(kicad_pcb
	(version 20260206)
	(generator "pcbnew")
	(generator_version "10.0")
	(general
		(thickness 1.6)
		(legacy_teardrops no)
	)
	(paper "A4")
	(layers
		(0 "F.Cu" signal "TOP")
		(4 "In1.Cu" signal "L2GND")
		(6 "In2.Cu" signal "L3")
		(8 "In3.Cu" signal "L4GND")
		(10 "In4.Cu" signal "L5")
		(12 "In5.Cu" signal "L6GND")
		(14 "In6.Cu" signal "L7VCC")
		(16 "In7.Cu" signal "L8VCC")
		(18 "In8.Cu" signal "L9GND")
		(20 "In9.Cu" signal "L10")
		(22 "In10.Cu" signal "L11GND")
		(24 "In11.Cu" signal "L12")
		(26 "In12.Cu" signal "L13GND")
		(2 "B.Cu" signal "BOTTOM")
		(9 "F.Adhes" user "F.Adhesive")
		(11 "B.Adhes" user "B.Adhesive")
		(13 "F.Paste" user "Package Geometry/Pastemask Top")
		(15 "B.Paste" user "Package Geometry/Pastemask Bottom")
		(5 "F.SilkS" user "Ref Des/Silkscreen Top")
		(7 "B.SilkS" user "Ref Des/Silkscreen Bottom")
		(1 "F.Mask" user "Board Geometry/Soldermask Top")
		(3 "B.Mask" user "Board Geometry/Soldermask Bottom")
		(17 "Dwgs.User" user "User.Drawings")
		(19 "Cmts.User" user "User.Comments")
		(21 "Eco1.User" user "User.Eco1")
		(23 "Eco2.User" user "User.Eco2")
		(25 "Edge.Cuts" user "Board Geometry/Outline")
		(27 "Margin" user)
		(31 "F.CrtYd" user "Package Geometry/Place Bound Top")
		(29 "B.CrtYd" user "Package Geometry/Place Bound Bottom")
		(35 "F.Fab" user "Ref Des/Assembly Top")
		(33 "B.Fab" user "Ref Des/Assembly Bottom")
	)
	(setup
		(pad_to_mask_clearance 0)
		(allow_soldermask_bridges_in_footprints no)
		(tenting
			(front yes)
			(back yes)
		)
		(covering
			(front no)
			(back no)
		)
		(plugging
			(front no)
			(back no)
		)
		(capping no)
		(filling no)
		(pcbplotparams
			(layerselection 0x00000000_00000000_55555555_5755f5ff)
			(plot_on_all_layers_selection 0x00000000_00000000_00000000_00000000)
			(disableapertmacros no)
			(usegerberextensions no)
			(usegerberattributes yes)
			(usegerberadvancedattributes yes)
			(creategerberjobfile yes)
			(dashed_line_dash_ratio 12)
			(dashed_line_gap_ratio 3)
			(svgprecision 4)
			(plotframeref no)
			(mode 1)
			(useauxorigin no)
			(pdf_front_fp_property_popups yes)
			(pdf_back_fp_property_popups yes)
			(pdf_metadata yes)
			(pdf_single_document no)
			(dxfpolygonmode yes)
			(dxfimperialunits yes)
			(dxfusepcbnewfont yes)
			(psnegative no)
			(psa4output no)
			(plot_black_and_white yes)
			(sketchpadsonfab no)
			(plotpadnumbers no)
			(hidednponfab no)
			(sketchdnponfab yes)
			(crossoutdnponfab yes)
			(subtractmaskfromsilk no)
			(outputformat 1)
			(mirror no)
			(drillshape 1)
			(scaleselection 1)
			(outputdirectory "")
		)
	)
	(segment
		(start 425.148248 -24.226012)
		(end 425.684188 -24.226012)
		(width 0.089408)
		(layer "In9.Cu")
		(net "PUMP_TACH1")
	)
	(segment
		(start 183.014366 3.433572)
		(end 182.61965 3.038856)
		(width 0.089408)
		(layer "In9.Cu")
		(net "PUMP_TACH1")
	)
	(segment
		(start 432.133756 -22.809708)
		(end 432.14798 -22.795484)
		(width 0.089408)
		(layer "In9.Cu")
		(net "PUMP_TACH1")
	)
	(segment
		(start 422.69029 -28.534614)
		(end 422.69029 -27.063446)
		(width 0.089408)
		(layer "In9.Cu")
		(net "PUMP_TACH1")
	)
	(segment
		(start 321.705224 4.941316)
		(end 183.825896 4.941316)
		(width 0.089408)
		(layer "In9.Cu")
		(net "PUMP_TACH1")
	)
	(segment
		(start 323.549772 2.536952)
		(end 323.549772 3.096768)
		(width 0.089408)
		(layer "In9.Cu")
		(net "PUMP_TACH1")
	)
	(segment
		(start 331.158596 4.785868)
		(end 331.158596 4.17068)
		(width 0.089408)
		(layer "In9.Cu")
		(net "PUMP_TACH1")
	)
	(segment
		(start 432.14798 -22.795484)
		(end 432.948334 -22.795484)
		(width 0.089408)
		(layer "In9.Cu")
		(net "PUMP_TACH1")
	)
	(segment
		(start 14.27734 -4.89204)
		(end 14.5796 -5.1943)
		(width 0.089408)
		(layer "In11.Cu")
		(net "PUMP_TACH1")
	)
	(segment
		(start 21.734526 -21.127974)
		(end 21.244306 -21.618194)
		(width 0.089408)
		(layer "In11.Cu")
		(net "PUMP_TACH1")
	)
	(segment
		(start 398.5768 0.4572)
		(end 382.133602 0.4572)
		(width 0.089408)
		(layer "In11.Cu")
		(net "PUMP_TACH1")
	)
	(segment
		(start 14.5796 0.02159)
		(end 14.5796 -0.988822)
		(width 0.089408)
		(layer "In11.Cu")
		(net "PUMP_TACH1")
	)
	(segment
		(start 117.816122 4.070604)
		(end 103.528622 4.070604)
		(width 0.089408)
		(layer "In11.Cu")
		(net "PUMP_TACH1")
	)
	(segment
		(start 362.218732 -2.3114)
		(end 358.2924 -2.3114)
		(width 0.089408)
		(layer "In11.Cu")
		(net "PUMP_TACH1")
	)
	(segment
		(start 14.436344 -118.882922)
		(end 13.235432 -120.083834)
		(width 0.089408)
		(layer "In11.Cu")
		(net "PUMP_TACH1")
	)
	(segment
		(start 11.156696 -51.071272)
		(end 11.156696 -51.215036)
		(width 0.089408)
		(layer "In11.Cu")
		(net "PUMP_TACH1")
	)
	(segment
		(start 14.436344 -113.384838)
		(end 14.436344 -118.882922)
		(width 0.089408)
		(layer "In11.Cu")
		(net "PUMP_TACH1")
	)
	(segment
		(start 11.156696 -51.215036)
		(end 11.11123 -51.260502)
		(width 0.089408)
		(layer "In11.Cu")
		(net "PUMP_TACH1")
	)
	(segment
		(start 14.98473 -5.709666)
		(end 21.384768 -5.709666)
		(width 0.089408)
		(layer "In11.Cu")
		(net "PUMP_TACH1")
	)
	(segment
		(start 21.244306 -21.618194)
		(end 15.110714 -21.618194)
		(width 0.089408)
		(layer "In11.Cu")
		(net "PUMP_TACH1")
	)
	(segment
		(start 10.875772 -71.397368)
		(end 10.875772 -80.60944)
		(width 0.089408)
		(layer "In11.Cu")
		(net "PUMP_TACH1")
	)
	(segment
		(start 183.420258 -1.333754)
		(end 181.292246 -3.461766)
		(width 0.089408)
		(layer "In11.Cu")
		(net "PUMP_TACH1")
	)
	(segment
		(start 12.546076 -111.49457)
		(end 14.436344 -113.384838)
		(width 0.089408)
		(layer "In11.Cu")
		(net "PUMP_TACH1")
	)
	(segment
		(start 14.611858 -47.61611)
		(end 11.156696 -51.071272)
		(width 0.089408)
		(layer "In11.Cu")
		(net "PUMP_TACH1")
	)
	(segment
		(start 179.055268 -3.90144)
		(end 177.14468 -3.90144)
		(width 0.089408)
		(layer "In11.Cu")
		(net "PUMP_TACH1")
	)
	(segment
		(start 12.546076 -109.600238)
		(end 12.546076 -111.49457)
		(width 0.089408)
		(layer "In11.Cu")
		(net "PUMP_TACH1")
	)
	(segment
		(start 426.728636 -0.727202)
		(end 423.85361 2.147824)
		(width 0.089408)
		(layer "In11.Cu")
		(net "PUMP_TACH1")
	)
	(segment
		(start 14.5796 -0.988822)
		(end 14.27734 -1.291082)
		(width 0.089408)
		(layer "In11.Cu")
		(net "PUMP_TACH1")
	)
	(segment
		(start 28.67406 4.681982)
		(end 27.93873 3.946652)
		(width 0.089408)
		(layer "In11.Cu")
		(net "PUMP_TACH1")
	)
	(segment
		(start 15.56258 1.00457)
		(end 14.5796 0.02159)
		(width 0.089408)
		(layer "In11.Cu")
		(net "PUMP_TACH1")
	)
	(segment
		(start 165.538912 3.626358)
		(end 164.483288 4.681982)
		(width 0.089408)
		(layer "In11.Cu")
		(net "PUMP_TACH1")
	)
	(segment
		(start 177.14468 -3.90144)
		(end 176.449482 -4.596638)
		(width 0.089408)
		(layer "In11.Cu")
		(net "PUMP_TACH1")
	)
	(segment
		(start 103.528622 4.070604)
		(end 102.917244 4.681982)
		(width 0.089408)
		(layer "In11.Cu")
		(net "PUMP_TACH1")
	)
	(segment
		(start 182.67172 1.130554)
		(end 183.420258 0.382016)
		(width 0.089408)
		(layer "In11.Cu")
		(net "PUMP_TACH1")
	)
	(segment
		(start 171.720256 -3.734816)
		(end 171.174156 -3.188716)
		(width 0.089408)
		(layer "In11.Cu")
		(net "PUMP_TACH1")
	)
	(segment
		(start 165.538912 0.114808)
		(end 165.538912 3.626358)
		(width 0.089408)
		(layer "In11.Cu")
		(net "PUMP_TACH1")
	)
	(segment
		(start 0.5969 -119.3292)
		(end 0.5969 -119.2911)
		(width 0.089408)
		(layer "In11.Cu")
		(net "PUMP_TACH1")
	)
	(segment
		(start 176.068482 -5.751576)
		(end 174.801276 -5.751576)
		(width 0.089408)
		(layer "In11.Cu")
		(net "PUMP_TACH1")
	)
	(segment
		(start 11.171936 -80.905604)
		(end 11.171936 -82.37347)
		(width 0.089408)
		(layer "In11.Cu")
		(net "PUMP_TACH1")
	)
	(segment
		(start 410.6418 2.794)
		(end 400.936968 2.794)
		(width 0.089408)
		(layer "In11.Cu")
		(net "PUMP_TACH1")
	)
	(segment
		(start 174.801276 -5.751576)
		(end 172.784516 -3.734816)
		(width 0.089408)
		(layer "In11.Cu")
		(net "PUMP_TACH1")
	)
	(segment
		(start 400.936968 2.794)
		(end 398.610836 0.467868)
		(width 0.089408)
		(layer "In11.Cu")
		(net "PUMP_TACH1")
	)
	(segment
		(start 423.85361 2.147824)
		(end 411.287976 2.147824)
		(width 0.089408)
		(layer "In11.Cu")
		(net "PUMP_TACH1")
	)
	(segment
		(start 8.521954 -119.95785)
		(end 1.22555 -119.95785)
		(width 0.089408)
		(layer "In11.Cu")
		(net "PUMP_TACH1")
	)
	(segment
		(start 14.326362 -41.588436)
		(end 14.611858 -41.873932)
		(width 0.089408)
		(layer "In11.Cu")
		(net "PUMP_TACH1")
	)
	(segment
		(start 167.799004 -2.145284)
		(end 165.538912 0.114808)
		(width 0.089408)
		(layer "In11.Cu")
		(net "PUMP_TACH1")
	)
	(segment
		(start 1.22555 -119.95785)
		(end 0.5969 -119.3292)
		(width 0.089408)
		(layer "In11.Cu")
		(net "PUMP_TACH1")
	)
	(segment
		(start 164.483288 4.681982)
		(end 118.4275 4.681982)
		(width 0.089408)
		(layer "In11.Cu")
		(net "PUMP_TACH1")
	)
	(segment
		(start 14.5796 -5.304536)
		(end 14.98473 -5.709666)
		(width 0.089408)
		(layer "In11.Cu")
		(net "PUMP_TACH1")
	)
	(segment
		(start 16.993108 1.00457)
		(end 15.56258 1.00457)
		(width 0.089408)
		(layer "In11.Cu")
		(net "PUMP_TACH1")
	)
	(segment
		(start 167.799004 -3.01371)
		(end 167.799004 -2.145284)
		(width 0.089408)
		(layer "In11.Cu")
		(net "PUMP_TACH1")
	)
	(segment
		(start 19.792696 3.804158)
		(end 16.993108 1.00457)
		(width 0.089408)
		(layer "In11.Cu")
		(net "PUMP_TACH1")
	)
	(segment
		(start 21.384768 -5.709666)
		(end 21.734526 -6.059424)
		(width 0.089408)
		(layer "In11.Cu")
		(net "PUMP_TACH1")
	)
	(segment
		(start 11.11123 -67.199764)
		(end 11.655044 -67.743578)
		(width 0.089408)
		(layer "In11.Cu")
		(net "PUMP_TACH1")
	)
	(segment
		(start 14.611858 -41.873932)
		(end 14.611858 -47.61611)
		(width 0.089408)
		(layer "In11.Cu")
		(net "PUMP_TACH1")
	)
	(segment
		(start 22.499828 4.746752)
		(end 20.157186 4.746752)
		(width 0.089408)
		(layer "In11.Cu")
		(net "PUMP_TACH1")
	)
	(segment
		(start 102.917244 4.681982)
		(end 28.67406 4.681982)
		(width 0.089408)
		(layer "In11.Cu")
		(net "PUMP_TACH1")
	)
	(segment
		(start 13.235432 -120.083834)
		(end 8.647938 -120.083834)
		(width 0.089408)
		(layer "In11.Cu")
		(net "PUMP_TACH1")
	)
	(segment
		(start 176.449482 -4.596638)
		(end 176.449482 -5.370576)
		(width 0.089408)
		(layer "In11.Cu")
		(net "PUMP_TACH1")
	)
	(segment
		(start 27.93873 3.946652)
		(end 23.299928 3.946652)
		(width 0.089408)
		(layer "In11.Cu")
		(net "PUMP_TACH1")
	)
	(segment
		(start 11.655044 -67.743578)
		(end 11.655044 -70.618096)
		(width 0.089408)
		(layer "In11.Cu")
		(net "PUMP_TACH1")
	)
	(segment
		(start 181.292246 -3.461766)
		(end 179.494942 -3.461766)
		(width 0.089408)
		(layer "In11.Cu")
		(net "PUMP_TACH1")
	)
	(segment
		(start 398.587468 0.467868)
		(end 398.5768 0.4572)
		(width 0.089408)
		(layer "In11.Cu")
		(net "PUMP_TACH1")
	)
	(segment
		(start 10.52576 -107.579922)
		(end 12.546076 -109.600238)
		(width 0.089408)
		(layer "In11.Cu")
		(net "PUMP_TACH1")
	)
	(segment
		(start 10.52576 -83.019646)
		(end 10.52576 -107.579922)
		(width 0.089408)
		(layer "In11.Cu")
		(net "PUMP_TACH1")
	)
	(segment
		(start 398.610836 0.467868)
		(end 398.587468 0.467868)
		(width 0.089408)
		(layer "In11.Cu")
		(net "PUMP_TACH1")
	)
	(segment
		(start 11.171936 -82.37347)
		(end 10.52576 -83.019646)
		(width 0.089408)
		(layer "In11.Cu")
		(net "PUMP_TACH1")
	)
	(segment
		(start 176.449482 -5.370576)
		(end 176.068482 -5.751576)
		(width 0.089408)
		(layer "In11.Cu")
		(net "PUMP_TACH1")
	)
	(segment
		(start 14.5796 -5.1943)
		(end 14.5796 -5.304536)
		(width 0.089408)
		(layer "In11.Cu")
		(net "PUMP_TACH1")
	)
	(segment
		(start 118.4275 4.681982)
		(end 117.816122 4.070604)
		(width 0.089408)
		(layer "In11.Cu")
		(net "PUMP_TACH1")
	)
	(segment
		(start 10.875772 -80.60944)
		(end 11.171936 -80.905604)
		(width 0.089408)
		(layer "In11.Cu")
		(net "PUMP_TACH1")
	)
	(segment
		(start 182.61965 1.130554)
		(end 182.67172 1.130554)
		(width 0.089408)
		(layer "In11.Cu")
		(net "PUMP_TACH1")
	)
	(segment
		(start 382.133602 0.4572)
		(end 381.549402 -0.127)
		(width 0.089408)
		(layer "In11.Cu")
		(net "PUMP_TACH1")
	)
	(segment
		(start 14.326362 -22.402546)
		(end 14.326362 -41.588436)
		(width 0.089408)
		(layer "In11.Cu")
		(net "PUMP_TACH1")
	)
	(segment
		(start 21.734526 -6.059424)
		(end 21.734526 -21.127974)
		(width 0.089408)
		(layer "In11.Cu")
		(net "PUMP_TACH1")
	)
	(segment
		(start 11.11123 -51.260502)
		(end 11.11123 -67.199764)
		(width 0.089408)
		(layer "In11.Cu")
		(net "PUMP_TACH1")
	)
	(segment
		(start 14.27734 -1.291082)
		(end 14.27734 -4.89204)
		(width 0.089408)
		(layer "In11.Cu")
		(net "PUMP_TACH1")
	)
	(segment
		(start 167.97401 -3.188716)
		(end 167.799004 -3.01371)
		(width 0.089408)
		(layer "In11.Cu")
		(net "PUMP_TACH1")
	)
	(segment
		(start 8.647938 -120.083834)
		(end 8.521954 -119.95785)
		(width 0.089408)
		(layer "In11.Cu")
		(net "PUMP_TACH1")
	)
	(segment
		(start 20.157186 4.746752)
		(end 19.792696 4.382262)
		(width 0.089408)
		(layer "In11.Cu")
		(net "PUMP_TACH1")
	)
	(segment
		(start 19.792696 4.382262)
		(end 19.792696 3.804158)
		(width 0.089408)
		(layer "In11.Cu")
		(net "PUMP_TACH1")
	)
	(segment
		(start 411.287976 2.147824)
		(end 410.6418 2.794)
		(width 0.089408)
		(layer "In11.Cu")
		(net "PUMP_TACH1")
	)
	(segment
		(start 183.420258 0.382016)
		(end 183.420258 -1.333754)
		(width 0.089408)
		(layer "In11.Cu")
		(net "PUMP_TACH1")
	)
	(segment
		(start 381.549402 -0.127)
		(end 364.403132 -0.127)
		(width 0.089408)
		(layer "In11.Cu")
		(net "PUMP_TACH1")
	)
	(segment
		(start 364.403132 -0.127)
		(end 362.218732 -2.3114)
		(width 0.089408)
		(layer "In11.Cu")
		(net "PUMP_TACH1")
	)
	(segment
		(start 23.299928 3.946652)
		(end 22.499828 4.746752)
		(width 0.089408)
		(layer "In11.Cu")
		(net "PUMP_TACH1")
	)
	(segment
		(start 179.494942 -3.461766)
		(end 179.055268 -3.90144)
		(width 0.089408)
		(layer "In11.Cu")
		(net "PUMP_TACH1")
	)
	(segment
		(start 171.174156 -3.188716)
		(end 167.97401 -3.188716)
		(width 0.089408)
		(layer "In11.Cu")
		(net "PUMP_TACH1")
	)
	(segment
		(start 11.655044 -70.618096)
		(end 10.875772 -71.397368)
		(width 0.089408)
		(layer "In11.Cu")
		(net "PUMP_TACH1")
	)
	(segment
		(start 15.110714 -21.618194)
		(end 14.326362 -22.402546)
		(width 0.089408)
		(layer "In11.Cu")
		(net "PUMP_TACH1")
	)
	(segment
		(start 172.784516 -3.734816)
		(end 171.720256 -3.734816)
		(width 0.089408)
		(layer "In11.Cu")
		(net "PUMP_TACH1")
	)
	(segment
		(start 437.388 -20.0406)
		(end 437.388 -19.4945)
		(width 0.1016)
		(layer "F.Cu")
		(net "PUMP_TACH0")
	)
	(segment
		(start 423.890186 -28.134564)
		(end 424.366182 -28.134564)
		(width 0.10795)
		(layer "F.Cu")
		(net "PUMP_TACH0")
	)
	(segment
		(start 436.7911 -19.3675)
		(end 436.499 -19.3675)
		(width 0.1016)
		(layer "F.Cu")
		(net "PUMP_TACH0")
	)
	(segment
		(start 427.456346 -26.797)
		(end 428.6504 -26.797)
		(width 0.10795)
		(layer "F.Cu")
		(net "PUMP_TACH0")
	)
	(segment
		(start 437.1721 -20.2565)
		(end 437.2356 -20.193)
		(width 0.10795)
		(layer "F.Cu")
		(net "PUMP_TACH0")
	)
	(segment
		(start 437.2356 -20.193)
		(end 437.388 -20.0406)
		(width 0.1016)
		(layer "F.Cu")
		(net "PUMP_TACH0")
	)
	(segment
		(start 426.468794 -27.784552)
		(end 427.456346 -26.797)
		(width 0.10795)
		(layer "F.Cu")
		(net "PUMP_TACH0")
	)
	(segment
		(start 428.9552 -26.4922)
		(end 429.48098 -26.4922)
		(width 0.10795)
		(layer "F.Cu")
		(net "PUMP_TACH0")
	)
	(segment
		(start 424.716194 -27.784552)
		(end 426.468794 -27.784552)
		(width 0.10795)
		(layer "F.Cu")
		(net "PUMP_TACH0")
	)
	(segment
		(start 436.499 -20.2565)
		(end 437.1721 -20.2565)
		(width 0.10795)
		(layer "F.Cu")
		(net "PUMP_TACH0")
	)
	(segment
		(start 432.987958 -24.321262)
		(end 434.794152 -22.515068)
		(width 0.10795)
		(layer "F.Cu")
		(net "PUMP_TACH0")
	)
	(segment
		(start 429.48098 -26.4922)
		(end 429.9712 -26.4922)
		(width 0.10795)
		(layer "F.Cu")
		(net "PUMP_TACH0")
	)
	(segment
		(start 424.366182 -28.134564)
		(end 424.716194 -27.784552)
		(width 0.10795)
		(layer "F.Cu")
		(net "PUMP_TACH0")
	)
	(segment
		(start 428.6504 -26.797)
		(end 428.9552 -26.4922)
		(width 0.10795)
		(layer "F.Cu")
		(net "PUMP_TACH0")
	)
	(segment
		(start 436.9181 -19.4945)
		(end 436.7911 -19.3675)
		(width 0.1016)
		(layer "F.Cu")
		(net "PUMP_TACH0")
	)
	(segment
		(start 430.276 -26.797)
		(end 430.9491 -26.797)
		(width 0.10795)
		(layer "F.Cu")
		(net "PUMP_TACH0")
	)
	(segment
		(start 436.1561 -20.2565)
		(end 436.499 -20.2565)
		(width 0.10795)
		(layer "F.Cu")
		(net "PUMP_TACH0")
	)
	(segment
		(start 437.388 -19.4945)
		(end 436.9181 -19.4945)
		(width 0.1016)
		(layer "F.Cu")
		(net "PUMP_TACH0")
	)
	(segment
		(start 430.9491 -26.797)
		(end 431.8 -26.797)
		(width 0.10795)
		(layer "F.Cu")
		(net "PUMP_TACH0")
	)
	(segment
		(start 432.987958 -26.104342)
		(end 432.987958 -24.321262)
		(width 0.10795)
		(layer "F.Cu")
		(net "PUMP_TACH0")
	)
	(segment
		(start 431.8 -26.797)
		(end 432.2953 -26.797)
		(width 0.10795)
		(layer "F.Cu")
		(net "PUMP_TACH0")
	)
	(segment
		(start 429.9712 -26.4922)
		(end 430.276 -26.797)
		(width 0.10795)
		(layer "F.Cu")
		(net "PUMP_TACH0")
	)
	(segment
		(start 434.794152 -21.618448)
		(end 436.1561 -20.2565)
		(width 0.10795)
		(layer "F.Cu")
		(net "PUMP_TACH0")
	)
	(segment
		(start 432.2953 -26.797)
		(end 432.987958 -26.104342)
		(width 0.10795)
		(layer "F.Cu")
		(net "PUMP_TACH0")
	)
	(segment
		(start 434.794152 -22.515068)
		(end 434.794152 -21.618448)
		(width 0.10795)
		(layer "F.Cu")
		(net "PUMP_TACH0")
	)
	(via
		(at 429.48098 -26.4922)
		(size 0.762)
		(drill 0.381)
		(layers "F.Cu" "B.Cu")
		(net "PUMP_TACH0")
	)
	(via
		(at 390.981946 -18.588736)
		(size 0.6604)
		(drill 0.3302)
		(layers "F.Cu" "B.Cu")
		(net "PD_SMB_M2_EN")
	)
	(segment
		(start 389.290052 -20.51812)
		(end 390.17575 -20.51812)
		(width 0.10795)
		(layer "B.Cu")
		(net "PD_SMB_M2_EN")
	)
	(segment
		(start 387.917182 -15.434818)
		(end 387.604 -15.748)
		(width 0.10795)
		(layer "B.Cu")
		(net "PD_SMB_M2_EN")
	)
	(segment
		(start 387.604 -18.93316)
		(end 388.27202 -19.60118)
		(width 0.10795)
		(layer "B.Cu")
		(net "PD_SMB_M2_EN")
	)
	(segment
		(start 390.40562 -19.165062)
		(end 390.981946 -18.588736)
		(width 0.10795)
		(layer "B.Cu")
		(net "PD_SMB_M2_EN")
	)
	(segment
		(start 392.030458 -17.540224)
		(end 392.030458 -16.691864)
		(width 0.10795)
		(layer "B.Cu")
		(net "PD_SMB_M2_EN")
	)
	(segment
		(start 390.981946 -18.588736)
		(end 392.030458 -17.540224)
		(width 0.10795)
		(layer "B.Cu")
		(net "PD_SMB_M2_EN")
	)
	(segment
		(start 388.27202 -19.60118)
		(end 388.57428 -19.60118)
		(width 0.10795)
		(layer "B.Cu")
		(net "PD_SMB_M2_EN")
	)
	(segment
		(start 390.17575 -20.51812)
		(end 390.40562 -20.28825)
		(width 0.10795)
		(layer "B.Cu")
		(net "PD_SMB_M2_EN")
	)
	(segment
		(start 388.57428 -19.60118)
		(end 388.908798 -19.935698)
		(width 0.10795)
		(layer "B.Cu")
		(net "PD_SMB_M2_EN")
	)
	(segment
		(start 390.40562 -20.28825)
		(end 390.40562 -19.165062)
		(width 0.10795)
		(layer "B.Cu")
		(net "PD_SMB_M2_EN")
	)
	(segment
		(start 387.604 -16.383)
		(end 387.604 -18.93316)
		(width 0.10795)
		(layer "B.Cu")
		(net "PD_SMB_M2_EN")
	)
	(segment
		(start 388.908798 -20.136866)
		(end 389.290052 -20.51812)
		(width 0.10795)
		(layer "B.Cu")
		(net "PD_SMB_M2_EN")
	)
	(segment
		(start 387.604 -15.748)
		(end 387.604 -16.383)
		(width 0.10795)
		(layer "B.Cu")
		(net "PD_SMB_M2_EN")
	)
	(segment
		(start 388.908798 -19.935698)
		(end 388.908798 -20.136866)
		(width 0.10795)
		(layer "B.Cu")
		(net "PD_SMB_M2_EN")
	)
	(segment
		(start 387.917182 -14.528292)
		(end 387.917182 -15.434818)
		(width 0.10795)
		(layer "B.Cu")
		(net "PD_SMB_M2_EN")
	)
	(via
		(at 395.80439 -13.920978)
		(size 0.6604)
		(drill 0.3302)
		(layers "F.Cu" "B.Cu")
		(net "P1V8_M2")
	)
	(via
		(at 391.54608 -20.164298)
		(size 0.508)
		(drill 0.254)
		(layers "F.Cu" "B.Cu")
		(net "P1V8_M2")
	)
	(via
		(at 395.42974 -18.22704)
		(size 0.508)
		(drill 0.254)
		(layers "F.Cu" "B.Cu")
		(net "P1V8_M2")
	)
	(segment
		(start 395.80439 -12.832334)
		(end 395.561058 -12.589002)
		(width 0.254)
		(layer "B.Cu")
		(net "P1V8_M2")
	)
	(segment
		(start 394.2207 -19.812)
		(end 393.861036 -19.812)
		(width 0.254)
		(layer "B.Cu")
		(net "P1V8_M2")
	)
	(segment
		(start 395.85138 -16.438372)
		(end 396.216886 -16.438372)
		(width 0.254)
		(layer "B.Cu")
		(net "P1V8_M2")
	)
	(segment
		(start 393.667234 -13.736574)
		(end 393.981178 -13.42263)
		(width 0.254)
		(layer "B.Cu")
		(net "P1V8_M2")
	)
	(segment
		(start 395.80439 -13.920978)
		(end 395.80439 -14.905482)
		(width 0.254)
		(layer "B.Cu")
		(net "P1V8_M2")
	)
	(segment
		(start 393.848336 -19.7993)
		(end 393.446 -19.7993)
		(width 0.254)
		(layer "B.Cu")
		(net "P1V8_M2")
	)
	(segment
		(start 393.3825 -22.48408)
		(end 394.2334 -23.33498)
		(width 0.254)
		(layer "B.Cu")
		(net "P1V8_M2")
	)
	(segment
		(start 393.4079 -20.6248)
		(end 393.4079 -21.010118)
		(width 0.254)
		(layer "B.Cu")
		(net "P1V8_M2")
	)
	(segment
		(start 391.54735 -20.164298)
		(end 391.54735 -20.163028)
		(width 0.254)
		(layer "B.Cu")
		(net "P1V8_M2")
	)
	(segment
		(start 393.3825 -21.035518)
		(end 393.3825 -22.48408)
		(width 0.254)
		(layer "B.Cu")
		(net "P1V8_M2")
	)
	(segment
		(start 393.981178 -13.42263)
		(end 393.981178 -12.582144)
		(width 0.254)
		(layer "B.Cu")
		(net "P1V8_M2")
	)
	(segment
		(start 395.42974 -18.22704)
		(end 395.42974 -16.860012)
		(width 0.254)
		(layer "B.Cu")
		(net "P1V8_M2")
	)
	(segment
		(start 392.72845 -19.68119)
		(end 392.84656 -19.7993)
		(width 0.254)
		(layer "B.Cu")
		(net "P1V8_M2")
	)
	(segment
		(start 389.867902 -10.418572)
		(end 389.867902 -11.807952)
		(width 0.254)
		(layer "B.Cu")
		(net "P1V8_M2")
	)
	(segment
		(start 396.289276 -15.390368)
		(end 396.289276 -16.365982)
		(width 0.254)
		(layer "B.Cu")
		(net "P1V8_M2")
	)
	(segment
		(start 391.796524 -13.736574)
		(end 393.667234 -13.736574)
		(width 0.254)
		(layer "B.Cu")
		(net "P1V8_M2")
	)
	(segment
		(start 391.54735 -20.163028)
		(end 392.029188 -19.68119)
		(width 0.254)
		(layer "B.Cu")
		(net "P1V8_M2")
	)
	(segment
		(start 393.4079 -21.010118)
		(end 393.3825 -21.035518)
		(width 0.254)
		(layer "B.Cu")
		(net "P1V8_M2")
	)
	(segment
		(start 394.171932 -25.143714)
		(end 394.171932 -24.533098)
		(width 0.254)
		(layer "B.Cu")
		(net "P1V8_M2")
	)
	(segment
		(start 394.171932 -24.533098)
		(end 394.2334 -24.47163)
		(width 0.254)
		(layer "B.Cu")
		(net "P1V8_M2")
	)
	(segment
		(start 391.54608 -20.164298)
		(end 391.54735 -20.164298)
		(width 0.254)
		(layer "B.Cu")
		(net "P1V8_M2")
	)
	(segment
		(start 389.861806 -8.696452)
		(end 389.861806 -10.412476)
		(width 0.254)
		(layer "B.Cu")
		(net "P1V8_M2")
	)
	(segment
		(start 389.867902 -11.807952)
		(end 391.796524 -13.736574)
		(width 0.254)
		(layer "B.Cu")
		(net "P1V8_M2")
	)
	(segment
		(start 393.446 -20.161504)
		(end 393.4079 -20.199604)
		(width 0.254)
		(layer "B.Cu")
		(net "P1V8_M2")
	)
	(segment
		(start 393.981178 -12.582144)
		(end 395.5415 -12.582144)
		(width 0.254)
		(layer "B.Cu")
		(net "P1V8_M2")
	)
	(segment
		(start 393.861036 -19.812)
		(end 393.848336 -19.7993)
		(width 0.254)
		(layer "B.Cu")
		(net "P1V8_M2")
	)
	(segment
		(start 389.861806 -10.412476)
		(end 389.867902 -10.418572)
		(width 0.254)
		(layer "B.Cu")
		(net "P1V8_M2")
	)
	(segment
		(start 394.2334 -24.47163)
		(end 394.2334 -23.876)
		(width 0.254)
		(layer "B.Cu")
		(net "P1V8_M2")
	)
	(segment
		(start 392.029188 -19.68119)
		(end 392.382756 -19.68119)
		(width 0.254)
		(layer "B.Cu")
		(net "P1V8_M2")
	)
	(segment
		(start 393.446 -19.7993)
		(end 393.446 -20.161504)
		(width 0.254)
		(layer "B.Cu")
		(net "P1V8_M2")
	)
	(segment
		(start 395.561058 -12.589002)
		(end 395.548358 -12.589002)
		(width 0.254)
		(layer "B.Cu")
		(net "P1V8_M2")
	)
	(segment
		(start 395.80439 -14.905482)
		(end 396.289276 -15.390368)
		(width 0.254)
		(layer "B.Cu")
		(net "P1V8_M2")
	)
	(segment
		(start 395.80439 -13.920978)
		(end 395.80439 -12.832334)
		(width 0.254)
		(layer "B.Cu")
		(net "P1V8_M2")
	)
	(segment
		(start 392.84656 -19.7993)
		(end 393.446 -19.7993)
		(width 0.254)
		(layer "B.Cu")
		(net "P1V8_M2")
	)
	(segment
		(start 395.42974 -16.860012)
		(end 395.85138 -16.438372)
		(width 0.254)
		(layer "B.Cu")
		(net "P1V8_M2")
	)
	(segment
		(start 396.216886 -16.438372)
		(end 396.978886 -16.438372)
		(width 0.254)
		(layer "B.Cu")
		(net "P1V8_M2")
	)
	(segment
		(start 396.289276 -16.365982)
		(end 396.216886 -16.438372)
		(width 0.254)
		(layer "B.Cu")
		(net "P1V8_M2")
	)
	(segment
		(start 393.4079 -20.199604)
		(end 393.4079 -20.6248)
		(width 0.254)
		(layer "B.Cu")
		(net "P1V8_M2")
	)
	(segment
		(start 392.382756 -19.68119)
		(end 392.72845 -19.68119)
		(width 0.254)
		(layer "B.Cu")
		(net "P1V8_M2")
	)
	(segment
		(start 394.2334 -23.33498)
		(end 394.2334 -23.876)
		(width 0.254)
		(layer "B.Cu")
		(net "P1V8_M2")
	)
	(segment
		(start 395.5415 -12.582144)
		(end 395.548358 -12.589002)
		(width 0.254)
		(layer "B.Cu")
		(net "P1V8_M2")
	)
	(segment
		(start 394.35024 -19.30654)
		(end 392.403838 -19.30654)
		(width 0.254)
		(layer "In9.Cu")
		(net "P1V8_M2")
	)
	(segment
		(start 392.403838 -19.30654)
		(end 391.54608 -20.164298)
		(width 0.254)
		(layer "In9.Cu")
		(net "P1V8_M2")
	)
	(segment
		(start 395.42974 -18.22704)
		(end 394.35024 -19.30654)
		(width 0.254)
		(layer "In9.Cu")
		(net "P1V8_M2")
	)
	(segment
		(start -0.324612 -116.362988)
		(end -0.4953 -116.1923)
		(width 0.10795)
		(layer "F.Cu")
		(net "PUMP_TACH1_R")
	)
	(segment
		(start -1.453388 -115.234212)
		(end -1.453388 -114.954812)
		(width 0.10795)
		(layer "F.Cu")
		(net "PUMP_TACH1_R")
	)
	(segment
		(start -0.324612 -116.985034)
		(end -0.324612 -116.362988)
		(width 0.10795)
		(layer "F.Cu")
		(net "PUMP_TACH1_R")
	)
	(segment
		(start -0.4953 -116.1923)
		(end -1.453388 -115.234212)
		(width 0.10795)
		(layer "F.Cu")
		(net "PUMP_TACH1_R")
	)
	(via
		(at -0.4953 -116.1923)
		(size 0.508)
		(drill 0.254)
		(layers "F.Cu" "B.Cu")
		(net "PUMP_TACH1_R")
	)
	(segment
		(start -3.739388 -114.954812)
		(end -3.739388 -115.141248)
		(width 0.10795)
		(layer "F.Cu")
		(net "PUMP_TACH1_D")
	)
	(segment
		(start -3.739388 -115.141248)
		(end -4.321556 -115.723416)
		(width 0.10795)
		(layer "F.Cu")
		(net "PUMP_TACH1_D")
	)
	(via
		(at -4.321556 -115.723416)
		(size 0.508)
		(drill 0.254)
		(layers "F.Cu" "B.Cu")
		(net "PUMP_TACH1_D")
	)
	(segment
		(start 0.553974 -117.672866)
		(end -1.185926 -115.932966)
		(width 0.089408)
		(layer "In11.Cu")
		(net "PUMP_TACH1_D")
	)
	(segment
		(start -4.112006 -115.932966)
		(end -4.321556 -115.723416)
		(width 0.089408)
		(layer "In11.Cu")
		(net "PUMP_TACH1_D")
	)
	(segment
		(start 4.373372 -118.679976)
		(end 3.366262 -117.672866)
		(width 0.089408)
		(layer "In11.Cu")
		(net "PUMP_TACH1_D")
	)
	(segment
		(start -1.185926 -115.932966)
		(end -4.112006 -115.932966)
		(width 0.089408)
		(layer "In11.Cu")
		(net "PUMP_TACH1_D")
	)
	(segment
		(start 3.366262 -117.672866)
		(end 0.553974 -117.672866)
		(width 0.089408)
		(layer "In11.Cu")
		(net "PUMP_TACH1_D")
	)
	(segment
		(start 5.210048 -118.679976)
		(end 4.373372 -118.679976)
		(width 0.089408)
		(layer "In11.Cu")
		(net "PUMP_TACH1_D")
	)
	(segment
		(start 439.938668 -32.184848)
		(end 439.854594 -32.100774)
		(width 0.254)
		(layer "B.Cu")
		(net "BMC_M_CLK")
	)
	(segment
		(start 440.284362 -32.184848)
		(end 439.938668 -32.184848)
		(width 0.254)
		(layer "B.Cu")
		(net "BMC_M_CLK")
	)
	(segment
		(start 439.493406 -33.101026)
		(end 439.493406 -32.100774)
		(width 0.254)
		(layer "B.Cu")
		(net "BMC_M_CLK")
	)
	(segment
		(start 439.854594 -32.100774)
		(end 439.493406 -32.100774)
		(width 0.254)
		(layer "B.Cu")
		(net "BMC_M_CLK")
	)
	(segment
		(start 476.740728 -133.284214)
		(end 476.349568 -132.893054)
		(width 0.1016)
		(layer "B.Cu")
		(net "SMB_DEBUG_STBY_LVC3_SDA_CONN")
	)
	(segment
		(start 477.848422 -132.838444)
		(end 477.402652 -133.284214)
		(width 0.1016)
		(layer "B.Cu")
		(net "SMB_DEBUG_STBY_LVC3_SDA_CONN")
	)
	(segment
		(start 475.4499 -134.988554)
		(end 475.4499 -134.00024)
		(width 0.10795)
		(layer "B.Cu")
		(net "SMB_DEBUG_STBY_LVC3_SDA_CONN")
	)
	(segment
		(start 475.525084 -135.063738)
		(end 475.4499 -134.988554)
		(width 0.10795)
		(layer "B.Cu")
		(net "SMB_DEBUG_STBY_LVC3_SDA_CONN")
	)
	(segment
		(start 487.1339 -134.9121)
		(end 481.53574 -134.9121)
		(width 0.1016)
		(layer "B.Cu")
		(net "SMB_DEBUG_STBY_LVC3_SDA_CONN")
	)
	(segment
		(start 487.583734 -133.977126)
		(end 487.583734 -134.462266)
		(width 0.1016)
		(layer "B.Cu")
		(net "SMB_DEBUG_STBY_LVC3_SDA_CONN")
	)
	(segment
		(start 475.525084 -135.41756)
		(end 475.525084 -135.063738)
		(width 0.10795)
		(layer "B.Cu")
		(net "SMB_DEBUG_STBY_LVC3_SDA_CONN")
	)
	(segment
		(start 486.751122 -133.45541)
		(end 487.062018 -133.45541)
		(width 0.1016)
		(layer "B.Cu")
		(net "SMB_DEBUG_STBY_LVC3_SDA_CONN")
	)
	(segment
		(start 480.360228 -136.087612)
		(end 475.671388 -136.087612)
		(width 0.1016)
		(layer "B.Cu")
		(net "SMB_DEBUG_STBY_LVC3_SDA_CONN")
	)
	(segment
		(start 475.595696 -132.893054)
		(end 475.4499 -133.03885)
		(width 0.1016)
		(layer "B.Cu")
		(net "SMB_DEBUG_STBY_LVC3_SDA_CONN")
	)
	(segment
		(start 476.349568 -132.893054)
		(end 475.595696 -132.893054)
		(width 0.1016)
		(layer "B.Cu")
		(net "SMB_DEBUG_STBY_LVC3_SDA_CONN")
	)
	(segment
		(start 475.525084 -135.941308)
		(end 475.525084 -135.41756)
		(width 0.10795)
		(layer "B.Cu")
		(net "SMB_DEBUG_STBY_LVC3_SDA_CONN")
	)
	(segment
		(start 477.402652 -133.284214)
		(end 476.740728 -133.284214)
		(width 0.1016)
		(layer "B.Cu")
		(net "SMB_DEBUG_STBY_LVC3_SDA_CONN")
	)
	(segment
		(start 481.53574 -134.9121)
		(end 480.360228 -136.087612)
		(width 0.1016)
		(layer "B.Cu")
		(net "SMB_DEBUG_STBY_LVC3_SDA_CONN")
	)
	(segment
		(start 487.583734 -134.462266)
		(end 487.1339 -134.9121)
		(width 0.1016)
		(layer "B.Cu")
		(net "SMB_DEBUG_STBY_LVC3_SDA_CONN")
	)
	(segment
		(start 475.4499 -133.03885)
		(end 475.4499 -134.00024)
		(width 0.1016)
		(layer "B.Cu")
		(net "SMB_DEBUG_STBY_LVC3_SDA_CONN")
	)
	(segment
		(start 475.671388 -136.087612)
		(end 475.525084 -135.941308)
		(width 0.10795)
		(layer "B.Cu")
		(net "SMB_DEBUG_STBY_LVC3_SDA_CONN")
	)
	(segment
		(start 487.062018 -133.45541)
		(end 487.583734 -133.977126)
		(width 0.1016)
		(layer "B.Cu")
		(net "SMB_DEBUG_STBY_LVC3_SDA_CONN")
	)
	(segment
		(start 481.66655 -135.1407)
		(end 487.26471 -135.1407)
		(width 0.1016)
		(layer "B.Cu")
		(net "SMB_DEBUG_STBY_LVC3_SCL_CONN")
	)
	(segment
		(start 474.80474 -135.41756)
		(end 474.80474 -135.83666)
		(width 0.1016)
		(layer "B.Cu")
		(net "SMB_DEBUG_STBY_LVC3_SCL_CONN")
	)
	(segment
		(start 488.46359 -133.45541)
		(end 488.751118 -133.45541)
		(width 0.1016)
		(layer "B.Cu")
		(net "SMB_DEBUG_STBY_LVC3_SCL_CONN")
	)
	(segment
		(start 474.79966 -133.114796)
		(end 474.79966 -134.00024)
		(width 0.1016)
		(layer "B.Cu")
		(net "SMB_DEBUG_STBY_LVC3_SCL_CONN")
	)
	(segment
		(start 477.081088 -132.83311)
		(end 476.708724 -132.83311)
		(width 0.1016)
		(layer "B.Cu")
		(net "SMB_DEBUG_STBY_LVC3_SCL_CONN")
	)
	(segment
		(start 475.318836 -132.59562)
		(end 474.79966 -133.114796)
		(width 0.1016)
		(layer "B.Cu")
		(net "SMB_DEBUG_STBY_LVC3_SCL_CONN")
	)
	(segment
		(start 476.708724 -132.83311)
		(end 476.471234 -132.59562)
		(width 0.1016)
		(layer "B.Cu")
		(net "SMB_DEBUG_STBY_LVC3_SCL_CONN")
	)
	(segment
		(start 487.26471 -135.1407)
		(end 487.9086 -134.49681)
		(width 0.1016)
		(layer "B.Cu")
		(net "SMB_DEBUG_STBY_LVC3_SCL_CONN")
	)
	(segment
		(start 474.80474 -135.41756)
		(end 474.80474 -134.00532)
		(width 0.1016)
		(layer "B.Cu")
		(net "SMB_DEBUG_STBY_LVC3_SCL_CONN")
	)
	(segment
		(start 475.34068 -136.3726)
		(end 480.43465 -136.3726)
		(width 0.1016)
		(layer "B.Cu")
		(net "SMB_DEBUG_STBY_LVC3_SCL_CONN")
	)
	(segment
		(start 487.9086 -134.0104)
		(end 488.46359 -133.45541)
		(width 0.1016)
		(layer "B.Cu")
		(net "SMB_DEBUG_STBY_LVC3_SCL_CONN")
	)
	(segment
		(start 476.471234 -132.59562)
		(end 475.318836 -132.59562)
		(width 0.1016)
		(layer "B.Cu")
		(net "SMB_DEBUG_STBY_LVC3_SCL_CONN")
	)
	(segment
		(start 474.80474 -134.00532)
		(end 474.79966 -134.00024)
		(width 0.1016)
		(layer "B.Cu")
		(net "SMB_DEBUG_STBY_LVC3_SCL_CONN")
	)
	(segment
		(start 480.43465 -136.3726)
		(end 481.66655 -135.1407)
		(width 0.1016)
		(layer "B.Cu")
		(net "SMB_DEBUG_STBY_LVC3_SCL_CONN")
	)
	(segment
		(start 487.9086 -134.49681)
		(end 487.9086 -134.0104)
		(width 0.1016)
		(layer "B.Cu")
		(net "SMB_DEBUG_STBY_LVC3_SCL_CONN")
	)
	(segment
		(start 474.80474 -135.83666)
		(end 475.34068 -136.3726)
		(width 0.1016)
		(layer "B.Cu")
		(net "SMB_DEBUG_STBY_LVC3_SCL_CONN")
	)
	(via
		(at 497.6368 -146.031966)
		(size 0.508)
		(drill 0.254)
		(layers "F.Cu" "B.Cu")
		(net "SPA_MID_DBG2_TX_R")
	)
	(segment
		(start 498.4496 -144.78)
		(end 499.080028 -144.78)
		(width 0.10795)
		(layer "B.Cu")
		(net "SPA_MID_DBG2_TX_R")
	)
	(segment
		(start 497.6368 -148.3614)
		(end 497.6368 -146.031966)
		(width 0.10795)
		(layer "B.Cu")
		(net "SPA_MID_DBG2_TX_R")
	)
	(segment
		(start 498.3734 -149.098)
		(end 497.6368 -148.3614)
		(width 0.10795)
		(layer "B.Cu")
		(net "SPA_MID_DBG2_TX_R")
	)
	(segment
		(start 500.38 -151.0538)
		(end 500.2022 -151.0538)
		(width 0.10795)
		(layer "B.Cu")
		(net "SPA_MID_DBG2_TX_R")
	)
	(segment
		(start 499.5672 -150.4188)
		(end 499.5672 -149.5552)
		(width 0.10795)
		(layer "B.Cu")
		(net "SPA_MID_DBG2_TX_R")
	)
	(segment
		(start 497.6368 -146.031966)
		(end 497.6368 -145.5928)
		(width 0.10795)
		(layer "B.Cu")
		(net "SPA_MID_DBG2_TX_R")
	)
	(segment
		(start 499.11 -149.098)
		(end 498.3734 -149.098)
		(width 0.10795)
		(layer "B.Cu")
		(net "SPA_MID_DBG2_TX_R")
	)
	(segment
		(start 499.5672 -149.5552)
		(end 499.11 -149.098)
		(width 0.10795)
		(layer "B.Cu")
		(net "SPA_MID_DBG2_TX_R")
	)
	(segment
		(start 500.2022 -151.0538)
		(end 499.5672 -150.4188)
		(width 0.10795)
		(layer "B.Cu")
		(net "SPA_MID_DBG2_TX_R")
	)
	(segment
		(start 497.6368 -145.5928)
		(end 498.4496 -144.78)
		(width 0.10795)
		(layer "B.Cu")
		(net "SPA_MID_DBG2_TX_R")
	)
	(via
		(at 501.142 -151.6888)
		(size 0.508)
		(drill 0.254)
		(layers "F.Cu" "B.Cu")
		(net "SPA_MID_DBG2_TX")
	)
	(segment
		(start 500.888 -151.9428)
		(end 501.142 -151.6888)
		(width 0.10795)
		(layer "B.Cu")
		(net "SPA_MID_DBG2_TX")
	)
	(segment
		(start 500.38 -151.9428)
		(end 500.888 -151.9428)
		(width 0.10795)
		(layer "B.Cu")
		(net "SPA_MID_DBG2_TX")
	)
	(segment
		(start 501.142 -151.6888)
		(end 500.9134 -151.6888)
		(width 0.089408)
		(layer "In4.Cu")
		(net "SPA_MID_DBG2_TX")
	)
	(segment
		(start 483.2096 -141.7701)
		(end 483.2096 -133.91388)
		(width 0.089408)
		(layer "In4.Cu")
		(net "SPA_MID_DBG2_TX")
	)
	(segment
		(start 488.48645 -150.9776)
		(end 485.9909 -148.48205)
		(width 0.089408)
		(layer "In4.Cu")
		(net "SPA_MID_DBG2_TX")
	)
	(segment
		(start 485.9909 -144.5514)
		(end 483.2096 -141.7701)
		(width 0.089408)
		(layer "In4.Cu")
		(net "SPA_MID_DBG2_TX")
	)
	(segment
		(start 483.2096 -133.91388)
		(end 482.75113 -133.45541)
		(width 0.089408)
		(layer "In4.Cu")
		(net "SPA_MID_DBG2_TX")
	)
	(segment
		(start 491.212632 -150.392892)
		(end 490.627924 -150.9776)
		(width 0.089408)
		(layer "In4.Cu")
		(net "SPA_MID_DBG2_TX")
	)
	(segment
		(start 500.9134 -151.6888)
		(end 500.2022 -150.9776)
		(width 0.089408)
		(layer "In4.Cu")
		(net "SPA_MID_DBG2_TX")
	)
	(segment
		(start 493.398048 -150.9776)
		(end 492.81334 -150.392892)
		(width 0.089408)
		(layer "In4.Cu")
		(net "SPA_MID_DBG2_TX")
	)
	(segment
		(start 490.627924 -150.9776)
		(end 488.48645 -150.9776)
		(width 0.089408)
		(layer "In4.Cu")
		(net "SPA_MID_DBG2_TX")
	)
	(segment
		(start 492.81334 -150.392892)
		(end 491.212632 -150.392892)
		(width 0.089408)
		(layer "In4.Cu")
		(net "SPA_MID_DBG2_TX")
	)
	(segment
		(start 500.2022 -150.9776)
		(end 493.398048 -150.9776)
		(width 0.089408)
		(layer "In4.Cu")
		(net "SPA_MID_DBG2_TX")
	)
	(segment
		(start 485.9909 -148.48205)
		(end 485.9909 -144.5514)
		(width 0.089408)
		(layer "In4.Cu")
		(net "SPA_MID_DBG2_TX")
	)
	(segment
		(start 483.616 -139.4206)
		(end 482.7524 -139.4206)
		(width 0.10795)
		(layer "F.Cu")
		(net "SPA_MID_DBG2_RX_BUF")
	)
	(segment
		(start 481.2284 -139.3444)
		(end 481.6348 -138.938)
		(width 0.10795)
		(layer "F.Cu")
		(net "SPA_MID_DBG2_RX_BUF")
	)
	(segment
		(start 479.3234 -138.7094)
		(end 479.9584 -139.3444)
		(width 0.10795)
		(layer "F.Cu")
		(net "SPA_MID_DBG2_RX_BUF")
	)
	(segment
		(start 482.154992 -138.938)
		(end 482.434392 -139.2174)
		(width 0.10795)
		(layer "F.Cu")
		(net "SPA_MID_DBG2_RX_BUF")
	)
	(segment
		(start 481.6348 -138.938)
		(end 482.154992 -138.938)
		(width 0.10795)
		(layer "F.Cu")
		(net "SPA_MID_DBG2_RX_BUF")
	)
	(segment
		(start 482.434392 -139.2174)
		(end 482.5492 -139.2174)
		(width 0.10795)
		(layer "F.Cu")
		(net "SPA_MID_DBG2_RX_BUF")
	)
	(segment
		(start 482.7524 -139.4206)
		(end 482.5492 -139.2174)
		(width 0.10795)
		(layer "F.Cu")
		(net "SPA_MID_DBG2_RX_BUF")
	)
	(segment
		(start 479.9584 -139.3444)
		(end 481.2284 -139.3444)
		(width 0.10795)
		(layer "F.Cu")
		(net "SPA_MID_DBG2_RX_BUF")
	)
	(via
		(at 482.5492 -139.2174)
		(size 0.508)
		(drill 0.254)
		(layers "F.Cu" "B.Cu")
		(net "SPA_MID_DBG2_RX_BUF")
	)
	(via
		(at 493.351312 -129.212848)
		(size 0.508)
		(drill 0.254)
		(layers "F.Cu" "B.Cu")
		(net "SPA_MID_DBG2_RX_BUF")
	)
	(via
		(at 494.07318 -129.76098)
		(size 0.6604)
		(drill 0.3302)
		(layers "F.Cu" "B.Cu")
		(net "SPA_MID_DBG2_RX_BUF")
	)
	(segment
		(start 493.720374 -129.212848)
		(end 493.351312 -129.212848)
		(width 0.10795)
		(layer "B.Cu")
		(net "SPA_MID_DBG2_RX_BUF")
	)
	(segment
		(start 494.07318 -129.565654)
		(end 493.720374 -129.212848)
		(width 0.10795)
		(layer "B.Cu")
		(net "SPA_MID_DBG2_RX_BUF")
	)
	(segment
		(start 494.07318 -130.51282)
		(end 493.653572 -130.932428)
		(width 0.10795)
		(layer "B.Cu")
		(net "SPA_MID_DBG2_RX_BUF")
	)
	(segment
		(start 494.07318 -129.76098)
		(end 494.07318 -129.565654)
		(width 0.10795)
		(layer "B.Cu")
		(net "SPA_MID_DBG2_RX_BUF")
	)
	(segment
		(start 493.653572 -130.932428)
		(end 493.653572 -131.445)
		(width 0.10795)
		(layer "B.Cu")
		(net "SPA_MID_DBG2_RX_BUF")
	)
	(segment
		(start 494.07318 -129.76098)
		(end 494.07318 -130.51282)
		(width 0.10795)
		(layer "B.Cu")
		(net "SPA_MID_DBG2_RX_BUF")
	)
	(segment
		(start 484.6574 -137.1092)
		(end 482.5492 -139.2174)
		(width 0.089408)
		(layer "In11.Cu")
		(net "SPA_MID_DBG2_RX_BUF")
	)
	(segment
		(start 493.8776 -129.739136)
		(end 493.8776 -133.7818)
		(width 0.089408)
		(layer "In11.Cu")
		(net "SPA_MID_DBG2_RX_BUF")
	)
	(segment
		(start 493.351312 -129.212848)
		(end 493.8776 -129.739136)
		(width 0.089408)
		(layer "In11.Cu")
		(net "SPA_MID_DBG2_RX_BUF")
	)
	(segment
		(start 490.5502 -137.1092)
		(end 484.6574 -137.1092)
		(width 0.089408)
		(layer "In11.Cu")
		(net "SPA_MID_DBG2_RX_BUF")
	)
	(segment
		(start 493.8776 -133.7818)
		(end 490.5502 -137.1092)
		(width 0.089408)
		(layer "In11.Cu")
		(net "SPA_MID_DBG2_RX_BUF")
	)
	(via
		(at 498.9322 -152.8826)
		(size 0.6604)
		(drill 0.3302)
		(layers "F.Cu" "B.Cu")
		(net "SPA_MID_DBG1_TX_R")
	)
	(segment
		(start 498.9322 -152.8826)
		(end 498.9322 -153.0604)
		(width 0.10795)
		(layer "B.Cu")
		(net "SPA_MID_DBG1_TX_R")
	)
	(segment
		(start 499.0592 -153.1874)
		(end 499.745 -153.1874)
		(width 0.10795)
		(layer "B.Cu")
		(net "SPA_MID_DBG1_TX_R")
	)
	(segment
		(start 498.953028 -149.9362)
		(end 498.953028 -150.439628)
		(width 0.10795)
		(layer "B.Cu")
		(net "SPA_MID_DBG1_TX_R")
	)
	(segment
		(start 498.9322 -152.4)
		(end 498.9322 -152.8826)
		(width 0.10795)
		(layer "B.Cu")
		(net "SPA_MID_DBG1_TX_R")
	)
	(segment
		(start 498.953028 -150.439628)
		(end 499.1862 -150.6728)
		(width 0.10795)
		(layer "B.Cu")
		(net "SPA_MID_DBG1_TX_R")
	)
	(segment
		(start 498.9322 -153.0604)
		(end 499.0592 -153.1874)
		(width 0.10795)
		(layer "B.Cu")
		(net "SPA_MID_DBG1_TX_R")
	)
	(segment
		(start 499.1862 -152.146)
		(end 498.9322 -152.4)
		(width 0.10795)
		(layer "B.Cu")
		(net "SPA_MID_DBG1_TX_R")
	)
	(segment
		(start 499.1862 -150.6728)
		(end 499.1862 -152.146)
		(width 0.10795)
		(layer "B.Cu")
		(net "SPA_MID_DBG1_TX_R")
	)
	(segment
		(start 500.253 -146.9136)
		(end 500.3292 -146.8374)
		(width 0.10795)
		(layer "B.Cu")
		(net "SPA_MID_DBG1_TX_EN")
	)
	(segment
		(start 500.253 -148.1582)
		(end 500.253 -146.9136)
		(width 0.10795)
		(layer "B.Cu")
		(net "SPA_MID_DBG1_TX_EN")
	)
	(via
		(at 498.8814 -154.432)
		(size 0.6604)
		(drill 0.3302)
		(layers "F.Cu" "B.Cu")
		(net "SPA_MID_DBG1_TX")
	)
	(segment
		(start 498.094 -154.432)
		(end 498.8814 -154.432)
		(width 0.10795)
		(layer "B.Cu")
		(net "SPA_MID_DBG1_TX")
	)
	(segment
		(start 496.000024 -149.84984)
		(end 496.8748 -150.724616)
		(width 0.10795)
		(layer "B.Cu")
		(net "SPA_MID_DBG1_TX")
	)
	(segment
		(start 497.4082 -153.7462)
		(end 498.094 -154.432)
		(width 0.10795)
		(layer "B.Cu")
		(net "SPA_MID_DBG1_TX")
	)
	(segment
		(start 500.634 -153.1874)
		(end 500.634 -153.7462)
		(width 0.10795)
		(layer "B.Cu")
		(net "SPA_MID_DBG1_TX")
	)
	(segment
		(start 497.4082 -153.2382)
		(end 497.4082 -153.7462)
		(width 0.10795)
		(layer "B.Cu")
		(net "SPA_MID_DBG1_TX")
	)
	(segment
		(start 499.9482 -154.432)
		(end 498.8814 -154.432)
		(width 0.10795)
		(layer "B.Cu")
		(net "SPA_MID_DBG1_TX")
	)
	(segment
		(start 500.634 -153.7462)
		(end 499.9482 -154.432)
		(width 0.10795)
		(layer "B.Cu")
		(net "SPA_MID_DBG1_TX")
	)
	(segment
		(start 496.8748 -152.7048)
		(end 497.4082 -153.2382)
		(width 0.10795)
		(layer "B.Cu")
		(net "SPA_MID_DBG1_TX")
	)
	(segment
		(start 496.8748 -150.724616)
		(end 496.8748 -152.7048)
		(width 0.10795)
		(layer "B.Cu")
		(net "SPA_MID_DBG1_TX")
	)
	(via
		(at 477.581468 -131.049268)
		(size 0.6604)
		(drill 0.3302)
		(layers "F.Cu" "B.Cu")
		(net "SMB_DEBUG_STBY_LVC3_SDA_R1")
	)
	(segment
		(start 475.4499 -129.42824)
		(end 475.4499 -130.449066)
		(width 0.10795)
		(layer "B.Cu")
		(net "SMB_DEBUG_STBY_LVC3_SDA_R1")
	)
	(segment
		(start 477.110806 -130.578606)
		(end 477.581468 -131.049268)
		(width 0.10795)
		(layer "B.Cu")
		(net "SMB_DEBUG_STBY_LVC3_SDA_R1")
	)
	(segment
		(start 475.4499 -127.878078)
		(end 474.814138 -127.242316)
		(width 0.10795)
		(layer "B.Cu")
		(net "SMB_DEBUG_STBY_LVC3_SDA_R1")
	)
	(segment
		(start 475.4499 -129.42824)
		(end 475.4499 -127.878078)
		(width 0.10795)
		(layer "B.Cu")
		(net "SMB_DEBUG_STBY_LVC3_SDA_R1")
	)
	(segment
		(start 475.4499 -130.449066)
		(end 475.57944 -130.578606)
		(width 0.10795)
		(layer "B.Cu")
		(net "SMB_DEBUG_STBY_LVC3_SDA_R1")
	)
	(segment
		(start 477.848422 -131.316222)
		(end 477.581468 -131.049268)
		(width 0.10795)
		(layer "B.Cu")
		(net "SMB_DEBUG_STBY_LVC3_SDA_R1")
	)
	(segment
		(start 477.848422 -131.949444)
		(end 477.848422 -131.316222)
		(width 0.10795)
		(layer "B.Cu")
		(net "SMB_DEBUG_STBY_LVC3_SDA_R1")
	)
	(segment
		(start 475.57944 -130.578606)
		(end 477.110806 -130.578606)
		(width 0.10795)
		(layer "B.Cu")
		(net "SMB_DEBUG_STBY_LVC3_SDA_R1")
	)
	(segment
		(start 477.081088 -131.94411)
		(end 477.081088 -131.265422)
		(width 0.10795)
		(layer "B.Cu")
		(net "SMB_DEBUG_STBY_LVC3_SCL_R1")
	)
	(segment
		(start 474.801946 -128.096772)
		(end 474.801946 -128.020572)
		(width 0.10795)
		(layer "B.Cu")
		(net "SMB_DEBUG_STBY_LVC3_SCL_R1")
	)
	(segment
		(start 474.79966 -129.42824)
		(end 474.79966 -128.099058)
		(width 0.10795)
		(layer "B.Cu")
		(net "SMB_DEBUG_STBY_LVC3_SCL_R1")
	)
	(segment
		(start 477.081088 -131.265422)
		(end 476.654876 -130.83921)
		(width 0.10795)
		(layer "B.Cu")
		(net "SMB_DEBUG_STBY_LVC3_SCL_R1")
	)
	(segment
		(start 474.79966 -130.39344)
		(end 474.79966 -129.42824)
		(width 0.10795)
		(layer "B.Cu")
		(net "SMB_DEBUG_STBY_LVC3_SCL_R1")
	)
	(segment
		(start 475.24543 -130.83921)
		(end 474.79966 -130.39344)
		(width 0.10795)
		(layer "B.Cu")
		(net "SMB_DEBUG_STBY_LVC3_SCL_R1")
	)
	(segment
		(start 474.79966 -128.099058)
		(end 474.801946 -128.096772)
		(width 0.10795)
		(layer "B.Cu")
		(net "SMB_DEBUG_STBY_LVC3_SCL_R1")
	)
	(segment
		(start 476.654876 -130.83921)
		(end 475.24543 -130.83921)
		(width 0.10795)
		(layer "B.Cu")
		(net "SMB_DEBUG_STBY_LVC3_SCL_R1")
	)
	(via
		(at 471.05062 -135.415528)
		(size 0.508)
		(drill 0.254)
		(layers "F.Cu" "B.Cu")
		(net "FM_CPU_CATERR_MSMI_LVT3_N")
	)
	(via
		(at 472.365832 -140.387832)
		(size 0.508)
		(drill 0.254)
		(layers "F.Cu" "B.Cu")
		(net "FM_CPU_CATERR_MSMI_LVT3_N")
	)
	(via
		(at 466.574886 -134.260844)
		(size 0.6604)
		(drill 0.3302)
		(layers "F.Cu" "B.Cu")
		(net "FM_CPU_CATERR_MSMI_LVT3_N")
	)
	(segment
		(start 469.138 -133.5024)
		(end 470.8906 -133.5024)
		(width 0.10795)
		(layer "B.Cu")
		(net "FM_CPU_CATERR_MSMI_LVT3_N")
	)
	(segment
		(start 470.535 -134.7978)
		(end 470.535 -134.4676)
		(width 0.10795)
		(layer "B.Cu")
		(net "FM_CPU_CATERR_MSMI_LVT3_N")
	)
	(segment
		(start 470.535 -134.7978)
		(end 470.535 -134.899908)
		(width 0.10795)
		(layer "B.Cu")
		(net "FM_CPU_CATERR_MSMI_LVT3_N")
	)
	(segment
		(start 469.138 -133.5024)
		(end 468.825072 -133.5024)
		(width 0.10795)
		(layer "B.Cu")
		(net "FM_CPU_CATERR_MSMI_LVT3_N")
	)
	(segment
		(start 468.496396 -133.173724)
		(end 467.665816 -133.173724)
		(width 0.10795)
		(layer "B.Cu")
		(net "FM_CPU_CATERR_MSMI_LVT3_N")
	)
	(segment
		(start 467.665816 -133.173724)
		(end 466.578696 -134.260844)
		(width 0.10795)
		(layer "B.Cu")
		(net "FM_CPU_CATERR_MSMI_LVT3_N")
	)
	(segment
		(start 468.825072 -133.5024)
		(end 468.496396 -133.173724)
		(width 0.10795)
		(layer "B.Cu")
		(net "FM_CPU_CATERR_MSMI_LVT3_N")
	)
	(segment
		(start 470.535 -134.899908)
		(end 471.05062 -135.415528)
		(width 0.10795)
		(layer "B.Cu")
		(net "FM_CPU_CATERR_MSMI_LVT3_N")
	)
	(segment
		(start 473.660216 -140.387832)
		(end 472.365832 -140.387832)
		(width 0.10795)
		(layer "B.Cu")
		(net "FM_CPU_CATERR_MSMI_LVT3_N")
	)
	(segment
		(start 470.535 -134.4676)
		(end 470.8906 -134.112)
		(width 0.10795)
		(layer "B.Cu")
		(net "FM_CPU_CATERR_MSMI_LVT3_N")
	)
	(segment
		(start 466.578696 -134.260844)
		(end 466.574886 -134.260844)
		(width 0.10795)
		(layer "B.Cu")
		(net "FM_CPU_CATERR_MSMI_LVT3_N")
	)
	(segment
		(start 470.8906 -134.112)
		(end 470.8906 -133.5024)
		(width 0.10795)
		(layer "B.Cu")
		(net "FM_CPU_CATERR_MSMI_LVT3_N")
	)
	(segment
		(start 472.854274 -137.231374)
		(end 472.854274 -139.89939)
		(width 0.089408)
		(layer "In4.Cu")
		(net "FM_CPU_CATERR_MSMI_LVT3_N")
	)
	(segment
		(start 472.854274 -139.89939)
		(end 472.365832 -140.387832)
		(width 0.089408)
		(layer "In4.Cu")
		(net "FM_CPU_CATERR_MSMI_LVT3_N")
	)
	(segment
		(start 471.05062 -135.415528)
		(end 471.05062 -135.42772)
		(width 0.089408)
		(layer "In4.Cu")
		(net "FM_CPU_CATERR_MSMI_LVT3_N")
	)
	(segment
		(start 471.05062 -135.42772)
		(end 472.854274 -137.231374)
		(width 0.089408)
		(layer "In4.Cu")
		(net "FM_CPU_CATERR_MSMI_LVT3_N")
	)
	(segment
		(start 484.732076 -139.4206)
		(end 485.394 -139.4206)
		(width 0.10795)
		(layer "F.Cu")
		(net "DEBUG_CARD2_PRSNT")
	)
	(segment
		(start 484.4288 -140.1064)
		(end 484.4288 -139.723876)
		(width 0.10795)
		(layer "F.Cu")
		(net "DEBUG_CARD2_PRSNT")
	)
	(segment
		(start 484.4288 -139.723876)
		(end 484.732076 -139.4206)
		(width 0.10795)
		(layer "F.Cu")
		(net "DEBUG_CARD2_PRSNT")
	)
	(via
		(at 484.4288 -140.1064)
		(size 0.508)
		(drill 0.254)
		(layers "F.Cu" "B.Cu")
		(net "DEBUG_CARD2_PRSNT")
	)
	(via
		(at 496.4049 -138.5189)
		(size 0.6604)
		(drill 0.3302)
		(layers "F.Cu" "B.Cu")
		(net "DEBUG_CARD2_PRSNT")
	)
	(segment
		(start 491.5789 -133.74624)
		(end 490.6772 -133.74624)
		(width 0.10795)
		(layer "B.Cu")
		(net "DEBUG_CARD2_PRSNT")
	)
	(segment
		(start 480.9236 -129.2225)
		(end 480.9236 -130.2131)
		(width 0.10795)
		(layer "B.Cu")
		(net "DEBUG_CARD2_PRSNT")
	)
	(segment
		(start 496.611402 -140.307314)
		(end 496.611402 -140.007594)
		(width 0.10795)
		(layer "B.Cu")
		(net "DEBUG_CARD2_PRSNT")
	)
	(segment
		(start 494.665 -135.2804)
		(end 494.203228 -134.818628)
		(width 0.10795)
		(layer "B.Cu")
		(net "DEBUG_CARD2_PRSNT")
	)
	(segment
		(start 496.4049 -137.6807)
		(end 495.1984 -136.4742)
		(width 0.10795)
		(layer "B.Cu")
		(net "DEBUG_CARD2_PRSNT")
	)
	(segment
		(start 483.642416 -134.56412)
		(end 484.751126 -133.45541)
		(width 0.10795)
		(layer "B.Cu")
		(net "DEBUG_CARD2_PRSNT")
	)
	(segment
		(start 498.036088 -141.732)
		(end 496.611402 -140.307314)
		(width 0.10795)
		(layer "B.Cu")
		(net "DEBUG_CARD2_PRSNT")
	)
	(segment
		(start 477.6978 -128.8415)
		(end 480.5426 -128.8415)
		(width 0.10795)
		(layer "B.Cu")
		(net "DEBUG_CARD2_PRSNT")
	)
	(segment
		(start 492.10214 -133.223)
		(end 491.5789 -133.74624)
		(width 0.10795)
		(layer "B.Cu")
		(net "DEBUG_CARD2_PRSNT")
	)
	(segment
		(start 494.203228 -134.310628)
		(end 494.0808 -134.1882)
		(width 0.10795)
		(layer "B.Cu")
		(net "DEBUG_CARD2_PRSNT")
	)
	(segment
		(start 492.3536 -134.060946)
		(end 492.3536 -133.223)
		(width 0.10795)
		(layer "B.Cu")
		(net "DEBUG_CARD2_PRSNT")
	)
	(segment
		(start 485.34955 -133.45541)
		(end 484.751126 -133.45541)
		(width 0.10795)
		(layer "B.Cu")
		(net "DEBUG_CARD2_PRSNT")
	)
	(segment
		(start 476.10014 -129.42824)
		(end 477.11106 -129.42824)
		(width 0.10795)
		(layer "B.Cu")
		(net "DEBUG_CARD2_PRSNT")
	)
	(segment
		(start 499.710202 -141.732)
		(end 498.036088 -141.732)
		(width 0.10795)
		(layer "B.Cu")
		(net "DEBUG_CARD2_PRSNT")
	)
	(segment
		(start 495.1984 -135.8138)
		(end 494.665 -135.2804)
		(width 0.10795)
		(layer "B.Cu")
		(net "DEBUG_CARD2_PRSNT")
	)
	(segment
		(start 490.6772 -133.74624)
		(end 489.51896 -132.588)
		(width 0.10795)
		(layer "B.Cu")
		(net "DEBUG_CARD2_PRSNT")
	)
	(segment
		(start 492.480854 -134.1882)
		(end 492.3536 -134.060946)
		(width 0.10795)
		(layer "B.Cu")
		(net "DEBUG_CARD2_PRSNT")
	)
	(segment
		(start 479.89871 -133.94309)
		(end 480.51974 -134.56412)
		(width 0.10795)
		(layer "B.Cu")
		(net "DEBUG_CARD2_PRSNT")
	)
	(segment
		(start 489.51896 -132.588)
		(end 486.21696 -132.588)
		(width 0.10795)
		(layer "B.Cu")
		(net "DEBUG_CARD2_PRSNT")
	)
	(segment
		(start 480.5426 -128.8415)
		(end 480.9236 -129.2225)
		(width 0.10795)
		(layer "B.Cu")
		(net "DEBUG_CARD2_PRSNT")
	)
	(segment
		(start 480.9236 -130.2131)
		(end 479.89871 -131.23799)
		(width 0.10795)
		(layer "B.Cu")
		(net "DEBUG_CARD2_PRSNT")
	)
	(segment
		(start 496.4049 -139.801092)
		(end 496.4049 -138.5189)
		(width 0.10795)
		(layer "B.Cu")
		(net "DEBUG_CARD2_PRSNT")
	)
	(segment
		(start 500.1514 -141.290802)
		(end 499.710202 -141.732)
		(width 0.10795)
		(layer "B.Cu")
		(net "DEBUG_CARD2_PRSNT")
	)
	(segment
		(start 492.3536 -133.223)
		(end 492.10214 -133.223)
		(width 0.10795)
		(layer "B.Cu")
		(net "DEBUG_CARD2_PRSNT")
	)
	(segment
		(start 500.1514 -141.290802)
		(end 500.38 -141.519402)
		(width 0.10795)
		(layer "B.Cu")
		(net "DEBUG_CARD2_PRSNT")
	)
	(segment
		(start 479.89871 -131.23799)
		(end 479.89871 -133.94309)
		(width 0.10795)
		(layer "B.Cu")
		(net "DEBUG_CARD2_PRSNT")
	)
	(segment
		(start 486.21696 -132.588)
		(end 485.34955 -133.45541)
		(width 0.10795)
		(layer "B.Cu")
		(net "DEBUG_CARD2_PRSNT")
	)
	(segment
		(start 496.611402 -140.007594)
		(end 496.4049 -139.801092)
		(width 0.10795)
		(layer "B.Cu")
		(net "DEBUG_CARD2_PRSNT")
	)
	(segment
		(start 495.1984 -136.4742)
		(end 495.1984 -135.8138)
		(width 0.10795)
		(layer "B.Cu")
		(net "DEBUG_CARD2_PRSNT")
	)
	(segment
		(start 494.203228 -134.818628)
		(end 494.203228 -134.310628)
		(width 0.10795)
		(layer "B.Cu")
		(net "DEBUG_CARD2_PRSNT")
	)
	(segment
		(start 500.38 -141.519402)
		(end 500.38 -143.002)
		(width 0.10795)
		(layer "B.Cu")
		(net "DEBUG_CARD2_PRSNT")
	)
	(segment
		(start 477.11106 -129.42824)
		(end 477.6978 -128.8415)
		(width 0.10795)
		(layer "B.Cu")
		(net "DEBUG_CARD2_PRSNT")
	)
	(segment
		(start 496.4049 -138.5189)
		(end 496.4049 -137.6807)
		(width 0.10795)
		(layer "B.Cu")
		(net "DEBUG_CARD2_PRSNT")
	)
	(segment
		(start 500.1514 -140.8684)
		(end 500.1514 -141.290802)
		(width 0.10795)
		(layer "B.Cu")
		(net "DEBUG_CARD2_PRSNT")
	)
	(segment
		(start 494.0808 -134.1882)
		(end 492.480854 -134.1882)
		(width 0.10795)
		(layer "B.Cu")
		(net "DEBUG_CARD2_PRSNT")
	)
	(segment
		(start 480.51974 -134.56412)
		(end 483.642416 -134.56412)
		(width 0.10795)
		(layer "B.Cu")
		(net "DEBUG_CARD2_PRSNT")
	)
	(segment
		(start 484.751126 -133.45541)
		(end 485.3178 -134.022084)
		(width 0.089408)
		(layer "In4.Cu")
		(net "DEBUG_CARD2_PRSNT")
	)
	(segment
		(start 484.4288 -140.0302)
		(end 484.4288 -140.1064)
		(width 0.089408)
		(layer "In4.Cu")
		(net "DEBUG_CARD2_PRSNT")
	)
	(segment
		(start 485.3178 -139.1412)
		(end 484.4288 -140.0302)
		(width 0.089408)
		(layer "In4.Cu")
		(net "DEBUG_CARD2_PRSNT")
	)
	(segment
		(start 485.3178 -134.022084)
		(end 485.3178 -139.1412)
		(width 0.089408)
		(layer "In4.Cu")
		(net "DEBUG_CARD2_PRSNT")
	)
	(segment
		(start 313.299602 -36.539678)
		(end 313.299602 -34.652458)
		(width 0.10795)
		(layer "F.Cu")
		(net "FM_ADR_COMPLETE_CPU1_R")
	)
	(segment
		(start 313.299602 -34.652458)
		(end 312.593228 -34.652458)
		(width 0.10795)
		(layer "F.Cu")
		(net "FM_ADR_COMPLETE_CPU1_R")
	)
	(segment
		(start 313.12866 -36.71062)
		(end 313.299602 -36.539678)
		(width 0.10795)
		(layer "F.Cu")
		(net "FM_ADR_COMPLETE_CPU1_R")
	)
	(segment
		(start 312.593228 -34.652458)
		(end 312.510932 -34.734754)
		(width 0.10795)
		(layer "F.Cu")
		(net "FM_ADR_COMPLETE_CPU1_R")
	)
	(segment
		(start 312.510932 -34.734754)
		(end 312.142124 -34.734754)
		(width 0.10795)
		(layer "F.Cu")
		(net "FM_ADR_COMPLETE_CPU1_R")
	)
	(via
		(at 313.12866 -36.71062)
		(size 0.762)
		(drill 0.381)
		(layers "F.Cu" "B.Cu")
		(net "FM_ADR_COMPLETE_CPU1_R")
	)
	(segment
		(start 309.18785 -32.492696)
		(end 309.18785 -32.93999)
		(width 0.10795)
		(layer "F.Cu")
		(net "FM_ADR_COMPLETE_CPU0_R")
	)
	(segment
		(start 311.34685 -33.942782)
		(end 311.34685 -34.726626)
		(width 0.10795)
		(layer "F.Cu")
		(net "FM_ADR_COMPLETE_CPU0_R")
	)
	(segment
		(start 309.605934 -30.239716)
		(end 309.18785 -30.6578)
		(width 0.10795)
		(layer "F.Cu")
		(net "FM_ADR_COMPLETE_CPU0_R")
	)
	(segment
		(start 309.18785 -30.6578)
		(end 309.18785 -32.492696)
		(width 0.10795)
		(layer "F.Cu")
		(net "FM_ADR_COMPLETE_CPU0_R")
	)
	(segment
		(start 309.18785 -32.93999)
		(end 309.543196 -33.295336)
		(width 0.10795)
		(layer "F.Cu")
		(net "FM_ADR_COMPLETE_CPU0_R")
	)
	(segment
		(start 309.543196 -33.295336)
		(end 310.699404 -33.295336)
		(width 0.10795)
		(layer "F.Cu")
		(net "FM_ADR_COMPLETE_CPU0_R")
	)
	(segment
		(start 310.699404 -33.295336)
		(end 311.34685 -33.942782)
		(width 0.10795)
		(layer "F.Cu")
		(net "FM_ADR_COMPLETE_CPU0_R")
	)
	(via
		(at 309.605934 -30.239716)
		(size 0.762)
		(drill 0.381)
		(layers "F.Cu" "B.Cu")
		(net "FM_ADR_COMPLETE_CPU0_R")
	)
	(via
		(at 308.8894 -27.05608)
		(size 0.6604)
		(drill 0.3302)
		(layers "F.Cu" "B.Cu")
		(net "IRQ_DIMM_SAVE_LVT3_CPU1")
	)
	(segment
		(start 316.449964 -28.52039)
		(end 316.449964 -27.115262)
		(width 0.10795)
		(layer "B.Cu")
		(net "IRQ_DIMM_SAVE_LVT3_CPU1")
	)
	(segment
		(start 313.944254 -26.731468)
		(end 313.349894 -26.137108)
		(width 0.10795)
		(layer "B.Cu")
		(net "IRQ_DIMM_SAVE_LVT3_CPU1")
	)
	(segment
		(start 315.410088 -30.209236)
		(end 315.497464 -30.296612)
		(width 0.10795)
		(layer "B.Cu")
		(net "IRQ_DIMM_SAVE_LVT3_CPU1")
	)
	(segment
		(start 308.8894 -26.5176)
		(end 308.8894 -27.05608)
		(width 0.10795)
		(layer "B.Cu")
		(net "IRQ_DIMM_SAVE_LVT3_CPU1")
	)
	(segment
		(start 315.410088 -29.511752)
		(end 315.410088 -30.209236)
		(width 0.10795)
		(layer "B.Cu")
		(net "IRQ_DIMM_SAVE_LVT3_CPU1")
	)
	(segment
		(start 316.449964 -27.115262)
		(end 316.06617 -26.731468)
		(width 0.10795)
		(layer "B.Cu")
		(net "IRQ_DIMM_SAVE_LVT3_CPU1")
	)
	(segment
		(start 316.060074 -29.511752)
		(end 316.060074 -28.91028)
		(width 0.10795)
		(layer "B.Cu")
		(net "IRQ_DIMM_SAVE_LVT3_CPU1")
	)
	(segment
		(start 316.06617 -26.731468)
		(end 313.944254 -26.731468)
		(width 0.10795)
		(layer "B.Cu")
		(net "IRQ_DIMM_SAVE_LVT3_CPU1")
	)
	(segment
		(start 315.497464 -30.296612)
		(end 315.898022 -30.296612)
		(width 0.10795)
		(layer "B.Cu")
		(net "IRQ_DIMM_SAVE_LVT3_CPU1")
	)
	(segment
		(start 316.060074 -30.13456)
		(end 316.060074 -29.511752)
		(width 0.10795)
		(layer "B.Cu")
		(net "IRQ_DIMM_SAVE_LVT3_CPU1")
	)
	(segment
		(start 308.8894 -27.508708)
		(end 309.436516 -28.055824)
		(width 0.10795)
		(layer "B.Cu")
		(net "IRQ_DIMM_SAVE_LVT3_CPU1")
	)
	(segment
		(start 308.8894 -27.05608)
		(end 308.8894 -27.508708)
		(width 0.10795)
		(layer "B.Cu")
		(net "IRQ_DIMM_SAVE_LVT3_CPU1")
	)
	(segment
		(start 315.898022 -30.296612)
		(end 316.060074 -30.13456)
		(width 0.10795)
		(layer "B.Cu")
		(net "IRQ_DIMM_SAVE_LVT3_CPU1")
	)
	(segment
		(start 313.349894 -26.137108)
		(end 309.269892 -26.137108)
		(width 0.10795)
		(layer "B.Cu")
		(net "IRQ_DIMM_SAVE_LVT3_CPU1")
	)
	(segment
		(start 316.060074 -28.91028)
		(end 316.449964 -28.52039)
		(width 0.10795)
		(layer "B.Cu")
		(net "IRQ_DIMM_SAVE_LVT3_CPU1")
	)
	(segment
		(start 309.269892 -26.137108)
		(end 308.8894 -26.5176)
		(width 0.10795)
		(layer "B.Cu")
		(net "IRQ_DIMM_SAVE_LVT3_CPU1")
	)
	(via
		(at 315.468 -31.75)
		(size 0.6604)
		(drill 0.3302)
		(layers "F.Cu" "B.Cu")
		(net "IRQ_DIMM_SAVE_CPU1_R_N")
	)
	(segment
		(start 315.410088 -28.145994)
		(end 315.130688 -28.425394)
		(width 0.10795)
		(layer "B.Cu")
		(net "IRQ_DIMM_SAVE_CPU1_R_N")
	)
	(segment
		(start 313.97575 -29.14142)
		(end 313.97575 -30.709108)
		(width 0.10795)
		(layer "B.Cu")
		(net "IRQ_DIMM_SAVE_CPU1_R_N")
	)
	(segment
		(start 313.97575 -30.709108)
		(end 314.0964 -30.829758)
		(width 0.10795)
		(layer "B.Cu")
		(net "IRQ_DIMM_SAVE_CPU1_R_N")
	)
	(segment
		(start 315.130688 -28.425394)
		(end 314.691776 -28.425394)
		(width 0.10795)
		(layer "B.Cu")
		(net "IRQ_DIMM_SAVE_CPU1_R_N")
	)
	(segment
		(start 314.691776 -28.425394)
		(end 313.97575 -29.14142)
		(width 0.10795)
		(layer "B.Cu")
		(net "IRQ_DIMM_SAVE_CPU1_R_N")
	)
	(segment
		(start 315.410088 -27.733752)
		(end 315.410088 -28.145994)
		(width 0.10795)
		(layer "B.Cu")
		(net "IRQ_DIMM_SAVE_CPU1_R_N")
	)
	(segment
		(start 314.547758 -30.829758)
		(end 314.0964 -30.829758)
		(width 0.10795)
		(layer "B.Cu")
		(net "IRQ_DIMM_SAVE_CPU1_R_N")
	)
	(segment
		(start 315.468 -31.75)
		(end 314.547758 -30.829758)
		(width 0.10795)
		(layer "B.Cu")
		(net "IRQ_DIMM_SAVE_CPU1_R_N")
	)
	(segment
		(start 319.028064 -35.432492)
		(end 320.433954 -35.432492)
		(width 0.10795)
		(layer "F.Cu")
		(net "FM_ADR_COMPLETE_CPU1_N")
	)
	(segment
		(start 322.7324 -35.750754)
		(end 322.7324 -35.052)
		(width 0.10795)
		(layer "F.Cu")
		(net "FM_ADR_COMPLETE_CPU1_N")
	)
	(segment
		(start 321.51574 -36.509706)
		(end 322.431156 -36.509706)
		(width 0.10795)
		(layer "F.Cu")
		(net "FM_ADR_COMPLETE_CPU1_N")
	)
	(segment
		(start 317.365126 -33.564576)
		(end 316.368938 -33.564576)
		(width 0.10795)
		(layer "F.Cu")
		(net "FM_ADR_COMPLETE_CPU1_N")
	)
	(segment
		(start 317.61938 -34.936938)
		(end 317.888874 -34.667444)
		(width 0.10795)
		(layer "F.Cu")
		(net "FM_ADR_COMPLETE_CPU1_N")
	)
	(segment
		(start 316.233556 -33.699958)
		(end 315.458602 -33.699958)
		(width 0.10795)
		(layer "F.Cu")
		(net "FM_ADR_COMPLETE_CPU1_N")
	)
	(segment
		(start 320.95313 -35.947096)
		(end 321.51574 -36.509706)
		(width 0.10795)
		(layer "F.Cu")
		(net "FM_ADR_COMPLETE_CPU1_N")
	)
	(segment
		(start 317.888874 -34.667444)
		(end 317.888874 -34.088324)
		(width 0.10795)
		(layer "F.Cu")
		(net "FM_ADR_COMPLETE_CPU1_N")
	)
	(segment
		(start 322.7324 -34.163)
		(end 322.7324 -35.052)
		(width 0.10795)
		(layer "F.Cu")
		(net "FM_ADR_COMPLETE_CPU1_N")
	)
	(segment
		(start 320.433954 -35.432492)
		(end 320.948558 -35.947096)
		(width 0.10795)
		(layer "F.Cu")
		(net "FM_ADR_COMPLETE_CPU1_N")
	)
	(segment
		(start 322.431156 -36.509706)
		(end 322.569332 -36.37153)
		(width 0.10795)
		(layer "F.Cu")
		(net "FM_ADR_COMPLETE_CPU1_N")
	)
	(segment
		(start 315.458602 -33.391602)
		(end 314.96 -32.893)
		(width 0.10795)
		(layer "F.Cu")
		(net "FM_ADR_COMPLETE_CPU1_N")
	)
	(segment
		(start 322.569332 -36.37153)
		(end 322.569332 -35.913822)
		(width 0.10795)
		(layer "F.Cu")
		(net "FM_ADR_COMPLETE_CPU1_N")
	)
	(segment
		(start 316.368938 -33.564576)
		(end 316.233556 -33.699958)
		(width 0.10795)
		(layer "F.Cu")
		(net "FM_ADR_COMPLETE_CPU1_N")
	)
	(segment
		(start 318.421512 -36.039044)
		(end 319.028064 -35.432492)
		(width 0.10795)
		(layer "F.Cu")
		(net "FM_ADR_COMPLETE_CPU1_N")
	)
	(segment
		(start 322.569332 -35.913822)
		(end 322.7324 -35.750754)
		(width 0.10795)
		(layer "F.Cu")
		(net "FM_ADR_COMPLETE_CPU1_N")
	)
	(segment
		(start 320.948558 -35.947096)
		(end 320.95313 -35.947096)
		(width 0.10795)
		(layer "F.Cu")
		(net "FM_ADR_COMPLETE_CPU1_N")
	)
	(segment
		(start 317.888874 -34.088324)
		(end 317.365126 -33.564576)
		(width 0.10795)
		(layer "F.Cu")
		(net "FM_ADR_COMPLETE_CPU1_N")
	)
	(segment
		(start 317.61938 -35.818572)
		(end 317.839852 -36.039044)
		(width 0.10795)
		(layer "F.Cu")
		(net "FM_ADR_COMPLETE_CPU1_N")
	)
	(segment
		(start 315.458602 -33.699958)
		(end 315.458602 -33.391602)
		(width 0.10795)
		(layer "F.Cu")
		(net "FM_ADR_COMPLETE_CPU1_N")
	)
	(segment
		(start 317.839852 -36.039044)
		(end 318.421512 -36.039044)
		(width 0.10795)
		(layer "F.Cu")
		(net "FM_ADR_COMPLETE_CPU1_N")
	)
	(segment
		(start 317.61938 -34.936938)
		(end 317.61938 -35.818572)
		(width 0.10795)
		(layer "F.Cu")
		(net "FM_ADR_COMPLETE_CPU1_N")
	)
	(via
		(at 314.96 -32.893)
		(size 0.508)
		(drill 0.254)
		(layers "F.Cu" "B.Cu")
		(net "FM_ADR_COMPLETE_CPU1_N")
	)
	(segment
		(start 314.96 -32.893)
		(end 314.0964 -32.0294)
		(width 0.10795)
		(layer "B.Cu")
		(net "FM_ADR_COMPLETE_CPU1_N")
	)
	(segment
		(start 314.0964 -32.0294)
		(end 314.0964 -31.718758)
		(width 0.10795)
		(layer "B.Cu")
		(net "FM_ADR_COMPLETE_CPU1_N")
	)
	(via
		(at 492.284258 -57.916064)
		(size 0.5588)
		(drill 0.3048)
		(layers "F.Cu" "B.Cu")
		(net "P5V_STBY_USBC")
	)
	(via
		(at 492.975138 -57.907936)
		(size 0.5588)
		(drill 0.3048)
		(layers "F.Cu" "B.Cu")
		(net "P5V_STBY_USBC")
	)
	(via
		(at 500.253 -58.3184)
		(size 0.5588)
		(drill 0.3048)
		(layers "F.Cu" "B.Cu")
		(net "P5V_STBY_USBC")
	)
	(via
		(at 485.195626 -56.732932)
		(size 0.5588)
		(drill 0.3048)
		(layers "F.Cu" "B.Cu")
		(net "P5V_STBY_USBC")
	)
	(via
		(at 485.178862 -57.42686)
		(size 0.5588)
		(drill 0.3048)
		(layers "F.Cu" "B.Cu")
		(net "P5V_STBY_USBC")
	)
	(via
		(at 498.54612 -58.875676)
		(size 0.6604)
		(drill 0.3302)
		(layers "F.Cu" "B.Cu")
		(net "P5V_STBY_USBC")
	)
	(via
		(at 499.4402 -58.3184)
		(size 0.5588)
		(drill 0.3048)
		(layers "F.Cu" "B.Cu")
		(net "P5V_STBY_USBC")
	)
	(segment
		(start 495.809016 -59.499246)
		(end 494.045494 -59.499246)
		(width 1.016)
		(layer "B.Cu")
		(net "P5V_STBY_USBC")
	)
	(segment
		(start 466.993986 -136.260586)
		(end 466.993986 -137.033)
		(width 0.10795)
		(layer "F.Cu")
		(net "JTAG_MCP_TCK_R1")
	)
	(segment
		(start 466.598 -135.8646)
		(end 466.993986 -136.260586)
		(width 0.10795)
		(layer "F.Cu")
		(net "JTAG_MCP_TCK_R1")
	)
	(via
		(at 466.598 -135.8646)
		(size 0.508)
		(drill 0.254)
		(layers "F.Cu" "B.Cu")
		(net "JTAG_MCP_TCK_R1")
	)
	(segment
		(start 464.4644 -135.255)
		(end 465.9884 -135.255)
		(width 0.10795)
		(layer "B.Cu")
		(net "JTAG_MCP_TCK_R1")
	)
	(segment
		(start 465.9884 -135.255)
		(end 466.598 -135.8646)
		(width 0.10795)
		(layer "B.Cu")
		(net "JTAG_MCP_TCK_R1")
	)
	(segment
		(start 451.117716 -60.788296)
		(end 451.117716 -60.480702)
		(width 0.1016)
		(layer "F.Cu")
		(net "KR_P1_OCP_TX_DP")
	)
	(segment
		(start 450.950076 -62.00267)
		(end 450.950076 -60.955936)
		(width 0.1016)
		(layer "F.Cu")
		(net "KR_P1_OCP_TX_DP")
	)
	(segment
		(start 451.117716 -60.480702)
		(end 451.015862 -60.378848)
		(width 0.1016)
		(layer "F.Cu")
		(net "KR_P1_OCP_TX_DP")
	)
	(segment
		(start 451.015862 -60.378848)
		(end 450.710554 -60.378848)
		(width 0.1016)
		(layer "F.Cu")
		(net "KR_P1_OCP_TX_DP")
	)
	(segment
		(start 398.63395 -103.84536)
		(end 399.12925 -103.615236)
		(width 0.10033)
		(layer "F.Cu")
		(net "KR_P1_OCP_TX_DP")
	)
	(segment
		(start 450.950076 -60.955936)
		(end 451.117716 -60.788296)
		(width 0.1016)
		(layer "F.Cu")
		(net "KR_P1_OCP_TX_DP")
	)
	(via
		(at 399.12925 -103.615236)
		(size 0.508)
		(drill 0.254)
		(layers "F.Cu" "B.Cu")
		(net "KR_P1_OCP_TX_DP")
	)
	(via
		(at 450.710554 -60.378848)
		(size 0.508)
		(drill 0.254)
		(layers "F.Cu" "B.Cu")
		(net "KR_P1_OCP_TX_DP")
	)
	(segment
		(start 443.641226 -56.57596)
		(end 443.335918 -56.270652)
		(width 0.101346)
		(layer "In9.Cu")
		(net "KR_P1_OCP_TX_DP")
	)
	(segment
		(start 404.850346 -100.645468)
		(end 404.850346 -101.077268)
		(width 0.101346)
		(layer "In9.Cu")
		(net "KR_P1_OCP_TX_DP")
	)
	(segment
		(start 411.136338 -96.126046)
		(end 409.470098 -97.792286)
		(width 0.101346)
		(layer "In9.Cu")
		(net "KR_P1_OCP_TX_DP")
	)
	(segment
		(start 417.845494 -63.930276)
		(end 417.845494 -79.249778)
		(width 0.101346)
		(layer "In9.Cu")
		(net "KR_P1_OCP_TX_DP")
	)
	(segment
		(start 417.281614 -79.813658)
		(end 417.281614 -83.577684)
		(width 0.101346)
		(layer "In9.Cu")
		(net "KR_P1_OCP_TX_DP")
	)
	(segment
		(start 412.401512 -89.943432)
		(end 411.136338 -91.208606)
		(width 0.101346)
		(layer "In9.Cu")
		(net "KR_P1_OCP_TX_DP")
	)
	(segment
		(start 400.379184 -102.979982)
		(end 400.379438 -102.979982)
		(width 0.089154)
		(layer "In9.Cu")
		(net "KR_P1_OCP_TX_DP")
	)
	(segment
		(start 440.898534 -56.270652)
		(end 436.494428 -56.270652)
		(width 0.101346)
		(layer "In9.Cu")
		(net "KR_P1_OCP_TX_DP")
	)
	(segment
		(start 418.401246 -61.125862)
		(end 418.401246 -63.374524)
		(width 0.101346)
		(layer "In9.Cu")
		(net "KR_P1_OCP_TX_DP")
	)
	(segment
		(start 417.281614 -83.577684)
		(end 414.920684 -85.938614)
		(width 0.101346)
		(layer "In9.Cu")
		(net "KR_P1_OCP_TX_DP")
	)
	(segment
		(start 404.635208 -101.292406)
		(end 404.203408 -101.292406)
		(width 0.101346)
		(layer "In9.Cu")
		(net "KR_P1_OCP_TX_DP")
	)
	(segment
		(start 450.710554 -60.378848)
		(end 451.034404 -60.378848)
		(width 0.101346)
		(layer "In9.Cu")
		(net "KR_P1_OCP_TX_DP")
	)
	(segment
		(start 445.525144 -56.270652)
		(end 445.219836 -56.57596)
		(width 0.101346)
		(layer "In9.Cu")
		(net "KR_P1_OCP_TX_DP")
	)
	(segment
		(start 443.945264 -56.57596)
		(end 443.641226 -56.57596)
		(width 0.101346)
		(layer "In9.Cu")
		(net "KR_P1_OCP_TX_DP")
	)
	(segment
		(start 429.532034 -54.71922)
		(end 427.743874 -56.50738)
		(width 0.101346)
		(layer "In9.Cu")
		(net "KR_P1_OCP_TX_DP")
	)
	(segment
		(start 403.498304 -101.99751)
		(end 401.361656 -101.99751)
		(width 0.101346)
		(layer "In9.Cu")
		(net "KR_P1_OCP_TX_DP")
	)
	(segment
		(start 427.743874 -56.50738)
		(end 425.760896 -56.50738)
		(width 0.101346)
		(layer "In9.Cu")
		(net "KR_P1_OCP_TX_DP")
	)
	(segment
		(start 425.760896 -56.50738)
		(end 424.758866 -57.50941)
		(width 0.101346)
		(layer "In9.Cu")
		(net "KR_P1_OCP_TX_DP")
	)
	(segment
		(start 442.422534 -56.57596)
		(end 442.117226 -56.270652)
		(width 0.101346)
		(layer "In9.Cu")
		(net "KR_P1_OCP_TX_DP")
	)
	(segment
		(start 441.203842 -56.57596)
		(end 440.898534 -56.270652)
		(width 0.101346)
		(layer "In9.Cu")
		(net "KR_P1_OCP_TX_DP")
	)
	(segment
		(start 398.791176 -103.615236)
		(end 399.12925 -103.615236)
		(width 0.089154)
		(layer "In9.Cu")
		(net "KR_P1_OCP_TX_DP")
	)
	(segment
		(start 444.250572 -56.270652)
		(end 443.945264 -56.57596)
		(width 0.101346)
		(layer "In9.Cu")
		(net "KR_P1_OCP_TX_DP")
	)
	(segment
		(start 405.754332 -97.792286)
		(end 405.224742 -98.321876)
		(width 0.101346)
		(layer "In9.Cu")
		(net "KR_P1_OCP_TX_DP")
	)
	(segment
		(start 443.03188 -56.270652)
		(end 442.726572 -56.57596)
		(width 0.101346)
		(layer "In9.Cu")
		(net "KR_P1_OCP_TX_DP")
	)
	(segment
		(start 404.850346 -101.077268)
		(end 404.635208 -101.292406)
		(width 0.101346)
		(layer "In9.Cu")
		(net "KR_P1_OCP_TX_DP")
	)
	(segment
		(start 413.436562 -87.514684)
		(end 412.401512 -88.549734)
		(width 0.101346)
		(layer "In9.Cu")
		(net "KR_P1_OCP_TX_DP")
	)
	(segment
		(start 398.733518 -103.557578)
		(end 398.791176 -103.615236)
		(width 0.089154)
		(layer "In9.Cu")
		(net "KR_P1_OCP_TX_DP")
	)
	(segment
		(start 442.117226 -56.270652)
		(end 441.813188 -56.270652)
		(width 0.101346)
		(layer "In9.Cu")
		(net "KR_P1_OCP_TX_DP")
	)
	(segment
		(start 399.984976 -103.212646)
		(end 399.132298 -103.212646)
		(width 0.089154)
		(layer "In9.Cu")
		(net "KR_P1_OCP_TX_DP")
	)
	(segment
		(start 418.401246 -63.374524)
		(end 417.845494 -63.930276)
		(width 0.101346)
		(layer "In9.Cu")
		(net "KR_P1_OCP_TX_DP")
	)
	(segment
		(start 401.361656 -101.99751)
		(end 400.379184 -102.979982)
		(width 0.101346)
		(layer "In9.Cu")
		(net "KR_P1_OCP_TX_DP")
	)
	(segment
		(start 441.50788 -56.57596)
		(end 441.203842 -56.57596)
		(width 0.101346)
		(layer "In9.Cu")
		(net "KR_P1_OCP_TX_DP")
	)
	(segment
		(start 434.942996 -54.71922)
		(end 429.532034 -54.71922)
		(width 0.101346)
		(layer "In9.Cu")
		(net "KR_P1_OCP_TX_DP")
	)
	(segment
		(start 412.401512 -88.549734)
		(end 412.401512 -89.943432)
		(width 0.101346)
		(layer "In9.Cu")
		(net "KR_P1_OCP_TX_DP")
	)
	(segment
		(start 451.034404 -60.378848)
		(end 451.13575 -60.277502)
		(width 0.101346)
		(layer "In9.Cu")
		(net "KR_P1_OCP_TX_DP")
	)
	(segment
		(start 448.210178 -56.270652)
		(end 445.525144 -56.270652)
		(width 0.101346)
		(layer "In9.Cu")
		(net "KR_P1_OCP_TX_DP")
	)
	(segment
		(start 413.676338 -85.938614)
		(end 413.436562 -86.17839)
		(width 0.101346)
		(layer "In9.Cu")
		(net "KR_P1_OCP_TX_DP")
	)
	(segment
		(start 413.436562 -86.17839)
		(end 413.436562 -87.514684)
		(width 0.101346)
		(layer "In9.Cu")
		(net "KR_P1_OCP_TX_DP")
	)
	(segment
		(start 404.203408 -101.292406)
		(end 403.498304 -101.99751)
		(width 0.101346)
		(layer "In9.Cu")
		(net "KR_P1_OCP_TX_DP")
	)
	(segment
		(start 400.36369 -102.99573)
		(end 400.202146 -102.99573)
		(width 0.089154)
		(layer "In9.Cu")
		(net "KR_P1_OCP_TX_DP")
	)
	(segment
		(start 443.335918 -56.270652)
		(end 443.03188 -56.270652)
		(width 0.101346)
		(layer "In9.Cu")
		(net "KR_P1_OCP_TX_DP")
	)
	(segment
		(start 417.845494 -79.249778)
		(end 417.281614 -79.813658)
		(width 0.101346)
		(layer "In9.Cu")
		(net "KR_P1_OCP_TX_DP")
	)
	(segment
		(start 411.136338 -91.208606)
		(end 411.136338 -96.126046)
		(width 0.101346)
		(layer "In9.Cu")
		(net "KR_P1_OCP_TX_DP")
	)
	(segment
		(start 400.379438 -102.979982)
		(end 400.36369 -102.99573)
		(width 0.089154)
		(layer "In9.Cu")
		(net "KR_P1_OCP_TX_DP")
	)
	(segment
		(start 441.813188 -56.270652)
		(end 441.50788 -56.57596)
		(width 0.101346)
		(layer "In9.Cu")
		(net "KR_P1_OCP_TX_DP")
	)
	(segment
		(start 444.915798 -56.57596)
		(end 444.61049 -56.270652)
		(width 0.101346)
		(layer "In9.Cu")
		(net "KR_P1_OCP_TX_DP")
	)
	(segment
		(start 424.758866 -57.50941)
		(end 422.017698 -57.50941)
		(width 0.101346)
		(layer "In9.Cu")
		(net "KR_P1_OCP_TX_DP")
	)
	(segment
		(start 400.12112 -103.076756)
		(end 400.120866 -103.076756)
		(width 0.089154)
		(layer "In9.Cu")
		(net "KR_P1_OCP_TX_DP")
	)
	(segment
		(start 409.470098 -97.792286)
		(end 405.754332 -97.792286)
		(width 0.101346)
		(layer "In9.Cu")
		(net "KR_P1_OCP_TX_DP")
	)
	(segment
		(start 400.202146 -102.99573)
		(end 400.12112 -103.076756)
		(width 0.089154)
		(layer "In9.Cu")
		(net "KR_P1_OCP_TX_DP")
	)
	(segment
		(start 405.224742 -98.321876)
		(end 405.224742 -100.271072)
		(width 0.101346)
		(layer "In9.Cu")
		(net "KR_P1_OCP_TX_DP")
	)
	(segment
		(start 405.224742 -100.271072)
		(end 404.850346 -100.645468)
		(width 0.101346)
		(layer "In9.Cu")
		(net "KR_P1_OCP_TX_DP")
	)
	(segment
		(start 422.017698 -57.50941)
		(end 418.401246 -61.125862)
		(width 0.101346)
		(layer "In9.Cu")
		(net "KR_P1_OCP_TX_DP")
	)
	(segment
		(start 442.726572 -56.57596)
		(end 442.422534 -56.57596)
		(width 0.101346)
		(layer "In9.Cu")
		(net "KR_P1_OCP_TX_DP")
	)
	(segment
		(start 445.219836 -56.57596)
		(end 444.915798 -56.57596)
		(width 0.101346)
		(layer "In9.Cu")
		(net "KR_P1_OCP_TX_DP")
	)
	(segment
		(start 414.920684 -85.938614)
		(end 413.676338 -85.938614)
		(width 0.101346)
		(layer "In9.Cu")
		(net "KR_P1_OCP_TX_DP")
	)
	(segment
		(start 436.494428 -56.270652)
		(end 434.942996 -54.71922)
		(width 0.101346)
		(layer "In9.Cu")
		(net "KR_P1_OCP_TX_DP")
	)
	(segment
		(start 400.120866 -103.076756)
		(end 399.984976 -103.212646)
		(width 0.089154)
		(layer "In9.Cu")
		(net "KR_P1_OCP_TX_DP")
	)
	(segment
		(start 451.13575 -60.277502)
		(end 451.13575 -59.196224)
		(width 0.101346)
		(layer "In9.Cu")
		(net "KR_P1_OCP_TX_DP")
	)
	(segment
		(start 451.13575 -59.196224)
		(end 448.210178 -56.270652)
		(width 0.101346)
		(layer "In9.Cu")
		(net "KR_P1_OCP_TX_DP")
	)
	(segment
		(start 444.61049 -56.270652)
		(end 444.250572 -56.270652)
		(width 0.101346)
		(layer "In9.Cu")
		(net "KR_P1_OCP_TX_DP")
	)
	(arc
		(start 399.132298 -103.212646)
		(mid 398.868636 -103.310834)
		(end 398.733518 -103.557578)
		(width 0.089154)
		(layer "In9.Cu")
		(net "KR_P1_OCP_TX_DP")
	)
	(segment
		(start 451.749922 -60.959238)
		(end 451.749922 -62.00267)
		(width 0.1016)
		(layer "F.Cu")
		(net "KR_P1_OCP_TX_DN")
	)
	(segment
		(start 451.576186 -60.785502)
		(end 451.749922 -60.959238)
		(width 0.1016)
		(layer "F.Cu")
		(net "KR_P1_OCP_TX_DN")
	)
	(segment
		(start 451.677786 -60.378848)
		(end 451.576186 -60.480448)
		(width 0.1016)
		(layer "F.Cu")
		(net "KR_P1_OCP_TX_DN")
	)
	(segment
		(start 451.980554 -60.378848)
		(end 451.677786 -60.378848)
		(width 0.1016)
		(layer "F.Cu")
		(net "KR_P1_OCP_TX_DN")
	)
	(segment
		(start 397.64335 -103.84536)
		(end 398.13865 -103.615236)
		(width 0.10033)
		(layer "F.Cu")
		(net "KR_P1_OCP_TX_DN")
	)
	(segment
		(start 451.576186 -60.480448)
		(end 451.576186 -60.785502)
		(width 0.1016)
		(layer "F.Cu")
		(net "KR_P1_OCP_TX_DN")
	)
	(via
		(at 398.13865 -103.615236)
		(size 0.508)
		(drill 0.254)
		(layers "F.Cu" "B.Cu")
		(net "KR_P1_OCP_TX_DN")
	)
	(via
		(at 451.980554 -60.378848)
		(size 0.508)
		(drill 0.254)
		(layers "F.Cu" "B.Cu")
		(net "KR_P1_OCP_TX_DN")
	)
	(segment
		(start 398.13865 -103.615236)
		(end 398.476724 -103.615236)
		(width 0.089154)
		(layer "In9.Cu")
		(net "KR_P1_OCP_TX_DN")
	)
	(segment
		(start 401.18792 -101.578156)
		(end 403.324568 -101.578156)
		(width 0.101346)
		(layer "In9.Cu")
		(net "KR_P1_OCP_TX_DN")
	)
	(segment
		(start 411.982158 -89.769696)
		(end 411.982158 -88.375998)
		(width 0.101346)
		(layer "In9.Cu")
		(net "KR_P1_OCP_TX_DN")
	)
	(segment
		(start 409.296362 -97.372932)
		(end 410.716984 -95.95231)
		(width 0.101346)
		(layer "In9.Cu")
		(net "KR_P1_OCP_TX_DN")
	)
	(segment
		(start 417.981892 -60.952126)
		(end 421.843962 -57.090056)
		(width 0.101346)
		(layer "In9.Cu")
		(net "KR_P1_OCP_TX_DN")
	)
	(segment
		(start 429.358298 -54.299866)
		(end 435.116732 -54.299866)
		(width 0.101346)
		(layer "In9.Cu")
		(net "KR_P1_OCP_TX_DN")
	)
	(segment
		(start 425.58716 -56.088026)
		(end 427.570138 -56.088026)
		(width 0.101346)
		(layer "In9.Cu")
		(net "KR_P1_OCP_TX_DN")
	)
	(segment
		(start 427.570138 -56.088026)
		(end 429.358298 -54.299866)
		(width 0.101346)
		(layer "In9.Cu")
		(net "KR_P1_OCP_TX_DN")
	)
	(segment
		(start 436.668164 -55.851298)
		(end 448.383914 -55.851298)
		(width 0.101346)
		(layer "In9.Cu")
		(net "KR_P1_OCP_TX_DN")
	)
	(segment
		(start 451.555104 -59.022488)
		(end 451.555104 -60.277502)
		(width 0.101346)
		(layer "In9.Cu")
		(net "KR_P1_OCP_TX_DN")
	)
	(segment
		(start 399.132044 -103.021892)
		(end 399.905728 -103.021892)
		(width 0.089154)
		(layer "In9.Cu")
		(net "KR_P1_OCP_TX_DN")
	)
	(segment
		(start 451.555104 -60.277502)
		(end 451.65645 -60.378848)
		(width 0.101346)
		(layer "In9.Cu")
		(net "KR_P1_OCP_TX_DN")
	)
	(segment
		(start 400.067018 -102.860602)
		(end 400.067018 -102.699058)
		(width 0.089154)
		(layer "In9.Cu")
		(net "KR_P1_OCP_TX_DN")
	)
	(segment
		(start 416.86226 -79.639922)
		(end 417.42614 -79.076042)
		(width 0.101346)
		(layer "In9.Cu")
		(net "KR_P1_OCP_TX_DN")
	)
	(segment
		(start 398.476724 -103.615236)
		(end 398.544542 -103.530146)
		(width 0.089154)
		(layer "In9.Cu")
		(net "KR_P1_OCP_TX_DN")
	)
	(segment
		(start 414.746948 -85.51926)
		(end 416.86226 -83.403948)
		(width 0.101346)
		(layer "In9.Cu")
		(net "KR_P1_OCP_TX_DN")
	)
	(segment
		(start 403.324568 -101.578156)
		(end 404.805388 -100.097336)
		(width 0.101346)
		(layer "In9.Cu")
		(net "KR_P1_OCP_TX_DN")
	)
	(segment
		(start 451.65645 -60.378848)
		(end 451.980554 -60.378848)
		(width 0.101346)
		(layer "In9.Cu")
		(net "KR_P1_OCP_TX_DN")
	)
	(segment
		(start 400.067018 -102.699058)
		(end 400.082766 -102.68331)
		(width 0.089154)
		(layer "In9.Cu")
		(net "KR_P1_OCP_TX_DN")
	)
	(segment
		(start 413.017208 -87.340948)
		(end 413.017208 -86.004654)
		(width 0.101346)
		(layer "In9.Cu")
		(net "KR_P1_OCP_TX_DN")
	)
	(segment
		(start 435.116732 -54.299866)
		(end 436.668164 -55.851298)
		(width 0.101346)
		(layer "In9.Cu")
		(net "KR_P1_OCP_TX_DN")
	)
	(segment
		(start 411.982158 -88.375998)
		(end 413.017208 -87.340948)
		(width 0.101346)
		(layer "In9.Cu")
		(net "KR_P1_OCP_TX_DN")
	)
	(segment
		(start 417.42614 -63.75654)
		(end 417.981892 -63.200788)
		(width 0.101346)
		(layer "In9.Cu")
		(net "KR_P1_OCP_TX_DN")
	)
	(segment
		(start 404.805388 -98.14814)
		(end 405.580596 -97.372932)
		(width 0.101346)
		(layer "In9.Cu")
		(net "KR_P1_OCP_TX_DN")
	)
	(segment
		(start 413.017208 -86.004654)
		(end 413.502602 -85.51926)
		(width 0.101346)
		(layer "In9.Cu")
		(net "KR_P1_OCP_TX_DN")
	)
	(segment
		(start 417.42614 -79.076042)
		(end 417.42614 -63.75654)
		(width 0.101346)
		(layer "In9.Cu")
		(net "KR_P1_OCP_TX_DN")
	)
	(segment
		(start 399.905728 -103.021892)
		(end 400.067018 -102.860602)
		(width 0.089154)
		(layer "In9.Cu")
		(net "KR_P1_OCP_TX_DN")
	)
	(segment
		(start 416.86226 -83.403948)
		(end 416.86226 -79.639922)
		(width 0.101346)
		(layer "In9.Cu")
		(net "KR_P1_OCP_TX_DN")
	)
	(segment
		(start 405.580596 -97.372932)
		(end 409.296362 -97.372932)
		(width 0.101346)
		(layer "In9.Cu")
		(net "KR_P1_OCP_TX_DN")
	)
	(segment
		(start 417.981892 -63.200788)
		(end 417.981892 -60.952126)
		(width 0.101346)
		(layer "In9.Cu")
		(net "KR_P1_OCP_TX_DN")
	)
	(segment
		(start 404.805388 -100.097336)
		(end 404.805388 -98.14814)
		(width 0.101346)
		(layer "In9.Cu")
		(net "KR_P1_OCP_TX_DN")
	)
	(segment
		(start 410.716984 -91.03487)
		(end 411.982158 -89.769696)
		(width 0.101346)
		(layer "In9.Cu")
		(net "KR_P1_OCP_TX_DN")
	)
	(segment
		(start 448.383914 -55.851298)
		(end 451.555104 -59.022488)
		(width 0.101346)
		(layer "In9.Cu")
		(net "KR_P1_OCP_TX_DN")
	)
	(segment
		(start 410.716984 -95.95231)
		(end 410.716984 -91.03487)
		(width 0.101346)
		(layer "In9.Cu")
		(net "KR_P1_OCP_TX_DN")
	)
	(segment
		(start 424.58513 -57.090056)
		(end 425.58716 -56.088026)
		(width 0.101346)
		(layer "In9.Cu")
		(net "KR_P1_OCP_TX_DN")
	)
	(segment
		(start 413.502602 -85.51926)
		(end 414.746948 -85.51926)
		(width 0.101346)
		(layer "In9.Cu")
		(net "KR_P1_OCP_TX_DN")
	)
	(segment
		(start 421.843962 -57.090056)
		(end 424.58513 -57.090056)
		(width 0.101346)
		(layer "In9.Cu")
		(net "KR_P1_OCP_TX_DN")
	)
	(segment
		(start 400.082766 -102.68331)
		(end 401.18792 -101.578156)
		(width 0.101346)
		(layer "In9.Cu")
		(net "KR_P1_OCP_TX_DN")
	)
	(arc
		(start 398.544542 -103.530146)
		(mid 398.743652 -103.166591)
		(end 399.132044 -103.021892)
		(width 0.089154)
		(layer "In9.Cu")
		(net "KR_P1_OCP_TX_DN")
	)
	(segment
		(start 460.319628 -63.626492)
		(end 460.622396 -63.626492)
		(width 0.1016)
		(layer "F.Cu")
		(net "KR_P1_OCP_RX_DP")
	)
	(segment
		(start 460.550006 -63.045848)
		(end 460.550006 -62.00267)
		(width 0.10033)
		(layer "F.Cu")
		(net "KR_P1_OCP_RX_DP")
	)
	(segment
		(start 407.950162 -96.303846)
		(end 407.753566 -96.500442)
		(width 0.10033)
		(layer "F.Cu")
		(net "KR_P1_OCP_RX_DP")
	)
	(segment
		(start 460.55026 -63.046102)
		(end 460.550006 -63.045848)
		(width 0.10033)
		(layer "F.Cu")
		(net "KR_P1_OCP_RX_DP")
	)
	(segment
		(start 408.469084 -96.601788)
		(end 408.171142 -96.303846)
		(width 0.10033)
		(layer "F.Cu")
		(net "KR_P1_OCP_RX_DP")
	)
	(segment
		(start 460.723996 -63.219838)
		(end 460.55026 -63.046102)
		(width 0.1016)
		(layer "F.Cu")
		(net "KR_P1_OCP_RX_DP")
	)
	(segment
		(start 460.622396 -63.626492)
		(end 460.723996 -63.524892)
		(width 0.1016)
		(layer "F.Cu")
		(net "KR_P1_OCP_RX_DP")
	)
	(segment
		(start 460.723996 -63.524892)
		(end 460.723996 -63.219838)
		(width 0.1016)
		(layer "F.Cu")
		(net "KR_P1_OCP_RX_DP")
	)
	(segment
		(start 408.171142 -96.303846)
		(end 407.950162 -96.303846)
		(width 0.10033)
		(layer "F.Cu")
		(net "KR_P1_OCP_RX_DP")
	)
	(via
		(at 460.319628 -63.626492)
		(size 0.508)
		(drill 0.254)
		(layers "F.Cu" "B.Cu")
		(net "KR_P1_OCP_RX_DP")
	)
	(via
		(at 408.469084 -96.601788)
		(size 0.508)
		(drill 0.254)
		(layers "F.Cu" "B.Cu")
		(net "KR_P1_OCP_RX_DP")
	)
	(segment
		(start 450.716142 -55.15229)
		(end 456.76693 -55.15229)
		(width 0.101346)
		(layer "In9.Cu")
		(net "KR_P1_OCP_RX_DP")
	)
	(segment
		(start 415.154364 -83.781138)
		(end 415.154364 -82.812128)
		(width 0.101346)
		(layer "In9.Cu")
		(net "KR_P1_OCP_RX_DP")
	)
	(segment
		(start 424.279314 -56.449468)
		(end 425.303442 -55.42534)
		(width 0.101346)
		(layer "In9.Cu")
		(net "KR_P1_OCP_RX_DP")
	)
	(segment
		(start 425.303442 -55.42534)
		(end 426.80382 -55.42534)
		(width 0.101346)
		(layer "In9.Cu")
		(net "KR_P1_OCP_RX_DP")
	)
	(segment
		(start 409.443174 -96.203262)
		(end 410.082238 -95.564198)
		(width 0.101346)
		(layer "In9.Cu")
		(net "KR_P1_OCP_RX_DP")
	)
	(segment
		(start 448.888104 -55.457598)
		(end 449.192142 -55.457598)
		(width 0.101346)
		(layer "In9.Cu")
		(net "KR_P1_OCP_RX_DP")
	)
	(segment
		(start 460.744824 -63.201296)
		(end 460.319628 -63.626492)
		(width 0.101346)
		(layer "In9.Cu")
		(net "KR_P1_OCP_RX_DP")
	)
	(segment
		(start 421.563292 -56.449468)
		(end 424.279314 -56.449468)
		(width 0.101346)
		(layer "In9.Cu")
		(net "KR_P1_OCP_RX_DP")
	)
	(segment
		(start 416.791394 -63.044324)
		(end 416.983418 -62.8523)
		(width 0.101346)
		(layer "In9.Cu")
		(net "KR_P1_OCP_RX_DP")
	)
	(segment
		(start 412.363412 -85.619336)
		(end 413.100774 -84.881974)
		(width 0.101346)
		(layer "In9.Cu")
		(net "KR_P1_OCP_RX_DP")
	)
	(segment
		(start 437.021224 -55.15229)
		(end 448.582796 -55.15229)
		(width 0.101346)
		(layer "In9.Cu")
		(net "KR_P1_OCP_RX_DP")
	)
	(segment
		(start 416.983418 -61.029342)
		(end 421.563292 -56.449468)
		(width 0.101346)
		(layer "In9.Cu")
		(net "KR_P1_OCP_RX_DP")
	)
	(segment
		(start 410.082238 -88.50757)
		(end 411.038548 -87.55126)
		(width 0.101346)
		(layer "In9.Cu")
		(net "KR_P1_OCP_RX_DP")
	)
	(segment
		(start 450.106796 -55.457598)
		(end 450.410834 -55.457598)
		(width 0.101346)
		(layer "In9.Cu")
		(net "KR_P1_OCP_RX_DP")
	)
	(segment
		(start 449.801488 -55.15229)
		(end 450.106796 -55.457598)
		(width 0.101346)
		(layer "In9.Cu")
		(net "KR_P1_OCP_RX_DP")
	)
	(segment
		(start 415.6202 -80.0989)
		(end 415.6202 -78.9051)
		(width 0.101346)
		(layer "In9.Cu")
		(net "KR_P1_OCP_RX_DP")
	)
	(segment
		(start 416.791394 -77.733906)
		(end 416.791394 -63.044324)
		(width 0.101346)
		(layer "In9.Cu")
		(net "KR_P1_OCP_RX_DP")
	)
	(segment
		(start 426.80382 -55.42534)
		(end 428.634144 -53.595016)
		(width 0.101346)
		(layer "In9.Cu")
		(net "KR_P1_OCP_RX_DP")
	)
	(segment
		(start 410.082238 -95.564198)
		(end 410.082238 -88.50757)
		(width 0.101346)
		(layer "In9.Cu")
		(net "KR_P1_OCP_RX_DP")
	)
	(segment
		(start 416.983418 -62.8523)
		(end 416.983418 -61.029342)
		(width 0.101346)
		(layer "In9.Cu")
		(net "KR_P1_OCP_RX_DP")
	)
	(segment
		(start 411.038548 -87.55126)
		(end 411.800294 -87.55126)
		(width 0.101346)
		(layer "In9.Cu")
		(net "KR_P1_OCP_RX_DP")
	)
	(segment
		(start 413.100774 -84.881974)
		(end 414.053528 -84.881974)
		(width 0.101346)
		(layer "In9.Cu")
		(net "KR_P1_OCP_RX_DP")
	)
	(segment
		(start 450.410834 -55.457598)
		(end 450.716142 -55.15229)
		(width 0.101346)
		(layer "In9.Cu")
		(net "KR_P1_OCP_RX_DP")
	)
	(segment
		(start 408.86761 -96.203262)
		(end 409.443174 -96.203262)
		(width 0.101346)
		(layer "In9.Cu")
		(net "KR_P1_OCP_RX_DP")
	)
	(segment
		(start 449.192142 -55.457598)
		(end 449.49745 -55.15229)
		(width 0.101346)
		(layer "In9.Cu")
		(net "KR_P1_OCP_RX_DP")
	)
	(segment
		(start 460.744824 -59.130184)
		(end 460.744824 -63.201296)
		(width 0.101346)
		(layer "In9.Cu")
		(net "KR_P1_OCP_RX_DP")
	)
	(segment
		(start 456.76693 -55.15229)
		(end 460.744824 -59.130184)
		(width 0.101346)
		(layer "In9.Cu")
		(net "KR_P1_OCP_RX_DP")
	)
	(segment
		(start 414.91027 -80.80883)
		(end 415.6202 -80.0989)
		(width 0.101346)
		(layer "In9.Cu")
		(net "KR_P1_OCP_RX_DP")
	)
	(segment
		(start 411.800294 -87.55126)
		(end 412.363412 -86.988142)
		(width 0.101346)
		(layer "In9.Cu")
		(net "KR_P1_OCP_RX_DP")
	)
	(segment
		(start 415.154364 -82.812128)
		(end 414.91027 -82.568034)
		(width 0.101346)
		(layer "In9.Cu")
		(net "KR_P1_OCP_RX_DP")
	)
	(segment
		(start 428.634144 -53.595016)
		(end 435.46395 -53.595016)
		(width 0.101346)
		(layer "In9.Cu")
		(net "KR_P1_OCP_RX_DP")
	)
	(segment
		(start 408.469084 -96.601788)
		(end 408.86761 -96.203262)
		(width 0.101346)
		(layer "In9.Cu")
		(net "KR_P1_OCP_RX_DP")
	)
	(segment
		(start 435.46395 -53.595016)
		(end 437.021224 -55.15229)
		(width 0.101346)
		(layer "In9.Cu")
		(net "KR_P1_OCP_RX_DP")
	)
	(segment
		(start 448.582796 -55.15229)
		(end 448.888104 -55.457598)
		(width 0.101346)
		(layer "In9.Cu")
		(net "KR_P1_OCP_RX_DP")
	)
	(segment
		(start 449.49745 -55.15229)
		(end 449.801488 -55.15229)
		(width 0.101346)
		(layer "In9.Cu")
		(net "KR_P1_OCP_RX_DP")
	)
	(segment
		(start 414.91027 -82.568034)
		(end 414.91027 -80.80883)
		(width 0.101346)
		(layer "In9.Cu")
		(net "KR_P1_OCP_RX_DP")
	)
	(segment
		(start 415.6202 -78.9051)
		(end 416.791394 -77.733906)
		(width 0.101346)
		(layer "In9.Cu")
		(net "KR_P1_OCP_RX_DP")
	)
	(segment
		(start 412.363412 -86.988142)
		(end 412.363412 -85.619336)
		(width 0.101346)
		(layer "In9.Cu")
		(net "KR_P1_OCP_RX_DP")
	)
	(segment
		(start 414.053528 -84.881974)
		(end 415.154364 -83.781138)
		(width 0.101346)
		(layer "In9.Cu")
		(net "KR_P1_OCP_RX_DP")
	)
	(segment
		(start 461.182466 -63.208916)
		(end 461.350106 -63.041276)
		(width 0.1016)
		(layer "F.Cu")
		(net "KR_P1_OCP_RX_DN")
	)
	(segment
		(start 407.91257 -95.846646)
		(end 407.753566 -95.687642)
		(width 0.10033)
		(layer "F.Cu")
		(net "KR_P1_OCP_RX_DN")
	)
	(segment
		(start 408.469084 -95.547434)
		(end 408.169872 -95.846646)
		(width 0.10033)
		(layer "F.Cu")
		(net "KR_P1_OCP_RX_DN")
	)
	(segment
		(start 461.350106 -63.041276)
		(end 461.350106 -62.00267)
		(width 0.10033)
		(layer "F.Cu")
		(net "KR_P1_OCP_RX_DN")
	)
	(segment
		(start 408.169872 -95.846646)
		(end 407.91257 -95.846646)
		(width 0.10033)
		(layer "F.Cu")
		(net "KR_P1_OCP_RX_DN")
	)
	(segment
		(start 461.589628 -63.626492)
		(end 461.28432 -63.626492)
		(width 0.1016)
		(layer "F.Cu")
		(net "KR_P1_OCP_RX_DN")
	)
	(segment
		(start 461.182466 -63.524638)
		(end 461.182466 -63.208916)
		(width 0.1016)
		(layer "F.Cu")
		(net "KR_P1_OCP_RX_DN")
	)
	(segment
		(start 461.28432 -63.626492)
		(end 461.182466 -63.524638)
		(width 0.1016)
		(layer "F.Cu")
		(net "KR_P1_OCP_RX_DN")
	)
	(via
		(at 408.469084 -95.547434)
		(size 0.508)
		(drill 0.254)
		(layers "F.Cu" "B.Cu")
		(net "KR_P1_OCP_RX_DN")
	)
	(via
		(at 461.589628 -63.626492)
		(size 0.508)
		(drill 0.254)
		(layers "F.Cu" "B.Cu")
		(net "KR_P1_OCP_RX_DN")
	)
	(segment
		(start 437.19496 -54.732936)
		(end 456.940666 -54.732936)
		(width 0.101346)
		(layer "In9.Cu")
		(net "KR_P1_OCP_RX_DN")
	)
	(segment
		(start 416.37204 -77.56017)
		(end 416.37204 -62.870588)
		(width 0.101346)
		(layer "In9.Cu")
		(net "KR_P1_OCP_RX_DN")
	)
	(segment
		(start 461.164178 -63.201042)
		(end 461.589628 -63.626492)
		(width 0.101346)
		(layer "In9.Cu")
		(net "KR_P1_OCP_RX_DN")
	)
	(segment
		(start 410.864812 -87.131906)
		(end 411.626558 -87.131906)
		(width 0.101346)
		(layer "In9.Cu")
		(net "KR_P1_OCP_RX_DN")
	)
	(segment
		(start 409.662884 -88.333834)
		(end 410.864812 -87.131906)
		(width 0.101346)
		(layer "In9.Cu")
		(net "KR_P1_OCP_RX_DN")
	)
	(segment
		(start 408.705558 -95.783908)
		(end 409.269438 -95.783908)
		(width 0.101346)
		(layer "In9.Cu")
		(net "KR_P1_OCP_RX_DN")
	)
	(segment
		(start 412.927038 -84.46262)
		(end 413.879792 -84.46262)
		(width 0.101346)
		(layer "In9.Cu")
		(net "KR_P1_OCP_RX_DN")
	)
	(segment
		(start 435.637686 -53.175662)
		(end 437.19496 -54.732936)
		(width 0.101346)
		(layer "In9.Cu")
		(net "KR_P1_OCP_RX_DN")
	)
	(segment
		(start 415.200846 -78.731364)
		(end 416.37204 -77.56017)
		(width 0.101346)
		(layer "In9.Cu")
		(net "KR_P1_OCP_RX_DN")
	)
	(segment
		(start 424.105578 -56.030114)
		(end 425.129706 -55.005986)
		(width 0.101346)
		(layer "In9.Cu")
		(net "KR_P1_OCP_RX_DN")
	)
	(segment
		(start 414.490916 -80.635094)
		(end 415.200846 -79.925164)
		(width 0.101346)
		(layer "In9.Cu")
		(net "KR_P1_OCP_RX_DN")
	)
	(segment
		(start 416.37204 -62.870588)
		(end 416.564064 -62.678564)
		(width 0.101346)
		(layer "In9.Cu")
		(net "KR_P1_OCP_RX_DN")
	)
	(segment
		(start 414.73501 -83.607402)
		(end 414.73501 -82.985864)
		(width 0.101346)
		(layer "In9.Cu")
		(net "KR_P1_OCP_RX_DN")
	)
	(segment
		(start 426.630084 -55.005986)
		(end 428.460408 -53.175662)
		(width 0.101346)
		(layer "In9.Cu")
		(net "KR_P1_OCP_RX_DN")
	)
	(segment
		(start 456.940666 -54.732936)
		(end 461.164178 -58.956448)
		(width 0.101346)
		(layer "In9.Cu")
		(net "KR_P1_OCP_RX_DN")
	)
	(segment
		(start 413.879792 -84.46262)
		(end 414.73501 -83.607402)
		(width 0.101346)
		(layer "In9.Cu")
		(net "KR_P1_OCP_RX_DN")
	)
	(segment
		(start 416.564064 -62.678564)
		(end 416.564064 -60.855606)
		(width 0.101346)
		(layer "In9.Cu")
		(net "KR_P1_OCP_RX_DN")
	)
	(segment
		(start 408.469084 -95.547434)
		(end 408.705558 -95.783908)
		(width 0.101346)
		(layer "In9.Cu")
		(net "KR_P1_OCP_RX_DN")
	)
	(segment
		(start 411.626558 -87.131906)
		(end 411.944058 -86.814406)
		(width 0.101346)
		(layer "In9.Cu")
		(net "KR_P1_OCP_RX_DN")
	)
	(segment
		(start 415.200846 -79.925164)
		(end 415.200846 -78.731364)
		(width 0.101346)
		(layer "In9.Cu")
		(net "KR_P1_OCP_RX_DN")
	)
	(segment
		(start 411.944058 -86.814406)
		(end 411.944058 -85.4456)
		(width 0.101346)
		(layer "In9.Cu")
		(net "KR_P1_OCP_RX_DN")
	)
	(segment
		(start 428.460408 -53.175662)
		(end 435.637686 -53.175662)
		(width 0.101346)
		(layer "In9.Cu")
		(net "KR_P1_OCP_RX_DN")
	)
	(segment
		(start 411.944058 -85.4456)
		(end 412.927038 -84.46262)
		(width 0.101346)
		(layer "In9.Cu")
		(net "KR_P1_OCP_RX_DN")
	)
	(segment
		(start 409.269438 -95.783908)
		(end 409.662884 -95.390462)
		(width 0.101346)
		(layer "In9.Cu")
		(net "KR_P1_OCP_RX_DN")
	)
	(segment
		(start 414.490916 -82.74177)
		(end 414.490916 -80.635094)
		(width 0.101346)
		(layer "In9.Cu")
		(net "KR_P1_OCP_RX_DN")
	)
	(segment
		(start 421.389556 -56.030114)
		(end 424.105578 -56.030114)
		(width 0.101346)
		(layer "In9.Cu")
		(net "KR_P1_OCP_RX_DN")
	)
	(segment
		(start 425.129706 -55.005986)
		(end 426.630084 -55.005986)
		(width 0.101346)
		(layer "In9.Cu")
		(net "KR_P1_OCP_RX_DN")
	)
	(segment
		(start 416.564064 -60.855606)
		(end 421.389556 -56.030114)
		(width 0.101346)
		(layer "In9.Cu")
		(net "KR_P1_OCP_RX_DN")
	)
	(segment
		(start 409.662884 -95.390462)
		(end 409.662884 -88.333834)
		(width 0.101346)
		(layer "In9.Cu")
		(net "KR_P1_OCP_RX_DN")
	)
	(segment
		(start 461.164178 -58.956448)
		(end 461.164178 -63.201042)
		(width 0.101346)
		(layer "In9.Cu")
		(net "KR_P1_OCP_RX_DN")
	)
	(segment
		(start 414.73501 -82.985864)
		(end 414.490916 -82.74177)
		(width 0.101346)
		(layer "In9.Cu")
		(net "KR_P1_OCP_RX_DN")
	)
	(segment
		(start 396.15745 -106.42092)
		(end 395.66215 -106.190796)
		(width 0.10033)
		(layer "F.Cu")
		(net "KR_P1_OCP_RX_C_DP")
	)
	(segment
		(start 406.115012 -96.607376)
		(end 406.418796 -96.303592)
		(width 0.10033)
		(layer "F.Cu")
		(net "KR_P1_OCP_RX_C_DP")
	)
	(segment
		(start 406.667716 -96.303592)
		(end 406.864566 -96.500442)
		(width 0.10033)
		(layer "F.Cu")
		(net "KR_P1_OCP_RX_C_DP")
	)
	(segment
		(start 406.418796 -96.303592)
		(end 406.667716 -96.303592)
		(width 0.10033)
		(layer "F.Cu")
		(net "KR_P1_OCP_RX_C_DP")
	)
	(via
		(at 406.115012 -96.607376)
		(size 0.508)
		(drill 0.254)
		(layers "F.Cu" "B.Cu")
		(net "KR_P1_OCP_RX_C_DP")
	)
	(via
		(at 395.66215 -106.190796)
		(size 0.508)
		(drill 0.254)
		(layers "F.Cu" "B.Cu")
		(net "KR_P1_OCP_RX_C_DP")
	)
	(segment
		(start 401.973796 -100.081842)
		(end 402.720302 -99.335336)
		(width 0.101346)
		(layer "In9.Cu")
		(net "KR_P1_OCP_RX_C_DP")
	)
	(segment
		(start 403.152102 -99.335336)
		(end 403.366986 -99.120452)
		(width 0.101346)
		(layer "In9.Cu")
		(net "KR_P1_OCP_RX_C_DP")
	)
	(segment
		(start 399.441416 -102.485952)
		(end 399.732246 -102.195122)
		(width 0.089154)
		(layer "In9.Cu")
		(net "KR_P1_OCP_RX_C_DP")
	)
	(segment
		(start 397.243554 -102.770432)
		(end 397.243554 -102.73919)
		(width 0.089154)
		(layer "In9.Cu")
		(net "KR_P1_OCP_RX_C_DP")
	)
	(segment
		(start 400.097752 -101.596952)
		(end 401.612862 -100.081842)
		(width 0.101346)
		(layer "In9.Cu")
		(net "KR_P1_OCP_RX_C_DP")
	)
	(segment
		(start 398.434052 -102.41026)
		(end 398.465802 -102.391718)
		(width 0.089154)
		(layer "In9.Cu")
		(net "KR_P1_OCP_RX_C_DP")
	)
	(segment
		(start 404.0886 -98.3742)
		(end 404.0886 -97.967038)
		(width 0.101346)
		(layer "In9.Cu")
		(net "KR_P1_OCP_RX_C_DP")
	)
	(segment
		(start 404.854156 -96.737932)
		(end 405.266906 -96.325182)
		(width 0.101346)
		(layer "In9.Cu")
		(net "KR_P1_OCP_RX_C_DP")
	)
	(segment
		(start 404.0886 -97.967038)
		(end 404.854156 -97.201482)
		(width 0.101346)
		(layer "In9.Cu")
		(net "KR_P1_OCP_RX_C_DP")
	)
	(segment
		(start 402.720302 -99.335336)
		(end 403.152102 -99.335336)
		(width 0.101346)
		(layer "In9.Cu")
		(net "KR_P1_OCP_RX_C_DP")
	)
	(segment
		(start 403.554438 -98.5012)
		(end 403.9616 -98.5012)
		(width 0.101346)
		(layer "In9.Cu")
		(net "KR_P1_OCP_RX_C_DP")
	)
	(segment
		(start 399.920714 -101.6127)
		(end 400.082004 -101.6127)
		(width 0.089154)
		(layer "In9.Cu")
		(net "KR_P1_OCP_RX_C_DP")
	)
	(segment
		(start 395.324076 -106.190796)
		(end 395.266164 -106.132884)
		(width 0.089154)
		(layer "In9.Cu")
		(net "KR_P1_OCP_RX_C_DP")
	)
	(segment
		(start 399.732246 -102.195122)
		(end 399.732246 -101.801168)
		(width 0.089154)
		(layer "In9.Cu")
		(net "KR_P1_OCP_RX_C_DP")
	)
	(segment
		(start 395.66215 -106.190796)
		(end 395.324076 -106.190796)
		(width 0.089154)
		(layer "In9.Cu")
		(net "KR_P1_OCP_RX_C_DP")
	)
	(segment
		(start 399.732246 -101.801168)
		(end 399.920714 -101.6127)
		(width 0.089154)
		(layer "In9.Cu")
		(net "KR_P1_OCP_RX_C_DP")
	)
	(segment
		(start 403.9616 -98.5012)
		(end 404.0886 -98.3742)
		(width 0.101346)
		(layer "In9.Cu")
		(net "KR_P1_OCP_RX_C_DP")
	)
	(segment
		(start 405.266906 -96.325182)
		(end 405.832818 -96.325182)
		(width 0.101346)
		(layer "In9.Cu")
		(net "KR_P1_OCP_RX_C_DP")
	)
	(segment
		(start 403.366986 -98.688652)
		(end 403.554438 -98.5012)
		(width 0.101346)
		(layer "In9.Cu")
		(net "KR_P1_OCP_RX_C_DP")
	)
	(segment
		(start 401.612862 -100.081842)
		(end 401.973796 -100.081842)
		(width 0.101346)
		(layer "In9.Cu")
		(net "KR_P1_OCP_RX_C_DP")
	)
	(segment
		(start 396.252954 -104.487472)
		(end 396.252954 -104.45623)
		(width 0.089154)
		(layer "In9.Cu")
		(net "KR_P1_OCP_RX_C_DP")
	)
	(segment
		(start 396.748254 -103.628952)
		(end 396.748254 -103.59771)
		(width 0.089154)
		(layer "In9.Cu")
		(net "KR_P1_OCP_RX_C_DP")
	)
	(segment
		(start 403.366986 -99.120452)
		(end 403.366986 -98.688652)
		(width 0.101346)
		(layer "In9.Cu")
		(net "KR_P1_OCP_RX_C_DP")
	)
	(segment
		(start 395.757654 -105.345992)
		(end 395.757654 -105.31475)
		(width 0.089154)
		(layer "In9.Cu")
		(net "KR_P1_OCP_RX_C_DP")
	)
	(segment
		(start 400.082004 -101.6127)
		(end 400.097752 -101.596952)
		(width 0.089154)
		(layer "In9.Cu")
		(net "KR_P1_OCP_RX_C_DP")
	)
	(segment
		(start 399.12671 -102.485952)
		(end 399.441416 -102.485952)
		(width 0.089154)
		(layer "In9.Cu")
		(net "KR_P1_OCP_RX_C_DP")
	)
	(segment
		(start 405.832818 -96.325182)
		(end 406.115012 -96.607376)
		(width 0.101346)
		(layer "In9.Cu")
		(net "KR_P1_OCP_RX_C_DP")
	)
	(segment
		(start 404.854156 -97.201482)
		(end 404.854156 -96.737932)
		(width 0.101346)
		(layer "In9.Cu")
		(net "KR_P1_OCP_RX_C_DP")
	)
	(arc
		(start 396.748254 -103.59771)
		(mid 396.805921 -103.40765)
		(end 396.947898 -103.26878)
		(width 0.089154)
		(layer "In9.Cu")
		(net "KR_P1_OCP_RX_C_DP")
	)
	(arc
		(start 396.947898 -103.26878)
		(mid 397.161028 -103.058337)
		(end 397.243554 -102.770432)
		(width 0.089154)
		(layer "In9.Cu")
		(net "KR_P1_OCP_RX_C_DP")
	)
	(arc
		(start 397.843502 -102.41026)
		(mid 398.138794 -102.489357)
		(end 398.434052 -102.41026)
		(width 0.089154)
		(layer "In9.Cu")
		(net "KR_P1_OCP_RX_C_DP")
	)
	(arc
		(start 396.252954 -104.45623)
		(mid 396.310621 -104.26617)
		(end 396.452598 -104.1273)
		(width 0.089154)
		(layer "In9.Cu")
		(net "KR_P1_OCP_RX_C_DP")
	)
	(arc
		(start 398.465802 -102.391718)
		(mid 398.651389 -102.355227)
		(end 398.833086 -102.40772)
		(width 0.089154)
		(layer "In9.Cu")
		(net "KR_P1_OCP_RX_C_DP")
	)
	(arc
		(start 395.266164 -106.132884)
		(mid 395.330967 -105.966126)
		(end 395.461998 -105.84434)
		(width 0.089154)
		(layer "In9.Cu")
		(net "KR_P1_OCP_RX_C_DP")
	)
	(arc
		(start 395.957298 -104.98582)
		(mid 396.170428 -104.775377)
		(end 396.252954 -104.487472)
		(width 0.089154)
		(layer "In9.Cu")
		(net "KR_P1_OCP_RX_C_DP")
	)
	(arc
		(start 397.243554 -102.73919)
		(mid 397.450946 -102.405824)
		(end 397.843502 -102.41026)
		(width 0.089154)
		(layer "In9.Cu")
		(net "KR_P1_OCP_RX_C_DP")
	)
	(arc
		(start 396.452598 -104.1273)
		(mid 396.665728 -103.916857)
		(end 396.748254 -103.628952)
		(width 0.089154)
		(layer "In9.Cu")
		(net "KR_P1_OCP_RX_C_DP")
	)
	(arc
		(start 395.757654 -105.31475)
		(mid 395.815321 -105.12469)
		(end 395.957298 -104.98582)
		(width 0.089154)
		(layer "In9.Cu")
		(net "KR_P1_OCP_RX_C_DP")
	)
	(arc
		(start 395.461998 -105.84434)
		(mid 395.675128 -105.633897)
		(end 395.757654 -105.345992)
		(width 0.089154)
		(layer "In9.Cu")
		(net "KR_P1_OCP_RX_C_DP")
	)
	(arc
		(start 398.833086 -102.40772)
		(mid 398.974799 -102.465978)
		(end 399.12671 -102.485952)
		(width 0.089154)
		(layer "In9.Cu")
		(net "KR_P1_OCP_RX_C_DP")
	)
	(segment
		(start 406.115012 -95.591884)
		(end 406.408382 -95.885254)
		(width 0.10033)
		(layer "F.Cu")
		(net "KR_P1_OCP_RX_C_DN")
	)
	(segment
		(start 406.408382 -95.885254)
		(end 406.666954 -95.885254)
		(width 0.10033)
		(layer "F.Cu")
		(net "KR_P1_OCP_RX_C_DN")
	)
	(segment
		(start 406.666954 -95.885254)
		(end 406.864566 -95.687642)
		(width 0.10033)
		(layer "F.Cu")
		(net "KR_P1_OCP_RX_C_DN")
	)
	(segment
		(start 395.16685 -106.42092)
		(end 394.67155 -106.190796)
		(width 0.10033)
		(layer "F.Cu")
		(net "KR_P1_OCP_RX_C_DN")
	)
	(via
		(at 406.115012 -95.591884)
		(size 0.508)
		(drill 0.254)
		(layers "F.Cu" "B.Cu")
		(net "KR_P1_OCP_RX_C_DN")
	)
	(via
		(at 394.67155 -106.190796)
		(size 0.508)
		(drill 0.254)
		(layers "F.Cu" "B.Cu")
		(net "KR_P1_OCP_RX_C_DN")
	)
	(segment
		(start 404.434802 -97.027746)
		(end 404.434802 -96.564196)
		(width 0.101346)
		(layer "In9.Cu")
		(net "KR_P1_OCP_RX_C_DN")
	)
	(segment
		(start 399.785332 -101.316028)
		(end 399.80108 -101.30028)
		(width 0.089154)
		(layer "In9.Cu")
		(net "KR_P1_OCP_RX_C_DN")
	)
	(segment
		(start 399.541492 -102.115874)
		(end 399.541492 -101.72192)
		(width 0.089154)
		(layer "In9.Cu")
		(net "KR_P1_OCP_RX_C_DN")
	)
	(segment
		(start 399.80108 -101.300534)
		(end 401.439126 -99.662488)
		(width 0.101346)
		(layer "In9.Cu")
		(net "KR_P1_OCP_RX_C_DN")
	)
	(segment
		(start 404.434802 -96.564196)
		(end 405.09317 -95.905828)
		(width 0.101346)
		(layer "In9.Cu")
		(net "KR_P1_OCP_RX_C_DN")
	)
	(segment
		(start 399.362168 -102.295198)
		(end 399.541492 -102.115874)
		(width 0.089154)
		(layer "In9.Cu")
		(net "KR_P1_OCP_RX_C_DN")
	)
	(segment
		(start 397.0528 -102.767892)
		(end 397.0528 -102.735126)
		(width 0.089154)
		(layer "In9.Cu")
		(net "KR_P1_OCP_RX_C_DN")
	)
	(segment
		(start 401.80006 -99.662488)
		(end 403.35962 -98.102674)
		(width 0.101346)
		(layer "In9.Cu")
		(net "KR_P1_OCP_RX_C_DN")
	)
	(segment
		(start 395.5669 -105.343452)
		(end 395.5669 -105.310686)
		(width 0.089154)
		(layer "In9.Cu")
		(net "KR_P1_OCP_RX_C_DN")
	)
	(segment
		(start 399.80108 -101.30028)
		(end 399.80108 -101.300534)
		(width 0.089154)
		(layer "In9.Cu")
		(net "KR_P1_OCP_RX_C_DN")
	)
	(segment
		(start 399.541492 -101.72192)
		(end 399.785332 -101.47808)
		(width 0.089154)
		(layer "In9.Cu")
		(net "KR_P1_OCP_RX_C_DN")
	)
	(segment
		(start 398.338548 -102.244906)
		(end 398.377156 -102.222554)
		(width 0.089154)
		(layer "In9.Cu")
		(net "KR_P1_OCP_RX_C_DN")
	)
	(segment
		(start 396.5575 -103.626412)
		(end 396.5575 -103.593646)
		(width 0.089154)
		(layer "In9.Cu")
		(net "KR_P1_OCP_RX_C_DN")
	)
	(segment
		(start 399.126964 -102.295198)
		(end 399.362168 -102.295198)
		(width 0.089154)
		(layer "In9.Cu")
		(net "KR_P1_OCP_RX_C_DN")
	)
	(segment
		(start 394.67155 -106.190796)
		(end 395.009624 -106.190796)
		(width 0.089154)
		(layer "In9.Cu")
		(net "KR_P1_OCP_RX_C_DN")
	)
	(segment
		(start 405.09317 -95.905828)
		(end 405.801068 -95.905828)
		(width 0.101346)
		(layer "In9.Cu")
		(net "KR_P1_OCP_RX_C_DN")
	)
	(segment
		(start 405.801068 -95.905828)
		(end 406.115012 -95.591884)
		(width 0.101346)
		(layer "In9.Cu")
		(net "KR_P1_OCP_RX_C_DN")
	)
	(segment
		(start 401.439126 -99.662488)
		(end 401.80006 -99.662488)
		(width 0.101346)
		(layer "In9.Cu")
		(net "KR_P1_OCP_RX_C_DN")
	)
	(segment
		(start 403.35962 -98.102674)
		(end 404.434802 -97.027746)
		(width 0.101346)
		(layer "In9.Cu")
		(net "KR_P1_OCP_RX_C_DN")
	)
	(segment
		(start 396.0622 -104.484932)
		(end 396.0622 -104.452166)
		(width 0.089154)
		(layer "In9.Cu")
		(net "KR_P1_OCP_RX_C_DN")
	)
	(segment
		(start 399.785332 -101.47808)
		(end 399.785332 -101.316028)
		(width 0.089154)
		(layer "In9.Cu")
		(net "KR_P1_OCP_RX_C_DN")
	)
	(segment
		(start 395.009624 -106.190796)
		(end 395.074648 -106.125772)
		(width 0.089154)
		(layer "In9.Cu")
		(net "KR_P1_OCP_RX_C_DN")
	)
	(arc
		(start 398.927828 -102.242112)
		(mid 399.023938 -102.281622)
		(end 399.126964 -102.295198)
		(width 0.089154)
		(layer "In9.Cu")
		(net "KR_P1_OCP_RX_C_DN")
	)
	(arc
		(start 395.862048 -104.820466)
		(mid 396.005852 -104.678783)
		(end 396.0622 -104.484932)
		(width 0.089154)
		(layer "In9.Cu")
		(net "KR_P1_OCP_RX_C_DN")
	)
	(arc
		(start 396.0622 -104.452166)
		(mid 396.146481 -104.168949)
		(end 396.357348 -103.961946)
		(width 0.089154)
		(layer "In9.Cu")
		(net "KR_P1_OCP_RX_C_DN")
	)
	(arc
		(start 395.366748 -105.678986)
		(mid 395.510552 -105.537303)
		(end 395.5669 -105.343452)
		(width 0.089154)
		(layer "In9.Cu")
		(net "KR_P1_OCP_RX_C_DN")
	)
	(arc
		(start 396.852648 -103.103426)
		(mid 396.996452 -102.961743)
		(end 397.0528 -102.767892)
		(width 0.089154)
		(layer "In9.Cu")
		(net "KR_P1_OCP_RX_C_DN")
	)
	(arc
		(start 396.5575 -103.593646)
		(mid 396.641781 -103.310429)
		(end 396.852648 -103.103426)
		(width 0.089154)
		(layer "In9.Cu")
		(net "KR_P1_OCP_RX_C_DN")
	)
	(arc
		(start 397.938752 -102.244906)
		(mid 398.13865 -102.298405)
		(end 398.338548 -102.244906)
		(width 0.089154)
		(layer "In9.Cu")
		(net "KR_P1_OCP_RX_C_DN")
	)
	(arc
		(start 398.377156 -102.222554)
		(mid 398.654914 -102.164405)
		(end 398.927828 -102.242112)
		(width 0.089154)
		(layer "In9.Cu")
		(net "KR_P1_OCP_RX_C_DN")
	)
	(arc
		(start 395.074648 -106.125772)
		(mid 395.167356 -105.867502)
		(end 395.366748 -105.678986)
		(width 0.089154)
		(layer "In9.Cu")
		(net "KR_P1_OCP_RX_C_DN")
	)
	(arc
		(start 396.357348 -103.961946)
		(mid 396.501152 -103.820263)
		(end 396.5575 -103.626412)
		(width 0.089154)
		(layer "In9.Cu")
		(net "KR_P1_OCP_RX_C_DN")
	)
	(arc
		(start 397.0528 -102.735126)
		(mid 397.357243 -102.239649)
		(end 397.938752 -102.244906)
		(width 0.089154)
		(layer "In9.Cu")
		(net "KR_P1_OCP_RX_C_DN")
	)
	(arc
		(start 395.5669 -105.310686)
		(mid 395.651181 -105.027469)
		(end 395.862048 -104.820466)
		(width 0.089154)
		(layer "In9.Cu")
		(net "KR_P1_OCP_RX_C_DN")
	)
	(segment
		(start 172.280072 -73.189338)
		(end 171.511214 -73.189338)
		(width 0.10795)
		(layer "F.Cu")
		(net "P3V3_DB1200_R1")
	)
	(segment
		(start 174.058072 -73.189338)
		(end 174.986696 -73.189338)
		(width 0.10795)
		(layer "F.Cu")
		(net "P3V3_DB1200_R1")
	)
	(segment
		(start 171.511214 -73.189338)
		(end 171.315126 -72.99325)
		(width 0.10795)
		(layer "F.Cu")
		(net "P3V3_DB1200_R1")
	)
	(via
		(at 174.986696 -73.189338)
		(size 0.508)
		(drill 0.254)
		(layers "F.Cu" "B.Cu")
		(net "P3V3_DB1200_R1")
	)
	(via
		(at 171.315126 -72.99325)
		(size 0.508)
		(drill 0.254)
		(layers "F.Cu" "B.Cu")
		(net "P3V3_DB1200_R1")
	)
	(segment
		(start 174.999396 -73.189338)
		(end 175.332136 -73.522078)
		(width 0.10795)
		(layer "B.Cu")
		(net "P3V3_DB1200_R1")
	)
	(segment
		(start 175.332136 -73.522078)
		(end 175.332136 -74.018648)
		(width 0.10795)
		(layer "B.Cu")
		(net "P3V3_DB1200_R1")
	)
	(segment
		(start 174.986696 -73.189338)
		(end 174.999396 -73.189338)
		(width 0.10795)
		(layer "B.Cu")
		(net "P3V3_DB1200_R1")
	)
	(segment
		(start 171.315126 -72.99325)
		(end 171.511214 -73.189338)
		(width 0.089408)
		(layer "In9.Cu")
		(net "P3V3_DB1200_R1")
	)
	(segment
		(start 171.511214 -73.189338)
		(end 174.986696 -73.189338)
		(width 0.089408)
		(layer "In9.Cu")
		(net "P3V3_DB1200_R1")
	)
	(segment
		(start 168.208452 -75.13447)
		(end 168.208452 -75.221084)
		(width 0.10795)
		(layer "F.Cu")
		(net "FM_DB1200_PWRGD_R")
	)
	(segment
		(start 168.020238 -76.04252)
		(end 168.020238 -75.630786)
		(width 0.10795)
		(layer "F.Cu")
		(net "FM_DB1200_PWRGD_R")
	)
	(segment
		(start 168.172638 -76.19492)
		(end 168.020238 -76.04252)
		(width 0.10795)
		(layer "F.Cu")
		(net "FM_DB1200_PWRGD_R")
	)
	(segment
		(start 168.07942 -74.551032)
		(end 168.07942 -75.005438)
		(width 0.10795)
		(layer "F.Cu")
		(net "FM_DB1200_PWRGD_R")
	)
	(segment
		(start 168.020238 -75.630786)
		(end 168.208452 -75.442572)
		(width 0.10795)
		(layer "F.Cu")
		(net "FM_DB1200_PWRGD_R")
	)
	(segment
		(start 168.208452 -75.442572)
		(end 168.208452 -75.221084)
		(width 0.10795)
		(layer "F.Cu")
		(net "FM_DB1200_PWRGD_R")
	)
	(segment
		(start 168.07942 -75.005438)
		(end 168.208452 -75.13447)
		(width 0.10795)
		(layer "F.Cu")
		(net "FM_DB1200_PWRGD_R")
	)
	(segment
		(start 168.172638 -76.593192)
		(end 168.172638 -76.19492)
		(width 0.10795)
		(layer "F.Cu")
		(net "FM_DB1200_PWRGD_R")
	)
	(via
		(at 171.00296 -69.64426)
		(size 0.6604)
		(drill 0.3302)
		(layers "F.Cu" "B.Cu")
		(net "FM_DB1200_PWRGD_R")
	)
	(via
		(at 168.208452 -75.221084)
		(size 0.508)
		(drill 0.254)
		(layers "F.Cu" "B.Cu")
		(net "FM_DB1200_PWRGD_R")
	)
	(via
		(at 167.868854 -71.083424)
		(size 0.508)
		(drill 0.254)
		(layers "F.Cu" "B.Cu")
		(net "FM_DB1200_PWRGD_R")
	)
	(segment
		(start 168.737534 -71.083424)
		(end 167.868854 -71.083424)
		(width 0.10795)
		(layer "B.Cu")
		(net "FM_DB1200_PWRGD_R")
	)
	(segment
		(start 171.00296 -69.64426)
		(end 170.624246 -69.64426)
		(width 0.10795)
		(layer "B.Cu")
		(net "FM_DB1200_PWRGD_R")
	)
	(segment
		(start 168.088818 -74.542396)
		(end 168.088818 -75.10145)
		(width 0.10795)
		(layer "B.Cu")
		(net "FM_DB1200_PWRGD_R")
	)
	(segment
		(start 170.624246 -69.64426)
		(end 170.366944 -69.386958)
		(width 0.10795)
		(layer "B.Cu")
		(net "FM_DB1200_PWRGD_R")
	)
	(segment
		(start 170.366944 -69.386958)
		(end 169.425874 -69.386958)
		(width 0.10795)
		(layer "B.Cu")
		(net "FM_DB1200_PWRGD_R")
	)
	(segment
		(start 171.260262 -69.386958)
		(end 171.00296 -69.64426)
		(width 0.10795)
		(layer "B.Cu")
		(net "FM_DB1200_PWRGD_R")
	)
	(segment
		(start 169.084752 -69.72808)
		(end 169.084752 -70.736206)
		(width 0.10795)
		(layer "B.Cu")
		(net "FM_DB1200_PWRGD_R")
	)
	(segment
		(start 169.084752 -70.736206)
		(end 168.737534 -71.083424)
		(width 0.10795)
		(layer "B.Cu")
		(net "FM_DB1200_PWRGD_R")
	)
	(segment
		(start 175.438816 -69.602604)
		(end 173.055534 -69.602604)
		(width 0.10795)
		(layer "B.Cu")
		(net "FM_DB1200_PWRGD_R")
	)
	(segment
		(start 168.088818 -75.10145)
		(end 168.208452 -75.221084)
		(width 0.10795)
		(layer "B.Cu")
		(net "FM_DB1200_PWRGD_R")
	)
	(segment
		(start 169.425874 -69.386958)
		(end 169.084752 -69.72808)
		(width 0.10795)
		(layer "B.Cu")
		(net "FM_DB1200_PWRGD_R")
	)
	(segment
		(start 172.839888 -69.386958)
		(end 171.260262 -69.386958)
		(width 0.10795)
		(layer "B.Cu")
		(net "FM_DB1200_PWRGD_R")
	)
	(segment
		(start 173.055534 -69.602604)
		(end 172.839888 -69.386958)
		(width 0.10795)
		(layer "B.Cu")
		(net "FM_DB1200_PWRGD_R")
	)
	(segment
		(start 168.208452 -74.017124)
		(end 166.858696 -72.667368)
		(width 0.089408)
		(layer "In11.Cu")
		(net "FM_DB1200_PWRGD_R")
	)
	(segment
		(start 168.208452 -75.221084)
		(end 168.208452 -74.017124)
		(width 0.089408)
		(layer "In11.Cu")
		(net "FM_DB1200_PWRGD_R")
	)
	(segment
		(start 166.858696 -72.667368)
		(end 166.858696 -72.093582)
		(width 0.089408)
		(layer "In11.Cu")
		(net "FM_DB1200_PWRGD_R")
	)
	(segment
		(start 166.858696 -72.093582)
		(end 167.868854 -71.083424)
		(width 0.089408)
		(layer "In11.Cu")
		(net "FM_DB1200_PWRGD_R")
	)
	(segment
		(start 398.234154 -152.397206)
		(end 398.2339 -152.396952)
		(width 0.10795)
		(layer "F.Cu")
		(net "PU_PVNN_PCH_PINALRT_N")
	)
	(segment
		(start 398.776698 -152.397206)
		(end 398.234154 -152.397206)
		(width 0.10795)
		(layer "F.Cu")
		(net "PU_PVNN_PCH_PINALRT_N")
	)
	(segment
		(start 399.929604 -152.343104)
		(end 398.8308 -152.343104)
		(width 0.10795)
		(layer "F.Cu")
		(net "PU_PVNN_PCH_PINALRT_N")
	)
	(segment
		(start 398.8308 -152.343104)
		(end 398.776698 -152.397206)
		(width 0.10795)
		(layer "F.Cu")
		(net "PU_PVNN_PCH_PINALRT_N")
	)
	(segment
		(start 400.25066 -152.66416)
		(end 399.929604 -152.343104)
		(width 0.10795)
		(layer "F.Cu")
		(net "PU_PVNN_PCH_PINALRT_N")
	)
	(segment
		(start 423.090086 -39.334694)
		(end 423.506392 -39.751)
		(width 0.3556)
		(layer "F.Cu")
		(net "PVCCIO_CPU0_R")
	)
	(via
		(at 434.5051 -44.8691)
		(size 0.6604)
		(drill 0.3302)
		(layers "F.Cu" "B.Cu")
		(net "PVCCIO_CPU0_R")
	)
	(via
		(at 423.506392 -39.751)
		(size 0.4572)
		(drill 0.2032)
		(layers "F.Cu" "B.Cu")
		(net "PVCCIO_CPU0_R")
	)
	(via
		(at 435.253384 -44.65193)
		(size 0.508)
		(drill 0.254)
		(layers "F.Cu" "B.Cu")
		(net "PVCCIO_CPU0_R")
	)
	(via
		(at 425.200826 -44.70146)
		(size 0.508)
		(drill 0.254)
		(layers "F.Cu" "B.Cu")
		(net "PVCCIO_CPU0_R")
	)
	(segment
		(start 434.72989 -43.70578)
		(end 434.72989 -44.128436)
		(width 0.381)
		(layer "B.Cu")
		(net "PVCCIO_CPU0_R")
	)
	(segment
		(start 434.72989 -44.128436)
		(end 435.253384 -44.65193)
		(width 0.381)
		(layer "B.Cu")
		(net "PVCCIO_CPU0_R")
	)
	(segment
		(start 435.253384 -44.65193)
		(end 435.036214 -44.8691)
		(width 0.254)
		(layer "B.Cu")
		(net "PVCCIO_CPU0_R")
	)
	(segment
		(start 435.036214 -44.8691)
		(end 434.5051 -44.8691)
		(width 0.254)
		(layer "B.Cu")
		(net "PVCCIO_CPU0_R")
	)
	(segment
		(start 434.493924 -45.040042)
		(end 433.730146 -45.040042)
		(width 0.254)
		(layer "In2.Cu")
		(net "PVCCIO_CPU0_R")
	)
	(segment
		(start 425.454826 -44.70146)
		(end 425.200826 -44.70146)
		(width 0.254)
		(layer "In2.Cu")
		(net "PVCCIO_CPU0_R")
	)
	(segment
		(start 425.932346 -45.17898)
		(end 425.454826 -44.70146)
		(width 0.254)
		(layer "In2.Cu")
		(net "PVCCIO_CPU0_R")
	)
	(segment
		(start 433.730146 -45.040042)
		(end 433.605178 -45.16501)
		(width 0.254)
		(layer "In2.Cu")
		(net "PVCCIO_CPU0_R")
	)
	(segment
		(start 435.253384 -44.65193)
		(end 434.882036 -44.65193)
		(width 0.254)
		(layer "In2.Cu")
		(net "PVCCIO_CPU0_R")
	)
	(segment
		(start 432.99126 -45.16501)
		(end 432.97729 -45.17898)
		(width 0.254)
		(layer "In2.Cu")
		(net "PVCCIO_CPU0_R")
	)
	(segment
		(start 434.882036 -44.65193)
		(end 434.493924 -45.040042)
		(width 0.254)
		(layer "In2.Cu")
		(net "PVCCIO_CPU0_R")
	)
	(segment
		(start 433.605178 -45.16501)
		(end 432.99126 -45.16501)
		(width 0.254)
		(layer "In2.Cu")
		(net "PVCCIO_CPU0_R")
	)
	(segment
		(start 432.97729 -45.17898)
		(end 425.932346 -45.17898)
		(width 0.254)
		(layer "In2.Cu")
		(net "PVCCIO_CPU0_R")
	)
	(segment
		(start 425.200826 -44.70146)
		(end 424.810682 -44.70146)
		(width 0.254)
		(layer "In9.Cu")
		(net "PVCCIO_CPU0_R")
	)
	(segment
		(start 424.398694 -44.289472)
		(end 424.398694 -42.328846)
		(width 0.254)
		(layer "In9.Cu")
		(net "PVCCIO_CPU0_R")
	)
	(segment
		(start 424.810682 -44.70146)
		(end 424.398694 -44.289472)
		(width 0.254)
		(layer "In9.Cu")
		(net "PVCCIO_CPU0_R")
	)
	(segment
		(start 424.398694 -42.328846)
		(end 423.506392 -41.436544)
		(width 0.254)
		(layer "In9.Cu")
		(net "PVCCIO_CPU0_R")
	)
	(segment
		(start 423.506392 -41.436544)
		(end 423.506392 -39.751)
		(width 0.254)
		(layer "In9.Cu")
		(net "PVCCIO_CPU0_R")
	)
	(segment
		(start 419.890194 -44.647358)
		(end 420.042086 -44.79925)
		(width 0.089408)
		(layer "F.Cu")
		(net "PECI_SEL")
	)
	(segment
		(start 420.042086 -45.786294)
		(end 420.423086 -46.167294)
		(width 0.089408)
		(layer "F.Cu")
		(net "PECI_SEL")
	)
	(segment
		(start 420.042086 -44.79925)
		(end 420.042086 -45.786294)
		(width 0.089408)
		(layer "F.Cu")
		(net "PECI_SEL")
	)
	(segment
		(start 419.890194 -43.334686)
		(end 419.890194 -44.647358)
		(width 0.089408)
		(layer "F.Cu")
		(net "PECI_SEL")
	)
	(via
		(at 420.423086 -46.167294)
		(size 0.508)
		(drill 0.254)
		(layers "F.Cu" "B.Cu")
		(net "PECI_SEL")
	)
	(via
		(at 405.638 -67.5386)
		(size 0.6604)
		(drill 0.3302)
		(layers "F.Cu" "B.Cu")
		(net "PECI_SEL")
	)
	(via
		(at 407.472388 -68.099178)
		(size 0.508)
		(drill 0.254)
		(layers "F.Cu" "B.Cu")
		(net "PECI_SEL")
	)
	(segment
		(start 393.451588 -74.468482)
		(end 393.451842 -74.468228)
		(width 0.10795)
		(layer "B.Cu")
		(net "PECI_SEL")
	)
	(segment
		(start 380.1872 -83.07324)
		(end 380.529846 -83.07324)
		(width 0.10795)
		(layer "B.Cu")
		(net "PECI_SEL")
	)
	(segment
		(start 393.215368 -74.468482)
		(end 393.451588 -74.468482)
		(width 0.10795)
		(layer "B.Cu")
		(net "PECI_SEL")
	)
	(segment
		(start 393.215114 -74.468228)
		(end 393.215368 -74.468482)
		(width 0.10795)
		(layer "B.Cu")
		(net "PECI_SEL")
	)
	(segment
		(start 397.366744 -71.050404)
		(end 397.83258 -70.584568)
		(width 0.10795)
		(layer "B.Cu")
		(net "PECI_SEL")
	)
	(segment
		(start 380.1872 -83.07324)
		(end 380.15672 -83.07324)
		(width 0.10795)
		(layer "B.Cu")
		(net "PECI_SEL")
	)
	(segment
		(start 380.790958 -81.071974)
		(end 381.038354 -80.824578)
		(width 0.10795)
		(layer "B.Cu")
		(net "PECI_SEL")
	)
	(segment
		(start 404.26894 -68.90766)
		(end 405.638 -67.5386)
		(width 0.10795)
		(layer "B.Cu")
		(net "PECI_SEL")
	)
	(segment
		(start 389.06323 -75.269598)
		(end 389.06323 -75.203558)
		(width 0.10795)
		(layer "B.Cu")
		(net "PECI_SEL")
	)
	(segment
		(start 383.90576 -79.96174)
		(end 384.55346 -79.31404)
		(width 0.10795)
		(layer "B.Cu")
		(net "PECI_SEL")
	)
	(segment
		(start 380.529846 -83.07324)
		(end 380.99746 -82.605626)
		(width 0.10795)
		(layer "B.Cu")
		(net "PECI_SEL")
	)
	(segment
		(start 391.5664 -74.468228)
		(end 391.933938 -74.468228)
		(width 0.10795)
		(layer "B.Cu")
		(net "PECI_SEL")
	)
	(segment
		(start 385.1402 -77.80528)
		(end 386.527294 -77.80528)
		(width 0.10795)
		(layer "B.Cu")
		(net "PECI_SEL")
	)
	(segment
		(start 381.038354 -80.824578)
		(end 381.099822 -80.824578)
		(width 0.10795)
		(layer "B.Cu")
		(net "PECI_SEL")
	)
	(segment
		(start 388.757414 -75.575414)
		(end 389.06323 -75.269598)
		(width 0.10795)
		(layer "B.Cu")
		(net "PECI_SEL")
	)
	(segment
		(start 405.946356 -67.5386)
		(end 405.638 -67.5386)
		(width 0.10795)
		(layer "B.Cu")
		(net "PECI_SEL")
	)
	(segment
		(start 384.55346 -78.39202)
		(end 385.1402 -77.80528)
		(width 0.10795)
		(layer "B.Cu")
		(net "PECI_SEL")
	)
	(segment
		(start 381.099822 -80.824578)
		(end 381.96266 -79.96174)
		(width 0.10795)
		(layer "B.Cu")
		(net "PECI_SEL")
	)
	(segment
		(start 380.15672 -83.07324)
		(end 378.87656 -84.3534)
		(width 0.10795)
		(layer "B.Cu")
		(net "PECI_SEL")
	)
	(segment
		(start 390.479788 -73.787)
		(end 390.885172 -73.787)
		(width 0.10795)
		(layer "B.Cu")
		(net "PECI_SEL")
	)
	(segment
		(start 380.790958 -81.421986)
		(end 380.790958 -81.071974)
		(width 0.10795)
		(layer "B.Cu")
		(net "PECI_SEL")
	)
	(segment
		(start 393.475972 -74.468228)
		(end 396.893796 -71.050404)
		(width 0.10795)
		(layer "B.Cu")
		(net "PECI_SEL")
	)
	(segment
		(start 407.472388 -68.099178)
		(end 406.506934 -68.099178)
		(width 0.10795)
		(layer "B.Cu")
		(net "PECI_SEL")
	)
	(segment
		(start 378.87656 -84.3534)
		(end 378.46 -84.3534)
		(width 0.10795)
		(layer "B.Cu")
		(net "PECI_SEL")
	)
	(segment
		(start 406.506934 -68.099178)
		(end 405.946356 -67.5386)
		(width 0.10795)
		(layer "B.Cu")
		(net "PECI_SEL")
	)
	(segment
		(start 398.65046 -70.584568)
		(end 400.327368 -68.90766)
		(width 0.10795)
		(layer "B.Cu")
		(net "PECI_SEL")
	)
	(segment
		(start 380.99746 -82.605626)
		(end 380.99746 -81.628488)
		(width 0.10795)
		(layer "B.Cu")
		(net "PECI_SEL")
	)
	(segment
		(start 391.934192 -74.468482)
		(end 392.804142 -74.468482)
		(width 0.10795)
		(layer "B.Cu")
		(net "PECI_SEL")
	)
	(segment
		(start 384.55346 -79.31404)
		(end 384.55346 -78.39202)
		(width 0.10795)
		(layer "B.Cu")
		(net "PECI_SEL")
	)
	(segment
		(start 392.804396 -74.468228)
		(end 393.215114 -74.468228)
		(width 0.10795)
		(layer "B.Cu")
		(net "PECI_SEL")
	)
	(segment
		(start 400.327368 -68.90766)
		(end 404.26894 -68.90766)
		(width 0.10795)
		(layer "B.Cu")
		(net "PECI_SEL")
	)
	(segment
		(start 391.933938 -74.468228)
		(end 391.934192 -74.468482)
		(width 0.10795)
		(layer "B.Cu")
		(net "PECI_SEL")
	)
	(segment
		(start 392.804142 -74.468482)
		(end 392.804396 -74.468228)
		(width 0.10795)
		(layer "B.Cu")
		(net "PECI_SEL")
	)
	(segment
		(start 389.06323 -75.203558)
		(end 390.479788 -73.787)
		(width 0.10795)
		(layer "B.Cu")
		(net "PECI_SEL")
	)
	(segment
		(start 390.885172 -73.787)
		(end 391.5664 -74.468228)
		(width 0.10795)
		(layer "B.Cu")
		(net "PECI_SEL")
	)
	(segment
		(start 397.83258 -70.584568)
		(end 398.65046 -70.584568)
		(width 0.10795)
		(layer "B.Cu")
		(net "PECI_SEL")
	)
	(segment
		(start 380.99746 -81.628488)
		(end 380.790958 -81.421986)
		(width 0.10795)
		(layer "B.Cu")
		(net "PECI_SEL")
	)
	(segment
		(start 393.451842 -74.468228)
		(end 393.475972 -74.468228)
		(width 0.10795)
		(layer "B.Cu")
		(net "PECI_SEL")
	)
	(segment
		(start 381.96266 -79.96174)
		(end 383.90576 -79.96174)
		(width 0.10795)
		(layer "B.Cu")
		(net "PECI_SEL")
	)
	(segment
		(start 386.527294 -77.80528)
		(end 388.75716 -75.575414)
		(width 0.10795)
		(layer "B.Cu")
		(net "PECI_SEL")
	)
	(segment
		(start 396.893796 -71.050404)
		(end 397.366744 -71.050404)
		(width 0.10795)
		(layer "B.Cu")
		(net "PECI_SEL")
	)
	(segment
		(start 388.75716 -75.575414)
		(end 388.757414 -75.575414)
		(width 0.10795)
		(layer "B.Cu")
		(net "PECI_SEL")
	)
	(segment
		(start 418.85235 -47.785782)
		(end 418.078412 -48.55972)
		(width 0.089408)
		(layer "In9.Cu")
		(net "PECI_SEL")
	)
	(segment
		(start 419.683184 -46.727618)
		(end 419.309042 -46.727618)
		(width 0.089408)
		(layer "In9.Cu")
		(net "PECI_SEL")
	)
	(segment
		(start 419.11651 -46.92015)
		(end 419.086538 -46.92015)
		(width 0.089408)
		(layer "In9.Cu")
		(net "PECI_SEL")
	)
	(segment
		(start 413.462724 -48.763428)
		(end 412.573216 -49.652936)
		(width 0.089408)
		(layer "In9.Cu")
		(net "PECI_SEL")
	)
	(segment
		(start 409.099258 -61.410342)
		(end 409.099258 -65.920366)
		(width 0.089408)
		(layer "In9.Cu")
		(net "PECI_SEL")
	)
	(segment
		(start 419.309042 -46.727618)
		(end 419.11651 -46.92015)
		(width 0.089408)
		(layer "In9.Cu")
		(net "PECI_SEL")
	)
	(segment
		(start 419.086538 -46.92015)
		(end 418.85235 -47.154338)
		(width 0.089408)
		(layer "In9.Cu")
		(net "PECI_SEL")
	)
	(segment
		(start 407.472388 -67.547236)
		(end 407.472388 -68.099178)
		(width 0.089408)
		(layer "In9.Cu")
		(net "PECI_SEL")
	)
	(segment
		(start 408.98699 -53.791358)
		(end 408.98699 -55.611014)
		(width 0.089408)
		(layer "In9.Cu")
		(net "PECI_SEL")
	)
	(segment
		(start 418.85235 -47.154338)
		(end 418.85235 -47.785782)
		(width 0.089408)
		(layer "In9.Cu")
		(net "PECI_SEL")
	)
	(segment
		(start 416.035744 -48.763428)
		(end 413.462724 -48.763428)
		(width 0.089408)
		(layer "In9.Cu")
		(net "PECI_SEL")
	)
	(segment
		(start 408.917648 -61.228732)
		(end 409.099258 -61.410342)
		(width 0.089408)
		(layer "In9.Cu")
		(net "PECI_SEL")
	)
	(segment
		(start 408.98699 -55.611014)
		(end 408.917648 -55.680356)
		(width 0.089408)
		(layer "In9.Cu")
		(net "PECI_SEL")
	)
	(segment
		(start 412.573216 -49.652936)
		(end 412.573216 -50.205132)
		(width 0.089408)
		(layer "In9.Cu")
		(net "PECI_SEL")
	)
	(segment
		(start 416.239452 -48.55972)
		(end 416.035744 -48.763428)
		(width 0.089408)
		(layer "In9.Cu")
		(net "PECI_SEL")
	)
	(segment
		(start 408.917648 -55.680356)
		(end 408.917648 -61.228732)
		(width 0.089408)
		(layer "In9.Cu")
		(net "PECI_SEL")
	)
	(segment
		(start 418.078412 -48.55972)
		(end 416.239452 -48.55972)
		(width 0.089408)
		(layer "In9.Cu")
		(net "PECI_SEL")
	)
	(segment
		(start 420.423086 -46.167294)
		(end 420.243508 -46.167294)
		(width 0.089408)
		(layer "In9.Cu")
		(net "PECI_SEL")
	)
	(segment
		(start 412.573216 -50.205132)
		(end 408.98699 -53.791358)
		(width 0.089408)
		(layer "In9.Cu")
		(net "PECI_SEL")
	)
	(segment
		(start 420.243508 -46.167294)
		(end 419.683184 -46.727618)
		(width 0.089408)
		(layer "In9.Cu")
		(net "PECI_SEL")
	)
	(segment
		(start 409.099258 -65.920366)
		(end 407.472388 -67.547236)
		(width 0.089408)
		(layer "In9.Cu")
		(net "PECI_SEL")
	)
	(segment
		(start 397.558768 -113.479834)
		(end 397.64335 -113.519204)
		(width 0.10668)
		(layer "F.Cu")
		(net "SMB_SLOTX24_PCH_STBY_LVC3_SDA")
	)
	(segment
		(start 397.470376 -113.43894)
		(end 397.558768 -113.479834)
		(width 0.10668)
		(layer "F.Cu")
		(net "SMB_SLOTX24_PCH_STBY_LVC3_SDA")
	)
	(segment
		(start 397.14805 -113.28908)
		(end 397.470376 -113.43894)
		(width 0.10668)
		(layer "F.Cu")
		(net "SMB_SLOTX24_PCH_STBY_LVC3_SDA")
	)
	(via
		(at 397.64335 -113.519204)
		(size 0.508)
		(drill 0.254)
		(layers "F.Cu" "B.Cu")
		(net "SMB_SLOTX24_PCH_STBY_LVC3_SDA")
	)
	(via
		(at 389.22325 -101.898196)
		(size 0.508)
		(drill 0.254)
		(layers "F.Cu" "B.Cu")
		(net "SMB_SLOTX24_PCH_STBY_LVC3_SDA")
	)
	(via
		(at 463.909156 -9.013444)
		(size 0.508)
		(drill 0.254)
		(layers "F.Cu" "B.Cu")
		(net "SMB_SLOTX24_PCH_STBY_LVC3_SDA")
	)
	(segment
		(start 398.307814 -113.969546)
		(end 398.318228 -113.97996)
		(width 0.10795)
		(layer "B.Cu")
		(net "SMB_SLOTX24_PCH_STBY_LVC3_SDA")
	)
	(segment
		(start 399.764758 -114.113818)
		(end 399.764758 -114.716814)
		(width 0.10795)
		(layer "B.Cu")
		(net "SMB_SLOTX24_PCH_STBY_LVC3_SDA")
	)
	(segment
		(start 464.174078 -9.013444)
		(end 464.232244 -9.07161)
		(width 0.10795)
		(layer "B.Cu")
		(net "SMB_SLOTX24_PCH_STBY_LVC3_SDA")
	)
	(segment
		(start 467.07425 -9.50468)
		(end 467.1822 -9.39673)
		(width 0.10795)
		(layer "B.Cu")
		(net "SMB_SLOTX24_PCH_STBY_LVC3_SDA")
	)
	(segment
		(start 399.298414 -113.969546)
		(end 399.308828 -113.97996)
		(width 0.10795)
		(layer "B.Cu")
		(net "SMB_SLOTX24_PCH_STBY_LVC3_SDA")
	)
	(segment
		(start 467.1822 -9.39673)
		(end 467.1822 -8.69696)
		(width 0.10795)
		(layer "B.Cu")
		(net "SMB_SLOTX24_PCH_STBY_LVC3_SDA")
	)
	(segment
		(start 398.318228 -113.97996)
		(end 398.949672 -113.97996)
		(width 0.10795)
		(layer "B.Cu")
		(net "SMB_SLOTX24_PCH_STBY_LVC3_SDA")
	)
	(segment
		(start 467.1822 -8.69696)
		(end 467.32952 -8.54964)
		(width 0.10795)
		(layer "B.Cu")
		(net "SMB_SLOTX24_PCH_STBY_LVC3_SDA")
	)
	(segment
		(start 465.239862 -9.07161)
		(end 465.672932 -9.50468)
		(width 0.10795)
		(layer "B.Cu")
		(net "SMB_SLOTX24_PCH_STBY_LVC3_SDA")
	)
	(segment
		(start 398.949672 -113.97996)
		(end 398.960086 -113.969546)
		(width 0.10795)
		(layer "B.Cu")
		(net "SMB_SLOTX24_PCH_STBY_LVC3_SDA")
	)
	(segment
		(start 398.093692 -113.969546)
		(end 398.307814 -113.969546)
		(width 0.10795)
		(layer "B.Cu")
		(net "SMB_SLOTX24_PCH_STBY_LVC3_SDA")
	)
	(segment
		(start 397.64335 -113.519204)
		(end 398.093692 -113.969546)
		(width 0.10795)
		(layer "B.Cu")
		(net "SMB_SLOTX24_PCH_STBY_LVC3_SDA")
	)
	(segment
		(start 399.6309 -113.97996)
		(end 399.764758 -114.113818)
		(width 0.10795)
		(layer "B.Cu")
		(net "SMB_SLOTX24_PCH_STBY_LVC3_SDA")
	)
	(segment
		(start 399.308828 -113.97996)
		(end 399.6309 -113.97996)
		(width 0.10795)
		(layer "B.Cu")
		(net "SMB_SLOTX24_PCH_STBY_LVC3_SDA")
	)
	(segment
		(start 468.100664 -8.54964)
		(end 469.197944 -9.64692)
		(width 0.10795)
		(layer "B.Cu")
		(net "SMB_SLOTX24_PCH_STBY_LVC3_SDA")
	)
	(segment
		(start 398.960086 -113.969546)
		(end 399.298414 -113.969546)
		(width 0.10795)
		(layer "B.Cu")
		(net "SMB_SLOTX24_PCH_STBY_LVC3_SDA")
	)
	(segment
		(start 463.909156 -9.013444)
		(end 464.174078 -9.013444)
		(width 0.10795)
		(layer "B.Cu")
		(net "SMB_SLOTX24_PCH_STBY_LVC3_SDA")
	)
	(segment
		(start 467.32952 -8.54964)
		(end 468.100664 -8.54964)
		(width 0.10795)
		(layer "B.Cu")
		(net "SMB_SLOTX24_PCH_STBY_LVC3_SDA")
	)
	(segment
		(start 464.232244 -9.07161)
		(end 465.239862 -9.07161)
		(width 0.10795)
		(layer "B.Cu")
		(net "SMB_SLOTX24_PCH_STBY_LVC3_SDA")
	)
	(segment
		(start 465.672932 -9.50468)
		(end 467.07425 -9.50468)
		(width 0.10795)
		(layer "B.Cu")
		(net "SMB_SLOTX24_PCH_STBY_LVC3_SDA")
	)
	(segment
		(start 389.05434 -101.60508)
		(end 389.075676 -101.52634)
		(width 0.0889)
		(layer "In4.Cu")
		(net "SMB_SLOTX24_PCH_STBY_LVC3_SDA")
	)
	(segment
		(start 391.6045 -101.88702)
		(end 391.6045 -101.919786)
		(width 0.0889)
		(layer "In4.Cu")
		(net "SMB_SLOTX24_PCH_STBY_LVC3_SDA")
	)
	(segment
		(start 397.094964 -104.585262)
		(end 397.389096 -104.879394)
		(width 0.0889)
		(layer "In4.Cu")
		(net "SMB_SLOTX24_PCH_STBY_LVC3_SDA")
	)
	(segment
		(start 399.736564 -104.879394)
		(end 399.948654 -105.091484)
		(width 0.0889)
		(layer "In4.Cu")
		(net "SMB_SLOTX24_PCH_STBY_LVC3_SDA")
	)
	(segment
		(start 392.0998 -102.720902)
		(end 392.0998 -103.039672)
		(width 0.0889)
		(layer "In4.Cu")
		(net "SMB_SLOTX24_PCH_STBY_LVC3_SDA")
	)
	(segment
		(start 399.948654 -112.441736)
		(end 399.27403 -113.11636)
		(width 0.0889)
		(layer "In4.Cu")
		(net "SMB_SLOTX24_PCH_STBY_LVC3_SDA")
	)
	(segment
		(start 397.744442 -113.519204)
		(end 397.64335 -113.519204)
		(width 0.0889)
		(layer "In4.Cu")
		(net "SMB_SLOTX24_PCH_STBY_LVC3_SDA")
	)
	(segment
		(start 392.0998 -103.039672)
		(end 392.7602 -103.700072)
		(width 0.0889)
		(layer "In4.Cu")
		(net "SMB_SLOTX24_PCH_STBY_LVC3_SDA")
	)
	(segment
		(start 396.852648 -104.127046)
		(end 396.957042 -104.187244)
		(width 0.0889)
		(layer "In4.Cu")
		(net "SMB_SLOTX24_PCH_STBY_LVC3_SDA")
	)
	(segment
		(start 392.7602 -103.700072)
		(end 393.425934 -103.700072)
		(width 0.0889)
		(layer "In4.Cu")
		(net "SMB_SLOTX24_PCH_STBY_LVC3_SDA")
	)
	(segment
		(start 393.881102 -104.126792)
		(end 393.898882 -104.136952)
		(width 0.0889)
		(layer "In4.Cu")
		(net "SMB_SLOTX24_PCH_STBY_LVC3_SDA")
	)
	(segment
		(start 398.147286 -113.11636)
		(end 397.744442 -113.519204)
		(width 0.0889)
		(layer "In4.Cu")
		(net "SMB_SLOTX24_PCH_STBY_LVC3_SDA")
	)
	(segment
		(start 393.425934 -103.700072)
		(end 393.758674 -104.033066)
		(width 0.0889)
		(layer "In4.Cu")
		(net "SMB_SLOTX24_PCH_STBY_LVC3_SDA")
	)
	(segment
		(start 389.22325 -101.898196)
		(end 389.05434 -101.60508)
		(width 0.0889)
		(layer "In4.Cu")
		(net "SMB_SLOTX24_PCH_STBY_LVC3_SDA")
	)
	(segment
		(start 399.27403 -113.11636)
		(end 398.147286 -113.11636)
		(width 0.0889)
		(layer "In4.Cu")
		(net "SMB_SLOTX24_PCH_STBY_LVC3_SDA")
	)
	(segment
		(start 399.948654 -105.091484)
		(end 399.948654 -112.441736)
		(width 0.0889)
		(layer "In4.Cu")
		(net "SMB_SLOTX24_PCH_STBY_LVC3_SDA")
	)
	(segment
		(start 397.094964 -104.426004)
		(end 397.094964 -104.585262)
		(width 0.0889)
		(layer "In4.Cu")
		(net "SMB_SLOTX24_PCH_STBY_LVC3_SDA")
	)
	(segment
		(start 397.389096 -104.879394)
		(end 399.736564 -104.879394)
		(width 0.0889)
		(layer "In4.Cu")
		(net "SMB_SLOTX24_PCH_STBY_LVC3_SDA")
	)
	(arc
		(start 395.862048 -104.127046)
		(mid 396.15745 -104.206177)
		(end 396.452852 -104.127046)
		(width 0.0889)
		(layer "In4.Cu")
		(net "SMB_SLOTX24_PCH_STBY_LVC3_SDA")
	)
	(arc
		(start 393.898882 -104.136952)
		(mid 394.186537 -104.206011)
		(end 394.471652 -104.127046)
		(width 0.0889)
		(layer "In4.Cu")
		(net "SMB_SLOTX24_PCH_STBY_LVC3_SDA")
	)
	(arc
		(start 394.871448 -104.127046)
		(mid 395.16685 -104.206177)
		(end 395.462252 -104.127046)
		(width 0.0889)
		(layer "In4.Cu")
		(net "SMB_SLOTX24_PCH_STBY_LVC3_SDA")
	)
	(arc
		(start 391.6045 -101.919786)
		(mid 391.672529 -102.174451)
		(end 391.84453 -102.374192)
		(width 0.0889)
		(layer "In4.Cu")
		(net "SMB_SLOTX24_PCH_STBY_LVC3_SDA")
	)
	(arc
		(start 391.84453 -102.374192)
		(mid 391.892093 -102.405984)
		(end 391.94232 -102.433374)
		(width 0.0889)
		(layer "In4.Cu")
		(net "SMB_SLOTX24_PCH_STBY_LVC3_SDA")
	)
	(arc
		(start 396.452852 -104.127046)
		(mid 396.65275 -104.073547)
		(end 396.852648 -104.127046)
		(width 0.0889)
		(layer "In4.Cu")
		(net "SMB_SLOTX24_PCH_STBY_LVC3_SDA")
	)
	(arc
		(start 394.471652 -104.127046)
		(mid 394.67155 -104.073547)
		(end 394.871448 -104.127046)
		(width 0.0889)
		(layer "In4.Cu")
		(net "SMB_SLOTX24_PCH_STBY_LVC3_SDA")
	)
	(arc
		(start 396.957042 -104.187244)
		(mid 397.058017 -104.288133)
		(end 397.094964 -104.426004)
		(width 0.0889)
		(layer "In4.Cu")
		(net "SMB_SLOTX24_PCH_STBY_LVC3_SDA")
	)
	(arc
		(start 391.404348 -101.551486)
		(mid 391.548152 -101.693169)
		(end 391.6045 -101.88702)
		(width 0.0889)
		(layer "In4.Cu")
		(net "SMB_SLOTX24_PCH_STBY_LVC3_SDA")
	)
	(arc
		(start 390.013952 -101.551486)
		(mid 390.21385 -101.497987)
		(end 390.413748 -101.551486)
		(width 0.0889)
		(layer "In4.Cu")
		(net "SMB_SLOTX24_PCH_STBY_LVC3_SDA")
	)
	(arc
		(start 389.075676 -101.52634)
		(mid 389.252305 -101.499071)
		(end 389.423148 -101.551486)
		(width 0.0889)
		(layer "In4.Cu")
		(net "SMB_SLOTX24_PCH_STBY_LVC3_SDA")
	)
	(arc
		(start 393.789154 -104.061514)
		(mid 393.833567 -104.096352)
		(end 393.881102 -104.126792)
		(width 0.0889)
		(layer "In4.Cu")
		(net "SMB_SLOTX24_PCH_STBY_LVC3_SDA")
	)
	(arc
		(start 389.423148 -101.551486)
		(mid 389.71855 -101.630617)
		(end 390.013952 -101.551486)
		(width 0.0889)
		(layer "In4.Cu")
		(net "SMB_SLOTX24_PCH_STBY_LVC3_SDA")
	)
	(arc
		(start 391.004552 -101.551486)
		(mid 391.20445 -101.497987)
		(end 391.404348 -101.551486)
		(width 0.0889)
		(layer "In4.Cu")
		(net "SMB_SLOTX24_PCH_STBY_LVC3_SDA")
	)
	(arc
		(start 393.758674 -104.033066)
		(mid 393.773662 -104.04756)
		(end 393.789154 -104.061514)
		(width 0.0889)
		(layer "In4.Cu")
		(net "SMB_SLOTX24_PCH_STBY_LVC3_SDA")
	)
	(arc
		(start 390.413748 -101.551486)
		(mid 390.70915 -101.630617)
		(end 391.004552 -101.551486)
		(width 0.0889)
		(layer "In4.Cu")
		(net "SMB_SLOTX24_PCH_STBY_LVC3_SDA")
	)
	(arc
		(start 395.462252 -104.127046)
		(mid 395.66215 -104.073547)
		(end 395.862048 -104.127046)
		(width 0.0889)
		(layer "In4.Cu")
		(net "SMB_SLOTX24_PCH_STBY_LVC3_SDA")
	)
	(arc
		(start 391.94232 -102.433374)
		(mid 392.057885 -102.556976)
		(end 392.0998 -102.720902)
		(width 0.0889)
		(layer "In4.Cu")
		(net "SMB_SLOTX24_PCH_STBY_LVC3_SDA")
	)
	(segment
		(start 392.350752 -73.570084)
		(end 392.188954 -73.408286)
		(width 0.089408)
		(layer "In9.Cu")
		(net "SMB_SLOTX24_PCH_STBY_LVC3_SDA")
	)
	(segment
		(start 395.140688 -51.85029)
		(end 395.268704 -51.722274)
		(width 0.089408)
		(layer "In9.Cu")
		(net "SMB_SLOTX24_PCH_STBY_LVC3_SDA")
	)
	(segment
		(start 389.972804 -83.17611)
		(end 390.275572 -82.873342)
		(width 0.089408)
		(layer "In9.Cu")
		(net "SMB_SLOTX24_PCH_STBY_LVC3_SDA")
	)
	(segment
		(start 395.268704 -51.722274)
		(end 395.268704 -51.717956)
		(width 0.089408)
		(layer "In9.Cu")
		(net "SMB_SLOTX24_PCH_STBY_LVC3_SDA")
	)
	(segment
		(start 385.907026 -89.101422)
		(end 385.907026 -88.632284)
		(width 0.089408)
		(layer "In9.Cu")
		(net "SMB_SLOTX24_PCH_STBY_LVC3_SDA")
	)
	(segment
		(start 385.1656 -97.627186)
		(end 385.1656 -97.59442)
		(width 0.0889)
		(layer "In9.Cu")
		(net "SMB_SLOTX24_PCH_STBY_LVC3_SDA")
	)
	(segment
		(start 395.390878 -45.572172)
		(end 396.03934 -44.92371)
		(width 0.089408)
		(layer "In9.Cu")
		(net "SMB_SLOTX24_PCH_STBY_LVC3_SDA")
	)
	(segment
		(start 397.477488 -30.857698)
		(end 397.477488 -24.263096)
		(width 0.089408)
		(layer "In9.Cu")
		(net "SMB_SLOTX24_PCH_STBY_LVC3_SDA")
	)
	(segment
		(start 413.841438 -20.18792)
		(end 414.252664 -19.776694)
		(width 0.089408)
		(layer "In9.Cu")
		(net "SMB_SLOTX24_PCH_STBY_LVC3_SDA")
	)
	(segment
		(start 399.061432 -22.520656)
		(end 400.76755 -22.520656)
		(width 0.089408)
		(layer "In9.Cu")
		(net "SMB_SLOTX24_PCH_STBY_LVC3_SDA")
	)
	(segment
		(start 418.993066 -20.447508)
		(end 420.331646 -20.447508)
		(width 0.089408)
		(layer "In9.Cu")
		(net "SMB_SLOTX24_PCH_STBY_LVC3_SDA")
	)
	(segment
		(start 395.350492 -54.719728)
		(end 395.350492 -53.135276)
		(width 0.089408)
		(layer "In9.Cu")
		(net "SMB_SLOTX24_PCH_STBY_LVC3_SDA")
	)
	(segment
		(start 385.4831 -92.545154)
		(end 385.4831 -91.886278)
		(width 0.089408)
		(layer "In9.Cu")
		(net "SMB_SLOTX24_PCH_STBY_LVC3_SDA")
	)
	(segment
		(start 385.6609 -100.192332)
		(end 385.6609 -100.16998)
		(width 0.0889)
		(layer "In9.Cu")
		(net "SMB_SLOTX24_PCH_STBY_LVC3_SDA")
	)
	(segment
		(start 460.82458 -9.321292)
		(end 461.720184 -8.425688)
		(width 0.089408)
		(layer "In9.Cu")
		(net "SMB_SLOTX24_PCH_STBY_LVC3_SDA")
	)
	(segment
		(start 446.889124 -24.403304)
		(end 449.409566 -24.403304)
		(width 0.089408)
		(layer "In9.Cu")
		(net "SMB_SLOTX24_PCH_STBY_LVC3_SDA")
	)
	(segment
		(start 395.268958 -51.717702)
		(end 395.268958 -51.401218)
		(width 0.089408)
		(layer "In9.Cu")
		(net "SMB_SLOTX24_PCH_STBY_LVC3_SDA")
	)
	(segment
		(start 385.377182 -91.78036)
		(end 385.377182 -89.631266)
		(width 0.089408)
		(layer "In9.Cu")
		(net "SMB_SLOTX24_PCH_STBY_LVC3_SDA")
	)
	(segment
		(start 433.1716 -20.183602)
		(end 434.768752 -20.183602)
		(width 0.089408)
		(layer "In9.Cu")
		(net "SMB_SLOTX24_PCH_STBY_LVC3_SDA")
	)
	(segment
		(start 456.350116 -18.878042)
		(end 457.441808 -17.78635)
		(width 0.089408)
		(layer "In9.Cu")
		(net "SMB_SLOTX24_PCH_STBY_LVC3_SDA")
	)
	(segment
		(start 397.387826 -35.330638)
		(end 397.176752 -35.119564)
		(width 0.089408)
		(layer "In9.Cu")
		(net "SMB_SLOTX24_PCH_STBY_LVC3_SDA")
	)
	(segment
		(start 384.731768 -95.22333)
		(end 384.731768 -94.023434)
		(width 0.089408)
		(layer "In9.Cu")
		(net "SMB_SLOTX24_PCH_STBY_LVC3_SDA")
	)
	(segment
		(start 394.591794 -63.663068)
		(end 395.349984 -62.904878)
		(width 0.089408)
		(layer "In9.Cu")
		(net "SMB_SLOTX24_PCH_STBY_LVC3_SDA")
	)
	(segment
		(start 395.140434 -52.76723)
		(end 395.140688 -52.766976)
		(width 0.089408)
		(layer "In9.Cu")
		(net "SMB_SLOTX24_PCH_STBY_LVC3_SDA")
	)
	(segment
		(start 418.322252 -19.776694)
		(end 418.674296 -20.128738)
		(width 0.089408)
		(layer "In9.Cu")
		(net "SMB_SLOTX24_PCH_STBY_LVC3_SDA")
	)
	(segment
		(start 395.086586 -49.073054)
		(end 395.086586 -47.770034)
		(width 0.089408)
		(layer "In9.Cu")
		(net "SMB_SLOTX24_PCH_STBY_LVC3_SDA")
	)
	(segment
		(start 395.268704 -51.717956)
		(end 395.268958 -51.717702)
		(width 0.089408)
		(layer "In9.Cu")
		(net "SMB_SLOTX24_PCH_STBY_LVC3_SDA")
	)
	(segment
		(start 395.268704 -49.255172)
		(end 395.086586 -49.073054)
		(width 0.089408)
		(layer "In9.Cu")
		(net "SMB_SLOTX24_PCH_STBY_LVC3_SDA")
	)
	(segment
		(start 384.6703 -96.768666)
		(end 384.6703 -96.366076)
		(width 0.0889)
		(layer "In9.Cu")
		(net "SMB_SLOTX24_PCH_STBY_LVC3_SDA")
	)
	(segment
		(start 457.146152 -13.851128)
		(end 460.82458 -10.1727)
		(width 0.089408)
		(layer "In9.Cu")
		(net "SMB_SLOTX24_PCH_STBY_LVC3_SDA")
	)
	(segment
		(start 396.03934 -44.92371)
		(end 396.03934 -44.093638)
		(width 0.089408)
		(layer "In9.Cu")
		(net "SMB_SLOTX24_PCH_STBY_LVC3_SDA")
	)
	(segment
		(start 414.252664 -19.776694)
		(end 418.322252 -19.776694)
		(width 0.089408)
		(layer "In9.Cu")
		(net "SMB_SLOTX24_PCH_STBY_LVC3_SDA")
	)
	(segment
		(start 398.086834 -32.558228)
		(end 398.086834 -31.467044)
		(width 0.089408)
		(layer "In9.Cu")
		(net "SMB_SLOTX24_PCH_STBY_LVC3_SDA")
	)
	(segment
		(start 394.591794 -65.323466)
		(end 394.591794 -64.848486)
		(width 0.089408)
		(layer "In9.Cu")
		(net "SMB_SLOTX24_PCH_STBY_LVC3_SDA")
	)
	(segment
		(start 427.946058 -20.7518)
		(end 432.603402 -20.7518)
		(width 0.089408)
		(layer "In9.Cu")
		(net "SMB_SLOTX24_PCH_STBY_LVC3_SDA")
	)
	(segment
		(start 389.972804 -85.78469)
		(end 389.972804 -83.17611)
		(width 0.089408)
		(layer "In9.Cu")
		(net "SMB_SLOTX24_PCH_STBY_LVC3_SDA")
	)
	(segment
		(start 400.76755 -22.520656)
		(end 401.64258 -23.395686)
		(width 0.089408)
		(layer "In9.Cu")
		(net "SMB_SLOTX24_PCH_STBY_LVC3_SDA")
	)
	(segment
		(start 395.350492 -53.135276)
		(end 395.140434 -52.925218)
		(width 0.089408)
		(layer "In9.Cu")
		(net "SMB_SLOTX24_PCH_STBY_LVC3_SDA")
	)
	(segment
		(start 403.135592 -23.236682)
		(end 411.602936 -23.236682)
		(width 0.089408)
		(layer "In9.Cu")
		(net "SMB_SLOTX24_PCH_STBY_LVC3_SDA")
	)
	(segment
		(start 402.976588 -23.395686)
		(end 403.135592 -23.236682)
		(width 0.089408)
		(layer "In9.Cu")
		(net "SMB_SLOTX24_PCH_STBY_LVC3_SDA")
	)
	(segment
		(start 387.202172 -101.459284)
		(end 387.042152 -101.551486)
		(width 0.0889)
		(layer "In9.Cu")
		(net "SMB_SLOTX24_PCH_STBY_LVC3_SDA")
	)
	(segment
		(start 395.390878 -47.465742)
		(end 395.390878 -45.572172)
		(width 0.089408)
		(layer "In9.Cu")
		(net "SMB_SLOTX24_PCH_STBY_LVC3_SDA")
	)
	(segment
		(start 411.602936 -23.236682)
		(end 413.1183 -21.721318)
		(width 0.089408)
		(layer "In9.Cu")
		(net "SMB_SLOTX24_PCH_STBY_LVC3_SDA")
	)
	(segment
		(start 390.7536 -78.937866)
		(end 390.7536 -78.561946)
		(width 0.089408)
		(layer "In9.Cu")
		(net "SMB_SLOTX24_PCH_STBY_LVC3_SDA")
	)
	(segment
		(start 397.56842 -42.564558)
		(end 397.56842 -40.053514)
		(width 0.089408)
		(layer "In9.Cu")
		(net "SMB_SLOTX24_PCH_STBY_LVC3_SDA")
	)
	(segment
		(start 413.471868 -20.55749)
		(end 413.841438 -20.18792)
		(width 0.0889)
		(layer "In9.Cu")
		(net "SMB_SLOTX24_PCH_STBY_LVC3_SDA")
	)
	(segment
		(start 432.603402 -20.7518)
		(end 433.1716 -20.183602)
		(width 0.089408)
		(layer "In9.Cu")
		(net "SMB_SLOTX24_PCH_STBY_LVC3_SDA")
	)
	(segment
		(start 438.0484 -21.70303)
		(end 440.73953 -21.70303)
		(width 0.089408)
		(layer "In9.Cu")
		(net "SMB_SLOTX24_PCH_STBY_LVC3_SDA")
	)
	(segment
		(start 384.6703 -96.366076)
		(end 384.36677 -96.062546)
		(width 0.0889)
		(layer "In9.Cu")
		(net "SMB_SLOTX24_PCH_STBY_LVC3_SDA")
	)
	(segment
		(start 392.188954 -72.665082)
		(end 392.618976 -72.23506)
		(width 0.089408)
		(layer "In9.Cu")
		(net "SMB_SLOTX24_PCH_STBY_LVC3_SDA")
	)
	(segment
		(start 461.720184 -8.425688)
		(end 462.47431 -8.425688)
		(width 0.089408)
		(layer "In9.Cu")
		(net "SMB_SLOTX24_PCH_STBY_LVC3_SDA")
	)
	(segment
		(start 385.377182 -89.631266)
		(end 385.907026 -89.101422)
		(width 0.089408)
		(layer "In9.Cu")
		(net "SMB_SLOTX24_PCH_STBY_LVC3_SDA")
	)
	(segment
		(start 435.650386 -21.065236)
		(end 437.410606 -21.065236)
		(width 0.089408)
		(layer "In9.Cu")
		(net "SMB_SLOTX24_PCH_STBY_LVC3_SDA")
	)
	(segment
		(start 396.03934 -44.093638)
		(end 397.56842 -42.564558)
		(width 0.089408)
		(layer "In9.Cu")
		(net "SMB_SLOTX24_PCH_STBY_LVC3_SDA")
	)
	(segment
		(start 391.925048 -77.390498)
		(end 391.925048 -76.097892)
		(width 0.089408)
		(layer "In9.Cu")
		(net "SMB_SLOTX24_PCH_STBY_LVC3_SDA")
	)
	(segment
		(start 392.618976 -72.23506)
		(end 392.618976 -71.14286)
		(width 0.089408)
		(layer "In9.Cu")
		(net "SMB_SLOTX24_PCH_STBY_LVC3_SDA")
	)
	(segment
		(start 426.714666 -19.520408)
		(end 427.946058 -20.7518)
		(width 0.089408)
		(layer "In9.Cu")
		(net "SMB_SLOTX24_PCH_STBY_LVC3_SDA")
	)
	(segment
		(start 385.6609 -98.475292)
		(end 385.6609 -98.45294)
		(width 0.0889)
		(layer "In9.Cu")
		(net "SMB_SLOTX24_PCH_STBY_LVC3_SDA")
	)
	(segment
		(start 395.350238 -54.719982)
		(end 395.350492 -54.719728)
		(width 0.089408)
		(layer "In9.Cu")
		(net "SMB_SLOTX24_PCH_STBY_LVC3_SDA")
	)
	(segment
		(start 388.21995 -87.537544)
		(end 389.972804 -85.78469)
		(width 0.089408)
		(layer "In9.Cu")
		(net "SMB_SLOTX24_PCH_STBY_LVC3_SDA")
	)
	(segment
		(start 463.062066 -9.013444)
		(end 463.909156 -9.013444)
		(width 0.089408)
		(layer "In9.Cu")
		(net "SMB_SLOTX24_PCH_STBY_LVC3_SDA")
	)
	(segment
		(start 395.349984 -62.869064)
		(end 395.350238 -62.86881)
		(width 0.089408)
		(layer "In9.Cu")
		(net "SMB_SLOTX24_PCH_STBY_LVC3_SDA")
	)
	(segment
		(start 457.146152 -14.752574)
		(end 457.146152 -13.851128)
		(width 0.089408)
		(layer "In9.Cu")
		(net "SMB_SLOTX24_PCH_STBY_LVC3_SDA")
	)
	(segment
		(start 395.349984 -62.904878)
		(end 395.349984 -62.869064)
		(width 0.089408)
		(layer "In9.Cu")
		(net "SMB_SLOTX24_PCH_STBY_LVC3_SDA")
	)
	(segment
		(start 390.162796 -81.656682)
		(end 390.162796 -79.52867)
		(width 0.089408)
		(layer "In9.Cu")
		(net "SMB_SLOTX24_PCH_STBY_LVC3_SDA")
	)
	(segment
		(start 449.409566 -24.403304)
		(end 454.934828 -18.878042)
		(width 0.089408)
		(layer "In9.Cu")
		(net "SMB_SLOTX24_PCH_STBY_LVC3_SDA")
	)
	(segment
		(start 397.176752 -35.119564)
		(end 397.176752 -33.46831)
		(width 0.089408)
		(layer "In9.Cu")
		(net "SMB_SLOTX24_PCH_STBY_LVC3_SDA")
	)
	(segment
		(start 385.39547 -92.632784)
		(end 385.4831 -92.545154)
		(width 0.089408)
		(layer "In9.Cu")
		(net "SMB_SLOTX24_PCH_STBY_LVC3_SDA")
	)
	(segment
		(start 398.086834 -31.467044)
		(end 397.477488 -30.857698)
		(width 0.089408)
		(layer "In9.Cu")
		(net "SMB_SLOTX24_PCH_STBY_LVC3_SDA")
	)
	(segment
		(start 388.044436 -101.517196)
		(end 387.91769 -101.579934)
		(width 0.0889)
		(layer "In9.Cu")
		(net "SMB_SLOTX24_PCH_STBY_LVC3_SDA")
	)
	(segment
		(start 390.275572 -81.769458)
		(end 390.162796 -81.656682)
		(width 0.089408)
		(layer "In9.Cu")
		(net "SMB_SLOTX24_PCH_STBY_LVC3_SDA")
	)
	(segment
		(start 418.674296 -20.128738)
		(end 418.674296 -20.130262)
		(width 0.089408)
		(layer "In9.Cu")
		(net "SMB_SLOTX24_PCH_STBY_LVC3_SDA")
	)
	(segment
		(start 401.64258 -23.395686)
		(end 402.976588 -23.395686)
		(width 0.089408)
		(layer "In9.Cu")
		(net "SMB_SLOTX24_PCH_STBY_LVC3_SDA")
	)
	(segment
		(start 392.188954 -73.408286)
		(end 392.188954 -72.665082)
		(width 0.089408)
		(layer "In9.Cu")
		(net "SMB_SLOTX24_PCH_STBY_LVC3_SDA")
	)
	(segment
		(start 395.140688 -52.766976)
		(end 395.140688 -51.85029)
		(width 0.089408)
		(layer "In9.Cu")
		(net "SMB_SLOTX24_PCH_STBY_LVC3_SDA")
	)
	(segment
		(start 394.591794 -64.848486)
		(end 394.592048 -64.848232)
		(width 0.089408)
		(layer "In9.Cu")
		(net "SMB_SLOTX24_PCH_STBY_LVC3_SDA")
	)
	(segment
		(start 385.907026 -88.632284)
		(end 387.001766 -87.537544)
		(width 0.089408)
		(layer "In9.Cu")
		(net "SMB_SLOTX24_PCH_STBY_LVC3_SDA")
	)
	(segment
		(start 394.592048 -64.848232)
		(end 394.592048 -63.82131)
		(width 0.089408)
		(layer "In9.Cu")
		(net "SMB_SLOTX24_PCH_STBY_LVC3_SDA")
	)
	(segment
		(start 390.7536 -78.561946)
		(end 391.925048 -77.390498)
		(width 0.089408)
		(layer "In9.Cu")
		(net "SMB_SLOTX24_PCH_STBY_LVC3_SDA")
	)
	(segment
		(start 389.05434 -101.60508)
		(end 388.964932 -101.581204)
		(width 0.0889)
		(layer "In9.Cu")
		(net "SMB_SLOTX24_PCH_STBY_LVC3_SDA")
	)
	(segment
		(start 418.674296 -20.130262)
		(end 418.908738 -20.364704)
		(width 0.089408)
		(layer "In9.Cu")
		(net "SMB_SLOTX24_PCH_STBY_LVC3_SDA")
	)
	(segment
		(start 437.410606 -21.065236)
		(end 438.0484 -21.70303)
		(width 0.089408)
		(layer "In9.Cu")
		(net "SMB_SLOTX24_PCH_STBY_LVC3_SDA")
	)
	(segment
		(start 384.36677 -95.588328)
		(end 384.731768 -95.22333)
		(width 0.089408)
		(layer "In9.Cu")
		(net "SMB_SLOTX24_PCH_STBY_LVC3_SDA")
	)
	(segment
		(start 391.925048 -76.097892)
		(end 392.350752 -75.672188)
		(width 0.089408)
		(layer "In9.Cu")
		(net "SMB_SLOTX24_PCH_STBY_LVC3_SDA")
	)
	(segment
		(start 445.144652 -22.658832)
		(end 446.889124 -24.403304)
		(width 0.089408)
		(layer "In9.Cu")
		(net "SMB_SLOTX24_PCH_STBY_LVC3_SDA")
	)
	(segment
		(start 457.441808 -17.78635)
		(end 457.441808 -15.04823)
		(width 0.089408)
		(layer "In9.Cu")
		(net "SMB_SLOTX24_PCH_STBY_LVC3_SDA")
	)
	(segment
		(start 413.1183 -21.721318)
		(end 413.471868 -21.36775)
		(width 0.0889)
		(layer "In9.Cu")
		(net "SMB_SLOTX24_PCH_STBY_LVC3_SDA")
	)
	(segment
		(start 395.140434 -52.925218)
		(end 395.140434 -52.76723)
		(width 0.089408)
		(layer "In9.Cu")
		(net "SMB_SLOTX24_PCH_STBY_LVC3_SDA")
	)
	(segment
		(start 395.086586 -47.770034)
		(end 395.390878 -47.465742)
		(width 0.089408)
		(layer "In9.Cu")
		(net "SMB_SLOTX24_PCH_STBY_LVC3_SDA")
	)
	(segment
		(start 394.592048 -69.169788)
		(end 394.592048 -65.32372)
		(width 0.089408)
		(layer "In9.Cu")
		(net "SMB_SLOTX24_PCH_STBY_LVC3_SDA")
	)
	(segment
		(start 384.36677 -96.062546)
		(end 384.36677 -95.588328)
		(width 0.089408)
		(layer "In9.Cu")
		(net "SMB_SLOTX24_PCH_STBY_LVC3_SDA")
	)
	(segment
		(start 420.331646 -20.447508)
		(end 421.193976 -19.585178)
		(width 0.089408)
		(layer "In9.Cu")
		(net "SMB_SLOTX24_PCH_STBY_LVC3_SDA")
	)
	(segment
		(start 385.4831 -91.886278)
		(end 385.377182 -91.78036)
		(width 0.089408)
		(layer "In9.Cu")
		(net "SMB_SLOTX24_PCH_STBY_LVC3_SDA")
	)
	(segment
		(start 394.592048 -65.32372)
		(end 394.591794 -65.323466)
		(width 0.089408)
		(layer "In9.Cu")
		(net "SMB_SLOTX24_PCH_STBY_LVC3_SDA")
	)
	(segment
		(start 384.731768 -94.023434)
		(end 385.39547 -93.359732)
		(width 0.089408)
		(layer "In9.Cu")
		(net "SMB_SLOTX24_PCH_STBY_LVC3_SDA")
	)
	(segment
		(start 434.768752 -20.183602)
		(end 435.650386 -21.065236)
		(width 0.089408)
		(layer "In9.Cu")
		(net "SMB_SLOTX24_PCH_STBY_LVC3_SDA")
	)
	(segment
		(start 395.268704 -51.400964)
		(end 395.268704 -49.255172)
		(width 0.089408)
		(layer "In9.Cu")
		(net "SMB_SLOTX24_PCH_STBY_LVC3_SDA")
	)
	(segment
		(start 394.592048 -63.82131)
		(end 394.591794 -63.821056)
		(width 0.089408)
		(layer "In9.Cu")
		(net "SMB_SLOTX24_PCH_STBY_LVC3_SDA")
	)
	(segment
		(start 387.001766 -87.537544)
		(end 388.21995 -87.537544)
		(width 0.089408)
		(layer "In9.Cu")
		(net "SMB_SLOTX24_PCH_STBY_LVC3_SDA")
	)
	(segment
		(start 395.268958 -51.401218)
		(end 395.268704 -51.400964)
		(width 0.089408)
		(layer "In9.Cu")
		(net "SMB_SLOTX24_PCH_STBY_LVC3_SDA")
	)
	(segment
		(start 397.56842 -40.053514)
		(end 397.387826 -39.87292)
		(width 0.089408)
		(layer "In9.Cu")
		(net "SMB_SLOTX24_PCH_STBY_LVC3_SDA")
	)
	(segment
		(start 394.591794 -63.821056)
		(end 394.591794 -63.663068)
		(width 0.089408)
		(layer "In9.Cu")
		(net "SMB_SLOTX24_PCH_STBY_LVC3_SDA")
	)
	(segment
		(start 454.934828 -18.878042)
		(end 456.350116 -18.878042)
		(width 0.089408)
		(layer "In9.Cu")
		(net "SMB_SLOTX24_PCH_STBY_LVC3_SDA")
	)
	(segment
		(start 460.82458 -10.1727)
		(end 460.82458 -9.321292)
		(width 0.089408)
		(layer "In9.Cu")
		(net "SMB_SLOTX24_PCH_STBY_LVC3_SDA")
	)
	(segment
		(start 397.387826 -39.87292)
		(end 397.387826 -35.330638)
		(width 0.089408)
		(layer "In9.Cu")
		(net "SMB_SLOTX24_PCH_STBY_LVC3_SDA")
	)
	(segment
		(start 392.618976 -71.14286)
		(end 394.592048 -69.169788)
		(width 0.089408)
		(layer "In9.Cu")
		(net "SMB_SLOTX24_PCH_STBY_LVC3_SDA")
	)
	(segment
		(start 385.1656 -101.061266)
		(end 385.1656 -101.018086)
		(width 0.0889)
		(layer "In9.Cu")
		(net "SMB_SLOTX24_PCH_STBY_LVC3_SDA")
	)
	(segment
		(start 462.47431 -8.425688)
		(end 463.062066 -9.013444)
		(width 0.089408)
		(layer "In9.Cu")
		(net "SMB_SLOTX24_PCH_STBY_LVC3_SDA")
	)
	(segment
		(start 390.162796 -79.52867)
		(end 390.7536 -78.937866)
		(width 0.089408)
		(layer "In9.Cu")
		(net "SMB_SLOTX24_PCH_STBY_LVC3_SDA")
	)
	(segment
		(start 397.176752 -33.46831)
		(end 398.086834 -32.558228)
		(width 0.089408)
		(layer "In9.Cu")
		(net "SMB_SLOTX24_PCH_STBY_LVC3_SDA")
	)
	(segment
		(start 389.22325 -101.898196)
		(end 389.05434 -101.60508)
		(width 0.0889)
		(layer "In9.Cu")
		(net "SMB_SLOTX24_PCH_STBY_LVC3_SDA")
	)
	(segment
		(start 395.350238 -62.86881)
		(end 395.350238 -54.719982)
		(width 0.089408)
		(layer "In9.Cu")
		(net "SMB_SLOTX24_PCH_STBY_LVC3_SDA")
	)
	(segment
		(start 397.477488 -24.263096)
		(end 397.477234 -24.262842)
		(width 0.089408)
		(layer "In9.Cu")
		(net "SMB_SLOTX24_PCH_STBY_LVC3_SDA")
	)
	(segment
		(start 413.471868 -21.36775)
		(end 413.471868 -20.55749)
		(width 0.0889)
		(layer "In9.Cu")
		(net "SMB_SLOTX24_PCH_STBY_LVC3_SDA")
	)
	(segment
		(start 441.695332 -22.658832)
		(end 445.144652 -22.658832)
		(width 0.089408)
		(layer "In9.Cu")
		(net "SMB_SLOTX24_PCH_STBY_LVC3_SDA")
	)
	(segment
		(start 385.1656 -99.344226)
		(end 385.1656 -99.301046)
		(width 0.0889)
		(layer "In9.Cu")
		(net "SMB_SLOTX24_PCH_STBY_LVC3_SDA")
	)
	(segment
		(start 390.275572 -82.873342)
		(end 390.275572 -81.769458)
		(width 0.089408)
		(layer "In9.Cu")
		(net "SMB_SLOTX24_PCH_STBY_LVC3_SDA")
	)
	(segment
		(start 421.193976 -19.585178)
		(end 421.714676 -19.585178)
		(width 0.089408)
		(layer "In9.Cu")
		(net "SMB_SLOTX24_PCH_STBY_LVC3_SDA")
	)
	(segment
		(start 421.714676 -19.585178)
		(end 421.779446 -19.520408)
		(width 0.089408)
		(layer "In9.Cu")
		(net "SMB_SLOTX24_PCH_STBY_LVC3_SDA")
	)
	(segment
		(start 397.477234 -24.104854)
		(end 399.061432 -22.520656)
		(width 0.089408)
		(layer "In9.Cu")
		(net "SMB_SLOTX24_PCH_STBY_LVC3_SDA")
	)
	(segment
		(start 421.779446 -19.520408)
		(end 426.714666 -19.520408)
		(width 0.089408)
		(layer "In9.Cu")
		(net "SMB_SLOTX24_PCH_STBY_LVC3_SDA")
	)
	(segment
		(start 440.73953 -21.70303)
		(end 441.695332 -22.658832)
		(width 0.089408)
		(layer "In9.Cu")
		(net "SMB_SLOTX24_PCH_STBY_LVC3_SDA")
	)
	(segment
		(start 392.350752 -75.672188)
		(end 392.350752 -73.570084)
		(width 0.089408)
		(layer "In9.Cu")
		(net "SMB_SLOTX24_PCH_STBY_LVC3_SDA")
	)
	(segment
		(start 388.432548 -101.551486)
		(end 388.30885 -101.480366)
		(width 0.0889)
		(layer "In9.Cu")
		(net "SMB_SLOTX24_PCH_STBY_LVC3_SDA")
	)
	(segment
		(start 397.477234 -24.262842)
		(end 397.477234 -24.104854)
		(width 0.089408)
		(layer "In9.Cu")
		(net "SMB_SLOTX24_PCH_STBY_LVC3_SDA")
	)
	(segment
		(start 418.908738 -20.364704)
		(end 418.910262 -20.364704)
		(width 0.089408)
		(layer "In9.Cu")
		(net "SMB_SLOTX24_PCH_STBY_LVC3_SDA")
	)
	(segment
		(start 457.441808 -15.04823)
		(end 457.146152 -14.752574)
		(width 0.089408)
		(layer "In9.Cu")
		(net "SMB_SLOTX24_PCH_STBY_LVC3_SDA")
	)
	(segment
		(start 385.39547 -93.359732)
		(end 385.39547 -92.632784)
		(width 0.089408)
		(layer "In9.Cu")
		(net "SMB_SLOTX24_PCH_STBY_LVC3_SDA")
	)
	(segment
		(start 418.910262 -20.364704)
		(end 418.993066 -20.447508)
		(width 0.089408)
		(layer "In9.Cu")
		(net "SMB_SLOTX24_PCH_STBY_LVC3_SDA")
	)
	(arc
		(start 385.460748 -99.834446)
		(mid 385.249884 -99.627442)
		(end 385.1656 -99.344226)
		(width 0.0889)
		(layer "In9.Cu")
		(net "SMB_SLOTX24_PCH_STBY_LVC3_SDA")
	)
	(arc
		(start 385.6609 -98.45294)
		(mid 385.60455 -98.25909)
		(end 385.460748 -98.117406)
		(width 0.0889)
		(layer "In9.Cu")
		(net "SMB_SLOTX24_PCH_STBY_LVC3_SDA")
	)
	(arc
		(start 386.451348 -101.551486)
		(mid 386.25145 -101.497987)
		(end 386.051552 -101.551486)
		(width 0.0889)
		(layer "In9.Cu")
		(net "SMB_SLOTX24_PCH_STBY_LVC3_SDA")
	)
	(arc
		(start 386.051552 -101.551486)
		(mid 385.75615 -101.630617)
		(end 385.460748 -101.551486)
		(width 0.0889)
		(layer "In9.Cu")
		(net "SMB_SLOTX24_PCH_STBY_LVC3_SDA")
	)
	(arc
		(start 388.964932 -101.581204)
		(mid 388.695207 -101.629764)
		(end 388.432548 -101.551486)
		(width 0.0889)
		(layer "In9.Cu")
		(net "SMB_SLOTX24_PCH_STBY_LVC3_SDA")
	)
	(arc
		(start 385.1656 -97.59442)
		(mid 385.10925 -97.40057)
		(end 384.965448 -97.258886)
		(width 0.0889)
		(layer "In9.Cu")
		(net "SMB_SLOTX24_PCH_STBY_LVC3_SDA")
	)
	(arc
		(start 385.1656 -101.018086)
		(mid 385.249881 -100.734869)
		(end 385.460748 -100.527866)
		(width 0.0889)
		(layer "In9.Cu")
		(net "SMB_SLOTX24_PCH_STBY_LVC3_SDA")
	)
	(arc
		(start 385.460748 -98.117406)
		(mid 385.249884 -97.910402)
		(end 385.1656 -97.627186)
		(width 0.0889)
		(layer "In9.Cu")
		(net "SMB_SLOTX24_PCH_STBY_LVC3_SDA")
	)
	(arc
		(start 387.042152 -101.551486)
		(mid 386.74675 -101.630617)
		(end 386.451348 -101.551486)
		(width 0.0889)
		(layer "In9.Cu")
		(net "SMB_SLOTX24_PCH_STBY_LVC3_SDA")
	)
	(arc
		(start 385.460748 -98.810826)
		(mid 385.604552 -98.669143)
		(end 385.6609 -98.475292)
		(width 0.0889)
		(layer "In9.Cu")
		(net "SMB_SLOTX24_PCH_STBY_LVC3_SDA")
	)
	(arc
		(start 385.460748 -100.527866)
		(mid 385.604552 -100.386183)
		(end 385.6609 -100.192332)
		(width 0.0889)
		(layer "In9.Cu")
		(net "SMB_SLOTX24_PCH_STBY_LVC3_SDA")
	)
	(arc
		(start 385.460748 -101.551486)
		(mid 385.249884 -101.344482)
		(end 385.1656 -101.061266)
		(width 0.0889)
		(layer "In9.Cu")
		(net "SMB_SLOTX24_PCH_STBY_LVC3_SDA")
	)
	(arc
		(start 384.965448 -97.258886)
		(mid 384.754584 -97.051882)
		(end 384.6703 -96.768666)
		(width 0.0889)
		(layer "In9.Cu")
		(net "SMB_SLOTX24_PCH_STBY_LVC3_SDA")
	)
	(arc
		(start 387.91769 -101.579934)
		(mid 387.682404 -101.590709)
		(end 387.459474 -101.514656)
		(width 0.0889)
		(layer "In9.Cu")
		(net "SMB_SLOTX24_PCH_STBY_LVC3_SDA")
	)
	(arc
		(start 385.6609 -100.16998)
		(mid 385.60455 -99.97613)
		(end 385.460748 -99.834446)
		(width 0.0889)
		(layer "In9.Cu")
		(net "SMB_SLOTX24_PCH_STBY_LVC3_SDA")
	)
	(arc
		(start 387.459474 -101.514656)
		(mid 387.335053 -101.467309)
		(end 387.202172 -101.459284)
		(width 0.0889)
		(layer "In9.Cu")
		(net "SMB_SLOTX24_PCH_STBY_LVC3_SDA")
	)
	(arc
		(start 385.1656 -99.301046)
		(mid 385.249881 -99.017829)
		(end 385.460748 -98.810826)
		(width 0.0889)
		(layer "In9.Cu")
		(net "SMB_SLOTX24_PCH_STBY_LVC3_SDA")
	)
	(arc
		(start 388.30885 -101.480366)
		(mid 388.173686 -101.477506)
		(end 388.044436 -101.517196)
		(width 0.0889)
		(layer "In9.Cu")
		(net "SMB_SLOTX24_PCH_STBY_LVC3_SDA")
	)
	(segment
		(start 400.880072 -113.35512)
		(end 401.85848 -113.35512)
		(width 0.10795)
		(layer "F.Cu")
		(net "SMB_SLOTX24_PCH_STBY_LVC3_SCL")
	)
	(segment
		(start 401.85848 -113.35512)
		(end 401.9042 -113.3094)
		(width 0.10795)
		(layer "F.Cu")
		(net "SMB_SLOTX24_PCH_STBY_LVC3_SCL")
	)
	(via
		(at 388.72795 -101.039676)
		(size 0.508)
		(drill 0.254)
		(layers "F.Cu" "B.Cu")
		(net "SMB_SLOTX24_PCH_STBY_LVC3_SCL")
	)
	(via
		(at 401.9042 -113.3094)
		(size 0.508)
		(drill 0.254)
		(layers "F.Cu" "B.Cu")
		(net "SMB_SLOTX24_PCH_STBY_LVC3_SCL")
	)
	(via
		(at 464.71332 -9.80948)
		(size 0.508)
		(drill 0.254)
		(layers "F.Cu" "B.Cu")
		(net "SMB_SLOTX24_PCH_STBY_LVC3_SCL")
	)
	(via
		(at 402.09724 -114.12728)
		(size 0.6604)
		(drill 0.3302)
		(layers "F.Cu" "B.Cu")
		(net "SMB_SLOTX24_PCH_STBY_LVC3_SCL")
	)
	(segment
		(start 400.756628 -114.690144)
		(end 401.534376 -114.690144)
		(width 0.10795)
		(layer "B.Cu")
		(net "SMB_SLOTX24_PCH_STBY_LVC3_SCL")
	)
	(segment
		(start 464.71332 -9.80948)
		(end 464.693 -9.80948)
		(width 0.10795)
		(layer "B.Cu")
		(net "SMB_SLOTX24_PCH_STBY_LVC3_SCL")
	)
	(segment
		(start 464.693 -9.80948)
		(end 464.693 -9.8298)
		(width 0.10795)
		(layer "B.Cu")
		(net "SMB_SLOTX24_PCH_STBY_LVC3_SCL")
	)
	(segment
		(start 465.215986 -9.797034)
		(end 466.774276 -9.797034)
		(width 0.10795)
		(layer "B.Cu")
		(net "SMB_SLOTX24_PCH_STBY_LVC3_SCL")
	)
	(segment
		(start 467.175088 -9.788398)
		(end 467.21141 -9.82472)
		(width 0.10795)
		(layer "B.Cu")
		(net "SMB_SLOTX24_PCH_STBY_LVC3_SCL")
	)
	(segment
		(start 401.534376 -114.690144)
		(end 402.09724 -114.12728)
		(width 0.10795)
		(layer "B.Cu")
		(net "SMB_SLOTX24_PCH_STBY_LVC3_SCL")
	)
	(segment
		(start 402.15312 -113.55832)
		(end 401.9042 -113.3094)
		(width 0.10795)
		(layer "B.Cu")
		(net "SMB_SLOTX24_PCH_STBY_LVC3_SCL")
	)
	(segment
		(start 467.62416 -9.64692)
		(end 468.181944 -9.64692)
		(width 0.10795)
		(layer "B.Cu")
		(net "SMB_SLOTX24_PCH_STBY_LVC3_SCL")
	)
	(segment
		(start 467.44636 -9.82472)
		(end 467.62416 -9.64692)
		(width 0.10795)
		(layer "B.Cu")
		(net "SMB_SLOTX24_PCH_STBY_LVC3_SCL")
	)
	(segment
		(start 466.782912 -9.788398)
		(end 467.175088 -9.788398)
		(width 0.10795)
		(layer "B.Cu")
		(net "SMB_SLOTX24_PCH_STBY_LVC3_SCL")
	)
	(segment
		(start 464.693 -9.8298)
		(end 465.18322 -9.8298)
		(width 0.10795)
		(layer "B.Cu")
		(net "SMB_SLOTX24_PCH_STBY_LVC3_SCL")
	)
	(segment
		(start 465.18322 -9.8298)
		(end 465.215986 -9.797034)
		(width 0.10795)
		(layer "B.Cu")
		(net "SMB_SLOTX24_PCH_STBY_LVC3_SCL")
	)
	(segment
		(start 402.15312 -114.0714)
		(end 402.15312 -113.55832)
		(width 0.10795)
		(layer "B.Cu")
		(net "SMB_SLOTX24_PCH_STBY_LVC3_SCL")
	)
	(segment
		(start 402.09724 -114.12728)
		(end 402.15312 -114.0714)
		(width 0.10795)
		(layer "B.Cu")
		(net "SMB_SLOTX24_PCH_STBY_LVC3_SCL")
	)
	(segment
		(start 466.774276 -9.797034)
		(end 466.782912 -9.788398)
		(width 0.10795)
		(layer "B.Cu")
		(net "SMB_SLOTX24_PCH_STBY_LVC3_SCL")
	)
	(segment
		(start 467.21141 -9.82472)
		(end 467.44636 -9.82472)
		(width 0.10795)
		(layer "B.Cu")
		(net "SMB_SLOTX24_PCH_STBY_LVC3_SCL")
	)
	(segment
		(start 388.72795 -101.039676)
		(end 388.89686 -101.332792)
		(width 0.0889)
		(layer "In4.Cu")
		(net "SMB_SLOTX24_PCH_STBY_LVC3_SCL")
	)
	(segment
		(start 397.887444 -104.031034)
		(end 397.921734 -104.065324)
		(width 0.0889)
		(layer "In4.Cu")
		(net "SMB_SLOTX24_PCH_STBY_LVC3_SCL")
	)
	(segment
		(start 399.41373 -104.065324)
		(end 400.1389 -104.790494)
		(width 0.0889)
		(layer "In4.Cu")
		(net "SMB_SLOTX24_PCH_STBY_LVC3_SCL")
	)
	(segment
		(start 392.2903 -102.960932)
		(end 392.839194 -103.509826)
		(width 0.0889)
		(layer "In4.Cu")
		(net "SMB_SLOTX24_PCH_STBY_LVC3_SCL")
	)
	(segment
		(start 391.795 -101.876606)
		(end 391.795 -101.909372)
		(width 0.0889)
		(layer "In4.Cu")
		(net "SMB_SLOTX24_PCH_STBY_LVC3_SCL")
	)
	(segment
		(start 400.1389 -104.790494)
		(end 400.1389 -112.44326)
		(width 0.0889)
		(layer "In4.Cu")
		(net "SMB_SLOTX24_PCH_STBY_LVC3_SCL")
	)
	(segment
		(start 397.205962 -104.031034)
		(end 397.887444 -104.031034)
		(width 0.0889)
		(layer "In4.Cu")
		(net "SMB_SLOTX24_PCH_STBY_LVC3_SCL")
	)
	(segment
		(start 393.976352 -103.961692)
		(end 393.987782 -103.968296)
		(width 0.0889)
		(layer "In4.Cu")
		(net "SMB_SLOTX24_PCH_STBY_LVC3_SCL")
	)
	(segment
		(start 397.921734 -104.065324)
		(end 399.41373 -104.065324)
		(width 0.0889)
		(layer "In4.Cu")
		(net "SMB_SLOTX24_PCH_STBY_LVC3_SCL")
	)
	(segment
		(start 392.839194 -103.509826)
		(end 393.504928 -103.509826)
		(width 0.0889)
		(layer "In4.Cu")
		(net "SMB_SLOTX24_PCH_STBY_LVC3_SCL")
	)
	(segment
		(start 388.89686 -101.332792)
		(end 388.986268 -101.356668)
		(width 0.0889)
		(layer "In4.Cu")
		(net "SMB_SLOTX24_PCH_STBY_LVC3_SCL")
	)
	(segment
		(start 392.2903 -102.70998)
		(end 392.2903 -102.960932)
		(width 0.0889)
		(layer "In4.Cu")
		(net "SMB_SLOTX24_PCH_STBY_LVC3_SCL")
	)
	(segment
		(start 401.00504 -113.3094)
		(end 401.9042 -113.3094)
		(width 0.0889)
		(layer "In4.Cu")
		(net "SMB_SLOTX24_PCH_STBY_LVC3_SCL")
	)
	(segment
		(start 400.1389 -112.44326)
		(end 401.00504 -113.3094)
		(width 0.0889)
		(layer "In4.Cu")
		(net "SMB_SLOTX24_PCH_STBY_LVC3_SCL")
	)
	(segment
		(start 393.504928 -103.509826)
		(end 393.893294 -103.898192)
		(width 0.0889)
		(layer "In4.Cu")
		(net "SMB_SLOTX24_PCH_STBY_LVC3_SCL")
	)
	(arc
		(start 391.499852 -101.386386)
		(mid 391.710716 -101.59339)
		(end 391.795 -101.876606)
		(width 0.0889)
		(layer "In4.Cu")
		(net "SMB_SLOTX24_PCH_STBY_LVC3_SCL")
	)
	(arc
		(start 389.518652 -101.386386)
		(mid 389.71855 -101.439885)
		(end 389.918448 -101.386386)
		(width 0.0889)
		(layer "In4.Cu")
		(net "SMB_SLOTX24_PCH_STBY_LVC3_SCL")
	)
	(arc
		(start 394.376148 -103.961946)
		(mid 394.67155 -103.882815)
		(end 394.966952 -103.961946)
		(width 0.0889)
		(layer "In4.Cu")
		(net "SMB_SLOTX24_PCH_STBY_LVC3_SCL")
	)
	(arc
		(start 395.957552 -103.961946)
		(mid 396.15745 -104.015445)
		(end 396.357348 -103.961946)
		(width 0.0889)
		(layer "In4.Cu")
		(net "SMB_SLOTX24_PCH_STBY_LVC3_SCL")
	)
	(arc
		(start 388.986268 -101.356668)
		(mid 389.255993 -101.308108)
		(end 389.518652 -101.386386)
		(width 0.0889)
		(layer "In4.Cu")
		(net "SMB_SLOTX24_PCH_STBY_LVC3_SCL")
	)
	(arc
		(start 393.987782 -103.968296)
		(mid 394.182788 -104.015397)
		(end 394.376148 -103.961946)
		(width 0.0889)
		(layer "In4.Cu")
		(net "SMB_SLOTX24_PCH_STBY_LVC3_SCL")
	)
	(arc
		(start 391.9474 -102.212394)
		(mid 392.006505 -102.251744)
		(end 392.071098 -102.281228)
		(width 0.0889)
		(layer "In4.Cu")
		(net "SMB_SLOTX24_PCH_STBY_LVC3_SCL")
	)
	(arc
		(start 392.071098 -102.281228)
		(mid 392.232347 -102.469203)
		(end 392.2903 -102.70998)
		(width 0.0889)
		(layer "In4.Cu")
		(net "SMB_SLOTX24_PCH_STBY_LVC3_SCL")
	)
	(arc
		(start 396.948152 -103.961946)
		(mid 397.072514 -104.013432)
		(end 397.205962 -104.031034)
		(width 0.0889)
		(layer "In4.Cu")
		(net "SMB_SLOTX24_PCH_STBY_LVC3_SCL")
	)
	(arc
		(start 390.509252 -101.386386)
		(mid 390.70915 -101.439885)
		(end 390.909048 -101.386386)
		(width 0.0889)
		(layer "In4.Cu")
		(net "SMB_SLOTX24_PCH_STBY_LVC3_SCL")
	)
	(arc
		(start 390.909048 -101.386386)
		(mid 391.20445 -101.307255)
		(end 391.499852 -101.386386)
		(width 0.0889)
		(layer "In4.Cu")
		(net "SMB_SLOTX24_PCH_STBY_LVC3_SCL")
	)
	(arc
		(start 396.357348 -103.961946)
		(mid 396.65275 -103.882815)
		(end 396.948152 -103.961946)
		(width 0.0889)
		(layer "In4.Cu")
		(net "SMB_SLOTX24_PCH_STBY_LVC3_SCL")
	)
	(arc
		(start 395.366748 -103.961946)
		(mid 395.66215 -103.882815)
		(end 395.957552 -103.961946)
		(width 0.0889)
		(layer "In4.Cu")
		(net "SMB_SLOTX24_PCH_STBY_LVC3_SCL")
	)
	(arc
		(start 394.966952 -103.961946)
		(mid 395.16685 -104.015445)
		(end 395.366748 -103.961946)
		(width 0.0889)
		(layer "In4.Cu")
		(net "SMB_SLOTX24_PCH_STBY_LVC3_SCL")
	)
	(arc
		(start 389.918448 -101.386386)
		(mid 390.21385 -101.307255)
		(end 390.509252 -101.386386)
		(width 0.0889)
		(layer "In4.Cu")
		(net "SMB_SLOTX24_PCH_STBY_LVC3_SCL")
	)
	(arc
		(start 391.795 -101.909372)
		(mid 391.837533 -102.077809)
		(end 391.9474 -102.212394)
		(width 0.0889)
		(layer "In4.Cu")
		(net "SMB_SLOTX24_PCH_STBY_LVC3_SCL")
	)
	(arc
		(start 393.893294 -103.898192)
		(mid 393.932732 -103.932678)
		(end 393.976352 -103.961692)
		(width 0.0889)
		(layer "In4.Cu")
		(net "SMB_SLOTX24_PCH_STBY_LVC3_SCL")
	)
	(segment
		(start 457.337922 -13.929614)
		(end 461.083152 -10.184384)
		(width 0.089408)
		(layer "In9.Cu")
		(net "SMB_SLOTX24_PCH_STBY_LVC3_SCL")
	)
	(segment
		(start 385.16433 -96.05391)
		(end 385.16433 -93.860874)
		(width 0.089408)
		(layer "In9.Cu")
		(net "SMB_SLOTX24_PCH_STBY_LVC3_SCL")
	)
	(segment
		(start 418.243004 -19.967702)
		(end 418.483288 -20.207986)
		(width 0.089408)
		(layer "In9.Cu")
		(net "SMB_SLOTX24_PCH_STBY_LVC3_SCL")
	)
	(segment
		(start 388.875524 -101.295708)
		(end 388.875524 -101.411532)
		(width 0.0889)
		(layer "In9.Cu")
		(net "SMB_SLOTX24_PCH_STBY_LVC3_SCL")
	)
	(segment
		(start 401.721574 -23.586948)
		(end 401.721828 -23.587202)
		(width 0.089408)
		(layer "In9.Cu")
		(net "SMB_SLOTX24_PCH_STBY_LVC3_SCL")
	)
	(segment
		(start 397.578834 -35.25139)
		(end 397.36776 -35.040316)
		(width 0.089408)
		(layer "In9.Cu")
		(net "SMB_SLOTX24_PCH_STBY_LVC3_SCL")
	)
	(segment
		(start 435.571138 -21.256244)
		(end 437.331358 -21.256244)
		(width 0.089408)
		(layer "In9.Cu")
		(net "SMB_SLOTX24_PCH_STBY_LVC3_SCL")
	)
	(segment
		(start 464.317588 -9.413748)
		(end 464.71332 -9.80948)
		(width 0.089408)
		(layer "In9.Cu")
		(net "SMB_SLOTX24_PCH_STBY_LVC3_SCL")
	)
	(segment
		(start 395.459712 -49.175924)
		(end 395.277594 -48.993806)
		(width 0.089408)
		(layer "In9.Cu")
		(net "SMB_SLOTX24_PCH_STBY_LVC3_SCL")
	)
	(segment
		(start 433.344066 -20.37461)
		(end 434.689504 -20.37461)
		(width 0.089408)
		(layer "In9.Cu")
		(net "SMB_SLOTX24_PCH_STBY_LVC3_SCL")
	)
	(segment
		(start 418.483288 -20.207986)
		(end 418.483288 -20.20951)
		(width 0.089408)
		(layer "In9.Cu")
		(net "SMB_SLOTX24_PCH_STBY_LVC3_SCL")
	)
	(segment
		(start 419.072314 -20.638516)
		(end 420.252398 -20.638516)
		(width 0.089408)
		(layer "In9.Cu")
		(net "SMB_SLOTX24_PCH_STBY_LVC3_SCL")
	)
	(segment
		(start 385.16433 -93.860874)
		(end 385.586224 -93.43898)
		(width 0.089408)
		(layer "In9.Cu")
		(net "SMB_SLOTX24_PCH_STBY_LVC3_SCL")
	)
	(segment
		(start 446.809876 -24.594312)
		(end 449.488814 -24.594312)
		(width 0.089408)
		(layer "In9.Cu")
		(net "SMB_SLOTX24_PCH_STBY_LVC3_SCL")
	)
	(segment
		(start 420.252398 -20.638516)
		(end 420.252652 -20.63877)
		(width 0.089408)
		(layer "In9.Cu")
		(net "SMB_SLOTX24_PCH_STBY_LVC3_SCL")
	)
	(segment
		(start 395.540992 -62.984126)
		(end 395.540992 -62.948312)
		(width 0.089408)
		(layer "In9.Cu")
		(net "SMB_SLOTX24_PCH_STBY_LVC3_SCL")
	)
	(segment
		(start 394.782802 -65.244218)
		(end 394.782802 -64.927734)
		(width 0.089408)
		(layer "In9.Cu")
		(net "SMB_SLOTX24_PCH_STBY_LVC3_SCL")
	)
	(segment
		(start 390.9568 -78.629002)
		(end 392.116056 -77.469746)
		(width 0.089408)
		(layer "In9.Cu")
		(net "SMB_SLOTX24_PCH_STBY_LVC3_SCL")
	)
	(segment
		(start 392.116056 -76.17714)
		(end 392.54176 -75.751436)
		(width 0.089408)
		(layer "In9.Cu")
		(net "SMB_SLOTX24_PCH_STBY_LVC3_SCL")
	)
	(segment
		(start 385.674108 -92.66428)
		(end 385.674108 -91.80703)
		(width 0.089408)
		(layer "In9.Cu")
		(net "SMB_SLOTX24_PCH_STBY_LVC3_SCL")
	)
	(segment
		(start 403.21484 -23.42769)
		(end 411.682184 -23.42769)
		(width 0.089408)
		(layer "In9.Cu")
		(net "SMB_SLOTX24_PCH_STBY_LVC3_SCL")
	)
	(segment
		(start 394.783056 -65.244472)
		(end 394.782802 -65.244218)
		(width 0.089408)
		(layer "In9.Cu")
		(net "SMB_SLOTX24_PCH_STBY_LVC3_SCL")
	)
	(segment
		(start 395.331696 -51.929538)
		(end 395.459712 -51.801522)
		(width 0.089408)
		(layer "In9.Cu")
		(net "SMB_SLOTX24_PCH_STBY_LVC3_SCL")
	)
	(segment
		(start 457.632816 -14.956536)
		(end 457.337922 -14.661642)
		(width 0.089408)
		(layer "In9.Cu")
		(net "SMB_SLOTX24_PCH_STBY_LVC3_SCL")
	)
	(segment
		(start 396.230348 -45.002958)
		(end 396.230348 -44.172886)
		(width 0.089408)
		(layer "In9.Cu")
		(net "SMB_SLOTX24_PCH_STBY_LVC3_SCL")
	)
	(segment
		(start 388.72795 -101.039676)
		(end 388.875524 -101.295708)
		(width 0.0889)
		(layer "In9.Cu")
		(net "SMB_SLOTX24_PCH_STBY_LVC3_SCL")
	)
	(segment
		(start 461.799432 -8.616696)
		(end 462.395062 -8.616696)
		(width 0.089408)
		(layer "In9.Cu")
		(net "SMB_SLOTX24_PCH_STBY_LVC3_SCL")
	)
	(segment
		(start 455.005186 -19.07794)
		(end 456.420474 -19.07794)
		(width 0.089408)
		(layer "In9.Cu")
		(net "SMB_SLOTX24_PCH_STBY_LVC3_SCL")
	)
	(segment
		(start 418.831014 -20.555712)
		(end 418.914072 -20.63877)
		(width 0.089408)
		(layer "In9.Cu")
		(net "SMB_SLOTX24_PCH_STBY_LVC3_SCL")
	)
	(segment
		(start 462.395062 -8.616696)
		(end 463.170016 -9.39165)
		(width 0.089408)
		(layer "In9.Cu")
		(net "SMB_SLOTX24_PCH_STBY_LVC3_SCL")
	)
	(segment
		(start 420.41064 -20.63877)
		(end 421.273224 -19.776186)
		(width 0.089408)
		(layer "In9.Cu")
		(net "SMB_SLOTX24_PCH_STBY_LVC3_SCL")
	)
	(segment
		(start 413.707326 -21.402294)
		(end 413.707326 -20.736052)
		(width 0.089408)
		(layer "In9.Cu")
		(net "SMB_SLOTX24_PCH_STBY_LVC3_SCL")
	)
	(segment
		(start 427.86681 -20.942808)
		(end 432.775868 -20.942808)
		(width 0.089408)
		(layer "In9.Cu")
		(net "SMB_SLOTX24_PCH_STBY_LVC3_SCL")
	)
	(segment
		(start 394.782802 -64.927734)
		(end 394.783056 -64.92748)
		(width 0.089408)
		(layer "In9.Cu")
		(net "SMB_SLOTX24_PCH_STBY_LVC3_SCL")
	)
	(segment
		(start 432.775868 -20.942808)
		(end 433.344066 -20.37461)
		(width 0.089408)
		(layer "In9.Cu")
		(net "SMB_SLOTX24_PCH_STBY_LVC3_SCL")
	)
	(segment
		(start 398.277842 -32.637476)
		(end 398.277842 -31.387796)
		(width 0.089408)
		(layer "In9.Cu")
		(net "SMB_SLOTX24_PCH_STBY_LVC3_SCL")
	)
	(segment
		(start 397.668496 -30.77845)
		(end 397.668496 -24.183848)
		(width 0.089408)
		(layer "In9.Cu")
		(net "SMB_SLOTX24_PCH_STBY_LVC3_SCL")
	)
	(segment
		(start 390.9568 -79.004922)
		(end 390.9568 -78.629002)
		(width 0.089408)
		(layer "In9.Cu")
		(net "SMB_SLOTX24_PCH_STBY_LVC3_SCL")
	)
	(segment
		(start 397.759428 -40.132762)
		(end 397.759682 -40.132508)
		(width 0.089408)
		(layer "In9.Cu")
		(net "SMB_SLOTX24_PCH_STBY_LVC3_SCL")
	)
	(segment
		(start 388.299198 -87.728552)
		(end 390.163812 -85.863938)
		(width 0.089408)
		(layer "In9.Cu")
		(net "SMB_SLOTX24_PCH_STBY_LVC3_SCL")
	)
	(segment
		(start 399.14068 -22.711664)
		(end 400.688302 -22.711664)
		(width 0.089408)
		(layer "In9.Cu")
		(net "SMB_SLOTX24_PCH_STBY_LVC3_SCL")
	)
	(segment
		(start 392.54176 -73.490836)
		(end 392.379962 -73.329038)
		(width 0.089408)
		(layer "In9.Cu")
		(net "SMB_SLOTX24_PCH_STBY_LVC3_SCL")
	)
	(segment
		(start 395.581886 -45.65142)
		(end 396.230348 -45.002958)
		(width 0.089408)
		(layer "In9.Cu")
		(net "SMB_SLOTX24_PCH_STBY_LVC3_SCL")
	)
	(segment
		(start 386.098034 -88.981788)
		(end 387.35127 -87.728552)
		(width 0.089408)
		(layer "In9.Cu")
		(net "SMB_SLOTX24_PCH_STBY_LVC3_SCL")
	)
	(segment
		(start 418.82949 -20.555712)
		(end 418.831014 -20.555712)
		(width 0.089408)
		(layer "In9.Cu")
		(net "SMB_SLOTX24_PCH_STBY_LVC3_SCL")
	)
	(segment
		(start 395.581886 -47.54499)
		(end 395.581886 -45.65142)
		(width 0.089408)
		(layer "In9.Cu")
		(net "SMB_SLOTX24_PCH_STBY_LVC3_SCL")
	)
	(segment
		(start 394.783056 -63.742062)
		(end 395.540992 -62.984126)
		(width 0.089408)
		(layer "In9.Cu")
		(net "SMB_SLOTX24_PCH_STBY_LVC3_SCL")
	)
	(segment
		(start 392.379962 -72.74433)
		(end 392.810492 -72.3138)
		(width 0.089408)
		(layer "In9.Cu")
		(net "SMB_SLOTX24_PCH_STBY_LVC3_SCL")
	)
	(segment
		(start 440.660282 -21.894038)
		(end 441.616084 -22.84984)
		(width 0.089408)
		(layer "In9.Cu")
		(net "SMB_SLOTX24_PCH_STBY_LVC3_SCL")
	)
	(segment
		(start 419.07206 -20.63877)
		(end 419.072314 -20.638516)
		(width 0.089408)
		(layer "In9.Cu")
		(net "SMB_SLOTX24_PCH_STBY_LVC3_SCL")
	)
	(segment
		(start 426.635418 -19.711416)
		(end 427.86681 -20.942808)
		(width 0.089408)
		(layer "In9.Cu")
		(net "SMB_SLOTX24_PCH_STBY_LVC3_SCL")
	)
	(segment
		(start 395.5415 -54.798976)
		(end 395.5415 -53.056028)
		(width 0.089408)
		(layer "In9.Cu")
		(net "SMB_SLOTX24_PCH_STBY_LVC3_SCL")
	)
	(segment
		(start 385.674108 -91.80703)
		(end 385.56819 -91.701112)
		(width 0.089408)
		(layer "In9.Cu")
		(net "SMB_SLOTX24_PCH_STBY_LVC3_SCL")
	)
	(segment
		(start 390.504172 -81.727802)
		(end 390.365996 -81.589626)
		(width 0.089408)
		(layer "In9.Cu")
		(net "SMB_SLOTX24_PCH_STBY_LVC3_SCL")
	)
	(segment
		(start 385.8514 -98.485706)
		(end 385.8514 -98.442526)
		(width 0.0889)
		(layer "In9.Cu")
		(net "SMB_SLOTX24_PCH_STBY_LVC3_SCL")
	)
	(segment
		(start 392.116056 -77.469746)
		(end 392.116056 -76.17714)
		(width 0.089408)
		(layer "In9.Cu")
		(net "SMB_SLOTX24_PCH_STBY_LVC3_SCL")
	)
	(segment
		(start 463.616294 -9.39165)
		(end 463.638392 -9.413748)
		(width 0.089408)
		(layer "In9.Cu")
		(net "SMB_SLOTX24_PCH_STBY_LVC3_SCL")
	)
	(segment
		(start 463.638392 -9.413748)
		(end 464.317588 -9.413748)
		(width 0.089408)
		(layer "In9.Cu")
		(net "SMB_SLOTX24_PCH_STBY_LVC3_SCL")
	)
	(segment
		(start 411.682184 -23.42769)
		(end 413.309562 -21.800312)
		(width 0.089408)
		(layer "In9.Cu")
		(net "SMB_SLOTX24_PCH_STBY_LVC3_SCL")
	)
	(segment
		(start 395.277594 -48.993806)
		(end 395.277594 -47.849282)
		(width 0.089408)
		(layer "In9.Cu")
		(net "SMB_SLOTX24_PCH_STBY_LVC3_SCL")
	)
	(segment
		(start 392.54176 -75.751436)
		(end 392.54176 -73.490836)
		(width 0.089408)
		(layer "In9.Cu")
		(net "SMB_SLOTX24_PCH_STBY_LVC3_SCL")
	)
	(segment
		(start 390.365996 -81.589626)
		(end 390.365996 -79.595726)
		(width 0.089408)
		(layer "In9.Cu")
		(net "SMB_SLOTX24_PCH_STBY_LVC3_SCL")
	)
	(segment
		(start 392.810492 -72.3138)
		(end 392.810492 -71.2216)
		(width 0.089408)
		(layer "In9.Cu")
		(net "SMB_SLOTX24_PCH_STBY_LVC3_SCL")
	)
	(segment
		(start 403.055836 -23.586694)
		(end 403.21484 -23.42769)
		(width 0.089408)
		(layer "In9.Cu")
		(net "SMB_SLOTX24_PCH_STBY_LVC3_SCL")
	)
	(segment
		(start 385.3561 -97.616772)
		(end 385.3561 -97.584006)
		(width 0.0889)
		(layer "In9.Cu")
		(net "SMB_SLOTX24_PCH_STBY_LVC3_SCL")
	)
	(segment
		(start 387.140704 -101.274372)
		(end 386.946648 -101.386386)
		(width 0.0889)
		(layer "In9.Cu")
		(net "SMB_SLOTX24_PCH_STBY_LVC3_SCL")
	)
	(segment
		(start 414.475676 -19.967702)
		(end 418.243004 -19.967702)
		(width 0.089408)
		(layer "In9.Cu")
		(net "SMB_SLOTX24_PCH_STBY_LVC3_SCL")
	)
	(segment
		(start 395.277594 -47.849282)
		(end 395.581886 -47.54499)
		(width 0.089408)
		(layer "In9.Cu")
		(net "SMB_SLOTX24_PCH_STBY_LVC3_SCL")
	)
	(segment
		(start 401.880324 -23.586694)
		(end 403.055836 -23.586694)
		(width 0.089408)
		(layer "In9.Cu")
		(net "SMB_SLOTX24_PCH_STBY_LVC3_SCL")
	)
	(segment
		(start 461.083152 -9.332976)
		(end 461.799432 -8.616696)
		(width 0.089408)
		(layer "In9.Cu")
		(net "SMB_SLOTX24_PCH_STBY_LVC3_SCL")
	)
	(segment
		(start 413.309562 -21.800312)
		(end 413.309562 -21.800058)
		(width 0.089408)
		(layer "In9.Cu")
		(net "SMB_SLOTX24_PCH_STBY_LVC3_SCL")
	)
	(segment
		(start 386.098034 -89.188544)
		(end 386.098034 -88.981788)
		(width 0.089408)
		(layer "In9.Cu")
		(net "SMB_SLOTX24_PCH_STBY_LVC3_SCL")
	)
	(segment
		(start 394.783056 -64.92748)
		(end 394.783056 -63.742062)
		(width 0.089408)
		(layer "In9.Cu")
		(net "SMB_SLOTX24_PCH_STBY_LVC3_SCL")
	)
	(segment
		(start 395.459712 -51.801522)
		(end 395.459712 -51.797204)
		(width 0.089408)
		(layer "In9.Cu")
		(net "SMB_SLOTX24_PCH_STBY_LVC3_SCL")
	)
	(segment
		(start 437.331358 -21.256244)
		(end 437.969152 -21.894038)
		(width 0.089408)
		(layer "In9.Cu")
		(net "SMB_SLOTX24_PCH_STBY_LVC3_SCL")
	)
	(segment
		(start 385.8514 -100.202746)
		(end 385.8514 -100.159566)
		(width 0.0889)
		(layer "In9.Cu")
		(net "SMB_SLOTX24_PCH_STBY_LVC3_SCL")
	)
	(segment
		(start 390.163812 -83.255358)
		(end 390.504172 -82.914998)
		(width 0.089408)
		(layer "In9.Cu")
		(net "SMB_SLOTX24_PCH_STBY_LVC3_SCL")
	)
	(segment
		(start 397.36776 -35.040316)
		(end 397.36776 -33.547558)
		(width 0.089408)
		(layer "In9.Cu")
		(net "SMB_SLOTX24_PCH_STBY_LVC3_SCL")
	)
	(segment
		(start 395.459712 -51.321716)
		(end 395.459712 -49.175924)
		(width 0.089408)
		(layer "In9.Cu")
		(net "SMB_SLOTX24_PCH_STBY_LVC3_SCL")
	)
	(segment
		(start 392.810492 -71.2216)
		(end 394.783056 -69.249036)
		(width 0.089408)
		(layer "In9.Cu")
		(net "SMB_SLOTX24_PCH_STBY_LVC3_SCL")
	)
	(segment
		(start 394.783056 -69.249036)
		(end 394.783056 -65.244472)
		(width 0.089408)
		(layer "In9.Cu")
		(net "SMB_SLOTX24_PCH_STBY_LVC3_SCL")
	)
	(segment
		(start 441.616084 -22.84984)
		(end 445.065404 -22.84984)
		(width 0.089408)
		(layer "In9.Cu")
		(net "SMB_SLOTX24_PCH_STBY_LVC3_SCL")
	)
	(segment
		(start 434.689504 -20.37461)
		(end 435.571138 -21.256244)
		(width 0.089408)
		(layer "In9.Cu")
		(net "SMB_SLOTX24_PCH_STBY_LVC3_SCL")
	)
	(segment
		(start 397.668496 -24.183848)
		(end 399.14068 -22.711664)
		(width 0.089408)
		(layer "In9.Cu")
		(net "SMB_SLOTX24_PCH_STBY_LVC3_SCL")
	)
	(segment
		(start 395.459712 -51.797204)
		(end 395.459966 -51.79695)
		(width 0.089408)
		(layer "In9.Cu")
		(net "SMB_SLOTX24_PCH_STBY_LVC3_SCL")
	)
	(segment
		(start 392.379962 -73.329038)
		(end 392.379962 -72.74433)
		(width 0.089408)
		(layer "In9.Cu")
		(net "SMB_SLOTX24_PCH_STBY_LVC3_SCL")
	)
	(segment
		(start 445.065404 -22.84984)
		(end 446.809876 -24.594312)
		(width 0.089408)
		(layer "In9.Cu")
		(net "SMB_SLOTX24_PCH_STBY_LVC3_SCL")
	)
	(segment
		(start 390.163812 -85.863938)
		(end 390.163812 -83.255358)
		(width 0.089408)
		(layer "In9.Cu")
		(net "SMB_SLOTX24_PCH_STBY_LVC3_SCL")
	)
	(segment
		(start 385.56819 -89.718388)
		(end 386.098034 -89.188544)
		(width 0.089408)
		(layer "In9.Cu")
		(net "SMB_SLOTX24_PCH_STBY_LVC3_SCL")
	)
	(segment
		(start 418.483288 -20.20951)
		(end 418.82949 -20.555712)
		(width 0.089408)
		(layer "In9.Cu")
		(net "SMB_SLOTX24_PCH_STBY_LVC3_SCL")
	)
	(segment
		(start 457.632816 -17.865598)
		(end 457.632816 -14.956536)
		(width 0.089408)
		(layer "In9.Cu")
		(net "SMB_SLOTX24_PCH_STBY_LVC3_SCL")
	)
	(segment
		(start 388.528052 -101.386386)
		(end 388.377176 -101.299264)
		(width 0.0889)
		(layer "In9.Cu")
		(net "SMB_SLOTX24_PCH_STBY_LVC3_SCL")
	)
	(segment
		(start 390.504172 -82.914998)
		(end 390.504172 -81.727802)
		(width 0.089408)
		(layer "In9.Cu")
		(net "SMB_SLOTX24_PCH_STBY_LVC3_SCL")
	)
	(segment
		(start 401.563586 -23.586948)
		(end 401.721574 -23.586948)
		(width 0.089408)
		(layer "In9.Cu")
		(net "SMB_SLOTX24_PCH_STBY_LVC3_SCL")
	)
	(segment
		(start 385.586224 -92.752164)
		(end 385.674108 -92.66428)
		(width 0.089408)
		(layer "In9.Cu")
		(net "SMB_SLOTX24_PCH_STBY_LVC3_SCL")
	)
	(segment
		(start 385.586224 -93.43898)
		(end 385.586224 -92.752164)
		(width 0.089408)
		(layer "In9.Cu")
		(net "SMB_SLOTX24_PCH_STBY_LVC3_SCL")
	)
	(segment
		(start 395.459966 -51.79695)
		(end 395.459966 -51.32197)
		(width 0.089408)
		(layer "In9.Cu")
		(net "SMB_SLOTX24_PCH_STBY_LVC3_SCL")
	)
	(segment
		(start 385.56819 -91.701112)
		(end 385.56819 -89.718388)
		(width 0.089408)
		(layer "In9.Cu")
		(net "SMB_SLOTX24_PCH_STBY_LVC3_SCL")
	)
	(segment
		(start 463.170016 -9.39165)
		(end 463.616294 -9.39165)
		(width 0.089408)
		(layer "In9.Cu")
		(net "SMB_SLOTX24_PCH_STBY_LVC3_SCL")
	)
	(segment
		(start 421.273224 -19.776186)
		(end 421.793924 -19.776186)
		(width 0.089408)
		(layer "In9.Cu")
		(net "SMB_SLOTX24_PCH_STBY_LVC3_SCL")
	)
	(segment
		(start 395.540992 -62.948312)
		(end 395.541246 -62.948058)
		(width 0.089408)
		(layer "In9.Cu")
		(net "SMB_SLOTX24_PCH_STBY_LVC3_SCL")
	)
	(segment
		(start 401.879816 -23.587202)
		(end 401.880324 -23.586694)
		(width 0.089408)
		(layer "In9.Cu")
		(net "SMB_SLOTX24_PCH_STBY_LVC3_SCL")
	)
	(segment
		(start 384.8608 -96.758252)
		(end 384.8608 -96.35744)
		(width 0.0889)
		(layer "In9.Cu")
		(net "SMB_SLOTX24_PCH_STBY_LVC3_SCL")
	)
	(segment
		(start 395.541246 -62.948058)
		(end 395.541246 -54.79923)
		(width 0.089408)
		(layer "In9.Cu")
		(net "SMB_SLOTX24_PCH_STBY_LVC3_SCL")
	)
	(segment
		(start 413.309562 -21.800058)
		(end 413.707326 -21.402294)
		(width 0.089408)
		(layer "In9.Cu")
		(net "SMB_SLOTX24_PCH_STBY_LVC3_SCL")
	)
	(segment
		(start 456.420474 -19.07794)
		(end 457.632816 -17.865598)
		(width 0.089408)
		(layer "In9.Cu")
		(net "SMB_SLOTX24_PCH_STBY_LVC3_SCL")
	)
	(segment
		(start 449.488814 -24.594312)
		(end 455.005186 -19.07794)
		(width 0.089408)
		(layer "In9.Cu")
		(net "SMB_SLOTX24_PCH_STBY_LVC3_SCL")
	)
	(segment
		(start 398.277842 -31.387796)
		(end 397.668496 -30.77845)
		(width 0.089408)
		(layer "In9.Cu")
		(net "SMB_SLOTX24_PCH_STBY_LVC3_SCL")
	)
	(segment
		(start 387.9596 -101.346)
		(end 387.854444 -101.397816)
		(width 0.0889)
		(layer "In9.Cu")
		(net "SMB_SLOTX24_PCH_STBY_LVC3_SCL")
	)
	(segment
		(start 395.541246 -54.79923)
		(end 395.5415 -54.798976)
		(width 0.089408)
		(layer "In9.Cu")
		(net "SMB_SLOTX24_PCH_STBY_LVC3_SCL")
	)
	(segment
		(start 461.083152 -10.184384)
		(end 461.083152 -9.332976)
		(width 0.089408)
		(layer "In9.Cu")
		(net "SMB_SLOTX24_PCH_STBY_LVC3_SCL")
	)
	(segment
		(start 418.914072 -20.63877)
		(end 419.07206 -20.63877)
		(width 0.089408)
		(layer "In9.Cu")
		(net "SMB_SLOTX24_PCH_STBY_LVC3_SCL")
	)
	(segment
		(start 397.578834 -39.793672)
		(end 397.578834 -35.25139)
		(width 0.089408)
		(layer "In9.Cu")
		(net "SMB_SLOTX24_PCH_STBY_LVC3_SCL")
	)
	(segment
		(start 395.5415 -53.056028)
		(end 395.331696 -52.846224)
		(width 0.089408)
		(layer "In9.Cu")
		(net "SMB_SLOTX24_PCH_STBY_LVC3_SCL")
	)
	(segment
		(start 390.365996 -79.595726)
		(end 390.9568 -79.004922)
		(width 0.089408)
		(layer "In9.Cu")
		(net "SMB_SLOTX24_PCH_STBY_LVC3_SCL")
	)
	(segment
		(start 400.688302 -22.711664)
		(end 401.563586 -23.586948)
		(width 0.089408)
		(layer "In9.Cu")
		(net "SMB_SLOTX24_PCH_STBY_LVC3_SCL")
	)
	(segment
		(start 395.459966 -51.32197)
		(end 395.459712 -51.321716)
		(width 0.089408)
		(layer "In9.Cu")
		(net "SMB_SLOTX24_PCH_STBY_LVC3_SCL")
	)
	(segment
		(start 396.230348 -44.172886)
		(end 397.759428 -42.643806)
		(width 0.089408)
		(layer "In9.Cu")
		(net "SMB_SLOTX24_PCH_STBY_LVC3_SCL")
	)
	(segment
		(start 421.793924 -19.776186)
		(end 421.858694 -19.711416)
		(width 0.089408)
		(layer "In9.Cu")
		(net "SMB_SLOTX24_PCH_STBY_LVC3_SCL")
	)
	(segment
		(start 420.252652 -20.63877)
		(end 420.41064 -20.63877)
		(width 0.089408)
		(layer "In9.Cu")
		(net "SMB_SLOTX24_PCH_STBY_LVC3_SCL")
	)
	(segment
		(start 397.759682 -39.97452)
		(end 397.578834 -39.793672)
		(width 0.089408)
		(layer "In9.Cu")
		(net "SMB_SLOTX24_PCH_STBY_LVC3_SCL")
	)
	(segment
		(start 395.331696 -52.846224)
		(end 395.331696 -51.929538)
		(width 0.089408)
		(layer "In9.Cu")
		(net "SMB_SLOTX24_PCH_STBY_LVC3_SCL")
	)
	(segment
		(start 413.707326 -20.736052)
		(end 414.475676 -19.967702)
		(width 0.089408)
		(layer "In9.Cu")
		(net "SMB_SLOTX24_PCH_STBY_LVC3_SCL")
	)
	(segment
		(start 387.35127 -87.728552)
		(end 388.299198 -87.728552)
		(width 0.089408)
		(layer "In9.Cu")
		(net "SMB_SLOTX24_PCH_STBY_LVC3_SCL")
	)
	(segment
		(start 437.969152 -21.894038)
		(end 440.660282 -21.894038)
		(width 0.089408)
		(layer "In9.Cu")
		(net "SMB_SLOTX24_PCH_STBY_LVC3_SCL")
	)
	(segment
		(start 397.759682 -40.132508)
		(end 397.759682 -39.97452)
		(width 0.089408)
		(layer "In9.Cu")
		(net "SMB_SLOTX24_PCH_STBY_LVC3_SCL")
	)
	(segment
		(start 401.721828 -23.587202)
		(end 401.879816 -23.587202)
		(width 0.089408)
		(layer "In9.Cu")
		(net "SMB_SLOTX24_PCH_STBY_LVC3_SCL")
	)
	(segment
		(start 397.36776 -33.547558)
		(end 398.277842 -32.637476)
		(width 0.089408)
		(layer "In9.Cu")
		(net "SMB_SLOTX24_PCH_STBY_LVC3_SCL")
	)
	(segment
		(start 397.759428 -42.643806)
		(end 397.759428 -40.132762)
		(width 0.089408)
		(layer "In9.Cu")
		(net "SMB_SLOTX24_PCH_STBY_LVC3_SCL")
	)
	(segment
		(start 384.8608 -96.35744)
		(end 385.16433 -96.05391)
		(width 0.0889)
		(layer "In9.Cu")
		(net "SMB_SLOTX24_PCH_STBY_LVC3_SCL")
	)
	(segment
		(start 421.858694 -19.711416)
		(end 426.635418 -19.711416)
		(width 0.089408)
		(layer "In9.Cu")
		(net "SMB_SLOTX24_PCH_STBY_LVC3_SCL")
	)
	(segment
		(start 457.337922 -14.661642)
		(end 457.337922 -13.929614)
		(width 0.089408)
		(layer "In9.Cu")
		(net "SMB_SLOTX24_PCH_STBY_LVC3_SCL")
	)
	(arc
		(start 385.8514 -100.159566)
		(mid 385.767119 -99.876349)
		(end 385.556252 -99.669346)
		(width 0.0889)
		(layer "In9.Cu")
		(net "SMB_SLOTX24_PCH_STBY_LVC3_SCL")
	)
	(arc
		(start 385.556252 -100.692966)
		(mid 385.767116 -100.485962)
		(end 385.8514 -100.202746)
		(width 0.0889)
		(layer "In9.Cu")
		(net "SMB_SLOTX24_PCH_STBY_LVC3_SCL")
	)
	(arc
		(start 385.3561 -97.584006)
		(mid 385.271819 -97.300789)
		(end 385.060952 -97.093786)
		(width 0.0889)
		(layer "In9.Cu")
		(net "SMB_SLOTX24_PCH_STBY_LVC3_SCL")
	)
	(arc
		(start 385.060952 -97.093786)
		(mid 384.917148 -96.952103)
		(end 384.8608 -96.758252)
		(width 0.0889)
		(layer "In9.Cu")
		(net "SMB_SLOTX24_PCH_STBY_LVC3_SCL")
	)
	(arc
		(start 387.553962 -101.34854)
		(mid 387.353672 -101.276142)
		(end 387.140704 -101.274372)
		(width 0.0889)
		(layer "In9.Cu")
		(net "SMB_SLOTX24_PCH_STBY_LVC3_SCL")
	)
	(arc
		(start 385.8514 -98.442526)
		(mid 385.767119 -98.159309)
		(end 385.556252 -97.952306)
		(width 0.0889)
		(layer "In9.Cu")
		(net "SMB_SLOTX24_PCH_STBY_LVC3_SCL")
	)
	(arc
		(start 386.946648 -101.386386)
		(mid 386.74675 -101.439885)
		(end 386.546852 -101.386386)
		(width 0.0889)
		(layer "In9.Cu")
		(net "SMB_SLOTX24_PCH_STBY_LVC3_SCL")
	)
	(arc
		(start 385.556252 -98.975926)
		(mid 385.767116 -98.768922)
		(end 385.8514 -98.485706)
		(width 0.0889)
		(layer "In9.Cu")
		(net "SMB_SLOTX24_PCH_STBY_LVC3_SCL")
	)
	(arc
		(start 388.875524 -101.411532)
		(mid 388.698895 -101.438801)
		(end 388.528052 -101.386386)
		(width 0.0889)
		(layer "In9.Cu")
		(net "SMB_SLOTX24_PCH_STBY_LVC3_SCL")
	)
	(arc
		(start 385.956048 -101.386386)
		(mid 385.40944 -101.239574)
		(end 385.556252 -100.692966)
		(width 0.0889)
		(layer "In9.Cu")
		(net "SMB_SLOTX24_PCH_STBY_LVC3_SCL")
	)
	(arc
		(start 388.377176 -101.299264)
		(mid 388.16429 -101.285966)
		(end 387.9596 -101.346)
		(width 0.0889)
		(layer "In9.Cu")
		(net "SMB_SLOTX24_PCH_STBY_LVC3_SCL")
	)
	(arc
		(start 385.556252 -97.952306)
		(mid 385.412448 -97.810623)
		(end 385.3561 -97.616772)
		(width 0.0889)
		(layer "In9.Cu")
		(net "SMB_SLOTX24_PCH_STBY_LVC3_SCL")
	)
	(arc
		(start 386.546852 -101.386386)
		(mid 386.25145 -101.307255)
		(end 385.956048 -101.386386)
		(width 0.0889)
		(layer "In9.Cu")
		(net "SMB_SLOTX24_PCH_STBY_LVC3_SCL")
	)
	(arc
		(start 385.556252 -99.669346)
		(mid 385.355941 -99.322636)
		(end 385.556252 -98.975926)
		(width 0.0889)
		(layer "In9.Cu")
		(net "SMB_SLOTX24_PCH_STBY_LVC3_SCL")
	)
	(arc
		(start 387.854444 -101.397816)
		(mid 387.699812 -101.399953)
		(end 387.553962 -101.34854)
		(width 0.0889)
		(layer "In9.Cu")
		(net "SMB_SLOTX24_PCH_STBY_LVC3_SCL")
	)
	(segment
		(start 166.67226 -75.58786)
		(end 166.2684 -75.184)
		(width 0.1016)
		(layer "F.Cu")
		(net "Net_341")
	)
	(segment
		(start 166.67226 -76.593192)
		(end 166.67226 -75.58786)
		(width 0.1016)
		(layer "F.Cu")
		(net "Net_341")
	)
	(via
		(at 166.2684 -75.184)
		(size 0.508)
		(drill 0.254)
		(layers "F.Cu" "B.Cu")
		(net "Net_341")
	)
	(via
		(at 165.317424 -74.233024)
		(size 0.6604)
		(drill 0.3302)
		(layers "F.Cu" "B.Cu")
		(net "Net_341")
	)
	(segment
		(start 166.2684 -75.184)
		(end 165.317424 -74.233024)
		(width 0.1016)
		(layer "B.Cu")
		(net "Net_341")
	)
	(via
		(at 449.51142 -2.55778)
		(size 0.6604)
		(drill 0.3302)
		(layers "F.Cu" "B.Cu")
		(net "PU_UV_HIGH_SET")
	)
	(segment
		(start 450.2658 -0.160528)
		(end 450.2658 -1.8034)
		(width 0.10795)
		(layer "B.Cu")
		(net "PU_UV_HIGH_SET")
	)
	(segment
		(start 449.51142 -3.51282)
		(end 449.51142 -2.55778)
		(width 0.10795)
		(layer "B.Cu")
		(net "PU_UV_HIGH_SET")
	)
	(segment
		(start 450.2658 -1.8034)
		(end 449.51142 -2.55778)
		(width 0.10795)
		(layer "B.Cu")
		(net "PU_UV_HIGH_SET")
	)
	(segment
		(start 450.690488 0.26416)
		(end 450.2658 -0.160528)
		(width 0.10795)
		(layer "B.Cu")
		(net "PU_UV_HIGH_SET")
	)
	(segment
		(start 450.3674 -3.8608)
		(end 449.8594 -3.8608)
		(width 0.10795)
		(layer "B.Cu")
		(net "PU_UV_HIGH_SET")
	)
	(segment
		(start 449.454016 3.81)
		(end 450.690488 2.573528)
		(width 0.10795)
		(layer "B.Cu")
		(net "PU_UV_HIGH_SET")
	)
	(segment
		(start 450.690488 2.573528)
		(end 450.690488 0.26416)
		(width 0.10795)
		(layer "B.Cu")
		(net "PU_UV_HIGH_SET")
	)
	(segment
		(start 449.8594 -3.8608)
		(end 449.51142 -3.51282)
		(width 0.10795)
		(layer "B.Cu")
		(net "PU_UV_HIGH_SET")
	)
	(segment
		(start 456.106784 -0.355346)
		(end 457.074016 0.611886)
		(width 0.10795)
		(layer "F.Cu")
		(net "PU_SPI_BMC_BT_CS0_N")
	)
	(segment
		(start 457.074016 0.611886)
		(end 457.074016 1.27)
		(width 0.10795)
		(layer "F.Cu")
		(net "PU_SPI_BMC_BT_CS0_N")
	)
	(segment
		(start 456.106784 -1.539494)
		(end 456.106784 -0.355346)
		(width 0.10795)
		(layer "F.Cu")
		(net "PU_SPI_BMC_BT_CS0_N")
	)
	(via
		(at 455.60488 -1.876298)
		(size 0.6604)
		(drill 0.3302)
		(layers "F.Cu" "B.Cu")
		(net "PU_SPI_BMC_BT_CS0_N")
	)
	(segment
		(start 455.60488 -1.876298)
		(end 457.074016 -0.407162)
		(width 0.10795)
		(layer "B.Cu")
		(net "PU_SPI_BMC_BT_CS0_N")
	)
	(segment
		(start 457.074016 -0.407162)
		(end 457.074016 1.27)
		(width 0.10795)
		(layer "B.Cu")
		(net "PU_SPI_BMC_BT_CS0_N")
	)
	(via
		(at 450.7484 -2.2352)
		(size 0.6604)
		(drill 0.3302)
		(layers "F.Cu" "B.Cu")
		(net "PD_UV_HIGH_SET")
	)
	(segment
		(start 453.041258 0.468122)
		(end 453.041258 2.317242)
		(width 0.10795)
		(layer "B.Cu")
		(net "PD_UV_HIGH_SET")
	)
	(segment
		(start 450.85 -4.8514)
		(end 451.5104 -5.5118)
		(width 0.10795)
		(layer "B.Cu")
		(net "PD_UV_HIGH_SET")
	)
	(segment
		(start 450.7484 -3.302)
		(end 450.85 -3.4036)
		(width 0.10795)
		(layer "B.Cu")
		(net "PD_UV_HIGH_SET")
	)
	(segment
		(start 450.7484 -1.824736)
		(end 453.041258 0.468122)
		(width 0.10795)
		(layer "B.Cu")
		(net "PD_UV_HIGH_SET")
	)
	(segment
		(start 450.85 -3.4036)
		(end 450.85 -4.8514)
		(width 0.10795)
		(layer "B.Cu")
		(net "PD_UV_HIGH_SET")
	)
	(segment
		(start 450.7484 -2.2352)
		(end 450.7484 -1.824736)
		(width 0.10795)
		(layer "B.Cu")
		(net "PD_UV_HIGH_SET")
	)
	(segment
		(start 451.5104 -5.5118)
		(end 451.7898 -5.5118)
		(width 0.10795)
		(layer "B.Cu")
		(net "PD_UV_HIGH_SET")
	)
	(segment
		(start 453.041258 2.317242)
		(end 454.534016 3.81)
		(width 0.10795)
		(layer "B.Cu")
		(net "PD_UV_HIGH_SET")
	)
	(segment
		(start 450.7484 -2.2352)
		(end 450.7484 -3.302)
		(width 0.10795)
		(layer "B.Cu")
		(net "PD_UV_HIGH_SET")
	)
	(segment
		(start 448.667886 -40.2971)
		(end 449.297044 -39.667942)
		(width 0.10795)
		(layer "F.Cu")
		(net "PD_SPI_BMC_BT_CS0_N")
	)
	(segment
		(start 448.2719 -40.2971)
		(end 448.667886 -40.2971)
		(width 0.10795)
		(layer "F.Cu")
		(net "PD_SPI_BMC_BT_CS0_N")
	)
	(via
		(at 449.297044 -39.667942)
		(size 0.508)
		(drill 0.254)
		(layers "F.Cu" "B.Cu")
		(net "PD_SPI_BMC_BT_CS0_N")
	)
	(via
		(at 463.32902 -10.084562)
		(size 0.508)
		(drill 0.254)
		(layers "F.Cu" "B.Cu")
		(net "PD_SPI_BMC_BT_CS0_N")
	)
	(segment
		(start 462.495392 -8.171688)
		(end 462.49463 -8.170926)
		(width 0.089408)
		(layer "In4.Cu")
		(net "PD_SPI_BMC_BT_CS0_N")
	)
	(segment
		(start 462.629504 -0.121158)
		(end 462.154016 0.35433)
		(width 0.089408)
		(layer "In4.Cu")
		(net "PD_SPI_BMC_BT_CS0_N")
	)
	(segment
		(start 463.2071 -9.830054)
		(end 463.2071 -8.799322)
		(width 0.089408)
		(layer "In4.Cu")
		(net "PD_SPI_BMC_BT_CS0_N")
	)
	(segment
		(start 462.154016 0.35433)
		(end 462.154016 1.27)
		(width 0.089408)
		(layer "In4.Cu")
		(net "PD_SPI_BMC_BT_CS0_N")
	)
	(segment
		(start 463.32902 -10.084562)
		(end 463.32902 -9.951974)
		(width 0.089408)
		(layer "In4.Cu")
		(net "PD_SPI_BMC_BT_CS0_N")
	)
	(segment
		(start 460.44231 -4.972812)
		(end 460.710534 -4.704588)
		(width 0.089408)
		(layer "In4.Cu")
		(net "PD_SPI_BMC_BT_CS0_N")
	)
	(segment
		(start 462.629504 -0.699262)
		(end 462.629504 -0.121158)
		(width 0.089408)
		(layer "In4.Cu")
		(net "PD_SPI_BMC_BT_CS0_N")
	)
	(segment
		(start 460.44231 -7.875778)
		(end 460.44231 -4.972812)
		(width 0.089408)
		(layer "In4.Cu")
		(net "PD_SPI_BMC_BT_CS0_N")
	)
	(segment
		(start 460.737458 -8.170926)
		(end 460.44231 -7.875778)
		(width 0.089408)
		(layer "In4.Cu")
		(net "PD_SPI_BMC_BT_CS0_N")
	)
	(segment
		(start 462.53527 -0.793496)
		(end 462.629504 -0.699262)
		(width 0.089408)
		(layer "In4.Cu")
		(net "PD_SPI_BMC_BT_CS0_N")
	)
	(segment
		(start 463.32902 -9.951974)
		(end 463.2071 -9.830054)
		(width 0.089408)
		(layer "In4.Cu")
		(net "PD_SPI_BMC_BT_CS0_N")
	)
	(segment
		(start 462.53527 -3.486404)
		(end 462.53527 -0.793496)
		(width 0.089408)
		(layer "In4.Cu")
		(net "PD_SPI_BMC_BT_CS0_N")
	)
	(segment
		(start 463.2071 -8.799322)
		(end 462.579466 -8.171688)
		(width 0.089408)
		(layer "In4.Cu")
		(net "PD_SPI_BMC_BT_CS0_N")
	)
	(segment
		(start 460.710534 -4.704588)
		(end 461.317086 -4.704588)
		(width 0.089408)
		(layer "In4.Cu")
		(net "PD_SPI_BMC_BT_CS0_N")
	)
	(segment
		(start 462.49463 -8.170926)
		(end 460.737458 -8.170926)
		(width 0.089408)
		(layer "In4.Cu")
		(net "PD_SPI_BMC_BT_CS0_N")
	)
	(segment
		(start 461.317086 -4.704588)
		(end 462.53527 -3.486404)
		(width 0.089408)
		(layer "In4.Cu")
		(net "PD_SPI_BMC_BT_CS0_N")
	)
	(segment
		(start 462.579466 -8.171688)
		(end 462.495392 -8.171688)
		(width 0.089408)
		(layer "In4.Cu")
		(net "PD_SPI_BMC_BT_CS0_N")
	)
	(segment
		(start 463.32902 -10.084562)
		(end 463.32902 -10.511536)
		(width 0.089408)
		(layer "In9.Cu")
		(net "PD_SPI_BMC_BT_CS0_N")
	)
	(segment
		(start 462.440274 -15.937992)
		(end 460.601822 -17.776444)
		(width 0.089408)
		(layer "In9.Cu")
		(net "PD_SPI_BMC_BT_CS0_N")
	)
	(segment
		(start 454.264014 -33.625028)
		(end 449.297044 -38.591998)
		(width 0.089408)
		(layer "In9.Cu")
		(net "PD_SPI_BMC_BT_CS0_N")
	)
	(segment
		(start 463.234024 -10.606532)
		(end 463.234024 -12.024614)
		(width 0.089408)
		(layer "In9.Cu")
		(net "PD_SPI_BMC_BT_CS0_N")
	)
	(segment
		(start 463.32902 -10.511536)
		(end 463.234024 -10.606532)
		(width 0.089408)
		(layer "In9.Cu")
		(net "PD_SPI_BMC_BT_CS0_N")
	)
	(segment
		(start 455.934572 -26.026618)
		(end 455.42581 -26.53538)
		(width 0.089408)
		(layer "In9.Cu")
		(net "PD_SPI_BMC_BT_CS0_N")
	)
	(segment
		(start 455.42581 -32.100266)
		(end 454.264014 -33.262062)
		(width 0.089408)
		(layer "In9.Cu")
		(net "PD_SPI_BMC_BT_CS0_N")
	)
	(segment
		(start 455.934572 -22.931628)
		(end 455.934572 -26.026618)
		(width 0.089408)
		(layer "In9.Cu")
		(net "PD_SPI_BMC_BT_CS0_N")
	)
	(segment
		(start 454.264014 -33.262062)
		(end 454.264014 -33.625028)
		(width 0.089408)
		(layer "In9.Cu")
		(net "PD_SPI_BMC_BT_CS0_N")
	)
	(segment
		(start 460.601822 -17.776444)
		(end 460.601822 -18.264378)
		(width 0.089408)
		(layer "In9.Cu")
		(net "PD_SPI_BMC_BT_CS0_N")
	)
	(segment
		(start 464.458304 -15.169896)
		(end 463.690208 -15.937992)
		(width 0.089408)
		(layer "In9.Cu")
		(net "PD_SPI_BMC_BT_CS0_N")
	)
	(segment
		(start 464.458304 -13.248894)
		(end 464.458304 -15.169896)
		(width 0.089408)
		(layer "In9.Cu")
		(net "PD_SPI_BMC_BT_CS0_N")
	)
	(segment
		(start 463.690208 -15.937992)
		(end 462.440274 -15.937992)
		(width 0.089408)
		(layer "In9.Cu")
		(net "PD_SPI_BMC_BT_CS0_N")
	)
	(segment
		(start 460.601822 -18.264378)
		(end 455.934572 -22.931628)
		(width 0.089408)
		(layer "In9.Cu")
		(net "PD_SPI_BMC_BT_CS0_N")
	)
	(segment
		(start 455.42581 -26.53538)
		(end 455.42581 -32.100266)
		(width 0.089408)
		(layer "In9.Cu")
		(net "PD_SPI_BMC_BT_CS0_N")
	)
	(segment
		(start 463.234024 -12.024614)
		(end 464.458304 -13.248894)
		(width 0.089408)
		(layer "In9.Cu")
		(net "PD_SPI_BMC_BT_CS0_N")
	)
	(segment
		(start 449.297044 -38.591998)
		(end 449.297044 -39.667942)
		(width 0.089408)
		(layer "In9.Cu")
		(net "PD_SPI_BMC_BT_CS0_N")
	)
	(segment
		(start 409.490164 -29.734764)
		(end 409.090114 -29.334714)
		(width 0.10795)
		(layer "F.Cu")
		(net "TP_RGMII2TXD2_GPIOU2")
	)
	(via
		(at 405.715978 -29.005022)
		(size 0.508)
		(drill 0.254)
		(layers "F.Cu" "B.Cu")
		(net "TP_RGMII2TXD2_GPIOU2")
	)
	(via
		(at 409.090114 -29.334714)
		(size 0.4572)
		(drill 0.2032)
		(layers "F.Cu" "B.Cu")
		(net "TP_RGMII2TXD2_GPIOU2")
	)
	(segment
		(start 405.715978 -29.005022)
		(end 405.384 -29.337)
		(width 0.089408)
		(layer "B.Cu")
		(net "TP_RGMII2TXD2_GPIOU2")
	)
	(segment
		(start 408.1018 -28.956)
		(end 408.7114 -28.956)
		(width 0.089408)
		(layer "B.Cu")
		(net "TP_RGMII2TXD2_GPIOU2")
	)
	(segment
		(start 406.7556 -28.7274)
		(end 405.9936 -28.7274)
		(width 0.089408)
		(layer "B.Cu")
		(net "TP_RGMII2TXD2_GPIOU2")
	)
	(segment
		(start 405.384 -29.337)
		(end 404.9141 -29.337)
		(width 0.089408)
		(layer "B.Cu")
		(net "TP_RGMII2TXD2_GPIOU2")
	)
	(segment
		(start 407.8732 -28.7274)
		(end 408.1018 -28.956)
		(width 0.089408)
		(layer "B.Cu")
		(net "TP_RGMII2TXD2_GPIOU2")
	)
	(segment
		(start 406.7556 -28.7274)
		(end 407.8732 -28.7274)
		(width 0.089408)
		(layer "B.Cu")
		(net "TP_RGMII2TXD2_GPIOU2")
	)
	(segment
		(start 408.7114 -28.956)
		(end 409.090114 -29.334714)
		(width 0.089408)
		(layer "B.Cu")
		(net "TP_RGMII2TXD2_GPIOU2")
	)
	(segment
		(start 405.9936 -28.7274)
		(end 405.715978 -29.005022)
		(width 0.089408)
		(layer "B.Cu")
		(net "TP_RGMII2TXD2_GPIOU2")
	)
	(segment
		(start 461.640428 -2.484374)
		(end 462.878678 -3.722624)
		(width 0.10795)
		(layer "F.Cu")
		(net "SMB_HOST_STBY_LVC3_SDA_R5")
	)
	(segment
		(start 462.878678 -3.722624)
		(end 462.878678 -4.386072)
		(width 0.10795)
		(layer "F.Cu")
		(net "SMB_HOST_STBY_LVC3_SDA_R5")
	)
	(segment
		(start 461.447642 -2.484374)
		(end 461.640428 -2.484374)
		(width 0.10795)
		(layer "F.Cu")
		(net "SMB_HOST_STBY_LVC3_SDA_R5")
	)
	(segment
		(start 462.026 -1.906016)
		(end 461.447642 -2.484374)
		(width 0.10795)
		(layer "F.Cu")
		(net "SMB_HOST_STBY_LVC3_SDA_R5")
	)
	(segment
		(start 462.026 -1.524)
		(end 462.026 -1.906016)
		(width 0.10795)
		(layer "F.Cu")
		(net "SMB_HOST_STBY_LVC3_SDA_R5")
	)
	(via
		(at 446.37833 -21.537676)
		(size 0.508)
		(drill 0.254)
		(layers "F.Cu" "B.Cu")
		(net "SMB_HOST_STBY_LVC3_SDA_R5")
	)
	(via
		(at 445.35598 -22.48408)
		(size 0.6604)
		(drill 0.3302)
		(layers "F.Cu" "B.Cu")
		(net "SMB_HOST_STBY_LVC3_SDA_R5")
	)
	(via
		(at 461.447642 -2.484374)
		(size 0.508)
		(drill 0.254)
		(layers "F.Cu" "B.Cu")
		(net "SMB_HOST_STBY_LVC3_SDA_R5")
	)
	(segment
		(start 445.35598 -22.48408)
		(end 445.570864 -22.269196)
		(width 0.10795)
		(layer "B.Cu")
		(net "SMB_HOST_STBY_LVC3_SDA_R5")
	)
	(segment
		(start 446.37833 -21.537676)
		(end 446.247266 -21.66874)
		(width 0.10795)
		(layer "B.Cu")
		(net "SMB_HOST_STBY_LVC3_SDA_R5")
	)
	(segment
		(start 446.247266 -21.66874)
		(end 446.247266 -22.269196)
		(width 0.10795)
		(layer "B.Cu")
		(net "SMB_HOST_STBY_LVC3_SDA_R5")
	)
	(segment
		(start 445.570864 -22.269196)
		(end 446.247266 -22.269196)
		(width 0.10795)
		(layer "B.Cu")
		(net "SMB_HOST_STBY_LVC3_SDA_R5")
	)
	(segment
		(start 445.938148 -21.977858)
		(end 446.37833 -21.537676)
		(width 0.089408)
		(layer "In9.Cu")
		(net "SMB_HOST_STBY_LVC3_SDA_R5")
	)
	(segment
		(start 459.936342 -10.48893)
		(end 459.936342 -10.646918)
		(width 0.089408)
		(layer "In9.Cu")
		(net "SMB_HOST_STBY_LVC3_SDA_R5")
	)
	(segment
		(start 456.276202 -18.6817)
		(end 454.71715 -18.6817)
		(width 0.089408)
		(layer "In9.Cu")
		(net "SMB_HOST_STBY_LVC3_SDA_R5")
	)
	(segment
		(start 449.96735 -23.4315)
		(end 446.405254 -23.4315)
		(width 0.089408)
		(layer "In9.Cu")
		(net "SMB_HOST_STBY_LVC3_SDA_R5")
	)
	(segment
		(start 459.9178 -3.309874)
		(end 459.9178 -6.13918)
		(width 0.089408)
		(layer "In9.Cu")
		(net "SMB_HOST_STBY_LVC3_SDA_R5")
	)
	(segment
		(start 459.936088 -8.329168)
		(end 459.936088 -10.488676)
		(width 0.089408)
		(layer "In9.Cu")
		(net "SMB_HOST_STBY_LVC3_SDA_R5")
	)
	(segment
		(start 456.94092 -14.825218)
		(end 457.2508 -15.135098)
		(width 0.089408)
		(layer "In9.Cu")
		(net "SMB_HOST_STBY_LVC3_SDA_R5")
	)
	(segment
		(start 454.71715 -18.6817)
		(end 449.96735 -23.4315)
		(width 0.089408)
		(layer "In9.Cu")
		(net "SMB_HOST_STBY_LVC3_SDA_R5")
	)
	(segment
		(start 460.7433 -2.484374)
		(end 459.9178 -3.309874)
		(width 0.089408)
		(layer "In9.Cu")
		(net "SMB_HOST_STBY_LVC3_SDA_R5")
	)
	(segment
		(start 446.405254 -23.4315)
		(end 445.938148 -22.964394)
		(width 0.089408)
		(layer "In9.Cu")
		(net "SMB_HOST_STBY_LVC3_SDA_R5")
	)
	(segment
		(start 456.94092 -13.64234)
		(end 456.94092 -14.825218)
		(width 0.089408)
		(layer "In9.Cu")
		(net "SMB_HOST_STBY_LVC3_SDA_R5")
	)
	(segment
		(start 460.2861 -7.979156)
		(end 459.936088 -8.329168)
		(width 0.089408)
		(layer "In9.Cu")
		(net "SMB_HOST_STBY_LVC3_SDA_R5")
	)
	(segment
		(start 461.447642 -2.484374)
		(end 460.7433 -2.484374)
		(width 0.089408)
		(layer "In9.Cu")
		(net "SMB_HOST_STBY_LVC3_SDA_R5")
	)
	(segment
		(start 457.2508 -15.135098)
		(end 457.2508 -17.707102)
		(width 0.089408)
		(layer "In9.Cu")
		(net "SMB_HOST_STBY_LVC3_SDA_R5")
	)
	(segment
		(start 445.938148 -22.964394)
		(end 445.938148 -21.977858)
		(width 0.089408)
		(layer "In9.Cu")
		(net "SMB_HOST_STBY_LVC3_SDA_R5")
	)
	(segment
		(start 460.2861 -6.50748)
		(end 460.2861 -7.979156)
		(width 0.089408)
		(layer "In9.Cu")
		(net "SMB_HOST_STBY_LVC3_SDA_R5")
	)
	(segment
		(start 459.936342 -10.646918)
		(end 456.94092 -13.64234)
		(width 0.089408)
		(layer "In9.Cu")
		(net "SMB_HOST_STBY_LVC3_SDA_R5")
	)
	(segment
		(start 457.2508 -17.707102)
		(end 456.276202 -18.6817)
		(width 0.089408)
		(layer "In9.Cu")
		(net "SMB_HOST_STBY_LVC3_SDA_R5")
	)
	(segment
		(start 459.9178 -6.13918)
		(end 460.2861 -6.50748)
		(width 0.089408)
		(layer "In9.Cu")
		(net "SMB_HOST_STBY_LVC3_SDA_R5")
	)
	(segment
		(start 459.936088 -10.488676)
		(end 459.936342 -10.48893)
		(width 0.089408)
		(layer "In9.Cu")
		(net "SMB_HOST_STBY_LVC3_SDA_R5")
	)
	(segment
		(start 446.474088 -22.904196)
		(end 446.093596 -22.904196)
		(width 0.10795)
		(layer "F.Cu")
		(net "SMB_HOST_STBY_LVC3_SCL_R5")
	)
	(segment
		(start 445.8716 -22.6822)
		(end 445.8716 -22.2758)
		(width 0.10795)
		(layer "F.Cu")
		(net "SMB_HOST_STBY_LVC3_SCL_R5")
	)
	(segment
		(start 461.648556 -2.9718)
		(end 462.078578 -3.401822)
		(width 0.10795)
		(layer "F.Cu")
		(net "SMB_HOST_STBY_LVC3_SCL_R5")
	)
	(segment
		(start 459.232 -2.209038)
		(end 459.385162 -2.3622)
		(width 0.10795)
		(layer "F.Cu")
		(net "SMB_HOST_STBY_LVC3_SCL_R5")
	)
	(segment
		(start 462.078578 -3.401822)
		(end 462.078578 -4.386072)
		(width 0.10795)
		(layer "F.Cu")
		(net "SMB_HOST_STBY_LVC3_SCL_R5")
	)
	(segment
		(start 459.385162 -2.3622)
		(end 459.639162 -2.6162)
		(width 0.10795)
		(layer "F.Cu")
		(net "SMB_HOST_STBY_LVC3_SCL_R5")
	)
	(segment
		(start 446.093596 -22.904196)
		(end 445.8716 -22.6822)
		(width 0.10795)
		(layer "F.Cu")
		(net "SMB_HOST_STBY_LVC3_SCL_R5")
	)
	(segment
		(start 459.232 -1.524)
		(end 459.232 -2.209038)
		(width 0.10795)
		(layer "F.Cu")
		(net "SMB_HOST_STBY_LVC3_SCL_R5")
	)
	(segment
		(start 459.639162 -2.6162)
		(end 460.8576 -2.6162)
		(width 0.10795)
		(layer "F.Cu")
		(net "SMB_HOST_STBY_LVC3_SCL_R5")
	)
	(segment
		(start 461.2132 -2.9718)
		(end 461.648556 -2.9718)
		(width 0.10795)
		(layer "F.Cu")
		(net "SMB_HOST_STBY_LVC3_SCL_R5")
	)
	(segment
		(start 460.8576 -2.6162)
		(end 461.2132 -2.9718)
		(width 0.10795)
		(layer "F.Cu")
		(net "SMB_HOST_STBY_LVC3_SCL_R5")
	)
	(via
		(at 445.8716 -22.2758)
		(size 0.762)
		(drill 0.381)
		(layers "F.Cu" "B.Cu")
		(net "SMB_HOST_STBY_LVC3_SCL_R5")
	)
	(via
		(at 459.385162 -2.3622)
		(size 0.508)
		(drill 0.254)
		(layers "F.Cu" "B.Cu")
		(net "SMB_HOST_STBY_LVC3_SCL_R5")
	)
	(via
		(at 446.474088 -22.904196)
		(size 0.508)
		(drill 0.254)
		(layers "F.Cu" "B.Cu")
		(net "SMB_HOST_STBY_LVC3_SCL_R5")
	)
	(segment
		(start 446.268094 -23.642574)
		(end 446.268094 -23.11019)
		(width 0.10795)
		(layer "B.Cu")
		(net "SMB_HOST_STBY_LVC3_SCL_R5")
	)
	(segment
		(start 446.268094 -23.11019)
		(end 446.474088 -22.904196)
		(width 0.10795)
		(layer "B.Cu")
		(net "SMB_HOST_STBY_LVC3_SCL_R5")
	)
	(segment
		(start 446.810384 -23.240492)
		(end 449.888102 -23.240492)
		(width 0.089408)
		(layer "In9.Cu")
		(net "SMB_HOST_STBY_LVC3_SCL_R5")
	)
	(segment
		(start 456.749912 -13.563092)
		(end 459.74508 -10.567924)
		(width 0.089408)
		(layer "In9.Cu")
		(net "SMB_HOST_STBY_LVC3_SCL_R5")
	)
	(segment
		(start 446.474088 -22.904196)
		(end 446.810384 -23.240492)
		(width 0.089408)
		(layer "In9.Cu")
		(net "SMB_HOST_STBY_LVC3_SCL_R5")
	)
	(segment
		(start 454.637902 -18.490692)
		(end 456.196954 -18.490692)
		(width 0.089408)
		(layer "In9.Cu")
		(net "SMB_HOST_STBY_LVC3_SCL_R5")
	)
	(segment
		(start 457.059792 -15.214346)
		(end 456.749912 -14.904466)
		(width 0.089408)
		(layer "In9.Cu")
		(net "SMB_HOST_STBY_LVC3_SCL_R5")
	)
	(segment
		(start 457.059792 -17.627854)
		(end 457.059792 -15.214346)
		(width 0.089408)
		(layer "In9.Cu")
		(net "SMB_HOST_STBY_LVC3_SCL_R5")
	)
	(segment
		(start 459.033626 -3.357626)
		(end 459.033626 -2.713736)
		(width 0.089408)
		(layer "In9.Cu")
		(net "SMB_HOST_STBY_LVC3_SCL_R5")
	)
	(segment
		(start 459.6892 -6.180836)
		(end 459.6892 -4.0132)
		(width 0.089408)
		(layer "In9.Cu")
		(net "SMB_HOST_STBY_LVC3_SCL_R5")
	)
	(segment
		(start 460.095092 -7.899908)
		(end 460.095092 -6.586728)
		(width 0.089408)
		(layer "In9.Cu")
		(net "SMB_HOST_STBY_LVC3_SCL_R5")
	)
	(segment
		(start 459.033626 -2.713736)
		(end 459.385162 -2.3622)
		(width 0.089408)
		(layer "In9.Cu")
		(net "SMB_HOST_STBY_LVC3_SCL_R5")
	)
	(segment
		(start 456.749912 -14.904466)
		(end 456.749912 -13.563092)
		(width 0.089408)
		(layer "In9.Cu")
		(net "SMB_HOST_STBY_LVC3_SCL_R5")
	)
	(segment
		(start 459.6892 -4.0132)
		(end 459.033626 -3.357626)
		(width 0.089408)
		(layer "In9.Cu")
		(net "SMB_HOST_STBY_LVC3_SCL_R5")
	)
	(segment
		(start 459.74508 -10.567924)
		(end 459.74508 -8.24992)
		(width 0.089408)
		(layer "In9.Cu")
		(net "SMB_HOST_STBY_LVC3_SCL_R5")
	)
	(segment
		(start 459.74508 -8.24992)
		(end 460.095092 -7.899908)
		(width 0.089408)
		(layer "In9.Cu")
		(net "SMB_HOST_STBY_LVC3_SCL_R5")
	)
	(segment
		(start 449.888102 -23.240492)
		(end 454.637902 -18.490692)
		(width 0.089408)
		(layer "In9.Cu")
		(net "SMB_HOST_STBY_LVC3_SCL_R5")
	)
	(segment
		(start 456.196954 -18.490692)
		(end 457.059792 -17.627854)
		(width 0.089408)
		(layer "In9.Cu")
		(net "SMB_HOST_STBY_LVC3_SCL_R5")
	)
	(segment
		(start 460.095092 -6.586728)
		(end 459.6892 -6.180836)
		(width 0.089408)
		(layer "In9.Cu")
		(net "SMB_HOST_STBY_LVC3_SCL_R5")
	)
	(segment
		(start 420.69004 -40.13454)
		(end 420.290244 -39.734744)
		(width 0.089408)
		(layer "F.Cu")
		(net "RST_BMC_EXTRST_N")
	)
	(via
		(at 420.290244 -39.734744)
		(size 0.4572)
		(drill 0.2032)
		(layers "F.Cu" "B.Cu")
		(net "RST_BMC_EXTRST_N")
	)
	(via
		(at 439.7629 -23.40356)
		(size 0.508)
		(drill 0.254)
		(layers "F.Cu" "B.Cu")
		(net "RST_BMC_EXTRST_N")
	)
	(via
		(at 438.87644 -23.85568)
		(size 0.6604)
		(drill 0.3302)
		(layers "F.Cu" "B.Cu")
		(net "RST_BMC_EXTRST_N")
	)
	(segment
		(start 439.31078 -23.85568)
		(end 439.7629 -23.40356)
		(width 0.10795)
		(layer "B.Cu")
		(net "RST_BMC_EXTRST_N")
	)
	(segment
		(start 436.8165 -22.352)
		(end 437.159654 -22.352)
		(width 0.10795)
		(layer "B.Cu")
		(net "RST_BMC_EXTRST_N")
	)
	(segment
		(start 437.814974 -23.15972)
		(end 437.814974 -22.6314)
		(width 0.10795)
		(layer "B.Cu")
		(net "RST_BMC_EXTRST_N")
	)
	(segment
		(start 438.510934 -23.85568)
		(end 437.814974 -23.15972)
		(width 0.10795)
		(layer "B.Cu")
		(net "RST_BMC_EXTRST_N")
	)
	(segment
		(start 437.159654 -22.352)
		(end 437.439054 -22.6314)
		(width 0.10795)
		(layer "B.Cu")
		(net "RST_BMC_EXTRST_N")
	)
	(segment
		(start 437.439054 -22.6314)
		(end 437.814974 -22.6314)
		(width 0.10795)
		(layer "B.Cu")
		(net "RST_BMC_EXTRST_N")
	)
	(segment
		(start 438.87644 -23.85568)
		(end 438.510934 -23.85568)
		(width 0.10795)
		(layer "B.Cu")
		(net "RST_BMC_EXTRST_N")
	)
	(segment
		(start 438.87644 -23.85568)
		(end 439.31078 -23.85568)
		(width 0.10795)
		(layer "B.Cu")
		(net "RST_BMC_EXTRST_N")
	)
	(segment
		(start 434.152802 -21.22043)
		(end 434.683408 -21.751036)
		(width 0.089408)
		(layer "In9.Cu")
		(net "RST_BMC_EXTRST_N")
	)
	(segment
		(start 427.41596 -23.102316)
		(end 432.524916 -23.102316)
		(width 0.089408)
		(layer "In9.Cu")
		(net "RST_BMC_EXTRST_N")
	)
	(segment
		(start 435.841394 -23.40356)
		(end 439.7629 -23.40356)
		(width 0.089408)
		(layer "In9.Cu")
		(net "RST_BMC_EXTRST_N")
	)
	(segment
		(start 423.886376 -30.229048)
		(end 423.886376 -28.44292)
		(width 0.089408)
		(layer "In9.Cu")
		(net "RST_BMC_EXTRST_N")
	)
	(segment
		(start 426.135038 -24.282908)
		(end 426.447204 -23.970742)
		(width 0.089408)
		(layer "In9.Cu")
		(net "RST_BMC_EXTRST_N")
	)
	(segment
		(start 420.290244 -39.734744)
		(end 419.08984 -38.53434)
		(width 0.089408)
		(layer "In9.Cu")
		(net "RST_BMC_EXTRST_N")
	)
	(segment
		(start 418.248592 -38.218618)
		(end 418.248592 -33.30067)
		(width 0.089408)
		(layer "In9.Cu")
		(net "RST_BMC_EXTRST_N")
	)
	(segment
		(start 432.524916 -23.102316)
		(end 432.69535 -23.27275)
		(width 0.089408)
		(layer "In9.Cu")
		(net "RST_BMC_EXTRST_N")
	)
	(segment
		(start 433.191158 -23.27275)
		(end 433.578 -22.885908)
		(width 0.089408)
		(layer "In9.Cu")
		(net "RST_BMC_EXTRST_N")
	)
	(segment
		(start 418.564314 -38.53434)
		(end 418.248592 -38.218618)
		(width 0.089408)
		(layer "In9.Cu")
		(net "RST_BMC_EXTRST_N")
	)
	(segment
		(start 432.69535 -23.27275)
		(end 433.191158 -23.27275)
		(width 0.089408)
		(layer "In9.Cu")
		(net "RST_BMC_EXTRST_N")
	)
	(segment
		(start 423.59072 -30.524704)
		(end 423.886376 -30.229048)
		(width 0.089408)
		(layer "In9.Cu")
		(net "RST_BMC_EXTRST_N")
	)
	(segment
		(start 433.570126 -22.33803)
		(end 433.578 -22.330156)
		(width 0.089408)
		(layer "In9.Cu")
		(net "RST_BMC_EXTRST_N")
	)
	(segment
		(start 426.135038 -24.383238)
		(end 426.135038 -24.282908)
		(width 0.089408)
		(layer "In9.Cu")
		(net "RST_BMC_EXTRST_N")
	)
	(segment
		(start 433.578 -21.463508)
		(end 433.821078 -21.22043)
		(width 0.089408)
		(layer "In9.Cu")
		(net "RST_BMC_EXTRST_N")
	)
	(segment
		(start 433.578 -22.885908)
		(end 433.578 -22.719792)
		(width 0.089408)
		(layer "In9.Cu")
		(net "RST_BMC_EXTRST_N")
	)
	(segment
		(start 423.886376 -28.44292)
		(end 424.018202 -28.311094)
		(width 0.089408)
		(layer "In9.Cu")
		(net "RST_BMC_EXTRST_N")
	)
	(segment
		(start 419.08984 -38.53434)
		(end 418.564314 -38.53434)
		(width 0.089408)
		(layer "In9.Cu")
		(net "RST_BMC_EXTRST_N")
	)
	(segment
		(start 418.507418 -33.041844)
		(end 418.507418 -31.11754)
		(width 0.089408)
		(layer "In9.Cu")
		(net "RST_BMC_EXTRST_N")
	)
	(segment
		(start 424.018202 -25.907492)
		(end 425.288202 -24.637492)
		(width 0.089408)
		(layer "In9.Cu")
		(net "RST_BMC_EXTRST_N")
	)
	(segment
		(start 425.880784 -24.637492)
		(end 426.135038 -24.383238)
		(width 0.089408)
		(layer "In9.Cu")
		(net "RST_BMC_EXTRST_N")
	)
	(segment
		(start 434.683408 -22.245574)
		(end 435.841394 -23.40356)
		(width 0.089408)
		(layer "In9.Cu")
		(net "RST_BMC_EXTRST_N")
	)
	(segment
		(start 424.018202 -28.311094)
		(end 424.018202 -25.907492)
		(width 0.089408)
		(layer "In9.Cu")
		(net "RST_BMC_EXTRST_N")
	)
	(segment
		(start 418.507418 -31.11754)
		(end 419.100254 -30.524704)
		(width 0.089408)
		(layer "In9.Cu")
		(net "RST_BMC_EXTRST_N")
	)
	(segment
		(start 418.248592 -33.30067)
		(end 418.507418 -33.041844)
		(width 0.089408)
		(layer "In9.Cu")
		(net "RST_BMC_EXTRST_N")
	)
	(segment
		(start 426.547534 -23.970742)
		(end 427.41596 -23.102316)
		(width 0.089408)
		(layer "In9.Cu")
		(net "RST_BMC_EXTRST_N")
	)
	(segment
		(start 434.683408 -21.751036)
		(end 434.683408 -22.245574)
		(width 0.089408)
		(layer "In9.Cu")
		(net "RST_BMC_EXTRST_N")
	)
	(segment
		(start 425.288202 -24.637492)
		(end 425.880784 -24.637492)
		(width 0.089408)
		(layer "In9.Cu")
		(net "RST_BMC_EXTRST_N")
	)
	(segment
		(start 426.447204 -23.970742)
		(end 426.547534 -23.970742)
		(width 0.089408)
		(layer "In9.Cu")
		(net "RST_BMC_EXTRST_N")
	)
	(segment
		(start 419.100254 -30.524704)
		(end 423.59072 -30.524704)
		(width 0.089408)
		(layer "In9.Cu")
		(net "RST_BMC_EXTRST_N")
	)
	(segment
		(start 433.578 -22.330156)
		(end 433.578 -21.463508)
		(width 0.089408)
		(layer "In9.Cu")
		(net "RST_BMC_EXTRST_N")
	)
	(segment
		(start 433.570126 -22.711918)
		(end 433.570126 -22.33803)
		(width 0.089408)
		(layer "In9.Cu")
		(net "RST_BMC_EXTRST_N")
	)
	(segment
		(start 433.821078 -21.22043)
		(end 434.152802 -21.22043)
		(width 0.089408)
		(layer "In9.Cu")
		(net "RST_BMC_EXTRST_N")
	)
	(segment
		(start 433.578 -22.719792)
		(end 433.570126 -22.711918)
		(width 0.089408)
		(layer "In9.Cu")
		(net "RST_BMC_EXTRST_N")
	)
	(segment
		(start 408.690064 -32.934656)
		(end 409.090114 -32.534606)
		(width 0.10795)
		(layer "F.Cu")
		(net "PU_JTAG_BMC_RTCK")
	)
	(via
		(at 409.474162 -33.50768)
		(size 0.6604)
		(drill 0.3302)
		(layers "F.Cu" "B.Cu")
		(net "PU_JTAG_BMC_RTCK")
	)
	(via
		(at 409.090114 -32.534606)
		(size 0.4572)
		(drill 0.2032)
		(layers "F.Cu" "B.Cu")
		(net "PU_JTAG_BMC_RTCK")
	)
	(segment
		(start 409.349702 -35.350704)
		(end 409.474162 -35.226244)
		(width 0.10795)
		(layer "B.Cu")
		(net "PU_JTAG_BMC_RTCK")
	)
	(segment
		(start 409.090114 -33.121854)
		(end 409.090114 -32.534606)
		(width 0.10795)
		(layer "B.Cu")
		(net "PU_JTAG_BMC_RTCK")
	)
	(segment
		(start 408.93111 -35.350704)
		(end 409.349702 -35.350704)
		(width 0.10795)
		(layer "B.Cu")
		(net "PU_JTAG_BMC_RTCK")
	)
	(segment
		(start 407.091896 -36.2458)
		(end 408.036014 -36.2458)
		(width 0.10795)
		(layer "B.Cu")
		(net "PU_JTAG_BMC_RTCK")
	)
	(segment
		(start 409.474162 -35.226244)
		(end 409.474162 -33.50768)
		(width 0.10795)
		(layer "B.Cu")
		(net "PU_JTAG_BMC_RTCK")
	)
	(segment
		(start 405.14524 -35.7505)
		(end 406.596596 -35.7505)
		(width 0.10795)
		(layer "B.Cu")
		(net "PU_JTAG_BMC_RTCK")
	)
	(segment
		(start 409.474162 -33.505902)
		(end 409.090114 -33.121854)
		(width 0.10795)
		(layer "B.Cu")
		(net "PU_JTAG_BMC_RTCK")
	)
	(segment
		(start 402.647658 -36.491164)
		(end 404.404576 -36.491164)
		(width 0.10795)
		(layer "B.Cu")
		(net "PU_JTAG_BMC_RTCK")
	)
	(segment
		(start 406.596596 -35.7505)
		(end 407.091896 -36.2458)
		(width 0.10795)
		(layer "B.Cu")
		(net "PU_JTAG_BMC_RTCK")
	)
	(segment
		(start 402.488146 -36.331652)
		(end 402.647658 -36.491164)
		(width 0.10795)
		(layer "B.Cu")
		(net "PU_JTAG_BMC_RTCK")
	)
	(segment
		(start 409.474162 -33.50768)
		(end 409.474162 -33.505902)
		(width 0.10795)
		(layer "B.Cu")
		(net "PU_JTAG_BMC_RTCK")
	)
	(segment
		(start 404.404576 -36.491164)
		(end 405.14524 -35.7505)
		(width 0.10795)
		(layer "B.Cu")
		(net "PU_JTAG_BMC_RTCK")
	)
	(segment
		(start 408.036014 -36.2458)
		(end 408.93111 -35.350704)
		(width 0.10795)
		(layer "B.Cu")
		(net "PU_JTAG_BMC_RTCK")
	)
	(segment
		(start 405.44369 -43.239182)
		(end 405.826976 -42.855896)
		(width 0.089408)
		(layer "F.Cu")
		(net "RST_SYSTEM_BTN_R_N")
	)
	(segment
		(start 405.44369 -43.431714)
		(end 405.44369 -43.239182)
		(width 0.089408)
		(layer "F.Cu")
		(net "RST_SYSTEM_BTN_R_N")
	)
	(segment
		(start 407.365454 -42.10177)
		(end 407.732484 -41.73474)
		(width 0.089408)
		(layer "F.Cu")
		(net "RST_SYSTEM_BTN_R_N")
	)
	(segment
		(start 407.732484 -41.73474)
		(end 407.890218 -41.73474)
		(width 0.089408)
		(layer "F.Cu")
		(net "RST_SYSTEM_BTN_R_N")
	)
	(segment
		(start 405.826976 -42.454322)
		(end 406.179528 -42.10177)
		(width 0.089408)
		(layer "F.Cu")
		(net "RST_SYSTEM_BTN_R_N")
	)
	(segment
		(start 404.4823 -44.69384)
		(end 404.4823 -44.393104)
		(width 0.254)
		(layer "F.Cu")
		(net "RST_SYSTEM_BTN_R_N")
	)
	(segment
		(start 404.4823 -44.393104)
		(end 405.140668 -43.734736)
		(width 0.254)
		(layer "F.Cu")
		(net "RST_SYSTEM_BTN_R_N")
	)
	(segment
		(start 406.179528 -42.10177)
		(end 407.365454 -42.10177)
		(width 0.089408)
		(layer "F.Cu")
		(net "RST_SYSTEM_BTN_R_N")
	)
	(segment
		(start 405.826976 -42.855896)
		(end 405.826976 -42.454322)
		(width 0.089408)
		(layer "F.Cu")
		(net "RST_SYSTEM_BTN_R_N")
	)
	(segment
		(start 405.140668 -43.734736)
		(end 405.44369 -43.431714)
		(width 0.089408)
		(layer "F.Cu")
		(net "RST_SYSTEM_BTN_R_N")
	)
	(via
		(at 404.4823 -44.69384)
		(size 0.762)
		(drill 0.381)
		(layers "F.Cu" "B.Cu")
		(net "RST_SYSTEM_BTN_R_N")
	)
	(via
		(at 453.517 -42.672)
		(size 0.508)
		(drill 0.254)
		(layers "F.Cu" "B.Cu")
		(net "RST_SYSTEM_BTN_R_N")
	)
	(via
		(at 405.140668 -43.734736)
		(size 0.4572)
		(drill 0.2032)
		(layers "F.Cu" "B.Cu")
		(net "RST_SYSTEM_BTN_R_N")
	)
	(segment
		(start 454.4822 -42.545)
		(end 454.3552 -42.672)
		(width 0.10795)
		(layer "B.Cu")
		(net "RST_SYSTEM_BTN_R_N")
	)
	(segment
		(start 454.3552 -42.672)
		(end 453.517 -42.672)
		(width 0.10795)
		(layer "B.Cu")
		(net "RST_SYSTEM_BTN_R_N")
	)
	(segment
		(start 423.300652 -43.99788)
		(end 423.300652 -43.686984)
		(width 0.089408)
		(layer "In4.Cu")
		(net "RST_SYSTEM_BTN_R_N")
	)
	(segment
		(start 423.28719 -43.354244)
		(end 424.354498 -42.286936)
		(width 0.089408)
		(layer "In4.Cu")
		(net "RST_SYSTEM_BTN_R_N")
	)
	(segment
		(start 430.161192 -40.63746)
		(end 430.70272 -40.63746)
		(width 0.0889)
		(layer "In4.Cu")
		(net "RST_SYSTEM_BTN_R_N")
	)
	(segment
		(start 453.4535 -42.6085)
		(end 453.517 -42.672)
		(width 0.089408)
		(layer "In4.Cu")
		(net "RST_SYSTEM_BTN_R_N")
	)
	(segment
		(start 413.286194 -44.910502)
		(end 418.69614 -44.910502)
		(width 0.089408)
		(layer "In4.Cu")
		(net "RST_SYSTEM_BTN_R_N")
	)
	(segment
		(start 405.140668 -43.734736)
		(end 405.515318 -43.360086)
		(width 0.089408)
		(layer "In4.Cu")
		(net "RST_SYSTEM_BTN_R_N")
	)
	(segment
		(start 423.28719 -43.673522)
		(end 423.28719 -43.354244)
		(width 0.089408)
		(layer "In4.Cu")
		(net "RST_SYSTEM_BTN_R_N")
	)
	(segment
		(start 434.78958 -41.690036)
		(end 452.027036 -41.690036)
		(width 0.089408)
		(layer "In4.Cu")
		(net "RST_SYSTEM_BTN_R_N")
	)
	(segment
		(start 434.392832 -41.293288)
		(end 434.78958 -41.690036)
		(width 0.089408)
		(layer "In4.Cu")
		(net "RST_SYSTEM_BTN_R_N")
	)
	(segment
		(start 428.215298 -40.23614)
		(end 429.759872 -40.23614)
		(width 0.0889)
		(layer "In4.Cu")
		(net "RST_SYSTEM_BTN_R_N")
	)
	(segment
		(start 452.027036 -41.690036)
		(end 452.9455 -42.6085)
		(width 0.089408)
		(layer "In4.Cu")
		(net "RST_SYSTEM_BTN_R_N")
	)
	(segment
		(start 408.46248 -46.302676)
		(end 409.509468 -46.302676)
		(width 0.089408)
		(layer "In4.Cu")
		(net "RST_SYSTEM_BTN_R_N")
	)
	(segment
		(start 424.354498 -42.286936)
		(end 426.164502 -42.286936)
		(width 0.089408)
		(layer "In4.Cu")
		(net "RST_SYSTEM_BTN_R_N")
	)
	(segment
		(start 408.238198 -46.078394)
		(end 408.46248 -46.302676)
		(width 0.089408)
		(layer "In4.Cu")
		(net "RST_SYSTEM_BTN_R_N")
	)
	(segment
		(start 406.315418 -43.719242)
		(end 406.315418 -43.890438)
		(width 0.089408)
		(layer "In4.Cu")
		(net "RST_SYSTEM_BTN_R_N")
	)
	(segment
		(start 429.759872 -40.23614)
		(end 430.161192 -40.63746)
		(width 0.0889)
		(layer "In4.Cu")
		(net "RST_SYSTEM_BTN_R_N")
	)
	(segment
		(start 409.509468 -46.302676)
		(end 410.269436 -45.542708)
		(width 0.089408)
		(layer "In4.Cu")
		(net "RST_SYSTEM_BTN_R_N")
	)
	(segment
		(start 428.134018 -40.31742)
		(end 428.215298 -40.23614)
		(width 0.0889)
		(layer "In4.Cu")
		(net "RST_SYSTEM_BTN_R_N")
	)
	(segment
		(start 406.315418 -43.890438)
		(end 406.624536 -44.199556)
		(width 0.089408)
		(layer "In4.Cu")
		(net "RST_SYSTEM_BTN_R_N")
	)
	(segment
		(start 406.624536 -44.199556)
		(end 406.97785 -44.199556)
		(width 0.089408)
		(layer "In4.Cu")
		(net "RST_SYSTEM_BTN_R_N")
	)
	(segment
		(start 431.795936 -41.730676)
		(end 432.972718 -41.730676)
		(width 0.089408)
		(layer "In4.Cu")
		(net "RST_SYSTEM_BTN_R_N")
	)
	(segment
		(start 452.9455 -42.6085)
		(end 453.4535 -42.6085)
		(width 0.089408)
		(layer "In4.Cu")
		(net "RST_SYSTEM_BTN_R_N")
	)
	(segment
		(start 430.70272 -40.63746)
		(end 431.795936 -41.730676)
		(width 0.089408)
		(layer "In4.Cu")
		(net "RST_SYSTEM_BTN_R_N")
	)
	(segment
		(start 423.08145 -44.217082)
		(end 423.300652 -43.99788)
		(width 0.089408)
		(layer "In4.Cu")
		(net "RST_SYSTEM_BTN_R_N")
	)
	(segment
		(start 405.515318 -43.360086)
		(end 405.956262 -43.360086)
		(width 0.089408)
		(layer "In4.Cu")
		(net "RST_SYSTEM_BTN_R_N")
	)
	(segment
		(start 406.97785 -44.199556)
		(end 408.238198 -45.459904)
		(width 0.089408)
		(layer "In4.Cu")
		(net "RST_SYSTEM_BTN_R_N")
	)
	(segment
		(start 426.164502 -42.286936)
		(end 428.134018 -40.31742)
		(width 0.089408)
		(layer "In4.Cu")
		(net "RST_SYSTEM_BTN_R_N")
	)
	(segment
		(start 410.269436 -45.542708)
		(end 412.653988 -45.542708)
		(width 0.089408)
		(layer "In4.Cu")
		(net "RST_SYSTEM_BTN_R_N")
	)
	(segment
		(start 419.038532 -44.56811)
		(end 419.965886 -44.56811)
		(width 0.089408)
		(layer "In4.Cu")
		(net "RST_SYSTEM_BTN_R_N")
	)
	(segment
		(start 423.300652 -43.686984)
		(end 423.28719 -43.673522)
		(width 0.089408)
		(layer "In4.Cu")
		(net "RST_SYSTEM_BTN_R_N")
	)
	(segment
		(start 412.653988 -45.542708)
		(end 413.286194 -44.910502)
		(width 0.089408)
		(layer "In4.Cu")
		(net "RST_SYSTEM_BTN_R_N")
	)
	(segment
		(start 433.410106 -41.293288)
		(end 434.392832 -41.293288)
		(width 0.089408)
		(layer "In4.Cu")
		(net "RST_SYSTEM_BTN_R_N")
	)
	(segment
		(start 432.972718 -41.730676)
		(end 433.410106 -41.293288)
		(width 0.089408)
		(layer "In4.Cu")
		(net "RST_SYSTEM_BTN_R_N")
	)
	(segment
		(start 418.69614 -44.910502)
		(end 419.038532 -44.56811)
		(width 0.089408)
		(layer "In4.Cu")
		(net "RST_SYSTEM_BTN_R_N")
	)
	(segment
		(start 405.956262 -43.360086)
		(end 406.315418 -43.719242)
		(width 0.089408)
		(layer "In4.Cu")
		(net "RST_SYSTEM_BTN_R_N")
	)
	(segment
		(start 419.965886 -44.56811)
		(end 420.316914 -44.217082)
		(width 0.089408)
		(layer "In4.Cu")
		(net "RST_SYSTEM_BTN_R_N")
	)
	(segment
		(start 408.238198 -45.459904)
		(end 408.238198 -46.078394)
		(width 0.089408)
		(layer "In4.Cu")
		(net "RST_SYSTEM_BTN_R_N")
	)
	(segment
		(start 420.316914 -44.217082)
		(end 423.08145 -44.217082)
		(width 0.089408)
		(layer "In4.Cu")
		(net "RST_SYSTEM_BTN_R_N")
	)
	(segment
		(start 368.344704 -72.295004)
		(end 367.945162 -71.895462)
		(width 0.10795)
		(layer "F.Cu")
		(net "RST_BMC_SYSRST_BTN_OUT_B_R1_N")
	)
	(segment
		(start 368.344958 -72.295004)
		(end 368.344704 -72.295004)
		(width 0.10795)
		(layer "F.Cu")
		(net "RST_BMC_SYSRST_BTN_OUT_B_R1_N")
	)
	(via
		(at 398.36471 -62.931294)
		(size 0.508)
		(drill 0.254)
		(layers "F.Cu" "B.Cu")
		(net "RST_BMC_SYSRST_BTN_OUT_B_R1_N")
	)
	(via
		(at 396.9766 -61.8744)
		(size 0.6604)
		(drill 0.3302)
		(layers "F.Cu" "B.Cu")
		(net "RST_BMC_SYSRST_BTN_OUT_B_R1_N")
	)
	(via
		(at 367.945162 -71.895462)
		(size 0.4572)
		(drill 0.2032)
		(layers "F.Cu" "B.Cu")
		(net "RST_BMC_SYSRST_BTN_OUT_B_R1_N")
	)
	(segment
		(start 396.9766 -61.8744)
		(end 396.997174 -61.894974)
		(width 0.10795)
		(layer "B.Cu")
		(net "RST_BMC_SYSRST_BTN_OUT_B_R1_N")
	)
	(segment
		(start 398.36471 -62.838584)
		(end 397.971518 -62.445392)
		(width 0.10795)
		(layer "B.Cu")
		(net "RST_BMC_SYSRST_BTN_OUT_B_R1_N")
	)
	(segment
		(start 397.971518 -62.445392)
		(end 397.971518 -61.894974)
		(width 0.10795)
		(layer "B.Cu")
		(net "RST_BMC_SYSRST_BTN_OUT_B_R1_N")
	)
	(segment
		(start 398.36471 -62.931294)
		(end 398.36471 -62.838584)
		(width 0.10795)
		(layer "B.Cu")
		(net "RST_BMC_SYSRST_BTN_OUT_B_R1_N")
	)
	(segment
		(start 396.997174 -61.894974)
		(end 397.971518 -61.894974)
		(width 0.10795)
		(layer "B.Cu")
		(net "RST_BMC_SYSRST_BTN_OUT_B_R1_N")
	)
	(segment
		(start 389.35406 -64.059816)
		(end 389.565388 -63.848488)
		(width 0.089408)
		(layer "In4.Cu")
		(net "RST_BMC_SYSRST_BTN_OUT_B_R1_N")
	)
	(segment
		(start 376.522996 -65.004696)
		(end 377.101862 -65.004696)
		(width 0.089408)
		(layer "In4.Cu")
		(net "RST_BMC_SYSRST_BTN_OUT_B_R1_N")
	)
	(segment
		(start 393.657582 -63.848488)
		(end 393.657836 -63.848742)
		(width 0.089408)
		(layer "In4.Cu")
		(net "RST_BMC_SYSRST_BTN_OUT_B_R1_N")
	)
	(segment
		(start 378.97562 -64.3763)
		(end 381.005588 -64.3763)
		(width 0.089408)
		(layer "In4.Cu")
		(net "RST_BMC_SYSRST_BTN_OUT_B_R1_N")
	)
	(segment
		(start 378.20346 -65.14846)
		(end 378.97562 -64.3763)
		(width 0.089408)
		(layer "In4.Cu")
		(net "RST_BMC_SYSRST_BTN_OUT_B_R1_N")
	)
	(segment
		(start 385.045458 -65.718944)
		(end 386.704586 -64.059816)
		(width 0.089408)
		(layer "In4.Cu")
		(net "RST_BMC_SYSRST_BTN_OUT_B_R1_N")
	)
	(segment
		(start 367.571782 -68.54063)
		(end 367.790476 -68.321936)
		(width 0.089408)
		(layer "In4.Cu")
		(net "RST_BMC_SYSRST_BTN_OUT_B_R1_N")
	)
	(segment
		(start 383.141728 -65.225676)
		(end 383.634996 -65.718944)
		(width 0.089408)
		(layer "In4.Cu")
		(net "RST_BMC_SYSRST_BTN_OUT_B_R1_N")
	)
	(segment
		(start 383.634996 -65.718944)
		(end 385.045458 -65.718944)
		(width 0.089408)
		(layer "In4.Cu")
		(net "RST_BMC_SYSRST_BTN_OUT_B_R1_N")
	)
	(segment
		(start 381.854964 -65.225676)
		(end 383.141728 -65.225676)
		(width 0.089408)
		(layer "In4.Cu")
		(net "RST_BMC_SYSRST_BTN_OUT_B_R1_N")
	)
	(segment
		(start 393.657836 -63.848742)
		(end 393.815824 -63.848742)
		(width 0.089408)
		(layer "In4.Cu")
		(net "RST_BMC_SYSRST_BTN_OUT_B_R1_N")
	)
	(segment
		(start 370.420138 -67.104006)
		(end 370.97843 -66.545714)
		(width 0.089408)
		(layer "In4.Cu")
		(net "RST_BMC_SYSRST_BTN_OUT_B_R1_N")
	)
	(segment
		(start 393.815824 -63.848742)
		(end 393.816078 -63.848996)
		(width 0.089408)
		(layer "In4.Cu")
		(net "RST_BMC_SYSRST_BTN_OUT_B_R1_N")
	)
	(segment
		(start 365.971836 -69.340476)
		(end 366.19053 -69.121782)
		(width 0.089408)
		(layer "In4.Cu")
		(net "RST_BMC_SYSRST_BTN_OUT_B_R1_N")
	)
	(segment
		(start 389.565388 -63.848488)
		(end 393.657582 -63.848488)
		(width 0.089408)
		(layer "In4.Cu")
		(net "RST_BMC_SYSRST_BTN_OUT_B_R1_N")
	)
	(segment
		(start 366.617504 -71.895462)
		(end 365.971836 -71.249794)
		(width 0.089408)
		(layer "In4.Cu")
		(net "RST_BMC_SYSRST_BTN_OUT_B_R1_N")
	)
	(segment
		(start 367.945162 -71.895462)
		(end 366.617504 -71.895462)
		(width 0.089408)
		(layer "In4.Cu")
		(net "RST_BMC_SYSRST_BTN_OUT_B_R1_N")
	)
	(segment
		(start 375.677938 -65.849754)
		(end 376.522996 -65.004696)
		(width 0.089408)
		(layer "In4.Cu")
		(net "RST_BMC_SYSRST_BTN_OUT_B_R1_N")
	)
	(segment
		(start 370.420138 -67.10426)
		(end 370.420138 -67.104006)
		(width 0.089408)
		(layer "In4.Cu")
		(net "RST_BMC_SYSRST_BTN_OUT_B_R1_N")
	)
	(segment
		(start 365.971836 -71.249794)
		(end 365.971836 -69.340476)
		(width 0.089408)
		(layer "In4.Cu")
		(net "RST_BMC_SYSRST_BTN_OUT_B_R1_N")
	)
	(segment
		(start 393.816078 -63.848996)
		(end 393.974066 -63.848996)
		(width 0.089408)
		(layer "In4.Cu")
		(net "RST_BMC_SYSRST_BTN_OUT_B_R1_N")
	)
	(segment
		(start 374.49252 -65.849754)
		(end 375.677938 -65.849754)
		(width 0.089408)
		(layer "In4.Cu")
		(net "RST_BMC_SYSRST_BTN_OUT_B_R1_N")
	)
	(segment
		(start 367.275872 -69.121782)
		(end 367.571782 -68.825872)
		(width 0.089408)
		(layer "In4.Cu")
		(net "RST_BMC_SYSRST_BTN_OUT_B_R1_N")
	)
	(segment
		(start 367.790476 -68.321936)
		(end 369.202462 -68.321936)
		(width 0.089408)
		(layer "In4.Cu")
		(net "RST_BMC_SYSRST_BTN_OUT_B_R1_N")
	)
	(segment
		(start 393.974066 -63.848996)
		(end 395.401038 -62.422024)
		(width 0.089408)
		(layer "In4.Cu")
		(net "RST_BMC_SYSRST_BTN_OUT_B_R1_N")
	)
	(segment
		(start 367.571782 -68.825872)
		(end 367.571782 -68.54063)
		(width 0.089408)
		(layer "In4.Cu")
		(net "RST_BMC_SYSRST_BTN_OUT_B_R1_N")
	)
	(segment
		(start 398.36471 -62.838584)
		(end 398.36471 -62.931294)
		(width 0.089408)
		(layer "In4.Cu")
		(net "RST_BMC_SYSRST_BTN_OUT_B_R1_N")
	)
	(segment
		(start 395.401038 -62.422024)
		(end 397.94815 -62.422024)
		(width 0.089408)
		(layer "In4.Cu")
		(net "RST_BMC_SYSRST_BTN_OUT_B_R1_N")
	)
	(segment
		(start 369.202462 -68.321936)
		(end 370.420138 -67.10426)
		(width 0.089408)
		(layer "In4.Cu")
		(net "RST_BMC_SYSRST_BTN_OUT_B_R1_N")
	)
	(segment
		(start 377.101862 -65.004696)
		(end 377.245626 -65.14846)
		(width 0.089408)
		(layer "In4.Cu")
		(net "RST_BMC_SYSRST_BTN_OUT_B_R1_N")
	)
	(segment
		(start 377.245626 -65.14846)
		(end 378.20346 -65.14846)
		(width 0.089408)
		(layer "In4.Cu")
		(net "RST_BMC_SYSRST_BTN_OUT_B_R1_N")
	)
	(segment
		(start 397.94815 -62.422024)
		(end 398.36471 -62.838584)
		(width 0.089408)
		(layer "In4.Cu")
		(net "RST_BMC_SYSRST_BTN_OUT_B_R1_N")
	)
	(segment
		(start 381.005588 -64.3763)
		(end 381.854964 -65.225676)
		(width 0.089408)
		(layer "In4.Cu")
		(net "RST_BMC_SYSRST_BTN_OUT_B_R1_N")
	)
	(segment
		(start 366.19053 -69.121782)
		(end 367.275872 -69.121782)
		(width 0.089408)
		(layer "In4.Cu")
		(net "RST_BMC_SYSRST_BTN_OUT_B_R1_N")
	)
	(segment
		(start 386.704586 -64.059816)
		(end 389.35406 -64.059816)
		(width 0.089408)
		(layer "In4.Cu")
		(net "RST_BMC_SYSRST_BTN_OUT_B_R1_N")
	)
	(segment
		(start 370.97843 -66.545714)
		(end 373.79656 -66.545714)
		(width 0.089408)
		(layer "In4.Cu")
		(net "RST_BMC_SYSRST_BTN_OUT_B_R1_N")
	)
	(segment
		(start 373.79656 -66.545714)
		(end 374.49252 -65.849754)
		(width 0.089408)
		(layer "In4.Cu")
		(net "RST_BMC_SYSRST_BTN_OUT_B_R1_N")
	)
	(segment
		(start 375.144792 -72.695308)
		(end 374.744996 -73.095104)
		(width 0.1016)
		(layer "F.Cu")
		(net "FM_PWR_BTN_R2_N")
	)
	(via
		(at 376.902218 -90.615262)
		(size 0.508)
		(drill 0.254)
		(layers "F.Cu" "B.Cu")
		(net "FM_PWR_BTN_R2_N")
	)
	(via
		(at 375.144792 -72.695308)
		(size 0.4572)
		(drill 0.2032)
		(layers "F.Cu" "B.Cu")
		(net "FM_PWR_BTN_R2_N")
	)
	(via
		(at 376.194574 -90.48242)
		(size 0.6604)
		(drill 0.3302)
		(layers "F.Cu" "B.Cu")
		(net "FM_PWR_BTN_R2_N")
	)
	(segment
		(start 376.275854 -90.40114)
		(end 376.194574 -90.48242)
		(width 0.10795)
		(layer "B.Cu")
		(net "FM_PWR_BTN_R2_N")
	)
	(segment
		(start 376.688096 -90.40114)
		(end 376.275854 -90.40114)
		(width 0.10795)
		(layer "B.Cu")
		(net "FM_PWR_BTN_R2_N")
	)
	(segment
		(start 376.902218 -90.615262)
		(end 376.688096 -90.40114)
		(width 0.10795)
		(layer "B.Cu")
		(net "FM_PWR_BTN_R2_N")
	)
	(segment
		(start 376.215656 -90.89517)
		(end 376.215656 -91.284298)
		(width 0.10795)
		(layer "B.Cu")
		(net "FM_PWR_BTN_R2_N")
	)
	(segment
		(start 376.194574 -90.874088)
		(end 376.215656 -90.89517)
		(width 0.10795)
		(layer "B.Cu")
		(net "FM_PWR_BTN_R2_N")
	)
	(segment
		(start 376.194574 -90.48242)
		(end 376.194574 -90.874088)
		(width 0.10795)
		(layer "B.Cu")
		(net "FM_PWR_BTN_R2_N")
	)
	(segment
		(start 375.550684 -73.37298)
		(end 375.550684 -76.016866)
		(width 0.089408)
		(layer "In11.Cu")
		(net "FM_PWR_BTN_R2_N")
	)
	(segment
		(start 376.902218 -90.327734)
		(end 376.902218 -90.615262)
		(width 0.089408)
		(layer "In11.Cu")
		(net "FM_PWR_BTN_R2_N")
	)
	(segment
		(start 375.518426 -79.903574)
		(end 375.129044 -80.292956)
		(width 0.089408)
		(layer "In11.Cu")
		(net "FM_PWR_BTN_R2_N")
	)
	(segment
		(start 377.340622 -89.88933)
		(end 376.902218 -90.327734)
		(width 0.089408)
		(layer "In11.Cu")
		(net "FM_PWR_BTN_R2_N")
	)
	(segment
		(start 375.576846 -81.80832)
		(end 375.576846 -87.044784)
		(width 0.089408)
		(layer "In11.Cu")
		(net "FM_PWR_BTN_R2_N")
	)
	(segment
		(start 375.550684 -76.016866)
		(end 375.518426 -76.049124)
		(width 0.089408)
		(layer "In11.Cu")
		(net "FM_PWR_BTN_R2_N")
	)
	(segment
		(start 377.340622 -88.80856)
		(end 377.340622 -89.88933)
		(width 0.089408)
		(layer "In11.Cu")
		(net "FM_PWR_BTN_R2_N")
	)
	(segment
		(start 375.144792 -72.695308)
		(end 375.144792 -72.967088)
		(width 0.089408)
		(layer "In11.Cu")
		(net "FM_PWR_BTN_R2_N")
	)
	(segment
		(start 375.576846 -87.044784)
		(end 377.340622 -88.80856)
		(width 0.089408)
		(layer "In11.Cu")
		(net "FM_PWR_BTN_R2_N")
	)
	(segment
		(start 375.129044 -80.292956)
		(end 375.129044 -81.360518)
		(width 0.089408)
		(layer "In11.Cu")
		(net "FM_PWR_BTN_R2_N")
	)
	(segment
		(start 375.518426 -76.049124)
		(end 375.518426 -79.903574)
		(width 0.089408)
		(layer "In11.Cu")
		(net "FM_PWR_BTN_R2_N")
	)
	(segment
		(start 375.144792 -72.967088)
		(end 375.550684 -73.37298)
		(width 0.089408)
		(layer "In11.Cu")
		(net "FM_PWR_BTN_R2_N")
	)
	(segment
		(start 375.129044 -81.360518)
		(end 375.576846 -81.80832)
		(width 0.089408)
		(layer "In11.Cu")
		(net "FM_PWR_BTN_R2_N")
	)
	(segment
		(start 411.09011 -40.13454)
		(end 410.69006 -40.53459)
		(width 0.089408)
		(layer "F.Cu")
		(net "FM_PWR_BTN_R1_N")
	)
	(via
		(at 410.69006 -40.53459)
		(size 0.4572)
		(drill 0.2032)
		(layers "F.Cu" "B.Cu")
		(net "FM_PWR_BTN_R1_N")
	)
	(via
		(at 403.237446 -48.768)
		(size 0.508)
		(drill 0.254)
		(layers "F.Cu" "B.Cu")
		(net "FM_PWR_BTN_R1_N")
	)
	(via
		(at 404.267924 -50.373026)
		(size 0.6604)
		(drill 0.3302)
		(layers "F.Cu" "B.Cu")
		(net "FM_PWR_BTN_R1_N")
	)
	(segment
		(start 404.267924 -50.373026)
		(end 404.267924 -49.798478)
		(width 0.10795)
		(layer "B.Cu")
		(net "FM_PWR_BTN_R1_N")
	)
	(segment
		(start 405.44496 -50.9397)
		(end 404.834598 -50.9397)
		(width 0.10795)
		(layer "B.Cu")
		(net "FM_PWR_BTN_R1_N")
	)
	(segment
		(start 404.267924 -49.798478)
		(end 403.237446 -48.768)
		(width 0.10795)
		(layer "B.Cu")
		(net "FM_PWR_BTN_R1_N")
	)
	(segment
		(start 404.834598 -50.9397)
		(end 404.267924 -50.373026)
		(width 0.10795)
		(layer "B.Cu")
		(net "FM_PWR_BTN_R1_N")
	)
	(segment
		(start 407.899108 -43.9801)
		(end 408.077924 -43.801284)
		(width 0.089408)
		(layer "In9.Cu")
		(net "FM_PWR_BTN_R1_N")
	)
	(segment
		(start 405.358346 -44.893738)
		(end 407.140918 -44.893738)
		(width 0.089408)
		(layer "In9.Cu")
		(net "FM_PWR_BTN_R1_N")
	)
	(segment
		(start 407.140918 -44.893738)
		(end 407.899108 -44.135548)
		(width 0.089408)
		(layer "In9.Cu")
		(net "FM_PWR_BTN_R1_N")
	)
	(segment
		(start 404.718774 -46.69028)
		(end 404.718774 -45.53331)
		(width 0.089408)
		(layer "In9.Cu")
		(net "FM_PWR_BTN_R1_N")
	)
	(segment
		(start 408.077924 -43.80103)
		(end 408.607006 -43.271948)
		(width 0.089408)
		(layer "In9.Cu")
		(net "FM_PWR_BTN_R1_N")
	)
	(segment
		(start 410.282644 -42.497756)
		(end 410.282644 -41.150286)
		(width 0.089408)
		(layer "In9.Cu")
		(net "FM_PWR_BTN_R1_N")
	)
	(segment
		(start 403.237446 -48.768)
		(end 403.237446 -48.171608)
		(width 0.089408)
		(layer "In9.Cu")
		(net "FM_PWR_BTN_R1_N")
	)
	(segment
		(start 403.237446 -48.171608)
		(end 404.718774 -46.69028)
		(width 0.089408)
		(layer "In9.Cu")
		(net "FM_PWR_BTN_R1_N")
	)
	(segment
		(start 408.60726 -43.271948)
		(end 408.826462 -43.052746)
		(width 0.089408)
		(layer "In9.Cu")
		(net "FM_PWR_BTN_R1_N")
	)
	(segment
		(start 408.826462 -43.052746)
		(end 409.727654 -43.052746)
		(width 0.089408)
		(layer "In9.Cu")
		(net "FM_PWR_BTN_R1_N")
	)
	(segment
		(start 407.899108 -44.135548)
		(end 407.899108 -43.9801)
		(width 0.089408)
		(layer "In9.Cu")
		(net "FM_PWR_BTN_R1_N")
	)
	(segment
		(start 410.282644 -41.150286)
		(end 410.69006 -40.74287)
		(width 0.089408)
		(layer "In9.Cu")
		(net "FM_PWR_BTN_R1_N")
	)
	(segment
		(start 408.607006 -43.271948)
		(end 408.60726 -43.271948)
		(width 0.089408)
		(layer "In9.Cu")
		(net "FM_PWR_BTN_R1_N")
	)
	(segment
		(start 410.69006 -40.74287)
		(end 410.69006 -40.53459)
		(width 0.089408)
		(layer "In9.Cu")
		(net "FM_PWR_BTN_R1_N")
	)
	(segment
		(start 409.727654 -43.052746)
		(end 410.282644 -42.497756)
		(width 0.089408)
		(layer "In9.Cu")
		(net "FM_PWR_BTN_R1_N")
	)
	(segment
		(start 408.077924 -43.801284)
		(end 408.077924 -43.80103)
		(width 0.089408)
		(layer "In9.Cu")
		(net "FM_PWR_BTN_R1_N")
	)
	(segment
		(start 404.718774 -45.53331)
		(end 405.358346 -44.893738)
		(width 0.089408)
		(layer "In9.Cu")
		(net "FM_PWR_BTN_R1_N")
	)
	(segment
		(start 369.545108 -68.695316)
		(end 369.944904 -69.095112)
		(width 0.10795)
		(layer "F.Cu")
		(net "FM_PCH_PWRBTN_R1_N")
	)
	(via
		(at 369.545108 -68.695316)
		(size 0.4572)
		(drill 0.2032)
		(layers "F.Cu" "B.Cu")
		(net "FM_PCH_PWRBTN_R1_N")
	)
	(segment
		(start 370.036344 -68.048632)
		(end 369.545108 -68.539868)
		(width 0.10795)
		(layer "B.Cu")
		(net "FM_PCH_PWRBTN_R1_N")
	)
	(segment
		(start 370.334794 -68.048632)
		(end 370.036344 -68.048632)
		(width 0.10795)
		(layer "B.Cu")
		(net "FM_PCH_PWRBTN_R1_N")
	)
	(segment
		(start 369.545108 -68.539868)
		(end 369.545108 -68.695316)
		(width 0.10795)
		(layer "B.Cu")
		(net "FM_PCH_PWRBTN_R1_N")
	)
	(segment
		(start 399.129758 -153.996898)
		(end 399.131282 -153.998422)
		(width 0.10795)
		(layer "F.Cu")
		(net "PU_PVNN_PCH_VDIO")
	)
	(segment
		(start 399.342102 -154.20086)
		(end 399.67408 -154.20086)
		(width 0.10795)
		(layer "F.Cu")
		(net "PU_PVNN_PCH_VDIO")
	)
	(segment
		(start 399.139664 -153.998422)
		(end 399.342102 -154.20086)
		(width 0.10795)
		(layer "F.Cu")
		(net "PU_PVNN_PCH_VDIO")
	)
	(segment
		(start 398.2339 -153.996898)
		(end 399.129758 -153.996898)
		(width 0.10795)
		(layer "F.Cu")
		(net "PU_PVNN_PCH_VDIO")
	)
	(segment
		(start 399.131282 -153.998422)
		(end 399.139664 -153.998422)
		(width 0.10795)
		(layer "F.Cu")
		(net "PU_PVNN_PCH_VDIO")
	)
	(segment
		(start 400.558 -153.93924)
		(end 400.558 -154.19324)
		(width 0.10795)
		(layer "F.Cu")
		(net "PU_PVNN_PCH_VCLK")
	)
	(segment
		(start 400.215862 -153.597102)
		(end 400.558 -153.93924)
		(width 0.10795)
		(layer "F.Cu")
		(net "PU_PVNN_PCH_VCLK")
	)
	(segment
		(start 403.22246 -155.269946)
		(end 402.582634 -155.269946)
		(width 0.10795)
		(layer "F.Cu")
		(net "PU_PVNN_PCH_VCLK")
	)
	(segment
		(start 400.81454 -154.19324)
		(end 400.558 -154.19324)
		(width 0.10795)
		(layer "F.Cu")
		(net "PU_PVNN_PCH_VCLK")
	)
	(segment
		(start 401.0152 -154.3939)
		(end 400.81454 -154.19324)
		(width 0.10795)
		(layer "F.Cu")
		(net "PU_PVNN_PCH_VCLK")
	)
	(segment
		(start 398.2339 -153.597102)
		(end 400.215862 -153.597102)
		(width 0.10795)
		(layer "F.Cu")
		(net "PU_PVNN_PCH_VCLK")
	)
	(segment
		(start 402.582634 -155.269946)
		(end 401.706588 -154.3939)
		(width 0.10795)
		(layer "F.Cu")
		(net "PU_PVNN_PCH_VCLK")
	)
	(segment
		(start 401.706588 -154.3939)
		(end 401.0152 -154.3939)
		(width 0.10795)
		(layer "F.Cu")
		(net "PU_PVNN_PCH_VCLK")
	)
	(via
		(at 403.22246 -155.269946)
		(size 0.762)
		(drill 0.381)
		(layers "F.Cu" "B.Cu")
		(net "PU_PVNN_PCH_VCLK")
	)
	(segment
		(start 481.9396 -33.11144)
		(end 482.03104 -33.02)
		(width 0.10795)
		(layer "F.Cu")
		(net "XTAL_CK_MNG_OUT_R")
	)
	(segment
		(start 482.03104 -33.02)
		(end 482.6508 -33.02)
		(width 0.10795)
		(layer "F.Cu")
		(net "XTAL_CK_MNG_OUT_R")
	)
	(segment
		(start 481.0125 -33.11144)
		(end 481.9396 -33.11144)
		(width 0.10795)
		(layer "F.Cu")
		(net "XTAL_CK_MNG_OUT_R")
	)
	(segment
		(start 474.7895 -29.1084)
		(end 474.3196 -29.1084)
		(width 0.10795)
		(layer "F.Cu")
		(net "SMB_HOST_STBY_LVC3_SDA_R4")
	)
	(segment
		(start 473.583 -29.845)
		(end 473.202 -29.845)
		(width 0.10795)
		(layer "F.Cu")
		(net "SMB_HOST_STBY_LVC3_SDA_R4")
	)
	(segment
		(start 474.3196 -29.1084)
		(end 473.583 -29.845)
		(width 0.10795)
		(layer "F.Cu")
		(net "SMB_HOST_STBY_LVC3_SDA_R4")
	)
	(segment
		(start 474.7895 -29.60878)
		(end 474.32722 -29.60878)
		(width 0.10795)
		(layer "F.Cu")
		(net "SMB_HOST_STBY_LVC3_SCL_R4")
	)
	(segment
		(start 473.583 -30.607)
		(end 473.202 -30.607)
		(width 0.10795)
		(layer "F.Cu")
		(net "SMB_HOST_STBY_LVC3_SCL_R4")
	)
	(segment
		(start 473.837 -30.353)
		(end 473.583 -30.607)
		(width 0.10795)
		(layer "F.Cu")
		(net "SMB_HOST_STBY_LVC3_SCL_R4")
	)
	(segment
		(start 473.837 -30.099)
		(end 473.837 -30.353)
		(width 0.10795)
		(layer "F.Cu")
		(net "SMB_HOST_STBY_LVC3_SCL_R4")
	)
	(segment
		(start 474.32722 -29.60878)
		(end 473.837 -30.099)
		(width 0.10795)
		(layer "F.Cu")
		(net "SMB_HOST_STBY_LVC3_SCL_R4")
	)
	(segment
		(start 371.963696 -69.513704)
		(end 371.545104 -69.095112)
		(width 0.10795)
		(layer "F.Cu")
		(net "PU_CPLD1_PT20D_PROGRAMN")
	)
	(via
		(at 371.963696 -69.513704)
		(size 0.4572)
		(drill 0.2032)
		(layers "F.Cu" "B.Cu")
		(net "PU_CPLD1_PT20D_PROGRAMN")
	)
	(via
		(at 372.32082 -68.855082)
		(size 0.6604)
		(drill 0.3302)
		(layers "F.Cu" "B.Cu")
		(net "PU_CPLD1_PT20D_PROGRAMN")
	)
	(segment
		(start 372.339616 -69.18833)
		(end 372.014242 -69.513704)
		(width 0.10795)
		(layer "B.Cu")
		(net "PU_CPLD1_PT20D_PROGRAMN")
	)
	(segment
		(start 371.915182 -66.996818)
		(end 371.983 -66.929)
		(width 0.10795)
		(layer "B.Cu")
		(net "PU_CPLD1_PT20D_PROGRAMN")
	)
	(segment
		(start 371.983 -66.929)
		(end 371.983 -66.5734)
		(width 0.10795)
		(layer "B.Cu")
		(net "PU_CPLD1_PT20D_PROGRAMN")
	)
	(segment
		(start 372.339616 -68.855082)
		(end 372.339616 -69.18833)
		(width 0.10795)
		(layer "B.Cu")
		(net "PU_CPLD1_PT20D_PROGRAMN")
	)
	(segment
		(start 372.339616 -68.855082)
		(end 372.339616 -67.988688)
		(width 0.10795)
		(layer "B.Cu")
		(net "PU_CPLD1_PT20D_PROGRAMN")
	)
	(segment
		(start 371.915182 -67.564254)
		(end 371.915182 -66.996818)
		(width 0.10795)
		(layer "B.Cu")
		(net "PU_CPLD1_PT20D_PROGRAMN")
	)
	(segment
		(start 372.339616 -67.988688)
		(end 371.915182 -67.564254)
		(width 0.10795)
		(layer "B.Cu")
		(net "PU_CPLD1_PT20D_PROGRAMN")
	)
	(segment
		(start 372.32082 -68.855082)
		(end 372.339616 -68.855082)
		(width 0.10795)
		(layer "B.Cu")
		(net "PU_CPLD1_PT20D_PROGRAMN")
	)
	(segment
		(start 372.014242 -69.513704)
		(end 371.963696 -69.513704)
		(width 0.10795)
		(layer "B.Cu")
		(net "PU_CPLD1_PT20D_PROGRAMN")
	)
	(segment
		(start 479.77298 -35.12058)
		(end 479.77298 -35.5854)
		(width 0.10795)
		(layer "F.Cu")
		(net "PU_33P_33M_SMBADR")
	)
	(segment
		(start 479.77298 -36.16198)
		(end 480.4029 -36.7919)
		(width 0.10795)
		(layer "F.Cu")
		(net "PU_33P_33M_SMBADR")
	)
	(segment
		(start 479.65106 -33.9725)
		(end 479.65106 -34.99866)
		(width 0.10795)
		(layer "F.Cu")
		(net "PU_33P_33M_SMBADR")
	)
	(segment
		(start 479.65106 -34.99866)
		(end 479.77298 -35.12058)
		(width 0.10795)
		(layer "F.Cu")
		(net "PU_33P_33M_SMBADR")
	)
	(segment
		(start 479.77298 -35.5854)
		(end 479.77298 -36.16198)
		(width 0.10795)
		(layer "F.Cu")
		(net "PU_33P_33M_SMBADR")
	)
	(via
		(at 480.4029 -36.7919)
		(size 0.762)
		(drill 0.381)
		(layers "F.Cu" "B.Cu")
		(net "PU_33P_33M_SMBADR")
	)
	(segment
		(start 410.400246 -23.867618)
		(end 410.048964 -23.516336)
		(width 0.089408)
		(layer "F.Cu")
		(net "FM_GLOBAL_RST_WARN_N_R")
	)
	(segment
		(start 410.400246 -24.943816)
		(end 411.09011 -25.63368)
		(width 0.089408)
		(layer "F.Cu")
		(net "FM_GLOBAL_RST_WARN_N_R")
	)
	(segment
		(start 410.400246 -24.56688)
		(end 410.400246 -23.867618)
		(width 0.089408)
		(layer "F.Cu")
		(net "FM_GLOBAL_RST_WARN_N_R")
	)
	(segment
		(start 411.09011 -25.63368)
		(end 411.09011 -26.534618)
		(width 0.089408)
		(layer "F.Cu")
		(net "FM_GLOBAL_RST_WARN_N_R")
	)
	(segment
		(start 410.048964 -23.516336)
		(end 410.048964 -23.070566)
		(width 0.089408)
		(layer "F.Cu")
		(net "FM_GLOBAL_RST_WARN_N_R")
	)
	(segment
		(start 410.400246 -24.56688)
		(end 410.400246 -24.943816)
		(width 0.089408)
		(layer "F.Cu")
		(net "FM_GLOBAL_RST_WARN_N_R")
	)
	(via
		(at 410.400246 -24.56688)
		(size 0.508)
		(drill 0.254)
		(layers "F.Cu" "B.Cu")
		(net "FM_GLOBAL_RST_WARN_N_R")
	)
	(via
		(at 7.174484 -124.855478)
		(size 0.6604)
		(drill 0.3302)
		(layers "F.Cu" "B.Cu")
		(net "PWRGD_PVDDQ_KLM_N")
	)
	(segment
		(start 11.161268 -125.913134)
		(end 11.161268 -125.052328)
		(width 0.10795)
		(layer "B.Cu")
		(net "PWRGD_PVDDQ_KLM_N")
	)
	(segment
		(start 9.260332 -124.728732)
		(end 9.260332 -123.921266)
		(width 0.10795)
		(layer "B.Cu")
		(net "PWRGD_PVDDQ_KLM_N")
	)
	(segment
		(start 7.174484 -124.855478)
		(end 8.108696 -123.921266)
		(width 0.10795)
		(layer "B.Cu")
		(net "PWRGD_PVDDQ_KLM_N")
	)
	(segment
		(start 11.161268 -125.913134)
		(end 12.197334 -125.913134)
		(width 0.10795)
		(layer "B.Cu")
		(net "PWRGD_PVDDQ_KLM_N")
	)
	(segment
		(start 12.3317 -126.0475)
		(end 13.0048 -126.0475)
		(width 0.10795)
		(layer "B.Cu")
		(net "PWRGD_PVDDQ_KLM_N")
	)
	(segment
		(start 9.4234 -124.8918)
		(end 9.260332 -124.728732)
		(width 0.10795)
		(layer "B.Cu")
		(net "PWRGD_PVDDQ_KLM_N")
	)
	(segment
		(start 11.00074 -124.8918)
		(end 9.4234 -124.8918)
		(width 0.10795)
		(layer "B.Cu")
		(net "PWRGD_PVDDQ_KLM_N")
	)
	(segment
		(start 8.108696 -123.921266)
		(end 9.260332 -123.921266)
		(width 0.10795)
		(layer "B.Cu")
		(net "PWRGD_PVDDQ_KLM_N")
	)
	(segment
		(start 12.197334 -125.913134)
		(end 12.3317 -126.0475)
		(width 0.10795)
		(layer "B.Cu")
		(net "PWRGD_PVDDQ_KLM_N")
	)
	(segment
		(start 11.161268 -125.052328)
		(end 11.00074 -124.8918)
		(width 0.10795)
		(layer "B.Cu")
		(net "PWRGD_PVDDQ_KLM_N")
	)
	(segment
		(start 28.6893 -30.255972)
		(end 29.213556 -30.780228)
		(width 0.10795)
		(layer "F.Cu")
		(net "PWRGD_PVDDQ_GHJ_N")
	)
	(segment
		(start 29.213556 -31.899098)
		(end 29.406088 -32.09163)
		(width 0.10795)
		(layer "F.Cu")
		(net "PWRGD_PVDDQ_GHJ_N")
	)
	(segment
		(start 28.217622 -30.190694)
		(end 28.2829 -30.255972)
		(width 0.10795)
		(layer "F.Cu")
		(net "PWRGD_PVDDQ_GHJ_N")
	)
	(segment
		(start 28.217622 -29.6799)
		(end 28.786074 -29.111448)
		(width 0.10795)
		(layer "F.Cu")
		(net "PWRGD_PVDDQ_GHJ_N")
	)
	(segment
		(start 29.213556 -30.780228)
		(end 29.213556 -31.899098)
		(width 0.10795)
		(layer "F.Cu")
		(net "PWRGD_PVDDQ_GHJ_N")
	)
	(segment
		(start 28.217622 -30.190694)
		(end 28.217622 -29.6799)
		(width 0.10795)
		(layer "F.Cu")
		(net "PWRGD_PVDDQ_GHJ_N")
	)
	(segment
		(start 28.786074 -29.111448)
		(end 28.99537 -29.111448)
		(width 0.10795)
		(layer "F.Cu")
		(net "PWRGD_PVDDQ_GHJ_N")
	)
	(segment
		(start 28.99537 -29.111448)
		(end 29.495496 -28.611322)
		(width 0.10795)
		(layer "F.Cu")
		(net "PWRGD_PVDDQ_GHJ_N")
	)
	(segment
		(start 29.495496 -28.611322)
		(end 29.495496 -28.547822)
		(width 0.10795)
		(layer "F.Cu")
		(net "PWRGD_PVDDQ_GHJ_N")
	)
	(segment
		(start 28.2829 -30.255972)
		(end 28.6893 -30.255972)
		(width 0.10795)
		(layer "F.Cu")
		(net "PWRGD_PVDDQ_GHJ_N")
	)
	(segment
		(start 29.406088 -32.09163)
		(end 30.20949 -32.09163)
		(width 0.10795)
		(layer "F.Cu")
		(net "PWRGD_PVDDQ_GHJ_N")
	)
	(segment
		(start 186.047126 -126.586488)
		(end 185.4835 -126.022862)
		(width 0.10795)
		(layer "F.Cu")
		(net "PWRGD_PVDDQ_DEF_N")
	)
	(segment
		(start 186.047126 -127.5207)
		(end 186.047126 -126.586488)
		(width 0.10795)
		(layer "F.Cu")
		(net "PWRGD_PVDDQ_DEF_N")
	)
	(segment
		(start 186.450224 -127.923798)
		(end 186.047126 -127.5207)
		(width 0.10795)
		(layer "F.Cu")
		(net "PWRGD_PVDDQ_DEF_N")
	)
	(segment
		(start 185.4835 -126.022862)
		(end 184.890664 -126.022862)
		(width 0.10795)
		(layer "F.Cu")
		(net "PWRGD_PVDDQ_DEF_N")
	)
	(segment
		(start 186.882532 -127.923798)
		(end 186.450224 -127.923798)
		(width 0.10795)
		(layer "F.Cu")
		(net "PWRGD_PVDDQ_DEF_N")
	)
	(segment
		(start 185.600086 -128.54432)
		(end 186.220608 -127.923798)
		(width 0.10795)
		(layer "F.Cu")
		(net "PWRGD_PVDDQ_DEF_N")
	)
	(segment
		(start 184.41416 -128.54432)
		(end 185.600086 -128.54432)
		(width 0.10795)
		(layer "F.Cu")
		(net "PWRGD_PVDDQ_DEF_N")
	)
	(segment
		(start 186.220608 -127.923798)
		(end 186.450224 -127.923798)
		(width 0.10795)
		(layer "F.Cu")
		(net "PWRGD_PVDDQ_DEF_N")
	)
	(via
		(at 184.19826 -129.77114)
		(size 0.6604)
		(drill 0.3302)
		(layers "F.Cu" "B.Cu")
		(net "PWRGD_PVDDQ_DEF_N")
	)
	(via
		(at 184.41416 -128.54432)
		(size 0.508)
		(drill 0.254)
		(layers "F.Cu" "B.Cu")
		(net "PWRGD_PVDDQ_DEF_N")
	)
	(segment
		(start 184.57164 -128.7018)
		(end 184.41416 -128.54432)
		(width 0.10795)
		(layer "B.Cu")
		(net "PWRGD_PVDDQ_DEF_N")
	)
	(segment
		(start 184.41416 -128.54432)
		(end 184.19826 -128.76022)
		(width 0.10795)
		(layer "B.Cu")
		(net "PWRGD_PVDDQ_DEF_N")
	)
	(segment
		(start 184.19826 -128.76022)
		(end 184.19826 -129.77114)
		(width 0.10795)
		(layer "B.Cu")
		(net "PWRGD_PVDDQ_DEF_N")
	)
	(segment
		(start 185.2549 -128.7018)
		(end 184.57164 -128.7018)
		(width 0.10795)
		(layer "B.Cu")
		(net "PWRGD_PVDDQ_DEF_N")
	)
	(segment
		(start 183.820562 -23.388828)
		(end 183.251348 -23.958042)
		(width 0.10795)
		(layer "F.Cu")
		(net "PWRGD_PVDDQ_ABC_N")
	)
	(segment
		(start 183.031384 -21.34362)
		(end 183.820562 -22.132798)
		(width 0.10795)
		(layer "F.Cu")
		(net "PWRGD_PVDDQ_ABC_N")
	)
	(segment
		(start 181.877462 -23.958042)
		(end 181.632606 -24.202898)
		(width 0.10795)
		(layer "F.Cu")
		(net "PWRGD_PVDDQ_ABC_N")
	)
	(segment
		(start 181.632606 -24.202898)
		(end 181.632606 -25.213564)
		(width 0.10795)
		(layer "F.Cu")
		(net "PWRGD_PVDDQ_ABC_N")
	)
	(segment
		(start 183.820562 -22.132798)
		(end 183.820562 -23.388828)
		(width 0.10795)
		(layer "F.Cu")
		(net "PWRGD_PVDDQ_ABC_N")
	)
	(segment
		(start 183.031384 -20.722844)
		(end 183.031384 -21.34362)
		(width 0.10795)
		(layer "F.Cu")
		(net "PWRGD_PVDDQ_ABC_N")
	)
	(segment
		(start 181.801262 -25.38222)
		(end 182.604664 -25.38222)
		(width 0.10795)
		(layer "F.Cu")
		(net "PWRGD_PVDDQ_ABC_N")
	)
	(segment
		(start 181.400704 -23.481284)
		(end 181.877462 -23.958042)
		(width 0.10795)
		(layer "F.Cu")
		(net "PWRGD_PVDDQ_ABC_N")
	)
	(segment
		(start 181.632606 -25.213564)
		(end 181.801262 -25.38222)
		(width 0.10795)
		(layer "F.Cu")
		(net "PWRGD_PVDDQ_ABC_N")
	)
	(segment
		(start 183.251348 -23.958042)
		(end 181.877462 -23.958042)
		(width 0.10795)
		(layer "F.Cu")
		(net "PWRGD_PVDDQ_ABC_N")
	)
	(segment
		(start 181.5338 -19.22526)
		(end 183.031384 -20.722844)
		(width 0.10795)
		(layer "F.Cu")
		(net "PWRGD_PVDDQ_ABC_N")
	)
	(segment
		(start 180.612796 -23.481284)
		(end 181.400704 -23.481284)
		(width 0.10795)
		(layer "F.Cu")
		(net "PWRGD_PVDDQ_ABC_N")
	)
	(via
		(at 181.5338 -19.22526)
		(size 0.762)
		(drill 0.381)
		(layers "F.Cu" "B.Cu")
		(net "PWRGD_PVDDQ_ABC_N")
	)
	(segment
		(start 12.0777 -128.109218)
		(end 12.0777 -125.800612)
		(width 0.254)
		(layer "F.Cu")
		(net "P12V_NVDIMM_KLM_D")
	)
	(segment
		(start 12.0777 -125.800612)
		(end 11.131296 -124.854208)
		(width 0.254)
		(layer "F.Cu")
		(net "P12V_NVDIMM_KLM_D")
	)
	(via
		(at 12.0777 -128.109218)
		(size 0.508)
		(drill 0.254)
		(layers "F.Cu" "B.Cu")
		(net "P12V_NVDIMM_KLM_D")
	)
	(via
		(at 9.554972 -127.724662)
		(size 0.6604)
		(drill 0.3302)
		(layers "F.Cu" "B.Cu")
		(net "P12V_NVDIMM_KLM_D")
	)
	(segment
		(start 10.919968 -127.357632)
		(end 11.612626 -127.357632)
		(width 0.254)
		(layer "B.Cu")
		(net "P12V_NVDIMM_KLM_D")
	)
	(segment
		(start 12.0777 -128.8034)
		(end 12.0777 -128.109218)
		(width 0.254)
		(layer "B.Cu")
		(net "P12V_NVDIMM_KLM_D")
	)
	(segment
		(start 11.612626 -127.357632)
		(end 12.0777 -127.822706)
		(width 0.254)
		(layer "B.Cu")
		(net "P12V_NVDIMM_KLM_D")
	)
	(segment
		(start 9.514332 -127.724662)
		(end 9.260332 -127.470662)
		(width 0.254)
		(layer "B.Cu")
		(net "P12V_NVDIMM_KLM_D")
	)
	(segment
		(start 9.554972 -127.724662)
		(end 9.514332 -127.724662)
		(width 0.254)
		(layer "B.Cu")
		(net "P12V_NVDIMM_KLM_D")
	)
	(segment
		(start 10.552938 -127.724662)
		(end 10.919968 -127.357632)
		(width 0.254)
		(layer "B.Cu")
		(net "P12V_NVDIMM_KLM_D")
	)
	(segment
		(start 9.260332 -127.470662)
		(end 9.260332 -125.913134)
		(width 0.254)
		(layer "B.Cu")
		(net "P12V_NVDIMM_KLM_D")
	)
	(segment
		(start 12.0777 -127.822706)
		(end 12.0777 -128.109218)
		(width 0.254)
		(layer "B.Cu")
		(net "P12V_NVDIMM_KLM_D")
	)
	(segment
		(start 9.554972 -127.724662)
		(end 10.552938 -127.724662)
		(width 0.254)
		(layer "B.Cu")
		(net "P12V_NVDIMM_KLM_D")
	)
	(segment
		(start 27.843988 -32.735266)
		(end 27.864562 -32.714692)
		(width 0.254)
		(layer "F.Cu")
		(net "P12V_NVDIMM_GHJ_D")
	)
	(segment
		(start 27.864562 -32.714692)
		(end 27.864562 -32.34563)
		(width 0.254)
		(layer "F.Cu")
		(net "P12V_NVDIMM_GHJ_D")
	)
	(segment
		(start 28.118562 -32.09163)
		(end 28.217622 -32.09163)
		(width 0.254)
		(layer "F.Cu")
		(net "P12V_NVDIMM_GHJ_D")
	)
	(segment
		(start 27.864562 -32.34563)
		(end 28.118562 -32.09163)
		(width 0.254)
		(layer "F.Cu")
		(net "P12V_NVDIMM_GHJ_D")
	)
	(via
		(at 10.80008 4.291584)
		(size 0.508)
		(drill 0.254)
		(layers "F.Cu" "B.Cu")
		(net "P12V_NVDIMM_GHJ_D")
	)
	(via
		(at 27.843988 -32.735266)
		(size 0.508)
		(drill 0.254)
		(layers "F.Cu" "B.Cu")
		(net "P12V_NVDIMM_GHJ_D")
	)
	(segment
		(start 10.508996 4.291584)
		(end 10.01141 3.793998)
		(width 0.254)
		(layer "B.Cu")
		(net "P12V_NVDIMM_GHJ_D")
	)
	(segment
		(start 28.03779 -31.148782)
		(end 28.119832 -31.06674)
		(width 0.254)
		(layer "B.Cu")
		(net "P12V_NVDIMM_GHJ_D")
	)
	(segment
		(start 10.01141 3.793998)
		(end 10.01141 3.192272)
		(width 0.254)
		(layer "B.Cu")
		(net "P12V_NVDIMM_GHJ_D")
	)
	(segment
		(start 27.843988 -32.735266)
		(end 28.03779 -32.541464)
		(width 0.254)
		(layer "B.Cu")
		(net "P12V_NVDIMM_GHJ_D")
	)
	(segment
		(start 10.01141 3.192272)
		(end 9.061958 2.24282)
		(width 0.254)
		(layer "B.Cu")
		(net "P12V_NVDIMM_GHJ_D")
	)
	(segment
		(start 10.80008 4.291584)
		(end 10.508996 4.291584)
		(width 0.254)
		(layer "B.Cu")
		(net "P12V_NVDIMM_GHJ_D")
	)
	(segment
		(start 28.03779 -32.541464)
		(end 28.03779 -31.148782)
		(width 0.254)
		(layer "B.Cu")
		(net "P12V_NVDIMM_GHJ_D")
	)
	(segment
		(start 27.843988 -32.860234)
		(end 27.843988 -32.735266)
		(width 0.254)
		(layer "In2.Cu")
		(net "P12V_NVDIMM_GHJ_D")
	)
	(segment
		(start 10.80008 4.291584)
		(end 11.014456 4.291584)
		(width 0.254)
		(layer "In2.Cu")
		(net "P12V_NVDIMM_GHJ_D")
	)
	(segment
		(start 26.3652 -2.306066)
		(end 26.3652 -4.640834)
		(width 0.254)
		(layer "In2.Cu")
		(net "P12V_NVDIMM_GHJ_D")
	)
	(segment
		(start 24.892508 -0.833374)
		(end 26.3652 -2.306066)
		(width 0.254)
		(layer "In2.Cu")
		(net "P12V_NVDIMM_GHJ_D")
	)
	(segment
		(start 29.02077 -33.214818)
		(end 28.198572 -33.214818)
		(width 0.254)
		(layer "In2.Cu")
		(net "P12V_NVDIMM_GHJ_D")
	)
	(segment
		(start 14.769084 3.132582)
		(end 15.323566 2.5781)
		(width 0.254)
		(layer "In2.Cu")
		(net "P12V_NVDIMM_GHJ_D")
	)
	(segment
		(start 29.6164 -20.654518)
		(end 29.6164 -32.619188)
		(width 0.254)
		(layer "In2.Cu")
		(net "P12V_NVDIMM_GHJ_D")
	)
	(segment
		(start 29.6164 -32.619188)
		(end 29.02077 -33.214818)
		(width 0.254)
		(layer "In2.Cu")
		(net "P12V_NVDIMM_GHJ_D")
	)
	(segment
		(start 19.6215 2.5781)
		(end 23.032974 -0.833374)
		(width 0.254)
		(layer "In2.Cu")
		(net "P12V_NVDIMM_GHJ_D")
	)
	(segment
		(start 15.323566 2.5781)
		(end 19.6215 2.5781)
		(width 0.254)
		(layer "In2.Cu")
		(net "P12V_NVDIMM_GHJ_D")
	)
	(segment
		(start 11.014456 4.291584)
		(end 12.173458 3.132582)
		(width 0.254)
		(layer "In2.Cu")
		(net "P12V_NVDIMM_GHJ_D")
	)
	(segment
		(start 23.032974 -0.833374)
		(end 24.892508 -0.833374)
		(width 0.254)
		(layer "In2.Cu")
		(net "P12V_NVDIMM_GHJ_D")
	)
	(segment
		(start 28.0416 -19.079718)
		(end 29.6164 -20.654518)
		(width 0.254)
		(layer "In2.Cu")
		(net "P12V_NVDIMM_GHJ_D")
	)
	(segment
		(start 28.0416 -6.317234)
		(end 28.0416 -19.079718)
		(width 0.254)
		(layer "In2.Cu")
		(net "P12V_NVDIMM_GHJ_D")
	)
	(segment
		(start 12.173458 3.132582)
		(end 14.769084 3.132582)
		(width 0.254)
		(layer "In2.Cu")
		(net "P12V_NVDIMM_GHJ_D")
	)
	(segment
		(start 28.198572 -33.214818)
		(end 27.843988 -32.860234)
		(width 0.254)
		(layer "In2.Cu")
		(net "P12V_NVDIMM_GHJ_D")
	)
	(segment
		(start 26.3652 -4.640834)
		(end 28.0416 -6.317234)
		(width 0.254)
		(layer "In2.Cu")
		(net "P12V_NVDIMM_GHJ_D")
	)
	(segment
		(start 183.215026 -126.5682)
		(end 183.215026 -126.0602)
		(width 0.254)
		(layer "F.Cu")
		(net "P12V_NVDIMM_DEF_D")
	)
	(segment
		(start 183.361076 -127.341884)
		(end 183.222392 -127.2032)
		(width 0.254)
		(layer "F.Cu")
		(net "P12V_NVDIMM_DEF_D")
	)
	(segment
		(start 183.94299 -127.923798)
		(end 183.361076 -127.341884)
		(width 0.254)
		(layer "F.Cu")
		(net "P12V_NVDIMM_DEF_D")
	)
	(segment
		(start 183.222392 -126.575566)
		(end 183.215026 -126.5682)
		(width 0.254)
		(layer "F.Cu")
		(net "P12V_NVDIMM_DEF_D")
	)
	(segment
		(start 183.222392 -127.2032)
		(end 183.222392 -126.575566)
		(width 0.254)
		(layer "F.Cu")
		(net "P12V_NVDIMM_DEF_D")
	)
	(segment
		(start 184.890664 -127.923798)
		(end 183.94299 -127.923798)
		(width 0.254)
		(layer "F.Cu")
		(net "P12V_NVDIMM_DEF_D")
	)
	(via
		(at 183.361076 -127.341884)
		(size 0.508)
		(drill 0.254)
		(layers "F.Cu" "B.Cu")
		(net "P12V_NVDIMM_DEF_D")
	)
	(via
		(at 331.597 -137.795)
		(size 0.508)
		(drill 0.254)
		(layers "F.Cu" "B.Cu")
		(net "P12V_NVDIMM_DEF_D")
	)
	(via
		(at 354.624132 -136.54913)
		(size 0.508)
		(drill 0.254)
		(layers "F.Cu" "B.Cu")
		(net "P12V_NVDIMM_DEF_D")
	)
	(via
		(at 328.99096 -125.313186)
		(size 0.508)
		(drill 0.254)
		(layers "F.Cu" "B.Cu")
		(net "P12V_NVDIMM_DEF_D")
	)
	(segment
		(start 354.82149 -136.54913)
		(end 356.177088 -137.904728)
		(width 0.254)
		(layer "B.Cu")
		(net "P12V_NVDIMM_DEF_D")
	)
	(segment
		(start 356.177088 -137.904728)
		(end 356.479348 -137.904728)
		(width 0.254)
		(layer "B.Cu")
		(net "P12V_NVDIMM_DEF_D")
	)
	(segment
		(start 354.624132 -136.54913)
		(end 354.82149 -136.54913)
		(width 0.254)
		(layer "B.Cu")
		(net "P12V_NVDIMM_DEF_D")
	)
	(segment
		(start 332.324456 -129.267204)
		(end 332.324456 -135.558022)
		(width 0.254)
		(layer "In4.Cu")
		(net "P12V_NVDIMM_DEF_D")
	)
	(segment
		(start 332.324456 -135.558022)
		(end 331.597 -136.285478)
		(width 0.254)
		(layer "In4.Cu")
		(net "P12V_NVDIMM_DEF_D")
	)
	(segment
		(start 328.99096 -125.933708)
		(end 332.324456 -129.267204)
		(width 0.254)
		(layer "In4.Cu")
		(net "P12V_NVDIMM_DEF_D")
	)
	(segment
		(start 328.99096 -125.313186)
		(end 328.99096 -125.933708)
		(width 0.254)
		(layer "In4.Cu")
		(net "P12V_NVDIMM_DEF_D")
	)
	(segment
		(start 331.597 -136.285478)
		(end 331.597 -137.795)
		(width 0.254)
		(layer "In4.Cu")
		(net "P12V_NVDIMM_DEF_D")
	)
	(segment
		(start 190.916814 -128.279398)
		(end 193.055748 -126.140464)
		(width 0.254)
		(layer "In9.Cu")
		(net "P12V_NVDIMM_DEF_D")
	)
	(segment
		(start 186.984386 -128.279398)
		(end 190.916814 -128.279398)
		(width 0.254)
		(layer "In9.Cu")
		(net "P12V_NVDIMM_DEF_D")
	)
	(segment
		(start 353.771708 -135.317484)
		(end 337.308698 -135.317484)
		(width 0.254)
		(layer "In9.Cu")
		(net "P12V_NVDIMM_DEF_D")
	)
	(segment
		(start 193.055748 -126.140464)
		(end 220.439488 -126.140464)
		(width 0.254)
		(layer "In9.Cu")
		(net "P12V_NVDIMM_DEF_D")
	)
	(segment
		(start 325.796656 -127.215646)
		(end 327.699116 -125.313186)
		(width 0.254)
		(layer "In9.Cu")
		(net "P12V_NVDIMM_DEF_D")
	)
	(segment
		(start 323.559424 -127.215646)
		(end 325.796656 -127.215646)
		(width 0.254)
		(layer "In9.Cu")
		(net "P12V_NVDIMM_DEF_D")
	)
	(segment
		(start 322.76542 -128.00965)
		(end 323.559424 -127.215646)
		(width 0.254)
		(layer "In9.Cu")
		(net "P12V_NVDIMM_DEF_D")
	)
	(segment
		(start 327.699116 -125.313186)
		(end 328.99096 -125.313186)
		(width 0.254)
		(layer "In9.Cu")
		(net "P12V_NVDIMM_DEF_D")
	)
	(segment
		(start 220.439488 -126.140464)
		(end 221.719394 -127.42037)
		(width 0.254)
		(layer "In9.Cu")
		(net "P12V_NVDIMM_DEF_D")
	)
	(segment
		(start 183.361076 -127.341884)
		(end 183.463438 -127.444246)
		(width 0.254)
		(layer "In9.Cu")
		(net "P12V_NVDIMM_DEF_D")
	)
	(segment
		(start 334.278986 -136.652)
		(end 333.000604 -137.930382)
		(width 0.254)
		(layer "In9.Cu")
		(net "P12V_NVDIMM_DEF_D")
	)
	(segment
		(start 246.635778 -125.17628)
		(end 264.655808 -125.17628)
		(width 0.254)
		(layer "In9.Cu")
		(net "P12V_NVDIMM_DEF_D")
	)
	(segment
		(start 265.414506 -124.417582)
		(end 285.234888 -124.417582)
		(width 0.254)
		(layer "In9.Cu")
		(net "P12V_NVDIMM_DEF_D")
	)
	(segment
		(start 354.624132 -136.169908)
		(end 353.771708 -135.317484)
		(width 0.254)
		(layer "In9.Cu")
		(net "P12V_NVDIMM_DEF_D")
	)
	(segment
		(start 244.391688 -127.42037)
		(end 246.635778 -125.17628)
		(width 0.254)
		(layer "In9.Cu")
		(net "P12V_NVDIMM_DEF_D")
	)
	(segment
		(start 354.624132 -136.54913)
		(end 354.624132 -136.169908)
		(width 0.254)
		(layer "In9.Cu")
		(net "P12V_NVDIMM_DEF_D")
	)
	(segment
		(start 333.000604 -137.930382)
		(end 331.732382 -137.930382)
		(width 0.254)
		(layer "In9.Cu")
		(net "P12V_NVDIMM_DEF_D")
	)
	(segment
		(start 186.149234 -127.444246)
		(end 186.984386 -128.279398)
		(width 0.254)
		(layer "In9.Cu")
		(net "P12V_NVDIMM_DEF_D")
	)
	(segment
		(start 288.826956 -128.00965)
		(end 322.76542 -128.00965)
		(width 0.254)
		(layer "In9.Cu")
		(net "P12V_NVDIMM_DEF_D")
	)
	(segment
		(start 285.234888 -124.417582)
		(end 288.826956 -128.00965)
		(width 0.254)
		(layer "In9.Cu")
		(net "P12V_NVDIMM_DEF_D")
	)
	(segment
		(start 264.655808 -125.17628)
		(end 265.414506 -124.417582)
		(width 0.254)
		(layer "In9.Cu")
		(net "P12V_NVDIMM_DEF_D")
	)
	(segment
		(start 331.732382 -137.930382)
		(end 331.597 -137.795)
		(width 0.254)
		(layer "In9.Cu")
		(net "P12V_NVDIMM_DEF_D")
	)
	(segment
		(start 183.463438 -127.444246)
		(end 186.149234 -127.444246)
		(width 0.254)
		(layer "In9.Cu")
		(net "P12V_NVDIMM_DEF_D")
	)
	(segment
		(start 337.308698 -135.317484)
		(end 335.974182 -136.652)
		(width 0.254)
		(layer "In9.Cu")
		(net "P12V_NVDIMM_DEF_D")
	)
	(segment
		(start 335.974182 -136.652)
		(end 334.278986 -136.652)
		(width 0.254)
		(layer "In9.Cu")
		(net "P12V_NVDIMM_DEF_D")
	)
	(segment
		(start 221.719394 -127.42037)
		(end 244.391688 -127.42037)
		(width 0.254)
		(layer "In9.Cu")
		(net "P12V_NVDIMM_DEF_D")
	)
	(segment
		(start 176.911508 -24.384508)
		(end 176.022 -23.495)
		(width 0.254)
		(layer "F.Cu")
		(net "P12V_NVDIMM_ABC_D")
	)
	(segment
		(start 178.80711 -24.973788)
		(end 178.80711 -24.961088)
		(width 0.254)
		(layer "F.Cu")
		(net "P12V_NVDIMM_ABC_D")
	)
	(segment
		(start 351.731834 -23.048976)
		(end 351.731834 -22.249638)
		(width 0.254)
		(layer "F.Cu")
		(net "P12V_NVDIMM_ABC_D")
	)
	(segment
		(start 350.129856 -23.362666)
		(end 351.418144 -23.362666)
		(width 0.254)
		(layer "F.Cu")
		(net "P12V_NVDIMM_ABC_D")
	)
	(segment
		(start 178.80711 -24.961088)
		(end 178.23053 -24.384508)
		(width 0.254)
		(layer "F.Cu")
		(net "P12V_NVDIMM_ABC_D")
	)
	(segment
		(start 179.215542 -25.38222)
		(end 178.80711 -24.973788)
		(width 0.254)
		(layer "F.Cu")
		(net "P12V_NVDIMM_ABC_D")
	)
	(segment
		(start 351.418144 -23.362666)
		(end 351.731834 -23.048976)
		(width 0.254)
		(layer "F.Cu")
		(net "P12V_NVDIMM_ABC_D")
	)
	(segment
		(start 178.23053 -24.384508)
		(end 176.911508 -24.384508)
		(width 0.254)
		(layer "F.Cu")
		(net "P12V_NVDIMM_ABC_D")
	)
	(segment
		(start 180.612796 -25.38222)
		(end 179.215542 -25.38222)
		(width 0.254)
		(layer "F.Cu")
		(net "P12V_NVDIMM_ABC_D")
	)
	(via
		(at 350.129856 -23.362666)
		(size 0.508)
		(drill 0.254)
		(layers "F.Cu" "B.Cu")
		(net "P12V_NVDIMM_ABC_D")
	)
	(via
		(at 176.022 -23.495)
		(size 0.508)
		(drill 0.254)
		(layers "F.Cu" "B.Cu")
		(net "P12V_NVDIMM_ABC_D")
	)
	(via
		(at 175.72482 -22.81428)
		(size 0.6604)
		(drill 0.3302)
		(layers "F.Cu" "B.Cu")
		(net "P12V_NVDIMM_ABC_D")
	)
	(segment
		(start 176.022 -23.495)
		(end 176.022 -23.11146)
		(width 0.254)
		(layer "B.Cu")
		(net "P12V_NVDIMM_ABC_D")
	)
	(segment
		(start 176.022 -23.11146)
		(end 175.72482 -22.81428)
		(width 0.254)
		(layer "B.Cu")
		(net "P12V_NVDIMM_ABC_D")
	)
	(segment
		(start 184.05983 -20.613116)
		(end 184.05983 -23.05177)
		(width 0.254)
		(layer "In4.Cu")
		(net "P12V_NVDIMM_ABC_D")
	)
	(segment
		(start 330.389484 -27.8638)
		(end 329.350116 -27.8638)
		(width 0.254)
		(layer "In4.Cu")
		(net "P12V_NVDIMM_ABC_D")
	)
	(segment
		(start 197.369684 -1.324356)
		(end 197.354698 -1.30937)
		(width 0.254)
		(layer "In4.Cu")
		(net "P12V_NVDIMM_ABC_D")
	)
	(segment
		(start 191.062356 -20.1422)
		(end 184.530746 -20.1422)
		(width 0.254)
		(layer "In4.Cu")
		(net "P12V_NVDIMM_ABC_D")
	)
	(segment
		(start 264.773156 -1.18872)
		(end 264.54354 -1.418336)
		(width 0.254)
		(layer "In4.Cu")
		(net "P12V_NVDIMM_ABC_D")
	)
	(segment
		(start 347.9292 -18.0086)
		(end 342.685116 -18.0086)
		(width 0.254)
		(layer "In4.Cu")
		(net "P12V_NVDIMM_ABC_D")
	)
	(segment
		(start 191.962278 -19.242278)
		(end 191.062356 -20.1422)
		(width 0.254)
		(layer "In4.Cu")
		(net "P12V_NVDIMM_ABC_D")
	)
	(segment
		(start 321.832478 -1.753108)
		(end 321.26809 -1.18872)
		(width 0.254)
		(layer "In4.Cu")
		(net "P12V_NVDIMM_ABC_D")
	)
	(segment
		(start 337.1342 -22.1742)
		(end 333.1464 -26.162)
		(width 0.254)
		(layer "In4.Cu")
		(net "P12V_NVDIMM_ABC_D")
	)
	(segment
		(start 321.831716 -3.979164)
		(end 321.831462 -3.979164)
		(width 0.254)
		(layer "In4.Cu")
		(net "P12V_NVDIMM_ABC_D")
	)
	(segment
		(start 339.0138 -17.4498)
		(end 338.2264 -18.2372)
		(width 0.254)
		(layer "In4.Cu")
		(net "P12V_NVDIMM_ABC_D")
	)
	(segment
		(start 191.5668 -6.909054)
		(end 191.5668 -9.394952)
		(width 0.254)
		(layer "In4.Cu")
		(net "P12V_NVDIMM_ABC_D")
	)
	(segment
		(start 260.975856 0.06477)
		(end 260.222238 0.06477)
		(width 0.254)
		(layer "In4.Cu")
		(net "P12V_NVDIMM_ABC_D")
	)
	(segment
		(start 190.9064 -6.248654)
		(end 191.5668 -6.909054)
		(width 0.254)
		(layer "In4.Cu")
		(net "P12V_NVDIMM_ABC_D")
	)
	(segment
		(start 191.9478 -11.128248)
		(end 191.3128 -11.763248)
		(width 0.254)
		(layer "In4.Cu")
		(net "P12V_NVDIMM_ABC_D")
	)
	(segment
		(start 333.1464 -26.162)
		(end 332.091284 -26.162)
		(width 0.254)
		(layer "In4.Cu")
		(net "P12V_NVDIMM_ABC_D")
	)
	(segment
		(start 176.911 -24.384)
		(end 176.022 -23.495)
		(width 0.254)
		(layer "In4.Cu")
		(net "P12V_NVDIMM_ABC_D")
	)
	(segment
		(start 322.582794 -4.730242)
		(end 321.831716 -3.979164)
		(width 0.254)
		(layer "In4.Cu")
		(net "P12V_NVDIMM_ABC_D")
	)
	(segment
		(start 322.582794 -23.10003)
		(end 322.582794 -4.730242)
		(width 0.254)
		(layer "In4.Cu")
		(net "P12V_NVDIMM_ABC_D")
	)
	(segment
		(start 191.272922 -3.912362)
		(end 191.272922 -5.094224)
		(width 0.254)
		(layer "In4.Cu")
		(net "P12V_NVDIMM_ABC_D")
	)
	(segment
		(start 191.962278 -17.819878)
		(end 191.962278 -19.242278)
		(width 0.254)
		(layer "In4.Cu")
		(net "P12V_NVDIMM_ABC_D")
	)
	(segment
		(start 321.831462 -3.979164)
		(end 321.564 -3.711702)
		(width 0.254)
		(layer "In4.Cu")
		(net "P12V_NVDIMM_ABC_D")
	)
	(segment
		(start 184.530746 -20.1422)
		(end 184.05983 -20.613116)
		(width 0.254)
		(layer "In4.Cu")
		(net "P12V_NVDIMM_ABC_D")
	)
	(segment
		(start 348.6658 -18.7452)
		(end 347.9292 -18.0086)
		(width 0.254)
		(layer "In4.Cu")
		(net "P12V_NVDIMM_ABC_D")
	)
	(segment
		(start 337.1342 -20.585684)
		(end 337.1342 -22.1742)
		(width 0.254)
		(layer "In4.Cu")
		(net "P12V_NVDIMM_ABC_D")
	)
	(segment
		(start 191.9478 -9.775952)
		(end 191.9478 -11.128248)
		(width 0.254)
		(layer "In4.Cu")
		(net "P12V_NVDIMM_ABC_D")
	)
	(segment
		(start 350.762824 -19.927824)
		(end 349.5802 -18.7452)
		(width 0.254)
		(layer "In4.Cu")
		(net "P12V_NVDIMM_ABC_D")
	)
	(segment
		(start 349.5802 -18.7452)
		(end 348.6658 -18.7452)
		(width 0.254)
		(layer "In4.Cu")
		(net "P12V_NVDIMM_ABC_D")
	)
	(segment
		(start 326.152764 -26.67)
		(end 322.582794 -23.10003)
		(width 0.254)
		(layer "In4.Cu")
		(net "P12V_NVDIMM_ABC_D")
	)
	(segment
		(start 338.2264 -18.2372)
		(end 338.2264 -19.493484)
		(width 0.254)
		(layer "In4.Cu")
		(net "P12V_NVDIMM_ABC_D")
	)
	(segment
		(start 184.05983 -23.05177)
		(end 182.7276 -24.384)
		(width 0.254)
		(layer "In4.Cu")
		(net "P12V_NVDIMM_ABC_D")
	)
	(segment
		(start 342.685116 -18.0086)
		(end 342.126316 -17.4498)
		(width 0.254)
		(layer "In4.Cu")
		(net "P12V_NVDIMM_ABC_D")
	)
	(segment
		(start 321.564 -2.909316)
		(end 321.832478 -2.640838)
		(width 0.254)
		(layer "In4.Cu")
		(net "P12V_NVDIMM_ABC_D")
	)
	(segment
		(start 191.3128 -11.763248)
		(end 191.3128 -17.1704)
		(width 0.254)
		(layer "In4.Cu")
		(net "P12V_NVDIMM_ABC_D")
	)
	(segment
		(start 260.222238 0.06477)
		(end 258.833112 -1.324356)
		(width 0.254)
		(layer "In4.Cu")
		(net "P12V_NVDIMM_ABC_D")
	)
	(segment
		(start 191.883284 -3.302)
		(end 191.272922 -3.912362)
		(width 0.254)
		(layer "In4.Cu")
		(net "P12V_NVDIMM_ABC_D")
	)
	(segment
		(start 350.402144 -23.362666)
		(end 350.762824 -23.001986)
		(width 0.254)
		(layer "In4.Cu")
		(net "P12V_NVDIMM_ABC_D")
	)
	(segment
		(start 338.2264 -19.493484)
		(end 337.1342 -20.585684)
		(width 0.254)
		(layer "In4.Cu")
		(net "P12V_NVDIMM_ABC_D")
	)
	(segment
		(start 321.564 -3.711702)
		(end 321.564 -2.909316)
		(width 0.254)
		(layer "In4.Cu")
		(net "P12V_NVDIMM_ABC_D")
	)
	(segment
		(start 195.03263 -1.30937)
		(end 193.04 -3.302)
		(width 0.254)
		(layer "In4.Cu")
		(net "P12V_NVDIMM_ABC_D")
	)
	(segment
		(start 350.129856 -23.362666)
		(end 350.402144 -23.362666)
		(width 0.254)
		(layer "In4.Cu")
		(net "P12V_NVDIMM_ABC_D")
	)
	(segment
		(start 262.458962 -1.418336)
		(end 260.975856 0.06477)
		(width 0.254)
		(layer "In4.Cu")
		(net "P12V_NVDIMM_ABC_D")
	)
	(segment
		(start 197.354698 -1.30937)
		(end 195.03263 -1.30937)
		(width 0.254)
		(layer "In4.Cu")
		(net "P12V_NVDIMM_ABC_D")
	)
	(segment
		(start 321.832478 -2.640838)
		(end 321.832478 -1.753108)
		(width 0.254)
		(layer "In4.Cu")
		(net "P12V_NVDIMM_ABC_D")
	)
	(segment
		(start 191.3128 -17.1704)
		(end 191.962278 -17.819878)
		(width 0.254)
		(layer "In4.Cu")
		(net "P12V_NVDIMM_ABC_D")
	)
	(segment
		(start 329.350116 -27.8638)
		(end 328.156316 -26.67)
		(width 0.254)
		(layer "In4.Cu")
		(net "P12V_NVDIMM_ABC_D")
	)
	(segment
		(start 264.54354 -1.418336)
		(end 262.458962 -1.418336)
		(width 0.254)
		(layer "In4.Cu")
		(net "P12V_NVDIMM_ABC_D")
	)
	(segment
		(start 193.04 -3.302)
		(end 191.883284 -3.302)
		(width 0.254)
		(layer "In4.Cu")
		(net "P12V_NVDIMM_ABC_D")
	)
	(segment
		(start 328.156316 -26.67)
		(end 326.152764 -26.67)
		(width 0.254)
		(layer "In4.Cu")
		(net "P12V_NVDIMM_ABC_D")
	)
	(segment
		(start 332.091284 -26.162)
		(end 330.389484 -27.8638)
		(width 0.254)
		(layer "In4.Cu")
		(net "P12V_NVDIMM_ABC_D")
	)
	(segment
		(start 350.762824 -23.001986)
		(end 350.762824 -19.927824)
		(width 0.254)
		(layer "In4.Cu")
		(net "P12V_NVDIMM_ABC_D")
	)
	(segment
		(start 258.833112 -1.324356)
		(end 197.369684 -1.324356)
		(width 0.254)
		(layer "In4.Cu")
		(net "P12V_NVDIMM_ABC_D")
	)
	(segment
		(start 321.26809 -1.18872)
		(end 264.773156 -1.18872)
		(width 0.254)
		(layer "In4.Cu")
		(net "P12V_NVDIMM_ABC_D")
	)
	(segment
		(start 342.126316 -17.4498)
		(end 339.0138 -17.4498)
		(width 0.254)
		(layer "In4.Cu")
		(net "P12V_NVDIMM_ABC_D")
	)
	(segment
		(start 182.7276 -24.384)
		(end 176.911 -24.384)
		(width 0.254)
		(layer "In4.Cu")
		(net "P12V_NVDIMM_ABC_D")
	)
	(segment
		(start 190.9064 -5.460746)
		(end 190.9064 -6.248654)
		(width 0.254)
		(layer "In4.Cu")
		(net "P12V_NVDIMM_ABC_D")
	)
	(segment
		(start 191.5668 -9.394952)
		(end 191.9478 -9.775952)
		(width 0.254)
		(layer "In4.Cu")
		(net "P12V_NVDIMM_ABC_D")
	)
	(segment
		(start 191.272922 -5.094224)
		(end 190.9064 -5.460746)
		(width 0.254)
		(layer "In4.Cu")
		(net "P12V_NVDIMM_ABC_D")
	)
	(segment
		(start 28.7655 -69.2531)
		(end 27.6225 -69.2531)
		(width 0.254)
		(layer "F.Cu")
		(net "TEMP_SENSOR_E")
	)
	(segment
		(start 27.6225 -69.2531)
		(end 27.559 -69.3166)
		(width 0.254)
		(layer "F.Cu")
		(net "TEMP_SENSOR_E")
	)
	(segment
		(start 26.0858 -69.3166)
		(end 26.7462 -69.3166)
		(width 0.254)
		(layer "F.Cu")
		(net "TEMP_SENSOR_E")
	)
	(segment
		(start 27.559 -69.3166)
		(end 26.7462 -69.3166)
		(width 0.254)
		(layer "F.Cu")
		(net "TEMP_SENSOR_E")
	)
	(segment
		(start 23.9395 -67.848988)
		(end 24.618188 -67.848988)
		(width 0.254)
		(layer "F.Cu")
		(net "TEMP_SENSOR_E")
	)
	(segment
		(start 24.618188 -67.848988)
		(end 26.0858 -69.3166)
		(width 0.254)
		(layer "F.Cu")
		(net "TEMP_SENSOR_E")
	)
	(via
		(at 28.7655 -69.2531)
		(size 0.762)
		(drill 0.381)
		(layers "F.Cu" "B.Cu")
		(net "TEMP_SENSOR_E")
	)
	(segment
		(start 24.76246 -71.4756)
		(end 25.7937 -71.4756)
		(width 0.254)
		(layer "F.Cu")
		(net "TEMP_SENSOR_B")
	)
	(segment
		(start 24.321008 -68.796408)
		(end 23.946612 -68.796408)
		(width 0.254)
		(layer "F.Cu")
		(net "TEMP_SENSOR_B")
	)
	(segment
		(start 25.7937 -71.099426)
		(end 25.7937 -71.4756)
		(width 0.254)
		(layer "F.Cu")
		(net "TEMP_SENSOR_B")
	)
	(segment
		(start 24.8412 -69.3166)
		(end 24.321008 -68.796408)
		(width 0.254)
		(layer "F.Cu")
		(net "TEMP_SENSOR_B")
	)
	(segment
		(start 24.8412 -70.146926)
		(end 25.7937 -71.099426)
		(width 0.254)
		(layer "F.Cu")
		(net "TEMP_SENSOR_B")
	)
	(segment
		(start 24.8412 -69.3166)
		(end 24.8412 -70.146926)
		(width 0.254)
		(layer "F.Cu")
		(net "TEMP_SENSOR_B")
	)
	(segment
		(start 24.59736 -71.6407)
		(end 24.76246 -71.4756)
		(width 0.254)
		(layer "F.Cu")
		(net "TEMP_SENSOR_B")
	)
	(via
		(at 24.59736 -71.6407)
		(size 0.762)
		(drill 0.381)
		(layers "F.Cu" "B.Cu")
		(net "TEMP_SENSOR_B")
	)
	(segment
		(start 396.65275 -117.58168)
		(end 397.14805 -117.811804)
		(width 0.1143)
		(layer "F.Cu")
		(net "USB3_P01_TXP")
	)
	(via
		(at 397.14805 -117.811804)
		(size 0.508)
		(drill 0.254)
		(layers "F.Cu" "B.Cu")
		(net "USB3_P01_TXP")
	)
	(via
		(at 469.95588 -64.389)
		(size 0.508)
		(drill 0.254)
		(layers "F.Cu" "B.Cu")
		(net "USB3_P01_TXP")
	)
	(segment
		(start 471.986102 -66.43497)
		(end 471.652092 -66.358008)
		(width 0.1143)
		(layer "B.Cu")
		(net "USB3_P01_TXP")
	)
	(segment
		(start 473.836492 -66.32829)
		(end 472.42603 -66.653918)
		(width 0.1143)
		(layer "B.Cu")
		(net "USB3_P01_TXP")
	)
	(segment
		(start 479.687636 -61.702696)
		(end 479.014282 -62.124082)
		(width 0.1143)
		(layer "B.Cu")
		(net "USB3_P01_TXP")
	)
	(segment
		(start 481.101908 -61.37656)
		(end 479.687636 -61.702696)
		(width 0.1143)
		(layer "B.Cu")
		(net "USB3_P01_TXP")
	)
	(segment
		(start 470.144602 -65.71234)
		(end 469.962738 -65.42151)
		(width 0.1143)
		(layer "B.Cu")
		(net "USB3_P01_TXP")
	)
	(segment
		(start 470.28989 -66.16065)
		(end 470.10828 -65.86982)
		(width 0.1143)
		(layer "B.Cu")
		(net "USB3_P01_TXP")
	)
	(segment
		(start 485.256586 -60.009532)
		(end 484.968296 -60.297822)
		(width 0.1143)
		(layer "B.Cu")
		(net "USB3_P01_TXP")
	)
	(segment
		(start 471.514932 -66.443606)
		(end 471.180922 -66.36639)
		(width 0.1143)
		(layer "B.Cu")
		(net "USB3_P01_TXP")
	)
	(segment
		(start 484.75011 -60.297822)
		(end 483.32517 -61.1886)
		(width 0.1143)
		(layer "B.Cu")
		(net "USB3_P01_TXP")
	)
	(segment
		(start 469.962738 -65.42151)
		(end 469.805258 -65.385188)
		(width 0.1143)
		(layer "B.Cu")
		(net "USB3_P01_TXP")
	)
	(segment
		(start 481.801678 -61.53785)
		(end 481.101908 -61.37656)
		(width 0.1143)
		(layer "B.Cu")
		(net "USB3_P01_TXP")
	)
	(segment
		(start 479.014282 -62.124082)
		(end 477.397572 -64.711834)
		(width 0.1143)
		(layer "B.Cu")
		(net "USB3_P01_TXP")
	)
	(segment
		(start 483.32517 -61.1886)
		(end 481.801678 -61.53785)
		(width 0.1143)
		(layer "B.Cu")
		(net "USB3_P01_TXP")
	)
	(segment
		(start 472.42603 -66.653918)
		(end 472.0717 -66.57213)
		(width 0.1143)
		(layer "B.Cu")
		(net "USB3_P01_TXP")
	)
	(segment
		(start 469.529668 -64.730884)
		(end 469.871552 -64.389)
		(width 0.1143)
		(layer "B.Cu")
		(net "USB3_P01_TXP")
	)
	(segment
		(start 477.397572 -64.711834)
		(end 475.430342 -65.295526)
		(width 0.1143)
		(layer "B.Cu")
		(net "USB3_P01_TXP")
	)
	(segment
		(start 471.09507 -66.22923)
		(end 470.76106 -66.152268)
		(width 0.1143)
		(layer "B.Cu")
		(net "USB3_P01_TXP")
	)
	(segment
		(start 470.6239 -66.237866)
		(end 470.28989 -66.16065)
		(width 0.1143)
		(layer "B.Cu")
		(net "USB3_P01_TXP")
	)
	(segment
		(start 472.0717 -66.57213)
		(end 471.986102 -66.43497)
		(width 0.1143)
		(layer "B.Cu")
		(net "USB3_P01_TXP")
	)
	(segment
		(start 470.10828 -65.86982)
		(end 470.144602 -65.71234)
		(width 0.1143)
		(layer "B.Cu")
		(net "USB3_P01_TXP")
	)
	(segment
		(start 469.529668 -64.94399)
		(end 469.529668 -64.730884)
		(width 0.1143)
		(layer "B.Cu")
		(net "USB3_P01_TXP")
	)
	(segment
		(start 469.805258 -65.385188)
		(end 469.529668 -64.94399)
		(width 0.1143)
		(layer "B.Cu")
		(net "USB3_P01_TXP")
	)
	(segment
		(start 475.430342 -65.295526)
		(end 473.836492 -66.32829)
		(width 0.1143)
		(layer "B.Cu")
		(net "USB3_P01_TXP")
	)
	(segment
		(start 484.968296 -60.297822)
		(end 484.75011 -60.297822)
		(width 0.1143)
		(layer "B.Cu")
		(net "USB3_P01_TXP")
	)
	(segment
		(start 469.871552 -64.389)
		(end 469.95588 -64.389)
		(width 0.1143)
		(layer "B.Cu")
		(net "USB3_P01_TXP")
	)
	(segment
		(start 470.76106 -66.152268)
		(end 470.6239 -66.237866)
		(width 0.1143)
		(layer "B.Cu")
		(net "USB3_P01_TXP")
	)
	(segment
		(start 471.180922 -66.36639)
		(end 471.09507 -66.22923)
		(width 0.1143)
		(layer "B.Cu")
		(net "USB3_P01_TXP")
	)
	(segment
		(start 471.652092 -66.358008)
		(end 471.514932 -66.443606)
		(width 0.1143)
		(layer "B.Cu")
		(net "USB3_P01_TXP")
	)
	(segment
		(start 424.035474 -83.339432)
		(end 423.53865 -85.440012)
		(width 0.1143)
		(layer "In9.Cu")
		(net "USB3_P01_TXP")
	)
	(segment
		(start 423.591482 -96.518222)
		(end 423.155618 -96.80321)
		(width 0.1143)
		(layer "In9.Cu")
		(net "USB3_P01_TXP")
	)
	(segment
		(start 426.399452 -65.06591)
		(end 423.33672 -68.128642)
		(width 0.1143)
		(layer "In9.Cu")
		(net "USB3_P01_TXP")
	)
	(segment
		(start 421.29583 -96.80321)
		(end 418.136578 -98.808032)
		(width 0.1143)
		(layer "In9.Cu")
		(net "USB3_P01_TXP")
	)
	(segment
		(start 417.617402 -102.68585)
		(end 417.383976 -103.671878)
		(width 0.1143)
		(layer "In9.Cu")
		(net "USB3_P01_TXP")
	)
	(segment
		(start 401.740878 -120.03532)
		(end 401.376642 -119.799862)
		(width 0.0889)
		(layer "In9.Cu")
		(net "USB3_P01_TXP")
	)
	(segment
		(start 417.481004 -102.25278)
		(end 417.481004 -102.253034)
		(width 0.1143)
		(layer "In9.Cu")
		(net "USB3_P01_TXP")
	)
	(segment
		(start 405.201882 -120.683528)
		(end 404.48738 -120.51284)
		(width 0.1143)
		(layer "In9.Cu")
		(net "USB3_P01_TXP")
	)
	(segment
		(start 424.560492 -92.422472)
		(end 423.591482 -96.518222)
		(width 0.1143)
		(layer "In9.Cu")
		(net "USB3_P01_TXP")
	)
	(segment
		(start 411.462982 -121.600214)
		(end 410.446728 -121.351294)
		(width 0.1143)
		(layer "In9.Cu")
		(net "USB3_P01_TXP")
	)
	(segment
		(start 469.95588 -64.389)
		(end 469.754204 -64.389)
		(width 0.1143)
		(layer "In9.Cu")
		(net "USB3_P01_TXP")
	)
	(segment
		(start 401.743418 -120.036082)
		(end 401.742148 -120.036082)
		(width 0.0889)
		(layer "In9.Cu")
		(net "USB3_P01_TXP")
	)
	(segment
		(start 417.38931 -101.96195)
		(end 417.481004 -102.25278)
		(width 0.1143)
		(layer "In9.Cu")
		(net "USB3_P01_TXP")
	)
	(segment
		(start 423.977816 -78.594966)
		(end 423.97807 -78.59522)
		(width 0.1143)
		(layer "In9.Cu")
		(net "USB3_P01_TXP")
	)
	(segment
		(start 423.361612 -81.20126)
		(end 424.035474 -83.339432)
		(width 0.1143)
		(layer "In9.Cu")
		(net "USB3_P01_TXP")
	)
	(segment
		(start 396.748 -117.82298)
		(end 396.748 -117.800628)
		(width 0.0889)
		(layer "In9.Cu")
		(net "USB3_P01_TXP")
	)
	(segment
		(start 469.646 -64.280796)
		(end 469.646 -63.822072)
		(width 0.1143)
		(layer "In9.Cu")
		(net "USB3_P01_TXP")
	)
	(segment
		(start 423.33672 -76.558394)
		(end 423.97807 -78.594966)
		(width 0.1143)
		(layer "In9.Cu")
		(net "USB3_P01_TXP")
	)
	(segment
		(start 404.48738 -120.51284)
		(end 403.67712 -120.755918)
		(width 0.1143)
		(layer "In9.Cu")
		(net "USB3_P01_TXP")
	)
	(segment
		(start 423.97807 -78.594966)
		(end 423.977816 -78.594966)
		(width 0.1143)
		(layer "In9.Cu")
		(net "USB3_P01_TXP")
	)
	(segment
		(start 417.525962 -102.395528)
		(end 417.548568 -102.466902)
		(width 0.1143)
		(layer "In9.Cu")
		(net "USB3_P01_TXP")
	)
	(segment
		(start 418.342318 -117.02923)
		(end 416.02406 -117.72138)
		(width 0.1143)
		(layer "In9.Cu")
		(net "USB3_P01_TXP")
	)
	(segment
		(start 400.515074 -118.93804)
		(end 399.840196 -118.93804)
		(width 0.0889)
		(layer "In9.Cu")
		(net "USB3_P01_TXP")
	)
	(segment
		(start 399.840196 -118.93804)
		(end 399.751296 -118.84914)
		(width 0.0889)
		(layer "In9.Cu")
		(net "USB3_P01_TXP")
	)
	(segment
		(start 412.615634 -121.200164)
		(end 411.462982 -121.600214)
		(width 0.1143)
		(layer "In9.Cu")
		(net "USB3_P01_TXP")
	)
	(segment
		(start 417.481004 -102.253034)
		(end 417.503356 -102.3239)
		(width 0.1143)
		(layer "In9.Cu")
		(net "USB3_P01_TXP")
	)
	(segment
		(start 401.017994 -119.441214)
		(end 401.017994 -119.31523)
		(width 0.0889)
		(layer "In9.Cu")
		(net "USB3_P01_TXP")
	)
	(segment
		(start 400.829272 -119.126508)
		(end 400.703542 -119.126508)
		(width 0.0889)
		(layer "In9.Cu")
		(net "USB3_P01_TXP")
	)
	(segment
		(start 413.036766 -119.950738)
		(end 412.615634 -121.200164)
		(width 0.1143)
		(layer "In9.Cu")
		(net "USB3_P01_TXP")
	)
	(segment
		(start 424.098466 -88.083136)
		(end 424.039792 -88.330532)
		(width 0.1143)
		(layer "In9.Cu")
		(net "USB3_P01_TXP")
	)
	(segment
		(start 424.21556 -87.58809)
		(end 424.098466 -88.083136)
		(width 0.1143)
		(layer "In9.Cu")
		(net "USB3_P01_TXP")
	)
	(segment
		(start 398.834102 -119.017034)
		(end 398.834102 -119.01678)
		(width 0.0889)
		(layer "In9.Cu")
		(net "USB3_P01_TXP")
	)
	(segment
		(start 469.646 -63.822072)
		(end 469.281764 -63.457836)
		(width 0.1143)
		(layer "In9.Cu")
		(net "USB3_P01_TXP")
	)
	(segment
		(start 417.50361 -102.324154)
		(end 417.525962 -102.395528)
		(width 0.1143)
		(layer "In9.Cu")
		(net "USB3_P01_TXP")
	)
	(segment
		(start 399.484596 -118.84914)
		(end 399.395696 -118.93804)
		(width 0.0889)
		(layer "In9.Cu")
		(net "USB3_P01_TXP")
	)
	(segment
		(start 403.67712 -120.755918)
		(end 402.587714 -120.504204)
		(width 0.1143)
		(layer "In9.Cu")
		(net "USB3_P01_TXP")
	)
	(segment
		(start 399.751296 -118.84914)
		(end 399.484596 -118.84914)
		(width 0.0889)
		(layer "In9.Cu")
		(net "USB3_P01_TXP")
	)
	(segment
		(start 419.908482 -111.685578)
		(end 419.521894 -112.906302)
		(width 0.1143)
		(layer "In9.Cu")
		(net "USB3_P01_TXP")
	)
	(segment
		(start 469.754204 -64.389)
		(end 469.646 -64.280796)
		(width 0.1143)
		(layer "In9.Cu")
		(net "USB3_P01_TXP")
	)
	(segment
		(start 401.376642 -119.799862)
		(end 401.017994 -119.441214)
		(width 0.0889)
		(layer "In9.Cu")
		(net "USB3_P01_TXP")
	)
	(segment
		(start 397.2433 -118.6815)
		(end 397.2433 -118.648734)
		(width 0.0889)
		(layer "In9.Cu")
		(net "USB3_P01_TXP")
	)
	(segment
		(start 401.834096 -120.033288)
		(end 401.8153 -120.021604)
		(width 0.0889)
		(layer "In9.Cu")
		(net "USB3_P01_TXP")
	)
	(segment
		(start 423.97807 -78.59522)
		(end 423.361612 -81.20126)
		(width 0.1143)
		(layer "In9.Cu")
		(net "USB3_P01_TXP")
	)
	(segment
		(start 410.446728 -121.351294)
		(end 409.776422 -121.529094)
		(width 0.1143)
		(layer "In9.Cu")
		(net "USB3_P01_TXP")
	)
	(segment
		(start 466.692996 -63.457836)
		(end 465.084922 -65.06591)
		(width 0.1143)
		(layer "In9.Cu")
		(net "USB3_P01_TXP")
	)
	(segment
		(start 423.53865 -85.440012)
		(end 424.21556 -87.58809)
		(width 0.1143)
		(layer "In9.Cu")
		(net "USB3_P01_TXP")
	)
	(segment
		(start 418.136578 -98.808032)
		(end 417.38931 -101.96195)
		(width 0.1143)
		(layer "In9.Cu")
		(net "USB3_P01_TXP")
	)
	(segment
		(start 423.981372 -88.577928)
		(end 423.980864 -88.577928)
		(width 0.1143)
		(layer "In9.Cu")
		(net "USB3_P01_TXP")
	)
	(segment
		(start 417.383976 -103.671878)
		(end 419.908482 -111.685578)
		(width 0.1143)
		(layer "In9.Cu")
		(net "USB3_P01_TXP")
	)
	(segment
		(start 423.33672 -68.128642)
		(end 423.33672 -76.558394)
		(width 0.1143)
		(layer "In9.Cu")
		(net "USB3_P01_TXP")
	)
	(segment
		(start 397.300196 -117.797072)
		(end 397.14805 -117.811804)
		(width 0.0889)
		(layer "In9.Cu")
		(net "USB3_P01_TXP")
	)
	(segment
		(start 401.8153 -120.021604)
		(end 401.74545 -120.03786)
		(width 0.0889)
		(layer "In9.Cu")
		(net "USB3_P01_TXP")
	)
	(segment
		(start 397.25854 -117.36578)
		(end 397.258794 -117.36578)
		(width 0.0889)
		(layer "In9.Cu")
		(net "USB3_P01_TXP")
	)
	(segment
		(start 414.80359 -117.319044)
		(end 413.328358 -118.197376)
		(width 0.1143)
		(layer "In9.Cu")
		(net "USB3_P01_TXP")
	)
	(segment
		(start 401.742148 -120.036082)
		(end 401.740878 -120.03532)
		(width 0.0889)
		(layer "In9.Cu")
		(net "USB3_P01_TXP")
	)
	(segment
		(start 413.328358 -118.197376)
		(end 412.88462 -119.452644)
		(width 0.1143)
		(layer "In9.Cu")
		(net "USB3_P01_TXP")
	)
	(segment
		(start 412.88462 -119.452644)
		(end 413.036766 -119.950738)
		(width 0.1143)
		(layer "In9.Cu")
		(net "USB3_P01_TXP")
	)
	(segment
		(start 417.548568 -102.466902)
		(end 417.617402 -102.68585)
		(width 0.1143)
		(layer "In9.Cu")
		(net "USB3_P01_TXP")
	)
	(segment
		(start 465.084922 -65.06591)
		(end 426.399452 -65.06591)
		(width 0.1143)
		(layer "In9.Cu")
		(net "USB3_P01_TXP")
	)
	(segment
		(start 469.281764 -63.457836)
		(end 466.692996 -63.457836)
		(width 0.1143)
		(layer "In9.Cu")
		(net "USB3_P01_TXP")
	)
	(segment
		(start 401.74545 -120.03786)
		(end 401.745196 -120.03786)
		(width 0.0889)
		(layer "In9.Cu")
		(net "USB3_P01_TXP")
	)
	(segment
		(start 409.776422 -121.529094)
		(end 406.18029 -120.341136)
		(width 0.1143)
		(layer "In9.Cu")
		(net "USB3_P01_TXP")
	)
	(segment
		(start 417.503356 -102.3239)
		(end 417.50361 -102.324154)
		(width 0.1143)
		(layer "In9.Cu")
		(net "USB3_P01_TXP")
	)
	(segment
		(start 398.834102 -119.01678)
		(end 398.833848 -119.017034)
		(width 0.0889)
		(layer "In9.Cu")
		(net "USB3_P01_TXP")
	)
	(segment
		(start 419.441884 -115.273074)
		(end 418.342318 -117.02923)
		(width 0.1143)
		(layer "In9.Cu")
		(net "USB3_P01_TXP")
	)
	(segment
		(start 419.521894 -112.906302)
		(end 419.851332 -113.973102)
		(width 0.1143)
		(layer "In9.Cu")
		(net "USB3_P01_TXP")
	)
	(segment
		(start 416.02406 -117.72138)
		(end 414.80359 -117.319044)
		(width 0.1143)
		(layer "In9.Cu")
		(net "USB3_P01_TXP")
	)
	(segment
		(start 423.7101 -89.723976)
		(end 424.560492 -92.422472)
		(width 0.1143)
		(layer "In9.Cu")
		(net "USB3_P01_TXP")
	)
	(segment
		(start 406.18029 -120.341136)
		(end 405.201882 -120.683528)
		(width 0.1143)
		(layer "In9.Cu")
		(net "USB3_P01_TXP")
	)
	(segment
		(start 400.703542 -119.126508)
		(end 400.515074 -118.93804)
		(width 0.0889)
		(layer "In9.Cu")
		(net "USB3_P01_TXP")
	)
	(segment
		(start 423.155618 -96.80321)
		(end 421.29583 -96.80321)
		(width 0.1143)
		(layer "In9.Cu")
		(net "USB3_P01_TXP")
	)
	(segment
		(start 419.851332 -113.973102)
		(end 419.441884 -115.273074)
		(width 0.1143)
		(layer "In9.Cu")
		(net "USB3_P01_TXP")
	)
	(segment
		(start 399.395696 -118.93804)
		(end 399.128996 -118.93804)
		(width 0.0889)
		(layer "In9.Cu")
		(net "USB3_P01_TXP")
	)
	(segment
		(start 401.745196 -120.03786)
		(end 401.743418 -120.036082)
		(width 0.0889)
		(layer "In9.Cu")
		(net "USB3_P01_TXP")
	)
	(segment
		(start 424.039792 -88.330532)
		(end 423.981372 -88.577928)
		(width 0.1143)
		(layer "In9.Cu")
		(net "USB3_P01_TXP")
	)
	(segment
		(start 423.980864 -88.577928)
		(end 423.7101 -89.723976)
		(width 0.1143)
		(layer "In9.Cu")
		(net "USB3_P01_TXP")
	)
	(segment
		(start 401.017994 -119.31523)
		(end 400.829272 -119.126508)
		(width 0.0889)
		(layer "In9.Cu")
		(net "USB3_P01_TXP")
	)
	(segment
		(start 402.587714 -120.504204)
		(end 401.834096 -120.033288)
		(width 0.1143)
		(layer "In9.Cu")
		(net "USB3_P01_TXP")
	)
	(arc
		(start 396.948152 -118.158514)
		(mid 396.804348 -118.016831)
		(end 396.748 -117.82298)
		(width 0.0889)
		(layer "In9.Cu")
		(net "USB3_P01_TXP")
	)
	(arc
		(start 397.2433 -118.648734)
		(mid 397.159019 -118.365517)
		(end 396.948152 -118.158514)
		(width 0.0889)
		(layer "In9.Cu")
		(net "USB3_P01_TXP")
	)
	(arc
		(start 396.948152 -117.465094)
		(mid 397.098034 -117.398843)
		(end 397.25854 -117.36578)
		(width 0.0889)
		(layer "In9.Cu")
		(net "USB3_P01_TXP")
	)
	(arc
		(start 397.258794 -117.36578)
		(mid 397.417379 -117.414214)
		(end 397.495268 -117.560598)
		(width 0.0889)
		(layer "In9.Cu")
		(net "USB3_P01_TXP")
	)
	(arc
		(start 398.434052 -119.017034)
		(mid 398.13865 -118.937903)
		(end 397.843248 -119.017034)
		(width 0.0889)
		(layer "In9.Cu")
		(net "USB3_P01_TXP")
	)
	(arc
		(start 398.833848 -119.017034)
		(mid 398.63395 -119.070533)
		(end 398.434052 -119.017034)
		(width 0.0889)
		(layer "In9.Cu")
		(net "USB3_P01_TXP")
	)
	(arc
		(start 397.495268 -117.560598)
		(mid 397.446754 -117.719281)
		(end 397.300196 -117.797072)
		(width 0.0889)
		(layer "In9.Cu")
		(net "USB3_P01_TXP")
	)
	(arc
		(start 397.843248 -119.017034)
		(mid 397.448001 -119.019617)
		(end 397.2433 -118.6815)
		(width 0.0889)
		(layer "In9.Cu")
		(net "USB3_P01_TXP")
	)
	(arc
		(start 399.128996 -118.93804)
		(mid 398.976361 -118.958165)
		(end 398.834102 -119.017034)
		(width 0.0889)
		(layer "In9.Cu")
		(net "USB3_P01_TXP")
	)
	(arc
		(start 396.748 -117.800628)
		(mid 396.80435 -117.606778)
		(end 396.948152 -117.465094)
		(width 0.0889)
		(layer "In9.Cu")
		(net "USB3_P01_TXP")
	)
	(segment
		(start 397.470376 -116.87302)
		(end 397.558768 -116.913914)
		(width 0.1143)
		(layer "F.Cu")
		(net "USB3_P01_TXN")
	)
	(segment
		(start 397.14805 -116.72316)
		(end 397.470376 -116.87302)
		(width 0.1143)
		(layer "F.Cu")
		(net "USB3_P01_TXN")
	)
	(segment
		(start 397.558768 -116.913914)
		(end 397.64335 -116.953284)
		(width 0.1143)
		(layer "F.Cu")
		(net "USB3_P01_TXN")
	)
	(via
		(at 397.64335 -116.953284)
		(size 0.508)
		(drill 0.254)
		(layers "F.Cu" "B.Cu")
		(net "USB3_P01_TXN")
	)
	(via
		(at 469.015318 -64.389)
		(size 0.508)
		(drill 0.254)
		(layers "F.Cu" "B.Cu")
		(net "USB3_P01_TXN")
	)
	(segment
		(start 475.53245 -65.517014)
		(end 477.554036 -64.91732)
		(width 0.1143)
		(layer "B.Cu")
		(net "USB3_P01_TXN")
	)
	(segment
		(start 470.137998 -66.373502)
		(end 472.42603 -66.901568)
		(width 0.1143)
		(layer "B.Cu")
		(net "USB3_P01_TXN")
	)
	(segment
		(start 481.801424 -61.7855)
		(end 483.418642 -61.414914)
		(width 0.1143)
		(layer "B.Cu")
		(net "USB3_P01_TXN")
	)
	(segment
		(start 473.93225 -66.554096)
		(end 475.53245 -65.517014)
		(width 0.1143)
		(layer "B.Cu")
		(net "USB3_P01_TXN")
	)
	(segment
		(start 477.554036 -64.91732)
		(end 479.189542 -62.299088)
		(width 0.1143)
		(layer "B.Cu")
		(net "USB3_P01_TXN")
	)
	(segment
		(start 479.189542 -62.299088)
		(end 479.781362 -61.928756)
		(width 0.1143)
		(layer "B.Cu")
		(net "USB3_P01_TXN")
	)
	(segment
		(start 469.015318 -64.389)
		(end 469.288368 -64.66205)
		(width 0.1143)
		(layer "B.Cu")
		(net "USB3_P01_TXN")
	)
	(segment
		(start 469.288368 -64.66205)
		(end 469.288368 -65.013332)
		(width 0.1143)
		(layer "B.Cu")
		(net "USB3_P01_TXN")
	)
	(segment
		(start 469.288368 -65.013332)
		(end 470.137998 -66.373502)
		(width 0.1143)
		(layer "B.Cu")
		(net "USB3_P01_TXN")
	)
	(segment
		(start 472.42603 -66.901822)
		(end 473.93225 -66.554096)
		(width 0.1143)
		(layer "B.Cu")
		(net "USB3_P01_TXN")
	)
	(segment
		(start 483.418642 -61.414914)
		(end 484.819452 -60.539122)
		(width 0.1143)
		(layer "B.Cu")
		(net "USB3_P01_TXN")
	)
	(segment
		(start 479.781362 -61.928756)
		(end 481.101908 -61.62421)
		(width 0.1143)
		(layer "B.Cu")
		(net "USB3_P01_TXN")
	)
	(segment
		(start 484.819452 -60.539122)
		(end 484.97617 -60.539122)
		(width 0.1143)
		(layer "B.Cu")
		(net "USB3_P01_TXN")
	)
	(segment
		(start 472.42603 -66.901568)
		(end 472.42603 -66.901822)
		(width 0.1143)
		(layer "B.Cu")
		(net "USB3_P01_TXN")
	)
	(segment
		(start 484.97617 -60.539122)
		(end 485.25938 -60.822332)
		(width 0.1143)
		(layer "B.Cu")
		(net "USB3_P01_TXN")
	)
	(segment
		(start 481.101908 -61.62421)
		(end 481.801424 -61.7855)
		(width 0.1143)
		(layer "B.Cu")
		(net "USB3_P01_TXN")
	)
	(segment
		(start 404.496016 -120.815354)
		(end 403.686772 -121.058178)
		(width 0.1143)
		(layer "In9.Cu")
		(net "USB3_P01_TXN")
	)
	(segment
		(start 419.828218 -112.907318)
		(end 420.157402 -113.973864)
		(width 0.1143)
		(layer "In9.Cu")
		(net "USB3_P01_TXN")
	)
	(segment
		(start 402.474176 -120.778016)
		(end 401.679156 -120.280938)
		(width 0.1143)
		(layer "In9.Cu")
		(net "USB3_P01_TXN")
	)
	(segment
		(start 418.531548 -117.277642)
		(end 418.531548 -117.277896)
		(width 0.1143)
		(layer "In9.Cu")
		(net "USB3_P01_TXN")
	)
	(segment
		(start 424.863514 -92.411296)
		(end 423.849038 -96.69907)
		(width 0.1143)
		(layer "In9.Cu")
		(net "USB3_P01_TXN")
	)
	(segment
		(start 469.160606 -63.749936)
		(end 466.814154 -63.749936)
		(width 0.1143)
		(layer "In9.Cu")
		(net "USB3_P01_TXN")
	)
	(segment
		(start 406.805638 -121.029222)
		(end 406.700736 -120.820688)
		(width 0.1143)
		(layer "In9.Cu")
		(net "USB3_P01_TXN")
	)
	(segment
		(start 424.013122 -89.7128)
		(end 424.863514 -92.411296)
		(width 0.1143)
		(layer "In9.Cu")
		(net "USB3_P01_TXN")
	)
	(segment
		(start 423.664634 -81.190084)
		(end 424.338496 -83.328256)
		(width 0.1143)
		(layer "In9.Cu")
		(net "USB3_P01_TXN")
	)
	(segment
		(start 420.21506 -111.685832)
		(end 419.828218 -112.907318)
		(width 0.1143)
		(layer "In9.Cu")
		(net "USB3_P01_TXN")
	)
	(segment
		(start 407.131266 -121.136918)
		(end 406.805638 -121.029222)
		(width 0.1143)
		(layer "In9.Cu")
		(net "USB3_P01_TXN")
	)
	(segment
		(start 469.3539 -64.280034)
		(end 469.3539 -63.94323)
		(width 0.1143)
		(layer "In9.Cu")
		(net "USB3_P01_TXN")
	)
	(segment
		(start 397.0528 -118.691914)
		(end 397.0528 -118.659148)
		(width 0.0889)
		(layer "In9.Cu")
		(net "USB3_P01_TXN")
	)
	(segment
		(start 409.06065 -121.774458)
		(end 408.735276 -121.666762)
		(width 0.1143)
		(layer "In9.Cu")
		(net "USB3_P01_TXN")
	)
	(segment
		(start 424.281092 -78.584044)
		(end 423.664634 -81.190084)
		(width 0.1143)
		(layer "In9.Cu")
		(net "USB3_P01_TXN")
	)
	(segment
		(start 420.157402 -113.973864)
		(end 419.709346 -115.396518)
		(width 0.1143)
		(layer "In9.Cu")
		(net "USB3_P01_TXN")
	)
	(segment
		(start 412.846774 -121.429272)
		(end 411.477206 -121.904506)
		(width 0.1143)
		(layer "In9.Cu")
		(net "USB3_P01_TXN")
	)
	(segment
		(start 423.841672 -85.428836)
		(end 424.518582 -87.576914)
		(width 0.1143)
		(layer "In9.Cu")
		(net "USB3_P01_TXN")
	)
	(segment
		(start 413.192214 -119.459248)
		(end 413.343598 -119.955056)
		(width 0.1143)
		(layer "In9.Cu")
		(net "USB3_P01_TXN")
	)
	(segment
		(start 408.095958 -121.455688)
		(end 407.770584 -121.347992)
		(width 0.1143)
		(layer "In9.Cu")
		(net "USB3_P01_TXN")
	)
	(segment
		(start 423.24274 -97.09531)
		(end 421.38092 -97.09531)
		(width 0.1143)
		(layer "In9.Cu")
		(net "USB3_P01_TXN")
	)
	(segment
		(start 421.38092 -97.09531)
		(end 418.393626 -98.991166)
		(width 0.1143)
		(layer "In9.Cu")
		(net "USB3_P01_TXN")
	)
	(segment
		(start 408.63012 -121.458228)
		(end 408.304492 -121.350786)
		(width 0.1143)
		(layer "In9.Cu")
		(net "USB3_P01_TXN")
	)
	(segment
		(start 469.015318 -64.389)
		(end 469.244934 -64.389)
		(width 0.1143)
		(layer "In9.Cu")
		(net "USB3_P01_TXN")
	)
	(segment
		(start 417.920424 -102.674928)
		(end 417.686998 -103.660956)
		(width 0.1143)
		(layer "In9.Cu")
		(net "USB3_P01_TXN")
	)
	(segment
		(start 417.686998 -103.660956)
		(end 420.21506 -111.685832)
		(width 0.1143)
		(layer "In9.Cu")
		(net "USB3_P01_TXN")
	)
	(segment
		(start 407.665428 -121.139458)
		(end 407.3398 -121.032016)
		(width 0.1143)
		(layer "In9.Cu")
		(net "USB3_P01_TXN")
	)
	(segment
		(start 403.686772 -121.058178)
		(end 402.474176 -120.778016)
		(width 0.1143)
		(layer "In9.Cu")
		(net "USB3_P01_TXN")
	)
	(segment
		(start 401.256246 -119.94896)
		(end 400.435826 -119.12854)
		(width 0.0889)
		(layer "In9.Cu")
		(net "USB3_P01_TXN")
	)
	(segment
		(start 407.770584 -121.347992)
		(end 407.665428 -121.139458)
		(width 0.1143)
		(layer "In9.Cu")
		(net "USB3_P01_TXN")
	)
	(segment
		(start 424.518582 -87.576914)
		(end 424.013122 -89.7128)
		(width 0.1143)
		(layer "In9.Cu")
		(net "USB3_P01_TXN")
	)
	(segment
		(start 401.66036 -120.269254)
		(end 401.644358 -120.199658)
		(width 0.0889)
		(layer "In9.Cu")
		(net "USB3_P01_TXN")
	)
	(segment
		(start 423.849038 -96.69907)
		(end 423.24274 -97.09531)
		(width 0.1143)
		(layer "In9.Cu")
		(net "USB3_P01_TXN")
	)
	(segment
		(start 411.477206 -121.904506)
		(end 410.449522 -121.652792)
		(width 0.1143)
		(layer "In9.Cu")
		(net "USB3_P01_TXN")
	)
	(segment
		(start 405.217376 -120.987566)
		(end 404.496016 -120.815354)
		(width 0.1143)
		(layer "In9.Cu")
		(net "USB3_P01_TXN")
	)
	(segment
		(start 406.183084 -120.649746)
		(end 405.217376 -120.987566)
		(width 0.1143)
		(layer "In9.Cu")
		(net "USB3_P01_TXN")
	)
	(segment
		(start 409.767278 -121.833894)
		(end 409.269438 -121.669302)
		(width 0.1143)
		(layer "In9.Cu")
		(net "USB3_P01_TXN")
	)
	(segment
		(start 423.62882 -68.2498)
		(end 423.62882 -76.513436)
		(width 0.1143)
		(layer "In9.Cu")
		(net "USB3_P01_TXN")
	)
	(segment
		(start 418.393626 -98.991166)
		(end 417.692332 -101.951028)
		(width 0.1143)
		(layer "In9.Cu")
		(net "USB3_P01_TXN")
	)
	(segment
		(start 413.568642 -118.39448)
		(end 413.192214 -119.459248)
		(width 0.1143)
		(layer "In9.Cu")
		(net "USB3_P01_TXN")
	)
	(segment
		(start 466.814154 -63.749936)
		(end 465.20608 -65.35801)
		(width 0.1143)
		(layer "In9.Cu")
		(net "USB3_P01_TXN")
	)
	(segment
		(start 417.692332 -101.951028)
		(end 417.920424 -102.674928)
		(width 0.1143)
		(layer "In9.Cu")
		(net "USB3_P01_TXN")
	)
	(segment
		(start 410.449522 -121.652792)
		(end 409.767278 -121.833894)
		(width 0.1143)
		(layer "In9.Cu")
		(net "USB3_P01_TXN")
	)
	(segment
		(start 469.3539 -63.94323)
		(end 469.160606 -63.749936)
		(width 0.1143)
		(layer "In9.Cu")
		(net "USB3_P01_TXN")
	)
	(segment
		(start 416.019742 -118.027704)
		(end 414.838642 -117.638322)
		(width 0.1143)
		(layer "In9.Cu")
		(net "USB3_P01_TXN")
	)
	(segment
		(start 401.679156 -120.280938)
		(end 401.66036 -120.269254)
		(width 0.0889)
		(layer "In9.Cu")
		(net "USB3_P01_TXN")
	)
	(segment
		(start 406.700736 -120.820688)
		(end 406.183084 -120.649746)
		(width 0.1143)
		(layer "In9.Cu")
		(net "USB3_P01_TXN")
	)
	(segment
		(start 414.838642 -117.638322)
		(end 413.568642 -118.39448)
		(width 0.1143)
		(layer "In9.Cu")
		(net "USB3_P01_TXN")
	)
	(segment
		(start 424.338496 -83.328256)
		(end 423.841672 -85.428836)
		(width 0.1143)
		(layer "In9.Cu")
		(net "USB3_P01_TXN")
	)
	(segment
		(start 408.735276 -121.666762)
		(end 408.63012 -121.458228)
		(width 0.1143)
		(layer "In9.Cu")
		(net "USB3_P01_TXN")
	)
	(segment
		(start 418.531548 -117.277896)
		(end 416.019742 -118.027704)
		(width 0.1143)
		(layer "In9.Cu")
		(net "USB3_P01_TXN")
	)
	(segment
		(start 400.435826 -119.12854)
		(end 399.12925 -119.12854)
		(width 0.0889)
		(layer "In9.Cu")
		(net "USB3_P01_TXN")
	)
	(segment
		(start 401.641818 -120.198134)
		(end 401.256246 -119.94896)
		(width 0.0889)
		(layer "In9.Cu")
		(net "USB3_P01_TXN")
	)
	(segment
		(start 401.644358 -120.199658)
		(end 401.641818 -120.198134)
		(width 0.0889)
		(layer "In9.Cu")
		(net "USB3_P01_TXN")
	)
	(segment
		(start 396.5575 -117.833394)
		(end 396.5575 -117.790214)
		(width 0.0889)
		(layer "In9.Cu")
		(net "USB3_P01_TXN")
	)
	(segment
		(start 408.304492 -121.350786)
		(end 408.095958 -121.455688)
		(width 0.1143)
		(layer "In9.Cu")
		(net "USB3_P01_TXN")
	)
	(segment
		(start 469.244934 -64.389)
		(end 469.3539 -64.280034)
		(width 0.1143)
		(layer "In9.Cu")
		(net "USB3_P01_TXN")
	)
	(segment
		(start 426.52061 -65.35801)
		(end 423.62882 -68.2498)
		(width 0.1143)
		(layer "In9.Cu")
		(net "USB3_P01_TXN")
	)
	(segment
		(start 465.20608 -65.35801)
		(end 426.52061 -65.35801)
		(width 0.1143)
		(layer "In9.Cu")
		(net "USB3_P01_TXN")
	)
	(segment
		(start 423.62882 -76.513436)
		(end 424.281092 -78.584044)
		(width 0.1143)
		(layer "In9.Cu")
		(net "USB3_P01_TXN")
	)
	(segment
		(start 407.3398 -121.032016)
		(end 407.131266 -121.136918)
		(width 0.1143)
		(layer "In9.Cu")
		(net "USB3_P01_TXN")
	)
	(segment
		(start 413.343598 -119.955056)
		(end 412.846774 -121.429272)
		(width 0.1143)
		(layer "In9.Cu")
		(net "USB3_P01_TXN")
	)
	(segment
		(start 409.269438 -121.669302)
		(end 409.06065 -121.774458)
		(width 0.1143)
		(layer "In9.Cu")
		(net "USB3_P01_TXN")
	)
	(segment
		(start 419.709346 -115.396518)
		(end 418.531548 -117.277642)
		(width 0.1143)
		(layer "In9.Cu")
		(net "USB3_P01_TXN")
	)
	(arc
		(start 396.852648 -117.299994)
		(mid 397.238436 -117.10483)
		(end 397.64335 -116.953284)
		(width 0.0889)
		(layer "In9.Cu")
		(net "USB3_P01_TXN")
	)
	(arc
		(start 397.0528 -118.659148)
		(mid 396.99645 -118.465298)
		(end 396.852648 -118.323614)
		(width 0.0889)
		(layer "In9.Cu")
		(net "USB3_P01_TXN")
	)
	(arc
		(start 396.5575 -117.790214)
		(mid 396.641781 -117.506997)
		(end 396.852648 -117.299994)
		(width 0.0889)
		(layer "In9.Cu")
		(net "USB3_P01_TXN")
	)
	(arc
		(start 398.338548 -119.182134)
		(mid 398.13865 -119.128635)
		(end 397.938752 -119.182134)
		(width 0.0889)
		(layer "In9.Cu")
		(net "USB3_P01_TXN")
	)
	(arc
		(start 397.938752 -119.182134)
		(mid 397.357244 -119.187388)
		(end 397.0528 -118.691914)
		(width 0.0889)
		(layer "In9.Cu")
		(net "USB3_P01_TXN")
	)
	(arc
		(start 399.12925 -119.12854)
		(mid 399.025784 -119.14221)
		(end 398.929352 -119.182134)
		(width 0.0889)
		(layer "In9.Cu")
		(net "USB3_P01_TXN")
	)
	(arc
		(start 398.929352 -119.182134)
		(mid 398.63395 -119.261265)
		(end 398.338548 -119.182134)
		(width 0.0889)
		(layer "In9.Cu")
		(net "USB3_P01_TXN")
	)
	(arc
		(start 396.852648 -118.323614)
		(mid 396.641784 -118.11661)
		(end 396.5575 -117.833394)
		(width 0.0889)
		(layer "In9.Cu")
		(net "USB3_P01_TXN")
	)
	(segment
		(start 396.7988 -125.81128)
		(end 396.729966 -125.97765)
		(width 0.0889)
		(layer "F.Cu")
		(net "USB3_P01_RXP")
	)
	(segment
		(start 396.69593 -125.485652)
		(end 396.713964 -125.533912)
		(width 0.0889)
		(layer "F.Cu")
		(net "USB3_P01_RXP")
	)
	(segment
		(start 396.729966 -125.97765)
		(end 396.545308 -126.162308)
		(width 0.0889)
		(layer "F.Cu")
		(net "USB3_P01_RXP")
	)
	(segment
		(start 396.545308 -127.679196)
		(end 396.711678 -127.845566)
		(width 0.0889)
		(layer "F.Cu")
		(net "USB3_P01_RXP")
	)
	(segment
		(start 396.656814 -125.38075)
		(end 396.69593 -125.485652)
		(width 0.0889)
		(layer "F.Cu")
		(net "USB3_P01_RXP")
	)
	(segment
		(start 396.711678 -127.845566)
		(end 397.51 -127.845566)
		(width 0.0889)
		(layer "F.Cu")
		(net "USB3_P01_RXP")
	)
	(segment
		(start 396.713964 -125.533912)
		(end 396.7988 -125.618748)
		(width 0.0889)
		(layer "F.Cu")
		(net "USB3_P01_RXP")
	)
	(segment
		(start 396.545308 -126.162308)
		(end 396.545308 -127.679196)
		(width 0.0889)
		(layer "F.Cu")
		(net "USB3_P01_RXP")
	)
	(segment
		(start 396.7988 -125.618748)
		(end 396.7988 -125.81128)
		(width 0.0889)
		(layer "F.Cu")
		(net "USB3_P01_RXP")
	)
	(segment
		(start 396.48511 -124.919994)
		(end 396.656814 -125.38075)
		(width 0.0889)
		(layer "F.Cu")
		(net "USB3_P01_RXP")
	)
	(via
		(at 397.51 -127.845566)
		(size 0.508)
		(drill 0.254)
		(layers "F.Cu" "B.Cu")
		(net "USB3_P01_RXP")
	)
	(via
		(at 482.439726 -60.20181)
		(size 0.508)
		(drill 0.254)
		(layers "F.Cu" "B.Cu")
		(net "USB3_P01_RXP")
	)
	(via
		(at 472.03868 -64.4398)
		(size 0.508)
		(drill 0.254)
		(layers "F.Cu" "B.Cu")
		(net "USB3_P01_RXP")
	)
	(segment
		(start 471.983562 -65.294002)
		(end 471.78849 -65.172082)
		(width 0.1143)
		(layer "B.Cu")
		(net "USB3_P01_RXP")
	)
	(segment
		(start 484.22941 -58.461402)
		(end 483.904798 -58.786014)
		(width 0.1143)
		(layer "B.Cu")
		(net "USB3_P01_RXP")
	)
	(segment
		(start 471.67038 -64.98336)
		(end 471.67038 -64.74714)
		(width 0.1143)
		(layer "B.Cu")
		(net "USB3_P01_RXP")
	)
	(segment
		(start 479.566986 -60.55995)
		(end 479.232976 -60.637166)
		(width 0.1143)
		(layer "B.Cu")
		(net "USB3_P01_RXP")
	)
	(segment
		(start 473.201492 -65.1637)
		(end 473.064332 -65.078102)
		(width 0.1143)
		(layer "B.Cu")
		(net "USB3_P01_RXP")
	)
	(segment
		(start 482.439472 -60.201302)
		(end 481.692966 -60.373514)
		(width 0.1143)
		(layer "B.Cu")
		(net "USB3_P01_RXP")
	)
	(segment
		(start 483.904798 -59.215782)
		(end 483.615492 -59.678062)
		(width 0.1143)
		(layer "B.Cu")
		(net "USB3_P01_RXP")
	)
	(segment
		(start 478.37979 -61.035184)
		(end 478.343468 -61.192664)
		(width 0.1143)
		(layer "B.Cu")
		(net "USB3_P01_RXP")
	)
	(segment
		(start 473.064332 -65.078102)
		(end 472.730322 -65.155064)
		(width 0.1143)
		(layer "B.Cu")
		(net "USB3_P01_RXP")
	)
	(segment
		(start 473.803726 -65.024508)
		(end 473.201492 -65.1637)
		(width 0.1143)
		(layer "B.Cu")
		(net "USB3_P01_RXP")
	)
	(segment
		(start 471.67038 -64.74714)
		(end 471.97772 -64.4398)
		(width 0.1143)
		(layer "B.Cu")
		(net "USB3_P01_RXP")
	)
	(segment
		(start 483.615492 -59.678062)
		(end 482.974142 -60.078874)
		(width 0.1143)
		(layer "B.Cu")
		(net "USB3_P01_RXP")
	)
	(segment
		(start 471.97772 -64.4398)
		(end 472.03868 -64.4398)
		(width 0.1143)
		(layer "B.Cu")
		(net "USB3_P01_RXP")
	)
	(segment
		(start 472.730322 -65.155064)
		(end 472.64447 -65.292224)
		(width 0.1143)
		(layer "B.Cu")
		(net "USB3_P01_RXP")
	)
	(segment
		(start 478.052638 -61.374274)
		(end 476.571818 -63.744094)
		(width 0.1143)
		(layer "B.Cu")
		(net "USB3_P01_RXP")
	)
	(segment
		(start 482.867462 -60.103512)
		(end 482.439726 -60.20181)
		(width 0.1143)
		(layer "B.Cu")
		(net "USB3_P01_RXP")
	)
	(segment
		(start 479.232976 -60.637166)
		(end 478.828354 -60.889896)
		(width 0.1143)
		(layer "B.Cu")
		(net "USB3_P01_RXP")
	)
	(segment
		(start 472.64447 -65.292224)
		(end 472.31046 -65.36944)
		(width 0.1143)
		(layer "B.Cu")
		(net "USB3_P01_RXP")
	)
	(segment
		(start 476.571818 -63.744094)
		(end 475.10954 -64.177926)
		(width 0.1143)
		(layer "B.Cu")
		(net "USB3_P01_RXP")
	)
	(segment
		(start 478.67062 -60.853574)
		(end 478.37979 -61.035184)
		(width 0.1143)
		(layer "B.Cu")
		(net "USB3_P01_RXP")
	)
	(segment
		(start 478.828354 -60.889896)
		(end 478.67062 -60.853574)
		(width 0.1143)
		(layer "B.Cu")
		(net "USB3_P01_RXP")
	)
	(segment
		(start 478.343468 -61.192664)
		(end 478.052638 -61.374274)
		(width 0.1143)
		(layer "B.Cu")
		(net "USB3_P01_RXP")
	)
	(segment
		(start 481.033582 -60.221368)
		(end 480.124008 -60.431426)
		(width 0.1143)
		(layer "B.Cu")
		(net "USB3_P01_RXP")
	)
	(segment
		(start 480.124008 -60.431426)
		(end 479.986848 -60.345828)
		(width 0.1143)
		(layer "B.Cu")
		(net "USB3_P01_RXP")
	)
	(segment
		(start 481.692966 -60.373514)
		(end 481.033582 -60.221368)
		(width 0.1143)
		(layer "B.Cu")
		(net "USB3_P01_RXP")
	)
	(segment
		(start 479.652838 -60.423044)
		(end 479.566986 -60.55995)
		(width 0.1143)
		(layer "B.Cu")
		(net "USB3_P01_RXP")
	)
	(segment
		(start 484.880158 -58.103262)
		(end 484.522018 -58.461402)
		(width 0.1143)
		(layer "B.Cu")
		(net "USB3_P01_RXP")
	)
	(segment
		(start 482.439726 -60.20181)
		(end 482.439472 -60.201302)
		(width 0.1143)
		(layer "B.Cu")
		(net "USB3_P01_RXP")
	)
	(segment
		(start 471.78849 -65.172082)
		(end 471.67038 -64.98336)
		(width 0.1143)
		(layer "B.Cu")
		(net "USB3_P01_RXP")
	)
	(segment
		(start 485.58577 -58.103262)
		(end 484.880158 -58.103262)
		(width 0.1143)
		(layer "B.Cu")
		(net "USB3_P01_RXP")
	)
	(segment
		(start 482.974142 -60.078874)
		(end 482.867462 -60.103512)
		(width 0.1143)
		(layer "B.Cu")
		(net "USB3_P01_RXP")
	)
	(segment
		(start 472.31046 -65.36944)
		(end 471.983562 -65.294002)
		(width 0.1143)
		(layer "B.Cu")
		(net "USB3_P01_RXP")
	)
	(segment
		(start 479.986848 -60.345828)
		(end 479.652838 -60.423044)
		(width 0.1143)
		(layer "B.Cu")
		(net "USB3_P01_RXP")
	)
	(segment
		(start 475.10954 -64.177926)
		(end 473.803726 -65.024508)
		(width 0.1143)
		(layer "B.Cu")
		(net "USB3_P01_RXP")
	)
	(segment
		(start 484.522018 -58.461402)
		(end 484.22941 -58.461402)
		(width 0.1143)
		(layer "B.Cu")
		(net "USB3_P01_RXP")
	)
	(segment
		(start 483.904798 -58.786014)
		(end 483.904798 -59.215782)
		(width 0.1143)
		(layer "B.Cu")
		(net "USB3_P01_RXP")
	)
	(segment
		(start 421.223186 -113.914428)
		(end 420.623746 -115.818412)
		(width 0.1143)
		(layer "In9.Cu")
		(net "USB3_P01_RXP")
	)
	(segment
		(start 424.995848 -89.642442)
		(end 425.862496 -92.39123)
		(width 0.1143)
		(layer "In9.Cu")
		(net "USB3_P01_RXP")
	)
	(segment
		(start 414.335976 -119.953786)
		(end 413.545782 -122.300238)
		(width 0.1143)
		(layer "In9.Cu")
		(net "USB3_P01_RXP")
	)
	(segment
		(start 472.03868 -64.4398)
		(end 471.83548 -64.4398)
		(width 0.1143)
		(layer "In9.Cu")
		(net "USB3_P01_RXP")
	)
	(segment
		(start 418.68979 -103.715058)
		(end 421.206168 -111.701326)
		(width 0.1143)
		(layer "In9.Cu")
		(net "USB3_P01_RXP")
	)
	(segment
		(start 413.215582 -123.797314)
		(end 413.00654 -123.900946)
		(width 0.1143)
		(layer "In9.Cu")
		(net "USB3_P01_RXP")
	)
	(segment
		(start 405.312372 -124.912374)
		(end 403.0599 -125.379988)
		(width 0.1143)
		(layer "In9.Cu")
		(net "USB3_P01_RXP")
	)
	(segment
		(start 471.72118 -64.5541)
		(end 471.72118 -65.076578)
		(width 0.1143)
		(layer "In9.Cu")
		(net "USB3_P01_RXP")
	)
	(segment
		(start 397.703802 -126.336806)
		(end 397.06804 -126.666244)
		(width 0.1143)
		(layer "In9.Cu")
		(net "USB3_P01_RXP")
	)
	(segment
		(start 397.27505 -128.080516)
		(end 397.51 -127.845566)
		(width 0.1143)
		(layer "In9.Cu")
		(net "USB3_P01_RXP")
	)
	(segment
		(start 424.692064 -97.335594)
		(end 423.619422 -98.037142)
		(width 0.1143)
		(layer "In9.Cu")
		(net "USB3_P01_RXP")
	)
	(segment
		(start 396.938754 -127.872998)
		(end 396.981172 -127.986282)
		(width 0.1143)
		(layer "In9.Cu")
		(net "USB3_P01_RXP")
	)
	(segment
		(start 414.34893 -119.054626)
		(end 414.19526 -119.483378)
		(width 0.1143)
		(layer "In9.Cu")
		(net "USB3_P01_RXP")
	)
	(segment
		(start 402.20646 -125.08992)
		(end 400.495262 -125.678692)
		(width 0.1143)
		(layer "In9.Cu")
		(net "USB3_P01_RXP")
	)
	(segment
		(start 424.885358 -80.114648)
		(end 424.652694 -81.097882)
		(width 0.1143)
		(layer "In9.Cu")
		(net "USB3_P01_RXP")
	)
	(segment
		(start 412.802578 -124.506482)
		(end 410.519118 -125.520958)
		(width 0.1143)
		(layer "In9.Cu")
		(net "USB3_P01_RXP")
	)
	(segment
		(start 408.399742 -124.920756)
		(end 406.92578 -125.320806)
		(width 0.1143)
		(layer "In9.Cu")
		(net "USB3_P01_RXP")
	)
	(segment
		(start 425.285154 -78.42504)
		(end 424.885358 -80.11414)
		(width 0.1143)
		(layer "In9.Cu")
		(net "USB3_P01_RXP")
	)
	(segment
		(start 399.107914 -126.330964)
		(end 398.89811 -126.228348)
		(width 0.1143)
		(layer "In9.Cu")
		(net "USB3_P01_RXP")
	)
	(segment
		(start 415.939986 -119.07774)
		(end 414.918906 -118.73738)
		(width 0.1143)
		(layer "In9.Cu")
		(net "USB3_P01_RXP")
	)
	(segment
		(start 413.00654 -123.900946)
		(end 412.802578 -124.506482)
		(width 0.1143)
		(layer "In9.Cu")
		(net "USB3_P01_RXP")
	)
	(segment
		(start 419.250368 -99.614228)
		(end 418.689028 -101.985826)
		(width 0.1143)
		(layer "In9.Cu")
		(net "USB3_P01_RXP")
	)
	(segment
		(start 421.73525 -98.037142)
		(end 419.250368 -99.614228)
		(width 0.1143)
		(layer "In9.Cu")
		(net "USB3_P01_RXP")
	)
	(segment
		(start 400.3929 -125.88875)
		(end 400.068796 -126.000256)
		(width 0.1143)
		(layer "In9.Cu")
		(net "USB3_P01_RXP")
	)
	(segment
		(start 424.844464 -85.483192)
		(end 425.49318 -87.5411)
		(width 0.1143)
		(layer "In9.Cu")
		(net "USB3_P01_RXP")
	)
	(segment
		(start 471.72118 -65.076578)
		(end 470.499948 -66.29781)
		(width 0.1143)
		(layer "In9.Cu")
		(net "USB3_P01_RXP")
	)
	(segment
		(start 413.53994 -122.8344)
		(end 413.330898 -122.938286)
		(width 0.1143)
		(layer "In9.Cu")
		(net "USB3_P01_RXP")
	)
	(segment
		(start 418.689028 -101.985826)
		(end 418.923216 -102.72903)
		(width 0.1143)
		(layer "In9.Cu")
		(net "USB3_P01_RXP")
	)
	(segment
		(start 410.519118 -125.520958)
		(end 408.399742 -124.920756)
		(width 0.1143)
		(layer "In9.Cu")
		(net "USB3_P01_RXP")
	)
	(segment
		(start 413.330898 -122.938286)
		(end 413.221424 -123.263152)
		(width 0.1143)
		(layer "In9.Cu")
		(net "USB3_P01_RXP")
	)
	(segment
		(start 425.862496 -92.39123)
		(end 424.692064 -97.335594)
		(width 0.1143)
		(layer "In9.Cu")
		(net "USB3_P01_RXP")
	)
	(segment
		(start 399.534634 -126.0094)
		(end 399.432272 -126.219204)
		(width 0.1143)
		(layer "In9.Cu")
		(net "USB3_P01_RXP")
	)
	(segment
		(start 400.495262 -125.678692)
		(end 400.3929 -125.88875)
		(width 0.1143)
		(layer "In9.Cu")
		(net "USB3_P01_RXP")
	)
	(segment
		(start 423.619422 -98.037142)
		(end 421.73525 -98.037142)
		(width 0.1143)
		(layer "In9.Cu")
		(net "USB3_P01_RXP")
	)
	(segment
		(start 398.89811 -126.228348)
		(end 398.221708 -126.461266)
		(width 0.1143)
		(layer "In9.Cu")
		(net "USB3_P01_RXP")
	)
	(segment
		(start 470.499948 -66.29781)
		(end 426.910246 -66.29781)
		(width 0.1143)
		(layer "In9.Cu")
		(net "USB3_P01_RXP")
	)
	(segment
		(start 396.981172 -127.986282)
		(end 397.113252 -128.080516)
		(width 0.1143)
		(layer "In9.Cu")
		(net "USB3_P01_RXP")
	)
	(segment
		(start 414.918906 -118.73738)
		(end 414.34893 -119.054626)
		(width 0.1143)
		(layer "In9.Cu")
		(net "USB3_P01_RXP")
	)
	(segment
		(start 424.885358 -80.11414)
		(end 424.885358 -80.114648)
		(width 0.1143)
		(layer "In9.Cu")
		(net "USB3_P01_RXP")
	)
	(segment
		(start 396.937738 -127.288036)
		(end 396.938754 -127.872998)
		(width 0.1143)
		(layer "In9.Cu")
		(net "USB3_P01_RXP")
	)
	(segment
		(start 413.649414 -122.509534)
		(end 413.53994 -122.8344)
		(width 0.1143)
		(layer "In9.Cu")
		(net "USB3_P01_RXP")
	)
	(segment
		(start 413.221424 -123.263152)
		(end 413.325056 -123.472194)
		(width 0.1143)
		(layer "In9.Cu")
		(net "USB3_P01_RXP")
	)
	(segment
		(start 425.49318 -87.5411)
		(end 424.995848 -89.642442)
		(width 0.1143)
		(layer "In9.Cu")
		(net "USB3_P01_RXP")
	)
	(segment
		(start 424.652694 -81.097882)
		(end 425.355258 -83.325462)
		(width 0.1143)
		(layer "In9.Cu")
		(net "USB3_P01_RXP")
	)
	(segment
		(start 413.325056 -123.472194)
		(end 413.215582 -123.797314)
		(width 0.1143)
		(layer "In9.Cu")
		(net "USB3_P01_RXP")
	)
	(segment
		(start 471.83548 -64.4398)
		(end 471.72118 -64.5541)
		(width 0.1143)
		(layer "In9.Cu")
		(net "USB3_P01_RXP")
	)
	(segment
		(start 398.221708 -126.461266)
		(end 397.703802 -126.336806)
		(width 0.1143)
		(layer "In9.Cu")
		(net "USB3_P01_RXP")
	)
	(segment
		(start 397.113252 -128.080516)
		(end 397.27505 -128.080516)
		(width 0.1143)
		(layer "In9.Cu")
		(net "USB3_P01_RXP")
	)
	(segment
		(start 418.923216 -102.72903)
		(end 418.68979 -103.715058)
		(width 0.1143)
		(layer "In9.Cu")
		(net "USB3_P01_RXP")
	)
	(segment
		(start 425.355258 -83.325462)
		(end 424.844464 -85.483192)
		(width 0.1143)
		(layer "In9.Cu")
		(net "USB3_P01_RXP")
	)
	(segment
		(start 424.56862 -68.639436)
		(end 424.56862 -76.154026)
		(width 0.1143)
		(layer "In9.Cu")
		(net "USB3_P01_RXP")
	)
	(segment
		(start 419.15715 -118.15953)
		(end 415.939986 -119.07774)
		(width 0.1143)
		(layer "In9.Cu")
		(net "USB3_P01_RXP")
	)
	(segment
		(start 399.858992 -125.897894)
		(end 399.534634 -126.0094)
		(width 0.1143)
		(layer "In9.Cu")
		(net "USB3_P01_RXP")
	)
	(segment
		(start 426.910246 -66.29781)
		(end 424.56862 -68.639436)
		(width 0.1143)
		(layer "In9.Cu")
		(net "USB3_P01_RXP")
	)
	(segment
		(start 413.545782 -122.300238)
		(end 413.649414 -122.509534)
		(width 0.1143)
		(layer "In9.Cu")
		(net "USB3_P01_RXP")
	)
	(segment
		(start 406.92578 -125.320806)
		(end 405.312372 -124.912374)
		(width 0.1143)
		(layer "In9.Cu")
		(net "USB3_P01_RXP")
	)
	(segment
		(start 403.0599 -125.379988)
		(end 402.20646 -125.08992)
		(width 0.1143)
		(layer "In9.Cu")
		(net "USB3_P01_RXP")
	)
	(segment
		(start 400.068796 -126.000256)
		(end 399.858992 -125.897894)
		(width 0.1143)
		(layer "In9.Cu")
		(net "USB3_P01_RXP")
	)
	(segment
		(start 421.206168 -111.701326)
		(end 420.868348 -112.765586)
		(width 0.1143)
		(layer "In9.Cu")
		(net "USB3_P01_RXP")
	)
	(segment
		(start 420.623746 -115.818412)
		(end 419.15715 -118.15953)
		(width 0.1143)
		(layer "In9.Cu")
		(net "USB3_P01_RXP")
	)
	(segment
		(start 397.06804 -126.666244)
		(end 396.937738 -127.288036)
		(width 0.1143)
		(layer "In9.Cu")
		(net "USB3_P01_RXP")
	)
	(segment
		(start 420.868348 -112.765586)
		(end 421.223186 -113.914428)
		(width 0.1143)
		(layer "In9.Cu")
		(net "USB3_P01_RXP")
	)
	(segment
		(start 399.432272 -126.219204)
		(end 399.107914 -126.330964)
		(width 0.1143)
		(layer "In9.Cu")
		(net "USB3_P01_RXP")
	)
	(segment
		(start 414.19526 -119.483378)
		(end 414.335976 -119.953786)
		(width 0.1143)
		(layer "In9.Cu")
		(net "USB3_P01_RXP")
	)
	(segment
		(start 424.56862 -76.154026)
		(end 425.285154 -78.42504)
		(width 0.1143)
		(layer "In9.Cu")
		(net "USB3_P01_RXP")
	)
	(segment
		(start 396.354808 -127.49149)
		(end 396.354808 -127.75819)
		(width 0.0889)
		(layer "F.Cu")
		(net "USB3_P01_RXN")
	)
	(segment
		(start 396.354808 -127.75819)
		(end 396.632684 -128.036066)
		(width 0.0889)
		(layer "F.Cu")
		(net "USB3_P01_RXN")
	)
	(segment
		(start 397.4846 -128.32588)
		(end 397.4846 -128.582166)
		(width 0.0889)
		(layer "F.Cu")
		(net "USB3_P01_RXN")
	)
	(segment
		(start 397.4846 -128.582166)
		(end 397.51 -128.607566)
		(width 0.0889)
		(layer "F.Cu")
		(net "USB3_P01_RXN")
	)
	(segment
		(start 396.265908 -127.40259)
		(end 396.354808 -127.49149)
		(width 0.0889)
		(layer "F.Cu")
		(net "USB3_P01_RXN")
	)
	(segment
		(start 396.535402 -125.800358)
		(end 396.535402 -125.90272)
		(width 0.0889)
		(layer "F.Cu")
		(net "USB3_P01_RXN")
	)
	(segment
		(start 396.354808 -127.04699)
		(end 396.265908 -127.13589)
		(width 0.0889)
		(layer "F.Cu")
		(net "USB3_P01_RXN")
	)
	(segment
		(start 396.48511 -125.750066)
		(end 396.535402 -125.800358)
		(width 0.0889)
		(layer "F.Cu")
		(net "USB3_P01_RXN")
	)
	(segment
		(start 397.337534 -128.23698)
		(end 397.3957 -128.23698)
		(width 0.0889)
		(layer "F.Cu")
		(net "USB3_P01_RXN")
	)
	(segment
		(start 396.354808 -126.083314)
		(end 396.354808 -126.33579)
		(width 0.0889)
		(layer "F.Cu")
		(net "USB3_P01_RXN")
	)
	(segment
		(start 396.535402 -125.90272)
		(end 396.354808 -126.083314)
		(width 0.0889)
		(layer "F.Cu")
		(net "USB3_P01_RXN")
	)
	(segment
		(start 396.354808 -126.78029)
		(end 396.354808 -127.04699)
		(width 0.0889)
		(layer "F.Cu")
		(net "USB3_P01_RXN")
	)
	(segment
		(start 396.265908 -126.69139)
		(end 396.354808 -126.78029)
		(width 0.0889)
		(layer "F.Cu")
		(net "USB3_P01_RXN")
	)
	(segment
		(start 396.632684 -128.036066)
		(end 397.13662 -128.036066)
		(width 0.0889)
		(layer "F.Cu")
		(net "USB3_P01_RXN")
	)
	(segment
		(start 396.354808 -126.33579)
		(end 396.265908 -126.42469)
		(width 0.0889)
		(layer "F.Cu")
		(net "USB3_P01_RXN")
	)
	(segment
		(start 397.13662 -128.036066)
		(end 397.337534 -128.23698)
		(width 0.0889)
		(layer "F.Cu")
		(net "USB3_P01_RXN")
	)
	(segment
		(start 397.3957 -128.23698)
		(end 397.4846 -128.32588)
		(width 0.0889)
		(layer "F.Cu")
		(net "USB3_P01_RXN")
	)
	(segment
		(start 396.265908 -126.42469)
		(end 396.265908 -126.69139)
		(width 0.0889)
		(layer "F.Cu")
		(net "USB3_P01_RXN")
	)
	(segment
		(start 396.265908 -127.13589)
		(end 396.265908 -127.40259)
		(width 0.0889)
		(layer "F.Cu")
		(net "USB3_P01_RXN")
	)
	(via
		(at 397.51 -128.607566)
		(size 0.508)
		(drill 0.254)
		(layers "F.Cu" "B.Cu")
		(net "USB3_P01_RXN")
	)
	(via
		(at 471.09888 -64.4398)
		(size 0.508)
		(drill 0.254)
		(layers "F.Cu" "B.Cu")
		(net "USB3_P01_RXN")
	)
	(segment
		(start 484.599234 -58.702702)
		(end 484.799894 -58.903362)
		(width 0.1143)
		(layer "B.Cu")
		(net "USB3_P01_RXN")
	)
	(segment
		(start 483.06736 -60.305188)
		(end 483.067106 -60.305442)
		(width 0.1143)
		(layer "B.Cu")
		(net "USB3_P01_RXN")
	)
	(segment
		(start 471.42908 -64.77)
		(end 471.42908 -65.052702)
		(width 0.1143)
		(layer "B.Cu")
		(net "USB3_P01_RXN")
	)
	(segment
		(start 481.692966 -60.621164)
		(end 483.066852 -60.304426)
		(width 0.1143)
		(layer "B.Cu")
		(net "USB3_P01_RXN")
	)
	(segment
		(start 473.899484 -65.25006)
		(end 475.211648 -64.399414)
		(width 0.1143)
		(layer "B.Cu")
		(net "USB3_P01_RXN")
	)
	(segment
		(start 483.067106 -60.305442)
		(end 483.790498 -59.853322)
		(width 0.1143)
		(layer "B.Cu")
		(net "USB3_P01_RXN")
	)
	(segment
		(start 471.889836 -65.520062)
		(end 472.309698 -65.617344)
		(width 0.1143)
		(layer "B.Cu")
		(net "USB3_P01_RXN")
	)
	(segment
		(start 479.326702 -60.86348)
		(end 481.033582 -60.469272)
		(width 0.1143)
		(layer "B.Cu")
		(net "USB3_P01_RXN")
	)
	(segment
		(start 471.09888 -64.4398)
		(end 471.42908 -64.77)
		(width 0.1143)
		(layer "B.Cu")
		(net "USB3_P01_RXN")
	)
	(segment
		(start 484.329486 -58.702702)
		(end 484.599234 -58.702702)
		(width 0.1143)
		(layer "B.Cu")
		(net "USB3_P01_RXN")
	)
	(segment
		(start 484.799894 -58.903362)
		(end 485.58577 -58.903362)
		(width 0.1143)
		(layer "B.Cu")
		(net "USB3_P01_RXN")
	)
	(segment
		(start 481.033582 -60.469272)
		(end 481.692966 -60.621164)
		(width 0.1143)
		(layer "B.Cu")
		(net "USB3_P01_RXN")
	)
	(segment
		(start 476.728282 -63.94958)
		(end 478.227898 -61.549534)
		(width 0.1143)
		(layer "B.Cu")
		(net "USB3_P01_RXN")
	)
	(segment
		(start 484.146098 -58.88609)
		(end 484.329486 -58.702702)
		(width 0.1143)
		(layer "B.Cu")
		(net "USB3_P01_RXN")
	)
	(segment
		(start 471.42908 -65.052702)
		(end 471.61323 -65.347342)
		(width 0.1143)
		(layer "B.Cu")
		(net "USB3_P01_RXN")
	)
	(segment
		(start 472.309698 -65.617344)
		(end 473.899484 -65.25006)
		(width 0.1143)
		(layer "B.Cu")
		(net "USB3_P01_RXN")
	)
	(segment
		(start 471.61323 -65.347342)
		(end 471.889836 -65.520062)
		(width 0.1143)
		(layer "B.Cu")
		(net "USB3_P01_RXN")
	)
	(segment
		(start 478.227898 -61.549534)
		(end 479.326702 -60.86348)
		(width 0.1143)
		(layer "B.Cu")
		(net "USB3_P01_RXN")
	)
	(segment
		(start 483.790498 -59.853322)
		(end 484.146098 -59.285124)
		(width 0.1143)
		(layer "B.Cu")
		(net "USB3_P01_RXN")
	)
	(segment
		(start 484.146098 -59.285124)
		(end 484.146098 -58.88609)
		(width 0.1143)
		(layer "B.Cu")
		(net "USB3_P01_RXN")
	)
	(segment
		(start 475.211648 -64.399414)
		(end 476.728282 -63.94958)
		(width 0.1143)
		(layer "B.Cu")
		(net "USB3_P01_RXN")
	)
	(segment
		(start 483.066852 -60.304426)
		(end 483.06736 -60.305188)
		(width 0.1143)
		(layer "B.Cu")
		(net "USB3_P01_RXN")
	)
	(segment
		(start 396.6464 -127.873252)
		(end 396.646654 -127.9144)
		(width 0.1143)
		(layer "In9.Cu")
		(net "USB3_P01_RXN")
	)
	(segment
		(start 420.562024 -112.764316)
		(end 420.917116 -113.913666)
		(width 0.1143)
		(layer "In9.Cu")
		(net "USB3_P01_RXN")
	)
	(segment
		(start 414.889188 -118.419372)
		(end 414.110932 -118.852696)
		(width 0.1143)
		(layer "In9.Cu")
		(net "USB3_P01_RXN")
	)
	(segment
		(start 424.434508 -97.154746)
		(end 423.5323 -97.745042)
		(width 0.1143)
		(layer "In9.Cu")
		(net "USB3_P01_RXN")
	)
	(segment
		(start 408.401266 -124.61748)
		(end 406.92324 -125.0188)
		(width 0.1143)
		(layer "In9.Cu")
		(net "USB3_P01_RXN")
	)
	(segment
		(start 423.5323 -97.745042)
		(end 421.65016 -97.745042)
		(width 0.1143)
		(layer "In9.Cu")
		(net "USB3_P01_RXN")
	)
	(segment
		(start 418.96919 -117.90934)
		(end 415.946844 -118.771924)
		(width 0.1143)
		(layer "In9.Cu")
		(net "USB3_P01_RXN")
	)
	(segment
		(start 413.88792 -119.47525)
		(end 414.029398 -119.948452)
		(width 0.1143)
		(layer "In9.Cu")
		(net "USB3_P01_RXN")
	)
	(segment
		(start 406.92324 -125.0188)
		(end 405.318976 -124.612654)
		(width 0.1143)
		(layer "In9.Cu")
		(net "USB3_P01_RXN")
	)
	(segment
		(start 424.541442 -85.494368)
		(end 425.190158 -87.552276)
		(width 0.1143)
		(layer "In9.Cu")
		(net "USB3_P01_RXN")
	)
	(segment
		(start 471.09888 -64.4398)
		(end 471.36558 -64.4398)
		(width 0.1143)
		(layer "In9.Cu")
		(net "USB3_P01_RXN")
	)
	(segment
		(start 396.738602 -128.17221)
		(end 397.019526 -128.372616)
		(width 0.1143)
		(layer "In9.Cu")
		(net "USB3_P01_RXN")
	)
	(segment
		(start 396.646654 -127.9144)
		(end 396.646654 -127.92583)
		(width 0.1143)
		(layer "In9.Cu")
		(net "USB3_P01_RXN")
	)
	(segment
		(start 424.593258 -80.07985)
		(end 424.593258 -80.080358)
		(width 0.1143)
		(layer "In9.Cu")
		(net "USB3_P01_RXN")
	)
	(segment
		(start 424.349672 -81.109058)
		(end 425.052236 -83.336638)
		(width 0.1143)
		(layer "In9.Cu")
		(net "USB3_P01_RXN")
	)
	(segment
		(start 418.386768 -103.72598)
		(end 420.89959 -111.701072)
		(width 0.1143)
		(layer "In9.Cu")
		(net "USB3_P01_RXN")
	)
	(segment
		(start 418.99332 -99.431094)
		(end 418.386006 -101.996748)
		(width 0.1143)
		(layer "In9.Cu")
		(net "USB3_P01_RXN")
	)
	(segment
		(start 424.982132 -78.436216)
		(end 424.593258 -80.07985)
		(width 0.1143)
		(layer "In9.Cu")
		(net "USB3_P01_RXN")
	)
	(segment
		(start 410.49702 -125.211078)
		(end 408.401266 -124.61748)
		(width 0.1143)
		(layer "In9.Cu")
		(net "USB3_P01_RXN")
	)
	(segment
		(start 415.946844 -118.771924)
		(end 414.889188 -118.419372)
		(width 0.1143)
		(layer "In9.Cu")
		(net "USB3_P01_RXN")
	)
	(segment
		(start 414.110932 -118.852696)
		(end 413.88792 -119.47525)
		(width 0.1143)
		(layer "In9.Cu")
		(net "USB3_P01_RXN")
	)
	(segment
		(start 412.566358 -124.291598)
		(end 410.49702 -125.211078)
		(width 0.1143)
		(layer "In9.Cu")
		(net "USB3_P01_RXN")
	)
	(segment
		(start 419.66261 -116.802408)
		(end 419.662356 -116.802408)
		(width 0.1143)
		(layer "In9.Cu")
		(net "USB3_P01_RXN")
	)
	(segment
		(start 424.27652 -68.518278)
		(end 424.27652 -76.199238)
		(width 0.1143)
		(layer "In9.Cu")
		(net "USB3_P01_RXN")
	)
	(segment
		(start 425.052236 -83.336638)
		(end 424.541442 -85.494368)
		(width 0.1143)
		(layer "In9.Cu")
		(net "USB3_P01_RXN")
	)
	(segment
		(start 396.810484 -126.470664)
		(end 396.645384 -127.258064)
		(width 0.1143)
		(layer "In9.Cu")
		(net "USB3_P01_RXN")
	)
	(segment
		(start 397.66621 -126.02718)
		(end 397.558768 -126.082806)
		(width 0.1143)
		(layer "In9.Cu")
		(net "USB3_P01_RXN")
	)
	(segment
		(start 397.558768 -126.082806)
		(end 396.810484 -126.470664)
		(width 0.1143)
		(layer "In9.Cu")
		(net "USB3_P01_RXN")
	)
	(segment
		(start 403.078442 -125.077728)
		(end 402.205952 -124.781056)
		(width 0.1143)
		(layer "In9.Cu")
		(net "USB3_P01_RXN")
	)
	(segment
		(start 420.917116 -113.913666)
		(end 420.356284 -115.694968)
		(width 0.1143)
		(layer "In9.Cu")
		(net "USB3_P01_RXN")
	)
	(segment
		(start 396.646654 -127.873252)
		(end 396.6464 -127.873252)
		(width 0.1143)
		(layer "In9.Cu")
		(net "USB3_P01_RXN")
	)
	(segment
		(start 471.36558 -64.4398)
		(end 471.42908 -64.5033)
		(width 0.1143)
		(layer "In9.Cu")
		(net "USB3_P01_RXN")
	)
	(segment
		(start 424.593258 -80.080358)
		(end 424.349672 -81.109058)
		(width 0.1143)
		(layer "In9.Cu")
		(net "USB3_P01_RXN")
	)
	(segment
		(start 419.662356 -116.802408)
		(end 418.96919 -117.90934)
		(width 0.1143)
		(layer "In9.Cu")
		(net "USB3_P01_RXN")
	)
	(segment
		(start 470.37879 -66.00571)
		(end 426.789088 -66.00571)
		(width 0.1143)
		(layer "In9.Cu")
		(net "USB3_P01_RXN")
	)
	(segment
		(start 471.42908 -64.95542)
		(end 470.37879 -66.00571)
		(width 0.1143)
		(layer "In9.Cu")
		(net "USB3_P01_RXN")
	)
	(segment
		(start 414.029398 -119.948452)
		(end 412.566358 -124.291598)
		(width 0.1143)
		(layer "In9.Cu")
		(net "USB3_P01_RXN")
	)
	(segment
		(start 396.646654 -127.92583)
		(end 396.738602 -128.17221)
		(width 0.1143)
		(layer "In9.Cu")
		(net "USB3_P01_RXN")
	)
	(segment
		(start 424.692826 -89.653618)
		(end 425.559474 -92.402406)
		(width 0.1143)
		(layer "In9.Cu")
		(net "USB3_P01_RXN")
	)
	(segment
		(start 424.27652 -76.199238)
		(end 424.982132 -78.436216)
		(width 0.1143)
		(layer "In9.Cu")
		(net "USB3_P01_RXN")
	)
	(segment
		(start 402.205952 -124.781056)
		(end 398.20723 -126.157228)
		(width 0.1143)
		(layer "In9.Cu")
		(net "USB3_P01_RXN")
	)
	(segment
		(start 418.386006 -101.996748)
		(end 418.620194 -102.739952)
		(width 0.1143)
		(layer "In9.Cu")
		(net "USB3_P01_RXN")
	)
	(segment
		(start 397.019526 -128.372616)
		(end 397.27505 -128.372616)
		(width 0.1143)
		(layer "In9.Cu")
		(net "USB3_P01_RXN")
	)
	(segment
		(start 421.65016 -97.745042)
		(end 418.99332 -99.431094)
		(width 0.1143)
		(layer "In9.Cu")
		(net "USB3_P01_RXN")
	)
	(segment
		(start 425.559474 -92.402406)
		(end 424.434508 -97.154746)
		(width 0.1143)
		(layer "In9.Cu")
		(net "USB3_P01_RXN")
	)
	(segment
		(start 397.27505 -128.372616)
		(end 397.51 -128.607566)
		(width 0.1143)
		(layer "In9.Cu")
		(net "USB3_P01_RXN")
	)
	(segment
		(start 396.645384 -127.258064)
		(end 396.646654 -127.873252)
		(width 0.1143)
		(layer "In9.Cu")
		(net "USB3_P01_RXN")
	)
	(segment
		(start 398.20723 -126.157228)
		(end 397.66621 -126.02718)
		(width 0.1143)
		(layer "In9.Cu")
		(net "USB3_P01_RXN")
	)
	(segment
		(start 425.190158 -87.552276)
		(end 424.692826 -89.653618)
		(width 0.1143)
		(layer "In9.Cu")
		(net "USB3_P01_RXN")
	)
	(segment
		(start 426.789088 -66.00571)
		(end 424.27652 -68.518278)
		(width 0.1143)
		(layer "In9.Cu")
		(net "USB3_P01_RXN")
	)
	(segment
		(start 405.318976 -124.612654)
		(end 403.078442 -125.077728)
		(width 0.1143)
		(layer "In9.Cu")
		(net "USB3_P01_RXN")
	)
	(segment
		(start 471.42908 -64.5033)
		(end 471.42908 -64.95542)
		(width 0.1143)
		(layer "In9.Cu")
		(net "USB3_P01_RXN")
	)
	(segment
		(start 418.620194 -102.739952)
		(end 418.386768 -103.72598)
		(width 0.1143)
		(layer "In9.Cu")
		(net "USB3_P01_RXN")
	)
	(segment
		(start 420.89959 -111.701072)
		(end 420.562024 -112.764316)
		(width 0.1143)
		(layer "In9.Cu")
		(net "USB3_P01_RXN")
	)
	(segment
		(start 420.356284 -115.694968)
		(end 419.66261 -116.802408)
		(width 0.1143)
		(layer "In9.Cu")
		(net "USB3_P01_RXN")
	)
	(segment
		(start 494.795048 -54.733952)
		(end 495.460528 -54.733952)
		(width 0.1143)
		(layer "F.Cu")
		(net "USB3_P01_FB_TXP")
	)
	(segment
		(start 493.577118 -55.499254)
		(end 493.691418 -55.613554)
		(width 0.1143)
		(layer "F.Cu")
		(net "USB3_P01_FB_TXP")
	)
	(segment
		(start 495.460528 -54.733952)
		(end 495.689636 -54.96306)
		(width 0.1143)
		(layer "F.Cu")
		(net "USB3_P01_FB_TXP")
	)
	(segment
		(start 495.85626 -54.96306)
		(end 495.989356 -54.829964)
		(width 0.1143)
		(layer "F.Cu")
		(net "USB3_P01_FB_TXP")
	)
	(segment
		(start 493.691418 -55.613554)
		(end 493.915446 -55.613554)
		(width 0.1143)
		(layer "F.Cu")
		(net "USB3_P01_FB_TXP")
	)
	(segment
		(start 493.915446 -55.613554)
		(end 494.795048 -54.733952)
		(width 0.1143)
		(layer "F.Cu")
		(net "USB3_P01_FB_TXP")
	)
	(segment
		(start 495.689636 -54.96306)
		(end 495.85626 -54.96306)
		(width 0.1143)
		(layer "F.Cu")
		(net "USB3_P01_FB_TXP")
	)
	(segment
		(start 495.989356 -54.829964)
		(end 496.24996 -54.829964)
		(width 0.1143)
		(layer "F.Cu")
		(net "USB3_P01_FB_TXP")
	)
	(segment
		(start 493.577118 -55.28183)
		(end 493.577118 -55.499254)
		(width 0.1143)
		(layer "F.Cu")
		(net "USB3_P01_FB_TXP")
	)
	(via
		(at 493.577118 -55.28183)
		(size 0.508)
		(drill 0.254)
		(layers "F.Cu" "B.Cu")
		(net "USB3_P01_FB_TXP")
	)
	(via
		(at 491.54588 -57.578752)
		(size 0.508)
		(drill 0.254)
		(layers "F.Cu" "B.Cu")
		(net "USB3_P01_FB_TXP")
	)
	(segment
		(start 490.483144 -60.016644)
		(end 490.59592 -60.12942)
		(width 0.1143)
		(layer "B.Cu")
		(net "USB3_P01_FB_TXP")
	)
	(segment
		(start 491.49254 -55.705756)
		(end 491.425738 -55.772558)
		(width 0.1143)
		(layer "B.Cu")
		(net "USB3_P01_FB_TXP")
	)
	(segment
		(start 491.425738 -56.464708)
		(end 491.425738 -56.811926)
		(width 0.1143)
		(layer "B.Cu")
		(net "USB3_P01_FB_TXP")
	)
	(segment
		(start 491.54588 -58.677302)
		(end 491.43158 -58.563002)
		(width 0.1143)
		(layer "B.Cu")
		(net "USB3_P01_FB_TXP")
	)
	(segment
		(start 490.59592 -60.294774)
		(end 490.72419 -60.423044)
		(width 0.1143)
		(layer "B.Cu")
		(net "USB3_P01_FB_TXP")
	)
	(segment
		(start 491.425738 -56.464708)
		(end 491.425738 -55.880762)
		(width 0.1143)
		(layer "B.Cu")
		(net "USB3_P01_FB_TXP")
	)
	(segment
		(start 490.934756 -60.423044)
		(end 491.54588 -59.81192)
		(width 0.1143)
		(layer "B.Cu")
		(net "USB3_P01_FB_TXP")
	)
	(segment
		(start 491.425738 -55.772558)
		(end 491.425738 -55.880762)
		(width 0.1143)
		(layer "B.Cu")
		(net "USB3_P01_FB_TXP")
	)
	(segment
		(start 491.425738 -56.811926)
		(end 491.54588 -56.932068)
		(width 0.1143)
		(layer "B.Cu")
		(net "USB3_P01_FB_TXP")
	)
	(segment
		(start 490.59592 -60.12942)
		(end 490.59592 -60.294774)
		(width 0.1143)
		(layer "B.Cu")
		(net "USB3_P01_FB_TXP")
	)
	(segment
		(start 491.54588 -58.105802)
		(end 491.54588 -57.578752)
		(width 0.1143)
		(layer "B.Cu")
		(net "USB3_P01_FB_TXP")
	)
	(segment
		(start 492.62538 -55.0545)
		(end 491.781084 -55.0545)
		(width 0.1143)
		(layer "B.Cu")
		(net "USB3_P01_FB_TXP")
	)
	(segment
		(start 491.43158 -58.563002)
		(end 491.43158 -58.220102)
		(width 0.1143)
		(layer "B.Cu")
		(net "USB3_P01_FB_TXP")
	)
	(segment
		(start 490.72419 -60.423044)
		(end 490.934756 -60.423044)
		(width 0.1143)
		(layer "B.Cu")
		(net "USB3_P01_FB_TXP")
	)
	(segment
		(start 491.492286 -55.705502)
		(end 491.49254 -55.705756)
		(width 0.1143)
		(layer "B.Cu")
		(net "USB3_P01_FB_TXP")
	)
	(segment
		(start 491.43158 -58.220102)
		(end 491.54588 -58.105802)
		(width 0.1143)
		(layer "B.Cu")
		(net "USB3_P01_FB_TXP")
	)
	(segment
		(start 491.492286 -55.343298)
		(end 491.492286 -55.705502)
		(width 0.1143)
		(layer "B.Cu")
		(net "USB3_P01_FB_TXP")
	)
	(segment
		(start 493.577118 -55.28183)
		(end 493.382554 -55.476394)
		(width 0.1143)
		(layer "B.Cu")
		(net "USB3_P01_FB_TXP")
	)
	(segment
		(start 493.382554 -55.476394)
		(end 493.047274 -55.476394)
		(width 0.1143)
		(layer "B.Cu")
		(net "USB3_P01_FB_TXP")
	)
	(segment
		(start 491.54588 -56.932068)
		(end 491.54588 -57.578752)
		(width 0.1143)
		(layer "B.Cu")
		(net "USB3_P01_FB_TXP")
	)
	(segment
		(start 491.781084 -55.0545)
		(end 491.492286 -55.343298)
		(width 0.1143)
		(layer "B.Cu")
		(net "USB3_P01_FB_TXP")
	)
	(segment
		(start 493.047274 -55.476394)
		(end 492.62538 -55.0545)
		(width 0.1143)
		(layer "B.Cu")
		(net "USB3_P01_FB_TXP")
	)
	(segment
		(start 491.54588 -59.81192)
		(end 491.54588 -58.677302)
		(width 0.1143)
		(layer "B.Cu")
		(net "USB3_P01_FB_TXP")
	)
	(segment
		(start 489.65612 -60.016644)
		(end 490.483144 -60.016644)
		(width 0.1143)
		(layer "B.Cu")
		(net "USB3_P01_FB_TXP")
	)
	(segment
		(start 495.981736 -55.329836)
		(end 495.85626 -55.20436)
		(width 0.1143)
		(layer "F.Cu")
		(net "USB3_P01_FB_TXN")
	)
	(segment
		(start 495.85626 -55.20436)
		(end 495.58956 -55.20436)
		(width 0.1143)
		(layer "F.Cu")
		(net "USB3_P01_FB_TXN")
	)
	(segment
		(start 493.712754 -55.854854)
		(end 493.577118 -55.99049)
		(width 0.1143)
		(layer "F.Cu")
		(net "USB3_P01_FB_TXN")
	)
	(segment
		(start 495.58956 -55.20436)
		(end 495.360452 -54.975252)
		(width 0.1143)
		(layer "F.Cu")
		(net "USB3_P01_FB_TXN")
	)
	(segment
		(start 494.895124 -54.975252)
		(end 494.015522 -55.854854)
		(width 0.1143)
		(layer "F.Cu")
		(net "USB3_P01_FB_TXN")
	)
	(segment
		(start 494.015522 -55.854854)
		(end 493.712754 -55.854854)
		(width 0.1143)
		(layer "F.Cu")
		(net "USB3_P01_FB_TXN")
	)
	(segment
		(start 496.24996 -55.329836)
		(end 495.981736 -55.329836)
		(width 0.1143)
		(layer "F.Cu")
		(net "USB3_P01_FB_TXN")
	)
	(segment
		(start 493.577118 -55.99049)
		(end 493.577118 -56.173116)
		(width 0.1143)
		(layer "F.Cu")
		(net "USB3_P01_FB_TXN")
	)
	(segment
		(start 495.360452 -54.975252)
		(end 494.895124 -54.975252)
		(width 0.1143)
		(layer "F.Cu")
		(net "USB3_P01_FB_TXN")
	)
	(via
		(at 491.78718 -59.204098)
		(size 0.508)
		(drill 0.254)
		(layers "F.Cu" "B.Cu")
		(net "USB3_P01_FB_TXN")
	)
	(via
		(at 493.577118 -56.173116)
		(size 0.508)
		(drill 0.254)
		(layers "F.Cu" "B.Cu")
		(net "USB3_P01_FB_TXN")
	)
	(segment
		(start 492.947198 -55.717694)
		(end 492.525304 -55.2958)
		(width 0.1143)
		(layer "B.Cu")
		(net "USB3_P01_FB_TXN")
	)
	(segment
		(start 489.65612 -60.816744)
		(end 490.490256 -60.816744)
		(width 0.1143)
		(layer "B.Cu")
		(net "USB3_P01_FB_TXN")
	)
	(segment
		(start 491.925864 -56.464708)
		(end 491.925864 -55.880762)
		(width 0.1143)
		(layer "B.Cu")
		(net "USB3_P01_FB_TXN")
	)
	(segment
		(start 490.642656 -60.664344)
		(end 491.034832 -60.664344)
		(width 0.1143)
		(layer "B.Cu")
		(net "USB3_P01_FB_TXN")
	)
	(segment
		(start 493.406176 -55.717694)
		(end 492.947198 -55.717694)
		(width 0.1143)
		(layer "B.Cu")
		(net "USB3_P01_FB_TXN")
	)
	(segment
		(start 492.525304 -55.2958)
		(end 491.88116 -55.2958)
		(width 0.1143)
		(layer "B.Cu")
		(net "USB3_P01_FB_TXN")
	)
	(segment
		(start 490.490256 -60.816744)
		(end 490.642656 -60.664344)
		(width 0.1143)
		(layer "B.Cu")
		(net "USB3_P01_FB_TXN")
	)
	(segment
		(start 491.78718 -59.911996)
		(end 491.78718 -59.204098)
		(width 0.1143)
		(layer "B.Cu")
		(net "USB3_P01_FB_TXN")
	)
	(segment
		(start 491.78718 -56.915812)
		(end 491.78718 -59.204098)
		(width 0.1143)
		(layer "B.Cu")
		(net "USB3_P01_FB_TXN")
	)
	(segment
		(start 491.733586 -55.443374)
		(end 491.733586 -55.605426)
		(width 0.1143)
		(layer "B.Cu")
		(net "USB3_P01_FB_TXN")
	)
	(segment
		(start 491.925864 -55.797704)
		(end 491.925864 -55.880762)
		(width 0.1143)
		(layer "B.Cu")
		(net "USB3_P01_FB_TXN")
	)
	(segment
		(start 491.88116 -55.2958)
		(end 491.733586 -55.443374)
		(width 0.1143)
		(layer "B.Cu")
		(net "USB3_P01_FB_TXN")
	)
	(segment
		(start 493.577118 -55.888636)
		(end 493.406176 -55.717694)
		(width 0.1143)
		(layer "B.Cu")
		(net "USB3_P01_FB_TXN")
	)
	(segment
		(start 491.925864 -56.777128)
		(end 491.78718 -56.915812)
		(width 0.1143)
		(layer "B.Cu")
		(net "USB3_P01_FB_TXN")
	)
	(segment
		(start 491.733586 -55.605426)
		(end 491.925864 -55.797704)
		(width 0.1143)
		(layer "B.Cu")
		(net "USB3_P01_FB_TXN")
	)
	(segment
		(start 491.925864 -56.464708)
		(end 491.925864 -56.777128)
		(width 0.1143)
		(layer "B.Cu")
		(net "USB3_P01_FB_TXN")
	)
	(segment
		(start 493.577118 -56.173116)
		(end 493.577118 -55.888636)
		(width 0.1143)
		(layer "B.Cu")
		(net "USB3_P01_FB_TXN")
	)
	(segment
		(start 491.034832 -60.664344)
		(end 491.78718 -59.911996)
		(width 0.1143)
		(layer "B.Cu")
		(net "USB3_P01_FB_TXN")
	)
	(segment
		(start 497.211604 -54.829964)
		(end 497.949982 -54.829964)
		(width 0.1143)
		(layer "F.Cu")
		(net "USB3_P01_FB_RXP")
	)
	(segment
		(start 497.052854 -54.671214)
		(end 497.211604 -54.829964)
		(width 0.1143)
		(layer "F.Cu")
		(net "USB3_P01_FB_RXP")
	)
	(via
		(at 497.052854 -54.671214)
		(size 0.508)
		(drill 0.254)
		(layers "F.Cu" "B.Cu")
		(net "USB3_P01_FB_RXP")
	)
	(via
		(at 490.726476 -54.025546)
		(size 0.508)
		(drill 0.254)
		(layers "F.Cu" "B.Cu")
		(net "USB3_P01_FB_RXP")
	)
	(segment
		(start 490.058456 -55.426356)
		(end 490.058456 -55.607966)
		(width 0.1143)
		(layer "B.Cu")
		(net "USB3_P01_FB_RXP")
	)
	(segment
		(start 489.873798 -57.078626)
		(end 489.712 -57.078626)
		(width 0.1143)
		(layer "B.Cu")
		(net "USB3_P01_FB_RXP")
	)
	(segment
		(start 490.424216 -54.327806)
		(end 490.058456 -55.426356)
		(width 0.1143)
		(layer "B.Cu")
		(net "USB3_P01_FB_RXP")
	)
	(segment
		(start 491.590838 -53.5559)
		(end 493.203738 -53.5559)
		(width 0.1143)
		(layer "B.Cu")
		(net "USB3_P01_FB_RXP")
	)
	(segment
		(start 489.712 -57.078626)
		(end 489.469684 -57.321196)
		(width 0.1143)
		(layer "B.Cu")
		(net "USB3_P01_FB_RXP")
	)
	(segment
		(start 491.032546 -53.719476)
		(end 491.590838 -53.5559)
		(width 0.1143)
		(layer "B.Cu")
		(net "USB3_P01_FB_RXP")
	)
	(segment
		(start 488.35564 -58.351166)
		(end 488.35564 -58.1787)
		(width 0.1143)
		(layer "B.Cu")
		(net "USB3_P01_FB_RXP")
	)
	(segment
		(start 489.257848 -57.694576)
		(end 489.09605 -57.694576)
		(width 0.1143)
		(layer "B.Cu")
		(net "USB3_P01_FB_RXP")
	)
	(segment
		(start 490.094016 -56.696356)
		(end 490.094016 -56.858408)
		(width 0.1143)
		(layer "B.Cu")
		(net "USB3_P01_FB_RXP")
	)
	(segment
		(start 488.522518 -58.429906)
		(end 488.43438 -58.429906)
		(width 0.1143)
		(layer "B.Cu")
		(net "USB3_P01_FB_RXP")
	)
	(segment
		(start 489.469684 -57.48274)
		(end 489.257848 -57.694576)
		(width 0.1143)
		(layer "B.Cu")
		(net "USB3_P01_FB_RXP")
	)
	(segment
		(start 493.203738 -53.5559)
		(end 495.960654 -54.52364)
		(width 0.1143)
		(layer "B.Cu")
		(net "USB3_P01_FB_RXP")
	)
	(segment
		(start 496.783868 -54.9402)
		(end 497.052854 -54.671214)
		(width 0.1143)
		(layer "B.Cu")
		(net "USB3_P01_FB_RXP")
	)
	(segment
		(start 490.094016 -56.858408)
		(end 489.873798 -57.078626)
		(width 0.1143)
		(layer "B.Cu")
		(net "USB3_P01_FB_RXP")
	)
	(segment
		(start 488.853734 -57.937146)
		(end 488.853734 -58.09869)
		(width 0.1143)
		(layer "B.Cu")
		(net "USB3_P01_FB_RXP")
	)
	(segment
		(start 489.09605 -57.694576)
		(end 488.853734 -57.937146)
		(width 0.1143)
		(layer "B.Cu")
		(net "USB3_P01_FB_RXP")
	)
	(segment
		(start 496.671092 -54.9402)
		(end 496.783868 -54.9402)
		(width 0.1143)
		(layer "B.Cu")
		(net "USB3_P01_FB_RXP")
	)
	(segment
		(start 489.925868 -56.464708)
		(end 489.925868 -55.880762)
		(width 0.1143)
		(layer "B.Cu")
		(net "USB3_P01_FB_RXP")
	)
	(segment
		(start 489.469684 -57.321196)
		(end 489.469684 -57.48274)
		(width 0.1143)
		(layer "B.Cu")
		(net "USB3_P01_FB_RXP")
	)
	(segment
		(start 488.280202 -58.103262)
		(end 487.61777 -58.103262)
		(width 0.1143)
		(layer "B.Cu")
		(net "USB3_P01_FB_RXP")
	)
	(segment
		(start 488.43438 -58.429906)
		(end 488.35564 -58.351166)
		(width 0.1143)
		(layer "B.Cu")
		(net "USB3_P01_FB_RXP")
	)
	(segment
		(start 490.726476 -54.025546)
		(end 491.032546 -53.719476)
		(width 0.1143)
		(layer "B.Cu")
		(net "USB3_P01_FB_RXP")
	)
	(segment
		(start 488.853734 -58.09869)
		(end 488.522518 -58.429906)
		(width 0.1143)
		(layer "B.Cu")
		(net "USB3_P01_FB_RXP")
	)
	(segment
		(start 490.058456 -55.607966)
		(end 489.925868 -55.740554)
		(width 0.1143)
		(layer "B.Cu")
		(net "USB3_P01_FB_RXP")
	)
	(segment
		(start 495.960654 -54.52364)
		(end 496.671092 -54.9402)
		(width 0.1143)
		(layer "B.Cu")
		(net "USB3_P01_FB_RXP")
	)
	(segment
		(start 489.925868 -56.528208)
		(end 490.094016 -56.696356)
		(width 0.1143)
		(layer "B.Cu")
		(net "USB3_P01_FB_RXP")
	)
	(segment
		(start 490.726476 -54.025546)
		(end 490.424216 -54.327806)
		(width 0.1143)
		(layer "B.Cu")
		(net "USB3_P01_FB_RXP")
	)
	(segment
		(start 489.925868 -56.464708)
		(end 489.925868 -56.528208)
		(width 0.1143)
		(layer "B.Cu")
		(net "USB3_P01_FB_RXP")
	)
	(segment
		(start 489.925868 -55.740554)
		(end 489.925868 -55.880762)
		(width 0.1143)
		(layer "B.Cu")
		(net "USB3_P01_FB_RXP")
	)
	(segment
		(start 488.35564 -58.1787)
		(end 488.280202 -58.103262)
		(width 0.1143)
		(layer "B.Cu")
		(net "USB3_P01_FB_RXP")
	)
	(segment
		(start 497.052854 -55.471314)
		(end 497.194332 -55.329836)
		(width 0.1143)
		(layer "F.Cu")
		(net "USB3_P01_FB_RXN")
	)
	(segment
		(start 497.194332 -55.329836)
		(end 497.949982 -55.329836)
		(width 0.1143)
		(layer "F.Cu")
		(net "USB3_P01_FB_RXN")
	)
	(via
		(at 489.826046 -57.467754)
		(size 0.508)
		(drill 0.254)
		(layers "F.Cu" "B.Cu")
		(net "USB3_P01_FB_RXN")
	)
	(via
		(at 497.052854 -55.471314)
		(size 0.508)
		(drill 0.254)
		(layers "F.Cu" "B.Cu")
		(net "USB3_P01_FB_RXN")
	)
	(segment
		(start 495.10061 -54.599078)
		(end 495.03076 -54.453282)
		(width 0.1143)
		(layer "B.Cu")
		(net "USB3_P01_FB_RXN")
	)
	(segment
		(start 490.63529 -54.458362)
		(end 490.299756 -55.465726)
		(width 0.1143)
		(layer "B.Cu")
		(net "USB3_P01_FB_RXN")
	)
	(segment
		(start 497.052854 -55.471314)
		(end 496.76304 -55.1815)
		(width 0.1143)
		(layer "B.Cu")
		(net "USB3_P01_FB_RXN")
	)
	(segment
		(start 490.42574 -56.464708)
		(end 490.42574 -55.880762)
		(width 0.1143)
		(layer "B.Cu")
		(net "USB3_P01_FB_RXN")
	)
	(segment
		(start 490.335316 -56.958484)
		(end 489.826046 -57.467754)
		(width 0.1143)
		(layer "B.Cu")
		(net "USB3_P01_FB_RXN")
	)
	(segment
		(start 492.705136 -53.9115)
		(end 492.362236 -53.9115)
		(width 0.1143)
		(layer "B.Cu")
		(net "USB3_P01_FB_RXN")
	)
	(segment
		(start 488.622594 -58.671206)
		(end 488.249214 -58.671206)
		(width 0.1143)
		(layer "B.Cu")
		(net "USB3_P01_FB_RXN")
	)
	(segment
		(start 491.625636 -53.7972)
		(end 491.1598 -53.933852)
		(width 0.1143)
		(layer "B.Cu")
		(net "USB3_P01_FB_RXN")
	)
	(segment
		(start 488.249214 -58.671206)
		(end 488.017058 -58.903362)
		(width 0.1143)
		(layer "B.Cu")
		(net "USB3_P01_FB_RXN")
	)
	(segment
		(start 495.570002 -54.642512)
		(end 495.424206 -54.712616)
		(width 0.1143)
		(layer "B.Cu")
		(net "USB3_P01_FB_RXN")
	)
	(segment
		(start 493.374934 -53.993034)
		(end 493.305084 -53.847492)
		(width 0.1143)
		(layer "B.Cu")
		(net "USB3_P01_FB_RXN")
	)
	(segment
		(start 493.844326 -54.036722)
		(end 493.69853 -54.106826)
		(width 0.1143)
		(layer "B.Cu")
		(net "USB3_P01_FB_RXN")
	)
	(segment
		(start 494.561368 -54.409594)
		(end 494.237772 -54.296056)
		(width 0.1143)
		(layer "B.Cu")
		(net "USB3_P01_FB_RXN")
	)
	(segment
		(start 492.819436 -53.7972)
		(end 492.705136 -53.9115)
		(width 0.1143)
		(layer "B.Cu")
		(net "USB3_P01_FB_RXN")
	)
	(segment
		(start 492.362236 -53.9115)
		(end 492.247936 -53.7972)
		(width 0.1143)
		(layer "B.Cu")
		(net "USB3_P01_FB_RXN")
	)
	(segment
		(start 496.60556 -55.1815)
		(end 495.858546 -54.743858)
		(width 0.1143)
		(layer "B.Cu")
		(net "USB3_P01_FB_RXN")
	)
	(segment
		(start 490.299756 -55.465726)
		(end 490.299756 -55.607458)
		(width 0.1143)
		(layer "B.Cu")
		(net "USB3_P01_FB_RXN")
	)
	(segment
		(start 490.42574 -56.5658)
		(end 490.335316 -56.656224)
		(width 0.1143)
		(layer "B.Cu")
		(net "USB3_P01_FB_RXN")
	)
	(segment
		(start 494.167922 -54.15026)
		(end 493.844326 -54.036722)
		(width 0.1143)
		(layer "B.Cu")
		(net "USB3_P01_FB_RXN")
	)
	(segment
		(start 495.03076 -54.453282)
		(end 494.707164 -54.339744)
		(width 0.1143)
		(layer "B.Cu")
		(net "USB3_P01_FB_RXN")
	)
	(segment
		(start 490.42574 -56.464708)
		(end 490.42574 -56.5658)
		(width 0.1143)
		(layer "B.Cu")
		(net "USB3_P01_FB_RXN")
	)
	(segment
		(start 488.017058 -58.903362)
		(end 487.61777 -58.903362)
		(width 0.1143)
		(layer "B.Cu")
		(net "USB3_P01_FB_RXN")
	)
	(segment
		(start 490.299756 -55.607458)
		(end 490.42574 -55.733442)
		(width 0.1143)
		(layer "B.Cu")
		(net "USB3_P01_FB_RXN")
	)
	(segment
		(start 493.69853 -54.106826)
		(end 493.374934 -53.993034)
		(width 0.1143)
		(layer "B.Cu")
		(net "USB3_P01_FB_RXN")
	)
	(segment
		(start 495.424206 -54.712616)
		(end 495.10061 -54.599078)
		(width 0.1143)
		(layer "B.Cu")
		(net "USB3_P01_FB_RXN")
	)
	(segment
		(start 491.1598 -53.933852)
		(end 490.63529 -54.458362)
		(width 0.1143)
		(layer "B.Cu")
		(net "USB3_P01_FB_RXN")
	)
	(segment
		(start 493.162336 -53.7972)
		(end 492.819436 -53.7972)
		(width 0.1143)
		(layer "B.Cu")
		(net "USB3_P01_FB_RXN")
	)
	(segment
		(start 490.335316 -56.656224)
		(end 490.335316 -56.958484)
		(width 0.1143)
		(layer "B.Cu")
		(net "USB3_P01_FB_RXN")
	)
	(segment
		(start 496.76304 -55.1815)
		(end 496.60556 -55.1815)
		(width 0.1143)
		(layer "B.Cu")
		(net "USB3_P01_FB_RXN")
	)
	(segment
		(start 489.826046 -57.467754)
		(end 488.622594 -58.671206)
		(width 0.1143)
		(layer "B.Cu")
		(net "USB3_P01_FB_RXN")
	)
	(segment
		(start 495.858546 -54.743858)
		(end 495.570002 -54.642512)
		(width 0.1143)
		(layer "B.Cu")
		(net "USB3_P01_FB_RXN")
	)
	(segment
		(start 494.237772 -54.296056)
		(end 494.167922 -54.15026)
		(width 0.1143)
		(layer "B.Cu")
		(net "USB3_P01_FB_RXN")
	)
	(segment
		(start 492.247936 -53.7972)
		(end 491.625636 -53.7972)
		(width 0.1143)
		(layer "B.Cu")
		(net "USB3_P01_FB_RXN")
	)
	(segment
		(start 494.707164 -54.339744)
		(end 494.561368 -54.409594)
		(width 0.1143)
		(layer "B.Cu")
		(net "USB3_P01_FB_RXN")
	)
	(segment
		(start 493.305084 -53.847492)
		(end 493.162336 -53.7972)
		(width 0.1143)
		(layer "B.Cu")
		(net "USB3_P01_FB_RXN")
	)
	(segment
		(start 490.42574 -55.733442)
		(end 490.42574 -55.880762)
		(width 0.1143)
		(layer "B.Cu")
		(net "USB3_P01_FB_RXN")
	)
	(segment
		(start 487.62412 -60.016644)
		(end 487.029252 -60.016644)
		(width 0.1143)
		(layer "B.Cu")
		(net "USB3_P01_C_TXP")
	)
	(segment
		(start 487.029252 -60.016644)
		(end 486.749852 -60.296044)
		(width 0.1143)
		(layer "B.Cu")
		(net "USB3_P01_C_TXP")
	)
	(segment
		(start 486.432098 -60.296044)
		(end 486.145586 -60.009532)
		(width 0.1143)
		(layer "B.Cu")
		(net "USB3_P01_C_TXP")
	)
	(segment
		(start 486.749852 -60.296044)
		(end 486.432098 -60.296044)
		(width 0.1143)
		(layer "B.Cu")
		(net "USB3_P01_C_TXP")
	)
	(segment
		(start 486.985564 -60.816744)
		(end 486.706164 -60.537344)
		(width 0.1143)
		(layer "B.Cu")
		(net "USB3_P01_C_TXN")
	)
	(segment
		(start 486.706164 -60.537344)
		(end 486.433368 -60.537344)
		(width 0.1143)
		(layer "B.Cu")
		(net "USB3_P01_C_TXN")
	)
	(segment
		(start 487.62412 -60.816744)
		(end 486.985564 -60.816744)
		(width 0.1143)
		(layer "B.Cu")
		(net "USB3_P01_C_TXN")
	)
	(segment
		(start 486.433368 -60.537344)
		(end 486.14838 -60.822332)
		(width 0.1143)
		(layer "B.Cu")
		(net "USB3_P01_C_TXN")
	)
	(segment
		(start 374.83161 -99.140772)
		(end 374.306592 -99.140772)
		(width 0.0889)
		(layer "F.Cu")
		(net "FM_SLPS3_R_N")
	)
	(segment
		(start 371.7925 -98.3615)
		(end 371.475 -98.044)
		(width 0.10795)
		(layer "F.Cu")
		(net "FM_SLPS3_R_N")
	)
	(segment
		(start 375.92 -99.354894)
		(end 375.551192 -99.354894)
		(width 0.0889)
		(layer "F.Cu")
		(net "FM_SLPS3_R_N")
	)
	(segment
		(start 373.99341 -98.82759)
		(end 373.52732 -98.3615)
		(width 0.10795)
		(layer "F.Cu")
		(net "FM_SLPS3_R_N")
	)
	(segment
		(start 374.93829 -99.034092)
		(end 374.83161 -99.140772)
		(width 0.0889)
		(layer "F.Cu")
		(net "FM_SLPS3_R_N")
	)
	(segment
		(start 373.52732 -98.3615)
		(end 371.7925 -98.3615)
		(width 0.10795)
		(layer "F.Cu")
		(net "FM_SLPS3_R_N")
	)
	(segment
		(start 374.306592 -99.140772)
		(end 373.99341 -98.82759)
		(width 0.0889)
		(layer "F.Cu")
		(net "FM_SLPS3_R_N")
	)
	(segment
		(start 371.475 -98.044)
		(end 370.967 -98.044)
		(width 0.10795)
		(layer "F.Cu")
		(net "FM_SLPS3_R_N")
	)
	(segment
		(start 375.23039 -99.034092)
		(end 374.93829 -99.034092)
		(width 0.0889)
		(layer "F.Cu")
		(net "FM_SLPS3_R_N")
	)
	(segment
		(start 375.551192 -99.354894)
		(end 375.23039 -99.034092)
		(width 0.0889)
		(layer "F.Cu")
		(net "FM_SLPS3_R_N")
	)
	(segment
		(start 415.090102 -41.93921)
		(end 414.711896 -42.317416)
		(width 0.10795)
		(layer "F.Cu")
		(net "RST_PLTRST_BUF_N_R")
	)
	(segment
		(start 413.712406 -46.980348)
		(end 413.207454 -47.4853)
		(width 0.10795)
		(layer "F.Cu")
		(net "RST_PLTRST_BUF_N_R")
	)
	(segment
		(start 413.916114 -46.950376)
		(end 413.886142 -46.980348)
		(width 0.1143)
		(layer "F.Cu")
		(net "RST_PLTRST_BUF_N_R")
	)
	(segment
		(start 412.742888 -48.960024)
		(end 412.742888 -49.382426)
		(width 0.10795)
		(layer "F.Cu")
		(net "RST_PLTRST_BUF_N_R")
	)
	(segment
		(start 413.886142 -46.980348)
		(end 413.712406 -46.980348)
		(width 0.10795)
		(layer "F.Cu")
		(net "RST_PLTRST_BUF_N_R")
	)
	(segment
		(start 412.742888 -49.382426)
		(end 412.3944 -49.730914)
		(width 0.10795)
		(layer "F.Cu")
		(net "RST_PLTRST_BUF_N_R")
	)
	(segment
		(start 414.711896 -42.317416)
		(end 414.711896 -44.3484)
		(width 0.10795)
		(layer "F.Cu")
		(net "RST_PLTRST_BUF_N_R")
	)
	(segment
		(start 414.711896 -44.3484)
		(end 414.711896 -44.807124)
		(width 0.1143)
		(layer "F.Cu")
		(net "RST_PLTRST_BUF_N_R")
	)
	(segment
		(start 415.090102 -41.73474)
		(end 415.090102 -41.93921)
		(width 0.10795)
		(layer "F.Cu")
		(net "RST_PLTRST_BUF_N_R")
	)
	(segment
		(start 413.207454 -48.774858)
		(end 413.022288 -48.960024)
		(width 0.10795)
		(layer "F.Cu")
		(net "RST_PLTRST_BUF_N_R")
	)
	(segment
		(start 413.207454 -47.4853)
		(end 413.207454 -48.774858)
		(width 0.10795)
		(layer "F.Cu")
		(net "RST_PLTRST_BUF_N_R")
	)
	(segment
		(start 414.711896 -44.807124)
		(end 413.916114 -45.602906)
		(width 0.1143)
		(layer "F.Cu")
		(net "RST_PLTRST_BUF_N_R")
	)
	(segment
		(start 413.022288 -48.960024)
		(end 412.742888 -48.960024)
		(width 0.10795)
		(layer "F.Cu")
		(net "RST_PLTRST_BUF_N_R")
	)
	(segment
		(start 413.916114 -45.602906)
		(end 413.916114 -46.950376)
		(width 0.1143)
		(layer "F.Cu")
		(net "RST_PLTRST_BUF_N_R")
	)
	(segment
		(start 412.3944 -49.730914)
		(end 412.3944 -50.18532)
		(width 0.10795)
		(layer "F.Cu")
		(net "RST_PLTRST_BUF_N_R")
	)
	(via
		(at 413.886142 -46.980348)
		(size 0.762)
		(drill 0.381)
		(layers "F.Cu" "B.Cu")
		(net "RST_PLTRST_BUF_N_R")
	)
	(segment
		(start 404.876 -115.697)
		(end 405.511 -115.697)
		(width 0.10795)
		(layer "F.Cu")
		(net "CLK_48M_USB_BMC_R")
	)
	(segment
		(start 413.489902 -41.73474)
		(end 413.090106 -42.134536)
		(width 0.10795)
		(layer "F.Cu")
		(net "CLK_48M_USB_BMC_R")
	)
	(segment
		(start 413.490156 -41.73474)
		(end 413.489902 -41.73474)
		(width 0.10795)
		(layer "F.Cu")
		(net "CLK_48M_USB_BMC_R")
	)
	(via
		(at 437.451754 -63.635128)
		(size 0.508)
		(drill 0.254)
		(layers "F.Cu" "B.Cu")
		(net "CLK_48M_USB_BMC_R")
	)
	(via
		(at 413.090106 -42.134536)
		(size 0.4572)
		(drill 0.2032)
		(layers "F.Cu" "B.Cu")
		(net "CLK_48M_USB_BMC_R")
	)
	(via
		(at 405.511 -115.697)
		(size 0.508)
		(drill 0.254)
		(layers "F.Cu" "B.Cu")
		(net "CLK_48M_USB_BMC_R")
	)
	(segment
		(start 428.700692 -63.02756)
		(end 429.951388 -63.02756)
		(width 0.089408)
		(layer "In9.Cu")
		(net "CLK_48M_USB_BMC_R")
	)
	(segment
		(start 417.670742 -111.285782)
		(end 417.670742 -110.954058)
		(width 0.089408)
		(layer "In9.Cu")
		(net "CLK_48M_USB_BMC_R")
	)
	(segment
		(start 415.660332 -114.162332)
		(end 416.663886 -114.162332)
		(width 0.089408)
		(layer "In9.Cu")
		(net "CLK_48M_USB_BMC_R")
	)
	(segment
		(start 409.820364 -114.586258)
		(end 410.970222 -113.4364)
		(width 0.089408)
		(layer "In9.Cu")
		(net "CLK_48M_USB_BMC_R")
	)
	(segment
		(start 411.625542 -113.436908)
		(end 411.957266 -113.436908)
		(width 0.089408)
		(layer "In9.Cu")
		(net "CLK_48M_USB_BMC_R")
	)
	(segment
		(start 437.114442 -63.97244)
		(end 437.451754 -63.635128)
		(width 0.089408)
		(layer "In9.Cu")
		(net "CLK_48M_USB_BMC_R")
	)
	(segment
		(start 412.369 -113.4364)
		(end 412.921704 -112.883696)
		(width 0.089408)
		(layer "In9.Cu")
		(net "CLK_48M_USB_BMC_R")
	)
	(segment
		(start 417.654486 -111.302038)
		(end 417.670742 -111.285782)
		(width 0.089408)
		(layer "In9.Cu")
		(net "CLK_48M_USB_BMC_R")
	)
	(segment
		(start 416.315652 -106.74604)
		(end 416.315652 -97.972372)
		(width 0.089408)
		(layer "In9.Cu")
		(net "CLK_48M_USB_BMC_R")
	)
	(segment
		(start 416.663886 -114.162332)
		(end 416.66414 -114.162586)
		(width 0.089408)
		(layer "In9.Cu")
		(net "CLK_48M_USB_BMC_R")
	)
	(segment
		(start 414.381696 -112.883696)
		(end 415.660332 -114.162332)
		(width 0.089408)
		(layer "In9.Cu")
		(net "CLK_48M_USB_BMC_R")
	)
	(segment
		(start 428.619666 -63.108586)
		(end 428.700692 -63.02756)
		(width 0.089408)
		(layer "In9.Cu")
		(net "CLK_48M_USB_BMC_R")
	)
	(segment
		(start 418.714174 -96.201992)
		(end 421.287702 -93.628464)
		(width 0.089408)
		(layer "In9.Cu")
		(net "CLK_48M_USB_BMC_R")
	)
	(segment
		(start 417.654486 -113.435384)
		(end 417.654486 -111.302038)
		(width 0.089408)
		(layer "In9.Cu")
		(net "CLK_48M_USB_BMC_R")
	)
	(segment
		(start 417.670742 -110.954058)
		(end 417.670488 -110.953804)
		(width 0.089408)
		(layer "In9.Cu")
		(net "CLK_48M_USB_BMC_R")
	)
	(segment
		(start 411.957774 -113.4364)
		(end 412.369 -113.4364)
		(width 0.089408)
		(layer "In9.Cu")
		(net "CLK_48M_USB_BMC_R")
	)
	(segment
		(start 421.287702 -78.388464)
		(end 422.150286 -77.52588)
		(width 0.089408)
		(layer "In9.Cu")
		(net "CLK_48M_USB_BMC_R")
	)
	(segment
		(start 416.315652 -97.972372)
		(end 418.086032 -96.201992)
		(width 0.089408)
		(layer "In9.Cu")
		(net "CLK_48M_USB_BMC_R")
	)
	(segment
		(start 422.150286 -77.52588)
		(end 422.150286 -64.835024)
		(width 0.089408)
		(layer "In9.Cu")
		(net "CLK_48M_USB_BMC_R")
	)
	(segment
		(start 417.670488 -108.100876)
		(end 416.315652 -106.74604)
		(width 0.089408)
		(layer "In9.Cu")
		(net "CLK_48M_USB_BMC_R")
	)
	(segment
		(start 430.896268 -63.97244)
		(end 437.114442 -63.97244)
		(width 0.089408)
		(layer "In9.Cu")
		(net "CLK_48M_USB_BMC_R")
	)
	(segment
		(start 418.086032 -96.201992)
		(end 418.714174 -96.201992)
		(width 0.089408)
		(layer "In9.Cu")
		(net "CLK_48M_USB_BMC_R")
	)
	(segment
		(start 406.621742 -114.586258)
		(end 409.820364 -114.586258)
		(width 0.089408)
		(layer "In9.Cu")
		(net "CLK_48M_USB_BMC_R")
	)
	(segment
		(start 412.921704 -112.883696)
		(end 414.381696 -112.883696)
		(width 0.089408)
		(layer "In9.Cu")
		(net "CLK_48M_USB_BMC_R")
	)
	(segment
		(start 421.287702 -93.628464)
		(end 421.287702 -78.388464)
		(width 0.089408)
		(layer "In9.Cu")
		(net "CLK_48M_USB_BMC_R")
	)
	(segment
		(start 416.66414 -114.162586)
		(end 416.927284 -114.162586)
		(width 0.089408)
		(layer "In9.Cu")
		(net "CLK_48M_USB_BMC_R")
	)
	(segment
		(start 423.876724 -63.108586)
		(end 428.619666 -63.108586)
		(width 0.089408)
		(layer "In9.Cu")
		(net "CLK_48M_USB_BMC_R")
	)
	(segment
		(start 417.670488 -110.953804)
		(end 417.670488 -108.100876)
		(width 0.089408)
		(layer "In9.Cu")
		(net "CLK_48M_USB_BMC_R")
	)
	(segment
		(start 411.957266 -113.436908)
		(end 411.957774 -113.4364)
		(width 0.089408)
		(layer "In9.Cu")
		(net "CLK_48M_USB_BMC_R")
	)
	(segment
		(start 411.625034 -113.4364)
		(end 411.625542 -113.436908)
		(width 0.089408)
		(layer "In9.Cu")
		(net "CLK_48M_USB_BMC_R")
	)
	(segment
		(start 410.970222 -113.4364)
		(end 411.625034 -113.4364)
		(width 0.089408)
		(layer "In9.Cu")
		(net "CLK_48M_USB_BMC_R")
	)
	(segment
		(start 429.951388 -63.02756)
		(end 430.896268 -63.97244)
		(width 0.089408)
		(layer "In9.Cu")
		(net "CLK_48M_USB_BMC_R")
	)
	(segment
		(start 422.150286 -64.835024)
		(end 423.876724 -63.108586)
		(width 0.089408)
		(layer "In9.Cu")
		(net "CLK_48M_USB_BMC_R")
	)
	(segment
		(start 405.511 -115.697)
		(end 406.621742 -114.586258)
		(width 0.089408)
		(layer "In9.Cu")
		(net "CLK_48M_USB_BMC_R")
	)
	(segment
		(start 416.927284 -114.162586)
		(end 417.654486 -113.435384)
		(width 0.089408)
		(layer "In9.Cu")
		(net "CLK_48M_USB_BMC_R")
	)
	(segment
		(start 425.076366 -45.564806)
		(end 425.827698 -46.316138)
		(width 0.089408)
		(layer "In11.Cu")
		(net "CLK_48M_USB_BMC_R")
	)
	(segment
		(start 426.714666 -49.214786)
		(end 427.039532 -49.214786)
		(width 0.089408)
		(layer "In11.Cu")
		(net "CLK_48M_USB_BMC_R")
	)
	(segment
		(start 413.464756 -41.759886)
		(end 414.48482 -41.759886)
		(width 0.089408)
		(layer "In11.Cu")
		(net "CLK_48M_USB_BMC_R")
	)
	(segment
		(start 425.827698 -47.205138)
		(end 425.70019 -47.332646)
		(width 0.089408)
		(layer "In11.Cu")
		(net "CLK_48M_USB_BMC_R")
	)
	(segment
		(start 413.090106 -42.134536)
		(end 413.464756 -41.759886)
		(width 0.089408)
		(layer "In11.Cu")
		(net "CLK_48M_USB_BMC_R")
	)
	(segment
		(start 428.133764 -50.309018)
		(end 428.133764 -50.734976)
		(width 0.089408)
		(layer "In11.Cu")
		(net "CLK_48M_USB_BMC_R")
	)
	(segment
		(start 434.837332 -57.438544)
		(end 434.837332 -63.479934)
		(width 0.089408)
		(layer "In11.Cu")
		(net "CLK_48M_USB_BMC_R")
	)
	(segment
		(start 425.70019 -48.20031)
		(end 426.714666 -49.214786)
		(width 0.089408)
		(layer "In11.Cu")
		(net "CLK_48M_USB_BMC_R")
	)
	(segment
		(start 435.360064 -64.002666)
		(end 437.084216 -64.002666)
		(width 0.089408)
		(layer "In11.Cu")
		(net "CLK_48M_USB_BMC_R")
	)
	(segment
		(start 428.133764 -50.734976)
		(end 434.837332 -57.438544)
		(width 0.089408)
		(layer "In11.Cu")
		(net "CLK_48M_USB_BMC_R")
	)
	(segment
		(start 434.837332 -63.479934)
		(end 435.360064 -64.002666)
		(width 0.089408)
		(layer "In11.Cu")
		(net "CLK_48M_USB_BMC_R")
	)
	(segment
		(start 424.024806 -45.564806)
		(end 425.076366 -45.564806)
		(width 0.089408)
		(layer "In11.Cu")
		(net "CLK_48M_USB_BMC_R")
	)
	(segment
		(start 414.48482 -41.759886)
		(end 415.250376 -42.525442)
		(width 0.089408)
		(layer "In11.Cu")
		(net "CLK_48M_USB_BMC_R")
	)
	(segment
		(start 420.985442 -42.525442)
		(end 424.024806 -45.564806)
		(width 0.089408)
		(layer "In11.Cu")
		(net "CLK_48M_USB_BMC_R")
	)
	(segment
		(start 437.084216 -64.002666)
		(end 437.451754 -63.635128)
		(width 0.089408)
		(layer "In11.Cu")
		(net "CLK_48M_USB_BMC_R")
	)
	(segment
		(start 425.827698 -46.316138)
		(end 425.827698 -47.205138)
		(width 0.089408)
		(layer "In11.Cu")
		(net "CLK_48M_USB_BMC_R")
	)
	(segment
		(start 425.70019 -47.332646)
		(end 425.70019 -48.20031)
		(width 0.089408)
		(layer "In11.Cu")
		(net "CLK_48M_USB_BMC_R")
	)
	(segment
		(start 427.039532 -49.214786)
		(end 428.133764 -50.309018)
		(width 0.089408)
		(layer "In11.Cu")
		(net "CLK_48M_USB_BMC_R")
	)
	(segment
		(start 415.250376 -42.525442)
		(end 420.985442 -42.525442)
		(width 0.089408)
		(layer "In11.Cu")
		(net "CLK_48M_USB_BMC_R")
	)
	(segment
		(start 495.346482 -42.688256)
		(end 495.549174 -42.688256)
		(width 0.10795)
		(layer "F.Cu")
		(net "V_IO_VSYNC_J")
	)
	(segment
		(start 493.168686 -44.447714)
		(end 493.916462 -43.699938)
		(width 0.10795)
		(layer "F.Cu")
		(net "V_IO_VSYNC_J")
	)
	(segment
		(start 493.916462 -43.699938)
		(end 494.3348 -43.699938)
		(width 0.10795)
		(layer "F.Cu")
		(net "V_IO_VSYNC_J")
	)
	(segment
		(start 493.168686 -46.569884)
		(end 493.168686 -44.447714)
		(width 0.10795)
		(layer "F.Cu")
		(net "V_IO_VSYNC_J")
	)
	(segment
		(start 495.6175 -42.61993)
		(end 496.704874 -42.61993)
		(width 0.10795)
		(layer "F.Cu")
		(net "V_IO_VSYNC_J")
	)
	(segment
		(start 494.3348 -43.699938)
		(end 495.346482 -42.688256)
		(width 0.10795)
		(layer "F.Cu")
		(net "V_IO_VSYNC_J")
	)
	(segment
		(start 495.549174 -42.688256)
		(end 495.6175 -42.61993)
		(width 0.10795)
		(layer "F.Cu")
		(net "V_IO_VSYNC_J")
	)
	(segment
		(start 493.168686 -46.569884)
		(end 492.228886 -46.569884)
		(width 0.10795)
		(layer "F.Cu")
		(net "V_IO_VSYNC_J")
	)
	(via
		(at 495.549174 -42.688256)
		(size 0.508)
		(drill 0.254)
		(layers "F.Cu" "B.Cu")
		(net "V_IO_VSYNC_J")
	)
	(via
		(at 494.3348 -43.699938)
		(size 0.762)
		(drill 0.381)
		(layers "F.Cu" "B.Cu")
		(net "V_IO_VSYNC_J")
	)
	(segment
		(start 499.0338 -46.101)
		(end 498.863112 -46.271688)
		(width 0.10795)
		(layer "B.Cu")
		(net "V_IO_VSYNC_J")
	)
	(segment
		(start 496.29822 -42.688256)
		(end 499.0338 -45.423836)
		(width 0.10795)
		(layer "B.Cu")
		(net "V_IO_VSYNC_J")
	)
	(segment
		(start 495.549174 -42.688256)
		(end 496.29822 -42.688256)
		(width 0.10795)
		(layer "B.Cu")
		(net "V_IO_VSYNC_J")
	)
	(segment
		(start 498.863112 -46.271688)
		(end 498.487954 -46.271688)
		(width 0.10795)
		(layer "B.Cu")
		(net "V_IO_VSYNC_J")
	)
	(segment
		(start 497.904008 -46.271688)
		(end 498.487954 -46.271688)
		(width 0.10795)
		(layer "B.Cu")
		(net "V_IO_VSYNC_J")
	)
	(segment
		(start 499.0338 -45.423836)
		(end 499.0338 -46.101)
		(width 0.10795)
		(layer "B.Cu")
		(net "V_IO_VSYNC_J")
	)
	(segment
		(start 493.954054 -44.779946)
		(end 493.9157 -44.8183)
		(width 0.10795)
		(layer "F.Cu")
		(net "V_IO_HSYNC_J")
	)
	(segment
		(start 495.824256 -44.619926)
		(end 495.664236 -44.779946)
		(width 0.10795)
		(layer "F.Cu")
		(net "V_IO_HSYNC_J")
	)
	(segment
		(start 496.704874 -44.619926)
		(end 495.824256 -44.619926)
		(width 0.10795)
		(layer "F.Cu")
		(net "V_IO_HSYNC_J")
	)
	(segment
		(start 495.664236 -44.779946)
		(end 493.954054 -44.779946)
		(width 0.10795)
		(layer "F.Cu")
		(net "V_IO_HSYNC_J")
	)
	(via
		(at 496.352322 -43.688)
		(size 0.6604)
		(drill 0.3302)
		(layers "F.Cu" "B.Cu")
		(net "V_IO_HSYNC_J")
	)
	(via
		(at 493.9157 -44.8183)
		(size 0.508)
		(drill 0.254)
		(layers "F.Cu" "B.Cu")
		(net "V_IO_HSYNC_J")
	)
	(segment
		(start 496.6716 -43.688)
		(end 498.487954 -45.504354)
		(width 0.10795)
		(layer "B.Cu")
		(net "V_IO_HSYNC_J")
	)
	(segment
		(start 493.644428 -42.597324)
		(end 493.719104 -42.672)
		(width 0.10795)
		(layer "B.Cu")
		(net "V_IO_HSYNC_J")
	)
	(segment
		(start 493.828324 -44.8183)
		(end 493.214152 -44.204128)
		(width 0.10795)
		(layer "B.Cu")
		(net "V_IO_HSYNC_J")
	)
	(segment
		(start 494.449354 -42.294048)
		(end 495.441224 -43.285918)
		(width 0.10795)
		(layer "B.Cu")
		(net "V_IO_HSYNC_J")
	)
	(segment
		(start 493.719104 -42.672)
		(end 493.719104 -43.056048)
		(width 0.10795)
		(layer "B.Cu")
		(net "V_IO_HSYNC_J")
	)
	(segment
		(start 493.345978 -43.511724)
		(end 493.345978 -43.316398)
		(width 0.10795)
		(layer "B.Cu")
		(net "V_IO_HSYNC_J")
	)
	(segment
		(start 495.95024 -43.285918)
		(end 496.352322 -43.688)
		(width 0.10795)
		(layer "B.Cu")
		(net "V_IO_HSYNC_J")
	)
	(segment
		(start 498.487954 -45.504354)
		(end 498.487954 -45.771816)
		(width 0.10795)
		(layer "B.Cu")
		(net "V_IO_HSYNC_J")
	)
	(segment
		(start 493.214152 -44.204128)
		(end 493.214152 -43.64355)
		(width 0.10795)
		(layer "B.Cu")
		(net "V_IO_HSYNC_J")
	)
	(segment
		(start 493.644428 -42.294048)
		(end 493.644428 -42.597324)
		(width 0.10795)
		(layer "B.Cu")
		(net "V_IO_HSYNC_J")
	)
	(segment
		(start 493.9157 -44.8183)
		(end 493.828324 -44.8183)
		(width 0.10795)
		(layer "B.Cu")
		(net "V_IO_HSYNC_J")
	)
	(segment
		(start 495.441224 -43.285918)
		(end 495.95024 -43.285918)
		(width 0.10795)
		(layer "B.Cu")
		(net "V_IO_HSYNC_J")
	)
	(segment
		(start 493.606328 -43.056048)
		(end 493.719104 -43.056048)
		(width 0.10795)
		(layer "B.Cu")
		(net "V_IO_HSYNC_J")
	)
	(segment
		(start 493.214152 -43.64355)
		(end 493.345978 -43.511724)
		(width 0.10795)
		(layer "B.Cu")
		(net "V_IO_HSYNC_J")
	)
	(segment
		(start 498.487954 -45.771816)
		(end 497.904008 -45.771816)
		(width 0.10795)
		(layer "B.Cu")
		(net "V_IO_HSYNC_J")
	)
	(segment
		(start 496.352322 -43.688)
		(end 496.6716 -43.688)
		(width 0.10795)
		(layer "B.Cu")
		(net "V_IO_HSYNC_J")
	)
	(segment
		(start 493.345978 -43.316398)
		(end 493.606328 -43.056048)
		(width 0.10795)
		(layer "B.Cu")
		(net "V_IO_HSYNC_J")
	)
	(segment
		(start 493.644428 -42.294048)
		(end 494.449354 -42.294048)
		(width 0.10795)
		(layer "B.Cu")
		(net "V_IO_HSYNC_J")
	)
	(segment
		(start 493.4458 -48.7172)
		(end 493.8522 -48.3108)
		(width 0.10795)
		(layer "F.Cu")
		(net "VGA_REAR_VSYNC_S")
	)
	(segment
		(start 492.228886 -47.928022)
		(end 493.014 -48.713136)
		(width 0.10795)
		(layer "F.Cu")
		(net "VGA_REAR_VSYNC_S")
	)
	(segment
		(start 493.014 -48.713136)
		(end 493.018064 -48.7172)
		(width 0.10795)
		(layer "F.Cu")
		(net "VGA_REAR_VSYNC_S")
	)
	(segment
		(start 493.017048 -48.713136)
		(end 493.014 -48.713136)
		(width 0.10795)
		(layer "F.Cu")
		(net "VGA_REAR_VSYNC_S")
	)
	(segment
		(start 492.228886 -47.458884)
		(end 492.228886 -47.928022)
		(width 0.10795)
		(layer "F.Cu")
		(net "VGA_REAR_VSYNC_S")
	)
	(segment
		(start 493.018064 -48.7172)
		(end 493.4458 -48.7172)
		(width 0.10795)
		(layer "F.Cu")
		(net "VGA_REAR_VSYNC_S")
	)
	(via
		(at 493.8522 -48.3108)
		(size 0.508)
		(drill 0.254)
		(layers "F.Cu" "B.Cu")
		(net "VGA_REAR_VSYNC_S")
	)
	(via
		(at 498.625368 -42.655744)
		(size 0.508)
		(drill 0.254)
		(layers "F.Cu" "B.Cu")
		(net "VGA_REAR_VSYNC_S")
	)
	(via
		(at 493.017048 -48.713136)
		(size 0.762)
		(drill 0.381)
		(layers "F.Cu" "B.Cu")
		(net "VGA_REAR_VSYNC_S")
	)
	(segment
		(start 498.625368 -42.444416)
		(end 498.792754 -42.27703)
		(width 0.10795)
		(layer "B.Cu")
		(net "VGA_REAR_VSYNC_S")
	)
	(segment
		(start 498.792754 -42.27703)
		(end 498.792754 -41.545256)
		(width 0.10795)
		(layer "B.Cu")
		(net "VGA_REAR_VSYNC_S")
	)
	(segment
		(start 498.625368 -42.655744)
		(end 498.625368 -42.444416)
		(width 0.10795)
		(layer "B.Cu")
		(net "VGA_REAR_VSYNC_S")
	)
	(segment
		(start 497.8146 -43.466512)
		(end 497.8146 -44.9326)
		(width 0.089408)
		(layer "In4.Cu")
		(net "VGA_REAR_VSYNC_S")
	)
	(segment
		(start 497.8146 -44.9326)
		(end 494.4364 -48.3108)
		(width 0.089408)
		(layer "In4.Cu")
		(net "VGA_REAR_VSYNC_S")
	)
	(segment
		(start 494.4364 -48.3108)
		(end 493.8522 -48.3108)
		(width 0.089408)
		(layer "In4.Cu")
		(net "VGA_REAR_VSYNC_S")
	)
	(segment
		(start 498.625368 -42.655744)
		(end 497.8146 -43.466512)
		(width 0.089408)
		(layer "In4.Cu")
		(net "VGA_REAR_VSYNC_S")
	)
	(via
		(at 492.2012 -41.402)
		(size 0.6604)
		(drill 0.3302)
		(layers "F.Cu" "B.Cu")
		(net "VGA_REAR_HSYNC_S")
	)
	(segment
		(start 493.644428 -41.405048)
		(end 493.495076 -41.5544)
		(width 0.10795)
		(layer "B.Cu")
		(net "VGA_REAR_HSYNC_S")
	)
	(segment
		(start 494.831878 -41.494456)
		(end 495.025934 -41.494456)
		(width 0.10795)
		(layer "B.Cu")
		(net "VGA_REAR_HSYNC_S")
	)
	(segment
		(start 493.495076 -41.5544)
		(end 492.3536 -41.5544)
		(width 0.10795)
		(layer "B.Cu")
		(net "VGA_REAR_HSYNC_S")
	)
	(segment
		(start 493.644428 -41.405048)
		(end 494.74247 -41.405048)
		(width 0.10795)
		(layer "B.Cu")
		(net "VGA_REAR_HSYNC_S")
	)
	(segment
		(start 492.3536 -41.5544)
		(end 492.2012 -41.402)
		(width 0.10795)
		(layer "B.Cu")
		(net "VGA_REAR_HSYNC_S")
	)
	(segment
		(start 494.74247 -41.405048)
		(end 494.831878 -41.494456)
		(width 0.10795)
		(layer "B.Cu")
		(net "VGA_REAR_HSYNC_S")
	)
	(segment
		(start 496.82781 -48.742854)
		(end 496.82781 -49.946814)
		(width 0.508)
		(layer "F.Cu")
		(net "P5V_VGA")
	)
	(segment
		(start 496.82781 -49.946814)
		(end 496.326668 -50.447956)
		(width 0.508)
		(layer "F.Cu")
		(net "P5V_VGA")
	)
	(segment
		(start 496.326668 -50.447956)
		(end 495.990118 -50.447956)
		(width 0.508)
		(layer "F.Cu")
		(net "P5V_VGA")
	)
	(segment
		(start 496.704874 -48.619918)
		(end 496.82781 -48.742854)
		(width 0.508)
		(layer "F.Cu")
		(net "P5V_VGA")
	)
	(via
		(at 495.990118 -50.447956)
		(size 0.508)
		(drill 0.254)
		(layers "F.Cu" "B.Cu")
		(net "P5V_VGA")
	)
	(via
		(at 493.35563 -52.45735)
		(size 0.6604)
		(drill 0.3302)
		(layers "F.Cu" "B.Cu")
		(net "P5V_VGA")
	)
	(segment
		(start 489.850176 -51.816)
		(end 490.019086 -51.64709)
		(width 0.508)
		(layer "B.Cu")
		(net "P5V_VGA")
	)
	(segment
		(start 491.34649 -51.2064)
		(end 492.847376 -51.2064)
		(width 0.508)
		(layer "B.Cu")
		(net "P5V_VGA")
	)
	(segment
		(start 489.42752 -51.816)
		(end 489.850176 -51.816)
		(width 0.508)
		(layer "B.Cu")
		(net "P5V_VGA")
	)
	(segment
		(start 493.35563 -52.45735)
		(end 493.36579 -52.46751)
		(width 0.508)
		(layer "B.Cu")
		(net "P5V_VGA")
	)
	(segment
		(start 493.970564 -52.46751)
		(end 495.990118 -50.447956)
		(width 0.508)
		(layer "B.Cu")
		(net "P5V_VGA")
	)
	(segment
		(start 490.9058 -51.64709)
		(end 491.34649 -51.2064)
		(width 0.508)
		(layer "B.Cu")
		(net "P5V_VGA")
	)
	(segment
		(start 490.019086 -51.64709)
		(end 490.9058 -51.64709)
		(width 0.508)
		(layer "B.Cu")
		(net "P5V_VGA")
	)
	(segment
		(start 493.36579 -52.46751)
		(end 493.970564 -52.46751)
		(width 0.508)
		(layer "B.Cu")
		(net "P5V_VGA")
	)
	(segment
		(start 492.847376 -51.2064)
		(end 493.35563 -51.714654)
		(width 0.508)
		(layer "B.Cu")
		(net "P5V_VGA")
	)
	(segment
		(start 488.297474 -52.946046)
		(end 489.42752 -51.816)
		(width 0.508)
		(layer "B.Cu")
		(net "P5V_VGA")
	)
	(segment
		(start 493.35563 -51.714654)
		(end 493.35563 -52.45735)
		(width 0.508)
		(layer "B.Cu")
		(net "P5V_VGA")
	)
	(segment
		(start 489.744004 -33.415986)
		(end 489.18495 -33.415986)
		(width 0.10795)
		(layer "F.Cu")
		(net "V_IO_R_J")
	)
	(segment
		(start 489.876592 -33.283398)
		(end 489.744004 -33.415986)
		(width 0.10795)
		(layer "F.Cu")
		(net "V_IO_R_J")
	)
	(segment
		(start 490.158024 -33.283398)
		(end 489.876592 -33.283398)
		(width 0.10795)
		(layer "F.Cu")
		(net "V_IO_R_J")
	)
	(segment
		(start 491.197646 -34.186876)
		(end 490.6137 -34.186876)
		(width 0.10795)
		(layer "F.Cu")
		(net "V_IO_R_J")
	)
	(segment
		(start 489.077 -33.523936)
		(end 489.077 -33.655)
		(width 0.10795)
		(layer "F.Cu")
		(net "V_IO_R_J")
	)
	(segment
		(start 492.083598 -34.452052)
		(end 493.128046 -35.4965)
		(width 0.10795)
		(layer "F.Cu")
		(net "V_IO_R_J")
	)
	(segment
		(start 490.091476 -34.186876)
		(end 490.6137 -34.186876)
		(width 0.10795)
		(layer "F.Cu")
		(net "V_IO_R_J")
	)
	(segment
		(start 491.197646 -34.186876)
		(end 491.44301 -34.186876)
		(width 0.10795)
		(layer "F.Cu")
		(net "V_IO_R_J")
	)
	(segment
		(start 496.07597 -36.619942)
		(end 496.704874 -36.619942)
		(width 0.10795)
		(layer "F.Cu")
		(net "V_IO_R_J")
	)
	(segment
		(start 489.5596 -33.655)
		(end 490.091476 -34.186876)
		(width 0.10795)
		(layer "F.Cu")
		(net "V_IO_R_J")
	)
	(segment
		(start 489.077 -33.655)
		(end 489.5596 -33.655)
		(width 0.10795)
		(layer "F.Cu")
		(net "V_IO_R_J")
	)
	(segment
		(start 493.128046 -35.4965)
		(end 494.599468 -36.967922)
		(width 0.10795)
		(layer "F.Cu")
		(net "V_IO_R_J")
	)
	(segment
		(start 489.18495 -33.415986)
		(end 489.077 -33.523936)
		(width 0.10795)
		(layer "F.Cu")
		(net "V_IO_R_J")
	)
	(segment
		(start 491.44301 -34.186876)
		(end 492.083598 -34.452052)
		(width 0.10795)
		(layer "F.Cu")
		(net "V_IO_R_J")
	)
	(segment
		(start 495.72799 -36.967922)
		(end 496.07597 -36.619942)
		(width 0.10795)
		(layer "F.Cu")
		(net "V_IO_R_J")
	)
	(segment
		(start 494.599468 -36.967922)
		(end 495.72799 -36.967922)
		(width 0.10795)
		(layer "F.Cu")
		(net "V_IO_R_J")
	)
	(via
		(at 490.158024 -33.283398)
		(size 0.508)
		(drill 0.254)
		(layers "F.Cu" "B.Cu")
		(net "V_IO_R_J")
	)
	(via
		(at 493.128046 -35.4965)
		(size 0.762)
		(drill 0.381)
		(layers "F.Cu" "B.Cu")
		(net "V_IO_R_J")
	)
	(via
		(at 421.7416 -25.019)
		(size 0.508)
		(drill 0.254)
		(layers "F.Cu" "B.Cu")
		(net "V_IO_R_J")
	)
	(via
		(at 471.2716 -10.3632)
		(size 0.508)
		(drill 0.254)
		(layers "F.Cu" "B.Cu")
		(net "V_IO_R_J")
	)
	(segment
		(start 421.7416 -25.394666)
		(end 421.482266 -25.654)
		(width 0.10795)
		(layer "B.Cu")
		(net "V_IO_R_J")
	)
	(segment
		(start 421.7416 -25.019)
		(end 421.7416 -25.394666)
		(width 0.10795)
		(layer "B.Cu")
		(net "V_IO_R_J")
	)
	(segment
		(start 420.3192 -25.4762)
		(end 419.608 -24.765)
		(width 0.1143)
		(layer "B.Cu")
		(net "V_IO_R_J")
	)
	(segment
		(start 420.497 -25.654)
		(end 420.3192 -25.4762)
		(width 0.10795)
		(layer "B.Cu")
		(net "V_IO_R_J")
	)
	(segment
		(start 420.624 -25.654)
		(end 420.497 -25.654)
		(width 0.10795)
		(layer "B.Cu")
		(net "V_IO_R_J")
	)
	(segment
		(start 421.482266 -25.654)
		(end 420.624 -25.654)
		(width 0.10795)
		(layer "B.Cu")
		(net "V_IO_R_J")
	)
	(segment
		(start 471.801444 -9.347962)
		(end 471.969338 -9.180068)
		(width 0.089408)
		(layer "In4.Cu")
		(net "V_IO_R_J")
	)
	(segment
		(start 477.497902 -12.48156)
		(end 478.2312 -13.214858)
		(width 0.089408)
		(layer "In4.Cu")
		(net "V_IO_R_J")
	)
	(segment
		(start 488.979464 -30.598618)
		(end 488.979464 -30.972506)
		(width 0.089408)
		(layer "In4.Cu")
		(net "V_IO_R_J")
	)
	(segment
		(start 489.199428 -31.19247)
		(end 489.199428 -32.324802)
		(width 0.089408)
		(layer "In4.Cu")
		(net "V_IO_R_J")
	)
	(segment
		(start 485.793288 -19.740626)
		(end 485.793288 -20.48383)
		(width 0.089408)
		(layer "In4.Cu")
		(net "V_IO_R_J")
	)
	(segment
		(start 474.439488 -9.180068)
		(end 475.91472 -10.6553)
		(width 0.089408)
		(layer "In4.Cu")
		(net "V_IO_R_J")
	)
	(segment
		(start 478.2312 -13.214858)
		(end 478.2312 -15.475458)
		(width 0.089408)
		(layer "In4.Cu")
		(net "V_IO_R_J")
	)
	(segment
		(start 484.57358 -18.520918)
		(end 485.793288 -19.740626)
		(width 0.089408)
		(layer "In4.Cu")
		(net "V_IO_R_J")
	)
	(segment
		(start 483.830376 -18.520918)
		(end 484.57358 -18.520918)
		(width 0.089408)
		(layer "In4.Cu")
		(net "V_IO_R_J")
	)
	(segment
		(start 476.71482 -12.48156)
		(end 477.497902 -12.48156)
		(width 0.089408)
		(layer "In4.Cu")
		(net "V_IO_R_J")
	)
	(segment
		(start 485.793288 -20.48383)
		(end 485.839008 -20.52955)
		(width 0.089408)
		(layer "In4.Cu")
		(net "V_IO_R_J")
	)
	(segment
		(start 485.839008 -25.965912)
		(end 489.105702 -29.232606)
		(width 0.089408)
		(layer "In4.Cu")
		(net "V_IO_R_J")
	)
	(segment
		(start 478.2312 -15.475458)
		(end 480.265232 -17.50949)
		(width 0.089408)
		(layer "In4.Cu")
		(net "V_IO_R_J")
	)
	(segment
		(start 471.969338 -9.180068)
		(end 474.439488 -9.180068)
		(width 0.089408)
		(layer "In4.Cu")
		(net "V_IO_R_J")
	)
	(segment
		(start 480.265232 -17.50949)
		(end 482.818948 -17.50949)
		(width 0.089408)
		(layer "In4.Cu")
		(net "V_IO_R_J")
	)
	(segment
		(start 489.105702 -29.232606)
		(end 489.105702 -30.47238)
		(width 0.089408)
		(layer "In4.Cu")
		(net "V_IO_R_J")
	)
	(segment
		(start 475.91472 -11.68146)
		(end 476.71482 -12.48156)
		(width 0.089408)
		(layer "In4.Cu")
		(net "V_IO_R_J")
	)
	(segment
		(start 489.199428 -32.324802)
		(end 490.158024 -33.283398)
		(width 0.089408)
		(layer "In4.Cu")
		(net "V_IO_R_J")
	)
	(segment
		(start 485.839008 -20.52955)
		(end 485.839008 -25.965912)
		(width 0.089408)
		(layer "In4.Cu")
		(net "V_IO_R_J")
	)
	(segment
		(start 489.105702 -30.47238)
		(end 488.979464 -30.598618)
		(width 0.089408)
		(layer "In4.Cu")
		(net "V_IO_R_J")
	)
	(segment
		(start 488.979464 -30.972506)
		(end 489.199428 -31.19247)
		(width 0.089408)
		(layer "In4.Cu")
		(net "V_IO_R_J")
	)
	(segment
		(start 471.801444 -9.833356)
		(end 471.801444 -9.347962)
		(width 0.089408)
		(layer "In4.Cu")
		(net "V_IO_R_J")
	)
	(segment
		(start 475.91472 -10.6553)
		(end 475.91472 -11.68146)
		(width 0.089408)
		(layer "In4.Cu")
		(net "V_IO_R_J")
	)
	(segment
		(start 482.818948 -17.50949)
		(end 483.830376 -18.520918)
		(width 0.089408)
		(layer "In4.Cu")
		(net "V_IO_R_J")
	)
	(segment
		(start 471.2716 -10.3632)
		(end 471.801444 -9.833356)
		(width 0.089408)
		(layer "In4.Cu")
		(net "V_IO_R_J")
	)
	(segment
		(start 446.418716 -23.697438)
		(end 448.437762 -23.697438)
		(width 0.089408)
		(layer "In11.Cu")
		(net "V_IO_R_J")
	)
	(segment
		(start 432.165252 -23.57628)
		(end 432.556666 -23.967694)
		(width 0.089408)
		(layer "In11.Cu")
		(net "V_IO_R_J")
	)
	(segment
		(start 428.544228 -24.638508)
		(end 429.606456 -23.57628)
		(width 0.089408)
		(layer "In11.Cu")
		(net "V_IO_R_J")
	)
	(segment
		(start 432.556666 -23.967694)
		(end 433.594256 -23.967694)
		(width 0.089408)
		(layer "In11.Cu")
		(net "V_IO_R_J")
	)
	(segment
		(start 421.7416 -25.019)
		(end 422.122092 -24.638508)
		(width 0.089408)
		(layer "In11.Cu")
		(net "V_IO_R_J")
	)
	(segment
		(start 433.944522 -23.617428)
		(end 436.819802 -23.617428)
		(width 0.089408)
		(layer "In11.Cu")
		(net "V_IO_R_J")
	)
	(segment
		(start 448.437762 -23.697438)
		(end 448.829938 -23.305262)
		(width 0.089408)
		(layer "In11.Cu")
		(net "V_IO_R_J")
	)
	(segment
		(start 457.140818 -16.358108)
		(end 457.140818 -14.330934)
		(width 0.089408)
		(layer "In11.Cu")
		(net "V_IO_R_J")
	)
	(segment
		(start 448.829938 -23.305262)
		(end 450.162422 -23.305262)
		(width 0.089408)
		(layer "In11.Cu")
		(net "V_IO_R_J")
	)
	(segment
		(start 437.557926 -22.879304)
		(end 445.600582 -22.879304)
		(width 0.089408)
		(layer "In11.Cu")
		(net "V_IO_R_J")
	)
	(segment
		(start 453.849232 -19.618452)
		(end 453.849232 -17.722342)
		(width 0.089408)
		(layer "In11.Cu")
		(net "V_IO_R_J")
	)
	(segment
		(start 454.819258 -16.752316)
		(end 456.74661 -16.752316)
		(width 0.089408)
		(layer "In11.Cu")
		(net "V_IO_R_J")
	)
	(segment
		(start 470.343738 -11.697462)
		(end 471.2716 -10.7696)
		(width 0.089408)
		(layer "In11.Cu")
		(net "V_IO_R_J")
	)
	(segment
		(start 471.2716 -10.7696)
		(end 471.2716 -10.3632)
		(width 0.089408)
		(layer "In11.Cu")
		(net "V_IO_R_J")
	)
	(segment
		(start 450.162422 -23.305262)
		(end 453.849232 -19.618452)
		(width 0.089408)
		(layer "In11.Cu")
		(net "V_IO_R_J")
	)
	(segment
		(start 433.594256 -23.967694)
		(end 433.944522 -23.617428)
		(width 0.089408)
		(layer "In11.Cu")
		(net "V_IO_R_J")
	)
	(segment
		(start 429.606456 -23.57628)
		(end 432.165252 -23.57628)
		(width 0.089408)
		(layer "In11.Cu")
		(net "V_IO_R_J")
	)
	(segment
		(start 422.122092 -24.638508)
		(end 428.544228 -24.638508)
		(width 0.089408)
		(layer "In11.Cu")
		(net "V_IO_R_J")
	)
	(segment
		(start 463.588608 -12.960096)
		(end 467.323678 -12.960096)
		(width 0.089408)
		(layer "In11.Cu")
		(net "V_IO_R_J")
	)
	(segment
		(start 456.74661 -16.752316)
		(end 457.140818 -16.358108)
		(width 0.089408)
		(layer "In11.Cu")
		(net "V_IO_R_J")
	)
	(segment
		(start 460.951834 -13.196824)
		(end 463.35188 -13.196824)
		(width 0.089408)
		(layer "In11.Cu")
		(net "V_IO_R_J")
	)
	(segment
		(start 467.323678 -12.960096)
		(end 468.586312 -11.697462)
		(width 0.089408)
		(layer "In11.Cu")
		(net "V_IO_R_J")
	)
	(segment
		(start 463.35188 -13.196824)
		(end 463.588608 -12.960096)
		(width 0.089408)
		(layer "In11.Cu")
		(net "V_IO_R_J")
	)
	(segment
		(start 457.140818 -14.330934)
		(end 457.551282 -13.92047)
		(width 0.089408)
		(layer "In11.Cu")
		(net "V_IO_R_J")
	)
	(segment
		(start 436.819802 -23.617428)
		(end 437.557926 -22.879304)
		(width 0.089408)
		(layer "In11.Cu")
		(net "V_IO_R_J")
	)
	(segment
		(start 453.849232 -17.722342)
		(end 454.819258 -16.752316)
		(width 0.089408)
		(layer "In11.Cu")
		(net "V_IO_R_J")
	)
	(segment
		(start 445.600582 -22.879304)
		(end 446.418716 -23.697438)
		(width 0.089408)
		(layer "In11.Cu")
		(net "V_IO_R_J")
	)
	(segment
		(start 460.228188 -13.92047)
		(end 460.951834 -13.196824)
		(width 0.089408)
		(layer "In11.Cu")
		(net "V_IO_R_J")
	)
	(segment
		(start 457.551282 -13.92047)
		(end 460.228188 -13.92047)
		(width 0.089408)
		(layer "In11.Cu")
		(net "V_IO_R_J")
	)
	(segment
		(start 468.586312 -11.697462)
		(end 470.343738 -11.697462)
		(width 0.089408)
		(layer "In11.Cu")
		(net "V_IO_R_J")
	)
	(segment
		(start 489.0262 -34.8742)
		(end 489.338874 -35.186874)
		(width 0.10795)
		(layer "F.Cu")
		(net "V_IO_G_J")
	)
	(segment
		(start 495.19078 -37.95141)
		(end 494.686336 -37.95141)
		(width 0.10795)
		(layer "F.Cu")
		(net "V_IO_G_J")
	)
	(segment
		(start 495.859308 -38.619938)
		(end 495.19078 -37.95141)
		(width 0.10795)
		(layer "F.Cu")
		(net "V_IO_G_J")
	)
	(segment
		(start 489.0262 -35.719258)
		(end 489.040932 -35.73399)
		(width 0.10795)
		(layer "F.Cu")
		(net "V_IO_G_J")
	)
	(segment
		(start 489.338874 -35.186874)
		(end 490.6137 -35.186874)
		(width 0.10795)
		(layer "F.Cu")
		(net "V_IO_G_J")
	)
	(segment
		(start 491.9218 -35.186874)
		(end 491.197646 -35.186874)
		(width 0.10795)
		(layer "F.Cu")
		(net "V_IO_G_J")
	)
	(segment
		(start 491.197646 -35.186874)
		(end 490.6137 -35.186874)
		(width 0.10795)
		(layer "F.Cu")
		(net "V_IO_G_J")
	)
	(segment
		(start 496.704874 -38.619938)
		(end 495.859308 -38.619938)
		(width 0.10795)
		(layer "F.Cu")
		(net "V_IO_G_J")
	)
	(segment
		(start 489.0262 -34.8742)
		(end 489.0262 -35.719258)
		(width 0.10795)
		(layer "F.Cu")
		(net "V_IO_G_J")
	)
	(segment
		(start 493.73409 -36.999164)
		(end 491.9218 -35.186874)
		(width 0.10795)
		(layer "F.Cu")
		(net "V_IO_G_J")
	)
	(segment
		(start 494.686336 -37.95141)
		(end 493.73409 -36.999164)
		(width 0.10795)
		(layer "F.Cu")
		(net "V_IO_G_J")
	)
	(via
		(at 470.780618 -8.89)
		(size 0.508)
		(drill 0.254)
		(layers "F.Cu" "B.Cu")
		(net "V_IO_G_J")
	)
	(via
		(at 493.73409 -36.999164)
		(size 0.762)
		(drill 0.381)
		(layers "F.Cu" "B.Cu")
		(net "V_IO_G_J")
	)
	(via
		(at 489.040932 -35.73399)
		(size 0.508)
		(drill 0.254)
		(layers "F.Cu" "B.Cu")
		(net "V_IO_G_J")
	)
	(via
		(at 422.1226 -23.4696)
		(size 0.508)
		(drill 0.254)
		(layers "F.Cu" "B.Cu")
		(net "V_IO_G_J")
	)
	(segment
		(start 420.878 -23.114)
		(end 420.624 -23.114)
		(width 0.10795)
		(layer "B.Cu")
		(net "V_IO_G_J")
	)
	(segment
		(start 421.9956 -23.3426)
		(end 421.1066 -23.3426)
		(width 0.10795)
		(layer "B.Cu")
		(net "V_IO_G_J")
	)
	(segment
		(start 420.547546 -23.114)
		(end 420.624 -23.114)
		(width 0.10795)
		(layer "B.Cu")
		(net "V_IO_G_J")
	)
	(segment
		(start 422.1226 -23.4696)
		(end 421.9956 -23.3426)
		(width 0.10795)
		(layer "B.Cu")
		(net "V_IO_G_J")
	)
	(segment
		(start 420.166546 -23.495)
		(end 420.547546 -23.114)
		(width 0.10795)
		(layer "B.Cu")
		(net "V_IO_G_J")
	)
	(segment
		(start 419.608 -23.495)
		(end 420.166546 -23.495)
		(width 0.10795)
		(layer "B.Cu")
		(net "V_IO_G_J")
	)
	(segment
		(start 421.1066 -23.3426)
		(end 420.878 -23.114)
		(width 0.10795)
		(layer "B.Cu")
		(net "V_IO_G_J")
	)
	(segment
		(start 484.077772 -17.923256)
		(end 483.066598 -16.912082)
		(width 0.089408)
		(layer "In4.Cu")
		(net "V_IO_G_J")
	)
	(segment
		(start 490.755432 -34.872168)
		(end 490.755432 -31.675832)
		(width 0.089408)
		(layer "In4.Cu")
		(net "V_IO_G_J")
	)
	(segment
		(start 489.8898 -30.8102)
		(end 489.8898 -29.171646)
		(width 0.089408)
		(layer "In4.Cu")
		(net "V_IO_G_J")
	)
	(segment
		(start 479.044 -15.4432)
		(end 479.044 -13.1826)
		(width 0.089408)
		(layer "In4.Cu")
		(net "V_IO_G_J")
	)
	(segment
		(start 470.780618 -8.515096)
		(end 470.780618 -8.89)
		(width 0.089408)
		(layer "In4.Cu")
		(net "V_IO_G_J")
	)
	(segment
		(start 474.331284 -8.152384)
		(end 471.14333 -8.152384)
		(width 0.089408)
		(layer "In4.Cu")
		(net "V_IO_G_J")
	)
	(segment
		(start 489.8898 -29.171646)
		(end 486.436416 -25.718262)
		(width 0.089408)
		(layer "In4.Cu")
		(net "V_IO_G_J")
	)
	(segment
		(start 477.181672 -11.884152)
		(end 476.533464 -11.235944)
		(width 0.089408)
		(layer "In4.Cu")
		(net "V_IO_G_J")
	)
	(segment
		(start 479.044 -13.1826)
		(end 477.745552 -11.884152)
		(width 0.089408)
		(layer "In4.Cu")
		(net "V_IO_G_J")
	)
	(segment
		(start 489.040932 -35.73399)
		(end 489.392722 -35.3822)
		(width 0.089408)
		(layer "In4.Cu")
		(net "V_IO_G_J")
	)
	(segment
		(start 490.2454 -35.3822)
		(end 490.755432 -34.872168)
		(width 0.089408)
		(layer "In4.Cu")
		(net "V_IO_G_J")
	)
	(segment
		(start 480.512882 -16.912082)
		(end 479.044 -15.4432)
		(width 0.089408)
		(layer "In4.Cu")
		(net "V_IO_G_J")
	)
	(segment
		(start 486.436416 -25.718262)
		(end 486.436416 -19.538696)
		(width 0.089408)
		(layer "In4.Cu")
		(net "V_IO_G_J")
	)
	(segment
		(start 483.066598 -16.912082)
		(end 480.512882 -16.912082)
		(width 0.089408)
		(layer "In4.Cu")
		(net "V_IO_G_J")
	)
	(segment
		(start 476.533464 -10.354564)
		(end 474.331284 -8.152384)
		(width 0.089408)
		(layer "In4.Cu")
		(net "V_IO_G_J")
	)
	(segment
		(start 477.745552 -11.884152)
		(end 477.181672 -11.884152)
		(width 0.089408)
		(layer "In4.Cu")
		(net "V_IO_G_J")
	)
	(segment
		(start 489.392722 -35.3822)
		(end 490.2454 -35.3822)
		(width 0.089408)
		(layer "In4.Cu")
		(net "V_IO_G_J")
	)
	(segment
		(start 471.14333 -8.152384)
		(end 470.780618 -8.515096)
		(width 0.089408)
		(layer "In4.Cu")
		(net "V_IO_G_J")
	)
	(segment
		(start 490.755432 -31.675832)
		(end 489.8898 -30.8102)
		(width 0.089408)
		(layer "In4.Cu")
		(net "V_IO_G_J")
	)
	(segment
		(start 484.820976 -17.923256)
		(end 484.077772 -17.923256)
		(width 0.089408)
		(layer "In4.Cu")
		(net "V_IO_G_J")
	)
	(segment
		(start 486.436416 -19.538696)
		(end 484.820976 -17.923256)
		(width 0.089408)
		(layer "In4.Cu")
		(net "V_IO_G_J")
	)
	(segment
		(start 476.533464 -11.235944)
		(end 476.533464 -10.354564)
		(width 0.089408)
		(layer "In4.Cu")
		(net "V_IO_G_J")
	)
	(segment
		(start 426.459904 -24.022558)
		(end 426.326046 -24.156416)
		(width 0.089408)
		(layer "In11.Cu")
		(net "V_IO_G_J")
	)
	(segment
		(start 470.780618 -8.89)
		(end 470.780618 -9.36244)
		(width 0.089408)
		(layer "In11.Cu")
		(net "V_IO_G_J")
	)
	(segment
		(start 426.57141 -24.022558)
		(end 426.459904 -24.022558)
		(width 0.089408)
		(layer "In11.Cu")
		(net "V_IO_G_J")
	)
	(segment
		(start 453.251824 -17.474692)
		(end 453.251824 -19.370802)
		(width 0.089408)
		(layer "In11.Cu")
		(net "V_IO_G_J")
	)
	(segment
		(start 454.809352 -15.439644)
		(end 454.809352 -15.917164)
		(width 0.089408)
		(layer "In11.Cu")
		(net "V_IO_G_J")
	)
	(segment
		(start 433.346606 -23.370286)
		(end 432.816 -23.370286)
		(width 0.089408)
		(layer "In11.Cu")
		(net "V_IO_G_J")
	)
	(segment
		(start 429.358806 -22.978872)
		(end 428.57166 -23.766018)
		(width 0.089408)
		(layer "In11.Cu")
		(net "V_IO_G_J")
	)
	(segment
		(start 470.6239 -9.519158)
		(end 470.6239 -10.56894)
		(width 0.089408)
		(layer "In11.Cu")
		(net "V_IO_G_J")
	)
	(segment
		(start 470.780618 -9.36244)
		(end 470.6239 -9.519158)
		(width 0.089408)
		(layer "In11.Cu")
		(net "V_IO_G_J")
	)
	(segment
		(start 426.82795 -23.766018)
		(end 426.57141 -24.022558)
		(width 0.089408)
		(layer "In11.Cu")
		(net "V_IO_G_J")
	)
	(segment
		(start 460.704184 -12.599416)
		(end 460.15656 -13.14704)
		(width 0.089408)
		(layer "In11.Cu")
		(net "V_IO_G_J")
	)
	(segment
		(start 470.092786 -11.100054)
		(end 468.338662 -11.100054)
		(width 0.089408)
		(layer "In11.Cu")
		(net "V_IO_G_J")
	)
	(segment
		(start 454.809352 -15.917164)
		(end 453.251824 -17.474692)
		(width 0.089408)
		(layer "In11.Cu")
		(net "V_IO_G_J")
	)
	(segment
		(start 436.321708 -23.02002)
		(end 433.696872 -23.02002)
		(width 0.089408)
		(layer "In11.Cu")
		(net "V_IO_G_J")
	)
	(segment
		(start 426.326046 -24.156416)
		(end 422.809416 -24.156416)
		(width 0.089408)
		(layer "In11.Cu")
		(net "V_IO_G_J")
	)
	(segment
		(start 453.251824 -19.370802)
		(end 451.20941 -21.413216)
		(width 0.089408)
		(layer "In11.Cu")
		(net "V_IO_G_J")
	)
	(segment
		(start 451.20941 -21.413216)
		(end 449.756276 -21.413216)
		(width 0.089408)
		(layer "In11.Cu")
		(net "V_IO_G_J")
	)
	(segment
		(start 428.57166 -23.766018)
		(end 426.82795 -23.766018)
		(width 0.089408)
		(layer "In11.Cu")
		(net "V_IO_G_J")
	)
	(segment
		(start 463.340958 -12.362688)
		(end 463.10423 -12.599416)
		(width 0.089408)
		(layer "In11.Cu")
		(net "V_IO_G_J")
	)
	(segment
		(start 457.101956 -13.14704)
		(end 454.809352 -15.439644)
		(width 0.089408)
		(layer "In11.Cu")
		(net "V_IO_G_J")
	)
	(segment
		(start 449.756276 -21.413216)
		(end 448.887596 -22.281896)
		(width 0.089408)
		(layer "In11.Cu")
		(net "V_IO_G_J")
	)
	(segment
		(start 437.059832 -22.281896)
		(end 436.321708 -23.02002)
		(width 0.089408)
		(layer "In11.Cu")
		(net "V_IO_G_J")
	)
	(segment
		(start 468.338662 -11.100054)
		(end 467.076028 -12.362688)
		(width 0.089408)
		(layer "In11.Cu")
		(net "V_IO_G_J")
	)
	(segment
		(start 463.10423 -12.599416)
		(end 460.704184 -12.599416)
		(width 0.089408)
		(layer "In11.Cu")
		(net "V_IO_G_J")
	)
	(segment
		(start 433.696872 -23.02002)
		(end 433.346606 -23.370286)
		(width 0.089408)
		(layer "In11.Cu")
		(net "V_IO_G_J")
	)
	(segment
		(start 460.15656 -13.14704)
		(end 457.101956 -13.14704)
		(width 0.089408)
		(layer "In11.Cu")
		(net "V_IO_G_J")
	)
	(segment
		(start 432.424586 -22.978872)
		(end 429.358806 -22.978872)
		(width 0.089408)
		(layer "In11.Cu")
		(net "V_IO_G_J")
	)
	(segment
		(start 467.076028 -12.362688)
		(end 463.340958 -12.362688)
		(width 0.089408)
		(layer "In11.Cu")
		(net "V_IO_G_J")
	)
	(segment
		(start 448.887596 -22.281896)
		(end 437.059832 -22.281896)
		(width 0.089408)
		(layer "In11.Cu")
		(net "V_IO_G_J")
	)
	(segment
		(start 422.809416 -24.156416)
		(end 422.1226 -23.4696)
		(width 0.089408)
		(layer "In11.Cu")
		(net "V_IO_G_J")
	)
	(segment
		(start 470.6239 -10.56894)
		(end 470.092786 -11.100054)
		(width 0.089408)
		(layer "In11.Cu")
		(net "V_IO_G_J")
	)
	(segment
		(start 432.816 -23.370286)
		(end 432.424586 -22.978872)
		(width 0.089408)
		(layer "In11.Cu")
		(net "V_IO_G_J")
	)
	(segment
		(start 491.542578 -35.687)
		(end 491.197646 -35.687)
		(width 0.10795)
		(layer "F.Cu")
		(net "V_IO_B_J")
	)
	(segment
		(start 495.716052 -40.619934)
		(end 494.876328 -41.459658)
		(width 0.10795)
		(layer "F.Cu")
		(net "V_IO_B_J")
	)
	(segment
		(start 494.876328 -41.459658)
		(end 494.51895 -41.459658)
		(width 0.10795)
		(layer "F.Cu")
		(net "V_IO_B_J")
	)
	(segment
		(start 494.151412 -41.459658)
		(end 493.43691 -40.745156)
		(width 0.10795)
		(layer "F.Cu")
		(net "V_IO_B_J")
	)
	(segment
		(start 490.474 -37.338)
		(end 491.2106 -37.338)
		(width 0.10795)
		(layer "F.Cu")
		(net "V_IO_B_J")
	)
	(segment
		(start 493.43691 -40.745156)
		(end 493.43691 -37.573204)
		(width 0.10795)
		(layer "F.Cu")
		(net "V_IO_B_J")
	)
	(segment
		(start 491.66653 -35.802824)
		(end 491.658402 -35.802824)
		(width 0.10795)
		(layer "F.Cu")
		(net "V_IO_B_J")
	)
	(segment
		(start 490.474 -36.576)
		(end 490.474 -37.338)
		(width 0.10795)
		(layer "F.Cu")
		(net "V_IO_B_J")
	)
	(segment
		(start 494.51895 -41.459658)
		(end 494.151412 -41.459658)
		(width 0.10795)
		(layer "F.Cu")
		(net "V_IO_B_J")
	)
	(segment
		(start 490.6137 -36.4363)
		(end 490.474 -36.576)
		(width 0.10795)
		(layer "F.Cu")
		(net "V_IO_B_J")
	)
	(segment
		(start 493.43691 -37.573204)
		(end 491.66653 -35.802824)
		(width 0.10795)
		(layer "F.Cu")
		(net "V_IO_B_J")
	)
	(segment
		(start 491.2106 -37.338)
		(end 491.236 -37.3634)
		(width 0.10795)
		(layer "F.Cu")
		(net "V_IO_B_J")
	)
	(segment
		(start 491.197646 -35.687)
		(end 490.6137 -35.687)
		(width 0.10795)
		(layer "F.Cu")
		(net "V_IO_B_J")
	)
	(segment
		(start 491.658402 -35.802824)
		(end 491.542578 -35.687)
		(width 0.10795)
		(layer "F.Cu")
		(net "V_IO_B_J")
	)
	(segment
		(start 490.6137 -35.687)
		(end 490.6137 -36.4363)
		(width 0.10795)
		(layer "F.Cu")
		(net "V_IO_B_J")
	)
	(segment
		(start 496.704874 -40.619934)
		(end 495.716052 -40.619934)
		(width 0.10795)
		(layer "F.Cu")
		(net "V_IO_B_J")
	)
	(via
		(at 491.236 -37.3634)
		(size 0.508)
		(drill 0.254)
		(layers "F.Cu" "B.Cu")
		(net "V_IO_B_J")
	)
	(via
		(at 470.0524 -10.502392)
		(size 0.508)
		(drill 0.254)
		(layers "F.Cu" "B.Cu")
		(net "V_IO_B_J")
	)
	(via
		(at 421.386 -22.352)
		(size 0.508)
		(drill 0.254)
		(layers "F.Cu" "B.Cu")
		(net "V_IO_B_J")
	)
	(via
		(at 494.51895 -41.459658)
		(size 0.762)
		(drill 0.381)
		(layers "F.Cu" "B.Cu")
		(net "V_IO_B_J")
	)
	(segment
		(start 419.735 -22.352)
		(end 419.608 -22.225)
		(width 0.10795)
		(layer "B.Cu")
		(net "V_IO_B_J")
	)
	(segment
		(start 421.386 -22.352)
		(end 420.624 -22.352)
		(width 0.10795)
		(layer "B.Cu")
		(net "V_IO_B_J")
	)
	(segment
		(start 420.624 -22.352)
		(end 419.735 -22.352)
		(width 0.10795)
		(layer "B.Cu")
		(net "V_IO_B_J")
	)
	(segment
		(start 488.60202 -35.09518)
		(end 488.60202 -31.44012)
		(width 0.089408)
		(layer "In4.Cu")
		(net "V_IO_B_J")
	)
	(segment
		(start 488.569 -35.1282)
		(end 488.60202 -35.09518)
		(width 0.089408)
		(layer "In4.Cu")
		(net "V_IO_B_J")
	)
	(segment
		(start 474.76918 -11.771376)
		(end 474.224604 -11.2268)
		(width 0.089408)
		(layer "In4.Cu")
		(net "V_IO_B_J")
	)
	(segment
		(start 474.224604 -11.2268)
		(end 470.9922 -11.2268)
		(width 0.089408)
		(layer "In4.Cu")
		(net "V_IO_B_J")
	)
	(segment
		(start 477.3676 -15.739618)
		(end 477.3676 -14.71676)
		(width 0.089408)
		(layer "In4.Cu")
		(net "V_IO_B_J")
	)
	(segment
		(start 488.8484 -36.195)
		(end 488.569 -35.9156)
		(width 0.089408)
		(layer "In4.Cu")
		(net "V_IO_B_J")
	)
	(segment
		(start 470.9922 -11.2268)
		(end 470.267792 -10.502392)
		(width 0.089408)
		(layer "In4.Cu")
		(net "V_IO_B_J")
	)
	(segment
		(start 490.1438 -36.195)
		(end 488.8484 -36.195)
		(width 0.089408)
		(layer "In4.Cu")
		(net "V_IO_B_J")
	)
	(segment
		(start 479.73488 -18.106898)
		(end 477.3676 -15.739618)
		(width 0.089408)
		(layer "In4.Cu")
		(net "V_IO_B_J")
	)
	(segment
		(start 485.241346 -26.213308)
		(end 485.241346 -25.718516)
		(width 0.089408)
		(layer "In4.Cu")
		(net "V_IO_B_J")
	)
	(segment
		(start 485.2416 -20.7772)
		(end 482.571298 -18.106898)
		(width 0.089408)
		(layer "In4.Cu")
		(net "V_IO_B_J")
	)
	(segment
		(start 488.60202 -31.44012)
		(end 488.195366 -31.033466)
		(width 0.089408)
		(layer "In4.Cu")
		(net "V_IO_B_J")
	)
	(segment
		(start 488.569 -35.9156)
		(end 488.569 -35.1282)
		(width 0.089408)
		(layer "In4.Cu")
		(net "V_IO_B_J")
	)
	(segment
		(start 482.571298 -18.106898)
		(end 479.73488 -18.106898)
		(width 0.089408)
		(layer "In4.Cu")
		(net "V_IO_B_J")
	)
	(segment
		(start 488.195366 -31.033466)
		(end 488.195366 -29.167328)
		(width 0.089408)
		(layer "In4.Cu")
		(net "V_IO_B_J")
	)
	(segment
		(start 485.241346 -25.718516)
		(end 485.2416 -25.718262)
		(width 0.089408)
		(layer "In4.Cu")
		(net "V_IO_B_J")
	)
	(segment
		(start 470.267792 -10.502392)
		(end 470.0524 -10.502392)
		(width 0.089408)
		(layer "In4.Cu")
		(net "V_IO_B_J")
	)
	(segment
		(start 474.76918 -12.11834)
		(end 474.76918 -11.771376)
		(width 0.089408)
		(layer "In4.Cu")
		(net "V_IO_B_J")
	)
	(segment
		(start 488.195366 -29.167328)
		(end 485.241346 -26.213308)
		(width 0.089408)
		(layer "In4.Cu")
		(net "V_IO_B_J")
	)
	(segment
		(start 477.3676 -14.71676)
		(end 474.76918 -12.11834)
		(width 0.089408)
		(layer "In4.Cu")
		(net "V_IO_B_J")
	)
	(segment
		(start 485.2416 -25.718262)
		(end 485.2416 -20.7772)
		(width 0.089408)
		(layer "In4.Cu")
		(net "V_IO_B_J")
	)
	(segment
		(start 491.236 -37.2872)
		(end 490.1438 -36.195)
		(width 0.089408)
		(layer "In4.Cu")
		(net "V_IO_B_J")
	)
	(segment
		(start 491.236 -37.3634)
		(end 491.236 -37.2872)
		(width 0.089408)
		(layer "In4.Cu")
		(net "V_IO_B_J")
	)
	(segment
		(start 429.111156 -22.381464)
		(end 432.401472 -22.381464)
		(width 0.089408)
		(layer "In11.Cu")
		(net "V_IO_B_J")
	)
	(segment
		(start 449.917312 -20.1676)
		(end 451.411848 -18.673064)
		(width 0.089408)
		(layer "In11.Cu")
		(net "V_IO_B_J")
	)
	(segment
		(start 468.091266 -10.502392)
		(end 470.0524 -10.502392)
		(width 0.089408)
		(layer "In11.Cu")
		(net "V_IO_B_J")
	)
	(segment
		(start 421.386 -22.352)
		(end 421.643048 -22.352)
		(width 0.089408)
		(layer "In11.Cu")
		(net "V_IO_B_J")
	)
	(segment
		(start 439.99785 -20.593304)
		(end 444.650622 -20.593304)
		(width 0.089408)
		(layer "In11.Cu")
		(net "V_IO_B_J")
	)
	(segment
		(start 433.703222 -21.079714)
		(end 439.51144 -21.079714)
		(width 0.089408)
		(layer "In11.Cu")
		(net "V_IO_B_J")
	)
	(segment
		(start 444.650622 -20.593304)
		(end 445.018668 -20.225258)
		(width 0.089408)
		(layer "In11.Cu")
		(net "V_IO_B_J")
	)
	(segment
		(start 424.358562 -23.965662)
		(end 424.548554 -23.77567)
		(width 0.089408)
		(layer "In11.Cu")
		(net "V_IO_B_J")
	)
	(segment
		(start 463.093308 -11.76528)
		(end 466.828378 -11.76528)
		(width 0.089408)
		(layer "In11.Cu")
		(net "V_IO_B_J")
	)
	(segment
		(start 466.828378 -11.76528)
		(end 468.091266 -10.502392)
		(width 0.089408)
		(layer "In11.Cu")
		(net "V_IO_B_J")
	)
	(segment
		(start 424.548554 -23.77567)
		(end 425.97324 -23.77567)
		(width 0.089408)
		(layer "In11.Cu")
		(net "V_IO_B_J")
	)
	(segment
		(start 428.373794 -23.118826)
		(end 429.111156 -22.381464)
		(width 0.089408)
		(layer "In11.Cu")
		(net "V_IO_B_J")
	)
	(segment
		(start 459.890368 -12.549632)
		(end 460.437992 -12.002008)
		(width 0.089408)
		(layer "In11.Cu")
		(net "V_IO_B_J")
	)
	(segment
		(start 451.411848 -17.36852)
		(end 453.376538 -15.40383)
		(width 0.089408)
		(layer "In11.Cu")
		(net "V_IO_B_J")
	)
	(segment
		(start 432.401472 -22.381464)
		(end 433.703222 -21.079714)
		(width 0.089408)
		(layer "In11.Cu")
		(net "V_IO_B_J")
	)
	(segment
		(start 445.018668 -20.225258)
		(end 447.827146 -20.225258)
		(width 0.089408)
		(layer "In11.Cu")
		(net "V_IO_B_J")
	)
	(segment
		(start 460.437992 -12.002008)
		(end 462.85658 -12.002008)
		(width 0.089408)
		(layer "In11.Cu")
		(net "V_IO_B_J")
	)
	(segment
		(start 447.827146 -20.225258)
		(end 447.884804 -20.1676)
		(width 0.089408)
		(layer "In11.Cu")
		(net "V_IO_B_J")
	)
	(segment
		(start 426.630084 -23.118826)
		(end 428.373794 -23.118826)
		(width 0.089408)
		(layer "In11.Cu")
		(net "V_IO_B_J")
	)
	(segment
		(start 451.411848 -18.673064)
		(end 451.411848 -17.36852)
		(width 0.089408)
		(layer "In11.Cu")
		(net "V_IO_B_J")
	)
	(segment
		(start 425.97324 -23.77567)
		(end 426.630084 -23.118826)
		(width 0.089408)
		(layer "In11.Cu")
		(net "V_IO_B_J")
	)
	(segment
		(start 447.884804 -20.1676)
		(end 449.917312 -20.1676)
		(width 0.089408)
		(layer "In11.Cu")
		(net "V_IO_B_J")
	)
	(segment
		(start 453.376538 -15.228316)
		(end 456.055222 -12.549632)
		(width 0.089408)
		(layer "In11.Cu")
		(net "V_IO_B_J")
	)
	(segment
		(start 421.643048 -22.352)
		(end 423.25671 -23.965662)
		(width 0.089408)
		(layer "In11.Cu")
		(net "V_IO_B_J")
	)
	(segment
		(start 456.055222 -12.549632)
		(end 459.890368 -12.549632)
		(width 0.089408)
		(layer "In11.Cu")
		(net "V_IO_B_J")
	)
	(segment
		(start 453.376538 -15.40383)
		(end 453.376538 -15.228316)
		(width 0.089408)
		(layer "In11.Cu")
		(net "V_IO_B_J")
	)
	(segment
		(start 462.85658 -12.002008)
		(end 463.093308 -11.76528)
		(width 0.089408)
		(layer "In11.Cu")
		(net "V_IO_B_J")
	)
	(segment
		(start 423.25671 -23.965662)
		(end 424.358562 -23.965662)
		(width 0.089408)
		(layer "In11.Cu")
		(net "V_IO_B_J")
	)
	(segment
		(start 439.51144 -21.079714)
		(end 439.99785 -20.593304)
		(width 0.089408)
		(layer "In11.Cu")
		(net "V_IO_B_J")
	)
	(segment
		(start 498.03304 -46.779942)
		(end 497.87302 -46.619922)
		(width 0.10795)
		(layer "F.Cu")
		(net "V_IBMC_5V_DDC_SDA_J")
	)
	(segment
		(start 494.411 -45.72)
		(end 495.310922 -46.619922)
		(width 0.10795)
		(layer "F.Cu")
		(net "V_IBMC_5V_DDC_SDA_J")
	)
	(segment
		(start 495.310922 -46.619922)
		(end 496.704874 -46.619922)
		(width 0.10795)
		(layer "F.Cu")
		(net "V_IBMC_5V_DDC_SDA_J")
	)
	(segment
		(start 497.87302 -46.619922)
		(end 496.704874 -46.619922)
		(width 0.10795)
		(layer "F.Cu")
		(net "V_IBMC_5V_DDC_SDA_J")
	)
	(segment
		(start 498.6782 -47.425102)
		(end 498.03304 -46.779942)
		(width 0.1016)
		(layer "F.Cu")
		(net "V_IBMC_5V_DDC_SDA_J")
	)
	(segment
		(start 498.6782 -48.514)
		(end 498.6782 -47.425102)
		(width 0.1016)
		(layer "F.Cu")
		(net "V_IBMC_5V_DDC_SDA_J")
	)
	(via
		(at 498.6782 -48.514)
		(size 0.508)
		(drill 0.254)
		(layers "F.Cu" "B.Cu")
		(net "V_IBMC_5V_DDC_SDA_J")
	)
	(via
		(at 494.411 -45.72)
		(size 0.762)
		(drill 0.381)
		(layers "F.Cu" "B.Cu")
		(net "V_IBMC_5V_DDC_SDA_J")
	)
	(segment
		(start 494.702084 -45.295312)
		(end 495.20348 -45.295312)
		(width 0.10795)
		(layer "B.Cu")
		(net "V_IBMC_5V_DDC_SDA_J")
	)
	(segment
		(start 498.487954 -47.771812)
		(end 497.904008 -47.771812)
		(width 0.1016)
		(layer "B.Cu")
		(net "V_IBMC_5V_DDC_SDA_J")
	)
	(segment
		(start 497.1796 -45.049186)
		(end 497.1796 -47.5742)
		(width 0.1016)
		(layer "B.Cu")
		(net "V_IBMC_5V_DDC_SDA_J")
	)
	(segment
		(start 494.702084 -45.295312)
		(end 494.702084 -44.537376)
		(width 0.10795)
		(layer "B.Cu")
		(net "V_IBMC_5V_DDC_SDA_J")
	)
	(segment
		(start 498.6782 -48.514)
		(end 498.6782 -48.387)
		(width 0.1016)
		(layer "B.Cu")
		(net "V_IBMC_5V_DDC_SDA_J")
	)
	(segment
		(start 497.1796 -47.5742)
		(end 497.377212 -47.771812)
		(width 0.1016)
		(layer "B.Cu")
		(net "V_IBMC_5V_DDC_SDA_J")
	)
	(segment
		(start 494.702084 -44.537376)
		(end 494.706148 -44.533312)
		(width 0.10795)
		(layer "B.Cu")
		(net "V_IBMC_5V_DDC_SDA_J")
	)
	(segment
		(start 498.6782 -48.387)
		(end 498.487954 -48.196754)
		(width 0.1016)
		(layer "B.Cu")
		(net "V_IBMC_5V_DDC_SDA_J")
	)
	(segment
		(start 497.377212 -47.771812)
		(end 497.904008 -47.771812)
		(width 0.1016)
		(layer "B.Cu")
		(net "V_IBMC_5V_DDC_SDA_J")
	)
	(segment
		(start 496.590574 -44.46016)
		(end 497.1796 -45.049186)
		(width 0.1016)
		(layer "B.Cu")
		(net "V_IBMC_5V_DDC_SDA_J")
	)
	(segment
		(start 495.20348 -45.295312)
		(end 496.038632 -44.46016)
		(width 0.10795)
		(layer "B.Cu")
		(net "V_IBMC_5V_DDC_SDA_J")
	)
	(segment
		(start 496.038632 -44.46016)
		(end 496.590574 -44.46016)
		(width 0.10795)
		(layer "B.Cu")
		(net "V_IBMC_5V_DDC_SDA_J")
	)
	(segment
		(start 498.487954 -48.196754)
		(end 498.487954 -47.771812)
		(width 0.1016)
		(layer "B.Cu")
		(net "V_IBMC_5V_DDC_SDA_J")
	)
	(segment
		(start 494.707164 -48.34763)
		(end 495.274854 -47.77994)
		(width 0.1016)
		(layer "F.Cu")
		(net "V_IBMC_5V_DDC_SCL_J")
	)
	(segment
		(start 495.434874 -47.61992)
		(end 496.704874 -47.61992)
		(width 0.10795)
		(layer "F.Cu")
		(net "V_IBMC_5V_DDC_SCL_J")
	)
	(segment
		(start 493.931194 -49.1236)
		(end 494.707164 -48.34763)
		(width 0.1016)
		(layer "F.Cu")
		(net "V_IBMC_5V_DDC_SCL_J")
	)
	(segment
		(start 495.274854 -47.77994)
		(end 495.434874 -47.61992)
		(width 0.10795)
		(layer "F.Cu")
		(net "V_IBMC_5V_DDC_SCL_J")
	)
	(via
		(at 494.707164 -48.34763)
		(size 0.762)
		(drill 0.381)
		(layers "F.Cu" "B.Cu")
		(net "V_IBMC_5V_DDC_SCL_J")
	)
	(via
		(at 493.931194 -49.1236)
		(size 0.508)
		(drill 0.254)
		(layers "F.Cu" "B.Cu")
		(net "V_IBMC_5V_DDC_SCL_J")
	)
	(segment
		(start 499.461282 -47.747682)
		(end 498.985286 -47.271686)
		(width 0.1016)
		(layer "B.Cu")
		(net "V_IBMC_5V_DDC_SCL_J")
	)
	(segment
		(start 497.482622 -49.347374)
		(end 498.88013 -49.347374)
		(width 0.1016)
		(layer "B.Cu")
		(net "V_IBMC_5V_DDC_SCL_J")
	)
	(segment
		(start 494.712244 -48.392588)
		(end 494.418874 -48.392588)
		(width 0.10795)
		(layer "B.Cu")
		(net "V_IBMC_5V_DDC_SCL_J")
	)
	(segment
		(start 494.712244 -49.154588)
		(end 497.289836 -49.154588)
		(width 0.1016)
		(layer "B.Cu")
		(net "V_IBMC_5V_DDC_SCL_J")
	)
	(segment
		(start 494.289842 -48.764952)
		(end 493.931194 -49.1236)
		(width 0.10795)
		(layer "B.Cu")
		(net "V_IBMC_5V_DDC_SCL_J")
	)
	(segment
		(start 494.418874 -48.392588)
		(end 494.289842 -48.52162)
		(width 0.10795)
		(layer "B.Cu")
		(net "V_IBMC_5V_DDC_SCL_J")
	)
	(segment
		(start 494.712244 -48.392588)
		(end 494.712244 -49.154588)
		(width 0.10795)
		(layer "B.Cu")
		(net "V_IBMC_5V_DDC_SCL_J")
	)
	(segment
		(start 498.88013 -49.347374)
		(end 499.461282 -48.766222)
		(width 0.1016)
		(layer "B.Cu")
		(net "V_IBMC_5V_DDC_SCL_J")
	)
	(segment
		(start 497.904008 -47.271686)
		(end 498.487954 -47.271686)
		(width 0.1016)
		(layer "B.Cu")
		(net "V_IBMC_5V_DDC_SCL_J")
	)
	(segment
		(start 494.289842 -48.52162)
		(end 494.289842 -48.764952)
		(width 0.10795)
		(layer "B.Cu")
		(net "V_IBMC_5V_DDC_SCL_J")
	)
	(segment
		(start 498.985286 -47.271686)
		(end 498.487954 -47.271686)
		(width 0.1016)
		(layer "B.Cu")
		(net "V_IBMC_5V_DDC_SCL_J")
	)
	(segment
		(start 499.461282 -48.766222)
		(end 499.461282 -47.747682)
		(width 0.1016)
		(layer "B.Cu")
		(net "V_IBMC_5V_DDC_SCL_J")
	)
	(segment
		(start 497.289836 -49.154588)
		(end 497.482622 -49.347374)
		(width 0.1016)
		(layer "B.Cu")
		(net "V_IBMC_5V_DDC_SCL_J")
	)
	(segment
		(start 400.56816 -121.179082)
		(end 400.05 -121.355104)
		(width 0.0889)
		(layer "F.Cu")
		(net "USB_PCH_BMC_P4_DP_R")
	)
	(segment
		(start 407.749502 -122.011186)
		(end 407.469594 -122.011186)
		(width 0.0889)
		(layer "F.Cu")
		(net "USB_PCH_BMC_P4_DP_R")
	)
	(segment
		(start 404.98522 -121.621804)
		(end 401.773898 -121.621804)
		(width 0.0889)
		(layer "F.Cu")
		(net "USB_PCH_BMC_P4_DP_R")
	)
	(segment
		(start 405.560276 -122.19686)
		(end 404.98522 -121.621804)
		(width 0.0889)
		(layer "F.Cu")
		(net "USB_PCH_BMC_P4_DP_R")
	)
	(segment
		(start 407.28392 -122.19686)
		(end 405.560276 -122.19686)
		(width 0.0889)
		(layer "F.Cu")
		(net "USB_PCH_BMC_P4_DP_R")
	)
	(segment
		(start 401.002246 -121.043954)
		(end 400.790156 -121.043954)
		(width 0.0889)
		(layer "F.Cu")
		(net "USB_PCH_BMC_P4_DP_R")
	)
	(segment
		(start 401.773898 -121.621804)
		(end 401.316698 -121.164604)
		(width 0.0889)
		(layer "F.Cu")
		(net "USB_PCH_BMC_P4_DP_R")
	)
	(segment
		(start 407.469594 -122.011186)
		(end 407.28392 -122.19686)
		(width 0.0889)
		(layer "F.Cu")
		(net "USB_PCH_BMC_P4_DP_R")
	)
	(segment
		(start 401.316698 -121.164604)
		(end 401.18157 -121.164604)
		(width 0.0889)
		(layer "F.Cu")
		(net "USB_PCH_BMC_P4_DP_R")
	)
	(segment
		(start 401.18157 -121.164604)
		(end 401.002246 -121.043954)
		(width 0.0889)
		(layer "F.Cu")
		(net "USB_PCH_BMC_P4_DP_R")
	)
	(segment
		(start 400.790156 -121.043954)
		(end 400.56816 -121.179082)
		(width 0.0889)
		(layer "F.Cu")
		(net "USB_PCH_BMC_P4_DP_R")
	)
	(segment
		(start 403.472904 -121.901204)
		(end 403.384004 -121.812304)
		(width 0.0889)
		(layer "F.Cu")
		(net "USB_PCH_BMC_P4_DN_R")
	)
	(segment
		(start 407.37536 -122.823986)
		(end 407.311352 -122.759978)
		(width 0.0889)
		(layer "F.Cu")
		(net "USB_PCH_BMC_P4_DN_R")
	)
	(segment
		(start 400.927316 -121.30786)
		(end 400.880072 -121.355104)
		(width 0.0889)
		(layer "F.Cu")
		(net "USB_PCH_BMC_P4_DN_R")
	)
	(segment
		(start 404.539704 -121.812304)
		(end 404.450804 -121.901204)
		(width 0.0889)
		(layer "F.Cu")
		(net "USB_PCH_BMC_P4_DN_R")
	)
	(segment
		(start 406.17394 -122.38736)
		(end 406.08504 -122.47626)
		(width 0.0889)
		(layer "F.Cu")
		(net "USB_PCH_BMC_P4_DN_R")
	)
	(segment
		(start 401.123404 -121.355104)
		(end 401.053046 -121.30786)
		(width 0.0889)
		(layer "F.Cu")
		(net "USB_PCH_BMC_P4_DN_R")
	)
	(segment
		(start 402.406104 -121.812304)
		(end 402.317204 -121.901204)
		(width 0.0889)
		(layer "F.Cu")
		(net "USB_PCH_BMC_P4_DN_R")
	)
	(segment
		(start 406.52954 -122.47626)
		(end 406.44064 -122.38736)
		(width 0.0889)
		(layer "F.Cu")
		(net "USB_PCH_BMC_P4_DN_R")
	)
	(segment
		(start 401.237704 -121.355104)
		(end 401.123404 -121.355104)
		(width 0.0889)
		(layer "F.Cu")
		(net "USB_PCH_BMC_P4_DN_R")
	)
	(segment
		(start 406.88514 -122.38736)
		(end 406.79624 -122.47626)
		(width 0.0889)
		(layer "F.Cu")
		(net "USB_PCH_BMC_P4_DN_R")
	)
	(segment
		(start 405.81834 -122.47626)
		(end 405.72944 -122.38736)
		(width 0.0889)
		(layer "F.Cu")
		(net "USB_PCH_BMC_P4_DN_R")
	)
	(segment
		(start 406.08504 -122.47626)
		(end 405.81834 -122.47626)
		(width 0.0889)
		(layer "F.Cu")
		(net "USB_PCH_BMC_P4_DN_R")
	)
	(segment
		(start 401.694904 -121.812304)
		(end 401.237704 -121.355104)
		(width 0.0889)
		(layer "F.Cu")
		(net "USB_PCH_BMC_P4_DN_R")
	)
	(segment
		(start 406.44064 -122.38736)
		(end 406.17394 -122.38736)
		(width 0.0889)
		(layer "F.Cu")
		(net "USB_PCH_BMC_P4_DN_R")
	)
	(segment
		(start 404.450804 -121.901204)
		(end 404.184104 -121.901204)
		(width 0.0889)
		(layer "F.Cu")
		(net "USB_PCH_BMC_P4_DN_R")
	)
	(segment
		(start 403.739604 -121.901204)
		(end 403.472904 -121.901204)
		(width 0.0889)
		(layer "F.Cu")
		(net "USB_PCH_BMC_P4_DN_R")
	)
	(segment
		(start 405.72944 -122.38736)
		(end 405.481282 -122.38736)
		(width 0.0889)
		(layer "F.Cu")
		(net "USB_PCH_BMC_P4_DN_R")
	)
	(segment
		(start 402.050504 -121.901204)
		(end 401.961604 -121.812304)
		(width 0.0889)
		(layer "F.Cu")
		(net "USB_PCH_BMC_P4_DN_R")
	)
	(segment
		(start 405.481282 -122.38736)
		(end 405.337772 -122.24385)
		(width 0.0889)
		(layer "F.Cu")
		(net "USB_PCH_BMC_P4_DN_R")
	)
	(segment
		(start 405.212042 -122.24385)
		(end 405.023574 -122.055382)
		(width 0.0889)
		(layer "F.Cu")
		(net "USB_PCH_BMC_P4_DN_R")
	)
	(segment
		(start 407.749502 -122.823986)
		(end 407.37536 -122.823986)
		(width 0.0889)
		(layer "F.Cu")
		(net "USB_PCH_BMC_P4_DN_R")
	)
	(segment
		(start 401.961604 -121.812304)
		(end 401.694904 -121.812304)
		(width 0.0889)
		(layer "F.Cu")
		(net "USB_PCH_BMC_P4_DN_R")
	)
	(segment
		(start 407.311352 -122.759978)
		(end 407.311352 -122.450352)
		(width 0.0889)
		(layer "F.Cu")
		(net "USB_PCH_BMC_P4_DN_R")
	)
	(segment
		(start 402.761704 -121.901204)
		(end 402.672804 -121.812304)
		(width 0.0889)
		(layer "F.Cu")
		(net "USB_PCH_BMC_P4_DN_R")
	)
	(segment
		(start 406.79624 -122.47626)
		(end 406.52954 -122.47626)
		(width 0.0889)
		(layer "F.Cu")
		(net "USB_PCH_BMC_P4_DN_R")
	)
	(segment
		(start 403.828504 -121.812304)
		(end 403.739604 -121.901204)
		(width 0.0889)
		(layer "F.Cu")
		(net "USB_PCH_BMC_P4_DN_R")
	)
	(segment
		(start 404.184104 -121.901204)
		(end 404.095204 -121.812304)
		(width 0.0889)
		(layer "F.Cu")
		(net "USB_PCH_BMC_P4_DN_R")
	)
	(segment
		(start 407.24836 -122.38736)
		(end 406.88514 -122.38736)
		(width 0.0889)
		(layer "F.Cu")
		(net "USB_PCH_BMC_P4_DN_R")
	)
	(segment
		(start 403.117304 -121.812304)
		(end 403.028404 -121.901204)
		(width 0.0889)
		(layer "F.Cu")
		(net "USB_PCH_BMC_P4_DN_R")
	)
	(segment
		(start 402.672804 -121.812304)
		(end 402.406104 -121.812304)
		(width 0.0889)
		(layer "F.Cu")
		(net "USB_PCH_BMC_P4_DN_R")
	)
	(segment
		(start 401.053046 -121.30786)
		(end 400.927316 -121.30786)
		(width 0.0889)
		(layer "F.Cu")
		(net "USB_PCH_BMC_P4_DN_R")
	)
	(segment
		(start 404.095204 -121.812304)
		(end 403.828504 -121.812304)
		(width 0.0889)
		(layer "F.Cu")
		(net "USB_PCH_BMC_P4_DN_R")
	)
	(segment
		(start 402.317204 -121.901204)
		(end 402.050504 -121.901204)
		(width 0.0889)
		(layer "F.Cu")
		(net "USB_PCH_BMC_P4_DN_R")
	)
	(segment
		(start 405.023574 -122.055382)
		(end 405.023574 -121.929652)
		(width 0.0889)
		(layer "F.Cu")
		(net "USB_PCH_BMC_P4_DN_R")
	)
	(segment
		(start 403.028404 -121.901204)
		(end 402.761704 -121.901204)
		(width 0.0889)
		(layer "F.Cu")
		(net "USB_PCH_BMC_P4_DN_R")
	)
	(segment
		(start 403.384004 -121.812304)
		(end 403.117304 -121.812304)
		(width 0.0889)
		(layer "F.Cu")
		(net "USB_PCH_BMC_P4_DN_R")
	)
	(segment
		(start 405.023574 -121.929652)
		(end 404.906226 -121.812304)
		(width 0.0889)
		(layer "F.Cu")
		(net "USB_PCH_BMC_P4_DN_R")
	)
	(segment
		(start 404.906226 -121.812304)
		(end 404.539704 -121.812304)
		(width 0.0889)
		(layer "F.Cu")
		(net "USB_PCH_BMC_P4_DN_R")
	)
	(segment
		(start 407.311352 -122.450352)
		(end 407.24836 -122.38736)
		(width 0.0889)
		(layer "F.Cu")
		(net "USB_PCH_BMC_P4_DN_R")
	)
	(segment
		(start 405.337772 -122.24385)
		(end 405.212042 -122.24385)
		(width 0.0889)
		(layer "F.Cu")
		(net "USB_PCH_BMC_P4_DN_R")
	)
	(segment
		(start 401.0152 -119.6848)
		(end 400.7358 -119.6848)
		(width 0.0889)
		(layer "F.Cu")
		(net "USB2_PCH_BMC_P5_DP_R")
	)
	(segment
		(start 401.154392 -119.545608)
		(end 401.0152 -119.6848)
		(width 0.0889)
		(layer "F.Cu")
		(net "USB2_PCH_BMC_P5_DP_R")
	)
	(segment
		(start 400.7358 -119.6848)
		(end 400.406108 -119.355108)
		(width 0.0889)
		(layer "F.Cu")
		(net "USB2_PCH_BMC_P5_DP_R")
	)
	(segment
		(start 400.406108 -119.355108)
		(end 400.05 -119.355108)
		(width 0.0889)
		(layer "F.Cu")
		(net "USB2_PCH_BMC_P5_DP_R")
	)
	(segment
		(start 408.319478 -119.051832)
		(end 407.879042 -119.051832)
		(width 0.0889)
		(layer "F.Cu")
		(net "USB2_PCH_BMC_P5_DP_R")
	)
	(segment
		(start 407.879042 -119.051832)
		(end 407.385266 -119.545608)
		(width 0.0889)
		(layer "F.Cu")
		(net "USB2_PCH_BMC_P5_DP_R")
	)
	(segment
		(start 407.385266 -119.545608)
		(end 401.154392 -119.545608)
		(width 0.0889)
		(layer "F.Cu")
		(net "USB2_PCH_BMC_P5_DP_R")
	)
	(segment
		(start 406.172924 -119.266208)
		(end 406.261824 -119.355108)
		(width 0.0889)
		(layer "F.Cu")
		(net "USB2_PCH_BMC_P5_DN_R")
	)
	(segment
		(start 407.498042 -119.163338)
		(end 407.71826 -118.94312)
		(width 0.0889)
		(layer "F.Cu")
		(net "USB2_PCH_BMC_P5_DN_R")
	)
	(segment
		(start 406.261824 -119.355108)
		(end 406.528524 -119.355108)
		(width 0.0889)
		(layer "F.Cu")
		(net "USB2_PCH_BMC_P5_DN_R")
	)
	(segment
		(start 402.972524 -119.355108)
		(end 403.061424 -119.266208)
		(width 0.0889)
		(layer "F.Cu")
		(net "USB2_PCH_BMC_P5_DN_R")
	)
	(segment
		(start 407.858468 -118.239032)
		(end 408.319478 -118.239032)
		(width 0.0889)
		(layer "F.Cu")
		(net "USB2_PCH_BMC_P5_DN_R")
	)
	(segment
		(start 405.817324 -119.355108)
		(end 405.906224 -119.266208)
		(width 0.0889)
		(layer "F.Cu")
		(net "USB2_PCH_BMC_P5_DN_R")
	)
	(segment
		(start 404.039324 -119.266208)
		(end 404.128224 -119.355108)
		(width 0.0889)
		(layer "F.Cu")
		(net "USB2_PCH_BMC_P5_DN_R")
	)
	(segment
		(start 403.061424 -119.266208)
		(end 403.328124 -119.266208)
		(width 0.0889)
		(layer "F.Cu")
		(net "USB2_PCH_BMC_P5_DN_R")
	)
	(segment
		(start 405.461724 -119.266208)
		(end 405.550624 -119.355108)
		(width 0.0889)
		(layer "F.Cu")
		(net "USB2_PCH_BMC_P5_DN_R")
	)
	(segment
		(start 403.328124 -119.266208)
		(end 403.417024 -119.355108)
		(width 0.0889)
		(layer "F.Cu")
		(net "USB2_PCH_BMC_P5_DN_R")
	)
	(segment
		(start 404.128224 -119.355108)
		(end 404.394924 -119.355108)
		(width 0.0889)
		(layer "F.Cu")
		(net "USB2_PCH_BMC_P5_DN_R")
	)
	(segment
		(start 400.880072 -119.355108)
		(end 402.972524 -119.355108)
		(width 0.0889)
		(layer "F.Cu")
		(net "USB2_PCH_BMC_P5_DN_R")
	)
	(segment
		(start 404.394924 -119.355108)
		(end 404.483824 -119.266208)
		(width 0.0889)
		(layer "F.Cu")
		(net "USB2_PCH_BMC_P5_DN_R")
	)
	(segment
		(start 403.772624 -119.266208)
		(end 404.039324 -119.266208)
		(width 0.0889)
		(layer "F.Cu")
		(net "USB2_PCH_BMC_P5_DN_R")
	)
	(segment
		(start 406.528524 -119.355108)
		(end 406.617424 -119.266208)
		(width 0.0889)
		(layer "F.Cu")
		(net "USB2_PCH_BMC_P5_DN_R")
	)
	(segment
		(start 404.483824 -119.266208)
		(end 404.750524 -119.266208)
		(width 0.0889)
		(layer "F.Cu")
		(net "USB2_PCH_BMC_P5_DN_R")
	)
	(segment
		(start 405.906224 -119.266208)
		(end 406.172924 -119.266208)
		(width 0.0889)
		(layer "F.Cu")
		(net "USB2_PCH_BMC_P5_DN_R")
	)
	(segment
		(start 403.683724 -119.355108)
		(end 403.772624 -119.266208)
		(width 0.0889)
		(layer "F.Cu")
		(net "USB2_PCH_BMC_P5_DN_R")
	)
	(segment
		(start 404.750524 -119.266208)
		(end 404.839424 -119.355108)
		(width 0.0889)
		(layer "F.Cu")
		(net "USB2_PCH_BMC_P5_DN_R")
	)
	(segment
		(start 405.195024 -119.266208)
		(end 405.461724 -119.266208)
		(width 0.0889)
		(layer "F.Cu")
		(net "USB2_PCH_BMC_P5_DN_R")
	)
	(segment
		(start 406.884124 -119.266208)
		(end 406.973024 -119.355108)
		(width 0.0889)
		(layer "F.Cu")
		(net "USB2_PCH_BMC_P5_DN_R")
	)
	(segment
		(start 406.973024 -119.355108)
		(end 407.306272 -119.355108)
		(width 0.0889)
		(layer "F.Cu")
		(net "USB2_PCH_BMC_P5_DN_R")
	)
	(segment
		(start 405.106124 -119.355108)
		(end 405.195024 -119.266208)
		(width 0.0889)
		(layer "F.Cu")
		(net "USB2_PCH_BMC_P5_DN_R")
	)
	(segment
		(start 405.550624 -119.355108)
		(end 405.817324 -119.355108)
		(width 0.0889)
		(layer "F.Cu")
		(net "USB2_PCH_BMC_P5_DN_R")
	)
	(segment
		(start 403.417024 -119.355108)
		(end 403.683724 -119.355108)
		(width 0.0889)
		(layer "F.Cu")
		(net "USB2_PCH_BMC_P5_DN_R")
	)
	(segment
		(start 406.617424 -119.266208)
		(end 406.884124 -119.266208)
		(width 0.0889)
		(layer "F.Cu")
		(net "USB2_PCH_BMC_P5_DN_R")
	)
	(segment
		(start 404.839424 -119.355108)
		(end 405.106124 -119.355108)
		(width 0.0889)
		(layer "F.Cu")
		(net "USB2_PCH_BMC_P5_DN_R")
	)
	(segment
		(start 407.71826 -118.37924)
		(end 407.858468 -118.239032)
		(width 0.0889)
		(layer "F.Cu")
		(net "USB2_PCH_BMC_P5_DN_R")
	)
	(segment
		(start 407.306272 -119.355108)
		(end 407.498042 -119.163338)
		(width 0.0889)
		(layer "F.Cu")
		(net "USB2_PCH_BMC_P5_DN_R")
	)
	(segment
		(start 407.71826 -118.94312)
		(end 407.71826 -118.37924)
		(width 0.0889)
		(layer "F.Cu")
		(net "USB2_PCH_BMC_P5_DN_R")
	)
	(via
		(at 407.498042 -119.163338)
		(size 0.508)
		(drill 0.254)
		(layers "F.Cu" "B.Cu")
		(net "USB2_PCH_BMC_P5_DN_R")
	)
	(segment
		(start 406.43683 -120.35028)
		(end 405.797258 -120.35028)
		(width 0.0889)
		(layer "F.Cu")
		(net "USB2_P02_DP_R")
	)
	(segment
		(start 406.516078 -120.271032)
		(end 406.43683 -120.35028)
		(width 0.0889)
		(layer "F.Cu")
		(net "USB2_P02_DP_R")
	)
	(segment
		(start 401.131532 -120.569228)
		(end 401.0406 -120.66016)
		(width 0.0889)
		(layer "F.Cu")
		(net "USB2_P02_DP_R")
	)
	(segment
		(start 401.0406 -120.66016)
		(end 400.465036 -120.854978)
		(width 0.0889)
		(layer "F.Cu")
		(net "USB2_P02_DP_R")
	)
	(segment
		(start 402.108416 -121.07418)
		(end 401.603464 -120.569228)
		(width 0.0889)
		(layer "F.Cu")
		(net "USB2_P02_DP_R")
	)
	(segment
		(start 401.603464 -120.569228)
		(end 401.131532 -120.569228)
		(width 0.0889)
		(layer "F.Cu")
		(net "USB2_P02_DP_R")
	)
	(segment
		(start 405.797258 -120.35028)
		(end 405.073358 -121.07418)
		(width 0.0889)
		(layer "F.Cu")
		(net "USB2_P02_DP_R")
	)
	(segment
		(start 405.073358 -121.07418)
		(end 402.108416 -121.07418)
		(width 0.0889)
		(layer "F.Cu")
		(net "USB2_P02_DP_R")
	)
	(segment
		(start 404.429722 -121.26468)
		(end 404.163022 -121.26468)
		(width 0.0889)
		(layer "F.Cu")
		(net "USB2_P02_DN_R")
	)
	(segment
		(start 405.46655 -121.076212)
		(end 405.34082 -121.076212)
		(width 0.0889)
		(layer "F.Cu")
		(net "USB2_P02_DN_R")
	)
	(segment
		(start 405.876252 -120.54078)
		(end 405.655272 -120.76176)
		(width 0.0889)
		(layer "F.Cu")
		(net "USB2_P02_DN_R")
	)
	(segment
		(start 405.655272 -120.88749)
		(end 405.46655 -121.076212)
		(width 0.0889)
		(layer "F.Cu")
		(net "USB2_P02_DN_R")
	)
	(segment
		(start 402.296122 -121.26468)
		(end 402.029422 -121.26468)
		(width 0.0889)
		(layer "F.Cu")
		(net "USB2_P02_DN_R")
	)
	(segment
		(start 405.152352 -121.26468)
		(end 404.874222 -121.26468)
		(width 0.0889)
		(layer "F.Cu")
		(net "USB2_P02_DN_R")
	)
	(segment
		(start 406.090628 -120.62968)
		(end 406.001728 -120.54078)
		(width 0.0889)
		(layer "F.Cu")
		(net "USB2_P02_DN_R")
	)
	(segment
		(start 404.518622 -121.35358)
		(end 404.429722 -121.26468)
		(width 0.0889)
		(layer "F.Cu")
		(net "USB2_P02_DN_R")
	)
	(segment
		(start 406.179528 -121.083832)
		(end 406.090628 -120.994932)
		(width 0.0889)
		(layer "F.Cu")
		(net "USB2_P02_DN_R")
	)
	(segment
		(start 402.385022 -121.35358)
		(end 402.296122 -121.26468)
		(width 0.0889)
		(layer "F.Cu")
		(net "USB2_P02_DN_R")
	)
	(segment
		(start 405.34082 -121.076212)
		(end 405.152352 -121.26468)
		(width 0.0889)
		(layer "F.Cu")
		(net "USB2_P02_DN_R")
	)
	(segment
		(start 403.718522 -121.26468)
		(end 403.451822 -121.26468)
		(width 0.0889)
		(layer "F.Cu")
		(net "USB2_P02_DN_R")
	)
	(segment
		(start 404.074122 -121.35358)
		(end 403.807422 -121.35358)
		(width 0.0889)
		(layer "F.Cu")
		(net "USB2_P02_DN_R")
	)
	(segment
		(start 406.001728 -120.54078)
		(end 405.876252 -120.54078)
		(width 0.0889)
		(layer "F.Cu")
		(net "USB2_P02_DN_R")
	)
	(segment
		(start 403.451822 -121.26468)
		(end 403.362922 -121.35358)
		(width 0.0889)
		(layer "F.Cu")
		(net "USB2_P02_DN_R")
	)
	(segment
		(start 402.651722 -121.35358)
		(end 402.385022 -121.35358)
		(width 0.0889)
		(layer "F.Cu")
		(net "USB2_P02_DN_R")
	)
	(segment
		(start 406.090628 -120.994932)
		(end 406.090628 -120.62968)
		(width 0.0889)
		(layer "F.Cu")
		(net "USB2_P02_DN_R")
	)
	(segment
		(start 401.52447 -120.759728)
		(end 401.390358 -120.759728)
		(width 0.0889)
		(layer "F.Cu")
		(net "USB2_P02_DN_R")
	)
	(segment
		(start 403.096222 -121.35358)
		(end 403.007322 -121.26468)
		(width 0.0889)
		(layer "F.Cu")
		(net "USB2_P02_DN_R")
	)
	(segment
		(start 406.516078 -121.083832)
		(end 406.179528 -121.083832)
		(width 0.0889)
		(layer "F.Cu")
		(net "USB2_P02_DN_R")
	)
	(segment
		(start 401.390358 -120.759728)
		(end 401.295108 -120.854978)
		(width 0.0889)
		(layer "F.Cu")
		(net "USB2_P02_DN_R")
	)
	(segment
		(start 403.362922 -121.35358)
		(end 403.096222 -121.35358)
		(width 0.0889)
		(layer "F.Cu")
		(net "USB2_P02_DN_R")
	)
	(segment
		(start 404.874222 -121.26468)
		(end 404.785322 -121.35358)
		(width 0.0889)
		(layer "F.Cu")
		(net "USB2_P02_DN_R")
	)
	(segment
		(start 404.785322 -121.35358)
		(end 404.518622 -121.35358)
		(width 0.0889)
		(layer "F.Cu")
		(net "USB2_P02_DN_R")
	)
	(segment
		(start 403.007322 -121.26468)
		(end 402.740622 -121.26468)
		(width 0.0889)
		(layer "F.Cu")
		(net "USB2_P02_DN_R")
	)
	(segment
		(start 402.029422 -121.26468)
		(end 401.52447 -120.759728)
		(width 0.0889)
		(layer "F.Cu")
		(net "USB2_P02_DN_R")
	)
	(segment
		(start 402.740622 -121.26468)
		(end 402.651722 -121.35358)
		(width 0.0889)
		(layer "F.Cu")
		(net "USB2_P02_DN_R")
	)
	(segment
		(start 404.163022 -121.26468)
		(end 404.074122 -121.35358)
		(width 0.0889)
		(layer "F.Cu")
		(net "USB2_P02_DN_R")
	)
	(segment
		(start 405.655272 -120.76176)
		(end 405.655272 -120.88749)
		(width 0.0889)
		(layer "F.Cu")
		(net "USB2_P02_DN_R")
	)
	(segment
		(start 403.807422 -121.35358)
		(end 403.718522 -121.26468)
		(width 0.0889)
		(layer "F.Cu")
		(net "USB2_P02_DN_R")
	)
	(segment
		(start 407.890218 -34.534602)
		(end 407.490168 -34.134552)
		(width 0.10795)
		(layer "F.Cu")
		(net "SMB_PEHPCPU0_STBY_LVC3_R2_SDA")
	)
	(via
		(at 407.0604 -34.507424)
		(size 0.508)
		(drill 0.254)
		(layers "F.Cu" "B.Cu")
		(net "SMB_PEHPCPU0_STBY_LVC3_R2_SDA")
	)
	(via
		(at 407.490168 -34.134552)
		(size 0.4572)
		(drill 0.2032)
		(layers "F.Cu" "B.Cu")
		(net "SMB_PEHPCPU0_STBY_LVC3_R2_SDA")
	)
	(segment
		(start 407.368756 -34.507424)
		(end 407.490168 -34.386012)
		(width 0.089408)
		(layer "B.Cu")
		(net "SMB_PEHPCPU0_STBY_LVC3_R2_SDA")
	)
	(segment
		(start 407.490168 -34.386012)
		(end 407.490168 -34.134552)
		(width 0.089408)
		(layer "B.Cu")
		(net "SMB_PEHPCPU0_STBY_LVC3_R2_SDA")
	)
	(segment
		(start 407.0604 -34.507424)
		(end 407.368756 -34.507424)
		(width 0.089408)
		(layer "B.Cu")
		(net "SMB_PEHPCPU0_STBY_LVC3_R2_SDA")
	)
	(segment
		(start 407.0604 -34.507424)
		(end 406.698704 -34.507424)
		(width 0.089408)
		(layer "B.Cu")
		(net "SMB_PEHPCPU0_STBY_LVC3_R2_SDA")
	)
	(segment
		(start 406.698704 -34.507424)
		(end 406.504648 -34.313368)
		(width 0.089408)
		(layer "B.Cu")
		(net "SMB_PEHPCPU0_STBY_LVC3_R2_SDA")
	)
	(segment
		(start 406.504648 -34.313368)
		(end 406.2476 -34.313368)
		(width 0.089408)
		(layer "B.Cu")
		(net "SMB_PEHPCPU0_STBY_LVC3_R2_SDA")
	)
	(segment
		(start 408.690064 -34.534602)
		(end 408.290014 -34.934652)
		(width 0.10795)
		(layer "F.Cu")
		(net "SMB_PEHPCPU0_STBY_LVC3_R2_SCL")
	)
	(via
		(at 407.569162 -35.714178)
		(size 0.508)
		(drill 0.254)
		(layers "F.Cu" "B.Cu")
		(net "SMB_PEHPCPU0_STBY_LVC3_R2_SCL")
	)
	(via
		(at 408.290014 -34.934652)
		(size 0.4572)
		(drill 0.2032)
		(layers "F.Cu" "B.Cu")
		(net "SMB_PEHPCPU0_STBY_LVC3_R2_SCL")
	)
	(segment
		(start 407.213054 -35.714178)
		(end 407.569162 -35.714178)
		(width 0.089408)
		(layer "B.Cu")
		(net "SMB_PEHPCPU0_STBY_LVC3_R2_SCL")
	)
	(segment
		(start 407.871168 -35.714178)
		(end 408.290014 -35.295332)
		(width 0.089408)
		(layer "B.Cu")
		(net "SMB_PEHPCPU0_STBY_LVC3_R2_SCL")
	)
	(segment
		(start 407.569162 -35.714178)
		(end 407.871168 -35.714178)
		(width 0.089408)
		(layer "B.Cu")
		(net "SMB_PEHPCPU0_STBY_LVC3_R2_SCL")
	)
	(segment
		(start 406.592786 -35.09391)
		(end 407.213054 -35.714178)
		(width 0.089408)
		(layer "B.Cu")
		(net "SMB_PEHPCPU0_STBY_LVC3_R2_SCL")
	)
	(segment
		(start 408.290014 -35.295332)
		(end 408.290014 -34.934652)
		(width 0.089408)
		(layer "B.Cu")
		(net "SMB_PEHPCPU0_STBY_LVC3_R2_SCL")
	)
	(segment
		(start 406.247854 -35.09391)
		(end 406.592786 -35.09391)
		(width 0.089408)
		(layer "B.Cu")
		(net "SMB_PEHPCPU0_STBY_LVC3_R2_SCL")
	)
	(segment
		(start 490.306614 -47.930054)
		(end 490.723174 -47.930054)
		(width 0.10795)
		(layer "B.Cu")
		(net "Q25W2_GATE")
	)
	(segment
		(start 492.487712 -47.80534)
		(end 492.487712 -48.311816)
		(width 0.10795)
		(layer "B.Cu")
		(net "Q25W2_GATE")
	)
	(segment
		(start 491.54334 -47.62246)
		(end 492.10468 -47.62246)
		(width 0.10795)
		(layer "B.Cu")
		(net "Q25W2_GATE")
	)
	(segment
		(start 490.723174 -47.930054)
		(end 490.728 -47.93488)
		(width 0.10795)
		(layer "B.Cu")
		(net "Q25W2_GATE")
	)
	(segment
		(start 491.235746 -47.930054)
		(end 491.54334 -47.62246)
		(width 0.10795)
		(layer "B.Cu")
		(net "Q25W2_GATE")
	)
	(segment
		(start 492.370872 -47.6885)
		(end 492.487712 -47.80534)
		(width 0.10795)
		(layer "B.Cu")
		(net "Q25W2_GATE")
	)
	(segment
		(start 491.157006 -47.930054)
		(end 491.235746 -47.930054)
		(width 0.10795)
		(layer "B.Cu")
		(net "Q25W2_GATE")
	)
	(segment
		(start 491.15218 -47.93488)
		(end 491.157006 -47.930054)
		(width 0.10795)
		(layer "B.Cu")
		(net "Q25W2_GATE")
	)
	(segment
		(start 490.728 -47.93488)
		(end 491.15218 -47.93488)
		(width 0.10795)
		(layer "B.Cu")
		(net "Q25W2_GATE")
	)
	(segment
		(start 492.10468 -47.62246)
		(end 492.17072 -47.6885)
		(width 0.10795)
		(layer "B.Cu")
		(net "Q25W2_GATE")
	)
	(segment
		(start 492.17072 -47.6885)
		(end 492.370872 -47.6885)
		(width 0.10795)
		(layer "B.Cu")
		(net "Q25W2_GATE")
	)
	(segment
		(start 492.25454 -45.77588)
		(end 491.51032 -45.77588)
		(width 0.10795)
		(layer "B.Cu")
		(net "Q25W1_GATE")
	)
	(segment
		(start 492.487712 -46.009052)
		(end 492.25454 -45.77588)
		(width 0.10795)
		(layer "B.Cu")
		(net "Q25W1_GATE")
	)
	(segment
		(start 491.25378 -46.03242)
		(end 491.25378 -46.407324)
		(width 0.10795)
		(layer "B.Cu")
		(net "Q25W1_GATE")
	)
	(segment
		(start 492.487712 -46.533816)
		(end 492.487712 -46.009052)
		(width 0.10795)
		(layer "B.Cu")
		(net "Q25W1_GATE")
	)
	(segment
		(start 491.51032 -45.77588)
		(end 491.25378 -46.03242)
		(width 0.10795)
		(layer "B.Cu")
		(net "Q25W1_GATE")
	)
	(segment
		(start 491.25378 -46.407324)
		(end 490.995716 -46.665388)
		(width 0.10795)
		(layer "B.Cu")
		(net "Q25W1_GATE")
	)
	(segment
		(start 490.995716 -46.665388)
		(end 490.334046 -46.665388)
		(width 0.10795)
		(layer "B.Cu")
		(net "Q25W1_GATE")
	)
	(via
		(at 489.5342 -51.054)
		(size 0.6604)
		(drill 0.3302)
		(layers "F.Cu" "B.Cu")
		(net "P5V_VGA_D")
	)
	(via
		(at 501.039892 -41.969944)
		(size 0.508)
		(drill 0.254)
		(layers "F.Cu" "B.Cu")
		(net "P5V_VGA_D")
	)
	(via
		(at 495.549174 -48.569372)
		(size 0.508)
		(drill 0.254)
		(layers "F.Cu" "B.Cu")
		(net "P5V_VGA_D")
	)
	(via
		(at 491.6424 -50.4698)
		(size 0.508)
		(drill 0.254)
		(layers "F.Cu" "B.Cu")
		(net "P5V_VGA_D")
	)
	(segment
		(start 500.246142 -43.64101)
		(end 500.246142 -43.04284)
		(width 0.508)
		(layer "B.Cu")
		(net "P5V_VGA_D")
	)
	(segment
		(start 496.967002 -41.41343)
		(end 496.885976 -41.494456)
		(width 0.508)
		(layer "B.Cu")
		(net "P5V_VGA_D")
	)
	(segment
		(start 486.417874 -52.946046)
		(end 486.417874 -52.880006)
		(width 0.4064)
		(layer "B.Cu")
		(net "P5V_VGA_D")
	)
	(segment
		(start 497.561108 -42.762678)
		(end 498.94744 -44.14901)
		(width 0.508)
		(layer "B.Cu")
		(net "P5V_VGA_D")
	)
	(segment
		(start 489.5342 -50.733198)
		(end 490.360716 -49.906682)
		(width 0.508)
		(layer "B.Cu")
		(net "P5V_VGA_D")
	)
	(segment
		(start 497.561108 -41.41343)
		(end 496.967002 -41.41343)
		(width 0.508)
		(layer "B.Cu")
		(net "P5V_VGA_D")
	)
	(segment
		(start 496.529614 -48.122586)
		(end 496.529614 -47.605696)
		(width 0.508)
		(layer "B.Cu")
		(net "P5V_VGA_D")
	)
	(segment
		(start 496.529614 -46.20387)
		(end 496.529614 -47.605696)
		(width 0.508)
		(layer "B.Cu")
		(net "P5V_VGA_D")
	)
	(segment
		(start 496.082828 -48.569372)
		(end 496.529614 -48.122586)
		(width 0.508)
		(layer "B.Cu")
		(net "P5V_VGA_D")
	)
	(segment
		(start 487.172254 -51.73091)
		(end 487.320082 -51.73091)
		(width 0.508)
		(layer "B.Cu")
		(net "P5V_VGA_D")
	)
	(segment
		(start 490.360716 -49.906682)
		(end 491.079282 -49.906682)
		(width 0.508)
		(layer "B.Cu")
		(net "P5V_VGA_D")
	)
	(segment
		(start 488.276392 -51.702208)
		(end 488.9246 -51.054)
		(width 0.508)
		(layer "B.Cu")
		(net "P5V_VGA_D")
	)
	(segment
		(start 488.9246 -51.054)
		(end 489.5342 -51.054)
		(width 0.508)
		(layer "B.Cu")
		(net "P5V_VGA_D")
	)
	(segment
		(start 496.523772 -46.198028)
		(end 496.529614 -46.20387)
		(width 0.508)
		(layer "B.Cu")
		(net "P5V_VGA_D")
	)
	(segment
		(start 489.5342 -51.054)
		(end 489.5342 -50.733198)
		(width 0.508)
		(layer "B.Cu")
		(net "P5V_VGA_D")
	)
	(segment
		(start 499.738142 -44.14901)
		(end 500.246142 -43.64101)
		(width 0.508)
		(layer "B.Cu")
		(net "P5V_VGA_D")
	)
	(segment
		(start 486.417874 -52.48529)
		(end 487.172254 -51.73091)
		(width 0.508)
		(layer "B.Cu")
		(net "P5V_VGA_D")
	)
	(segment
		(start 491.079282 -49.906682)
		(end 491.6424 -50.4698)
		(width 0.508)
		(layer "B.Cu")
		(net "P5V_VGA_D")
	)
	(segment
		(start 486.417874 -52.880006)
		(end 486.417874 -52.48529)
		(width 0.508)
		(layer "B.Cu")
		(net "P5V_VGA_D")
	)
	(segment
		(start 500.093234 -42.395648)
		(end 500.093234 -41.545256)
		(width 0.508)
		(layer "B.Cu")
		(net "P5V_VGA_D")
	)
	(segment
		(start 500.246142 -43.04284)
		(end 500.246142 -42.548556)
		(width 0.508)
		(layer "B.Cu")
		(net "P5V_VGA_D")
	)
	(segment
		(start 496.885976 -41.494456)
		(end 496.326414 -41.494456)
		(width 0.508)
		(layer "B.Cu")
		(net "P5V_VGA_D")
	)
	(segment
		(start 495.549174 -48.569372)
		(end 496.082828 -48.569372)
		(width 0.508)
		(layer "B.Cu")
		(net "P5V_VGA_D")
	)
	(segment
		(start 500.093234 -41.545256)
		(end 500.615204 -41.545256)
		(width 0.508)
		(layer "B.Cu")
		(net "P5V_VGA_D")
	)
	(segment
		(start 497.561108 -41.41343)
		(end 497.561108 -42.762678)
		(width 0.508)
		(layer "B.Cu")
		(net "P5V_VGA_D")
	)
	(segment
		(start 500.246142 -42.548556)
		(end 500.093234 -42.395648)
		(width 0.508)
		(layer "B.Cu")
		(net "P5V_VGA_D")
	)
	(segment
		(start 487.320082 -51.73091)
		(end 487.348784 -51.702208)
		(width 0.508)
		(layer "B.Cu")
		(net "P5V_VGA_D")
	)
	(segment
		(start 500.615204 -41.545256)
		(end 501.039892 -41.969944)
		(width 0.508)
		(layer "B.Cu")
		(net "P5V_VGA_D")
	)
	(segment
		(start 498.94744 -44.14901)
		(end 499.738142 -44.14901)
		(width 0.508)
		(layer "B.Cu")
		(net "P5V_VGA_D")
	)
	(segment
		(start 487.348784 -51.702208)
		(end 488.276392 -51.702208)
		(width 0.508)
		(layer "B.Cu")
		(net "P5V_VGA_D")
	)
	(segment
		(start 491.6424 -50.4698)
		(end 492.1758 -51.0032)
		(width 0.508)
		(layer "In4.Cu")
		(net "P5V_VGA_D")
	)
	(segment
		(start 495.549174 -49.32426)
		(end 495.549174 -48.569372)
		(width 0.508)
		(layer "In4.Cu")
		(net "P5V_VGA_D")
	)
	(segment
		(start 494.462308 -50.411126)
		(end 495.549174 -49.32426)
		(width 0.508)
		(layer "In4.Cu")
		(net "P5V_VGA_D")
	)
	(segment
		(start 493.452404 -50.411126)
		(end 494.462308 -50.411126)
		(width 0.508)
		(layer "In4.Cu")
		(net "P5V_VGA_D")
	)
	(segment
		(start 496.43157 -48.569372)
		(end 497.41455 -47.586392)
		(width 0.508)
		(layer "In4.Cu")
		(net "P5V_VGA_D")
	)
	(segment
		(start 492.86033 -51.0032)
		(end 493.452404 -50.411126)
		(width 0.508)
		(layer "In4.Cu")
		(net "P5V_VGA_D")
	)
	(segment
		(start 492.1758 -51.0032)
		(end 492.86033 -51.0032)
		(width 0.508)
		(layer "In4.Cu")
		(net "P5V_VGA_D")
	)
	(segment
		(start 501.039892 -47.267368)
		(end 501.039892 -41.969944)
		(width 0.508)
		(layer "In4.Cu")
		(net "P5V_VGA_D")
	)
	(segment
		(start 497.41455 -47.586392)
		(end 500.720868 -47.586392)
		(width 0.508)
		(layer "In4.Cu")
		(net "P5V_VGA_D")
	)
	(segment
		(start 500.720868 -47.586392)
		(end 501.039892 -47.267368)
		(width 0.508)
		(layer "In4.Cu")
		(net "P5V_VGA_D")
	)
	(segment
		(start 495.549174 -48.569372)
		(end 496.43157 -48.569372)
		(width 0.508)
		(layer "In4.Cu")
		(net "P5V_VGA_D")
	)
	(via
		(at 496.33378 -44.980352)
		(size 0.6604)
		(drill 0.3302)
		(layers "F.Cu" "B.Cu")
		(net "I2C_BMC_VGA_DDC_SDA_G")
	)
	(segment
		(start 494.5888 -46.297596)
		(end 494.5888 -46.684438)
		(width 0.1016)
		(layer "B.Cu")
		(net "I2C_BMC_VGA_DDC_SDA_G")
	)
	(segment
		(start 492.09198 -47.1932)
		(end 491.837726 -46.938946)
		(width 0.1016)
		(layer "B.Cu")
		(net "I2C_BMC_VGA_DDC_SDA_G")
	)
	(segment
		(start 494.039398 -47.23384)
		(end 492.29772 -47.23384)
		(width 0.1016)
		(layer "B.Cu")
		(net "I2C_BMC_VGA_DDC_SDA_G")
	)
	(segment
		(start 496.33378 -44.980352)
		(end 496.177316 -44.980352)
		(width 0.10795)
		(layer "B.Cu")
		(net "I2C_BMC_VGA_DDC_SDA_G")
	)
	(segment
		(start 495.15268 -46.157642)
		(end 494.728754 -46.157642)
		(width 0.1016)
		(layer "B.Cu")
		(net "I2C_BMC_VGA_DDC_SDA_G")
	)
	(segment
		(start 495.634772 -45.522896)
		(end 495.634772 -46.198028)
		(width 0.10795)
		(layer "B.Cu")
		(net "I2C_BMC_VGA_DDC_SDA_G")
	)
	(segment
		(start 492.29772 -47.23384)
		(end 492.19358 -47.1932)
		(width 0.1016)
		(layer "B.Cu")
		(net "I2C_BMC_VGA_DDC_SDA_G")
	)
	(segment
		(start 492.19358 -47.1932)
		(end 492.09198 -47.1932)
		(width 0.1016)
		(layer "B.Cu")
		(net "I2C_BMC_VGA_DDC_SDA_G")
	)
	(segment
		(start 494.702084 -46.184312)
		(end 494.5888 -46.297596)
		(width 0.1016)
		(layer "B.Cu")
		(net "I2C_BMC_VGA_DDC_SDA_G")
	)
	(segment
		(start 494.728754 -46.157642)
		(end 494.702084 -46.184312)
		(width 0.1016)
		(layer "B.Cu")
		(net "I2C_BMC_VGA_DDC_SDA_G")
	)
	(segment
		(start 495.193066 -46.198028)
		(end 495.15268 -46.157642)
		(width 0.1016)
		(layer "B.Cu")
		(net "I2C_BMC_VGA_DDC_SDA_G")
	)
	(segment
		(start 495.634772 -46.198028)
		(end 495.193066 -46.198028)
		(width 0.1016)
		(layer "B.Cu")
		(net "I2C_BMC_VGA_DDC_SDA_G")
	)
	(segment
		(start 494.5888 -46.684438)
		(end 494.039398 -47.23384)
		(width 0.1016)
		(layer "B.Cu")
		(net "I2C_BMC_VGA_DDC_SDA_G")
	)
	(segment
		(start 491.837726 -46.938946)
		(end 491.837726 -46.533816)
		(width 0.1016)
		(layer "B.Cu")
		(net "I2C_BMC_VGA_DDC_SDA_G")
	)
	(segment
		(start 496.177316 -44.980352)
		(end 495.634772 -45.522896)
		(width 0.10795)
		(layer "B.Cu")
		(net "I2C_BMC_VGA_DDC_SDA_G")
	)
	(segment
		(start 419.090094 -28.134564)
		(end 419.490144 -27.734514)
		(width 0.10795)
		(layer "F.Cu")
		(net "I2C_BMC_VGA_DDC_SDA")
	)
	(via
		(at 419.490144 -27.734514)
		(size 0.4572)
		(drill 0.2032)
		(layers "F.Cu" "B.Cu")
		(net "I2C_BMC_VGA_DDC_SDA")
	)
	(via
		(at 476.266764 -44.648628)
		(size 0.508)
		(drill 0.254)
		(layers "F.Cu" "B.Cu")
		(net "I2C_BMC_VGA_DDC_SDA")
	)
	(via
		(at 424.744388 -25.076404)
		(size 0.6604)
		(drill 0.3302)
		(layers "F.Cu" "B.Cu")
		(net "I2C_BMC_VGA_DDC_SDA")
	)
	(via
		(at 492.5568 -49.3522)
		(size 0.508)
		(drill 0.254)
		(layers "F.Cu" "B.Cu")
		(net "I2C_BMC_VGA_DDC_SDA")
	)
	(segment
		(start 424.744388 -25.076404)
		(end 424.948096 -25.076404)
		(width 0.10795)
		(layer "B.Cu")
		(net "I2C_BMC_VGA_DDC_SDA")
	)
	(segment
		(start 491.837726 -48.633126)
		(end 492.5568 -49.3522)
		(width 0.1016)
		(layer "B.Cu")
		(net "I2C_BMC_VGA_DDC_SDA")
	)
	(segment
		(start 423.1132 -25.81148)
		(end 422.509442 -25.81148)
		(width 0.10795)
		(layer "B.Cu")
		(net "I2C_BMC_VGA_DDC_SDA")
	)
	(segment
		(start 423.848276 -25.076404)
		(end 423.1132 -25.81148)
		(width 0.10795)
		(layer "B.Cu")
		(net "I2C_BMC_VGA_DDC_SDA")
	)
	(segment
		(start 422.509442 -25.81148)
		(end 421.553132 -26.76779)
		(width 0.10795)
		(layer "B.Cu")
		(net "I2C_BMC_VGA_DDC_SDA")
	)
	(segment
		(start 421.553132 -26.76779)
		(end 420.842186 -26.76779)
		(width 0.10795)
		(layer "B.Cu")
		(net "I2C_BMC_VGA_DDC_SDA")
	)
	(segment
		(start 420.053008 -27.17165)
		(end 419.490144 -27.734514)
		(width 0.10795)
		(layer "B.Cu")
		(net "I2C_BMC_VGA_DDC_SDA")
	)
	(segment
		(start 420.842186 -26.76779)
		(end 420.438326 -27.17165)
		(width 0.10795)
		(layer "B.Cu")
		(net "I2C_BMC_VGA_DDC_SDA")
	)
	(segment
		(start 424.948096 -25.076404)
		(end 427.4185 -22.606)
		(width 0.10795)
		(layer "B.Cu")
		(net "I2C_BMC_VGA_DDC_SDA")
	)
	(segment
		(start 424.744388 -25.076404)
		(end 423.848276 -25.076404)
		(width 0.10795)
		(layer "B.Cu")
		(net "I2C_BMC_VGA_DDC_SDA")
	)
	(segment
		(start 491.837726 -48.311816)
		(end 491.837726 -48.633126)
		(width 0.1016)
		(layer "B.Cu")
		(net "I2C_BMC_VGA_DDC_SDA")
	)
	(segment
		(start 420.438326 -27.17165)
		(end 420.053008 -27.17165)
		(width 0.10795)
		(layer "B.Cu")
		(net "I2C_BMC_VGA_DDC_SDA")
	)
	(segment
		(start 477.371156 -37.779198)
		(end 476.050356 -37.779198)
		(width 0.089408)
		(layer "In4.Cu")
		(net "I2C_BMC_VGA_DDC_SDA")
	)
	(segment
		(start 421.30091 -26.723848)
		(end 420.973758 -27.051)
		(width 0.089408)
		(layer "In4.Cu")
		(net "I2C_BMC_VGA_DDC_SDA")
	)
	(segment
		(start 476.266764 -44.648628)
		(end 476.27794 -44.648628)
		(width 0.089408)
		(layer "In4.Cu")
		(net "I2C_BMC_VGA_DDC_SDA")
	)
	(segment
		(start 467.416896 -35.865816)
		(end 465.802726 -34.251646)
		(width 0.089408)
		(layer "In4.Cu")
		(net "I2C_BMC_VGA_DDC_SDA")
	)
	(segment
		(start 419.438328 -27.051)
		(end 419.185344 -27.303984)
		(width 0.089408)
		(layer "In4.Cu")
		(net "I2C_BMC_VGA_DDC_SDA")
	)
	(segment
		(start 422.690544 -26.723594)
		(end 422.69029 -26.723848)
		(width 0.089408)
		(layer "In4.Cu")
		(net "I2C_BMC_VGA_DDC_SDA")
	)
	(segment
		(start 476.27794 -44.008548)
		(end 476.800418 -43.48607)
		(width 0.089408)
		(layer "In4.Cu")
		(net "I2C_BMC_VGA_DDC_SDA")
	)
	(segment
		(start 420.973758 -27.051)
		(end 419.438328 -27.051)
		(width 0.089408)
		(layer "In4.Cu")
		(net "I2C_BMC_VGA_DDC_SDA")
	)
	(segment
		(start 478.28581 -38.68039)
		(end 477.40189 -37.79647)
		(width 0.089408)
		(layer "In4.Cu")
		(net "I2C_BMC_VGA_DDC_SDA")
	)
	(segment
		(start 426.449998 -27.29992)
		(end 423.424858 -27.29992)
		(width 0.089408)
		(layer "In4.Cu")
		(net "I2C_BMC_VGA_DDC_SDA")
	)
	(segment
		(start 470.236296 -37.067998)
		(end 469.972136 -37.332158)
		(width 0.089408)
		(layer "In4.Cu")
		(net "I2C_BMC_VGA_DDC_SDA")
	)
	(segment
		(start 422.848532 -26.723594)
		(end 422.690544 -26.723594)
		(width 0.089408)
		(layer "In4.Cu")
		(net "I2C_BMC_VGA_DDC_SDA")
	)
	(segment
		(start 436.345584 -22.940772)
		(end 435.57698 -22.940772)
		(width 0.089408)
		(layer "In4.Cu")
		(net "I2C_BMC_VGA_DDC_SDA")
	)
	(segment
		(start 465.802726 -34.251646)
		(end 463.713576 -34.251646)
		(width 0.089408)
		(layer "In4.Cu")
		(net "I2C_BMC_VGA_DDC_SDA")
	)
	(segment
		(start 463.713576 -34.251646)
		(end 461.44053 -31.9786)
		(width 0.089408)
		(layer "In4.Cu")
		(net "I2C_BMC_VGA_DDC_SDA")
	)
	(segment
		(start 449.910708 -28.949396)
		(end 446.413636 -25.452324)
		(width 0.089408)
		(layer "In4.Cu")
		(net "I2C_BMC_VGA_DDC_SDA")
	)
	(segment
		(start 457.4794 -30.572202)
		(end 456.745086 -29.837888)
		(width 0.089408)
		(layer "In4.Cu")
		(net "I2C_BMC_VGA_DDC_SDA")
	)
	(segment
		(start 469.972136 -37.332158)
		(end 469.248998 -37.332158)
		(width 0.089408)
		(layer "In4.Cu")
		(net "I2C_BMC_VGA_DDC_SDA")
	)
	(segment
		(start 423.424858 -27.29992)
		(end 422.848532 -26.723594)
		(width 0.089408)
		(layer "In4.Cu")
		(net "I2C_BMC_VGA_DDC_SDA")
	)
	(segment
		(start 476.27794 -44.648628)
		(end 476.27794 -44.008548)
		(width 0.089408)
		(layer "In4.Cu")
		(net "I2C_BMC_VGA_DDC_SDA")
	)
	(segment
		(start 419.185344 -27.303984)
		(end 419.185344 -27.429714)
		(width 0.089408)
		(layer "In4.Cu")
		(net "I2C_BMC_VGA_DDC_SDA")
	)
	(segment
		(start 477.388428 -37.79647)
		(end 477.371156 -37.779198)
		(width 0.089408)
		(layer "In4.Cu")
		(net "I2C_BMC_VGA_DDC_SDA")
	)
	(segment
		(start 461.44053 -31.9786)
		(end 460.222854 -31.9786)
		(width 0.089408)
		(layer "In4.Cu")
		(net "I2C_BMC_VGA_DDC_SDA")
	)
	(segment
		(start 474.970602 -38.08603)
		(end 472.986862 -38.08603)
		(width 0.089408)
		(layer "In4.Cu")
		(net "I2C_BMC_VGA_DDC_SDA")
	)
	(segment
		(start 452.433436 -29.837888)
		(end 451.544944 -28.949396)
		(width 0.089408)
		(layer "In4.Cu")
		(net "I2C_BMC_VGA_DDC_SDA")
	)
	(segment
		(start 435.57698 -22.940772)
		(end 432.65344 -25.864312)
		(width 0.089408)
		(layer "In4.Cu")
		(net "I2C_BMC_VGA_DDC_SDA")
	)
	(segment
		(start 422.69029 -26.723848)
		(end 421.30091 -26.723848)
		(width 0.089408)
		(layer "In4.Cu")
		(net "I2C_BMC_VGA_DDC_SDA")
	)
	(segment
		(start 426.450252 -27.300174)
		(end 426.449998 -27.29992)
		(width 0.089408)
		(layer "In4.Cu")
		(net "I2C_BMC_VGA_DDC_SDA")
	)
	(segment
		(start 429.744378 -27.300174)
		(end 426.450252 -27.300174)
		(width 0.089408)
		(layer "In4.Cu")
		(net "I2C_BMC_VGA_DDC_SDA")
	)
	(segment
		(start 476.050356 -37.779198)
		(end 475.751652 -38.077902)
		(width 0.089408)
		(layer "In4.Cu")
		(net "I2C_BMC_VGA_DDC_SDA")
	)
	(segment
		(start 478.28581 -39.453312)
		(end 478.28581 -38.68039)
		(width 0.089408)
		(layer "In4.Cu")
		(net "I2C_BMC_VGA_DDC_SDA")
	)
	(segment
		(start 436.851044 -22.435312)
		(end 436.345584 -22.940772)
		(width 0.089408)
		(layer "In4.Cu")
		(net "I2C_BMC_VGA_DDC_SDA")
	)
	(segment
		(start 478.26168 -39.477442)
		(end 478.28581 -39.453312)
		(width 0.089408)
		(layer "In4.Cu")
		(net "I2C_BMC_VGA_DDC_SDA")
	)
	(segment
		(start 446.413636 -24.717756)
		(end 444.131192 -22.435312)
		(width 0.089408)
		(layer "In4.Cu")
		(net "I2C_BMC_VGA_DDC_SDA")
	)
	(segment
		(start 432.65344 -25.864312)
		(end 431.18024 -25.864312)
		(width 0.089408)
		(layer "In4.Cu")
		(net "I2C_BMC_VGA_DDC_SDA")
	)
	(segment
		(start 446.413636 -25.452324)
		(end 446.413636 -24.717756)
		(width 0.089408)
		(layer "In4.Cu")
		(net "I2C_BMC_VGA_DDC_SDA")
	)
	(segment
		(start 476.800418 -43.48607)
		(end 476.800418 -41.693338)
		(width 0.089408)
		(layer "In4.Cu")
		(net "I2C_BMC_VGA_DDC_SDA")
	)
	(segment
		(start 451.544944 -28.949396)
		(end 449.910708 -28.949396)
		(width 0.089408)
		(layer "In4.Cu")
		(net "I2C_BMC_VGA_DDC_SDA")
	)
	(segment
		(start 477.40189 -37.79647)
		(end 477.388428 -37.79647)
		(width 0.089408)
		(layer "In4.Cu")
		(net "I2C_BMC_VGA_DDC_SDA")
	)
	(segment
		(start 467.782656 -35.865816)
		(end 467.416896 -35.865816)
		(width 0.089408)
		(layer "In4.Cu")
		(net "I2C_BMC_VGA_DDC_SDA")
	)
	(segment
		(start 431.18024 -25.864312)
		(end 429.744378 -27.300174)
		(width 0.089408)
		(layer "In4.Cu")
		(net "I2C_BMC_VGA_DDC_SDA")
	)
	(segment
		(start 474.97873 -38.077902)
		(end 474.970602 -38.08603)
		(width 0.089408)
		(layer "In4.Cu")
		(net "I2C_BMC_VGA_DDC_SDA")
	)
	(segment
		(start 469.248998 -37.332158)
		(end 467.782656 -35.865816)
		(width 0.089408)
		(layer "In4.Cu")
		(net "I2C_BMC_VGA_DDC_SDA")
	)
	(segment
		(start 458.816456 -30.572202)
		(end 457.4794 -30.572202)
		(width 0.089408)
		(layer "In4.Cu")
		(net "I2C_BMC_VGA_DDC_SDA")
	)
	(segment
		(start 472.986862 -38.08603)
		(end 471.96883 -37.067998)
		(width 0.089408)
		(layer "In4.Cu")
		(net "I2C_BMC_VGA_DDC_SDA")
	)
	(segment
		(start 456.745086 -29.837888)
		(end 452.433436 -29.837888)
		(width 0.089408)
		(layer "In4.Cu")
		(net "I2C_BMC_VGA_DDC_SDA")
	)
	(segment
		(start 475.751652 -38.077902)
		(end 474.97873 -38.077902)
		(width 0.089408)
		(layer "In4.Cu")
		(net "I2C_BMC_VGA_DDC_SDA")
	)
	(segment
		(start 419.185344 -27.429714)
		(end 419.490144 -27.734514)
		(width 0.089408)
		(layer "In4.Cu")
		(net "I2C_BMC_VGA_DDC_SDA")
	)
	(segment
		(start 478.26168 -40.232076)
		(end 478.26168 -39.477442)
		(width 0.089408)
		(layer "In4.Cu")
		(net "I2C_BMC_VGA_DDC_SDA")
	)
	(segment
		(start 476.800418 -41.693338)
		(end 478.26168 -40.232076)
		(width 0.089408)
		(layer "In4.Cu")
		(net "I2C_BMC_VGA_DDC_SDA")
	)
	(segment
		(start 460.222854 -31.9786)
		(end 458.816456 -30.572202)
		(width 0.089408)
		(layer "In4.Cu")
		(net "I2C_BMC_VGA_DDC_SDA")
	)
	(segment
		(start 444.131192 -22.435312)
		(end 436.851044 -22.435312)
		(width 0.089408)
		(layer "In4.Cu")
		(net "I2C_BMC_VGA_DDC_SDA")
	)
	(segment
		(start 471.96883 -37.067998)
		(end 470.236296 -37.067998)
		(width 0.089408)
		(layer "In4.Cu")
		(net "I2C_BMC_VGA_DDC_SDA")
	)
	(segment
		(start 476.28429 -44.653454)
		(end 476.670878 -44.653454)
		(width 0.089408)
		(layer "In11.Cu")
		(net "I2C_BMC_VGA_DDC_SDA")
	)
	(segment
		(start 478.824544 -46.20895)
		(end 479.08845 -46.472856)
		(width 0.0889)
		(layer "In11.Cu")
		(net "I2C_BMC_VGA_DDC_SDA")
	)
	(segment
		(start 488.784138 -48.36795)
		(end 489.115862 -48.36795)
		(width 0.0889)
		(layer "In11.Cu")
		(net "I2C_BMC_VGA_DDC_SDA")
	)
	(segment
		(start 480.259644 -50.24882)
		(end 483.191058 -50.24882)
		(width 0.089408)
		(layer "In11.Cu")
		(net "I2C_BMC_VGA_DDC_SDA")
	)
	(segment
		(start 488.428538 -48.72355)
		(end 488.784138 -48.36795)
		(width 0.0889)
		(layer "In11.Cu")
		(net "I2C_BMC_VGA_DDC_SDA")
	)
	(segment
		(start 489.115862 -48.36795)
		(end 489.371386 -48.623474)
		(width 0.0889)
		(layer "In11.Cu")
		(net "I2C_BMC_VGA_DDC_SDA")
	)
	(segment
		(start 476.670878 -44.653454)
		(end 477.0755 -45.058076)
		(width 0.0889)
		(layer "In11.Cu")
		(net "I2C_BMC_VGA_DDC_SDA")
	)
	(segment
		(start 485.954324 -49.435258)
		(end 486.666032 -48.72355)
		(width 0.0889)
		(layer "In11.Cu")
		(net "I2C_BMC_VGA_DDC_SDA")
	)
	(segment
		(start 485.733344 -49.435258)
		(end 485.954324 -49.435258)
		(width 0.0889)
		(layer "In11.Cu")
		(net "I2C_BMC_VGA_DDC_SDA")
	)
	(segment
		(start 477.0755 -45.1485)
		(end 478.13595 -46.20895)
		(width 0.0889)
		(layer "In11.Cu")
		(net "I2C_BMC_VGA_DDC_SDA")
	)
	(segment
		(start 483.191058 -50.24882)
		(end 484.00462 -49.435258)
		(width 0.089408)
		(layer "In11.Cu")
		(net "I2C_BMC_VGA_DDC_SDA")
	)
	(segment
		(start 484.00462 -49.435258)
		(end 485.733344 -49.435258)
		(width 0.089408)
		(layer "In11.Cu")
		(net "I2C_BMC_VGA_DDC_SDA")
	)
	(segment
		(start 477.0755 -45.058076)
		(end 477.0755 -45.1485)
		(width 0.0889)
		(layer "In11.Cu")
		(net "I2C_BMC_VGA_DDC_SDA")
	)
	(segment
		(start 479.08845 -49.077626)
		(end 480.259644 -50.24882)
		(width 0.0889)
		(layer "In11.Cu")
		(net "I2C_BMC_VGA_DDC_SDA")
	)
	(segment
		(start 479.08845 -46.472856)
		(end 479.08845 -49.077626)
		(width 0.0889)
		(layer "In11.Cu")
		(net "I2C_BMC_VGA_DDC_SDA")
	)
	(segment
		(start 491.828074 -48.623474)
		(end 492.5568 -49.3522)
		(width 0.0889)
		(layer "In11.Cu")
		(net "I2C_BMC_VGA_DDC_SDA")
	)
	(segment
		(start 476.27794 -44.648628)
		(end 476.27794 -44.659804)
		(width 0.089408)
		(layer "In11.Cu")
		(net "I2C_BMC_VGA_DDC_SDA")
	)
	(segment
		(start 478.13595 -46.20895)
		(end 478.824544 -46.20895)
		(width 0.0889)
		(layer "In11.Cu")
		(net "I2C_BMC_VGA_DDC_SDA")
	)
	(segment
		(start 476.27794 -44.659804)
		(end 476.28429 -44.653454)
		(width 0.089408)
		(layer "In11.Cu")
		(net "I2C_BMC_VGA_DDC_SDA")
	)
	(segment
		(start 476.266764 -44.648628)
		(end 476.27794 -44.648628)
		(width 0.089408)
		(layer "In11.Cu")
		(net "I2C_BMC_VGA_DDC_SDA")
	)
	(segment
		(start 486.666032 -48.72355)
		(end 488.428538 -48.72355)
		(width 0.0889)
		(layer "In11.Cu")
		(net "I2C_BMC_VGA_DDC_SDA")
	)
	(segment
		(start 489.371386 -48.623474)
		(end 491.828074 -48.623474)
		(width 0.0889)
		(layer "In11.Cu")
		(net "I2C_BMC_VGA_DDC_SDA")
	)
	(via
		(at 493.819942 -50.912776)
		(size 0.6604)
		(drill 0.3302)
		(layers "F.Cu" "B.Cu")
		(net "I2C_BMC_VGA_DDC_SCL_G")
	)
	(segment
		(start 493.137698 -47.968916)
		(end 493.137698 -48.311816)
		(width 0.10795)
		(layer "B.Cu")
		(net "I2C_BMC_VGA_DDC_SCL_G")
	)
	(segment
		(start 493.409224 -47.69739)
		(end 493.137698 -47.968916)
		(width 0.1016)
		(layer "B.Cu")
		(net "I2C_BMC_VGA_DDC_SCL_G")
	)
	(segment
		(start 493.137698 -50.230532)
		(end 493.819942 -50.912776)
		(width 0.10795)
		(layer "B.Cu")
		(net "I2C_BMC_VGA_DDC_SCL_G")
	)
	(segment
		(start 495.538506 -47.503588)
		(end 495.640614 -47.605696)
		(width 0.1016)
		(layer "B.Cu")
		(net "I2C_BMC_VGA_DDC_SCL_G")
	)
	(segment
		(start 494.712244 -47.503588)
		(end 495.538506 -47.503588)
		(width 0.1016)
		(layer "B.Cu")
		(net "I2C_BMC_VGA_DDC_SCL_G")
	)
	(segment
		(start 493.137698 -48.311816)
		(end 493.137698 -50.230532)
		(width 0.10795)
		(layer "B.Cu")
		(net "I2C_BMC_VGA_DDC_SCL_G")
	)
	(segment
		(start 494.518442 -47.69739)
		(end 493.409224 -47.69739)
		(width 0.1016)
		(layer "B.Cu")
		(net "I2C_BMC_VGA_DDC_SCL_G")
	)
	(segment
		(start 494.712244 -47.503588)
		(end 494.518442 -47.69739)
		(width 0.1016)
		(layer "B.Cu")
		(net "I2C_BMC_VGA_DDC_SCL_G")
	)
	(segment
		(start 418.290248 -28.134564)
		(end 418.690298 -27.734514)
		(width 0.10795)
		(layer "F.Cu")
		(net "I2C_BMC_VGA_DDC_SCL")
	)
	(via
		(at 492.3536 -45.2628)
		(size 0.508)
		(drill 0.254)
		(layers "F.Cu" "B.Cu")
		(net "I2C_BMC_VGA_DDC_SCL")
	)
	(via
		(at 425.04741 -24.078438)
		(size 0.6604)
		(drill 0.3302)
		(layers "F.Cu" "B.Cu")
		(net "I2C_BMC_VGA_DDC_SCL")
	)
	(via
		(at 418.690298 -27.734514)
		(size 0.4572)
		(drill 0.2032)
		(layers "F.Cu" "B.Cu")
		(net "I2C_BMC_VGA_DDC_SCL")
	)
	(via
		(at 476.715328 -44.175426)
		(size 0.508)
		(drill 0.254)
		(layers "F.Cu" "B.Cu")
		(net "I2C_BMC_VGA_DDC_SCL")
	)
	(segment
		(start 492.3536 -45.2628)
		(end 493.137698 -46.046898)
		(width 0.10795)
		(layer "B.Cu")
		(net "I2C_BMC_VGA_DDC_SCL")
	)
	(segment
		(start 423.285158 -25.028906)
		(end 423.285158 -25.343358)
		(width 0.10795)
		(layer "B.Cu")
		(net "I2C_BMC_VGA_DDC_SCL")
	)
	(segment
		(start 424.485562 -24.078438)
		(end 423.914824 -24.649176)
		(width 0.10795)
		(layer "B.Cu")
		(net "I2C_BMC_VGA_DDC_SCL")
	)
	(segment
		(start 419.96614 -26.9621)
		(end 419.965886 -26.962354)
		(width 0.10795)
		(layer "B.Cu")
		(net "I2C_BMC_VGA_DDC_SCL")
	)
	(segment
		(start 421.466264 -26.558494)
		(end 420.62908 -26.558494)
		(width 0.10795)
		(layer "B.Cu")
		(net "I2C_BMC_VGA_DDC_SCL")
	)
	(segment
		(start 425.04741 -24.078438)
		(end 425.591478 -24.078438)
		(width 0.10795)
		(layer "B.Cu")
		(net "I2C_BMC_VGA_DDC_SCL")
	)
	(segment
		(start 420.225474 -26.9621)
		(end 419.96614 -26.9621)
		(width 0.10795)
		(layer "B.Cu")
		(net "I2C_BMC_VGA_DDC_SCL")
	)
	(segment
		(start 422.422574 -25.602184)
		(end 421.466264 -26.558494)
		(width 0.10795)
		(layer "B.Cu")
		(net "I2C_BMC_VGA_DDC_SCL")
	)
	(segment
		(start 426.545248 -23.124668)
		(end 426.545248 -22.717252)
		(width 0.10795)
		(layer "B.Cu")
		(net "I2C_BMC_VGA_DDC_SCL")
	)
	(segment
		(start 419.965886 -26.962354)
		(end 419.645846 -26.962354)
		(width 0.10795)
		(layer "B.Cu")
		(net "I2C_BMC_VGA_DDC_SCL")
	)
	(segment
		(start 418.873686 -27.734514)
		(end 418.690298 -27.734514)
		(width 0.10795)
		(layer "B.Cu")
		(net "I2C_BMC_VGA_DDC_SCL")
	)
	(segment
		(start 423.285158 -25.343358)
		(end 423.026332 -25.602184)
		(width 0.10795)
		(layer "B.Cu")
		(net "I2C_BMC_VGA_DDC_SCL")
	)
	(segment
		(start 420.62908 -26.558494)
		(end 420.225474 -26.9621)
		(width 0.10795)
		(layer "B.Cu")
		(net "I2C_BMC_VGA_DDC_SCL")
	)
	(segment
		(start 423.664888 -24.649176)
		(end 423.285158 -25.028906)
		(width 0.10795)
		(layer "B.Cu")
		(net "I2C_BMC_VGA_DDC_SCL")
	)
	(segment
		(start 426.545248 -22.717252)
		(end 427.4185 -21.844)
		(width 0.10795)
		(layer "B.Cu")
		(net "I2C_BMC_VGA_DDC_SCL")
	)
	(segment
		(start 423.914824 -24.649176)
		(end 423.664888 -24.649176)
		(width 0.10795)
		(layer "B.Cu")
		(net "I2C_BMC_VGA_DDC_SCL")
	)
	(segment
		(start 425.04741 -24.078438)
		(end 424.485562 -24.078438)
		(width 0.10795)
		(layer "B.Cu")
		(net "I2C_BMC_VGA_DDC_SCL")
	)
	(segment
		(start 419.645846 -26.962354)
		(end 418.873686 -27.734514)
		(width 0.10795)
		(layer "B.Cu")
		(net "I2C_BMC_VGA_DDC_SCL")
	)
	(segment
		(start 425.591478 -24.078438)
		(end 426.545248 -23.124668)
		(width 0.10795)
		(layer "B.Cu")
		(net "I2C_BMC_VGA_DDC_SCL")
	)
	(segment
		(start 493.137698 -46.046898)
		(end 493.137698 -46.533816)
		(width 0.10795)
		(layer "B.Cu")
		(net "I2C_BMC_VGA_DDC_SCL")
	)
	(segment
		(start 423.026332 -25.602184)
		(end 422.422574 -25.602184)
		(width 0.10795)
		(layer "B.Cu")
		(net "I2C_BMC_VGA_DDC_SCL")
	)
	(segment
		(start 457.558648 -30.381194)
		(end 456.819254 -29.6418)
		(width 0.089408)
		(layer "In4.Cu")
		(net "I2C_BMC_VGA_DDC_SCL")
	)
	(segment
		(start 478.452688 -40.328342)
		(end 478.452688 -39.55669)
		(width 0.089408)
		(layer "In4.Cu")
		(net "I2C_BMC_VGA_DDC_SCL")
	)
	(segment
		(start 475.752922 -37.806376)
		(end 472.977464 -37.806376)
		(width 0.089408)
		(layer "In4.Cu")
		(net "I2C_BMC_VGA_DDC_SCL")
	)
	(segment
		(start 472.048078 -36.87699)
		(end 470.157048 -36.87699)
		(width 0.089408)
		(layer "In4.Cu")
		(net "I2C_BMC_VGA_DDC_SCL")
	)
	(segment
		(start 467.861904 -35.674808)
		(end 467.496144 -35.674808)
		(width 0.089408)
		(layer "In4.Cu")
		(net "I2C_BMC_VGA_DDC_SCL")
	)
	(segment
		(start 452.507604 -29.6418)
		(end 451.624192 -28.758388)
		(width 0.089408)
		(layer "In4.Cu")
		(net "I2C_BMC_VGA_DDC_SCL")
	)
	(segment
		(start 477.452182 -37.576506)
		(end 475.982792 -37.576506)
		(width 0.089408)
		(layer "In4.Cu")
		(net "I2C_BMC_VGA_DDC_SCL")
	)
	(segment
		(start 449.989956 -28.758388)
		(end 446.604644 -25.373076)
		(width 0.089408)
		(layer "In4.Cu")
		(net "I2C_BMC_VGA_DDC_SCL")
	)
	(segment
		(start 469.892888 -37.14115)
		(end 469.349074 -37.14115)
		(width 0.089408)
		(layer "In4.Cu")
		(net "I2C_BMC_VGA_DDC_SCL")
	)
	(segment
		(start 451.624192 -28.758388)
		(end 449.989956 -28.758388)
		(width 0.089408)
		(layer "In4.Cu")
		(net "I2C_BMC_VGA_DDC_SCL")
	)
	(segment
		(start 460.302102 -31.787592)
		(end 458.895704 -30.381194)
		(width 0.089408)
		(layer "In4.Cu")
		(net "I2C_BMC_VGA_DDC_SCL")
	)
	(segment
		(start 422.611042 -26.533094)
		(end 421.221662 -26.533094)
		(width 0.089408)
		(layer "In4.Cu")
		(net "I2C_BMC_VGA_DDC_SCL")
	)
	(segment
		(start 478.452688 -39.55669)
		(end 478.500948 -39.50843)
		(width 0.089408)
		(layer "In4.Cu")
		(net "I2C_BMC_VGA_DDC_SCL")
	)
	(segment
		(start 431.101246 -25.67305)
		(end 429.66513 -27.109166)
		(width 0.089408)
		(layer "In4.Cu")
		(net "I2C_BMC_VGA_DDC_SCL")
	)
	(segment
		(start 478.500948 -39.50843)
		(end 478.500948 -38.625272)
		(width 0.089408)
		(layer "In4.Cu")
		(net "I2C_BMC_VGA_DDC_SCL")
	)
	(segment
		(start 418.944044 -27.480768)
		(end 418.690298 -27.734514)
		(width 0.089408)
		(layer "In4.Cu")
		(net "I2C_BMC_VGA_DDC_SCL")
	)
	(segment
		(start 463.792824 -34.060638)
		(end 461.519778 -31.787592)
		(width 0.089408)
		(layer "In4.Cu")
		(net "I2C_BMC_VGA_DDC_SCL")
	)
	(segment
		(start 477.003618 -41.777412)
		(end 478.452688 -40.328342)
		(width 0.089408)
		(layer "In4.Cu")
		(net "I2C_BMC_VGA_DDC_SCL")
	)
	(segment
		(start 470.157048 -36.87699)
		(end 469.892888 -37.14115)
		(width 0.089408)
		(layer "In4.Cu")
		(net "I2C_BMC_VGA_DDC_SCL")
	)
	(segment
		(start 446.604644 -25.373076)
		(end 446.604644 -24.638508)
		(width 0.089408)
		(layer "In4.Cu")
		(net "I2C_BMC_VGA_DDC_SCL")
	)
	(segment
		(start 478.500948 -38.625272)
		(end 477.452182 -37.576506)
		(width 0.089408)
		(layer "In4.Cu")
		(net "I2C_BMC_VGA_DDC_SCL")
	)
	(segment
		(start 467.928706 -35.74161)
		(end 467.861904 -35.674808)
		(width 0.089408)
		(layer "In4.Cu")
		(net "I2C_BMC_VGA_DDC_SCL")
	)
	(segment
		(start 477.003618 -43.887136)
		(end 477.003618 -41.777412)
		(width 0.089408)
		(layer "In4.Cu")
		(net "I2C_BMC_VGA_DDC_SCL")
	)
	(segment
		(start 422.769792 -26.53284)
		(end 422.769538 -26.532586)
		(width 0.089408)
		(layer "In4.Cu")
		(net "I2C_BMC_VGA_DDC_SCL")
	)
	(segment
		(start 458.895704 -30.381194)
		(end 457.558648 -30.381194)
		(width 0.089408)
		(layer "In4.Cu")
		(net "I2C_BMC_VGA_DDC_SCL")
	)
	(segment
		(start 423.504106 -27.109166)
		(end 422.92778 -26.53284)
		(width 0.089408)
		(layer "In4.Cu")
		(net "I2C_BMC_VGA_DDC_SCL")
	)
	(segment
		(start 469.349074 -37.14115)
		(end 467.949534 -35.74161)
		(width 0.089408)
		(layer "In4.Cu")
		(net "I2C_BMC_VGA_DDC_SCL")
	)
	(segment
		(start 418.944044 -27.203908)
		(end 418.944044 -27.480768)
		(width 0.089408)
		(layer "In4.Cu")
		(net "I2C_BMC_VGA_DDC_SCL")
	)
	(segment
		(start 421.221662 -26.533094)
		(end 420.945056 -26.8097)
		(width 0.089408)
		(layer "In4.Cu")
		(net "I2C_BMC_VGA_DDC_SCL")
	)
	(segment
		(start 422.92778 -26.53284)
		(end 422.769792 -26.53284)
		(width 0.089408)
		(layer "In4.Cu")
		(net "I2C_BMC_VGA_DDC_SCL")
	)
	(segment
		(start 461.519778 -31.787592)
		(end 460.302102 -31.787592)
		(width 0.089408)
		(layer "In4.Cu")
		(net "I2C_BMC_VGA_DDC_SCL")
	)
	(segment
		(start 444.21044 -22.244304)
		(end 436.771796 -22.244304)
		(width 0.089408)
		(layer "In4.Cu")
		(net "I2C_BMC_VGA_DDC_SCL")
	)
	(segment
		(start 419.338252 -26.8097)
		(end 418.944044 -27.203908)
		(width 0.089408)
		(layer "In4.Cu")
		(net "I2C_BMC_VGA_DDC_SCL")
	)
	(segment
		(start 436.266336 -22.749764)
		(end 435.497732 -22.749764)
		(width 0.089408)
		(layer "In4.Cu")
		(net "I2C_BMC_VGA_DDC_SCL")
	)
	(segment
		(start 422.61155 -26.532586)
		(end 422.611042 -26.533094)
		(width 0.089408)
		(layer "In4.Cu")
		(net "I2C_BMC_VGA_DDC_SCL")
	)
	(segment
		(start 436.771796 -22.244304)
		(end 436.266336 -22.749764)
		(width 0.089408)
		(layer "In4.Cu")
		(net "I2C_BMC_VGA_DDC_SCL")
	)
	(segment
		(start 431.867818 -25.67305)
		(end 431.101246 -25.67305)
		(width 0.089408)
		(layer "In4.Cu")
		(net "I2C_BMC_VGA_DDC_SCL")
	)
	(segment
		(start 472.977464 -37.806376)
		(end 472.048078 -36.87699)
		(width 0.089408)
		(layer "In4.Cu")
		(net "I2C_BMC_VGA_DDC_SCL")
	)
	(segment
		(start 476.715328 -44.175426)
		(end 477.003618 -43.887136)
		(width 0.089408)
		(layer "In4.Cu")
		(net "I2C_BMC_VGA_DDC_SCL")
	)
	(segment
		(start 432.574192 -25.673304)
		(end 431.868072 -25.673304)
		(width 0.089408)
		(layer "In4.Cu")
		(net "I2C_BMC_VGA_DDC_SCL")
	)
	(segment
		(start 465.881974 -34.060638)
		(end 463.792824 -34.060638)
		(width 0.089408)
		(layer "In4.Cu")
		(net "I2C_BMC_VGA_DDC_SCL")
	)
	(segment
		(start 431.868072 -25.673304)
		(end 431.867818 -25.67305)
		(width 0.089408)
		(layer "In4.Cu")
		(net "I2C_BMC_VGA_DDC_SCL")
	)
	(segment
		(start 429.66513 -27.109166)
		(end 423.504106 -27.109166)
		(width 0.089408)
		(layer "In4.Cu")
		(net "I2C_BMC_VGA_DDC_SCL")
	)
	(segment
		(start 435.497732 -22.749764)
		(end 432.574192 -25.673304)
		(width 0.089408)
		(layer "In4.Cu")
		(net "I2C_BMC_VGA_DDC_SCL")
	)
	(segment
		(start 456.819254 -29.6418)
		(end 452.507604 -29.6418)
		(width 0.089408)
		(layer "In4.Cu")
		(net "I2C_BMC_VGA_DDC_SCL")
	)
	(segment
		(start 475.982792 -37.576506)
		(end 475.752922 -37.806376)
		(width 0.089408)
		(layer "In4.Cu")
		(net "I2C_BMC_VGA_DDC_SCL")
	)
	(segment
		(start 446.604644 -24.638508)
		(end 444.21044 -22.244304)
		(width 0.089408)
		(layer "In4.Cu")
		(net "I2C_BMC_VGA_DDC_SCL")
	)
	(segment
		(start 467.949534 -35.74161)
		(end 467.928706 -35.74161)
		(width 0.089408)
		(layer "In4.Cu")
		(net "I2C_BMC_VGA_DDC_SCL")
	)
	(segment
		(start 422.769538 -26.532586)
		(end 422.61155 -26.532586)
		(width 0.089408)
		(layer "In4.Cu")
		(net "I2C_BMC_VGA_DDC_SCL")
	)
	(segment
		(start 420.945056 -26.8097)
		(end 419.338252 -26.8097)
		(width 0.089408)
		(layer "In4.Cu")
		(net "I2C_BMC_VGA_DDC_SCL")
	)
	(segment
		(start 467.496144 -35.674808)
		(end 465.881974 -34.060638)
		(width 0.089408)
		(layer "In4.Cu")
		(net "I2C_BMC_VGA_DDC_SCL")
	)
	(segment
		(start 489.39958 -48.382174)
		(end 491.926626 -48.382174)
		(width 0.0889)
		(layer "In11.Cu")
		(net "I2C_BMC_VGA_DDC_SCL")
	)
	(segment
		(start 486.637076 -48.48225)
		(end 488.400344 -48.48225)
		(width 0.0889)
		(layer "In11.Cu")
		(net "I2C_BMC_VGA_DDC_SCL")
	)
	(segment
		(start 488.400344 -48.48225)
		(end 488.705144 -48.17745)
		(width 0.0889)
		(layer "In11.Cu")
		(net "I2C_BMC_VGA_DDC_SCL")
	)
	(segment
		(start 486.484676 -48.63465)
		(end 486.637076 -48.48225)
		(width 0.0889)
		(layer "In11.Cu")
		(net "I2C_BMC_VGA_DDC_SCL")
	)
	(segment
		(start 476.715328 -44.356528)
		(end 477.3168 -44.958)
		(width 0.0889)
		(layer "In11.Cu")
		(net "I2C_BMC_VGA_DDC_SCL")
	)
	(segment
		(start 483.011988 -50.057812)
		(end 483.82555 -49.24425)
		(width 0.089408)
		(layer "In11.Cu")
		(net "I2C_BMC_VGA_DDC_SCL")
	)
	(segment
		(start 477.3168 -45.048424)
		(end 478.236026 -45.96765)
		(width 0.0889)
		(layer "In11.Cu")
		(net "I2C_BMC_VGA_DDC_SCL")
	)
	(segment
		(start 485.875076 -49.24425)
		(end 486.484676 -48.63465)
		(width 0.089408)
		(layer "In11.Cu")
		(net "I2C_BMC_VGA_DDC_SCL")
	)
	(segment
		(start 479.32975 -46.37278)
		(end 479.32975 -48.97755)
		(width 0.0889)
		(layer "In11.Cu")
		(net "I2C_BMC_VGA_DDC_SCL")
	)
	(segment
		(start 488.705144 -48.17745)
		(end 489.194856 -48.17745)
		(width 0.0889)
		(layer "In11.Cu")
		(net "I2C_BMC_VGA_DDC_SCL")
	)
	(segment
		(start 483.82555 -49.24425)
		(end 485.875076 -49.24425)
		(width 0.089408)
		(layer "In11.Cu")
		(net "I2C_BMC_VGA_DDC_SCL")
	)
	(segment
		(start 476.715328 -44.175426)
		(end 476.715328 -44.356528)
		(width 0.0889)
		(layer "In11.Cu")
		(net "I2C_BMC_VGA_DDC_SCL")
	)
	(segment
		(start 478.92462 -45.96765)
		(end 479.32975 -46.37278)
		(width 0.0889)
		(layer "In11.Cu")
		(net "I2C_BMC_VGA_DDC_SCL")
	)
	(segment
		(start 492.3536 -47.9552)
		(end 492.3536 -45.2628)
		(width 0.0889)
		(layer "In11.Cu")
		(net "I2C_BMC_VGA_DDC_SCL")
	)
	(segment
		(start 479.32975 -48.97755)
		(end 480.410012 -50.057812)
		(width 0.0889)
		(layer "In11.Cu")
		(net "I2C_BMC_VGA_DDC_SCL")
	)
	(segment
		(start 480.410012 -50.057812)
		(end 483.011988 -50.057812)
		(width 0.089408)
		(layer "In11.Cu")
		(net "I2C_BMC_VGA_DDC_SCL")
	)
	(segment
		(start 477.3168 -44.958)
		(end 477.3168 -45.048424)
		(width 0.0889)
		(layer "In11.Cu")
		(net "I2C_BMC_VGA_DDC_SCL")
	)
	(segment
		(start 478.236026 -45.96765)
		(end 478.92462 -45.96765)
		(width 0.0889)
		(layer "In11.Cu")
		(net "I2C_BMC_VGA_DDC_SCL")
	)
	(segment
		(start 491.926626 -48.382174)
		(end 492.3536 -47.9552)
		(width 0.0889)
		(layer "In11.Cu")
		(net "I2C_BMC_VGA_DDC_SCL")
	)
	(segment
		(start 489.194856 -48.17745)
		(end 489.39958 -48.382174)
		(width 0.0889)
		(layer "In11.Cu")
		(net "I2C_BMC_VGA_DDC_SCL")
	)
	(segment
		(start 418.290248 -28.934664)
		(end 418.690298 -28.534614)
		(width 0.10795)
		(layer "F.Cu")
		(net "BMC_VGA_VSYNC")
	)
	(via
		(at 426.3136 -26.162)
		(size 0.508)
		(drill 0.254)
		(layers "F.Cu" "B.Cu")
		(net "BMC_VGA_VSYNC")
	)
	(via
		(at 456.2094 -17.4752)
		(size 0.508)
		(drill 0.254)
		(layers "F.Cu" "B.Cu")
		(net "BMC_VGA_VSYNC")
	)
	(via
		(at 447.3702 -30.2514)
		(size 0.508)
		(drill 0.254)
		(layers "F.Cu" "B.Cu")
		(net "BMC_VGA_VSYNC")
	)
	(via
		(at 418.690298 -28.534614)
		(size 0.4572)
		(drill 0.2032)
		(layers "F.Cu" "B.Cu")
		(net "BMC_VGA_VSYNC")
	)
	(via
		(at 499.5418 -38.7096)
		(size 0.508)
		(drill 0.254)
		(layers "F.Cu" "B.Cu")
		(net "BMC_VGA_VSYNC")
	)
	(segment
		(start 499.442994 -38.960806)
		(end 499.5418 -38.862)
		(width 0.10795)
		(layer "B.Cu")
		(net "BMC_VGA_VSYNC")
	)
	(segment
		(start 499.442994 -39.702486)
		(end 499.442994 -38.960806)
		(width 0.10795)
		(layer "B.Cu")
		(net "BMC_VGA_VSYNC")
	)
	(segment
		(start 499.5418 -38.862)
		(end 499.5418 -38.7096)
		(width 0.10795)
		(layer "B.Cu")
		(net "BMC_VGA_VSYNC")
	)
	(segment
		(start 471.452956 -13.8684)
		(end 466.232748 -13.8684)
		(width 0.089408)
		(layer "In4.Cu")
		(net "BMC_VGA_VSYNC")
	)
	(segment
		(start 476.91294 -20.73402)
		(end 476.91294 -19.328384)
		(width 0.089408)
		(layer "In4.Cu")
		(net "BMC_VGA_VSYNC")
	)
	(segment
		(start 463.624168 -16.47698)
		(end 462.526126 -16.47698)
		(width 0.0889)
		(layer "In4.Cu")
		(net "BMC_VGA_VSYNC")
	)
	(segment
		(start 492.913416 -38.5572)
		(end 491.63732 -38.5572)
		(width 0.089408)
		(layer "In4.Cu")
		(net "BMC_VGA_VSYNC")
	)
	(segment
		(start 483.829106 -30.484064)
		(end 482.935788 -29.590746)
		(width 0.089408)
		(layer "In4.Cu")
		(net "BMC_VGA_VSYNC")
	)
	(segment
		(start 482.935788 -26.934414)
		(end 482.191822 -26.190448)
		(width 0.089408)
		(layer "In4.Cu")
		(net "BMC_VGA_VSYNC")
	)
	(segment
		(start 482.935788 -29.590746)
		(end 482.935788 -26.934414)
		(width 0.089408)
		(layer "In4.Cu")
		(net "BMC_VGA_VSYNC")
	)
	(segment
		(start 479.912426 -22.195282)
		(end 478.374202 -22.195282)
		(width 0.089408)
		(layer "In4.Cu")
		(net "BMC_VGA_VSYNC")
	)
	(segment
		(start 482.191822 -26.190448)
		(end 482.191822 -24.474678)
		(width 0.089408)
		(layer "In4.Cu")
		(net "BMC_VGA_VSYNC")
	)
	(segment
		(start 482.191822 -24.474678)
		(end 479.912426 -22.195282)
		(width 0.089408)
		(layer "In4.Cu")
		(net "BMC_VGA_VSYNC")
	)
	(segment
		(start 493.33912 -38.982904)
		(end 492.913416 -38.5572)
		(width 0.089408)
		(layer "In4.Cu")
		(net "BMC_VGA_VSYNC")
	)
	(segment
		(start 476.91294 -19.328384)
		(end 471.452956 -13.8684)
		(width 0.089408)
		(layer "In4.Cu")
		(net "BMC_VGA_VSYNC")
	)
	(segment
		(start 461.627474 -17.375632)
		(end 456.308968 -17.375632)
		(width 0.089408)
		(layer "In4.Cu")
		(net "BMC_VGA_VSYNC")
	)
	(segment
		(start 488.430062 -36.792408)
		(end 486.75671 -35.119056)
		(width 0.089408)
		(layer "In4.Cu")
		(net "BMC_VGA_VSYNC")
	)
	(segment
		(start 486.440734 -30.484064)
		(end 483.829106 -30.484064)
		(width 0.089408)
		(layer "In4.Cu")
		(net "BMC_VGA_VSYNC")
	)
	(segment
		(start 478.374202 -22.195282)
		(end 476.91294 -20.73402)
		(width 0.089408)
		(layer "In4.Cu")
		(net "BMC_VGA_VSYNC")
	)
	(segment
		(start 496.748816 -38.177978)
		(end 494.957862 -38.177978)
		(width 0.089408)
		(layer "In4.Cu")
		(net "BMC_VGA_VSYNC")
	)
	(segment
		(start 494.152936 -38.982904)
		(end 493.33912 -38.982904)
		(width 0.089408)
		(layer "In4.Cu")
		(net "BMC_VGA_VSYNC")
	)
	(segment
		(start 486.75671 -30.958536)
		(end 486.756456 -30.958282)
		(width 0.089408)
		(layer "In4.Cu")
		(net "BMC_VGA_VSYNC")
	)
	(segment
		(start 462.526126 -16.47698)
		(end 461.627474 -17.375632)
		(width 0.089408)
		(layer "In4.Cu")
		(net "BMC_VGA_VSYNC")
	)
	(segment
		(start 466.232748 -13.8684)
		(end 463.624168 -16.47698)
		(width 0.0889)
		(layer "In4.Cu")
		(net "BMC_VGA_VSYNC")
	)
	(segment
		(start 489.872528 -36.792408)
		(end 488.430062 -36.792408)
		(width 0.089408)
		(layer "In4.Cu")
		(net "BMC_VGA_VSYNC")
	)
	(segment
		(start 499.5418 -38.7096)
		(end 497.280438 -38.7096)
		(width 0.089408)
		(layer "In4.Cu")
		(net "BMC_VGA_VSYNC")
	)
	(segment
		(start 456.308968 -17.375632)
		(end 456.2094 -17.4752)
		(width 0.089408)
		(layer "In4.Cu")
		(net "BMC_VGA_VSYNC")
	)
	(segment
		(start 486.75671 -35.119056)
		(end 486.75671 -30.958536)
		(width 0.089408)
		(layer "In4.Cu")
		(net "BMC_VGA_VSYNC")
	)
	(segment
		(start 494.957862 -38.177978)
		(end 494.152936 -38.982904)
		(width 0.089408)
		(layer "In4.Cu")
		(net "BMC_VGA_VSYNC")
	)
	(segment
		(start 486.756456 -30.958282)
		(end 486.756456 -30.799786)
		(width 0.089408)
		(layer "In4.Cu")
		(net "BMC_VGA_VSYNC")
	)
	(segment
		(start 497.280438 -38.7096)
		(end 496.748816 -38.177978)
		(width 0.089408)
		(layer "In4.Cu")
		(net "BMC_VGA_VSYNC")
	)
	(segment
		(start 491.63732 -38.5572)
		(end 489.872528 -36.792408)
		(width 0.089408)
		(layer "In4.Cu")
		(net "BMC_VGA_VSYNC")
	)
	(segment
		(start 486.756456 -30.799786)
		(end 486.440734 -30.484064)
		(width 0.089408)
		(layer "In4.Cu")
		(net "BMC_VGA_VSYNC")
	)
	(segment
		(start 444.536068 -23.89632)
		(end 442.85408 -23.89632)
		(width 0.089408)
		(layer "In9.Cu")
		(net "BMC_VGA_VSYNC")
	)
	(segment
		(start 435.203346 -24.142954)
		(end 433.0446 -26.3017)
		(width 0.089408)
		(layer "In9.Cu")
		(net "BMC_VGA_VSYNC")
	)
	(segment
		(start 442.607446 -24.142954)
		(end 435.203346 -24.142954)
		(width 0.089408)
		(layer "In9.Cu")
		(net "BMC_VGA_VSYNC")
	)
	(segment
		(start 442.85408 -23.89632)
		(end 442.607446 -24.142954)
		(width 0.089408)
		(layer "In9.Cu")
		(net "BMC_VGA_VSYNC")
	)
	(segment
		(start 446.919096 -30.702504)
		(end 446.370456 -30.702504)
		(width 0.089408)
		(layer "In9.Cu")
		(net "BMC_VGA_VSYNC")
	)
	(segment
		(start 446.370456 -30.702504)
		(end 446.087246 -30.419294)
		(width 0.089408)
		(layer "In9.Cu")
		(net "BMC_VGA_VSYNC")
	)
	(segment
		(start 426.4533 -26.3017)
		(end 426.3136 -26.162)
		(width 0.089408)
		(layer "In9.Cu")
		(net "BMC_VGA_VSYNC")
	)
	(segment
		(start 446.087246 -30.419294)
		(end 446.087246 -25.447498)
		(width 0.089408)
		(layer "In9.Cu")
		(net "BMC_VGA_VSYNC")
	)
	(segment
		(start 447.3702 -30.2514)
		(end 446.919096 -30.702504)
		(width 0.089408)
		(layer "In9.Cu")
		(net "BMC_VGA_VSYNC")
	)
	(segment
		(start 433.0446 -26.3017)
		(end 426.4533 -26.3017)
		(width 0.089408)
		(layer "In9.Cu")
		(net "BMC_VGA_VSYNC")
	)
	(segment
		(start 446.087246 -25.447498)
		(end 444.536068 -23.89632)
		(width 0.089408)
		(layer "In9.Cu")
		(net "BMC_VGA_VSYNC")
	)
	(segment
		(start 455.723498 -23.346664)
		(end 455.723498 -18.873978)
		(width 0.089408)
		(layer "In11.Cu")
		(net "BMC_VGA_VSYNC")
	)
	(segment
		(start 451.006464 -27.225498)
		(end 453.688196 -24.543766)
		(width 0.089408)
		(layer "In11.Cu")
		(net "BMC_VGA_VSYNC")
	)
	(segment
		(start 456.2094 -18.388076)
		(end 456.2094 -17.4752)
		(width 0.089408)
		(layer "In11.Cu")
		(net "BMC_VGA_VSYNC")
	)
	(segment
		(start 449.101464 -27.479498)
		(end 449.457064 -27.479498)
		(width 0.089408)
		(layer "In11.Cu")
		(net "BMC_VGA_VSYNC")
	)
	(segment
		(start 447.3702 -29.210762)
		(end 449.101464 -27.479498)
		(width 0.089408)
		(layer "In11.Cu")
		(net "BMC_VGA_VSYNC")
	)
	(segment
		(start 418.314124 -28.065222)
		(end 418.690298 -28.441396)
		(width 0.089408)
		(layer "In11.Cu")
		(net "BMC_VGA_VSYNC")
	)
	(segment
		(start 418.690298 -28.441396)
		(end 418.690298 -28.534614)
		(width 0.089408)
		(layer "In11.Cu")
		(net "BMC_VGA_VSYNC")
	)
	(segment
		(start 449.711064 -27.225498)
		(end 451.006464 -27.225498)
		(width 0.089408)
		(layer "In11.Cu")
		(net "BMC_VGA_VSYNC")
	)
	(segment
		(start 447.3702 -30.2514)
		(end 447.3702 -29.210762)
		(width 0.089408)
		(layer "In11.Cu")
		(net "BMC_VGA_VSYNC")
	)
	(segment
		(start 426.3136 -26.162)
		(end 425.882308 -26.593292)
		(width 0.089408)
		(layer "In11.Cu")
		(net "BMC_VGA_VSYNC")
	)
	(segment
		(start 455.723498 -18.873978)
		(end 456.2094 -18.388076)
		(width 0.089408)
		(layer "In11.Cu")
		(net "BMC_VGA_VSYNC")
	)
	(segment
		(start 454.526396 -24.543766)
		(end 455.723498 -23.346664)
		(width 0.089408)
		(layer "In11.Cu")
		(net "BMC_VGA_VSYNC")
	)
	(segment
		(start 449.457064 -27.479498)
		(end 449.711064 -27.225498)
		(width 0.089408)
		(layer "In11.Cu")
		(net "BMC_VGA_VSYNC")
	)
	(segment
		(start 425.882308 -26.593292)
		(end 419.09111 -26.593292)
		(width 0.089408)
		(layer "In11.Cu")
		(net "BMC_VGA_VSYNC")
	)
	(segment
		(start 419.09111 -26.593292)
		(end 418.314124 -27.370278)
		(width 0.089408)
		(layer "In11.Cu")
		(net "BMC_VGA_VSYNC")
	)
	(segment
		(start 418.314124 -27.370278)
		(end 418.314124 -28.065222)
		(width 0.089408)
		(layer "In11.Cu")
		(net "BMC_VGA_VSYNC")
	)
	(segment
		(start 453.688196 -24.543766)
		(end 454.526396 -24.543766)
		(width 0.089408)
		(layer "In11.Cu")
		(net "BMC_VGA_VSYNC")
	)
	(segment
		(start 413.490156 -28.934664)
		(end 413.890206 -28.534614)
		(width 0.10795)
		(layer "F.Cu")
		(net "BMC_VGA_RED")
	)
	(via
		(at 413.890206 -28.534614)
		(size 0.4572)
		(drill 0.2032)
		(layers "F.Cu" "B.Cu")
		(net "BMC_VGA_RED")
	)
	(via
		(at 418.1348 -26.3652)
		(size 0.6604)
		(drill 0.3302)
		(layers "F.Cu" "B.Cu")
		(net "BMC_VGA_RED")
	)
	(segment
		(start 415.472372 -27.630628)
		(end 415.472372 -27.412696)
		(width 0.10795)
		(layer "B.Cu")
		(net "BMC_VGA_RED")
	)
	(segment
		(start 416.9664 -26.035)
		(end 417.2204 -26.035)
		(width 0.10795)
		(layer "B.Cu")
		(net "BMC_VGA_RED")
	)
	(segment
		(start 417.2204 -26.035)
		(end 417.699952 -26.514552)
		(width 0.10795)
		(layer "B.Cu")
		(net "BMC_VGA_RED")
	)
	(segment
		(start 414.289494 -28.135326)
		(end 414.967674 -28.135326)
		(width 0.10795)
		(layer "B.Cu")
		(net "BMC_VGA_RED")
	)
	(segment
		(start 414.967674 -28.135326)
		(end 415.472372 -27.630628)
		(width 0.10795)
		(layer "B.Cu")
		(net "BMC_VGA_RED")
	)
	(segment
		(start 418.1348 -26.3652)
		(end 418.1348 -25.505156)
		(width 0.10795)
		(layer "B.Cu")
		(net "BMC_VGA_RED")
	)
	(segment
		(start 416.179 -26.706068)
		(end 416.179 -26.035)
		(width 0.10795)
		(layer "B.Cu")
		(net "BMC_VGA_RED")
	)
	(segment
		(start 417.985448 -26.514552)
		(end 418.1348 -26.3652)
		(width 0.10795)
		(layer "B.Cu")
		(net "BMC_VGA_RED")
	)
	(segment
		(start 417.699952 -26.514552)
		(end 417.985448 -26.514552)
		(width 0.10795)
		(layer "B.Cu")
		(net "BMC_VGA_RED")
	)
	(segment
		(start 415.472372 -27.412696)
		(end 416.179 -26.706068)
		(width 0.10795)
		(layer "B.Cu")
		(net "BMC_VGA_RED")
	)
	(segment
		(start 413.890206 -28.534614)
		(end 414.289494 -28.135326)
		(width 0.10795)
		(layer "B.Cu")
		(net "BMC_VGA_RED")
	)
	(segment
		(start 418.1348 -25.505156)
		(end 418.084 -25.454356)
		(width 0.10795)
		(layer "B.Cu")
		(net "BMC_VGA_RED")
	)
	(segment
		(start 416.179 -26.035)
		(end 416.9664 -26.035)
		(width 0.10795)
		(layer "B.Cu")
		(net "BMC_VGA_RED")
	)
	(segment
		(start 418.084 -25.454356)
		(end 418.084 -24.765)
		(width 0.10795)
		(layer "B.Cu")
		(net "BMC_VGA_RED")
	)
	(segment
		(start 416.690048 -29.734764)
		(end 417.089336 -29.335476)
		(width 0.10795)
		(layer "F.Cu")
		(net "BMC_VGA_HSYNC")
	)
	(via
		(at 417.089336 -29.335476)
		(size 0.4572)
		(drill 0.2032)
		(layers "F.Cu" "B.Cu")
		(net "BMC_VGA_HSYNC")
	)
	(via
		(at 426.755306 -25.164542)
		(size 0.508)
		(drill 0.254)
		(layers "F.Cu" "B.Cu")
		(net "BMC_VGA_HSYNC")
	)
	(via
		(at 455.7014 -18.008092)
		(size 0.508)
		(drill 0.254)
		(layers "F.Cu" "B.Cu")
		(net "BMC_VGA_HSYNC")
	)
	(via
		(at 446.5574 -30.2514)
		(size 0.508)
		(drill 0.254)
		(layers "F.Cu" "B.Cu")
		(net "BMC_VGA_HSYNC")
	)
	(via
		(at 495.144806 -38.629082)
		(size 0.508)
		(drill 0.254)
		(layers "F.Cu" "B.Cu")
		(net "BMC_VGA_HSYNC")
	)
	(segment
		(start 495.676174 -39.651686)
		(end 495.676174 -39.16045)
		(width 0.10795)
		(layer "B.Cu")
		(net "BMC_VGA_HSYNC")
	)
	(segment
		(start 495.676174 -39.16045)
		(end 495.144806 -38.629082)
		(width 0.10795)
		(layer "B.Cu")
		(net "BMC_VGA_HSYNC")
	)
	(segment
		(start 465.881212 -14.809216)
		(end 471.887804 -14.809216)
		(width 0.089408)
		(layer "In4.Cu")
		(net "BMC_VGA_HSYNC")
	)
	(segment
		(start 482.578156 -29.815028)
		(end 483.604824 -30.841696)
		(width 0.089408)
		(layer "In4.Cu")
		(net "BMC_VGA_HSYNC")
	)
	(segment
		(start 494.86947 -39.465504)
		(end 495.144806 -39.190168)
		(width 0.089408)
		(layer "In4.Cu")
		(net "BMC_VGA_HSYNC")
	)
	(segment
		(start 486.292398 -30.841696)
		(end 486.398824 -30.948122)
		(width 0.089408)
		(layer "In4.Cu")
		(net "BMC_VGA_HSYNC")
	)
	(segment
		(start 461.77581 -17.733264)
		(end 462.552034 -16.95704)
		(width 0.089408)
		(layer "In4.Cu")
		(net "BMC_VGA_HSYNC")
	)
	(segment
		(start 482.577902 -29.442664)
		(end 482.577902 -29.738828)
		(width 0.089408)
		(layer "In4.Cu")
		(net "BMC_VGA_HSYNC")
	)
	(segment
		(start 476.50654 -20.911566)
		(end 478.150174 -22.5552)
		(width 0.089408)
		(layer "In4.Cu")
		(net "BMC_VGA_HSYNC")
	)
	(segment
		(start 456.685142 -17.733264)
		(end 461.77581 -17.733264)
		(width 0.089408)
		(layer "In4.Cu")
		(net "BMC_VGA_HSYNC")
	)
	(segment
		(start 492.039656 -39.465504)
		(end 494.86947 -39.465504)
		(width 0.089408)
		(layer "In4.Cu")
		(net "BMC_VGA_HSYNC")
	)
	(segment
		(start 476.50654 -19.427952)
		(end 476.50654 -20.911566)
		(width 0.089408)
		(layer "In4.Cu")
		(net "BMC_VGA_HSYNC")
	)
	(segment
		(start 486.399078 -35.289236)
		(end 488.295442 -37.1856)
		(width 0.089408)
		(layer "In4.Cu")
		(net "BMC_VGA_HSYNC")
	)
	(segment
		(start 481.83419 -26.338784)
		(end 482.578156 -27.08275)
		(width 0.089408)
		(layer "In4.Cu")
		(net "BMC_VGA_HSYNC")
	)
	(segment
		(start 486.398824 -31.106618)
		(end 486.399078 -31.106872)
		(width 0.089408)
		(layer "In4.Cu")
		(net "BMC_VGA_HSYNC")
	)
	(segment
		(start 489.759752 -37.1856)
		(end 492.039656 -39.465504)
		(width 0.089408)
		(layer "In4.Cu")
		(net "BMC_VGA_HSYNC")
	)
	(segment
		(start 482.578156 -27.08275)
		(end 482.578156 -29.44241)
		(width 0.089408)
		(layer "In4.Cu")
		(net "BMC_VGA_HSYNC")
	)
	(segment
		(start 488.295442 -37.1856)
		(end 489.759752 -37.1856)
		(width 0.089408)
		(layer "In4.Cu")
		(net "BMC_VGA_HSYNC")
	)
	(segment
		(start 463.733388 -16.95704)
		(end 465.881212 -14.809216)
		(width 0.0889)
		(layer "In4.Cu")
		(net "BMC_VGA_HSYNC")
	)
	(segment
		(start 482.578156 -29.44241)
		(end 482.577902 -29.442664)
		(width 0.089408)
		(layer "In4.Cu")
		(net "BMC_VGA_HSYNC")
	)
	(segment
		(start 482.577902 -29.738828)
		(end 482.578156 -29.739082)
		(width 0.089408)
		(layer "In4.Cu")
		(net "BMC_VGA_HSYNC")
	)
	(segment
		(start 482.578156 -29.739082)
		(end 482.578156 -29.815028)
		(width 0.089408)
		(layer "In4.Cu")
		(net "BMC_VGA_HSYNC")
	)
	(segment
		(start 495.144806 -39.190168)
		(end 495.144806 -38.629082)
		(width 0.089408)
		(layer "In4.Cu")
		(net "BMC_VGA_HSYNC")
	)
	(segment
		(start 478.150174 -22.5552)
		(end 479.766376 -22.5552)
		(width 0.089408)
		(layer "In4.Cu")
		(net "BMC_VGA_HSYNC")
	)
	(segment
		(start 479.766376 -22.5552)
		(end 481.83419 -24.623014)
		(width 0.089408)
		(layer "In4.Cu")
		(net "BMC_VGA_HSYNC")
	)
	(segment
		(start 483.604824 -30.841696)
		(end 486.292398 -30.841696)
		(width 0.089408)
		(layer "In4.Cu")
		(net "BMC_VGA_HSYNC")
	)
	(segment
		(start 462.552034 -16.95704)
		(end 463.733388 -16.95704)
		(width 0.0889)
		(layer "In4.Cu")
		(net "BMC_VGA_HSYNC")
	)
	(segment
		(start 486.398824 -30.948122)
		(end 486.398824 -31.106618)
		(width 0.089408)
		(layer "In4.Cu")
		(net "BMC_VGA_HSYNC")
	)
	(segment
		(start 481.83419 -24.623014)
		(end 481.83419 -26.338784)
		(width 0.089408)
		(layer "In4.Cu")
		(net "BMC_VGA_HSYNC")
	)
	(segment
		(start 471.887804 -14.809216)
		(end 476.50654 -19.427952)
		(width 0.089408)
		(layer "In4.Cu")
		(net "BMC_VGA_HSYNC")
	)
	(segment
		(start 455.7014 -18.008092)
		(end 456.410314 -18.008092)
		(width 0.089408)
		(layer "In4.Cu")
		(net "BMC_VGA_HSYNC")
	)
	(segment
		(start 456.410314 -18.008092)
		(end 456.685142 -17.733264)
		(width 0.089408)
		(layer "In4.Cu")
		(net "BMC_VGA_HSYNC")
	)
	(segment
		(start 486.399078 -31.106872)
		(end 486.399078 -35.289236)
		(width 0.089408)
		(layer "In4.Cu")
		(net "BMC_VGA_HSYNC")
	)
	(segment
		(start 444.615316 -23.705566)
		(end 446.278 -25.36825)
		(width 0.089408)
		(layer "In9.Cu")
		(net "BMC_VGA_HSYNC")
	)
	(segment
		(start 432.8541 -25.7556)
		(end 434.6575 -23.9522)
		(width 0.089408)
		(layer "In9.Cu")
		(net "BMC_VGA_HSYNC")
	)
	(segment
		(start 427.789086 -25.7556)
		(end 432.8541 -25.7556)
		(width 0.089408)
		(layer "In9.Cu")
		(net "BMC_VGA_HSYNC")
	)
	(segment
		(start 446.278 -25.36825)
		(end 446.278 -29.972)
		(width 0.089408)
		(layer "In9.Cu")
		(net "BMC_VGA_HSYNC")
	)
	(segment
		(start 426.755306 -25.164542)
		(end 427.198028 -25.164542)
		(width 0.089408)
		(layer "In9.Cu")
		(net "BMC_VGA_HSYNC")
	)
	(segment
		(start 427.198028 -25.164542)
		(end 427.789086 -25.7556)
		(width 0.089408)
		(layer "In9.Cu")
		(net "BMC_VGA_HSYNC")
	)
	(segment
		(start 442.528198 -23.9522)
		(end 442.774832 -23.705566)
		(width 0.089408)
		(layer "In9.Cu")
		(net "BMC_VGA_HSYNC")
	)
	(segment
		(start 442.774832 -23.705566)
		(end 444.615316 -23.705566)
		(width 0.089408)
		(layer "In9.Cu")
		(net "BMC_VGA_HSYNC")
	)
	(segment
		(start 434.6575 -23.9522)
		(end 442.528198 -23.9522)
		(width 0.089408)
		(layer "In9.Cu")
		(net "BMC_VGA_HSYNC")
	)
	(segment
		(start 446.278 -29.972)
		(end 446.5574 -30.2514)
		(width 0.089408)
		(layer "In9.Cu")
		(net "BMC_VGA_HSYNC")
	)
	(segment
		(start 422.77665 -25.770078)
		(end 423.066464 -25.480264)
		(width 0.089408)
		(layer "In11.Cu")
		(net "BMC_VGA_HSYNC")
	)
	(segment
		(start 455.3458 -23.1902)
		(end 455.3458 -18.363692)
		(width 0.089408)
		(layer "In11.Cu")
		(net "BMC_VGA_HSYNC")
	)
	(segment
		(start 449.3006 -27.1018)
		(end 449.5546 -26.8478)
		(width 0.089408)
		(layer "In11.Cu")
		(net "BMC_VGA_HSYNC")
	)
	(segment
		(start 453.52081 -24.17699)
		(end 454.35901 -24.17699)
		(width 0.089408)
		(layer "In11.Cu")
		(net "BMC_VGA_HSYNC")
	)
	(segment
		(start 448.945 -27.1018)
		(end 449.3006 -27.1018)
		(width 0.089408)
		(layer "In11.Cu")
		(net "BMC_VGA_HSYNC")
	)
	(segment
		(start 426.439584 -25.480264)
		(end 426.755306 -25.164542)
		(width 0.089408)
		(layer "In11.Cu")
		(net "BMC_VGA_HSYNC")
	)
	(segment
		(start 455.3458 -18.363692)
		(end 455.7014 -18.008092)
		(width 0.089408)
		(layer "In11.Cu")
		(net "BMC_VGA_HSYNC")
	)
	(segment
		(start 449.5546 -26.8478)
		(end 450.85 -26.8478)
		(width 0.089408)
		(layer "In11.Cu")
		(net "BMC_VGA_HSYNC")
	)
	(segment
		(start 450.85 -26.8478)
		(end 453.52081 -24.17699)
		(width 0.089408)
		(layer "In11.Cu")
		(net "BMC_VGA_HSYNC")
	)
	(segment
		(start 417.4744 -28.950412)
		(end 417.4744 -27.28976)
		(width 0.089408)
		(layer "In11.Cu")
		(net "BMC_VGA_HSYNC")
	)
	(segment
		(start 446.5574 -29.4894)
		(end 448.945 -27.1018)
		(width 0.089408)
		(layer "In11.Cu")
		(net "BMC_VGA_HSYNC")
	)
	(segment
		(start 420.22141 -25.770078)
		(end 422.77665 -25.770078)
		(width 0.089408)
		(layer "In11.Cu")
		(net "BMC_VGA_HSYNC")
	)
	(segment
		(start 454.35901 -24.17699)
		(end 455.3458 -23.1902)
		(width 0.089408)
		(layer "In11.Cu")
		(net "BMC_VGA_HSYNC")
	)
	(segment
		(start 419.16985 -25.59431)
		(end 420.045642 -25.59431)
		(width 0.089408)
		(layer "In11.Cu")
		(net "BMC_VGA_HSYNC")
	)
	(segment
		(start 423.066464 -25.480264)
		(end 426.439584 -25.480264)
		(width 0.089408)
		(layer "In11.Cu")
		(net "BMC_VGA_HSYNC")
	)
	(segment
		(start 420.045642 -25.59431)
		(end 420.22141 -25.770078)
		(width 0.089408)
		(layer "In11.Cu")
		(net "BMC_VGA_HSYNC")
	)
	(segment
		(start 417.4744 -27.28976)
		(end 419.16985 -25.59431)
		(width 0.089408)
		(layer "In11.Cu")
		(net "BMC_VGA_HSYNC")
	)
	(segment
		(start 446.5574 -30.2514)
		(end 446.5574 -29.4894)
		(width 0.089408)
		(layer "In11.Cu")
		(net "BMC_VGA_HSYNC")
	)
	(segment
		(start 417.089336 -29.335476)
		(end 417.4744 -28.950412)
		(width 0.089408)
		(layer "In11.Cu")
		(net "BMC_VGA_HSYNC")
	)
	(segment
		(start 413.490156 -28.134564)
		(end 413.8676 -27.75712)
		(width 0.10795)
		(layer "F.Cu")
		(net "BMC_VGA_GREEN")
	)
	(segment
		(start 413.8676 -27.75712)
		(end 413.889698 -27.75712)
		(width 0.10795)
		(layer "F.Cu")
		(net "BMC_VGA_GREEN")
	)
	(via
		(at 413.889698 -27.75712)
		(size 0.4572)
		(drill 0.2032)
		(layers "F.Cu" "B.Cu")
		(net "BMC_VGA_GREEN")
	)
	(via
		(at 415.387536 -26.798778)
		(size 0.6604)
		(drill 0.3302)
		(layers "F.Cu" "B.Cu")
		(net "BMC_VGA_GREEN")
	)
	(segment
		(start 416.9664 -22.987)
		(end 417.576 -22.987)
		(width 0.10795)
		(layer "B.Cu")
		(net "BMC_VGA_GREEN")
	)
	(segment
		(start 416.179 -22.987)
		(end 416.9664 -22.987)
		(width 0.10795)
		(layer "B.Cu")
		(net "BMC_VGA_GREEN")
	)
	(segment
		(start 415.387536 -26.798778)
		(end 415.546032 -26.640282)
		(width 0.10795)
		(layer "B.Cu")
		(net "BMC_VGA_GREEN")
	)
	(segment
		(start 417.576 -22.987)
		(end 418.084 -23.495)
		(width 0.10795)
		(layer "B.Cu")
		(net "BMC_VGA_GREEN")
	)
	(segment
		(start 414.837372 -27.348942)
		(end 415.387536 -26.798778)
		(width 0.10795)
		(layer "B.Cu")
		(net "BMC_VGA_GREEN")
	)
	(segment
		(start 416.0774 -22.987)
		(end 416.179 -22.987)
		(width 0.10795)
		(layer "B.Cu")
		(net "BMC_VGA_GREEN")
	)
	(segment
		(start 415.546032 -26.640282)
		(end 415.546032 -23.518368)
		(width 0.10795)
		(layer "B.Cu")
		(net "BMC_VGA_GREEN")
	)
	(segment
		(start 415.546032 -23.518368)
		(end 416.0774 -22.987)
		(width 0.10795)
		(layer "B.Cu")
		(net "BMC_VGA_GREEN")
	)
	(segment
		(start 413.889698 -27.75712)
		(end 414.297876 -27.348942)
		(width 0.089408)
		(layer "B.Cu")
		(net "BMC_VGA_GREEN")
	)
	(segment
		(start 414.297876 -27.348942)
		(end 414.837372 -27.348942)
		(width 0.10795)
		(layer "B.Cu")
		(net "BMC_VGA_GREEN")
	)
	(segment
		(start 413.490156 -27.334718)
		(end 413.8676 -26.957274)
		(width 0.10795)
		(layer "F.Cu")
		(net "BMC_VGA_BLUE")
	)
	(via
		(at 413.8676 -26.957274)
		(size 0.4572)
		(drill 0.2032)
		(layers "F.Cu" "B.Cu")
		(net "BMC_VGA_BLUE")
	)
	(via
		(at 418.7698 -20.8534)
		(size 0.6604)
		(drill 0.3302)
		(layers "F.Cu" "B.Cu")
		(net "BMC_VGA_BLUE")
	)
	(segment
		(start 418.084 -21.5392)
		(end 418.7698 -20.8534)
		(width 0.10795)
		(layer "B.Cu")
		(net "BMC_VGA_BLUE")
	)
	(segment
		(start 416.179 -22.225)
		(end 416.9664 -22.225)
		(width 0.10795)
		(layer "B.Cu")
		(net "BMC_VGA_BLUE")
	)
	(segment
		(start 415.003996 -25.059894)
		(end 415.003996 -23.17623)
		(width 0.10795)
		(layer "B.Cu")
		(net "BMC_VGA_BLUE")
	)
	(segment
		(start 413.8676 -26.957274)
		(end 414.58261 -26.242264)
		(width 0.10795)
		(layer "B.Cu")
		(net "BMC_VGA_BLUE")
	)
	(segment
		(start 415.003996 -23.17623)
		(end 415.955226 -22.225)
		(width 0.10795)
		(layer "B.Cu")
		(net "BMC_VGA_BLUE")
	)
	(segment
		(start 416.9664 -22.225)
		(end 418.084 -22.225)
		(width 0.10795)
		(layer "B.Cu")
		(net "BMC_VGA_BLUE")
	)
	(segment
		(start 414.58261 -26.242264)
		(end 414.58261 -25.48128)
		(width 0.10795)
		(layer "B.Cu")
		(net "BMC_VGA_BLUE")
	)
	(segment
		(start 415.955226 -22.225)
		(end 416.179 -22.225)
		(width 0.10795)
		(layer "B.Cu")
		(net "BMC_VGA_BLUE")
	)
	(segment
		(start 414.58261 -25.48128)
		(end 415.003996 -25.059894)
		(width 0.10795)
		(layer "B.Cu")
		(net "BMC_VGA_BLUE")
	)
	(segment
		(start 418.084 -22.225)
		(end 418.084 -21.5392)
		(width 0.10795)
		(layer "B.Cu")
		(net "BMC_VGA_BLUE")
	)
	(segment
		(start 438.4675 -18.542)
		(end 438.404 -18.6055)
		(width 0.1016)
		(layer "F.Cu")
		(net "PUMP_TACH_R")
	)
	(segment
		(start 438.404 -18.6055)
		(end 437.388 -18.6055)
		(width 0.1016)
		(layer "F.Cu")
		(net "PUMP_TACH_R")
	)
	(segment
		(start 441.0456 -18.542)
		(end 442.0616 -17.526)
		(width 0.1016)
		(layer "F.Cu")
		(net "PUMP_TACH_R")
	)
	(segment
		(start 438.912 -18.542)
		(end 438.4675 -18.542)
		(width 0.1016)
		(layer "F.Cu")
		(net "PUMP_TACH_R")
	)
	(segment
		(start 438.912 -18.542)
		(end 441.0456 -18.542)
		(width 0.1016)
		(layer "F.Cu")
		(net "PUMP_TACH_R")
	)
	(via
		(at 442.0616 -17.526)
		(size 0.762)
		(drill 0.381)
		(layers "F.Cu" "B.Cu")
		(net "PUMP_TACH_R")
	)
	(segment
		(start 324.8406 3.7592)
		(end 326.04075 4.95935)
		(width 0.1016)
		(layer "F.Cu")
		(net "PUMP_TACH_D")
	)
	(segment
		(start 438.912 -20.828)
		(end 438.912 -21.6408)
		(width 0.1016)
		(layer "F.Cu")
		(net "PUMP_TACH_D")
	)
	(segment
		(start 449.3895 -17.8689)
		(end 448.9577 -17.4371)
		(width 0.1016)
		(layer "F.Cu")
		(net "PUMP_TACH_D")
	)
	(segment
		(start 438.912 -21.6408)
		(end 439.2422 -21.971)
		(width 0.1016)
		(layer "F.Cu")
		(net "PUMP_TACH_D")
	)
	(segment
		(start 326.04075 4.95935)
		(end 329.855322 4.95935)
		(width 0.1016)
		(layer "F.Cu")
		(net "PUMP_TACH_D")
	)
	(segment
		(start 329.855322 4.95935)
		(end 330.085446 4.729226)
		(width 0.1016)
		(layer "F.Cu")
		(net "PUMP_TACH_D")
	)
	(segment
		(start 441.198 -21.971)
		(end 442.7728 -20.3962)
		(width 0.1016)
		(layer "F.Cu")
		(net "PUMP_TACH_D")
	)
	(segment
		(start 439.2422 -21.971)
		(end 441.198 -21.971)
		(width 0.1016)
		(layer "F.Cu")
		(net "PUMP_TACH_D")
	)
	(segment
		(start 445.443102 -17.725898)
		(end 442.7728 -20.3962)
		(width 0.1016)
		(layer "F.Cu")
		(net "PUMP_TACH_D")
	)
	(segment
		(start 448.110102 -17.725898)
		(end 445.443102 -17.725898)
		(width 0.1016)
		(layer "F.Cu")
		(net "PUMP_TACH_D")
	)
	(segment
		(start 448.3989 -17.4371)
		(end 448.110102 -17.725898)
		(width 0.1016)
		(layer "F.Cu")
		(net "PUMP_TACH_D")
	)
	(segment
		(start 448.9577 -17.4371)
		(end 448.3989 -17.4371)
		(width 0.1016)
		(layer "F.Cu")
		(net "PUMP_TACH_D")
	)
	(via
		(at 442.7728 -20.3962)
		(size 0.762)
		(drill 0.381)
		(layers "F.Cu" "B.Cu")
		(net "PUMP_TACH_D")
	)
	(via
		(at 330.085446 4.729226)
		(size 0.508)
		(drill 0.254)
		(layers "F.Cu" "B.Cu")
		(net "PUMP_TACH_D")
	)
	(via
		(at 324.8406 3.7592)
		(size 0.508)
		(drill 0.254)
		(layers "F.Cu" "B.Cu")
		(net "PUMP_TACH_D")
	)
	(via
		(at 179.1335 -2.1844)
		(size 0.508)
		(drill 0.254)
		(layers "F.Cu" "B.Cu")
		(net "PUMP_TACH_D")
	)
	(via
		(at 440.65825 -2.346452)
		(size 0.508)
		(drill 0.254)
		(layers "F.Cu" "B.Cu")
		(net "PUMP_TACH_D")
	)
	(via
		(at 449.3895 -17.8689)
		(size 0.508)
		(drill 0.254)
		(layers "F.Cu" "B.Cu")
		(net "PUMP_TACH_D")
	)
	(segment
		(start 458.600556 -1.767078)
		(end 457.831444 -1.767078)
		(width 0.0889)
		(layer "In2.Cu")
		(net "PUMP_TACH_D")
	)
	(segment
		(start 460.134462 -16.94561)
		(end 462.529936 -14.550136)
		(width 0.0889)
		(layer "In2.Cu")
		(net "PUMP_TACH_D")
	)
	(segment
		(start 449.3895 -17.8689)
		(end 449.4784 -17.8689)
		(width 0.0889)
		(layer "In2.Cu")
		(net "PUMP_TACH_D")
	)
	(segment
		(start 461.890872 -3.573018)
		(end 461.890872 -3.19913)
		(width 0.0889)
		(layer "In2.Cu")
		(net "PUMP_TACH_D")
	)
	(segment
		(start 462.87817 -10.39114)
		(end 462.87817 -8.995664)
		(width 0.0889)
		(layer "In2.Cu")
		(net "PUMP_TACH_D")
	)
	(segment
		(start 461.532732 -8.56615)
		(end 460.145638 -7.179056)
		(width 0.0889)
		(layer "In2.Cu")
		(net "PUMP_TACH_D")
	)
	(segment
		(start 461.890872 -3.19913)
		(end 461.626966 -2.935224)
		(width 0.0889)
		(layer "In2.Cu")
		(net "PUMP_TACH_D")
	)
	(segment
		(start 461.626966 -2.935224)
		(end 461.187038 -2.935224)
		(width 0.0889)
		(layer "In2.Cu")
		(net "PUMP_TACH_D")
	)
	(segment
		(start 460.145638 -5.318252)
		(end 461.890872 -3.573018)
		(width 0.0889)
		(layer "In2.Cu")
		(net "PUMP_TACH_D")
	)
	(segment
		(start 460.145638 -7.179056)
		(end 460.145638 -5.318252)
		(width 0.0889)
		(layer "In2.Cu")
		(net "PUMP_TACH_D")
	)
	(segment
		(start 459.427326 -1.76657)
		(end 458.601064 -1.76657)
		(width 0.0889)
		(layer "In2.Cu")
		(net "PUMP_TACH_D")
	)
	(segment
		(start 457.831444 -1.767078)
		(end 457.830936 -1.76657)
		(width 0.0889)
		(layer "In2.Cu")
		(net "PUMP_TACH_D")
	)
	(segment
		(start 458.601064 -1.76657)
		(end 458.600556 -1.767078)
		(width 0.0889)
		(layer "In2.Cu")
		(net "PUMP_TACH_D")
	)
	(segment
		(start 462.448656 -8.56615)
		(end 461.532732 -8.56615)
		(width 0.0889)
		(layer "In2.Cu")
		(net "PUMP_TACH_D")
	)
	(segment
		(start 455.79538 -1.60655)
		(end 452.949056 -1.60655)
		(width 0.0889)
		(layer "In2.Cu")
		(net "PUMP_TACH_D")
	)
	(segment
		(start 457.830936 -1.76657)
		(end 455.9554 -1.76657)
		(width 0.0889)
		(layer "In2.Cu")
		(net "PUMP_TACH_D")
	)
	(segment
		(start 462.529936 -10.739374)
		(end 462.87817 -10.39114)
		(width 0.0889)
		(layer "In2.Cu")
		(net "PUMP_TACH_D")
	)
	(segment
		(start 460.890874 -2.63906)
		(end 460.299816 -2.63906)
		(width 0.0889)
		(layer "In2.Cu")
		(net "PUMP_TACH_D")
	)
	(segment
		(start 455.9554 -1.76657)
		(end 455.79538 -1.60655)
		(width 0.0889)
		(layer "In2.Cu")
		(net "PUMP_TACH_D")
	)
	(segment
		(start 462.87817 -8.995664)
		(end 462.448656 -8.56615)
		(width 0.0889)
		(layer "In2.Cu")
		(net "PUMP_TACH_D")
	)
	(segment
		(start 460.299816 -2.63906)
		(end 459.427326 -1.76657)
		(width 0.0889)
		(layer "In2.Cu")
		(net "PUMP_TACH_D")
	)
	(segment
		(start 449.4784 -17.8689)
		(end 450.40169 -16.94561)
		(width 0.0889)
		(layer "In2.Cu")
		(net "PUMP_TACH_D")
	)
	(segment
		(start 462.529936 -14.550136)
		(end 462.529936 -10.739374)
		(width 0.0889)
		(layer "In2.Cu")
		(net "PUMP_TACH_D")
	)
	(segment
		(start 440.65825 -2.589784)
		(end 440.65825 -2.346452)
		(width 0.0889)
		(layer "In2.Cu")
		(net "PUMP_TACH_D")
	)
	(segment
		(start 461.187038 -2.935224)
		(end 460.890874 -2.63906)
		(width 0.0889)
		(layer "In2.Cu")
		(net "PUMP_TACH_D")
	)
	(segment
		(start 450.744336 -3.81127)
		(end 441.879736 -3.81127)
		(width 0.0889)
		(layer "In2.Cu")
		(net "PUMP_TACH_D")
	)
	(segment
		(start 441.879736 -3.81127)
		(end 440.65825 -2.589784)
		(width 0.0889)
		(layer "In2.Cu")
		(net "PUMP_TACH_D")
	)
	(segment
		(start 450.40169 -16.94561)
		(end 460.134462 -16.94561)
		(width 0.0889)
		(layer "In2.Cu")
		(net "PUMP_TACH_D")
	)
	(segment
		(start 452.949056 -1.60655)
		(end 450.744336 -3.81127)
		(width 0.0889)
		(layer "In2.Cu")
		(net "PUMP_TACH_D")
	)
	(segment
		(start 403.680676 -1.6764)
		(end 406.690576 -1.6764)
		(width 0.0889)
		(layer "In4.Cu")
		(net "PUMP_TACH_D")
	)
	(segment
		(start 356.1842 -1.7018)
		(end 358.4194 -1.7018)
		(width 0.0889)
		(layer "In4.Cu")
		(net "PUMP_TACH_D")
	)
	(segment
		(start 180.213 -2.4638)
		(end 179.9336 -2.1844)
		(width 0.0889)
		(layer "In4.Cu")
		(net "PUMP_TACH_D")
	)
	(segment
		(start 330.592938 5.236718)
		(end 336.599276 5.236718)
		(width 0.0889)
		(layer "In4.Cu")
		(net "PUMP_TACH_D")
	)
	(segment
		(start 182.651908 -0.564896)
		(end 182.651908 -1.421892)
		(width 0.0889)
		(layer "In4.Cu")
		(net "PUMP_TACH_D")
	)
	(segment
		(start 323.49567 5.10413)
		(end 182.85333 5.10413)
		(width 0.0889)
		(layer "In4.Cu")
		(net "PUMP_TACH_D")
	)
	(segment
		(start 343.54008 -1.704086)
		(end 344.9955 -1.704086)
		(width 0.0889)
		(layer "In4.Cu")
		(net "PUMP_TACH_D")
	)
	(segment
		(start 330.085446 4.729226)
		(end 330.592938 5.236718)
		(width 0.0889)
		(layer "In4.Cu")
		(net "PUMP_TACH_D")
	)
	(segment
		(start 181.631082 3.881882)
		(end 181.631082 2.328418)
		(width 0.0889)
		(layer "In4.Cu")
		(net "PUMP_TACH_D")
	)
	(segment
		(start 182.85333 5.10413)
		(end 181.631082 3.881882)
		(width 0.0889)
		(layer "In4.Cu")
		(net "PUMP_TACH_D")
	)
	(segment
		(start 420.18839 0.93726)
		(end 422.0464 -0.92075)
		(width 0.0889)
		(layer "In4.Cu")
		(net "PUMP_TACH_D")
	)
	(segment
		(start 417.537646 0.93726)
		(end 420.18839 0.93726)
		(width 0.0889)
		(layer "In4.Cu")
		(net "PUMP_TACH_D")
	)
	(segment
		(start 388.8994 -2.413)
		(end 400.3294 -2.413)
		(width 0.0889)
		(layer "In4.Cu")
		(net "PUMP_TACH_D")
	)
	(segment
		(start 379.81255 0.19685)
		(end 381.357378 -1.347978)
		(width 0.0889)
		(layer "In4.Cu")
		(net "PUMP_TACH_D")
	)
	(segment
		(start 179.9336 -2.1844)
		(end 179.1335 -2.1844)
		(width 0.0889)
		(layer "In4.Cu")
		(net "PUMP_TACH_D")
	)
	(segment
		(start 346.3036 2.69748)
		(end 348.297246 4.691126)
		(width 0.0889)
		(layer "In4.Cu")
		(net "PUMP_TACH_D")
	)
	(segment
		(start 350.288352 4.691126)
		(end 353.0854 1.894078)
		(width 0.0889)
		(layer "In4.Cu")
		(net "PUMP_TACH_D")
	)
	(segment
		(start 344.9955 -1.704086)
		(end 346.3036 -0.395986)
		(width 0.0889)
		(layer "In4.Cu")
		(net "PUMP_TACH_D")
	)
	(segment
		(start 183.0705 1.74625)
		(end 183.0705 -0.084582)
		(width 0.0889)
		(layer "In4.Cu")
		(net "PUMP_TACH_D")
	)
	(segment
		(start 362.370878 -2.199386)
		(end 364.722664 0.1524)
		(width 0.0889)
		(layer "In4.Cu")
		(net "PUMP_TACH_D")
	)
	(segment
		(start 358.4194 -1.7018)
		(end 358.916986 -2.199386)
		(width 0.0889)
		(layer "In4.Cu")
		(net "PUMP_TACH_D")
	)
	(segment
		(start 336.599276 5.236718)
		(end 343.54008 -1.704086)
		(width 0.0889)
		(layer "In4.Cu")
		(net "PUMP_TACH_D")
	)
	(segment
		(start 384.4544 -2.6416)
		(end 388.6708 -2.6416)
		(width 0.0889)
		(layer "In4.Cu")
		(net "PUMP_TACH_D")
	)
	(segment
		(start 181.61 -2.4638)
		(end 180.213 -2.4638)
		(width 0.0889)
		(layer "In4.Cu")
		(net "PUMP_TACH_D")
	)
	(segment
		(start 425.9072 -1.9558)
		(end 430.4284 -1.9558)
		(width 0.0889)
		(layer "In4.Cu")
		(net "PUMP_TACH_D")
	)
	(segment
		(start 183.070246 -0.146558)
		(end 182.651908 -0.564896)
		(width 0.0889)
		(layer "In4.Cu")
		(net "PUMP_TACH_D")
	)
	(segment
		(start 346.3036 -0.395986)
		(end 346.3036 2.69748)
		(width 0.0889)
		(layer "In4.Cu")
		(net "PUMP_TACH_D")
	)
	(segment
		(start 422.0464 -0.92075)
		(end 424.87215 -0.92075)
		(width 0.0889)
		(layer "In4.Cu")
		(net "PUMP_TACH_D")
	)
	(segment
		(start 383.160778 -1.347978)
		(end 384.4544 -2.6416)
		(width 0.0889)
		(layer "In4.Cu")
		(net "PUMP_TACH_D")
	)
	(segment
		(start 430.4284 -1.9558)
		(end 430.819052 -2.346452)
		(width 0.0889)
		(layer "In4.Cu")
		(net "PUMP_TACH_D")
	)
	(segment
		(start 183.070246 -0.084836)
		(end 183.070246 -0.146558)
		(width 0.0889)
		(layer "In4.Cu")
		(net "PUMP_TACH_D")
	)
	(segment
		(start 430.819052 -2.346452)
		(end 440.65825 -2.346452)
		(width 0.0889)
		(layer "In4.Cu")
		(net "PUMP_TACH_D")
	)
	(segment
		(start 364.722664 0.1524)
		(end 377.811284 0.1524)
		(width 0.0889)
		(layer "In4.Cu")
		(net "PUMP_TACH_D")
	)
	(segment
		(start 182.829708 1.987042)
		(end 183.0705 1.74625)
		(width 0.0889)
		(layer "In4.Cu")
		(net "PUMP_TACH_D")
	)
	(segment
		(start 181.631082 2.328418)
		(end 181.972458 1.987042)
		(width 0.0889)
		(layer "In4.Cu")
		(net "PUMP_TACH_D")
	)
	(segment
		(start 377.855734 0.19685)
		(end 379.81255 0.19685)
		(width 0.0889)
		(layer "In4.Cu")
		(net "PUMP_TACH_D")
	)
	(segment
		(start 183.0705 -0.084582)
		(end 183.070246 -0.084836)
		(width 0.0889)
		(layer "In4.Cu")
		(net "PUMP_TACH_D")
	)
	(segment
		(start 377.811284 0.1524)
		(end 377.855734 0.19685)
		(width 0.0889)
		(layer "In4.Cu")
		(net "PUMP_TACH_D")
	)
	(segment
		(start 353.0854 1.397)
		(end 356.1842 -1.7018)
		(width 0.0889)
		(layer "In4.Cu")
		(net "PUMP_TACH_D")
	)
	(segment
		(start 407.755598 -0.611378)
		(end 415.989008 -0.611378)
		(width 0.0889)
		(layer "In4.Cu")
		(net "PUMP_TACH_D")
	)
	(segment
		(start 415.989008 -0.611378)
		(end 417.537646 0.93726)
		(width 0.0889)
		(layer "In4.Cu")
		(net "PUMP_TACH_D")
	)
	(segment
		(start 381.357378 -1.347978)
		(end 383.160778 -1.347978)
		(width 0.0889)
		(layer "In4.Cu")
		(net "PUMP_TACH_D")
	)
	(segment
		(start 181.972458 1.987042)
		(end 182.829708 1.987042)
		(width 0.0889)
		(layer "In4.Cu")
		(net "PUMP_TACH_D")
	)
	(segment
		(start 400.3294 -2.413)
		(end 400.576542 -2.165858)
		(width 0.0889)
		(layer "In4.Cu")
		(net "PUMP_TACH_D")
	)
	(segment
		(start 406.690576 -1.6764)
		(end 407.755598 -0.611378)
		(width 0.0889)
		(layer "In4.Cu")
		(net "PUMP_TACH_D")
	)
	(segment
		(start 324.8406 3.7592)
		(end 323.49567 5.10413)
		(width 0.0889)
		(layer "In4.Cu")
		(net "PUMP_TACH_D")
	)
	(segment
		(start 353.0854 1.894078)
		(end 353.0854 1.397)
		(width 0.0889)
		(layer "In4.Cu")
		(net "PUMP_TACH_D")
	)
	(segment
		(start 182.651908 -1.421892)
		(end 181.61 -2.4638)
		(width 0.0889)
		(layer "In4.Cu")
		(net "PUMP_TACH_D")
	)
	(segment
		(start 403.191218 -2.165858)
		(end 403.680676 -1.6764)
		(width 0.0889)
		(layer "In4.Cu")
		(net "PUMP_TACH_D")
	)
	(segment
		(start 388.6708 -2.6416)
		(end 388.8994 -2.413)
		(width 0.0889)
		(layer "In4.Cu")
		(net "PUMP_TACH_D")
	)
	(segment
		(start 348.297246 4.691126)
		(end 350.288352 4.691126)
		(width 0.0889)
		(layer "In4.Cu")
		(net "PUMP_TACH_D")
	)
	(segment
		(start 400.576542 -2.165858)
		(end 403.191218 -2.165858)
		(width 0.0889)
		(layer "In4.Cu")
		(net "PUMP_TACH_D")
	)
	(segment
		(start 424.87215 -0.92075)
		(end 425.9072 -1.9558)
		(width 0.0889)
		(layer "In4.Cu")
		(net "PUMP_TACH_D")
	)
	(segment
		(start 358.916986 -2.199386)
		(end 362.370878 -2.199386)
		(width 0.0889)
		(layer "In4.Cu")
		(net "PUMP_TACH_D")
	)
	(segment
		(start 13.555472 -22.674834)
		(end 11.686794 -20.806156)
		(width 0.0889)
		(layer "In11.Cu")
		(net "PUMP_TACH_D")
	)
	(segment
		(start 9.368282 -90.639646)
		(end 7.869936 -89.1413)
		(width 0.0889)
		(layer "In11.Cu")
		(net "PUMP_TACH_D")
	)
	(segment
		(start 18.099278 5.498338)
		(end 103.164132 5.498338)
		(width 0.0889)
		(layer "In11.Cu")
		(net "PUMP_TACH_D")
	)
	(segment
		(start 10.290048 -118.679976)
		(end 12.127484 -116.84254)
		(width 0.0889)
		(layer "In11.Cu")
		(net "PUMP_TACH_D")
	)
	(segment
		(start 7.869936 -89.1413)
		(end -1.079246 -89.1413)
		(width 0.0889)
		(layer "In11.Cu")
		(net "PUMP_TACH_D")
	)
	(segment
		(start -1.079246 -89.1413)
		(end -5.417058 -84.803488)
		(width 0.0889)
		(layer "In11.Cu")
		(net "PUMP_TACH_D")
	)
	(segment
		(start 13.405866 -0.843534)
		(end 13.957554 -0.291846)
		(width 0.0889)
		(layer "In11.Cu")
		(net "PUMP_TACH_D")
	)
	(segment
		(start 13.405866 -2.820924)
		(end 13.405866 -0.843534)
		(width 0.0889)
		(layer "In11.Cu")
		(net "PUMP_TACH_D")
	)
	(segment
		(start 166.375842 4.150106)
		(end 166.375842 0.448564)
		(width 0.0889)
		(layer "In11.Cu")
		(net "PUMP_TACH_D")
	)
	(segment
		(start 172.598588 -1.65608)
		(end 173.521624 -2.579116)
		(width 0.0889)
		(layer "In11.Cu")
		(net "PUMP_TACH_D")
	)
	(segment
		(start 15.630398 2.135632)
		(end 16.53159 2.135632)
		(width 0.0889)
		(layer "In11.Cu")
		(net "PUMP_TACH_D")
	)
	(segment
		(start 118.115842 5.433568)
		(end 165.09238 5.433568)
		(width 0.0889)
		(layer "In11.Cu")
		(net "PUMP_TACH_D")
	)
	(segment
		(start 11.686794 -4.539996)
		(end 13.405866 -2.820924)
		(width 0.0889)
		(layer "In11.Cu")
		(net "PUMP_TACH_D")
	)
	(segment
		(start 8.19404 -108.619798)
		(end 8.19404 -105.800398)
		(width 0.0889)
		(layer "In11.Cu")
		(net "PUMP_TACH_D")
	)
	(segment
		(start 103.164132 5.498338)
		(end 103.84028 4.82219)
		(width 0.0889)
		(layer "In11.Cu")
		(net "PUMP_TACH_D")
	)
	(segment
		(start 166.375842 0.448564)
		(end 168.480486 -1.65608)
		(width 0.0889)
		(layer "In11.Cu")
		(net "PUMP_TACH_D")
	)
	(segment
		(start -5.417058 -84.803488)
		(end -5.417058 -45.186092)
		(width 0.0889)
		(layer "In11.Cu")
		(net "PUMP_TACH_D")
	)
	(segment
		(start 9.334754 -42.7355)
		(end 10.606278 -41.463976)
		(width 0.0889)
		(layer "In11.Cu")
		(net "PUMP_TACH_D")
	)
	(segment
		(start 165.09238 5.433568)
		(end 166.375842 4.150106)
		(width 0.0889)
		(layer "In11.Cu")
		(net "PUMP_TACH_D")
	)
	(segment
		(start 12.127484 -112.553242)
		(end 8.19404 -108.619798)
		(width 0.0889)
		(layer "In11.Cu")
		(net "PUMP_TACH_D")
	)
	(segment
		(start 17.508474 3.112516)
		(end 17.508474 4.907534)
		(width 0.0889)
		(layer "In11.Cu")
		(net "PUMP_TACH_D")
	)
	(segment
		(start 11.686794 -20.806156)
		(end 11.686794 -4.539996)
		(width 0.0889)
		(layer "In11.Cu")
		(net "PUMP_TACH_D")
	)
	(segment
		(start -2.966466 -42.7355)
		(end 9.334754 -42.7355)
		(width 0.0889)
		(layer "In11.Cu")
		(net "PUMP_TACH_D")
	)
	(segment
		(start 17.508474 4.907534)
		(end 18.099278 5.498338)
		(width 0.0889)
		(layer "In11.Cu")
		(net "PUMP_TACH_D")
	)
	(segment
		(start 178.738784 -2.579116)
		(end 179.1335 -2.1844)
		(width 0.0889)
		(layer "In11.Cu")
		(net "PUMP_TACH_D")
	)
	(segment
		(start 12.127484 -116.84254)
		(end 12.127484 -112.553242)
		(width 0.0889)
		(layer "In11.Cu")
		(net "PUMP_TACH_D")
	)
	(segment
		(start 168.480486 -1.65608)
		(end 172.598588 -1.65608)
		(width 0.0889)
		(layer "In11.Cu")
		(net "PUMP_TACH_D")
	)
	(segment
		(start 173.521624 -2.579116)
		(end 178.738784 -2.579116)
		(width 0.0889)
		(layer "In11.Cu")
		(net "PUMP_TACH_D")
	)
	(segment
		(start 8.19404 -105.800398)
		(end 9.368282 -104.626156)
		(width 0.0889)
		(layer "In11.Cu")
		(net "PUMP_TACH_D")
	)
	(segment
		(start 13.555472 -35.997134)
		(end 13.555472 -22.674834)
		(width 0.0889)
		(layer "In11.Cu")
		(net "PUMP_TACH_D")
	)
	(segment
		(start -5.417058 -45.186092)
		(end -2.966466 -42.7355)
		(width 0.0889)
		(layer "In11.Cu")
		(net "PUMP_TACH_D")
	)
	(segment
		(start 9.368282 -104.626156)
		(end 9.368282 -90.639646)
		(width 0.0889)
		(layer "In11.Cu")
		(net "PUMP_TACH_D")
	)
	(segment
		(start 13.957554 0.462788)
		(end 15.630398 2.135632)
		(width 0.0889)
		(layer "In11.Cu")
		(net "PUMP_TACH_D")
	)
	(segment
		(start 13.957554 -0.291846)
		(end 13.957554 0.462788)
		(width 0.0889)
		(layer "In11.Cu")
		(net "PUMP_TACH_D")
	)
	(segment
		(start 10.606278 -38.946328)
		(end 13.555472 -35.997134)
		(width 0.0889)
		(layer "In11.Cu")
		(net "PUMP_TACH_D")
	)
	(segment
		(start 117.504464 4.82219)
		(end 118.115842 5.433568)
		(width 0.0889)
		(layer "In11.Cu")
		(net "PUMP_TACH_D")
	)
	(segment
		(start 10.606278 -41.463976)
		(end 10.606278 -38.946328)
		(width 0.0889)
		(layer "In11.Cu")
		(net "PUMP_TACH_D")
	)
	(segment
		(start 16.53159 2.135632)
		(end 17.508474 3.112516)
		(width 0.0889)
		(layer "In11.Cu")
		(net "PUMP_TACH_D")
	)
	(segment
		(start 103.84028 4.82219)
		(end 117.504464 4.82219)
		(width 0.0889)
		(layer "In11.Cu")
		(net "PUMP_TACH_D")
	)
	(segment
		(start 428.997618 -22.851618)
		(end 428.252382 -22.851618)
		(width 0.10795)
		(layer "F.Cu")
		(net "PUMP_PWM_OUT_R")
	)
	(segment
		(start 430.95037 -20.40763)
		(end 430.403 -20.955)
		(width 0.10795)
		(layer "F.Cu")
		(net "PUMP_PWM_OUT_R")
	)
	(segment
		(start 429.006 -22.86)
		(end 429.006 -22.431756)
		(width 0.10795)
		(layer "F.Cu")
		(net "PUMP_PWM_OUT_R")
	)
	(segment
		(start 430.403 -20.955)
		(end 429.895 -20.955)
		(width 0.10795)
		(layer "F.Cu")
		(net "PUMP_PWM_OUT_R")
	)
	(segment
		(start 429.006 -20.955)
		(end 429.895 -20.955)
		(width 0.10795)
		(layer "F.Cu")
		(net "PUMP_PWM_OUT_R")
	)
	(segment
		(start 428.608998 -22.034754)
		(end 428.608998 -21.352002)
		(width 0.10795)
		(layer "F.Cu")
		(net "PUMP_PWM_OUT_R")
	)
	(segment
		(start 430.95037 -19.809714)
		(end 430.95037 -20.40763)
		(width 0.10795)
		(layer "F.Cu")
		(net "PUMP_PWM_OUT_R")
	)
	(segment
		(start 428.608998 -21.352002)
		(end 429.006 -20.955)
		(width 0.10795)
		(layer "F.Cu")
		(net "PUMP_PWM_OUT_R")
	)
	(segment
		(start 429.006 -22.86)
		(end 428.997618 -22.851618)
		(width 0.10795)
		(layer "F.Cu")
		(net "PUMP_PWM_OUT_R")
	)
	(segment
		(start 428.252382 -22.851618)
		(end 428.244 -22.86)
		(width 0.10795)
		(layer "F.Cu")
		(net "PUMP_PWM_OUT_R")
	)
	(segment
		(start 429.006 -22.431756)
		(end 428.608998 -22.034754)
		(width 0.10795)
		(layer "F.Cu")
		(net "PUMP_PWM_OUT_R")
	)
	(via
		(at 425.069 4.2799)
		(size 0.508)
		(drill 0.254)
		(layers "F.Cu" "B.Cu")
		(net "PUMP_PWM_OUT_R")
	)
	(via
		(at 430.95037 -19.809714)
		(size 0.508)
		(drill 0.254)
		(layers "F.Cu" "B.Cu")
		(net "PUMP_PWM_OUT_R")
	)
	(via
		(at 380.15164 2.604008)
		(size 0.508)
		(drill 0.254)
		(layers "F.Cu" "B.Cu")
		(net "PUMP_PWM_OUT_R")
	)
	(via
		(at 427.53534 2.70002)
		(size 0.6604)
		(drill 0.3302)
		(layers "F.Cu" "B.Cu")
		(net "PUMP_PWM_OUT_R")
	)
	(via
		(at 180.5432 -1.8034)
		(size 0.508)
		(drill 0.254)
		(layers "F.Cu" "B.Cu")
		(net "PUMP_PWM_OUT_R")
	)
	(via
		(at 447.515488 1.83388)
		(size 0.508)
		(drill 0.254)
		(layers "F.Cu" "B.Cu")
		(net "PUMP_PWM_OUT_R")
	)
	(segment
		(start 426.64888 2.70002)
		(end 427.53534 2.70002)
		(width 0.10795)
		(layer "B.Cu")
		(net "PUMP_PWM_OUT_R")
	)
	(segment
		(start 429.34382 2.70002)
		(end 431.746152 5.102352)
		(width 0.10795)
		(layer "B.Cu")
		(net "PUMP_PWM_OUT_R")
	)
	(segment
		(start 427.53534 2.70002)
		(end 429.34382 2.70002)
		(width 0.10795)
		(layer "B.Cu")
		(net "PUMP_PWM_OUT_R")
	)
	(segment
		(start 447.515488 4.312412)
		(end 447.515488 1.83388)
		(width 0.10795)
		(layer "B.Cu")
		(net "PUMP_PWM_OUT_R")
	)
	(segment
		(start 431.746152 5.102352)
		(end 446.725548 5.102352)
		(width 0.10795)
		(layer "B.Cu")
		(net "PUMP_PWM_OUT_R")
	)
	(segment
		(start 425.069 4.2799)
		(end 426.64888 2.70002)
		(width 0.10795)
		(layer "B.Cu")
		(net "PUMP_PWM_OUT_R")
	)
	(segment
		(start 446.725548 5.102352)
		(end 447.515488 4.312412)
		(width 0.10795)
		(layer "B.Cu")
		(net "PUMP_PWM_OUT_R")
	)
	(segment
		(start 326.162162 -0.62865)
		(end 322.927726 2.605786)
		(width 0.089408)
		(layer "In9.Cu")
		(net "PUMP_PWM_OUT_R")
	)
	(segment
		(start 449.390008 -21.8694)
		(end 453.75068 -17.508728)
		(width 0.089408)
		(layer "In9.Cu")
		(net "PUMP_PWM_OUT_R")
	)
	(segment
		(start 441.375546 -21.833078)
		(end 444.561976 -21.833078)
		(width 0.089408)
		(layer "In9.Cu")
		(net "PUMP_PWM_OUT_R")
	)
	(segment
		(start 440.887866 -21.345398)
		(end 441.375546 -21.833078)
		(width 0.089408)
		(layer "In9.Cu")
		(net "PUMP_PWM_OUT_R")
	)
	(segment
		(start 355.185472 -21.659088)
		(end 354.838254 -22.006306)
		(width 0.089408)
		(layer "In9.Cu")
		(net "PUMP_PWM_OUT_R")
	)
	(segment
		(start 360.377486 -9.829546)
		(end 359.103168 -11.103864)
		(width 0.089408)
		(layer "In9.Cu")
		(net "PUMP_PWM_OUT_R")
	)
	(segment
		(start 451.193154 0.277114)
		(end 448.933316 0.277114)
		(width 0.089408)
		(layer "In9.Cu")
		(net "PUMP_PWM_OUT_R")
	)
	(segment
		(start 350.901 -20.490688)
		(end 350.901 -19.412966)
		(width 0.089408)
		(layer "In9.Cu")
		(net "PUMP_PWM_OUT_R")
	)
	(segment
		(start 359.34904 -19.021552)
		(end 359.321354 -19.049238)
		(width 0.089408)
		(layer "In9.Cu")
		(net "PUMP_PWM_OUT_R")
	)
	(segment
		(start 458.726286 -11.08075)
		(end 458.726286 -8.138414)
		(width 0.089408)
		(layer "In9.Cu")
		(net "PUMP_PWM_OUT_R")
	)
	(segment
		(start 434.312314 -19.755866)
		(end 434.846984 -19.755866)
		(width 0.089408)
		(layer "In9.Cu")
		(net "PUMP_PWM_OUT_R")
	)
	(segment
		(start 186.84367 4.55168)
		(end 183.993536 4.55168)
		(width 0.089408)
		(layer "In9.Cu")
		(net "PUMP_PWM_OUT_R")
	)
	(segment
		(start 455.695812 -1.396238)
		(end 452.866506 -1.396238)
		(width 0.089408)
		(layer "In9.Cu")
		(net "PUMP_PWM_OUT_R")
	)
	(segment
		(start 456.334368 -12.0142)
		(end 457.792836 -12.0142)
		(width 0.089408)
		(layer "In9.Cu")
		(net "PUMP_PWM_OUT_R")
	)
	(segment
		(start 362.582206 -7.267194)
		(end 362.582206 -9.316466)
		(width 0.089408)
		(layer "In9.Cu")
		(net "PUMP_PWM_OUT_R")
	)
	(segment
		(start 430.95037 -19.809714)
		(end 431.091086 -19.809714)
		(width 0.089408)
		(layer "In9.Cu")
		(net "PUMP_PWM_OUT_R")
	)
	(segment
		(start 377.7488 0.94742)
		(end 372.82501 -3.97637)
		(width 0.089408)
		(layer "In9.Cu")
		(net "PUMP_PWM_OUT_R")
	)
	(segment
		(start 447.515488 1.694942)
		(end 447.515488 1.83388)
		(width 0.089408)
		(layer "In9.Cu")
		(net "PUMP_PWM_OUT_R")
	)
	(segment
		(start 360.67365 -9.829546)
		(end 360.377486 -9.829546)
		(width 0.089408)
		(layer "In9.Cu")
		(net "PUMP_PWM_OUT_R")
	)
	(segment
		(start 452.866506 -1.396238)
		(end 451.193154 0.277114)
		(width 0.089408)
		(layer "In9.Cu")
		(net "PUMP_PWM_OUT_R")
	)
	(segment
		(start 183.400954 3.536188)
		(end 183.616092 3.32105)
		(width 0.089408)
		(layer "In9.Cu")
		(net "PUMP_PWM_OUT_R")
	)
	(segment
		(start 431.624232 -19.276568)
		(end 433.833016 -19.276568)
		(width 0.089408)
		(layer "In9.Cu")
		(net "PUMP_PWM_OUT_R")
	)
	(segment
		(start 358.263444 -21.659088)
		(end 355.185472 -21.659088)
		(width 0.089408)
		(layer "In9.Cu")
		(net "PUMP_PWM_OUT_R")
	)
	(segment
		(start 322.927726 2.605786)
		(end 322.927726 3.11912)
		(width 0.089408)
		(layer "In9.Cu")
		(net "PUMP_PWM_OUT_R")
	)
	(segment
		(start 380.15164 2.604008)
		(end 380.137924 2.604008)
		(width 0.089408)
		(layer "In9.Cu")
		(net "PUMP_PWM_OUT_R")
	)
	(segment
		(start 447.11239 -20.897342)
		(end 448.084448 -21.8694)
		(width 0.089408)
		(layer "In9.Cu")
		(net "PUMP_PWM_OUT_R")
	)
	(segment
		(start 457.792836 -12.0142)
		(end 458.726286 -11.08075)
		(width 0.089408)
		(layer "In9.Cu")
		(net "PUMP_PWM_OUT_R")
	)
	(segment
		(start 448.933316 0.277114)
		(end 447.515488 1.694942)
		(width 0.089408)
		(layer "In9.Cu")
		(net "PUMP_PWM_OUT_R")
	)
	(segment
		(start 360.004614 -13.802614)
		(end 360.004614 -18.3642)
		(width 0.089408)
		(layer "In9.Cu")
		(net "PUMP_PWM_OUT_R")
	)
	(segment
		(start 454.71334 -13.635228)
		(end 456.334368 -12.0142)
		(width 0.089408)
		(layer "In9.Cu")
		(net "PUMP_PWM_OUT_R")
	)
	(segment
		(start 453.75068 -16.74114)
		(end 454.71334 -15.77848)
		(width 0.089408)
		(layer "In9.Cu")
		(net "PUMP_PWM_OUT_R")
	)
	(segment
		(start 336.943192 -7.604252)
		(end 335.34858 -6.00964)
		(width 0.089408)
		(layer "In9.Cu")
		(net "PUMP_PWM_OUT_R")
	)
	(segment
		(start 321.629278 4.417568)
		(end 186.977782 4.417568)
		(width 0.089408)
		(layer "In9.Cu")
		(net "PUMP_PWM_OUT_R")
	)
	(segment
		(start 438.196736 -21.345398)
		(end 440.887866 -21.345398)
		(width 0.089408)
		(layer "In9.Cu")
		(net "PUMP_PWM_OUT_R")
	)
	(segment
		(start 183.616092 0.526796)
		(end 183.030368 -0.058928)
		(width 0.089408)
		(layer "In9.Cu")
		(net "PUMP_PWM_OUT_R")
	)
	(segment
		(start 360.004614 -18.3642)
		(end 359.34904 -19.019774)
		(width 0.089408)
		(layer "In9.Cu")
		(net "PUMP_PWM_OUT_R")
	)
	(segment
		(start 360.673904 -9.8298)
		(end 360.67365 -9.829546)
		(width 0.089408)
		(layer "In9.Cu")
		(net "PUMP_PWM_OUT_R")
	)
	(segment
		(start 350.901 -19.412966)
		(end 349.320612 -17.832578)
		(width 0.089408)
		(layer "In9.Cu")
		(net "PUMP_PWM_OUT_R")
	)
	(segment
		(start 335.34858 -6.00964)
		(end 331.361796 -6.00964)
		(width 0.089408)
		(layer "In9.Cu")
		(net "PUMP_PWM_OUT_R")
	)
	(segment
		(start 359.34904 -19.019774)
		(end 359.34904 -19.021552)
		(width 0.089408)
		(layer "In9.Cu")
		(net "PUMP_PWM_OUT_R")
	)
	(segment
		(start 343.337642 -12.71778)
		(end 338.224114 -7.604252)
		(width 0.089408)
		(layer "In9.Cu")
		(net "PUMP_PWM_OUT_R")
	)
	(segment
		(start 458.726286 -8.138414)
		(end 457.454 -6.866128)
		(width 0.089408)
		(layer "In9.Cu")
		(net "PUMP_PWM_OUT_R")
	)
	(segment
		(start 329.657202 -4.305046)
		(end 329.657202 -2.228342)
		(width 0.089408)
		(layer "In9.Cu")
		(net "PUMP_PWM_OUT_R")
	)
	(segment
		(start 380.1364 2.5908)
		(end 378.6124 2.5908)
		(width 0.089408)
		(layer "In9.Cu")
		(net "PUMP_PWM_OUT_R")
	)
	(segment
		(start 377.7488 1.7272)
		(end 377.7488 0.94742)
		(width 0.089408)
		(layer "In9.Cu")
		(net "PUMP_PWM_OUT_R")
	)
	(segment
		(start 180.67274 -0.48514)
		(end 180.67274 -1.67386)
		(width 0.089408)
		(layer "In9.Cu")
		(net "PUMP_PWM_OUT_R")
	)
	(segment
		(start 380.137924 2.604008)
		(end 380.137924 2.592324)
		(width 0.089408)
		(layer "In9.Cu")
		(net "PUMP_PWM_OUT_R")
	)
	(segment
		(start 433.833016 -19.276568)
		(end 434.312314 -19.755866)
		(width 0.089408)
		(layer "In9.Cu")
		(net "PUMP_PWM_OUT_R")
	)
	(segment
		(start 365.87303 -3.97637)
		(end 362.582206 -7.267194)
		(width 0.089408)
		(layer "In9.Cu")
		(net "PUMP_PWM_OUT_R")
	)
	(segment
		(start 331.361796 -6.00964)
		(end 329.657202 -4.305046)
		(width 0.089408)
		(layer "In9.Cu")
		(net "PUMP_PWM_OUT_R")
	)
	(segment
		(start 378.6124 2.5908)
		(end 377.7488 1.7272)
		(width 0.089408)
		(layer "In9.Cu")
		(net "PUMP_PWM_OUT_R")
	)
	(segment
		(start 329.657202 -2.228342)
		(end 328.05751 -0.62865)
		(width 0.089408)
		(layer "In9.Cu")
		(net "PUMP_PWM_OUT_R")
	)
	(segment
		(start 434.846984 -19.755866)
		(end 435.798722 -20.707604)
		(width 0.089408)
		(layer "In9.Cu")
		(net "PUMP_PWM_OUT_R")
	)
	(segment
		(start 431.091086 -19.809714)
		(end 431.624232 -19.276568)
		(width 0.089408)
		(layer "In9.Cu")
		(net "PUMP_PWM_OUT_R")
	)
	(segment
		(start 352.416618 -22.006306)
		(end 350.901 -20.490688)
		(width 0.089408)
		(layer "In9.Cu")
		(net "PUMP_PWM_OUT_R")
	)
	(segment
		(start 338.224114 -7.604252)
		(end 336.943192 -7.604252)
		(width 0.089408)
		(layer "In9.Cu")
		(net "PUMP_PWM_OUT_R")
	)
	(segment
		(start 328.05751 -0.62865)
		(end 326.162162 -0.62865)
		(width 0.089408)
		(layer "In9.Cu")
		(net "PUMP_PWM_OUT_R")
	)
	(segment
		(start 362.582206 -9.316466)
		(end 362.068872 -9.8298)
		(width 0.089408)
		(layer "In9.Cu")
		(net "PUMP_PWM_OUT_R")
	)
	(segment
		(start 349.320612 -17.832578)
		(end 349.320612 -15.403068)
		(width 0.089408)
		(layer "In9.Cu")
		(net "PUMP_PWM_OUT_R")
	)
	(segment
		(start 354.838254 -22.006306)
		(end 352.416618 -22.006306)
		(width 0.089408)
		(layer "In9.Cu")
		(net "PUMP_PWM_OUT_R")
	)
	(segment
		(start 457.454 -6.866128)
		(end 457.454 -4.456684)
		(width 0.089408)
		(layer "In9.Cu")
		(net "PUMP_PWM_OUT_R")
	)
	(segment
		(start 180.67274 -1.67386)
		(end 180.5432 -1.8034)
		(width 0.089408)
		(layer "In9.Cu")
		(net "PUMP_PWM_OUT_R")
	)
	(segment
		(start 435.798722 -20.707604)
		(end 437.558942 -20.707604)
		(width 0.089408)
		(layer "In9.Cu")
		(net "PUMP_PWM_OUT_R")
	)
	(segment
		(start 359.321354 -20.601178)
		(end 358.263444 -21.659088)
		(width 0.089408)
		(layer "In9.Cu")
		(net "PUMP_PWM_OUT_R")
	)
	(segment
		(start 456.4126 -2.113026)
		(end 455.695812 -1.396238)
		(width 0.089408)
		(layer "In9.Cu")
		(net "PUMP_PWM_OUT_R")
	)
	(segment
		(start 454.71334 -15.77848)
		(end 454.71334 -13.635228)
		(width 0.089408)
		(layer "In9.Cu")
		(net "PUMP_PWM_OUT_R")
	)
	(segment
		(start 445.497712 -20.897342)
		(end 447.11239 -20.897342)
		(width 0.089408)
		(layer "In9.Cu")
		(net "PUMP_PWM_OUT_R")
	)
	(segment
		(start 359.321354 -19.049238)
		(end 359.321354 -20.601178)
		(width 0.089408)
		(layer "In9.Cu")
		(net "PUMP_PWM_OUT_R")
	)
	(segment
		(start 448.084448 -21.8694)
		(end 449.390008 -21.8694)
		(width 0.089408)
		(layer "In9.Cu")
		(net "PUMP_PWM_OUT_R")
	)
	(segment
		(start 186.977782 4.417568)
		(end 186.84367 4.55168)
		(width 0.089408)
		(layer "In9.Cu")
		(net "PUMP_PWM_OUT_R")
	)
	(segment
		(start 444.561976 -21.833078)
		(end 445.497712 -20.897342)
		(width 0.089408)
		(layer "In9.Cu")
		(net "PUMP_PWM_OUT_R")
	)
	(segment
		(start 372.82501 -3.97637)
		(end 365.87303 -3.97637)
		(width 0.089408)
		(layer "In9.Cu")
		(net "PUMP_PWM_OUT_R")
	)
	(segment
		(start 349.320612 -15.403068)
		(end 346.635324 -12.71778)
		(width 0.089408)
		(layer "In9.Cu")
		(net "PUMP_PWM_OUT_R")
	)
	(segment
		(start 183.400954 3.959098)
		(end 183.400954 3.536188)
		(width 0.089408)
		(layer "In9.Cu")
		(net "PUMP_PWM_OUT_R")
	)
	(segment
		(start 456.4126 -3.415284)
		(end 456.4126 -2.113026)
		(width 0.089408)
		(layer "In9.Cu")
		(net "PUMP_PWM_OUT_R")
	)
	(segment
		(start 346.635324 -12.71778)
		(end 343.337642 -12.71778)
		(width 0.089408)
		(layer "In9.Cu")
		(net "PUMP_PWM_OUT_R")
	)
	(segment
		(start 322.927726 3.11912)
		(end 321.629278 4.417568)
		(width 0.089408)
		(layer "In9.Cu")
		(net "PUMP_PWM_OUT_R")
	)
	(segment
		(start 380.137924 2.592324)
		(end 380.1364 2.592324)
		(width 0.089408)
		(layer "In9.Cu")
		(net "PUMP_PWM_OUT_R")
	)
	(segment
		(start 359.103168 -11.103864)
		(end 359.103168 -12.901168)
		(width 0.089408)
		(layer "In9.Cu")
		(net "PUMP_PWM_OUT_R")
	)
	(segment
		(start 183.993536 4.55168)
		(end 183.400954 3.959098)
		(width 0.089408)
		(layer "In9.Cu")
		(net "PUMP_PWM_OUT_R")
	)
	(segment
		(start 359.103168 -12.901168)
		(end 360.004614 -13.802614)
		(width 0.089408)
		(layer "In9.Cu")
		(net "PUMP_PWM_OUT_R")
	)
	(segment
		(start 380.1364 2.592324)
		(end 380.1364 2.5908)
		(width 0.089408)
		(layer "In9.Cu")
		(net "PUMP_PWM_OUT_R")
	)
	(segment
		(start 457.454 -4.456684)
		(end 456.4126 -3.415284)
		(width 0.089408)
		(layer "In9.Cu")
		(net "PUMP_PWM_OUT_R")
	)
	(segment
		(start 181.098952 -0.058928)
		(end 180.67274 -0.48514)
		(width 0.089408)
		(layer "In9.Cu")
		(net "PUMP_PWM_OUT_R")
	)
	(segment
		(start 437.558942 -20.707604)
		(end 438.196736 -21.345398)
		(width 0.089408)
		(layer "In9.Cu")
		(net "PUMP_PWM_OUT_R")
	)
	(segment
		(start 453.75068 -17.508728)
		(end 453.75068 -16.74114)
		(width 0.089408)
		(layer "In9.Cu")
		(net "PUMP_PWM_OUT_R")
	)
	(segment
		(start 362.068872 -9.8298)
		(end 360.673904 -9.8298)
		(width 0.089408)
		(layer "In9.Cu")
		(net "PUMP_PWM_OUT_R")
	)
	(segment
		(start 183.616092 3.32105)
		(end 183.616092 0.526796)
		(width 0.089408)
		(layer "In9.Cu")
		(net "PUMP_PWM_OUT_R")
	)
	(segment
		(start 183.030368 -0.058928)
		(end 181.098952 -0.058928)
		(width 0.089408)
		(layer "In9.Cu")
		(net "PUMP_PWM_OUT_R")
	)
	(segment
		(start 8.796274 -119.726202)
		(end 10.700512 -119.726202)
		(width 0.089408)
		(layer "In11.Cu")
		(net "PUMP_PWM_OUT_R")
	)
	(segment
		(start 392.397488 0.8255)
		(end 398.4625 0.8255)
		(width 0.089408)
		(layer "In11.Cu")
		(net "PUMP_PWM_OUT_R")
	)
	(segment
		(start 13.949426 -22.511512)
		(end 12.080748 -20.642834)
		(width 0.089408)
		(layer "In11.Cu")
		(net "PUMP_PWM_OUT_R")
	)
	(segment
		(start 382.9304 2.7686)
		(end 384.87096 0.82804)
		(width 0.089408)
		(layer "In11.Cu")
		(net "PUMP_PWM_OUT_R")
	)
	(segment
		(start 13.79982 -1.16205)
		(end 14.2494 -0.71247)
		(width 0.089408)
		(layer "In11.Cu")
		(net "PUMP_PWM_OUT_R")
	)
	(segment
		(start 7.957312 -88.6714)
		(end -0.99187 -88.6714)
		(width 0.089408)
		(layer "In11.Cu")
		(net "PUMP_PWM_OUT_R")
	)
	(segment
		(start 164.929058 5.039614)
		(end 165.981888 3.986784)
		(width 0.089408)
		(layer "In11.Cu")
		(net "PUMP_PWM_OUT_R")
	)
	(segment
		(start -5.023104 -66.53911)
		(end -5.023104 -62.65291)
		(width 0.0889)
		(layer "In11.Cu")
		(net "PUMP_PWM_OUT_R")
	)
	(segment
		(start 10.304526 -43.129454)
		(end 13.949426 -39.484554)
		(width 0.089408)
		(layer "In11.Cu")
		(net "PUMP_PWM_OUT_R")
	)
	(segment
		(start -5.023104 -84.640166)
		(end -5.023104 -67.087496)
		(width 0.0889)
		(layer "In11.Cu")
		(net "PUMP_PWM_OUT_R")
	)
	(segment
		(start 11.708892 -118.349014)
		(end 12.5984 -117.459506)
		(width 0.089408)
		(layer "In11.Cu")
		(net "PUMP_PWM_OUT_R")
	)
	(segment
		(start 384.87096 0.82804)
		(end 392.394948 0.82804)
		(width 0.089408)
		(layer "In11.Cu")
		(net "PUMP_PWM_OUT_R")
	)
	(segment
		(start 392.394948 0.82804)
		(end 392.397488 0.8255)
		(width 0.089408)
		(layer "In11.Cu")
		(net "PUMP_PWM_OUT_R")
	)
	(segment
		(start 13.79982 -2.984246)
		(end 13.79982 -1.16205)
		(width 0.089408)
		(layer "In11.Cu")
		(net "PUMP_PWM_OUT_R")
	)
	(segment
		(start 168.50233 -2.050034)
		(end 168.502584 -2.050288)
		(width 0.089408)
		(layer "In11.Cu")
		(net "PUMP_PWM_OUT_R")
	)
	(segment
		(start 178.78552 -3.2512)
		(end 180.23332 -1.8034)
		(width 0.089408)
		(layer "In11.Cu")
		(net "PUMP_PWM_OUT_R")
	)
	(segment
		(start 165.981888 0.611886)
		(end 165.981634 0.611632)
		(width 0.089408)
		(layer "In11.Cu")
		(net "PUMP_PWM_OUT_R")
	)
	(segment
		(start -5.023104 -45.349414)
		(end -2.803144 -43.129454)
		(width 0.089408)
		(layer "In11.Cu")
		(net "PUMP_PWM_OUT_R")
	)
	(segment
		(start 380.15164 2.604008)
		(end 380.149608 2.604008)
		(width 0.089408)
		(layer "In11.Cu")
		(net "PUMP_PWM_OUT_R")
	)
	(segment
		(start 12.080748 -20.642834)
		(end 12.080748 -4.703318)
		(width 0.089408)
		(layer "In11.Cu")
		(net "PUMP_PWM_OUT_R")
	)
	(segment
		(start 411.0482 4.826)
		(end 424.5229 4.826)
		(width 0.089408)
		(layer "In11.Cu")
		(net "PUMP_PWM_OUT_R")
	)
	(segment
		(start 9.559036 -90.273124)
		(end 7.957312 -88.6714)
		(width 0.089408)
		(layer "In11.Cu")
		(net "PUMP_PWM_OUT_R")
	)
	(segment
		(start 12.080748 -4.703318)
		(end 13.79982 -2.984246)
		(width 0.089408)
		(layer "In11.Cu")
		(net "PUMP_PWM_OUT_R")
	)
	(segment
		(start 103.00081 5.104384)
		(end 103.676958 4.428236)
		(width 0.089408)
		(layer "In11.Cu")
		(net "PUMP_PWM_OUT_R")
	)
	(segment
		(start 168.317164 -2.050034)
		(end 168.50233 -2.050034)
		(width 0.089408)
		(layer "In11.Cu")
		(net "PUMP_PWM_OUT_R")
	)
	(segment
		(start 20.00885 5.104384)
		(end 103.00081 5.104384)
		(width 0.089408)
		(layer "In11.Cu")
		(net "PUMP_PWM_OUT_R")
	)
	(segment
		(start 12.5984 -117.459506)
		(end 12.5984 -112.362996)
		(width 0.089408)
		(layer "In11.Cu")
		(net "PUMP_PWM_OUT_R")
	)
	(segment
		(start 14.2494 -0.71247)
		(end 14.2494 0.197358)
		(width 0.089408)
		(layer "In11.Cu")
		(net "PUMP_PWM_OUT_R")
	)
	(segment
		(start 7.750048 -118.679976)
		(end 8.796274 -119.726202)
		(width 0.089408)
		(layer "In11.Cu")
		(net "PUMP_PWM_OUT_R")
	)
	(segment
		(start 172.288962 -2.050034)
		(end 173.490128 -3.2512)
		(width 0.089408)
		(layer "In11.Cu")
		(net "PUMP_PWM_OUT_R")
	)
	(segment
		(start 398.4625 0.8255)
		(end 400.788632 3.151632)
		(width 0.089408)
		(layer "In11.Cu")
		(net "PUMP_PWM_OUT_R")
	)
	(segment
		(start -5.023104 -62.65291)
		(end -5.023104 -45.349414)
		(width 0.089408)
		(layer "In11.Cu")
		(net "PUMP_PWM_OUT_R")
	)
	(segment
		(start 11.708892 -118.717822)
		(end 11.708892 -118.349014)
		(width 0.089408)
		(layer "In11.Cu")
		(net "PUMP_PWM_OUT_R")
	)
	(segment
		(start 12.5984 -112.362996)
		(end 8.587994 -108.35259)
		(width 0.089408)
		(layer "In11.Cu")
		(net "PUMP_PWM_OUT_R")
	)
	(segment
		(start 19.435064 4.29641)
		(end 19.435064 4.530598)
		(width 0.089408)
		(layer "In11.Cu")
		(net "PUMP_PWM_OUT_R")
	)
	(segment
		(start 400.788632 3.151632)
		(end 409.373832 3.151632)
		(width 0.089408)
		(layer "In11.Cu")
		(net "PUMP_PWM_OUT_R")
	)
	(segment
		(start 380.3142 2.7686)
		(end 382.9304 2.7686)
		(width 0.089408)
		(layer "In11.Cu")
		(net "PUMP_PWM_OUT_R")
	)
	(segment
		(start 8.587994 -105.96372)
		(end 9.559036 -104.992678)
		(width 0.089408)
		(layer "In11.Cu")
		(net "PUMP_PWM_OUT_R")
	)
	(segment
		(start 168.502584 -2.050288)
		(end 168.643554 -2.050288)
		(width 0.089408)
		(layer "In11.Cu")
		(net "PUMP_PWM_OUT_R")
	)
	(segment
		(start 103.676958 4.428236)
		(end 117.667786 4.428236)
		(width 0.089408)
		(layer "In11.Cu")
		(net "PUMP_PWM_OUT_R")
	)
	(segment
		(start 9.559036 -104.992678)
		(end 9.559036 -90.273124)
		(width 0.089408)
		(layer "In11.Cu")
		(net "PUMP_PWM_OUT_R")
	)
	(segment
		(start -5.023104 -67.087496)
		(end -5.023104 -66.53911)
		(width 0.089408)
		(layer "In11.Cu")
		(net "PUMP_PWM_OUT_R")
	)
	(segment
		(start 180.23332 -1.8034)
		(end 180.5432 -1.8034)
		(width 0.089408)
		(layer "In11.Cu")
		(net "PUMP_PWM_OUT_R")
	)
	(segment
		(start 165.981634 0.611632)
		(end 165.981634 0.285496)
		(width 0.089408)
		(layer "In11.Cu")
		(net "PUMP_PWM_OUT_R")
	)
	(segment
		(start 19.435064 4.530598)
		(end 20.00885 5.104384)
		(width 0.089408)
		(layer "In11.Cu")
		(net "PUMP_PWM_OUT_R")
	)
	(segment
		(start 168.643554 -2.050288)
		(end 168.643808 -2.050034)
		(width 0.089408)
		(layer "In11.Cu")
		(net "PUMP_PWM_OUT_R")
	)
	(segment
		(start -0.99187 -88.6714)
		(end -5.023104 -84.640166)
		(width 0.089408)
		(layer "In11.Cu")
		(net "PUMP_PWM_OUT_R")
	)
	(segment
		(start 168.643808 -2.050034)
		(end 172.288962 -2.050034)
		(width 0.089408)
		(layer "In11.Cu")
		(net "PUMP_PWM_OUT_R")
	)
	(segment
		(start 424.5229 4.826)
		(end 425.069 4.2799)
		(width 0.089408)
		(layer "In11.Cu")
		(net "PUMP_PWM_OUT_R")
	)
	(segment
		(start 409.373832 3.151632)
		(end 411.0482 4.826)
		(width 0.089408)
		(layer "In11.Cu")
		(net "PUMP_PWM_OUT_R")
	)
	(segment
		(start 13.949426 -39.484554)
		(end 13.949426 -22.511512)
		(width 0.089408)
		(layer "In11.Cu")
		(net "PUMP_PWM_OUT_R")
	)
	(segment
		(start 118.279164 5.039614)
		(end 164.929058 5.039614)
		(width 0.089408)
		(layer "In11.Cu")
		(net "PUMP_PWM_OUT_R")
	)
	(segment
		(start -2.803144 -43.129454)
		(end 10.304526 -43.129454)
		(width 0.089408)
		(layer "In11.Cu")
		(net "PUMP_PWM_OUT_R")
	)
	(segment
		(start 16.594836 1.456182)
		(end 19.435064 4.29641)
		(width 0.089408)
		(layer "In11.Cu")
		(net "PUMP_PWM_OUT_R")
	)
	(segment
		(start 8.587994 -108.35259)
		(end 8.587994 -105.96372)
		(width 0.089408)
		(layer "In11.Cu")
		(net "PUMP_PWM_OUT_R")
	)
	(segment
		(start 14.2494 0.197358)
		(end 15.508224 1.456182)
		(width 0.089408)
		(layer "In11.Cu")
		(net "PUMP_PWM_OUT_R")
	)
	(segment
		(start 380.149608 2.604008)
		(end 380.3142 2.7686)
		(width 0.089408)
		(layer "In11.Cu")
		(net "PUMP_PWM_OUT_R")
	)
	(segment
		(start 173.490128 -3.2512)
		(end 178.78552 -3.2512)
		(width 0.089408)
		(layer "In11.Cu")
		(net "PUMP_PWM_OUT_R")
	)
	(segment
		(start 15.508224 1.456182)
		(end 16.594836 1.456182)
		(width 0.089408)
		(layer "In11.Cu")
		(net "PUMP_PWM_OUT_R")
	)
	(segment
		(start 165.981888 3.986784)
		(end 165.981888 0.611886)
		(width 0.089408)
		(layer "In11.Cu")
		(net "PUMP_PWM_OUT_R")
	)
	(segment
		(start 165.981634 0.285496)
		(end 168.317164 -2.050034)
		(width 0.089408)
		(layer "In11.Cu")
		(net "PUMP_PWM_OUT_R")
	)
	(segment
		(start 117.667786 4.428236)
		(end 118.279164 5.039614)
		(width 0.089408)
		(layer "In11.Cu")
		(net "PUMP_PWM_OUT_R")
	)
	(segment
		(start 10.700512 -119.726202)
		(end 11.708892 -118.717822)
		(width 0.089408)
		(layer "In11.Cu")
		(net "PUMP_PWM_OUT_R")
	)
	(segment
		(start 430.5046 -22.586696)
		(end 430.5046 -21.509482)
		(width 0.10795)
		(layer "F.Cu")
		(net "PUMP_PWM_OUT_BUF")
	)
	(segment
		(start 431.785014 -20.229068)
		(end 431.785014 -19.727672)
		(width 0.10795)
		(layer "F.Cu")
		(net "PUMP_PWM_OUT_BUF")
	)
	(segment
		(start 430.5046 -21.509482)
		(end 431.785014 -20.229068)
		(width 0.10795)
		(layer "F.Cu")
		(net "PUMP_PWM_OUT_BUF")
	)
	(segment
		(start 430.231296 -22.86)
		(end 430.5046 -22.586696)
		(width 0.10795)
		(layer "F.Cu")
		(net "PUMP_PWM_OUT_BUF")
	)
	(segment
		(start 429.895 -22.86)
		(end 430.231296 -22.86)
		(width 0.10795)
		(layer "F.Cu")
		(net "PUMP_PWM_OUT_BUF")
	)
	(segment
		(start 423.985436 -26.963116)
		(end 423.67327 -26.963116)
		(width 0.10795)
		(layer "F.Cu")
		(net "PUMP_PWM_OUT")
	)
	(segment
		(start 431.632614 -22.921468)
		(end 430.782222 -22.921468)
		(width 0.10033)
		(layer "F.Cu")
		(net "PUMP_PWM_OUT")
	)
	(segment
		(start 426.5295 -25.625044)
		(end 426.086524 -25.625044)
		(width 0.089408)
		(layer "F.Cu")
		(net "PUMP_PWM_OUT")
	)
	(segment
		(start 428.92853 -23.30958)
		(end 428.136812 -24.101298)
		(width 0.10033)
		(layer "F.Cu")
		(net "PUMP_PWM_OUT")
	)
	(segment
		(start 423.67327 -26.963116)
		(end 423.478452 -27.157934)
		(width 0.10795)
		(layer "F.Cu")
		(net "PUMP_PWM_OUT")
	)
	(segment
		(start 430.39411 -23.30958)
		(end 428.92853 -23.30958)
		(width 0.10033)
		(layer "F.Cu")
		(net "PUMP_PWM_OUT")
	)
	(segment
		(start 432.435 -21.505672)
		(end 432.435 -22.119082)
		(width 0.10795)
		(layer "F.Cu")
		(net "PUMP_PWM_OUT")
	)
	(segment
		(start 425.86656 -26.509218)
		(end 425.696126 -26.679652)
		(width 0.10795)
		(layer "F.Cu")
		(net "PUMP_PWM_OUT")
	)
	(segment
		(start 428.136812 -24.101298)
		(end 428.136812 -24.434292)
		(width 0.10795)
		(layer "F.Cu")
		(net "PUMP_PWM_OUT")
	)
	(segment
		(start 432.435 -22.119082)
		(end 431.632614 -22.921468)
		(width 0.10033)
		(layer "F.Cu")
		(net "PUMP_PWM_OUT")
	)
	(segment
		(start 428.136812 -24.434292)
		(end 426.94606 -25.625044)
		(width 0.10795)
		(layer "F.Cu")
		(net "PUMP_PWM_OUT")
	)
	(segment
		(start 424.261788 -26.686764)
		(end 424.261788 -26.688542)
		(width 0.10795)
		(layer "F.Cu")
		(net "PUMP_PWM_OUT")
	)
	(segment
		(start 423.314368 -27.70632)
		(end 422.718484 -27.70632)
		(width 0.10795)
		(layer "F.Cu")
		(net "PUMP_PWM_OUT")
	)
	(segment
		(start 425.696126 -26.679652)
		(end 424.2689 -26.679652)
		(width 0.10795)
		(layer "F.Cu")
		(net "PUMP_PWM_OUT")
	)
	(segment
		(start 424.2689 -26.679652)
		(end 424.261788 -26.686764)
		(width 0.10795)
		(layer "F.Cu")
		(net "PUMP_PWM_OUT")
	)
	(segment
		(start 430.782222 -22.921468)
		(end 430.39411 -23.30958)
		(width 0.10033)
		(layer "F.Cu")
		(net "PUMP_PWM_OUT")
	)
	(segment
		(start 424.261788 -26.688542)
		(end 424.04411 -26.90622)
		(width 0.10795)
		(layer "F.Cu")
		(net "PUMP_PWM_OUT")
	)
	(segment
		(start 425.86656 -25.845008)
		(end 425.86656 -26.509218)
		(width 0.10795)
		(layer "F.Cu")
		(net "PUMP_PWM_OUT")
	)
	(segment
		(start 422.718484 -27.70632)
		(end 422.29024 -28.134564)
		(width 0.10795)
		(layer "F.Cu")
		(net "PUMP_PWM_OUT")
	)
	(segment
		(start 423.478452 -27.542236)
		(end 423.314368 -27.70632)
		(width 0.10795)
		(layer "F.Cu")
		(net "PUMP_PWM_OUT")
	)
	(segment
		(start 424.04411 -26.90622)
		(end 424.042332 -26.90622)
		(width 0.10795)
		(layer "F.Cu")
		(net "PUMP_PWM_OUT")
	)
	(segment
		(start 423.478452 -27.157934)
		(end 423.478452 -27.542236)
		(width 0.10795)
		(layer "F.Cu")
		(net "PUMP_PWM_OUT")
	)
	(segment
		(start 426.086524 -25.625044)
		(end 425.86656 -25.845008)
		(width 0.10795)
		(layer "F.Cu")
		(net "PUMP_PWM_OUT")
	)
	(segment
		(start 424.042332 -26.90622)
		(end 423.985436 -26.963116)
		(width 0.10795)
		(layer "F.Cu")
		(net "PUMP_PWM_OUT")
	)
	(segment
		(start 426.94606 -25.625044)
		(end 426.5295 -25.625044)
		(width 0.10795)
		(layer "F.Cu")
		(net "PUMP_PWM_OUT")
	)
	(via
		(at 428.136812 -24.101298)
		(size 0.762)
		(drill 0.381)
		(layers "F.Cu" "B.Cu")
		(net "PUMP_PWM_OUT")
	)
	(via
		(at 463.7024 -122.4534)
		(size 0.6604)
		(drill 0.3302)
		(layers "F.Cu" "B.Cu")
		(net "P5V_TPS2061")
	)
	(via
		(at 14.104112 -121.610628)
		(size 0.6604)
		(drill 0.3302)
		(layers "F.Cu" "B.Cu")
		(net "P12V_PUMP")
	)
	(via
		(at 469.4428 -129.667)
		(size 0.6604)
		(drill 0.3302)
		(layers "F.Cu" "B.Cu")
		(net "FM_USB_P0_EN_R_N")
	)
	(segment
		(start 415.601404 -52.0192)
		(end 415.671 -52.088796)
		(width 0.10795)
		(layer "F.Cu")
		(net "FM_OCP_MEZZC_PRES_N")
	)
	(segment
		(start 415.1249 -52.574952)
		(end 415.447734 -52.897786)
		(width 0.10795)
		(layer "F.Cu")
		(net "FM_OCP_MEZZC_PRES_N")
	)
	(segment
		(start 465.349844 -62.002924)
		(end 465.349844 -63.5)
		(width 0.10795)
		(layer "F.Cu")
		(net "FM_OCP_MEZZC_PRES_N")
	)
	(segment
		(start 465.350098 -62.00267)
		(end 465.349844 -62.002924)
		(width 0.10795)
		(layer "F.Cu")
		(net "FM_OCP_MEZZC_PRES_N")
	)
	(segment
		(start 415.1249 -52.0192)
		(end 415.1249 -52.574952)
		(width 0.10795)
		(layer "F.Cu")
		(net "FM_OCP_MEZZC_PRES_N")
	)
	(segment
		(start 465.349844 -63.5)
		(end 465.2518 -63.598044)
		(width 0.10795)
		(layer "F.Cu")
		(net "FM_OCP_MEZZC_PRES_N")
	)
	(segment
		(start 415.671 -52.088796)
		(end 416.402012 -52.088796)
		(width 0.10795)
		(layer "F.Cu")
		(net "FM_OCP_MEZZC_PRES_N")
	)
	(segment
		(start 415.1249 -52.0192)
		(end 415.601404 -52.0192)
		(width 0.10795)
		(layer "F.Cu")
		(net "FM_OCP_MEZZC_PRES_N")
	)
	(segment
		(start 465.2518 -63.598044)
		(end 465.2518 -64.077088)
		(width 0.10795)
		(layer "F.Cu")
		(net "FM_OCP_MEZZC_PRES_N")
	)
	(via
		(at 415.447734 -52.897786)
		(size 0.508)
		(drill 0.254)
		(layers "F.Cu" "B.Cu")
		(net "FM_OCP_MEZZC_PRES_N")
	)
	(via
		(at 465.2518 -64.077088)
		(size 0.508)
		(drill 0.254)
		(layers "F.Cu" "B.Cu")
		(net "FM_OCP_MEZZC_PRES_N")
	)
	(via
		(at 465.9376 -55.0926)
		(size 0.508)
		(drill 0.254)
		(layers "F.Cu" "B.Cu")
		(net "FM_OCP_MEZZC_PRES_N")
	)
	(segment
		(start 465.9376 -55.0926)
		(end 464.9978 -55.0926)
		(width 0.089408)
		(layer "In2.Cu")
		(net "FM_OCP_MEZZC_PRES_N")
	)
	(segment
		(start 464.26628 -54.36108)
		(end 436.601362 -54.36108)
		(width 0.089408)
		(layer "In2.Cu")
		(net "FM_OCP_MEZZC_PRES_N")
	)
	(segment
		(start 427.48835 -53.234844)
		(end 426.741082 -53.982112)
		(width 0.089408)
		(layer "In2.Cu")
		(net "FM_OCP_MEZZC_PRES_N")
	)
	(segment
		(start 415.816796 -52.528724)
		(end 415.447734 -52.897786)
		(width 0.089408)
		(layer "In2.Cu")
		(net "FM_OCP_MEZZC_PRES_N")
	)
	(segment
		(start 436.601362 -54.36108)
		(end 435.475126 -53.234844)
		(width 0.089408)
		(layer "In2.Cu")
		(net "FM_OCP_MEZZC_PRES_N")
	)
	(segment
		(start 420.445184 -52.19319)
		(end 420.10965 -52.528724)
		(width 0.089408)
		(layer "In2.Cu")
		(net "FM_OCP_MEZZC_PRES_N")
	)
	(segment
		(start 420.10965 -52.528724)
		(end 415.816796 -52.528724)
		(width 0.089408)
		(layer "In2.Cu")
		(net "FM_OCP_MEZZC_PRES_N")
	)
	(segment
		(start 422.795192 -52.19319)
		(end 420.445184 -52.19319)
		(width 0.089408)
		(layer "In2.Cu")
		(net "FM_OCP_MEZZC_PRES_N")
	)
	(segment
		(start 435.475126 -53.234844)
		(end 427.48835 -53.234844)
		(width 0.089408)
		(layer "In2.Cu")
		(net "FM_OCP_MEZZC_PRES_N")
	)
	(segment
		(start 426.741082 -53.982112)
		(end 424.584114 -53.982112)
		(width 0.089408)
		(layer "In2.Cu")
		(net "FM_OCP_MEZZC_PRES_N")
	)
	(segment
		(start 464.9978 -55.0926)
		(end 464.26628 -54.36108)
		(width 0.089408)
		(layer "In2.Cu")
		(net "FM_OCP_MEZZC_PRES_N")
	)
	(segment
		(start 424.584114 -53.982112)
		(end 422.795192 -52.19319)
		(width 0.089408)
		(layer "In2.Cu")
		(net "FM_OCP_MEZZC_PRES_N")
	)
	(segment
		(start 465.584286 -55.445914)
		(end 465.584286 -63.744602)
		(width 0.089408)
		(layer "In4.Cu")
		(net "FM_OCP_MEZZC_PRES_N")
	)
	(segment
		(start 465.584286 -63.744602)
		(end 465.2518 -64.077088)
		(width 0.089408)
		(layer "In4.Cu")
		(net "FM_OCP_MEZZC_PRES_N")
	)
	(segment
		(start 465.9376 -55.0926)
		(end 465.584286 -55.445914)
		(width 0.089408)
		(layer "In4.Cu")
		(net "FM_OCP_MEZZC_PRES_N")
	)
	(segment
		(start 422.545764 -54.104286)
		(end 421.792146 -54.857904)
		(width 0.10795)
		(layer "F.Cu")
		(net "FM_OCP_MEZZC_PRES_LVT3_BMC")
	)
	(segment
		(start 418.180012 -53.031644)
		(end 418.79393 -53.645562)
		(width 0.10795)
		(layer "F.Cu")
		(net "FM_OCP_MEZZC_PRES_LVT3_BMC")
	)
	(segment
		(start 419.052756 -53.645562)
		(end 419.435026 -54.027832)
		(width 0.10795)
		(layer "F.Cu")
		(net "FM_OCP_MEZZC_PRES_LVT3_BMC")
	)
	(segment
		(start 420.450264 -54.857904)
		(end 420.154862 -54.562502)
		(width 0.10795)
		(layer "F.Cu")
		(net "FM_OCP_MEZZC_PRES_LVT3_BMC")
	)
	(segment
		(start 412.690056 -40.13454)
		(end 412.290006 -40.53459)
		(width 0.10795)
		(layer "F.Cu")
		(net "FM_OCP_MEZZC_PRES_LVT3_BMC")
	)
	(segment
		(start 418.180012 -52.738782)
		(end 418.180012 -53.031644)
		(width 0.10795)
		(layer "F.Cu")
		(net "FM_OCP_MEZZC_PRES_LVT3_BMC")
	)
	(segment
		(start 421.792146 -54.857904)
		(end 420.450264 -54.857904)
		(width 0.10795)
		(layer "F.Cu")
		(net "FM_OCP_MEZZC_PRES_LVT3_BMC")
	)
	(segment
		(start 420.154862 -54.562502)
		(end 419.78453 -54.562502)
		(width 0.10795)
		(layer "F.Cu")
		(net "FM_OCP_MEZZC_PRES_LVT3_BMC")
	)
	(segment
		(start 419.78453 -54.562502)
		(end 419.435026 -54.212998)
		(width 0.10795)
		(layer "F.Cu")
		(net "FM_OCP_MEZZC_PRES_LVT3_BMC")
	)
	(segment
		(start 418.180012 -52.738782)
		(end 418.180012 -52.088796)
		(width 0.10795)
		(layer "F.Cu")
		(net "FM_OCP_MEZZC_PRES_LVT3_BMC")
	)
	(segment
		(start 419.435026 -54.212998)
		(end 419.435026 -54.027832)
		(width 0.10795)
		(layer "F.Cu")
		(net "FM_OCP_MEZZC_PRES_LVT3_BMC")
	)
	(segment
		(start 418.79393 -53.645562)
		(end 419.052756 -53.645562)
		(width 0.10795)
		(layer "F.Cu")
		(net "FM_OCP_MEZZC_PRES_LVT3_BMC")
	)
	(via
		(at 412.290006 -40.53459)
		(size 0.4572)
		(drill 0.2032)
		(layers "F.Cu" "B.Cu")
		(net "FM_OCP_MEZZC_PRES_LVT3_BMC")
	)
	(via
		(at 422.545764 -54.104286)
		(size 0.508)
		(drill 0.254)
		(layers "F.Cu" "B.Cu")
		(net "FM_OCP_MEZZC_PRES_LVT3_BMC")
	)
	(via
		(at 404.33371 -60.301378)
		(size 0.508)
		(drill 0.254)
		(layers "F.Cu" "B.Cu")
		(net "FM_OCP_MEZZC_PRES_LVT3_BMC")
	)
	(via
		(at 408.139646 -61.26734)
		(size 0.508)
		(drill 0.254)
		(layers "F.Cu" "B.Cu")
		(net "FM_OCP_MEZZC_PRES_LVT3_BMC")
	)
	(segment
		(start 419.126416 -54.864)
		(end 419.578536 -54.41188)
		(width 0.089408)
		(layer "In2.Cu")
		(net "FM_OCP_MEZZC_PRES_LVT3_BMC")
	)
	(segment
		(start 409.838398 -55.313834)
		(end 409.838398 -53.915564)
		(width 0.089408)
		(layer "In2.Cu")
		(net "FM_OCP_MEZZC_PRES_LVT3_BMC")
	)
	(segment
		(start 415.163 -54.864)
		(end 419.126416 -54.864)
		(width 0.089408)
		(layer "In2.Cu")
		(net "FM_OCP_MEZZC_PRES_LVT3_BMC")
	)
	(segment
		(start 420.514272 -54.41188)
		(end 421.192706 -53.733446)
		(width 0.089408)
		(layer "In2.Cu")
		(net "FM_OCP_MEZZC_PRES_LVT3_BMC")
	)
	(segment
		(start 421.192706 -53.733446)
		(end 422.264332 -53.733446)
		(width 0.089408)
		(layer "In2.Cu")
		(net "FM_OCP_MEZZC_PRES_LVT3_BMC")
	)
	(segment
		(start 422.264332 -53.733446)
		(end 422.545764 -54.014878)
		(width 0.089408)
		(layer "In2.Cu")
		(net "FM_OCP_MEZZC_PRES_LVT3_BMC")
	)
	(segment
		(start 422.545764 -54.014878)
		(end 422.545764 -54.104286)
		(width 0.089408)
		(layer "In2.Cu")
		(net "FM_OCP_MEZZC_PRES_LVT3_BMC")
	)
	(segment
		(start 409.838398 -53.915564)
		(end 410.102558 -53.651404)
		(width 0.089408)
		(layer "In2.Cu")
		(net "FM_OCP_MEZZC_PRES_LVT3_BMC")
	)
	(segment
		(start 419.578536 -54.41188)
		(end 420.514272 -54.41188)
		(width 0.089408)
		(layer "In2.Cu")
		(net "FM_OCP_MEZZC_PRES_LVT3_BMC")
	)
	(segment
		(start 409.549092 -55.60314)
		(end 409.838398 -55.313834)
		(width 0.089408)
		(layer "In2.Cu")
		(net "FM_OCP_MEZZC_PRES_LVT3_BMC")
	)
	(segment
		(start 413.950404 -53.651404)
		(end 415.163 -54.864)
		(width 0.089408)
		(layer "In2.Cu")
		(net "FM_OCP_MEZZC_PRES_LVT3_BMC")
	)
	(segment
		(start 408.139646 -61.26734)
		(end 409.549092 -59.857894)
		(width 0.089408)
		(layer "In2.Cu")
		(net "FM_OCP_MEZZC_PRES_LVT3_BMC")
	)
	(segment
		(start 410.102558 -53.651404)
		(end 413.950404 -53.651404)
		(width 0.089408)
		(layer "In2.Cu")
		(net "FM_OCP_MEZZC_PRES_LVT3_BMC")
	)
	(segment
		(start 409.549092 -59.857894)
		(end 409.549092 -55.60314)
		(width 0.089408)
		(layer "In2.Cu")
		(net "FM_OCP_MEZZC_PRES_LVT3_BMC")
	)
	(segment
		(start 411.115256 -42.290746)
		(end 411.115256 -41.179242)
		(width 0.089408)
		(layer "In9.Cu")
		(net "FM_OCP_MEZZC_PRES_LVT3_BMC")
	)
	(segment
		(start 404.6093 -59.252612)
		(end 404.6093 -56.510936)
		(width 0.089408)
		(layer "In9.Cu")
		(net "FM_OCP_MEZZC_PRES_LVT3_BMC")
	)
	(segment
		(start 407.371804 -45.084492)
		(end 408.268932 -44.187364)
		(width 0.089408)
		(layer "In9.Cu")
		(net "FM_OCP_MEZZC_PRES_LVT3_BMC")
	)
	(segment
		(start 411.115256 -41.179242)
		(end 411.334712 -40.959786)
		(width 0.089408)
		(layer "In9.Cu")
		(net "FM_OCP_MEZZC_PRES_LVT3_BMC")
	)
	(segment
		(start 403.227794 -55.12943)
		(end 403.227794 -53.769514)
		(width 0.089408)
		(layer "In9.Cu")
		(net "FM_OCP_MEZZC_PRES_LVT3_BMC")
	)
	(segment
		(start 408.268932 -44.187364)
		(end 408.268932 -43.880278)
		(width 0.089408)
		(layer "In9.Cu")
		(net "FM_OCP_MEZZC_PRES_LVT3_BMC")
	)
	(segment
		(start 410.886402 -42.5196)
		(end 411.115256 -42.290746)
		(width 0.089408)
		(layer "In9.Cu")
		(net "FM_OCP_MEZZC_PRES_LVT3_BMC")
	)
	(segment
		(start 405.478742 -45.084492)
		(end 407.371804 -45.084492)
		(width 0.089408)
		(layer "In9.Cu")
		(net "FM_OCP_MEZZC_PRES_LVT3_BMC")
	)
	(segment
		(start 408.686254 -43.462956)
		(end 409.692602 -43.462956)
		(width 0.089408)
		(layer "In9.Cu")
		(net "FM_OCP_MEZZC_PRES_LVT3_BMC")
	)
	(segment
		(start 405.135588 -51.86172)
		(end 405.135588 -47.77232)
		(width 0.089408)
		(layer "In9.Cu")
		(net "FM_OCP_MEZZC_PRES_LVT3_BMC")
	)
	(segment
		(start 404.909782 -47.546514)
		(end 404.909782 -45.653452)
		(width 0.089408)
		(layer "In9.Cu")
		(net "FM_OCP_MEZZC_PRES_LVT3_BMC")
	)
	(segment
		(start 408.268932 -43.880278)
		(end 408.686254 -43.462956)
		(width 0.089408)
		(layer "In9.Cu")
		(net "FM_OCP_MEZZC_PRES_LVT3_BMC")
	)
	(segment
		(start 409.692602 -43.462956)
		(end 410.635958 -42.5196)
		(width 0.089408)
		(layer "In9.Cu")
		(net "FM_OCP_MEZZC_PRES_LVT3_BMC")
	)
	(segment
		(start 411.334712 -40.959786)
		(end 411.334966 -40.959786)
		(width 0.089408)
		(layer "In9.Cu")
		(net "FM_OCP_MEZZC_PRES_LVT3_BMC")
	)
	(segment
		(start 404.33371 -59.528202)
		(end 404.6093 -59.252612)
		(width 0.089408)
		(layer "In9.Cu")
		(net "FM_OCP_MEZZC_PRES_LVT3_BMC")
	)
	(segment
		(start 412.254192 -40.53459)
		(end 412.290006 -40.53459)
		(width 0.089408)
		(layer "In9.Cu")
		(net "FM_OCP_MEZZC_PRES_LVT3_BMC")
	)
	(segment
		(start 405.135588 -47.77232)
		(end 404.909782 -47.546514)
		(width 0.089408)
		(layer "In9.Cu")
		(net "FM_OCP_MEZZC_PRES_LVT3_BMC")
	)
	(segment
		(start 404.6093 -56.510936)
		(end 403.227794 -55.12943)
		(width 0.089408)
		(layer "In9.Cu")
		(net "FM_OCP_MEZZC_PRES_LVT3_BMC")
	)
	(segment
		(start 411.842458 -40.946324)
		(end 412.254192 -40.53459)
		(width 0.089408)
		(layer "In9.Cu")
		(net "FM_OCP_MEZZC_PRES_LVT3_BMC")
	)
	(segment
		(start 404.909782 -45.653452)
		(end 405.478742 -45.084492)
		(width 0.089408)
		(layer "In9.Cu")
		(net "FM_OCP_MEZZC_PRES_LVT3_BMC")
	)
	(segment
		(start 404.33371 -60.301378)
		(end 404.33371 -59.528202)
		(width 0.089408)
		(layer "In9.Cu")
		(net "FM_OCP_MEZZC_PRES_LVT3_BMC")
	)
	(segment
		(start 410.635958 -42.5196)
		(end 410.886402 -42.5196)
		(width 0.089408)
		(layer "In9.Cu")
		(net "FM_OCP_MEZZC_PRES_LVT3_BMC")
	)
	(segment
		(start 403.227794 -53.769514)
		(end 405.135588 -51.86172)
		(width 0.089408)
		(layer "In9.Cu")
		(net "FM_OCP_MEZZC_PRES_LVT3_BMC")
	)
	(segment
		(start 411.334966 -40.959786)
		(end 411.348428 -40.946324)
		(width 0.089408)
		(layer "In9.Cu")
		(net "FM_OCP_MEZZC_PRES_LVT3_BMC")
	)
	(segment
		(start 411.348428 -40.946324)
		(end 411.842458 -40.946324)
		(width 0.089408)
		(layer "In9.Cu")
		(net "FM_OCP_MEZZC_PRES_LVT3_BMC")
	)
	(segment
		(start 408.139646 -61.26734)
		(end 406.867106 -59.9948)
		(width 0.089408)
		(layer "In11.Cu")
		(net "FM_OCP_MEZZC_PRES_LVT3_BMC")
	)
	(segment
		(start 404.69693 -60.235338)
		(end 404.39975 -60.235338)
		(width 0.089408)
		(layer "In11.Cu")
		(net "FM_OCP_MEZZC_PRES_LVT3_BMC")
	)
	(segment
		(start 404.39975 -60.235338)
		(end 404.33371 -60.301378)
		(width 0.089408)
		(layer "In11.Cu")
		(net "FM_OCP_MEZZC_PRES_LVT3_BMC")
	)
	(segment
		(start 406.867106 -59.9948)
		(end 404.937468 -59.9948)
		(width 0.089408)
		(layer "In11.Cu")
		(net "FM_OCP_MEZZC_PRES_LVT3_BMC")
	)
	(segment
		(start 404.937468 -59.9948)
		(end 404.69693 -60.235338)
		(width 0.089408)
		(layer "In11.Cu")
		(net "FM_OCP_MEZZC_PRES_LVT3_BMC")
	)
	(segment
		(start 412.690056 -40.93464)
		(end 412.674054 -40.93464)
		(width 0.10795)
		(layer "F.Cu")
		(net "FM_OCP_MEZZB_PRES_LVT3_BMC")
	)
	(segment
		(start 412.674054 -40.93464)
		(end 412.3055 -41.303194)
		(width 0.10795)
		(layer "F.Cu")
		(net "FM_OCP_MEZZB_PRES_LVT3_BMC")
	)
	(via
		(at 404.58898 -55.3466)
		(size 0.508)
		(drill 0.254)
		(layers "F.Cu" "B.Cu")
		(net "FM_OCP_MEZZB_PRES_LVT3_BMC")
	)
	(via
		(at 409.0797 -56.55818)
		(size 0.6604)
		(drill 0.3302)
		(layers "F.Cu" "B.Cu")
		(net "FM_OCP_MEZZB_PRES_LVT3_BMC")
	)
	(via
		(at 412.3055 -41.303194)
		(size 0.4572)
		(drill 0.2032)
		(layers "F.Cu" "B.Cu")
		(net "FM_OCP_MEZZB_PRES_LVT3_BMC")
	)
	(segment
		(start 405.526494 -56.784748)
		(end 404.58898 -55.847234)
		(width 0.10795)
		(layer "B.Cu")
		(net "FM_OCP_MEZZB_PRES_LVT3_BMC")
	)
	(segment
		(start 406.054814 -55.626)
		(end 406.054814 -56.242458)
		(width 0.10795)
		(layer "B.Cu")
		(net "FM_OCP_MEZZB_PRES_LVT3_BMC")
	)
	(segment
		(start 409.0797 -56.55818)
		(end 409.0035 -56.55818)
		(width 0.10795)
		(layer "B.Cu")
		(net "FM_OCP_MEZZB_PRES_LVT3_BMC")
	)
	(segment
		(start 406.583896 -56.352948)
		(end 406.7048 -56.232044)
		(width 0.10795)
		(layer "B.Cu")
		(net "FM_OCP_MEZZB_PRES_LVT3_BMC")
	)
	(segment
		(start 406.054814 -56.242458)
		(end 406.165304 -56.352948)
		(width 0.10795)
		(layer "B.Cu")
		(net "FM_OCP_MEZZB_PRES_LVT3_BMC")
	)
	(segment
		(start 406.165304 -56.352948)
		(end 406.583896 -56.352948)
		(width 0.10795)
		(layer "B.Cu")
		(net "FM_OCP_MEZZB_PRES_LVT3_BMC")
	)
	(segment
		(start 409.0035 -56.55818)
		(end 408.60218 -56.15686)
		(width 0.10795)
		(layer "B.Cu")
		(net "FM_OCP_MEZZB_PRES_LVT3_BMC")
	)
	(segment
		(start 406.77338 -56.784748)
		(end 405.526494 -56.784748)
		(width 0.10795)
		(layer "B.Cu")
		(net "FM_OCP_MEZZB_PRES_LVT3_BMC")
	)
	(segment
		(start 407.65222 -55.626)
		(end 407.86304 -55.83682)
		(width 0.10795)
		(layer "B.Cu")
		(net "FM_OCP_MEZZB_PRES_LVT3_BMC")
	)
	(segment
		(start 404.58898 -55.847234)
		(end 404.58898 -55.3466)
		(width 0.10795)
		(layer "B.Cu")
		(net "FM_OCP_MEZZB_PRES_LVT3_BMC")
	)
	(segment
		(start 407.86304 -55.83682)
		(end 407.86304 -56.15686)
		(width 0.10795)
		(layer "B.Cu")
		(net "FM_OCP_MEZZB_PRES_LVT3_BMC")
	)
	(segment
		(start 408.60218 -56.15686)
		(end 407.86304 -56.15686)
		(width 0.10795)
		(layer "B.Cu")
		(net "FM_OCP_MEZZB_PRES_LVT3_BMC")
	)
	(segment
		(start 406.7048 -56.232044)
		(end 406.7048 -55.626)
		(width 0.10795)
		(layer "B.Cu")
		(net "FM_OCP_MEZZB_PRES_LVT3_BMC")
	)
	(segment
		(start 407.86304 -56.15686)
		(end 407.401268 -56.15686)
		(width 0.10795)
		(layer "B.Cu")
		(net "FM_OCP_MEZZB_PRES_LVT3_BMC")
	)
	(segment
		(start 406.7048 -55.626)
		(end 407.65222 -55.626)
		(width 0.10795)
		(layer "B.Cu")
		(net "FM_OCP_MEZZB_PRES_LVT3_BMC")
	)
	(segment
		(start 407.401268 -56.15686)
		(end 406.77338 -56.784748)
		(width 0.10795)
		(layer "B.Cu")
		(net "FM_OCP_MEZZB_PRES_LVT3_BMC")
	)
	(segment
		(start 406.169114 -49.581816)
		(end 406.169114 -51.667918)
		(width 0.089408)
		(layer "In9.Cu")
		(net "FM_OCP_MEZZB_PRES_LVT3_BMC")
	)
	(segment
		(start 406.423368 -49.327562)
		(end 406.169114 -49.581816)
		(width 0.089408)
		(layer "In9.Cu")
		(net "FM_OCP_MEZZB_PRES_LVT3_BMC")
	)
	(segment
		(start 408.764994 -45.274992)
		(end 407.464006 -45.274992)
		(width 0.089408)
		(layer "In9.Cu")
		(net "FM_OCP_MEZZB_PRES_LVT3_BMC")
	)
	(segment
		(start 406.169114 -51.667918)
		(end 405.078184 -52.758848)
		(width 0.089408)
		(layer "In9.Cu")
		(net "FM_OCP_MEZZB_PRES_LVT3_BMC")
	)
	(segment
		(start 410.695394 -45.174408)
		(end 410.308552 -45.56125)
		(width 0.089408)
		(layer "In9.Cu")
		(net "FM_OCP_MEZZB_PRES_LVT3_BMC")
	)
	(segment
		(start 411.937454 -43.507914)
		(end 411.598618 -43.84675)
		(width 0.089408)
		(layer "In9.Cu")
		(net "FM_OCP_MEZZB_PRES_LVT3_BMC")
	)
	(segment
		(start 407.464006 -45.274992)
		(end 407.463752 -45.275246)
		(width 0.089408)
		(layer "In9.Cu")
		(net "FM_OCP_MEZZB_PRES_LVT3_BMC")
	)
	(segment
		(start 410.308552 -45.56125)
		(end 409.051252 -45.56125)
		(width 0.089408)
		(layer "In9.Cu")
		(net "FM_OCP_MEZZB_PRES_LVT3_BMC")
	)
	(segment
		(start 404.58898 -55.318914)
		(end 404.58898 -55.3466)
		(width 0.089408)
		(layer "In9.Cu")
		(net "FM_OCP_MEZZB_PRES_LVT3_BMC")
	)
	(segment
		(start 405.078184 -54.82971)
		(end 404.58898 -55.318914)
		(width 0.089408)
		(layer "In9.Cu")
		(net "FM_OCP_MEZZB_PRES_LVT3_BMC")
	)
	(segment
		(start 411.598618 -44.56938)
		(end 410.99359 -45.174408)
		(width 0.089408)
		(layer "In9.Cu")
		(net "FM_OCP_MEZZB_PRES_LVT3_BMC")
	)
	(segment
		(start 405.73325 -45.630338)
		(end 405.73325 -47.845218)
		(width 0.089408)
		(layer "In9.Cu")
		(net "FM_OCP_MEZZB_PRES_LVT3_BMC")
	)
	(segment
		(start 409.051252 -45.56125)
		(end 408.764994 -45.274992)
		(width 0.089408)
		(layer "In9.Cu")
		(net "FM_OCP_MEZZB_PRES_LVT3_BMC")
	)
	(segment
		(start 405.73325 -47.845218)
		(end 406.423368 -48.535336)
		(width 0.089408)
		(layer "In9.Cu")
		(net "FM_OCP_MEZZB_PRES_LVT3_BMC")
	)
	(segment
		(start 406.423368 -48.535336)
		(end 406.423368 -49.327562)
		(width 0.089408)
		(layer "In9.Cu")
		(net "FM_OCP_MEZZB_PRES_LVT3_BMC")
	)
	(segment
		(start 410.99359 -45.174408)
		(end 410.695394 -45.174408)
		(width 0.089408)
		(layer "In9.Cu")
		(net "FM_OCP_MEZZB_PRES_LVT3_BMC")
	)
	(segment
		(start 411.598618 -43.84675)
		(end 411.598618 -44.56938)
		(width 0.089408)
		(layer "In9.Cu")
		(net "FM_OCP_MEZZB_PRES_LVT3_BMC")
	)
	(segment
		(start 405.078184 -52.758848)
		(end 405.078184 -54.82971)
		(width 0.089408)
		(layer "In9.Cu")
		(net "FM_OCP_MEZZB_PRES_LVT3_BMC")
	)
	(segment
		(start 407.463752 -45.275246)
		(end 406.088342 -45.275246)
		(width 0.089408)
		(layer "In9.Cu")
		(net "FM_OCP_MEZZB_PRES_LVT3_BMC")
	)
	(segment
		(start 412.3055 -41.303194)
		(end 411.937454 -41.67124)
		(width 0.089408)
		(layer "In9.Cu")
		(net "FM_OCP_MEZZB_PRES_LVT3_BMC")
	)
	(segment
		(start 411.937454 -41.67124)
		(end 411.937454 -43.507914)
		(width 0.089408)
		(layer "In9.Cu")
		(net "FM_OCP_MEZZB_PRES_LVT3_BMC")
	)
	(segment
		(start 406.088342 -45.275246)
		(end 405.73325 -45.630338)
		(width 0.089408)
		(layer "In9.Cu")
		(net "FM_OCP_MEZZB_PRES_LVT3_BMC")
	)
	(segment
		(start 440.600846 -113.880646)
		(end 441.2361 -114.5159)
		(width 0.10795)
		(layer "F.Cu")
		(net "FM_OCP_MEZZA_PRES_N")
	)
	(segment
		(start 440.600846 -112.205516)
		(end 440.600846 -113.880646)
		(width 0.10795)
		(layer "F.Cu")
		(net "FM_OCP_MEZZA_PRES_N")
	)
	(via
		(at 474.1926 -116.4336)
		(size 0.6604)
		(drill 0.3302)
		(layers "F.Cu" "B.Cu")
		(net "FM_OCP_MEZZA_PRES_N")
	)
	(via
		(at 441.2361 -114.5159)
		(size 0.508)
		(drill 0.254)
		(layers "F.Cu" "B.Cu")
		(net "FM_OCP_MEZZA_PRES_N")
	)
	(via
		(at 474.47581 -115.058698)
		(size 0.508)
		(drill 0.254)
		(layers "F.Cu" "B.Cu")
		(net "FM_OCP_MEZZA_PRES_N")
	)
	(segment
		(start 474.1926 -115.341908)
		(end 474.1926 -116.4336)
		(width 0.10795)
		(layer "B.Cu")
		(net "FM_OCP_MEZZA_PRES_N")
	)
	(segment
		(start 474.47581 -115.058698)
		(end 474.1926 -115.341908)
		(width 0.10795)
		(layer "B.Cu")
		(net "FM_OCP_MEZZA_PRES_N")
	)
	(segment
		(start 474.1926 -116.4336)
		(end 474.1926 -117.0432)
		(width 0.10795)
		(layer "B.Cu")
		(net "FM_OCP_MEZZA_PRES_N")
	)
	(segment
		(start 474.1926 -117.0432)
		(end 474.8149 -117.6655)
		(width 0.10795)
		(layer "B.Cu")
		(net "FM_OCP_MEZZA_PRES_N")
	)
	(segment
		(start 476.19539 -120.03659)
		(end 476.19539 -117.67439)
		(width 0.10795)
		(layer "B.Cu")
		(net "FM_OCP_MEZZA_PRES_N")
	)
	(segment
		(start 476.4151 -120.2563)
		(end 476.19539 -120.03659)
		(width 0.10795)
		(layer "B.Cu")
		(net "FM_OCP_MEZZA_PRES_N")
	)
	(segment
		(start 477.814132 -120.2563)
		(end 476.4151 -120.2563)
		(width 0.10795)
		(layer "B.Cu")
		(net "FM_OCP_MEZZA_PRES_N")
	)
	(segment
		(start 476.19539 -117.67439)
		(end 476.1865 -117.6655)
		(width 0.10795)
		(layer "B.Cu")
		(net "FM_OCP_MEZZA_PRES_N")
	)
	(segment
		(start 474.8149 -117.6655)
		(end 476.1865 -117.6655)
		(width 0.10795)
		(layer "B.Cu")
		(net "FM_OCP_MEZZA_PRES_N")
	)
	(segment
		(start 477.952562 -120.39473)
		(end 477.814132 -120.2563)
		(width 0.10795)
		(layer "B.Cu")
		(net "FM_OCP_MEZZA_PRES_N")
	)
	(segment
		(start 478.286064 -120.39473)
		(end 477.952562 -120.39473)
		(width 0.10795)
		(layer "B.Cu")
		(net "FM_OCP_MEZZA_PRES_N")
	)
	(segment
		(start 474.47581 -115.058698)
		(end 474.071442 -115.463066)
		(width 0.089408)
		(layer "In2.Cu")
		(net "FM_OCP_MEZZA_PRES_N")
	)
	(segment
		(start 467.893908 -113.315496)
		(end 441.263786 -113.315496)
		(width 0.089408)
		(layer "In2.Cu")
		(net "FM_OCP_MEZZA_PRES_N")
	)
	(segment
		(start 470.784936 -115.463066)
		(end 469.594438 -114.272568)
		(width 0.089408)
		(layer "In2.Cu")
		(net "FM_OCP_MEZZA_PRES_N")
	)
	(segment
		(start 440.948826 -114.228626)
		(end 441.2361 -114.5159)
		(width 0.089408)
		(layer "In2.Cu")
		(net "FM_OCP_MEZZA_PRES_N")
	)
	(segment
		(start 474.071442 -115.463066)
		(end 470.784936 -115.463066)
		(width 0.089408)
		(layer "In2.Cu")
		(net "FM_OCP_MEZZA_PRES_N")
	)
	(segment
		(start 441.263786 -113.315496)
		(end 440.948826 -113.630456)
		(width 0.089408)
		(layer "In2.Cu")
		(net "FM_OCP_MEZZA_PRES_N")
	)
	(segment
		(start 468.85098 -114.272568)
		(end 467.893908 -113.315496)
		(width 0.089408)
		(layer "In2.Cu")
		(net "FM_OCP_MEZZA_PRES_N")
	)
	(segment
		(start 469.594438 -114.272568)
		(end 468.85098 -114.272568)
		(width 0.089408)
		(layer "In2.Cu")
		(net "FM_OCP_MEZZA_PRES_N")
	)
	(segment
		(start 440.948826 -113.630456)
		(end 440.948826 -114.228626)
		(width 0.089408)
		(layer "In2.Cu")
		(net "FM_OCP_MEZZA_PRES_N")
	)
	(segment
		(start 373.544846 -79.894684)
		(end 373.14505 -79.494888)
		(width 0.1016)
		(layer "F.Cu")
		(net "FM_CPLD_USB_P0_EN_N")
	)
	(via
		(at 389.847582 -78.688692)
		(size 0.508)
		(drill 0.254)
		(layers "F.Cu" "B.Cu")
		(net "FM_CPLD_USB_P0_EN_N")
	)
	(via
		(at 419.962584 -99.162108)
		(size 0.6604)
		(drill 0.3302)
		(layers "F.Cu" "B.Cu")
		(net "FM_CPLD_USB_P0_EN_N")
	)
	(via
		(at 373.544846 -79.894684)
		(size 0.4572)
		(drill 0.2032)
		(layers "F.Cu" "B.Cu")
		(net "FM_CPLD_USB_P0_EN_N")
	)
	(segment
		(start 469.839294 -115.680744)
		(end 469.839294 -114.999262)
		(width 0.1016)
		(layer "B.Cu")
		(net "FM_CPLD_USB_P0_EN_N")
	)
	(segment
		(start 420.753794 -100.555298)
		(end 419.962584 -99.764088)
		(width 0.1016)
		(layer "B.Cu")
		(net "FM_CPLD_USB_P0_EN_N")
	)
	(segment
		(start 425.22521 -121.599198)
		(end 420.753794 -117.127782)
		(width 0.1016)
		(layer "B.Cu")
		(net "FM_CPLD_USB_P0_EN_N")
	)
	(segment
		(start 413.770318 -81.487264)
		(end 415.643314 -83.36026)
		(width 0.1016)
		(layer "B.Cu")
		(net "FM_CPLD_USB_P0_EN_N")
	)
	(segment
		(start 469.49233 -114.652298)
		(end 468.589614 -114.652298)
		(width 0.1016)
		(layer "B.Cu")
		(net "FM_CPLD_USB_P0_EN_N")
	)
	(segment
		(start 469.839294 -114.999262)
		(end 469.49233 -114.652298)
		(width 0.1016)
		(layer "B.Cu")
		(net "FM_CPLD_USB_P0_EN_N")
	)
	(segment
		(start 469.646 -125.984)
		(end 469.11895 -125.45695)
		(width 0.1016)
		(layer "B.Cu")
		(net "FM_CPLD_USB_P0_EN_N")
	)
	(segment
		(start 413.770318 -75.205844)
		(end 413.770318 -81.487264)
		(width 0.1016)
		(layer "B.Cu")
		(net "FM_CPLD_USB_P0_EN_N")
	)
	(segment
		(start 397.626586 -74.704194)
		(end 398.987264 -73.343516)
		(width 0.1016)
		(layer "B.Cu")
		(net "FM_CPLD_USB_P0_EN_N")
	)
	(segment
		(start 419.962584 -99.764088)
		(end 419.962584 -99.162108)
		(width 0.1016)
		(layer "B.Cu")
		(net "FM_CPLD_USB_P0_EN_N")
	)
	(segment
		(start 469.11895 -124.659136)
		(end 468.696548 -124.236734)
		(width 0.1016)
		(layer "B.Cu")
		(net "FM_CPLD_USB_P0_EN_N")
	)
	(segment
		(start 396.625826 -74.704194)
		(end 397.626586 -74.704194)
		(width 0.1016)
		(layer "B.Cu")
		(net "FM_CPLD_USB_P0_EN_N")
	)
	(segment
		(start 467.046818 -113.109502)
		(end 441.177934 -113.109502)
		(width 0.1016)
		(layer "B.Cu")
		(net "FM_CPLD_USB_P0_EN_N")
	)
	(segment
		(start 469.11895 -125.45695)
		(end 469.11895 -124.659136)
		(width 0.1016)
		(layer "B.Cu")
		(net "FM_CPLD_USB_P0_EN_N")
	)
	(segment
		(start 468.696548 -124.236734)
		(end 468.696548 -123.15952)
		(width 0.1016)
		(layer "B.Cu")
		(net "FM_CPLD_USB_P0_EN_N")
	)
	(segment
		(start 419.928802 -87.414862)
		(end 419.928802 -87.415116)
		(width 0.1016)
		(layer "B.Cu")
		(net "FM_CPLD_USB_P0_EN_N")
	)
	(segment
		(start 420.599362 -88.085676)
		(end 420.599362 -93.712284)
		(width 0.1016)
		(layer "B.Cu")
		(net "FM_CPLD_USB_P0_EN_N")
	)
	(segment
		(start 399.556224 -73.343516)
		(end 400.066764 -72.832976)
		(width 0.1016)
		(layer "B.Cu")
		(net "FM_CPLD_USB_P0_EN_N")
	)
	(segment
		(start 411.39745 -72.832976)
		(end 413.770318 -75.205844)
		(width 0.1016)
		(layer "B.Cu")
		(net "FM_CPLD_USB_P0_EN_N")
	)
	(segment
		(start 439.8137 -114.473736)
		(end 439.8137 -120.00865)
		(width 0.1016)
		(layer "B.Cu")
		(net "FM_CPLD_USB_P0_EN_N")
	)
	(segment
		(start 441.177934 -113.109502)
		(end 439.8137 -114.473736)
		(width 0.1016)
		(layer "B.Cu")
		(net "FM_CPLD_USB_P0_EN_N")
	)
	(segment
		(start 438.223152 -121.599198)
		(end 425.22521 -121.599198)
		(width 0.1016)
		(layer "B.Cu")
		(net "FM_CPLD_USB_P0_EN_N")
	)
	(segment
		(start 415.885884 -83.372198)
		(end 415.886138 -83.372198)
		(width 0.1016)
		(layer "B.Cu")
		(net "FM_CPLD_USB_P0_EN_N")
	)
	(segment
		(start 419.962584 -94.349062)
		(end 419.962584 -99.162108)
		(width 0.1016)
		(layer "B.Cu")
		(net "FM_CPLD_USB_P0_EN_N")
	)
	(segment
		(start 396.19047 -75.13955)
		(end 396.625826 -74.704194)
		(width 0.1016)
		(layer "B.Cu")
		(net "FM_CPLD_USB_P0_EN_N")
	)
	(segment
		(start 393.954762 -77.479398)
		(end 396.19047 -75.24369)
		(width 0.1016)
		(layer "B.Cu")
		(net "FM_CPLD_USB_P0_EN_N")
	)
	(segment
		(start 390.041892 -78.688692)
		(end 391.251186 -77.479398)
		(width 0.1016)
		(layer "B.Cu")
		(net "FM_CPLD_USB_P0_EN_N")
	)
	(segment
		(start 400.066764 -72.832976)
		(end 411.39745 -72.832976)
		(width 0.1016)
		(layer "B.Cu")
		(net "FM_CPLD_USB_P0_EN_N")
	)
	(segment
		(start 419.928802 -87.415116)
		(end 420.599362 -88.085676)
		(width 0.1016)
		(layer "B.Cu")
		(net "FM_CPLD_USB_P0_EN_N")
	)
	(segment
		(start 420.599362 -93.712284)
		(end 419.962584 -94.349062)
		(width 0.1016)
		(layer "B.Cu")
		(net "FM_CPLD_USB_P0_EN_N")
	)
	(segment
		(start 468.696548 -123.15952)
		(end 469.382348 -122.47372)
		(width 0.1016)
		(layer "B.Cu")
		(net "FM_CPLD_USB_P0_EN_N")
	)
	(segment
		(start 469.382348 -122.47372)
		(end 469.382348 -116.13769)
		(width 0.1016)
		(layer "B.Cu")
		(net "FM_CPLD_USB_P0_EN_N")
	)
	(segment
		(start 469.382348 -116.13769)
		(end 469.839294 -115.680744)
		(width 0.1016)
		(layer "B.Cu")
		(net "FM_CPLD_USB_P0_EN_N")
	)
	(segment
		(start 439.8137 -120.00865)
		(end 438.223152 -121.599198)
		(width 0.1016)
		(layer "B.Cu")
		(net "FM_CPLD_USB_P0_EN_N")
	)
	(segment
		(start 398.987264 -73.343516)
		(end 399.556224 -73.343516)
		(width 0.1016)
		(layer "B.Cu")
		(net "FM_CPLD_USB_P0_EN_N")
	)
	(segment
		(start 396.19047 -75.24369)
		(end 396.19047 -75.13955)
		(width 0.1016)
		(layer "B.Cu")
		(net "FM_CPLD_USB_P0_EN_N")
	)
	(segment
		(start 468.589614 -114.652298)
		(end 467.046818 -113.109502)
		(width 0.1016)
		(layer "B.Cu")
		(net "FM_CPLD_USB_P0_EN_N")
	)
	(segment
		(start 415.873946 -83.36026)
		(end 415.885884 -83.372198)
		(width 0.1016)
		(layer "B.Cu")
		(net "FM_CPLD_USB_P0_EN_N")
	)
	(segment
		(start 415.643314 -83.36026)
		(end 415.873946 -83.36026)
		(width 0.1016)
		(layer "B.Cu")
		(net "FM_CPLD_USB_P0_EN_N")
	)
	(segment
		(start 391.251186 -77.479398)
		(end 393.954762 -77.479398)
		(width 0.1016)
		(layer "B.Cu")
		(net "FM_CPLD_USB_P0_EN_N")
	)
	(segment
		(start 415.886138 -83.372198)
		(end 419.928802 -87.414862)
		(width 0.1016)
		(layer "B.Cu")
		(net "FM_CPLD_USB_P0_EN_N")
	)
	(segment
		(start 420.753794 -117.127782)
		(end 420.753794 -100.555298)
		(width 0.1016)
		(layer "B.Cu")
		(net "FM_CPLD_USB_P0_EN_N")
	)
	(segment
		(start 389.847582 -78.688692)
		(end 390.041892 -78.688692)
		(width 0.1016)
		(layer "B.Cu")
		(net "FM_CPLD_USB_P0_EN_N")
	)
	(segment
		(start 384.153918 -77.562964)
		(end 382.639062 -79.07782)
		(width 0.0889)
		(layer "In4.Cu")
		(net "FM_CPLD_USB_P0_EN_N")
	)
	(segment
		(start 388.951216 -78.688692)
		(end 388.645908 -78.383384)
		(width 0.0889)
		(layer "In4.Cu")
		(net "FM_CPLD_USB_P0_EN_N")
	)
	(segment
		(start 386.998464 -78.383384)
		(end 386.178044 -77.562964)
		(width 0.0889)
		(layer "In4.Cu")
		(net "FM_CPLD_USB_P0_EN_N")
	)
	(segment
		(start 373.917972 -79.521558)
		(end 373.544846 -79.894684)
		(width 0.0889)
		(layer "In4.Cu")
		(net "FM_CPLD_USB_P0_EN_N")
	)
	(segment
		(start 380.07671 -80.26781)
		(end 375.359422 -80.26781)
		(width 0.0889)
		(layer "In4.Cu")
		(net "FM_CPLD_USB_P0_EN_N")
	)
	(segment
		(start 386.178044 -77.562964)
		(end 384.153918 -77.562964)
		(width 0.0889)
		(layer "In4.Cu")
		(net "FM_CPLD_USB_P0_EN_N")
	)
	(segment
		(start 382.639062 -79.07782)
		(end 381.2667 -79.07782)
		(width 0.0889)
		(layer "In4.Cu")
		(net "FM_CPLD_USB_P0_EN_N")
	)
	(segment
		(start 374.61317 -79.521558)
		(end 373.917972 -79.521558)
		(width 0.0889)
		(layer "In4.Cu")
		(net "FM_CPLD_USB_P0_EN_N")
	)
	(segment
		(start 389.847582 -78.688692)
		(end 388.951216 -78.688692)
		(width 0.0889)
		(layer "In4.Cu")
		(net "FM_CPLD_USB_P0_EN_N")
	)
	(segment
		(start 375.359422 -80.26781)
		(end 374.61317 -79.521558)
		(width 0.0889)
		(layer "In4.Cu")
		(net "FM_CPLD_USB_P0_EN_N")
	)
	(segment
		(start 381.2667 -79.07782)
		(end 380.07671 -80.26781)
		(width 0.0889)
		(layer "In4.Cu")
		(net "FM_CPLD_USB_P0_EN_N")
	)
	(segment
		(start 388.645908 -78.383384)
		(end 386.998464 -78.383384)
		(width 0.0889)
		(layer "In4.Cu")
		(net "FM_CPLD_USB_P0_EN_N")
	)
	(segment
		(start 419.090094 -41.73474)
		(end 418.690044 -42.13479)
		(width 0.10795)
		(layer "F.Cu")
		(net "UV_HIGH_SET")
	)
	(via
		(at 446.809622 -2.36474)
		(size 0.508)
		(drill 0.254)
		(layers "F.Cu" "B.Cu")
		(net "UV_HIGH_SET")
	)
	(via
		(at 406.540208 -66.365374)
		(size 0.508)
		(drill 0.254)
		(layers "F.Cu" "B.Cu")
		(net "UV_HIGH_SET")
	)
	(via
		(at 454.496424 -9.724644)
		(size 0.508)
		(drill 0.254)
		(layers "F.Cu" "B.Cu")
		(net "UV_HIGH_SET")
	)
	(via
		(at 330.51496 -120.961912)
		(size 0.508)
		(drill 0.254)
		(layers "F.Cu" "B.Cu")
		(net "UV_HIGH_SET")
	)
	(via
		(at 401.59686 -86.05393)
		(size 0.508)
		(drill 0.254)
		(layers "F.Cu" "B.Cu")
		(net "UV_HIGH_SET")
	)
	(via
		(at 418.690044 -42.13479)
		(size 0.4572)
		(drill 0.2032)
		(layers "F.Cu" "B.Cu")
		(net "UV_HIGH_SET")
	)
	(via
		(at 403.99462 -155.09748)
		(size 0.508)
		(drill 0.254)
		(layers "F.Cu" "B.Cu")
		(net "UV_HIGH_SET")
	)
	(via
		(at 419.339776 -128.312164)
		(size 0.508)
		(drill 0.254)
		(layers "F.Cu" "B.Cu")
		(net "UV_HIGH_SET")
	)
	(via
		(at 21.744686 -97.849436)
		(size 0.508)
		(drill 0.254)
		(layers "F.Cu" "B.Cu")
		(net "UV_HIGH_SET")
	)
	(via
		(at 416.560254 -94.18066)
		(size 0.508)
		(drill 0.254)
		(layers "F.Cu" "B.Cu")
		(net "UV_HIGH_SET")
	)
	(via
		(at 419.477444 -127.055118)
		(size 0.6604)
		(drill 0.3302)
		(layers "F.Cu" "B.Cu")
		(net "UV_HIGH_SET")
	)
	(segment
		(start 451.994016 4.154424)
		(end 451.994016 3.81)
		(width 0.10795)
		(layer "B.Cu")
		(net "UV_HIGH_SET")
	)
	(segment
		(start 418.373306 -103.57231)
		(end 416.531806 -101.73081)
		(width 0.10795)
		(layer "B.Cu")
		(net "UV_HIGH_SET")
	)
	(segment
		(start 418.663374 -119.842026)
		(end 418.663374 -119.58447)
		(width 0.10795)
		(layer "B.Cu")
		(net "UV_HIGH_SET")
	)
	(segment
		(start 450.812662 5.335778)
		(end 451.994016 4.154424)
		(width 0.10795)
		(layer "B.Cu")
		(net "UV_HIGH_SET")
	)
	(segment
		(start 448.275202 4.7117)
		(end 448.89928 5.335778)
		(width 0.10795)
		(layer "B.Cu")
		(net "UV_HIGH_SET")
	)
	(segment
		(start 418.663374 -119.58447)
		(end 418.662612 -119.583708)
		(width 0.10795)
		(layer "B.Cu")
		(net "UV_HIGH_SET")
	)
	(segment
		(start 418.373306 -108.360464)
		(end 418.373306 -103.57231)
		(width 0.10795)
		(layer "B.Cu")
		(net "UV_HIGH_SET")
	)
	(segment
		(start 419.025832 -128.626108)
		(end 418.496496 -128.626108)
		(width 0.10795)
		(layer "B.Cu")
		(net "UV_HIGH_SET")
	)
	(segment
		(start 416.531806 -94.209108)
		(end 416.560254 -94.18066)
		(width 0.10795)
		(layer "B.Cu")
		(net "UV_HIGH_SET")
	)
	(segment
		(start 417.737544 -108.996226)
		(end 418.373306 -108.360464)
		(width 0.10795)
		(layer "B.Cu")
		(net "UV_HIGH_SET")
	)
	(segment
		(start 420.450518 -121.98731)
		(end 420.450772 -121.987056)
		(width 0.10795)
		(layer "B.Cu")
		(net "UV_HIGH_SET")
	)
	(segment
		(start 418.215318 -127.963422)
		(end 419.123622 -127.055118)
		(width 0.10795)
		(layer "B.Cu")
		(net "UV_HIGH_SET")
	)
	(segment
		(start 417.737544 -117.57279)
		(end 417.737544 -108.996226)
		(width 0.10795)
		(layer "B.Cu")
		(net "UV_HIGH_SET")
	)
	(segment
		(start 21.0312 -97.13595)
		(end 21.744686 -97.849436)
		(width 0.10795)
		(layer "B.Cu")
		(net "UV_HIGH_SET")
	)
	(segment
		(start 418.496496 -128.626108)
		(end 418.215318 -128.34493)
		(width 0.10795)
		(layer "B.Cu")
		(net "UV_HIGH_SET")
	)
	(segment
		(start 20.3835 -90.1065)
		(end 20.3835 -90.8177)
		(width 0.10795)
		(layer "B.Cu")
		(net "UV_HIGH_SET")
	)
	(segment
		(start 419.477444 -127.055118)
		(end 420.450518 -126.082044)
		(width 0.10795)
		(layer "B.Cu")
		(net "UV_HIGH_SET")
	)
	(segment
		(start 448.89928 5.335778)
		(end 450.812662 5.335778)
		(width 0.10795)
		(layer "B.Cu")
		(net "UV_HIGH_SET")
	)
	(segment
		(start 20.32 -90.8812)
		(end 20.32 -92.202)
		(width 0.10795)
		(layer "B.Cu")
		(net "UV_HIGH_SET")
	)
	(segment
		(start 418.215318 -128.34493)
		(end 418.215318 -127.963422)
		(width 0.10795)
		(layer "B.Cu")
		(net "UV_HIGH_SET")
	)
	(segment
		(start 20.3835 -90.8177)
		(end 20.32 -90.8812)
		(width 0.10795)
		(layer "B.Cu")
		(net "UV_HIGH_SET")
	)
	(segment
		(start 418.662612 -119.583708)
		(end 418.662612 -118.497858)
		(width 0.10795)
		(layer "B.Cu")
		(net "UV_HIGH_SET")
	)
	(segment
		(start 21.5646 -93.4466)
		(end 21.5646 -95.3516)
		(width 0.10795)
		(layer "B.Cu")
		(net "UV_HIGH_SET")
	)
	(segment
		(start 448.275202 -0.89916)
		(end 448.275202 4.7117)
		(width 0.10795)
		(layer "B.Cu")
		(net "UV_HIGH_SET")
	)
	(segment
		(start 21.0312 -95.885)
		(end 21.0312 -97.13595)
		(width 0.10795)
		(layer "B.Cu")
		(net "UV_HIGH_SET")
	)
	(segment
		(start 419.339776 -128.312164)
		(end 419.025832 -128.626108)
		(width 0.10795)
		(layer "B.Cu")
		(net "UV_HIGH_SET")
	)
	(segment
		(start 420.450518 -126.082044)
		(end 420.450518 -121.98731)
		(width 0.10795)
		(layer "B.Cu")
		(net "UV_HIGH_SET")
	)
	(segment
		(start 21.5646 -95.3516)
		(end 21.0312 -95.885)
		(width 0.10795)
		(layer "B.Cu")
		(net "UV_HIGH_SET")
	)
	(segment
		(start 420.450772 -121.629424)
		(end 418.663374 -119.842026)
		(width 0.10795)
		(layer "B.Cu")
		(net "UV_HIGH_SET")
	)
	(segment
		(start 420.450772 -121.987056)
		(end 420.450772 -121.629424)
		(width 0.10795)
		(layer "B.Cu")
		(net "UV_HIGH_SET")
	)
	(segment
		(start 418.662612 -118.497858)
		(end 417.737544 -117.57279)
		(width 0.10795)
		(layer "B.Cu")
		(net "UV_HIGH_SET")
	)
	(segment
		(start 446.809622 -2.36474)
		(end 448.275202 -0.89916)
		(width 0.10795)
		(layer "B.Cu")
		(net "UV_HIGH_SET")
	)
	(segment
		(start 20.32 -92.202)
		(end 21.5646 -93.4466)
		(width 0.10795)
		(layer "B.Cu")
		(net "UV_HIGH_SET")
	)
	(segment
		(start 416.531806 -101.73081)
		(end 416.531806 -94.209108)
		(width 0.10795)
		(layer "B.Cu")
		(net "UV_HIGH_SET")
	)
	(segment
		(start 419.123622 -127.055118)
		(end 419.477444 -127.055118)
		(width 0.10795)
		(layer "B.Cu")
		(net "UV_HIGH_SET")
	)
	(segment
		(start 400.513296 -76.918312)
		(end 401.152106 -77.557122)
		(width 0.089408)
		(layer "In2.Cu")
		(net "UV_HIGH_SET")
	)
	(segment
		(start 405.37638 -67.541394)
		(end 405.37638 -70.23862)
		(width 0.089408)
		(layer "In2.Cu")
		(net "UV_HIGH_SET")
	)
	(segment
		(start 406.536398 -66.365374)
		(end 405.666448 -67.235324)
		(width 0.089408)
		(layer "In2.Cu")
		(net "UV_HIGH_SET")
	)
	(segment
		(start 405.666448 -67.251326)
		(end 405.37638 -67.541394)
		(width 0.089408)
		(layer "In2.Cu")
		(net "UV_HIGH_SET")
	)
	(segment
		(start 401.152106 -78.363064)
		(end 400.504152 -79.011018)
		(width 0.089408)
		(layer "In2.Cu")
		(net "UV_HIGH_SET")
	)
	(segment
		(start 399.739866 -82.257138)
		(end 400.898868 -83.41614)
		(width 0.089408)
		(layer "In2.Cu")
		(net "UV_HIGH_SET")
	)
	(segment
		(start 400.898868 -83.41614)
		(end 400.898868 -85.355938)
		(width 0.089408)
		(layer "In2.Cu")
		(net "UV_HIGH_SET")
	)
	(segment
		(start 400.513296 -73.754996)
		(end 400.513296 -76.918312)
		(width 0.089408)
		(layer "In2.Cu")
		(net "UV_HIGH_SET")
	)
	(segment
		(start 400.898868 -85.355938)
		(end 401.59686 -86.05393)
		(width 0.089408)
		(layer "In2.Cu")
		(net "UV_HIGH_SET")
	)
	(segment
		(start 406.540208 -66.365374)
		(end 406.536398 -66.365374)
		(width 0.089408)
		(layer "In2.Cu")
		(net "UV_HIGH_SET")
	)
	(segment
		(start 400.504152 -80.38211)
		(end 399.739866 -81.146396)
		(width 0.089408)
		(layer "In2.Cu")
		(net "UV_HIGH_SET")
	)
	(segment
		(start 400.825716 -73.442576)
		(end 400.513296 -73.754996)
		(width 0.089408)
		(layer "In2.Cu")
		(net "UV_HIGH_SET")
	)
	(segment
		(start 399.739866 -81.146396)
		(end 399.739866 -82.257138)
		(width 0.089408)
		(layer "In2.Cu")
		(net "UV_HIGH_SET")
	)
	(segment
		(start 401.152106 -77.557122)
		(end 401.152106 -78.363064)
		(width 0.089408)
		(layer "In2.Cu")
		(net "UV_HIGH_SET")
	)
	(segment
		(start 400.504152 -79.011018)
		(end 400.504152 -80.38211)
		(width 0.089408)
		(layer "In2.Cu")
		(net "UV_HIGH_SET")
	)
	(segment
		(start 405.37638 -70.23862)
		(end 402.172424 -73.442576)
		(width 0.089408)
		(layer "In2.Cu")
		(net "UV_HIGH_SET")
	)
	(segment
		(start 405.666448 -67.235324)
		(end 405.666448 -67.251326)
		(width 0.089408)
		(layer "In2.Cu")
		(net "UV_HIGH_SET")
	)
	(segment
		(start 402.172424 -73.442576)
		(end 400.825716 -73.442576)
		(width 0.089408)
		(layer "In2.Cu")
		(net "UV_HIGH_SET")
	)
	(segment
		(start 359.16616 -144.30248)
		(end 354.437696 -144.30248)
		(width 0.089408)
		(layer "In4.Cu")
		(net "UV_HIGH_SET")
	)
	(segment
		(start 359.366058 -144.502378)
		(end 359.16616 -144.30248)
		(width 0.089408)
		(layer "In4.Cu")
		(net "UV_HIGH_SET")
	)
	(segment
		(start 413.442658 -86.21014)
		(end 413.790892 -85.861906)
		(width 0.089408)
		(layer "In4.Cu")
		(net "UV_HIGH_SET")
	)
	(segment
		(start 400.961606 -86.875366)
		(end 401.225766 -87.139526)
		(width 0.089408)
		(layer "In4.Cu")
		(net "UV_HIGH_SET")
	)
	(segment
		(start 354.437696 -144.30248)
		(end 351.552256 -141.41704)
		(width 0.089408)
		(layer "In4.Cu")
		(net "UV_HIGH_SET")
	)
	(segment
		(start 361.571032 -144.502378)
		(end 359.366058 -144.502378)
		(width 0.089408)
		(layer "In4.Cu")
		(net "UV_HIGH_SET")
	)
	(segment
		(start 386.76072 -145.331942)
		(end 384.902202 -147.19046)
		(width 0.089408)
		(layer "In4.Cu")
		(net "UV_HIGH_SET")
	)
	(segment
		(start 336.20202 -126.02718)
		(end 332.469744 -122.294904)
		(width 0.089408)
		(layer "In4.Cu")
		(net "UV_HIGH_SET")
	)
	(segment
		(start 403.11959 -86.267036)
		(end 404.498048 -86.267036)
		(width 0.089408)
		(layer "In4.Cu")
		(net "UV_HIGH_SET")
	)
	(segment
		(start 392.111738 -148.322792)
		(end 389.120888 -145.331942)
		(width 0.089408)
		(layer "In4.Cu")
		(net "UV_HIGH_SET")
	)
	(segment
		(start 336.20202 -131.23418)
		(end 336.20202 -126.02718)
		(width 0.089408)
		(layer "In4.Cu")
		(net "UV_HIGH_SET")
	)
	(segment
		(start 408.622246 -87.785194)
		(end 409.420822 -87.785194)
		(width 0.089408)
		(layer "In4.Cu")
		(net "UV_HIGH_SET")
	)
	(segment
		(start 351.552256 -141.41704)
		(end 343.629488 -141.41704)
		(width 0.089408)
		(layer "In4.Cu")
		(net "UV_HIGH_SET")
	)
	(segment
		(start 332.469744 -122.043698)
		(end 331.387958 -120.961912)
		(width 0.089408)
		(layer "In4.Cu")
		(net "UV_HIGH_SET")
	)
	(segment
		(start 416.568636 -94.172024)
		(end 416.56 -94.18066)
		(width 0.089408)
		(layer "In4.Cu")
		(net "UV_HIGH_SET")
	)
	(segment
		(start 404.013416 -150.826216)
		(end 401.850352 -150.826216)
		(width 0.089408)
		(layer "In4.Cu")
		(net "UV_HIGH_SET")
	)
	(segment
		(start 409.420822 -87.785194)
		(end 410.114242 -88.478614)
		(width 0.089408)
		(layer "In4.Cu")
		(net "UV_HIGH_SET")
	)
	(segment
		(start 400.961606 -86.501478)
		(end 400.961606 -86.875366)
		(width 0.089408)
		(layer "In4.Cu")
		(net "UV_HIGH_SET")
	)
	(segment
		(start 401.59686 -86.05393)
		(end 401.409154 -86.05393)
		(width 0.089408)
		(layer "In4.Cu")
		(net "UV_HIGH_SET")
	)
	(segment
		(start 369.186714 -147.978368)
		(end 366.544352 -147.978368)
		(width 0.089408)
		(layer "In4.Cu")
		(net "UV_HIGH_SET")
	)
	(segment
		(start 413.442658 -86.212172)
		(end 413.442658 -86.21014)
		(width 0.089408)
		(layer "In4.Cu")
		(net "UV_HIGH_SET")
	)
	(segment
		(start 384.902202 -147.19046)
		(end 372.834916 -147.19046)
		(width 0.089408)
		(layer "In4.Cu")
		(net "UV_HIGH_SET")
	)
	(segment
		(start 363.903768 -145.337784)
		(end 362.406438 -145.337784)
		(width 0.089408)
		(layer "In4.Cu")
		(net "UV_HIGH_SET")
	)
	(segment
		(start 401.850098 -150.82647)
		(end 401.553934 -150.82647)
		(width 0.089408)
		(layer "In4.Cu")
		(net "UV_HIGH_SET")
	)
	(segment
		(start 404.5331 -154.559)
		(end 404.5331 -151.3459)
		(width 0.089408)
		(layer "In4.Cu")
		(net "UV_HIGH_SET")
	)
	(segment
		(start 417.950904 -93.359224)
		(end 417.138104 -94.172024)
		(width 0.089408)
		(layer "In4.Cu")
		(net "UV_HIGH_SET")
	)
	(segment
		(start 410.114242 -88.478614)
		(end 411.176216 -88.478614)
		(width 0.089408)
		(layer "In4.Cu")
		(net "UV_HIGH_SET")
	)
	(segment
		(start 389.120888 -145.331942)
		(end 386.76072 -145.331942)
		(width 0.089408)
		(layer "In4.Cu")
		(net "UV_HIGH_SET")
	)
	(segment
		(start 417.281106 -85.861906)
		(end 417.950904 -86.531704)
		(width 0.089408)
		(layer "In4.Cu")
		(net "UV_HIGH_SET")
	)
	(segment
		(start 331.387958 -120.961912)
		(end 330.51496 -120.961912)
		(width 0.089408)
		(layer "In4.Cu")
		(net "UV_HIGH_SET")
	)
	(segment
		(start 417.138104 -94.172024)
		(end 416.568636 -94.172024)
		(width 0.089408)
		(layer "In4.Cu")
		(net "UV_HIGH_SET")
	)
	(segment
		(start 334.447896 -136.947656)
		(end 334.5688 -136.826752)
		(width 0.089408)
		(layer "In4.Cu")
		(net "UV_HIGH_SET")
	)
	(segment
		(start 334.5688 -136.826752)
		(end 334.5688 -132.8674)
		(width 0.089408)
		(layer "In4.Cu")
		(net "UV_HIGH_SET")
	)
	(segment
		(start 371.295676 -145.869406)
		(end 369.186714 -147.978368)
		(width 0.089408)
		(layer "In4.Cu")
		(net "UV_HIGH_SET")
	)
	(segment
		(start 453.885808 -10.33526)
		(end 454.496424 -9.724644)
		(width 0.089408)
		(layer "In4.Cu")
		(net "UV_HIGH_SET")
	)
	(segment
		(start 416.56 -94.18066)
		(end 416.560254 -94.18066)
		(width 0.089408)
		(layer "In4.Cu")
		(net "UV_HIGH_SET")
	)
	(segment
		(start 407.928826 -88.478614)
		(end 408.622246 -87.785194)
		(width 0.089408)
		(layer "In4.Cu")
		(net "UV_HIGH_SET")
	)
	(segment
		(start 401.553934 -150.82647)
		(end 400.30146 -149.573996)
		(width 0.089408)
		(layer "In4.Cu")
		(net "UV_HIGH_SET")
	)
	(segment
		(start 404.498048 -86.267036)
		(end 406.709626 -88.478614)
		(width 0.089408)
		(layer "In4.Cu")
		(net "UV_HIGH_SET")
	)
	(segment
		(start 401.409154 -86.05393)
		(end 400.961606 -86.501478)
		(width 0.089408)
		(layer "In4.Cu")
		(net "UV_HIGH_SET")
	)
	(segment
		(start 447.706496 -6.549644)
		(end 448.193922 -6.549644)
		(width 0.089408)
		(layer "In4.Cu")
		(net "UV_HIGH_SET")
	)
	(segment
		(start 400.30146 -149.573996)
		(end 397.105124 -149.573996)
		(width 0.089408)
		(layer "In4.Cu")
		(net "UV_HIGH_SET")
	)
	(segment
		(start 343.629488 -141.41704)
		(end 341.605108 -139.39266)
		(width 0.089408)
		(layer "In4.Cu")
		(net "UV_HIGH_SET")
	)
	(segment
		(start 341.605108 -139.39266)
		(end 336.39506 -139.39266)
		(width 0.089408)
		(layer "In4.Cu")
		(net "UV_HIGH_SET")
	)
	(segment
		(start 413.790892 -85.861906)
		(end 417.281106 -85.861906)
		(width 0.089408)
		(layer "In4.Cu")
		(net "UV_HIGH_SET")
	)
	(segment
		(start 395.85392 -148.322792)
		(end 392.111738 -148.322792)
		(width 0.089408)
		(layer "In4.Cu")
		(net "UV_HIGH_SET")
	)
	(segment
		(start 451.979538 -10.33526)
		(end 453.885808 -10.33526)
		(width 0.089408)
		(layer "In4.Cu")
		(net "UV_HIGH_SET")
	)
	(segment
		(start 446.809622 -2.615438)
		(end 445.81445 -3.61061)
		(width 0.089408)
		(layer "In4.Cu")
		(net "UV_HIGH_SET")
	)
	(segment
		(start 406.709626 -88.478614)
		(end 407.928826 -88.478614)
		(width 0.089408)
		(layer "In4.Cu")
		(net "UV_HIGH_SET")
	)
	(segment
		(start 397.105124 -149.573996)
		(end 395.85392 -148.322792)
		(width 0.089408)
		(layer "In4.Cu")
		(net "UV_HIGH_SET")
	)
	(segment
		(start 446.809622 -2.36474)
		(end 446.809622 -2.615438)
		(width 0.089408)
		(layer "In4.Cu")
		(net "UV_HIGH_SET")
	)
	(segment
		(start 336.39506 -139.39266)
		(end 334.447896 -137.445496)
		(width 0.089408)
		(layer "In4.Cu")
		(net "UV_HIGH_SET")
	)
	(segment
		(start 445.81445 -3.61061)
		(end 445.81445 -5.296662)
		(width 0.089408)
		(layer "In4.Cu")
		(net "UV_HIGH_SET")
	)
	(segment
		(start 332.469744 -122.294904)
		(end 332.469744 -122.043698)
		(width 0.089408)
		(layer "In4.Cu")
		(net "UV_HIGH_SET")
	)
	(segment
		(start 401.850352 -150.826216)
		(end 401.850098 -150.82647)
		(width 0.089408)
		(layer "In4.Cu")
		(net "UV_HIGH_SET")
	)
	(segment
		(start 371.513862 -145.869406)
		(end 371.295676 -145.869406)
		(width 0.089408)
		(layer "In4.Cu")
		(net "UV_HIGH_SET")
	)
	(segment
		(start 366.544352 -147.978368)
		(end 363.903768 -145.337784)
		(width 0.089408)
		(layer "In4.Cu")
		(net "UV_HIGH_SET")
	)
	(segment
		(start 448.193922 -6.549644)
		(end 451.979538 -10.33526)
		(width 0.089408)
		(layer "In4.Cu")
		(net "UV_HIGH_SET")
	)
	(segment
		(start 446.824862 -5.66801)
		(end 447.706496 -6.549644)
		(width 0.089408)
		(layer "In4.Cu")
		(net "UV_HIGH_SET")
	)
	(segment
		(start 404.5331 -151.3459)
		(end 404.013416 -150.826216)
		(width 0.089408)
		(layer "In4.Cu")
		(net "UV_HIGH_SET")
	)
	(segment
		(start 372.834916 -147.19046)
		(end 371.513862 -145.869406)
		(width 0.089408)
		(layer "In4.Cu")
		(net "UV_HIGH_SET")
	)
	(segment
		(start 446.185798 -5.66801)
		(end 446.824862 -5.66801)
		(width 0.089408)
		(layer "In4.Cu")
		(net "UV_HIGH_SET")
	)
	(segment
		(start 411.176216 -88.478614)
		(end 413.442658 -86.212172)
		(width 0.089408)
		(layer "In4.Cu")
		(net "UV_HIGH_SET")
	)
	(segment
		(start 445.81445 -5.296662)
		(end 446.185798 -5.66801)
		(width 0.089408)
		(layer "In4.Cu")
		(net "UV_HIGH_SET")
	)
	(segment
		(start 403.99462 -155.09748)
		(end 404.5331 -154.559)
		(width 0.089408)
		(layer "In4.Cu")
		(net "UV_HIGH_SET")
	)
	(segment
		(start 334.5688 -132.8674)
		(end 336.20202 -131.23418)
		(width 0.089408)
		(layer "In4.Cu")
		(net "UV_HIGH_SET")
	)
	(segment
		(start 334.447896 -137.445496)
		(end 334.447896 -136.947656)
		(width 0.089408)
		(layer "In4.Cu")
		(net "UV_HIGH_SET")
	)
	(segment
		(start 362.406438 -145.337784)
		(end 361.571032 -144.502378)
		(width 0.089408)
		(layer "In4.Cu")
		(net "UV_HIGH_SET")
	)
	(segment
		(start 402.2471 -87.139526)
		(end 403.11959 -86.267036)
		(width 0.089408)
		(layer "In4.Cu")
		(net "UV_HIGH_SET")
	)
	(segment
		(start 417.950904 -86.531704)
		(end 417.950904 -93.359224)
		(width 0.089408)
		(layer "In4.Cu")
		(net "UV_HIGH_SET")
	)
	(segment
		(start 401.225766 -87.139526)
		(end 402.2471 -87.139526)
		(width 0.089408)
		(layer "In4.Cu")
		(net "UV_HIGH_SET")
	)
	(segment
		(start 21.744686 -99.121722)
		(end 23.326344 -100.70338)
		(width 0.089408)
		(layer "In9.Cu")
		(net "UV_HIGH_SET")
	)
	(segment
		(start 418.989764 -156.861764)
		(end 421.632634 -156.861764)
		(width 0.089408)
		(layer "In9.Cu")
		(net "UV_HIGH_SET")
	)
	(segment
		(start 413.38119 -47.349156)
		(end 413.7914 -46.938946)
		(width 0.089408)
		(layer "In9.Cu")
		(net "UV_HIGH_SET")
	)
	(segment
		(start 423.135806 -137.764774)
		(end 416.1282 -130.757168)
		(width 0.089408)
		(layer "In9.Cu")
		(net "UV_HIGH_SET")
	)
	(segment
		(start 264.074656 -122.08764)
		(end 307.058568 -122.08764)
		(width 0.089408)
		(layer "In9.Cu")
		(net "UV_HIGH_SET")
	)
	(segment
		(start 39.68496 -121.4628)
		(end 147.606004 -121.4628)
		(width 0.089408)
		(layer "In9.Cu")
		(net "UV_HIGH_SET")
	)
	(segment
		(start 222.757238 -122.316494)
		(end 223.053402 -122.316494)
		(width 0.089408)
		(layer "In9.Cu")
		(net "UV_HIGH_SET")
	)
	(segment
		(start 412.552134 -47.673006)
		(end 412.875984 -47.349156)
		(width 0.089408)
		(layer "In9.Cu")
		(net "UV_HIGH_SET")
	)
	(segment
		(start 180.39207 -123.281186)
		(end 181.894988 -124.784104)
		(width 0.089408)
		(layer "In9.Cu")
		(net "UV_HIGH_SET")
	)
	(segment
		(start 21.744686 -97.849436)
		(end 21.744686 -99.121722)
		(width 0.089408)
		(layer "In9.Cu")
		(net "UV_HIGH_SET")
	)
	(segment
		(start 417.35121 -125.2982)
		(end 417.751514 -125.698504)
		(width 0.089408)
		(layer "In9.Cu")
		(net "UV_HIGH_SET")
	)
	(segment
		(start 185.992516 -124.784104)
		(end 187.00242 -123.7742)
		(width 0.089408)
		(layer "In9.Cu")
		(net "UV_HIGH_SET")
	)
	(segment
		(start 319.660778 -125.73)
		(end 321.14363 -124.247148)
		(width 0.089408)
		(layer "In9.Cu")
		(net "UV_HIGH_SET")
	)
	(segment
		(start 406.69972 -62.383162)
		(end 406.69972 -53.43144)
		(width 0.089408)
		(layer "In9.Cu")
		(net "UV_HIGH_SET")
	)
	(segment
		(start 172.129704 -125.459744)
		(end 174.308262 -123.281186)
		(width 0.089408)
		(layer "In9.Cu")
		(net "UV_HIGH_SET")
	)
	(segment
		(start 408.264614 -154.4447)
		(end 410.43352 -154.4447)
		(width 0.089408)
		(layer "In9.Cu")
		(net "UV_HIGH_SET")
	)
	(segment
		(start 223.053656 -122.316748)
		(end 244.433598 -122.316748)
		(width 0.089408)
		(layer "In9.Cu")
		(net "UV_HIGH_SET")
	)
	(segment
		(start 413.7914 -46.938946)
		(end 413.7914 -46.380908)
		(width 0.089408)
		(layer "In9.Cu")
		(net "UV_HIGH_SET")
	)
	(segment
		(start 432.507136 -141.405356)
		(end 424.501564 -141.405356)
		(width 0.089408)
		(layer "In9.Cu")
		(net "UV_HIGH_SET")
	)
	(segment
		(start 223.053402 -122.316494)
		(end 223.053656 -122.316748)
		(width 0.089408)
		(layer "In9.Cu")
		(net "UV_HIGH_SET")
	)
	(segment
		(start 23.326344 -109.16031)
		(end 25.091898 -110.925864)
		(width 0.089408)
		(layer "In9.Cu")
		(net "UV_HIGH_SET")
	)
	(segment
		(start 418.080952 -42.743882)
		(end 418.690044 -42.13479)
		(width 0.089408)
		(layer "In9.Cu")
		(net "UV_HIGH_SET")
	)
	(segment
		(start 161.111438 -126.743206)
		(end 163.733988 -124.120656)
		(width 0.089408)
		(layer "In9.Cu")
		(net "UV_HIGH_SET")
	)
	(segment
		(start 431.455322 -147.288504)
		(end 432.293268 -147.288504)
		(width 0.089408)
		(layer "In9.Cu")
		(net "UV_HIGH_SET")
	)
	(segment
		(start 406.540208 -66.365374)
		(end 406.544018 -66.365374)
		(width 0.089408)
		(layer "In9.Cu")
		(net "UV_HIGH_SET")
	)
	(segment
		(start 29.148024 -110.925864)
		(end 39.68496 -121.4628)
		(width 0.089408)
		(layer "In9.Cu")
		(net "UV_HIGH_SET")
	)
	(segment
		(start 412.875984 -47.349156)
		(end 413.38119 -47.349156)
		(width 0.089408)
		(layer "In9.Cu")
		(net "UV_HIGH_SET")
	)
	(segment
		(start 434.7337 -144.848072)
		(end 434.7337 -143.63192)
		(width 0.089408)
		(layer "In9.Cu")
		(net "UV_HIGH_SET")
	)
	(segment
		(start 416.56889 -125.2982)
		(end 417.35121 -125.2982)
		(width 0.089408)
		(layer "In9.Cu")
		(net "UV_HIGH_SET")
	)
	(segment
		(start 416.426142 -154.298142)
		(end 418.989764 -156.861764)
		(width 0.089408)
		(layer "In9.Cu")
		(net "UV_HIGH_SET")
	)
	(segment
		(start 410.43352 -154.4447)
		(end 410.525722 -154.444192)
		(width 0.089408)
		(layer "In9.Cu")
		(net "UV_HIGH_SET")
	)
	(segment
		(start 415.891726 -130.465068)
		(end 415.891726 -129.837434)
		(width 0.089408)
		(layer "In9.Cu")
		(net "UV_HIGH_SET")
	)
	(segment
		(start 411.628082 -47.673006)
		(end 412.552134 -47.673006)
		(width 0.089408)
		(layer "In9.Cu")
		(net "UV_HIGH_SET")
	)
	(segment
		(start 421.632634 -156.861764)
		(end 423.360596 -155.133802)
		(width 0.089408)
		(layer "In9.Cu")
		(net "UV_HIGH_SET")
	)
	(segment
		(start 423.352976 -152.256744)
		(end 423.352976 -151.245824)
		(width 0.089408)
		(layer "In9.Cu")
		(net "UV_HIGH_SET")
	)
	(segment
		(start 409.876752 -50.254408)
		(end 409.876752 -49.424336)
		(width 0.089408)
		(layer "In9.Cu")
		(net "UV_HIGH_SET")
	)
	(segment
		(start 152.375108 -126.231904)
		(end 155.805378 -126.231904)
		(width 0.089408)
		(layer "In9.Cu")
		(net "UV_HIGH_SET")
	)
	(segment
		(start 406.544018 -66.365374)
		(end 407.089864 -65.819528)
		(width 0.089408)
		(layer "In9.Cu")
		(net "UV_HIGH_SET")
	)
	(segment
		(start 221.299532 -123.7742)
		(end 222.757238 -122.316494)
		(width 0.089408)
		(layer "In9.Cu")
		(net "UV_HIGH_SET")
	)
	(segment
		(start 167.344598 -125.459744)
		(end 172.129704 -125.459744)
		(width 0.089408)
		(layer "In9.Cu")
		(net "UV_HIGH_SET")
	)
	(segment
		(start 417.751514 -126.591822)
		(end 419.339776 -128.180084)
		(width 0.089408)
		(layer "In9.Cu")
		(net "UV_HIGH_SET")
	)
	(segment
		(start 417.751514 -125.698504)
		(end 417.751514 -126.591822)
		(width 0.089408)
		(layer "In9.Cu")
		(net "UV_HIGH_SET")
	)
	(segment
		(start 406.854152 -63.78448)
		(end 406.854152 -62.537594)
		(width 0.089408)
		(layer "In9.Cu")
		(net "UV_HIGH_SET")
	)
	(segment
		(start 423.360596 -155.133802)
		(end 423.360596 -152.264364)
		(width 0.089408)
		(layer "In9.Cu")
		(net "UV_HIGH_SET")
	)
	(segment
		(start 307.058568 -122.08764)
		(end 310.700928 -125.73)
		(width 0.089408)
		(layer "In9.Cu")
		(net "UV_HIGH_SET")
	)
	(segment
		(start 423.6212 -150.9776)
		(end 423.6212 -147.895056)
		(width 0.089408)
		(layer "In9.Cu")
		(net "UV_HIGH_SET")
	)
	(segment
		(start 405.963628 -154.778456)
		(end 406.759156 -155.573984)
		(width 0.089408)
		(layer "In9.Cu")
		(net "UV_HIGH_SET")
	)
	(segment
		(start 181.894988 -124.784104)
		(end 185.992516 -124.784104)
		(width 0.089408)
		(layer "In9.Cu")
		(net "UV_HIGH_SET")
	)
	(segment
		(start 323.219318 -124.247148)
		(end 326.504554 -120.961912)
		(width 0.089408)
		(layer "In9.Cu")
		(net "UV_HIGH_SET")
	)
	(segment
		(start 430.865026 -146.698208)
		(end 431.455322 -147.288504)
		(width 0.089408)
		(layer "In9.Cu")
		(net "UV_HIGH_SET")
	)
	(segment
		(start 166.449756 -124.784104)
		(end 166.668958 -124.784104)
		(width 0.089408)
		(layer "In9.Cu")
		(net "UV_HIGH_SET")
	)
	(segment
		(start 406.69972 -53.43144)
		(end 409.876752 -50.254408)
		(width 0.089408)
		(layer "In9.Cu")
		(net "UV_HIGH_SET")
	)
	(segment
		(start 432.293268 -147.288504)
		(end 434.7337 -144.848072)
		(width 0.089408)
		(layer "In9.Cu")
		(net "UV_HIGH_SET")
	)
	(segment
		(start 419.339776 -128.180084)
		(end 419.339776 -128.312164)
		(width 0.089408)
		(layer "In9.Cu")
		(net "UV_HIGH_SET")
	)
	(segment
		(start 406.854152 -62.537594)
		(end 406.69972 -62.383162)
		(width 0.089408)
		(layer "In9.Cu")
		(net "UV_HIGH_SET")
	)
	(segment
		(start 165.786308 -124.120656)
		(end 166.449756 -124.784104)
		(width 0.089408)
		(layer "In9.Cu")
		(net "UV_HIGH_SET")
	)
	(segment
		(start 155.805378 -126.231904)
		(end 156.31668 -126.743206)
		(width 0.089408)
		(layer "In9.Cu")
		(net "UV_HIGH_SET")
	)
	(segment
		(start 410.671772 -154.298142)
		(end 416.426142 -154.298142)
		(width 0.089408)
		(layer "In9.Cu")
		(net "UV_HIGH_SET")
	)
	(segment
		(start 415.891726 -129.837434)
		(end 415.883598 -129.829306)
		(width 0.089408)
		(layer "In9.Cu")
		(net "UV_HIGH_SET")
	)
	(segment
		(start 166.668958 -124.784104)
		(end 167.344598 -125.459744)
		(width 0.089408)
		(layer "In9.Cu")
		(net "UV_HIGH_SET")
	)
	(segment
		(start 413.7914 -46.380908)
		(end 417.428426 -42.743882)
		(width 0.089408)
		(layer "In9.Cu")
		(net "UV_HIGH_SET")
	)
	(segment
		(start 416.1282 -130.757168)
		(end 416.1282 -130.701542)
		(width 0.089408)
		(layer "In9.Cu")
		(net "UV_HIGH_SET")
	)
	(segment
		(start 156.31668 -126.743206)
		(end 161.111438 -126.743206)
		(width 0.089408)
		(layer "In9.Cu")
		(net "UV_HIGH_SET")
	)
	(segment
		(start 423.352976 -151.245824)
		(end 423.6212 -150.9776)
		(width 0.089408)
		(layer "In9.Cu")
		(net "UV_HIGH_SET")
	)
	(segment
		(start 407.089864 -64.020192)
		(end 406.854152 -63.78448)
		(width 0.089408)
		(layer "In9.Cu")
		(net "UV_HIGH_SET")
	)
	(segment
		(start 423.135806 -140.039598)
		(end 423.135806 -137.764774)
		(width 0.089408)
		(layer "In9.Cu")
		(net "UV_HIGH_SET")
	)
	(segment
		(start 263.23163 -122.930666)
		(end 264.074656 -122.08764)
		(width 0.089408)
		(layer "In9.Cu")
		(net "UV_HIGH_SET")
	)
	(segment
		(start 310.700928 -125.73)
		(end 319.660778 -125.73)
		(width 0.089408)
		(layer "In9.Cu")
		(net "UV_HIGH_SET")
	)
	(segment
		(start 407.133044 -155.573984)
		(end 408.26182 -154.445208)
		(width 0.089408)
		(layer "In9.Cu")
		(net "UV_HIGH_SET")
	)
	(segment
		(start 326.504554 -120.961912)
		(end 330.51496 -120.961912)
		(width 0.089408)
		(layer "In9.Cu")
		(net "UV_HIGH_SET")
	)
	(segment
		(start 423.6212 -147.895056)
		(end 424.818048 -146.698208)
		(width 0.089408)
		(layer "In9.Cu")
		(net "UV_HIGH_SET")
	)
	(segment
		(start 187.00242 -123.7742)
		(end 221.299532 -123.7742)
		(width 0.089408)
		(layer "In9.Cu")
		(net "UV_HIGH_SET")
	)
	(segment
		(start 403.99462 -155.09748)
		(end 404.313644 -154.778456)
		(width 0.089408)
		(layer "In9.Cu")
		(net "UV_HIGH_SET")
	)
	(segment
		(start 424.818048 -146.698208)
		(end 430.865026 -146.698208)
		(width 0.089408)
		(layer "In9.Cu")
		(net "UV_HIGH_SET")
	)
	(segment
		(start 406.759156 -155.573984)
		(end 407.133044 -155.573984)
		(width 0.089408)
		(layer "In9.Cu")
		(net "UV_HIGH_SET")
	)
	(segment
		(start 244.433598 -122.316748)
		(end 245.047516 -122.930666)
		(width 0.089408)
		(layer "In9.Cu")
		(net "UV_HIGH_SET")
	)
	(segment
		(start 147.606004 -121.4628)
		(end 152.375108 -126.231904)
		(width 0.089408)
		(layer "In9.Cu")
		(net "UV_HIGH_SET")
	)
	(segment
		(start 321.14363 -124.247148)
		(end 323.219318 -124.247148)
		(width 0.089408)
		(layer "In9.Cu")
		(net "UV_HIGH_SET")
	)
	(segment
		(start 245.047516 -122.930666)
		(end 263.23163 -122.930666)
		(width 0.089408)
		(layer "In9.Cu")
		(net "UV_HIGH_SET")
	)
	(segment
		(start 25.091898 -110.925864)
		(end 29.148024 -110.925864)
		(width 0.089408)
		(layer "In9.Cu")
		(net "UV_HIGH_SET")
	)
	(segment
		(start 424.501564 -141.405356)
		(end 423.135806 -140.039598)
		(width 0.089408)
		(layer "In9.Cu")
		(net "UV_HIGH_SET")
	)
	(segment
		(start 434.7337 -143.63192)
		(end 432.507136 -141.405356)
		(width 0.089408)
		(layer "In9.Cu")
		(net "UV_HIGH_SET")
	)
	(segment
		(start 415.883598 -125.983492)
		(end 416.56889 -125.2982)
		(width 0.089408)
		(layer "In9.Cu")
		(net "UV_HIGH_SET")
	)
	(segment
		(start 408.26182 -154.445208)
		(end 408.264614 -154.4447)
		(width 0.089408)
		(layer "In9.Cu")
		(net "UV_HIGH_SET")
	)
	(segment
		(start 174.308262 -123.281186)
		(end 180.39207 -123.281186)
		(width 0.089408)
		(layer "In9.Cu")
		(net "UV_HIGH_SET")
	)
	(segment
		(start 163.733988 -124.120656)
		(end 165.786308 -124.120656)
		(width 0.089408)
		(layer "In9.Cu")
		(net "UV_HIGH_SET")
	)
	(segment
		(start 423.360596 -152.264364)
		(end 423.352976 -152.256744)
		(width 0.089408)
		(layer "In9.Cu")
		(net "UV_HIGH_SET")
	)
	(segment
		(start 409.876752 -49.424336)
		(end 411.628082 -47.673006)
		(width 0.089408)
		(layer "In9.Cu")
		(net "UV_HIGH_SET")
	)
	(segment
		(start 404.313644 -154.778456)
		(end 405.963628 -154.778456)
		(width 0.089408)
		(layer "In9.Cu")
		(net "UV_HIGH_SET")
	)
	(segment
		(start 416.1282 -130.701542)
		(end 415.891726 -130.465068)
		(width 0.089408)
		(layer "In9.Cu")
		(net "UV_HIGH_SET")
	)
	(segment
		(start 407.089864 -65.819528)
		(end 407.089864 -64.020192)
		(width 0.089408)
		(layer "In9.Cu")
		(net "UV_HIGH_SET")
	)
	(segment
		(start 410.525722 -154.444192)
		(end 410.671772 -154.298142)
		(width 0.089408)
		(layer "In9.Cu")
		(net "UV_HIGH_SET")
	)
	(segment
		(start 415.883598 -129.829306)
		(end 415.883598 -125.983492)
		(width 0.089408)
		(layer "In9.Cu")
		(net "UV_HIGH_SET")
	)
	(segment
		(start 23.326344 -100.70338)
		(end 23.326344 -109.16031)
		(width 0.089408)
		(layer "In9.Cu")
		(net "UV_HIGH_SET")
	)
	(segment
		(start 417.428426 -42.743882)
		(end 418.080952 -42.743882)
		(width 0.089408)
		(layer "In9.Cu")
		(net "UV_HIGH_SET")
	)
	(segment
		(start 418.29228 -19.90852)
		(end 418.985446 -19.215354)
		(width 0.089408)
		(layer "In11.Cu")
		(net "UV_HIGH_SET")
	)
	(segment
		(start 408.695652 -37.999162)
		(end 408.985466 -37.709348)
		(width 0.089408)
		(layer "In11.Cu")
		(net "UV_HIGH_SET")
	)
	(segment
		(start 411.100016 -30.630622)
		(end 411.100016 -29.960824)
		(width 0.089408)
		(layer "In11.Cu")
		(net "UV_HIGH_SET")
	)
	(segment
		(start 409.245562 -37.709348)
		(end 409.250642 -37.704268)
		(width 0.089408)
		(layer "In11.Cu")
		(net "UV_HIGH_SET")
	)
	(segment
		(start 410.032454 -32.122364)
		(end 410.032708 -32.122364)
		(width 0.089408)
		(layer "In11.Cu")
		(net "UV_HIGH_SET")
	)
	(segment
		(start 412.654496 -20.958048)
		(end 413.602424 -20.958048)
		(width 0.089408)
		(layer "In11.Cu")
		(net "UV_HIGH_SET")
	)
	(segment
		(start 437.24703 -17.379696)
		(end 437.907938 -18.040604)
		(width 0.089408)
		(layer "In11.Cu")
		(net "UV_HIGH_SET")
	)
	(segment
		(start 423.485056 -19.215354)
		(end 425.145454 -17.554956)
		(width 0.089408)
		(layer "In11.Cu")
		(net "UV_HIGH_SET")
	)
	(segment
		(start 414.651952 -19.90852)
		(end 418.29228 -19.90852)
		(width 0.089408)
		(layer "In11.Cu")
		(net "UV_HIGH_SET")
	)
	(segment
		(start 408.985466 -37.709348)
		(end 409.245562 -37.709348)
		(width 0.089408)
		(layer "In11.Cu")
		(net "UV_HIGH_SET")
	)
	(segment
		(start 409.513532 -36.372292)
		(end 409.26893 -36.12769)
		(width 0.089408)
		(layer "In11.Cu")
		(net "UV_HIGH_SET")
	)
	(segment
		(start 435.524656 -17.379696)
		(end 437.24703 -17.379696)
		(width 0.089408)
		(layer "In11.Cu")
		(net "UV_HIGH_SET")
	)
	(segment
		(start 408.932634 -36.12769)
		(end 408.664664 -35.85972)
		(width 0.089408)
		(layer "In11.Cu")
		(net "UV_HIGH_SET")
	)
	(segment
		(start 410.071316 -38.541706)
		(end 408.935174 -38.541706)
		(width 0.089408)
		(layer "In11.Cu")
		(net "UV_HIGH_SET")
	)
	(segment
		(start 413.602424 -20.958048)
		(end 414.651952 -19.90852)
		(width 0.089408)
		(layer "In11.Cu")
		(net "UV_HIGH_SET")
	)
	(segment
		(start 408.935174 -38.541706)
		(end 408.695652 -38.302184)
		(width 0.089408)
		(layer "In11.Cu")
		(net "UV_HIGH_SET")
	)
	(segment
		(start 414.430718 -40.93845)
		(end 413.006032 -40.93845)
		(width 0.089408)
		(layer "In11.Cu")
		(net "UV_HIGH_SET")
	)
	(segment
		(start 410.252164 -31.902908)
		(end 410.252164 -31.902654)
		(width 0.089408)
		(layer "In11.Cu")
		(net "UV_HIGH_SET")
	)
	(segment
		(start 408.664664 -33.8328)
		(end 409.50261 -32.994854)
		(width 0.089408)
		(layer "In11.Cu")
		(net "UV_HIGH_SET")
	)
	(segment
		(start 443.774576 -17.304004)
		(end 444.82258 -16.256)
		(width 0.089408)
		(layer "In11.Cu")
		(net "UV_HIGH_SET")
	)
	(segment
		(start 418.690044 -42.13479)
		(end 418.31387 -41.758616)
		(width 0.089408)
		(layer "In11.Cu")
		(net "UV_HIGH_SET")
	)
	(segment
		(start 409.327096 -37.704268)
		(end 409.513532 -37.517832)
		(width 0.089408)
		(layer "In11.Cu")
		(net "UV_HIGH_SET")
	)
	(segment
		(start 412.976822 -40.90924)
		(end 412.934658 -40.90924)
		(width 0.089408)
		(layer "In11.Cu")
		(net "UV_HIGH_SET")
	)
	(segment
		(start 410.488892 -29.718)
		(end 410.302202 -29.53131)
		(width 0.089408)
		(layer "In11.Cu")
		(net "UV_HIGH_SET")
	)
	(segment
		(start 410.302202 -26.64079)
		(end 409.502356 -25.840944)
		(width 0.089408)
		(layer "In11.Cu")
		(net "UV_HIGH_SET")
	)
	(segment
		(start 452.34225 -11.878818)
		(end 454.496424 -9.724644)
		(width 0.089408)
		(layer "In11.Cu")
		(net "UV_HIGH_SET")
	)
	(segment
		(start 415.250884 -41.758616)
		(end 414.430718 -40.93845)
		(width 0.089408)
		(layer "In11.Cu")
		(net "UV_HIGH_SET")
	)
	(segment
		(start 444.82258 -16.256)
		(end 445.74206 -16.256)
		(width 0.089408)
		(layer "In11.Cu")
		(net "UV_HIGH_SET")
	)
	(segment
		(start 418.31387 -41.758616)
		(end 415.250884 -41.758616)
		(width 0.089408)
		(layer "In11.Cu")
		(net "UV_HIGH_SET")
	)
	(segment
		(start 409.619958 -32.135318)
		(end 410.0195 -32.135318)
		(width 0.089408)
		(layer "In11.Cu")
		(net "UV_HIGH_SET")
	)
	(segment
		(start 410.302202 -29.53131)
		(end 410.302202 -26.64079)
		(width 0.089408)
		(layer "In11.Cu")
		(net "UV_HIGH_SET")
	)
	(segment
		(start 410.610558 -40.09644)
		(end 410.291788 -39.77767)
		(width 0.089408)
		(layer "In11.Cu")
		(net "UV_HIGH_SET")
	)
	(segment
		(start 409.50261 -32.252666)
		(end 409.619958 -32.135318)
		(width 0.089408)
		(layer "In11.Cu")
		(net "UV_HIGH_SET")
	)
	(segment
		(start 438.6707 -18.040604)
		(end 439.4073 -17.304004)
		(width 0.089408)
		(layer "In11.Cu")
		(net "UV_HIGH_SET")
	)
	(segment
		(start 412.415736 -40.09644)
		(end 410.610558 -40.09644)
		(width 0.089408)
		(layer "In11.Cu")
		(net "UV_HIGH_SET")
	)
	(segment
		(start 409.50261 -32.994854)
		(end 409.50261 -32.252666)
		(width 0.089408)
		(layer "In11.Cu")
		(net "UV_HIGH_SET")
	)
	(segment
		(start 410.291788 -38.762178)
		(end 410.071316 -38.541706)
		(width 0.089408)
		(layer "In11.Cu")
		(net "UV_HIGH_SET")
	)
	(segment
		(start 437.907938 -18.040604)
		(end 438.6707 -18.040604)
		(width 0.089408)
		(layer "In11.Cu")
		(net "UV_HIGH_SET")
	)
	(segment
		(start 445.74206 -16.256)
		(end 450.119242 -11.878818)
		(width 0.089408)
		(layer "In11.Cu")
		(net "UV_HIGH_SET")
	)
	(segment
		(start 410.368496 -20.199096)
		(end 411.895544 -20.199096)
		(width 0.089408)
		(layer "In11.Cu")
		(net "UV_HIGH_SET")
	)
	(segment
		(start 439.4073 -17.304004)
		(end 443.774576 -17.304004)
		(width 0.089408)
		(layer "In11.Cu")
		(net "UV_HIGH_SET")
	)
	(segment
		(start 412.934658 -40.90924)
		(end 412.715456 -40.690038)
		(width 0.089408)
		(layer "In11.Cu")
		(net "UV_HIGH_SET")
	)
	(segment
		(start 410.31541 -31.839408)
		(end 410.31541 -31.415228)
		(width 0.089408)
		(layer "In11.Cu")
		(net "UV_HIGH_SET")
	)
	(segment
		(start 409.502356 -25.840944)
		(end 409.502356 -21.065236)
		(width 0.089408)
		(layer "In11.Cu")
		(net "UV_HIGH_SET")
	)
	(segment
		(start 410.31541 -31.415228)
		(end 411.100016 -30.630622)
		(width 0.089408)
		(layer "In11.Cu")
		(net "UV_HIGH_SET")
	)
	(segment
		(start 425.145454 -17.554956)
		(end 435.349396 -17.554956)
		(width 0.089408)
		(layer "In11.Cu")
		(net "UV_HIGH_SET")
	)
	(segment
		(start 411.100016 -29.960824)
		(end 410.857192 -29.718)
		(width 0.089408)
		(layer "In11.Cu")
		(net "UV_HIGH_SET")
	)
	(segment
		(start 409.513532 -37.517832)
		(end 409.513532 -36.372292)
		(width 0.089408)
		(layer "In11.Cu")
		(net "UV_HIGH_SET")
	)
	(segment
		(start 410.291788 -39.77767)
		(end 410.291788 -38.762178)
		(width 0.089408)
		(layer "In11.Cu")
		(net "UV_HIGH_SET")
	)
	(segment
		(start 410.857192 -29.718)
		(end 410.488892 -29.718)
		(width 0.089408)
		(layer "In11.Cu")
		(net "UV_HIGH_SET")
	)
	(segment
		(start 409.26893 -36.12769)
		(end 408.932634 -36.12769)
		(width 0.089408)
		(layer "In11.Cu")
		(net "UV_HIGH_SET")
	)
	(segment
		(start 410.0195 -32.135318)
		(end 410.032454 -32.122364)
		(width 0.089408)
		(layer "In11.Cu")
		(net "UV_HIGH_SET")
	)
	(segment
		(start 435.349396 -17.554956)
		(end 435.524656 -17.379696)
		(width 0.089408)
		(layer "In11.Cu")
		(net "UV_HIGH_SET")
	)
	(segment
		(start 408.695652 -38.302184)
		(end 408.695652 -37.999162)
		(width 0.089408)
		(layer "In11.Cu")
		(net "UV_HIGH_SET")
	)
	(segment
		(start 409.502356 -21.065236)
		(end 410.368496 -20.199096)
		(width 0.089408)
		(layer "In11.Cu")
		(net "UV_HIGH_SET")
	)
	(segment
		(start 409.250642 -37.704268)
		(end 409.327096 -37.704268)
		(width 0.089408)
		(layer "In11.Cu")
		(net "UV_HIGH_SET")
	)
	(segment
		(start 412.715456 -40.39616)
		(end 412.415736 -40.09644)
		(width 0.089408)
		(layer "In11.Cu")
		(net "UV_HIGH_SET")
	)
	(segment
		(start 413.006032 -40.93845)
		(end 412.976822 -40.90924)
		(width 0.089408)
		(layer "In11.Cu")
		(net "UV_HIGH_SET")
	)
	(segment
		(start 410.252164 -31.902654)
		(end 410.31541 -31.839408)
		(width 0.089408)
		(layer "In11.Cu")
		(net "UV_HIGH_SET")
	)
	(segment
		(start 411.895544 -20.199096)
		(end 412.654496 -20.958048)
		(width 0.089408)
		(layer "In11.Cu")
		(net "UV_HIGH_SET")
	)
	(segment
		(start 412.715456 -40.690038)
		(end 412.715456 -40.39616)
		(width 0.089408)
		(layer "In11.Cu")
		(net "UV_HIGH_SET")
	)
	(segment
		(start 410.032708 -32.122364)
		(end 410.252164 -31.902908)
		(width 0.089408)
		(layer "In11.Cu")
		(net "UV_HIGH_SET")
	)
	(segment
		(start 450.119242 -11.878818)
		(end 452.34225 -11.878818)
		(width 0.089408)
		(layer "In11.Cu")
		(net "UV_HIGH_SET")
	)
	(segment
		(start 408.664664 -35.85972)
		(end 408.664664 -33.8328)
		(width 0.089408)
		(layer "In11.Cu")
		(net "UV_HIGH_SET")
	)
	(segment
		(start 418.985446 -19.215354)
		(end 423.485056 -19.215354)
		(width 0.089408)
		(layer "In11.Cu")
		(net "UV_HIGH_SET")
	)
	(segment
		(start 463.439256 -1.082802)
		(end 463.439256 -0.874014)
		(width 0.10795)
		(layer "F.Cu")
		(net "SPI_BMC_BT_WP0_N")
	)
	(segment
		(start 413.490156 -40.13454)
		(end 413.090106 -40.53459)
		(width 0.10795)
		(layer "F.Cu")
		(net "SPI_BMC_BT_WP0_N")
	)
	(segment
		(start 464.312254 -1.9558)
		(end 463.439256 -1.082802)
		(width 0.10795)
		(layer "F.Cu")
		(net "SPI_BMC_BT_WP0_N")
	)
	(segment
		(start 465.6074 -1.9558)
		(end 464.312254 -1.9558)
		(width 0.10795)
		(layer "F.Cu")
		(net "SPI_BMC_BT_WP0_N")
	)
	(via
		(at 413.090106 -40.53459)
		(size 0.4572)
		(drill 0.2032)
		(layers "F.Cu" "B.Cu")
		(net "SPI_BMC_BT_WP0_N")
	)
	(via
		(at 461.29575 -43.050968)
		(size 0.508)
		(drill 0.254)
		(layers "F.Cu" "B.Cu")
		(net "SPI_BMC_BT_WP0_N")
	)
	(via
		(at 461.69961 -43.789092)
		(size 0.6604)
		(drill 0.3302)
		(layers "F.Cu" "B.Cu")
		(net "SPI_BMC_BT_WP0_N")
	)
	(via
		(at 463.439256 -0.874014)
		(size 0.508)
		(drill 0.254)
		(layers "F.Cu" "B.Cu")
		(net "SPI_BMC_BT_WP0_N")
	)
	(segment
		(start 461.69961 -43.454828)
		(end 461.69961 -43.789092)
		(width 0.10795)
		(layer "B.Cu")
		(net "SPI_BMC_BT_WP0_N")
	)
	(segment
		(start 461.29575 -43.050968)
		(end 461.69961 -43.454828)
		(width 0.10795)
		(layer "B.Cu")
		(net "SPI_BMC_BT_WP0_N")
	)
	(segment
		(start 463.027014 -34.310574)
		(end 461.580992 -35.756596)
		(width 0.089408)
		(layer "In9.Cu")
		(net "SPI_BMC_BT_WP0_N")
	)
	(segment
		(start 466.686646 -9.766808)
		(end 467.050374 -9.766808)
		(width 0.089408)
		(layer "In9.Cu")
		(net "SPI_BMC_BT_WP0_N")
	)
	(segment
		(start 461.838294 -5.677662)
		(end 463.821526 -7.660894)
		(width 0.089408)
		(layer "In9.Cu")
		(net "SPI_BMC_BT_WP0_N")
	)
	(segment
		(start 466.1154 -16.333724)
		(end 464.714336 -17.734788)
		(width 0.089408)
		(layer "In9.Cu")
		(net "SPI_BMC_BT_WP0_N")
	)
	(segment
		(start 464.714336 -19.331178)
		(end 462.956656 -21.088858)
		(width 0.089408)
		(layer "In9.Cu")
		(net "SPI_BMC_BT_WP0_N")
	)
	(segment
		(start 467.379304 -10.499344)
		(end 466.1154 -11.763248)
		(width 0.089408)
		(layer "In9.Cu")
		(net "SPI_BMC_BT_WP0_N")
	)
	(segment
		(start 462.794096 -1.519174)
		(end 462.794096 -4.153662)
		(width 0.089408)
		(layer "In9.Cu")
		(net "SPI_BMC_BT_WP0_N")
	)
	(segment
		(start 463.821526 -7.660894)
		(end 464.446874 -7.660894)
		(width 0.089408)
		(layer "In9.Cu")
		(net "SPI_BMC_BT_WP0_N")
	)
	(segment
		(start 461.580992 -35.756596)
		(end 461.580992 -39.168832)
		(width 0.089408)
		(layer "In9.Cu")
		(net "SPI_BMC_BT_WP0_N")
	)
	(segment
		(start 464.714336 -17.734788)
		(end 464.714336 -19.331178)
		(width 0.089408)
		(layer "In9.Cu")
		(net "SPI_BMC_BT_WP0_N")
	)
	(segment
		(start 463.027014 -28.582366)
		(end 463.027014 -34.310574)
		(width 0.089408)
		(layer "In9.Cu")
		(net "SPI_BMC_BT_WP0_N")
	)
	(segment
		(start 461.580992 -39.168832)
		(end 461.752696 -39.340536)
		(width 0.089408)
		(layer "In9.Cu")
		(net "SPI_BMC_BT_WP0_N")
	)
	(segment
		(start 466.686392 -9.767062)
		(end 466.686646 -9.766808)
		(width 0.089408)
		(layer "In9.Cu")
		(net "SPI_BMC_BT_WP0_N")
	)
	(segment
		(start 464.496404 -23.808944)
		(end 464.496404 -27.112976)
		(width 0.089408)
		(layer "In9.Cu")
		(net "SPI_BMC_BT_WP0_N")
	)
	(segment
		(start 466.367876 -9.767062)
		(end 466.686392 -9.767062)
		(width 0.089408)
		(layer "In9.Cu")
		(net "SPI_BMC_BT_WP0_N")
	)
	(segment
		(start 466.032088 -9.246108)
		(end 466.032088 -9.431274)
		(width 0.089408)
		(layer "In9.Cu")
		(net "SPI_BMC_BT_WP0_N")
	)
	(segment
		(start 464.446874 -7.660894)
		(end 466.032088 -9.246108)
		(width 0.089408)
		(layer "In9.Cu")
		(net "SPI_BMC_BT_WP0_N")
	)
	(segment
		(start 462.956656 -21.088858)
		(end 462.956656 -22.269196)
		(width 0.089408)
		(layer "In9.Cu")
		(net "SPI_BMC_BT_WP0_N")
	)
	(segment
		(start 460.952088 -40.893746)
		(end 460.952088 -42.707306)
		(width 0.089408)
		(layer "In9.Cu")
		(net "SPI_BMC_BT_WP0_N")
	)
	(segment
		(start 466.1154 -11.763248)
		(end 466.1154 -16.333724)
		(width 0.089408)
		(layer "In9.Cu")
		(net "SPI_BMC_BT_WP0_N")
	)
	(segment
		(start 461.838294 -5.109464)
		(end 461.838294 -5.677662)
		(width 0.089408)
		(layer "In9.Cu")
		(net "SPI_BMC_BT_WP0_N")
	)
	(segment
		(start 467.379304 -10.095738)
		(end 467.379304 -10.499344)
		(width 0.089408)
		(layer "In9.Cu")
		(net "SPI_BMC_BT_WP0_N")
	)
	(segment
		(start 462.794096 -4.153662)
		(end 461.838294 -5.109464)
		(width 0.089408)
		(layer "In9.Cu")
		(net "SPI_BMC_BT_WP0_N")
	)
	(segment
		(start 467.050374 -9.766808)
		(end 467.379304 -10.095738)
		(width 0.089408)
		(layer "In9.Cu")
		(net "SPI_BMC_BT_WP0_N")
	)
	(segment
		(start 463.439256 -0.874014)
		(end 462.794096 -1.519174)
		(width 0.089408)
		(layer "In9.Cu")
		(net "SPI_BMC_BT_WP0_N")
	)
	(segment
		(start 461.752696 -40.093138)
		(end 460.952088 -40.893746)
		(width 0.089408)
		(layer "In9.Cu")
		(net "SPI_BMC_BT_WP0_N")
	)
	(segment
		(start 461.752696 -39.340536)
		(end 461.752696 -40.093138)
		(width 0.089408)
		(layer "In9.Cu")
		(net "SPI_BMC_BT_WP0_N")
	)
	(segment
		(start 464.496404 -27.112976)
		(end 463.027014 -28.582366)
		(width 0.089408)
		(layer "In9.Cu")
		(net "SPI_BMC_BT_WP0_N")
	)
	(segment
		(start 460.952088 -42.707306)
		(end 461.29575 -43.050968)
		(width 0.089408)
		(layer "In9.Cu")
		(net "SPI_BMC_BT_WP0_N")
	)
	(segment
		(start 466.032088 -9.431274)
		(end 466.367876 -9.767062)
		(width 0.089408)
		(layer "In9.Cu")
		(net "SPI_BMC_BT_WP0_N")
	)
	(segment
		(start 462.956656 -22.269196)
		(end 464.496404 -23.808944)
		(width 0.089408)
		(layer "In9.Cu")
		(net "SPI_BMC_BT_WP0_N")
	)
	(segment
		(start 422.712134 -40.455596)
		(end 422.394888 -40.13835)
		(width 0.089408)
		(layer "In11.Cu")
		(net "SPI_BMC_BT_WP0_N")
	)
	(segment
		(start 413.160972 -40.53459)
		(end 413.090106 -40.53459)
		(width 0.089408)
		(layer "In11.Cu")
		(net "SPI_BMC_BT_WP0_N")
	)
	(segment
		(start 422.394888 -40.13835)
		(end 413.557212 -40.13835)
		(width 0.089408)
		(layer "In11.Cu")
		(net "SPI_BMC_BT_WP0_N")
	)
	(segment
		(start 435.134258 -41.487598)
		(end 435.105556 -41.458896)
		(width 0.089408)
		(layer "In11.Cu")
		(net "SPI_BMC_BT_WP0_N")
	)
	(segment
		(start 444.956438 -41.097454)
		(end 444.566294 -41.487598)
		(width 0.089408)
		(layer "In11.Cu")
		(net "SPI_BMC_BT_WP0_N")
	)
	(segment
		(start 435.105556 -41.458896)
		(end 435.092602 -41.458896)
		(width 0.089408)
		(layer "In11.Cu")
		(net "SPI_BMC_BT_WP0_N")
	)
	(segment
		(start 460.115412 -41.032176)
		(end 459.60284 -40.519604)
		(width 0.089408)
		(layer "In11.Cu")
		(net "SPI_BMC_BT_WP0_N")
	)
	(segment
		(start 444.566294 -41.487598)
		(end 435.134258 -41.487598)
		(width 0.089408)
		(layer "In11.Cu")
		(net "SPI_BMC_BT_WP0_N")
	)
	(segment
		(start 447.999612 -40.519604)
		(end 447.421762 -41.097454)
		(width 0.089408)
		(layer "In11.Cu")
		(net "SPI_BMC_BT_WP0_N")
	)
	(segment
		(start 435.092602 -41.458896)
		(end 434.089302 -40.455596)
		(width 0.089408)
		(layer "In11.Cu")
		(net "SPI_BMC_BT_WP0_N")
	)
	(segment
		(start 447.421762 -41.097454)
		(end 444.956438 -41.097454)
		(width 0.089408)
		(layer "In11.Cu")
		(net "SPI_BMC_BT_WP0_N")
	)
	(segment
		(start 459.60284 -40.519604)
		(end 447.999612 -40.519604)
		(width 0.089408)
		(layer "In11.Cu")
		(net "SPI_BMC_BT_WP0_N")
	)
	(segment
		(start 461.047084 -43.050968)
		(end 460.115412 -42.119296)
		(width 0.089408)
		(layer "In11.Cu")
		(net "SPI_BMC_BT_WP0_N")
	)
	(segment
		(start 460.115412 -42.119296)
		(end 460.115412 -41.032176)
		(width 0.089408)
		(layer "In11.Cu")
		(net "SPI_BMC_BT_WP0_N")
	)
	(segment
		(start 413.557212 -40.13835)
		(end 413.160972 -40.53459)
		(width 0.089408)
		(layer "In11.Cu")
		(net "SPI_BMC_BT_WP0_N")
	)
	(segment
		(start 434.089302 -40.455596)
		(end 422.712134 -40.455596)
		(width 0.089408)
		(layer "In11.Cu")
		(net "SPI_BMC_BT_WP0_N")
	)
	(segment
		(start 461.29575 -43.050968)
		(end 461.047084 -43.050968)
		(width 0.089408)
		(layer "In11.Cu")
		(net "SPI_BMC_BT_WP0_N")
	)
	(segment
		(start 424.14444 -40.93464)
		(end 423.890186 -40.93464)
		(width 0.089408)
		(layer "F.Cu")
		(net "SPI_BMC_BT_CS0_N")
	)
	(segment
		(start 377.805696 -25.489662)
		(end 376.879866 -25.489662)
		(width 0.10795)
		(layer "F.Cu")
		(net "SPI_BMC_BT_CS0_N")
	)
	(segment
		(start 378.25807 -26.24455)
		(end 378.25807 -25.942036)
		(width 0.10795)
		(layer "F.Cu")
		(net "SPI_BMC_BT_CS0_N")
	)
	(segment
		(start 425.31157 -43.855132)
		(end 425.472352 -43.855132)
		(width 0.089408)
		(layer "F.Cu")
		(net "SPI_BMC_BT_CS0_N")
	)
	(segment
		(start 378.219462 -26.24455)
		(end 378.25807 -26.24455)
		(width 0.10795)
		(layer "F.Cu")
		(net "SPI_BMC_BT_CS0_N")
	)
	(segment
		(start 425.71162 -43.615864)
		(end 425.71162 -42.50182)
		(width 0.089408)
		(layer "F.Cu")
		(net "SPI_BMC_BT_CS0_N")
	)
	(segment
		(start 425.472352 -43.855132)
		(end 425.71162 -43.615864)
		(width 0.089408)
		(layer "F.Cu")
		(net "SPI_BMC_BT_CS0_N")
	)
	(segment
		(start 425.71162 -42.50182)
		(end 424.14444 -40.93464)
		(width 0.089408)
		(layer "F.Cu")
		(net "SPI_BMC_BT_CS0_N")
	)
	(segment
		(start 378.25807 -25.942036)
		(end 377.805696 -25.489662)
		(width 0.10795)
		(layer "F.Cu")
		(net "SPI_BMC_BT_CS0_N")
	)
	(via
		(at 378.219462 -26.24455)
		(size 0.508)
		(drill 0.254)
		(layers "F.Cu" "B.Cu")
		(net "SPI_BMC_BT_CS0_N")
	)
	(via
		(at 462.396078 -9.938512)
		(size 0.508)
		(drill 0.254)
		(layers "F.Cu" "B.Cu")
		(net "SPI_BMC_BT_CS0_N")
	)
	(via
		(at 378.1552 -36.83)
		(size 0.508)
		(drill 0.254)
		(layers "F.Cu" "B.Cu")
		(net "SPI_BMC_BT_CS0_N")
	)
	(via
		(at 425.31157 -43.855132)
		(size 0.508)
		(drill 0.254)
		(layers "F.Cu" "B.Cu")
		(net "SPI_BMC_BT_CS0_N")
	)
	(via
		(at 376.2502 -24.6126)
		(size 0.6604)
		(drill 0.3302)
		(layers "F.Cu" "B.Cu")
		(net "SPI_BMC_BT_CS0_N")
	)
	(segment
		(start 376.2502 -24.6126)
		(end 376.991372 -25.353772)
		(width 0.10795)
		(layer "B.Cu")
		(net "SPI_BMC_BT_CS0_N")
	)
	(segment
		(start 377.328684 -25.353772)
		(end 378.219462 -26.24455)
		(width 0.10795)
		(layer "B.Cu")
		(net "SPI_BMC_BT_CS0_N")
	)
	(segment
		(start 376.991372 -25.353772)
		(end 377.328684 -25.353772)
		(width 0.10795)
		(layer "B.Cu")
		(net "SPI_BMC_BT_CS0_N")
	)
	(segment
		(start 379.0188 -28.946094)
		(end 378.262642 -29.702252)
		(width 0.0889)
		(layer "In2.Cu")
		(net "SPI_BMC_BT_CS0_N")
	)
	(segment
		(start 378.09424 -35.136836)
		(end 378.09424 -36.76904)
		(width 0.0889)
		(layer "In2.Cu")
		(net "SPI_BMC_BT_CS0_N")
	)
	(segment
		(start 378.219462 -26.24455)
		(end 377.89358 -26.570432)
		(width 0.0889)
		(layer "In2.Cu")
		(net "SPI_BMC_BT_CS0_N")
	)
	(segment
		(start 378.262642 -29.702252)
		(end 378.262642 -34.968434)
		(width 0.0889)
		(layer "In2.Cu")
		(net "SPI_BMC_BT_CS0_N")
	)
	(segment
		(start 377.89358 -27.187144)
		(end 379.0188 -28.312364)
		(width 0.0889)
		(layer "In2.Cu")
		(net "SPI_BMC_BT_CS0_N")
	)
	(segment
		(start 377.89358 -26.570432)
		(end 377.89358 -27.187144)
		(width 0.0889)
		(layer "In2.Cu")
		(net "SPI_BMC_BT_CS0_N")
	)
	(segment
		(start 379.0188 -28.312364)
		(end 379.0188 -28.946094)
		(width 0.0889)
		(layer "In2.Cu")
		(net "SPI_BMC_BT_CS0_N")
	)
	(segment
		(start 378.262642 -34.968434)
		(end 378.09424 -35.136836)
		(width 0.0889)
		(layer "In2.Cu")
		(net "SPI_BMC_BT_CS0_N")
	)
	(segment
		(start 378.09424 -36.76904)
		(end 378.1552 -36.83)
		(width 0.0889)
		(layer "In2.Cu")
		(net "SPI_BMC_BT_CS0_N")
	)
	(segment
		(start 380.096776 -39.75354)
		(end 379.700282 -39.75354)
		(width 0.089408)
		(layer "In4.Cu")
		(net "SPI_BMC_BT_CS0_N")
	)
	(segment
		(start 459.614016 0.557784)
		(end 459.614016 1.27)
		(width 0.089408)
		(layer "In4.Cu")
		(net "SPI_BMC_BT_CS0_N")
	)
	(segment
		(start 462.680304 -8.830056)
		(end 462.415382 -8.565134)
		(width 0.089408)
		(layer "In4.Cu")
		(net "SPI_BMC_BT_CS0_N")
	)
	(segment
		(start 379.34011 -40.113712)
		(end 378.817886 -40.113712)
		(width 0.089408)
		(layer "In4.Cu")
		(net "SPI_BMC_BT_CS0_N")
	)
	(segment
		(start 380.660656 -38.534086)
		(end 380.393956 -38.800786)
		(width 0.089408)
		(layer "In4.Cu")
		(net "SPI_BMC_BT_CS0_N")
	)
	(segment
		(start 460.24927 -0.07747)
		(end 459.614016 0.557784)
		(width 0.089408)
		(layer "In4.Cu")
		(net "SPI_BMC_BT_CS0_N")
	)
	(segment
		(start 401.080478 -43.143678)
		(end 400.120104 -43.143678)
		(width 0.089408)
		(layer "In4.Cu")
		(net "SPI_BMC_BT_CS0_N")
	)
	(segment
		(start 462.680304 -9.654286)
		(end 462.680304 -8.830056)
		(width 0.089408)
		(layer "In4.Cu")
		(net "SPI_BMC_BT_CS0_N")
	)
	(segment
		(start 391.084308 -39.37)
		(end 389.74522 -38.030912)
		(width 0.089408)
		(layer "In4.Cu")
		(net "SPI_BMC_BT_CS0_N")
	)
	(segment
		(start 412.451296 -46.839378)
		(end 412.451296 -47.171102)
		(width 0.089408)
		(layer "In4.Cu")
		(net "SPI_BMC_BT_CS0_N")
	)
	(segment
		(start 420.535862 -44.816776)
		(end 419.481 -45.871638)
		(width 0.089408)
		(layer "In4.Cu")
		(net "SPI_BMC_BT_CS0_N")
	)
	(segment
		(start 380.393956 -38.800786)
		(end 380.393956 -39.45636)
		(width 0.089408)
		(layer "In4.Cu")
		(net "SPI_BMC_BT_CS0_N")
	)
	(segment
		(start 392.85291 -40.123364)
		(end 391.61339 -40.123364)
		(width 0.089408)
		(layer "In4.Cu")
		(net "SPI_BMC_BT_CS0_N")
	)
	(segment
		(start 400.120104 -43.143678)
		(end 399.454116 -42.47769)
		(width 0.089408)
		(layer "In4.Cu")
		(net "SPI_BMC_BT_CS0_N")
	)
	(segment
		(start 384.30581 -37.16909)
		(end 384.074416 -37.400484)
		(width 0.089408)
		(layer "In4.Cu")
		(net "SPI_BMC_BT_CS0_N")
	)
	(segment
		(start 399.454116 -42.47769)
		(end 399.454116 -42.476928)
		(width 0.089408)
		(layer "In4.Cu")
		(net "SPI_BMC_BT_CS0_N")
	)
	(segment
		(start 388.836916 -38.030912)
		(end 387.975094 -37.16909)
		(width 0.089408)
		(layer "In4.Cu")
		(net "SPI_BMC_BT_CS0_N")
	)
	(segment
		(start 382.338834 -38.42131)
		(end 380.76886 -38.42131)
		(width 0.089408)
		(layer "In4.Cu")
		(net "SPI_BMC_BT_CS0_N")
	)
	(segment
		(start 398.202404 -42.115232)
		(end 397.580612 -41.49344)
		(width 0.089408)
		(layer "In4.Cu")
		(net "SPI_BMC_BT_CS0_N")
	)
	(segment
		(start 378.1552 -37.341048)
		(end 378.1552 -36.83)
		(width 0.089408)
		(layer "In4.Cu")
		(net "SPI_BMC_BT_CS0_N")
	)
	(segment
		(start 424.283378 -44.653962)
		(end 423.454576 -44.653962)
		(width 0.089408)
		(layer "In4.Cu")
		(net "SPI_BMC_BT_CS0_N")
	)
	(segment
		(start 408.046174 -47.097696)
		(end 408.046174 -46.501304)
		(width 0.089408)
		(layer "In4.Cu")
		(net "SPI_BMC_BT_CS0_N")
	)
	(segment
		(start 418.777928 -45.488352)
		(end 413.616648 -45.488352)
		(width 0.089408)
		(layer "In4.Cu")
		(net "SPI_BMC_BT_CS0_N")
	)
	(segment
		(start 379.700282 -39.75354)
		(end 379.34011 -40.113712)
		(width 0.089408)
		(layer "In4.Cu")
		(net "SPI_BMC_BT_CS0_N")
	)
	(segment
		(start 396.493746 -40.386)
		(end 396.219426 -40.66032)
		(width 0.089408)
		(layer "In4.Cu")
		(net "SPI_BMC_BT_CS0_N")
	)
	(segment
		(start 408.046174 -46.501304)
		(end 407.777442 -46.232572)
		(width 0.089408)
		(layer "In4.Cu")
		(net "SPI_BMC_BT_CS0_N")
	)
	(segment
		(start 396.219426 -40.66032)
		(end 393.389866 -40.66032)
		(width 0.089408)
		(layer "In4.Cu")
		(net "SPI_BMC_BT_CS0_N")
	)
	(segment
		(start 408.432508 -47.48403)
		(end 408.046174 -47.097696)
		(width 0.089408)
		(layer "In4.Cu")
		(net "SPI_BMC_BT_CS0_N")
	)
	(segment
		(start 460.547212 -4.31038)
		(end 461.153764 -4.31038)
		(width 0.089408)
		(layer "In4.Cu")
		(net "SPI_BMC_BT_CS0_N")
	)
	(segment
		(start 412.451042 -46.653958)
		(end 412.451042 -46.839124)
		(width 0.089408)
		(layer "In4.Cu")
		(net "SPI_BMC_BT_CS0_N")
	)
	(segment
		(start 407.777442 -45.617892)
		(end 407.777188 -45.617638)
		(width 0.089408)
		(layer "In4.Cu")
		(net "SPI_BMC_BT_CS0_N")
	)
	(segment
		(start 406.979882 -44.741592)
		(end 402.678392 -44.741592)
		(width 0.089408)
		(layer "In4.Cu")
		(net "SPI_BMC_BT_CS0_N")
	)
	(segment
		(start 407.777442 -46.232572)
		(end 407.777442 -45.617892)
		(width 0.089408)
		(layer "In4.Cu")
		(net "SPI_BMC_BT_CS0_N")
	)
	(segment
		(start 462.055972 -3.408172)
		(end 462.055972 -1.274318)
		(width 0.089408)
		(layer "In4.Cu")
		(net "SPI_BMC_BT_CS0_N")
	)
	(segment
		(start 382.405636 -38.354508)
		(end 382.338834 -38.42131)
		(width 0.089408)
		(layer "In4.Cu")
		(net "SPI_BMC_BT_CS0_N")
	)
	(segment
		(start 397.477996 -40.386)
		(end 396.493746 -40.386)
		(width 0.089408)
		(layer "In4.Cu")
		(net "SPI_BMC_BT_CS0_N")
	)
	(segment
		(start 419.161214 -45.871638)
		(end 418.777928 -45.488352)
		(width 0.089408)
		(layer "In4.Cu")
		(net "SPI_BMC_BT_CS0_N")
	)
	(segment
		(start 380.76886 -38.42131)
		(end 380.660656 -38.529514)
		(width 0.089408)
		(layer "In4.Cu")
		(net "SPI_BMC_BT_CS0_N")
	)
	(segment
		(start 425.082208 -43.855132)
		(end 424.283378 -44.653962)
		(width 0.089408)
		(layer "In4.Cu")
		(net "SPI_BMC_BT_CS0_N")
	)
	(segment
		(start 380.393956 -39.45636)
		(end 380.096776 -39.75354)
		(width 0.089408)
		(layer "In4.Cu")
		(net "SPI_BMC_BT_CS0_N")
	)
	(segment
		(start 460.095092 -4.7625)
		(end 460.547212 -4.31038)
		(width 0.089408)
		(layer "In4.Cu")
		(net "SPI_BMC_BT_CS0_N")
	)
	(segment
		(start 460.859124 -0.07747)
		(end 460.24927 -0.07747)
		(width 0.089408)
		(layer "In4.Cu")
		(net "SPI_BMC_BT_CS0_N")
	)
	(segment
		(start 391.61339 -40.123364)
		(end 391.084308 -39.594282)
		(width 0.089408)
		(layer "In4.Cu")
		(net "SPI_BMC_BT_CS0_N")
	)
	(segment
		(start 378.520198 -39.816024)
		(end 378.520198 -37.706046)
		(width 0.089408)
		(layer "In4.Cu")
		(net "SPI_BMC_BT_CS0_N")
	)
	(segment
		(start 460.574136 -8.565134)
		(end 460.095092 -8.08609)
		(width 0.089408)
		(layer "In4.Cu")
		(net "SPI_BMC_BT_CS0_N")
	)
	(segment
		(start 419.481 -45.871638)
		(end 419.161214 -45.871638)
		(width 0.089408)
		(layer "In4.Cu")
		(net "SPI_BMC_BT_CS0_N")
	)
	(segment
		(start 402.678392 -44.741592)
		(end 401.080478 -43.143678)
		(width 0.089408)
		(layer "In4.Cu")
		(net "SPI_BMC_BT_CS0_N")
	)
	(segment
		(start 391.084308 -39.594282)
		(end 391.084308 -39.37)
		(width 0.089408)
		(layer "In4.Cu")
		(net "SPI_BMC_BT_CS0_N")
	)
	(segment
		(start 387.975094 -37.16909)
		(end 384.30581 -37.16909)
		(width 0.089408)
		(layer "In4.Cu")
		(net "SPI_BMC_BT_CS0_N")
	)
	(segment
		(start 423.454576 -44.653962)
		(end 423.291762 -44.816776)
		(width 0.089408)
		(layer "In4.Cu")
		(net "SPI_BMC_BT_CS0_N")
	)
	(segment
		(start 462.055972 -1.274318)
		(end 460.859124 -0.07747)
		(width 0.089408)
		(layer "In4.Cu")
		(net "SPI_BMC_BT_CS0_N")
	)
	(segment
		(start 393.389866 -40.66032)
		(end 392.85291 -40.123364)
		(width 0.089408)
		(layer "In4.Cu")
		(net "SPI_BMC_BT_CS0_N")
	)
	(segment
		(start 461.153764 -4.31038)
		(end 462.055972 -3.408172)
		(width 0.089408)
		(layer "In4.Cu")
		(net "SPI_BMC_BT_CS0_N")
	)
	(segment
		(start 412.138368 -47.48403)
		(end 408.432508 -47.48403)
		(width 0.089408)
		(layer "In4.Cu")
		(net "SPI_BMC_BT_CS0_N")
	)
	(segment
		(start 399.454116 -42.476928)
		(end 399.09242 -42.115232)
		(width 0.089408)
		(layer "In4.Cu")
		(net "SPI_BMC_BT_CS0_N")
	)
	(segment
		(start 423.291762 -44.816776)
		(end 420.535862 -44.816776)
		(width 0.089408)
		(layer "In4.Cu")
		(net "SPI_BMC_BT_CS0_N")
	)
	(segment
		(start 382.40589 -38.354508)
		(end 382.405636 -38.354508)
		(width 0.089408)
		(layer "In4.Cu")
		(net "SPI_BMC_BT_CS0_N")
	)
	(segment
		(start 425.31157 -43.855132)
		(end 425.082208 -43.855132)
		(width 0.089408)
		(layer "In4.Cu")
		(net "SPI_BMC_BT_CS0_N")
	)
	(segment
		(start 413.616648 -45.488352)
		(end 412.451042 -46.653958)
		(width 0.089408)
		(layer "In4.Cu")
		(net "SPI_BMC_BT_CS0_N")
	)
	(segment
		(start 412.451296 -47.171102)
		(end 412.138368 -47.48403)
		(width 0.089408)
		(layer "In4.Cu")
		(net "SPI_BMC_BT_CS0_N")
	)
	(segment
		(start 399.09242 -42.115232)
		(end 398.202404 -42.115232)
		(width 0.089408)
		(layer "In4.Cu")
		(net "SPI_BMC_BT_CS0_N")
	)
	(segment
		(start 397.580612 -41.49344)
		(end 397.580612 -40.488616)
		(width 0.089408)
		(layer "In4.Cu")
		(net "SPI_BMC_BT_CS0_N")
	)
	(segment
		(start 384.074416 -37.400484)
		(end 383.359914 -37.400484)
		(width 0.089408)
		(layer "In4.Cu")
		(net "SPI_BMC_BT_CS0_N")
	)
	(segment
		(start 460.095092 -8.08609)
		(end 460.095092 -4.7625)
		(width 0.089408)
		(layer "In4.Cu")
		(net "SPI_BMC_BT_CS0_N")
	)
	(segment
		(start 407.777188 -45.538898)
		(end 406.979882 -44.741592)
		(width 0.089408)
		(layer "In4.Cu")
		(net "SPI_BMC_BT_CS0_N")
	)
	(segment
		(start 397.580612 -40.488616)
		(end 397.477996 -40.386)
		(width 0.089408)
		(layer "In4.Cu")
		(net "SPI_BMC_BT_CS0_N")
	)
	(segment
		(start 462.415382 -8.565134)
		(end 460.574136 -8.565134)
		(width 0.089408)
		(layer "In4.Cu")
		(net "SPI_BMC_BT_CS0_N")
	)
	(segment
		(start 407.777188 -45.617638)
		(end 407.777188 -45.538898)
		(width 0.089408)
		(layer "In4.Cu")
		(net "SPI_BMC_BT_CS0_N")
	)
	(segment
		(start 378.817886 -40.113712)
		(end 378.520198 -39.816024)
		(width 0.089408)
		(layer "In4.Cu")
		(net "SPI_BMC_BT_CS0_N")
	)
	(segment
		(start 412.451042 -46.839124)
		(end 412.451296 -46.839378)
		(width 0.089408)
		(layer "In4.Cu")
		(net "SPI_BMC_BT_CS0_N")
	)
	(segment
		(start 462.396078 -9.938512)
		(end 462.680304 -9.654286)
		(width 0.089408)
		(layer "In4.Cu")
		(net "SPI_BMC_BT_CS0_N")
	)
	(segment
		(start 378.520198 -37.706046)
		(end 378.1552 -37.341048)
		(width 0.089408)
		(layer "In4.Cu")
		(net "SPI_BMC_BT_CS0_N")
	)
	(segment
		(start 380.660656 -38.529514)
		(end 380.660656 -38.534086)
		(width 0.089408)
		(layer "In4.Cu")
		(net "SPI_BMC_BT_CS0_N")
	)
	(segment
		(start 383.359914 -37.400484)
		(end 382.40589 -38.354508)
		(width 0.089408)
		(layer "In4.Cu")
		(net "SPI_BMC_BT_CS0_N")
	)
	(segment
		(start 389.74522 -38.030912)
		(end 388.836916 -38.030912)
		(width 0.089408)
		(layer "In4.Cu")
		(net "SPI_BMC_BT_CS0_N")
	)
	(segment
		(start 463.51698 -9.706356)
		(end 463.494882 -9.684258)
		(width 0.089408)
		(layer "In9.Cu")
		(net "SPI_BMC_BT_CS0_N")
	)
	(segment
		(start 461.0862 -18.3896)
		(end 461.0862 -17.706086)
		(width 0.089408)
		(layer "In9.Cu")
		(net "SPI_BMC_BT_CS0_N")
	)
	(segment
		(start 457.6064 -21.8694)
		(end 461.0862 -18.3896)
		(width 0.089408)
		(layer "In9.Cu")
		(net "SPI_BMC_BT_CS0_N")
	)
	(segment
		(start 454.556622 -33.74644)
		(end 454.556622 -33.726628)
		(width 0.089408)
		(layer "In9.Cu")
		(net "SPI_BMC_BT_CS0_N")
	)
	(segment
		(start 461.0862 -17.706086)
		(end 462.561686 -16.2306)
		(width 0.089408)
		(layer "In9.Cu")
		(net "SPI_BMC_BT_CS0_N")
	)
	(segment
		(start 428.001684 -41.316148)
		(end 429.058832 -40.259)
		(width 0.089408)
		(layer "In9.Cu")
		(net "SPI_BMC_BT_CS0_N")
	)
	(segment
		(start 447.33464 -39.755572)
		(end 447.728594 -40.149526)
		(width 0.089408)
		(layer "In9.Cu")
		(net "SPI_BMC_BT_CS0_N")
	)
	(segment
		(start 464.750912 -10.413746)
		(end 464.043522 -9.706356)
		(width 0.089408)
		(layer "In9.Cu")
		(net "SPI_BMC_BT_CS0_N")
	)
	(segment
		(start 449.742306 -39.859458)
		(end 449.742306 -38.560756)
		(width 0.089408)
		(layer "In9.Cu")
		(net "SPI_BMC_BT_CS0_N")
	)
	(segment
		(start 425.31157 -43.855132)
		(end 425.472352 -43.855132)
		(width 0.089408)
		(layer "In9.Cu")
		(net "SPI_BMC_BT_CS0_N")
	)
	(segment
		(start 449.452238 -40.149526)
		(end 449.742306 -39.859458)
		(width 0.089408)
		(layer "In9.Cu")
		(net "SPI_BMC_BT_CS0_N")
	)
	(segment
		(start 457.6064 -26.4414)
		(end 457.6064 -21.8694)
		(width 0.089408)
		(layer "In9.Cu")
		(net "SPI_BMC_BT_CS0_N")
	)
	(segment
		(start 456.711304 -31.571946)
		(end 456.711304 -30.314138)
		(width 0.089408)
		(layer "In9.Cu")
		(net "SPI_BMC_BT_CS0_N")
	)
	(segment
		(start 464.043522 -9.706356)
		(end 463.51698 -9.706356)
		(width 0.089408)
		(layer "In9.Cu")
		(net "SPI_BMC_BT_CS0_N")
	)
	(segment
		(start 425.71162 -42.53738)
		(end 426.932852 -41.316148)
		(width 0.089408)
		(layer "In9.Cu")
		(net "SPI_BMC_BT_CS0_N")
	)
	(segment
		(start 454.556622 -33.726628)
		(end 456.711304 -31.571946)
		(width 0.089408)
		(layer "In9.Cu")
		(net "SPI_BMC_BT_CS0_N")
	)
	(segment
		(start 447.728594 -40.149526)
		(end 449.452238 -40.149526)
		(width 0.089408)
		(layer "In9.Cu")
		(net "SPI_BMC_BT_CS0_N")
	)
	(segment
		(start 456.62088 -27.42692)
		(end 457.6064 -26.4414)
		(width 0.089408)
		(layer "In9.Cu")
		(net "SPI_BMC_BT_CS0_N")
	)
	(segment
		(start 425.472352 -43.855132)
		(end 425.71162 -43.615864)
		(width 0.089408)
		(layer "In9.Cu")
		(net "SPI_BMC_BT_CS0_N")
	)
	(segment
		(start 462.650332 -9.684258)
		(end 462.396078 -9.938512)
		(width 0.089408)
		(layer "In9.Cu")
		(net "SPI_BMC_BT_CS0_N")
	)
	(segment
		(start 462.561686 -16.2306)
		(end 463.81162 -16.2306)
		(width 0.089408)
		(layer "In9.Cu")
		(net "SPI_BMC_BT_CS0_N")
	)
	(segment
		(start 456.62088 -30.223714)
		(end 456.62088 -27.42692)
		(width 0.089408)
		(layer "In9.Cu")
		(net "SPI_BMC_BT_CS0_N")
	)
	(segment
		(start 434.37302 -40.259)
		(end 434.876448 -39.755572)
		(width 0.089408)
		(layer "In9.Cu")
		(net "SPI_BMC_BT_CS0_N")
	)
	(segment
		(start 463.81162 -16.2306)
		(end 464.750912 -15.291308)
		(width 0.089408)
		(layer "In9.Cu")
		(net "SPI_BMC_BT_CS0_N")
	)
	(segment
		(start 426.932852 -41.316148)
		(end 428.001684 -41.316148)
		(width 0.089408)
		(layer "In9.Cu")
		(net "SPI_BMC_BT_CS0_N")
	)
	(segment
		(start 456.711304 -30.314138)
		(end 456.62088 -30.223714)
		(width 0.089408)
		(layer "In9.Cu")
		(net "SPI_BMC_BT_CS0_N")
	)
	(segment
		(start 463.494882 -9.684258)
		(end 462.650332 -9.684258)
		(width 0.089408)
		(layer "In9.Cu")
		(net "SPI_BMC_BT_CS0_N")
	)
	(segment
		(start 425.71162 -43.615864)
		(end 425.71162 -42.53738)
		(width 0.089408)
		(layer "In9.Cu")
		(net "SPI_BMC_BT_CS0_N")
	)
	(segment
		(start 449.742306 -38.560756)
		(end 454.556622 -33.74644)
		(width 0.089408)
		(layer "In9.Cu")
		(net "SPI_BMC_BT_CS0_N")
	)
	(segment
		(start 429.058832 -40.259)
		(end 434.37302 -40.259)
		(width 0.089408)
		(layer "In9.Cu")
		(net "SPI_BMC_BT_CS0_N")
	)
	(segment
		(start 464.750912 -15.291308)
		(end 464.750912 -10.413746)
		(width 0.089408)
		(layer "In9.Cu")
		(net "SPI_BMC_BT_CS0_N")
	)
	(segment
		(start 434.876448 -39.755572)
		(end 447.33464 -39.755572)
		(width 0.089408)
		(layer "In9.Cu")
		(net "SPI_BMC_BT_CS0_N")
	)
	(segment
		(start 408.238706 -33.364932)
		(end 408.744928 -33.364932)
		(width 0.1016)
		(layer "F.Cu")
		(net "SMB_PEHPCPU0_STBY_LVC3_SDA")
	)
	(segment
		(start 421.815006 -115.252754)
		(end 421.813736 -115.251484)
		(width 0.1016)
		(layer "F.Cu")
		(net "SMB_PEHPCPU0_STBY_LVC3_SDA")
	)
	(segment
		(start 409.175204 -32.934656)
		(end 409.490164 -32.934656)
		(width 0.1016)
		(layer "F.Cu")
		(net "SMB_PEHPCPU0_STBY_LVC3_SDA")
	)
	(segment
		(start 422.026588 -115.252754)
		(end 421.815006 -115.252754)
		(width 0.1016)
		(layer "F.Cu")
		(net "SMB_PEHPCPU0_STBY_LVC3_SDA")
	)
	(segment
		(start 421.813736 -115.251484)
		(end 421.4749 -115.251484)
		(width 0.1016)
		(layer "F.Cu")
		(net "SMB_PEHPCPU0_STBY_LVC3_SDA")
	)
	(segment
		(start 421.386 -115.162584)
		(end 421.386 -114.7445)
		(width 0.1016)
		(layer "F.Cu")
		(net "SMB_PEHPCPU0_STBY_LVC3_SDA")
	)
	(segment
		(start 408.744928 -33.364932)
		(end 409.175204 -32.934656)
		(width 0.1016)
		(layer "F.Cu")
		(net "SMB_PEHPCPU0_STBY_LVC3_SDA")
	)
	(segment
		(start 421.4749 -115.251484)
		(end 421.386 -115.162584)
		(width 0.1016)
		(layer "F.Cu")
		(net "SMB_PEHPCPU0_STBY_LVC3_SDA")
	)
	(via
		(at 408.238706 -33.364932)
		(size 0.4572)
		(drill 0.2032)
		(layers "F.Cu" "B.Cu")
		(net "SMB_PEHPCPU0_STBY_LVC3_SDA")
	)
	(via
		(at 422.026588 -115.252754)
		(size 0.508)
		(drill 0.254)
		(layers "F.Cu" "B.Cu")
		(net "SMB_PEHPCPU0_STBY_LVC3_SDA")
	)
	(via
		(at 426.915326 -61.62167)
		(size 0.508)
		(drill 0.254)
		(layers "F.Cu" "B.Cu")
		(net "SMB_PEHPCPU0_STBY_LVC3_SDA")
	)
	(segment
		(start 419.755828 -95.788226)
		(end 419.755828 -105.955338)
		(width 0.089408)
		(layer "In2.Cu")
		(net "SMB_PEHPCPU0_STBY_LVC3_SDA")
	)
	(segment
		(start 419.755574 -113.193322)
		(end 421.815006 -115.252754)
		(width 0.089408)
		(layer "In2.Cu")
		(net "SMB_PEHPCPU0_STBY_LVC3_SDA")
	)
	(segment
		(start 421.818816 -80.752442)
		(end 421.818816 -93.725238)
		(width 0.089408)
		(layer "In2.Cu")
		(net "SMB_PEHPCPU0_STBY_LVC3_SDA")
	)
	(segment
		(start 419.755828 -105.955338)
		(end 419.755574 -105.955592)
		(width 0.089408)
		(layer "In2.Cu")
		(net "SMB_PEHPCPU0_STBY_LVC3_SDA")
	)
	(segment
		(start 421.594788 -80.528414)
		(end 421.818816 -80.752442)
		(width 0.089408)
		(layer "In2.Cu")
		(net "SMB_PEHPCPU0_STBY_LVC3_SDA")
	)
	(segment
		(start 421.818816 -93.725238)
		(end 419.755828 -95.788226)
		(width 0.089408)
		(layer "In2.Cu")
		(net "SMB_PEHPCPU0_STBY_LVC3_SDA")
	)
	(segment
		(start 426.915326 -61.62167)
		(end 425.548298 -61.62167)
		(width 0.089408)
		(layer "In2.Cu")
		(net "SMB_PEHPCPU0_STBY_LVC3_SDA")
	)
	(segment
		(start 421.594788 -65.57518)
		(end 421.594788 -80.528414)
		(width 0.089408)
		(layer "In2.Cu")
		(net "SMB_PEHPCPU0_STBY_LVC3_SDA")
	)
	(segment
		(start 421.815006 -115.252754)
		(end 422.026588 -115.252754)
		(width 0.089408)
		(layer "In2.Cu")
		(net "SMB_PEHPCPU0_STBY_LVC3_SDA")
	)
	(segment
		(start 425.548298 -61.62167)
		(end 421.594788 -65.57518)
		(width 0.089408)
		(layer "In2.Cu")
		(net "SMB_PEHPCPU0_STBY_LVC3_SDA")
	)
	(segment
		(start 419.755574 -105.955592)
		(end 419.755574 -113.193322)
		(width 0.089408)
		(layer "In2.Cu")
		(net "SMB_PEHPCPU0_STBY_LVC3_SDA")
	)
	(segment
		(start 427.260512 -61.276484)
		(end 427.260512 -60.917074)
		(width 0.089408)
		(layer "In11.Cu")
		(net "SMB_PEHPCPU0_STBY_LVC3_SDA")
	)
	(segment
		(start 420.609014 -43.107102)
		(end 414.448498 -43.107102)
		(width 0.089408)
		(layer "In11.Cu")
		(net "SMB_PEHPCPU0_STBY_LVC3_SDA")
	)
	(segment
		(start 425.756324 -50.353468)
		(end 425.046902 -50.353468)
		(width 0.089408)
		(layer "In11.Cu")
		(net "SMB_PEHPCPU0_STBY_LVC3_SDA")
	)
	(segment
		(start 408.91841 -42.509948)
		(end 407.903172 -41.49471)
		(width 0.089408)
		(layer "In11.Cu")
		(net "SMB_PEHPCPU0_STBY_LVC3_SDA")
	)
	(segment
		(start 428.243492 -59.934094)
		(end 428.243492 -58.90895)
		(width 0.089408)
		(layer "In11.Cu")
		(net "SMB_PEHPCPU0_STBY_LVC3_SDA")
	)
	(segment
		(start 407.289 -35.749992)
		(end 407.289 -35.64509)
		(width 0.089408)
		(layer "In11.Cu")
		(net "SMB_PEHPCPU0_STBY_LVC3_SDA")
	)
	(segment
		(start 424.81246 -50.119026)
		(end 424.81246 -49.787302)
		(width 0.089408)
		(layer "In11.Cu")
		(net "SMB_PEHPCPU0_STBY_LVC3_SDA")
	)
	(segment
		(start 427.348904 -51.946048)
		(end 425.756324 -50.353468)
		(width 0.089408)
		(layer "In11.Cu")
		(net "SMB_PEHPCPU0_STBY_LVC3_SDA")
	)
	(segment
		(start 414.238186 -43.055032)
		(end 414.237932 -43.055286)
		(width 0.089408)
		(layer "In11.Cu")
		(net "SMB_PEHPCPU0_STBY_LVC3_SDA")
	)
	(segment
		(start 407.515314 -38.69055)
		(end 407.761186 -38.444678)
		(width 0.089408)
		(layer "In11.Cu")
		(net "SMB_PEHPCPU0_STBY_LVC3_SDA")
	)
	(segment
		(start 407.864818 -38.290246)
		(end 407.864818 -37.97935)
		(width 0.089408)
		(layer "In11.Cu")
		(net "SMB_PEHPCPU0_STBY_LVC3_SDA")
	)
	(segment
		(start 407.296112 -35.757104)
		(end 407.289 -35.749992)
		(width 0.089408)
		(layer "In11.Cu")
		(net "SMB_PEHPCPU0_STBY_LVC3_SDA")
	)
	(segment
		(start 412.32074 -43.055286)
		(end 411.775402 -42.509948)
		(width 0.089408)
		(layer "In11.Cu")
		(net "SMB_PEHPCPU0_STBY_LVC3_SDA")
	)
	(segment
		(start 427.260512 -60.917074)
		(end 428.243492 -59.934094)
		(width 0.089408)
		(layer "In11.Cu")
		(net "SMB_PEHPCPU0_STBY_LVC3_SDA")
	)
	(segment
		(start 414.237932 -43.055286)
		(end 412.32074 -43.055286)
		(width 0.089408)
		(layer "In11.Cu")
		(net "SMB_PEHPCPU0_STBY_LVC3_SDA")
	)
	(segment
		(start 407.761186 -38.444678)
		(end 407.761186 -38.393878)
		(width 0.089408)
		(layer "In11.Cu")
		(net "SMB_PEHPCPU0_STBY_LVC3_SDA")
	)
	(segment
		(start 407.334466 -37.760148)
		(end 407.296112 -37.721794)
		(width 0.089408)
		(layer "In11.Cu")
		(net "SMB_PEHPCPU0_STBY_LVC3_SDA")
	)
	(segment
		(start 407.903172 -41.49471)
		(end 407.903172 -39.606982)
		(width 0.089408)
		(layer "In11.Cu")
		(net "SMB_PEHPCPU0_STBY_LVC3_SDA")
	)
	(segment
		(start 406.89403 -34.197798)
		(end 407.726896 -33.364932)
		(width 0.089408)
		(layer "In11.Cu")
		(net "SMB_PEHPCPU0_STBY_LVC3_SDA")
	)
	(segment
		(start 427.348904 -58.014362)
		(end 427.348904 -51.946048)
		(width 0.089408)
		(layer "In11.Cu")
		(net "SMB_PEHPCPU0_STBY_LVC3_SDA")
	)
	(segment
		(start 424.859958 -48.693324)
		(end 422.828974 -46.66234)
		(width 0.089408)
		(layer "In11.Cu")
		(net "SMB_PEHPCPU0_STBY_LVC3_SDA")
	)
	(segment
		(start 407.515314 -39.219124)
		(end 407.515314 -38.69055)
		(width 0.089408)
		(layer "In11.Cu")
		(net "SMB_PEHPCPU0_STBY_LVC3_SDA")
	)
	(segment
		(start 424.81246 -49.787302)
		(end 424.859958 -49.739804)
		(width 0.089408)
		(layer "In11.Cu")
		(net "SMB_PEHPCPU0_STBY_LVC3_SDA")
	)
	(segment
		(start 428.243492 -58.90895)
		(end 427.348904 -58.014362)
		(width 0.089408)
		(layer "In11.Cu")
		(net "SMB_PEHPCPU0_STBY_LVC3_SDA")
	)
	(segment
		(start 407.645616 -37.760148)
		(end 407.334466 -37.760148)
		(width 0.089408)
		(layer "In11.Cu")
		(net "SMB_PEHPCPU0_STBY_LVC3_SDA")
	)
	(segment
		(start 407.864818 -37.97935)
		(end 407.645616 -37.760148)
		(width 0.089408)
		(layer "In11.Cu")
		(net "SMB_PEHPCPU0_STBY_LVC3_SDA")
	)
	(segment
		(start 426.915326 -61.62167)
		(end 427.260512 -61.276484)
		(width 0.089408)
		(layer "In11.Cu")
		(net "SMB_PEHPCPU0_STBY_LVC3_SDA")
	)
	(segment
		(start 422.828974 -45.914564)
		(end 422.961308 -45.78223)
		(width 0.089408)
		(layer "In11.Cu")
		(net "SMB_PEHPCPU0_STBY_LVC3_SDA")
	)
	(segment
		(start 406.89403 -35.25012)
		(end 406.89403 -34.197798)
		(width 0.089408)
		(layer "In11.Cu")
		(net "SMB_PEHPCPU0_STBY_LVC3_SDA")
	)
	(segment
		(start 407.903172 -39.606982)
		(end 407.515314 -39.219124)
		(width 0.089408)
		(layer "In11.Cu")
		(net "SMB_PEHPCPU0_STBY_LVC3_SDA")
	)
	(segment
		(start 425.046902 -50.353468)
		(end 424.81246 -50.119026)
		(width 0.089408)
		(layer "In11.Cu")
		(net "SMB_PEHPCPU0_STBY_LVC3_SDA")
	)
	(segment
		(start 414.448498 -43.107102)
		(end 414.396682 -43.055286)
		(width 0.089408)
		(layer "In11.Cu")
		(net "SMB_PEHPCPU0_STBY_LVC3_SDA")
	)
	(segment
		(start 414.396428 -43.055286)
		(end 414.396174 -43.055032)
		(width 0.089408)
		(layer "In11.Cu")
		(net "SMB_PEHPCPU0_STBY_LVC3_SDA")
	)
	(segment
		(start 422.961308 -45.459396)
		(end 420.609014 -43.107102)
		(width 0.089408)
		(layer "In11.Cu")
		(net "SMB_PEHPCPU0_STBY_LVC3_SDA")
	)
	(segment
		(start 407.289 -35.64509)
		(end 406.89403 -35.25012)
		(width 0.089408)
		(layer "In11.Cu")
		(net "SMB_PEHPCPU0_STBY_LVC3_SDA")
	)
	(segment
		(start 407.726896 -33.364932)
		(end 408.238706 -33.364932)
		(width 0.089408)
		(layer "In11.Cu")
		(net "SMB_PEHPCPU0_STBY_LVC3_SDA")
	)
	(segment
		(start 411.775402 -42.509948)
		(end 408.91841 -42.509948)
		(width 0.089408)
		(layer "In11.Cu")
		(net "SMB_PEHPCPU0_STBY_LVC3_SDA")
	)
	(segment
		(start 414.396174 -43.055032)
		(end 414.238186 -43.055032)
		(width 0.089408)
		(layer "In11.Cu")
		(net "SMB_PEHPCPU0_STBY_LVC3_SDA")
	)
	(segment
		(start 424.859958 -49.739804)
		(end 424.859958 -48.693324)
		(width 0.089408)
		(layer "In11.Cu")
		(net "SMB_PEHPCPU0_STBY_LVC3_SDA")
	)
	(segment
		(start 407.761186 -38.393878)
		(end 407.864818 -38.290246)
		(width 0.089408)
		(layer "In11.Cu")
		(net "SMB_PEHPCPU0_STBY_LVC3_SDA")
	)
	(segment
		(start 422.828974 -46.66234)
		(end 422.828974 -45.914564)
		(width 0.089408)
		(layer "In11.Cu")
		(net "SMB_PEHPCPU0_STBY_LVC3_SDA")
	)
	(segment
		(start 407.296112 -37.721794)
		(end 407.296112 -35.757104)
		(width 0.089408)
		(layer "In11.Cu")
		(net "SMB_PEHPCPU0_STBY_LVC3_SDA")
	)
	(segment
		(start 414.396682 -43.055286)
		(end 414.396428 -43.055286)
		(width 0.089408)
		(layer "In11.Cu")
		(net "SMB_PEHPCPU0_STBY_LVC3_SDA")
	)
	(segment
		(start 422.961308 -45.78223)
		(end 422.961308 -45.459396)
		(width 0.089408)
		(layer "In11.Cu")
		(net "SMB_PEHPCPU0_STBY_LVC3_SDA")
	)
	(segment
		(start 420.2176 -115.7478)
		(end 420.2176 -115.2906)
		(width 0.10795)
		(layer "F.Cu")
		(net "SMB_PEHPCPU0_STBY_LVC3_SCL")
	)
	(segment
		(start 407.890218 -35.334702)
		(end 407.490168 -34.934652)
		(width 0.1016)
		(layer "F.Cu")
		(net "SMB_PEHPCPU0_STBY_LVC3_SCL")
	)
	(segment
		(start 422.01338 -115.887754)
		(end 420.357554 -115.887754)
		(width 0.10795)
		(layer "F.Cu")
		(net "SMB_PEHPCPU0_STBY_LVC3_SCL")
	)
	(segment
		(start 420.2176 -115.2906)
		(end 420.624 -114.8842)
		(width 0.10795)
		(layer "F.Cu")
		(net "SMB_PEHPCPU0_STBY_LVC3_SCL")
	)
	(segment
		(start 420.624 -114.8842)
		(end 420.624 -114.7445)
		(width 0.10795)
		(layer "F.Cu")
		(net "SMB_PEHPCPU0_STBY_LVC3_SCL")
	)
	(segment
		(start 420.357554 -115.887754)
		(end 420.2176 -115.7478)
		(width 0.10795)
		(layer "F.Cu")
		(net "SMB_PEHPCPU0_STBY_LVC3_SCL")
	)
	(via
		(at 427.667166 -61.555884)
		(size 0.508)
		(drill 0.254)
		(layers "F.Cu" "B.Cu")
		(net "SMB_PEHPCPU0_STBY_LVC3_SCL")
	)
	(via
		(at 420.2176 -115.7478)
		(size 0.762)
		(drill 0.381)
		(layers "F.Cu" "B.Cu")
		(net "SMB_PEHPCPU0_STBY_LVC3_SCL")
	)
	(via
		(at 422.01338 -115.887754)
		(size 0.508)
		(drill 0.254)
		(layers "F.Cu" "B.Cu")
		(net "SMB_PEHPCPU0_STBY_LVC3_SCL")
	)
	(via
		(at 407.490168 -34.934652)
		(size 0.4572)
		(drill 0.2032)
		(layers "F.Cu" "B.Cu")
		(net "SMB_PEHPCPU0_STBY_LVC3_SCL")
	)
	(segment
		(start 419.564566 -95.709232)
		(end 419.564566 -113.27257)
		(width 0.089408)
		(layer "In2.Cu")
		(net "SMB_PEHPCPU0_STBY_LVC3_SCL")
	)
	(segment
		(start 427.667166 -61.555884)
		(end 427.332648 -61.221366)
		(width 0.089408)
		(layer "In2.Cu")
		(net "SMB_PEHPCPU0_STBY_LVC3_SCL")
	)
	(segment
		(start 421.627808 -80.83169)
		(end 421.627808 -93.64599)
		(width 0.089408)
		(layer "In2.Cu")
		(net "SMB_PEHPCPU0_STBY_LVC3_SCL")
	)
	(segment
		(start 422.138856 -64.760856)
		(end 421.130984 -64.760856)
		(width 0.089408)
		(layer "In2.Cu")
		(net "SMB_PEHPCPU0_STBY_LVC3_SCL")
	)
	(segment
		(start 421.130984 -64.760856)
		(end 420.604188 -65.287652)
		(width 0.089408)
		(layer "In2.Cu")
		(net "SMB_PEHPCPU0_STBY_LVC3_SCL")
	)
	(segment
		(start 419.582346 -113.668302)
		(end 421.801798 -115.887754)
		(width 0.089408)
		(layer "In2.Cu")
		(net "SMB_PEHPCPU0_STBY_LVC3_SCL")
	)
	(segment
		(start 427.332648 -61.221366)
		(end 425.678346 -61.221366)
		(width 0.089408)
		(layer "In2.Cu")
		(net "SMB_PEHPCPU0_STBY_LVC3_SCL")
	)
	(segment
		(start 420.604188 -74.208386)
		(end 420.603172 -74.209402)
		(width 0.089408)
		(layer "In2.Cu")
		(net "SMB_PEHPCPU0_STBY_LVC3_SCL")
	)
	(segment
		(start 419.582346 -113.29035)
		(end 419.582346 -113.668302)
		(width 0.089408)
		(layer "In2.Cu")
		(net "SMB_PEHPCPU0_STBY_LVC3_SCL")
	)
	(segment
		(start 419.564566 -113.27257)
		(end 419.582346 -113.29035)
		(width 0.089408)
		(layer "In2.Cu")
		(net "SMB_PEHPCPU0_STBY_LVC3_SCL")
	)
	(segment
		(start 421.627808 -93.64599)
		(end 419.564566 -95.709232)
		(width 0.089408)
		(layer "In2.Cu")
		(net "SMB_PEHPCPU0_STBY_LVC3_SCL")
	)
	(segment
		(start 425.678346 -61.221366)
		(end 422.138856 -64.760856)
		(width 0.089408)
		(layer "In2.Cu")
		(net "SMB_PEHPCPU0_STBY_LVC3_SCL")
	)
	(segment
		(start 420.604188 -65.287652)
		(end 420.604188 -74.208386)
		(width 0.089408)
		(layer "In2.Cu")
		(net "SMB_PEHPCPU0_STBY_LVC3_SCL")
	)
	(segment
		(start 420.603172 -74.209402)
		(end 420.603172 -79.807054)
		(width 0.089408)
		(layer "In2.Cu")
		(net "SMB_PEHPCPU0_STBY_LVC3_SCL")
	)
	(segment
		(start 420.603172 -79.807054)
		(end 421.627808 -80.83169)
		(width 0.089408)
		(layer "In2.Cu")
		(net "SMB_PEHPCPU0_STBY_LVC3_SCL")
	)
	(segment
		(start 421.801798 -115.887754)
		(end 422.01338 -115.887754)
		(width 0.089408)
		(layer "In2.Cu")
		(net "SMB_PEHPCPU0_STBY_LVC3_SCL")
	)
	(segment
		(start 408.715464 -39.54907)
		(end 408.715464 -41.490138)
		(width 0.089408)
		(layer "In11.Cu")
		(net "SMB_PEHPCPU0_STBY_LVC3_SCL")
	)
	(segment
		(start 428.4345 -60.013342)
		(end 427.45152 -60.996322)
		(width 0.089408)
		(layer "In11.Cu")
		(net "SMB_PEHPCPU0_STBY_LVC3_SCL")
	)
	(segment
		(start 426.339 -49.774856)
		(end 426.339 -50.584862)
		(width 0.089408)
		(layer "In11.Cu")
		(net "SMB_PEHPCPU0_STBY_LVC3_SCL")
	)
	(segment
		(start 423.509694 -46.70425)
		(end 425.191174 -48.38573)
		(width 0.089408)
		(layer "In11.Cu")
		(net "SMB_PEHPCPU0_STBY_LVC3_SCL")
	)
	(segment
		(start 423.019728 -46.06544)
		(end 423.019728 -46.43628)
		(width 0.089408)
		(layer "In11.Cu")
		(net "SMB_PEHPCPU0_STBY_LVC3_SCL")
	)
	(segment
		(start 427.45152 -60.996322)
		(end 427.45152 -61.340238)
		(width 0.089408)
		(layer "In11.Cu")
		(net "SMB_PEHPCPU0_STBY_LVC3_SCL")
	)
	(segment
		(start 408.982926 -41.7576)
		(end 411.7594 -41.7576)
		(width 0.089408)
		(layer "In11.Cu")
		(net "SMB_PEHPCPU0_STBY_LVC3_SCL")
	)
	(segment
		(start 427.539912 -51.785774)
		(end 427.539912 -57.935114)
		(width 0.089408)
		(layer "In11.Cu")
		(net "SMB_PEHPCPU0_STBY_LVC3_SCL")
	)
	(segment
		(start 407.8986 -35.936428)
		(end 407.8986 -37.488876)
		(width 0.089408)
		(layer "In11.Cu")
		(net "SMB_PEHPCPU0_STBY_LVC3_SCL")
	)
	(segment
		(start 412.491174 -42.5196)
		(end 412.802324 -42.83075)
		(width 0.089408)
		(layer "In11.Cu")
		(net "SMB_PEHPCPU0_STBY_LVC3_SCL")
	)
	(segment
		(start 411.8864 -41.8846)
		(end 411.8864 -42.3164)
		(width 0.089408)
		(layer "In11.Cu")
		(net "SMB_PEHPCPU0_STBY_LVC3_SCL")
	)
	(segment
		(start 414.527746 -42.916348)
		(end 420.741348 -42.916348)
		(width 0.089408)
		(layer "In11.Cu")
		(net "SMB_PEHPCPU0_STBY_LVC3_SCL")
	)
	(segment
		(start 427.539912 -57.935114)
		(end 428.4345 -58.829702)
		(width 0.089408)
		(layer "In11.Cu")
		(net "SMB_PEHPCPU0_STBY_LVC3_SCL")
	)
	(segment
		(start 411.8864 -42.3164)
		(end 412.0896 -42.5196)
		(width 0.089408)
		(layer "In11.Cu")
		(net "SMB_PEHPCPU0_STBY_LVC3_SCL")
	)
	(segment
		(start 420.741348 -42.916348)
		(end 423.237406 -45.412406)
		(width 0.089408)
		(layer "In11.Cu")
		(net "SMB_PEHPCPU0_STBY_LVC3_SCL")
	)
	(segment
		(start 423.09288 -45.992034)
		(end 423.09288 -45.992288)
		(width 0.089408)
		(layer "In11.Cu")
		(net "SMB_PEHPCPU0_STBY_LVC3_SCL")
	)
	(segment
		(start 414.442148 -42.83075)
		(end 414.527746 -42.916348)
		(width 0.089408)
		(layer "In11.Cu")
		(net "SMB_PEHPCPU0_STBY_LVC3_SCL")
	)
	(segment
		(start 407.8986 -37.488876)
		(end 408.121104 -37.71138)
		(width 0.089408)
		(layer "In11.Cu")
		(net "SMB_PEHPCPU0_STBY_LVC3_SCL")
	)
	(segment
		(start 426.339 -50.584862)
		(end 427.539912 -51.785774)
		(width 0.089408)
		(layer "In11.Cu")
		(net "SMB_PEHPCPU0_STBY_LVC3_SCL")
	)
	(segment
		(start 407.787094 -38.790118)
		(end 407.787094 -39.09441)
		(width 0.089408)
		(layer "In11.Cu")
		(net "SMB_PEHPCPU0_STBY_LVC3_SCL")
	)
	(segment
		(start 407.256742 -35.168078)
		(end 407.256742 -35.29457)
		(width 0.089408)
		(layer "In11.Cu")
		(net "SMB_PEHPCPU0_STBY_LVC3_SCL")
	)
	(segment
		(start 408.121104 -38.456108)
		(end 407.787094 -38.790118)
		(width 0.089408)
		(layer "In11.Cu")
		(net "SMB_PEHPCPU0_STBY_LVC3_SCL")
	)
	(segment
		(start 423.237406 -45.847508)
		(end 423.09288 -45.992034)
		(width 0.089408)
		(layer "In11.Cu")
		(net "SMB_PEHPCPU0_STBY_LVC3_SCL")
	)
	(segment
		(start 408.715464 -41.490138)
		(end 408.982926 -41.7576)
		(width 0.089408)
		(layer "In11.Cu")
		(net "SMB_PEHPCPU0_STBY_LVC3_SCL")
	)
	(segment
		(start 412.802324 -42.83075)
		(end 414.442148 -42.83075)
		(width 0.089408)
		(layer "In11.Cu")
		(net "SMB_PEHPCPU0_STBY_LVC3_SCL")
	)
	(segment
		(start 425.191174 -48.38573)
		(end 425.191174 -48.62703)
		(width 0.089408)
		(layer "In11.Cu")
		(net "SMB_PEHPCPU0_STBY_LVC3_SCL")
	)
	(segment
		(start 407.787094 -39.09441)
		(end 408.035506 -39.342822)
		(width 0.089408)
		(layer "In11.Cu")
		(net "SMB_PEHPCPU0_STBY_LVC3_SCL")
	)
	(segment
		(start 427.45152 -61.340238)
		(end 427.667166 -61.555884)
		(width 0.089408)
		(layer "In11.Cu")
		(net "SMB_PEHPCPU0_STBY_LVC3_SCL")
	)
	(segment
		(start 411.7594 -41.7576)
		(end 411.8864 -41.8846)
		(width 0.089408)
		(layer "In11.Cu")
		(net "SMB_PEHPCPU0_STBY_LVC3_SCL")
	)
	(segment
		(start 425.191174 -48.62703)
		(end 426.339 -49.774856)
		(width 0.089408)
		(layer "In11.Cu")
		(net "SMB_PEHPCPU0_STBY_LVC3_SCL")
	)
	(segment
		(start 408.035506 -39.342822)
		(end 408.509216 -39.342822)
		(width 0.089408)
		(layer "In11.Cu")
		(net "SMB_PEHPCPU0_STBY_LVC3_SCL")
	)
	(segment
		(start 428.4345 -58.829702)
		(end 428.4345 -60.013342)
		(width 0.089408)
		(layer "In11.Cu")
		(net "SMB_PEHPCPU0_STBY_LVC3_SCL")
	)
	(segment
		(start 423.09288 -45.992288)
		(end 423.019728 -46.06544)
		(width 0.089408)
		(layer "In11.Cu")
		(net "SMB_PEHPCPU0_STBY_LVC3_SCL")
	)
	(segment
		(start 423.237406 -45.412406)
		(end 423.237406 -45.847508)
		(width 0.089408)
		(layer "In11.Cu")
		(net "SMB_PEHPCPU0_STBY_LVC3_SCL")
	)
	(segment
		(start 408.121104 -37.71138)
		(end 408.121104 -38.456108)
		(width 0.089408)
		(layer "In11.Cu")
		(net "SMB_PEHPCPU0_STBY_LVC3_SCL")
	)
	(segment
		(start 407.490168 -34.934652)
		(end 407.256742 -35.168078)
		(width 0.089408)
		(layer "In11.Cu")
		(net "SMB_PEHPCPU0_STBY_LVC3_SCL")
	)
	(segment
		(start 423.019728 -46.43628)
		(end 423.287698 -46.70425)
		(width 0.089408)
		(layer "In11.Cu")
		(net "SMB_PEHPCPU0_STBY_LVC3_SCL")
	)
	(segment
		(start 408.509216 -39.342822)
		(end 408.715464 -39.54907)
		(width 0.089408)
		(layer "In11.Cu")
		(net "SMB_PEHPCPU0_STBY_LVC3_SCL")
	)
	(segment
		(start 407.256742 -35.29457)
		(end 407.8986 -35.936428)
		(width 0.089408)
		(layer "In11.Cu")
		(net "SMB_PEHPCPU0_STBY_LVC3_SCL")
	)
	(segment
		(start 423.287698 -46.70425)
		(end 423.509694 -46.70425)
		(width 0.089408)
		(layer "In11.Cu")
		(net "SMB_PEHPCPU0_STBY_LVC3_SCL")
	)
	(segment
		(start 412.0896 -42.5196)
		(end 412.491174 -42.5196)
		(width 0.089408)
		(layer "In11.Cu")
		(net "SMB_PEHPCPU0_STBY_LVC3_SCL")
	)
	(segment
		(start 422.8211 -114.731292)
		(end 422.8211 -115.8875)
		(width 0.1016)
		(layer "F.Cu")
		(net "SMB_PEHPCPU0_STBY_LVC3_R_SDA")
	)
	(segment
		(start 421.945308 -113.8555)
		(end 422.8211 -114.731292)
		(width 0.1016)
		(layer "F.Cu")
		(net "SMB_PEHPCPU0_STBY_LVC3_R_SDA")
	)
	(segment
		(start 421.386 -113.8555)
		(end 421.945308 -113.8555)
		(width 0.1016)
		(layer "F.Cu")
		(net "SMB_PEHPCPU0_STBY_LVC3_R_SDA")
	)
	(segment
		(start 421.8686 -116.84)
		(end 416.6616 -116.84)
		(width 0.1016)
		(layer "F.Cu")
		(net "SMB_PEHPCPU0_STBY_LVC3_R_SDA")
	)
	(segment
		(start 416.6616 -116.84)
		(end 416.5854 -116.7638)
		(width 0.1016)
		(layer "F.Cu")
		(net "SMB_PEHPCPU0_STBY_LVC3_R_SDA")
	)
	(segment
		(start 422.8211 -115.8875)
		(end 421.8686 -116.84)
		(width 0.1016)
		(layer "F.Cu")
		(net "SMB_PEHPCPU0_STBY_LVC3_R_SDA")
	)
	(segment
		(start 421.3225 -113.03)
		(end 421.3225 -113.792)
		(width 0.1016)
		(layer "F.Cu")
		(net "SMB_PEHPCPU0_STBY_LVC3_R_SDA")
	)
	(segment
		(start 420.94912 -111.125)
		(end 420.94912 -112.65662)
		(width 0.1016)
		(layer "F.Cu")
		(net "SMB_PEHPCPU0_STBY_LVC3_R_SDA")
	)
	(segment
		(start 420.94912 -112.65662)
		(end 421.3225 -113.03)
		(width 0.1016)
		(layer "F.Cu")
		(net "SMB_PEHPCPU0_STBY_LVC3_R_SDA")
	)
	(segment
		(start 421.3225 -113.792)
		(end 421.386 -113.8555)
		(width 0.1016)
		(layer "F.Cu")
		(net "SMB_PEHPCPU0_STBY_LVC3_R_SDA")
	)
	(via
		(at 416.5854 -116.7638)
		(size 0.508)
		(drill 0.254)
		(layers "F.Cu" "B.Cu")
		(net "SMB_PEHPCPU0_STBY_LVC3_R_SDA")
	)
	(via
		(at 404.0632 -35.0012)
		(size 0.508)
		(drill 0.254)
		(layers "F.Cu" "B.Cu")
		(net "SMB_PEHPCPU0_STBY_LVC3_R_SDA")
	)
	(via
		(at 470.122504 -54.088284)
		(size 0.508)
		(drill 0.254)
		(layers "F.Cu" "B.Cu")
		(net "SMB_PEHPCPU0_STBY_LVC3_R_SDA")
	)
	(via
		(at 427.8122 -59.329066)
		(size 0.508)
		(drill 0.254)
		(layers "F.Cu" "B.Cu")
		(net "SMB_PEHPCPU0_STBY_LVC3_R_SDA")
	)
	(via
		(at 462.622392 -36.432998)
		(size 0.508)
		(drill 0.254)
		(layers "F.Cu" "B.Cu")
		(net "SMB_PEHPCPU0_STBY_LVC3_R_SDA")
	)
	(via
		(at 457.384912 -60.68568)
		(size 0.6604)
		(drill 0.3302)
		(layers "F.Cu" "B.Cu")
		(net "SMB_PEHPCPU0_STBY_LVC3_R_SDA")
	)
	(segment
		(start 427.8122 -59.329066)
		(end 427.8122 -57.455816)
		(width 0.10795)
		(layer "B.Cu")
		(net "SMB_PEHPCPU0_STBY_LVC3_R_SDA")
	)
	(segment
		(start 462.545938 -57.219596)
		(end 462.685638 -57.079896)
		(width 0.089408)
		(layer "B.Cu")
		(net "SMB_PEHPCPU0_STBY_LVC3_R_SDA")
	)
	(segment
		(start 436.534052 -61.1632)
		(end 456.90028 -61.1632)
		(width 0.10795)
		(layer "B.Cu")
		(net "SMB_PEHPCPU0_STBY_LVC3_R_SDA")
	)
	(segment
		(start 435.620922 -57.694322)
		(end 435.620922 -60.25007)
		(width 0.10795)
		(layer "B.Cu")
		(net "SMB_PEHPCPU0_STBY_LVC3_R_SDA")
	)
	(segment
		(start 435.620922 -60.25007)
		(end 436.534052 -61.1632)
		(width 0.10795)
		(layer "B.Cu")
		(net "SMB_PEHPCPU0_STBY_LVC3_R_SDA")
	)
	(segment
		(start 462.197196 -57.568338)
		(end 462.197196 -57.506108)
		(width 0.089408)
		(layer "B.Cu")
		(net "SMB_PEHPCPU0_STBY_LVC3_R_SDA")
	)
	(segment
		(start 458.116178 -60.68568)
		(end 458.975206 -59.826652)
		(width 0.089408)
		(layer "B.Cu")
		(net "SMB_PEHPCPU0_STBY_LVC3_R_SDA")
	)
	(segment
		(start 458.975206 -59.826652)
		(end 459.938882 -59.826652)
		(width 0.089408)
		(layer "B.Cu")
		(net "SMB_PEHPCPU0_STBY_LVC3_R_SDA")
	)
	(segment
		(start 404.183088 -35.0012)
		(end 404.0632 -35.0012)
		(width 0.089408)
		(layer "B.Cu")
		(net "SMB_PEHPCPU0_STBY_LVC3_R_SDA")
	)
	(segment
		(start 469.4936 -54.5084)
		(end 469.913716 -54.088284)
		(width 0.089408)
		(layer "B.Cu")
		(net "SMB_PEHPCPU0_STBY_LVC3_R_SDA")
	)
	(segment
		(start 466.1408 -57.079896)
		(end 468.712296 -54.5084)
		(width 0.089408)
		(layer "B.Cu")
		(net "SMB_PEHPCPU0_STBY_LVC3_R_SDA")
	)
	(segment
		(start 405.3586 -34.313368)
		(end 405.046688 -34.313368)
		(width 0.089408)
		(layer "B.Cu")
		(net "SMB_PEHPCPU0_STBY_LVC3_R_SDA")
	)
	(segment
		(start 427.8122 -57.455816)
		(end 429.997616 -55.2704)
		(width 0.10795)
		(layer "B.Cu")
		(net "SMB_PEHPCPU0_STBY_LVC3_R_SDA")
	)
	(segment
		(start 462.685638 -57.079896)
		(end 466.1408 -57.079896)
		(width 0.089408)
		(layer "B.Cu")
		(net "SMB_PEHPCPU0_STBY_LVC3_R_SDA")
	)
	(segment
		(start 404.758906 -34.60115)
		(end 404.583138 -34.60115)
		(width 0.089408)
		(layer "B.Cu")
		(net "SMB_PEHPCPU0_STBY_LVC3_R_SDA")
	)
	(segment
		(start 429.997616 -55.2704)
		(end 433.197 -55.2704)
		(width 0.10795)
		(layer "B.Cu")
		(net "SMB_PEHPCPU0_STBY_LVC3_R_SDA")
	)
	(segment
		(start 457.384912 -60.68568)
		(end 458.116178 -60.68568)
		(width 0.089408)
		(layer "B.Cu")
		(net "SMB_PEHPCPU0_STBY_LVC3_R_SDA")
	)
	(segment
		(start 433.197 -55.2704)
		(end 435.620922 -57.694322)
		(width 0.10795)
		(layer "B.Cu")
		(net "SMB_PEHPCPU0_STBY_LVC3_R_SDA")
	)
	(segment
		(start 462.483708 -57.219596)
		(end 462.545938 -57.219596)
		(width 0.089408)
		(layer "B.Cu")
		(net "SMB_PEHPCPU0_STBY_LVC3_R_SDA")
	)
	(segment
		(start 457.3778 -60.68568)
		(end 457.384912 -60.68568)
		(width 0.10795)
		(layer "B.Cu")
		(net "SMB_PEHPCPU0_STBY_LVC3_R_SDA")
	)
	(segment
		(start 456.90028 -61.1632)
		(end 457.3778 -60.68568)
		(width 0.10795)
		(layer "B.Cu")
		(net "SMB_PEHPCPU0_STBY_LVC3_R_SDA")
	)
	(segment
		(start 462.197196 -57.506108)
		(end 462.483708 -57.219596)
		(width 0.089408)
		(layer "B.Cu")
		(net "SMB_PEHPCPU0_STBY_LVC3_R_SDA")
	)
	(segment
		(start 405.046688 -34.313368)
		(end 404.758906 -34.60115)
		(width 0.089408)
		(layer "B.Cu")
		(net "SMB_PEHPCPU0_STBY_LVC3_R_SDA")
	)
	(segment
		(start 469.913716 -54.088284)
		(end 470.122504 -54.088284)
		(width 0.089408)
		(layer "B.Cu")
		(net "SMB_PEHPCPU0_STBY_LVC3_R_SDA")
	)
	(segment
		(start 404.583138 -34.60115)
		(end 404.183088 -35.0012)
		(width 0.089408)
		(layer "B.Cu")
		(net "SMB_PEHPCPU0_STBY_LVC3_R_SDA")
	)
	(segment
		(start 459.938882 -59.826652)
		(end 462.197196 -57.568338)
		(width 0.089408)
		(layer "B.Cu")
		(net "SMB_PEHPCPU0_STBY_LVC3_R_SDA")
	)
	(segment
		(start 468.712296 -54.5084)
		(end 469.4936 -54.5084)
		(width 0.089408)
		(layer "B.Cu")
		(net "SMB_PEHPCPU0_STBY_LVC3_R_SDA")
	)
	(segment
		(start 418.220906 -63.756286)
		(end 418.220906 -64.867536)
		(width 0.089408)
		(layer "In2.Cu")
		(net "SMB_PEHPCPU0_STBY_LVC3_R_SDA")
	)
	(segment
		(start 415.017458 -89.671144)
		(end 415.017458 -93.923866)
		(width 0.089408)
		(layer "In2.Cu")
		(net "SMB_PEHPCPU0_STBY_LVC3_R_SDA")
	)
	(segment
		(start 416.353752 -106.301286)
		(end 415.555684 -107.099354)
		(width 0.089408)
		(layer "In2.Cu")
		(net "SMB_PEHPCPU0_STBY_LVC3_R_SDA")
	)
	(segment
		(start 415.017458 -85.164422)
		(end 415.017458 -86.836758)
		(width 0.089408)
		(layer "In2.Cu")
		(net "SMB_PEHPCPU0_STBY_LVC3_R_SDA")
	)
	(segment
		(start 416.354006 -104.471216)
		(end 416.353752 -104.47147)
		(width 0.089408)
		(layer "In2.Cu")
		(net "SMB_PEHPCPU0_STBY_LVC3_R_SDA")
	)
	(segment
		(start 416.353752 -104.257348)
		(end 416.353752 -104.312974)
		(width 0.089408)
		(layer "In2.Cu")
		(net "SMB_PEHPCPU0_STBY_LVC3_R_SDA")
	)
	(segment
		(start 417.386008 -76.410312)
		(end 417.386008 -82.637376)
		(width 0.089408)
		(layer "In2.Cu")
		(net "SMB_PEHPCPU0_STBY_LVC3_R_SDA")
	)
	(segment
		(start 415.899092 -95.345504)
		(end 415.899092 -103.802688)
		(width 0.089408)
		(layer "In2.Cu")
		(net "SMB_PEHPCPU0_STBY_LVC3_R_SDA")
	)
	(segment
		(start 415.017458 -93.923866)
		(end 415.409126 -94.315534)
		(width 0.089408)
		(layer "In2.Cu")
		(net "SMB_PEHPCPU0_STBY_LVC3_R_SDA")
	)
	(segment
		(start 417.98875 -75.80757)
		(end 417.386008 -76.410312)
		(width 0.089408)
		(layer "In2.Cu")
		(net "SMB_PEHPCPU0_STBY_LVC3_R_SDA")
	)
	(segment
		(start 415.332672 -109.470444)
		(end 415.332672 -112.159288)
		(width 0.089408)
		(layer "In2.Cu")
		(net "SMB_PEHPCPU0_STBY_LVC3_R_SDA")
	)
	(segment
		(start 417.989004 -75.670918)
		(end 417.98875 -75.671172)
		(width 0.089408)
		(layer "In2.Cu")
		(net "SMB_PEHPCPU0_STBY_LVC3_R_SDA")
	)
	(segment
		(start 427.8122 -59.033156)
		(end 427.722792 -58.943748)
		(width 0.089408)
		(layer "In2.Cu")
		(net "SMB_PEHPCPU0_STBY_LVC3_R_SDA")
	)
	(segment
		(start 417.98875 -75.671172)
		(end 417.98875 -75.80757)
		(width 0.089408)
		(layer "In2.Cu")
		(net "SMB_PEHPCPU0_STBY_LVC3_R_SDA")
	)
	(segment
		(start 423.033444 -58.943748)
		(end 418.220906 -63.756286)
		(width 0.089408)
		(layer "In2.Cu")
		(net "SMB_PEHPCPU0_STBY_LVC3_R_SDA")
	)
	(segment
		(start 415.409126 -94.855538)
		(end 415.899092 -95.345504)
		(width 0.089408)
		(layer "In2.Cu")
		(net "SMB_PEHPCPU0_STBY_LVC3_R_SDA")
	)
	(segment
		(start 415.555684 -109.247432)
		(end 415.332672 -109.470444)
		(width 0.089408)
		(layer "In2.Cu")
		(net "SMB_PEHPCPU0_STBY_LVC3_R_SDA")
	)
	(segment
		(start 415.017458 -89.354152)
		(end 415.017204 -89.354406)
		(width 0.089408)
		(layer "In2.Cu")
		(net "SMB_PEHPCPU0_STBY_LVC3_R_SDA")
	)
	(segment
		(start 418.220906 -64.867536)
		(end 418.220652 -64.86779)
		(width 0.089408)
		(layer "In2.Cu")
		(net "SMB_PEHPCPU0_STBY_LVC3_R_SDA")
	)
	(segment
		(start 416.354006 -104.313228)
		(end 416.354006 -104.471216)
		(width 0.089408)
		(layer "In2.Cu")
		(net "SMB_PEHPCPU0_STBY_LVC3_R_SDA")
	)
	(segment
		(start 418.220652 -64.86779)
		(end 418.220652 -71.002398)
		(width 0.089408)
		(layer "In2.Cu")
		(net "SMB_PEHPCPU0_STBY_LVC3_R_SDA")
	)
	(segment
		(start 415.017204 -89.354406)
		(end 415.017204 -89.67089)
		(width 0.089408)
		(layer "In2.Cu")
		(net "SMB_PEHPCPU0_STBY_LVC3_R_SDA")
	)
	(segment
		(start 417.98875 -71.2343)
		(end 417.98875 -75.512676)
		(width 0.089408)
		(layer "In2.Cu")
		(net "SMB_PEHPCPU0_STBY_LVC3_R_SDA")
	)
	(segment
		(start 415.605468 -115.783868)
		(end 416.5854 -116.7638)
		(width 0.089408)
		(layer "In2.Cu")
		(net "SMB_PEHPCPU0_STBY_LVC3_R_SDA")
	)
	(segment
		(start 427.8122 -59.329066)
		(end 427.8122 -59.033156)
		(width 0.089408)
		(layer "In2.Cu")
		(net "SMB_PEHPCPU0_STBY_LVC3_R_SDA")
	)
	(segment
		(start 427.722792 -58.943748)
		(end 423.033444 -58.943748)
		(width 0.089408)
		(layer "In2.Cu")
		(net "SMB_PEHPCPU0_STBY_LVC3_R_SDA")
	)
	(segment
		(start 417.989004 -75.51293)
		(end 417.989004 -75.670918)
		(width 0.089408)
		(layer "In2.Cu")
		(net "SMB_PEHPCPU0_STBY_LVC3_R_SDA")
	)
	(segment
		(start 417.386262 -82.63763)
		(end 417.386262 -82.795618)
		(width 0.089408)
		(layer "In2.Cu")
		(net "SMB_PEHPCPU0_STBY_LVC3_R_SDA")
	)
	(segment
		(start 417.98875 -75.512676)
		(end 417.989004 -75.51293)
		(width 0.089408)
		(layer "In2.Cu")
		(net "SMB_PEHPCPU0_STBY_LVC3_R_SDA")
	)
	(segment
		(start 417.386262 -82.795618)
		(end 415.017458 -85.164422)
		(width 0.089408)
		(layer "In2.Cu")
		(net "SMB_PEHPCPU0_STBY_LVC3_R_SDA")
	)
	(segment
		(start 417.386008 -82.637376)
		(end 417.386262 -82.63763)
		(width 0.089408)
		(layer "In2.Cu")
		(net "SMB_PEHPCPU0_STBY_LVC3_R_SDA")
	)
	(segment
		(start 415.056066 -87.594186)
		(end 415.017458 -87.632794)
		(width 0.089408)
		(layer "In2.Cu")
		(net "SMB_PEHPCPU0_STBY_LVC3_R_SDA")
	)
	(segment
		(start 416.353752 -104.47147)
		(end 416.353752 -106.301286)
		(width 0.089408)
		(layer "In2.Cu")
		(net "SMB_PEHPCPU0_STBY_LVC3_R_SDA")
	)
	(segment
		(start 415.899092 -103.802688)
		(end 416.353752 -104.257348)
		(width 0.089408)
		(layer "In2.Cu")
		(net "SMB_PEHPCPU0_STBY_LVC3_R_SDA")
	)
	(segment
		(start 416.353752 -104.312974)
		(end 416.354006 -104.313228)
		(width 0.089408)
		(layer "In2.Cu")
		(net "SMB_PEHPCPU0_STBY_LVC3_R_SDA")
	)
	(segment
		(start 415.605468 -112.432084)
		(end 415.605468 -115.783868)
		(width 0.089408)
		(layer "In2.Cu")
		(net "SMB_PEHPCPU0_STBY_LVC3_R_SDA")
	)
	(segment
		(start 415.017458 -86.836758)
		(end 415.056066 -86.875366)
		(width 0.089408)
		(layer "In2.Cu")
		(net "SMB_PEHPCPU0_STBY_LVC3_R_SDA")
	)
	(segment
		(start 418.220652 -71.002398)
		(end 417.98875 -71.2343)
		(width 0.089408)
		(layer "In2.Cu")
		(net "SMB_PEHPCPU0_STBY_LVC3_R_SDA")
	)
	(segment
		(start 415.409126 -94.315534)
		(end 415.409126 -94.855538)
		(width 0.089408)
		(layer "In2.Cu")
		(net "SMB_PEHPCPU0_STBY_LVC3_R_SDA")
	)
	(segment
		(start 415.332672 -112.159288)
		(end 415.605468 -112.432084)
		(width 0.089408)
		(layer "In2.Cu")
		(net "SMB_PEHPCPU0_STBY_LVC3_R_SDA")
	)
	(segment
		(start 415.017204 -89.67089)
		(end 415.017458 -89.671144)
		(width 0.089408)
		(layer "In2.Cu")
		(net "SMB_PEHPCPU0_STBY_LVC3_R_SDA")
	)
	(segment
		(start 415.017458 -87.632794)
		(end 415.017458 -89.354152)
		(width 0.089408)
		(layer "In2.Cu")
		(net "SMB_PEHPCPU0_STBY_LVC3_R_SDA")
	)
	(segment
		(start 415.555684 -107.099354)
		(end 415.555684 -109.247432)
		(width 0.089408)
		(layer "In2.Cu")
		(net "SMB_PEHPCPU0_STBY_LVC3_R_SDA")
	)
	(segment
		(start 415.056066 -86.875366)
		(end 415.056066 -87.594186)
		(width 0.089408)
		(layer "In2.Cu")
		(net "SMB_PEHPCPU0_STBY_LVC3_R_SDA")
	)
	(segment
		(start 412.445454 -33.759902)
		(end 408.935174 -33.759902)
		(width 0.089408)
		(layer "In4.Cu")
		(net "SMB_PEHPCPU0_STBY_LVC3_R_SDA")
	)
	(segment
		(start 408.394662 -34.560002)
		(end 405.058626 -34.560002)
		(width 0.089408)
		(layer "In4.Cu")
		(net "SMB_PEHPCPU0_STBY_LVC3_R_SDA")
	)
	(segment
		(start 442.655706 -38.3032)
		(end 435.294024 -38.3032)
		(width 0.089408)
		(layer "In4.Cu")
		(net "SMB_PEHPCPU0_STBY_LVC3_R_SDA")
	)
	(segment
		(start 462.622392 -36.432998)
		(end 462.622392 -36.478464)
		(width 0.089408)
		(layer "In4.Cu")
		(net "SMB_PEHPCPU0_STBY_LVC3_R_SDA")
	)
	(segment
		(start 462.247996 -36.85286)
		(end 459.810104 -36.85286)
		(width 0.089408)
		(layer "In4.Cu")
		(net "SMB_PEHPCPU0_STBY_LVC3_R_SDA")
	)
	(segment
		(start 405.058626 -34.560002)
		(end 405.05761 -34.558986)
		(width 0.089408)
		(layer "In4.Cu")
		(net "SMB_PEHPCPU0_STBY_LVC3_R_SDA")
	)
	(segment
		(start 414.049464 -37.3888)
		(end 413.192214 -36.53155)
		(width 0.089408)
		(layer "In4.Cu")
		(net "SMB_PEHPCPU0_STBY_LVC3_R_SDA")
	)
	(segment
		(start 408.935174 -33.759902)
		(end 408.715464 -33.979612)
		(width 0.089408)
		(layer "In4.Cu")
		(net "SMB_PEHPCPU0_STBY_LVC3_R_SDA")
	)
	(segment
		(start 408.715464 -33.979612)
		(end 408.715464 -34.2392)
		(width 0.089408)
		(layer "In4.Cu")
		(net "SMB_PEHPCPU0_STBY_LVC3_R_SDA")
	)
	(segment
		(start 435.294024 -38.3032)
		(end 434.015642 -37.024818)
		(width 0.089408)
		(layer "In4.Cu")
		(net "SMB_PEHPCPU0_STBY_LVC3_R_SDA")
	)
	(segment
		(start 404.505414 -34.558986)
		(end 404.0632 -35.0012)
		(width 0.089408)
		(layer "In4.Cu")
		(net "SMB_PEHPCPU0_STBY_LVC3_R_SDA")
	)
	(segment
		(start 462.622392 -36.478464)
		(end 462.247996 -36.85286)
		(width 0.089408)
		(layer "In4.Cu")
		(net "SMB_PEHPCPU0_STBY_LVC3_R_SDA")
	)
	(segment
		(start 413.192214 -34.506662)
		(end 412.445454 -33.759902)
		(width 0.089408)
		(layer "In4.Cu")
		(net "SMB_PEHPCPU0_STBY_LVC3_R_SDA")
	)
	(segment
		(start 458.492098 -35.534854)
		(end 447.405506 -35.534854)
		(width 0.089408)
		(layer "In4.Cu")
		(net "SMB_PEHPCPU0_STBY_LVC3_R_SDA")
	)
	(segment
		(start 434.015642 -37.024818)
		(end 424.010582 -37.024818)
		(width 0.089408)
		(layer "In4.Cu")
		(net "SMB_PEHPCPU0_STBY_LVC3_R_SDA")
	)
	(segment
		(start 424.010582 -37.024818)
		(end 423.296842 -37.738558)
		(width 0.089408)
		(layer "In4.Cu")
		(net "SMB_PEHPCPU0_STBY_LVC3_R_SDA")
	)
	(segment
		(start 419.360858 -37.738558)
		(end 419.0111 -37.3888)
		(width 0.089408)
		(layer "In4.Cu")
		(net "SMB_PEHPCPU0_STBY_LVC3_R_SDA")
	)
	(segment
		(start 419.0111 -37.3888)
		(end 414.049464 -37.3888)
		(width 0.089408)
		(layer "In4.Cu")
		(net "SMB_PEHPCPU0_STBY_LVC3_R_SDA")
	)
	(segment
		(start 443.25286 -37.706046)
		(end 442.655706 -38.3032)
		(width 0.089408)
		(layer "In4.Cu")
		(net "SMB_PEHPCPU0_STBY_LVC3_R_SDA")
	)
	(segment
		(start 405.05761 -34.558986)
		(end 404.505414 -34.558986)
		(width 0.089408)
		(layer "In4.Cu")
		(net "SMB_PEHPCPU0_STBY_LVC3_R_SDA")
	)
	(segment
		(start 445.234314 -37.706046)
		(end 443.25286 -37.706046)
		(width 0.089408)
		(layer "In4.Cu")
		(net "SMB_PEHPCPU0_STBY_LVC3_R_SDA")
	)
	(segment
		(start 459.810104 -36.85286)
		(end 458.492098 -35.534854)
		(width 0.089408)
		(layer "In4.Cu")
		(net "SMB_PEHPCPU0_STBY_LVC3_R_SDA")
	)
	(segment
		(start 423.296842 -37.738558)
		(end 419.360858 -37.738558)
		(width 0.089408)
		(layer "In4.Cu")
		(net "SMB_PEHPCPU0_STBY_LVC3_R_SDA")
	)
	(segment
		(start 447.405506 -35.534854)
		(end 445.234314 -37.706046)
		(width 0.089408)
		(layer "In4.Cu")
		(net "SMB_PEHPCPU0_STBY_LVC3_R_SDA")
	)
	(segment
		(start 408.715464 -34.2392)
		(end 408.394662 -34.560002)
		(width 0.089408)
		(layer "In4.Cu")
		(net "SMB_PEHPCPU0_STBY_LVC3_R_SDA")
	)
	(segment
		(start 413.192214 -36.53155)
		(end 413.192214 -34.506662)
		(width 0.089408)
		(layer "In4.Cu")
		(net "SMB_PEHPCPU0_STBY_LVC3_R_SDA")
	)
	(segment
		(start 469.8238 -53.74513)
		(end 469.8238 -53.6702)
		(width 0.0889)
		(layer "In9.Cu")
		(net "SMB_PEHPCPU0_STBY_LVC3_R_SDA")
	)
	(segment
		(start 462.838292 -35.712908)
		(end 462.838292 -36.217098)
		(width 0.089408)
		(layer "In9.Cu")
		(net "SMB_PEHPCPU0_STBY_LVC3_R_SDA")
	)
	(segment
		(start 468.094314 -43.738038)
		(end 468.094314 -37.426138)
		(width 0.0889)
		(layer "In9.Cu")
		(net "SMB_PEHPCPU0_STBY_LVC3_R_SDA")
	)
	(segment
		(start 463.442812 -35.108388)
		(end 462.838292 -35.712908)
		(width 0.0889)
		(layer "In9.Cu")
		(net "SMB_PEHPCPU0_STBY_LVC3_R_SDA")
	)
	(segment
		(start 468.023702 -48.376078)
		(end 469.49995 -46.89983)
		(width 0.0889)
		(layer "In9.Cu")
		(net "SMB_PEHPCPU0_STBY_LVC3_R_SDA")
	)
	(segment
		(start 468.023702 -51.870102)
		(end 468.023702 -48.376078)
		(width 0.0889)
		(layer "In9.Cu")
		(net "SMB_PEHPCPU0_STBY_LVC3_R_SDA")
	)
	(segment
		(start 469.8238 -53.6702)
		(end 468.023702 -51.870102)
		(width 0.0889)
		(layer "In9.Cu")
		(net "SMB_PEHPCPU0_STBY_LVC3_R_SDA")
	)
	(segment
		(start 469.49995 -46.89983)
		(end 469.49995 -45.143674)
		(width 0.0889)
		(layer "In9.Cu")
		(net "SMB_PEHPCPU0_STBY_LVC3_R_SDA")
	)
	(segment
		(start 462.838292 -36.217098)
		(end 462.622392 -36.432998)
		(width 0.089408)
		(layer "In9.Cu")
		(net "SMB_PEHPCPU0_STBY_LVC3_R_SDA")
	)
	(segment
		(start 468.094314 -37.426138)
		(end 465.776564 -35.108388)
		(width 0.0889)
		(layer "In9.Cu")
		(net "SMB_PEHPCPU0_STBY_LVC3_R_SDA")
	)
	(segment
		(start 470.122504 -54.088284)
		(end 470.122504 -54.043834)
		(width 0.0889)
		(layer "In9.Cu")
		(net "SMB_PEHPCPU0_STBY_LVC3_R_SDA")
	)
	(segment
		(start 465.776564 -35.108388)
		(end 463.442812 -35.108388)
		(width 0.0889)
		(layer "In9.Cu")
		(net "SMB_PEHPCPU0_STBY_LVC3_R_SDA")
	)
	(segment
		(start 469.49995 -45.143674)
		(end 468.094314 -43.738038)
		(width 0.0889)
		(layer "In9.Cu")
		(net "SMB_PEHPCPU0_STBY_LVC3_R_SDA")
	)
	(segment
		(start 470.122504 -54.043834)
		(end 469.8238 -53.74513)
		(width 0.0889)
		(layer "In9.Cu")
		(net "SMB_PEHPCPU0_STBY_LVC3_R_SDA")
	)
	(segment
		(start 420.29888 -112.89538)
		(end 420.4335 -113.03)
		(width 0.1016)
		(layer "F.Cu")
		(net "SMB_PEHPCPU0_STBY_LVC3_R_SCL")
	)
	(segment
		(start 420.624 -113.2205)
		(end 420.624 -113.8555)
		(width 0.1016)
		(layer "F.Cu")
		(net "SMB_PEHPCPU0_STBY_LVC3_R_SCL")
	)
	(segment
		(start 420.0652 -114.8334)
		(end 420.0652 -114.1476)
		(width 0.1016)
		(layer "F.Cu")
		(net "SMB_PEHPCPU0_STBY_LVC3_R_SCL")
	)
	(segment
		(start 420.4335 -113.03)
		(end 420.624 -113.2205)
		(width 0.1016)
		(layer "F.Cu")
		(net "SMB_PEHPCPU0_STBY_LVC3_R_SCL")
	)
	(segment
		(start 416.7378 -116.2304)
		(end 418.6682 -116.2304)
		(width 0.1016)
		(layer "F.Cu")
		(net "SMB_PEHPCPU0_STBY_LVC3_R_SCL")
	)
	(segment
		(start 420.0652 -114.1476)
		(end 420.3573 -113.8555)
		(width 0.1016)
		(layer "F.Cu")
		(net "SMB_PEHPCPU0_STBY_LVC3_R_SCL")
	)
	(segment
		(start 418.6682 -116.2304)
		(end 420.0652 -114.8334)
		(width 0.1016)
		(layer "F.Cu")
		(net "SMB_PEHPCPU0_STBY_LVC3_R_SCL")
	)
	(segment
		(start 420.3573 -113.8555)
		(end 420.624 -113.8555)
		(width 0.1016)
		(layer "F.Cu")
		(net "SMB_PEHPCPU0_STBY_LVC3_R_SCL")
	)
	(segment
		(start 420.29888 -111.125)
		(end 420.29888 -112.89538)
		(width 0.1016)
		(layer "F.Cu")
		(net "SMB_PEHPCPU0_STBY_LVC3_R_SCL")
	)
	(segment
		(start 416.56 -116.0526)
		(end 416.7378 -116.2304)
		(width 0.1016)
		(layer "F.Cu")
		(net "SMB_PEHPCPU0_STBY_LVC3_R_SCL")
	)
	(via
		(at 456.020932 -60.621926)
		(size 0.6604)
		(drill 0.3302)
		(layers "F.Cu" "B.Cu")
		(net "SMB_PEHPCPU0_STBY_LVC3_R_SCL")
	)
	(via
		(at 463.425286 -36.487862)
		(size 0.508)
		(drill 0.254)
		(layers "F.Cu" "B.Cu")
		(net "SMB_PEHPCPU0_STBY_LVC3_R_SCL")
	)
	(via
		(at 427.134528 -59.35091)
		(size 0.508)
		(drill 0.254)
		(layers "F.Cu" "B.Cu")
		(net "SMB_PEHPCPU0_STBY_LVC3_R_SCL")
	)
	(via
		(at 469.315546 -54.088284)
		(size 0.508)
		(drill 0.254)
		(layers "F.Cu" "B.Cu")
		(net "SMB_PEHPCPU0_STBY_LVC3_R_SCL")
	)
	(via
		(at 416.56 -116.0526)
		(size 0.508)
		(drill 0.254)
		(layers "F.Cu" "B.Cu")
		(net "SMB_PEHPCPU0_STBY_LVC3_R_SCL")
	)
	(via
		(at 404.749 -35.0012)
		(size 0.508)
		(drill 0.254)
		(layers "F.Cu" "B.Cu")
		(net "SMB_PEHPCPU0_STBY_LVC3_R_SCL")
	)
	(segment
		(start 427.1772 -57.731406)
		(end 429.883062 -55.025544)
		(width 0.10795)
		(layer "B.Cu")
		(net "SMB_PEHPCPU0_STBY_LVC3_R_SCL")
	)
	(segment
		(start 433.2986 -55.025544)
		(end 435.885082 -57.612026)
		(width 0.10795)
		(layer "B.Cu")
		(net "SMB_PEHPCPU0_STBY_LVC3_R_SCL")
	)
	(segment
		(start 404.84171 -35.09391)
		(end 404.749 -35.0012)
		(width 0.089408)
		(layer "B.Cu")
		(net "SMB_PEHPCPU0_STBY_LVC3_R_SCL")
	)
	(segment
		(start 435.885082 -57.612026)
		(end 435.885082 -60.15482)
		(width 0.10795)
		(layer "B.Cu")
		(net "SMB_PEHPCPU0_STBY_LVC3_R_SCL")
	)
	(segment
		(start 460.686658 -56.825896)
		(end 465.982304 -56.825896)
		(width 0.089408)
		(layer "B.Cu")
		(net "SMB_PEHPCPU0_STBY_LVC3_R_SCL")
	)
	(segment
		(start 458.318362 -60.120276)
		(end 459.282038 -59.1566)
		(width 0.089408)
		(layer "B.Cu")
		(net "SMB_PEHPCPU0_STBY_LVC3_R_SCL")
	)
	(segment
		(start 436.639462 -60.9092)
		(end 455.733658 -60.9092)
		(width 0.10795)
		(layer "B.Cu")
		(net "SMB_PEHPCPU0_STBY_LVC3_R_SCL")
	)
	(segment
		(start 468.719916 -54.088284)
		(end 469.315546 -54.088284)
		(width 0.089408)
		(layer "B.Cu")
		(net "SMB_PEHPCPU0_STBY_LVC3_R_SCL")
	)
	(segment
		(start 456.020932 -60.621926)
		(end 456.522582 -60.120276)
		(width 0.089408)
		(layer "B.Cu")
		(net "SMB_PEHPCPU0_STBY_LVC3_R_SCL")
	)
	(segment
		(start 427.134528 -59.35091)
		(end 427.134528 -59.241436)
		(width 0.10795)
		(layer "B.Cu")
		(net "SMB_PEHPCPU0_STBY_LVC3_R_SCL")
	)
	(segment
		(start 427.1772 -59.198764)
		(end 427.1772 -57.731406)
		(width 0.10795)
		(layer "B.Cu")
		(net "SMB_PEHPCPU0_STBY_LVC3_R_SCL")
	)
	(segment
		(start 427.134528 -59.241436)
		(end 427.1772 -59.198764)
		(width 0.10795)
		(layer "B.Cu")
		(net "SMB_PEHPCPU0_STBY_LVC3_R_SCL")
	)
	(segment
		(start 465.982304 -56.825896)
		(end 468.719916 -54.088284)
		(width 0.089408)
		(layer "B.Cu")
		(net "SMB_PEHPCPU0_STBY_LVC3_R_SCL")
	)
	(segment
		(start 459.282038 -58.230516)
		(end 460.686658 -56.825896)
		(width 0.089408)
		(layer "B.Cu")
		(net "SMB_PEHPCPU0_STBY_LVC3_R_SCL")
	)
	(segment
		(start 429.883062 -55.025544)
		(end 433.2986 -55.025544)
		(width 0.10795)
		(layer "B.Cu")
		(net "SMB_PEHPCPU0_STBY_LVC3_R_SCL")
	)
	(segment
		(start 405.358854 -35.09391)
		(end 404.84171 -35.09391)
		(width 0.089408)
		(layer "B.Cu")
		(net "SMB_PEHPCPU0_STBY_LVC3_R_SCL")
	)
	(segment
		(start 459.282038 -59.1566)
		(end 459.282038 -58.230516)
		(width 0.089408)
		(layer "B.Cu")
		(net "SMB_PEHPCPU0_STBY_LVC3_R_SCL")
	)
	(segment
		(start 455.733658 -60.9092)
		(end 456.020932 -60.621926)
		(width 0.10795)
		(layer "B.Cu")
		(net "SMB_PEHPCPU0_STBY_LVC3_R_SCL")
	)
	(segment
		(start 456.522582 -60.120276)
		(end 458.318362 -60.120276)
		(width 0.089408)
		(layer "B.Cu")
		(net "SMB_PEHPCPU0_STBY_LVC3_R_SCL")
	)
	(segment
		(start 435.885082 -60.15482)
		(end 436.639462 -60.9092)
		(width 0.10795)
		(layer "B.Cu")
		(net "SMB_PEHPCPU0_STBY_LVC3_R_SCL")
	)
	(segment
		(start 418.179758 -71.313548)
		(end 418.41166 -71.081646)
		(width 0.089408)
		(layer "In2.Cu")
		(net "SMB_PEHPCPU0_STBY_LVC3_R_SCL")
	)
	(segment
		(start 422.896538 -59.35091)
		(end 427.134528 -59.35091)
		(width 0.089408)
		(layer "In2.Cu")
		(net "SMB_PEHPCPU0_STBY_LVC3_R_SCL")
	)
	(segment
		(start 418.411914 -64.946784)
		(end 418.411914 -63.835534)
		(width 0.089408)
		(layer "In2.Cu")
		(net "SMB_PEHPCPU0_STBY_LVC3_R_SCL")
	)
	(segment
		(start 415.208466 -88.784176)
		(end 415.863278 -88.129364)
		(width 0.089408)
		(layer "In2.Cu")
		(net "SMB_PEHPCPU0_STBY_LVC3_R_SCL")
	)
	(segment
		(start 417.577016 -82.87512)
		(end 417.57727 -82.874866)
		(width 0.089408)
		(layer "In2.Cu")
		(net "SMB_PEHPCPU0_STBY_LVC3_R_SCL")
	)
	(segment
		(start 415.796476 -112.353344)
		(end 415.79673 -112.35309)
		(width 0.089408)
		(layer "In2.Cu")
		(net "SMB_PEHPCPU0_STBY_LVC3_R_SCL")
	)
	(segment
		(start 417.57727 -82.874866)
		(end 417.57727 -82.558382)
		(width 0.089408)
		(layer "In2.Cu")
		(net "SMB_PEHPCPU0_STBY_LVC3_R_SCL")
	)
	(segment
		(start 416.545014 -104.23398)
		(end 416.54476 -104.233726)
		(width 0.089408)
		(layer "In2.Cu")
		(net "SMB_PEHPCPU0_STBY_LVC3_R_SCL")
	)
	(segment
		(start 415.600134 -94.236286)
		(end 415.208466 -93.844618)
		(width 0.089408)
		(layer "In2.Cu")
		(net "SMB_PEHPCPU0_STBY_LVC3_R_SCL")
	)
	(segment
		(start 418.180012 -75.59167)
		(end 418.180012 -75.433682)
		(width 0.089408)
		(layer "In2.Cu")
		(net "SMB_PEHPCPU0_STBY_LVC3_R_SCL")
	)
	(segment
		(start 415.746692 -107.178602)
		(end 416.54476 -106.380534)
		(width 0.089408)
		(layer "In2.Cu")
		(net "SMB_PEHPCPU0_STBY_LVC3_R_SCL")
	)
	(segment
		(start 415.52368 -112.08004)
		(end 415.52368 -109.549692)
		(width 0.089408)
		(layer "In2.Cu")
		(net "SMB_PEHPCPU0_STBY_LVC3_R_SCL")
	)
	(segment
		(start 416.0901 -103.65232)
		(end 416.0901 -95.266256)
		(width 0.089408)
		(layer "In2.Cu")
		(net "SMB_PEHPCPU0_STBY_LVC3_R_SCL")
	)
	(segment
		(start 415.863278 -86.39429)
		(end 417.577016 -84.680552)
		(width 0.089408)
		(layer "In2.Cu")
		(net "SMB_PEHPCPU0_STBY_LVC3_R_SCL")
	)
	(segment
		(start 416.453828 -116.0526)
		(end 415.796476 -115.395248)
		(width 0.089408)
		(layer "In2.Cu")
		(net "SMB_PEHPCPU0_STBY_LVC3_R_SCL")
	)
	(segment
		(start 416.56 -116.0526)
		(end 416.453828 -116.0526)
		(width 0.089408)
		(layer "In2.Cu")
		(net "SMB_PEHPCPU0_STBY_LVC3_R_SCL")
	)
	(segment
		(start 418.179758 -75.886818)
		(end 418.179758 -75.75042)
		(width 0.089408)
		(layer "In2.Cu")
		(net "SMB_PEHPCPU0_STBY_LVC3_R_SCL")
	)
	(segment
		(start 418.179758 -75.75042)
		(end 418.180266 -75.749912)
		(width 0.089408)
		(layer "In2.Cu")
		(net "SMB_PEHPCPU0_STBY_LVC3_R_SCL")
	)
	(segment
		(start 417.577016 -76.48956)
		(end 418.179758 -75.886818)
		(width 0.089408)
		(layer "In2.Cu")
		(net "SMB_PEHPCPU0_STBY_LVC3_R_SCL")
	)
	(segment
		(start 418.180266 -75.591924)
		(end 418.180012 -75.59167)
		(width 0.089408)
		(layer "In2.Cu")
		(net "SMB_PEHPCPU0_STBY_LVC3_R_SCL")
	)
	(segment
		(start 416.54476 -104.233726)
		(end 416.54476 -104.10698)
		(width 0.089408)
		(layer "In2.Cu")
		(net "SMB_PEHPCPU0_STBY_LVC3_R_SCL")
	)
	(segment
		(start 415.796476 -115.395248)
		(end 415.796476 -112.353344)
		(width 0.089408)
		(layer "In2.Cu")
		(net "SMB_PEHPCPU0_STBY_LVC3_R_SCL")
	)
	(segment
		(start 416.54476 -106.380534)
		(end 416.54476 -104.550718)
		(width 0.089408)
		(layer "In2.Cu")
		(net "SMB_PEHPCPU0_STBY_LVC3_R_SCL")
	)
	(segment
		(start 415.79673 -112.35309)
		(end 415.52368 -112.08004)
		(width 0.089408)
		(layer "In2.Cu")
		(net "SMB_PEHPCPU0_STBY_LVC3_R_SCL")
	)
	(segment
		(start 415.52368 -109.549692)
		(end 415.746692 -109.32668)
		(width 0.089408)
		(layer "In2.Cu")
		(net "SMB_PEHPCPU0_STBY_LVC3_R_SCL")
	)
	(segment
		(start 418.179758 -75.433428)
		(end 418.179758 -71.313548)
		(width 0.089408)
		(layer "In2.Cu")
		(net "SMB_PEHPCPU0_STBY_LVC3_R_SCL")
	)
	(segment
		(start 417.57727 -82.558382)
		(end 417.577016 -82.558128)
		(width 0.089408)
		(layer "In2.Cu")
		(net "SMB_PEHPCPU0_STBY_LVC3_R_SCL")
	)
	(segment
		(start 417.577016 -84.680552)
		(end 417.577016 -82.87512)
		(width 0.089408)
		(layer "In2.Cu")
		(net "SMB_PEHPCPU0_STBY_LVC3_R_SCL")
	)
	(segment
		(start 418.41166 -71.081646)
		(end 418.41166 -64.947038)
		(width 0.089408)
		(layer "In2.Cu")
		(net "SMB_PEHPCPU0_STBY_LVC3_R_SCL")
	)
	(segment
		(start 415.863278 -88.129364)
		(end 415.863278 -86.39429)
		(width 0.089408)
		(layer "In2.Cu")
		(net "SMB_PEHPCPU0_STBY_LVC3_R_SCL")
	)
	(segment
		(start 415.600134 -94.77629)
		(end 415.600134 -94.236286)
		(width 0.089408)
		(layer "In2.Cu")
		(net "SMB_PEHPCPU0_STBY_LVC3_R_SCL")
	)
	(segment
		(start 416.54476 -104.10698)
		(end 416.0901 -103.65232)
		(width 0.089408)
		(layer "In2.Cu")
		(net "SMB_PEHPCPU0_STBY_LVC3_R_SCL")
	)
	(segment
		(start 418.411914 -63.835534)
		(end 422.896538 -59.35091)
		(width 0.089408)
		(layer "In2.Cu")
		(net "SMB_PEHPCPU0_STBY_LVC3_R_SCL")
	)
	(segment
		(start 416.545014 -104.550464)
		(end 416.545014 -104.23398)
		(width 0.089408)
		(layer "In2.Cu")
		(net "SMB_PEHPCPU0_STBY_LVC3_R_SCL")
	)
	(segment
		(start 418.180266 -75.749912)
		(end 418.180266 -75.591924)
		(width 0.089408)
		(layer "In2.Cu")
		(net "SMB_PEHPCPU0_STBY_LVC3_R_SCL")
	)
	(segment
		(start 418.41166 -64.947038)
		(end 418.411914 -64.946784)
		(width 0.089408)
		(layer "In2.Cu")
		(net "SMB_PEHPCPU0_STBY_LVC3_R_SCL")
	)
	(segment
		(start 418.180012 -75.433682)
		(end 418.179758 -75.433428)
		(width 0.089408)
		(layer "In2.Cu")
		(net "SMB_PEHPCPU0_STBY_LVC3_R_SCL")
	)
	(segment
		(start 415.746692 -109.32668)
		(end 415.746692 -107.178602)
		(width 0.089408)
		(layer "In2.Cu")
		(net "SMB_PEHPCPU0_STBY_LVC3_R_SCL")
	)
	(segment
		(start 416.0901 -95.266256)
		(end 415.600134 -94.77629)
		(width 0.089408)
		(layer "In2.Cu")
		(net "SMB_PEHPCPU0_STBY_LVC3_R_SCL")
	)
	(segment
		(start 417.577016 -82.558128)
		(end 417.577016 -76.48956)
		(width 0.089408)
		(layer "In2.Cu")
		(net "SMB_PEHPCPU0_STBY_LVC3_R_SCL")
	)
	(segment
		(start 415.208466 -93.844618)
		(end 415.208466 -88.784176)
		(width 0.089408)
		(layer "In2.Cu")
		(net "SMB_PEHPCPU0_STBY_LVC3_R_SCL")
	)
	(segment
		(start 416.54476 -104.550718)
		(end 416.545014 -104.550464)
		(width 0.089408)
		(layer "In2.Cu")
		(net "SMB_PEHPCPU0_STBY_LVC3_R_SCL")
	)
	(segment
		(start 442.709808 -38.5191)
		(end 443.290706 -37.938202)
		(width 0.089408)
		(layer "In4.Cu")
		(net "SMB_PEHPCPU0_STBY_LVC3_R_SCL")
	)
	(segment
		(start 412.834836 -36.444174)
		(end 414.742122 -38.35146)
		(width 0.089408)
		(layer "In4.Cu")
		(net "SMB_PEHPCPU0_STBY_LVC3_R_SCL")
	)
	(segment
		(start 416.5346 -38.35146)
		(end 417.16198 -37.72408)
		(width 0.089408)
		(layer "In4.Cu")
		(net "SMB_PEHPCPU0_STBY_LVC3_R_SCL")
	)
	(segment
		(start 414.742122 -38.35146)
		(end 416.5346 -38.35146)
		(width 0.089408)
		(layer "In4.Cu")
		(net "SMB_PEHPCPU0_STBY_LVC3_R_SCL")
	)
	(segment
		(start 408.93492 -34.560002)
		(end 412.072328 -34.560002)
		(width 0.089408)
		(layer "In4.Cu")
		(net "SMB_PEHPCPU0_STBY_LVC3_R_SCL")
	)
	(segment
		(start 408.399488 -35.355022)
		(end 408.715464 -35.039046)
		(width 0.089408)
		(layer "In4.Cu")
		(net "SMB_PEHPCPU0_STBY_LVC3_R_SCL")
	)
	(segment
		(start 412.072328 -34.560002)
		(end 412.834836 -35.32251)
		(width 0.089408)
		(layer "In4.Cu")
		(net "SMB_PEHPCPU0_STBY_LVC3_R_SCL")
	)
	(segment
		(start 443.290706 -37.938202)
		(end 445.286892 -37.938202)
		(width 0.089408)
		(layer "In4.Cu")
		(net "SMB_PEHPCPU0_STBY_LVC3_R_SCL")
	)
	(segment
		(start 404.749 -35.0012)
		(end 404.91537 -34.83483)
		(width 0.089408)
		(layer "In4.Cu")
		(net "SMB_PEHPCPU0_STBY_LVC3_R_SCL")
	)
	(segment
		(start 435.239668 -38.5191)
		(end 442.709808 -38.5191)
		(width 0.089408)
		(layer "In4.Cu")
		(net "SMB_PEHPCPU0_STBY_LVC3_R_SCL")
	)
	(segment
		(start 406.769824 -34.83483)
		(end 407.290016 -35.355022)
		(width 0.089408)
		(layer "In4.Cu")
		(net "SMB_PEHPCPU0_STBY_LVC3_R_SCL")
	)
	(segment
		(start 404.91537 -34.83483)
		(end 406.769824 -34.83483)
		(width 0.089408)
		(layer "In4.Cu")
		(net "SMB_PEHPCPU0_STBY_LVC3_R_SCL")
	)
	(segment
		(start 462.86928 -37.043868)
		(end 463.425286 -36.487862)
		(width 0.089408)
		(layer "In4.Cu")
		(net "SMB_PEHPCPU0_STBY_LVC3_R_SCL")
	)
	(segment
		(start 419.8366 -38.5572)
		(end 423.8244 -38.5572)
		(width 0.089408)
		(layer "In4.Cu")
		(net "SMB_PEHPCPU0_STBY_LVC3_R_SCL")
	)
	(segment
		(start 412.834836 -35.32251)
		(end 412.834836 -36.444174)
		(width 0.089408)
		(layer "In4.Cu")
		(net "SMB_PEHPCPU0_STBY_LVC3_R_SCL")
	)
	(segment
		(start 458.41285 -35.725862)
		(end 459.730856 -37.043868)
		(width 0.089408)
		(layer "In4.Cu")
		(net "SMB_PEHPCPU0_STBY_LVC3_R_SCL")
	)
	(segment
		(start 459.730856 -37.043868)
		(end 462.86928 -37.043868)
		(width 0.089408)
		(layer "In4.Cu")
		(net "SMB_PEHPCPU0_STBY_LVC3_R_SCL")
	)
	(segment
		(start 423.8244 -38.5572)
		(end 425.165774 -37.215826)
		(width 0.089408)
		(layer "In4.Cu")
		(net "SMB_PEHPCPU0_STBY_LVC3_R_SCL")
	)
	(segment
		(start 456.16622 -35.852608)
		(end 456.292966 -35.725862)
		(width 0.089408)
		(layer "In4.Cu")
		(net "SMB_PEHPCPU0_STBY_LVC3_R_SCL")
	)
	(segment
		(start 407.290016 -35.355022)
		(end 408.399488 -35.355022)
		(width 0.089408)
		(layer "In4.Cu")
		(net "SMB_PEHPCPU0_STBY_LVC3_R_SCL")
	)
	(segment
		(start 425.165774 -37.215826)
		(end 433.936394 -37.215826)
		(width 0.089408)
		(layer "In4.Cu")
		(net "SMB_PEHPCPU0_STBY_LVC3_R_SCL")
	)
	(segment
		(start 408.715464 -35.039046)
		(end 408.715464 -34.779458)
		(width 0.089408)
		(layer "In4.Cu")
		(net "SMB_PEHPCPU0_STBY_LVC3_R_SCL")
	)
	(segment
		(start 408.715464 -34.779458)
		(end 408.93492 -34.560002)
		(width 0.089408)
		(layer "In4.Cu")
		(net "SMB_PEHPCPU0_STBY_LVC3_R_SCL")
	)
	(segment
		(start 417.16198 -37.72408)
		(end 419.00348 -37.72408)
		(width 0.089408)
		(layer "In4.Cu")
		(net "SMB_PEHPCPU0_STBY_LVC3_R_SCL")
	)
	(segment
		(start 445.286892 -37.938202)
		(end 447.372486 -35.852608)
		(width 0.089408)
		(layer "In4.Cu")
		(net "SMB_PEHPCPU0_STBY_LVC3_R_SCL")
	)
	(segment
		(start 433.936394 -37.215826)
		(end 435.239668 -38.5191)
		(width 0.089408)
		(layer "In4.Cu")
		(net "SMB_PEHPCPU0_STBY_LVC3_R_SCL")
	)
	(segment
		(start 419.00348 -37.72408)
		(end 419.8366 -38.5572)
		(width 0.089408)
		(layer "In4.Cu")
		(net "SMB_PEHPCPU0_STBY_LVC3_R_SCL")
	)
	(segment
		(start 447.372486 -35.852608)
		(end 456.16622 -35.852608)
		(width 0.089408)
		(layer "In4.Cu")
		(net "SMB_PEHPCPU0_STBY_LVC3_R_SCL")
	)
	(segment
		(start 456.292966 -35.725862)
		(end 458.41285 -35.725862)
		(width 0.089408)
		(layer "In4.Cu")
		(net "SMB_PEHPCPU0_STBY_LVC3_R_SCL")
	)
	(segment
		(start 465.676488 -35.349688)
		(end 467.897464 -37.570664)
		(width 0.0889)
		(layer "In9.Cu")
		(net "SMB_PEHPCPU0_STBY_LVC3_R_SCL")
	)
	(segment
		(start 469.25865 -45.24375)
		(end 469.25865 -46.799754)
		(width 0.0889)
		(layer "In9.Cu")
		(net "SMB_PEHPCPU0_STBY_LVC3_R_SCL")
	)
	(segment
		(start 463.0293 -35.80638)
		(end 463.485992 -35.349688)
		(width 0.089408)
		(layer "In9.Cu")
		(net "SMB_PEHPCPU0_STBY_LVC3_R_SCL")
	)
	(segment
		(start 463.485992 -35.349688)
		(end 465.676488 -35.349688)
		(width 0.0889)
		(layer "In9.Cu")
		(net "SMB_PEHPCPU0_STBY_LVC3_R_SCL")
	)
	(segment
		(start 467.782402 -48.276002)
		(end 467.782402 -51.970178)
		(width 0.0889)
		(layer "In9.Cu")
		(net "SMB_PEHPCPU0_STBY_LVC3_R_SCL")
	)
	(segment
		(start 469.556592 -53.847238)
		(end 469.315546 -54.088284)
		(width 0.0889)
		(layer "In9.Cu")
		(net "SMB_PEHPCPU0_STBY_LVC3_R_SCL")
	)
	(segment
		(start 463.312256 -36.487862)
		(end 463.0293 -36.204906)
		(width 0.089408)
		(layer "In9.Cu")
		(net "SMB_PEHPCPU0_STBY_LVC3_R_SCL")
	)
	(segment
		(start 463.0293 -36.204906)
		(end 463.0293 -35.80638)
		(width 0.089408)
		(layer "In9.Cu")
		(net "SMB_PEHPCPU0_STBY_LVC3_R_SCL")
	)
	(segment
		(start 467.897464 -43.882564)
		(end 469.25865 -45.24375)
		(width 0.0889)
		(layer "In9.Cu")
		(net "SMB_PEHPCPU0_STBY_LVC3_R_SCL")
	)
	(segment
		(start 469.556592 -53.744368)
		(end 469.556592 -53.847238)
		(width 0.0889)
		(layer "In9.Cu")
		(net "SMB_PEHPCPU0_STBY_LVC3_R_SCL")
	)
	(segment
		(start 467.782402 -51.970178)
		(end 469.556592 -53.744368)
		(width 0.0889)
		(layer "In9.Cu")
		(net "SMB_PEHPCPU0_STBY_LVC3_R_SCL")
	)
	(segment
		(start 467.897464 -37.570664)
		(end 467.897464 -43.882564)
		(width 0.0889)
		(layer "In9.Cu")
		(net "SMB_PEHPCPU0_STBY_LVC3_R_SCL")
	)
	(segment
		(start 463.425286 -36.487862)
		(end 463.312256 -36.487862)
		(width 0.089408)
		(layer "In9.Cu")
		(net "SMB_PEHPCPU0_STBY_LVC3_R_SCL")
	)
	(segment
		(start 469.25865 -46.799754)
		(end 467.782402 -48.276002)
		(width 0.0889)
		(layer "In9.Cu")
		(net "SMB_PEHPCPU0_STBY_LVC3_R_SCL")
	)
	(segment
		(start 419.896544 -89.6747)
		(end 420.128446 -89.6747)
		(width 0.1016)
		(layer "F.Cu")
		(net "SMB_CPU0_PE_HP_GTL_SDA")
	)
	(segment
		(start 421.4114 -90.957654)
		(end 421.4114 -91.965018)
		(width 0.1016)
		(layer "F.Cu")
		(net "SMB_CPU0_PE_HP_GTL_SDA")
	)
	(segment
		(start 421.75938 -102.432866)
		(end 421.345614 -102.0191)
		(width 0.1016)
		(layer "F.Cu")
		(net "SMB_CPU0_PE_HP_GTL_SDA")
	)
	(segment
		(start 421.345614 -100.758752)
		(end 420.243 -99.656138)
		(width 0.1016)
		(layer "F.Cu")
		(net "SMB_CPU0_PE_HP_GTL_SDA")
	)
	(segment
		(start 419.655244 -89.4334)
		(end 419.896544 -89.6747)
		(width 0.1016)
		(layer "F.Cu")
		(net "SMB_CPU0_PE_HP_GTL_SDA")
	)
	(segment
		(start 422.024302 -102.432866)
		(end 421.75938 -102.432866)
		(width 0.1016)
		(layer "F.Cu")
		(net "SMB_CPU0_PE_HP_GTL_SDA")
	)
	(segment
		(start 421.345614 -102.0191)
		(end 421.345614 -100.758752)
		(width 0.1016)
		(layer "F.Cu")
		(net "SMB_CPU0_PE_HP_GTL_SDA")
	)
	(segment
		(start 420.243 -99.656138)
		(end 420.243 -94.195392)
		(width 0.1016)
		(layer "F.Cu")
		(net "SMB_CPU0_PE_HP_GTL_SDA")
	)
	(segment
		(start 421.4114 -93.026992)
		(end 421.4114 -91.965018)
		(width 0.1016)
		(layer "F.Cu")
		(net "SMB_CPU0_PE_HP_GTL_SDA")
	)
	(segment
		(start 422.2877 -104.267)
		(end 422.2877 -102.696264)
		(width 0.1016)
		(layer "F.Cu")
		(net "SMB_CPU0_PE_HP_GTL_SDA")
	)
	(segment
		(start 293.22776 -66.305938)
		(end 292.65626 -66.305938)
		(width 0.1016)
		(layer "F.Cu")
		(net "SMB_CPU0_PE_HP_GTL_SDA")
	)
	(segment
		(start 420.243 -94.195392)
		(end 421.4114 -93.026992)
		(width 0.1016)
		(layer "F.Cu")
		(net "SMB_CPU0_PE_HP_GTL_SDA")
	)
	(segment
		(start 420.128446 -89.6747)
		(end 421.4114 -90.957654)
		(width 0.1016)
		(layer "F.Cu")
		(net "SMB_CPU0_PE_HP_GTL_SDA")
	)
	(segment
		(start 422.2877 -102.696264)
		(end 422.024302 -102.432866)
		(width 0.1016)
		(layer "F.Cu")
		(net "SMB_CPU0_PE_HP_GTL_SDA")
	)
	(via
		(at 419.655244 -89.4334)
		(size 0.508)
		(drill 0.254)
		(layers "F.Cu" "B.Cu")
		(net "SMB_CPU0_PE_HP_GTL_SDA")
	)
	(via
		(at 399.4658 -60.8076)
		(size 0.508)
		(drill 0.254)
		(layers "F.Cu" "B.Cu")
		(net "SMB_CPU0_PE_HP_GTL_SDA")
	)
	(via
		(at 358.795066 -68.141342)
		(size 0.508)
		(drill 0.254)
		(layers "F.Cu" "B.Cu")
		(net "SMB_CPU0_PE_HP_GTL_SDA")
	)
	(via
		(at 398.579594 -84.211668)
		(size 0.508)
		(drill 0.254)
		(layers "F.Cu" "B.Cu")
		(net "SMB_CPU0_PE_HP_GTL_SDA")
	)
	(via
		(at 293.22776 -66.305938)
		(size 0.508)
		(drill 0.254)
		(layers "F.Cu" "B.Cu")
		(net "SMB_CPU0_PE_HP_GTL_SDA")
	)
	(via
		(at 421.4114 -91.965018)
		(size 0.762)
		(drill 0.381)
		(layers "F.Cu" "B.Cu")
		(net "SMB_CPU0_PE_HP_GTL_SDA")
	)
	(segment
		(start 395.29512 -71.20128)
		(end 395.29512 -72.138286)
		(width 0.089408)
		(layer "In2.Cu")
		(net "SMB_CPU0_PE_HP_GTL_SDA")
	)
	(segment
		(start 399.4658 -60.8076)
		(end 397.87576 -62.39764)
		(width 0.089408)
		(layer "In2.Cu")
		(net "SMB_CPU0_PE_HP_GTL_SDA")
	)
	(segment
		(start 396.957296 -76.4032)
		(end 396.957296 -82.58937)
		(width 0.089408)
		(layer "In2.Cu")
		(net "SMB_CPU0_PE_HP_GTL_SDA")
	)
	(segment
		(start 395.00556 -70.91172)
		(end 395.29512 -71.20128)
		(width 0.089408)
		(layer "In2.Cu")
		(net "SMB_CPU0_PE_HP_GTL_SDA")
	)
	(segment
		(start 396.960344 -76.400152)
		(end 396.957296 -76.4032)
		(width 0.089408)
		(layer "In2.Cu")
		(net "SMB_CPU0_PE_HP_GTL_SDA")
	)
	(segment
		(start 397.209264 -64.483488)
		(end 396.792704 -64.483488)
		(width 0.089408)
		(layer "In2.Cu")
		(net "SMB_CPU0_PE_HP_GTL_SDA")
	)
	(segment
		(start 396.792704 -64.483488)
		(end 395.00556 -66.270632)
		(width 0.089408)
		(layer "In2.Cu")
		(net "SMB_CPU0_PE_HP_GTL_SDA")
	)
	(segment
		(start 397.87576 -63.816992)
		(end 397.209264 -64.483488)
		(width 0.089408)
		(layer "In2.Cu")
		(net "SMB_CPU0_PE_HP_GTL_SDA")
	)
	(segment
		(start 396.957296 -82.58937)
		(end 398.579594 -84.211668)
		(width 0.089408)
		(layer "In2.Cu")
		(net "SMB_CPU0_PE_HP_GTL_SDA")
	)
	(segment
		(start 396.960344 -73.471786)
		(end 396.960344 -76.400152)
		(width 0.089408)
		(layer "In2.Cu")
		(net "SMB_CPU0_PE_HP_GTL_SDA")
	)
	(segment
		(start 395.00556 -66.270632)
		(end 395.00556 -70.91172)
		(width 0.089408)
		(layer "In2.Cu")
		(net "SMB_CPU0_PE_HP_GTL_SDA")
	)
	(segment
		(start 396.355062 -72.866504)
		(end 396.960344 -73.471786)
		(width 0.089408)
		(layer "In2.Cu")
		(net "SMB_CPU0_PE_HP_GTL_SDA")
	)
	(segment
		(start 396.023338 -72.866504)
		(end 396.355062 -72.866504)
		(width 0.089408)
		(layer "In2.Cu")
		(net "SMB_CPU0_PE_HP_GTL_SDA")
	)
	(segment
		(start 397.87576 -62.39764)
		(end 397.87576 -63.816992)
		(width 0.089408)
		(layer "In2.Cu")
		(net "SMB_CPU0_PE_HP_GTL_SDA")
	)
	(segment
		(start 395.29512 -72.138286)
		(end 396.023338 -72.866504)
		(width 0.089408)
		(layer "In2.Cu")
		(net "SMB_CPU0_PE_HP_GTL_SDA")
	)
	(segment
		(start 374.69826 -59.8678)
		(end 379.02642 -59.8678)
		(width 0.089408)
		(layer "In4.Cu")
		(net "SMB_CPU0_PE_HP_GTL_SDA")
	)
	(segment
		(start 394.171678 -59.73318)
		(end 394.864844 -60.426346)
		(width 0.089408)
		(layer "In4.Cu")
		(net "SMB_CPU0_PE_HP_GTL_SDA")
	)
	(segment
		(start 413.287718 -84.619592)
		(end 418.466778 -84.619592)
		(width 0.089408)
		(layer "In4.Cu")
		(net "SMB_CPU0_PE_HP_GTL_SDA")
	)
	(segment
		(start 366.291622 -65.208404)
		(end 366.291622 -61.389006)
		(width 0.089408)
		(layer "In4.Cu")
		(net "SMB_CPU0_PE_HP_GTL_SDA")
	)
	(segment
		(start 399.4658 -60.5028)
		(end 399.4658 -60.8076)
		(width 0.089408)
		(layer "In4.Cu")
		(net "SMB_CPU0_PE_HP_GTL_SDA")
	)
	(segment
		(start 394.864844 -60.426346)
		(end 397.965168 -60.426346)
		(width 0.089408)
		(layer "In4.Cu")
		(net "SMB_CPU0_PE_HP_GTL_SDA")
	)
	(segment
		(start 410.10332 -84.72932)
		(end 413.17799 -84.72932)
		(width 0.089408)
		(layer "In4.Cu")
		(net "SMB_CPU0_PE_HP_GTL_SDA")
	)
	(segment
		(start 408.571192 -84.392008)
		(end 409.766008 -84.392008)
		(width 0.089408)
		(layer "In4.Cu")
		(net "SMB_CPU0_PE_HP_GTL_SDA")
	)
	(segment
		(start 418.466778 -84.619592)
		(end 419.183566 -85.33638)
		(width 0.089408)
		(layer "In4.Cu")
		(net "SMB_CPU0_PE_HP_GTL_SDA")
	)
	(segment
		(start 419.183566 -85.33638)
		(end 419.183566 -86.02853)
		(width 0.089408)
		(layer "In4.Cu")
		(net "SMB_CPU0_PE_HP_GTL_SDA")
	)
	(segment
		(start 419.183566 -89.55405)
		(end 419.272466 -89.64295)
		(width 0.089408)
		(layer "In4.Cu")
		(net "SMB_CPU0_PE_HP_GTL_SDA")
	)
	(segment
		(start 409.766008 -84.392008)
		(end 410.10332 -84.72932)
		(width 0.089408)
		(layer "In4.Cu")
		(net "SMB_CPU0_PE_HP_GTL_SDA")
	)
	(segment
		(start 358.89438 -68.494148)
		(end 360.520996 -68.494148)
		(width 0.089408)
		(layer "In4.Cu")
		(net "SMB_CPU0_PE_HP_GTL_SDA")
	)
	(segment
		(start 419.183566 -86.02853)
		(end 419.18382 -86.028784)
		(width 0.089408)
		(layer "In4.Cu")
		(net "SMB_CPU0_PE_HP_GTL_SDA")
	)
	(segment
		(start 398.818862 -84.450936)
		(end 400.542506 -84.450936)
		(width 0.089408)
		(layer "In4.Cu")
		(net "SMB_CPU0_PE_HP_GTL_SDA")
	)
	(segment
		(start 361.891834 -67.12331)
		(end 364.376716 -67.12331)
		(width 0.089408)
		(layer "In4.Cu")
		(net "SMB_CPU0_PE_HP_GTL_SDA")
	)
	(segment
		(start 403.022562 -84.716366)
		(end 403.093682 -84.787486)
		(width 0.089408)
		(layer "In4.Cu")
		(net "SMB_CPU0_PE_HP_GTL_SDA")
	)
	(segment
		(start 391.417302 -59.365388)
		(end 392.08837 -59.365388)
		(width 0.089408)
		(layer "In4.Cu")
		(net "SMB_CPU0_PE_HP_GTL_SDA")
	)
	(segment
		(start 405.557228 -84.787486)
		(end 406.023572 -85.25383)
		(width 0.089408)
		(layer "In4.Cu")
		(net "SMB_CPU0_PE_HP_GTL_SDA")
	)
	(segment
		(start 381.97028 -60.88126)
		(end 382.914652 -59.936888)
		(width 0.089408)
		(layer "In4.Cu")
		(net "SMB_CPU0_PE_HP_GTL_SDA")
	)
	(segment
		(start 397.965168 -60.426346)
		(end 398.328642 -60.062872)
		(width 0.089408)
		(layer "In4.Cu")
		(net "SMB_CPU0_PE_HP_GTL_SDA")
	)
	(segment
		(start 360.520996 -68.494148)
		(end 361.891834 -67.12331)
		(width 0.089408)
		(layer "In4.Cu")
		(net "SMB_CPU0_PE_HP_GTL_SDA")
	)
	(segment
		(start 419.18382 -86.512908)
		(end 419.183566 -86.513162)
		(width 0.089408)
		(layer "In4.Cu")
		(net "SMB_CPU0_PE_HP_GTL_SDA")
	)
	(segment
		(start 403.093682 -84.787486)
		(end 405.557228 -84.787486)
		(width 0.089408)
		(layer "In4.Cu")
		(net "SMB_CPU0_PE_HP_GTL_SDA")
	)
	(segment
		(start 391.26287 -59.51982)
		(end 391.417302 -59.365388)
		(width 0.089408)
		(layer "In4.Cu")
		(net "SMB_CPU0_PE_HP_GTL_SDA")
	)
	(segment
		(start 419.183566 -86.513162)
		(end 419.183566 -89.55405)
		(width 0.089408)
		(layer "In4.Cu")
		(net "SMB_CPU0_PE_HP_GTL_SDA")
	)
	(segment
		(start 400.542506 -84.450936)
		(end 400.807936 -84.716366)
		(width 0.089408)
		(layer "In4.Cu")
		(net "SMB_CPU0_PE_HP_GTL_SDA")
	)
	(segment
		(start 392.456162 -59.73318)
		(end 394.171678 -59.73318)
		(width 0.089408)
		(layer "In4.Cu")
		(net "SMB_CPU0_PE_HP_GTL_SDA")
	)
	(segment
		(start 400.807936 -84.716366)
		(end 403.022562 -84.716366)
		(width 0.089408)
		(layer "In4.Cu")
		(net "SMB_CPU0_PE_HP_GTL_SDA")
	)
	(segment
		(start 379.02642 -59.8678)
		(end 380.03988 -60.88126)
		(width 0.089408)
		(layer "In4.Cu")
		(net "SMB_CPU0_PE_HP_GTL_SDA")
	)
	(segment
		(start 419.18382 -86.028784)
		(end 419.18382 -86.512908)
		(width 0.089408)
		(layer "In4.Cu")
		(net "SMB_CPU0_PE_HP_GTL_SDA")
	)
	(segment
		(start 366.291622 -61.389006)
		(end 367.424208 -60.25642)
		(width 0.089408)
		(layer "In4.Cu")
		(net "SMB_CPU0_PE_HP_GTL_SDA")
	)
	(segment
		(start 419.445694 -89.64295)
		(end 419.655244 -89.4334)
		(width 0.089408)
		(layer "In4.Cu")
		(net "SMB_CPU0_PE_HP_GTL_SDA")
	)
	(segment
		(start 358.795066 -68.394834)
		(end 358.89438 -68.494148)
		(width 0.089408)
		(layer "In4.Cu")
		(net "SMB_CPU0_PE_HP_GTL_SDA")
	)
	(segment
		(start 364.376716 -67.12331)
		(end 366.291622 -65.208404)
		(width 0.089408)
		(layer "In4.Cu")
		(net "SMB_CPU0_PE_HP_GTL_SDA")
	)
	(segment
		(start 385.88188 -59.54014)
		(end 387.082284 -59.54014)
		(width 0.089408)
		(layer "In4.Cu")
		(net "SMB_CPU0_PE_HP_GTL_SDA")
	)
	(segment
		(start 398.579594 -84.211668)
		(end 398.818862 -84.450936)
		(width 0.089408)
		(layer "In4.Cu")
		(net "SMB_CPU0_PE_HP_GTL_SDA")
	)
	(segment
		(start 419.272466 -89.64295)
		(end 419.445694 -89.64295)
		(width 0.089408)
		(layer "In4.Cu")
		(net "SMB_CPU0_PE_HP_GTL_SDA")
	)
	(segment
		(start 389.30072 -59.51982)
		(end 391.26287 -59.51982)
		(width 0.089408)
		(layer "In4.Cu")
		(net "SMB_CPU0_PE_HP_GTL_SDA")
	)
	(segment
		(start 413.17799 -84.72932)
		(end 413.287718 -84.619592)
		(width 0.089408)
		(layer "In4.Cu")
		(net "SMB_CPU0_PE_HP_GTL_SDA")
	)
	(segment
		(start 385.485132 -59.936888)
		(end 385.88188 -59.54014)
		(width 0.089408)
		(layer "In4.Cu")
		(net "SMB_CPU0_PE_HP_GTL_SDA")
	)
	(segment
		(start 367.424208 -60.25642)
		(end 374.30964 -60.25642)
		(width 0.089408)
		(layer "In4.Cu")
		(net "SMB_CPU0_PE_HP_GTL_SDA")
	)
	(segment
		(start 387.500622 -59.958478)
		(end 388.862062 -59.958478)
		(width 0.089408)
		(layer "In4.Cu")
		(net "SMB_CPU0_PE_HP_GTL_SDA")
	)
	(segment
		(start 399.025872 -60.062872)
		(end 399.4658 -60.5028)
		(width 0.089408)
		(layer "In4.Cu")
		(net "SMB_CPU0_PE_HP_GTL_SDA")
	)
	(segment
		(start 380.03988 -60.88126)
		(end 381.97028 -60.88126)
		(width 0.089408)
		(layer "In4.Cu")
		(net "SMB_CPU0_PE_HP_GTL_SDA")
	)
	(segment
		(start 387.082284 -59.54014)
		(end 387.500622 -59.958478)
		(width 0.089408)
		(layer "In4.Cu")
		(net "SMB_CPU0_PE_HP_GTL_SDA")
	)
	(segment
		(start 382.914652 -59.936888)
		(end 385.485132 -59.936888)
		(width 0.089408)
		(layer "In4.Cu")
		(net "SMB_CPU0_PE_HP_GTL_SDA")
	)
	(segment
		(start 407.70937 -85.25383)
		(end 408.571192 -84.392008)
		(width 0.089408)
		(layer "In4.Cu")
		(net "SMB_CPU0_PE_HP_GTL_SDA")
	)
	(segment
		(start 406.023572 -85.25383)
		(end 407.70937 -85.25383)
		(width 0.089408)
		(layer "In4.Cu")
		(net "SMB_CPU0_PE_HP_GTL_SDA")
	)
	(segment
		(start 388.862062 -59.958478)
		(end 389.30072 -59.51982)
		(width 0.089408)
		(layer "In4.Cu")
		(net "SMB_CPU0_PE_HP_GTL_SDA")
	)
	(segment
		(start 392.08837 -59.365388)
		(end 392.456162 -59.73318)
		(width 0.089408)
		(layer "In4.Cu")
		(net "SMB_CPU0_PE_HP_GTL_SDA")
	)
	(segment
		(start 358.795066 -68.141342)
		(end 358.795066 -68.394834)
		(width 0.089408)
		(layer "In4.Cu")
		(net "SMB_CPU0_PE_HP_GTL_SDA")
	)
	(segment
		(start 374.30964 -60.25642)
		(end 374.69826 -59.8678)
		(width 0.089408)
		(layer "In4.Cu")
		(net "SMB_CPU0_PE_HP_GTL_SDA")
	)
	(segment
		(start 398.328642 -60.062872)
		(end 399.025872 -60.062872)
		(width 0.089408)
		(layer "In4.Cu")
		(net "SMB_CPU0_PE_HP_GTL_SDA")
	)
	(segment
		(start 293.22776 -66.305938)
		(end 292.934644 -66.474848)
		(width 0.0889)
		(layer "In11.Cu")
		(net "SMB_CPU0_PE_HP_GTL_SDA")
	)
	(segment
		(start 293.216584 -66.705988)
		(end 293.22776 -66.705988)
		(width 0.0889)
		(layer "In11.Cu")
		(net "SMB_CPU0_PE_HP_GTL_SDA")
	)
	(segment
		(start 353.059746 -65.44564)
		(end 355.376226 -67.76212)
		(width 0.089408)
		(layer "In11.Cu")
		(net "SMB_CPU0_PE_HP_GTL_SDA")
	)
	(segment
		(start 302.653446 -69.182234)
		(end 302.686212 -69.182234)
		(width 0.0889)
		(layer "In11.Cu")
		(net "SMB_CPU0_PE_HP_GTL_SDA")
	)
	(segment
		(start 358.009444 -67.76212)
		(end 358.388666 -68.141342)
		(width 0.089408)
		(layer "In11.Cu")
		(net "SMB_CPU0_PE_HP_GTL_SDA")
	)
	(segment
		(start 306.961794 -68.686172)
		(end 307.379878 -68.686172)
		(width 0.0889)
		(layer "In11.Cu")
		(net "SMB_CPU0_PE_HP_GTL_SDA")
	)
	(segment
		(start 300.077632 -69.677534)
		(end 300.1137 -69.677534)
		(width 0.0889)
		(layer "In11.Cu")
		(net "SMB_CPU0_PE_HP_GTL_SDA")
	)
	(segment
		(start 294.933624 -68.687188)
		(end 294.96639 -68.687188)
		(width 0.0889)
		(layer "In11.Cu")
		(net "SMB_CPU0_PE_HP_GTL_SDA")
	)
	(segment
		(start 358.388666 -68.141342)
		(end 358.795066 -68.141342)
		(width 0.089408)
		(layer "In11.Cu")
		(net "SMB_CPU0_PE_HP_GTL_SDA")
	)
	(segment
		(start 298.360592 -69.677534)
		(end 298.39666 -69.677534)
		(width 0.0889)
		(layer "In11.Cu")
		(net "SMB_CPU0_PE_HP_GTL_SDA")
	)
	(segment
		(start 307.4035 -68.66255)
		(end 307.75529 -68.66255)
		(width 0.089408)
		(layer "In11.Cu")
		(net "SMB_CPU0_PE_HP_GTL_SDA")
	)
	(segment
		(start 297.520106 -69.182234)
		(end 297.537886 -69.182234)
		(width 0.0889)
		(layer "In11.Cu")
		(net "SMB_CPU0_PE_HP_GTL_SDA")
	)
	(segment
		(start 292.934644 -66.474848)
		(end 292.913562 -66.553588)
		(width 0.0889)
		(layer "In11.Cu")
		(net "SMB_CPU0_PE_HP_GTL_SDA")
	)
	(segment
		(start 307.75529 -68.66255)
		(end 309.03164 -69.9389)
		(width 0.089408)
		(layer "In11.Cu")
		(net "SMB_CPU0_PE_HP_GTL_SDA")
	)
	(segment
		(start 304.363374 -68.191888)
		(end 304.413158 -68.191888)
		(width 0.0889)
		(layer "In11.Cu")
		(net "SMB_CPU0_PE_HP_GTL_SDA")
	)
	(segment
		(start 295.788334 -69.182234)
		(end 295.818306 -69.182234)
		(width 0.0889)
		(layer "In11.Cu")
		(net "SMB_CPU0_PE_HP_GTL_SDA")
	)
	(segment
		(start 331.86624 -69.9389)
		(end 336.3595 -65.44564)
		(width 0.089408)
		(layer "In11.Cu")
		(net "SMB_CPU0_PE_HP_GTL_SDA")
	)
	(segment
		(start 309.03164 -69.9389)
		(end 331.86624 -69.9389)
		(width 0.089408)
		(layer "In11.Cu")
		(net "SMB_CPU0_PE_HP_GTL_SDA")
	)
	(segment
		(start 301.794672 -69.677534)
		(end 301.83074 -69.677534)
		(width 0.0889)
		(layer "In11.Cu")
		(net "SMB_CPU0_PE_HP_GTL_SDA")
	)
	(segment
		(start 336.3595 -65.44564)
		(end 353.059746 -65.44564)
		(width 0.089408)
		(layer "In11.Cu")
		(net "SMB_CPU0_PE_HP_GTL_SDA")
	)
	(segment
		(start 303.508156 -68.687188)
		(end 303.540922 -68.687188)
		(width 0.0889)
		(layer "In11.Cu")
		(net "SMB_CPU0_PE_HP_GTL_SDA")
	)
	(segment
		(start 307.379878 -68.686172)
		(end 307.4035 -68.66255)
		(width 0.0889)
		(layer "In11.Cu")
		(net "SMB_CPU0_PE_HP_GTL_SDA")
	)
	(segment
		(start 294.071294 -68.191634)
		(end 294.10406 -68.191634)
		(width 0.0889)
		(layer "In11.Cu")
		(net "SMB_CPU0_PE_HP_GTL_SDA")
	)
	(segment
		(start 355.376226 -67.76212)
		(end 358.009444 -67.76212)
		(width 0.089408)
		(layer "In11.Cu")
		(net "SMB_CPU0_PE_HP_GTL_SDA")
	)
	(arc
		(start 304.900076 -68.487036)
		(mid 305.246786 -68.687347)
		(end 305.593496 -68.487036)
		(width 0.0889)
		(layer "In11.Cu")
		(net "SMB_CPU0_PE_HP_GTL_SDA")
	)
	(arc
		(start 302.686212 -69.182234)
		(mid 302.877854 -69.125068)
		(end 303.017936 -68.982336)
		(width 0.0889)
		(layer "In11.Cu")
		(net "SMB_CPU0_PE_HP_GTL_SDA")
	)
	(arc
		(start 294.96639 -68.687188)
		(mid 295.249607 -68.771469)
		(end 295.45661 -68.982336)
		(width 0.0889)
		(layer "In11.Cu")
		(net "SMB_CPU0_PE_HP_GTL_SDA")
	)
	(arc
		(start 293.746174 -67.581272)
		(mid 293.686072 -67.785601)
		(end 293.73957 -67.991736)
		(width 0.0889)
		(layer "In11.Cu")
		(net "SMB_CPU0_PE_HP_GTL_SDA")
	)
	(arc
		(start 301.465996 -69.477636)
		(mid 301.60474 -69.619669)
		(end 301.794672 -69.677534)
		(width 0.0889)
		(layer "In11.Cu")
		(net "SMB_CPU0_PE_HP_GTL_SDA")
	)
	(arc
		(start 297.176952 -68.987924)
		(mid 297.322918 -69.130323)
		(end 297.520106 -69.182234)
		(width 0.0889)
		(layer "In11.Cu")
		(net "SMB_CPU0_PE_HP_GTL_SDA")
	)
	(arc
		(start 299.748956 -69.477636)
		(mid 299.8877 -69.619669)
		(end 300.077632 -69.677534)
		(width 0.0889)
		(layer "In11.Cu")
		(net "SMB_CPU0_PE_HP_GTL_SDA")
	)
	(arc
		(start 303.540922 -68.687188)
		(mid 303.734772 -68.630838)
		(end 303.876456 -68.487036)
		(width 0.0889)
		(layer "In11.Cu")
		(net "SMB_CPU0_PE_HP_GTL_SDA")
	)
	(arc
		(start 294.10406 -68.191634)
		(mid 294.389484 -68.275101)
		(end 294.59809 -68.487036)
		(width 0.0889)
		(layer "In11.Cu")
		(net "SMB_CPU0_PE_HP_GTL_SDA")
	)
	(arc
		(start 294.59809 -68.487036)
		(mid 294.739773 -68.63084)
		(end 294.933624 -68.687188)
		(width 0.0889)
		(layer "In11.Cu")
		(net "SMB_CPU0_PE_HP_GTL_SDA")
	)
	(arc
		(start 296.15003 -68.982336)
		(mid 296.665085 -68.686805)
		(end 297.176952 -68.987924)
		(width 0.0889)
		(layer "In11.Cu")
		(net "SMB_CPU0_PE_HP_GTL_SDA")
	)
	(arc
		(start 302.159416 -69.477636)
		(mid 302.368024 -69.265704)
		(end 302.653446 -69.182234)
		(width 0.0889)
		(layer "In11.Cu")
		(net "SMB_CPU0_PE_HP_GTL_SDA")
	)
	(arc
		(start 293.739824 -67.000882)
		(mid 293.819139 -67.290254)
		(end 293.746174 -67.581272)
		(width 0.089408)
		(layer "In11.Cu")
		(net "SMB_CPU0_PE_HP_GTL_SDA")
	)
	(arc
		(start 305.593496 -68.487036)
		(mid 306.105306 -68.191369)
		(end 306.617116 -68.487036)
		(width 0.0889)
		(layer "In11.Cu")
		(net "SMB_CPU0_PE_HP_GTL_SDA")
	)
	(arc
		(start 293.73957 -67.991736)
		(mid 293.879649 -68.134472)
		(end 294.071294 -68.191634)
		(width 0.0889)
		(layer "In11.Cu")
		(net "SMB_CPU0_PE_HP_GTL_SDA")
	)
	(arc
		(start 303.876456 -68.487036)
		(mid 304.082015 -68.276939)
		(end 304.363374 -68.191888)
		(width 0.0889)
		(layer "In11.Cu")
		(net "SMB_CPU0_PE_HP_GTL_SDA")
	)
	(arc
		(start 303.017936 -68.982336)
		(mid 303.22494 -68.771472)
		(end 303.508156 -68.687188)
		(width 0.0889)
		(layer "In11.Cu")
		(net "SMB_CPU0_PE_HP_GTL_SDA")
	)
	(arc
		(start 295.45661 -68.982336)
		(mid 295.596689 -69.125072)
		(end 295.788334 -69.182234)
		(width 0.0889)
		(layer "In11.Cu")
		(net "SMB_CPU0_PE_HP_GTL_SDA")
	)
	(arc
		(start 304.413158 -68.191888)
		(mid 304.69452 -68.276934)
		(end 304.900076 -68.487036)
		(width 0.0889)
		(layer "In11.Cu")
		(net "SMB_CPU0_PE_HP_GTL_SDA")
	)
	(arc
		(start 301.83074 -69.677534)
		(mid 302.020669 -69.619664)
		(end 302.159416 -69.477636)
		(width 0.0889)
		(layer "In11.Cu")
		(net "SMB_CPU0_PE_HP_GTL_SDA")
	)
	(arc
		(start 292.913562 -66.553588)
		(mid 293.048124 -66.6635)
		(end 293.216584 -66.705988)
		(width 0.0889)
		(layer "In11.Cu")
		(net "SMB_CPU0_PE_HP_GTL_SDA")
	)
	(arc
		(start 297.537886 -69.182234)
		(mid 297.82331 -69.265701)
		(end 298.031916 -69.477636)
		(width 0.0889)
		(layer "In11.Cu")
		(net "SMB_CPU0_PE_HP_GTL_SDA")
	)
	(arc
		(start 300.442376 -69.477636)
		(mid 300.954186 -69.181969)
		(end 301.465996 -69.477636)
		(width 0.0889)
		(layer "In11.Cu")
		(net "SMB_CPU0_PE_HP_GTL_SDA")
	)
	(arc
		(start 300.1137 -69.677534)
		(mid 300.303629 -69.619664)
		(end 300.442376 -69.477636)
		(width 0.0889)
		(layer "In11.Cu")
		(net "SMB_CPU0_PE_HP_GTL_SDA")
	)
	(arc
		(start 298.725336 -69.477636)
		(mid 299.237146 -69.181969)
		(end 299.748956 -69.477636)
		(width 0.0889)
		(layer "In11.Cu")
		(net "SMB_CPU0_PE_HP_GTL_SDA")
	)
	(arc
		(start 298.031916 -69.477636)
		(mid 298.17066 -69.619669)
		(end 298.360592 -69.677534)
		(width 0.0889)
		(layer "In11.Cu")
		(net "SMB_CPU0_PE_HP_GTL_SDA")
	)
	(arc
		(start 295.818306 -69.182234)
		(mid 296.009948 -69.125068)
		(end 296.15003 -68.982336)
		(width 0.0889)
		(layer "In11.Cu")
		(net "SMB_CPU0_PE_HP_GTL_SDA")
	)
	(arc
		(start 306.617116 -68.487036)
		(mid 306.762779 -68.632755)
		(end 306.961794 -68.686172)
		(width 0.0889)
		(layer "In11.Cu")
		(net "SMB_CPU0_PE_HP_GTL_SDA")
	)
	(arc
		(start 293.22776 -66.705988)
		(mid 293.523219 -66.784978)
		(end 293.739824 -67.000882)
		(width 0.0889)
		(layer "In11.Cu")
		(net "SMB_CPU0_PE_HP_GTL_SDA")
	)
	(arc
		(start 298.39666 -69.677534)
		(mid 298.586589 -69.619664)
		(end 298.725336 -69.477636)
		(width 0.0889)
		(layer "In11.Cu")
		(net "SMB_CPU0_PE_HP_GTL_SDA")
	)
	(segment
		(start 292.36924 -66.800984)
		(end 291.79774 -66.800984)
		(width 0.1016)
		(layer "F.Cu")
		(net "SMB_CPU0_PE_HP_GTL_SCL")
	)
	(segment
		(start 420.0144 -99.75088)
		(end 420.0144 -94.10065)
		(width 0.1016)
		(layer "F.Cu")
		(net "SMB_CPU0_PE_HP_GTL_SCL")
	)
	(segment
		(start 419.6207 -103.7336)
		(end 419.391338 -103.504238)
		(width 0.10795)
		(layer "F.Cu")
		(net "SMB_CPU0_PE_HP_GTL_SCL")
	)
	(segment
		(start 421.06977 -101.862382)
		(end 421.06977 -100.80625)
		(width 0.1016)
		(layer "F.Cu")
		(net "SMB_CPU0_PE_HP_GTL_SCL")
	)
	(segment
		(start 419.845744 -89.9033)
		(end 419.655244 -90.0938)
		(width 0.1016)
		(layer "F.Cu")
		(net "SMB_CPU0_PE_HP_GTL_SCL")
	)
	(segment
		(start 420.908226 -102.028498)
		(end 420.908226 -102.023926)
		(width 0.10795)
		(layer "F.Cu")
		(net "SMB_CPU0_PE_HP_GTL_SCL")
	)
	(segment
		(start 420.908226 -102.023926)
		(end 421.06977 -101.862382)
		(width 0.1016)
		(layer "F.Cu")
		(net "SMB_CPU0_PE_HP_GTL_SCL")
	)
	(segment
		(start 420.0271 -89.9033)
		(end 419.845744 -89.9033)
		(width 0.1016)
		(layer "F.Cu")
		(net "SMB_CPU0_PE_HP_GTL_SCL")
	)
	(segment
		(start 419.391338 -102.667562)
		(end 419.618668 -102.440232)
		(width 0.10795)
		(layer "F.Cu")
		(net "SMB_CPU0_PE_HP_GTL_SCL")
	)
	(segment
		(start 420.8526 -90.7288)
		(end 420.0271 -89.9033)
		(width 0.1016)
		(layer "F.Cu")
		(net "SMB_CPU0_PE_HP_GTL_SCL")
	)
	(segment
		(start 421.06977 -100.80625)
		(end 420.0144 -99.75088)
		(width 0.1016)
		(layer "F.Cu")
		(net "SMB_CPU0_PE_HP_GTL_SCL")
	)
	(segment
		(start 420.496492 -102.440232)
		(end 420.908226 -102.028498)
		(width 0.10795)
		(layer "F.Cu")
		(net "SMB_CPU0_PE_HP_GTL_SCL")
	)
	(segment
		(start 420.8526 -93.26245)
		(end 420.8526 -90.7288)
		(width 0.1016)
		(layer "F.Cu")
		(net "SMB_CPU0_PE_HP_GTL_SCL")
	)
	(segment
		(start 419.618668 -102.440232)
		(end 420.496492 -102.440232)
		(width 0.10795)
		(layer "F.Cu")
		(net "SMB_CPU0_PE_HP_GTL_SCL")
	)
	(segment
		(start 420.0144 -94.10065)
		(end 420.8526 -93.26245)
		(width 0.1016)
		(layer "F.Cu")
		(net "SMB_CPU0_PE_HP_GTL_SCL")
	)
	(segment
		(start 419.6207 -104.267)
		(end 419.6207 -103.7336)
		(width 0.10795)
		(layer "F.Cu")
		(net "SMB_CPU0_PE_HP_GTL_SCL")
	)
	(segment
		(start 419.391338 -103.504238)
		(end 419.391338 -102.667562)
		(width 0.10795)
		(layer "F.Cu")
		(net "SMB_CPU0_PE_HP_GTL_SCL")
	)
	(via
		(at 419.655244 -90.0938)
		(size 0.508)
		(drill 0.254)
		(layers "F.Cu" "B.Cu")
		(net "SMB_CPU0_PE_HP_GTL_SCL")
	)
	(via
		(at 358.388666 -68.700142)
		(size 0.508)
		(drill 0.254)
		(layers "F.Cu" "B.Cu")
		(net "SMB_CPU0_PE_HP_GTL_SCL")
	)
	(via
		(at 292.36924 -66.800984)
		(size 0.508)
		(drill 0.254)
		(layers "F.Cu" "B.Cu")
		(net "SMB_CPU0_PE_HP_GTL_SCL")
	)
	(via
		(at 398.860772 -60.481464)
		(size 0.508)
		(drill 0.254)
		(layers "F.Cu" "B.Cu")
		(net "SMB_CPU0_PE_HP_GTL_SCL")
	)
	(via
		(at 398.579594 -84.872068)
		(size 0.508)
		(drill 0.254)
		(layers "F.Cu" "B.Cu")
		(net "SMB_CPU0_PE_HP_GTL_SCL")
	)
	(segment
		(start 396.292578 -73.079356)
		(end 396.769336 -73.556114)
		(width 0.089408)
		(layer "In2.Cu")
		(net "SMB_CPU0_PE_HP_GTL_SCL")
	)
	(segment
		(start 398.860772 -60.481464)
		(end 398.860772 -60.952634)
		(width 0.089408)
		(layer "In2.Cu")
		(net "SMB_CPU0_PE_HP_GTL_SCL")
	)
	(segment
		(start 396.769336 -73.556114)
		(end 396.769336 -76.296012)
		(width 0.089408)
		(layer "In2.Cu")
		(net "SMB_CPU0_PE_HP_GTL_SCL")
	)
	(segment
		(start 398.860772 -60.952634)
		(end 397.684752 -62.128654)
		(width 0.089408)
		(layer "In2.Cu")
		(net "SMB_CPU0_PE_HP_GTL_SCL")
	)
	(segment
		(start 395.054328 -72.173084)
		(end 395.9606 -73.079356)
		(width 0.089408)
		(layer "In2.Cu")
		(net "SMB_CPU0_PE_HP_GTL_SCL")
	)
	(segment
		(start 394.814552 -66.191384)
		(end 394.814552 -70.990968)
		(width 0.089408)
		(layer "In2.Cu")
		(net "SMB_CPU0_PE_HP_GTL_SCL")
	)
	(segment
		(start 396.769336 -76.296012)
		(end 396.766288 -76.29906)
		(width 0.089408)
		(layer "In2.Cu")
		(net "SMB_CPU0_PE_HP_GTL_SCL")
	)
	(segment
		(start 395.9606 -73.079356)
		(end 396.292578 -73.079356)
		(width 0.089408)
		(layer "In2.Cu")
		(net "SMB_CPU0_PE_HP_GTL_SCL")
	)
	(segment
		(start 395.054328 -71.230744)
		(end 395.054328 -72.173084)
		(width 0.089408)
		(layer "In2.Cu")
		(net "SMB_CPU0_PE_HP_GTL_SCL")
	)
	(segment
		(start 394.814552 -70.990968)
		(end 395.054328 -71.230744)
		(width 0.089408)
		(layer "In2.Cu")
		(net "SMB_CPU0_PE_HP_GTL_SCL")
	)
	(segment
		(start 397.684752 -63.737744)
		(end 397.130016 -64.29248)
		(width 0.089408)
		(layer "In2.Cu")
		(net "SMB_CPU0_PE_HP_GTL_SCL")
	)
	(segment
		(start 396.766288 -76.29906)
		(end 396.766288 -83.058762)
		(width 0.089408)
		(layer "In2.Cu")
		(net "SMB_CPU0_PE_HP_GTL_SCL")
	)
	(segment
		(start 397.130016 -64.29248)
		(end 396.713456 -64.29248)
		(width 0.089408)
		(layer "In2.Cu")
		(net "SMB_CPU0_PE_HP_GTL_SCL")
	)
	(segment
		(start 396.713456 -64.29248)
		(end 394.814552 -66.191384)
		(width 0.089408)
		(layer "In2.Cu")
		(net "SMB_CPU0_PE_HP_GTL_SCL")
	)
	(segment
		(start 396.766288 -83.058762)
		(end 398.579594 -84.872068)
		(width 0.089408)
		(layer "In2.Cu")
		(net "SMB_CPU0_PE_HP_GTL_SCL")
	)
	(segment
		(start 397.684752 -62.128654)
		(end 397.684752 -63.737744)
		(width 0.089408)
		(layer "In2.Cu")
		(net "SMB_CPU0_PE_HP_GTL_SCL")
	)
	(segment
		(start 378.939552 -60.07735)
		(end 374.785128 -60.07735)
		(width 0.089408)
		(layer "In4.Cu")
		(net "SMB_CPU0_PE_HP_GTL_SCL")
	)
	(segment
		(start 360.621072 -68.735448)
		(end 358.865424 -68.735448)
		(width 0.089408)
		(layer "In4.Cu")
		(net "SMB_CPU0_PE_HP_GTL_SCL")
	)
	(segment
		(start 366.51692 -61.460126)
		(end 366.51692 -65.253362)
		(width 0.089408)
		(layer "In4.Cu")
		(net "SMB_CPU0_PE_HP_GTL_SCL")
	)
	(segment
		(start 400.728688 -84.907374)
		(end 402.852382 -84.907374)
		(width 0.089408)
		(layer "In4.Cu")
		(net "SMB_CPU0_PE_HP_GTL_SCL")
	)
	(segment
		(start 374.396508 -60.46597)
		(end 367.511076 -60.46597)
		(width 0.089408)
		(layer "In4.Cu")
		(net "SMB_CPU0_PE_HP_GTL_SCL")
	)
	(segment
		(start 419.445694 -89.88425)
		(end 419.655244 -90.0938)
		(width 0.089408)
		(layer "In4.Cu")
		(net "SMB_CPU0_PE_HP_GTL_SCL")
	)
	(segment
		(start 392.009122 -59.556396)
		(end 391.49655 -59.556396)
		(width 0.089408)
		(layer "In4.Cu")
		(net "SMB_CPU0_PE_HP_GTL_SCL")
	)
	(segment
		(start 418.94252 -86.412832)
		(end 418.942266 -86.413086)
		(width 0.089408)
		(layer "In4.Cu")
		(net "SMB_CPU0_PE_HP_GTL_SCL")
	)
	(segment
		(start 390.817608 -60.354972)
		(end 387.62686 -60.354972)
		(width 0.089408)
		(layer "In4.Cu")
		(net "SMB_CPU0_PE_HP_GTL_SCL")
	)
	(segment
		(start 407.809446 -85.49513)
		(end 408.671268 -84.633308)
		(width 0.089408)
		(layer "In4.Cu")
		(net "SMB_CPU0_PE_HP_GTL_SCL")
	)
	(segment
		(start 398.860772 -60.481464)
		(end 398.724882 -60.617354)
		(width 0.089408)
		(layer "In4.Cu")
		(net "SMB_CPU0_PE_HP_GTL_SCL")
	)
	(segment
		(start 358.865424 -68.735448)
		(end 358.830118 -68.700142)
		(width 0.089408)
		(layer "In4.Cu")
		(net "SMB_CPU0_PE_HP_GTL_SCL")
	)
	(segment
		(start 367.511076 -60.46597)
		(end 366.51692 -61.460126)
		(width 0.089408)
		(layer "In4.Cu")
		(net "SMB_CPU0_PE_HP_GTL_SCL")
	)
	(segment
		(start 418.942266 -86.413086)
		(end 418.942266 -89.654126)
		(width 0.089408)
		(layer "In4.Cu")
		(net "SMB_CPU0_PE_HP_GTL_SCL")
	)
	(segment
		(start 394.09243 -59.924188)
		(end 392.376914 -59.924188)
		(width 0.089408)
		(layer "In4.Cu")
		(net "SMB_CPU0_PE_HP_GTL_SCL")
	)
	(segment
		(start 398.759426 -84.692236)
		(end 400.51355 -84.692236)
		(width 0.089408)
		(layer "In4.Cu")
		(net "SMB_CPU0_PE_HP_GTL_SCL")
	)
	(segment
		(start 410.07665 -84.972906)
		(end 413.20466 -84.972906)
		(width 0.089408)
		(layer "In4.Cu")
		(net "SMB_CPU0_PE_HP_GTL_SCL")
	)
	(segment
		(start 413.20466 -84.972906)
		(end 413.316674 -84.860892)
		(width 0.089408)
		(layer "In4.Cu")
		(net "SMB_CPU0_PE_HP_GTL_SCL")
	)
	(segment
		(start 409.737052 -84.633308)
		(end 410.07665 -84.972906)
		(width 0.089408)
		(layer "In4.Cu")
		(net "SMB_CPU0_PE_HP_GTL_SCL")
	)
	(segment
		(start 402.852382 -84.907374)
		(end 402.995892 -85.050884)
		(width 0.089408)
		(layer "In4.Cu")
		(net "SMB_CPU0_PE_HP_GTL_SCL")
	)
	(segment
		(start 392.376914 -59.924188)
		(end 392.009122 -59.556396)
		(width 0.089408)
		(layer "In4.Cu")
		(net "SMB_CPU0_PE_HP_GTL_SCL")
	)
	(segment
		(start 398.724882 -60.617354)
		(end 394.785596 -60.617354)
		(width 0.089408)
		(layer "In4.Cu")
		(net "SMB_CPU0_PE_HP_GTL_SCL")
	)
	(segment
		(start 418.942266 -89.654126)
		(end 419.17239 -89.88425)
		(width 0.089408)
		(layer "In4.Cu")
		(net "SMB_CPU0_PE_HP_GTL_SCL")
	)
	(segment
		(start 385.95554 -59.74588)
		(end 385.573524 -60.127896)
		(width 0.089408)
		(layer "In4.Cu")
		(net "SMB_CPU0_PE_HP_GTL_SCL")
	)
	(segment
		(start 379.953012 -61.09081)
		(end 378.939552 -60.07735)
		(width 0.089408)
		(layer "In4.Cu")
		(net "SMB_CPU0_PE_HP_GTL_SCL")
	)
	(segment
		(start 418.94252 -86.12886)
		(end 418.94252 -86.412832)
		(width 0.089408)
		(layer "In4.Cu")
		(net "SMB_CPU0_PE_HP_GTL_SCL")
	)
	(segment
		(start 400.51355 -84.692236)
		(end 400.728688 -84.907374)
		(width 0.089408)
		(layer "In4.Cu")
		(net "SMB_CPU0_PE_HP_GTL_SCL")
	)
	(segment
		(start 374.785128 -60.07735)
		(end 374.396508 -60.46597)
		(width 0.089408)
		(layer "In4.Cu")
		(net "SMB_CPU0_PE_HP_GTL_SCL")
	)
	(segment
		(start 387.017768 -59.74588)
		(end 385.95554 -59.74588)
		(width 0.089408)
		(layer "In4.Cu")
		(net "SMB_CPU0_PE_HP_GTL_SCL")
	)
	(segment
		(start 418.366702 -84.860892)
		(end 418.942266 -85.436456)
		(width 0.089408)
		(layer "In4.Cu")
		(net "SMB_CPU0_PE_HP_GTL_SCL")
	)
	(segment
		(start 405.923496 -85.49513)
		(end 407.809446 -85.49513)
		(width 0.089408)
		(layer "In4.Cu")
		(net "SMB_CPU0_PE_HP_GTL_SCL")
	)
	(segment
		(start 391.49655 -59.556396)
		(end 391.08634 -59.966606)
		(width 0.089408)
		(layer "In4.Cu")
		(net "SMB_CPU0_PE_HP_GTL_SCL")
	)
	(segment
		(start 402.995892 -85.050884)
		(end 405.47925 -85.050884)
		(width 0.089408)
		(layer "In4.Cu")
		(net "SMB_CPU0_PE_HP_GTL_SCL")
	)
	(segment
		(start 385.573524 -60.127896)
		(end 383.020062 -60.127896)
		(width 0.089408)
		(layer "In4.Cu")
		(net "SMB_CPU0_PE_HP_GTL_SCL")
	)
	(segment
		(start 418.942266 -86.128606)
		(end 418.94252 -86.12886)
		(width 0.089408)
		(layer "In4.Cu")
		(net "SMB_CPU0_PE_HP_GTL_SCL")
	)
	(segment
		(start 364.405672 -67.36461)
		(end 361.99191 -67.36461)
		(width 0.089408)
		(layer "In4.Cu")
		(net "SMB_CPU0_PE_HP_GTL_SCL")
	)
	(segment
		(start 418.942266 -85.436456)
		(end 418.942266 -86.128606)
		(width 0.089408)
		(layer "In4.Cu")
		(net "SMB_CPU0_PE_HP_GTL_SCL")
	)
	(segment
		(start 405.47925 -85.050884)
		(end 405.923496 -85.49513)
		(width 0.089408)
		(layer "In4.Cu")
		(net "SMB_CPU0_PE_HP_GTL_SCL")
	)
	(segment
		(start 358.830118 -68.700142)
		(end 358.388666 -68.700142)
		(width 0.089408)
		(layer "In4.Cu")
		(net "SMB_CPU0_PE_HP_GTL_SCL")
	)
	(segment
		(start 419.17239 -89.88425)
		(end 419.445694 -89.88425)
		(width 0.089408)
		(layer "In4.Cu")
		(net "SMB_CPU0_PE_HP_GTL_SCL")
	)
	(segment
		(start 366.51692 -65.253362)
		(end 364.405672 -67.36461)
		(width 0.089408)
		(layer "In4.Cu")
		(net "SMB_CPU0_PE_HP_GTL_SCL")
	)
	(segment
		(start 391.08634 -60.08624)
		(end 390.817608 -60.354972)
		(width 0.089408)
		(layer "In4.Cu")
		(net "SMB_CPU0_PE_HP_GTL_SCL")
	)
	(segment
		(start 391.08634 -59.966606)
		(end 391.08634 -60.08624)
		(width 0.089408)
		(layer "In4.Cu")
		(net "SMB_CPU0_PE_HP_GTL_SCL")
	)
	(segment
		(start 382.057148 -61.09081)
		(end 379.953012 -61.09081)
		(width 0.089408)
		(layer "In4.Cu")
		(net "SMB_CPU0_PE_HP_GTL_SCL")
	)
	(segment
		(start 387.62686 -60.354972)
		(end 387.017768 -59.74588)
		(width 0.089408)
		(layer "In4.Cu")
		(net "SMB_CPU0_PE_HP_GTL_SCL")
	)
	(segment
		(start 361.99191 -67.36461)
		(end 360.621072 -68.735448)
		(width 0.089408)
		(layer "In4.Cu")
		(net "SMB_CPU0_PE_HP_GTL_SCL")
	)
	(segment
		(start 383.020062 -60.127896)
		(end 382.057148 -61.09081)
		(width 0.089408)
		(layer "In4.Cu")
		(net "SMB_CPU0_PE_HP_GTL_SCL")
	)
	(segment
		(start 394.785596 -60.617354)
		(end 394.09243 -59.924188)
		(width 0.089408)
		(layer "In4.Cu")
		(net "SMB_CPU0_PE_HP_GTL_SCL")
	)
	(segment
		(start 408.671268 -84.633308)
		(end 409.737052 -84.633308)
		(width 0.089408)
		(layer "In4.Cu")
		(net "SMB_CPU0_PE_HP_GTL_SCL")
	)
	(segment
		(start 398.579594 -84.872068)
		(end 398.759426 -84.692236)
		(width 0.089408)
		(layer "In4.Cu")
		(net "SMB_CPU0_PE_HP_GTL_SCL")
	)
	(segment
		(start 413.316674 -84.860892)
		(end 418.366702 -84.860892)
		(width 0.089408)
		(layer "In4.Cu")
		(net "SMB_CPU0_PE_HP_GTL_SCL")
	)
	(segment
		(start 297.004994 -69.071998)
		(end 297.008296 -69.07784)
		(width 0.0889)
		(layer "In11.Cu")
		(net "SMB_CPU0_PE_HP_GTL_SCL")
	)
	(segment
		(start 304.370232 -68.382388)
		(end 304.4063 -68.382388)
		(width 0.0889)
		(layer "In11.Cu")
		(net "SMB_CPU0_PE_HP_GTL_SCL")
	)
	(segment
		(start 292.36924 -66.800984)
		(end 292.662356 -66.632074)
		(width 0.0889)
		(layer "In11.Cu")
		(net "SMB_CPU0_PE_HP_GTL_SCL")
	)
	(segment
		(start 298.360846 -69.868288)
		(end 298.396406 -69.868288)
		(width 0.0889)
		(layer "In11.Cu")
		(net "SMB_CPU0_PE_HP_GTL_SCL")
	)
	(segment
		(start 307.374036 -68.876926)
		(end 307.40096 -68.90385)
		(width 0.0889)
		(layer "In11.Cu")
		(net "SMB_CPU0_PE_HP_GTL_SCL")
	)
	(segment
		(start 301.794926 -69.868288)
		(end 301.830486 -69.868288)
		(width 0.0889)
		(layer "In11.Cu")
		(net "SMB_CPU0_PE_HP_GTL_SCL")
	)
	(segment
		(start 294.06469 -68.382134)
		(end 294.097456 -68.382134)
		(width 0.0889)
		(layer "In11.Cu")
		(net "SMB_CPU0_PE_HP_GTL_SCL")
	)
	(segment
		(start 307.401468 -68.904358)
		(end 307.65496 -68.904358)
		(width 0.089408)
		(layer "In11.Cu")
		(net "SMB_CPU0_PE_HP_GTL_SCL")
	)
	(segment
		(start 302.66005 -69.372734)
		(end 302.692816 -69.372734)
		(width 0.0889)
		(layer "In11.Cu")
		(net "SMB_CPU0_PE_HP_GTL_SCL")
	)
	(segment
		(start 336.45983 -65.687448)
		(end 352.991674 -65.687448)
		(width 0.089408)
		(layer "In11.Cu")
		(net "SMB_CPU0_PE_HP_GTL_SCL")
	)
	(segment
		(start 297.495214 -69.372734)
		(end 297.531282 -69.372734)
		(width 0.0889)
		(layer "In11.Cu")
		(net "SMB_CPU0_PE_HP_GTL_SCL")
	)
	(segment
		(start 357.918512 -67.981068)
		(end 358.388666 -68.451222)
		(width 0.089408)
		(layer "In11.Cu")
		(net "SMB_CPU0_PE_HP_GTL_SCL")
	)
	(segment
		(start 331.96657 -70.180708)
		(end 336.45983 -65.687448)
		(width 0.089408)
		(layer "In11.Cu")
		(net "SMB_CPU0_PE_HP_GTL_SCL")
	)
	(segment
		(start 307.40096 -68.90385)
		(end 307.401468 -68.904358)
		(width 0.089408)
		(layer "In11.Cu")
		(net "SMB_CPU0_PE_HP_GTL_SCL")
	)
	(segment
		(start 300.077886 -69.868288)
		(end 300.113446 -69.868288)
		(width 0.0889)
		(layer "In11.Cu")
		(net "SMB_CPU0_PE_HP_GTL_SCL")
	)
	(segment
		(start 355.285294 -67.981068)
		(end 357.918512 -67.981068)
		(width 0.089408)
		(layer "In11.Cu")
		(net "SMB_CPU0_PE_HP_GTL_SCL")
	)
	(segment
		(start 306.898548 -68.876926)
		(end 307.374036 -68.876926)
		(width 0.0889)
		(layer "In11.Cu")
		(net "SMB_CPU0_PE_HP_GTL_SCL")
	)
	(segment
		(start 294.92702 -68.877688)
		(end 294.959786 -68.877688)
		(width 0.0889)
		(layer "In11.Cu")
		(net "SMB_CPU0_PE_HP_GTL_SCL")
	)
	(segment
		(start 358.388666 -68.451222)
		(end 358.388666 -68.700142)
		(width 0.089408)
		(layer "In11.Cu")
		(net "SMB_CPU0_PE_HP_GTL_SCL")
	)
	(segment
		(start 308.93131 -70.180708)
		(end 331.96657 -70.180708)
		(width 0.089408)
		(layer "In11.Cu")
		(net "SMB_CPU0_PE_HP_GTL_SCL")
	)
	(segment
		(start 295.78173 -69.372734)
		(end 295.82491 -69.372734)
		(width 0.0889)
		(layer "In11.Cu")
		(net "SMB_CPU0_PE_HP_GTL_SCL")
	)
	(segment
		(start 293.20998 -66.896488)
		(end 293.22776 -66.896488)
		(width 0.0889)
		(layer "In11.Cu")
		(net "SMB_CPU0_PE_HP_GTL_SCL")
	)
	(segment
		(start 292.662356 -66.632074)
		(end 292.751764 -66.656204)
		(width 0.0889)
		(layer "In11.Cu")
		(net "SMB_CPU0_PE_HP_GTL_SCL")
	)
	(segment
		(start 303.51476 -68.877688)
		(end 303.547526 -68.877688)
		(width 0.0889)
		(layer "In11.Cu")
		(net "SMB_CPU0_PE_HP_GTL_SCL")
	)
	(segment
		(start 307.65496 -68.904358)
		(end 308.93131 -70.180708)
		(width 0.089408)
		(layer "In11.Cu")
		(net "SMB_CPU0_PE_HP_GTL_SCL")
	)
	(segment
		(start 352.991674 -65.687448)
		(end 355.285294 -67.981068)
		(width 0.089408)
		(layer "In11.Cu")
		(net "SMB_CPU0_PE_HP_GTL_SCL")
	)
	(arc
		(start 303.183036 -69.077586)
		(mid 303.323115 -68.93485)
		(end 303.51476 -68.877688)
		(width 0.0889)
		(layer "In11.Cu")
		(net "SMB_CPU0_PE_HP_GTL_SCL")
	)
	(arc
		(start 303.547526 -68.877688)
		(mid 303.83295 -68.794221)
		(end 304.041556 -68.582286)
		(width 0.0889)
		(layer "In11.Cu")
		(net "SMB_CPU0_PE_HP_GTL_SCL")
	)
	(arc
		(start 302.692816 -69.372734)
		(mid 302.976033 -69.288453)
		(end 303.183036 -69.077586)
		(width 0.0889)
		(layer "In11.Cu")
		(net "SMB_CPU0_PE_HP_GTL_SCL")
	)
	(arc
		(start 297.866816 -69.572886)
		(mid 298.075424 -69.784818)
		(end 298.360846 -69.868288)
		(width 0.0889)
		(layer "In11.Cu")
		(net "SMB_CPU0_PE_HP_GTL_SCL")
	)
	(arc
		(start 300.607476 -69.572886)
		(mid 300.954186 -69.372575)
		(end 301.300896 -69.572886)
		(width 0.0889)
		(layer "In11.Cu")
		(net "SMB_CPU0_PE_HP_GTL_SCL")
	)
	(arc
		(start 295.29151 -69.077586)
		(mid 295.498514 -69.28845)
		(end 295.78173 -69.372734)
		(width 0.0889)
		(layer "In11.Cu")
		(net "SMB_CPU0_PE_HP_GTL_SCL")
	)
	(arc
		(start 304.041556 -68.582286)
		(mid 304.1803 -68.440253)
		(end 304.370232 -68.382388)
		(width 0.0889)
		(layer "In11.Cu")
		(net "SMB_CPU0_PE_HP_GTL_SCL")
	)
	(arc
		(start 301.300896 -69.572886)
		(mid 301.509504 -69.784818)
		(end 301.794926 -69.868288)
		(width 0.0889)
		(layer "In11.Cu")
		(net "SMB_CPU0_PE_HP_GTL_SCL")
	)
	(arc
		(start 293.22776 -66.896488)
		(mid 293.427833 -66.950112)
		(end 293.574216 -67.09664)
		(width 0.0889)
		(layer "In11.Cu")
		(net "SMB_CPU0_PE_HP_GTL_SCL")
	)
	(arc
		(start 305.758596 -68.582286)
		(mid 306.105306 -68.381975)
		(end 306.452016 -68.582286)
		(width 0.0889)
		(layer "In11.Cu")
		(net "SMB_CPU0_PE_HP_GTL_SCL")
	)
	(arc
		(start 304.734976 -68.582286)
		(mid 305.246786 -68.877953)
		(end 305.758596 -68.582286)
		(width 0.0889)
		(layer "In11.Cu")
		(net "SMB_CPU0_PE_HP_GTL_SCL")
	)
	(arc
		(start 300.113446 -69.868288)
		(mid 300.39887 -69.784821)
		(end 300.607476 -69.572886)
		(width 0.0889)
		(layer "In11.Cu")
		(net "SMB_CPU0_PE_HP_GTL_SCL")
	)
	(arc
		(start 299.583856 -69.572886)
		(mid 299.792464 -69.784818)
		(end 300.077886 -69.868288)
		(width 0.0889)
		(layer "In11.Cu")
		(net "SMB_CPU0_PE_HP_GTL_SCL")
	)
	(arc
		(start 296.31513 -69.077586)
		(mid 296.658406 -68.877635)
		(end 297.004994 -69.071998)
		(width 0.0889)
		(layer "In11.Cu")
		(net "SMB_CPU0_PE_HP_GTL_SCL")
	)
	(arc
		(start 304.4063 -68.382388)
		(mid 304.596229 -68.440258)
		(end 304.734976 -68.582286)
		(width 0.0889)
		(layer "In11.Cu")
		(net "SMB_CPU0_PE_HP_GTL_SCL")
	)
	(arc
		(start 297.008296 -69.07784)
		(mid 297.213917 -69.287763)
		(end 297.495214 -69.372734)
		(width 0.0889)
		(layer "In11.Cu")
		(net "SMB_CPU0_PE_HP_GTL_SCL")
	)
	(arc
		(start 294.959786 -68.877688)
		(mid 295.151428 -68.934854)
		(end 295.29151 -69.077586)
		(width 0.0889)
		(layer "In11.Cu")
		(net "SMB_CPU0_PE_HP_GTL_SCL")
	)
	(arc
		(start 302.324516 -69.572886)
		(mid 302.466199 -69.429082)
		(end 302.66005 -69.372734)
		(width 0.0889)
		(layer "In11.Cu")
		(net "SMB_CPU0_PE_HP_GTL_SCL")
	)
	(arc
		(start 293.579042 -67.487546)
		(mid 293.495286 -67.786633)
		(end 293.57447 -68.086986)
		(width 0.0889)
		(layer "In11.Cu")
		(net "SMB_CPU0_PE_HP_GTL_SCL")
	)
	(arc
		(start 294.097456 -68.382134)
		(mid 294.291306 -68.438484)
		(end 294.43299 -68.582286)
		(width 0.0889)
		(layer "In11.Cu")
		(net "SMB_CPU0_PE_HP_GTL_SCL")
	)
	(arc
		(start 298.396406 -69.868288)
		(mid 298.68183 -69.784821)
		(end 298.890436 -69.572886)
		(width 0.0889)
		(layer "In11.Cu")
		(net "SMB_CPU0_PE_HP_GTL_SCL")
	)
	(arc
		(start 294.43299 -68.582286)
		(mid 294.641598 -68.794218)
		(end 294.92702 -68.877688)
		(width 0.0889)
		(layer "In11.Cu")
		(net "SMB_CPU0_PE_HP_GTL_SCL")
	)
	(arc
		(start 298.890436 -69.572886)
		(mid 299.237146 -69.372575)
		(end 299.583856 -69.572886)
		(width 0.0889)
		(layer "In11.Cu")
		(net "SMB_CPU0_PE_HP_GTL_SCL")
	)
	(arc
		(start 293.574216 -67.09664)
		(mid 293.627593 -67.291449)
		(end 293.579042 -67.487546)
		(width 0.089408)
		(layer "In11.Cu")
		(net "SMB_CPU0_PE_HP_GTL_SCL")
	)
	(arc
		(start 306.452016 -68.582286)
		(mid 306.640443 -68.782391)
		(end 306.898548 -68.876926)
		(width 0.0889)
		(layer "In11.Cu")
		(net "SMB_CPU0_PE_HP_GTL_SCL")
	)
	(arc
		(start 295.82491 -69.372734)
		(mid 296.108127 -69.288453)
		(end 296.31513 -69.077586)
		(width 0.0889)
		(layer "In11.Cu")
		(net "SMB_CPU0_PE_HP_GTL_SCL")
	)
	(arc
		(start 301.830486 -69.868288)
		(mid 302.11591 -69.784821)
		(end 302.324516 -69.572886)
		(width 0.0889)
		(layer "In11.Cu")
		(net "SMB_CPU0_PE_HP_GTL_SCL")
	)
	(arc
		(start 293.57447 -68.086986)
		(mid 293.781474 -68.29785)
		(end 294.06469 -68.382134)
		(width 0.0889)
		(layer "In11.Cu")
		(net "SMB_CPU0_PE_HP_GTL_SCL")
	)
	(arc
		(start 292.751764 -66.656204)
		(mid 292.953174 -66.829157)
		(end 293.20998 -66.896488)
		(width 0.0889)
		(layer "In11.Cu")
		(net "SMB_CPU0_PE_HP_GTL_SCL")
	)
	(arc
		(start 297.531282 -69.372734)
		(mid 297.725132 -69.429084)
		(end 297.866816 -69.572886)
		(width 0.0889)
		(layer "In11.Cu")
		(net "SMB_CPU0_PE_HP_GTL_SCL")
	)
	(segment
		(start 421.3987 -105.029)
		(end 420.94912 -105.47858)
		(width 0.1016)
		(layer "F.Cu")
		(net "SMB_CPU0_PE_HP_GTL_R_SDA")
	)
	(segment
		(start 421.127936 -103.373936)
		(end 421.3987 -103.6447)
		(width 0.10795)
		(layer "F.Cu")
		(net "SMB_CPU0_PE_HP_GTL_R_SDA")
	)
	(segment
		(start 420.94912 -105.47858)
		(end 420.94912 -107.01528)
		(width 0.1016)
		(layer "F.Cu")
		(net "SMB_CPU0_PE_HP_GTL_R_SDA")
	)
	(segment
		(start 421.3987 -104.267)
		(end 421.3987 -105.029)
		(width 0.1016)
		(layer "F.Cu")
		(net "SMB_CPU0_PE_HP_GTL_R_SDA")
	)
	(segment
		(start 421.127936 -102.614476)
		(end 421.127936 -103.373936)
		(width 0.10795)
		(layer "F.Cu")
		(net "SMB_CPU0_PE_HP_GTL_R_SDA")
	)
	(segment
		(start 421.3987 -103.6447)
		(end 421.3987 -104.267)
		(width 0.10795)
		(layer "F.Cu")
		(net "SMB_CPU0_PE_HP_GTL_R_SDA")
	)
	(via
		(at 421.127936 -102.614476)
		(size 0.762)
		(drill 0.381)
		(layers "F.Cu" "B.Cu")
		(net "SMB_CPU0_PE_HP_GTL_R_SDA")
	)
	(segment
		(start 420.5097 -105.029)
		(end 420.3065 -105.2322)
		(width 0.1016)
		(layer "F.Cu")
		(net "SMB_CPU0_PE_HP_GTL_R_SCL")
	)
	(segment
		(start 420.29888 -105.311702)
		(end 420.29888 -107.01528)
		(width 0.1016)
		(layer "F.Cu")
		(net "SMB_CPU0_PE_HP_GTL_R_SCL")
	)
	(segment
		(start 420.5097 -104.267)
		(end 420.5097 -103.634794)
		(width 0.10795)
		(layer "F.Cu")
		(net "SMB_CPU0_PE_HP_GTL_R_SCL")
	)
	(segment
		(start 420.5097 -103.634794)
		(end 419.94074 -103.065834)
		(width 0.10795)
		(layer "F.Cu")
		(net "SMB_CPU0_PE_HP_GTL_R_SCL")
	)
	(segment
		(start 420.5097 -104.267)
		(end 420.5097 -105.029)
		(width 0.1016)
		(layer "F.Cu")
		(net "SMB_CPU0_PE_HP_GTL_R_SCL")
	)
	(segment
		(start 420.3065 -105.2322)
		(end 420.3065 -105.304082)
		(width 0.1016)
		(layer "F.Cu")
		(net "SMB_CPU0_PE_HP_GTL_R_SCL")
	)
	(segment
		(start 420.3065 -105.304082)
		(end 420.29888 -105.311702)
		(width 0.1016)
		(layer "F.Cu")
		(net "SMB_CPU0_PE_HP_GTL_R_SCL")
	)
	(via
		(at 419.94074 -103.065834)
		(size 0.762)
		(drill 0.381)
		(layers "F.Cu" "B.Cu")
		(net "SMB_CPU0_PE_HP_GTL_R_SCL")
	)
	(segment
		(start 469.138 -50.720244)
		(end 468.728298 -51.129946)
		(width 0.10795)
		(layer "F.Cu")
		(net "FM_OCP_MEZZB_PRES_N")
	)
	(segment
		(start 468.728298 -51.129946)
		(end 468.728298 -51.688746)
		(width 0.10795)
		(layer "F.Cu")
		(net "FM_OCP_MEZZB_PRES_N")
	)
	(segment
		(start 468.728298 -51.688746)
		(end 468.5411 -51.875944)
		(width 0.10795)
		(layer "F.Cu")
		(net "FM_OCP_MEZZB_PRES_N")
	)
	(segment
		(start 469.138 -50.4444)
		(end 469.138 -50.720244)
		(width 0.10795)
		(layer "F.Cu")
		(net "FM_OCP_MEZZB_PRES_N")
	)
	(via
		(at 469.138 -50.4444)
		(size 0.508)
		(drill 0.254)
		(layers "F.Cu" "B.Cu")
		(net "FM_OCP_MEZZB_PRES_N")
	)
	(via
		(at 467.8426 -44.2468)
		(size 0.6604)
		(drill 0.3302)
		(layers "F.Cu" "B.Cu")
		(net "FM_OCP_MEZZB_PRES_N")
	)
	(segment
		(start 435.089554 -47.450502)
		(end 435.292754 -47.450502)
		(width 0.10795)
		(layer "B.Cu")
		(net "FM_OCP_MEZZB_PRES_N")
	)
	(segment
		(start 410.920438 -55.042562)
		(end 412.317946 -55.042562)
		(width 0.10795)
		(layer "B.Cu")
		(net "FM_OCP_MEZZB_PRES_N")
	)
	(segment
		(start 427.788578 -51.013614)
		(end 427.917102 -50.88509)
		(width 0.10795)
		(layer "B.Cu")
		(net "FM_OCP_MEZZB_PRES_N")
	)
	(segment
		(start 434.504338 -48.035718)
		(end 435.089554 -47.450502)
		(width 0.10795)
		(layer "B.Cu")
		(net "FM_OCP_MEZZB_PRES_N")
	)
	(segment
		(start 418.869368 -51.970432)
		(end 421.065452 -51.970432)
		(width 0.10795)
		(layer "B.Cu")
		(net "FM_OCP_MEZZB_PRES_N")
	)
	(segment
		(start 427.917102 -50.88509)
		(end 431.319686 -50.88509)
		(width 0.10795)
		(layer "B.Cu")
		(net "FM_OCP_MEZZB_PRES_N")
	)
	(segment
		(start 421.344852 -51.691032)
		(end 423.322242 -51.691032)
		(width 0.10795)
		(layer "B.Cu")
		(net "FM_OCP_MEZZB_PRES_N")
	)
	(segment
		(start 468.97036 -44.2468)
		(end 469.649302 -44.925742)
		(width 0.10795)
		(layer "B.Cu")
		(net "FM_OCP_MEZZB_PRES_N")
	)
	(segment
		(start 423.480992 -51.532282)
		(end 425.335954 -51.532282)
		(width 0.10795)
		(layer "B.Cu")
		(net "FM_OCP_MEZZB_PRES_N")
	)
	(segment
		(start 427.40707 -51.013614)
		(end 427.788578 -51.013614)
		(width 0.10795)
		(layer "B.Cu")
		(net "FM_OCP_MEZZB_PRES_N")
	)
	(segment
		(start 435.292754 -47.450502)
		(end 435.956456 -46.7868)
		(width 0.10795)
		(layer "B.Cu")
		(net "FM_OCP_MEZZB_PRES_N")
	)
	(segment
		(start 427.278546 -50.88509)
		(end 427.40707 -51.013614)
		(width 0.10795)
		(layer "B.Cu")
		(net "FM_OCP_MEZZB_PRES_N")
	)
	(segment
		(start 406.054814 -52.430426)
		(end 406.29332 -52.19192)
		(width 0.10795)
		(layer "B.Cu")
		(net "FM_OCP_MEZZB_PRES_N")
	)
	(segment
		(start 435.956456 -46.7868)
		(end 462.2165 -46.7868)
		(width 0.10795)
		(layer "B.Cu")
		(net "FM_OCP_MEZZB_PRES_N")
	)
	(segment
		(start 425.983146 -50.88509)
		(end 427.278546 -50.88509)
		(width 0.10795)
		(layer "B.Cu")
		(net "FM_OCP_MEZZB_PRES_N")
	)
	(segment
		(start 421.065452 -51.970432)
		(end 421.344852 -51.691032)
		(width 0.10795)
		(layer "B.Cu")
		(net "FM_OCP_MEZZB_PRES_N")
	)
	(segment
		(start 409.013152 -55.956962)
		(end 410.006038 -55.956962)
		(width 0.10795)
		(layer "B.Cu")
		(net "FM_OCP_MEZZB_PRES_N")
	)
	(segment
		(start 415.064448 -55.775352)
		(end 418.869368 -51.970432)
		(width 0.10795)
		(layer "B.Cu")
		(net "FM_OCP_MEZZB_PRES_N")
	)
	(segment
		(start 431.319686 -50.88509)
		(end 434.169058 -48.035718)
		(width 0.10795)
		(layer "B.Cu")
		(net "FM_OCP_MEZZB_PRES_N")
	)
	(segment
		(start 469.649302 -44.925742)
		(end 469.649302 -49.933098)
		(width 0.10795)
		(layer "B.Cu")
		(net "FM_OCP_MEZZB_PRES_N")
	)
	(segment
		(start 462.2165 -46.7868)
		(end 464.7565 -44.2468)
		(width 0.10795)
		(layer "B.Cu")
		(net "FM_OCP_MEZZB_PRES_N")
	)
	(segment
		(start 412.317946 -55.042562)
		(end 413.050736 -55.775352)
		(width 0.10795)
		(layer "B.Cu")
		(net "FM_OCP_MEZZB_PRES_N")
	)
	(segment
		(start 406.29332 -52.19192)
		(end 407.05532 -52.19192)
		(width 0.10795)
		(layer "B.Cu")
		(net "FM_OCP_MEZZB_PRES_N")
	)
	(segment
		(start 408.28722 -53.42382)
		(end 408.28722 -55.23103)
		(width 0.10795)
		(layer "B.Cu")
		(net "FM_OCP_MEZZB_PRES_N")
	)
	(segment
		(start 406.054814 -53.848)
		(end 406.054814 -52.430426)
		(width 0.10795)
		(layer "B.Cu")
		(net "FM_OCP_MEZZB_PRES_N")
	)
	(segment
		(start 434.169058 -48.035718)
		(end 434.504338 -48.035718)
		(width 0.10795)
		(layer "B.Cu")
		(net "FM_OCP_MEZZB_PRES_N")
	)
	(segment
		(start 410.006038 -55.956962)
		(end 410.920438 -55.042562)
		(width 0.10795)
		(layer "B.Cu")
		(net "FM_OCP_MEZZB_PRES_N")
	)
	(segment
		(start 423.322242 -51.691032)
		(end 423.480992 -51.532282)
		(width 0.10795)
		(layer "B.Cu")
		(net "FM_OCP_MEZZB_PRES_N")
	)
	(segment
		(start 407.05532 -52.19192)
		(end 408.28722 -53.42382)
		(width 0.10795)
		(layer "B.Cu")
		(net "FM_OCP_MEZZB_PRES_N")
	)
	(segment
		(start 469.649302 -49.933098)
		(end 469.138 -50.4444)
		(width 0.10795)
		(layer "B.Cu")
		(net "FM_OCP_MEZZB_PRES_N")
	)
	(segment
		(start 413.050736 -55.775352)
		(end 415.064448 -55.775352)
		(width 0.10795)
		(layer "B.Cu")
		(net "FM_OCP_MEZZB_PRES_N")
	)
	(segment
		(start 425.335954 -51.532282)
		(end 425.983146 -50.88509)
		(width 0.10795)
		(layer "B.Cu")
		(net "FM_OCP_MEZZB_PRES_N")
	)
	(segment
		(start 467.8426 -44.2468)
		(end 468.97036 -44.2468)
		(width 0.10795)
		(layer "B.Cu")
		(net "FM_OCP_MEZZB_PRES_N")
	)
	(segment
		(start 464.7565 -44.2468)
		(end 467.8426 -44.2468)
		(width 0.10795)
		(layer "B.Cu")
		(net "FM_OCP_MEZZB_PRES_N")
	)
	(segment
		(start 408.28722 -55.23103)
		(end 409.013152 -55.956962)
		(width 0.10795)
		(layer "B.Cu")
		(net "FM_OCP_MEZZB_PRES_N")
	)
	(segment
		(start 421.0304 -45.535342)
		(end 421.0304 -46.482)
		(width 0.10795)
		(layer "F.Cu")
		(net "BMC_STRAP_BIT5")
	)
	(segment
		(start 419.890194 -41.73474)
		(end 420.343838 -42.188384)
		(width 0.10795)
		(layer "F.Cu")
		(net "BMC_STRAP_BIT5")
	)
	(segment
		(start 420.865046 -48.079152)
		(end 420.865046 -47.464472)
		(width 0.10795)
		(layer "F.Cu")
		(net "BMC_STRAP_BIT5")
	)
	(segment
		(start 421.132 -46.5836)
		(end 421.132 -47.075598)
		(width 0.10795)
		(layer "F.Cu")
		(net "BMC_STRAP_BIT5")
	)
	(segment
		(start 421.0304 -46.482)
		(end 421.132 -46.5836)
		(width 0.10795)
		(layer "F.Cu")
		(net "BMC_STRAP_BIT5")
	)
	(segment
		(start 420.343838 -44.84878)
		(end 421.0304 -45.535342)
		(width 0.10795)
		(layer "F.Cu")
		(net "BMC_STRAP_BIT5")
	)
	(segment
		(start 420.343838 -42.188384)
		(end 420.343838 -44.84878)
		(width 0.10795)
		(layer "F.Cu")
		(net "BMC_STRAP_BIT5")
	)
	(segment
		(start 420.865046 -47.342552)
		(end 421.132 -47.075598)
		(width 0.089408)
		(layer "F.Cu")
		(net "BMC_STRAP_BIT5")
	)
	(segment
		(start 420.865046 -47.464472)
		(end 420.865046 -47.342552)
		(width 0.089408)
		(layer "F.Cu")
		(net "BMC_STRAP_BIT5")
	)
	(via
		(at 421.132 -47.075598)
		(size 0.762)
		(drill 0.381)
		(layers "F.Cu" "B.Cu")
		(net "BMC_STRAP_BIT5")
	)
	(segment
		(start 418.290248 -40.93464)
		(end 418.674804 -41.319196)
		(width 0.10795)
		(layer "F.Cu")
		(net "BMC_STRAP_BIT3")
	)
	(via
		(at 419.370256 -43.518074)
		(size 0.6604)
		(drill 0.3302)
		(layers "F.Cu" "B.Cu")
		(net "BMC_STRAP_BIT3")
	)
	(via
		(at 418.674804 -41.319196)
		(size 0.4572)
		(drill 0.2032)
		(layers "F.Cu" "B.Cu")
		(net "BMC_STRAP_BIT3")
	)
	(segment
		(start 418.674804 -41.434004)
		(end 418.674804 -41.319196)
		(width 0.10795)
		(layer "B.Cu")
		(net "BMC_STRAP_BIT3")
	)
	(segment
		(start 419.074092 -42.702734)
		(end 419.074092 -41.833292)
		(width 0.10795)
		(layer "B.Cu")
		(net "BMC_STRAP_BIT3")
	)
	(segment
		(start 418.680646 -44.650152)
		(end 419.370256 -43.960542)
		(width 0.10795)
		(layer "B.Cu")
		(net "BMC_STRAP_BIT3")
	)
	(segment
		(start 419.370256 -43.518074)
		(end 419.370256 -42.998898)
		(width 0.10795)
		(layer "B.Cu")
		(net "BMC_STRAP_BIT3")
	)
	(segment
		(start 419.370256 -43.960542)
		(end 419.370256 -43.518074)
		(width 0.10795)
		(layer "B.Cu")
		(net "BMC_STRAP_BIT3")
	)
	(segment
		(start 419.074092 -41.833292)
		(end 418.674804 -41.434004)
		(width 0.10795)
		(layer "B.Cu")
		(net "BMC_STRAP_BIT3")
	)
	(segment
		(start 419.370256 -42.998898)
		(end 419.074092 -42.702734)
		(width 0.10795)
		(layer "B.Cu")
		(net "BMC_STRAP_BIT3")
	)
	(segment
		(start 423.2402 -45.350684)
		(end 423.2402 -45.7962)
		(width 0.10795)
		(layer "F.Cu")
		(net "BMC_STRAP_BIT27")
	)
	(segment
		(start 423.037 -45.9994)
		(end 423.037 -46.685454)
		(width 0.10795)
		(layer "F.Cu")
		(net "BMC_STRAP_BIT27")
	)
	(segment
		(start 421.49014 -42.534586)
		(end 421.884602 -42.929048)
		(width 0.10795)
		(layer "F.Cu")
		(net "BMC_STRAP_BIT27")
	)
	(segment
		(start 421.884602 -43.995086)
		(end 423.2402 -45.350684)
		(width 0.10795)
		(layer "F.Cu")
		(net "BMC_STRAP_BIT27")
	)
	(segment
		(start 423.767758 -47.05223)
		(end 423.803826 -47.088298)
		(width 0.10795)
		(layer "F.Cu")
		(net "BMC_STRAP_BIT27")
	)
	(segment
		(start 423.506646 -47.925736)
		(end 423.506646 -48.079152)
		(width 0.10795)
		(layer "F.Cu")
		(net "BMC_STRAP_BIT27")
	)
	(segment
		(start 423.403776 -47.05223)
		(end 423.767758 -47.05223)
		(width 0.10795)
		(layer "F.Cu")
		(net "BMC_STRAP_BIT27")
	)
	(segment
		(start 423.803826 -47.628556)
		(end 423.506646 -47.925736)
		(width 0.10795)
		(layer "F.Cu")
		(net "BMC_STRAP_BIT27")
	)
	(segment
		(start 421.884602 -42.929048)
		(end 421.884602 -43.995086)
		(width 0.10795)
		(layer "F.Cu")
		(net "BMC_STRAP_BIT27")
	)
	(segment
		(start 423.2402 -45.7962)
		(end 423.037 -45.9994)
		(width 0.10795)
		(layer "F.Cu")
		(net "BMC_STRAP_BIT27")
	)
	(segment
		(start 423.803826 -47.088298)
		(end 423.803826 -47.628556)
		(width 0.10795)
		(layer "F.Cu")
		(net "BMC_STRAP_BIT27")
	)
	(segment
		(start 423.037 -46.685454)
		(end 423.403776 -47.05223)
		(width 0.10795)
		(layer "F.Cu")
		(net "BMC_STRAP_BIT27")
	)
	(via
		(at 423.803826 -47.088298)
		(size 0.762)
		(drill 0.381)
		(layers "F.Cu" "B.Cu")
		(net "BMC_STRAP_BIT27")
	)
	(segment
		(start 421.6908 -46.634654)
		(end 421.6908 -47.387002)
		(width 0.10795)
		(layer "F.Cu")
		(net "BMC_STRAP_BIT20")
	)
	(segment
		(start 421.627046 -47.450756)
		(end 421.627046 -48.079152)
		(width 0.10795)
		(layer "F.Cu")
		(net "BMC_STRAP_BIT20")
	)
	(segment
		(start 420.69004 -43.334686)
		(end 420.75989 -43.404536)
		(width 0.10795)
		(layer "F.Cu")
		(net "BMC_STRAP_BIT20")
	)
	(segment
		(start 421.259 -46.202854)
		(end 421.6908 -46.634654)
		(width 0.10795)
		(layer "F.Cu")
		(net "BMC_STRAP_BIT20")
	)
	(segment
		(start 420.75989 -43.404536)
		(end 420.75989 -44.8437)
		(width 0.10795)
		(layer "F.Cu")
		(net "BMC_STRAP_BIT20")
	)
	(segment
		(start 421.259 -45.34281)
		(end 421.259 -45.654468)
		(width 0.10795)
		(layer "F.Cu")
		(net "BMC_STRAP_BIT20")
	)
	(segment
		(start 420.75989 -44.8437)
		(end 421.259 -45.34281)
		(width 0.10795)
		(layer "F.Cu")
		(net "BMC_STRAP_BIT20")
	)
	(segment
		(start 421.259 -45.654468)
		(end 421.259 -46.202854)
		(width 0.10795)
		(layer "F.Cu")
		(net "BMC_STRAP_BIT20")
	)
	(segment
		(start 421.6908 -47.387002)
		(end 421.627046 -47.450756)
		(width 0.10795)
		(layer "F.Cu")
		(net "BMC_STRAP_BIT20")
	)
	(via
		(at 421.259 -45.654468)
		(size 0.508)
		(drill 0.254)
		(layers "F.Cu" "B.Cu")
		(net "BMC_STRAP_BIT20")
	)
	(segment
		(start 422.9862 -45.43806)
		(end 422.9862 -45.7454)
		(width 0.10795)
		(layer "F.Cu")
		(net "BMC_STRAP_BIT18")
	)
	(segment
		(start 422.744646 -47.224442)
		(end 422.744646 -48.079152)
		(width 0.10795)
		(layer "F.Cu")
		(net "BMC_STRAP_BIT18")
	)
	(segment
		(start 422.9862 -45.7454)
		(end 422.512236 -46.219364)
		(width 0.10795)
		(layer "F.Cu")
		(net "BMC_STRAP_BIT18")
	)
	(segment
		(start 422.512236 -46.219364)
		(end 422.512236 -46.992032)
		(width 0.10795)
		(layer "F.Cu")
		(net "BMC_STRAP_BIT18")
	)
	(segment
		(start 422.512236 -46.992032)
		(end 422.744646 -47.224442)
		(width 0.10795)
		(layer "F.Cu")
		(net "BMC_STRAP_BIT18")
	)
	(segment
		(start 421.49014 -43.334686)
		(end 421.49014 -43.942)
		(width 0.10795)
		(layer "F.Cu")
		(net "BMC_STRAP_BIT18")
	)
	(segment
		(start 421.49014 -43.942)
		(end 422.9862 -45.43806)
		(width 0.10795)
		(layer "F.Cu")
		(net "BMC_STRAP_BIT18")
	)
	(via
		(at 422.512236 -46.992032)
		(size 0.762)
		(drill 0.381)
		(layers "F.Cu" "B.Cu")
		(net "BMC_STRAP_BIT18")
	)
	(segment
		(start 419.543992 -42.880788)
		(end 419.890194 -42.534586)
		(width 0.10795)
		(layer "F.Cu")
		(net "BMC_STRAP_BIT17")
	)
	(segment
		(start 419.9382 -47.914306)
		(end 420.103046 -48.079152)
		(width 0.10795)
		(layer "F.Cu")
		(net "BMC_STRAP_BIT17")
	)
	(segment
		(start 419.80231 -46.178216)
		(end 419.80231 -44.91736)
		(width 0.10795)
		(layer "F.Cu")
		(net "BMC_STRAP_BIT17")
	)
	(segment
		(start 419.9382 -47.464726)
		(end 419.9382 -47.914306)
		(width 0.10795)
		(layer "F.Cu")
		(net "BMC_STRAP_BIT17")
	)
	(segment
		(start 419.663372 -46.317154)
		(end 419.80231 -46.178216)
		(width 0.10795)
		(layer "F.Cu")
		(net "BMC_STRAP_BIT17")
	)
	(segment
		(start 419.663372 -47.189898)
		(end 419.9382 -47.464726)
		(width 0.10795)
		(layer "F.Cu")
		(net "BMC_STRAP_BIT17")
	)
	(segment
		(start 419.80231 -44.91736)
		(end 419.543992 -44.659042)
		(width 0.10795)
		(layer "F.Cu")
		(net "BMC_STRAP_BIT17")
	)
	(segment
		(start 419.663372 -46.317154)
		(end 419.663372 -47.189898)
		(width 0.10795)
		(layer "F.Cu")
		(net "BMC_STRAP_BIT17")
	)
	(segment
		(start 419.543992 -44.659042)
		(end 419.543992 -42.880788)
		(width 0.10795)
		(layer "F.Cu")
		(net "BMC_STRAP_BIT17")
	)
	(via
		(at 419.663372 -46.317154)
		(size 0.762)
		(drill 0.381)
		(layers "F.Cu" "B.Cu")
		(net "BMC_STRAP_BIT17")
	)
	(segment
		(start 418.67328 -43.86326)
		(end 418.67328 -43.7515)
		(width 0.10795)
		(layer "F.Cu")
		(net "BMC_SELF_HW_RST")
	)
	(segment
		(start 418.67328 -43.7515)
		(end 419.090094 -43.334686)
		(width 0.10795)
		(layer "F.Cu")
		(net "BMC_SELF_HW_RST")
	)
	(via
		(at 418.67328 -43.86326)
		(size 0.4572)
		(drill 0.2032)
		(layers "F.Cu" "B.Cu")
		(net "BMC_SELF_HW_RST")
	)
	(via
		(at 454.6854 -39.116)
		(size 0.508)
		(drill 0.254)
		(layers "F.Cu" "B.Cu")
		(net "BMC_SELF_HW_RST")
	)
	(segment
		(start 459.480666 -37.630608)
		(end 459.480666 -37.130736)
		(width 0.10795)
		(layer "B.Cu")
		(net "BMC_SELF_HW_RST")
	)
	(segment
		(start 455.695812 -25.769062)
		(end 455.695812 -20.001484)
		(width 0.10795)
		(layer "B.Cu")
		(net "BMC_SELF_HW_RST")
	)
	(segment
		(start 458.181202 -29.810202)
		(end 457.709524 -29.810202)
		(width 0.10795)
		(layer "B.Cu")
		(net "BMC_SELF_HW_RST")
	)
	(segment
		(start 458.669898 -33.099502)
		(end 459.29804 -33.099502)
		(width 0.10795)
		(layer "B.Cu")
		(net "BMC_SELF_HW_RST")
	)
	(segment
		(start 459.567788 -31.882588)
		(end 459.697074 -31.753302)
		(width 0.10795)
		(layer "B.Cu")
		(net "BMC_SELF_HW_RST")
	)
	(segment
		(start 454.186798 -17.307306)
		(end 453.809608 -16.930116)
		(width 0.10795)
		(layer "B.Cu")
		(net "BMC_SELF_HW_RST")
	)
	(segment
		(start 458.830934 -35.743134)
		(end 458.054202 -34.966402)
		(width 0.10795)
		(layer "B.Cu")
		(net "BMC_SELF_HW_RST")
	)
	(segment
		(start 452.569072 -16.467328)
		(end 452.569072 -15.698216)
		(width 0.10795)
		(layer "B.Cu")
		(net "BMC_SELF_HW_RST")
	)
	(segment
		(start 455.32929 -27.429968)
		(end 455.32929 -26.135584)
		(width 0.10795)
		(layer "B.Cu")
		(net "BMC_SELF_HW_RST")
	)
	(segment
		(start 453.809608 -16.930116)
		(end 453.03186 -16.930116)
		(width 0.10795)
		(layer "B.Cu")
		(net "BMC_SELF_HW_RST")
	)
	(segment
		(start 459.697074 -31.326074)
		(end 458.181202 -29.810202)
		(width 0.10795)
		(layer "B.Cu")
		(net "BMC_SELF_HW_RST")
	)
	(segment
		(start 458.054202 -34.966402)
		(end 458.054202 -33.715198)
		(width 0.10795)
		(layer "B.Cu")
		(net "BMC_SELF_HW_RST")
	)
	(segment
		(start 450.167756 -15.84833)
		(end 449.231512 -15.84833)
		(width 0.10795)
		(layer "B.Cu")
		(net "BMC_SELF_HW_RST")
	)
	(segment
		(start 457.709524 -29.810202)
		(end 455.32929 -27.429968)
		(width 0.10795)
		(layer "B.Cu")
		(net "BMC_SELF_HW_RST")
	)
	(segment
		(start 458.054202 -33.715198)
		(end 458.669898 -33.099502)
		(width 0.10795)
		(layer "B.Cu")
		(net "BMC_SELF_HW_RST")
	)
	(segment
		(start 456.3364 -39.116)
		(end 457.320904 -38.131496)
		(width 0.10795)
		(layer "B.Cu")
		(net "BMC_SELF_HW_RST")
	)
	(segment
		(start 455.32929 -26.135584)
		(end 455.695812 -25.769062)
		(width 0.10795)
		(layer "B.Cu")
		(net "BMC_SELF_HW_RST")
	)
	(segment
		(start 459.480666 -37.130736)
		(end 458.830934 -36.481004)
		(width 0.10795)
		(layer "B.Cu")
		(net "BMC_SELF_HW_RST")
	)
	(segment
		(start 458.979778 -38.131496)
		(end 459.480666 -37.630608)
		(width 0.10795)
		(layer "B.Cu")
		(net "BMC_SELF_HW_RST")
	)
	(segment
		(start 454.186798 -18.49247)
		(end 454.186798 -17.307306)
		(width 0.10795)
		(layer "B.Cu")
		(net "BMC_SELF_HW_RST")
	)
	(segment
		(start 459.567788 -32.829754)
		(end 459.567788 -31.882588)
		(width 0.10795)
		(layer "B.Cu")
		(net "BMC_SELF_HW_RST")
	)
	(segment
		(start 457.320904 -38.131496)
		(end 458.979778 -38.131496)
		(width 0.10795)
		(layer "B.Cu")
		(net "BMC_SELF_HW_RST")
	)
	(segment
		(start 453.03186 -16.930116)
		(end 452.569072 -16.467328)
		(width 0.10795)
		(layer "B.Cu")
		(net "BMC_SELF_HW_RST")
	)
	(segment
		(start 459.697074 -31.753302)
		(end 459.697074 -31.326074)
		(width 0.10795)
		(layer "B.Cu")
		(net "BMC_SELF_HW_RST")
	)
	(segment
		(start 452.569072 -15.698216)
		(end 452.250556 -15.3797)
		(width 0.10795)
		(layer "B.Cu")
		(net "BMC_SELF_HW_RST")
	)
	(segment
		(start 459.29804 -33.099502)
		(end 459.567788 -32.829754)
		(width 0.10795)
		(layer "B.Cu")
		(net "BMC_SELF_HW_RST")
	)
	(segment
		(start 454.6854 -39.116)
		(end 456.3364 -39.116)
		(width 0.10795)
		(layer "B.Cu")
		(net "BMC_SELF_HW_RST")
	)
	(segment
		(start 458.830934 -36.481004)
		(end 458.830934 -35.743134)
		(width 0.10795)
		(layer "B.Cu")
		(net "BMC_SELF_HW_RST")
	)
	(segment
		(start 455.695812 -20.001484)
		(end 454.186798 -18.49247)
		(width 0.10795)
		(layer "B.Cu")
		(net "BMC_SELF_HW_RST")
	)
	(segment
		(start 450.636386 -15.3797)
		(end 450.167756 -15.84833)
		(width 0.10795)
		(layer "B.Cu")
		(net "BMC_SELF_HW_RST")
	)
	(segment
		(start 452.250556 -15.3797)
		(end 450.636386 -15.3797)
		(width 0.10795)
		(layer "B.Cu")
		(net "BMC_SELF_HW_RST")
	)
	(segment
		(start 423.716958 -45.058076)
		(end 423.990516 -45.331634)
		(width 0.089408)
		(layer "In9.Cu")
		(net "BMC_SELF_HW_RST")
	)
	(segment
		(start 428.680372 -42.493184)
		(end 428.791878 -42.381678)
		(width 0.089408)
		(layer "In9.Cu")
		(net "BMC_SELF_HW_RST")
	)
	(segment
		(start 428.378874 -42.794682)
		(end 428.378874 -42.742358)
		(width 0.089408)
		(layer "In9.Cu")
		(net "BMC_SELF_HW_RST")
	)
	(segment
		(start 419.119812 -44.309792)
		(end 422.512236 -44.309792)
		(width 0.089408)
		(layer "In9.Cu")
		(net "BMC_SELF_HW_RST")
	)
	(segment
		(start 435.429406 -41.316402)
		(end 448.360038 -41.316402)
		(width 0.089408)
		(layer "In9.Cu")
		(net "BMC_SELF_HW_RST")
	)
	(segment
		(start 427.013624 -44.159932)
		(end 428.378874 -42.794682)
		(width 0.089408)
		(layer "In9.Cu")
		(net "BMC_SELF_HW_RST")
	)
	(segment
		(start 434.36413 -42.381678)
		(end 435.429406 -41.316402)
		(width 0.089408)
		(layer "In9.Cu")
		(net "BMC_SELF_HW_RST")
	)
	(segment
		(start 428.628048 -42.493184)
		(end 428.680372 -42.493184)
		(width 0.089408)
		(layer "In9.Cu")
		(net "BMC_SELF_HW_RST")
	)
	(segment
		(start 422.512236 -44.309792)
		(end 423.26052 -45.058076)
		(width 0.089408)
		(layer "In9.Cu")
		(net "BMC_SELF_HW_RST")
	)
	(segment
		(start 423.990516 -45.331634)
		(end 425.687998 -45.331634)
		(width 0.089408)
		(layer "In9.Cu")
		(net "BMC_SELF_HW_RST")
	)
	(segment
		(start 449.219574 -41.302178)
		(end 450.392546 -40.129206)
		(width 0.089408)
		(layer "In9.Cu")
		(net "BMC_SELF_HW_RST")
	)
	(segment
		(start 448.374262 -41.302178)
		(end 449.219574 -41.302178)
		(width 0.089408)
		(layer "In9.Cu")
		(net "BMC_SELF_HW_RST")
	)
	(segment
		(start 453.694546 -38.125146)
		(end 454.6854 -39.116)
		(width 0.089408)
		(layer "In9.Cu")
		(net "BMC_SELF_HW_RST")
	)
	(segment
		(start 451.097904 -38.125146)
		(end 453.694546 -38.125146)
		(width 0.089408)
		(layer "In9.Cu")
		(net "BMC_SELF_HW_RST")
	)
	(segment
		(start 450.392546 -38.830504)
		(end 451.097904 -38.125146)
		(width 0.089408)
		(layer "In9.Cu")
		(net "BMC_SELF_HW_RST")
	)
	(segment
		(start 428.791878 -42.381678)
		(end 434.36413 -42.381678)
		(width 0.089408)
		(layer "In9.Cu")
		(net "BMC_SELF_HW_RST")
	)
	(segment
		(start 423.26052 -45.058076)
		(end 423.716958 -45.058076)
		(width 0.089408)
		(layer "In9.Cu")
		(net "BMC_SELF_HW_RST")
	)
	(segment
		(start 448.360038 -41.316402)
		(end 448.374262 -41.302178)
		(width 0.089408)
		(layer "In9.Cu")
		(net "BMC_SELF_HW_RST")
	)
	(segment
		(start 426.8597 -44.159932)
		(end 427.013624 -44.159932)
		(width 0.089408)
		(layer "In9.Cu")
		(net "BMC_SELF_HW_RST")
	)
	(segment
		(start 425.687998 -45.331634)
		(end 426.8597 -44.159932)
		(width 0.089408)
		(layer "In9.Cu")
		(net "BMC_SELF_HW_RST")
	)
	(segment
		(start 450.392546 -40.129206)
		(end 450.392546 -38.830504)
		(width 0.089408)
		(layer "In9.Cu")
		(net "BMC_SELF_HW_RST")
	)
	(segment
		(start 428.378874 -42.742358)
		(end 428.628048 -42.493184)
		(width 0.089408)
		(layer "In9.Cu")
		(net "BMC_SELF_HW_RST")
	)
	(segment
		(start 418.67328 -43.86326)
		(end 419.119812 -44.309792)
		(width 0.089408)
		(layer "In9.Cu")
		(net "BMC_SELF_HW_RST")
	)
	(segment
		(start 388.645654 -33.698434)
		(end 388.8232 -33.520888)
		(width 0.1016)
		(layer "F.Cu")
		(net "RST_PCIE_M2_DEV_IC_N")
	)
	(segment
		(start 384.33756 -81.79054)
		(end 383.790698 -82.337402)
		(width 0.10795)
		(layer "F.Cu")
		(net "RST_PCIE_M2_DEV_IC_N")
	)
	(segment
		(start 388.8232 -33.520888)
		(end 390.347454 -33.520888)
		(width 0.1016)
		(layer "F.Cu")
		(net "RST_PCIE_M2_DEV_IC_N")
	)
	(segment
		(start 384.5814 -81.735168)
		(end 384.526028 -81.79054)
		(width 0.10795)
		(layer "F.Cu")
		(net "RST_PCIE_M2_DEV_IC_N")
	)
	(segment
		(start 383.790698 -82.337402)
		(end 383.790698 -82.719926)
		(width 0.10795)
		(layer "F.Cu")
		(net "RST_PCIE_M2_DEV_IC_N")
	)
	(segment
		(start 384.526028 -81.79054)
		(end 384.33756 -81.79054)
		(width 0.10795)
		(layer "F.Cu")
		(net "RST_PCIE_M2_DEV_IC_N")
	)
	(via
		(at 388.645654 -33.698434)
		(size 0.508)
		(drill 0.254)
		(layers "F.Cu" "B.Cu")
		(net "RST_PCIE_M2_DEV_IC_N")
	)
	(via
		(at 384.5814 -81.735168)
		(size 0.508)
		(drill 0.254)
		(layers "F.Cu" "B.Cu")
		(net "RST_PCIE_M2_DEV_IC_N")
	)
	(via
		(at 382.911096 -55.5244)
		(size 0.508)
		(drill 0.254)
		(layers "F.Cu" "B.Cu")
		(net "RST_PCIE_M2_DEV_IC_N")
	)
	(segment
		(start 382.802384 -55.415688)
		(end 382.911096 -55.5244)
		(width 0.089408)
		(layer "In2.Cu")
		(net "RST_PCIE_M2_DEV_IC_N")
	)
	(segment
		(start 382.991614 -46.902624)
		(end 382.991614 -50.818288)
		(width 0.089408)
		(layer "In2.Cu")
		(net "RST_PCIE_M2_DEV_IC_N")
	)
	(segment
		(start 389.513318 -34.915094)
		(end 386.157216 -38.271196)
		(width 0.089408)
		(layer "In2.Cu")
		(net "RST_PCIE_M2_DEV_IC_N")
	)
	(segment
		(start 386.157216 -38.271196)
		(end 386.157216 -39.1414)
		(width 0.089408)
		(layer "In2.Cu")
		(net "RST_PCIE_M2_DEV_IC_N")
	)
	(segment
		(start 385.174998 -44.71924)
		(end 382.991614 -46.902624)
		(width 0.089408)
		(layer "In2.Cu")
		(net "RST_PCIE_M2_DEV_IC_N")
	)
	(segment
		(start 382.992122 -50.818796)
		(end 382.992122 -51.746912)
		(width 0.089408)
		(layer "In2.Cu")
		(net "RST_PCIE_M2_DEV_IC_N")
	)
	(segment
		(start 382.992122 -51.746912)
		(end 382.802384 -51.93665)
		(width 0.089408)
		(layer "In2.Cu")
		(net "RST_PCIE_M2_DEV_IC_N")
	)
	(segment
		(start 382.991614 -50.818288)
		(end 382.992122 -50.818796)
		(width 0.089408)
		(layer "In2.Cu")
		(net "RST_PCIE_M2_DEV_IC_N")
	)
	(segment
		(start 389.513318 -34.015172)
		(end 389.513318 -34.915094)
		(width 0.089408)
		(layer "In2.Cu")
		(net "RST_PCIE_M2_DEV_IC_N")
	)
	(segment
		(start 385.174998 -40.123618)
		(end 385.174998 -44.71924)
		(width 0.089408)
		(layer "In2.Cu")
		(net "RST_PCIE_M2_DEV_IC_N")
	)
	(segment
		(start 382.802384 -51.93665)
		(end 382.802384 -55.415688)
		(width 0.089408)
		(layer "In2.Cu")
		(net "RST_PCIE_M2_DEV_IC_N")
	)
	(segment
		(start 386.157216 -39.1414)
		(end 385.174998 -40.123618)
		(width 0.089408)
		(layer "In2.Cu")
		(net "RST_PCIE_M2_DEV_IC_N")
	)
	(segment
		(start 388.645654 -33.698434)
		(end 389.19658 -33.698434)
		(width 0.089408)
		(layer "In2.Cu")
		(net "RST_PCIE_M2_DEV_IC_N")
	)
	(segment
		(start 389.19658 -33.698434)
		(end 389.513318 -34.015172)
		(width 0.089408)
		(layer "In2.Cu")
		(net "RST_PCIE_M2_DEV_IC_N")
	)
	(segment
		(start 384.5814 -81.735168)
		(end 384.5814 -80.76184)
		(width 0.089408)
		(layer "In11.Cu")
		(net "RST_PCIE_M2_DEV_IC_N")
	)
	(segment
		(start 384.007868 -70.6628)
		(end 384.007868 -65.435734)
		(width 0.089408)
		(layer "In11.Cu")
		(net "RST_PCIE_M2_DEV_IC_N")
	)
	(segment
		(start 382.726184 -64.15405)
		(end 382.726184 -61.523118)
		(width 0.089408)
		(layer "In11.Cu")
		(net "RST_PCIE_M2_DEV_IC_N")
	)
	(segment
		(start 384.5814 -80.76184)
		(end 385.739132 -79.604108)
		(width 0.089408)
		(layer "In11.Cu")
		(net "RST_PCIE_M2_DEV_IC_N")
	)
	(segment
		(start 385.738624 -74.205084)
		(end 385.738878 -74.20483)
		(width 0.089408)
		(layer "In11.Cu")
		(net "RST_PCIE_M2_DEV_IC_N")
	)
	(segment
		(start 385.739132 -79.604108)
		(end 385.739132 -74.7776)
		(width 0.089408)
		(layer "In11.Cu")
		(net "RST_PCIE_M2_DEV_IC_N")
	)
	(segment
		(start 385.738878 -73.888346)
		(end 384.969766 -73.119234)
		(width 0.089408)
		(layer "In11.Cu")
		(net "RST_PCIE_M2_DEV_IC_N")
	)
	(segment
		(start 384.007868 -65.435734)
		(end 382.726184 -64.15405)
		(width 0.089408)
		(layer "In11.Cu")
		(net "RST_PCIE_M2_DEV_IC_N")
	)
	(segment
		(start 384.969766 -72.833738)
		(end 383.69875 -71.562722)
		(width 0.089408)
		(layer "In11.Cu")
		(net "RST_PCIE_M2_DEV_IC_N")
	)
	(segment
		(start 383.2987 -60.950602)
		(end 383.2987 -55.912004)
		(width 0.089408)
		(layer "In11.Cu")
		(net "RST_PCIE_M2_DEV_IC_N")
	)
	(segment
		(start 384.969766 -73.119234)
		(end 384.969766 -72.833738)
		(width 0.089408)
		(layer "In11.Cu")
		(net "RST_PCIE_M2_DEV_IC_N")
	)
	(segment
		(start 385.739132 -74.7776)
		(end 385.738624 -74.777092)
		(width 0.089408)
		(layer "In11.Cu")
		(net "RST_PCIE_M2_DEV_IC_N")
	)
	(segment
		(start 383.69875 -70.971918)
		(end 384.007868 -70.6628)
		(width 0.089408)
		(layer "In11.Cu")
		(net "RST_PCIE_M2_DEV_IC_N")
	)
	(segment
		(start 383.69875 -71.562722)
		(end 383.69875 -70.971918)
		(width 0.089408)
		(layer "In11.Cu")
		(net "RST_PCIE_M2_DEV_IC_N")
	)
	(segment
		(start 385.738624 -74.777092)
		(end 385.738624 -74.205084)
		(width 0.089408)
		(layer "In11.Cu")
		(net "RST_PCIE_M2_DEV_IC_N")
	)
	(segment
		(start 385.738878 -74.20483)
		(end 385.738878 -73.888346)
		(width 0.089408)
		(layer "In11.Cu")
		(net "RST_PCIE_M2_DEV_IC_N")
	)
	(segment
		(start 383.2987 -55.912004)
		(end 382.911096 -55.5244)
		(width 0.089408)
		(layer "In11.Cu")
		(net "RST_PCIE_M2_DEV_IC_N")
	)
	(segment
		(start 382.726184 -61.523118)
		(end 383.2987 -60.950602)
		(width 0.089408)
		(layer "In11.Cu")
		(net "RST_PCIE_M2_DEV_IC_N")
	)
	(segment
		(start 384.391154 -80.6069)
		(end 384.737864 -80.6069)
		(width 0.1016)
		(layer "F.Cu")
		(net "RST_PCIE_M2_DEV_AND")
	)
	(segment
		(start 384.737864 -80.6069)
		(end 385.344924 -79.99984)
		(width 0.1016)
		(layer "F.Cu")
		(net "RST_PCIE_M2_DEV_AND")
	)
	(segment
		(start 383.140712 -80.941926)
		(end 383.140712 -80.367886)
		(width 0.1016)
		(layer "F.Cu")
		(net "RST_PCIE_M2_DEV_AND")
	)
	(segment
		(start 384.050286 -80.266032)
		(end 384.391154 -80.6069)
		(width 0.1016)
		(layer "F.Cu")
		(net "RST_PCIE_M2_DEV_AND")
	)
	(segment
		(start 385.89712 -80.25892)
		(end 387.003544 -80.25892)
		(width 0.1016)
		(layer "F.Cu")
		(net "RST_PCIE_M2_DEV_AND")
	)
	(segment
		(start 383.140712 -80.367886)
		(end 383.242566 -80.266032)
		(width 0.1016)
		(layer "F.Cu")
		(net "RST_PCIE_M2_DEV_AND")
	)
	(segment
		(start 383.242566 -80.266032)
		(end 384.050286 -80.266032)
		(width 0.1016)
		(layer "F.Cu")
		(net "RST_PCIE_M2_DEV_AND")
	)
	(segment
		(start 385.344924 -79.99984)
		(end 385.63804 -79.99984)
		(width 0.1016)
		(layer "F.Cu")
		(net "RST_PCIE_M2_DEV_AND")
	)
	(segment
		(start 388.242302 -81.497678)
		(end 388.242302 -81.923636)
		(width 0.1016)
		(layer "F.Cu")
		(net "RST_PCIE_M2_DEV_AND")
	)
	(segment
		(start 387.003544 -80.25892)
		(end 388.242302 -81.497678)
		(width 0.1016)
		(layer "F.Cu")
		(net "RST_PCIE_M2_DEV_AND")
	)
	(segment
		(start 385.63804 -79.99984)
		(end 385.89712 -80.25892)
		(width 0.1016)
		(layer "F.Cu")
		(net "RST_PCIE_M2_DEV_AND")
	)
	(segment
		(start 471.17 -42.4434)
		(end 471.077798 -42.351198)
		(width 0.1016)
		(layer "F.Cu")
		(net "PWRGD_P2V5_BMC_STBY")
	)
	(segment
		(start 471.5891 -43.0784)
		(end 471.5891 -42.8625)
		(width 0.1016)
		(layer "F.Cu")
		(net "PWRGD_P2V5_BMC_STBY")
	)
	(segment
		(start 446.88506 -18.70456)
		(end 447.548 -19.3675)
		(width 0.1016)
		(layer "F.Cu")
		(net "PWRGD_P2V5_BMC_STBY")
	)
	(segment
		(start 446.531492 -18.703798)
		(end 446.532 -18.703798)
		(width 0.1016)
		(layer "F.Cu")
		(net "PWRGD_P2V5_BMC_STBY")
	)
	(segment
		(start 471.077798 -42.351198)
		(end 471.077798 -41.059608)
		(width 0.1016)
		(layer "F.Cu")
		(net "PWRGD_P2V5_BMC_STBY")
	)
	(segment
		(start 446.532 -18.703798)
		(end 446.532 -18.70456)
		(width 0.1016)
		(layer "F.Cu")
		(net "PWRGD_P2V5_BMC_STBY")
	)
	(segment
		(start 471.5891 -42.8625)
		(end 471.17 -42.4434)
		(width 0.1016)
		(layer "F.Cu")
		(net "PWRGD_P2V5_BMC_STBY")
	)
	(segment
		(start 446.532 -18.70456)
		(end 446.88506 -18.70456)
		(width 0.1016)
		(layer "F.Cu")
		(net "PWRGD_P2V5_BMC_STBY")
	)
	(via
		(at 471.17 -42.4434)
		(size 0.508)
		(drill 0.254)
		(layers "F.Cu" "B.Cu")
		(net "PWRGD_P2V5_BMC_STBY")
	)
	(via
		(at 470.742518 -27.482038)
		(size 0.508)
		(drill 0.254)
		(layers "F.Cu" "B.Cu")
		(net "PWRGD_P2V5_BMC_STBY")
	)
	(via
		(at 446.531492 -18.703798)
		(size 0.508)
		(drill 0.254)
		(layers "F.Cu" "B.Cu")
		(net "PWRGD_P2V5_BMC_STBY")
	)
	(segment
		(start 463.86623 -23.40483)
		(end 461.39354 -20.93214)
		(width 0.0889)
		(layer "In2.Cu")
		(net "PWRGD_P2V5_BMC_STBY")
	)
	(segment
		(start 446.54724 -18.719546)
		(end 446.531492 -18.703798)
		(width 0.0889)
		(layer "In2.Cu")
		(net "PWRGD_P2V5_BMC_STBY")
	)
	(segment
		(start 456.547728 -21.96338)
		(end 453.303894 -18.719546)
		(width 0.0889)
		(layer "In2.Cu")
		(net "PWRGD_P2V5_BMC_STBY")
	)
	(segment
		(start 461.39354 -20.93214)
		(end 458.821536 -20.93214)
		(width 0.0889)
		(layer "In2.Cu")
		(net "PWRGD_P2V5_BMC_STBY")
	)
	(segment
		(start 458.821536 -20.93214)
		(end 457.790296 -21.96338)
		(width 0.0889)
		(layer "In2.Cu")
		(net "PWRGD_P2V5_BMC_STBY")
	)
	(segment
		(start 453.303894 -18.719546)
		(end 446.54724 -18.719546)
		(width 0.0889)
		(layer "In2.Cu")
		(net "PWRGD_P2V5_BMC_STBY")
	)
	(segment
		(start 470.742518 -27.482038)
		(end 470.135204 -27.482038)
		(width 0.089408)
		(layer "In2.Cu")
		(net "PWRGD_P2V5_BMC_STBY")
	)
	(segment
		(start 470.135204 -27.482038)
		(end 468.948262 -26.295096)
		(width 0.089408)
		(layer "In2.Cu")
		(net "PWRGD_P2V5_BMC_STBY")
	)
	(segment
		(start 465.597494 -23.40483)
		(end 463.86623 -23.40483)
		(width 0.0889)
		(layer "In2.Cu")
		(net "PWRGD_P2V5_BMC_STBY")
	)
	(segment
		(start 457.790296 -21.96338)
		(end 456.547728 -21.96338)
		(width 0.0889)
		(layer "In2.Cu")
		(net "PWRGD_P2V5_BMC_STBY")
	)
	(segment
		(start 468.948262 -26.295096)
		(end 468.48776 -26.295096)
		(width 0.089408)
		(layer "In2.Cu")
		(net "PWRGD_P2V5_BMC_STBY")
	)
	(segment
		(start 468.48776 -26.295096)
		(end 465.597494 -23.40483)
		(width 0.089408)
		(layer "In2.Cu")
		(net "PWRGD_P2V5_BMC_STBY")
	)
	(segment
		(start 472.261438 -27.88412)
		(end 471.859356 -27.482038)
		(width 0.0889)
		(layer "In9.Cu")
		(net "PWRGD_P2V5_BMC_STBY")
	)
	(segment
		(start 470.684352 -38.909498)
		(end 470.684606 -38.909244)
		(width 0.0889)
		(layer "In9.Cu")
		(net "PWRGD_P2V5_BMC_STBY")
	)
	(segment
		(start 470.183718 -35.639248)
		(end 470.028778 -35.484308)
		(width 0.0889)
		(layer "In9.Cu")
		(net "PWRGD_P2V5_BMC_STBY")
	)
	(segment
		(start 470.684352 -40.773858)
		(end 470.684352 -38.909498)
		(width 0.0889)
		(layer "In9.Cu")
		(net "PWRGD_P2V5_BMC_STBY")
	)
	(segment
		(start 470.028778 -31.75762)
		(end 472.261438 -29.52496)
		(width 0.0889)
		(layer "In9.Cu")
		(net "PWRGD_P2V5_BMC_STBY")
	)
	(segment
		(start 471.17 -42.4434)
		(end 471.055446 -42.328846)
		(width 0.0889)
		(layer "In9.Cu")
		(net "PWRGD_P2V5_BMC_STBY")
	)
	(segment
		(start 470.028778 -35.484308)
		(end 470.028778 -31.75762)
		(width 0.0889)
		(layer "In9.Cu")
		(net "PWRGD_P2V5_BMC_STBY")
	)
	(segment
		(start 472.261438 -29.52496)
		(end 472.261438 -27.88412)
		(width 0.0889)
		(layer "In9.Cu")
		(net "PWRGD_P2V5_BMC_STBY")
	)
	(segment
		(start 471.859356 -27.482038)
		(end 470.742518 -27.482038)
		(width 0.0889)
		(layer "In9.Cu")
		(net "PWRGD_P2V5_BMC_STBY")
	)
	(segment
		(start 471.055446 -41.144952)
		(end 470.684352 -40.773858)
		(width 0.0889)
		(layer "In9.Cu")
		(net "PWRGD_P2V5_BMC_STBY")
	)
	(segment
		(start 470.684606 -38.751256)
		(end 470.183718 -38.250368)
		(width 0.0889)
		(layer "In9.Cu")
		(net "PWRGD_P2V5_BMC_STBY")
	)
	(segment
		(start 470.183718 -38.250368)
		(end 470.183718 -35.639248)
		(width 0.0889)
		(layer "In9.Cu")
		(net "PWRGD_P2V5_BMC_STBY")
	)
	(segment
		(start 470.684606 -38.909244)
		(end 470.684606 -38.751256)
		(width 0.0889)
		(layer "In9.Cu")
		(net "PWRGD_P2V5_BMC_STBY")
	)
	(segment
		(start 471.055446 -42.328846)
		(end 471.055446 -41.144952)
		(width 0.0889)
		(layer "In9.Cu")
		(net "PWRGD_P2V5_BMC_STBY")
	)
	(segment
		(start 381.51562 -148.817076)
		(end 381.51562 -150.203916)
		(width 0.508)
		(layer "F.Cu")
		(net "VR_P1V05_PCH_STBY_PH1_SW_RC")
	)
	(segment
		(start 372.550182 -148.781262)
		(end 372.550182 -148.149564)
		(width 0.508)
		(layer "F.Cu")
		(net "VR_PVNN_PCH_PH1_PHASE_SW_RC")
	)
	(segment
		(start 372.528338 -148.12772)
		(end 372.528338 -147.450048)
		(width 0.508)
		(layer "F.Cu")
		(net "VR_PVNN_PCH_PH1_PHASE_SW_RC")
	)
	(segment
		(start 372.550182 -148.149564)
		(end 372.528338 -148.12772)
		(width 0.508)
		(layer "F.Cu")
		(net "VR_PVNN_PCH_PH1_PHASE_SW_RC")
	)
	(segment
		(start 8.033258 -13.302996)
		(end 7.605522 -13.302996)
		(width 0.508)
		(layer "F.Cu")
		(net "VR_PVDDQ_GHJ_PH2_SW_RC")
	)
	(segment
		(start 8.382254 -12.954)
		(end 8.033258 -13.302996)
		(width 0.508)
		(layer "F.Cu")
		(net "VR_PVDDQ_GHJ_PH2_SW_RC")
	)
	(segment
		(start 8.763 -12.954)
		(end 8.382254 -12.954)
		(width 0.508)
		(layer "F.Cu")
		(net "VR_PVDDQ_GHJ_PH2_SW_RC")
	)
	(segment
		(start 8.787638 -6.240018)
		(end 8.09117 -6.240018)
		(width 0.508)
		(layer "F.Cu")
		(net "VR_PVDDQ_GHJ_PH1_SW_RC")
	)
	(segment
		(start 7.582916 -5.731764)
		(end 7.582916 -5.552948)
		(width 0.508)
		(layer "F.Cu")
		(net "VR_PVDDQ_GHJ_PH1_SW_RC")
	)
	(segment
		(start 8.09117 -6.240018)
		(end 7.582916 -5.731764)
		(width 0.508)
		(layer "F.Cu")
		(net "VR_PVDDQ_GHJ_PH1_SW_RC")
	)
	(segment
		(start 343.2556 -141.224)
		(end 343.2556 -140.259816)
		(width 0.508)
		(layer "F.Cu")
		(net "VR_PVDDQ_DEF_PH2_SW_RC")
	)
	(segment
		(start 343.2556 -141.8336)
		(end 343.408 -141.986)
		(width 0.508)
		(layer "F.Cu")
		(net "VR_PVDDQ_DEF_PH2_SW_RC")
	)
	(segment
		(start 343.2556 -140.259816)
		(end 343.459308 -140.056108)
		(width 0.508)
		(layer "F.Cu")
		(net "VR_PVDDQ_DEF_PH2_SW_RC")
	)
	(segment
		(start 343.408 -141.986)
		(end 343.408 -142.3924)
		(width 0.508)
		(layer "F.Cu")
		(net "VR_PVDDQ_DEF_PH2_SW_RC")
	)
	(segment
		(start 343.2556 -141.224)
		(end 343.2556 -141.8336)
		(width 0.508)
		(layer "F.Cu")
		(net "VR_PVDDQ_DEF_PH2_SW_RC")
	)
	(via
		(at 343.459308 -140.056108)
		(size 0.762)
		(drill 0.381)
		(layers "F.Cu" "B.Cu")
		(net "VR_PVDDQ_DEF_PH2_SW_RC")
	)
	(segment
		(start 344.241628 -157.48)
		(end 343.492328 -157.48)
		(width 0.508)
		(layer "F.Cu")
		(net "VR_PVDDQ_DEF_PH1_SW_RC")
	)
	(segment
		(start 344.597228 -157.1244)
		(end 344.241628 -157.48)
		(width 0.508)
		(layer "F.Cu")
		(net "VR_PVDDQ_DEF_PH1_SW_RC")
	)
	(segment
		(start 341.87638 -2.02438)
		(end 342.29548 -2.44348)
		(width 0.4064)
		(layer "F.Cu")
		(net "VR_PVDDQ_ABC_PH2_SW_RC")
	)
	(segment
		(start 342.29548 -2.44348)
		(end 343.19464 -2.44348)
		(width 0.4064)
		(layer "F.Cu")
		(net "VR_PVDDQ_ABC_PH2_SW_RC")
	)
	(segment
		(start 341.27186 -2.02438)
		(end 341.87638 -2.02438)
		(width 0.4064)
		(layer "F.Cu")
		(net "VR_PVDDQ_ABC_PH2_SW_RC")
	)
	(segment
		(start 338.709 -10.3378)
		(end 339.663278 -10.3378)
		(width 0.508)
		(layer "F.Cu")
		(net "VR_PVDDQ_ABC_PH1_SW_RC")
	)
	(segment
		(start 339.663278 -10.3378)
		(end 339.667088 -10.34161)
		(width 0.508)
		(layer "F.Cu")
		(net "VR_PVDDQ_ABC_PH1_SW_RC")
	)
	(segment
		(start 171.123102 -57.812686)
		(end 172.239686 -57.812686)
		(width 0.508)
		(layer "F.Cu")
		(net "VR_PVCCIO_CPU1_PH1_SW_RC")
	)
	(segment
		(start 172.239686 -57.812686)
		(end 172.3644 -57.9374)
		(width 0.508)
		(layer "F.Cu")
		(net "VR_PVCCIO_CPU1_PH1_SW_RC")
	)
	(segment
		(start 343.5858 -94.107)
		(end 344.17 -93.5228)
		(width 0.508)
		(layer "F.Cu")
		(net "VR_PVCCIO_CPU0_PH1_SW_RC")
	)
	(segment
		(start 343.1032 -94.107)
		(end 343.5858 -94.107)
		(width 0.508)
		(layer "F.Cu")
		(net "VR_PVCCIO_CPU0_PH1_SW_RC")
	)
	(segment
		(start 37.060124 -93.897196)
		(end 36.62934 -93.897196)
		(width 0.508)
		(layer "F.Cu")
		(net "VR_PVSA_CPU1_PHASE_SW_RC")
	)
	(segment
		(start 37.12972 -93.8276)
		(end 37.060124 -93.897196)
		(width 0.508)
		(layer "F.Cu")
		(net "VR_PVSA_CPU1_PHASE_SW_RC")
	)
	(segment
		(start 37.51834 -93.8276)
		(end 37.12972 -93.8276)
		(width 0.508)
		(layer "F.Cu")
		(net "VR_PVSA_CPU1_PHASE_SW_RC")
	)
	(segment
		(start 37.187886 -85.6996)
		(end 38.076886 -85.6996)
		(width 0.508)
		(layer "F.Cu")
		(net "VR_PVCCIN_CPU1_PHASE5_RC")
	)
	(segment
		(start 38.2524 -77.7494)
		(end 36.7284 -77.7494)
		(width 0.508)
		(layer "F.Cu")
		(net "VR_PVCCIN_CPU1_PHASE4_RC")
	)
	(segment
		(start 38.9128 -69.3166)
		(end 37.5158 -69.3166)
		(width 0.508)
		(layer "F.Cu")
		(net "VR_PVCCIN_CPU1_PHASE3_RC")
	)
	(segment
		(start 37.316664 -61.214)
		(end 36.5506 -61.214)
		(width 0.508)
		(layer "F.Cu")
		(net "VR_PVCCIN_CPU1_PHASE2_RC")
	)
	(segment
		(start 37.440616 -61.090048)
		(end 37.316664 -61.214)
		(width 0.508)
		(layer "F.Cu")
		(net "VR_PVCCIN_CPU1_PHASE2_RC")
	)
	(segment
		(start 38.02634 -61.090048)
		(end 37.440616 -61.090048)
		(width 0.508)
		(layer "F.Cu")
		(net "VR_PVCCIN_CPU1_PHASE2_RC")
	)
	(segment
		(start 38.2016 -52.9082)
		(end 36.5506 -52.9082)
		(width 0.508)
		(layer "F.Cu")
		(net "VR_PVCCIN_CPU1_PHASE1_RC")
	)
	(segment
		(start 202.612244 -93.36024)
		(end 203.760832 -93.36024)
		(width 0.508)
		(layer "F.Cu")
		(net "VR_PVSA_CPU0_PHASE_SW_RC")
	)
	(segment
		(start 202.394566 -93.577918)
		(end 202.612244 -93.36024)
		(width 0.508)
		(layer "F.Cu")
		(net "VR_PVSA_CPU0_PHASE_SW_RC")
	)
	(segment
		(start 201.366628 -93.577918)
		(end 202.394566 -93.577918)
		(width 0.508)
		(layer "F.Cu")
		(net "VR_PVSA_CPU0_PHASE_SW_RC")
	)
	(segment
		(start 202.184 -85.4456)
		(end 203.6572 -85.4456)
		(width 0.508)
		(layer "F.Cu")
		(net "VR_PVCCIN_CPU0_PHASE5_RC")
	)
	(segment
		(start 202.63358 -77.47)
		(end 203.5302 -77.47)
		(width 0.508)
		(layer "F.Cu")
		(net "VR_PVCCIN_CPU0_PHASE4_RC")
	)
	(segment
		(start 203.454254 -69.342)
		(end 203.428346 -69.316092)
		(width 0.508)
		(layer "F.Cu")
		(net "VR_PVCCIN_CPU0_PHASE3_RC")
	)
	(segment
		(start 203.7334 -69.342)
		(end 203.454254 -69.342)
		(width 0.508)
		(layer "F.Cu")
		(net "VR_PVCCIN_CPU0_PHASE3_RC")
	)
	(segment
		(start 203.428346 -69.316092)
		(end 202.841098 -69.316092)
		(width 0.508)
		(layer "F.Cu")
		(net "VR_PVCCIN_CPU0_PHASE3_RC")
	)
	(segment
		(start 203.04379 -61.214)
		(end 203.035154 -61.205364)
		(width 0.508)
		(layer "F.Cu")
		(net "VR_PVCCIN_CPU0_PHASE2_RC")
	)
	(segment
		(start 203.9874 -61.214)
		(end 203.04379 -61.214)
		(width 0.508)
		(layer "F.Cu")
		(net "VR_PVCCIN_CPU0_PHASE2_RC")
	)
	(segment
		(start 202.158346 -52.7304)
		(end 203.1619 -52.7304)
		(width 0.508)
		(layer "F.Cu")
		(net "VR_PVCCIN_CPU0_PHASE1_RC")
	)
	(segment
		(start 451.3326 -21.9837)
		(end 450.929756 -21.9837)
		(width 0.254)
		(layer "F.Cu")
		(net "VR_P2V5_BMC_STBY_FB")
	)
	(segment
		(start 452.767192 -22.105874)
		(end 451.954646 -22.105874)
		(width 0.254)
		(layer "F.Cu")
		(net "VR_P2V5_BMC_STBY_FB")
	)
	(segment
		(start 450.929756 -21.9837)
		(end 449.998084 -22.915372)
		(width 0.254)
		(layer "F.Cu")
		(net "VR_P2V5_BMC_STBY_FB")
	)
	(segment
		(start 451.3326 -21.4884)
		(end 451.0532 -21.209)
		(width 0.254)
		(layer "F.Cu")
		(net "VR_P2V5_BMC_STBY_FB")
	)
	(segment
		(start 451.954646 -22.105874)
		(end 451.832472 -21.9837)
		(width 0.254)
		(layer "F.Cu")
		(net "VR_P2V5_BMC_STBY_FB")
	)
	(segment
		(start 451.832472 -21.9837)
		(end 451.3326 -21.9837)
		(width 0.254)
		(layer "F.Cu")
		(net "VR_P2V5_BMC_STBY_FB")
	)
	(segment
		(start 451.3326 -21.9837)
		(end 451.3326 -21.4884)
		(width 0.254)
		(layer "F.Cu")
		(net "VR_P2V5_BMC_STBY_FB")
	)
	(segment
		(start 451.0532 -21.209)
		(end 450.215 -21.209)
		(width 0.254)
		(layer "F.Cu")
		(net "VR_P2V5_BMC_STBY_FB")
	)
	(via
		(at 449.998084 -22.915372)
		(size 0.762)
		(drill 0.381)
		(layers "F.Cu" "B.Cu")
		(net "VR_P2V5_BMC_STBY_FB")
	)
	(segment
		(start 484.7082 -130.683)
		(end 483.1842 -130.683)
		(width 0.10795)
		(layer "F.Cu")
		(net "SPA_MID_DBG2_RX")
	)
	(segment
		(start 483.1842 -130.683)
		(end 482.3968 -131.4704)
		(width 0.10795)
		(layer "F.Cu")
		(net "SPA_MID_DBG2_RX")
	)
	(segment
		(start 481.17379 -133.45541)
		(end 480.75088 -133.45541)
		(width 0.10795)
		(layer "F.Cu")
		(net "SPA_MID_DBG2_RX")
	)
	(segment
		(start 482.3968 -132.2324)
		(end 481.17379 -133.45541)
		(width 0.10795)
		(layer "F.Cu")
		(net "SPA_MID_DBG2_RX")
	)
	(segment
		(start 482.3968 -131.4704)
		(end 482.3968 -132.2324)
		(width 0.10795)
		(layer "F.Cu")
		(net "SPA_MID_DBG2_RX")
	)
	(via
		(at 484.7082 -130.683)
		(size 0.508)
		(drill 0.254)
		(layers "F.Cu" "B.Cu")
		(net "SPA_MID_DBG2_RX")
	)
	(via
		(at 490.322108 -131.22656)
		(size 0.6604)
		(drill 0.3302)
		(layers "F.Cu" "B.Cu")
		(net "SPA_MID_DBG2_RX")
	)
	(segment
		(start 491.41888 -133.0706)
		(end 490.86516 -133.0706)
		(width 0.10795)
		(layer "B.Cu")
		(net "SPA_MID_DBG2_RX")
	)
	(segment
		(start 489.778548 -130.683)
		(end 484.7082 -130.683)
		(width 0.10795)
		(layer "B.Cu")
		(net "SPA_MID_DBG2_RX")
	)
	(segment
		(start 492.693198 -132.546598)
		(end 493.003586 -132.856986)
		(width 0.10795)
		(layer "B.Cu")
		(net "SPA_MID_DBG2_RX")
	)
	(segment
		(start 490.322108 -132.527548)
		(end 490.322108 -131.22656)
		(width 0.10795)
		(layer "B.Cu")
		(net "SPA_MID_DBG2_RX")
	)
	(segment
		(start 493.003586 -132.856986)
		(end 493.003586 -133.223)
		(width 0.10795)
		(layer "B.Cu")
		(net "SPA_MID_DBG2_RX")
	)
	(segment
		(start 491.54588 -133.0706)
		(end 492.069882 -132.546598)
		(width 0.10795)
		(layer "B.Cu")
		(net "SPA_MID_DBG2_RX")
	)
	(segment
		(start 491.41888 -133.0706)
		(end 491.54588 -133.0706)
		(width 0.10795)
		(layer "B.Cu")
		(net "SPA_MID_DBG2_RX")
	)
	(segment
		(start 490.322108 -131.22656)
		(end 489.778548 -130.683)
		(width 0.10795)
		(layer "B.Cu")
		(net "SPA_MID_DBG2_RX")
	)
	(segment
		(start 490.86516 -133.0706)
		(end 490.322108 -132.527548)
		(width 0.10795)
		(layer "B.Cu")
		(net "SPA_MID_DBG2_RX")
	)
	(segment
		(start 492.069882 -132.546598)
		(end 492.693198 -132.546598)
		(width 0.10795)
		(layer "B.Cu")
		(net "SPA_MID_DBG2_RX")
	)
	(segment
		(start 406.066498 -35.334702)
		(end 404.680674 -36.720526)
		(width 0.1016)
		(layer "F.Cu")
		(net "SMB_DEBUG_STBY_LVC3_SDA_R")
	)
	(segment
		(start 403.219158 -36.720526)
		(end 402.62302 -36.720526)
		(width 0.1016)
		(layer "F.Cu")
		(net "SMB_DEBUG_STBY_LVC3_SDA_R")
	)
	(segment
		(start 404.680674 -36.720526)
		(end 403.219158 -36.720526)
		(width 0.1016)
		(layer "F.Cu")
		(net "SMB_DEBUG_STBY_LVC3_SDA_R")
	)
	(segment
		(start 407.090118 -35.334702)
		(end 406.066498 -35.334702)
		(width 0.1016)
		(layer "F.Cu")
		(net "SMB_DEBUG_STBY_LVC3_SDA_R")
	)
	(segment
		(start 402.62302 -36.720526)
		(end 402.361146 -36.458652)
		(width 0.1016)
		(layer "F.Cu")
		(net "SMB_DEBUG_STBY_LVC3_SDA_R")
	)
	(via
		(at 403.219158 -36.720526)
		(size 0.508)
		(drill 0.254)
		(layers "F.Cu" "B.Cu")
		(net "SMB_DEBUG_STBY_LVC3_SDA_R")
	)
	(segment
		(start 401.472146 -36.458652)
		(end 401.044918 -36.458652)
		(width 0.1016)
		(layer "F.Cu")
		(net "SMB_DEBUG_STBY_LVC3_SDA")
	)
	(segment
		(start 400.08937 -37.4142)
		(end 400.08937 -37.413946)
		(width 0.1016)
		(layer "F.Cu")
		(net "SMB_DEBUG_STBY_LVC3_SDA")
	)
	(segment
		(start 399.796 -37.69868)
		(end 399.796 -37.973)
		(width 0.1016)
		(layer "F.Cu")
		(net "SMB_DEBUG_STBY_LVC3_SDA")
	)
	(segment
		(start 400.08937 -37.413946)
		(end 400.080734 -37.413946)
		(width 0.1016)
		(layer "F.Cu")
		(net "SMB_DEBUG_STBY_LVC3_SDA")
	)
	(segment
		(start 400.080734 -37.413946)
		(end 399.796 -37.69868)
		(width 0.1016)
		(layer "F.Cu")
		(net "SMB_DEBUG_STBY_LVC3_SDA")
	)
	(segment
		(start 401.044918 -36.458652)
		(end 400.08937 -37.4142)
		(width 0.1016)
		(layer "F.Cu")
		(net "SMB_DEBUG_STBY_LVC3_SDA")
	)
	(via
		(at 472.820238 -53.716174)
		(size 0.508)
		(drill 0.254)
		(layers "F.Cu" "B.Cu")
		(net "SMB_DEBUG_STBY_LVC3_SDA")
	)
	(via
		(at 399.796 -37.973)
		(size 0.508)
		(drill 0.254)
		(layers "F.Cu" "B.Cu")
		(net "SMB_DEBUG_STBY_LVC3_SDA")
	)
	(via
		(at 427.059344 -116.25326)
		(size 0.6604)
		(drill 0.3302)
		(layers "F.Cu" "B.Cu")
		(net "SMB_DEBUG_STBY_LVC3_SDA")
	)
	(via
		(at 427.84649 -116.692934)
		(size 0.508)
		(drill 0.254)
		(layers "F.Cu" "B.Cu")
		(net "SMB_DEBUG_STBY_LVC3_SDA")
	)
	(via
		(at 426.4914 -75.438)
		(size 0.508)
		(drill 0.254)
		(layers "F.Cu" "B.Cu")
		(net "SMB_DEBUG_STBY_LVC3_SDA")
	)
	(via
		(at 474.138752 -131.350512)
		(size 0.508)
		(drill 0.254)
		(layers "F.Cu" "B.Cu")
		(net "SMB_DEBUG_STBY_LVC3_SDA")
	)
	(segment
		(start 471.0176 -142.45209)
		(end 471.969846 -143.404336)
		(width 0.1016)
		(layer "B.Cu")
		(net "SMB_DEBUG_STBY_LVC3_SDA")
	)
	(segment
		(start 471.216228 -135.83793)
		(end 471.20302 -135.851138)
		(width 0.10795)
		(layer "B.Cu")
		(net "SMB_DEBUG_STBY_LVC3_SDA")
	)
	(segment
		(start 474.235526 -131.10083)
		(end 474.008196 -130.8735)
		(width 0.10795)
		(layer "B.Cu")
		(net "SMB_DEBUG_STBY_LVC3_SDA")
	)
	(segment
		(start 474.008196 -130.8735)
		(end 473.804234 -130.8735)
		(width 0.10795)
		(layer "B.Cu")
		(net "SMB_DEBUG_STBY_LVC3_SDA")
	)
	(segment
		(start 471.466418 -134.81558)
		(end 471.466418 -135.233918)
		(width 0.10795)
		(layer "B.Cu")
		(net "SMB_DEBUG_STBY_LVC3_SDA")
	)
	(segment
		(start 474.410278 -131.890516)
		(end 473.45473 -132.846064)
		(width 0.10795)
		(layer "B.Cu")
		(net "SMB_DEBUG_STBY_LVC3_SDA")
	)
	(segment
		(start 474.138752 -131.350512)
		(end 474.235526 -131.253738)
		(width 0.10795)
		(layer "B.Cu")
		(net "SMB_DEBUG_STBY_LVC3_SDA")
	)
	(segment
		(start 472.45905 -143.404336)
		(end 472.693746 -143.639032)
		(width 0.1016)
		(layer "B.Cu")
		(net "SMB_DEBUG_STBY_LVC3_SDA")
	)
	(segment
		(start 471.466418 -135.233918)
		(end 471.473022 -135.240522)
		(width 0.10795)
		(layer "B.Cu")
		(net "SMB_DEBUG_STBY_LVC3_SDA")
	)
	(segment
		(start 474.650816 -145.470372)
		(end 474.650816 -143.77416)
		(width 0.10795)
		(layer "B.Cu")
		(net "SMB_DEBUG_STBY_LVC3_SDA")
	)
	(segment
		(start 467.4997 -138.643106)
		(end 468.254334 -139.39774)
		(width 0.1016)
		(layer "B.Cu")
		(net "SMB_DEBUG_STBY_LVC3_SDA")
	)
	(segment
		(start 474.650816 -143.77416)
		(end 474.584268 -143.707612)
		(width 0.10795)
		(layer "B.Cu")
		(net "SMB_DEBUG_STBY_LVC3_SDA")
	)
	(segment
		(start 426.4914 -75.438)
		(end 425.599098 -76.330302)
		(width 0.10795)
		(layer "B.Cu")
		(net "SMB_DEBUG_STBY_LVC3_SDA")
	)
	(segment
		(start 425.599098 -76.330302)
		(end 425.599098 -79.867506)
		(width 0.10795)
		(layer "B.Cu")
		(net "SMB_DEBUG_STBY_LVC3_SDA")
	)
	(segment
		(start 468.685118 -135.85444)
		(end 467.4997 -137.039858)
		(width 0.1016)
		(layer "B.Cu")
		(net "SMB_DEBUG_STBY_LVC3_SDA")
	)
	(segment
		(start 427.059344 -116.05895)
		(end 427.059344 -116.25326)
		(width 0.10795)
		(layer "B.Cu")
		(net "SMB_DEBUG_STBY_LVC3_SDA")
	)
	(segment
		(start 427.059344 -116.25326)
		(end 427.059344 -116.384324)
		(width 0.10795)
		(layer "B.Cu")
		(net "SMB_DEBUG_STBY_LVC3_SDA")
	)
	(segment
		(start 473.44457 -127.51562)
		(end 473.717874 -127.242316)
		(width 0.10795)
		(layer "B.Cu")
		(net "SMB_DEBUG_STBY_LVC3_SDA")
	)
	(segment
		(start 427.811438 -115.306856)
		(end 427.059344 -116.05895)
		(width 0.10795)
		(layer "B.Cu")
		(net "SMB_DEBUG_STBY_LVC3_SDA")
	)
	(segment
		(start 471.466164 -134.815326)
		(end 471.466418 -134.81558)
		(width 0.10795)
		(layer "B.Cu")
		(net "SMB_DEBUG_STBY_LVC3_SDA")
	)
	(segment
		(start 427.811438 -111.703866)
		(end 427.811438 -115.306856)
		(width 0.10795)
		(layer "B.Cu")
		(net "SMB_DEBUG_STBY_LVC3_SDA")
	)
	(segment
		(start 470.859866 -141.650974)
		(end 471.0176 -141.808708)
		(width 0.1016)
		(layer "B.Cu")
		(net "SMB_DEBUG_STBY_LVC3_SDA")
	)
	(segment
		(start 473.45473 -132.846064)
		(end 473.45473 -133.587744)
		(width 0.10795)
		(layer "B.Cu")
		(net "SMB_DEBUG_STBY_LVC3_SDA")
	)
	(segment
		(start 471.466164 -134.623302)
		(end 471.466164 -134.815326)
		(width 0.10795)
		(layer "B.Cu")
		(net "SMB_DEBUG_STBY_LVC3_SDA")
	)
	(segment
		(start 468.8586 -139.67206)
		(end 468.8586 -140.86205)
		(width 0.1016)
		(layer "B.Cu")
		(net "SMB_DEBUG_STBY_LVC3_SDA")
	)
	(segment
		(start 425.599098 -79.867506)
		(end 425.82846 -80.096868)
		(width 0.10795)
		(layer "B.Cu")
		(net "SMB_DEBUG_STBY_LVC3_SDA")
	)
	(segment
		(start 471.473022 -135.240522)
		(end 471.473022 -135.590534)
		(width 0.10795)
		(layer "B.Cu")
		(net "SMB_DEBUG_STBY_LVC3_SDA")
	)
	(segment
		(start 468.719916 -135.851138)
		(end 468.716614 -135.85444)
		(width 0.10795)
		(layer "B.Cu")
		(net "SMB_DEBUG_STBY_LVC3_SDA")
	)
	(segment
		(start 427.059344 -116.384324)
		(end 427.367954 -116.692934)
		(width 0.10795)
		(layer "B.Cu")
		(net "SMB_DEBUG_STBY_LVC3_SDA")
	)
	(segment
		(start 425.82846 -109.720888)
		(end 427.811438 -111.703866)
		(width 0.10795)
		(layer "B.Cu")
		(net "SMB_DEBUG_STBY_LVC3_SDA")
	)
	(segment
		(start 468.716614 -135.85444)
		(end 468.685118 -135.85444)
		(width 0.1016)
		(layer "B.Cu")
		(net "SMB_DEBUG_STBY_LVC3_SDA")
	)
	(segment
		(start 474.138752 -131.350512)
		(end 474.410278 -131.622038)
		(width 0.10795)
		(layer "B.Cu")
		(net "SMB_DEBUG_STBY_LVC3_SDA")
	)
	(segment
		(start 468.254334 -139.39774)
		(end 468.58428 -139.39774)
		(width 0.1016)
		(layer "B.Cu")
		(net "SMB_DEBUG_STBY_LVC3_SDA")
	)
	(segment
		(start 471.82405 -134.265416)
		(end 471.466164 -134.623302)
		(width 0.10795)
		(layer "B.Cu")
		(net "SMB_DEBUG_STBY_LVC3_SDA")
	)
	(segment
		(start 468.58428 -139.39774)
		(end 468.8586 -139.67206)
		(width 0.1016)
		(layer "B.Cu")
		(net "SMB_DEBUG_STBY_LVC3_SDA")
	)
	(segment
		(start 473.44457 -127.715264)
		(end 473.44457 -127.51562)
		(width 0.10795)
		(layer "B.Cu")
		(net "SMB_DEBUG_STBY_LVC3_SDA")
	)
	(segment
		(start 473.45473 -133.587744)
		(end 472.777058 -134.265416)
		(width 0.10795)
		(layer "B.Cu")
		(net "SMB_DEBUG_STBY_LVC3_SDA")
	)
	(segment
		(start 467.4997 -137.039858)
		(end 467.4997 -138.643106)
		(width 0.1016)
		(layer "B.Cu")
		(net "SMB_DEBUG_STBY_LVC3_SDA")
	)
	(segment
		(start 472.693746 -143.639032)
		(end 473.660216 -143.639032)
		(width 0.1016)
		(layer "B.Cu")
		(net "SMB_DEBUG_STBY_LVC3_SDA")
	)
	(segment
		(start 469.647524 -141.650974)
		(end 470.859866 -141.650974)
		(width 0.1016)
		(layer "B.Cu")
		(net "SMB_DEBUG_STBY_LVC3_SDA")
	)
	(segment
		(start 473.804234 -130.8735)
		(end 472.851988 -129.921254)
		(width 0.10795)
		(layer "B.Cu")
		(net "SMB_DEBUG_STBY_LVC3_SDA")
	)
	(segment
		(start 425.82846 -80.096868)
		(end 425.82846 -109.720888)
		(width 0.10795)
		(layer "B.Cu")
		(net "SMB_DEBUG_STBY_LVC3_SDA")
	)
	(segment
		(start 471.969846 -143.404336)
		(end 472.45905 -143.404336)
		(width 0.1016)
		(layer "B.Cu")
		(net "SMB_DEBUG_STBY_LVC3_SDA")
	)
	(segment
		(start 427.367954 -116.692934)
		(end 427.84649 -116.692934)
		(width 0.10795)
		(layer "B.Cu")
		(net "SMB_DEBUG_STBY_LVC3_SDA")
	)
	(segment
		(start 473.717874 -127.242316)
		(end 473.925138 -127.242316)
		(width 0.10795)
		(layer "B.Cu")
		(net "SMB_DEBUG_STBY_LVC3_SDA")
	)
	(segment
		(start 471.225626 -135.83793)
		(end 471.216228 -135.83793)
		(width 0.10795)
		(layer "B.Cu")
		(net "SMB_DEBUG_STBY_LVC3_SDA")
	)
	(segment
		(start 472.851988 -129.921254)
		(end 472.851988 -128.307846)
		(width 0.10795)
		(layer "B.Cu")
		(net "SMB_DEBUG_STBY_LVC3_SDA")
	)
	(segment
		(start 474.515688 -143.639032)
		(end 473.660216 -143.639032)
		(width 0.1016)
		(layer "B.Cu")
		(net "SMB_DEBUG_STBY_LVC3_SDA")
	)
	(segment
		(start 472.851988 -128.307846)
		(end 473.44457 -127.715264)
		(width 0.10795)
		(layer "B.Cu")
		(net "SMB_DEBUG_STBY_LVC3_SDA")
	)
	(segment
		(start 468.8586 -140.86205)
		(end 469.647524 -141.650974)
		(width 0.1016)
		(layer "B.Cu")
		(net "SMB_DEBUG_STBY_LVC3_SDA")
	)
	(segment
		(start 471.0176 -141.808708)
		(end 471.0176 -142.45209)
		(width 0.1016)
		(layer "B.Cu")
		(net "SMB_DEBUG_STBY_LVC3_SDA")
	)
	(segment
		(start 471.473022 -135.590534)
		(end 471.225626 -135.83793)
		(width 0.10795)
		(layer "B.Cu")
		(net "SMB_DEBUG_STBY_LVC3_SDA")
	)
	(segment
		(start 471.20302 -135.851138)
		(end 468.719916 -135.851138)
		(width 0.10795)
		(layer "B.Cu")
		(net "SMB_DEBUG_STBY_LVC3_SDA")
	)
	(segment
		(start 472.777058 -134.265416)
		(end 471.82405 -134.265416)
		(width 0.10795)
		(layer "B.Cu")
		(net "SMB_DEBUG_STBY_LVC3_SDA")
	)
	(segment
		(start 474.235526 -131.253738)
		(end 474.235526 -131.10083)
		(width 0.10795)
		(layer "B.Cu")
		(net "SMB_DEBUG_STBY_LVC3_SDA")
	)
	(segment
		(start 474.584268 -143.707612)
		(end 474.515688 -143.639032)
		(width 0.1016)
		(layer "B.Cu")
		(net "SMB_DEBUG_STBY_LVC3_SDA")
	)
	(segment
		(start 474.410278 -131.622038)
		(end 474.410278 -131.890516)
		(width 0.10795)
		(layer "B.Cu")
		(net "SMB_DEBUG_STBY_LVC3_SDA")
	)
	(segment
		(start 418.68979 -44.376848)
		(end 418.880036 -44.186602)
		(width 0.089408)
		(layer "In4.Cu")
		(net "SMB_DEBUG_STBY_LVC3_SDA")
	)
	(segment
		(start 433.40528 -40.88384)
		(end 434.55844 -40.88384)
		(width 0.089408)
		(layer "In4.Cu")
		(net "SMB_DEBUG_STBY_LVC3_SDA")
	)
	(segment
		(start 432.712876 -118.6688)
		(end 430.643792 -118.6688)
		(width 0.089408)
		(layer "In4.Cu")
		(net "SMB_DEBUG_STBY_LVC3_SDA")
	)
	(segment
		(start 428.160688 -116.50345)
		(end 427.950122 -116.692934)
		(width 0.089408)
		(layer "In4.Cu")
		(net "SMB_DEBUG_STBY_LVC3_SDA")
	)
	(segment
		(start 399.796 -37.973)
		(end 400.2659 -38.4429)
		(width 0.089408)
		(layer "In4.Cu")
		(net "SMB_DEBUG_STBY_LVC3_SDA")
	)
	(segment
		(start 434.7083 -114.933476)
		(end 434.7083 -116.673376)
		(width 0.089408)
		(layer "In4.Cu")
		(net "SMB_DEBUG_STBY_LVC3_SDA")
	)
	(segment
		(start 402.000466 -40.372538)
		(end 402.885656 -41.257728)
		(width 0.089408)
		(layer "In4.Cu")
		(net "SMB_DEBUG_STBY_LVC3_SDA")
	)
	(segment
		(start 422.078658 -43.82643)
		(end 424.09618 -41.808908)
		(width 0.089408)
		(layer "In4.Cu")
		(net "SMB_DEBUG_STBY_LVC3_SDA")
	)
	(segment
		(start 434.98262 -41.30802)
		(end 450.548756 -41.30802)
		(width 0.089408)
		(layer "In4.Cu")
		(net "SMB_DEBUG_STBY_LVC3_SDA")
	)
	(segment
		(start 410.548836 -43.172634)
		(end 411.75305 -44.376848)
		(width 0.089408)
		(layer "In4.Cu")
		(net "SMB_DEBUG_STBY_LVC3_SDA")
	)
	(segment
		(start 476.970852 -116.769388)
		(end 471.825574 -116.769388)
		(width 0.089408)
		(layer "In4.Cu")
		(net "SMB_DEBUG_STBY_LVC3_SDA")
	)
	(segment
		(start 430.643792 -118.6688)
		(end 430.5935 -118.618508)
		(width 0.089408)
		(layer "In4.Cu")
		(net "SMB_DEBUG_STBY_LVC3_SDA")
	)
	(segment
		(start 420.167562 -43.82643)
		(end 422.078658 -43.82643)
		(width 0.089408)
		(layer "In4.Cu")
		(net "SMB_DEBUG_STBY_LVC3_SDA")
	)
	(segment
		(start 427.950122 -116.692934)
		(end 427.84649 -116.692934)
		(width 0.089408)
		(layer "In4.Cu")
		(net "SMB_DEBUG_STBY_LVC3_SDA")
	)
	(segment
		(start 477.393 -123.6472)
		(end 478.513902 -122.526298)
		(width 0.089408)
		(layer "In4.Cu")
		(net "SMB_DEBUG_STBY_LVC3_SDA")
	)
	(segment
		(start 427.977554 -39.850822)
		(end 429.914812 -39.850822)
		(width 0.089408)
		(layer "In4.Cu")
		(net "SMB_DEBUG_STBY_LVC3_SDA")
	)
	(segment
		(start 430.523396 -118.618508)
		(end 428.408338 -116.50345)
		(width 0.089408)
		(layer "In4.Cu")
		(net "SMB_DEBUG_STBY_LVC3_SDA")
	)
	(segment
		(start 434.55844 -40.88384)
		(end 434.98262 -41.30802)
		(width 0.089408)
		(layer "In4.Cu")
		(net "SMB_DEBUG_STBY_LVC3_SDA")
	)
	(segment
		(start 466.788246 -43.785282)
		(end 467.550754 -44.54779)
		(width 0.089408)
		(layer "In4.Cu")
		(net "SMB_DEBUG_STBY_LVC3_SDA")
	)
	(segment
		(start 439.6486 -113.8174)
		(end 435.824376 -113.8174)
		(width 0.089408)
		(layer "In4.Cu")
		(net "SMB_DEBUG_STBY_LVC3_SDA")
	)
	(segment
		(start 424.09618 -41.808908)
		(end 426.019468 -41.808908)
		(width 0.089408)
		(layer "In4.Cu")
		(net "SMB_DEBUG_STBY_LVC3_SDA")
	)
	(segment
		(start 450.937884 -40.918892)
		(end 456.335892 -40.918892)
		(width 0.089408)
		(layer "In4.Cu")
		(net "SMB_DEBUG_STBY_LVC3_SDA")
	)
	(segment
		(start 434.7083 -116.673376)
		(end 432.712876 -118.6688)
		(width 0.089408)
		(layer "In4.Cu")
		(net "SMB_DEBUG_STBY_LVC3_SDA")
	)
	(segment
		(start 468.548212 -44.54779)
		(end 470.1413 -46.140878)
		(width 0.089408)
		(layer "In4.Cu")
		(net "SMB_DEBUG_STBY_LVC3_SDA")
	)
	(segment
		(start 477.393 -127.615696)
		(end 477.393 -123.6472)
		(width 0.089408)
		(layer "In4.Cu")
		(net "SMB_DEBUG_STBY_LVC3_SDA")
	)
	(segment
		(start 467.914482 -112.858296)
		(end 440.607704 -112.858296)
		(width 0.089408)
		(layer "In4.Cu")
		(net "SMB_DEBUG_STBY_LVC3_SDA")
	)
	(segment
		(start 474.452696 -131.036568)
		(end 474.452696 -130.556)
		(width 0.089408)
		(layer "In4.Cu")
		(net "SMB_DEBUG_STBY_LVC3_SDA")
	)
	(segment
		(start 470.1413 -46.140878)
		(end 470.1413 -52.2859)
		(width 0.089408)
		(layer "In4.Cu")
		(net "SMB_DEBUG_STBY_LVC3_SDA")
	)
	(segment
		(start 471.571574 -53.716174)
		(end 472.820238 -53.716174)
		(width 0.089408)
		(layer "In4.Cu")
		(net "SMB_DEBUG_STBY_LVC3_SDA")
	)
	(segment
		(start 435.824376 -113.8174)
		(end 434.7083 -114.933476)
		(width 0.089408)
		(layer "In4.Cu")
		(net "SMB_DEBUG_STBY_LVC3_SDA")
	)
	(segment
		(start 470.1413 -52.2859)
		(end 471.571574 -53.716174)
		(width 0.089408)
		(layer "In4.Cu")
		(net "SMB_DEBUG_STBY_LVC3_SDA")
	)
	(segment
		(start 401.08251 -40.372538)
		(end 402.000466 -40.372538)
		(width 0.089408)
		(layer "In4.Cu")
		(net "SMB_DEBUG_STBY_LVC3_SDA")
	)
	(segment
		(start 467.550754 -44.54779)
		(end 468.548212 -44.54779)
		(width 0.089408)
		(layer "In4.Cu")
		(net "SMB_DEBUG_STBY_LVC3_SDA")
	)
	(segment
		(start 430.5935 -118.618508)
		(end 430.523396 -118.618508)
		(width 0.089408)
		(layer "In4.Cu")
		(net "SMB_DEBUG_STBY_LVC3_SDA")
	)
	(segment
		(start 474.138752 -131.350512)
		(end 474.452696 -131.036568)
		(width 0.089408)
		(layer "In4.Cu")
		(net "SMB_DEBUG_STBY_LVC3_SDA")
	)
	(segment
		(start 450.548756 -41.30802)
		(end 450.937884 -40.918892)
		(width 0.089408)
		(layer "In4.Cu")
		(net "SMB_DEBUG_STBY_LVC3_SDA")
	)
	(segment
		(start 474.452696 -130.556)
		(end 477.393 -127.615696)
		(width 0.089408)
		(layer "In4.Cu")
		(net "SMB_DEBUG_STBY_LVC3_SDA")
	)
	(segment
		(start 400.2659 -39.555928)
		(end 401.08251 -40.372538)
		(width 0.089408)
		(layer "In4.Cu")
		(net "SMB_DEBUG_STBY_LVC3_SDA")
	)
	(segment
		(start 429.914812 -39.850822)
		(end 430.312576 -40.248586)
		(width 0.089408)
		(layer "In4.Cu")
		(net "SMB_DEBUG_STBY_LVC3_SDA")
	)
	(segment
		(start 440.607704 -112.858296)
		(end 439.6486 -113.8174)
		(width 0.089408)
		(layer "In4.Cu")
		(net "SMB_DEBUG_STBY_LVC3_SDA")
	)
	(segment
		(start 400.2659 -38.4429)
		(end 400.2659 -39.555928)
		(width 0.089408)
		(layer "In4.Cu")
		(net "SMB_DEBUG_STBY_LVC3_SDA")
	)
	(segment
		(start 478.513902 -122.526298)
		(end 478.513902 -118.312438)
		(width 0.089408)
		(layer "In4.Cu")
		(net "SMB_DEBUG_STBY_LVC3_SDA")
	)
	(segment
		(start 419.80739 -44.186602)
		(end 420.167562 -43.82643)
		(width 0.089408)
		(layer "In4.Cu")
		(net "SMB_DEBUG_STBY_LVC3_SDA")
	)
	(segment
		(start 471.825574 -116.769388)
		(end 467.914482 -112.858296)
		(width 0.089408)
		(layer "In4.Cu")
		(net "SMB_DEBUG_STBY_LVC3_SDA")
	)
	(segment
		(start 411.75305 -44.376848)
		(end 418.68979 -44.376848)
		(width 0.089408)
		(layer "In4.Cu")
		(net "SMB_DEBUG_STBY_LVC3_SDA")
	)
	(segment
		(start 402.885656 -41.257728)
		(end 406.517348 -41.257728)
		(width 0.089408)
		(layer "In4.Cu")
		(net "SMB_DEBUG_STBY_LVC3_SDA")
	)
	(segment
		(start 459.202282 -43.785282)
		(end 466.788246 -43.785282)
		(width 0.089408)
		(layer "In4.Cu")
		(net "SMB_DEBUG_STBY_LVC3_SDA")
	)
	(segment
		(start 430.312576 -40.248586)
		(end 432.770026 -40.248586)
		(width 0.089408)
		(layer "In4.Cu")
		(net "SMB_DEBUG_STBY_LVC3_SDA")
	)
	(segment
		(start 428.408338 -116.50345)
		(end 428.160688 -116.50345)
		(width 0.089408)
		(layer "In4.Cu")
		(net "SMB_DEBUG_STBY_LVC3_SDA")
	)
	(segment
		(start 406.517348 -41.257728)
		(end 408.432254 -43.172634)
		(width 0.089408)
		(layer "In4.Cu")
		(net "SMB_DEBUG_STBY_LVC3_SDA")
	)
	(segment
		(start 408.432254 -43.172634)
		(end 410.548836 -43.172634)
		(width 0.089408)
		(layer "In4.Cu")
		(net "SMB_DEBUG_STBY_LVC3_SDA")
	)
	(segment
		(start 478.513902 -118.312438)
		(end 476.970852 -116.769388)
		(width 0.089408)
		(layer "In4.Cu")
		(net "SMB_DEBUG_STBY_LVC3_SDA")
	)
	(segment
		(start 426.019468 -41.808908)
		(end 427.977554 -39.850822)
		(width 0.089408)
		(layer "In4.Cu")
		(net "SMB_DEBUG_STBY_LVC3_SDA")
	)
	(segment
		(start 456.335892 -40.918892)
		(end 459.202282 -43.785282)
		(width 0.089408)
		(layer "In4.Cu")
		(net "SMB_DEBUG_STBY_LVC3_SDA")
	)
	(segment
		(start 418.880036 -44.186602)
		(end 419.80739 -44.186602)
		(width 0.089408)
		(layer "In4.Cu")
		(net "SMB_DEBUG_STBY_LVC3_SDA")
	)
	(segment
		(start 432.770026 -40.248586)
		(end 433.40528 -40.88384)
		(width 0.089408)
		(layer "In4.Cu")
		(net "SMB_DEBUG_STBY_LVC3_SDA")
	)
	(segment
		(start 427.348142 -67.353688)
		(end 425.921678 -68.780152)
		(width 0.089408)
		(layer "In9.Cu")
		(net "SMB_DEBUG_STBY_LVC3_SDA")
	)
	(segment
		(start 477.214438 -57.837832)
		(end 477.214438 -64.338962)
		(width 0.089408)
		(layer "In9.Cu")
		(net "SMB_DEBUG_STBY_LVC3_SDA")
	)
	(segment
		(start 425.921678 -75.164696)
		(end 426.194982 -75.438)
		(width 0.089408)
		(layer "In9.Cu")
		(net "SMB_DEBUG_STBY_LVC3_SDA")
	)
	(segment
		(start 426.194982 -75.438)
		(end 426.4914 -75.438)
		(width 0.089408)
		(layer "In9.Cu")
		(net "SMB_DEBUG_STBY_LVC3_SDA")
	)
	(segment
		(start 472.820238 -53.716174)
		(end 472.820238 -54.660038)
		(width 0.089408)
		(layer "In9.Cu")
		(net "SMB_DEBUG_STBY_LVC3_SDA")
	)
	(segment
		(start 472.820238 -54.660038)
		(end 473.197682 -55.037482)
		(width 0.089408)
		(layer "In9.Cu")
		(net "SMB_DEBUG_STBY_LVC3_SDA")
	)
	(segment
		(start 474.199712 -67.353688)
		(end 427.348142 -67.353688)
		(width 0.089408)
		(layer "In9.Cu")
		(net "SMB_DEBUG_STBY_LVC3_SDA")
	)
	(segment
		(start 473.197682 -55.037482)
		(end 474.414088 -55.037482)
		(width 0.089408)
		(layer "In9.Cu")
		(net "SMB_DEBUG_STBY_LVC3_SDA")
	)
	(segment
		(start 425.921678 -68.780152)
		(end 425.921678 -75.164696)
		(width 0.089408)
		(layer "In9.Cu")
		(net "SMB_DEBUG_STBY_LVC3_SDA")
	)
	(segment
		(start 477.214438 -64.338962)
		(end 474.199712 -67.353688)
		(width 0.089408)
		(layer "In9.Cu")
		(net "SMB_DEBUG_STBY_LVC3_SDA")
	)
	(segment
		(start 474.414088 -55.037482)
		(end 477.214438 -57.837832)
		(width 0.089408)
		(layer "In9.Cu")
		(net "SMB_DEBUG_STBY_LVC3_SDA")
	)
	(segment
		(start 405.155146 -36.8554)
		(end 405.155146 -36.533074)
		(width 0.1016)
		(layer "F.Cu")
		(net "SMB_DEBUG_STBY_LVC3_SCL_R")
	)
	(segment
		(start 404.723854 -36.954206)
		(end 405.05634 -36.954206)
		(width 0.1016)
		(layer "F.Cu")
		(net "SMB_DEBUG_STBY_LVC3_SCL_R")
	)
	(segment
		(start 405.05634 -36.954206)
		(end 405.155146 -36.8554)
		(width 0.1016)
		(layer "F.Cu")
		(net "SMB_DEBUG_STBY_LVC3_SCL_R")
	)
	(segment
		(start 405.155146 -36.533074)
		(end 405.991568 -35.696652)
		(width 0.1016)
		(layer "F.Cu")
		(net "SMB_DEBUG_STBY_LVC3_SCL_R")
	)
	(segment
		(start 402.627592 -36.954206)
		(end 402.361146 -37.220652)
		(width 0.1016)
		(layer "F.Cu")
		(net "SMB_DEBUG_STBY_LVC3_SCL_R")
	)
	(segment
		(start 404.723854 -36.954206)
		(end 402.627592 -36.954206)
		(width 0.1016)
		(layer "F.Cu")
		(net "SMB_DEBUG_STBY_LVC3_SCL_R")
	)
	(segment
		(start 408.328114 -35.696652)
		(end 408.690064 -35.334702)
		(width 0.1016)
		(layer "F.Cu")
		(net "SMB_DEBUG_STBY_LVC3_SCL_R")
	)
	(segment
		(start 405.991568 -35.696652)
		(end 408.328114 -35.696652)
		(width 0.1016)
		(layer "F.Cu")
		(net "SMB_DEBUG_STBY_LVC3_SCL_R")
	)
	(via
		(at 404.723854 -36.954206)
		(size 0.508)
		(drill 0.254)
		(layers "F.Cu" "B.Cu")
		(net "SMB_DEBUG_STBY_LVC3_SCL_R")
	)
	(segment
		(start 400.269202 -38.160198)
		(end 399.796 -38.6334)
		(width 0.1016)
		(layer "F.Cu")
		(net "SMB_DEBUG_STBY_LVC3_SCL")
	)
	(segment
		(start 401.472146 -37.220652)
		(end 400.642328 -37.220652)
		(width 0.1016)
		(layer "F.Cu")
		(net "SMB_DEBUG_STBY_LVC3_SCL")
	)
	(segment
		(start 400.642328 -37.220652)
		(end 400.269202 -37.593778)
		(width 0.1016)
		(layer "F.Cu")
		(net "SMB_DEBUG_STBY_LVC3_SCL")
	)
	(segment
		(start 400.269202 -37.593778)
		(end 400.269202 -38.160198)
		(width 0.1016)
		(layer "F.Cu")
		(net "SMB_DEBUG_STBY_LVC3_SCL")
	)
	(via
		(at 399.796 -38.6334)
		(size 0.508)
		(drill 0.254)
		(layers "F.Cu" "B.Cu")
		(net "SMB_DEBUG_STBY_LVC3_SCL")
	)
	(via
		(at 468.05342 -138.486896)
		(size 0.6604)
		(drill 0.3302)
		(layers "F.Cu" "B.Cu")
		(net "SMB_DEBUG_STBY_LVC3_SCL")
	)
	(via
		(at 427.84649 -116.035328)
		(size 0.508)
		(drill 0.254)
		(layers "F.Cu" "B.Cu")
		(net "SMB_DEBUG_STBY_LVC3_SCL")
	)
	(via
		(at 472.339416 -54.154324)
		(size 0.508)
		(drill 0.254)
		(layers "F.Cu" "B.Cu")
		(net "SMB_DEBUG_STBY_LVC3_SCL")
	)
	(via
		(at 426.4914 -76.073)
		(size 0.508)
		(drill 0.254)
		(layers "F.Cu" "B.Cu")
		(net "SMB_DEBUG_STBY_LVC3_SCL")
	)
	(via
		(at 474.958156 -131.37515)
		(size 0.508)
		(drill 0.254)
		(layers "F.Cu" "B.Cu")
		(net "SMB_DEBUG_STBY_LVC3_SCL")
	)
	(segment
		(start 473.90177 -130.63855)
		(end 474.221556 -130.63855)
		(width 0.10795)
		(layer "B.Cu")
		(net "SMB_DEBUG_STBY_LVC3_SCL")
	)
	(segment
		(start 474.963236 -144.184116)
		(end 474.963236 -143.717518)
		(width 0.10795)
		(layer "B.Cu")
		(net "SMB_DEBUG_STBY_LVC3_SCL")
	)
	(segment
		(start 472.642946 -142.988792)
		(end 472.477846 -143.153892)
		(width 0.1016)
		(layer "B.Cu")
		(net "SMB_DEBUG_STBY_LVC3_SCL")
	)
	(segment
		(start 473.735654 -133.634988)
		(end 472.873324 -134.497318)
		(width 0.1016)
		(layer "B.Cu")
		(net "SMB_DEBUG_STBY_LVC3_SCL")
	)
	(segment
		(start 474.221556 -130.63855)
		(end 474.958156 -131.37515)
		(width 0.10795)
		(layer "B.Cu")
		(net "SMB_DEBUG_STBY_LVC3_SCL")
	)
	(segment
		(start 474.96349 -143.717264)
		(end 474.96349 -143.157448)
		(width 0.10795)
		(layer "B.Cu")
		(net "SMB_DEBUG_STBY_LVC3_SCL")
	)
	(segment
		(start 474.64218 -131.691126)
		(end 474.64218 -131.992624)
		(width 0.1016)
		(layer "B.Cu")
		(net "SMB_DEBUG_STBY_LVC3_SCL")
	)
	(segment
		(start 473.086938 -128.405382)
		(end 473.086938 -129.823718)
		(width 0.10795)
		(layer "B.Cu")
		(net "SMB_DEBUG_STBY_LVC3_SCL")
	)
	(segment
		(start 426.06341 -79.999332)
		(end 425.834048 -79.76997)
		(width 0.10795)
		(layer "B.Cu")
		(net "SMB_DEBUG_STBY_LVC3_SCL")
	)
	(segment
		(start 425.834048 -76.730352)
		(end 426.4914 -76.073)
		(width 0.10795)
		(layer "B.Cu")
		(net "SMB_DEBUG_STBY_LVC3_SCL")
	)
	(segment
		(start 471.920316 -134.497318)
		(end 471.775536 -134.642098)
		(width 0.1016)
		(layer "B.Cu")
		(net "SMB_DEBUG_STBY_LVC3_SCL")
	)
	(segment
		(start 474.64218 -131.992624)
		(end 473.735654 -132.89915)
		(width 0.1016)
		(layer "B.Cu")
		(net "SMB_DEBUG_STBY_LVC3_SCL")
	)
	(segment
		(start 474.963236 -143.717518)
		(end 474.96349 -143.717264)
		(width 0.10795)
		(layer "B.Cu")
		(net "SMB_DEBUG_STBY_LVC3_SCL")
	)
	(segment
		(start 471.312494 -136.069832)
		(end 471.299286 -136.08304)
		(width 0.1016)
		(layer "B.Cu")
		(net "SMB_DEBUG_STBY_LVC3_SCL")
	)
	(segment
		(start 471.2716 -142.324328)
		(end 471.2716 -141.72057)
		(width 0.1016)
		(layer "B.Cu")
		(net "SMB_DEBUG_STBY_LVC3_SCL")
	)
	(segment
		(start 474.958156 -131.37515)
		(end 474.64218 -131.691126)
		(width 0.1016)
		(layer "B.Cu")
		(net "SMB_DEBUG_STBY_LVC3_SCL")
	)
	(segment
		(start 469.1126 -140.792708)
		(end 469.1126 -139.546076)
		(width 0.1016)
		(layer "B.Cu")
		(net "SMB_DEBUG_STBY_LVC3_SCL")
	)
	(segment
		(start 471.2716 -141.72057)
		(end 470.948004 -141.396974)
		(width 0.1016)
		(layer "B.Cu")
		(net "SMB_DEBUG_STBY_LVC3_SCL")
	)
	(segment
		(start 427.858174 -116.035328)
		(end 428.046388 -115.847114)
		(width 0.10795)
		(layer "B.Cu")
		(net "SMB_DEBUG_STBY_LVC3_SCL")
	)
	(segment
		(start 473.660216 -142.988792)
		(end 472.642946 -142.988792)
		(width 0.1016)
		(layer "B.Cu")
		(net "SMB_DEBUG_STBY_LVC3_SCL")
	)
	(segment
		(start 473.735654 -132.89915)
		(end 473.735654 -133.634988)
		(width 0.1016)
		(layer "B.Cu")
		(net "SMB_DEBUG_STBY_LVC3_SCL")
	)
	(segment
		(start 475.412816 -144.633696)
		(end 474.963236 -144.184116)
		(width 0.10795)
		(layer "B.Cu")
		(net "SMB_DEBUG_STBY_LVC3_SCL")
	)
	(segment
		(start 467.91118 -136.988042)
		(end 467.91118 -138.344656)
		(width 0.1016)
		(layer "B.Cu")
		(net "SMB_DEBUG_STBY_LVC3_SCL")
	)
	(segment
		(start 426.06341 -109.623352)
		(end 426.06341 -79.999332)
		(width 0.10795)
		(layer "B.Cu")
		(net "SMB_DEBUG_STBY_LVC3_SCL")
	)
	(segment
		(start 468.816182 -136.08304)
		(end 467.91118 -136.988042)
		(width 0.1016)
		(layer "B.Cu")
		(net "SMB_DEBUG_STBY_LVC3_SCL")
	)
	(segment
		(start 472.101164 -143.153892)
		(end 471.2716 -142.324328)
		(width 0.1016)
		(layer "B.Cu")
		(net "SMB_DEBUG_STBY_LVC3_SCL")
	)
	(segment
		(start 471.775536 -134.642098)
		(end 471.775536 -135.616188)
		(width 0.1016)
		(layer "B.Cu")
		(net "SMB_DEBUG_STBY_LVC3_SCL")
	)
	(segment
		(start 472.873324 -134.497318)
		(end 471.920316 -134.497318)
		(width 0.1016)
		(layer "B.Cu")
		(net "SMB_DEBUG_STBY_LVC3_SCL")
	)
	(segment
		(start 475.412816 -145.470372)
		(end 475.412816 -144.633696)
		(width 0.10795)
		(layer "B.Cu")
		(net "SMB_DEBUG_STBY_LVC3_SCL")
	)
	(segment
		(start 469.716866 -141.396974)
		(end 469.1126 -140.792708)
		(width 0.1016)
		(layer "B.Cu")
		(net "SMB_DEBUG_STBY_LVC3_SCL")
	)
	(segment
		(start 428.046388 -111.60633)
		(end 426.06341 -109.623352)
		(width 0.10795)
		(layer "B.Cu")
		(net "SMB_DEBUG_STBY_LVC3_SCL")
	)
	(segment
		(start 471.299286 -136.08304)
		(end 468.816182 -136.08304)
		(width 0.1016)
		(layer "B.Cu")
		(net "SMB_DEBUG_STBY_LVC3_SCL")
	)
	(segment
		(start 473.471748 -128.020572)
		(end 473.086938 -128.405382)
		(width 0.10795)
		(layer "B.Cu")
		(net "SMB_DEBUG_STBY_LVC3_SCL")
	)
	(segment
		(start 471.775536 -135.616188)
		(end 471.321892 -136.069832)
		(width 0.1016)
		(layer "B.Cu")
		(net "SMB_DEBUG_STBY_LVC3_SCL")
	)
	(segment
		(start 428.046388 -115.847114)
		(end 428.046388 -111.60633)
		(width 0.10795)
		(layer "B.Cu")
		(net "SMB_DEBUG_STBY_LVC3_SCL")
	)
	(segment
		(start 471.321892 -136.069832)
		(end 471.312494 -136.069832)
		(width 0.1016)
		(layer "B.Cu")
		(net "SMB_DEBUG_STBY_LVC3_SCL")
	)
	(segment
		(start 472.477846 -143.153892)
		(end 472.101164 -143.153892)
		(width 0.1016)
		(layer "B.Cu")
		(net "SMB_DEBUG_STBY_LVC3_SCL")
	)
	(segment
		(start 474.794834 -142.988792)
		(end 473.660216 -142.988792)
		(width 0.1016)
		(layer "B.Cu")
		(net "SMB_DEBUG_STBY_LVC3_SCL")
	)
	(segment
		(start 425.834048 -79.76997)
		(end 425.834048 -76.730352)
		(width 0.10795)
		(layer "B.Cu")
		(net "SMB_DEBUG_STBY_LVC3_SCL")
	)
	(segment
		(start 469.1126 -139.546076)
		(end 468.05342 -138.486896)
		(width 0.1016)
		(layer "B.Cu")
		(net "SMB_DEBUG_STBY_LVC3_SCL")
	)
	(segment
		(start 474.96349 -143.157448)
		(end 474.794834 -142.988792)
		(width 0.1016)
		(layer "B.Cu")
		(net "SMB_DEBUG_STBY_LVC3_SCL")
	)
	(segment
		(start 467.91118 -138.344656)
		(end 468.05342 -138.486896)
		(width 0.1016)
		(layer "B.Cu")
		(net "SMB_DEBUG_STBY_LVC3_SCL")
	)
	(segment
		(start 427.84649 -116.035328)
		(end 427.858174 -116.035328)
		(width 0.10795)
		(layer "B.Cu")
		(net "SMB_DEBUG_STBY_LVC3_SCL")
	)
	(segment
		(start 470.948004 -141.396974)
		(end 469.716866 -141.396974)
		(width 0.1016)
		(layer "B.Cu")
		(net "SMB_DEBUG_STBY_LVC3_SCL")
	)
	(segment
		(start 473.086938 -129.823718)
		(end 473.90177 -130.63855)
		(width 0.10795)
		(layer "B.Cu")
		(net "SMB_DEBUG_STBY_LVC3_SCL")
	)
	(segment
		(start 473.912946 -128.020572)
		(end 473.471748 -128.020572)
		(width 0.10795)
		(layer "B.Cu")
		(net "SMB_DEBUG_STBY_LVC3_SCL")
	)
	(segment
		(start 453.028304 -42.164)
		(end 452.247 -41.382696)
		(width 0.089408)
		(layer "In4.Cu")
		(net "SMB_DEBUG_STBY_LVC3_SCL")
	)
	(segment
		(start 434.467 -114.8334)
		(end 434.467 -116.5733)
		(width 0.089408)
		(layer "In4.Cu")
		(net "SMB_DEBUG_STBY_LVC3_SCL")
	)
	(segment
		(start 431.935128 -41.539668)
		(end 430.835054 -40.439594)
		(width 0.089408)
		(layer "In4.Cu")
		(net "SMB_DEBUG_STBY_LVC3_SCL")
	)
	(segment
		(start 458.065124 -42.9895)
		(end 455.5363 -42.9895)
		(width 0.089408)
		(layer "In4.Cu")
		(net "SMB_DEBUG_STBY_LVC3_SCL")
	)
	(segment
		(start 401.90039 -40.613838)
		(end 401.053554 -40.613838)
		(width 0.089408)
		(layer "In4.Cu")
		(net "SMB_DEBUG_STBY_LVC3_SCL")
	)
	(segment
		(start 418.523674 -44.567856)
		(end 418.52342 -44.567602)
		(width 0.089408)
		(layer "In4.Cu")
		(net "SMB_DEBUG_STBY_LVC3_SCL")
	)
	(segment
		(start 450.744336 -41.382696)
		(end 450.628004 -41.499028)
		(width 0.089408)
		(layer "In4.Cu")
		(net "SMB_DEBUG_STBY_LVC3_SCL")
	)
	(segment
		(start 418.681662 -44.567856)
		(end 418.523674 -44.567856)
		(width 0.089408)
		(layer "In4.Cu")
		(net "SMB_DEBUG_STBY_LVC3_SCL")
	)
	(segment
		(start 420.24681 -44.017184)
		(end 419.886638 -44.377356)
		(width 0.089408)
		(layer "In4.Cu")
		(net "SMB_DEBUG_STBY_LVC3_SCL")
	)
	(segment
		(start 432.6128 -118.4275)
		(end 430.602644 -118.4275)
		(width 0.089408)
		(layer "In4.Cu")
		(net "SMB_DEBUG_STBY_LVC3_SCL")
	)
	(segment
		(start 439.548524 -113.5761)
		(end 435.7243 -113.5761)
		(width 0.089408)
		(layer "In4.Cu")
		(net "SMB_DEBUG_STBY_LVC3_SCL")
	)
	(segment
		(start 428.055278 -40.126158)
		(end 428.055024 -40.126158)
		(width 0.089408)
		(layer "In4.Cu")
		(net "SMB_DEBUG_STBY_LVC3_SCL")
	)
	(segment
		(start 433.330858 -41.10228)
		(end 432.89347 -41.539668)
		(width 0.089408)
		(layer "In4.Cu")
		(net "SMB_DEBUG_STBY_LVC3_SCL")
	)
	(segment
		(start 454.7108 -42.164)
		(end 453.028304 -42.164)
		(width 0.089408)
		(layer "In4.Cu")
		(net "SMB_DEBUG_STBY_LVC3_SCL")
	)
	(segment
		(start 434.868828 -41.499028)
		(end 434.47208 -41.10228)
		(width 0.089408)
		(layer "In4.Cu")
		(net "SMB_DEBUG_STBY_LVC3_SCL")
	)
	(segment
		(start 411.673548 -44.567602)
		(end 410.519372 -43.413426)
		(width 0.089408)
		(layer "In4.Cu")
		(net "SMB_DEBUG_STBY_LVC3_SCL")
	)
	(segment
		(start 430.233328 -40.439594)
		(end 429.83912 -40.045386)
		(width 0.089408)
		(layer "In4.Cu")
		(net "SMB_DEBUG_STBY_LVC3_SCL")
	)
	(segment
		(start 401.053554 -40.613838)
		(end 399.796 -39.356284)
		(width 0.089408)
		(layer "In4.Cu")
		(net "SMB_DEBUG_STBY_LVC3_SCL")
	)
	(segment
		(start 428.18685 -116.26215)
		(end 427.947582 -116.035328)
		(width 0.089408)
		(layer "In4.Cu")
		(net "SMB_DEBUG_STBY_LVC3_SCL")
	)
	(segment
		(start 435.7243 -113.5761)
		(end 434.467 -114.8334)
		(width 0.089408)
		(layer "In4.Cu")
		(net "SMB_DEBUG_STBY_LVC3_SCL")
	)
	(segment
		(start 406.367996 -41.448736)
		(end 402.735288 -41.448736)
		(width 0.089408)
		(layer "In4.Cu")
		(net "SMB_DEBUG_STBY_LVC3_SCL")
	)
	(segment
		(start 418.681916 -44.567602)
		(end 418.681662 -44.567856)
		(width 0.089408)
		(layer "In4.Cu")
		(net "SMB_DEBUG_STBY_LVC3_SCL")
	)
	(segment
		(start 474.660722 -130.61823)
		(end 477.6343 -127.644652)
		(width 0.089408)
		(layer "In4.Cu")
		(net "SMB_DEBUG_STBY_LVC3_SCL")
	)
	(segment
		(start 427.947582 -116.035328)
		(end 427.84649 -116.035328)
		(width 0.089408)
		(layer "In4.Cu")
		(net "SMB_DEBUG_STBY_LVC3_SCL")
	)
	(segment
		(start 422.157906 -44.017184)
		(end 420.24681 -44.017184)
		(width 0.089408)
		(layer "In4.Cu")
		(net "SMB_DEBUG_STBY_LVC3_SCL")
	)
	(segment
		(start 429.83912 -40.045386)
		(end 428.13605 -40.045386)
		(width 0.089408)
		(layer "In4.Cu")
		(net "SMB_DEBUG_STBY_LVC3_SCL")
	)
	(segment
		(start 434.467 -116.5733)
		(end 432.6128 -118.4275)
		(width 0.089408)
		(layer "In4.Cu")
		(net "SMB_DEBUG_STBY_LVC3_SCL")
	)
	(segment
		(start 402.735288 -41.448736)
		(end 401.90039 -40.613838)
		(width 0.089408)
		(layer "In4.Cu")
		(net "SMB_DEBUG_STBY_LVC3_SCL")
	)
	(segment
		(start 452.247 -41.382696)
		(end 450.744336 -41.382696)
		(width 0.089408)
		(layer "In4.Cu")
		(net "SMB_DEBUG_STBY_LVC3_SCL")
	)
	(segment
		(start 468.014558 -112.616996)
		(end 440.507628 -112.616996)
		(width 0.089408)
		(layer "In4.Cu")
		(net "SMB_DEBUG_STBY_LVC3_SCL")
	)
	(segment
		(start 430.602644 -118.4275)
		(end 428.437294 -116.26215)
		(width 0.089408)
		(layer "In4.Cu")
		(net "SMB_DEBUG_STBY_LVC3_SCL")
	)
	(segment
		(start 477.6343 -123.747276)
		(end 478.70491 -122.676666)
		(width 0.089408)
		(layer "In4.Cu")
		(net "SMB_DEBUG_STBY_LVC3_SCL")
	)
	(segment
		(start 466.68817 -44.026582)
		(end 459.102206 -44.026582)
		(width 0.089408)
		(layer "In4.Cu")
		(net "SMB_DEBUG_STBY_LVC3_SCL")
	)
	(segment
		(start 424.106848 -42.068242)
		(end 422.157906 -44.017184)
		(width 0.089408)
		(layer "In4.Cu")
		(net "SMB_DEBUG_STBY_LVC3_SCL")
	)
	(segment
		(start 474.660722 -131.077716)
		(end 474.660722 -130.61823)
		(width 0.089408)
		(layer "In4.Cu")
		(net "SMB_DEBUG_STBY_LVC3_SCL")
	)
	(segment
		(start 469.9 -46.169834)
		(end 468.519256 -44.78909)
		(width 0.089408)
		(layer "In4.Cu")
		(net "SMB_DEBUG_STBY_LVC3_SCL")
	)
	(segment
		(start 440.507628 -112.616996)
		(end 439.548524 -113.5761)
		(width 0.089408)
		(layer "In4.Cu")
		(net "SMB_DEBUG_STBY_LVC3_SCL")
	)
	(segment
		(start 450.628004 -41.499028)
		(end 434.868828 -41.499028)
		(width 0.089408)
		(layer "In4.Cu")
		(net "SMB_DEBUG_STBY_LVC3_SCL")
	)
	(segment
		(start 474.958156 -131.37515)
		(end 474.660722 -131.077716)
		(width 0.089408)
		(layer "In4.Cu")
		(net "SMB_DEBUG_STBY_LVC3_SCL")
	)
	(segment
		(start 410.519372 -43.413426)
		(end 408.332686 -43.413426)
		(width 0.089408)
		(layer "In4.Cu")
		(net "SMB_DEBUG_STBY_LVC3_SCL")
	)
	(segment
		(start 469.9 -52.314856)
		(end 469.9 -46.169834)
		(width 0.089408)
		(layer "In4.Cu")
		(net "SMB_DEBUG_STBY_LVC3_SCL")
	)
	(segment
		(start 408.332686 -43.413426)
		(end 406.367996 -41.448736)
		(width 0.089408)
		(layer "In4.Cu")
		(net "SMB_DEBUG_STBY_LVC3_SCL")
	)
	(segment
		(start 428.437294 -116.26215)
		(end 428.18685 -116.26215)
		(width 0.089408)
		(layer "In4.Cu")
		(net "SMB_DEBUG_STBY_LVC3_SCL")
	)
	(segment
		(start 418.769038 -44.567602)
		(end 418.681916 -44.567602)
		(width 0.089408)
		(layer "In4.Cu")
		(net "SMB_DEBUG_STBY_LVC3_SCL")
	)
	(segment
		(start 432.89347 -41.539668)
		(end 431.935128 -41.539668)
		(width 0.089408)
		(layer "In4.Cu")
		(net "SMB_DEBUG_STBY_LVC3_SCL")
	)
	(segment
		(start 477.6343 -127.644652)
		(end 477.6343 -123.747276)
		(width 0.089408)
		(layer "In4.Cu")
		(net "SMB_DEBUG_STBY_LVC3_SCL")
	)
	(segment
		(start 419.886638 -44.377356)
		(end 418.959284 -44.377356)
		(width 0.089408)
		(layer "In4.Cu")
		(net "SMB_DEBUG_STBY_LVC3_SCL")
	)
	(segment
		(start 478.70491 -122.676666)
		(end 478.70491 -118.23319)
		(width 0.089408)
		(layer "In4.Cu")
		(net "SMB_DEBUG_STBY_LVC3_SCL")
	)
	(segment
		(start 434.47208 -41.10228)
		(end 433.330858 -41.10228)
		(width 0.089408)
		(layer "In4.Cu")
		(net "SMB_DEBUG_STBY_LVC3_SCL")
	)
	(segment
		(start 428.13605 -40.045386)
		(end 428.055278 -40.126158)
		(width 0.089408)
		(layer "In4.Cu")
		(net "SMB_DEBUG_STBY_LVC3_SCL")
	)
	(segment
		(start 476.999808 -116.528088)
		(end 471.92565 -116.528088)
		(width 0.089408)
		(layer "In4.Cu")
		(net "SMB_DEBUG_STBY_LVC3_SCL")
	)
	(segment
		(start 468.519256 -44.78909)
		(end 467.450678 -44.78909)
		(width 0.089408)
		(layer "In4.Cu")
		(net "SMB_DEBUG_STBY_LVC3_SCL")
	)
	(segment
		(start 430.835054 -40.439594)
		(end 430.233328 -40.439594)
		(width 0.089408)
		(layer "In4.Cu")
		(net "SMB_DEBUG_STBY_LVC3_SCL")
	)
	(segment
		(start 478.70491 -118.23319)
		(end 476.999808 -116.528088)
		(width 0.089408)
		(layer "In4.Cu")
		(net "SMB_DEBUG_STBY_LVC3_SCL")
	)
	(segment
		(start 418.52342 -44.567602)
		(end 411.673548 -44.567602)
		(width 0.089408)
		(layer "In4.Cu")
		(net "SMB_DEBUG_STBY_LVC3_SCL")
	)
	(segment
		(start 428.055024 -40.126158)
		(end 426.11294 -42.068242)
		(width 0.089408)
		(layer "In4.Cu")
		(net "SMB_DEBUG_STBY_LVC3_SCL")
	)
	(segment
		(start 459.102206 -44.026582)
		(end 458.065124 -42.9895)
		(width 0.089408)
		(layer "In4.Cu")
		(net "SMB_DEBUG_STBY_LVC3_SCL")
	)
	(segment
		(start 399.796 -39.356284)
		(end 399.796 -38.6334)
		(width 0.089408)
		(layer "In4.Cu")
		(net "SMB_DEBUG_STBY_LVC3_SCL")
	)
	(segment
		(start 472.339416 -54.154324)
		(end 471.739468 -54.154324)
		(width 0.089408)
		(layer "In4.Cu")
		(net "SMB_DEBUG_STBY_LVC3_SCL")
	)
	(segment
		(start 471.739468 -54.154324)
		(end 469.9 -52.314856)
		(width 0.089408)
		(layer "In4.Cu")
		(net "SMB_DEBUG_STBY_LVC3_SCL")
	)
	(segment
		(start 418.959284 -44.377356)
		(end 418.769038 -44.567602)
		(width 0.089408)
		(layer "In4.Cu")
		(net "SMB_DEBUG_STBY_LVC3_SCL")
	)
	(segment
		(start 467.450678 -44.78909)
		(end 466.68817 -44.026582)
		(width 0.089408)
		(layer "In4.Cu")
		(net "SMB_DEBUG_STBY_LVC3_SCL")
	)
	(segment
		(start 455.5363 -42.9895)
		(end 454.7108 -42.164)
		(width 0.089408)
		(layer "In4.Cu")
		(net "SMB_DEBUG_STBY_LVC3_SCL")
	)
	(segment
		(start 471.92565 -116.528088)
		(end 468.014558 -112.616996)
		(width 0.089408)
		(layer "In4.Cu")
		(net "SMB_DEBUG_STBY_LVC3_SCL")
	)
	(segment
		(start 426.11294 -42.068242)
		(end 424.106848 -42.068242)
		(width 0.089408)
		(layer "In4.Cu")
		(net "SMB_DEBUG_STBY_LVC3_SCL")
	)
	(segment
		(start 472.3257 -54.16804)
		(end 472.3257 -54.506876)
		(width 0.089408)
		(layer "In9.Cu")
		(net "SMB_DEBUG_STBY_LVC3_SCL")
	)
	(segment
		(start 476.973138 -57.986422)
		(end 476.973138 -64.238886)
		(width 0.089408)
		(layer "In9.Cu")
		(net "SMB_DEBUG_STBY_LVC3_SCL")
	)
	(segment
		(start 476.973138 -64.238886)
		(end 474.049344 -67.16268)
		(width 0.089408)
		(layer "In9.Cu")
		(net "SMB_DEBUG_STBY_LVC3_SCL")
	)
	(segment
		(start 474.049344 -67.16268)
		(end 427.268894 -67.16268)
		(width 0.089408)
		(layer "In9.Cu")
		(net "SMB_DEBUG_STBY_LVC3_SCL")
	)
	(segment
		(start 473.097606 -55.278782)
		(end 474.265498 -55.278782)
		(width 0.089408)
		(layer "In9.Cu")
		(net "SMB_DEBUG_STBY_LVC3_SCL")
	)
	(segment
		(start 472.3257 -54.506876)
		(end 473.097606 -55.278782)
		(width 0.089408)
		(layer "In9.Cu")
		(net "SMB_DEBUG_STBY_LVC3_SCL")
	)
	(segment
		(start 426.304456 -75.88885)
		(end 426.30725 -75.88885)
		(width 0.089408)
		(layer "In9.Cu")
		(net "SMB_DEBUG_STBY_LVC3_SCL")
	)
	(segment
		(start 474.265498 -55.278782)
		(end 476.973138 -57.986422)
		(width 0.089408)
		(layer "In9.Cu")
		(net "SMB_DEBUG_STBY_LVC3_SCL")
	)
	(segment
		(start 425.680378 -75.264772)
		(end 426.304456 -75.88885)
		(width 0.089408)
		(layer "In9.Cu")
		(net "SMB_DEBUG_STBY_LVC3_SCL")
	)
	(segment
		(start 472.339416 -54.154324)
		(end 472.3257 -54.16804)
		(width 0.089408)
		(layer "In9.Cu")
		(net "SMB_DEBUG_STBY_LVC3_SCL")
	)
	(segment
		(start 427.268894 -67.16268)
		(end 425.680378 -68.751196)
		(width 0.089408)
		(layer "In9.Cu")
		(net "SMB_DEBUG_STBY_LVC3_SCL")
	)
	(segment
		(start 426.30725 -75.88885)
		(end 426.4914 -76.073)
		(width 0.089408)
		(layer "In9.Cu")
		(net "SMB_DEBUG_STBY_LVC3_SCL")
	)
	(segment
		(start 425.680378 -68.751196)
		(end 425.680378 -75.264772)
		(width 0.089408)
		(layer "In9.Cu")
		(net "SMB_DEBUG_STBY_LVC3_SCL")
	)
	(via
		(at 448.2846 -23.3172)
		(size 0.6604)
		(drill 0.3302)
		(layers "F.Cu" "B.Cu")
		(net "SMB_HOST_STBY_LVC3_SDA_R3")
	)
	(segment
		(start 450.5325 -22.733)
		(end 452.2978 -22.733)
		(width 0.1016)
		(layer "B.Cu")
		(net "SMB_HOST_STBY_LVC3_SDA_R3")
	)
	(segment
		(start 450.3928 -23.3172)
		(end 450.5325 -23.1775)
		(width 0.10795)
		(layer "B.Cu")
		(net "SMB_HOST_STBY_LVC3_SDA_R3")
	)
	(segment
		(start 448.2846 -23.3172)
		(end 450.3928 -23.3172)
		(width 0.10795)
		(layer "B.Cu")
		(net "SMB_HOST_STBY_LVC3_SDA_R3")
	)
	(segment
		(start 450.5325 -23.1775)
		(end 450.5325 -22.733)
		(width 0.10795)
		(layer "B.Cu")
		(net "SMB_HOST_STBY_LVC3_SDA_R3")
	)
	(via
		(at 448.2846 -24.638)
		(size 0.6604)
		(drill 0.3302)
		(layers "F.Cu" "B.Cu")
		(net "SMB_HOST_STBY_LVC3_SCL_R3")
	)
	(segment
		(start 450.5325 -24.4475)
		(end 450.5325 -24.003)
		(width 0.10795)
		(layer "B.Cu")
		(net "SMB_HOST_STBY_LVC3_SCL_R3")
	)
	(segment
		(start 450.342 -24.638)
		(end 450.5325 -24.4475)
		(width 0.10795)
		(layer "B.Cu")
		(net "SMB_HOST_STBY_LVC3_SCL_R3")
	)
	(segment
		(start 448.2846 -24.638)
		(end 450.342 -24.638)
		(width 0.10795)
		(layer "B.Cu")
		(net "SMB_HOST_STBY_LVC3_SCL_R3")
	)
	(segment
		(start 450.5325 -24.003)
		(end 452.2978 -24.003)
		(width 0.1016)
		(layer "B.Cu")
		(net "SMB_HOST_STBY_LVC3_SCL_R3")
	)
	(via
		(at 448.31 -25.908)
		(size 0.6604)
		(drill 0.3302)
		(layers "F.Cu" "B.Cu")
		(net "PD_ID_EEPROM_WP")
	)
	(segment
		(start 448.31 -25.908)
		(end 450.0118 -25.908)
		(width 0.1016)
		(layer "B.Cu")
		(net "PD_ID_EEPROM_WP")
	)
	(segment
		(start 450.5325 -25.273)
		(end 452.2978 -25.273)
		(width 0.1016)
		(layer "B.Cu")
		(net "PD_ID_EEPROM_WP")
	)
	(segment
		(start 450.5325 -25.3873)
		(end 450.5325 -25.273)
		(width 0.1016)
		(layer "B.Cu")
		(net "PD_ID_EEPROM_WP")
	)
	(segment
		(start 450.0118 -25.908)
		(end 450.5325 -25.3873)
		(width 0.1016)
		(layer "B.Cu")
		(net "PD_ID_EEPROM_WP")
	)
	(segment
		(start 408.690064 -31.33471)
		(end 408.290014 -30.93466)
		(width 0.254)
		(layer "F.Cu")
		(net "P3V3_USB2A_ALG")
	)
	(via
		(at 399.572734 -30.644846)
		(size 0.508)
		(drill 0.254)
		(layers "F.Cu" "B.Cu")
		(net "P3V3_USB2A_ALG")
	)
	(via
		(at 408.290014 -30.93466)
		(size 0.4572)
		(drill 0.2032)
		(layers "F.Cu" "B.Cu")
		(net "P3V3_USB2A_ALG")
	)
	(segment
		(start 401.361656 -31.000446)
		(end 401.412456 -31.000446)
		(width 0.381)
		(layer "B.Cu")
		(net "P3V3_USB2A_ALG")
	)
	(segment
		(start 399.664936 -30.737048)
		(end 399.979896 -30.737048)
		(width 0.508)
		(layer "B.Cu")
		(net "P3V3_USB2A_ALG")
	)
	(segment
		(start 402.606256 -31.000446)
		(end 401.412456 -31.000446)
		(width 0.381)
		(layer "B.Cu")
		(net "P3V3_USB2A_ALG")
	)
	(segment
		(start 399.979896 -30.737048)
		(end 400.049746 -30.806898)
		(width 0.508)
		(layer "B.Cu")
		(net "P3V3_USB2A_ALG")
	)
	(segment
		(start 400.409156 -30.806898)
		(end 401.168108 -30.806898)
		(width 0.508)
		(layer "B.Cu")
		(net "P3V3_USB2A_ALG")
	)
	(segment
		(start 401.168108 -30.806898)
		(end 401.361656 -31.000446)
		(width 0.508)
		(layer "B.Cu")
		(net "P3V3_USB2A_ALG")
	)
	(segment
		(start 399.572734 -30.644846)
		(end 399.664936 -30.737048)
		(width 0.508)
		(layer "B.Cu")
		(net "P3V3_USB2A_ALG")
	)
	(segment
		(start 400.049746 -30.806898)
		(end 400.409156 -30.806898)
		(width 0.508)
		(layer "B.Cu")
		(net "P3V3_USB2A_ALG")
	)
	(segment
		(start 405.551894 -31.756096)
		(end 406.609804 -31.756096)
		(width 0.508)
		(layer "In4.Cu")
		(net "P3V3_USB2A_ALG")
	)
	(segment
		(start 402.707348 -31.238952)
		(end 403.078442 -31.610046)
		(width 0.508)
		(layer "In4.Cu")
		(net "P3V3_USB2A_ALG")
	)
	(segment
		(start 403.078442 -31.610046)
		(end 405.405844 -31.610046)
		(width 0.508)
		(layer "In4.Cu")
		(net "P3V3_USB2A_ALG")
	)
	(segment
		(start 400.16684 -31.238952)
		(end 402.707348 -31.238952)
		(width 0.508)
		(layer "In4.Cu")
		(net "P3V3_USB2A_ALG")
	)
	(segment
		(start 406.609804 -31.756096)
		(end 407.43124 -30.93466)
		(width 0.508)
		(layer "In4.Cu")
		(net "P3V3_USB2A_ALG")
	)
	(segment
		(start 405.405844 -31.610046)
		(end 405.551894 -31.756096)
		(width 0.508)
		(layer "In4.Cu")
		(net "P3V3_USB2A_ALG")
	)
	(segment
		(start 399.572734 -30.644846)
		(end 400.16684 -31.238952)
		(width 0.508)
		(layer "In4.Cu")
		(net "P3V3_USB2A_ALG")
	)
	(segment
		(start 407.43124 -30.93466)
		(end 408.290014 -30.93466)
		(width 0.508)
		(layer "In4.Cu")
		(net "P3V3_USB2A_ALG")
	)
	(segment
		(start 417.490148 -40.13454)
		(end 417.890198 -40.53459)
		(width 0.10795)
		(layer "F.Cu")
		(net "HSC_SMBUS_SWITCH_EN")
	)
	(via
		(at 417.890198 -40.53459)
		(size 0.4572)
		(drill 0.2032)
		(layers "F.Cu" "B.Cu")
		(net "HSC_SMBUS_SWITCH_EN")
	)
	(via
		(at 398.761204 -78.248256)
		(size 0.508)
		(drill 0.254)
		(layers "F.Cu" "B.Cu")
		(net "HSC_SMBUS_SWITCH_EN")
	)
	(via
		(at 400.346672 -79.586328)
		(size 0.6604)
		(drill 0.3302)
		(layers "F.Cu" "B.Cu")
		(net "HSC_SMBUS_SWITCH_EN")
	)
	(segment
		(start 404.233634 -78.54442)
		(end 404.6474 -78.130654)
		(width 0.10795)
		(layer "B.Cu")
		(net "HSC_SMBUS_SWITCH_EN")
	)
	(segment
		(start 398.761204 -78.492604)
		(end 398.761204 -78.248256)
		(width 0.10795)
		(layer "B.Cu")
		(net "HSC_SMBUS_SWITCH_EN")
	)
	(segment
		(start 403.606 -77.64272)
		(end 402.62048 -77.64272)
		(width 0.10795)
		(layer "B.Cu")
		(net "HSC_SMBUS_SWITCH_EN")
	)
	(segment
		(start 400.676872 -79.586328)
		(end 400.346672 -79.586328)
		(width 0.10795)
		(layer "B.Cu")
		(net "HSC_SMBUS_SWITCH_EN")
	)
	(segment
		(start 404.53945 -77.64272)
		(end 403.606 -77.64272)
		(width 0.10795)
		(layer "B.Cu")
		(net "HSC_SMBUS_SWITCH_EN")
	)
	(segment
		(start 402.62048 -77.64272)
		(end 400.676872 -79.586328)
		(width 0.10795)
		(layer "B.Cu")
		(net "HSC_SMBUS_SWITCH_EN")
	)
	(segment
		(start 404.233634 -79.235808)
		(end 404.233634 -78.54442)
		(width 0.10795)
		(layer "B.Cu")
		(net "HSC_SMBUS_SWITCH_EN")
	)
	(segment
		(start 398.78 -78.5114)
		(end 398.761204 -78.492604)
		(width 0.10795)
		(layer "B.Cu")
		(net "HSC_SMBUS_SWITCH_EN")
	)
	(segment
		(start 404.6474 -78.130654)
		(end 404.6474 -77.75067)
		(width 0.10795)
		(layer "B.Cu")
		(net "HSC_SMBUS_SWITCH_EN")
	)
	(segment
		(start 404.6474 -77.75067)
		(end 404.53945 -77.64272)
		(width 0.10795)
		(layer "B.Cu")
		(net "HSC_SMBUS_SWITCH_EN")
	)
	(segment
		(start 399.881598 -79.586328)
		(end 398.80667 -78.5114)
		(width 0.10795)
		(layer "B.Cu")
		(net "HSC_SMBUS_SWITCH_EN")
	)
	(segment
		(start 398.80667 -78.5114)
		(end 398.78 -78.5114)
		(width 0.10795)
		(layer "B.Cu")
		(net "HSC_SMBUS_SWITCH_EN")
	)
	(segment
		(start 400.346672 -79.586328)
		(end 399.881598 -79.586328)
		(width 0.10795)
		(layer "B.Cu")
		(net "HSC_SMBUS_SWITCH_EN")
	)
	(segment
		(start 416.16884 -40.909494)
		(end 415.865056 -41.213278)
		(width 0.089408)
		(layer "In9.Cu")
		(net "HSC_SMBUS_SWITCH_EN")
	)
	(segment
		(start 406.975564 -49.787302)
		(end 406.975564 -51.873404)
		(width 0.089408)
		(layer "In9.Cu")
		(net "HSC_SMBUS_SWITCH_EN")
	)
	(segment
		(start 402.293328 -71.91121)
		(end 401.969732 -71.587614)
		(width 0.089408)
		(layer "In9.Cu")
		(net "HSC_SMBUS_SWITCH_EN")
	)
	(segment
		(start 415.865056 -41.490138)
		(end 415.6456 -41.709594)
		(width 0.089408)
		(layer "In9.Cu")
		(net "HSC_SMBUS_SWITCH_EN")
	)
	(segment
		(start 400.214084 -76.679044)
		(end 399.100802 -77.792326)
		(width 0.089408)
		(layer "In9.Cu")
		(net "HSC_SMBUS_SWITCH_EN")
	)
	(segment
		(start 405.349456 -66.466974)
		(end 405.345646 -66.470784)
		(width 0.089408)
		(layer "In9.Cu")
		(net "HSC_SMBUS_SWITCH_EN")
	)
	(segment
		(start 414.034224 -43.974512)
		(end 412.45282 -45.555916)
		(width 0.089408)
		(layer "In9.Cu")
		(net "HSC_SMBUS_SWITCH_EN")
	)
	(segment
		(start 405.23795 -61.011054)
		(end 404.36038 -61.888624)
		(width 0.089408)
		(layer "In9.Cu")
		(net "HSC_SMBUS_SWITCH_EN")
	)
	(segment
		(start 417.515548 -40.90924)
		(end 417.2458 -40.90924)
		(width 0.089408)
		(layer "In9.Cu")
		(net "HSC_SMBUS_SWITCH_EN")
	)
	(segment
		(start 405.34971 -64.77889)
		(end 405.34971 -65.328038)
		(width 0.089408)
		(layer "In9.Cu")
		(net "HSC_SMBUS_SWITCH_EN")
	)
	(segment
		(start 399.100802 -77.792326)
		(end 399.100802 -77.908658)
		(width 0.089408)
		(layer "In9.Cu")
		(net "HSC_SMBUS_SWITCH_EN")
	)
	(segment
		(start 405.793448 -53.05552)
		(end 405.793448 -59.0804)
		(width 0.089408)
		(layer "In9.Cu")
		(net "HSC_SMBUS_SWITCH_EN")
	)
	(segment
		(start 400.214084 -73.620122)
		(end 400.214084 -76.679044)
		(width 0.089408)
		(layer "In9.Cu")
		(net "HSC_SMBUS_SWITCH_EN")
	)
	(segment
		(start 405.34971 -65.328038)
		(end 405.349964 -65.328292)
		(width 0.089408)
		(layer "In9.Cu")
		(net "HSC_SMBUS_SWITCH_EN")
	)
	(segment
		(start 399.100802 -77.908658)
		(end 398.761204 -78.248256)
		(width 0.089408)
		(layer "In9.Cu")
		(net "HSC_SMBUS_SWITCH_EN")
	)
	(segment
		(start 405.349964 -65.328292)
		(end 405.349964 -65.86728)
		(width 0.089408)
		(layer "In9.Cu")
		(net "HSC_SMBUS_SWITCH_EN")
	)
	(segment
		(start 405.345646 -66.471038)
		(end 402.931376 -68.885308)
		(width 0.089408)
		(layer "In9.Cu")
		(net "HSC_SMBUS_SWITCH_EN")
	)
	(segment
		(start 410.094176 -46.31563)
		(end 406.947116 -46.31563)
		(width 0.089408)
		(layer "In9.Cu")
		(net "HSC_SMBUS_SWITCH_EN")
	)
	(segment
		(start 414.034224 -42.982642)
		(end 414.034224 -43.974512)
		(width 0.089408)
		(layer "In9.Cu")
		(net "HSC_SMBUS_SWITCH_EN")
	)
	(segment
		(start 416.445954 -40.90924)
		(end 416.4457 -40.909494)
		(width 0.089408)
		(layer "In9.Cu")
		(net "HSC_SMBUS_SWITCH_EN")
	)
	(segment
		(start 405.23795 -59.635898)
		(end 405.23795 -61.011054)
		(width 0.089408)
		(layer "In9.Cu")
		(net "HSC_SMBUS_SWITCH_EN")
	)
	(segment
		(start 404.36038 -61.888624)
		(end 404.36038 -63.12916)
		(width 0.089408)
		(layer "In9.Cu")
		(net "HSC_SMBUS_SWITCH_EN")
	)
	(segment
		(start 406.493726 -47.466758)
		(end 407.138886 -48.111918)
		(width 0.089408)
		(layer "In9.Cu")
		(net "HSC_SMBUS_SWITCH_EN")
	)
	(segment
		(start 416.4457 -40.909494)
		(end 416.16884 -40.909494)
		(width 0.089408)
		(layer "In9.Cu")
		(net "HSC_SMBUS_SWITCH_EN")
	)
	(segment
		(start 415.6456 -41.709594)
		(end 415.307272 -41.709594)
		(width 0.089408)
		(layer "In9.Cu")
		(net "HSC_SMBUS_SWITCH_EN")
	)
	(segment
		(start 416.93465 -40.909494)
		(end 416.934396 -40.90924)
		(width 0.089408)
		(layer "In9.Cu")
		(net "HSC_SMBUS_SWITCH_EN")
	)
	(segment
		(start 404.85568 -63.62446)
		(end 404.85568 -64.28486)
		(width 0.089408)
		(layer "In9.Cu")
		(net "HSC_SMBUS_SWITCH_EN")
	)
	(segment
		(start 416.934396 -40.90924)
		(end 416.445954 -40.90924)
		(width 0.089408)
		(layer "In9.Cu")
		(net "HSC_SMBUS_SWITCH_EN")
	)
	(segment
		(start 407.138886 -48.111918)
		(end 407.138886 -49.62398)
		(width 0.089408)
		(layer "In9.Cu")
		(net "HSC_SMBUS_SWITCH_EN")
	)
	(segment
		(start 405.349964 -65.86728)
		(end 405.349456 -65.867788)
		(width 0.089408)
		(layer "In9.Cu")
		(net "HSC_SMBUS_SWITCH_EN")
	)
	(segment
		(start 417.890198 -40.53459)
		(end 417.515548 -40.90924)
		(width 0.089408)
		(layer "In9.Cu")
		(net "HSC_SMBUS_SWITCH_EN")
	)
	(segment
		(start 405.349456 -65.867788)
		(end 405.349456 -66.466974)
		(width 0.089408)
		(layer "In9.Cu")
		(net "HSC_SMBUS_SWITCH_EN")
	)
	(segment
		(start 406.947116 -46.31563)
		(end 406.493726 -46.76902)
		(width 0.089408)
		(layer "In9.Cu")
		(net "HSC_SMBUS_SWITCH_EN")
	)
	(segment
		(start 404.85568 -64.28486)
		(end 405.34971 -64.77889)
		(width 0.089408)
		(layer "In9.Cu")
		(net "HSC_SMBUS_SWITCH_EN")
	)
	(segment
		(start 402.667216 -71.91121)
		(end 402.293328 -71.91121)
		(width 0.089408)
		(layer "In9.Cu")
		(net "HSC_SMBUS_SWITCH_EN")
	)
	(segment
		(start 401.071842 -71.587614)
		(end 400.507454 -72.152002)
		(width 0.089408)
		(layer "In9.Cu")
		(net "HSC_SMBUS_SWITCH_EN")
	)
	(segment
		(start 415.865056 -41.213278)
		(end 415.865056 -41.490138)
		(width 0.089408)
		(layer "In9.Cu")
		(net "HSC_SMBUS_SWITCH_EN")
	)
	(segment
		(start 405.345646 -66.470784)
		(end 405.345646 -66.471038)
		(width 0.089408)
		(layer "In9.Cu")
		(net "HSC_SMBUS_SWITCH_EN")
	)
	(segment
		(start 405.793448 -59.0804)
		(end 405.23795 -59.635898)
		(width 0.089408)
		(layer "In9.Cu")
		(net "HSC_SMBUS_SWITCH_EN")
	)
	(segment
		(start 402.931376 -68.885308)
		(end 402.931376 -71.64705)
		(width 0.089408)
		(layer "In9.Cu")
		(net "HSC_SMBUS_SWITCH_EN")
	)
	(segment
		(start 417.2458 -40.90924)
		(end 417.245546 -40.909494)
		(width 0.089408)
		(layer "In9.Cu")
		(net "HSC_SMBUS_SWITCH_EN")
	)
	(segment
		(start 417.245546 -40.909494)
		(end 416.93465 -40.909494)
		(width 0.089408)
		(layer "In9.Cu")
		(net "HSC_SMBUS_SWITCH_EN")
	)
	(segment
		(start 402.931376 -71.64705)
		(end 402.667216 -71.91121)
		(width 0.089408)
		(layer "In9.Cu")
		(net "HSC_SMBUS_SWITCH_EN")
	)
	(segment
		(start 400.507454 -73.326752)
		(end 400.214084 -73.620122)
		(width 0.089408)
		(layer "In9.Cu")
		(net "HSC_SMBUS_SWITCH_EN")
	)
	(segment
		(start 410.85389 -45.555916)
		(end 410.094176 -46.31563)
		(width 0.089408)
		(layer "In9.Cu")
		(net "HSC_SMBUS_SWITCH_EN")
	)
	(segment
		(start 406.493726 -46.76902)
		(end 406.493726 -47.466758)
		(width 0.089408)
		(layer "In9.Cu")
		(net "HSC_SMBUS_SWITCH_EN")
	)
	(segment
		(start 406.975564 -51.873404)
		(end 405.793448 -53.05552)
		(width 0.089408)
		(layer "In9.Cu")
		(net "HSC_SMBUS_SWITCH_EN")
	)
	(segment
		(start 404.36038 -63.12916)
		(end 404.85568 -63.62446)
		(width 0.089408)
		(layer "In9.Cu")
		(net "HSC_SMBUS_SWITCH_EN")
	)
	(segment
		(start 407.138886 -49.62398)
		(end 406.975564 -49.787302)
		(width 0.089408)
		(layer "In9.Cu")
		(net "HSC_SMBUS_SWITCH_EN")
	)
	(segment
		(start 401.969732 -71.587614)
		(end 401.071842 -71.587614)
		(width 0.089408)
		(layer "In9.Cu")
		(net "HSC_SMBUS_SWITCH_EN")
	)
	(segment
		(start 412.45282 -45.555916)
		(end 410.85389 -45.555916)
		(width 0.089408)
		(layer "In9.Cu")
		(net "HSC_SMBUS_SWITCH_EN")
	)
	(segment
		(start 400.507454 -72.152002)
		(end 400.507454 -73.326752)
		(width 0.089408)
		(layer "In9.Cu")
		(net "HSC_SMBUS_SWITCH_EN")
	)
	(segment
		(start 415.307272 -41.709594)
		(end 414.034224 -42.982642)
		(width 0.089408)
		(layer "In9.Cu")
		(net "HSC_SMBUS_SWITCH_EN")
	)
	(via
		(at 443.3951 -23.3299)
		(size 0.6604)
		(drill 0.3302)
		(layers "F.Cu" "B.Cu")
		(net "FM_TPM_PRES_RST_N_R")
	)
	(segment
		(start 442.8871 -21.3233)
		(end 442.8871 -20.8788)
		(width 0.10795)
		(layer "B.Cu")
		(net "FM_TPM_PRES_RST_N_R")
	)
	(segment
		(start 443.3951 -22.3393)
		(end 443.3951 -23.3299)
		(width 0.10795)
		(layer "B.Cu")
		(net "FM_TPM_PRES_RST_N_R")
	)
	(segment
		(start 443.3951 -22.3393)
		(end 443.3951 -21.8313)
		(width 0.10795)
		(layer "B.Cu")
		(net "FM_TPM_PRES_RST_N_R")
	)
	(segment
		(start 443.3951 -21.8313)
		(end 442.8871 -21.3233)
		(width 0.10795)
		(layer "B.Cu")
		(net "FM_TPM_PRES_RST_N_R")
	)
	(segment
		(start 418.079936 -44.109132)
		(end 418.079936 -43.617388)
		(width 0.10795)
		(layer "F.Cu")
		(net "FM_BMC_ONCTL_R_N")
	)
	(segment
		(start 418.554408 -47.846234)
		(end 418.779706 -47.620936)
		(width 0.10795)
		(layer "F.Cu")
		(net "FM_BMC_ONCTL_R_N")
	)
	(segment
		(start 419.095682 -46.15434)
		(end 419.09492 -46.153578)
		(width 0.10795)
		(layer "F.Cu")
		(net "FM_BMC_ONCTL_R_N")
	)
	(segment
		(start 419.09492 -46.153578)
		(end 419.09492 -45.968158)
		(width 0.10795)
		(layer "F.Cu")
		(net "FM_BMC_ONCTL_R_N")
	)
	(segment
		(start 418.779706 -47.067216)
		(end 419.095682 -46.75124)
		(width 0.10795)
		(layer "F.Cu")
		(net "FM_BMC_ONCTL_R_N")
	)
	(segment
		(start 417.944046 -42.988484)
		(end 417.490148 -42.534586)
		(width 0.10795)
		(layer "F.Cu")
		(net "FM_BMC_ONCTL_R_N")
	)
	(segment
		(start 418.779706 -47.620936)
		(end 418.779706 -47.067216)
		(width 0.10795)
		(layer "F.Cu")
		(net "FM_BMC_ONCTL_R_N")
	)
	(segment
		(start 418.080952 -43.616372)
		(end 418.080952 -43.614848)
		(width 0.10795)
		(layer "F.Cu")
		(net "FM_BMC_ONCTL_R_N")
	)
	(segment
		(start 418.554408 -48.064166)
		(end 418.554408 -47.846234)
		(width 0.10795)
		(layer "F.Cu")
		(net "FM_BMC_ONCTL_R_N")
	)
	(segment
		(start 419.095682 -46.75124)
		(end 419.095682 -46.15434)
		(width 0.10795)
		(layer "F.Cu")
		(net "FM_BMC_ONCTL_R_N")
	)
	(segment
		(start 418.779706 -45.19549)
		(end 418.628322 -45.044106)
		(width 0.10795)
		(layer "F.Cu")
		(net "FM_BMC_ONCTL_R_N")
	)
	(segment
		(start 419.09492 -45.968158)
		(end 418.779706 -45.652944)
		(width 0.10795)
		(layer "F.Cu")
		(net "FM_BMC_ONCTL_R_N")
	)
	(segment
		(start 418.080952 -44.110148)
		(end 418.079936 -44.109132)
		(width 0.10795)
		(layer "F.Cu")
		(net "FM_BMC_ONCTL_R_N")
	)
	(segment
		(start 418.080952 -43.614848)
		(end 417.944046 -43.477942)
		(width 0.10795)
		(layer "F.Cu")
		(net "FM_BMC_ONCTL_R_N")
	)
	(segment
		(start 418.628322 -45.044106)
		(end 418.080952 -44.496736)
		(width 0.10795)
		(layer "F.Cu")
		(net "FM_BMC_ONCTL_R_N")
	)
	(segment
		(start 419.316408 -48.064166)
		(end 418.554408 -48.064166)
		(width 0.10795)
		(layer "F.Cu")
		(net "FM_BMC_ONCTL_R_N")
	)
	(segment
		(start 418.080952 -44.496736)
		(end 418.080952 -44.110148)
		(width 0.10795)
		(layer "F.Cu")
		(net "FM_BMC_ONCTL_R_N")
	)
	(segment
		(start 418.079936 -43.617388)
		(end 418.080952 -43.616372)
		(width 0.10795)
		(layer "F.Cu")
		(net "FM_BMC_ONCTL_R_N")
	)
	(segment
		(start 418.779706 -45.652944)
		(end 418.779706 -45.19549)
		(width 0.10795)
		(layer "F.Cu")
		(net "FM_BMC_ONCTL_R_N")
	)
	(segment
		(start 417.944046 -43.477942)
		(end 417.944046 -42.988484)
		(width 0.10795)
		(layer "F.Cu")
		(net "FM_BMC_ONCTL_R_N")
	)
	(via
		(at 418.628322 -45.044106)
		(size 0.508)
		(drill 0.254)
		(layers "F.Cu" "B.Cu")
		(net "FM_BMC_ONCTL_R_N")
	)
	(segment
		(start 423.92854 -41.73474)
		(end 423.890186 -41.73474)
		(width 0.10795)
		(layer "F.Cu")
		(net "FM_BMC_NMI_N_R")
	)
	(segment
		(start 424.692826 -42.930826)
		(end 424.5102 -42.7482)
		(width 0.10795)
		(layer "F.Cu")
		(net "FM_BMC_NMI_N_R")
	)
	(segment
		(start 426.3136 -45.6184)
		(end 426.39996 -45.70476)
		(width 0.10795)
		(layer "F.Cu")
		(net "FM_BMC_NMI_N_R")
	)
	(segment
		(start 424.5102 -42.3164)
		(end 423.92854 -41.73474)
		(width 0.10795)
		(layer "F.Cu")
		(net "FM_BMC_NMI_N_R")
	)
	(segment
		(start 424.692826 -44.847764)
		(end 424.692826 -42.930826)
		(width 0.10795)
		(layer "F.Cu")
		(net "FM_BMC_NMI_N_R")
	)
	(segment
		(start 424.5102 -42.7482)
		(end 424.5102 -42.3164)
		(width 0.10795)
		(layer "F.Cu")
		(net "FM_BMC_NMI_N_R")
	)
	(segment
		(start 426.681646 -47.843186)
		(end 426.681646 -48.079152)
		(width 0.10795)
		(layer "F.Cu")
		(net "FM_BMC_NMI_N_R")
	)
	(segment
		(start 426.3136 -45.6184)
		(end 425.463462 -45.6184)
		(width 0.10795)
		(layer "F.Cu")
		(net "FM_BMC_NMI_N_R")
	)
	(segment
		(start 426.39996 -45.70476)
		(end 426.39996 -47.5615)
		(width 0.10795)
		(layer "F.Cu")
		(net "FM_BMC_NMI_N_R")
	)
	(segment
		(start 425.463462 -45.6184)
		(end 424.692826 -44.847764)
		(width 0.10795)
		(layer "F.Cu")
		(net "FM_BMC_NMI_N_R")
	)
	(segment
		(start 426.39996 -47.5615)
		(end 426.681646 -47.843186)
		(width 0.10795)
		(layer "F.Cu")
		(net "FM_BMC_NMI_N_R")
	)
	(via
		(at 426.3136 -45.6184)
		(size 0.762)
		(drill 0.381)
		(layers "F.Cu" "B.Cu")
		(net "FM_BMC_NMI_N_R")
	)
	(via
		(at 446.375282 -16.002508)
		(size 0.6604)
		(drill 0.3302)
		(layers "F.Cu" "B.Cu")
		(net "VREF_2V2")
	)
	(segment
		(start 447.9036 -17.777968)
		(end 447.8782 -17.752568)
		(width 0.1016)
		(layer "B.Cu")
		(net "VREF_2V2")
	)
	(segment
		(start 447.8782 -17.752568)
		(end 447.8782 -17.3482)
		(width 0.1016)
		(layer "B.Cu")
		(net "VREF_2V2")
	)
	(segment
		(start 447.8655 -18.794476)
		(end 447.9036 -18.756376)
		(width 0.1016)
		(layer "B.Cu")
		(net "VREF_2V2")
	)
	(segment
		(start 447.9036 -18.1102)
		(end 447.9036 -17.777968)
		(width 0.1016)
		(layer "B.Cu")
		(net "VREF_2V2")
	)
	(segment
		(start 447.022728 -16.002508)
		(end 447.8782 -16.85798)
		(width 0.1016)
		(layer "B.Cu")
		(net "VREF_2V2")
	)
	(segment
		(start 446.375282 -16.002508)
		(end 447.022728 -16.002508)
		(width 0.1016)
		(layer "B.Cu")
		(net "VREF_2V2")
	)
	(segment
		(start 447.8655 -19.28876)
		(end 447.8655 -18.794476)
		(width 0.1016)
		(layer "B.Cu")
		(net "VREF_2V2")
	)
	(segment
		(start 447.9036 -18.756376)
		(end 447.9036 -18.1102)
		(width 0.1016)
		(layer "B.Cu")
		(net "VREF_2V2")
	)
	(segment
		(start 447.8782 -16.85798)
		(end 447.8782 -17.3482)
		(width 0.1016)
		(layer "B.Cu")
		(net "VREF_2V2")
	)
	(segment
		(start 413.090106 -31.73476)
		(end 412.690056 -31.33471)
		(width 0.254)
		(layer "F.Cu")
		(net "VCC_VA_3V3")
	)
	(segment
		(start 413.490156 -31.33471)
		(end 413.090106 -31.73476)
		(width 0.254)
		(layer "F.Cu")
		(net "VCC_VA_3V3")
	)
	(via
		(at 412.634938 -31.279592)
		(size 0.508)
		(drill 0.254)
		(layers "F.Cu" "B.Cu")
		(net "VCC_VA_3V3")
	)
	(via
		(at 413.090106 -31.73476)
		(size 0.4572)
		(drill 0.2032)
		(layers "F.Cu" "B.Cu")
		(net "VCC_VA_3V3")
	)
	(segment
		(start 412.634938 -31.270194)
		(end 411.324552 -29.959808)
		(width 0.4572)
		(layer "B.Cu")
		(net "VCC_VA_3V3")
	)
	(segment
		(start 411.1625 -27.813)
		(end 411.1625 -27.58948)
		(width 0.508)
		(layer "B.Cu")
		(net "VCC_VA_3V3")
	)
	(segment
		(start 411.299914 -29.103574)
		(end 411.324552 -29.128212)
		(width 0.508)
		(layer "B.Cu")
		(net "VCC_VA_3V3")
	)
	(segment
		(start 412.634938 -31.279592)
		(end 412.634938 -31.270194)
		(width 0.4572)
		(layer "B.Cu")
		(net "VCC_VA_3V3")
	)
	(segment
		(start 410.365194 -26.2382)
		(end 410.679646 -26.552652)
		(width 0.508)
		(layer "B.Cu")
		(net "VCC_VA_3V3")
	)
	(segment
		(start 409.3845 -26.035)
		(end 409.5877 -26.2382)
		(width 0.508)
		(layer "B.Cu")
		(net "VCC_VA_3V3")
	)
	(segment
		(start 411.324552 -29.128212)
		(end 411.324552 -29.55036)
		(width 0.508)
		(layer "B.Cu")
		(net "VCC_VA_3V3")
	)
	(segment
		(start 411.299914 -28.31846)
		(end 411.1625 -28.181046)
		(width 0.508)
		(layer "B.Cu")
		(net "VCC_VA_3V3")
	)
	(segment
		(start 411.299914 -28.73756)
		(end 411.299914 -28.31846)
		(width 0.508)
		(layer "B.Cu")
		(net "VCC_VA_3V3")
	)
	(segment
		(start 409.5877 -26.2382)
		(end 410.365194 -26.2382)
		(width 0.508)
		(layer "B.Cu")
		(net "VCC_VA_3V3")
	)
	(segment
		(start 411.299914 -28.73756)
		(end 411.299914 -29.103574)
		(width 0.508)
		(layer "B.Cu")
		(net "VCC_VA_3V3")
	)
	(segment
		(start 411.1625 -28.181046)
		(end 411.1625 -27.813)
		(width 0.508)
		(layer "B.Cu")
		(net "VCC_VA_3V3")
	)
	(segment
		(start 413.090106 -31.73476)
		(end 412.634938 -31.279592)
		(width 0.4572)
		(layer "B.Cu")
		(net "VCC_VA_3V3")
	)
	(segment
		(start 411.324552 -29.959808)
		(end 411.324552 -29.55036)
		(width 0.4572)
		(layer "B.Cu")
		(net "VCC_VA_3V3")
	)
	(segment
		(start 410.679646 -27.106626)
		(end 410.679646 -26.552652)
		(width 0.508)
		(layer "B.Cu")
		(net "VCC_VA_3V3")
	)
	(segment
		(start 411.1625 -27.58948)
		(end 410.679646 -27.106626)
		(width 0.508)
		(layer "B.Cu")
		(net "VCC_VA_3V3")
	)
	(segment
		(start 422.070022 -39.267892)
		(end 421.710358 -39.267892)
		(width 0.254)
		(layer "F.Cu")
		(net "VCC_PA_3V3")
	)
	(segment
		(start 419.090094 -34.534602)
		(end 419.489128 -34.933636)
		(width 0.3048)
		(layer "F.Cu")
		(net "VCC_PA_3V3")
	)
	(segment
		(start 422.29024 -39.334694)
		(end 422.29024 -39.334948)
		(width 0.254)
		(layer "F.Cu")
		(net "VCC_PA_3V3")
	)
	(segment
		(start 421.710358 -39.267892)
		(end 421.643556 -39.334694)
		(width 0.254)
		(layer "F.Cu")
		(net "VCC_PA_3V3")
	)
	(segment
		(start 422.136824 -39.334694)
		(end 422.070022 -39.267892)
		(width 0.254)
		(layer "F.Cu")
		(net "VCC_PA_3V3")
	)
	(segment
		(start 421.643556 -39.334694)
		(end 421.49014 -39.334694)
		(width 0.254)
		(layer "F.Cu")
		(net "VCC_PA_3V3")
	)
	(segment
		(start 422.29024 -39.334948)
		(end 422.690036 -39.734744)
		(width 0.254)
		(layer "F.Cu")
		(net "VCC_PA_3V3")
	)
	(segment
		(start 422.29024 -39.334694)
		(end 422.136824 -39.334694)
		(width 0.254)
		(layer "F.Cu")
		(net "VCC_PA_3V3")
	)
	(via
		(at 419.489128 -34.933636)
		(size 0.4572)
		(drill 0.2032)
		(layers "F.Cu" "B.Cu")
		(net "VCC_PA_3V3")
	)
	(via
		(at 427.14418 -43.16476)
		(size 0.6604)
		(drill 0.3302)
		(layers "F.Cu" "B.Cu")
		(net "VCC_PA_3V3")
	)
	(via
		(at 422.690036 -39.734744)
		(size 0.4572)
		(drill 0.2032)
		(layers "F.Cu" "B.Cu")
		(net "VCC_PA_3V3")
	)
	(segment
		(start 417.490148 -30.53461)
		(end 417.890198 -30.13456)
		(width 0.254)
		(layer "F.Cu")
		(net "VCC_D_3V3")
	)
	(segment
		(start 417.890198 -30.13456)
		(end 418.290248 -30.53461)
		(width 0.254)
		(layer "F.Cu")
		(net "VCC_D_3V3")
	)
	(segment
		(start 417.490148 -30.523688)
		(end 417.1061 -30.13964)
		(width 0.254)
		(layer "F.Cu")
		(net "VCC_D_3V3")
	)
	(segment
		(start 416.71113 -30.53461)
		(end 417.1061 -30.13964)
		(width 0.254)
		(layer "F.Cu")
		(net "VCC_D_3V3")
	)
	(segment
		(start 415.090102 -38.534594)
		(end 414.690052 -38.934644)
		(width 0.254)
		(layer "F.Cu")
		(net "VCC_D_3V3")
	)
	(segment
		(start 418.290248 -39.334694)
		(end 418.691822 -38.93312)
		(width 0.2032)
		(layer "F.Cu")
		(net "VCC_D_3V3")
	)
	(segment
		(start 411.09011 -37.734748)
		(end 411.49016 -37.334698)
		(width 0.254)
		(layer "F.Cu")
		(net "VCC_D_3V3")
	)
	(segment
		(start 411.889194 -38.534594)
		(end 411.89021 -38.534594)
		(width 0.3048)
		(layer "F.Cu")
		(net "VCC_D_3V3")
	)
	(segment
		(start 411.09011 -36.134548)
		(end 411.49016 -35.734498)
		(width 0.254)
		(layer "F.Cu")
		(net "VCC_D_3V3")
	)
	(segment
		(start 413.083502 -38.941248)
		(end 412.690056 -39.334694)
		(width 0.3556)
		(layer "F.Cu")
		(net "VCC_D_3V3")
	)
	(segment
		(start 417.090098 -38.934644)
		(end 416.690048 -39.334694)
		(width 0.254)
		(layer "F.Cu")
		(net "VCC_D_3V3")
	)
	(segment
		(start 411.5054 -38.1508)
		(end 411.889194 -38.534594)
		(width 0.3048)
		(layer "F.Cu")
		(net "VCC_D_3V3")
	)
	(segment
		(start 419.495224 -38.139878)
		(end 419.090094 -37.734748)
		(width 0.2032)
		(layer "F.Cu")
		(net "VCC_D_3V3")
	)
	(segment
		(start 418.691822 -38.93312)
		(end 419.265862 -38.93312)
		(width 0.2032)
		(layer "F.Cu")
		(net "VCC_D_3V3")
	)
	(segment
		(start 416.690048 -30.53461)
		(end 416.71113 -30.53461)
		(width 0.254)
		(layer "F.Cu")
		(net "VCC_D_3V3")
	)
	(segment
		(start 411.49016 -37.334698)
		(end 411.09011 -36.934648)
		(width 0.254)
		(layer "F.Cu")
		(net "VCC_D_3V3")
	)
	(segment
		(start 417.490148 -30.53461)
		(end 417.490148 -30.523688)
		(width 0.254)
		(layer "F.Cu")
		(net "VCC_D_3V3")
	)
	(segment
		(start 411.49016 -35.734498)
		(end 411.090364 -35.334702)
		(width 0.254)
		(layer "F.Cu")
		(net "VCC_D_3V3")
	)
	(segment
		(start 419.495224 -38.703758)
		(end 419.495224 -38.139878)
		(width 0.2032)
		(layer "F.Cu")
		(net "VCC_D_3V3")
	)
	(segment
		(start 419.265862 -38.93312)
		(end 419.495224 -38.703758)
		(width 0.2032)
		(layer "F.Cu")
		(net "VCC_D_3V3")
	)
	(segment
		(start 411.090364 -35.334702)
		(end 411.09011 -35.334702)
		(width 0.254)
		(layer "F.Cu")
		(net "VCC_D_3V3")
	)
	(segment
		(start 417.490148 -39.334694)
		(end 417.090098 -38.934644)
		(width 0.254)
		(layer "F.Cu")
		(net "VCC_D_3V3")
	)
	(segment
		(start 414.290256 -31.33471)
		(end 414.690306 -31.73476)
		(width 0.254)
		(layer "F.Cu")
		(net "VCC_D_3V3")
	)
	(via
		(at 411.5054 -38.1508)
		(size 0.4572)
		(drill 0.2032)
		(layers "F.Cu" "B.Cu")
		(net "VCC_D_3V3")
	)
	(via
		(at 411.49016 -35.734498)
		(size 0.4572)
		(drill 0.2032)
		(layers "F.Cu" "B.Cu")
		(net "VCC_D_3V3")
	)
	(via
		(at 413.083502 -38.941248)
		(size 0.4572)
		(drill 0.2032)
		(layers "F.Cu" "B.Cu")
		(net "VCC_D_3V3")
	)
	(via
		(at 417.090098 -38.934644)
		(size 0.4572)
		(drill 0.2032)
		(layers "F.Cu" "B.Cu")
		(net "VCC_D_3V3")
	)
	(via
		(at 411.49016 -37.334698)
		(size 0.4572)
		(drill 0.2032)
		(layers "F.Cu" "B.Cu")
		(net "VCC_D_3V3")
	)
	(via
		(at 414.690306 -31.73476)
		(size 0.4572)
		(drill 0.2032)
		(layers "F.Cu" "B.Cu")
		(net "VCC_D_3V3")
	)
	(via
		(at 417.1061 -30.13964)
		(size 0.4572)
		(drill 0.2032)
		(layers "F.Cu" "B.Cu")
		(net "VCC_D_3V3")
	)
	(via
		(at 414.690052 -38.934644)
		(size 0.4572)
		(drill 0.2032)
		(layers "F.Cu" "B.Cu")
		(net "VCC_D_3V3")
	)
	(via
		(at 418.691822 -38.93312)
		(size 0.4572)
		(drill 0.2032)
		(layers "F.Cu" "B.Cu")
		(net "VCC_D_3V3")
	)
	(via
		(at 414.528 -44.1452)
		(size 0.6604)
		(drill 0.3302)
		(layers "F.Cu" "B.Cu")
		(net "VCC_D_3V3")
	)
	(via
		(at 417.890198 -30.13456)
		(size 0.4572)
		(drill 0.2032)
		(layers "F.Cu" "B.Cu")
		(net "VCC_D_3V3")
	)
	(segment
		(start 412.508446 -39.516304)
		(end 413.083502 -38.941248)
		(width 0.508)
		(layer "B.Cu")
		(net "VCC_D_3V3")
	)
	(segment
		(start 412.508446 -39.735252)
		(end 412.508446 -39.516304)
		(width 0.508)
		(layer "B.Cu")
		(net "VCC_D_3V3")
	)
	(segment
		(start 411.503368 -39.63797)
		(end 412.411164 -39.63797)
		(width 0.508)
		(layer "B.Cu")
		(net "VCC_D_3V3")
	)
	(segment
		(start 411.5308 -37.294058)
		(end 411.5308 -36.5506)
		(width 0.4572)
		(layer "B.Cu")
		(net "VCC_D_3V3")
	)
	(segment
		(start 412.411164 -39.63797)
		(end 412.508446 -39.735252)
		(width 0.508)
		(layer "B.Cu")
		(net "VCC_D_3V3")
	)
	(segment
		(start 411.49016 -37.334698)
		(end 411.5308 -37.294058)
		(width 0.4572)
		(layer "B.Cu")
		(net "VCC_D_3V3")
	)
	(segment
		(start 411.5308 -35.775138)
		(end 411.5308 -36.5506)
		(width 0.4572)
		(layer "B.Cu")
		(net "VCC_D_3V3")
	)
	(segment
		(start 411.49016 -35.734498)
		(end 411.5308 -35.775138)
		(width 0.4572)
		(layer "B.Cu")
		(net "VCC_D_3V3")
	)
	(segment
		(start 417.890198 -30.13456)
		(end 418.61486 -30.13456)
		(width 0.508)
		(layer "B.Cu")
		(net "VCC_D_3V3")
	)
	(segment
		(start 414.29051 -29.734764)
		(end 414.290256 -29.734764)
		(width 0.254)
		(layer "F.Cu")
		(net "VCC_DACAV3V3")
	)
	(segment
		(start 414.290256 -30.53461)
		(end 414.690306 -30.13456)
		(width 0.254)
		(layer "F.Cu")
		(net "VCC_DACAV3V3")
	)
	(segment
		(start 414.690306 -30.13456)
		(end 414.29051 -29.734764)
		(width 0.254)
		(layer "F.Cu")
		(net "VCC_DACAV3V3")
	)
	(via
		(at 414.690306 -30.13456)
		(size 0.4572)
		(drill 0.2032)
		(layers "F.Cu" "B.Cu")
		(net "VCC_DACAV3V3")
	)
	(via
		(at 400.52498 -32.277812)
		(size 0.6604)
		(drill 0.3302)
		(layers "F.Cu" "B.Cu")
		(net "VCC_DACAV3V3")
	)
	(via
		(at 404.814024 -32.778192)
		(size 0.508)
		(drill 0.254)
		(layers "F.Cu" "B.Cu")
		(net "VCC_DACAV3V3")
	)
	(segment
		(start 400.52498 -32.62122)
		(end 400.351498 -32.794702)
		(width 0.254)
		(layer "B.Cu")
		(net "VCC_DACAV3V3")
	)
	(segment
		(start 400.351498 -33.385506)
		(end 400.351498 -33.452562)
		(width 0.508)
		(layer "B.Cu")
		(net "VCC_DACAV3V3")
	)
	(segment
		(start 401.903184 -33.960816)
		(end 402.209 -33.655)
		(width 0.508)
		(layer "B.Cu")
		(net "VCC_DACAV3V3")
	)
	(segment
		(start 404.791164 -32.801052)
		(end 404.814024 -32.778192)
		(width 0.508)
		(layer "B.Cu")
		(net "VCC_DACAV3V3")
	)
	(segment
		(start 400.351498 -33.452562)
		(end 400.859752 -33.960816)
		(width 0.508)
		(layer "B.Cu")
		(net "VCC_DACAV3V3")
	)
	(segment
		(start 400.859752 -33.960816)
		(end 401.903184 -33.960816)
		(width 0.508)
		(layer "B.Cu")
		(net "VCC_DACAV3V3")
	)
	(segment
		(start 402.209 -33.655)
		(end 403.062948 -32.801052)
		(width 0.508)
		(layer "B.Cu")
		(net "VCC_DACAV3V3")
	)
	(segment
		(start 404.204424 -32.801052)
		(end 404.791164 -32.801052)
		(width 0.508)
		(layer "B.Cu")
		(net "VCC_DACAV3V3")
	)
	(segment
		(start 403.062948 -32.801052)
		(end 403.391624 -32.801052)
		(width 0.508)
		(layer "B.Cu")
		(net "VCC_DACAV3V3")
	)
	(segment
		(start 403.391624 -32.801052)
		(end 404.204424 -32.801052)
		(width 0.508)
		(layer "B.Cu")
		(net "VCC_DACAV3V3")
	)
	(segment
		(start 400.52498 -32.277812)
		(end 400.52498 -32.62122)
		(width 0.254)
		(layer "B.Cu")
		(net "VCC_DACAV3V3")
	)
	(segment
		(start 400.351498 -32.794702)
		(end 400.351498 -33.385506)
		(width 0.254)
		(layer "B.Cu")
		(net "VCC_DACAV3V3")
	)
	(segment
		(start 413.893 -31.496)
		(end 414.690306 -30.698694)
		(width 0.508)
		(layer "In9.Cu")
		(net "VCC_DACAV3V3")
	)
	(segment
		(start 404.814024 -33.005014)
		(end 405.196548 -33.387538)
		(width 0.508)
		(layer "In9.Cu")
		(net "VCC_DACAV3V3")
	)
	(segment
		(start 406.410414 -32.780986)
		(end 408.498548 -32.780986)
		(width 0.508)
		(layer "In9.Cu")
		(net "VCC_DACAV3V3")
	)
	(segment
		(start 408.498548 -32.780986)
		(end 408.836114 -33.118552)
		(width 0.508)
		(layer "In9.Cu")
		(net "VCC_DACAV3V3")
	)
	(segment
		(start 408.836114 -33.118552)
		(end 412.532322 -33.118552)
		(width 0.508)
		(layer "In9.Cu")
		(net "VCC_DACAV3V3")
	)
	(segment
		(start 414.690306 -30.698694)
		(end 414.690306 -30.13456)
		(width 0.508)
		(layer "In9.Cu")
		(net "VCC_DACAV3V3")
	)
	(segment
		(start 413.893 -31.757874)
		(end 413.893 -31.496)
		(width 0.508)
		(layer "In9.Cu")
		(net "VCC_DACAV3V3")
	)
	(segment
		(start 405.196548 -33.387538)
		(end 405.803862 -33.387538)
		(width 0.508)
		(layer "In9.Cu")
		(net "VCC_DACAV3V3")
	)
	(segment
		(start 404.814024 -32.778192)
		(end 404.814024 -33.005014)
		(width 0.508)
		(layer "In9.Cu")
		(net "VCC_DACAV3V3")
	)
	(segment
		(start 405.803862 -33.387538)
		(end 406.410414 -32.780986)
		(width 0.508)
		(layer "In9.Cu")
		(net "VCC_DACAV3V3")
	)
	(segment
		(start 412.532322 -33.118552)
		(end 413.893 -31.757874)
		(width 0.508)
		(layer "In9.Cu")
		(net "VCC_DACAV3V3")
	)
	(segment
		(start 415.090102 -30.53461)
		(end 415.490152 -30.13456)
		(width 0.254)
		(layer "F.Cu")
		(net "VCC_A_1V1")
	)
	(segment
		(start 415.090356 -29.734764)
		(end 415.090102 -29.734764)
		(width 0.254)
		(layer "F.Cu")
		(net "VCC_A_1V1")
	)
	(segment
		(start 415.490152 -30.13456)
		(end 415.090356 -29.734764)
		(width 0.254)
		(layer "F.Cu")
		(net "VCC_A_1V1")
	)
	(via
		(at 415.490152 -30.13456)
		(size 0.4572)
		(drill 0.2032)
		(layers "F.Cu" "B.Cu")
		(net "VCC_A_1V1")
	)
	(segment
		(start 415.903664 -30.988)
		(end 416.3695 -30.988)
		(width 0.508)
		(layer "B.Cu")
		(net "VCC_A_1V1")
	)
	(segment
		(start 415.4805 -30.124908)
		(end 415.490152 -30.13456)
		(width 0.508)
		(layer "B.Cu")
		(net "VCC_A_1V1")
	)
	(segment
		(start 415.29 -31.0515)
		(end 414.6931 -31.0515)
		(width 0.508)
		(layer "B.Cu")
		(net "VCC_A_1V1")
	)
	(segment
		(start 415.490152 -30.13456)
		(end 415.490152 -30.339792)
		(width 0.508)
		(layer "B.Cu")
		(net "VCC_A_1V1")
	)
	(segment
		(start 415.490152 -30.339792)
		(end 415.29 -30.539944)
		(width 0.508)
		(layer "B.Cu")
		(net "VCC_A_1V1")
	)
	(segment
		(start 415.29 -31.0515)
		(end 415.840164 -31.0515)
		(width 0.508)
		(layer "B.Cu")
		(net "VCC_A_1V1")
	)
	(segment
		(start 415.840164 -31.0515)
		(end 415.903664 -30.988)
		(width 0.508)
		(layer "B.Cu")
		(net "VCC_A_1V1")
	)
	(segment
		(start 414.6931 -31.0515)
		(end 414.684972 -31.043372)
		(width 0.508)
		(layer "B.Cu")
		(net "VCC_A_1V1")
	)
	(segment
		(start 414.684972 -31.043372)
		(end 413.922972 -31.043372)
		(width 0.508)
		(layer "B.Cu")
		(net "VCC_A_1V1")
	)
	(segment
		(start 415.4805 -29.337)
		(end 415.4805 -30.124908)
		(width 0.508)
		(layer "B.Cu")
		(net "VCC_A_1V1")
	)
	(segment
		(start 415.29 -30.539944)
		(end 415.29 -31.0515)
		(width 0.508)
		(layer "B.Cu")
		(net "VCC_A_1V1")
	)
	(segment
		(start 411.086046 -21.239226)
		(end 411.675072 -20.6502)
		(width 0.381)
		(layer "F.Cu")
		(net "VCC_ADCAV3V3")
	)
	(segment
		(start 411.086046 -21.307552)
		(end 411.086046 -21.239226)
		(width 0.381)
		(layer "F.Cu")
		(net "VCC_ADCAV3V3")
	)
	(segment
		(start 413.490156 -30.53461)
		(end 413.096456 -30.92831)
		(width 0.254)
		(layer "F.Cu")
		(net "VCC_ADCAV3V3")
	)
	(segment
		(start 411.675072 -20.6502)
		(end 411.7086 -20.6502)
		(width 0.381)
		(layer "F.Cu")
		(net "VCC_ADCAV3V3")
	)
	(via
		(at 413.096456 -30.92831)
		(size 0.4572)
		(drill 0.2032)
		(layers "F.Cu" "B.Cu")
		(net "VCC_ADCAV3V3")
	)
	(via
		(at 411.988 -21.463)
		(size 0.6604)
		(drill 0.3302)
		(layers "F.Cu" "B.Cu")
		(net "VCC_ADCAV3V3")
	)
	(via
		(at 411.7086 -20.6502)
		(size 0.508)
		(drill 0.254)
		(layers "F.Cu" "B.Cu")
		(net "VCC_ADCAV3V3")
	)
	(segment
		(start 413.0675 -26.940256)
		(end 413.489902 -27.362658)
		(width 0.1397)
		(layer "B.Cu")
		(net "VCC_ADCAV3V3")
	)
	(segment
		(start 413.0675 -25.273)
		(end 413.0675 -24.384)
		(width 0.381)
		(layer "B.Cu")
		(net "VCC_ADCAV3V3")
	)
	(segment
		(start 413.489902 -27.362658)
		(end 413.489902 -30.349952)
		(width 0.1397)
		(layer "B.Cu")
		(net "VCC_ADCAV3V3")
	)
	(segment
		(start 412.6738 -29.952696)
		(end 412.689802 -29.968698)
		(width 0.1397)
		(layer "B.Cu")
		(net "VCC_ADCAV3V3")
	)
	(segment
		(start 411.7086 -21.1836)
		(end 411.988 -21.463)
		(width 0.381)
		(layer "B.Cu")
		(net "VCC_ADCAV3V3")
	)
	(segment
		(start 413.489902 -30.349952)
		(end 413.096456 -30.743398)
		(width 0.1397)
		(layer "B.Cu")
		(net "VCC_ADCAV3V3")
	)
	(segment
		(start 412.623 -23.6474)
		(end 413.0675 -24.0919)
		(width 0.381)
		(layer "B.Cu")
		(net "VCC_ADCAV3V3")
	)
	(segment
		(start 411.7086 -20.6502)
		(end 411.7086 -21.1836)
		(width 0.381)
		(layer "B.Cu")
		(net "VCC_ADCAV3V3")
	)
	(segment
		(start 412.689802 -30.521656)
		(end 413.096456 -30.92831)
		(width 0.1397)
		(layer "B.Cu")
		(net "VCC_ADCAV3V3")
	)
	(segment
		(start 412.623 -23.0632)
		(end 412.623 -23.6474)
		(width 0.381)
		(layer "B.Cu")
		(net "VCC_ADCAV3V3")
	)
	(segment
		(start 413.096456 -30.743398)
		(end 413.096456 -30.92831)
		(width 0.1397)
		(layer "B.Cu")
		(net "VCC_ADCAV3V3")
	)
	(segment
		(start 413.0675 -26.162)
		(end 413.0675 -26.940256)
		(width 0.254)
		(layer "B.Cu")
		(net "VCC_ADCAV3V3")
	)
	(segment
		(start 412.623 -22.098)
		(end 412.623 -23.0632)
		(width 0.381)
		(layer "B.Cu")
		(net "VCC_ADCAV3V3")
	)
	(segment
		(start 413.0675 -24.0919)
		(end 413.0675 -24.384)
		(width 0.381)
		(layer "B.Cu")
		(net "VCC_ADCAV3V3")
	)
	(segment
		(start 413.0675 -26.940256)
		(end 412.6738 -27.333956)
		(width 0.1397)
		(layer "B.Cu")
		(net "VCC_ADCAV3V3")
	)
	(segment
		(start 412.6738 -27.333956)
		(end 412.6738 -29.952696)
		(width 0.1397)
		(layer "B.Cu")
		(net "VCC_ADCAV3V3")
	)
	(segment
		(start 412.689802 -29.968698)
		(end 412.689802 -30.521656)
		(width 0.1397)
		(layer "B.Cu")
		(net "VCC_ADCAV3V3")
	)
	(segment
		(start 413.0675 -26.162)
		(end 413.0675 -25.273)
		(width 0.381)
		(layer "B.Cu")
		(net "VCC_ADCAV3V3")
	)
	(segment
		(start 411.988 -21.463)
		(end 412.623 -22.098)
		(width 0.381)
		(layer "B.Cu")
		(net "VCC_ADCAV3V3")
	)
	(segment
		(start 411.61716 -30.468824)
		(end 412.076646 -30.92831)
		(width 0.254)
		(layer "In11.Cu")
		(net "VCC_ADCAV3V3")
	)
	(segment
		(start 411.61716 -28.973018)
		(end 411.61716 -30.468824)
		(width 0.254)
		(layer "In11.Cu")
		(net "VCC_ADCAV3V3")
	)
	(segment
		(start 412.076646 -30.92831)
		(end 413.096456 -30.92831)
		(width 0.254)
		(layer "In11.Cu")
		(net "VCC_ADCAV3V3")
	)
	(segment
		(start 411.7086 -22.08657)
		(end 412.019496 -22.397466)
		(width 0.254)
		(layer "In11.Cu")
		(net "VCC_ADCAV3V3")
	)
	(segment
		(start 412.019496 -28.570682)
		(end 411.61716 -28.973018)
		(width 0.254)
		(layer "In11.Cu")
		(net "VCC_ADCAV3V3")
	)
	(segment
		(start 412.019496 -22.397466)
		(end 412.019496 -28.570682)
		(width 0.254)
		(layer "In11.Cu")
		(net "VCC_ADCAV3V3")
	)
	(segment
		(start 411.7086 -20.6502)
		(end 411.7086 -22.08657)
		(width 0.254)
		(layer "In11.Cu")
		(net "VCC_ADCAV3V3")
	)
	(segment
		(start 410.290264 -28.934664)
		(end 409.890214 -28.534614)
		(width 0.10795)
		(layer "F.Cu")
		(net "VCCBAT_TW12")
	)
	(via
		(at 409.890214 -28.534614)
		(size 0.508)
		(drill 0.254)
		(layers "F.Cu" "B.Cu")
		(net "VCCBAT_TW12")
	)
	(segment
		(start 408.93238 -28.13304)
		(end 409.28036 -28.13304)
		(width 0.127)
		(layer "B.Cu")
		(net "VCCBAT_TW12")
	)
	(segment
		(start 409.28036 -28.13304)
		(end 409.681934 -28.534614)
		(width 0.127)
		(layer "B.Cu")
		(net "VCCBAT_TW12")
	)
	(segment
		(start 408.06116 -27.40406)
		(end 407.8351 -27.178)
		(width 0.254)
		(layer "B.Cu")
		(net "VCCBAT_TW12")
	)
	(segment
		(start 408.625548 -27.571192)
		(end 408.458416 -27.40406)
		(width 0.254)
		(layer "B.Cu")
		(net "VCCBAT_TW12")
	)
	(segment
		(start 410.28366 -27.454606)
		(end 410.157168 -27.328114)
		(width 0.127)
		(layer "B.Cu")
		(net "VCCBAT_TW12")
	)
	(segment
		(start 408.625548 -27.826208)
		(end 408.93238 -28.13304)
		(width 0.127)
		(layer "B.Cu")
		(net "VCCBAT_TW12")
	)
	(segment
		(start 410.157168 -27.328114)
		(end 408.868626 -27.328114)
		(width 0.127)
		(layer "B.Cu")
		(net "VCCBAT_TW12")
	)
	(segment
		(start 408.868626 -27.328114)
		(end 408.625548 -27.571192)
		(width 0.127)
		(layer "B.Cu")
		(net "VCCBAT_TW12")
	)
	(segment
		(start 407.8351 -27.178)
		(end 407.543 -27.178)
		(width 0.254)
		(layer "B.Cu")
		(net "VCCBAT_TW12")
	)
	(segment
		(start 409.890214 -28.534614)
		(end 410.28366 -28.141168)
		(width 0.127)
		(layer "B.Cu")
		(net "VCCBAT_TW12")
	)
	(segment
		(start 408.458416 -27.40406)
		(end 408.06116 -27.40406)
		(width 0.254)
		(layer "B.Cu")
		(net "VCCBAT_TW12")
	)
	(segment
		(start 408.625548 -27.571192)
		(end 408.625548 -27.826208)
		(width 0.127)
		(layer "B.Cu")
		(net "VCCBAT_TW12")
	)
	(segment
		(start 409.681934 -28.534614)
		(end 409.890214 -28.534614)
		(width 0.127)
		(layer "B.Cu")
		(net "VCCBAT_TW12")
	)
	(segment
		(start 410.28366 -28.141168)
		(end 410.28366 -27.454606)
		(width 0.127)
		(layer "B.Cu")
		(net "VCCBAT_TW12")
	)
	(via
		(at 17.05102 -93.8657)
		(size 0.6604)
		(drill 0.3302)
		(layers "F.Cu" "B.Cu")
		(net "UV_HIGH_SET_N")
	)
	(segment
		(start 17.5895 -92.583)
		(end 18.3515 -92.583)
		(width 0.10795)
		(layer "B.Cu")
		(net "UV_HIGH_SET_N")
	)
	(segment
		(start 17.05102 -93.8657)
		(end 17.05102 -93.803724)
		(width 0.10795)
		(layer "B.Cu")
		(net "UV_HIGH_SET_N")
	)
	(segment
		(start 18.3515 -92.583)
		(end 18.669 -92.2655)
		(width 0.10795)
		(layer "B.Cu")
		(net "UV_HIGH_SET_N")
	)
	(segment
		(start 18.669 -92.2655)
		(end 19.431 -92.2655)
		(width 0.10795)
		(layer "B.Cu")
		(net "UV_HIGH_SET_N")
	)
	(segment
		(start 17.5895 -93.265244)
		(end 17.5895 -92.583)
		(width 0.10795)
		(layer "B.Cu")
		(net "UV_HIGH_SET_N")
	)
	(segment
		(start 17.05102 -93.803724)
		(end 17.5895 -93.265244)
		(width 0.10795)
		(layer "B.Cu")
		(net "UV_HIGH_SET_N")
	)
	(segment
		(start 447.548 -20.2565)
		(end 446.4431 -20.2565)
		(width 0.10795)
		(layer "F.Cu")
		(net "PWRGD_P2V5_BMC_STBY_R")
	)
	(segment
		(start 449.9864 -20.7264)
		(end 451.2056 -20.7264)
		(width 0.10795)
		(layer "F.Cu")
		(net "PWRGD_P2V5_BMC_STBY_R")
	)
	(segment
		(start 449.8213 -20.2565)
		(end 448.437 -20.2565)
		(width 0.1016)
		(layer "F.Cu")
		(net "PWRGD_P2V5_BMC_STBY_R")
	)
	(segment
		(start 449.834 -20.2692)
		(end 449.8213 -20.2565)
		(width 0.1016)
		(layer "F.Cu")
		(net "PWRGD_P2V5_BMC_STBY_R")
	)
	(segment
		(start 449.834 -20.2692)
		(end 449.834 -20.574)
		(width 0.10795)
		(layer "F.Cu")
		(net "PWRGD_P2V5_BMC_STBY_R")
	)
	(segment
		(start 452.355712 -21.194522)
		(end 452.767192 -21.606002)
		(width 0.1016)
		(layer "F.Cu")
		(net "PWRGD_P2V5_BMC_STBY_R")
	)
	(segment
		(start 448.437 -20.2565)
		(end 447.548 -20.2565)
		(width 0.1016)
		(layer "F.Cu")
		(net "PWRGD_P2V5_BMC_STBY_R")
	)
	(segment
		(start 449.834 -20.574)
		(end 449.9864 -20.7264)
		(width 0.10795)
		(layer "F.Cu")
		(net "PWRGD_P2V5_BMC_STBY_R")
	)
	(segment
		(start 446.4431 -20.2565)
		(end 446.0748 -19.8882)
		(width 0.10795)
		(layer "F.Cu")
		(net "PWRGD_P2V5_BMC_STBY_R")
	)
	(segment
		(start 451.2056 -20.7264)
		(end 451.673722 -21.194522)
		(width 0.1016)
		(layer "F.Cu")
		(net "PWRGD_P2V5_BMC_STBY_R")
	)
	(segment
		(start 451.673722 -21.194522)
		(end 452.355712 -21.194522)
		(width 0.1016)
		(layer "F.Cu")
		(net "PWRGD_P2V5_BMC_STBY_R")
	)
	(via
		(at 446.0748 -19.8882)
		(size 0.762)
		(drill 0.381)
		(layers "F.Cu" "B.Cu")
		(net "PWRGD_P2V5_BMC_STBY_R")
	)
	(segment
		(start 377.75896 -24.219662)
		(end 376.879866 -24.219662)
		(width 0.10795)
		(layer "F.Cu")
		(net "TP_TPM_SPI_4")
	)
	(segment
		(start 378.631196 -25.091898)
		(end 377.75896 -24.219662)
		(width 0.10795)
		(layer "F.Cu")
		(net "TP_TPM_SPI_4")
	)
	(via
		(at 378.631196 -25.091898)
		(size 0.508)
		(drill 0.254)
		(layers "F.Cu" "B.Cu")
		(net "TP_TPM_SPI_4")
	)
	(segment
		(start 369.08613 -24.219662)
		(end 367.329466 -24.219662)
		(width 0.10795)
		(layer "F.Cu")
		(net "TP_TPM_SPI_3")
	)
	(segment
		(start 369.267486 -24.038306)
		(end 369.08613 -24.219662)
		(width 0.10795)
		(layer "F.Cu")
		(net "TP_TPM_SPI_3")
	)
	(via
		(at 369.267486 -24.038306)
		(size 0.508)
		(drill 0.254)
		(layers "F.Cu" "B.Cu")
		(net "TP_TPM_SPI_3")
	)
	(via
		(at 370.254276 -24.509476)
		(size 0.6604)
		(drill 0.3302)
		(layers "F.Cu" "B.Cu")
		(net "TP_TPM_SPI_3")
	)
	(segment
		(start 369.783106 -24.038306)
		(end 369.267486 -24.038306)
		(width 0.10795)
		(layer "B.Cu")
		(net "TP_TPM_SPI_3")
	)
	(segment
		(start 370.254276 -24.509476)
		(end 369.783106 -24.038306)
		(width 0.10795)
		(layer "B.Cu")
		(net "TP_TPM_SPI_3")
	)
	(segment
		(start 369.22329 -22.949662)
		(end 367.329466 -22.949662)
		(width 0.10795)
		(layer "F.Cu")
		(net "TP_TPM_SPI_2")
	)
	(segment
		(start 369.658138 -23.38451)
		(end 369.22329 -22.949662)
		(width 0.10795)
		(layer "F.Cu")
		(net "TP_TPM_SPI_2")
	)
	(via
		(at 369.658138 -23.38451)
		(size 0.508)
		(drill 0.254)
		(layers "F.Cu" "B.Cu")
		(net "TP_TPM_SPI_2")
	)
	(segment
		(start 368.450876 -21.679662)
		(end 368.670078 -21.898864)
		(width 0.10795)
		(layer "F.Cu")
		(net "TP_TPM_SPI_1")
	)
	(segment
		(start 369.824 -21.381212)
		(end 369.824 -21.082)
		(width 0.10795)
		(layer "F.Cu")
		(net "TP_TPM_SPI_1")
	)
	(segment
		(start 369.306348 -21.898864)
		(end 369.824 -21.381212)
		(width 0.10795)
		(layer "F.Cu")
		(net "TP_TPM_SPI_1")
	)
	(segment
		(start 369.824 -21.082)
		(end 370.078 -20.828)
		(width 0.10795)
		(layer "F.Cu")
		(net "TP_TPM_SPI_1")
	)
	(segment
		(start 368.670078 -21.898864)
		(end 369.306348 -21.898864)
		(width 0.10795)
		(layer "F.Cu")
		(net "TP_TPM_SPI_1")
	)
	(segment
		(start 367.329466 -21.679662)
		(end 368.450876 -21.679662)
		(width 0.10795)
		(layer "F.Cu")
		(net "TP_TPM_SPI_1")
	)
	(via
		(at 370.078 -20.828)
		(size 0.508)
		(drill 0.254)
		(layers "F.Cu" "B.Cu")
		(net "TP_TPM_SPI_1")
	)
	(segment
		(start 367.329466 -20.409662)
		(end 368.376962 -20.409662)
		(width 0.10795)
		(layer "F.Cu")
		(net "TP_TPM_SPI_0")
	)
	(segment
		(start 368.376962 -20.409662)
		(end 369.2398 -21.2725)
		(width 0.10795)
		(layer "F.Cu")
		(net "TP_TPM_SPI_0")
	)
	(via
		(at 369.2398 -21.2725)
		(size 0.508)
		(drill 0.254)
		(layers "F.Cu" "B.Cu")
		(net "TP_TPM_SPI_0")
	)
	(via
		(at 370.02466 -22.126448)
		(size 0.6604)
		(drill 0.3302)
		(layers "F.Cu" "B.Cu")
		(net "TP_TPM_SPI_0")
	)
	(segment
		(start 370.02466 -22.05736)
		(end 369.2398 -21.2725)
		(width 0.10795)
		(layer "B.Cu")
		(net "TP_TPM_SPI_0")
	)
	(segment
		(start 370.02466 -22.126448)
		(end 370.02466 -22.05736)
		(width 0.10795)
		(layer "B.Cu")
		(net "TP_TPM_SPI_0")
	)
	(segment
		(start 378.285502 -26.759662)
		(end 378.40412 -26.87828)
		(width 0.10795)
		(layer "F.Cu")
		(net "SPI_TPM_BMC_DI_R")
	)
	(segment
		(start 376.879866 -26.759662)
		(end 378.285502 -26.759662)
		(width 0.10795)
		(layer "F.Cu")
		(net "SPI_TPM_BMC_DI_R")
	)
	(via
		(at 378.40412 -26.87828)
		(size 0.508)
		(drill 0.254)
		(layers "F.Cu" "B.Cu")
		(net "SPI_TPM_BMC_DI_R")
	)
	(via
		(at 376.1994 -26.035)
		(size 0.6604)
		(drill 0.3302)
		(layers "F.Cu" "B.Cu")
		(net "SPI_TPM_BMC_DI_R")
	)
	(segment
		(start 378.40412 -26.87828)
		(end 378.230892 -26.705052)
		(width 0.10795)
		(layer "B.Cu")
		(net "SPI_TPM_BMC_DI_R")
	)
	(segment
		(start 377.688094 -26.364438)
		(end 377.493022 -26.364438)
		(width 0.10795)
		(layer "B.Cu")
		(net "SPI_TPM_BMC_DI_R")
	)
	(segment
		(start 376.528838 -26.364438)
		(end 376.1994 -26.035)
		(width 0.10795)
		(layer "B.Cu")
		(net "SPI_TPM_BMC_DI_R")
	)
	(segment
		(start 378.028708 -26.705052)
		(end 377.688094 -26.364438)
		(width 0.10795)
		(layer "B.Cu")
		(net "SPI_TPM_BMC_DI_R")
	)
	(segment
		(start 377.493022 -26.364438)
		(end 376.528838 -26.364438)
		(width 0.10795)
		(layer "B.Cu")
		(net "SPI_TPM_BMC_DI_R")
	)
	(segment
		(start 378.230892 -26.705052)
		(end 378.028708 -26.705052)
		(width 0.10795)
		(layer "B.Cu")
		(net "SPI_TPM_BMC_DI_R")
	)
	(segment
		(start 378.185934 -21.343366)
		(end 378.474478 -21.63191)
		(width 0.1016)
		(layer "F.Cu")
		(net "PU_TPM_SPI_FLASH_RESET_2_N")
	)
	(segment
		(start 376.879866 -20.409662)
		(end 377.911614 -20.409662)
		(width 0.1016)
		(layer "F.Cu")
		(net "PU_TPM_SPI_FLASH_RESET_2_N")
	)
	(segment
		(start 377.911614 -20.409662)
		(end 378.185934 -20.683982)
		(width 0.1016)
		(layer "F.Cu")
		(net "PU_TPM_SPI_FLASH_RESET_2_N")
	)
	(segment
		(start 378.185934 -20.683982)
		(end 378.185934 -21.343366)
		(width 0.1016)
		(layer "F.Cu")
		(net "PU_TPM_SPI_FLASH_RESET_2_N")
	)
	(via
		(at 376.555 -21.209)
		(size 0.6604)
		(drill 0.3302)
		(layers "F.Cu" "B.Cu")
		(net "PU_TPM_SPI_FLASH_RESET_2_N")
	)
	(via
		(at 378.474478 -21.63191)
		(size 0.508)
		(drill 0.254)
		(layers "F.Cu" "B.Cu")
		(net "PU_TPM_SPI_FLASH_RESET_2_N")
	)
	(segment
		(start 377.698 -21.209)
		(end 378.054616 -21.209)
		(width 0.1016)
		(layer "B.Cu")
		(net "PU_TPM_SPI_FLASH_RESET_2_N")
	)
	(segment
		(start 377.698 -21.209)
		(end 376.555 -21.209)
		(width 0.1016)
		(layer "B.Cu")
		(net "PU_TPM_SPI_FLASH_RESET_2_N")
	)
	(segment
		(start 378.474478 -21.628862)
		(end 378.474478 -21.63191)
		(width 0.1016)
		(layer "B.Cu")
		(net "PU_TPM_SPI_FLASH_RESET_2_N")
	)
	(segment
		(start 378.054616 -21.209)
		(end 378.474478 -21.628862)
		(width 0.1016)
		(layer "B.Cu")
		(net "PU_TPM_SPI_FLASH_RESET_2_N")
	)
	(segment
		(start 368.866928 -27.813)
		(end 368.866928 -27.3431)
		(width 0.10795)
		(layer "F.Cu")
		(net "TPM_SPI_BMC_WP_N")
	)
	(segment
		(start 463.632296 -0.254)
		(end 463.931 -0.552704)
		(width 0.10795)
		(layer "F.Cu")
		(net "TPM_SPI_BMC_WP_N")
	)
	(segment
		(start 464.286854 -1.3716)
		(end 464.845146 -1.3716)
		(width 0.10795)
		(layer "F.Cu")
		(net "TPM_SPI_BMC_WP_N")
	)
	(segment
		(start 368.28349 -26.759662)
		(end 367.329466 -26.759662)
		(width 0.10795)
		(layer "F.Cu")
		(net "TPM_SPI_BMC_WP_N")
	)
	(segment
		(start 368.866928 -27.3431)
		(end 368.28349 -26.759662)
		(width 0.10795)
		(layer "F.Cu")
		(net "TPM_SPI_BMC_WP_N")
	)
	(segment
		(start 463.931 -0.552704)
		(end 463.931 -1.015746)
		(width 0.10795)
		(layer "F.Cu")
		(net "TPM_SPI_BMC_WP_N")
	)
	(segment
		(start 463.931 -1.015746)
		(end 464.286854 -1.3716)
		(width 0.10795)
		(layer "F.Cu")
		(net "TPM_SPI_BMC_WP_N")
	)
	(segment
		(start 464.845146 -1.3716)
		(end 465.149946 -1.0668)
		(width 0.10795)
		(layer "F.Cu")
		(net "TPM_SPI_BMC_WP_N")
	)
	(segment
		(start 465.149946 -1.0668)
		(end 465.6074 -1.0668)
		(width 0.10795)
		(layer "F.Cu")
		(net "TPM_SPI_BMC_WP_N")
	)
	(via
		(at 463.632296 -0.254)
		(size 0.508)
		(drill 0.254)
		(layers "F.Cu" "B.Cu")
		(net "TPM_SPI_BMC_WP_N")
	)
	(via
		(at 368.866928 -27.813)
		(size 0.508)
		(drill 0.254)
		(layers "F.Cu" "B.Cu")
		(net "TPM_SPI_BMC_WP_N")
	)
	(segment
		(start 370.078 -27.559)
		(end 369.120928 -27.559)
		(width 0.10795)
		(layer "B.Cu")
		(net "TPM_SPI_BMC_WP_N")
	)
	(segment
		(start 369.120928 -27.559)
		(end 368.866928 -27.813)
		(width 0.10795)
		(layer "B.Cu")
		(net "TPM_SPI_BMC_WP_N")
	)
	(segment
		(start 370.078 -26.6065)
		(end 370.078 -27.559)
		(width 0.1016)
		(layer "B.Cu")
		(net "TPM_SPI_BMC_WP_N")
	)
	(segment
		(start 380.856744 -11.594084)
		(end 380.857252 -11.594084)
		(width 0.089408)
		(layer "In11.Cu")
		(net "TPM_SPI_BMC_WP_N")
	)
	(segment
		(start 396.620746 -11.5443)
		(end 399.442686 -8.72236)
		(width 0.089408)
		(layer "In11.Cu")
		(net "TPM_SPI_BMC_WP_N")
	)
	(segment
		(start 459.263496 -1.657096)
		(end 459.656434 -2.050034)
		(width 0.089408)
		(layer "In11.Cu")
		(net "TPM_SPI_BMC_WP_N")
	)
	(segment
		(start 407.358596 -6.88975)
		(end 407.871422 -6.88975)
		(width 0.089408)
		(layer "In11.Cu")
		(net "TPM_SPI_BMC_WP_N")
	)
	(segment
		(start 371.041168 -21.410168)
		(end 371.041168 -21.40966)
		(width 0.089408)
		(layer "In11.Cu")
		(net "TPM_SPI_BMC_WP_N")
	)
	(segment
		(start 451.678294 -1.657096)
		(end 459.263496 -1.657096)
		(width 0.089408)
		(layer "In11.Cu")
		(net "TPM_SPI_BMC_WP_N")
	)
	(segment
		(start 461.575912 -2.050034)
		(end 463.371946 -0.254)
		(width 0.089408)
		(layer "In11.Cu")
		(net "TPM_SPI_BMC_WP_N")
	)
	(segment
		(start 463.371946 -0.254)
		(end 463.632296 -0.254)
		(width 0.089408)
		(layer "In11.Cu")
		(net "TPM_SPI_BMC_WP_N")
	)
	(segment
		(start 408.314652 -6.889496)
		(end 408.314906 -6.88975)
		(width 0.089408)
		(layer "In11.Cu")
		(net "TPM_SPI_BMC_WP_N")
	)
	(segment
		(start 448.849242 -4.486148)
		(end 451.678294 -1.657096)
		(width 0.089408)
		(layer "In11.Cu")
		(net "TPM_SPI_BMC_WP_N")
	)
	(segment
		(start 407.871422 -6.88975)
		(end 407.871676 -6.889496)
		(width 0.089408)
		(layer "In11.Cu")
		(net "TPM_SPI_BMC_WP_N")
	)
	(segment
		(start 437.336184 -4.974336)
		(end 440.580018 -4.974336)
		(width 0.089408)
		(layer "In11.Cu")
		(net "TPM_SPI_BMC_WP_N")
	)
	(segment
		(start 459.656434 -2.050034)
		(end 461.575912 -2.050034)
		(width 0.089408)
		(layer "In11.Cu")
		(net "TPM_SPI_BMC_WP_N")
	)
	(segment
		(start 370.571268 -21.880068)
		(end 371.041168 -21.410168)
		(width 0.089408)
		(layer "In11.Cu")
		(net "TPM_SPI_BMC_WP_N")
	)
	(segment
		(start 380.907036 -11.5443)
		(end 396.620746 -11.5443)
		(width 0.089408)
		(layer "In11.Cu")
		(net "TPM_SPI_BMC_WP_N")
	)
	(segment
		(start 441.068206 -4.486148)
		(end 448.849242 -4.486148)
		(width 0.089408)
		(layer "In11.Cu")
		(net "TPM_SPI_BMC_WP_N")
	)
	(segment
		(start 440.580018 -4.974336)
		(end 441.068206 -4.486148)
		(width 0.089408)
		(layer "In11.Cu")
		(net "TPM_SPI_BMC_WP_N")
	)
	(segment
		(start 408.314906 -6.88975)
		(end 416.763454 -6.88975)
		(width 0.089408)
		(layer "In11.Cu")
		(net "TPM_SPI_BMC_WP_N")
	)
	(segment
		(start 436.51932 -5.7912)
		(end 437.336184 -4.974336)
		(width 0.089408)
		(layer "In11.Cu")
		(net "TPM_SPI_BMC_WP_N")
	)
	(segment
		(start 380.857252 -11.594084)
		(end 380.907036 -11.5443)
		(width 0.089408)
		(layer "In11.Cu")
		(net "TPM_SPI_BMC_WP_N")
	)
	(segment
		(start 371.041168 -21.40966)
		(end 380.856744 -11.594084)
		(width 0.089408)
		(layer "In11.Cu")
		(net "TPM_SPI_BMC_WP_N")
	)
	(segment
		(start 370.571268 -26.10866)
		(end 370.571268 -21.880068)
		(width 0.089408)
		(layer "In11.Cu")
		(net "TPM_SPI_BMC_WP_N")
	)
	(segment
		(start 416.763454 -6.88975)
		(end 417.862004 -5.7912)
		(width 0.089408)
		(layer "In11.Cu")
		(net "TPM_SPI_BMC_WP_N")
	)
	(segment
		(start 368.866928 -27.813)
		(end 370.571268 -26.10866)
		(width 0.089408)
		(layer "In11.Cu")
		(net "TPM_SPI_BMC_WP_N")
	)
	(segment
		(start 407.871676 -6.889496)
		(end 408.314652 -6.889496)
		(width 0.089408)
		(layer "In11.Cu")
		(net "TPM_SPI_BMC_WP_N")
	)
	(segment
		(start 417.862004 -5.7912)
		(end 436.51932 -5.7912)
		(width 0.089408)
		(layer "In11.Cu")
		(net "TPM_SPI_BMC_WP_N")
	)
	(segment
		(start 399.442686 -8.72236)
		(end 405.525986 -8.72236)
		(width 0.089408)
		(layer "In11.Cu")
		(net "TPM_SPI_BMC_WP_N")
	)
	(segment
		(start 405.525986 -8.72236)
		(end 407.358596 -6.88975)
		(width 0.089408)
		(layer "In11.Cu")
		(net "TPM_SPI_BMC_WP_N")
	)
	(segment
		(start 377.805696 -17.869662)
		(end 378.668534 -18.7325)
		(width 0.1016)
		(layer "F.Cu")
		(net "PU_TPM_SPI_BMC_HOLD_N")
	)
	(segment
		(start 376.879866 -17.869662)
		(end 377.805696 -17.869662)
		(width 0.1016)
		(layer "F.Cu")
		(net "PU_TPM_SPI_BMC_HOLD_N")
	)
	(via
		(at 378.668534 -18.7325)
		(size 0.508)
		(drill 0.254)
		(layers "F.Cu" "B.Cu")
		(net "PU_TPM_SPI_BMC_HOLD_N")
	)
	(via
		(at 376.555 -19.685)
		(size 0.6604)
		(drill 0.3302)
		(layers "F.Cu" "B.Cu")
		(net "PU_TPM_SPI_BMC_HOLD_N")
	)
	(segment
		(start 378.605034 -18.669)
		(end 378.668534 -18.7325)
		(width 0.1016)
		(layer "B.Cu")
		(net "PU_TPM_SPI_BMC_HOLD_N")
	)
	(segment
		(start 376.682 -18.796)
		(end 376.682 -19.558)
		(width 0.1016)
		(layer "B.Cu")
		(net "PU_TPM_SPI_BMC_HOLD_N")
	)
	(segment
		(start 376.682 -19.558)
		(end 376.555 -19.685)
		(width 0.1016)
		(layer "B.Cu")
		(net "PU_TPM_SPI_BMC_HOLD_N")
	)
	(segment
		(start 377.698 -18.669)
		(end 376.809 -18.669)
		(width 0.1016)
		(layer "B.Cu")
		(net "PU_TPM_SPI_BMC_HOLD_N")
	)
	(segment
		(start 377.698 -18.669)
		(end 378.605034 -18.669)
		(width 0.1016)
		(layer "B.Cu")
		(net "PU_TPM_SPI_BMC_HOLD_N")
	)
	(segment
		(start 376.809 -18.669)
		(end 376.682 -18.796)
		(width 0.1016)
		(layer "B.Cu")
		(net "PU_TPM_SPI_BMC_HOLD_N")
	)
	(segment
		(start 478.316798 -144.289272)
		(end 477.698816 -144.907254)
		(width 0.1016)
		(layer "B.Cu")
		(net "PCA9555_INT_N")
	)
	(segment
		(start 479.299016 -144.289272)
		(end 478.316798 -144.289272)
		(width 0.1016)
		(layer "B.Cu")
		(net "PCA9555_INT_N")
	)
	(segment
		(start 477.698816 -144.907254)
		(end 477.698816 -145.470372)
		(width 0.1016)
		(layer "B.Cu")
		(net "PCA9555_INT_N")
	)
	(segment
		(start 479.299016 -142.988792)
		(end 480.301808 -142.988792)
		(width 0.1016)
		(layer "B.Cu")
		(net "PCA9555_A2")
	)
	(segment
		(start 480.4664 -142.8242)
		(end 480.8474 -142.8242)
		(width 0.1016)
		(layer "B.Cu")
		(net "PCA9555_A2")
	)
	(segment
		(start 480.301808 -142.988792)
		(end 480.4664 -142.8242)
		(width 0.1016)
		(layer "B.Cu")
		(net "PCA9555_A2")
	)
	(segment
		(start 480.8474 -142.8242)
		(end 481.271072 -143.247872)
		(width 0.1016)
		(layer "B.Cu")
		(net "PCA9555_A2")
	)
	(segment
		(start 481.623116 -143.247872)
		(end 481.623116 -142.485872)
		(width 0.1016)
		(layer "B.Cu")
		(net "PCA9555_A2")
	)
	(segment
		(start 481.271072 -143.247872)
		(end 481.623116 -143.247872)
		(width 0.1016)
		(layer "B.Cu")
		(net "PCA9555_A2")
	)
	(via
		(at 480.708716 -143.51)
		(size 0.6604)
		(drill 0.3302)
		(layers "F.Cu" "B.Cu")
		(net "PCA9555_A1")
	)
	(segment
		(start 481.242116 -144.390872)
		(end 481.623116 -144.009872)
		(width 0.1016)
		(layer "B.Cu")
		(net "PCA9555_A1")
	)
	(segment
		(start 480.9236 -143.51)
		(end 481.076 -143.6624)
		(width 0.1016)
		(layer "B.Cu")
		(net "PCA9555_A1")
	)
	(segment
		(start 480.2632 -143.639032)
		(end 479.299016 -143.639032)
		(width 0.1016)
		(layer "B.Cu")
		(net "PCA9555_A1")
	)
	(segment
		(start 481.242116 -144.771872)
		(end 481.242116 -144.390872)
		(width 0.1016)
		(layer "B.Cu")
		(net "PCA9555_A1")
	)
	(segment
		(start 481.076 -143.6624)
		(end 481.275644 -143.6624)
		(width 0.1016)
		(layer "B.Cu")
		(net "PCA9555_A1")
	)
	(segment
		(start 480.708716 -143.51)
		(end 480.9236 -143.51)
		(width 0.1016)
		(layer "B.Cu")
		(net "PCA9555_A1")
	)
	(segment
		(start 480.392232 -143.51)
		(end 480.2632 -143.639032)
		(width 0.1016)
		(layer "B.Cu")
		(net "PCA9555_A1")
	)
	(segment
		(start 480.708716 -143.51)
		(end 480.392232 -143.51)
		(width 0.1016)
		(layer "B.Cu")
		(net "PCA9555_A1")
	)
	(segment
		(start 481.275644 -143.6624)
		(end 481.623116 -144.009872)
		(width 0.1016)
		(layer "B.Cu")
		(net "PCA9555_A1")
	)
	(segment
		(start 476.936816 -145.470372)
		(end 476.174816 -145.470372)
		(width 0.1016)
		(layer "B.Cu")
		(net "PCA9555_A0")
	)
	(segment
		(start 476.174816 -145.470372)
		(end 476.174816 -144.688814)
		(width 0.1016)
		(layer "B.Cu")
		(net "PCA9555_A0")
	)
	(segment
		(start 475.373192 -143.88719)
		(end 475.373192 -142.810992)
		(width 0.1016)
		(layer "B.Cu")
		(net "PCA9555_A0")
	)
	(segment
		(start 474.815916 -142.0749)
		(end 474.552264 -142.338552)
		(width 0.1016)
		(layer "B.Cu")
		(net "PCA9555_A0")
	)
	(segment
		(start 475.4626 -142.342616)
		(end 475.194884 -142.0749)
		(width 0.1016)
		(layer "B.Cu")
		(net "PCA9555_A0")
	)
	(segment
		(start 476.174816 -144.688814)
		(end 475.373192 -143.88719)
		(width 0.1016)
		(layer "B.Cu")
		(net "PCA9555_A0")
	)
	(segment
		(start 475.4626 -142.721584)
		(end 475.4626 -142.342616)
		(width 0.1016)
		(layer "B.Cu")
		(net "PCA9555_A0")
	)
	(segment
		(start 474.552264 -142.338552)
		(end 473.660216 -142.338552)
		(width 0.1016)
		(layer "B.Cu")
		(net "PCA9555_A0")
	)
	(segment
		(start 475.373192 -142.810992)
		(end 475.4626 -142.721584)
		(width 0.1016)
		(layer "B.Cu")
		(net "PCA9555_A0")
	)
	(segment
		(start 475.194884 -142.0749)
		(end 474.815916 -142.0749)
		(width 0.1016)
		(layer "B.Cu")
		(net "PCA9555_A0")
	)
	(segment
		(start 434.304948 -8.886698)
		(end 434.3019 -8.889746)
		(width 0.1143)
		(layer "F.Cu")
		(net "P3E_CPU0_PE1_PCH_CON_TXP<9>")
	)
	(segment
		(start 337.672426 -117.941598)
		(end 338.333588 -117.941598)
		(width 0.1143)
		(layer "F.Cu")
		(net "P3E_CPU0_PE1_PCH_CON_TXP<9>")
	)
	(segment
		(start 434.3019 -8.889746)
		(end 434.3019 -9.8171)
		(width 0.1143)
		(layer "F.Cu")
		(net "P3E_CPU0_PE1_PCH_CON_TXP<9>")
	)
	(segment
		(start 434.1241 -9.9949)
		(end 433.961032 -9.9949)
		(width 0.1143)
		(layer "F.Cu")
		(net "P3E_CPU0_PE1_PCH_CON_TXP<9>")
	)
	(segment
		(start 434.3019 -9.8171)
		(end 434.1241 -9.9949)
		(width 0.1143)
		(layer "F.Cu")
		(net "P3E_CPU0_PE1_PCH_CON_TXP<9>")
	)
	(segment
		(start 434.075586 -8.657336)
		(end 434.304948 -8.886698)
		(width 0.1143)
		(layer "F.Cu")
		(net "P3E_CPU0_PE1_PCH_CON_TXP<9>")
	)
	(segment
		(start 434.075586 -7.789672)
		(end 434.075586 -8.657336)
		(width 0.1143)
		(layer "F.Cu")
		(net "P3E_CPU0_PE1_PCH_CON_TXP<9>")
	)
	(via
		(at 433.961032 -9.9949)
		(size 0.508)
		(drill 0.254)
		(layers "F.Cu" "B.Cu")
		(net "P3E_CPU0_PE1_PCH_CON_TXP<9>")
	)
	(via
		(at 337.672426 -117.941598)
		(size 0.508)
		(drill 0.254)
		(layers "F.Cu" "B.Cu")
		(net "P3E_CPU0_PE1_PCH_CON_TXP<9>")
	)
	(segment
		(start 328.887074 -71.92264)
		(end 328.594466 -70.545452)
		(width 0.1143)
		(layer "In9.Cu")
		(net "P3E_CPU0_PE1_PCH_CON_TXP<9>")
	)
	(segment
		(start 330.915518 -94.150688)
		(end 330.915518 -94.150942)
		(width 0.1143)
		(layer "In9.Cu")
		(net "P3E_CPU0_PE1_PCH_CON_TXP<9>")
	)
	(segment
		(start 391.743692 -12.383262)
		(end 400.317208 -10.559542)
		(width 0.1143)
		(layer "In9.Cu")
		(net "P3E_CPU0_PE1_PCH_CON_TXP<9>")
	)
	(segment
		(start 434.3019 -9.816846)
		(end 434.124354 -9.9949)
		(width 0.1143)
		(layer "In9.Cu")
		(net "P3E_CPU0_PE1_PCH_CON_TXP<9>")
	)
	(segment
		(start 371.689376 -18.271998)
		(end 371.643656 -18.043144)
		(width 0.1143)
		(layer "In9.Cu")
		(net "P3E_CPU0_PE1_PCH_CON_TXP<9>")
	)
	(segment
		(start 370.516404 -19.733768)
		(end 370.70665 -19.448526)
		(width 0.1143)
		(layer "In9.Cu")
		(net "P3E_CPU0_PE1_PCH_CON_TXP<9>")
	)
	(segment
		(start 330.633578 -92.026232)
		(end 330.437998 -91.898978)
		(width 0.1143)
		(layer "In9.Cu")
		(net "P3E_CPU0_PE1_PCH_CON_TXP<9>")
	)
	(segment
		(start 324.88505 -110.273592)
		(end 328.339958 -107.083352)
		(width 0.1143)
		(layer "In9.Cu")
		(net "P3E_CPU0_PE1_PCH_CON_TXP<9>")
	)
	(segment
		(start 433.94757 -8.76681)
		(end 434.3019 -9.27227)
		(width 0.1143)
		(layer "In9.Cu")
		(net "P3E_CPU0_PE1_PCH_CON_TXP<9>")
	)
	(segment
		(start 370.935504 -19.402552)
		(end 371.12575 -19.11731)
		(width 0.1143)
		(layer "In9.Cu")
		(net "P3E_CPU0_PE1_PCH_CON_TXP<9>")
	)
	(segment
		(start 371.643656 -18.043144)
		(end 371.833902 -17.757648)
		(width 0.1143)
		(layer "In9.Cu")
		(net "P3E_CPU0_PE1_PCH_CON_TXP<9>")
	)
	(segment
		(start 330.577698 -92.557346)
		(end 330.704952 -92.361512)
		(width 0.1143)
		(layer "In9.Cu")
		(net "P3E_CPU0_PE1_PCH_CON_TXP<9>")
	)
	(segment
		(start 372.207282 -17.197832)
		(end 372.397528 -16.91259)
		(width 0.1143)
		(layer "In9.Cu")
		(net "P3E_CPU0_PE1_PCH_CON_TXP<9>")
	)
	(segment
		(start 330.01585 -89.911174)
		(end 330.01585 -89.91092)
		(width 0.1143)
		(layer "In9.Cu")
		(net "P3E_CPU0_PE1_PCH_CON_TXP<9>")
	)
	(segment
		(start 333.515208 -53.658008)
		(end 333.67853 -53.35651)
		(width 0.1143)
		(layer "In9.Cu")
		(net "P3E_CPU0_PE1_PCH_CON_TXP<9>")
	)
	(segment
		(start 330.915772 -94.149672)
		(end 330.788772 -93.551248)
		(width 0.1143)
		(layer "In9.Cu")
		(net "P3E_CPU0_PE1_PCH_CON_TXP<9>")
	)
	(segment
		(start 372.397528 -16.91259)
		(end 372.626382 -16.866616)
		(width 0.1143)
		(layer "In9.Cu")
		(net "P3E_CPU0_PE1_PCH_CON_TXP<9>")
	)
	(segment
		(start 330.282804 -90.373962)
		(end 330.211684 -90.038428)
		(width 0.1143)
		(layer "In9.Cu")
		(net "P3E_CPU0_PE1_PCH_CON_TXP<9>")
	)
	(segment
		(start 330.585572 -95.703136)
		(end 330.915518 -94.150688)
		(width 0.1143)
		(layer "In9.Cu")
		(net "P3E_CPU0_PE1_PCH_CON_TXP<9>")
	)
	(segment
		(start 432.717448 -8.321294)
		(end 433.94757 -8.76681)
		(width 0.1143)
		(layer "In9.Cu")
		(net "P3E_CPU0_PE1_PCH_CON_TXP<9>")
	)
	(segment
		(start 373.132858 -15.809214)
		(end 376.622056 -13.482828)
		(width 0.1143)
		(layer "In9.Cu")
		(net "P3E_CPU0_PE1_PCH_CON_TXP<9>")
	)
	(segment
		(start 420.287704 -8.366252)
		(end 421.472614 -8.114284)
		(width 0.1143)
		(layer "In9.Cu")
		(net "P3E_CPU0_PE1_PCH_CON_TXP<9>")
	)
	(segment
		(start 328.657204 -83.51139)
		(end 329.175364 -81.39303)
		(width 0.1143)
		(layer "In9.Cu")
		(net "P3E_CPU0_PE1_PCH_CON_TXP<9>")
	)
	(segment
		(start 337.672426 -118.168928)
		(end 337.400138 -118.441216)
		(width 0.1143)
		(layer "In9.Cu")
		(net "P3E_CPU0_PE1_PCH_CON_TXP<9>")
	)
	(segment
		(start 328.657458 -83.51139)
		(end 328.657204 -83.51139)
		(width 0.1143)
		(layer "In9.Cu")
		(net "P3E_CPU0_PE1_PCH_CON_TXP<9>")
	)
	(segment
		(start 333.581502 -53.881782)
		(end 333.515208 -53.658008)
		(width 0.1143)
		(layer "In9.Cu")
		(net "P3E_CPU0_PE1_PCH_CON_TXP<9>")
	)
	(segment
		(start 330.858876 -102.50551)
		(end 330.92009 -102.444296)
		(width 0.1143)
		(layer "In9.Cu")
		(net "P3E_CPU0_PE1_PCH_CON_TXP<9>")
	)
	(segment
		(start 432.421792 -8.384032)
		(end 432.717448 -8.321294)
		(width 0.1143)
		(layer "In9.Cu")
		(net "P3E_CPU0_PE1_PCH_CON_TXP<9>")
	)
	(segment
		(start 328.594466 -70.545452)
		(end 331.13853 -58.043318)
		(width 0.1143)
		(layer "In9.Cu")
		(net "P3E_CPU0_PE1_PCH_CON_TXP<9>")
	)
	(segment
		(start 338.32546 -51.09337)
		(end 340.575646 -51.551332)
		(width 0.1143)
		(layer "In9.Cu")
		(net "P3E_CPU0_PE1_PCH_CON_TXP<9>")
	)
	(segment
		(start 426.3009 -8.082026)
		(end 427.623732 -8.363204)
		(width 0.1143)
		(layer "In9.Cu")
		(net "P3E_CPU0_PE1_PCH_CON_TXP<9>")
	)
	(segment
		(start 400.317208 -10.559542)
		(end 401.383246 -8.960358)
		(width 0.1143)
		(layer "In9.Cu")
		(net "P3E_CPU0_PE1_PCH_CON_TXP<9>")
	)
	(segment
		(start 330.437998 -91.898978)
		(end 330.366624 -91.563444)
		(width 0.1143)
		(layer "In9.Cu")
		(net "P3E_CPU0_PE1_PCH_CON_TXP<9>")
	)
	(segment
		(start 417.932108 -8.363712)
		(end 419.104318 -8.114792)
		(width 0.1143)
		(layer "In9.Cu")
		(net "P3E_CPU0_PE1_PCH_CON_TXP<9>")
	)
	(segment
		(start 422.714928 -8.37819)
		(end 423.892472 -8.128254)
		(width 0.1143)
		(layer "In9.Cu")
		(net "P3E_CPU0_PE1_PCH_CON_TXP<9>")
	)
	(segment
		(start 431.363628 -8.074914)
		(end 432.421792 -8.384032)
		(width 0.1143)
		(layer "In9.Cu")
		(net "P3E_CPU0_PE1_PCH_CON_TXP<9>")
	)
	(segment
		(start 402.475192 -8.553958)
		(end 403.91588 -8.859012)
		(width 0.1143)
		(layer "In9.Cu")
		(net "P3E_CPU0_PE1_PCH_CON_TXP<9>")
	)
	(segment
		(start 330.916026 -93.355414)
		(end 330.844652 -93.01988)
		(width 0.1143)
		(layer "In9.Cu")
		(net "P3E_CPU0_PE1_PCH_CON_TXP<9>")
	)
	(segment
		(start 330.788772 -93.551248)
		(end 330.916026 -93.355414)
		(width 0.1143)
		(layer "In9.Cu")
		(net "P3E_CPU0_PE1_PCH_CON_TXP<9>")
	)
	(segment
		(start 365.510064 -29.51734)
		(end 365.921544 -27.459686)
		(width 0.1143)
		(layer "In9.Cu")
		(net "P3E_CPU0_PE1_PCH_CON_TXP<9>")
	)
	(segment
		(start 365.712756 -30.530546)
		(end 365.510064 -29.51734)
		(width 0.1143)
		(layer "In9.Cu")
		(net "P3E_CPU0_PE1_PCH_CON_TXP<9>")
	)
	(segment
		(start 434.3019 -9.27227)
		(end 434.3019 -9.816846)
		(width 0.1143)
		(layer "In9.Cu")
		(net "P3E_CPU0_PE1_PCH_CON_TXP<9>")
	)
	(segment
		(start 332.934056 -55.076598)
		(end 333.097632 -54.7751)
		(width 0.1143)
		(layer "In9.Cu")
		(net "P3E_CPU0_PE1_PCH_CON_TXP<9>")
	)
	(segment
		(start 371.833902 -17.757648)
		(end 372.062756 -17.711928)
		(width 0.1143)
		(layer "In9.Cu")
		(net "P3E_CPU0_PE1_PCH_CON_TXP<9>")
	)
	(segment
		(start 365.921544 -27.459686)
		(end 367.499138 -26.408126)
		(width 0.1143)
		(layer "In9.Cu")
		(net "P3E_CPU0_PE1_PCH_CON_TXP<9>")
	)
	(segment
		(start 333.902304 -53.289962)
		(end 334.065626 -52.988464)
		(width 0.1143)
		(layer "In9.Cu")
		(net "P3E_CPU0_PE1_PCH_CON_TXP<9>")
	)
	(segment
		(start 419.104318 -8.114792)
		(end 420.287704 -8.366252)
		(width 0.1143)
		(layer "In9.Cu")
		(net "P3E_CPU0_PE1_PCH_CON_TXP<9>")
	)
	(segment
		(start 328.339958 -107.083352)
		(end 330.858876 -102.50551)
		(width 0.1143)
		(layer "In9.Cu")
		(net "P3E_CPU0_PE1_PCH_CON_TXP<9>")
	)
	(segment
		(start 365.237776 -32.902398)
		(end 365.712756 -30.530546)
		(width 0.1143)
		(layer "In9.Cu")
		(net "P3E_CPU0_PE1_PCH_CON_TXP<9>")
	)
	(segment
		(start 370.70665 -19.448526)
		(end 370.935504 -19.402552)
		(width 0.1143)
		(layer "In9.Cu")
		(net "P3E_CPU0_PE1_PCH_CON_TXP<9>")
	)
	(segment
		(start 333.41818 -54.18328)
		(end 333.581502 -53.881782)
		(width 0.1143)
		(layer "In9.Cu")
		(net "P3E_CPU0_PE1_PCH_CON_TXP<9>")
	)
	(segment
		(start 330.211684 -90.038428)
		(end 330.01585 -89.911174)
		(width 0.1143)
		(layer "In9.Cu")
		(net "P3E_CPU0_PE1_PCH_CON_TXP<9>")
	)
	(segment
		(start 329.175364 -81.39303)
		(end 328.343768 -77.480668)
		(width 0.1143)
		(layer "In9.Cu")
		(net "P3E_CPU0_PE1_PCH_CON_TXP<9>")
	)
	(segment
		(start 423.892472 -8.128254)
		(end 424.987212 -8.360918)
		(width 0.1143)
		(layer "In9.Cu")
		(net "P3E_CPU0_PE1_PCH_CON_TXP<9>")
	)
	(segment
		(start 429.89754 -8.386572)
		(end 431.363628 -8.074914)
		(width 0.1143)
		(layer "In9.Cu")
		(net "P3E_CPU0_PE1_PCH_CON_TXP<9>")
	)
	(segment
		(start 376.622056 -13.482828)
		(end 379.48362 -12.875768)
		(width 0.1143)
		(layer "In9.Cu")
		(net "P3E_CPU0_PE1_PCH_CON_TXP<9>")
	)
	(segment
		(start 333.031084 -54.551326)
		(end 333.194406 -54.249828)
		(width 0.1143)
		(layer "In9.Cu")
		(net "P3E_CPU0_PE1_PCH_CON_TXP<9>")
	)
	(segment
		(start 372.816628 -16.581374)
		(end 372.770908 -16.35252)
		(width 0.1143)
		(layer "In9.Cu")
		(net "P3E_CPU0_PE1_PCH_CON_TXP<9>")
	)
	(segment
		(start 328.65314 -76.024232)
		(end 328.334624 -74.523346)
		(width 0.1143)
		(layer "In9.Cu")
		(net "P3E_CPU0_PE1_PCH_CON_TXP<9>")
	)
	(segment
		(start 328.343768 -77.480668)
		(end 328.65314 -76.024232)
		(width 0.1143)
		(layer "In9.Cu")
		(net "P3E_CPU0_PE1_PCH_CON_TXP<9>")
	)
	(segment
		(start 359.73258 -45.473112)
		(end 359.733088 -45.472604)
		(width 0.1143)
		(layer "In9.Cu")
		(net "P3E_CPU0_PE1_PCH_CON_TXP<9>")
	)
	(segment
		(start 410.473144 -7.46633)
		(end 415.516568 -8.537702)
		(width 0.1143)
		(layer "In9.Cu")
		(net "P3E_CPU0_PE1_PCH_CON_TXP<9>")
	)
	(segment
		(start 330.915518 -94.150942)
		(end 330.915772 -94.149672)
		(width 0.1143)
		(layer "In9.Cu")
		(net "P3E_CPU0_PE1_PCH_CON_TXP<9>")
	)
	(segment
		(start 360.94543 -43.186858)
		(end 362.322364 -36.495736)
		(width 0.1143)
		(layer "In9.Cu")
		(net "P3E_CPU0_PE1_PCH_CON_TXP<9>")
	)
	(segment
		(start 380.302516 -13.049758)
		(end 387.594094 -11.501374)
		(width 0.1143)
		(layer "In9.Cu")
		(net "P3E_CPU0_PE1_PCH_CON_TXP<9>")
	)
	(segment
		(start 328.334624 -74.523346)
		(end 328.887074 -71.92264)
		(width 0.1143)
		(layer "In9.Cu")
		(net "P3E_CPU0_PE1_PCH_CON_TXP<9>")
	)
	(segment
		(start 333.67853 -53.35651)
		(end 333.902304 -53.289962)
		(width 0.1143)
		(layer "In9.Cu")
		(net "P3E_CPU0_PE1_PCH_CON_TXP<9>")
	)
	(segment
		(start 324.88505 -117.364764)
		(end 324.88505 -110.273592)
		(width 0.1143)
		(layer "In9.Cu")
		(net "P3E_CPU0_PE1_PCH_CON_TXP<9>")
	)
	(segment
		(start 333.999332 -52.76469)
		(end 334.162654 -52.463192)
		(width 0.1143)
		(layer "In9.Cu")
		(net "P3E_CPU0_PE1_PCH_CON_TXP<9>")
	)
	(segment
		(start 335.17586 -51.734212)
		(end 338.32546 -51.09337)
		(width 0.1143)
		(layer "In9.Cu")
		(net "P3E_CPU0_PE1_PCH_CON_TXP<9>")
	)
	(segment
		(start 330.92009 -102.444296)
		(end 331.208888 -98.63709)
		(width 0.1143)
		(layer "In9.Cu")
		(net "P3E_CPU0_PE1_PCH_CON_TXP<9>")
	)
	(segment
		(start 332.710282 -55.143146)
		(end 332.934056 -55.076598)
		(width 0.1143)
		(layer "In9.Cu")
		(net "P3E_CPU0_PE1_PCH_CON_TXP<9>")
	)
	(segment
		(start 368.731292 -20.875244)
		(end 370.516404 -19.733768)
		(width 0.1143)
		(layer "In9.Cu")
		(net "P3E_CPU0_PE1_PCH_CON_TXP<9>")
	)
	(segment
		(start 340.575646 -51.551332)
		(end 357.294434 -47.069248)
		(width 0.1143)
		(layer "In9.Cu")
		(net "P3E_CPU0_PE1_PCH_CON_TXP<9>")
	)
	(segment
		(start 330.226924 -90.905076)
		(end 330.15555 -90.569542)
		(width 0.1143)
		(layer "In9.Cu")
		(net "P3E_CPU0_PE1_PCH_CON_TXP<9>")
	)
	(segment
		(start 333.096108 -118.441216)
		(end 332.504034 -119.03329)
		(width 0.1143)
		(layer "In9.Cu")
		(net "P3E_CPU0_PE1_PCH_CON_TXP<9>")
	)
	(segment
		(start 331.13853 -58.043318)
		(end 332.710282 -55.143146)
		(width 0.1143)
		(layer "In9.Cu")
		(net "P3E_CPU0_PE1_PCH_CON_TXP<9>")
	)
	(segment
		(start 357.294434 -47.069248)
		(end 359.73258 -45.472858)
		(width 0.1143)
		(layer "In9.Cu")
		(net "P3E_CPU0_PE1_PCH_CON_TXP<9>")
	)
	(segment
		(start 330.01585 -89.91092)
		(end 328.657204 -83.511898)
		(width 0.1143)
		(layer "In9.Cu")
		(net "P3E_CPU0_PE1_PCH_CON_TXP<9>")
	)
	(segment
		(start 367.499138 -26.408126)
		(end 368.731292 -20.875244)
		(width 0.1143)
		(layer "In9.Cu")
		(net "P3E_CPU0_PE1_PCH_CON_TXP<9>")
	)
	(segment
		(start 330.493878 -91.36761)
		(end 330.422758 -91.03233)
		(width 0.1143)
		(layer "In9.Cu")
		(net "P3E_CPU0_PE1_PCH_CON_TXP<9>")
	)
	(segment
		(start 428.70501 -8.133334)
		(end 429.89754 -8.386572)
		(width 0.1143)
		(layer "In9.Cu")
		(net "P3E_CPU0_PE1_PCH_CON_TXP<9>")
	)
	(segment
		(start 371.08003 -18.888456)
		(end 371.270276 -18.603214)
		(width 0.1143)
		(layer "In9.Cu")
		(net "P3E_CPU0_PE1_PCH_CON_TXP<9>")
	)
	(segment
		(start 372.253002 -17.426686)
		(end 372.207282 -17.197832)
		(width 0.1143)
		(layer "In9.Cu")
		(net "P3E_CPU0_PE1_PCH_CON_TXP<9>")
	)
	(segment
		(start 330.648818 -92.89288)
		(end 330.577698 -92.557346)
		(width 0.1143)
		(layer "In9.Cu")
		(net "P3E_CPU0_PE1_PCH_CON_TXP<9>")
	)
	(segment
		(start 403.91588 -8.859012)
		(end 410.473144 -7.46633)
		(width 0.1143)
		(layer "In9.Cu")
		(net "P3E_CPU0_PE1_PCH_CON_TXP<9>")
	)
	(segment
		(start 332.504034 -119.03329)
		(end 326.553576 -119.03329)
		(width 0.1143)
		(layer "In9.Cu")
		(net "P3E_CPU0_PE1_PCH_CON_TXP<9>")
	)
	(segment
		(start 333.194406 -54.249828)
		(end 333.41818 -54.18328)
		(width 0.1143)
		(layer "In9.Cu")
		(net "P3E_CPU0_PE1_PCH_CON_TXP<9>")
	)
	(segment
		(start 371.49913 -18.55724)
		(end 371.689376 -18.271998)
		(width 0.1143)
		(layer "In9.Cu")
		(net "P3E_CPU0_PE1_PCH_CON_TXP<9>")
	)
	(segment
		(start 333.097632 -54.7751)
		(end 333.031084 -54.551326)
		(width 0.1143)
		(layer "In9.Cu")
		(net "P3E_CPU0_PE1_PCH_CON_TXP<9>")
	)
	(segment
		(start 424.987212 -8.360918)
		(end 426.3009 -8.082026)
		(width 0.1143)
		(layer "In9.Cu")
		(net "P3E_CPU0_PE1_PCH_CON_TXP<9>")
	)
	(segment
		(start 415.516568 -8.537702)
		(end 417.133786 -8.19404)
		(width 0.1143)
		(layer "In9.Cu")
		(net "P3E_CPU0_PE1_PCH_CON_TXP<9>")
	)
	(segment
		(start 372.062756 -17.711928)
		(end 372.253002 -17.426686)
		(width 0.1143)
		(layer "In9.Cu")
		(net "P3E_CPU0_PE1_PCH_CON_TXP<9>")
	)
	(segment
		(start 379.48362 -12.875768)
		(end 380.302516 -13.049758)
		(width 0.1143)
		(layer "In9.Cu")
		(net "P3E_CPU0_PE1_PCH_CON_TXP<9>")
	)
	(segment
		(start 372.770908 -16.35252)
		(end 373.132858 -15.809214)
		(width 0.1143)
		(layer "In9.Cu")
		(net "P3E_CPU0_PE1_PCH_CON_TXP<9>")
	)
	(segment
		(start 330.422758 -91.03233)
		(end 330.226924 -90.905076)
		(width 0.1143)
		(layer "In9.Cu")
		(net "P3E_CPU0_PE1_PCH_CON_TXP<9>")
	)
	(segment
		(start 371.12575 -19.11731)
		(end 371.08003 -18.888456)
		(width 0.1143)
		(layer "In9.Cu")
		(net "P3E_CPU0_PE1_PCH_CON_TXP<9>")
	)
	(segment
		(start 337.400138 -118.441216)
		(end 333.096108 -118.441216)
		(width 0.1143)
		(layer "In9.Cu")
		(net "P3E_CPU0_PE1_PCH_CON_TXP<9>")
	)
	(segment
		(start 330.15555 -90.569542)
		(end 330.282804 -90.373962)
		(width 0.1143)
		(layer "In9.Cu")
		(net "P3E_CPU0_PE1_PCH_CON_TXP<9>")
	)
	(segment
		(start 372.626382 -16.866616)
		(end 372.816628 -16.581374)
		(width 0.1143)
		(layer "In9.Cu")
		(net "P3E_CPU0_PE1_PCH_CON_TXP<9>")
	)
	(segment
		(start 417.133786 -8.19404)
		(end 417.932108 -8.363712)
		(width 0.1143)
		(layer "In9.Cu")
		(net "P3E_CPU0_PE1_PCH_CON_TXP<9>")
	)
	(segment
		(start 387.594094 -11.501374)
		(end 391.743692 -12.383262)
		(width 0.1143)
		(layer "In9.Cu")
		(net "P3E_CPU0_PE1_PCH_CON_TXP<9>")
	)
	(segment
		(start 326.553576 -119.03329)
		(end 324.88505 -117.364764)
		(width 0.1143)
		(layer "In9.Cu")
		(net "P3E_CPU0_PE1_PCH_CON_TXP<9>")
	)
	(segment
		(start 401.383246 -8.960358)
		(end 402.475192 -8.553958)
		(width 0.1143)
		(layer "In9.Cu")
		(net "P3E_CPU0_PE1_PCH_CON_TXP<9>")
	)
	(segment
		(start 334.065626 -52.988464)
		(end 333.999332 -52.76469)
		(width 0.1143)
		(layer "In9.Cu")
		(net "P3E_CPU0_PE1_PCH_CON_TXP<9>")
	)
	(segment
		(start 371.270276 -18.603214)
		(end 371.49913 -18.55724)
		(width 0.1143)
		(layer "In9.Cu")
		(net "P3E_CPU0_PE1_PCH_CON_TXP<9>")
	)
	(segment
		(start 427.623732 -8.363204)
		(end 428.70501 -8.133334)
		(width 0.1143)
		(layer "In9.Cu")
		(net "P3E_CPU0_PE1_PCH_CON_TXP<9>")
	)
	(segment
		(start 359.733088 -45.472604)
		(end 360.94543 -43.186858)
		(width 0.1143)
		(layer "In9.Cu")
		(net "P3E_CPU0_PE1_PCH_CON_TXP<9>")
	)
	(segment
		(start 359.73258 -45.472858)
		(end 359.73258 -45.473112)
		(width 0.1143)
		(layer "In9.Cu")
		(net "P3E_CPU0_PE1_PCH_CON_TXP<9>")
	)
	(segment
		(start 421.472614 -8.114284)
		(end 422.714928 -8.37819)
		(width 0.1143)
		(layer "In9.Cu")
		(net "P3E_CPU0_PE1_PCH_CON_TXP<9>")
	)
	(segment
		(start 434.124354 -9.9949)
		(end 433.961032 -9.9949)
		(width 0.1143)
		(layer "In9.Cu")
		(net "P3E_CPU0_PE1_PCH_CON_TXP<9>")
	)
	(segment
		(start 330.844652 -93.01988)
		(end 330.648818 -92.89288)
		(width 0.1143)
		(layer "In9.Cu")
		(net "P3E_CPU0_PE1_PCH_CON_TXP<9>")
	)
	(segment
		(start 330.366624 -91.563444)
		(end 330.493878 -91.36761)
		(width 0.1143)
		(layer "In9.Cu")
		(net "P3E_CPU0_PE1_PCH_CON_TXP<9>")
	)
	(segment
		(start 334.162654 -52.463192)
		(end 335.17586 -51.734212)
		(width 0.1143)
		(layer "In9.Cu")
		(net "P3E_CPU0_PE1_PCH_CON_TXP<9>")
	)
	(segment
		(start 331.208888 -98.63709)
		(end 330.585572 -95.703136)
		(width 0.1143)
		(layer "In9.Cu")
		(net "P3E_CPU0_PE1_PCH_CON_TXP<9>")
	)
	(segment
		(start 362.322364 -36.495736)
		(end 365.237776 -32.902398)
		(width 0.1143)
		(layer "In9.Cu")
		(net "P3E_CPU0_PE1_PCH_CON_TXP<9>")
	)
	(segment
		(start 328.657204 -83.511898)
		(end 328.657458 -83.51139)
		(width 0.1143)
		(layer "In9.Cu")
		(net "P3E_CPU0_PE1_PCH_CON_TXP<9>")
	)
	(segment
		(start 337.672426 -117.941598)
		(end 337.672426 -118.168928)
		(width 0.1143)
		(layer "In9.Cu")
		(net "P3E_CPU0_PE1_PCH_CON_TXP<9>")
	)
	(segment
		(start 330.704952 -92.361512)
		(end 330.633578 -92.026232)
		(width 0.1143)
		(layer "In9.Cu")
		(net "P3E_CPU0_PE1_PCH_CON_TXP<9>")
	)
	(segment
		(start 431.615342 -10.078466)
		(end 431.830734 -10.078466)
		(width 0.1143)
		(layer "F.Cu")
		(net "P3E_CPU0_PE1_PCH_CON_TXP<8>")
	)
	(segment
		(start 431.977292 -9.931908)
		(end 431.977292 -8.959342)
		(width 0.1143)
		(layer "F.Cu")
		(net "P3E_CPU0_PE1_PCH_CON_TXP<8>")
	)
	(segment
		(start 431.830734 -10.078466)
		(end 431.977292 -9.931908)
		(width 0.1143)
		(layer "F.Cu")
		(net "P3E_CPU0_PE1_PCH_CON_TXP<8>")
	)
	(segment
		(start 331.2668 -117.35562)
		(end 331.999844 -117.35562)
		(width 0.1143)
		(layer "F.Cu")
		(net "P3E_CPU0_PE1_PCH_CON_TXP<8>")
	)
	(segment
		(start 431.977292 -8.959342)
		(end 431.675286 -8.657336)
		(width 0.1143)
		(layer "F.Cu")
		(net "P3E_CPU0_PE1_PCH_CON_TXP<8>")
	)
	(segment
		(start 431.675286 -8.657336)
		(end 431.675286 -7.789672)
		(width 0.1143)
		(layer "F.Cu")
		(net "P3E_CPU0_PE1_PCH_CON_TXP<8>")
	)
	(via
		(at 431.615342 -10.078466)
		(size 0.508)
		(drill 0.254)
		(layers "F.Cu" "B.Cu")
		(net "P3E_CPU0_PE1_PCH_CON_TXP<8>")
	)
	(via
		(at 331.2668 -117.35562)
		(size 0.508)
		(drill 0.254)
		(layers "F.Cu" "B.Cu")
		(net "P3E_CPU0_PE1_PCH_CON_TXP<8>")
	)
	(segment
		(start 328.632312 -107.954318)
		(end 326.001888 -110.584742)
		(width 0.1143)
		(layer "In9.Cu")
		(net "P3E_CPU0_PE1_PCH_CON_TXP<8>")
	)
	(segment
		(start 329.538838 -71.92264)
		(end 328.986388 -74.523346)
		(width 0.1143)
		(layer "In9.Cu")
		(net "P3E_CPU0_PE1_PCH_CON_TXP<8>")
	)
	(segment
		(start 403.29866 -9.408668)
		(end 403.036786 -9.464548)
		(width 0.1143)
		(layer "In9.Cu")
		(net "P3E_CPU0_PE1_PCH_CON_TXP<8>")
	)
	(segment
		(start 330.504292 -104.894126)
		(end 330.339192 -105.194354)
		(width 0.1143)
		(layer "In9.Cu")
		(net "P3E_CPU0_PE1_PCH_CON_TXP<8>")
	)
	(segment
		(start 431.615342 -10.078466)
		(end 431.754534 -10.078466)
		(width 0.1143)
		(layer "In9.Cu")
		(net "P3E_CPU0_PE1_PCH_CON_TXP<8>")
	)
	(segment
		(start 366.446308 -30.875224)
		(end 366.01908 -33.011618)
		(width 0.1143)
		(layer "In9.Cu")
		(net "P3E_CPU0_PE1_PCH_CON_TXP<8>")
	)
	(segment
		(start 401.640294 -10.092436)
		(end 401.37842 -10.148316)
		(width 0.1143)
		(layer "In9.Cu")
		(net "P3E_CPU0_PE1_PCH_CON_TXP<8>")
	)
	(segment
		(start 329.84567 -81.483454)
		(end 329.425808 -83.20278)
		(width 0.1143)
		(layer "In9.Cu")
		(net "P3E_CPU0_PE1_PCH_CON_TXP<8>")
	)
	(segment
		(start 330.01458 -105.784396)
		(end 329.84948 -106.084624)
		(width 0.1143)
		(layer "In9.Cu")
		(net "P3E_CPU0_PE1_PCH_CON_TXP<8>")
	)
	(segment
		(start 329.47356 -78.937104)
		(end 329.544934 -79.272638)
		(width 0.1143)
		(layer "In9.Cu")
		(net "P3E_CPU0_PE1_PCH_CON_TXP<8>")
	)
	(segment
		(start 330.439268 -104.669844)
		(end 330.504292 -104.894126)
		(width 0.1143)
		(layer "In9.Cu")
		(net "P3E_CPU0_PE1_PCH_CON_TXP<8>")
	)
	(segment
		(start 431.754534 -10.078466)
		(end 431.9651 -9.8679)
		(width 0.1143)
		(layer "In9.Cu")
		(net "P3E_CPU0_PE1_PCH_CON_TXP<8>")
	)
	(segment
		(start 340.698582 -52.263548)
		(end 338.32546 -51.78044)
		(width 0.1143)
		(layer "In9.Cu")
		(net "P3E_CPU0_PE1_PCH_CON_TXP<8>")
	)
	(segment
		(start 330.828904 -104.304084)
		(end 330.604622 -104.369362)
		(width 0.1143)
		(layer "In9.Cu")
		(net "P3E_CPU0_PE1_PCH_CON_TXP<8>")
	)
	(segment
		(start 402.16328 -10.741152)
		(end 401.85213 -10.53846)
		(width 0.1143)
		(layer "In9.Cu")
		(net "P3E_CPU0_PE1_PCH_CON_TXP<8>")
	)
	(segment
		(start 332.677516 -57.246266)
		(end 332.51394 -57.547764)
		(width 0.1143)
		(layer "In9.Cu")
		(net "P3E_CPU0_PE1_PCH_CON_TXP<8>")
	)
	(segment
		(start 331.806042 -58.50763)
		(end 331.64272 -58.809128)
		(width 0.1143)
		(layer "In9.Cu")
		(net "P3E_CPU0_PE1_PCH_CON_TXP<8>")
	)
	(segment
		(start 329.489054 -79.804006)
		(end 329.684634 -79.931006)
		(width 0.1143)
		(layer "In9.Cu")
		(net "P3E_CPU0_PE1_PCH_CON_TXP<8>")
	)
	(segment
		(start 329.684634 -79.931006)
		(end 329.756008 -80.26654)
		(width 0.1143)
		(layer "In9.Cu")
		(net "P3E_CPU0_PE1_PCH_CON_TXP<8>")
	)
	(segment
		(start 338.32546 -51.78044)
		(end 335.457038 -52.364132)
		(width 0.1143)
		(layer "In9.Cu")
		(net "P3E_CPU0_PE1_PCH_CON_TXP<8>")
	)
	(segment
		(start 376.873262 -14.07922)
		(end 374.812814 -15.45336)
		(width 0.1143)
		(layer "In9.Cu")
		(net "P3E_CPU0_PE1_PCH_CON_TXP<8>")
	)
	(segment
		(start 368.969798 -22.733)
		(end 368.060224 -26.814018)
		(width 0.1143)
		(layer "In9.Cu")
		(net "P3E_CPU0_PE1_PCH_CON_TXP<8>")
	)
	(segment
		(start 331.418692 -102.889304)
		(end 331.483716 -103.113586)
		(width 0.1143)
		(layer "In9.Cu")
		(net "P3E_CPU0_PE1_PCH_CON_TXP<8>")
	)
	(segment
		(start 331.318616 -103.413814)
		(end 331.094334 -103.479092)
		(width 0.1143)
		(layer "In9.Cu")
		(net "P3E_CPU0_PE1_PCH_CON_TXP<8>")
	)
	(segment
		(start 431.82921 -8.885936)
		(end 431.828956 -8.885936)
		(width 0.1143)
		(layer "In9.Cu")
		(net "P3E_CPU0_PE1_PCH_CON_TXP<8>")
	)
	(segment
		(start 401.85213 -10.53846)
		(end 401.775676 -10.18032)
		(width 0.1143)
		(layer "In9.Cu")
		(net "P3E_CPU0_PE1_PCH_CON_TXP<8>")
	)
	(segment
		(start 374.812814 -15.45336)
		(end 370.74983 -21.547074)
		(width 0.1143)
		(layer "In9.Cu")
		(net "P3E_CPU0_PE1_PCH_CON_TXP<8>")
	)
	(segment
		(start 417.117276 -8.852662)
		(end 415.480246 -9.200388)
		(width 0.1143)
		(layer "In9.Cu")
		(net "P3E_CPU0_PE1_PCH_CON_TXP<8>")
	)
	(segment
		(start 332.610968 -57.022492)
		(end 332.677516 -57.246266)
		(width 0.1143)
		(layer "In9.Cu")
		(net "P3E_CPU0_PE1_PCH_CON_TXP<8>")
	)
	(segment
		(start 403.080474 -10.214102)
		(end 402.763482 -10.701274)
		(width 0.1143)
		(layer "In9.Cu")
		(net "P3E_CPU0_PE1_PCH_CON_TXP<8>")
	)
	(segment
		(start 362.937552 -36.808918)
		(end 361.587796 -43.365928)
		(width 0.1143)
		(layer "In9.Cu")
		(net "P3E_CPU0_PE1_PCH_CON_TXP<8>")
	)
	(segment
		(start 329.33386 -78.278736)
		(end 329.206606 -78.47457)
		(width 0.1143)
		(layer "In9.Cu")
		(net "P3E_CPU0_PE1_PCH_CON_TXP<8>")
	)
	(segment
		(start 329.41768 -79.468472)
		(end 329.489054 -79.804006)
		(width 0.1143)
		(layer "In9.Cu")
		(net "P3E_CPU0_PE1_PCH_CON_TXP<8>")
	)
	(segment
		(start 426.3009 -8.744204)
		(end 424.987212 -9.023096)
		(width 0.1143)
		(layer "In9.Cu")
		(net "P3E_CPU0_PE1_PCH_CON_TXP<8>")
	)
	(segment
		(start 331.27569 -95.53575)
		(end 331.897736 -98.46437)
		(width 0.1143)
		(layer "In9.Cu")
		(net "P3E_CPU0_PE1_PCH_CON_TXP<8>")
	)
	(segment
		(start 331.094334 -103.479092)
		(end 330.92898 -103.779574)
		(width 0.1143)
		(layer "In9.Cu")
		(net "P3E_CPU0_PE1_PCH_CON_TXP<8>")
	)
	(segment
		(start 331.263244 -91.063572)
		(end 331.334618 -91.399106)
		(width 0.1143)
		(layer "In9.Cu")
		(net "P3E_CPU0_PE1_PCH_CON_TXP<8>")
	)
	(segment
		(start 327.545954 -117.72646)
		(end 331.1779 -117.72646)
		(width 0.1143)
		(layer "In9.Cu")
		(net "P3E_CPU0_PE1_PCH_CON_TXP<8>")
	)
	(segment
		(start 330.994004 -104.003856)
		(end 330.828904 -104.304084)
		(width 0.1143)
		(layer "In9.Cu")
		(net "P3E_CPU0_PE1_PCH_CON_TXP<8>")
	)
	(segment
		(start 332.193392 -58.139584)
		(end 332.029816 -58.441082)
		(width 0.1143)
		(layer "In9.Cu")
		(net "P3E_CPU0_PE1_PCH_CON_TXP<8>")
	)
	(segment
		(start 360.233722 -45.918628)
		(end 360.167682 -45.961808)
		(width 0.1143)
		(layer "In9.Cu")
		(net "P3E_CPU0_PE1_PCH_CON_TXP<8>")
	)
	(segment
		(start 403.591776 -10.23366)
		(end 403.434042 -9.496552)
		(width 0.1143)
		(layer "In9.Cu")
		(net "P3E_CPU0_PE1_PCH_CON_TXP<8>")
	)
	(segment
		(start 331.207364 -91.594686)
		(end 331.278484 -91.93022)
		(width 0.1143)
		(layer "In9.Cu")
		(net "P3E_CPU0_PE1_PCH_CON_TXP<8>")
	)
	(segment
		(start 331.483716 -103.113586)
		(end 331.318616 -103.413814)
		(width 0.1143)
		(layer "In9.Cu")
		(net "P3E_CPU0_PE1_PCH_CON_TXP<8>")
	)
	(segment
		(start 389.561832 -12.596368)
		(end 387.536182 -12.165838)
		(width 0.1143)
		(layer "In9.Cu")
		(net "P3E_CPU0_PE1_PCH_CON_TXP<8>")
	)
	(segment
		(start 331.278484 -91.93022)
		(end 331.474318 -92.057474)
		(width 0.1143)
		(layer "In9.Cu")
		(net "P3E_CPU0_PE1_PCH_CON_TXP<8>")
	)
	(segment
		(start 421.472614 -8.776462)
		(end 420.287704 -9.02843)
		(width 0.1143)
		(layer "In9.Cu")
		(net "P3E_CPU0_PE1_PCH_CON_TXP<8>")
	)
	(segment
		(start 401.37842 -10.148316)
		(end 401.290536 -10.283444)
		(width 0.1143)
		(layer "In9.Cu")
		(net "P3E_CPU0_PE1_PCH_CON_TXP<8>")
	)
	(segment
		(start 431.319686 -8.737092)
		(end 429.874934 -9.043924)
		(width 0.1143)
		(layer "In9.Cu")
		(net "P3E_CPU0_PE1_PCH_CON_TXP<8>")
	)
	(segment
		(start 408.937206 -8.452612)
		(end 405.856948 -9.108186)
		(width 0.1143)
		(layer "In9.Cu")
		(net "P3E_CPU0_PE1_PCH_CON_TXP<8>")
	)
	(segment
		(start 402.763482 -10.701274)
		(end 402.391372 -10.780776)
		(width 0.1143)
		(layer "In9.Cu")
		(net "P3E_CPU0_PE1_PCH_CON_TXP<8>")
	)
	(segment
		(start 329.756008 -80.26654)
		(end 329.628754 -80.462374)
		(width 0.1143)
		(layer "In9.Cu")
		(net "P3E_CPU0_PE1_PCH_CON_TXP<8>")
	)
	(segment
		(start 329.84948 -106.084624)
		(end 329.625198 -106.149902)
		(width 0.1143)
		(layer "In9.Cu")
		(net "P3E_CPU0_PE1_PCH_CON_TXP<8>")
	)
	(segment
		(start 409.520644 -9.209024)
		(end 409.183078 -8.99033)
		(width 0.1143)
		(layer "In9.Cu")
		(net "P3E_CPU0_PE1_PCH_CON_TXP<8>")
	)
	(segment
		(start 335.457038 -52.364132)
		(end 334.929988 -52.743354)
		(width 0.1143)
		(layer "In9.Cu")
		(net "P3E_CPU0_PE1_PCH_CON_TXP<8>")
	)
	(segment
		(start 389.562086 -12.596368)
		(end 389.561832 -12.596368)
		(width 0.1143)
		(layer "In9.Cu")
		(net "P3E_CPU0_PE1_PCH_CON_TXP<8>")
	)
	(segment
		(start 334.929988 -52.743354)
		(end 332.610968 -57.022492)
		(width 0.1143)
		(layer "In9.Cu")
		(net "P3E_CPU0_PE1_PCH_CON_TXP<8>")
	)
	(segment
		(start 387.536182 -12.165838)
		(end 380.280926 -13.706602)
		(width 0.1143)
		(layer "In9.Cu")
		(net "P3E_CPU0_PE1_PCH_CON_TXP<8>")
	)
	(segment
		(start 329.425808 -83.20278)
		(end 331.06741 -90.936318)
		(width 0.1143)
		(layer "In9.Cu")
		(net "P3E_CPU0_PE1_PCH_CON_TXP<8>")
	)
	(segment
		(start 328.986388 -74.523346)
		(end 329.30465 -76.024232)
		(width 0.1143)
		(layer "In9.Cu")
		(net "P3E_CPU0_PE1_PCH_CON_TXP<8>")
	)
	(segment
		(start 366.01908 -33.011618)
		(end 362.937552 -36.808918)
		(width 0.1143)
		(layer "In9.Cu")
		(net "P3E_CPU0_PE1_PCH_CON_TXP<8>")
	)
	(segment
		(start 366.53978 -27.82316)
		(end 366.18799 -29.581856)
		(width 0.1143)
		(layer "In9.Cu")
		(net "P3E_CPU0_PE1_PCH_CON_TXP<8>")
	)
	(segment
		(start 332.51394 -57.547764)
		(end 332.290166 -57.614312)
		(width 0.1143)
		(layer "In9.Cu")
		(net "P3E_CPU0_PE1_PCH_CON_TXP<8>")
	)
	(segment
		(start 431.9651 -9.8679)
		(end 431.9651 -9.021826)
		(width 0.1143)
		(layer "In9.Cu")
		(net "P3E_CPU0_PE1_PCH_CON_TXP<8>")
	)
	(segment
		(start 329.277726 -78.810104)
		(end 329.47356 -78.937104)
		(width 0.1143)
		(layer "In9.Cu")
		(net "P3E_CPU0_PE1_PCH_CON_TXP<8>")
	)
	(segment
		(start 420.287704 -9.02843)
		(end 419.083744 -8.772652)
		(width 0.1143)
		(layer "In9.Cu")
		(net "P3E_CPU0_PE1_PCH_CON_TXP<8>")
	)
	(segment
		(start 329.250548 -70.565264)
		(end 329.538838 -71.92264)
		(width 0.1143)
		(layer "In9.Cu")
		(net "P3E_CPU0_PE1_PCH_CON_TXP<8>")
	)
	(segment
		(start 423.892472 -8.790432)
		(end 422.714928 -9.040368)
		(width 0.1143)
		(layer "In9.Cu")
		(net "P3E_CPU0_PE1_PCH_CON_TXP<8>")
	)
	(segment
		(start 402.948902 -9.599676)
		(end 403.080474 -10.214102)
		(width 0.1143)
		(layer "In9.Cu")
		(net "P3E_CPU0_PE1_PCH_CON_TXP<8>")
	)
	(segment
		(start 329.544934 -79.272638)
		(end 329.41768 -79.468472)
		(width 0.1143)
		(layer "In9.Cu")
		(net "P3E_CPU0_PE1_PCH_CON_TXP<8>")
	)
	(segment
		(start 403.433788 -9.496552)
		(end 403.29866 -9.408668)
		(width 0.1143)
		(layer "In9.Cu")
		(net "P3E_CPU0_PE1_PCH_CON_TXP<8>")
	)
	(segment
		(start 405.128984 -10.198354)
		(end 403.930358 -10.453116)
		(width 0.1143)
		(layer "In9.Cu")
		(net "P3E_CPU0_PE1_PCH_CON_TXP<8>")
	)
	(segment
		(start 331.2668 -117.63756)
		(end 331.2668 -117.35562)
		(width 0.1143)
		(layer "In9.Cu")
		(net "P3E_CPU0_PE1_PCH_CON_TXP<8>")
	)
	(segment
		(start 428.679356 -8.789924)
		(end 427.598078 -9.019794)
		(width 0.1143)
		(layer "In9.Cu")
		(net "P3E_CPU0_PE1_PCH_CON_TXP<8>")
	)
	(segment
		(start 391.709656 -13.052806)
		(end 389.562086 -12.596368)
		(width 0.1143)
		(layer "In9.Cu")
		(net "P3E_CPU0_PE1_PCH_CON_TXP<8>")
	)
	(segment
		(start 331.897736 -98.46437)
		(end 331.897736 -98.464624)
		(width 0.1143)
		(layer "In9.Cu")
		(net "P3E_CPU0_PE1_PCH_CON_TXP<8>")
	)
	(segment
		(start 330.339192 -105.194354)
		(end 330.24953 -105.220516)
		(width 0.1143)
		(layer "In9.Cu")
		(net "P3E_CPU0_PE1_PCH_CON_TXP<8>")
	)
	(segment
		(start 328.995532 -77.480668)
		(end 329.066652 -77.816202)
		(width 0.1143)
		(layer "In9.Cu")
		(net "P3E_CPU0_PE1_PCH_CON_TXP<8>")
	)
	(segment
		(start 331.685138 -101.261164)
		(end 331.584046 -102.588822)
		(width 0.1143)
		(layer "In9.Cu")
		(net "P3E_CPU0_PE1_PCH_CON_TXP<8>")
	)
	(segment
		(start 331.64272 -58.809128)
		(end 329.250548 -70.565264)
		(width 0.1143)
		(layer "In9.Cu")
		(net "P3E_CPU0_PE1_PCH_CON_TXP<8>")
	)
	(segment
		(start 403.036786 -9.464548)
		(end 402.948902 -9.599676)
		(width 0.1143)
		(layer "In9.Cu")
		(net "P3E_CPU0_PE1_PCH_CON_TXP<8>")
	)
	(segment
		(start 330.92898 -103.779574)
		(end 330.994004 -104.003856)
		(width 0.1143)
		(layer "In9.Cu")
		(net "P3E_CPU0_PE1_PCH_CON_TXP<8>")
	)
	(segment
		(start 329.066652 -77.816202)
		(end 329.262486 -77.943202)
		(width 0.1143)
		(layer "In9.Cu")
		(net "P3E_CPU0_PE1_PCH_CON_TXP<8>")
	)
	(segment
		(start 326.001888 -116.182394)
		(end 327.545954 -117.72646)
		(width 0.1143)
		(layer "In9.Cu")
		(net "P3E_CPU0_PE1_PCH_CON_TXP<8>")
	)
	(segment
		(start 331.1779 -117.72646)
		(end 331.2668 -117.63756)
		(width 0.1143)
		(layer "In9.Cu")
		(net "P3E_CPU0_PE1_PCH_CON_TXP<8>")
	)
	(segment
		(start 366.18799 -29.581856)
		(end 366.446308 -30.875224)
		(width 0.1143)
		(layer "In9.Cu")
		(net "P3E_CPU0_PE1_PCH_CON_TXP<8>")
	)
	(segment
		(start 422.714928 -9.040368)
		(end 421.472614 -8.776462)
		(width 0.1143)
		(layer "In9.Cu")
		(net "P3E_CPU0_PE1_PCH_CON_TXP<8>")
	)
	(segment
		(start 331.659992 -93.727524)
		(end 331.27569 -95.53575)
		(width 0.1143)
		(layer "In9.Cu")
		(net "P3E_CPU0_PE1_PCH_CON_TXP<8>")
	)
	(segment
		(start 331.897736 -98.464624)
		(end 331.685138 -101.261164)
		(width 0.1143)
		(layer "In9.Cu")
		(net "P3E_CPU0_PE1_PCH_CON_TXP<8>")
	)
	(segment
		(start 329.625198 -106.149902)
		(end 328.632312 -107.954318)
		(width 0.1143)
		(layer "In9.Cu")
		(net "P3E_CPU0_PE1_PCH_CON_TXP<8>")
	)
	(segment
		(start 403.434042 -9.496552)
		(end 403.433788 -9.496552)
		(width 0.1143)
		(layer "In9.Cu")
		(net "P3E_CPU0_PE1_PCH_CON_TXP<8>")
	)
	(segment
		(start 361.587796 -43.365928)
		(end 360.233722 -45.918628)
		(width 0.1143)
		(layer "In9.Cu")
		(net "P3E_CPU0_PE1_PCH_CON_TXP<8>")
	)
	(segment
		(start 330.24953 -105.220516)
		(end 330.11491 -105.259632)
		(width 0.1143)
		(layer "In9.Cu")
		(net "P3E_CPU0_PE1_PCH_CON_TXP<8>")
	)
	(segment
		(start 401.16125 -11.042396)
		(end 391.709656 -13.052806)
		(width 0.1143)
		(layer "In9.Cu")
		(net "P3E_CPU0_PE1_PCH_CON_TXP<8>")
	)
	(segment
		(start 368.060224 -26.814018)
		(end 366.53978 -27.82316)
		(width 0.1143)
		(layer "In9.Cu")
		(net "P3E_CPU0_PE1_PCH_CON_TXP<8>")
	)
	(segment
		(start 330.11491 -105.259632)
		(end 329.949556 -105.560114)
		(width 0.1143)
		(layer "In9.Cu")
		(net "P3E_CPU0_PE1_PCH_CON_TXP<8>")
	)
	(segment
		(start 331.474318 -92.057474)
		(end 331.545438 -92.392754)
		(width 0.1143)
		(layer "In9.Cu")
		(net "P3E_CPU0_PE1_PCH_CON_TXP<8>")
	)
	(segment
		(start 409.089098 -8.551418)
		(end 408.937206 -8.452612)
		(width 0.1143)
		(layer "In9.Cu")
		(net "P3E_CPU0_PE1_PCH_CON_TXP<8>")
	)
	(segment
		(start 329.84567 -81.4832)
		(end 329.84567 -81.483454)
		(width 0.1143)
		(layer "In9.Cu")
		(net "P3E_CPU0_PE1_PCH_CON_TXP<8>")
	)
	(segment
		(start 431.9651 -9.021826)
		(end 431.82921 -8.885936)
		(width 0.1143)
		(layer "In9.Cu")
		(net "P3E_CPU0_PE1_PCH_CON_TXP<8>")
	)
	(segment
		(start 409.183078 -8.99033)
		(end 409.089098 -8.551418)
		(width 0.1143)
		(layer "In9.Cu")
		(net "P3E_CPU0_PE1_PCH_CON_TXP<8>")
	)
	(segment
		(start 405.856948 -9.108186)
		(end 405.128984 -10.198354)
		(width 0.1143)
		(layer "In9.Cu")
		(net "P3E_CPU0_PE1_PCH_CON_TXP<8>")
	)
	(segment
		(start 417.911534 -9.021572)
		(end 417.117276 -8.852662)
		(width 0.1143)
		(layer "In9.Cu")
		(net "P3E_CPU0_PE1_PCH_CON_TXP<8>")
	)
	(segment
		(start 401.290536 -10.283444)
		(end 401.380452 -10.703306)
		(width 0.1143)
		(layer "In9.Cu")
		(net "P3E_CPU0_PE1_PCH_CON_TXP<8>")
	)
	(segment
		(start 326.001888 -110.584742)
		(end 326.001888 -116.182394)
		(width 0.1143)
		(layer "In9.Cu")
		(net "P3E_CPU0_PE1_PCH_CON_TXP<8>")
	)
	(segment
		(start 424.987212 -9.023096)
		(end 423.892472 -8.790432)
		(width 0.1143)
		(layer "In9.Cu")
		(net "P3E_CPU0_PE1_PCH_CON_TXP<8>")
	)
	(segment
		(start 331.584046 -102.588822)
		(end 331.418692 -102.889304)
		(width 0.1143)
		(layer "In9.Cu")
		(net "P3E_CPU0_PE1_PCH_CON_TXP<8>")
	)
	(segment
		(start 360.167682 -45.961808)
		(end 357.578406 -47.657766)
		(width 0.1143)
		(layer "In9.Cu")
		(net "P3E_CPU0_PE1_PCH_CON_TXP<8>")
	)
	(segment
		(start 427.598078 -9.019794)
		(end 426.3009 -8.744204)
		(width 0.1143)
		(layer "In9.Cu")
		(net "P3E_CPU0_PE1_PCH_CON_TXP<8>")
	)
	(segment
		(start 410.445712 -8.13181)
		(end 410.230574 -8.177784)
		(width 0.1143)
		(layer "In9.Cu")
		(net "P3E_CPU0_PE1_PCH_CON_TXP<8>")
	)
	(segment
		(start 403.930358 -10.453116)
		(end 403.591776 -10.23366)
		(width 0.1143)
		(layer "In9.Cu")
		(net "P3E_CPU0_PE1_PCH_CON_TXP<8>")
	)
	(segment
		(start 410.239464 -8.764524)
		(end 410.020516 -9.10336)
		(width 0.1143)
		(layer "In9.Cu")
		(net "P3E_CPU0_PE1_PCH_CON_TXP<8>")
	)
	(segment
		(start 401.775422 -10.18032)
		(end 401.640294 -10.092436)
		(width 0.1143)
		(layer "In9.Cu")
		(net "P3E_CPU0_PE1_PCH_CON_TXP<8>")
	)
	(segment
		(start 329.262486 -77.943202)
		(end 329.33386 -78.278736)
		(width 0.1143)
		(layer "In9.Cu")
		(net "P3E_CPU0_PE1_PCH_CON_TXP<8>")
	)
	(segment
		(start 331.334618 -91.399106)
		(end 331.207364 -91.594686)
		(width 0.1143)
		(layer "In9.Cu")
		(net "P3E_CPU0_PE1_PCH_CON_TXP<8>")
	)
	(segment
		(start 330.604622 -104.369362)
		(end 330.439268 -104.669844)
		(width 0.1143)
		(layer "In9.Cu")
		(net "P3E_CPU0_PE1_PCH_CON_TXP<8>")
	)
	(segment
		(start 410.230574 -8.177784)
		(end 410.142944 -8.313166)
		(width 0.1143)
		(layer "In9.Cu")
		(net "P3E_CPU0_PE1_PCH_CON_TXP<8>")
	)
	(segment
		(start 379.45568 -13.531342)
		(end 376.873262 -14.07922)
		(width 0.1143)
		(layer "In9.Cu")
		(net "P3E_CPU0_PE1_PCH_CON_TXP<8>")
	)
	(segment
		(start 410.142944 -8.313166)
		(end 410.239464 -8.764524)
		(width 0.1143)
		(layer "In9.Cu")
		(net "P3E_CPU0_PE1_PCH_CON_TXP<8>")
	)
	(segment
		(start 429.874934 -9.043924)
		(end 428.679356 -8.789924)
		(width 0.1143)
		(layer "In9.Cu")
		(net "P3E_CPU0_PE1_PCH_CON_TXP<8>")
	)
	(segment
		(start 329.628754 -80.462374)
		(end 329.84567 -81.4832)
		(width 0.1143)
		(layer "In9.Cu")
		(net "P3E_CPU0_PE1_PCH_CON_TXP<8>")
	)
	(segment
		(start 419.083744 -8.772652)
		(end 417.911534 -9.021572)
		(width 0.1143)
		(layer "In9.Cu")
		(net "P3E_CPU0_PE1_PCH_CON_TXP<8>")
	)
	(segment
		(start 331.06741 -90.936318)
		(end 331.263244 -91.063572)
		(width 0.1143)
		(layer "In9.Cu")
		(net "P3E_CPU0_PE1_PCH_CON_TXP<8>")
	)
	(segment
		(start 402.391372 -10.780776)
		(end 402.16328 -10.741152)
		(width 0.1143)
		(layer "In9.Cu")
		(net "P3E_CPU0_PE1_PCH_CON_TXP<8>")
	)
	(segment
		(start 410.020516 -9.10336)
		(end 409.520644 -9.209024)
		(width 0.1143)
		(layer "In9.Cu")
		(net "P3E_CPU0_PE1_PCH_CON_TXP<8>")
	)
	(segment
		(start 329.30465 -76.024232)
		(end 328.995532 -77.480668)
		(width 0.1143)
		(layer "In9.Cu")
		(net "P3E_CPU0_PE1_PCH_CON_TXP<8>")
	)
	(segment
		(start 331.545438 -92.392754)
		(end 331.418184 -92.588588)
		(width 0.1143)
		(layer "In9.Cu")
		(net "P3E_CPU0_PE1_PCH_CON_TXP<8>")
	)
	(segment
		(start 431.828956 -8.885936)
		(end 431.319686 -8.737092)
		(width 0.1143)
		(layer "In9.Cu")
		(net "P3E_CPU0_PE1_PCH_CON_TXP<8>")
	)
	(segment
		(start 357.578406 -47.657766)
		(end 340.698582 -52.263548)
		(width 0.1143)
		(layer "In9.Cu")
		(net "P3E_CPU0_PE1_PCH_CON_TXP<8>")
	)
	(segment
		(start 401.380452 -10.703306)
		(end 401.16125 -11.042396)
		(width 0.1143)
		(layer "In9.Cu")
		(net "P3E_CPU0_PE1_PCH_CON_TXP<8>")
	)
	(segment
		(start 332.126844 -57.91581)
		(end 332.193392 -58.139584)
		(width 0.1143)
		(layer "In9.Cu")
		(net "P3E_CPU0_PE1_PCH_CON_TXP<8>")
	)
	(segment
		(start 332.029816 -58.441082)
		(end 331.806042 -58.50763)
		(width 0.1143)
		(layer "In9.Cu")
		(net "P3E_CPU0_PE1_PCH_CON_TXP<8>")
	)
	(segment
		(start 370.74983 -21.547074)
		(end 368.969798 -22.733)
		(width 0.1143)
		(layer "In9.Cu")
		(net "P3E_CPU0_PE1_PCH_CON_TXP<8>")
	)
	(segment
		(start 332.290166 -57.614312)
		(end 332.126844 -57.91581)
		(width 0.1143)
		(layer "In9.Cu")
		(net "P3E_CPU0_PE1_PCH_CON_TXP<8>")
	)
	(segment
		(start 380.280926 -13.706602)
		(end 379.45568 -13.531342)
		(width 0.1143)
		(layer "In9.Cu")
		(net "P3E_CPU0_PE1_PCH_CON_TXP<8>")
	)
	(segment
		(start 329.206606 -78.47457)
		(end 329.277726 -78.810104)
		(width 0.1143)
		(layer "In9.Cu")
		(net "P3E_CPU0_PE1_PCH_CON_TXP<8>")
	)
	(segment
		(start 329.949556 -105.560114)
		(end 330.01458 -105.784396)
		(width 0.1143)
		(layer "In9.Cu")
		(net "P3E_CPU0_PE1_PCH_CON_TXP<8>")
	)
	(segment
		(start 331.418184 -92.588588)
		(end 331.659992 -93.727524)
		(width 0.1143)
		(layer "In9.Cu")
		(net "P3E_CPU0_PE1_PCH_CON_TXP<8>")
	)
	(segment
		(start 401.775676 -10.18032)
		(end 401.775422 -10.18032)
		(width 0.1143)
		(layer "In9.Cu")
		(net "P3E_CPU0_PE1_PCH_CON_TXP<8>")
	)
	(segment
		(start 415.480246 -9.200388)
		(end 410.445712 -8.13181)
		(width 0.1143)
		(layer "In9.Cu")
		(net "P3E_CPU0_PE1_PCH_CON_TXP<8>")
	)
	(segment
		(start 445.663066 -10.002266)
		(end 445.863726 -10.588752)
		(width 0.1143)
		(layer "F.Cu")
		(net "P3E_CPU0_PE1_PCH_CON_TXP<15>")
	)
	(segment
		(start 446.39865 -10.962386)
		(end 446.39865 -11.12393)
		(width 0.1143)
		(layer "F.Cu")
		(net "P3E_CPU0_PE1_PCH_CON_TXP<15>")
	)
	(segment
		(start 445.994536 -10.719816)
		(end 446.156334 -10.719816)
		(width 0.1143)
		(layer "F.Cu")
		(net "P3E_CPU0_PE1_PCH_CON_TXP<15>")
	)
	(segment
		(start 445.863726 -10.588752)
		(end 445.994536 -10.719816)
		(width 0.1143)
		(layer "F.Cu")
		(net "P3E_CPU0_PE1_PCH_CON_TXP<15>")
	)
	(segment
		(start 446.98412 -11.3665)
		(end 447.09842 -11.2522)
		(width 0.1143)
		(layer "F.Cu")
		(net "P3E_CPU0_PE1_PCH_CON_TXP<15>")
	)
	(segment
		(start 445.8716 -9.5758)
		(end 445.663066 -10.002266)
		(width 0.1143)
		(layer "F.Cu")
		(net "P3E_CPU0_PE1_PCH_CON_TXP<15>")
	)
	(segment
		(start 453.10425 -9.426702)
		(end 453.486266 -9.044686)
		(width 0.1143)
		(layer "F.Cu")
		(net "P3E_CPU0_PE1_PCH_CON_TXP<15>")
	)
	(segment
		(start 319.1129 -123.46432)
		(end 319.26022 -123.317)
		(width 0.1143)
		(layer "F.Cu")
		(net "P3E_CPU0_PE1_PCH_CON_TXP<15>")
	)
	(segment
		(start 446.156334 -10.719816)
		(end 446.39865 -10.962386)
		(width 0.1143)
		(layer "F.Cu")
		(net "P3E_CPU0_PE1_PCH_CON_TXP<15>")
	)
	(segment
		(start 450.18452 -11.2522)
		(end 450.29882 -11.3665)
		(width 0.1143)
		(layer "F.Cu")
		(net "P3E_CPU0_PE1_PCH_CON_TXP<15>")
	)
	(segment
		(start 449.38442 -11.3665)
		(end 449.72732 -11.3665)
		(width 0.1143)
		(layer "F.Cu")
		(net "P3E_CPU0_PE1_PCH_CON_TXP<15>")
	)
	(segment
		(start 447.44132 -11.2522)
		(end 447.55562 -11.3665)
		(width 0.1143)
		(layer "F.Cu")
		(net "P3E_CPU0_PE1_PCH_CON_TXP<15>")
	)
	(segment
		(start 451.811136 -10.719816)
		(end 452.053452 -10.4775)
		(width 0.1143)
		(layer "F.Cu")
		(net "P3E_CPU0_PE1_PCH_CON_TXP<15>")
	)
	(segment
		(start 448.35572 -11.2522)
		(end 448.47002 -11.3665)
		(width 0.1143)
		(layer "F.Cu")
		(net "P3E_CPU0_PE1_PCH_CON_TXP<15>")
	)
	(segment
		(start 446.39865 -11.12393)
		(end 446.64122 -11.3665)
		(width 0.1143)
		(layer "F.Cu")
		(net "P3E_CPU0_PE1_PCH_CON_TXP<15>")
	)
	(segment
		(start 452.053452 -10.4775)
		(end 452.053452 -10.315702)
		(width 0.1143)
		(layer "F.Cu")
		(net "P3E_CPU0_PE1_PCH_CON_TXP<15>")
	)
	(segment
		(start 452.457566 -10.073386)
		(end 452.700136 -9.830816)
		(width 0.1143)
		(layer "F.Cu")
		(net "P3E_CPU0_PE1_PCH_CON_TXP<15>")
	)
	(segment
		(start 449.72732 -11.3665)
		(end 449.84162 -11.2522)
		(width 0.1143)
		(layer "F.Cu")
		(net "P3E_CPU0_PE1_PCH_CON_TXP<15>")
	)
	(segment
		(start 448.01282 -11.2522)
		(end 448.35572 -11.2522)
		(width 0.1143)
		(layer "F.Cu")
		(net "P3E_CPU0_PE1_PCH_CON_TXP<15>")
	)
	(segment
		(start 449.84162 -11.2522)
		(end 450.18452 -11.2522)
		(width 0.1143)
		(layer "F.Cu")
		(net "P3E_CPU0_PE1_PCH_CON_TXP<15>")
	)
	(segment
		(start 453.486266 -9.044686)
		(end 453.486266 -8.866124)
		(width 0.1143)
		(layer "F.Cu")
		(net "P3E_CPU0_PE1_PCH_CON_TXP<15>")
	)
	(segment
		(start 451.649338 -10.719816)
		(end 451.811136 -10.719816)
		(width 0.1143)
		(layer "F.Cu")
		(net "P3E_CPU0_PE1_PCH_CON_TXP<15>")
	)
	(segment
		(start 447.89852 -11.3665)
		(end 448.01282 -11.2522)
		(width 0.1143)
		(layer "F.Cu")
		(net "P3E_CPU0_PE1_PCH_CON_TXP<15>")
	)
	(segment
		(start 452.942452 -9.426702)
		(end 453.10425 -9.426702)
		(width 0.1143)
		(layer "F.Cu")
		(net "P3E_CPU0_PE1_PCH_CON_TXP<15>")
	)
	(segment
		(start 447.09842 -11.2522)
		(end 447.44132 -11.2522)
		(width 0.1143)
		(layer "F.Cu")
		(net "P3E_CPU0_PE1_PCH_CON_TXP<15>")
	)
	(segment
		(start 449.27012 -11.2522)
		(end 449.38442 -11.3665)
		(width 0.1143)
		(layer "F.Cu")
		(net "P3E_CPU0_PE1_PCH_CON_TXP<15>")
	)
	(segment
		(start 452.700136 -9.830816)
		(end 452.700136 -9.669272)
		(width 0.1143)
		(layer "F.Cu")
		(net "P3E_CPU0_PE1_PCH_CON_TXP<15>")
	)
	(segment
		(start 448.81292 -11.3665)
		(end 448.92722 -11.2522)
		(width 0.1143)
		(layer "F.Cu")
		(net "P3E_CPU0_PE1_PCH_CON_TXP<15>")
	)
	(segment
		(start 452.053452 -10.315702)
		(end 452.296022 -10.073386)
		(width 0.1143)
		(layer "F.Cu")
		(net "P3E_CPU0_PE1_PCH_CON_TXP<15>")
	)
	(segment
		(start 451.164452 -11.3665)
		(end 451.407022 -11.12393)
		(width 0.1143)
		(layer "F.Cu")
		(net "P3E_CPU0_PE1_PCH_CON_TXP<15>")
	)
	(segment
		(start 446.64122 -11.3665)
		(end 446.98412 -11.3665)
		(width 0.1143)
		(layer "F.Cu")
		(net "P3E_CPU0_PE1_PCH_CON_TXP<15>")
	)
	(segment
		(start 452.296022 -10.073386)
		(end 452.457566 -10.073386)
		(width 0.1143)
		(layer "F.Cu")
		(net "P3E_CPU0_PE1_PCH_CON_TXP<15>")
	)
	(segment
		(start 451.407022 -11.12393)
		(end 451.407022 -10.962386)
		(width 0.1143)
		(layer "F.Cu")
		(net "P3E_CPU0_PE1_PCH_CON_TXP<15>")
	)
	(segment
		(start 453.277478 -8.657336)
		(end 453.277478 -7.789672)
		(width 0.1143)
		(layer "F.Cu")
		(net "P3E_CPU0_PE1_PCH_CON_TXP<15>")
	)
	(segment
		(start 448.92722 -11.2522)
		(end 449.27012 -11.2522)
		(width 0.1143)
		(layer "F.Cu")
		(net "P3E_CPU0_PE1_PCH_CON_TXP<15>")
	)
	(segment
		(start 453.486266 -8.866124)
		(end 453.277478 -8.657336)
		(width 0.1143)
		(layer "F.Cu")
		(net "P3E_CPU0_PE1_PCH_CON_TXP<15>")
	)
	(segment
		(start 447.55562 -11.3665)
		(end 447.89852 -11.3665)
		(width 0.1143)
		(layer "F.Cu")
		(net "P3E_CPU0_PE1_PCH_CON_TXP<15>")
	)
	(segment
		(start 448.47002 -11.3665)
		(end 448.81292 -11.3665)
		(width 0.1143)
		(layer "F.Cu")
		(net "P3E_CPU0_PE1_PCH_CON_TXP<15>")
	)
	(segment
		(start 450.29882 -11.3665)
		(end 451.164452 -11.3665)
		(width 0.1143)
		(layer "F.Cu")
		(net "P3E_CPU0_PE1_PCH_CON_TXP<15>")
	)
	(segment
		(start 452.700136 -9.669272)
		(end 452.942452 -9.426702)
		(width 0.1143)
		(layer "F.Cu")
		(net "P3E_CPU0_PE1_PCH_CON_TXP<15>")
	)
	(segment
		(start 319.26022 -123.317)
		(end 319.7225 -123.317)
		(width 0.1143)
		(layer "F.Cu")
		(net "P3E_CPU0_PE1_PCH_CON_TXP<15>")
	)
	(segment
		(start 451.407022 -10.962386)
		(end 451.649338 -10.719816)
		(width 0.1143)
		(layer "F.Cu")
		(net "P3E_CPU0_PE1_PCH_CON_TXP<15>")
	)
	(via
		(at 319.1129 -123.46432)
		(size 0.508)
		(drill 0.254)
		(layers "F.Cu" "B.Cu")
		(net "P3E_CPU0_PE1_PCH_CON_TXP<15>")
	)
	(via
		(at 445.8716 -9.5758)
		(size 0.508)
		(drill 0.254)
		(layers "F.Cu" "B.Cu")
		(net "P3E_CPU0_PE1_PCH_CON_TXP<15>")
	)
	(segment
		(start 326.780652 -94.300802)
		(end 326.63892 -94.967298)
		(width 0.1143)
		(layer "In9.Cu")
		(net "P3E_CPU0_PE1_PCH_CON_TXP<15>")
	)
	(segment
		(start 372.351046 -8.311388)
		(end 371.327172 -8.106664)
		(width 0.1143)
		(layer "In9.Cu")
		(net "P3E_CPU0_PE1_PCH_CON_TXP<15>")
	)
	(segment
		(start 327.284842 -53.38064)
		(end 327.055988 -53.42636)
		(width 0.1143)
		(layer "In9.Cu")
		(net "P3E_CPU0_PE1_PCH_CON_TXP<15>")
	)
	(segment
		(start 325.928736 -55.116984)
		(end 325.73849 -55.402226)
		(width 0.1143)
		(layer "In9.Cu")
		(net "P3E_CPU0_PE1_PCH_CON_TXP<15>")
	)
	(segment
		(start 426.407834 -4.131564)
		(end 425.093638 -4.41071)
		(width 0.1143)
		(layer "In9.Cu")
		(net "P3E_CPU0_PE1_PCH_CON_TXP<15>")
	)
	(segment
		(start 327.055988 -53.42636)
		(end 327.055988 -53.426614)
		(width 0.1143)
		(layer "In9.Cu")
		(net "P3E_CPU0_PE1_PCH_CON_TXP<15>")
	)
	(segment
		(start 327.475088 -53.095398)
		(end 327.284842 -53.38064)
		(width 0.1143)
		(layer "In9.Cu")
		(net "P3E_CPU0_PE1_PCH_CON_TXP<15>")
	)
	(segment
		(start 361.407456 -29.12237)
		(end 361.560872 -29.889196)
		(width 0.1143)
		(layer "In9.Cu")
		(net "P3E_CPU0_PE1_PCH_CON_TXP<15>")
	)
	(segment
		(start 326.148192 -62.771782)
		(end 325.621142 -63.569342)
		(width 0.1143)
		(layer "In9.Cu")
		(net "P3E_CPU0_PE1_PCH_CON_TXP<15>")
	)
	(segment
		(start 384.490214 -4.941316)
		(end 384.26136 -4.895596)
		(width 0.1143)
		(layer "In9.Cu")
		(net "P3E_CPU0_PE1_PCH_CON_TXP<15>")
	)
	(segment
		(start 355.615494 -43.52417)
		(end 340.840314 -47.483776)
		(width 0.1143)
		(layer "In9.Cu")
		(net "P3E_CPU0_PE1_PCH_CON_TXP<15>")
	)
	(segment
		(start 338.32546 -46.97222)
		(end 333.483712 -47.957486)
		(width 0.1143)
		(layer "In9.Cu")
		(net "P3E_CPU0_PE1_PCH_CON_TXP<15>")
	)
	(segment
		(start 325.358252 -56.69788)
		(end 325.399654 -57.016904)
		(width 0.1143)
		(layer "In9.Cu")
		(net "P3E_CPU0_PE1_PCH_CON_TXP<15>")
	)
	(segment
		(start 317.019178 -112.119918)
		(end 317.019178 -112.120172)
		(width 0.1143)
		(layer "In9.Cu")
		(net "P3E_CPU0_PE1_PCH_CON_TXP<15>")
	)
	(segment
		(start 445.286384 -6.779006)
		(end 439.614818 -6.779006)
		(width 0.1143)
		(layer "In9.Cu")
		(net "P3E_CPU0_PE1_PCH_CON_TXP<15>")
	)
	(segment
		(start 439.614818 -6.779006)
		(end 433.642516 -4.153408)
		(width 0.1143)
		(layer "In9.Cu")
		(net "P3E_CPU0_PE1_PCH_CON_TXP<15>")
	)
	(segment
		(start 408.403552 -0.479552)
		(end 408.403552 -0.479298)
		(width 0.1143)
		(layer "In9.Cu")
		(net "P3E_CPU0_PE1_PCH_CON_TXP<15>")
	)
	(segment
		(start 447.248026 -8.905748)
		(end 446.605406 -7.349236)
		(width 0.1143)
		(layer "In9.Cu")
		(net "P3E_CPU0_PE1_PCH_CON_TXP<15>")
	)
	(segment
		(start 316.812168 -122.153172)
		(end 316.769242 -122.382788)
		(width 0.1143)
		(layer "In9.Cu")
		(net "P3E_CPU0_PE1_PCH_CON_TXP<15>")
	)
	(segment
		(start 318.9478 -123.91644)
		(end 319.1129 -123.75134)
		(width 0.1143)
		(layer "In9.Cu")
		(net "P3E_CPU0_PE1_PCH_CON_TXP<15>")
	)
	(segment
		(start 402.241258 -1.988566)
		(end 399.702528 -2.49555)
		(width 0.1143)
		(layer "In9.Cu")
		(net "P3E_CPU0_PE1_PCH_CON_TXP<15>")
	)
	(segment
		(start 315.786262 -115.412266)
		(end 315.786262 -115.755166)
		(width 0.1143)
		(layer "In9.Cu")
		(net "P3E_CPU0_PE1_PCH_CON_TXP<15>")
	)
	(segment
		(start 325.91121 -57.784238)
		(end 326.037448 -58.411364)
		(width 0.1143)
		(layer "In9.Cu")
		(net "P3E_CPU0_PE1_PCH_CON_TXP<15>")
	)
	(segment
		(start 421.558466 -4.159504)
		(end 420.373302 -4.411472)
		(width 0.1143)
		(layer "In9.Cu")
		(net "P3E_CPU0_PE1_PCH_CON_TXP<15>")
	)
	(segment
		(start 415.571686 -0.428752)
		(end 414.280096 -0.774446)
		(width 0.1143)
		(layer "In9.Cu")
		(net "P3E_CPU0_PE1_PCH_CON_TXP<15>")
	)
	(segment
		(start 315.786262 -117.787166)
		(end 315.621162 -117.952266)
		(width 0.1143)
		(layer "In9.Cu")
		(net "P3E_CPU0_PE1_PCH_CON_TXP<15>")
	)
	(segment
		(start 361.560872 -29.889196)
		(end 361.261914 -31.383224)
		(width 0.1143)
		(layer "In9.Cu")
		(net "P3E_CPU0_PE1_PCH_CON_TXP<15>")
	)
	(segment
		(start 371.327172 -8.106664)
		(end 369.791488 -8.414004)
		(width 0.1143)
		(layer "In9.Cu")
		(net "P3E_CPU0_PE1_PCH_CON_TXP<15>")
	)
	(segment
		(start 416.633152 -0.82931)
		(end 415.571686 -0.428752)
		(width 0.1143)
		(layer "In9.Cu")
		(net "P3E_CPU0_PE1_PCH_CON_TXP<15>")
	)
	(segment
		(start 326.874378 -101.261164)
		(end 324.91172 -104.82834)
		(width 0.1143)
		(layer "In9.Cu")
		(net "P3E_CPU0_PE1_PCH_CON_TXP<15>")
	)
	(segment
		(start 433.642516 -4.153408)
		(end 432.575716 -4.380484)
		(width 0.1143)
		(layer "In9.Cu")
		(net "P3E_CPU0_PE1_PCH_CON_TXP<15>")
	)
	(segment
		(start 390.796272 -2.009902)
		(end 387.642608 -2.641092)
		(width 0.1143)
		(layer "In9.Cu")
		(net "P3E_CPU0_PE1_PCH_CON_TXP<15>")
	)
	(segment
		(start 411.29966 -1.01219)
		(end 408.954986 -0.309626)
		(width 0.1143)
		(layer "In9.Cu")
		(net "P3E_CPU0_PE1_PCH_CON_TXP<15>")
	)
	(segment
		(start 324.437756 -69.385434)
		(end 324.97649 -71.92264)
		(width 0.1143)
		(layer "In9.Cu")
		(net "P3E_CPU0_PE1_PCH_CON_TXP<15>")
	)
	(segment
		(start 431.508662 -4.06908)
		(end 429.893476 -4.412742)
		(width 0.1143)
		(layer "In9.Cu")
		(net "P3E_CPU0_PE1_PCH_CON_TXP<15>")
	)
	(segment
		(start 402.771864 -2.050796)
		(end 402.435568 -2.118106)
		(width 0.1143)
		(layer "In9.Cu")
		(net "P3E_CPU0_PE1_PCH_CON_TXP<15>")
	)
	(segment
		(start 418.57295 -2.753106)
		(end 418.342318 -2.78892)
		(width 0.1143)
		(layer "In9.Cu")
		(net "P3E_CPU0_PE1_PCH_CON_TXP<15>")
	)
	(segment
		(start 324.42404 -74.522838)
		(end 324.742556 -76.023978)
		(width 0.1143)
		(layer "In9.Cu")
		(net "P3E_CPU0_PE1_PCH_CON_TXP<15>")
	)
	(segment
		(start 356.669848 -42.83329)
		(end 355.615494 -43.52417)
		(width 0.1143)
		(layer "In9.Cu")
		(net "P3E_CPU0_PE1_PCH_CON_TXP<15>")
	)
	(segment
		(start 402.901404 -1.856486)
		(end 402.771864 -2.050796)
		(width 0.1143)
		(layer "In9.Cu")
		(net "P3E_CPU0_PE1_PCH_CON_TXP<15>")
	)
	(segment
		(start 326.911462 -53.940456)
		(end 326.721216 -54.225952)
		(width 0.1143)
		(layer "In9.Cu")
		(net "P3E_CPU0_PE1_PCH_CON_TXP<15>")
	)
	(segment
		(start 423.926254 -4.162552)
		(end 422.748456 -4.412488)
		(width 0.1143)
		(layer "In9.Cu")
		(net "P3E_CPU0_PE1_PCH_CON_TXP<15>")
	)
	(segment
		(start 326.302116 -54.556914)
		(end 326.347836 -54.785768)
		(width 0.1143)
		(layer "In9.Cu")
		(net "P3E_CPU0_PE1_PCH_CON_TXP<15>")
	)
	(segment
		(start 425.093638 -4.41071)
		(end 423.926254 -4.162552)
		(width 0.1143)
		(layer "In9.Cu")
		(net "P3E_CPU0_PE1_PCH_CON_TXP<15>")
	)
	(segment
		(start 418.065458 -2.586736)
		(end 418.02939 -2.35585)
		(width 0.1143)
		(layer "In9.Cu")
		(net "P3E_CPU0_PE1_PCH_CON_TXP<15>")
	)
	(segment
		(start 315.786262 -116.428266)
		(end 315.786262 -116.771166)
		(width 0.1143)
		(layer "In9.Cu")
		(net "P3E_CPU0_PE1_PCH_CON_TXP<15>")
	)
	(segment
		(start 403.2377 -1.78943)
		(end 402.901404 -1.856486)
		(width 0.1143)
		(layer "In9.Cu")
		(net "P3E_CPU0_PE1_PCH_CON_TXP<15>")
	)
	(segment
		(start 379.846586 -7.838694)
		(end 377.22556 -8.394954)
		(width 0.1143)
		(layer "In9.Cu")
		(net "P3E_CPU0_PE1_PCH_CON_TXP<15>")
	)
	(segment
		(start 399.702528 -2.49555)
		(end 398.372584 -2.229866)
		(width 0.1143)
		(layer "In9.Cu")
		(net "P3E_CPU0_PE1_PCH_CON_TXP<15>")
	)
	(segment
		(start 403.768052 -1.85166)
		(end 403.431756 -1.91897)
		(width 0.1143)
		(layer "In9.Cu")
		(net "P3E_CPU0_PE1_PCH_CON_TXP<15>")
	)
	(segment
		(start 315.621162 -120.70588)
		(end 315.814964 -120.988836)
		(width 0.1143)
		(layer "In9.Cu")
		(net "P3E_CPU0_PE1_PCH_CON_TXP<15>")
	)
	(segment
		(start 317.438786 -123.360942)
		(end 318.241934 -123.91644)
		(width 0.1143)
		(layer "In9.Cu")
		(net "P3E_CPU0_PE1_PCH_CON_TXP<15>")
	)
	(segment
		(start 315.621162 -117.279166)
		(end 315.786262 -117.444266)
		(width 0.1143)
		(layer "In9.Cu")
		(net "P3E_CPU0_PE1_PCH_CON_TXP<15>")
	)
	(segment
		(start 406.61209 -1.47701)
		(end 405.625808 -1.819656)
		(width 0.1143)
		(layer "In9.Cu")
		(net "P3E_CPU0_PE1_PCH_CON_TXP<15>")
	)
	(segment
		(start 316.769242 -122.382788)
		(end 317.438786 -123.360942)
		(width 0.1143)
		(layer "In9.Cu")
		(net "P3E_CPU0_PE1_PCH_CON_TXP<15>")
	)
	(segment
		(start 398.372584 -2.229866)
		(end 396.7607 -2.5527)
		(width 0.1143)
		(layer "In9.Cu")
		(net "P3E_CPU0_PE1_PCH_CON_TXP<15>")
	)
	(segment
		(start 384.775456 -4.75107)
		(end 384.490214 -4.941316)
		(width 0.1143)
		(layer "In9.Cu")
		(net "P3E_CPU0_PE1_PCH_CON_TXP<15>")
	)
	(segment
		(start 446.642236 -10.044684)
		(end 447.032888 -9.654032)
		(width 0.1143)
		(layer "In9.Cu")
		(net "P3E_CPU0_PE1_PCH_CON_TXP<15>")
	)
	(segment
		(start 408.954986 -0.309626)
		(end 408.403552 -0.479552)
		(width 0.1143)
		(layer "In9.Cu")
		(net "P3E_CPU0_PE1_PCH_CON_TXP<15>")
	)
	(segment
		(start 324.97649 -71.92264)
		(end 324.42404 -74.522838)
		(width 0.1143)
		(layer "In9.Cu")
		(net "P3E_CPU0_PE1_PCH_CON_TXP<15>")
	)
	(segment
		(start 396.7607 -2.5527)
		(end 394.602208 -2.121408)
		(width 0.1143)
		(layer "In9.Cu")
		(net "P3E_CPU0_PE1_PCH_CON_TXP<15>")
	)
	(segment
		(start 445.851026 -10.044684)
		(end 446.642236 -10.044684)
		(width 0.1143)
		(layer "In9.Cu")
		(net "P3E_CPU0_PE1_PCH_CON_TXP<15>")
	)
	(segment
		(start 403.431756 -1.91897)
		(end 403.2377 -1.78943)
		(width 0.1143)
		(layer "In9.Cu")
		(net "P3E_CPU0_PE1_PCH_CON_TXP<15>")
	)
	(segment
		(start 447.032888 -9.654032)
		(end 447.131694 -9.437878)
		(width 0.1143)
		(layer "In9.Cu")
		(net "P3E_CPU0_PE1_PCH_CON_TXP<15>")
	)
	(segment
		(start 387.357366 -2.831338)
		(end 387.311392 -3.060192)
		(width 0.1143)
		(layer "In9.Cu")
		(net "P3E_CPU0_PE1_PCH_CON_TXP<15>")
	)
	(segment
		(start 403.897592 -1.65735)
		(end 403.768052 -1.85166)
		(width 0.1143)
		(layer "In9.Cu")
		(net "P3E_CPU0_PE1_PCH_CON_TXP<15>")
	)
	(segment
		(start 316.044326 -121.031762)
		(end 316.238128 -121.314718)
		(width 0.1143)
		(layer "In9.Cu")
		(net "P3E_CPU0_PE1_PCH_CON_TXP<15>")
	)
	(segment
		(start 315.786262 -116.771166)
		(end 315.621162 -116.936266)
		(width 0.1143)
		(layer "In9.Cu")
		(net "P3E_CPU0_PE1_PCH_CON_TXP<15>")
	)
	(segment
		(start 417.311078 -1.831086)
		(end 416.633152 -0.82931)
		(width 0.1143)
		(layer "In9.Cu")
		(net "P3E_CPU0_PE1_PCH_CON_TXP<15>")
	)
	(segment
		(start 325.149718 -80.852772)
		(end 324.494398 -83.532218)
		(width 0.1143)
		(layer "In9.Cu")
		(net "P3E_CPU0_PE1_PCH_CON_TXP<15>")
	)
	(segment
		(start 402.435568 -2.118106)
		(end 402.241258 -1.988566)
		(width 0.1143)
		(layer "In9.Cu")
		(net "P3E_CPU0_PE1_PCH_CON_TXP<15>")
	)
	(segment
		(start 316.238128 -121.314718)
		(end 316.195202 -121.544334)
		(width 0.1143)
		(layer "In9.Cu")
		(net "P3E_CPU0_PE1_PCH_CON_TXP<15>")
	)
	(segment
		(start 315.621162 -115.247166)
		(end 315.786262 -115.412266)
		(width 0.1143)
		(layer "In9.Cu")
		(net "P3E_CPU0_PE1_PCH_CON_TXP<15>")
	)
	(segment
		(start 361.261914 -31.383224)
		(end 358.753918 -34.47415)
		(width 0.1143)
		(layer "In9.Cu")
		(net "P3E_CPU0_PE1_PCH_CON_TXP<15>")
	)
	(segment
		(start 324.742556 -76.023978)
		(end 324.433184 -77.480922)
		(width 0.1143)
		(layer "In9.Cu")
		(net "P3E_CPU0_PE1_PCH_CON_TXP<15>")
	)
	(segment
		(start 326.63892 -93.63329)
		(end 326.780652 -94.300802)
		(width 0.1143)
		(layer "In9.Cu")
		(net "P3E_CPU0_PE1_PCH_CON_TXP<15>")
	)
	(segment
		(start 385.620768 -4.187444)
		(end 385.335526 -4.37769)
		(width 0.1143)
		(layer "In9.Cu")
		(net "P3E_CPU0_PE1_PCH_CON_TXP<15>")
	)
	(segment
		(start 325.621142 -63.569342)
		(end 324.437756 -69.385434)
		(width 0.1143)
		(layer "In9.Cu")
		(net "P3E_CPU0_PE1_PCH_CON_TXP<15>")
	)
	(segment
		(start 325.750428 -59.846718)
		(end 326.24268 -62.308232)
		(width 0.1143)
		(layer "In9.Cu")
		(net "P3E_CPU0_PE1_PCH_CON_TXP<15>")
	)
	(segment
		(start 418.84981 -2.95529)
		(end 418.57295 -2.753106)
		(width 0.1143)
		(layer "In9.Cu")
		(net "P3E_CPU0_PE1_PCH_CON_TXP<15>")
	)
	(segment
		(start 419.810184 -4.291838)
		(end 419.443154 -4.020312)
		(width 0.1143)
		(layer "In9.Cu")
		(net "P3E_CPU0_PE1_PCH_CON_TXP<15>")
	)
	(segment
		(start 326.63892 -54.242462)
		(end 326.492362 -54.271672)
		(width 0.1143)
		(layer "In9.Cu")
		(net "P3E_CPU0_PE1_PCH_CON_TXP<15>")
	)
	(segment
		(start 326.721216 -54.225952)
		(end 326.63892 -54.242462)
		(width 0.1143)
		(layer "In9.Cu")
		(net "P3E_CPU0_PE1_PCH_CON_TXP<15>")
	)
	(segment
		(start 326.24268 -62.308232)
		(end 326.148192 -62.771782)
		(width 0.1143)
		(layer "In9.Cu")
		(net "P3E_CPU0_PE1_PCH_CON_TXP<15>")
	)
	(segment
		(start 327.429368 -52.86629)
		(end 327.475088 -53.095398)
		(width 0.1143)
		(layer "In9.Cu")
		(net "P3E_CPU0_PE1_PCH_CON_TXP<15>")
	)
	(segment
		(start 326.4662 -54.310788)
		(end 326.302116 -54.556914)
		(width 0.1143)
		(layer "In9.Cu")
		(net "P3E_CPU0_PE1_PCH_CON_TXP<15>")
	)
	(segment
		(start 326.492362 -54.271672)
		(end 326.4662 -54.310788)
		(width 0.1143)
		(layer "In9.Cu")
		(net "P3E_CPU0_PE1_PCH_CON_TXP<15>")
	)
	(segment
		(start 315.814964 -120.988836)
		(end 316.044326 -121.031762)
		(width 0.1143)
		(layer "In9.Cu")
		(net "P3E_CPU0_PE1_PCH_CON_TXP<15>")
	)
	(segment
		(start 385.951984 -3.768344)
		(end 385.666742 -3.95859)
		(width 0.1143)
		(layer "In9.Cu")
		(net "P3E_CPU0_PE1_PCH_CON_TXP<15>")
	)
	(segment
		(start 446.605406 -7.349236)
		(end 446.261998 -7.004812)
		(width 0.1143)
		(layer "In9.Cu")
		(net "P3E_CPU0_PE1_PCH_CON_TXP<15>")
	)
	(segment
		(start 364.026196 -23.9776)
		(end 362.191554 -25.200864)
		(width 0.1143)
		(layer "In9.Cu")
		(net "P3E_CPU0_PE1_PCH_CON_TXP<15>")
	)
	(segment
		(start 394.602208 -2.121408)
		(end 392.977116 -2.44602)
		(width 0.1143)
		(layer "In9.Cu")
		(net "P3E_CPU0_PE1_PCH_CON_TXP<15>")
	)
	(segment
		(start 392.977116 -2.44602)
		(end 390.796272 -2.009902)
		(width 0.1143)
		(layer "In9.Cu")
		(net "P3E_CPU0_PE1_PCH_CON_TXP<15>")
	)
	(segment
		(start 315.621162 -114.904266)
		(end 315.621162 -115.247166)
		(width 0.1143)
		(layer "In9.Cu")
		(net "P3E_CPU0_PE1_PCH_CON_TXP<15>")
	)
	(segment
		(start 408.403552 -0.479298)
		(end 407.852118 -0.649732)
		(width 0.1143)
		(layer "In9.Cu")
		(net "P3E_CPU0_PE1_PCH_CON_TXP<15>")
	)
	(segment
		(start 386.180838 -3.814064)
		(end 385.951984 -3.768344)
		(width 0.1143)
		(layer "In9.Cu")
		(net "P3E_CPU0_PE1_PCH_CON_TXP<15>")
	)
	(segment
		(start 315.786262 -118.460266)
		(end 315.786262 -118.803166)
		(width 0.1143)
		(layer "In9.Cu")
		(net "P3E_CPU0_PE1_PCH_CON_TXP<15>")
	)
	(segment
		(start 384.26136 -4.895596)
		(end 379.846586 -7.838694)
		(width 0.1143)
		(layer "In9.Cu")
		(net "P3E_CPU0_PE1_PCH_CON_TXP<15>")
	)
	(segment
		(start 384.82143 -4.522216)
		(end 384.775456 -4.75107)
		(width 0.1143)
		(layer "In9.Cu")
		(net "P3E_CPU0_PE1_PCH_CON_TXP<15>")
	)
	(segment
		(start 387.311392 -3.060192)
		(end 387.02615 -3.250438)
		(width 0.1143)
		(layer "In9.Cu")
		(net "P3E_CPU0_PE1_PCH_CON_TXP<15>")
	)
	(segment
		(start 427.664372 -4.398772)
		(end 426.407834 -4.131564)
		(width 0.1143)
		(layer "In9.Cu")
		(net "P3E_CPU0_PE1_PCH_CON_TXP<15>")
	)
	(segment
		(start 376.018552 -8.138668)
		(end 374.803416 -8.39724)
		(width 0.1143)
		(layer "In9.Cu")
		(net "P3E_CPU0_PE1_PCH_CON_TXP<15>")
	)
	(segment
		(start 387.642608 -2.641092)
		(end 387.357366 -2.831338)
		(width 0.1143)
		(layer "In9.Cu")
		(net "P3E_CPU0_PE1_PCH_CON_TXP<15>")
	)
	(segment
		(start 428.745142 -4.168902)
		(end 427.664372 -4.398772)
		(width 0.1143)
		(layer "In9.Cu")
		(net "P3E_CPU0_PE1_PCH_CON_TXP<15>")
	)
	(segment
		(start 385.335526 -4.37769)
		(end 385.106672 -4.33197)
		(width 0.1143)
		(layer "In9.Cu")
		(net "P3E_CPU0_PE1_PCH_CON_TXP<15>")
	)
	(segment
		(start 316.195202 -121.544334)
		(end 316.389004 -121.82729)
		(width 0.1143)
		(layer "In9.Cu")
		(net "P3E_CPU0_PE1_PCH_CON_TXP<15>")
	)
	(segment
		(start 317.019178 -112.120172)
		(end 315.621162 -114.904266)
		(width 0.1143)
		(layer "In9.Cu")
		(net "P3E_CPU0_PE1_PCH_CON_TXP<15>")
	)
	(segment
		(start 315.621162 -115.920266)
		(end 315.621162 -116.263166)
		(width 0.1143)
		(layer "In9.Cu")
		(net "P3E_CPU0_PE1_PCH_CON_TXP<15>")
	)
	(segment
		(start 387.02615 -3.250438)
		(end 386.797296 -3.204718)
		(width 0.1143)
		(layer "In9.Cu")
		(net "P3E_CPU0_PE1_PCH_CON_TXP<15>")
	)
	(segment
		(start 404.357332 -1.565656)
		(end 403.897592 -1.65735)
		(width 0.1143)
		(layer "In9.Cu")
		(net "P3E_CPU0_PE1_PCH_CON_TXP<15>")
	)
	(segment
		(start 446.261998 -7.004812)
		(end 445.286384 -6.779006)
		(width 0.1143)
		(layer "In9.Cu")
		(net "P3E_CPU0_PE1_PCH_CON_TXP<15>")
	)
	(segment
		(start 325.399654 -57.016904)
		(end 325.91121 -57.784238)
		(width 0.1143)
		(layer "In9.Cu")
		(net "P3E_CPU0_PE1_PCH_CON_TXP<15>")
	)
	(segment
		(start 373.363236 -8.109204)
		(end 372.351046 -8.311388)
		(width 0.1143)
		(layer "In9.Cu")
		(net "P3E_CPU0_PE1_PCH_CON_TXP<15>")
	)
	(segment
		(start 315.621162 -117.952266)
		(end 315.621162 -118.295166)
		(width 0.1143)
		(layer "In9.Cu")
		(net "P3E_CPU0_PE1_PCH_CON_TXP<15>")
	)
	(segment
		(start 369.791488 -8.414004)
		(end 365.669322 -16.105632)
		(width 0.1143)
		(layer "In9.Cu")
		(net "P3E_CPU0_PE1_PCH_CON_TXP<15>")
	)
	(segment
		(start 325.73849 -55.402226)
		(end 325.358252 -56.69788)
		(width 0.1143)
		(layer "In9.Cu")
		(net "P3E_CPU0_PE1_PCH_CON_TXP<15>")
	)
	(segment
		(start 315.621162 -118.968266)
		(end 315.621162 -120.70588)
		(width 0.1143)
		(layer "In9.Cu")
		(net "P3E_CPU0_PE1_PCH_CON_TXP<15>")
	)
	(segment
		(start 326.578722 -95.250508)
		(end 327.152508 -97.952306)
		(width 0.1143)
		(layer "In9.Cu")
		(net "P3E_CPU0_PE1_PCH_CON_TXP<15>")
	)
	(segment
		(start 324.91172 -104.82834)
		(end 317.019178 -112.119918)
		(width 0.1143)
		(layer "In9.Cu")
		(net "P3E_CPU0_PE1_PCH_CON_TXP<15>")
	)
	(segment
		(start 315.621162 -116.936266)
		(end 315.621162 -117.279166)
		(width 0.1143)
		(layer "In9.Cu")
		(net "P3E_CPU0_PE1_PCH_CON_TXP<15>")
	)
	(segment
		(start 386.512054 -3.394964)
		(end 386.46608 -3.623818)
		(width 0.1143)
		(layer "In9.Cu")
		(net "P3E_CPU0_PE1_PCH_CON_TXP<15>")
	)
	(segment
		(start 445.680084 -9.767316)
		(end 445.680084 -9.873742)
		(width 0.1143)
		(layer "In9.Cu")
		(net "P3E_CPU0_PE1_PCH_CON_TXP<15>")
	)
	(segment
		(start 324.433184 -77.480922)
		(end 325.149718 -80.852772)
		(width 0.1143)
		(layer "In9.Cu")
		(net "P3E_CPU0_PE1_PCH_CON_TXP<15>")
	)
	(segment
		(start 386.797296 -3.204718)
		(end 386.512054 -3.394964)
		(width 0.1143)
		(layer "In9.Cu")
		(net "P3E_CPU0_PE1_PCH_CON_TXP<15>")
	)
	(segment
		(start 340.840314 -47.483776)
		(end 338.32546 -46.97222)
		(width 0.1143)
		(layer "In9.Cu")
		(net "P3E_CPU0_PE1_PCH_CON_TXP<15>")
	)
	(segment
		(start 414.280096 -0.774446)
		(end 413.09036 -0.46863)
		(width 0.1143)
		(layer "In9.Cu")
		(net "P3E_CPU0_PE1_PCH_CON_TXP<15>")
	)
	(segment
		(start 445.680084 -9.873742)
		(end 445.851026 -10.044684)
		(width 0.1143)
		(layer "In9.Cu")
		(net "P3E_CPU0_PE1_PCH_CON_TXP<15>")
	)
	(segment
		(start 445.8716 -9.5758)
		(end 445.680084 -9.767316)
		(width 0.1143)
		(layer "In9.Cu")
		(net "P3E_CPU0_PE1_PCH_CON_TXP<15>")
	)
	(segment
		(start 316.618366 -121.870216)
		(end 316.812168 -122.153172)
		(width 0.1143)
		(layer "In9.Cu")
		(net "P3E_CPU0_PE1_PCH_CON_TXP<15>")
	)
	(segment
		(start 374.803416 -8.39724)
		(end 373.363236 -8.109204)
		(width 0.1143)
		(layer "In9.Cu")
		(net "P3E_CPU0_PE1_PCH_CON_TXP<15>")
	)
	(segment
		(start 418.342318 -2.78892)
		(end 418.065458 -2.586736)
		(width 0.1143)
		(layer "In9.Cu")
		(net "P3E_CPU0_PE1_PCH_CON_TXP<15>")
	)
	(segment
		(start 419.443154 -4.020312)
		(end 418.84981 -2.95529)
		(width 0.1143)
		(layer "In9.Cu")
		(net "P3E_CPU0_PE1_PCH_CON_TXP<15>")
	)
	(segment
		(start 315.786262 -118.803166)
		(end 315.621162 -118.968266)
		(width 0.1143)
		(layer "In9.Cu")
		(net "P3E_CPU0_PE1_PCH_CON_TXP<15>")
	)
	(segment
		(start 326.865742 -53.711856)
		(end 326.911462 -53.940456)
		(width 0.1143)
		(layer "In9.Cu")
		(net "P3E_CPU0_PE1_PCH_CON_TXP<15>")
	)
	(segment
		(start 385.106672 -4.33197)
		(end 384.82143 -4.522216)
		(width 0.1143)
		(layer "In9.Cu")
		(net "P3E_CPU0_PE1_PCH_CON_TXP<15>")
	)
	(segment
		(start 413.09036 -0.46863)
		(end 411.29966 -1.01219)
		(width 0.1143)
		(layer "In9.Cu")
		(net "P3E_CPU0_PE1_PCH_CON_TXP<15>")
	)
	(segment
		(start 315.786262 -115.755166)
		(end 315.621162 -115.920266)
		(width 0.1143)
		(layer "In9.Cu")
		(net "P3E_CPU0_PE1_PCH_CON_TXP<15>")
	)
	(segment
		(start 422.748456 -4.412488)
		(end 421.558466 -4.159504)
		(width 0.1143)
		(layer "In9.Cu")
		(net "P3E_CPU0_PE1_PCH_CON_TXP<15>")
	)
	(segment
		(start 315.621162 -118.295166)
		(end 315.786262 -118.460266)
		(width 0.1143)
		(layer "In9.Cu")
		(net "P3E_CPU0_PE1_PCH_CON_TXP<15>")
	)
	(segment
		(start 358.753918 -34.47415)
		(end 357.264208 -41.712896)
		(width 0.1143)
		(layer "In9.Cu")
		(net "P3E_CPU0_PE1_PCH_CON_TXP<15>")
	)
	(segment
		(start 327.055988 -53.426614)
		(end 326.865742 -53.711856)
		(width 0.1143)
		(layer "In9.Cu")
		(net "P3E_CPU0_PE1_PCH_CON_TXP<15>")
	)
	(segment
		(start 326.347836 -54.785768)
		(end 326.15759 -55.071264)
		(width 0.1143)
		(layer "In9.Cu")
		(net "P3E_CPU0_PE1_PCH_CON_TXP<15>")
	)
	(segment
		(start 326.037448 -58.411364)
		(end 325.750428 -59.846718)
		(width 0.1143)
		(layer "In9.Cu")
		(net "P3E_CPU0_PE1_PCH_CON_TXP<15>")
	)
	(segment
		(start 447.131694 -9.437878)
		(end 447.248026 -8.905748)
		(width 0.1143)
		(layer "In9.Cu")
		(net "P3E_CPU0_PE1_PCH_CON_TXP<15>")
	)
	(segment
		(start 407.852118 -0.649732)
		(end 406.61209 -1.47701)
		(width 0.1143)
		(layer "In9.Cu")
		(net "P3E_CPU0_PE1_PCH_CON_TXP<15>")
	)
	(segment
		(start 429.893476 -4.412742)
		(end 428.745142 -4.168902)
		(width 0.1143)
		(layer "In9.Cu")
		(net "P3E_CPU0_PE1_PCH_CON_TXP<15>")
	)
	(segment
		(start 318.241934 -123.91644)
		(end 318.9478 -123.91644)
		(width 0.1143)
		(layer "In9.Cu")
		(net "P3E_CPU0_PE1_PCH_CON_TXP<15>")
	)
	(segment
		(start 326.905112 -101.205284)
		(end 326.874378 -101.261164)
		(width 0.1143)
		(layer "In9.Cu")
		(net "P3E_CPU0_PE1_PCH_CON_TXP<15>")
	)
	(segment
		(start 418.02939 -2.35585)
		(end 417.311078 -1.831086)
		(width 0.1143)
		(layer "In9.Cu")
		(net "P3E_CPU0_PE1_PCH_CON_TXP<15>")
	)
	(segment
		(start 326.15759 -55.071264)
		(end 325.928736 -55.116984)
		(width 0.1143)
		(layer "In9.Cu")
		(net "P3E_CPU0_PE1_PCH_CON_TXP<15>")
	)
	(segment
		(start 405.625808 -1.819656)
		(end 404.357332 -1.565656)
		(width 0.1143)
		(layer "In9.Cu")
		(net "P3E_CPU0_PE1_PCH_CON_TXP<15>")
	)
	(segment
		(start 377.22556 -8.394954)
		(end 376.018552 -8.138668)
		(width 0.1143)
		(layer "In9.Cu")
		(net "P3E_CPU0_PE1_PCH_CON_TXP<15>")
	)
	(segment
		(start 365.669322 -16.105632)
		(end 364.026196 -23.9776)
		(width 0.1143)
		(layer "In9.Cu")
		(net "P3E_CPU0_PE1_PCH_CON_TXP<15>")
	)
	(segment
		(start 315.786262 -117.444266)
		(end 315.786262 -117.787166)
		(width 0.1143)
		(layer "In9.Cu")
		(net "P3E_CPU0_PE1_PCH_CON_TXP<15>")
	)
	(segment
		(start 333.483712 -47.957486)
		(end 328.139044 -51.802284)
		(width 0.1143)
		(layer "In9.Cu")
		(net "P3E_CPU0_PE1_PCH_CON_TXP<15>")
	)
	(segment
		(start 420.373302 -4.411472)
		(end 419.810184 -4.291838)
		(width 0.1143)
		(layer "In9.Cu")
		(net "P3E_CPU0_PE1_PCH_CON_TXP<15>")
	)
	(segment
		(start 357.264208 -41.712896)
		(end 356.669848 -42.83329)
		(width 0.1143)
		(layer "In9.Cu")
		(net "P3E_CPU0_PE1_PCH_CON_TXP<15>")
	)
	(segment
		(start 362.191554 -25.200864)
		(end 361.407456 -29.12237)
		(width 0.1143)
		(layer "In9.Cu")
		(net "P3E_CPU0_PE1_PCH_CON_TXP<15>")
	)
	(segment
		(start 327.152508 -97.952306)
		(end 326.905112 -101.205284)
		(width 0.1143)
		(layer "In9.Cu")
		(net "P3E_CPU0_PE1_PCH_CON_TXP<15>")
	)
	(segment
		(start 328.139044 -51.802284)
		(end 327.429368 -52.86629)
		(width 0.1143)
		(layer "In9.Cu")
		(net "P3E_CPU0_PE1_PCH_CON_TXP<15>")
	)
	(segment
		(start 319.1129 -123.75134)
		(end 319.1129 -123.46432)
		(width 0.1143)
		(layer "In9.Cu")
		(net "P3E_CPU0_PE1_PCH_CON_TXP<15>")
	)
	(segment
		(start 385.666742 -3.95859)
		(end 385.620768 -4.187444)
		(width 0.1143)
		(layer "In9.Cu")
		(net "P3E_CPU0_PE1_PCH_CON_TXP<15>")
	)
	(segment
		(start 326.63892 -94.967298)
		(end 326.578722 -95.250508)
		(width 0.1143)
		(layer "In9.Cu")
		(net "P3E_CPU0_PE1_PCH_CON_TXP<15>")
	)
	(segment
		(start 315.621162 -116.263166)
		(end 315.786262 -116.428266)
		(width 0.1143)
		(layer "In9.Cu")
		(net "P3E_CPU0_PE1_PCH_CON_TXP<15>")
	)
	(segment
		(start 432.575716 -4.380484)
		(end 431.508662 -4.06908)
		(width 0.1143)
		(layer "In9.Cu")
		(net "P3E_CPU0_PE1_PCH_CON_TXP<15>")
	)
	(segment
		(start 386.46608 -3.623818)
		(end 386.180838 -3.814064)
		(width 0.1143)
		(layer "In9.Cu")
		(net "P3E_CPU0_PE1_PCH_CON_TXP<15>")
	)
	(segment
		(start 316.389004 -121.82729)
		(end 316.618366 -121.870216)
		(width 0.1143)
		(layer "In9.Cu")
		(net "P3E_CPU0_PE1_PCH_CON_TXP<15>")
	)
	(segment
		(start 324.494398 -83.532218)
		(end 326.63892 -93.63329)
		(width 0.1143)
		(layer "In9.Cu")
		(net "P3E_CPU0_PE1_PCH_CON_TXP<15>")
	)
	(segment
		(start 451.397878 -8.936736)
		(end 451.677278 -8.657336)
		(width 0.1143)
		(layer "F.Cu")
		(net "P3E_CPU0_PE1_PCH_CON_TXP<14>")
	)
	(segment
		(start 446.25133 -8.700008)
		(end 446.61455 -8.336788)
		(width 0.1143)
		(layer "F.Cu")
		(net "P3E_CPU0_PE1_PCH_CON_TXP<14>")
	)
	(segment
		(start 451.677278 -8.657336)
		(end 451.677278 -7.789672)
		(width 0.1143)
		(layer "F.Cu")
		(net "P3E_CPU0_PE1_PCH_CON_TXP<14>")
	)
	(segment
		(start 322.998338 -122.555)
		(end 323.6595 -122.555)
		(width 0.1143)
		(layer "F.Cu")
		(net "P3E_CPU0_PE1_PCH_CON_TXP<14>")
	)
	(segment
		(start 451.397878 -9.19861)
		(end 451.397878 -8.936736)
		(width 0.1143)
		(layer "F.Cu")
		(net "P3E_CPU0_PE1_PCH_CON_TXP<14>")
	)
	(segment
		(start 447.902838 -9.454134)
		(end 451.142354 -9.454134)
		(width 0.1143)
		(layer "F.Cu")
		(net "P3E_CPU0_PE1_PCH_CON_TXP<14>")
	)
	(segment
		(start 451.142354 -9.454134)
		(end 451.397878 -9.19861)
		(width 0.1143)
		(layer "F.Cu")
		(net "P3E_CPU0_PE1_PCH_CON_TXP<14>")
	)
	(segment
		(start 446.786254 -8.336788)
		(end 447.902838 -9.454134)
		(width 0.1143)
		(layer "F.Cu")
		(net "P3E_CPU0_PE1_PCH_CON_TXP<14>")
	)
	(segment
		(start 446.61455 -8.336788)
		(end 446.786254 -8.336788)
		(width 0.1143)
		(layer "F.Cu")
		(net "P3E_CPU0_PE1_PCH_CON_TXP<14>")
	)
	(via
		(at 322.998338 -122.555)
		(size 0.508)
		(drill 0.254)
		(layers "F.Cu" "B.Cu")
		(net "P3E_CPU0_PE1_PCH_CON_TXP<14>")
	)
	(via
		(at 446.25133 -8.700008)
		(size 0.508)
		(drill 0.254)
		(layers "F.Cu" "B.Cu")
		(net "P3E_CPU0_PE1_PCH_CON_TXP<14>")
	)
	(segment
		(start 371.862604 -10.320274)
		(end 371.997732 -10.408158)
		(width 0.1143)
		(layer "In9.Cu")
		(net "P3E_CPU0_PE1_PCH_CON_TXP<14>")
	)
	(segment
		(start 369.171982 -12.352528)
		(end 369.441984 -12.140946)
		(width 0.1143)
		(layer "In9.Cu")
		(net "P3E_CPU0_PE1_PCH_CON_TXP<14>")
	)
	(segment
		(start 327.82637 -98.053652)
		(end 327.262998 -95.403416)
		(width 0.1143)
		(layer "In9.Cu")
		(net "P3E_CPU0_PE1_PCH_CON_TXP<14>")
	)
	(segment
		(start 326.45731 -59.912504)
		(end 326.63892 -59.003946)
		(width 0.1143)
		(layer "In9.Cu")
		(net "P3E_CPU0_PE1_PCH_CON_TXP<14>")
	)
	(segment
		(start 326.63892 -59.003946)
		(end 326.654668 -58.925206)
		(width 0.1143)
		(layer "In9.Cu")
		(net "P3E_CPU0_PE1_PCH_CON_TXP<14>")
	)
	(segment
		(start 366.202976 -16.69034)
		(end 368.060224 -13.223748)
		(width 0.1143)
		(layer "In9.Cu")
		(net "P3E_CPU0_PE1_PCH_CON_TXP<14>")
	)
	(segment
		(start 371.550438 -10.503662)
		(end 371.638576 -10.36828)
		(width 0.1143)
		(layer "In9.Cu")
		(net "P3E_CPU0_PE1_PCH_CON_TXP<14>")
	)
	(segment
		(start 405.776938 -3.858514)
		(end 408.46375 -4.39547)
		(width 0.1143)
		(layer "In9.Cu")
		(net "P3E_CPU0_PE1_PCH_CON_TXP<14>")
	)
	(segment
		(start 317.227966 -121.14149)
		(end 316.496446 -119.488458)
		(width 0.1143)
		(layer "In9.Cu")
		(net "P3E_CPU0_PE1_PCH_CON_TXP<14>")
	)
	(segment
		(start 422.731946 -5.07111)
		(end 423.909744 -4.821174)
		(width 0.1143)
		(layer "In9.Cu")
		(net "P3E_CPU0_PE1_PCH_CON_TXP<14>")
	)
	(segment
		(start 372.425468 -11.049508)
		(end 379.440694 -9.559798)
		(width 0.1143)
		(layer "In9.Cu")
		(net "P3E_CPU0_PE1_PCH_CON_TXP<14>")
	)
	(segment
		(start 371.638576 -10.36828)
		(end 371.862604 -10.320274)
		(width 0.1143)
		(layer "In9.Cu")
		(net "P3E_CPU0_PE1_PCH_CON_TXP<14>")
	)
	(segment
		(start 433.594002 -4.826)
		(end 439.70194 -7.511034)
		(width 0.1143)
		(layer "In9.Cu")
		(net "P3E_CPU0_PE1_PCH_CON_TXP<14>")
	)
	(segment
		(start 429.918368 -5.080254)
		(end 431.505106 -4.742942)
		(width 0.1143)
		(layer "In9.Cu")
		(net "P3E_CPU0_PE1_PCH_CON_TXP<14>")
	)
	(segment
		(start 361.96778 -31.628334)
		(end 362.278422 -30.073346)
		(width 0.1143)
		(layer "In9.Cu")
		(net "P3E_CPU0_PE1_PCH_CON_TXP<14>")
	)
	(segment
		(start 317.116714 -117.243352)
		(end 316.369192 -114.915442)
		(width 0.1143)
		(layer "In9.Cu")
		(net "P3E_CPU0_PE1_PCH_CON_TXP<14>")
	)
	(segment
		(start 338.324444 -47.659544)
		(end 340.806024 -48.163988)
		(width 0.1143)
		(layer "In9.Cu")
		(net "P3E_CPU0_PE1_PCH_CON_TXP<14>")
	)
	(segment
		(start 327.572116 -101.38664)
		(end 327.581768 -101.261164)
		(width 0.1143)
		(layer "In9.Cu")
		(net "P3E_CPU0_PE1_PCH_CON_TXP<14>")
	)
	(segment
		(start 371.997732 -10.408158)
		(end 372.087394 -10.829798)
		(width 0.1143)
		(layer "In9.Cu")
		(net "P3E_CPU0_PE1_PCH_CON_TXP<14>")
	)
	(segment
		(start 394.01369 -7.169404)
		(end 394.209524 -7.296658)
		(width 0.1143)
		(layer "In9.Cu")
		(net "P3E_CPU0_PE1_PCH_CON_TXP<14>")
	)
	(segment
		(start 327.581768 -101.261164)
		(end 327.82637 -98.053652)
		(width 0.1143)
		(layer "In9.Cu")
		(net "P3E_CPU0_PE1_PCH_CON_TXP<14>")
	)
	(segment
		(start 408.46375 -4.39547)
		(end 410.0068 -4.06781)
		(width 0.1143)
		(layer "In9.Cu")
		(net "P3E_CPU0_PE1_PCH_CON_TXP<14>")
	)
	(segment
		(start 426.381926 -4.788154)
		(end 427.660562 -5.060188)
		(width 0.1143)
		(layer "In9.Cu")
		(net "P3E_CPU0_PE1_PCH_CON_TXP<14>")
	)
	(segment
		(start 317.605156 -112.452912)
		(end 325.493634 -105.165398)
		(width 0.1143)
		(layer "In9.Cu")
		(net "P3E_CPU0_PE1_PCH_CON_TXP<14>")
	)
	(segment
		(start 326.848724 -58.795666)
		(end 326.916034 -58.459624)
		(width 0.1143)
		(layer "In9.Cu")
		(net "P3E_CPU0_PE1_PCH_CON_TXP<14>")
	)
	(segment
		(start 326.915272 -61.359542)
		(end 326.720962 -61.230002)
		(width 0.1143)
		(layer "In9.Cu")
		(net "P3E_CPU0_PE1_PCH_CON_TXP<14>")
	)
	(segment
		(start 322.467224 -122.714512)
		(end 321.538346 -122.714512)
		(width 0.1143)
		(layer "In9.Cu")
		(net "P3E_CPU0_PE1_PCH_CON_TXP<14>")
	)
	(segment
		(start 322.90512 -122.884438)
		(end 322.790566 -122.884438)
		(width 0.1143)
		(layer "In9.Cu")
		(net "P3E_CPU0_PE1_PCH_CON_TXP<14>")
	)
	(segment
		(start 362.78058 -25.58415)
		(end 362.78058 -25.584404)
		(width 0.1143)
		(layer "In9.Cu")
		(net "P3E_CPU0_PE1_PCH_CON_TXP<14>")
	)
	(segment
		(start 326.238108 -63.823088)
		(end 326.4662 -63.47841)
		(width 0.1143)
		(layer "In9.Cu")
		(net "P3E_CPU0_PE1_PCH_CON_TXP<14>")
	)
	(segment
		(start 328.652632 -52.291996)
		(end 333.81696 -48.57623)
		(width 0.1143)
		(layer "In9.Cu")
		(net "P3E_CPU0_PE1_PCH_CON_TXP<14>")
	)
	(segment
		(start 326.860662 -57.89422)
		(end 326.754236 -57.361074)
		(width 0.1143)
		(layer "In9.Cu")
		(net "P3E_CPU0_PE1_PCH_CON_TXP<14>")
	)
	(segment
		(start 316.496446 -119.488458)
		(end 317.116714 -117.243352)
		(width 0.1143)
		(layer "In9.Cu")
		(net "P3E_CPU0_PE1_PCH_CON_TXP<14>")
	)
	(segment
		(start 394.209524 -7.296658)
		(end 394.544804 -7.225284)
		(width 0.1143)
		(layer "In9.Cu")
		(net "P3E_CPU0_PE1_PCH_CON_TXP<14>")
	)
	(segment
		(start 325.075804 -74.522838)
		(end 325.628254 -71.92264)
		(width 0.1143)
		(layer "In9.Cu")
		(net "P3E_CPU0_PE1_PCH_CON_TXP<14>")
	)
	(segment
		(start 333.81696 -48.57623)
		(end 338.324444 -47.659544)
		(width 0.1143)
		(layer "In9.Cu")
		(net "P3E_CPU0_PE1_PCH_CON_TXP<14>")
	)
	(segment
		(start 379.440694 -9.559798)
		(end 380.303278 -9.742932)
		(width 0.1143)
		(layer "In9.Cu")
		(net "P3E_CPU0_PE1_PCH_CON_TXP<14>")
	)
	(segment
		(start 369.143788 -12.58443)
		(end 369.171982 -12.352528)
		(width 0.1143)
		(layer "In9.Cu")
		(net "P3E_CPU0_PE1_PCH_CON_TXP<14>")
	)
	(segment
		(start 325.493634 -105.165398)
		(end 327.572116 -101.38664)
		(width 0.1143)
		(layer "In9.Cu")
		(net "P3E_CPU0_PE1_PCH_CON_TXP<14>")
	)
	(segment
		(start 326.4662 -63.47841)
		(end 326.753982 -63.043816)
		(width 0.1143)
		(layer "In9.Cu")
		(net "P3E_CPU0_PE1_PCH_CON_TXP<14>")
	)
	(segment
		(start 393.678156 -7.240524)
		(end 394.01369 -7.169404)
		(width 0.1143)
		(layer "In9.Cu")
		(net "P3E_CPU0_PE1_PCH_CON_TXP<14>")
	)
	(segment
		(start 393.550902 -7.436358)
		(end 393.678156 -7.240524)
		(width 0.1143)
		(layer "In9.Cu")
		(net "P3E_CPU0_PE1_PCH_CON_TXP<14>")
	)
	(segment
		(start 410.0068 -4.06781)
		(end 412.036768 -4.498848)
		(width 0.1143)
		(layer "In9.Cu")
		(net "P3E_CPU0_PE1_PCH_CON_TXP<14>")
	)
	(segment
		(start 444.549784 -7.511034)
		(end 445.403732 -8.364982)
		(width 0.1143)
		(layer "In9.Cu")
		(net "P3E_CPU0_PE1_PCH_CON_TXP<14>")
	)
	(segment
		(start 369.943634 -11.957558)
		(end 369.971574 -11.72591)
		(width 0.1143)
		(layer "In9.Cu")
		(net "P3E_CPU0_PE1_PCH_CON_TXP<14>")
	)
	(segment
		(start 372.087394 -10.829798)
		(end 372.425468 -11.049508)
		(width 0.1143)
		(layer "In9.Cu")
		(net "P3E_CPU0_PE1_PCH_CON_TXP<14>")
	)
	(segment
		(start 394.672058 -7.02945)
		(end 396.031212 -6.74116)
		(width 0.1143)
		(layer "In9.Cu")
		(net "P3E_CPU0_PE1_PCH_CON_TXP<14>")
	)
	(segment
		(start 391.918698 -7.613904)
		(end 393.019788 -7.380224)
		(width 0.1143)
		(layer "In9.Cu")
		(net "P3E_CPU0_PE1_PCH_CON_TXP<14>")
	)
	(segment
		(start 370.241576 -11.514328)
		(end 371.42039 -11.263122)
		(width 0.1143)
		(layer "In9.Cu")
		(net "P3E_CPU0_PE1_PCH_CON_TXP<14>")
	)
	(segment
		(start 359.317036 -34.893758)
		(end 361.96778 -31.628334)
		(width 0.1143)
		(layer "In9.Cu")
		(net "P3E_CPU0_PE1_PCH_CON_TXP<14>")
	)
	(segment
		(start 391.124948 -7.445502)
		(end 391.918698 -7.613904)
		(width 0.1143)
		(layer "In9.Cu")
		(net "P3E_CPU0_PE1_PCH_CON_TXP<14>")
	)
	(segment
		(start 316.369192 -114.915442)
		(end 317.605156 -112.452912)
		(width 0.1143)
		(layer "In9.Cu")
		(net "P3E_CPU0_PE1_PCH_CON_TXP<14>")
	)
	(segment
		(start 393.019788 -7.380224)
		(end 393.215622 -7.507478)
		(width 0.1143)
		(layer "In9.Cu")
		(net "P3E_CPU0_PE1_PCH_CON_TXP<14>")
	)
	(segment
		(start 326.753982 -63.043816)
		(end 326.920352 -62.22619)
		(width 0.1143)
		(layer "In9.Cu")
		(net "P3E_CPU0_PE1_PCH_CON_TXP<14>")
	)
	(segment
		(start 446.098168 -8.364982)
		(end 446.25133 -8.518144)
		(width 0.1143)
		(layer "In9.Cu")
		(net "P3E_CPU0_PE1_PCH_CON_TXP<14>")
	)
	(segment
		(start 325.166228 -83.462368)
		(end 325.166482 -83.461606)
		(width 0.1143)
		(layer "In9.Cu")
		(net "P3E_CPU0_PE1_PCH_CON_TXP<14>")
	)
	(segment
		(start 357.853488 -42.004234)
		(end 359.317036 -34.893758)
		(width 0.1143)
		(layer "In9.Cu")
		(net "P3E_CPU0_PE1_PCH_CON_TXP<14>")
	)
	(segment
		(start 355.884734 -44.121832)
		(end 357.180642 -43.272964)
		(width 0.1143)
		(layer "In9.Cu")
		(net "P3E_CPU0_PE1_PCH_CON_TXP<14>")
	)
	(segment
		(start 326.853042 -61.889894)
		(end 326.982582 -61.695584)
		(width 0.1143)
		(layer "In9.Cu")
		(net "P3E_CPU0_PE1_PCH_CON_TXP<14>")
	)
	(segment
		(start 427.660562 -5.060188)
		(end 428.741586 -4.830064)
		(width 0.1143)
		(layer "In9.Cu")
		(net "P3E_CPU0_PE1_PCH_CON_TXP<14>")
	)
	(segment
		(start 404.833074 -4.046982)
		(end 405.776938 -3.858514)
		(width 0.1143)
		(layer "In9.Cu")
		(net "P3E_CPU0_PE1_PCH_CON_TXP<14>")
	)
	(segment
		(start 326.720962 -61.230002)
		(end 326.45731 -59.912504)
		(width 0.1143)
		(layer "In9.Cu")
		(net "P3E_CPU0_PE1_PCH_CON_TXP<14>")
	)
	(segment
		(start 428.741586 -4.830064)
		(end 429.918368 -5.080254)
		(width 0.1143)
		(layer "In9.Cu")
		(net "P3E_CPU0_PE1_PCH_CON_TXP<14>")
	)
	(segment
		(start 326.754236 -57.361074)
		(end 328.652632 -52.291996)
		(width 0.1143)
		(layer "In9.Cu")
		(net "P3E_CPU0_PE1_PCH_CON_TXP<14>")
	)
	(segment
		(start 322.998338 -122.555)
		(end 322.998338 -122.79122)
		(width 0.1143)
		(layer "In9.Cu")
		(net "P3E_CPU0_PE1_PCH_CON_TXP<14>")
	)
	(segment
		(start 326.916034 -58.459624)
		(end 326.786494 -58.265314)
		(width 0.1143)
		(layer "In9.Cu")
		(net "P3E_CPU0_PE1_PCH_CON_TXP<14>")
	)
	(segment
		(start 414.852104 -3.901186)
		(end 420.347394 -5.068062)
		(width 0.1143)
		(layer "In9.Cu")
		(net "P3E_CPU0_PE1_PCH_CON_TXP<14>")
	)
	(segment
		(start 412.036768 -4.498848)
		(end 414.852104 -3.901186)
		(width 0.1143)
		(layer "In9.Cu")
		(net "P3E_CPU0_PE1_PCH_CON_TXP<14>")
	)
	(segment
		(start 403.810724 -3.83794)
		(end 404.833074 -4.046982)
		(width 0.1143)
		(layer "In9.Cu")
		(net "P3E_CPU0_PE1_PCH_CON_TXP<14>")
	)
	(segment
		(start 362.080556 -29.084016)
		(end 362.78058 -25.58415)
		(width 0.1143)
		(layer "In9.Cu")
		(net "P3E_CPU0_PE1_PCH_CON_TXP<14>")
	)
	(segment
		(start 446.25133 -8.518144)
		(end 446.25133 -8.700008)
		(width 0.1143)
		(layer "In9.Cu")
		(net "P3E_CPU0_PE1_PCH_CON_TXP<14>")
	)
	(segment
		(start 368.87404 -12.795758)
		(end 369.143788 -12.58443)
		(width 0.1143)
		(layer "In9.Cu")
		(net "P3E_CPU0_PE1_PCH_CON_TXP<14>")
	)
	(segment
		(start 326.920352 -62.22619)
		(end 326.853042 -61.889894)
		(width 0.1143)
		(layer "In9.Cu")
		(net "P3E_CPU0_PE1_PCH_CON_TXP<14>")
	)
	(segment
		(start 322.637404 -122.884692)
		(end 322.467224 -122.714512)
		(width 0.1143)
		(layer "In9.Cu")
		(net "P3E_CPU0_PE1_PCH_CON_TXP<14>")
	)
	(segment
		(start 371.6401 -10.925048)
		(end 371.550438 -10.503662)
		(width 0.1143)
		(layer "In9.Cu")
		(net "P3E_CPU0_PE1_PCH_CON_TXP<14>")
	)
	(segment
		(start 369.673632 -12.16914)
		(end 369.943634 -11.957558)
		(width 0.1143)
		(layer "In9.Cu")
		(net "P3E_CPU0_PE1_PCH_CON_TXP<14>")
	)
	(segment
		(start 326.786494 -58.265314)
		(end 326.860662 -57.89422)
		(width 0.1143)
		(layer "In9.Cu")
		(net "P3E_CPU0_PE1_PCH_CON_TXP<14>")
	)
	(segment
		(start 327.482454 -94.36989)
		(end 325.166228 -83.462368)
		(width 0.1143)
		(layer "In9.Cu")
		(net "P3E_CPU0_PE1_PCH_CON_TXP<14>")
	)
	(segment
		(start 432.550824 -5.047996)
		(end 433.594002 -4.826)
		(width 0.1143)
		(layer "In9.Cu")
		(net "P3E_CPU0_PE1_PCH_CON_TXP<14>")
	)
	(segment
		(start 321.538346 -122.714512)
		(end 317.914782 -121.678954)
		(width 0.1143)
		(layer "In9.Cu")
		(net "P3E_CPU0_PE1_PCH_CON_TXP<14>")
	)
	(segment
		(start 326.654668 -58.925206)
		(end 326.848724 -58.795666)
		(width 0.1143)
		(layer "In9.Cu")
		(net "P3E_CPU0_PE1_PCH_CON_TXP<14>")
	)
	(segment
		(start 325.628254 -71.92264)
		(end 325.098156 -69.426582)
		(width 0.1143)
		(layer "In9.Cu")
		(net "P3E_CPU0_PE1_PCH_CON_TXP<14>")
	)
	(segment
		(start 431.505106 -4.742942)
		(end 432.550824 -5.047996)
		(width 0.1143)
		(layer "In9.Cu")
		(net "P3E_CPU0_PE1_PCH_CON_TXP<14>")
	)
	(segment
		(start 357.180642 -43.272964)
		(end 357.853488 -42.004234)
		(width 0.1143)
		(layer "In9.Cu")
		(net "P3E_CPU0_PE1_PCH_CON_TXP<14>")
	)
	(segment
		(start 369.441984 -12.140946)
		(end 369.673632 -12.16914)
		(width 0.1143)
		(layer "In9.Cu")
		(net "P3E_CPU0_PE1_PCH_CON_TXP<14>")
	)
	(segment
		(start 369.971574 -11.72591)
		(end 370.241576 -11.514328)
		(width 0.1143)
		(layer "In9.Cu")
		(net "P3E_CPU0_PE1_PCH_CON_TXP<14>")
	)
	(segment
		(start 394.544804 -7.225284)
		(end 394.672058 -7.02945)
		(width 0.1143)
		(layer "In9.Cu")
		(net "P3E_CPU0_PE1_PCH_CON_TXP<14>")
	)
	(segment
		(start 425.067984 -5.0673)
		(end 426.381926 -4.788154)
		(width 0.1143)
		(layer "In9.Cu")
		(net "P3E_CPU0_PE1_PCH_CON_TXP<14>")
	)
	(segment
		(start 393.215622 -7.507478)
		(end 393.550902 -7.436358)
		(width 0.1143)
		(layer "In9.Cu")
		(net "P3E_CPU0_PE1_PCH_CON_TXP<14>")
	)
	(segment
		(start 423.909744 -4.821174)
		(end 425.067984 -5.0673)
		(width 0.1143)
		(layer "In9.Cu")
		(net "P3E_CPU0_PE1_PCH_CON_TXP<14>")
	)
	(segment
		(start 420.347394 -5.068062)
		(end 421.532304 -4.816094)
		(width 0.1143)
		(layer "In9.Cu")
		(net "P3E_CPU0_PE1_PCH_CON_TXP<14>")
	)
	(segment
		(start 368.642138 -12.767818)
		(end 368.87404 -12.795758)
		(width 0.1143)
		(layer "In9.Cu")
		(net "P3E_CPU0_PE1_PCH_CON_TXP<14>")
	)
	(segment
		(start 325.084948 -77.480922)
		(end 325.39432 -76.023978)
		(width 0.1143)
		(layer "In9.Cu")
		(net "P3E_CPU0_PE1_PCH_CON_TXP<14>")
	)
	(segment
		(start 380.303278 -9.742932)
		(end 391.124948 -7.445502)
		(width 0.1143)
		(layer "In9.Cu")
		(net "P3E_CPU0_PE1_PCH_CON_TXP<14>")
	)
	(segment
		(start 325.166482 -83.461606)
		(end 325.802752 -80.859376)
		(width 0.1143)
		(layer "In9.Cu")
		(net "P3E_CPU0_PE1_PCH_CON_TXP<14>")
	)
	(segment
		(start 364.59541 -24.3713)
		(end 366.202976 -16.69034)
		(width 0.1143)
		(layer "In9.Cu")
		(net "P3E_CPU0_PE1_PCH_CON_TXP<14>")
	)
	(segment
		(start 325.802752 -80.859376)
		(end 325.084948 -77.480922)
		(width 0.1143)
		(layer "In9.Cu")
		(net "P3E_CPU0_PE1_PCH_CON_TXP<14>")
	)
	(segment
		(start 445.403732 -8.364982)
		(end 446.098168 -8.364982)
		(width 0.1143)
		(layer "In9.Cu")
		(net "P3E_CPU0_PE1_PCH_CON_TXP<14>")
	)
	(segment
		(start 326.982582 -61.695584)
		(end 326.915272 -61.359542)
		(width 0.1143)
		(layer "In9.Cu")
		(net "P3E_CPU0_PE1_PCH_CON_TXP<14>")
	)
	(segment
		(start 325.39432 -76.023978)
		(end 325.075804 -74.522838)
		(width 0.1143)
		(layer "In9.Cu")
		(net "P3E_CPU0_PE1_PCH_CON_TXP<14>")
	)
	(segment
		(start 322.790566 -122.884438)
		(end 322.74637 -122.884692)
		(width 0.1143)
		(layer "In9.Cu")
		(net "P3E_CPU0_PE1_PCH_CON_TXP<14>")
	)
	(segment
		(start 368.060224 -13.223748)
		(end 368.642138 -12.767818)
		(width 0.1143)
		(layer "In9.Cu")
		(net "P3E_CPU0_PE1_PCH_CON_TXP<14>")
	)
	(segment
		(start 340.806024 -48.163988)
		(end 355.884734 -44.121832)
		(width 0.1143)
		(layer "In9.Cu")
		(net "P3E_CPU0_PE1_PCH_CON_TXP<14>")
	)
	(segment
		(start 325.098156 -69.426582)
		(end 326.238108 -63.823088)
		(width 0.1143)
		(layer "In9.Cu")
		(net "P3E_CPU0_PE1_PCH_CON_TXP<14>")
	)
	(segment
		(start 396.031212 -6.74116)
		(end 403.810724 -3.83794)
		(width 0.1143)
		(layer "In9.Cu")
		(net "P3E_CPU0_PE1_PCH_CON_TXP<14>")
	)
	(segment
		(start 439.70194 -7.511034)
		(end 444.549784 -7.511034)
		(width 0.1143)
		(layer "In9.Cu")
		(net "P3E_CPU0_PE1_PCH_CON_TXP<14>")
	)
	(segment
		(start 322.74637 -122.884692)
		(end 322.637404 -122.884692)
		(width 0.1143)
		(layer "In9.Cu")
		(net "P3E_CPU0_PE1_PCH_CON_TXP<14>")
	)
	(segment
		(start 327.262998 -95.403416)
		(end 327.482454 -94.36989)
		(width 0.1143)
		(layer "In9.Cu")
		(net "P3E_CPU0_PE1_PCH_CON_TXP<14>")
	)
	(segment
		(start 322.998338 -122.79122)
		(end 322.90512 -122.884438)
		(width 0.1143)
		(layer "In9.Cu")
		(net "P3E_CPU0_PE1_PCH_CON_TXP<14>")
	)
	(segment
		(start 371.42039 -11.263122)
		(end 371.6401 -10.925048)
		(width 0.1143)
		(layer "In9.Cu")
		(net "P3E_CPU0_PE1_PCH_CON_TXP<14>")
	)
	(segment
		(start 317.914782 -121.678954)
		(end 317.227966 -121.14149)
		(width 0.1143)
		(layer "In9.Cu")
		(net "P3E_CPU0_PE1_PCH_CON_TXP<14>")
	)
	(segment
		(start 362.278422 -30.073346)
		(end 362.080556 -29.084016)
		(width 0.1143)
		(layer "In9.Cu")
		(net "P3E_CPU0_PE1_PCH_CON_TXP<14>")
	)
	(segment
		(start 362.78058 -25.584404)
		(end 364.59541 -24.3713)
		(width 0.1143)
		(layer "In9.Cu")
		(net "P3E_CPU0_PE1_PCH_CON_TXP<14>")
	)
	(segment
		(start 421.532304 -4.816094)
		(end 422.731946 -5.07111)
		(width 0.1143)
		(layer "In9.Cu")
		(net "P3E_CPU0_PE1_PCH_CON_TXP<14>")
	)
	(segment
		(start 323.10324 -120.396)
		(end 322.99656 -120.50268)
		(width 0.1143)
		(layer "F.Cu")
		(net "P3E_CPU0_PE1_PCH_CON_TXP<13>")
	)
	(segment
		(start 443.676786 -8.47344)
		(end 443.676786 -7.789672)
		(width 0.1143)
		(layer "F.Cu")
		(net "P3E_CPU0_PE1_PCH_CON_TXP<13>")
	)
	(segment
		(start 443.83325 -9.12495)
		(end 443.956186 -9.002014)
		(width 0.1143)
		(layer "F.Cu")
		(net "P3E_CPU0_PE1_PCH_CON_TXP<13>")
	)
	(segment
		(start 323.6595 -120.396)
		(end 323.10324 -120.396)
		(width 0.1143)
		(layer "F.Cu")
		(net "P3E_CPU0_PE1_PCH_CON_TXP<13>")
	)
	(segment
		(start 443.6237 -9.12495)
		(end 443.83325 -9.12495)
		(width 0.1143)
		(layer "F.Cu")
		(net "P3E_CPU0_PE1_PCH_CON_TXP<13>")
	)
	(segment
		(start 443.956186 -9.002014)
		(end 443.956186 -8.75284)
		(width 0.1143)
		(layer "F.Cu")
		(net "P3E_CPU0_PE1_PCH_CON_TXP<13>")
	)
	(segment
		(start 443.956186 -8.75284)
		(end 443.676786 -8.47344)
		(width 0.1143)
		(layer "F.Cu")
		(net "P3E_CPU0_PE1_PCH_CON_TXP<13>")
	)
	(via
		(at 322.99656 -120.50268)
		(size 0.508)
		(drill 0.254)
		(layers "F.Cu" "B.Cu")
		(net "P3E_CPU0_PE1_PCH_CON_TXP<13>")
	)
	(via
		(at 443.6237 -9.12495)
		(size 0.508)
		(drill 0.254)
		(layers "F.Cu" "B.Cu")
		(net "P3E_CPU0_PE1_PCH_CON_TXP<13>")
	)
	(segment
		(start 328.79665 -54.22519)
		(end 328.699876 -54.012592)
		(width 0.1143)
		(layer "In9.Cu")
		(net "P3E_CPU0_PE1_PCH_CON_TXP<13>")
	)
	(segment
		(start 328.320146 -55.49773)
		(end 328.440288 -55.176674)
		(width 0.1143)
		(layer "In9.Cu")
		(net "P3E_CPU0_PE1_PCH_CON_TXP<13>")
	)
	(segment
		(start 318.187832 -112.792002)
		(end 318.187832 -112.791748)
		(width 0.1143)
		(layer "In9.Cu")
		(net "P3E_CPU0_PE1_PCH_CON_TXP<13>")
	)
	(segment
		(start 367.425732 -16.290544)
		(end 367.358168 -16.067024)
		(width 0.1143)
		(layer "In9.Cu")
		(net "P3E_CPU0_PE1_PCH_CON_TXP<13>")
	)
	(segment
		(start 415.836608 -4.771136)
		(end 416.171888 -4.84251)
		(width 0.1143)
		(layer "In9.Cu")
		(net "P3E_CPU0_PE1_PCH_CON_TXP<13>")
	)
	(segment
		(start 358.444292 -42.32021)
		(end 359.916476 -35.169348)
		(width 0.1143)
		(layer "In9.Cu")
		(net "P3E_CPU0_PE1_PCH_CON_TXP<13>")
	)
	(segment
		(start 334.047592 -49.216818)
		(end 338.32546 -48.346106)
		(width 0.1143)
		(layer "In9.Cu")
		(net "P3E_CPU0_PE1_PCH_CON_TXP<13>")
	)
	(segment
		(start 365.971582 -20.976844)
		(end 366.780318 -17.146016)
		(width 0.1143)
		(layer "In9.Cu")
		(net "P3E_CPU0_PE1_PCH_CON_TXP<13>")
	)
	(segment
		(start 413.69996 -4.802632)
		(end 413.848804 -4.771136)
		(width 0.1143)
		(layer "In9.Cu")
		(net "P3E_CPU0_PE1_PCH_CON_TXP<13>")
	)
	(segment
		(start 417.824412 -5.193792)
		(end 417.824412 -5.194046)
		(width 0.1143)
		(layer "In9.Cu")
		(net "P3E_CPU0_PE1_PCH_CON_TXP<13>")
	)
	(segment
		(start 414.842706 -4.559808)
		(end 415.177986 -4.631182)
		(width 0.1143)
		(layer "In9.Cu")
		(net "P3E_CPU0_PE1_PCH_CON_TXP<13>")
	)
	(segment
		(start 320.148966 -121.43105)
		(end 318.255396 -121.093484)
		(width 0.1143)
		(layer "In9.Cu")
		(net "P3E_CPU0_PE1_PCH_CON_TXP<13>")
	)
	(segment
		(start 367.905538 -15.39494)
		(end 367.837974 -15.17142)
		(width 0.1143)
		(layer "In9.Cu")
		(net "P3E_CPU0_PE1_PCH_CON_TXP<13>")
	)
	(segment
		(start 317.792862 -117.229382)
		(end 317.077344 -115.004596)
		(width 0.1143)
		(layer "In9.Cu")
		(net "P3E_CPU0_PE1_PCH_CON_TXP<13>")
	)
	(segment
		(start 415.640774 -4.89839)
		(end 415.836608 -4.771136)
		(width 0.1143)
		(layer "In9.Cu")
		(net "P3E_CPU0_PE1_PCH_CON_TXP<13>")
	)
	(segment
		(start 408.40279 -5.069078)
		(end 409.974796 -4.735068)
		(width 0.1143)
		(layer "In9.Cu")
		(net "P3E_CPU0_PE1_PCH_CON_TXP<13>")
	)
	(segment
		(start 427.635162 -5.717032)
		(end 428.71644 -5.486908)
		(width 0.1143)
		(layer "In9.Cu")
		(net "P3E_CPU0_PE1_PCH_CON_TXP<13>")
	)
	(segment
		(start 413.51327 -4.842002)
		(end 413.51327 -4.842256)
		(width 0.1143)
		(layer "In9.Cu")
		(net "P3E_CPU0_PE1_PCH_CON_TXP<13>")
	)
	(segment
		(start 418.62248 -5.532374)
		(end 418.818314 -5.405374)
		(width 0.1143)
		(layer "In9.Cu")
		(net "P3E_CPU0_PE1_PCH_CON_TXP<13>")
	)
	(segment
		(start 338.32546 -48.346106)
		(end 340.763352 -48.842168)
		(width 0.1143)
		(layer "In9.Cu")
		(net "P3E_CPU0_PE1_PCH_CON_TXP<13>")
	)
	(segment
		(start 413.050736 -5.10921)
		(end 413.38627 -5.037836)
		(width 0.1143)
		(layer "In9.Cu")
		(net "P3E_CPU0_PE1_PCH_CON_TXP<13>")
	)
	(segment
		(start 425.04614 -5.724906)
		(end 426.360082 -5.44576)
		(width 0.1143)
		(layer "In9.Cu")
		(net "P3E_CPU0_PE1_PCH_CON_TXP<13>")
	)
	(segment
		(start 417.16579 -5.053838)
		(end 417.293044 -5.249672)
		(width 0.1143)
		(layer "In9.Cu")
		(net "P3E_CPU0_PE1_PCH_CON_TXP<13>")
	)
	(segment
		(start 404.861522 -4.72948)
		(end 405.78278 -4.54533)
		(width 0.1143)
		(layer "In9.Cu")
		(net "P3E_CPU0_PE1_PCH_CON_TXP<13>")
	)
	(segment
		(start 326.894952 -64.048386)
		(end 327.391268 -63.298324)
		(width 0.1143)
		(layer "In9.Cu")
		(net "P3E_CPU0_PE1_PCH_CON_TXP<13>")
	)
	(segment
		(start 422.715182 -5.729732)
		(end 423.89298 -5.479796)
		(width 0.1143)
		(layer "In9.Cu")
		(net "P3E_CPU0_PE1_PCH_CON_TXP<13>")
	)
	(segment
		(start 326.159622 -105.427018)
		(end 328.223372 -101.675184)
		(width 0.1143)
		(layer "In9.Cu")
		(net "P3E_CPU0_PE1_PCH_CON_TXP<13>")
	)
	(segment
		(start 409.974796 -4.735068)
		(end 411.996382 -5.164328)
		(width 0.1143)
		(layer "In9.Cu")
		(net "P3E_CPU0_PE1_PCH_CON_TXP<13>")
	)
	(segment
		(start 329.032616 -53.594762)
		(end 329.152758 -53.273706)
		(width 0.1143)
		(layer "In9.Cu")
		(net "P3E_CPU0_PE1_PCH_CON_TXP<13>")
	)
	(segment
		(start 415.30524 -4.827016)
		(end 415.640774 -4.89839)
		(width 0.1143)
		(layer "In9.Cu")
		(net "P3E_CPU0_PE1_PCH_CON_TXP<13>")
	)
	(segment
		(start 414.507172 -4.630928)
		(end 414.842706 -4.559808)
		(width 0.1143)
		(layer "In9.Cu")
		(net "P3E_CPU0_PE1_PCH_CON_TXP<13>")
	)
	(segment
		(start 416.171888 -4.84251)
		(end 416.299142 -5.038344)
		(width 0.1143)
		(layer "In9.Cu")
		(net "P3E_CPU0_PE1_PCH_CON_TXP<13>")
	)
	(segment
		(start 327.391268 -63.298324)
		(end 328.160634 -59.372754)
		(width 0.1143)
		(layer "In9.Cu")
		(net "P3E_CPU0_PE1_PCH_CON_TXP<13>")
	)
	(segment
		(start 329.152758 -53.273706)
		(end 329.056238 -53.061108)
		(width 0.1143)
		(layer "In9.Cu")
		(net "P3E_CPU0_PE1_PCH_CON_TXP<13>")
	)
	(segment
		(start 418.286946 -5.461254)
		(end 418.62248 -5.532374)
		(width 0.1143)
		(layer "In9.Cu")
		(net "P3E_CPU0_PE1_PCH_CON_TXP<13>")
	)
	(segment
		(start 328.699876 -54.012592)
		(end 328.820018 -53.691536)
		(width 0.1143)
		(layer "In9.Cu")
		(net "P3E_CPU0_PE1_PCH_CON_TXP<13>")
	)
	(segment
		(start 413.848804 -4.770882)
		(end 414.044638 -4.898136)
		(width 0.1143)
		(layer "In9.Cu")
		(net "P3E_CPU0_PE1_PCH_CON_TXP<13>")
	)
	(segment
		(start 371.097556 -12.002262)
		(end 379.48235 -10.221468)
		(width 0.1143)
		(layer "In9.Cu")
		(net "P3E_CPU0_PE1_PCH_CON_TXP<13>")
	)
	(segment
		(start 403.82571 -4.517644)
		(end 404.861522 -4.72948)
		(width 0.1143)
		(layer "In9.Cu")
		(net "P3E_CPU0_PE1_PCH_CON_TXP<13>")
	)
	(segment
		(start 433.545234 -5.498592)
		(end 439.614056 -8.1661)
		(width 0.1143)
		(layer "In9.Cu")
		(net "P3E_CPU0_PE1_PCH_CON_TXP<13>")
	)
	(segment
		(start 367.263934 -16.592804)
		(end 367.425732 -16.290544)
		(width 0.1143)
		(layer "In9.Cu")
		(net "P3E_CPU0_PE1_PCH_CON_TXP<13>")
	)
	(segment
		(start 318.255396 -121.093484)
		(end 317.73495 -120.685814)
		(width 0.1143)
		(layer "In9.Cu")
		(net "P3E_CPU0_PE1_PCH_CON_TXP<13>")
	)
	(segment
		(start 443.832996 -9.12495)
		(end 443.6237 -9.12495)
		(width 0.1143)
		(layer "In9.Cu")
		(net "P3E_CPU0_PE1_PCH_CON_TXP<13>")
	)
	(segment
		(start 367.52022 -15.764764)
		(end 367.74374 -15.6972)
		(width 0.1143)
		(layer "In9.Cu")
		(net "P3E_CPU0_PE1_PCH_CON_TXP<13>")
	)
	(segment
		(start 366.780318 -17.146016)
		(end 367.040414 -16.660368)
		(width 0.1143)
		(layer "In9.Cu")
		(net "P3E_CPU0_PE1_PCH_CON_TXP<13>")
	)
	(segment
		(start 326.280018 -71.92264)
		(end 325.776082 -69.549518)
		(width 0.1143)
		(layer "In9.Cu")
		(net "P3E_CPU0_PE1_PCH_CON_TXP<13>")
	)
	(segment
		(start 362.766356 -29.13507)
		(end 363.39653 -25.985216)
		(width 0.1143)
		(layer "In9.Cu")
		(net "P3E_CPU0_PE1_PCH_CON_TXP<13>")
	)
	(segment
		(start 368.404902 -14.113002)
		(end 371.097556 -12.002262)
		(width 0.1143)
		(layer "In9.Cu")
		(net "P3E_CPU0_PE1_PCH_CON_TXP<13>")
	)
	(segment
		(start 439.614056 -8.1661)
		(end 443.652656 -8.1661)
		(width 0.1143)
		(layer "In9.Cu")
		(net "P3E_CPU0_PE1_PCH_CON_TXP<13>")
	)
	(segment
		(start 390.867392 -8.174482)
		(end 392.00455 -8.41629)
		(width 0.1143)
		(layer "In9.Cu")
		(net "P3E_CPU0_PE1_PCH_CON_TXP<13>")
	)
	(segment
		(start 329.056238 -53.061108)
		(end 329.057508 -53.057298)
		(width 0.1143)
		(layer "In9.Cu")
		(net "P3E_CPU0_PE1_PCH_CON_TXP<13>")
	)
	(segment
		(start 413.848804 -4.771136)
		(end 413.848804 -4.770882)
		(width 0.1143)
		(layer "In9.Cu")
		(net "P3E_CPU0_PE1_PCH_CON_TXP<13>")
	)
	(segment
		(start 415.177986 -4.631182)
		(end 415.30524 -4.827016)
		(width 0.1143)
		(layer "In9.Cu")
		(net "P3E_CPU0_PE1_PCH_CON_TXP<13>")
	)
	(segment
		(start 392.00455 -8.41629)
		(end 395.205712 -7.736332)
		(width 0.1143)
		(layer "In9.Cu")
		(net "P3E_CPU0_PE1_PCH_CON_TXP<13>")
	)
	(segment
		(start 356.159054 -44.715938)
		(end 357.713534 -43.69816)
		(width 0.1143)
		(layer "In9.Cu")
		(net "P3E_CPU0_PE1_PCH_CON_TXP<13>")
	)
	(segment
		(start 412.854902 -4.981956)
		(end 413.050736 -5.10921)
		(width 0.1143)
		(layer "In9.Cu")
		(net "P3E_CPU0_PE1_PCH_CON_TXP<13>")
	)
	(segment
		(start 362.976922 -30.187138)
		(end 362.766356 -29.13507)
		(width 0.1143)
		(layer "In9.Cu")
		(net "P3E_CPU0_PE1_PCH_CON_TXP<13>")
	)
	(segment
		(start 428.71644 -5.486908)
		(end 429.892968 -5.736844)
		(width 0.1143)
		(layer "In9.Cu")
		(net "P3E_CPU0_PE1_PCH_CON_TXP<13>")
	)
	(segment
		(start 325.824088 -83.489292)
		(end 326.460612 -80.886808)
		(width 0.1143)
		(layer "In9.Cu")
		(net "P3E_CPU0_PE1_PCH_CON_TXP<13>")
	)
	(segment
		(start 417.628578 -5.321046)
		(end 417.824412 -5.193792)
		(width 0.1143)
		(layer "In9.Cu")
		(net "P3E_CPU0_PE1_PCH_CON_TXP<13>")
	)
	(segment
		(start 367.74374 -15.6972)
		(end 367.905538 -15.39494)
		(width 0.1143)
		(layer "In9.Cu")
		(net "P3E_CPU0_PE1_PCH_CON_TXP<13>")
	)
	(segment
		(start 328.676254 -54.546246)
		(end 328.79665 -54.22519)
		(width 0.1143)
		(layer "In9.Cu")
		(net "P3E_CPU0_PE1_PCH_CON_TXP<13>")
	)
	(segment
		(start 405.78278 -4.54533)
		(end 408.40279 -5.069078)
		(width 0.1143)
		(layer "In9.Cu")
		(net "P3E_CPU0_PE1_PCH_CON_TXP<13>")
	)
	(segment
		(start 321.957954 -120.917208)
		(end 320.148966 -121.43105)
		(width 0.1143)
		(layer "In9.Cu")
		(net "P3E_CPU0_PE1_PCH_CON_TXP<13>")
	)
	(segment
		(start 326.460612 -80.886808)
		(end 325.736966 -77.480922)
		(width 0.1143)
		(layer "In9.Cu")
		(net "P3E_CPU0_PE1_PCH_CON_TXP<13>")
	)
	(segment
		(start 420.32301 -5.72516)
		(end 421.50792 -5.473192)
		(width 0.1143)
		(layer "In9.Cu")
		(net "P3E_CPU0_PE1_PCH_CON_TXP<13>")
	)
	(segment
		(start 416.634676 -5.109718)
		(end 416.83051 -4.982464)
		(width 0.1143)
		(layer "In9.Cu")
		(net "P3E_CPU0_PE1_PCH_CON_TXP<13>")
	)
	(segment
		(start 365.162592 -24.807672)
		(end 365.971582 -20.976844)
		(width 0.1143)
		(layer "In9.Cu")
		(net "P3E_CPU0_PE1_PCH_CON_TXP<13>")
	)
	(segment
		(start 417.293044 -5.249672)
		(end 417.628578 -5.321046)
		(width 0.1143)
		(layer "In9.Cu")
		(net "P3E_CPU0_PE1_PCH_CON_TXP<13>")
	)
	(segment
		(start 432.526186 -5.715508)
		(end 433.545234 -5.498592)
		(width 0.1143)
		(layer "In9.Cu")
		(net "P3E_CPU0_PE1_PCH_CON_TXP<13>")
	)
	(segment
		(start 328.343768 -54.964076)
		(end 328.46391 -54.64302)
		(width 0.1143)
		(layer "In9.Cu")
		(net "P3E_CPU0_PE1_PCH_CON_TXP<13>")
	)
	(segment
		(start 395.205712 -7.736332)
		(end 403.82571 -4.517644)
		(width 0.1143)
		(layer "In9.Cu")
		(net "P3E_CPU0_PE1_PCH_CON_TXP<13>")
	)
	(segment
		(start 328.160634 -59.372754)
		(end 327.649332 -56.818022)
		(width 0.1143)
		(layer "In9.Cu")
		(net "P3E_CPU0_PE1_PCH_CON_TXP<13>")
	)
	(segment
		(start 443.94755 -8.460994)
		(end 443.94755 -9.010396)
		(width 0.1143)
		(layer "In9.Cu")
		(net "P3E_CPU0_PE1_PCH_CON_TXP<13>")
	)
	(segment
		(start 362.655866 -31.793434)
		(end 362.976922 -30.187138)
		(width 0.1143)
		(layer "In9.Cu")
		(net "P3E_CPU0_PE1_PCH_CON_TXP<13>")
	)
	(segment
		(start 328.107548 -55.594504)
		(end 328.320146 -55.49773)
		(width 0.1143)
		(layer "In9.Cu")
		(net "P3E_CPU0_PE1_PCH_CON_TXP<13>")
	)
	(segment
		(start 357.713534 -43.69816)
		(end 358.444292 -42.32021)
		(width 0.1143)
		(layer "In9.Cu")
		(net "P3E_CPU0_PE1_PCH_CON_TXP<13>")
	)
	(segment
		(start 416.299142 -5.038344)
		(end 416.634676 -5.109718)
		(width 0.1143)
		(layer "In9.Cu")
		(net "P3E_CPU0_PE1_PCH_CON_TXP<13>")
	)
	(segment
		(start 363.39653 -25.985216)
		(end 365.162592 -24.807672)
		(width 0.1143)
		(layer "In9.Cu")
		(net "P3E_CPU0_PE1_PCH_CON_TXP<13>")
	)
	(segment
		(start 328.440288 -55.176674)
		(end 328.343768 -54.964076)
		(width 0.1143)
		(layer "In9.Cu")
		(net "P3E_CPU0_PE1_PCH_CON_TXP<13>")
	)
	(segment
		(start 328.223372 -101.675184)
		(end 328.493628 -98.12655)
		(width 0.1143)
		(layer "In9.Cu")
		(net "P3E_CPU0_PE1_PCH_CON_TXP<13>")
	)
	(segment
		(start 414.044638 -4.898136)
		(end 414.380172 -4.826762)
		(width 0.1143)
		(layer "In9.Cu")
		(net "P3E_CPU0_PE1_PCH_CON_TXP<13>")
	)
	(segment
		(start 413.38627 -5.037836)
		(end 413.51327 -4.842002)
		(width 0.1143)
		(layer "In9.Cu")
		(net "P3E_CPU0_PE1_PCH_CON_TXP<13>")
	)
	(segment
		(start 317.1825 -119.438166)
		(end 317.792862 -117.229382)
		(width 0.1143)
		(layer "In9.Cu")
		(net "P3E_CPU0_PE1_PCH_CON_TXP<13>")
	)
	(segment
		(start 322.582032 -120.917208)
		(end 321.957954 -120.917208)
		(width 0.1143)
		(layer "In9.Cu")
		(net "P3E_CPU0_PE1_PCH_CON_TXP<13>")
	)
	(segment
		(start 329.057508 -53.057298)
		(end 329.186286 -52.713636)
		(width 0.1143)
		(layer "In9.Cu")
		(net "P3E_CPU0_PE1_PCH_CON_TXP<13>")
	)
	(segment
		(start 359.916476 -35.169348)
		(end 362.655866 -31.793434)
		(width 0.1143)
		(layer "In9.Cu")
		(net "P3E_CPU0_PE1_PCH_CON_TXP<13>")
	)
	(segment
		(start 326.046084 -76.023978)
		(end 325.727568 -74.523092)
		(width 0.1143)
		(layer "In9.Cu")
		(net "P3E_CPU0_PE1_PCH_CON_TXP<13>")
	)
	(segment
		(start 411.996382 -5.164328)
		(end 412.854902 -4.981956)
		(width 0.1143)
		(layer "In9.Cu")
		(net "P3E_CPU0_PE1_PCH_CON_TXP<13>")
	)
	(segment
		(start 327.923398 -95.444056)
		(end 328.143362 -94.409006)
		(width 0.1143)
		(layer "In9.Cu")
		(net "P3E_CPU0_PE1_PCH_CON_TXP<13>")
	)
	(segment
		(start 380.35611 -10.406888)
		(end 390.867392 -8.174482)
		(width 0.1143)
		(layer "In9.Cu")
		(net "P3E_CPU0_PE1_PCH_CON_TXP<13>")
	)
	(segment
		(start 328.820018 -53.691536)
		(end 329.032616 -53.594762)
		(width 0.1143)
		(layer "In9.Cu")
		(net "P3E_CPU0_PE1_PCH_CON_TXP<13>")
	)
	(segment
		(start 325.727568 -74.523092)
		(end 326.280018 -71.92264)
		(width 0.1143)
		(layer "In9.Cu")
		(net "P3E_CPU0_PE1_PCH_CON_TXP<13>")
	)
	(segment
		(start 340.763352 -48.842168)
		(end 356.159054 -44.715938)
		(width 0.1143)
		(layer "In9.Cu")
		(net "P3E_CPU0_PE1_PCH_CON_TXP<13>")
	)
	(segment
		(start 322.99656 -120.50268)
		(end 322.582032 -120.917208)
		(width 0.1143)
		(layer "In9.Cu")
		(net "P3E_CPU0_PE1_PCH_CON_TXP<13>")
	)
	(segment
		(start 367.837974 -15.17142)
		(end 368.404902 -14.113002)
		(width 0.1143)
		(layer "In9.Cu")
		(net "P3E_CPU0_PE1_PCH_CON_TXP<13>")
	)
	(segment
		(start 429.892968 -5.736844)
		(end 431.458624 -5.404104)
		(width 0.1143)
		(layer "In9.Cu")
		(net "P3E_CPU0_PE1_PCH_CON_TXP<13>")
	)
	(segment
		(start 367.358168 -16.067024)
		(end 367.52022 -15.764764)
		(width 0.1143)
		(layer "In9.Cu")
		(net "P3E_CPU0_PE1_PCH_CON_TXP<13>")
	)
	(segment
		(start 329.186286 -52.713636)
		(end 334.047592 -49.216818)
		(width 0.1143)
		(layer "In9.Cu")
		(net "P3E_CPU0_PE1_PCH_CON_TXP<13>")
	)
	(segment
		(start 328.493628 -98.12655)
		(end 327.923398 -95.444056)
		(width 0.1143)
		(layer "In9.Cu")
		(net "P3E_CPU0_PE1_PCH_CON_TXP<13>")
	)
	(segment
		(start 426.360082 -5.44576)
		(end 427.635162 -5.717032)
		(width 0.1143)
		(layer "In9.Cu")
		(net "P3E_CPU0_PE1_PCH_CON_TXP<13>")
	)
	(segment
		(start 431.458624 -5.404104)
		(end 432.526186 -5.715508)
		(width 0.1143)
		(layer "In9.Cu")
		(net "P3E_CPU0_PE1_PCH_CON_TXP<13>")
	)
	(segment
		(start 443.652656 -8.1661)
		(end 443.94755 -8.460994)
		(width 0.1143)
		(layer "In9.Cu")
		(net "P3E_CPU0_PE1_PCH_CON_TXP<13>")
	)
	(segment
		(start 318.187832 -112.791748)
		(end 326.159622 -105.427018)
		(width 0.1143)
		(layer "In9.Cu")
		(net "P3E_CPU0_PE1_PCH_CON_TXP<13>")
	)
	(segment
		(start 413.51327 -4.842256)
		(end 413.69996 -4.802632)
		(width 0.1143)
		(layer "In9.Cu")
		(net "P3E_CPU0_PE1_PCH_CON_TXP<13>")
	)
	(segment
		(start 423.89298 -5.479796)
		(end 425.04614 -5.724906)
		(width 0.1143)
		(layer "In9.Cu")
		(net "P3E_CPU0_PE1_PCH_CON_TXP<13>")
	)
	(segment
		(start 327.649332 -56.818022)
		(end 328.107548 -55.594504)
		(width 0.1143)
		(layer "In9.Cu")
		(net "P3E_CPU0_PE1_PCH_CON_TXP<13>")
	)
	(segment
		(start 325.776082 -69.549518)
		(end 326.894952 -64.048386)
		(width 0.1143)
		(layer "In9.Cu")
		(net "P3E_CPU0_PE1_PCH_CON_TXP<13>")
	)
	(segment
		(start 328.143362 -94.409006)
		(end 325.824088 -83.489292)
		(width 0.1143)
		(layer "In9.Cu")
		(net "P3E_CPU0_PE1_PCH_CON_TXP<13>")
	)
	(segment
		(start 418.818314 -5.405374)
		(end 420.32301 -5.72516)
		(width 0.1143)
		(layer "In9.Cu")
		(net "P3E_CPU0_PE1_PCH_CON_TXP<13>")
	)
	(segment
		(start 379.48235 -10.221468)
		(end 380.35611 -10.406888)
		(width 0.1143)
		(layer "In9.Cu")
		(net "P3E_CPU0_PE1_PCH_CON_TXP<13>")
	)
	(segment
		(start 416.83051 -4.982464)
		(end 417.16579 -5.053838)
		(width 0.1143)
		(layer "In9.Cu")
		(net "P3E_CPU0_PE1_PCH_CON_TXP<13>")
	)
	(segment
		(start 328.46391 -54.64302)
		(end 328.676254 -54.546246)
		(width 0.1143)
		(layer "In9.Cu")
		(net "P3E_CPU0_PE1_PCH_CON_TXP<13>")
	)
	(segment
		(start 317.73495 -120.685814)
		(end 317.1825 -119.438166)
		(width 0.1143)
		(layer "In9.Cu")
		(net "P3E_CPU0_PE1_PCH_CON_TXP<13>")
	)
	(segment
		(start 443.94755 -9.010396)
		(end 443.832996 -9.12495)
		(width 0.1143)
		(layer "In9.Cu")
		(net "P3E_CPU0_PE1_PCH_CON_TXP<13>")
	)
	(segment
		(start 414.380172 -4.826762)
		(end 414.507172 -4.630928)
		(width 0.1143)
		(layer "In9.Cu")
		(net "P3E_CPU0_PE1_PCH_CON_TXP<13>")
	)
	(segment
		(start 417.824412 -5.194046)
		(end 418.159692 -5.26542)
		(width 0.1143)
		(layer "In9.Cu")
		(net "P3E_CPU0_PE1_PCH_CON_TXP<13>")
	)
	(segment
		(start 421.50792 -5.473192)
		(end 422.715182 -5.729732)
		(width 0.1143)
		(layer "In9.Cu")
		(net "P3E_CPU0_PE1_PCH_CON_TXP<13>")
	)
	(segment
		(start 367.040414 -16.660368)
		(end 367.263934 -16.592804)
		(width 0.1143)
		(layer "In9.Cu")
		(net "P3E_CPU0_PE1_PCH_CON_TXP<13>")
	)
	(segment
		(start 418.159692 -5.26542)
		(end 418.286946 -5.461254)
		(width 0.1143)
		(layer "In9.Cu")
		(net "P3E_CPU0_PE1_PCH_CON_TXP<13>")
	)
	(segment
		(start 317.077344 -115.004596)
		(end 318.187832 -112.792002)
		(width 0.1143)
		(layer "In9.Cu")
		(net "P3E_CPU0_PE1_PCH_CON_TXP<13>")
	)
	(segment
		(start 325.736966 -77.480922)
		(end 326.046084 -76.023978)
		(width 0.1143)
		(layer "In9.Cu")
		(net "P3E_CPU0_PE1_PCH_CON_TXP<13>")
	)
	(segment
		(start 441.2742 -10.0584)
		(end 441.522358 -9.810242)
		(width 0.1143)
		(layer "F.Cu")
		(net "P3E_CPU0_PE1_PCH_CON_TXP<12>")
	)
	(segment
		(start 441.1218 -10.0584)
		(end 441.2742 -10.0584)
		(width 0.1143)
		(layer "F.Cu")
		(net "P3E_CPU0_PE1_PCH_CON_TXP<12>")
	)
	(segment
		(start 441.522358 -8.903208)
		(end 441.276486 -8.657336)
		(width 0.1143)
		(layer "F.Cu")
		(net "P3E_CPU0_PE1_PCH_CON_TXP<12>")
	)
	(segment
		(start 319.564004 -119.26316)
		(end 320.27622 -119.26316)
		(width 0.1143)
		(layer "F.Cu")
		(net "P3E_CPU0_PE1_PCH_CON_TXP<12>")
	)
	(segment
		(start 441.276486 -8.657336)
		(end 441.276486 -7.789672)
		(width 0.1143)
		(layer "F.Cu")
		(net "P3E_CPU0_PE1_PCH_CON_TXP<12>")
	)
	(segment
		(start 441.522358 -9.810242)
		(end 441.522358 -8.903208)
		(width 0.1143)
		(layer "F.Cu")
		(net "P3E_CPU0_PE1_PCH_CON_TXP<12>")
	)
	(via
		(at 319.564004 -119.26316)
		(size 0.508)
		(drill 0.254)
		(layers "F.Cu" "B.Cu")
		(net "P3E_CPU0_PE1_PCH_CON_TXP<12>")
	)
	(via
		(at 441.1218 -10.0584)
		(size 0.508)
		(drill 0.254)
		(layers "F.Cu" "B.Cu")
		(net "P3E_CPU0_PE1_PCH_CON_TXP<12>")
	)
	(segment
		(start 328.552556 -93.10878)
		(end 328.67981 -92.912946)
		(width 0.1143)
		(layer "In9.Cu")
		(net "P3E_CPU0_PE1_PCH_CON_TXP<12>")
	)
	(segment
		(start 439.619644 -8.862314)
		(end 441.247022 -8.862314)
		(width 0.1143)
		(layer "In9.Cu")
		(net "P3E_CPU0_PE1_PCH_CON_TXP<12>")
	)
	(segment
		(start 390.291066 -9.12622)
		(end 390.418066 -8.930386)
		(width 0.1143)
		(layer "In9.Cu")
		(net "P3E_CPU0_PE1_PCH_CON_TXP<12>")
	)
	(segment
		(start 326.38873 -77.490574)
		(end 326.388984 -77.489558)
		(width 0.1143)
		(layer "In9.Cu")
		(net "P3E_CPU0_PE1_PCH_CON_TXP<12>")
	)
	(segment
		(start 328.201782 -91.45651)
		(end 328.130662 -91.120976)
		(width 0.1143)
		(layer "In9.Cu")
		(net "P3E_CPU0_PE1_PCH_CON_TXP<12>")
	)
	(segment
		(start 327.38822 -87.625428)
		(end 327.515474 -87.429594)
		(width 0.1143)
		(layer "In9.Cu")
		(net "P3E_CPU0_PE1_PCH_CON_TXP<12>")
	)
	(segment
		(start 389.424418 -9.14146)
		(end 389.759698 -9.07034)
		(width 0.1143)
		(layer "In9.Cu")
		(net "P3E_CPU0_PE1_PCH_CON_TXP<12>")
	)
	(segment
		(start 405.733504 -5.214366)
		(end 408.47518 -5.762244)
		(width 0.1143)
		(layer "In9.Cu")
		(net "P3E_CPU0_PE1_PCH_CON_TXP<12>")
	)
	(segment
		(start 326.576944 -75.454256)
		(end 326.567038 -75.407266)
		(width 0.1143)
		(layer "In9.Cu")
		(net "P3E_CPU0_PE1_PCH_CON_TXP<12>")
	)
	(segment
		(start 326.931782 -71.92264)
		(end 326.426322 -69.54266)
		(width 0.1143)
		(layer "In9.Cu")
		(net "P3E_CPU0_PE1_PCH_CON_TXP<12>")
	)
	(segment
		(start 441.2742 -10.0584)
		(end 441.1218 -10.0584)
		(width 0.1143)
		(layer "In9.Cu")
		(net "P3E_CPU0_PE1_PCH_CON_TXP<12>")
	)
	(segment
		(start 334.329786 -49.84623)
		(end 334.330294 -49.845722)
		(width 0.1143)
		(layer "In9.Cu")
		(net "P3E_CPU0_PE1_PCH_CON_TXP<12>")
	)
	(segment
		(start 404.84425 -5.392674)
		(end 405.733504 -5.214366)
		(width 0.1143)
		(layer "In9.Cu")
		(net "P3E_CPU0_PE1_PCH_CON_TXP<12>")
	)
	(segment
		(start 363.647482 -30.2895)
		(end 363.424216 -29.172916)
		(width 0.1143)
		(layer "In9.Cu")
		(net "P3E_CPU0_PE1_PCH_CON_TXP<12>")
	)
	(segment
		(start 327.177146 -86.631526)
		(end 327.3044 -86.435692)
		(width 0.1143)
		(layer "In9.Cu")
		(net "P3E_CPU0_PE1_PCH_CON_TXP<12>")
	)
	(segment
		(start 390.418066 -8.930386)
		(end 390.7536 -8.859266)
		(width 0.1143)
		(layer "In9.Cu")
		(net "P3E_CPU0_PE1_PCH_CON_TXP<12>")
	)
	(segment
		(start 379.47092 -10.879328)
		(end 380.355602 -11.067288)
		(width 0.1143)
		(layer "In9.Cu")
		(net "P3E_CPU0_PE1_PCH_CON_TXP<12>")
	)
	(segment
		(start 363.290866 -32.073342)
		(end 363.647482 -30.2895)
		(width 0.1143)
		(layer "In9.Cu")
		(net "P3E_CPU0_PE1_PCH_CON_TXP<12>")
	)
	(segment
		(start 326.647048 -76.265024)
		(end 326.649842 -76.260198)
		(width 0.1143)
		(layer "In9.Cu")
		(net "P3E_CPU0_PE1_PCH_CON_TXP<12>")
	)
	(segment
		(start 327.485248 -65.162684)
		(end 327.553574 -64.826642)
		(width 0.1143)
		(layer "In9.Cu")
		(net "P3E_CPU0_PE1_PCH_CON_TXP<12>")
	)
	(segment
		(start 417.947856 -6.38048)
		(end 419.12032 -6.13156)
		(width 0.1143)
		(layer "In9.Cu")
		(net "P3E_CPU0_PE1_PCH_CON_TXP<12>")
	)
	(segment
		(start 326.389746 -77.486002)
		(end 326.389492 -77.484732)
		(width 0.1143)
		(layer "In9.Cu")
		(net "P3E_CPU0_PE1_PCH_CON_TXP<12>")
	)
	(segment
		(start 326.698864 -76.029566)
		(end 326.696832 -76.019914)
		(width 0.1143)
		(layer "In9.Cu")
		(net "P3E_CPU0_PE1_PCH_CON_TXP<12>")
	)
	(segment
		(start 326.4662 -77.114654)
		(end 326.63892 -76.303124)
		(width 0.1143)
		(layer "In9.Cu")
		(net "P3E_CPU0_PE1_PCH_CON_TXP<12>")
	)
	(segment
		(start 329.959462 -52.991004)
		(end 330.11491 -52.879244)
		(width 0.1143)
		(layer "In9.Cu")
		(net "P3E_CPU0_PE1_PCH_CON_TXP<12>")
	)
	(segment
		(start 326.63892 -84.093812)
		(end 326.544686 -83.649312)
		(width 0.1143)
		(layer "In9.Cu")
		(net "P3E_CPU0_PE1_PCH_CON_TXP<12>")
	)
	(segment
		(start 326.378824 -74.52614)
		(end 326.63892 -73.301606)
		(width 0.1143)
		(layer "In9.Cu")
		(net "P3E_CPU0_PE1_PCH_CON_TXP<12>")
	)
	(segment
		(start 319.564004 -119.495316)
		(end 319.30467 -119.75465)
		(width 0.1143)
		(layer "In9.Cu")
		(net "P3E_CPU0_PE1_PCH_CON_TXP<12>")
	)
	(segment
		(start 326.4662 -74.932794)
		(end 326.389238 -74.570082)
		(width 0.1143)
		(layer "In9.Cu")
		(net "P3E_CPU0_PE1_PCH_CON_TXP<12>")
	)
	(segment
		(start 328.83475 -94.437962)
		(end 328.76363 -94.102428)
		(width 0.1143)
		(layer "In9.Cu")
		(net "P3E_CPU0_PE1_PCH_CON_TXP<12>")
	)
	(segment
		(start 319.564004 -119.26316)
		(end 319.564004 -119.495316)
		(width 0.1143)
		(layer "In9.Cu")
		(net "P3E_CPU0_PE1_PCH_CON_TXP<12>")
	)
	(segment
		(start 328.468736 -91.919044)
		(end 328.397616 -91.58351)
		(width 0.1143)
		(layer "In9.Cu")
		(net "P3E_CPU0_PE1_PCH_CON_TXP<12>")
	)
	(segment
		(start 433.477924 -6.163056)
		(end 439.619644 -8.862314)
		(width 0.1143)
		(layer "In9.Cu")
		(net "P3E_CPU0_PE1_PCH_CON_TXP<12>")
	)
	(segment
		(start 326.38873 -74.567288)
		(end 326.387714 -74.562716)
		(width 0.1143)
		(layer "In9.Cu")
		(net "P3E_CPU0_PE1_PCH_CON_TXP<12>")
	)
	(segment
		(start 318.1096 -118.514368)
		(end 318.468502 -117.215412)
		(width 0.1143)
		(layer "In9.Cu")
		(net "P3E_CPU0_PE1_PCH_CON_TXP<12>")
	)
	(segment
		(start 326.389492 -77.487272)
		(end 326.389746 -77.486002)
		(width 0.1143)
		(layer "In9.Cu")
		(net "P3E_CPU0_PE1_PCH_CON_TXP<12>")
	)
	(segment
		(start 390.7536 -8.859266)
		(end 392.466068 -9.223248)
		(width 0.1143)
		(layer "In9.Cu")
		(net "P3E_CPU0_PE1_PCH_CON_TXP<12>")
	)
	(segment
		(start 327.28281 -66.158364)
		(end 327.351136 -65.822322)
		(width 0.1143)
		(layer "In9.Cu")
		(net "P3E_CPU0_PE1_PCH_CON_TXP<12>")
	)
	(segment
		(start 327.3044 -86.435692)
		(end 327.23328 -86.100412)
		(width 0.1143)
		(layer "In9.Cu")
		(net "P3E_CPU0_PE1_PCH_CON_TXP<12>")
	)
	(segment
		(start 327.492868 -64.296036)
		(end 327.990454 -63.543942)
		(width 0.1143)
		(layer "In9.Cu")
		(net "P3E_CPU0_PE1_PCH_CON_TXP<12>")
	)
	(segment
		(start 326.63892 -83.263994)
		(end 326.866758 -82.332068)
		(width 0.1143)
		(layer "In9.Cu")
		(net "P3E_CPU0_PE1_PCH_CON_TXP<12>")
	)
	(segment
		(start 328.623676 -93.44406)
		(end 328.552556 -93.10878)
		(width 0.1143)
		(layer "In9.Cu")
		(net "P3E_CPU0_PE1_PCH_CON_TXP<12>")
	)
	(segment
		(start 326.688196 -105.850182)
		(end 328.88936 -101.849428)
		(width 0.1143)
		(layer "In9.Cu")
		(net "P3E_CPU0_PE1_PCH_CON_TXP<12>")
	)
	(segment
		(start 328.341482 -92.114878)
		(end 328.468736 -91.919044)
		(width 0.1143)
		(layer "In9.Cu")
		(net "P3E_CPU0_PE1_PCH_CON_TXP<12>")
	)
	(segment
		(start 326.387714 -74.562716)
		(end 326.38746 -74.5617)
		(width 0.1143)
		(layer "In9.Cu")
		(net "P3E_CPU0_PE1_PCH_CON_TXP<12>")
	)
	(segment
		(start 429.875442 -6.395466)
		(end 431.420016 -6.067552)
		(width 0.1143)
		(layer "In9.Cu")
		(net "P3E_CPU0_PE1_PCH_CON_TXP<12>")
	)
	(segment
		(start 326.389238 -74.570082)
		(end 326.38873 -74.567288)
		(width 0.1143)
		(layer "In9.Cu")
		(net "P3E_CPU0_PE1_PCH_CON_TXP<12>")
	)
	(segment
		(start 326.380348 -74.528934)
		(end 326.378824 -74.52614)
		(width 0.1143)
		(layer "In9.Cu")
		(net "P3E_CPU0_PE1_PCH_CON_TXP<12>")
	)
	(segment
		(start 317.786004 -115.092988)
		(end 318.739012 -113.194084)
		(width 0.1143)
		(layer "In9.Cu")
		(net "P3E_CPU0_PE1_PCH_CON_TXP<12>")
	)
	(segment
		(start 326.63892 -76.303124)
		(end 326.647048 -76.265024)
		(width 0.1143)
		(layer "In9.Cu")
		(net "P3E_CPU0_PE1_PCH_CON_TXP<12>")
	)
	(segment
		(start 326.696832 -76.019914)
		(end 326.696578 -76.018644)
		(width 0.1143)
		(layer "In9.Cu")
		(net "P3E_CPU0_PE1_PCH_CON_TXP<12>")
	)
	(segment
		(start 422.715182 -6.39191)
		(end 423.892726 -6.14172)
		(width 0.1143)
		(layer "In9.Cu")
		(net "P3E_CPU0_PE1_PCH_CON_TXP<12>")
	)
	(segment
		(start 328.88936 -101.849428)
		(end 329.165458 -98.221038)
		(width 0.1143)
		(layer "In9.Cu")
		(net "P3E_CPU0_PE1_PCH_CON_TXP<12>")
	)
	(segment
		(start 388.76605 -9.281414)
		(end 388.96163 -9.408668)
		(width 0.1143)
		(layer "In9.Cu")
		(net "P3E_CPU0_PE1_PCH_CON_TXP<12>")
	)
	(segment
		(start 318.468756 -117.215412)
		(end 317.786004 -115.092988)
		(width 0.1143)
		(layer "In9.Cu")
		(net "P3E_CPU0_PE1_PCH_CON_TXP<12>")
	)
	(segment
		(start 326.38873 -77.48143)
		(end 326.4662 -77.114654)
		(width 0.1143)
		(layer "In9.Cu")
		(net "P3E_CPU0_PE1_PCH_CON_TXP<12>")
	)
	(segment
		(start 328.397616 -91.58351)
		(end 328.201782 -91.45651)
		(width 0.1143)
		(layer "In9.Cu")
		(net "P3E_CPU0_PE1_PCH_CON_TXP<12>")
	)
	(segment
		(start 327.222104 -65.627758)
		(end 327.29043 -65.291716)
		(width 0.1143)
		(layer "In9.Cu")
		(net "P3E_CPU0_PE1_PCH_CON_TXP<12>")
	)
	(segment
		(start 326.63892 -73.301606)
		(end 326.931782 -71.92264)
		(width 0.1143)
		(layer "In9.Cu")
		(net "P3E_CPU0_PE1_PCH_CON_TXP<12>")
	)
	(segment
		(start 326.38746 -74.5617)
		(end 326.380348 -74.528934)
		(width 0.1143)
		(layer "In9.Cu")
		(net "P3E_CPU0_PE1_PCH_CON_TXP<12>")
	)
	(segment
		(start 318.468502 -117.215412)
		(end 318.468756 -117.215412)
		(width 0.1143)
		(layer "In9.Cu")
		(net "P3E_CPU0_PE1_PCH_CON_TXP<12>")
	)
	(segment
		(start 425.029376 -6.383274)
		(end 426.343064 -6.104382)
		(width 0.1143)
		(layer "In9.Cu")
		(net "P3E_CPU0_PE1_PCH_CON_TXP<12>")
	)
	(segment
		(start 420.310056 -6.384544)
		(end 421.494966 -6.132576)
		(width 0.1143)
		(layer "In9.Cu")
		(net "P3E_CPU0_PE1_PCH_CON_TXP<12>")
	)
	(segment
		(start 423.892726 -6.14172)
		(end 425.029376 -6.383274)
		(width 0.1143)
		(layer "In9.Cu")
		(net "P3E_CPU0_PE1_PCH_CON_TXP<12>")
	)
	(segment
		(start 441.4901 -9.8425)
		(end 441.2742 -10.0584)
		(width 0.1143)
		(layer "In9.Cu")
		(net "P3E_CPU0_PE1_PCH_CON_TXP<12>")
	)
	(segment
		(start 363.424216 -29.172916)
		(end 363.982508 -26.382472)
		(width 0.1143)
		(layer "In9.Cu")
		(net "P3E_CPU0_PE1_PCH_CON_TXP<12>")
	)
	(segment
		(start 328.598022 -95.55226)
		(end 328.83475 -94.437962)
		(width 0.1143)
		(layer "In9.Cu")
		(net "P3E_CPU0_PE1_PCH_CON_TXP<12>")
	)
	(segment
		(start 358.220264 -44.14012)
		(end 359.07345 -42.531284)
		(width 0.1143)
		(layer "In9.Cu")
		(net "P3E_CPU0_PE1_PCH_CON_TXP<12>")
	)
	(segment
		(start 335.948274 -49.516792)
		(end 338.326984 -49.033176)
		(width 0.1143)
		(layer "In9.Cu")
		(net "P3E_CPU0_PE1_PCH_CON_TXP<12>")
	)
	(segment
		(start 327.162414 -81.123028)
		(end 326.415908 -77.608938)
		(width 0.1143)
		(layer "In9.Cu")
		(net "P3E_CPU0_PE1_PCH_CON_TXP<12>")
	)
	(segment
		(start 328.608436 -92.577412)
		(end 328.412856 -92.450158)
		(width 0.1143)
		(layer "In9.Cu")
		(net "P3E_CPU0_PE1_PCH_CON_TXP<12>")
	)
	(segment
		(start 328.76363 -94.102428)
		(end 328.89063 -93.906848)
		(width 0.1143)
		(layer "In9.Cu")
		(net "P3E_CPU0_PE1_PCH_CON_TXP<12>")
	)
	(segment
		(start 367.277904 -18.041112)
		(end 369.304824 -14.259306)
		(width 0.1143)
		(layer "In9.Cu")
		(net "P3E_CPU0_PE1_PCH_CON_TXP<12>")
	)
	(segment
		(start 328.130662 -91.120976)
		(end 328.257662 -90.925142)
		(width 0.1143)
		(layer "In9.Cu")
		(net "P3E_CPU0_PE1_PCH_CON_TXP<12>")
	)
	(segment
		(start 327.037446 -85.973158)
		(end 326.63892 -84.093812)
		(width 0.1143)
		(layer "In9.Cu")
		(net "P3E_CPU0_PE1_PCH_CON_TXP<12>")
	)
	(segment
		(start 327.351136 -65.822322)
		(end 327.222104 -65.627758)
		(width 0.1143)
		(layer "In9.Cu")
		(net "P3E_CPU0_PE1_PCH_CON_TXP<12>")
	)
	(segment
		(start 328.386948 -57.176924)
		(end 329.959462 -52.991004)
		(width 0.1143)
		(layer "In9.Cu")
		(net "P3E_CPU0_PE1_PCH_CON_TXP<12>")
	)
	(segment
		(start 426.343064 -6.104382)
		(end 427.61281 -6.37413)
		(width 0.1143)
		(layer "In9.Cu")
		(net "P3E_CPU0_PE1_PCH_CON_TXP<12>")
	)
	(segment
		(start 327.424542 -64.632078)
		(end 327.492868 -64.296036)
		(width 0.1143)
		(layer "In9.Cu")
		(net "P3E_CPU0_PE1_PCH_CON_TXP<12>")
	)
	(segment
		(start 404.20671 -5.262626)
		(end 404.84425 -5.392674)
		(width 0.1143)
		(layer "In9.Cu")
		(net "P3E_CPU0_PE1_PCH_CON_TXP<12>")
	)
	(segment
		(start 356.459028 -45.294296)
		(end 358.220264 -44.14012)
		(width 0.1143)
		(layer "In9.Cu")
		(net "P3E_CPU0_PE1_PCH_CON_TXP<12>")
	)
	(segment
		(start 326.63892 -75.74661)
		(end 326.576944 -75.454256)
		(width 0.1143)
		(layer "In9.Cu")
		(net "P3E_CPU0_PE1_PCH_CON_TXP<12>")
	)
	(segment
		(start 326.388984 -77.482446)
		(end 326.38873 -77.48143)
		(width 0.1143)
		(layer "In9.Cu")
		(net "P3E_CPU0_PE1_PCH_CON_TXP<12>")
	)
	(segment
		(start 326.68464 -76.09713)
		(end 326.697848 -76.034646)
		(width 0.1143)
		(layer "In9.Cu")
		(net "P3E_CPU0_PE1_PCH_CON_TXP<12>")
	)
	(segment
		(start 408.47518 -5.762244)
		(end 410.11475 -5.414518)
		(width 0.1143)
		(layer "In9.Cu")
		(net "P3E_CPU0_PE1_PCH_CON_TXP<12>")
	)
	(segment
		(start 419.12032 -6.13156)
		(end 420.310056 -6.384544)
		(width 0.1143)
		(layer "In9.Cu")
		(net "P3E_CPU0_PE1_PCH_CON_TXP<12>")
	)
	(segment
		(start 318.1096 -119.373142)
		(end 318.1096 -118.514368)
		(width 0.1143)
		(layer "In9.Cu")
		(net "P3E_CPU0_PE1_PCH_CON_TXP<12>")
	)
	(segment
		(start 363.982508 -26.382472)
		(end 365.738664 -25.210008)
		(width 0.1143)
		(layer "In9.Cu")
		(net "P3E_CPU0_PE1_PCH_CON_TXP<12>")
	)
	(segment
		(start 431.420016 -6.067552)
		(end 432.477164 -6.376162)
		(width 0.1143)
		(layer "In9.Cu")
		(net "P3E_CPU0_PE1_PCH_CON_TXP<12>")
	)
	(segment
		(start 327.087992 -66.287396)
		(end 327.28281 -66.158364)
		(width 0.1143)
		(layer "In9.Cu")
		(net "P3E_CPU0_PE1_PCH_CON_TXP<12>")
	)
	(segment
		(start 327.444354 -87.094314)
		(end 327.24852 -86.96706)
		(width 0.1143)
		(layer "In9.Cu")
		(net "P3E_CPU0_PE1_PCH_CON_TXP<12>")
	)
	(segment
		(start 328.89063 -93.906848)
		(end 328.81951 -93.571314)
		(width 0.1143)
		(layer "In9.Cu")
		(net "P3E_CPU0_PE1_PCH_CON_TXP<12>")
	)
	(segment
		(start 441.4901 -9.105392)
		(end 441.4901 -9.8425)
		(width 0.1143)
		(layer "In9.Cu")
		(net "P3E_CPU0_PE1_PCH_CON_TXP<12>")
	)
	(segment
		(start 389.759698 -9.07034)
		(end 389.955532 -9.197594)
		(width 0.1143)
		(layer "In9.Cu")
		(net "P3E_CPU0_PE1_PCH_CON_TXP<12>")
	)
	(segment
		(start 327.990708 -90.462608)
		(end 327.38822 -87.625428)
		(width 0.1143)
		(layer "In9.Cu")
		(net "P3E_CPU0_PE1_PCH_CON_TXP<12>")
	)
	(segment
		(start 428.693834 -6.14426)
		(end 429.875442 -6.395466)
		(width 0.1143)
		(layer "In9.Cu")
		(net "P3E_CPU0_PE1_PCH_CON_TXP<12>")
	)
	(segment
		(start 326.866758 -82.332068)
		(end 327.162414 -81.123028)
		(width 0.1143)
		(layer "In9.Cu")
		(net "P3E_CPU0_PE1_PCH_CON_TXP<12>")
	)
	(segment
		(start 389.297164 -9.337294)
		(end 389.424418 -9.14146)
		(width 0.1143)
		(layer "In9.Cu")
		(net "P3E_CPU0_PE1_PCH_CON_TXP<12>")
	)
	(segment
		(start 327.23328 -86.100412)
		(end 327.037446 -85.973158)
		(width 0.1143)
		(layer "In9.Cu")
		(net "P3E_CPU0_PE1_PCH_CON_TXP<12>")
	)
	(segment
		(start 417.172902 -6.216142)
		(end 417.947856 -6.38048)
		(width 0.1143)
		(layer "In9.Cu")
		(net "P3E_CPU0_PE1_PCH_CON_TXP<12>")
	)
	(segment
		(start 328.67981 -92.912946)
		(end 328.608436 -92.577412)
		(width 0.1143)
		(layer "In9.Cu")
		(net "P3E_CPU0_PE1_PCH_CON_TXP<12>")
	)
	(segment
		(start 326.649842 -76.260198)
		(end 326.650096 -76.259182)
		(width 0.1143)
		(layer "In9.Cu")
		(net "P3E_CPU0_PE1_PCH_CON_TXP<12>")
	)
	(segment
		(start 326.388984 -77.489558)
		(end 326.389492 -77.487272)
		(width 0.1143)
		(layer "In9.Cu")
		(net "P3E_CPU0_PE1_PCH_CON_TXP<12>")
	)
	(segment
		(start 421.494966 -6.132576)
		(end 422.715182 -6.39191)
		(width 0.1143)
		(layer "In9.Cu")
		(net "P3E_CPU0_PE1_PCH_CON_TXP<12>")
	)
	(segment
		(start 327.515474 -87.429594)
		(end 327.444354 -87.094314)
		(width 0.1143)
		(layer "In9.Cu")
		(net "P3E_CPU0_PE1_PCH_CON_TXP<12>")
	)
	(segment
		(start 340.70417 -49.517046)
		(end 356.459028 -45.294296)
		(width 0.1143)
		(layer "In9.Cu")
		(net "P3E_CPU0_PE1_PCH_CON_TXP<12>")
	)
	(segment
		(start 371.441726 -12.584684)
		(end 379.47092 -10.879328)
		(width 0.1143)
		(layer "In9.Cu")
		(net "P3E_CPU0_PE1_PCH_CON_TXP<12>")
	)
	(segment
		(start 365.738664 -25.210008)
		(end 367.277904 -18.041112)
		(width 0.1143)
		(layer "In9.Cu")
		(net "P3E_CPU0_PE1_PCH_CON_TXP<12>")
	)
	(segment
		(start 326.544686 -83.649312)
		(end 326.63892 -83.263994)
		(width 0.1143)
		(layer "In9.Cu")
		(net "P3E_CPU0_PE1_PCH_CON_TXP<12>")
	)
	(segment
		(start 326.696578 -76.018644)
		(end 326.63892 -75.74661)
		(width 0.1143)
		(layer "In9.Cu")
		(net "P3E_CPU0_PE1_PCH_CON_TXP<12>")
	)
	(segment
		(start 326.63892 -105.895648)
		(end 326.688196 -105.850182)
		(width 0.1143)
		(layer "In9.Cu")
		(net "P3E_CPU0_PE1_PCH_CON_TXP<12>")
	)
	(segment
		(start 318.739012 -113.194084)
		(end 326.63892 -105.895648)
		(width 0.1143)
		(layer "In9.Cu")
		(net "P3E_CPU0_PE1_PCH_CON_TXP<12>")
	)
	(segment
		(start 327.553574 -64.826642)
		(end 327.424542 -64.632078)
		(width 0.1143)
		(layer "In9.Cu")
		(net "P3E_CPU0_PE1_PCH_CON_TXP<12>")
	)
	(segment
		(start 380.355602 -11.067288)
		(end 388.76605 -9.281414)
		(width 0.1143)
		(layer "In9.Cu")
		(net "P3E_CPU0_PE1_PCH_CON_TXP<12>")
	)
	(segment
		(start 329.165458 -98.221038)
		(end 328.598022 -95.55226)
		(width 0.1143)
		(layer "In9.Cu")
		(net "P3E_CPU0_PE1_PCH_CON_TXP<12>")
	)
	(segment
		(start 427.61281 -6.37413)
		(end 428.693834 -6.14426)
		(width 0.1143)
		(layer "In9.Cu")
		(net "P3E_CPU0_PE1_PCH_CON_TXP<12>")
	)
	(segment
		(start 395.084554 -8.666988)
		(end 404.20671 -5.262626)
		(width 0.1143)
		(layer "In9.Cu")
		(net "P3E_CPU0_PE1_PCH_CON_TXP<12>")
	)
	(segment
		(start 360.524806 -35.48126)
		(end 363.290866 -32.073342)
		(width 0.1143)
		(layer "In9.Cu")
		(net "P3E_CPU0_PE1_PCH_CON_TXP<12>")
	)
	(segment
		(start 326.697848 -76.034646)
		(end 326.698864 -76.029566)
		(width 0.1143)
		(layer "In9.Cu")
		(net "P3E_CPU0_PE1_PCH_CON_TXP<12>")
	)
	(segment
		(start 318.491108 -119.75465)
		(end 318.1096 -119.373142)
		(width 0.1143)
		(layer "In9.Cu")
		(net "P3E_CPU0_PE1_PCH_CON_TXP<12>")
	)
	(segment
		(start 415.529522 -6.565138)
		(end 417.172902 -6.216142)
		(width 0.1143)
		(layer "In9.Cu")
		(net "P3E_CPU0_PE1_PCH_CON_TXP<12>")
	)
	(segment
		(start 359.07345 -42.531284)
		(end 360.524806 -35.48126)
		(width 0.1143)
		(layer "In9.Cu")
		(net "P3E_CPU0_PE1_PCH_CON_TXP<12>")
	)
	(segment
		(start 389.955532 -9.197594)
		(end 390.291066 -9.12622)
		(width 0.1143)
		(layer "In9.Cu")
		(net "P3E_CPU0_PE1_PCH_CON_TXP<12>")
	)
	(segment
		(start 326.426322 -69.54266)
		(end 327.087992 -66.287396)
		(width 0.1143)
		(layer "In9.Cu")
		(net "P3E_CPU0_PE1_PCH_CON_TXP<12>")
	)
	(segment
		(start 410.11475 -5.414518)
		(end 415.529522 -6.565138)
		(width 0.1143)
		(layer "In9.Cu")
		(net "P3E_CPU0_PE1_PCH_CON_TXP<12>")
	)
	(segment
		(start 327.24852 -86.96706)
		(end 327.177146 -86.631526)
		(width 0.1143)
		(layer "In9.Cu")
		(net "P3E_CPU0_PE1_PCH_CON_TXP<12>")
	)
	(segment
		(start 392.466068 -9.223248)
		(end 395.084554 -8.666988)
		(width 0.1143)
		(layer "In9.Cu")
		(net "P3E_CPU0_PE1_PCH_CON_TXP<12>")
	)
	(segment
		(start 327.990454 -63.543942)
		(end 328.81697 -59.327034)
		(width 0.1143)
		(layer "In9.Cu")
		(net "P3E_CPU0_PE1_PCH_CON_TXP<12>")
	)
	(segment
		(start 432.477164 -6.376162)
		(end 433.477924 -6.163056)
		(width 0.1143)
		(layer "In9.Cu")
		(net "P3E_CPU0_PE1_PCH_CON_TXP<12>")
	)
	(segment
		(start 328.257662 -90.925142)
		(end 328.186542 -90.589862)
		(width 0.1143)
		(layer "In9.Cu")
		(net "P3E_CPU0_PE1_PCH_CON_TXP<12>")
	)
	(segment
		(start 319.30467 -119.75465)
		(end 318.491108 -119.75465)
		(width 0.1143)
		(layer "In9.Cu")
		(net "P3E_CPU0_PE1_PCH_CON_TXP<12>")
	)
	(segment
		(start 338.326984 -49.033176)
		(end 340.70417 -49.517046)
		(width 0.1143)
		(layer "In9.Cu")
		(net "P3E_CPU0_PE1_PCH_CON_TXP<12>")
	)
	(segment
		(start 441.247022 -8.862314)
		(end 441.4901 -9.105392)
		(width 0.1143)
		(layer "In9.Cu")
		(net "P3E_CPU0_PE1_PCH_CON_TXP<12>")
	)
	(segment
		(start 334.330294 -49.845722)
		(end 335.948274 -49.516792)
		(width 0.1143)
		(layer "In9.Cu")
		(net "P3E_CPU0_PE1_PCH_CON_TXP<12>")
	)
	(segment
		(start 328.412856 -92.450158)
		(end 328.341482 -92.114878)
		(width 0.1143)
		(layer "In9.Cu")
		(net "P3E_CPU0_PE1_PCH_CON_TXP<12>")
	)
	(segment
		(start 328.186542 -90.589862)
		(end 327.990708 -90.462608)
		(width 0.1143)
		(layer "In9.Cu")
		(net "P3E_CPU0_PE1_PCH_CON_TXP<12>")
	)
	(segment
		(start 326.412606 -77.603858)
		(end 326.38873 -77.490574)
		(width 0.1143)
		(layer "In9.Cu")
		(net "P3E_CPU0_PE1_PCH_CON_TXP<12>")
	)
	(segment
		(start 330.11491 -52.879244)
		(end 334.329786 -49.84623)
		(width 0.1143)
		(layer "In9.Cu")
		(net "P3E_CPU0_PE1_PCH_CON_TXP<12>")
	)
	(segment
		(start 328.81951 -93.571314)
		(end 328.623676 -93.44406)
		(width 0.1143)
		(layer "In9.Cu")
		(net "P3E_CPU0_PE1_PCH_CON_TXP<12>")
	)
	(segment
		(start 326.389492 -77.484732)
		(end 326.388984 -77.482446)
		(width 0.1143)
		(layer "In9.Cu")
		(net "P3E_CPU0_PE1_PCH_CON_TXP<12>")
	)
	(segment
		(start 326.650096 -76.259182)
		(end 326.65035 -76.258674)
		(width 0.1143)
		(layer "In9.Cu")
		(net "P3E_CPU0_PE1_PCH_CON_TXP<12>")
	)
	(segment
		(start 326.415908 -77.608938)
		(end 326.412606 -77.603858)
		(width 0.1143)
		(layer "In9.Cu")
		(net "P3E_CPU0_PE1_PCH_CON_TXP<12>")
	)
	(segment
		(start 326.567038 -75.407266)
		(end 326.4662 -74.932794)
		(width 0.1143)
		(layer "In9.Cu")
		(net "P3E_CPU0_PE1_PCH_CON_TXP<12>")
	)
	(segment
		(start 369.304824 -14.259306)
		(end 371.441726 -12.584684)
		(width 0.1143)
		(layer "In9.Cu")
		(net "P3E_CPU0_PE1_PCH_CON_TXP<12>")
	)
	(segment
		(start 327.29043 -65.291716)
		(end 327.485248 -65.162684)
		(width 0.1143)
		(layer "In9.Cu")
		(net "P3E_CPU0_PE1_PCH_CON_TXP<12>")
	)
	(segment
		(start 328.81697 -59.327034)
		(end 328.386948 -57.176924)
		(width 0.1143)
		(layer "In9.Cu")
		(net "P3E_CPU0_PE1_PCH_CON_TXP<12>")
	)
	(segment
		(start 388.96163 -9.408668)
		(end 389.297164 -9.337294)
		(width 0.1143)
		(layer "In9.Cu")
		(net "P3E_CPU0_PE1_PCH_CON_TXP<12>")
	)
	(segment
		(start 326.65035 -76.258674)
		(end 326.68464 -76.09713)
		(width 0.1143)
		(layer "In9.Cu")
		(net "P3E_CPU0_PE1_PCH_CON_TXP<12>")
	)
	(segment
		(start 439.117232 -8.898382)
		(end 438.876186 -8.657336)
		(width 0.1143)
		(layer "F.Cu")
		(net "P3E_CPU0_PE1_PCH_CON_TXP<11>")
	)
	(segment
		(start 438.755282 -10.02411)
		(end 438.98947 -10.02411)
		(width 0.1143)
		(layer "F.Cu")
		(net "P3E_CPU0_PE1_PCH_CON_TXP<11>")
	)
	(segment
		(start 438.98947 -10.02411)
		(end 439.117232 -9.896348)
		(width 0.1143)
		(layer "F.Cu")
		(net "P3E_CPU0_PE1_PCH_CON_TXP<11>")
	)
	(segment
		(start 438.876186 -8.657336)
		(end 438.876186 -7.789672)
		(width 0.1143)
		(layer "F.Cu")
		(net "P3E_CPU0_PE1_PCH_CON_TXP<11>")
	)
	(segment
		(start 320.8528 -118.415816)
		(end 322.1355 -118.415816)
		(width 0.1143)
		(layer "F.Cu")
		(net "P3E_CPU0_PE1_PCH_CON_TXP<11>")
	)
	(segment
		(start 320.7766 -118.492016)
		(end 320.8528 -118.415816)
		(width 0.1143)
		(layer "F.Cu")
		(net "P3E_CPU0_PE1_PCH_CON_TXP<11>")
	)
	(segment
		(start 439.117232 -9.896348)
		(end 439.117232 -8.898382)
		(width 0.1143)
		(layer "F.Cu")
		(net "P3E_CPU0_PE1_PCH_CON_TXP<11>")
	)
	(via
		(at 320.7766 -118.492016)
		(size 0.508)
		(drill 0.254)
		(layers "F.Cu" "B.Cu")
		(net "P3E_CPU0_PE1_PCH_CON_TXP<11>")
	)
	(via
		(at 438.755282 -10.02411)
		(size 0.508)
		(drill 0.254)
		(layers "F.Cu" "B.Cu")
		(net "P3E_CPU0_PE1_PCH_CON_TXP<11>")
	)
	(segment
		(start 330.430886 -55.287672)
		(end 330.013818 -55.061612)
		(width 0.1143)
		(layer "In9.Cu")
		(net "P3E_CPU0_PE1_PCH_CON_TXP<11>")
	)
	(segment
		(start 321.661536 -116.45392)
		(end 321.547236 -116.33962)
		(width 0.1143)
		(layer "In9.Cu")
		(net "P3E_CPU0_PE1_PCH_CON_TXP<11>")
	)
	(segment
		(start 410.43987 -6.14553)
		(end 415.509456 -7.221982)
		(width 0.1143)
		(layer "In9.Cu")
		(net "P3E_CPU0_PE1_PCH_CON_TXP<11>")
	)
	(segment
		(start 321.547236 -114.49812)
		(end 321.661536 -114.38382)
		(width 0.1143)
		(layer "In9.Cu")
		(net "P3E_CPU0_PE1_PCH_CON_TXP<11>")
	)
	(segment
		(start 327.031096 -74.523092)
		(end 327.583546 -71.92264)
		(width 0.1143)
		(layer "In9.Cu")
		(net "P3E_CPU0_PE1_PCH_CON_TXP<11>")
	)
	(segment
		(start 331.437234 -53.419248)
		(end 331.823822 -53.304948)
		(width 0.1143)
		(layer "In9.Cu")
		(net "P3E_CPU0_PE1_PCH_CON_TXP<11>")
	)
	(segment
		(start 427.609 -7.0358)
		(end 428.690024 -6.80593)
		(width 0.1143)
		(layer "In9.Cu")
		(net "P3E_CPU0_PE1_PCH_CON_TXP<11>")
	)
	(segment
		(start 331.167994 -53.837078)
		(end 330.945744 -53.716682)
		(width 0.1143)
		(layer "In9.Cu")
		(net "P3E_CPU0_PE1_PCH_CON_TXP<11>")
	)
	(segment
		(start 428.690024 -6.80593)
		(end 429.883824 -7.059422)
		(width 0.1143)
		(layer "In9.Cu")
		(net "P3E_CPU0_PE1_PCH_CON_TXP<11>")
	)
	(segment
		(start 399.28927 -7.966202)
		(end 399.386044 -7.753858)
		(width 0.1143)
		(layer "In9.Cu")
		(net "P3E_CPU0_PE1_PCH_CON_TXP<11>")
	)
	(segment
		(start 330.095098 -54.671976)
		(end 330.249784 -54.626002)
		(width 0.1143)
		(layer "In9.Cu")
		(net "P3E_CPU0_PE1_PCH_CON_TXP<11>")
	)
	(segment
		(start 322.91274 -110.21568)
		(end 327.330816 -106.134154)
		(width 0.1143)
		(layer "In9.Cu")
		(net "P3E_CPU0_PE1_PCH_CON_TXP<11>")
	)
	(segment
		(start 322.50253 -112.523778)
		(end 322.50253 -111.032798)
		(width 0.1143)
		(layer "In9.Cu")
		(net "P3E_CPU0_PE1_PCH_CON_TXP<11>")
	)
	(segment
		(start 330.651612 -54.84368)
		(end 331.055218 -54.723538)
		(width 0.1143)
		(layer "In9.Cu")
		(net "P3E_CPU0_PE1_PCH_CON_TXP<11>")
	)
	(segment
		(start 322.217288 -113.30432)
		(end 321.661536 -113.30432)
		(width 0.1143)
		(layer "In9.Cu")
		(net "P3E_CPU0_PE1_PCH_CON_TXP<11>")
	)
	(segment
		(start 321.661536 -114.38382)
		(end 322.217288 -114.38382)
		(width 0.1143)
		(layer "In9.Cu")
		(net "P3E_CPU0_PE1_PCH_CON_TXP<11>")
	)
	(segment
		(start 334.611472 -50.475388)
		(end 338.32546 -49.719738)
		(width 0.1143)
		(layer "In9.Cu")
		(net "P3E_CPU0_PE1_PCH_CON_TXP<11>")
	)
	(segment
		(start 331.29855 -54.27472)
		(end 331.167994 -53.837078)
		(width 0.1143)
		(layer "In9.Cu")
		(net "P3E_CPU0_PE1_PCH_CON_TXP<11>")
	)
	(segment
		(start 397.558768 -8.435848)
		(end 397.80337 -8.344408)
		(width 0.1143)
		(layer "In9.Cu")
		(net "P3E_CPU0_PE1_PCH_CON_TXP<11>")
	)
	(segment
		(start 321.547236 -116.33962)
		(end 321.547236 -116.07292)
		(width 0.1143)
		(layer "In9.Cu")
		(net "P3E_CPU0_PE1_PCH_CON_TXP<11>")
	)
	(segment
		(start 400.659092 -7.278624)
		(end 400.871436 -7.375398)
		(width 0.1143)
		(layer "In9.Cu")
		(net "P3E_CPU0_PE1_PCH_CON_TXP<11>")
	)
	(segment
		(start 420.28745 -7.041896)
		(end 421.47236 -6.789928)
		(width 0.1143)
		(layer "In9.Cu")
		(net "P3E_CPU0_PE1_PCH_CON_TXP<11>")
	)
	(segment
		(start 398.755362 -7.989316)
		(end 398.96796 -8.08609)
		(width 0.1143)
		(layer "In9.Cu")
		(net "P3E_CPU0_PE1_PCH_CON_TXP<11>")
	)
	(segment
		(start 331.09154 -53.231796)
		(end 331.437234 -53.419248)
		(width 0.1143)
		(layer "In9.Cu")
		(net "P3E_CPU0_PE1_PCH_CON_TXP<11>")
	)
	(segment
		(start 330.344018 -54.676802)
		(end 330.651612 -54.84368)
		(width 0.1143)
		(layer "In9.Cu")
		(net "P3E_CPU0_PE1_PCH_CON_TXP<11>")
	)
	(segment
		(start 419.121336 -6.793992)
		(end 420.28745 -7.041896)
		(width 0.1143)
		(layer "In9.Cu")
		(net "P3E_CPU0_PE1_PCH_CON_TXP<11>")
	)
	(segment
		(start 398.337024 -8.321548)
		(end 398.434052 -8.109204)
		(width 0.1143)
		(layer "In9.Cu")
		(net "P3E_CPU0_PE1_PCH_CON_TXP<11>")
	)
	(segment
		(start 327.349612 -76.024232)
		(end 327.031096 -74.523092)
		(width 0.1143)
		(layer "In9.Cu")
		(net "P3E_CPU0_PE1_PCH_CON_TXP<11>")
	)
	(segment
		(start 330.249784 -54.626002)
		(end 330.344018 -54.677056)
		(width 0.1143)
		(layer "In9.Cu")
		(net "P3E_CPU0_PE1_PCH_CON_TXP<11>")
	)
	(segment
		(start 322.50253 -115.164362)
		(end 322.217288 -114.87912)
		(width 0.1143)
		(layer "In9.Cu")
		(net "P3E_CPU0_PE1_PCH_CON_TXP<11>")
	)
	(segment
		(start 338.32546 -49.719738)
		(end 340.66861 -50.196496)
		(width 0.1143)
		(layer "In9.Cu")
		(net "P3E_CPU0_PE1_PCH_CON_TXP<11>")
	)
	(segment
		(start 429.883824 -7.059422)
		(end 431.401982 -6.737096)
		(width 0.1143)
		(layer "In9.Cu")
		(net "P3E_CPU0_PE1_PCH_CON_TXP<11>")
	)
	(segment
		(start 367.878614 -18.367756)
		(end 369.884706 -14.624812)
		(width 0.1143)
		(layer "In9.Cu")
		(net "P3E_CPU0_PE1_PCH_CON_TXP<11>")
	)
	(segment
		(start 321.661536 -112.80902)
		(end 322.217288 -112.80902)
		(width 0.1143)
		(layer "In9.Cu")
		(net "P3E_CPU0_PE1_PCH_CON_TXP<11>")
	)
	(segment
		(start 399.707354 -7.63397)
		(end 399.919698 -7.730744)
		(width 0.1143)
		(layer "In9.Cu")
		(net "P3E_CPU0_PE1_PCH_CON_TXP<11>")
	)
	(segment
		(start 330.722986 -53.595778)
		(end 330.677012 -53.441092)
		(width 0.1143)
		(layer "In9.Cu")
		(net "P3E_CPU0_PE1_PCH_CON_TXP<11>")
	)
	(segment
		(start 321.860926 -118.043198)
		(end 322.50253 -117.401594)
		(width 0.1143)
		(layer "In9.Cu")
		(net "P3E_CPU0_PE1_PCH_CON_TXP<11>")
	)
	(segment
		(start 329.319636 -57.100978)
		(end 329.682602 -57.174892)
		(width 0.1143)
		(layer "In9.Cu")
		(net "P3E_CPU0_PE1_PCH_CON_TXP<11>")
	)
	(segment
		(start 329.530964 -102.135432)
		(end 329.825604 -98.260662)
		(width 0.1143)
		(layer "In9.Cu")
		(net "P3E_CPU0_PE1_PCH_CON_TXP<11>")
	)
	(segment
		(start 321.547236 -113.19002)
		(end 321.547236 -112.92332)
		(width 0.1143)
		(layer "In9.Cu")
		(net "P3E_CPU0_PE1_PCH_CON_TXP<11>")
	)
	(segment
		(start 431.401982 -6.737096)
		(end 432.445668 -7.041896)
		(width 0.1143)
		(layer "In9.Cu")
		(net "P3E_CPU0_PE1_PCH_CON_TXP<11>")
	)
	(segment
		(start 332.556104 -51.953668)
		(end 332.556358 -51.953414)
		(width 0.1143)
		(layer "In9.Cu")
		(net "P3E_CPU0_PE1_PCH_CON_TXP<11>")
	)
	(segment
		(start 330.013818 -55.061612)
		(end 329.967844 -54.906926)
		(width 0.1143)
		(layer "In9.Cu")
		(net "P3E_CPU0_PE1_PCH_CON_TXP<11>")
	)
	(segment
		(start 380.312422 -11.736578)
		(end 387.676644 -10.172954)
		(width 0.1143)
		(layer "In9.Cu")
		(net "P3E_CPU0_PE1_PCH_CON_TXP<11>")
	)
	(segment
		(start 398.015968 -8.441436)
		(end 398.337024 -8.321548)
		(width 0.1143)
		(layer "In9.Cu")
		(net "P3E_CPU0_PE1_PCH_CON_TXP<11>")
	)
	(segment
		(start 330.344018 -54.677056)
		(end 330.344018 -54.676802)
		(width 0.1143)
		(layer "In9.Cu")
		(net "P3E_CPU0_PE1_PCH_CON_TXP<11>")
	)
	(segment
		(start 387.676644 -10.172954)
		(end 391.7061 -11.029442)
		(width 0.1143)
		(layer "In9.Cu")
		(net "P3E_CPU0_PE1_PCH_CON_TXP<11>")
	)
	(segment
		(start 433.424584 -6.83387)
		(end 438.672986 -9.140698)
		(width 0.1143)
		(layer "In9.Cu")
		(net "P3E_CPU0_PE1_PCH_CON_TXP<11>")
	)
	(segment
		(start 322.50253 -115.673378)
		(end 322.50253 -115.164362)
		(width 0.1143)
		(layer "In9.Cu")
		(net "P3E_CPU0_PE1_PCH_CON_TXP<11>")
	)
	(segment
		(start 330.804266 -53.206142)
		(end 330.958952 -53.160168)
		(width 0.1143)
		(layer "In9.Cu")
		(net "P3E_CPU0_PE1_PCH_CON_TXP<11>")
	)
	(segment
		(start 397.80337 -8.344408)
		(end 398.015968 -8.441436)
		(width 0.1143)
		(layer "In9.Cu")
		(net "P3E_CPU0_PE1_PCH_CON_TXP<11>")
	)
	(segment
		(start 321.547236 -114.76482)
		(end 321.547236 -114.49812)
		(width 0.1143)
		(layer "In9.Cu")
		(net "P3E_CPU0_PE1_PCH_CON_TXP<11>")
	)
	(segment
		(start 393.319 -10.686542)
		(end 393.53871 -10.348468)
		(width 0.1143)
		(layer "In9.Cu")
		(net "P3E_CPU0_PE1_PCH_CON_TXP<11>")
	)
	(segment
		(start 329.25766 -95.588328)
		(end 329.583796 -94.053914)
		(width 0.1143)
		(layer "In9.Cu")
		(net "P3E_CPU0_PE1_PCH_CON_TXP<11>")
	)
	(segment
		(start 327.833482 -81.212944)
		(end 327.04024 -77.480668)
		(width 0.1143)
		(layer "In9.Cu")
		(net "P3E_CPU0_PE1_PCH_CON_TXP<11>")
	)
	(segment
		(start 321.661536 -113.30432)
		(end 321.547236 -113.19002)
		(width 0.1143)
		(layer "In9.Cu")
		(net "P3E_CPU0_PE1_PCH_CON_TXP<11>")
	)
	(segment
		(start 398.96796 -8.08609)
		(end 399.28927 -7.966202)
		(width 0.1143)
		(layer "In9.Cu")
		(net "P3E_CPU0_PE1_PCH_CON_TXP<11>")
	)
	(segment
		(start 329.800712 -58.027062)
		(end 329.552808 -57.654444)
		(width 0.1143)
		(layer "In9.Cu")
		(net "P3E_CPU0_PE1_PCH_CON_TXP<11>")
	)
	(segment
		(start 322.50253 -117.401594)
		(end 322.50253 -116.739162)
		(width 0.1143)
		(layer "In9.Cu")
		(net "P3E_CPU0_PE1_PCH_CON_TXP<11>")
	)
	(segment
		(start 417.949126 -7.042912)
		(end 419.121336 -6.793992)
		(width 0.1143)
		(layer "In9.Cu")
		(net "P3E_CPU0_PE1_PCH_CON_TXP<11>")
	)
	(segment
		(start 391.7061 -11.029442)
		(end 393.319 -10.686542)
		(width 0.1143)
		(layer "In9.Cu")
		(net "P3E_CPU0_PE1_PCH_CON_TXP<11>")
	)
	(segment
		(start 401.192746 -7.25551)
		(end 401.28952 -7.043166)
		(width 0.1143)
		(layer "In9.Cu")
		(net "P3E_CPU0_PE1_PCH_CON_TXP<11>")
	)
	(segment
		(start 330.018898 -56.952642)
		(end 330.120752 -56.449722)
		(width 0.1143)
		(layer "In9.Cu")
		(net "P3E_CPU0_PE1_PCH_CON_TXP<11>")
	)
	(segment
		(start 329.967844 -54.906926)
		(end 330.095098 -54.671976)
		(width 0.1143)
		(layer "In9.Cu")
		(net "P3E_CPU0_PE1_PCH_CON_TXP<11>")
	)
	(segment
		(start 432.445668 -7.041896)
		(end 433.424584 -6.83387)
		(width 0.1143)
		(layer "In9.Cu")
		(net "P3E_CPU0_PE1_PCH_CON_TXP<11>")
	)
	(segment
		(start 330.677012 -53.441092)
		(end 330.804266 -53.206142)
		(width 0.1143)
		(layer "In9.Cu")
		(net "P3E_CPU0_PE1_PCH_CON_TXP<11>")
	)
	(segment
		(start 340.66861 -50.196496)
		(end 356.724966 -45.893482)
		(width 0.1143)
		(layer "In9.Cu")
		(net "P3E_CPU0_PE1_PCH_CON_TXP<11>")
	)
	(segment
		(start 359.682288 -42.812716)
		(end 361.106974 -35.888676)
		(width 0.1143)
		(layer "In9.Cu")
		(net "P3E_CPU0_PE1_PCH_CON_TXP<11>")
	)
	(segment
		(start 396.67053 -8.767318)
		(end 397.558768 -8.435848)
		(width 0.1143)
		(layer "In9.Cu")
		(net "P3E_CPU0_PE1_PCH_CON_TXP<11>")
	)
	(segment
		(start 329.220576 -57.586372)
		(end 329.131422 -57.451752)
		(width 0.1143)
		(layer "In9.Cu")
		(net "P3E_CPU0_PE1_PCH_CON_TXP<11>")
	)
	(segment
		(start 330.958952 -53.160168)
		(end 331.09154 -53.23205)
		(width 0.1143)
		(layer "In9.Cu")
		(net "P3E_CPU0_PE1_PCH_CON_TXP<11>")
	)
	(segment
		(start 321.661536 -115.95862)
		(end 322.217288 -115.95862)
		(width 0.1143)
		(layer "In9.Cu")
		(net "P3E_CPU0_PE1_PCH_CON_TXP<11>")
	)
	(segment
		(start 328.518012 -64.331088)
		(end 328.518012 -64.330834)
		(width 0.1143)
		(layer "In9.Cu")
		(net "P3E_CPU0_PE1_PCH_CON_TXP<11>")
	)
	(segment
		(start 320.8909 -118.043198)
		(end 321.860926 -118.043198)
		(width 0.1143)
		(layer "In9.Cu")
		(net "P3E_CPU0_PE1_PCH_CON_TXP<11>")
	)
	(segment
		(start 393.53871 -10.348468)
		(end 393.429236 -9.834372)
		(width 0.1143)
		(layer "In9.Cu")
		(net "P3E_CPU0_PE1_PCH_CON_TXP<11>")
	)
	(segment
		(start 322.217288 -115.95862)
		(end 322.50253 -115.673378)
		(width 0.1143)
		(layer "In9.Cu")
		(net "P3E_CPU0_PE1_PCH_CON_TXP<11>")
	)
	(segment
		(start 356.724966 -45.893482)
		(end 358.751886 -44.566586)
		(width 0.1143)
		(layer "In9.Cu")
		(net "P3E_CPU0_PE1_PCH_CON_TXP<11>")
	)
	(segment
		(start 332.556358 -51.953414)
		(end 333.583788 -51.214528)
		(width 0.1143)
		(layer "In9.Cu")
		(net "P3E_CPU0_PE1_PCH_CON_TXP<11>")
	)
	(segment
		(start 322.217288 -114.87912)
		(end 321.661536 -114.87912)
		(width 0.1143)
		(layer "In9.Cu")
		(net "P3E_CPU0_PE1_PCH_CON_TXP<11>")
	)
	(segment
		(start 322.50253 -111.032798)
		(end 322.91274 -110.21568)
		(width 0.1143)
		(layer "In9.Cu")
		(net "P3E_CPU0_PE1_PCH_CON_TXP<11>")
	)
	(segment
		(start 329.552808 -57.654444)
		(end 329.220576 -57.586372)
		(width 0.1143)
		(layer "In9.Cu")
		(net "P3E_CPU0_PE1_PCH_CON_TXP<11>")
	)
	(segment
		(start 333.583788 -51.214528)
		(end 333.584042 -51.214528)
		(width 0.1143)
		(layer "In9.Cu")
		(net "P3E_CPU0_PE1_PCH_CON_TXP<11>")
	)
	(segment
		(start 361.106974 -35.888676)
		(end 363.9185 -32.424116)
		(width 0.1143)
		(layer "In9.Cu")
		(net "P3E_CPU0_PE1_PCH_CON_TXP<11>")
	)
	(segment
		(start 395.480286 -10.227056)
		(end 396.67053 -8.767318)
		(width 0.1143)
		(layer "In9.Cu")
		(net "P3E_CPU0_PE1_PCH_CON_TXP<11>")
	)
	(segment
		(start 401.61083 -6.923278)
		(end 404.194518 -7.470902)
		(width 0.1143)
		(layer "In9.Cu")
		(net "P3E_CPU0_PE1_PCH_CON_TXP<11>")
	)
	(segment
		(start 322.50253 -116.739162)
		(end 322.217288 -116.45392)
		(width 0.1143)
		(layer "In9.Cu")
		(net "P3E_CPU0_PE1_PCH_CON_TXP<11>")
	)
	(segment
		(start 423.892726 -6.803898)
		(end 425.00296 -7.039864)
		(width 0.1143)
		(layer "In9.Cu")
		(net "P3E_CPU0_PE1_PCH_CON_TXP<11>")
	)
	(segment
		(start 327.330816 -106.134154)
		(end 329.530964 -102.135432)
		(width 0.1143)
		(layer "In9.Cu")
		(net "P3E_CPU0_PE1_PCH_CON_TXP<11>")
	)
	(segment
		(start 322.217288 -116.45392)
		(end 321.661536 -116.45392)
		(width 0.1143)
		(layer "In9.Cu")
		(net "P3E_CPU0_PE1_PCH_CON_TXP<11>")
	)
	(segment
		(start 394.023342 -10.245344)
		(end 394.361416 -10.465054)
		(width 0.1143)
		(layer "In9.Cu")
		(net "P3E_CPU0_PE1_PCH_CON_TXP<11>")
	)
	(segment
		(start 330.544932 -55.674768)
		(end 330.430886 -55.287672)
		(width 0.1143)
		(layer "In9.Cu")
		(net "P3E_CPU0_PE1_PCH_CON_TXP<11>")
	)
	(segment
		(start 366.331754 -25.58669)
		(end 367.878614 -18.367756)
		(width 0.1143)
		(layer "In9.Cu")
		(net "P3E_CPU0_PE1_PCH_CON_TXP<11>")
	)
	(segment
		(start 329.583796 -94.053914)
		(end 327.311004 -83.349592)
		(width 0.1143)
		(layer "In9.Cu")
		(net "P3E_CPU0_PE1_PCH_CON_TXP<11>")
	)
	(segment
		(start 426.316648 -6.760972)
		(end 427.609 -7.0358)
		(width 0.1143)
		(layer "In9.Cu")
		(net "P3E_CPU0_PE1_PCH_CON_TXP<11>")
	)
	(segment
		(start 399.386044 -7.753858)
		(end 399.707354 -7.63397)
		(width 0.1143)
		(layer "In9.Cu")
		(net "P3E_CPU0_PE1_PCH_CON_TXP<11>")
	)
	(segment
		(start 322.217288 -114.38382)
		(end 322.50253 -114.098578)
		(width 0.1143)
		(layer "In9.Cu")
		(net "P3E_CPU0_PE1_PCH_CON_TXP<11>")
	)
	(segment
		(start 393.517374 -9.69899)
		(end 393.778486 -9.64311)
		(width 0.1143)
		(layer "In9.Cu")
		(net "P3E_CPU0_PE1_PCH_CON_TXP<11>")
	)
	(segment
		(start 322.50253 -114.098578)
		(end 322.50253 -113.589562)
		(width 0.1143)
		(layer "In9.Cu")
		(net "P3E_CPU0_PE1_PCH_CON_TXP<11>")
	)
	(segment
		(start 394.361416 -10.465054)
		(end 395.480286 -10.227056)
		(width 0.1143)
		(layer "In9.Cu")
		(net "P3E_CPU0_PE1_PCH_CON_TXP<11>")
	)
	(segment
		(start 393.429236 -9.834372)
		(end 393.517374 -9.69899)
		(width 0.1143)
		(layer "In9.Cu")
		(net "P3E_CPU0_PE1_PCH_CON_TXP<11>")
	)
	(segment
		(start 328.518012 -64.330834)
		(end 329.800712 -58.027062)
		(width 0.1143)
		(layer "In9.Cu")
		(net "P3E_CPU0_PE1_PCH_CON_TXP<11>")
	)
	(segment
		(start 321.661536 -114.87912)
		(end 321.547236 -114.76482)
		(width 0.1143)
		(layer "In9.Cu")
		(net "P3E_CPU0_PE1_PCH_CON_TXP<11>")
	)
	(segment
		(start 404.194518 -7.470902)
		(end 410.43987 -6.14553)
		(width 0.1143)
		(layer "In9.Cu")
		(net "P3E_CPU0_PE1_PCH_CON_TXP<11>")
	)
	(segment
		(start 399.919698 -7.730744)
		(end 400.241008 -7.610856)
		(width 0.1143)
		(layer "In9.Cu")
		(net "P3E_CPU0_PE1_PCH_CON_TXP<11>")
	)
	(segment
		(start 438.672986 -9.140698)
		(end 439.08345 -9.550908)
		(width 0.1143)
		(layer "In9.Cu")
		(net "P3E_CPU0_PE1_PCH_CON_TXP<11>")
	)
	(segment
		(start 333.584042 -51.214528)
		(end 334.611472 -50.475388)
		(width 0.1143)
		(layer "In9.Cu")
		(net "P3E_CPU0_PE1_PCH_CON_TXP<11>")
	)
	(segment
		(start 332.556104 -51.953922)
		(end 332.556104 -51.953668)
		(width 0.1143)
		(layer "In9.Cu")
		(net "P3E_CPU0_PE1_PCH_CON_TXP<11>")
	)
	(segment
		(start 439.08345 -9.550908)
		(end 439.08345 -9.90981)
		(width 0.1143)
		(layer "In9.Cu")
		(net "P3E_CPU0_PE1_PCH_CON_TXP<11>")
	)
	(segment
		(start 330.94549 -53.716428)
		(end 330.722986 -53.595778)
		(width 0.1143)
		(layer "In9.Cu")
		(net "P3E_CPU0_PE1_PCH_CON_TXP<11>")
	)
	(segment
		(start 400.337782 -7.398512)
		(end 400.659092 -7.278624)
		(width 0.1143)
		(layer "In9.Cu")
		(net "P3E_CPU0_PE1_PCH_CON_TXP<11>")
	)
	(segment
		(start 438.96915 -10.02411)
		(end 438.755282 -10.02411)
		(width 0.1143)
		(layer "In9.Cu")
		(net "P3E_CPU0_PE1_PCH_CON_TXP<11>")
	)
	(segment
		(start 369.884706 -14.624812)
		(end 371.71503 -13.189966)
		(width 0.1143)
		(layer "In9.Cu")
		(net "P3E_CPU0_PE1_PCH_CON_TXP<11>")
	)
	(segment
		(start 329.682602 -57.174892)
		(end 330.018898 -56.952642)
		(width 0.1143)
		(layer "In9.Cu")
		(net "P3E_CPU0_PE1_PCH_CON_TXP<11>")
	)
	(segment
		(start 320.7766 -118.157498)
		(end 320.8909 -118.043198)
		(width 0.1143)
		(layer "In9.Cu")
		(net "P3E_CPU0_PE1_PCH_CON_TXP<11>")
	)
	(segment
		(start 322.50253 -113.589562)
		(end 322.217288 -113.30432)
		(width 0.1143)
		(layer "In9.Cu")
		(net "P3E_CPU0_PE1_PCH_CON_TXP<11>")
	)
	(segment
		(start 364.334552 -30.347412)
		(end 364.104936 -29.198316)
		(width 0.1143)
		(layer "In9.Cu")
		(net "P3E_CPU0_PE1_PCH_CON_TXP<11>")
	)
	(segment
		(start 327.04024 -77.480668)
		(end 327.349612 -76.024232)
		(width 0.1143)
		(layer "In9.Cu")
		(net "P3E_CPU0_PE1_PCH_CON_TXP<11>")
	)
	(segment
		(start 364.596172 -26.74239)
		(end 366.331754 -25.58669)
		(width 0.1143)
		(layer "In9.Cu")
		(net "P3E_CPU0_PE1_PCH_CON_TXP<11>")
	)
	(segment
		(start 331.09154 -53.23205)
		(end 331.09154 -53.231796)
		(width 0.1143)
		(layer "In9.Cu")
		(net "P3E_CPU0_PE1_PCH_CON_TXP<11>")
	)
	(segment
		(start 425.00296 -7.039864)
		(end 426.316648 -6.760972)
		(width 0.1143)
		(layer "In9.Cu")
		(net "P3E_CPU0_PE1_PCH_CON_TXP<11>")
	)
	(segment
		(start 327.311004 -83.349592)
		(end 327.833482 -81.212944)
		(width 0.1143)
		(layer "In9.Cu")
		(net "P3E_CPU0_PE1_PCH_CON_TXP<11>")
	)
	(segment
		(start 379.431804 -11.54938)
		(end 380.312422 -11.736578)
		(width 0.1143)
		(layer "In9.Cu")
		(net "P3E_CPU0_PE1_PCH_CON_TXP<11>")
	)
	(segment
		(start 363.9185 -32.424116)
		(end 364.334552 -30.347412)
		(width 0.1143)
		(layer "In9.Cu")
		(net "P3E_CPU0_PE1_PCH_CON_TXP<11>")
	)
	(segment
		(start 322.217288 -112.80902)
		(end 322.50253 -112.523778)
		(width 0.1143)
		(layer "In9.Cu")
		(net "P3E_CPU0_PE1_PCH_CON_TXP<11>")
	)
	(segment
		(start 327.583546 -71.92264)
		(end 327.271888 -70.456044)
		(width 0.1143)
		(layer "In9.Cu")
		(net "P3E_CPU0_PE1_PCH_CON_TXP<11>")
	)
	(segment
		(start 329.184762 -57.190386)
		(end 329.319636 -57.100978)
		(width 0.1143)
		(layer "In9.Cu")
		(net "P3E_CPU0_PE1_PCH_CON_TXP<11>")
	)
	(segment
		(start 329.131422 -57.451752)
		(end 329.184762 -57.190386)
		(width 0.1143)
		(layer "In9.Cu")
		(net "P3E_CPU0_PE1_PCH_CON_TXP<11>")
	)
	(segment
		(start 327.271888 -70.456044)
		(end 328.518012 -64.331088)
		(width 0.1143)
		(layer "In9.Cu")
		(net "P3E_CPU0_PE1_PCH_CON_TXP<11>")
	)
	(segment
		(start 439.08345 -9.90981)
		(end 438.96915 -10.02411)
		(width 0.1143)
		(layer "In9.Cu")
		(net "P3E_CPU0_PE1_PCH_CON_TXP<11>")
	)
	(segment
		(start 331.055218 -54.723538)
		(end 331.29855 -54.27472)
		(width 0.1143)
		(layer "In9.Cu")
		(net "P3E_CPU0_PE1_PCH_CON_TXP<11>")
	)
	(segment
		(start 415.509456 -7.221982)
		(end 417.15055 -6.873494)
		(width 0.1143)
		(layer "In9.Cu")
		(net "P3E_CPU0_PE1_PCH_CON_TXP<11>")
	)
	(segment
		(start 417.15055 -6.873494)
		(end 417.949126 -7.042912)
		(width 0.1143)
		(layer "In9.Cu")
		(net "P3E_CPU0_PE1_PCH_CON_TXP<11>")
	)
	(segment
		(start 393.778486 -9.64311)
		(end 393.913868 -9.731248)
		(width 0.1143)
		(layer "In9.Cu")
		(net "P3E_CPU0_PE1_PCH_CON_TXP<11>")
	)
	(segment
		(start 371.71503 -13.189966)
		(end 379.431804 -11.54938)
		(width 0.1143)
		(layer "In9.Cu")
		(net "P3E_CPU0_PE1_PCH_CON_TXP<11>")
	)
	(segment
		(start 330.120752 -56.449722)
		(end 330.121006 -56.449214)
		(width 0.1143)
		(layer "In9.Cu")
		(net "P3E_CPU0_PE1_PCH_CON_TXP<11>")
	)
	(segment
		(start 393.913868 -9.731248)
		(end 394.023342 -10.245344)
		(width 0.1143)
		(layer "In9.Cu")
		(net "P3E_CPU0_PE1_PCH_CON_TXP<11>")
	)
	(segment
		(start 358.751886 -44.566586)
		(end 359.682288 -42.812716)
		(width 0.1143)
		(layer "In9.Cu")
		(net "P3E_CPU0_PE1_PCH_CON_TXP<11>")
	)
	(segment
		(start 321.547236 -112.92332)
		(end 321.661536 -112.80902)
		(width 0.1143)
		(layer "In9.Cu")
		(net "P3E_CPU0_PE1_PCH_CON_TXP<11>")
	)
	(segment
		(start 330.121006 -56.449214)
		(end 330.544932 -55.674768)
		(width 0.1143)
		(layer "In9.Cu")
		(net "P3E_CPU0_PE1_PCH_CON_TXP<11>")
	)
	(segment
		(start 401.28952 -7.043166)
		(end 401.61083 -6.923278)
		(width 0.1143)
		(layer "In9.Cu")
		(net "P3E_CPU0_PE1_PCH_CON_TXP<11>")
	)
	(segment
		(start 330.945744 -53.716682)
		(end 330.94549 -53.716428)
		(width 0.1143)
		(layer "In9.Cu")
		(net "P3E_CPU0_PE1_PCH_CON_TXP<11>")
	)
	(segment
		(start 320.7766 -118.492016)
		(end 320.7766 -118.157498)
		(width 0.1143)
		(layer "In9.Cu")
		(net "P3E_CPU0_PE1_PCH_CON_TXP<11>")
	)
	(segment
		(start 400.871436 -7.375398)
		(end 401.192746 -7.25551)
		(width 0.1143)
		(layer "In9.Cu")
		(net "P3E_CPU0_PE1_PCH_CON_TXP<11>")
	)
	(segment
		(start 421.47236 -6.789928)
		(end 422.715182 -7.053834)
		(width 0.1143)
		(layer "In9.Cu")
		(net "P3E_CPU0_PE1_PCH_CON_TXP<11>")
	)
	(segment
		(start 422.715182 -7.053834)
		(end 423.892726 -6.803898)
		(width 0.1143)
		(layer "In9.Cu")
		(net "P3E_CPU0_PE1_PCH_CON_TXP<11>")
	)
	(segment
		(start 398.434052 -8.109204)
		(end 398.755362 -7.989316)
		(width 0.1143)
		(layer "In9.Cu")
		(net "P3E_CPU0_PE1_PCH_CON_TXP<11>")
	)
	(segment
		(start 329.825604 -98.260662)
		(end 329.25766 -95.588328)
		(width 0.1143)
		(layer "In9.Cu")
		(net "P3E_CPU0_PE1_PCH_CON_TXP<11>")
	)
	(segment
		(start 400.241008 -7.610856)
		(end 400.337782 -7.398512)
		(width 0.1143)
		(layer "In9.Cu")
		(net "P3E_CPU0_PE1_PCH_CON_TXP<11>")
	)
	(segment
		(start 364.104936 -29.198316)
		(end 364.596172 -26.74239)
		(width 0.1143)
		(layer "In9.Cu")
		(net "P3E_CPU0_PE1_PCH_CON_TXP<11>")
	)
	(segment
		(start 321.547236 -116.07292)
		(end 321.661536 -115.95862)
		(width 0.1143)
		(layer "In9.Cu")
		(net "P3E_CPU0_PE1_PCH_CON_TXP<11>")
	)
	(segment
		(start 331.823822 -53.304948)
		(end 332.556104 -51.953922)
		(width 0.1143)
		(layer "In9.Cu")
		(net "P3E_CPU0_PE1_PCH_CON_TXP<11>")
	)
	(segment
		(start 436.475886 -8.657336)
		(end 436.723282 -8.904732)
		(width 0.1143)
		(layer "F.Cu")
		(net "P3E_CPU0_PE1_PCH_CON_TXP<10>")
	)
	(segment
		(start 436.723282 -8.904732)
		(end 436.723282 -9.961118)
		(width 0.1143)
		(layer "F.Cu")
		(net "P3E_CPU0_PE1_PCH_CON_TXP<10>")
	)
	(segment
		(start 436.475886 -7.789672)
		(end 436.475886 -8.657336)
		(width 0.1143)
		(layer "F.Cu")
		(net "P3E_CPU0_PE1_PCH_CON_TXP<10>")
	)
	(segment
		(start 335.87944 -120.038368)
		(end 336.540602 -120.038368)
		(width 0.1143)
		(layer "F.Cu")
		(net "P3E_CPU0_PE1_PCH_CON_TXP<10>")
	)
	(segment
		(start 436.55488 -10.12952)
		(end 436.361332 -10.12952)
		(width 0.1143)
		(layer "F.Cu")
		(net "P3E_CPU0_PE1_PCH_CON_TXP<10>")
	)
	(segment
		(start 436.723282 -9.961118)
		(end 436.55488 -10.12952)
		(width 0.1143)
		(layer "F.Cu")
		(net "P3E_CPU0_PE1_PCH_CON_TXP<10>")
	)
	(via
		(at 335.87944 -120.038368)
		(size 0.508)
		(drill 0.254)
		(layers "F.Cu" "B.Cu")
		(net "P3E_CPU0_PE1_PCH_CON_TXP<10>")
	)
	(via
		(at 436.361332 -10.12952)
		(size 0.508)
		(drill 0.254)
		(layers "F.Cu" "B.Cu")
		(net "P3E_CPU0_PE1_PCH_CON_TXP<10>")
	)
	(segment
		(start 330.906628 -119.941594)
		(end 325.70166 -119.941594)
		(width 0.1143)
		(layer "In9.Cu")
		(net "P3E_CPU0_PE1_PCH_CON_TXP<10>")
	)
	(segment
		(start 435.939184 -8.650224)
		(end 436.697882 -9.408922)
		(width 0.1143)
		(layer "In9.Cu")
		(net "P3E_CPU0_PE1_PCH_CON_TXP<10>")
	)
	(segment
		(start 329.927458 -95.671894)
		(end 330.253594 -94.134686)
		(width 0.1143)
		(layer "In9.Cu")
		(net "P3E_CPU0_PE1_PCH_CON_TXP<10>")
	)
	(segment
		(start 403.986238 -8.18388)
		(end 410.463746 -6.809232)
		(width 0.1143)
		(layer "In9.Cu")
		(net "P3E_CPU0_PE1_PCH_CON_TXP<10>")
	)
	(segment
		(start 380.317756 -12.390374)
		(end 387.624066 -10.839196)
		(width 0.1143)
		(layer "In9.Cu")
		(net "P3E_CPU0_PE1_PCH_CON_TXP<10>")
	)
	(segment
		(start 426.301154 -7.419848)
		(end 427.62932 -7.702296)
		(width 0.1143)
		(layer "In9.Cu")
		(net "P3E_CPU0_PE1_PCH_CON_TXP<10>")
	)
	(segment
		(start 410.463746 -6.809232)
		(end 415.50336 -7.880096)
		(width 0.1143)
		(layer "In9.Cu")
		(net "P3E_CPU0_PE1_PCH_CON_TXP<10>")
	)
	(segment
		(start 323.491606 -116.953792)
		(end 323.656706 -116.788692)
		(width 0.1143)
		(layer "In9.Cu")
		(net "P3E_CPU0_PE1_PCH_CON_TXP<10>")
	)
	(segment
		(start 331.46492 -55.390288)
		(end 331.628242 -55.08879)
		(width 0.1143)
		(layer "In9.Cu")
		(net "P3E_CPU0_PE1_PCH_CON_TXP<10>")
	)
	(segment
		(start 332.33614 -54.129178)
		(end 332.499462 -53.82768)
		(width 0.1143)
		(layer "In9.Cu")
		(net "P3E_CPU0_PE1_PCH_CON_TXP<10>")
	)
	(segment
		(start 330.253594 -94.134686)
		(end 327.98258 -83.437222)
		(width 0.1143)
		(layer "In9.Cu")
		(net "P3E_CPU0_PE1_PCH_CON_TXP<10>")
	)
	(segment
		(start 359.26014 -45.008038)
		(end 360.313986 -43.020996)
		(width 0.1143)
		(layer "In9.Cu")
		(net "P3E_CPU0_PE1_PCH_CON_TXP<10>")
	)
	(segment
		(start 361.725972 -36.159186)
		(end 364.504224 -32.734504)
		(width 0.1143)
		(layer "In9.Cu")
		(net "P3E_CPU0_PE1_PCH_CON_TXP<10>")
	)
	(segment
		(start 325.45909 -119.699024)
		(end 325.45909 -119.465598)
		(width 0.1143)
		(layer "In9.Cu")
		(net "P3E_CPU0_PE1_PCH_CON_TXP<10>")
	)
	(segment
		(start 360.313986 -43.020996)
		(end 361.725972 -36.159186)
		(width 0.1143)
		(layer "In9.Cu")
		(net "P3E_CPU0_PE1_PCH_CON_TXP<10>")
	)
	(segment
		(start 431.366422 -7.401052)
		(end 432.446176 -7.716266)
		(width 0.1143)
		(layer "In9.Cu")
		(net "P3E_CPU0_PE1_PCH_CON_TXP<10>")
	)
	(segment
		(start 422.714928 -7.716012)
		(end 423.892726 -7.466076)
		(width 0.1143)
		(layer "In9.Cu")
		(net "P3E_CPU0_PE1_PCH_CON_TXP<10>")
	)
	(segment
		(start 331.367892 -55.91556)
		(end 331.531214 -55.614062)
		(width 0.1143)
		(layer "In9.Cu")
		(net "P3E_CPU0_PE1_PCH_CON_TXP<10>")
	)
	(segment
		(start 332.015338 -54.720744)
		(end 331.949044 -54.49697)
		(width 0.1143)
		(layer "In9.Cu")
		(net "P3E_CPU0_PE1_PCH_CON_TXP<10>")
	)
	(segment
		(start 323.656706 -115.429792)
		(end 323.491606 -115.264692)
		(width 0.1143)
		(layer "In9.Cu")
		(net "P3E_CPU0_PE1_PCH_CON_TXP<10>")
	)
	(segment
		(start 323.656706 -116.788692)
		(end 323.656706 -116.445792)
		(width 0.1143)
		(layer "In9.Cu")
		(net "P3E_CPU0_PE1_PCH_CON_TXP<10>")
	)
	(segment
		(start 327.68286 -74.523346)
		(end 328.23531 -71.92264)
		(width 0.1143)
		(layer "In9.Cu")
		(net "P3E_CPU0_PE1_PCH_CON_TXP<10>")
	)
	(segment
		(start 370.360194 -15.51432)
		(end 370.2939 -15.290546)
		(width 0.1143)
		(layer "In9.Cu")
		(net "P3E_CPU0_PE1_PCH_CON_TXP<10>")
	)
	(segment
		(start 420.287704 -7.704074)
		(end 421.47236 -7.452106)
		(width 0.1143)
		(layer "In9.Cu")
		(net "P3E_CPU0_PE1_PCH_CON_TXP<10>")
	)
	(segment
		(start 335.652364 -120.455436)
		(end 331.42047 -120.455436)
		(width 0.1143)
		(layer "In9.Cu")
		(net "P3E_CPU0_PE1_PCH_CON_TXP<10>")
	)
	(segment
		(start 332.499462 -53.82768)
		(end 332.433168 -53.603906)
		(width 0.1143)
		(layer "In9.Cu")
		(net "P3E_CPU0_PE1_PCH_CON_TXP<10>")
	)
	(segment
		(start 424.987466 -7.69874)
		(end 426.301154 -7.419848)
		(width 0.1143)
		(layer "In9.Cu")
		(net "P3E_CPU0_PE1_PCH_CON_TXP<10>")
	)
	(segment
		(start 379.454156 -12.206986)
		(end 380.317756 -12.390374)
		(width 0.1143)
		(layer "In9.Cu")
		(net "P3E_CPU0_PE1_PCH_CON_TXP<10>")
	)
	(segment
		(start 436.555134 -10.12952)
		(end 436.361332 -10.12952)
		(width 0.1143)
		(layer "In9.Cu")
		(net "P3E_CPU0_PE1_PCH_CON_TXP<10>")
	)
	(segment
		(start 387.624066 -10.839196)
		(end 391.691368 -11.703812)
		(width 0.1143)
		(layer "In9.Cu")
		(net "P3E_CPU0_PE1_PCH_CON_TXP<10>")
	)
	(segment
		(start 366.919764 -25.974294)
		(end 368.538506 -18.524728)
		(width 0.1143)
		(layer "In9.Cu")
		(net "P3E_CPU0_PE1_PCH_CON_TXP<10>")
	)
	(segment
		(start 369.324636 -17.07642)
		(end 369.488212 -16.774922)
		(width 0.1143)
		(layer "In9.Cu")
		(net "P3E_CPU0_PE1_PCH_CON_TXP<10>")
	)
	(segment
		(start 391.691368 -11.703812)
		(end 398.08023 -10.346436)
		(width 0.1143)
		(layer "In9.Cu")
		(net "P3E_CPU0_PE1_PCH_CON_TXP<10>")
	)
	(segment
		(start 370.2939 -15.290546)
		(end 370.457476 -14.989048)
		(width 0.1143)
		(layer "In9.Cu")
		(net "P3E_CPU0_PE1_PCH_CON_TXP<10>")
	)
	(segment
		(start 371.976904 -13.79601)
		(end 379.454156 -12.206986)
		(width 0.1143)
		(layer "In9.Cu")
		(net "P3E_CPU0_PE1_PCH_CON_TXP<10>")
	)
	(segment
		(start 324.498462 -118.50497)
		(end 324.265036 -118.50497)
		(width 0.1143)
		(layer "In9.Cu")
		(net "P3E_CPU0_PE1_PCH_CON_TXP<10>")
	)
	(segment
		(start 369.972844 -15.882112)
		(end 370.196618 -15.815564)
		(width 0.1143)
		(layer "In9.Cu")
		(net "P3E_CPU0_PE1_PCH_CON_TXP<10>")
	)
	(segment
		(start 370.457476 -14.989048)
		(end 371.976904 -13.79601)
		(width 0.1143)
		(layer "In9.Cu")
		(net "P3E_CPU0_PE1_PCH_CON_TXP<10>")
	)
	(segment
		(start 368.538506 -18.524728)
		(end 369.00358 -17.667986)
		(width 0.1143)
		(layer "In9.Cu")
		(net "P3E_CPU0_PE1_PCH_CON_TXP<10>")
	)
	(segment
		(start 429.871124 -7.718806)
		(end 431.366422 -7.401052)
		(width 0.1143)
		(layer "In9.Cu")
		(net "P3E_CPU0_PE1_PCH_CON_TXP<10>")
	)
	(segment
		(start 335.87944 -120.22836)
		(end 335.652364 -120.455436)
		(width 0.1143)
		(layer "In9.Cu")
		(net "P3E_CPU0_PE1_PCH_CON_TXP<10>")
	)
	(segment
		(start 325.216774 -119.223282)
		(end 324.983348 -119.223282)
		(width 0.1143)
		(layer "In9.Cu")
		(net "P3E_CPU0_PE1_PCH_CON_TXP<10>")
	)
	(segment
		(start 324.740778 -118.747286)
		(end 324.498462 -118.50497)
		(width 0.1143)
		(layer "In9.Cu")
		(net "P3E_CPU0_PE1_PCH_CON_TXP<10>")
	)
	(segment
		(start 331.531214 -55.614062)
		(end 331.46492 -55.390288)
		(width 0.1143)
		(layer "In9.Cu")
		(net "P3E_CPU0_PE1_PCH_CON_TXP<10>")
	)
	(segment
		(start 417.13785 -7.532878)
		(end 417.923472 -7.699756)
		(width 0.1143)
		(layer "In9.Cu")
		(net "P3E_CPU0_PE1_PCH_CON_TXP<10>")
	)
	(segment
		(start 364.504224 -32.734504)
		(end 364.991396 -30.302454)
		(width 0.1143)
		(layer "In9.Cu")
		(net "P3E_CPU0_PE1_PCH_CON_TXP<10>")
	)
	(segment
		(start 436.697882 -9.408922)
		(end 436.697882 -9.986772)
		(width 0.1143)
		(layer "In9.Cu")
		(net "P3E_CPU0_PE1_PCH_CON_TXP<10>")
	)
	(segment
		(start 333.080614 -52.40909)
		(end 334.893158 -51.105308)
		(width 0.1143)
		(layer "In9.Cu")
		(net "P3E_CPU0_PE1_PCH_CON_TXP<10>")
	)
	(segment
		(start 338.325206 -50.406808)
		(end 340.616286 -50.872644)
		(width 0.1143)
		(layer "In9.Cu")
		(net "P3E_CPU0_PE1_PCH_CON_TXP<10>")
	)
	(segment
		(start 357.017574 -46.476158)
		(end 359.26014 -45.008038)
		(width 0.1143)
		(layer "In9.Cu")
		(net "P3E_CPU0_PE1_PCH_CON_TXP<10>")
	)
	(segment
		(start 364.991396 -30.302454)
		(end 364.762288 -29.155898)
		(width 0.1143)
		(layer "In9.Cu")
		(net "P3E_CPU0_PE1_PCH_CON_TXP<10>")
	)
	(segment
		(start 332.820264 -53.23586)
		(end 332.983586 -52.934362)
		(width 0.1143)
		(layer "In9.Cu")
		(net "P3E_CPU0_PE1_PCH_CON_TXP<10>")
	)
	(segment
		(start 370.196618 -15.815564)
		(end 370.360194 -15.51432)
		(width 0.1143)
		(layer "In9.Cu")
		(net "P3E_CPU0_PE1_PCH_CON_TXP<10>")
	)
	(segment
		(start 323.491606 -115.937792)
		(end 323.656706 -115.772692)
		(width 0.1143)
		(layer "In9.Cu")
		(net "P3E_CPU0_PE1_PCH_CON_TXP<10>")
	)
	(segment
		(start 332.917292 -52.710588)
		(end 333.080614 -52.40909)
		(width 0.1143)
		(layer "In9.Cu")
		(net "P3E_CPU0_PE1_PCH_CON_TXP<10>")
	)
	(segment
		(start 369.39093 -17.300194)
		(end 369.324636 -17.07642)
		(width 0.1143)
		(layer "In9.Cu")
		(net "P3E_CPU0_PE1_PCH_CON_TXP<10>")
	)
	(segment
		(start 324.265036 -118.50497)
		(end 323.491606 -117.73154)
		(width 0.1143)
		(layer "In9.Cu")
		(net "P3E_CPU0_PE1_PCH_CON_TXP<10>")
	)
	(segment
		(start 330.723748 -56.75757)
		(end 331.144118 -55.982108)
		(width 0.1143)
		(layer "In9.Cu")
		(net "P3E_CPU0_PE1_PCH_CON_TXP<10>")
	)
	(segment
		(start 330.511404 -98.422714)
		(end 329.927458 -95.671894)
		(width 0.1143)
		(layer "In9.Cu")
		(net "P3E_CPU0_PE1_PCH_CON_TXP<10>")
	)
	(segment
		(start 332.112366 -54.195472)
		(end 332.33614 -54.129178)
		(width 0.1143)
		(layer "In9.Cu")
		(net "P3E_CPU0_PE1_PCH_CON_TXP<10>")
	)
	(segment
		(start 324.983348 -119.223282)
		(end 324.740778 -118.980712)
		(width 0.1143)
		(layer "In9.Cu")
		(net "P3E_CPU0_PE1_PCH_CON_TXP<10>")
	)
	(segment
		(start 331.949044 -54.49697)
		(end 332.112366 -54.195472)
		(width 0.1143)
		(layer "In9.Cu")
		(net "P3E_CPU0_PE1_PCH_CON_TXP<10>")
	)
	(segment
		(start 433.367942 -7.519924)
		(end 435.939184 -8.650224)
		(width 0.1143)
		(layer "In9.Cu")
		(net "P3E_CPU0_PE1_PCH_CON_TXP<10>")
	)
	(segment
		(start 428.710852 -7.472426)
		(end 429.871124 -7.718806)
		(width 0.1143)
		(layer "In9.Cu")
		(net "P3E_CPU0_PE1_PCH_CON_TXP<10>")
	)
	(segment
		(start 436.697882 -9.986772)
		(end 436.555134 -10.12952)
		(width 0.1143)
		(layer "In9.Cu")
		(net "P3E_CPU0_PE1_PCH_CON_TXP<10>")
	)
	(segment
		(start 323.491606 -116.280692)
		(end 323.491606 -115.937792)
		(width 0.1143)
		(layer "In9.Cu")
		(net "P3E_CPU0_PE1_PCH_CON_TXP<10>")
	)
	(segment
		(start 402.022056 -7.76732)
		(end 403.986238 -8.18388)
		(width 0.1143)
		(layer "In9.Cu")
		(net "P3E_CPU0_PE1_PCH_CON_TXP<10>")
	)
	(segment
		(start 328.504296 -81.30286)
		(end 327.692004 -77.480668)
		(width 0.1143)
		(layer "In9.Cu")
		(net "P3E_CPU0_PE1_PCH_CON_TXP<10>")
	)
	(segment
		(start 423.892726 -7.466076)
		(end 424.987466 -7.69874)
		(width 0.1143)
		(layer "In9.Cu")
		(net "P3E_CPU0_PE1_PCH_CON_TXP<10>")
	)
	(segment
		(start 369.711986 -16.708628)
		(end 369.875562 -16.40713)
		(width 0.1143)
		(layer "In9.Cu")
		(net "P3E_CPU0_PE1_PCH_CON_TXP<10>")
	)
	(segment
		(start 324.740778 -118.980712)
		(end 324.740778 -118.747286)
		(width 0.1143)
		(layer "In9.Cu")
		(net "P3E_CPU0_PE1_PCH_CON_TXP<10>")
	)
	(segment
		(start 328.23531 -71.92264)
		(end 327.93051 -70.487794)
		(width 0.1143)
		(layer "In9.Cu")
		(net "P3E_CPU0_PE1_PCH_CON_TXP<10>")
	)
	(segment
		(start 398.08023 -10.346436)
		(end 399.062956 -8.871712)
		(width 0.1143)
		(layer "In9.Cu")
		(net "P3E_CPU0_PE1_PCH_CON_TXP<10>")
	)
	(segment
		(start 330.22032 -102.255574)
		(end 330.511404 -98.422714)
		(width 0.1143)
		(layer "In9.Cu")
		(net "P3E_CPU0_PE1_PCH_CON_TXP<10>")
	)
	(segment
		(start 399.062956 -8.871712)
		(end 402.022056 -7.76732)
		(width 0.1143)
		(layer "In9.Cu")
		(net "P3E_CPU0_PE1_PCH_CON_TXP<10>")
	)
	(segment
		(start 365.164624 -27.142694)
		(end 366.919764 -25.974294)
		(width 0.1143)
		(layer "In9.Cu")
		(net "P3E_CPU0_PE1_PCH_CON_TXP<10>")
	)
	(segment
		(start 419.095682 -7.450836)
		(end 420.287704 -7.704074)
		(width 0.1143)
		(layer "In9.Cu")
		(net "P3E_CPU0_PE1_PCH_CON_TXP<10>")
	)
	(segment
		(start 432.446176 -7.716266)
		(end 433.367942 -7.519924)
		(width 0.1143)
		(layer "In9.Cu")
		(net "P3E_CPU0_PE1_PCH_CON_TXP<10>")
	)
	(segment
		(start 327.98258 -83.437222)
		(end 328.504296 -81.30286)
		(width 0.1143)
		(layer "In9.Cu")
		(net "P3E_CPU0_PE1_PCH_CON_TXP<10>")
	)
	(segment
		(start 331.628242 -55.08879)
		(end 331.852016 -55.022242)
		(width 0.1143)
		(layer "In9.Cu")
		(net "P3E_CPU0_PE1_PCH_CON_TXP<10>")
	)
	(segment
		(start 331.852016 -55.022242)
		(end 332.015338 -54.720744)
		(width 0.1143)
		(layer "In9.Cu")
		(net "P3E_CPU0_PE1_PCH_CON_TXP<10>")
	)
	(segment
		(start 332.433168 -53.603906)
		(end 332.59649 -53.302408)
		(width 0.1143)
		(layer "In9.Cu")
		(net "P3E_CPU0_PE1_PCH_CON_TXP<10>")
	)
	(segment
		(start 334.893158 -51.105308)
		(end 338.325206 -50.406808)
		(width 0.1143)
		(layer "In9.Cu")
		(net "P3E_CPU0_PE1_PCH_CON_TXP<10>")
	)
	(segment
		(start 331.144118 -55.982108)
		(end 331.367892 -55.91556)
		(width 0.1143)
		(layer "In9.Cu")
		(net "P3E_CPU0_PE1_PCH_CON_TXP<10>")
	)
	(segment
		(start 328.001376 -76.024232)
		(end 327.68286 -74.523346)
		(width 0.1143)
		(layer "In9.Cu")
		(net "P3E_CPU0_PE1_PCH_CON_TXP<10>")
	)
	(segment
		(start 335.87944 -120.038368)
		(end 335.87944 -120.22836)
		(width 0.1143)
		(layer "In9.Cu")
		(net "P3E_CPU0_PE1_PCH_CON_TXP<10>")
	)
	(segment
		(start 369.875562 -16.40713)
		(end 369.809268 -16.183356)
		(width 0.1143)
		(layer "In9.Cu")
		(net "P3E_CPU0_PE1_PCH_CON_TXP<10>")
	)
	(segment
		(start 327.843896 -106.575352)
		(end 330.22032 -102.255574)
		(width 0.1143)
		(layer "In9.Cu")
		(net "P3E_CPU0_PE1_PCH_CON_TXP<10>")
	)
	(segment
		(start 323.491606 -115.264692)
		(end 323.491606 -110.59668)
		(width 0.1143)
		(layer "In9.Cu")
		(net "P3E_CPU0_PE1_PCH_CON_TXP<10>")
	)
	(segment
		(start 323.491606 -117.73154)
		(end 323.491606 -116.953792)
		(width 0.1143)
		(layer "In9.Cu")
		(net "P3E_CPU0_PE1_PCH_CON_TXP<10>")
	)
	(segment
		(start 415.50336 -7.880096)
		(end 417.13785 -7.532878)
		(width 0.1143)
		(layer "In9.Cu")
		(net "P3E_CPU0_PE1_PCH_CON_TXP<10>")
	)
	(segment
		(start 327.93051 -70.487794)
		(end 330.723748 -56.75757)
		(width 0.1143)
		(layer "In9.Cu")
		(net "P3E_CPU0_PE1_PCH_CON_TXP<10>")
	)
	(segment
		(start 369.809268 -16.183356)
		(end 369.972844 -15.882112)
		(width 0.1143)
		(layer "In9.Cu")
		(net "P3E_CPU0_PE1_PCH_CON_TXP<10>")
	)
	(segment
		(start 369.00358 -17.667986)
		(end 369.227354 -17.601438)
		(width 0.1143)
		(layer "In9.Cu")
		(net "P3E_CPU0_PE1_PCH_CON_TXP<10>")
	)
	(segment
		(start 332.983586 -52.934362)
		(end 332.917292 -52.710588)
		(width 0.1143)
		(layer "In9.Cu")
		(net "P3E_CPU0_PE1_PCH_CON_TXP<10>")
	)
	(segment
		(start 417.923472 -7.699756)
		(end 419.095682 -7.450836)
		(width 0.1143)
		(layer "In9.Cu")
		(net "P3E_CPU0_PE1_PCH_CON_TXP<10>")
	)
	(segment
		(start 323.656706 -115.772692)
		(end 323.656706 -115.429792)
		(width 0.1143)
		(layer "In9.Cu")
		(net "P3E_CPU0_PE1_PCH_CON_TXP<10>")
	)
	(segment
		(start 421.47236 -7.452106)
		(end 422.714928 -7.716012)
		(width 0.1143)
		(layer "In9.Cu")
		(net "P3E_CPU0_PE1_PCH_CON_TXP<10>")
	)
	(segment
		(start 323.656706 -116.445792)
		(end 323.491606 -116.280692)
		(width 0.1143)
		(layer "In9.Cu")
		(net "P3E_CPU0_PE1_PCH_CON_TXP<10>")
	)
	(segment
		(start 323.491606 -110.59668)
		(end 327.843896 -106.575352)
		(width 0.1143)
		(layer "In9.Cu")
		(net "P3E_CPU0_PE1_PCH_CON_TXP<10>")
	)
	(segment
		(start 325.70166 -119.941594)
		(end 325.45909 -119.699024)
		(width 0.1143)
		(layer "In9.Cu")
		(net "P3E_CPU0_PE1_PCH_CON_TXP<10>")
	)
	(segment
		(start 364.762288 -29.155898)
		(end 365.164624 -27.142694)
		(width 0.1143)
		(layer "In9.Cu")
		(net "P3E_CPU0_PE1_PCH_CON_TXP<10>")
	)
	(segment
		(start 332.59649 -53.302408)
		(end 332.820264 -53.23586)
		(width 0.1143)
		(layer "In9.Cu")
		(net "P3E_CPU0_PE1_PCH_CON_TXP<10>")
	)
	(segment
		(start 340.616286 -50.872644)
		(end 357.017574 -46.476158)
		(width 0.1143)
		(layer "In9.Cu")
		(net "P3E_CPU0_PE1_PCH_CON_TXP<10>")
	)
	(segment
		(start 369.227354 -17.601438)
		(end 369.39093 -17.300194)
		(width 0.1143)
		(layer "In9.Cu")
		(net "P3E_CPU0_PE1_PCH_CON_TXP<10>")
	)
	(segment
		(start 369.488212 -16.774922)
		(end 369.711986 -16.708628)
		(width 0.1143)
		(layer "In9.Cu")
		(net "P3E_CPU0_PE1_PCH_CON_TXP<10>")
	)
	(segment
		(start 331.42047 -120.455436)
		(end 330.906628 -119.941594)
		(width 0.1143)
		(layer "In9.Cu")
		(net "P3E_CPU0_PE1_PCH_CON_TXP<10>")
	)
	(segment
		(start 427.62932 -7.702296)
		(end 428.710852 -7.472426)
		(width 0.1143)
		(layer "In9.Cu")
		(net "P3E_CPU0_PE1_PCH_CON_TXP<10>")
	)
	(segment
		(start 327.692004 -77.480668)
		(end 328.001376 -76.024232)
		(width 0.1143)
		(layer "In9.Cu")
		(net "P3E_CPU0_PE1_PCH_CON_TXP<10>")
	)
	(segment
		(start 325.45909 -119.465598)
		(end 325.216774 -119.223282)
		(width 0.1143)
		(layer "In9.Cu")
		(net "P3E_CPU0_PE1_PCH_CON_TXP<10>")
	)
	(segment
		(start 337.672426 -119.211598)
		(end 338.333588 -119.211598)
		(width 0.1143)
		(layer "F.Cu")
		(net "P3E_CPU0_PE1_PCH_CON_TXN<9>")
	)
	(segment
		(start 434.5432 -8.989822)
		(end 434.875686 -8.657336)
		(width 0.1143)
		(layer "F.Cu")
		(net "P3E_CPU0_PE1_PCH_CON_TXN<9>")
	)
	(segment
		(start 434.5432 -9.8044)
		(end 434.5432 -8.989822)
		(width 0.1143)
		(layer "F.Cu")
		(net "P3E_CPU0_PE1_PCH_CON_TXN<9>")
	)
	(segment
		(start 434.926232 -9.9949)
		(end 434.7337 -9.9949)
		(width 0.1143)
		(layer "F.Cu")
		(net "P3E_CPU0_PE1_PCH_CON_TXN<9>")
	)
	(segment
		(start 434.7337 -9.9949)
		(end 434.5432 -9.8044)
		(width 0.1143)
		(layer "F.Cu")
		(net "P3E_CPU0_PE1_PCH_CON_TXN<9>")
	)
	(segment
		(start 434.875686 -8.657336)
		(end 434.875686 -7.789672)
		(width 0.1143)
		(layer "F.Cu")
		(net "P3E_CPU0_PE1_PCH_CON_TXN<9>")
	)
	(via
		(at 337.672426 -119.211598)
		(size 0.508)
		(drill 0.254)
		(layers "F.Cu" "B.Cu")
		(net "P3E_CPU0_PE1_PCH_CON_TXN<9>")
	)
	(via
		(at 434.926232 -9.9949)
		(size 0.508)
		(drill 0.254)
		(layers "F.Cu" "B.Cu")
		(net "P3E_CPU0_PE1_PCH_CON_TXN<9>")
	)
	(segment
		(start 332.625192 -119.32539)
		(end 326.432418 -119.32539)
		(width 0.1143)
		(layer "In9.Cu")
		(net "P3E_CPU0_PE1_PCH_CON_TXN<9>")
	)
	(segment
		(start 340.566502 -51.251358)
		(end 357.173022 -46.799246)
		(width 0.1143)
		(layer "In9.Cu")
		(net "P3E_CPU0_PE1_PCH_CON_TXN<9>")
	)
	(segment
		(start 328.58837 -71.92264)
		(end 328.296016 -70.546722)
		(width 0.1143)
		(layer "In9.Cu")
		(net "P3E_CPU0_PE1_PCH_CON_TXN<9>")
	)
	(segment
		(start 364.965488 -32.774382)
		(end 365.414814 -30.530546)
		(width 0.1143)
		(layer "In9.Cu")
		(net "P3E_CPU0_PE1_PCH_CON_TXN<9>")
	)
	(segment
		(start 415.516568 -8.238998)
		(end 417.133786 -7.895336)
		(width 0.1143)
		(layer "In9.Cu")
		(net "P3E_CPU0_PE1_PCH_CON_TXN<9>")
	)
	(segment
		(start 335.056226 -51.4604)
		(end 338.32546 -50.795174)
		(width 0.1143)
		(layer "In9.Cu")
		(net "P3E_CPU0_PE1_PCH_CON_TXN<9>")
	)
	(segment
		(start 417.133786 -7.895336)
		(end 417.932108 -8.065008)
		(width 0.1143)
		(layer "In9.Cu")
		(net "P3E_CPU0_PE1_PCH_CON_TXN<9>")
	)
	(segment
		(start 367.239296 -26.230072)
		(end 368.472212 -20.693888)
		(width 0.1143)
		(layer "In9.Cu")
		(net "P3E_CPU0_PE1_PCH_CON_TXN<9>")
	)
	(segment
		(start 330.637896 -102.301548)
		(end 330.914248 -98.656902)
		(width 0.1143)
		(layer "In9.Cu")
		(net "P3E_CPU0_PE1_PCH_CON_TXN<9>")
	)
	(segment
		(start 379.48362 -12.577064)
		(end 380.30277 -12.751054)
		(width 0.1143)
		(layer "In9.Cu")
		(net "P3E_CPU0_PE1_PCH_CON_TXN<9>")
	)
	(segment
		(start 359.510076 -45.26915)
		(end 360.667554 -43.086782)
		(width 0.1143)
		(layer "In9.Cu")
		(net "P3E_CPU0_PE1_PCH_CON_TXN<9>")
	)
	(segment
		(start 360.667554 -43.086782)
		(end 362.050584 -36.366958)
		(width 0.1143)
		(layer "In9.Cu")
		(net "P3E_CPU0_PE1_PCH_CON_TXN<9>")
	)
	(segment
		(start 337.672426 -119.211598)
		(end 337.672426 -119.005604)
		(width 0.1143)
		(layer "In9.Cu")
		(net "P3E_CPU0_PE1_PCH_CON_TXN<9>")
	)
	(segment
		(start 365.414814 -30.530546)
		(end 365.212122 -29.51734)
		(width 0.1143)
		(layer "In9.Cu")
		(net "P3E_CPU0_PE1_PCH_CON_TXN<9>")
	)
	(segment
		(start 423.892472 -7.82955)
		(end 424.987212 -8.062214)
		(width 0.1143)
		(layer "In9.Cu")
		(net "P3E_CPU0_PE1_PCH_CON_TXN<9>")
	)
	(segment
		(start 338.32546 -50.795174)
		(end 340.566502 -51.251358)
		(width 0.1143)
		(layer "In9.Cu")
		(net "P3E_CPU0_PE1_PCH_CON_TXN<9>")
	)
	(segment
		(start 365.212122 -29.51734)
		(end 365.658654 -27.283664)
		(width 0.1143)
		(layer "In9.Cu")
		(net "P3E_CPU0_PE1_PCH_CON_TXN<9>")
	)
	(segment
		(start 330.286868 -95.703136)
		(end 330.617068 -94.149672)
		(width 0.1143)
		(layer "In9.Cu")
		(net "P3E_CPU0_PE1_PCH_CON_TXN<9>")
	)
	(segment
		(start 400.139916 -10.29843)
		(end 401.192492 -8.719312)
		(width 0.1143)
		(layer "In9.Cu")
		(net "P3E_CPU0_PE1_PCH_CON_TXN<9>")
	)
	(segment
		(start 333.217266 -118.733316)
		(end 332.625192 -119.32539)
		(width 0.1143)
		(layer "In9.Cu")
		(net "P3E_CPU0_PE1_PCH_CON_TXN<9>")
	)
	(segment
		(start 432.73853 -8.018018)
		(end 434.133752 -8.523478)
		(width 0.1143)
		(layer "In9.Cu")
		(net "P3E_CPU0_PE1_PCH_CON_TXN<9>")
	)
	(segment
		(start 330.617068 -94.149672)
		(end 328.357484 -83.507326)
		(width 0.1143)
		(layer "In9.Cu")
		(net "P3E_CPU0_PE1_PCH_CON_TXN<9>")
	)
	(segment
		(start 333.93761 -52.265072)
		(end 335.056226 -51.4604)
		(width 0.1143)
		(layer "In9.Cu")
		(net "P3E_CPU0_PE1_PCH_CON_TXN<9>")
	)
	(segment
		(start 357.173022 -46.799246)
		(end 357.17353 -46.799246)
		(width 0.1143)
		(layer "In9.Cu")
		(net "P3E_CPU0_PE1_PCH_CON_TXN<9>")
	)
	(segment
		(start 328.108818 -106.89717)
		(end 330.63688 -102.302564)
		(width 0.1143)
		(layer "In9.Cu")
		(net "P3E_CPU0_PE1_PCH_CON_TXN<9>")
	)
	(segment
		(start 328.875644 -81.388458)
		(end 328.045064 -77.480668)
		(width 0.1143)
		(layer "In9.Cu")
		(net "P3E_CPU0_PE1_PCH_CON_TXN<9>")
	)
	(segment
		(start 326.432418 -119.32539)
		(end 324.59295 -117.485922)
		(width 0.1143)
		(layer "In9.Cu")
		(net "P3E_CPU0_PE1_PCH_CON_TXN<9>")
	)
	(segment
		(start 380.30277 -12.751054)
		(end 387.594094 -11.20267)
		(width 0.1143)
		(layer "In9.Cu")
		(net "P3E_CPU0_PE1_PCH_CON_TXN<9>")
	)
	(segment
		(start 328.106786 -106.900726)
		(end 328.108564 -106.89717)
		(width 0.1143)
		(layer "In9.Cu")
		(net "P3E_CPU0_PE1_PCH_CON_TXN<9>")
	)
	(segment
		(start 387.594094 -11.20267)
		(end 391.743692 -12.084558)
		(width 0.1143)
		(layer "In9.Cu")
		(net "P3E_CPU0_PE1_PCH_CON_TXN<9>")
	)
	(segment
		(start 328.03592 -74.523346)
		(end 328.58837 -71.92264)
		(width 0.1143)
		(layer "In9.Cu")
		(net "P3E_CPU0_PE1_PCH_CON_TXN<9>")
	)
	(segment
		(start 330.914248 -98.656902)
		(end 330.286868 -95.703136)
		(width 0.1143)
		(layer "In9.Cu")
		(net "P3E_CPU0_PE1_PCH_CON_TXN<9>")
	)
	(segment
		(start 431.374804 -7.77367)
		(end 432.433222 -8.082788)
		(width 0.1143)
		(layer "In9.Cu")
		(net "P3E_CPU0_PE1_PCH_CON_TXN<9>")
	)
	(segment
		(start 434.7337 -9.9949)
		(end 434.926232 -9.9949)
		(width 0.1143)
		(layer "In9.Cu")
		(net "P3E_CPU0_PE1_PCH_CON_TXN<9>")
	)
	(segment
		(start 401.192492 -8.719312)
		(end 402.45284 -8.250428)
		(width 0.1143)
		(layer "In9.Cu")
		(net "P3E_CPU0_PE1_PCH_CON_TXN<9>")
	)
	(segment
		(start 324.59295 -117.485922)
		(end 324.59295 -110.145576)
		(width 0.1143)
		(layer "In9.Cu")
		(net "P3E_CPU0_PE1_PCH_CON_TXN<9>")
	)
	(segment
		(start 434.594 -9.8552)
		(end 434.7337 -9.9949)
		(width 0.1143)
		(layer "In9.Cu")
		(net "P3E_CPU0_PE1_PCH_CON_TXN<9>")
	)
	(segment
		(start 434.594 -9.180068)
		(end 434.594 -9.8552)
		(width 0.1143)
		(layer "In9.Cu")
		(net "P3E_CPU0_PE1_PCH_CON_TXN<9>")
	)
	(segment
		(start 328.296016 -70.546722)
		(end 330.860908 -57.94248)
		(width 0.1143)
		(layer "In9.Cu")
		(net "P3E_CPU0_PE1_PCH_CON_TXN<9>")
	)
	(segment
		(start 372.922292 -15.59814)
		(end 376.506486 -13.208508)
		(width 0.1143)
		(layer "In9.Cu")
		(net "P3E_CPU0_PE1_PCH_CON_TXN<9>")
	)
	(segment
		(start 421.472614 -7.81558)
		(end 422.714928 -8.079486)
		(width 0.1143)
		(layer "In9.Cu")
		(net "P3E_CPU0_PE1_PCH_CON_TXN<9>")
	)
	(segment
		(start 432.433222 -8.082788)
		(end 432.73853 -8.018018)
		(width 0.1143)
		(layer "In9.Cu")
		(net "P3E_CPU0_PE1_PCH_CON_TXN<9>")
	)
	(segment
		(start 370.307362 -19.520662)
		(end 372.922292 -15.59814)
		(width 0.1143)
		(layer "In9.Cu")
		(net "P3E_CPU0_PE1_PCH_CON_TXN<9>")
	)
	(segment
		(start 420.287704 -8.067548)
		(end 421.472614 -7.81558)
		(width 0.1143)
		(layer "In9.Cu")
		(net "P3E_CPU0_PE1_PCH_CON_TXN<9>")
	)
	(segment
		(start 362.050584 -36.366958)
		(end 364.965488 -32.774382)
		(width 0.1143)
		(layer "In9.Cu")
		(net "P3E_CPU0_PE1_PCH_CON_TXN<9>")
	)
	(segment
		(start 429.89754 -8.087868)
		(end 431.374804 -7.77367)
		(width 0.1143)
		(layer "In9.Cu")
		(net "P3E_CPU0_PE1_PCH_CON_TXN<9>")
	)
	(segment
		(start 410.473144 -7.167626)
		(end 415.516568 -8.238998)
		(width 0.1143)
		(layer "In9.Cu")
		(net "P3E_CPU0_PE1_PCH_CON_TXN<9>")
	)
	(segment
		(start 368.472212 -20.693888)
		(end 370.307362 -19.520662)
		(width 0.1143)
		(layer "In9.Cu")
		(net "P3E_CPU0_PE1_PCH_CON_TXN<9>")
	)
	(segment
		(start 330.860908 -57.94248)
		(end 333.93761 -52.265072)
		(width 0.1143)
		(layer "In9.Cu")
		(net "P3E_CPU0_PE1_PCH_CON_TXN<9>")
	)
	(segment
		(start 328.357484 -83.507326)
		(end 328.875644 -81.388458)
		(width 0.1143)
		(layer "In9.Cu")
		(net "P3E_CPU0_PE1_PCH_CON_TXN<9>")
	)
	(segment
		(start 328.108564 -106.89717)
		(end 328.108818 -106.89717)
		(width 0.1143)
		(layer "In9.Cu")
		(net "P3E_CPU0_PE1_PCH_CON_TXN<9>")
	)
	(segment
		(start 337.672426 -119.005604)
		(end 337.400138 -118.733316)
		(width 0.1143)
		(layer "In9.Cu")
		(net "P3E_CPU0_PE1_PCH_CON_TXN<9>")
	)
	(segment
		(start 428.70501 -7.83463)
		(end 429.89754 -8.087868)
		(width 0.1143)
		(layer "In9.Cu")
		(net "P3E_CPU0_PE1_PCH_CON_TXN<9>")
	)
	(segment
		(start 419.104318 -7.816088)
		(end 420.287704 -8.067548)
		(width 0.1143)
		(layer "In9.Cu")
		(net "P3E_CPU0_PE1_PCH_CON_TXN<9>")
	)
	(segment
		(start 328.045064 -77.480668)
		(end 328.354436 -76.024232)
		(width 0.1143)
		(layer "In9.Cu")
		(net "P3E_CPU0_PE1_PCH_CON_TXN<9>")
	)
	(segment
		(start 402.45284 -8.250428)
		(end 403.916134 -8.560308)
		(width 0.1143)
		(layer "In9.Cu")
		(net "P3E_CPU0_PE1_PCH_CON_TXN<9>")
	)
	(segment
		(start 328.354436 -76.024232)
		(end 328.03592 -74.523346)
		(width 0.1143)
		(layer "In9.Cu")
		(net "P3E_CPU0_PE1_PCH_CON_TXN<9>")
	)
	(segment
		(start 427.623732 -8.0645)
		(end 428.70501 -7.83463)
		(width 0.1143)
		(layer "In9.Cu")
		(net "P3E_CPU0_PE1_PCH_CON_TXN<9>")
	)
	(segment
		(start 365.658654 -27.283664)
		(end 367.239296 -26.230072)
		(width 0.1143)
		(layer "In9.Cu")
		(net "P3E_CPU0_PE1_PCH_CON_TXN<9>")
	)
	(segment
		(start 422.714928 -8.079486)
		(end 423.892472 -7.82955)
		(width 0.1143)
		(layer "In9.Cu")
		(net "P3E_CPU0_PE1_PCH_CON_TXN<9>")
	)
	(segment
		(start 424.987212 -8.062214)
		(end 426.3009 -7.783322)
		(width 0.1143)
		(layer "In9.Cu")
		(net "P3E_CPU0_PE1_PCH_CON_TXN<9>")
	)
	(segment
		(start 337.400138 -118.733316)
		(end 333.217266 -118.733316)
		(width 0.1143)
		(layer "In9.Cu")
		(net "P3E_CPU0_PE1_PCH_CON_TXN<9>")
	)
	(segment
		(start 403.916134 -8.560308)
		(end 410.473144 -7.167626)
		(width 0.1143)
		(layer "In9.Cu")
		(net "P3E_CPU0_PE1_PCH_CON_TXN<9>")
	)
	(segment
		(start 330.63688 -102.302564)
		(end 330.637896 -102.301548)
		(width 0.1143)
		(layer "In9.Cu")
		(net "P3E_CPU0_PE1_PCH_CON_TXN<9>")
	)
	(segment
		(start 391.743692 -12.084558)
		(end 400.139916 -10.29843)
		(width 0.1143)
		(layer "In9.Cu")
		(net "P3E_CPU0_PE1_PCH_CON_TXN<9>")
	)
	(segment
		(start 426.3009 -7.783322)
		(end 427.623732 -8.0645)
		(width 0.1143)
		(layer "In9.Cu")
		(net "P3E_CPU0_PE1_PCH_CON_TXN<9>")
	)
	(segment
		(start 434.133752 -8.523478)
		(end 434.594 -9.180068)
		(width 0.1143)
		(layer "In9.Cu")
		(net "P3E_CPU0_PE1_PCH_CON_TXN<9>")
	)
	(segment
		(start 357.17353 -46.799246)
		(end 359.510076 -45.26915)
		(width 0.1143)
		(layer "In9.Cu")
		(net "P3E_CPU0_PE1_PCH_CON_TXN<9>")
	)
	(segment
		(start 417.932108 -8.065008)
		(end 419.104318 -7.816088)
		(width 0.1143)
		(layer "In9.Cu")
		(net "P3E_CPU0_PE1_PCH_CON_TXN<9>")
	)
	(segment
		(start 376.506486 -13.208508)
		(end 379.48362 -12.577064)
		(width 0.1143)
		(layer "In9.Cu")
		(net "P3E_CPU0_PE1_PCH_CON_TXN<9>")
	)
	(segment
		(start 324.59295 -110.145576)
		(end 328.106786 -106.900726)
		(width 0.1143)
		(layer "In9.Cu")
		(net "P3E_CPU0_PE1_PCH_CON_TXN<9>")
	)
	(segment
		(start 432.580542 -10.078466)
		(end 432.378866 -10.078466)
		(width 0.1143)
		(layer "F.Cu")
		(net "P3E_CPU0_PE1_PCH_CON_TXN<8>")
	)
	(segment
		(start 432.218592 -9.918192)
		(end 432.218592 -8.91413)
		(width 0.1143)
		(layer "F.Cu")
		(net "P3E_CPU0_PE1_PCH_CON_TXN<8>")
	)
	(segment
		(start 432.475386 -8.657336)
		(end 432.475386 -7.789672)
		(width 0.1143)
		(layer "F.Cu")
		(net "P3E_CPU0_PE1_PCH_CON_TXN<8>")
	)
	(segment
		(start 332.01102 -118.5164)
		(end 331.2668 -118.5164)
		(width 0.1143)
		(layer "F.Cu")
		(net "P3E_CPU0_PE1_PCH_CON_TXN<8>")
	)
	(segment
		(start 432.218592 -8.91413)
		(end 432.475386 -8.657336)
		(width 0.1143)
		(layer "F.Cu")
		(net "P3E_CPU0_PE1_PCH_CON_TXN<8>")
	)
	(segment
		(start 432.378866 -10.078466)
		(end 432.218592 -9.918192)
		(width 0.1143)
		(layer "F.Cu")
		(net "P3E_CPU0_PE1_PCH_CON_TXN<8>")
	)
	(via
		(at 432.580542 -10.078466)
		(size 0.508)
		(drill 0.254)
		(layers "F.Cu" "B.Cu")
		(net "P3E_CPU0_PE1_PCH_CON_TXN<8>")
	)
	(via
		(at 331.2668 -118.5164)
		(size 0.508)
		(drill 0.254)
		(layers "F.Cu" "B.Cu")
		(net "P3E_CPU0_PE1_PCH_CON_TXN<8>")
	)
	(segment
		(start 331.297534 -102.503478)
		(end 331.392022 -101.261164)
		(width 0.1143)
		(layer "In9.Cu")
		(net "P3E_CPU0_PE1_PCH_CON_TXN<8>")
	)
	(segment
		(start 365.890048 -29.581856)
		(end 366.277144 -27.646884)
		(width 0.1143)
		(layer "In9.Cu")
		(net "P3E_CPU0_PE1_PCH_CON_TXN<8>")
	)
	(segment
		(start 408.99461 -8.141716)
		(end 409.349702 -8.37184)
		(width 0.1143)
		(layer "In9.Cu")
		(net "P3E_CPU0_PE1_PCH_CON_TXN<8>")
	)
	(segment
		(start 423.892472 -8.491728)
		(end 424.987212 -8.724392)
		(width 0.1143)
		(layer "In9.Cu")
		(net "P3E_CPU0_PE1_PCH_CON_TXN<8>")
	)
	(segment
		(start 370.53901 -21.336254)
		(end 374.601994 -15.24254)
		(width 0.1143)
		(layer "In9.Cu")
		(net "P3E_CPU0_PE1_PCH_CON_TXN<8>")
	)
	(segment
		(start 419.083744 -8.473948)
		(end 420.287704 -8.729726)
		(width 0.1143)
		(layer "In9.Cu")
		(net "P3E_CPU0_PE1_PCH_CON_TXN<8>")
	)
	(segment
		(start 420.287704 -8.729726)
		(end 421.472614 -8.477758)
		(width 0.1143)
		(layer "In9.Cu")
		(net "P3E_CPU0_PE1_PCH_CON_TXN<8>")
	)
	(segment
		(start 379.45568 -13.232638)
		(end 380.280926 -13.407898)
		(width 0.1143)
		(layer "In9.Cu")
		(net "P3E_CPU0_PE1_PCH_CON_TXN<8>")
	)
	(segment
		(start 402.323046 -10.49655)
		(end 402.328634 -10.495534)
		(width 0.1143)
		(layer "In9.Cu")
		(net "P3E_CPU0_PE1_PCH_CON_TXN<8>")
	)
	(segment
		(start 331.2668 -118.5164)
		(end 331.2668 -118.13286)
		(width 0.1143)
		(layer "In9.Cu")
		(net "P3E_CPU0_PE1_PCH_CON_TXN<8>")
	)
	(segment
		(start 402.330412 -10.49528)
		(end 402.584158 -10.44067)
		(width 0.1143)
		(layer "In9.Cu")
		(net "P3E_CPU0_PE1_PCH_CON_TXN<8>")
	)
	(segment
		(start 409.928314 -8.707374)
		(end 409.831794 -8.256016)
		(width 0.1143)
		(layer "In9.Cu")
		(net "P3E_CPU0_PE1_PCH_CON_TXN<8>")
	)
	(segment
		(start 403.356318 -9.097518)
		(end 403.694392 -9.317228)
		(width 0.1143)
		(layer "In9.Cu")
		(net "P3E_CPU0_PE1_PCH_CON_TXN<8>")
	)
	(segment
		(start 417.911534 -8.722868)
		(end 419.083744 -8.473948)
		(width 0.1143)
		(layer "In9.Cu")
		(net "P3E_CPU0_PE1_PCH_CON_TXN<8>")
	)
	(segment
		(start 405.67991 -8.847074)
		(end 408.99461 -8.141716)
		(width 0.1143)
		(layer "In9.Cu")
		(net "P3E_CPU0_PE1_PCH_CON_TXN<8>")
	)
	(segment
		(start 376.757692 -13.8049)
		(end 379.45568 -13.232638)
		(width 0.1143)
		(layer "In9.Cu")
		(net "P3E_CPU0_PE1_PCH_CON_TXN<8>")
	)
	(segment
		(start 340.689946 -51.962812)
		(end 357.456994 -47.388018)
		(width 0.1143)
		(layer "In9.Cu")
		(net "P3E_CPU0_PE1_PCH_CON_TXN<8>")
	)
	(segment
		(start 387.536182 -11.867134)
		(end 391.709656 -12.754102)
		(width 0.1143)
		(layer "In9.Cu")
		(net "P3E_CPU0_PE1_PCH_CON_TXN<8>")
	)
	(segment
		(start 328.696828 -77.480668)
		(end 329.005946 -76.024232)
		(width 0.1143)
		(layer "In9.Cu")
		(net "P3E_CPU0_PE1_PCH_CON_TXN<8>")
	)
	(segment
		(start 404.951946 -9.937242)
		(end 405.67991 -8.847074)
		(width 0.1143)
		(layer "In9.Cu")
		(net "P3E_CPU0_PE1_PCH_CON_TXN<8>")
	)
	(segment
		(start 328.687684 -74.523346)
		(end 329.240134 -71.92264)
		(width 0.1143)
		(layer "In9.Cu")
		(net "P3E_CPU0_PE1_PCH_CON_TXN<8>")
	)
	(segment
		(start 402.857462 -9.203944)
		(end 403.356318 -9.097518)
		(width 0.1143)
		(layer "In9.Cu")
		(net "P3E_CPU0_PE1_PCH_CON_TXN<8>")
	)
	(segment
		(start 329.54595 -81.478628)
		(end 328.696828 -77.480668)
		(width 0.1143)
		(layer "In9.Cu")
		(net "P3E_CPU0_PE1_PCH_CON_TXN<8>")
	)
	(segment
		(start 431.330862 -8.435848)
		(end 431.98288 -8.626348)
		(width 0.1143)
		(layer "In9.Cu")
		(net "P3E_CPU0_PE1_PCH_CON_TXN<8>")
	)
	(segment
		(start 403.85238 -10.054082)
		(end 403.987762 -10.14222)
		(width 0.1143)
		(layer "In9.Cu")
		(net "P3E_CPU0_PE1_PCH_CON_TXN<8>")
	)
	(segment
		(start 338.32546 -51.482244)
		(end 340.688676 -51.96332)
		(width 0.1143)
		(layer "In9.Cu")
		(net "P3E_CPU0_PE1_PCH_CON_TXN<8>")
	)
	(segment
		(start 374.601994 -15.24254)
		(end 376.757692 -13.8049)
		(width 0.1143)
		(layer "In9.Cu")
		(net "P3E_CPU0_PE1_PCH_CON_TXN<8>")
	)
	(segment
		(start 432.2572 -9.9314)
		(end 432.404266 -10.078466)
		(width 0.1143)
		(layer "In9.Cu")
		(net "P3E_CPU0_PE1_PCH_CON_TXN<8>")
	)
	(segment
		(start 331.1525 -118.01856)
		(end 327.424796 -118.01856)
		(width 0.1143)
		(layer "In9.Cu")
		(net "P3E_CPU0_PE1_PCH_CON_TXN<8>")
	)
	(segment
		(start 401.069302 -10.646156)
		(end 400.979386 -10.225786)
		(width 0.1143)
		(layer "In9.Cu")
		(net "P3E_CPU0_PE1_PCH_CON_TXN<8>")
	)
	(segment
		(start 360.007408 -45.71746)
		(end 360.01071 -45.715174)
		(width 0.1143)
		(layer "In9.Cu")
		(net "P3E_CPU0_PE1_PCH_CON_TXN<8>")
	)
	(segment
		(start 410.050996 -7.91718)
		(end 410.445712 -7.833106)
		(width 0.1143)
		(layer "In9.Cu")
		(net "P3E_CPU0_PE1_PCH_CON_TXN<8>")
	)
	(segment
		(start 366.148366 -30.875224)
		(end 365.890048 -29.581856)
		(width 0.1143)
		(layer "In9.Cu")
		(net "P3E_CPU0_PE1_PCH_CON_TXN<8>")
	)
	(segment
		(start 402.769324 -10.156444)
		(end 402.637752 -9.542018)
		(width 0.1143)
		(layer "In9.Cu")
		(net "P3E_CPU0_PE1_PCH_CON_TXN<8>")
	)
	(segment
		(start 400.979386 -10.225786)
		(end 401.199096 -9.887712)
		(width 0.1143)
		(layer "In9.Cu")
		(net "P3E_CPU0_PE1_PCH_CON_TXN<8>")
	)
	(segment
		(start 334.704944 -52.545234)
		(end 335.337404 -52.09032)
		(width 0.1143)
		(layer "In9.Cu")
		(net "P3E_CPU0_PE1_PCH_CON_TXN<8>")
	)
	(segment
		(start 403.987762 -10.14222)
		(end 404.951946 -9.937242)
		(width 0.1143)
		(layer "In9.Cu")
		(net "P3E_CPU0_PE1_PCH_CON_TXN<8>")
	)
	(segment
		(start 331.361288 -93.727524)
		(end 329.125834 -83.198716)
		(width 0.1143)
		(layer "In9.Cu")
		(net "P3E_CPU0_PE1_PCH_CON_TXN<8>")
	)
	(segment
		(start 427.598078 -8.72109)
		(end 428.679356 -8.49122)
		(width 0.1143)
		(layer "In9.Cu")
		(net "P3E_CPU0_PE1_PCH_CON_TXN<8>")
	)
	(segment
		(start 422.714928 -8.741664)
		(end 423.892472 -8.491728)
		(width 0.1143)
		(layer "In9.Cu")
		(net "P3E_CPU0_PE1_PCH_CON_TXN<8>")
	)
	(segment
		(start 360.01071 -45.715174)
		(end 361.30992 -43.265852)
		(width 0.1143)
		(layer "In9.Cu")
		(net "P3E_CPU0_PE1_PCH_CON_TXN<8>")
	)
	(segment
		(start 361.30992 -43.265852)
		(end 362.665772 -36.68014)
		(width 0.1143)
		(layer "In9.Cu")
		(net "P3E_CPU0_PE1_PCH_CON_TXN<8>")
	)
	(segment
		(start 367.800636 -26.63571)
		(end 368.71021 -22.554946)
		(width 0.1143)
		(layer "In9.Cu")
		(net "P3E_CPU0_PE1_PCH_CON_TXN<8>")
	)
	(segment
		(start 429.874934 -8.74522)
		(end 431.330862 -8.435848)
		(width 0.1143)
		(layer "In9.Cu")
		(net "P3E_CPU0_PE1_PCH_CON_TXN<8>")
	)
	(segment
		(start 409.578302 -8.898128)
		(end 409.840938 -8.842502)
		(width 0.1143)
		(layer "In9.Cu")
		(net "P3E_CPU0_PE1_PCH_CON_TXN<8>")
	)
	(segment
		(start 380.280926 -13.407898)
		(end 387.536182 -11.867134)
		(width 0.1143)
		(layer "In9.Cu")
		(net "P3E_CPU0_PE1_PCH_CON_TXN<8>")
	)
	(segment
		(start 366.277144 -27.646884)
		(end 367.800636 -26.63571)
		(width 0.1143)
		(layer "In9.Cu")
		(net "P3E_CPU0_PE1_PCH_CON_TXN<8>")
	)
	(segment
		(start 335.337404 -52.09032)
		(end 338.32546 -51.482244)
		(width 0.1143)
		(layer "In9.Cu")
		(net "P3E_CPU0_PE1_PCH_CON_TXN<8>")
	)
	(segment
		(start 331.365098 -58.70829)
		(end 334.704944 -52.545234)
		(width 0.1143)
		(layer "In9.Cu")
		(net "P3E_CPU0_PE1_PCH_CON_TXN<8>")
	)
	(segment
		(start 402.036026 -10.000996)
		(end 402.112734 -10.35939)
		(width 0.1143)
		(layer "In9.Cu")
		(net "P3E_CPU0_PE1_PCH_CON_TXN<8>")
	)
	(segment
		(start 432.404266 -10.078466)
		(end 432.580542 -10.078466)
		(width 0.1143)
		(layer "In9.Cu")
		(net "P3E_CPU0_PE1_PCH_CON_TXN<8>")
	)
	(segment
		(start 402.584158 -10.44067)
		(end 402.769324 -10.156444)
		(width 0.1143)
		(layer "In9.Cu")
		(net "P3E_CPU0_PE1_PCH_CON_TXN<8>")
	)
	(segment
		(start 428.679356 -8.49122)
		(end 429.874934 -8.74522)
		(width 0.1143)
		(layer "In9.Cu")
		(net "P3E_CPU0_PE1_PCH_CON_TXN<8>")
	)
	(segment
		(start 403.694392 -9.317228)
		(end 403.85238 -10.054082)
		(width 0.1143)
		(layer "In9.Cu")
		(net "P3E_CPU0_PE1_PCH_CON_TXN<8>")
	)
	(segment
		(start 328.952098 -70.566534)
		(end 331.365098 -58.70829)
		(width 0.1143)
		(layer "In9.Cu")
		(net "P3E_CPU0_PE1_PCH_CON_TXN<8>")
	)
	(segment
		(start 328.396346 -107.777026)
		(end 331.297534 -102.503478)
		(width 0.1143)
		(layer "In9.Cu")
		(net "P3E_CPU0_PE1_PCH_CON_TXN<8>")
	)
	(segment
		(start 391.709656 -12.754102)
		(end 400.981672 -10.781792)
		(width 0.1143)
		(layer "In9.Cu")
		(net "P3E_CPU0_PE1_PCH_CON_TXN<8>")
	)
	(segment
		(start 340.688676 -51.96332)
		(end 340.689946 -51.962812)
		(width 0.1143)
		(layer "In9.Cu")
		(net "P3E_CPU0_PE1_PCH_CON_TXN<8>")
	)
	(segment
		(start 368.71021 -22.554946)
		(end 370.53901 -21.336254)
		(width 0.1143)
		(layer "In9.Cu")
		(net "P3E_CPU0_PE1_PCH_CON_TXN<8>")
	)
	(segment
		(start 415.480246 -8.901684)
		(end 417.117276 -8.553958)
		(width 0.1143)
		(layer "In9.Cu")
		(net "P3E_CPU0_PE1_PCH_CON_TXN<8>")
	)
	(segment
		(start 402.112734 -10.35939)
		(end 402.323046 -10.49655)
		(width 0.1143)
		(layer "In9.Cu")
		(net "P3E_CPU0_PE1_PCH_CON_TXN<8>")
	)
	(segment
		(start 410.445712 -7.833106)
		(end 415.480246 -8.901684)
		(width 0.1143)
		(layer "In9.Cu")
		(net "P3E_CPU0_PE1_PCH_CON_TXN<8>")
	)
	(segment
		(start 402.637752 -9.542018)
		(end 402.857462 -9.203944)
		(width 0.1143)
		(layer "In9.Cu")
		(net "P3E_CPU0_PE1_PCH_CON_TXN<8>")
	)
	(segment
		(start 432.2572 -8.900668)
		(end 432.2572 -9.9314)
		(width 0.1143)
		(layer "In9.Cu")
		(net "P3E_CPU0_PE1_PCH_CON_TXN<8>")
	)
	(segment
		(start 409.840938 -8.842502)
		(end 409.928314 -8.707374)
		(width 0.1143)
		(layer "In9.Cu")
		(net "P3E_CPU0_PE1_PCH_CON_TXN<8>")
	)
	(segment
		(start 325.709788 -110.463584)
		(end 328.396346 -107.777026)
		(width 0.1143)
		(layer "In9.Cu")
		(net "P3E_CPU0_PE1_PCH_CON_TXN<8>")
	)
	(segment
		(start 431.98288 -8.626348)
		(end 432.2572 -8.900668)
		(width 0.1143)
		(layer "In9.Cu")
		(net "P3E_CPU0_PE1_PCH_CON_TXN<8>")
	)
	(segment
		(start 325.709788 -116.303552)
		(end 325.709788 -110.463584)
		(width 0.1143)
		(layer "In9.Cu")
		(net "P3E_CPU0_PE1_PCH_CON_TXN<8>")
	)
	(segment
		(start 402.328634 -10.495534)
		(end 402.330412 -10.49528)
		(width 0.1143)
		(layer "In9.Cu")
		(net "P3E_CPU0_PE1_PCH_CON_TXN<8>")
	)
	(segment
		(start 357.456994 -47.388018)
		(end 360.007408 -45.71746)
		(width 0.1143)
		(layer "In9.Cu")
		(net "P3E_CPU0_PE1_PCH_CON_TXN<8>")
	)
	(segment
		(start 362.665772 -36.68014)
		(end 365.746538 -32.883348)
		(width 0.1143)
		(layer "In9.Cu")
		(net "P3E_CPU0_PE1_PCH_CON_TXN<8>")
	)
	(segment
		(start 401.199096 -9.887712)
		(end 401.697952 -9.781286)
		(width 0.1143)
		(layer "In9.Cu")
		(net "P3E_CPU0_PE1_PCH_CON_TXN<8>")
	)
	(segment
		(start 331.603096 -98.484182)
		(end 330.976986 -95.53575)
		(width 0.1143)
		(layer "In9.Cu")
		(net "P3E_CPU0_PE1_PCH_CON_TXN<8>")
	)
	(segment
		(start 331.2668 -118.13286)
		(end 331.1525 -118.01856)
		(width 0.1143)
		(layer "In9.Cu")
		(net "P3E_CPU0_PE1_PCH_CON_TXN<8>")
	)
	(segment
		(start 365.746538 -32.883348)
		(end 366.148366 -30.875224)
		(width 0.1143)
		(layer "In9.Cu")
		(net "P3E_CPU0_PE1_PCH_CON_TXN<8>")
	)
	(segment
		(start 327.424796 -118.01856)
		(end 325.709788 -116.303552)
		(width 0.1143)
		(layer "In9.Cu")
		(net "P3E_CPU0_PE1_PCH_CON_TXN<8>")
	)
	(segment
		(start 330.976986 -95.53575)
		(end 331.361288 -93.727524)
		(width 0.1143)
		(layer "In9.Cu")
		(net "P3E_CPU0_PE1_PCH_CON_TXN<8>")
	)
	(segment
		(start 401.697952 -9.781286)
		(end 402.036026 -10.000996)
		(width 0.1143)
		(layer "In9.Cu")
		(net "P3E_CPU0_PE1_PCH_CON_TXN<8>")
	)
	(segment
		(start 409.443428 -8.810752)
		(end 409.578302 -8.898128)
		(width 0.1143)
		(layer "In9.Cu")
		(net "P3E_CPU0_PE1_PCH_CON_TXN<8>")
	)
	(segment
		(start 417.117276 -8.553958)
		(end 417.911534 -8.722868)
		(width 0.1143)
		(layer "In9.Cu")
		(net "P3E_CPU0_PE1_PCH_CON_TXN<8>")
	)
	(segment
		(start 426.3009 -8.4455)
		(end 427.598078 -8.72109)
		(width 0.1143)
		(layer "In9.Cu")
		(net "P3E_CPU0_PE1_PCH_CON_TXN<8>")
	)
	(segment
		(start 409.349702 -8.37184)
		(end 409.443428 -8.810752)
		(width 0.1143)
		(layer "In9.Cu")
		(net "P3E_CPU0_PE1_PCH_CON_TXN<8>")
	)
	(segment
		(start 409.831794 -8.256016)
		(end 410.050996 -7.91718)
		(width 0.1143)
		(layer "In9.Cu")
		(net "P3E_CPU0_PE1_PCH_CON_TXN<8>")
	)
	(segment
		(start 424.987212 -8.724392)
		(end 426.3009 -8.4455)
		(width 0.1143)
		(layer "In9.Cu")
		(net "P3E_CPU0_PE1_PCH_CON_TXN<8>")
	)
	(segment
		(start 329.240134 -71.92264)
		(end 328.952098 -70.566534)
		(width 0.1143)
		(layer "In9.Cu")
		(net "P3E_CPU0_PE1_PCH_CON_TXN<8>")
	)
	(segment
		(start 329.005946 -76.024232)
		(end 328.687684 -74.523346)
		(width 0.1143)
		(layer "In9.Cu")
		(net "P3E_CPU0_PE1_PCH_CON_TXN<8>")
	)
	(segment
		(start 331.392022 -101.261164)
		(end 331.603096 -98.484182)
		(width 0.1143)
		(layer "In9.Cu")
		(net "P3E_CPU0_PE1_PCH_CON_TXN<8>")
	)
	(segment
		(start 421.472614 -8.477758)
		(end 422.714928 -8.741664)
		(width 0.1143)
		(layer "In9.Cu")
		(net "P3E_CPU0_PE1_PCH_CON_TXN<8>")
	)
	(segment
		(start 400.981672 -10.781792)
		(end 401.069302 -10.646156)
		(width 0.1143)
		(layer "In9.Cu")
		(net "P3E_CPU0_PE1_PCH_CON_TXN<8>")
	)
	(segment
		(start 329.125834 -83.198716)
		(end 329.54595 -81.478628)
		(width 0.1143)
		(layer "In9.Cu")
		(net "P3E_CPU0_PE1_PCH_CON_TXN<8>")
	)
	(segment
		(start 319.7225 -124.587)
		(end 319.14592 -124.587)
		(width 0.1143)
		(layer "F.Cu")
		(net "P3E_CPU0_PE1_PCH_CON_TXN<15>")
	)
	(segment
		(start 453.727566 -9.144762)
		(end 453.727566 -9.007348)
		(width 0.1143)
		(layer "F.Cu")
		(net "P3E_CPU0_PE1_PCH_CON_TXN<15>")
	)
	(segment
		(start 445.434466 -10.080752)
		(end 445.653414 -10.72007)
		(width 0.1143)
		(layer "F.Cu")
		(net "P3E_CPU0_PE1_PCH_CON_TXN<15>")
	)
	(segment
		(start 445.653414 -10.72007)
		(end 446.541144 -11.6078)
		(width 0.1143)
		(layer "F.Cu")
		(net "P3E_CPU0_PE1_PCH_CON_TXN<15>")
	)
	(segment
		(start 446.541144 -11.6078)
		(end 451.264528 -11.6078)
		(width 0.1143)
		(layer "F.Cu")
		(net "P3E_CPU0_PE1_PCH_CON_TXN<15>")
	)
	(segment
		(start 453.727566 -9.007348)
		(end 454.077578 -8.657336)
		(width 0.1143)
		(layer "F.Cu")
		(net "P3E_CPU0_PE1_PCH_CON_TXN<15>")
	)
	(segment
		(start 445.008 -9.87171)
		(end 445.434466 -10.080752)
		(width 0.1143)
		(layer "F.Cu")
		(net "P3E_CPU0_PE1_PCH_CON_TXN<15>")
	)
	(segment
		(start 319.14592 -124.587)
		(end 319.10528 -124.62764)
		(width 0.1143)
		(layer "F.Cu")
		(net "P3E_CPU0_PE1_PCH_CON_TXN<15>")
	)
	(segment
		(start 451.264528 -11.6078)
		(end 453.727566 -9.144762)
		(width 0.1143)
		(layer "F.Cu")
		(net "P3E_CPU0_PE1_PCH_CON_TXN<15>")
	)
	(segment
		(start 454.077578 -8.657336)
		(end 454.077578 -7.789672)
		(width 0.1143)
		(layer "F.Cu")
		(net "P3E_CPU0_PE1_PCH_CON_TXN<15>")
	)
	(via
		(at 319.10528 -124.62764)
		(size 0.508)
		(drill 0.254)
		(layers "F.Cu" "B.Cu")
		(net "P3E_CPU0_PE1_PCH_CON_TXN<15>")
	)
	(via
		(at 445.008 -9.87171)
		(size 0.508)
		(drill 0.254)
		(layers "F.Cu" "B.Cu")
		(net "P3E_CPU0_PE1_PCH_CON_TXN<15>")
	)
	(segment
		(start 338.32546 -46.674024)
		(end 333.364078 -47.683674)
		(width 0.1143)
		(layer "In9.Cu")
		(net "P3E_CPU0_PE1_PCH_CON_TXN<15>")
	)
	(segment
		(start 445.729868 -10.336784)
		(end 446.763394 -10.336784)
		(width 0.1143)
		(layer "In9.Cu")
		(net "P3E_CPU0_PE1_PCH_CON_TXN<15>")
	)
	(segment
		(start 447.410586 -9.530842)
		(end 447.55308 -8.878824)
		(width 0.1143)
		(layer "In9.Cu")
		(net "P3E_CPU0_PE1_PCH_CON_TXN<15>")
	)
	(segment
		(start 446.85331 -7.184136)
		(end 446.409826 -6.738874)
		(width 0.1143)
		(layer "In9.Cu")
		(net "P3E_CPU0_PE1_PCH_CON_TXN<15>")
	)
	(segment
		(start 318.82334 -124.20854)
		(end 319.10528 -124.49048)
		(width 0.1143)
		(layer "In9.Cu")
		(net "P3E_CPU0_PE1_PCH_CON_TXN<15>")
	)
	(segment
		(start 447.55308 -8.878824)
		(end 446.85331 -7.184136)
		(width 0.1143)
		(layer "In9.Cu")
		(net "P3E_CPU0_PE1_PCH_CON_TXN<15>")
	)
	(segment
		(start 421.558466 -3.8608)
		(end 420.373302 -4.112768)
		(width 0.1143)
		(layer "In9.Cu")
		(net "P3E_CPU0_PE1_PCH_CON_TXN<15>")
	)
	(segment
		(start 326.540876 -101.261164)
		(end 326.4662 -101.3968)
		(width 0.1143)
		(layer "In9.Cu")
		(net "P3E_CPU0_PE1_PCH_CON_TXN<15>")
	)
	(segment
		(start 417.524692 -1.625092)
		(end 416.823144 -0.588772)
		(width 0.1143)
		(layer "In9.Cu")
		(net "P3E_CPU0_PE1_PCH_CON_TXN<15>")
	)
	(segment
		(start 326.6186 -101.11994)
		(end 326.540876 -101.261164)
		(width 0.1143)
		(layer "In9.Cu")
		(net "P3E_CPU0_PE1_PCH_CON_TXN<15>")
	)
	(segment
		(start 365.391954 -16.004794)
		(end 363.764576 -23.800816)
		(width 0.1143)
		(layer "In9.Cu")
		(net "P3E_CPU0_PE1_PCH_CON_TXN<15>")
	)
	(segment
		(start 324.13448 -77.480922)
		(end 324.849998 -80.8482)
		(width 0.1143)
		(layer "In9.Cu")
		(net "P3E_CPU0_PE1_PCH_CON_TXN<15>")
	)
	(segment
		(start 379.731016 -7.564374)
		(end 377.22556 -8.09625)
		(width 0.1143)
		(layer "In9.Cu")
		(net "P3E_CPU0_PE1_PCH_CON_TXN<15>")
	)
	(segment
		(start 405.60498 -1.517396)
		(end 404.357586 -1.267714)
		(width 0.1143)
		(layer "In9.Cu")
		(net "P3E_CPU0_PE1_PCH_CON_TXN<15>")
	)
	(segment
		(start 315.329062 -120.796304)
		(end 317.22822 -123.570492)
		(width 0.1143)
		(layer "In9.Cu")
		(net "P3E_CPU0_PE1_PCH_CON_TXN<15>")
	)
	(segment
		(start 319.10528 -124.49048)
		(end 319.10528 -124.62764)
		(width 0.1143)
		(layer "In9.Cu")
		(net "P3E_CPU0_PE1_PCH_CON_TXN<15>")
	)
	(segment
		(start 419.073838 -2.75717)
		(end 417.524692 -1.625092)
		(width 0.1143)
		(layer "In9.Cu")
		(net "P3E_CPU0_PE1_PCH_CON_TXN<15>")
	)
	(segment
		(start 406.481026 -1.213104)
		(end 405.60498 -1.517396)
		(width 0.1143)
		(layer "In9.Cu")
		(net "P3E_CPU0_PE1_PCH_CON_TXN<15>")
	)
	(segment
		(start 355.49459 -43.253914)
		(end 340.83117 -47.183802)
		(width 0.1143)
		(layer "In9.Cu")
		(net "P3E_CPU0_PE1_PCH_CON_TXN<15>")
	)
	(segment
		(start 398.372584 -1.931924)
		(end 396.7607 -2.254758)
		(width 0.1143)
		(layer "In9.Cu")
		(net "P3E_CPU0_PE1_PCH_CON_TXN<15>")
	)
	(segment
		(start 447.276728 -9.82345)
		(end 447.410586 -9.530842)
		(width 0.1143)
		(layer "In9.Cu")
		(net "P3E_CPU0_PE1_PCH_CON_TXN<15>")
	)
	(segment
		(start 445.319912 -6.486906)
		(end 439.676286 -6.486906)
		(width 0.1143)
		(layer "In9.Cu")
		(net "P3E_CPU0_PE1_PCH_CON_TXN<15>")
	)
	(segment
		(start 325.34606 -63.45555)
		(end 324.139306 -69.386704)
		(width 0.1143)
		(layer "In9.Cu")
		(net "P3E_CPU0_PE1_PCH_CON_TXN<15>")
	)
	(segment
		(start 433.674012 -3.847846)
		(end 432.586892 -4.07924)
		(width 0.1143)
		(layer "In9.Cu")
		(net "P3E_CPU0_PE1_PCH_CON_TXN<15>")
	)
	(segment
		(start 324.125336 -74.522838)
		(end 324.443852 -76.023978)
		(width 0.1143)
		(layer "In9.Cu")
		(net "P3E_CPU0_PE1_PCH_CON_TXN<15>")
	)
	(segment
		(start 363.764576 -23.800816)
		(end 361.928664 -25.024842)
		(width 0.1143)
		(layer "In9.Cu")
		(net "P3E_CPU0_PE1_PCH_CON_TXN<15>")
	)
	(segment
		(start 361.12069 -29.06522)
		(end 361.109514 -29.12237)
		(width 0.1143)
		(layer "In9.Cu")
		(net "P3E_CPU0_PE1_PCH_CON_TXN<15>")
	)
	(segment
		(start 446.763394 -10.336784)
		(end 447.276728 -9.82345)
		(width 0.1143)
		(layer "In9.Cu")
		(net "P3E_CPU0_PE1_PCH_CON_TXN<15>")
	)
	(segment
		(start 324.443852 -76.023978)
		(end 324.13448 -77.480922)
		(width 0.1143)
		(layer "In9.Cu")
		(net "P3E_CPU0_PE1_PCH_CON_TXN<15>")
	)
	(segment
		(start 429.893476 -4.114038)
		(end 428.745142 -3.870198)
		(width 0.1143)
		(layer "In9.Cu")
		(net "P3E_CPU0_PE1_PCH_CON_TXN<15>")
	)
	(segment
		(start 358.482138 -34.345372)
		(end 356.986332 -41.61282)
		(width 0.1143)
		(layer "In9.Cu")
		(net "P3E_CPU0_PE1_PCH_CON_TXN<15>")
	)
	(segment
		(start 415.586926 -0.122174)
		(end 414.278572 -0.47244)
		(width 0.1143)
		(layer "In9.Cu")
		(net "P3E_CPU0_PE1_PCH_CON_TXN<15>")
	)
	(segment
		(start 326.280018 -95.250508)
		(end 326.63892 -96.940624)
		(width 0.1143)
		(layer "In9.Cu")
		(net "P3E_CPU0_PE1_PCH_CON_TXN<15>")
	)
	(segment
		(start 361.120944 -29.06522)
		(end 361.12069 -29.06522)
		(width 0.1143)
		(layer "In9.Cu")
		(net "P3E_CPU0_PE1_PCH_CON_TXN<15>")
	)
	(segment
		(start 408.953716 -0.004064)
		(end 407.725372 -0.383032)
		(width 0.1143)
		(layer "In9.Cu")
		(net "P3E_CPU0_PE1_PCH_CON_TXN<15>")
	)
	(segment
		(start 446.409826 -6.738874)
		(end 445.319912 -6.486906)
		(width 0.1143)
		(layer "In9.Cu")
		(net "P3E_CPU0_PE1_PCH_CON_TXN<15>")
	)
	(segment
		(start 369.598956 -8.154416)
		(end 365.391954 -16.004794)
		(width 0.1143)
		(layer "In9.Cu")
		(net "P3E_CPU0_PE1_PCH_CON_TXN<15>")
	)
	(segment
		(start 445.008 -9.87171)
		(end 445.264794 -9.87171)
		(width 0.1143)
		(layer "In9.Cu")
		(net "P3E_CPU0_PE1_PCH_CON_TXN<15>")
	)
	(segment
		(start 422.748456 -4.113784)
		(end 421.558466 -3.8608)
		(width 0.1143)
		(layer "In9.Cu")
		(net "P3E_CPU0_PE1_PCH_CON_TXN<15>")
	)
	(segment
		(start 318.150748 -124.20854)
		(end 318.82334 -124.20854)
		(width 0.1143)
		(layer "In9.Cu")
		(net "P3E_CPU0_PE1_PCH_CON_TXN<15>")
	)
	(segment
		(start 414.278572 -0.47244)
		(end 413.083756 -0.1651)
		(width 0.1143)
		(layer "In9.Cu")
		(net "P3E_CPU0_PE1_PCH_CON_TXN<15>")
	)
	(segment
		(start 399.702528 -2.197608)
		(end 398.372584 -1.931924)
		(width 0.1143)
		(layer "In9.Cu")
		(net "P3E_CPU0_PE1_PCH_CON_TXN<15>")
	)
	(segment
		(start 427.664372 -4.100068)
		(end 426.407834 -3.83286)
		(width 0.1143)
		(layer "In9.Cu")
		(net "P3E_CPU0_PE1_PCH_CON_TXN<15>")
	)
	(segment
		(start 325.636128 -57.898284)
		(end 325.739506 -58.411618)
		(width 0.1143)
		(layer "In9.Cu")
		(net "P3E_CPU0_PE1_PCH_CON_TXN<15>")
	)
	(segment
		(start 326.481948 -94.300548)
		(end 326.4662 -94.374716)
		(width 0.1143)
		(layer "In9.Cu")
		(net "P3E_CPU0_PE1_PCH_CON_TXN<15>")
	)
	(segment
		(start 325.452486 -59.846718)
		(end 325.944484 -62.307724)
		(width 0.1143)
		(layer "In9.Cu")
		(net "P3E_CPU0_PE1_PCH_CON_TXN<15>")
	)
	(segment
		(start 416.823144 -0.588772)
		(end 415.586926 -0.122174)
		(width 0.1143)
		(layer "In9.Cu")
		(net "P3E_CPU0_PE1_PCH_CON_TXN<15>")
	)
	(segment
		(start 360.989626 -31.2547)
		(end 358.482138 -34.345372)
		(width 0.1143)
		(layer "In9.Cu")
		(net "P3E_CPU0_PE1_PCH_CON_TXN<15>")
	)
	(segment
		(start 315.329062 -114.834924)
		(end 315.329062 -120.796304)
		(width 0.1143)
		(layer "In9.Cu")
		(net "P3E_CPU0_PE1_PCH_CON_TXN<15>")
	)
	(segment
		(start 387.528816 -2.365756)
		(end 379.731016 -7.564374)
		(width 0.1143)
		(layer "In9.Cu")
		(net "P3E_CPU0_PE1_PCH_CON_TXN<15>")
	)
	(segment
		(start 426.407834 -3.83286)
		(end 425.093638 -4.112006)
		(width 0.1143)
		(layer "In9.Cu")
		(net "P3E_CPU0_PE1_PCH_CON_TXN<15>")
	)
	(segment
		(start 371.327172 -7.808722)
		(end 369.598956 -8.154416)
		(width 0.1143)
		(layer "In9.Cu")
		(net "P3E_CPU0_PE1_PCH_CON_TXN<15>")
	)
	(segment
		(start 419.66769 -3.822954)
		(end 419.073838 -2.75717)
		(width 0.1143)
		(layer "In9.Cu")
		(net "P3E_CPU0_PE1_PCH_CON_TXN<15>")
	)
	(segment
		(start 326.4662 -94.374716)
		(end 326.280018 -95.250508)
		(width 0.1143)
		(layer "In9.Cu")
		(net "P3E_CPU0_PE1_PCH_CON_TXN<15>")
	)
	(segment
		(start 324.849998 -80.8482)
		(end 324.194678 -83.527646)
		(width 0.1143)
		(layer "In9.Cu")
		(net "P3E_CPU0_PE1_PCH_CON_TXN<15>")
	)
	(segment
		(start 361.26293 -29.889196)
		(end 360.989626 -31.2547)
		(width 0.1143)
		(layer "In9.Cu")
		(net "P3E_CPU0_PE1_PCH_CON_TXN<15>")
	)
	(segment
		(start 325.060564 -56.674512)
		(end 325.118476 -57.122314)
		(width 0.1143)
		(layer "In9.Cu")
		(net "P3E_CPU0_PE1_PCH_CON_TXN<15>")
	)
	(segment
		(start 356.446836 -42.629836)
		(end 355.49459 -43.253914)
		(width 0.1143)
		(layer "In9.Cu")
		(net "P3E_CPU0_PE1_PCH_CON_TXN<15>")
	)
	(segment
		(start 356.986332 -41.61282)
		(end 356.446836 -42.629836)
		(width 0.1143)
		(layer "In9.Cu")
		(net "P3E_CPU0_PE1_PCH_CON_TXN<15>")
	)
	(segment
		(start 411.299152 -0.706882)
		(end 408.953716 -0.004064)
		(width 0.1143)
		(layer "In9.Cu")
		(net "P3E_CPU0_PE1_PCH_CON_TXN<15>")
	)
	(segment
		(start 325.944484 -62.307724)
		(end 325.87311 -62.65799)
		(width 0.1143)
		(layer "In9.Cu")
		(net "P3E_CPU0_PE1_PCH_CON_TXN<15>")
	)
	(segment
		(start 327.92543 -51.596036)
		(end 325.47052 -55.277004)
		(width 0.1143)
		(layer "In9.Cu")
		(net "P3E_CPU0_PE1_PCH_CON_TXN<15>")
	)
	(segment
		(start 324.677786 -71.92264)
		(end 324.125336 -74.522838)
		(width 0.1143)
		(layer "In9.Cu")
		(net "P3E_CPU0_PE1_PCH_CON_TXN<15>")
	)
	(segment
		(start 324.194678 -83.527646)
		(end 326.481948 -94.300548)
		(width 0.1143)
		(layer "In9.Cu")
		(net "P3E_CPU0_PE1_PCH_CON_TXN<15>")
	)
	(segment
		(start 374.801638 -8.09879)
		(end 373.363236 -7.811262)
		(width 0.1143)
		(layer "In9.Cu")
		(net "P3E_CPU0_PE1_PCH_CON_TXN<15>")
	)
	(segment
		(start 392.977116 -2.148078)
		(end 390.796272 -1.71196)
		(width 0.1143)
		(layer "In9.Cu")
		(net "P3E_CPU0_PE1_PCH_CON_TXN<15>")
	)
	(segment
		(start 425.093638 -4.112006)
		(end 423.926254 -3.863848)
		(width 0.1143)
		(layer "In9.Cu")
		(net "P3E_CPU0_PE1_PCH_CON_TXN<15>")
	)
	(segment
		(start 326.63892 -96.940624)
		(end 326.857868 -97.971864)
		(width 0.1143)
		(layer "In9.Cu")
		(net "P3E_CPU0_PE1_PCH_CON_TXN<15>")
	)
	(segment
		(start 325.47052 -55.277004)
		(end 325.060564 -56.674512)
		(width 0.1143)
		(layer "In9.Cu")
		(net "P3E_CPU0_PE1_PCH_CON_TXN<15>")
	)
	(segment
		(start 333.364078 -47.683674)
		(end 327.92543 -51.596036)
		(width 0.1143)
		(layer "In9.Cu")
		(net "P3E_CPU0_PE1_PCH_CON_TXN<15>")
	)
	(segment
		(start 326.63892 -100.852478)
		(end 326.6186 -101.11994)
		(width 0.1143)
		(layer "In9.Cu")
		(net "P3E_CPU0_PE1_PCH_CON_TXN<15>")
	)
	(segment
		(start 390.796272 -1.71196)
		(end 387.528816 -2.365756)
		(width 0.1143)
		(layer "In9.Cu")
		(net "P3E_CPU0_PE1_PCH_CON_TXN<15>")
	)
	(segment
		(start 325.739506 -58.411618)
		(end 325.452486 -59.846718)
		(width 0.1143)
		(layer "In9.Cu")
		(net "P3E_CPU0_PE1_PCH_CON_TXN<15>")
	)
	(segment
		(start 324.678548 -104.645968)
		(end 316.781942 -111.941356)
		(width 0.1143)
		(layer "In9.Cu")
		(net "P3E_CPU0_PE1_PCH_CON_TXN<15>")
	)
	(segment
		(start 361.928664 -25.024842)
		(end 361.120944 -29.06522)
		(width 0.1143)
		(layer "In9.Cu")
		(net "P3E_CPU0_PE1_PCH_CON_TXN<15>")
	)
	(segment
		(start 419.93312 -4.019042)
		(end 419.66769 -3.822954)
		(width 0.1143)
		(layer "In9.Cu")
		(net "P3E_CPU0_PE1_PCH_CON_TXN<15>")
	)
	(segment
		(start 373.363236 -7.811262)
		(end 372.351046 -8.013446)
		(width 0.1143)
		(layer "In9.Cu")
		(net "P3E_CPU0_PE1_PCH_CON_TXN<15>")
	)
	(segment
		(start 326.4662 -101.3968)
		(end 324.678548 -104.645968)
		(width 0.1143)
		(layer "In9.Cu")
		(net "P3E_CPU0_PE1_PCH_CON_TXN<15>")
	)
	(segment
		(start 423.926254 -3.863848)
		(end 422.748456 -4.113784)
		(width 0.1143)
		(layer "In9.Cu")
		(net "P3E_CPU0_PE1_PCH_CON_TXN<15>")
	)
	(segment
		(start 394.602208 -1.823466)
		(end 392.977116 -2.148078)
		(width 0.1143)
		(layer "In9.Cu")
		(net "P3E_CPU0_PE1_PCH_CON_TXN<15>")
	)
	(segment
		(start 445.264794 -9.87171)
		(end 445.729868 -10.336784)
		(width 0.1143)
		(layer "In9.Cu")
		(net "P3E_CPU0_PE1_PCH_CON_TXN<15>")
	)
	(segment
		(start 428.745142 -3.870198)
		(end 427.664372 -4.100068)
		(width 0.1143)
		(layer "In9.Cu")
		(net "P3E_CPU0_PE1_PCH_CON_TXN<15>")
	)
	(segment
		(start 407.725372 -0.383032)
		(end 406.481026 -1.213104)
		(width 0.1143)
		(layer "In9.Cu")
		(net "P3E_CPU0_PE1_PCH_CON_TXN<15>")
	)
	(segment
		(start 317.22822 -123.570492)
		(end 318.150748 -124.20854)
		(width 0.1143)
		(layer "In9.Cu")
		(net "P3E_CPU0_PE1_PCH_CON_TXN<15>")
	)
	(segment
		(start 377.22556 -8.09625)
		(end 376.018552 -7.839964)
		(width 0.1143)
		(layer "In9.Cu")
		(net "P3E_CPU0_PE1_PCH_CON_TXN<15>")
	)
	(segment
		(start 325.87311 -62.65799)
		(end 325.34606 -63.45555)
		(width 0.1143)
		(layer "In9.Cu")
		(net "P3E_CPU0_PE1_PCH_CON_TXN<15>")
	)
	(segment
		(start 361.109514 -29.12237)
		(end 361.26293 -29.889196)
		(width 0.1143)
		(layer "In9.Cu")
		(net "P3E_CPU0_PE1_PCH_CON_TXN<15>")
	)
	(segment
		(start 413.083756 -0.1651)
		(end 411.299152 -0.706882)
		(width 0.1143)
		(layer "In9.Cu")
		(net "P3E_CPU0_PE1_PCH_CON_TXN<15>")
	)
	(segment
		(start 372.351046 -8.013446)
		(end 371.327172 -7.808722)
		(width 0.1143)
		(layer "In9.Cu")
		(net "P3E_CPU0_PE1_PCH_CON_TXN<15>")
	)
	(segment
		(start 404.357586 -1.267714)
		(end 399.702528 -2.197608)
		(width 0.1143)
		(layer "In9.Cu")
		(net "P3E_CPU0_PE1_PCH_CON_TXN<15>")
	)
	(segment
		(start 324.139306 -69.386704)
		(end 324.677786 -71.92264)
		(width 0.1143)
		(layer "In9.Cu")
		(net "P3E_CPU0_PE1_PCH_CON_TXN<15>")
	)
	(segment
		(start 376.018552 -7.839964)
		(end 374.801638 -8.09879)
		(width 0.1143)
		(layer "In9.Cu")
		(net "P3E_CPU0_PE1_PCH_CON_TXN<15>")
	)
	(segment
		(start 326.857868 -97.971864)
		(end 326.63892 -100.852478)
		(width 0.1143)
		(layer "In9.Cu")
		(net "P3E_CPU0_PE1_PCH_CON_TXN<15>")
	)
	(segment
		(start 431.519838 -3.767836)
		(end 429.893476 -4.114038)
		(width 0.1143)
		(layer "In9.Cu")
		(net "P3E_CPU0_PE1_PCH_CON_TXN<15>")
	)
	(segment
		(start 340.83117 -47.183802)
		(end 338.32546 -46.674024)
		(width 0.1143)
		(layer "In9.Cu")
		(net "P3E_CPU0_PE1_PCH_CON_TXN<15>")
	)
	(segment
		(start 439.676286 -6.486906)
		(end 433.674012 -3.847846)
		(width 0.1143)
		(layer "In9.Cu")
		(net "P3E_CPU0_PE1_PCH_CON_TXN<15>")
	)
	(segment
		(start 420.373302 -4.112768)
		(end 419.93312 -4.019042)
		(width 0.1143)
		(layer "In9.Cu")
		(net "P3E_CPU0_PE1_PCH_CON_TXN<15>")
	)
	(segment
		(start 316.781942 -111.941356)
		(end 315.329062 -114.834924)
		(width 0.1143)
		(layer "In9.Cu")
		(net "P3E_CPU0_PE1_PCH_CON_TXN<15>")
	)
	(segment
		(start 432.586892 -4.07924)
		(end 431.519838 -3.767836)
		(width 0.1143)
		(layer "In9.Cu")
		(net "P3E_CPU0_PE1_PCH_CON_TXN<15>")
	)
	(segment
		(start 396.7607 -2.254758)
		(end 394.602208 -1.823466)
		(width 0.1143)
		(layer "In9.Cu")
		(net "P3E_CPU0_PE1_PCH_CON_TXN<15>")
	)
	(segment
		(start 325.118476 -57.122314)
		(end 325.636128 -57.898284)
		(width 0.1143)
		(layer "In9.Cu")
		(net "P3E_CPU0_PE1_PCH_CON_TXN<15>")
	)
	(segment
		(start 447.356738 -8.56615)
		(end 446.88633 -8.095488)
		(width 0.1143)
		(layer "F.Cu")
		(net "P3E_CPU0_PE1_PCH_CON_TXN<14>")
	)
	(segment
		(start 449.717414 -9.098534)
		(end 449.374514 -9.098534)
		(width 0.1143)
		(layer "F.Cu")
		(net "P3E_CPU0_PE1_PCH_CON_TXN<14>")
	)
	(segment
		(start 447.760598 -8.970264)
		(end 447.760598 -8.80872)
		(width 0.1143)
		(layer "F.Cu")
		(net "P3E_CPU0_PE1_PCH_CON_TXN<14>")
	)
	(segment
		(start 447.518282 -8.56615)
		(end 447.356738 -8.56615)
		(width 0.1143)
		(layer "F.Cu")
		(net "P3E_CPU0_PE1_PCH_CON_TXN<14>")
	)
	(segment
		(start 451.156578 -9.098534)
		(end 451.042278 -9.212834)
		(width 0.1143)
		(layer "F.Cu")
		(net "P3E_CPU0_PE1_PCH_CON_TXN<14>")
	)
	(segment
		(start 448.460114 -9.098534)
		(end 448.345814 -9.212834)
		(width 0.1143)
		(layer "F.Cu")
		(net "P3E_CPU0_PE1_PCH_CON_TXN<14>")
	)
	(segment
		(start 449.374514 -9.098534)
		(end 449.260214 -9.212834)
		(width 0.1143)
		(layer "F.Cu")
		(net "P3E_CPU0_PE1_PCH_CON_TXN<14>")
	)
	(segment
		(start 450.877178 -8.657336)
		(end 451.156578 -8.936736)
		(width 0.1143)
		(layer "F.Cu")
		(net "P3E_CPU0_PE1_PCH_CON_TXN<14>")
	)
	(segment
		(start 448.002914 -9.212834)
		(end 447.760598 -8.970264)
		(width 0.1143)
		(layer "F.Cu")
		(net "P3E_CPU0_PE1_PCH_CON_TXN<14>")
	)
	(segment
		(start 323.046344 -123.825)
		(end 323.002148 -123.780804)
		(width 0.1143)
		(layer "F.Cu")
		(net "P3E_CPU0_PE1_PCH_CON_TXN<14>")
	)
	(segment
		(start 446.88633 -8.095488)
		(end 446.61201 -8.095488)
		(width 0.1143)
		(layer "F.Cu")
		(net "P3E_CPU0_PE1_PCH_CON_TXN<14>")
	)
	(segment
		(start 447.760598 -8.80872)
		(end 447.518282 -8.56615)
		(width 0.1143)
		(layer "F.Cu")
		(net "P3E_CPU0_PE1_PCH_CON_TXN<14>")
	)
	(segment
		(start 323.6595 -123.825)
		(end 323.046344 -123.825)
		(width 0.1143)
		(layer "F.Cu")
		(net "P3E_CPU0_PE1_PCH_CON_TXN<14>")
	)
	(segment
		(start 449.831714 -9.212834)
		(end 449.717414 -9.098534)
		(width 0.1143)
		(layer "F.Cu")
		(net "P3E_CPU0_PE1_PCH_CON_TXN<14>")
	)
	(segment
		(start 449.260214 -9.212834)
		(end 448.917314 -9.212834)
		(width 0.1143)
		(layer "F.Cu")
		(net "P3E_CPU0_PE1_PCH_CON_TXN<14>")
	)
	(segment
		(start 448.803014 -9.098534)
		(end 448.460114 -9.098534)
		(width 0.1143)
		(layer "F.Cu")
		(net "P3E_CPU0_PE1_PCH_CON_TXN<14>")
	)
	(segment
		(start 448.917314 -9.212834)
		(end 448.803014 -9.098534)
		(width 0.1143)
		(layer "F.Cu")
		(net "P3E_CPU0_PE1_PCH_CON_TXN<14>")
	)
	(segment
		(start 446.61201 -8.095488)
		(end 446.25133 -7.734808)
		(width 0.1143)
		(layer "F.Cu")
		(net "P3E_CPU0_PE1_PCH_CON_TXN<14>")
	)
	(segment
		(start 451.156578 -8.936736)
		(end 451.156578 -9.098534)
		(width 0.1143)
		(layer "F.Cu")
		(net "P3E_CPU0_PE1_PCH_CON_TXN<14>")
	)
	(segment
		(start 448.345814 -9.212834)
		(end 448.002914 -9.212834)
		(width 0.1143)
		(layer "F.Cu")
		(net "P3E_CPU0_PE1_PCH_CON_TXN<14>")
	)
	(segment
		(start 451.042278 -9.212834)
		(end 449.831714 -9.212834)
		(width 0.1143)
		(layer "F.Cu")
		(net "P3E_CPU0_PE1_PCH_CON_TXN<14>")
	)
	(segment
		(start 450.877178 -7.789672)
		(end 450.877178 -8.657336)
		(width 0.1143)
		(layer "F.Cu")
		(net "P3E_CPU0_PE1_PCH_CON_TXN<14>")
	)
	(via
		(at 323.002148 -123.780804)
		(size 0.508)
		(drill 0.254)
		(layers "F.Cu" "B.Cu")
		(net "P3E_CPU0_PE1_PCH_CON_TXN<14>")
	)
	(via
		(at 446.25133 -7.734808)
		(size 0.508)
		(drill 0.254)
		(layers "F.Cu" "B.Cu")
		(net "P3E_CPU0_PE1_PCH_CON_TXN<14>")
	)
	(segment
		(start 317.36792 -112.27435)
		(end 325.260462 -104.983026)
		(width 0.1143)
		(layer "In9.Cu")
		(net "P3E_CPU0_PE1_PCH_CON_TXN<14>")
	)
	(segment
		(start 322.56222 -123.176792)
		(end 322.516246 -123.176792)
		(width 0.1143)
		(layer "In9.Cu")
		(net "P3E_CPU0_PE1_PCH_CON_TXN<14>")
	)
	(segment
		(start 391.918698 -7.3152)
		(end 395.949424 -6.459728)
		(width 0.1143)
		(layer "In9.Cu")
		(net "P3E_CPU0_PE1_PCH_CON_TXN<14>")
	)
	(segment
		(start 367.831624 -13.031724)
		(end 370.114576 -11.242548)
		(width 0.1143)
		(layer "In9.Cu")
		(net "P3E_CPU0_PE1_PCH_CON_TXN<14>")
	)
	(segment
		(start 361.782614 -29.084016)
		(end 362.51769 -25.408382)
		(width 0.1143)
		(layer "In9.Cu")
		(net "P3E_CPU0_PE1_PCH_CON_TXN<14>")
	)
	(segment
		(start 429.918368 -4.78155)
		(end 431.516282 -4.441698)
		(width 0.1143)
		(layer "In9.Cu")
		(net "P3E_CPU0_PE1_PCH_CON_TXN<14>")
	)
	(segment
		(start 327.288652 -101.261164)
		(end 327.53173 -98.07321)
		(width 0.1143)
		(layer "In9.Cu")
		(net "P3E_CPU0_PE1_PCH_CON_TXN<14>")
	)
	(segment
		(start 412.036768 -4.200144)
		(end 414.852104 -3.602482)
		(width 0.1143)
		(layer "In9.Cu")
		(net "P3E_CPU0_PE1_PCH_CON_TXN<14>")
	)
	(segment
		(start 405.776938 -3.560572)
		(end 408.461972 -4.09702)
		(width 0.1143)
		(layer "In9.Cu")
		(net "P3E_CPU0_PE1_PCH_CON_TXN<14>")
	)
	(segment
		(start 322.346066 -123.006612)
		(end 321.497198 -123.006612)
		(width 0.1143)
		(layer "In9.Cu")
		(net "P3E_CPU0_PE1_PCH_CON_TXN<14>")
	)
	(segment
		(start 403.787102 -3.534918)
		(end 404.833836 -3.748786)
		(width 0.1143)
		(layer "In9.Cu")
		(net "P3E_CPU0_PE1_PCH_CON_TXN<14>")
	)
	(segment
		(start 408.461972 -4.09702)
		(end 410.0068 -3.769106)
		(width 0.1143)
		(layer "In9.Cu")
		(net "P3E_CPU0_PE1_PCH_CON_TXN<14>")
	)
	(segment
		(start 326.4789 -62.92977)
		(end 326.622156 -62.225682)
		(width 0.1143)
		(layer "In9.Cu")
		(net "P3E_CPU0_PE1_PCH_CON_TXN<14>")
	)
	(segment
		(start 372.258336 -10.229088)
		(end 372.347998 -10.650728)
		(width 0.1143)
		(layer "In9.Cu")
		(net "P3E_CPU0_PE1_PCH_CON_TXN<14>")
	)
	(segment
		(start 410.0068 -3.769106)
		(end 412.036768 -4.200144)
		(width 0.1143)
		(layer "In9.Cu")
		(net "P3E_CPU0_PE1_PCH_CON_TXN<14>")
	)
	(segment
		(start 316.811914 -117.249702)
		(end 316.054486 -114.891312)
		(width 0.1143)
		(layer "In9.Cu")
		(net "P3E_CPU0_PE1_PCH_CON_TXN<14>")
	)
	(segment
		(start 432.562 -4.746752)
		(end 433.625244 -4.520438)
		(width 0.1143)
		(layer "In9.Cu")
		(net "P3E_CPU0_PE1_PCH_CON_TXN<14>")
	)
	(segment
		(start 370.114576 -11.242548)
		(end 371.24132 -11.002518)
		(width 0.1143)
		(layer "In9.Cu")
		(net "P3E_CPU0_PE1_PCH_CON_TXN<14>")
	)
	(segment
		(start 445.52489 -8.072882)
		(end 446.114678 -8.072882)
		(width 0.1143)
		(layer "In9.Cu")
		(net "P3E_CPU0_PE1_PCH_CON_TXN<14>")
	)
	(segment
		(start 324.866762 -83.457288)
		(end 325.503032 -80.854804)
		(width 0.1143)
		(layer "In9.Cu")
		(net "P3E_CPU0_PE1_PCH_CON_TXN<14>")
	)
	(segment
		(start 321.497198 -123.006612)
		(end 317.779654 -121.944384)
		(width 0.1143)
		(layer "In9.Cu")
		(net "P3E_CPU0_PE1_PCH_CON_TXN<14>")
	)
	(segment
		(start 316.054486 -114.891312)
		(end 316.054232 -114.891312)
		(width 0.1143)
		(layer "In9.Cu")
		(net "P3E_CPU0_PE1_PCH_CON_TXN<14>")
	)
	(segment
		(start 325.32955 -71.92264)
		(end 324.799706 -69.427852)
		(width 0.1143)
		(layer "In9.Cu")
		(net "P3E_CPU0_PE1_PCH_CON_TXN<14>")
	)
	(segment
		(start 327.285604 -101.300788)
		(end 327.288652 -101.261164)
		(width 0.1143)
		(layer "In9.Cu")
		(net "P3E_CPU0_PE1_PCH_CON_TXN<14>")
	)
	(segment
		(start 325.503032 -80.854804)
		(end 324.786244 -77.480922)
		(width 0.1143)
		(layer "In9.Cu")
		(net "P3E_CPU0_PE1_PCH_CON_TXN<14>")
	)
	(segment
		(start 317.779654 -121.944384)
		(end 316.990222 -121.326656)
		(width 0.1143)
		(layer "In9.Cu")
		(net "P3E_CPU0_PE1_PCH_CON_TXN<14>")
	)
	(segment
		(start 323.002148 -123.61672)
		(end 322.56222 -123.176792)
		(width 0.1143)
		(layer "In9.Cu")
		(net "P3E_CPU0_PE1_PCH_CON_TXN<14>")
	)
	(segment
		(start 372.483126 -10.738612)
		(end 379.440694 -9.261094)
		(width 0.1143)
		(layer "In9.Cu")
		(net "P3E_CPU0_PE1_PCH_CON_TXN<14>")
	)
	(segment
		(start 356.95763 -43.06951)
		(end 357.575612 -41.904158)
		(width 0.1143)
		(layer "In9.Cu")
		(net "P3E_CPU0_PE1_PCH_CON_TXN<14>")
	)
	(segment
		(start 359.045256 -34.76498)
		(end 361.695238 -31.500064)
		(width 0.1143)
		(layer "In9.Cu")
		(net "P3E_CPU0_PE1_PCH_CON_TXN<14>")
	)
	(segment
		(start 340.79688 -47.864014)
		(end 355.76383 -43.851576)
		(width 0.1143)
		(layer "In9.Cu")
		(net "P3E_CPU0_PE1_PCH_CON_TXN<14>")
	)
	(segment
		(start 323.002148 -123.780804)
		(end 323.002148 -123.61672)
		(width 0.1143)
		(layer "In9.Cu")
		(net "P3E_CPU0_PE1_PCH_CON_TXN<14>")
	)
	(segment
		(start 426.381926 -4.48945)
		(end 427.660562 -4.761484)
		(width 0.1143)
		(layer "In9.Cu")
		(net "P3E_CPU0_PE1_PCH_CON_TXN<14>")
	)
	(segment
		(start 328.410062 -52.106576)
		(end 333.697326 -48.302418)
		(width 0.1143)
		(layer "In9.Cu")
		(net "P3E_CPU0_PE1_PCH_CON_TXN<14>")
	)
	(segment
		(start 316.990222 -121.326656)
		(end 316.187074 -119.511318)
		(width 0.1143)
		(layer "In9.Cu")
		(net "P3E_CPU0_PE1_PCH_CON_TXN<14>")
	)
	(segment
		(start 357.575612 -41.904158)
		(end 359.045256 -34.76498)
		(width 0.1143)
		(layer "In9.Cu")
		(net "P3E_CPU0_PE1_PCH_CON_TXN<14>")
	)
	(segment
		(start 326.622156 -62.225682)
		(end 326.159368 -59.912504)
		(width 0.1143)
		(layer "In9.Cu")
		(net "P3E_CPU0_PE1_PCH_CON_TXN<14>")
	)
	(segment
		(start 324.799706 -69.427852)
		(end 325.963026 -63.709042)
		(width 0.1143)
		(layer "In9.Cu")
		(net "P3E_CPU0_PE1_PCH_CON_TXN<14>")
	)
	(segment
		(start 414.852104 -3.602482)
		(end 420.347394 -4.769358)
		(width 0.1143)
		(layer "In9.Cu")
		(net "P3E_CPU0_PE1_PCH_CON_TXN<14>")
	)
	(segment
		(start 367.83137 -13.032232)
		(end 367.831116 -13.032232)
		(width 0.1143)
		(layer "In9.Cu")
		(net "P3E_CPU0_PE1_PCH_CON_TXN<14>")
	)
	(segment
		(start 355.76383 -43.851576)
		(end 356.95763 -43.06951)
		(width 0.1143)
		(layer "In9.Cu")
		(net "P3E_CPU0_PE1_PCH_CON_TXN<14>")
	)
	(segment
		(start 325.095616 -76.023978)
		(end 324.7771 -74.522838)
		(width 0.1143)
		(layer "In9.Cu")
		(net "P3E_CPU0_PE1_PCH_CON_TXN<14>")
	)
	(segment
		(start 371.920008 -10.009124)
		(end 372.258336 -10.229088)
		(width 0.1143)
		(layer "In9.Cu")
		(net "P3E_CPU0_PE1_PCH_CON_TXN<14>")
	)
	(segment
		(start 371.32895 -10.86739)
		(end 371.239288 -10.44575)
		(width 0.1143)
		(layer "In9.Cu")
		(net "P3E_CPU0_PE1_PCH_CON_TXN<14>")
	)
	(segment
		(start 379.440694 -9.261094)
		(end 380.303278 -9.444228)
		(width 0.1143)
		(layer "In9.Cu")
		(net "P3E_CPU0_PE1_PCH_CON_TXN<14>")
	)
	(segment
		(start 326.964294 -95.403416)
		(end 327.18375 -94.36989)
		(width 0.1143)
		(layer "In9.Cu")
		(net "P3E_CPU0_PE1_PCH_CON_TXN<14>")
	)
	(segment
		(start 367.831116 -13.032232)
		(end 367.831624 -13.031724)
		(width 0.1143)
		(layer "In9.Cu")
		(net "P3E_CPU0_PE1_PCH_CON_TXN<14>")
	)
	(segment
		(start 380.303278 -9.444228)
		(end 391.124948 -7.146798)
		(width 0.1143)
		(layer "In9.Cu")
		(net "P3E_CPU0_PE1_PCH_CON_TXN<14>")
	)
	(segment
		(start 433.625244 -4.520438)
		(end 439.763408 -7.218934)
		(width 0.1143)
		(layer "In9.Cu")
		(net "P3E_CPU0_PE1_PCH_CON_TXN<14>")
	)
	(segment
		(start 361.98048 -30.073346)
		(end 361.782614 -29.084016)
		(width 0.1143)
		(layer "In9.Cu")
		(net "P3E_CPU0_PE1_PCH_CON_TXN<14>")
	)
	(segment
		(start 446.25133 -7.93623)
		(end 446.25133 -7.734808)
		(width 0.1143)
		(layer "In9.Cu")
		(net "P3E_CPU0_PE1_PCH_CON_TXN<14>")
	)
	(segment
		(start 316.054232 -114.891312)
		(end 317.36792 -112.27435)
		(width 0.1143)
		(layer "In9.Cu")
		(net "P3E_CPU0_PE1_PCH_CON_TXN<14>")
	)
	(segment
		(start 372.347998 -10.650728)
		(end 372.483126 -10.738612)
		(width 0.1143)
		(layer "In9.Cu")
		(net "P3E_CPU0_PE1_PCH_CON_TXN<14>")
	)
	(segment
		(start 420.347394 -4.769358)
		(end 421.532304 -4.51739)
		(width 0.1143)
		(layer "In9.Cu")
		(net "P3E_CPU0_PE1_PCH_CON_TXN<14>")
	)
	(segment
		(start 325.963026 -63.709042)
		(end 326.4662 -62.949074)
		(width 0.1143)
		(layer "In9.Cu")
		(net "P3E_CPU0_PE1_PCH_CON_TXN<14>")
	)
	(segment
		(start 425.067984 -4.768596)
		(end 426.381926 -4.48945)
		(width 0.1143)
		(layer "In9.Cu")
		(net "P3E_CPU0_PE1_PCH_CON_TXN<14>")
	)
	(segment
		(start 362.51769 -25.408382)
		(end 364.33379 -24.194516)
		(width 0.1143)
		(layer "In9.Cu")
		(net "P3E_CPU0_PE1_PCH_CON_TXN<14>")
	)
	(segment
		(start 365.925608 -16.589502)
		(end 367.83137 -13.032232)
		(width 0.1143)
		(layer "In9.Cu")
		(net "P3E_CPU0_PE1_PCH_CON_TXN<14>")
	)
	(segment
		(start 427.660562 -4.761484)
		(end 428.741586 -4.53136)
		(width 0.1143)
		(layer "In9.Cu")
		(net "P3E_CPU0_PE1_PCH_CON_TXN<14>")
	)
	(segment
		(start 316.187074 -119.511318)
		(end 316.811914 -117.249702)
		(width 0.1143)
		(layer "In9.Cu")
		(net "P3E_CPU0_PE1_PCH_CON_TXN<14>")
	)
	(segment
		(start 371.459506 -10.107676)
		(end 371.920008 -10.009124)
		(width 0.1143)
		(layer "In9.Cu")
		(net "P3E_CPU0_PE1_PCH_CON_TXN<14>")
	)
	(segment
		(start 326.4662 -62.949074)
		(end 326.4789 -62.92977)
		(width 0.1143)
		(layer "In9.Cu")
		(net "P3E_CPU0_PE1_PCH_CON_TXN<14>")
	)
	(segment
		(start 421.532304 -4.51739)
		(end 422.731946 -4.772406)
		(width 0.1143)
		(layer "In9.Cu")
		(net "P3E_CPU0_PE1_PCH_CON_TXN<14>")
	)
	(segment
		(start 371.24132 -11.002518)
		(end 371.32895 -10.86739)
		(width 0.1143)
		(layer "In9.Cu")
		(net "P3E_CPU0_PE1_PCH_CON_TXN<14>")
	)
	(segment
		(start 431.516282 -4.441698)
		(end 432.562 -4.746752)
		(width 0.1143)
		(layer "In9.Cu")
		(net "P3E_CPU0_PE1_PCH_CON_TXN<14>")
	)
	(segment
		(start 326.56272 -57.89422)
		(end 326.451214 -57.33669)
		(width 0.1143)
		(layer "In9.Cu")
		(net "P3E_CPU0_PE1_PCH_CON_TXN<14>")
	)
	(segment
		(start 325.260462 -104.983026)
		(end 327.285604 -101.300788)
		(width 0.1143)
		(layer "In9.Cu")
		(net "P3E_CPU0_PE1_PCH_CON_TXN<14>")
	)
	(segment
		(start 324.866508 -83.457288)
		(end 324.866762 -83.457288)
		(width 0.1143)
		(layer "In9.Cu")
		(net "P3E_CPU0_PE1_PCH_CON_TXN<14>")
	)
	(segment
		(start 371.239288 -10.44575)
		(end 371.459506 -10.107676)
		(width 0.1143)
		(layer "In9.Cu")
		(net "P3E_CPU0_PE1_PCH_CON_TXN<14>")
	)
	(segment
		(start 364.33379 -24.194516)
		(end 365.925608 -16.589502)
		(width 0.1143)
		(layer "In9.Cu")
		(net "P3E_CPU0_PE1_PCH_CON_TXN<14>")
	)
	(segment
		(start 404.833836 -3.748786)
		(end 405.776938 -3.560572)
		(width 0.1143)
		(layer "In9.Cu")
		(net "P3E_CPU0_PE1_PCH_CON_TXN<14>")
	)
	(segment
		(start 391.124948 -7.146798)
		(end 391.918698 -7.3152)
		(width 0.1143)
		(layer "In9.Cu")
		(net "P3E_CPU0_PE1_PCH_CON_TXN<14>")
	)
	(segment
		(start 326.159368 -59.912504)
		(end 326.56272 -57.89422)
		(width 0.1143)
		(layer "In9.Cu")
		(net "P3E_CPU0_PE1_PCH_CON_TXN<14>")
	)
	(segment
		(start 361.695238 -31.500064)
		(end 361.98048 -30.073346)
		(width 0.1143)
		(layer "In9.Cu")
		(net "P3E_CPU0_PE1_PCH_CON_TXN<14>")
	)
	(segment
		(start 324.7771 -74.522838)
		(end 325.32955 -71.92264)
		(width 0.1143)
		(layer "In9.Cu")
		(net "P3E_CPU0_PE1_PCH_CON_TXN<14>")
	)
	(segment
		(start 333.697326 -48.302418)
		(end 338.324444 -47.361348)
		(width 0.1143)
		(layer "In9.Cu")
		(net "P3E_CPU0_PE1_PCH_CON_TXN<14>")
	)
	(segment
		(start 444.670942 -7.218934)
		(end 445.52489 -8.072882)
		(width 0.1143)
		(layer "In9.Cu")
		(net "P3E_CPU0_PE1_PCH_CON_TXN<14>")
	)
	(segment
		(start 327.18375 -94.36989)
		(end 324.866508 -83.457288)
		(width 0.1143)
		(layer "In9.Cu")
		(net "P3E_CPU0_PE1_PCH_CON_TXN<14>")
	)
	(segment
		(start 428.741586 -4.53136)
		(end 429.918368 -4.78155)
		(width 0.1143)
		(layer "In9.Cu")
		(net "P3E_CPU0_PE1_PCH_CON_TXN<14>")
	)
	(segment
		(start 327.53173 -98.07321)
		(end 326.964294 -95.403416)
		(width 0.1143)
		(layer "In9.Cu")
		(net "P3E_CPU0_PE1_PCH_CON_TXN<14>")
	)
	(segment
		(start 422.731946 -4.772406)
		(end 423.909744 -4.52247)
		(width 0.1143)
		(layer "In9.Cu")
		(net "P3E_CPU0_PE1_PCH_CON_TXN<14>")
	)
	(segment
		(start 322.516246 -123.176792)
		(end 322.346066 -123.006612)
		(width 0.1143)
		(layer "In9.Cu")
		(net "P3E_CPU0_PE1_PCH_CON_TXN<14>")
	)
	(segment
		(start 395.949424 -6.459728)
		(end 403.787102 -3.534918)
		(width 0.1143)
		(layer "In9.Cu")
		(net "P3E_CPU0_PE1_PCH_CON_TXN<14>")
	)
	(segment
		(start 326.451214 -57.33669)
		(end 328.410062 -52.106576)
		(width 0.1143)
		(layer "In9.Cu")
		(net "P3E_CPU0_PE1_PCH_CON_TXN<14>")
	)
	(segment
		(start 324.786244 -77.480922)
		(end 325.095616 -76.023978)
		(width 0.1143)
		(layer "In9.Cu")
		(net "P3E_CPU0_PE1_PCH_CON_TXN<14>")
	)
	(segment
		(start 338.324444 -47.361348)
		(end 340.79688 -47.864014)
		(width 0.1143)
		(layer "In9.Cu")
		(net "P3E_CPU0_PE1_PCH_CON_TXN<14>")
	)
	(segment
		(start 439.763408 -7.218934)
		(end 444.670942 -7.218934)
		(width 0.1143)
		(layer "In9.Cu")
		(net "P3E_CPU0_PE1_PCH_CON_TXN<14>")
	)
	(segment
		(start 423.909744 -4.52247)
		(end 425.067984 -4.768596)
		(width 0.1143)
		(layer "In9.Cu")
		(net "P3E_CPU0_PE1_PCH_CON_TXN<14>")
	)
	(segment
		(start 446.114678 -8.072882)
		(end 446.25133 -7.93623)
		(width 0.1143)
		(layer "In9.Cu")
		(net "P3E_CPU0_PE1_PCH_CON_TXN<14>")
	)
	(segment
		(start 444.197486 -9.019286)
		(end 444.197486 -8.710168)
		(width 0.1143)
		(layer "F.Cu")
		(net "P3E_CPU0_PE1_PCH_CON_TXN<13>")
	)
	(segment
		(start 444.30315 -9.12495)
		(end 444.197486 -9.019286)
		(width 0.1143)
		(layer "F.Cu")
		(net "P3E_CPU0_PE1_PCH_CON_TXN<13>")
	)
	(segment
		(start 444.197486 -8.710168)
		(end 444.476886 -8.430768)
		(width 0.1143)
		(layer "F.Cu")
		(net "P3E_CPU0_PE1_PCH_CON_TXN<13>")
	)
	(segment
		(start 444.476886 -8.430768)
		(end 444.476886 -7.789672)
		(width 0.1143)
		(layer "F.Cu")
		(net "P3E_CPU0_PE1_PCH_CON_TXN<13>")
	)
	(segment
		(start 444.5635 -9.12495)
		(end 444.30315 -9.12495)
		(width 0.1143)
		(layer "F.Cu")
		(net "P3E_CPU0_PE1_PCH_CON_TXN<13>")
	)
	(segment
		(start 323.6595 -121.666)
		(end 322.979034 -121.666)
		(width 0.1143)
		(layer "F.Cu")
		(net "P3E_CPU0_PE1_PCH_CON_TXN<13>")
	)
	(via
		(at 444.5635 -9.12495)
		(size 0.508)
		(drill 0.254)
		(layers "F.Cu" "B.Cu")
		(net "P3E_CPU0_PE1_PCH_CON_TXN<13>")
	)
	(via
		(at 322.979034 -121.666)
		(size 0.508)
		(drill 0.254)
		(layers "F.Cu" "B.Cu")
		(net "P3E_CPU0_PE1_PCH_CON_TXN<13>")
	)
	(segment
		(start 425.04614 -5.426202)
		(end 426.360082 -5.147056)
		(width 0.1143)
		(layer "In9.Cu")
		(net "P3E_CPU0_PE1_PCH_CON_TXN<13>")
	)
	(segment
		(start 439.675524 -7.874)
		(end 443.773814 -7.874)
		(width 0.1143)
		(layer "In9.Cu")
		(net "P3E_CPU0_PE1_PCH_CON_TXN<13>")
	)
	(segment
		(start 328.782426 -52.959)
		(end 328.78395 -52.954428)
		(width 0.1143)
		(layer "In9.Cu")
		(net "P3E_CPU0_PE1_PCH_CON_TXN<13>")
	)
	(segment
		(start 444.23965 -9.010396)
		(end 444.354204 -9.12495)
		(width 0.1143)
		(layer "In9.Cu")
		(net "P3E_CPU0_PE1_PCH_CON_TXN<13>")
	)
	(segment
		(start 362.67898 -30.187138)
		(end 362.468414 -29.13507)
		(width 0.1143)
		(layer "In9.Cu")
		(net "P3E_CPU0_PE1_PCH_CON_TXN<13>")
	)
	(segment
		(start 328.943716 -52.528216)
		(end 333.927958 -48.943006)
		(width 0.1143)
		(layer "In9.Cu")
		(net "P3E_CPU0_PE1_PCH_CON_TXN<13>")
	)
	(segment
		(start 395.12367 -7.4549)
		(end 403.802088 -4.214622)
		(width 0.1143)
		(layer "In9.Cu")
		(net "P3E_CPU0_PE1_PCH_CON_TXN<13>")
	)
	(segment
		(start 317.497206 -120.87098)
		(end 316.873128 -119.461026)
		(width 0.1143)
		(layer "In9.Cu")
		(net "P3E_CPU0_PE1_PCH_CON_TXN<13>")
	)
	(segment
		(start 426.360082 -5.147056)
		(end 427.635162 -5.418328)
		(width 0.1143)
		(layer "In9.Cu")
		(net "P3E_CPU0_PE1_PCH_CON_TXN<13>")
	)
	(segment
		(start 325.477632 -69.550788)
		(end 326.61987 -63.93434)
		(width 0.1143)
		(layer "In9.Cu")
		(net "P3E_CPU0_PE1_PCH_CON_TXN<13>")
	)
	(segment
		(start 316.799214 -115.094258)
		(end 316.799214 -115.094004)
		(width 0.1143)
		(layer "In9.Cu")
		(net "P3E_CPU0_PE1_PCH_CON_TXN<13>")
	)
	(segment
		(start 390.867392 -7.875778)
		(end 392.00455 -8.117586)
		(width 0.1143)
		(layer "In9.Cu")
		(net "P3E_CPU0_PE1_PCH_CON_TXN<13>")
	)
	(segment
		(start 433.576476 -5.19303)
		(end 439.675524 -7.874)
		(width 0.1143)
		(layer "In9.Cu")
		(net "P3E_CPU0_PE1_PCH_CON_TXN<13>")
	)
	(segment
		(start 320.163952 -121.730516)
		(end 318.13246 -121.368312)
		(width 0.1143)
		(layer "In9.Cu")
		(net "P3E_CPU0_PE1_PCH_CON_TXN<13>")
	)
	(segment
		(start 364.901226 -24.630634)
		(end 366.50295 -17.04467)
		(width 0.1143)
		(layer "In9.Cu")
		(net "P3E_CPU0_PE1_PCH_CON_TXN<13>")
	)
	(segment
		(start 421.50792 -5.174488)
		(end 422.715182 -5.431028)
		(width 0.1143)
		(layer "In9.Cu")
		(net "P3E_CPU0_PE1_PCH_CON_TXN<13>")
	)
	(segment
		(start 316.762638 -114.980212)
		(end 316.7634 -114.978688)
		(width 0.1143)
		(layer "In9.Cu")
		(net "P3E_CPU0_PE1_PCH_CON_TXN<13>")
	)
	(segment
		(start 368.176302 -13.920978)
		(end 370.917216 -11.772392)
		(width 0.1143)
		(layer "In9.Cu")
		(net "P3E_CPU0_PE1_PCH_CON_TXN<13>")
	)
	(segment
		(start 366.50295 -17.04467)
		(end 368.176302 -13.920978)
		(width 0.1143)
		(layer "In9.Cu")
		(net "P3E_CPU0_PE1_PCH_CON_TXN<13>")
	)
	(segment
		(start 444.23965 -8.339836)
		(end 444.23965 -9.010396)
		(width 0.1143)
		(layer "In9.Cu")
		(net "P3E_CPU0_PE1_PCH_CON_TXN<13>")
	)
	(segment
		(start 316.873128 -119.461026)
		(end 317.487808 -117.235732)
		(width 0.1143)
		(layer "In9.Cu")
		(net "P3E_CPU0_PE1_PCH_CON_TXN<13>")
	)
	(segment
		(start 395.11605 -7.456678)
		(end 395.11605 -7.456424)
		(width 0.1143)
		(layer "In9.Cu")
		(net "P3E_CPU0_PE1_PCH_CON_TXN<13>")
	)
	(segment
		(start 444.354204 -9.12495)
		(end 444.5635 -9.12495)
		(width 0.1143)
		(layer "In9.Cu")
		(net "P3E_CPU0_PE1_PCH_CON_TXN<13>")
	)
	(segment
		(start 405.78278 -4.247388)
		(end 408.401012 -4.770628)
		(width 0.1143)
		(layer "In9.Cu")
		(net "P3E_CPU0_PE1_PCH_CON_TXN<13>")
	)
	(segment
		(start 326.63892 -63.905638)
		(end 327.115678 -63.185294)
		(width 0.1143)
		(layer "In9.Cu")
		(net "P3E_CPU0_PE1_PCH_CON_TXN<13>")
	)
	(segment
		(start 325.981314 -71.92264)
		(end 325.477632 -69.550788)
		(width 0.1143)
		(layer "In9.Cu")
		(net "P3E_CPU0_PE1_PCH_CON_TXN<13>")
	)
	(segment
		(start 413.639 -4.516628)
		(end 414.842706 -4.261104)
		(width 0.1143)
		(layer "In9.Cu")
		(net "P3E_CPU0_PE1_PCH_CON_TXN<13>")
	)
	(segment
		(start 409.974796 -4.436364)
		(end 411.996382 -4.865624)
		(width 0.1143)
		(layer "In9.Cu")
		(net "P3E_CPU0_PE1_PCH_CON_TXN<13>")
	)
	(segment
		(start 362.383324 -31.665418)
		(end 362.67898 -30.187138)
		(width 0.1143)
		(layer "In9.Cu")
		(net "P3E_CPU0_PE1_PCH_CON_TXN<13>")
	)
	(segment
		(start 431.4698 -5.10286)
		(end 432.537362 -5.414264)
		(width 0.1143)
		(layer "In9.Cu")
		(net "P3E_CPU0_PE1_PCH_CON_TXN<13>")
	)
	(segment
		(start 322.979034 -121.666)
		(end 322.522342 -121.209308)
		(width 0.1143)
		(layer "In9.Cu")
		(net "P3E_CPU0_PE1_PCH_CON_TXN<13>")
	)
	(segment
		(start 325.428864 -74.523092)
		(end 325.981314 -71.92264)
		(width 0.1143)
		(layer "In9.Cu")
		(net "P3E_CPU0_PE1_PCH_CON_TXN<13>")
	)
	(segment
		(start 316.799468 -115.095528)
		(end 316.799214 -115.094258)
		(width 0.1143)
		(layer "In9.Cu")
		(net "P3E_CPU0_PE1_PCH_CON_TXN<13>")
	)
	(segment
		(start 326.61987 -63.93434)
		(end 326.63892 -63.905638)
		(width 0.1143)
		(layer "In9.Cu")
		(net "P3E_CPU0_PE1_PCH_CON_TXN<13>")
	)
	(segment
		(start 359.644696 -35.04057)
		(end 362.383324 -31.665418)
		(width 0.1143)
		(layer "In9.Cu")
		(net "P3E_CPU0_PE1_PCH_CON_TXN<13>")
	)
	(segment
		(start 422.715182 -5.431028)
		(end 423.89298 -5.181092)
		(width 0.1143)
		(layer "In9.Cu")
		(net "P3E_CPU0_PE1_PCH_CON_TXN<13>")
	)
	(segment
		(start 328.78395 -52.954428)
		(end 328.943716 -52.528216)
		(width 0.1143)
		(layer "In9.Cu")
		(net "P3E_CPU0_PE1_PCH_CON_TXN<13>")
	)
	(segment
		(start 327.115678 -63.185294)
		(end 327.862692 -59.37377)
		(width 0.1143)
		(layer "In9.Cu")
		(net "P3E_CPU0_PE1_PCH_CON_TXN<13>")
	)
	(segment
		(start 423.89298 -5.181092)
		(end 425.04614 -5.426202)
		(width 0.1143)
		(layer "In9.Cu")
		(net "P3E_CPU0_PE1_PCH_CON_TXN<13>")
	)
	(segment
		(start 411.996382 -4.865624)
		(end 413.639 -4.516628)
		(width 0.1143)
		(layer "In9.Cu")
		(net "P3E_CPU0_PE1_PCH_CON_TXN<13>")
	)
	(segment
		(start 317.898526 -112.716818)
		(end 317.901066 -112.658652)
		(width 0.1143)
		(layer "In9.Cu")
		(net "P3E_CPU0_PE1_PCH_CON_TXN<13>")
	)
	(segment
		(start 327.34631 -56.793638)
		(end 328.782426 -52.959)
		(width 0.1143)
		(layer "In9.Cu")
		(net "P3E_CPU0_PE1_PCH_CON_TXN<13>")
	)
	(segment
		(start 322.522342 -121.209308)
		(end 321.998848 -121.209308)
		(width 0.1143)
		(layer "In9.Cu")
		(net "P3E_CPU0_PE1_PCH_CON_TXN<13>")
	)
	(segment
		(start 328.198988 -98.146362)
		(end 327.624694 -95.444056)
		(width 0.1143)
		(layer "In9.Cu")
		(net "P3E_CPU0_PE1_PCH_CON_TXN<13>")
	)
	(segment
		(start 392.00455 -8.117586)
		(end 395.11605 -7.456678)
		(width 0.1143)
		(layer "In9.Cu")
		(net "P3E_CPU0_PE1_PCH_CON_TXN<13>")
	)
	(segment
		(start 428.71644 -5.188204)
		(end 429.892968 -5.43814)
		(width 0.1143)
		(layer "In9.Cu")
		(net "P3E_CPU0_PE1_PCH_CON_TXN<13>")
	)
	(segment
		(start 363.13364 -25.809194)
		(end 364.901226 -24.630634)
		(width 0.1143)
		(layer "In9.Cu")
		(net "P3E_CPU0_PE1_PCH_CON_TXN<13>")
	)
	(segment
		(start 327.93686 -101.590094)
		(end 328.198988 -98.146362)
		(width 0.1143)
		(layer "In9.Cu")
		(net "P3E_CPU0_PE1_PCH_CON_TXN<13>")
	)
	(segment
		(start 443.773814 -7.874)
		(end 444.23965 -8.339836)
		(width 0.1143)
		(layer "In9.Cu")
		(net "P3E_CPU0_PE1_PCH_CON_TXN<13>")
	)
	(segment
		(start 414.842706 -4.261104)
		(end 420.32301 -5.426456)
		(width 0.1143)
		(layer "In9.Cu")
		(net "P3E_CPU0_PE1_PCH_CON_TXN<13>")
	)
	(segment
		(start 357.490522 -43.494706)
		(end 358.166416 -42.220134)
		(width 0.1143)
		(layer "In9.Cu")
		(net "P3E_CPU0_PE1_PCH_CON_TXN<13>")
	)
	(segment
		(start 327.624694 -95.444056)
		(end 327.844658 -94.409006)
		(width 0.1143)
		(layer "In9.Cu")
		(net "P3E_CPU0_PE1_PCH_CON_TXN<13>")
	)
	(segment
		(start 327.936606 -101.590094)
		(end 327.93686 -101.590094)
		(width 0.1143)
		(layer "In9.Cu")
		(net "P3E_CPU0_PE1_PCH_CON_TXN<13>")
	)
	(segment
		(start 321.998848 -121.209308)
		(end 320.163952 -121.730516)
		(width 0.1143)
		(layer "In9.Cu")
		(net "P3E_CPU0_PE1_PCH_CON_TXN<13>")
	)
	(segment
		(start 316.7634 -114.978688)
		(end 317.898526 -112.716818)
		(width 0.1143)
		(layer "In9.Cu")
		(net "P3E_CPU0_PE1_PCH_CON_TXN<13>")
	)
	(segment
		(start 404.862284 -4.431284)
		(end 404.8633 -4.43103)
		(width 0.1143)
		(layer "In9.Cu")
		(net "P3E_CPU0_PE1_PCH_CON_TXN<13>")
	)
	(segment
		(start 317.901066 -112.658652)
		(end 325.92645 -105.244646)
		(width 0.1143)
		(layer "In9.Cu")
		(net "P3E_CPU0_PE1_PCH_CON_TXN<13>")
	)
	(segment
		(start 340.754208 -48.542194)
		(end 356.03815 -44.445682)
		(width 0.1143)
		(layer "In9.Cu")
		(net "P3E_CPU0_PE1_PCH_CON_TXN<13>")
	)
	(segment
		(start 327.862692 -59.37377)
		(end 327.34631 -56.793638)
		(width 0.1143)
		(layer "In9.Cu")
		(net "P3E_CPU0_PE1_PCH_CON_TXN<13>")
	)
	(segment
		(start 333.927958 -48.943006)
		(end 338.32546 -48.04791)
		(width 0.1143)
		(layer "In9.Cu")
		(net "P3E_CPU0_PE1_PCH_CON_TXN<13>")
	)
	(segment
		(start 379.48235 -9.922764)
		(end 380.35611 -10.108184)
		(width 0.1143)
		(layer "In9.Cu")
		(net "P3E_CPU0_PE1_PCH_CON_TXN<13>")
	)
	(segment
		(start 370.970556 -11.730482)
		(end 379.48235 -9.922764)
		(width 0.1143)
		(layer "In9.Cu")
		(net "P3E_CPU0_PE1_PCH_CON_TXN<13>")
	)
	(segment
		(start 316.799722 -115.095528)
		(end 316.799468 -115.095528)
		(width 0.1143)
		(layer "In9.Cu")
		(net "P3E_CPU0_PE1_PCH_CON_TXN<13>")
	)
	(segment
		(start 420.32301 -5.426456)
		(end 421.50792 -5.174488)
		(width 0.1143)
		(layer "In9.Cu")
		(net "P3E_CPU0_PE1_PCH_CON_TXN<13>")
	)
	(segment
		(start 429.892968 -5.43814)
		(end 431.4698 -5.10286)
		(width 0.1143)
		(layer "In9.Cu")
		(net "P3E_CPU0_PE1_PCH_CON_TXN<13>")
	)
	(segment
		(start 370.916962 -11.772392)
		(end 370.970556 -11.730482)
		(width 0.1143)
		(layer "In9.Cu")
		(net "P3E_CPU0_PE1_PCH_CON_TXN<13>")
	)
	(segment
		(start 370.917216 -11.772392)
		(end 370.916962 -11.772392)
		(width 0.1143)
		(layer "In9.Cu")
		(net "P3E_CPU0_PE1_PCH_CON_TXN<13>")
	)
	(segment
		(start 362.468414 -29.13507)
		(end 363.13364 -25.809194)
		(width 0.1143)
		(layer "In9.Cu")
		(net "P3E_CPU0_PE1_PCH_CON_TXN<13>")
	)
	(segment
		(start 356.03815 -44.445682)
		(end 357.490522 -43.494706)
		(width 0.1143)
		(layer "In9.Cu")
		(net "P3E_CPU0_PE1_PCH_CON_TXN<13>")
	)
	(segment
		(start 327.844658 -94.409006)
		(end 325.524368 -83.48472)
		(width 0.1143)
		(layer "In9.Cu")
		(net "P3E_CPU0_PE1_PCH_CON_TXN<13>")
	)
	(segment
		(start 380.35611 -10.108184)
		(end 390.867392 -7.875778)
		(width 0.1143)
		(layer "In9.Cu")
		(net "P3E_CPU0_PE1_PCH_CON_TXN<13>")
	)
	(segment
		(start 395.11605 -7.456424)
		(end 395.119352 -7.455662)
		(width 0.1143)
		(layer "In9.Cu")
		(net "P3E_CPU0_PE1_PCH_CON_TXN<13>")
	)
	(segment
		(start 403.802088 -4.214622)
		(end 403.803866 -4.214876)
		(width 0.1143)
		(layer "In9.Cu")
		(net "P3E_CPU0_PE1_PCH_CON_TXN<13>")
	)
	(segment
		(start 432.537362 -5.414264)
		(end 433.576476 -5.19303)
		(width 0.1143)
		(layer "In9.Cu")
		(net "P3E_CPU0_PE1_PCH_CON_TXN<13>")
	)
	(segment
		(start 317.487808 -117.235732)
		(end 316.799722 -115.095528)
		(width 0.1143)
		(layer "In9.Cu")
		(net "P3E_CPU0_PE1_PCH_CON_TXN<13>")
	)
	(segment
		(start 358.166416 -42.220134)
		(end 359.644696 -35.04057)
		(width 0.1143)
		(layer "In9.Cu")
		(net "P3E_CPU0_PE1_PCH_CON_TXN<13>")
	)
	(segment
		(start 326.160892 -80.882236)
		(end 325.438262 -77.480922)
		(width 0.1143)
		(layer "In9.Cu")
		(net "P3E_CPU0_PE1_PCH_CON_TXN<13>")
	)
	(segment
		(start 395.119352 -7.455662)
		(end 395.12367 -7.4549)
		(width 0.1143)
		(layer "In9.Cu")
		(net "P3E_CPU0_PE1_PCH_CON_TXN<13>")
	)
	(segment
		(start 325.74738 -76.023978)
		(end 325.428864 -74.523092)
		(width 0.1143)
		(layer "In9.Cu")
		(net "P3E_CPU0_PE1_PCH_CON_TXN<13>")
	)
	(segment
		(start 325.524368 -83.48472)
		(end 326.160892 -80.882236)
		(width 0.1143)
		(layer "In9.Cu")
		(net "P3E_CPU0_PE1_PCH_CON_TXN<13>")
	)
	(segment
		(start 325.92645 -105.244646)
		(end 327.936606 -101.590094)
		(width 0.1143)
		(layer "In9.Cu")
		(net "P3E_CPU0_PE1_PCH_CON_TXN<13>")
	)
	(segment
		(start 403.803866 -4.214876)
		(end 404.862284 -4.431284)
		(width 0.1143)
		(layer "In9.Cu")
		(net "P3E_CPU0_PE1_PCH_CON_TXN<13>")
	)
	(segment
		(start 316.799214 -115.094004)
		(end 316.762638 -114.980212)
		(width 0.1143)
		(layer "In9.Cu")
		(net "P3E_CPU0_PE1_PCH_CON_TXN<13>")
	)
	(segment
		(start 408.401012 -4.770628)
		(end 409.974796 -4.436364)
		(width 0.1143)
		(layer "In9.Cu")
		(net "P3E_CPU0_PE1_PCH_CON_TXN<13>")
	)
	(segment
		(start 318.13246 -121.368312)
		(end 317.497206 -120.87098)
		(width 0.1143)
		(layer "In9.Cu")
		(net "P3E_CPU0_PE1_PCH_CON_TXN<13>")
	)
	(segment
		(start 325.438262 -77.480922)
		(end 325.74738 -76.023978)
		(width 0.1143)
		(layer "In9.Cu")
		(net "P3E_CPU0_PE1_PCH_CON_TXN<13>")
	)
	(segment
		(start 427.635162 -5.418328)
		(end 428.71644 -5.188204)
		(width 0.1143)
		(layer "In9.Cu")
		(net "P3E_CPU0_PE1_PCH_CON_TXN<13>")
	)
	(segment
		(start 404.8633 -4.43103)
		(end 405.78278 -4.247388)
		(width 0.1143)
		(layer "In9.Cu")
		(net "P3E_CPU0_PE1_PCH_CON_TXN<13>")
	)
	(segment
		(start 338.32546 -48.04791)
		(end 340.754208 -48.542194)
		(width 0.1143)
		(layer "In9.Cu")
		(net "P3E_CPU0_PE1_PCH_CON_TXN<13>")
	)
	(segment
		(start 441.981844 -10.029444)
		(end 442.111892 -10.029444)
		(width 0.1143)
		(layer "F.Cu")
		(net "P3E_CPU0_PE1_PCH_CON_TXN<12>")
	)
	(segment
		(start 441.763658 -8.908288)
		(end 441.763658 -9.811258)
		(width 0.1143)
		(layer "F.Cu")
		(net "P3E_CPU0_PE1_PCH_CON_TXN<12>")
	)
	(segment
		(start 442.076586 -7.789672)
		(end 442.076586 -8.59536)
		(width 0.1143)
		(layer "F.Cu")
		(net "P3E_CPU0_PE1_PCH_CON_TXN<12>")
	)
	(segment
		(start 320.27622 -120.53316)
		(end 319.56756 -120.53316)
		(width 0.1143)
		(layer "F.Cu")
		(net "P3E_CPU0_PE1_PCH_CON_TXN<12>")
	)
	(segment
		(start 441.763658 -9.811258)
		(end 441.981844 -10.029444)
		(width 0.1143)
		(layer "F.Cu")
		(net "P3E_CPU0_PE1_PCH_CON_TXN<12>")
	)
	(segment
		(start 442.076586 -8.59536)
		(end 441.763658 -8.908288)
		(width 0.1143)
		(layer "F.Cu")
		(net "P3E_CPU0_PE1_PCH_CON_TXN<12>")
	)
	(via
		(at 319.56756 -120.53316)
		(size 0.508)
		(drill 0.254)
		(layers "F.Cu" "B.Cu")
		(net "P3E_CPU0_PE1_PCH_CON_TXN<12>")
	)
	(via
		(at 442.111892 -10.029444)
		(size 0.508)
		(drill 0.254)
		(layers "F.Cu" "B.Cu")
		(net "P3E_CPU0_PE1_PCH_CON_TXN<12>")
	)
	(segment
		(start 429.875442 -6.096762)
		(end 431.431192 -5.766308)
		(width 0.1143)
		(layer "In9.Cu")
		(net "P3E_CPU0_PE1_PCH_CON_TXN<12>")
	)
	(segment
		(start 340.695026 -49.217072)
		(end 356.338124 -45.02404)
		(width 0.1143)
		(layer "In9.Cu")
		(net "P3E_CPU0_PE1_PCH_CON_TXN<12>")
	)
	(segment
		(start 328.083926 -57.152286)
		(end 329.716892 -52.80533)
		(width 0.1143)
		(layer "In9.Cu")
		(net "P3E_CPU0_PE1_PCH_CON_TXN<12>")
	)
	(segment
		(start 356.338124 -45.02404)
		(end 357.997252 -43.93692)
		(width 0.1143)
		(layer "In9.Cu")
		(net "P3E_CPU0_PE1_PCH_CON_TXN<12>")
	)
	(segment
		(start 441.36818 -8.570214)
		(end 441.7822 -8.984234)
		(width 0.1143)
		(layer "In9.Cu")
		(net "P3E_CPU0_PE1_PCH_CON_TXN<12>")
	)
	(segment
		(start 328.535792 -94.436946)
		(end 326.244458 -83.645248)
		(width 0.1143)
		(layer "In9.Cu")
		(net "P3E_CPU0_PE1_PCH_CON_TXN<12>")
	)
	(segment
		(start 392.466068 -8.924544)
		(end 395.002512 -8.385556)
		(width 0.1143)
		(layer "In9.Cu")
		(net "P3E_CPU0_PE1_PCH_CON_TXN<12>")
	)
	(segment
		(start 329.716892 -52.80533)
		(end 334.257142 -49.538128)
		(width 0.1143)
		(layer "In9.Cu")
		(net "P3E_CPU0_PE1_PCH_CON_TXN<12>")
	)
	(segment
		(start 317.8175 -119.4943)
		(end 317.8175 -118.474744)
		(width 0.1143)
		(layer "In9.Cu")
		(net "P3E_CPU0_PE1_PCH_CON_TXN<12>")
	)
	(segment
		(start 326.18045 -74.9935)
		(end 326.104758 -74.637392)
		(width 0.1143)
		(layer "In9.Cu")
		(net "P3E_CPU0_PE1_PCH_CON_TXN<12>")
	)
	(segment
		(start 334.257142 -49.538128)
		(end 334.323944 -49.548796)
		(width 0.1143)
		(layer "In9.Cu")
		(net "P3E_CPU0_PE1_PCH_CON_TXN<12>")
	)
	(segment
		(start 423.892726 -5.843016)
		(end 425.029376 -6.08457)
		(width 0.1143)
		(layer "In9.Cu")
		(net "P3E_CPU0_PE1_PCH_CON_TXN<12>")
	)
	(segment
		(start 326.45477 -105.66781)
		(end 326.455024 -105.66781)
		(width 0.1143)
		(layer "In9.Cu")
		(net "P3E_CPU0_PE1_PCH_CON_TXN<12>")
	)
	(segment
		(start 390.7536 -8.560562)
		(end 392.466068 -8.924544)
		(width 0.1143)
		(layer "In9.Cu")
		(net "P3E_CPU0_PE1_PCH_CON_TXN<12>")
	)
	(segment
		(start 328.519028 -59.327542)
		(end 328.083926 -57.152286)
		(width 0.1143)
		(layer "In9.Cu")
		(net "P3E_CPU0_PE1_PCH_CON_TXN<12>")
	)
	(segment
		(start 417.947856 -6.081776)
		(end 419.12032 -5.832856)
		(width 0.1143)
		(layer "In9.Cu")
		(net "P3E_CPU0_PE1_PCH_CON_TXN<12>")
	)
	(segment
		(start 319.56756 -120.2563)
		(end 319.35801 -120.04675)
		(width 0.1143)
		(layer "In9.Cu")
		(net "P3E_CPU0_PE1_PCH_CON_TXN<12>")
	)
	(segment
		(start 404.183088 -4.959604)
		(end 404.844758 -5.094478)
		(width 0.1143)
		(layer "In9.Cu")
		(net "P3E_CPU0_PE1_PCH_CON_TXN<12>")
	)
	(segment
		(start 318.36995 -120.04675)
		(end 317.8175 -119.4943)
		(width 0.1143)
		(layer "In9.Cu")
		(net "P3E_CPU0_PE1_PCH_CON_TXN<12>")
	)
	(segment
		(start 327.466706 -63.80607)
		(end 327.714864 -63.430912)
		(width 0.1143)
		(layer "In9.Cu")
		(net "P3E_CPU0_PE1_PCH_CON_TXN<12>")
	)
	(segment
		(start 363.018324 -31.945072)
		(end 363.34954 -30.2895)
		(width 0.1143)
		(layer "In9.Cu")
		(net "P3E_CPU0_PE1_PCH_CON_TXN<12>")
	)
	(segment
		(start 326.091042 -77.486002)
		(end 326.090026 -77.48143)
		(width 0.1143)
		(layer "In9.Cu")
		(net "P3E_CPU0_PE1_PCH_CON_TXN<12>")
	)
	(segment
		(start 363.126274 -29.172916)
		(end 363.719618 -26.20645)
		(width 0.1143)
		(layer "In9.Cu")
		(net "P3E_CPU0_PE1_PCH_CON_TXN<12>")
	)
	(segment
		(start 326.099678 -74.623676)
		(end 326.079612 -74.52868)
		(width 0.1143)
		(layer "In9.Cu")
		(net "P3E_CPU0_PE1_PCH_CON_TXN<12>")
	)
	(segment
		(start 441.7822 -9.8044)
		(end 442.007244 -10.029444)
		(width 0.1143)
		(layer "In9.Cu")
		(net "P3E_CPU0_PE1_PCH_CON_TXN<12>")
	)
	(segment
		(start 328.602848 -101.764084)
		(end 328.870818 -98.24085)
		(width 0.1143)
		(layer "In9.Cu")
		(net "P3E_CPU0_PE1_PCH_CON_TXN<12>")
	)
	(segment
		(start 439.681112 -8.570214)
		(end 441.36818 -8.570214)
		(width 0.1143)
		(layer "In9.Cu")
		(net "P3E_CPU0_PE1_PCH_CON_TXN<12>")
	)
	(segment
		(start 427.61281 -6.075426)
		(end 428.693834 -5.845556)
		(width 0.1143)
		(layer "In9.Cu")
		(net "P3E_CPU0_PE1_PCH_CON_TXN<12>")
	)
	(segment
		(start 431.431192 -5.766308)
		(end 432.48834 -6.074918)
		(width 0.1143)
		(layer "In9.Cu")
		(net "P3E_CPU0_PE1_PCH_CON_TXN<12>")
	)
	(segment
		(start 326.40016 -76.029566)
		(end 326.29094 -75.514708)
		(width 0.1143)
		(layer "In9.Cu")
		(net "P3E_CPU0_PE1_PCH_CON_TXN<12>")
	)
	(segment
		(start 326.281034 -75.467718)
		(end 326.18045 -74.9935)
		(width 0.1143)
		(layer "In9.Cu")
		(net "P3E_CPU0_PE1_PCH_CON_TXN<12>")
	)
	(segment
		(start 326.29094 -75.514708)
		(end 326.281034 -75.467718)
		(width 0.1143)
		(layer "In9.Cu")
		(net "P3E_CPU0_PE1_PCH_CON_TXN<12>")
	)
	(segment
		(start 326.138032 -77.71765)
		(end 326.090026 -77.491336)
		(width 0.1143)
		(layer "In9.Cu")
		(net "P3E_CPU0_PE1_PCH_CON_TXN<12>")
	)
	(segment
		(start 357.997252 -43.93692)
		(end 358.795574 -42.431208)
		(width 0.1143)
		(layer "In9.Cu")
		(net "P3E_CPU0_PE1_PCH_CON_TXN<12>")
	)
	(segment
		(start 327.217786 -64.18199)
		(end 327.466452 -63.806324)
		(width 0.1143)
		(layer "In9.Cu")
		(net "P3E_CPU0_PE1_PCH_CON_TXN<12>")
	)
	(segment
		(start 326.454008 -105.668572)
		(end 326.45477 -105.66781)
		(width 0.1143)
		(layer "In9.Cu")
		(net "P3E_CPU0_PE1_PCH_CON_TXN<12>")
	)
	(segment
		(start 360.253026 -35.352482)
		(end 363.018324 -31.945072)
		(width 0.1143)
		(layer "In9.Cu")
		(net "P3E_CPU0_PE1_PCH_CON_TXN<12>")
	)
	(segment
		(start 326.090026 -77.48143)
		(end 326.090026 -77.481176)
		(width 0.1143)
		(layer "In9.Cu")
		(net "P3E_CPU0_PE1_PCH_CON_TXN<12>")
	)
	(segment
		(start 405.733504 -4.916424)
		(end 408.472894 -5.46354)
		(width 0.1143)
		(layer "In9.Cu")
		(net "P3E_CPU0_PE1_PCH_CON_TXN<12>")
	)
	(segment
		(start 318.501776 -113.015522)
		(end 326.454008 -105.668572)
		(width 0.1143)
		(layer "In9.Cu")
		(net "P3E_CPU0_PE1_PCH_CON_TXN<12>")
	)
	(segment
		(start 380.355602 -10.768584)
		(end 390.7536 -8.560562)
		(width 0.1143)
		(layer "In9.Cu")
		(net "P3E_CPU0_PE1_PCH_CON_TXN<12>")
	)
	(segment
		(start 326.244458 -83.645248)
		(end 326.63892 -82.032602)
		(width 0.1143)
		(layer "In9.Cu")
		(net "P3E_CPU0_PE1_PCH_CON_TXN<12>")
	)
	(segment
		(start 408.473402 -5.463794)
		(end 410.11475 -5.115814)
		(width 0.1143)
		(layer "In9.Cu")
		(net "P3E_CPU0_PE1_PCH_CON_TXN<12>")
	)
	(segment
		(start 338.326476 -48.734726)
		(end 340.695026 -49.217072)
		(width 0.1143)
		(layer "In9.Cu")
		(net "P3E_CPU0_PE1_PCH_CON_TXN<12>")
	)
	(segment
		(start 365.477806 -25.032716)
		(end 367.00079 -17.939512)
		(width 0.1143)
		(layer "In9.Cu")
		(net "P3E_CPU0_PE1_PCH_CON_TXN<12>")
	)
	(segment
		(start 334.323944 -49.548796)
		(end 338.326476 -48.734726)
		(width 0.1143)
		(layer "In9.Cu")
		(net "P3E_CPU0_PE1_PCH_CON_TXN<12>")
	)
	(segment
		(start 326.103234 -74.63155)
		(end 326.100186 -74.625962)
		(width 0.1143)
		(layer "In9.Cu")
		(net "P3E_CPU0_PE1_PCH_CON_TXN<12>")
	)
	(segment
		(start 379.47092 -10.580624)
		(end 380.355602 -10.768584)
		(width 0.1143)
		(layer "In9.Cu")
		(net "P3E_CPU0_PE1_PCH_CON_TXN<12>")
	)
	(segment
		(start 432.48834 -6.074918)
		(end 433.509166 -5.857494)
		(width 0.1143)
		(layer "In9.Cu")
		(net "P3E_CPU0_PE1_PCH_CON_TXN<12>")
	)
	(segment
		(start 326.090026 -77.481176)
		(end 326.180196 -77.053948)
		(width 0.1143)
		(layer "In9.Cu")
		(net "P3E_CPU0_PE1_PCH_CON_TXN<12>")
	)
	(segment
		(start 422.715182 -6.093206)
		(end 423.892726 -5.843016)
		(width 0.1143)
		(layer "In9.Cu")
		(net "P3E_CPU0_PE1_PCH_CON_TXN<12>")
	)
	(segment
		(start 419.12032 -5.832856)
		(end 420.310056 -6.08584)
		(width 0.1143)
		(layer "In9.Cu")
		(net "P3E_CPU0_PE1_PCH_CON_TXN<12>")
	)
	(segment
		(start 425.029376 -6.08457)
		(end 426.343064 -5.805678)
		(width 0.1143)
		(layer "In9.Cu")
		(net "P3E_CPU0_PE1_PCH_CON_TXN<12>")
	)
	(segment
		(start 326.104758 -74.637392)
		(end 326.103234 -74.63155)
		(width 0.1143)
		(layer "In9.Cu")
		(net "P3E_CPU0_PE1_PCH_CON_TXN<12>")
	)
	(segment
		(start 328.299318 -95.55226)
		(end 328.5363 -94.436692)
		(width 0.1143)
		(layer "In9.Cu")
		(net "P3E_CPU0_PE1_PCH_CON_TXN<12>")
	)
	(segment
		(start 371.314726 -12.312904)
		(end 379.47092 -10.580624)
		(width 0.1143)
		(layer "In9.Cu")
		(net "P3E_CPU0_PE1_PCH_CON_TXN<12>")
	)
	(segment
		(start 326.63892 -82.032602)
		(end 326.86244 -81.118964)
		(width 0.1143)
		(layer "In9.Cu")
		(net "P3E_CPU0_PE1_PCH_CON_TXN<12>")
	)
	(segment
		(start 326.455024 -105.66781)
		(end 328.602848 -101.764084)
		(width 0.1143)
		(layer "In9.Cu")
		(net "P3E_CPU0_PE1_PCH_CON_TXN<12>")
	)
	(segment
		(start 326.180196 -77.053948)
		(end 326.37222 -76.15174)
		(width 0.1143)
		(layer "In9.Cu")
		(net "P3E_CPU0_PE1_PCH_CON_TXN<12>")
	)
	(segment
		(start 327.466452 -63.806324)
		(end 327.466706 -63.80607)
		(width 0.1143)
		(layer "In9.Cu")
		(net "P3E_CPU0_PE1_PCH_CON_TXN<12>")
	)
	(segment
		(start 326.63892 -80.06588)
		(end 326.4662 -79.252064)
		(width 0.1143)
		(layer "In9.Cu")
		(net "P3E_CPU0_PE1_PCH_CON_TXN<12>")
	)
	(segment
		(start 358.795574 -42.431208)
		(end 360.253026 -35.352482)
		(width 0.1143)
		(layer "In9.Cu")
		(net "P3E_CPU0_PE1_PCH_CON_TXN<12>")
	)
	(segment
		(start 363.719618 -26.20645)
		(end 365.477806 -25.032716)
		(width 0.1143)
		(layer "In9.Cu")
		(net "P3E_CPU0_PE1_PCH_CON_TXN<12>")
	)
	(segment
		(start 326.127618 -69.542914)
		(end 327.217786 -64.18199)
		(width 0.1143)
		(layer "In9.Cu")
		(net "P3E_CPU0_PE1_PCH_CON_TXN<12>")
	)
	(segment
		(start 441.7822 -8.984234)
		(end 441.7822 -9.8044)
		(width 0.1143)
		(layer "In9.Cu")
		(net "P3E_CPU0_PE1_PCH_CON_TXN<12>")
	)
	(segment
		(start 420.310056 -6.08584)
		(end 421.494966 -5.833872)
		(width 0.1143)
		(layer "In9.Cu")
		(net "P3E_CPU0_PE1_PCH_CON_TXN<12>")
	)
	(segment
		(start 319.35801 -120.04675)
		(end 318.36995 -120.04675)
		(width 0.1143)
		(layer "In9.Cu")
		(net "P3E_CPU0_PE1_PCH_CON_TXN<12>")
	)
	(segment
		(start 326.100186 -74.625962)
		(end 326.099678 -74.623676)
		(width 0.1143)
		(layer "In9.Cu")
		(net "P3E_CPU0_PE1_PCH_CON_TXN<12>")
	)
	(segment
		(start 410.11475 -5.115814)
		(end 415.529522 -6.266434)
		(width 0.1143)
		(layer "In9.Cu")
		(net "P3E_CPU0_PE1_PCH_CON_TXN<12>")
	)
	(segment
		(start 442.007244 -10.029444)
		(end 442.111892 -10.029444)
		(width 0.1143)
		(layer "In9.Cu")
		(net "P3E_CPU0_PE1_PCH_CON_TXN<12>")
	)
	(segment
		(start 326.633078 -71.92264)
		(end 326.127618 -69.542914)
		(width 0.1143)
		(layer "In9.Cu")
		(net "P3E_CPU0_PE1_PCH_CON_TXN<12>")
	)
	(segment
		(start 326.37222 -76.15174)
		(end 326.375268 -76.146914)
		(width 0.1143)
		(layer "In9.Cu")
		(net "P3E_CPU0_PE1_PCH_CON_TXN<12>")
	)
	(segment
		(start 326.079612 -74.52868)
		(end 326.633078 -71.92264)
		(width 0.1143)
		(layer "In9.Cu")
		(net "P3E_CPU0_PE1_PCH_CON_TXN<12>")
	)
	(segment
		(start 326.141334 -77.72273)
		(end 326.138032 -77.71765)
		(width 0.1143)
		(layer "In9.Cu")
		(net "P3E_CPU0_PE1_PCH_CON_TXN<12>")
	)
	(segment
		(start 318.163702 -117.221762)
		(end 317.471298 -115.068604)
		(width 0.1143)
		(layer "In9.Cu")
		(net "P3E_CPU0_PE1_PCH_CON_TXN<12>")
	)
	(segment
		(start 426.343064 -5.805678)
		(end 427.61281 -6.075426)
		(width 0.1143)
		(layer "In9.Cu")
		(net "P3E_CPU0_PE1_PCH_CON_TXN<12>")
	)
	(segment
		(start 317.471298 -115.068604)
		(end 318.501776 -113.015522)
		(width 0.1143)
		(layer "In9.Cu")
		(net "P3E_CPU0_PE1_PCH_CON_TXN<12>")
	)
	(segment
		(start 404.844758 -5.094478)
		(end 405.733504 -4.916424)
		(width 0.1143)
		(layer "In9.Cu")
		(net "P3E_CPU0_PE1_PCH_CON_TXN<12>")
	)
	(segment
		(start 428.693834 -5.845556)
		(end 429.875442 -6.096762)
		(width 0.1143)
		(layer "In9.Cu")
		(net "P3E_CPU0_PE1_PCH_CON_TXN<12>")
	)
	(segment
		(start 326.86244 -81.118964)
		(end 326.63892 -80.06588)
		(width 0.1143)
		(layer "In9.Cu")
		(net "P3E_CPU0_PE1_PCH_CON_TXN<12>")
	)
	(segment
		(start 326.375268 -76.146914)
		(end 326.40016 -76.029566)
		(width 0.1143)
		(layer "In9.Cu")
		(net "P3E_CPU0_PE1_PCH_CON_TXN<12>")
	)
	(segment
		(start 319.56756 -120.53316)
		(end 319.56756 -120.2563)
		(width 0.1143)
		(layer "In9.Cu")
		(net "P3E_CPU0_PE1_PCH_CON_TXN<12>")
	)
	(segment
		(start 417.172902 -5.917438)
		(end 417.947856 -6.081776)
		(width 0.1143)
		(layer "In9.Cu")
		(net "P3E_CPU0_PE1_PCH_CON_TXN<12>")
	)
	(segment
		(start 363.34954 -30.2895)
		(end 363.126274 -29.172916)
		(width 0.1143)
		(layer "In9.Cu")
		(net "P3E_CPU0_PE1_PCH_CON_TXN<12>")
	)
	(segment
		(start 327.714864 -63.430912)
		(end 328.519028 -59.327542)
		(width 0.1143)
		(layer "In9.Cu")
		(net "P3E_CPU0_PE1_PCH_CON_TXN<12>")
	)
	(segment
		(start 367.00079 -17.939512)
		(end 369.076224 -14.067028)
		(width 0.1143)
		(layer "In9.Cu")
		(net "P3E_CPU0_PE1_PCH_CON_TXN<12>")
	)
	(segment
		(start 433.509166 -5.857494)
		(end 439.681112 -8.570214)
		(width 0.1143)
		(layer "In9.Cu")
		(net "P3E_CPU0_PE1_PCH_CON_TXN<12>")
	)
	(segment
		(start 421.494966 -5.833872)
		(end 422.715182 -6.093206)
		(width 0.1143)
		(layer "In9.Cu")
		(net "P3E_CPU0_PE1_PCH_CON_TXN<12>")
	)
	(segment
		(start 317.8175 -118.474744)
		(end 318.163702 -117.221762)
		(width 0.1143)
		(layer "In9.Cu")
		(net "P3E_CPU0_PE1_PCH_CON_TXN<12>")
	)
	(segment
		(start 326.4662 -79.252064)
		(end 326.141334 -77.72273)
		(width 0.1143)
		(layer "In9.Cu")
		(net "P3E_CPU0_PE1_PCH_CON_TXN<12>")
	)
	(segment
		(start 395.002512 -8.385556)
		(end 404.183088 -4.959604)
		(width 0.1143)
		(layer "In9.Cu")
		(net "P3E_CPU0_PE1_PCH_CON_TXN<12>")
	)
	(segment
		(start 408.472894 -5.46354)
		(end 408.473402 -5.463794)
		(width 0.1143)
		(layer "In9.Cu")
		(net "P3E_CPU0_PE1_PCH_CON_TXN<12>")
	)
	(segment
		(start 328.870818 -98.24085)
		(end 328.299318 -95.55226)
		(width 0.1143)
		(layer "In9.Cu")
		(net "P3E_CPU0_PE1_PCH_CON_TXN<12>")
	)
	(segment
		(start 326.090026 -77.491336)
		(end 326.091042 -77.486002)
		(width 0.1143)
		(layer "In9.Cu")
		(net "P3E_CPU0_PE1_PCH_CON_TXN<12>")
	)
	(segment
		(start 415.529522 -6.266434)
		(end 417.172902 -5.917438)
		(width 0.1143)
		(layer "In9.Cu")
		(net "P3E_CPU0_PE1_PCH_CON_TXN<12>")
	)
	(segment
		(start 328.5363 -94.436692)
		(end 328.535792 -94.436946)
		(width 0.1143)
		(layer "In9.Cu")
		(net "P3E_CPU0_PE1_PCH_CON_TXN<12>")
	)
	(segment
		(start 369.076224 -14.067028)
		(end 371.314726 -12.312904)
		(width 0.1143)
		(layer "In9.Cu")
		(net "P3E_CPU0_PE1_PCH_CON_TXN<12>")
	)
	(segment
		(start 439.358532 -8.97509)
		(end 439.676286 -8.657336)
		(width 0.1143)
		(layer "F.Cu")
		(net "P3E_CPU0_PE1_PCH_CON_TXN<11>")
	)
	(segment
		(start 322.1355 -117.222016)
		(end 320.802 -117.222016)
		(width 0.1143)
		(layer "F.Cu")
		(net "P3E_CPU0_PE1_PCH_CON_TXN<11>")
	)
	(segment
		(start 439.358532 -9.824212)
		(end 439.358532 -8.97509)
		(width 0.1143)
		(layer "F.Cu")
		(net "P3E_CPU0_PE1_PCH_CON_TXN<11>")
	)
	(segment
		(start 320.802 -117.222016)
		(end 320.7258 -117.298216)
		(width 0.1143)
		(layer "F.Cu")
		(net "P3E_CPU0_PE1_PCH_CON_TXN<11>")
	)
	(segment
		(start 439.55843 -10.02411)
		(end 439.358532 -9.824212)
		(width 0.1143)
		(layer "F.Cu")
		(net "P3E_CPU0_PE1_PCH_CON_TXN<11>")
	)
	(segment
		(start 439.676286 -8.657336)
		(end 439.676286 -7.789672)
		(width 0.1143)
		(layer "F.Cu")
		(net "P3E_CPU0_PE1_PCH_CON_TXN<11>")
	)
	(segment
		(start 439.720482 -10.02411)
		(end 439.55843 -10.02411)
		(width 0.1143)
		(layer "F.Cu")
		(net "P3E_CPU0_PE1_PCH_CON_TXN<11>")
	)
	(via
		(at 439.720482 -10.02411)
		(size 0.508)
		(drill 0.254)
		(layers "F.Cu" "B.Cu")
		(net "P3E_CPU0_PE1_PCH_CON_TXN<11>")
	)
	(via
		(at 320.7258 -117.298216)
		(size 0.508)
		(drill 0.254)
		(layers "F.Cu" "B.Cu")
		(net "P3E_CPU0_PE1_PCH_CON_TXN<11>")
	)
	(segment
		(start 321.739768 -117.751098)
		(end 322.21043 -117.280436)
		(width 0.1143)
		(layer "In9.Cu")
		(net "P3E_CPU0_PE1_PCH_CON_TXN<11>")
	)
	(segment
		(start 363.806994 -29.198316)
		(end 364.333282 -26.566114)
		(width 0.1143)
		(layer "In9.Cu")
		(net "P3E_CPU0_PE1_PCH_CON_TXN<11>")
	)
	(segment
		(start 415.509456 -6.923278)
		(end 417.15055 -6.57479)
		(width 0.1143)
		(layer "In9.Cu")
		(net "P3E_CPU0_PE1_PCH_CON_TXN<11>")
	)
	(segment
		(start 394.283946 -10.066274)
		(end 394.419074 -10.153904)
		(width 0.1143)
		(layer "In9.Cu")
		(net "P3E_CPU0_PE1_PCH_CON_TXN<11>")
	)
	(segment
		(start 321.255136 -114.885978)
		(end 321.255136 -114.376962)
		(width 0.1143)
		(layer "In9.Cu")
		(net "P3E_CPU0_PE1_PCH_CON_TXN<11>")
	)
	(segment
		(start 327.011284 -83.34502)
		(end 327.533762 -81.208372)
		(width 0.1143)
		(layer "In9.Cu")
		(net "P3E_CPU0_PE1_PCH_CON_TXN<11>")
	)
	(segment
		(start 431.413158 -6.435852)
		(end 432.456844 -6.740652)
		(width 0.1143)
		(layer "In9.Cu")
		(net "P3E_CPU0_PE1_PCH_CON_TXN<11>")
	)
	(segment
		(start 331.470254 -53.104796)
		(end 331.624686 -53.059076)
		(width 0.1143)
		(layer "In9.Cu")
		(net "P3E_CPU0_PE1_PCH_CON_TXN<11>")
	)
	(segment
		(start 340.659466 -49.896522)
		(end 356.604062 -45.623226)
		(width 0.1143)
		(layer "In9.Cu")
		(net "P3E_CPU0_PE1_PCH_CON_TXN<11>")
	)
	(segment
		(start 321.255136 -112.802162)
		(end 321.540378 -112.51692)
		(width 0.1143)
		(layer "In9.Cu")
		(net "P3E_CPU0_PE1_PCH_CON_TXN<11>")
	)
	(segment
		(start 322.21043 -117.280436)
		(end 322.21043 -116.86032)
		(width 0.1143)
		(layer "In9.Cu")
		(net "P3E_CPU0_PE1_PCH_CON_TXN<11>")
	)
	(segment
		(start 420.28745 -6.743192)
		(end 421.47236 -6.491224)
		(width 0.1143)
		(layer "In9.Cu")
		(net "P3E_CPU0_PE1_PCH_CON_TXN<11>")
	)
	(segment
		(start 322.21043 -113.97742)
		(end 322.21043 -113.71072)
		(width 0.1143)
		(layer "In9.Cu")
		(net "P3E_CPU0_PE1_PCH_CON_TXN<11>")
	)
	(segment
		(start 330.18476 -55.486808)
		(end 329.7682 -55.260748)
		(width 0.1143)
		(layer "In9.Cu")
		(net "P3E_CPU0_PE1_PCH_CON_TXN<11>")
	)
	(segment
		(start 330.362306 -53.408326)
		(end 330.604876 -52.960524)
		(width 0.1143)
		(layer "In9.Cu")
		(net "P3E_CPU0_PE1_PCH_CON_TXN<11>")
	)
	(segment
		(start 426.316648 -6.462268)
		(end 427.609 -6.737096)
		(width 0.1143)
		(layer "In9.Cu")
		(net "P3E_CPU0_PE1_PCH_CON_TXN<11>")
	)
	(segment
		(start 329.530964 -98.280474)
		(end 328.958956 -95.588328)
		(width 0.1143)
		(layer "In9.Cu")
		(net "P3E_CPU0_PE1_PCH_CON_TXN<11>")
	)
	(segment
		(start 367.6015 -18.266156)
		(end 369.656106 -14.432788)
		(width 0.1143)
		(layer "In9.Cu")
		(net "P3E_CPU0_PE1_PCH_CON_TXN<11>")
	)
	(segment
		(start 322.675504 -110.037118)
		(end 327.09739 -105.951782)
		(width 0.1143)
		(layer "In9.Cu")
		(net "P3E_CPU0_PE1_PCH_CON_TXN<11>")
	)
	(segment
		(start 438.84088 -8.89508)
		(end 439.37555 -9.42975)
		(width 0.1143)
		(layer "In9.Cu")
		(net "P3E_CPU0_PE1_PCH_CON_TXN<11>")
	)
	(segment
		(start 327.097644 -105.951782)
		(end 329.244452 -102.050088)
		(width 0.1143)
		(layer "In9.Cu")
		(net "P3E_CPU0_PE1_PCH_CON_TXN<11>")
	)
	(segment
		(start 423.892726 -6.505194)
		(end 425.00296 -6.74116)
		(width 0.1143)
		(layer "In9.Cu")
		(net "P3E_CPU0_PE1_PCH_CON_TXN<11>")
	)
	(segment
		(start 327.09739 -105.951782)
		(end 327.097644 -105.951782)
		(width 0.1143)
		(layer "In9.Cu")
		(net "P3E_CPU0_PE1_PCH_CON_TXN<11>")
	)
	(segment
		(start 417.949126 -6.744208)
		(end 419.121336 -6.495288)
		(width 0.1143)
		(layer "In9.Cu")
		(net "P3E_CPU0_PE1_PCH_CON_TXN<11>")
	)
	(segment
		(start 321.540378 -115.17122)
		(end 321.255136 -114.885978)
		(width 0.1143)
		(layer "In9.Cu")
		(net "P3E_CPU0_PE1_PCH_CON_TXN<11>")
	)
	(segment
		(start 421.47236 -6.491224)
		(end 422.715182 -6.75513)
		(width 0.1143)
		(layer "In9.Cu")
		(net "P3E_CPU0_PE1_PCH_CON_TXN<11>")
	)
	(segment
		(start 359.404412 -42.71264)
		(end 360.835194 -35.759898)
		(width 0.1143)
		(layer "In9.Cu")
		(net "P3E_CPU0_PE1_PCH_CON_TXN<11>")
	)
	(segment
		(start 328.922634 -57.013602)
		(end 329.259184 -56.790336)
		(width 0.1143)
		(layer "In9.Cu")
		(net "P3E_CPU0_PE1_PCH_CON_TXN<11>")
	)
	(segment
		(start 329.49007 -58.087768)
		(end 329.376278 -57.916572)
		(width 0.1143)
		(layer "In9.Cu")
		(net "P3E_CPU0_PE1_PCH_CON_TXN<11>")
	)
	(segment
		(start 393.338304 -9.438386)
		(end 393.836144 -9.33196)
		(width 0.1143)
		(layer "In9.Cu")
		(net "P3E_CPU0_PE1_PCH_CON_TXN<11>")
	)
	(segment
		(start 330.230226 -55.640986)
		(end 330.18476 -55.486808)
		(width 0.1143)
		(layer "In9.Cu")
		(net "P3E_CPU0_PE1_PCH_CON_TXN<11>")
	)
	(segment
		(start 439.58383 -10.02411)
		(end 439.720482 -10.02411)
		(width 0.1143)
		(layer "In9.Cu")
		(net "P3E_CPU0_PE1_PCH_CON_TXN<11>")
	)
	(segment
		(start 334.491838 -50.201576)
		(end 338.32546 -49.421542)
		(width 0.1143)
		(layer "In9.Cu")
		(net "P3E_CPU0_PE1_PCH_CON_TXN<11>")
	)
	(segment
		(start 320.7258 -117.298216)
		(end 320.7258 -117.636798)
		(width 0.1143)
		(layer "In9.Cu")
		(net "P3E_CPU0_PE1_PCH_CON_TXN<11>")
	)
	(segment
		(start 330.477368 -53.794914)
		(end 330.362306 -53.408326)
		(width 0.1143)
		(layer "In9.Cu")
		(net "P3E_CPU0_PE1_PCH_CON_TXN<11>")
	)
	(segment
		(start 427.609 -6.737096)
		(end 428.690024 -6.507226)
		(width 0.1143)
		(layer "In9.Cu")
		(net "P3E_CPU0_PE1_PCH_CON_TXN<11>")
	)
	(segment
		(start 330.684378 -54.528974)
		(end 330.856082 -54.47792)
		(width 0.1143)
		(layer "In9.Cu")
		(net "P3E_CPU0_PE1_PCH_CON_TXN<11>")
	)
	(segment
		(start 327.284842 -71.92264)
		(end 326.973438 -70.457314)
		(width 0.1143)
		(layer "In9.Cu")
		(net "P3E_CPU0_PE1_PCH_CON_TXN<11>")
	)
	(segment
		(start 322.21043 -116.86032)
		(end 322.09613 -116.74602)
		(width 0.1143)
		(layer "In9.Cu")
		(net "P3E_CPU0_PE1_PCH_CON_TXN<11>")
	)
	(segment
		(start 439.37555 -9.81583)
		(end 439.58383 -10.02411)
		(width 0.1143)
		(layer "In9.Cu")
		(net "P3E_CPU0_PE1_PCH_CON_TXN<11>")
	)
	(segment
		(start 393.13993 -10.425938)
		(end 393.22756 -10.29081)
		(width 0.1143)
		(layer "In9.Cu")
		(net "P3E_CPU0_PE1_PCH_CON_TXN<11>")
	)
	(segment
		(start 371.58803 -12.918186)
		(end 379.431296 -11.250676)
		(width 0.1143)
		(layer "In9.Cu")
		(net "P3E_CPU0_PE1_PCH_CON_TXN<11>")
	)
	(segment
		(start 330.28255 -54.311296)
		(end 330.684378 -54.528974)
		(width 0.1143)
		(layer "In9.Cu")
		(net "P3E_CPU0_PE1_PCH_CON_TXN<11>")
	)
	(segment
		(start 321.255136 -114.376962)
		(end 321.540378 -114.09172)
		(width 0.1143)
		(layer "In9.Cu")
		(net "P3E_CPU0_PE1_PCH_CON_TXN<11>")
	)
	(segment
		(start 326.741536 -77.480668)
		(end 327.050908 -76.024232)
		(width 0.1143)
		(layer "In9.Cu")
		(net "P3E_CPU0_PE1_PCH_CON_TXN<11>")
	)
	(segment
		(start 394.174726 -9.552178)
		(end 394.283946 -10.066274)
		(width 0.1143)
		(layer "In9.Cu")
		(net "P3E_CPU0_PE1_PCH_CON_TXN<11>")
	)
	(segment
		(start 428.690024 -6.507226)
		(end 429.883824 -6.760718)
		(width 0.1143)
		(layer "In9.Cu")
		(net "P3E_CPU0_PE1_PCH_CON_TXN<11>")
	)
	(segment
		(start 328.958956 -95.588328)
		(end 329.285092 -94.053914)
		(width 0.1143)
		(layer "In9.Cu")
		(net "P3E_CPU0_PE1_PCH_CON_TXN<11>")
	)
	(segment
		(start 321.255136 -113.311178)
		(end 321.255136 -112.802162)
		(width 0.1143)
		(layer "In9.Cu")
		(net "P3E_CPU0_PE1_PCH_CON_TXN<11>")
	)
	(segment
		(start 322.09613 -113.59642)
		(end 321.540378 -113.59642)
		(width 0.1143)
		(layer "In9.Cu")
		(net "P3E_CPU0_PE1_PCH_CON_TXN<11>")
	)
	(segment
		(start 360.835194 -35.759898)
		(end 363.645958 -32.295846)
		(width 0.1143)
		(layer "In9.Cu")
		(net "P3E_CPU0_PE1_PCH_CON_TXN<11>")
	)
	(segment
		(start 366.070896 -25.409398)
		(end 367.6015 -18.266156)
		(width 0.1143)
		(layer "In9.Cu")
		(net "P3E_CPU0_PE1_PCH_CON_TXN<11>")
	)
	(segment
		(start 404.194518 -7.172198)
		(end 410.43987 -5.846826)
		(width 0.1143)
		(layer "In9.Cu")
		(net "P3E_CPU0_PE1_PCH_CON_TXN<11>")
	)
	(segment
		(start 425.00296 -6.74116)
		(end 426.316648 -6.462268)
		(width 0.1143)
		(layer "In9.Cu")
		(net "P3E_CPU0_PE1_PCH_CON_TXN<11>")
	)
	(segment
		(start 329.376278 -57.916572)
		(end 329.043538 -57.8485)
		(width 0.1143)
		(layer "In9.Cu")
		(net "P3E_CPU0_PE1_PCH_CON_TXN<11>")
	)
	(segment
		(start 364.333282 -26.566114)
		(end 366.070896 -25.409398)
		(width 0.1143)
		(layer "In9.Cu")
		(net "P3E_CPU0_PE1_PCH_CON_TXN<11>")
	)
	(segment
		(start 321.255136 -116.460778)
		(end 321.255136 -115.951762)
		(width 0.1143)
		(layer "In9.Cu")
		(net "P3E_CPU0_PE1_PCH_CON_TXN<11>")
	)
	(segment
		(start 330.991718 -52.845462)
		(end 331.470254 -53.104796)
		(width 0.1143)
		(layer "In9.Cu")
		(net "P3E_CPU0_PE1_PCH_CON_TXN<11>")
	)
	(segment
		(start 432.456844 -6.740652)
		(end 433.45608 -6.528308)
		(width 0.1143)
		(layer "In9.Cu")
		(net "P3E_CPU0_PE1_PCH_CON_TXN<11>")
	)
	(segment
		(start 322.21043 -112.40262)
		(end 322.21043 -110.963456)
		(width 0.1143)
		(layer "In9.Cu")
		(net "P3E_CPU0_PE1_PCH_CON_TXN<11>")
	)
	(segment
		(start 329.895708 -54.426358)
		(end 330.28255 -54.311296)
		(width 0.1143)
		(layer "In9.Cu")
		(net "P3E_CPU0_PE1_PCH_CON_TXN<11>")
	)
	(segment
		(start 379.431296 -11.250676)
		(end 379.431804 -11.250676)
		(width 0.1143)
		(layer "In9.Cu")
		(net "P3E_CPU0_PE1_PCH_CON_TXN<11>")
	)
	(segment
		(start 338.32546 -49.421542)
		(end 340.659466 -49.896522)
		(width 0.1143)
		(layer "In9.Cu")
		(net "P3E_CPU0_PE1_PCH_CON_TXN<11>")
	)
	(segment
		(start 328.82078 -57.512204)
		(end 328.922634 -57.013602)
		(width 0.1143)
		(layer "In9.Cu")
		(net "P3E_CPU0_PE1_PCH_CON_TXN<11>")
	)
	(segment
		(start 439.37555 -9.42975)
		(end 439.37555 -9.81583)
		(width 0.1143)
		(layer "In9.Cu")
		(net "P3E_CPU0_PE1_PCH_CON_TXN<11>")
	)
	(segment
		(start 321.540378 -114.09172)
		(end 322.09613 -114.09172)
		(width 0.1143)
		(layer "In9.Cu")
		(net "P3E_CPU0_PE1_PCH_CON_TXN<11>")
	)
	(segment
		(start 322.21043 -110.963456)
		(end 322.675504 -110.037118)
		(width 0.1143)
		(layer "In9.Cu")
		(net "P3E_CPU0_PE1_PCH_CON_TXN<11>")
	)
	(segment
		(start 379.431804 -11.250676)
		(end 380.312422 -11.437874)
		(width 0.1143)
		(layer "In9.Cu")
		(net "P3E_CPU0_PE1_PCH_CON_TXN<11>")
	)
	(segment
		(start 417.15055 -6.57479)
		(end 417.949126 -6.744208)
		(width 0.1143)
		(layer "In9.Cu")
		(net "P3E_CPU0_PE1_PCH_CON_TXN<11>")
	)
	(segment
		(start 394.419074 -10.153904)
		(end 395.318742 -9.962642)
		(width 0.1143)
		(layer "In9.Cu")
		(net "P3E_CPU0_PE1_PCH_CON_TXN<11>")
	)
	(segment
		(start 320.8401 -117.751098)
		(end 321.739768 -117.751098)
		(width 0.1143)
		(layer "In9.Cu")
		(net "P3E_CPU0_PE1_PCH_CON_TXN<11>")
	)
	(segment
		(start 322.09613 -115.17122)
		(end 321.540378 -115.17122)
		(width 0.1143)
		(layer "In9.Cu")
		(net "P3E_CPU0_PE1_PCH_CON_TXN<11>")
	)
	(segment
		(start 321.540378 -113.59642)
		(end 321.255136 -113.311178)
		(width 0.1143)
		(layer "In9.Cu")
		(net "P3E_CPU0_PE1_PCH_CON_TXN<11>")
	)
	(segment
		(start 327.050908 -76.024232)
		(end 326.732392 -74.523092)
		(width 0.1143)
		(layer "In9.Cu")
		(net "P3E_CPU0_PE1_PCH_CON_TXN<11>")
	)
	(segment
		(start 322.21043 -113.71072)
		(end 322.09613 -113.59642)
		(width 0.1143)
		(layer "In9.Cu")
		(net "P3E_CPU0_PE1_PCH_CON_TXN<11>")
	)
	(segment
		(start 391.7061 -10.730738)
		(end 393.13993 -10.425938)
		(width 0.1143)
		(layer "In9.Cu")
		(net "P3E_CPU0_PE1_PCH_CON_TXN<11>")
	)
	(segment
		(start 326.732392 -74.523092)
		(end 327.284842 -71.92264)
		(width 0.1143)
		(layer "In9.Cu")
		(net "P3E_CPU0_PE1_PCH_CON_TXN<11>")
	)
	(segment
		(start 387.676644 -9.87425)
		(end 391.7061 -10.730738)
		(width 0.1143)
		(layer "In9.Cu")
		(net "P3E_CPU0_PE1_PCH_CON_TXN<11>")
	)
	(segment
		(start 364.03661 -30.347412)
		(end 363.806994 -29.198316)
		(width 0.1143)
		(layer "In9.Cu")
		(net "P3E_CPU0_PE1_PCH_CON_TXN<11>")
	)
	(segment
		(start 322.09613 -115.66652)
		(end 322.21043 -115.55222)
		(width 0.1143)
		(layer "In9.Cu")
		(net "P3E_CPU0_PE1_PCH_CON_TXN<11>")
	)
	(segment
		(start 393.836144 -9.33196)
		(end 394.174726 -9.552178)
		(width 0.1143)
		(layer "In9.Cu")
		(net "P3E_CPU0_PE1_PCH_CON_TXN<11>")
	)
	(segment
		(start 331.624686 -53.059076)
		(end 332.299056 -51.81473)
		(width 0.1143)
		(layer "In9.Cu")
		(net "P3E_CPU0_PE1_PCH_CON_TXN<11>")
	)
	(segment
		(start 329.843384 -56.347868)
		(end 330.230226 -55.640986)
		(width 0.1143)
		(layer "In9.Cu")
		(net "P3E_CPU0_PE1_PCH_CON_TXN<11>")
	)
	(segment
		(start 327.533762 -81.208372)
		(end 326.741536 -77.480668)
		(width 0.1143)
		(layer "In9.Cu")
		(net "P3E_CPU0_PE1_PCH_CON_TXN<11>")
	)
	(segment
		(start 329.622404 -56.86425)
		(end 329.756516 -56.775604)
		(width 0.1143)
		(layer "In9.Cu")
		(net "P3E_CPU0_PE1_PCH_CON_TXN<11>")
	)
	(segment
		(start 320.7258 -117.636798)
		(end 320.8401 -117.751098)
		(width 0.1143)
		(layer "In9.Cu")
		(net "P3E_CPU0_PE1_PCH_CON_TXN<11>")
	)
	(segment
		(start 429.883824 -6.760718)
		(end 431.413158 -6.435852)
		(width 0.1143)
		(layer "In9.Cu")
		(net "P3E_CPU0_PE1_PCH_CON_TXN<11>")
	)
	(segment
		(start 393.118086 -9.77646)
		(end 393.338304 -9.438386)
		(width 0.1143)
		(layer "In9.Cu")
		(net "P3E_CPU0_PE1_PCH_CON_TXN<11>")
	)
	(segment
		(start 329.285092 -94.053914)
		(end 327.011284 -83.34502)
		(width 0.1143)
		(layer "In9.Cu")
		(net "P3E_CPU0_PE1_PCH_CON_TXN<11>")
	)
	(segment
		(start 369.656106 -14.432788)
		(end 371.58803 -12.918186)
		(width 0.1143)
		(layer "In9.Cu")
		(net "P3E_CPU0_PE1_PCH_CON_TXN<11>")
	)
	(segment
		(start 329.756516 -56.775604)
		(end 329.843384 -56.347868)
		(width 0.1143)
		(layer "In9.Cu")
		(net "P3E_CPU0_PE1_PCH_CON_TXN<11>")
	)
	(segment
		(start 356.604062 -45.623226)
		(end 358.528874 -44.363132)
		(width 0.1143)
		(layer "In9.Cu")
		(net "P3E_CPU0_PE1_PCH_CON_TXN<11>")
	)
	(segment
		(start 329.653138 -54.87416)
		(end 329.895708 -54.426358)
		(width 0.1143)
		(layer "In9.Cu")
		(net "P3E_CPU0_PE1_PCH_CON_TXN<11>")
	)
	(segment
		(start 380.312422 -11.437874)
		(end 387.676644 -9.87425)
		(width 0.1143)
		(layer "In9.Cu")
		(net "P3E_CPU0_PE1_PCH_CON_TXN<11>")
	)
	(segment
		(start 358.528874 -44.363132)
		(end 359.404412 -42.71264)
		(width 0.1143)
		(layer "In9.Cu")
		(net "P3E_CPU0_PE1_PCH_CON_TXN<11>")
	)
	(segment
		(start 329.7682 -55.260748)
		(end 329.653138 -54.87416)
		(width 0.1143)
		(layer "In9.Cu")
		(net "P3E_CPU0_PE1_PCH_CON_TXN<11>")
	)
	(segment
		(start 401.588224 -6.619748)
		(end 404.194518 -7.172198)
		(width 0.1143)
		(layer "In9.Cu")
		(net "P3E_CPU0_PE1_PCH_CON_TXN<11>")
	)
	(segment
		(start 322.21043 -115.55222)
		(end 322.21043 -115.28552)
		(width 0.1143)
		(layer "In9.Cu")
		(net "P3E_CPU0_PE1_PCH_CON_TXN<11>")
	)
	(segment
		(start 329.259184 -56.790336)
		(end 329.622404 -56.86425)
		(width 0.1143)
		(layer "In9.Cu")
		(net "P3E_CPU0_PE1_PCH_CON_TXN<11>")
	)
	(segment
		(start 321.540378 -116.74602)
		(end 321.255136 -116.460778)
		(width 0.1143)
		(layer "In9.Cu")
		(net "P3E_CPU0_PE1_PCH_CON_TXN<11>")
	)
	(segment
		(start 363.645958 -32.295846)
		(end 364.03661 -30.347412)
		(width 0.1143)
		(layer "In9.Cu")
		(net "P3E_CPU0_PE1_PCH_CON_TXN<11>")
	)
	(segment
		(start 433.45608 -6.528308)
		(end 438.84088 -8.89508)
		(width 0.1143)
		(layer "In9.Cu")
		(net "P3E_CPU0_PE1_PCH_CON_TXN<11>")
	)
	(segment
		(start 393.22756 -10.29081)
		(end 393.118086 -9.77646)
		(width 0.1143)
		(layer "In9.Cu")
		(net "P3E_CPU0_PE1_PCH_CON_TXN<11>")
	)
	(segment
		(start 322.21043 -115.28552)
		(end 322.09613 -115.17122)
		(width 0.1143)
		(layer "In9.Cu")
		(net "P3E_CPU0_PE1_PCH_CON_TXN<11>")
	)
	(segment
		(start 322.09613 -112.51692)
		(end 322.21043 -112.40262)
		(width 0.1143)
		(layer "In9.Cu")
		(net "P3E_CPU0_PE1_PCH_CON_TXN<11>")
	)
	(segment
		(start 321.255136 -115.951762)
		(end 321.540378 -115.66652)
		(width 0.1143)
		(layer "In9.Cu")
		(net "P3E_CPU0_PE1_PCH_CON_TXN<11>")
	)
	(segment
		(start 330.856082 -54.47792)
		(end 330.983844 -54.242208)
		(width 0.1143)
		(layer "In9.Cu")
		(net "P3E_CPU0_PE1_PCH_CON_TXN<11>")
	)
	(segment
		(start 395.318742 -9.962642)
		(end 396.494 -8.521192)
		(width 0.1143)
		(layer "In9.Cu")
		(net "P3E_CPU0_PE1_PCH_CON_TXN<11>")
	)
	(segment
		(start 330.983844 -54.242208)
		(end 330.922376 -54.036468)
		(width 0.1143)
		(layer "In9.Cu")
		(net "P3E_CPU0_PE1_PCH_CON_TXN<11>")
	)
	(segment
		(start 332.33106 -51.755548)
		(end 334.491838 -50.201576)
		(width 0.1143)
		(layer "In9.Cu")
		(net "P3E_CPU0_PE1_PCH_CON_TXN<11>")
	)
	(segment
		(start 419.121336 -6.495288)
		(end 420.28745 -6.743192)
		(width 0.1143)
		(layer "In9.Cu")
		(net "P3E_CPU0_PE1_PCH_CON_TXN<11>")
	)
	(segment
		(start 322.09613 -114.09172)
		(end 322.21043 -113.97742)
		(width 0.1143)
		(layer "In9.Cu")
		(net "P3E_CPU0_PE1_PCH_CON_TXN<11>")
	)
	(segment
		(start 321.540378 -112.51692)
		(end 322.09613 -112.51692)
		(width 0.1143)
		(layer "In9.Cu")
		(net "P3E_CPU0_PE1_PCH_CON_TXN<11>")
	)
	(segment
		(start 422.715182 -6.75513)
		(end 423.892726 -6.505194)
		(width 0.1143)
		(layer "In9.Cu")
		(net "P3E_CPU0_PE1_PCH_CON_TXN<11>")
	)
	(segment
		(start 330.922376 -54.036468)
		(end 330.477368 -53.794914)
		(width 0.1143)
		(layer "In9.Cu")
		(net "P3E_CPU0_PE1_PCH_CON_TXN<11>")
	)
	(segment
		(start 410.43987 -5.846826)
		(end 415.509456 -6.923278)
		(width 0.1143)
		(layer "In9.Cu")
		(net "P3E_CPU0_PE1_PCH_CON_TXN<11>")
	)
	(segment
		(start 326.973438 -70.457314)
		(end 329.49007 -58.087768)
		(width 0.1143)
		(layer "In9.Cu")
		(net "P3E_CPU0_PE1_PCH_CON_TXN<11>")
	)
	(segment
		(start 329.043538 -57.8485)
		(end 328.82078 -57.512204)
		(width 0.1143)
		(layer "In9.Cu")
		(net "P3E_CPU0_PE1_PCH_CON_TXN<11>")
	)
	(segment
		(start 321.540378 -115.66652)
		(end 322.09613 -115.66652)
		(width 0.1143)
		(layer "In9.Cu")
		(net "P3E_CPU0_PE1_PCH_CON_TXN<11>")
	)
	(segment
		(start 330.604876 -52.960524)
		(end 330.991718 -52.845462)
		(width 0.1143)
		(layer "In9.Cu")
		(net "P3E_CPU0_PE1_PCH_CON_TXN<11>")
	)
	(segment
		(start 332.299056 -51.81473)
		(end 332.33106 -51.755548)
		(width 0.1143)
		(layer "In9.Cu")
		(net "P3E_CPU0_PE1_PCH_CON_TXN<11>")
	)
	(segment
		(start 322.09613 -116.74602)
		(end 321.540378 -116.74602)
		(width 0.1143)
		(layer "In9.Cu")
		(net "P3E_CPU0_PE1_PCH_CON_TXN<11>")
	)
	(segment
		(start 329.244452 -102.050088)
		(end 329.530964 -98.280474)
		(width 0.1143)
		(layer "In9.Cu")
		(net "P3E_CPU0_PE1_PCH_CON_TXN<11>")
	)
	(segment
		(start 396.494 -8.521192)
		(end 401.588224 -6.619748)
		(width 0.1143)
		(layer "In9.Cu")
		(net "P3E_CPU0_PE1_PCH_CON_TXN<11>")
	)
	(segment
		(start 436.964582 -9.965182)
		(end 437.12892 -10.12952)
		(width 0.1143)
		(layer "F.Cu")
		(net "P3E_CPU0_PE1_PCH_CON_TXN<10>")
	)
	(segment
		(start 437.275986 -7.789672)
		(end 437.275986 -8.657336)
		(width 0.1143)
		(layer "F.Cu")
		(net "P3E_CPU0_PE1_PCH_CON_TXN<10>")
	)
	(segment
		(start 437.275986 -8.657336)
		(end 436.964582 -8.96874)
		(width 0.1143)
		(layer "F.Cu")
		(net "P3E_CPU0_PE1_PCH_CON_TXN<10>")
	)
	(segment
		(start 335.85404 -121.282968)
		(end 336.515202 -121.282968)
		(width 0.1143)
		(layer "F.Cu")
		(net "P3E_CPU0_PE1_PCH_CON_TXN<10>")
	)
	(segment
		(start 437.12892 -10.12952)
		(end 437.326532 -10.12952)
		(width 0.1143)
		(layer "F.Cu")
		(net "P3E_CPU0_PE1_PCH_CON_TXN<10>")
	)
	(segment
		(start 436.964582 -8.96874)
		(end 436.964582 -9.965182)
		(width 0.1143)
		(layer "F.Cu")
		(net "P3E_CPU0_PE1_PCH_CON_TXN<10>")
	)
	(via
		(at 437.326532 -10.12952)
		(size 0.508)
		(drill 0.254)
		(layers "F.Cu" "B.Cu")
		(net "P3E_CPU0_PE1_PCH_CON_TXN<10>")
	)
	(via
		(at 335.85404 -121.282968)
		(size 0.508)
		(drill 0.254)
		(layers "F.Cu" "B.Cu")
		(net "P3E_CPU0_PE1_PCH_CON_TXN<10>")
	)
	(segment
		(start 329.95489 -94.134686)
		(end 327.68286 -83.43265)
		(width 0.1143)
		(layer "In9.Cu")
		(net "P3E_CPU0_PE1_PCH_CON_TXN<10>")
	)
	(segment
		(start 323.199506 -110.468664)
		(end 327.610724 -106.39298)
		(width 0.1143)
		(layer "In9.Cu")
		(net "P3E_CPU0_PE1_PCH_CON_TXN<10>")
	)
	(segment
		(start 327.936606 -71.92264)
		(end 327.63206 -70.489064)
		(width 0.1143)
		(layer "In9.Cu")
		(net "P3E_CPU0_PE1_PCH_CON_TXN<10>")
	)
	(segment
		(start 329.933808 -102.17023)
		(end 330.216764 -98.442272)
		(width 0.1143)
		(layer "In9.Cu")
		(net "P3E_CPU0_PE1_PCH_CON_TXN<10>")
	)
	(segment
		(start 387.624066 -10.540492)
		(end 391.691368 -11.405108)
		(width 0.1143)
		(layer "In9.Cu")
		(net "P3E_CPU0_PE1_PCH_CON_TXN<10>")
	)
	(segment
		(start 401.99945 -7.46379)
		(end 403.986238 -7.885176)
		(width 0.1143)
		(layer "In9.Cu")
		(net "P3E_CPU0_PE1_PCH_CON_TXN<10>")
	)
	(segment
		(start 432.457352 -7.415022)
		(end 433.399184 -7.214362)
		(width 0.1143)
		(layer "In9.Cu")
		(net "P3E_CPU0_PE1_PCH_CON_TXN<10>")
	)
	(segment
		(start 334.773524 -50.831496)
		(end 338.325206 -50.108612)
		(width 0.1143)
		(layer "In9.Cu")
		(net "P3E_CPU0_PE1_PCH_CON_TXN<10>")
	)
	(segment
		(start 360.03611 -42.92092)
		(end 361.454192 -36.030408)
		(width 0.1143)
		(layer "In9.Cu")
		(net "P3E_CPU0_PE1_PCH_CON_TXN<10>")
	)
	(segment
		(start 330.446126 -56.656732)
		(end 332.85557 -52.21097)
		(width 0.1143)
		(layer "In9.Cu")
		(net "P3E_CPU0_PE1_PCH_CON_TXN<10>")
	)
	(segment
		(start 421.47236 -7.153402)
		(end 422.714928 -7.417308)
		(width 0.1143)
		(layer "In9.Cu")
		(net "P3E_CPU0_PE1_PCH_CON_TXN<10>")
	)
	(segment
		(start 433.399184 -7.214362)
		(end 436.107078 -8.404606)
		(width 0.1143)
		(layer "In9.Cu")
		(net "P3E_CPU0_PE1_PCH_CON_TXN<10>")
	)
	(segment
		(start 424.987466 -7.400036)
		(end 426.301154 -7.121144)
		(width 0.1143)
		(layer "In9.Cu")
		(net "P3E_CPU0_PE1_PCH_CON_TXN<10>")
	)
	(segment
		(start 327.68286 -83.43265)
		(end 328.204576 -81.298288)
		(width 0.1143)
		(layer "In9.Cu")
		(net "P3E_CPU0_PE1_PCH_CON_TXN<10>")
	)
	(segment
		(start 420.287704 -7.40537)
		(end 421.47236 -7.153402)
		(width 0.1143)
		(layer "In9.Cu")
		(net "P3E_CPU0_PE1_PCH_CON_TXN<10>")
	)
	(segment
		(start 331.299312 -120.747536)
		(end 330.78547 -120.233694)
		(width 0.1143)
		(layer "In9.Cu")
		(net "P3E_CPU0_PE1_PCH_CON_TXN<10>")
	)
	(segment
		(start 417.13785 -7.234174)
		(end 417.923472 -7.401052)
		(width 0.1143)
		(layer "In9.Cu")
		(net "P3E_CPU0_PE1_PCH_CON_TXN<10>")
	)
	(segment
		(start 364.464346 -29.155898)
		(end 364.901734 -26.966672)
		(width 0.1143)
		(layer "In9.Cu")
		(net "P3E_CPU0_PE1_PCH_CON_TXN<10>")
	)
	(segment
		(start 356.89667 -46.205902)
		(end 359.037128 -44.804584)
		(width 0.1143)
		(layer "In9.Cu")
		(net "P3E_CPU0_PE1_PCH_CON_TXN<10>")
	)
	(segment
		(start 335.85404 -121.282968)
		(end 335.85404 -121.136664)
		(width 0.1143)
		(layer "In9.Cu")
		(net "P3E_CPU0_PE1_PCH_CON_TXN<10>")
	)
	(segment
		(start 330.78547 -120.233694)
		(end 325.580502 -120.233694)
		(width 0.1143)
		(layer "In9.Cu")
		(net "P3E_CPU0_PE1_PCH_CON_TXN<10>")
	)
	(segment
		(start 368.261646 -18.421858)
		(end 370.229384 -14.796516)
		(width 0.1143)
		(layer "In9.Cu")
		(net "P3E_CPU0_PE1_PCH_CON_TXN<10>")
	)
	(segment
		(start 419.095682 -7.152132)
		(end 420.287704 -7.40537)
		(width 0.1143)
		(layer "In9.Cu")
		(net "P3E_CPU0_PE1_PCH_CON_TXN<10>")
	)
	(segment
		(start 410.463746 -6.510528)
		(end 415.50336 -7.581392)
		(width 0.1143)
		(layer "In9.Cu")
		(net "P3E_CPU0_PE1_PCH_CON_TXN<10>")
	)
	(segment
		(start 429.871124 -7.420102)
		(end 431.377598 -7.099808)
		(width 0.1143)
		(layer "In9.Cu")
		(net "P3E_CPU0_PE1_PCH_CON_TXN<10>")
	)
	(segment
		(start 329.628754 -95.671894)
		(end 329.95489 -94.134686)
		(width 0.1143)
		(layer "In9.Cu")
		(net "P3E_CPU0_PE1_PCH_CON_TXN<10>")
	)
	(segment
		(start 371.84965 -13.52423)
		(end 379.454156 -11.908282)
		(width 0.1143)
		(layer "In9.Cu")
		(net "P3E_CPU0_PE1_PCH_CON_TXN<10>")
	)
	(segment
		(start 327.63206 -70.489064)
		(end 330.446126 -56.656732)
		(width 0.1143)
		(layer "In9.Cu")
		(net "P3E_CPU0_PE1_PCH_CON_TXN<10>")
	)
	(segment
		(start 415.50336 -7.581392)
		(end 417.13785 -7.234174)
		(width 0.1143)
		(layer "In9.Cu")
		(net "P3E_CPU0_PE1_PCH_CON_TXN<10>")
	)
	(segment
		(start 398.872202 -8.63092)
		(end 401.99945 -7.46379)
		(width 0.1143)
		(layer "In9.Cu")
		(net "P3E_CPU0_PE1_PCH_CON_TXN<10>")
	)
	(segment
		(start 361.454192 -36.030408)
		(end 364.231936 -32.606488)
		(width 0.1143)
		(layer "In9.Cu")
		(net "P3E_CPU0_PE1_PCH_CON_TXN<10>")
	)
	(segment
		(start 335.85404 -121.136664)
		(end 335.464912 -120.747536)
		(width 0.1143)
		(layer "In9.Cu")
		(net "P3E_CPU0_PE1_PCH_CON_TXN<10>")
	)
	(segment
		(start 359.037128 -44.804584)
		(end 360.03611 -42.92092)
		(width 0.1143)
		(layer "In9.Cu")
		(net "P3E_CPU0_PE1_PCH_CON_TXN<10>")
	)
	(segment
		(start 423.892726 -7.167372)
		(end 424.987466 -7.400036)
		(width 0.1143)
		(layer "In9.Cu")
		(net "P3E_CPU0_PE1_PCH_CON_TXN<10>")
	)
	(segment
		(start 325.580502 -120.233694)
		(end 323.199506 -117.852698)
		(width 0.1143)
		(layer "In9.Cu")
		(net "P3E_CPU0_PE1_PCH_CON_TXN<10>")
	)
	(segment
		(start 366.65916 -25.796494)
		(end 368.261646 -18.421858)
		(width 0.1143)
		(layer "In9.Cu")
		(net "P3E_CPU0_PE1_PCH_CON_TXN<10>")
	)
	(segment
		(start 397.903192 -10.085324)
		(end 398.872202 -8.63092)
		(width 0.1143)
		(layer "In9.Cu")
		(net "P3E_CPU0_PE1_PCH_CON_TXN<10>")
	)
	(segment
		(start 428.710852 -7.173722)
		(end 429.871124 -7.420102)
		(width 0.1143)
		(layer "In9.Cu")
		(net "P3E_CPU0_PE1_PCH_CON_TXN<10>")
	)
	(segment
		(start 327.384156 -74.523346)
		(end 327.936606 -71.92264)
		(width 0.1143)
		(layer "In9.Cu")
		(net "P3E_CPU0_PE1_PCH_CON_TXN<10>")
	)
	(segment
		(start 327.702672 -76.024232)
		(end 327.384156 -74.523346)
		(width 0.1143)
		(layer "In9.Cu")
		(net "P3E_CPU0_PE1_PCH_CON_TXN<10>")
	)
	(segment
		(start 340.607142 -50.57267)
		(end 356.89667 -46.205902)
		(width 0.1143)
		(layer "In9.Cu")
		(net "P3E_CPU0_PE1_PCH_CON_TXN<10>")
	)
	(segment
		(start 431.377598 -7.099808)
		(end 432.457352 -7.415022)
		(width 0.1143)
		(layer "In9.Cu")
		(net "P3E_CPU0_PE1_PCH_CON_TXN<10>")
	)
	(segment
		(start 380.317756 -12.09167)
		(end 387.624066 -10.540492)
		(width 0.1143)
		(layer "In9.Cu")
		(net "P3E_CPU0_PE1_PCH_CON_TXN<10>")
	)
	(segment
		(start 436.989982 -9.965436)
		(end 437.154066 -10.12952)
		(width 0.1143)
		(layer "In9.Cu")
		(net "P3E_CPU0_PE1_PCH_CON_TXN<10>")
	)
	(segment
		(start 332.85557 -52.21097)
		(end 334.773524 -50.831496)
		(width 0.1143)
		(layer "In9.Cu")
		(net "P3E_CPU0_PE1_PCH_CON_TXN<10>")
	)
	(segment
		(start 436.989982 -9.287764)
		(end 436.989982 -9.965436)
		(width 0.1143)
		(layer "In9.Cu")
		(net "P3E_CPU0_PE1_PCH_CON_TXN<10>")
	)
	(segment
		(start 426.301154 -7.121144)
		(end 427.62932 -7.403592)
		(width 0.1143)
		(layer "In9.Cu")
		(net "P3E_CPU0_PE1_PCH_CON_TXN<10>")
	)
	(segment
		(start 338.325206 -50.108612)
		(end 340.607142 -50.57267)
		(width 0.1143)
		(layer "In9.Cu")
		(net "P3E_CPU0_PE1_PCH_CON_TXN<10>")
	)
	(segment
		(start 327.3933 -77.480668)
		(end 327.702672 -76.024232)
		(width 0.1143)
		(layer "In9.Cu")
		(net "P3E_CPU0_PE1_PCH_CON_TXN<10>")
	)
	(segment
		(start 335.464912 -120.747536)
		(end 331.299312 -120.747536)
		(width 0.1143)
		(layer "In9.Cu")
		(net "P3E_CPU0_PE1_PCH_CON_TXN<10>")
	)
	(segment
		(start 330.216764 -98.442272)
		(end 329.628754 -95.671894)
		(width 0.1143)
		(layer "In9.Cu")
		(net "P3E_CPU0_PE1_PCH_CON_TXN<10>")
	)
	(segment
		(start 327.610724 -106.39298)
		(end 329.933808 -102.17023)
		(width 0.1143)
		(layer "In9.Cu")
		(net "P3E_CPU0_PE1_PCH_CON_TXN<10>")
	)
	(segment
		(start 323.199506 -117.852698)
		(end 323.199506 -110.468664)
		(width 0.1143)
		(layer "In9.Cu")
		(net "P3E_CPU0_PE1_PCH_CON_TXN<10>")
	)
	(segment
		(start 436.107078 -8.404606)
		(end 436.989982 -9.287764)
		(width 0.1143)
		(layer "In9.Cu")
		(net "P3E_CPU0_PE1_PCH_CON_TXN<10>")
	)
	(segment
		(start 364.231936 -32.606488)
		(end 364.693454 -30.302454)
		(width 0.1143)
		(layer "In9.Cu")
		(net "P3E_CPU0_PE1_PCH_CON_TXN<10>")
	)
	(segment
		(start 422.714928 -7.417308)
		(end 423.892726 -7.167372)
		(width 0.1143)
		(layer "In9.Cu")
		(net "P3E_CPU0_PE1_PCH_CON_TXN<10>")
	)
	(segment
		(start 437.154066 -10.12952)
		(end 437.326532 -10.12952)
		(width 0.1143)
		(layer "In9.Cu")
		(net "P3E_CPU0_PE1_PCH_CON_TXN<10>")
	)
	(segment
		(start 328.204576 -81.298288)
		(end 327.3933 -77.480668)
		(width 0.1143)
		(layer "In9.Cu")
		(net "P3E_CPU0_PE1_PCH_CON_TXN<10>")
	)
	(segment
		(start 364.901734 -26.966672)
		(end 366.65916 -25.796494)
		(width 0.1143)
		(layer "In9.Cu")
		(net "P3E_CPU0_PE1_PCH_CON_TXN<10>")
	)
	(segment
		(start 427.62932 -7.403592)
		(end 428.710852 -7.173722)
		(width 0.1143)
		(layer "In9.Cu")
		(net "P3E_CPU0_PE1_PCH_CON_TXN<10>")
	)
	(segment
		(start 364.693454 -30.302454)
		(end 364.464346 -29.155898)
		(width 0.1143)
		(layer "In9.Cu")
		(net "P3E_CPU0_PE1_PCH_CON_TXN<10>")
	)
	(segment
		(start 417.923472 -7.401052)
		(end 419.095682 -7.152132)
		(width 0.1143)
		(layer "In9.Cu")
		(net "P3E_CPU0_PE1_PCH_CON_TXN<10>")
	)
	(segment
		(start 379.454156 -11.908282)
		(end 380.317756 -12.09167)
		(width 0.1143)
		(layer "In9.Cu")
		(net "P3E_CPU0_PE1_PCH_CON_TXN<10>")
	)
	(segment
		(start 370.229384 -14.796516)
		(end 371.84965 -13.52423)
		(width 0.1143)
		(layer "In9.Cu")
		(net "P3E_CPU0_PE1_PCH_CON_TXN<10>")
	)
	(segment
		(start 403.986238 -7.885176)
		(end 410.463746 -6.510528)
		(width 0.1143)
		(layer "In9.Cu")
		(net "P3E_CPU0_PE1_PCH_CON_TXN<10>")
	)
	(segment
		(start 391.691368 -11.405108)
		(end 397.903192 -10.085324)
		(width 0.1143)
		(layer "In9.Cu")
		(net "P3E_CPU0_PE1_PCH_CON_TXN<10>")
	)
	(segment
		(start 433.275486 -3.758184)
		(end 433.275486 -4.386072)
		(width 0.1143)
		(layer "F.Cu")
		(net "P3E_CPU0_PE1_PCH_CON_RXP<9>")
	)
	(segment
		(start 433.011834 -2.860294)
		(end 433.37988 -2.860294)
		(width 0.1143)
		(layer "F.Cu")
		(net "P3E_CPU0_PE1_PCH_CON_RXP<9>")
	)
	(segment
		(start 433.531518 -3.011932)
		(end 433.531518 -3.502152)
		(width 0.1143)
		(layer "F.Cu")
		(net "P3E_CPU0_PE1_PCH_CON_RXP<9>")
	)
	(segment
		(start 433.531518 -3.502152)
		(end 433.275486 -3.758184)
		(width 0.1143)
		(layer "F.Cu")
		(net "P3E_CPU0_PE1_PCH_CON_RXP<9>")
	)
	(segment
		(start 433.37988 -2.860294)
		(end 433.531518 -3.011932)
		(width 0.1143)
		(layer "F.Cu")
		(net "P3E_CPU0_PE1_PCH_CON_RXP<9>")
	)
	(via
		(at 366.278414 -124.262642)
		(size 0.508)
		(drill 0.254)
		(layers "F.Cu" "B.Cu")
		(net "P3E_CPU0_PE1_PCH_CON_RXP<9>")
	)
	(via
		(at 433.011834 -2.860294)
		(size 0.508)
		(drill 0.254)
		(layers "F.Cu" "B.Cu")
		(net "P3E_CPU0_PE1_PCH_CON_RXP<9>")
	)
	(segment
		(start 366.405414 -124.389642)
		(end 366.278414 -124.262642)
		(width 0.1143)
		(layer "B.Cu")
		(net "P3E_CPU0_PE1_PCH_CON_RXP<9>")
	)
	(segment
		(start 366.938814 -124.389642)
		(end 366.405414 -124.389642)
		(width 0.1143)
		(layer "B.Cu")
		(net "P3E_CPU0_PE1_PCH_CON_RXP<9>")
	)
	(segment
		(start 366.278414 -124.262642)
		(end 366.278414 -124.688346)
		(width 0.1143)
		(layer "In9.Cu")
		(net "P3E_CPU0_PE1_PCH_CON_RXP<9>")
	)
	(segment
		(start 379.01118 -19.539458)
		(end 380.591568 -18.433796)
		(width 0.1143)
		(layer "In9.Cu")
		(net "P3E_CPU0_PE1_PCH_CON_RXP<9>")
	)
	(segment
		(start 363.39272 -120.938798)
		(end 366.113314 -118.218204)
		(width 0.1143)
		(layer "In9.Cu")
		(net "P3E_CPU0_PE1_PCH_CON_RXP<9>")
	)
	(segment
		(start 365.151162 -49.148492)
		(end 369.682014 -45.394118)
		(width 0.1143)
		(layer "In9.Cu")
		(net "P3E_CPU0_PE1_PCH_CON_RXP<9>")
	)
	(segment
		(start 363.8296 -89.588594)
		(end 363.8296 -75.0062)
		(width 0.1143)
		(layer "In9.Cu")
		(net "P3E_CPU0_PE1_PCH_CON_RXP<9>")
	)
	(segment
		(start 371.067076 -38.473634)
		(end 370.963444 -37.955728)
		(width 0.1143)
		(layer "In9.Cu")
		(net "P3E_CPU0_PE1_PCH_CON_RXP<9>")
	)
	(segment
		(start 429.354996 -17.116552)
		(end 431.301144 -17.512284)
		(width 0.1143)
		(layer "In9.Cu")
		(net "P3E_CPU0_PE1_PCH_CON_RXP<9>")
	)
	(segment
		(start 361.690158 -67.238372)
		(end 363.215428 -60.056014)
		(width 0.1143)
		(layer "In9.Cu")
		(net "P3E_CPU0_PE1_PCH_CON_RXP<9>")
	)
	(segment
		(start 377.741434 -20.1549)
		(end 379.01118 -19.539458)
		(width 0.1143)
		(layer "In9.Cu")
		(net "P3E_CPU0_PE1_PCH_CON_RXP<9>")
	)
	(segment
		(start 418.01161 -15.07363)
		(end 428.558198 -17.28597)
		(width 0.1143)
		(layer "In9.Cu")
		(net "P3E_CPU0_PE1_PCH_CON_RXP<9>")
	)
	(segment
		(start 414.637474 -15.7861)
		(end 418.01161 -15.07363)
		(width 0.1143)
		(layer "In9.Cu")
		(net "P3E_CPU0_PE1_PCH_CON_RXP<9>")
	)
	(segment
		(start 451.57771 -16.770858)
		(end 451.63486 -16.713708)
		(width 0.1143)
		(layer "In9.Cu")
		(net "P3E_CPU0_PE1_PCH_CON_RXP<9>")
	)
	(segment
		(start 371.884448 -33.351724)
		(end 372.243604 -32.813244)
		(width 0.1143)
		(layer "In9.Cu")
		(net "P3E_CPU0_PE1_PCH_CON_RXP<9>")
	)
	(segment
		(start 363.8296 -75.0062)
		(end 362.932472 -74.109072)
		(width 0.1143)
		(layer "In9.Cu")
		(net "P3E_CPU0_PE1_PCH_CON_RXP<9>")
	)
	(segment
		(start 433.488592 -2.740152)
		(end 433.36845 -2.860294)
		(width 0.1143)
		(layer "In9.Cu")
		(net "P3E_CPU0_PE1_PCH_CON_RXP<9>")
	)
	(segment
		(start 454.735946 -6.191504)
		(end 454.842372 -5.657088)
		(width 0.1143)
		(layer "In9.Cu")
		(net "P3E_CPU0_PE1_PCH_CON_RXP<9>")
	)
	(segment
		(start 453.165464 -14.502638)
		(end 452.695056 -12.289028)
		(width 0.1143)
		(layer "In9.Cu")
		(net "P3E_CPU0_PE1_PCH_CON_RXP<9>")
	)
	(segment
		(start 364.031784 -52.427632)
		(end 365.151162 -49.148492)
		(width 0.1143)
		(layer "In9.Cu")
		(net "P3E_CPU0_PE1_PCH_CON_RXP<9>")
	)
	(segment
		(start 434.861462 -18.506186)
		(end 435.648354 -18.690082)
		(width 0.1143)
		(layer "In9.Cu")
		(net "P3E_CPU0_PE1_PCH_CON_RXP<9>")
	)
	(segment
		(start 366.113314 -110.55858)
		(end 363.970316 -108.415582)
		(width 0.1143)
		(layer "In9.Cu")
		(net "P3E_CPU0_PE1_PCH_CON_RXP<9>")
	)
	(segment
		(start 453.72655 -10.19429)
		(end 453.72655 -10.193782)
		(width 0.1143)
		(layer "In9.Cu")
		(net "P3E_CPU0_PE1_PCH_CON_RXP<9>")
	)
	(segment
		(start 370.963444 -37.955728)
		(end 371.884448 -33.351724)
		(width 0.1143)
		(layer "In9.Cu")
		(net "P3E_CPU0_PE1_PCH_CON_RXP<9>")
	)
	(segment
		(start 407.809446 -14.339062)
		(end 414.637474 -15.7861)
		(width 0.1143)
		(layer "In9.Cu")
		(net "P3E_CPU0_PE1_PCH_CON_RXP<9>")
	)
	(segment
		(start 387.27888 -17.014444)
		(end 391.251948 -17.85874)
		(width 0.1143)
		(layer "In9.Cu")
		(net "P3E_CPU0_PE1_PCH_CON_RXP<9>")
	)
	(segment
		(start 364.697264 -93.86824)
		(end 363.8296 -89.588594)
		(width 0.1143)
		(layer "In9.Cu")
		(net "P3E_CPU0_PE1_PCH_CON_RXP<9>")
	)
	(segment
		(start 366.113314 -118.218204)
		(end 366.113314 -110.55858)
		(width 0.1143)
		(layer "In9.Cu")
		(net "P3E_CPU0_PE1_PCH_CON_RXP<9>")
	)
	(segment
		(start 362.300266 -72.095614)
		(end 361.702858 -69.28358)
		(width 0.1143)
		(layer "In9.Cu")
		(net "P3E_CPU0_PE1_PCH_CON_RXP<9>")
	)
	(segment
		(start 372.243604 -32.813244)
		(end 372.82501 -31.941008)
		(width 0.1143)
		(layer "In9.Cu")
		(net "P3E_CPU0_PE1_PCH_CON_RXP<9>")
	)
	(segment
		(start 364.912402 -56.576976)
		(end 364.031784 -52.427632)
		(width 0.1143)
		(layer "In9.Cu")
		(net "P3E_CPU0_PE1_PCH_CON_RXP<9>")
	)
	(segment
		(start 436.309262 -18.557494)
		(end 437.197754 -18.735548)
		(width 0.1143)
		(layer "In9.Cu")
		(net "P3E_CPU0_PE1_PCH_CON_RXP<9>")
	)
	(segment
		(start 363.970316 -105.929684)
		(end 364.697264 -105.202736)
		(width 0.1143)
		(layer "In9.Cu")
		(net "P3E_CPU0_PE1_PCH_CON_RXP<9>")
	)
	(segment
		(start 452.850758 -11.508232)
		(end 453.72655 -10.19429)
		(width 0.1143)
		(layer "In9.Cu")
		(net "P3E_CPU0_PE1_PCH_CON_RXP<9>")
	)
	(segment
		(start 366.278414 -124.688346)
		(end 366.16386 -124.8029)
		(width 0.1143)
		(layer "In9.Cu")
		(net "P3E_CPU0_PE1_PCH_CON_RXP<9>")
	)
	(segment
		(start 437.197754 -18.735548)
		(end 438.879488 -18.399506)
		(width 0.1143)
		(layer "In9.Cu")
		(net "P3E_CPU0_PE1_PCH_CON_RXP<9>")
	)
	(segment
		(start 451.97522 -16.373094)
		(end 453.165464 -14.502638)
		(width 0.1143)
		(layer "In9.Cu")
		(net "P3E_CPU0_PE1_PCH_CON_RXP<9>")
	)
	(segment
		(start 449.659502 -18.848832)
		(end 450.694806 -18.158714)
		(width 0.1143)
		(layer "In9.Cu")
		(net "P3E_CPU0_PE1_PCH_CON_RXP<9>")
	)
	(segment
		(start 372.857014 -31.893002)
		(end 374.120156 -25.578054)
		(width 0.1143)
		(layer "In9.Cu")
		(net "P3E_CPU0_PE1_PCH_CON_RXP<9>")
	)
	(segment
		(start 361.901232 -68.294758)
		(end 361.690158 -67.238372)
		(width 0.1143)
		(layer "In9.Cu")
		(net "P3E_CPU0_PE1_PCH_CON_RXP<9>")
	)
	(segment
		(start 452.695056 -12.289028)
		(end 452.850758 -11.508232)
		(width 0.1143)
		(layer "In9.Cu")
		(net "P3E_CPU0_PE1_PCH_CON_RXP<9>")
	)
	(segment
		(start 454.73366 -5.112512)
		(end 453.01154 -3.963924)
		(width 0.1143)
		(layer "In9.Cu")
		(net "P3E_CPU0_PE1_PCH_CON_RXP<9>")
	)
	(segment
		(start 453.72655 -10.193782)
		(end 454.503282 -6.540246)
		(width 0.1143)
		(layer "In9.Cu")
		(net "P3E_CPU0_PE1_PCH_CON_RXP<9>")
	)
	(segment
		(start 451.871842 -2.25425)
		(end 448.266058 -0.673608)
		(width 0.1143)
		(layer "In9.Cu")
		(net "P3E_CPU0_PE1_PCH_CON_RXP<9>")
	)
	(segment
		(start 450.694806 -18.158714)
		(end 451.57771 -16.770858)
		(width 0.1143)
		(layer "In9.Cu")
		(net "P3E_CPU0_PE1_PCH_CON_RXP<9>")
	)
	(segment
		(start 454.503282 -6.540246)
		(end 454.735946 -6.191504)
		(width 0.1143)
		(layer "In9.Cu")
		(net "P3E_CPU0_PE1_PCH_CON_RXP<9>")
	)
	(segment
		(start 434.472334 -0.673608)
		(end 433.488592 -1.65735)
		(width 0.1143)
		(layer "In9.Cu")
		(net "P3E_CPU0_PE1_PCH_CON_RXP<9>")
	)
	(segment
		(start 363.970316 -108.415582)
		(end 363.970316 -105.929684)
		(width 0.1143)
		(layer "In9.Cu")
		(net "P3E_CPU0_PE1_PCH_CON_RXP<9>")
	)
	(segment
		(start 434.37937 -17.650968)
		(end 434.861462 -18.506186)
		(width 0.1143)
		(layer "In9.Cu")
		(net "P3E_CPU0_PE1_PCH_CON_RXP<9>")
	)
	(segment
		(start 380.591568 -18.433796)
		(end 387.27888 -17.014444)
		(width 0.1143)
		(layer "In9.Cu")
		(net "P3E_CPU0_PE1_PCH_CON_RXP<9>")
	)
	(segment
		(start 435.648354 -18.690082)
		(end 436.309262 -18.557494)
		(width 0.1143)
		(layer "In9.Cu")
		(net "P3E_CPU0_PE1_PCH_CON_RXP<9>")
	)
	(segment
		(start 364.697264 -105.202736)
		(end 364.697264 -93.86824)
		(width 0.1143)
		(layer "In9.Cu")
		(net "P3E_CPU0_PE1_PCH_CON_RXP<9>")
	)
	(segment
		(start 362.932472 -74.109072)
		(end 362.300266 -72.095614)
		(width 0.1143)
		(layer "In9.Cu")
		(net "P3E_CPU0_PE1_PCH_CON_RXP<9>")
	)
	(segment
		(start 428.558452 -17.28597)
		(end 429.354996 -17.116552)
		(width 0.1143)
		(layer "In9.Cu")
		(net "P3E_CPU0_PE1_PCH_CON_RXP<9>")
	)
	(segment
		(start 431.301144 -17.512284)
		(end 432.497992 -17.26819)
		(width 0.1143)
		(layer "In9.Cu")
		(net "P3E_CPU0_PE1_PCH_CON_RXP<9>")
	)
	(segment
		(start 363.39272 -124.223272)
		(end 363.39272 -120.938798)
		(width 0.1143)
		(layer "In9.Cu")
		(net "P3E_CPU0_PE1_PCH_CON_RXP<9>")
	)
	(segment
		(start 366.16386 -124.8029)
		(end 363.972348 -124.8029)
		(width 0.1143)
		(layer "In9.Cu")
		(net "P3E_CPU0_PE1_PCH_CON_RXP<9>")
	)
	(segment
		(start 433.36845 -2.860294)
		(end 433.011834 -2.860294)
		(width 0.1143)
		(layer "In9.Cu")
		(net "P3E_CPU0_PE1_PCH_CON_RXP<9>")
	)
	(segment
		(start 374.120156 -25.578054)
		(end 377.741434 -20.1549)
		(width 0.1143)
		(layer "In9.Cu")
		(net "P3E_CPU0_PE1_PCH_CON_RXP<9>")
	)
	(segment
		(start 448.266058 -0.673608)
		(end 434.472334 -0.673608)
		(width 0.1143)
		(layer "In9.Cu")
		(net "P3E_CPU0_PE1_PCH_CON_RXP<9>")
	)
	(segment
		(start 391.251948 -17.85874)
		(end 407.809446 -14.339062)
		(width 0.1143)
		(layer "In9.Cu")
		(net "P3E_CPU0_PE1_PCH_CON_RXP<9>")
	)
	(segment
		(start 428.558198 -17.28597)
		(end 428.558452 -17.28597)
		(width 0.1143)
		(layer "In9.Cu")
		(net "P3E_CPU0_PE1_PCH_CON_RXP<9>")
	)
	(segment
		(start 438.879488 -18.399506)
		(end 445.345058 -19.714972)
		(width 0.1143)
		(layer "In9.Cu")
		(net "P3E_CPU0_PE1_PCH_CON_RXP<9>")
	)
	(segment
		(start 451.63486 -16.713708)
		(end 451.97522 -16.373094)
		(width 0.1143)
		(layer "In9.Cu")
		(net "P3E_CPU0_PE1_PCH_CON_RXP<9>")
	)
	(segment
		(start 363.972348 -124.8029)
		(end 363.39272 -124.223272)
		(width 0.1143)
		(layer "In9.Cu")
		(net "P3E_CPU0_PE1_PCH_CON_RXP<9>")
	)
	(segment
		(start 433.488592 -1.65735)
		(end 433.488592 -2.740152)
		(width 0.1143)
		(layer "In9.Cu")
		(net "P3E_CPU0_PE1_PCH_CON_RXP<9>")
	)
	(segment
		(start 445.345058 -19.714972)
		(end 449.659502 -18.848832)
		(width 0.1143)
		(layer "In9.Cu")
		(net "P3E_CPU0_PE1_PCH_CON_RXP<9>")
	)
	(segment
		(start 454.842372 -5.657088)
		(end 454.73366 -5.112512)
		(width 0.1143)
		(layer "In9.Cu")
		(net "P3E_CPU0_PE1_PCH_CON_RXP<9>")
	)
	(segment
		(start 361.702858 -69.28358)
		(end 361.901232 -68.294758)
		(width 0.1143)
		(layer "In9.Cu")
		(net "P3E_CPU0_PE1_PCH_CON_RXP<9>")
	)
	(segment
		(start 432.497992 -17.26819)
		(end 434.37937 -17.650968)
		(width 0.1143)
		(layer "In9.Cu")
		(net "P3E_CPU0_PE1_PCH_CON_RXP<9>")
	)
	(segment
		(start 372.82501 -31.941008)
		(end 372.82501 -31.941262)
		(width 0.1143)
		(layer "In9.Cu")
		(net "P3E_CPU0_PE1_PCH_CON_RXP<9>")
	)
	(segment
		(start 369.682014 -45.394118)
		(end 371.067076 -38.473634)
		(width 0.1143)
		(layer "In9.Cu")
		(net "P3E_CPU0_PE1_PCH_CON_RXP<9>")
	)
	(segment
		(start 372.82501 -31.941262)
		(end 372.857014 -31.893002)
		(width 0.1143)
		(layer "In9.Cu")
		(net "P3E_CPU0_PE1_PCH_CON_RXP<9>")
	)
	(segment
		(start 363.215428 -60.056014)
		(end 364.912402 -56.576976)
		(width 0.1143)
		(layer "In9.Cu")
		(net "P3E_CPU0_PE1_PCH_CON_RXP<9>")
	)
	(segment
		(start 453.01154 -3.963924)
		(end 451.871842 -2.25425)
		(width 0.1143)
		(layer "In9.Cu")
		(net "P3E_CPU0_PE1_PCH_CON_RXP<9>")
	)
	(segment
		(start 430.875186 -3.69316)
		(end 430.875186 -4.386072)
		(width 0.1143)
		(layer "F.Cu")
		(net "P3E_CPU0_PE1_PCH_CON_RXP<8>")
	)
	(segment
		(start 431.094388 -3.473958)
		(end 430.875186 -3.69316)
		(width 0.1143)
		(layer "F.Cu")
		(net "P3E_CPU0_PE1_PCH_CON_RXP<8>")
	)
	(segment
		(start 430.937162 -2.874518)
		(end 431.094388 -3.031744)
		(width 0.1143)
		(layer "F.Cu")
		(net "P3E_CPU0_PE1_PCH_CON_RXP<8>")
	)
	(segment
		(start 430.5808 -2.874518)
		(end 430.937162 -2.874518)
		(width 0.1143)
		(layer "F.Cu")
		(net "P3E_CPU0_PE1_PCH_CON_RXP<8>")
	)
	(segment
		(start 431.094388 -3.031744)
		(end 431.094388 -3.473958)
		(width 0.1143)
		(layer "F.Cu")
		(net "P3E_CPU0_PE1_PCH_CON_RXP<8>")
	)
	(via
		(at 430.5808 -2.874518)
		(size 0.508)
		(drill 0.254)
		(layers "F.Cu" "B.Cu")
		(net "P3E_CPU0_PE1_PCH_CON_RXP<8>")
	)
	(via
		(at 366.303814 -121.316242)
		(size 0.508)
		(drill 0.254)
		(layers "F.Cu" "B.Cu")
		(net "P3E_CPU0_PE1_PCH_CON_RXP<8>")
	)
	(segment
		(start 366.430814 -121.443242)
		(end 366.931956 -121.443242)
		(width 0.1016)
		(layer "B.Cu")
		(net "P3E_CPU0_PE1_PCH_CON_RXP<8>")
	)
	(segment
		(start 366.303814 -121.316242)
		(end 366.430814 -121.443242)
		(width 0.1016)
		(layer "B.Cu")
		(net "P3E_CPU0_PE1_PCH_CON_RXP<8>")
	)
	(segment
		(start 431.018188 -2.171954)
		(end 433.158392 -0.03175)
		(width 0.1143)
		(layer "In9.Cu")
		(net "P3E_CPU0_PE1_PCH_CON_RXP<8>")
	)
	(segment
		(start 431.018188 -2.696972)
		(end 431.018188 -2.171954)
		(width 0.1143)
		(layer "In9.Cu")
		(net "P3E_CPU0_PE1_PCH_CON_RXP<8>")
	)
	(segment
		(start 434.481224 -19.140678)
		(end 434.087778 -18.552922)
		(width 0.1143)
		(layer "In9.Cu")
		(net "P3E_CPU0_PE1_PCH_CON_RXP<8>")
	)
	(segment
		(start 363.524038 -68.2498)
		(end 363.091222 -69.895212)
		(width 0.1143)
		(layer "In9.Cu")
		(net "P3E_CPU0_PE1_PCH_CON_RXP<8>")
	)
	(segment
		(start 455.480674 -4.820412)
		(end 458.062584 -8.691626)
		(width 0.1143)
		(layer "In9.Cu")
		(net "P3E_CPU0_PE1_PCH_CON_RXP<8>")
	)
	(segment
		(start 431.548032 -18.230596)
		(end 429.367696 -17.787366)
		(width 0.1143)
		(layer "In9.Cu")
		(net "P3E_CPU0_PE1_PCH_CON_RXP<8>")
	)
	(segment
		(start 446.445132 -20.170648)
		(end 445.016636 -20.461732)
		(width 0.1143)
		(layer "In9.Cu")
		(net "P3E_CPU0_PE1_PCH_CON_RXP<8>")
	)
	(segment
		(start 368.8207 -104.222296)
		(end 368.8207 -113.78184)
		(width 0.1143)
		(layer "In9.Cu")
		(net "P3E_CPU0_PE1_PCH_CON_RXP<8>")
	)
	(segment
		(start 362.838492 -66.87693)
		(end 363.424978 -67.757802)
		(width 0.1143)
		(layer "In9.Cu")
		(net "P3E_CPU0_PE1_PCH_CON_RXP<8>")
	)
	(segment
		(start 417.994592 -15.771876)
		(end 414.626044 -16.505682)
		(width 0.1143)
		(layer "In9.Cu")
		(net "P3E_CPU0_PE1_PCH_CON_RXP<8>")
	)
	(segment
		(start 378.14631 -20.715732)
		(end 376.118882 -23.755858)
		(width 0.1143)
		(layer "In9.Cu")
		(net "P3E_CPU0_PE1_PCH_CON_RXP<8>")
	)
	(segment
		(start 387.833362 -17.836896)
		(end 387.159246 -17.70126)
		(width 0.1143)
		(layer "In9.Cu")
		(net "P3E_CPU0_PE1_PCH_CON_RXP<8>")
	)
	(segment
		(start 442.651134 -21.314918)
		(end 434.481224 -19.140678)
		(width 0.1143)
		(layer "In9.Cu")
		(net "P3E_CPU0_PE1_PCH_CON_RXP<8>")
	)
	(segment
		(start 430.840642 -2.874518)
		(end 431.018188 -2.696972)
		(width 0.1143)
		(layer "In9.Cu")
		(net "P3E_CPU0_PE1_PCH_CON_RXP<8>")
	)
	(segment
		(start 364.635796 -121.812304)
		(end 366.189514 -121.812304)
		(width 0.1143)
		(layer "In9.Cu")
		(net "P3E_CPU0_PE1_PCH_CON_RXP<8>")
	)
	(segment
		(start 448.415664 -0.03175)
		(end 452.341234 -1.753616)
		(width 0.1143)
		(layer "In9.Cu")
		(net "P3E_CPU0_PE1_PCH_CON_RXP<8>")
	)
	(segment
		(start 364.3122 -121.175272)
		(end 364.3122 -121.488708)
		(width 0.1143)
		(layer "In9.Cu")
		(net "P3E_CPU0_PE1_PCH_CON_RXP<8>")
	)
	(segment
		(start 364.017052 -74.253852)
		(end 364.4646 -74.7014)
		(width 0.1143)
		(layer "In9.Cu")
		(net "P3E_CPU0_PE1_PCH_CON_RXP<8>")
	)
	(segment
		(start 458.062584 -8.691626)
		(end 457.952602 -9.240012)
		(width 0.1143)
		(layer "In9.Cu")
		(net "P3E_CPU0_PE1_PCH_CON_RXP<8>")
	)
	(segment
		(start 457.297536 -10.222992)
		(end 455.900536 -10.502392)
		(width 0.1143)
		(layer "In9.Cu")
		(net "P3E_CPU0_PE1_PCH_CON_RXP<8>")
	)
	(segment
		(start 452.341234 -1.753616)
		(end 453.507094 -3.5052)
		(width 0.1143)
		(layer "In9.Cu")
		(net "P3E_CPU0_PE1_PCH_CON_RXP<8>")
	)
	(segment
		(start 380.90729 -19.029172)
		(end 379.28296 -20.164552)
		(width 0.1143)
		(layer "In9.Cu")
		(net "P3E_CPU0_PE1_PCH_CON_RXP<8>")
	)
	(segment
		(start 406.560274 -16.378428)
		(end 405.535384 -16.58747)
		(width 0.1143)
		(layer "In9.Cu")
		(net "P3E_CPU0_PE1_PCH_CON_RXP<8>")
	)
	(segment
		(start 363.825536 -60.31865)
		(end 362.635292 -65.92062)
		(width 0.1143)
		(layer "In9.Cu")
		(net "P3E_CPU0_PE1_PCH_CON_RXP<8>")
	)
	(segment
		(start 370.10467 -45.8978)
		(end 365.888016 -49.392586)
		(width 0.1143)
		(layer "In9.Cu")
		(net "P3E_CPU0_PE1_PCH_CON_RXP<8>")
	)
	(segment
		(start 457.952602 -9.240012)
		(end 457.297536 -10.222992)
		(width 0.1143)
		(layer "In9.Cu")
		(net "P3E_CPU0_PE1_PCH_CON_RXP<8>")
	)
	(segment
		(start 375.435622 -33.297114)
		(end 374.760744 -34.236406)
		(width 0.1143)
		(layer "In9.Cu")
		(net "P3E_CPU0_PE1_PCH_CON_RXP<8>")
	)
	(segment
		(start 362.635292 -65.92062)
		(end 362.838492 -66.87693)
		(width 0.1143)
		(layer "In9.Cu")
		(net "P3E_CPU0_PE1_PCH_CON_RXP<8>")
	)
	(segment
		(start 414.626044 -16.505682)
		(end 407.791666 -15.01521)
		(width 0.1143)
		(layer "In9.Cu")
		(net "P3E_CPU0_PE1_PCH_CON_RXP<8>")
	)
	(segment
		(start 407.791666 -15.01521)
		(end 407.408634 -15.096744)
		(width 0.1143)
		(layer "In9.Cu")
		(net "P3E_CPU0_PE1_PCH_CON_RXP<8>")
	)
	(segment
		(start 363.091222 -69.895212)
		(end 364.017052 -74.253852)
		(width 0.1143)
		(layer "In9.Cu")
		(net "P3E_CPU0_PE1_PCH_CON_RXP<8>")
	)
	(segment
		(start 375.002552 -31.406846)
		(end 375.435622 -33.297114)
		(width 0.1143)
		(layer "In9.Cu")
		(net "P3E_CPU0_PE1_PCH_CON_RXP<8>")
	)
	(segment
		(start 366.9919 -115.61064)
		(end 366.9919 -118.495572)
		(width 0.1143)
		(layer "In9.Cu")
		(net "P3E_CPU0_PE1_PCH_CON_RXP<8>")
	)
	(segment
		(start 376.118882 -23.755858)
		(end 375.319036 -26.79954)
		(width 0.1143)
		(layer "In9.Cu")
		(net "P3E_CPU0_PE1_PCH_CON_RXP<8>")
	)
	(segment
		(start 364.3122 -121.488708)
		(end 364.635796 -121.812304)
		(width 0.1143)
		(layer "In9.Cu")
		(net "P3E_CPU0_PE1_PCH_CON_RXP<8>")
	)
	(segment
		(start 365.516414 -100.91801)
		(end 368.8207 -104.222296)
		(width 0.1143)
		(layer "In9.Cu")
		(net "P3E_CPU0_PE1_PCH_CON_RXP<8>")
	)
	(segment
		(start 434.087778 -18.552922)
		(end 432.010312 -18.136616)
		(width 0.1143)
		(layer "In9.Cu")
		(net "P3E_CPU0_PE1_PCH_CON_RXP<8>")
	)
	(segment
		(start 391.218674 -18.5166)
		(end 387.833362 -17.836896)
		(width 0.1143)
		(layer "In9.Cu")
		(net "P3E_CPU0_PE1_PCH_CON_RXP<8>")
	)
	(segment
		(start 364.4646 -89.354152)
		(end 365.516414 -94.277942)
		(width 0.1143)
		(layer "In9.Cu")
		(net "P3E_CPU0_PE1_PCH_CON_RXP<8>")
	)
	(segment
		(start 375.319036 -26.79954)
		(end 375.682002 -28.508198)
		(width 0.1143)
		(layer "In9.Cu")
		(net "P3E_CPU0_PE1_PCH_CON_RXP<8>")
	)
	(segment
		(start 379.28296 -20.164552)
		(end 378.14631 -20.715732)
		(width 0.1143)
		(layer "In9.Cu")
		(net "P3E_CPU0_PE1_PCH_CON_RXP<8>")
	)
	(segment
		(start 387.159246 -17.70126)
		(end 380.90729 -19.029172)
		(width 0.1143)
		(layer "In9.Cu")
		(net "P3E_CPU0_PE1_PCH_CON_RXP<8>")
	)
	(segment
		(start 445.016636 -20.461732)
		(end 444.549276 -20.929092)
		(width 0.1143)
		(layer "In9.Cu")
		(net "P3E_CPU0_PE1_PCH_CON_RXP<8>")
	)
	(segment
		(start 450.284088 -20.219924)
		(end 448.482212 -20.580604)
		(width 0.1143)
		(layer "In9.Cu")
		(net "P3E_CPU0_PE1_PCH_CON_RXP<8>")
	)
	(segment
		(start 454.048114 -14.302994)
		(end 450.284088 -20.219924)
		(width 0.1143)
		(layer "In9.Cu")
		(net "P3E_CPU0_PE1_PCH_CON_RXP<8>")
	)
	(segment
		(start 375.682002 -28.508198)
		(end 375.002552 -31.406846)
		(width 0.1143)
		(layer "In9.Cu")
		(net "P3E_CPU0_PE1_PCH_CON_RXP<8>")
	)
	(segment
		(start 432.010312 -18.136616)
		(end 431.548032 -18.230596)
		(width 0.1143)
		(layer "In9.Cu")
		(net "P3E_CPU0_PE1_PCH_CON_RXP<8>")
	)
	(segment
		(start 402.856446 -16.042894)
		(end 391.218674 -18.5166)
		(width 0.1143)
		(layer "In9.Cu")
		(net "P3E_CPU0_PE1_PCH_CON_RXP<8>")
	)
	(segment
		(start 368.8207 -113.78184)
		(end 366.9919 -115.61064)
		(width 0.1143)
		(layer "In9.Cu")
		(net "P3E_CPU0_PE1_PCH_CON_RXP<8>")
	)
	(segment
		(start 405.535384 -16.58747)
		(end 402.856446 -16.042894)
		(width 0.1143)
		(layer "In9.Cu")
		(net "P3E_CPU0_PE1_PCH_CON_RXP<8>")
	)
	(segment
		(start 363.424978 -67.757802)
		(end 363.524038 -68.2498)
		(width 0.1143)
		(layer "In9.Cu")
		(net "P3E_CPU0_PE1_PCH_CON_RXP<8>")
	)
	(segment
		(start 454.340214 -12.843256)
		(end 454.048114 -14.302994)
		(width 0.1143)
		(layer "In9.Cu")
		(net "P3E_CPU0_PE1_PCH_CON_RXP<8>")
	)
	(segment
		(start 365.516414 -94.277942)
		(end 365.516414 -100.91801)
		(width 0.1143)
		(layer "In9.Cu")
		(net "P3E_CPU0_PE1_PCH_CON_RXP<8>")
	)
	(segment
		(start 455.900536 -10.502392)
		(end 454.340214 -12.843256)
		(width 0.1143)
		(layer "In9.Cu")
		(net "P3E_CPU0_PE1_PCH_CON_RXP<8>")
	)
	(segment
		(start 366.303814 -121.698004)
		(end 366.303814 -121.316242)
		(width 0.1143)
		(layer "In9.Cu")
		(net "P3E_CPU0_PE1_PCH_CON_RXP<8>")
	)
	(segment
		(start 444.549276 -20.929092)
		(end 442.651134 -21.314918)
		(width 0.1143)
		(layer "In9.Cu")
		(net "P3E_CPU0_PE1_PCH_CON_RXP<8>")
	)
	(segment
		(start 366.9919 -118.495572)
		(end 364.3122 -121.175272)
		(width 0.1143)
		(layer "In9.Cu")
		(net "P3E_CPU0_PE1_PCH_CON_RXP<8>")
	)
	(segment
		(start 364.4646 -74.7014)
		(end 364.4646 -89.354152)
		(width 0.1143)
		(layer "In9.Cu")
		(net "P3E_CPU0_PE1_PCH_CON_RXP<8>")
	)
	(segment
		(start 365.888016 -49.392586)
		(end 364.760764 -52.694332)
		(width 0.1143)
		(layer "In9.Cu")
		(net "P3E_CPU0_PE1_PCH_CON_RXP<8>")
	)
	(segment
		(start 433.158392 -0.03175)
		(end 448.415664 -0.03175)
		(width 0.1143)
		(layer "In9.Cu")
		(net "P3E_CPU0_PE1_PCH_CON_RXP<8>")
	)
	(segment
		(start 374.760744 -34.236406)
		(end 372.256812 -35.90544)
		(width 0.1143)
		(layer "In9.Cu")
		(net "P3E_CPU0_PE1_PCH_CON_RXP<8>")
	)
	(segment
		(start 370.291106 -45.743368)
		(end 370.10467 -45.8978)
		(width 0.1143)
		(layer "In9.Cu")
		(net "P3E_CPU0_PE1_PCH_CON_RXP<8>")
	)
	(segment
		(start 407.408634 -15.096744)
		(end 406.560274 -16.378428)
		(width 0.1143)
		(layer "In9.Cu")
		(net "P3E_CPU0_PE1_PCH_CON_RXP<8>")
	)
	(segment
		(start 364.760764 -52.694332)
		(end 365.60252 -56.67502)
		(width 0.1143)
		(layer "In9.Cu")
		(net "P3E_CPU0_PE1_PCH_CON_RXP<8>")
	)
	(segment
		(start 453.507094 -3.5052)
		(end 455.480674 -4.820412)
		(width 0.1143)
		(layer "In9.Cu")
		(net "P3E_CPU0_PE1_PCH_CON_RXP<8>")
	)
	(segment
		(start 428.440342 -17.972786)
		(end 417.994592 -15.771876)
		(width 0.1143)
		(layer "In9.Cu")
		(net "P3E_CPU0_PE1_PCH_CON_RXP<8>")
	)
	(segment
		(start 430.5808 -2.874518)
		(end 430.840642 -2.874518)
		(width 0.1143)
		(layer "In9.Cu")
		(net "P3E_CPU0_PE1_PCH_CON_RXP<8>")
	)
	(segment
		(start 448.482212 -20.580604)
		(end 446.445132 -20.170648)
		(width 0.1143)
		(layer "In9.Cu")
		(net "P3E_CPU0_PE1_PCH_CON_RXP<8>")
	)
	(segment
		(start 365.60252 -56.67502)
		(end 363.825536 -60.31865)
		(width 0.1143)
		(layer "In9.Cu")
		(net "P3E_CPU0_PE1_PCH_CON_RXP<8>")
	)
	(segment
		(start 366.189514 -121.812304)
		(end 366.303814 -121.698004)
		(width 0.1143)
		(layer "In9.Cu")
		(net "P3E_CPU0_PE1_PCH_CON_RXP<8>")
	)
	(segment
		(start 429.367696 -17.787366)
		(end 428.440342 -17.972786)
		(width 0.1143)
		(layer "In9.Cu")
		(net "P3E_CPU0_PE1_PCH_CON_RXP<8>")
	)
	(segment
		(start 372.256812 -35.90544)
		(end 370.291106 -45.743368)
		(width 0.1143)
		(layer "In9.Cu")
		(net "P3E_CPU0_PE1_PCH_CON_RXP<8>")
	)
	(segment
		(start 448.841368 -2.42189)
		(end 448.955668 -2.30759)
		(width 0.1143)
		(layer "F.Cu")
		(net "P3E_CPU0_PE1_PCH_CON_RXP<15>")
	)
	(segment
		(start 447.333116 -3.358388)
		(end 447.333116 -3.196844)
		(width 0.1143)
		(layer "F.Cu")
		(net "P3E_CPU0_PE1_PCH_CON_RXP<15>")
	)
	(segment
		(start 449.412868 -2.42189)
		(end 449.755768 -2.42189)
		(width 0.1143)
		(layer "F.Cu")
		(net "P3E_CPU0_PE1_PCH_CON_RXP<15>")
	)
	(segment
		(start 448.955668 -2.30759)
		(end 449.298568 -2.30759)
		(width 0.1143)
		(layer "F.Cu")
		(net "P3E_CPU0_PE1_PCH_CON_RXP<15>")
	)
	(segment
		(start 448.498468 -2.42189)
		(end 448.841368 -2.42189)
		(width 0.1143)
		(layer "F.Cu")
		(net "P3E_CPU0_PE1_PCH_CON_RXP<15>")
	)
	(segment
		(start 450.670168 -2.42189)
		(end 450.784468 -2.30759)
		(width 0.1143)
		(layer "F.Cu")
		(net "P3E_CPU0_PE1_PCH_CON_RXP<15>")
	)
	(segment
		(start 447.216022 -5.09143)
		(end 446.776856 -4.652264)
		(width 0.1143)
		(layer "F.Cu")
		(net "P3E_CPU0_PE1_PCH_CON_RXP<15>")
	)
	(segment
		(start 452.756778 -3.478784)
		(end 452.477378 -3.758184)
		(width 0.1143)
		(layer "F.Cu")
		(net "P3E_CPU0_PE1_PCH_CON_RXP<15>")
	)
	(segment
		(start 449.298568 -2.30759)
		(end 449.412868 -2.42189)
		(width 0.1143)
		(layer "F.Cu")
		(net "P3E_CPU0_PE1_PCH_CON_RXP<15>")
	)
	(segment
		(start 450.327268 -2.42189)
		(end 450.670168 -2.42189)
		(width 0.1143)
		(layer "F.Cu")
		(net "P3E_CPU0_PE1_PCH_CON_RXP<15>")
	)
	(segment
		(start 451.698868 -2.30759)
		(end 452.041768 -2.30759)
		(width 0.1143)
		(layer "F.Cu")
		(net "P3E_CPU0_PE1_PCH_CON_RXP<15>")
	)
	(segment
		(start 448.384168 -2.30759)
		(end 448.498468 -2.42189)
		(width 0.1143)
		(layer "F.Cu")
		(net "P3E_CPU0_PE1_PCH_CON_RXP<15>")
	)
	(segment
		(start 452.688452 -2.954274)
		(end 452.756778 -3.0226)
		(width 0.1143)
		(layer "F.Cu")
		(net "P3E_CPU0_PE1_PCH_CON_RXP<15>")
	)
	(segment
		(start 451.241668 -2.42189)
		(end 451.584568 -2.42189)
		(width 0.1143)
		(layer "F.Cu")
		(net "P3E_CPU0_PE1_PCH_CON_RXP<15>")
	)
	(segment
		(start 452.526654 -2.954274)
		(end 452.688452 -2.954274)
		(width 0.1143)
		(layer "F.Cu")
		(net "P3E_CPU0_PE1_PCH_CON_RXP<15>")
	)
	(segment
		(start 452.756778 -3.0226)
		(end 452.756778 -3.478784)
		(width 0.1143)
		(layer "F.Cu")
		(net "P3E_CPU0_PE1_PCH_CON_RXP<15>")
	)
	(segment
		(start 451.584568 -2.42189)
		(end 451.698868 -2.30759)
		(width 0.1143)
		(layer "F.Cu")
		(net "P3E_CPU0_PE1_PCH_CON_RXP<15>")
	)
	(segment
		(start 451.127368 -2.30759)
		(end 451.241668 -2.42189)
		(width 0.1143)
		(layer "F.Cu")
		(net "P3E_CPU0_PE1_PCH_CON_RXP<15>")
	)
	(segment
		(start 450.212968 -2.30759)
		(end 450.327268 -2.42189)
		(width 0.1143)
		(layer "F.Cu")
		(net "P3E_CPU0_PE1_PCH_CON_RXP<15>")
	)
	(segment
		(start 447.0908 -3.600958)
		(end 447.333116 -3.358388)
		(width 0.1143)
		(layer "F.Cu")
		(net "P3E_CPU0_PE1_PCH_CON_RXP<15>")
	)
	(segment
		(start 447.9798 -2.55016)
		(end 448.22237 -2.30759)
		(width 0.1143)
		(layer "F.Cu")
		(net "P3E_CPU0_PE1_PCH_CON_RXP<15>")
	)
	(segment
		(start 447.333116 -3.196844)
		(end 447.575686 -2.954274)
		(width 0.1143)
		(layer "F.Cu")
		(net "P3E_CPU0_PE1_PCH_CON_RXP<15>")
	)
	(segment
		(start 452.284338 -2.55016)
		(end 452.284338 -2.711704)
		(width 0.1143)
		(layer "F.Cu")
		(net "P3E_CPU0_PE1_PCH_CON_RXP<15>")
	)
	(segment
		(start 448.22237 -2.30759)
		(end 448.384168 -2.30759)
		(width 0.1143)
		(layer "F.Cu")
		(net "P3E_CPU0_PE1_PCH_CON_RXP<15>")
	)
	(segment
		(start 450.784468 -2.30759)
		(end 451.127368 -2.30759)
		(width 0.1143)
		(layer "F.Cu")
		(net "P3E_CPU0_PE1_PCH_CON_RXP<15>")
	)
	(segment
		(start 452.477378 -3.758184)
		(end 452.477378 -4.386072)
		(width 0.1143)
		(layer "F.Cu")
		(net "P3E_CPU0_PE1_PCH_CON_RXP<15>")
	)
	(segment
		(start 449.755768 -2.42189)
		(end 449.870068 -2.30759)
		(width 0.1143)
		(layer "F.Cu")
		(net "P3E_CPU0_PE1_PCH_CON_RXP<15>")
	)
	(segment
		(start 447.737484 -2.954274)
		(end 447.9798 -2.711704)
		(width 0.1143)
		(layer "F.Cu")
		(net "P3E_CPU0_PE1_PCH_CON_RXP<15>")
	)
	(segment
		(start 452.041768 -2.30759)
		(end 452.284338 -2.55016)
		(width 0.1143)
		(layer "F.Cu")
		(net "P3E_CPU0_PE1_PCH_CON_RXP<15>")
	)
	(segment
		(start 446.929002 -3.600958)
		(end 447.0908 -3.600958)
		(width 0.1143)
		(layer "F.Cu")
		(net "P3E_CPU0_PE1_PCH_CON_RXP<15>")
	)
	(segment
		(start 446.776856 -4.652264)
		(end 446.776856 -3.753104)
		(width 0.1143)
		(layer "F.Cu")
		(net "P3E_CPU0_PE1_PCH_CON_RXP<15>")
	)
	(segment
		(start 446.776856 -3.753104)
		(end 446.929002 -3.600958)
		(width 0.1143)
		(layer "F.Cu")
		(net "P3E_CPU0_PE1_PCH_CON_RXP<15>")
	)
	(segment
		(start 449.870068 -2.30759)
		(end 450.212968 -2.30759)
		(width 0.1143)
		(layer "F.Cu")
		(net "P3E_CPU0_PE1_PCH_CON_RXP<15>")
	)
	(segment
		(start 447.9798 -2.711704)
		(end 447.9798 -2.55016)
		(width 0.1143)
		(layer "F.Cu")
		(net "P3E_CPU0_PE1_PCH_CON_RXP<15>")
	)
	(segment
		(start 452.284338 -2.711704)
		(end 452.526654 -2.954274)
		(width 0.1143)
		(layer "F.Cu")
		(net "P3E_CPU0_PE1_PCH_CON_RXP<15>")
	)
	(segment
		(start 447.575686 -2.954274)
		(end 447.737484 -2.954274)
		(width 0.1143)
		(layer "F.Cu")
		(net "P3E_CPU0_PE1_PCH_CON_RXP<15>")
	)
	(via
		(at 352.734626 -126.68123)
		(size 0.508)
		(drill 0.254)
		(layers "F.Cu" "B.Cu")
		(net "P3E_CPU0_PE1_PCH_CON_RXP<15>")
	)
	(via
		(at 447.216022 -5.09143)
		(size 0.508)
		(drill 0.254)
		(layers "F.Cu" "B.Cu")
		(net "P3E_CPU0_PE1_PCH_CON_RXP<15>")
	)
	(segment
		(start 352.791014 -126.624842)
		(end 352.734626 -126.68123)
		(width 0.10795)
		(layer "B.Cu")
		(net "P3E_CPU0_PE1_PCH_CON_RXP<15>")
	)
	(segment
		(start 353.400614 -126.624842)
		(end 352.791014 -126.624842)
		(width 0.10795)
		(layer "B.Cu")
		(net "P3E_CPU0_PE1_PCH_CON_RXP<15>")
	)
	(segment
		(start 418.80536 -10.882884)
		(end 414.646618 -11.714734)
		(width 0.1143)
		(layer "In9.Cu")
		(net "P3E_CPU0_PE1_PCH_CON_RXP<15>")
	)
	(segment
		(start 359.145586 -86.628224)
		(end 358.654096 -88.94318)
		(width 0.1143)
		(layer "In9.Cu")
		(net "P3E_CPU0_PE1_PCH_CON_RXP<15>")
	)
	(segment
		(start 344.988896 -125.037596)
		(end 345.222322 -125.037596)
		(width 0.1143)
		(layer "In9.Cu")
		(net "P3E_CPU0_PE1_PCH_CON_RXP<15>")
	)
	(segment
		(start 345.464638 -125.513338)
		(end 345.707208 -125.755908)
		(width 0.1143)
		(layer "In9.Cu")
		(net "P3E_CPU0_PE1_PCH_CON_RXP<15>")
	)
	(segment
		(start 362.547916 -43.671236)
		(end 358.693212 -50.310034)
		(width 0.1143)
		(layer "In9.Cu")
		(net "P3E_CPU0_PE1_PCH_CON_RXP<15>")
	)
	(segment
		(start 446.129156 -11.27633)
		(end 444.156338 -10.881614)
		(width 0.1143)
		(layer "In9.Cu")
		(net "P3E_CPU0_PE1_PCH_CON_RXP<15>")
	)
	(segment
		(start 359.117646 -57.772554)
		(end 359.18902 -58.108088)
		(width 0.1143)
		(layer "In9.Cu")
		(net "P3E_CPU0_PE1_PCH_CON_RXP<15>")
	)
	(segment
		(start 359.384854 -58.235342)
		(end 359.455974 -58.570876)
		(width 0.1143)
		(layer "In9.Cu")
		(net "P3E_CPU0_PE1_PCH_CON_RXP<15>")
	)
	(segment
		(start 438.57291 -11.579098)
		(end 435.321456 -10.888218)
		(width 0.1143)
		(layer "In9.Cu")
		(net "P3E_CPU0_PE1_PCH_CON_RXP<15>")
	)
	(segment
		(start 359.033826 -56.583072)
		(end 358.906572 -56.778906)
		(width 0.1143)
		(layer "In9.Cu")
		(net "P3E_CPU0_PE1_PCH_CON_RXP<15>")
	)
	(segment
		(start 359.32872 -58.766456)
		(end 359.400094 -59.10199)
		(width 0.1143)
		(layer "In9.Cu")
		(net "P3E_CPU0_PE1_PCH_CON_RXP<15>")
	)
	(segment
		(start 358.78135 -89.139268)
		(end 358.71023 -89.474802)
		(width 0.1143)
		(layer "In9.Cu")
		(net "P3E_CPU0_PE1_PCH_CON_RXP<15>")
	)
	(segment
		(start 448.166998 -9.932416)
		(end 447.783966 -10.596626)
		(width 0.1143)
		(layer "In9.Cu")
		(net "P3E_CPU0_PE1_PCH_CON_RXP<15>")
	)
	(segment
		(start 360.373422 -113.13922)
		(end 359.583736 -116.86159)
		(width 0.1143)
		(layer "In9.Cu")
		(net "P3E_CPU0_PE1_PCH_CON_RXP<15>")
	)
	(segment
		(start 358.693212 -50.310034)
		(end 358.596946 -50.793396)
		(width 0.1143)
		(layer "In9.Cu")
		(net "P3E_CPU0_PE1_PCH_CON_RXP<15>")
	)
	(segment
		(start 358.267 -106.891328)
		(end 358.267 -107.597448)
		(width 0.1143)
		(layer "In9.Cu")
		(net "P3E_CPU0_PE1_PCH_CON_RXP<15>")
	)
	(segment
		(start 359.173526 -57.24144)
		(end 359.2449 -57.576974)
		(width 0.1143)
		(layer "In9.Cu")
		(net "P3E_CPU0_PE1_PCH_CON_RXP<15>")
	)
	(segment
		(start 421.07612 -10.72896)
		(end 419.579806 -11.04773)
		(width 0.1143)
		(layer "In9.Cu")
		(net "P3E_CPU0_PE1_PCH_CON_RXP<15>")
	)
	(segment
		(start 358.906572 -56.778906)
		(end 358.977946 -57.114186)
		(width 0.1143)
		(layer "In9.Cu")
		(net "P3E_CPU0_PE1_PCH_CON_RXP<15>")
	)
	(segment
		(start 349.24873 -126.677674)
		(end 349.41383 -126.842774)
		(width 0.1143)
		(layer "In9.Cu")
		(net "P3E_CPU0_PE1_PCH_CON_RXP<15>")
	)
	(segment
		(start 358.695244 -55.78475)
		(end 358.766618 -56.120284)
		(width 0.1143)
		(layer "In9.Cu")
		(net "P3E_CPU0_PE1_PCH_CON_RXP<15>")
	)
	(segment
		(start 344.648282 -121.06656)
		(end 344.325702 -121.57964)
		(width 0.1143)
		(layer "In9.Cu")
		(net "P3E_CPU0_PE1_PCH_CON_RXP<15>")
	)
	(segment
		(start 435.321456 -10.888218)
		(end 433.312316 -11.314938)
		(width 0.1143)
		(layer "In9.Cu")
		(net "P3E_CPU0_PE1_PCH_CON_RXP<15>")
	)
	(segment
		(start 359.18902 -58.108088)
		(end 359.384854 -58.235342)
		(width 0.1143)
		(layer "In9.Cu")
		(net "P3E_CPU0_PE1_PCH_CON_RXP<15>")
	)
	(segment
		(start 447.542666 -6.669024)
		(end 448.422268 -8.804148)
		(width 0.1143)
		(layer "In9.Cu")
		(net "P3E_CPU0_PE1_PCH_CON_RXP<15>")
	)
	(segment
		(start 358.092248 -91.589606)
		(end 358.020874 -91.924886)
		(width 0.1143)
		(layer "In9.Cu")
		(net "P3E_CPU0_PE1_PCH_CON_RXP<15>")
	)
	(segment
		(start 433.312316 -11.314938)
		(end 433.305204 -11.310112)
		(width 0.1143)
		(layer "In9.Cu")
		(net "P3E_CPU0_PE1_PCH_CON_RXP<15>")
	)
	(segment
		(start 358.591104 -79.305404)
		(end 357.702612 -80.193388)
		(width 0.1143)
		(layer "In9.Cu")
		(net "P3E_CPU0_PE1_PCH_CON_RXP<15>")
	)
	(segment
		(start 447.783966 -10.596626)
		(end 447.117724 -11.075924)
		(width 0.1143)
		(layer "In9.Cu")
		(net "P3E_CPU0_PE1_PCH_CON_RXP<15>")
	)
	(segment
		(start 423.197782 -11.180318)
		(end 421.07612 -10.72896)
		(width 0.1143)
		(layer "In9.Cu")
		(net "P3E_CPU0_PE1_PCH_CON_RXP<15>")
	)
	(segment
		(start 345.707208 -126.57074)
		(end 345.979242 -126.842774)
		(width 0.1143)
		(layer "In9.Cu")
		(net "P3E_CPU0_PE1_PCH_CON_RXP<15>")
	)
	(segment
		(start 446.900808 -5.377434)
		(end 446.900808 -6.027166)
		(width 0.1143)
		(layer "In9.Cu")
		(net "P3E_CPU0_PE1_PCH_CON_RXP<15>")
	)
	(segment
		(start 428.554388 -11.389868)
		(end 427.739302 -11.224006)
		(width 0.1143)
		(layer "In9.Cu")
		(net "P3E_CPU0_PE1_PCH_CON_RXP<15>")
	)
	(segment
		(start 359.400094 -59.10199)
		(end 357.943404 -65.959482)
		(width 0.1143)
		(layer "In9.Cu")
		(net "P3E_CPU0_PE1_PCH_CON_RXP<15>")
	)
	(segment
		(start 448.422268 -8.804148)
		(end 448.166998 -9.932416)
		(width 0.1143)
		(layer "In9.Cu")
		(net "P3E_CPU0_PE1_PCH_CON_RXP<15>")
	)
	(segment
		(start 358.570276 -90.13317)
		(end 358.499156 -90.46845)
		(width 0.1143)
		(layer "In9.Cu")
		(net "P3E_CPU0_PE1_PCH_CON_RXP<15>")
	)
	(segment
		(start 358.020874 -91.924886)
		(end 358.148128 -92.12072)
		(width 0.1143)
		(layer "In9.Cu")
		(net "P3E_CPU0_PE1_PCH_CON_RXP<15>")
	)
	(segment
		(start 350.77273 -126.842774)
		(end 351.107756 -127.1778)
		(width 0.1143)
		(layer "In9.Cu")
		(net "P3E_CPU0_PE1_PCH_CON_RXP<15>")
	)
	(segment
		(start 357.703374 -93.41993)
		(end 357.992426 -94.78137)
		(width 0.1143)
		(layer "In9.Cu")
		(net "P3E_CPU0_PE1_PCH_CON_RXP<15>")
	)
	(segment
		(start 344.325702 -121.57964)
		(end 344.325702 -124.374402)
		(width 0.1143)
		(layer "In9.Cu")
		(net "P3E_CPU0_PE1_PCH_CON_RXP<15>")
	)
	(segment
		(start 358.303322 -90.595704)
		(end 358.231948 -90.931238)
		(width 0.1143)
		(layer "In9.Cu")
		(net "P3E_CPU0_PE1_PCH_CON_RXP<15>")
	)
	(segment
		(start 357.881174 -92.583254)
		(end 357.703374 -93.41993)
		(width 0.1143)
		(layer "In9.Cu")
		(net "P3E_CPU0_PE1_PCH_CON_RXP<15>")
	)
	(segment
		(start 358.267 -104.221788)
		(end 358.267 -106.218228)
		(width 0.1143)
		(layer "In9.Cu")
		(net "P3E_CPU0_PE1_PCH_CON_RXP<15>")
	)
	(segment
		(start 356.869746 -67.478402)
		(end 356.528878 -68.537328)
		(width 0.1143)
		(layer "In9.Cu")
		(net "P3E_CPU0_PE1_PCH_CON_RXP<15>")
	)
	(segment
		(start 359.145586 -84.138008)
		(end 359.145586 -86.628224)
		(width 0.1143)
		(layer "In9.Cu")
		(net "P3E_CPU0_PE1_PCH_CON_RXP<15>")
	)
	(segment
		(start 358.4321 -106.383328)
		(end 358.4321 -106.726228)
		(width 0.1143)
		(layer "In9.Cu")
		(net "P3E_CPU0_PE1_PCH_CON_RXP<15>")
	)
	(segment
		(start 350.26473 -126.677674)
		(end 350.42983 -126.842774)
		(width 0.1143)
		(layer "In9.Cu")
		(net "P3E_CPU0_PE1_PCH_CON_RXP<15>")
	)
	(segment
		(start 358.148128 -92.12072)
		(end 358.076754 -92.456254)
		(width 0.1143)
		(layer "In9.Cu")
		(net "P3E_CPU0_PE1_PCH_CON_RXP<15>")
	)
	(segment
		(start 358.231948 -90.931238)
		(end 358.359202 -91.126818)
		(width 0.1143)
		(layer "In9.Cu")
		(net "P3E_CPU0_PE1_PCH_CON_RXP<15>")
	)
	(segment
		(start 366.772698 -33.382458)
		(end 363.896148 -36.926012)
		(width 0.1143)
		(layer "In9.Cu")
		(net "P3E_CPU0_PE1_PCH_CON_RXP<15>")
	)
	(segment
		(start 348.90583 -126.677674)
		(end 349.24873 -126.677674)
		(width 0.1143)
		(layer "In9.Cu")
		(net "P3E_CPU0_PE1_PCH_CON_RXP<15>")
	)
	(segment
		(start 427.344332 -10.96264)
		(end 426.246036 -10.73912)
		(width 0.1143)
		(layer "In9.Cu")
		(net "P3E_CPU0_PE1_PCH_CON_RXP<15>")
	)
	(segment
		(start 370.420138 -23.807674)
		(end 369.763294 -26.760932)
		(width 0.1143)
		(layer "In9.Cu")
		(net "P3E_CPU0_PE1_PCH_CON_RXP<15>")
	)
	(segment
		(start 440.79033 -11.108182)
		(end 438.57291 -11.579098)
		(width 0.1143)
		(layer "In9.Cu")
		(net "P3E_CPU0_PE1_PCH_CON_RXP<15>")
	)
	(segment
		(start 357.702612 -80.193388)
		(end 357.702612 -82.695034)
		(width 0.1143)
		(layer "In9.Cu")
		(net "P3E_CPU0_PE1_PCH_CON_RXP<15>")
	)
	(segment
		(start 363.896148 -36.926012)
		(end 362.547916 -43.671236)
		(width 0.1143)
		(layer "In9.Cu")
		(net "P3E_CPU0_PE1_PCH_CON_RXP<15>")
	)
	(segment
		(start 369.44681 -27.18308)
		(end 368.669824 -27.35453)
		(width 0.1143)
		(layer "In9.Cu")
		(net "P3E_CPU0_PE1_PCH_CON_RXP<15>")
	)
	(segment
		(start 414.646618 -11.714734)
		(end 408.221434 -10.349992)
		(width 0.1143)
		(layer "In9.Cu")
		(net "P3E_CPU0_PE1_PCH_CON_RXP<15>")
	)
	(segment
		(start 358.36098 -54.211474)
		(end 358.555544 -55.126382)
		(width 0.1143)
		(layer "In9.Cu")
		(net "P3E_CPU0_PE1_PCH_CON_RXP<15>")
	)
	(segment
		(start 345.84259 -120.385586)
		(end 344.648282 -121.06656)
		(width 0.1143)
		(layer "In9.Cu")
		(net "P3E_CPU0_PE1_PCH_CON_RXP<15>")
	)
	(segment
		(start 358.65435 -88.943434)
		(end 358.78135 -89.139268)
		(width 0.1143)
		(layer "In9.Cu")
		(net "P3E_CPU0_PE1_PCH_CON_RXP<15>")
	)
	(segment
		(start 359.397046 -108.542328)
		(end 360.373422 -113.13922)
		(width 0.1143)
		(layer "In9.Cu")
		(net "P3E_CPU0_PE1_PCH_CON_RXP<15>")
	)
	(segment
		(start 447.117724 -11.075924)
		(end 446.129156 -11.27633)
		(width 0.1143)
		(layer "In9.Cu")
		(net "P3E_CPU0_PE1_PCH_CON_RXP<15>")
	)
	(segment
		(start 353.14636 -127.1778)
		(end 353.39782 -126.92634)
		(width 0.1143)
		(layer "In9.Cu")
		(net "P3E_CPU0_PE1_PCH_CON_RXP<15>")
	)
	(segment
		(start 447.216022 -5.09143)
		(end 447.186812 -5.09143)
		(width 0.1143)
		(layer "In9.Cu")
		(net "P3E_CPU0_PE1_PCH_CON_RXP<15>")
	)
	(segment
		(start 441.908692 -11.33094)
		(end 440.79033 -11.108182)
		(width 0.1143)
		(layer "In9.Cu")
		(net "P3E_CPU0_PE1_PCH_CON_RXP<15>")
	)
	(segment
		(start 357.943404 -65.959482)
		(end 356.869746 -67.478402)
		(width 0.1143)
		(layer "In9.Cu")
		(net "P3E_CPU0_PE1_PCH_CON_RXP<15>")
	)
	(segment
		(start 358.555544 -55.126382)
		(end 358.751124 -55.253636)
		(width 0.1143)
		(layer "In9.Cu")
		(net "P3E_CPU0_PE1_PCH_CON_RXP<15>")
	)
	(segment
		(start 349.75673 -126.842774)
		(end 349.92183 -126.677674)
		(width 0.1143)
		(layer "In9.Cu")
		(net "P3E_CPU0_PE1_PCH_CON_RXP<15>")
	)
	(segment
		(start 387.526784 -12.982702)
		(end 380.270258 -14.523212)
		(width 0.1143)
		(layer "In9.Cu")
		(net "P3E_CPU0_PE1_PCH_CON_RXP<15>")
	)
	(segment
		(start 358.443276 -89.937336)
		(end 358.570276 -90.13317)
		(width 0.1143)
		(layer "In9.Cu")
		(net "P3E_CPU0_PE1_PCH_CON_RXP<15>")
	)
	(segment
		(start 350.42983 -126.842774)
		(end 350.77273 -126.842774)
		(width 0.1143)
		(layer "In9.Cu")
		(net "P3E_CPU0_PE1_PCH_CON_RXP<15>")
	)
	(segment
		(start 427.739302 -11.224006)
		(end 427.344332 -10.96264)
		(width 0.1143)
		(layer "In9.Cu")
		(net "P3E_CPU0_PE1_PCH_CON_RXP<15>")
	)
	(segment
		(start 358.591104 -73.817226)
		(end 358.591104 -79.305404)
		(width 0.1143)
		(layer "In9.Cu")
		(net "P3E_CPU0_PE1_PCH_CON_RXP<15>")
	)
	(segment
		(start 352.734626 -126.336298)
		(end 352.734626 -126.68123)
		(width 0.1143)
		(layer "In9.Cu")
		(net "P3E_CPU0_PE1_PCH_CON_RXP<15>")
	)
	(segment
		(start 358.939592 -52.515008)
		(end 358.36098 -54.211474)
		(width 0.1143)
		(layer "In9.Cu")
		(net "P3E_CPU0_PE1_PCH_CON_RXP<15>")
	)
	(segment
		(start 425.312586 -10.929112)
		(end 425.25442 -10.917428)
		(width 0.1143)
		(layer "In9.Cu")
		(net "P3E_CPU0_PE1_PCH_CON_RXP<15>")
	)
	(segment
		(start 358.654096 -88.94318)
		(end 358.65435 -88.943434)
		(width 0.1143)
		(layer "In9.Cu")
		(net "P3E_CPU0_PE1_PCH_CON_RXP<15>")
	)
	(segment
		(start 353.39782 -126.380748)
		(end 353.17938 -126.22276)
		(width 0.1143)
		(layer "In9.Cu")
		(net "P3E_CPU0_PE1_PCH_CON_RXP<15>")
	)
	(segment
		(start 359.455974 -58.570876)
		(end 359.32872 -58.766456)
		(width 0.1143)
		(layer "In9.Cu")
		(net "P3E_CPU0_PE1_PCH_CON_RXP<15>")
	)
	(segment
		(start 419.579806 -11.04773)
		(end 418.80536 -10.882884)
		(width 0.1143)
		(layer "In9.Cu")
		(net "P3E_CPU0_PE1_PCH_CON_RXP<15>")
	)
	(segment
		(start 356.528878 -68.537328)
		(end 356.800912 -69.939408)
		(width 0.1143)
		(layer "In9.Cu")
		(net "P3E_CPU0_PE1_PCH_CON_RXP<15>")
	)
	(segment
		(start 367.026444 -29.67228)
		(end 367.270792 -30.896306)
		(width 0.1143)
		(layer "In9.Cu")
		(net "P3E_CPU0_PE1_PCH_CON_RXP<15>")
	)
	(segment
		(start 352.84918 -126.222252)
		(end 352.734626 -126.336298)
		(width 0.1143)
		(layer "In9.Cu")
		(net "P3E_CPU0_PE1_PCH_CON_RXP<15>")
	)
	(segment
		(start 352.86696 -126.222252)
		(end 352.84918 -126.222252)
		(width 0.1143)
		(layer "In9.Cu")
		(net "P3E_CPU0_PE1_PCH_CON_RXP<15>")
	)
	(segment
		(start 358.596946 -50.793396)
		(end 358.940608 -52.512214)
		(width 0.1143)
		(layer "In9.Cu")
		(net "P3E_CPU0_PE1_PCH_CON_RXP<15>")
	)
	(segment
		(start 357.127556 -98.85299)
		(end 358.267 -104.221788)
		(width 0.1143)
		(layer "In9.Cu")
		(net "P3E_CPU0_PE1_PCH_CON_RXP<15>")
	)
	(segment
		(start 358.766618 -56.120284)
		(end 358.962452 -56.247538)
		(width 0.1143)
		(layer "In9.Cu")
		(net "P3E_CPU0_PE1_PCH_CON_RXP<15>")
	)
	(segment
		(start 358.425496 -107.894882)
		(end 359.397046 -108.542328)
		(width 0.1143)
		(layer "In9.Cu")
		(net "P3E_CPU0_PE1_PCH_CON_RXP<15>")
	)
	(segment
		(start 345.222322 -125.037596)
		(end 345.464638 -125.279912)
		(width 0.1143)
		(layer "In9.Cu")
		(net "P3E_CPU0_PE1_PCH_CON_RXP<15>")
	)
	(segment
		(start 349.41383 -126.842774)
		(end 349.75673 -126.842774)
		(width 0.1143)
		(layer "In9.Cu")
		(net "P3E_CPU0_PE1_PCH_CON_RXP<15>")
	)
	(segment
		(start 345.979242 -126.842774)
		(end 348.74073 -126.842774)
		(width 0.1143)
		(layer "In9.Cu")
		(net "P3E_CPU0_PE1_PCH_CON_RXP<15>")
	)
	(segment
		(start 353.17938 -126.22276)
		(end 352.86696 -126.222252)
		(width 0.1143)
		(layer "In9.Cu")
		(net "P3E_CPU0_PE1_PCH_CON_RXP<15>")
	)
	(segment
		(start 358.359202 -91.126818)
		(end 358.288082 -91.462352)
		(width 0.1143)
		(layer "In9.Cu")
		(net "P3E_CPU0_PE1_PCH_CON_RXP<15>")
	)
	(segment
		(start 358.491028 -117.696234)
		(end 345.84259 -120.385586)
		(width 0.1143)
		(layer "In9.Cu")
		(net "P3E_CPU0_PE1_PCH_CON_RXP<15>")
	)
	(segment
		(start 358.499156 -90.46845)
		(end 358.303322 -90.595704)
		(width 0.1143)
		(layer "In9.Cu")
		(net "P3E_CPU0_PE1_PCH_CON_RXP<15>")
	)
	(segment
		(start 380.270258 -14.523212)
		(end 379.485906 -14.356842)
		(width 0.1143)
		(layer "In9.Cu")
		(net "P3E_CPU0_PE1_PCH_CON_RXP<15>")
	)
	(segment
		(start 358.267 -107.597448)
		(end 358.425496 -107.894882)
		(width 0.1143)
		(layer "In9.Cu")
		(net "P3E_CPU0_PE1_PCH_CON_RXP<15>")
	)
	(segment
		(start 431.123852 -10.866882)
		(end 428.554388 -11.389868)
		(width 0.1143)
		(layer "In9.Cu")
		(net "P3E_CPU0_PE1_PCH_CON_RXP<15>")
	)
	(segment
		(start 351.107756 -127.1778)
		(end 353.14636 -127.1778)
		(width 0.1143)
		(layer "In9.Cu")
		(net "P3E_CPU0_PE1_PCH_CON_RXP<15>")
	)
	(segment
		(start 367.270792 -30.896306)
		(end 366.772698 -33.382458)
		(width 0.1143)
		(layer "In9.Cu")
		(net "P3E_CPU0_PE1_PCH_CON_RXP<15>")
	)
	(segment
		(start 358.71023 -89.474802)
		(end 358.514396 -89.601802)
		(width 0.1143)
		(layer "In9.Cu")
		(net "P3E_CPU0_PE1_PCH_CON_RXP<15>")
	)
	(segment
		(start 358.4321 -106.726228)
		(end 358.267 -106.891328)
		(width 0.1143)
		(layer "In9.Cu")
		(net "P3E_CPU0_PE1_PCH_CON_RXP<15>")
	)
	(segment
		(start 367.309146 -28.258008)
		(end 367.026444 -29.67228)
		(width 0.1143)
		(layer "In9.Cu")
		(net "P3E_CPU0_PE1_PCH_CON_RXP<15>")
	)
	(segment
		(start 424.83532 -10.832084)
		(end 423.197782 -11.180318)
		(width 0.1143)
		(layer "In9.Cu")
		(net "P3E_CPU0_PE1_PCH_CON_RXP<15>")
	)
	(segment
		(start 358.076754 -92.456254)
		(end 357.881174 -92.583254)
		(width 0.1143)
		(layer "In9.Cu")
		(net "P3E_CPU0_PE1_PCH_CON_RXP<15>")
	)
	(segment
		(start 426.246036 -10.73912)
		(end 425.312586 -10.929112)
		(width 0.1143)
		(layer "In9.Cu")
		(net "P3E_CPU0_PE1_PCH_CON_RXP<15>")
	)
	(segment
		(start 433.305204 -11.310112)
		(end 431.123852 -10.866882)
		(width 0.1143)
		(layer "In9.Cu")
		(net "P3E_CPU0_PE1_PCH_CON_RXP<15>")
	)
	(segment
		(start 359.2449 -57.576974)
		(end 359.117646 -57.772554)
		(width 0.1143)
		(layer "In9.Cu")
		(net "P3E_CPU0_PE1_PCH_CON_RXP<15>")
	)
	(segment
		(start 447.186812 -5.09143)
		(end 446.900808 -5.377434)
		(width 0.1143)
		(layer "In9.Cu")
		(net "P3E_CPU0_PE1_PCH_CON_RXP<15>")
	)
	(segment
		(start 358.962452 -56.247538)
		(end 359.033826 -56.583072)
		(width 0.1143)
		(layer "In9.Cu")
		(net "P3E_CPU0_PE1_PCH_CON_RXP<15>")
	)
	(segment
		(start 356.800912 -69.939408)
		(end 358.591104 -73.817226)
		(width 0.1143)
		(layer "In9.Cu")
		(net "P3E_CPU0_PE1_PCH_CON_RXP<15>")
	)
	(segment
		(start 344.325702 -124.374402)
		(end 344.988896 -125.037596)
		(width 0.1143)
		(layer "In9.Cu")
		(net "P3E_CPU0_PE1_PCH_CON_RXP<15>")
	)
	(segment
		(start 425.25442 -10.917428)
		(end 425.25442 -10.917174)
		(width 0.1143)
		(layer "In9.Cu")
		(net "P3E_CPU0_PE1_PCH_CON_RXP<15>")
	)
	(segment
		(start 375.649744 -15.961868)
		(end 370.420138 -23.807674)
		(width 0.1143)
		(layer "In9.Cu")
		(net "P3E_CPU0_PE1_PCH_CON_RXP<15>")
	)
	(segment
		(start 358.822498 -55.58917)
		(end 358.695244 -55.78475)
		(width 0.1143)
		(layer "In9.Cu")
		(net "P3E_CPU0_PE1_PCH_CON_RXP<15>")
	)
	(segment
		(start 359.583736 -116.86159)
		(end 358.491028 -117.696234)
		(width 0.1143)
		(layer "In9.Cu")
		(net "P3E_CPU0_PE1_PCH_CON_RXP<15>")
	)
	(segment
		(start 358.977946 -57.114186)
		(end 359.173526 -57.24144)
		(width 0.1143)
		(layer "In9.Cu")
		(net "P3E_CPU0_PE1_PCH_CON_RXP<15>")
	)
	(segment
		(start 358.514396 -89.601802)
		(end 358.443276 -89.937336)
		(width 0.1143)
		(layer "In9.Cu")
		(net "P3E_CPU0_PE1_PCH_CON_RXP<15>")
	)
	(segment
		(start 369.763294 -26.760932)
		(end 369.44681 -27.18308)
		(width 0.1143)
		(layer "In9.Cu")
		(net "P3E_CPU0_PE1_PCH_CON_RXP<15>")
	)
	(segment
		(start 357.702612 -82.695034)
		(end 359.145586 -84.138008)
		(width 0.1143)
		(layer "In9.Cu")
		(net "P3E_CPU0_PE1_PCH_CON_RXP<15>")
	)
	(segment
		(start 377.388628 -14.802358)
		(end 375.649744 -15.961868)
		(width 0.1143)
		(layer "In9.Cu")
		(net "P3E_CPU0_PE1_PCH_CON_RXP<15>")
	)
	(segment
		(start 368.669824 -27.35453)
		(end 367.309146 -28.258008)
		(width 0.1143)
		(layer "In9.Cu")
		(net "P3E_CPU0_PE1_PCH_CON_RXP<15>")
	)
	(segment
		(start 358.751124 -55.253636)
		(end 358.822498 -55.58917)
		(width 0.1143)
		(layer "In9.Cu")
		(net "P3E_CPU0_PE1_PCH_CON_RXP<15>")
	)
	(segment
		(start 391.68197 -13.865606)
		(end 387.526784 -12.982702)
		(width 0.1143)
		(layer "In9.Cu")
		(net "P3E_CPU0_PE1_PCH_CON_RXP<15>")
	)
	(segment
		(start 425.25442 -10.917174)
		(end 424.83532 -10.832084)
		(width 0.1143)
		(layer "In9.Cu")
		(net "P3E_CPU0_PE1_PCH_CON_RXP<15>")
	)
	(segment
		(start 408.221434 -10.349992)
		(end 391.68197 -13.865606)
		(width 0.1143)
		(layer "In9.Cu")
		(net "P3E_CPU0_PE1_PCH_CON_RXP<15>")
	)
	(segment
		(start 358.267 -106.218228)
		(end 358.4321 -106.383328)
		(width 0.1143)
		(layer "In9.Cu")
		(net "P3E_CPU0_PE1_PCH_CON_RXP<15>")
	)
	(segment
		(start 379.485906 -14.356842)
		(end 377.388628 -14.802358)
		(width 0.1143)
		(layer "In9.Cu")
		(net "P3E_CPU0_PE1_PCH_CON_RXP<15>")
	)
	(segment
		(start 349.92183 -126.677674)
		(end 350.26473 -126.677674)
		(width 0.1143)
		(layer "In9.Cu")
		(net "P3E_CPU0_PE1_PCH_CON_RXP<15>")
	)
	(segment
		(start 348.74073 -126.842774)
		(end 348.90583 -126.677674)
		(width 0.1143)
		(layer "In9.Cu")
		(net "P3E_CPU0_PE1_PCH_CON_RXP<15>")
	)
	(segment
		(start 345.464638 -125.279912)
		(end 345.464638 -125.513338)
		(width 0.1143)
		(layer "In9.Cu")
		(net "P3E_CPU0_PE1_PCH_CON_RXP<15>")
	)
	(segment
		(start 444.156338 -10.881614)
		(end 441.908692 -11.33094)
		(width 0.1143)
		(layer "In9.Cu")
		(net "P3E_CPU0_PE1_PCH_CON_RXP<15>")
	)
	(segment
		(start 358.940608 -52.512214)
		(end 358.939592 -52.515008)
		(width 0.1143)
		(layer "In9.Cu")
		(net "P3E_CPU0_PE1_PCH_CON_RXP<15>")
	)
	(segment
		(start 345.707208 -125.755908)
		(end 345.707208 -126.57074)
		(width 0.1143)
		(layer "In9.Cu")
		(net "P3E_CPU0_PE1_PCH_CON_RXP<15>")
	)
	(segment
		(start 358.288082 -91.462352)
		(end 358.092248 -91.589606)
		(width 0.1143)
		(layer "In9.Cu")
		(net "P3E_CPU0_PE1_PCH_CON_RXP<15>")
	)
	(segment
		(start 446.900808 -6.027166)
		(end 447.542666 -6.669024)
		(width 0.1143)
		(layer "In9.Cu")
		(net "P3E_CPU0_PE1_PCH_CON_RXP<15>")
	)
	(segment
		(start 353.39782 -126.92634)
		(end 353.39782 -126.380748)
		(width 0.1143)
		(layer "In9.Cu")
		(net "P3E_CPU0_PE1_PCH_CON_RXP<15>")
	)
	(segment
		(start 357.992426 -94.78137)
		(end 357.127556 -98.85299)
		(width 0.1143)
		(layer "In9.Cu")
		(net "P3E_CPU0_PE1_PCH_CON_RXP<15>")
	)
	(segment
		(start 449.133214 -3.095752)
		(end 449.133214 -3.2512)
		(width 0.1143)
		(layer "F.Cu")
		(net "P3E_CPU0_PE1_PCH_CON_RXP<14>")
	)
	(segment
		(start 448.48653 -5.406644)
		(end 448.48653 -5.749544)
		(width 0.1143)
		(layer "F.Cu")
		(net "P3E_CPU0_PE1_PCH_CON_RXP<14>")
	)
	(segment
		(start 449.866512 -3.095752)
		(end 449.523612 -3.095752)
		(width 0.1143)
		(layer "F.Cu")
		(net "P3E_CPU0_PE1_PCH_CON_RXP<14>")
	)
	(segment
		(start 450.56933 -3.513836)
		(end 450.56933 -3.271012)
		(width 0.1143)
		(layer "F.Cu")
		(net "P3E_CPU0_PE1_PCH_CON_RXP<14>")
	)
	(segment
		(start 449.980812 -2.981452)
		(end 449.866512 -3.095752)
		(width 0.1143)
		(layer "F.Cu")
		(net "P3E_CPU0_PE1_PCH_CON_RXP<14>")
	)
	(segment
		(start 448.60083 -4.377944)
		(end 448.48653 -4.492244)
		(width 0.1143)
		(layer "F.Cu")
		(net "P3E_CPU0_PE1_PCH_CON_RXP<14>")
	)
	(segment
		(start 450.56933 -3.271012)
		(end 450.27977 -2.981452)
		(width 0.1143)
		(layer "F.Cu")
		(net "P3E_CPU0_PE1_PCH_CON_RXP<14>")
	)
	(segment
		(start 448.48653 -4.492244)
		(end 448.48653 -4.835144)
		(width 0.1143)
		(layer "F.Cu")
		(net "P3E_CPU0_PE1_PCH_CON_RXP<14>")
	)
	(segment
		(start 448.48653 -3.736086)
		(end 448.48653 -3.920744)
		(width 0.1143)
		(layer "F.Cu")
		(net "P3E_CPU0_PE1_PCH_CON_RXP<14>")
	)
	(segment
		(start 449.247514 -2.981452)
		(end 449.133214 -3.095752)
		(width 0.1143)
		(layer "F.Cu")
		(net "P3E_CPU0_PE1_PCH_CON_RXP<14>")
	)
	(segment
		(start 448.48653 -4.835144)
		(end 448.60083 -4.949444)
		(width 0.1143)
		(layer "F.Cu")
		(net "P3E_CPU0_PE1_PCH_CON_RXP<14>")
	)
	(segment
		(start 450.077078 -3.638296)
		(end 450.120512 -3.594862)
		(width 0.1143)
		(layer "F.Cu")
		(net "P3E_CPU0_PE1_PCH_CON_RXP<14>")
	)
	(segment
		(start 448.60083 -4.949444)
		(end 448.60083 -5.292344)
		(width 0.1143)
		(layer "F.Cu")
		(net "P3E_CPU0_PE1_PCH_CON_RXP<14>")
	)
	(segment
		(start 448.48653 -5.749544)
		(end 448.835526 -6.09854)
		(width 0.1143)
		(layer "F.Cu")
		(net "P3E_CPU0_PE1_PCH_CON_RXP<14>")
	)
	(segment
		(start 450.27977 -2.981452)
		(end 449.980812 -2.981452)
		(width 0.1143)
		(layer "F.Cu")
		(net "P3E_CPU0_PE1_PCH_CON_RXP<14>")
	)
	(segment
		(start 448.7291 -3.493516)
		(end 448.48653 -3.736086)
		(width 0.1143)
		(layer "F.Cu")
		(net "P3E_CPU0_PE1_PCH_CON_RXP<14>")
	)
	(segment
		(start 448.48653 -3.920744)
		(end 448.60083 -4.035044)
		(width 0.1143)
		(layer "F.Cu")
		(net "P3E_CPU0_PE1_PCH_CON_RXP<14>")
	)
	(segment
		(start 448.890644 -3.493516)
		(end 448.7291 -3.493516)
		(width 0.1143)
		(layer "F.Cu")
		(net "P3E_CPU0_PE1_PCH_CON_RXP<14>")
	)
	(segment
		(start 448.60083 -4.035044)
		(end 448.60083 -4.377944)
		(width 0.1143)
		(layer "F.Cu")
		(net "P3E_CPU0_PE1_PCH_CON_RXP<14>")
	)
	(segment
		(start 448.60083 -5.292344)
		(end 448.48653 -5.406644)
		(width 0.1143)
		(layer "F.Cu")
		(net "P3E_CPU0_PE1_PCH_CON_RXP<14>")
	)
	(segment
		(start 449.409312 -2.981452)
		(end 449.247514 -2.981452)
		(width 0.1143)
		(layer "F.Cu")
		(net "P3E_CPU0_PE1_PCH_CON_RXP<14>")
	)
	(segment
		(start 449.133214 -3.2512)
		(end 448.890644 -3.493516)
		(width 0.1143)
		(layer "F.Cu")
		(net "P3E_CPU0_PE1_PCH_CON_RXP<14>")
	)
	(segment
		(start 450.077078 -4.386072)
		(end 450.077078 -3.638296)
		(width 0.1143)
		(layer "F.Cu")
		(net "P3E_CPU0_PE1_PCH_CON_RXP<14>")
	)
	(segment
		(start 450.120512 -3.594862)
		(end 450.488304 -3.594862)
		(width 0.1143)
		(layer "F.Cu")
		(net "P3E_CPU0_PE1_PCH_CON_RXP<14>")
	)
	(segment
		(start 449.523612 -3.095752)
		(end 449.409312 -2.981452)
		(width 0.1143)
		(layer "F.Cu")
		(net "P3E_CPU0_PE1_PCH_CON_RXP<14>")
	)
	(segment
		(start 450.488304 -3.594862)
		(end 450.56933 -3.513836)
		(width 0.1143)
		(layer "F.Cu")
		(net "P3E_CPU0_PE1_PCH_CON_RXP<14>")
	)
	(via
		(at 448.835526 -6.09854)
		(size 0.508)
		(drill 0.254)
		(layers "F.Cu" "B.Cu")
		(net "P3E_CPU0_PE1_PCH_CON_RXP<14>")
	)
	(via
		(at 347.584014 -126.370842)
		(size 0.508)
		(drill 0.254)
		(layers "F.Cu" "B.Cu")
		(net "P3E_CPU0_PE1_PCH_CON_RXP<14>")
	)
	(segment
		(start 348.244414 -126.345442)
		(end 347.609414 -126.345442)
		(width 0.10795)
		(layer "B.Cu")
		(net "P3E_CPU0_PE1_PCH_CON_RXP<14>")
	)
	(segment
		(start 347.609414 -126.345442)
		(end 347.584014 -126.370842)
		(width 0.10795)
		(layer "B.Cu")
		(net "P3E_CPU0_PE1_PCH_CON_RXP<14>")
	)
	(segment
		(start 427.455838 -11.823446)
		(end 428.701708 -12.076684)
		(width 0.1143)
		(layer "In9.Cu")
		(net "P3E_CPU0_PE1_PCH_CON_RXP<14>")
	)
	(segment
		(start 358.830118 -118.284244)
		(end 360.408728 -117.078506)
		(width 0.1143)
		(layer "In9.Cu")
		(net "P3E_CPU0_PE1_PCH_CON_RXP<14>")
	)
	(segment
		(start 360.389424 -103.613458)
		(end 360.104182 -103.328216)
		(width 0.1143)
		(layer "In9.Cu")
		(net "P3E_CPU0_PE1_PCH_CON_RXP<14>")
	)
	(segment
		(start 359.582212 -51.872388)
		(end 359.342182 -50.671476)
		(width 0.1143)
		(layer "In9.Cu")
		(net "P3E_CPU0_PE1_PCH_CON_RXP<14>")
	)
	(segment
		(start 377.747784 -15.401798)
		(end 379.423676 -15.045182)
		(width 0.1143)
		(layer "In9.Cu")
		(net "P3E_CPU0_PE1_PCH_CON_RXP<14>")
	)
	(segment
		(start 438.219342 -12.51331)
		(end 439.399426 -12.754864)
		(width 0.1143)
		(layer "In9.Cu")
		(net "P3E_CPU0_PE1_PCH_CON_RXP<14>")
	)
	(segment
		(start 440.406282 -12.960858)
		(end 441.500006 -13.184632)
		(width 0.1143)
		(layer "In9.Cu")
		(net "P3E_CPU0_PE1_PCH_CON_RXP<14>")
	)
	(segment
		(start 348.480634 -125.492002)
		(end 348.480634 -124.853192)
		(width 0.1143)
		(layer "In9.Cu")
		(net "P3E_CPU0_PE1_PCH_CON_RXP<14>")
	)
	(segment
		(start 449.037202 -9.915906)
		(end 449.263008 -8.884158)
		(width 0.1143)
		(layer "In9.Cu")
		(net "P3E_CPU0_PE1_PCH_CON_RXP<14>")
	)
	(segment
		(start 432.18481 -11.770868)
		(end 432.664616 -12.087606)
		(width 0.1143)
		(layer "In9.Cu")
		(net "P3E_CPU0_PE1_PCH_CON_RXP<14>")
	)
	(segment
		(start 443.668404 -13.683996)
		(end 443.892432 -13.348462)
		(width 0.1143)
		(layer "In9.Cu")
		(net "P3E_CPU0_PE1_PCH_CON_RXP<14>")
	)
	(segment
		(start 359.28681 -104.903016)
		(end 359.17251 -104.788716)
		(width 0.1143)
		(layer "In9.Cu")
		(net "P3E_CPU0_PE1_PCH_CON_RXP<14>")
	)
	(segment
		(start 360.4641 -82.496152)
		(end 359.97007 -82.002122)
		(width 0.1143)
		(layer "In9.Cu")
		(net "P3E_CPU0_PE1_PCH_CON_RXP<14>")
	)
	(segment
		(start 444.108078 -12.675616)
		(end 444.24219 -12.765024)
		(width 0.1143)
		(layer "In9.Cu")
		(net "P3E_CPU0_PE1_PCH_CON_RXP<14>")
	)
	(segment
		(start 369.860576 -28.392882)
		(end 370.19611 -28.168854)
		(width 0.1143)
		(layer "In9.Cu")
		(net "P3E_CPU0_PE1_PCH_CON_RXP<14>")
	)
	(segment
		(start 359.30205 -98.025712)
		(end 359.30205 -93.051122)
		(width 0.1143)
		(layer "In9.Cu")
		(net "P3E_CPU0_PE1_PCH_CON_RXP<14>")
	)
	(segment
		(start 449.263008 -8.884158)
		(end 448.549522 -7.152386)
		(width 0.1143)
		(layer "In9.Cu")
		(net "P3E_CPU0_PE1_PCH_CON_RXP<14>")
	)
	(segment
		(start 369.647216 -28.35021)
		(end 369.860576 -28.392882)
		(width 0.1143)
		(layer "In9.Cu")
		(net "P3E_CPU0_PE1_PCH_CON_RXP<14>")
	)
	(segment
		(start 444.24219 -12.765024)
		(end 444.34125 -13.258038)
		(width 0.1143)
		(layer "In9.Cu")
		(net "P3E_CPU0_PE1_PCH_CON_RXP<14>")
	)
	(segment
		(start 437.604916 -12.637516)
		(end 437.607964 -12.6365)
		(width 0.1143)
		(layer "In9.Cu")
		(net "P3E_CPU0_PE1_PCH_CON_RXP<14>")
	)
	(segment
		(start 380.15291 -15.200376)
		(end 387.368034 -13.667486)
		(width 0.1143)
		(layer "In9.Cu")
		(net "P3E_CPU0_PE1_PCH_CON_RXP<14>")
	)
	(segment
		(start 346.16517 -120.976644)
		(end 358.830118 -118.284244)
		(width 0.1143)
		(layer "In9.Cu")
		(net "P3E_CPU0_PE1_PCH_CON_RXP<14>")
	)
	(segment
		(start 421.415464 -12.226544)
		(end 424.806364 -11.50493)
		(width 0.1143)
		(layer "In9.Cu")
		(net "P3E_CPU0_PE1_PCH_CON_RXP<14>")
	)
	(segment
		(start 436.48122 -12.864846)
		(end 437.604916 -12.637516)
		(width 0.1143)
		(layer "In9.Cu")
		(net "P3E_CPU0_PE1_PCH_CON_RXP<14>")
	)
	(segment
		(start 439.735722 -12.532614)
		(end 439.800492 -12.216384)
		(width 0.1143)
		(layer "In9.Cu")
		(net "P3E_CPU0_PE1_PCH_CON_RXP<14>")
	)
	(segment
		(start 439.399426 -12.754864)
		(end 439.735722 -12.532614)
		(width 0.1143)
		(layer "In9.Cu")
		(net "P3E_CPU0_PE1_PCH_CON_RXP<14>")
	)
	(segment
		(start 414.58388 -12.407646)
		(end 418.542724 -11.615674)
		(width 0.1143)
		(layer "In9.Cu")
		(net "P3E_CPU0_PE1_PCH_CON_RXP<14>")
	)
	(segment
		(start 359.28681 -102.832916)
		(end 360.104182 -102.832916)
		(width 0.1143)
		(layer "In9.Cu")
		(net "P3E_CPU0_PE1_PCH_CON_RXP<14>")
	)
	(segment
		(start 443.206886 -13.77696)
		(end 443.668404 -13.683996)
		(width 0.1143)
		(layer "In9.Cu")
		(net "P3E_CPU0_PE1_PCH_CON_RXP<14>")
	)
	(segment
		(start 424.806364 -11.50493)
		(end 425.253404 -11.596116)
		(width 0.1143)
		(layer "In9.Cu")
		(net "P3E_CPU0_PE1_PCH_CON_RXP<14>")
	)
	(segment
		(start 444.677038 -13.482066)
		(end 445.138556 -13.389102)
		(width 0.1143)
		(layer "In9.Cu")
		(net "P3E_CPU0_PE1_PCH_CON_RXP<14>")
	)
	(segment
		(start 361.159806 -113.541302)
		(end 360.389424 -109.91596)
		(width 0.1143)
		(layer "In9.Cu")
		(net "P3E_CPU0_PE1_PCH_CON_RXP<14>")
	)
	(segment
		(start 359.342182 -50.671476)
		(end 359.397046 -50.39741)
		(width 0.1143)
		(layer "In9.Cu")
		(net "P3E_CPU0_PE1_PCH_CON_RXP<14>")
	)
	(segment
		(start 445.352932 -12.426188)
		(end 446.8495 -12.125706)
		(width 0.1143)
		(layer "In9.Cu")
		(net "P3E_CPU0_PE1_PCH_CON_RXP<14>")
	)
	(segment
		(start 360.389424 -104.122474)
		(end 360.389424 -103.613458)
		(width 0.1143)
		(layer "In9.Cu")
		(net "P3E_CPU0_PE1_PCH_CON_RXP<14>")
	)
	(segment
		(start 344.986864 -123.843542)
		(end 344.986864 -121.837958)
		(width 0.1143)
		(layer "In9.Cu")
		(net "P3E_CPU0_PE1_PCH_CON_RXP<14>")
	)
	(segment
		(start 345.17203 -121.543064)
		(end 346.16517 -120.976644)
		(width 0.1143)
		(layer "In9.Cu")
		(net "P3E_CPU0_PE1_PCH_CON_RXP<14>")
	)
	(segment
		(start 445.138556 -13.389102)
		(end 445.362584 -13.053568)
		(width 0.1143)
		(layer "In9.Cu")
		(net "P3E_CPU0_PE1_PCH_CON_RXP<14>")
	)
	(segment
		(start 360.389424 -102.547674)
		(end 360.389424 -101.219762)
		(width 0.1143)
		(layer "In9.Cu")
		(net "P3E_CPU0_PE1_PCH_CON_RXP<14>")
	)
	(segment
		(start 347.584014 -126.021592)
		(end 347.698314 -125.907292)
		(width 0.1143)
		(layer "In9.Cu")
		(net "P3E_CPU0_PE1_PCH_CON_RXP<14>")
	)
	(segment
		(start 446.8495 -12.125706)
		(end 448.34683 -11.048238)
		(width 0.1143)
		(layer "In9.Cu")
		(net "P3E_CPU0_PE1_PCH_CON_RXP<14>")
	)
	(segment
		(start 359.97007 -76.3778)
		(end 359.344468 -73.903586)
		(width 0.1143)
		(layer "In9.Cu")
		(net "P3E_CPU0_PE1_PCH_CON_RXP<14>")
	)
	(segment
		(start 358.543352 -66.32194)
		(end 360.17962 -58.617104)
		(width 0.1143)
		(layer "In9.Cu")
		(net "P3E_CPU0_PE1_PCH_CON_RXP<14>")
	)
	(segment
		(start 428.701708 -12.076684)
		(end 431.191162 -11.570462)
		(width 0.1143)
		(layer "In9.Cu")
		(net "P3E_CPU0_PE1_PCH_CON_RXP<14>")
	)
	(segment
		(start 359.344468 -73.903586)
		(end 357.474266 -69.85254)
		(width 0.1143)
		(layer "In9.Cu")
		(net "P3E_CPU0_PE1_PCH_CON_RXP<14>")
	)
	(segment
		(start 368.05616 -32.821118)
		(end 369.78463 -30.227524)
		(width 0.1143)
		(layer "In9.Cu")
		(net "P3E_CPU0_PE1_PCH_CON_RXP<14>")
	)
	(segment
		(start 359.17251 -104.522016)
		(end 359.28681 -104.407716)
		(width 0.1143)
		(layer "In9.Cu")
		(net "P3E_CPU0_PE1_PCH_CON_RXP<14>")
	)
	(segment
		(start 439.800492 -12.216384)
		(end 439.935112 -12.127484)
		(width 0.1143)
		(layer "In9.Cu")
		(net "P3E_CPU0_PE1_PCH_CON_RXP<14>")
	)
	(segment
		(start 359.17251 -104.788716)
		(end 359.17251 -104.522016)
		(width 0.1143)
		(layer "In9.Cu")
		(net "P3E_CPU0_PE1_PCH_CON_RXP<14>")
	)
	(segment
		(start 443.793372 -12.855194)
		(end 443.88278 -12.720828)
		(width 0.1143)
		(layer "In9.Cu")
		(net "P3E_CPU0_PE1_PCH_CON_RXP<14>")
	)
	(segment
		(start 442.637418 -12.970002)
		(end 442.772038 -13.059918)
		(width 0.1143)
		(layer "In9.Cu")
		(net "P3E_CPU0_PE1_PCH_CON_RXP<14>")
	)
	(segment
		(start 369.78463 -30.227524)
		(end 369.994688 -29.176726)
		(width 0.1143)
		(layer "In9.Cu")
		(net "P3E_CPU0_PE1_PCH_CON_RXP<14>")
	)
	(segment
		(start 370.19611 -28.168854)
		(end 370.993924 -24.179784)
		(width 0.1143)
		(layer "In9.Cu")
		(net "P3E_CPU0_PE1_PCH_CON_RXP<14>")
	)
	(segment
		(start 369.770914 -28.841192)
		(end 369.557554 -28.79852)
		(width 0.1143)
		(layer "In9.Cu")
		(net "P3E_CPU0_PE1_PCH_CON_RXP<14>")
	)
	(segment
		(start 360.03484 -100.865178)
		(end 360.03484 -98.758502)
		(width 0.1143)
		(layer "In9.Cu")
		(net "P3E_CPU0_PE1_PCH_CON_RXP<14>")
	)
	(segment
		(start 443.892432 -13.348462)
		(end 443.793372 -12.855194)
		(width 0.1143)
		(layer "In9.Cu")
		(net "P3E_CPU0_PE1_PCH_CON_RXP<14>")
	)
	(segment
		(start 347.698314 -125.907292)
		(end 348.065344 -125.907292)
		(width 0.1143)
		(layer "In9.Cu")
		(net "P3E_CPU0_PE1_PCH_CON_RXP<14>")
	)
	(segment
		(start 357.474266 -69.85254)
		(end 357.222298 -68.587112)
		(width 0.1143)
		(layer "In9.Cu")
		(net "P3E_CPU0_PE1_PCH_CON_RXP<14>")
	)
	(segment
		(start 426.220128 -11.39952)
		(end 427.080934 -11.575288)
		(width 0.1143)
		(layer "In9.Cu")
		(net "P3E_CPU0_PE1_PCH_CON_RXP<14>")
	)
	(segment
		(start 360.4641 -91.889072)
		(end 360.4641 -82.496152)
		(width 0.1143)
		(layer "In9.Cu")
		(net "P3E_CPU0_PE1_PCH_CON_RXP<14>")
	)
	(segment
		(start 363.221016 -43.811698)
		(end 364.531402 -37.16274)
		(width 0.1143)
		(layer "In9.Cu")
		(net "P3E_CPU0_PE1_PCH_CON_RXP<14>")
	)
	(segment
		(start 360.775758 -49.177194)
		(end 360.671618 -48.78705)
		(width 0.1143)
		(layer "In9.Cu")
		(net "P3E_CPU0_PE1_PCH_CON_RXP<14>")
	)
	(segment
		(start 442.871098 -13.552932)
		(end 443.206886 -13.77696)
		(width 0.1143)
		(layer "In9.Cu")
		(net "P3E_CPU0_PE1_PCH_CON_RXP<14>")
	)
	(segment
		(start 364.531402 -37.16274)
		(end 368.05616 -32.821118)
		(width 0.1143)
		(layer "In9.Cu")
		(net "P3E_CPU0_PE1_PCH_CON_RXP<14>")
	)
	(segment
		(start 379.423676 -15.045182)
		(end 380.15291 -15.200376)
		(width 0.1143)
		(layer "In9.Cu")
		(net "P3E_CPU0_PE1_PCH_CON_RXP<14>")
	)
	(segment
		(start 360.104182 -102.832916)
		(end 360.389424 -102.547674)
		(width 0.1143)
		(layer "In9.Cu")
		(net "P3E_CPU0_PE1_PCH_CON_RXP<14>")
	)
	(segment
		(start 370.993924 -24.179784)
		(end 376.122692 -16.485108)
		(width 0.1143)
		(layer "In9.Cu")
		(net "P3E_CPU0_PE1_PCH_CON_RXP<14>")
	)
	(segment
		(start 448.34683 -11.048238)
		(end 449.037202 -9.915906)
		(width 0.1143)
		(layer "In9.Cu")
		(net "P3E_CPU0_PE1_PCH_CON_RXP<14>")
	)
	(segment
		(start 391.52068 -14.549374)
		(end 408.08656 -11.028172)
		(width 0.1143)
		(layer "In9.Cu")
		(net "P3E_CPU0_PE1_PCH_CON_RXP<14>")
	)
	(segment
		(start 359.837482 -49.63922)
		(end 359.99293 -49.597818)
		(width 0.1143)
		(layer "In9.Cu")
		(net "P3E_CPU0_PE1_PCH_CON_RXP<14>")
	)
	(segment
		(start 357.455978 -67.860164)
		(end 358.543352 -66.32194)
		(width 0.1143)
		(layer "In9.Cu")
		(net "P3E_CPU0_PE1_PCH_CON_RXP<14>")
	)
	(segment
		(start 360.389424 -101.219762)
		(end 360.03484 -100.865178)
		(width 0.1143)
		(layer "In9.Cu")
		(net "P3E_CPU0_PE1_PCH_CON_RXP<14>")
	)
	(segment
		(start 360.17962 -58.617104)
		(end 359.184448 -53.93309)
		(width 0.1143)
		(layer "In9.Cu")
		(net "P3E_CPU0_PE1_PCH_CON_RXP<14>")
	)
	(segment
		(start 445.362584 -13.053568)
		(end 445.263524 -12.5603)
		(width 0.1143)
		(layer "In9.Cu")
		(net "P3E_CPU0_PE1_PCH_CON_RXP<14>")
	)
	(segment
		(start 360.104182 -104.903016)
		(end 359.28681 -104.903016)
		(width 0.1143)
		(layer "In9.Cu")
		(net "P3E_CPU0_PE1_PCH_CON_RXP<14>")
	)
	(segment
		(start 359.17251 -103.213916)
		(end 359.17251 -102.947216)
		(width 0.1143)
		(layer "In9.Cu")
		(net "P3E_CPU0_PE1_PCH_CON_RXP<14>")
	)
	(segment
		(start 444.34125 -13.258038)
		(end 444.677038 -13.482066)
		(width 0.1143)
		(layer "In9.Cu")
		(net "P3E_CPU0_PE1_PCH_CON_RXP<14>")
	)
	(segment
		(start 359.17251 -102.947216)
		(end 359.28681 -102.832916)
		(width 0.1143)
		(layer "In9.Cu")
		(net "P3E_CPU0_PE1_PCH_CON_RXP<14>")
	)
	(segment
		(start 387.368034 -13.667486)
		(end 391.52068 -14.549374)
		(width 0.1143)
		(layer "In9.Cu")
		(net "P3E_CPU0_PE1_PCH_CON_RXP<14>")
	)
	(segment
		(start 344.986864 -121.837958)
		(end 345.17203 -121.543064)
		(width 0.1143)
		(layer "In9.Cu")
		(net "P3E_CPU0_PE1_PCH_CON_RXP<14>")
	)
	(segment
		(start 347.845634 -124.218192)
		(end 345.361514 -124.218192)
		(width 0.1143)
		(layer "In9.Cu")
		(net "P3E_CPU0_PE1_PCH_CON_RXP<14>")
	)
	(segment
		(start 440.248548 -12.308078)
		(end 440.183778 -12.624308)
		(width 0.1143)
		(layer "In9.Cu")
		(net "P3E_CPU0_PE1_PCH_CON_RXP<14>")
	)
	(segment
		(start 360.104182 -103.328216)
		(end 359.28681 -103.328216)
		(width 0.1143)
		(layer "In9.Cu")
		(net "P3E_CPU0_PE1_PCH_CON_RXP<14>")
	)
	(segment
		(start 442.772038 -13.059918)
		(end 442.871098 -13.552932)
		(width 0.1143)
		(layer "In9.Cu")
		(net "P3E_CPU0_PE1_PCH_CON_RXP<14>")
	)
	(segment
		(start 369.557554 -28.79852)
		(end 369.467892 -28.664408)
		(width 0.1143)
		(layer "In9.Cu")
		(net "P3E_CPU0_PE1_PCH_CON_RXP<14>")
	)
	(segment
		(start 360.389424 -109.91596)
		(end 360.389424 -105.188258)
		(width 0.1143)
		(layer "In9.Cu")
		(net "P3E_CPU0_PE1_PCH_CON_RXP<14>")
	)
	(segment
		(start 360.53903 -49.58461)
		(end 360.775758 -49.177194)
		(width 0.1143)
		(layer "In9.Cu")
		(net "P3E_CPU0_PE1_PCH_CON_RXP<14>")
	)
	(segment
		(start 360.03484 -98.758502)
		(end 359.30205 -98.025712)
		(width 0.1143)
		(layer "In9.Cu")
		(net "P3E_CPU0_PE1_PCH_CON_RXP<14>")
	)
	(segment
		(start 360.408728 -117.078506)
		(end 361.159806 -113.541302)
		(width 0.1143)
		(layer "In9.Cu")
		(net "P3E_CPU0_PE1_PCH_CON_RXP<14>")
	)
	(segment
		(start 360.148632 -49.688496)
		(end 360.53903 -49.58461)
		(width 0.1143)
		(layer "In9.Cu")
		(net "P3E_CPU0_PE1_PCH_CON_RXP<14>")
	)
	(segment
		(start 345.361514 -124.218192)
		(end 344.986864 -123.843542)
		(width 0.1143)
		(layer "In9.Cu")
		(net "P3E_CPU0_PE1_PCH_CON_RXP<14>")
	)
	(segment
		(start 432.664616 -12.087606)
		(end 436.48122 -12.864846)
		(width 0.1143)
		(layer "In9.Cu")
		(net "P3E_CPU0_PE1_PCH_CON_RXP<14>")
	)
	(segment
		(start 431.191162 -11.570462)
		(end 432.18481 -11.770868)
		(width 0.1143)
		(layer "In9.Cu")
		(net "P3E_CPU0_PE1_PCH_CON_RXP<14>")
	)
	(segment
		(start 357.222298 -68.587112)
		(end 357.455978 -67.860164)
		(width 0.1143)
		(layer "In9.Cu")
		(net "P3E_CPU0_PE1_PCH_CON_RXP<14>")
	)
	(segment
		(start 359.28681 -104.407716)
		(end 360.104182 -104.407716)
		(width 0.1143)
		(layer "In9.Cu")
		(net "P3E_CPU0_PE1_PCH_CON_RXP<14>")
	)
	(segment
		(start 347.584014 -126.370842)
		(end 347.584014 -126.021592)
		(width 0.1143)
		(layer "In9.Cu")
		(net "P3E_CPU0_PE1_PCH_CON_RXP<14>")
	)
	(segment
		(start 437.607964 -12.6365)
		(end 438.219342 -12.51331)
		(width 0.1143)
		(layer "In9.Cu")
		(net "P3E_CPU0_PE1_PCH_CON_RXP<14>")
	)
	(segment
		(start 359.397046 -50.39741)
		(end 359.837482 -49.63922)
		(width 0.1143)
		(layer "In9.Cu")
		(net "P3E_CPU0_PE1_PCH_CON_RXP<14>")
	)
	(segment
		(start 448.549522 -7.152386)
		(end 448.549522 -6.384544)
		(width 0.1143)
		(layer "In9.Cu")
		(net "P3E_CPU0_PE1_PCH_CON_RXP<14>")
	)
	(segment
		(start 441.500006 -13.184632)
		(end 441.560458 -13.184632)
		(width 0.1143)
		(layer "In9.Cu")
		(net "P3E_CPU0_PE1_PCH_CON_RXP<14>")
	)
	(segment
		(start 359.99293 -49.597818)
		(end 360.148632 -49.688496)
		(width 0.1143)
		(layer "In9.Cu")
		(net "P3E_CPU0_PE1_PCH_CON_RXP<14>")
	)
	(segment
		(start 369.467892 -28.664408)
		(end 369.51285 -28.439872)
		(width 0.1143)
		(layer "In9.Cu")
		(net "P3E_CPU0_PE1_PCH_CON_RXP<14>")
	)
	(segment
		(start 359.694988 -52.436014)
		(end 359.582212 -51.872388)
		(width 0.1143)
		(layer "In9.Cu")
		(net "P3E_CPU0_PE1_PCH_CON_RXP<14>")
	)
	(segment
		(start 359.30205 -93.051122)
		(end 360.4641 -91.889072)
		(width 0.1143)
		(layer "In9.Cu")
		(net "P3E_CPU0_PE1_PCH_CON_RXP<14>")
	)
	(segment
		(start 360.671618 -48.78705)
		(end 360.51617 -48.696626)
		(width 0.1143)
		(layer "In9.Cu")
		(net "P3E_CPU0_PE1_PCH_CON_RXP<14>")
	)
	(segment
		(start 360.51617 -48.696626)
		(end 360.474768 -48.540924)
		(width 0.1143)
		(layer "In9.Cu")
		(net "P3E_CPU0_PE1_PCH_CON_RXP<14>")
	)
	(segment
		(start 440.183778 -12.624308)
		(end 440.406282 -12.960858)
		(width 0.1143)
		(layer "In9.Cu")
		(net "P3E_CPU0_PE1_PCH_CON_RXP<14>")
	)
	(segment
		(start 360.389424 -105.188258)
		(end 360.104182 -104.903016)
		(width 0.1143)
		(layer "In9.Cu")
		(net "P3E_CPU0_PE1_PCH_CON_RXP<14>")
	)
	(segment
		(start 443.88278 -12.720828)
		(end 444.108078 -12.675616)
		(width 0.1143)
		(layer "In9.Cu")
		(net "P3E_CPU0_PE1_PCH_CON_RXP<14>")
	)
	(segment
		(start 348.480634 -124.853192)
		(end 347.845634 -124.218192)
		(width 0.1143)
		(layer "In9.Cu")
		(net "P3E_CPU0_PE1_PCH_CON_RXP<14>")
	)
	(segment
		(start 408.08656 -11.028172)
		(end 414.58388 -12.407646)
		(width 0.1143)
		(layer "In9.Cu")
		(net "P3E_CPU0_PE1_PCH_CON_RXP<14>")
	)
	(segment
		(start 359.28681 -103.328216)
		(end 359.17251 -103.213916)
		(width 0.1143)
		(layer "In9.Cu")
		(net "P3E_CPU0_PE1_PCH_CON_RXP<14>")
	)
	(segment
		(start 439.935112 -12.127484)
		(end 440.159648 -12.173458)
		(width 0.1143)
		(layer "In9.Cu")
		(net "P3E_CPU0_PE1_PCH_CON_RXP<14>")
	)
	(segment
		(start 369.994688 -29.176726)
		(end 369.770914 -28.841192)
		(width 0.1143)
		(layer "In9.Cu")
		(net "P3E_CPU0_PE1_PCH_CON_RXP<14>")
	)
	(segment
		(start 441.560458 -13.184632)
		(end 442.637418 -12.970002)
		(width 0.1143)
		(layer "In9.Cu")
		(net "P3E_CPU0_PE1_PCH_CON_RXP<14>")
	)
	(segment
		(start 445.263524 -12.5603)
		(end 445.352932 -12.426188)
		(width 0.1143)
		(layer "In9.Cu")
		(net "P3E_CPU0_PE1_PCH_CON_RXP<14>")
	)
	(segment
		(start 359.184448 -53.93309)
		(end 359.694988 -52.436014)
		(width 0.1143)
		(layer "In9.Cu")
		(net "P3E_CPU0_PE1_PCH_CON_RXP<14>")
	)
	(segment
		(start 376.122692 -16.485108)
		(end 377.747784 -15.401798)
		(width 0.1143)
		(layer "In9.Cu")
		(net "P3E_CPU0_PE1_PCH_CON_RXP<14>")
	)
	(segment
		(start 440.159648 -12.173458)
		(end 440.248548 -12.308078)
		(width 0.1143)
		(layer "In9.Cu")
		(net "P3E_CPU0_PE1_PCH_CON_RXP<14>")
	)
	(segment
		(start 448.549522 -6.384544)
		(end 448.835526 -6.09854)
		(width 0.1143)
		(layer "In9.Cu")
		(net "P3E_CPU0_PE1_PCH_CON_RXP<14>")
	)
	(segment
		(start 360.474768 -48.540924)
		(end 363.221016 -43.811698)
		(width 0.1143)
		(layer "In9.Cu")
		(net "P3E_CPU0_PE1_PCH_CON_RXP<14>")
	)
	(segment
		(start 360.104182 -104.407716)
		(end 360.389424 -104.122474)
		(width 0.1143)
		(layer "In9.Cu")
		(net "P3E_CPU0_PE1_PCH_CON_RXP<14>")
	)
	(segment
		(start 418.542724 -11.615674)
		(end 421.415464 -12.226544)
		(width 0.1143)
		(layer "In9.Cu")
		(net "P3E_CPU0_PE1_PCH_CON_RXP<14>")
	)
	(segment
		(start 359.97007 -82.002122)
		(end 359.97007 -76.3778)
		(width 0.1143)
		(layer "In9.Cu")
		(net "P3E_CPU0_PE1_PCH_CON_RXP<14>")
	)
	(segment
		(start 427.080934 -11.575288)
		(end 427.455838 -11.823446)
		(width 0.1143)
		(layer "In9.Cu")
		(net "P3E_CPU0_PE1_PCH_CON_RXP<14>")
	)
	(segment
		(start 348.065344 -125.907292)
		(end 348.480634 -125.492002)
		(width 0.1143)
		(layer "In9.Cu")
		(net "P3E_CPU0_PE1_PCH_CON_RXP<14>")
	)
	(segment
		(start 369.51285 -28.439872)
		(end 369.647216 -28.35021)
		(width 0.1143)
		(layer "In9.Cu")
		(net "P3E_CPU0_PE1_PCH_CON_RXP<14>")
	)
	(segment
		(start 425.253404 -11.596116)
		(end 426.220128 -11.39952)
		(width 0.1143)
		(layer "In9.Cu")
		(net "P3E_CPU0_PE1_PCH_CON_RXP<14>")
	)
	(segment
		(start 442.876686 -4.8895)
		(end 442.876686 -4.386072)
		(width 0.1143)
		(layer "F.Cu")
		(net "P3E_CPU0_PE1_PCH_CON_RXP<13>")
	)
	(segment
		(start 443.226444 -5.239258)
		(end 442.876686 -4.8895)
		(width 0.1143)
		(layer "F.Cu")
		(net "P3E_CPU0_PE1_PCH_CON_RXP<13>")
	)
	(segment
		(start 442.995304 -5.892038)
		(end 443.226444 -5.660898)
		(width 0.1143)
		(layer "F.Cu")
		(net "P3E_CPU0_PE1_PCH_CON_RXP<13>")
	)
	(segment
		(start 443.226444 -5.660898)
		(end 443.226444 -5.239258)
		(width 0.1143)
		(layer "F.Cu")
		(net "P3E_CPU0_PE1_PCH_CON_RXP<13>")
	)
	(segment
		(start 442.760608 -5.892038)
		(end 442.995304 -5.892038)
		(width 0.1143)
		(layer "F.Cu")
		(net "P3E_CPU0_PE1_PCH_CON_RXP<13>")
	)
	(via
		(at 347.042486 -123.600972)
		(size 0.508)
		(drill 0.254)
		(layers "F.Cu" "B.Cu")
		(net "P3E_CPU0_PE1_PCH_CON_RXP<13>")
	)
	(via
		(at 442.760608 -5.892038)
		(size 0.508)
		(drill 0.254)
		(layers "F.Cu" "B.Cu")
		(net "P3E_CPU0_PE1_PCH_CON_RXP<13>")
	)
	(segment
		(start 347.685614 -123.576842)
		(end 347.066616 -123.576842)
		(width 0.10795)
		(layer "B.Cu")
		(net "P3E_CPU0_PE1_PCH_CON_RXP<13>")
	)
	(segment
		(start 347.066616 -123.576842)
		(end 347.042486 -123.600972)
		(width 0.10795)
		(layer "B.Cu")
		(net "P3E_CPU0_PE1_PCH_CON_RXP<13>")
	)
	(segment
		(start 426.673518 -12.163806)
		(end 426.835316 -12.271502)
		(width 0.1143)
		(layer "In9.Cu")
		(net "P3E_CPU0_PE1_PCH_CON_RXP<13>")
	)
	(segment
		(start 425.251118 -12.274296)
		(end 425.251118 -12.274042)
		(width 0.1143)
		(layer "In9.Cu")
		(net "P3E_CPU0_PE1_PCH_CON_RXP<13>")
	)
	(segment
		(start 446.471294 -4.180332)
		(end 443.978538 -4.709922)
		(width 0.1143)
		(layer "In9.Cu")
		(net "P3E_CPU0_PE1_PCH_CON_RXP<13>")
	)
	(segment
		(start 450.26453 -4.86156)
		(end 448.679062 -4.180332)
		(width 0.1143)
		(layer "In9.Cu")
		(net "P3E_CPU0_PE1_PCH_CON_RXP<13>")
	)
	(segment
		(start 348.43212 -123.109228)
		(end 350.6724 -120.868948)
		(width 0.1143)
		(layer "In9.Cu")
		(net "P3E_CPU0_PE1_PCH_CON_RXP<13>")
	)
	(segment
		(start 448.679062 -4.180332)
		(end 446.471294 -4.180332)
		(width 0.1143)
		(layer "In9.Cu")
		(net "P3E_CPU0_PE1_PCH_CON_RXP<13>")
	)
	(segment
		(start 428.743872 -13.116306)
		(end 429.488346 -12.624054)
		(width 0.1143)
		(layer "In9.Cu")
		(net "P3E_CPU0_PE1_PCH_CON_RXP<13>")
	)
	(segment
		(start 429.683672 -12.584176)
		(end 435.576726 -13.774166)
		(width 0.1143)
		(layer "In9.Cu")
		(net "P3E_CPU0_PE1_PCH_CON_RXP<13>")
	)
	(segment
		(start 427.162722 -12.765786)
		(end 427.73346 -13.143484)
		(width 0.1143)
		(layer "In9.Cu")
		(net "P3E_CPU0_PE1_PCH_CON_RXP<13>")
	)
	(segment
		(start 449.996814 -9.229344)
		(end 450.59473 -6.41477)
		(width 0.1143)
		(layer "In9.Cu")
		(net "P3E_CPU0_PE1_PCH_CON_RXP<13>")
	)
	(segment
		(start 361.2896 -76.345542)
		(end 360.57967 -75.635358)
		(width 0.1143)
		(layer "In9.Cu")
		(net "P3E_CPU0_PE1_PCH_CON_RXP<13>")
	)
	(segment
		(start 357.894382 -68.607432)
		(end 358.0257 -68.200524)
		(width 0.1143)
		(layer "In9.Cu")
		(net "P3E_CPU0_PE1_PCH_CON_RXP<13>")
	)
	(segment
		(start 380.094744 -15.877032)
		(end 387.365494 -14.332458)
		(width 0.1143)
		(layer "In9.Cu")
		(net "P3E_CPU0_PE1_PCH_CON_RXP<13>")
	)
	(segment
		(start 426.673772 -12.163552)
		(end 426.673518 -12.163552)
		(width 0.1143)
		(layer "In9.Cu")
		(net "P3E_CPU0_PE1_PCH_CON_RXP<13>")
	)
	(segment
		(start 361.232196 -50.79111)
		(end 361.908344 -47.411386)
		(width 0.1143)
		(layer "In9.Cu")
		(net "P3E_CPU0_PE1_PCH_CON_RXP<13>")
	)
	(segment
		(start 391.48512 -15.207234)
		(end 408.017218 -11.693398)
		(width 0.1143)
		(layer "In9.Cu")
		(net "P3E_CPU0_PE1_PCH_CON_RXP<13>")
	)
	(segment
		(start 442.776864 -14.673834)
		(end 445.425576 -14.14399)
		(width 0.1143)
		(layer "In9.Cu")
		(net "P3E_CPU0_PE1_PCH_CON_RXP<13>")
	)
	(segment
		(start 414.624266 -13.095732)
		(end 418.641784 -12.29233)
		(width 0.1143)
		(layer "In9.Cu")
		(net "P3E_CPU0_PE1_PCH_CON_RXP<13>")
	)
	(segment
		(start 368.248692 -33.715706)
		(end 370.425218 -30.451044)
		(width 0.1143)
		(layer "In9.Cu")
		(net "P3E_CPU0_PE1_PCH_CON_RXP<13>")
	)
	(segment
		(start 428.169324 -13.232892)
		(end 428.743872 -13.116306)
		(width 0.1143)
		(layer "In9.Cu")
		(net "P3E_CPU0_PE1_PCH_CON_RXP<13>")
	)
	(segment
		(start 361.835954 -113.416334)
		(end 361.202732 -110.435644)
		(width 0.1143)
		(layer "In9.Cu")
		(net "P3E_CPU0_PE1_PCH_CON_RXP<13>")
	)
	(segment
		(start 449.989448 -11.10234)
		(end 450.180202 -10.147808)
		(width 0.1143)
		(layer "In9.Cu")
		(net "P3E_CPU0_PE1_PCH_CON_RXP<13>")
	)
	(segment
		(start 445.425576 -14.14399)
		(end 449.989448 -11.10234)
		(width 0.1143)
		(layer "In9.Cu")
		(net "P3E_CPU0_PE1_PCH_CON_RXP<13>")
	)
	(segment
		(start 443.978538 -4.709922)
		(end 443.249558 -5.445506)
		(width 0.1143)
		(layer "In9.Cu")
		(net "P3E_CPU0_PE1_PCH_CON_RXP<13>")
	)
	(segment
		(start 358.097328 -69.656706)
		(end 357.894382 -68.607432)
		(width 0.1143)
		(layer "In9.Cu")
		(net "P3E_CPU0_PE1_PCH_CON_RXP<13>")
	)
	(segment
		(start 437.003952 -14.374114)
		(end 439.251344 -13.924788)
		(width 0.1143)
		(layer "In9.Cu")
		(net "P3E_CPU0_PE1_PCH_CON_RXP<13>")
	)
	(segment
		(start 350.672654 -120.868948)
		(end 350.855788 -120.685814)
		(width 0.1143)
		(layer "In9.Cu")
		(net "P3E_CPU0_PE1_PCH_CON_RXP<13>")
	)
	(segment
		(start 347.042486 -123.600972)
		(end 347.042486 -123.50877)
		(width 0.1143)
		(layer "In9.Cu")
		(net "P3E_CPU0_PE1_PCH_CON_RXP<13>")
	)
	(segment
		(start 359.161842 -66.592704)
		(end 360.92638 -58.28792)
		(width 0.1143)
		(layer "In9.Cu")
		(net "P3E_CPU0_PE1_PCH_CON_RXP<13>")
	)
	(segment
		(start 361.202732 -103.854758)
		(end 362.118656 -99.38131)
		(width 0.1143)
		(layer "In9.Cu")
		(net "P3E_CPU0_PE1_PCH_CON_RXP<13>")
	)
	(segment
		(start 350.855788 -120.685814)
		(end 359.083864 -118.937024)
		(width 0.1143)
		(layer "In9.Cu")
		(net "P3E_CPU0_PE1_PCH_CON_RXP<13>")
	)
	(segment
		(start 379.330712 -15.714472)
		(end 380.094744 -15.877032)
		(width 0.1143)
		(layer "In9.Cu")
		(net "P3E_CPU0_PE1_PCH_CON_RXP<13>")
	)
	(segment
		(start 359.083864 -118.937024)
		(end 360.96956 -117.496336)
		(width 0.1143)
		(layer "In9.Cu")
		(net "P3E_CPU0_PE1_PCH_CON_RXP<13>")
	)
	(segment
		(start 358.0257 -68.200524)
		(end 359.161842 -66.592704)
		(width 0.1143)
		(layer "In9.Cu")
		(net "P3E_CPU0_PE1_PCH_CON_RXP<13>")
	)
	(segment
		(start 347.042486 -123.50877)
		(end 347.442028 -123.109228)
		(width 0.1143)
		(layer "In9.Cu")
		(net "P3E_CPU0_PE1_PCH_CON_RXP<13>")
	)
	(segment
		(start 426.235622 -12.074144)
		(end 426.673772 -12.163552)
		(width 0.1143)
		(layer "In9.Cu")
		(net "P3E_CPU0_PE1_PCH_CON_RXP<13>")
	)
	(segment
		(start 376.69089 -16.901922)
		(end 378.069856 -15.982696)
		(width 0.1143)
		(layer "In9.Cu")
		(net "P3E_CPU0_PE1_PCH_CON_RXP<13>")
	)
	(segment
		(start 363.756448 -44.638468)
		(end 365.186722 -37.486336)
		(width 0.1143)
		(layer "In9.Cu")
		(net "P3E_CPU0_PE1_PCH_CON_RXP<13>")
	)
	(segment
		(start 360.06278 -54.219602)
		(end 361.232196 -50.79111)
		(width 0.1143)
		(layer "In9.Cu")
		(net "P3E_CPU0_PE1_PCH_CON_RXP<13>")
	)
	(segment
		(start 387.365494 -14.332458)
		(end 391.48512 -15.207234)
		(width 0.1143)
		(layer "In9.Cu")
		(net "P3E_CPU0_PE1_PCH_CON_RXP<13>")
	)
	(segment
		(start 443.249558 -5.777738)
		(end 443.135258 -5.892038)
		(width 0.1143)
		(layer "In9.Cu")
		(net "P3E_CPU0_PE1_PCH_CON_RXP<13>")
	)
	(segment
		(start 424.784774 -12.203176)
		(end 425.192952 -12.28598)
		(width 0.1143)
		(layer "In9.Cu")
		(net "P3E_CPU0_PE1_PCH_CON_RXP<13>")
	)
	(segment
		(start 365.186722 -37.486336)
		(end 368.248692 -33.715706)
		(width 0.1143)
		(layer "In9.Cu")
		(net "P3E_CPU0_PE1_PCH_CON_RXP<13>")
	)
	(segment
		(start 359.995724 -73.77049)
		(end 358.097328 -69.656706)
		(width 0.1143)
		(layer "In9.Cu")
		(net "P3E_CPU0_PE1_PCH_CON_RXP<13>")
	)
	(segment
		(start 378.069856 -15.982696)
		(end 379.330712 -15.714472)
		(width 0.1143)
		(layer "In9.Cu")
		(net "P3E_CPU0_PE1_PCH_CON_RXP<13>")
	)
	(segment
		(start 362.118656 -99.38131)
		(end 362.118656 -95.736918)
		(width 0.1143)
		(layer "In9.Cu")
		(net "P3E_CPU0_PE1_PCH_CON_RXP<13>")
	)
	(segment
		(start 443.135258 -5.892038)
		(end 442.760608 -5.892038)
		(width 0.1143)
		(layer "In9.Cu")
		(net "P3E_CPU0_PE1_PCH_CON_RXP<13>")
	)
	(segment
		(start 347.442028 -123.109228)
		(end 348.43212 -123.109228)
		(width 0.1143)
		(layer "In9.Cu")
		(net "P3E_CPU0_PE1_PCH_CON_RXP<13>")
	)
	(segment
		(start 421.459406 -12.891262)
		(end 424.784774 -12.203176)
		(width 0.1143)
		(layer "In9.Cu")
		(net "P3E_CPU0_PE1_PCH_CON_RXP<13>")
	)
	(segment
		(start 450.180202 -10.147808)
		(end 449.996814 -9.229344)
		(width 0.1143)
		(layer "In9.Cu")
		(net "P3E_CPU0_PE1_PCH_CON_RXP<13>")
	)
	(segment
		(start 425.251118 -12.274042)
		(end 426.235622 -12.074144)
		(width 0.1143)
		(layer "In9.Cu")
		(net "P3E_CPU0_PE1_PCH_CON_RXP<13>")
	)
	(segment
		(start 443.249558 -5.445506)
		(end 443.249558 -5.777738)
		(width 0.1143)
		(layer "In9.Cu")
		(net "P3E_CPU0_PE1_PCH_CON_RXP<13>")
	)
	(segment
		(start 450.59473 -6.41477)
		(end 450.264276 -4.86156)
		(width 0.1143)
		(layer "In9.Cu")
		(net "P3E_CPU0_PE1_PCH_CON_RXP<13>")
	)
	(segment
		(start 427.73346 -13.143484)
		(end 428.169324 -13.232892)
		(width 0.1143)
		(layer "In9.Cu")
		(net "P3E_CPU0_PE1_PCH_CON_RXP<13>")
	)
	(segment
		(start 450.264276 -4.86156)
		(end 450.26453 -4.86156)
		(width 0.1143)
		(layer "In9.Cu")
		(net "P3E_CPU0_PE1_PCH_CON_RXP<13>")
	)
	(segment
		(start 435.576726 -13.774166)
		(end 436.252112 -14.224)
		(width 0.1143)
		(layer "In9.Cu")
		(net "P3E_CPU0_PE1_PCH_CON_RXP<13>")
	)
	(segment
		(start 371.626384 -24.500586)
		(end 376.69089 -16.901922)
		(width 0.1143)
		(layer "In9.Cu")
		(net "P3E_CPU0_PE1_PCH_CON_RXP<13>")
	)
	(segment
		(start 360.96956 -117.496336)
		(end 361.835954 -113.416334)
		(width 0.1143)
		(layer "In9.Cu")
		(net "P3E_CPU0_PE1_PCH_CON_RXP<13>")
	)
	(segment
		(start 361.908344 -47.411386)
		(end 363.756448 -44.638468)
		(width 0.1143)
		(layer "In9.Cu")
		(net "P3E_CPU0_PE1_PCH_CON_RXP<13>")
	)
	(segment
		(start 418.641784 -12.29233)
		(end 421.459406 -12.891262)
		(width 0.1143)
		(layer "In9.Cu")
		(net "P3E_CPU0_PE1_PCH_CON_RXP<13>")
	)
	(segment
		(start 425.192952 -12.28598)
		(end 425.251118 -12.274296)
		(width 0.1143)
		(layer "In9.Cu")
		(net "P3E_CPU0_PE1_PCH_CON_RXP<13>")
	)
	(segment
		(start 429.488346 -12.624054)
		(end 429.683672 -12.584176)
		(width 0.1143)
		(layer "In9.Cu")
		(net "P3E_CPU0_PE1_PCH_CON_RXP<13>")
	)
	(segment
		(start 361.2896 -91.827858)
		(end 361.2896 -76.345542)
		(width 0.1143)
		(layer "In9.Cu")
		(net "P3E_CPU0_PE1_PCH_CON_RXP<13>")
	)
	(segment
		(start 426.835316 -12.271502)
		(end 427.162722 -12.765786)
		(width 0.1143)
		(layer "In9.Cu")
		(net "P3E_CPU0_PE1_PCH_CON_RXP<13>")
	)
	(segment
		(start 370.425218 -30.451044)
		(end 371.626384 -24.500586)
		(width 0.1143)
		(layer "In9.Cu")
		(net "P3E_CPU0_PE1_PCH_CON_RXP<13>")
	)
	(segment
		(start 362.118656 -95.736918)
		(end 361.2896 -91.827858)
		(width 0.1143)
		(layer "In9.Cu")
		(net "P3E_CPU0_PE1_PCH_CON_RXP<13>")
	)
	(segment
		(start 408.017218 -11.693398)
		(end 414.624266 -13.095732)
		(width 0.1143)
		(layer "In9.Cu")
		(net "P3E_CPU0_PE1_PCH_CON_RXP<13>")
	)
	(segment
		(start 360.57967 -75.635358)
		(end 359.995724 -73.77049)
		(width 0.1143)
		(layer "In9.Cu")
		(net "P3E_CPU0_PE1_PCH_CON_RXP<13>")
	)
	(segment
		(start 350.6724 -120.868948)
		(end 350.672654 -120.868948)
		(width 0.1143)
		(layer "In9.Cu")
		(net "P3E_CPU0_PE1_PCH_CON_RXP<13>")
	)
	(segment
		(start 361.202732 -110.435644)
		(end 361.202732 -103.854758)
		(width 0.1143)
		(layer "In9.Cu")
		(net "P3E_CPU0_PE1_PCH_CON_RXP<13>")
	)
	(segment
		(start 360.92638 -58.28792)
		(end 360.06278 -54.219602)
		(width 0.1143)
		(layer "In9.Cu")
		(net "P3E_CPU0_PE1_PCH_CON_RXP<13>")
	)
	(segment
		(start 426.673518 -12.163552)
		(end 426.673518 -12.163806)
		(width 0.1143)
		(layer "In9.Cu")
		(net "P3E_CPU0_PE1_PCH_CON_RXP<13>")
	)
	(segment
		(start 436.252112 -14.224)
		(end 437.003952 -14.374114)
		(width 0.1143)
		(layer "In9.Cu")
		(net "P3E_CPU0_PE1_PCH_CON_RXP<13>")
	)
	(segment
		(start 439.251344 -13.924788)
		(end 442.776864 -14.673834)
		(width 0.1143)
		(layer "In9.Cu")
		(net "P3E_CPU0_PE1_PCH_CON_RXP<13>")
	)
	(segment
		(start 440.686952 -5.343398)
		(end 440.476386 -5.132832)
		(width 0.1143)
		(layer "F.Cu")
		(net "P3E_CPU0_PE1_PCH_CON_RXP<12>")
	)
	(segment
		(start 440.224672 -5.667248)
		(end 440.603132 -5.667248)
		(width 0.1143)
		(layer "F.Cu")
		(net "P3E_CPU0_PE1_PCH_CON_RXP<12>")
	)
	(segment
		(start 440.476386 -5.132832)
		(end 440.476386 -4.386072)
		(width 0.1143)
		(layer "F.Cu")
		(net "P3E_CPU0_PE1_PCH_CON_RXP<12>")
	)
	(segment
		(start 440.686952 -5.583428)
		(end 440.686952 -5.343398)
		(width 0.1143)
		(layer "F.Cu")
		(net "P3E_CPU0_PE1_PCH_CON_RXP<12>")
	)
	(segment
		(start 440.603132 -5.667248)
		(end 440.686952 -5.583428)
		(width 0.1143)
		(layer "F.Cu")
		(net "P3E_CPU0_PE1_PCH_CON_RXP<12>")
	)
	(via
		(at 440.224672 -5.667248)
		(size 0.508)
		(drill 0.254)
		(layers "F.Cu" "B.Cu")
		(net "P3E_CPU0_PE1_PCH_CON_RXP<12>")
	)
	(via
		(at 352.105214 -122.586242)
		(size 0.508)
		(drill 0.254)
		(layers "F.Cu" "B.Cu")
		(net "P3E_CPU0_PE1_PCH_CON_RXP<12>")
	)
	(segment
		(start 352.181414 -122.662442)
		(end 352.105214 -122.586242)
		(width 0.10795)
		(layer "B.Cu")
		(net "P3E_CPU0_PE1_PCH_CON_RXP<12>")
	)
	(segment
		(start 352.765614 -122.662442)
		(end 352.181414 -122.662442)
		(width 0.10795)
		(layer "B.Cu")
		(net "P3E_CPU0_PE1_PCH_CON_RXP<12>")
	)
	(segment
		(start 441.191396 -4.64947)
		(end 441.191396 -4.649724)
		(width 0.1143)
		(layer "In9.Cu")
		(net "P3E_CPU0_PE1_PCH_CON_RXP<12>")
	)
	(segment
		(start 425.665392 -13.542518)
		(end 426.542708 -13.364464)
		(width 0.1143)
		(layer "In9.Cu")
		(net "P3E_CPU0_PE1_PCH_CON_RXP<12>")
	)
	(segment
		(start 440.73826 -5.10286)
		(end 440.73826 -5.53974)
		(width 0.1143)
		(layer "In9.Cu")
		(net "P3E_CPU0_PE1_PCH_CON_RXP<12>")
	)
	(segment
		(start 368.730276 -34.1503)
		(end 371.030246 -30.700472)
		(width 0.1143)
		(layer "In9.Cu")
		(net "P3E_CPU0_PE1_PCH_CON_RXP<12>")
	)
	(segment
		(start 362.754164 -95.353378)
		(end 361.9246 -91.449906)
		(width 0.1143)
		(layer "In9.Cu")
		(net "P3E_CPU0_PE1_PCH_CON_RXP<12>")
	)
	(segment
		(start 446.397888 -3.545332)
		(end 441.191396 -4.64947)
		(width 0.1143)
		(layer "In9.Cu")
		(net "P3E_CPU0_PE1_PCH_CON_RXP<12>")
	)
	(segment
		(start 428.792132 -14.127988)
		(end 429.792384 -13.924534)
		(width 0.1143)
		(layer "In9.Cu")
		(net "P3E_CPU0_PE1_PCH_CON_RXP<12>")
	)
	(segment
		(start 440.610752 -5.667248)
		(end 440.224672 -5.667248)
		(width 0.1143)
		(layer "In9.Cu")
		(net "P3E_CPU0_PE1_PCH_CON_RXP<12>")
	)
	(segment
		(start 450.597016 -11.518392)
		(end 450.868542 -10.159746)
		(width 0.1143)
		(layer "In9.Cu")
		(net "P3E_CPU0_PE1_PCH_CON_RXP<12>")
	)
	(segment
		(start 362.567728 -47.599854)
		(end 364.35665 -44.932854)
		(width 0.1143)
		(layer "In9.Cu")
		(net "P3E_CPU0_PE1_PCH_CON_RXP<12>")
	)
	(segment
		(start 351.04197 -121.398284)
		(end 359.257346 -119.652034)
		(width 0.1143)
		(layer "In9.Cu")
		(net "P3E_CPU0_PE1_PCH_CON_RXP<12>")
	)
	(segment
		(start 451.260464 -6.394196)
		(end 450.831458 -4.382262)
		(width 0.1143)
		(layer "In9.Cu")
		(net "P3E_CPU0_PE1_PCH_CON_RXP<12>")
	)
	(segment
		(start 364.35665 -44.932854)
		(end 365.048292 -41.47693)
		(width 0.1143)
		(layer "In9.Cu")
		(net "P3E_CPU0_PE1_PCH_CON_RXP<12>")
	)
	(segment
		(start 407.958798 -12.356338)
		(end 414.577276 -13.763244)
		(width 0.1143)
		(layer "In9.Cu")
		(net "P3E_CPU0_PE1_PCH_CON_RXP<12>")
	)
	(segment
		(start 359.257346 -119.652034)
		(end 361.529884 -117.916452)
		(width 0.1143)
		(layer "In9.Cu")
		(net "P3E_CPU0_PE1_PCH_CON_RXP<12>")
	)
	(segment
		(start 361.43946 -52.22113)
		(end 361.932474 -50.775108)
		(width 0.1143)
		(layer "In9.Cu")
		(net "P3E_CPU0_PE1_PCH_CON_RXP<12>")
	)
	(segment
		(start 350.113854 -122.326146)
		(end 351.04197 -121.398284)
		(width 0.1143)
		(layer "In9.Cu")
		(net "P3E_CPU0_PE1_PCH_CON_RXP<12>")
	)
	(segment
		(start 359.639362 -69.050408)
		(end 359.845102 -68.020692)
		(width 0.1143)
		(layer "In9.Cu")
		(net "P3E_CPU0_PE1_PCH_CON_RXP<12>")
	)
	(segment
		(start 425.108878 -13.91031)
		(end 425.665392 -13.542518)
		(width 0.1143)
		(layer "In9.Cu")
		(net "P3E_CPU0_PE1_PCH_CON_RXP<12>")
	)
	(segment
		(start 371.030246 -30.700472)
		(end 372.306088 -24.700484)
		(width 0.1143)
		(layer "In9.Cu")
		(net "P3E_CPU0_PE1_PCH_CON_RXP<12>")
	)
	(segment
		(start 439.76671 -16.135858)
		(end 440.923934 -16.437864)
		(width 0.1143)
		(layer "In9.Cu")
		(net "P3E_CPU0_PE1_PCH_CON_RXP<12>")
	)
	(segment
		(start 426.752512 -13.406628)
		(end 427.421294 -13.84935)
		(width 0.1143)
		(layer "In9.Cu")
		(net "P3E_CPU0_PE1_PCH_CON_RXP<12>")
	)
	(segment
		(start 426.542708 -13.364464)
		(end 426.752512 -13.406628)
		(width 0.1143)
		(layer "In9.Cu")
		(net "P3E_CPU0_PE1_PCH_CON_RXP<12>")
	)
	(segment
		(start 440.923934 -16.437864)
		(end 444.199518 -15.78229)
		(width 0.1143)
		(layer "In9.Cu")
		(net "P3E_CPU0_PE1_PCH_CON_RXP<12>")
	)
	(segment
		(start 361.152186 -75.166728)
		(end 360.487214 -73.042526)
		(width 0.1143)
		(layer "In9.Cu")
		(net "P3E_CPU0_PE1_PCH_CON_RXP<12>")
	)
	(segment
		(start 362.803186 -56.35117)
		(end 361.43946 -52.22113)
		(width 0.1143)
		(layer "In9.Cu")
		(net "P3E_CPU0_PE1_PCH_CON_RXP<12>")
	)
	(segment
		(start 418.636704 -12.951714)
		(end 424.1292 -14.109446)
		(width 0.1143)
		(layer "In9.Cu")
		(net "P3E_CPU0_PE1_PCH_CON_RXP<12>")
	)
	(segment
		(start 365.965486 -40.312594)
		(end 366.225836 -39.736268)
		(width 0.1143)
		(layer "In9.Cu")
		(net "P3E_CPU0_PE1_PCH_CON_RXP<12>")
	)
	(segment
		(start 360.487214 -73.042526)
		(end 359.639362 -69.050408)
		(width 0.1143)
		(layer "In9.Cu")
		(net "P3E_CPU0_PE1_PCH_CON_RXP<12>")
	)
	(segment
		(start 359.68559 -67.223132)
		(end 361.37215 -59.285124)
		(width 0.1143)
		(layer "In9.Cu")
		(net "P3E_CPU0_PE1_PCH_CON_RXP<12>")
	)
	(segment
		(start 414.577276 -13.763244)
		(end 418.636704 -12.951714)
		(width 0.1143)
		(layer "In9.Cu")
		(net "P3E_CPU0_PE1_PCH_CON_RXP<12>")
	)
	(segment
		(start 361.37215 -59.285124)
		(end 362.803186 -56.35117)
		(width 0.1143)
		(layer "In9.Cu")
		(net "P3E_CPU0_PE1_PCH_CON_RXP<12>")
	)
	(segment
		(start 362.754164 -99.461066)
		(end 362.754164 -95.353378)
		(width 0.1143)
		(layer "In9.Cu")
		(net "P3E_CPU0_PE1_PCH_CON_RXP<12>")
	)
	(segment
		(start 439.306462 -15.828518)
		(end 439.76671 -16.135858)
		(width 0.1143)
		(layer "In9.Cu")
		(net "P3E_CPU0_PE1_PCH_CON_RXP<12>")
	)
	(segment
		(start 427.421294 -13.84935)
		(end 428.792132 -14.127988)
		(width 0.1143)
		(layer "In9.Cu")
		(net "P3E_CPU0_PE1_PCH_CON_RXP<12>")
	)
	(segment
		(start 450.868542 -10.159746)
		(end 450.671184 -9.17194)
		(width 0.1143)
		(layer "In9.Cu")
		(net "P3E_CPU0_PE1_PCH_CON_RXP<12>")
	)
	(segment
		(start 424.1292 -14.109446)
		(end 425.108878 -13.91031)
		(width 0.1143)
		(layer "In9.Cu")
		(net "P3E_CPU0_PE1_PCH_CON_RXP<12>")
	)
	(segment
		(start 350.342454 -123.0376)
		(end 350.113854 -122.809)
		(width 0.1143)
		(layer "In9.Cu")
		(net "P3E_CPU0_PE1_PCH_CON_RXP<12>")
	)
	(segment
		(start 361.932474 -50.775108)
		(end 362.567728 -47.599854)
		(width 0.1143)
		(layer "In9.Cu")
		(net "P3E_CPU0_PE1_PCH_CON_RXP<12>")
	)
	(segment
		(start 366.225836 -39.736268)
		(end 367.002314 -36.277804)
		(width 0.1143)
		(layer "In9.Cu")
		(net "P3E_CPU0_PE1_PCH_CON_RXP<12>")
	)
	(segment
		(start 379.965204 -16.557498)
		(end 387.226302 -15.014956)
		(width 0.1143)
		(layer "In9.Cu")
		(net "P3E_CPU0_PE1_PCH_CON_RXP<12>")
	)
	(segment
		(start 377.209812 -17.343374)
		(end 378.20219 -16.681704)
		(width 0.1143)
		(layer "In9.Cu")
		(net "P3E_CPU0_PE1_PCH_CON_RXP<12>")
	)
	(segment
		(start 444.199518 -15.78229)
		(end 450.597016 -11.518392)
		(width 0.1143)
		(layer "In9.Cu")
		(net "P3E_CPU0_PE1_PCH_CON_RXP<12>")
	)
	(segment
		(start 365.048292 -41.47693)
		(end 365.965486 -40.312594)
		(width 0.1143)
		(layer "In9.Cu")
		(net "P3E_CPU0_PE1_PCH_CON_RXP<12>")
	)
	(segment
		(start 450.831458 -4.382262)
		(end 448.883786 -3.545332)
		(width 0.1143)
		(layer "In9.Cu")
		(net "P3E_CPU0_PE1_PCH_CON_RXP<12>")
	)
	(segment
		(start 361.529884 -117.916452)
		(end 362.49102 -113.390426)
		(width 0.1143)
		(layer "In9.Cu")
		(net "P3E_CPU0_PE1_PCH_CON_RXP<12>")
	)
	(segment
		(start 440.73826 -5.53974)
		(end 440.610752 -5.667248)
		(width 0.1143)
		(layer "In9.Cu")
		(net "P3E_CPU0_PE1_PCH_CON_RXP<12>")
	)
	(segment
		(start 441.191396 -4.649724)
		(end 440.73826 -5.10286)
		(width 0.1143)
		(layer "In9.Cu")
		(net "P3E_CPU0_PE1_PCH_CON_RXP<12>")
	)
	(segment
		(start 359.845102 -68.020692)
		(end 359.68559 -67.223132)
		(width 0.1143)
		(layer "In9.Cu")
		(net "P3E_CPU0_PE1_PCH_CON_RXP<12>")
	)
	(segment
		(start 367.002314 -36.277804)
		(end 368.730276 -34.1503)
		(width 0.1143)
		(layer "In9.Cu")
		(net "P3E_CPU0_PE1_PCH_CON_RXP<12>")
	)
	(segment
		(start 361.9246 -91.449906)
		(end 361.9246 -75.939396)
		(width 0.1143)
		(layer "In9.Cu")
		(net "P3E_CPU0_PE1_PCH_CON_RXP<12>")
	)
	(segment
		(start 379.375924 -16.432276)
		(end 379.965204 -16.557498)
		(width 0.1143)
		(layer "In9.Cu")
		(net "P3E_CPU0_PE1_PCH_CON_RXP<12>")
	)
	(segment
		(start 352.105214 -122.586242)
		(end 351.653856 -123.0376)
		(width 0.1143)
		(layer "In9.Cu")
		(net "P3E_CPU0_PE1_PCH_CON_RXP<12>")
	)
	(segment
		(start 362.49102 -113.390426)
		(end 362.028486 -111.212376)
		(width 0.1143)
		(layer "In9.Cu")
		(net "P3E_CPU0_PE1_PCH_CON_RXP<12>")
	)
	(segment
		(start 350.113854 -122.809)
		(end 350.113854 -122.326146)
		(width 0.1143)
		(layer "In9.Cu")
		(net "P3E_CPU0_PE1_PCH_CON_RXP<12>")
	)
	(segment
		(start 429.792384 -13.924534)
		(end 439.306462 -15.828518)
		(width 0.1143)
		(layer "In9.Cu")
		(net "P3E_CPU0_PE1_PCH_CON_RXP<12>")
	)
	(segment
		(start 387.226302 -15.014956)
		(end 391.338562 -15.889224)
		(width 0.1143)
		(layer "In9.Cu")
		(net "P3E_CPU0_PE1_PCH_CON_RXP<12>")
	)
	(segment
		(start 391.338562 -15.889224)
		(end 407.958798 -12.356338)
		(width 0.1143)
		(layer "In9.Cu")
		(net "P3E_CPU0_PE1_PCH_CON_RXP<12>")
	)
	(segment
		(start 448.883786 -3.545332)
		(end 446.397888 -3.545332)
		(width 0.1143)
		(layer "In9.Cu")
		(net "P3E_CPU0_PE1_PCH_CON_RXP<12>")
	)
	(segment
		(start 450.671184 -9.17194)
		(end 451.260464 -6.394196)
		(width 0.1143)
		(layer "In9.Cu")
		(net "P3E_CPU0_PE1_PCH_CON_RXP<12>")
	)
	(segment
		(start 362.028486 -103.004112)
		(end 362.754164 -99.461066)
		(width 0.1143)
		(layer "In9.Cu")
		(net "P3E_CPU0_PE1_PCH_CON_RXP<12>")
	)
	(segment
		(start 362.028486 -111.212376)
		(end 362.028486 -103.004112)
		(width 0.1143)
		(layer "In9.Cu")
		(net "P3E_CPU0_PE1_PCH_CON_RXP<12>")
	)
	(segment
		(start 372.306088 -24.700484)
		(end 377.209812 -17.343374)
		(width 0.1143)
		(layer "In9.Cu")
		(net "P3E_CPU0_PE1_PCH_CON_RXP<12>")
	)
	(segment
		(start 361.9246 -75.939396)
		(end 361.152186 -75.166728)
		(width 0.1143)
		(layer "In9.Cu")
		(net "P3E_CPU0_PE1_PCH_CON_RXP<12>")
	)
	(segment
		(start 378.20219 -16.681704)
		(end 379.375924 -16.432276)
		(width 0.1143)
		(layer "In9.Cu")
		(net "P3E_CPU0_PE1_PCH_CON_RXP<12>")
	)
	(segment
		(start 351.653856 -123.0376)
		(end 350.342454 -123.0376)
		(width 0.1143)
		(layer "In9.Cu")
		(net "P3E_CPU0_PE1_PCH_CON_RXP<12>")
	)
	(segment
		(start 438.330086 -3.504184)
		(end 438.330086 -3.024886)
		(width 0.1143)
		(layer "F.Cu")
		(net "P3E_CPU0_PE1_PCH_CON_RXP<11>")
	)
	(segment
		(start 438.195974 -2.890774)
		(end 437.814212 -2.890774)
		(width 0.1143)
		(layer "F.Cu")
		(net "P3E_CPU0_PE1_PCH_CON_RXP<11>")
	)
	(segment
		(start 438.076086 -3.758184)
		(end 438.330086 -3.504184)
		(width 0.1143)
		(layer "F.Cu")
		(net "P3E_CPU0_PE1_PCH_CON_RXP<11>")
	)
	(segment
		(start 438.076086 -4.386072)
		(end 438.076086 -3.758184)
		(width 0.1143)
		(layer "F.Cu")
		(net "P3E_CPU0_PE1_PCH_CON_RXP<11>")
	)
	(segment
		(start 438.330086 -3.024886)
		(end 438.195974 -2.890774)
		(width 0.1143)
		(layer "F.Cu")
		(net "P3E_CPU0_PE1_PCH_CON_RXP<11>")
	)
	(via
		(at 360.258614 -121.240042)
		(size 0.508)
		(drill 0.254)
		(layers "F.Cu" "B.Cu")
		(net "P3E_CPU0_PE1_PCH_CON_RXP<11>")
	)
	(via
		(at 437.814212 -2.890774)
		(size 0.508)
		(drill 0.254)
		(layers "F.Cu" "B.Cu")
		(net "P3E_CPU0_PE1_PCH_CON_RXP<11>")
	)
	(segment
		(start 360.937556 -121.392442)
		(end 360.411014 -121.392442)
		(width 0.1143)
		(layer "B.Cu")
		(net "P3E_CPU0_PE1_PCH_CON_RXP<11>")
	)
	(segment
		(start 360.411014 -121.392442)
		(end 360.258614 -121.240042)
		(width 0.1143)
		(layer "B.Cu")
		(net "P3E_CPU0_PE1_PCH_CON_RXP<11>")
	)
	(segment
		(start 363.54258 -56.387238)
		(end 361.994196 -59.561984)
		(width 0.1143)
		(layer "In9.Cu")
		(net "P3E_CPU0_PE1_PCH_CON_RXP<11>")
	)
	(segment
		(start 441.207398 -3.225292)
		(end 444.653924 -3.225292)
		(width 0.1143)
		(layer "In9.Cu")
		(net "P3E_CPU0_PE1_PCH_CON_RXP<11>")
	)
	(segment
		(start 449.183506 -2.910332)
		(end 451.393052 -3.928618)
		(width 0.1143)
		(layer "In9.Cu")
		(net "P3E_CPU0_PE1_PCH_CON_RXP<11>")
	)
	(segment
		(start 364.63605 -110.885986)
		(end 364.63605 -117.112034)
		(width 0.1143)
		(layer "In9.Cu")
		(net "P3E_CPU0_PE1_PCH_CON_RXP<11>")
	)
	(segment
		(start 362.700316 -108.950252)
		(end 364.63605 -110.885986)
		(width 0.1143)
		(layer "In9.Cu")
		(net "P3E_CPU0_PE1_PCH_CON_RXP<11>")
	)
	(segment
		(start 438.306972 -2.383282)
		(end 438.658254 -2.032)
		(width 0.1143)
		(layer "In9.Cu")
		(net "P3E_CPU0_PE1_PCH_CON_RXP<11>")
	)
	(segment
		(start 439.075068 -16.470122)
		(end 437.252872 -16.103346)
		(width 0.1143)
		(layer "In9.Cu")
		(net "P3E_CPU0_PE1_PCH_CON_RXP<11>")
	)
	(segment
		(start 369.662456 -38.492684)
		(end 369.351814 -39.94785)
		(width 0.1143)
		(layer "In9.Cu")
		(net "P3E_CPU0_PE1_PCH_CON_RXP<11>")
	)
	(segment
		(start 451.63486 -5.068062)
		(end 451.919594 -6.409944)
		(width 0.1143)
		(layer "In9.Cu")
		(net "P3E_CPU0_PE1_PCH_CON_RXP<11>")
	)
	(segment
		(start 435.667912 -16.425926)
		(end 428.673006 -15.009622)
		(width 0.1143)
		(layer "In9.Cu")
		(net "P3E_CPU0_PE1_PCH_CON_RXP<11>")
	)
	(segment
		(start 418.34308 -13.658596)
		(end 414.506664 -14.425676)
		(width 0.1143)
		(layer "In9.Cu")
		(net "P3E_CPU0_PE1_PCH_CON_RXP<11>")
	)
	(segment
		(start 437.814212 -2.890774)
		(end 438.205626 -2.890774)
		(width 0.1143)
		(layer "In9.Cu")
		(net "P3E_CPU0_PE1_PCH_CON_RXP<11>")
	)
	(segment
		(start 365.221266 -44.223686)
		(end 365.032544 -45.16501)
		(width 0.1143)
		(layer "In9.Cu")
		(net "P3E_CPU0_PE1_PCH_CON_RXP<11>")
	)
	(segment
		(start 369.351814 -39.94785)
		(end 367.892076 -40.921178)
		(width 0.1143)
		(layer "In9.Cu")
		(net "P3E_CPU0_PE1_PCH_CON_RXP<11>")
	)
	(segment
		(start 358.71277 -120.509284)
		(end 358.1908 -121.031254)
		(width 0.1143)
		(layer "In9.Cu")
		(net "P3E_CPU0_PE1_PCH_CON_RXP<11>")
	)
	(segment
		(start 361.2388 -120.509284)
		(end 358.71277 -120.509284)
		(width 0.1143)
		(layer "In9.Cu")
		(net "P3E_CPU0_PE1_PCH_CON_RXP<11>")
	)
	(segment
		(start 439.673492 -16.869156)
		(end 439.075068 -16.470122)
		(width 0.1143)
		(layer "In9.Cu")
		(net "P3E_CPU0_PE1_PCH_CON_RXP<11>")
	)
	(segment
		(start 360.543602 -68.134484)
		(end 360.350308 -69.100954)
		(width 0.1143)
		(layer "In9.Cu")
		(net "P3E_CPU0_PE1_PCH_CON_RXP<11>")
	)
	(segment
		(start 361.111038 -72.6821)
		(end 361.795568 -74.869802)
		(width 0.1143)
		(layer "In9.Cu")
		(net "P3E_CPU0_PE1_PCH_CON_RXP<11>")
	)
	(segment
		(start 391.260584 -16.555974)
		(end 387.198362 -15.692882)
		(width 0.1143)
		(layer "In9.Cu")
		(net "P3E_CPU0_PE1_PCH_CON_RXP<11>")
	)
	(segment
		(start 370.596668 -32.779716)
		(end 369.558316 -37.971984)
		(width 0.1143)
		(layer "In9.Cu")
		(net "P3E_CPU0_PE1_PCH_CON_RXP<11>")
	)
	(segment
		(start 379.905006 -17.241266)
		(end 379.495558 -17.154144)
		(width 0.1143)
		(layer "In9.Cu")
		(net "P3E_CPU0_PE1_PCH_CON_RXP<11>")
	)
	(segment
		(start 438.205626 -2.890774)
		(end 438.306972 -2.789428)
		(width 0.1143)
		(layer "In9.Cu")
		(net "P3E_CPU0_PE1_PCH_CON_RXP<11>")
	)
	(segment
		(start 399.873724 -14.725396)
		(end 391.260584 -16.555974)
		(width 0.1143)
		(layer "In9.Cu")
		(net "P3E_CPU0_PE1_PCH_CON_RXP<11>")
	)
	(segment
		(start 451.789038 -14.199108)
		(end 450.977762 -15.416276)
		(width 0.1143)
		(layer "In9.Cu")
		(net "P3E_CPU0_PE1_PCH_CON_RXP<11>")
	)
	(segment
		(start 424.029886 -14.864334)
		(end 418.34308 -13.658596)
		(width 0.1143)
		(layer "In9.Cu")
		(net "P3E_CPU0_PE1_PCH_CON_RXP<11>")
	)
	(segment
		(start 366.516158 -42.98442)
		(end 366.483646 -43.032934)
		(width 0.1143)
		(layer "In9.Cu")
		(net "P3E_CPU0_PE1_PCH_CON_RXP<11>")
	)
	(segment
		(start 358.445054 -121.793)
		(end 360.167428 -121.793)
		(width 0.1143)
		(layer "In9.Cu")
		(net "P3E_CPU0_PE1_PCH_CON_RXP<11>")
	)
	(segment
		(start 367.892076 -40.921178)
		(end 366.516158 -42.984166)
		(width 0.1143)
		(layer "In9.Cu")
		(net "P3E_CPU0_PE1_PCH_CON_RXP<11>")
	)
	(segment
		(start 428.673006 -15.009622)
		(end 427.5709 -15.230094)
		(width 0.1143)
		(layer "In9.Cu")
		(net "P3E_CPU0_PE1_PCH_CON_RXP<11>")
	)
	(segment
		(start 363.389164 -104.631236)
		(end 362.700316 -105.320084)
		(width 0.1143)
		(layer "In9.Cu")
		(net "P3E_CPU0_PE1_PCH_CON_RXP<11>")
	)
	(segment
		(start 366.516158 -42.984166)
		(end 366.516158 -42.98442)
		(width 0.1143)
		(layer "In9.Cu")
		(net "P3E_CPU0_PE1_PCH_CON_RXP<11>")
	)
	(segment
		(start 448.0052 -16.196564)
		(end 446.762886 -15.948406)
		(width 0.1143)
		(layer "In9.Cu")
		(net "P3E_CPU0_PE1_PCH_CON_RXP<11>")
	)
	(segment
		(start 424.835574 -14.702536)
		(end 424.029886 -14.864334)
		(width 0.1143)
		(layer "In9.Cu")
		(net "P3E_CPU0_PE1_PCH_CON_RXP<11>")
	)
	(segment
		(start 358.1908 -121.538746)
		(end 358.445054 -121.793)
		(width 0.1143)
		(layer "In9.Cu")
		(net "P3E_CPU0_PE1_PCH_CON_RXP<11>")
	)
	(segment
		(start 364.63605 -117.112034)
		(end 361.2388 -120.509284)
		(width 0.1143)
		(layer "In9.Cu")
		(net "P3E_CPU0_PE1_PCH_CON_RXP<11>")
	)
	(segment
		(start 446.139824 -2.910332)
		(end 449.183506 -2.910332)
		(width 0.1143)
		(layer "In9.Cu")
		(net "P3E_CPU0_PE1_PCH_CON_RXP<11>")
	)
	(segment
		(start 363.1438 -47.979076)
		(end 362.4707 -51.342798)
		(width 0.1143)
		(layer "In9.Cu")
		(net "P3E_CPU0_PE1_PCH_CON_RXP<11>")
	)
	(segment
		(start 362.4707 -51.342798)
		(end 363.54258 -56.387238)
		(width 0.1143)
		(layer "In9.Cu")
		(net "P3E_CPU0_PE1_PCH_CON_RXP<11>")
	)
	(segment
		(start 372.902734 -25.02408)
		(end 371.560852 -31.33471)
		(width 0.1143)
		(layer "In9.Cu")
		(net "P3E_CPU0_PE1_PCH_CON_RXP<11>")
	)
	(segment
		(start 365.032544 -45.16501)
		(end 363.1438 -47.979076)
		(width 0.1143)
		(layer "In9.Cu")
		(net "P3E_CPU0_PE1_PCH_CON_RXP<11>")
	)
	(segment
		(start 437.252872 -16.103346)
		(end 435.667912 -16.425926)
		(width 0.1143)
		(layer "In9.Cu")
		(net "P3E_CPU0_PE1_PCH_CON_RXP<11>")
	)
	(segment
		(start 365.641128 -43.594528)
		(end 365.221266 -44.223686)
		(width 0.1143)
		(layer "In9.Cu")
		(net "P3E_CPU0_PE1_PCH_CON_RXP<11>")
	)
	(segment
		(start 451.393052 -3.928618)
		(end 451.63486 -5.068062)
		(width 0.1143)
		(layer "In9.Cu")
		(net "P3E_CPU0_PE1_PCH_CON_RXP<11>")
	)
	(segment
		(start 387.198362 -15.692882)
		(end 379.905006 -17.241266)
		(width 0.1143)
		(layer "In9.Cu")
		(net "P3E_CPU0_PE1_PCH_CON_RXP<11>")
	)
	(segment
		(start 379.495558 -17.154144)
		(end 378.253244 -17.418304)
		(width 0.1143)
		(layer "In9.Cu")
		(net "P3E_CPU0_PE1_PCH_CON_RXP<11>")
	)
	(segment
		(start 440.368182 -2.87909)
		(end 440.672728 -3.08229)
		(width 0.1143)
		(layer "In9.Cu")
		(net "P3E_CPU0_PE1_PCH_CON_RXP<11>")
	)
	(segment
		(start 450.091556 -15.99057)
		(end 449.485004 -15.805912)
		(width 0.1143)
		(layer "In9.Cu")
		(net "P3E_CPU0_PE1_PCH_CON_RXP<11>")
	)
	(segment
		(start 451.336918 -9.154414)
		(end 451.572376 -10.262108)
		(width 0.1143)
		(layer "In9.Cu")
		(net "P3E_CPU0_PE1_PCH_CON_RXP<11>")
	)
	(segment
		(start 369.558316 -37.971984)
		(end 369.662456 -38.492684)
		(width 0.1143)
		(layer "In9.Cu")
		(net "P3E_CPU0_PE1_PCH_CON_RXP<11>")
	)
	(segment
		(start 446.762886 -15.948406)
		(end 444.012574 -16.628872)
		(width 0.1143)
		(layer "In9.Cu")
		(net "P3E_CPU0_PE1_PCH_CON_RXP<11>")
	)
	(segment
		(start 361.795568 -74.869802)
		(end 362.5596 -75.634088)
		(width 0.1143)
		(layer "In9.Cu")
		(net "P3E_CPU0_PE1_PCH_CON_RXP<11>")
	)
	(segment
		(start 444.653924 -3.225292)
		(end 446.139824 -2.910332)
		(width 0.1143)
		(layer "In9.Cu")
		(net "P3E_CPU0_PE1_PCH_CON_RXP<11>")
	)
	(segment
		(start 366.483646 -43.032934)
		(end 365.641128 -43.594528)
		(width 0.1143)
		(layer "In9.Cu")
		(net "P3E_CPU0_PE1_PCH_CON_RXP<11>")
	)
	(segment
		(start 361.994196 -59.561984)
		(end 360.364024 -67.23761)
		(width 0.1143)
		(layer "In9.Cu")
		(net "P3E_CPU0_PE1_PCH_CON_RXP<11>")
	)
	(segment
		(start 358.1908 -121.031254)
		(end 358.1908 -121.538746)
		(width 0.1143)
		(layer "In9.Cu")
		(net "P3E_CPU0_PE1_PCH_CON_RXP<11>")
	)
	(segment
		(start 362.5596 -90.872818)
		(end 363.389164 -94.967806)
		(width 0.1143)
		(layer "In9.Cu")
		(net "P3E_CPU0_PE1_PCH_CON_RXP<11>")
	)
	(segment
		(start 360.364024 -67.23761)
		(end 360.543602 -68.134484)
		(width 0.1143)
		(layer "In9.Cu")
		(net "P3E_CPU0_PE1_PCH_CON_RXP<11>")
	)
	(segment
		(start 371.560852 -31.33471)
		(end 370.596668 -32.779716)
		(width 0.1143)
		(layer "In9.Cu")
		(net "P3E_CPU0_PE1_PCH_CON_RXP<11>")
	)
	(segment
		(start 444.012574 -16.628872)
		(end 440.802014 -17.137634)
		(width 0.1143)
		(layer "In9.Cu")
		(net "P3E_CPU0_PE1_PCH_CON_RXP<11>")
	)
	(segment
		(start 438.658254 -2.032)
		(end 439.521092 -2.032)
		(width 0.1143)
		(layer "In9.Cu")
		(net "P3E_CPU0_PE1_PCH_CON_RXP<11>")
	)
	(segment
		(start 362.5596 -75.634088)
		(end 362.5596 -90.872818)
		(width 0.1143)
		(layer "In9.Cu")
		(net "P3E_CPU0_PE1_PCH_CON_RXP<11>")
	)
	(segment
		(start 414.506664 -14.425676)
		(end 407.890472 -13.02131)
		(width 0.1143)
		(layer "In9.Cu")
		(net "P3E_CPU0_PE1_PCH_CON_RXP<11>")
	)
	(segment
		(start 440.672728 -3.08229)
		(end 441.207398 -3.225292)
		(width 0.1143)
		(layer "In9.Cu")
		(net "P3E_CPU0_PE1_PCH_CON_RXP<11>")
	)
	(segment
		(start 360.167428 -121.793)
		(end 360.258614 -121.701814)
		(width 0.1143)
		(layer "In9.Cu")
		(net "P3E_CPU0_PE1_PCH_CON_RXP<11>")
	)
	(segment
		(start 363.389164 -94.967806)
		(end 363.389164 -104.631236)
		(width 0.1143)
		(layer "In9.Cu")
		(net "P3E_CPU0_PE1_PCH_CON_RXP<11>")
	)
	(segment
		(start 362.700316 -105.320084)
		(end 362.700316 -108.950252)
		(width 0.1143)
		(layer "In9.Cu")
		(net "P3E_CPU0_PE1_PCH_CON_RXP<11>")
	)
	(segment
		(start 377.748038 -17.755108)
		(end 372.902734 -25.02408)
		(width 0.1143)
		(layer "In9.Cu")
		(net "P3E_CPU0_PE1_PCH_CON_RXP<11>")
	)
	(segment
		(start 360.258614 -121.701814)
		(end 360.258614 -121.240042)
		(width 0.1143)
		(layer "In9.Cu")
		(net "P3E_CPU0_PE1_PCH_CON_RXP<11>")
	)
	(segment
		(start 407.890472 -13.02131)
		(end 399.873724 -14.725396)
		(width 0.1143)
		(layer "In9.Cu")
		(net "P3E_CPU0_PE1_PCH_CON_RXP<11>")
	)
	(segment
		(start 427.5709 -15.230094)
		(end 424.835574 -14.702536)
		(width 0.1143)
		(layer "In9.Cu")
		(net "P3E_CPU0_PE1_PCH_CON_RXP<11>")
	)
	(segment
		(start 450.977762 -15.416276)
		(end 450.585332 -15.8115)
		(width 0.1143)
		(layer "In9.Cu")
		(net "P3E_CPU0_PE1_PCH_CON_RXP<11>")
	)
	(segment
		(start 360.350308 -69.100954)
		(end 361.111038 -72.6821)
		(width 0.1143)
		(layer "In9.Cu")
		(net "P3E_CPU0_PE1_PCH_CON_RXP<11>")
	)
	(segment
		(start 378.253244 -17.418304)
		(end 377.748038 -17.755108)
		(width 0.1143)
		(layer "In9.Cu")
		(net "P3E_CPU0_PE1_PCH_CON_RXP<11>")
	)
	(segment
		(start 451.572376 -10.262108)
		(end 451.27164 -11.765788)
		(width 0.1143)
		(layer "In9.Cu")
		(net "P3E_CPU0_PE1_PCH_CON_RXP<11>")
	)
	(segment
		(start 450.585332 -15.8115)
		(end 450.091556 -15.99057)
		(width 0.1143)
		(layer "In9.Cu")
		(net "P3E_CPU0_PE1_PCH_CON_RXP<11>")
	)
	(segment
		(start 451.919594 -6.409944)
		(end 451.336918 -9.154414)
		(width 0.1143)
		(layer "In9.Cu")
		(net "P3E_CPU0_PE1_PCH_CON_RXP<11>")
	)
	(segment
		(start 439.521092 -2.032)
		(end 440.368182 -2.87909)
		(width 0.1143)
		(layer "In9.Cu")
		(net "P3E_CPU0_PE1_PCH_CON_RXP<11>")
	)
	(segment
		(start 451.27164 -11.765788)
		(end 451.789038 -14.199108)
		(width 0.1143)
		(layer "In9.Cu")
		(net "P3E_CPU0_PE1_PCH_CON_RXP<11>")
	)
	(segment
		(start 449.485004 -15.805912)
		(end 448.0052 -16.196564)
		(width 0.1143)
		(layer "In9.Cu")
		(net "P3E_CPU0_PE1_PCH_CON_RXP<11>")
	)
	(segment
		(start 440.802014 -17.137634)
		(end 439.673492 -16.869156)
		(width 0.1143)
		(layer "In9.Cu")
		(net "P3E_CPU0_PE1_PCH_CON_RXP<11>")
	)
	(segment
		(start 438.306972 -2.789428)
		(end 438.306972 -2.383282)
		(width 0.1143)
		(layer "In9.Cu")
		(net "P3E_CPU0_PE1_PCH_CON_RXP<11>")
	)
	(segment
		(start 435.675786 -3.758184)
		(end 435.675786 -4.386072)
		(width 0.1143)
		(layer "F.Cu")
		(net "P3E_CPU0_PE1_PCH_CON_RXP<10>")
	)
	(segment
		(start 435.933088 -2.95402)
		(end 435.933088 -3.500882)
		(width 0.1143)
		(layer "F.Cu")
		(net "P3E_CPU0_PE1_PCH_CON_RXP<10>")
	)
	(segment
		(start 435.818788 -2.83972)
		(end 435.933088 -2.95402)
		(width 0.1143)
		(layer "F.Cu")
		(net "P3E_CPU0_PE1_PCH_CON_RXP<10>")
	)
	(segment
		(start 435.431438 -2.83972)
		(end 435.818788 -2.83972)
		(width 0.1143)
		(layer "F.Cu")
		(net "P3E_CPU0_PE1_PCH_CON_RXP<10>")
	)
	(segment
		(start 435.933088 -3.500882)
		(end 435.675786 -3.758184)
		(width 0.1143)
		(layer "F.Cu")
		(net "P3E_CPU0_PE1_PCH_CON_RXP<10>")
	)
	(via
		(at 435.431438 -2.83972)
		(size 0.508)
		(drill 0.254)
		(layers "F.Cu" "B.Cu")
		(net "P3E_CPU0_PE1_PCH_CON_RXP<10>")
	)
	(via
		(at 360.258614 -125.583442)
		(size 0.508)
		(drill 0.254)
		(layers "F.Cu" "B.Cu")
		(net "P3E_CPU0_PE1_PCH_CON_RXP<10>")
	)
	(segment
		(start 360.284014 -125.558042)
		(end 360.258614 -125.583442)
		(width 0.1143)
		(layer "B.Cu")
		(net "P3E_CPU0_PE1_PCH_CON_RXP<10>")
	)
	(segment
		(start 360.893614 -125.558042)
		(end 360.284014 -125.558042)
		(width 0.1143)
		(layer "B.Cu")
		(net "P3E_CPU0_PE1_PCH_CON_RXP<10>")
	)
	(segment
		(start 452.228966 -3.998214)
		(end 451.420484 -2.785618)
		(width 0.1143)
		(layer "In9.Cu")
		(net "P3E_CPU0_PE1_PCH_CON_RXP<10>")
	)
	(segment
		(start 362.33862 -74.46899)
		(end 361.766612 -72.641714)
		(width 0.1143)
		(layer "In9.Cu")
		(net "P3E_CPU0_PE1_PCH_CON_RXP<10>")
	)
	(segment
		(start 363.1946 -89.98966)
		(end 363.1946 -75.325986)
		(width 0.1143)
		(layer "In9.Cu")
		(net "P3E_CPU0_PE1_PCH_CON_RXP<10>")
	)
	(segment
		(start 360.258614 -125.583442)
		(end 360.76001 -125.082046)
		(width 0.1143)
		(layer "In9.Cu")
		(net "P3E_CPU0_PE1_PCH_CON_RXP<10>")
	)
	(segment
		(start 450.864732 -16.50365)
		(end 451.506336 -15.860522)
		(width 0.1143)
		(layer "In9.Cu")
		(net "P3E_CPU0_PE1_PCH_CON_RXP<10>")
	)
	(segment
		(start 432.308254 -16.411956)
		(end 432.51247 -16.547084)
		(width 0.1143)
		(layer "In9.Cu")
		(net "P3E_CPU0_PE1_PCH_CON_RXP<10>")
	)
	(segment
		(start 414.490408 -15.092426)
		(end 418.286438 -14.332458)
		(width 0.1143)
		(layer "In9.Cu")
		(net "P3E_CPU0_PE1_PCH_CON_RXP<10>")
	)
	(segment
		(start 365.464344 -110.811056)
		(end 363.335316 -108.682028)
		(width 0.1143)
		(layer "In9.Cu")
		(net "P3E_CPU0_PE1_PCH_CON_RXP<10>")
	)
	(segment
		(start 440.816492 -17.885156)
		(end 443.017656 -17.58569)
		(width 0.1143)
		(layer "In9.Cu")
		(net "P3E_CPU0_PE1_PCH_CON_RXP<10>")
	)
	(segment
		(start 452.47941 -14.330934)
		(end 451.994524 -12.0523)
		(width 0.1143)
		(layer "In9.Cu")
		(net "P3E_CPU0_PE1_PCH_CON_RXP<10>")
	)
	(segment
		(start 451.506336 -15.860522)
		(end 452.47941 -14.330934)
		(width 0.1143)
		(layer "In9.Cu")
		(net "P3E_CPU0_PE1_PCH_CON_RXP<10>")
	)
	(segment
		(start 424.142916 -15.575788)
		(end 425.052744 -15.393162)
		(width 0.1143)
		(layer "In9.Cu")
		(net "P3E_CPU0_PE1_PCH_CON_RXP<10>")
	)
	(segment
		(start 364.534704 -48.685958)
		(end 367.171732 -46.50105)
		(width 0.1143)
		(layer "In9.Cu")
		(net "P3E_CPU0_PE1_PCH_CON_RXP<10>")
	)
	(segment
		(start 363.335316 -105.624884)
		(end 364.036864 -104.923336)
		(width 0.1143)
		(layer "In9.Cu")
		(net "P3E_CPU0_PE1_PCH_CON_RXP<10>")
	)
	(segment
		(start 361.766612 -72.641714)
		(end 361.028488 -69.165978)
		(width 0.1143)
		(layer "In9.Cu")
		(net "P3E_CPU0_PE1_PCH_CON_RXP<10>")
	)
	(segment
		(start 450.239892 -16.72844)
		(end 450.240654 -16.730218)
		(width 0.1143)
		(layer "In9.Cu")
		(net "P3E_CPU0_PE1_PCH_CON_RXP<10>")
	)
	(segment
		(start 360.76001 -125.082046)
		(end 361.128564 -125.082046)
		(width 0.1143)
		(layer "In9.Cu")
		(net "P3E_CPU0_PE1_PCH_CON_RXP<10>")
	)
	(segment
		(start 451.420484 -2.785618)
		(end 448.184524 -1.367536)
		(width 0.1143)
		(layer "In9.Cu")
		(net "P3E_CPU0_PE1_PCH_CON_RXP<10>")
	)
	(segment
		(start 364.22076 -56.47309)
		(end 363.322616 -52.241196)
		(width 0.1143)
		(layer "In9.Cu")
		(net "P3E_CPU0_PE1_PCH_CON_RXP<10>")
	)
	(segment
		(start 391.256012 -17.207484)
		(end 407.846276 -13.681456)
		(width 0.1143)
		(layer "In9.Cu")
		(net "P3E_CPU0_PE1_PCH_CON_RXP<10>")
	)
	(segment
		(start 378.512832 -18.057876)
		(end 379.500638 -17.848072)
		(width 0.1143)
		(layer "In9.Cu")
		(net "P3E_CPU0_PE1_PCH_CON_RXP<10>")
	)
	(segment
		(start 452.948548 -5.776214)
		(end 452.442072 -5.016754)
		(width 0.1143)
		(layer "In9.Cu")
		(net "P3E_CPU0_PE1_PCH_CON_RXP<10>")
	)
	(segment
		(start 452.442072 -5.016754)
		(end 452.228966 -3.998214)
		(width 0.1143)
		(layer "In9.Cu")
		(net "P3E_CPU0_PE1_PCH_CON_RXP<10>")
	)
	(segment
		(start 363.322616 -52.241196)
		(end 364.534704 -48.685958)
		(width 0.1143)
		(layer "In9.Cu")
		(net "P3E_CPU0_PE1_PCH_CON_RXP<10>")
	)
	(segment
		(start 361.214162 -68.236846)
		(end 361.022646 -67.279774)
		(width 0.1143)
		(layer "In9.Cu")
		(net "P3E_CPU0_PE1_PCH_CON_RXP<10>")
	)
	(segment
		(start 448.184524 -1.367536)
		(end 437.124094 -1.367536)
		(width 0.1143)
		(layer "In9.Cu")
		(net "P3E_CPU0_PE1_PCH_CON_RXP<10>")
	)
	(segment
		(start 379.500638 -17.848072)
		(end 379.845316 -17.921224)
		(width 0.1143)
		(layer "In9.Cu")
		(net "P3E_CPU0_PE1_PCH_CON_RXP<10>")
	)
	(segment
		(start 371.268244 -32.951928)
		(end 372.190264 -31.570676)
		(width 0.1143)
		(layer "In9.Cu")
		(net "P3E_CPU0_PE1_PCH_CON_RXP<10>")
	)
	(segment
		(start 372.190264 -31.570676)
		(end 373.52732 -25.281636)
		(width 0.1143)
		(layer "In9.Cu")
		(net "P3E_CPU0_PE1_PCH_CON_RXP<10>")
	)
	(segment
		(start 435.9021 -2.694686)
		(end 435.757066 -2.83972)
		(width 0.1143)
		(layer "In9.Cu")
		(net "P3E_CPU0_PE1_PCH_CON_RXP<10>")
	)
	(segment
		(start 363.335316 -108.682028)
		(end 363.335316 -105.624884)
		(width 0.1143)
		(layer "In9.Cu")
		(net "P3E_CPU0_PE1_PCH_CON_RXP<10>")
	)
	(segment
		(start 367.322354 -45.748956)
		(end 367.095024 -44.611798)
		(width 0.1143)
		(layer "In9.Cu")
		(net "P3E_CPU0_PE1_PCH_CON_RXP<10>")
	)
	(segment
		(start 361.725464 -121.444258)
		(end 365.464344 -117.705378)
		(width 0.1143)
		(layer "In9.Cu")
		(net "P3E_CPU0_PE1_PCH_CON_RXP<10>")
	)
	(segment
		(start 435.757066 -2.83972)
		(end 435.431438 -2.83972)
		(width 0.1143)
		(layer "In9.Cu")
		(net "P3E_CPU0_PE1_PCH_CON_RXP<10>")
	)
	(segment
		(start 445.402462 -18.06194)
		(end 447.980816 -17.542764)
		(width 0.1143)
		(layer "In9.Cu")
		(net "P3E_CPU0_PE1_PCH_CON_RXP<10>")
	)
	(segment
		(start 368.243358 -41.571418)
		(end 369.99545 -40.403018)
		(width 0.1143)
		(layer "In9.Cu")
		(net "P3E_CPU0_PE1_PCH_CON_RXP<10>")
	)
	(segment
		(start 418.286438 -14.332458)
		(end 424.142916 -15.575788)
		(width 0.1143)
		(layer "In9.Cu")
		(net "P3E_CPU0_PE1_PCH_CON_RXP<10>")
	)
	(segment
		(start 362.339128 -74.470514)
		(end 362.33862 -74.46899)
		(width 0.1143)
		(layer "In9.Cu")
		(net "P3E_CPU0_PE1_PCH_CON_RXP<10>")
	)
	(segment
		(start 438.772046 -17.340326)
		(end 440.816492 -17.885156)
		(width 0.1143)
		(layer "In9.Cu")
		(net "P3E_CPU0_PE1_PCH_CON_RXP<10>")
	)
	(segment
		(start 425.052744 -15.393162)
		(end 428.019972 -15.98549)
		(width 0.1143)
		(layer "In9.Cu")
		(net "P3E_CPU0_PE1_PCH_CON_RXP<10>")
	)
	(segment
		(start 387.23062 -16.353028)
		(end 391.256012 -17.207484)
		(width 0.1143)
		(layer "In9.Cu")
		(net "P3E_CPU0_PE1_PCH_CON_RXP<10>")
	)
	(segment
		(start 436.109364 -17.279112)
		(end 437.759602 -16.943578)
		(width 0.1143)
		(layer "In9.Cu")
		(net "P3E_CPU0_PE1_PCH_CON_RXP<10>")
	)
	(segment
		(start 379.845316 -17.921224)
		(end 387.23062 -16.353028)
		(width 0.1143)
		(layer "In9.Cu")
		(net "P3E_CPU0_PE1_PCH_CON_RXP<10>")
	)
	(segment
		(start 437.759602 -16.943578)
		(end 437.815736 -16.943578)
		(width 0.1143)
		(layer "In9.Cu")
		(net "P3E_CPU0_PE1_PCH_CON_RXP<10>")
	)
	(segment
		(start 453.772778 -6.600952)
		(end 453.443594 -6.106922)
		(width 0.1143)
		(layer "In9.Cu")
		(net "P3E_CPU0_PE1_PCH_CON_RXP<10>")
	)
	(segment
		(start 453.443594 -6.106922)
		(end 452.948548 -5.776214)
		(width 0.1143)
		(layer "In9.Cu")
		(net "P3E_CPU0_PE1_PCH_CON_RXP<10>")
	)
	(segment
		(start 438.345834 -17.0561)
		(end 438.772046 -17.340326)
		(width 0.1143)
		(layer "In9.Cu")
		(net "P3E_CPU0_PE1_PCH_CON_RXP<10>")
	)
	(segment
		(start 367.292636 -45.8978)
		(end 367.322354 -45.748956)
		(width 0.1143)
		(layer "In9.Cu")
		(net "P3E_CPU0_PE1_PCH_CON_RXP<10>")
	)
	(segment
		(start 361.028488 -69.165978)
		(end 361.214162 -68.236846)
		(width 0.1143)
		(layer "In9.Cu")
		(net "P3E_CPU0_PE1_PCH_CON_RXP<10>")
	)
	(segment
		(start 453.071484 -9.899396)
		(end 453.772778 -6.600952)
		(width 0.1143)
		(layer "In9.Cu")
		(net "P3E_CPU0_PE1_PCH_CON_RXP<10>")
	)
	(segment
		(start 437.124094 -1.367536)
		(end 436.369968 -1.527556)
		(width 0.1143)
		(layer "In9.Cu")
		(net "P3E_CPU0_PE1_PCH_CON_RXP<10>")
	)
	(segment
		(start 370.381784 -38.475666)
		(end 370.272818 -37.93109)
		(width 0.1143)
		(layer "In9.Cu")
		(net "P3E_CPU0_PE1_PCH_CON_RXP<10>")
	)
	(segment
		(start 429.124618 -15.764002)
		(end 432.308254 -16.411956)
		(width 0.1143)
		(layer "In9.Cu")
		(net "P3E_CPU0_PE1_PCH_CON_RXP<10>")
	)
	(segment
		(start 365.464344 -117.705378)
		(end 365.464344 -110.811056)
		(width 0.1143)
		(layer "In9.Cu")
		(net "P3E_CPU0_PE1_PCH_CON_RXP<10>")
	)
	(segment
		(start 363.1946 -75.325986)
		(end 362.339128 -74.470514)
		(width 0.1143)
		(layer "In9.Cu")
		(net "P3E_CPU0_PE1_PCH_CON_RXP<10>")
	)
	(segment
		(start 449.366894 -16.494252)
		(end 450.239892 -16.72844)
		(width 0.1143)
		(layer "In9.Cu")
		(net "P3E_CPU0_PE1_PCH_CON_RXP<10>")
	)
	(segment
		(start 435.9021 -2.10439)
		(end 435.9021 -2.694686)
		(width 0.1143)
		(layer "In9.Cu")
		(net "P3E_CPU0_PE1_PCH_CON_RXP<10>")
	)
	(segment
		(start 370.272818 -37.93109)
		(end 371.268244 -32.951928)
		(width 0.1143)
		(layer "In9.Cu")
		(net "P3E_CPU0_PE1_PCH_CON_RXP<10>")
	)
	(segment
		(start 364.036864 -104.923336)
		(end 364.036864 -94.160848)
		(width 0.1143)
		(layer "In9.Cu")
		(net "P3E_CPU0_PE1_PCH_CON_RXP<10>")
	)
	(segment
		(start 450.240654 -16.730218)
		(end 450.864732 -16.50365)
		(width 0.1143)
		(layer "In9.Cu")
		(net "P3E_CPU0_PE1_PCH_CON_RXP<10>")
	)
	(segment
		(start 451.994524 -12.0523)
		(end 452.164196 -11.254486)
		(width 0.1143)
		(layer "In9.Cu")
		(net "P3E_CPU0_PE1_PCH_CON_RXP<10>")
	)
	(segment
		(start 428.019972 -15.98549)
		(end 429.124618 -15.764002)
		(width 0.1143)
		(layer "In9.Cu")
		(net "P3E_CPU0_PE1_PCH_CON_RXP<10>")
	)
	(segment
		(start 447.980816 -17.542764)
		(end 448.613022 -16.693642)
		(width 0.1143)
		(layer "In9.Cu")
		(net "P3E_CPU0_PE1_PCH_CON_RXP<10>")
	)
	(segment
		(start 364.036864 -94.160848)
		(end 363.1946 -89.98966)
		(width 0.1143)
		(layer "In9.Cu")
		(net "P3E_CPU0_PE1_PCH_CON_RXP<10>")
	)
	(segment
		(start 432.51247 -16.547084)
		(end 436.109364 -17.279112)
		(width 0.1143)
		(layer "In9.Cu")
		(net "P3E_CPU0_PE1_PCH_CON_RXP<10>")
	)
	(segment
		(start 361.128564 -125.082046)
		(end 361.725464 -124.485146)
		(width 0.1143)
		(layer "In9.Cu")
		(net "P3E_CPU0_PE1_PCH_CON_RXP<10>")
	)
	(segment
		(start 373.52732 -25.281636)
		(end 378.205238 -18.262854)
		(width 0.1143)
		(layer "In9.Cu")
		(net "P3E_CPU0_PE1_PCH_CON_RXP<10>")
	)
	(segment
		(start 452.164196 -11.254486)
		(end 453.071484 -9.899396)
		(width 0.1143)
		(layer "In9.Cu")
		(net "P3E_CPU0_PE1_PCH_CON_RXP<10>")
	)
	(segment
		(start 443.017656 -17.58569)
		(end 445.402462 -18.06194)
		(width 0.1143)
		(layer "In9.Cu")
		(net "P3E_CPU0_PE1_PCH_CON_RXP<10>")
	)
	(segment
		(start 436.369968 -1.527556)
		(end 435.9021 -2.10439)
		(width 0.1143)
		(layer "In9.Cu")
		(net "P3E_CPU0_PE1_PCH_CON_RXP<10>")
	)
	(segment
		(start 367.47196 -42.72788)
		(end 368.243358 -41.571418)
		(width 0.1143)
		(layer "In9.Cu")
		(net "P3E_CPU0_PE1_PCH_CON_RXP<10>")
	)
	(segment
		(start 367.095024 -44.611798)
		(end 367.47196 -42.72788)
		(width 0.1143)
		(layer "In9.Cu")
		(net "P3E_CPU0_PE1_PCH_CON_RXP<10>")
	)
	(segment
		(start 448.613022 -16.693642)
		(end 449.366894 -16.494252)
		(width 0.1143)
		(layer "In9.Cu")
		(net "P3E_CPU0_PE1_PCH_CON_RXP<10>")
	)
	(segment
		(start 362.621068 -59.75223)
		(end 364.22076 -56.47309)
		(width 0.1143)
		(layer "In9.Cu")
		(net "P3E_CPU0_PE1_PCH_CON_RXP<10>")
	)
	(segment
		(start 361.022646 -67.279774)
		(end 362.621068 -59.75223)
		(width 0.1143)
		(layer "In9.Cu")
		(net "P3E_CPU0_PE1_PCH_CON_RXP<10>")
	)
	(segment
		(start 378.205238 -18.262854)
		(end 378.512832 -18.057876)
		(width 0.1143)
		(layer "In9.Cu")
		(net "P3E_CPU0_PE1_PCH_CON_RXP<10>")
	)
	(segment
		(start 361.725464 -124.485146)
		(end 361.725464 -121.444258)
		(width 0.1143)
		(layer "In9.Cu")
		(net "P3E_CPU0_PE1_PCH_CON_RXP<10>")
	)
	(segment
		(start 407.846276 -13.681456)
		(end 414.490408 -15.092426)
		(width 0.1143)
		(layer "In9.Cu")
		(net "P3E_CPU0_PE1_PCH_CON_RXP<10>")
	)
	(segment
		(start 437.815736 -16.943578)
		(end 438.345834 -17.0561)
		(width 0.1143)
		(layer "In9.Cu")
		(net "P3E_CPU0_PE1_PCH_CON_RXP<10>")
	)
	(segment
		(start 367.171732 -46.50105)
		(end 367.292636 -45.8978)
		(width 0.1143)
		(layer "In9.Cu")
		(net "P3E_CPU0_PE1_PCH_CON_RXP<10>")
	)
	(segment
		(start 369.99545 -40.403018)
		(end 370.381784 -38.475666)
		(width 0.1143)
		(layer "In9.Cu")
		(net "P3E_CPU0_PE1_PCH_CON_RXP<10>")
	)
	(segment
		(start 434.075586 -3.758184)
		(end 434.075586 -4.386072)
		(width 0.1143)
		(layer "F.Cu")
		(net "P3E_CPU0_PE1_PCH_CON_RXN<9>")
	)
	(segment
		(start 434.281834 -2.860294)
		(end 433.952904 -2.860294)
		(width 0.1143)
		(layer "F.Cu")
		(net "P3E_CPU0_PE1_PCH_CON_RXN<9>")
	)
	(segment
		(start 433.952904 -2.860294)
		(end 433.772818 -3.04038)
		(width 0.1143)
		(layer "F.Cu")
		(net "P3E_CPU0_PE1_PCH_CON_RXN<9>")
	)
	(segment
		(start 433.772818 -3.455416)
		(end 434.075586 -3.758184)
		(width 0.1143)
		(layer "F.Cu")
		(net "P3E_CPU0_PE1_PCH_CON_RXN<9>")
	)
	(segment
		(start 433.772818 -3.04038)
		(end 433.772818 -3.455416)
		(width 0.1143)
		(layer "F.Cu")
		(net "P3E_CPU0_PE1_PCH_CON_RXN<9>")
	)
	(via
		(at 366.278414 -125.583442)
		(size 0.508)
		(drill 0.254)
		(layers "F.Cu" "B.Cu")
		(net "P3E_CPU0_PE1_PCH_CON_RXN<9>")
	)
	(via
		(at 434.281834 -2.860294)
		(size 0.508)
		(drill 0.254)
		(layers "F.Cu" "B.Cu")
		(net "P3E_CPU0_PE1_PCH_CON_RXN<9>")
	)
	(segment
		(start 366.354614 -125.507242)
		(end 366.278414 -125.583442)
		(width 0.1143)
		(layer "B.Cu")
		(net "P3E_CPU0_PE1_PCH_CON_RXN<9>")
	)
	(segment
		(start 366.938814 -125.507242)
		(end 366.354614 -125.507242)
		(width 0.1143)
		(layer "B.Cu")
		(net "P3E_CPU0_PE1_PCH_CON_RXN<9>")
	)
	(segment
		(start 362.01731 -72.169782)
		(end 361.404408 -69.285358)
		(width 0.1143)
		(layer "In9.Cu")
		(net "P3E_CPU0_PE1_PCH_CON_RXN<9>")
	)
	(segment
		(start 361.60329 -68.294504)
		(end 361.391708 -67.236594)
		(width 0.1143)
		(layer "In9.Cu")
		(net "P3E_CPU0_PE1_PCH_CON_RXN<9>")
	)
	(segment
		(start 407.809446 -14.040358)
		(end 414.637474 -15.487396)
		(width 0.1143)
		(layer "In9.Cu")
		(net "P3E_CPU0_PE1_PCH_CON_RXN<9>")
	)
	(segment
		(start 363.5375 -89.618058)
		(end 363.5375 -75.127358)
		(width 0.1143)
		(layer "In9.Cu")
		(net "P3E_CPU0_PE1_PCH_CON_RXN<9>")
	)
	(segment
		(start 378.862844 -19.286728)
		(end 380.472696 -18.160238)
		(width 0.1143)
		(layer "In9.Cu")
		(net "P3E_CPU0_PE1_PCH_CON_RXN<9>")
	)
	(segment
		(start 369.415822 -45.235114)
		(end 370.769134 -38.473634)
		(width 0.1143)
		(layer "In9.Cu")
		(net "P3E_CPU0_PE1_PCH_CON_RXN<9>")
	)
	(segment
		(start 444.013336 -19.145758)
		(end 444.349378 -19.214084)
		(width 0.1143)
		(layer "In9.Cu")
		(net "P3E_CPU0_PE1_PCH_CON_RXN<9>")
	)
	(segment
		(start 363.10062 -124.34443)
		(end 363.10062 -120.81764)
		(width 0.1143)
		(layer "In9.Cu")
		(net "P3E_CPU0_PE1_PCH_CON_RXN<9>")
	)
	(segment
		(start 452.80072 -4.174744)
		(end 451.676008 -2.487676)
		(width 0.1143)
		(layer "In9.Cu")
		(net "P3E_CPU0_PE1_PCH_CON_RXN<9>")
	)
	(segment
		(start 451.745858 -16.189198)
		(end 452.854822 -14.446504)
		(width 0.1143)
		(layer "In9.Cu")
		(net "P3E_CPU0_PE1_PCH_CON_RXN<9>")
	)
	(segment
		(start 364.60557 -56.53913)
		(end 363.72927 -52.409598)
		(width 0.1143)
		(layer "In9.Cu")
		(net "P3E_CPU0_PE1_PCH_CON_RXN<9>")
	)
	(segment
		(start 445.345058 -19.416522)
		(end 445.345566 -19.416776)
		(width 0.1143)
		(layer "In9.Cu")
		(net "P3E_CPU0_PE1_PCH_CON_RXN<9>")
	)
	(segment
		(start 361.404408 -69.285358)
		(end 361.60329 -68.294504)
		(width 0.1143)
		(layer "In9.Cu")
		(net "P3E_CPU0_PE1_PCH_CON_RXN<9>")
	)
	(segment
		(start 361.391708 -67.236594)
		(end 362.937044 -59.960256)
		(width 0.1143)
		(layer "In9.Cu")
		(net "P3E_CPU0_PE1_PCH_CON_RXN<9>")
	)
	(segment
		(start 444.880238 -19.153378)
		(end 445.009016 -19.348196)
		(width 0.1143)
		(layer "In9.Cu")
		(net "P3E_CPU0_PE1_PCH_CON_RXN<9>")
	)
	(segment
		(start 448.204336 -0.965708)
		(end 435.609492 -0.965708)
		(width 0.1143)
		(layer "In9.Cu")
		(net "P3E_CPU0_PE1_PCH_CON_RXN<9>")
	)
	(segment
		(start 448.029838 -18.70964)
		(end 448.224148 -18.838926)
		(width 0.1143)
		(layer "In9.Cu")
		(net "P3E_CPU0_PE1_PCH_CON_RXN<9>")
	)
	(segment
		(start 447.693542 -18.77695)
		(end 448.029838 -18.70964)
		(width 0.1143)
		(layer "In9.Cu")
		(net "P3E_CPU0_PE1_PCH_CON_RXN<9>")
	)
	(segment
		(start 443.884558 -18.95094)
		(end 444.013336 -19.145758)
		(width 0.1143)
		(layer "In9.Cu")
		(net "P3E_CPU0_PE1_PCH_CON_RXN<9>")
	)
	(segment
		(start 452.575422 -11.394186)
		(end 453.452484 -10.078212)
		(width 0.1143)
		(layer "In9.Cu")
		(net "P3E_CPU0_PE1_PCH_CON_RXN<9>")
	)
	(segment
		(start 451.02653 -17.092422)
		(end 451.348348 -16.586962)
		(width 0.1143)
		(layer "In9.Cu")
		(net "P3E_CPU0_PE1_PCH_CON_RXN<9>")
	)
	(segment
		(start 366.115092 -125.095)
		(end 363.85119 -125.095)
		(width 0.1143)
		(layer "In9.Cu")
		(net "P3E_CPU0_PE1_PCH_CON_RXN<9>")
	)
	(segment
		(start 363.5375 -75.127358)
		(end 362.67517 -74.265028)
		(width 0.1143)
		(layer "In9.Cu")
		(net "P3E_CPU0_PE1_PCH_CON_RXN<9>")
	)
	(segment
		(start 363.678216 -108.53674)
		(end 363.678216 -105.808526)
		(width 0.1143)
		(layer "In9.Cu")
		(net "P3E_CPU0_PE1_PCH_CON_RXN<9>")
	)
	(segment
		(start 435.101492 -1.130808)
		(end 434.936392 -0.965708)
		(width 0.1143)
		(layer "In9.Cu")
		(net "P3E_CPU0_PE1_PCH_CON_RXN<9>")
	)
	(segment
		(start 445.345566 -19.416776)
		(end 447.564256 -18.971514)
		(width 0.1143)
		(layer "In9.Cu")
		(net "P3E_CPU0_PE1_PCH_CON_RXN<9>")
	)
	(segment
		(start 443.548516 -18.882614)
		(end 443.884558 -18.95094)
		(width 0.1143)
		(layer "In9.Cu")
		(net "P3E_CPU0_PE1_PCH_CON_RXN<9>")
	)
	(segment
		(start 365.821214 -118.097046)
		(end 365.821214 -110.679738)
		(width 0.1143)
		(layer "In9.Cu")
		(net "P3E_CPU0_PE1_PCH_CON_RXN<9>")
	)
	(segment
		(start 436.309262 -18.259552)
		(end 437.197754 -18.437606)
		(width 0.1143)
		(layer "In9.Cu")
		(net "P3E_CPU0_PE1_PCH_CON_RXN<9>")
	)
	(segment
		(start 433.913534 -2.860294)
		(end 434.281834 -2.860294)
		(width 0.1143)
		(layer "In9.Cu")
		(net "P3E_CPU0_PE1_PCH_CON_RXN<9>")
	)
	(segment
		(start 434.593492 -0.965708)
		(end 433.780692 -1.778508)
		(width 0.1143)
		(layer "In9.Cu")
		(net "P3E_CPU0_PE1_PCH_CON_RXN<9>")
	)
	(segment
		(start 443.353698 -19.011646)
		(end 443.548516 -18.882614)
		(width 0.1143)
		(layer "In9.Cu")
		(net "P3E_CPU0_PE1_PCH_CON_RXN<9>")
	)
	(segment
		(start 365.821214 -110.679738)
		(end 363.678216 -108.53674)
		(width 0.1143)
		(layer "In9.Cu")
		(net "P3E_CPU0_PE1_PCH_CON_RXN<9>")
	)
	(segment
		(start 364.901226 -48.976026)
		(end 369.415822 -45.235114)
		(width 0.1143)
		(layer "In9.Cu")
		(net "P3E_CPU0_PE1_PCH_CON_RXN<9>")
	)
	(segment
		(start 454.54443 -5.657088)
		(end 454.47077 -5.288534)
		(width 0.1143)
		(layer "In9.Cu")
		(net "P3E_CPU0_PE1_PCH_CON_RXN<9>")
	)
	(segment
		(start 447.564256 -18.971514)
		(end 447.693542 -18.77695)
		(width 0.1143)
		(layer "In9.Cu")
		(net "P3E_CPU0_PE1_PCH_CON_RXN<9>")
	)
	(segment
		(start 444.349378 -19.214084)
		(end 444.544196 -19.085052)
		(width 0.1143)
		(layer "In9.Cu")
		(net "P3E_CPU0_PE1_PCH_CON_RXN<9>")
	)
	(segment
		(start 418.01161 -14.774926)
		(end 428.557944 -16.987266)
		(width 0.1143)
		(layer "In9.Cu")
		(net "P3E_CPU0_PE1_PCH_CON_RXN<9>")
	)
	(segment
		(start 371.609366 -33.237678)
		(end 372.000272 -32.650938)
		(width 0.1143)
		(layer "In9.Cu")
		(net "P3E_CPU0_PE1_PCH_CON_RXN<9>")
	)
	(segment
		(start 450.481192 -17.949672)
		(end 450.665342 -17.660366)
		(width 0.1143)
		(layer "In9.Cu")
		(net "P3E_CPU0_PE1_PCH_CON_RXN<9>")
	)
	(segment
		(start 445.009016 -19.348196)
		(end 445.345058 -19.416522)
		(width 0.1143)
		(layer "In9.Cu")
		(net "P3E_CPU0_PE1_PCH_CON_RXN<9>")
	)
	(segment
		(start 370.665502 -37.955728)
		(end 371.609366 -33.237678)
		(width 0.1143)
		(layer "In9.Cu")
		(net "P3E_CPU0_PE1_PCH_CON_RXN<9>")
	)
	(segment
		(start 432.497992 -16.969994)
		(end 434.5686 -17.391126)
		(width 0.1143)
		(layer "In9.Cu")
		(net "P3E_CPU0_PE1_PCH_CON_RXN<9>")
	)
	(segment
		(start 362.937044 -59.960256)
		(end 364.60557 -56.53913)
		(width 0.1143)
		(layer "In9.Cu")
		(net "P3E_CPU0_PE1_PCH_CON_RXN<9>")
	)
	(segment
		(start 450.798692 -17.143222)
		(end 451.02653 -17.092422)
		(width 0.1143)
		(layer "In9.Cu")
		(net "P3E_CPU0_PE1_PCH_CON_RXN<9>")
	)
	(segment
		(start 363.10062 -120.81764)
		(end 365.821214 -118.097046)
		(width 0.1143)
		(layer "In9.Cu")
		(net "P3E_CPU0_PE1_PCH_CON_RXN<9>")
	)
	(segment
		(start 364.405164 -93.898212)
		(end 363.5375 -89.618058)
		(width 0.1143)
		(layer "In9.Cu")
		(net "P3E_CPU0_PE1_PCH_CON_RXN<9>")
	)
	(segment
		(start 444.544196 -19.085052)
		(end 444.880238 -19.153378)
		(width 0.1143)
		(layer "In9.Cu")
		(net "P3E_CPU0_PE1_PCH_CON_RXN<9>")
	)
	(segment
		(start 454.229216 -6.424676)
		(end 454.46061 -6.077458)
		(width 0.1143)
		(layer "In9.Cu")
		(net "P3E_CPU0_PE1_PCH_CON_RXN<9>")
	)
	(segment
		(start 431.301144 -17.214088)
		(end 432.497992 -16.969994)
		(width 0.1143)
		(layer "In9.Cu")
		(net "P3E_CPU0_PE1_PCH_CON_RXN<9>")
	)
	(segment
		(start 363.85119 -125.095)
		(end 363.10062 -124.34443)
		(width 0.1143)
		(layer "In9.Cu")
		(net "P3E_CPU0_PE1_PCH_CON_RXN<9>")
	)
	(segment
		(start 380.472696 -18.160238)
		(end 387.279388 -16.715486)
		(width 0.1143)
		(layer "In9.Cu")
		(net "P3E_CPU0_PE1_PCH_CON_RXN<9>")
	)
	(segment
		(start 433.780692 -1.778508)
		(end 433.780692 -2.727452)
		(width 0.1143)
		(layer "In9.Cu")
		(net "P3E_CPU0_PE1_PCH_CON_RXN<9>")
	)
	(segment
		(start 433.780692 -2.727452)
		(end 433.913534 -2.860294)
		(width 0.1143)
		(layer "In9.Cu")
		(net "P3E_CPU0_PE1_PCH_CON_RXN<9>")
	)
	(segment
		(start 372.000272 -32.650938)
		(end 372.581932 -31.778956)
		(width 0.1143)
		(layer "In9.Cu")
		(net "P3E_CPU0_PE1_PCH_CON_RXN<9>")
	)
	(segment
		(start 366.278414 -125.583442)
		(end 366.278414 -125.258322)
		(width 0.1143)
		(layer "In9.Cu")
		(net "P3E_CPU0_PE1_PCH_CON_RXN<9>")
	)
	(segment
		(start 429.353726 -16.818102)
		(end 431.301144 -17.214088)
		(width 0.1143)
		(layer "In9.Cu")
		(net "P3E_CPU0_PE1_PCH_CON_RXN<9>")
	)
	(segment
		(start 452.396606 -12.29106)
		(end 452.575422 -11.394186)
		(width 0.1143)
		(layer "In9.Cu")
		(net "P3E_CPU0_PE1_PCH_CON_RXN<9>")
	)
	(segment
		(start 438.879996 -18.10131)
		(end 443.353698 -19.011646)
		(width 0.1143)
		(layer "In9.Cu")
		(net "P3E_CPU0_PE1_PCH_CON_RXN<9>")
	)
	(segment
		(start 373.84482 -25.464008)
		(end 377.542552 -19.926554)
		(width 0.1143)
		(layer "In9.Cu")
		(net "P3E_CPU0_PE1_PCH_CON_RXN<9>")
	)
	(segment
		(start 362.67517 -74.265028)
		(end 362.01731 -72.169782)
		(width 0.1143)
		(layer "In9.Cu")
		(net "P3E_CPU0_PE1_PCH_CON_RXN<9>")
	)
	(segment
		(start 449.545456 -18.57375)
		(end 450.481192 -17.949672)
		(width 0.1143)
		(layer "In9.Cu")
		(net "P3E_CPU0_PE1_PCH_CON_RXN<9>")
	)
	(segment
		(start 391.252202 -17.560036)
		(end 407.809446 -14.040358)
		(width 0.1143)
		(layer "In9.Cu")
		(net "P3E_CPU0_PE1_PCH_CON_RXN<9>")
	)
	(segment
		(start 434.5686 -17.391126)
		(end 435.052978 -18.250916)
		(width 0.1143)
		(layer "In9.Cu")
		(net "P3E_CPU0_PE1_PCH_CON_RXN<9>")
	)
	(segment
		(start 435.609492 -0.965708)
		(end 435.444392 -1.130808)
		(width 0.1143)
		(layer "In9.Cu")
		(net "P3E_CPU0_PE1_PCH_CON_RXN<9>")
	)
	(segment
		(start 448.224148 -18.838926)
		(end 449.545456 -18.57375)
		(width 0.1143)
		(layer "In9.Cu")
		(net "P3E_CPU0_PE1_PCH_CON_RXN<9>")
	)
	(segment
		(start 434.936392 -0.965708)
		(end 434.593492 -0.965708)
		(width 0.1143)
		(layer "In9.Cu")
		(net "P3E_CPU0_PE1_PCH_CON_RXN<9>")
	)
	(segment
		(start 454.46061 -6.077458)
		(end 454.54443 -5.657088)
		(width 0.1143)
		(layer "In9.Cu")
		(net "P3E_CPU0_PE1_PCH_CON_RXN<9>")
	)
	(segment
		(start 452.854822 -14.446504)
		(end 452.396606 -12.29106)
		(width 0.1143)
		(layer "In9.Cu")
		(net "P3E_CPU0_PE1_PCH_CON_RXN<9>")
	)
	(segment
		(start 438.879742 -18.10131)
		(end 438.879996 -18.10131)
		(width 0.1143)
		(layer "In9.Cu")
		(net "P3E_CPU0_PE1_PCH_CON_RXN<9>")
	)
	(segment
		(start 437.197754 -18.437606)
		(end 438.879742 -18.10131)
		(width 0.1143)
		(layer "In9.Cu")
		(net "P3E_CPU0_PE1_PCH_CON_RXN<9>")
	)
	(segment
		(start 372.581932 -31.778956)
		(end 373.84482 -25.464008)
		(width 0.1143)
		(layer "In9.Cu")
		(net "P3E_CPU0_PE1_PCH_CON_RXN<9>")
	)
	(segment
		(start 435.444392 -1.130808)
		(end 435.101492 -1.130808)
		(width 0.1143)
		(layer "In9.Cu")
		(net "P3E_CPU0_PE1_PCH_CON_RXN<9>")
	)
	(segment
		(start 454.47077 -5.288534)
		(end 452.80072 -4.174744)
		(width 0.1143)
		(layer "In9.Cu")
		(net "P3E_CPU0_PE1_PCH_CON_RXN<9>")
	)
	(segment
		(start 363.72927 -52.409598)
		(end 364.901226 -48.976026)
		(width 0.1143)
		(layer "In9.Cu")
		(net "P3E_CPU0_PE1_PCH_CON_RXN<9>")
	)
	(segment
		(start 377.542552 -19.926554)
		(end 378.862844 -19.286728)
		(width 0.1143)
		(layer "In9.Cu")
		(net "P3E_CPU0_PE1_PCH_CON_RXN<9>")
	)
	(segment
		(start 364.405164 -105.081578)
		(end 364.405164 -93.898212)
		(width 0.1143)
		(layer "In9.Cu")
		(net "P3E_CPU0_PE1_PCH_CON_RXN<9>")
	)
	(segment
		(start 435.65318 -18.391124)
		(end 436.309262 -18.259552)
		(width 0.1143)
		(layer "In9.Cu")
		(net "P3E_CPU0_PE1_PCH_CON_RXN<9>")
	)
	(segment
		(start 450.614542 -17.432528)
		(end 450.798692 -17.143222)
		(width 0.1143)
		(layer "In9.Cu")
		(net "P3E_CPU0_PE1_PCH_CON_RXN<9>")
	)
	(segment
		(start 450.665342 -17.660366)
		(end 450.614542 -17.432528)
		(width 0.1143)
		(layer "In9.Cu")
		(net "P3E_CPU0_PE1_PCH_CON_RXN<9>")
	)
	(segment
		(start 451.348348 -16.586962)
		(end 451.745858 -16.189198)
		(width 0.1143)
		(layer "In9.Cu")
		(net "P3E_CPU0_PE1_PCH_CON_RXN<9>")
	)
	(segment
		(start 370.769134 -38.473634)
		(end 370.665502 -37.955728)
		(width 0.1143)
		(layer "In9.Cu")
		(net "P3E_CPU0_PE1_PCH_CON_RXN<9>")
	)
	(segment
		(start 428.557944 -16.987266)
		(end 429.353726 -16.818102)
		(width 0.1143)
		(layer "In9.Cu")
		(net "P3E_CPU0_PE1_PCH_CON_RXN<9>")
	)
	(segment
		(start 366.278414 -125.258322)
		(end 366.115092 -125.095)
		(width 0.1143)
		(layer "In9.Cu")
		(net "P3E_CPU0_PE1_PCH_CON_RXN<9>")
	)
	(segment
		(start 363.678216 -105.808526)
		(end 364.405164 -105.081578)
		(width 0.1143)
		(layer "In9.Cu")
		(net "P3E_CPU0_PE1_PCH_CON_RXN<9>")
	)
	(segment
		(start 435.052978 -18.250916)
		(end 435.65318 -18.391124)
		(width 0.1143)
		(layer "In9.Cu")
		(net "P3E_CPU0_PE1_PCH_CON_RXN<9>")
	)
	(segment
		(start 414.637474 -15.487396)
		(end 418.01161 -14.774926)
		(width 0.1143)
		(layer "In9.Cu")
		(net "P3E_CPU0_PE1_PCH_CON_RXN<9>")
	)
	(segment
		(start 451.676008 -2.487676)
		(end 448.204336 -0.965708)
		(width 0.1143)
		(layer "In9.Cu")
		(net "P3E_CPU0_PE1_PCH_CON_RXN<9>")
	)
	(segment
		(start 453.452484 -10.078212)
		(end 454.229216 -6.424676)
		(width 0.1143)
		(layer "In9.Cu")
		(net "P3E_CPU0_PE1_PCH_CON_RXN<9>")
	)
	(segment
		(start 387.279388 -16.715486)
		(end 391.252202 -17.560036)
		(width 0.1143)
		(layer "In9.Cu")
		(net "P3E_CPU0_PE1_PCH_CON_RXN<9>")
	)
	(segment
		(start 431.675286 -3.758184)
		(end 431.675286 -4.386072)
		(width 0.1143)
		(layer "F.Cu")
		(net "P3E_CPU0_PE1_PCH_CON_RXN<8>")
	)
	(segment
		(start 431.335688 -3.418586)
		(end 431.675286 -3.758184)
		(width 0.1143)
		(layer "F.Cu")
		(net "P3E_CPU0_PE1_PCH_CON_RXN<8>")
	)
	(segment
		(start 431.8508 -2.874518)
		(end 431.505614 -2.874518)
		(width 0.1143)
		(layer "F.Cu")
		(net "P3E_CPU0_PE1_PCH_CON_RXN<8>")
	)
	(segment
		(start 431.505614 -2.874518)
		(end 431.335688 -3.044444)
		(width 0.1143)
		(layer "F.Cu")
		(net "P3E_CPU0_PE1_PCH_CON_RXN<8>")
	)
	(segment
		(start 431.335688 -3.044444)
		(end 431.335688 -3.418586)
		(width 0.1143)
		(layer "F.Cu")
		(net "P3E_CPU0_PE1_PCH_CON_RXN<8>")
	)
	(via
		(at 366.227868 -122.662696)
		(size 0.508)
		(drill 0.254)
		(layers "F.Cu" "B.Cu")
		(net "P3E_CPU0_PE1_PCH_CON_RXN<8>")
	)
	(via
		(at 431.8508 -2.874518)
		(size 0.508)
		(drill 0.254)
		(layers "F.Cu" "B.Cu")
		(net "P3E_CPU0_PE1_PCH_CON_RXN<8>")
	)
	(segment
		(start 366.931956 -122.560842)
		(end 366.329722 -122.560842)
		(width 0.1016)
		(layer "B.Cu")
		(net "P3E_CPU0_PE1_PCH_CON_RXN<8>")
	)
	(segment
		(start 366.329722 -122.560842)
		(end 366.227868 -122.662696)
		(width 0.1016)
		(layer "B.Cu")
		(net "P3E_CPU0_PE1_PCH_CON_RXN<8>")
	)
	(segment
		(start 431.310288 -2.696972)
		(end 431.310288 -2.293112)
		(width 0.1143)
		(layer "In9.Cu")
		(net "P3E_CPU0_PE1_PCH_CON_RXN<8>")
	)
	(segment
		(start 457.121514 -9.960102)
		(end 455.724514 -10.239502)
		(width 0.1143)
		(layer "In9.Cu")
		(net "P3E_CPU0_PE1_PCH_CON_RXN<8>")
	)
	(segment
		(start 365.63808 -49.22012)
		(end 364.45825 -52.676044)
		(width 0.1143)
		(layer "In9.Cu")
		(net "P3E_CPU0_PE1_PCH_CON_RXN<8>")
	)
	(segment
		(start 405.535384 -16.289274)
		(end 402.855176 -15.744444)
		(width 0.1143)
		(layer "In9.Cu")
		(net "P3E_CPU0_PE1_PCH_CON_RXN<8>")
	)
	(segment
		(start 375.848626 -23.634192)
		(end 375.018808 -26.792428)
		(width 0.1143)
		(layer "In9.Cu")
		(net "P3E_CPU0_PE1_PCH_CON_RXN<8>")
	)
	(segment
		(start 448.354196 -0.32385)
		(end 452.1454 -1.986788)
		(width 0.1143)
		(layer "In9.Cu")
		(net "P3E_CPU0_PE1_PCH_CON_RXN<8>")
	)
	(segment
		(start 363.149896 -67.871848)
		(end 363.224064 -68.24091)
		(width 0.1143)
		(layer "In9.Cu")
		(net "P3E_CPU0_PE1_PCH_CON_RXN<8>")
	)
	(segment
		(start 364.514638 -122.104404)
		(end 366.078008 -122.104404)
		(width 0.1143)
		(layer "In9.Cu")
		(net "P3E_CPU0_PE1_PCH_CON_RXN<8>")
	)
	(segment
		(start 387.157468 -17.40281)
		(end 380.788418 -18.755614)
		(width 0.1143)
		(layer "In9.Cu")
		(net "P3E_CPU0_PE1_PCH_CON_RXN<8>")
	)
	(segment
		(start 429.368204 -17.48917)
		(end 428.441866 -17.67459)
		(width 0.1143)
		(layer "In9.Cu")
		(net "P3E_CPU0_PE1_PCH_CON_RXN<8>")
	)
	(segment
		(start 362.336588 -65.92062)
		(end 362.564426 -66.993008)
		(width 0.1143)
		(layer "In9.Cu")
		(net "P3E_CPU0_PE1_PCH_CON_RXN<8>")
	)
	(segment
		(start 414.626044 -16.20647)
		(end 407.792174 -14.715998)
		(width 0.1143)
		(layer "In9.Cu")
		(net "P3E_CPU0_PE1_PCH_CON_RXN<8>")
	)
	(segment
		(start 371.993922 -35.729418)
		(end 370.02466 -45.584364)
		(width 0.1143)
		(layer "In9.Cu")
		(net "P3E_CPU0_PE1_PCH_CON_RXN<8>")
	)
	(segment
		(start 366.227868 -122.254264)
		(end 366.227868 -122.662696)
		(width 0.1143)
		(layer "In9.Cu")
		(net "P3E_CPU0_PE1_PCH_CON_RXN<8>")
	)
	(segment
		(start 431.487834 -2.874518)
		(end 431.310288 -2.696972)
		(width 0.1143)
		(layer "In9.Cu")
		(net "P3E_CPU0_PE1_PCH_CON_RXN<8>")
	)
	(segment
		(start 444.87211 -20.193)
		(end 444.40475 -20.660106)
		(width 0.1143)
		(layer "In9.Cu")
		(net "P3E_CPU0_PE1_PCH_CON_RXN<8>")
	)
	(segment
		(start 368.5286 -113.660682)
		(end 366.6998 -115.489482)
		(width 0.1143)
		(layer "In9.Cu")
		(net "P3E_CPU0_PE1_PCH_CON_RXN<8>")
	)
	(segment
		(start 374.554496 -34.022792)
		(end 371.993922 -35.729418)
		(width 0.1143)
		(layer "In9.Cu")
		(net "P3E_CPU0_PE1_PCH_CON_RXN<8>")
	)
	(segment
		(start 457.28763 -8.35406)
		(end 457.516484 -8.39978)
		(width 0.1143)
		(layer "In9.Cu")
		(net "P3E_CPU0_PE1_PCH_CON_RXN<8>")
	)
	(segment
		(start 362.790994 -69.8881)
		(end 363.749082 -74.399394)
		(width 0.1143)
		(layer "In9.Cu")
		(net "P3E_CPU0_PE1_PCH_CON_RXN<8>")
	)
	(segment
		(start 364.45825 -52.676044)
		(end 365.295942 -56.637174)
		(width 0.1143)
		(layer "In9.Cu")
		(net "P3E_CPU0_PE1_PCH_CON_RXN<8>")
	)
	(segment
		(start 433.27955 -0.32385)
		(end 448.354196 -0.32385)
		(width 0.1143)
		(layer "In9.Cu")
		(net "P3E_CPU0_PE1_PCH_CON_RXN<8>")
	)
	(segment
		(start 453.77227 -14.19225)
		(end 450.10451 -19.957796)
		(width 0.1143)
		(layer "In9.Cu")
		(net "P3E_CPU0_PE1_PCH_CON_RXN<8>")
	)
	(segment
		(start 456.833732 -7.37616)
		(end 457.143104 -7.83971)
		(width 0.1143)
		(layer "In9.Cu")
		(net "P3E_CPU0_PE1_PCH_CON_RXN<8>")
	)
	(segment
		(start 457.67752 -9.125966)
		(end 457.121514 -9.960102)
		(width 0.1143)
		(layer "In9.Cu")
		(net "P3E_CPU0_PE1_PCH_CON_RXN<8>")
	)
	(segment
		(start 363.547152 -60.222892)
		(end 362.336588 -65.92062)
		(width 0.1143)
		(layer "In9.Cu")
		(net "P3E_CPU0_PE1_PCH_CON_RXN<8>")
	)
	(segment
		(start 448.482466 -20.282408)
		(end 446.444878 -19.872452)
		(width 0.1143)
		(layer "In9.Cu")
		(net "P3E_CPU0_PE1_PCH_CON_RXN<8>")
	)
	(segment
		(start 365.224314 -101.039168)
		(end 368.5286 -104.343454)
		(width 0.1143)
		(layer "In9.Cu")
		(net "P3E_CPU0_PE1_PCH_CON_RXN<8>")
	)
	(segment
		(start 444.40475 -20.660106)
		(end 442.660024 -21.014944)
		(width 0.1143)
		(layer "In9.Cu")
		(net "P3E_CPU0_PE1_PCH_CON_RXN<8>")
	)
	(segment
		(start 434.662834 -18.886678)
		(end 434.263546 -18.290032)
		(width 0.1143)
		(layer "In9.Cu")
		(net "P3E_CPU0_PE1_PCH_CON_RXN<8>")
	)
	(segment
		(start 407.792174 -14.715998)
		(end 407.230834 -14.835632)
		(width 0.1143)
		(layer "In9.Cu")
		(net "P3E_CPU0_PE1_PCH_CON_RXN<8>")
	)
	(segment
		(start 432.009804 -17.83842)
		(end 431.548032 -17.9324)
		(width 0.1143)
		(layer "In9.Cu")
		(net "P3E_CPU0_PE1_PCH_CON_RXN<8>")
	)
	(segment
		(start 365.295942 -56.637174)
		(end 363.547152 -60.222892)
		(width 0.1143)
		(layer "In9.Cu")
		(net "P3E_CPU0_PE1_PCH_CON_RXN<8>")
	)
	(segment
		(start 362.564426 -66.993008)
		(end 363.149896 -67.871848)
		(width 0.1143)
		(layer "In9.Cu")
		(net "P3E_CPU0_PE1_PCH_CON_RXN<8>")
	)
	(segment
		(start 417.993576 -15.472918)
		(end 414.626044 -16.20647)
		(width 0.1143)
		(layer "In9.Cu")
		(net "P3E_CPU0_PE1_PCH_CON_RXN<8>")
	)
	(segment
		(start 375.382536 -28.50515)
		(end 374.702832 -31.406592)
		(width 0.1143)
		(layer "In9.Cu")
		(net "P3E_CPU0_PE1_PCH_CON_RXN<8>")
	)
	(segment
		(start 453.296274 -3.715766)
		(end 455.269854 -5.031232)
		(width 0.1143)
		(layer "In9.Cu")
		(net "P3E_CPU0_PE1_PCH_CON_RXN<8>")
	)
	(segment
		(start 377.947174 -20.487386)
		(end 375.848626 -23.634192)
		(width 0.1143)
		(layer "In9.Cu")
		(net "P3E_CPU0_PE1_PCH_CON_RXN<8>")
	)
	(segment
		(start 456.604878 -7.330186)
		(end 456.833732 -7.37616)
		(width 0.1143)
		(layer "In9.Cu")
		(net "P3E_CPU0_PE1_PCH_CON_RXN<8>")
	)
	(segment
		(start 364.0201 -121.609866)
		(end 364.514638 -122.104404)
		(width 0.1143)
		(layer "In9.Cu")
		(net "P3E_CPU0_PE1_PCH_CON_RXN<8>")
	)
	(segment
		(start 431.310288 -2.293112)
		(end 433.27955 -0.32385)
		(width 0.1143)
		(layer "In9.Cu")
		(net "P3E_CPU0_PE1_PCH_CON_RXN<8>")
	)
	(segment
		(start 434.263546 -18.290032)
		(end 432.009804 -17.83842)
		(width 0.1143)
		(layer "In9.Cu")
		(net "P3E_CPU0_PE1_PCH_CON_RXN<8>")
	)
	(segment
		(start 375.12117 -33.233614)
		(end 374.554496 -34.022792)
		(width 0.1143)
		(layer "In9.Cu")
		(net "P3E_CPU0_PE1_PCH_CON_RXN<8>")
	)
	(segment
		(start 456.460352 -6.81609)
		(end 456.414632 -7.044944)
		(width 0.1143)
		(layer "In9.Cu")
		(net "P3E_CPU0_PE1_PCH_CON_RXN<8>")
	)
	(segment
		(start 364.0201 -121.054114)
		(end 364.0201 -121.609866)
		(width 0.1143)
		(layer "In9.Cu")
		(net "P3E_CPU0_PE1_PCH_CON_RXN<8>")
	)
	(segment
		(start 455.724514 -10.239502)
		(end 454.628504 -11.883898)
		(width 0.1143)
		(layer "In9.Cu")
		(net "P3E_CPU0_PE1_PCH_CON_RXN<8>")
	)
	(segment
		(start 363.749082 -74.399394)
		(end 364.1725 -74.822558)
		(width 0.1143)
		(layer "In9.Cu")
		(net "P3E_CPU0_PE1_PCH_CON_RXN<8>")
	)
	(segment
		(start 379.134624 -19.911822)
		(end 377.947174 -20.487386)
		(width 0.1143)
		(layer "In9.Cu")
		(net "P3E_CPU0_PE1_PCH_CON_RXN<8>")
	)
	(segment
		(start 450.10451 -19.957796)
		(end 448.482466 -20.282408)
		(width 0.1143)
		(layer "In9.Cu")
		(net "P3E_CPU0_PE1_PCH_CON_RXN<8>")
	)
	(segment
		(start 457.752196 -8.753094)
		(end 457.67752 -9.125966)
		(width 0.1143)
		(layer "In9.Cu")
		(net "P3E_CPU0_PE1_PCH_CON_RXN<8>")
	)
	(segment
		(start 366.078008 -122.104404)
		(end 366.227868 -122.254264)
		(width 0.1143)
		(layer "In9.Cu")
		(net "P3E_CPU0_PE1_PCH_CON_RXN<8>")
	)
	(segment
		(start 407.230834 -14.835632)
		(end 406.383236 -16.1163)
		(width 0.1143)
		(layer "In9.Cu")
		(net "P3E_CPU0_PE1_PCH_CON_RXN<8>")
	)
	(segment
		(start 366.6998 -118.374414)
		(end 364.0201 -121.054114)
		(width 0.1143)
		(layer "In9.Cu")
		(net "P3E_CPU0_PE1_PCH_CON_RXN<8>")
	)
	(segment
		(start 374.702832 -31.406592)
		(end 375.12117 -33.233614)
		(width 0.1143)
		(layer "In9.Cu")
		(net "P3E_CPU0_PE1_PCH_CON_RXN<8>")
	)
	(segment
		(start 434.663088 -18.886424)
		(end 434.663088 -18.886678)
		(width 0.1143)
		(layer "In9.Cu")
		(net "P3E_CPU0_PE1_PCH_CON_RXN<8>")
	)
	(segment
		(start 454.065132 -12.72921)
		(end 453.77227 -14.19225)
		(width 0.1143)
		(layer "In9.Cu")
		(net "P3E_CPU0_PE1_PCH_CON_RXN<8>")
	)
	(segment
		(start 368.5286 -104.343454)
		(end 368.5286 -113.660682)
		(width 0.1143)
		(layer "In9.Cu")
		(net "P3E_CPU0_PE1_PCH_CON_RXN<8>")
	)
	(segment
		(start 454.628504 -11.883898)
		(end 454.39965 -11.929618)
		(width 0.1143)
		(layer "In9.Cu")
		(net "P3E_CPU0_PE1_PCH_CON_RXN<8>")
	)
	(segment
		(start 454.255378 -12.443968)
		(end 454.065132 -12.72921)
		(width 0.1143)
		(layer "In9.Cu")
		(net "P3E_CPU0_PE1_PCH_CON_RXN<8>")
	)
	(segment
		(start 428.441866 -17.67459)
		(end 417.993576 -15.472918)
		(width 0.1143)
		(layer "In9.Cu")
		(net "P3E_CPU0_PE1_PCH_CON_RXN<8>")
	)
	(segment
		(start 456.414632 -7.044944)
		(end 456.604878 -7.330186)
		(width 0.1143)
		(layer "In9.Cu")
		(net "P3E_CPU0_PE1_PCH_CON_RXN<8>")
	)
	(segment
		(start 434.663088 -18.886678)
		(end 434.662834 -18.886678)
		(width 0.1143)
		(layer "In9.Cu")
		(net "P3E_CPU0_PE1_PCH_CON_RXN<8>")
	)
	(segment
		(start 363.224064 -68.24091)
		(end 362.790994 -69.8881)
		(width 0.1143)
		(layer "In9.Cu")
		(net "P3E_CPU0_PE1_PCH_CON_RXN<8>")
	)
	(segment
		(start 454.39965 -11.929618)
		(end 454.209404 -12.21486)
		(width 0.1143)
		(layer "In9.Cu")
		(net "P3E_CPU0_PE1_PCH_CON_RXN<8>")
	)
	(segment
		(start 366.6998 -115.489482)
		(end 366.6998 -118.374414)
		(width 0.1143)
		(layer "In9.Cu")
		(net "P3E_CPU0_PE1_PCH_CON_RXN<8>")
	)
	(segment
		(start 442.660024 -21.014944)
		(end 434.663088 -18.886424)
		(width 0.1143)
		(layer "In9.Cu")
		(net "P3E_CPU0_PE1_PCH_CON_RXN<8>")
	)
	(segment
		(start 457.143104 -7.83971)
		(end 457.097384 -8.068818)
		(width 0.1143)
		(layer "In9.Cu")
		(net "P3E_CPU0_PE1_PCH_CON_RXN<8>")
	)
	(segment
		(start 375.018808 -26.792428)
		(end 375.382536 -28.50515)
		(width 0.1143)
		(layer "In9.Cu")
		(net "P3E_CPU0_PE1_PCH_CON_RXN<8>")
	)
	(segment
		(start 391.21715 -18.21815)
		(end 387.157468 -17.40281)
		(width 0.1143)
		(layer "In9.Cu")
		(net "P3E_CPU0_PE1_PCH_CON_RXN<8>")
	)
	(segment
		(start 364.1725 -74.822558)
		(end 364.1725 -89.38514)
		(width 0.1143)
		(layer "In9.Cu")
		(net "P3E_CPU0_PE1_PCH_CON_RXN<8>")
	)
	(segment
		(start 364.1725 -89.38514)
		(end 365.224314 -94.30893)
		(width 0.1143)
		(layer "In9.Cu")
		(net "P3E_CPU0_PE1_PCH_CON_RXN<8>")
	)
	(segment
		(start 452.1454 -1.986788)
		(end 453.296274 -3.715766)
		(width 0.1143)
		(layer "In9.Cu")
		(net "P3E_CPU0_PE1_PCH_CON_RXN<8>")
	)
	(segment
		(start 454.209404 -12.21486)
		(end 454.255378 -12.443968)
		(width 0.1143)
		(layer "In9.Cu")
		(net "P3E_CPU0_PE1_PCH_CON_RXN<8>")
	)
	(segment
		(start 402.855176 -15.744444)
		(end 391.21715 -18.21815)
		(width 0.1143)
		(layer "In9.Cu")
		(net "P3E_CPU0_PE1_PCH_CON_RXN<8>")
	)
	(segment
		(start 446.444878 -19.872452)
		(end 444.87211 -20.193)
		(width 0.1143)
		(layer "In9.Cu")
		(net "P3E_CPU0_PE1_PCH_CON_RXN<8>")
	)
	(segment
		(start 370.02466 -45.584364)
		(end 365.63808 -49.22012)
		(width 0.1143)
		(layer "In9.Cu")
		(net "P3E_CPU0_PE1_PCH_CON_RXN<8>")
	)
	(segment
		(start 455.269854 -5.031232)
		(end 456.460352 -6.81609)
		(width 0.1143)
		(layer "In9.Cu")
		(net "P3E_CPU0_PE1_PCH_CON_RXN<8>")
	)
	(segment
		(start 380.788418 -18.755614)
		(end 379.134624 -19.911822)
		(width 0.1143)
		(layer "In9.Cu")
		(net "P3E_CPU0_PE1_PCH_CON_RXN<8>")
	)
	(segment
		(start 431.8508 -2.874518)
		(end 431.487834 -2.874518)
		(width 0.1143)
		(layer "In9.Cu")
		(net "P3E_CPU0_PE1_PCH_CON_RXN<8>")
	)
	(segment
		(start 365.224314 -94.30893)
		(end 365.224314 -101.039168)
		(width 0.1143)
		(layer "In9.Cu")
		(net "P3E_CPU0_PE1_PCH_CON_RXN<8>")
	)
	(segment
		(start 431.548032 -17.9324)
		(end 429.368204 -17.48917)
		(width 0.1143)
		(layer "In9.Cu")
		(net "P3E_CPU0_PE1_PCH_CON_RXN<8>")
	)
	(segment
		(start 457.097384 -8.068818)
		(end 457.28763 -8.35406)
		(width 0.1143)
		(layer "In9.Cu")
		(net "P3E_CPU0_PE1_PCH_CON_RXN<8>")
	)
	(segment
		(start 457.516484 -8.39978)
		(end 457.752196 -8.753094)
		(width 0.1143)
		(layer "In9.Cu")
		(net "P3E_CPU0_PE1_PCH_CON_RXN<8>")
	)
	(segment
		(start 406.383236 -16.1163)
		(end 405.535384 -16.289274)
		(width 0.1143)
		(layer "In9.Cu")
		(net "P3E_CPU0_PE1_PCH_CON_RXN<8>")
	)
	(segment
		(start 448.122294 -2.06629)
		(end 452.141844 -2.06629)
		(width 0.1143)
		(layer "F.Cu")
		(net "P3E_CPU0_PE1_PCH_CON_RXN<15>")
	)
	(segment
		(start 446.535556 -4.82219)
		(end 446.535556 -3.653028)
		(width 0.1143)
		(layer "F.Cu")
		(net "P3E_CPU0_PE1_PCH_CON_RXN<15>")
	)
	(segment
		(start 453.277478 -3.758184)
		(end 453.277478 -4.386072)
		(width 0.1143)
		(layer "F.Cu")
		(net "P3E_CPU0_PE1_PCH_CON_RXN<15>")
	)
	(segment
		(start 446.535556 -3.653028)
		(end 448.122294 -2.06629)
		(width 0.1143)
		(layer "F.Cu")
		(net "P3E_CPU0_PE1_PCH_CON_RXN<15>")
	)
	(segment
		(start 452.998078 -3.478784)
		(end 453.277478 -3.758184)
		(width 0.1143)
		(layer "F.Cu")
		(net "P3E_CPU0_PE1_PCH_CON_RXN<15>")
	)
	(segment
		(start 452.141844 -2.06629)
		(end 452.998078 -2.922524)
		(width 0.1143)
		(layer "F.Cu")
		(net "P3E_CPU0_PE1_PCH_CON_RXN<15>")
	)
	(segment
		(start 452.998078 -2.922524)
		(end 452.998078 -3.478784)
		(width 0.1143)
		(layer "F.Cu")
		(net "P3E_CPU0_PE1_PCH_CON_RXN<15>")
	)
	(segment
		(start 446.275968 -5.081778)
		(end 446.535556 -4.82219)
		(width 0.1143)
		(layer "F.Cu")
		(net "P3E_CPU0_PE1_PCH_CON_RXN<15>")
	)
	(via
		(at 446.275968 -5.081778)
		(size 0.508)
		(drill 0.254)
		(layers "F.Cu" "B.Cu")
		(net "P3E_CPU0_PE1_PCH_CON_RXN<15>")
	)
	(via
		(at 352.740214 -125.380242)
		(size 0.508)
		(drill 0.254)
		(layers "F.Cu" "B.Cu")
		(net "P3E_CPU0_PE1_PCH_CON_RXN<15>")
	)
	(segment
		(start 352.892614 -125.532642)
		(end 352.740214 -125.380242)
		(width 0.10795)
		(layer "B.Cu")
		(net "P3E_CPU0_PE1_PCH_CON_RXN<15>")
	)
	(segment
		(start 353.400614 -125.532642)
		(end 352.892614 -125.532642)
		(width 0.10795)
		(layer "B.Cu")
		(net "P3E_CPU0_PE1_PCH_CON_RXN<15>")
	)
	(segment
		(start 357.410512 -80.07223)
		(end 358.299004 -79.184246)
		(width 0.1143)
		(layer "In9.Cu")
		(net "P3E_CPU0_PE1_PCH_CON_RXN<15>")
	)
	(segment
		(start 408.221434 -10.051288)
		(end 414.648396 -11.416284)
		(width 0.1143)
		(layer "In9.Cu")
		(net "P3E_CPU0_PE1_PCH_CON_RXN<15>")
	)
	(segment
		(start 357.410512 -82.816192)
		(end 357.410512 -80.07223)
		(width 0.1143)
		(layer "In9.Cu")
		(net "P3E_CPU0_PE1_PCH_CON_RXN<15>")
	)
	(segment
		(start 428.554388 -11.091672)
		(end 431.123852 -10.568686)
		(width 0.1143)
		(layer "In9.Cu")
		(net "P3E_CPU0_PE1_PCH_CON_RXN<15>")
	)
	(segment
		(start 358.29875 -73.881488)
		(end 358.299004 -73.881488)
		(width 0.1143)
		(layer "In9.Cu")
		(net "P3E_CPU0_PE1_PCH_CON_RXN<15>")
	)
	(segment
		(start 421.07612 -10.430256)
		(end 423.197782 -10.881614)
		(width 0.1143)
		(layer "In9.Cu")
		(net "P3E_CPU0_PE1_PCH_CON_RXN<15>")
	)
	(segment
		(start 418.806884 -10.584434)
		(end 419.579806 -10.749026)
		(width 0.1143)
		(layer "In9.Cu")
		(net "P3E_CPU0_PE1_PCH_CON_RXN<15>")
	)
	(segment
		(start 358.416098 -50.205132)
		(end 362.270802 -43.56608)
		(width 0.1143)
		(layer "In9.Cu")
		(net "P3E_CPU0_PE1_PCH_CON_RXN<15>")
	)
	(segment
		(start 357.669846 -65.840356)
		(end 359.10139 -59.102244)
		(width 0.1143)
		(layer "In9.Cu")
		(net "P3E_CPU0_PE1_PCH_CON_RXN<15>")
	)
	(segment
		(start 357.693468 -94.780862)
		(end 357.40467 -93.41993)
		(width 0.1143)
		(layer "In9.Cu")
		(net "P3E_CPU0_PE1_PCH_CON_RXN<15>")
	)
	(segment
		(start 359.10139 -59.102244)
		(end 358.058466 -54.19344)
		(width 0.1143)
		(layer "In9.Cu")
		(net "P3E_CPU0_PE1_PCH_CON_RXN<15>")
	)
	(segment
		(start 362.270802 -43.56608)
		(end 363.623606 -36.797742)
		(width 0.1143)
		(layer "In9.Cu")
		(net "P3E_CPU0_PE1_PCH_CON_RXN<15>")
	)
	(segment
		(start 358.853486 -84.259166)
		(end 357.410512 -82.816192)
		(width 0.1143)
		(layer "In9.Cu")
		(net "P3E_CPU0_PE1_PCH_CON_RXN<15>")
	)
	(segment
		(start 424.833796 -10.533634)
		(end 425.312586 -10.630916)
		(width 0.1143)
		(layer "In9.Cu")
		(net "P3E_CPU0_PE1_PCH_CON_RXN<15>")
	)
	(segment
		(start 379.485906 -14.058138)
		(end 380.270004 -14.224508)
		(width 0.1143)
		(layer "In9.Cu")
		(net "P3E_CPU0_PE1_PCH_CON_RXN<15>")
	)
	(segment
		(start 357.693722 -94.780862)
		(end 357.693468 -94.780862)
		(width 0.1143)
		(layer "In9.Cu")
		(net "P3E_CPU0_PE1_PCH_CON_RXN<15>")
	)
	(segment
		(start 358.299004 -73.881742)
		(end 358.29875 -73.881488)
		(width 0.1143)
		(layer "In9.Cu")
		(net "P3E_CPU0_PE1_PCH_CON_RXN<15>")
	)
	(segment
		(start 358.638602 -52.492402)
		(end 358.29875 -50.793142)
		(width 0.1143)
		(layer "In9.Cu")
		(net "P3E_CPU0_PE1_PCH_CON_RXN<15>")
	)
	(segment
		(start 358.299004 -79.184246)
		(end 358.299004 -73.881742)
		(width 0.1143)
		(layer "In9.Cu")
		(net "P3E_CPU0_PE1_PCH_CON_RXN<15>")
	)
	(segment
		(start 366.500156 -33.254188)
		(end 366.97285 -30.896306)
		(width 0.1143)
		(layer "In9.Cu")
		(net "P3E_CPU0_PE1_PCH_CON_RXN<15>")
	)
	(segment
		(start 369.491514 -26.635964)
		(end 370.14658 -23.690834)
		(width 0.1143)
		(layer "In9.Cu")
		(net "P3E_CPU0_PE1_PCH_CON_RXN<15>")
	)
	(segment
		(start 423.197782 -10.881614)
		(end 424.833796 -10.533634)
		(width 0.1143)
		(layer "In9.Cu")
		(net "P3E_CPU0_PE1_PCH_CON_RXN<15>")
	)
	(segment
		(start 356.227634 -68.519294)
		(end 356.605332 -67.346322)
		(width 0.1143)
		(layer "In9.Cu")
		(net "P3E_CPU0_PE1_PCH_CON_RXN<15>")
	)
	(segment
		(start 441.908692 -11.032998)
		(end 444.156338 -10.583672)
		(width 0.1143)
		(layer "In9.Cu")
		(net "P3E_CPU0_PE1_PCH_CON_RXN<15>")
	)
	(segment
		(start 426.18787 -10.452608)
		(end 426.246036 -10.440924)
		(width 0.1143)
		(layer "In9.Cu")
		(net "P3E_CPU0_PE1_PCH_CON_RXN<15>")
	)
	(segment
		(start 352.740214 -125.380242)
		(end 352.740214 -125.802898)
		(width 0.1143)
		(layer "In9.Cu")
		(net "P3E_CPU0_PE1_PCH_CON_RXN<15>")
	)
	(segment
		(start 446.608708 -5.404612)
		(end 446.285874 -5.081778)
		(width 0.1143)
		(layer "In9.Cu")
		(net "P3E_CPU0_PE1_PCH_CON_RXN<15>")
	)
	(segment
		(start 356.52075 -70.029832)
		(end 356.227634 -68.519294)
		(width 0.1143)
		(layer "In9.Cu")
		(net "P3E_CPU0_PE1_PCH_CON_RXN<15>")
	)
	(segment
		(start 426.18787 -10.452862)
		(end 426.18787 -10.452608)
		(width 0.1143)
		(layer "In9.Cu")
		(net "P3E_CPU0_PE1_PCH_CON_RXN<15>")
	)
	(segment
		(start 391.68197 -13.566902)
		(end 408.221434 -10.051288)
		(width 0.1143)
		(layer "In9.Cu")
		(net "P3E_CPU0_PE1_PCH_CON_RXN<15>")
	)
	(segment
		(start 380.270004 -14.224508)
		(end 387.526784 -12.683998)
		(width 0.1143)
		(layer "In9.Cu")
		(net "P3E_CPU0_PE1_PCH_CON_RXN<15>")
	)
	(segment
		(start 345.858084 -127.134874)
		(end 345.415108 -126.691898)
		(width 0.1143)
		(layer "In9.Cu")
		(net "P3E_CPU0_PE1_PCH_CON_RXN<15>")
	)
	(segment
		(start 358.365806 -117.423946)
		(end 359.320084 -116.69522)
		(width 0.1143)
		(layer "In9.Cu")
		(net "P3E_CPU0_PE1_PCH_CON_RXN<15>")
	)
	(segment
		(start 368.553746 -27.080972)
		(end 369.2779 -26.921206)
		(width 0.1143)
		(layer "In9.Cu")
		(net "P3E_CPU0_PE1_PCH_CON_RXN<15>")
	)
	(segment
		(start 358.853486 -86.59749)
		(end 358.853486 -84.259166)
		(width 0.1143)
		(layer "In9.Cu")
		(net "P3E_CPU0_PE1_PCH_CON_RXN<15>")
	)
	(segment
		(start 358.471216 -52.983384)
		(end 358.638602 -52.492402)
		(width 0.1143)
		(layer "In9.Cu")
		(net "P3E_CPU0_PE1_PCH_CON_RXN<15>")
	)
	(segment
		(start 447.891662 -9.82472)
		(end 448.116706 -8.829802)
		(width 0.1143)
		(layer "In9.Cu")
		(net "P3E_CPU0_PE1_PCH_CON_RXN<15>")
	)
	(segment
		(start 358.29875 -50.793142)
		(end 358.416098 -50.205132)
		(width 0.1143)
		(layer "In9.Cu")
		(net "P3E_CPU0_PE1_PCH_CON_RXN<15>")
	)
	(segment
		(start 447.294762 -6.834378)
		(end 446.608708 -6.148324)
		(width 0.1143)
		(layer "In9.Cu")
		(net "P3E_CPU0_PE1_PCH_CON_RXN<15>")
	)
	(segment
		(start 369.2779 -26.921206)
		(end 369.491514 -26.635964)
		(width 0.1143)
		(layer "In9.Cu")
		(net "P3E_CPU0_PE1_PCH_CON_RXN<15>")
	)
	(segment
		(start 387.526784 -12.683998)
		(end 391.68197 -13.566902)
		(width 0.1143)
		(layer "In9.Cu")
		(net "P3E_CPU0_PE1_PCH_CON_RXN<15>")
	)
	(segment
		(start 433.312316 -11.016234)
		(end 435.321456 -10.589514)
		(width 0.1143)
		(layer "In9.Cu")
		(net "P3E_CPU0_PE1_PCH_CON_RXN<15>")
	)
	(segment
		(start 359.135934 -108.719366)
		(end 358.20223 -108.09732)
		(width 0.1143)
		(layer "In9.Cu")
		(net "P3E_CPU0_PE1_PCH_CON_RXN<15>")
	)
	(segment
		(start 357.9749 -107.6706)
		(end 357.9749 -104.252522)
		(width 0.1143)
		(layer "In9.Cu")
		(net "P3E_CPU0_PE1_PCH_CON_RXN<15>")
	)
	(segment
		(start 352.740214 -125.802898)
		(end 352.867468 -125.930152)
		(width 0.1143)
		(layer "In9.Cu")
		(net "P3E_CPU0_PE1_PCH_CON_RXN<15>")
	)
	(segment
		(start 357.40467 -93.41993)
		(end 358.853486 -86.59749)
		(width 0.1143)
		(layer "In9.Cu")
		(net "P3E_CPU0_PE1_PCH_CON_RXN<15>")
	)
	(segment
		(start 344.033602 -121.495312)
		(end 344.439748 -120.848882)
		(width 0.1143)
		(layer "In9.Cu")
		(net "P3E_CPU0_PE1_PCH_CON_RXN<15>")
	)
	(segment
		(start 358.299004 -73.881488)
		(end 356.52075 -70.029832)
		(width 0.1143)
		(layer "In9.Cu")
		(net "P3E_CPU0_PE1_PCH_CON_RXN<15>")
	)
	(segment
		(start 440.788552 -10.809732)
		(end 441.908692 -11.032998)
		(width 0.1143)
		(layer "In9.Cu")
		(net "P3E_CPU0_PE1_PCH_CON_RXN<15>")
	)
	(segment
		(start 375.438924 -15.751048)
		(end 377.273058 -14.528038)
		(width 0.1143)
		(layer "In9.Cu")
		(net "P3E_CPU0_PE1_PCH_CON_RXN<15>")
	)
	(segment
		(start 358.058466 -54.19344)
		(end 358.471216 -52.983384)
		(width 0.1143)
		(layer "In9.Cu")
		(net "P3E_CPU0_PE1_PCH_CON_RXN<15>")
	)
	(segment
		(start 425.312586 -10.630916)
		(end 426.18787 -10.452862)
		(width 0.1143)
		(layer "In9.Cu")
		(net "P3E_CPU0_PE1_PCH_CON_RXN<15>")
	)
	(segment
		(start 363.623606 -36.797742)
		(end 366.500156 -33.254188)
		(width 0.1143)
		(layer "In9.Cu")
		(net "P3E_CPU0_PE1_PCH_CON_RXN<15>")
	)
	(segment
		(start 435.321456 -10.589514)
		(end 438.57291 -11.280394)
		(width 0.1143)
		(layer "In9.Cu")
		(net "P3E_CPU0_PE1_PCH_CON_RXN<15>")
	)
	(segment
		(start 345.737434 -120.109234)
		(end 358.365806 -117.423946)
		(width 0.1143)
		(layer "In9.Cu")
		(net "P3E_CPU0_PE1_PCH_CON_RXN<15>")
	)
	(segment
		(start 433.31003 -11.012678)
		(end 433.312316 -11.016234)
		(width 0.1143)
		(layer "In9.Cu")
		(net "P3E_CPU0_PE1_PCH_CON_RXN<15>")
	)
	(segment
		(start 344.033602 -124.49556)
		(end 344.033602 -121.495312)
		(width 0.1143)
		(layer "In9.Cu")
		(net "P3E_CPU0_PE1_PCH_CON_RXN<15>")
	)
	(segment
		(start 344.439748 -120.848882)
		(end 345.737434 -120.109234)
		(width 0.1143)
		(layer "In9.Cu")
		(net "P3E_CPU0_PE1_PCH_CON_RXN<15>")
	)
	(segment
		(start 414.648396 -11.416284)
		(end 418.806884 -10.584434)
		(width 0.1143)
		(layer "In9.Cu")
		(net "P3E_CPU0_PE1_PCH_CON_RXN<15>")
	)
	(segment
		(start 427.853348 -10.948924)
		(end 428.554388 -11.091672)
		(width 0.1143)
		(layer "In9.Cu")
		(net "P3E_CPU0_PE1_PCH_CON_RXN<15>")
	)
	(segment
		(start 356.605332 -67.346322)
		(end 357.669846 -65.840356)
		(width 0.1143)
		(layer "In9.Cu")
		(net "P3E_CPU0_PE1_PCH_CON_RXN<15>")
	)
	(segment
		(start 353.274122 -125.93066)
		(end 353.68992 -126.231396)
		(width 0.1143)
		(layer "In9.Cu")
		(net "P3E_CPU0_PE1_PCH_CON_RXN<15>")
	)
	(segment
		(start 446.285874 -5.081778)
		(end 446.275968 -5.081778)
		(width 0.1143)
		(layer "In9.Cu")
		(net "P3E_CPU0_PE1_PCH_CON_RXN<15>")
	)
	(segment
		(start 446.128902 -10.978134)
		(end 446.99809 -10.802112)
		(width 0.1143)
		(layer "In9.Cu")
		(net "P3E_CPU0_PE1_PCH_CON_RXN<15>")
	)
	(segment
		(start 360.074718 -113.13922)
		(end 359.135934 -108.719366)
		(width 0.1143)
		(layer "In9.Cu")
		(net "P3E_CPU0_PE1_PCH_CON_RXN<15>")
	)
	(segment
		(start 357.9749 -104.252522)
		(end 356.828852 -98.85299)
		(width 0.1143)
		(layer "In9.Cu")
		(net "P3E_CPU0_PE1_PCH_CON_RXN<15>")
	)
	(segment
		(start 350.986598 -127.4699)
		(end 350.651572 -127.134874)
		(width 0.1143)
		(layer "In9.Cu")
		(net "P3E_CPU0_PE1_PCH_CON_RXN<15>")
	)
	(segment
		(start 419.579806 -10.749026)
		(end 421.07612 -10.430256)
		(width 0.1143)
		(layer "In9.Cu")
		(net "P3E_CPU0_PE1_PCH_CON_RXN<15>")
	)
	(segment
		(start 366.728502 -29.67228)
		(end 367.046256 -28.081732)
		(width 0.1143)
		(layer "In9.Cu")
		(net "P3E_CPU0_PE1_PCH_CON_RXN<15>")
	)
	(segment
		(start 367.046256 -28.081732)
		(end 368.553746 -27.080972)
		(width 0.1143)
		(layer "In9.Cu")
		(net "P3E_CPU0_PE1_PCH_CON_RXN<15>")
	)
	(segment
		(start 353.267518 -127.4699)
		(end 350.986598 -127.4699)
		(width 0.1143)
		(layer "In9.Cu")
		(net "P3E_CPU0_PE1_PCH_CON_RXN<15>")
	)
	(segment
		(start 377.273058 -14.528038)
		(end 379.485906 -14.058138)
		(width 0.1143)
		(layer "In9.Cu")
		(net "P3E_CPU0_PE1_PCH_CON_RXN<15>")
	)
	(segment
		(start 444.156338 -10.583672)
		(end 446.128902 -10.978134)
		(width 0.1143)
		(layer "In9.Cu")
		(net "P3E_CPU0_PE1_PCH_CON_RXN<15>")
	)
	(segment
		(start 370.14658 -23.690834)
		(end 375.438924 -15.751048)
		(width 0.1143)
		(layer "In9.Cu")
		(net "P3E_CPU0_PE1_PCH_CON_RXN<15>")
	)
	(segment
		(start 446.608708 -6.148324)
		(end 446.608708 -5.404612)
		(width 0.1143)
		(layer "In9.Cu")
		(net "P3E_CPU0_PE1_PCH_CON_RXN<15>")
	)
	(segment
		(start 345.415108 -125.877066)
		(end 344.033602 -124.49556)
		(width 0.1143)
		(layer "In9.Cu")
		(net "P3E_CPU0_PE1_PCH_CON_RXN<15>")
	)
	(segment
		(start 353.68992 -126.231396)
		(end 353.68992 -127.047498)
		(width 0.1143)
		(layer "In9.Cu")
		(net "P3E_CPU0_PE1_PCH_CON_RXN<15>")
	)
	(segment
		(start 431.123852 -10.568686)
		(end 433.31003 -11.012678)
		(width 0.1143)
		(layer "In9.Cu")
		(net "P3E_CPU0_PE1_PCH_CON_RXN<15>")
	)
	(segment
		(start 366.97285 -30.896306)
		(end 366.728502 -29.67228)
		(width 0.1143)
		(layer "In9.Cu")
		(net "P3E_CPU0_PE1_PCH_CON_RXN<15>")
	)
	(segment
		(start 345.415108 -126.691898)
		(end 345.415108 -125.877066)
		(width 0.1143)
		(layer "In9.Cu")
		(net "P3E_CPU0_PE1_PCH_CON_RXN<15>")
	)
	(segment
		(start 356.828852 -98.85299)
		(end 357.693722 -94.780862)
		(width 0.1143)
		(layer "In9.Cu")
		(net "P3E_CPU0_PE1_PCH_CON_RXN<15>")
	)
	(segment
		(start 447.562224 -10.39622)
		(end 447.891662 -9.82472)
		(width 0.1143)
		(layer "In9.Cu")
		(net "P3E_CPU0_PE1_PCH_CON_RXN<15>")
	)
	(segment
		(start 359.320084 -116.69522)
		(end 360.074718 -113.13922)
		(width 0.1143)
		(layer "In9.Cu")
		(net "P3E_CPU0_PE1_PCH_CON_RXN<15>")
	)
	(segment
		(start 427.458378 -10.687558)
		(end 427.853348 -10.948924)
		(width 0.1143)
		(layer "In9.Cu")
		(net "P3E_CPU0_PE1_PCH_CON_RXN<15>")
	)
	(segment
		(start 352.867468 -125.930152)
		(end 353.274122 -125.93066)
		(width 0.1143)
		(layer "In9.Cu")
		(net "P3E_CPU0_PE1_PCH_CON_RXN<15>")
	)
	(segment
		(start 438.57291 -11.280394)
		(end 440.788552 -10.809732)
		(width 0.1143)
		(layer "In9.Cu")
		(net "P3E_CPU0_PE1_PCH_CON_RXN<15>")
	)
	(segment
		(start 350.651572 -127.134874)
		(end 345.858084 -127.134874)
		(width 0.1143)
		(layer "In9.Cu")
		(net "P3E_CPU0_PE1_PCH_CON_RXN<15>")
	)
	(segment
		(start 448.116706 -8.829802)
		(end 447.294762 -6.834378)
		(width 0.1143)
		(layer "In9.Cu")
		(net "P3E_CPU0_PE1_PCH_CON_RXN<15>")
	)
	(segment
		(start 358.20223 -108.09732)
		(end 357.9749 -107.6706)
		(width 0.1143)
		(layer "In9.Cu")
		(net "P3E_CPU0_PE1_PCH_CON_RXN<15>")
	)
	(segment
		(start 353.68992 -127.047498)
		(end 353.267518 -127.4699)
		(width 0.1143)
		(layer "In9.Cu")
		(net "P3E_CPU0_PE1_PCH_CON_RXN<15>")
	)
	(segment
		(start 426.246036 -10.440924)
		(end 427.458378 -10.687558)
		(width 0.1143)
		(layer "In9.Cu")
		(net "P3E_CPU0_PE1_PCH_CON_RXN<15>")
	)
	(segment
		(start 446.99809 -10.802112)
		(end 447.562224 -10.39622)
		(width 0.1143)
		(layer "In9.Cu")
		(net "P3E_CPU0_PE1_PCH_CON_RXN<15>")
	)
	(segment
		(start 450.877178 -3.237484)
		(end 450.379846 -2.740152)
		(width 0.1143)
		(layer "F.Cu")
		(net "P3E_CPU0_PE1_PCH_CON_RXN<14>")
	)
	(segment
		(start 450.379846 -2.740152)
		(end 449.147438 -2.740152)
		(width 0.1143)
		(layer "F.Cu")
		(net "P3E_CPU0_PE1_PCH_CON_RXN<14>")
	)
	(segment
		(start 448.888612 -2.992628)
		(end 448.24523 -3.63601)
		(width 0.1143)
		(layer "F.Cu")
		(net "P3E_CPU0_PE1_PCH_CON_RXN<14>")
	)
	(segment
		(start 448.24523 -5.74675)
		(end 447.89344 -6.09854)
		(width 0.1143)
		(layer "F.Cu")
		(net "P3E_CPU0_PE1_PCH_CON_RXN<14>")
	)
	(segment
		(start 448.24523 -3.63601)
		(end 448.24523 -5.74675)
		(width 0.1143)
		(layer "F.Cu")
		(net "P3E_CPU0_PE1_PCH_CON_RXN<14>")
	)
	(segment
		(start 450.877178 -4.386072)
		(end 450.877178 -3.237484)
		(width 0.1143)
		(layer "F.Cu")
		(net "P3E_CPU0_PE1_PCH_CON_RXN<14>")
	)
	(segment
		(start 448.894962 -2.992628)
		(end 448.888612 -2.992628)
		(width 0.1143)
		(layer "F.Cu")
		(net "P3E_CPU0_PE1_PCH_CON_RXN<14>")
	)
	(segment
		(start 449.147438 -2.740152)
		(end 448.894962 -2.992628)
		(width 0.1143)
		(layer "F.Cu")
		(net "P3E_CPU0_PE1_PCH_CON_RXN<14>")
	)
	(via
		(at 347.584014 -125.151642)
		(size 0.508)
		(drill 0.254)
		(layers "F.Cu" "B.Cu")
		(net "P3E_CPU0_PE1_PCH_CON_RXN<14>")
	)
	(via
		(at 447.89344 -6.09854)
		(size 0.508)
		(drill 0.254)
		(layers "F.Cu" "B.Cu")
		(net "P3E_CPU0_PE1_PCH_CON_RXN<14>")
	)
	(segment
		(start 348.244414 -125.227842)
		(end 347.660214 -125.227842)
		(width 0.10795)
		(layer "B.Cu")
		(net "P3E_CPU0_PE1_PCH_CON_RXN<14>")
	)
	(segment
		(start 347.660214 -125.227842)
		(end 347.584014 -125.151642)
		(width 0.10795)
		(layer "B.Cu")
		(net "P3E_CPU0_PE1_PCH_CON_RXN<14>")
	)
	(segment
		(start 359.165652 -104.115616)
		(end 359.983024 -104.115616)
		(width 0.1143)
		(layer "In9.Cu")
		(net "P3E_CPU0_PE1_PCH_CON_RXN<14>")
	)
	(segment
		(start 387.368034 -13.368782)
		(end 391.52068 -14.25067)
		(width 0.1143)
		(layer "In9.Cu")
		(net "P3E_CPU0_PE1_PCH_CON_RXN<14>")
	)
	(segment
		(start 344.694764 -123.9647)
		(end 344.694764 -121.753884)
		(width 0.1143)
		(layer "In9.Cu")
		(net "P3E_CPU0_PE1_PCH_CON_RXN<14>")
	)
	(segment
		(start 369.799108 -28.082494)
		(end 369.93322 -27.992832)
		(width 0.1143)
		(layer "In9.Cu")
		(net "P3E_CPU0_PE1_PCH_CON_RXN<14>")
	)
	(segment
		(start 448.257422 -6.462522)
		(end 447.89344 -6.09854)
		(width 0.1143)
		(layer "In9.Cu")
		(net "P3E_CPU0_PE1_PCH_CON_RXN<14>")
	)
	(segment
		(start 359.983024 -102.540816)
		(end 360.097324 -102.426516)
		(width 0.1143)
		(layer "In9.Cu")
		(net "P3E_CPU0_PE1_PCH_CON_RXN<14>")
	)
	(segment
		(start 440.58332 -12.69873)
		(end 441.529724 -12.892532)
		(width 0.1143)
		(layer "In9.Cu")
		(net "P3E_CPU0_PE1_PCH_CON_RXN<14>")
	)
	(segment
		(start 439.538364 -12.039092)
		(end 439.875168 -11.816842)
		(width 0.1143)
		(layer "In9.Cu")
		(net "P3E_CPU0_PE1_PCH_CON_RXN<14>")
	)
	(segment
		(start 360.097324 -102.426516)
		(end 360.097324 -101.34092)
		(width 0.1143)
		(layer "In9.Cu")
		(net "P3E_CPU0_PE1_PCH_CON_RXN<14>")
	)
	(segment
		(start 444.962534 -13.126466)
		(end 445.052196 -12.9921)
		(width 0.1143)
		(layer "In9.Cu")
		(net "P3E_CPU0_PE1_PCH_CON_RXN<14>")
	)
	(segment
		(start 356.9208 -68.56984)
		(end 357.191564 -67.728084)
		(width 0.1143)
		(layer "In9.Cu")
		(net "P3E_CPU0_PE1_PCH_CON_RXN<14>")
	)
	(segment
		(start 439.473594 -12.355322)
		(end 439.538364 -12.039092)
		(width 0.1143)
		(layer "In9.Cu")
		(net "P3E_CPU0_PE1_PCH_CON_RXN<14>")
	)
	(segment
		(start 421.415464 -11.92784)
		(end 424.805094 -11.20648)
		(width 0.1143)
		(layer "In9.Cu")
		(net "P3E_CPU0_PE1_PCH_CON_RXN<14>")
	)
	(segment
		(start 360.161078 -48.499014)
		(end 362.943648 -43.707304)
		(width 0.1143)
		(layer "In9.Cu")
		(net "P3E_CPU0_PE1_PCH_CON_RXN<14>")
	)
	(segment
		(start 360.14533 -116.911882)
		(end 360.438954 -115.529106)
		(width 0.1143)
		(layer "In9.Cu")
		(net "P3E_CPU0_PE1_PCH_CON_RXN<14>")
	)
	(segment
		(start 426.220128 -11.101324)
		(end 427.19498 -11.300206)
		(width 0.1143)
		(layer "In9.Cu")
		(net "P3E_CPU0_PE1_PCH_CON_RXN<14>")
	)
	(segment
		(start 432.298348 -11.495532)
		(end 432.778408 -11.812524)
		(width 0.1143)
		(layer "In9.Cu")
		(net "P3E_CPU0_PE1_PCH_CON_RXN<14>")
	)
	(segment
		(start 369.157504 -28.72613)
		(end 369.24996 -28.26385)
		(width 0.1143)
		(layer "In9.Cu")
		(net "P3E_CPU0_PE1_PCH_CON_RXN<14>")
	)
	(segment
		(start 368.945922 -30.959044)
		(end 368.899948 -30.729936)
		(width 0.1143)
		(layer "In9.Cu")
		(net "P3E_CPU0_PE1_PCH_CON_RXN<14>")
	)
	(segment
		(start 360.383074 -114.997738)
		(end 360.578908 -114.870738)
		(width 0.1143)
		(layer "In9.Cu")
		(net "P3E_CPU0_PE1_PCH_CON_RXN<14>")
	)
	(segment
		(start 347.584014 -125.151642)
		(end 347.584014 -125.500892)
		(width 0.1143)
		(layer "In9.Cu")
		(net "P3E_CPU0_PE1_PCH_CON_RXN<14>")
	)
	(segment
		(start 377.632214 -15.127732)
		(end 379.423676 -14.746478)
		(width 0.1143)
		(layer "In9.Cu")
		(net "P3E_CPU0_PE1_PCH_CON_RXN<14>")
	)
	(segment
		(start 347.944186 -125.615192)
		(end 348.188534 -125.370844)
		(width 0.1143)
		(layer "In9.Cu")
		(net "P3E_CPU0_PE1_PCH_CON_RXN<14>")
	)
	(segment
		(start 359.165652 -103.620316)
		(end 358.88041 -103.335074)
		(width 0.1143)
		(layer "In9.Cu")
		(net "P3E_CPU0_PE1_PCH_CON_RXN<14>")
	)
	(segment
		(start 414.585658 -12.109196)
		(end 418.543994 -11.317224)
		(width 0.1143)
		(layer "In9.Cu")
		(net "P3E_CPU0_PE1_PCH_CON_RXN<14>")
	)
	(segment
		(start 359.392982 -52.416202)
		(end 359.3338 -52.1208)
		(width 0.1143)
		(layer "In9.Cu")
		(net "P3E_CPU0_PE1_PCH_CON_RXN<14>")
	)
	(segment
		(start 438.220104 -12.215114)
		(end 439.339228 -12.444222)
		(width 0.1143)
		(layer "In9.Cu")
		(net "P3E_CPU0_PE1_PCH_CON_RXN<14>")
	)
	(segment
		(start 448.957954 -8.911082)
		(end 448.257422 -7.210298)
		(width 0.1143)
		(layer "In9.Cu")
		(net "P3E_CPU0_PE1_PCH_CON_RXN<14>")
	)
	(segment
		(start 443.034674 -12.883896)
		(end 443.133734 -13.37691)
		(width 0.1143)
		(layer "In9.Cu")
		(net "P3E_CPU0_PE1_PCH_CON_RXN<14>")
	)
	(segment
		(start 360.578908 -114.870738)
		(end 360.650028 -114.535204)
		(width 0.1143)
		(layer "In9.Cu")
		(net "P3E_CPU0_PE1_PCH_CON_RXN<14>")
	)
	(segment
		(start 359.880916 -58.617104)
		(end 358.881934 -53.915056)
		(width 0.1143)
		(layer "In9.Cu")
		(net "P3E_CPU0_PE1_PCH_CON_RXN<14>")
	)
	(segment
		(start 360.438954 -115.529106)
		(end 360.3117 -115.333272)
		(width 0.1143)
		(layer "In9.Cu")
		(net "P3E_CPU0_PE1_PCH_CON_RXN<14>")
	)
	(segment
		(start 440.55919 -12.248134)
		(end 440.49442 -12.56411)
		(width 0.1143)
		(layer "In9.Cu")
		(net "P3E_CPU0_PE1_PCH_CON_RXN<14>")
	)
	(segment
		(start 360.347006 -49.33315)
		(end 360.462068 -49.135284)
		(width 0.1143)
		(layer "In9.Cu")
		(net "P3E_CPU0_PE1_PCH_CON_RXN<14>")
	)
	(segment
		(start 358.270048 -66.202306)
		(end 359.880916 -58.617104)
		(width 0.1143)
		(layer "In9.Cu")
		(net "P3E_CPU0_PE1_PCH_CON_RXN<14>")
	)
	(segment
		(start 440.49442 -12.56411)
		(end 440.58332 -12.69873)
		(width 0.1143)
		(layer "In9.Cu")
		(net "P3E_CPU0_PE1_PCH_CON_RXN<14>")
	)
	(segment
		(start 367.820702 -32.647636)
		(end 368.945922 -30.959044)
		(width 0.1143)
		(layer "In9.Cu")
		(net "P3E_CPU0_PE1_PCH_CON_RXN<14>")
	)
	(segment
		(start 360.420412 -48.979074)
		(end 360.26471 -48.88865)
		(width 0.1143)
		(layer "In9.Cu")
		(net "P3E_CPU0_PE1_PCH_CON_RXN<14>")
	)
	(segment
		(start 359.67797 -82.12328)
		(end 359.67797 -76.414376)
		(width 0.1143)
		(layer "In9.Cu")
		(net "P3E_CPU0_PE1_PCH_CON_RXN<14>")
	)
	(segment
		(start 357.194358 -69.943726)
		(end 356.9208 -68.56984)
		(width 0.1143)
		(layer "In9.Cu")
		(net "P3E_CPU0_PE1_PCH_CON_RXN<14>")
	)
	(segment
		(start 369.93322 -27.992832)
		(end 370.718842 -24.065738)
		(width 0.1143)
		(layer "In9.Cu")
		(net "P3E_CPU0_PE1_PCH_CON_RXN<14>")
	)
	(segment
		(start 358.881934 -53.915056)
		(end 359.392982 -52.416202)
		(width 0.1143)
		(layer "In9.Cu")
		(net "P3E_CPU0_PE1_PCH_CON_RXN<14>")
	)
	(segment
		(start 369.594892 -29.104082)
		(end 369.381786 -29.06141)
		(width 0.1143)
		(layer "In9.Cu")
		(net "P3E_CPU0_PE1_PCH_CON_RXN<14>")
	)
	(segment
		(start 369.6843 -29.238194)
		(end 369.594892 -29.104082)
		(width 0.1143)
		(layer "In9.Cu")
		(net "P3E_CPU0_PE1_PCH_CON_RXN<14>")
	)
	(segment
		(start 443.582044 -13.286994)
		(end 443.482984 -12.79398)
		(width 0.1143)
		(layer "In9.Cu")
		(net "P3E_CPU0_PE1_PCH_CON_RXN<14>")
	)
	(segment
		(start 437.54675 -12.349988)
		(end 437.547258 -12.34948)
		(width 0.1143)
		(layer "In9.Cu")
		(net "P3E_CPU0_PE1_PCH_CON_RXN<14>")
	)
	(segment
		(start 427.19498 -11.300206)
		(end 427.569884 -11.548364)
		(width 0.1143)
		(layer "In9.Cu")
		(net "P3E_CPU0_PE1_PCH_CON_RXN<14>")
	)
	(segment
		(start 358.88041 -104.909874)
		(end 358.88041 -104.400858)
		(width 0.1143)
		(layer "In9.Cu")
		(net "P3E_CPU0_PE1_PCH_CON_RXN<14>")
	)
	(segment
		(start 443.706758 -12.458192)
		(end 444.169292 -12.365228)
		(width 0.1143)
		(layer "In9.Cu")
		(net "P3E_CPU0_PE1_PCH_CON_RXN<14>")
	)
	(segment
		(start 359.983024 -105.195116)
		(end 359.165652 -105.195116)
		(width 0.1143)
		(layer "In9.Cu")
		(net "P3E_CPU0_PE1_PCH_CON_RXN<14>")
	)
	(segment
		(start 369.509294 -30.113478)
		(end 369.6843 -29.238194)
		(width 0.1143)
		(layer "In9.Cu")
		(net "P3E_CPU0_PE1_PCH_CON_RXN<14>")
	)
	(segment
		(start 360.097324 -105.309416)
		(end 359.983024 -105.195116)
		(width 0.1143)
		(layer "In9.Cu")
		(net "P3E_CPU0_PE1_PCH_CON_RXN<14>")
	)
	(segment
		(start 359.00995 -98.14687)
		(end 359.00995 -92.929964)
		(width 0.1143)
		(layer "In9.Cu")
		(net "P3E_CPU0_PE1_PCH_CON_RXN<14>")
	)
	(segment
		(start 439.875168 -11.816842)
		(end 440.33694 -11.91133)
		(width 0.1143)
		(layer "In9.Cu")
		(net "P3E_CPU0_PE1_PCH_CON_RXN<14>")
	)
	(segment
		(start 358.88041 -104.400858)
		(end 359.165652 -104.115616)
		(width 0.1143)
		(layer "In9.Cu")
		(net "P3E_CPU0_PE1_PCH_CON_RXN<14>")
	)
	(segment
		(start 443.492382 -13.42136)
		(end 443.582044 -13.286994)
		(width 0.1143)
		(layer "In9.Cu")
		(net "P3E_CPU0_PE1_PCH_CON_RXN<14>")
	)
	(segment
		(start 437.547258 -12.34948)
		(end 437.547512 -12.34948)
		(width 0.1143)
		(layer "In9.Cu")
		(net "P3E_CPU0_PE1_PCH_CON_RXN<14>")
	)
	(segment
		(start 444.738252 -13.171678)
		(end 444.962534 -13.126466)
		(width 0.1143)
		(layer "In9.Cu")
		(net "P3E_CPU0_PE1_PCH_CON_RXN<14>")
	)
	(segment
		(start 444.169292 -12.365228)
		(end 444.504826 -12.589002)
		(width 0.1143)
		(layer "In9.Cu")
		(net "P3E_CPU0_PE1_PCH_CON_RXN<14>")
	)
	(segment
		(start 368.899948 -30.729936)
		(end 369.090194 -30.444694)
		(width 0.1143)
		(layer "In9.Cu")
		(net "P3E_CPU0_PE1_PCH_CON_RXN<14>")
	)
	(segment
		(start 369.090194 -30.444694)
		(end 369.319048 -30.39872)
		(width 0.1143)
		(layer "In9.Cu")
		(net "P3E_CPU0_PE1_PCH_CON_RXN<14>")
	)
	(segment
		(start 443.133734 -13.37691)
		(end 443.2681 -13.466572)
		(width 0.1143)
		(layer "In9.Cu")
		(net "P3E_CPU0_PE1_PCH_CON_RXN<14>")
	)
	(segment
		(start 391.52068 -14.25067)
		(end 408.08656 -10.729468)
		(width 0.1143)
		(layer "In9.Cu")
		(net "P3E_CPU0_PE1_PCH_CON_RXN<14>")
	)
	(segment
		(start 446.73012 -11.85164)
		(end 448.128136 -10.845546)
		(width 0.1143)
		(layer "In9.Cu")
		(net "P3E_CPU0_PE1_PCH_CON_RXN<14>")
	)
	(segment
		(start 359.165652 -105.195116)
		(end 358.88041 -104.909874)
		(width 0.1143)
		(layer "In9.Cu")
		(net "P3E_CPU0_PE1_PCH_CON_RXN<14>")
	)
	(segment
		(start 360.3117 -115.333272)
		(end 360.383074 -114.997738)
		(width 0.1143)
		(layer "In9.Cu")
		(net "P3E_CPU0_PE1_PCH_CON_RXN<14>")
	)
	(segment
		(start 344.694764 -121.753884)
		(end 344.963496 -121.32564)
		(width 0.1143)
		(layer "In9.Cu")
		(net "P3E_CPU0_PE1_PCH_CON_RXN<14>")
	)
	(segment
		(start 364.25886 -37.034978)
		(end 367.820702 -32.647636)
		(width 0.1143)
		(layer "In9.Cu")
		(net "P3E_CPU0_PE1_PCH_CON_RXN<14>")
	)
	(segment
		(start 432.778408 -11.812524)
		(end 436.48122 -12.56665)
		(width 0.1143)
		(layer "In9.Cu")
		(net "P3E_CPU0_PE1_PCH_CON_RXN<14>")
	)
	(segment
		(start 369.319048 -30.39872)
		(end 369.509294 -30.113478)
		(width 0.1143)
		(layer "In9.Cu")
		(net "P3E_CPU0_PE1_PCH_CON_RXN<14>")
	)
	(segment
		(start 359.983024 -103.620316)
		(end 359.165652 -103.620316)
		(width 0.1143)
		(layer "In9.Cu")
		(net "P3E_CPU0_PE1_PCH_CON_RXN<14>")
	)
	(segment
		(start 369.24996 -28.26385)
		(end 369.585748 -28.039822)
		(width 0.1143)
		(layer "In9.Cu")
		(net "P3E_CPU0_PE1_PCH_CON_RXN<14>")
	)
	(segment
		(start 360.172 -82.61731)
		(end 359.67797 -82.12328)
		(width 0.1143)
		(layer "In9.Cu")
		(net "P3E_CPU0_PE1_PCH_CON_RXN<14>")
	)
	(segment
		(start 445.052196 -12.9921)
		(end 444.953136 -12.499086)
		(width 0.1143)
		(layer "In9.Cu")
		(net "P3E_CPU0_PE1_PCH_CON_RXN<14>")
	)
	(segment
		(start 428.701708 -11.778488)
		(end 431.190908 -11.272266)
		(width 0.1143)
		(layer "In9.Cu")
		(net "P3E_CPU0_PE1_PCH_CON_RXN<14>")
	)
	(segment
		(start 344.963496 -121.32564)
		(end 346.060014 -120.700292)
		(width 0.1143)
		(layer "In9.Cu")
		(net "P3E_CPU0_PE1_PCH_CON_RXN<14>")
	)
	(segment
		(start 359.3338 -52.1208)
		(end 359.04424 -50.671476)
		(width 0.1143)
		(layer "In9.Cu")
		(net "P3E_CPU0_PE1_PCH_CON_RXN<14>")
	)
	(segment
		(start 441.529724 -12.892532)
		(end 441.531502 -12.892532)
		(width 0.1143)
		(layer "In9.Cu")
		(net "P3E_CPU0_PE1_PCH_CON_RXN<14>")
	)
	(segment
		(start 439.339228 -12.444222)
		(end 439.40603 -12.400026)
		(width 0.1143)
		(layer "In9.Cu")
		(net "P3E_CPU0_PE1_PCH_CON_RXN<14>")
	)
	(segment
		(start 380.152656 -14.901672)
		(end 387.368034 -13.368782)
		(width 0.1143)
		(layer "In9.Cu")
		(net "P3E_CPU0_PE1_PCH_CON_RXN<14>")
	)
	(segment
		(start 443.482984 -12.79398)
		(end 443.706758 -12.458192)
		(width 0.1143)
		(layer "In9.Cu")
		(net "P3E_CPU0_PE1_PCH_CON_RXN<14>")
	)
	(segment
		(start 358.88041 -102.826058)
		(end 359.165652 -102.540816)
		(width 0.1143)
		(layer "In9.Cu")
		(net "P3E_CPU0_PE1_PCH_CON_RXN<14>")
	)
	(segment
		(start 360.097324 -101.34092)
		(end 359.74274 -100.986336)
		(width 0.1143)
		(layer "In9.Cu")
		(net "P3E_CPU0_PE1_PCH_CON_RXN<14>")
	)
	(segment
		(start 448.128136 -10.845546)
		(end 448.76212 -9.80567)
		(width 0.1143)
		(layer "In9.Cu")
		(net "P3E_CPU0_PE1_PCH_CON_RXN<14>")
	)
	(segment
		(start 347.724476 -124.510292)
		(end 345.240356 -124.510292)
		(width 0.1143)
		(layer "In9.Cu")
		(net "P3E_CPU0_PE1_PCH_CON_RXN<14>")
	)
	(segment
		(start 359.74274 -100.986336)
		(end 359.74274 -98.87966)
		(width 0.1143)
		(layer "In9.Cu")
		(net "P3E_CPU0_PE1_PCH_CON_RXN<14>")
	)
	(segment
		(start 444.603886 -13.082016)
		(end 444.738252 -13.171678)
		(width 0.1143)
		(layer "In9.Cu")
		(net "P3E_CPU0_PE1_PCH_CON_RXN<14>")
	)
	(segment
		(start 431.190908 -11.272266)
		(end 432.298348 -11.495532)
		(width 0.1143)
		(layer "In9.Cu")
		(net "P3E_CPU0_PE1_PCH_CON_RXN<14>")
	)
	(segment
		(start 360.190796 -49.374806)
		(end 360.347006 -49.33315)
		(width 0.1143)
		(layer "In9.Cu")
		(net "P3E_CPU0_PE1_PCH_CON_RXN<14>")
	)
	(segment
		(start 360.097324 -103.734616)
		(end 359.983024 -103.620316)
		(width 0.1143)
		(layer "In9.Cu")
		(net "P3E_CPU0_PE1_PCH_CON_RXN<14>")
	)
	(segment
		(start 359.04424 -50.671476)
		(end 359.119932 -50.292508)
		(width 0.1143)
		(layer "In9.Cu")
		(net "P3E_CPU0_PE1_PCH_CON_RXN<14>")
	)
	(segment
		(start 370.718842 -24.065738)
		(end 375.911872 -16.274288)
		(width 0.1143)
		(layer "In9.Cu")
		(net "P3E_CPU0_PE1_PCH_CON_RXN<14>")
	)
	(segment
		(start 360.861102 -113.541302)
		(end 360.097324 -109.946694)
		(width 0.1143)
		(layer "In9.Cu")
		(net "P3E_CPU0_PE1_PCH_CON_RXN<14>")
	)
	(segment
		(start 359.067862 -74.001376)
		(end 357.194358 -69.943726)
		(width 0.1143)
		(layer "In9.Cu")
		(net "P3E_CPU0_PE1_PCH_CON_RXN<14>")
	)
	(segment
		(start 442.698886 -12.659868)
		(end 443.034674 -12.883896)
		(width 0.1143)
		(layer "In9.Cu")
		(net "P3E_CPU0_PE1_PCH_CON_RXN<14>")
	)
	(segment
		(start 359.67797 -76.414376)
		(end 359.067862 -74.001376)
		(width 0.1143)
		(layer "In9.Cu")
		(net "P3E_CPU0_PE1_PCH_CON_RXN<14>")
	)
	(segment
		(start 436.48122 -12.56665)
		(end 437.54675 -12.349988)
		(width 0.1143)
		(layer "In9.Cu")
		(net "P3E_CPU0_PE1_PCH_CON_RXN<14>")
	)
	(segment
		(start 424.805094 -11.20648)
		(end 425.253404 -11.29792)
		(width 0.1143)
		(layer "In9.Cu")
		(net "P3E_CPU0_PE1_PCH_CON_RXN<14>")
	)
	(segment
		(start 359.119932 -50.292508)
		(end 359.645458 -49.38776)
		(width 0.1143)
		(layer "In9.Cu")
		(net "P3E_CPU0_PE1_PCH_CON_RXN<14>")
	)
	(segment
		(start 418.543994 -11.317224)
		(end 421.415464 -11.92784)
		(width 0.1143)
		(layer "In9.Cu")
		(net "P3E_CPU0_PE1_PCH_CON_RXN<14>")
	)
	(segment
		(start 437.547512 -12.34948)
		(end 437.55056 -12.348464)
		(width 0.1143)
		(layer "In9.Cu")
		(net "P3E_CPU0_PE1_PCH_CON_RXN<14>")
	)
	(segment
		(start 345.240356 -124.510292)
		(end 344.694764 -123.9647)
		(width 0.1143)
		(layer "In9.Cu")
		(net "P3E_CPU0_PE1_PCH_CON_RXN<14>")
	)
	(segment
		(start 379.423676 -14.746478)
		(end 380.152656 -14.901672)
		(width 0.1143)
		(layer "In9.Cu")
		(net "P3E_CPU0_PE1_PCH_CON_RXN<14>")
	)
	(segment
		(start 346.060014 -120.700292)
		(end 358.704896 -118.011956)
		(width 0.1143)
		(layer "In9.Cu")
		(net "P3E_CPU0_PE1_PCH_CON_RXN<14>")
	)
	(segment
		(start 347.698314 -125.615192)
		(end 347.944186 -125.615192)
		(width 0.1143)
		(layer "In9.Cu")
		(net "P3E_CPU0_PE1_PCH_CON_RXN<14>")
	)
	(segment
		(start 425.253404 -11.29792)
		(end 426.220128 -11.101324)
		(width 0.1143)
		(layer "In9.Cu")
		(net "P3E_CPU0_PE1_PCH_CON_RXN<14>")
	)
	(segment
		(start 369.381786 -29.06141)
		(end 369.157504 -28.72613)
		(width 0.1143)
		(layer "In9.Cu")
		(net "P3E_CPU0_PE1_PCH_CON_RXN<14>")
	)
	(segment
		(start 408.08656 -10.729468)
		(end 414.585658 -12.109196)
		(width 0.1143)
		(layer "In9.Cu")
		(net "P3E_CPU0_PE1_PCH_CON_RXN<14>")
	)
	(segment
		(start 441.531502 -12.892532)
		(end 442.698886 -12.659868)
		(width 0.1143)
		(layer "In9.Cu")
		(net "P3E_CPU0_PE1_PCH_CON_RXN<14>")
	)
	(segment
		(start 360.789982 -113.876836)
		(end 360.861102 -113.541302)
		(width 0.1143)
		(layer "In9.Cu")
		(net "P3E_CPU0_PE1_PCH_CON_RXN<14>")
	)
	(segment
		(start 359.165652 -102.540816)
		(end 359.983024 -102.540816)
		(width 0.1143)
		(layer "In9.Cu")
		(net "P3E_CPU0_PE1_PCH_CON_RXN<14>")
	)
	(segment
		(start 440.33694 -11.91133)
		(end 440.55919 -12.248134)
		(width 0.1143)
		(layer "In9.Cu")
		(net "P3E_CPU0_PE1_PCH_CON_RXN<14>")
	)
	(segment
		(start 360.097324 -104.001316)
		(end 360.097324 -103.734616)
		(width 0.1143)
		(layer "In9.Cu")
		(net "P3E_CPU0_PE1_PCH_CON_RXN<14>")
	)
	(segment
		(start 443.2681 -13.466572)
		(end 443.492382 -13.42136)
		(width 0.1143)
		(layer "In9.Cu")
		(net "P3E_CPU0_PE1_PCH_CON_RXN<14>")
	)
	(segment
		(start 360.650028 -114.535204)
		(end 360.522774 -114.33937)
		(width 0.1143)
		(layer "In9.Cu")
		(net "P3E_CPU0_PE1_PCH_CON_RXN<14>")
	)
	(segment
		(start 427.569884 -11.548364)
		(end 428.701708 -11.778488)
		(width 0.1143)
		(layer "In9.Cu")
		(net "P3E_CPU0_PE1_PCH_CON_RXN<14>")
	)
	(segment
		(start 360.522774 -114.33937)
		(end 360.594148 -114.003836)
		(width 0.1143)
		(layer "In9.Cu")
		(net "P3E_CPU0_PE1_PCH_CON_RXN<14>")
	)
	(segment
		(start 360.097324 -109.946694)
		(end 360.097324 -105.309416)
		(width 0.1143)
		(layer "In9.Cu")
		(net "P3E_CPU0_PE1_PCH_CON_RXN<14>")
	)
	(segment
		(start 360.26471 -48.88865)
		(end 360.161078 -48.499014)
		(width 0.1143)
		(layer "In9.Cu")
		(net "P3E_CPU0_PE1_PCH_CON_RXN<14>")
	)
	(segment
		(start 358.704896 -118.011956)
		(end 360.14533 -116.911882)
		(width 0.1143)
		(layer "In9.Cu")
		(net "P3E_CPU0_PE1_PCH_CON_RXN<14>")
	)
	(segment
		(start 437.55056 -12.348464)
		(end 438.220104 -12.215114)
		(width 0.1143)
		(layer "In9.Cu")
		(net "P3E_CPU0_PE1_PCH_CON_RXN<14>")
	)
	(segment
		(start 359.00995 -92.929964)
		(end 360.172 -91.767914)
		(width 0.1143)
		(layer "In9.Cu")
		(net "P3E_CPU0_PE1_PCH_CON_RXN<14>")
	)
	(segment
		(start 369.585748 -28.039822)
		(end 369.799108 -28.082494)
		(width 0.1143)
		(layer "In9.Cu")
		(net "P3E_CPU0_PE1_PCH_CON_RXN<14>")
	)
	(segment
		(start 360.594148 -114.003836)
		(end 360.789982 -113.876836)
		(width 0.1143)
		(layer "In9.Cu")
		(net "P3E_CPU0_PE1_PCH_CON_RXN<14>")
	)
	(segment
		(start 444.504826 -12.589002)
		(end 444.603886 -13.082016)
		(width 0.1143)
		(layer "In9.Cu")
		(net "P3E_CPU0_PE1_PCH_CON_RXN<14>")
	)
	(segment
		(start 448.257422 -7.210298)
		(end 448.257422 -6.462522)
		(width 0.1143)
		(layer "In9.Cu")
		(net "P3E_CPU0_PE1_PCH_CON_RXN<14>")
	)
	(segment
		(start 359.645458 -49.38776)
		(end 360.035094 -49.284128)
		(width 0.1143)
		(layer "In9.Cu")
		(net "P3E_CPU0_PE1_PCH_CON_RXN<14>")
	)
	(segment
		(start 439.40603 -12.400026)
		(end 439.406284 -12.399772)
		(width 0.1143)
		(layer "In9.Cu")
		(net "P3E_CPU0_PE1_PCH_CON_RXN<14>")
	)
	(segment
		(start 444.953136 -12.499086)
		(end 445.17691 -12.163552)
		(width 0.1143)
		(layer "In9.Cu")
		(net "P3E_CPU0_PE1_PCH_CON_RXN<14>")
	)
	(segment
		(start 360.035094 -49.284128)
		(end 360.190796 -49.374806)
		(width 0.1143)
		(layer "In9.Cu")
		(net "P3E_CPU0_PE1_PCH_CON_RXN<14>")
	)
	(segment
		(start 348.188534 -125.370844)
		(end 348.188534 -124.97435)
		(width 0.1143)
		(layer "In9.Cu")
		(net "P3E_CPU0_PE1_PCH_CON_RXN<14>")
	)
	(segment
		(start 439.406284 -12.399772)
		(end 439.473594 -12.355322)
		(width 0.1143)
		(layer "In9.Cu")
		(net "P3E_CPU0_PE1_PCH_CON_RXN<14>")
	)
	(segment
		(start 360.172 -91.767914)
		(end 360.172 -82.61731)
		(width 0.1143)
		(layer "In9.Cu")
		(net "P3E_CPU0_PE1_PCH_CON_RXN<14>")
	)
	(segment
		(start 448.76212 -9.80567)
		(end 448.957954 -8.911082)
		(width 0.1143)
		(layer "In9.Cu")
		(net "P3E_CPU0_PE1_PCH_CON_RXN<14>")
	)
	(segment
		(start 358.88041 -103.335074)
		(end 358.88041 -102.826058)
		(width 0.1143)
		(layer "In9.Cu")
		(net "P3E_CPU0_PE1_PCH_CON_RXN<14>")
	)
	(segment
		(start 347.584014 -125.500892)
		(end 347.698314 -125.615192)
		(width 0.1143)
		(layer "In9.Cu")
		(net "P3E_CPU0_PE1_PCH_CON_RXN<14>")
	)
	(segment
		(start 362.943648 -43.707304)
		(end 364.25886 -37.034978)
		(width 0.1143)
		(layer "In9.Cu")
		(net "P3E_CPU0_PE1_PCH_CON_RXN<14>")
	)
	(segment
		(start 357.191564 -67.728084)
		(end 358.270048 -66.202306)
		(width 0.1143)
		(layer "In9.Cu")
		(net "P3E_CPU0_PE1_PCH_CON_RXN<14>")
	)
	(segment
		(start 360.462068 -49.135284)
		(end 360.420412 -48.979074)
		(width 0.1143)
		(layer "In9.Cu")
		(net "P3E_CPU0_PE1_PCH_CON_RXN<14>")
	)
	(segment
		(start 445.17691 -12.163552)
		(end 446.73012 -11.85164)
		(width 0.1143)
		(layer "In9.Cu")
		(net "P3E_CPU0_PE1_PCH_CON_RXN<14>")
	)
	(segment
		(start 359.74274 -98.87966)
		(end 359.00995 -98.14687)
		(width 0.1143)
		(layer "In9.Cu")
		(net "P3E_CPU0_PE1_PCH_CON_RXN<14>")
	)
	(segment
		(start 348.188534 -124.97435)
		(end 347.724476 -124.510292)
		(width 0.1143)
		(layer "In9.Cu")
		(net "P3E_CPU0_PE1_PCH_CON_RXN<14>")
	)
	(segment
		(start 359.983024 -104.115616)
		(end 360.097324 -104.001316)
		(width 0.1143)
		(layer "In9.Cu")
		(net "P3E_CPU0_PE1_PCH_CON_RXN<14>")
	)
	(segment
		(start 375.911872 -16.274288)
		(end 377.632214 -15.127732)
		(width 0.1143)
		(layer "In9.Cu")
		(net "P3E_CPU0_PE1_PCH_CON_RXN<14>")
	)
	(segment
		(start 444.030608 -5.892038)
		(end 443.718696 -5.892038)
		(width 0.1143)
		(layer "F.Cu")
		(net "P3E_CPU0_PE1_PCH_CON_RXN<13>")
	)
	(segment
		(start 443.467744 -5.146294)
		(end 443.676786 -4.937252)
		(width 0.1143)
		(layer "F.Cu")
		(net "P3E_CPU0_PE1_PCH_CON_RXN<13>")
	)
	(segment
		(start 443.467744 -5.641086)
		(end 443.467744 -5.146294)
		(width 0.1143)
		(layer "F.Cu")
		(net "P3E_CPU0_PE1_PCH_CON_RXN<13>")
	)
	(segment
		(start 443.676786 -4.937252)
		(end 443.676786 -4.386072)
		(width 0.1143)
		(layer "F.Cu")
		(net "P3E_CPU0_PE1_PCH_CON_RXN<13>")
	)
	(segment
		(start 443.718696 -5.892038)
		(end 443.467744 -5.641086)
		(width 0.1143)
		(layer "F.Cu")
		(net "P3E_CPU0_PE1_PCH_CON_RXN<13>")
	)
	(via
		(at 347.050614 -122.383042)
		(size 0.508)
		(drill 0.254)
		(layers "F.Cu" "B.Cu")
		(net "P3E_CPU0_PE1_PCH_CON_RXN<13>")
	)
	(via
		(at 444.030608 -5.892038)
		(size 0.508)
		(drill 0.254)
		(layers "F.Cu" "B.Cu")
		(net "P3E_CPU0_PE1_PCH_CON_RXN<13>")
	)
	(segment
		(start 347.126814 -122.459242)
		(end 347.050614 -122.383042)
		(width 0.10795)
		(layer "B.Cu")
		(net "P3E_CPU0_PE1_PCH_CON_RXN<13>")
	)
	(segment
		(start 347.711014 -122.459242)
		(end 347.126814 -122.459242)
		(width 0.10795)
		(layer "B.Cu")
		(net "P3E_CPU0_PE1_PCH_CON_RXN<13>")
	)
	(segment
		(start 449.698364 -9.227566)
		(end 450.296026 -6.415024)
		(width 0.1143)
		(layer "In9.Cu")
		(net "P3E_CPU0_PE1_PCH_CON_RXN<13>")
	)
	(segment
		(start 360.910632 -108.666026)
		(end 360.910632 -108.323126)
		(width 0.1143)
		(layer "In9.Cu")
		(net "P3E_CPU0_PE1_PCH_CON_RXN<13>")
	)
	(segment
		(start 360.745532 -105.783126)
		(end 360.910632 -105.618026)
		(width 0.1143)
		(layer "In9.Cu")
		(net "P3E_CPU0_PE1_PCH_CON_RXN<13>")
	)
	(segment
		(start 429.683672 -12.28598)
		(end 435.690772 -13.499084)
		(width 0.1143)
		(layer "In9.Cu")
		(net "P3E_CPU0_PE1_PCH_CON_RXN<13>")
	)
	(segment
		(start 408.016202 -11.39444)
		(end 414.626044 -12.797282)
		(width 0.1143)
		(layer "In9.Cu")
		(net "P3E_CPU0_PE1_PCH_CON_RXN<13>")
	)
	(segment
		(start 360.745532 -107.142026)
		(end 360.745532 -106.799126)
		(width 0.1143)
		(layer "In9.Cu")
		(net "P3E_CPU0_PE1_PCH_CON_RXN<13>")
	)
	(segment
		(start 350.232472 -120.662192)
		(end 350.465898 -120.662192)
		(width 0.1143)
		(layer "In9.Cu")
		(net "P3E_CPU0_PE1_PCH_CON_RXN<13>")
	)
	(segment
		(start 360.910632 -108.323126)
		(end 360.745532 -108.158026)
		(width 0.1143)
		(layer "In9.Cu")
		(net "P3E_CPU0_PE1_PCH_CON_RXN<13>")
	)
	(segment
		(start 448.618864 -4.472432)
		(end 446.502028 -4.472432)
		(width 0.1143)
		(layer "In9.Cu")
		(net "P3E_CPU0_PE1_PCH_CON_RXN<13>")
	)
	(segment
		(start 421.706548 -12.541504)
		(end 424.784266 -11.90498)
		(width 0.1143)
		(layer "In9.Cu")
		(net "P3E_CPU0_PE1_PCH_CON_RXN<13>")
	)
	(segment
		(start 360.627676 -58.28792)
		(end 359.760266 -54.201568)
		(width 0.1143)
		(layer "In9.Cu")
		(net "P3E_CPU0_PE1_PCH_CON_RXN<13>")
	)
	(segment
		(start 442.778642 -14.375384)
		(end 445.31153 -13.868908)
		(width 0.1143)
		(layer "In9.Cu")
		(net "P3E_CPU0_PE1_PCH_CON_RXN<13>")
	)
	(segment
		(start 427.847506 -12.868656)
		(end 428.169578 -12.934696)
		(width 0.1143)
		(layer "In9.Cu")
		(net "P3E_CPU0_PE1_PCH_CON_RXN<13>")
	)
	(segment
		(start 429.3743 -12.348972)
		(end 429.683672 -12.28598)
		(width 0.1143)
		(layer "In9.Cu")
		(net "P3E_CPU0_PE1_PCH_CON_RXN<13>")
	)
	(segment
		(start 427.373542 -12.554966)
		(end 427.847506 -12.868656)
		(width 0.1143)
		(layer "In9.Cu")
		(net "P3E_CPU0_PE1_PCH_CON_RXN<13>")
	)
	(segment
		(start 424.785028 -11.90498)
		(end 425.192952 -11.987784)
		(width 0.1143)
		(layer "In9.Cu")
		(net "P3E_CPU0_PE1_PCH_CON_RXN<13>")
	)
	(segment
		(start 449.726558 -10.926318)
		(end 449.88226 -10.147808)
		(width 0.1143)
		(layer "In9.Cu")
		(net "P3E_CPU0_PE1_PCH_CON_RXN<13>")
	)
	(segment
		(start 448.59575 -11.679936)
		(end 448.881246 -11.48969)
		(width 0.1143)
		(layer "In9.Cu")
		(net "P3E_CPU0_PE1_PCH_CON_RXN<13>")
	)
	(segment
		(start 347.050614 -122.383042)
		(end 347.4847 -122.817128)
		(width 0.1143)
		(layer "In9.Cu")
		(net "P3E_CPU0_PE1_PCH_CON_RXN<13>")
	)
	(segment
		(start 358.958642 -118.664736)
		(end 360.706162 -117.329712)
		(width 0.1143)
		(layer "In9.Cu")
		(net "P3E_CPU0_PE1_PCH_CON_RXN<13>")
	)
	(segment
		(start 360.910632 -103.82504)
		(end 361.826556 -99.351592)
		(width 0.1143)
		(layer "In9.Cu")
		(net "P3E_CPU0_PE1_PCH_CON_RXN<13>")
	)
	(segment
		(start 370.150136 -30.336744)
		(end 371.351302 -24.386286)
		(width 0.1143)
		(layer "In9.Cu")
		(net "P3E_CPU0_PE1_PCH_CON_RXN<13>")
	)
	(segment
		(start 443.541658 -5.565902)
		(end 443.541658 -5.777738)
		(width 0.1143)
		(layer "In9.Cu")
		(net "P3E_CPU0_PE1_PCH_CON_RXN<13>")
	)
	(segment
		(start 360.9975 -76.4667)
		(end 360.322114 -75.791314)
		(width 0.1143)
		(layer "In9.Cu")
		(net "P3E_CPU0_PE1_PCH_CON_RXN<13>")
	)
	(segment
		(start 360.745532 -108.831126)
		(end 360.910632 -108.666026)
		(width 0.1143)
		(layer "In9.Cu")
		(net "P3E_CPU0_PE1_PCH_CON_RXN<13>")
	)
	(segment
		(start 448.926966 -11.260836)
		(end 449.212208 -11.07059)
		(width 0.1143)
		(layer "In9.Cu")
		(net "P3E_CPU0_PE1_PCH_CON_RXN<13>")
	)
	(segment
		(start 360.949494 -50.71491)
		(end 361.633262 -47.29734)
		(width 0.1143)
		(layer "In9.Cu")
		(net "P3E_CPU0_PE1_PCH_CON_RXN<13>")
	)
	(segment
		(start 421.705786 -12.54125)
		(end 421.706548 -12.541504)
		(width 0.1143)
		(layer "In9.Cu")
		(net "P3E_CPU0_PE1_PCH_CON_RXN<13>")
	)
	(segment
		(start 439.253122 -13.626338)
		(end 442.778642 -14.375384)
		(width 0.1143)
		(layer "In9.Cu")
		(net "P3E_CPU0_PE1_PCH_CON_RXN<13>")
	)
	(segment
		(start 449.88226 -10.147808)
		(end 449.698364 -9.227566)
		(width 0.1143)
		(layer "In9.Cu")
		(net "P3E_CPU0_PE1_PCH_CON_RXN<13>")
	)
	(segment
		(start 360.910632 -107.307126)
		(end 360.745532 -107.142026)
		(width 0.1143)
		(layer "In9.Cu")
		(net "P3E_CPU0_PE1_PCH_CON_RXN<13>")
	)
	(segment
		(start 360.910632 -106.291126)
		(end 360.745532 -106.126026)
		(width 0.1143)
		(layer "In9.Cu")
		(net "P3E_CPU0_PE1_PCH_CON_RXN<13>")
	)
	(segment
		(start 444.124588 -4.977638)
		(end 443.541658 -5.565902)
		(width 0.1143)
		(layer "In9.Cu")
		(net "P3E_CPU0_PE1_PCH_CON_RXN<13>")
	)
	(segment
		(start 357.817166 -69.746876)
		(end 357.593138 -68.589144)
		(width 0.1143)
		(layer "In9.Cu")
		(net "P3E_CPU0_PE1_PCH_CON_RXN<13>")
	)
	(segment
		(start 350.465898 -120.662192)
		(end 350.710246 -120.417844)
		(width 0.1143)
		(layer "In9.Cu")
		(net "P3E_CPU0_PE1_PCH_CON_RXN<13>")
	)
	(segment
		(start 428.63008 -12.841224)
		(end 429.3743 -12.348972)
		(width 0.1143)
		(layer "In9.Cu")
		(net "P3E_CPU0_PE1_PCH_CON_RXN<13>")
	)
	(segment
		(start 448.0814 -11.824208)
		(end 448.366896 -11.634216)
		(width 0.1143)
		(layer "In9.Cu")
		(net "P3E_CPU0_PE1_PCH_CON_RXN<13>")
	)
	(segment
		(start 371.351302 -24.386286)
		(end 376.48007 -16.691102)
		(width 0.1143)
		(layer "In9.Cu")
		(net "P3E_CPU0_PE1_PCH_CON_RXN<13>")
	)
	(segment
		(start 349.271844 -121.62282)
		(end 349.51416 -121.380504)
		(width 0.1143)
		(layer "In9.Cu")
		(net "P3E_CPU0_PE1_PCH_CON_RXN<13>")
	)
	(segment
		(start 360.910632 -105.618026)
		(end 360.910632 -103.82504)
		(width 0.1143)
		(layer "In9.Cu")
		(net "P3E_CPU0_PE1_PCH_CON_RXN<13>")
	)
	(segment
		(start 446.111376 -13.137388)
		(end 446.34023 -13.183108)
		(width 0.1143)
		(layer "In9.Cu")
		(net "P3E_CPU0_PE1_PCH_CON_RXN<13>")
	)
	(segment
		(start 360.910632 -107.650026)
		(end 360.910632 -107.307126)
		(width 0.1143)
		(layer "In9.Cu")
		(net "P3E_CPU0_PE1_PCH_CON_RXN<13>")
	)
	(segment
		(start 421.705786 -12.541504)
		(end 421.705786 -12.54125)
		(width 0.1143)
		(layer "In9.Cu")
		(net "P3E_CPU0_PE1_PCH_CON_RXN<13>")
	)
	(segment
		(start 449.441316 -11.116564)
		(end 449.726558 -10.926318)
		(width 0.1143)
		(layer "In9.Cu")
		(net "P3E_CPU0_PE1_PCH_CON_RXN<13>")
	)
	(segment
		(start 357.593138 -68.589144)
		(end 357.761286 -68.06819)
		(width 0.1143)
		(layer "In9.Cu")
		(net "P3E_CPU0_PE1_PCH_CON_RXN<13>")
	)
	(segment
		(start 435.690772 -13.499084)
		(end 436.366158 -13.948664)
		(width 0.1143)
		(layer "In9.Cu")
		(net "P3E_CPU0_PE1_PCH_CON_RXN<13>")
	)
	(segment
		(start 379.330712 -15.415768)
		(end 380.094744 -15.578328)
		(width 0.1143)
		(layer "In9.Cu")
		(net "P3E_CPU0_PE1_PCH_CON_RXN<13>")
	)
	(segment
		(start 377.954286 -15.70863)
		(end 379.330712 -15.415768)
		(width 0.1143)
		(layer "In9.Cu")
		(net "P3E_CPU0_PE1_PCH_CON_RXN<13>")
	)
	(segment
		(start 443.541658 -5.777738)
		(end 443.655958 -5.892038)
		(width 0.1143)
		(layer "In9.Cu")
		(net "P3E_CPU0_PE1_PCH_CON_RXN<13>")
	)
	(segment
		(start 436.366158 -13.948664)
		(end 437.003952 -14.076172)
		(width 0.1143)
		(layer "In9.Cu")
		(net "P3E_CPU0_PE1_PCH_CON_RXN<13>")
	)
	(segment
		(start 349.51416 -121.380504)
		(end 349.747586 -121.380504)
		(width 0.1143)
		(layer "In9.Cu")
		(net "P3E_CPU0_PE1_PCH_CON_RXN<13>")
	)
	(segment
		(start 376.48007 -16.691102)
		(end 377.954286 -15.70863)
		(width 0.1143)
		(layer "In9.Cu")
		(net "P3E_CPU0_PE1_PCH_CON_RXN<13>")
	)
	(segment
		(start 380.094744 -15.578328)
		(end 387.365494 -14.033754)
		(width 0.1143)
		(layer "In9.Cu")
		(net "P3E_CPU0_PE1_PCH_CON_RXN<13>")
	)
	(segment
		(start 445.31153 -13.868908)
		(end 445.78016 -13.556488)
		(width 0.1143)
		(layer "In9.Cu")
		(net "P3E_CPU0_PE1_PCH_CON_RXN<13>")
	)
	(segment
		(start 348.553532 -122.574558)
		(end 348.553532 -122.341132)
		(width 0.1143)
		(layer "In9.Cu")
		(net "P3E_CPU0_PE1_PCH_CON_RXN<13>")
	)
	(segment
		(start 360.745532 -109.174026)
		(end 360.745532 -108.831126)
		(width 0.1143)
		(layer "In9.Cu")
		(net "P3E_CPU0_PE1_PCH_CON_RXN<13>")
	)
	(segment
		(start 368.013234 -33.542224)
		(end 370.150136 -30.336744)
		(width 0.1143)
		(layer "In9.Cu")
		(net "P3E_CPU0_PE1_PCH_CON_RXN<13>")
	)
	(segment
		(start 350.710246 -120.417844)
		(end 358.958642 -118.664736)
		(width 0.1143)
		(layer "In9.Cu")
		(net "P3E_CPU0_PE1_PCH_CON_RXN<13>")
	)
	(segment
		(start 447.190368 -12.616688)
		(end 447.236088 -12.387834)
		(width 0.1143)
		(layer "In9.Cu")
		(net "P3E_CPU0_PE1_PCH_CON_RXN<13>")
	)
	(segment
		(start 426.788072 -11.888724)
		(end 427.046644 -12.060936)
		(width 0.1143)
		(layer "In9.Cu")
		(net "P3E_CPU0_PE1_PCH_CON_RXN<13>")
	)
	(segment
		(start 361.53725 -113.416334)
		(end 360.910632 -110.466378)
		(width 0.1143)
		(layer "In9.Cu")
		(net "P3E_CPU0_PE1_PCH_CON_RXN<13>")
	)
	(segment
		(start 358.888284 -66.47307)
		(end 360.627676 -58.28792)
		(width 0.1143)
		(layer "In9.Cu")
		(net "P3E_CPU0_PE1_PCH_CON_RXN<13>")
	)
	(segment
		(start 446.502028 -4.472432)
		(end 444.124588 -4.977638)
		(width 0.1143)
		(layer "In9.Cu")
		(net "P3E_CPU0_PE1_PCH_CON_RXN<13>")
	)
	(segment
		(start 445.78016 -13.556488)
		(end 445.826134 -13.327634)
		(width 0.1143)
		(layer "In9.Cu")
		(net "P3E_CPU0_PE1_PCH_CON_RXN<13>")
	)
	(segment
		(start 361.826556 -99.351592)
		(end 361.826556 -95.767652)
		(width 0.1143)
		(layer "In9.Cu")
		(net "P3E_CPU0_PE1_PCH_CON_RXN<13>")
	)
	(segment
		(start 359.72242 -73.8759)
		(end 357.817166 -69.746876)
		(width 0.1143)
		(layer "In9.Cu")
		(net "P3E_CPU0_PE1_PCH_CON_RXN<13>")
	)
	(segment
		(start 357.761286 -68.06819)
		(end 358.888284 -66.47307)
		(width 0.1143)
		(layer "In9.Cu")
		(net "P3E_CPU0_PE1_PCH_CON_RXN<13>")
	)
	(segment
		(start 447.236088 -12.387834)
		(end 447.52133 -12.197588)
		(width 0.1143)
		(layer "In9.Cu")
		(net "P3E_CPU0_PE1_PCH_CON_RXN<13>")
	)
	(segment
		(start 363.481366 -44.524422)
		(end 364.91418 -37.358066)
		(width 0.1143)
		(layer "In9.Cu")
		(net "P3E_CPU0_PE1_PCH_CON_RXN<13>")
	)
	(segment
		(start 447.750438 -12.243562)
		(end 448.03568 -12.053316)
		(width 0.1143)
		(layer "In9.Cu")
		(net "P3E_CPU0_PE1_PCH_CON_RXN<13>")
	)
	(segment
		(start 445.826134 -13.327634)
		(end 446.111376 -13.137388)
		(width 0.1143)
		(layer "In9.Cu")
		(net "P3E_CPU0_PE1_PCH_CON_RXN<13>")
	)
	(segment
		(start 359.760266 -54.201568)
		(end 360.949494 -50.71491)
		(width 0.1143)
		(layer "In9.Cu")
		(net "P3E_CPU0_PE1_PCH_CON_RXN<13>")
	)
	(segment
		(start 418.643562 -11.993626)
		(end 421.460168 -12.592558)
		(width 0.1143)
		(layer "In9.Cu")
		(net "P3E_CPU0_PE1_PCH_CON_RXN<13>")
	)
	(segment
		(start 450.296026 -6.415024)
		(end 450.010022 -5.070348)
		(width 0.1143)
		(layer "In9.Cu")
		(net "P3E_CPU0_PE1_PCH_CON_RXN<13>")
	)
	(segment
		(start 447.52133 -12.197588)
		(end 447.750438 -12.243562)
		(width 0.1143)
		(layer "In9.Cu")
		(net "P3E_CPU0_PE1_PCH_CON_RXN<13>")
	)
	(segment
		(start 425.192952 -11.987784)
		(end 426.235876 -11.775948)
		(width 0.1143)
		(layer "In9.Cu")
		(net "P3E_CPU0_PE1_PCH_CON_RXN<13>")
	)
	(segment
		(start 360.9975 -91.858592)
		(end 360.9975 -76.4667)
		(width 0.1143)
		(layer "In9.Cu")
		(net "P3E_CPU0_PE1_PCH_CON_RXN<13>")
	)
	(segment
		(start 437.003952 -14.076172)
		(end 439.253122 -13.626338)
		(width 0.1143)
		(layer "In9.Cu")
		(net "P3E_CPU0_PE1_PCH_CON_RXN<13>")
	)
	(segment
		(start 448.366896 -11.634216)
		(end 448.59575 -11.679936)
		(width 0.1143)
		(layer "In9.Cu")
		(net "P3E_CPU0_PE1_PCH_CON_RXN<13>")
	)
	(segment
		(start 450.010022 -5.070348)
		(end 448.618864 -4.472432)
		(width 0.1143)
		(layer "In9.Cu")
		(net "P3E_CPU0_PE1_PCH_CON_RXN<13>")
	)
	(segment
		(start 360.322114 -75.791314)
		(end 359.72242 -73.8759)
		(width 0.1143)
		(layer "In9.Cu")
		(net "P3E_CPU0_PE1_PCH_CON_RXN<13>")
	)
	(segment
		(start 424.784266 -11.90498)
		(end 424.785028 -11.90498)
		(width 0.1143)
		(layer "In9.Cu")
		(net "P3E_CPU0_PE1_PCH_CON_RXN<13>")
	)
	(segment
		(start 449.212208 -11.07059)
		(end 449.441316 -11.116564)
		(width 0.1143)
		(layer "In9.Cu")
		(net "P3E_CPU0_PE1_PCH_CON_RXN<13>")
	)
	(segment
		(start 360.745532 -108.158026)
		(end 360.745532 -107.815126)
		(width 0.1143)
		(layer "In9.Cu")
		(net "P3E_CPU0_PE1_PCH_CON_RXN<13>")
	)
	(segment
		(start 426.235876 -11.775948)
		(end 426.788072 -11.888724)
		(width 0.1143)
		(layer "In9.Cu")
		(net "P3E_CPU0_PE1_PCH_CON_RXN<13>")
	)
	(segment
		(start 421.460168 -12.592558)
		(end 421.705786 -12.541504)
		(width 0.1143)
		(layer "In9.Cu")
		(net "P3E_CPU0_PE1_PCH_CON_RXN<13>")
	)
	(segment
		(start 360.745532 -107.815126)
		(end 360.910632 -107.650026)
		(width 0.1143)
		(layer "In9.Cu")
		(net "P3E_CPU0_PE1_PCH_CON_RXN<13>")
	)
	(segment
		(start 361.826556 -95.767652)
		(end 360.9975 -91.858592)
		(width 0.1143)
		(layer "In9.Cu")
		(net "P3E_CPU0_PE1_PCH_CON_RXN<13>")
	)
	(segment
		(start 360.910632 -106.634026)
		(end 360.910632 -106.291126)
		(width 0.1143)
		(layer "In9.Cu")
		(net "P3E_CPU0_PE1_PCH_CON_RXN<13>")
	)
	(segment
		(start 443.655958 -5.892038)
		(end 444.030608 -5.892038)
		(width 0.1143)
		(layer "In9.Cu")
		(net "P3E_CPU0_PE1_PCH_CON_RXN<13>")
	)
	(segment
		(start 348.795848 -122.098816)
		(end 349.029274 -122.098816)
		(width 0.1143)
		(layer "In9.Cu")
		(net "P3E_CPU0_PE1_PCH_CON_RXN<13>")
	)
	(segment
		(start 361.633262 -47.29734)
		(end 363.481366 -44.524422)
		(width 0.1143)
		(layer "In9.Cu")
		(net "P3E_CPU0_PE1_PCH_CON_RXN<13>")
	)
	(segment
		(start 349.271844 -121.856246)
		(end 349.271844 -121.62282)
		(width 0.1143)
		(layer "In9.Cu")
		(net "P3E_CPU0_PE1_PCH_CON_RXN<13>")
	)
	(segment
		(start 360.745532 -106.126026)
		(end 360.745532 -105.783126)
		(width 0.1143)
		(layer "In9.Cu")
		(net "P3E_CPU0_PE1_PCH_CON_RXN<13>")
	)
	(segment
		(start 349.990156 -120.904508)
		(end 350.232472 -120.662192)
		(width 0.1143)
		(layer "In9.Cu")
		(net "P3E_CPU0_PE1_PCH_CON_RXN<13>")
	)
	(segment
		(start 428.169578 -12.934696)
		(end 428.63008 -12.841224)
		(width 0.1143)
		(layer "In9.Cu")
		(net "P3E_CPU0_PE1_PCH_CON_RXN<13>")
	)
	(segment
		(start 446.34023 -13.183108)
		(end 447.190368 -12.616688)
		(width 0.1143)
		(layer "In9.Cu")
		(net "P3E_CPU0_PE1_PCH_CON_RXN<13>")
	)
	(segment
		(start 349.747586 -121.380504)
		(end 349.990156 -121.137934)
		(width 0.1143)
		(layer "In9.Cu")
		(net "P3E_CPU0_PE1_PCH_CON_RXN<13>")
	)
	(segment
		(start 448.881246 -11.48969)
		(end 448.926966 -11.260836)
		(width 0.1143)
		(layer "In9.Cu")
		(net "P3E_CPU0_PE1_PCH_CON_RXN<13>")
	)
	(segment
		(start 360.706162 -117.329712)
		(end 361.53725 -113.416334)
		(width 0.1143)
		(layer "In9.Cu")
		(net "P3E_CPU0_PE1_PCH_CON_RXN<13>")
	)
	(segment
		(start 448.03568 -12.053316)
		(end 448.0814 -11.824208)
		(width 0.1143)
		(layer "In9.Cu")
		(net "P3E_CPU0_PE1_PCH_CON_RXN<13>")
	)
	(segment
		(start 349.029274 -122.098816)
		(end 349.271844 -121.856246)
		(width 0.1143)
		(layer "In9.Cu")
		(net "P3E_CPU0_PE1_PCH_CON_RXN<13>")
	)
	(segment
		(start 360.745532 -106.799126)
		(end 360.910632 -106.634026)
		(width 0.1143)
		(layer "In9.Cu")
		(net "P3E_CPU0_PE1_PCH_CON_RXN<13>")
	)
	(segment
		(start 364.91418 -37.358066)
		(end 368.013234 -33.542224)
		(width 0.1143)
		(layer "In9.Cu")
		(net "P3E_CPU0_PE1_PCH_CON_RXN<13>")
	)
	(segment
		(start 360.910632 -109.339126)
		(end 360.745532 -109.174026)
		(width 0.1143)
		(layer "In9.Cu")
		(net "P3E_CPU0_PE1_PCH_CON_RXN<13>")
	)
	(segment
		(start 348.553532 -122.341132)
		(end 348.795848 -122.098816)
		(width 0.1143)
		(layer "In9.Cu")
		(net "P3E_CPU0_PE1_PCH_CON_RXN<13>")
	)
	(segment
		(start 349.990156 -121.137934)
		(end 349.990156 -120.904508)
		(width 0.1143)
		(layer "In9.Cu")
		(net "P3E_CPU0_PE1_PCH_CON_RXN<13>")
	)
	(segment
		(start 414.626044 -12.797282)
		(end 418.643562 -11.993626)
		(width 0.1143)
		(layer "In9.Cu")
		(net "P3E_CPU0_PE1_PCH_CON_RXN<13>")
	)
	(segment
		(start 391.48512 -14.90853)
		(end 408.016202 -11.39444)
		(width 0.1143)
		(layer "In9.Cu")
		(net "P3E_CPU0_PE1_PCH_CON_RXN<13>")
	)
	(segment
		(start 347.4847 -122.817128)
		(end 348.310962 -122.817128)
		(width 0.1143)
		(layer "In9.Cu")
		(net "P3E_CPU0_PE1_PCH_CON_RXN<13>")
	)
	(segment
		(start 387.365494 -14.033754)
		(end 391.48512 -14.90853)
		(width 0.1143)
		(layer "In9.Cu")
		(net "P3E_CPU0_PE1_PCH_CON_RXN<13>")
	)
	(segment
		(start 427.046644 -12.060936)
		(end 427.373542 -12.554966)
		(width 0.1143)
		(layer "In9.Cu")
		(net "P3E_CPU0_PE1_PCH_CON_RXN<13>")
	)
	(segment
		(start 360.910632 -110.466378)
		(end 360.910632 -109.339126)
		(width 0.1143)
		(layer "In9.Cu")
		(net "P3E_CPU0_PE1_PCH_CON_RXN<13>")
	)
	(segment
		(start 348.310962 -122.817128)
		(end 348.553532 -122.574558)
		(width 0.1143)
		(layer "In9.Cu")
		(net "P3E_CPU0_PE1_PCH_CON_RXN<13>")
	)
	(segment
		(start 441.06211 -5.36448)
		(end 441.276486 -5.150104)
		(width 0.1143)
		(layer "F.Cu")
		(net "P3E_CPU0_PE1_PCH_CON_RXN<12>")
	)
	(segment
		(start 441.276486 -5.150104)
		(end 441.276486 -4.386072)
		(width 0.1143)
		(layer "F.Cu")
		(net "P3E_CPU0_PE1_PCH_CON_RXN<12>")
	)
	(segment
		(start 441.494672 -5.667248)
		(end 441.1472 -5.667248)
		(width 0.1143)
		(layer "F.Cu")
		(net "P3E_CPU0_PE1_PCH_CON_RXN<12>")
	)
	(segment
		(start 441.1472 -5.667248)
		(end 441.06211 -5.582158)
		(width 0.1143)
		(layer "F.Cu")
		(net "P3E_CPU0_PE1_PCH_CON_RXN<12>")
	)
	(segment
		(start 441.06211 -5.582158)
		(end 441.06211 -5.36448)
		(width 0.1143)
		(layer "F.Cu")
		(net "P3E_CPU0_PE1_PCH_CON_RXN<12>")
	)
	(via
		(at 352.105214 -123.780042)
		(size 0.508)
		(drill 0.254)
		(layers "F.Cu" "B.Cu")
		(net "P3E_CPU0_PE1_PCH_CON_RXN<12>")
	)
	(via
		(at 441.494672 -5.667248)
		(size 0.508)
		(drill 0.254)
		(layers "F.Cu" "B.Cu")
		(net "P3E_CPU0_PE1_PCH_CON_RXN<12>")
	)
	(segment
		(start 352.765614 -123.780042)
		(end 352.105214 -123.780042)
		(width 0.10795)
		(layer "B.Cu")
		(net "P3E_CPU0_PE1_PCH_CON_RXN<12>")
	)
	(segment
		(start 429.791876 -13.626338)
		(end 428.792132 -13.829792)
		(width 0.1143)
		(layer "In9.Cu")
		(net "P3E_CPU0_PE1_PCH_CON_RXN<12>")
	)
	(segment
		(start 387.226302 -14.716252)
		(end 379.965204 -16.258794)
		(width 0.1143)
		(layer "In9.Cu")
		(net "P3E_CPU0_PE1_PCH_CON_RXN<12>")
	)
	(segment
		(start 416.549332 -13.07084)
		(end 416.549332 -13.071094)
		(width 0.1143)
		(layer "In9.Cu")
		(net "P3E_CPU0_PE1_PCH_CON_RXN<12>")
	)
	(segment
		(start 450.577204 -4.59105)
		(end 450.96176 -6.39445)
		(width 0.1143)
		(layer "In9.Cu")
		(net "P3E_CPU0_PE1_PCH_CON_RXN<12>")
	)
	(segment
		(start 360.894884 -75.322938)
		(end 361.6325 -76.060554)
		(width 0.1143)
		(layer "In9.Cu")
		(net "P3E_CPU0_PE1_PCH_CON_RXN<12>")
	)
	(segment
		(start 359.340912 -69.052186)
		(end 360.204258 -73.116694)
		(width 0.1143)
		(layer "In9.Cu")
		(net "P3E_CPU0_PE1_PCH_CON_RXN<12>")
	)
	(segment
		(start 361.649772 -50.698908)
		(end 361.131104 -52.219606)
		(width 0.1143)
		(layer "In9.Cu")
		(net "P3E_CPU0_PE1_PCH_CON_RXN<12>")
	)
	(segment
		(start 361.736386 -110.05566)
		(end 361.736386 -111.24311)
		(width 0.1143)
		(layer "In9.Cu")
		(net "P3E_CPU0_PE1_PCH_CON_RXN<12>")
	)
	(segment
		(start 424.995086 -13.635228)
		(end 424.130216 -13.810996)
		(width 0.1143)
		(layer "In9.Cu")
		(net "P3E_CPU0_PE1_PCH_CON_RXN<12>")
	)
	(segment
		(start 441.175648 -5.667248)
		(end 441.03036 -5.52196)
		(width 0.1143)
		(layer "In9.Cu")
		(net "P3E_CPU0_PE1_PCH_CON_RXN<12>")
	)
	(segment
		(start 364.081568 -44.818554)
		(end 362.292646 -47.485554)
		(width 0.1143)
		(layer "In9.Cu")
		(net "P3E_CPU0_PE1_PCH_CON_RXN<12>")
	)
	(segment
		(start 350.896428 -121.130314)
		(end 349.821754 -122.204988)
		(width 0.1143)
		(layer "In9.Cu")
		(net "P3E_CPU0_PE1_PCH_CON_RXN<12>")
	)
	(segment
		(start 441.03036 -5.52196)
		(end 441.03036 -5.224018)
		(width 0.1143)
		(layer "In9.Cu")
		(net "P3E_CPU0_PE1_PCH_CON_RXN<12>")
	)
	(segment
		(start 361.571286 -108.53166)
		(end 361.571286 -108.87456)
		(width 0.1143)
		(layer "In9.Cu")
		(net "P3E_CPU0_PE1_PCH_CON_RXN<12>")
	)
	(segment
		(start 418.638228 -12.653264)
		(end 416.549332 -13.07084)
		(width 0.1143)
		(layer "In9.Cu")
		(net "P3E_CPU0_PE1_PCH_CON_RXN<12>")
	)
	(segment
		(start 361.6325 -76.060554)
		(end 361.6325 -91.48064)
		(width 0.1143)
		(layer "In9.Cu")
		(net "P3E_CPU0_PE1_PCH_CON_RXN<12>")
	)
	(segment
		(start 360.204258 -73.116694)
		(end 360.204258 -73.116948)
		(width 0.1143)
		(layer "In9.Cu")
		(net "P3E_CPU0_PE1_PCH_CON_RXN<12>")
	)
	(segment
		(start 364.775242 -41.350946)
		(end 364.081568 -44.818554)
		(width 0.1143)
		(layer "In9.Cu")
		(net "P3E_CPU0_PE1_PCH_CON_RXN<12>")
	)
	(segment
		(start 361.571286 -106.01579)
		(end 361.571286 -106.35869)
		(width 0.1143)
		(layer "In9.Cu")
		(net "P3E_CPU0_PE1_PCH_CON_RXN<12>")
	)
	(segment
		(start 361.736386 -111.24311)
		(end 362.192316 -113.390426)
		(width 0.1143)
		(layer "In9.Cu")
		(net "P3E_CPU0_PE1_PCH_CON_RXN<12>")
	)
	(segment
		(start 361.736386 -105.50779)
		(end 361.736386 -105.85069)
		(width 0.1143)
		(layer "In9.Cu")
		(net "P3E_CPU0_PE1_PCH_CON_RXN<12>")
	)
	(segment
		(start 441.336938 -4.91744)
		(end 446.428622 -3.837432)
		(width 0.1143)
		(layer "In9.Cu")
		(net "P3E_CPU0_PE1_PCH_CON_RXN<12>")
	)
	(segment
		(start 362.292646 -47.485554)
		(end 361.649772 -50.698908)
		(width 0.1143)
		(layer "In9.Cu")
		(net "P3E_CPU0_PE1_PCH_CON_RXN<12>")
	)
	(segment
		(start 361.736386 -108.36656)
		(end 361.571286 -108.53166)
		(width 0.1143)
		(layer "In9.Cu")
		(net "P3E_CPU0_PE1_PCH_CON_RXN<12>")
	)
	(segment
		(start 448.823588 -3.837432)
		(end 450.577204 -4.59105)
		(width 0.1143)
		(layer "In9.Cu")
		(net "P3E_CPU0_PE1_PCH_CON_RXN<12>")
	)
	(segment
		(start 361.736386 -104.83469)
		(end 361.571286 -104.99979)
		(width 0.1143)
		(layer "In9.Cu")
		(net "P3E_CPU0_PE1_PCH_CON_RXN<12>")
	)
	(segment
		(start 361.736386 -105.85069)
		(end 361.571286 -106.01579)
		(width 0.1143)
		(layer "In9.Cu")
		(net "P3E_CPU0_PE1_PCH_CON_RXN<12>")
	)
	(segment
		(start 376.998992 -17.132554)
		(end 372.032022 -24.584914)
		(width 0.1143)
		(layer "In9.Cu")
		(net "P3E_CPU0_PE1_PCH_CON_RXN<12>")
	)
	(segment
		(start 407.958798 -12.057634)
		(end 391.338562 -15.59052)
		(width 0.1143)
		(layer "In9.Cu")
		(net "P3E_CPU0_PE1_PCH_CON_RXN<12>")
	)
	(segment
		(start 426.542454 -13.066268)
		(end 425.5516 -13.267436)
		(width 0.1143)
		(layer "In9.Cu")
		(net "P3E_CPU0_PE1_PCH_CON_RXN<12>")
	)
	(segment
		(start 365.713772 -40.159686)
		(end 364.775242 -41.350946)
		(width 0.1143)
		(layer "In9.Cu")
		(net "P3E_CPU0_PE1_PCH_CON_RXN<12>")
	)
	(segment
		(start 359.54716 -68.020692)
		(end 359.340912 -69.052186)
		(width 0.1143)
		(layer "In9.Cu")
		(net "P3E_CPU0_PE1_PCH_CON_RXN<12>")
	)
	(segment
		(start 439.888122 -15.865602)
		(end 439.420762 -15.553182)
		(width 0.1143)
		(layer "In9.Cu")
		(net "P3E_CPU0_PE1_PCH_CON_RXN<12>")
	)
	(segment
		(start 378.08662 -16.407638)
		(end 376.998992 -17.132554)
		(width 0.1143)
		(layer "In9.Cu")
		(net "P3E_CPU0_PE1_PCH_CON_RXN<12>")
	)
	(segment
		(start 362.192316 -113.390426)
		(end 361.266486 -117.749828)
		(width 0.1143)
		(layer "In9.Cu")
		(net "P3E_CPU0_PE1_PCH_CON_RXN<12>")
	)
	(segment
		(start 368.494818 -33.976818)
		(end 366.732058 -36.14674)
		(width 0.1143)
		(layer "In9.Cu")
		(net "P3E_CPU0_PE1_PCH_CON_RXN<12>")
	)
	(segment
		(start 350.221296 -123.3297)
		(end 351.654872 -123.3297)
		(width 0.1143)
		(layer "In9.Cu")
		(net "P3E_CPU0_PE1_PCH_CON_RXN<12>")
	)
	(segment
		(start 361.6325 -91.48064)
		(end 362.462064 -95.384112)
		(width 0.1143)
		(layer "In9.Cu")
		(net "P3E_CPU0_PE1_PCH_CON_RXN<12>")
	)
	(segment
		(start 379.375924 -16.133572)
		(end 378.08662 -16.407638)
		(width 0.1143)
		(layer "In9.Cu")
		(net "P3E_CPU0_PE1_PCH_CON_RXN<12>")
	)
	(segment
		(start 426.866304 -13.131292)
		(end 426.542454 -13.066268)
		(width 0.1143)
		(layer "In9.Cu")
		(net "P3E_CPU0_PE1_PCH_CON_RXN<12>")
	)
	(segment
		(start 361.736386 -109.03966)
		(end 361.736386 -109.38256)
		(width 0.1143)
		(layer "In9.Cu")
		(net "P3E_CPU0_PE1_PCH_CON_RXN<12>")
	)
	(segment
		(start 446.428622 -3.837432)
		(end 448.823588 -3.837432)
		(width 0.1143)
		(layer "In9.Cu")
		(net "P3E_CPU0_PE1_PCH_CON_RXN<12>")
	)
	(segment
		(start 366.732058 -36.14674)
		(end 365.947198 -39.64305)
		(width 0.1143)
		(layer "In9.Cu")
		(net "P3E_CPU0_PE1_PCH_CON_RXN<12>")
	)
	(segment
		(start 360.204258 -73.116948)
		(end 360.894884 -75.322938)
		(width 0.1143)
		(layer "In9.Cu")
		(net "P3E_CPU0_PE1_PCH_CON_RXN<12>")
	)
	(segment
		(start 351.654872 -123.3297)
		(end 352.105214 -123.780042)
		(width 0.1143)
		(layer "In9.Cu")
		(net "P3E_CPU0_PE1_PCH_CON_RXN<12>")
	)
	(segment
		(start 361.571286 -109.89056)
		(end 361.736386 -110.05566)
		(width 0.1143)
		(layer "In9.Cu")
		(net "P3E_CPU0_PE1_PCH_CON_RXN<12>")
	)
	(segment
		(start 379.965204 -16.258794)
		(end 379.375924 -16.133572)
		(width 0.1143)
		(layer "In9.Cu")
		(net "P3E_CPU0_PE1_PCH_CON_RXN<12>")
	)
	(segment
		(start 361.736386 -102.974394)
		(end 361.736386 -104.83469)
		(width 0.1143)
		(layer "In9.Cu")
		(net "P3E_CPU0_PE1_PCH_CON_RXN<12>")
	)
	(segment
		(start 361.571286 -106.35869)
		(end 361.736386 -106.52379)
		(width 0.1143)
		(layer "In9.Cu")
		(net "P3E_CPU0_PE1_PCH_CON_RXN<12>")
	)
	(segment
		(start 440.93257 -16.138144)
		(end 439.888122 -15.865602)
		(width 0.1143)
		(layer "In9.Cu")
		(net "P3E_CPU0_PE1_PCH_CON_RXN<12>")
	)
	(segment
		(start 450.96176 -6.39445)
		(end 450.372734 -9.170162)
		(width 0.1143)
		(layer "In9.Cu")
		(net "P3E_CPU0_PE1_PCH_CON_RXN<12>")
	)
	(segment
		(start 444.085472 -15.507208)
		(end 440.93257 -16.138144)
		(width 0.1143)
		(layer "In9.Cu")
		(net "P3E_CPU0_PE1_PCH_CON_RXN<12>")
	)
	(segment
		(start 359.132124 -119.379746)
		(end 350.896428 -121.130314)
		(width 0.1143)
		(layer "In9.Cu")
		(net "P3E_CPU0_PE1_PCH_CON_RXN<12>")
	)
	(segment
		(start 362.462064 -95.384112)
		(end 362.462064 -99.431348)
		(width 0.1143)
		(layer "In9.Cu")
		(net "P3E_CPU0_PE1_PCH_CON_RXN<12>")
	)
	(segment
		(start 365.947198 -39.64305)
		(end 365.713772 -40.159686)
		(width 0.1143)
		(layer "In9.Cu")
		(net "P3E_CPU0_PE1_PCH_CON_RXN<12>")
	)
	(segment
		(start 414.579054 -13.464794)
		(end 407.958798 -12.057634)
		(width 0.1143)
		(layer "In9.Cu")
		(net "P3E_CPU0_PE1_PCH_CON_RXN<12>")
	)
	(segment
		(start 439.420762 -15.553182)
		(end 429.791876 -13.626338)
		(width 0.1143)
		(layer "In9.Cu")
		(net "P3E_CPU0_PE1_PCH_CON_RXN<12>")
	)
	(segment
		(start 361.131104 -52.219606)
		(end 362.48848 -56.329834)
		(width 0.1143)
		(layer "In9.Cu")
		(net "P3E_CPU0_PE1_PCH_CON_RXN<12>")
	)
	(segment
		(start 361.571286 -109.54766)
		(end 361.571286 -109.89056)
		(width 0.1143)
		(layer "In9.Cu")
		(net "P3E_CPU0_PE1_PCH_CON_RXN<12>")
	)
	(segment
		(start 361.571286 -108.87456)
		(end 361.736386 -109.03966)
		(width 0.1143)
		(layer "In9.Cu")
		(net "P3E_CPU0_PE1_PCH_CON_RXN<12>")
	)
	(segment
		(start 361.266486 -117.749828)
		(end 359.132124 -119.379746)
		(width 0.1143)
		(layer "In9.Cu")
		(net "P3E_CPU0_PE1_PCH_CON_RXN<12>")
	)
	(segment
		(start 349.821754 -122.204988)
		(end 349.821754 -122.930158)
		(width 0.1143)
		(layer "In9.Cu")
		(net "P3E_CPU0_PE1_PCH_CON_RXN<12>")
	)
	(segment
		(start 362.48848 -56.329834)
		(end 361.093766 -59.189366)
		(width 0.1143)
		(layer "In9.Cu")
		(net "P3E_CPU0_PE1_PCH_CON_RXN<12>")
	)
	(segment
		(start 372.032022 -24.584914)
		(end 370.75618 -30.584902)
		(width 0.1143)
		(layer "In9.Cu")
		(net "P3E_CPU0_PE1_PCH_CON_RXN<12>")
	)
	(segment
		(start 416.549332 -13.071094)
		(end 414.579054 -13.464794)
		(width 0.1143)
		(layer "In9.Cu")
		(net "P3E_CPU0_PE1_PCH_CON_RXN<12>")
	)
	(segment
		(start 361.736386 -106.52379)
		(end 361.736386 -108.36656)
		(width 0.1143)
		(layer "In9.Cu")
		(net "P3E_CPU0_PE1_PCH_CON_RXN<12>")
	)
	(segment
		(start 391.338562 -15.59052)
		(end 387.226302 -14.716252)
		(width 0.1143)
		(layer "In9.Cu")
		(net "P3E_CPU0_PE1_PCH_CON_RXN<12>")
	)
	(segment
		(start 361.736386 -109.38256)
		(end 361.571286 -109.54766)
		(width 0.1143)
		(layer "In9.Cu")
		(net "P3E_CPU0_PE1_PCH_CON_RXN<12>")
	)
	(segment
		(start 450.5706 -10.159746)
		(end 450.334126 -11.34237)
		(width 0.1143)
		(layer "In9.Cu")
		(net "P3E_CPU0_PE1_PCH_CON_RXN<12>")
	)
	(segment
		(start 427.53534 -13.574268)
		(end 426.866304 -13.131292)
		(width 0.1143)
		(layer "In9.Cu")
		(net "P3E_CPU0_PE1_PCH_CON_RXN<12>")
	)
	(segment
		(start 359.38714 -67.221354)
		(end 359.54716 -68.020692)
		(width 0.1143)
		(layer "In9.Cu")
		(net "P3E_CPU0_PE1_PCH_CON_RXN<12>")
	)
	(segment
		(start 370.75618 -30.584902)
		(end 368.494818 -33.976818)
		(width 0.1143)
		(layer "In9.Cu")
		(net "P3E_CPU0_PE1_PCH_CON_RXN<12>")
	)
	(segment
		(start 424.130216 -13.810996)
		(end 418.638228 -12.653264)
		(width 0.1143)
		(layer "In9.Cu")
		(net "P3E_CPU0_PE1_PCH_CON_RXN<12>")
	)
	(segment
		(start 361.093766 -59.189366)
		(end 359.38714 -67.221354)
		(width 0.1143)
		(layer "In9.Cu")
		(net "P3E_CPU0_PE1_PCH_CON_RXN<12>")
	)
	(segment
		(start 450.334126 -11.34237)
		(end 444.085472 -15.507208)
		(width 0.1143)
		(layer "In9.Cu")
		(net "P3E_CPU0_PE1_PCH_CON_RXN<12>")
	)
	(segment
		(start 450.372734 -9.170162)
		(end 450.5706 -10.159746)
		(width 0.1143)
		(layer "In9.Cu")
		(net "P3E_CPU0_PE1_PCH_CON_RXN<12>")
	)
	(segment
		(start 441.494672 -5.667248)
		(end 441.175648 -5.667248)
		(width 0.1143)
		(layer "In9.Cu")
		(net "P3E_CPU0_PE1_PCH_CON_RXN<12>")
	)
	(segment
		(start 362.462064 -99.431348)
		(end 361.736386 -102.974394)
		(width 0.1143)
		(layer "In9.Cu")
		(net "P3E_CPU0_PE1_PCH_CON_RXN<12>")
	)
	(segment
		(start 441.03036 -5.224018)
		(end 441.336938 -4.91744)
		(width 0.1143)
		(layer "In9.Cu")
		(net "P3E_CPU0_PE1_PCH_CON_RXN<12>")
	)
	(segment
		(start 361.571286 -104.99979)
		(end 361.571286 -105.34269)
		(width 0.1143)
		(layer "In9.Cu")
		(net "P3E_CPU0_PE1_PCH_CON_RXN<12>")
	)
	(segment
		(start 425.5516 -13.267436)
		(end 424.995086 -13.635228)
		(width 0.1143)
		(layer "In9.Cu")
		(net "P3E_CPU0_PE1_PCH_CON_RXN<12>")
	)
	(segment
		(start 428.792132 -13.829792)
		(end 427.53534 -13.574268)
		(width 0.1143)
		(layer "In9.Cu")
		(net "P3E_CPU0_PE1_PCH_CON_RXN<12>")
	)
	(segment
		(start 361.571286 -105.34269)
		(end 361.736386 -105.50779)
		(width 0.1143)
		(layer "In9.Cu")
		(net "P3E_CPU0_PE1_PCH_CON_RXN<12>")
	)
	(segment
		(start 349.821754 -122.930158)
		(end 350.221296 -123.3297)
		(width 0.1143)
		(layer "In9.Cu")
		(net "P3E_CPU0_PE1_PCH_CON_RXN<12>")
	)
	(segment
		(start 438.571386 -3.033014)
		(end 438.713626 -2.890774)
		(width 0.1143)
		(layer "F.Cu")
		(net "P3E_CPU0_PE1_PCH_CON_RXN<11>")
	)
	(segment
		(start 438.571386 -3.453384)
		(end 438.571386 -3.033014)
		(width 0.1143)
		(layer "F.Cu")
		(net "P3E_CPU0_PE1_PCH_CON_RXN<11>")
	)
	(segment
		(start 438.876186 -4.386072)
		(end 438.876186 -3.758184)
		(width 0.1143)
		(layer "F.Cu")
		(net "P3E_CPU0_PE1_PCH_CON_RXN<11>")
	)
	(segment
		(start 438.713626 -2.890774)
		(end 439.084212 -2.890774)
		(width 0.1143)
		(layer "F.Cu")
		(net "P3E_CPU0_PE1_PCH_CON_RXN<11>")
	)
	(segment
		(start 438.876186 -3.758184)
		(end 438.571386 -3.453384)
		(width 0.1143)
		(layer "F.Cu")
		(net "P3E_CPU0_PE1_PCH_CON_RXN<11>")
	)
	(via
		(at 360.284014 -122.560842)
		(size 0.508)
		(drill 0.254)
		(layers "F.Cu" "B.Cu")
		(net "P3E_CPU0_PE1_PCH_CON_RXN<11>")
	)
	(via
		(at 439.084212 -2.890774)
		(size 0.508)
		(drill 0.254)
		(layers "F.Cu" "B.Cu")
		(net "P3E_CPU0_PE1_PCH_CON_RXN<11>")
	)
	(segment
		(start 360.334814 -122.510042)
		(end 360.284014 -122.560842)
		(width 0.1143)
		(layer "B.Cu")
		(net "P3E_CPU0_PE1_PCH_CON_RXN<11>")
	)
	(segment
		(start 360.937556 -122.510042)
		(end 360.334814 -122.510042)
		(width 0.1143)
		(layer "B.Cu")
		(net "P3E_CPU0_PE1_PCH_CON_RXN<11>")
	)
	(segment
		(start 433.340256 -15.656306)
		(end 433.676298 -15.724378)
		(width 0.1143)
		(layer "In9.Cu")
		(net "P3E_CPU0_PE1_PCH_CON_RXN<11>")
	)
	(segment
		(start 444.684658 -3.517392)
		(end 441.169044 -3.517392)
		(width 0.1143)
		(layer "In9.Cu")
		(net "P3E_CPU0_PE1_PCH_CON_RXN<11>")
	)
	(segment
		(start 450.91731 -12.29868)
		(end 451.044564 -12.102846)
		(width 0.1143)
		(layer "In9.Cu")
		(net "P3E_CPU0_PE1_PCH_CON_RXN<11>")
	)
	(segment
		(start 369.260374 -37.971984)
		(end 370.321586 -32.66567)
		(width 0.1143)
		(layer "In9.Cu")
		(net "P3E_CPU0_PE1_PCH_CON_RXN<11>")
	)
	(segment
		(start 360.065574 -67.235832)
		(end 361.715812 -59.466226)
		(width 0.1143)
		(layer "In9.Cu")
		(net "P3E_CPU0_PE1_PCH_CON_RXN<11>")
	)
	(segment
		(start 357.8987 -120.910096)
		(end 358.591612 -120.217184)
		(width 0.1143)
		(layer "In9.Cu")
		(net "P3E_CPU0_PE1_PCH_CON_RXN<11>")
	)
	(segment
		(start 366.27308 -42.822114)
		(end 367.681256 -40.710358)
		(width 0.1143)
		(layer "In9.Cu")
		(net "P3E_CPU0_PE1_PCH_CON_RXN<11>")
	)
	(segment
		(start 360.828082 -72.756268)
		(end 360.827828 -72.75576)
		(width 0.1143)
		(layer "In9.Cu")
		(net "P3E_CPU0_PE1_PCH_CON_RXN<11>")
	)
	(segment
		(start 451.137528 -4.132834)
		(end 449.119244 -3.202432)
		(width 0.1143)
		(layer "In9.Cu")
		(net "P3E_CPU0_PE1_PCH_CON_RXN<11>")
	)
	(segment
		(start 361.715812 -59.466226)
		(end 363.235748 -56.349646)
		(width 0.1143)
		(layer "In9.Cu")
		(net "P3E_CPU0_PE1_PCH_CON_RXN<11>")
	)
	(segment
		(start 446.170558 -3.202686)
		(end 446.170558 -3.202432)
		(width 0.1143)
		(layer "In9.Cu")
		(net "P3E_CPU0_PE1_PCH_CON_RXN<11>")
	)
	(segment
		(start 440.182 -3.106166)
		(end 439.399934 -2.3241)
		(width 0.1143)
		(layer "In9.Cu")
		(net "P3E_CPU0_PE1_PCH_CON_RXN<11>")
	)
	(segment
		(start 448.327526 -15.809214)
		(end 448.445128 -15.607538)
		(width 0.1143)
		(layer "In9.Cu")
		(net "P3E_CPU0_PE1_PCH_CON_RXN<11>")
	)
	(segment
		(start 434.866542 -15.797022)
		(end 435.202584 -15.865094)
		(width 0.1143)
		(layer "In9.Cu")
		(net "P3E_CPU0_PE1_PCH_CON_RXN<11>")
	)
	(segment
		(start 369.090702 -39.770558)
		(end 369.364006 -38.490652)
		(width 0.1143)
		(layer "In9.Cu")
		(net "P3E_CPU0_PE1_PCH_CON_RXN<11>")
	)
	(segment
		(start 434.206904 -15.663418)
		(end 434.335936 -15.857982)
		(width 0.1143)
		(layer "In9.Cu")
		(net "P3E_CPU0_PE1_PCH_CON_RXN<11>")
	)
	(segment
		(start 364.946184 -44.10964)
		(end 365.430308 -43.383708)
		(width 0.1143)
		(layer "In9.Cu")
		(net "P3E_CPU0_PE1_PCH_CON_RXN<11>")
	)
	(segment
		(start 449.490592 -15.502128)
		(end 449.490846 -15.502128)
		(width 0.1143)
		(layer "In9.Cu")
		(net "P3E_CPU0_PE1_PCH_CON_RXN<11>")
	)
	(segment
		(start 424.834558 -14.404594)
		(end 427.569884 -14.932406)
		(width 0.1143)
		(layer "In9.Cu")
		(net "P3E_CPU0_PE1_PCH_CON_RXN<11>")
	)
	(segment
		(start 448.445128 -15.607538)
		(end 448.776598 -15.519908)
		(width 0.1143)
		(layer "In9.Cu")
		(net "P3E_CPU0_PE1_PCH_CON_RXN<11>")
	)
	(segment
		(start 435.667658 -16.12773)
		(end 437.252618 -15.80515)
		(width 0.1143)
		(layer "In9.Cu")
		(net "P3E_CPU0_PE1_PCH_CON_RXN<11>")
	)
	(segment
		(start 362.868718 -47.864776)
		(end 364.757462 -45.050456)
		(width 0.1143)
		(layer "In9.Cu")
		(net "P3E_CPU0_PE1_PCH_CON_RXN<11>")
	)
	(segment
		(start 446.170812 -3.202432)
		(end 446.170558 -3.202686)
		(width 0.1143)
		(layer "In9.Cu")
		(net "P3E_CPU0_PE1_PCH_CON_RXN<11>")
	)
	(segment
		(start 450.424042 -15.559024)
		(end 450.750432 -15.230602)
		(width 0.1143)
		(layer "In9.Cu")
		(net "P3E_CPU0_PE1_PCH_CON_RXN<11>")
	)
	(segment
		(start 379.905006 -16.942562)
		(end 387.198362 -15.394178)
		(width 0.1143)
		(layer "In9.Cu")
		(net "P3E_CPU0_PE1_PCH_CON_RXN<11>")
	)
	(segment
		(start 362.408216 -109.07141)
		(end 362.408216 -105.198926)
		(width 0.1143)
		(layer "In9.Cu")
		(net "P3E_CPU0_PE1_PCH_CON_RXN<11>")
	)
	(segment
		(start 440.813444 -16.839946)
		(end 443.954408 -16.342106)
		(width 0.1143)
		(layer "In9.Cu")
		(net "P3E_CPU0_PE1_PCH_CON_RXN<11>")
	)
	(segment
		(start 446.170558 -3.202432)
		(end 444.684658 -3.517392)
		(width 0.1143)
		(layer "In9.Cu")
		(net "P3E_CPU0_PE1_PCH_CON_RXN<11>")
	)
	(segment
		(start 433.870862 -15.595346)
		(end 434.206904 -15.663418)
		(width 0.1143)
		(layer "In9.Cu")
		(net "P3E_CPU0_PE1_PCH_CON_RXN<11>")
	)
	(segment
		(start 448.776598 -15.519908)
		(end 448.978274 -15.63751)
		(width 0.1143)
		(layer "In9.Cu")
		(net "P3E_CPU0_PE1_PCH_CON_RXN<11>")
	)
	(segment
		(start 407.890472 -12.722606)
		(end 414.508442 -14.127226)
		(width 0.1143)
		(layer "In9.Cu")
		(net "P3E_CPU0_PE1_PCH_CON_RXN<11>")
	)
	(segment
		(start 360.284014 -122.560842)
		(end 360.284014 -122.242834)
		(width 0.1143)
		(layer "In9.Cu")
		(net "P3E_CPU0_PE1_PCH_CON_RXN<11>")
	)
	(segment
		(start 449.490846 -15.502128)
		(end 450.083428 -15.682722)
		(width 0.1143)
		(layer "In9.Cu")
		(net "P3E_CPU0_PE1_PCH_CON_RXN<11>")
	)
	(segment
		(start 450.97319 -11.767566)
		(end 451.273926 -10.263886)
		(width 0.1143)
		(layer "In9.Cu")
		(net "P3E_CPU0_PE1_PCH_CON_RXN<11>")
	)
	(segment
		(start 443.954408 -16.342106)
		(end 446.756028 -15.64894)
		(width 0.1143)
		(layer "In9.Cu")
		(net "P3E_CPU0_PE1_PCH_CON_RXN<11>")
	)
	(segment
		(start 450.750432 -15.230602)
		(end 451.477634 -14.139418)
		(width 0.1143)
		(layer "In9.Cu")
		(net "P3E_CPU0_PE1_PCH_CON_RXN<11>")
	)
	(segment
		(start 451.038214 -9.154414)
		(end 451.62089 -6.409944)
		(width 0.1143)
		(layer "In9.Cu")
		(net "P3E_CPU0_PE1_PCH_CON_RXN<11>")
	)
	(segment
		(start 360.284014 -122.242834)
		(end 360.12628 -122.0851)
		(width 0.1143)
		(layer "In9.Cu")
		(net "P3E_CPU0_PE1_PCH_CON_RXN<11>")
	)
	(segment
		(start 362.408216 -105.198926)
		(end 363.097064 -104.510078)
		(width 0.1143)
		(layer "In9.Cu")
		(net "P3E_CPU0_PE1_PCH_CON_RXN<11>")
	)
	(segment
		(start 416.512248 -13.726668)
		(end 416.512248 -13.726414)
		(width 0.1143)
		(layer "In9.Cu")
		(net "P3E_CPU0_PE1_PCH_CON_RXN<11>")
	)
	(segment
		(start 446.756028 -15.64894)
		(end 447.996056 -15.896844)
		(width 0.1143)
		(layer "In9.Cu")
		(net "P3E_CPU0_PE1_PCH_CON_RXN<11>")
	)
	(segment
		(start 427.569884 -14.932406)
		(end 428.67326 -14.711426)
		(width 0.1143)
		(layer "In9.Cu")
		(net "P3E_CPU0_PE1_PCH_CON_RXN<11>")
	)
	(segment
		(start 435.202584 -15.865094)
		(end 435.331616 -16.059658)
		(width 0.1143)
		(layer "In9.Cu")
		(net "P3E_CPU0_PE1_PCH_CON_RXN<11>")
	)
	(segment
		(start 451.477634 -14.139418)
		(end 451.184518 -12.761214)
		(width 0.1143)
		(layer "In9.Cu")
		(net "P3E_CPU0_PE1_PCH_CON_RXN<11>")
	)
	(segment
		(start 416.512248 -13.726414)
		(end 418.34435 -13.360146)
		(width 0.1143)
		(layer "In9.Cu")
		(net "P3E_CPU0_PE1_PCH_CON_RXN<11>")
	)
	(segment
		(start 365.430308 -43.383708)
		(end 366.27308 -42.822114)
		(width 0.1143)
		(layer "In9.Cu")
		(net "P3E_CPU0_PE1_PCH_CON_RXN<11>")
	)
	(segment
		(start 438.599072 -2.50444)
		(end 438.599072 -2.785872)
		(width 0.1143)
		(layer "In9.Cu")
		(net "P3E_CPU0_PE1_PCH_CON_RXN<11>")
	)
	(segment
		(start 387.198362 -15.394178)
		(end 391.260584 -16.25727)
		(width 0.1143)
		(layer "In9.Cu")
		(net "P3E_CPU0_PE1_PCH_CON_RXN<11>")
	)
	(segment
		(start 360.051858 -69.102732)
		(end 360.24566 -68.134484)
		(width 0.1143)
		(layer "In9.Cu")
		(net "P3E_CPU0_PE1_PCH_CON_RXN<11>")
	)
	(segment
		(start 418.34435 -13.360146)
		(end 424.03141 -14.565884)
		(width 0.1143)
		(layer "In9.Cu")
		(net "P3E_CPU0_PE1_PCH_CON_RXN<11>")
	)
	(segment
		(start 450.988684 -12.634214)
		(end 450.91731 -12.29868)
		(width 0.1143)
		(layer "In9.Cu")
		(net "P3E_CPU0_PE1_PCH_CON_RXN<11>")
	)
	(segment
		(start 432.875182 -15.39367)
		(end 433.211224 -15.461742)
		(width 0.1143)
		(layer "In9.Cu")
		(net "P3E_CPU0_PE1_PCH_CON_RXN<11>")
	)
	(segment
		(start 367.681256 -40.710358)
		(end 369.090702 -39.770558)
		(width 0.1143)
		(layer "In9.Cu")
		(net "P3E_CPU0_PE1_PCH_CON_RXN<11>")
	)
	(segment
		(start 360.827828 -72.75576)
		(end 360.051858 -69.102732)
		(width 0.1143)
		(layer "In9.Cu")
		(net "P3E_CPU0_PE1_PCH_CON_RXN<11>")
	)
	(segment
		(start 371.286786 -31.21914)
		(end 372.628668 -24.90851)
		(width 0.1143)
		(layer "In9.Cu")
		(net "P3E_CPU0_PE1_PCH_CON_RXN<11>")
	)
	(segment
		(start 438.703974 -2.890774)
		(end 439.084212 -2.890774)
		(width 0.1143)
		(layer "In9.Cu")
		(net "P3E_CPU0_PE1_PCH_CON_RXN<11>")
	)
	(segment
		(start 363.235748 -56.349646)
		(end 362.17225 -51.344576)
		(width 0.1143)
		(layer "In9.Cu")
		(net "P3E_CPU0_PE1_PCH_CON_RXN<11>")
	)
	(segment
		(start 432.680618 -15.522702)
		(end 432.875182 -15.39367)
		(width 0.1143)
		(layer "In9.Cu")
		(net "P3E_CPU0_PE1_PCH_CON_RXN<11>")
	)
	(segment
		(start 370.321586 -32.66567)
		(end 371.286786 -31.21914)
		(width 0.1143)
		(layer "In9.Cu")
		(net "P3E_CPU0_PE1_PCH_CON_RXN<11>")
	)
	(segment
		(start 440.550554 -3.352292)
		(end 440.182 -3.106166)
		(width 0.1143)
		(layer "In9.Cu")
		(net "P3E_CPU0_PE1_PCH_CON_RXN<11>")
	)
	(segment
		(start 451.044564 -12.102846)
		(end 450.97319 -11.767566)
		(width 0.1143)
		(layer "In9.Cu")
		(net "P3E_CPU0_PE1_PCH_CON_RXN<11>")
	)
	(segment
		(start 434.671978 -15.926054)
		(end 434.866542 -15.797022)
		(width 0.1143)
		(layer "In9.Cu")
		(net "P3E_CPU0_PE1_PCH_CON_RXN<11>")
	)
	(segment
		(start 439.189114 -16.19504)
		(end 439.79211 -16.596868)
		(width 0.1143)
		(layer "In9.Cu")
		(net "P3E_CPU0_PE1_PCH_CON_RXN<11>")
	)
	(segment
		(start 372.628668 -24.90851)
		(end 377.537218 -17.544288)
		(width 0.1143)
		(layer "In9.Cu")
		(net "P3E_CPU0_PE1_PCH_CON_RXN<11>")
	)
	(segment
		(start 360.24566 -68.134484)
		(end 360.065574 -67.235832)
		(width 0.1143)
		(layer "In9.Cu")
		(net "P3E_CPU0_PE1_PCH_CON_RXN<11>")
	)
	(segment
		(start 438.599072 -2.785872)
		(end 438.703974 -2.890774)
		(width 0.1143)
		(layer "In9.Cu")
		(net "P3E_CPU0_PE1_PCH_CON_RXN<11>")
	)
	(segment
		(start 438.779412 -2.3241)
		(end 438.599072 -2.50444)
		(width 0.1143)
		(layer "In9.Cu")
		(net "P3E_CPU0_PE1_PCH_CON_RXN<11>")
	)
	(segment
		(start 362.2675 -75.755246)
		(end 361.538012 -75.025758)
		(width 0.1143)
		(layer "In9.Cu")
		(net "P3E_CPU0_PE1_PCH_CON_RXN<11>")
	)
	(segment
		(start 391.260584 -16.25727)
		(end 407.890472 -12.722606)
		(width 0.1143)
		(layer "In9.Cu")
		(net "P3E_CPU0_PE1_PCH_CON_RXN<11>")
	)
	(segment
		(start 437.252618 -15.80515)
		(end 439.189114 -16.19504)
		(width 0.1143)
		(layer "In9.Cu")
		(net "P3E_CPU0_PE1_PCH_CON_RXN<11>")
	)
	(segment
		(start 363.097064 -94.99727)
		(end 362.2675 -90.902282)
		(width 0.1143)
		(layer "In9.Cu")
		(net "P3E_CPU0_PE1_PCH_CON_RXN<11>")
	)
	(segment
		(start 439.79211 -16.596868)
		(end 440.813444 -16.839946)
		(width 0.1143)
		(layer "In9.Cu")
		(net "P3E_CPU0_PE1_PCH_CON_RXN<11>")
	)
	(segment
		(start 441.169044 -3.517392)
		(end 440.550554 -3.352292)
		(width 0.1143)
		(layer "In9.Cu")
		(net "P3E_CPU0_PE1_PCH_CON_RXN<11>")
	)
	(segment
		(start 364.757462 -45.050456)
		(end 364.946184 -44.10964)
		(width 0.1143)
		(layer "In9.Cu")
		(net "P3E_CPU0_PE1_PCH_CON_RXN<11>")
	)
	(segment
		(start 360.12628 -122.0851)
		(end 358.323896 -122.0851)
		(width 0.1143)
		(layer "In9.Cu")
		(net "P3E_CPU0_PE1_PCH_CON_RXN<11>")
	)
	(segment
		(start 433.676298 -15.724378)
		(end 433.870862 -15.595346)
		(width 0.1143)
		(layer "In9.Cu")
		(net "P3E_CPU0_PE1_PCH_CON_RXN<11>")
	)
	(segment
		(start 369.364006 -38.490652)
		(end 369.260374 -37.971984)
		(width 0.1143)
		(layer "In9.Cu")
		(net "P3E_CPU0_PE1_PCH_CON_RXN<11>")
	)
	(segment
		(start 377.537218 -17.544288)
		(end 378.137674 -17.144238)
		(width 0.1143)
		(layer "In9.Cu")
		(net "P3E_CPU0_PE1_PCH_CON_RXN<11>")
	)
	(segment
		(start 433.211224 -15.461742)
		(end 433.340256 -15.656306)
		(width 0.1143)
		(layer "In9.Cu")
		(net "P3E_CPU0_PE1_PCH_CON_RXN<11>")
	)
	(segment
		(start 447.996056 -15.896844)
		(end 448.327526 -15.809214)
		(width 0.1143)
		(layer "In9.Cu")
		(net "P3E_CPU0_PE1_PCH_CON_RXN<11>")
	)
	(segment
		(start 362.17225 -51.344576)
		(end 362.868718 -47.864776)
		(width 0.1143)
		(layer "In9.Cu")
		(net "P3E_CPU0_PE1_PCH_CON_RXN<11>")
	)
	(segment
		(start 424.03141 -14.565884)
		(end 424.834558 -14.404594)
		(width 0.1143)
		(layer "In9.Cu")
		(net "P3E_CPU0_PE1_PCH_CON_RXN<11>")
	)
	(segment
		(start 451.184518 -12.761214)
		(end 450.988684 -12.634214)
		(width 0.1143)
		(layer "In9.Cu")
		(net "P3E_CPU0_PE1_PCH_CON_RXN<11>")
	)
	(segment
		(start 364.34395 -111.007144)
		(end 362.408216 -109.07141)
		(width 0.1143)
		(layer "In9.Cu")
		(net "P3E_CPU0_PE1_PCH_CON_RXN<11>")
	)
	(segment
		(start 448.978274 -15.63751)
		(end 449.490592 -15.502128)
		(width 0.1143)
		(layer "In9.Cu")
		(net "P3E_CPU0_PE1_PCH_CON_RXN<11>")
	)
	(segment
		(start 428.67326 -14.711426)
		(end 432.680618 -15.522702)
		(width 0.1143)
		(layer "In9.Cu")
		(net "P3E_CPU0_PE1_PCH_CON_RXN<11>")
	)
	(segment
		(start 357.8987 -121.659904)
		(end 357.8987 -120.910096)
		(width 0.1143)
		(layer "In9.Cu")
		(net "P3E_CPU0_PE1_PCH_CON_RXN<11>")
	)
	(segment
		(start 414.508442 -14.127226)
		(end 416.512248 -13.726668)
		(width 0.1143)
		(layer "In9.Cu")
		(net "P3E_CPU0_PE1_PCH_CON_RXN<11>")
	)
	(segment
		(start 435.331616 -16.059658)
		(end 435.667658 -16.12773)
		(width 0.1143)
		(layer "In9.Cu")
		(net "P3E_CPU0_PE1_PCH_CON_RXN<11>")
	)
	(segment
		(start 361.538012 -75.025758)
		(end 360.828082 -72.756268)
		(width 0.1143)
		(layer "In9.Cu")
		(net "P3E_CPU0_PE1_PCH_CON_RXN<11>")
	)
	(segment
		(start 451.273926 -10.263886)
		(end 451.038214 -9.154414)
		(width 0.1143)
		(layer "In9.Cu")
		(net "P3E_CPU0_PE1_PCH_CON_RXN<11>")
	)
	(segment
		(start 358.591612 -120.217184)
		(end 361.117642 -120.217184)
		(width 0.1143)
		(layer "In9.Cu")
		(net "P3E_CPU0_PE1_PCH_CON_RXN<11>")
	)
	(segment
		(start 363.097064 -104.510078)
		(end 363.097064 -94.99727)
		(width 0.1143)
		(layer "In9.Cu")
		(net "P3E_CPU0_PE1_PCH_CON_RXN<11>")
	)
	(segment
		(start 451.62089 -6.409944)
		(end 451.137528 -4.132834)
		(width 0.1143)
		(layer "In9.Cu")
		(net "P3E_CPU0_PE1_PCH_CON_RXN<11>")
	)
	(segment
		(start 361.117642 -120.217184)
		(end 364.34395 -116.990876)
		(width 0.1143)
		(layer "In9.Cu")
		(net "P3E_CPU0_PE1_PCH_CON_RXN<11>")
	)
	(segment
		(start 364.34395 -116.990876)
		(end 364.34395 -111.007144)
		(width 0.1143)
		(layer "In9.Cu")
		(net "P3E_CPU0_PE1_PCH_CON_RXN<11>")
	)
	(segment
		(start 449.119244 -3.202432)
		(end 446.170812 -3.202432)
		(width 0.1143)
		(layer "In9.Cu")
		(net "P3E_CPU0_PE1_PCH_CON_RXN<11>")
	)
	(segment
		(start 434.335936 -15.857982)
		(end 434.671978 -15.926054)
		(width 0.1143)
		(layer "In9.Cu")
		(net "P3E_CPU0_PE1_PCH_CON_RXN<11>")
	)
	(segment
		(start 362.2675 -90.902282)
		(end 362.2675 -75.755246)
		(width 0.1143)
		(layer "In9.Cu")
		(net "P3E_CPU0_PE1_PCH_CON_RXN<11>")
	)
	(segment
		(start 358.323896 -122.0851)
		(end 357.8987 -121.659904)
		(width 0.1143)
		(layer "In9.Cu")
		(net "P3E_CPU0_PE1_PCH_CON_RXN<11>")
	)
	(segment
		(start 450.083428 -15.682722)
		(end 450.424042 -15.559024)
		(width 0.1143)
		(layer "In9.Cu")
		(net "P3E_CPU0_PE1_PCH_CON_RXN<11>")
	)
	(segment
		(start 379.495558 -16.85544)
		(end 379.905006 -16.942562)
		(width 0.1143)
		(layer "In9.Cu")
		(net "P3E_CPU0_PE1_PCH_CON_RXN<11>")
	)
	(segment
		(start 439.399934 -2.3241)
		(end 438.779412 -2.3241)
		(width 0.1143)
		(layer "In9.Cu")
		(net "P3E_CPU0_PE1_PCH_CON_RXN<11>")
	)
	(segment
		(start 378.137674 -17.144238)
		(end 379.495558 -16.85544)
		(width 0.1143)
		(layer "In9.Cu")
		(net "P3E_CPU0_PE1_PCH_CON_RXN<11>")
	)
	(segment
		(start 436.174388 -2.96672)
		(end 436.174388 -3.456686)
		(width 0.1143)
		(layer "F.Cu")
		(net "P3E_CPU0_PE1_PCH_CON_RXN<10>")
	)
	(segment
		(start 436.301388 -2.83972)
		(end 436.174388 -2.96672)
		(width 0.1143)
		(layer "F.Cu")
		(net "P3E_CPU0_PE1_PCH_CON_RXN<10>")
	)
	(segment
		(start 436.174388 -3.456686)
		(end 436.475886 -3.758184)
		(width 0.1143)
		(layer "F.Cu")
		(net "P3E_CPU0_PE1_PCH_CON_RXN<10>")
	)
	(segment
		(start 436.475886 -3.758184)
		(end 436.475886 -4.386072)
		(width 0.1143)
		(layer "F.Cu")
		(net "P3E_CPU0_PE1_PCH_CON_RXN<10>")
	)
	(segment
		(start 436.701438 -2.83972)
		(end 436.301388 -2.83972)
		(width 0.1143)
		(layer "F.Cu")
		(net "P3E_CPU0_PE1_PCH_CON_RXN<10>")
	)
	(via
		(at 436.701438 -2.83972)
		(size 0.508)
		(drill 0.254)
		(layers "F.Cu" "B.Cu")
		(net "P3E_CPU0_PE1_PCH_CON_RXN<10>")
	)
	(via
		(at 360.233214 -124.338842)
		(size 0.508)
		(drill 0.254)
		(layers "F.Cu" "B.Cu")
		(net "P3E_CPU0_PE1_PCH_CON_RXN<10>")
	)
	(segment
		(start 360.893614 -124.440442)
		(end 360.334814 -124.440442)
		(width 0.1143)
		(layer "B.Cu")
		(net "P3E_CPU0_PE1_PCH_CON_RXN<10>")
	)
	(segment
		(start 360.334814 -124.440442)
		(end 360.233214 -124.338842)
		(width 0.1143)
		(layer "B.Cu")
		(net "P3E_CPU0_PE1_PCH_CON_RXN<10>")
	)
	(segment
		(start 436.1942 -2.732786)
		(end 436.301134 -2.83972)
		(width 0.1143)
		(layer "In9.Cu")
		(net "P3E_CPU0_PE1_PCH_CON_RXN<10>")
	)
	(segment
		(start 361.483656 -72.715882)
		(end 361.483402 -72.715374)
		(width 0.1143)
		(layer "In9.Cu")
		(net "P3E_CPU0_PE1_PCH_CON_RXN<10>")
	)
	(segment
		(start 447.812922 -17.27835)
		(end 447.812922 -17.278604)
		(width 0.1143)
		(layer "In9.Cu")
		(net "P3E_CPU0_PE1_PCH_CON_RXN<10>")
	)
	(segment
		(start 365.172244 -115.501166)
		(end 365.007144 -115.336066)
		(width 0.1143)
		(layer "In9.Cu")
		(net "P3E_CPU0_PE1_PCH_CON_RXN<10>")
	)
	(segment
		(start 447.813176 -17.278604)
		(end 447.813176 -17.27835)
		(width 0.1143)
		(layer "In9.Cu")
		(net "P3E_CPU0_PE1_PCH_CON_RXN<10>")
	)
	(segment
		(start 452.168768 -14.2748)
		(end 451.69582 -12.0523)
		(width 0.1143)
		(layer "In9.Cu")
		(net "P3E_CPU0_PE1_PCH_CON_RXN<10>")
	)
	(segment
		(start 361.433364 -122.3391)
		(end 361.268264 -122.174)
		(width 0.1143)
		(layer "In9.Cu")
		(net "P3E_CPU0_PE1_PCH_CON_RXN<10>")
	)
	(segment
		(start 365.007144 -116.009166)
		(end 365.172244 -115.844066)
		(width 0.1143)
		(layer "In9.Cu")
		(net "P3E_CPU0_PE1_PCH_CON_RXN<10>")
	)
	(segment
		(start 368.032538 -41.360598)
		(end 369.732814 -40.226996)
		(width 0.1143)
		(layer "In9.Cu")
		(net "P3E_CPU0_PE1_PCH_CON_RXN<10>")
	)
	(segment
		(start 363.24032 -119.282718)
		(end 363.473746 -119.282718)
		(width 0.1143)
		(layer "In9.Cu")
		(net "P3E_CPU0_PE1_PCH_CON_RXN<10>")
	)
	(segment
		(start 438.893966 -17.070324)
		(end 440.835034 -17.587722)
		(width 0.1143)
		(layer "In9.Cu")
		(net "P3E_CPU0_PE1_PCH_CON_RXN<10>")
	)
	(segment
		(start 436.531766 -1.79197)
		(end 436.1942 -2.208022)
		(width 0.1143)
		(layer "In9.Cu")
		(net "P3E_CPU0_PE1_PCH_CON_RXN<10>")
	)
	(segment
		(start 370.993162 -32.837882)
		(end 371.916198 -31.455106)
		(width 0.1143)
		(layer "In9.Cu")
		(net "P3E_CPU0_PE1_PCH_CON_RXN<10>")
	)
	(segment
		(start 361.433364 -121.666)
		(end 361.433364 -121.3231)
		(width 0.1143)
		(layer "In9.Cu")
		(net "P3E_CPU0_PE1_PCH_CON_RXN<10>")
	)
	(segment
		(start 364.91037 -117.846094)
		(end 365.172244 -117.58422)
		(width 0.1143)
		(layer "In9.Cu")
		(net "P3E_CPU0_PE1_PCH_CON_RXN<10>")
	)
	(segment
		(start 361.268264 -122.8471)
		(end 361.433364 -122.682)
		(width 0.1143)
		(layer "In9.Cu")
		(net "P3E_CPU0_PE1_PCH_CON_RXN<10>")
	)
	(segment
		(start 360.91622 -68.236846)
		(end 360.724196 -67.277996)
		(width 0.1143)
		(layer "In9.Cu")
		(net "P3E_CPU0_PE1_PCH_CON_RXN<10>")
	)
	(segment
		(start 424.144694 -15.277338)
		(end 425.05249 -15.09522)
		(width 0.1143)
		(layer "In9.Cu")
		(net "P3E_CPU0_PE1_PCH_CON_RXN<10>")
	)
	(segment
		(start 437.730138 -16.651478)
		(end 437.848502 -16.651478)
		(width 0.1143)
		(layer "In9.Cu")
		(net "P3E_CPU0_PE1_PCH_CON_RXN<10>")
	)
	(segment
		(start 364.284514 -48.513492)
		(end 366.90554 -46.342046)
		(width 0.1143)
		(layer "In9.Cu")
		(net "P3E_CPU0_PE1_PCH_CON_RXN<10>")
	)
	(segment
		(start 362.08208 -74.626724)
		(end 362.081826 -74.626724)
		(width 0.1143)
		(layer "In9.Cu")
		(net "P3E_CPU0_PE1_PCH_CON_RXN<10>")
	)
	(segment
		(start 361.268264 -123.19)
		(end 361.268264 -122.8471)
		(width 0.1143)
		(layer "In9.Cu")
		(net "P3E_CPU0_PE1_PCH_CON_RXN<10>")
	)
	(segment
		(start 367.19637 -42.614596)
		(end 368.032538 -41.360598)
		(width 0.1143)
		(layer "In9.Cu")
		(net "P3E_CPU0_PE1_PCH_CON_RXN<10>")
	)
	(segment
		(start 367.024412 -45.748956)
		(end 366.797082 -44.611798)
		(width 0.1143)
		(layer "In9.Cu")
		(net "P3E_CPU0_PE1_PCH_CON_RXN<10>")
	)
	(segment
		(start 414.492186 -14.793976)
		(end 418.288216 -14.034008)
		(width 0.1143)
		(layer "In9.Cu")
		(net "P3E_CPU0_PE1_PCH_CON_RXN<10>")
	)
	(segment
		(start 363.020102 -52.223162)
		(end 364.284514 -48.513492)
		(width 0.1143)
		(layer "In9.Cu")
		(net "P3E_CPU0_PE1_PCH_CON_RXN<10>")
	)
	(segment
		(start 362.9025 -90.01887)
		(end 362.9025 -75.447144)
		(width 0.1143)
		(layer "In9.Cu")
		(net "P3E_CPU0_PE1_PCH_CON_RXN<10>")
	)
	(segment
		(start 407.846276 -13.382752)
		(end 414.492186 -14.793976)
		(width 0.1143)
		(layer "In9.Cu")
		(net "P3E_CPU0_PE1_PCH_CON_RXN<10>")
	)
	(segment
		(start 363.958632 -118.564406)
		(end 364.192058 -118.564406)
		(width 0.1143)
		(layer "In9.Cu")
		(net "P3E_CPU0_PE1_PCH_CON_RXN<10>")
	)
	(segment
		(start 450.23024 -16.423132)
		(end 450.703696 -16.251174)
		(width 0.1143)
		(layer "In9.Cu")
		(net "P3E_CPU0_PE1_PCH_CON_RXN<10>")
	)
	(segment
		(start 361.433364 -121.3231)
		(end 362.279692 -120.476772)
		(width 0.1143)
		(layer "In9.Cu")
		(net "P3E_CPU0_PE1_PCH_CON_RXN<10>")
	)
	(segment
		(start 453.461374 -6.660642)
		(end 453.232774 -6.317488)
		(width 0.1143)
		(layer "In9.Cu")
		(net "P3E_CPU0_PE1_PCH_CON_RXN<10>")
	)
	(segment
		(start 362.998004 -119.75846)
		(end 362.998004 -119.525034)
		(width 0.1143)
		(layer "In9.Cu")
		(net "P3E_CPU0_PE1_PCH_CON_RXN<10>")
	)
	(segment
		(start 451.63486 -3.634232)
		(end 451.22465 -3.019044)
		(width 0.1143)
		(layer "In9.Cu")
		(net "P3E_CPU0_PE1_PCH_CON_RXN<10>")
	)
	(segment
		(start 362.081572 -74.62647)
		(end 361.483656 -72.715882)
		(width 0.1143)
		(layer "In9.Cu")
		(net "P3E_CPU0_PE1_PCH_CON_RXN<10>")
	)
	(segment
		(start 425.05249 -15.09522)
		(end 428.019972 -15.687548)
		(width 0.1143)
		(layer "In9.Cu")
		(net "P3E_CPU0_PE1_PCH_CON_RXN<10>")
	)
	(segment
		(start 437.154828 -1.659636)
		(end 436.531766 -1.79197)
		(width 0.1143)
		(layer "In9.Cu")
		(net "P3E_CPU0_PE1_PCH_CON_RXN<10>")
	)
	(segment
		(start 362.998004 -119.525034)
		(end 363.24032 -119.282718)
		(width 0.1143)
		(layer "In9.Cu")
		(net "P3E_CPU0_PE1_PCH_CON_RXN<10>")
	)
	(segment
		(start 361.268264 -122.174)
		(end 361.268264 -121.8311)
		(width 0.1143)
		(layer "In9.Cu")
		(net "P3E_CPU0_PE1_PCH_CON_RXN<10>")
	)
	(segment
		(start 365.007144 -116.352066)
		(end 365.007144 -116.009166)
		(width 0.1143)
		(layer "In9.Cu")
		(net "P3E_CPU0_PE1_PCH_CON_RXN<10>")
	)
	(segment
		(start 437.848502 -16.651478)
		(end 437.848756 -16.651732)
		(width 0.1143)
		(layer "In9.Cu")
		(net "P3E_CPU0_PE1_PCH_CON_RXN<10>")
	)
	(segment
		(start 360.730038 -69.167502)
		(end 360.91622 -68.236846)
		(width 0.1143)
		(layer "In9.Cu")
		(net "P3E_CPU0_PE1_PCH_CON_RXN<10>")
	)
	(segment
		(start 364.434628 -118.08841)
		(end 364.676944 -117.846094)
		(width 0.1143)
		(layer "In9.Cu")
		(net "P3E_CPU0_PE1_PCH_CON_RXN<10>")
	)
	(segment
		(start 362.9025 -75.447144)
		(end 362.08208 -74.626724)
		(width 0.1143)
		(layer "In9.Cu")
		(net "P3E_CPU0_PE1_PCH_CON_RXN<10>")
	)
	(segment
		(start 361.268264 -121.8311)
		(end 361.433364 -121.666)
		(width 0.1143)
		(layer "In9.Cu")
		(net "P3E_CPU0_PE1_PCH_CON_RXN<10>")
	)
	(segment
		(start 369.732814 -40.226996)
		(end 370.083842 -38.475666)
		(width 0.1143)
		(layer "In9.Cu")
		(net "P3E_CPU0_PE1_PCH_CON_RXN<10>")
	)
	(segment
		(start 366.90554 -46.342046)
		(end 366.994694 -45.8978)
		(width 0.1143)
		(layer "In9.Cu")
		(net "P3E_CPU0_PE1_PCH_CON_RXN<10>")
	)
	(segment
		(start 391.256012 -16.90878)
		(end 407.846276 -13.382752)
		(width 0.1143)
		(layer "In9.Cu")
		(net "P3E_CPU0_PE1_PCH_CON_RXN<10>")
	)
	(segment
		(start 363.043216 -108.803186)
		(end 363.043216 -105.503726)
		(width 0.1143)
		(layer "In9.Cu")
		(net "P3E_CPU0_PE1_PCH_CON_RXN<10>")
	)
	(segment
		(start 363.716316 -119.040148)
		(end 363.716316 -118.806722)
		(width 0.1143)
		(layer "In9.Cu")
		(net "P3E_CPU0_PE1_PCH_CON_RXN<10>")
	)
	(segment
		(start 362.342684 -59.656472)
		(end 363.913928 -56.435244)
		(width 0.1143)
		(layer "In9.Cu")
		(net "P3E_CPU0_PE1_PCH_CON_RXN<10>")
	)
	(segment
		(start 365.172244 -115.844066)
		(end 365.172244 -115.501166)
		(width 0.1143)
		(layer "In9.Cu")
		(net "P3E_CPU0_PE1_PCH_CON_RXN<10>")
	)
	(segment
		(start 449.367402 -16.191738)
		(end 450.23024 -16.423132)
		(width 0.1143)
		(layer "In9.Cu")
		(net "P3E_CPU0_PE1_PCH_CON_RXN<10>")
	)
	(segment
		(start 365.172244 -117.58422)
		(end 365.172244 -116.517166)
		(width 0.1143)
		(layer "In9.Cu")
		(net "P3E_CPU0_PE1_PCH_CON_RXN<10>")
	)
	(segment
		(start 365.007144 -112.456214)
		(end 365.172244 -112.291114)
		(width 0.1143)
		(layer "In9.Cu")
		(net "P3E_CPU0_PE1_PCH_CON_RXN<10>")
	)
	(segment
		(start 362.279692 -120.476772)
		(end 362.279692 -120.243346)
		(width 0.1143)
		(layer "In9.Cu")
		(net "P3E_CPU0_PE1_PCH_CON_RXN<10>")
	)
	(segment
		(start 451.22465 -3.019044)
		(end 448.12331 -1.659636)
		(width 0.1143)
		(layer "In9.Cu")
		(net "P3E_CPU0_PE1_PCH_CON_RXN<10>")
	)
	(segment
		(start 432.626516 -16.272002)
		(end 436.109364 -16.980916)
		(width 0.1143)
		(layer "In9.Cu")
		(net "P3E_CPU0_PE1_PCH_CON_RXN<10>")
	)
	(segment
		(start 369.974876 -37.93109)
		(end 370.993162 -32.837882)
		(width 0.1143)
		(layer "In9.Cu")
		(net "P3E_CPU0_PE1_PCH_CON_RXN<10>")
	)
	(segment
		(start 365.172244 -110.932214)
		(end 363.043216 -108.803186)
		(width 0.1143)
		(layer "In9.Cu")
		(net "P3E_CPU0_PE1_PCH_CON_RXN<10>")
	)
	(segment
		(start 363.913928 -56.435244)
		(end 363.020102 -52.223162)
		(width 0.1143)
		(layer "In9.Cu")
		(net "P3E_CPU0_PE1_PCH_CON_RXN<10>")
	)
	(segment
		(start 360.724196 -67.277996)
		(end 362.342684 -59.656472)
		(width 0.1143)
		(layer "In9.Cu")
		(net "P3E_CPU0_PE1_PCH_CON_RXN<10>")
	)
	(segment
		(start 363.043216 -105.503726)
		(end 363.744764 -104.802178)
		(width 0.1143)
		(layer "In9.Cu")
		(net "P3E_CPU0_PE1_PCH_CON_RXN<10>")
	)
	(segment
		(start 362.279692 -120.243346)
		(end 362.522008 -120.00103)
		(width 0.1143)
		(layer "In9.Cu")
		(net "P3E_CPU0_PE1_PCH_CON_RXN<10>")
	)
	(segment
		(start 445.402208 -17.763998)
		(end 447.812922 -17.27835)
		(width 0.1143)
		(layer "In9.Cu")
		(net "P3E_CPU0_PE1_PCH_CON_RXN<10>")
	)
	(segment
		(start 361.007406 -124.789946)
		(end 361.433364 -124.363988)
		(width 0.1143)
		(layer "In9.Cu")
		(net "P3E_CPU0_PE1_PCH_CON_RXN<10>")
	)
	(segment
		(start 418.288216 -14.034008)
		(end 424.144694 -15.277338)
		(width 0.1143)
		(layer "In9.Cu")
		(net "P3E_CPU0_PE1_PCH_CON_RXN<10>")
	)
	(segment
		(start 452.737728 -5.987034)
		(end 452.167498 -5.13207)
		(width 0.1143)
		(layer "In9.Cu")
		(net "P3E_CPU0_PE1_PCH_CON_RXN<10>")
	)
	(segment
		(start 450.703696 -16.251174)
		(end 451.27672 -15.676626)
		(width 0.1143)
		(layer "In9.Cu")
		(net "P3E_CPU0_PE1_PCH_CON_RXN<10>")
	)
	(segment
		(start 436.1942 -2.208022)
		(end 436.1942 -2.732786)
		(width 0.1143)
		(layer "In9.Cu")
		(net "P3E_CPU0_PE1_PCH_CON_RXN<10>")
	)
	(segment
		(start 365.007144 -111.440214)
		(end 365.172244 -111.275114)
		(width 0.1143)
		(layer "In9.Cu")
		(net "P3E_CPU0_PE1_PCH_CON_RXN<10>")
	)
	(segment
		(start 365.172244 -112.964214)
		(end 365.007144 -112.799114)
		(width 0.1143)
		(layer "In9.Cu")
		(net "P3E_CPU0_PE1_PCH_CON_RXN<10>")
	)
	(segment
		(start 379.845316 -17.62252)
		(end 387.231128 -16.05407)
		(width 0.1143)
		(layer "In9.Cu")
		(net "P3E_CPU0_PE1_PCH_CON_RXN<10>")
	)
	(segment
		(start 360.684318 -124.789946)
		(end 361.007406 -124.789946)
		(width 0.1143)
		(layer "In9.Cu")
		(net "P3E_CPU0_PE1_PCH_CON_RXN<10>")
	)
	(segment
		(start 378.397262 -17.783556)
		(end 379.500638 -17.549368)
		(width 0.1143)
		(layer "In9.Cu")
		(net "P3E_CPU0_PE1_PCH_CON_RXN<10>")
	)
	(segment
		(start 451.27672 -15.676626)
		(end 452.168768 -14.2748)
		(width 0.1143)
		(layer "In9.Cu")
		(net "P3E_CPU0_PE1_PCH_CON_RXN<10>")
	)
	(segment
		(start 360.233214 -124.338842)
		(end 360.684318 -124.789946)
		(width 0.1143)
		(layer "In9.Cu")
		(net "P3E_CPU0_PE1_PCH_CON_RXN<10>")
	)
	(segment
		(start 363.473746 -119.282718)
		(end 363.716316 -119.040148)
		(width 0.1143)
		(layer "In9.Cu")
		(net "P3E_CPU0_PE1_PCH_CON_RXN<10>")
	)
	(segment
		(start 451.69582 -12.0523)
		(end 451.89013 -11.138662)
		(width 0.1143)
		(layer "In9.Cu")
		(net "P3E_CPU0_PE1_PCH_CON_RXN<10>")
	)
	(segment
		(start 447.813176 -17.27835)
		(end 448.43954 -16.437102)
		(width 0.1143)
		(layer "In9.Cu")
		(net "P3E_CPU0_PE1_PCH_CON_RXN<10>")
	)
	(segment
		(start 365.172244 -112.291114)
		(end 365.172244 -111.948214)
		(width 0.1143)
		(layer "In9.Cu")
		(net "P3E_CPU0_PE1_PCH_CON_RXN<10>")
	)
	(segment
		(start 366.797082 -44.611798)
		(end 367.19637 -42.614596)
		(width 0.1143)
		(layer "In9.Cu")
		(net "P3E_CPU0_PE1_PCH_CON_RXN<10>")
	)
	(segment
		(start 365.007144 -115.336066)
		(end 365.007144 -114.993166)
		(width 0.1143)
		(layer "In9.Cu")
		(net "P3E_CPU0_PE1_PCH_CON_RXN<10>")
	)
	(segment
		(start 436.301134 -2.83972)
		(end 436.701438 -2.83972)
		(width 0.1143)
		(layer "In9.Cu")
		(net "P3E_CPU0_PE1_PCH_CON_RXN<10>")
	)
	(segment
		(start 370.083842 -38.475666)
		(end 369.974876 -37.93109)
		(width 0.1143)
		(layer "In9.Cu")
		(net "P3E_CPU0_PE1_PCH_CON_RXN<10>")
	)
	(segment
		(start 379.500638 -17.549368)
		(end 379.845316 -17.62252)
		(width 0.1143)
		(layer "In9.Cu")
		(net "P3E_CPU0_PE1_PCH_CON_RXN<10>")
	)
	(segment
		(start 364.676944 -117.846094)
		(end 364.91037 -117.846094)
		(width 0.1143)
		(layer "In9.Cu")
		(net "P3E_CPU0_PE1_PCH_CON_RXN<10>")
	)
	(segment
		(start 451.89013 -11.138662)
		(end 452.797418 -9.783572)
		(width 0.1143)
		(layer "In9.Cu")
		(net "P3E_CPU0_PE1_PCH_CON_RXN<10>")
	)
	(segment
		(start 436.109364 -16.980916)
		(end 437.730138 -16.651478)
		(width 0.1143)
		(layer "In9.Cu")
		(net "P3E_CPU0_PE1_PCH_CON_RXN<10>")
	)
	(segment
		(start 363.744764 -94.190058)
		(end 362.9025 -90.01887)
		(width 0.1143)
		(layer "In9.Cu")
		(net "P3E_CPU0_PE1_PCH_CON_RXN<10>")
	)
	(segment
		(start 364.192058 -118.564406)
		(end 364.434628 -118.321836)
		(width 0.1143)
		(layer "In9.Cu")
		(net "P3E_CPU0_PE1_PCH_CON_RXN<10>")
	)
	(segment
		(start 364.434628 -118.321836)
		(end 364.434628 -118.08841)
		(width 0.1143)
		(layer "In9.Cu")
		(net "P3E_CPU0_PE1_PCH_CON_RXN<10>")
	)
	(segment
		(start 437.848756 -16.651732)
		(end 438.461404 -16.78178)
		(width 0.1143)
		(layer "In9.Cu")
		(net "P3E_CPU0_PE1_PCH_CON_RXN<10>")
	)
	(segment
		(start 448.43954 -16.437102)
		(end 449.367402 -16.191738)
		(width 0.1143)
		(layer "In9.Cu")
		(net "P3E_CPU0_PE1_PCH_CON_RXN<10>")
	)
	(segment
		(start 361.483402 -72.715374)
		(end 360.730038 -69.167502)
		(width 0.1143)
		(layer "In9.Cu")
		(net "P3E_CPU0_PE1_PCH_CON_RXN<10>")
	)
	(segment
		(start 365.172244 -111.275114)
		(end 365.172244 -110.932214)
		(width 0.1143)
		(layer "In9.Cu")
		(net "P3E_CPU0_PE1_PCH_CON_RXN<10>")
	)
	(segment
		(start 365.007144 -114.993166)
		(end 365.172244 -114.828066)
		(width 0.1143)
		(layer "In9.Cu")
		(net "P3E_CPU0_PE1_PCH_CON_RXN<10>")
	)
	(segment
		(start 365.007144 -111.783114)
		(end 365.007144 -111.440214)
		(width 0.1143)
		(layer "In9.Cu")
		(net "P3E_CPU0_PE1_PCH_CON_RXN<10>")
	)
	(segment
		(start 443.0268 -17.289526)
		(end 445.402208 -17.763998)
		(width 0.1143)
		(layer "In9.Cu")
		(net "P3E_CPU0_PE1_PCH_CON_RXN<10>")
	)
	(segment
		(start 429.125126 -15.465806)
		(end 432.4223 -16.136874)
		(width 0.1143)
		(layer "In9.Cu")
		(net "P3E_CPU0_PE1_PCH_CON_RXN<10>")
	)
	(segment
		(start 361.433364 -122.682)
		(end 361.433364 -122.3391)
		(width 0.1143)
		(layer "In9.Cu")
		(net "P3E_CPU0_PE1_PCH_CON_RXN<10>")
	)
	(segment
		(start 366.994694 -45.8978)
		(end 367.024412 -45.748956)
		(width 0.1143)
		(layer "In9.Cu")
		(net "P3E_CPU0_PE1_PCH_CON_RXN<10>")
	)
	(segment
		(start 447.812922 -17.278604)
		(end 447.813176 -17.278604)
		(width 0.1143)
		(layer "In9.Cu")
		(net "P3E_CPU0_PE1_PCH_CON_RXN<10>")
	)
	(segment
		(start 361.433364 -123.3551)
		(end 361.268264 -123.19)
		(width 0.1143)
		(layer "In9.Cu")
		(net "P3E_CPU0_PE1_PCH_CON_RXN<10>")
	)
	(segment
		(start 452.167498 -5.13207)
		(end 451.954392 -4.113276)
		(width 0.1143)
		(layer "In9.Cu")
		(net "P3E_CPU0_PE1_PCH_CON_RXN<10>")
	)
	(segment
		(start 452.797418 -9.783572)
		(end 453.461374 -6.660642)
		(width 0.1143)
		(layer "In9.Cu")
		(net "P3E_CPU0_PE1_PCH_CON_RXN<10>")
	)
	(segment
		(start 365.172244 -116.517166)
		(end 365.007144 -116.352066)
		(width 0.1143)
		(layer "In9.Cu")
		(net "P3E_CPU0_PE1_PCH_CON_RXN<10>")
	)
	(segment
		(start 365.007144 -112.799114)
		(end 365.007144 -112.456214)
		(width 0.1143)
		(layer "In9.Cu")
		(net "P3E_CPU0_PE1_PCH_CON_RXN<10>")
	)
	(segment
		(start 363.716316 -118.806722)
		(end 363.958632 -118.564406)
		(width 0.1143)
		(layer "In9.Cu")
		(net "P3E_CPU0_PE1_PCH_CON_RXN<10>")
	)
	(segment
		(start 432.4223 -16.136874)
		(end 432.626516 -16.272002)
		(width 0.1143)
		(layer "In9.Cu")
		(net "P3E_CPU0_PE1_PCH_CON_RXN<10>")
	)
	(segment
		(start 365.172244 -114.828066)
		(end 365.172244 -112.964214)
		(width 0.1143)
		(layer "In9.Cu")
		(net "P3E_CPU0_PE1_PCH_CON_RXN<10>")
	)
	(segment
		(start 377.994418 -18.052034)
		(end 378.397262 -17.783556)
		(width 0.1143)
		(layer "In9.Cu")
		(net "P3E_CPU0_PE1_PCH_CON_RXN<10>")
	)
	(segment
		(start 440.835034 -17.587722)
		(end 443.0268 -17.289526)
		(width 0.1143)
		(layer "In9.Cu")
		(net "P3E_CPU0_PE1_PCH_CON_RXN<10>")
	)
	(segment
		(start 453.232774 -6.317488)
		(end 452.737728 -5.987034)
		(width 0.1143)
		(layer "In9.Cu")
		(net "P3E_CPU0_PE1_PCH_CON_RXN<10>")
	)
	(segment
		(start 365.172244 -111.948214)
		(end 365.007144 -111.783114)
		(width 0.1143)
		(layer "In9.Cu")
		(net "P3E_CPU0_PE1_PCH_CON_RXN<10>")
	)
	(segment
		(start 438.461404 -16.78178)
		(end 438.893966 -17.070324)
		(width 0.1143)
		(layer "In9.Cu")
		(net "P3E_CPU0_PE1_PCH_CON_RXN<10>")
	)
	(segment
		(start 428.019972 -15.687548)
		(end 429.125126 -15.465806)
		(width 0.1143)
		(layer "In9.Cu")
		(net "P3E_CPU0_PE1_PCH_CON_RXN<10>")
	)
	(segment
		(start 371.916198 -31.455106)
		(end 373.253254 -25.166066)
		(width 0.1143)
		(layer "In9.Cu")
		(net "P3E_CPU0_PE1_PCH_CON_RXN<10>")
	)
	(segment
		(start 362.081826 -74.626724)
		(end 362.081572 -74.62647)
		(width 0.1143)
		(layer "In9.Cu")
		(net "P3E_CPU0_PE1_PCH_CON_RXN<10>")
	)
	(segment
		(start 361.433364 -124.363988)
		(end 361.433364 -123.3551)
		(width 0.1143)
		(layer "In9.Cu")
		(net "P3E_CPU0_PE1_PCH_CON_RXN<10>")
	)
	(segment
		(start 451.954392 -4.113276)
		(end 451.63486 -3.634232)
		(width 0.1143)
		(layer "In9.Cu")
		(net "P3E_CPU0_PE1_PCH_CON_RXN<10>")
	)
	(segment
		(start 362.522008 -120.00103)
		(end 362.755434 -120.00103)
		(width 0.1143)
		(layer "In9.Cu")
		(net "P3E_CPU0_PE1_PCH_CON_RXN<10>")
	)
	(segment
		(start 373.253254 -25.166066)
		(end 377.994418 -18.052034)
		(width 0.1143)
		(layer "In9.Cu")
		(net "P3E_CPU0_PE1_PCH_CON_RXN<10>")
	)
	(segment
		(start 387.231128 -16.05407)
		(end 391.256012 -16.90878)
		(width 0.1143)
		(layer "In9.Cu")
		(net "P3E_CPU0_PE1_PCH_CON_RXN<10>")
	)
	(segment
		(start 363.744764 -104.802178)
		(end 363.744764 -94.190058)
		(width 0.1143)
		(layer "In9.Cu")
		(net "P3E_CPU0_PE1_PCH_CON_RXN<10>")
	)
	(segment
		(start 362.755434 -120.00103)
		(end 362.998004 -119.75846)
		(width 0.1143)
		(layer "In9.Cu")
		(net "P3E_CPU0_PE1_PCH_CON_RXN<10>")
	)
	(segment
		(start 448.12331 -1.659636)
		(end 437.154828 -1.659636)
		(width 0.1143)
		(layer "In9.Cu")
		(net "P3E_CPU0_PE1_PCH_CON_RXN<10>")
	)
	(segment
		(start 435.384956 -37.769546)
		(end 435.384956 -37.8333)
		(width 0.4064)
		(layer "F.Cu")
		(net "P2V5_AUX_BMC")
	)
	(segment
		(start 436.522114 -36.632388)
		(end 435.384956 -37.769546)
		(width 0.4064)
		(layer "F.Cu")
		(net "P2V5_AUX_BMC")
	)
	(segment
		(start 442.921898 -26.232612)
		(end 443.357 -26.543)
		(width 0.3048)
		(layer "F.Cu")
		(net "P2V5_AUX_BMC")
	)
	(via
		(at 443.357 -26.543)
		(size 0.4572)
		(drill 0.2032)
		(layers "F.Cu" "B.Cu")
		(net "P2V5_AUX_BMC")
	)
	(via
		(at 435.384956 -37.8333)
		(size 0.4572)
		(drill 0.2032)
		(layers "F.Cu" "B.Cu")
		(net "P2V5_AUX_BMC")
	)
	(via
		(at 447.929 -23.3426)
		(size 0.762)
		(drill 0.381)
		(layers "F.Cu" "B.Cu")
		(net "P2V5_AUX_BMC")
	)
	(segment
		(start 435.384956 -37.8333)
		(end 435.384956 -37.956744)
		(width 0.508)
		(layer "In9.Cu")
		(net "P2V5_AUX_BMC")
	)
	(segment
		(start 444.708026 -27.894026)
		(end 443.357 -26.543)
		(width 0.508)
		(layer "In9.Cu")
		(net "P2V5_AUX_BMC")
	)
	(segment
		(start 444.1444 -37.035486)
		(end 444.1444 -31.0896)
		(width 0.508)
		(layer "In9.Cu")
		(net "P2V5_AUX_BMC")
	)
	(segment
		(start 435.384956 -37.956744)
		(end 435.869588 -38.441376)
		(width 0.508)
		(layer "In9.Cu")
		(net "P2V5_AUX_BMC")
	)
	(segment
		(start 444.708026 -30.526228)
		(end 444.708026 -27.894026)
		(width 0.508)
		(layer "In9.Cu")
		(net "P2V5_AUX_BMC")
	)
	(segment
		(start 442.73851 -38.441376)
		(end 444.1444 -37.035486)
		(width 0.508)
		(layer "In9.Cu")
		(net "P2V5_AUX_BMC")
	)
	(segment
		(start 435.869588 -38.441376)
		(end 442.73851 -38.441376)
		(width 0.508)
		(layer "In9.Cu")
		(net "P2V5_AUX_BMC")
	)
	(segment
		(start 444.351664 -30.882336)
		(end 444.351918 -30.882336)
		(width 0.508)
		(layer "In9.Cu")
		(net "P2V5_AUX_BMC")
	)
	(segment
		(start 444.1444 -31.0896)
		(end 444.351664 -30.882336)
		(width 0.508)
		(layer "In9.Cu")
		(net "P2V5_AUX_BMC")
	)
	(segment
		(start 444.351918 -30.882336)
		(end 444.708026 -30.526228)
		(width 0.508)
		(layer "In9.Cu")
		(net "P2V5_AUX_BMC")
	)
	(segment
		(start 436.121556 -25.03805)
		(end 436.516018 -25.432512)
		(width 0.3048)
		(layer "F.Cu")
		(net "P1V2_AUX_BMC")
	)
	(segment
		(start 436.522114 -37.432742)
		(end 436.522114 -37.432488)
		(width 0.4064)
		(layer "F.Cu")
		(net "P1V2_AUX_BMC")
	)
	(segment
		(start 419.089332 -36.13531)
		(end 418.635942 -36.13531)
		(width 0.254)
		(layer "F.Cu")
		(net "P1V2_AUX_BMC")
	)
	(segment
		(start 453.3265 -32.131)
		(end 453.3265 -31.496)
		(width 0.254)
		(layer "F.Cu")
		(net "P1V2_AUX_BMC")
	)
	(segment
		(start 442.921898 -25.432258)
		(end 443.322456 -25.0317)
		(width 0.3048)
		(layer "F.Cu")
		(net "P1V2_AUX_BMC")
	)
	(segment
		(start 436.522114 -31.83255)
		(end 436.921656 -31.433008)
		(width 0.3048)
		(layer "F.Cu")
		(net "P1V2_AUX_BMC")
	)
	(segment
		(start 442.921898 -36.632388)
		(end 442.923168 -36.632388)
		(width 0.3048)
		(layer "F.Cu")
		(net "P1V2_AUX_BMC")
	)
	(segment
		(start 436.522114 -33.432496)
		(end 436.52186 -33.432496)
		(width 0.3048)
		(layer "F.Cu")
		(net "P1V2_AUX_BMC")
	)
	(segment
		(start 442.921898 -25.432512)
		(end 442.921898 -25.432258)
		(width 0.3048)
		(layer "F.Cu")
		(net "P1V2_AUX_BMC")
	)
	(segment
		(start 442.921898 -27.032712)
		(end 442.921898 -27.032458)
		(width 0.3048)
		(layer "F.Cu")
		(net "P1V2_AUX_BMC")
	)
	(segment
		(start 437.32196 -31.83255)
		(end 437.32196 -31.832296)
		(width 0.3048)
		(layer "F.Cu")
		(net "P1V2_AUX_BMC")
	)
	(segment
		(start 452.30288 -31.3055)
		(end 452.30288 -31.17088)
		(width 0.4064)
		(layer "F.Cu")
		(net "P1V2_AUX_BMC")
	)
	(segment
		(start 442.921898 -30.232604)
		(end 442.922152 -30.232604)
		(width 0.3048)
		(layer "F.Cu")
		(net "P1V2_AUX_BMC")
	)
	(segment
		(start 436.521098 -27.832558)
		(end 436.121556 -28.2321)
		(width 0.3048)
		(layer "F.Cu")
		(net "P1V2_AUX_BMC")
	)
	(segment
		(start 418.63645 -33.734756)
		(end 418.635942 -33.735264)
		(width 0.254)
		(layer "F.Cu")
		(net "P1V2_AUX_BMC")
	)
	(segment
		(start 438.12206 -30.232604)
		(end 438.521856 -29.832808)
		(width 0.3048)
		(layer "F.Cu")
		(net "P1V2_AUX_BMC")
	)
	(segment
		(start 437.32196 -31.832296)
		(end 437.721756 -31.4325)
		(width 0.3048)
		(layer "F.Cu")
		(net "P1V2_AUX_BMC")
	)
	(segment
		(start 442.922152 -30.232604)
		(end 443.322456 -29.8323)
		(width 0.3048)
		(layer "F.Cu")
		(net "P1V2_AUX_BMC")
	)
	(segment
		(start 442.122052 -29.432504)
		(end 442.522356 -29.0322)
		(width 0.3048)
		(layer "F.Cu")
		(net "P1V2_AUX_BMC")
	)
	(segment
		(start 418.635942 -36.13531)
		(end 418.635942 -35.334702)
		(width 0.254)
		(layer "F.Cu")
		(net "P1V2_AUX_BMC")
	)
	(segment
		(start 419.090094 -36.134548)
		(end 419.089332 -36.13531)
		(width 0.254)
		(layer "F.Cu")
		(net "P1V2_AUX_BMC")
	)
	(segment
		(start 442.122306 -31.83255)
		(end 442.522356 -31.4325)
		(width 0.3048)
		(layer "F.Cu")
		(net "P1V2_AUX_BMC")
	)
	(segment
		(start 442.923168 -36.632388)
		(end 443.322456 -36.2331)
		(width 0.3048)
		(layer "F.Cu")
		(net "P1V2_AUX_BMC")
	)
	(segment
		(start 419.090094 -33.734756)
		(end 419.490144 -34.134552)
		(width 0.254)
		(layer "F.Cu")
		(net "P1V2_AUX_BMC")
	)
	(segment
		(start 436.121556 -24.7777)
		(end 436.121556 -25.03805)
		(width 0.3048)
		(layer "F.Cu")
		(net "P1V2_AUX_BMC")
	)
	(segment
		(start 419.090094 -32.134556)
		(end 419.490144 -31.734506)
		(width 0.254)
		(layer "F.Cu")
		(net "P1V2_AUX_BMC")
	)
	(segment
		(start 436.921656 -29.832554)
		(end 437.321706 -29.432504)
		(width 0.3048)
		(layer "F.Cu")
		(net "P1V2_AUX_BMC")
	)
	(segment
		(start 442.122052 -31.83255)
		(end 442.122306 -31.83255)
		(width 0.3048)
		(layer "F.Cu")
		(net "P1V2_AUX_BMC")
	)
	(segment
		(start 436.522114 -30.232096)
		(end 436.921656 -29.832554)
		(width 0.3048)
		(layer "F.Cu")
		(net "P1V2_AUX_BMC")
	)
	(segment
		(start 441.321952 -26.232612)
		(end 441.321952 -26.231596)
		(width 0.3048)
		(layer "F.Cu")
		(net "P1V2_AUX_BMC")
	)
	(segment
		(start 436.522114 -26.232612)
		(end 436.520844 -26.232612)
		(width 0.3048)
		(layer "F.Cu")
		(net "P1V2_AUX_BMC")
	)
	(segment
		(start 437.321706 -29.432504)
		(end 437.32196 -29.432504)
		(width 0.3048)
		(layer "F.Cu")
		(net "P1V2_AUX_BMC")
	)
	(segment
		(start 443.322202 -27.433016)
		(end 442.921898 -27.032712)
		(width 0.3048)
		(layer "F.Cu")
		(net "P1V2_AUX_BMC")
	)
	(segment
		(start 419.490144 -36.534598)
		(end 419.090094 -36.934648)
		(width 0.254)
		(layer "F.Cu")
		(net "P1V2_AUX_BMC")
	)
	(segment
		(start 442.921898 -27.879548)
		(end 443.425072 -28.382722)
		(width 0.3048)
		(layer "F.Cu")
		(net "P1V2_AUX_BMC")
	)
	(segment
		(start 436.522114 -30.232604)
		(end 436.522114 -30.232096)
		(width 0.3048)
		(layer "F.Cu")
		(net "P1V2_AUX_BMC")
	)
	(segment
		(start 436.516018 -25.432512)
		(end 436.522114 -25.432512)
		(width 0.3048)
		(layer "F.Cu")
		(net "P1V2_AUX_BMC")
	)
	(segment
		(start 419.090094 -35.334702)
		(end 418.635942 -35.334702)
		(width 0.254)
		(layer "F.Cu")
		(net "P1V2_AUX_BMC")
	)
	(segment
		(start 418.635942 -32.588708)
		(end 419.090094 -32.134556)
		(width 0.254)
		(layer "F.Cu")
		(net "P1V2_AUX_BMC")
	)
	(segment
		(start 436.520844 -26.232612)
		(end 436.121556 -26.6319)
		(width 0.3048)
		(layer "F.Cu")
		(net "P1V2_AUX_BMC")
	)
	(segment
		(start 442.922406 -31.83255)
		(end 443.322456 -31.4325)
		(width 0.3048)
		(layer "F.Cu")
		(net "P1V2_AUX_BMC")
	)
	(segment
		(start 436.522114 -27.832558)
		(end 436.521098 -27.832558)
		(width 0.3048)
		(layer "F.Cu")
		(net "P1V2_AUX_BMC")
	)
	(segment
		(start 438.521856 -29.832808)
		(end 438.521856 -29.8323)
		(width 0.3048)
		(layer "F.Cu")
		(net "P1V2_AUX_BMC")
	)
	(segment
		(start 418.635942 -33.735264)
		(end 418.635942 -32.588708)
		(width 0.254)
		(layer "F.Cu")
		(net "P1V2_AUX_BMC")
	)
	(segment
		(start 452.30288 -31.17088)
		(end 451.612 -30.48)
		(width 0.4064)
		(layer "F.Cu")
		(net "P1V2_AUX_BMC")
	)
	(segment
		(start 441.321952 -26.231596)
		(end 440.922156 -25.8318)
		(width 0.3048)
		(layer "F.Cu")
		(net "P1V2_AUX_BMC")
	)
	(segment
		(start 419.090094 -33.734756)
		(end 418.63645 -33.734756)
		(width 0.254)
		(layer "F.Cu")
		(net "P1V2_AUX_BMC")
	)
	(segment
		(start 442.921898 -31.83255)
		(end 442.922406 -31.83255)
		(width 0.3048)
		(layer "F.Cu")
		(net "P1V2_AUX_BMC")
	)
	(segment
		(start 419.090094 -36.934648)
		(end 418.635942 -36.480496)
		(width 0.254)
		(layer "F.Cu")
		(net "P1V2_AUX_BMC")
	)
	(segment
		(start 436.52186 -33.432496)
		(end 436.121556 -33.8328)
		(width 0.3048)
		(layer "F.Cu")
		(net "P1V2_AUX_BMC")
	)
	(segment
		(start 418.635942 -36.480496)
		(end 418.635942 -36.13531)
		(width 0.254)
		(layer "F.Cu")
		(net "P1V2_AUX_BMC")
	)
	(segment
		(start 418.635942 -35.334702)
		(end 418.635942 -33.735264)
		(width 0.254)
		(layer "F.Cu")
		(net "P1V2_AUX_BMC")
	)
	(segment
		(start 443.532006 -33.432496)
		(end 442.921898 -33.432496)
		(width 0.3048)
		(layer "F.Cu")
		(net "P1V2_AUX_BMC")
	)
	(segment
		(start 419.090094 -33.734756)
		(end 419.490144 -33.334706)
		(width 0.254)
		(layer "F.Cu")
		(net "P1V2_AUX_BMC")
	)
	(segment
		(start 419.090094 -35.334702)
		(end 419.490144 -35.734498)
		(width 0.254)
		(layer "F.Cu")
		(net "P1V2_AUX_BMC")
	)
	(segment
		(start 436.921656 -31.433008)
		(end 436.921656 -31.4325)
		(width 0.3048)
		(layer "F.Cu")
		(net "P1V2_AUX_BMC")
	)
	(segment
		(start 436.121556 -37.8333)
		(end 436.522114 -37.432742)
		(width 0.4064)
		(layer "F.Cu")
		(net "P1V2_AUX_BMC")
	)
	(segment
		(start 442.921898 -27.832558)
		(end 442.921898 -27.879548)
		(width 0.3048)
		(layer "F.Cu")
		(net "P1V2_AUX_BMC")
	)
	(segment
		(start 452.30288 -37.1475)
		(end 452.30288 -38.2905)
		(width 0.508)
		(layer "F.Cu")
		(net "P1V2_AUX_BMC")
	)
	(segment
		(start 452.30288 -39.0779)
		(end 452.30288 -38.2905)
		(width 0.508)
		(layer "F.Cu")
		(net "P1V2_AUX_BMC")
	)
	(via
		(at 443.532006 -33.432496)
		(size 0.4572)
		(drill 0.2032)
		(layers "F.Cu" "B.Cu")
		(net "P1V2_AUX_BMC")
	)
	(via
		(at 419.490144 -33.334706)
		(size 0.4572)
		(drill 0.2032)
		(layers "F.Cu" "B.Cu")
		(net "P1V2_AUX_BMC")
	)
	(via
		(at 436.121556 -24.7777)
		(size 0.4572)
		(drill 0.2032)
		(layers "F.Cu" "B.Cu")
		(net "P1V2_AUX_BMC")
	)
	(via
		(at 419.490144 -34.134552)
		(size 0.4572)
		(drill 0.2032)
		(layers "F.Cu" "B.Cu")
		(net "P1V2_AUX_BMC")
	)
	(via
		(at 451.612 -30.48)
		(size 0.508)
		(drill 0.254)
		(layers "F.Cu" "B.Cu")
		(net "P1V2_AUX_BMC")
	)
	(via
		(at 436.121556 -26.6319)
		(size 0.4572)
		(drill 0.2032)
		(layers "F.Cu" "B.Cu")
		(net "P1V2_AUX_BMC")
	)
	(via
		(at 436.121556 -33.8328)
		(size 0.4572)
		(drill 0.2032)
		(layers "F.Cu" "B.Cu")
		(net "P1V2_AUX_BMC")
	)
	(via
		(at 470.9795 -35.2044)
		(size 0.508)
		(drill 0.254)
		(layers "F.Cu" "B.Cu")
		(net "P1V2_AUX_BMC")
	)
	(via
		(at 453.3265 -31.496)
		(size 0.508)
		(drill 0.254)
		(layers "F.Cu" "B.Cu")
		(net "P1V2_AUX_BMC")
	)
	(via
		(at 443.322456 -31.4325)
		(size 0.4572)
		(drill 0.2032)
		(layers "F.Cu" "B.Cu")
		(net "P1V2_AUX_BMC")
	)
	(via
		(at 419.490144 -31.734506)
		(size 0.4572)
		(drill 0.2032)
		(layers "F.Cu" "B.Cu")
		(net "P1V2_AUX_BMC")
	)
	(via
		(at 419.490144 -35.734498)
		(size 0.4572)
		(drill 0.2032)
		(layers "F.Cu" "B.Cu")
		(net "P1V2_AUX_BMC")
	)
	(via
		(at 436.121556 -28.2321)
		(size 0.4572)
		(drill 0.2032)
		(layers "F.Cu" "B.Cu")
		(net "P1V2_AUX_BMC")
	)
	(via
		(at 443.322456 -25.0317)
		(size 0.4572)
		(drill 0.2032)
		(layers "F.Cu" "B.Cu")
		(net "P1V2_AUX_BMC")
	)
	(via
		(at 469.54186 -35.90544)
		(size 0.508)
		(drill 0.254)
		(layers "F.Cu" "B.Cu")
		(net "P1V2_AUX_BMC")
	)
	(via
		(at 442.522356 -29.0322)
		(size 0.4572)
		(drill 0.2032)
		(layers "F.Cu" "B.Cu")
		(net "P1V2_AUX_BMC")
	)
	(via
		(at 440.922156 -25.8318)
		(size 0.4572)
		(drill 0.2032)
		(layers "F.Cu" "B.Cu")
		(net "P1V2_AUX_BMC")
	)
	(via
		(at 471.7415 -35.2044)
		(size 0.508)
		(drill 0.254)
		(layers "F.Cu" "B.Cu")
		(net "P1V2_AUX_BMC")
	)
	(via
		(at 438.521856 -29.8323)
		(size 0.4572)
		(drill 0.2032)
		(layers "F.Cu" "B.Cu")
		(net "P1V2_AUX_BMC")
	)
	(via
		(at 436.921656 -29.832554)
		(size 0.4572)
		(drill 0.2032)
		(layers "F.Cu" "B.Cu")
		(net "P1V2_AUX_BMC")
	)
	(via
		(at 442.522356 -31.4325)
		(size 0.4572)
		(drill 0.2032)
		(layers "F.Cu" "B.Cu")
		(net "P1V2_AUX_BMC")
	)
	(via
		(at 437.690006 -44.707048)
		(size 0.508)
		(drill 0.254)
		(layers "F.Cu" "B.Cu")
		(net "P1V2_AUX_BMC")
	)
	(via
		(at 443.322456 -36.2331)
		(size 0.4572)
		(drill 0.2032)
		(layers "F.Cu" "B.Cu")
		(net "P1V2_AUX_BMC")
	)
	(via
		(at 443.322202 -27.433016)
		(size 0.4572)
		(drill 0.2032)
		(layers "F.Cu" "B.Cu")
		(net "P1V2_AUX_BMC")
	)
	(via
		(at 444.32093 -44.730416)
		(size 0.508)
		(drill 0.254)
		(layers "F.Cu" "B.Cu")
		(net "P1V2_AUX_BMC")
	)
	(via
		(at 451.358 -29.4005)
		(size 0.508)
		(drill 0.254)
		(layers "F.Cu" "B.Cu")
		(net "P1V2_AUX_BMC")
	)
	(via
		(at 469.527128 -36.66744)
		(size 0.508)
		(drill 0.254)
		(layers "F.Cu" "B.Cu")
		(net "P1V2_AUX_BMC")
	)
	(via
		(at 443.425072 -28.382722)
		(size 0.4572)
		(drill 0.2032)
		(layers "F.Cu" "B.Cu")
		(net "P1V2_AUX_BMC")
	)
	(via
		(at 419.490144 -36.534598)
		(size 0.4572)
		(drill 0.2032)
		(layers "F.Cu" "B.Cu")
		(net "P1V2_AUX_BMC")
	)
	(via
		(at 452.30288 -39.0779)
		(size 0.508)
		(drill 0.254)
		(layers "F.Cu" "B.Cu")
		(net "P1V2_AUX_BMC")
	)
	(via
		(at 436.6514 -44.704)
		(size 0.508)
		(drill 0.254)
		(layers "F.Cu" "B.Cu")
		(net "P1V2_AUX_BMC")
	)
	(via
		(at 436.121556 -37.8333)
		(size 0.4572)
		(drill 0.2032)
		(layers "F.Cu" "B.Cu")
		(net "P1V2_AUX_BMC")
	)
	(via
		(at 436.921656 -31.4325)
		(size 0.4572)
		(drill 0.2032)
		(layers "F.Cu" "B.Cu")
		(net "P1V2_AUX_BMC")
	)
	(via
		(at 437.721756 -31.4325)
		(size 0.4572)
		(drill 0.2032)
		(layers "F.Cu" "B.Cu")
		(net "P1V2_AUX_BMC")
	)
	(via
		(at 442.849 -24.4856)
		(size 0.4572)
		(drill 0.2032)
		(layers "F.Cu" "B.Cu")
		(net "P1V2_AUX_BMC")
	)
	(via
		(at 443.322456 -29.8323)
		(size 0.4572)
		(drill 0.2032)
		(layers "F.Cu" "B.Cu")
		(net "P1V2_AUX_BMC")
	)
	(segment
		(start 443.827408 -36.738052)
		(end 443.322456 -36.2331)
		(width 0.254)
		(layer "B.Cu")
		(net "P1V2_AUX_BMC")
	)
	(segment
		(start 419.41115 -31.8135)
		(end 419.490144 -31.734506)
		(width 0.508)
		(layer "B.Cu")
		(net "P1V2_AUX_BMC")
	)
	(segment
		(start 419.271196 -34.3535)
		(end 419.490144 -34.134552)
		(width 0.381)
		(layer "B.Cu")
		(net "P1V2_AUX_BMC")
	)
	(segment
		(start 418.870638 -36.767516)
		(end 418.871654 -36.7665)
		(width 0.381)
		(layer "B.Cu")
		(net "P1V2_AUX_BMC")
	)
	(segment
		(start 418.719 -34.3535)
		(end 419.271196 -34.3535)
		(width 0.381)
		(layer "B.Cu")
		(net "P1V2_AUX_BMC")
	)
	(segment
		(start 418.719 -31.8135)
		(end 419.41115 -31.8135)
		(width 0.508)
		(layer "B.Cu")
		(net "P1V2_AUX_BMC")
	)
	(segment
		(start 442.6458 -24.2824)
		(end 442.0362 -24.2824)
		(width 0.381)
		(layer "B.Cu")
		(net "P1V2_AUX_BMC")
	)
	(segment
		(start 418.870638 -37.5285)
		(end 418.870638 -36.767516)
		(width 0.381)
		(layer "B.Cu")
		(net "P1V2_AUX_BMC")
	)
	(segment
		(start 444.1317 -36.738052)
		(end 443.827408 -36.738052)
		(width 0.254)
		(layer "B.Cu")
		(net "P1V2_AUX_BMC")
	)
	(segment
		(start 418.871654 -36.7665)
		(end 419.258242 -36.7665)
		(width 0.381)
		(layer "B.Cu")
		(net "P1V2_AUX_BMC")
	)
	(segment
		(start 442.849 -24.4856)
		(end 442.6458 -24.2824)
		(width 0.381)
		(layer "B.Cu")
		(net "P1V2_AUX_BMC")
	)
	(segment
		(start 436.638192 -44.690792)
		(end 436.6514 -44.704)
		(width 0.381)
		(layer "B.Cu")
		(net "P1V2_AUX_BMC")
	)
	(segment
		(start 419.258242 -36.7665)
		(end 419.490144 -36.534598)
		(width 0.381)
		(layer "B.Cu")
		(net "P1V2_AUX_BMC")
	)
	(segment
		(start 418.719 -34.3535)
		(end 418.719 -35.1155)
		(width 0.381)
		(layer "B.Cu")
		(net "P1V2_AUX_BMC")
	)
	(segment
		(start 420.69004 -39.334694)
		(end 421.09009 -39.734744)
		(width 0.254)
		(layer "F.Cu")
		(net "P1V15_AUX_BMC")
	)
	(segment
		(start 415.090102 -39.334694)
		(end 415.490152 -38.934644)
		(width 0.254)
		(layer "F.Cu")
		(net "P1V15_AUX_BMC")
	)
	(segment
		(start 411.89021 -31.33471)
		(end 411.09011 -30.53461)
		(width 0.254)
		(layer "F.Cu")
		(net "P1V15_AUX_BMC")
	)
	(via
		(at 413.090106 -38.134544)
		(size 0.4572)
		(drill 0.2032)
		(layers "F.Cu" "B.Cu")
		(net "P1V15_AUX_BMC")
	)
	(via
		(at 415.890202 -37.968936)
		(size 0.4572)
		(drill 0.2032)
		(layers "F.Cu" "B.Cu")
		(net "P1V15_AUX_BMC")
	)
	(via
		(at 459.08976 -41.15562)
		(size 0.508)
		(drill 0.254)
		(layers "F.Cu" "B.Cu")
		(net "P1V15_AUX_BMC")
	)
	(via
		(at 459.08976 -42.93362)
		(size 0.508)
		(drill 0.254)
		(layers "F.Cu" "B.Cu")
		(net "P1V15_AUX_BMC")
	)
	(via
		(at 459.08976 -42.04462)
		(size 0.508)
		(drill 0.254)
		(layers "F.Cu" "B.Cu")
		(net "P1V15_AUX_BMC")
	)
	(via
		(at 427.4693 -46.77156)
		(size 0.508)
		(drill 0.254)
		(layers "F.Cu" "B.Cu")
		(net "P1V15_AUX_BMC")
	)
	(via
		(at 412.29026 -31.73476)
		(size 0.4572)
		(drill 0.2032)
		(layers "F.Cu" "B.Cu")
		(net "P1V15_AUX_BMC")
	)
	(via
		(at 417.090098 -36.534598)
		(size 0.4572)
		(drill 0.2032)
		(layers "F.Cu" "B.Cu")
		(net "P1V15_AUX_BMC")
	)
	(via
		(at 417.890198 -31.73476)
		(size 0.4572)
		(drill 0.2032)
		(layers "F.Cu" "B.Cu")
		(net "P1V15_AUX_BMC")
	)
	(via
		(at 417.090098 -31.73476)
		(size 0.4572)
		(drill 0.2032)
		(layers "F.Cu" "B.Cu")
		(net "P1V15_AUX_BMC")
	)
	(via
		(at 426.8343 -46.583854)
		(size 0.508)
		(drill 0.254)
		(layers "F.Cu" "B.Cu")
		(net "P1V15_AUX_BMC")
	)
	(via
		(at 415.4805 -32.57296)
		(size 0.4572)
		(drill 0.2032)
		(layers "F.Cu" "B.Cu")
		(net "P1V15_AUX_BMC")
	)
	(via
		(at 412.29026 -37.334698)
		(size 0.4572)
		(drill 0.2032)
		(layers "F.Cu" "B.Cu")
		(net "P1V15_AUX_BMC")
	)
	(via
		(at 412.29026 -32.534606)
		(size 0.4572)
		(drill 0.2032)
		(layers "F.Cu" "B.Cu")
		(net "P1V15_AUX_BMC")
	)
	(via
		(at 421.09009 -39.734744)
		(size 0.508)
		(drill 0.254)
		(layers "F.Cu" "B.Cu")
		(net "P1V15_AUX_BMC")
	)
	(via
		(at 426.81398 -47.2186)
		(size 0.508)
		(drill 0.254)
		(layers "F.Cu" "B.Cu")
		(net "P1V15_AUX_BMC")
	)
	(via
		(at 412.29026 -35.734498)
		(size 0.4572)
		(drill 0.2032)
		(layers "F.Cu" "B.Cu")
		(net "P1V15_AUX_BMC")
	)
	(via
		(at 415.490152 -38.934644)
		(size 0.4572)
		(drill 0.2032)
		(layers "F.Cu" "B.Cu")
		(net "P1V15_AUX_BMC")
	)
	(via
		(at 412.29026 -34.134552)
		(size 0.4572)
		(drill 0.2032)
		(layers "F.Cu" "B.Cu")
		(net "P1V15_AUX_BMC")
	)
	(segment
		(start 425.862496 -47.122334)
		(end 425.862496 -46.3296)
		(width 0.10795)
		(layer "F.Cu")
		(net "GPIOS7")
	)
	(segment
		(start 425.919646 -47.179484)
		(end 425.919646 -48.079152)
		(width 0.10795)
		(layer "F.Cu")
		(net "GPIOS7")
	)
	(segment
		(start 425.862496 -47.122334)
		(end 425.919646 -47.179484)
		(width 0.10795)
		(layer "F.Cu")
		(net "GPIOS7")
	)
	(segment
		(start 424.2816 -42.3926)
		(end 424.0276 -42.1386)
		(width 0.10795)
		(layer "F.Cu")
		(net "GPIOS7")
	)
	(segment
		(start 424.2816 -42.824654)
		(end 424.2816 -42.3926)
		(width 0.10795)
		(layer "F.Cu")
		(net "GPIOS7")
	)
	(segment
		(start 424.482006 -44.94911)
		(end 424.482006 -43.02506)
		(width 0.10795)
		(layer "F.Cu")
		(net "GPIOS7")
	)
	(segment
		(start 424.482006 -43.02506)
		(end 424.2816 -42.824654)
		(width 0.10795)
		(layer "F.Cu")
		(net "GPIOS7")
	)
	(segment
		(start 424.0276 -42.1386)
		(end 423.493946 -42.1386)
		(width 0.10795)
		(layer "F.Cu")
		(net "GPIOS7")
	)
	(segment
		(start 423.493946 -42.1386)
		(end 423.090086 -41.73474)
		(width 0.10795)
		(layer "F.Cu")
		(net "GPIOS7")
	)
	(segment
		(start 425.862496 -46.3296)
		(end 424.482006 -44.94911)
		(width 0.10795)
		(layer "F.Cu")
		(net "GPIOS7")
	)
	(via
		(at 425.862496 -47.122334)
		(size 0.762)
		(drill 0.381)
		(layers "F.Cu" "B.Cu")
		(net "GPIOS7")
	)
	(segment
		(start 417.2077 -65.4812)
		(end 417.0045 -65.278)
		(width 0.10795)
		(layer "F.Cu")
		(net "FM_TPM_PRES_RST_N")
	)
	(segment
		(start 430.256442 -51.5366)
		(end 434.488844 -51.5366)
		(width 0.10795)
		(layer "F.Cu")
		(net "FM_TPM_PRES_RST_N")
	)
	(segment
		(start 426.41901 -54.75986)
		(end 426.41901 -50.796444)
		(width 0.10795)
		(layer "F.Cu")
		(net "FM_TPM_PRES_RST_N")
	)
	(segment
		(start 419.2016 -62.611)
		(end 419.2016 -61.97727)
		(width 0.10795)
		(layer "F.Cu")
		(net "FM_TPM_PRES_RST_N")
	)
	(segment
		(start 417.0045 -65.278)
		(end 417.0045 -64.897)
		(width 0.10795)
		(layer "F.Cu")
		(net "FM_TPM_PRES_RST_N")
	)
	(segment
		(start 398.13865 -111.57204)
		(end 398.63395 -111.802164)
		(width 0.10795)
		(layer "F.Cu")
		(net "FM_TPM_PRES_RST_N")
	)
	(segment
		(start 414.556448 -65.030096)
		(end 415.473896 -65.030096)
		(width 0.10795)
		(layer "F.Cu")
		(net "FM_TPM_PRES_RST_N")
	)
	(segment
		(start 428.696374 -49.976532)
		(end 430.256442 -51.5366)
		(width 0.10795)
		(layer "F.Cu")
		(net "FM_TPM_PRES_RST_N")
	)
	(segment
		(start 427.645068 -49.976532)
		(end 428.696374 -49.976532)
		(width 0.10795)
		(layer "F.Cu")
		(net "FM_TPM_PRES_RST_N")
	)
	(segment
		(start 434.488844 -51.5366)
		(end 435.912514 -50.11293)
		(width 0.10795)
		(layer "F.Cu")
		(net "FM_TPM_PRES_RST_N")
	)
	(segment
		(start 415.544 -65.1002)
		(end 416.3568 -65.1002)
		(width 0.10795)
		(layer "F.Cu")
		(net "FM_TPM_PRES_RST_N")
	)
	(segment
		(start 416.3568 -65.1002)
		(end 416.56 -64.897)
		(width 0.10795)
		(layer "F.Cu")
		(net "FM_TPM_PRES_RST_N")
	)
	(segment
		(start 418.36467 -65.4812)
		(end 417.2077 -65.4812)
		(width 0.10795)
		(layer "F.Cu")
		(net "FM_TPM_PRES_RST_N")
	)
	(segment
		(start 426.41901 -50.796444)
		(end 427.645068 -49.976532)
		(width 0.10795)
		(layer "F.Cu")
		(net "FM_TPM_PRES_RST_N")
	)
	(segment
		(start 435.912514 -47.724314)
		(end 435.1782 -46.99)
		(width 0.10795)
		(layer "F.Cu")
		(net "FM_TPM_PRES_RST_N")
	)
	(segment
		(start 435.1782 -46.99)
		(end 435.102 -46.99)
		(width 0.10795)
		(layer "F.Cu")
		(net "FM_TPM_PRES_RST_N")
	)
	(segment
		(start 415.473896 -65.030096)
		(end 415.544 -65.1002)
		(width 0.10795)
		(layer "F.Cu")
		(net "FM_TPM_PRES_RST_N")
	)
	(segment
		(start 419.2016 -61.97727)
		(end 426.41901 -54.75986)
		(width 0.10795)
		(layer "F.Cu")
		(net "FM_TPM_PRES_RST_N")
	)
	(segment
		(start 419.2016 -62.611)
		(end 419.2016 -64.64427)
		(width 0.10795)
		(layer "F.Cu")
		(net "FM_TPM_PRES_RST_N")
	)
	(segment
		(start 435.912514 -50.11293)
		(end 435.912514 -47.724314)
		(width 0.10795)
		(layer "F.Cu")
		(net "FM_TPM_PRES_RST_N")
	)
	(segment
		(start 419.2016 -64.64427)
		(end 418.36467 -65.4812)
		(width 0.10795)
		(layer "F.Cu")
		(net "FM_TPM_PRES_RST_N")
	)
	(segment
		(start 416.56 -64.897)
		(end 417.0045 -64.897)
		(width 0.10795)
		(layer "F.Cu")
		(net "FM_TPM_PRES_RST_N")
	)
	(via
		(at 395.98092 -91.47302)
		(size 0.508)
		(drill 0.254)
		(layers "F.Cu" "B.Cu")
		(net "FM_TPM_PRES_RST_N")
	)
	(via
		(at 398.63395 -111.802164)
		(size 0.508)
		(drill 0.254)
		(layers "F.Cu" "B.Cu")
		(net "FM_TPM_PRES_RST_N")
	)
	(via
		(at 435.102 -46.99)
		(size 0.508)
		(drill 0.254)
		(layers "F.Cu" "B.Cu")
		(net "FM_TPM_PRES_RST_N")
	)
	(via
		(at 419.2016 -62.611)
		(size 0.762)
		(drill 0.381)
		(layers "F.Cu" "B.Cu")
		(net "FM_TPM_PRES_RST_N")
	)
	(segment
		(start 451.20052 -21.336)
		(end 451.612 -21.336)
		(width 0.10795)
		(layer "B.Cu")
		(net "FM_TPM_PRES_RST_N")
	)
	(segment
		(start 453.47382 -43.829986)
		(end 453.47382 -45.998384)
		(width 0.10795)
		(layer "B.Cu")
		(net "FM_TPM_PRES_RST_N")
	)
	(segment
		(start 457.86167 -31.469076)
		(end 457.86167 -30.959298)
		(width 0.10795)
		(layer "B.Cu")
		(net "FM_TPM_PRES_RST_N")
	)
	(segment
		(start 452.619618 -21.336)
		(end 451.612 -21.336)
		(width 0.10795)
		(layer "B.Cu")
		(net "FM_TPM_PRES_RST_N")
	)
	(segment
		(start 444.900812 -19.869912)
		(end 446.716404 -19.869912)
		(width 0.10795)
		(layer "B.Cu")
		(net "FM_TPM_PRES_RST_N")
	)
	(segment
		(start 442.5061 -22.3393)
		(end 441.8838 -22.3393)
		(width 0.10795)
		(layer "B.Cu")
		(net "FM_TPM_PRES_RST_N")
	)
	(segment
		(start 453.4535 -26.934922)
		(end 453.4535 -22.169882)
		(width 0.10795)
		(layer "B.Cu")
		(net "FM_TPM_PRES_RST_N")
	)
	(segment
		(start 453.47382 -45.998384)
		(end 453.117204 -46.355)
		(width 0.10795)
		(layer "B.Cu")
		(net "FM_TPM_PRES_RST_N")
	)
	(segment
		(start 457.208128 -30.68955)
		(end 453.4535 -26.934922)
		(width 0.10795)
		(layer "B.Cu")
		(net "FM_TPM_PRES_RST_N")
	)
	(segment
		(start 442.158882 -18.42262)
		(end 444.174118 -18.42262)
		(width 0.10795)
		(layer "B.Cu")
		(net "FM_TPM_PRES_RST_N")
	)
	(segment
		(start 447.435732 -20.58924)
		(end 447.8655 -20.58924)
		(width 0.10795)
		(layer "B.Cu")
		(net "FM_TPM_PRES_RST_N")
	)
	(segment
		(start 435.737 -46.355)
		(end 435.102 -46.99)
		(width 0.10795)
		(layer "B.Cu")
		(net "FM_TPM_PRES_RST_N")
	)
	(segment
		(start 444.174118 -18.42262)
		(end 444.627 -18.875502)
		(width 0.10795)
		(layer "B.Cu")
		(net "FM_TPM_PRES_RST_N")
	)
	(segment
		(start 450.4563 -20.59178)
		(end 451.20052 -21.336)
		(width 0.10795)
		(layer "B.Cu")
		(net "FM_TPM_PRES_RST_N")
	)
	(segment
		(start 448.967098 -20.59178)
		(end 448.964558 -20.58924)
		(width 0.10795)
		(layer "B.Cu")
		(net "FM_TPM_PRES_RST_N")
	)
	(segment
		(start 441.7314 -22.1869)
		(end 441.7314 -18.850102)
		(width 0.10795)
		(layer "B.Cu")
		(net "FM_TPM_PRES_RST_N")
	)
	(segment
		(start 444.627 -19.5961)
		(end 444.900812 -19.869912)
		(width 0.10795)
		(layer "B.Cu")
		(net "FM_TPM_PRES_RST_N")
	)
	(segment
		(start 456.787758 -32.062674)
		(end 457.268072 -32.062674)
		(width 0.10795)
		(layer "B.Cu")
		(net "FM_TPM_PRES_RST_N")
	)
	(segment
		(start 456.025758 -32.353758)
		(end 456.472544 -32.800544)
		(width 0.10795)
		(layer "B.Cu")
		(net "FM_TPM_PRES_RST_N")
	)
	(segment
		(start 453.4535 -22.169882)
		(end 452.619618 -21.336)
		(width 0.10795)
		(layer "B.Cu")
		(net "FM_TPM_PRES_RST_N")
	)
	(segment
		(start 441.7314 -18.850102)
		(end 442.158882 -18.42262)
		(width 0.10795)
		(layer "B.Cu")
		(net "FM_TPM_PRES_RST_N")
	)
	(segment
		(start 453.117204 -46.355)
		(end 435.737 -46.355)
		(width 0.10795)
		(layer "B.Cu")
		(net "FM_TPM_PRES_RST_N")
	)
	(segment
		(start 444.627 -18.875502)
		(end 444.627 -19.5961)
		(width 0.10795)
		(layer "B.Cu")
		(net "FM_TPM_PRES_RST_N")
	)
	(segment
		(start 453.009 -43.365166)
		(end 453.47382 -43.829986)
		(width 0.10795)
		(layer "B.Cu")
		(net "FM_TPM_PRES_RST_N")
	)
	(segment
		(start 453.263 -42.164)
		(end 453.009 -42.418)
		(width 0.10795)
		(layer "B.Cu")
		(net "FM_TPM_PRES_RST_N")
	)
	(segment
		(start 448.964558 -20.58924)
		(end 447.8655 -20.58924)
		(width 0.10795)
		(layer "B.Cu")
		(net "FM_TPM_PRES_RST_N")
	)
	(segment
		(start 456.787758 -32.062674)
		(end 456.025758 -32.062674)
		(width 0.10795)
		(layer "B.Cu")
		(net "FM_TPM_PRES_RST_N")
	)
	(segment
		(start 446.716404 -19.869912)
		(end 447.435732 -20.58924)
		(width 0.10795)
		(layer "B.Cu")
		(net "FM_TPM_PRES_RST_N")
	)
	(segment
		(start 456.306428 -34.09442)
		(end 454.559416 -34.09442)
		(width 0.10795)
		(layer "B.Cu")
		(net "FM_TPM_PRES_RST_N")
	)
	(segment
		(start 453.367648 -35.286188)
		(end 453.367648 -40.132)
		(width 0.10795)
		(layer "B.Cu")
		(net "FM_TPM_PRES_RST_N")
	)
	(segment
		(start 456.025758 -32.062674)
		(end 456.025758 -32.353758)
		(width 0.10795)
		(layer "B.Cu")
		(net "FM_TPM_PRES_RST_N")
	)
	(segment
		(start 454.559416 -34.09442)
		(end 453.367648 -35.286188)
		(width 0.10795)
		(layer "B.Cu")
		(net "FM_TPM_PRES_RST_N")
	)
	(segment
		(start 457.86167 -30.959298)
		(end 457.591922 -30.68955)
		(width 0.10795)
		(layer "B.Cu")
		(net "FM_TPM_PRES_RST_N")
	)
	(segment
		(start 449.3895 -20.59178)
		(end 448.967098 -20.59178)
		(width 0.10795)
		(layer "B.Cu")
		(net "FM_TPM_PRES_RST_N")
	)
	(segment
		(start 453.009 -42.418)
		(end 453.009 -43.365166)
		(width 0.10795)
		(layer "B.Cu")
		(net "FM_TPM_PRES_RST_N")
	)
	(segment
		(start 457.268072 -32.062674)
		(end 457.86167 -31.469076)
		(width 0.10795)
		(layer "B.Cu")
		(net "FM_TPM_PRES_RST_N")
	)
	(segment
		(start 449.3895 -20.59178)
		(end 450.4563 -20.59178)
		(width 0.10795)
		(layer "B.Cu")
		(net "FM_TPM_PRES_RST_N")
	)
	(segment
		(start 454.025 -41.783)
		(end 453.644 -42.164)
		(width 0.10795)
		(layer "B.Cu")
		(net "FM_TPM_PRES_RST_N")
	)
	(segment
		(start 454.025 -40.789352)
		(end 454.025 -41.783)
		(width 0.10795)
		(layer "B.Cu")
		(net "FM_TPM_PRES_RST_N")
	)
	(segment
		(start 456.472544 -33.928304)
		(end 456.306428 -34.09442)
		(width 0.10795)
		(layer "B.Cu")
		(net "FM_TPM_PRES_RST_N")
	)
	(segment
		(start 441.8838 -22.3393)
		(end 441.7314 -22.1869)
		(width 0.10795)
		(layer "B.Cu")
		(net "FM_TPM_PRES_RST_N")
	)
	(segment
		(start 453.644 -42.164)
		(end 453.263 -42.164)
		(width 0.10795)
		(layer "B.Cu")
		(net "FM_TPM_PRES_RST_N")
	)
	(segment
		(start 456.472544 -32.800544)
		(end 456.472544 -33.928304)
		(width 0.10795)
		(layer "B.Cu")
		(net "FM_TPM_PRES_RST_N")
	)
	(segment
		(start 453.367648 -40.132)
		(end 454.025 -40.789352)
		(width 0.10795)
		(layer "B.Cu")
		(net "FM_TPM_PRES_RST_N")
	)
	(segment
		(start 457.591922 -30.68955)
		(end 457.208128 -30.68955)
		(width 0.10795)
		(layer "B.Cu")
		(net "FM_TPM_PRES_RST_N")
	)
	(segment
		(start 410.959808 -56.480202)
		(end 411.67431 -55.7657)
		(width 0.089408)
		(layer "In9.Cu")
		(net "FM_TPM_PRES_RST_N")
	)
	(segment
		(start 433.976018 -45.864018)
		(end 435.102 -46.99)
		(width 0.089408)
		(layer "In9.Cu")
		(net "FM_TPM_PRES_RST_N")
	)
	(segment
		(start 403.281134 -81.388712)
		(end 403.700996 -81.388712)
		(width 0.089408)
		(layer "In9.Cu")
		(net "FM_TPM_PRES_RST_N")
	)
	(segment
		(start 404.452836 -74.650854)
		(end 408.391868 -70.711822)
		(width 0.089408)
		(layer "In9.Cu")
		(net "FM_TPM_PRES_RST_N")
	)
	(segment
		(start 410.959808 -60.398406)
		(end 410.959808 -56.480202)
		(width 0.089408)
		(layer "In9.Cu")
		(net "FM_TPM_PRES_RST_N")
	)
	(segment
		(start 424.2689 -48.10506)
		(end 427.34738 -48.10506)
		(width 0.089408)
		(layer "In9.Cu")
		(net "FM_TPM_PRES_RST_N")
	)
	(segment
		(start 395.98092 -91.47302)
		(end 400.961606 -86.492334)
		(width 0.089408)
		(layer "In9.Cu")
		(net "FM_TPM_PRES_RST_N")
	)
	(segment
		(start 411.67431 -55.7657)
		(end 411.9499 -55.7657)
		(width 0.089408)
		(layer "In9.Cu")
		(net "FM_TPM_PRES_RST_N")
	)
	(segment
		(start 411.109922 -60.54852)
		(end 410.959808 -60.398406)
		(width 0.089408)
		(layer "In9.Cu")
		(net "FM_TPM_PRES_RST_N")
	)
	(segment
		(start 404.228046 -80.875886)
		(end 404.671784 -80.432148)
		(width 0.089408)
		(layer "In9.Cu")
		(net "FM_TPM_PRES_RST_N")
	)
	(segment
		(start 402.92274 -83.72856)
		(end 402.92274 -81.747106)
		(width 0.089408)
		(layer "In9.Cu")
		(net "FM_TPM_PRES_RST_N")
	)
	(segment
		(start 411.9499 -55.7657)
		(end 411.950154 -55.765954)
		(width 0.089408)
		(layer "In9.Cu")
		(net "FM_TPM_PRES_RST_N")
	)
	(segment
		(start 408.391868 -70.444614)
		(end 411.109922 -67.72656)
		(width 0.089408)
		(layer "In9.Cu")
		(net "FM_TPM_PRES_RST_N")
	)
	(segment
		(start 416.995356 -52.208684)
		(end 418.537136 -52.208684)
		(width 0.089408)
		(layer "In9.Cu")
		(net "FM_TPM_PRES_RST_N")
	)
	(segment
		(start 415.40049 -53.80355)
		(end 416.995356 -52.208684)
		(width 0.089408)
		(layer "In9.Cu")
		(net "FM_TPM_PRES_RST_N")
	)
	(segment
		(start 423.233088 -49.140872)
		(end 424.2689 -48.10506)
		(width 0.089408)
		(layer "In9.Cu")
		(net "FM_TPM_PRES_RST_N")
	)
	(segment
		(start 420.822882 -50.86858)
		(end 422.55059 -49.140872)
		(width 0.089408)
		(layer "In9.Cu")
		(net "FM_TPM_PRES_RST_N")
	)
	(segment
		(start 404.213822 -80.875886)
		(end 404.228046 -80.875886)
		(width 0.089408)
		(layer "In9.Cu")
		(net "FM_TPM_PRES_RST_N")
	)
	(segment
		(start 429.207422 -45.864018)
		(end 433.976018 -45.864018)
		(width 0.089408)
		(layer "In9.Cu")
		(net "FM_TPM_PRES_RST_N")
	)
	(segment
		(start 413.446468 -55.74792)
		(end 414.037526 -55.74792)
		(width 0.089408)
		(layer "In9.Cu")
		(net "FM_TPM_PRES_RST_N")
	)
	(segment
		(start 402.92274 -81.747106)
		(end 403.281134 -81.388712)
		(width 0.089408)
		(layer "In9.Cu")
		(net "FM_TPM_PRES_RST_N")
	)
	(segment
		(start 419.87724 -50.86858)
		(end 420.822882 -50.86858)
		(width 0.089408)
		(layer "In9.Cu")
		(net "FM_TPM_PRES_RST_N")
	)
	(segment
		(start 411.950154 -55.765954)
		(end 413.428434 -55.765954)
		(width 0.089408)
		(layer "In9.Cu")
		(net "FM_TPM_PRES_RST_N")
	)
	(segment
		(start 408.391868 -70.711822)
		(end 408.391868 -70.444614)
		(width 0.089408)
		(layer "In9.Cu")
		(net "FM_TPM_PRES_RST_N")
	)
	(segment
		(start 411.109922 -67.72656)
		(end 411.109922 -60.54852)
		(width 0.089408)
		(layer "In9.Cu")
		(net "FM_TPM_PRES_RST_N")
	)
	(segment
		(start 422.55059 -49.140872)
		(end 423.233088 -49.140872)
		(width 0.089408)
		(layer "In9.Cu")
		(net "FM_TPM_PRES_RST_N")
	)
	(segment
		(start 427.34738 -48.10506)
		(end 429.1076 -46.34484)
		(width 0.089408)
		(layer "In9.Cu")
		(net "FM_TPM_PRES_RST_N")
	)
	(segment
		(start 403.700996 -81.388712)
		(end 404.213822 -80.875886)
		(width 0.089408)
		(layer "In9.Cu")
		(net "FM_TPM_PRES_RST_N")
	)
	(segment
		(start 418.537136 -52.208684)
		(end 419.87724 -50.86858)
		(width 0.089408)
		(layer "In9.Cu")
		(net "FM_TPM_PRES_RST_N")
	)
	(segment
		(start 415.40049 -54.384956)
		(end 415.40049 -53.80355)
		(width 0.089408)
		(layer "In9.Cu")
		(net "FM_TPM_PRES_RST_N")
	)
	(segment
		(start 413.428434 -55.765954)
		(end 413.446468 -55.74792)
		(width 0.089408)
		(layer "In9.Cu")
		(net "FM_TPM_PRES_RST_N")
	)
	(segment
		(start 404.671784 -80.432148)
		(end 404.671784 -79.803752)
		(width 0.089408)
		(layer "In9.Cu")
		(net "FM_TPM_PRES_RST_N")
	)
	(segment
		(start 429.1076 -45.96384)
		(end 429.207422 -45.864018)
		(width 0.089408)
		(layer "In9.Cu")
		(net "FM_TPM_PRES_RST_N")
	)
	(segment
		(start 400.961606 -86.492334)
		(end 400.961606 -85.692488)
		(width 0.089408)
		(layer "In9.Cu")
		(net "FM_TPM_PRES_RST_N")
	)
	(segment
		(start 429.1076 -46.34484)
		(end 429.1076 -45.96384)
		(width 0.089408)
		(layer "In9.Cu")
		(net "FM_TPM_PRES_RST_N")
	)
	(segment
		(start 404.671784 -79.803752)
		(end 404.452836 -79.584804)
		(width 0.089408)
		(layer "In9.Cu")
		(net "FM_TPM_PRES_RST_N")
	)
	(segment
		(start 400.961606 -85.692488)
		(end 402.92274 -83.72856)
		(width 0.089408)
		(layer "In9.Cu")
		(net "FM_TPM_PRES_RST_N")
	)
	(segment
		(start 414.037526 -55.74792)
		(end 415.40049 -54.384956)
		(width 0.089408)
		(layer "In9.Cu")
		(net "FM_TPM_PRES_RST_N")
	)
	(segment
		(start 404.452836 -79.584804)
		(end 404.452836 -74.650854)
		(width 0.089408)
		(layer "In9.Cu")
		(net "FM_TPM_PRES_RST_N")
	)
	(segment
		(start 399.104866 -111.802164)
		(end 398.63395 -111.802164)
		(width 0.089408)
		(layer "In11.Cu")
		(net "FM_TPM_PRES_RST_N")
	)
	(segment
		(start 399.94078 -110.96625)
		(end 399.104866 -111.802164)
		(width 0.089408)
		(layer "In11.Cu")
		(net "FM_TPM_PRES_RST_N")
	)
	(segment
		(start 395.522196 -91.931744)
		(end 395.522196 -93.018864)
		(width 0.089408)
		(layer "In11.Cu")
		(net "FM_TPM_PRES_RST_N")
	)
	(segment
		(start 399.94078 -96.444816)
		(end 399.94078 -110.96625)
		(width 0.089408)
		(layer "In11.Cu")
		(net "FM_TPM_PRES_RST_N")
	)
	(segment
		(start 396.928086 -94.424754)
		(end 397.920718 -94.424754)
		(width 0.089408)
		(layer "In11.Cu")
		(net "FM_TPM_PRES_RST_N")
	)
	(segment
		(start 397.920718 -94.424754)
		(end 399.94078 -96.444816)
		(width 0.089408)
		(layer "In11.Cu")
		(net "FM_TPM_PRES_RST_N")
	)
	(segment
		(start 395.98092 -91.47302)
		(end 395.522196 -91.931744)
		(width 0.089408)
		(layer "In11.Cu")
		(net "FM_TPM_PRES_RST_N")
	)
	(segment
		(start 395.522196 -93.018864)
		(end 396.928086 -94.424754)
		(width 0.089408)
		(layer "In11.Cu")
		(net "FM_TPM_PRES_RST_N")
	)
	(via
		(at 439.74512 -22.66188)
		(size 0.6604)
		(drill 0.3302)
		(layers "F.Cu" "B.Cu")
		(net "FM_TPM_PRES_RST")
	)
	(segment
		(start 439.63717 -22.66188)
		(end 439.52922 -22.55393)
		(width 0.10795)
		(layer "B.Cu")
		(net "FM_TPM_PRES_RST")
	)
	(segment
		(start 439.52922 -22.55393)
		(end 439.52922 -21.96338)
		(width 0.10795)
		(layer "B.Cu")
		(net "FM_TPM_PRES_RST")
	)
	(segment
		(start 439.74512 -22.66188)
		(end 439.63717 -22.66188)
		(width 0.10795)
		(layer "B.Cu")
		(net "FM_TPM_PRES_RST")
	)
	(segment
		(start 440.7281 -19.9263)
		(end 440.7281 -22.36089)
		(width 0.10795)
		(layer "B.Cu")
		(net "FM_TPM_PRES_RST")
	)
	(segment
		(start 439.91784 -21.29282)
		(end 439.91784 -20.80768)
		(width 0.10795)
		(layer "B.Cu")
		(net "FM_TPM_PRES_RST")
	)
	(segment
		(start 439.91784 -21.57476)
		(end 439.91784 -21.29282)
		(width 0.10795)
		(layer "B.Cu")
		(net "FM_TPM_PRES_RST")
	)
	(segment
		(start 439.30316 -20.193)
		(end 437.769 -20.193)
		(width 0.10795)
		(layer "B.Cu")
		(net "FM_TPM_PRES_RST")
	)
	(segment
		(start 439.52922 -21.96338)
		(end 439.91784 -21.57476)
		(width 0.10795)
		(layer "B.Cu")
		(net "FM_TPM_PRES_RST")
	)
	(segment
		(start 439.91784 -20.80768)
		(end 439.30316 -20.193)
		(width 0.10795)
		(layer "B.Cu")
		(net "FM_TPM_PRES_RST")
	)
	(segment
		(start 440.7281 -22.36089)
		(end 440.42711 -22.66188)
		(width 0.10795)
		(layer "B.Cu")
		(net "FM_TPM_PRES_RST")
	)
	(segment
		(start 440.42711 -22.66188)
		(end 439.74512 -22.66188)
		(width 0.10795)
		(layer "B.Cu")
		(net "FM_TPM_PRES_RST")
	)
	(segment
		(start 492.14278 -152.91816)
		(end 492.28502 -152.77592)
		(width 0.10795)
		(layer "F.Cu")
		(net "SPA_MID_DBG1_RX")
	)
	(segment
		(start 491.413546 -152.91816)
		(end 492.14278 -152.91816)
		(width 0.10795)
		(layer "F.Cu")
		(net "SPA_MID_DBG1_RX")
	)
	(segment
		(start 483.616 -138.120628)
		(end 484.258112 -138.120628)
		(width 0.10795)
		(layer "F.Cu")
		(net "SPA_MID_DBG1_RX")
	)
	(segment
		(start 484.258112 -138.120628)
		(end 484.505 -138.367516)
		(width 0.10795)
		(layer "F.Cu")
		(net "SPA_MID_DBG1_RX")
	)
	(segment
		(start 484.505 -138.367516)
		(end 484.505 -138.5824)
		(width 0.10795)
		(layer "F.Cu")
		(net "SPA_MID_DBG1_RX")
	)
	(via
		(at 497.6622 -131.572)
		(size 0.508)
		(drill 0.254)
		(layers "F.Cu" "B.Cu")
		(net "SPA_MID_DBG1_RX")
	)
	(via
		(at 484.505 -138.5824)
		(size 0.508)
		(drill 0.254)
		(layers "F.Cu" "B.Cu")
		(net "SPA_MID_DBG1_RX")
	)
	(via
		(at 492.28502 -152.77592)
		(size 0.508)
		(drill 0.254)
		(layers "F.Cu" "B.Cu")
		(net "SPA_MID_DBG1_RX")
	)
	(segment
		(start 492.325406 -152.816306)
		(end 492.28502 -152.77592)
		(width 0.089408)
		(layer "In2.Cu")
		(net "SPA_MID_DBG1_RX")
	)
	(segment
		(start 496.582954 -152.816306)
		(end 492.325406 -152.816306)
		(width 0.089408)
		(layer "In2.Cu")
		(net "SPA_MID_DBG1_RX")
	)
	(segment
		(start 497.6622 -131.572)
		(end 497.68633 -131.59613)
		(width 0.089408)
		(layer "In2.Cu")
		(net "SPA_MID_DBG1_RX")
	)
	(segment
		(start 497.68633 -131.59613)
		(end 497.68633 -132.77977)
		(width 0.089408)
		(layer "In2.Cu")
		(net "SPA_MID_DBG1_RX")
	)
	(segment
		(start 498.502686 -138.888724)
		(end 497.117624 -140.273786)
		(width 0.089408)
		(layer "In2.Cu")
		(net "SPA_MID_DBG1_RX")
	)
	(segment
		(start 497.117624 -140.273786)
		(end 497.117624 -152.281636)
		(width 0.089408)
		(layer "In2.Cu")
		(net "SPA_MID_DBG1_RX")
	)
	(segment
		(start 498.502686 -133.596126)
		(end 498.502686 -138.888724)
		(width 0.089408)
		(layer "In2.Cu")
		(net "SPA_MID_DBG1_RX")
	)
	(segment
		(start 497.117624 -152.281636)
		(end 496.582954 -152.816306)
		(width 0.089408)
		(layer "In2.Cu")
		(net "SPA_MID_DBG1_RX")
	)
	(segment
		(start 497.68633 -132.77977)
		(end 498.502686 -133.596126)
		(width 0.089408)
		(layer "In2.Cu")
		(net "SPA_MID_DBG1_RX")
	)
	(segment
		(start 497.6622 -131.572)
		(end 497.421154 -131.813046)
		(width 0.0889)
		(layer "In9.Cu")
		(net "SPA_MID_DBG1_RX")
	)
	(segment
		(start 497.421154 -131.813046)
		(end 497.141754 -131.813046)
		(width 0.0889)
		(layer "In9.Cu")
		(net "SPA_MID_DBG1_RX")
	)
	(segment
		(start 484.505 -137.3124)
		(end 484.505 -138.5824)
		(width 0.0889)
		(layer "In9.Cu")
		(net "SPA_MID_DBG1_RX")
	)
	(segment
		(start 490.26699 -133.7056)
		(end 489.125768 -134.846822)
		(width 0.0889)
		(layer "In9.Cu")
		(net "SPA_MID_DBG1_RX")
	)
	(segment
		(start 497.141754 -131.813046)
		(end 495.2492 -133.7056)
		(width 0.0889)
		(layer "In9.Cu")
		(net "SPA_MID_DBG1_RX")
	)
	(segment
		(start 495.2492 -133.7056)
		(end 490.26699 -133.7056)
		(width 0.0889)
		(layer "In9.Cu")
		(net "SPA_MID_DBG1_RX")
	)
	(segment
		(start 486.970578 -134.846822)
		(end 484.505 -137.3124)
		(width 0.0889)
		(layer "In9.Cu")
		(net "SPA_MID_DBG1_RX")
	)
	(segment
		(start 489.125768 -134.846822)
		(end 486.970578 -134.846822)
		(width 0.0889)
		(layer "In9.Cu")
		(net "SPA_MID_DBG1_RX")
	)
	(segment
		(start 433.1462 -31.1658)
		(end 433.1462 -30.90037)
		(width 0.10795)
		(layer "F.Cu")
		(net "BMC_ZQ")
	)
	(segment
		(start 435.162198 -30.79242)
		(end 433.705 -30.79242)
		(width 0.10795)
		(layer "F.Cu")
		(net "BMC_ZQ")
	)
	(segment
		(start 433.1462 -30.90037)
		(end 433.25415 -30.79242)
		(width 0.10795)
		(layer "F.Cu")
		(net "BMC_ZQ")
	)
	(segment
		(start 433.3494 -31.369)
		(end 433.1462 -31.1658)
		(width 0.10795)
		(layer "F.Cu")
		(net "BMC_ZQ")
	)
	(segment
		(start 433.3494 -31.7373)
		(end 433.3494 -31.369)
		(width 0.10795)
		(layer "F.Cu")
		(net "BMC_ZQ")
	)
	(segment
		(start 433.25415 -30.79242)
		(end 433.705 -30.79242)
		(width 0.10795)
		(layer "F.Cu")
		(net "BMC_ZQ")
	)
	(segment
		(start 436.522114 -29.432504)
		(end 435.162198 -30.79242)
		(width 0.10795)
		(layer "F.Cu")
		(net "BMC_ZQ")
	)
	(via
		(at 433.705 -30.79242)
		(size 0.508)
		(drill 0.254)
		(layers "F.Cu" "B.Cu")
		(net "BMC_ZQ")
	)
	(segment
		(start 451.66407 -17.749266)
		(end 452.095362 -17.749266)
		(width 0.10795)
		(layer "B.Cu")
		(net "BMC_TPM_HW_C_RST")
	)
	(segment
		(start 452.5645 -19.177)
		(end 452.5645 -18.218404)
		(width 0.10795)
		(layer "B.Cu")
		(net "BMC_TPM_HW_C_RST")
	)
	(segment
		(start 453.5551 -19.177)
		(end 453.8218 -19.4437)
		(width 0.10795)
		(layer "B.Cu")
		(net "BMC_TPM_HW_C_RST")
	)
	(segment
		(start 451.030594 -17.9451)
		(end 451.468236 -17.9451)
		(width 0.10795)
		(layer "B.Cu")
		(net "BMC_TPM_HW_C_RST")
	)
	(segment
		(start 452.5645 -18.218404)
		(end 452.095362 -17.749266)
		(width 0.10795)
		(layer "B.Cu")
		(net "BMC_TPM_HW_C_RST")
	)
	(segment
		(start 453.8218 -19.4437)
		(end 453.8218 -19.7993)
		(width 0.10795)
		(layer "B.Cu")
		(net "BMC_TPM_HW_C_RST")
	)
	(segment
		(start 451.468236 -17.9451)
		(end 451.66407 -17.749266)
		(width 0.10795)
		(layer "B.Cu")
		(net "BMC_TPM_HW_C_RST")
	)
	(segment
		(start 452.5645 -19.177)
		(end 453.5551 -19.177)
		(width 0.10795)
		(layer "B.Cu")
		(net "BMC_TPM_HW_C_RST")
	)
	(segment
		(start 443.252606 -33.0327)
		(end 444.065406 -32.2199)
		(width 0.10795)
		(layer "F.Cu")
		(net "BMC_M_WE_N")
	)
	(segment
		(start 450.14388 -30.983174)
		(end 450.14388 -31.3055)
		(width 0.10795)
		(layer "F.Cu")
		(net "BMC_M_WE_N")
	)
	(segment
		(start 444.636906 -30.734)
		(end 446.173606 -30.734)
		(width 0.10795)
		(layer "F.Cu")
		(net "BMC_M_WE_N")
	)
	(segment
		(start 442.522356 -33.0327)
		(end 443.252606 -33.0327)
		(width 0.10795)
		(layer "F.Cu")
		(net "BMC_M_WE_N")
	)
	(segment
		(start 442.12256 -33.432496)
		(end 442.522356 -33.0327)
		(width 0.10795)
		(layer "F.Cu")
		(net "BMC_M_WE_N")
	)
	(segment
		(start 422.29024 -35.334702)
		(end 421.89019 -35.734752)
		(width 0.1016)
		(layer "F.Cu")
		(net "BMC_M_WE_N")
	)
	(segment
		(start 442.122052 -33.432496)
		(end 442.12256 -33.432496)
		(width 0.10795)
		(layer "F.Cu")
		(net "BMC_M_WE_N")
	)
	(segment
		(start 449.894706 -30.734)
		(end 450.14388 -30.983174)
		(width 0.10795)
		(layer "F.Cu")
		(net "BMC_M_WE_N")
	)
	(segment
		(start 444.065406 -31.3055)
		(end 444.636906 -30.734)
		(width 0.10795)
		(layer "F.Cu")
		(net "BMC_M_WE_N")
	)
	(segment
		(start 451.41388 -31.3055)
		(end 450.14388 -31.3055)
		(width 0.10795)
		(layer "F.Cu")
		(net "BMC_M_WE_N")
	)
	(segment
		(start 444.065406 -32.2199)
		(end 444.065406 -31.3055)
		(width 0.10795)
		(layer "F.Cu")
		(net "BMC_M_WE_N")
	)
	(segment
		(start 446.173606 -30.734)
		(end 449.894706 -30.734)
		(width 0.10795)
		(layer "F.Cu")
		(net "BMC_M_WE_N")
	)
	(via
		(at 442.522356 -33.0327)
		(size 0.4572)
		(drill 0.2032)
		(layers "F.Cu" "B.Cu")
		(net "BMC_M_WE_N")
	)
	(via
		(at 446.173606 -30.734)
		(size 0.508)
		(drill 0.254)
		(layers "F.Cu" "B.Cu")
		(net "BMC_M_WE_N")
	)
	(via
		(at 421.89019 -35.734752)
		(size 0.4572)
		(drill 0.2032)
		(layers "F.Cu" "B.Cu")
		(net "BMC_M_WE_N")
	)
	(segment
		(start 440.941968 -33.269428)
		(end 440.877198 -33.204658)
		(width 0.089408)
		(layer "In2.Cu")
		(net "BMC_M_WE_N")
	)
	(segment
		(start 433.105814 -35.028124)
		(end 433.07127 -35.062668)
		(width 0.089408)
		(layer "In2.Cu")
		(net "BMC_M_WE_N")
	)
	(segment
		(start 440.58459 -33.0835)
		(end 438.551066 -33.0835)
		(width 0.089408)
		(layer "In2.Cu")
		(net "BMC_M_WE_N")
	)
	(segment
		(start 431.177446 -36.279328)
		(end 430.966626 -36.279328)
		(width 0.089408)
		(layer "In2.Cu")
		(net "BMC_M_WE_N")
	)
	(segment
		(start 437.745378 -33.417256)
		(end 435.761892 -33.417256)
		(width 0.089408)
		(layer "In2.Cu")
		(net "BMC_M_WE_N")
	)
	(segment
		(start 432.493928 -35.062668)
		(end 432.44008 -35.116516)
		(width 0.089408)
		(layer "In2.Cu")
		(net "BMC_M_WE_N")
	)
	(segment
		(start 432.773074 -35.062922)
		(end 432.77282 -35.062668)
		(width 0.089408)
		(layer "In2.Cu")
		(net "BMC_M_WE_N")
	)
	(segment
		(start 442.66358 -33.51911)
		(end 441.54471 -33.51911)
		(width 0.089408)
		(layer "In2.Cu")
		(net "BMC_M_WE_N")
	)
	(segment
		(start 423.756074 -36.128452)
		(end 422.652444 -36.128452)
		(width 0.089408)
		(layer "In2.Cu")
		(net "BMC_M_WE_N")
	)
	(segment
		(start 422.392094 -36.020756)
		(end 422.220644 -35.849052)
		(width 0.089408)
		(layer "In2.Cu")
		(net "BMC_M_WE_N")
	)
	(segment
		(start 432.44008 -35.395408)
		(end 432.440334 -35.395662)
		(width 0.089408)
		(layer "In2.Cu")
		(net "BMC_M_WE_N")
	)
	(segment
		(start 433.438554 -34.397442)
		(end 433.4383 -34.397188)
		(width 0.089408)
		(layer "In2.Cu")
		(net "BMC_M_WE_N")
	)
	(segment
		(start 424.791124 -36.648136)
		(end 424.63593 -36.492942)
		(width 0.089408)
		(layer "In2.Cu")
		(net "BMC_M_WE_N")
	)
	(segment
		(start 429.439832 -36.911788)
		(end 425.427648 -36.911788)
		(width 0.089408)
		(layer "In2.Cu")
		(net "BMC_M_WE_N")
	)
	(segment
		(start 433.159408 -34.397188)
		(end 433.10556 -34.451036)
		(width 0.089408)
		(layer "In2.Cu")
		(net "BMC_M_WE_N")
	)
	(segment
		(start 433.945538 -34.16935)
		(end 433.717446 -34.397442)
		(width 0.089408)
		(layer "In2.Cu")
		(net "BMC_M_WE_N")
	)
	(segment
		(start 432.440334 -35.674554)
		(end 432.300888 -35.814)
		(width 0.089408)
		(layer "In2.Cu")
		(net "BMC_M_WE_N")
	)
	(segment
		(start 442.522356 -33.0327)
		(end 442.745114 -33.0327)
		(width 0.089408)
		(layer "In2.Cu")
		(net "BMC_M_WE_N")
	)
	(arc
		(start 432.440334 -35.395662)
		(mid 432.49802 -35.535108)
		(end 432.440334 -35.674554)
		(width 0.089408)
		(layer "In2.Cu")
		(net "BMC_M_WE_N")
	)
	(arc
		(start 440.877198 -33.204658)
		(mid 440.742934 -33.115009)
		(end 440.58459 -33.0835)
		(width 0.089408)
		(layer "In2.Cu")
		(net "BMC_M_WE_N")
	)
	(arc
		(start 442.745114 -33.0327)
		(mid 442.954201 -33.172407)
		(end 442.905134 -33.419034)
		(width 0.089408)
		(layer "In2.Cu")
		(net "BMC_M_WE_N")
	)
	(arc
		(start 433.10556 -34.729928)
		(mid 433.167498 -34.87901)
		(end 433.105814 -35.028124)
		(width 0.089408)
		(layer "In2.Cu")
		(net "BMC_M_WE_N")
	)
	(arc
		(start 430.558956 -36.448238)
		(mid 430.045498 -36.79132)
		(end 429.439832 -36.911788)
		(width 0.089408)
		(layer "In2.Cu")
		(net "BMC_M_WE_N")
	)
	(arc
		(start 432.44008 -35.116516)
		(mid 432.382394 -35.255962)
		(end 432.44008 -35.395408)
		(width 0.089408)
		(layer "In2.Cu")
		(net "BMC_M_WE_N")
	)
	(arc
		(start 430.966626 -36.279328)
		(mid 430.745978 -36.323218)
		(end 430.558956 -36.448238)
		(width 0.089408)
		(layer "In2.Cu")
		(net "BMC_M_WE_N")
	)
	(arc
		(start 422.652444 -36.128452)
		(mid 422.51157 -36.100466)
		(end 422.392094 -36.020756)
		(width 0.089408)
		(layer "In2.Cu")
		(net "BMC_M_WE_N")
	)
	(arc
		(start 433.07127 -35.062668)
		(mid 432.922188 -35.124606)
		(end 432.773074 -35.062922)
		(width 0.089408)
		(layer "In2.Cu")
		(net "BMC_M_WE_N")
	)
	(arc
		(start 432.77282 -35.062668)
		(mid 432.633374 -35.004982)
		(end 432.493928 -35.062668)
		(width 0.089408)
		(layer "In2.Cu")
		(net "BMC_M_WE_N")
	)
	(arc
		(start 432.300888 -35.814)
		(mid 431.785448 -36.158406)
		(end 431.177446 -36.279328)
		(width 0.089408)
		(layer "In2.Cu")
		(net "BMC_M_WE_N")
	)
	(arc
		(start 438.551066 -33.0835)
		(mid 438.318754 -33.12971)
		(end 438.121806 -33.2613)
		(width 0.089408)
		(layer "In2.Cu")
		(net "BMC_M_WE_N")
	)
	(arc
		(start 425.427648 -36.911788)
		(mid 425.083166 -36.843266)
		(end 424.791124 -36.648136)
		(width 0.089408)
		(layer "In2.Cu")
		(net "BMC_M_WE_N")
	)
	(arc
		(start 442.905134 -33.419034)
		(mid 442.794308 -33.493086)
		(end 442.66358 -33.51911)
		(width 0.089408)
		(layer "In2.Cu")
		(net "BMC_M_WE_N")
	)
	(arc
		(start 438.121806 -33.2613)
		(mid 437.949099 -33.376699)
		(end 437.745378 -33.417256)
		(width 0.089408)
		(layer "In2.Cu")
		(net "BMC_M_WE_N")
	)
	(arc
		(start 422.220644 -35.849052)
		(mid 422.068571 -35.753896)
		(end 421.89019 -35.734752)
		(width 0.089408)
		(layer "In2.Cu")
		(net "BMC_M_WE_N")
	)
	(arc
		(start 424.63593 -36.492942)
		(mid 424.232263 -36.223157)
		(end 423.756074 -36.128452)
		(width 0.089408)
		(layer "In2.Cu")
		(net "BMC_M_WE_N")
	)
	(arc
		(start 433.4383 -34.397188)
		(mid 433.298854 -34.339502)
		(end 433.159408 -34.397188)
		(width 0.089408)
		(layer "In2.Cu")
		(net "BMC_M_WE_N")
	)
	(arc
		(start 433.10556 -34.451036)
		(mid 433.047874 -34.590482)
		(end 433.10556 -34.729928)
		(width 0.089408)
		(layer "In2.Cu")
		(net "BMC_M_WE_N")
	)
	(arc
		(start 433.717446 -34.397442)
		(mid 433.578 -34.455128)
		(end 433.438554 -34.397442)
		(width 0.089408)
		(layer "In2.Cu")
		(net "BMC_M_WE_N")
	)
	(arc
		(start 441.54471 -33.51911)
		(mid 441.218516 -33.454208)
		(end 440.941968 -33.269428)
		(width 0.089408)
		(layer "In2.Cu")
		(net "BMC_M_WE_N")
	)
	(arc
		(start 435.761892 -33.417256)
		(mid 434.778922 -33.612669)
		(end 433.945538 -34.16935)
		(width 0.089408)
		(layer "In2.Cu")
		(net "BMC_M_WE_N")
	)
	(segment
		(start 419.090094 -32.934656)
		(end 419.490144 -32.534606)
		(width 0.254)
		(layer "F.Cu")
		(net "BMC_M_VREFCA")
	)
	(segment
		(start 442.921898 -34.232596)
		(end 443.531244 -34.232596)
		(width 0.3048)
		(layer "F.Cu")
		(net "BMC_M_VREFCA")
	)
	(segment
		(start 443.531244 -34.232596)
		(end 443.532006 -34.233358)
		(width 0.3048)
		(layer "F.Cu")
		(net "BMC_M_VREFCA")
	)
	(via
		(at 443.532006 -34.233358)
		(size 0.4572)
		(drill 0.2032)
		(layers "F.Cu" "B.Cu")
		(net "BMC_M_VREFCA")
	)
	(via
		(at 447.0908 -27.6606)
		(size 0.6604)
		(drill 0.3302)
		(layers "F.Cu" "B.Cu")
		(net "BMC_M_VREFCA")
	)
	(via
		(at 444.09995 -30.27426)
		(size 0.508)
		(drill 0.254)
		(layers "F.Cu" "B.Cu")
		(net "BMC_M_VREFCA")
	)
	(via
		(at 419.490144 -32.534606)
		(size 0.4572)
		(drill 0.2032)
		(layers "F.Cu" "B.Cu")
		(net "BMC_M_VREFCA")
	)
	(segment
		(start 447.30289 -27.87269)
		(end 447.0908 -27.6606)
		(width 0.381)
		(layer "B.Cu")
		(net "BMC_M_VREFCA")
	)
	(segment
		(start 444.91275 -29.6164)
		(end 445.72555 -29.6164)
		(width 0.381)
		(layer "B.Cu")
		(net "BMC_M_VREFCA")
	)
	(segment
		(start 446.53835 -29.6164)
		(end 447.30289 -29.6164)
		(width 0.381)
		(layer "B.Cu")
		(net "BMC_M_VREFCA")
	)
	(segment
		(start 444.09995 -29.6164)
		(end 444.91275 -29.6164)
		(width 0.381)
		(layer "B.Cu")
		(net "BMC_M_VREFCA")
	)
	(segment
		(start 419.51275 -32.512)
		(end 419.490144 -32.534606)
		(width 0.508)
		(layer "B.Cu")
		(net "BMC_M_VREFCA")
	)
	(segment
		(start 445.72555 -29.6164)
		(end 446.53835 -29.6164)
		(width 0.381)
		(layer "B.Cu")
		(net "BMC_M_VREFCA")
	)
	(segment
		(start 444.09995 -30.27426)
		(end 444.09995 -29.6164)
		(width 0.381)
		(layer "B.Cu")
		(net "BMC_M_VREFCA")
	)
	(segment
		(start 447.30289 -29.6164)
		(end 447.30289 -28.8036)
		(width 0.381)
		(layer "B.Cu")
		(net "BMC_M_VREFCA")
	)
	(segment
		(start 447.30289 -28.8036)
		(end 447.30289 -27.87269)
		(width 0.381)
		(layer "B.Cu")
		(net "BMC_M_VREFCA")
	)
	(segment
		(start 420.116 -32.512)
		(end 419.51275 -32.512)
		(width 0.508)
		(layer "B.Cu")
		(net "BMC_M_VREFCA")
	)
	(segment
		(start 427.72457 -42.56405)
		(end 426.5295 -41.369234)
		(width 0.10795)
		(layer "F.Cu")
		(net "BMC_M_RST_N")
	)
	(segment
		(start 443.760606 -36.09086)
		(end 443.502288 -35.832542)
		(width 0.10795)
		(layer "F.Cu")
		(net "BMC_M_RST_N")
	)
	(segment
		(start 444.268606 -37.1221)
		(end 444.167006 -37.2237)
		(width 0.10795)
		(layer "F.Cu")
		(net "BMC_M_RST_N")
	)
	(segment
		(start 424.405044 -39.334694)
		(end 423.890186 -39.334694)
		(width 0.10795)
		(layer "F.Cu")
		(net "BMC_M_RST_N")
	)
	(segment
		(start 452.166228 -36.629848)
		(end 452.554848 -36.629848)
		(width 0.10795)
		(layer "F.Cu")
		(net "BMC_M_RST_N")
	)
	(segment
		(start 452.554848 -36.629848)
		(end 453.009 -37.084)
		(width 0.10795)
		(layer "F.Cu")
		(net "BMC_M_RST_N")
	)
	(segment
		(start 442.921898 -35.833558)
		(end 442.921898 -35.832542)
		(width 0.10795)
		(layer "F.Cu")
		(net "BMC_M_RST_N")
	)
	(segment
		(start 453.009 -39.497)
		(end 453.644 -40.132)
		(width 0.10795)
		(layer "F.Cu")
		(net "BMC_M_RST_N")
	)
	(segment
		(start 451.41388 -35.8775)
		(end 452.166228 -36.629848)
		(width 0.10795)
		(layer "F.Cu")
		(net "BMC_M_RST_N")
	)
	(segment
		(start 447.369692 -36.5379)
		(end 444.370206 -36.5379)
		(width 0.10795)
		(layer "F.Cu")
		(net "BMC_M_RST_N")
	)
	(segment
		(start 444.370206 -36.5379)
		(end 444.268606 -36.6395)
		(width 0.10795)
		(layer "F.Cu")
		(net "BMC_M_RST_N")
	)
	(segment
		(start 428.804578 -42.918888)
		(end 428.581566 -42.918888)
		(width 0.10795)
		(layer "F.Cu")
		(net "BMC_M_RST_N")
	)
	(segment
		(start 444.268606 -36.6395)
		(end 444.268606 -37.1221)
		(width 0.10795)
		(layer "F.Cu")
		(net "BMC_M_RST_N")
	)
	(segment
		(start 449.882006 -36.5379)
		(end 447.369692 -36.5379)
		(width 0.10795)
		(layer "F.Cu")
		(net "BMC_M_RST_N")
	)
	(segment
		(start 442.522356 -36.2331)
		(end 442.921898 -35.833558)
		(width 0.10795)
		(layer "F.Cu")
		(net "BMC_M_RST_N")
	)
	(segment
		(start 444.167006 -37.2237)
		(end 443.836806 -37.2237)
		(width 0.10795)
		(layer "F.Cu")
		(net "BMC_M_RST_N")
	)
	(segment
		(start 450.14388 -35.8775)
		(end 451.41388 -35.8775)
		(width 0.10795)
		(layer "F.Cu")
		(net "BMC_M_RST_N")
	)
	(segment
		(start 450.14388 -35.8775)
		(end 450.14388 -36.276026)
		(width 0.10795)
		(layer "F.Cu")
		(net "BMC_M_RST_N")
	)
	(segment
		(start 443.836806 -37.2237)
		(end 443.760606 -37.1475)
		(width 0.10795)
		(layer "F.Cu")
		(net "BMC_M_RST_N")
	)
	(segment
		(start 450.14388 -36.276026)
		(end 449.882006 -36.5379)
		(width 0.10795)
		(layer "F.Cu")
		(net "BMC_M_RST_N")
	)
	(segment
		(start 443.760606 -37.1475)
		(end 443.760606 -36.09086)
		(width 0.10795)
		(layer "F.Cu")
		(net "BMC_M_RST_N")
	)
	(segment
		(start 443.502288 -35.832542)
		(end 442.921898 -35.832542)
		(width 0.10795)
		(layer "F.Cu")
		(net "BMC_M_RST_N")
	)
	(segment
		(start 426.5295 -41.369234)
		(end 424.557952 -39.398194)
		(width 0.10795)
		(layer "F.Cu")
		(net "BMC_M_RST_N")
	)
	(segment
		(start 453.009 -37.084)
		(end 453.009 -39.497)
		(width 0.10795)
		(layer "F.Cu")
		(net "BMC_M_RST_N")
	)
	(via
		(at 447.369692 -36.5379)
		(size 0.508)
		(drill 0.254)
		(layers "F.Cu" "B.Cu")
		(net "BMC_M_RST_N")
	)
	(via
		(at 428.804578 -42.918888)
		(size 0.4572)
		(drill 0.2032)
		(layers "F.Cu" "B.Cu")
		(net "BMC_M_RST_N")
	)
	(via
		(at 442.522356 -36.2331)
		(size 0.4572)
		(drill 0.2032)
		(layers "F.Cu" "B.Cu")
		(net "BMC_M_RST_N")
	)
	(arc
		(start 428.581566 -42.918888)
		(mid 428.117778 -42.826711)
		(end 427.72457 -42.56405)
		(width 0.10795)
		(layer "F.Cu")
		(net "BMC_M_RST_N")
	)
	(arc
		(start 424.557952 -39.398194)
		(mid 424.487812 -39.351235)
		(end 424.405044 -39.334694)
		(width 0.10795)
		(layer "F.Cu")
		(net "BMC_M_RST_N")
	)
	(segment
		(start 442.942218 -37.214556)
		(end 442.942218 -36.78428)
		(width 0.089408)
		(layer "In2.Cu")
		(net "BMC_M_RST_N")
	)
	(segment
		(start 440.277504 -39.61511)
		(end 440.56808 -39.61511)
		(width 0.089408)
		(layer "In2.Cu")
		(net "BMC_M_RST_N")
	)
	(segment
		(start 442.849254 -36.559998)
		(end 442.522356 -36.2331)
		(width 0.089408)
		(layer "In2.Cu")
		(net "BMC_M_RST_N")
	)
	(segment
		(start 437.258206 -42.639996)
		(end 437.493918 -42.639996)
		(width 0.089408)
		(layer "In2.Cu")
		(net "BMC_M_RST_N")
	)
	(segment
		(start 439.612278 -40.117522)
		(end 440.001152 -39.728648)
		(width 0.089408)
		(layer "In2.Cu")
		(net "BMC_M_RST_N")
	)
	(segment
		(start 435.911244 -43.558714)
		(end 436.527448 -42.94251)
		(width 0.089408)
		(layer "In2.Cu")
		(net "BMC_M_RST_N")
	)
	(segment
		(start 440.001152 -39.728648)
		(end 440.001406 -39.728648)
		(width 0.089408)
		(layer "In2.Cu")
		(net "BMC_M_RST_N")
	)
	(segment
		(start 428.804578 -42.918888)
		(end 429.510698 -43.625008)
		(width 0.089408)
		(layer "In2.Cu")
		(net "BMC_M_RST_N")
	)
	(segment
		(start 441.01385 -39.430452)
		(end 442.738764 -37.705538)
		(width 0.089408)
		(layer "In2.Cu")
		(net "BMC_M_RST_N")
	)
	(segment
		(start 439.4327 -40.774874)
		(end 439.4327 -40.5511)
		(width 0.089408)
		(layer "In2.Cu")
		(net "BMC_M_RST_N")
	)
	(segment
		(start 430.02327 -43.837352)
		(end 435.238652 -43.837352)
		(width 0.089408)
		(layer "In2.Cu")
		(net "BMC_M_RST_N")
	)
	(segment
		(start 437.956452 -42.44848)
		(end 439.293 -41.111932)
		(width 0.089408)
		(layer "In2.Cu")
		(net "BMC_M_RST_N")
	)
	(arc
		(start 439.4327 -40.5511)
		(mid 439.479374 -40.316455)
		(end 439.612278 -40.117522)
		(width 0.089408)
		(layer "In2.Cu")
		(net "BMC_M_RST_N")
	)
	(arc
		(start 437.493918 -42.639996)
		(mid 437.744226 -42.590224)
		(end 437.956452 -42.44848)
		(width 0.089408)
		(layer "In2.Cu")
		(net "BMC_M_RST_N")
	)
	(arc
		(start 435.238652 -43.837352)
		(mid 435.602658 -43.764929)
		(end 435.911244 -43.558714)
		(width 0.089408)
		(layer "In2.Cu")
		(net "BMC_M_RST_N")
	)
	(arc
		(start 439.293 -41.111932)
		(mid 439.396359 -40.957289)
		(end 439.4327 -40.774874)
		(width 0.089408)
		(layer "In2.Cu")
		(net "BMC_M_RST_N")
	)
	(arc
		(start 429.510698 -43.625008)
		(mid 429.745868 -43.782144)
		(end 430.02327 -43.837352)
		(width 0.089408)
		(layer "In2.Cu")
		(net "BMC_M_RST_N")
	)
	(arc
		(start 442.738764 -37.705538)
		(mid 442.889335 -37.480288)
		(end 442.942218 -37.214556)
		(width 0.089408)
		(layer "In2.Cu")
		(net "BMC_M_RST_N")
	)
	(arc
		(start 436.527448 -42.94251)
		(mid 436.862738 -42.71857)
		(end 437.258206 -42.639996)
		(width 0.089408)
		(layer "In2.Cu")
		(net "BMC_M_RST_N")
	)
	(arc
		(start 440.001406 -39.728648)
		(mid 440.128249 -39.644617)
		(end 440.277504 -39.61511)
		(width 0.089408)
		(layer "In2.Cu")
		(net "BMC_M_RST_N")
	)
	(arc
		(start 440.56808 -39.61511)
		(mid 440.809334 -39.567122)
		(end 441.01385 -39.430452)
		(width 0.089408)
		(layer "In2.Cu")
		(net "BMC_M_RST_N")
	)
	(arc
		(start 442.942218 -36.78428)
		(mid 442.918054 -36.662889)
		(end 442.849254 -36.559998)
		(width 0.089408)
		(layer "In2.Cu")
		(net "BMC_M_RST_N")
	)
	(segment
		(start 437.32196 -33.433004)
		(end 437.721756 -33.8328)
		(width 0.10795)
		(layer "F.Cu")
		(net "BMC_M_RAS_N")
	)
	(segment
		(start 421.49014 -35.334702)
		(end 421.49014 -35.334956)
		(width 0.089408)
		(layer "F.Cu")
		(net "BMC_M_RAS_N")
	)
	(segment
		(start 437.32196 -33.432496)
		(end 437.32196 -33.433004)
		(width 0.10795)
		(layer "F.Cu")
		(net "BMC_M_RAS_N")
	)
	(segment
		(start 421.49014 -35.334956)
		(end 421.090344 -35.734752)
		(width 0.089408)
		(layer "F.Cu")
		(net "BMC_M_RAS_N")
	)
	(via
		(at 430.007776 -36.668202)
		(size 0.508)
		(drill 0.254)
		(layers "F.Cu" "B.Cu")
		(net "BMC_M_RAS_N")
	)
	(via
		(at 437.721756 -33.8328)
		(size 0.4572)
		(drill 0.2032)
		(layers "F.Cu" "B.Cu")
		(net "BMC_M_RAS_N")
	)
	(via
		(at 421.090344 -35.734752)
		(size 0.4572)
		(drill 0.2032)
		(layers "F.Cu" "B.Cu")
		(net "BMC_M_RAS_N")
	)
	(segment
		(start 423.667428 -36.9824)
		(end 425.49064 -36.9824)
		(width 0.10795)
		(layer "B.Cu")
		(net "BMC_M_RAS_N")
	)
	(segment
		(start 423.278808 -36.3347)
		(end 423.278808 -36.59378)
		(width 0.10795)
		(layer "B.Cu")
		(net "BMC_M_RAS_N")
	)
	(segment
		(start 440.153806 -35.0393)
		(end 439.290206 -34.1757)
		(width 0.10795)
		(layer "B.Cu")
		(net "BMC_M_RAS_N")
	)
	(segment
		(start 448.11188 -35.8775)
		(end 446.826132 -35.8775)
		(width 0.10795)
		(layer "B.Cu")
		(net "BMC_M_RAS_N")
	)
	(segment
		(start 446.826132 -35.8775)
		(end 446.241932 -35.2933)
		(width 0.10795)
		(layer "B.Cu")
		(net "BMC_M_RAS_N")
	)
	(segment
		(start 423.932858 -36.004246)
		(end 425.800012 -36.004246)
		(width 0.10795)
		(layer "B.Cu")
		(net "BMC_M_RAS_N")
	)
	(segment
		(start 426.813726 -36.481766)
		(end 427.70933 -36.481766)
		(width 0.10795)
		(layer "B.Cu")
		(net "BMC_M_RAS_N")
	)
	(segment
		(start 426.5295 -36.360862)
		(end 426.534834 -36.366196)
		(width 0.10795)
		(layer "B.Cu")
		(net "BMC_M_RAS_N")
	)
	(segment
		(start 438.104534 -34.215578)
		(end 437.721756 -33.8328)
		(width 0.10795)
		(layer "B.Cu")
		(net "BMC_M_RAS_N")
	)
	(segment
		(start 421.090344 -35.734752)
		(end 421.090344 -36.006786)
		(width 0.10795)
		(layer "B.Cu")
		(net "BMC_M_RAS_N")
	)
	(segment
		(start 433.762404 -34.784792)
		(end 432.050952 -36.496244)
		(width 0.10795)
		(layer "B.Cu")
		(net "BMC_M_RAS_N")
	)
	(segment
		(start 431.635916 -36.668202)
		(end 430.007776 -36.668202)
		(width 0.10795)
		(layer "B.Cu")
		(net "BMC_M_RAS_N")
	)
	(segment
		(start 435.751478 -34.207704)
		(end 435.155594 -34.207704)
		(width 0.10795)
		(layer "B.Cu")
		(net "BMC_M_RAS_N")
	)
	(segment
		(start 428.784004 -36.668202)
		(end 430.007776 -36.668202)
		(width 0.10795)
		(layer "B.Cu")
		(net "BMC_M_RAS_N")
	)
	(segment
		(start 439.290206 -34.1757)
		(end 438.72023 -34.1757)
		(width 0.10795)
		(layer "B.Cu")
		(net "BMC_M_RAS_N")
	)
	(segment
		(start 446.241932 -35.2933)
		(end 442.135006 -35.2933)
		(width 0.10795)
		(layer "B.Cu")
		(net "BMC_M_RAS_N")
	)
	(segment
		(start 437.721756 -33.8328)
		(end 437.424068 -34.130742)
		(width 0.10795)
		(layer "B.Cu")
		(net "BMC_M_RAS_N")
	)
	(segment
		(start 426.415962 -36.259516)
		(end 426.41647 -36.260024)
		(width 0.10795)
		(layer "B.Cu")
		(net "BMC_M_RAS_N")
	)
	(segment
		(start 442.135006 -35.2933)
		(end 441.881006 -35.0393)
		(width 0.10795)
		(layer "B.Cu")
		(net "BMC_M_RAS_N")
	)
	(segment
		(start 428.031656 -36.15944)
		(end 428.031656 -35.855402)
		(width 0.10795)
		(layer "B.Cu")
		(net "BMC_M_RAS_N")
	)
	(segment
		(start 438.680352 -34.215578)
		(end 438.104534 -34.215578)
		(width 0.10795)
		(layer "B.Cu")
		(net "BMC_M_RAS_N")
	)
	(segment
		(start 437.131206 -34.2519)
		(end 435.954424 -34.2519)
		(width 0.10795)
		(layer "B.Cu")
		(net "BMC_M_RAS_N")
	)
	(segment
		(start 441.881006 -35.0393)
		(end 440.153806 -35.0393)
		(width 0.10795)
		(layer "B.Cu")
		(net "BMC_M_RAS_N")
	)
	(segment
		(start 421.202358 -36.1188)
		(end 423.062908 -36.1188)
		(width 0.10795)
		(layer "B.Cu")
		(net "BMC_M_RAS_N")
	)
	(segment
		(start 425.49064 -36.493196)
		(end 423.932858 -36.493196)
		(width 0.10795)
		(layer "B.Cu")
		(net "BMC_M_RAS_N")
	)
	(segment
		(start 428.520606 -35.855402)
		(end 428.520606 -36.404804)
		(width 0.10795)
		(layer "B.Cu")
		(net "BMC_M_RAS_N")
	)
	(segment
		(start 438.72023 -34.1757)
		(end 438.680352 -34.215578)
		(width 0.10795)
		(layer "B.Cu")
		(net "BMC_M_RAS_N")
	)
	(arc
		(start 435.155594 -34.207704)
		(mid 434.401601 -34.357682)
		(end 433.762404 -34.784792)
		(width 0.10795)
		(layer "B.Cu")
		(net "BMC_M_RAS_N")
	)
	(arc
		(start 425.49064 -36.9824)
		(mid 425.735242 -36.737798)
		(end 425.49064 -36.493196)
		(width 0.10795)
		(layer "B.Cu")
		(net "BMC_M_RAS_N")
	)
	(arc
		(start 426.41647 -36.260024)
		(mid 426.471544 -36.312058)
		(end 426.5295 -36.360862)
		(width 0.10795)
		(layer "B.Cu")
		(net "BMC_M_RAS_N")
	)
	(arc
		(start 428.031656 -35.855402)
		(mid 428.276258 -35.6108)
		(end 428.520606 -35.855402)
		(width 0.10795)
		(layer "B.Cu")
		(net "BMC_M_RAS_N")
	)
	(arc
		(start 427.70933 -36.481766)
		(mid 427.937249 -36.387359)
		(end 428.031656 -36.15944)
		(width 0.10795)
		(layer "B.Cu")
		(net "BMC_M_RAS_N")
	)
	(arc
		(start 437.424068 -34.130742)
		(mid 437.289673 -34.220415)
		(end 437.131206 -34.2519)
		(width 0.10795)
		(layer "B.Cu")
		(net "BMC_M_RAS_N")
	)
	(arc
		(start 423.278808 -36.59378)
		(mid 423.392632 -36.868576)
		(end 423.667428 -36.9824)
		(width 0.10795)
		(layer "B.Cu")
		(net "BMC_M_RAS_N")
	)
	(arc
		(start 421.090344 -36.006786)
		(mid 421.123152 -36.085992)
		(end 421.202358 -36.1188)
		(width 0.10795)
		(layer "B.Cu")
		(net "BMC_M_RAS_N")
	)
	(arc
		(start 423.932858 -36.493196)
		(mid 423.68851 -36.248848)
		(end 423.932858 -36.004246)
		(width 0.10795)
		(layer "B.Cu")
		(net "BMC_M_RAS_N")
	)
	(arc
		(start 426.534834 -36.366196)
		(mid 426.662791 -36.451694)
		(end 426.813726 -36.481766)
		(width 0.10795)
		(layer "B.Cu")
		(net "BMC_M_RAS_N")
	)
	(arc
		(start 428.520606 -36.404804)
		(mid 428.597753 -36.591055)
		(end 428.784004 -36.668202)
		(width 0.10795)
		(layer "B.Cu")
		(net "BMC_M_RAS_N")
	)
	(arc
		(start 425.800012 -36.004246)
		(mid 426.133399 -36.070579)
		(end 426.415962 -36.259516)
		(width 0.10795)
		(layer "B.Cu")
		(net "BMC_M_RAS_N")
	)
	(arc
		(start 423.062908 -36.1188)
		(mid 423.215572 -36.182036)
		(end 423.278808 -36.3347)
		(width 0.10795)
		(layer "B.Cu")
		(net "BMC_M_RAS_N")
	)
	(arc
		(start 432.050952 -36.496244)
		(mid 431.860546 -36.623532)
		(end 431.635916 -36.668202)
		(width 0.10795)
		(layer "B.Cu")
		(net "BMC_M_RAS_N")
	)
	(arc
		(start 435.954424 -34.2519)
		(mid 435.850562 -34.240761)
		(end 435.751478 -34.207704)
		(width 0.10795)
		(layer "B.Cu")
		(net "BMC_M_RAS_N")
	)
	(segment
		(start 442.814964 -38.9255)
		(end 441.321952 -37.432488)
		(width 0.10795)
		(layer "F.Cu")
		(net "BMC_M_PAR")
	)
	(segment
		(start 443.532006 -38.9255)
		(end 442.814964 -38.9255)
		(width 0.10795)
		(layer "F.Cu")
		(net "BMC_M_PAR")
	)
	(via
		(at 443.532006 -38.9255)
		(size 0.4572)
		(drill 0.2032)
		(layers "F.Cu" "B.Cu")
		(net "BMC_M_PAR")
	)
	(via
		(at 443.1284 -38.3286)
		(size 0.6604)
		(drill 0.3302)
		(layers "F.Cu" "B.Cu")
		(net "BMC_M_PAR")
	)
	(segment
		(start 443.1284 -38.3286)
		(end 443.1284 -37.7698)
		(width 0.10795)
		(layer "B.Cu")
		(net "BMC_M_PAR")
	)
	(segment
		(start 444.062866 -38.81755)
		(end 443.954916 -38.9255)
		(width 0.10795)
		(layer "B.Cu")
		(net "BMC_M_PAR")
	)
	(segment
		(start 444.062866 -38.39591)
		(end 444.062866 -38.81755)
		(width 0.10795)
		(layer "B.Cu")
		(net "BMC_M_PAR")
	)
	(segment
		(start 444.1317 -37.627052)
		(end 444.1317 -37.98951)
		(width 0.10795)
		(layer "B.Cu")
		(net "BMC_M_PAR")
	)
	(segment
		(start 444.062866 -38.058344)
		(end 444.062866 -38.39591)
		(width 0.10795)
		(layer "B.Cu")
		(net "BMC_M_PAR")
	)
	(segment
		(start 444.1317 -37.98951)
		(end 444.062866 -38.058344)
		(width 0.10795)
		(layer "B.Cu")
		(net "BMC_M_PAR")
	)
	(segment
		(start 443.271148 -37.627052)
		(end 444.1317 -37.627052)
		(width 0.10795)
		(layer "B.Cu")
		(net "BMC_M_PAR")
	)
	(segment
		(start 443.1284 -37.7698)
		(end 443.271148 -37.627052)
		(width 0.10795)
		(layer "B.Cu")
		(net "BMC_M_PAR")
	)
	(segment
		(start 443.954916 -38.9255)
		(end 443.532006 -38.9255)
		(width 0.10795)
		(layer "B.Cu")
		(net "BMC_M_PAR")
	)
	(segment
		(start 441.321952 -32.632396)
		(end 441.722256 -33.0327)
		(width 0.10795)
		(layer "F.Cu")
		(net "BMC_M_ODT")
	)
	(segment
		(start 420.690294 -34.534602)
		(end 421.090344 -34.934652)
		(width 0.089408)
		(layer "F.Cu")
		(net "BMC_M_ODT")
	)
	(segment
		(start 420.69004 -34.534602)
		(end 420.690294 -34.534602)
		(width 0.089408)
		(layer "F.Cu")
		(net "BMC_M_ODT")
	)
	(via
		(at 421.090344 -34.934652)
		(size 0.4572)
		(drill 0.2032)
		(layers "F.Cu" "B.Cu")
		(net "BMC_M_ODT")
	)
	(via
		(at 441.722256 -33.0327)
		(size 0.4572)
		(drill 0.2032)
		(layers "F.Cu" "B.Cu")
		(net "BMC_M_ODT")
	)
	(via
		(at 442.157866 -33.7947)
		(size 0.508)
		(drill 0.254)
		(layers "F.Cu" "B.Cu")
		(net "BMC_M_ODT")
	)
	(segment
		(start 442.922406 -33.7947)
		(end 442.157866 -33.7947)
		(width 0.10795)
		(layer "B.Cu")
		(net "BMC_M_ODT")
	)
	(segment
		(start 448.11188 -33.5915)
		(end 446.826132 -33.5915)
		(width 0.10795)
		(layer "B.Cu")
		(net "BMC_M_ODT")
	)
	(segment
		(start 441.576206 -33.7947)
		(end 441.436506 -33.655)
		(width 0.10795)
		(layer "B.Cu")
		(net "BMC_M_ODT")
	)
	(segment
		(start 444.421006 -33.9471)
		(end 444.167006 -33.9471)
		(width 0.10795)
		(layer "B.Cu")
		(net "BMC_M_ODT")
	)
	(segment
		(start 444.167006 -33.9471)
		(end 444.014606 -33.7947)
		(width 0.10795)
		(layer "B.Cu")
		(net "BMC_M_ODT")
	)
	(segment
		(start 446.826132 -33.5915)
		(end 446.826132 -33.151826)
		(width 0.10795)
		(layer "B.Cu")
		(net "BMC_M_ODT")
	)
	(segment
		(start 442.998606 -32.8295)
		(end 442.998606 -33.7185)
		(width 0.10795)
		(layer "B.Cu")
		(net "BMC_M_ODT")
	)
	(segment
		(start 444.014606 -32.8549)
		(end 443.836806 -32.6771)
		(width 0.10795)
		(layer "B.Cu")
		(net "BMC_M_ODT")
	)
	(segment
		(start 443.151006 -32.6771)
		(end 442.998606 -32.8295)
		(width 0.10795)
		(layer "B.Cu")
		(net "BMC_M_ODT")
	)
	(segment
		(start 444.573406 -33.1851)
		(end 444.573406 -33.7947)
		(width 0.10795)
		(layer "B.Cu")
		(net "BMC_M_ODT")
	)
	(segment
		(start 443.836806 -32.6771)
		(end 443.151006 -32.6771)
		(width 0.10795)
		(layer "B.Cu")
		(net "BMC_M_ODT")
	)
	(segment
		(start 446.707006 -33.0327)
		(end 444.725806 -33.0327)
		(width 0.10795)
		(layer "B.Cu")
		(net "BMC_M_ODT")
	)
	(segment
		(start 442.998606 -33.7185)
		(end 442.922406 -33.7947)
		(width 0.10795)
		(layer "B.Cu")
		(net "BMC_M_ODT")
	)
	(segment
		(start 446.826132 -33.151826)
		(end 446.707006 -33.0327)
		(width 0.10795)
		(layer "B.Cu")
		(net "BMC_M_ODT")
	)
	(segment
		(start 442.157866 -33.7947)
		(end 441.576206 -33.7947)
		(width 0.10795)
		(layer "B.Cu")
		(net "BMC_M_ODT")
	)
	(segment
		(start 444.573406 -33.7947)
		(end 444.421006 -33.9471)
		(width 0.10795)
		(layer "B.Cu")
		(net "BMC_M_ODT")
	)
	(segment
		(start 441.436506 -33.655)
		(end 441.436506 -33.31845)
		(width 0.10795)
		(layer "B.Cu")
		(net "BMC_M_ODT")
	)
	(segment
		(start 444.014606 -33.7947)
		(end 444.014606 -32.8549)
		(width 0.10795)
		(layer "B.Cu")
		(net "BMC_M_ODT")
	)
	(segment
		(start 444.725806 -33.0327)
		(end 444.573406 -33.1851)
		(width 0.10795)
		(layer "B.Cu")
		(net "BMC_M_ODT")
	)
	(segment
		(start 441.436506 -33.31845)
		(end 441.722256 -33.0327)
		(width 0.10795)
		(layer "B.Cu")
		(net "BMC_M_ODT")
	)
	(segment
		(start 423.53992 -35.341052)
		(end 421.863774 -35.341052)
		(width 0.089408)
		(layer "In2.Cu")
		(net "BMC_M_ODT")
	)
	(segment
		(start 424.903646 -36.16579)
		(end 424.459908 -35.722052)
		(width 0.089408)
		(layer "In2.Cu")
		(net "BMC_M_ODT")
	)
	(segment
		(start 430.679098 -35.7378)
		(end 430.148746 -35.7378)
		(width 0.089408)
		(layer "In2.Cu")
		(net "BMC_M_ODT")
	)
	(segment
		(start 431.640996 -35.200082)
		(end 431.403506 -35.437572)
		(width 0.089408)
		(layer "In2.Cu")
		(net "BMC_M_ODT")
	)
	(segment
		(start 433.772056 -33.069276)
		(end 433.621434 -33.219644)
		(width 0.089408)
		(layer "In2.Cu")
		(net "BMC_M_ODT")
	)
	(segment
		(start 421.649144 -35.252152)
		(end 421.502332 -35.10534)
		(width 0.089408)
		(layer "In2.Cu")
		(net "BMC_M_ODT")
	)
	(segment
		(start 432.265328 -34.16046)
		(end 432.30673 -34.201862)
		(width 0.089408)
		(layer "In2.Cu")
		(net "BMC_M_ODT")
	)
	(segment
		(start 429.868076 -35.854132)
		(end 429.824896 -35.897312)
		(width 0.089408)
		(layer "In2.Cu")
		(net "BMC_M_ODT")
	)
	(segment
		(start 440.976258 -32.643826)
		(end 434.799232 -32.643826)
		(width 0.089408)
		(layer "In2.Cu")
		(net "BMC_M_ODT")
	)
	(segment
		(start 431.579782 -34.805874)
		(end 431.64125 -34.867342)
		(width 0.089408)
		(layer "In2.Cu")
		(net "BMC_M_ODT")
	)
	(segment
		(start 432.639216 -33.868868)
		(end 432.598068 -33.82772)
		(width 0.089408)
		(layer "In2.Cu")
		(net "BMC_M_ODT")
	)
	(segment
		(start 441.722256 -33.0327)
		(end 441.585858 -32.896302)
		(width 0.089408)
		(layer "In2.Cu")
		(net "BMC_M_ODT")
	)
	(segment
		(start 428.646336 -36.3855)
		(end 425.433998 -36.3855)
		(width 0.089408)
		(layer "In2.Cu")
		(net "BMC_M_ODT")
	)
	(segment
		(start 433.320698 -33.21939)
		(end 433.26558 -33.164272)
		(width 0.089408)
		(layer "In2.Cu")
		(net "BMC_M_ODT")
	)
	(segment
		(start 432.93284 -33.497012)
		(end 432.97221 -33.536382)
		(width 0.089408)
		(layer "In2.Cu")
		(net "BMC_M_ODT")
	)
	(segment
		(start 431.973736 -34.534348)
		(end 431.912522 -34.473134)
		(width 0.089408)
		(layer "In2.Cu")
		(net "BMC_M_ODT")
	)
	(arc
		(start 432.598068 -33.82772)
		(mid 432.265328 -33.82772)
		(end 432.265328 -34.16046)
		(width 0.089408)
		(layer "In2.Cu")
		(net "BMC_M_ODT")
	)
	(arc
		(start 432.97221 -33.536382)
		(mid 432.972083 -33.869249)
		(end 432.639216 -33.868868)
		(width 0.089408)
		(layer "In2.Cu")
		(net "BMC_M_ODT")
	)
	(arc
		(start 441.585858 -32.896302)
		(mid 441.306185 -32.709368)
		(end 440.976258 -32.643826)
		(width 0.089408)
		(layer "In2.Cu")
		(net "BMC_M_ODT")
	)
	(arc
		(start 424.459908 -35.722052)
		(mid 424.0378 -35.440071)
		(end 423.53992 -35.341052)
		(width 0.089408)
		(layer "In2.Cu")
		(net "BMC_M_ODT")
	)
	(arc
		(start 425.433998 -36.3855)
		(mid 425.146962 -36.328405)
		(end 424.903646 -36.16579)
		(width 0.089408)
		(layer "In2.Cu")
		(net "BMC_M_ODT")
	)
	(arc
		(start 431.912522 -34.473134)
		(mid 431.579782 -34.473134)
		(end 431.579782 -34.805874)
		(width 0.089408)
		(layer "In2.Cu")
		(net "BMC_M_ODT")
	)
	(arc
		(start 433.621434 -33.219644)
		(mid 433.470976 -33.281928)
		(end 433.320698 -33.21939)
		(width 0.089408)
		(layer "In2.Cu")
		(net "BMC_M_ODT")
	)
	(arc
		(start 429.824896 -35.897312)
		(mid 429.284168 -36.258615)
		(end 428.646336 -36.3855)
		(width 0.089408)
		(layer "In2.Cu")
		(net "BMC_M_ODT")
	)
	(arc
		(start 433.26558 -33.164272)
		(mid 432.93284 -33.164272)
		(end 432.93284 -33.497012)
		(width 0.089408)
		(layer "In2.Cu")
		(net "BMC_M_ODT")
	)
	(arc
		(start 431.403506 -35.437572)
		(mid 431.071146 -35.659707)
		(end 430.679098 -35.7378)
		(width 0.089408)
		(layer "In2.Cu")
		(net "BMC_M_ODT")
	)
	(arc
		(start 431.64125 -34.867342)
		(mid 431.710163 -35.033802)
		(end 431.640996 -35.200082)
		(width 0.089408)
		(layer "In2.Cu")
		(net "BMC_M_ODT")
	)
	(arc
		(start 421.863774 -35.341052)
		(mid 421.747618 -35.317947)
		(end 421.649144 -35.252152)
		(width 0.089408)
		(layer "In2.Cu")
		(net "BMC_M_ODT")
	)
	(arc
		(start 434.799232 -32.643826)
		(mid 434.243336 -32.754401)
		(end 433.772056 -33.069276)
		(width 0.089408)
		(layer "In2.Cu")
		(net "BMC_M_ODT")
	)
	(arc
		(start 432.30673 -34.201862)
		(mid 432.306603 -34.534729)
		(end 431.973736 -34.534348)
		(width 0.089408)
		(layer "In2.Cu")
		(net "BMC_M_ODT")
	)
	(arc
		(start 421.502332 -35.10534)
		(mid 421.31331 -34.97904)
		(end 421.090344 -34.934652)
		(width 0.089408)
		(layer "In2.Cu")
		(net "BMC_M_ODT")
	)
	(arc
		(start 430.148746 -35.7378)
		(mid 429.996834 -35.768035)
		(end 429.868076 -35.854132)
		(width 0.089408)
		(layer "In2.Cu")
		(net "BMC_M_ODT")
	)
	(segment
		(start 435.404006 -42.108374)
		(end 434.800756 -41.505124)
		(width 0.10795)
		(layer "F.Cu")
		(net "BMC_M_MALERT_N")
	)
	(segment
		(start 434.3654 -37.989256)
		(end 436.121556 -36.2331)
		(width 0.10795)
		(layer "F.Cu")
		(net "BMC_M_MALERT_N")
	)
	(segment
		(start 435.388766 -42.6212)
		(end 435.388766 -43.086274)
		(width 0.10795)
		(layer "F.Cu")
		(net "BMC_M_MALERT_N")
	)
	(segment
		(start 434.854604 -38.3921)
		(end 434.854604 -39.0017)
		(width 0.10795)
		(layer "F.Cu")
		(net "BMC_M_MALERT_N")
	)
	(segment
		(start 435.343808 -39.54653)
		(end 435.343808 -38.3921)
		(width 0.10795)
		(layer "F.Cu")
		(net "BMC_M_MALERT_N")
	)
	(segment
		(start 435.404006 -42.108374)
		(end 435.404006 -42.60596)
		(width 0.10795)
		(layer "F.Cu")
		(net "BMC_M_MALERT_N")
	)
	(segment
		(start 436.522114 -35.832542)
		(end 436.121556 -36.2331)
		(width 0.10795)
		(layer "F.Cu")
		(net "BMC_M_MALERT_N")
	)
	(segment
		(start 434.800756 -41.505124)
		(end 434.800756 -40.089582)
		(width 0.10795)
		(layer "F.Cu")
		(net "BMC_M_MALERT_N")
	)
	(segment
		(start 434.3654 -39.0017)
		(end 434.3654 -37.989256)
		(width 0.10795)
		(layer "F.Cu")
		(net "BMC_M_MALERT_N")
	)
	(segment
		(start 435.404006 -42.60596)
		(end 435.388766 -42.6212)
		(width 0.10795)
		(layer "F.Cu")
		(net "BMC_M_MALERT_N")
	)
	(segment
		(start 419.890194 -38.534594)
		(end 420.290244 -38.935152)
		(width 0.1016)
		(layer "F.Cu")
		(net "BMC_M_MALERT_N")
	)
	(segment
		(start 434.800756 -40.089582)
		(end 435.343808 -39.54653)
		(width 0.10795)
		(layer "F.Cu")
		(net "BMC_M_MALERT_N")
	)
	(via
		(at 420.290244 -38.935152)
		(size 0.4572)
		(drill 0.2032)
		(layers "F.Cu" "B.Cu")
		(net "BMC_M_MALERT_N")
	)
	(via
		(at 424.975528 -39.27475)
		(size 0.508)
		(drill 0.254)
		(layers "F.Cu" "B.Cu")
		(net "BMC_M_MALERT_N")
	)
	(via
		(at 436.121556 -36.2331)
		(size 0.4572)
		(drill 0.2032)
		(layers "F.Cu" "B.Cu")
		(net "BMC_M_MALERT_N")
	)
	(arc
		(start 434.854604 -39.0017)
		(mid 434.610002 -39.246302)
		(end 434.3654 -39.0017)
		(width 0.10795)
		(layer "F.Cu")
		(net "BMC_M_MALERT_N")
	)
	(arc
		(start 435.343808 -38.3921)
		(mid 435.099206 -38.147498)
		(end 434.854604 -38.3921)
		(width 0.10795)
		(layer "F.Cu")
		(net "BMC_M_MALERT_N")
	)
	(segment
		(start 433.770278 -39.680896)
		(end 433.457858 -39.368476)
		(width 0.10795)
		(layer "B.Cu")
		(net "BMC_M_MALERT_N")
	)
	(segment
		(start 434.462174 -38.989)
		(end 434.149754 -38.67658)
		(width 0.10795)
		(layer "B.Cu")
		(net "BMC_M_MALERT_N")
	)
	(segment
		(start 432.167284 -39.908734)
		(end 431.664364 -39.908734)
		(width 0.10795)
		(layer "B.Cu")
		(net "BMC_M_MALERT_N")
	)
	(segment
		(start 421.873934 -39.082726)
		(end 421.873934 -38.909498)
		(width 0.10795)
		(layer "B.Cu")
		(net "BMC_M_MALERT_N")
	)
	(segment
		(start 433.804314 -38.67658)
		(end 433.803806 -38.677088)
		(width 0.10795)
		(layer "B.Cu")
		(net "BMC_M_MALERT_N")
	)
	(segment
		(start 436.032402 -36.447984)
		(end 434.495702 -37.985192)
		(width 0.10795)
		(layer "B.Cu")
		(net "BMC_M_MALERT_N")
	)
	(segment
		(start 434.808122 -38.988492)
		(end 434.807614 -38.989)
		(width 0.10795)
		(layer "B.Cu")
		(net "BMC_M_MALERT_N")
	)
	(segment
		(start 424.342306 -39.145972)
		(end 424.343068 -39.146734)
		(width 0.10795)
		(layer "B.Cu")
		(net "BMC_M_MALERT_N")
	)
	(segment
		(start 426.25137 -39.27475)
		(end 424.975528 -39.27475)
		(width 0.10795)
		(layer "B.Cu")
		(net "BMC_M_MALERT_N")
	)
	(segment
		(start 428.586138 -40.368982)
		(end 428.586138 -40.513762)
		(width 0.10795)
		(layer "B.Cu")
		(net "BMC_M_MALERT_N")
	)
	(segment
		(start 430.318672 -40.250618)
		(end 430.318672 -40.50538)
		(width 0.10795)
		(layer "B.Cu")
		(net "BMC_M_MALERT_N")
	)
	(segment
		(start 433.803806 -39.022528)
		(end 434.116226 -39.334948)
		(width 0.10795)
		(layer "B.Cu")
		(net "BMC_M_MALERT_N")
	)
	(segment
		(start 427.885606 -40.132)
		(end 427.68647 -40.132)
		(width 0.10795)
		(layer "B.Cu")
		(net "BMC_M_MALERT_N")
	)
	(segment
		(start 420.431976 -39.32174)
		(end 421.673274 -39.32174)
		(width 0.10795)
		(layer "B.Cu")
		(net "BMC_M_MALERT_N")
	)
	(segment
		(start 431.296826 -40.23995)
		(end 431.296826 -40.555672)
		(width 0.10795)
		(layer "B.Cu")
		(net "BMC_M_MALERT_N")
	)
	(segment
		(start 423.68978 -38.986968)
		(end 423.958512 -38.986968)
		(width 0.10795)
		(layer "B.Cu")
		(net "BMC_M_MALERT_N")
	)
	(segment
		(start 423.008044 -38.668452)
		(end 423.069766 -38.730174)
		(width 0.10795)
		(layer "B.Cu")
		(net "BMC_M_MALERT_N")
	)
	(segment
		(start 433.112418 -39.368476)
		(end 432.858418 -39.622476)
		(width 0.10795)
		(layer "B.Cu")
		(net "BMC_M_MALERT_N")
	)
	(segment
		(start 434.116226 -39.680388)
		(end 434.115718 -39.680896)
		(width 0.10795)
		(layer "B.Cu")
		(net "BMC_M_MALERT_N")
	)
	(segment
		(start 427.445678 -40.032178)
		(end 426.997368 -39.583868)
		(width 0.10795)
		(layer "B.Cu")
		(net "BMC_M_MALERT_N")
	)
	(segment
		(start 434.495702 -38.330632)
		(end 434.808122 -38.643052)
		(width 0.10795)
		(layer "B.Cu")
		(net "BMC_M_MALERT_N")
	)
	(segment
		(start 430.807876 -40.555672)
		(end 430.807876 -40.250618)
		(width 0.10795)
		(layer "B.Cu")
		(net "BMC_M_MALERT_N")
	)
	(segment
		(start 429.720756 -40.202612)
		(end 428.752508 -40.202612)
		(width 0.10795)
		(layer "B.Cu")
		(net "BMC_M_MALERT_N")
	)
	(segment
		(start 424.652186 -39.27475)
		(end 424.975528 -39.27475)
		(width 0.10795)
		(layer "B.Cu")
		(net "BMC_M_MALERT_N")
	)
	(segment
		(start 422.24198 -38.541452)
		(end 422.701466 -38.541452)
		(width 0.10795)
		(layer "B.Cu")
		(net "BMC_M_MALERT_N")
	)
	(segment
		(start 429.829722 -40.50538)
		(end 429.829722 -40.311578)
		(width 0.10795)
		(layer "B.Cu")
		(net "BMC_M_MALERT_N")
	)
	(segment
		(start 420.290244 -38.935152)
		(end 420.290244 -39.180008)
		(width 0.10795)
		(layer "B.Cu")
		(net "BMC_M_MALERT_N")
	)
	(segment
		(start 428.097188 -40.513762)
		(end 428.097188 -40.343582)
		(width 0.10795)
		(layer "B.Cu")
		(net "BMC_M_MALERT_N")
	)
	(arc
		(start 421.795956 -39.27094)
		(mid 421.853655 -39.184587)
		(end 421.873934 -39.082726)
		(width 0.10795)
		(layer "B.Cu")
		(net "BMC_M_MALERT_N")
	)
	(arc
		(start 423.069766 -38.730174)
		(mid 423.354231 -38.920247)
		(end 423.68978 -38.986968)
		(width 0.10795)
		(layer "B.Cu")
		(net "BMC_M_MALERT_N")
	)
	(arc
		(start 434.495702 -37.985192)
		(mid 434.424159 -38.157912)
		(end 434.495702 -38.330632)
		(width 0.10795)
		(layer "B.Cu")
		(net "BMC_M_MALERT_N")
	)
	(arc
		(start 420.290244 -39.180008)
		(mid 420.331756 -39.280228)
		(end 420.431976 -39.32174)
		(width 0.10795)
		(layer "B.Cu")
		(net "BMC_M_MALERT_N")
	)
	(arc
		(start 430.807876 -40.250618)
		(mid 430.563274 -40.006016)
		(end 430.318672 -40.250618)
		(width 0.10795)
		(layer "B.Cu")
		(net "BMC_M_MALERT_N")
	)
	(arc
		(start 423.958512 -38.986968)
		(mid 424.166232 -39.028286)
		(end 424.342306 -39.145972)
		(width 0.10795)
		(layer "B.Cu")
		(net "BMC_M_MALERT_N")
	)
	(arc
		(start 428.097188 -40.343582)
		(mid 428.035217 -40.193971)
		(end 427.885606 -40.132)
		(width 0.10795)
		(layer "B.Cu")
		(net "BMC_M_MALERT_N")
	)
	(arc
		(start 422.701466 -38.541452)
		(mid 422.867389 -38.574456)
		(end 423.008044 -38.668452)
		(width 0.10795)
		(layer "B.Cu")
		(net "BMC_M_MALERT_N")
	)
	(arc
		(start 433.457858 -39.368476)
		(mid 433.285138 -39.296933)
		(end 433.112418 -39.368476)
		(width 0.10795)
		(layer "B.Cu")
		(net "BMC_M_MALERT_N")
	)
	(arc
		(start 424.343068 -39.146734)
		(mid 424.484893 -39.241498)
		(end 424.652186 -39.27475)
		(width 0.10795)
		(layer "B.Cu")
		(net "BMC_M_MALERT_N")
	)
	(arc
		(start 434.115718 -39.680896)
		(mid 433.942998 -39.752439)
		(end 433.770278 -39.680896)
		(width 0.10795)
		(layer "B.Cu")
		(net "BMC_M_MALERT_N")
	)
	(arc
		(start 434.116226 -39.334948)
		(mid 434.187769 -39.507668)
		(end 434.116226 -39.680388)
		(width 0.10795)
		(layer "B.Cu")
		(net "BMC_M_MALERT_N")
	)
	(arc
		(start 434.807614 -38.989)
		(mid 434.634894 -39.060543)
		(end 434.462174 -38.989)
		(width 0.10795)
		(layer "B.Cu")
		(net "BMC_M_MALERT_N")
	)
	(arc
		(start 434.808122 -38.643052)
		(mid 434.879665 -38.815772)
		(end 434.808122 -38.988492)
		(width 0.10795)
		(layer "B.Cu")
		(net "BMC_M_MALERT_N")
	)
	(arc
		(start 428.752508 -40.202612)
		(mid 428.634867 -40.251341)
		(end 428.586138 -40.368982)
		(width 0.10795)
		(layer "B.Cu")
		(net "BMC_M_MALERT_N")
	)
	(arc
		(start 436.121556 -36.2331)
		(mid 436.09833 -36.349397)
		(end 436.032402 -36.447984)
		(width 0.10795)
		(layer "B.Cu")
		(net "BMC_M_MALERT_N")
	)
	(arc
		(start 432.858418 -39.622476)
		(mid 432.541323 -39.834352)
		(end 432.167284 -39.908734)
		(width 0.10795)
		(layer "B.Cu")
		(net "BMC_M_MALERT_N")
	)
	(arc
		(start 429.829722 -40.311578)
		(mid 429.797807 -40.234527)
		(end 429.720756 -40.202612)
		(width 0.10795)
		(layer "B.Cu")
		(net "BMC_M_MALERT_N")
	)
	(arc
		(start 426.5295 -39.312088)
		(mid 426.391681 -39.284141)
		(end 426.25137 -39.27475)
		(width 0.10795)
		(layer "B.Cu")
		(net "BMC_M_MALERT_N")
	)
	(arc
		(start 421.673274 -39.32174)
		(mid 421.739663 -39.308534)
		(end 421.795956 -39.27094)
		(width 0.10795)
		(layer "B.Cu")
		(net "BMC_M_MALERT_N")
	)
	(arc
		(start 421.873934 -38.909498)
		(mid 421.981732 -38.64925)
		(end 422.24198 -38.541452)
		(width 0.10795)
		(layer "B.Cu")
		(net "BMC_M_MALERT_N")
	)
	(arc
		(start 427.68647 -40.132)
		(mid 427.556137 -40.106057)
		(end 427.445678 -40.032178)
		(width 0.10795)
		(layer "B.Cu")
		(net "BMC_M_MALERT_N")
	)
	(arc
		(start 431.296826 -40.555672)
		(mid 431.052478 -40.80002)
		(end 430.807876 -40.555672)
		(width 0.10795)
		(layer "B.Cu")
		(net "BMC_M_MALERT_N")
	)
	(arc
		(start 426.997368 -39.583868)
		(mid 426.781154 -39.417471)
		(end 426.5295 -39.312088)
		(width 0.10795)
		(layer "B.Cu")
		(net "BMC_M_MALERT_N")
	)
	(arc
		(start 434.149754 -38.67658)
		(mid 433.977034 -38.605037)
		(end 433.804314 -38.67658)
		(width 0.10795)
		(layer "B.Cu")
		(net "BMC_M_MALERT_N")
	)
	(arc
		(start 431.664364 -39.908734)
		(mid 431.526766 -39.933258)
		(end 431.406046 -40.00373)
		(width 0.10795)
		(layer "B.Cu")
		(net "BMC_M_MALERT_N")
	)
	(arc
		(start 433.803806 -38.677088)
		(mid 433.732263 -38.849808)
		(end 433.803806 -39.022528)
		(width 0.10795)
		(layer "B.Cu")
		(net "BMC_M_MALERT_N")
	)
	(arc
		(start 430.318672 -40.50538)
		(mid 430.074324 -40.749728)
		(end 429.829722 -40.50538)
		(width 0.10795)
		(layer "B.Cu")
		(net "BMC_M_MALERT_N")
	)
	(arc
		(start 431.406046 -40.00373)
		(mid 431.325472 -40.109832)
		(end 431.296826 -40.23995)
		(width 0.10795)
		(layer "B.Cu")
		(net "BMC_M_MALERT_N")
	)
	(arc
		(start 428.586138 -40.513762)
		(mid 428.34179 -40.75811)
		(end 428.097188 -40.513762)
		(width 0.10795)
		(layer "B.Cu")
		(net "BMC_M_MALERT_N")
	)
	(segment
		(start 447.10096 -33.0327)
		(end 449.9864 -33.0327)
		(width 0.10795)
		(layer "F.Cu")
		(net "BMC_M_MACT_N")
	)
	(segment
		(start 449.9864 -33.0327)
		(end 450.14388 -32.87522)
		(width 0.10795)
		(layer "F.Cu")
		(net "BMC_M_MACT_N")
	)
	(segment
		(start 444.040006 -33.6677)
		(end 444.040006 -33.1597)
		(width 0.10795)
		(layer "F.Cu")
		(net "BMC_M_MACT_N")
	)
	(segment
		(start 444.040006 -33.1597)
		(end 444.167006 -33.0327)
		(width 0.10795)
		(layer "F.Cu")
		(net "BMC_M_MACT_N")
	)
	(segment
		(start 443.862206 -33.8455)
		(end 444.040006 -33.6677)
		(width 0.10795)
		(layer "F.Cu")
		(net "BMC_M_MACT_N")
	)
	(segment
		(start 439.874406 -35.1155)
		(end 440.433206 -34.5567)
		(width 0.10795)
		(layer "F.Cu")
		(net "BMC_M_MACT_N")
	)
	(segment
		(start 422.29024 -37.734748)
		(end 421.89019 -37.334698)
		(width 0.1016)
		(layer "F.Cu")
		(net "BMC_M_MACT_N")
	)
	(segment
		(start 444.167006 -33.0327)
		(end 447.10096 -33.0327)
		(width 0.10795)
		(layer "F.Cu")
		(net "BMC_M_MACT_N")
	)
	(segment
		(start 440.433206 -33.7693)
		(end 440.77001 -33.432496)
		(width 0.10795)
		(layer "F.Cu")
		(net "BMC_M_MACT_N")
	)
	(segment
		(start 440.433206 -34.5567)
		(end 440.433206 -33.7693)
		(width 0.10795)
		(layer "F.Cu")
		(net "BMC_M_MACT_N")
	)
	(segment
		(start 450.14388 -32.4485)
		(end 451.41388 -32.4485)
		(width 0.10795)
		(layer "F.Cu")
		(net "BMC_M_MACT_N")
	)
	(segment
		(start 440.77001 -33.432496)
		(end 441.321952 -33.432496)
		(width 0.10795)
		(layer "F.Cu")
		(net "BMC_M_MACT_N")
	)
	(segment
		(start 450.14388 -32.87522)
		(end 450.14388 -32.4485)
		(width 0.10795)
		(layer "F.Cu")
		(net "BMC_M_MACT_N")
	)
	(segment
		(start 439.874406 -35.4203)
		(end 439.874406 -35.1155)
		(width 0.10795)
		(layer "F.Cu")
		(net "BMC_M_MACT_N")
	)
	(segment
		(start 441.321952 -33.432496)
		(end 441.341002 -33.432496)
		(width 0.10795)
		(layer "F.Cu")
		(net "BMC_M_MACT_N")
	)
	(segment
		(start 441.341002 -33.432496)
		(end 441.754006 -33.8455)
		(width 0.10795)
		(layer "F.Cu")
		(net "BMC_M_MACT_N")
	)
	(segment
		(start 441.754006 -33.8455)
		(end 443.862206 -33.8455)
		(width 0.10795)
		(layer "F.Cu")
		(net "BMC_M_MACT_N")
	)
	(via
		(at 421.89019 -37.334698)
		(size 0.4572)
		(drill 0.2032)
		(layers "F.Cu" "B.Cu")
		(net "BMC_M_MACT_N")
	)
	(via
		(at 447.10096 -33.0327)
		(size 0.508)
		(drill 0.254)
		(layers "F.Cu" "B.Cu")
		(net "BMC_M_MACT_N")
	)
	(via
		(at 439.874406 -35.4203)
		(size 0.4572)
		(drill 0.2032)
		(layers "F.Cu" "B.Cu")
		(net "BMC_M_MACT_N")
	)
	(segment
		(start 438.821322 -36.47313)
		(end 438.750964 -36.543488)
		(width 0.089408)
		(layer "In2.Cu")
		(net "BMC_M_MACT_N")
	)
	(segment
		(start 422.010332 -37.334698)
		(end 421.89019 -37.334698)
		(width 0.089408)
		(layer "In2.Cu")
		(net "BMC_M_MACT_N")
	)
	(segment
		(start 422.364916 -37.568124)
		(end 422.217088 -37.420296)
		(width 0.089408)
		(layer "In2.Cu")
		(net "BMC_M_MACT_N")
	)
	(segment
		(start 429.983138 -39.155116)
		(end 429.983138 -39.22776)
		(width 0.089408)
		(layer "In2.Cu")
		(net "BMC_M_MACT_N")
	)
	(segment
		(start 435.177184 -37.141404)
		(end 433.739036 -38.579552)
		(width 0.089408)
		(layer "In2.Cu")
		(net "BMC_M_MACT_N")
	)
	(segment
		(start 425.158916 -39.244524)
		(end 423.791888 -37.877496)
		(width 0.089408)
		(layer "In2.Cu")
		(net "BMC_M_MACT_N")
	)
	(segment
		(start 428.816262 -39.475156)
		(end 425.715684 -39.475156)
		(width 0.089408)
		(layer "In2.Cu")
		(net "BMC_M_MACT_N")
	)
	(segment
		(start 429.51273 -39.22776)
		(end 429.51273 -39.139622)
		(width 0.089408)
		(layer "In2.Cu")
		(net "BMC_M_MACT_N")
	)
	(segment
		(start 438.51957 -36.6395)
		(end 436.38851 -36.6395)
		(width 0.089408)
		(layer "In2.Cu")
		(net "BMC_M_MACT_N")
	)
	(segment
		(start 430.453546 -39.249096)
		(end 430.453546 -39.155116)
		(width 0.089408)
		(layer "In2.Cu")
		(net "BMC_M_MACT_N")
	)
	(segment
		(start 429.042322 -39.139622)
		(end 429.042322 -39.249096)
		(width 0.089408)
		(layer "In2.Cu")
		(net "BMC_M_MACT_N")
	)
	(segment
		(start 439.874406 -35.4203)
		(end 439.517282 -35.777424)
		(width 0.089408)
		(layer "In2.Cu")
		(net "BMC_M_MACT_N")
	)
	(segment
		(start 431.839878 -39.36619)
		(end 430.57064 -39.36619)
		(width 0.089408)
		(layer "In2.Cu")
		(net "BMC_M_MACT_N")
	)
	(segment
		(start 423.493692 -37.754052)
		(end 422.813988 -37.754052)
		(width 0.089408)
		(layer "In2.Cu")
		(net "BMC_M_MACT_N")
	)
	(arc
		(start 423.791888 -37.877496)
		(mid 423.65506 -37.786134)
		(end 423.493692 -37.754052)
		(width 0.089408)
		(layer "In2.Cu")
		(net "BMC_M_MACT_N")
	)
	(arc
		(start 438.750964 -36.543488)
		(mid 438.644815 -36.614508)
		(end 438.51957 -36.6395)
		(width 0.089408)
		(layer "In2.Cu")
		(net "BMC_M_MACT_N")
	)
	(arc
		(start 425.715684 -39.475156)
		(mid 425.414345 -39.415234)
		(end 425.158916 -39.244524)
		(width 0.089408)
		(layer "In2.Cu")
		(net "BMC_M_MACT_N")
	)
	(arc
		(start 433.739036 -38.579552)
		(mid 432.867695 -39.161764)
		(end 431.839878 -39.36619)
		(width 0.089408)
		(layer "In2.Cu")
		(net "BMC_M_MACT_N")
	)
	(arc
		(start 429.51273 -39.139622)
		(mid 429.277526 -38.904418)
		(end 429.042322 -39.139622)
		(width 0.089408)
		(layer "In2.Cu")
		(net "BMC_M_MACT_N")
	)
	(arc
		(start 439.154062 -35.77717)
		(mid 438.821322 -35.77717)
		(end 438.821322 -36.10991)
		(width 0.089408)
		(layer "In2.Cu")
		(net "BMC_M_MACT_N")
	)
	(arc
		(start 439.517282 -35.777424)
		(mid 439.335582 -35.852649)
		(end 439.154062 -35.77717)
		(width 0.089408)
		(layer "In2.Cu")
		(net "BMC_M_MACT_N")
	)
	(arc
		(start 438.821322 -36.10991)
		(mid 438.896547 -36.29152)
		(end 438.821322 -36.47313)
		(width 0.089408)
		(layer "In2.Cu")
		(net "BMC_M_MACT_N")
	)
	(arc
		(start 422.217088 -37.420296)
		(mid 422.122228 -37.356912)
		(end 422.010332 -37.334698)
		(width 0.089408)
		(layer "In2.Cu")
		(net "BMC_M_MACT_N")
	)
	(arc
		(start 430.453546 -39.155116)
		(mid 430.218342 -38.919912)
		(end 429.983138 -39.155116)
		(width 0.089408)
		(layer "In2.Cu")
		(net "BMC_M_MACT_N")
	)
	(arc
		(start 436.38851 -36.6395)
		(mid 435.732925 -36.76998)
		(end 435.177184 -37.141404)
		(width 0.089408)
		(layer "In2.Cu")
		(net "BMC_M_MACT_N")
	)
	(arc
		(start 429.042322 -39.249096)
		(mid 428.976111 -39.408945)
		(end 428.816262 -39.475156)
		(width 0.089408)
		(layer "In2.Cu")
		(net "BMC_M_MACT_N")
	)
	(arc
		(start 429.983138 -39.22776)
		(mid 429.747934 -39.462964)
		(end 429.51273 -39.22776)
		(width 0.089408)
		(layer "In2.Cu")
		(net "BMC_M_MACT_N")
	)
	(arc
		(start 430.57064 -39.36619)
		(mid 430.487842 -39.331894)
		(end 430.453546 -39.249096)
		(width 0.089408)
		(layer "In2.Cu")
		(net "BMC_M_MACT_N")
	)
	(arc
		(start 422.813988 -37.754052)
		(mid 422.57097 -37.705731)
		(end 422.364916 -37.568124)
		(width 0.089408)
		(layer "In2.Cu")
		(net "BMC_M_MACT_N")
	)
	(segment
		(start 438.12206 -26.232104)
		(end 437.721756 -25.8318)
		(width 0.1016)
		(layer "F.Cu")
		(net "BMC_M_DQS1_DP")
	)
	(segment
		(start 424.15841 -31.16326)
		(end 425.62526 -31.16326)
		(width 0.10033)
		(layer "F.Cu")
		(net "BMC_M_DQS1_DP")
	)
	(segment
		(start 423.890186 -31.33471)
		(end 423.993056 -31.23184)
		(width 0.10033)
		(layer "F.Cu")
		(net "BMC_M_DQS1_DP")
	)
	(segment
		(start 438.12206 -26.232612)
		(end 438.12206 -26.232104)
		(width 0.1016)
		(layer "F.Cu")
		(net "BMC_M_DQS1_DP")
	)
	(segment
		(start 425.928536 -31.289244)
		(end 425.929044 -31.289752)
		(width 0.10033)
		(layer "F.Cu")
		(net "BMC_M_DQS1_DP")
	)
	(via
		(at 425.929044 -31.289752)
		(size 0.4572)
		(drill 0.2032)
		(layers "F.Cu" "B.Cu")
		(net "BMC_M_DQS1_DP")
	)
	(via
		(at 437.721756 -25.8318)
		(size 0.4572)
		(drill 0.2032)
		(layers "F.Cu" "B.Cu")
		(net "BMC_M_DQS1_DP")
	)
	(via
		(at 427.156118 -29.552646)
		(size 0.508)
		(drill 0.254)
		(layers "F.Cu" "B.Cu")
		(net "BMC_M_DQS1_DP")
	)
	(arc
		(start 425.62526 -31.16326)
		(mid 425.789459 -31.196011)
		(end 425.928536 -31.289244)
		(width 0.10033)
		(layer "F.Cu")
		(net "BMC_M_DQS1_DP")
	)
	(arc
		(start 423.993056 -31.23184)
		(mid 424.068907 -31.181095)
		(end 424.15841 -31.16326)
		(width 0.10033)
		(layer "F.Cu")
		(net "BMC_M_DQS1_DP")
	)
	(segment
		(start 432.848766 -26.869898)
		(end 433.501038 -27.52217)
		(width 0.10033)
		(layer "B.Cu")
		(net "BMC_M_DQS1_DP")
	)
	(segment
		(start 428.746158 -27.568906)
		(end 428.746158 -27.742642)
		(width 0.10033)
		(layer "B.Cu")
		(net "BMC_M_DQS1_DP")
	)
	(segment
		(start 430.268888 -27.742642)
		(end 430.268888 -27.564842)
		(width 0.10033)
		(layer "B.Cu")
		(net "BMC_M_DQS1_DP")
	)
	(segment
		(start 434.587142 -26.436066)
		(end 433.902358 -25.751282)
		(width 0.10033)
		(layer "B.Cu")
		(net "BMC_M_DQS1_DP")
	)
	(segment
		(start 436.551832 -25.66035)
		(end 437.308498 -25.66035)
		(width 0.10033)
		(layer "B.Cu")
		(net "BMC_M_DQS1_DP")
	)
	(segment
		(start 427.156118 -29.552646)
		(end 427.156118 -28.531312)
		(width 0.10033)
		(layer "B.Cu")
		(net "BMC_M_DQS1_DP")
	)
	(segment
		(start 435.98084 -26.096214)
		(end 436.320692 -25.756108)
		(width 0.10033)
		(layer "B.Cu")
		(net "BMC_M_DQS1_DP")
	)
	(segment
		(start 426.343064 -31.118302)
		(end 426.522642 -31.118302)
		(width 0.10033)
		(layer "B.Cu")
		(net "BMC_M_DQS1_DP")
	)
	(segment
		(start 437.721248 -25.831292)
		(end 437.721756 -25.8318)
		(width 0.10033)
		(layer "B.Cu")
		(net "BMC_M_DQS1_DP")
	)
	(segment
		(start 427.156118 -30.484826)
		(end 427.156118 -29.552646)
		(width 0.10033)
		(layer "B.Cu")
		(net "BMC_M_DQS1_DP")
	)
	(segment
		(start 432.399948 -27.699462)
		(end 432.399948 -27.055826)
		(width 0.10033)
		(layer "B.Cu")
		(net "BMC_M_DQS1_DP")
	)
	(segment
		(start 434.332634 -25.321006)
		(end 435.107842 -26.096214)
		(width 0.10033)
		(layer "B.Cu")
		(net "BMC_M_DQS1_DP")
	)
	(segment
		(start 430.877218 -27.564842)
		(end 430.877218 -27.699462)
		(width 0.10033)
		(layer "B.Cu")
		(net "BMC_M_DQS1_DP")
	)
	(segment
		(start 427.256448 -28.430982)
		(end 427.382178 -28.430982)
		(width 0.10033)
		(layer "B.Cu")
		(net "BMC_M_DQS1_DP")
	)
	(segment
		(start 428.137828 -27.675332)
		(end 428.137828 -27.568906)
		(width 0.10033)
		(layer "B.Cu")
		(net "BMC_M_DQS1_DP")
	)
	(arc
		(start 426.522642 -31.118302)
		(mid 426.970577 -30.932761)
		(end 427.156118 -30.484826)
		(width 0.10033)
		(layer "B.Cu")
		(net "BMC_M_DQS1_DP")
	)
	(arc
		(start 435.107842 -26.096214)
		(mid 435.544378 -26.277145)
		(end 435.98084 -26.096214)
		(width 0.10033)
		(layer "B.Cu")
		(net "BMC_M_DQS1_DP")
	)
	(arc
		(start 437.308498 -25.66035)
		(mid 437.531867 -25.704781)
		(end 437.721248 -25.831292)
		(width 0.10033)
		(layer "B.Cu")
		(net "BMC_M_DQS1_DP")
	)
	(arc
		(start 428.137828 -27.568906)
		(mid 428.44212 -27.264614)
		(end 428.746158 -27.568906)
		(width 0.10033)
		(layer "B.Cu")
		(net "BMC_M_DQS1_DP")
	)
	(arc
		(start 428.746158 -27.742642)
		(mid 429.50765 -28.504134)
		(end 430.268888 -27.742642)
		(width 0.10033)
		(layer "B.Cu")
		(net "BMC_M_DQS1_DP")
	)
	(arc
		(start 430.877218 -27.699462)
		(mid 431.63871 -28.460954)
		(end 432.399948 -27.699462)
		(width 0.10033)
		(layer "B.Cu")
		(net "BMC_M_DQS1_DP")
	)
	(arc
		(start 427.382178 -28.430982)
		(mid 427.916503 -28.209657)
		(end 428.137828 -27.675332)
		(width 0.10033)
		(layer "B.Cu")
		(net "BMC_M_DQS1_DP")
	)
	(arc
		(start 433.902358 -25.751282)
		(mid 433.902358 -25.321006)
		(end 434.332634 -25.321006)
		(width 0.10033)
		(layer "B.Cu")
		(net "BMC_M_DQS1_DP")
	)
	(arc
		(start 425.929044 -31.289752)
		(mid 426.118998 -31.162829)
		(end 426.343064 -31.118302)
		(width 0.10033)
		(layer "B.Cu")
		(net "BMC_M_DQS1_DP")
	)
	(arc
		(start 432.399948 -27.055826)
		(mid 432.562234 -26.812947)
		(end 432.848766 -26.869898)
		(width 0.10033)
		(layer "B.Cu")
		(net "BMC_M_DQS1_DP")
	)
	(arc
		(start 430.268888 -27.564842)
		(mid 430.57318 -27.26055)
		(end 430.877218 -27.564842)
		(width 0.10033)
		(layer "B.Cu")
		(net "BMC_M_DQS1_DP")
	)
	(arc
		(start 436.320692 -25.756108)
		(mid 436.42674 -25.685249)
		(end 436.551832 -25.66035)
		(width 0.10033)
		(layer "B.Cu")
		(net "BMC_M_DQS1_DP")
	)
	(arc
		(start 427.156118 -28.531312)
		(mid 427.185504 -28.460368)
		(end 427.256448 -28.430982)
		(width 0.10033)
		(layer "B.Cu")
		(net "BMC_M_DQS1_DP")
	)
	(arc
		(start 433.501038 -27.52217)
		(mid 434.587142 -27.52217)
		(end 434.587142 -26.436066)
		(width 0.10033)
		(layer "B.Cu")
		(net "BMC_M_DQS1_DP")
	)
	(segment
		(start 425.929044 -30.489652)
		(end 425.928536 -30.49016)
		(width 0.10033)
		(layer "F.Cu")
		(net "BMC_M_DQS1_DN")
	)
	(segment
		(start 438.12206 -25.432004)
		(end 437.721756 -25.0317)
		(width 0.1016)
		(layer "F.Cu")
		(net "BMC_M_DQS1_DN")
	)
	(segment
		(start 438.12206 -25.432512)
		(end 438.12206 -25.432004)
		(width 0.1016)
		(layer "F.Cu")
		(net "BMC_M_DQS1_DN")
	)
	(segment
		(start 425.406312 -30.70606)
		(end 424.447208 -30.70606)
		(width 0.10033)
		(layer "F.Cu")
		(net "BMC_M_DQS1_DN")
	)
	(via
		(at 437.721756 -25.0317)
		(size 0.4572)
		(drill 0.2032)
		(layers "F.Cu" "B.Cu")
		(net "BMC_M_DQS1_DN")
	)
	(via
		(at 435.011068 -25.352756)
		(size 0.508)
		(drill 0.254)
		(layers "F.Cu" "B.Cu")
		(net "BMC_M_DQS1_DN")
	)
	(via
		(at 425.929044 -30.489652)
		(size 0.4572)
		(drill 0.2032)
		(layers "F.Cu" "B.Cu")
		(net "BMC_M_DQS1_DN")
	)
	(arc
		(start 425.928536 -30.49016)
		(mid 425.688852 -30.649933)
		(end 425.406312 -30.70606)
		(width 0.10033)
		(layer "F.Cu")
		(net "BMC_M_DQS1_DN")
	)
	(arc
		(start 424.447208 -30.70606)
		(mid 424.155802 -30.662229)
		(end 423.890186 -30.53461)
		(width 0.10033)
		(layer "F.Cu")
		(net "BMC_M_DQS1_DN")
	)
	(segment
		(start 433.82438 -27.198828)
		(end 433.172108 -26.546556)
		(width 0.10033)
		(layer "B.Cu")
		(net "BMC_M_DQS1_DN")
	)
	(segment
		(start 426.698918 -28.531312)
		(end 426.698918 -30.484826)
		(width 0.10033)
		(layer "B.Cu")
		(net "BMC_M_DQS1_DN")
	)
	(segment
		(start 433.578762 -26.074624)
		(end 434.2638 -26.759408)
		(width 0.10033)
		(layer "B.Cu")
		(net "BMC_M_DQS1_DN")
	)
	(segment
		(start 431.942748 -27.055826)
		(end 431.942748 -27.699462)
		(width 0.10033)
		(layer "B.Cu")
		(net "BMC_M_DQS1_DN")
	)
	(segment
		(start 437.721756 -25.0317)
		(end 437.609996 -25.14346)
		(width 0.10033)
		(layer "B.Cu")
		(net "BMC_M_DQS1_DN")
	)
	(segment
		(start 435.99735 -25.432512)
		(end 435.657244 -25.772872)
		(width 0.10033)
		(layer "B.Cu")
		(net "BMC_M_DQS1_DN")
	)
	(segment
		(start 435.011068 -25.352756)
		(end 434.655976 -24.997664)
		(width 0.10033)
		(layer "B.Cu")
		(net "BMC_M_DQS1_DN")
	)
	(segment
		(start 431.334418 -27.699462)
		(end 431.334418 -27.564842)
		(width 0.10033)
		(layer "B.Cu")
		(net "BMC_M_DQS1_DN")
	)
	(segment
		(start 435.431184 -25.772872)
		(end 435.011068 -25.352756)
		(width 0.10033)
		(layer "B.Cu")
		(net "BMC_M_DQS1_DN")
	)
	(segment
		(start 427.382178 -27.973782)
		(end 427.256448 -27.973782)
		(width 0.10033)
		(layer "B.Cu")
		(net "BMC_M_DQS1_DN")
	)
	(segment
		(start 429.203358 -27.742642)
		(end 429.203358 -27.568906)
		(width 0.10033)
		(layer "B.Cu")
		(net "BMC_M_DQS1_DN")
	)
	(segment
		(start 429.811688 -27.564842)
		(end 429.811688 -27.742642)
		(width 0.10033)
		(layer "B.Cu")
		(net "BMC_M_DQS1_DN")
	)
	(segment
		(start 426.522642 -30.661102)
		(end 426.343064 -30.661102)
		(width 0.10033)
		(layer "B.Cu")
		(net "BMC_M_DQS1_DN")
	)
	(segment
		(start 427.680628 -27.568906)
		(end 427.680628 -27.675332)
		(width 0.10033)
		(layer "B.Cu")
		(net "BMC_M_DQS1_DN")
	)
	(segment
		(start 437.465978 -25.20315)
		(end 436.551832 -25.20315)
		(width 0.10033)
		(layer "B.Cu")
		(net "BMC_M_DQS1_DN")
	)
	(arc
		(start 433.172108 -26.546556)
		(mid 432.387223 -26.390433)
		(end 431.942748 -27.055826)
		(width 0.10033)
		(layer "B.Cu")
		(net "BMC_M_DQS1_DN")
	)
	(arc
		(start 434.2638 -26.759408)
		(mid 434.2638 -27.198828)
		(end 433.82438 -27.198828)
		(width 0.10033)
		(layer "B.Cu")
		(net "BMC_M_DQS1_DN")
	)
	(arc
		(start 429.203358 -27.568906)
		(mid 428.44212 -26.807668)
		(end 427.680628 -27.568906)
		(width 0.10033)
		(layer "B.Cu")
		(net "BMC_M_DQS1_DN")
	)
	(arc
		(start 437.609996 -25.14346)
		(mid 437.54392 -25.187611)
		(end 437.465978 -25.20315)
		(width 0.10033)
		(layer "B.Cu")
		(net "BMC_M_DQS1_DN")
	)
	(arc
		(start 431.334418 -27.564842)
		(mid 430.57318 -26.803604)
		(end 429.811688 -27.564842)
		(width 0.10033)
		(layer "B.Cu")
		(net "BMC_M_DQS1_DN")
	)
	(arc
		(start 426.343064 -30.661102)
		(mid 426.119014 -30.616536)
		(end 425.929044 -30.489652)
		(width 0.10033)
		(layer "B.Cu")
		(net "BMC_M_DQS1_DN")
	)
	(arc
		(start 426.698918 -30.484826)
		(mid 426.647288 -30.609472)
		(end 426.522642 -30.661102)
		(width 0.10033)
		(layer "B.Cu")
		(net "BMC_M_DQS1_DN")
	)
	(arc
		(start 429.811688 -27.742642)
		(mid 429.50765 -28.04668)
		(end 429.203358 -27.742642)
		(width 0.10033)
		(layer "B.Cu")
		(net "BMC_M_DQS1_DN")
	)
	(arc
		(start 427.680628 -27.675332)
		(mid 427.593214 -27.886368)
		(end 427.382178 -27.973782)
		(width 0.10033)
		(layer "B.Cu")
		(net "BMC_M_DQS1_DN")
	)
	(arc
		(start 434.655976 -24.997664)
		(mid 433.579079 -24.997601)
		(end 433.578762 -26.074624)
		(width 0.10033)
		(layer "B.Cu")
		(net "BMC_M_DQS1_DN")
	)
	(arc
		(start 436.551832 -25.20315)
		(mid 436.251786 -25.262704)
		(end 435.99735 -25.432512)
		(width 0.10033)
		(layer "B.Cu")
		(net "BMC_M_DQS1_DN")
	)
	(arc
		(start 435.657244 -25.772872)
		(mid 435.544214 -25.819691)
		(end 435.431184 -25.772872)
		(width 0.10033)
		(layer "B.Cu")
		(net "BMC_M_DQS1_DN")
	)
	(arc
		(start 427.256448 -27.973782)
		(mid 426.862215 -28.137079)
		(end 426.698918 -28.531312)
		(width 0.10033)
		(layer "B.Cu")
		(net "BMC_M_DQS1_DN")
	)
	(arc
		(start 431.942748 -27.699462)
		(mid 431.63871 -28.0035)
		(end 431.334418 -27.699462)
		(width 0.10033)
		(layer "B.Cu")
		(net "BMC_M_DQS1_DN")
	)
	(segment
		(start 425.988734 -33.233106)
		(end 424.108118 -33.233106)
		(width 0.10033)
		(layer "F.Cu")
		(net "BMC_M_DQS0_DP")
	)
	(segment
		(start 441.321952 -30.232096)
		(end 440.922156 -29.8323)
		(width 0.1016)
		(layer "F.Cu")
		(net "BMC_M_DQS0_DP")
	)
	(segment
		(start 441.321952 -30.232604)
		(end 441.321952 -30.232096)
		(width 0.1016)
		(layer "F.Cu")
		(net "BMC_M_DQS0_DP")
	)
	(segment
		(start 426.056044 -32.928052)
		(end 426.083222 -32.948372)
		(width 0.10033)
		(layer "F.Cu")
		(net "BMC_M_DQS0_DP")
	)
	(via
		(at 440.922156 -29.8323)
		(size 0.4572)
		(drill 0.2032)
		(layers "F.Cu" "B.Cu")
		(net "BMC_M_DQS0_DP")
	)
	(via
		(at 426.056044 -32.928052)
		(size 0.4572)
		(drill 0.2032)
		(layers "F.Cu" "B.Cu")
		(net "BMC_M_DQS0_DP")
	)
	(via
		(at 429.47844 -31.532322)
		(size 0.508)
		(drill 0.254)
		(layers "F.Cu" "B.Cu")
		(net "BMC_M_DQS0_DP")
	)
	(arc
		(start 424.108118 -33.233106)
		(mid 423.923311 -33.139236)
		(end 423.890186 -32.934656)
		(width 0.10033)
		(layer "F.Cu")
		(net "BMC_M_DQS0_DP")
	)
	(arc
		(start 426.083222 -32.948372)
		(mid 426.138784 -33.124894)
		(end 425.988734 -33.233106)
		(width 0.10033)
		(layer "F.Cu")
		(net "BMC_M_DQS0_DP")
	)
	(segment
		(start 427.833282 -33.123632)
		(end 426.15739 -33.123632)
		(width 0.10033)
		(layer "B.Cu")
		(net "BMC_M_DQS0_DP")
	)
	(segment
		(start 438.44083 -28.7147)
		(end 436.80761 -28.7147)
		(width 0.10033)
		(layer "B.Cu")
		(net "BMC_M_DQS0_DP")
	)
	(segment
		(start 439.48096 -30.043374)
		(end 440.255914 -29.26842)
		(width 0.10033)
		(layer "B.Cu")
		(net "BMC_M_DQS0_DP")
	)
	(segment
		(start 436.153306 -28.985464)
		(end 435.036468 -30.102048)
		(width 0.10033)
		(layer "B.Cu")
		(net "BMC_M_DQS0_DP")
	)
	(segment
		(start 440.627262 -28.896818)
		(end 440.627516 -28.896818)
		(width 0.10033)
		(layer "B.Cu")
		(net "BMC_M_DQS0_DP")
	)
	(segment
		(start 431.280062 -30.2006)
		(end 431.279808 -30.200346)
		(width 0.10033)
		(layer "B.Cu")
		(net "BMC_M_DQS0_DP")
	)
	(segment
		(start 428.248572 -32.76219)
		(end 427.92523 -33.085278)
		(width 0.10033)
		(layer "B.Cu")
		(net "BMC_M_DQS0_DP")
	)
	(segment
		(start 439.550048 -27.819604)
		(end 438.806336 -28.563316)
		(width 0.10033)
		(layer "B.Cu")
		(net "BMC_M_DQS0_DP")
	)
	(segment
		(start 431.279808 -30.200346)
		(end 431.279808 -30.2006)
		(width 0.10033)
		(layer "B.Cu")
		(net "BMC_M_DQS0_DP")
	)
	(segment
		(start 430.478184 -30.532578)
		(end 429.47844 -31.532322)
		(width 0.10033)
		(layer "B.Cu")
		(net "BMC_M_DQS0_DP")
	)
	(segment
		(start 440.302396 -30.621478)
		(end 439.720228 -30.621478)
		(width 0.10033)
		(layer "B.Cu")
		(net "BMC_M_DQS0_DP")
	)
	(segment
		(start 440.992006 -30.159452)
		(end 440.808872 -30.38221)
		(width 0.10033)
		(layer "B.Cu")
		(net "BMC_M_DQS0_DP")
	)
	(segment
		(start 434.798724 -30.2006)
		(end 431.280062 -30.2006)
		(width 0.10033)
		(layer "B.Cu")
		(net "BMC_M_DQS0_DP")
	)
	(segment
		(start 440.255914 -29.26842)
		(end 440.255914 -29.268166)
		(width 0.10033)
		(layer "B.Cu")
		(net "BMC_M_DQS0_DP")
	)
	(segment
		(start 426.056044 -33.022286)
		(end 426.056044 -32.928052)
		(width 0.10033)
		(layer "B.Cu")
		(net "BMC_M_DQS0_DP")
	)
	(segment
		(start 429.47844 -31.532322)
		(end 428.248572 -32.76219)
		(width 0.10033)
		(layer "B.Cu")
		(net "BMC_M_DQS0_DP")
	)
	(segment
		(start 440.255914 -29.268166)
		(end 440.627262 -28.896818)
		(width 0.10033)
		(layer "B.Cu")
		(net "BMC_M_DQS0_DP")
	)
	(arc
		(start 435.036468 -30.102048)
		(mid 434.92739 -30.174932)
		(end 434.798724 -30.2006)
		(width 0.10033)
		(layer "B.Cu")
		(net "BMC_M_DQS0_DP")
	)
	(arc
		(start 431.279808 -30.2006)
		(mid 430.845958 -30.286822)
		(end 430.478184 -30.532578)
		(width 0.10033)
		(layer "B.Cu")
		(net "BMC_M_DQS0_DP")
	)
	(arc
		(start 440.922156 -29.8323)
		(mid 441.035877 -29.979012)
		(end 440.992006 -30.159452)
		(width 0.10033)
		(layer "B.Cu")
		(net "BMC_M_DQS0_DP")
	)
	(arc
		(start 438.806336 -28.563316)
		(mid 438.63864 -28.675367)
		(end 438.44083 -28.7147)
		(width 0.10033)
		(layer "B.Cu")
		(net "BMC_M_DQS0_DP")
	)
	(arc
		(start 440.627516 -28.896818)
		(mid 440.627326 -27.819667)
		(end 439.550048 -27.819604)
		(width 0.10033)
		(layer "B.Cu")
		(net "BMC_M_DQS0_DP")
	)
	(arc
		(start 439.720228 -30.621478)
		(mid 439.407385 -30.412383)
		(end 439.48096 -30.043374)
		(width 0.10033)
		(layer "B.Cu")
		(net "BMC_M_DQS0_DP")
	)
	(arc
		(start 436.80761 -28.7147)
		(mid 436.453509 -28.784966)
		(end 436.153306 -28.985464)
		(width 0.10033)
		(layer "B.Cu")
		(net "BMC_M_DQS0_DP")
	)
	(arc
		(start 427.92523 -33.085278)
		(mid 427.883073 -33.113603)
		(end 427.833282 -33.123632)
		(width 0.10033)
		(layer "B.Cu")
		(net "BMC_M_DQS0_DP")
	)
	(arc
		(start 440.808872 -30.38221)
		(mid 440.582459 -30.558613)
		(end 440.302396 -30.621478)
		(width 0.10033)
		(layer "B.Cu")
		(net "BMC_M_DQS0_DP")
	)
	(arc
		(start 426.15739 -33.123632)
		(mid 426.085728 -33.093948)
		(end 426.056044 -33.022286)
		(width 0.10033)
		(layer "B.Cu")
		(net "BMC_M_DQS0_DP")
	)
	(segment
		(start 441.32246 -29.432504)
		(end 441.722256 -29.8323)
		(width 0.1016)
		(layer "F.Cu")
		(net "BMC_M_DQS0_DN")
	)
	(segment
		(start 441.321952 -29.432504)
		(end 441.32246 -29.432504)
		(width 0.1016)
		(layer "F.Cu")
		(net "BMC_M_DQS0_DN")
	)
	(segment
		(start 423.997628 -33.690306)
		(end 425.964604 -33.690306)
		(width 0.10033)
		(layer "F.Cu")
		(net "BMC_M_DQS0_DN")
	)
	(via
		(at 426.056044 -33.728152)
		(size 0.4572)
		(drill 0.2032)
		(layers "F.Cu" "B.Cu")
		(net "BMC_M_DQS0_DN")
	)
	(via
		(at 434.156358 -30.6578)
		(size 0.508)
		(drill 0.254)
		(layers "F.Cu" "B.Cu")
		(net "BMC_M_DQS0_DN")
	)
	(via
		(at 441.722256 -29.8323)
		(size 0.4572)
		(drill 0.2032)
		(layers "F.Cu" "B.Cu")
		(net "BMC_M_DQS0_DN")
	)
	(arc
		(start 423.890186 -33.734756)
		(mid 423.939481 -33.701818)
		(end 423.997628 -33.690306)
		(width 0.10033)
		(layer "F.Cu")
		(net "BMC_M_DQS0_DN")
	)
	(arc
		(start 425.964604 -33.690306)
		(mid 426.01408 -33.700147)
		(end 426.056044 -33.728152)
		(width 0.10033)
		(layer "F.Cu")
		(net "BMC_M_DQS0_DN")
	)
	(segment
		(start 431.279808 -30.6578)
		(end 434.156358 -30.6578)
		(width 0.10033)
		(layer "B.Cu")
		(net "BMC_M_DQS0_DN")
	)
	(segment
		(start 439.798714 -29.078682)
		(end 439.798714 -29.078936)
		(width 0.10033)
		(layer "B.Cu")
		(net "BMC_M_DQS0_DN")
	)
	(segment
		(start 426.202856 -33.580832)
		(end 427.833282 -33.580832)
		(width 0.10033)
		(layer "B.Cu")
		(net "BMC_M_DQS0_DN")
	)
	(segment
		(start 435.35981 -30.42539)
		(end 436.476648 -29.308806)
		(width 0.10033)
		(layer "B.Cu")
		(net "BMC_M_DQS0_DN")
	)
	(segment
		(start 436.807356 -29.1719)
		(end 438.44083 -29.1719)
		(width 0.10033)
		(layer "B.Cu")
		(net "BMC_M_DQS0_DN")
	)
	(segment
		(start 440.30392 -28.573476)
		(end 439.798714 -29.078682)
		(width 0.10033)
		(layer "B.Cu")
		(net "BMC_M_DQS0_DN")
	)
	(segment
		(start 428.248826 -33.40862)
		(end 430.801526 -30.85592)
		(width 0.10033)
		(layer "B.Cu")
		(net "BMC_M_DQS0_DN")
	)
	(segment
		(start 434.156358 -30.6578)
		(end 434.798978 -30.6578)
		(width 0.10033)
		(layer "B.Cu")
		(net "BMC_M_DQS0_DN")
	)
	(segment
		(start 439.720228 -31.078678)
		(end 440.30265 -31.078678)
		(width 0.10033)
		(layer "B.Cu")
		(net "BMC_M_DQS0_DN")
	)
	(segment
		(start 441.162186 -30.672786)
		(end 441.34532 -30.450028)
		(width 0.10033)
		(layer "B.Cu")
		(net "BMC_M_DQS0_DN")
	)
	(segment
		(start 439.798714 -29.078936)
		(end 439.157618 -29.720032)
		(width 0.10033)
		(layer "B.Cu")
		(net "BMC_M_DQS0_DN")
	)
	(segment
		(start 439.129678 -28.886658)
		(end 439.87339 -28.142946)
		(width 0.10033)
		(layer "B.Cu")
		(net "BMC_M_DQS0_DN")
	)
	(segment
		(start 426.056044 -33.728152)
		(end 426.11167 -33.632902)
		(width 0.10033)
		(layer "B.Cu")
		(net "BMC_M_DQS0_DN")
	)
	(segment
		(start 441.34532 -30.450028)
		(end 441.34532 -30.449774)
		(width 0.10033)
		(layer "B.Cu")
		(net "BMC_M_DQS0_DN")
	)
	(arc
		(start 436.476648 -29.308806)
		(mid 436.628378 -29.207423)
		(end 436.807356 -29.1719)
		(width 0.10033)
		(layer "B.Cu")
		(net "BMC_M_DQS0_DN")
	)
	(arc
		(start 440.30265 -31.078678)
		(mid 440.777945 -30.972119)
		(end 441.162186 -30.672786)
		(width 0.10033)
		(layer "B.Cu")
		(net "BMC_M_DQS0_DN")
	)
	(arc
		(start 427.833282 -33.580832)
		(mid 428.058192 -33.536077)
		(end 428.248826 -33.40862)
		(width 0.10033)
		(layer "B.Cu")
		(net "BMC_M_DQS0_DN")
	)
	(arc
		(start 439.157618 -29.720032)
		(mid 438.984942 -30.587364)
		(end 439.720228 -31.078678)
		(width 0.10033)
		(layer "B.Cu")
		(net "BMC_M_DQS0_DN")
	)
	(arc
		(start 434.798978 -30.6578)
		(mid 435.102499 -30.59735)
		(end 435.35981 -30.42539)
		(width 0.10033)
		(layer "B.Cu")
		(net "BMC_M_DQS0_DN")
	)
	(arc
		(start 430.801526 -30.85592)
		(mid 431.020949 -30.709243)
		(end 431.279808 -30.6578)
		(width 0.10033)
		(layer "B.Cu")
		(net "BMC_M_DQS0_DN")
	)
	(arc
		(start 439.87339 -28.142946)
		(mid 440.304174 -28.142946)
		(end 440.30392 -28.573476)
		(width 0.10033)
		(layer "B.Cu")
		(net "BMC_M_DQS0_DN")
	)
	(arc
		(start 426.11167 -33.632902)
		(mid 426.150348 -33.594788)
		(end 426.202856 -33.580832)
		(width 0.10033)
		(layer "B.Cu")
		(net "BMC_M_DQS0_DN")
	)
	(arc
		(start 441.34532 -30.449774)
		(mid 441.555421 -30.154243)
		(end 441.722256 -29.8323)
		(width 0.10033)
		(layer "B.Cu")
		(net "BMC_M_DQS0_DN")
	)
	(arc
		(start 438.44083 -29.1719)
		(mid 438.813612 -29.097767)
		(end 439.129678 -28.886658)
		(width 0.10033)
		(layer "B.Cu")
		(net "BMC_M_DQS0_DN")
	)
	(segment
		(start 437.32196 -26.232612)
		(end 437.320944 -26.232612)
		(width 0.10795)
		(layer "F.Cu")
		(net "BMC_M_DQ9")
	)
	(segment
		(start 437.320944 -26.232612)
		(end 436.921656 -26.6319)
		(width 0.10795)
		(layer "F.Cu")
		(net "BMC_M_DQ9")
	)
	(segment
		(start 422.29024 -32.134556)
		(end 421.89019 -31.734506)
		(width 0.1016)
		(layer "F.Cu")
		(net "BMC_M_DQ9")
	)
	(via
		(at 433.105052 -29.07538)
		(size 0.508)
		(drill 0.254)
		(layers "F.Cu" "B.Cu")
		(net "BMC_M_DQ9")
	)
	(via
		(at 421.89019 -31.734506)
		(size 0.4572)
		(drill 0.2032)
		(layers "F.Cu" "B.Cu")
		(net "BMC_M_DQ9")
	)
	(via
		(at 436.921656 -26.6319)
		(size 0.4572)
		(drill 0.2032)
		(layers "F.Cu" "B.Cu")
		(net "BMC_M_DQ9")
	)
	(segment
		(start 427.406054 -31.736792)
		(end 426.555408 -31.736792)
		(width 0.10795)
		(layer "B.Cu")
		(net "BMC_M_DQ9")
	)
	(segment
		(start 428.361094 -29.738574)
		(end 428.783496 -29.316172)
		(width 0.10795)
		(layer "B.Cu")
		(net "BMC_M_DQ9")
	)
	(segment
		(start 428.746666 -30.110684)
		(end 428.746666 -30.587188)
		(width 0.10795)
		(layer "B.Cu")
		(net "BMC_M_DQ9")
	)
	(segment
		(start 429.590708 -29.221684)
		(end 428.778416 -30.033976)
		(width 0.10795)
		(layer "B.Cu")
		(net "BMC_M_DQ9")
	)
	(segment
		(start 423.965878 -31.817056)
		(end 422.08958 -31.817056)
		(width 0.10795)
		(layer "B.Cu")
		(net "BMC_M_DQ9")
	)
	(segment
		(start 428.257462 -30.587188)
		(end 428.257462 -29.988764)
		(width 0.10795)
		(layer "B.Cu")
		(net "BMC_M_DQ9")
	)
	(segment
		(start 433.105306 -29.075634)
		(end 433.105052 -29.07538)
		(width 0.10795)
		(layer "B.Cu")
		(net "BMC_M_DQ9")
	)
	(segment
		(start 435.851554 -27.126692)
		(end 434.134768 -28.843478)
		(width 0.10795)
		(layer "B.Cu")
		(net "BMC_M_DQ9")
	)
	(segment
		(start 426.111924 -31.93034)
		(end 426.111416 -31.930848)
		(width 0.10795)
		(layer "B.Cu")
		(net "BMC_M_DQ9")
	)
	(segment
		(start 436.921656 -26.6319)
		(end 436.67934 -26.6319)
		(width 0.10795)
		(layer "B.Cu")
		(net "BMC_M_DQ9")
	)
	(segment
		(start 433.105052 -29.07538)
		(end 429.943768 -29.07538)
		(width 0.10795)
		(layer "B.Cu")
		(net "BMC_M_DQ9")
	)
	(segment
		(start 437.11495 -27.0383)
		(end 436.064914 -27.0383)
		(width 0.10795)
		(layer "B.Cu")
		(net "BMC_M_DQ9")
	)
	(segment
		(start 425.509944 -32.180022)
		(end 425.03979 -32.180022)
		(width 0.10795)
		(layer "B.Cu")
		(net "BMC_M_DQ9")
	)
	(segment
		(start 436.719218 -26.241756)
		(end 437.05653 -26.241756)
		(width 0.10795)
		(layer "B.Cu")
		(net "BMC_M_DQ9")
	)
	(segment
		(start 433.574444 -29.075634)
		(end 433.105306 -29.075634)
		(width 0.10795)
		(layer "B.Cu")
		(net "BMC_M_DQ9")
	)
	(segment
		(start 427.768258 -29.980382)
		(end 427.768258 -31.120842)
		(width 0.10795)
		(layer "B.Cu")
		(net "BMC_M_DQ9")
	)
	(segment
		(start 424.776646 -31.918402)
		(end 424.776646 -31.918148)
		(width 0.10795)
		(layer "B.Cu")
		(net "BMC_M_DQ9")
	)
	(segment
		(start 428.434754 -28.96743)
		(end 428.013114 -29.38907)
		(width 0.10795)
		(layer "B.Cu")
		(net "BMC_M_DQ9")
	)
	(segment
		(start 437.321452 -26.459434)
		(end 437.321452 -26.852626)
		(width 0.10795)
		(layer "B.Cu")
		(net "BMC_M_DQ9")
	)
	(segment
		(start 436.57139 -26.52395)
		(end 436.57139 -26.389584)
		(width 0.10795)
		(layer "B.Cu")
		(net "BMC_M_DQ9")
	)
	(arc
		(start 437.05653 -26.241756)
		(mid 437.159695 -26.256313)
		(end 437.254904 -26.298652)
		(width 0.10795)
		(layer "B.Cu")
		(net "BMC_M_DQ9")
	)
	(arc
		(start 424.776646 -31.918148)
		(mid 424.747442 -31.784088)
		(end 424.670474 -31.670498)
		(width 0.10795)
		(layer "B.Cu")
		(net "BMC_M_DQ9")
	)
	(arc
		(start 434.134768 -28.843478)
		(mid 433.877703 -29.015306)
		(end 433.574444 -29.075634)
		(width 0.10795)
		(layer "B.Cu")
		(net "BMC_M_DQ9")
	)
	(arc
		(start 437.271414 -26.97353)
		(mid 437.199628 -27.021496)
		(end 437.11495 -27.0383)
		(width 0.10795)
		(layer "B.Cu")
		(net "BMC_M_DQ9")
	)
	(arc
		(start 437.254904 -26.298652)
		(mid 437.304194 -26.372419)
		(end 437.321452 -26.459434)
		(width 0.10795)
		(layer "B.Cu")
		(net "BMC_M_DQ9")
	)
	(arc
		(start 436.67934 -26.6319)
		(mid 436.603008 -26.600282)
		(end 436.57139 -26.52395)
		(width 0.10795)
		(layer "B.Cu")
		(net "BMC_M_DQ9")
	)
	(arc
		(start 428.783496 -29.316172)
		(mid 428.783496 -28.967684)
		(end 428.434754 -28.96743)
		(width 0.10795)
		(layer "B.Cu")
		(net "BMC_M_DQ9")
	)
	(arc
		(start 424.670474 -31.670498)
		(mid 424.495124 -31.597977)
		(end 424.3197 -31.670498)
		(width 0.10795)
		(layer "B.Cu")
		(net "BMC_M_DQ9")
	)
	(arc
		(start 427.768258 -31.120842)
		(mid 427.707721 -31.42518)
		(end 427.53534 -31.683198)
		(width 0.10795)
		(layer "B.Cu")
		(net "BMC_M_DQ9")
	)
	(arc
		(start 426.555408 -31.736792)
		(mid 426.542444 -31.737047)
		(end 426.5295 -31.737808)
		(width 0.10795)
		(layer "B.Cu")
		(net "BMC_M_DQ9")
	)
	(arc
		(start 428.257462 -29.988764)
		(mid 428.284395 -29.853362)
		(end 428.361094 -29.738574)
		(width 0.10795)
		(layer "B.Cu")
		(net "BMC_M_DQ9")
	)
	(arc
		(start 424.3197 -31.670498)
		(mid 424.157365 -31.778967)
		(end 423.965878 -31.817056)
		(width 0.10795)
		(layer "B.Cu")
		(net "BMC_M_DQ9")
	)
	(arc
		(start 437.321452 -26.852626)
		(mid 437.30844 -26.918043)
		(end 437.271414 -26.97353)
		(width 0.10795)
		(layer "B.Cu")
		(net "BMC_M_DQ9")
	)
	(arc
		(start 436.064914 -27.0383)
		(mid 435.949439 -27.06127)
		(end 435.851554 -27.126692)
		(width 0.10795)
		(layer "B.Cu")
		(net "BMC_M_DQ9")
	)
	(arc
		(start 429.943768 -29.07538)
		(mid 429.75267 -29.113392)
		(end 429.590708 -29.221684)
		(width 0.10795)
		(layer "B.Cu")
		(net "BMC_M_DQ9")
	)
	(arc
		(start 422.08958 -31.817056)
		(mid 421.981686 -31.795595)
		(end 421.89019 -31.734506)
		(width 0.10795)
		(layer "B.Cu")
		(net "BMC_M_DQ9")
	)
	(arc
		(start 424.82516 -32.091122)
		(mid 424.788997 -32.008102)
		(end 424.776646 -31.918402)
		(width 0.10795)
		(layer "B.Cu")
		(net "BMC_M_DQ9")
	)
	(arc
		(start 426.5295 -31.737808)
		(mid 426.303525 -31.796805)
		(end 426.111924 -31.93034)
		(width 0.10795)
		(layer "B.Cu")
		(net "BMC_M_DQ9")
	)
	(arc
		(start 436.57139 -26.389584)
		(mid 436.614688 -26.285054)
		(end 436.719218 -26.241756)
		(width 0.10795)
		(layer "B.Cu")
		(net "BMC_M_DQ9")
	)
	(arc
		(start 426.111416 -31.930848)
		(mid 425.835458 -32.115237)
		(end 425.509944 -32.180022)
		(width 0.10795)
		(layer "B.Cu")
		(net "BMC_M_DQ9")
	)
	(arc
		(start 428.746666 -30.587188)
		(mid 428.502064 -30.83179)
		(end 428.257462 -30.587188)
		(width 0.10795)
		(layer "B.Cu")
		(net "BMC_M_DQ9")
	)
	(arc
		(start 428.013114 -29.38907)
		(mid 427.83184 -29.660366)
		(end 427.768258 -29.980382)
		(width 0.10795)
		(layer "B.Cu")
		(net "BMC_M_DQ9")
	)
	(arc
		(start 425.03979 -32.180022)
		(mid 424.923634 -32.156917)
		(end 424.82516 -32.091122)
		(width 0.10795)
		(layer "B.Cu")
		(net "BMC_M_DQ9")
	)
	(arc
		(start 428.778416 -30.033976)
		(mid 428.7549 -30.06917)
		(end 428.746666 -30.110684)
		(width 0.10795)
		(layer "B.Cu")
		(net "BMC_M_DQ9")
	)
	(arc
		(start 427.53534 -31.683198)
		(mid 427.476023 -31.722832)
		(end 427.406054 -31.736792)
		(width 0.10795)
		(layer "B.Cu")
		(net "BMC_M_DQ9")
	)
	(segment
		(start 428.206662 -29.866844)
		(end 429.630332 -28.444444)
		(width 0.10795)
		(layer "F.Cu")
		(net "BMC_M_DQ8")
	)
	(segment
		(start 427.515274 -30.212792)
		(end 427.453552 -30.15107)
		(width 0.10795)
		(layer "F.Cu")
		(net "BMC_M_DQ8")
	)
	(segment
		(start 434.028342 -28.258516)
		(end 430.560226 -28.258516)
		(width 0.10795)
		(layer "F.Cu")
		(net "BMC_M_DQ8")
	)
	(segment
		(start 426.823378 -30.904688)
		(end 426.761656 -30.842966)
		(width 0.10795)
		(layer "F.Cu")
		(net "BMC_M_DQ8")
	)
	(segment
		(start 439.819796 -25.391364)
		(end 438.822592 -24.39416)
		(width 0.10795)
		(layer "F.Cu")
		(net "BMC_M_DQ8")
	)
	(segment
		(start 437.224932 -23.73249)
		(end 436.021226 -23.73249)
		(width 0.10795)
		(layer "F.Cu")
		(net "BMC_M_DQ8")
	)
	(segment
		(start 427.453552 -29.80563)
		(end 427.45406 -29.805122)
		(width 0.10795)
		(layer "F.Cu")
		(net "BMC_M_DQ8")
	)
	(segment
		(start 426.469302 -31.604204)
		(end 426.823378 -31.250128)
		(width 0.10795)
		(layer "F.Cu")
		(net "BMC_M_DQ8")
	)
	(segment
		(start 427.514766 -30.55874)
		(end 427.515274 -30.558232)
		(width 0.10795)
		(layer "F.Cu")
		(net "BMC_M_DQ8")
	)
	(segment
		(start 434.940202 -24.840692)
		(end 434.940202 -27.346656)
		(width 0.10795)
		(layer "F.Cu")
		(net "BMC_M_DQ8")
	)
	(segment
		(start 426.761656 -30.497526)
		(end 426.762164 -30.497018)
		(width 0.10795)
		(layer "F.Cu")
		(net "BMC_M_DQ8")
	)
	(segment
		(start 427.107604 -30.497018)
		(end 427.169326 -30.55874)
		(width 0.10795)
		(layer "F.Cu")
		(net "BMC_M_DQ8")
	)
	(segment
		(start 423.535348 -31.734252)
		(end 424.348656 -31.734252)
		(width 0.10795)
		(layer "F.Cu")
		(net "BMC_M_DQ8")
	)
	(segment
		(start 427.7995 -29.805122)
		(end 427.861222 -29.866844)
		(width 0.10795)
		(layer "F.Cu")
		(net "BMC_M_DQ8")
	)
	(segment
		(start 435.27726 -24.040592)
		(end 435.267608 -24.050244)
		(width 0.10795)
		(layer "F.Cu")
		(net "BMC_M_DQ8")
	)
	(segment
		(start 423.159428 -31.96717)
		(end 423.291254 -31.835344)
		(width 0.10795)
		(layer "F.Cu")
		(net "BMC_M_DQ8")
	)
	(segment
		(start 430.07915 -28.258516)
		(end 430.560226 -28.258516)
		(width 0.10795)
		(layer "F.Cu")
		(net "BMC_M_DQ8")
	)
	(segment
		(start 424.55592 -31.820104)
		(end 424.718988 -31.983172)
		(width 0.10795)
		(layer "F.Cu")
		(net "BMC_M_DQ8")
	)
	(segment
		(start 424.82262 -32.026098)
		(end 425.450762 -32.026098)
		(width 0.10795)
		(layer "F.Cu")
		(net "BMC_M_DQ8")
	)
	(segment
		(start 441.321952 -25.432512)
		(end 439.918856 -25.432512)
		(width 0.10795)
		(layer "F.Cu")
		(net "BMC_M_DQ8")
	)
	(via
		(at 430.560226 -28.258516)
		(size 0.508)
		(drill 0.254)
		(layers "F.Cu" "B.Cu")
		(net "BMC_M_DQ8")
	)
	(arc
		(start 427.861222 -29.866844)
		(mid 428.033942 -29.938387)
		(end 428.206662 -29.866844)
		(width 0.10795)
		(layer "F.Cu")
		(net "BMC_M_DQ8")
	)
	(arc
		(start 427.45406 -29.805122)
		(mid 427.62678 -29.733579)
		(end 427.7995 -29.805122)
		(width 0.10795)
		(layer "F.Cu")
		(net "BMC_M_DQ8")
	)
	(arc
		(start 426.823378 -31.250128)
		(mid 426.894921 -31.077408)
		(end 426.823378 -30.904688)
		(width 0.10795)
		(layer "F.Cu")
		(net "BMC_M_DQ8")
	)
	(arc
		(start 427.169326 -30.55874)
		(mid 427.342046 -30.630283)
		(end 427.514766 -30.55874)
		(width 0.10795)
		(layer "F.Cu")
		(net "BMC_M_DQ8")
	)
	(arc
		(start 434.940202 -27.346656)
		(mid 434.673124 -27.991438)
		(end 434.028342 -28.258516)
		(width 0.10795)
		(layer "F.Cu")
		(net "BMC_M_DQ8")
	)
	(arc
		(start 429.630332 -28.444444)
		(mid 429.836251 -28.306824)
		(end 430.07915 -28.258516)
		(width 0.10795)
		(layer "F.Cu")
		(net "BMC_M_DQ8")
	)
	(arc
		(start 423.090086 -32.134556)
		(mid 423.108091 -32.04395)
		(end 423.159428 -31.96717)
		(width 0.10795)
		(layer "F.Cu")
		(net "BMC_M_DQ8")
	)
	(arc
		(start 435.267608 -24.050244)
		(mid 435.02534 -24.412919)
		(end 434.940202 -24.840692)
		(width 0.10795)
		(layer "F.Cu")
		(net "BMC_M_DQ8")
	)
	(arc
		(start 424.348656 -31.734252)
		(mid 424.460827 -31.756564)
		(end 424.55592 -31.820104)
		(width 0.10795)
		(layer "F.Cu")
		(net "BMC_M_DQ8")
	)
	(arc
		(start 425.450762 -32.026098)
		(mid 426.001992 -31.916451)
		(end 426.469302 -31.604204)
		(width 0.10795)
		(layer "F.Cu")
		(net "BMC_M_DQ8")
	)
	(arc
		(start 423.291254 -31.835344)
		(mid 423.403245 -31.760514)
		(end 423.535348 -31.734252)
		(width 0.10795)
		(layer "F.Cu")
		(net "BMC_M_DQ8")
	)
	(arc
		(start 436.021226 -23.73249)
		(mid 435.618603 -23.812559)
		(end 435.27726 -24.040592)
		(width 0.10795)
		(layer "F.Cu")
		(net "BMC_M_DQ8")
	)
	(arc
		(start 427.453552 -30.15107)
		(mid 427.382009 -29.97835)
		(end 427.453552 -29.80563)
		(width 0.10795)
		(layer "F.Cu")
		(net "BMC_M_DQ8")
	)
	(arc
		(start 439.918856 -25.432512)
		(mid 439.865254 -25.421756)
		(end 439.819796 -25.391364)
		(width 0.10795)
		(layer "F.Cu")
		(net "BMC_M_DQ8")
	)
	(arc
		(start 438.822592 -24.39416)
		(mid 438.089565 -23.90443)
		(end 437.224932 -23.73249)
		(width 0.10795)
		(layer "F.Cu")
		(net "BMC_M_DQ8")
	)
	(arc
		(start 424.718988 -31.983172)
		(mid 424.766535 -32.014942)
		(end 424.82262 -32.026098)
		(width 0.10795)
		(layer "F.Cu")
		(net "BMC_M_DQ8")
	)
	(arc
		(start 426.762164 -30.497018)
		(mid 426.934884 -30.425475)
		(end 427.107604 -30.497018)
		(width 0.10795)
		(layer "F.Cu")
		(net "BMC_M_DQ8")
	)
	(arc
		(start 427.515274 -30.558232)
		(mid 427.586817 -30.385512)
		(end 427.515274 -30.212792)
		(width 0.10795)
		(layer "F.Cu")
		(net "BMC_M_DQ8")
	)
	(arc
		(start 426.761656 -30.842966)
		(mid 426.690113 -30.670246)
		(end 426.761656 -30.497526)
		(width 0.10795)
		(layer "F.Cu")
		(net "BMC_M_DQ8")
	)
	(segment
		(start 438.12206 -31.832296)
		(end 438.521856 -31.4325)
		(width 0.10795)
		(layer "F.Cu")
		(net "BMC_M_DQ7")
	)
	(segment
		(start 420.69004 -32.934656)
		(end 421.09009 -33.334706)
		(width 0.1016)
		(layer "F.Cu")
		(net "BMC_M_DQ7")
	)
	(segment
		(start 438.12206 -31.83255)
		(end 438.12206 -31.832296)
		(width 0.10795)
		(layer "F.Cu")
		(net "BMC_M_DQ7")
	)
	(via
		(at 438.521856 -31.4325)
		(size 0.4572)
		(drill 0.2032)
		(layers "F.Cu" "B.Cu")
		(net "BMC_M_DQ7")
	)
	(via
		(at 421.09009 -33.334706)
		(size 0.508)
		(drill 0.254)
		(layers "F.Cu" "B.Cu")
		(net "BMC_M_DQ7")
	)
	(segment
		(start 438.77484 -31.642304)
		(end 438.623202 -31.642304)
		(width 0.089408)
		(layer "In2.Cu")
		(net "BMC_M_DQ7")
	)
	(segment
		(start 430.721516 -31.48203)
		(end 430.78146 -31.422086)
		(width 0.089408)
		(layer "In2.Cu")
		(net "BMC_M_DQ7")
	)
	(segment
		(start 438.521856 -31.540958)
		(end 438.521856 -31.4325)
		(width 0.089408)
		(layer "In2.Cu")
		(net "BMC_M_DQ7")
	)
	(segment
		(start 429.005238 -33.947608)
		(end 428.798482 -33.740598)
		(width 0.089408)
		(layer "In2.Cu")
		(net "BMC_M_DQ7")
	)
	(segment
		(start 427.352714 -34.850832)
		(end 427.465998 -34.737548)
		(width 0.089408)
		(layer "In2.Cu")
		(net "BMC_M_DQ7")
	)
	(segment
		(start 438.903364 -31.298388)
		(end 438.903364 -31.51378)
		(width 0.089408)
		(layer "In2.Cu")
		(net "BMC_M_DQ7")
	)
	(segment
		(start 429.806608 -32.729424)
		(end 429.810672 -32.733488)
		(width 0.089408)
		(layer "In2.Cu")
		(net "BMC_M_DQ7")
	)
	(segment
		(start 428.299118 -34.572956)
		(end 428.130462 -34.404046)
		(width 0.089408)
		(layer "In2.Cu")
		(net "BMC_M_DQ7")
	)
	(segment
		(start 431.001932 -31.32328)
		(end 436.180484 -31.32328)
		(width 0.089408)
		(layer "In2.Cu")
		(net "BMC_M_DQ7")
	)
	(segment
		(start 430.833784 -31.382716)
		(end 430.88814 -31.352744)
		(width 0.089408)
		(layer "In2.Cu")
		(net "BMC_M_DQ7")
	)
	(segment
		(start 428.46371 -34.07156)
		(end 428.67199 -34.280348)
		(width 0.089408)
		(layer "In2.Cu")
		(net "BMC_M_DQ7")
	)
	(segment
		(start 421.1701 -33.528)
		(end 421.685212 -34.043112)
		(width 0.089408)
		(layer "In2.Cu")
		(net "BMC_M_DQ7")
	)
	(segment
		(start 427.798738 -34.738056)
		(end 427.96587 -34.905442)
		(width 0.089408)
		(layer "In2.Cu")
		(net "BMC_M_DQ7")
	)
	(segment
		(start 426.853604 -34.996374)
		(end 427.001432 -34.996374)
		(width 0.089408)
		(layer "In2.Cu")
		(net "BMC_M_DQ7")
	)
	(segment
		(start 424.971718 -35.143186)
		(end 426.49902 -35.143186)
		(width 0.089408)
		(layer "In2.Cu")
		(net "BMC_M_DQ7")
	)
	(segment
		(start 430.143158 -32.401002)
		(end 430.139348 -32.396938)
		(width 0.089408)
		(layer "In2.Cu")
		(net "BMC_M_DQ7")
	)
	(segment
		(start 424.322494 -34.598864)
		(end 424.792648 -35.069018)
		(width 0.089408)
		(layer "In2.Cu")
		(net "BMC_M_DQ7")
	)
	(segment
		(start 422.182036 -34.248852)
		(end 423.47769 -34.248852)
		(width 0.089408)
		(layer "In2.Cu")
		(net "BMC_M_DQ7")
	)
	(segment
		(start 428.79899 -33.407858)
		(end 429.50511 -32.703262)
		(width 0.089408)
		(layer "In2.Cu")
		(net "BMC_M_DQ7")
	)
	(segment
		(start 436.836566 -31.0515)
		(end 438.589166 -31.0515)
		(width 0.089408)
		(layer "In2.Cu")
		(net "BMC_M_DQ7")
	)
	(segment
		(start 430.804828 -31.731204)
		(end 430.72177 -31.648146)
		(width 0.089408)
		(layer "In2.Cu")
		(net "BMC_M_DQ7")
	)
	(arc
		(start 427.465998 -34.737548)
		(mid 427.632473 -34.668889)
		(end 427.798738 -34.738056)
		(width 0.089408)
		(layer "In2.Cu")
		(net "BMC_M_DQ7")
	)
	(arc
		(start 429.50511 -32.703262)
		(mid 429.660611 -32.661504)
		(end 429.806608 -32.729424)
		(width 0.089408)
		(layer "In2.Cu")
		(net "BMC_M_DQ7")
	)
	(arc
		(start 421.09009 -33.334706)
		(mid 421.110879 -33.439309)
		(end 421.1701 -33.528)
		(width 0.089408)
		(layer "In2.Cu")
		(net "BMC_M_DQ7")
	)
	(arc
		(start 426.5295 -35.1409)
		(mid 426.59362 -35.120777)
		(end 426.648118 -35.081464)
		(width 0.089408)
		(layer "In2.Cu")
		(net "BMC_M_DQ7")
	)
	(arc
		(start 424.792648 -35.069018)
		(mid 424.874806 -35.123914)
		(end 424.971718 -35.143186)
		(width 0.089408)
		(layer "In2.Cu")
		(net "BMC_M_DQ7")
	)
	(arc
		(start 436.180484 -31.32328)
		(mid 436.389565 -31.281691)
		(end 436.566818 -31.16326)
		(width 0.089408)
		(layer "In2.Cu")
		(net "BMC_M_DQ7")
	)
	(arc
		(start 438.903364 -31.51378)
		(mid 438.86572 -31.60466)
		(end 438.77484 -31.642304)
		(width 0.089408)
		(layer "In2.Cu")
		(net "BMC_M_DQ7")
	)
	(arc
		(start 429.810672 -32.733488)
		(mid 430.143285 -32.733615)
		(end 430.143158 -32.401002)
		(width 0.089408)
		(layer "In2.Cu")
		(net "BMC_M_DQ7")
	)
	(arc
		(start 430.139348 -32.396938)
		(mid 430.139285 -32.064261)
		(end 430.472088 -32.063944)
		(width 0.089408)
		(layer "In2.Cu")
		(net "BMC_M_DQ7")
	)
	(arc
		(start 427.001432 -34.996374)
		(mid 427.191558 -34.958556)
		(end 427.352714 -34.850832)
		(width 0.089408)
		(layer "In2.Cu")
		(net "BMC_M_DQ7")
	)
	(arc
		(start 426.648118 -35.081464)
		(mid 426.742396 -35.01847)
		(end 426.853604 -34.996374)
		(width 0.089408)
		(layer "In2.Cu")
		(net "BMC_M_DQ7")
	)
	(arc
		(start 438.589166 -31.0515)
		(mid 438.727581 -31.079032)
		(end 438.844944 -31.157418)
		(width 0.089408)
		(layer "In2.Cu")
		(net "BMC_M_DQ7")
	)
	(arc
		(start 426.49902 -35.143186)
		(mid 426.514301 -35.142595)
		(end 426.5295 -35.1409)
		(width 0.089408)
		(layer "In2.Cu")
		(net "BMC_M_DQ7")
	)
	(arc
		(start 438.623202 -31.642304)
		(mid 438.55154 -31.61262)
		(end 438.521856 -31.540958)
		(width 0.089408)
		(layer "In2.Cu")
		(net "BMC_M_DQ7")
	)
	(arc
		(start 428.798482 -33.740598)
		(mid 428.729823 -33.574123)
		(end 428.79899 -33.407858)
		(width 0.089408)
		(layer "In2.Cu")
		(net "BMC_M_DQ7")
	)
	(arc
		(start 428.67199 -34.280348)
		(mid 429.004984 -34.280602)
		(end 429.005238 -33.947608)
		(width 0.089408)
		(layer "In2.Cu")
		(net "BMC_M_DQ7")
	)
	(arc
		(start 421.685212 -34.043112)
		(mid 421.913171 -34.195366)
		(end 422.182036 -34.248852)
		(width 0.089408)
		(layer "In2.Cu")
		(net "BMC_M_DQ7")
	)
	(arc
		(start 428.130462 -34.404046)
		(mid 428.130906 -34.071369)
		(end 428.46371 -34.07156)
		(width 0.089408)
		(layer "In2.Cu")
		(net "BMC_M_DQ7")
	)
	(arc
		(start 436.566818 -31.16326)
		(mid 436.690579 -31.080565)
		(end 436.836566 -31.0515)
		(width 0.089408)
		(layer "In2.Cu")
		(net "BMC_M_DQ7")
	)
	(arc
		(start 430.88814 -31.352744)
		(mid 430.943164 -31.330774)
		(end 431.001932 -31.32328)
		(width 0.089408)
		(layer "In2.Cu")
		(net "BMC_M_DQ7")
	)
	(arc
		(start 423.47769 -34.248852)
		(mid 423.934912 -34.339817)
		(end 424.322494 -34.598864)
		(width 0.089408)
		(layer "In2.Cu")
		(net "BMC_M_DQ7")
	)
	(arc
		(start 427.96587 -34.905442)
		(mid 428.298674 -34.905887)
		(end 428.299118 -34.572956)
		(width 0.089408)
		(layer "In2.Cu")
		(net "BMC_M_DQ7")
	)
	(arc
		(start 430.78146 -31.422086)
		(mid 430.806247 -31.400574)
		(end 430.833784 -31.382716)
		(width 0.089408)
		(layer "In2.Cu")
		(net "BMC_M_DQ7")
	)
	(arc
		(start 430.72177 -31.648146)
		(mid 430.687187 -31.565104)
		(end 430.721516 -31.48203)
		(width 0.089408)
		(layer "In2.Cu")
		(net "BMC_M_DQ7")
	)
	(arc
		(start 430.472088 -32.063944)
		(mid 430.804828 -32.063944)
		(end 430.804828 -31.731204)
		(width 0.089408)
		(layer "In2.Cu")
		(net "BMC_M_DQ7")
	)
	(arc
		(start 438.844944 -31.157418)
		(mid 438.88816 -31.222096)
		(end 438.903364 -31.298388)
		(width 0.089408)
		(layer "In2.Cu")
		(net "BMC_M_DQ7")
	)
	(segment
		(start 421.49014 -32.934656)
		(end 421.89019 -33.334706)
		(width 0.1016)
		(layer "F.Cu")
		(net "BMC_M_DQ6")
	)
	(segment
		(start 441.321952 -31.83255)
		(end 440.921648 -31.4325)
		(width 0.10795)
		(layer "F.Cu")
		(net "BMC_M_DQ6")
	)
	(via
		(at 421.89019 -33.334706)
		(size 0.4572)
		(drill 0.2032)
		(layers "F.Cu" "B.Cu")
		(net "BMC_M_DQ6")
	)
	(via
		(at 440.921648 -31.4325)
		(size 0.4572)
		(drill 0.2032)
		(layers "F.Cu" "B.Cu")
		(net "BMC_M_DQ6")
	)
	(segment
		(start 438.47004 -30.2387)
		(end 436.707534 -30.2387)
		(width 0.089408)
		(layer "In2.Cu")
		(net "BMC_M_DQ6")
	)
	(segment
		(start 426.864018 -34.257488)
		(end 426.732954 -34.388552)
		(width 0.089408)
		(layer "In2.Cu")
		(net "BMC_M_DQ6")
	)
	(segment
		(start 425.9072 -34.750502)
		(end 425.103036 -34.750502)
		(width 0.089408)
		(layer "In2.Cu")
		(net "BMC_M_DQ6")
	)
	(segment
		(start 434.645054 -30.45714)
		(end 434.521102 -30.45714)
		(width 0.089408)
		(layer "In2.Cu")
		(net "BMC_M_DQ6")
	)
	(segment
		(start 432.466242 -30.627574)
		(end 432.466242 -30.630368)
		(width 0.089408)
		(layer "In2.Cu")
		(net "BMC_M_DQ6")
	)
	(segment
		(start 430.779936 -30.732984)
		(end 427.627542 -33.885378)
		(width 0.089408)
		(layer "In2.Cu")
		(net "BMC_M_DQ6")
	)
	(segment
		(start 435.28869 -30.630368)
		(end 435.28869 -30.630622)
		(width 0.089408)
		(layer "In2.Cu")
		(net "BMC_M_DQ6")
	)
	(segment
		(start 435.11851 -30.800802)
		(end 434.988716 -30.800802)
		(width 0.089408)
		(layer "In2.Cu")
		(net "BMC_M_DQ6")
	)
	(segment
		(start 424.900344 -34.666428)
		(end 424.614086 -34.38017)
		(width 0.089408)
		(layer "In2.Cu")
		(net "BMC_M_DQ6")
	)
	(segment
		(start 441.1472 -31.530036)
		(end 441.1472 -31.66872)
		(width 0.089408)
		(layer "In2.Cu")
		(net "BMC_M_DQ6")
	)
	(segment
		(start 433.642516 -30.395418)
		(end 433.642008 -30.395418)
		(width 0.089408)
		(layer "In2.Cu")
		(net "BMC_M_DQ6")
	)
	(segment
		(start 432.262534 -30.834076)
		(end 432.199542 -30.834076)
		(width 0.089408)
		(layer "In2.Cu")
		(net "BMC_M_DQ6")
	)
	(segment
		(start 423.683938 -33.994852)
		(end 422.804844 -33.994852)
		(width 0.089408)
		(layer "In2.Cu")
		(net "BMC_M_DQ6")
	)
	(segment
		(start 439.620152 -31.020512)
		(end 439.263282 -30.663896)
		(width 0.089408)
		(layer "In2.Cu")
		(net "BMC_M_DQ6")
	)
	(segment
		(start 436.18023 -30.45714)
		(end 435.461918 -30.45714)
		(width 0.089408)
		(layer "In2.Cu")
		(net "BMC_M_DQ6")
	)
	(segment
		(start 440.921648 -31.4325)
		(end 441.022994 -31.4325)
		(width 0.089408)
		(layer "In2.Cu")
		(net "BMC_M_DQ6")
	)
	(segment
		(start 431.822606 -30.45714)
		(end 431.445924 -30.45714)
		(width 0.089408)
		(layer "In2.Cu")
		(net "BMC_M_DQ6")
	)
	(segment
		(start 432.93665 -30.630368)
		(end 432.93665 -30.627574)
		(width 0.089408)
		(layer "In2.Cu")
		(net "BMC_M_DQ6")
	)
	(segment
		(start 439.263282 -30.663896)
		(end 438.977024 -30.377638)
		(width 0.089408)
		(layer "In2.Cu")
		(net "BMC_M_DQ6")
	)
	(segment
		(start 441.008516 -31.807404)
		(end 440.610244 -31.807404)
		(width 0.089408)
		(layer "In2.Cu")
		(net "BMC_M_DQ6")
	)
	(segment
		(start 434.169058 -30.809184)
		(end 434.056028 -30.809184)
		(width 0.089408)
		(layer "In2.Cu")
		(net "BMC_M_DQ6")
	)
	(segment
		(start 439.666888 -31.066994)
		(end 439.620152 -31.020512)
		(width 0.089408)
		(layer "In2.Cu")
		(net "BMC_M_DQ6")
	)
	(segment
		(start 433.206652 -30.830774)
		(end 433.137056 -30.830774)
		(width 0.089408)
		(layer "In2.Cu")
		(net "BMC_M_DQ6")
	)
	(segment
		(start 422.371266 -33.815274)
		(end 422.370758 -33.815274)
		(width 0.089408)
		(layer "In2.Cu")
		(net "BMC_M_DQ6")
	)
	(segment
		(start 440.263788 -31.663894)
		(end 439.666888 -31.066994)
		(width 0.089408)
		(layer "In2.Cu")
		(net "BMC_M_DQ6")
	)
	(segment
		(start 433.877466 -30.630622)
		(end 433.877466 -30.630368)
		(width 0.089408)
		(layer "In2.Cu")
		(net "BMC_M_DQ6")
	)
	(segment
		(start 422.370758 -33.815274)
		(end 421.89019 -33.334706)
		(width 0.089408)
		(layer "In2.Cu")
		(net "BMC_M_DQ6")
	)
	(arc
		(start 432.199542 -30.834076)
		(mid 432.055499 -30.774411)
		(end 431.995834 -30.630368)
		(width 0.089408)
		(layer "In2.Cu")
		(net "BMC_M_DQ6")
	)
	(arc
		(start 425.103036 -34.750502)
		(mid 424.993349 -34.72859)
		(end 424.900344 -34.666428)
		(width 0.089408)
		(layer "In2.Cu")
		(net "BMC_M_DQ6")
	)
	(arc
		(start 436.442612 -30.348428)
		(mid 436.32223 -30.428865)
		(end 436.18023 -30.45714)
		(width 0.089408)
		(layer "In2.Cu")
		(net "BMC_M_DQ6")
	)
	(arc
		(start 432.466242 -30.630368)
		(mid 432.406577 -30.774411)
		(end 432.262534 -30.834076)
		(width 0.089408)
		(layer "In2.Cu")
		(net "BMC_M_DQ6")
	)
	(arc
		(start 435.28869 -30.630622)
		(mid 435.238845 -30.750957)
		(end 435.11851 -30.800802)
		(width 0.089408)
		(layer "In2.Cu")
		(net "BMC_M_DQ6")
	)
	(arc
		(start 438.977024 -30.377638)
		(mid 438.838579 -30.285132)
		(end 438.675272 -30.25267)
		(width 0.089408)
		(layer "In2.Cu")
		(net "BMC_M_DQ6")
	)
	(arc
		(start 434.988716 -30.800802)
		(mid 434.868201 -30.750883)
		(end 434.818282 -30.630368)
		(width 0.089408)
		(layer "In2.Cu")
		(net "BMC_M_DQ6")
	)
	(arc
		(start 434.347874 -30.630368)
		(mid 434.2955 -30.75681)
		(end 434.169058 -30.809184)
		(width 0.089408)
		(layer "In2.Cu")
		(net "BMC_M_DQ6")
	)
	(arc
		(start 433.137056 -30.830774)
		(mid 432.995348 -30.772076)
		(end 432.93665 -30.630368)
		(width 0.089408)
		(layer "In2.Cu")
		(net "BMC_M_DQ6")
	)
	(arc
		(start 431.445924 -30.45714)
		(mid 431.0855 -30.528833)
		(end 430.779936 -30.732984)
		(width 0.089408)
		(layer "In2.Cu")
		(net "BMC_M_DQ6")
	)
	(arc
		(start 433.407058 -30.630368)
		(mid 433.34836 -30.772076)
		(end 433.206652 -30.830774)
		(width 0.089408)
		(layer "In2.Cu")
		(net "BMC_M_DQ6")
	)
	(arc
		(start 435.461918 -30.45714)
		(mid 435.339427 -30.507877)
		(end 435.28869 -30.630368)
		(width 0.089408)
		(layer "In2.Cu")
		(net "BMC_M_DQ6")
	)
	(arc
		(start 433.877466 -30.630368)
		(mid 433.808651 -30.464233)
		(end 433.642516 -30.395418)
		(width 0.089408)
		(layer "In2.Cu")
		(net "BMC_M_DQ6")
	)
	(arc
		(start 431.995834 -30.630368)
		(mid 431.945097 -30.507877)
		(end 431.822606 -30.45714)
		(width 0.089408)
		(layer "In2.Cu")
		(net "BMC_M_DQ6")
	)
	(arc
		(start 441.022994 -31.4325)
		(mid 441.080566 -31.443916)
		(end 441.12942 -31.476442)
		(width 0.089408)
		(layer "In2.Cu")
		(net "BMC_M_DQ6")
	)
	(arc
		(start 427.217332 -34.055304)
		(mid 427.02717 -34.132803)
		(end 426.864018 -34.257488)
		(width 0.089408)
		(layer "In2.Cu")
		(net "BMC_M_DQ6")
	)
	(arc
		(start 427.627542 -33.885378)
		(mid 427.439336 -34.011133)
		(end 427.217332 -34.055304)
		(width 0.089408)
		(layer "In2.Cu")
		(net "BMC_M_DQ6")
	)
	(arc
		(start 436.707534 -30.2387)
		(mid 436.564162 -30.267219)
		(end 436.442612 -30.348428)
		(width 0.089408)
		(layer "In2.Cu")
		(net "BMC_M_DQ6")
	)
	(arc
		(start 433.642008 -30.395418)
		(mid 433.475873 -30.464233)
		(end 433.407058 -30.630368)
		(width 0.089408)
		(layer "In2.Cu")
		(net "BMC_M_DQ6")
	)
	(arc
		(start 438.675272 -30.25267)
		(mid 438.572893 -30.242198)
		(end 438.47004 -30.2387)
		(width 0.089408)
		(layer "In2.Cu")
		(net "BMC_M_DQ6")
	)
	(arc
		(start 434.521102 -30.45714)
		(mid 434.398611 -30.507877)
		(end 434.347874 -30.630368)
		(width 0.089408)
		(layer "In2.Cu")
		(net "BMC_M_DQ6")
	)
	(arc
		(start 432.93665 -30.627574)
		(mid 432.701446 -30.39237)
		(end 432.466242 -30.627574)
		(width 0.089408)
		(layer "In2.Cu")
		(net "BMC_M_DQ6")
	)
	(arc
		(start 434.818282 -30.630368)
		(mid 434.767545 -30.507877)
		(end 434.645054 -30.45714)
		(width 0.089408)
		(layer "In2.Cu")
		(net "BMC_M_DQ6")
	)
	(arc
		(start 440.610244 -31.807404)
		(mid 440.422742 -31.770108)
		(end 440.263788 -31.663894)
		(width 0.089408)
		(layer "In2.Cu")
		(net "BMC_M_DQ6")
	)
	(arc
		(start 441.1472 -31.66872)
		(mid 441.10658 -31.766784)
		(end 441.008516 -31.807404)
		(width 0.089408)
		(layer "In2.Cu")
		(net "BMC_M_DQ6")
	)
	(arc
		(start 441.12942 -31.476442)
		(mid 441.142639 -31.501803)
		(end 441.1472 -31.530036)
		(width 0.089408)
		(layer "In2.Cu")
		(net "BMC_M_DQ6")
	)
	(arc
		(start 422.804844 -33.994852)
		(mid 422.570199 -33.948178)
		(end 422.371266 -33.815274)
		(width 0.089408)
		(layer "In2.Cu")
		(net "BMC_M_DQ6")
	)
	(arc
		(start 434.056028 -30.809184)
		(mid 433.929766 -30.756884)
		(end 433.877466 -30.630622)
		(width 0.089408)
		(layer "In2.Cu")
		(net "BMC_M_DQ6")
	)
	(arc
		(start 426.732954 -34.388552)
		(mid 426.357997 -34.656037)
		(end 425.9072 -34.750502)
		(width 0.089408)
		(layer "In2.Cu")
		(net "BMC_M_DQ6")
	)
	(arc
		(start 424.614086 -34.38017)
		(mid 424.18733 -34.095021)
		(end 423.683938 -33.994852)
		(width 0.089408)
		(layer "In2.Cu")
		(net "BMC_M_DQ6")
	)
	(segment
		(start 437.32196 -31.03245)
		(end 437.721756 -30.632654)
		(width 0.10795)
		(layer "F.Cu")
		(net "BMC_M_DQ5")
	)
	(segment
		(start 422.29024 -32.934656)
		(end 422.69029 -32.534606)
		(width 0.089408)
		(layer "F.Cu")
		(net "BMC_M_DQ5")
	)
	(via
		(at 422.69029 -32.534606)
		(size 0.4572)
		(drill 0.2032)
		(layers "F.Cu" "B.Cu")
		(net "BMC_M_DQ5")
	)
	(via
		(at 437.721756 -30.632654)
		(size 0.4572)
		(drill 0.2032)
		(layers "F.Cu" "B.Cu")
		(net "BMC_M_DQ5")
	)
	(via
		(at 427.263814 -34.603182)
		(size 0.508)
		(drill 0.254)
		(layers "F.Cu" "B.Cu")
		(net "BMC_M_DQ5")
	)
	(segment
		(start 426.355256 -34.16427)
		(end 426.303694 -34.16427)
		(width 0.10795)
		(layer "B.Cu")
		(net "BMC_M_DQ5")
	)
	(segment
		(start 435.366414 -31.296864)
		(end 433.3494 -31.296864)
		(width 0.10795)
		(layer "B.Cu")
		(net "BMC_M_DQ5")
	)
	(segment
		(start 431.932588 -31.735776)
		(end 431.88255 -31.735776)
		(width 0.10795)
		(layer "B.Cu")
		(net "BMC_M_DQ5")
	)
	(segment
		(start 437.859932 -30.2387)
		(end 436.6641 -30.2387)
		(width 0.10795)
		(layer "B.Cu")
		(net "BMC_M_DQ5")
	)
	(segment
		(start 428.780448 -34.37128)
		(end 428.64659 -34.237422)
		(width 0.10795)
		(layer "B.Cu")
		(net "BMC_M_DQ5")
	)
	(segment
		(start 423.72788 -32.928052)
		(end 422.834054 -32.928052)
		(width 0.10795)
		(layer "B.Cu")
		(net "BMC_M_DQ5")
	)
	(segment
		(start 431.443638 -31.296864)
		(end 431.315114 -31.296864)
		(width 0.10795)
		(layer "B.Cu")
		(net "BMC_M_DQ5")
	)
	(segment
		(start 429.126396 -34.370772)
		(end 429.125888 -34.37128)
		(width 0.10795)
		(layer "B.Cu")
		(net "BMC_M_DQ5")
	)
	(segment
		(start 427.672246 -34.603182)
		(end 427.263814 -34.603182)
		(width 0.10795)
		(layer "B.Cu")
		(net "BMC_M_DQ5")
	)
	(segment
		(start 431.052732 -31.482792)
		(end 431.053494 -31.482538)
		(width 0.10795)
		(layer "B.Cu")
		(net "BMC_M_DQ5")
	)
	(segment
		(start 427.263814 -34.603182)
		(end 426.792644 -34.603182)
		(width 0.10795)
		(layer "B.Cu")
		(net "BMC_M_DQ5")
	)
	(segment
		(start 425.864782 -34.603182)
		(end 425.357544 -34.603182)
		(width 0.10795)
		(layer "B.Cu")
		(net "BMC_M_DQ5")
	)
	(segment
		(start 430.572164 -32.784796)
		(end 430.33569 -32.548322)
		(width 0.10795)
		(layer "B.Cu")
		(net "BMC_M_DQ5")
	)
	(segment
		(start 432.910488 -31.735776)
		(end 432.86045 -31.735776)
		(width 0.10795)
		(layer "B.Cu")
		(net "BMC_M_DQ5")
	)
	(segment
		(start 424.959272 -34.20491)
		(end 424.959272 -33.33242)
		(width 0.10795)
		(layer "B.Cu")
		(net "BMC_M_DQ5")
	)
	(segment
		(start 436.425594 -30.337506)
		(end 435.536848 -31.226252)
		(width 0.10795)
		(layer "B.Cu")
		(net "BMC_M_DQ5")
	)
	(segment
		(start 423.980864 -33.939988)
		(end 423.980864 -33.181036)
		(width 0.10795)
		(layer "B.Cu")
		(net "BMC_M_DQ5")
	)
	(segment
		(start 424.470068 -33.33242)
		(end 424.470068 -33.939988)
		(width 0.10795)
		(layer "B.Cu")
		(net "BMC_M_DQ5")
	)
	(segment
		(start 428.30115 -34.237422)
		(end 428.121318 -34.417254)
		(width 0.10795)
		(layer "B.Cu")
		(net "BMC_M_DQ5")
	)
	(segment
		(start 437.721756 -30.632654)
		(end 437.814974 -30.632654)
		(width 0.10795)
		(layer "B.Cu")
		(net "BMC_M_DQ5")
	)
	(segment
		(start 431.053494 -31.482538)
		(end 431.054256 -31.484316)
		(width 0.10795)
		(layer "B.Cu")
		(net "BMC_M_DQ5")
	)
	(segment
		(start 428.992538 -33.891474)
		(end 429.126396 -34.025332)
		(width 0.10795)
		(layer "B.Cu")
		(net "BMC_M_DQ5")
	)
	(segment
		(start 430.681638 -32.202374)
		(end 430.918112 -32.438848)
		(width 0.10795)
		(layer "B.Cu")
		(net "BMC_M_DQ5")
	)
	(segment
		(start 426.573188 -34.383726)
		(end 426.573188 -34.382202)
		(width 0.10795)
		(layer "B.Cu")
		(net "BMC_M_DQ5")
	)
	(segment
		(start 431.184558 -31.350966)
		(end 431.052732 -31.482792)
		(width 0.10795)
		(layer "B.Cu")
		(net "BMC_M_DQ5")
	)
	(segment
		(start 422.69029 -32.784288)
		(end 422.69029 -32.534606)
		(width 0.10795)
		(layer "B.Cu")
		(net "BMC_M_DQ5")
	)
	(segment
		(start 432.421538 -31.296864)
		(end 432.3715 -31.296864)
		(width 0.10795)
		(layer "B.Cu")
		(net "BMC_M_DQ5")
	)
	(segment
		(start 431.054256 -31.484316)
		(end 430.681638 -31.856934)
		(width 0.10795)
		(layer "B.Cu")
		(net "BMC_M_DQ5")
	)
	(segment
		(start 429.99025 -32.548322)
		(end 428.992538 -33.546034)
		(width 0.10795)
		(layer "B.Cu")
		(net "BMC_M_DQ5")
	)
	(segment
		(start 430.918112 -32.784288)
		(end 430.917604 -32.784796)
		(width 0.10795)
		(layer "B.Cu")
		(net "BMC_M_DQ5")
	)
	(arc
		(start 430.681638 -31.856934)
		(mid 430.610095 -32.029654)
		(end 430.681638 -32.202374)
		(width 0.10795)
		(layer "B.Cu")
		(net "BMC_M_DQ5")
	)
	(arc
		(start 432.152044 -31.51632)
		(mid 432.087767 -31.671499)
		(end 431.932588 -31.735776)
		(width 0.10795)
		(layer "B.Cu")
		(net "BMC_M_DQ5")
	)
	(arc
		(start 428.121318 -34.417254)
		(mid 427.915282 -34.554923)
		(end 427.672246 -34.603182)
		(width 0.10795)
		(layer "B.Cu")
		(net "BMC_M_DQ5")
	)
	(arc
		(start 437.961024 -30.28061)
		(mid 437.914643 -30.249619)
		(end 437.859932 -30.2387)
		(width 0.10795)
		(layer "B.Cu")
		(net "BMC_M_DQ5")
	)
	(arc
		(start 430.33569 -32.548322)
		(mid 430.16297 -32.476779)
		(end 429.99025 -32.548322)
		(width 0.10795)
		(layer "B.Cu")
		(net "BMC_M_DQ5")
	)
	(arc
		(start 430.917604 -32.784796)
		(mid 430.744884 -32.856339)
		(end 430.572164 -32.784796)
		(width 0.10795)
		(layer "B.Cu")
		(net "BMC_M_DQ5")
	)
	(arc
		(start 426.084238 -34.383726)
		(mid 426.019961 -34.538905)
		(end 425.864782 -34.603182)
		(width 0.10795)
		(layer "B.Cu")
		(net "BMC_M_DQ5")
	)
	(arc
		(start 425.357544 -34.603182)
		(mid 425.075923 -34.486531)
		(end 424.959272 -34.20491)
		(width 0.10795)
		(layer "B.Cu")
		(net "BMC_M_DQ5")
	)
	(arc
		(start 432.640994 -31.51632)
		(mid 432.576717 -31.361141)
		(end 432.421538 -31.296864)
		(width 0.10795)
		(layer "B.Cu")
		(net "BMC_M_DQ5")
	)
	(arc
		(start 431.88255 -31.735776)
		(mid 431.727371 -31.671499)
		(end 431.663094 -31.51632)
		(width 0.10795)
		(layer "B.Cu")
		(net "BMC_M_DQ5")
	)
	(arc
		(start 432.86045 -31.735776)
		(mid 432.705271 -31.671499)
		(end 432.640994 -31.51632)
		(width 0.10795)
		(layer "B.Cu")
		(net "BMC_M_DQ5")
	)
	(arc
		(start 431.315114 -31.296864)
		(mid 431.244448 -31.31092)
		(end 431.184558 -31.350966)
		(width 0.10795)
		(layer "B.Cu")
		(net "BMC_M_DQ5")
	)
	(arc
		(start 433.129944 -31.51632)
		(mid 433.065667 -31.671499)
		(end 432.910488 -31.735776)
		(width 0.10795)
		(layer "B.Cu")
		(net "BMC_M_DQ5")
	)
	(arc
		(start 432.3715 -31.296864)
		(mid 432.216321 -31.361141)
		(end 432.152044 -31.51632)
		(width 0.10795)
		(layer "B.Cu")
		(net "BMC_M_DQ5")
	)
	(arc
		(start 429.126396 -34.025332)
		(mid 429.197939 -34.198052)
		(end 429.126396 -34.370772)
		(width 0.10795)
		(layer "B.Cu")
		(net "BMC_M_DQ5")
	)
	(arc
		(start 426.573188 -34.382202)
		(mid 426.561977 -34.313246)
		(end 426.5295 -34.251392)
		(width 0.10795)
		(layer "B.Cu")
		(net "BMC_M_DQ5")
	)
	(arc
		(start 426.303694 -34.16427)
		(mid 426.148515 -34.228547)
		(end 426.084238 -34.383726)
		(width 0.10795)
		(layer "B.Cu")
		(net "BMC_M_DQ5")
	)
	(arc
		(start 429.125888 -34.37128)
		(mid 428.953168 -34.442823)
		(end 428.780448 -34.37128)
		(width 0.10795)
		(layer "B.Cu")
		(net "BMC_M_DQ5")
	)
	(arc
		(start 430.918112 -32.438848)
		(mid 430.989655 -32.611568)
		(end 430.918112 -32.784288)
		(width 0.10795)
		(layer "B.Cu")
		(net "BMC_M_DQ5")
	)
	(arc
		(start 428.64659 -34.237422)
		(mid 428.47387 -34.165879)
		(end 428.30115 -34.237422)
		(width 0.10795)
		(layer "B.Cu")
		(net "BMC_M_DQ5")
	)
	(arc
		(start 422.834054 -32.928052)
		(mid 422.732398 -32.885944)
		(end 422.69029 -32.784288)
		(width 0.10795)
		(layer "B.Cu")
		(net "BMC_M_DQ5")
	)
	(arc
		(start 437.814974 -30.632654)
		(mid 438.005728 -30.505451)
		(end 437.961024 -30.28061)
		(width 0.10795)
		(layer "B.Cu")
		(net "BMC_M_DQ5")
	)
	(arc
		(start 426.792644 -34.603182)
		(mid 426.637465 -34.538905)
		(end 426.573188 -34.383726)
		(width 0.10795)
		(layer "B.Cu")
		(net "BMC_M_DQ5")
	)
	(arc
		(start 424.470068 -33.939988)
		(mid 424.225466 -34.18459)
		(end 423.980864 -33.939988)
		(width 0.10795)
		(layer "B.Cu")
		(net "BMC_M_DQ5")
	)
	(arc
		(start 436.6641 -30.2387)
		(mid 436.535016 -30.264376)
		(end 436.425594 -30.337506)
		(width 0.10795)
		(layer "B.Cu")
		(net "BMC_M_DQ5")
	)
	(arc
		(start 424.959272 -33.33242)
		(mid 424.71467 -33.087818)
		(end 424.470068 -33.33242)
		(width 0.10795)
		(layer "B.Cu")
		(net "BMC_M_DQ5")
	)
	(arc
		(start 435.536848 -31.226252)
		(mid 435.458652 -31.278501)
		(end 435.366414 -31.296864)
		(width 0.10795)
		(layer "B.Cu")
		(net "BMC_M_DQ5")
	)
	(arc
		(start 423.980864 -33.181036)
		(mid 423.906767 -33.002149)
		(end 423.72788 -32.928052)
		(width 0.10795)
		(layer "B.Cu")
		(net "BMC_M_DQ5")
	)
	(arc
		(start 426.5295 -34.251392)
		(mid 426.45265 -34.1873)
		(end 426.355256 -34.16427)
		(width 0.10795)
		(layer "B.Cu")
		(net "BMC_M_DQ5")
	)
	(arc
		(start 433.3494 -31.296864)
		(mid 433.194221 -31.361141)
		(end 433.129944 -31.51632)
		(width 0.10795)
		(layer "B.Cu")
		(net "BMC_M_DQ5")
	)
	(arc
		(start 428.992538 -33.546034)
		(mid 428.920995 -33.718754)
		(end 428.992538 -33.891474)
		(width 0.10795)
		(layer "B.Cu")
		(net "BMC_M_DQ5")
	)
	(arc
		(start 431.663094 -31.51632)
		(mid 431.598817 -31.361141)
		(end 431.443638 -31.296864)
		(width 0.10795)
		(layer "B.Cu")
		(net "BMC_M_DQ5")
	)
	(segment
		(start 442.122052 -31.03245)
		(end 442.122306 -31.03245)
		(width 0.10795)
		(layer "F.Cu")
		(net "BMC_M_DQ4")
	)
	(segment
		(start 419.890194 -32.934656)
		(end 420.28999 -33.334706)
		(width 0.1016)
		(layer "F.Cu")
		(net "BMC_M_DQ4")
	)
	(segment
		(start 442.122306 -31.03245)
		(end 442.522356 -30.6324)
		(width 0.10795)
		(layer "F.Cu")
		(net "BMC_M_DQ4")
	)
	(via
		(at 442.522356 -30.6324)
		(size 0.4572)
		(drill 0.2032)
		(layers "F.Cu" "B.Cu")
		(net "BMC_M_DQ4")
	)
	(via
		(at 420.28999 -33.334706)
		(size 0.4572)
		(drill 0.2032)
		(layers "F.Cu" "B.Cu")
		(net "BMC_M_DQ4")
	)
	(segment
		(start 432.089306 -28.644088)
		(end 438.00522 -28.644088)
		(width 0.089408)
		(layer "In2.Cu")
		(net "BMC_M_DQ4")
	)
	(segment
		(start 420.44747 -33.135824)
		(end 420.946326 -32.636968)
		(width 0.089408)
		(layer "In2.Cu")
		(net "BMC_M_DQ4")
	)
	(segment
		(start 440.25947 -29.709364)
		(end 440.608212 -30.058106)
		(width 0.089408)
		(layer "In2.Cu")
		(net "BMC_M_DQ4")
	)
	(segment
		(start 441.04433 -30.2387)
		(end 441.571888 -30.2387)
		(width 0.089408)
		(layer "In2.Cu")
		(net "BMC_M_DQ4")
	)
	(segment
		(start 427.415706 -31.127192)
		(end 428.349918 -30.19298)
		(width 0.089408)
		(layer "In2.Cu")
		(net "BMC_M_DQ4")
	)
	(segment
		(start 422.205658 -32.115252)
		(end 424.80103 -32.115252)
		(width 0.089408)
		(layer "In2.Cu")
		(net "BMC_M_DQ4")
	)
	(segment
		(start 425.79798 -31.702248)
		(end 426.027596 -31.702248)
		(width 0.089408)
		(layer "In2.Cu")
		(net "BMC_M_DQ4")
	)
	(arc
		(start 441.571888 -30.2387)
		(mid 442.086279 -30.341019)
		(end 442.522356 -30.6324)
		(width 0.089408)
		(layer "In2.Cu")
		(net "BMC_M_DQ4")
	)
	(arc
		(start 438.00522 -28.644088)
		(mid 438.010306 -28.644217)
		(end 438.01538 -28.644596)
		(width 0.089408)
		(layer "In2.Cu")
		(net "BMC_M_DQ4")
	)
	(arc
		(start 425.520866 -31.817056)
		(mid 425.648007 -31.732103)
		(end 425.79798 -31.702248)
		(width 0.089408)
		(layer "In2.Cu")
		(net "BMC_M_DQ4")
	)
	(arc
		(start 426.027596 -31.702248)
		(mid 426.280658 -31.685836)
		(end 426.5295 -31.63697)
		(width 0.089408)
		(layer "In2.Cu")
		(net "BMC_M_DQ4")
	)
	(arc
		(start 424.80103 -32.115252)
		(mid 425.190614 -32.037759)
		(end 425.520866 -31.817056)
		(width 0.089408)
		(layer "In2.Cu")
		(net "BMC_M_DQ4")
	)
	(arc
		(start 440.608212 -30.058106)
		(mid 440.808319 -30.19175)
		(end 441.04433 -30.2387)
		(width 0.089408)
		(layer "In2.Cu")
		(net "BMC_M_DQ4")
	)
	(arc
		(start 426.5295 -31.63697)
		(mid 427.006386 -31.440804)
		(end 427.415706 -31.127192)
		(width 0.089408)
		(layer "In2.Cu")
		(net "BMC_M_DQ4")
	)
	(arc
		(start 438.01538 -28.644596)
		(mid 439.229442 -28.983036)
		(end 440.25947 -29.709364)
		(width 0.089408)
		(layer "In2.Cu")
		(net "BMC_M_DQ4")
	)
	(arc
		(start 428.349918 -30.19298)
		(mid 430.065564 -29.046622)
		(end 432.089306 -28.644088)
		(width 0.089408)
		(layer "In2.Cu")
		(net "BMC_M_DQ4")
	)
	(arc
		(start 420.946326 -32.636968)
		(mid 421.524098 -32.25085)
		(end 422.205658 -32.115252)
		(width 0.089408)
		(layer "In2.Cu")
		(net "BMC_M_DQ4")
	)
	(arc
		(start 420.28999 -33.334706)
		(mid 420.362985 -33.230717)
		(end 420.44747 -33.135824)
		(width 0.089408)
		(layer "In2.Cu")
		(net "BMC_M_DQ4")
	)
	(segment
		(start 438.521856 -30.632908)
		(end 438.521856 -30.6324)
		(width 0.10795)
		(layer "F.Cu")
		(net "BMC_M_DQ3")
	)
	(segment
		(start 423.090086 -33.734756)
		(end 423.490136 -33.334706)
		(width 0.1016)
		(layer "F.Cu")
		(net "BMC_M_DQ3")
	)
	(segment
		(start 438.12206 -31.03245)
		(end 438.122314 -31.03245)
		(width 0.10795)
		(layer "F.Cu")
		(net "BMC_M_DQ3")
	)
	(segment
		(start 438.122314 -31.03245)
		(end 438.521856 -30.632908)
		(width 0.10795)
		(layer "F.Cu")
		(net "BMC_M_DQ3")
	)
	(via
		(at 425.798488 -35.12185)
		(size 0.508)
		(drill 0.254)
		(layers "F.Cu" "B.Cu")
		(net "BMC_M_DQ3")
	)
	(via
		(at 423.490136 -33.334706)
		(size 0.4572)
		(drill 0.2032)
		(layers "F.Cu" "B.Cu")
		(net "BMC_M_DQ3")
	)
	(via
		(at 438.521856 -30.6324)
		(size 0.4572)
		(drill 0.2032)
		(layers "F.Cu" "B.Cu")
		(net "BMC_M_DQ3")
	)
	(segment
		(start 431.930302 -32.307022)
		(end 431.929794 -32.30753)
		(width 0.10795)
		(layer "B.Cu")
		(net "BMC_M_DQ3")
	)
	(segment
		(start 423.457624 -34.32048)
		(end 423.86377 -34.726626)
		(width 0.10795)
		(layer "B.Cu")
		(net "BMC_M_DQ3")
	)
	(segment
		(start 436.061358 -31.8516)
		(end 434.009292 -31.8516)
		(width 0.10795)
		(layer "B.Cu")
		(net "BMC_M_DQ3")
	)
	(segment
		(start 432.195224 -33.217612)
		(end 432.110896 -33.30194)
		(width 0.10795)
		(layer "B.Cu")
		(net "BMC_M_DQ3")
	)
	(segment
		(start 424.817794 -35.12185)
		(end 425.798488 -35.12185)
		(width 0.10795)
		(layer "B.Cu")
		(net "BMC_M_DQ3")
	)
	(segment
		(start 429.626776 -34.907728)
		(end 429.575976 -34.856928)
		(width 0.10795)
		(layer "B.Cu")
		(net "BMC_M_DQ3")
	)
	(segment
		(start 431.953416 -33.367218)
		(end 430.242726 -33.367218)
		(width 0.10795)
		(layer "B.Cu")
		(net "BMC_M_DQ3")
	)
	(segment
		(start 423.224452 -33.799526)
		(end 421.848788 -33.799526)
		(width 0.10795)
		(layer "B.Cu")
		(net "BMC_M_DQ3")
	)
	(segment
		(start 421.848788 -34.28873)
		(end 423.380916 -34.28873)
		(width 0.10795)
		(layer "B.Cu")
		(net "BMC_M_DQ3")
	)
	(segment
		(start 438.521856 -30.6324)
		(end 438.633108 -30.743398)
		(width 0.10795)
		(layer "B.Cu")
		(net "BMC_M_DQ3")
	)
	(segment
		(start 428.882302 -35.12185)
		(end 425.798488 -35.12185)
		(width 0.10795)
		(layer "B.Cu")
		(net "BMC_M_DQ3")
	)
	(segment
		(start 431.929794 -32.65297)
		(end 432.195224 -32.9184)
		(width 0.10795)
		(layer "B.Cu")
		(net "BMC_M_DQ3")
	)
	(segment
		(start 429.713644 -33.874456)
		(end 429.713644 -34.120328)
		(width 0.10795)
		(layer "B.Cu")
		(net "BMC_M_DQ3")
	)
	(segment
		(start 432.518058 -32.549338)
		(end 432.275742 -32.307022)
		(width 0.10795)
		(layer "B.Cu")
		(net "BMC_M_DQ3")
	)
	(segment
		(start 423.490136 -33.334706)
		(end 423.490136 -33.533842)
		(width 0.10795)
		(layer "B.Cu")
		(net "BMC_M_DQ3")
	)
	(segment
		(start 436.3593 -31.235904)
		(end 436.3593 -31.553658)
		(width 0.10795)
		(layer "B.Cu")
		(net "BMC_M_DQ3")
	)
	(segment
		(start 429.972724 -34.845752)
		(end 429.910748 -34.907728)
		(width 0.10795)
		(layer "B.Cu")
		(net "BMC_M_DQ3")
	)
	(segment
		(start 433.244498 -32.168338)
		(end 432.863498 -32.549338)
		(width 0.10795)
		(layer "B.Cu")
		(net "BMC_M_DQ3")
	)
	(segment
		(start 438.516014 -31.0261)
		(end 436.569104 -31.0261)
		(width 0.10795)
		(layer "B.Cu")
		(net "BMC_M_DQ3")
	)
	(segment
		(start 429.392588 -34.856928)
		(end 429.301148 -34.948368)
		(width 0.10795)
		(layer "B.Cu")
		(net "BMC_M_DQ3")
	)
	(segment
		(start 429.86579 -34.487612)
		(end 429.972724 -34.594546)
		(width 0.10795)
		(layer "B.Cu")
		(net "BMC_M_DQ3")
	)
	(arc
		(start 429.713644 -34.120328)
		(mid 429.753183 -34.319105)
		(end 429.86579 -34.487612)
		(width 0.10795)
		(layer "B.Cu")
		(net "BMC_M_DQ3")
	)
	(arc
		(start 423.86377 -34.726626)
		(mid 424.301466 -35.019148)
		(end 424.817794 -35.12185)
		(width 0.10795)
		(layer "B.Cu")
		(net "BMC_M_DQ3")
	)
	(arc
		(start 436.3593 -31.553658)
		(mid 436.272035 -31.764335)
		(end 436.061358 -31.8516)
		(width 0.10795)
		(layer "B.Cu")
		(net "BMC_M_DQ3")
	)
	(arc
		(start 429.301148 -34.948368)
		(mid 429.10898 -35.076771)
		(end 428.882302 -35.12185)
		(width 0.10795)
		(layer "B.Cu")
		(net "BMC_M_DQ3")
	)
	(arc
		(start 429.972724 -34.594546)
		(mid 430.024803 -34.720186)
		(end 429.972724 -34.845752)
		(width 0.10795)
		(layer "B.Cu")
		(net "BMC_M_DQ3")
	)
	(arc
		(start 438.633108 -30.743398)
		(mid 438.669005 -30.923863)
		(end 438.516014 -31.0261)
		(width 0.10795)
		(layer "B.Cu")
		(net "BMC_M_DQ3")
	)
	(arc
		(start 429.575976 -34.856928)
		(mid 429.484282 -34.818873)
		(end 429.392588 -34.856928)
		(width 0.10795)
		(layer "B.Cu")
		(net "BMC_M_DQ3")
	)
	(arc
		(start 432.863498 -32.549338)
		(mid 432.690778 -32.620881)
		(end 432.518058 -32.549338)
		(width 0.10795)
		(layer "B.Cu")
		(net "BMC_M_DQ3")
	)
	(arc
		(start 432.195224 -32.9184)
		(mid 432.257193 -33.068006)
		(end 432.195224 -33.217612)
		(width 0.10795)
		(layer "B.Cu")
		(net "BMC_M_DQ3")
	)
	(arc
		(start 430.242726 -33.367218)
		(mid 430.034326 -33.408671)
		(end 429.857662 -33.52673)
		(width 0.10795)
		(layer "B.Cu")
		(net "BMC_M_DQ3")
	)
	(arc
		(start 423.380916 -34.28873)
		(mid 423.422421 -34.296986)
		(end 423.457624 -34.32048)
		(width 0.10795)
		(layer "B.Cu")
		(net "BMC_M_DQ3")
	)
	(arc
		(start 432.275742 -32.307022)
		(mid 432.103022 -32.235479)
		(end 431.930302 -32.307022)
		(width 0.10795)
		(layer "B.Cu")
		(net "BMC_M_DQ3")
	)
	(arc
		(start 434.009292 -31.8516)
		(mid 433.595393 -31.933912)
		(end 433.244498 -32.168338)
		(width 0.10795)
		(layer "B.Cu")
		(net "BMC_M_DQ3")
	)
	(arc
		(start 432.110896 -33.30194)
		(mid 432.038644 -33.350218)
		(end 431.953416 -33.367218)
		(width 0.10795)
		(layer "B.Cu")
		(net "BMC_M_DQ3")
	)
	(arc
		(start 436.569104 -31.0261)
		(mid 436.42075 -31.08755)
		(end 436.3593 -31.235904)
		(width 0.10795)
		(layer "B.Cu")
		(net "BMC_M_DQ3")
	)
	(arc
		(start 429.910748 -34.907728)
		(mid 429.768762 -34.966466)
		(end 429.626776 -34.907728)
		(width 0.10795)
		(layer "B.Cu")
		(net "BMC_M_DQ3")
	)
	(arc
		(start 431.929794 -32.30753)
		(mid 431.858251 -32.48025)
		(end 431.929794 -32.65297)
		(width 0.10795)
		(layer "B.Cu")
		(net "BMC_M_DQ3")
	)
	(arc
		(start 429.857662 -33.52673)
		(mid 429.751062 -33.686268)
		(end 429.713644 -33.874456)
		(width 0.10795)
		(layer "B.Cu")
		(net "BMC_M_DQ3")
	)
	(arc
		(start 421.848788 -33.799526)
		(mid 421.604186 -34.044128)
		(end 421.848788 -34.28873)
		(width 0.10795)
		(layer "B.Cu")
		(net "BMC_M_DQ3")
	)
	(arc
		(start 423.490136 -33.533842)
		(mid 423.412319 -33.721709)
		(end 423.224452 -33.799526)
		(width 0.10795)
		(layer "B.Cu")
		(net "BMC_M_DQ3")
	)
	(segment
		(start 441.321952 -31.03245)
		(end 441.722256 -31.4325)
		(width 0.10795)
		(layer "F.Cu")
		(net "BMC_M_DQ2")
	)
	(segment
		(start 422.29024 -33.734756)
		(end 422.69029 -33.334706)
		(width 0.089408)
		(layer "F.Cu")
		(net "BMC_M_DQ2")
	)
	(via
		(at 422.69029 -33.334706)
		(size 0.508)
		(drill 0.254)
		(layers "F.Cu" "B.Cu")
		(net "BMC_M_DQ2")
	)
	(via
		(at 441.722256 -31.4325)
		(size 0.4572)
		(drill 0.2032)
		(layers "F.Cu" "B.Cu")
		(net "BMC_M_DQ2")
	)
	(segment
		(start 433.73675 -29.660088)
		(end 433.58435 -29.660088)
		(width 0.089408)
		(layer "In2.Cu")
		(net "BMC_M_DQ2")
	)
	(segment
		(start 436.64632 -29.52115)
		(end 436.527956 -29.639514)
		(width 0.089408)
		(layer "In2.Cu")
		(net "BMC_M_DQ2")
	)
	(segment
		(start 430.60239 -30.225746)
		(end 430.11979 -30.708092)
		(width 0.089408)
		(layer "In2.Cu")
		(net "BMC_M_DQ2")
	)
	(segment
		(start 433.266342 -29.978096)
		(end 433.113942 -29.978096)
		(width 0.089408)
		(layer "In2.Cu")
		(net "BMC_M_DQ2")
	)
	(segment
		(start 439.966354 -30.653736)
		(end 439.022236 -29.709618)
		(width 0.089408)
		(layer "In2.Cu")
		(net "BMC_M_DQ2")
	)
	(segment
		(start 435.839616 -29.977588)
		(end 434.05425 -29.977588)
		(width 0.089408)
		(layer "In2.Cu")
		(net "BMC_M_DQ2")
	)
	(segment
		(start 441.722256 -31.4325)
		(end 441.634372 -31.344616)
		(width 0.089408)
		(layer "In2.Cu")
		(net "BMC_M_DQ2")
	)
	(segment
		(start 438.337452 -29.4259)
		(end 436.87619 -29.4259)
		(width 0.089408)
		(layer "In2.Cu")
		(net "BMC_M_DQ2")
	)
	(segment
		(start 424.25874 -33.740852)
		(end 423.670222 -33.740852)
		(width 0.089408)
		(layer "In2.Cu")
		(net "BMC_M_DQ2")
	)
	(segment
		(start 426.603668 -33.843214)
		(end 426.5295 -33.917382)
		(width 0.089408)
		(layer "In2.Cu")
		(net "BMC_M_DQ2")
	)
	(segment
		(start 427.45787 -33.037272)
		(end 427.492668 -33.07207)
		(width 0.089408)
		(layer "In2.Cu")
		(net "BMC_M_DQ2")
	)
	(segment
		(start 425.057062 -34.333942)
		(end 424.609006 -33.885886)
		(width 0.089408)
		(layer "In2.Cu")
		(net "BMC_M_DQ2")
	)
	(segment
		(start 432.326034 -29.977588)
		(end 431.142902 -29.977588)
		(width 0.089408)
		(layer "In2.Cu")
		(net "BMC_M_DQ2")
	)
	(segment
		(start 427.492668 -33.335214)
		(end 427.36135 -33.466532)
		(width 0.089408)
		(layer "In2.Cu")
		(net "BMC_M_DQ2")
	)
	(segment
		(start 432.798728 -29.662882)
		(end 432.64074 -29.662882)
		(width 0.089408)
		(layer "In2.Cu")
		(net "BMC_M_DQ2")
	)
	(segment
		(start 426.5295 -33.917382)
		(end 426.181266 -34.266124)
		(width 0.089408)
		(layer "In2.Cu")
		(net "BMC_M_DQ2")
	)
	(arc
		(start 429.12157 -31.373572)
		(mid 428.78883 -31.373572)
		(end 428.78883 -31.706312)
		(width 0.089408)
		(layer "In2.Cu")
		(net "BMC_M_DQ2")
	)
	(arc
		(start 424.609006 -33.885886)
		(mid 424.448288 -33.778561)
		(end 424.25874 -33.740852)
		(width 0.089408)
		(layer "In2.Cu")
		(net "BMC_M_DQ2")
	)
	(arc
		(start 436.414164 -29.73959)
		(mid 436.150559 -29.915725)
		(end 435.839616 -29.977588)
		(width 0.089408)
		(layer "In2.Cu")
		(net "BMC_M_DQ2")
	)
	(arc
		(start 439.022236 -29.709618)
		(mid 438.708069 -29.499635)
		(end 438.337452 -29.4259)
		(width 0.089408)
		(layer "In2.Cu")
		(net "BMC_M_DQ2")
	)
	(arc
		(start 425.46143 -34.517584)
		(mid 425.242575 -34.462484)
		(end 425.057062 -34.333942)
		(width 0.089408)
		(layer "In2.Cu")
		(net "BMC_M_DQ2")
	)
	(arc
		(start 426.181266 -34.266124)
		(mid 425.910201 -34.447184)
		(end 425.590462 -34.510726)
		(width 0.089408)
		(layer "In2.Cu")
		(net "BMC_M_DQ2")
	)
	(arc
		(start 429.45431 -31.040832)
		(mid 429.45431 -31.373572)
		(end 429.12157 -31.373572)
		(width 0.089408)
		(layer "In2.Cu")
		(net "BMC_M_DQ2")
	)
	(arc
		(start 433.58435 -29.660088)
		(mid 433.471917 -29.706659)
		(end 433.425346 -29.819092)
		(width 0.089408)
		(layer "In2.Cu")
		(net "BMC_M_DQ2")
	)
	(arc
		(start 440.926728 -31.0515)
		(mid 440.406991 -30.948118)
		(end 439.966354 -30.653736)
		(width 0.089408)
		(layer "In2.Cu")
		(net "BMC_M_DQ2")
	)
	(arc
		(start 427.060614 -33.591246)
		(mid 426.814265 -33.684817)
		(end 426.603668 -33.843214)
		(width 0.089408)
		(layer "In2.Cu")
		(net "BMC_M_DQ2")
	)
	(arc
		(start 434.05425 -29.977588)
		(mid 433.942176 -29.931166)
		(end 433.895754 -29.819092)
		(width 0.089408)
		(layer "In2.Cu")
		(net "BMC_M_DQ2")
	)
	(arc
		(start 431.142902 -29.977588)
		(mid 430.873751 -30.031126)
		(end 430.64557 -30.183582)
		(width 0.089408)
		(layer "In2.Cu")
		(net "BMC_M_DQ2")
	)
	(arc
		(start 423.670222 -33.740852)
		(mid 423.139836 -33.635298)
		(end 422.69029 -33.334706)
		(width 0.089408)
		(layer "In2.Cu")
		(net "BMC_M_DQ2")
	)
	(arc
		(start 428.78883 -31.706312)
		(mid 428.78883 -32.039052)
		(end 428.45609 -32.039052)
		(width 0.089408)
		(layer "In2.Cu")
		(net "BMC_M_DQ2")
	)
	(arc
		(start 429.78705 -30.708092)
		(mid 429.45431 -30.708092)
		(end 429.45431 -31.040832)
		(width 0.089408)
		(layer "In2.Cu")
		(net "BMC_M_DQ2")
	)
	(arc
		(start 427.492668 -33.07207)
		(mid 427.547241 -33.203642)
		(end 427.492668 -33.335214)
		(width 0.089408)
		(layer "In2.Cu")
		(net "BMC_M_DQ2")
	)
	(arc
		(start 436.527956 -29.639514)
		(mid 436.472675 -29.691388)
		(end 436.414164 -29.73959)
		(width 0.089408)
		(layer "In2.Cu")
		(net "BMC_M_DQ2")
	)
	(arc
		(start 436.87619 -29.4259)
		(mid 436.751772 -29.450648)
		(end 436.64632 -29.52115)
		(width 0.089408)
		(layer "In2.Cu")
		(net "BMC_M_DQ2")
	)
	(arc
		(start 430.64557 -30.183582)
		(mid 430.62383 -30.204511)
		(end 430.60239 -30.225746)
		(width 0.089408)
		(layer "In2.Cu")
		(net "BMC_M_DQ2")
	)
	(arc
		(start 427.79061 -32.704532)
		(mid 427.45787 -32.704532)
		(end 427.45787 -33.037272)
		(width 0.089408)
		(layer "In2.Cu")
		(net "BMC_M_DQ2")
	)
	(arc
		(start 433.895754 -29.819092)
		(mid 433.849183 -29.706659)
		(end 433.73675 -29.660088)
		(width 0.089408)
		(layer "In2.Cu")
		(net "BMC_M_DQ2")
	)
	(arc
		(start 427.36135 -33.466532)
		(mid 427.223386 -33.558809)
		(end 427.060614 -33.591246)
		(width 0.089408)
		(layer "In2.Cu")
		(net "BMC_M_DQ2")
	)
	(arc
		(start 432.48453 -29.819092)
		(mid 432.438108 -29.931166)
		(end 432.326034 -29.977588)
		(width 0.089408)
		(layer "In2.Cu")
		(net "BMC_M_DQ2")
	)
	(arc
		(start 428.12335 -32.371792)
		(mid 428.12335 -32.704532)
		(end 427.79061 -32.704532)
		(width 0.089408)
		(layer "In2.Cu")
		(net "BMC_M_DQ2")
	)
	(arc
		(start 432.64074 -29.662882)
		(mid 432.530283 -29.708635)
		(end 432.48453 -29.819092)
		(width 0.089408)
		(layer "In2.Cu")
		(net "BMC_M_DQ2")
	)
	(arc
		(start 430.11979 -30.708092)
		(mid 429.95342 -30.777079)
		(end 429.78705 -30.708092)
		(width 0.089408)
		(layer "In2.Cu")
		(net "BMC_M_DQ2")
	)
	(arc
		(start 428.45609 -32.039052)
		(mid 428.12335 -32.039052)
		(end 428.12335 -32.371792)
		(width 0.089408)
		(layer "In2.Cu")
		(net "BMC_M_DQ2")
	)
	(arc
		(start 425.590462 -34.510726)
		(mid 425.526038 -34.515899)
		(end 425.46143 -34.517584)
		(width 0.089408)
		(layer "In2.Cu")
		(net "BMC_M_DQ2")
	)
	(arc
		(start 432.954938 -29.819092)
		(mid 432.909185 -29.708635)
		(end 432.798728 -29.662882)
		(width 0.089408)
		(layer "In2.Cu")
		(net "BMC_M_DQ2")
	)
	(arc
		(start 433.113942 -29.978096)
		(mid 433.001509 -29.931525)
		(end 432.954938 -29.819092)
		(width 0.089408)
		(layer "In2.Cu")
		(net "BMC_M_DQ2")
	)
	(arc
		(start 433.425346 -29.819092)
		(mid 433.378775 -29.931525)
		(end 433.266342 -29.978096)
		(width 0.089408)
		(layer "In2.Cu")
		(net "BMC_M_DQ2")
	)
	(arc
		(start 441.634372 -31.344616)
		(mid 441.309702 -31.127679)
		(end 440.926728 -31.0515)
		(width 0.089408)
		(layer "In2.Cu")
		(net "BMC_M_DQ2")
	)
	(segment
		(start 419.890194 -31.33471)
		(end 419.890194 -31.334456)
		(width 0.089408)
		(layer "F.Cu")
		(net "BMC_M_DQ15")
	)
	(segment
		(start 419.890194 -31.334456)
		(end 420.28999 -30.93466)
		(width 0.089408)
		(layer "F.Cu")
		(net "BMC_M_DQ15")
	)
	(segment
		(start 438.12206 -27.832304)
		(end 437.721756 -27.432)
		(width 0.10795)
		(layer "F.Cu")
		(net "BMC_M_DQ15")
	)
	(segment
		(start 438.12206 -27.832558)
		(end 438.12206 -27.832304)
		(width 0.10795)
		(layer "F.Cu")
		(net "BMC_M_DQ15")
	)
	(via
		(at 437.721756 -27.432)
		(size 0.4572)
		(drill 0.2032)
		(layers "F.Cu" "B.Cu")
		(net "BMC_M_DQ15")
	)
	(via
		(at 420.28999 -30.93466)
		(size 0.508)
		(drill 0.254)
		(layers "F.Cu" "B.Cu")
		(net "BMC_M_DQ15")
	)
	(segment
		(start 437.537098 -27.432)
		(end 437.721756 -27.432)
		(width 0.089408)
		(layer "In2.Cu")
		(net "BMC_M_DQ15")
	)
	(segment
		(start 420.35603 -30.540452)
		(end 423.33418 -30.540452)
		(width 0.089408)
		(layer "In2.Cu")
		(net "BMC_M_DQ15")
	)
	(segment
		(start 425.440348 -28.276042)
		(end 424.997372 -27.832812)
		(width 0.089408)
		(layer "In2.Cu")
		(net "BMC_M_DQ15")
	)
	(segment
		(start 435.106064 -25.73274)
		(end 435.106064 -25.801066)
		(width 0.089408)
		(layer "In2.Cu")
		(net "BMC_M_DQ15")
	)
	(segment
		(start 435.341268 -26.03627)
		(end 436.780686 -26.03627)
		(width 0.089408)
		(layer "In2.Cu")
		(net "BMC_M_DQ15")
	)
	(segment
		(start 432.754024 -25.801066)
		(end 432.754024 -25.725628)
		(width 0.089408)
		(layer "In2.Cu")
		(net "BMC_M_DQ15")
	)
	(segment
		(start 424.90517 -29.14396)
		(end 425.440348 -28.608782)
		(width 0.089408)
		(layer "In2.Cu")
		(net "BMC_M_DQ15")
	)
	(segment
		(start 426.589698 -27.678634)
		(end 428.051214 -26.22169)
		(width 0.089408)
		(layer "In2.Cu")
		(net "BMC_M_DQ15")
	)
	(segment
		(start 428.499524 -26.03627)
		(end 432.51882 -26.03627)
		(width 0.089408)
		(layer "In2.Cu")
		(net "BMC_M_DQ15")
	)
	(segment
		(start 423.991278 -30.268672)
		(end 424.726608 -29.534866)
		(width 0.089408)
		(layer "In2.Cu")
		(net "BMC_M_DQ15")
	)
	(segment
		(start 434.165248 -25.724358)
		(end 434.165248 -25.801066)
		(width 0.089408)
		(layer "In2.Cu")
		(net "BMC_M_DQ15")
	)
	(segment
		(start 434.635656 -25.801066)
		(end 434.635656 -25.73274)
		(width 0.089408)
		(layer "In2.Cu")
		(net "BMC_M_DQ15")
	)
	(segment
		(start 420.28999 -30.93466)
		(end 420.262812 -30.907482)
		(width 0.089408)
		(layer "In2.Cu")
		(net "BMC_M_DQ15")
	)
	(segment
		(start 426.465238 -27.803094)
		(end 426.589698 -27.678634)
		(width 0.089408)
		(layer "In2.Cu")
		(net "BMC_M_DQ15")
	)
	(segment
		(start 425.330112 -27.500072)
		(end 425.773088 -27.943302)
		(width 0.089408)
		(layer "In2.Cu")
		(net "BMC_M_DQ15")
	)
	(segment
		(start 433.224432 -25.725628)
		(end 433.224432 -25.801066)
		(width 0.089408)
		(layer "In2.Cu")
		(net "BMC_M_DQ15")
	)
	(segment
		(start 437.334406 -26.58999)
		(end 437.334406 -27.229308)
		(width 0.089408)
		(layer "In2.Cu")
		(net "BMC_M_DQ15")
	)
	(segment
		(start 433.69484 -25.801066)
		(end 433.69484 -25.724358)
		(width 0.089408)
		(layer "In2.Cu")
		(net "BMC_M_DQ15")
	)
	(arc
		(start 433.69484 -25.724358)
		(mid 433.930044 -25.489154)
		(end 434.165248 -25.724358)
		(width 0.089408)
		(layer "In2.Cu")
		(net "BMC_M_DQ15")
	)
	(arc
		(start 432.51882 -26.03627)
		(mid 432.685134 -25.96738)
		(end 432.754024 -25.801066)
		(width 0.089408)
		(layer "In2.Cu")
		(net "BMC_M_DQ15")
	)
	(arc
		(start 424.997372 -27.832812)
		(mid 424.997372 -27.500072)
		(end 425.330112 -27.500072)
		(width 0.089408)
		(layer "In2.Cu")
		(net "BMC_M_DQ15")
	)
	(arc
		(start 434.635656 -25.73274)
		(mid 434.87086 -25.497536)
		(end 435.106064 -25.73274)
		(width 0.089408)
		(layer "In2.Cu")
		(net "BMC_M_DQ15")
	)
	(arc
		(start 420.262812 -30.907482)
		(mid 420.194921 -30.743308)
		(end 420.262812 -30.57906)
		(width 0.089408)
		(layer "In2.Cu")
		(net "BMC_M_DQ15")
	)
	(arc
		(start 435.106064 -25.801066)
		(mid 435.174954 -25.96738)
		(end 435.341268 -26.03627)
		(width 0.089408)
		(layer "In2.Cu")
		(net "BMC_M_DQ15")
	)
	(arc
		(start 437.334406 -27.229308)
		(mid 437.393773 -27.372633)
		(end 437.537098 -27.432)
		(width 0.089408)
		(layer "In2.Cu")
		(net "BMC_M_DQ15")
	)
	(arc
		(start 433.224432 -25.801066)
		(mid 433.459636 -26.03627)
		(end 433.69484 -25.801066)
		(width 0.089408)
		(layer "In2.Cu")
		(net "BMC_M_DQ15")
	)
	(arc
		(start 425.963588 -28.010866)
		(mid 426.235072 -27.956864)
		(end 426.465238 -27.803094)
		(width 0.089408)
		(layer "In2.Cu")
		(net "BMC_M_DQ15")
	)
	(arc
		(start 423.33418 -30.540452)
		(mid 423.689717 -30.46982)
		(end 423.991278 -30.268672)
		(width 0.089408)
		(layer "In2.Cu")
		(net "BMC_M_DQ15")
	)
	(arc
		(start 436.780686 -26.03627)
		(mid 437.172225 -26.198451)
		(end 437.334406 -26.58999)
		(width 0.089408)
		(layer "In2.Cu")
		(net "BMC_M_DQ15")
	)
	(arc
		(start 425.440348 -28.608782)
		(mid 425.509335 -28.442412)
		(end 425.440348 -28.276042)
		(width 0.089408)
		(layer "In2.Cu")
		(net "BMC_M_DQ15")
	)
	(arc
		(start 425.773088 -27.943302)
		(mid 425.860705 -27.998643)
		(end 425.963588 -28.010866)
		(width 0.089408)
		(layer "In2.Cu")
		(net "BMC_M_DQ15")
	)
	(arc
		(start 432.754024 -25.725628)
		(mid 432.989228 -25.490424)
		(end 433.224432 -25.725628)
		(width 0.089408)
		(layer "In2.Cu")
		(net "BMC_M_DQ15")
	)
	(arc
		(start 434.165248 -25.801066)
		(mid 434.400452 -26.03627)
		(end 434.635656 -25.801066)
		(width 0.089408)
		(layer "In2.Cu")
		(net "BMC_M_DQ15")
	)
	(arc
		(start 428.051214 -26.22169)
		(mid 428.256971 -26.084523)
		(end 428.499524 -26.03627)
		(width 0.089408)
		(layer "In2.Cu")
		(net "BMC_M_DQ15")
	)
	(arc
		(start 424.726608 -29.534866)
		(mid 424.804631 -29.418097)
		(end 424.832018 -29.280358)
		(width 0.089408)
		(layer "In2.Cu")
		(net "BMC_M_DQ15")
	)
	(arc
		(start 424.832018 -29.280358)
		(mid 424.858521 -29.206753)
		(end 424.90517 -29.14396)
		(width 0.089408)
		(layer "In2.Cu")
		(net "BMC_M_DQ15")
	)
	(arc
		(start 420.262812 -30.57906)
		(mid 420.305581 -30.550483)
		(end 420.35603 -30.540452)
		(width 0.089408)
		(layer "In2.Cu")
		(net "BMC_M_DQ15")
	)
	(segment
		(start 420.69004 -31.33471)
		(end 421.09009 -30.93466)
		(width 0.089408)
		(layer "F.Cu")
		(net "BMC_M_DQ14")
	)
	(segment
		(start 441.321952 -27.831796)
		(end 440.922156 -27.432)
		(width 0.10795)
		(layer "F.Cu")
		(net "BMC_M_DQ14")
	)
	(segment
		(start 441.321952 -27.832558)
		(end 441.321952 -27.831796)
		(width 0.10795)
		(layer "F.Cu")
		(net "BMC_M_DQ14")
	)
	(via
		(at 440.922156 -27.432)
		(size 0.4572)
		(drill 0.2032)
		(layers "F.Cu" "B.Cu")
		(net "BMC_M_DQ14")
	)
	(via
		(at 429.50638 -26.187654)
		(size 0.508)
		(drill 0.254)
		(layers "F.Cu" "B.Cu")
		(net "BMC_M_DQ14")
	)
	(via
		(at 421.09009 -30.93466)
		(size 0.4572)
		(drill 0.2032)
		(layers "F.Cu" "B.Cu")
		(net "BMC_M_DQ14")
	)
	(segment
		(start 423.424096 -31.327852)
		(end 421.698928 -31.327852)
		(width 0.10795)
		(layer "B.Cu")
		(net "BMC_M_DQ14")
	)
	(segment
		(start 429.50638 -26.187654)
		(end 431.080164 -26.187654)
		(width 0.10795)
		(layer "B.Cu")
		(net "BMC_M_DQ14")
	)
	(segment
		(start 421.332152 -31.17596)
		(end 421.318944 -31.162752)
		(width 0.10795)
		(layer "B.Cu")
		(net "BMC_M_DQ14")
	)
	(segment
		(start 426.5295 -27.536648)
		(end 426.528484 -27.537664)
		(width 0.10795)
		(layer "B.Cu")
		(net "BMC_M_DQ14")
	)
	(segment
		(start 427.528228 -26.537412)
		(end 426.5295 -27.536648)
		(width 0.10795)
		(layer "B.Cu")
		(net "BMC_M_DQ14")
	)
	(segment
		(start 425.097702 -30.198822)
		(end 425.097702 -30.23489)
		(width 0.10795)
		(layer "B.Cu")
		(net "BMC_M_DQ14")
	)
	(segment
		(start 426.08754 -28.602178)
		(end 426.08754 -28.603194)
		(width 0.10795)
		(layer "B.Cu")
		(net "BMC_M_DQ14")
	)
	(segment
		(start 438.199784 -24.709628)
		(end 440.922156 -27.432)
		(width 0.10795)
		(layer "B.Cu")
		(net "BMC_M_DQ14")
	)
	(segment
		(start 433.73929 -24.142954)
		(end 436.831994 -24.142954)
		(width 0.10795)
		(layer "B.Cu")
		(net "BMC_M_DQ14")
	)
	(segment
		(start 429.50638 -26.187654)
		(end 428.372778 -26.187654)
		(width 0.10795)
		(layer "B.Cu")
		(net "BMC_M_DQ14")
	)
	(segment
		(start 425.732702 -29.459682)
		(end 425.21759 -29.974794)
		(width 0.10795)
		(layer "B.Cu")
		(net "BMC_M_DQ14")
	)
	(segment
		(start 431.602388 -25.971246)
		(end 433.212494 -24.36114)
		(width 0.10795)
		(layer "B.Cu")
		(net "BMC_M_DQ14")
	)
	(arc
		(start 428.372778 -26.187654)
		(mid 427.915697 -26.278497)
		(end 427.528228 -26.537412)
		(width 0.10795)
		(layer "B.Cu")
		(net "BMC_M_DQ14")
	)
	(arc
		(start 436.831994 -24.142954)
		(mid 437.572228 -24.290289)
		(end 438.199784 -24.709628)
		(width 0.10795)
		(layer "B.Cu")
		(net "BMC_M_DQ14")
	)
	(arc
		(start 433.212494 -24.36114)
		(mid 433.45419 -24.199644)
		(end 433.73929 -24.142954)
		(width 0.10795)
		(layer "B.Cu")
		(net "BMC_M_DQ14")
	)
	(arc
		(start 426.08754 -28.603194)
		(mid 425.995318 -29.066734)
		(end 425.732702 -29.459682)
		(width 0.10795)
		(layer "B.Cu")
		(net "BMC_M_DQ14")
	)
	(arc
		(start 425.21759 -29.974794)
		(mid 425.14109 -30.077946)
		(end 425.097702 -30.198822)
		(width 0.10795)
		(layer "B.Cu")
		(net "BMC_M_DQ14")
	)
	(arc
		(start 421.698928 -31.327852)
		(mid 421.500442 -31.288371)
		(end 421.332152 -31.17596)
		(width 0.10795)
		(layer "B.Cu")
		(net "BMC_M_DQ14")
	)
	(arc
		(start 421.318944 -31.162752)
		(mid 421.204612 -31.048611)
		(end 421.09009 -30.93466)
		(width 0.10795)
		(layer "B.Cu")
		(net "BMC_M_DQ14")
	)
	(arc
		(start 425.097702 -30.23489)
		(mid 425.0408 -30.520954)
		(end 424.878754 -30.763464)
		(width 0.10795)
		(layer "B.Cu")
		(net "BMC_M_DQ14")
	)
	(arc
		(start 426.528484 -27.537664)
		(mid 426.202143 -28.026067)
		(end 426.08754 -28.602178)
		(width 0.10795)
		(layer "B.Cu")
		(net "BMC_M_DQ14")
	)
	(arc
		(start 424.878754 -30.763464)
		(mid 424.204255 -31.18183)
		(end 423.424096 -31.327852)
		(width 0.10795)
		(layer "B.Cu")
		(net "BMC_M_DQ14")
	)
	(arc
		(start 431.080164 -26.187654)
		(mid 431.362826 -26.131429)
		(end 431.602388 -25.971246)
		(width 0.10795)
		(layer "B.Cu")
		(net "BMC_M_DQ14")
	)
	(segment
		(start 421.49014 -31.33471)
		(end 421.89019 -30.93466)
		(width 0.089408)
		(layer "F.Cu")
		(net "BMC_M_DQ13")
	)
	(segment
		(start 437.32196 -27.032458)
		(end 437.321198 -27.032458)
		(width 0.10795)
		(layer "F.Cu")
		(net "BMC_M_DQ13")
	)
	(segment
		(start 437.321198 -27.032458)
		(end 436.921656 -27.432)
		(width 0.10795)
		(layer "F.Cu")
		(net "BMC_M_DQ13")
	)
	(via
		(at 436.921656 -27.432)
		(size 0.4572)
		(drill 0.2032)
		(layers "F.Cu" "B.Cu")
		(net "BMC_M_DQ13")
	)
	(via
		(at 421.89019 -30.93466)
		(size 0.4572)
		(drill 0.2032)
		(layers "F.Cu" "B.Cu")
		(net "BMC_M_DQ13")
	)
	(segment
		(start 434.381656 -26.943558)
		(end 434.338984 -26.943558)
		(width 0.089408)
		(layer "In2.Cu")
		(net "BMC_M_DQ13")
	)
	(segment
		(start 429.673766 -26.97226)
		(end 429.663606 -26.97226)
		(width 0.089408)
		(layer "In2.Cu")
		(net "BMC_M_DQ13")
	)
	(segment
		(start 427.924468 -27.840432)
		(end 428.189136 -28.106624)
		(width 0.089408)
		(layer "In2.Cu")
		(net "BMC_M_DQ13")
	)
	(segment
		(start 430.14773 -26.515568)
		(end 430.105058 -26.515568)
		(width 0.089408)
		(layer "In2.Cu")
		(net "BMC_M_DQ13")
	)
	(segment
		(start 422.256966 -31.110174)
		(end 422.215564 -31.068772)
		(width 0.089408)
		(layer "In2.Cu")
		(net "BMC_M_DQ13")
	)
	(segment
		(start 425.12869 -29.938726)
		(end 423.958512 -31.104078)
		(width 0.089408)
		(layer "In2.Cu")
		(net "BMC_M_DQ13")
	)
	(segment
		(start 436.921656 -27.432)
		(end 436.567834 -27.07894)
		(width 0.089408)
		(layer "In2.Cu")
		(net "BMC_M_DQ13")
	)
	(segment
		(start 427.85665 -28.438348)
		(end 427.548294 -28.129484)
		(width 0.089408)
		(layer "In2.Cu")
		(net "BMC_M_DQ13")
	)
	(segment
		(start 431.558954 -26.943304)
		(end 431.516282 -26.943304)
		(width 0.089408)
		(layer "In2.Cu")
		(net "BMC_M_DQ13")
	)
	(segment
		(start 433.910994 -26.515568)
		(end 433.868322 -26.515568)
		(width 0.089408)
		(layer "In2.Cu")
		(net "BMC_M_DQ13")
	)
	(segment
		(start 429.206914 -26.515568)
		(end 428.702724 -26.515568)
		(width 0.089408)
		(layer "In2.Cu")
		(net "BMC_M_DQ13")
	)
	(segment
		(start 425.95292 -28.816808)
		(end 425.3865 -29.38272)
		(width 0.089408)
		(layer "In2.Cu")
		(net "BMC_M_DQ13")
	)
	(segment
		(start 423.355008 -31.353252)
		(end 422.843706 -31.353252)
		(width 0.089408)
		(layer "In2.Cu")
		(net "BMC_M_DQ13")
	)
	(segment
		(start 429.89119 -26.729436)
		(end 429.89119 -26.754836)
		(width 0.089408)
		(layer "In2.Cu")
		(net "BMC_M_DQ13")
	)
	(segment
		(start 433.440586 -26.943304)
		(end 433.397914 -26.943304)
		(width 0.089408)
		(layer "In2.Cu")
		(net "BMC_M_DQ13")
	)
	(segment
		(start 426.882306 -28.794202)
		(end 426.751496 -28.663138)
		(width 0.089408)
		(layer "In2.Cu")
		(net "BMC_M_DQ13")
	)
	(segment
		(start 432.49977 -26.943304)
		(end 432.457098 -26.943304)
		(width 0.089408)
		(layer "In2.Cu")
		(net "BMC_M_DQ13")
	)
	(segment
		(start 431.088546 -26.515568)
		(end 431.045874 -26.515568)
		(width 0.089408)
		(layer "In2.Cu")
		(net "BMC_M_DQ13")
	)
	(segment
		(start 432.029362 -26.515568)
		(end 431.98669 -26.515568)
		(width 0.089408)
		(layer "In2.Cu")
		(net "BMC_M_DQ13")
	)
	(segment
		(start 434.59527 -26.639012)
		(end 434.59527 -26.729944)
		(width 0.089408)
		(layer "In2.Cu")
		(net "BMC_M_DQ13")
	)
	(segment
		(start 434.841904 -26.515568)
		(end 434.71846 -26.515568)
		(width 0.089408)
		(layer "In2.Cu")
		(net "BMC_M_DQ13")
	)
	(segment
		(start 430.619154 -26.942288)
		(end 430.57445 -26.942288)
		(width 0.089408)
		(layer "In2.Cu")
		(net "BMC_M_DQ13")
	)
	(segment
		(start 436.409846 -27.013408)
		(end 436.043832 -27.013408)
		(width 0.089408)
		(layer "In2.Cu")
		(net "BMC_M_DQ13")
	)
	(segment
		(start 428.652432 -27.903932)
		(end 428.258224 -27.508454)
		(width 0.089408)
		(layer "In2.Cu")
		(net "BMC_M_DQ13")
	)
	(segment
		(start 432.970178 -26.515568)
		(end 432.927506 -26.515568)
		(width 0.089408)
		(layer "In2.Cu")
		(net "BMC_M_DQ13")
	)
	(segment
		(start 428.408592 -26.992834)
		(end 428.985426 -27.572208)
		(width 0.089408)
		(layer "In2.Cu")
		(net "BMC_M_DQ13")
	)
	(segment
		(start 428.559976 -26.563828)
		(end 428.432468 -26.66111)
		(width 0.089408)
		(layer "In2.Cu")
		(net "BMC_M_DQ13")
	)
	(arc
		(start 423.958512 -31.104078)
		(mid 423.681466 -31.288501)
		(end 423.355008 -31.353252)
		(width 0.089408)
		(layer "In2.Cu")
		(net "BMC_M_DQ13")
	)
	(arc
		(start 428.258224 -27.508454)
		(mid 427.925294 -27.507628)
		(end 427.924468 -27.840432)
		(width 0.089408)
		(layer "In2.Cu")
		(net "BMC_M_DQ13")
	)
	(arc
		(start 434.338984 -26.943558)
		(mid 434.187577 -26.880843)
		(end 434.124862 -26.729436)
		(width 0.089408)
		(layer "In2.Cu")
		(net "BMC_M_DQ13")
	)
	(arc
		(start 433.868322 -26.515568)
		(mid 433.717094 -26.578208)
		(end 433.654454 -26.729436)
		(width 0.089408)
		(layer "In2.Cu")
		(net "BMC_M_DQ13")
	)
	(arc
		(start 426.5295 -28.574746)
		(mid 426.419174 -28.599118)
		(end 426.325538 -28.662376)
		(width 0.089408)
		(layer "In2.Cu")
		(net "BMC_M_DQ13")
	)
	(arc
		(start 428.189136 -28.106624)
		(mid 428.188819 -28.438665)
		(end 427.85665 -28.438348)
		(width 0.089408)
		(layer "In2.Cu")
		(net "BMC_M_DQ13")
	)
	(arc
		(start 431.302414 -26.729436)
		(mid 431.239774 -26.578208)
		(end 431.088546 -26.515568)
		(width 0.089408)
		(layer "In2.Cu")
		(net "BMC_M_DQ13")
	)
	(arc
		(start 436.567834 -27.07894)
		(mid 436.495349 -27.030478)
		(end 436.409846 -27.013408)
		(width 0.089408)
		(layer "In2.Cu")
		(net "BMC_M_DQ13")
	)
	(arc
		(start 425.267374 -29.604208)
		(mid 425.231361 -29.785277)
		(end 425.12869 -29.938726)
		(width 0.089408)
		(layer "In2.Cu")
		(net "BMC_M_DQ13")
	)
	(arc
		(start 428.702724 -26.515568)
		(mid 428.627383 -26.527961)
		(end 428.559976 -26.563828)
		(width 0.089408)
		(layer "In2.Cu")
		(net "BMC_M_DQ13")
	)
	(arc
		(start 435.578504 -26.820622)
		(mid 435.240549 -26.594808)
		(end 434.841904 -26.515568)
		(width 0.089408)
		(layer "In2.Cu")
		(net "BMC_M_DQ13")
	)
	(arc
		(start 427.215046 -28.46197)
		(mid 427.214792 -28.794456)
		(end 426.882306 -28.794202)
		(width 0.089408)
		(layer "In2.Cu")
		(net "BMC_M_DQ13")
	)
	(arc
		(start 431.98669 -26.515568)
		(mid 431.835462 -26.578208)
		(end 431.772822 -26.729436)
		(width 0.089408)
		(layer "In2.Cu")
		(net "BMC_M_DQ13")
	)
	(arc
		(start 428.985426 -27.572208)
		(mid 428.984855 -27.904503)
		(end 428.652432 -27.903932)
		(width 0.089408)
		(layer "In2.Cu")
		(net "BMC_M_DQ13")
	)
	(arc
		(start 430.832006 -26.729436)
		(mid 430.769663 -26.879945)
		(end 430.619154 -26.942288)
		(width 0.089408)
		(layer "In2.Cu")
		(net "BMC_M_DQ13")
	)
	(arc
		(start 430.105058 -26.515568)
		(mid 429.95383 -26.578208)
		(end 429.89119 -26.729436)
		(width 0.089408)
		(layer "In2.Cu")
		(net "BMC_M_DQ13")
	)
	(arc
		(start 433.184046 -26.729436)
		(mid 433.121406 -26.578208)
		(end 432.970178 -26.515568)
		(width 0.089408)
		(layer "In2.Cu")
		(net "BMC_M_DQ13")
	)
	(arc
		(start 422.843706 -31.353252)
		(mid 422.526163 -31.290071)
		(end 422.256966 -31.110174)
		(width 0.089408)
		(layer "In2.Cu")
		(net "BMC_M_DQ13")
	)
	(arc
		(start 436.043832 -27.013408)
		(mid 435.791983 -26.963312)
		(end 435.578504 -26.820622)
		(width 0.089408)
		(layer "In2.Cu")
		(net "BMC_M_DQ13")
	)
	(arc
		(start 428.432468 -26.66111)
		(mid 428.420448 -26.670884)
		(end 428.4091 -26.68143)
		(width 0.089408)
		(layer "In2.Cu")
		(net "BMC_M_DQ13")
	)
	(arc
		(start 431.516282 -26.943304)
		(mid 431.365054 -26.880664)
		(end 431.302414 -26.729436)
		(width 0.089408)
		(layer "In2.Cu")
		(net "BMC_M_DQ13")
	)
	(arc
		(start 432.457098 -26.943304)
		(mid 432.30587 -26.880664)
		(end 432.24323 -26.729436)
		(width 0.089408)
		(layer "In2.Cu")
		(net "BMC_M_DQ13")
	)
	(arc
		(start 431.045874 -26.515568)
		(mid 430.894646 -26.578208)
		(end 430.832006 -26.729436)
		(width 0.089408)
		(layer "In2.Cu")
		(net "BMC_M_DQ13")
	)
	(arc
		(start 432.713638 -26.729436)
		(mid 432.650998 -26.880664)
		(end 432.49977 -26.943304)
		(width 0.089408)
		(layer "In2.Cu")
		(net "BMC_M_DQ13")
	)
	(arc
		(start 433.654454 -26.729436)
		(mid 433.591814 -26.880664)
		(end 433.440586 -26.943304)
		(width 0.089408)
		(layer "In2.Cu")
		(net "BMC_M_DQ13")
	)
	(arc
		(start 430.57445 -26.942288)
		(mid 430.423941 -26.879945)
		(end 430.361598 -26.729436)
		(width 0.089408)
		(layer "In2.Cu")
		(net "BMC_M_DQ13")
	)
	(arc
		(start 430.361598 -26.729436)
		(mid 430.298958 -26.578208)
		(end 430.14773 -26.515568)
		(width 0.089408)
		(layer "In2.Cu")
		(net "BMC_M_DQ13")
	)
	(arc
		(start 422.215564 -31.068772)
		(mid 422.066276 -30.969201)
		(end 421.89019 -30.93466)
		(width 0.089408)
		(layer "In2.Cu")
		(net "BMC_M_DQ13")
	)
	(arc
		(start 434.124862 -26.729436)
		(mid 434.062222 -26.578208)
		(end 433.910994 -26.515568)
		(width 0.089408)
		(layer "In2.Cu")
		(net "BMC_M_DQ13")
	)
	(arc
		(start 434.71846 -26.515568)
		(mid 434.631262 -26.551739)
		(end 434.59527 -26.639012)
		(width 0.089408)
		(layer "In2.Cu")
		(net "BMC_M_DQ13")
	)
	(arc
		(start 432.24323 -26.729436)
		(mid 432.18059 -26.578208)
		(end 432.029362 -26.515568)
		(width 0.089408)
		(layer "In2.Cu")
		(net "BMC_M_DQ13")
	)
	(arc
		(start 427.548294 -28.129484)
		(mid 427.215364 -28.129166)
		(end 427.215046 -28.46197)
		(width 0.089408)
		(layer "In2.Cu")
		(net "BMC_M_DQ13")
	)
	(arc
		(start 434.59527 -26.729944)
		(mid 434.532704 -26.880992)
		(end 434.381656 -26.943558)
		(width 0.089408)
		(layer "In2.Cu")
		(net "BMC_M_DQ13")
	)
	(arc
		(start 426.325538 -28.662376)
		(mid 426.123909 -28.702616)
		(end 425.95292 -28.816808)
		(width 0.089408)
		(layer "In2.Cu")
		(net "BMC_M_DQ13")
	)
	(arc
		(start 433.397914 -26.943304)
		(mid 433.246686 -26.880664)
		(end 433.184046 -26.729436)
		(width 0.089408)
		(layer "In2.Cu")
		(net "BMC_M_DQ13")
	)
	(arc
		(start 428.4091 -26.68143)
		(mid 428.344352 -26.837027)
		(end 428.408592 -26.992834)
		(width 0.089408)
		(layer "In2.Cu")
		(net "BMC_M_DQ13")
	)
	(arc
		(start 429.420782 -26.729436)
		(mid 429.358142 -26.578208)
		(end 429.206914 -26.515568)
		(width 0.089408)
		(layer "In2.Cu")
		(net "BMC_M_DQ13")
	)
	(arc
		(start 425.3865 -29.38272)
		(mid 425.310625 -29.484686)
		(end 425.267374 -29.604208)
		(width 0.089408)
		(layer "In2.Cu")
		(net "BMC_M_DQ13")
	)
	(arc
		(start 432.927506 -26.515568)
		(mid 432.776278 -26.578208)
		(end 432.713638 -26.729436)
		(width 0.089408)
		(layer "In2.Cu")
		(net "BMC_M_DQ13")
	)
	(arc
		(start 426.751496 -28.663138)
		(mid 426.649647 -28.59594)
		(end 426.5295 -28.574746)
		(width 0.089408)
		(layer "In2.Cu")
		(net "BMC_M_DQ13")
	)
	(arc
		(start 429.89119 -26.754836)
		(mid 429.827508 -26.908578)
		(end 429.673766 -26.97226)
		(width 0.089408)
		(layer "In2.Cu")
		(net "BMC_M_DQ13")
	)
	(arc
		(start 429.663606 -26.97226)
		(mid 429.491904 -26.901138)
		(end 429.420782 -26.729436)
		(width 0.089408)
		(layer "In2.Cu")
		(net "BMC_M_DQ13")
	)
	(arc
		(start 431.772822 -26.729436)
		(mid 431.710182 -26.880664)
		(end 431.558954 -26.943304)
		(width 0.089408)
		(layer "In2.Cu")
		(net "BMC_M_DQ13")
	)
	(segment
		(start 424.648122 -30.0863)
		(end 423.909236 -30.0863)
		(width 0.10795)
		(layer "F.Cu")
		(net "BMC_M_DQ12")
	)
	(segment
		(start 433.672742 -27.72664)
		(end 428.92599 -27.72664)
		(width 0.10795)
		(layer "F.Cu")
		(net "BMC_M_DQ12")
	)
	(segment
		(start 426.712888 -29.338778)
		(end 426.013118 -29.338778)
		(width 0.10795)
		(layer "F.Cu")
		(net "BMC_M_DQ12")
	)
	(segment
		(start 438.328308 -23.0886)
		(end 438.050686 -23.0886)
		(width 0.10795)
		(layer "F.Cu")
		(net "BMC_M_DQ12")
	)
	(segment
		(start 441.308236 -25.0063)
		(end 441.2234 -25.0063)
		(width 0.10795)
		(layer "F.Cu")
		(net "BMC_M_DQ12")
	)
	(segment
		(start 437.662066 -23.226776)
		(end 435.965854 -23.226776)
		(width 0.10795)
		(layer "F.Cu")
		(net "BMC_M_DQ12")
	)
	(segment
		(start 434.431186 -24.81072)
		(end 434.431186 -26.968196)
		(width 0.10795)
		(layer "F.Cu")
		(net "BMC_M_DQ12")
	)
	(segment
		(start 423.27576 -30.348936)
		(end 423.090086 -30.53461)
		(width 0.10795)
		(layer "F.Cu")
		(net "BMC_M_DQ12")
	)
	(segment
		(start 427.18228 -29.14142)
		(end 427.177454 -29.1465)
		(width 0.10795)
		(layer "F.Cu")
		(net "BMC_M_DQ12")
	)
	(segment
		(start 441.7568 -26.15057)
		(end 441.7568 -25.454864)
		(width 0.10795)
		(layer "F.Cu")
		(net "BMC_M_DQ12")
	)
	(segment
		(start 428.364396 -27.959304)
		(end 427.38421 -28.93949)
		(width 0.10795)
		(layer "F.Cu")
		(net "BMC_M_DQ12")
	)
	(segment
		(start 434.957728 -23.644352)
		(end 434.88356 -23.71852)
		(width 0.10795)
		(layer "F.Cu")
		(net "BMC_M_DQ12")
	)
	(segment
		(start 427.38421 -28.93949)
		(end 427.18228 -29.14142)
		(width 0.10795)
		(layer "F.Cu")
		(net "BMC_M_DQ12")
	)
	(segment
		(start 440.421268 -24.674068)
		(end 439.19521 -23.447756)
		(width 0.10795)
		(layer "F.Cu")
		(net "BMC_M_DQ12")
	)
	(segment
		(start 425.245276 -29.656532)
		(end 424.933872 -29.967936)
		(width 0.10795)
		(layer "F.Cu")
		(net "BMC_M_DQ12")
	)
	(via
		(at 427.38421 -28.93949)
		(size 0.508)
		(drill 0.254)
		(layers "F.Cu" "B.Cu")
		(net "BMC_M_DQ12")
	)
	(arc
		(start 441.7568 -25.454864)
		(mid 441.625419 -25.137681)
		(end 441.308236 -25.0063)
		(width 0.10795)
		(layer "F.Cu")
		(net "BMC_M_DQ12")
	)
	(arc
		(start 441.2234 -25.0063)
		(mid 440.789298 -24.919952)
		(end 440.421268 -24.674068)
		(width 0.10795)
		(layer "F.Cu")
		(net "BMC_M_DQ12")
	)
	(arc
		(start 426.013118 -29.338778)
		(mid 425.597596 -29.421301)
		(end 425.245276 -29.656532)
		(width 0.10795)
		(layer "F.Cu")
		(net "BMC_M_DQ12")
	)
	(arc
		(start 439.19521 -23.447756)
		(mid 438.797486 -23.181942)
		(end 438.328308 -23.0886)
		(width 0.10795)
		(layer "F.Cu")
		(net "BMC_M_DQ12")
	)
	(arc
		(start 437.9214 -23.119334)
		(mid 437.802417 -23.198836)
		(end 437.662066 -23.226776)
		(width 0.10795)
		(layer "F.Cu")
		(net "BMC_M_DQ12")
	)
	(arc
		(start 438.050686 -23.0886)
		(mid 437.984245 -23.096396)
		(end 437.9214 -23.119334)
		(width 0.10795)
		(layer "F.Cu")
		(net "BMC_M_DQ12")
	)
	(arc
		(start 427.177454 -29.1465)
		(mid 426.964294 -29.288836)
		(end 426.712888 -29.338778)
		(width 0.10795)
		(layer "F.Cu")
		(net "BMC_M_DQ12")
	)
	(arc
		(start 442.122052 -27.032458)
		(mid 441.851698 -26.627844)
		(end 441.7568 -26.15057)
		(width 0.10795)
		(layer "F.Cu")
		(net "BMC_M_DQ12")
	)
	(arc
		(start 434.88356 -23.71852)
		(mid 434.548732 -24.219626)
		(end 434.431186 -24.81072)
		(width 0.10795)
		(layer "F.Cu")
		(net "BMC_M_DQ12")
	)
	(arc
		(start 428.92599 -27.72664)
		(mid 428.622055 -27.787114)
		(end 428.364396 -27.959304)
		(width 0.10795)
		(layer "F.Cu")
		(net "BMC_M_DQ12")
	)
	(arc
		(start 424.933872 -29.967936)
		(mid 424.802769 -30.055536)
		(end 424.648122 -30.0863)
		(width 0.10795)
		(layer "F.Cu")
		(net "BMC_M_DQ12")
	)
	(arc
		(start 434.431186 -26.968196)
		(mid 434.209043 -27.504497)
		(end 433.672742 -27.72664)
		(width 0.10795)
		(layer "F.Cu")
		(net "BMC_M_DQ12")
	)
	(arc
		(start 423.909236 -30.0863)
		(mid 423.566351 -30.154558)
		(end 423.27576 -30.348936)
		(width 0.10795)
		(layer "F.Cu")
		(net "BMC_M_DQ12")
	)
	(arc
		(start 435.965854 -23.226776)
		(mid 435.420261 -23.335301)
		(end 434.957728 -23.644352)
		(width 0.10795)
		(layer "F.Cu")
		(net "BMC_M_DQ12")
	)
	(segment
		(start 438.12206 -27.032458)
		(end 438.12206 -27.032204)
		(width 0.10795)
		(layer "F.Cu")
		(net "BMC_M_DQ11")
	)
	(segment
		(start 438.12206 -27.032204)
		(end 437.721756 -26.6319)
		(width 0.10795)
		(layer "F.Cu")
		(net "BMC_M_DQ11")
	)
	(segment
		(start 421.49014 -32.134556)
		(end 421.89019 -32.534606)
		(width 0.1016)
		(layer "F.Cu")
		(net "BMC_M_DQ11")
	)
	(via
		(at 431.259488 -29.571442)
		(size 0.508)
		(drill 0.254)
		(layers "F.Cu" "B.Cu")
		(net "BMC_M_DQ11")
	)
	(via
		(at 437.721756 -26.6319)
		(size 0.4572)
		(drill 0.2032)
		(layers "F.Cu" "B.Cu")
		(net "BMC_M_DQ11")
	)
	(via
		(at 421.89019 -32.534606)
		(size 0.4572)
		(drill 0.2032)
		(layers "F.Cu" "B.Cu")
		(net "BMC_M_DQ11")
	)
	(segment
		(start 422.011602 -32.115252)
		(end 423.52468 -32.115252)
		(width 0.10795)
		(layer "B.Cu")
		(net "BMC_M_DQ11")
	)
	(segment
		(start 426.40377 -32.346138)
		(end 426.444156 -32.306006)
		(width 0.10795)
		(layer "B.Cu")
		(net "BMC_M_DQ11")
	)
	(segment
		(start 438.78246 -27.8384)
		(end 436.193438 -27.8384)
		(width 0.10795)
		(layer "B.Cu")
		(net "BMC_M_DQ11")
	)
	(segment
		(start 430.16551 -29.96819)
		(end 430.489614 -29.644086)
		(width 0.10795)
		(layer "B.Cu")
		(net "BMC_M_DQ11")
	)
	(segment
		(start 439.017664 -26.859992)
		(end 438.297066 -26.859992)
		(width 0.10795)
		(layer "B.Cu")
		(net "BMC_M_DQ11")
	)
	(segment
		(start 437.721756 -26.6319)
		(end 437.721756 -26.53538)
		(width 0.10795)
		(layer "B.Cu")
		(net "BMC_M_DQ11")
	)
	(segment
		(start 426.61078 -32.236918)
		(end 427.522894 -32.236918)
		(width 0.10795)
		(layer "B.Cu")
		(net "BMC_M_DQ11")
	)
	(segment
		(start 429.511968 -30.006544)
		(end 429.550576 -29.967936)
		(width 0.10795)
		(layer "B.Cu")
		(net "BMC_M_DQ11")
	)
	(segment
		(start 438.297066 -27.349196)
		(end 438.78246 -27.349196)
		(width 0.10795)
		(layer "B.Cu")
		(net "BMC_M_DQ11")
	)
	(segment
		(start 433.709826 -29.571442)
		(end 431.259488 -29.571442)
		(width 0.10795)
		(layer "B.Cu")
		(net "BMC_M_DQ11")
	)
	(segment
		(start 429.512222 -30.314138)
		(end 429.511968 -30.313884)
		(width 0.10795)
		(layer "B.Cu")
		(net "BMC_M_DQ11")
	)
	(segment
		(start 421.89019 -32.534606)
		(end 421.89019 -32.236664)
		(width 0.10795)
		(layer "B.Cu")
		(net "BMC_M_DQ11")
	)
	(segment
		(start 430.664874 -29.571442)
		(end 431.259488 -29.571442)
		(width 0.10795)
		(layer "B.Cu")
		(net "BMC_M_DQ11")
	)
	(segment
		(start 428.161196 -31.972504)
		(end 429.512222 -30.621478)
		(width 0.10795)
		(layer "B.Cu")
		(net "BMC_M_DQ11")
	)
	(segment
		(start 437.886348 -26.370788)
		(end 439.017664 -26.370788)
		(width 0.10795)
		(layer "B.Cu")
		(net "BMC_M_DQ11")
	)
	(segment
		(start 424.378882 -32.466026)
		(end 426.114718 -32.466026)
		(width 0.10795)
		(layer "B.Cu")
		(net "BMC_M_DQ11")
	)
	(segment
		(start 435.674262 -28.053538)
		(end 434.47208 -29.25572)
		(width 0.10795)
		(layer "B.Cu")
		(net "BMC_M_DQ11")
	)
	(segment
		(start 429.857916 -29.967936)
		(end 429.85817 -29.96819)
		(width 0.10795)
		(layer "B.Cu")
		(net "BMC_M_DQ11")
	)
	(segment
		(start 423.770044 -32.216852)
		(end 423.822876 -32.269684)
		(width 0.10795)
		(layer "B.Cu")
		(net "BMC_M_DQ11")
	)
	(arc
		(start 429.511968 -30.313884)
		(mid 429.44839 -30.160214)
		(end 429.511968 -30.006544)
		(width 0.10795)
		(layer "B.Cu")
		(net "BMC_M_DQ11")
	)
	(arc
		(start 426.444156 -32.306006)
		(mid 426.483851 -32.274044)
		(end 426.5295 -32.251396)
		(width 0.10795)
		(layer "B.Cu")
		(net "BMC_M_DQ11")
	)
	(arc
		(start 429.512222 -30.621478)
		(mid 429.5758 -30.467808)
		(end 429.512222 -30.314138)
		(width 0.10795)
		(layer "B.Cu")
		(net "BMC_M_DQ11")
	)
	(arc
		(start 434.47208 -29.25572)
		(mid 434.122341 -29.489345)
		(end 433.709826 -29.571442)
		(width 0.10795)
		(layer "B.Cu")
		(net "BMC_M_DQ11")
	)
	(arc
		(start 436.193438 -27.8384)
		(mid 435.912442 -27.894311)
		(end 435.674262 -28.053538)
		(width 0.10795)
		(layer "B.Cu")
		(net "BMC_M_DQ11")
	)
	(arc
		(start 426.114718 -32.466026)
		(mid 426.271159 -32.434814)
		(end 426.40377 -32.346138)
		(width 0.10795)
		(layer "B.Cu")
		(net "BMC_M_DQ11")
	)
	(arc
		(start 430.489614 -29.644086)
		(mid 430.57001 -29.590304)
		(end 430.664874 -29.571442)
		(width 0.10795)
		(layer "B.Cu")
		(net "BMC_M_DQ11")
	)
	(arc
		(start 421.89019 -32.236664)
		(mid 421.925751 -32.150813)
		(end 422.011602 -32.115252)
		(width 0.10795)
		(layer "B.Cu")
		(net "BMC_M_DQ11")
	)
	(arc
		(start 438.297066 -26.859992)
		(mid 438.052464 -27.104594)
		(end 438.297066 -27.349196)
		(width 0.10795)
		(layer "B.Cu")
		(net "BMC_M_DQ11")
	)
	(arc
		(start 429.85817 -29.96819)
		(mid 430.01184 -30.031768)
		(end 430.16551 -29.96819)
		(width 0.10795)
		(layer "B.Cu")
		(net "BMC_M_DQ11")
	)
	(arc
		(start 427.522894 -32.236918)
		(mid 427.868348 -32.168203)
		(end 428.161196 -31.972504)
		(width 0.10795)
		(layer "B.Cu")
		(net "BMC_M_DQ11")
	)
	(arc
		(start 439.017664 -26.370788)
		(mid 439.262266 -26.61539)
		(end 439.017664 -26.859992)
		(width 0.10795)
		(layer "B.Cu")
		(net "BMC_M_DQ11")
	)
	(arc
		(start 424.304714 -32.469328)
		(mid 424.341835 -32.468512)
		(end 424.378882 -32.466026)
		(width 0.10795)
		(layer "B.Cu")
		(net "BMC_M_DQ11")
	)
	(arc
		(start 429.550576 -29.967936)
		(mid 429.704246 -29.904358)
		(end 429.857916 -29.967936)
		(width 0.10795)
		(layer "B.Cu")
		(net "BMC_M_DQ11")
	)
	(arc
		(start 423.822876 -32.269684)
		(mid 424.043945 -32.417398)
		(end 424.304714 -32.469328)
		(width 0.10795)
		(layer "B.Cu")
		(net "BMC_M_DQ11")
	)
	(arc
		(start 423.52468 -32.115252)
		(mid 423.657457 -32.141663)
		(end 423.770044 -32.216852)
		(width 0.10795)
		(layer "B.Cu")
		(net "BMC_M_DQ11")
	)
	(arc
		(start 426.5295 -32.251396)
		(mid 426.569502 -32.24058)
		(end 426.61078 -32.236918)
		(width 0.10795)
		(layer "B.Cu")
		(net "BMC_M_DQ11")
	)
	(arc
		(start 437.721756 -26.53538)
		(mid 437.769964 -26.418996)
		(end 437.886348 -26.370788)
		(width 0.10795)
		(layer "B.Cu")
		(net "BMC_M_DQ11")
	)
	(arc
		(start 438.78246 -27.349196)
		(mid 439.027062 -27.593798)
		(end 438.78246 -27.8384)
		(width 0.10795)
		(layer "B.Cu")
		(net "BMC_M_DQ11")
	)
	(segment
		(start 441.321952 -27.031696)
		(end 440.922156 -26.6319)
		(width 0.10795)
		(layer "F.Cu")
		(net "BMC_M_DQ10")
	)
	(segment
		(start 422.29024 -31.33471)
		(end 422.69029 -30.93466)
		(width 0.089408)
		(layer "F.Cu")
		(net "BMC_M_DQ10")
	)
	(segment
		(start 441.321952 -27.032458)
		(end 441.321952 -27.031696)
		(width 0.10795)
		(layer "F.Cu")
		(net "BMC_M_DQ10")
	)
	(via
		(at 422.69029 -30.93466)
		(size 0.4572)
		(drill 0.2032)
		(layers "F.Cu" "B.Cu")
		(net "BMC_M_DQ10")
	)
	(via
		(at 440.922156 -26.6319)
		(size 0.4572)
		(drill 0.2032)
		(layers "F.Cu" "B.Cu")
		(net "BMC_M_DQ10")
	)
	(via
		(at 425.017184 -29.421328)
		(size 0.508)
		(drill 0.254)
		(layers "F.Cu" "B.Cu")
		(net "BMC_M_DQ10")
	)
	(segment
		(start 425.588176 -28.284932)
		(end 425.588176 -28.468574)
		(width 0.10795)
		(layer "B.Cu")
		(net "BMC_M_DQ10")
	)
	(segment
		(start 425.318174 -29.120338)
		(end 425.017184 -29.421328)
		(width 0.10795)
		(layer "B.Cu")
		(net "BMC_M_DQ10")
	)
	(segment
		(start 439.314336 -24.478488)
		(end 439.160412 -24.632412)
		(width 0.10795)
		(layer "B.Cu")
		(net "BMC_M_DQ10")
	)
	(segment
		(start 425.017184 -29.421328)
		(end 424.561762 -29.87675)
		(width 0.10795)
		(layer "B.Cu")
		(net "BMC_M_DQ10")
	)
	(segment
		(start 423.874946 -30.16123)
		(end 423.69867 -30.16123)
		(width 0.10795)
		(layer "B.Cu")
		(net "BMC_M_DQ10")
	)
	(segment
		(start 436.952898 -23.623524)
		(end 433.625244 -23.623524)
		(width 0.10795)
		(layer "B.Cu")
		(net "BMC_M_DQ10")
	)
	(segment
		(start 440.252358 -25.616154)
		(end 440.363864 -25.504648)
		(width 0.10795)
		(layer "B.Cu")
		(net "BMC_M_DQ10")
	)
	(segment
		(start 439.560462 -24.924258)
		(end 439.660284 -24.824436)
		(width 0.10795)
		(layer "B.Cu")
		(net "BMC_M_DQ10")
	)
	(segment
		(start 423.297604 -30.327346)
		(end 422.69029 -30.93466)
		(width 0.10795)
		(layer "B.Cu")
		(net "BMC_M_DQ10")
	)
	(segment
		(start 431.037492 -25.698704)
		(end 428.24019 -25.698704)
		(width 0.10795)
		(layer "B.Cu")
		(net "BMC_M_DQ10")
	)
	(segment
		(start 427.23562 -26.114756)
		(end 425.958 -27.392376)
		(width 0.10795)
		(layer "B.Cu")
		(net "BMC_M_DQ10")
	)
	(segment
		(start 438.922668 -24.632412)
		(end 438.860946 -24.57069)
		(width 0.10795)
		(layer "B.Cu")
		(net "BMC_M_DQ10")
	)
	(segment
		(start 432.978306 -23.891494)
		(end 431.265584 -25.604216)
		(width 0.10795)
		(layer "B.Cu")
		(net "BMC_M_DQ10")
	)
	(segment
		(start 440.017916 -25.1587)
		(end 439.90641 -25.270206)
		(width 0.10795)
		(layer "B.Cu")
		(net "BMC_M_DQ10")
	)
	(segment
		(start 440.922156 -26.6319)
		(end 440.252358 -25.962102)
		(width 0.10795)
		(layer "B.Cu")
		(net "BMC_M_DQ10")
	)
	(arc
		(start 433.625244 -23.623524)
		(mid 433.275124 -23.693167)
		(end 432.978306 -23.891494)
		(width 0.10795)
		(layer "B.Cu")
		(net "BMC_M_DQ10")
	)
	(arc
		(start 425.588176 -28.468574)
		(mid 425.518011 -28.821319)
		(end 425.318174 -29.120338)
		(width 0.10795)
		(layer "B.Cu")
		(net "BMC_M_DQ10")
	)
	(arc
		(start 425.958 -27.392376)
		(mid 425.684292 -27.801869)
		(end 425.588176 -28.284932)
		(width 0.10795)
		(layer "B.Cu")
		(net "BMC_M_DQ10")
	)
	(arc
		(start 431.265584 -25.604216)
		(mid 431.160935 -25.674141)
		(end 431.037492 -25.698704)
		(width 0.10795)
		(layer "B.Cu")
		(net "BMC_M_DQ10")
	)
	(arc
		(start 439.90641 -25.270206)
		(mid 439.560462 -25.270206)
		(end 439.560462 -24.924258)
		(width 0.10795)
		(layer "B.Cu")
		(net "BMC_M_DQ10")
	)
	(arc
		(start 428.24019 -25.698704)
		(mid 427.696541 -25.806842)
		(end 427.23562 -26.114756)
		(width 0.10795)
		(layer "B.Cu")
		(net "BMC_M_DQ10")
	)
	(arc
		(start 440.363864 -25.504648)
		(mid 440.363864 -25.1587)
		(end 440.017916 -25.1587)
		(width 0.10795)
		(layer "B.Cu")
		(net "BMC_M_DQ10")
	)
	(arc
		(start 440.252358 -25.962102)
		(mid 440.18071 -25.789128)
		(end 440.252358 -25.616154)
		(width 0.10795)
		(layer "B.Cu")
		(net "BMC_M_DQ10")
	)
	(arc
		(start 438.860946 -24.57069)
		(mid 438.70709 -24.42363)
		(end 438.546748 -24.28367)
		(width 0.10795)
		(layer "B.Cu")
		(net "BMC_M_DQ10")
	)
	(arc
		(start 438.546748 -24.28367)
		(mid 437.815483 -23.795055)
		(end 436.952898 -23.623524)
		(width 0.10795)
		(layer "B.Cu")
		(net "BMC_M_DQ10")
	)
	(arc
		(start 439.160412 -24.632412)
		(mid 439.04154 -24.68165)
		(end 438.922668 -24.632412)
		(width 0.10795)
		(layer "B.Cu")
		(net "BMC_M_DQ10")
	)
	(arc
		(start 423.69867 -30.16123)
		(mid 423.481619 -30.204404)
		(end 423.297604 -30.327346)
		(width 0.10795)
		(layer "B.Cu")
		(net "BMC_M_DQ10")
	)
	(arc
		(start 424.561762 -29.87675)
		(mid 424.246648 -30.087302)
		(end 423.874946 -30.16123)
		(width 0.10795)
		(layer "B.Cu")
		(net "BMC_M_DQ10")
	)
	(arc
		(start 439.660284 -24.824436)
		(mid 439.660284 -24.478488)
		(end 439.314336 -24.478488)
		(width 0.10795)
		(layer "B.Cu")
		(net "BMC_M_DQ10")
	)
	(segment
		(start 432.420014 -29.584904)
		(end 432.420014 -30.106874)
		(width 0.10795)
		(layer "F.Cu")
		(net "BMC_M_DQ1")
	)
	(segment
		(start 429.837088 -30.320488)
		(end 429.836834 -30.320488)
		(width 0.10795)
		(layer "F.Cu")
		(net "BMC_M_DQ1")
	)
	(segment
		(start 434.37683 -29.584904)
		(end 434.37683 -30.089348)
		(width 0.10795)
		(layer "F.Cu")
		(net "BMC_M_DQ1")
	)
	(segment
		(start 434.866034 -30.089348)
		(end 434.866034 -29.584904)
		(width 0.10795)
		(layer "F.Cu")
		(net "BMC_M_DQ1")
	)
	(segment
		(start 430.956466 -29.340302)
		(end 431.197004 -29.340302)
		(width 0.10795)
		(layer "F.Cu")
		(net "BMC_M_DQ1")
	)
	(segment
		(start 436.450994 -29.0195)
		(end 437.43499 -29.0195)
		(width 0.10795)
		(layer "F.Cu")
		(net "BMC_M_DQ1")
	)
	(segment
		(start 429.836834 -30.320488)
		(end 426.555662 -33.60166)
		(width 0.10795)
		(layer "F.Cu")
		(net "BMC_M_DQ1")
	)
	(segment
		(start 424.358816 -34.121852)
		(end 422.195244 -34.121852)
		(width 0.10795)
		(layer "F.Cu")
		(net "BMC_M_DQ1")
	)
	(segment
		(start 437.902858 -29.213302)
		(end 438.12206 -29.432504)
		(width 0.10795)
		(layer "F.Cu")
		(net "BMC_M_DQ1")
	)
	(segment
		(start 421.651684 -33.896554)
		(end 421.49014 -33.734756)
		(width 0.10795)
		(layer "F.Cu")
		(net "BMC_M_DQ1")
	)
	(segment
		(start 432.909218 -30.106874)
		(end 432.909218 -29.584904)
		(width 0.10795)
		(layer "F.Cu")
		(net "BMC_M_DQ1")
	)
	(segment
		(start 433.887626 -30.10662)
		(end 433.887626 -29.584904)
		(width 0.10795)
		(layer "F.Cu")
		(net "BMC_M_DQ1")
	)
	(segment
		(start 429.837088 -30.320488)
		(end 429.837088 -30.320234)
		(width 0.10795)
		(layer "F.Cu")
		(net "BMC_M_DQ1")
	)
	(segment
		(start 433.398422 -29.584904)
		(end 433.398422 -30.10662)
		(width 0.10795)
		(layer "F.Cu")
		(net "BMC_M_DQ1")
	)
	(segment
		(start 435.110636 -29.340302)
		(end 435.676548 -29.340302)
		(width 0.10795)
		(layer "F.Cu")
		(net "BMC_M_DQ1")
	)
	(segment
		(start 429.837088 -30.320234)
		(end 430.718468 -29.438854)
		(width 0.10795)
		(layer "F.Cu")
		(net "BMC_M_DQ1")
	)
	(segment
		(start 424.774868 -34.327084)
		(end 424.718734 -34.27095)
		(width 0.10795)
		(layer "F.Cu")
		(net "BMC_M_DQ1")
	)
	(segment
		(start 426.358558 -34.077402)
		(end 426.269404 -34.166556)
		(width 0.10795)
		(layer "F.Cu")
		(net "BMC_M_DQ1")
	)
	(segment
		(start 425.473368 -34.496248)
		(end 425.1833 -34.496248)
		(width 0.10795)
		(layer "F.Cu")
		(net "BMC_M_DQ1")
	)
	(segment
		(start 431.441606 -29.584904)
		(end 431.441606 -30.10662)
		(width 0.10795)
		(layer "F.Cu")
		(net "BMC_M_DQ1")
	)
	(segment
		(start 431.93081 -30.10662)
		(end 431.93081 -29.584904)
		(width 0.10795)
		(layer "F.Cu")
		(net "BMC_M_DQ1")
	)
	(via
		(at 429.837088 -30.320488)
		(size 0.508)
		(drill 0.254)
		(layers "F.Cu" "B.Cu")
		(net "BMC_M_DQ1")
	)
	(arc
		(start 433.398422 -30.10662)
		(mid 433.643024 -30.351222)
		(end 433.887626 -30.10662)
		(width 0.10795)
		(layer "F.Cu")
		(net "BMC_M_DQ1")
	)
	(arc
		(start 432.909218 -29.584904)
		(mid 433.15382 -29.340302)
		(end 433.398422 -29.584904)
		(width 0.10795)
		(layer "F.Cu")
		(net "BMC_M_DQ1")
	)
	(arc
		(start 426.269404 -34.166556)
		(mid 425.90418 -34.410591)
		(end 425.473368 -34.496248)
		(width 0.10795)
		(layer "F.Cu")
		(net "BMC_M_DQ1")
	)
	(arc
		(start 431.441606 -30.10662)
		(mid 431.686208 -30.351222)
		(end 431.93081 -30.10662)
		(width 0.10795)
		(layer "F.Cu")
		(net "BMC_M_DQ1")
	)
	(arc
		(start 426.555662 -33.60166)
		(mid 426.506606 -33.675078)
		(end 426.489368 -33.76168)
		(width 0.10795)
		(layer "F.Cu")
		(net "BMC_M_DQ1")
	)
	(arc
		(start 437.43499 -29.0195)
		(mid 437.6882 -29.069867)
		(end 437.902858 -29.213302)
		(width 0.10795)
		(layer "F.Cu")
		(net "BMC_M_DQ1")
	)
	(arc
		(start 431.93081 -29.584904)
		(mid 432.175412 -29.340302)
		(end 432.420014 -29.584904)
		(width 0.10795)
		(layer "F.Cu")
		(net "BMC_M_DQ1")
	)
	(arc
		(start 422.195244 -34.121852)
		(mid 421.901043 -34.063296)
		(end 421.651684 -33.896554)
		(width 0.10795)
		(layer "F.Cu")
		(net "BMC_M_DQ1")
	)
	(arc
		(start 434.37683 -30.089348)
		(mid 434.621432 -30.33395)
		(end 434.866034 -30.089348)
		(width 0.10795)
		(layer "F.Cu")
		(net "BMC_M_DQ1")
	)
	(arc
		(start 435.676548 -29.340302)
		(mid 435.846748 -29.306447)
		(end 435.991 -29.21)
		(width 0.10795)
		(layer "F.Cu")
		(net "BMC_M_DQ1")
	)
	(arc
		(start 434.866034 -29.584904)
		(mid 434.937676 -29.411944)
		(end 435.110636 -29.340302)
		(width 0.10795)
		(layer "F.Cu")
		(net "BMC_M_DQ1")
	)
	(arc
		(start 435.991 -29.21)
		(mid 436.202047 -29.068983)
		(end 436.450994 -29.0195)
		(width 0.10795)
		(layer "F.Cu")
		(net "BMC_M_DQ1")
	)
	(arc
		(start 425.1833 -34.496248)
		(mid 424.962264 -34.452281)
		(end 424.774868 -34.327084)
		(width 0.10795)
		(layer "F.Cu")
		(net "BMC_M_DQ1")
	)
	(arc
		(start 424.718734 -34.27095)
		(mid 424.553602 -34.160612)
		(end 424.358816 -34.121852)
		(width 0.10795)
		(layer "F.Cu")
		(net "BMC_M_DQ1")
	)
	(arc
		(start 432.420014 -30.106874)
		(mid 432.664616 -30.351476)
		(end 432.909218 -30.106874)
		(width 0.10795)
		(layer "F.Cu")
		(net "BMC_M_DQ1")
	)
	(arc
		(start 430.718468 -29.438854)
		(mid 430.827662 -29.365893)
		(end 430.956466 -29.340302)
		(width 0.10795)
		(layer "F.Cu")
		(net "BMC_M_DQ1")
	)
	(arc
		(start 426.489368 -33.76168)
		(mid 426.455378 -33.93256)
		(end 426.358558 -34.077402)
		(width 0.10795)
		(layer "F.Cu")
		(net "BMC_M_DQ1")
	)
	(arc
		(start 431.197004 -29.340302)
		(mid 431.369964 -29.411944)
		(end 431.441606 -29.584904)
		(width 0.10795)
		(layer "F.Cu")
		(net "BMC_M_DQ1")
	)
	(arc
		(start 433.887626 -29.584904)
		(mid 434.132228 -29.340302)
		(end 434.37683 -29.584904)
		(width 0.10795)
		(layer "F.Cu")
		(net "BMC_M_DQ1")
	)
	(segment
		(start 442.122052 -30.232604)
		(end 441.722256 -30.6324)
		(width 0.10795)
		(layer "F.Cu")
		(net "BMC_M_DQ0")
	)
	(segment
		(start 419.890194 -33.734756)
		(end 420.290244 -34.134806)
		(width 0.089408)
		(layer "F.Cu")
		(net "BMC_M_DQ0")
	)
	(via
		(at 420.290244 -34.134806)
		(size 0.4572)
		(drill 0.2032)
		(layers "F.Cu" "B.Cu")
		(net "BMC_M_DQ0")
	)
	(via
		(at 441.722256 -30.6324)
		(size 0.4572)
		(drill 0.2032)
		(layers "F.Cu" "B.Cu")
		(net "BMC_M_DQ0")
	)
	(segment
		(start 434.697124 -29.498798)
		(end 434.58892 -29.499052)
		(width 0.089408)
		(layer "In2.Cu")
		(net "BMC_M_DQ0")
	)
	(segment
		(start 440.084718 -30.212284)
		(end 439.570622 -29.698188)
		(width 0.089408)
		(layer "In2.Cu")
		(net "BMC_M_DQ0")
	)
	(segment
		(start 434.40731 -29.318204)
		(end 434.40731 -29.31795)
		(width 0.089408)
		(layer "In2.Cu")
		(net "BMC_M_DQ0")
	)
	(segment
		(start 441.722256 -30.6324)
		(end 441.09894 -30.6324)
		(width 0.089408)
		(layer "In2.Cu")
		(net "BMC_M_DQ0")
	)
	(segment
		(start 436.11292 -29.116782)
		(end 436.016146 -29.117036)
		(width 0.089408)
		(layer "In2.Cu")
		(net "BMC_M_DQ0")
	)
	(segment
		(start 435.64175 -29.49321)
		(end 435.525672 -29.493464)
		(width 0.089408)
		(layer "In2.Cu")
		(net "BMC_M_DQ0")
	)
	(segment
		(start 434.877718 -29.317188)
		(end 434.877718 -29.317442)
		(width 0.089408)
		(layer "In2.Cu")
		(net "BMC_M_DQ0")
	)
	(segment
		(start 434.208936 -29.120084)
		(end 432.264312 -29.122624)
		(width 0.089408)
		(layer "In2.Cu")
		(net "BMC_M_DQ0")
	)
	(segment
		(start 420.674546 -33.363408)
		(end 420.674546 -33.363662)
		(width 0.089408)
		(layer "In2.Cu")
		(net "BMC_M_DQ0")
	)
	(segment
		(start 435.818534 -29.31541)
		(end 435.818534 -29.315918)
		(width 0.089408)
		(layer "In2.Cu")
		(net "BMC_M_DQ0")
	)
	(segment
		(start 423.865294 -32.92348)
		(end 421.114728 -32.923226)
		(width 0.089408)
		(layer "In2.Cu")
		(net "BMC_M_DQ0")
	)
	(segment
		(start 435.149752 -29.11856)
		(end 435.075584 -29.118814)
		(width 0.089408)
		(layer "In2.Cu")
		(net "BMC_M_DQ0")
	)
	(segment
		(start 424.382184 -32.92348)
		(end 423.865294 -32.92348)
		(width 0.089408)
		(layer "In2.Cu")
		(net "BMC_M_DQ0")
	)
	(segment
		(start 438.129426 -29.028898)
		(end 436.32501 -29.028898)
		(width 0.089408)
		(layer "In2.Cu")
		(net "BMC_M_DQ0")
	)
	(segment
		(start 429.340772 -30.067504)
		(end 427.617636 -31.79064)
		(width 0.089408)
		(layer "In2.Cu")
		(net "BMC_M_DQ0")
	)
	(segment
		(start 426.78477 -32.135572)
		(end 426.28439 -32.135572)
		(width 0.089408)
		(layer "In2.Cu")
		(net "BMC_M_DQ0")
	)
	(segment
		(start 420.400734 -34.024316)
		(end 420.290244 -34.134806)
		(width 0.089408)
		(layer "In2.Cu")
		(net "BMC_M_DQ0")
	)
	(segment
		(start 432.264312 -29.122624)
		(end 432.262534 -29.123132)
		(width 0.089408)
		(layer "In2.Cu")
		(net "BMC_M_DQ0")
	)
	(arc
		(start 435.818534 -29.315918)
		(mid 435.76686 -29.441177)
		(end 435.64175 -29.49321)
		(width 0.089408)
		(layer "In2.Cu")
		(net "BMC_M_DQ0")
	)
	(arc
		(start 420.674546 -33.363662)
		(mid 420.603384 -33.721238)
		(end 420.400734 -34.024316)
		(width 0.089408)
		(layer "In2.Cu")
		(net "BMC_M_DQ0")
	)
	(arc
		(start 425.492164 -32.46374)
		(mid 424.982901 -32.804019)
		(end 424.382184 -32.92348)
		(width 0.089408)
		(layer "In2.Cu")
		(net "BMC_M_DQ0")
	)
	(arc
		(start 436.016146 -29.117036)
		(mid 435.876292 -29.175333)
		(end 435.818534 -29.31541)
		(width 0.089408)
		(layer "In2.Cu")
		(net "BMC_M_DQ0")
	)
	(arc
		(start 429.389286 -30.030166)
		(mid 429.36496 -30.048745)
		(end 429.340772 -30.067504)
		(width 0.089408)
		(layer "In2.Cu")
		(net "BMC_M_DQ0")
	)
	(arc
		(start 439.570622 -29.698188)
		(mid 438.909301 -29.235904)
		(end 438.129426 -29.028898)
		(width 0.089408)
		(layer "In2.Cu")
		(net "BMC_M_DQ0")
	)
	(arc
		(start 434.40731 -29.31795)
		(mid 434.349102 -29.177932)
		(end 434.208936 -29.120084)
		(width 0.089408)
		(layer "In2.Cu")
		(net "BMC_M_DQ0")
	)
	(arc
		(start 434.58892 -29.499052)
		(mid 434.460623 -29.446278)
		(end 434.40731 -29.318204)
		(width 0.089408)
		(layer "In2.Cu")
		(net "BMC_M_DQ0")
	)
	(arc
		(start 421.114728 -32.923226)
		(mid 420.803472 -33.052152)
		(end 420.674546 -33.363408)
		(width 0.089408)
		(layer "In2.Cu")
		(net "BMC_M_DQ0")
	)
	(arc
		(start 426.28439 -32.135572)
		(mid 425.855634 -32.220857)
		(end 425.492164 -32.46374)
		(width 0.089408)
		(layer "In2.Cu")
		(net "BMC_M_DQ0")
	)
	(arc
		(start 436.32501 -29.028898)
		(mid 436.253372 -29.043148)
		(end 436.192676 -29.083762)
		(width 0.089408)
		(layer "In2.Cu")
		(net "BMC_M_DQ0")
	)
	(arc
		(start 435.075584 -29.118814)
		(mid 434.935566 -29.177022)
		(end 434.877718 -29.317188)
		(width 0.089408)
		(layer "In2.Cu")
		(net "BMC_M_DQ0")
	)
	(arc
		(start 441.09894 -30.6324)
		(mid 440.550043 -30.523218)
		(end 440.084718 -30.212284)
		(width 0.089408)
		(layer "In2.Cu")
		(net "BMC_M_DQ0")
	)
	(arc
		(start 435.525672 -29.493464)
		(mid 435.400158 -29.441791)
		(end 435.348126 -29.316426)
		(width 0.089408)
		(layer "In2.Cu")
		(net "BMC_M_DQ0")
	)
	(arc
		(start 432.262534 -29.123132)
		(mid 430.756028 -29.355277)
		(end 429.389286 -30.030166)
		(width 0.089408)
		(layer "In2.Cu")
		(net "BMC_M_DQ0")
	)
	(arc
		(start 435.348126 -29.316426)
		(mid 435.289918 -29.176408)
		(end 435.149752 -29.11856)
		(width 0.089408)
		(layer "In2.Cu")
		(net "BMC_M_DQ0")
	)
	(arc
		(start 427.617636 -31.79064)
		(mid 427.235514 -32.045966)
		(end 426.78477 -32.135572)
		(width 0.089408)
		(layer "In2.Cu")
		(net "BMC_M_DQ0")
	)
	(arc
		(start 436.192676 -29.083762)
		(mid 436.156084 -29.108212)
		(end 436.11292 -29.116782)
		(width 0.089408)
		(layer "In2.Cu")
		(net "BMC_M_DQ0")
	)
	(arc
		(start 434.877718 -29.317442)
		(mid 434.824944 -29.445485)
		(end 434.697124 -29.498798)
		(width 0.089408)
		(layer "In2.Cu")
		(net "BMC_M_DQ0")
	)
	(segment
		(start 442.122052 -28.632404)
		(end 441.852304 -28.362656)
		(width 0.10795)
		(layer "F.Cu")
		(net "BMC_M_DM1")
	)
	(segment
		(start 427.565566 -31.821374)
		(end 430.530762 -28.856178)
		(width 0.10795)
		(layer "F.Cu")
		(net "BMC_M_DM1")
	)
	(segment
		(start 430.74971 -28.7655)
		(end 432.28006 -28.7655)
		(width 0.10795)
		(layer "F.Cu")
		(net "BMC_M_DM1")
	)
	(segment
		(start 441.53709 -28.2321)
		(end 440.826144 -28.2321)
		(width 0.10795)
		(layer "F.Cu")
		(net "BMC_M_DM1")
	)
	(segment
		(start 434.18252 -28.7655)
		(end 432.28006 -28.7655)
		(width 0.10795)
		(layer "F.Cu")
		(net "BMC_M_DM1")
	)
	(segment
		(start 440.30646 -27.712416)
		(end 440.30646 -26.901394)
		(width 0.10795)
		(layer "F.Cu")
		(net "BMC_M_DM1")
	)
	(segment
		(start 424.607228 -32.431736)
		(end 426.017182 -32.431736)
		(width 0.10795)
		(layer "F.Cu")
		(net "BMC_M_DM1")
	)
	(segment
		(start 437.35244 -24.24557)
		(end 436.085488 -24.24557)
		(width 0.10795)
		(layer "F.Cu")
		(net "BMC_M_DM1")
	)
	(segment
		(start 426.412914 -32.246316)
		(end 426.5295 -32.19323)
		(width 0.10795)
		(layer "F.Cu")
		(net "BMC_M_DM1")
	)
	(segment
		(start 440.143646 -26.508202)
		(end 438.254648 -24.619204)
		(width 0.10795)
		(layer "F.Cu")
		(net "BMC_M_DM1")
	)
	(segment
		(start 435.454806 -24.876252)
		(end 435.454806 -27.493214)
		(width 0.10795)
		(layer "F.Cu")
		(net "BMC_M_DM1")
	)
	(segment
		(start 423.890186 -32.134556)
		(end 423.89044 -32.13481)
		(width 0.10795)
		(layer "F.Cu")
		(net "BMC_M_DM1")
	)
	(segment
		(start 426.5295 -32.19323)
		(end 426.578014 -32.171132)
		(width 0.10795)
		(layer "F.Cu")
		(net "BMC_M_DM1")
	)
	(via
		(at 432.28006 -28.7655)
		(size 0.508)
		(drill 0.254)
		(layers "F.Cu" "B.Cu")
		(net "BMC_M_DM1")
	)
	(arc
		(start 430.530762 -28.856178)
		(mid 430.631216 -28.789057)
		(end 430.74971 -28.7655)
		(width 0.10795)
		(layer "F.Cu")
		(net "BMC_M_DM1")
	)
	(arc
		(start 426.335444 -32.29991)
		(mid 426.37176 -32.269617)
		(end 426.412914 -32.246316)
		(width 0.10795)
		(layer "F.Cu")
		(net "BMC_M_DM1")
	)
	(arc
		(start 423.89044 -32.13481)
		(mid 424.219305 -32.354551)
		(end 424.607228 -32.431736)
		(width 0.10795)
		(layer "F.Cu")
		(net "BMC_M_DM1")
	)
	(arc
		(start 440.826144 -28.2321)
		(mid 440.458672 -28.079888)
		(end 440.30646 -27.712416)
		(width 0.10795)
		(layer "F.Cu")
		(net "BMC_M_DM1")
	)
	(arc
		(start 436.085488 -24.24557)
		(mid 435.639528 -24.430292)
		(end 435.454806 -24.876252)
		(width 0.10795)
		(layer "F.Cu")
		(net "BMC_M_DM1")
	)
	(arc
		(start 426.017182 -32.431736)
		(mid 426.189423 -32.397475)
		(end 426.335444 -32.29991)
		(width 0.10795)
		(layer "F.Cu")
		(net "BMC_M_DM1")
	)
	(arc
		(start 441.852304 -28.362656)
		(mid 441.707683 -28.266023)
		(end 441.53709 -28.2321)
		(width 0.10795)
		(layer "F.Cu")
		(net "BMC_M_DM1")
	)
	(arc
		(start 435.454806 -27.493214)
		(mid 435.082162 -28.392856)
		(end 434.18252 -28.7655)
		(width 0.10795)
		(layer "F.Cu")
		(net "BMC_M_DM1")
	)
	(arc
		(start 426.578014 -32.171132)
		(mid 426.724881 -32.122364)
		(end 426.87875 -32.105854)
		(width 0.10795)
		(layer "F.Cu")
		(net "BMC_M_DM1")
	)
	(arc
		(start 426.87875 -32.105854)
		(mid 427.250449 -32.031918)
		(end 427.565566 -31.821374)
		(width 0.10795)
		(layer "F.Cu")
		(net "BMC_M_DM1")
	)
	(arc
		(start 440.30646 -26.901394)
		(mid 440.264152 -26.688605)
		(end 440.143646 -26.508202)
		(width 0.10795)
		(layer "F.Cu")
		(net "BMC_M_DM1")
	)
	(arc
		(start 438.254648 -24.619204)
		(mid 437.840697 -24.342674)
		(end 437.35244 -24.24557)
		(width 0.10795)
		(layer "F.Cu")
		(net "BMC_M_DM1")
	)
	(segment
		(start 438.12206 -28.632404)
		(end 438.12206 -28.631896)
		(width 0.10795)
		(layer "F.Cu")
		(net "BMC_M_DM0")
	)
	(segment
		(start 438.12206 -28.631896)
		(end 438.521856 -28.2321)
		(width 0.10795)
		(layer "F.Cu")
		(net "BMC_M_DM0")
	)
	(segment
		(start 419.890194 -32.134556)
		(end 420.290244 -31.73476)
		(width 0.1016)
		(layer "F.Cu")
		(net "BMC_M_DM0")
	)
	(via
		(at 438.521856 -28.2321)
		(size 0.4572)
		(drill 0.2032)
		(layers "F.Cu" "B.Cu")
		(net "BMC_M_DM0")
	)
	(via
		(at 420.290244 -31.73476)
		(size 0.4572)
		(drill 0.2032)
		(layers "F.Cu" "B.Cu")
		(net "BMC_M_DM0")
	)
	(segment
		(start 433.724304 -27.879548)
		(end 433.724304 -27.651456)
		(width 0.089408)
		(layer "In2.Cu")
		(net "BMC_M_DM0")
	)
	(segment
		(start 431.842672 -27.87777)
		(end 431.842672 -27.662378)
		(width 0.089408)
		(layer "In2.Cu")
		(net "BMC_M_DM0")
	)
	(segment
		(start 432.31308 -27.65679)
		(end 432.31308 -27.87777)
		(width 0.089408)
		(layer "In2.Cu")
		(net "BMC_M_DM0")
	)
	(segment
		(start 425.984416 -29.478224)
		(end 425.941236 -29.521404)
		(width 0.089408)
		(layer "In2.Cu")
		(net "BMC_M_DM0")
	)
	(segment
		(start 425.210478 -30.89783)
		(end 424.540934 -31.567374)
		(width 0.089408)
		(layer "In2.Cu")
		(net "BMC_M_DM0")
	)
	(segment
		(start 438.521856 -28.2321)
		(end 438.35193 -28.062174)
		(width 0.089408)
		(layer "In2.Cu")
		(net "BMC_M_DM0")
	)
	(segment
		(start 434.910484 -27.424126)
		(end 434.429916 -27.424126)
		(width 0.089408)
		(layer "In2.Cu")
		(net "BMC_M_DM0")
	)
	(segment
		(start 422.271444 -31.531052)
		(end 422.212008 -31.471616)
		(width 0.089408)
		(layer "In2.Cu")
		(net "BMC_M_DM0")
	)
	(segment
		(start 427.607222 -29.41701)
		(end 426.13199 -29.41701)
		(width 0.089408)
		(layer "In2.Cu")
		(net "BMC_M_DM0")
	)
	(segment
		(start 437.842406 -27.8511)
		(end 435.941216 -27.8511)
		(width 0.089408)
		(layer "In2.Cu")
		(net "BMC_M_DM0")
	)
	(segment
		(start 421.926258 -31.353252)
		(end 420.88689 -31.353252)
		(width 0.089408)
		(layer "In2.Cu")
		(net "BMC_M_DM0")
	)
	(segment
		(start 432.783488 -27.853386)
		(end 432.783488 -27.65679)
		(width 0.089408)
		(layer "In2.Cu")
		(net "BMC_M_DM0")
	)
	(segment
		(start 433.253896 -27.651456)
		(end 433.253896 -27.853386)
		(width 0.089408)
		(layer "In2.Cu")
		(net "BMC_M_DM0")
	)
	(segment
		(start 420.521892 -31.504636)
		(end 420.292276 -31.73476)
		(width 0.089408)
		(layer "In2.Cu")
		(net "BMC_M_DM0")
	)
	(segment
		(start 420.292276 -31.73476)
		(end 420.290244 -31.73476)
		(width 0.089408)
		(layer "In2.Cu")
		(net "BMC_M_DM0")
	)
	(segment
		(start 431.372264 -27.662378)
		(end 431.372264 -27.877262)
		(width 0.089408)
		(layer "In2.Cu")
		(net "BMC_M_DM0")
	)
	(segment
		(start 425.63288 -30.153356)
		(end 425.60113 -30.185106)
		(width 0.089408)
		(layer "In2.Cu")
		(net "BMC_M_DM0")
	)
	(segment
		(start 424.199558 -31.708852)
		(end 422.700704 -31.708852)
		(width 0.089408)
		(layer "In2.Cu")
		(net "BMC_M_DM0")
	)
	(segment
		(start 425.941236 -29.521404)
		(end 425.861734 -29.60116)
		(width 0.089408)
		(layer "In2.Cu")
		(net "BMC_M_DM0")
	)
	(segment
		(start 434.194712 -27.65933)
		(end 434.194712 -27.879548)
		(width 0.089408)
		(layer "In2.Cu")
		(net "BMC_M_DM0")
	)
	(segment
		(start 429.990758 -27.592528)
		(end 428.5615 -29.021786)
		(width 0.089408)
		(layer "In2.Cu")
		(net "BMC_M_DM0")
	)
	(segment
		(start 430.666652 -27.424126)
		(end 430.397158 -27.424126)
		(width 0.089408)
		(layer "In2.Cu")
		(net "BMC_M_DM0")
	)
	(segment
		(start 430.901856 -27.877262)
		(end 430.901856 -27.65933)
		(width 0.089408)
		(layer "In2.Cu")
		(net "BMC_M_DM0")
	)
	(arc
		(start 438.35193 -28.062174)
		(mid 438.118158 -27.905973)
		(end 437.842406 -27.8511)
		(width 0.089408)
		(layer "In2.Cu")
		(net "BMC_M_DM0")
	)
	(arc
		(start 425.60113 -30.185106)
		(mid 425.545844 -30.267847)
		(end 425.526454 -30.365446)
		(width 0.089408)
		(layer "In2.Cu")
		(net "BMC_M_DM0")
	)
	(arc
		(start 422.700704 -31.708852)
		(mid 422.468392 -31.662642)
		(end 422.271444 -31.531052)
		(width 0.089408)
		(layer "In2.Cu")
		(net "BMC_M_DM0")
	)
	(arc
		(start 425.861734 -29.60116)
		(mid 425.777555 -29.727004)
		(end 425.747942 -29.87548)
		(width 0.089408)
		(layer "In2.Cu")
		(net "BMC_M_DM0")
	)
	(arc
		(start 432.31308 -27.87777)
		(mid 432.077876 -28.112974)
		(end 431.842672 -27.87777)
		(width 0.089408)
		(layer "In2.Cu")
		(net "BMC_M_DM0")
	)
	(arc
		(start 435.240938 -27.561032)
		(mid 435.227846 -27.548325)
		(end 435.214268 -27.53614)
		(width 0.089408)
		(layer "In2.Cu")
		(net "BMC_M_DM0")
	)
	(arc
		(start 428.5615 -29.021786)
		(mid 428.123674 -29.314332)
		(end 427.607222 -29.41701)
		(width 0.089408)
		(layer "In2.Cu")
		(net "BMC_M_DM0")
	)
	(arc
		(start 424.540934 -31.567374)
		(mid 424.384324 -31.672081)
		(end 424.199558 -31.708852)
		(width 0.089408)
		(layer "In2.Cu")
		(net "BMC_M_DM0")
	)
	(arc
		(start 425.526454 -30.365446)
		(mid 425.401899 -30.651481)
		(end 425.210478 -30.89783)
		(width 0.089408)
		(layer "In2.Cu")
		(net "BMC_M_DM0")
	)
	(arc
		(start 422.212008 -31.471616)
		(mid 422.080905 -31.384016)
		(end 421.926258 -31.353252)
		(width 0.089408)
		(layer "In2.Cu")
		(net "BMC_M_DM0")
	)
	(arc
		(start 434.194712 -27.879548)
		(mid 433.959508 -28.114752)
		(end 433.724304 -27.879548)
		(width 0.089408)
		(layer "In2.Cu")
		(net "BMC_M_DM0")
	)
	(arc
		(start 434.429916 -27.424126)
		(mid 434.263602 -27.493016)
		(end 434.194712 -27.65933)
		(width 0.089408)
		(layer "In2.Cu")
		(net "BMC_M_DM0")
	)
	(arc
		(start 433.724304 -27.651456)
		(mid 433.4891 -27.416252)
		(end 433.253896 -27.651456)
		(width 0.089408)
		(layer "In2.Cu")
		(net "BMC_M_DM0")
	)
	(arc
		(start 433.253896 -27.853386)
		(mid 433.018692 -28.08859)
		(end 432.783488 -27.853386)
		(width 0.089408)
		(layer "In2.Cu")
		(net "BMC_M_DM0")
	)
	(arc
		(start 435.941216 -27.8511)
		(mid 435.562227 -27.775714)
		(end 435.240938 -27.561032)
		(width 0.089408)
		(layer "In2.Cu")
		(net "BMC_M_DM0")
	)
	(arc
		(start 435.214268 -27.53614)
		(mid 435.072384 -27.452998)
		(end 434.910484 -27.424126)
		(width 0.089408)
		(layer "In2.Cu")
		(net "BMC_M_DM0")
	)
	(arc
		(start 430.397158 -27.424126)
		(mid 430.177191 -27.46788)
		(end 429.990758 -27.592528)
		(width 0.089408)
		(layer "In2.Cu")
		(net "BMC_M_DM0")
	)
	(arc
		(start 431.372264 -27.877262)
		(mid 431.13706 -28.112466)
		(end 430.901856 -27.877262)
		(width 0.089408)
		(layer "In2.Cu")
		(net "BMC_M_DM0")
	)
	(arc
		(start 430.901856 -27.65933)
		(mid 430.832966 -27.493016)
		(end 430.666652 -27.424126)
		(width 0.089408)
		(layer "In2.Cu")
		(net "BMC_M_DM0")
	)
	(arc
		(start 432.783488 -27.65679)
		(mid 432.548284 -27.421586)
		(end 432.31308 -27.65679)
		(width 0.089408)
		(layer "In2.Cu")
		(net "BMC_M_DM0")
	)
	(arc
		(start 425.747942 -29.87548)
		(mid 425.718031 -30.025851)
		(end 425.63288 -30.153356)
		(width 0.089408)
		(layer "In2.Cu")
		(net "BMC_M_DM0")
	)
	(arc
		(start 431.842672 -27.662378)
		(mid 431.607468 -27.427174)
		(end 431.372264 -27.662378)
		(width 0.089408)
		(layer "In2.Cu")
		(net "BMC_M_DM0")
	)
	(arc
		(start 426.13199 -29.41701)
		(mid 426.05209 -29.432903)
		(end 425.984416 -29.478224)
		(width 0.089408)
		(layer "In2.Cu")
		(net "BMC_M_DM0")
	)
	(arc
		(start 420.88689 -31.353252)
		(mid 420.689322 -31.392604)
		(end 420.521892 -31.504636)
		(width 0.089408)
		(layer "In2.Cu")
		(net "BMC_M_DM0")
	)
	(segment
		(start 431.351182 -35.445446)
		(end 431.351182 -35.93465)
		(width 0.10795)
		(layer "F.Cu")
		(net "BMC_M_CS_N")
	)
	(segment
		(start 432.461162 -35.200844)
		(end 431.595784 -35.200844)
		(width 0.10795)
		(layer "F.Cu")
		(net "BMC_M_CS_N")
	)
	(segment
		(start 440.557666 -41.547034)
		(end 440.557666 -37.06876)
		(width 0.10795)
		(layer "F.Cu")
		(net "BMC_M_CS_N")
	)
	(segment
		(start 427.882812 -36.687252)
		(end 429.711104 -36.687252)
		(width 0.10795)
		(layer "F.Cu")
		(net "BMC_M_CS_N")
	)
	(segment
		(start 441.119006 -42.108374)
		(end 441.119006 -43.124374)
		(width 0.10795)
		(layer "F.Cu")
		(net "BMC_M_CS_N")
	)
	(segment
		(start 439.064146 -33.5788)
		(end 438.775856 -33.5788)
		(width 0.10795)
		(layer "F.Cu")
		(net "BMC_M_CS_N")
	)
	(segment
		(start 439.417206 -35.1155)
		(end 439.5216 -35.011106)
		(width 0.10795)
		(layer "F.Cu")
		(net "BMC_M_CS_N")
	)
	(segment
		(start 423.090086 -35.334702)
		(end 423.12844 -35.334702)
		(width 0.10795)
		(layer "F.Cu")
		(net "BMC_M_CS_N")
	)
	(segment
		(start 441.119006 -42.108374)
		(end 440.557666 -41.547034)
		(width 0.10795)
		(layer "F.Cu")
		(net "BMC_M_CS_N")
	)
	(segment
		(start 423.820844 -35.722052)
		(end 425.566332 -35.722052)
		(width 0.10795)
		(layer "F.Cu")
		(net "BMC_M_CS_N")
	)
	(segment
		(start 439.417206 -35.9283)
		(end 439.417206 -35.1155)
		(width 0.10795)
		(layer "F.Cu")
		(net "BMC_M_CS_N")
	)
	(segment
		(start 432.084988 -35.690048)
		(end 432.461162 -35.690048)
		(width 0.10795)
		(layer "F.Cu")
		(net "BMC_M_CS_N")
	)
	(segment
		(start 438.12206 -33.433004)
		(end 438.521856 -33.8328)
		(width 0.10795)
		(layer "F.Cu")
		(net "BMC_M_CS_N")
	)
	(segment
		(start 426.750226 -36.212526)
		(end 426.759624 -36.221924)
		(width 0.10795)
		(layer "F.Cu")
		(net "BMC_M_CS_N")
	)
	(segment
		(start 423.516044 -35.569652)
		(end 423.560494 -35.614356)
		(width 0.10795)
		(layer "F.Cu")
		(net "BMC_M_CS_N")
	)
	(segment
		(start 439.5216 -34.036254)
		(end 439.064146 -33.5788)
		(width 0.10795)
		(layer "F.Cu")
		(net "BMC_M_CS_N")
	)
	(segment
		(start 431.10658 -36.179252)
		(end 430.170844 -36.179252)
		(width 0.10795)
		(layer "F.Cu")
		(net "BMC_M_CS_N")
	)
	(segment
		(start 429.711104 -36.687252)
		(end 432.47437 -36.687252)
		(width 0.10795)
		(layer "F.Cu")
		(net "BMC_M_CS_N")
	)
	(segment
		(start 439.5216 -35.011106)
		(end 439.5216 -34.036254)
		(width 0.10795)
		(layer "F.Cu")
		(net "BMC_M_CS_N")
	)
	(segment
		(start 432.47437 -36.179252)
		(end 432.084988 -36.179252)
		(width 0.10795)
		(layer "F.Cu")
		(net "BMC_M_CS_N")
	)
	(segment
		(start 438.12206 -33.432496)
		(end 438.12206 -33.433004)
		(width 0.10795)
		(layer "F.Cu")
		(net "BMC_M_CS_N")
	)
	(segment
		(start 423.389044 -35.442652)
		(end 423.516044 -35.569652)
		(width 0.10795)
		(layer "F.Cu")
		(net "BMC_M_CS_N")
	)
	(segment
		(start 438.775856 -33.5788)
		(end 438.521856 -33.8328)
		(width 0.10795)
		(layer "F.Cu")
		(net "BMC_M_CS_N")
	)
	(segment
		(start 440.557666 -37.06876)
		(end 439.417206 -35.9283)
		(width 0.10795)
		(layer "F.Cu")
		(net "BMC_M_CS_N")
	)
	(via
		(at 429.711104 -36.687252)
		(size 0.508)
		(drill 0.254)
		(layers "F.Cu" "B.Cu")
		(net "BMC_M_CS_N")
	)
	(via
		(at 430.170844 -36.179252)
		(size 0.4572)
		(drill 0.2032)
		(layers "F.Cu" "B.Cu")
		(net "BMC_M_CS_N")
	)
	(via
		(at 438.521856 -33.8328)
		(size 0.4572)
		(drill 0.2032)
		(layers "F.Cu" "B.Cu")
		(net "BMC_M_CS_N")
	)
	(arc
		(start 432.084988 -36.179252)
		(mid 431.840386 -35.93465)
		(end 432.084988 -35.690048)
		(width 0.10795)
		(layer "F.Cu")
		(net "BMC_M_CS_N")
	)
	(arc
		(start 423.12844 -35.334702)
		(mid 423.26948 -35.362757)
		(end 423.389044 -35.442652)
		(width 0.10795)
		(layer "F.Cu")
		(net "BMC_M_CS_N")
	)
	(arc
		(start 426.5295 -36.026852)
		(mid 426.643868 -36.114928)
		(end 426.750226 -36.212526)
		(width 0.10795)
		(layer "F.Cu")
		(net "BMC_M_CS_N")
	)
	(arc
		(start 426.759624 -36.221924)
		(mid 427.274933 -36.566306)
		(end 427.882812 -36.687252)
		(width 0.10795)
		(layer "F.Cu")
		(net "BMC_M_CS_N")
	)
	(arc
		(start 431.351182 -35.93465)
		(mid 431.27954 -36.10761)
		(end 431.10658 -36.179252)
		(width 0.10795)
		(layer "F.Cu")
		(net "BMC_M_CS_N")
	)
	(arc
		(start 431.595784 -35.200844)
		(mid 431.422824 -35.272486)
		(end 431.351182 -35.445446)
		(width 0.10795)
		(layer "F.Cu")
		(net "BMC_M_CS_N")
	)
	(arc
		(start 425.566332 -35.722052)
		(mid 426.071452 -35.800073)
		(end 426.5295 -36.026852)
		(width 0.10795)
		(layer "F.Cu")
		(net "BMC_M_CS_N")
	)
	(arc
		(start 432.47437 -36.687252)
		(mid 432.72837 -36.433252)
		(end 432.47437 -36.179252)
		(width 0.10795)
		(layer "F.Cu")
		(net "BMC_M_CS_N")
	)
	(arc
		(start 432.461162 -35.690048)
		(mid 432.705764 -35.445446)
		(end 432.461162 -35.200844)
		(width 0.10795)
		(layer "F.Cu")
		(net "BMC_M_CS_N")
	)
	(arc
		(start 423.560494 -35.614356)
		(mid 423.679972 -35.694062)
		(end 423.820844 -35.722052)
		(width 0.10795)
		(layer "F.Cu")
		(net "BMC_M_CS_N")
	)
	(segment
		(start 430.170844 -36.179252)
		(end 431.598324 -36.179252)
		(width 0.10795)
		(layer "B.Cu")
		(net "BMC_M_CS_N")
	)
	(segment
		(start 435.183788 -33.693862)
		(end 435.362858 -33.693862)
		(width 0.10795)
		(layer "B.Cu")
		(net "BMC_M_CS_N")
	)
	(segment
		(start 438.521856 -33.812734)
		(end 438.521856 -33.8328)
		(width 0.10795)
		(layer "B.Cu")
		(net "BMC_M_CS_N")
	)
	(segment
		(start 435.978046 -33.4391)
		(end 438.10301 -33.4391)
		(width 0.10795)
		(layer "B.Cu")
		(net "BMC_M_CS_N")
	)
	(segment
		(start 438.180226 -33.471104)
		(end 438.521856 -33.812734)
		(width 0.10795)
		(layer "B.Cu")
		(net "BMC_M_CS_N")
	)
	(segment
		(start 431.688494 -36.141914)
		(end 433.39512 -34.43478)
		(width 0.10795)
		(layer "B.Cu")
		(net "BMC_M_CS_N")
	)
	(arc
		(start 438.10301 -33.4391)
		(mid 438.144807 -33.447414)
		(end 438.180226 -33.471104)
		(width 0.10795)
		(layer "B.Cu")
		(net "BMC_M_CS_N")
	)
	(arc
		(start 435.362858 -33.693862)
		(mid 435.496607 -33.667258)
		(end 435.61 -33.5915)
		(width 0.10795)
		(layer "B.Cu")
		(net "BMC_M_CS_N")
	)
	(arc
		(start 433.39512 -34.43478)
		(mid 434.215768 -33.886441)
		(end 435.183788 -33.693862)
		(width 0.10795)
		(layer "B.Cu")
		(net "BMC_M_CS_N")
	)
	(arc
		(start 431.598324 -36.179252)
		(mid 431.647119 -36.169546)
		(end 431.688494 -36.141914)
		(width 0.10795)
		(layer "B.Cu")
		(net "BMC_M_CS_N")
	)
	(arc
		(start 435.61 -33.5915)
		(mid 435.778861 -33.478671)
		(end 435.978046 -33.4391)
		(width 0.10795)
		(layer "B.Cu")
		(net "BMC_M_CS_N")
	)
	(segment
		(start 426.4152 -34.627566)
		(end 426.5295 -34.513266)
		(width 0.10033)
		(layer "F.Cu")
		(net "BMC_M_CLK_DP")
	)
	(segment
		(start 438.12206 -32.632396)
		(end 437.721756 -32.2326)
		(width 0.10033)
		(layer "F.Cu")
		(net "BMC_M_CLK_DP")
	)
	(segment
		(start 424.423078 -34.706052)
		(end 426.2247 -34.706052)
		(width 0.10033)
		(layer "F.Cu")
		(net "BMC_M_CLK_DP")
	)
	(segment
		(start 429.257714 -34.640774)
		(end 430.117758 -34.640774)
		(width 0.10033)
		(layer "F.Cu")
		(net "BMC_M_CLK_DP")
	)
	(segment
		(start 431.429668 -32.033464)
		(end 432.172872 -32.776668)
		(width 0.10033)
		(layer "F.Cu")
		(net "BMC_M_CLK_DP")
	)
	(segment
		(start 431.095912 -33.853628)
		(end 430.433988 -33.191704)
		(width 0.10033)
		(layer "F.Cu")
		(net "BMC_M_CLK_DP")
	)
	(segment
		(start 426.4152 -34.627312)
		(end 426.4152 -34.627566)
		(width 0.10033)
		(layer "F.Cu")
		(net "BMC_M_CLK_DP")
	)
	(segment
		(start 426.5295 -34.513266)
		(end 429.009048 -32.033464)
		(width 0.10033)
		(layer "F.Cu")
		(net "BMC_M_CLK_DP")
	)
	(segment
		(start 430.00422 -33.191704)
		(end 429.051974 -34.14395)
		(width 0.10033)
		(layer "F.Cu")
		(net "BMC_M_CLK_DP")
	)
	(via
		(at 435.690772 -32.5882)
		(size 0.508)
		(drill 0.254)
		(layers "F.Cu" "B.Cu")
		(net "BMC_M_CLK_DP")
	)
	(via
		(at 430.589944 -34.490152)
		(size 0.4572)
		(drill 0.2032)
		(layers "F.Cu" "B.Cu")
		(net "BMC_M_CLK_DP")
	)
	(via
		(at 437.721756 -32.2326)
		(size 0.4572)
		(drill 0.2032)
		(layers "F.Cu" "B.Cu")
		(net "BMC_M_CLK_DP")
	)
	(arc
		(start 429.009048 -32.033464)
		(mid 430.219358 -31.532137)
		(end 431.429668 -32.033464)
		(width 0.10033)
		(layer "F.Cu")
		(net "BMC_M_CLK_DP")
	)
	(arc
		(start 426.2247 -34.706052)
		(mid 426.327787 -34.68564)
		(end 426.4152 -34.627312)
		(width 0.10033)
		(layer "F.Cu")
		(net "BMC_M_CLK_DP")
	)
	(arc
		(start 429.051974 -34.14395)
		(mid 428.988902 -34.461036)
		(end 429.257714 -34.640774)
		(width 0.10033)
		(layer "F.Cu")
		(net "BMC_M_CLK_DP")
	)
	(arc
		(start 423.890186 -34.534602)
		(mid 424.143182 -34.662132)
		(end 424.423078 -34.706052)
		(width 0.10033)
		(layer "F.Cu")
		(net "BMC_M_CLK_DP")
	)
	(arc
		(start 430.117758 -34.640774)
		(mid 430.365569 -34.602202)
		(end 430.589944 -34.490152)
		(width 0.10033)
		(layer "F.Cu")
		(net "BMC_M_CLK_DP")
	)
	(arc
		(start 432.172872 -32.776668)
		(mid 432.172872 -33.853628)
		(end 431.095912 -33.853628)
		(width 0.10033)
		(layer "F.Cu")
		(net "BMC_M_CLK_DP")
	)
	(arc
		(start 430.433988 -33.191704)
		(mid 430.219104 -33.102696)
		(end 430.00422 -33.191704)
		(width 0.10033)
		(layer "F.Cu")
		(net "BMC_M_CLK_DP")
	)
	(segment
		(start 435.690772 -32.5882)
		(end 435.06136 -32.5882)
		(width 0.10033)
		(layer "B.Cu")
		(net "BMC_M_CLK_DP")
	)
	(segment
		(start 436.865776 -32.5882)
		(end 435.690772 -32.5882)
		(width 0.10033)
		(layer "B.Cu")
		(net "BMC_M_CLK_DP")
	)
	(segment
		(start 431.313336 -34.629852)
		(end 431.081942 -34.629852)
		(width 0.10033)
		(layer "B.Cu")
		(net "BMC_M_CLK_DP")
	)
	(segment
		(start 432.745896 -33.547304)
		(end 431.910744 -34.382456)
		(width 0.10033)
		(layer "B.Cu")
		(net "BMC_M_CLK_DP")
	)
	(segment
		(start 438.604406 -32.100774)
		(end 437.853582 -32.100774)
		(width 0.10033)
		(layer "B.Cu")
		(net "BMC_M_CLK_DP")
	)
	(segment
		(start 437.853582 -32.100774)
		(end 437.721756 -32.2326)
		(width 0.10033)
		(layer "B.Cu")
		(net "BMC_M_CLK_DP")
	)
	(arc
		(start 437.721756 -32.2326)
		(mid 437.329229 -32.495765)
		(end 436.865776 -32.5882)
		(width 0.10033)
		(layer "B.Cu")
		(net "BMC_M_CLK_DP")
	)
	(arc
		(start 435.06136 -32.5882)
		(mid 433.808237 -32.837462)
		(end 432.745896 -33.547304)
		(width 0.10033)
		(layer "B.Cu")
		(net "BMC_M_CLK_DP")
	)
	(arc
		(start 431.081942 -34.629852)
		(mid 430.826218 -34.594251)
		(end 430.589944 -34.490152)
		(width 0.10033)
		(layer "B.Cu")
		(net "BMC_M_CLK_DP")
	)
	(arc
		(start 431.910744 -34.382456)
		(mid 431.636637 -34.565545)
		(end 431.313336 -34.629852)
		(width 0.10033)
		(layer "B.Cu")
		(net "BMC_M_CLK_DP")
	)
	(segment
		(start 426.2247 -35.163252)
		(end 424.304206 -35.163252)
		(width 0.10033)
		(layer "F.Cu")
		(net "BMC_M_CLK_DN")
	)
	(segment
		(start 428.728632 -33.820608)
		(end 429.680878 -32.868362)
		(width 0.10033)
		(layer "F.Cu")
		(net "BMC_M_CLK_DN")
	)
	(segment
		(start 431.84953 -33.10001)
		(end 431.106326 -32.356806)
		(width 0.10033)
		(layer "F.Cu")
		(net "BMC_M_CLK_DN")
	)
	(segment
		(start 429.33239 -32.356806)
		(end 426.738542 -34.950908)
		(width 0.10033)
		(layer "F.Cu")
		(net "BMC_M_CLK_DN")
	)
	(segment
		(start 437.32196 -32.632396)
		(end 437.721756 -33.0327)
		(width 0.10033)
		(layer "F.Cu")
		(net "BMC_M_CLK_DN")
	)
	(segment
		(start 430.117758 -35.097974)
		(end 429.257714 -35.097974)
		(width 0.10033)
		(layer "F.Cu")
		(net "BMC_M_CLK_DN")
	)
	(segment
		(start 430.75733 -32.868362)
		(end 431.419254 -33.530286)
		(width 0.10033)
		(layer "F.Cu")
		(net "BMC_M_CLK_DN")
	)
	(via
		(at 430.589944 -35.290252)
		(size 0.4572)
		(drill 0.2032)
		(layers "F.Cu" "B.Cu")
		(net "BMC_M_CLK_DN")
	)
	(via
		(at 432.5874 -34.352484)
		(size 0.508)
		(drill 0.254)
		(layers "F.Cu" "B.Cu")
		(net "BMC_M_CLK_DN")
	)
	(via
		(at 437.721756 -33.0327)
		(size 0.4572)
		(drill 0.2032)
		(layers "F.Cu" "B.Cu")
		(net "BMC_M_CLK_DN")
	)
	(arc
		(start 431.106326 -32.356806)
		(mid 430.219358 -31.989412)
		(end 429.33239 -32.356806)
		(width 0.10033)
		(layer "F.Cu")
		(net "BMC_M_CLK_DN")
	)
	(arc
		(start 424.304206 -35.163252)
		(mid 424.080156 -35.207818)
		(end 423.890186 -35.334702)
		(width 0.10033)
		(layer "F.Cu")
		(net "BMC_M_CLK_DN")
	)
	(arc
		(start 430.589944 -35.290252)
		(mid 430.372676 -35.14788)
		(end 430.117758 -35.097974)
		(width 0.10033)
		(layer "F.Cu")
		(net "BMC_M_CLK_DN")
	)
	(arc
		(start 426.738542 -34.950908)
		(mid 426.502731 -35.10816)
		(end 426.2247 -35.163252)
		(width 0.10033)
		(layer "F.Cu")
		(net "BMC_M_CLK_DN")
	)
	(arc
		(start 429.257714 -35.097974)
		(mid 428.56639 -34.636046)
		(end 428.728632 -33.820608)
		(width 0.10033)
		(layer "F.Cu")
		(net "BMC_M_CLK_DN")
	)
	(arc
		(start 429.680878 -32.868362)
		(mid 430.219104 -32.645421)
		(end 430.75733 -32.868362)
		(width 0.10033)
		(layer "F.Cu")
		(net "BMC_M_CLK_DN")
	)
	(arc
		(start 431.419254 -33.530286)
		(mid 431.84953 -33.530286)
		(end 431.84953 -33.10001)
		(width 0.10033)
		(layer "F.Cu")
		(net "BMC_M_CLK_DN")
	)
	(segment
		(start 435.06136 -33.0454)
		(end 437.709056 -33.0454)
		(width 0.10033)
		(layer "B.Cu")
		(net "BMC_M_CLK_DN")
	)
	(segment
		(start 437.790082 -33.101026)
		(end 437.721756 -33.0327)
		(width 0.10033)
		(layer "B.Cu")
		(net "BMC_M_CLK_DN")
	)
	(segment
		(start 430.589944 -35.290252)
		(end 430.622456 -35.25774)
		(width 0.10033)
		(layer "B.Cu")
		(net "BMC_M_CLK_DN")
	)
	(segment
		(start 437.709056 -33.0454)
		(end 437.721756 -33.0327)
		(width 0.10033)
		(layer "B.Cu")
		(net "BMC_M_CLK_DN")
	)
	(segment
		(start 438.604406 -33.101026)
		(end 437.790082 -33.101026)
		(width 0.10033)
		(layer "B.Cu")
		(net "BMC_M_CLK_DN")
	)
	(segment
		(start 431.034444 -35.087052)
		(end 431.313336 -35.087052)
		(width 0.10033)
		(layer "B.Cu")
		(net "BMC_M_CLK_DN")
	)
	(segment
		(start 432.234086 -34.705798)
		(end 432.5874 -34.352484)
		(width 0.10033)
		(layer "B.Cu")
		(net "BMC_M_CLK_DN")
	)
	(segment
		(start 432.5874 -34.352484)
		(end 433.069238 -33.870646)
		(width 0.10033)
		(layer "B.Cu")
		(net "BMC_M_CLK_DN")
	)
	(arc
		(start 430.622456 -35.25774)
		(mid 430.811478 -35.13144)
		(end 431.034444 -35.087052)
		(width 0.10033)
		(layer "B.Cu")
		(net "BMC_M_CLK_DN")
	)
	(arc
		(start 433.069238 -33.870646)
		(mid 433.983217 -33.259881)
		(end 435.06136 -33.0454)
		(width 0.10033)
		(layer "B.Cu")
		(net "BMC_M_CLK_DN")
	)
	(arc
		(start 431.313336 -35.087052)
		(mid 431.81162 -34.987973)
		(end 432.234086 -34.705798)
		(width 0.10033)
		(layer "B.Cu")
		(net "BMC_M_CLK_DN")
	)
	(segment
		(start 422.29024 -34.534602)
		(end 422.290494 -34.534602)
		(width 0.089408)
		(layer "F.Cu")
		(net "BMC_M_CKE")
	)
	(segment
		(start 422.290494 -34.534602)
		(end 422.690544 -34.934652)
		(width 0.089408)
		(layer "F.Cu")
		(net "BMC_M_CKE")
	)
	(segment
		(start 442.122052 -32.632396)
		(end 441.722256 -32.2326)
		(width 0.10795)
		(layer "F.Cu")
		(net "BMC_M_CKE")
	)
	(via
		(at 444.802006 -31.379668)
		(size 0.508)
		(drill 0.254)
		(layers "F.Cu" "B.Cu")
		(net "BMC_M_CKE")
	)
	(via
		(at 441.722256 -32.2326)
		(size 0.4572)
		(drill 0.2032)
		(layers "F.Cu" "B.Cu")
		(net "BMC_M_CKE")
	)
	(via
		(at 422.690544 -34.934652)
		(size 0.4572)
		(drill 0.2032)
		(layers "F.Cu" "B.Cu")
		(net "BMC_M_CKE")
	)
	(segment
		(start 444.471806 -32.3215)
		(end 443.379606 -32.3215)
		(width 0.10795)
		(layer "B.Cu")
		(net "BMC_M_CKE")
	)
	(segment
		(start 447.342006 -31.5087)
		(end 447.342006 -31.1277)
		(width 0.10795)
		(layer "B.Cu")
		(net "BMC_M_CKE")
	)
	(segment
		(start 444.802006 -31.379668)
		(end 444.802006 -31.9913)
		(width 0.10795)
		(layer "B.Cu")
		(net "BMC_M_CKE")
	)
	(segment
		(start 445.157606 -30.3657)
		(end 444.802006 -30.7213)
		(width 0.10795)
		(layer "B.Cu")
		(net "BMC_M_CKE")
	)
	(segment
		(start 448.11188 -32.4485)
		(end 446.826132 -32.4485)
		(width 0.10795)
		(layer "B.Cu")
		(net "BMC_M_CKE")
	)
	(segment
		(start 446.826132 -32.4485)
		(end 446.826132 -32.024574)
		(width 0.10795)
		(layer "B.Cu")
		(net "BMC_M_CKE")
	)
	(segment
		(start 446.826132 -32.024574)
		(end 447.342006 -31.5087)
		(width 0.10795)
		(layer "B.Cu")
		(net "BMC_M_CKE")
	)
	(segment
		(start 442.128656 -31.8262)
		(end 441.722256 -32.2326)
		(width 0.10795)
		(layer "B.Cu")
		(net "BMC_M_CKE")
	)
	(segment
		(start 442.884306 -31.8262)
		(end 442.128656 -31.8262)
		(width 0.10795)
		(layer "B.Cu")
		(net "BMC_M_CKE")
	)
	(segment
		(start 443.379606 -32.3215)
		(end 442.884306 -31.8262)
		(width 0.10795)
		(layer "B.Cu")
		(net "BMC_M_CKE")
	)
	(segment
		(start 445.868806 -30.3657)
		(end 445.157606 -30.3657)
		(width 0.10795)
		(layer "B.Cu")
		(net "BMC_M_CKE")
	)
	(segment
		(start 447.342006 -31.1277)
		(end 447.151506 -30.9372)
		(width 0.10795)
		(layer "B.Cu")
		(net "BMC_M_CKE")
	)
	(segment
		(start 446.440306 -30.9372)
		(end 445.868806 -30.3657)
		(width 0.10795)
		(layer "B.Cu")
		(net "BMC_M_CKE")
	)
	(segment
		(start 447.151506 -30.9372)
		(end 446.440306 -30.9372)
		(width 0.10795)
		(layer "B.Cu")
		(net "BMC_M_CKE")
	)
	(segment
		(start 444.802006 -31.9913)
		(end 444.471806 -32.3215)
		(width 0.10795)
		(layer "B.Cu")
		(net "BMC_M_CKE")
	)
	(segment
		(start 444.802006 -30.7213)
		(end 444.802006 -31.379668)
		(width 0.10795)
		(layer "B.Cu")
		(net "BMC_M_CKE")
	)
	(segment
		(start 430.001426 -33.408366)
		(end 429.743362 -33.666176)
		(width 0.089408)
		(layer "In2.Cu")
		(net "BMC_M_CKE")
	)
	(segment
		(start 429.598582 -34.428176)
		(end 428.879762 -35.146996)
		(width 0.089408)
		(layer "In2.Cu")
		(net "BMC_M_CKE")
	)
	(segment
		(start 430.944274 -32.960564)
		(end 431.306224 -33.32226)
		(width 0.089408)
		(layer "In2.Cu")
		(net "BMC_M_CKE")
	)
	(segment
		(start 441.722256 -32.2326)
		(end 438.678828 -32.2326)
		(width 0.089408)
		(layer "In2.Cu")
		(net "BMC_M_CKE")
	)
	(segment
		(start 429.714914 -33.734756)
		(end 429.714914 -34.147506)
		(width 0.089408)
		(layer "In2.Cu")
		(net "BMC_M_CKE")
	)
	(segment
		(start 423.50309 -34.553652)
		(end 423.108628 -34.553652)
		(width 0.089408)
		(layer "In2.Cu")
		(net "BMC_M_CKE")
	)
	(segment
		(start 430.973484 -33.655254)
		(end 430.726342 -33.408112)
		(width 0.089408)
		(layer "In2.Cu")
		(net "BMC_M_CKE")
	)
	(segment
		(start 431.535586 -32.220916)
		(end 431.985674 -32.67075)
		(width 0.089408)
		(layer "In2.Cu")
		(net "BMC_M_CKE")
	)
	(segment
		(start 437.667146 -31.8135)
		(end 431.942748 -31.8135)
		(width 0.089408)
		(layer "In2.Cu")
		(net "BMC_M_CKE")
	)
	(segment
		(start 431.652934 -33.00349)
		(end 431.277014 -32.627824)
		(width 0.089408)
		(layer "In2.Cu")
		(net "BMC_M_CKE")
	)
	(segment
		(start 423.045128 -34.580068)
		(end 422.690544 -34.934652)
		(width 0.089408)
		(layer "In2.Cu")
		(net "BMC_M_CKE")
	)
	(segment
		(start 431.627788 -31.944056)
		(end 431.535586 -32.036512)
		(width 0.089408)
		(layer "In2.Cu")
		(net "BMC_M_CKE")
	)
	(segment
		(start 424.20667 -35.031934)
		(end 423.887646 -34.71291)
		(width 0.089408)
		(layer "In2.Cu")
		(net "BMC_M_CKE")
	)
	(segment
		(start 427.043596 -35.49015)
		(end 427.043596 -35.49142)
		(width 0.089408)
		(layer "In2.Cu")
		(net "BMC_M_CKE")
	)
	(segment
		(start 428.051468 -35.49015)
		(end 427.043596 -35.49015)
		(width 0.089408)
		(layer "In2.Cu")
		(net "BMC_M_CKE")
	)
	(segment
		(start 426.257212 -35.728402)
		(end 425.88815 -35.728402)
		(width 0.089408)
		(layer "In2.Cu")
		(net "BMC_M_CKE")
	)
	(arc
		(start 438.678828 -32.2326)
		(mid 438.460124 -32.189097)
		(end 438.274714 -32.065214)
		(width 0.089408)
		(layer "In2.Cu")
		(net "BMC_M_CKE")
	)
	(arc
		(start 431.535586 -32.036512)
		(mid 431.497469 -32.128714)
		(end 431.535586 -32.220916)
		(width 0.089408)
		(layer "In2.Cu")
		(net "BMC_M_CKE")
	)
	(arc
		(start 426.886624 -35.556444)
		(mid 426.713589 -35.641234)
		(end 426.5295 -35.698176)
		(width 0.089408)
		(layer "In2.Cu")
		(net "BMC_M_CKE")
	)
	(arc
		(start 430.726342 -33.408112)
		(mid 430.363794 -33.257903)
		(end 430.001426 -33.408366)
		(width 0.089408)
		(layer "In2.Cu")
		(net "BMC_M_CKE")
	)
	(arc
		(start 427.043596 -35.49142)
		(mid 426.958642 -35.508318)
		(end 426.886624 -35.556444)
		(width 0.089408)
		(layer "In2.Cu")
		(net "BMC_M_CKE")
	)
	(arc
		(start 428.879762 -35.146996)
		(mid 428.499752 -35.400974)
		(end 428.051468 -35.49015)
		(width 0.089408)
		(layer "In2.Cu")
		(net "BMC_M_CKE")
	)
	(arc
		(start 425.88815 -35.728402)
		(mid 424.978149 -35.547391)
		(end 424.20667 -35.031934)
		(width 0.089408)
		(layer "In2.Cu")
		(net "BMC_M_CKE")
	)
	(arc
		(start 431.306224 -33.32226)
		(mid 431.306415 -33.655318)
		(end 430.973484 -33.655254)
		(width 0.089408)
		(layer "In2.Cu")
		(net "BMC_M_CKE")
	)
	(arc
		(start 423.108628 -34.553652)
		(mid 423.074272 -34.560579)
		(end 423.045128 -34.580068)
		(width 0.089408)
		(layer "In2.Cu")
		(net "BMC_M_CKE")
	)
	(arc
		(start 426.5295 -35.698176)
		(mid 426.394195 -35.720855)
		(end 426.257212 -35.728402)
		(width 0.089408)
		(layer "In2.Cu")
		(net "BMC_M_CKE")
	)
	(arc
		(start 431.985674 -32.67075)
		(mid 431.985674 -33.00349)
		(end 431.652934 -33.00349)
		(width 0.089408)
		(layer "In2.Cu")
		(net "BMC_M_CKE")
	)
	(arc
		(start 431.277014 -32.627824)
		(mid 430.944274 -32.627824)
		(end 430.944274 -32.960564)
		(width 0.089408)
		(layer "In2.Cu")
		(net "BMC_M_CKE")
	)
	(arc
		(start 423.887646 -34.71291)
		(mid 423.71121 -34.595019)
		(end 423.50309 -34.553652)
		(width 0.089408)
		(layer "In2.Cu")
		(net "BMC_M_CKE")
	)
	(arc
		(start 429.714914 -34.147506)
		(mid 429.684679 -34.299418)
		(end 429.598582 -34.428176)
		(width 0.089408)
		(layer "In2.Cu")
		(net "BMC_M_CKE")
	)
	(arc
		(start 431.942748 -31.8135)
		(mid 431.772271 -31.847428)
		(end 431.627788 -31.944056)
		(width 0.089408)
		(layer "In2.Cu")
		(net "BMC_M_CKE")
	)
	(arc
		(start 438.274714 -32.065214)
		(mid 437.995959 -31.878956)
		(end 437.667146 -31.8135)
		(width 0.089408)
		(layer "In2.Cu")
		(net "BMC_M_CKE")
	)
	(arc
		(start 429.743362 -33.666176)
		(mid 429.722284 -33.697626)
		(end 429.714914 -33.734756)
		(width 0.089408)
		(layer "In2.Cu")
		(net "BMC_M_CKE")
	)
	(segment
		(start 435.420008 -34.6329)
		(end 436.755286 -34.6329)
		(width 0.10795)
		(layer "F.Cu")
		(net "BMC_M_CAS_N")
	)
	(segment
		(start 438.960006 -35.1917)
		(end 438.401206 -34.6329)
		(width 0.10795)
		(layer "F.Cu")
		(net "BMC_M_CAS_N")
	)
	(segment
		(start 439.976006 -42.108374)
		(end 439.976006 -43.124374)
		(width 0.10795)
		(layer "F.Cu")
		(net "BMC_M_CAS_N")
	)
	(segment
		(start 433.23129 -36.661344)
		(end 433.23129 -34.229294)
		(width 0.10795)
		(layer "F.Cu")
		(net "BMC_M_CAS_N")
	)
	(segment
		(start 438.960006 -36.57854)
		(end 438.960006 -35.1917)
		(width 0.10795)
		(layer "F.Cu")
		(net "BMC_M_CAS_N")
	)
	(segment
		(start 434.698902 -34.20618)
		(end 434.698902 -36.311586)
		(width 0.10795)
		(layer "F.Cu")
		(net "BMC_M_CAS_N")
	)
	(segment
		(start 437.32196 -34.233104)
		(end 437.32196 -34.232596)
		(width 0.10795)
		(layer "F.Cu")
		(net "BMC_M_CAS_N")
	)
	(segment
		(start 432.34356 -37.176202)
		(end 427.811438 -37.176202)
		(width 0.10795)
		(layer "F.Cu")
		(net "BMC_M_CAS_N")
	)
	(segment
		(start 435.188106 -36.311586)
		(end 435.188106 -34.864802)
		(width 0.10795)
		(layer "F.Cu")
		(net "BMC_M_CAS_N")
	)
	(segment
		(start 440.191144 -39.637716)
		(end 440.191144 -37.809678)
		(width 0.10795)
		(layer "F.Cu")
		(net "BMC_M_CAS_N")
	)
	(segment
		(start 433.720494 -34.229294)
		(end 433.720494 -36.38042)
		(width 0.10795)
		(layer "F.Cu")
		(net "BMC_M_CAS_N")
	)
	(segment
		(start 437.721756 -34.6329)
		(end 437.32196 -34.233104)
		(width 0.10795)
		(layer "F.Cu")
		(net "BMC_M_CAS_N")
	)
	(segment
		(start 439.976006 -42.108374)
		(end 439.417206 -41.549574)
		(width 0.10795)
		(layer "F.Cu")
		(net "BMC_M_CAS_N")
	)
	(segment
		(start 439.417206 -41.549574)
		(end 439.417206 -40.411654)
		(width 0.10795)
		(layer "F.Cu")
		(net "BMC_M_CAS_N")
	)
	(segment
		(start 439.417206 -40.411654)
		(end 440.191144 -39.637716)
		(width 0.10795)
		(layer "F.Cu")
		(net "BMC_M_CAS_N")
	)
	(segment
		(start 425.05376 -36.134548)
		(end 423.890186 -36.134548)
		(width 0.10795)
		(layer "F.Cu")
		(net "BMC_M_CAS_N")
	)
	(segment
		(start 437.039258 -34.515298)
		(end 437.32196 -34.232596)
		(width 0.10795)
		(layer "F.Cu")
		(net "BMC_M_CAS_N")
	)
	(segment
		(start 426.451776 -36.613084)
		(end 426.451522 -36.61283)
		(width 0.10795)
		(layer "F.Cu")
		(net "BMC_M_CAS_N")
	)
	(segment
		(start 432.34356 -37.176202)
		(end 432.85537 -37.176202)
		(width 0.10795)
		(layer "F.Cu")
		(net "BMC_M_CAS_N")
	)
	(segment
		(start 434.209698 -36.38042)
		(end 434.209698 -34.20618)
		(width 0.10795)
		(layer "F.Cu")
		(net "BMC_M_CAS_N")
	)
	(segment
		(start 438.401206 -34.6329)
		(end 437.721756 -34.6329)
		(width 0.10795)
		(layer "F.Cu")
		(net "BMC_M_CAS_N")
	)
	(segment
		(start 440.191144 -37.809678)
		(end 438.960006 -36.57854)
		(width 0.10795)
		(layer "F.Cu")
		(net "BMC_M_CAS_N")
	)
	(via
		(at 432.34356 -37.176202)
		(size 0.508)
		(drill 0.254)
		(layers "F.Cu" "B.Cu")
		(net "BMC_M_CAS_N")
	)
	(arc
		(start 426.451522 -36.61283)
		(mid 425.79242 -36.257441)
		(end 425.05376 -36.134548)
		(width 0.10795)
		(layer "F.Cu")
		(net "BMC_M_CAS_N")
	)
	(arc
		(start 433.720494 -36.38042)
		(mid 433.965096 -36.625022)
		(end 434.209698 -36.38042)
		(width 0.10795)
		(layer "F.Cu")
		(net "BMC_M_CAS_N")
	)
	(arc
		(start 434.209698 -34.20618)
		(mid 434.4543 -33.961578)
		(end 434.698902 -34.20618)
		(width 0.10795)
		(layer "F.Cu")
		(net "BMC_M_CAS_N")
	)
	(arc
		(start 433.051712 -37.094922)
		(mid 433.184631 -36.895995)
		(end 433.23129 -36.661344)
		(width 0.10795)
		(layer "F.Cu")
		(net "BMC_M_CAS_N")
	)
	(arc
		(start 435.188106 -34.864802)
		(mid 435.256029 -34.700823)
		(end 435.420008 -34.6329)
		(width 0.10795)
		(layer "F.Cu")
		(net "BMC_M_CAS_N")
	)
	(arc
		(start 436.755286 -34.6329)
		(mid 436.908962 -34.602332)
		(end 437.039258 -34.515298)
		(width 0.10795)
		(layer "F.Cu")
		(net "BMC_M_CAS_N")
	)
	(arc
		(start 426.5295 -36.68649)
		(mid 426.490128 -36.650327)
		(end 426.451776 -36.613084)
		(width 0.10795)
		(layer "F.Cu")
		(net "BMC_M_CAS_N")
	)
	(arc
		(start 427.811438 -37.176202)
		(mid 427.125291 -37.049608)
		(end 426.5295 -36.68649)
		(width 0.10795)
		(layer "F.Cu")
		(net "BMC_M_CAS_N")
	)
	(arc
		(start 433.23129 -34.229294)
		(mid 433.475892 -33.984692)
		(end 433.720494 -34.229294)
		(width 0.10795)
		(layer "F.Cu")
		(net "BMC_M_CAS_N")
	)
	(arc
		(start 434.698902 -36.311586)
		(mid 434.943504 -36.556188)
		(end 435.188106 -36.311586)
		(width 0.10795)
		(layer "F.Cu")
		(net "BMC_M_CAS_N")
	)
	(arc
		(start 432.85537 -37.176202)
		(mid 432.961611 -37.155069)
		(end 433.051712 -37.094922)
		(width 0.10795)
		(layer "F.Cu")
		(net "BMC_M_CAS_N")
	)
	(segment
		(start 442.274706 -34.5186)
		(end 442.389006 -34.6329)
		(width 0.10795)
		(layer "F.Cu")
		(net "BMC_M_BG0")
	)
	(segment
		(start 444.192406 -34.5059)
		(end 444.192406 -34.0487)
		(width 0.10795)
		(layer "F.Cu")
		(net "BMC_M_BG0")
	)
	(segment
		(start 444.319406 -33.9217)
		(end 444.624206 -33.9217)
		(width 0.10795)
		(layer "F.Cu")
		(net "BMC_M_BG0")
	)
	(segment
		(start 442.274706 -34.38525)
		(end 442.274706 -34.5186)
		(width 0.10795)
		(layer "F.Cu")
		(net "BMC_M_BG0")
	)
	(segment
		(start 444.065406 -34.6329)
		(end 444.192406 -34.5059)
		(width 0.10795)
		(layer "F.Cu")
		(net "BMC_M_BG0")
	)
	(segment
		(start 447.857118 -34.1757)
		(end 449.983606 -34.1757)
		(width 0.10795)
		(layer "F.Cu")
		(net "BMC_M_BG0")
	)
	(segment
		(start 444.624206 -33.9217)
		(end 444.878206 -34.1757)
		(width 0.10795)
		(layer "F.Cu")
		(net "BMC_M_BG0")
	)
	(segment
		(start 444.878206 -34.1757)
		(end 447.857118 -34.1757)
		(width 0.10795)
		(layer "F.Cu")
		(net "BMC_M_BG0")
	)
	(segment
		(start 442.122052 -34.233104)
		(end 442.122052 -34.232596)
		(width 0.10795)
		(layer "F.Cu")
		(net "BMC_M_BG0")
	)
	(segment
		(start 441.722256 -34.6329)
		(end 442.122052 -34.233104)
		(width 0.10795)
		(layer "F.Cu")
		(net "BMC_M_BG0")
	)
	(segment
		(start 444.192406 -34.0487)
		(end 444.319406 -33.9217)
		(width 0.10795)
		(layer "F.Cu")
		(net "BMC_M_BG0")
	)
	(segment
		(start 442.389006 -34.6329)
		(end 444.065406 -34.6329)
		(width 0.10795)
		(layer "F.Cu")
		(net "BMC_M_BG0")
	)
	(segment
		(start 450.14388 -33.5915)
		(end 451.41388 -33.5915)
		(width 0.10795)
		(layer "F.Cu")
		(net "BMC_M_BG0")
	)
	(segment
		(start 449.983606 -34.1757)
		(end 450.14388 -34.015426)
		(width 0.10795)
		(layer "F.Cu")
		(net "BMC_M_BG0")
	)
	(segment
		(start 421.49014 -36.134548)
		(end 421.89019 -36.534598)
		(width 0.1016)
		(layer "F.Cu")
		(net "BMC_M_BG0")
	)
	(segment
		(start 450.14388 -34.015426)
		(end 450.14388 -33.5915)
		(width 0.10795)
		(layer "F.Cu")
		(net "BMC_M_BG0")
	)
	(segment
		(start 442.122052 -34.232596)
		(end 442.274706 -34.38525)
		(width 0.10795)
		(layer "F.Cu")
		(net "BMC_M_BG0")
	)
	(via
		(at 447.857118 -34.1757)
		(size 0.508)
		(drill 0.254)
		(layers "F.Cu" "B.Cu")
		(net "BMC_M_BG0")
	)
	(via
		(at 421.89019 -36.534598)
		(size 0.4572)
		(drill 0.2032)
		(layers "F.Cu" "B.Cu")
		(net "BMC_M_BG0")
	)
	(via
		(at 441.722256 -34.6329)
		(size 0.4572)
		(drill 0.2032)
		(layers "F.Cu" "B.Cu")
		(net "BMC_M_BG0")
	)
	(segment
		(start 439.405522 -34.291016)
		(end 439.732674 -34.618168)
		(width 0.089408)
		(layer "In2.Cu")
		(net "BMC_M_BG0")
	)
	(segment
		(start 432.336448 -37.145214)
		(end 432.627278 -36.854384)
		(width 0.089408)
		(layer "In2.Cu")
		(net "BMC_M_BG0")
	)
	(segment
		(start 431.392584 -37.445442)
		(end 431.611786 -37.445442)
		(width 0.089408)
		(layer "In2.Cu")
		(net "BMC_M_BG0")
	)
	(segment
		(start 430.769776 -37.771324)
		(end 430.8856 -37.6555)
		(width 0.089408)
		(layer "In2.Cu")
		(net "BMC_M_BG0")
	)
	(segment
		(start 438.84977 -34.2011)
		(end 439.188352 -34.2011)
		(width 0.089408)
		(layer "In2.Cu")
		(net "BMC_M_BG0")
	)
	(segment
		(start 433.347876 -36.576762)
		(end 433.292758 -36.521644)
		(width 0.089408)
		(layer "In2.Cu")
		(net "BMC_M_BG0")
	)
	(segment
		(start 438.319418 -34.587688)
		(end 438.604152 -34.302954)
		(width 0.089408)
		(layer "In2.Cu")
		(net "BMC_M_BG0")
	)
	(segment
		(start 433.625498 -36.188904)
		(end 433.680362 -36.243768)
		(width 0.089408)
		(layer "In2.Cu")
		(net "BMC_M_BG0")
	)
	(segment
		(start 423.652188 -36.746688)
		(end 424.46321 -37.55771)
		(width 0.089408)
		(layer "In2.Cu")
		(net "BMC_M_BG0")
	)
	(segment
		(start 435.092602 -34.6583)
		(end 438.148984 -34.6583)
		(width 0.089408)
		(layer "In2.Cu")
		(net "BMC_M_BG0")
	)
	(segment
		(start 434.290978 -35.523424)
		(end 434.345842 -35.578288)
		(width 0.089408)
		(layer "In2.Cu")
		(net "BMC_M_BG0")
	)
	(segment
		(start 441.362592 -34.911284)
		(end 441.581032 -34.911284)
		(width 0.089408)
		(layer "In2.Cu")
		(net "BMC_M_BG0")
	)
	(segment
		(start 441.08116 -34.54146)
		(end 441.08116 -34.629852)
		(width 0.089408)
		(layer "In2.Cu")
		(net "BMC_M_BG0")
	)
	(segment
		(start 434.678836 -35.245802)
		(end 434.545232 -35.112198)
		(width 0.089408)
		(layer "In2.Cu")
		(net "BMC_M_BG0")
	)
	(segment
		(start 432.960018 -36.854384)
		(end 433.014882 -36.909248)
		(width 0.089408)
		(layer "In2.Cu")
		(net "BMC_M_BG0")
	)
	(segment
		(start 425.217336 -37.87013)
		(end 430.531778 -37.87013)
		(width 0.089408)
		(layer "In2.Cu")
		(net "BMC_M_BG0")
	)
	(segment
		(start 434.013356 -35.911282)
		(end 433.958238 -35.856164)
		(width 0.089408)
		(layer "In2.Cu")
		(net "BMC_M_BG0")
	)
	(segment
		(start 441.722002 -34.771076)
		(end 441.722256 -34.6329)
		(width 0.089408)
		(layer "In2.Cu")
		(net "BMC_M_BG0")
	)
	(segment
		(start 440.115198 -34.776664)
		(end 440.375548 -34.776664)
		(width 0.089408)
		(layer "In2.Cu")
		(net "BMC_M_BG0")
	)
	(segment
		(start 422.262808 -36.636452)
		(end 423.385996 -36.636452)
		(width 0.089408)
		(layer "In2.Cu")
		(net "BMC_M_BG0")
	)
	(segment
		(start 434.545232 -34.93643)
		(end 434.632862 -34.8488)
		(width 0.089408)
		(layer "In2.Cu")
		(net "BMC_M_BG0")
	)
	(arc
		(start 441.08116 -34.629852)
		(mid 441.16359 -34.828854)
		(end 441.362592 -34.911284)
		(width 0.089408)
		(layer "In2.Cu")
		(net "BMC_M_BG0")
	)
	(arc
		(start 439.188352 -34.2011)
		(mid 439.305883 -34.224461)
		(end 439.405522 -34.291016)
		(width 0.089408)
		(layer "In2.Cu")
		(net "BMC_M_BG0")
	)
	(arc
		(start 431.611786 -37.445442)
		(mid 432.00398 -37.367412)
		(end 432.336448 -37.145214)
		(width 0.089408)
		(layer "In2.Cu")
		(net "BMC_M_BG0")
	)
	(arc
		(start 441.581032 -34.911284)
		(mid 441.680443 -34.870264)
		(end 441.722002 -34.771076)
		(width 0.089408)
		(layer "In2.Cu")
		(net "BMC_M_BG0")
	)
	(arc
		(start 432.627278 -36.854384)
		(mid 432.793648 -36.785471)
		(end 432.960018 -36.854384)
		(width 0.089408)
		(layer "In2.Cu")
		(net "BMC_M_BG0")
	)
	(arc
		(start 434.545232 -35.112198)
		(mid 434.508755 -35.024314)
		(end 434.545232 -34.93643)
		(width 0.089408)
		(layer "In2.Cu")
		(net "BMC_M_BG0")
	)
	(arc
		(start 434.345842 -35.578288)
		(mid 434.678709 -35.578669)
		(end 434.678836 -35.245802)
		(width 0.089408)
		(layer "In2.Cu")
		(net "BMC_M_BG0")
	)
	(arc
		(start 440.610752 -34.54146)
		(mid 440.845956 -34.306256)
		(end 441.08116 -34.54146)
		(width 0.089408)
		(layer "In2.Cu")
		(net "BMC_M_BG0")
	)
	(arc
		(start 430.8856 -37.6555)
		(mid 431.118206 -37.500077)
		(end 431.392584 -37.445442)
		(width 0.089408)
		(layer "In2.Cu")
		(net "BMC_M_BG0")
	)
	(arc
		(start 421.89019 -36.534598)
		(mid 422.069664 -36.610527)
		(end 422.262808 -36.636452)
		(width 0.089408)
		(layer "In2.Cu")
		(net "BMC_M_BG0")
	)
	(arc
		(start 439.732674 -34.618168)
		(mid 439.908163 -34.735489)
		(end 440.115198 -34.776664)
		(width 0.089408)
		(layer "In2.Cu")
		(net "BMC_M_BG0")
	)
	(arc
		(start 433.292758 -36.521644)
		(mid 433.292758 -36.188904)
		(end 433.625498 -36.188904)
		(width 0.089408)
		(layer "In2.Cu")
		(net "BMC_M_BG0")
	)
	(arc
		(start 423.385996 -36.636452)
		(mid 423.530049 -36.665106)
		(end 423.652188 -36.746688)
		(width 0.089408)
		(layer "In2.Cu")
		(net "BMC_M_BG0")
	)
	(arc
		(start 433.958238 -35.856164)
		(mid 433.958238 -35.523424)
		(end 434.290978 -35.523424)
		(width 0.089408)
		(layer "In2.Cu")
		(net "BMC_M_BG0")
	)
	(arc
		(start 424.46321 -37.55771)
		(mid 424.809206 -37.788897)
		(end 425.217336 -37.87013)
		(width 0.089408)
		(layer "In2.Cu")
		(net "BMC_M_BG0")
	)
	(arc
		(start 440.375548 -34.776664)
		(mid 440.541862 -34.707774)
		(end 440.610752 -34.54146)
		(width 0.089408)
		(layer "In2.Cu")
		(net "BMC_M_BG0")
	)
	(arc
		(start 433.014882 -36.909248)
		(mid 433.347749 -36.909629)
		(end 433.347876 -36.576762)
		(width 0.089408)
		(layer "In2.Cu")
		(net "BMC_M_BG0")
	)
	(arc
		(start 433.680362 -36.243768)
		(mid 434.013229 -36.244149)
		(end 434.013356 -35.911282)
		(width 0.089408)
		(layer "In2.Cu")
		(net "BMC_M_BG0")
	)
	(arc
		(start 430.531778 -37.87013)
		(mid 430.660625 -37.844447)
		(end 430.769776 -37.771324)
		(width 0.089408)
		(layer "In2.Cu")
		(net "BMC_M_BG0")
	)
	(arc
		(start 438.148984 -34.6583)
		(mid 438.241228 -34.639951)
		(end 438.319418 -34.587688)
		(width 0.089408)
		(layer "In2.Cu")
		(net "BMC_M_BG0")
	)
	(arc
		(start 438.604152 -34.302954)
		(mid 438.716827 -34.227574)
		(end 438.84977 -34.2011)
		(width 0.089408)
		(layer "In2.Cu")
		(net "BMC_M_BG0")
	)
	(arc
		(start 434.632862 -34.8488)
		(mid 434.843778 -34.707807)
		(end 435.092602 -34.6583)
		(width 0.089408)
		(layer "In2.Cu")
		(net "BMC_M_BG0")
	)
	(segment
		(start 437.32196 -35.032442)
		(end 437.32196 -35.033204)
		(width 0.10795)
		(layer "F.Cu")
		(net "BMC_M_BA1")
	)
	(segment
		(start 433.547266 -37.665152)
		(end 427.461934 -37.665152)
		(width 0.10795)
		(layer "F.Cu")
		(net "BMC_M_BA1")
	)
	(segment
		(start 426.347636 -37.203634)
		(end 426.075348 -36.931346)
		(width 0.10795)
		(layer "F.Cu")
		(net "BMC_M_BA1")
	)
	(segment
		(start 422.573958 -36.418012)
		(end 422.290494 -36.134548)
		(width 0.10795)
		(layer "F.Cu")
		(net "BMC_M_BA1")
	)
	(segment
		(start 424.9166 -36.534852)
		(end 422.855644 -36.534852)
		(width 0.10795)
		(layer "F.Cu")
		(net "BMC_M_BA1")
	)
	(segment
		(start 433.130452 -39.384224)
		(end 432.750976 -39.384224)
		(width 0.10795)
		(layer "F.Cu")
		(net "BMC_M_BA1")
	)
	(segment
		(start 437.32196 -35.033204)
		(end 437.721756 -35.433)
		(width 0.10795)
		(layer "F.Cu")
		(net "BMC_M_BA1")
	)
	(segment
		(start 432.16957 -38.883082)
		(end 432.174142 -38.887654)
		(width 0.10795)
		(layer "F.Cu")
		(net "BMC_M_BA1")
	)
	(segment
		(start 422.290494 -36.134548)
		(end 422.29024 -36.134548)
		(width 0.10795)
		(layer "F.Cu")
		(net "BMC_M_BA1")
	)
	(segment
		(start 432.750976 -39.873428)
		(end 433.571904 -39.873428)
		(width 0.10795)
		(layer "F.Cu")
		(net "BMC_M_BA1")
	)
	(segment
		(start 433.87645 -39.568882)
		(end 433.87645 -37.994336)
		(width 0.10795)
		(layer "F.Cu")
		(net "BMC_M_BA1")
	)
	(segment
		(start 432.174142 -38.887654)
		(end 433.130452 -38.887654)
		(width 0.10795)
		(layer "F.Cu")
		(net "BMC_M_BA1")
	)
	(via
		(at 432.16957 -38.883082)
		(size 0.508)
		(drill 0.254)
		(layers "F.Cu" "B.Cu")
		(net "BMC_M_BA1")
	)
	(via
		(at 433.588668 -37.419026)
		(size 0.508)
		(drill 0.254)
		(layers "F.Cu" "B.Cu")
		(net "BMC_M_BA1")
	)
	(via
		(at 437.721756 -35.433)
		(size 0.4572)
		(drill 0.2032)
		(layers "F.Cu" "B.Cu")
		(net "BMC_M_BA1")
	)
	(arc
		(start 425.828968 -36.752784)
		(mid 425.385608 -36.590138)
		(end 424.9166 -36.534852)
		(width 0.10795)
		(layer "F.Cu")
		(net "BMC_M_BA1")
	)
	(arc
		(start 433.87645 -37.994336)
		(mid 433.780034 -37.761568)
		(end 433.547266 -37.665152)
		(width 0.10795)
		(layer "F.Cu")
		(net "BMC_M_BA1")
	)
	(arc
		(start 433.130452 -38.887654)
		(mid 433.378864 -39.136066)
		(end 433.130452 -39.384224)
		(width 0.10795)
		(layer "F.Cu")
		(net "BMC_M_BA1")
	)
	(arc
		(start 427.461934 -37.665152)
		(mid 426.858881 -37.545215)
		(end 426.347636 -37.203634)
		(width 0.10795)
		(layer "F.Cu")
		(net "BMC_M_BA1")
	)
	(arc
		(start 422.855644 -36.534852)
		(mid 422.703163 -36.504486)
		(end 422.573958 -36.418012)
		(width 0.10795)
		(layer "F.Cu")
		(net "BMC_M_BA1")
	)
	(arc
		(start 426.075348 -36.931346)
		(mid 425.959248 -36.83228)
		(end 425.828968 -36.752784)
		(width 0.10795)
		(layer "F.Cu")
		(net "BMC_M_BA1")
	)
	(arc
		(start 432.750976 -39.384224)
		(mid 432.506374 -39.628826)
		(end 432.750976 -39.873428)
		(width 0.10795)
		(layer "F.Cu")
		(net "BMC_M_BA1")
	)
	(arc
		(start 433.571904 -39.873428)
		(mid 433.787251 -39.784229)
		(end 433.87645 -39.568882)
		(width 0.10795)
		(layer "F.Cu")
		(net "BMC_M_BA1")
	)
	(segment
		(start 433.588668 -37.416994)
		(end 435.887876 -35.117786)
		(width 0.10795)
		(layer "B.Cu")
		(net "BMC_M_BA1")
	)
	(segment
		(start 433.588668 -37.419026)
		(end 433.588668 -37.416994)
		(width 0.10795)
		(layer "B.Cu")
		(net "BMC_M_BA1")
	)
	(segment
		(start 438.833006 -43.09745)
		(end 438.833006 -42.092626)
		(width 0.10795)
		(layer "B.Cu")
		(net "BMC_M_BA1")
	)
	(segment
		(start 438.655206 -35.8267)
		(end 438.115456 -35.8267)
		(width 0.10795)
		(layer "B.Cu")
		(net "BMC_M_BA1")
	)
	(segment
		(start 439.595006 -36.7665)
		(end 438.655206 -35.8267)
		(width 0.10795)
		(layer "B.Cu")
		(net "BMC_M_BA1")
	)
	(segment
		(start 439.239406 -39.1033)
		(end 439.595006 -38.7477)
		(width 0.10795)
		(layer "B.Cu")
		(net "BMC_M_BA1")
	)
	(segment
		(start 438.706006 -39.709852)
		(end 438.706006 -39.2303)
		(width 0.10795)
		(layer "B.Cu")
		(net "BMC_M_BA1")
	)
	(segment
		(start 438.115456 -35.8267)
		(end 437.721756 -35.433)
		(width 0.10795)
		(layer "B.Cu")
		(net "BMC_M_BA1")
	)
	(segment
		(start 432.20132 -38.806628)
		(end 433.588668 -37.419026)
		(width 0.10795)
		(layer "B.Cu")
		(net "BMC_M_BA1")
	)
	(segment
		(start 436.07736 -35.0393)
		(end 437.029606 -35.0393)
		(width 0.10795)
		(layer "B.Cu")
		(net "BMC_M_BA1")
	)
	(segment
		(start 438.833006 -39.1033)
		(end 439.239406 -39.1033)
		(width 0.10795)
		(layer "B.Cu")
		(net "BMC_M_BA1")
	)
	(segment
		(start 439.23712 -42.092626)
		(end 439.391806 -41.93794)
		(width 0.10795)
		(layer "B.Cu")
		(net "BMC_M_BA1")
	)
	(segment
		(start 439.391806 -40.395652)
		(end 438.706006 -39.709852)
		(width 0.10795)
		(layer "B.Cu")
		(net "BMC_M_BA1")
	)
	(segment
		(start 439.391806 -41.93794)
		(end 439.391806 -40.395652)
		(width 0.10795)
		(layer "B.Cu")
		(net "BMC_M_BA1")
	)
	(segment
		(start 439.595006 -38.7477)
		(end 439.595006 -36.7665)
		(width 0.10795)
		(layer "B.Cu")
		(net "BMC_M_BA1")
	)
	(segment
		(start 438.706006 -39.2303)
		(end 438.833006 -39.1033)
		(width 0.10795)
		(layer "B.Cu")
		(net "BMC_M_BA1")
	)
	(segment
		(start 437.53913 -35.250374)
		(end 437.721756 -35.433)
		(width 0.10795)
		(layer "B.Cu")
		(net "BMC_M_BA1")
	)
	(segment
		(start 438.833006 -42.092626)
		(end 439.23712 -42.092626)
		(width 0.10795)
		(layer "B.Cu")
		(net "BMC_M_BA1")
	)
	(arc
		(start 435.887876 -35.117786)
		(mid 435.974812 -35.059697)
		(end 436.07736 -35.0393)
		(width 0.10795)
		(layer "B.Cu")
		(net "BMC_M_BA1")
	)
	(arc
		(start 432.16957 -38.883082)
		(mid 432.177889 -38.841728)
		(end 432.20132 -38.806628)
		(width 0.10795)
		(layer "B.Cu")
		(net "BMC_M_BA1")
	)
	(arc
		(start 437.029606 -35.0393)
		(mid 437.305367 -35.094152)
		(end 437.53913 -35.250374)
		(width 0.10795)
		(layer "B.Cu")
		(net "BMC_M_BA1")
	)
	(segment
		(start 450.14388 -34.7345)
		(end 450.14388 -35.183826)
		(width 0.10795)
		(layer "F.Cu")
		(net "BMC_M_BA0")
	)
	(segment
		(start 451.41388 -34.7345)
		(end 450.14388 -34.7345)
		(width 0.10795)
		(layer "F.Cu")
		(net "BMC_M_BA0")
	)
	(segment
		(start 442.53531 -35.4457)
		(end 442.122052 -35.032442)
		(width 0.10795)
		(layer "F.Cu")
		(net "BMC_M_BA0")
	)
	(segment
		(start 443.862206 -35.5473)
		(end 443.760606 -35.4457)
		(width 0.10795)
		(layer "F.Cu")
		(net "BMC_M_BA0")
	)
	(segment
		(start 444.065406 -35.9283)
		(end 443.862206 -35.7251)
		(width 0.10795)
		(layer "F.Cu")
		(net "BMC_M_BA0")
	)
	(segment
		(start 444.624206 -35.2933)
		(end 444.471806 -35.4457)
		(width 0.10795)
		(layer "F.Cu")
		(net "BMC_M_BA0")
	)
	(segment
		(start 419.890194 -35.334702)
		(end 420.28999 -35.734498)
		(width 0.1016)
		(layer "F.Cu")
		(net "BMC_M_BA0")
	)
	(segment
		(start 444.471806 -35.4457)
		(end 444.471806 -35.8013)
		(width 0.10795)
		(layer "F.Cu")
		(net "BMC_M_BA0")
	)
	(segment
		(start 450.14388 -35.183826)
		(end 450.034406 -35.2933)
		(width 0.10795)
		(layer "F.Cu")
		(net "BMC_M_BA0")
	)
	(segment
		(start 450.034406 -35.2933)
		(end 446.935606 -35.2933)
		(width 0.10795)
		(layer "F.Cu")
		(net "BMC_M_BA0")
	)
	(segment
		(start 442.122052 -35.033204)
		(end 441.722256 -35.433)
		(width 0.10795)
		(layer "F.Cu")
		(net "BMC_M_BA0")
	)
	(segment
		(start 442.122052 -35.032442)
		(end 442.122052 -35.033204)
		(width 0.10795)
		(layer "F.Cu")
		(net "BMC_M_BA0")
	)
	(segment
		(start 444.344806 -35.9283)
		(end 444.065406 -35.9283)
		(width 0.10795)
		(layer "F.Cu")
		(net "BMC_M_BA0")
	)
	(segment
		(start 446.935606 -35.2933)
		(end 444.624206 -35.2933)
		(width 0.10795)
		(layer "F.Cu")
		(net "BMC_M_BA0")
	)
	(segment
		(start 444.471806 -35.8013)
		(end 444.344806 -35.9283)
		(width 0.10795)
		(layer "F.Cu")
		(net "BMC_M_BA0")
	)
	(segment
		(start 443.760606 -35.4457)
		(end 442.53531 -35.4457)
		(width 0.10795)
		(layer "F.Cu")
		(net "BMC_M_BA0")
	)
	(segment
		(start 443.862206 -35.7251)
		(end 443.862206 -35.5473)
		(width 0.10795)
		(layer "F.Cu")
		(net "BMC_M_BA0")
	)
	(via
		(at 441.722256 -35.433)
		(size 0.4572)
		(drill 0.2032)
		(layers "F.Cu" "B.Cu")
		(net "BMC_M_BA0")
	)
	(via
		(at 420.28999 -35.734498)
		(size 0.4572)
		(drill 0.2032)
		(layers "F.Cu" "B.Cu")
		(net "BMC_M_BA0")
	)
	(via
		(at 446.935606 -35.2933)
		(size 0.508)
		(drill 0.254)
		(layers "F.Cu" "B.Cu")
		(net "BMC_M_BA0")
	)
	(segment
		(start 436.163974 -38.242494)
		(end 435.425596 -38.242494)
		(width 0.089408)
		(layer "In2.Cu")
		(net "BMC_M_BA0")
	)
	(segment
		(start 420.671244 -36.496752)
		(end 420.671244 -36.49599)
		(width 0.089408)
		(layer "In2.Cu")
		(net "BMC_M_BA0")
	)
	(segment
		(start 434.510688 -38.621462)
		(end 434.093112 -39.039038)
		(width 0.089408)
		(layer "In2.Cu")
		(net "BMC_M_BA0")
	)
	(segment
		(start 423.176446 -38.430708)
		(end 423.167048 -38.421056)
		(width 0.089408)
		(layer "In2.Cu")
		(net "BMC_M_BA0")
	)
	(segment
		(start 422.466516 -38.101524)
		(end 422.227756 -37.862764)
		(width 0.089408)
		(layer "In2.Cu")
		(net "BMC_M_BA0")
	)
	(segment
		(start 421.596058 -37.601398)
		(end 421.595804 -37.601144)
		(width 0.089408)
		(layer "In2.Cu")
		(net "BMC_M_BA0")
	)
	(segment
		(start 421.369744 -37.055552)
		(end 421.35425 -37.040058)
		(width 0.089408)
		(layer "In2.Cu")
		(net "BMC_M_BA0")
	)
	(segment
		(start 439.961782 -36.161726)
		(end 439.095134 -37.028374)
		(width 0.089408)
		(layer "In2.Cu")
		(net "BMC_M_BA0")
	)
	(segment
		(start 441.722256 -35.433)
		(end 441.721748 -35.433508)
		(width 0.089408)
		(layer "In2.Cu")
		(net "BMC_M_BA0")
	)
	(segment
		(start 424.505882 -39.531036)
		(end 423.638218 -38.663372)
		(width 0.089408)
		(layer "In2.Cu")
		(net "BMC_M_BA0")
	)
	(segment
		(start 431.904394 -39.945564)
		(end 425.506642 -39.945564)
		(width 0.089408)
		(layer "In2.Cu")
		(net "BMC_M_BA0")
	)
	(segment
		(start 440.648852 -35.8775)
		(end 440.64809 -35.8775)
		(width 0.089408)
		(layer "In2.Cu")
		(net "BMC_M_BA0")
	)
	(segment
		(start 420.402258 -35.846766)
		(end 420.28999 -35.734498)
		(width 0.089408)
		(layer "In2.Cu")
		(net "BMC_M_BA0")
	)
	(segment
		(start 421.90416 -37.728652)
		(end 421.903144 -37.728652)
		(width 0.089408)
		(layer "In2.Cu")
		(net "BMC_M_BA0")
	)
	(arc
		(start 440.64809 -35.8775)
		(mid 440.276668 -35.951362)
		(end 439.961782 -36.161726)
		(width 0.089408)
		(layer "In2.Cu")
		(net "BMC_M_BA0")
	)
	(arc
		(start 423.638218 -38.663372)
		(mid 423.535055 -38.594567)
		(end 423.413428 -38.570408)
		(width 0.089408)
		(layer "In2.Cu")
		(net "BMC_M_BA0")
	)
	(arc
		(start 420.671244 -36.49599)
		(mid 420.601334 -36.14462)
		(end 420.402258 -35.846766)
		(width 0.089408)
		(layer "In2.Cu")
		(net "BMC_M_BA0")
	)
	(arc
		(start 422.831006 -38.281864)
		(mid 422.633924 -38.22167)
		(end 422.466516 -38.101524)
		(width 0.089408)
		(layer "In2.Cu")
		(net "BMC_M_BA0")
	)
	(arc
		(start 421.115744 -36.941252)
		(mid 420.801435 -36.811061)
		(end 420.671244 -36.496752)
		(width 0.089408)
		(layer "In2.Cu")
		(net "BMC_M_BA0")
	)
	(arc
		(start 441.721748 -35.433508)
		(mid 441.229414 -35.762096)
		(end 440.648852 -35.8775)
		(width 0.089408)
		(layer "In2.Cu")
		(net "BMC_M_BA0")
	)
	(arc
		(start 435.425596 -38.242494)
		(mid 434.930451 -38.340984)
		(end 434.510688 -38.621462)
		(width 0.089408)
		(layer "In2.Cu")
		(net "BMC_M_BA0")
	)
	(arc
		(start 425.506642 -39.945564)
		(mid 424.965035 -39.837832)
		(end 424.505882 -39.531036)
		(width 0.089408)
		(layer "In2.Cu")
		(net "BMC_M_BA0")
	)
	(arc
		(start 421.484044 -37.331396)
		(mid 421.454331 -37.182109)
		(end 421.369744 -37.055552)
		(width 0.089408)
		(layer "In2.Cu")
		(net "BMC_M_BA0")
	)
	(arc
		(start 421.903144 -37.728652)
		(mid 421.736944 -37.695575)
		(end 421.596058 -37.601398)
		(width 0.089408)
		(layer "In2.Cu")
		(net "BMC_M_BA0")
	)
	(arc
		(start 421.595804 -37.601144)
		(mid 421.513109 -37.477383)
		(end 421.484044 -37.331396)
		(width 0.089408)
		(layer "In2.Cu")
		(net "BMC_M_BA0")
	)
	(arc
		(start 434.093112 -39.039038)
		(mid 433.088905 -39.709964)
		(end 431.904394 -39.945564)
		(width 0.089408)
		(layer "In2.Cu")
		(net "BMC_M_BA0")
	)
	(arc
		(start 421.35425 -37.040058)
		(mid 421.244823 -36.966941)
		(end 421.115744 -36.941252)
		(width 0.089408)
		(layer "In2.Cu")
		(net "BMC_M_BA0")
	)
	(arc
		(start 422.227756 -37.862764)
		(mid 422.079303 -37.763508)
		(end 421.90416 -37.728652)
		(width 0.089408)
		(layer "In2.Cu")
		(net "BMC_M_BA0")
	)
	(arc
		(start 439.095134 -37.028374)
		(mid 437.750306 -37.926959)
		(end 436.163974 -38.242494)
		(width 0.089408)
		(layer "In2.Cu")
		(net "BMC_M_BA0")
	)
	(arc
		(start 423.167048 -38.421056)
		(mid 423.012871 -38.318038)
		(end 422.831006 -38.281864)
		(width 0.089408)
		(layer "In2.Cu")
		(net "BMC_M_BA0")
	)
	(arc
		(start 423.413428 -38.570408)
		(mid 423.286088 -38.515562)
		(end 423.176446 -38.430708)
		(width 0.089408)
		(layer "In2.Cu")
		(net "BMC_M_BA0")
	)
	(segment
		(start 438.248806 -41.529)
		(end 438.253632 -41.529)
		(width 0.10795)
		(layer "F.Cu")
		(net "BMC_M_A9")
	)
	(segment
		(start 438.248806 -40.4495)
		(end 438.248806 -41.529)
		(width 0.10795)
		(layer "F.Cu")
		(net "BMC_M_A9")
	)
	(segment
		(start 438.12206 -36.633404)
		(end 438.521856 -37.0332)
		(width 0.10795)
		(layer "F.Cu")
		(net "BMC_M_A9")
	)
	(segment
		(start 422.29024 -38.534594)
		(end 422.69029 -38.934644)
		(width 0.1016)
		(layer "F.Cu")
		(net "BMC_M_A9")
	)
	(segment
		(start 439.745882 -38.257226)
		(end 439.745882 -39.422832)
		(width 0.10795)
		(layer "F.Cu")
		(net "BMC_M_A9")
	)
	(segment
		(start 438.12206 -36.632388)
		(end 438.12206 -36.633404)
		(width 0.10795)
		(layer "F.Cu")
		(net "BMC_M_A9")
	)
	(segment
		(start 438.833006 -42.108374)
		(end 438.833006 -43.124374)
		(width 0.10795)
		(layer "F.Cu")
		(net "BMC_M_A9")
	)
	(segment
		(start 438.767474 -39.930832)
		(end 438.248806 -40.4495)
		(width 0.10795)
		(layer "F.Cu")
		(net "BMC_M_A9")
	)
	(segment
		(start 438.253632 -41.529)
		(end 438.833006 -42.108374)
		(width 0.10795)
		(layer "F.Cu")
		(net "BMC_M_A9")
	)
	(segment
		(start 438.521856 -37.0332)
		(end 439.745882 -38.257226)
		(width 0.10795)
		(layer "F.Cu")
		(net "BMC_M_A9")
	)
	(segment
		(start 439.256678 -39.422832)
		(end 439.256678 -38.709346)
		(width 0.10795)
		(layer "F.Cu")
		(net "BMC_M_A9")
	)
	(segment
		(start 438.767474 -38.709346)
		(end 438.767474 -39.930832)
		(width 0.10795)
		(layer "F.Cu")
		(net "BMC_M_A9")
	)
	(via
		(at 422.69029 -38.934644)
		(size 0.4572)
		(drill 0.2032)
		(layers "F.Cu" "B.Cu")
		(net "BMC_M_A9")
	)
	(via
		(at 429.665384 -41.382188)
		(size 0.508)
		(drill 0.254)
		(layers "F.Cu" "B.Cu")
		(net "BMC_M_A9")
	)
	(via
		(at 438.521856 -37.0332)
		(size 0.4572)
		(drill 0.2032)
		(layers "F.Cu" "B.Cu")
		(net "BMC_M_A9")
	)
	(arc
		(start 439.745882 -39.422832)
		(mid 439.50128 -39.667434)
		(end 439.256678 -39.422832)
		(width 0.10795)
		(layer "F.Cu")
		(net "BMC_M_A9")
	)
	(arc
		(start 439.256678 -38.709346)
		(mid 439.012076 -38.464744)
		(end 438.767474 -38.709346)
		(width 0.10795)
		(layer "F.Cu")
		(net "BMC_M_A9")
	)
	(segment
		(start 433.087018 -41.62171)
		(end 433.087018 -42.563288)
		(width 0.10795)
		(layer "B.Cu")
		(net "BMC_M_A9")
	)
	(segment
		(start 427.801024 -41.124378)
		(end 427.443646 -40.767)
		(width 0.10795)
		(layer "B.Cu")
		(net "BMC_M_A9")
	)
	(segment
		(start 427.222158 -40.767)
		(end 427.00956 -40.979598)
		(width 0.10795)
		(layer "B.Cu")
		(net "BMC_M_A9")
	)
	(segment
		(start 422.91 -39.154354)
		(end 422.69029 -38.934644)
		(width 0.10795)
		(layer "B.Cu")
		(net "BMC_M_A9")
	)
	(segment
		(start 426.618146 -39.940992)
		(end 426.618146 -39.941246)
		(width 0.10795)
		(layer "B.Cu")
		(net "BMC_M_A9")
	)
	(segment
		(start 423.719752 -39.349934)
		(end 423.382186 -39.349934)
		(width 0.10795)
		(layer "B.Cu")
		(net "BMC_M_A9")
	)
	(segment
		(start 424.18254 -39.604442)
		(end 424.074844 -39.497)
		(width 0.10795)
		(layer "B.Cu")
		(net "BMC_M_A9")
	)
	(segment
		(start 430.00803 -41.382188)
		(end 429.665384 -41.382188)
		(width 0.10795)
		(layer "B.Cu")
		(net "BMC_M_A9")
	)
	(segment
		(start 432.109118 -41.852596)
		(end 432.109118 -42.525696)
		(width 0.10795)
		(layer "B.Cu")
		(net "BMC_M_A9")
	)
	(segment
		(start 435.876446 -40.376348)
		(end 435.876446 -40.727884)
		(width 0.10795)
		(layer "B.Cu")
		(net "BMC_M_A9")
	)
	(segment
		(start 426.0977 -39.7256)
		(end 424.47464 -39.7256)
		(width 0.10795)
		(layer "B.Cu")
		(net "BMC_M_A9")
	)
	(segment
		(start 426.662088 -40.632126)
		(end 426.83303 -40.461438)
		(width 0.10795)
		(layer "B.Cu")
		(net "BMC_M_A9")
	)
	(segment
		(start 438.01665 -37.85235)
		(end 436.147718 -39.721282)
		(width 0.10795)
		(layer "B.Cu")
		(net "BMC_M_A9")
	)
	(segment
		(start 435.291992 -41.356026)
		(end 433.352702 -41.356026)
		(width 0.10795)
		(layer "B.Cu")
		(net "BMC_M_A9")
	)
	(segment
		(start 429.654208 -41.393364)
		(end 428.450502 -41.393364)
		(width 0.10795)
		(layer "B.Cu")
		(net "BMC_M_A9")
	)
	(segment
		(start 435.813708 -40.879268)
		(end 435.3687 -41.324276)
		(width 0.10795)
		(layer "B.Cu")
		(net "BMC_M_A9")
	)
	(segment
		(start 431.35677 -41.31818)
		(end 430.199546 -41.31818)
		(width 0.10795)
		(layer "B.Cu")
		(net "BMC_M_A9")
	)
	(segment
		(start 432.598068 -42.563288)
		(end 432.598068 -41.852596)
		(width 0.10795)
		(layer "B.Cu")
		(net "BMC_M_A9")
	)
	(segment
		(start 429.665384 -41.382188)
		(end 429.654208 -41.393364)
		(width 0.10795)
		(layer "B.Cu")
		(net "BMC_M_A9")
	)
	(segment
		(start 426.83303 -40.15613)
		(end 426.618146 -39.940992)
		(width 0.10795)
		(layer "B.Cu")
		(net "BMC_M_A9")
	)
	(segment
		(start 426.618146 -39.941246)
		(end 426.617892 -39.941246)
		(width 0.10795)
		(layer "B.Cu")
		(net "BMC_M_A9")
	)
	(segment
		(start 431.620168 -42.525696)
		(end 431.620168 -41.581578)
		(width 0.10795)
		(layer "B.Cu")
		(net "BMC_M_A9")
	)
	(arc
		(start 433.087018 -42.563288)
		(mid 432.84267 -42.807636)
		(end 432.598068 -42.563288)
		(width 0.10795)
		(layer "B.Cu")
		(net "BMC_M_A9")
	)
	(arc
		(start 430.08169 -41.366948)
		(mid 430.045634 -41.378308)
		(end 430.00803 -41.382188)
		(width 0.10795)
		(layer "B.Cu")
		(net "BMC_M_A9")
	)
	(arc
		(start 427.443646 -40.767)
		(mid 427.332902 -40.721128)
		(end 427.222158 -40.767)
		(width 0.10795)
		(layer "B.Cu")
		(net "BMC_M_A9")
	)
	(arc
		(start 435.3687 -41.324276)
		(mid 435.333506 -41.347792)
		(end 435.291992 -41.356026)
		(width 0.10795)
		(layer "B.Cu")
		(net "BMC_M_A9")
	)
	(arc
		(start 423.382186 -39.349934)
		(mid 423.126643 -39.299103)
		(end 422.91 -39.154354)
		(width 0.10795)
		(layer "B.Cu")
		(net "BMC_M_A9")
	)
	(arc
		(start 438.521856 -37.0332)
		(mid 438.317129 -37.472302)
		(end 438.01665 -37.85235)
		(width 0.10795)
		(layer "B.Cu")
		(net "BMC_M_A9")
	)
	(arc
		(start 431.620168 -41.581578)
		(mid 431.543021 -41.395327)
		(end 431.35677 -41.31818)
		(width 0.10795)
		(layer "B.Cu")
		(net "BMC_M_A9")
	)
	(arc
		(start 433.352702 -41.356026)
		(mid 433.164835 -41.433843)
		(end 433.087018 -41.62171)
		(width 0.10795)
		(layer "B.Cu")
		(net "BMC_M_A9")
	)
	(arc
		(start 428.450502 -41.393364)
		(mid 428.099021 -41.32345)
		(end 427.801024 -41.124378)
		(width 0.10795)
		(layer "B.Cu")
		(net "BMC_M_A9")
	)
	(arc
		(start 426.83303 -40.461438)
		(mid 426.896261 -40.308784)
		(end 426.83303 -40.15613)
		(width 0.10795)
		(layer "B.Cu")
		(net "BMC_M_A9")
	)
	(arc
		(start 432.109118 -42.525696)
		(mid 431.86477 -42.770044)
		(end 431.620168 -42.525696)
		(width 0.10795)
		(layer "B.Cu")
		(net "BMC_M_A9")
	)
	(arc
		(start 427.00956 -40.979598)
		(mid 426.662088 -40.979598)
		(end 426.662088 -40.632126)
		(width 0.10795)
		(layer "B.Cu")
		(net "BMC_M_A9")
	)
	(arc
		(start 436.147718 -39.721282)
		(mid 435.946953 -40.021843)
		(end 435.876446 -40.376348)
		(width 0.10795)
		(layer "B.Cu")
		(net "BMC_M_A9")
	)
	(arc
		(start 426.617892 -39.941246)
		(mid 426.379241 -39.781691)
		(end 426.0977 -39.7256)
		(width 0.10795)
		(layer "B.Cu")
		(net "BMC_M_A9")
	)
	(arc
		(start 424.074844 -39.497)
		(mid 423.911926 -39.388142)
		(end 423.719752 -39.349934)
		(width 0.10795)
		(layer "B.Cu")
		(net "BMC_M_A9")
	)
	(arc
		(start 432.598068 -41.852596)
		(mid 432.35372 -41.608248)
		(end 432.109118 -41.852596)
		(width 0.10795)
		(layer "B.Cu")
		(net "BMC_M_A9")
	)
	(arc
		(start 430.199546 -41.31818)
		(mid 430.135782 -41.330863)
		(end 430.08169 -41.366948)
		(width 0.10795)
		(layer "B.Cu")
		(net "BMC_M_A9")
	)
	(arc
		(start 435.876446 -40.727884)
		(mid 435.860132 -40.809811)
		(end 435.813708 -40.879268)
		(width 0.10795)
		(layer "B.Cu")
		(net "BMC_M_A9")
	)
	(arc
		(start 424.47464 -39.7256)
		(mid 424.316547 -39.69406)
		(end 424.18254 -39.604442)
		(width 0.10795)
		(layer "B.Cu")
		(net "BMC_M_A9")
	)
	(segment
		(start 446.589912 -37.7317)
		(end 449.932806 -37.7317)
		(width 0.10795)
		(layer "F.Cu")
		(net "BMC_M_A8")
	)
	(segment
		(start 442.522356 -37.0332)
		(end 442.522356 -37.66185)
		(width 0.10795)
		(layer "F.Cu")
		(net "BMC_M_A8")
	)
	(segment
		(start 442.522356 -37.66185)
		(end 442.770006 -37.9095)
		(width 0.10795)
		(layer "F.Cu")
		(net "BMC_M_A8")
	)
	(segment
		(start 445.081406 -37.8841)
		(end 445.233806 -37.7317)
		(width 0.10795)
		(layer "F.Cu")
		(net "BMC_M_A8")
	)
	(segment
		(start 442.122052 -36.632388)
		(end 442.122052 -36.632896)
		(width 0.10795)
		(layer "F.Cu")
		(net "BMC_M_A8")
	)
	(segment
		(start 442.122052 -36.632896)
		(end 442.522356 -37.0332)
		(width 0.10795)
		(layer "F.Cu")
		(net "BMC_M_A8")
	)
	(segment
		(start 445.233806 -37.7317)
		(end 446.589912 -37.7317)
		(width 0.10795)
		(layer "F.Cu")
		(net "BMC_M_A8")
	)
	(segment
		(start 444.573406 -38.4683)
		(end 444.852806 -38.4683)
		(width 0.10795)
		(layer "F.Cu")
		(net "BMC_M_A8")
	)
	(segment
		(start 445.081406 -38.2397)
		(end 445.081406 -37.8841)
		(width 0.10795)
		(layer "F.Cu")
		(net "BMC_M_A8")
	)
	(segment
		(start 444.852806 -38.4683)
		(end 445.081406 -38.2397)
		(width 0.10795)
		(layer "F.Cu")
		(net "BMC_M_A8")
	)
	(segment
		(start 451.41388 -37.1475)
		(end 450.14388 -37.1475)
		(width 0.10795)
		(layer "F.Cu")
		(net "BMC_M_A8")
	)
	(segment
		(start 442.770006 -37.9095)
		(end 444.014606 -37.9095)
		(width 0.10795)
		(layer "F.Cu")
		(net "BMC_M_A8")
	)
	(segment
		(start 421.49014 -38.534594)
		(end 421.090344 -38.935152)
		(width 0.1016)
		(layer "F.Cu")
		(net "BMC_M_A8")
	)
	(segment
		(start 450.14388 -37.520626)
		(end 450.14388 -37.1475)
		(width 0.10795)
		(layer "F.Cu")
		(net "BMC_M_A8")
	)
	(segment
		(start 449.932806 -37.7317)
		(end 450.14388 -37.520626)
		(width 0.10795)
		(layer "F.Cu")
		(net "BMC_M_A8")
	)
	(segment
		(start 444.014606 -37.9095)
		(end 444.573406 -38.4683)
		(width 0.10795)
		(layer "F.Cu")
		(net "BMC_M_A8")
	)
	(via
		(at 442.522356 -37.0332)
		(size 0.4572)
		(drill 0.2032)
		(layers "F.Cu" "B.Cu")
		(net "BMC_M_A8")
	)
	(via
		(at 421.090344 -38.935152)
		(size 0.4572)
		(drill 0.2032)
		(layers "F.Cu" "B.Cu")
		(net "BMC_M_A8")
	)
	(via
		(at 446.589912 -37.7317)
		(size 0.508)
		(drill 0.254)
		(layers "F.Cu" "B.Cu")
		(net "BMC_M_A8")
	)
	(segment
		(start 430.640744 -43.261788)
		(end 432.030886 -43.261788)
		(width 0.089408)
		(layer "In2.Cu")
		(net "BMC_M_A8")
	)
	(segment
		(start 438.253124 -40.458644)
		(end 439.727848 -38.98392)
		(width 0.089408)
		(layer "In2.Cu")
		(net "BMC_M_A8")
	)
	(segment
		(start 422.348914 -39.990014)
		(end 422.408604 -40.049704)
		(width 0.089408)
		(layer "In2.Cu")
		(net "BMC_M_A8")
	)
	(segment
		(start 422.266618 -39.641526)
		(end 422.266618 -39.791386)
		(width 0.089408)
		(layer "In2.Cu")
		(net "BMC_M_A8")
	)
	(segment
		(start 425.863766 -41.419018)
		(end 427.71568 -41.419018)
		(width 0.089408)
		(layer "In2.Cu")
		(net "BMC_M_A8")
	)
	(segment
		(start 428.536862 -41.759124)
		(end 429.61433 -42.836592)
		(width 0.089408)
		(layer "In2.Cu")
		(net "BMC_M_A8")
	)
	(segment
		(start 441.69076 -37.864796)
		(end 442.522356 -37.0332)
		(width 0.089408)
		(layer "In2.Cu")
		(net "BMC_M_A8")
	)
	(segment
		(start 422.104058 -39.355014)
		(end 422.178988 -39.429944)
		(width 0.089408)
		(layer "In2.Cu")
		(net "BMC_M_A8")
	)
	(arc
		(start 422.178988 -39.429944)
		(mid 422.243851 -39.527019)
		(end 422.266618 -39.641526)
		(width 0.089408)
		(layer "In2.Cu")
		(net "BMC_M_A8")
	)
	(arc
		(start 421.090344 -38.935152)
		(mid 421.63895 -39.044276)
		(end 422.104058 -39.355014)
		(width 0.089408)
		(layer "In2.Cu")
		(net "BMC_M_A8")
	)
	(arc
		(start 440.647328 -38.459664)
		(mid 440.731245 -38.436373)
		(end 440.814206 -38.40988)
		(width 0.089408)
		(layer "In2.Cu")
		(net "BMC_M_A8")
	)
	(arc
		(start 422.266618 -39.791386)
		(mid 422.288002 -39.898891)
		(end 422.348914 -39.990014)
		(width 0.089408)
		(layer "In2.Cu")
		(net "BMC_M_A8")
	)
	(arc
		(start 423.95521 -41.044114)
		(mid 424.891243 -41.324457)
		(end 425.863766 -41.419018)
		(width 0.089408)
		(layer "In2.Cu")
		(net "BMC_M_A8")
	)
	(arc
		(start 440.814206 -38.40988)
		(mid 441.283826 -38.187738)
		(end 441.69076 -37.864796)
		(width 0.089408)
		(layer "In2.Cu")
		(net "BMC_M_A8")
	)
	(arc
		(start 438.140348 -40.731186)
		(mid 438.19376 -40.651111)
		(end 438.212484 -40.556688)
		(width 0.089408)
		(layer "In2.Cu")
		(net "BMC_M_A8")
	)
	(arc
		(start 439.727848 -38.98392)
		(mid 440.15236 -38.660012)
		(end 440.647328 -38.459664)
		(width 0.089408)
		(layer "In2.Cu")
		(net "BMC_M_A8")
	)
	(arc
		(start 438.212484 -40.556688)
		(mid 438.223041 -40.503616)
		(end 438.253124 -40.458644)
		(width 0.089408)
		(layer "In2.Cu")
		(net "BMC_M_A8")
	)
	(arc
		(start 427.71568 -41.419018)
		(mid 428.1601 -41.507401)
		(end 428.536862 -41.759124)
		(width 0.089408)
		(layer "In2.Cu")
		(net "BMC_M_A8")
	)
	(arc
		(start 429.61433 -42.836592)
		(mid 430.085239 -43.151306)
		(end 430.640744 -43.261788)
		(width 0.089408)
		(layer "In2.Cu")
		(net "BMC_M_A8")
	)
	(arc
		(start 432.030886 -43.261788)
		(mid 435.337295 -42.604102)
		(end 438.140348 -40.731186)
		(width 0.089408)
		(layer "In2.Cu")
		(net "BMC_M_A8")
	)
	(arc
		(start 422.408604 -40.049704)
		(mid 423.136201 -40.617998)
		(end 423.95521 -41.044114)
		(width 0.089408)
		(layer "In2.Cu")
		(net "BMC_M_A8")
	)
	(segment
		(start 432.608482 -40.948356)
		(end 432.71694 -40.948356)
		(width 0.10795)
		(layer "F.Cu")
		(net "BMC_M_A7")
	)
	(segment
		(start 436.321962 -39.675562)
		(end 436.321962 -38.554406)
		(width 0.10795)
		(layer "F.Cu")
		(net "BMC_M_A7")
	)
	(segment
		(start 431.02403 -43.095672)
		(end 431.02403 -43.11523)
		(width 0.10795)
		(layer "F.Cu")
		(net "BMC_M_A7")
	)
	(segment
		(start 437.32196 -36.632896)
		(end 436.921656 -37.0332)
		(width 0.10795)
		(layer "F.Cu")
		(net "BMC_M_A7")
	)
	(segment
		(start 433.396644 -42.461434)
		(end 433.396644 -41.483534)
		(width 0.10795)
		(layer "F.Cu")
		(net "BMC_M_A7")
	)
	(segment
		(start 435.832758 -40.155876)
		(end 435.965854 -40.288972)
		(width 0.10795)
		(layer "F.Cu")
		(net "BMC_M_A7")
	)
	(segment
		(start 432.735228 -42.851324)
		(end 433.007008 -42.851324)
		(width 0.10795)
		(layer "F.Cu")
		(net "BMC_M_A7")
	)
	(segment
		(start 436.811166 -37.89934)
		(end 436.811166 -39.675562)
		(width 0.10795)
		(layer "F.Cu")
		(net "BMC_M_A7")
	)
	(segment
		(start 437.32196 -36.632388)
		(end 437.32196 -36.632896)
		(width 0.10795)
		(layer "F.Cu")
		(net "BMC_M_A7")
	)
	(segment
		(start 433.640992 -41.239186)
		(end 434.053742 -41.239186)
		(width 0.10795)
		(layer "F.Cu")
		(net "BMC_M_A7")
	)
	(segment
		(start 429.876712 -42.851324)
		(end 430.779682 -42.851324)
		(width 0.10795)
		(layer "F.Cu")
		(net "BMC_M_A7")
	)
	(segment
		(start 434.053742 -40.750236)
		(end 433.640992 -40.750236)
		(width 0.10795)
		(layer "F.Cu")
		(net "BMC_M_A7")
	)
	(segment
		(start 423.162476 -38.871398)
		(end 423.163238 -38.87216)
		(width 0.10795)
		(layer "F.Cu")
		(net "BMC_M_A7")
	)
	(segment
		(start 423.315384 -38.935152)
		(end 424.62323 -38.935152)
		(width 0.10795)
		(layer "F.Cu")
		(net "BMC_M_A7")
	)
	(segment
		(start 436.547006 -43.111674)
		(end 436.547006 -42.108374)
		(width 0.10795)
		(layer "F.Cu")
		(net "BMC_M_A7")
	)
	(segment
		(start 436.921656 -37.0332)
		(end 436.921656 -37.78885)
		(width 0.10795)
		(layer "F.Cu")
		(net "BMC_M_A7")
	)
	(segment
		(start 432.49088 -43.11523)
		(end 432.49088 -43.095672)
		(width 0.10795)
		(layer "F.Cu")
		(net "BMC_M_A7")
	)
	(segment
		(start 433.279804 -40.389048)
		(end 432.663092 -40.389048)
		(width 0.10795)
		(layer "F.Cu")
		(net "BMC_M_A7")
	)
	(segment
		(start 436.176674 -42.108374)
		(end 436.547006 -42.108374)
		(width 0.10795)
		(layer "F.Cu")
		(net "BMC_M_A7")
	)
	(segment
		(start 432.500532 -40.551608)
		(end 432.500532 -40.840406)
		(width 0.10795)
		(layer "F.Cu")
		(net "BMC_M_A7")
	)
	(segment
		(start 436.921656 -37.78885)
		(end 436.811166 -37.89934)
		(width 0.10795)
		(layer "F.Cu")
		(net "BMC_M_A7")
	)
	(segment
		(start 435.965854 -40.288972)
		(end 435.965854 -41.897554)
		(width 0.10795)
		(layer "F.Cu")
		(net "BMC_M_A7")
	)
	(segment
		(start 435.832758 -38.554406)
		(end 435.832758 -40.155876)
		(width 0.10795)
		(layer "F.Cu")
		(net "BMC_M_A7")
	)
	(segment
		(start 431.51298 -43.11523)
		(end 431.51298 -43.094656)
		(width 0.10795)
		(layer "F.Cu")
		(net "BMC_M_A7")
	)
	(segment
		(start 429.172878 -42.55135)
		(end 429.187356 -42.565828)
		(width 0.10795)
		(layer "F.Cu")
		(net "BMC_M_A7")
	)
	(segment
		(start 423.090086 -38.534594)
		(end 423.090086 -38.696646)
		(width 0.10795)
		(layer "F.Cu")
		(net "BMC_M_A7")
	)
	(segment
		(start 435.965854 -41.897554)
		(end 436.176674 -42.108374)
		(width 0.10795)
		(layer "F.Cu")
		(net "BMC_M_A7")
	)
	(segment
		(start 424.924728 -39.06012)
		(end 427.657768 -41.793414)
		(width 0.10795)
		(layer "F.Cu")
		(net "BMC_M_A7")
	)
	(segment
		(start 432.00193 -43.094656)
		(end 432.00193 -43.11523)
		(width 0.10795)
		(layer "F.Cu")
		(net "BMC_M_A7")
	)
	(via
		(at 432.71694 -40.948356)
		(size 0.508)
		(drill 0.254)
		(layers "F.Cu" "B.Cu")
		(net "BMC_M_A7")
	)
	(via
		(at 436.921656 -37.0332)
		(size 0.4572)
		(drill 0.2032)
		(layers "F.Cu" "B.Cu")
		(net "BMC_M_A7")
	)
	(via
		(at 435.921912 -39.312088)
		(size 0.508)
		(drill 0.254)
		(layers "F.Cu" "B.Cu")
		(net "BMC_M_A7")
	)
	(arc
		(start 433.007008 -42.851324)
		(mid 433.156018 -42.821684)
		(end 433.282344 -42.737278)
		(width 0.10795)
		(layer "F.Cu")
		(net "BMC_M_A7")
	)
	(arc
		(start 424.62323 -38.935152)
		(mid 424.786417 -38.96763)
		(end 424.924728 -39.06012)
		(width 0.10795)
		(layer "F.Cu")
		(net "BMC_M_A7")
	)
	(arc
		(start 432.500532 -40.840406)
		(mid 432.53215 -40.916738)
		(end 432.608482 -40.948356)
		(width 0.10795)
		(layer "F.Cu")
		(net "BMC_M_A7")
	)
	(arc
		(start 433.396644 -40.505888)
		(mid 433.362422 -40.42327)
		(end 433.279804 -40.389048)
		(width 0.10795)
		(layer "F.Cu")
		(net "BMC_M_A7")
	)
	(arc
		(start 432.663092 -40.389048)
		(mid 432.548145 -40.436661)
		(end 432.500532 -40.551608)
		(width 0.10795)
		(layer "F.Cu")
		(net "BMC_M_A7")
	)
	(arc
		(start 433.640992 -40.750236)
		(mid 433.468212 -40.678668)
		(end 433.396644 -40.505888)
		(width 0.10795)
		(layer "F.Cu")
		(net "BMC_M_A7")
	)
	(arc
		(start 427.791626 -41.91381)
		(mid 428.209853 -42.211681)
		(end 428.70247 -42.356532)
		(width 0.10795)
		(layer "F.Cu")
		(net "BMC_M_A7")
	)
	(arc
		(start 432.00193 -43.11523)
		(mid 432.246532 -43.359832)
		(end 432.49088 -43.11523)
		(width 0.10795)
		(layer "F.Cu")
		(net "BMC_M_A7")
	)
	(arc
		(start 432.49088 -43.095672)
		(mid 432.562448 -42.922892)
		(end 432.735228 -42.851324)
		(width 0.10795)
		(layer "F.Cu")
		(net "BMC_M_A7")
	)
	(arc
		(start 433.396644 -41.483534)
		(mid 433.468212 -41.310754)
		(end 433.640992 -41.239186)
		(width 0.10795)
		(layer "F.Cu")
		(net "BMC_M_A7")
	)
	(arc
		(start 434.053742 -41.239186)
		(mid 434.29809 -40.994838)
		(end 434.053742 -40.750236)
		(width 0.10795)
		(layer "F.Cu")
		(net "BMC_M_A7")
	)
	(arc
		(start 428.70247 -42.356532)
		(mid 428.957041 -42.407169)
		(end 429.172878 -42.55135)
		(width 0.10795)
		(layer "F.Cu")
		(net "BMC_M_A7")
	)
	(arc
		(start 433.282344 -42.737278)
		(mid 433.366908 -42.61072)
		(end 433.396644 -42.461434)
		(width 0.10795)
		(layer "F.Cu")
		(net "BMC_M_A7")
	)
	(arc
		(start 423.163238 -38.87216)
		(mid 423.233043 -38.918802)
		(end 423.315384 -38.935152)
		(width 0.10795)
		(layer "F.Cu")
		(net "BMC_M_A7")
	)
	(arc
		(start 431.51298 -43.094656)
		(mid 431.757582 -42.850054)
		(end 432.00193 -43.094656)
		(width 0.10795)
		(layer "F.Cu")
		(net "BMC_M_A7")
	)
	(arc
		(start 423.090086 -38.696646)
		(mid 423.108899 -38.791223)
		(end 423.162476 -38.871398)
		(width 0.10795)
		(layer "F.Cu")
		(net "BMC_M_A7")
	)
	(arc
		(start 429.187356 -42.565828)
		(mid 429.503635 -42.777159)
		(end 429.876712 -42.851324)
		(width 0.10795)
		(layer "F.Cu")
		(net "BMC_M_A7")
	)
	(arc
		(start 427.657768 -41.793414)
		(mid 427.723085 -41.855404)
		(end 427.791626 -41.91381)
		(width 0.10795)
		(layer "F.Cu")
		(net "BMC_M_A7")
	)
	(arc
		(start 436.811166 -39.675562)
		(mid 436.566564 -39.920164)
		(end 436.321962 -39.675562)
		(width 0.10795)
		(layer "F.Cu")
		(net "BMC_M_A7")
	)
	(arc
		(start 430.779682 -42.851324)
		(mid 430.952462 -42.922892)
		(end 431.02403 -43.095672)
		(width 0.10795)
		(layer "F.Cu")
		(net "BMC_M_A7")
	)
	(arc
		(start 436.321962 -38.554406)
		(mid 436.07736 -38.309804)
		(end 435.832758 -38.554406)
		(width 0.10795)
		(layer "F.Cu")
		(net "BMC_M_A7")
	)
	(arc
		(start 431.02403 -43.11523)
		(mid 431.268632 -43.359832)
		(end 431.51298 -43.11523)
		(width 0.10795)
		(layer "F.Cu")
		(net "BMC_M_A7")
	)
	(segment
		(start 432.71694 -40.948356)
		(end 432.79822 -40.867076)
		(width 0.10795)
		(layer "B.Cu")
		(net "BMC_M_A7")
	)
	(segment
		(start 432.79822 -40.867076)
		(end 434.166518 -40.867076)
		(width 0.10795)
		(layer "B.Cu")
		(net "BMC_M_A7")
	)
	(segment
		(start 437.11241 -37.493702)
		(end 437.11241 -37.7571)
		(width 0.10795)
		(layer "B.Cu")
		(net "BMC_M_A7")
	)
	(segment
		(start 435.915308 -39.312088)
		(end 435.921912 -39.312088)
		(width 0.10795)
		(layer "B.Cu")
		(net "BMC_M_A7")
	)
	(segment
		(start 434.49748 -40.729916)
		(end 435.915308 -39.312088)
		(width 0.10795)
		(layer "B.Cu")
		(net "BMC_M_A7")
	)
	(segment
		(start 436.8546 -38.3794)
		(end 435.921912 -39.312088)
		(width 0.10795)
		(layer "B.Cu")
		(net "BMC_M_A7")
	)
	(arc
		(start 437.11241 -37.7571)
		(mid 437.045431 -38.093918)
		(end 436.8546 -38.3794)
		(width 0.10795)
		(layer "B.Cu")
		(net "BMC_M_A7")
	)
	(arc
		(start 436.921656 -37.0332)
		(mid 437.062775 -37.244494)
		(end 437.11241 -37.493702)
		(width 0.10795)
		(layer "B.Cu")
		(net "BMC_M_A7")
	)
	(arc
		(start 434.166518 -40.867076)
		(mid 434.345646 -40.831427)
		(end 434.49748 -40.729916)
		(width 0.10795)
		(layer "B.Cu")
		(net "BMC_M_A7")
	)
	(segment
		(start 442.122052 -35.833304)
		(end 441.722256 -36.2331)
		(width 0.10795)
		(layer "F.Cu")
		(net "BMC_M_A6")
	)
	(segment
		(start 428.13478 -41.554654)
		(end 426.5295 -39.950644)
		(width 0.10795)
		(layer "F.Cu")
		(net "BMC_M_A6")
	)
	(segment
		(start 442.122052 -35.832542)
		(end 442.122052 -35.833304)
		(width 0.10795)
		(layer "F.Cu")
		(net "BMC_M_A6")
	)
	(segment
		(start 429.815498 -42.289222)
		(end 429.511968 -41.985692)
		(width 0.10795)
		(layer "F.Cu")
		(net "BMC_M_A6")
	)
	(segment
		(start 429.245268 -41.875202)
		(end 428.973234 -41.875202)
		(width 0.10795)
		(layer "F.Cu")
		(net "BMC_M_A6")
	)
	(segment
		(start 424.853862 -38.534594)
		(end 423.890186 -38.534594)
		(width 0.10795)
		(layer "F.Cu")
		(net "BMC_M_A6")
	)
	(segment
		(start 432.273964 -42.349674)
		(end 429.961548 -42.349674)
		(width 0.10795)
		(layer "F.Cu")
		(net "BMC_M_A6")
	)
	(segment
		(start 426.5295 -39.950644)
		(end 425.29506 -38.71722)
		(width 0.10795)
		(layer "F.Cu")
		(net "BMC_M_A6")
	)
	(segment
		(start 430.716436 -41.827704)
		(end 432.273964 -41.827704)
		(width 0.10795)
		(layer "F.Cu")
		(net "BMC_M_A6")
	)
	(via
		(at 441.722256 -36.2331)
		(size 0.4572)
		(drill 0.2032)
		(layers "F.Cu" "B.Cu")
		(net "BMC_M_A6")
	)
	(via
		(at 443.904116 -39.5859)
		(size 0.508)
		(drill 0.254)
		(layers "F.Cu" "B.Cu")
		(net "BMC_M_A6")
	)
	(via
		(at 430.716436 -41.827704)
		(size 0.508)
		(drill 0.254)
		(layers "F.Cu" "B.Cu")
		(net "BMC_M_A6")
	)
	(arc
		(start 429.511968 -41.985692)
		(mid 429.389605 -41.903932)
		(end 429.245268 -41.875202)
		(width 0.10795)
		(layer "F.Cu")
		(net "BMC_M_A6")
	)
	(arc
		(start 432.273964 -41.827704)
		(mid 432.535076 -42.088816)
		(end 432.273964 -42.349674)
		(width 0.10795)
		(layer "F.Cu")
		(net "BMC_M_A6")
	)
	(arc
		(start 428.410624 -41.74871)
		(mid 428.264339 -41.663568)
		(end 428.13478 -41.554654)
		(width 0.10795)
		(layer "F.Cu")
		(net "BMC_M_A6")
	)
	(arc
		(start 429.961548 -42.349674)
		(mid 429.882509 -42.33397)
		(end 429.815498 -42.289222)
		(width 0.10795)
		(layer "F.Cu")
		(net "BMC_M_A6")
	)
	(arc
		(start 428.973234 -41.875202)
		(mid 428.684904 -41.843195)
		(end 428.410624 -41.74871)
		(width 0.10795)
		(layer "F.Cu")
		(net "BMC_M_A6")
	)
	(arc
		(start 425.29506 -38.71722)
		(mid 425.092608 -38.582072)
		(end 424.853862 -38.534594)
		(width 0.10795)
		(layer "F.Cu")
		(net "BMC_M_A6")
	)
	(segment
		(start 445.02578 -42.092626)
		(end 445.208406 -41.91)
		(width 0.10795)
		(layer "B.Cu")
		(net "BMC_M_A6")
	)
	(segment
		(start 442.128656 -36.6395)
		(end 441.722256 -36.2331)
		(width 0.10795)
		(layer "B.Cu")
		(net "BMC_M_A6")
	)
	(segment
		(start 445.208406 -40.5257)
		(end 444.268606 -39.5859)
		(width 0.10795)
		(layer "B.Cu")
		(net "BMC_M_A6")
	)
	(segment
		(start 443.904116 -39.5859)
		(end 443.506606 -39.5859)
		(width 0.10795)
		(layer "B.Cu")
		(net "BMC_M_A6")
	)
	(segment
		(start 445.208406 -41.91)
		(end 445.208406 -40.5257)
		(width 0.10795)
		(layer "B.Cu")
		(net "BMC_M_A6")
	)
	(segment
		(start 442.617606 -39.1287)
		(end 442.617606 -37.6555)
		(width 0.10795)
		(layer "B.Cu")
		(net "BMC_M_A6")
	)
	(segment
		(start 442.922406 -37.3507)
		(end 442.922406 -36.7919)
		(width 0.10795)
		(layer "B.Cu")
		(net "BMC_M_A6")
	)
	(segment
		(start 442.922406 -36.7919)
		(end 442.770006 -36.6395)
		(width 0.10795)
		(layer "B.Cu")
		(net "BMC_M_A6")
	)
	(segment
		(start 442.770006 -36.6395)
		(end 442.128656 -36.6395)
		(width 0.10795)
		(layer "B.Cu")
		(net "BMC_M_A6")
	)
	(segment
		(start 443.506606 -39.5859)
		(end 443.151006 -39.2303)
		(width 0.10795)
		(layer "B.Cu")
		(net "BMC_M_A6")
	)
	(segment
		(start 442.719206 -39.2303)
		(end 442.617606 -39.1287)
		(width 0.10795)
		(layer "B.Cu")
		(net "BMC_M_A6")
	)
	(segment
		(start 443.151006 -39.2303)
		(end 442.719206 -39.2303)
		(width 0.10795)
		(layer "B.Cu")
		(net "BMC_M_A6")
	)
	(segment
		(start 444.548006 -43.09745)
		(end 444.548006 -42.092626)
		(width 0.10795)
		(layer "B.Cu")
		(net "BMC_M_A6")
	)
	(segment
		(start 442.617606 -37.6555)
		(end 442.922406 -37.3507)
		(width 0.10795)
		(layer "B.Cu")
		(net "BMC_M_A6")
	)
	(segment
		(start 444.268606 -39.5859)
		(end 443.904116 -39.5859)
		(width 0.10795)
		(layer "B.Cu")
		(net "BMC_M_A6")
	)
	(segment
		(start 444.548006 -42.092626)
		(end 445.02578 -42.092626)
		(width 0.10795)
		(layer "B.Cu")
		(net "BMC_M_A6")
	)
	(segment
		(start 439.989722 -37.073078)
		(end 438.58942 -38.47338)
		(width 0.089408)
		(layer "In2.Cu")
		(net "BMC_M_A6")
	)
	(segment
		(start 441.722256 -36.2331)
		(end 441.476638 -36.478718)
		(width 0.089408)
		(layer "In2.Cu")
		(net "BMC_M_A6")
	)
	(segment
		(start 434.875686 -40.011604)
		(end 434.303932 -40.583358)
		(width 0.089408)
		(layer "In2.Cu")
		(net "BMC_M_A6")
	)
	(segment
		(start 431.419254 -41.827704)
		(end 430.716436 -41.827704)
		(width 0.089408)
		(layer "In2.Cu")
		(net "BMC_M_A6")
	)
	(segment
		(start 441.067698 -36.648136)
		(end 441.015374 -36.648136)
		(width 0.089408)
		(layer "In2.Cu")
		(net "BMC_M_A6")
	)
	(arc
		(start 433.439062 -40.991028)
		(mid 432.512366 -41.610226)
		(end 431.419254 -41.827704)
		(width 0.089408)
		(layer "In2.Cu")
		(net "BMC_M_A6")
	)
	(arc
		(start 441.476638 -36.478718)
		(mid 441.289015 -36.604084)
		(end 441.067698 -36.648136)
		(width 0.089408)
		(layer "In2.Cu")
		(net "BMC_M_A6")
	)
	(arc
		(start 441.015374 -36.648136)
		(mid 440.46027 -36.758571)
		(end 439.989722 -37.073078)
		(width 0.089408)
		(layer "In2.Cu")
		(net "BMC_M_A6")
	)
	(arc
		(start 437.160924 -39.0652)
		(mid 435.924174 -39.311111)
		(end 434.875686 -40.011604)
		(width 0.089408)
		(layer "In2.Cu")
		(net "BMC_M_A6")
	)
	(arc
		(start 433.883308 -40.757602)
		(mid 433.645677 -40.8448)
		(end 433.439062 -40.991028)
		(width 0.089408)
		(layer "In2.Cu")
		(net "BMC_M_A6")
	)
	(arc
		(start 438.58942 -38.47338)
		(mid 437.934035 -38.911387)
		(end 437.160924 -39.0652)
		(width 0.089408)
		(layer "In2.Cu")
		(net "BMC_M_A6")
	)
	(arc
		(start 434.303932 -40.583358)
		(mid 434.110948 -40.712306)
		(end 433.883308 -40.757602)
		(width 0.089408)
		(layer "In2.Cu")
		(net "BMC_M_A6")
	)
	(segment
		(start 420.69004 -37.735256)
		(end 420.290244 -38.135052)
		(width 0.1016)
		(layer "F.Cu")
		(net "BMC_M_A5")
	)
	(segment
		(start 437.32196 -35.832542)
		(end 437.321198 -35.832542)
		(width 0.10795)
		(layer "F.Cu")
		(net "BMC_M_A5")
	)
	(segment
		(start 437.321198 -35.832542)
		(end 436.921656 -35.433)
		(width 0.10795)
		(layer "F.Cu")
		(net "BMC_M_A5")
	)
	(segment
		(start 420.69004 -37.734748)
		(end 420.69004 -37.735256)
		(width 0.1016)
		(layer "F.Cu")
		(net "BMC_M_A5")
	)
	(via
		(at 426.14596 -38.7731)
		(size 0.508)
		(drill 0.254)
		(layers "F.Cu" "B.Cu")
		(net "BMC_M_A5")
	)
	(via
		(at 436.921656 -35.433)
		(size 0.4572)
		(drill 0.2032)
		(layers "F.Cu" "B.Cu")
		(net "BMC_M_A5")
	)
	(via
		(at 420.290244 -38.135052)
		(size 0.4572)
		(drill 0.2032)
		(layers "F.Cu" "B.Cu")
		(net "BMC_M_A5")
	)
	(segment
		(start 435.836822 -35.948112)
		(end 432.55184 -39.233094)
		(width 0.10795)
		(layer "B.Cu")
		(net "BMC_M_A5")
	)
	(segment
		(start 438.960006 -37.5793)
		(end 437.105806 -39.4335)
		(width 0.10795)
		(layer "B.Cu")
		(net "BMC_M_A5")
	)
	(segment
		(start 421.94226 -37.741352)
		(end 420.0652 -37.741352)
		(width 0.10795)
		(layer "B.Cu")
		(net "BMC_M_A5")
	)
	(segment
		(start 437.553354 -36.6268)
		(end 438.693306 -36.6268)
		(width 0.10795)
		(layer "B.Cu")
		(net "BMC_M_A5")
	)
	(segment
		(start 429.866806 -39.408862)
		(end 427.691042 -39.408862)
		(width 0.10795)
		(layer "B.Cu")
		(net "BMC_M_A5")
	)
	(segment
		(start 438.693306 -36.6268)
		(end 438.960006 -36.8935)
		(width 0.10795)
		(layer "B.Cu")
		(net "BMC_M_A5")
	)
	(segment
		(start 437.105806 -39.4335)
		(end 437.105806 -41.900348)
		(width 0.10795)
		(layer "B.Cu")
		(net "BMC_M_A5")
	)
	(segment
		(start 437.105806 -41.900348)
		(end 436.913528 -42.092626)
		(width 0.10795)
		(layer "B.Cu")
		(net "BMC_M_A5")
	)
	(segment
		(start 436.547006 -43.09745)
		(end 436.547006 -42.092626)
		(width 0.10795)
		(layer "B.Cu")
		(net "BMC_M_A5")
	)
	(segment
		(start 438.960006 -36.8935)
		(end 438.960006 -37.5793)
		(width 0.10795)
		(layer "B.Cu")
		(net "BMC_M_A5")
	)
	(segment
		(start 436.685436 -35.8267)
		(end 436.129938 -35.8267)
		(width 0.10795)
		(layer "B.Cu")
		(net "BMC_M_A5")
	)
	(segment
		(start 425.022518 -38.49624)
		(end 425.022518 -38.60673)
		(width 0.10795)
		(layer "B.Cu")
		(net "BMC_M_A5")
	)
	(segment
		(start 427.555406 -39.352728)
		(end 427.078394 -38.875716)
		(width 0.10795)
		(layer "B.Cu")
		(net "BMC_M_A5")
	)
	(segment
		(start 424.044618 -38.441884)
		(end 424.044618 -38.492176)
		(width 0.10795)
		(layer "B.Cu")
		(net "BMC_M_A5")
	)
	(segment
		(start 430.600104 -39.164514)
		(end 430.600104 -39.16172)
		(width 0.10795)
		(layer "B.Cu")
		(net "BMC_M_A5")
	)
	(segment
		(start 423.936668 -38.600126)
		(end 423.481754 -38.600126)
		(width 0.10795)
		(layer "B.Cu")
		(net "BMC_M_A5")
	)
	(segment
		(start 432.127406 -39.408862)
		(end 430.844452 -39.408862)
		(width 0.10795)
		(layer "B.Cu")
		(net "BMC_M_A5")
	)
	(segment
		(start 430.111154 -39.16172)
		(end 430.111154 -39.164514)
		(width 0.10795)
		(layer "B.Cu")
		(net "BMC_M_A5")
	)
	(segment
		(start 422.500044 -38.160452)
		(end 422.246044 -37.906452)
		(width 0.10795)
		(layer "B.Cu")
		(net "BMC_M_A5")
	)
	(segment
		(start 426.83049 -38.7731)
		(end 426.14596 -38.7731)
		(width 0.10795)
		(layer "B.Cu")
		(net "BMC_M_A5")
	)
	(segment
		(start 426.14596 -38.7731)
		(end 425.69384 -38.7731)
		(width 0.10795)
		(layer "B.Cu")
		(net "BMC_M_A5")
	)
	(segment
		(start 424.533568 -38.60673)
		(end 424.533568 -38.441884)
		(width 0.10795)
		(layer "B.Cu")
		(net "BMC_M_A5")
	)
	(segment
		(start 436.921656 -35.433)
		(end 436.921656 -35.59048)
		(width 0.10795)
		(layer "B.Cu")
		(net "BMC_M_A5")
	)
	(segment
		(start 423.33545 -38.53942)
		(end 423.160444 -38.363652)
		(width 0.10795)
		(layer "B.Cu")
		(net "BMC_M_A5")
	)
	(segment
		(start 436.913528 -42.092626)
		(end 436.547006 -42.092626)
		(width 0.10795)
		(layer "B.Cu")
		(net "BMC_M_A5")
	)
	(segment
		(start 422.91508 -38.262052)
		(end 422.745408 -38.262052)
		(width 0.10795)
		(layer "B.Cu")
		(net "BMC_M_A5")
	)
	(segment
		(start 422.186354 -37.855144)
		(end 422.164764 -37.833554)
		(width 0.10795)
		(layer "B.Cu")
		(net "BMC_M_A5")
	)
	(segment
		(start 437.321706 -36.395152)
		(end 437.553354 -36.6268)
		(width 0.10795)
		(layer "B.Cu")
		(net "BMC_M_A5")
	)
	(segment
		(start 419.687248 -39.132256)
		(end 420.290244 -38.135052)
		(width 0.10795)
		(layer "B.Cu")
		(net "BMC_M_A5")
	)
	(segment
		(start 425.511468 -38.617652)
		(end 425.511468 -38.49624)
		(width 0.10795)
		(layer "B.Cu")
		(net "BMC_M_A5")
	)
	(segment
		(start 419.818566 -37.880798)
		(end 419.231826 -38.858952)
		(width 0.10795)
		(layer "B.Cu")
		(net "BMC_M_A5")
	)
	(segment
		(start 436.921656 -35.433)
		(end 437.321706 -35.83305)
		(width 0.10795)
		(layer "B.Cu")
		(net "BMC_M_A5")
	)
	(segment
		(start 437.321706 -35.83305)
		(end 437.321706 -36.395152)
		(width 0.10795)
		(layer "B.Cu")
		(net "BMC_M_A5")
	)
	(arc
		(start 425.511468 -38.49624)
		(mid 425.26712 -38.251892)
		(end 425.022518 -38.49624)
		(width 0.10795)
		(layer "B.Cu")
		(net "BMC_M_A5")
	)
	(arc
		(start 432.55184 -39.233094)
		(mid 432.357094 -39.363156)
		(end 432.127406 -39.408862)
		(width 0.10795)
		(layer "B.Cu")
		(net "BMC_M_A5")
	)
	(arc
		(start 423.481754 -38.600126)
		(mid 423.402563 -38.584338)
		(end 423.33545 -38.53942)
		(width 0.10795)
		(layer "B.Cu")
		(net "BMC_M_A5")
	)
	(arc
		(start 419.231826 -38.858952)
		(mid 419.322956 -39.223408)
		(end 419.687248 -39.132256)
		(width 0.10795)
		(layer "B.Cu")
		(net "BMC_M_A5")
	)
	(arc
		(start 422.164764 -37.833554)
		(mid 422.062678 -37.765343)
		(end 421.94226 -37.741352)
		(width 0.10795)
		(layer "B.Cu")
		(net "BMC_M_A5")
	)
	(arc
		(start 430.844452 -39.408862)
		(mid 430.671672 -39.337294)
		(end 430.600104 -39.164514)
		(width 0.10795)
		(layer "B.Cu")
		(net "BMC_M_A5")
	)
	(arc
		(start 436.921656 -35.59048)
		(mid 436.852469 -35.757513)
		(end 436.685436 -35.8267)
		(width 0.10795)
		(layer "B.Cu")
		(net "BMC_M_A5")
	)
	(arc
		(start 427.691042 -39.408862)
		(mid 427.617655 -39.394264)
		(end 427.555406 -39.352728)
		(width 0.10795)
		(layer "B.Cu")
		(net "BMC_M_A5")
	)
	(arc
		(start 424.533568 -38.441884)
		(mid 424.28922 -38.197536)
		(end 424.044618 -38.441884)
		(width 0.10795)
		(layer "B.Cu")
		(net "BMC_M_A5")
	)
	(arc
		(start 430.600104 -39.16172)
		(mid 430.355756 -38.917372)
		(end 430.111154 -39.16172)
		(width 0.10795)
		(layer "B.Cu")
		(net "BMC_M_A5")
	)
	(arc
		(start 422.745408 -38.262052)
		(mid 422.612631 -38.235641)
		(end 422.500044 -38.160452)
		(width 0.10795)
		(layer "B.Cu")
		(net "BMC_M_A5")
	)
	(arc
		(start 425.61637 -38.758876)
		(mid 425.540593 -38.7056)
		(end 425.511468 -38.617652)
		(width 0.10795)
		(layer "B.Cu")
		(net "BMC_M_A5")
	)
	(arc
		(start 427.078394 -38.875716)
		(mid 426.96464 -38.799771)
		(end 426.83049 -38.7731)
		(width 0.10795)
		(layer "B.Cu")
		(net "BMC_M_A5")
	)
	(arc
		(start 424.044618 -38.492176)
		(mid 424.013 -38.568508)
		(end 423.936668 -38.600126)
		(width 0.10795)
		(layer "B.Cu")
		(net "BMC_M_A5")
	)
	(arc
		(start 420.0652 -37.741352)
		(mid 419.923543 -37.778631)
		(end 419.818566 -37.880798)
		(width 0.10795)
		(layer "B.Cu")
		(net "BMC_M_A5")
	)
	(arc
		(start 430.111154 -39.164514)
		(mid 430.039586 -39.337294)
		(end 429.866806 -39.408862)
		(width 0.10795)
		(layer "B.Cu")
		(net "BMC_M_A5")
	)
	(arc
		(start 425.022518 -38.60673)
		(mid 424.77817 -38.851078)
		(end 424.533568 -38.60673)
		(width 0.10795)
		(layer "B.Cu")
		(net "BMC_M_A5")
	)
	(arc
		(start 423.160444 -38.363652)
		(mid 423.04787 -38.288432)
		(end 422.91508 -38.262052)
		(width 0.10795)
		(layer "B.Cu")
		(net "BMC_M_A5")
	)
	(arc
		(start 422.246044 -37.906452)
		(mid 422.217171 -37.879667)
		(end 422.186354 -37.855144)
		(width 0.10795)
		(layer "B.Cu")
		(net "BMC_M_A5")
	)
	(arc
		(start 425.69384 -38.7731)
		(mid 425.65446 -38.769508)
		(end 425.61637 -38.758876)
		(width 0.10795)
		(layer "B.Cu")
		(net "BMC_M_A5")
	)
	(arc
		(start 436.129938 -35.8267)
		(mid 435.971305 -35.858254)
		(end 435.836822 -35.948112)
		(width 0.10795)
		(layer "B.Cu")
		(net "BMC_M_A5")
	)
	(segment
		(start 440.48553 -35.175952)
		(end 440.62904 -35.032442)
		(width 0.10795)
		(layer "F.Cu")
		(net "BMC_M_A4")
	)
	(segment
		(start 440.48553 -36.056824)
		(end 440.48553 -35.175952)
		(width 0.10795)
		(layer "F.Cu")
		(net "BMC_M_A4")
	)
	(segment
		(start 440.62904 -35.032442)
		(end 441.321952 -35.032442)
		(width 0.10795)
		(layer "F.Cu")
		(net "BMC_M_A4")
	)
	(segment
		(start 421.49014 -37.734748)
		(end 421.89019 -38.134798)
		(width 0.1016)
		(layer "F.Cu")
		(net "BMC_M_A4")
	)
	(segment
		(start 440.687206 -36.2585)
		(end 440.48553 -36.056824)
		(width 0.10795)
		(layer "F.Cu")
		(net "BMC_M_A4")
	)
	(via
		(at 421.89019 -38.134798)
		(size 0.4572)
		(drill 0.2032)
		(layers "F.Cu" "B.Cu")
		(net "BMC_M_A4")
	)
	(via
		(at 440.687206 -36.2585)
		(size 0.4572)
		(drill 0.2032)
		(layers "F.Cu" "B.Cu")
		(net "BMC_M_A4")
	)
	(via
		(at 442.185806 -38.398704)
		(size 0.508)
		(drill 0.254)
		(layers "F.Cu" "B.Cu")
		(net "BMC_M_A4")
	)
	(segment
		(start 442.058806 -37.5539)
		(end 441.550806 -37.5539)
		(width 0.10795)
		(layer "B.Cu")
		(net "BMC_M_A4")
	)
	(segment
		(start 441.195206 -36.4363)
		(end 441.017406 -36.2585)
		(width 0.10795)
		(layer "B.Cu")
		(net "BMC_M_A4")
	)
	(segment
		(start 442.185806 -38.398704)
		(end 442.185806 -37.6809)
		(width 0.10795)
		(layer "B.Cu")
		(net "BMC_M_A4")
	)
	(segment
		(start 443.379606 -40.0431)
		(end 442.973206 -39.6367)
		(width 0.10795)
		(layer "B.Cu")
		(net "BMC_M_A4")
	)
	(segment
		(start 440.865006 -36.9951)
		(end 441.195206 -36.6649)
		(width 0.10795)
		(layer "B.Cu")
		(net "BMC_M_A4")
	)
	(segment
		(start 440.992006 -37.3253)
		(end 440.865006 -37.1983)
		(width 0.10795)
		(layer "B.Cu")
		(net "BMC_M_A4")
	)
	(segment
		(start 441.017406 -36.2585)
		(end 440.687206 -36.2585)
		(width 0.10795)
		(layer "B.Cu")
		(net "BMC_M_A4")
	)
	(segment
		(start 441.550806 -37.5539)
		(end 441.322206 -37.3253)
		(width 0.10795)
		(layer "B.Cu")
		(net "BMC_M_A4")
	)
	(segment
		(start 443.76848 -42.092626)
		(end 443.989206 -41.8719)
		(width 0.10795)
		(layer "B.Cu")
		(net "BMC_M_A4")
	)
	(segment
		(start 442.185806 -37.6809)
		(end 442.058806 -37.5539)
		(width 0.10795)
		(layer "B.Cu")
		(net "BMC_M_A4")
	)
	(segment
		(start 442.338206 -39.6367)
		(end 442.185806 -39.4843)
		(width 0.10795)
		(layer "B.Cu")
		(net "BMC_M_A4")
	)
	(segment
		(start 441.322206 -37.3253)
		(end 440.992006 -37.3253)
		(width 0.10795)
		(layer "B.Cu")
		(net "BMC_M_A4")
	)
	(segment
		(start 440.865006 -37.1983)
		(end 440.865006 -36.9951)
		(width 0.10795)
		(layer "B.Cu")
		(net "BMC_M_A4")
	)
	(segment
		(start 443.836806 -40.0431)
		(end 443.379606 -40.0431)
		(width 0.10795)
		(layer "B.Cu")
		(net "BMC_M_A4")
	)
	(segment
		(start 442.973206 -39.6367)
		(end 442.338206 -39.6367)
		(width 0.10795)
		(layer "B.Cu")
		(net "BMC_M_A4")
	)
	(segment
		(start 443.405006 -42.092626)
		(end 443.76848 -42.092626)
		(width 0.10795)
		(layer "B.Cu")
		(net "BMC_M_A4")
	)
	(segment
		(start 443.989206 -40.1955)
		(end 443.836806 -40.0431)
		(width 0.10795)
		(layer "B.Cu")
		(net "BMC_M_A4")
	)
	(segment
		(start 441.195206 -36.6649)
		(end 441.195206 -36.4363)
		(width 0.10795)
		(layer "B.Cu")
		(net "BMC_M_A4")
	)
	(segment
		(start 442.185806 -39.4843)
		(end 442.185806 -38.398704)
		(width 0.10795)
		(layer "B.Cu")
		(net "BMC_M_A4")
	)
	(segment
		(start 443.989206 -41.8719)
		(end 443.989206 -40.1955)
		(width 0.10795)
		(layer "B.Cu")
		(net "BMC_M_A4")
	)
	(segment
		(start 443.405006 -43.09745)
		(end 443.405006 -42.092626)
		(width 0.10795)
		(layer "B.Cu")
		(net "BMC_M_A4")
	)
	(segment
		(start 423.251122 -39.205662)
		(end 423.251376 -39.205916)
		(width 0.089408)
		(layer "In2.Cu")
		(net "BMC_M_A4")
	)
	(segment
		(start 431.239168 -41.108376)
		(end 431.239168 -40.6908)
		(width 0.089408)
		(layer "In2.Cu")
		(net "BMC_M_A4")
	)
	(segment
		(start 434.194712 -39.701216)
		(end 434.65496 -39.240968)
		(width 0.089408)
		(layer "In2.Cu")
		(net "BMC_M_A4")
	)
	(segment
		(start 425.674028 -40.455596)
		(end 430.533556 -40.455596)
		(width 0.089408)
		(layer "In2.Cu")
		(net "BMC_M_A4")
	)
	(segment
		(start 431.474372 -40.455596)
		(end 432.373532 -40.455596)
		(width 0.089408)
		(layer "In2.Cu")
		(net "BMC_M_A4")
	)
	(segment
		(start 423.19702 -38.98011)
		(end 423.19702 -39.07536)
		(width 0.089408)
		(layer "In2.Cu")
		(net "BMC_M_A4")
	)
	(segment
		(start 439.909204 -36.756848)
		(end 440.043316 -36.62299)
		(width 0.089408)
		(layer "In2.Cu")
		(net "BMC_M_A4")
	)
	(segment
		(start 421.89019 -38.134798)
		(end 421.85336 -38.171628)
		(width 0.089408)
		(layer "In2.Cu")
		(net "BMC_M_A4")
	)
	(segment
		(start 440.518042 -36.111688)
		(end 440.518804 -36.111688)
		(width 0.089408)
		(layer "In2.Cu")
		(net "BMC_M_A4")
	)
	(segment
		(start 421.85336 -38.171628)
		(end 421.85336 -38.172898)
		(width 0.089408)
		(layer "In2.Cu")
		(net "BMC_M_A4")
	)
	(segment
		(start 423.687748 -39.386764)
		(end 424.107864 -39.80688)
		(width 0.089408)
		(layer "In2.Cu")
		(net "BMC_M_A4")
	)
	(segment
		(start 438.79516 -37.870892)
		(end 439.909204 -36.756848)
		(width 0.089408)
		(layer "In2.Cu")
		(net "BMC_M_A4")
	)
	(segment
		(start 430.76876 -40.6908)
		(end 430.76876 -41.108376)
		(width 0.089408)
		(layer "In2.Cu")
		(net "BMC_M_A4")
	)
	(segment
		(start 435.991 -38.687502)
		(end 436.545482 -38.687502)
		(width 0.089408)
		(layer "In2.Cu")
		(net "BMC_M_A4")
	)
	(segment
		(start 422.534588 -38.540182)
		(end 422.640252 -38.540182)
		(width 0.089408)
		(layer "In2.Cu")
		(net "BMC_M_A4")
	)
	(segment
		(start 421.969184 -38.518592)
		(end 422.056814 -38.606222)
		(width 0.089408)
		(layer "In2.Cu")
		(net "BMC_M_A4")
	)
	(segment
		(start 440.214258 -36.28009)
		(end 440.287156 -36.207192)
		(width 0.089408)
		(layer "In2.Cu")
		(net "BMC_M_A4")
	)
	(arc
		(start 431.239168 -40.6908)
		(mid 431.308058 -40.524486)
		(end 431.474372 -40.455596)
		(width 0.089408)
		(layer "In2.Cu")
		(net "BMC_M_A4")
	)
	(arc
		(start 434.65496 -39.240968)
		(mid 435.267926 -38.831334)
		(end 435.991 -38.687502)
		(width 0.089408)
		(layer "In2.Cu")
		(net "BMC_M_A4")
	)
	(arc
		(start 423.545508 -39.327836)
		(mid 423.622492 -39.343149)
		(end 423.687748 -39.386764)
		(width 0.089408)
		(layer "In2.Cu")
		(net "BMC_M_A4")
	)
	(arc
		(start 423.251376 -39.205916)
		(mid 423.386311 -39.29614)
		(end 423.545508 -39.327836)
		(width 0.089408)
		(layer "In2.Cu")
		(net "BMC_M_A4")
	)
	(arc
		(start 440.287156 -36.207192)
		(mid 440.393102 -36.136465)
		(end 440.518042 -36.111688)
		(width 0.089408)
		(layer "In2.Cu")
		(net "BMC_M_A4")
	)
	(arc
		(start 436.863998 -38.670738)
		(mid 437.909149 -38.46292)
		(end 438.79516 -37.870892)
		(width 0.089408)
		(layer "In2.Cu")
		(net "BMC_M_A4")
	)
	(arc
		(start 421.919146 -38.44925)
		(mid 421.941394 -38.485921)
		(end 421.969184 -38.518592)
		(width 0.089408)
		(layer "In2.Cu")
		(net "BMC_M_A4")
	)
	(arc
		(start 424.107864 -39.80688)
		(mid 424.826412 -40.287062)
		(end 425.674028 -40.455596)
		(width 0.089408)
		(layer "In2.Cu")
		(net "BMC_M_A4")
	)
	(arc
		(start 422.640252 -38.540182)
		(mid 422.884923 -38.588832)
		(end 423.092372 -38.72738)
		(width 0.089408)
		(layer "In2.Cu")
		(net "BMC_M_A4")
	)
	(arc
		(start 436.545482 -38.687502)
		(mid 436.70496 -38.683297)
		(end 436.863998 -38.670738)
		(width 0.089408)
		(layer "In2.Cu")
		(net "BMC_M_A4")
	)
	(arc
		(start 440.043316 -36.62299)
		(mid 440.112145 -36.51984)
		(end 440.13628 -36.3982)
		(width 0.089408)
		(layer "In2.Cu")
		(net "BMC_M_A4")
	)
	(arc
		(start 422.056814 -38.606222)
		(mid 422.215982 -38.672263)
		(end 422.375076 -38.606222)
		(width 0.089408)
		(layer "In2.Cu")
		(net "BMC_M_A4")
	)
	(arc
		(start 423.19702 -39.07536)
		(mid 423.211125 -39.145889)
		(end 423.251122 -39.205662)
		(width 0.089408)
		(layer "In2.Cu")
		(net "BMC_M_A4")
	)
	(arc
		(start 430.76876 -41.108376)
		(mid 431.003964 -41.34358)
		(end 431.239168 -41.108376)
		(width 0.089408)
		(layer "In2.Cu")
		(net "BMC_M_A4")
	)
	(arc
		(start 422.375076 -38.606222)
		(mid 422.448261 -38.557322)
		(end 422.534588 -38.540182)
		(width 0.089408)
		(layer "In2.Cu")
		(net "BMC_M_A4")
	)
	(arc
		(start 430.533556 -40.455596)
		(mid 430.69987 -40.524486)
		(end 430.76876 -40.6908)
		(width 0.089408)
		(layer "In2.Cu")
		(net "BMC_M_A4")
	)
	(arc
		(start 423.092372 -38.72738)
		(mid 423.16985 -38.843334)
		(end 423.19702 -38.98011)
		(width 0.089408)
		(layer "In2.Cu")
		(net "BMC_M_A4")
	)
	(arc
		(start 440.13628 -36.3982)
		(mid 440.169263 -36.335179)
		(end 440.214258 -36.28009)
		(width 0.089408)
		(layer "In2.Cu")
		(net "BMC_M_A4")
	)
	(arc
		(start 440.518804 -36.111688)
		(mid 440.589178 -36.125686)
		(end 440.648852 -36.165536)
		(width 0.089408)
		(layer "In2.Cu")
		(net "BMC_M_A4")
	)
	(arc
		(start 440.648852 -36.165536)
		(mid 440.677268 -36.208203)
		(end 440.687206 -36.2585)
		(width 0.089408)
		(layer "In2.Cu")
		(net "BMC_M_A4")
	)
	(arc
		(start 432.373532 -40.455596)
		(mid 433.359156 -40.259543)
		(end 434.194712 -39.701216)
		(width 0.089408)
		(layer "In2.Cu")
		(net "BMC_M_A4")
	)
	(arc
		(start 421.85336 -38.172898)
		(mid 421.870044 -38.31493)
		(end 421.919146 -38.44925)
		(width 0.089408)
		(layer "In2.Cu")
		(net "BMC_M_A4")
	)
	(segment
		(start 438.153048 -35.032442)
		(end 438.540906 -35.4203)
		(width 0.10795)
		(layer "F.Cu")
		(net "BMC_M_A3")
	)
	(segment
		(start 438.12206 -35.032442)
		(end 438.153048 -35.032442)
		(width 0.10795)
		(layer "F.Cu")
		(net "BMC_M_A3")
	)
	(segment
		(start 419.890194 -36.934648)
		(end 419.490144 -37.334952)
		(width 0.1016)
		(layer "F.Cu")
		(net "BMC_M_A3")
	)
	(via
		(at 419.490144 -37.334952)
		(size 0.4572)
		(drill 0.2032)
		(layers "F.Cu" "B.Cu")
		(net "BMC_M_A3")
	)
	(via
		(at 438.540906 -35.4203)
		(size 0.4572)
		(drill 0.2032)
		(layers "F.Cu" "B.Cu")
		(net "BMC_M_A3")
	)
	(via
		(at 431.214276 -38.428168)
		(size 0.508)
		(drill 0.254)
		(layers "F.Cu" "B.Cu")
		(net "BMC_M_A3")
	)
	(segment
		(start 439.534046 -39.3573)
		(end 439.341006 -39.55034)
		(width 0.10795)
		(layer "B.Cu")
		(net "BMC_M_A3")
	)
	(segment
		(start 431.9016 -38.396672)
		(end 435.184296 -35.113468)
		(width 0.10795)
		(layer "B.Cu")
		(net "BMC_M_A3")
	)
	(segment
		(start 440.405774 -42.092626)
		(end 439.976006 -42.092626)
		(width 0.10795)
		(layer "B.Cu")
		(net "BMC_M_A3")
	)
	(segment
		(start 422.648888 -37.741352)
		(end 425.450508 -37.741352)
		(width 0.10795)
		(layer "B.Cu")
		(net "BMC_M_A3")
	)
	(segment
		(start 422.169844 -37.068252)
		(end 422.189148 -37.087302)
		(width 0.10795)
		(layer "B.Cu")
		(net "BMC_M_A3")
	)
	(segment
		(start 438.7469 -35.626294)
		(end 438.8358 -35.626294)
		(width 0.10795)
		(layer "B.Cu")
		(net "BMC_M_A3")
	)
	(segment
		(start 440.067954 -39.9542)
		(end 440.534806 -40.421052)
		(width 0.10795)
		(layer "B.Cu")
		(net "BMC_M_A3")
	)
	(segment
		(start 438.8358 -35.626294)
		(end 440.077606 -36.8681)
		(width 0.10795)
		(layer "B.Cu")
		(net "BMC_M_A3")
	)
	(segment
		(start 438.723532 -35.4203)
		(end 438.540906 -35.4203)
		(width 0.10795)
		(layer "B.Cu")
		(net "BMC_M_A3")
	)
	(segment
		(start 440.077606 -39.2049)
		(end 439.925206 -39.3573)
		(width 0.10795)
		(layer "B.Cu")
		(net "BMC_M_A3")
	)
	(segment
		(start 419.490144 -37.334952)
		(end 419.490144 -37.213286)
		(width 0.10795)
		(layer "B.Cu")
		(net "BMC_M_A3")
	)
	(segment
		(start 438.901332 -35.028124)
		(end 438.901332 -35.154108)
		(width 0.10795)
		(layer "B.Cu")
		(net "BMC_M_A3")
	)
	(segment
		(start 427.39564 -38.428168)
		(end 427.744382 -38.428168)
		(width 0.10795)
		(layer "B.Cu")
		(net "BMC_M_A3")
	)
	(segment
		(start 427.10354 -37.892482)
		(end 427.10354 -38.136068)
		(width 0.10795)
		(layer "B.Cu")
		(net "BMC_M_A3")
	)
	(segment
		(start 438.540906 -35.4203)
		(end 438.7469 -35.626294)
		(width 0.10795)
		(layer "B.Cu")
		(net "BMC_M_A3")
	)
	(segment
		(start 439.341006 -39.55034)
		(end 439.341006 -39.7383)
		(width 0.10795)
		(layer "B.Cu")
		(net "BMC_M_A3")
	)
	(segment
		(start 428.47768 -38.67531)
		(end 428.47768 -38.672516)
		(width 0.10795)
		(layer "B.Cu")
		(net "BMC_M_A3")
	)
	(segment
		(start 425.639484 -37.819584)
		(end 425.932346 -38.112446)
		(width 0.10795)
		(layer "B.Cu")
		(net "BMC_M_A3")
	)
	(segment
		(start 429.699928 -38.428168)
		(end 431.214276 -38.428168)
		(width 0.10795)
		(layer "B.Cu")
		(net "BMC_M_A3")
	)
	(segment
		(start 440.077606 -36.8681)
		(end 440.077606 -39.2049)
		(width 0.10795)
		(layer "B.Cu")
		(net "BMC_M_A3")
	)
	(segment
		(start 439.341006 -39.7383)
		(end 439.556906 -39.9542)
		(width 0.10795)
		(layer "B.Cu")
		(net "BMC_M_A3")
	)
	(segment
		(start 439.976006 -43.09745)
		(end 439.976006 -42.092626)
		(width 0.10795)
		(layer "B.Cu")
		(net "BMC_M_A3")
	)
	(segment
		(start 419.776656 -36.941252)
		(end 421.863266 -36.941252)
		(width 0.10795)
		(layer "B.Cu")
		(net "BMC_M_A3")
	)
	(segment
		(start 431.214276 -38.428168)
		(end 431.824892 -38.428168)
		(width 0.10795)
		(layer "B.Cu")
		(net "BMC_M_A3")
	)
	(segment
		(start 427.98873 -38.672516)
		(end 427.98873 -38.67531)
		(width 0.10795)
		(layer "B.Cu")
		(net "BMC_M_A3")
	)
	(segment
		(start 440.534806 -41.963594)
		(end 440.405774 -42.092626)
		(width 0.10795)
		(layer "B.Cu")
		(net "BMC_M_A3")
	)
	(segment
		(start 426.331634 -38.2778)
		(end 426.473112 -38.2778)
		(width 0.10795)
		(layer "B.Cu")
		(net "BMC_M_A3")
	)
	(segment
		(start 435.915308 -34.8107)
		(end 438.683908 -34.8107)
		(width 0.10795)
		(layer "B.Cu")
		(net "BMC_M_A3")
	)
	(segment
		(start 428.96663 -38.672516)
		(end 428.96663 -38.67531)
		(width 0.10795)
		(layer "B.Cu")
		(net "BMC_M_A3")
	)
	(segment
		(start 422.296844 -37.347652)
		(end 422.296844 -37.443156)
		(width 0.10795)
		(layer "B.Cu")
		(net "BMC_M_A3")
	)
	(segment
		(start 439.556906 -39.9542)
		(end 440.067954 -39.9542)
		(width 0.10795)
		(layer "B.Cu")
		(net "BMC_M_A3")
	)
	(segment
		(start 426.61459 -38.136322)
		(end 426.61459 -37.892482)
		(width 0.10795)
		(layer "B.Cu")
		(net "BMC_M_A3")
	)
	(segment
		(start 439.925206 -39.3573)
		(end 439.534046 -39.3573)
		(width 0.10795)
		(layer "B.Cu")
		(net "BMC_M_A3")
	)
	(segment
		(start 429.45558 -38.67531)
		(end 429.45558 -38.672516)
		(width 0.10795)
		(layer "B.Cu")
		(net "BMC_M_A3")
	)
	(segment
		(start 440.534806 -40.421052)
		(end 440.534806 -41.963594)
		(width 0.10795)
		(layer "B.Cu")
		(net "BMC_M_A3")
	)
	(arc
		(start 427.10354 -38.136068)
		(mid 427.189094 -38.342614)
		(end 427.39564 -38.428168)
		(width 0.10795)
		(layer "B.Cu")
		(net "BMC_M_A3")
	)
	(arc
		(start 428.47768 -38.672516)
		(mid 428.722282 -38.427914)
		(end 428.96663 -38.672516)
		(width 0.10795)
		(layer "B.Cu")
		(net "BMC_M_A3")
	)
	(arc
		(start 435.184296 -35.113468)
		(mid 435.519687 -34.889367)
		(end 435.915308 -34.8107)
		(width 0.10795)
		(layer "B.Cu")
		(net "BMC_M_A3")
	)
	(arc
		(start 438.901332 -35.154108)
		(mid 438.876313 -35.279887)
		(end 438.805066 -35.386518)
		(width 0.10795)
		(layer "B.Cu")
		(net "BMC_M_A3")
	)
	(arc
		(start 438.683908 -34.8107)
		(mid 438.83765 -34.874382)
		(end 438.901332 -35.028124)
		(width 0.10795)
		(layer "B.Cu")
		(net "BMC_M_A3")
	)
	(arc
		(start 425.932346 -38.112446)
		(mid 426.115541 -38.234853)
		(end 426.331634 -38.2778)
		(width 0.10795)
		(layer "B.Cu")
		(net "BMC_M_A3")
	)
	(arc
		(start 421.863266 -36.941252)
		(mid 422.029189 -36.974256)
		(end 422.169844 -37.068252)
		(width 0.10795)
		(layer "B.Cu")
		(net "BMC_M_A3")
	)
	(arc
		(start 438.805066 -35.386518)
		(mid 438.767658 -35.411513)
		(end 438.723532 -35.4203)
		(width 0.10795)
		(layer "B.Cu")
		(net "BMC_M_A3")
	)
	(arc
		(start 426.473112 -38.2778)
		(mid 426.573152 -38.236362)
		(end 426.61459 -38.136322)
		(width 0.10795)
		(layer "B.Cu")
		(net "BMC_M_A3")
	)
	(arc
		(start 428.96663 -38.67531)
		(mid 429.211232 -38.919912)
		(end 429.45558 -38.67531)
		(width 0.10795)
		(layer "B.Cu")
		(net "BMC_M_A3")
	)
	(arc
		(start 425.450508 -37.741352)
		(mid 425.552778 -37.761677)
		(end 425.639484 -37.819584)
		(width 0.10795)
		(layer "B.Cu")
		(net "BMC_M_A3")
	)
	(arc
		(start 427.98873 -38.67531)
		(mid 428.233332 -38.919912)
		(end 428.47768 -38.67531)
		(width 0.10795)
		(layer "B.Cu")
		(net "BMC_M_A3")
	)
	(arc
		(start 431.824892 -38.428168)
		(mid 431.866368 -38.420029)
		(end 431.9016 -38.396672)
		(width 0.10795)
		(layer "B.Cu")
		(net "BMC_M_A3")
	)
	(arc
		(start 419.490144 -37.213286)
		(mid 419.510078 -37.113071)
		(end 419.566852 -37.02812)
		(width 0.10795)
		(layer "B.Cu")
		(net "BMC_M_A3")
	)
	(arc
		(start 422.189148 -37.087302)
		(mid 422.268854 -37.20678)
		(end 422.296844 -37.347652)
		(width 0.10795)
		(layer "B.Cu")
		(net "BMC_M_A3")
	)
	(arc
		(start 419.566852 -37.02812)
		(mid 419.663111 -36.963802)
		(end 419.776656 -36.941252)
		(width 0.10795)
		(layer "B.Cu")
		(net "BMC_M_A3")
	)
	(arc
		(start 426.61459 -37.892482)
		(mid 426.859192 -37.64788)
		(end 427.10354 -37.892482)
		(width 0.10795)
		(layer "B.Cu")
		(net "BMC_M_A3")
	)
	(arc
		(start 427.744382 -38.428168)
		(mid 427.917162 -38.499736)
		(end 427.98873 -38.672516)
		(width 0.10795)
		(layer "B.Cu")
		(net "BMC_M_A3")
	)
	(arc
		(start 422.373044 -37.627052)
		(mid 422.499602 -37.711616)
		(end 422.648888 -37.741352)
		(width 0.10795)
		(layer "B.Cu")
		(net "BMC_M_A3")
	)
	(arc
		(start 422.296844 -37.443156)
		(mid 422.316643 -37.54269)
		(end 422.373044 -37.627052)
		(width 0.10795)
		(layer "B.Cu")
		(net "BMC_M_A3")
	)
	(arc
		(start 429.45558 -38.672516)
		(mid 429.527148 -38.499736)
		(end 429.699928 -38.428168)
		(width 0.10795)
		(layer "B.Cu")
		(net "BMC_M_A3")
	)
	(segment
		(start 421.49014 -36.934648)
		(end 421.09009 -37.334698)
		(width 0.1016)
		(layer "F.Cu")
		(net "BMC_M_A2")
	)
	(segment
		(start 441.321952 -36.632388)
		(end 441.321952 -36.633404)
		(width 0.10795)
		(layer "F.Cu")
		(net "BMC_M_A2")
	)
	(segment
		(start 441.321952 -36.633404)
		(end 440.941206 -37.01415)
		(width 0.10795)
		(layer "F.Cu")
		(net "BMC_M_A2")
	)
	(segment
		(start 440.941206 -37.01415)
		(end 440.941206 -37.8587)
		(width 0.10795)
		(layer "F.Cu")
		(net "BMC_M_A2")
	)
	(via
		(at 421.09009 -37.334698)
		(size 0.4572)
		(drill 0.2032)
		(layers "F.Cu" "B.Cu")
		(net "BMC_M_A2")
	)
	(via
		(at 442.320426 -40.0431)
		(size 0.508)
		(drill 0.254)
		(layers "F.Cu" "B.Cu")
		(net "BMC_M_A2")
	)
	(via
		(at 440.941206 -37.8587)
		(size 0.4572)
		(drill 0.2032)
		(layers "F.Cu" "B.Cu")
		(net "BMC_M_A2")
	)
	(segment
		(start 442.262006 -42.092626)
		(end 442.66358 -42.092626)
		(width 0.10795)
		(layer "B.Cu")
		(net "BMC_M_A2")
	)
	(segment
		(start 442.592206 -40.0431)
		(end 442.320426 -40.0431)
		(width 0.10795)
		(layer "B.Cu")
		(net "BMC_M_A2")
	)
	(segment
		(start 442.846206 -40.2971)
		(end 442.592206 -40.0431)
		(width 0.10795)
		(layer "B.Cu")
		(net "BMC_M_A2")
	)
	(segment
		(start 440.941206 -37.8587)
		(end 440.858402 -37.941504)
		(width 0.10795)
		(layer "B.Cu")
		(net "BMC_M_A2")
	)
	(segment
		(start 440.858402 -37.941504)
		(end 440.858402 -39.3827)
		(width 0.10795)
		(layer "B.Cu")
		(net "BMC_M_A2")
	)
	(segment
		(start 442.262006 -43.09745)
		(end 442.262006 -42.092626)
		(width 0.10795)
		(layer "B.Cu")
		(net "BMC_M_A2")
	)
	(segment
		(start 441.347606 -39.3827)
		(end 441.347606 -38.2143)
		(width 0.10795)
		(layer "B.Cu")
		(net "BMC_M_A2")
	)
	(segment
		(start 442.846206 -41.91)
		(end 442.846206 -40.2971)
		(width 0.10795)
		(layer "B.Cu")
		(net "BMC_M_A2")
	)
	(segment
		(start 441.836556 -39.74846)
		(end 442.131196 -40.0431)
		(width 0.10795)
		(layer "B.Cu")
		(net "BMC_M_A2")
	)
	(segment
		(start 442.66358 -42.092626)
		(end 442.846206 -41.91)
		(width 0.10795)
		(layer "B.Cu")
		(net "BMC_M_A2")
	)
	(segment
		(start 441.836556 -38.2143)
		(end 441.836556 -39.74846)
		(width 0.10795)
		(layer "B.Cu")
		(net "BMC_M_A2")
	)
	(segment
		(start 442.131196 -40.0431)
		(end 442.320426 -40.0431)
		(width 0.10795)
		(layer "B.Cu")
		(net "BMC_M_A2")
	)
	(arc
		(start 440.858402 -39.3827)
		(mid 441.103004 -39.627302)
		(end 441.347606 -39.3827)
		(width 0.10795)
		(layer "B.Cu")
		(net "BMC_M_A2")
	)
	(arc
		(start 441.347606 -38.2143)
		(mid 441.592208 -37.969698)
		(end 441.836556 -38.2143)
		(width 0.10795)
		(layer "B.Cu")
		(net "BMC_M_A2")
	)
	(segment
		(start 421.695372 -38.60038)
		(end 422.237916 -39.142924)
		(width 0.089408)
		(layer "In2.Cu")
		(net "BMC_M_A2")
	)
	(segment
		(start 438.333896 -39.84625)
		(end 439.235342 -38.944804)
		(width 0.089408)
		(layer "In2.Cu")
		(net "BMC_M_A2")
	)
	(segment
		(start 426.002958 -40.944038)
		(end 427.706282 -40.944038)
		(width 0.089408)
		(layer "In2.Cu")
		(net "BMC_M_A2")
	)
	(segment
		(start 428.984918 -41.473628)
		(end 429.979074 -42.467784)
		(width 0.089408)
		(layer "In2.Cu")
		(net "BMC_M_A2")
	)
	(segment
		(start 436.925466 -40.79494)
		(end 436.948072 -40.772334)
		(width 0.089408)
		(layer "In2.Cu")
		(net "BMC_M_A2")
	)
	(segment
		(start 437.93918 -39.98341)
		(end 438.00268 -39.98341)
		(width 0.089408)
		(layer "In2.Cu")
		(net "BMC_M_A2")
	)
	(segment
		(start 421.509444 -38.150038)
		(end 421.509444 -38.151308)
		(width 0.089408)
		(layer "In2.Cu")
		(net "BMC_M_A2")
	)
	(segment
		(start 421.21582 -37.638228)
		(end 421.355012 -37.77742)
		(width 0.089408)
		(layer "In2.Cu")
		(net "BMC_M_A2")
	)
	(segment
		(start 423.219372 -40.001444)
		(end 423.21988 -40.001952)
		(width 0.089408)
		(layer "In2.Cu")
		(net "BMC_M_A2")
	)
	(segment
		(start 437.059324 -40.501824)
		(end 437.277256 -40.283892)
		(width 0.089408)
		(layer "In2.Cu")
		(net "BMC_M_A2")
	)
	(segment
		(start 430.74463 -42.784776)
		(end 432.121564 -42.784776)
		(width 0.089408)
		(layer "In2.Cu")
		(net "BMC_M_A2")
	)
	(segment
		(start 422.686988 -39.328852)
		(end 422.73728 -39.328852)
		(width 0.089408)
		(layer "In2.Cu")
		(net "BMC_M_A2")
	)
	(segment
		(start 439.235342 -38.944804)
		(end 439.883042 -38.29685)
		(width 0.089408)
		(layer "In2.Cu")
		(net "BMC_M_A2")
	)
	(arc
		(start 436.948072 -40.772334)
		(mid 436.98702 -40.71311)
		(end 437.00065 -40.643556)
		(width 0.089408)
		(layer "In2.Cu")
		(net "BMC_M_A2")
	)
	(arc
		(start 422.73728 -39.328852)
		(mid 422.982621 -39.430475)
		(end 423.084244 -39.675816)
		(width 0.089408)
		(layer "In2.Cu")
		(net "BMC_M_A2")
	)
	(arc
		(start 437.00065 -40.643556)
		(mid 437.015905 -40.566864)
		(end 437.059324 -40.501824)
		(width 0.089408)
		(layer "In2.Cu")
		(net "BMC_M_A2")
	)
	(arc
		(start 427.706282 -40.944038)
		(mid 428.398274 -41.081666)
		(end 428.984918 -41.473628)
		(width 0.089408)
		(layer "In2.Cu")
		(net "BMC_M_A2")
	)
	(arc
		(start 438.00268 -39.98341)
		(mid 438.18192 -39.947757)
		(end 438.333896 -39.84625)
		(width 0.089408)
		(layer "In2.Cu")
		(net "BMC_M_A2")
	)
	(arc
		(start 422.237916 -39.142924)
		(mid 422.443966 -39.280539)
		(end 422.686988 -39.328852)
		(width 0.089408)
		(layer "In2.Cu")
		(net "BMC_M_A2")
	)
	(arc
		(start 423.21988 -40.001952)
		(mid 423.262047 -40.043365)
		(end 423.30497 -40.083994)
		(width 0.089408)
		(layer "In2.Cu")
		(net "BMC_M_A2")
	)
	(arc
		(start 437.277256 -40.283892)
		(mid 437.30213 -40.259843)
		(end 437.327802 -40.236648)
		(width 0.089408)
		(layer "In2.Cu")
		(net "BMC_M_A2")
	)
	(arc
		(start 432.121564 -42.784776)
		(mid 434.721415 -42.267633)
		(end 436.925466 -40.79494)
		(width 0.089408)
		(layer "In2.Cu")
		(net "BMC_M_A2")
	)
	(arc
		(start 423.084244 -39.675816)
		(mid 423.11952 -39.852021)
		(end 423.219372 -40.001444)
		(width 0.089408)
		(layer "In2.Cu")
		(net "BMC_M_A2")
	)
	(arc
		(start 421.355012 -37.77742)
		(mid 421.469297 -37.948364)
		(end 421.509444 -38.150038)
		(width 0.089408)
		(layer "In2.Cu")
		(net "BMC_M_A2")
	)
	(arc
		(start 437.327802 -40.236648)
		(mid 437.608305 -40.049222)
		(end 437.93918 -39.98341)
		(width 0.089408)
		(layer "In2.Cu")
		(net "BMC_M_A2")
	)
	(arc
		(start 421.509444 -38.151308)
		(mid 421.557765 -38.394326)
		(end 421.695372 -38.60038)
		(width 0.089408)
		(layer "In2.Cu")
		(net "BMC_M_A2")
	)
	(arc
		(start 423.30497 -40.083994)
		(mid 424.587084 -40.723819)
		(end 426.002958 -40.944038)
		(width 0.089408)
		(layer "In2.Cu")
		(net "BMC_M_A2")
	)
	(arc
		(start 439.883042 -38.29685)
		(mid 440.368547 -37.972539)
		(end 440.941206 -37.8587)
		(width 0.089408)
		(layer "In2.Cu")
		(net "BMC_M_A2")
	)
	(arc
		(start 421.09009 -37.334698)
		(mid 421.122765 -37.498969)
		(end 421.21582 -37.638228)
		(width 0.089408)
		(layer "In2.Cu")
		(net "BMC_M_A2")
	)
	(arc
		(start 429.979074 -42.467784)
		(mid 430.330328 -42.702421)
		(end 430.74463 -42.784776)
		(width 0.089408)
		(layer "In2.Cu")
		(net "BMC_M_A2")
	)
	(segment
		(start 437.300116 -40.058594)
		(end 437.300116 -38.5445)
		(width 0.10795)
		(layer "F.Cu")
		(net "BMC_M_A13")
	)
	(segment
		(start 428.48022 -41.185338)
		(end 425.579032 -38.28415)
		(width 0.10795)
		(layer "F.Cu")
		(net "BMC_M_A13")
	)
	(segment
		(start 437.78932 -38.5445)
		(end 437.78932 -39.660322)
		(width 0.10795)
		(layer "F.Cu")
		(net "BMC_M_A13")
	)
	(segment
		(start 437.690006 -42.108374)
		(end 437.300116 -41.718484)
		(width 0.10795)
		(layer "F.Cu")
		(net "BMC_M_A13")
	)
	(segment
		(start 437.32196 -37.432488)
		(end 437.322468 -37.432488)
		(width 0.10795)
		(layer "F.Cu")
		(net "BMC_M_A13")
	)
	(segment
		(start 429.73625 -40.004492)
		(end 429.73625 -41.11117)
		(width 0.10795)
		(layer "F.Cu")
		(net "BMC_M_A13")
	)
	(segment
		(start 437.112664 -40.246046)
		(end 437.300116 -40.058594)
		(width 0.10795)
		(layer "F.Cu")
		(net "BMC_M_A13")
	)
	(segment
		(start 431.717704 -40.061642)
		(end 431.39995 -40.061642)
		(width 0.10795)
		(layer "F.Cu")
		(net "BMC_M_A13")
	)
	(segment
		(start 424.252644 -37.734748)
		(end 423.890186 -37.734748)
		(width 0.10795)
		(layer "F.Cu")
		(net "BMC_M_A13")
	)
	(segment
		(start 431.203862 -41.11117)
		(end 431.203862 -40.79494)
		(width 0.10795)
		(layer "F.Cu")
		(net "BMC_M_A13")
	)
	(segment
		(start 437.300116 -41.707054)
		(end 437.112664 -41.519602)
		(width 0.10795)
		(layer "F.Cu")
		(net "BMC_M_A13")
	)
	(segment
		(start 438.278524 -38.389052)
		(end 437.32196 -37.432488)
		(width 0.10795)
		(layer "F.Cu")
		(net "BMC_M_A13")
	)
	(segment
		(start 437.300116 -41.718484)
		(end 437.300116 -41.707054)
		(width 0.10795)
		(layer "F.Cu")
		(net "BMC_M_A13")
	)
	(segment
		(start 437.112664 -41.519602)
		(end 437.112664 -40.246046)
		(width 0.10795)
		(layer "F.Cu")
		(net "BMC_M_A13")
	)
	(segment
		(start 431.44821 -40.550592)
		(end 431.717704 -40.550592)
		(width 0.10795)
		(layer "F.Cu")
		(net "BMC_M_A13")
	)
	(segment
		(start 430.225454 -41.11117)
		(end 430.225454 -40.004492)
		(width 0.10795)
		(layer "F.Cu")
		(net "BMC_M_A13")
	)
	(segment
		(start 431.887884 -41.300908)
		(end 431.3936 -41.300908)
		(width 0.10795)
		(layer "F.Cu")
		(net "BMC_M_A13")
	)
	(segment
		(start 437.322468 -37.432488)
		(end 437.709056 -37.0459)
		(width 0.10795)
		(layer "F.Cu")
		(net "BMC_M_A13")
	)
	(segment
		(start 429.464978 -41.382442)
		(end 428.95647 -41.382442)
		(width 0.10795)
		(layer "F.Cu")
		(net "BMC_M_A13")
	)
	(segment
		(start 438.278524 -39.660322)
		(end 438.278524 -38.389052)
		(width 0.10795)
		(layer "F.Cu")
		(net "BMC_M_A13")
	)
	(segment
		(start 430.714658 -39.865554)
		(end 430.714658 -41.11117)
		(width 0.10795)
		(layer "F.Cu")
		(net "BMC_M_A13")
	)
	(segment
		(start 437.690006 -43.124374)
		(end 437.690006 -42.108374)
		(width 0.10795)
		(layer "F.Cu")
		(net "BMC_M_A13")
	)
	(segment
		(start 432.012344 -40.962072)
		(end 432.012344 -41.176448)
		(width 0.10795)
		(layer "F.Cu")
		(net "BMC_M_A13")
	)
	(via
		(at 432.012344 -40.962072)
		(size 0.508)
		(drill 0.254)
		(layers "F.Cu" "B.Cu")
		(net "BMC_M_A13")
	)
	(via
		(at 433.399184 -40.2971)
		(size 0.508)
		(drill 0.254)
		(layers "F.Cu" "B.Cu")
		(net "BMC_M_A13")
	)
	(via
		(at 437.709056 -37.0459)
		(size 0.4572)
		(drill 0.2032)
		(layers "F.Cu" "B.Cu")
		(net "BMC_M_A13")
	)
	(arc
		(start 431.203862 -39.865554)
		(mid 430.95926 -39.620952)
		(end 430.714658 -39.865554)
		(width 0.10795)
		(layer "F.Cu")
		(net "BMC_M_A13")
	)
	(arc
		(start 431.717704 -40.550592)
		(mid 431.962052 -40.306244)
		(end 431.717704 -40.061642)
		(width 0.10795)
		(layer "F.Cu")
		(net "BMC_M_A13")
	)
	(arc
		(start 430.225454 -40.004492)
		(mid 429.980852 -39.75989)
		(end 429.73625 -40.004492)
		(width 0.10795)
		(layer "F.Cu")
		(net "BMC_M_A13")
	)
	(arc
		(start 428.95647 -41.382442)
		(mid 428.698721 -41.331284)
		(end 428.48022 -41.185338)
		(width 0.10795)
		(layer "F.Cu")
		(net "BMC_M_A13")
	)
	(arc
		(start 432.012344 -41.176448)
		(mid 431.975891 -41.264455)
		(end 431.887884 -41.300908)
		(width 0.10795)
		(layer "F.Cu")
		(net "BMC_M_A13")
	)
	(arc
		(start 437.78932 -39.660322)
		(mid 438.033922 -39.904924)
		(end 438.278524 -39.660322)
		(width 0.10795)
		(layer "F.Cu")
		(net "BMC_M_A13")
	)
	(arc
		(start 430.714658 -41.11117)
		(mid 430.470056 -41.355772)
		(end 430.225454 -41.11117)
		(width 0.10795)
		(layer "F.Cu")
		(net "BMC_M_A13")
	)
	(arc
		(start 425.579032 -38.28415)
		(mid 424.97048 -37.877529)
		(end 424.252644 -37.734748)
		(width 0.10795)
		(layer "F.Cu")
		(net "BMC_M_A13")
	)
	(arc
		(start 431.39995 -40.061642)
		(mid 431.261295 -40.004209)
		(end 431.203862 -39.865554)
		(width 0.10795)
		(layer "F.Cu")
		(net "BMC_M_A13")
	)
	(arc
		(start 437.300116 -38.5445)
		(mid 437.544718 -38.299898)
		(end 437.78932 -38.5445)
		(width 0.10795)
		(layer "F.Cu")
		(net "BMC_M_A13")
	)
	(arc
		(start 431.203862 -40.79494)
		(mid 431.27543 -40.62216)
		(end 431.44821 -40.550592)
		(width 0.10795)
		(layer "F.Cu")
		(net "BMC_M_A13")
	)
	(arc
		(start 429.73625 -41.11117)
		(mid 429.656796 -41.302988)
		(end 429.464978 -41.382442)
		(width 0.10795)
		(layer "F.Cu")
		(net "BMC_M_A13")
	)
	(arc
		(start 431.3936 -41.300908)
		(mid 431.259435 -41.245335)
		(end 431.203862 -41.11117)
		(width 0.10795)
		(layer "F.Cu")
		(net "BMC_M_A13")
	)
	(segment
		(start 436.499254 -37.465254)
		(end 436.499 -37.465)
		(width 0.10795)
		(layer "B.Cu")
		(net "BMC_M_A13")
	)
	(segment
		(start 436.372 -37.158422)
		(end 436.372 -37.158168)
		(width 0.10795)
		(layer "B.Cu")
		(net "BMC_M_A13")
	)
	(segment
		(start 432.012344 -40.939212)
		(end 432.483768 -40.467788)
		(width 0.10795)
		(layer "B.Cu")
		(net "BMC_M_A13")
	)
	(segment
		(start 433.399184 -40.2971)
		(end 434.013102 -40.2971)
		(width 0.10795)
		(layer "B.Cu")
		(net "BMC_M_A13")
	)
	(segment
		(start 437.2356 -36.7792)
		(end 437.35625 -36.89985)
		(width 0.10795)
		(layer "B.Cu")
		(net "BMC_M_A13")
	)
	(segment
		(start 432.012344 -40.962072)
		(end 432.012344 -40.939212)
		(width 0.10795)
		(layer "B.Cu")
		(net "BMC_M_A13")
	)
	(segment
		(start 434.362606 -40.15232)
		(end 436.499254 -38.015672)
		(width 0.10795)
		(layer "B.Cu")
		(net "BMC_M_A13")
	)
	(segment
		(start 432.998626 -40.2971)
		(end 433.399184 -40.2971)
		(width 0.10795)
		(layer "B.Cu")
		(net "BMC_M_A13")
	)
	(segment
		(start 436.890668 -36.6395)
		(end 436.898288 -36.6395)
		(width 0.10795)
		(layer "B.Cu")
		(net "BMC_M_A13")
	)
	(arc
		(start 436.499 -37.465)
		(mid 436.405015 -37.324341)
		(end 436.372 -37.158422)
		(width 0.10795)
		(layer "B.Cu")
		(net "BMC_M_A13")
	)
	(arc
		(start 432.483768 -40.467788)
		(mid 432.666832 -40.345405)
		(end 432.882802 -40.302434)
		(width 0.10795)
		(layer "B.Cu")
		(net "BMC_M_A13")
	)
	(arc
		(start 436.898288 -36.6395)
		(mid 437.080833 -36.67581)
		(end 437.2356 -36.7792)
		(width 0.10795)
		(layer "B.Cu")
		(net "BMC_M_A13")
	)
	(arc
		(start 434.013102 -40.2971)
		(mid 434.202256 -40.259475)
		(end 434.362606 -40.15232)
		(width 0.10795)
		(layer "B.Cu")
		(net "BMC_M_A13")
	)
	(arc
		(start 432.882802 -40.302434)
		(mid 432.940652 -40.298425)
		(end 432.998626 -40.2971)
		(width 0.10795)
		(layer "B.Cu")
		(net "BMC_M_A13")
	)
	(arc
		(start 436.499254 -38.015672)
		(mid 436.613197 -37.7405)
		(end 436.499254 -37.465254)
		(width 0.10795)
		(layer "B.Cu")
		(net "BMC_M_A13")
	)
	(arc
		(start 436.372 -37.158168)
		(mid 436.523914 -36.791414)
		(end 436.890668 -36.6395)
		(width 0.10795)
		(layer "B.Cu")
		(net "BMC_M_A13")
	)
	(arc
		(start 437.35625 -36.89985)
		(mid 437.518133 -37.007954)
		(end 437.709056 -37.0459)
		(width 0.10795)
		(layer "B.Cu")
		(net "BMC_M_A13")
	)
	(segment
		(start 422.29024 -36.934648)
		(end 422.703244 -37.347652)
		(width 0.089408)
		(layer "F.Cu")
		(net "BMC_M_A12")
	)
	(segment
		(start 438.686956 -34.232596)
		(end 438.12206 -34.232596)
		(width 0.10795)
		(layer "F.Cu")
		(net "BMC_M_A12")
	)
	(segment
		(start 439.112406 -34.197544)
		(end 439.004202 -34.08934)
		(width 0.10795)
		(layer "F.Cu")
		(net "BMC_M_A12")
	)
	(segment
		(start 439.004202 -34.08934)
		(end 438.830212 -34.08934)
		(width 0.10795)
		(layer "F.Cu")
		(net "BMC_M_A12")
	)
	(segment
		(start 438.830212 -34.08934)
		(end 438.686956 -34.232596)
		(width 0.10795)
		(layer "F.Cu")
		(net "BMC_M_A12")
	)
	(segment
		(start 439.112406 -34.6075)
		(end 439.112406 -34.197544)
		(width 0.10795)
		(layer "F.Cu")
		(net "BMC_M_A12")
	)
	(via
		(at 422.703244 -37.347652)
		(size 0.4572)
		(drill 0.2032)
		(layers "F.Cu" "B.Cu")
		(net "BMC_M_A12")
	)
	(via
		(at 439.112406 -34.6075)
		(size 0.4572)
		(drill 0.2032)
		(layers "F.Cu" "B.Cu")
		(net "BMC_M_A12")
	)
	(via
		(at 433.34051 -36.00196)
		(size 0.508)
		(drill 0.254)
		(layers "F.Cu" "B.Cu")
		(net "BMC_M_A12")
	)
	(segment
		(start 434.059838 -35.282632)
		(end 434.335936 -35.00628)
		(width 0.10795)
		(layer "B.Cu")
		(net "BMC_M_A12")
	)
	(segment
		(start 425.92752 -37.382196)
		(end 423.796714 -37.382196)
		(width 0.10795)
		(layer "B.Cu")
		(net "BMC_M_A12")
	)
	(segment
		(start 429.392334 -37.401754)
		(end 429.392334 -37.694616)
		(width 0.10795)
		(layer "B.Cu")
		(net "BMC_M_A12")
	)
	(segment
		(start 435.479952 -34.5059)
		(end 438.867042 -34.5059)
		(width 0.10795)
		(layer "B.Cu")
		(net "BMC_M_A12")
	)
	(segment
		(start 441.562236 -42.092626)
		(end 441.119006 -42.092626)
		(width 0.10795)
		(layer "B.Cu")
		(net "BMC_M_A12")
	)
	(segment
		(start 435.07152 -34.701734)
		(end 435.116986 -34.656268)
		(width 0.10795)
		(layer "B.Cu")
		(net "BMC_M_A12")
	)
	(segment
		(start 429.881284 -37.694616)
		(end 429.881284 -37.401754)
		(width 0.10795)
		(layer "B.Cu")
		(net "BMC_M_A12")
	)
	(segment
		(start 433.34051 -36.00196)
		(end 434.059838 -35.282632)
		(width 0.10795)
		(layer "B.Cu")
		(net "BMC_M_A12")
	)
	(segment
		(start 440.862212 -40.0431)
		(end 441.388246 -40.0431)
		(width 0.10795)
		(layer "B.Cu")
		(net "BMC_M_A12")
	)
	(segment
		(start 441.703206 -40.35806)
		(end 441.703206 -41.951656)
		(width 0.10795)
		(layer "B.Cu")
		(net "BMC_M_A12")
	)
	(segment
		(start 439.4454 -35.832288)
		(end 440.455812 -36.8427)
		(width 0.10795)
		(layer "B.Cu")
		(net "BMC_M_A12")
	)
	(segment
		(start 431.348134 -37.4015)
		(end 431.348134 -37.682932)
		(width 0.10795)
		(layer "B.Cu")
		(net "BMC_M_A12")
	)
	(segment
		(start 431.74412 -37.157152)
		(end 431.592482 -37.157152)
		(width 0.10795)
		(layer "B.Cu")
		(net "BMC_M_A12")
	)
	(segment
		(start 428.903384 -37.694616)
		(end 428.903384 -37.4015)
		(width 0.10795)
		(layer "B.Cu")
		(net "BMC_M_A12")
	)
	(segment
		(start 430.859184 -37.682932)
		(end 430.859184 -37.401754)
		(width 0.10795)
		(layer "B.Cu")
		(net "BMC_M_A12")
	)
	(segment
		(start 422.406572 -36.667948)
		(end 422.406572 -36.853876)
		(width 0.10795)
		(layer "B.Cu")
		(net "BMC_M_A12")
	)
	(segment
		(start 433.34051 -36.00196)
		(end 432.497484 -36.844986)
		(width 0.10795)
		(layer "B.Cu")
		(net "BMC_M_A12")
	)
	(segment
		(start 441.703206 -41.951656)
		(end 441.562236 -42.092626)
		(width 0.10795)
		(layer "B.Cu")
		(net "BMC_M_A12")
	)
	(segment
		(start 428.414434 -37.4015)
		(end 428.414434 -37.694616)
		(width 0.10795)
		(layer "B.Cu")
		(net "BMC_M_A12")
	)
	(segment
		(start 427.925484 -37.694616)
		(end 427.925484 -37.4015)
		(width 0.10795)
		(layer "B.Cu")
		(net "BMC_M_A12")
	)
	(segment
		(start 440.455812 -39.6367)
		(end 440.862212 -40.0431)
		(width 0.10795)
		(layer "B.Cu")
		(net "BMC_M_A12")
	)
	(segment
		(start 422.545002 -37.188902)
		(end 422.703244 -37.347652)
		(width 0.10795)
		(layer "B.Cu")
		(net "BMC_M_A12")
	)
	(segment
		(start 441.388246 -40.0431)
		(end 441.703206 -40.35806)
		(width 0.10795)
		(layer "B.Cu")
		(net "BMC_M_A12")
	)
	(segment
		(start 427.681136 -37.157152)
		(end 426.470826 -37.157152)
		(width 0.10795)
		(layer "B.Cu")
		(net "BMC_M_A12")
	)
	(segment
		(start 439.112406 -34.6075)
		(end 439.4454 -34.940494)
		(width 0.10795)
		(layer "B.Cu")
		(net "BMC_M_A12")
	)
	(segment
		(start 441.119006 -43.09745)
		(end 441.119006 -42.092626)
		(width 0.10795)
		(layer "B.Cu")
		(net "BMC_M_A12")
	)
	(segment
		(start 440.455812 -36.8427)
		(end 440.455812 -39.6367)
		(width 0.10795)
		(layer "B.Cu")
		(net "BMC_M_A12")
	)
	(segment
		(start 439.4454 -34.940494)
		(end 439.4454 -35.832288)
		(width 0.10795)
		(layer "B.Cu")
		(net "BMC_M_A12")
	)
	(segment
		(start 430.370234 -37.401754)
		(end 430.370234 -37.694616)
		(width 0.10795)
		(layer "B.Cu")
		(net "BMC_M_A12")
	)
	(arc
		(start 438.867042 -34.5059)
		(mid 438.999819 -34.532311)
		(end 439.112406 -34.6075)
		(width 0.10795)
		(layer "B.Cu")
		(net "BMC_M_A12")
	)
	(arc
		(start 431.592482 -37.157152)
		(mid 431.419702 -37.22872)
		(end 431.348134 -37.4015)
		(width 0.10795)
		(layer "B.Cu")
		(net "BMC_M_A12")
	)
	(arc
		(start 423.796714 -37.382196)
		(mid 423.408394 -37.304954)
		(end 423.079164 -37.085016)
		(width 0.10795)
		(layer "B.Cu")
		(net "BMC_M_A12")
	)
	(arc
		(start 430.370234 -37.694616)
		(mid 430.125886 -37.938964)
		(end 429.881284 -37.694616)
		(width 0.10795)
		(layer "B.Cu")
		(net "BMC_M_A12")
	)
	(arc
		(start 432.497484 -36.844986)
		(mid 432.151852 -37.075993)
		(end 431.74412 -37.157152)
		(width 0.10795)
		(layer "B.Cu")
		(net "BMC_M_A12")
	)
	(arc
		(start 422.845738 -36.667948)
		(mid 422.626282 -36.448492)
		(end 422.406572 -36.667948)
		(width 0.10795)
		(layer "B.Cu")
		(net "BMC_M_A12")
	)
	(arc
		(start 427.925484 -37.4015)
		(mid 427.853916 -37.22872)
		(end 427.681136 -37.157152)
		(width 0.10795)
		(layer "B.Cu")
		(net "BMC_M_A12")
	)
	(arc
		(start 435.116986 -34.656268)
		(mid 435.283516 -34.544996)
		(end 435.479952 -34.5059)
		(width 0.10795)
		(layer "B.Cu")
		(net "BMC_M_A12")
	)
	(arc
		(start 430.859184 -37.401754)
		(mid 430.614836 -37.157406)
		(end 430.370234 -37.401754)
		(width 0.10795)
		(layer "B.Cu")
		(net "BMC_M_A12")
	)
	(arc
		(start 428.414434 -37.694616)
		(mid 428.170086 -37.938964)
		(end 427.925484 -37.694616)
		(width 0.10795)
		(layer "B.Cu")
		(net "BMC_M_A12")
	)
	(arc
		(start 429.881284 -37.401754)
		(mid 429.636936 -37.157406)
		(end 429.392334 -37.401754)
		(width 0.10795)
		(layer "B.Cu")
		(net "BMC_M_A12")
	)
	(arc
		(start 429.392334 -37.694616)
		(mid 429.147986 -37.938964)
		(end 428.903384 -37.694616)
		(width 0.10795)
		(layer "B.Cu")
		(net "BMC_M_A12")
	)
	(arc
		(start 426.470826 -37.157152)
		(mid 426.290906 -37.19294)
		(end 426.13834 -37.29482)
		(width 0.10795)
		(layer "B.Cu")
		(net "BMC_M_A12")
	)
	(arc
		(start 434.701188 -34.85515)
		(mid 434.901618 -34.815282)
		(end 435.07152 -34.701734)
		(width 0.10795)
		(layer "B.Cu")
		(net "BMC_M_A12")
	)
	(arc
		(start 422.406572 -36.853876)
		(mid 422.442552 -37.035117)
		(end 422.545002 -37.188902)
		(width 0.10795)
		(layer "B.Cu")
		(net "BMC_M_A12")
	)
	(arc
		(start 426.13834 -37.29482)
		(mid 426.041615 -37.35945)
		(end 425.92752 -37.382196)
		(width 0.10795)
		(layer "B.Cu")
		(net "BMC_M_A12")
	)
	(arc
		(start 428.903384 -37.4015)
		(mid 428.659036 -37.157152)
		(end 428.414434 -37.4015)
		(width 0.10795)
		(layer "B.Cu")
		(net "BMC_M_A12")
	)
	(arc
		(start 423.079164 -37.085016)
		(mid 422.90803 -36.906933)
		(end 422.845738 -36.667948)
		(width 0.10795)
		(layer "B.Cu")
		(net "BMC_M_A12")
	)
	(arc
		(start 431.348134 -37.682932)
		(mid 431.103786 -37.92728)
		(end 430.859184 -37.682932)
		(width 0.10795)
		(layer "B.Cu")
		(net "BMC_M_A12")
	)
	(arc
		(start 434.335936 -35.00628)
		(mid 434.50353 -34.89439)
		(end 434.701188 -34.85515)
		(width 0.10795)
		(layer "B.Cu")
		(net "BMC_M_A12")
	)
	(segment
		(start 442.121544 -37.432488)
		(end 442.122052 -37.432488)
		(width 0.10795)
		(layer "F.Cu")
		(net "BMC_M_A11")
	)
	(segment
		(start 424.60545 -37.334952)
		(end 423.700702 -37.334952)
		(width 0.10795)
		(layer "F.Cu")
		(net "BMC_M_A11")
	)
	(segment
		(start 444.471806 -39.0017)
		(end 447.126106 -39.0017)
		(width 0.10795)
		(layer "F.Cu")
		(net "BMC_M_A11")
	)
	(segment
		(start 442.135006 -37.445442)
		(end 442.135006 -37.7825)
		(width 0.10795)
		(layer "F.Cu")
		(net "BMC_M_A11")
	)
	(segment
		(start 442.668406 -38.3159)
		(end 443.786006 -38.3159)
		(width 0.10795)
		(layer "F.Cu")
		(net "BMC_M_A11")
	)
	(segment
		(start 428.521368 -40.012112)
		(end 428.431452 -39.922196)
		(width 0.10795)
		(layer "F.Cu")
		(net "BMC_M_A11")
	)
	(segment
		(start 429.12792 -40.86225)
		(end 429.057054 -40.86225)
		(width 0.10795)
		(layer "F.Cu")
		(net "BMC_M_A11")
	)
	(segment
		(start 429.20539 -40.93972)
		(end 429.12792 -40.86225)
		(width 0.10795)
		(layer "F.Cu")
		(net "BMC_M_A11")
	)
	(segment
		(start 429.057054 -40.86225)
		(end 429.056546 -40.861742)
		(width 0.10795)
		(layer "F.Cu")
		(net "BMC_M_A11")
	)
	(segment
		(start 449.958206 -39.0017)
		(end 450.14388 -38.816026)
		(width 0.10795)
		(layer "F.Cu")
		(net "BMC_M_A11")
	)
	(segment
		(start 442.122052 -37.432488)
		(end 442.135006 -37.445442)
		(width 0.10795)
		(layer "F.Cu")
		(net "BMC_M_A11")
	)
	(segment
		(start 450.14388 -38.816026)
		(end 450.14388 -38.2905)
		(width 0.10795)
		(layer "F.Cu")
		(net "BMC_M_A11")
	)
	(segment
		(start 447.126106 -39.0017)
		(end 449.958206 -39.0017)
		(width 0.10795)
		(layer "F.Cu")
		(net "BMC_M_A11")
	)
	(segment
		(start 443.786006 -38.3159)
		(end 444.471806 -39.0017)
		(width 0.10795)
		(layer "F.Cu")
		(net "BMC_M_A11")
	)
	(segment
		(start 450.14388 -38.2905)
		(end 451.41388 -38.2905)
		(width 0.10795)
		(layer "F.Cu")
		(net "BMC_M_A11")
	)
	(segment
		(start 441.722256 -37.0332)
		(end 442.121544 -37.432488)
		(width 0.10795)
		(layer "F.Cu")
		(net "BMC_M_A11")
	)
	(segment
		(start 427.919388 -39.922196)
		(end 425.845986 -37.848794)
		(width 0.10795)
		(layer "F.Cu")
		(net "BMC_M_A11")
	)
	(segment
		(start 428.719234 -40.722042)
		(end 428.521368 -40.524176)
		(width 0.10795)
		(layer "F.Cu")
		(net "BMC_M_A11")
	)
	(segment
		(start 423.3418 -37.186362)
		(end 423.090086 -36.934648)
		(width 0.10795)
		(layer "F.Cu")
		(net "BMC_M_A11")
	)
	(segment
		(start 442.135006 -37.7825)
		(end 442.668406 -38.3159)
		(width 0.10795)
		(layer "F.Cu")
		(net "BMC_M_A11")
	)
	(via
		(at 447.126106 -39.0017)
		(size 0.508)
		(drill 0.254)
		(layers "F.Cu" "B.Cu")
		(net "BMC_M_A11")
	)
	(via
		(at 429.20539 -40.93972)
		(size 0.4572)
		(drill 0.2032)
		(layers "F.Cu" "B.Cu")
		(net "BMC_M_A11")
	)
	(via
		(at 441.722256 -37.0332)
		(size 0.4572)
		(drill 0.2032)
		(layers "F.Cu" "B.Cu")
		(net "BMC_M_A11")
	)
	(arc
		(start 429.056546 -40.861742)
		(mid 428.874001 -40.825432)
		(end 428.719234 -40.722042)
		(width 0.10795)
		(layer "F.Cu")
		(net "BMC_M_A11")
	)
	(arc
		(start 425.845986 -37.848794)
		(mid 425.276823 -37.468492)
		(end 424.60545 -37.334952)
		(width 0.10795)
		(layer "F.Cu")
		(net "BMC_M_A11")
	)
	(arc
		(start 423.700702 -37.334952)
		(mid 423.506479 -37.296336)
		(end 423.3418 -37.186362)
		(width 0.10795)
		(layer "F.Cu")
		(net "BMC_M_A11")
	)
	(arc
		(start 428.521368 -40.268144)
		(mid 428.574394 -40.140128)
		(end 428.521368 -40.012112)
		(width 0.10795)
		(layer "F.Cu")
		(net "BMC_M_A11")
	)
	(arc
		(start 428.17542 -39.922196)
		(mid 428.047404 -39.975222)
		(end 427.919388 -39.922196)
		(width 0.10795)
		(layer "F.Cu")
		(net "BMC_M_A11")
	)
	(arc
		(start 428.521368 -40.524176)
		(mid 428.468342 -40.39616)
		(end 428.521368 -40.268144)
		(width 0.10795)
		(layer "F.Cu")
		(net "BMC_M_A11")
	)
	(arc
		(start 428.431452 -39.922196)
		(mid 428.303436 -39.86917)
		(end 428.17542 -39.922196)
		(width 0.10795)
		(layer "F.Cu")
		(net "BMC_M_A11")
	)
	(segment
		(start 441.228734 -37.390832)
		(end 441.228734 -37.303964)
		(width 0.089408)
		(layer "In2.Cu")
		(net "BMC_M_A11")
	)
	(segment
		(start 441.722256 -37.0332)
		(end 441.722256 -37.27323)
		(width 0.089408)
		(layer "In2.Cu")
		(net "BMC_M_A11")
	)
	(segment
		(start 440.570874 -37.53993)
		(end 440.074812 -37.53993)
		(width 0.089408)
		(layer "In2.Cu")
		(net "BMC_M_A11")
	)
	(segment
		(start 436.0545 -40.558466)
		(end 436.0545 -40.628316)
		(width 0.089408)
		(layer "In2.Cu")
		(net "BMC_M_A11")
	)
	(segment
		(start 429.660812 -41.110408)
		(end 429.641508 -41.129712)
		(width 0.089408)
		(layer "In2.Cu")
		(net "BMC_M_A11")
	)
	(segment
		(start 440.758326 -37.303964)
		(end 440.758326 -37.352478)
		(width 0.089408)
		(layer "In2.Cu")
		(net "BMC_M_A11")
	)
	(segment
		(start 429.349662 -41.129712)
		(end 429.237648 -41.017952)
		(width 0.089408)
		(layer "In2.Cu")
		(net "BMC_M_A11")
	)
	(segment
		(start 434.156358 -41.444164)
		(end 433.75707 -41.444164)
		(width 0.089408)
		(layer "In2.Cu")
		(net "BMC_M_A11")
	)
	(segment
		(start 437.71947 -39.41826)
		(end 437.127142 -39.41826)
		(width 0.089408)
		(layer "In2.Cu")
		(net "BMC_M_A11")
	)
	(segment
		(start 435.937152 -40.912034)
		(end 435.607968 -41.241218)
		(width 0.089408)
		(layer "In2.Cu")
		(net "BMC_M_A11")
	)
	(segment
		(start 431.960274 -42.309034)
		(end 430.739042 -42.309034)
		(width 0.089408)
		(layer "In2.Cu")
		(net "BMC_M_A11")
	)
	(segment
		(start 436.917592 -39.505128)
		(end 436.18912 -40.2336)
		(width 0.089408)
		(layer "In2.Cu")
		(net "BMC_M_A11")
	)
	(segment
		(start 439.977784 -37.580062)
		(end 438.43702 -39.12108)
		(width 0.089408)
		(layer "In2.Cu")
		(net "BMC_M_A11")
	)
	(segment
		(start 435.118002 -41.444164)
		(end 434.93309 -41.444164)
		(width 0.089408)
		(layer "In2.Cu")
		(net "BMC_M_A11")
	)
	(segment
		(start 433.624736 -41.499028)
		(end 433.420774 -41.703498)
		(width 0.089408)
		(layer "In2.Cu")
		(net "BMC_M_A11")
	)
	(segment
		(start 434.615082 -41.126156)
		(end 434.474366 -41.126156)
		(width 0.089408)
		(layer "In2.Cu")
		(net "BMC_M_A11")
	)
	(segment
		(start 430.310544 -42.131488)
		(end 429.974248 -41.795192)
		(width 0.089408)
		(layer "In2.Cu")
		(net "BMC_M_A11")
	)
	(segment
		(start 429.974248 -41.462452)
		(end 429.993552 -41.443148)
		(width 0.089408)
		(layer "In2.Cu")
		(net "BMC_M_A11")
	)
	(arc
		(start 436.0545 -40.628316)
		(mid 436.024016 -40.78184)
		(end 435.937152 -40.912034)
		(width 0.089408)
		(layer "In2.Cu")
		(net "BMC_M_A11")
	)
	(arc
		(start 437.127142 -39.41826)
		(mid 437.013722 -39.440839)
		(end 436.917592 -39.505128)
		(width 0.089408)
		(layer "In2.Cu")
		(net "BMC_M_A11")
	)
	(arc
		(start 434.30952 -41.291002)
		(mid 434.26466 -41.399304)
		(end 434.156358 -41.444164)
		(width 0.089408)
		(layer "In2.Cu")
		(net "BMC_M_A11")
	)
	(arc
		(start 440.758326 -37.352478)
		(mid 440.703423 -37.485027)
		(end 440.570874 -37.53993)
		(width 0.089408)
		(layer "In2.Cu")
		(net "BMC_M_A11")
	)
	(arc
		(start 433.75707 -41.444164)
		(mid 433.685432 -41.458414)
		(end 433.624736 -41.499028)
		(width 0.089408)
		(layer "In2.Cu")
		(net "BMC_M_A11")
	)
	(arc
		(start 435.607968 -41.241218)
		(mid 435.38317 -41.391423)
		(end 435.118002 -41.444164)
		(width 0.089408)
		(layer "In2.Cu")
		(net "BMC_M_A11")
	)
	(arc
		(start 434.779928 -41.291002)
		(mid 434.731646 -41.174438)
		(end 434.615082 -41.126156)
		(width 0.089408)
		(layer "In2.Cu")
		(net "BMC_M_A11")
	)
	(arc
		(start 441.416694 -37.578792)
		(mid 441.283786 -37.52374)
		(end 441.228734 -37.390832)
		(width 0.089408)
		(layer "In2.Cu")
		(net "BMC_M_A11")
	)
	(arc
		(start 429.993552 -41.443148)
		(mid 429.993552 -41.110408)
		(end 429.660812 -41.110408)
		(width 0.089408)
		(layer "In2.Cu")
		(net "BMC_M_A11")
	)
	(arc
		(start 438.43702 -39.12108)
		(mid 438.107791 -39.341001)
		(end 437.71947 -39.41826)
		(width 0.089408)
		(layer "In2.Cu")
		(net "BMC_M_A11")
	)
	(arc
		(start 434.93309 -41.444164)
		(mid 434.824788 -41.399304)
		(end 434.779928 -41.291002)
		(width 0.089408)
		(layer "In2.Cu")
		(net "BMC_M_A11")
	)
	(arc
		(start 429.237648 -41.017952)
		(mid 429.213748 -40.982044)
		(end 429.20539 -40.93972)
		(width 0.089408)
		(layer "In2.Cu")
		(net "BMC_M_A11")
	)
	(arc
		(start 440.074812 -37.53993)
		(mid 440.022323 -37.550371)
		(end 439.977784 -37.580062)
		(width 0.089408)
		(layer "In2.Cu")
		(net "BMC_M_A11")
	)
	(arc
		(start 430.739042 -42.309034)
		(mid 430.507119 -42.262902)
		(end 430.310544 -42.131488)
		(width 0.089408)
		(layer "In2.Cu")
		(net "BMC_M_A11")
	)
	(arc
		(start 436.18912 -40.2336)
		(mid 436.089474 -40.382636)
		(end 436.0545 -40.558466)
		(width 0.089408)
		(layer "In2.Cu")
		(net "BMC_M_A11")
	)
	(arc
		(start 429.974248 -41.795192)
		(mid 429.905335 -41.628822)
		(end 429.974248 -41.462452)
		(width 0.089408)
		(layer "In2.Cu")
		(net "BMC_M_A11")
	)
	(arc
		(start 434.474366 -41.126156)
		(mid 434.357802 -41.174438)
		(end 434.30952 -41.291002)
		(width 0.089408)
		(layer "In2.Cu")
		(net "BMC_M_A11")
	)
	(arc
		(start 429.641508 -41.129712)
		(mid 429.495622 -41.190103)
		(end 429.349662 -41.129712)
		(width 0.089408)
		(layer "In2.Cu")
		(net "BMC_M_A11")
	)
	(arc
		(start 433.420774 -41.703498)
		(mid 432.750819 -42.151717)
		(end 431.960274 -42.309034)
		(width 0.089408)
		(layer "In2.Cu")
		(net "BMC_M_A11")
	)
	(arc
		(start 441.228734 -37.303964)
		(mid 440.99353 -37.06876)
		(end 440.758326 -37.303964)
		(width 0.089408)
		(layer "In2.Cu")
		(net "BMC_M_A11")
	)
	(arc
		(start 441.722256 -37.27323)
		(mid 441.632759 -37.489295)
		(end 441.416694 -37.578792)
		(width 0.089408)
		(layer "In2.Cu")
		(net "BMC_M_A11")
	)
	(segment
		(start 441.321952 -34.232596)
		(end 441.321952 -34.226246)
		(width 0.10795)
		(layer "F.Cu")
		(net "BMC_M_A10")
	)
	(segment
		(start 441.321952 -34.226246)
		(end 440.941206 -33.8455)
		(width 0.10795)
		(layer "F.Cu")
		(net "BMC_M_A10")
	)
	(segment
		(start 419.890194 -36.134548)
		(end 420.28999 -36.534598)
		(width 0.1016)
		(layer "F.Cu")
		(net "BMC_M_A10")
	)
	(via
		(at 444.564262 -34.489644)
		(size 0.508)
		(drill 0.254)
		(layers "F.Cu" "B.Cu")
		(net "BMC_M_A10")
	)
	(via
		(at 420.28999 -36.534598)
		(size 0.4572)
		(drill 0.2032)
		(layers "F.Cu" "B.Cu")
		(net "BMC_M_A10")
	)
	(via
		(at 440.941206 -33.8455)
		(size 0.4572)
		(drill 0.2032)
		(layers "F.Cu" "B.Cu")
		(net "BMC_M_A10")
	)
	(segment
		(start 440.611006 -33.8455)
		(end 440.534806 -33.9217)
		(width 0.10795)
		(layer "B.Cu")
		(net "BMC_M_A10")
	)
	(segment
		(start 446.656206 -34.1757)
		(end 446.826132 -34.345626)
		(width 0.10795)
		(layer "B.Cu")
		(net "BMC_M_A10")
	)
	(segment
		(start 442.643006 -34.7345)
		(end 442.643006 -34.4043)
		(width 0.10795)
		(layer "B.Cu")
		(net "BMC_M_A10")
	)
	(segment
		(start 440.941206 -33.8455)
		(end 440.611006 -33.8455)
		(width 0.10795)
		(layer "B.Cu")
		(net "BMC_M_A10")
	)
	(segment
		(start 444.564262 -34.489644)
		(end 444.878206 -34.1757)
		(width 0.10795)
		(layer "B.Cu")
		(net "BMC_M_A10")
	)
	(segment
		(start 442.541406 -34.8361)
		(end 442.643006 -34.7345)
		(width 0.10795)
		(layer "B.Cu")
		(net "BMC_M_A10")
	)
	(segment
		(start 443.151006 -34.6837)
		(end 443.252606 -34.7853)
		(width 0.10795)
		(layer "B.Cu")
		(net "BMC_M_A10")
	)
	(segment
		(start 441.627006 -34.1503)
		(end 441.982606 -34.1503)
		(width 0.10795)
		(layer "B.Cu")
		(net "BMC_M_A10")
	)
	(segment
		(start 440.534806 -33.9217)
		(end 440.534806 -34.5313)
		(width 0.10795)
		(layer "B.Cu")
		(net "BMC_M_A10")
	)
	(segment
		(start 442.185806 -34.7599)
		(end 442.262006 -34.8361)
		(width 0.10795)
		(layer "B.Cu")
		(net "BMC_M_A10")
	)
	(segment
		(start 446.826132 -34.345626)
		(end 446.826132 -34.7345)
		(width 0.10795)
		(layer "B.Cu")
		(net "BMC_M_A10")
	)
	(segment
		(start 443.252606 -34.7853)
		(end 444.268606 -34.7853)
		(width 0.10795)
		(layer "B.Cu")
		(net "BMC_M_A10")
	)
	(segment
		(start 441.982606 -34.1503)
		(end 442.185806 -34.3535)
		(width 0.10795)
		(layer "B.Cu")
		(net "BMC_M_A10")
	)
	(segment
		(start 440.636406 -34.6329)
		(end 441.144406 -34.6329)
		(width 0.10795)
		(layer "B.Cu")
		(net "BMC_M_A10")
	)
	(segment
		(start 440.534806 -34.5313)
		(end 440.636406 -34.6329)
		(width 0.10795)
		(layer "B.Cu")
		(net "BMC_M_A10")
	)
	(segment
		(start 443.151006 -34.4043)
		(end 443.151006 -34.6837)
		(width 0.10795)
		(layer "B.Cu")
		(net "BMC_M_A10")
	)
	(segment
		(start 442.185806 -34.3535)
		(end 442.185806 -34.7599)
		(width 0.10795)
		(layer "B.Cu")
		(net "BMC_M_A10")
	)
	(segment
		(start 441.144406 -34.6329)
		(end 441.627006 -34.1503)
		(width 0.10795)
		(layer "B.Cu")
		(net "BMC_M_A10")
	)
	(segment
		(start 444.268606 -34.7853)
		(end 444.564262 -34.489644)
		(width 0.10795)
		(layer "B.Cu")
		(net "BMC_M_A10")
	)
	(segment
		(start 442.262006 -34.8361)
		(end 442.541406 -34.8361)
		(width 0.10795)
		(layer "B.Cu")
		(net "BMC_M_A10")
	)
	(segment
		(start 448.11188 -34.7345)
		(end 446.826132 -34.7345)
		(width 0.10795)
		(layer "B.Cu")
		(net "BMC_M_A10")
	)
	(segment
		(start 444.878206 -34.1757)
		(end 446.656206 -34.1757)
		(width 0.10795)
		(layer "B.Cu")
		(net "BMC_M_A10")
	)
	(arc
		(start 442.643006 -34.4043)
		(mid 442.897006 -34.1503)
		(end 443.151006 -34.4043)
		(width 0.10795)
		(layer "B.Cu")
		(net "BMC_M_A10")
	)
	(segment
		(start 437.790336 -34.210752)
		(end 434.862224 -34.210752)
		(width 0.089408)
		(layer "In2.Cu")
		(net "BMC_M_A10")
	)
	(segment
		(start 423.21607 -36.382452)
		(end 422.525952 -36.382452)
		(width 0.089408)
		(layer "In2.Cu")
		(net "BMC_M_A10")
	)
	(segment
		(start 421.97401 -36.153852)
		(end 421.92321 -36.153852)
		(width 0.089408)
		(layer "In2.Cu")
		(net "BMC_M_A10")
	)
	(segment
		(start 431.716688 -36.756086)
		(end 431.42154 -36.756086)
		(width 0.089408)
		(layer "In2.Cu")
		(net "BMC_M_A10")
	)
	(segment
		(start 438.121806 -33.878774)
		(end 438.121806 -33.879282)
		(width 0.089408)
		(layer "In2.Cu")
		(net "BMC_M_A10")
	)
	(segment
		(start 429.77943 -37.3888)
		(end 425.714922 -37.3888)
		(width 0.089408)
		(layer "In2.Cu")
		(net "BMC_M_A10")
	)
	(segment
		(start 422.221914 -36.256468)
		(end 422.22166 -36.256468)
		(width 0.089408)
		(layer "In2.Cu")
		(net "BMC_M_A10")
	)
	(segment
		(start 438.56148 -33.456626)
		(end 438.467246 -33.45561)
		(width 0.089408)
		(layer "In2.Cu")
		(net "BMC_M_A10")
	)
	(segment
		(start 434.397658 -34.403284)
		(end 432.434492 -36.36645)
		(width 0.089408)
		(layer "In2.Cu")
		(net "BMC_M_A10")
	)
	(segment
		(start 421.119046 -35.349688)
		(end 420.307516 -35.349688)
		(width 0.089408)
		(layer "In2.Cu")
		(net "BMC_M_A10")
	)
	(arc
		(start 438.467246 -33.45561)
		(mid 438.219074 -33.605618)
		(end 438.121806 -33.878774)
		(width 0.089408)
		(layer "In2.Cu")
		(net "BMC_M_A10")
	)
	(arc
		(start 421.92321 -36.153852)
		(mid 421.630633 -36.032663)
		(end 421.509444 -35.740086)
		(width 0.089408)
		(layer "In2.Cu")
		(net "BMC_M_A10")
	)
	(arc
		(start 425.714922 -37.3888)
		(mid 425.001176 -37.25079)
		(end 424.390312 -36.85667)
		(width 0.089408)
		(layer "In2.Cu")
		(net "BMC_M_A10")
	)
	(arc
		(start 421.509444 -35.740086)
		(mid 421.395099 -35.464033)
		(end 421.119046 -35.349688)
		(width 0.089408)
		(layer "In2.Cu")
		(net "BMC_M_A10")
	)
	(arc
		(start 431.42154 -36.756086)
		(mid 431.026151 -36.823388)
		(end 430.675288 -37.017706)
		(width 0.089408)
		(layer "In2.Cu")
		(net "BMC_M_A10")
	)
	(arc
		(start 430.675288 -37.017706)
		(mid 430.264265 -37.292343)
		(end 429.77943 -37.3888)
		(width 0.089408)
		(layer "In2.Cu")
		(net "BMC_M_A10")
	)
	(arc
		(start 434.862224 -34.210752)
		(mid 434.610778 -34.260786)
		(end 434.397658 -34.403284)
		(width 0.089408)
		(layer "In2.Cu")
		(net "BMC_M_A10")
	)
	(arc
		(start 420.307516 -35.349688)
		(mid 420.025895 -35.466339)
		(end 419.909244 -35.74796)
		(width 0.089408)
		(layer "In2.Cu")
		(net "BMC_M_A10")
	)
	(arc
		(start 419.909244 -35.74796)
		(mid 420.00943 -36.184934)
		(end 420.28999 -36.534598)
		(width 0.089408)
		(layer "In2.Cu")
		(net "BMC_M_A10")
	)
	(arc
		(start 432.434492 -36.36645)
		(mid 432.103847 -36.613321)
		(end 431.716688 -36.756086)
		(width 0.089408)
		(layer "In2.Cu")
		(net "BMC_M_A10")
	)
	(arc
		(start 438.121806 -33.879282)
		(mid 438.024721 -34.113667)
		(end 437.790336 -34.210752)
		(width 0.089408)
		(layer "In2.Cu")
		(net "BMC_M_A10")
	)
	(arc
		(start 424.390312 -36.85667)
		(mid 423.849264 -36.505474)
		(end 423.21607 -36.382452)
		(width 0.089408)
		(layer "In2.Cu")
		(net "BMC_M_A10")
	)
	(arc
		(start 422.525952 -36.382452)
		(mid 422.361404 -36.349703)
		(end 422.221914 -36.256468)
		(width 0.089408)
		(layer "In2.Cu")
		(net "BMC_M_A10")
	)
	(arc
		(start 422.22166 -36.256468)
		(mid 422.108037 -36.180548)
		(end 421.97401 -36.153852)
		(width 0.089408)
		(layer "In2.Cu")
		(net "BMC_M_A10")
	)
	(arc
		(start 440.941206 -33.8455)
		(mid 439.767125 -33.554481)
		(end 438.56148 -33.456626)
		(width 0.089408)
		(layer "In2.Cu")
		(net "BMC_M_A10")
	)
	(segment
		(start 429.660558 -39.132002)
		(end 431.419508 -39.132002)
		(width 0.10795)
		(layer "F.Cu")
		(net "BMC_M_A1")
	)
	(segment
		(start 430.963578 -38.643052)
		(end 427.92269 -38.643052)
		(width 0.10795)
		(layer "F.Cu")
		(net "BMC_M_A1")
	)
	(segment
		(start 438.625234 -35.940492)
		(end 438.625234 -36.12642)
		(width 0.10795)
		(layer "F.Cu")
		(net "BMC_M_A1")
	)
	(segment
		(start 438.47512 -36.276534)
		(end 437.826658 -36.276534)
		(width 0.10795)
		(layer "F.Cu")
		(net "BMC_M_A1")
	)
	(segment
		(start 427.92269 -39.13251)
		(end 428.682404 -39.13251)
		(width 0.10795)
		(layer "F.Cu")
		(net "BMC_M_A1")
	)
	(segment
		(start 429.415702 -39.432992)
		(end 429.415702 -39.376858)
		(width 0.10795)
		(layer "F.Cu")
		(net "BMC_M_A1")
	)
	(segment
		(start 431.527458 -39.024052)
		(end 431.527458 -38.897306)
		(width 0.10795)
		(layer "F.Cu")
		(net "BMC_M_A1")
	)
	(segment
		(start 431.419508 -39.132002)
		(end 431.527458 -39.024052)
		(width 0.10795)
		(layer "F.Cu")
		(net "BMC_M_A1")
	)
	(segment
		(start 438.12206 -35.832542)
		(end 438.517284 -35.832542)
		(width 0.10795)
		(layer "F.Cu")
		(net "BMC_M_A1")
	)
	(segment
		(start 428.926752 -39.376858)
		(end 428.926752 -39.432992)
		(width 0.10795)
		(layer "F.Cu")
		(net "BMC_M_A1")
	)
	(segment
		(start 425.83481 -37.29101)
		(end 426.29455 -37.75075)
		(width 0.10795)
		(layer "F.Cu")
		(net "BMC_M_A1")
	)
	(segment
		(start 427.371764 -38.154102)
		(end 430.963578 -38.154102)
		(width 0.10795)
		(layer "F.Cu")
		(net "BMC_M_A1")
	)
	(segment
		(start 423.890186 -36.934648)
		(end 424.974512 -36.934648)
		(width 0.10795)
		(layer "F.Cu")
		(net "BMC_M_A1")
	)
	(via
		(at 431.527458 -38.897306)
		(size 0.508)
		(drill 0.254)
		(layers "F.Cu" "B.Cu")
		(net "BMC_M_A1")
	)
	(via
		(at 437.721756 -36.2331)
		(size 0.4572)
		(drill 0.2032)
		(layers "F.Cu" "B.Cu")
		(net "BMC_M_A1")
	)
	(via
		(at 439.214006 -38.138862)
		(size 0.508)
		(drill 0.254)
		(layers "F.Cu" "B.Cu")
		(net "BMC_M_A1")
	)
	(arc
		(start 430.963578 -38.154102)
		(mid 431.20818 -38.398704)
		(end 430.963578 -38.643052)
		(width 0.10795)
		(layer "F.Cu")
		(net "BMC_M_A1")
	)
	(arc
		(start 428.926752 -39.432992)
		(mid 429.171354 -39.677594)
		(end 429.415702 -39.432992)
		(width 0.10795)
		(layer "F.Cu")
		(net "BMC_M_A1")
	)
	(arc
		(start 426.29455 -37.75075)
		(mid 426.736805 -38.046255)
		(end 427.25848 -38.150038)
		(width 0.10795)
		(layer "F.Cu")
		(net "BMC_M_A1")
	)
	(arc
		(start 428.682404 -39.13251)
		(mid 428.855184 -39.204078)
		(end 428.926752 -39.376858)
		(width 0.10795)
		(layer "F.Cu")
		(net "BMC_M_A1")
	)
	(arc
		(start 437.826658 -36.276534)
		(mid 437.769892 -36.265243)
		(end 437.721756 -36.2331)
		(width 0.10795)
		(layer "F.Cu")
		(net "BMC_M_A1")
	)
	(arc
		(start 438.517284 -35.832542)
		(mid 438.593616 -35.86416)
		(end 438.625234 -35.940492)
		(width 0.10795)
		(layer "F.Cu")
		(net "BMC_M_A1")
	)
	(arc
		(start 424.974512 -36.934648)
		(mid 425.440108 -37.027261)
		(end 425.83481 -37.29101)
		(width 0.10795)
		(layer "F.Cu")
		(net "BMC_M_A1")
	)
	(arc
		(start 438.625234 -36.12642)
		(mid 438.581267 -36.232567)
		(end 438.47512 -36.276534)
		(width 0.10795)
		(layer "F.Cu")
		(net "BMC_M_A1")
	)
	(arc
		(start 427.25848 -38.150038)
		(mid 427.315087 -38.153061)
		(end 427.371764 -38.154102)
		(width 0.10795)
		(layer "F.Cu")
		(net "BMC_M_A1")
	)
	(arc
		(start 429.415702 -39.376858)
		(mid 429.487419 -39.203719)
		(end 429.660558 -39.132002)
		(width 0.10795)
		(layer "F.Cu")
		(net "BMC_M_A1")
	)
	(arc
		(start 427.92269 -38.643052)
		(mid 427.677834 -38.887908)
		(end 427.92269 -39.13251)
		(width 0.10795)
		(layer "F.Cu")
		(net "BMC_M_A1")
	)
	(segment
		(start 439.010806 -38.6969)
		(end 439.214006 -38.4937)
		(width 0.10795)
		(layer "B.Cu")
		(net "BMC_M_A1")
	)
	(segment
		(start 437.524906 -39.5986)
		(end 438.426606 -38.6969)
		(width 0.10795)
		(layer "B.Cu")
		(net "BMC_M_A1")
	)
	(segment
		(start 437.690006 -42.092626)
		(end 438.094374 -42.092626)
		(width 0.10795)
		(layer "B.Cu")
		(net "BMC_M_A1")
	)
	(segment
		(start 439.214006 -36.7665)
		(end 438.579006 -36.1315)
		(width 0.10795)
		(layer "B.Cu")
		(net "BMC_M_A1")
	)
	(segment
		(start 439.214006 -38.4937)
		(end 439.214006 -38.138862)
		(width 0.10795)
		(layer "B.Cu")
		(net "BMC_M_A1")
	)
	(segment
		(start 438.579006 -36.1315)
		(end 437.823356 -36.1315)
		(width 0.10795)
		(layer "B.Cu")
		(net "BMC_M_A1")
	)
	(segment
		(start 438.426606 -38.6969)
		(end 439.010806 -38.6969)
		(width 0.10795)
		(layer "B.Cu")
		(net "BMC_M_A1")
	)
	(segment
		(start 437.524906 -39.9161)
		(end 437.524906 -39.5986)
		(width 0.10795)
		(layer "B.Cu")
		(net "BMC_M_A1")
	)
	(segment
		(start 437.984646 -39.9923)
		(end 437.601106 -39.9923)
		(width 0.10795)
		(layer "B.Cu")
		(net "BMC_M_A1")
	)
	(segment
		(start 438.094374 -42.092626)
		(end 438.274206 -41.912794)
		(width 0.10795)
		(layer "B.Cu")
		(net "BMC_M_A1")
	)
	(segment
		(start 438.274206 -41.912794)
		(end 438.274206 -40.28186)
		(width 0.10795)
		(layer "B.Cu")
		(net "BMC_M_A1")
	)
	(segment
		(start 439.214006 -38.138862)
		(end 439.214006 -36.7665)
		(width 0.10795)
		(layer "B.Cu")
		(net "BMC_M_A1")
	)
	(segment
		(start 437.601106 -39.9923)
		(end 437.524906 -39.9161)
		(width 0.10795)
		(layer "B.Cu")
		(net "BMC_M_A1")
	)
	(segment
		(start 437.823356 -36.1315)
		(end 437.721756 -36.2331)
		(width 0.10795)
		(layer "B.Cu")
		(net "BMC_M_A1")
	)
	(segment
		(start 437.690006 -43.09745)
		(end 437.690006 -42.092626)
		(width 0.10795)
		(layer "B.Cu")
		(net "BMC_M_A1")
	)
	(segment
		(start 438.274206 -40.28186)
		(end 437.984646 -39.9923)
		(width 0.10795)
		(layer "B.Cu")
		(net "BMC_M_A1")
	)
	(segment
		(start 437.275732 -35.843464)
		(end 436.203344 -35.843464)
		(width 0.089408)
		(layer "In2.Cu")
		(net "BMC_M_A1")
	)
	(segment
		(start 437.72074 -36.2331)
		(end 437.38165 -35.887914)
		(width 0.089408)
		(layer "In2.Cu")
		(net "BMC_M_A1")
	)
	(segment
		(start 432.462686 -38.424358)
		(end 432.201828 -38.424358)
		(width 0.089408)
		(layer "In2.Cu")
		(net "BMC_M_A1")
	)
	(segment
		(start 435.614826 -36.008818)
		(end 433.72024 -37.903404)
		(width 0.089408)
		(layer "In2.Cu")
		(net "BMC_M_A1")
	)
	(segment
		(start 437.721756 -36.2331)
		(end 437.72074 -36.2331)
		(width 0.089408)
		(layer "In2.Cu")
		(net "BMC_M_A1")
	)
	(arc
		(start 432.201828 -38.424358)
		(mid 431.78998 -38.554377)
		(end 431.527458 -38.897306)
		(width 0.089408)
		(layer "In2.Cu")
		(net "BMC_M_A1")
	)
	(arc
		(start 433.72024 -37.903404)
		(mid 433.143269 -38.288923)
		(end 432.462686 -38.424358)
		(width 0.089408)
		(layer "In2.Cu")
		(net "BMC_M_A1")
	)
	(arc
		(start 437.38165 -35.887914)
		(mid 437.33317 -35.855009)
		(end 437.275732 -35.843464)
		(width 0.089408)
		(layer "In2.Cu")
		(net "BMC_M_A1")
	)
	(arc
		(start 436.203344 -35.843464)
		(mid 436.089407 -35.847405)
		(end 435.976014 -35.859212)
		(width 0.089408)
		(layer "In2.Cu")
		(net "BMC_M_A1")
	)
	(arc
		(start 435.976014 -35.859212)
		(mid 435.780542 -35.898094)
		(end 435.614826 -36.008818)
		(width 0.089408)
		(layer "In2.Cu")
		(net "BMC_M_A1")
	)
	(segment
		(start 441.321952 -35.832542)
		(end 441.321698 -35.832542)
		(width 0.10795)
		(layer "F.Cu")
		(net "BMC_M_A0")
	)
	(segment
		(start 420.69004 -36.134548)
		(end 421.09009 -36.534598)
		(width 0.1016)
		(layer "F.Cu")
		(net "BMC_M_A0")
	)
	(segment
		(start 441.321698 -35.832542)
		(end 440.922156 -35.433)
		(width 0.10795)
		(layer "F.Cu")
		(net "BMC_M_A0")
	)
	(via
		(at 443.8142 -35.8267)
		(size 0.508)
		(drill 0.254)
		(layers "F.Cu" "B.Cu")
		(net "BMC_M_A0")
	)
	(via
		(at 421.09009 -36.534598)
		(size 0.4572)
		(drill 0.2032)
		(layers "F.Cu" "B.Cu")
		(net "BMC_M_A0")
	)
	(via
		(at 440.922156 -35.433)
		(size 0.4572)
		(drill 0.2032)
		(layers "F.Cu" "B.Cu")
		(net "BMC_M_A0")
	)
	(segment
		(start 448.099688 -37.032692)
		(end 446.826132 -37.032692)
		(width 0.10795)
		(layer "B.Cu")
		(net "BMC_M_A0")
	)
	(segment
		(start 444.141606 -35.8267)
		(end 443.8142 -35.8267)
		(width 0.10795)
		(layer "B.Cu")
		(net "BMC_M_A0")
	)
	(segment
		(start 446.072006 -37.7825)
		(end 444.979806 -37.7825)
		(width 0.10795)
		(layer "B.Cu")
		(net "BMC_M_A0")
	)
	(segment
		(start 446.376806 -38.0873)
		(end 446.072006 -37.7825)
		(width 0.10795)
		(layer "B.Cu")
		(net "BMC_M_A0")
	)
	(segment
		(start 444.751206 -36.4363)
		(end 444.141606 -35.8267)
		(width 0.10795)
		(layer "B.Cu")
		(net "BMC_M_A0")
	)
	(segment
		(start 446.376806 -38.319964)
		(end 446.376806 -38.0873)
		(width 0.10795)
		(layer "B.Cu")
		(net "BMC_M_A0")
	)
	(segment
		(start 444.979806 -37.7825)
		(end 444.751206 -37.5539)
		(width 0.10795)
		(layer "B.Cu")
		(net "BMC_M_A0")
	)
	(segment
		(start 443.8142 -35.8267)
		(end 441.315856 -35.8267)
		(width 0.10795)
		(layer "B.Cu")
		(net "BMC_M_A0")
	)
	(segment
		(start 441.315856 -35.8267)
		(end 440.922156 -35.433)
		(width 0.10795)
		(layer "B.Cu")
		(net "BMC_M_A0")
	)
	(segment
		(start 444.751206 -37.5539)
		(end 444.751206 -36.4363)
		(width 0.10795)
		(layer "B.Cu")
		(net "BMC_M_A0")
	)
	(segment
		(start 446.826132 -37.032692)
		(end 446.826132 -38.319964)
		(width 0.10795)
		(layer "B.Cu")
		(net "BMC_M_A0")
	)
	(arc
		(start 446.826132 -38.319964)
		(mid 446.601596 -38.5445)
		(end 446.376806 -38.319964)
		(width 0.10795)
		(layer "B.Cu")
		(net "BMC_M_A0")
	)
	(segment
		(start 427.316392 -38.764718)
		(end 427.316392 -38.576504)
		(width 0.089408)
		(layer "In2.Cu")
		(net "BMC_M_A0")
	)
	(segment
		(start 436.055262 -35.0139)
		(end 439.872374 -35.0139)
		(width 0.089408)
		(layer "In2.Cu")
		(net "BMC_M_A0")
	)
	(segment
		(start 431.63109 -37.9476)
		(end 432.163728 -37.9476)
		(width 0.089408)
		(layer "In2.Cu")
		(net "BMC_M_A0")
	)
	(segment
		(start 426.845984 -38.576504)
		(end 426.845984 -38.764718)
		(width 0.089408)
		(layer "In2.Cu")
		(net "BMC_M_A0")
	)
	(segment
		(start 428.257208 -38.764718)
		(end 428.257208 -38.576504)
		(width 0.089408)
		(layer "In2.Cu")
		(net "BMC_M_A0")
	)
	(segment
		(start 423.479468 -37.081968)
		(end 424.61434 -38.21684)
		(width 0.089408)
		(layer "In2.Cu")
		(net "BMC_M_A0")
	)
	(segment
		(start 440.64428 -35.493452)
		(end 440.776106 -35.493452)
		(width 0.089408)
		(layer "In2.Cu")
		(net "BMC_M_A0")
	)
	(segment
		(start 433.558696 -37.36975)
		(end 435.815232 -35.113214)
		(width 0.089408)
		(layer "In2.Cu")
		(net "BMC_M_A0")
	)
	(segment
		(start 421.917622 -36.941252)
		(end 423.13987 -36.941252)
		(width 0.089408)
		(layer "In2.Cu")
		(net "BMC_M_A0")
	)
	(segment
		(start 427.7868 -38.576504)
		(end 427.7868 -38.764718)
		(width 0.089408)
		(layer "In2.Cu")
		(net "BMC_M_A0")
	)
	(segment
		(start 426.375576 -38.762686)
		(end 426.375576 -38.576504)
		(width 0.089408)
		(layer "In2.Cu")
		(net "BMC_M_A0")
	)
	(segment
		(start 428.492412 -38.3413)
		(end 430.837848 -38.3413)
		(width 0.089408)
		(layer "In2.Cu")
		(net "BMC_M_A0")
	)
	(segment
		(start 425.905168 -38.576504)
		(end 425.905168 -38.762686)
		(width 0.089408)
		(layer "In2.Cu")
		(net "BMC_M_A0")
	)
	(segment
		(start 421.484044 -36.687252)
		(end 421.611044 -36.814252)
		(width 0.089408)
		(layer "In2.Cu")
		(net "BMC_M_A0")
	)
	(segment
		(start 424.914568 -38.3413)
		(end 425.669964 -38.3413)
		(width 0.089408)
		(layer "In2.Cu")
		(net "BMC_M_A0")
	)
	(segment
		(start 440.109102 -35.111944)
		(end 440.381898 -35.38474)
		(width 0.089408)
		(layer "In2.Cu")
		(net "BMC_M_A0")
	)
	(segment
		(start 431.093118 -38.235382)
		(end 431.203862 -38.124638)
		(width 0.089408)
		(layer "In2.Cu")
		(net "BMC_M_A0")
	)
	(arc
		(start 427.7868 -38.764718)
		(mid 428.022004 -38.999922)
		(end 428.257208 -38.764718)
		(width 0.089408)
		(layer "In2.Cu")
		(net "BMC_M_A0")
	)
	(arc
		(start 430.837848 -38.3413)
		(mid 430.976015 -38.313723)
		(end 431.093118 -38.235382)
		(width 0.089408)
		(layer "In2.Cu")
		(net "BMC_M_A0")
	)
	(arc
		(start 426.845984 -38.764718)
		(mid 427.081188 -38.999922)
		(end 427.316392 -38.764718)
		(width 0.089408)
		(layer "In2.Cu")
		(net "BMC_M_A0")
	)
	(arc
		(start 432.163728 -37.9476)
		(mid 432.918693 -37.797428)
		(end 433.558696 -37.36975)
		(width 0.089408)
		(layer "In2.Cu")
		(net "BMC_M_A0")
	)
	(arc
		(start 428.257208 -38.576504)
		(mid 428.326098 -38.41019)
		(end 428.492412 -38.3413)
		(width 0.089408)
		(layer "In2.Cu")
		(net "BMC_M_A0")
	)
	(arc
		(start 421.611044 -36.814252)
		(mid 421.751703 -36.908237)
		(end 421.917622 -36.941252)
		(width 0.089408)
		(layer "In2.Cu")
		(net "BMC_M_A0")
	)
	(arc
		(start 431.203862 -38.124638)
		(mid 431.399862 -37.993612)
		(end 431.63109 -37.9476)
		(width 0.089408)
		(layer "In2.Cu")
		(net "BMC_M_A0")
	)
	(arc
		(start 427.316392 -38.576504)
		(mid 427.551596 -38.3413)
		(end 427.7868 -38.576504)
		(width 0.089408)
		(layer "In2.Cu")
		(net "BMC_M_A0")
	)
	(arc
		(start 440.381898 -35.38474)
		(mid 440.50228 -35.465177)
		(end 440.64428 -35.493452)
		(width 0.089408)
		(layer "In2.Cu")
		(net "BMC_M_A0")
	)
	(arc
		(start 426.375576 -38.576504)
		(mid 426.61078 -38.3413)
		(end 426.845984 -38.576504)
		(width 0.089408)
		(layer "In2.Cu")
		(net "BMC_M_A0")
	)
	(arc
		(start 421.09009 -36.534598)
		(mid 421.303174 -36.569365)
		(end 421.484044 -36.687252)
		(width 0.089408)
		(layer "In2.Cu")
		(net "BMC_M_A0")
	)
	(arc
		(start 423.13987 -36.941252)
		(mid 423.323664 -36.977829)
		(end 423.479468 -37.081968)
		(width 0.089408)
		(layer "In2.Cu")
		(net "BMC_M_A0")
	)
	(arc
		(start 425.669964 -38.3413)
		(mid 425.836278 -38.41019)
		(end 425.905168 -38.576504)
		(width 0.089408)
		(layer "In2.Cu")
		(net "BMC_M_A0")
	)
	(arc
		(start 435.815232 -35.113214)
		(mid 435.925359 -35.03963)
		(end 436.055262 -35.0139)
		(width 0.089408)
		(layer "In2.Cu")
		(net "BMC_M_A0")
	)
	(arc
		(start 425.905168 -38.762686)
		(mid 426.140372 -38.99789)
		(end 426.375576 -38.762686)
		(width 0.089408)
		(layer "In2.Cu")
		(net "BMC_M_A0")
	)
	(arc
		(start 424.61434 -38.21684)
		(mid 424.752072 -38.308933)
		(end 424.914568 -38.3413)
		(width 0.089408)
		(layer "In2.Cu")
		(net "BMC_M_A0")
	)
	(arc
		(start 440.776106 -35.493452)
		(mid 440.855131 -35.477733)
		(end 440.922156 -35.433)
		(width 0.089408)
		(layer "In2.Cu")
		(net "BMC_M_A0")
	)
	(arc
		(start 439.872374 -35.0139)
		(mid 440.000486 -35.039383)
		(end 440.109102 -35.111944)
		(width 0.089408)
		(layer "In2.Cu")
		(net "BMC_M_A0")
	)
	(segment
		(start 421.49014 -34.534602)
		(end 421.490394 -34.534602)
		(width 0.089408)
		(layer "F.Cu")
		(net "BMC_MIOZ")
	)
	(segment
		(start 427.591982 -35.795712)
		(end 427.252384 -35.795712)
		(width 0.10795)
		(layer "F.Cu")
		(net "BMC_MIOZ")
	)
	(segment
		(start 427.74108 -36.07435)
		(end 427.74108 -35.94481)
		(width 0.10795)
		(layer "F.Cu")
		(net "BMC_MIOZ")
	)
	(segment
		(start 421.490394 -34.534602)
		(end 421.890444 -34.934652)
		(width 0.089408)
		(layer "F.Cu")
		(net "BMC_MIOZ")
	)
	(segment
		(start 427.74108 -35.94481)
		(end 427.591982 -35.795712)
		(width 0.10795)
		(layer "F.Cu")
		(net "BMC_MIOZ")
	)
	(segment
		(start 427.252384 -35.795712)
		(end 427.122844 -35.925252)
		(width 0.10795)
		(layer "F.Cu")
		(net "BMC_MIOZ")
	)
	(via
		(at 427.122844 -35.925252)
		(size 0.4572)
		(drill 0.2032)
		(layers "F.Cu" "B.Cu")
		(net "BMC_MIOZ")
	)
	(via
		(at 424.366182 -35.6362)
		(size 0.508)
		(drill 0.254)
		(layers "F.Cu" "B.Cu")
		(net "BMC_MIOZ")
	)
	(via
		(at 421.890444 -34.934652)
		(size 0.4572)
		(drill 0.2032)
		(layers "F.Cu" "B.Cu")
		(net "BMC_MIOZ")
	)
	(segment
		(start 423.536872 -35.475672)
		(end 423.536364 -35.475164)
		(width 0.10795)
		(layer "B.Cu")
		(net "BMC_MIOZ")
	)
	(segment
		(start 426.424852 -35.6362)
		(end 424.366182 -35.6362)
		(width 0.10795)
		(layer "B.Cu")
		(net "BMC_MIOZ")
	)
	(segment
		(start 421.936418 -34.98088)
		(end 421.890444 -34.934652)
		(width 0.10795)
		(layer "B.Cu")
		(net "BMC_MIOZ")
	)
	(segment
		(start 424.366182 -35.6362)
		(end 423.924222 -35.6362)
		(width 0.10795)
		(layer "B.Cu")
		(net "BMC_MIOZ")
	)
	(segment
		(start 423.1894 -35.3314)
		(end 422.783 -35.3314)
		(width 0.10795)
		(layer "B.Cu")
		(net "BMC_MIOZ")
	)
	(arc
		(start 422.783 -35.3314)
		(mid 422.324835 -35.240359)
		(end 421.936418 -34.98088)
		(width 0.10795)
		(layer "B.Cu")
		(net "BMC_MIOZ")
	)
	(arc
		(start 426.5295 -35.641788)
		(mid 426.47725 -35.637604)
		(end 426.424852 -35.6362)
		(width 0.10795)
		(layer "B.Cu")
		(net "BMC_MIOZ")
	)
	(arc
		(start 427.122844 -35.925252)
		(mid 426.850452 -35.732708)
		(end 426.5295 -35.641788)
		(width 0.10795)
		(layer "B.Cu")
		(net "BMC_MIOZ")
	)
	(arc
		(start 423.536364 -35.475164)
		(mid 423.37719 -35.368744)
		(end 423.1894 -35.3314)
		(width 0.10795)
		(layer "B.Cu")
		(net "BMC_MIOZ")
	)
	(arc
		(start 423.924222 -35.6362)
		(mid 423.714572 -35.59448)
		(end 423.536872 -35.475672)
		(width 0.10795)
		(layer "B.Cu")
		(net "BMC_MIOZ")
	)
	(segment
		(start 401.17014 -30.67304)
		(end 401.23872 -30.74162)
		(width 0.10795)
		(layer "F.Cu")
		(net "A_USB2BVRES")
	)
	(segment
		(start 404.642828 -31.2166)
		(end 406.71877 -31.2166)
		(width 0.10795)
		(layer "F.Cu")
		(net "A_USB2BVRES")
	)
	(segment
		(start 403.525482 -31.397702)
		(end 404.225506 -31.397702)
		(width 0.10795)
		(layer "F.Cu")
		(net "A_USB2BVRES")
	)
	(segment
		(start 406.946862 -30.988508)
		(end 407.544016 -30.988508)
		(width 0.10795)
		(layer "F.Cu")
		(net "A_USB2BVRES")
	)
	(segment
		(start 407.544016 -30.988508)
		(end 407.890218 -31.33471)
		(width 0.10795)
		(layer "F.Cu")
		(net "A_USB2BVRES")
	)
	(segment
		(start 404.225506 -31.397702)
		(end 404.524718 -31.09849)
		(width 0.10795)
		(layer "F.Cu")
		(net "A_USB2BVRES")
	)
	(segment
		(start 404.524718 -31.09849)
		(end 404.642828 -31.2166)
		(width 0.10795)
		(layer "F.Cu")
		(net "A_USB2BVRES")
	)
	(segment
		(start 402.8694 -30.74162)
		(end 403.525482 -31.397702)
		(width 0.10795)
		(layer "F.Cu")
		(net "A_USB2BVRES")
	)
	(segment
		(start 406.71877 -31.2166)
		(end 406.946862 -30.988508)
		(width 0.10795)
		(layer "F.Cu")
		(net "A_USB2BVRES")
	)
	(segment
		(start 401.23872 -30.74162)
		(end 402.8694 -30.74162)
		(width 0.10795)
		(layer "F.Cu")
		(net "A_USB2BVRES")
	)
	(via
		(at 404.524718 -31.09849)
		(size 0.762)
		(drill 0.381)
		(layers "F.Cu" "B.Cu")
		(net "A_USB2BVRES")
	)
	(segment
		(start 408.290014 -31.734506)
		(end 407.890218 -32.134302)
		(width 0.089408)
		(layer "F.Cu")
		(net "A_USB2AVRES")
	)
	(segment
		(start 407.890218 -32.134302)
		(end 407.890218 -32.134556)
		(width 0.089408)
		(layer "F.Cu")
		(net "A_USB2AVRES")
	)
	(via
		(at 408.290014 -31.734506)
		(size 0.4572)
		(drill 0.2032)
		(layers "F.Cu" "B.Cu")
		(net "A_USB2AVRES")
	)
	(segment
		(start 406.892506 -32.6644)
		(end 407.416 -32.140906)
		(width 0.10795)
		(layer "B.Cu")
		(net "A_USB2AVRES")
	)
	(segment
		(start 407.416 -31.6865)
		(end 408.242008 -31.6865)
		(width 0.10795)
		(layer "B.Cu")
		(net "A_USB2AVRES")
	)
	(segment
		(start 408.242008 -31.6865)
		(end 408.290014 -31.734506)
		(width 0.10795)
		(layer "B.Cu")
		(net "A_USB2AVRES")
	)
	(segment
		(start 407.416 -32.140906)
		(end 407.416 -31.6865)
		(width 0.10795)
		(layer "B.Cu")
		(net "A_USB2AVRES")
	)
	(segment
		(start 30.217872 -98.379788)
		(end 30.04566 -98.552)
		(width 0.254)
		(layer "F.Cu")
		(net "VR_PVSA_CPU1_BOOT_R")
	)
	(segment
		(start 31.02991 -98.379788)
		(end 30.217872 -98.379788)
		(width 0.254)
		(layer "F.Cu")
		(net "VR_PVSA_CPU1_BOOT_R")
	)
	(segment
		(start 30.04566 -98.552)
		(end 29.5402 -98.552)
		(width 0.508)
		(layer "F.Cu")
		(net "VR_PVSA_CPU1_BOOT_R")
	)
	(segment
		(start 29.5402 -98.552)
		(end 29.49448 -98.59772)
		(width 0.508)
		(layer "F.Cu")
		(net "VR_PVSA_CPU1_BOOT_R")
	)
	(segment
		(start 195.168012 -98.379788)
		(end 196.017642 -98.379788)
		(width 0.254)
		(layer "F.Cu")
		(net "VR_PVSA_CPU0_BOOT_R")
	)
	(segment
		(start 195.007484 -98.540316)
		(end 195.168012 -98.379788)
		(width 0.254)
		(layer "F.Cu")
		(net "VR_PVSA_CPU0_BOOT_R")
	)
	(segment
		(start 194.818 -98.7298)
		(end 195.007484 -98.540316)
		(width 0.508)
		(layer "F.Cu")
		(net "VR_PVSA_CPU0_BOOT_R")
	)
	(segment
		(start 194.4116 -98.7298)
		(end 194.818 -98.7298)
		(width 0.508)
		(layer "F.Cu")
		(net "VR_PVSA_CPU0_BOOT_R")
	)
	(segment
		(start 377.067572 -156.671772)
		(end 377.233942 -156.838142)
		(width 0.254)
		(layer "F.Cu")
		(net "VR_PVNN_PCH_PH1_BOOT_R")
	)
	(segment
		(start 377.233942 -158.096458)
		(end 377.19 -158.1404)
		(width 0.508)
		(layer "F.Cu")
		(net "VR_PVNN_PCH_PH1_BOOT_R")
	)
	(segment
		(start 377.067572 -156.24302)
		(end 377.067572 -156.671772)
		(width 0.254)
		(layer "F.Cu")
		(net "VR_PVNN_PCH_PH1_BOOT_R")
	)
	(segment
		(start 377.233942 -156.838142)
		(end 377.233942 -157.630368)
		(width 0.254)
		(layer "F.Cu")
		(net "VR_PVNN_PCH_PH1_BOOT_R")
	)
	(segment
		(start 377.233942 -157.630368)
		(end 377.233942 -158.096458)
		(width 0.508)
		(layer "F.Cu")
		(net "VR_PVNN_PCH_PH1_BOOT_R")
	)
	(segment
		(start -1.41224 -148.028406)
		(end -0.497586 -148.028406)
		(width 0.254)
		(layer "F.Cu")
		(net "VR_PVDDQ_KLM_PH2_BOOT_R")
	)
	(segment
		(start -1.452626 -148.068792)
		(end -1.41224 -148.028406)
		(width 0.254)
		(layer "F.Cu")
		(net "VR_PVDDQ_KLM_PH2_BOOT_R")
	)
	(segment
		(start -1.670812 -148.286978)
		(end -1.452626 -148.068792)
		(width 0.508)
		(layer "F.Cu")
		(net "VR_PVDDQ_KLM_PH2_BOOT_R")
	)
	(segment
		(start -2.504694 -148.286978)
		(end -1.670812 -148.286978)
		(width 0.508)
		(layer "F.Cu")
		(net "VR_PVDDQ_KLM_PH2_BOOT_R")
	)
	(segment
		(start -0.497586 -138.884406)
		(end -1.62814 -138.884406)
		(width 0.254)
		(layer "F.Cu")
		(net "VR_PVDDQ_KLM_PH1_BOOT_R")
	)
	(segment
		(start -2.624074 -139.00531)
		(end -1.749044 -139.00531)
		(width 0.508)
		(layer "F.Cu")
		(net "VR_PVDDQ_KLM_PH1_BOOT_R")
	)
	(segment
		(start -1.749044 -139.00531)
		(end -1.62814 -138.884406)
		(width 0.508)
		(layer "F.Cu")
		(net "VR_PVDDQ_KLM_PH1_BOOT_R")
	)
	(via
		(at -1.62814 -138.884406)
		(size 0.508)
		(drill 0.254)
		(layers "F.Cu" "B.Cu")
		(net "VR_PVDDQ_KLM_PH1_BOOT_R")
	)
	(segment
		(start 1.4732 -18.161)
		(end 2.150364 -18.161)
		(width 0.254)
		(layer "F.Cu")
		(net "VR_PVDDQ_GHJ_PH2_BOOT_R")
	)
	(segment
		(start 1.4224 -18.2118)
		(end 1.4732 -18.161)
		(width 0.254)
		(layer "F.Cu")
		(net "VR_PVDDQ_GHJ_PH2_BOOT_R")
	)
	(segment
		(start 1.1176 -18.2118)
		(end 1.4224 -18.2118)
		(width 0.508)
		(layer "F.Cu")
		(net "VR_PVDDQ_GHJ_PH2_BOOT_R")
	)
	(segment
		(start 0.75184 -10.60196)
		(end 1.160018 -10.193782)
		(width 0.254)
		(layer "F.Cu")
		(net "VR_PVDDQ_GHJ_PH1_BOOT_R")
	)
	(segment
		(start 1.160018 -10.193782)
		(end 2.067814 -10.193782)
		(width 0.254)
		(layer "F.Cu")
		(net "VR_PVDDQ_GHJ_PH1_BOOT_R")
	)
	(segment
		(start 0.74676 -10.60196)
		(end 0.75184 -10.60196)
		(width 0.254)
		(layer "F.Cu")
		(net "VR_PVDDQ_GHJ_PH1_BOOT_R")
	)
	(segment
		(start 350.357186 -144.593818)
		(end 351.008442 -144.593818)
		(width 0.254)
		(layer "F.Cu")
		(net "VR_PVDDQ_DEF_PH2_BOOT_R")
	)
	(segment
		(start 351.008442 -144.593818)
		(end 351.099882 -144.502378)
		(width 0.254)
		(layer "F.Cu")
		(net "VR_PVDDQ_DEF_PH2_BOOT_R")
	)
	(segment
		(start 351.099882 -144.502378)
		(end 351.30105 -144.502378)
		(width 0.254)
		(layer "F.Cu")
		(net "VR_PVDDQ_DEF_PH2_BOOT_R")
	)
	(segment
		(start 351.30105 -144.502378)
		(end 351.819464 -144.502378)
		(width 0.508)
		(layer "F.Cu")
		(net "VR_PVDDQ_DEF_PH2_BOOT_R")
	)
	(segment
		(start 350.357186 -152.518618)
		(end 351.480882 -152.518618)
		(width 0.254)
		(layer "F.Cu")
		(net "VR_PVDDQ_DEF_PH1_BOOT_R")
	)
	(segment
		(start 351.7265 -152.273)
		(end 351.8535 -152.273)
		(width 0.508)
		(layer "F.Cu")
		(net "VR_PVDDQ_DEF_PH1_BOOT_R")
	)
	(segment
		(start 351.480882 -152.518618)
		(end 351.59315 -152.40635)
		(width 0.254)
		(layer "F.Cu")
		(net "VR_PVDDQ_DEF_PH1_BOOT_R")
	)
	(segment
		(start 351.59315 -152.40635)
		(end 351.7265 -152.273)
		(width 0.508)
		(layer "F.Cu")
		(net "VR_PVDDQ_DEF_PH1_BOOT_R")
	)
	(segment
		(start 349.262192 2.441702)
		(end 350.225106 2.441702)
		(width 0.254)
		(layer "F.Cu")
		(net "VR_PVDDQ_ABC_PH2_BOOT_R")
	)
	(segment
		(start 350.27235 2.488946)
		(end 350.294194 2.51079)
		(width 0.508)
		(layer "F.Cu")
		(net "VR_PVDDQ_ABC_PH2_BOOT_R")
	)
	(segment
		(start 350.225106 2.441702)
		(end 350.27235 2.488946)
		(width 0.254)
		(layer "F.Cu")
		(net "VR_PVDDQ_ABC_PH2_BOOT_R")
	)
	(segment
		(start 350.294194 2.51079)
		(end 351.090738 2.51079)
		(width 0.508)
		(layer "F.Cu")
		(net "VR_PVDDQ_ABC_PH2_BOOT_R")
	)
	(via
		(at 350.27235 2.488946)
		(size 0.508)
		(drill 0.254)
		(layers "F.Cu" "B.Cu")
		(net "VR_PVDDQ_ABC_PH2_BOOT_R")
	)
	(segment
		(start 351.410524 -5.693918)
		(end 351.409 -5.692394)
		(width 0.508)
		(layer "F.Cu")
		(net "VR_PVDDQ_ABC_PH1_BOOT_R")
	)
	(segment
		(start 351.409 -5.692394)
		(end 350.013016 -5.692394)
		(width 0.508)
		(layer "F.Cu")
		(net "VR_PVDDQ_ABC_PH1_BOOT_R")
	)
	(segment
		(start 350.013016 -5.692394)
		(end 349.341186 -5.692394)
		(width 0.254)
		(layer "F.Cu")
		(net "VR_PVDDQ_ABC_PH1_BOOT_R")
	)
	(segment
		(start 180.329586 -53.647594)
		(end 180.926486 -53.647594)
		(width 0.254)
		(layer "F.Cu")
		(net "VR_PVCCIO_CPU1_PH1_BOOT_R")
	)
	(segment
		(start 180.926486 -53.647594)
		(end 181.043072 -53.531008)
		(width 0.254)
		(layer "F.Cu")
		(net "VR_PVCCIO_CPU1_PH1_BOOT_R")
	)
	(segment
		(start 181.043072 -53.531008)
		(end 181.549294 -53.531008)
		(width 0.254)
		(layer "F.Cu")
		(net "VR_PVCCIO_CPU1_PH1_BOOT_R")
	)
	(segment
		(start 181.549294 -53.531008)
		(end 182.309008 -53.531008)
		(width 0.508)
		(layer "F.Cu")
		(net "VR_PVCCIO_CPU1_PH1_BOOT_R")
	)
	(segment
		(start 182.309008 -53.531008)
		(end 182.372 -53.594)
		(width 0.508)
		(layer "F.Cu")
		(net "VR_PVCCIO_CPU1_PH1_BOOT_R")
	)
	(via
		(at 181.549294 -53.531008)
		(size 0.508)
		(drill 0.254)
		(layers "F.Cu" "B.Cu")
		(net "VR_PVCCIO_CPU1_PH1_BOOT_R")
	)
	(segment
		(start 351.707196 -96.501204)
		(end 352.030284 -96.501204)
		(width 0.508)
		(layer "F.Cu")
		(net "VR_PVCCIO_CPU0_PH1_BOOT_R")
	)
	(segment
		(start 350.619822 -96.844866)
		(end 350.622108 -96.84258)
		(width 0.254)
		(layer "F.Cu")
		(net "VR_PVCCIO_CPU0_PH1_BOOT_R")
	)
	(segment
		(start 349.927164 -96.844866)
		(end 350.619822 -96.844866)
		(width 0.254)
		(layer "F.Cu")
		(net "VR_PVCCIO_CPU0_PH1_BOOT_R")
	)
	(segment
		(start 351.36582 -96.84258)
		(end 351.5995 -96.6089)
		(width 0.254)
		(layer "F.Cu")
		(net "VR_PVCCIO_CPU0_PH1_BOOT_R")
	)
	(segment
		(start 351.155 -96.84258)
		(end 351.36582 -96.84258)
		(width 0.254)
		(layer "F.Cu")
		(net "VR_PVCCIO_CPU0_PH1_BOOT_R")
	)
	(segment
		(start 351.5995 -96.6089)
		(end 351.707196 -96.501204)
		(width 0.508)
		(layer "F.Cu")
		(net "VR_PVCCIO_CPU0_PH1_BOOT_R")
	)
	(segment
		(start 350.622108 -96.84258)
		(end 351.155 -96.84258)
		(width 0.254)
		(layer "F.Cu")
		(net "VR_PVCCIO_CPU0_PH1_BOOT_R")
	)
	(via
		(at 351.155 -96.84258)
		(size 0.508)
		(drill 0.254)
		(layers "F.Cu" "B.Cu")
		(net "VR_PVCCIO_CPU0_PH1_BOOT_R")
	)
	(segment
		(start 29.5275 -90.551)
		(end 29.907484 -90.551)
		(width 0.508)
		(layer "F.Cu")
		(net "VR_PVCCIN_CPU1_PH5_BOOT_R")
	)
	(segment
		(start 30.206696 -90.251788)
		(end 31.02991 -90.251788)
		(width 0.254)
		(layer "F.Cu")
		(net "VR_PVCCIN_CPU1_PH5_BOOT_R")
	)
	(segment
		(start 30.13329 -90.325194)
		(end 30.206696 -90.251788)
		(width 0.254)
		(layer "F.Cu")
		(net "VR_PVCCIN_CPU1_PH5_BOOT_R")
	)
	(segment
		(start 29.907484 -90.551)
		(end 30.13329 -90.325194)
		(width 0.508)
		(layer "F.Cu")
		(net "VR_PVCCIN_CPU1_PH5_BOOT_R")
	)
	(segment
		(start 31.02991 -82.123788)
		(end 29.807408 -82.123788)
		(width 0.254)
		(layer "F.Cu")
		(net "VR_PVCCIN_CPU1_PH4_BOOT_R")
	)
	(segment
		(start 29.174186 -81.915)
		(end 29.382974 -82.123788)
		(width 0.508)
		(layer "F.Cu")
		(net "VR_PVCCIN_CPU1_PH4_BOOT_R")
	)
	(segment
		(start 28.8798 -81.915)
		(end 29.174186 -81.915)
		(width 0.508)
		(layer "F.Cu")
		(net "VR_PVCCIN_CPU1_PH4_BOOT_R")
	)
	(segment
		(start 29.382974 -82.123788)
		(end 29.807408 -82.123788)
		(width 0.254)
		(layer "F.Cu")
		(net "VR_PVCCIN_CPU1_PH4_BOOT_R")
	)
	(via
		(at 29.807408 -82.123788)
		(size 0.508)
		(drill 0.254)
		(layers "F.Cu" "B.Cu")
		(net "VR_PVCCIN_CPU1_PH4_BOOT_R")
	)
	(segment
		(start 29.246322 -73.744328)
		(end 29.098748 -73.744328)
		(width 0.254)
		(layer "F.Cu")
		(net "VR_PVCCIN_CPU1_PH3_BOOT_R")
	)
	(segment
		(start 29.79928 -73.995788)
		(end 29.497782 -73.995788)
		(width 0.254)
		(layer "F.Cu")
		(net "VR_PVCCIN_CPU1_PH3_BOOT_R")
	)
	(segment
		(start 31.02991 -73.995788)
		(end 29.79928 -73.995788)
		(width 0.254)
		(layer "F.Cu")
		(net "VR_PVCCIN_CPU1_PH3_BOOT_R")
	)
	(segment
		(start 29.497782 -73.995788)
		(end 29.246322 -73.744328)
		(width 0.254)
		(layer "F.Cu")
		(net "VR_PVCCIN_CPU1_PH3_BOOT_R")
	)
	(segment
		(start 29.098748 -73.744328)
		(end 28.820364 -73.744328)
		(width 0.508)
		(layer "F.Cu")
		(net "VR_PVCCIN_CPU1_PH3_BOOT_R")
	)
	(via
		(at 29.79928 -73.995788)
		(size 0.508)
		(drill 0.254)
		(layers "F.Cu" "B.Cu")
		(net "VR_PVCCIN_CPU1_PH3_BOOT_R")
	)
	(segment
		(start 30.334712 -65.867788)
		(end 31.02991 -65.867788)
		(width 0.254)
		(layer "F.Cu")
		(net "VR_PVCCIN_CPU1_PH2_BOOT_R")
	)
	(segment
		(start 30.2895 -65.913)
		(end 30.334712 -65.867788)
		(width 0.254)
		(layer "F.Cu")
		(net "VR_PVCCIN_CPU1_PH2_BOOT_R")
	)
	(segment
		(start 29.550868 -65.913)
		(end 29.7942 -65.913)
		(width 0.254)
		(layer "F.Cu")
		(net "VR_PVCCIN_CPU1_PH2_BOOT_R")
	)
	(segment
		(start 28.956 -65.913)
		(end 29.550868 -65.913)
		(width 0.508)
		(layer "F.Cu")
		(net "VR_PVCCIN_CPU1_PH2_BOOT_R")
	)
	(segment
		(start 29.7942 -65.913)
		(end 30.2895 -65.913)
		(width 0.254)
		(layer "F.Cu")
		(net "VR_PVCCIN_CPU1_PH2_BOOT_R")
	)
	(via
		(at 29.7942 -65.913)
		(size 0.508)
		(drill 0.254)
		(layers "F.Cu" "B.Cu")
		(net "VR_PVCCIN_CPU1_PH2_BOOT_R")
	)
	(segment
		(start 29.343858 -57.785)
		(end 29.867606 -57.785)
		(width 0.254)
		(layer "F.Cu")
		(net "VR_PVCCIN_CPU1_PH1_BOOT_R")
	)
	(segment
		(start 29.867606 -57.785)
		(end 30.462474 -57.785)
		(width 0.254)
		(layer "F.Cu")
		(net "VR_PVCCIN_CPU1_PH1_BOOT_R")
	)
	(segment
		(start 30.507686 -57.739788)
		(end 31.02991 -57.739788)
		(width 0.254)
		(layer "F.Cu")
		(net "VR_PVCCIN_CPU1_PH1_BOOT_R")
	)
	(segment
		(start 30.462474 -57.785)
		(end 30.507686 -57.739788)
		(width 0.254)
		(layer "F.Cu")
		(net "VR_PVCCIN_CPU1_PH1_BOOT_R")
	)
	(segment
		(start 28.956 -57.785)
		(end 29.343858 -57.785)
		(width 0.508)
		(layer "F.Cu")
		(net "VR_PVCCIN_CPU1_PH1_BOOT_R")
	)
	(via
		(at 29.867606 -57.785)
		(size 0.508)
		(drill 0.254)
		(layers "F.Cu" "B.Cu")
		(net "VR_PVCCIN_CPU1_PH1_BOOT_R")
	)
	(segment
		(start 194.02425 -90.3859)
		(end 194.7418 -90.3859)
		(width 0.508)
		(layer "F.Cu")
		(net "VR_PVCCIN_CPU0_PH5_BOOT_R")
	)
	(segment
		(start 195.371212 -90.251788)
		(end 196.030342 -90.251788)
		(width 0.254)
		(layer "F.Cu")
		(net "VR_PVCCIN_CPU0_PH5_BOOT_R")
	)
	(segment
		(start 194.7418 -90.3859)
		(end 195.2371 -90.3859)
		(width 0.254)
		(layer "F.Cu")
		(net "VR_PVCCIN_CPU0_PH5_BOOT_R")
	)
	(segment
		(start 195.2371 -90.3859)
		(end 195.371212 -90.251788)
		(width 0.254)
		(layer "F.Cu")
		(net "VR_PVCCIN_CPU0_PH5_BOOT_R")
	)
	(segment
		(start 195.396104 -82.209132)
		(end 195.13042 -82.209132)
		(width 0.254)
		(layer "F.Cu")
		(net "VR_PVCCIN_CPU0_PH4_BOOT_R")
	)
	(segment
		(start 194.888358 -82.209132)
		(end 194.0433 -82.209132)
		(width 0.508)
		(layer "F.Cu")
		(net "VR_PVCCIN_CPU0_PH4_BOOT_R")
	)
	(segment
		(start 195.481448 -82.123788)
		(end 195.396104 -82.209132)
		(width 0.254)
		(layer "F.Cu")
		(net "VR_PVCCIN_CPU0_PH4_BOOT_R")
	)
	(segment
		(start 196.030342 -82.123788)
		(end 195.481448 -82.123788)
		(width 0.254)
		(layer "F.Cu")
		(net "VR_PVCCIN_CPU0_PH4_BOOT_R")
	)
	(segment
		(start 195.13042 -82.209132)
		(end 194.888358 -82.209132)
		(width 0.508)
		(layer "F.Cu")
		(net "VR_PVCCIN_CPU0_PH4_BOOT_R")
	)
	(via
		(at 194.888358 -82.209132)
		(size 0.508)
		(drill 0.254)
		(layers "F.Cu" "B.Cu")
		(net "VR_PVCCIN_CPU0_PH4_BOOT_R")
	)
	(segment
		(start 194.49034 -73.9521)
		(end 193.72072 -73.9521)
		(width 0.508)
		(layer "F.Cu")
		(net "VR_PVCCIN_CPU0_PH3_BOOT_R")
	)
	(segment
		(start 194.605148 -73.995788)
		(end 194.5259 -73.91654)
		(width 0.254)
		(layer "F.Cu")
		(net "VR_PVCCIN_CPU0_PH3_BOOT_R")
	)
	(segment
		(start 194.5259 -73.91654)
		(end 194.49034 -73.9521)
		(width 0.508)
		(layer "F.Cu")
		(net "VR_PVCCIN_CPU0_PH3_BOOT_R")
	)
	(segment
		(start 193.72072 -73.9521)
		(end 193.50482 -74.168)
		(width 0.508)
		(layer "F.Cu")
		(net "VR_PVCCIN_CPU0_PH3_BOOT_R")
	)
	(segment
		(start 193.50482 -74.168)
		(end 193.4718 -74.168)
		(width 0.508)
		(layer "F.Cu")
		(net "VR_PVCCIN_CPU0_PH3_BOOT_R")
	)
	(segment
		(start 196.030342 -73.995788)
		(end 194.605148 -73.995788)
		(width 0.254)
		(layer "F.Cu")
		(net "VR_PVCCIN_CPU0_PH3_BOOT_R")
	)
	(via
		(at 194.5259 -73.91654)
		(size 0.762)
		(drill 0.381)
		(layers "F.Cu" "B.Cu")
		(net "VR_PVCCIN_CPU0_PH3_BOOT_R")
	)
	(segment
		(start 194.8942 -66.06667)
		(end 195.35013 -66.06667)
		(width 0.254)
		(layer "F.Cu")
		(net "VR_PVCCIN_CPU0_PH2_BOOT_R")
	)
	(segment
		(start 195.549012 -65.867788)
		(end 196.030342 -65.867788)
		(width 0.254)
		(layer "F.Cu")
		(net "VR_PVCCIN_CPU0_PH2_BOOT_R")
	)
	(segment
		(start 194.183 -66.06667)
		(end 194.8942 -66.06667)
		(width 0.508)
		(layer "F.Cu")
		(net "VR_PVCCIN_CPU0_PH2_BOOT_R")
	)
	(segment
		(start 195.35013 -66.06667)
		(end 195.549012 -65.867788)
		(width 0.254)
		(layer "F.Cu")
		(net "VR_PVCCIN_CPU0_PH2_BOOT_R")
	)
	(segment
		(start 194.7672 -57.912)
		(end 194.939412 -57.739788)
		(width 0.254)
		(layer "F.Cu")
		(net "VR_PVCCIN_CPU0_PH1_BOOT_R")
	)
	(segment
		(start 193.929 -57.912)
		(end 194.7672 -57.912)
		(width 0.508)
		(layer "F.Cu")
		(net "VR_PVCCIN_CPU0_PH1_BOOT_R")
	)
	(segment
		(start 194.939412 -57.739788)
		(end 196.030342 -57.739788)
		(width 0.254)
		(layer "F.Cu")
		(net "VR_PVCCIN_CPU0_PH1_BOOT_R")
	)
	(segment
		(start 386.357876 -157.77845)
		(end 386.357876 -158.152084)
		(width 0.508)
		(layer "F.Cu")
		(net "VR_P1V05_PCH_STBY_PH1_BOOT_R")
	)
	(segment
		(start 386.094224 -157.037278)
		(end 386.357876 -157.30093)
		(width 0.254)
		(layer "F.Cu")
		(net "VR_P1V05_PCH_STBY_PH1_BOOT_R")
	)
	(segment
		(start 386.357876 -157.30093)
		(end 386.357876 -157.77845)
		(width 0.254)
		(layer "F.Cu")
		(net "VR_P1V05_PCH_STBY_PH1_BOOT_R")
	)
	(segment
		(start 386.094224 -156.565092)
		(end 386.094224 -157.037278)
		(width 0.254)
		(layer "F.Cu")
		(net "VR_P1V05_PCH_STBY_PH1_BOOT_R")
	)
	(segment
		(start 6.16331 -134.383526)
		(end 5.214874 -134.383526)
		(width 0.508)
		(layer "F.Cu")
		(net "VR_PVDDQ_KLM_PH1_RC")
	)
	(segment
		(start 5.214874 -134.383526)
		(end 5.207 -134.3914)
		(width 0.508)
		(layer "F.Cu")
		(net "VR_PVDDQ_KLM_PH1_RC")
	)
	(segment
		(start 6.4008 -142.875)
		(end 7.71906 -142.875)
		(width 0.508)
		(layer "F.Cu")
		(net "VR_PVDDQ_KLM_PH2_RC")
	)
	(segment
		(start 7.71906 -142.875)
		(end 7.727188 -142.883128)
		(width 0.508)
		(layer "F.Cu")
		(net "VR_PVDDQ_KLM_PH2_RC")
	)
	(segment
		(start 377.544838 -76.694792)
		(end 377.145042 -76.294996)
		(width 0.1016)
		(layer "F.Cu")
		(net "TP_CPLD1_PL11A")
	)
	(via
		(at 378.2568 -75.9714)
		(size 0.6604)
		(drill 0.3302)
		(layers "F.Cu" "B.Cu")
		(net "TP_CPLD1_PL11A")
	)
	(via
		(at 377.544838 -76.694792)
		(size 0.4572)
		(drill 0.2032)
		(layers "F.Cu" "B.Cu")
		(net "TP_CPLD1_PL11A")
	)
	(segment
		(start 377.544838 -76.683362)
		(end 378.2568 -75.9714)
		(width 0.10795)
		(layer "B.Cu")
		(net "TP_CPLD1_PL11A")
	)
	(segment
		(start 377.544838 -76.694792)
		(end 377.544838 -76.683362)
		(width 0.10795)
		(layer "B.Cu")
		(net "TP_CPLD1_PL11A")
	)
	(segment
		(start 492.0742 -26.5938)
		(end 490.728 -26.5938)
		(width 0.10795)
		(layer "F.Cu")
		(net "SPA_MID_DBG_TX_R")
	)
	(segment
		(start 488.95635 -24.82215)
		(end 488.114594 -24.82215)
		(width 0.10795)
		(layer "F.Cu")
		(net "SPA_MID_DBG_TX_R")
	)
	(segment
		(start 487.384598 -25.552146)
		(end 485.773984 -25.552146)
		(width 0.10795)
		(layer "F.Cu")
		(net "SPA_MID_DBG_TX_R")
	)
	(segment
		(start 488.114594 -24.82215)
		(end 487.384598 -25.552146)
		(width 0.10795)
		(layer "F.Cu")
		(net "SPA_MID_DBG_TX_R")
	)
	(segment
		(start 492.182912 -25.258014)
		(end 492.2012 -25.276302)
		(width 0.10795)
		(layer "F.Cu")
		(net "SPA_MID_DBG_TX_R")
	)
	(segment
		(start 492.2012 -25.276302)
		(end 492.2012 -26.4668)
		(width 0.10795)
		(layer "F.Cu")
		(net "SPA_MID_DBG_TX_R")
	)
	(segment
		(start 492.2012 -26.4668)
		(end 492.0742 -26.5938)
		(width 0.10795)
		(layer "F.Cu")
		(net "SPA_MID_DBG_TX_R")
	)
	(segment
		(start 485.397048 -27.054048)
		(end 485.558084 -27.215084)
		(width 0.10795)
		(layer "F.Cu")
		(net "SPA_MID_DBG_TX_R")
	)
	(segment
		(start 485.773984 -25.552146)
		(end 485.397048 -25.929082)
		(width 0.10795)
		(layer "F.Cu")
		(net "SPA_MID_DBG_TX_R")
	)
	(segment
		(start 485.397048 -25.929082)
		(end 485.397048 -27.054048)
		(width 0.10795)
		(layer "F.Cu")
		(net "SPA_MID_DBG_TX_R")
	)
	(segment
		(start 485.558084 -27.215084)
		(end 485.875076 -27.215084)
		(width 0.10795)
		(layer "F.Cu")
		(net "SPA_MID_DBG_TX_R")
	)
	(segment
		(start 490.728 -26.5938)
		(end 488.95635 -24.82215)
		(width 0.10795)
		(layer "F.Cu")
		(net "SPA_MID_DBG_TX_R")
	)
	(via
		(at 356.235 -29.5402)
		(size 0.508)
		(drill 0.254)
		(layers "F.Cu" "B.Cu")
		(net "SPA_MID_DBG_TX_R")
	)
	(via
		(at 492.0742 -26.5938)
		(size 0.762)
		(drill 0.381)
		(layers "F.Cu" "B.Cu")
		(net "SPA_MID_DBG_TX_R")
	)
	(via
		(at 492.182912 -25.258014)
		(size 0.508)
		(drill 0.254)
		(layers "F.Cu" "B.Cu")
		(net "SPA_MID_DBG_TX_R")
	)
	(via
		(at 458.4192 0.381)
		(size 0.508)
		(drill 0.254)
		(layers "F.Cu" "B.Cu")
		(net "SPA_MID_DBG_TX_R")
	)
	(via
		(at 9.0551 -23.1521)
		(size 0.508)
		(drill 0.254)
		(layers "F.Cu" "B.Cu")
		(net "SPA_MID_DBG_TX_R")
	)
	(segment
		(start 4.499864 -35.710114)
		(end 5.142738 -36.352988)
		(width 0.089408)
		(layer "In2.Cu")
		(net "SPA_MID_DBG_TX_R")
	)
	(segment
		(start 469.816434 -9.146794)
		(end 470.067386 -8.895842)
		(width 0.089408)
		(layer "In2.Cu")
		(net "SPA_MID_DBG_TX_R")
	)
	(segment
		(start 468.851996 -9.146794)
		(end 469.816434 -9.146794)
		(width 0.089408)
		(layer "In2.Cu")
		(net "SPA_MID_DBG_TX_R")
	)
	(segment
		(start 462.9912 -0.992124)
		(end 463.273394 -1.274318)
		(width 0.089408)
		(layer "In2.Cu")
		(net "SPA_MID_DBG_TX_R")
	)
	(segment
		(start 467.703408 -7.998206)
		(end 468.851996 -9.146794)
		(width 0.089408)
		(layer "In2.Cu")
		(net "SPA_MID_DBG_TX_R")
	)
	(segment
		(start 463.455258 -1.274318)
		(end 464.046824 -1.865884)
		(width 0.089408)
		(layer "In2.Cu")
		(net "SPA_MID_DBG_TX_R")
	)
	(segment
		(start 470.676732 -7.831074)
		(end 474.017594 -7.831074)
		(width 0.089408)
		(layer "In2.Cu")
		(net "SPA_MID_DBG_TX_R")
	)
	(segment
		(start 465.172552 -5.89788)
		(end 466.763862 -5.89788)
		(width 0.089408)
		(layer "In2.Cu")
		(net "SPA_MID_DBG_TX_R")
	)
	(segment
		(start 470.067386 -8.895842)
		(end 470.067386 -8.44042)
		(width 0.089408)
		(layer "In2.Cu")
		(net "SPA_MID_DBG_TX_R")
	)
	(segment
		(start 458.4192 0.381)
		(end 458.738732 0.061468)
		(width 0.089408)
		(layer "In2.Cu")
		(net "SPA_MID_DBG_TX_R")
	)
	(segment
		(start 467.703408 -6.837426)
		(end 467.703408 -7.998206)
		(width 0.089408)
		(layer "In2.Cu")
		(net "SPA_MID_DBG_TX_R")
	)
	(segment
		(start 478.700592 -16.148812)
		(end 480.128072 -17.576292)
		(width 0.089408)
		(layer "In2.Cu")
		(net "SPA_MID_DBG_TX_R")
	)
	(segment
		(start 462.9912 -0.729234)
		(end 462.9912 -0.992124)
		(width 0.089408)
		(layer "In2.Cu")
		(net "SPA_MID_DBG_TX_R")
	)
	(segment
		(start 462.200498 0.061468)
		(end 462.9912 -0.729234)
		(width 0.089408)
		(layer "In2.Cu")
		(net "SPA_MID_DBG_TX_R")
	)
	(segment
		(start 480.128072 -17.576292)
		(end 485.51338 -17.576292)
		(width 0.089408)
		(layer "In2.Cu")
		(net "SPA_MID_DBG_TX_R")
	)
	(segment
		(start 5.142738 -36.352988)
		(end 9.059164 -36.352988)
		(width 0.089408)
		(layer "In2.Cu")
		(net "SPA_MID_DBG_TX_R")
	)
	(segment
		(start 458.738732 0.061468)
		(end 462.200498 0.061468)
		(width 0.089408)
		(layer "In2.Cu")
		(net "SPA_MID_DBG_TX_R")
	)
	(segment
		(start 470.067386 -8.44042)
		(end 470.676732 -7.831074)
		(width 0.089408)
		(layer "In2.Cu")
		(net "SPA_MID_DBG_TX_R")
	)
	(segment
		(start 478.700592 -10.405872)
		(end 478.700592 -16.148812)
		(width 0.089408)
		(layer "In2.Cu")
		(net "SPA_MID_DBG_TX_R")
	)
	(segment
		(start 464.046824 -1.865884)
		(end 464.046824 -4.0767)
		(width 0.089408)
		(layer "In2.Cu")
		(net "SPA_MID_DBG_TX_R")
	)
	(segment
		(start 9.863074 -35.549078)
		(end 9.863074 -23.960074)
		(width 0.089408)
		(layer "In2.Cu")
		(net "SPA_MID_DBG_TX_R")
	)
	(segment
		(start 464.046824 -4.0767)
		(end 464.897216 -4.927092)
		(width 0.089408)
		(layer "In2.Cu")
		(net "SPA_MID_DBG_TX_R")
	)
	(segment
		(start 9.863074 -23.960074)
		(end 9.0551 -23.1521)
		(width 0.089408)
		(layer "In2.Cu")
		(net "SPA_MID_DBG_TX_R")
	)
	(segment
		(start 464.897216 -5.622544)
		(end 465.172552 -5.89788)
		(width 0.089408)
		(layer "In2.Cu")
		(net "SPA_MID_DBG_TX_R")
	)
	(segment
		(start 464.897216 -4.927092)
		(end 464.897216 -5.622544)
		(width 0.089408)
		(layer "In2.Cu")
		(net "SPA_MID_DBG_TX_R")
	)
	(segment
		(start 492.182912 -24.245824)
		(end 492.182912 -25.258014)
		(width 0.089408)
		(layer "In2.Cu")
		(net "SPA_MID_DBG_TX_R")
	)
	(segment
		(start 474.780102 -8.593582)
		(end 476.888302 -8.593582)
		(width 0.089408)
		(layer "In2.Cu")
		(net "SPA_MID_DBG_TX_R")
	)
	(segment
		(start 485.51338 -17.576292)
		(end 492.182912 -24.245824)
		(width 0.089408)
		(layer "In2.Cu")
		(net "SPA_MID_DBG_TX_R")
	)
	(segment
		(start 474.017594 -7.831074)
		(end 474.780102 -8.593582)
		(width 0.089408)
		(layer "In2.Cu")
		(net "SPA_MID_DBG_TX_R")
	)
	(segment
		(start 476.888302 -8.593582)
		(end 478.700592 -10.405872)
		(width 0.089408)
		(layer "In2.Cu")
		(net "SPA_MID_DBG_TX_R")
	)
	(segment
		(start 463.273394 -1.274318)
		(end 463.455258 -1.274318)
		(width 0.089408)
		(layer "In2.Cu")
		(net "SPA_MID_DBG_TX_R")
	)
	(segment
		(start 466.763862 -5.89788)
		(end 467.703408 -6.837426)
		(width 0.089408)
		(layer "In2.Cu")
		(net "SPA_MID_DBG_TX_R")
	)
	(segment
		(start 9.059164 -36.352988)
		(end 9.863074 -35.549078)
		(width 0.089408)
		(layer "In2.Cu")
		(net "SPA_MID_DBG_TX_R")
	)
	(segment
		(start 102.842568 2.98704)
		(end 157.721046 2.98704)
		(width 0.089408)
		(layer "In9.Cu")
		(net "SPA_MID_DBG_TX_R")
	)
	(segment
		(start 176.345088 -4.579112)
		(end 176.47158 -4.45262)
		(width 0.089408)
		(layer "In9.Cu")
		(net "SPA_MID_DBG_TX_R")
	)
	(segment
		(start 27.470862 0.255524)
		(end 27.470862 0.455676)
		(width 0.089408)
		(layer "In9.Cu")
		(net "SPA_MID_DBG_TX_R")
	)
	(segment
		(start 161.41065 -0.702564)
		(end 161.760408 -0.702564)
		(width 0.089408)
		(layer "In9.Cu")
		(net "SPA_MID_DBG_TX_R")
	)
	(segment
		(start 261.08914 0.2286)
		(end 262.391906 -1.074166)
		(width 0.089408)
		(layer "In9.Cu")
		(net "SPA_MID_DBG_TX_R")
	)
	(segment
		(start 183.910224 -4.45262)
		(end 184.847992 -3.514852)
		(width 0.089408)
		(layer "In9.Cu")
		(net "SPA_MID_DBG_TX_R")
	)
	(segment
		(start 10.2108 -20.653756)
		(end 10.2108 -7.30123)
		(width 0.089408)
		(layer "In9.Cu")
		(net "SPA_MID_DBG_TX_R")
	)
	(segment
		(start 331.079602 -9.164574)
		(end 331.522578 -9.164574)
		(width 0.089408)
		(layer "In9.Cu")
		(net "SPA_MID_DBG_TX_R")
	)
	(segment
		(start 331.77988 -9.16432)
		(end 332.304898 -9.689338)
		(width 0.089408)
		(layer "In9.Cu")
		(net "SPA_MID_DBG_TX_R")
	)
	(segment
		(start 163.691062 -5.475224)
		(end 164.633402 -6.417564)
		(width 0.089408)
		(layer "In9.Cu")
		(net "SPA_MID_DBG_TX_R")
	)
	(segment
		(start 164.633402 -6.417564)
		(end 166.683436 -6.417564)
		(width 0.089408)
		(layer "In9.Cu")
		(net "SPA_MID_DBG_TX_R")
	)
	(segment
		(start 260.415786 0.2286)
		(end 261.08914 0.2286)
		(width 0.089408)
		(layer "In9.Cu")
		(net "SPA_MID_DBG_TX_R")
	)
	(segment
		(start 332.304898 -9.689338)
		(end 337.154266 -9.689338)
		(width 0.089408)
		(layer "In9.Cu")
		(net "SPA_MID_DBG_TX_R")
	)
	(segment
		(start 102.112064 3.717544)
		(end 102.842568 2.98704)
		(width 0.089408)
		(layer "In9.Cu")
		(net "SPA_MID_DBG_TX_R")
	)
	(segment
		(start 193.096642 -1.024128)
		(end 193.74485 -0.37592)
		(width 0.089408)
		(layer "In9.Cu")
		(net "SPA_MID_DBG_TX_R")
	)
	(segment
		(start 23.035768 -0.46863)
		(end 26.746708 -0.46863)
		(width 0.089408)
		(layer "In9.Cu")
		(net "SPA_MID_DBG_TX_R")
	)
	(segment
		(start 348.446598 -23.487888)
		(end 349.02648 -24.06777)
		(width 0.089408)
		(layer "In9.Cu")
		(net "SPA_MID_DBG_TX_R")
	)
	(segment
		(start 187.77204 -1.024128)
		(end 193.096642 -1.024128)
		(width 0.089408)
		(layer "In9.Cu")
		(net "SPA_MID_DBG_TX_R")
	)
	(segment
		(start 193.74485 -0.37592)
		(end 259.811266 -0.37592)
		(width 0.089408)
		(layer "In9.Cu")
		(net "SPA_MID_DBG_TX_R")
	)
	(segment
		(start 354.620322 -24.06777)
		(end 357.023924 -26.471372)
		(width 0.089408)
		(layer "In9.Cu")
		(net "SPA_MID_DBG_TX_R")
	)
	(segment
		(start 185.281316 -3.514852)
		(end 187.77204 -1.024128)
		(width 0.089408)
		(layer "In9.Cu")
		(net "SPA_MID_DBG_TX_R")
	)
	(segment
		(start 338.489036 -11.024108)
		(end 338.489036 -20.263866)
		(width 0.089408)
		(layer "In9.Cu")
		(net "SPA_MID_DBG_TX_R")
	)
	(segment
		(start 340.775544 -23.487888)
		(end 348.446598 -23.487888)
		(width 0.089408)
		(layer "In9.Cu")
		(net "SPA_MID_DBG_TX_R")
	)
	(segment
		(start 166.683436 -6.417564)
		(end 167.1574 -5.9436)
		(width 0.089408)
		(layer "In9.Cu")
		(net "SPA_MID_DBG_TX_R")
	)
	(segment
		(start 323.142356 -1.074166)
		(end 324.231 -2.16281)
		(width 0.089408)
		(layer "In9.Cu")
		(net "SPA_MID_DBG_TX_R")
	)
	(segment
		(start 170.368214 -4.2164)
		(end 171.358814 -5.207)
		(width 0.089408)
		(layer "In9.Cu")
		(net "SPA_MID_DBG_TX_R")
	)
	(segment
		(start 338.489036 -20.263866)
		(end 339.10397 -20.8788)
		(width 0.089408)
		(layer "In9.Cu")
		(net "SPA_MID_DBG_TX_R")
	)
	(segment
		(start 326.000872 -5.934964)
		(end 327.849992 -5.934964)
		(width 0.089408)
		(layer "In9.Cu")
		(net "SPA_MID_DBG_TX_R")
	)
	(segment
		(start 339.368384 -23.297134)
		(end 340.58479 -23.297134)
		(width 0.089408)
		(layer "In9.Cu")
		(net "SPA_MID_DBG_TX_R")
	)
	(segment
		(start 349.02648 -24.06777)
		(end 354.620322 -24.06777)
		(width 0.089408)
		(layer "In9.Cu")
		(net "SPA_MID_DBG_TX_R")
	)
	(segment
		(start 331.522832 -9.16432)
		(end 331.77988 -9.16432)
		(width 0.089408)
		(layer "In9.Cu")
		(net "SPA_MID_DBG_TX_R")
	)
	(segment
		(start 161.760408 -0.702564)
		(end 163.691062 -2.633218)
		(width 0.089408)
		(layer "In9.Cu")
		(net "SPA_MID_DBG_TX_R")
	)
	(segment
		(start 339.10397 -20.8788)
		(end 339.10397 -23.03272)
		(width 0.089408)
		(layer "In9.Cu")
		(net "SPA_MID_DBG_TX_R")
	)
	(segment
		(start 327.849992 -5.934964)
		(end 331.079602 -9.164574)
		(width 0.089408)
		(layer "In9.Cu")
		(net "SPA_MID_DBG_TX_R")
	)
	(segment
		(start 324.231 -2.16281)
		(end 324.231 -4.165092)
		(width 0.089408)
		(layer "In9.Cu")
		(net "SPA_MID_DBG_TX_R")
	)
	(segment
		(start 171.358814 -5.207)
		(end 171.361608 -5.207)
		(width 0.089408)
		(layer "In9.Cu")
		(net "SPA_MID_DBG_TX_R")
	)
	(segment
		(start 173.16323 -5.623814)
		(end 174.207932 -4.579112)
		(width 0.089408)
		(layer "In9.Cu")
		(net "SPA_MID_DBG_TX_R")
	)
	(segment
		(start 167.1574 -5.9436)
		(end 167.1574 -5.334)
		(width 0.089408)
		(layer "In9.Cu")
		(net "SPA_MID_DBG_TX_R")
	)
	(segment
		(start 184.847992 -3.514852)
		(end 185.281316 -3.514852)
		(width 0.089408)
		(layer "In9.Cu")
		(net "SPA_MID_DBG_TX_R")
	)
	(segment
		(start 339.10397 -23.03272)
		(end 339.368384 -23.297134)
		(width 0.089408)
		(layer "In9.Cu")
		(net "SPA_MID_DBG_TX_R")
	)
	(segment
		(start 324.231 -4.165092)
		(end 326.000872 -5.934964)
		(width 0.089408)
		(layer "In9.Cu")
		(net "SPA_MID_DBG_TX_R")
	)
	(segment
		(start 163.691062 -2.633218)
		(end 163.691062 -5.475224)
		(width 0.089408)
		(layer "In9.Cu")
		(net "SPA_MID_DBG_TX_R")
	)
	(segment
		(start 27.470608 0.45593)
		(end 27.470608 2.177288)
		(width 0.089408)
		(layer "In9.Cu")
		(net "SPA_MID_DBG_TX_R")
	)
	(segment
		(start 167.1574 -5.334)
		(end 168.275 -4.2164)
		(width 0.089408)
		(layer "In9.Cu")
		(net "SPA_MID_DBG_TX_R")
	)
	(segment
		(start 157.721046 2.98704)
		(end 161.41065 -0.702564)
		(width 0.089408)
		(layer "In9.Cu")
		(net "SPA_MID_DBG_TX_R")
	)
	(segment
		(start 14.08684 -3.42519)
		(end 14.08684 -0.373888)
		(width 0.089408)
		(layer "In9.Cu")
		(net "SPA_MID_DBG_TX_R")
	)
	(segment
		(start 20.529804 2.037334)
		(end 23.035768 -0.46863)
		(width 0.089408)
		(layer "In9.Cu")
		(net "SPA_MID_DBG_TX_R")
	)
	(segment
		(start 340.58479 -23.297134)
		(end 340.775544 -23.487888)
		(width 0.089408)
		(layer "In9.Cu")
		(net "SPA_MID_DBG_TX_R")
	)
	(segment
		(start 357.023924 -28.751276)
		(end 356.235 -29.5402)
		(width 0.089408)
		(layer "In9.Cu")
		(net "SPA_MID_DBG_TX_R")
	)
	(segment
		(start 331.522578 -9.164574)
		(end 331.522832 -9.16432)
		(width 0.089408)
		(layer "In9.Cu")
		(net "SPA_MID_DBG_TX_R")
	)
	(segment
		(start 176.47158 -4.45262)
		(end 183.910224 -4.45262)
		(width 0.089408)
		(layer "In9.Cu")
		(net "SPA_MID_DBG_TX_R")
	)
	(segment
		(start 357.023924 -26.471372)
		(end 357.023924 -28.751276)
		(width 0.089408)
		(layer "In9.Cu")
		(net "SPA_MID_DBG_TX_R")
	)
	(segment
		(start 14.08684 -0.373888)
		(end 16.498062 2.037334)
		(width 0.089408)
		(layer "In9.Cu")
		(net "SPA_MID_DBG_TX_R")
	)
	(segment
		(start 262.391906 -1.074166)
		(end 323.142356 -1.074166)
		(width 0.089408)
		(layer "In9.Cu")
		(net "SPA_MID_DBG_TX_R")
	)
	(segment
		(start 259.811266 -0.37592)
		(end 260.415786 0.2286)
		(width 0.089408)
		(layer "In9.Cu")
		(net "SPA_MID_DBG_TX_R")
	)
	(segment
		(start 337.154266 -9.689338)
		(end 338.489036 -11.024108)
		(width 0.089408)
		(layer "In9.Cu")
		(net "SPA_MID_DBG_TX_R")
	)
	(segment
		(start 29.010864 3.717544)
		(end 102.112064 3.717544)
		(width 0.089408)
		(layer "In9.Cu")
		(net "SPA_MID_DBG_TX_R")
	)
	(segment
		(start 171.778422 -5.623814)
		(end 173.16323 -5.623814)
		(width 0.089408)
		(layer "In9.Cu")
		(net "SPA_MID_DBG_TX_R")
	)
	(segment
		(start 26.746708 -0.46863)
		(end 27.470862 0.255524)
		(width 0.089408)
		(layer "In9.Cu")
		(net "SPA_MID_DBG_TX_R")
	)
	(segment
		(start 168.275 -4.2164)
		(end 170.368214 -4.2164)
		(width 0.089408)
		(layer "In9.Cu")
		(net "SPA_MID_DBG_TX_R")
	)
	(segment
		(start 27.470862 0.455676)
		(end 27.470608 0.45593)
		(width 0.089408)
		(layer "In9.Cu")
		(net "SPA_MID_DBG_TX_R")
	)
	(segment
		(start 10.2108 -7.30123)
		(end 14.08684 -3.42519)
		(width 0.089408)
		(layer "In9.Cu")
		(net "SPA_MID_DBG_TX_R")
	)
	(segment
		(start 27.470608 2.177288)
		(end 29.010864 3.717544)
		(width 0.089408)
		(layer "In9.Cu")
		(net "SPA_MID_DBG_TX_R")
	)
	(segment
		(start 9.452356 -21.4122)
		(end 10.2108 -20.653756)
		(width 0.089408)
		(layer "In9.Cu")
		(net "SPA_MID_DBG_TX_R")
	)
	(segment
		(start 171.361608 -5.207)
		(end 171.778422 -5.623814)
		(width 0.089408)
		(layer "In9.Cu")
		(net "SPA_MID_DBG_TX_R")
	)
	(segment
		(start 9.452356 -22.754844)
		(end 9.452356 -21.4122)
		(width 0.089408)
		(layer "In9.Cu")
		(net "SPA_MID_DBG_TX_R")
	)
	(segment
		(start 16.498062 2.037334)
		(end 20.529804 2.037334)
		(width 0.089408)
		(layer "In9.Cu")
		(net "SPA_MID_DBG_TX_R")
	)
	(segment
		(start 9.0551 -23.1521)
		(end 9.452356 -22.754844)
		(width 0.089408)
		(layer "In9.Cu")
		(net "SPA_MID_DBG_TX_R")
	)
	(segment
		(start 174.207932 -4.579112)
		(end 176.345088 -4.579112)
		(width 0.089408)
		(layer "In9.Cu")
		(net "SPA_MID_DBG_TX_R")
	)
	(segment
		(start 356.235 -29.5402)
		(end 356.362 -29.5402)
		(width 0.089408)
		(layer "In11.Cu")
		(net "SPA_MID_DBG_TX_R")
	)
	(segment
		(start 381.164592 -5.296408)
		(end 382.441704 -4.019296)
		(width 0.089408)
		(layer "In11.Cu")
		(net "SPA_MID_DBG_TX_R")
	)
	(segment
		(start 457.835 -0.2032)
		(end 458.4192 0.381)
		(width 0.089408)
		(layer "In11.Cu")
		(net "SPA_MID_DBG_TX_R")
	)
	(segment
		(start 439.7248 -2.2606)
		(end 440.44997 -2.98577)
		(width 0.089408)
		(layer "In11.Cu")
		(net "SPA_MID_DBG_TX_R")
	)
	(segment
		(start 449.732146 -0.2032)
		(end 457.835 -0.2032)
		(width 0.089408)
		(layer "In11.Cu")
		(net "SPA_MID_DBG_TX_R")
	)
	(segment
		(start 371.561868 -5.296408)
		(end 381.164592 -5.296408)
		(width 0.089408)
		(layer "In11.Cu")
		(net "SPA_MID_DBG_TX_R")
	)
	(segment
		(start 424.046142 -4.019296)
		(end 425.625768 -2.43967)
		(width 0.089408)
		(layer "In11.Cu")
		(net "SPA_MID_DBG_TX_R")
	)
	(segment
		(start 382.441704 -4.019296)
		(end 424.046142 -4.019296)
		(width 0.089408)
		(layer "In11.Cu")
		(net "SPA_MID_DBG_TX_R")
	)
	(segment
		(start 360.68 -16.178276)
		(end 371.561868 -5.296408)
		(width 0.089408)
		(layer "In11.Cu")
		(net "SPA_MID_DBG_TX_R")
	)
	(segment
		(start 425.999656 -2.43967)
		(end 426.178726 -2.2606)
		(width 0.089408)
		(layer "In11.Cu")
		(net "SPA_MID_DBG_TX_R")
	)
	(segment
		(start 446.949576 -2.98577)
		(end 449.732146 -0.2032)
		(width 0.089408)
		(layer "In11.Cu")
		(net "SPA_MID_DBG_TX_R")
	)
	(segment
		(start 360.68 -25.2222)
		(end 360.68 -16.178276)
		(width 0.089408)
		(layer "In11.Cu")
		(net "SPA_MID_DBG_TX_R")
	)
	(segment
		(start 440.44997 -2.98577)
		(end 446.949576 -2.98577)
		(width 0.089408)
		(layer "In11.Cu")
		(net "SPA_MID_DBG_TX_R")
	)
	(segment
		(start 356.362 -29.5402)
		(end 360.68 -25.2222)
		(width 0.089408)
		(layer "In11.Cu")
		(net "SPA_MID_DBG_TX_R")
	)
	(segment
		(start 426.178726 -2.2606)
		(end 439.7248 -2.2606)
		(width 0.089408)
		(layer "In11.Cu")
		(net "SPA_MID_DBG_TX_R")
	)
	(segment
		(start 425.625768 -2.43967)
		(end 425.999656 -2.43967)
		(width 0.089408)
		(layer "In11.Cu")
		(net "SPA_MID_DBG_TX_R")
	)
	(segment
		(start 488.654598 -29.774388)
		(end 488.177586 -29.297376)
		(width 0.10795)
		(layer "F.Cu")
		(net "SPA_MID_DBG_RX_R")
	)
	(segment
		(start 488.654598 -30.1752)
		(end 488.654598 -29.774388)
		(width 0.10795)
		(layer "F.Cu")
		(net "SPA_MID_DBG_RX_R")
	)
	(segment
		(start 488.177586 -29.297376)
		(end 487.970576 -29.297376)
		(width 0.10795)
		(layer "F.Cu")
		(net "SPA_MID_DBG_RX_R")
	)
	(via
		(at 401.677886 -12.229592)
		(size 0.6604)
		(drill 0.3302)
		(layers "F.Cu" "B.Cu")
		(net "SPA_MID_DBG_RX_R")
	)
	(via
		(at 356.6668 -30.2768)
		(size 0.508)
		(drill 0.254)
		(layers "F.Cu" "B.Cu")
		(net "SPA_MID_DBG_RX_R")
	)
	(via
		(at 400.054572 -18.088102)
		(size 0.508)
		(drill 0.254)
		(layers "F.Cu" "B.Cu")
		(net "SPA_MID_DBG_RX_R")
	)
	(via
		(at 392.458194 -6.139688)
		(size 0.508)
		(drill 0.254)
		(layers "F.Cu" "B.Cu")
		(net "SPA_MID_DBG_RX_R")
	)
	(via
		(at 8.636 -23.7109)
		(size 0.508)
		(drill 0.254)
		(layers "F.Cu" "B.Cu")
		(net "SPA_MID_DBG_RX_R")
	)
	(via
		(at 488.654598 -30.1752)
		(size 0.508)
		(drill 0.254)
		(layers "F.Cu" "B.Cu")
		(net "SPA_MID_DBG_RX_R")
	)
	(via
		(at 478.3328 -19.4564)
		(size 0.508)
		(drill 0.254)
		(layers "F.Cu" "B.Cu")
		(net "SPA_MID_DBG_RX_R")
	)
	(segment
		(start 393.492482 -5.1054)
		(end 392.458194 -6.139688)
		(width 0.10795)
		(layer "B.Cu")
		(net "SPA_MID_DBG_RX_R")
	)
	(segment
		(start 401.677886 -12.229592)
		(end 401.64004 -12.191746)
		(width 0.10795)
		(layer "B.Cu")
		(net "SPA_MID_DBG_RX_R")
	)
	(segment
		(start 401.64004 -6.582918)
		(end 400.162522 -5.1054)
		(width 0.10795)
		(layer "B.Cu")
		(net "SPA_MID_DBG_RX_R")
	)
	(segment
		(start 400.162522 -5.1054)
		(end 393.492482 -5.1054)
		(width 0.10795)
		(layer "B.Cu")
		(net "SPA_MID_DBG_RX_R")
	)
	(segment
		(start 401.677886 -14.75486)
		(end 401.677886 -12.229592)
		(width 0.10795)
		(layer "B.Cu")
		(net "SPA_MID_DBG_RX_R")
	)
	(segment
		(start 400.054572 -16.378174)
		(end 401.677886 -14.75486)
		(width 0.10795)
		(layer "B.Cu")
		(net "SPA_MID_DBG_RX_R")
	)
	(segment
		(start 401.64004 -12.191746)
		(end 401.64004 -6.582918)
		(width 0.10795)
		(layer "B.Cu")
		(net "SPA_MID_DBG_RX_R")
	)
	(segment
		(start 400.054572 -18.088102)
		(end 400.054572 -16.378174)
		(width 0.10795)
		(layer "B.Cu")
		(net "SPA_MID_DBG_RX_R")
	)
	(segment
		(start 483.25786 -18.86458)
		(end 485.16286 -18.86458)
		(width 0.089408)
		(layer "In2.Cu")
		(net "SPA_MID_DBG_RX_R")
	)
	(segment
		(start 9.595104 -33.718754)
		(end 9.595104 -24.670004)
		(width 0.089408)
		(layer "In2.Cu")
		(net "SPA_MID_DBG_RX_R")
	)
	(segment
		(start 478.3328 -19.4564)
		(end 481.09505 -19.4564)
		(width 0.089408)
		(layer "In2.Cu")
		(net "SPA_MID_DBG_RX_R")
	)
	(segment
		(start 8.301736 -35.012122)
		(end 9.595104 -33.718754)
		(width 0.089408)
		(layer "In2.Cu")
		(net "SPA_MID_DBG_RX_R")
	)
	(segment
		(start 481.254054 -19.615404)
		(end 482.507036 -19.615404)
		(width 0.089408)
		(layer "In2.Cu")
		(net "SPA_MID_DBG_RX_R")
	)
	(segment
		(start 5.899912 -35.710114)
		(end 6.597904 -35.012122)
		(width 0.089408)
		(layer "In2.Cu")
		(net "SPA_MID_DBG_RX_R")
	)
	(segment
		(start 489.111544 -22.813264)
		(end 489.111544 -29.718254)
		(width 0.089408)
		(layer "In2.Cu")
		(net "SPA_MID_DBG_RX_R")
	)
	(segment
		(start 9.595104 -24.670004)
		(end 8.636 -23.7109)
		(width 0.089408)
		(layer "In2.Cu")
		(net "SPA_MID_DBG_RX_R")
	)
	(segment
		(start 481.09505 -19.4564)
		(end 481.254054 -19.615404)
		(width 0.089408)
		(layer "In2.Cu")
		(net "SPA_MID_DBG_RX_R")
	)
	(segment
		(start 482.507036 -19.615404)
		(end 483.25786 -18.86458)
		(width 0.089408)
		(layer "In2.Cu")
		(net "SPA_MID_DBG_RX_R")
	)
	(segment
		(start 6.597904 -35.012122)
		(end 8.301736 -35.012122)
		(width 0.089408)
		(layer "In2.Cu")
		(net "SPA_MID_DBG_RX_R")
	)
	(segment
		(start 489.111544 -29.718254)
		(end 488.654598 -30.1752)
		(width 0.089408)
		(layer "In2.Cu")
		(net "SPA_MID_DBG_RX_R")
	)
	(segment
		(start 485.16286 -18.86458)
		(end 489.111544 -22.813264)
		(width 0.089408)
		(layer "In2.Cu")
		(net "SPA_MID_DBG_RX_R")
	)
	(segment
		(start 476.505524 -18.3515)
		(end 477.2279 -18.3515)
		(width 0.089408)
		(layer "In4.Cu")
		(net "SPA_MID_DBG_RX_R")
	)
	(segment
		(start 426.009816 -11.177016)
		(end 449.004182 -11.177016)
		(width 0.089408)
		(layer "In4.Cu")
		(net "SPA_MID_DBG_RX_R")
	)
	(segment
		(start 404.125938 -18.776696)
		(end 404.74265 -18.776696)
		(width 0.089408)
		(layer "In4.Cu")
		(net "SPA_MID_DBG_RX_R")
	)
	(segment
		(start 400.054572 -18.088102)
		(end 400.066764 -18.100294)
		(width 0.089408)
		(layer "In4.Cu")
		(net "SPA_MID_DBG_RX_R")
	)
	(segment
		(start 462.459832 -16.037306)
		(end 463.474562 -16.037306)
		(width 0.0889)
		(layer "In4.Cu")
		(net "SPA_MID_DBG_RX_R")
	)
	(segment
		(start 404.9522 -16.248634)
		(end 409.720034 -11.4808)
		(width 0.089408)
		(layer "In4.Cu")
		(net "SPA_MID_DBG_RX_R")
	)
	(segment
		(start 425.786296 -10.953496)
		(end 426.009816 -11.177016)
		(width 0.089408)
		(layer "In4.Cu")
		(net "SPA_MID_DBG_RX_R")
	)
	(segment
		(start 404.74265 -18.776696)
		(end 404.9522 -18.567146)
		(width 0.089408)
		(layer "In4.Cu")
		(net "SPA_MID_DBG_RX_R")
	)
	(segment
		(start 420.325804 -10.953496)
		(end 425.786296 -10.953496)
		(width 0.089408)
		(layer "In4.Cu")
		(net "SPA_MID_DBG_RX_R")
	)
	(segment
		(start 471.597736 -13.443712)
		(end 476.505524 -18.3515)
		(width 0.089408)
		(layer "In4.Cu")
		(net "SPA_MID_DBG_RX_R")
	)
	(segment
		(start 461.57642 -16.920718)
		(end 462.459832 -16.037306)
		(width 0.089408)
		(layer "In4.Cu")
		(net "SPA_MID_DBG_RX_R")
	)
	(segment
		(start 463.474562 -16.037306)
		(end 466.068156 -13.443712)
		(width 0.0889)
		(layer "In4.Cu")
		(net "SPA_MID_DBG_RX_R")
	)
	(segment
		(start 402.08327 -18.8849)
		(end 404.017734 -18.8849)
		(width 0.089408)
		(layer "In4.Cu")
		(net "SPA_MID_DBG_RX_R")
	)
	(segment
		(start 419.7985 -11.4808)
		(end 420.325804 -10.953496)
		(width 0.089408)
		(layer "In4.Cu")
		(net "SPA_MID_DBG_RX_R")
	)
	(segment
		(start 449.004182 -11.177016)
		(end 452.755 -14.927834)
		(width 0.089408)
		(layer "In4.Cu")
		(net "SPA_MID_DBG_RX_R")
	)
	(segment
		(start 477.2279 -18.3515)
		(end 478.3328 -19.4564)
		(width 0.089408)
		(layer "In4.Cu")
		(net "SPA_MID_DBG_RX_R")
	)
	(segment
		(start 404.9522 -18.567146)
		(end 404.9522 -16.248634)
		(width 0.089408)
		(layer "In4.Cu")
		(net "SPA_MID_DBG_RX_R")
	)
	(segment
		(start 453.03567 -16.920718)
		(end 461.57642 -16.920718)
		(width 0.089408)
		(layer "In4.Cu")
		(net "SPA_MID_DBG_RX_R")
	)
	(segment
		(start 452.755 -14.927834)
		(end 452.755 -16.640048)
		(width 0.089408)
		(layer "In4.Cu")
		(net "SPA_MID_DBG_RX_R")
	)
	(segment
		(start 466.068156 -13.443712)
		(end 471.597736 -13.443712)
		(width 0.089408)
		(layer "In4.Cu")
		(net "SPA_MID_DBG_RX_R")
	)
	(segment
		(start 401.298664 -18.100294)
		(end 402.08327 -18.8849)
		(width 0.089408)
		(layer "In4.Cu")
		(net "SPA_MID_DBG_RX_R")
	)
	(segment
		(start 400.066764 -18.100294)
		(end 401.298664 -18.100294)
		(width 0.089408)
		(layer "In4.Cu")
		(net "SPA_MID_DBG_RX_R")
	)
	(segment
		(start 404.017734 -18.8849)
		(end 404.125938 -18.776696)
		(width 0.089408)
		(layer "In4.Cu")
		(net "SPA_MID_DBG_RX_R")
	)
	(segment
		(start 452.755 -16.640048)
		(end 453.03567 -16.920718)
		(width 0.089408)
		(layer "In4.Cu")
		(net "SPA_MID_DBG_RX_R")
	)
	(segment
		(start 409.720034 -11.4808)
		(end 419.7985 -11.4808)
		(width 0.089408)
		(layer "In4.Cu")
		(net "SPA_MID_DBG_RX_R")
	)
	(segment
		(start 8.636 -23.7109)
		(end 8.636 -23.005034)
		(width 0.089408)
		(layer "In9.Cu")
		(net "SPA_MID_DBG_RX_R")
	)
	(segment
		(start 163.93287 -5.374894)
		(end 164.335206 -5.77723)
		(width 0.089408)
		(layer "In9.Cu")
		(net "SPA_MID_DBG_RX_R")
	)
	(segment
		(start 186.728354 -0.674624)
		(end 192.585594 -0.674624)
		(width 0.089408)
		(layer "In9.Cu")
		(net "SPA_MID_DBG_RX_R")
	)
	(segment
		(start 176.327054 -4.191)
		(end 183.18226 -4.191)
		(width 0.089408)
		(layer "In9.Cu")
		(net "SPA_MID_DBG_RX_R")
	)
	(segment
		(start 260.162802 0.626364)
		(end 261.044436 0.626364)
		(width 0.089408)
		(layer "In9.Cu")
		(net "SPA_MID_DBG_RX_R")
	)
	(segment
		(start 13.810996 -3.358896)
		(end 13.810996 -0.21209)
		(width 0.089408)
		(layer "In9.Cu")
		(net "SPA_MID_DBG_RX_R")
	)
	(segment
		(start 8.636 -23.005034)
		(end 9.210548 -22.430486)
		(width 0.089408)
		(layer "In9.Cu")
		(net "SPA_MID_DBG_RX_R")
	)
	(segment
		(start 102.212394 3.959352)
		(end 102.942898 3.228848)
		(width 0.089408)
		(layer "In9.Cu")
		(net "SPA_MID_DBG_RX_R")
	)
	(segment
		(start 337.254596 -9.44753)
		(end 338.730844 -10.923778)
		(width 0.089408)
		(layer "In9.Cu")
		(net "SPA_MID_DBG_RX_R")
	)
	(segment
		(start 23.15591 -0.226822)
		(end 26.646378 -0.226822)
		(width 0.089408)
		(layer "In9.Cu")
		(net "SPA_MID_DBG_RX_R")
	)
	(segment
		(start 331.179678 -8.922512)
		(end 331.88021 -8.922512)
		(width 0.089408)
		(layer "In9.Cu")
		(net "SPA_MID_DBG_RX_R")
	)
	(segment
		(start 163.93287 -2.532888)
		(end 163.93287 -5.374894)
		(width 0.089408)
		(layer "In9.Cu")
		(net "SPA_MID_DBG_RX_R")
	)
	(segment
		(start 183.44896 -3.9243)
		(end 183.44896 -3.197606)
		(width 0.089408)
		(layer "In9.Cu")
		(net "SPA_MID_DBG_RX_R")
	)
	(segment
		(start 27.2288 2.277618)
		(end 28.910534 3.959352)
		(width 0.089408)
		(layer "In9.Cu")
		(net "SPA_MID_DBG_RX_R")
	)
	(segment
		(start 9.210548 -21.244052)
		(end 9.9568 -20.4978)
		(width 0.089408)
		(layer "In9.Cu")
		(net "SPA_MID_DBG_RX_R")
	)
	(segment
		(start 102.942898 3.228848)
		(end 157.821376 3.228848)
		(width 0.089408)
		(layer "In9.Cu")
		(net "SPA_MID_DBG_RX_R")
	)
	(segment
		(start 26.646378 -0.226822)
		(end 27.2288 0.3556)
		(width 0.089408)
		(layer "In9.Cu")
		(net "SPA_MID_DBG_RX_R")
	)
	(segment
		(start 185.741818 0.002794)
		(end 186.050936 0.002794)
		(width 0.089408)
		(layer "In9.Cu")
		(net "SPA_MID_DBG_RX_R")
	)
	(segment
		(start 183.18226 -4.191)
		(end 183.44896 -3.9243)
		(width 0.089408)
		(layer "In9.Cu")
		(net "SPA_MID_DBG_RX_R")
	)
	(segment
		(start 338.730844 -19.24939)
		(end 340.176866 -20.695412)
		(width 0.089408)
		(layer "In9.Cu")
		(net "SPA_MID_DBG_RX_R")
	)
	(segment
		(start 323.242686 -0.832358)
		(end 324.472808 -2.06248)
		(width 0.089408)
		(layer "In9.Cu")
		(net "SPA_MID_DBG_RX_R")
	)
	(segment
		(start 332.405228 -9.44753)
		(end 337.254596 -9.44753)
		(width 0.089408)
		(layer "In9.Cu")
		(net "SPA_MID_DBG_RX_R")
	)
	(segment
		(start 170.471338 -3.974592)
		(end 171.793154 -5.296408)
		(width 0.089408)
		(layer "In9.Cu")
		(net "SPA_MID_DBG_RX_R")
	)
	(segment
		(start 165.393624 -5.77723)
		(end 167.196262 -3.974592)
		(width 0.089408)
		(layer "In9.Cu")
		(net "SPA_MID_DBG_RX_R")
	)
	(segment
		(start 356.6668 -29.710126)
		(end 356.6668 -30.2768)
		(width 0.089408)
		(layer "In9.Cu")
		(net "SPA_MID_DBG_RX_R")
	)
	(segment
		(start 340.875874 -23.24608)
		(end 348.575884 -23.24608)
		(width 0.089408)
		(layer "In9.Cu")
		(net "SPA_MID_DBG_RX_R")
	)
	(segment
		(start 9.210548 -22.430486)
		(end 9.210548 -21.244052)
		(width 0.089408)
		(layer "In9.Cu")
		(net "SPA_MID_DBG_RX_R")
	)
	(segment
		(start 173.148498 -5.296408)
		(end 174.107602 -4.337304)
		(width 0.089408)
		(layer "In9.Cu")
		(net "SPA_MID_DBG_RX_R")
	)
	(segment
		(start 348.575884 -23.24608)
		(end 349.155766 -23.825962)
		(width 0.089408)
		(layer "In9.Cu")
		(net "SPA_MID_DBG_RX_R")
	)
	(segment
		(start 161.860738 -0.460756)
		(end 163.93287 -2.532888)
		(width 0.089408)
		(layer "In9.Cu")
		(net "SPA_MID_DBG_RX_R")
	)
	(segment
		(start 357.265732 -26.371042)
		(end 357.265732 -29.111194)
		(width 0.089408)
		(layer "In9.Cu")
		(net "SPA_MID_DBG_RX_R")
	)
	(segment
		(start 184.606184 -1.13284)
		(end 185.741818 0.002794)
		(width 0.089408)
		(layer "In9.Cu")
		(net "SPA_MID_DBG_RX_R")
	)
	(segment
		(start 193.124328 -0.13589)
		(end 193.642742 -0.13589)
		(width 0.089408)
		(layer "In9.Cu")
		(net "SPA_MID_DBG_RX_R")
	)
	(segment
		(start 192.585594 -0.674624)
		(end 193.124328 -0.13589)
		(width 0.089408)
		(layer "In9.Cu")
		(net "SPA_MID_DBG_RX_R")
	)
	(segment
		(start 28.910534 3.959352)
		(end 102.212394 3.959352)
		(width 0.089408)
		(layer "In9.Cu")
		(net "SPA_MID_DBG_RX_R")
	)
	(segment
		(start 161.51098 -0.460756)
		(end 161.860738 -0.460756)
		(width 0.089408)
		(layer "In9.Cu")
		(net "SPA_MID_DBG_RX_R")
	)
	(segment
		(start 340.176866 -22.547072)
		(end 340.875874 -23.24608)
		(width 0.089408)
		(layer "In9.Cu")
		(net "SPA_MID_DBG_RX_R")
	)
	(segment
		(start 193.642742 -0.13589)
		(end 193.64452 -0.134112)
		(width 0.089408)
		(layer "In9.Cu")
		(net "SPA_MID_DBG_RX_R")
	)
	(segment
		(start 261.044436 0.626364)
		(end 262.503158 -0.832358)
		(width 0.089408)
		(layer "In9.Cu")
		(net "SPA_MID_DBG_RX_R")
	)
	(segment
		(start 354.720652 -23.825962)
		(end 357.265732 -26.371042)
		(width 0.089408)
		(layer "In9.Cu")
		(net "SPA_MID_DBG_RX_R")
	)
	(segment
		(start 193.64452 -0.134112)
		(end 259.402326 -0.134112)
		(width 0.089408)
		(layer "In9.Cu")
		(net "SPA_MID_DBG_RX_R")
	)
	(segment
		(start 20.641056 2.288032)
		(end 23.15591 -0.226822)
		(width 0.089408)
		(layer "In9.Cu")
		(net "SPA_MID_DBG_RX_R")
	)
	(segment
		(start 9.9568 -7.213092)
		(end 13.810996 -3.358896)
		(width 0.089408)
		(layer "In9.Cu")
		(net "SPA_MID_DBG_RX_R")
	)
	(segment
		(start 340.176866 -20.695412)
		(end 340.176866 -22.547072)
		(width 0.089408)
		(layer "In9.Cu")
		(net "SPA_MID_DBG_RX_R")
	)
	(segment
		(start 259.402326 -0.134112)
		(end 260.162802 0.626364)
		(width 0.089408)
		(layer "In9.Cu")
		(net "SPA_MID_DBG_RX_R")
	)
	(segment
		(start 331.88021 -8.922512)
		(end 332.405228 -9.44753)
		(width 0.089408)
		(layer "In9.Cu")
		(net "SPA_MID_DBG_RX_R")
	)
	(segment
		(start 324.472808 -2.06248)
		(end 324.472808 -4.064762)
		(width 0.089408)
		(layer "In9.Cu")
		(net "SPA_MID_DBG_RX_R")
	)
	(segment
		(start 326.101202 -5.693156)
		(end 327.950322 -5.693156)
		(width 0.089408)
		(layer "In9.Cu")
		(net "SPA_MID_DBG_RX_R")
	)
	(segment
		(start 164.335206 -5.77723)
		(end 165.393624 -5.77723)
		(width 0.089408)
		(layer "In9.Cu")
		(net "SPA_MID_DBG_RX_R")
	)
	(segment
		(start 174.107602 -4.337304)
		(end 176.18075 -4.337304)
		(width 0.089408)
		(layer "In9.Cu")
		(net "SPA_MID_DBG_RX_R")
	)
	(segment
		(start 176.18075 -4.337304)
		(end 176.327054 -4.191)
		(width 0.089408)
		(layer "In9.Cu")
		(net "SPA_MID_DBG_RX_R")
	)
	(segment
		(start 349.155766 -23.825962)
		(end 354.720652 -23.825962)
		(width 0.089408)
		(layer "In9.Cu")
		(net "SPA_MID_DBG_RX_R")
	)
	(segment
		(start 184.606184 -2.040382)
		(end 184.606184 -1.13284)
		(width 0.089408)
		(layer "In9.Cu")
		(net "SPA_MID_DBG_RX_R")
	)
	(segment
		(start 167.196262 -3.974592)
		(end 170.471338 -3.974592)
		(width 0.089408)
		(layer "In9.Cu")
		(net "SPA_MID_DBG_RX_R")
	)
	(segment
		(start 324.472808 -4.064762)
		(end 326.101202 -5.693156)
		(width 0.089408)
		(layer "In9.Cu")
		(net "SPA_MID_DBG_RX_R")
	)
	(segment
		(start 9.9568 -20.4978)
		(end 9.9568 -7.213092)
		(width 0.089408)
		(layer "In9.Cu")
		(net "SPA_MID_DBG_RX_R")
	)
	(segment
		(start 262.503158 -0.832358)
		(end 323.242686 -0.832358)
		(width 0.089408)
		(layer "In9.Cu")
		(net "SPA_MID_DBG_RX_R")
	)
	(segment
		(start 16.311118 2.288032)
		(end 20.641056 2.288032)
		(width 0.089408)
		(layer "In9.Cu")
		(net "SPA_MID_DBG_RX_R")
	)
	(segment
		(start 27.2288 0.3556)
		(end 27.2288 2.277618)
		(width 0.089408)
		(layer "In9.Cu")
		(net "SPA_MID_DBG_RX_R")
	)
	(segment
		(start 186.050936 0.002794)
		(end 186.728354 -0.674624)
		(width 0.089408)
		(layer "In9.Cu")
		(net "SPA_MID_DBG_RX_R")
	)
	(segment
		(start 338.730844 -10.923778)
		(end 338.730844 -19.24939)
		(width 0.089408)
		(layer "In9.Cu")
		(net "SPA_MID_DBG_RX_R")
	)
	(segment
		(start 157.821376 3.228848)
		(end 161.51098 -0.460756)
		(width 0.089408)
		(layer "In9.Cu")
		(net "SPA_MID_DBG_RX_R")
	)
	(segment
		(start 171.793154 -5.296408)
		(end 173.148498 -5.296408)
		(width 0.089408)
		(layer "In9.Cu")
		(net "SPA_MID_DBG_RX_R")
	)
	(segment
		(start 183.44896 -3.197606)
		(end 184.606184 -2.040382)
		(width 0.089408)
		(layer "In9.Cu")
		(net "SPA_MID_DBG_RX_R")
	)
	(segment
		(start 327.950322 -5.693156)
		(end 331.179678 -8.922512)
		(width 0.089408)
		(layer "In9.Cu")
		(net "SPA_MID_DBG_RX_R")
	)
	(segment
		(start 13.810996 -0.21209)
		(end 16.311118 2.288032)
		(width 0.089408)
		(layer "In9.Cu")
		(net "SPA_MID_DBG_RX_R")
	)
	(segment
		(start 357.265732 -29.111194)
		(end 356.6668 -29.710126)
		(width 0.089408)
		(layer "In9.Cu")
		(net "SPA_MID_DBG_RX_R")
	)
	(segment
		(start 371.804692 -5.881624)
		(end 369.40363 -8.282686)
		(width 0.089408)
		(layer "In11.Cu")
		(net "SPA_MID_DBG_RX_R")
	)
	(segment
		(start 390.947402 -4.628896)
		(end 384.224784 -4.628896)
		(width 0.089408)
		(layer "In11.Cu")
		(net "SPA_MID_DBG_RX_R")
	)
	(segment
		(start 392.458194 -6.139688)
		(end 390.947402 -4.628896)
		(width 0.089408)
		(layer "In11.Cu")
		(net "SPA_MID_DBG_RX_R")
	)
	(segment
		(start 382.972056 -5.881624)
		(end 371.804692 -5.881624)
		(width 0.089408)
		(layer "In11.Cu")
		(net "SPA_MID_DBG_RX_R")
	)
	(segment
		(start 384.224784 -4.628896)
		(end 382.972056 -5.881624)
		(width 0.089408)
		(layer "In11.Cu")
		(net "SPA_MID_DBG_RX_R")
	)
	(segment
		(start 361.40898 -25.53462)
		(end 356.6668 -30.2768)
		(width 0.089408)
		(layer "In11.Cu")
		(net "SPA_MID_DBG_RX_R")
	)
	(segment
		(start 361.40898 -17.508474)
		(end 361.40898 -25.53462)
		(width 0.089408)
		(layer "In11.Cu")
		(net "SPA_MID_DBG_RX_R")
	)
	(segment
		(start 369.40363 -8.282686)
		(end 369.40363 -9.513824)
		(width 0.089408)
		(layer "In11.Cu")
		(net "SPA_MID_DBG_RX_R")
	)
	(segment
		(start 369.40363 -9.513824)
		(end 361.40898 -17.508474)
		(width 0.089408)
		(layer "In11.Cu")
		(net "SPA_MID_DBG_RX_R")
	)
	(segment
		(start 487.970576 -30.795976)
		(end 488.321604 -31.147004)
		(width 0.10795)
		(layer "F.Cu")
		(net "SP2_BMC_CM_UART_TX_R1")
	)
	(segment
		(start 488.4674 -31.2928)
		(end 488.321604 -31.147004)
		(width 0.10795)
		(layer "F.Cu")
		(net "SP2_BMC_CM_UART_TX_R1")
	)
	(segment
		(start 489.211112 -30.936438)
		(end 488.85475 -31.2928)
		(width 0.10795)
		(layer "F.Cu")
		(net "SP2_BMC_CM_UART_TX_R1")
	)
	(segment
		(start 489.430568 -30.785562)
		(end 489.279692 -30.936438)
		(width 0.10795)
		(layer "F.Cu")
		(net "SP2_BMC_CM_UART_TX_R1")
	)
	(segment
		(start 487.970576 -30.186376)
		(end 487.970576 -30.795976)
		(width 0.10795)
		(layer "F.Cu")
		(net "SP2_BMC_CM_UART_TX_R1")
	)
	(segment
		(start 489.279692 -30.936438)
		(end 489.211112 -30.936438)
		(width 0.10795)
		(layer "F.Cu")
		(net "SP2_BMC_CM_UART_TX_R1")
	)
	(segment
		(start 488.85475 -31.2928)
		(end 488.4674 -31.2928)
		(width 0.10795)
		(layer "F.Cu")
		(net "SP2_BMC_CM_UART_TX_R1")
	)
	(via
		(at 489.430568 -30.785562)
		(size 0.508)
		(drill 0.254)
		(layers "F.Cu" "B.Cu")
		(net "SP2_BMC_CM_UART_TX_R1")
	)
	(via
		(at 488.321604 -31.147004)
		(size 0.762)
		(drill 0.381)
		(layers "F.Cu" "B.Cu")
		(net "SP2_BMC_CM_UART_TX_R1")
	)
	(segment
		(start 489.430568 -30.785562)
		(end 490.195362 -30.785562)
		(width 0.10795)
		(layer "B.Cu")
		(net "SP2_BMC_CM_UART_TX_R1")
	)
	(segment
		(start 490.195362 -30.785562)
		(end 490.6264 -31.2166)
		(width 0.10795)
		(layer "B.Cu")
		(net "SP2_BMC_CM_UART_TX_R1")
	)
	(segment
		(start 492.2012 -34.1884)
		(end 499.413276 -34.1884)
		(width 0.10795)
		(layer "B.Cu")
		(net "SP2_BMC_CM_UART_TX_R1")
	)
	(segment
		(start 490.6264 -32.6136)
		(end 492.2012 -34.1884)
		(width 0.10795)
		(layer "B.Cu")
		(net "SP2_BMC_CM_UART_TX_R1")
	)
	(segment
		(start 499.413276 -34.1884)
		(end 499.521226 -34.29635)
		(width 0.10795)
		(layer "B.Cu")
		(net "SP2_BMC_CM_UART_TX_R1")
	)
	(segment
		(start 499.521226 -34.29635)
		(end 499.521226 -34.715704)
		(width 0.10795)
		(layer "B.Cu")
		(net "SP2_BMC_CM_UART_TX_R1")
	)
	(segment
		(start 490.6264 -31.2166)
		(end 490.6264 -32.6136)
		(width 0.10795)
		(layer "B.Cu")
		(net "SP2_BMC_CM_UART_TX_R1")
	)
	(segment
		(start 498.632226 -35.263836)
		(end 498.437916 -35.458146)
		(width 0.10795)
		(layer "B.Cu")
		(net "SP2_BMC_CM_UART_TX_R")
	)
	(segment
		(start 498.632226 -34.715704)
		(end 498.632226 -35.263836)
		(width 0.10795)
		(layer "B.Cu")
		(net "SP2_BMC_CM_UART_TX_R")
	)
	(segment
		(start 498.437916 -35.458146)
		(end 496.919504 -35.458146)
		(width 0.10795)
		(layer "B.Cu")
		(net "SP2_BMC_CM_UART_TX_R")
	)
	(segment
		(start 485.4702 -29.3878)
		(end 485.4702 -28.50896)
		(width 0.10795)
		(layer "F.Cu")
		(net "SP2_BMC_CM_UART_RX_R1")
	)
	(segment
		(start 486.2068 -30.1244)
		(end 485.4702 -29.3878)
		(width 0.10795)
		(layer "F.Cu")
		(net "SP2_BMC_CM_UART_RX_R1")
	)
	(segment
		(start 486.687876 -28.116784)
		(end 485.887776 -28.116784)
		(width 0.10795)
		(layer "F.Cu")
		(net "SP2_BMC_CM_UART_RX_R1")
	)
	(segment
		(start 486.626916 -30.1244)
		(end 486.2068 -30.1244)
		(width 0.10795)
		(layer "F.Cu")
		(net "SP2_BMC_CM_UART_RX_R1")
	)
	(segment
		(start 485.887776 -28.116784)
		(end 485.875076 -28.104084)
		(width 0.10795)
		(layer "F.Cu")
		(net "SP2_BMC_CM_UART_RX_R1")
	)
	(segment
		(start 485.4702 -28.50896)
		(end 485.875076 -28.104084)
		(width 0.10795)
		(layer "F.Cu")
		(net "SP2_BMC_CM_UART_RX_R1")
	)
	(via
		(at 486.626916 -30.1244)
		(size 0.762)
		(drill 0.381)
		(layers "F.Cu" "B.Cu")
		(net "SP2_BMC_CM_UART_RX_R1")
	)
	(segment
		(start 486.915714 -27.227784)
		(end 486.687876 -27.227784)
		(width 0.10795)
		(layer "F.Cu")
		(net "SP2_BMC_CM_UART_RX_R")
	)
	(segment
		(start 487.176318 -27.488388)
		(end 486.915714 -27.227784)
		(width 0.10795)
		(layer "F.Cu")
		(net "SP2_BMC_CM_UART_RX_R")
	)
	(segment
		(start 486.85831 -32.27451)
		(end 486.85831 -31.074868)
		(width 0.10795)
		(layer "F.Cu")
		(net "SP2_BMC_CM_UART_RX_R")
	)
	(segment
		(start 486.85831 -31.074868)
		(end 487.176318 -30.75686)
		(width 0.10795)
		(layer "F.Cu")
		(net "SP2_BMC_CM_UART_RX_R")
	)
	(segment
		(start 487.176318 -30.75686)
		(end 487.176318 -27.488388)
		(width 0.10795)
		(layer "F.Cu")
		(net "SP2_BMC_CM_UART_RX_R")
	)
	(segment
		(start 487.223054 -32.639254)
		(end 486.85831 -32.27451)
		(width 0.10795)
		(layer "F.Cu")
		(net "SP2_BMC_CM_UART_RX_R")
	)
	(segment
		(start 487.604308 -32.639254)
		(end 487.223054 -32.639254)
		(width 0.10795)
		(layer "F.Cu")
		(net "SP2_BMC_CM_UART_RX_R")
	)
	(via
		(at 486.7656 -32.4866)
		(size 0.6604)
		(drill 0.3302)
		(layers "F.Cu" "B.Cu")
		(net "SP2_BMC_CM_UART_RX_R")
	)
	(via
		(at 487.604308 -32.639254)
		(size 0.508)
		(drill 0.254)
		(layers "F.Cu" "B.Cu")
		(net "SP2_BMC_CM_UART_RX_R")
	)
	(segment
		(start 489.40339 -35.445192)
		(end 490.203998 -35.445192)
		(width 0.10795)
		(layer "B.Cu")
		(net "SP2_BMC_CM_UART_RX_R")
	)
	(segment
		(start 486.8672 -32.385)
		(end 487.350054 -32.385)
		(width 0.10795)
		(layer "B.Cu")
		(net "SP2_BMC_CM_UART_RX_R")
	)
	(segment
		(start 487.2228 -34.9504)
		(end 487.299 -35.0266)
		(width 0.10795)
		(layer "B.Cu")
		(net "SP2_BMC_CM_UART_RX_R")
	)
	(segment
		(start 486.7656 -32.4866)
		(end 486.8672 -32.385)
		(width 0.10795)
		(layer "B.Cu")
		(net "SP2_BMC_CM_UART_RX_R")
	)
	(segment
		(start 486.8418 -34.0868)
		(end 487.053128 -34.298128)
		(width 0.10795)
		(layer "B.Cu")
		(net "SP2_BMC_CM_UART_RX_R")
	)
	(segment
		(start 486.7656 -32.4866)
		(end 486.8418 -32.5628)
		(width 0.10795)
		(layer "B.Cu")
		(net "SP2_BMC_CM_UART_RX_R")
	)
	(segment
		(start 487.053128 -34.31159)
		(end 487.2228 -34.481262)
		(width 0.10795)
		(layer "B.Cu")
		(net "SP2_BMC_CM_UART_RX_R")
	)
	(segment
		(start 488.984798 -35.0266)
		(end 489.40339 -35.445192)
		(width 0.10795)
		(layer "B.Cu")
		(net "SP2_BMC_CM_UART_RX_R")
	)
	(segment
		(start 487.350054 -32.385)
		(end 487.604308 -32.639254)
		(width 0.10795)
		(layer "B.Cu")
		(net "SP2_BMC_CM_UART_RX_R")
	)
	(segment
		(start 487.2228 -34.481262)
		(end 487.2228 -34.9504)
		(width 0.10795)
		(layer "B.Cu")
		(net "SP2_BMC_CM_UART_RX_R")
	)
	(segment
		(start 487.053128 -34.298128)
		(end 487.053128 -34.31159)
		(width 0.10795)
		(layer "B.Cu")
		(net "SP2_BMC_CM_UART_RX_R")
	)
	(segment
		(start 487.299 -35.0266)
		(end 488.984798 -35.0266)
		(width 0.10795)
		(layer "B.Cu")
		(net "SP2_BMC_CM_UART_RX_R")
	)
	(segment
		(start 486.8418 -32.5628)
		(end 486.8418 -34.0868)
		(width 0.10795)
		(layer "B.Cu")
		(net "SP2_BMC_CM_UART_RX_R")
	)
	(segment
		(start 393.0142 -89.65565)
		(end 393.159488 -89.800938)
		(width 0.10795)
		(layer "F.Cu")
		(net "FM_FLASH_ATTACH_CFG_STRAP")
	)
	(segment
		(start 392.557 -87.3125)
		(end 392.165078 -86.920578)
		(width 0.10795)
		(layer "F.Cu")
		(net "FM_FLASH_ATTACH_CFG_STRAP")
	)
	(segment
		(start 392.557 -87.3125)
		(end 392.684 -87.3125)
		(width 0.10795)
		(layer "F.Cu")
		(net "FM_FLASH_ATTACH_CFG_STRAP")
	)
	(segment
		(start 393.159488 -93.3704)
		(end 392.98499 -93.544898)
		(width 0.0889)
		(layer "F.Cu")
		(net "FM_FLASH_ATTACH_CFG_STRAP")
	)
	(segment
		(start 393.0142 -87.6427)
		(end 393.0142 -89.067132)
		(width 0.10795)
		(layer "F.Cu")
		(net "FM_FLASH_ATTACH_CFG_STRAP")
	)
	(segment
		(start 393.159488 -89.800938)
		(end 393.159488 -93.3704)
		(width 0.0889)
		(layer "F.Cu")
		(net "FM_FLASH_ATTACH_CFG_STRAP")
	)
	(segment
		(start 392.684 -87.3125)
		(end 393.0142 -87.6427)
		(width 0.10795)
		(layer "F.Cu")
		(net "FM_FLASH_ATTACH_CFG_STRAP")
	)
	(segment
		(start 392.165078 -86.920578)
		(end 392.165078 -86.569042)
		(width 0.10795)
		(layer "F.Cu")
		(net "FM_FLASH_ATTACH_CFG_STRAP")
	)
	(segment
		(start 393.0142 -89.067132)
		(end 393.0142 -89.65565)
		(width 0.10795)
		(layer "F.Cu")
		(net "FM_FLASH_ATTACH_CFG_STRAP")
	)
	(via
		(at 393.0142 -89.067132)
		(size 0.508)
		(drill 0.254)
		(layers "F.Cu" "B.Cu")
		(net "FM_FLASH_ATTACH_CFG_STRAP")
	)
	(via
		(at 359.66019 -44.396914)
		(size 0.6604)
		(drill 0.3302)
		(layers "F.Cu" "B.Cu")
		(net "FM_CPU_ERR1_LVT3_K_N")
	)
	(segment
		(start 362.270294 -43.131486)
		(end 361.508294 -43.131486)
		(width 0.10795)
		(layer "B.Cu")
		(net "FM_CPU_ERR1_LVT3_K_N")
	)
	(segment
		(start 361.444794 -44.294298)
		(end 361.342178 -44.396914)
		(width 0.10795)
		(layer "B.Cu")
		(net "FM_CPU_ERR1_LVT3_K_N")
	)
	(segment
		(start 361.508294 -43.131486)
		(end 361.444794 -43.194986)
		(width 0.10795)
		(layer "B.Cu")
		(net "FM_CPU_ERR1_LVT3_K_N")
	)
	(segment
		(start 361.444794 -43.956986)
		(end 361.444794 -44.294298)
		(width 0.10795)
		(layer "B.Cu")
		(net "FM_CPU_ERR1_LVT3_K_N")
	)
	(segment
		(start 361.342178 -44.396914)
		(end 359.66019 -44.396914)
		(width 0.10795)
		(layer "B.Cu")
		(net "FM_CPU_ERR1_LVT3_K_N")
	)
	(segment
		(start 361.444794 -43.956986)
		(end 361.444794 -43.194986)
		(width 0.10795)
		(layer "B.Cu")
		(net "FM_CPU_ERR1_LVT3_K_N")
	)
	(segment
		(start 363.865922 -74.026522)
		(end 364.501684 -74.662284)
		(width 0.10795)
		(layer "F.Cu")
		(net "PU_FAB2_MARKER_CPLD")
	)
	(segment
		(start 363.249718 -73.022206)
		(end 363.249718 -73.410318)
		(width 0.10795)
		(layer "F.Cu")
		(net "PU_FAB2_MARKER_CPLD")
	)
	(segment
		(start 365.9124 -74.662284)
		(end 366.745012 -75.494896)
		(width 0.10795)
		(layer "F.Cu")
		(net "PU_FAB2_MARKER_CPLD")
	)
	(segment
		(start 363.249718 -73.410318)
		(end 363.865922 -74.026522)
		(width 0.10795)
		(layer "F.Cu")
		(net "PU_FAB2_MARKER_CPLD")
	)
	(segment
		(start 364.501684 -74.662284)
		(end 365.9124 -74.662284)
		(width 0.10795)
		(layer "F.Cu")
		(net "PU_FAB2_MARKER_CPLD")
	)
	(via
		(at 363.865922 -74.026522)
		(size 0.508)
		(drill 0.254)
		(layers "F.Cu" "B.Cu")
		(net "PU_FAB2_MARKER_CPLD")
	)
	(segment
		(start 466.988398 2.612644)
		(end 466.947504 2.406904)
		(width 0.10795)
		(layer "F.Cu")
		(net "FM_BATTERY_SENSE_EN_N")
	)
	(segment
		(start 411.89021 -39.334694)
		(end 411.89021 -39.28999)
		(width 0.10795)
		(layer "F.Cu")
		(net "FM_BATTERY_SENSE_EN_N")
	)
	(segment
		(start 466.947504 2.406904)
		(end 466.70976 2.16916)
		(width 0.10795)
		(layer "F.Cu")
		(net "FM_BATTERY_SENSE_EN_N")
	)
	(segment
		(start 466.989668 2.7178)
		(end 466.988398 2.71653)
		(width 0.10795)
		(layer "F.Cu")
		(net "FM_BATTERY_SENSE_EN_N")
	)
	(segment
		(start 466.988398 2.71653)
		(end 466.988398 2.612644)
		(width 0.10795)
		(layer "F.Cu")
		(net "FM_BATTERY_SENSE_EN_N")
	)
	(segment
		(start 466.6234 3.9878)
		(end 466.6234 3.501898)
		(width 0.10795)
		(layer "F.Cu")
		(net "FM_BATTERY_SENSE_EN_N")
	)
	(segment
		(start 466.989668 3.13563)
		(end 466.989668 2.7178)
		(width 0.10795)
		(layer "F.Cu")
		(net "FM_BATTERY_SENSE_EN_N")
	)
	(segment
		(start 466.6234 3.9878)
		(end 466.6234 4.699)
		(width 0.10795)
		(layer "F.Cu")
		(net "FM_BATTERY_SENSE_EN_N")
	)
	(segment
		(start 466.70976 2.16916)
		(end 466.311996 2.16916)
		(width 0.10795)
		(layer "F.Cu")
		(net "FM_BATTERY_SENSE_EN_N")
	)
	(segment
		(start 466.6234 4.699)
		(end 466.5218 4.8006)
		(width 0.10795)
		(layer "F.Cu")
		(net "FM_BATTERY_SENSE_EN_N")
	)
	(segment
		(start 411.89021 -39.28999)
		(end 412.2928 -38.8874)
		(width 0.10795)
		(layer "F.Cu")
		(net "FM_BATTERY_SENSE_EN_N")
	)
	(segment
		(start 466.6234 3.501898)
		(end 466.989668 3.13563)
		(width 0.10795)
		(layer "F.Cu")
		(net "FM_BATTERY_SENSE_EN_N")
	)
	(via
		(at 479.0567 -38.463474)
		(size 0.508)
		(drill 0.254)
		(layers "F.Cu" "B.Cu")
		(net "FM_BATTERY_SENSE_EN_N")
	)
	(via
		(at 388.480046 -34.901632)
		(size 0.508)
		(drill 0.254)
		(layers "F.Cu" "B.Cu")
		(net "FM_BATTERY_SENSE_EN_N")
	)
	(via
		(at 466.580728 -43.303444)
		(size 0.508)
		(drill 0.254)
		(layers "F.Cu" "B.Cu")
		(net "FM_BATTERY_SENSE_EN_N")
	)
	(via
		(at 467.558882 -43.008804)
		(size 0.6604)
		(drill 0.3302)
		(layers "F.Cu" "B.Cu")
		(net "FM_BATTERY_SENSE_EN_N")
	)
	(via
		(at 466.5218 4.8006)
		(size 0.508)
		(drill 0.254)
		(layers "F.Cu" "B.Cu")
		(net "FM_BATTERY_SENSE_EN_N")
	)
	(via
		(at 412.2928 -38.8874)
		(size 0.4572)
		(drill 0.2032)
		(layers "F.Cu" "B.Cu")
		(net "FM_BATTERY_SENSE_EN_N")
	)
	(segment
		(start 466.580728 -43.303444)
		(end 467.264242 -43.303444)
		(width 0.10795)
		(layer "B.Cu")
		(net "FM_BATTERY_SENSE_EN_N")
	)
	(segment
		(start 387.689598 -34.655506)
		(end 388.23392 -34.655506)
		(width 0.10795)
		(layer "B.Cu")
		(net "FM_BATTERY_SENSE_EN_N")
	)
	(segment
		(start 388.23392 -34.655506)
		(end 388.480046 -34.901632)
		(width 0.10795)
		(layer "B.Cu")
		(net "FM_BATTERY_SENSE_EN_N")
	)
	(segment
		(start 467.264242 -43.303444)
		(end 467.558882 -43.008804)
		(width 0.10795)
		(layer "B.Cu")
		(net "FM_BATTERY_SENSE_EN_N")
	)
	(segment
		(start 472.567 -42.251376)
		(end 472.567 -39.974012)
		(width 0.089408)
		(layer "In2.Cu")
		(net "FM_BATTERY_SENSE_EN_N")
	)
	(segment
		(start 472.567 -39.974012)
		(end 472.942412 -39.5986)
		(width 0.089408)
		(layer "In2.Cu")
		(net "FM_BATTERY_SENSE_EN_N")
	)
	(segment
		(start 477.455992 -38.96868)
		(end 477.455992 -38.759638)
		(width 0.089408)
		(layer "In2.Cu")
		(net "FM_BATTERY_SENSE_EN_N")
	)
	(segment
		(start 469.711024 -43.927014)
		(end 470.400888 -43.23715)
		(width 0.089408)
		(layer "In2.Cu")
		(net "FM_BATTERY_SENSE_EN_N")
	)
	(segment
		(start 470.400888 -43.23715)
		(end 471.581226 -43.23715)
		(width 0.089408)
		(layer "In2.Cu")
		(net "FM_BATTERY_SENSE_EN_N")
	)
	(segment
		(start 471.581226 -43.23715)
		(end 472.567 -42.251376)
		(width 0.089408)
		(layer "In2.Cu")
		(net "FM_BATTERY_SENSE_EN_N")
	)
	(segment
		(start 475.730824 -39.279576)
		(end 477.145096 -39.279576)
		(width 0.089408)
		(layer "In2.Cu")
		(net "FM_BATTERY_SENSE_EN_N")
	)
	(segment
		(start 477.145096 -39.279576)
		(end 477.455992 -38.96868)
		(width 0.089408)
		(layer "In2.Cu")
		(net "FM_BATTERY_SENSE_EN_N")
	)
	(segment
		(start 477.752156 -38.463474)
		(end 479.0567 -38.463474)
		(width 0.089408)
		(layer "In2.Cu")
		(net "FM_BATTERY_SENSE_EN_N")
	)
	(segment
		(start 475.4118 -39.5986)
		(end 475.730824 -39.279576)
		(width 0.089408)
		(layer "In2.Cu")
		(net "FM_BATTERY_SENSE_EN_N")
	)
	(segment
		(start 472.942412 -39.5986)
		(end 475.4118 -39.5986)
		(width 0.089408)
		(layer "In2.Cu")
		(net "FM_BATTERY_SENSE_EN_N")
	)
	(segment
		(start 467.204298 -43.927014)
		(end 469.711024 -43.927014)
		(width 0.089408)
		(layer "In2.Cu")
		(net "FM_BATTERY_SENSE_EN_N")
	)
	(segment
		(start 466.580728 -43.303444)
		(end 467.204298 -43.927014)
		(width 0.089408)
		(layer "In2.Cu")
		(net "FM_BATTERY_SENSE_EN_N")
	)
	(segment
		(start 477.455992 -38.759638)
		(end 477.752156 -38.463474)
		(width 0.089408)
		(layer "In2.Cu")
		(net "FM_BATTERY_SENSE_EN_N")
	)
	(segment
		(start 403.32279 -35.150044)
		(end 405.070056 -36.89731)
		(width 0.089408)
		(layer "In4.Cu")
		(net "FM_BATTERY_SENSE_EN_N")
	)
	(segment
		(start 388.480046 -34.90976)
		(end 388.660386 -35.0901)
		(width 0.089408)
		(layer "In4.Cu")
		(net "FM_BATTERY_SENSE_EN_N")
	)
	(segment
		(start 411.06725 -36.700968)
		(end 411.31617 -36.949888)
		(width 0.089408)
		(layer "In4.Cu")
		(net "FM_BATTERY_SENSE_EN_N")
	)
	(segment
		(start 405.070056 -36.89731)
		(end 408.122628 -36.89731)
		(width 0.089408)
		(layer "In4.Cu")
		(net "FM_BATTERY_SENSE_EN_N")
	)
	(segment
		(start 394.175996 -35.967416)
		(end 394.929614 -36.721034)
		(width 0.089408)
		(layer "In4.Cu")
		(net "FM_BATTERY_SENSE_EN_N")
	)
	(segment
		(start 399.734532 -33.279334)
		(end 401.031202 -34.576004)
		(width 0.089408)
		(layer "In4.Cu")
		(net "FM_BATTERY_SENSE_EN_N")
	)
	(segment
		(start 390.971024 -33.46323)
		(end 392.75639 -33.46323)
		(width 0.089408)
		(layer "In4.Cu")
		(net "FM_BATTERY_SENSE_EN_N")
	)
	(segment
		(start 411.31617 -36.949888)
		(end 411.678882 -36.949888)
		(width 0.089408)
		(layer "In4.Cu")
		(net "FM_BATTERY_SENSE_EN_N")
	)
	(segment
		(start 408.948382 -36.146232)
		(end 410.820362 -36.146232)
		(width 0.089408)
		(layer "In4.Cu")
		(net "FM_BATTERY_SENSE_EN_N")
	)
	(segment
		(start 408.445462 -36.909248)
		(end 408.4574 -36.89731)
		(width 0.089408)
		(layer "In4.Cu")
		(net "FM_BATTERY_SENSE_EN_N")
	)
	(segment
		(start 394.929614 -36.721034)
		(end 396.129002 -36.721034)
		(width 0.089408)
		(layer "In4.Cu")
		(net "FM_BATTERY_SENSE_EN_N")
	)
	(segment
		(start 411.06725 -36.390072)
		(end 411.06725 -36.700968)
		(width 0.089408)
		(layer "In4.Cu")
		(net "FM_BATTERY_SENSE_EN_N")
	)
	(segment
		(start 412.2928 -38.070536)
		(end 412.2928 -38.8874)
		(width 0.089408)
		(layer "In4.Cu")
		(net "FM_BATTERY_SENSE_EN_N")
	)
	(segment
		(start 408.72918 -36.660836)
		(end 408.72918 -36.365434)
		(width 0.089408)
		(layer "In4.Cu")
		(net "FM_BATTERY_SENSE_EN_N")
	)
	(segment
		(start 401.031202 -34.576004)
		(end 401.420838 -34.576004)
		(width 0.089408)
		(layer "In4.Cu")
		(net "FM_BATTERY_SENSE_EN_N")
	)
	(segment
		(start 397.189706 -33.66643)
		(end 397.576802 -33.279334)
		(width 0.089408)
		(layer "In4.Cu")
		(net "FM_BATTERY_SENSE_EN_N")
	)
	(segment
		(start 408.492706 -36.89731)
		(end 408.72918 -36.660836)
		(width 0.089408)
		(layer "In4.Cu")
		(net "FM_BATTERY_SENSE_EN_N")
	)
	(segment
		(start 410.848048 -36.17087)
		(end 411.06725 -36.390072)
		(width 0.089408)
		(layer "In4.Cu")
		(net "FM_BATTERY_SENSE_EN_N")
	)
	(segment
		(start 410.845 -36.17087)
		(end 410.848048 -36.17087)
		(width 0.089408)
		(layer "In4.Cu")
		(net "FM_BATTERY_SENSE_EN_N")
	)
	(segment
		(start 408.4574 -36.89731)
		(end 408.492706 -36.89731)
		(width 0.089408)
		(layer "In4.Cu")
		(net "FM_BATTERY_SENSE_EN_N")
	)
	(segment
		(start 397.576802 -33.279334)
		(end 399.734532 -33.279334)
		(width 0.089408)
		(layer "In4.Cu")
		(net "FM_BATTERY_SENSE_EN_N")
	)
	(segment
		(start 394.175996 -34.882836)
		(end 394.175996 -35.967416)
		(width 0.089408)
		(layer "In4.Cu")
		(net "FM_BATTERY_SENSE_EN_N")
	)
	(segment
		(start 411.91561 -37.693346)
		(end 412.2928 -38.070536)
		(width 0.089408)
		(layer "In4.Cu")
		(net "FM_BATTERY_SENSE_EN_N")
	)
	(segment
		(start 408.134566 -36.909248)
		(end 408.445462 -36.909248)
		(width 0.089408)
		(layer "In4.Cu")
		(net "FM_BATTERY_SENSE_EN_N")
	)
	(segment
		(start 396.129002 -36.721034)
		(end 397.189706 -35.66033)
		(width 0.089408)
		(layer "In4.Cu")
		(net "FM_BATTERY_SENSE_EN_N")
	)
	(segment
		(start 401.994878 -35.150044)
		(end 403.32279 -35.150044)
		(width 0.089408)
		(layer "In4.Cu")
		(net "FM_BATTERY_SENSE_EN_N")
	)
	(segment
		(start 410.820362 -36.146232)
		(end 410.845 -36.17087)
		(width 0.089408)
		(layer "In4.Cu")
		(net "FM_BATTERY_SENSE_EN_N")
	)
	(segment
		(start 388.660386 -35.0901)
		(end 389.344154 -35.0901)
		(width 0.089408)
		(layer "In4.Cu")
		(net "FM_BATTERY_SENSE_EN_N")
	)
	(segment
		(start 389.344154 -35.0901)
		(end 390.971024 -33.46323)
		(width 0.089408)
		(layer "In4.Cu")
		(net "FM_BATTERY_SENSE_EN_N")
	)
	(segment
		(start 397.189706 -35.66033)
		(end 397.189706 -33.66643)
		(width 0.089408)
		(layer "In4.Cu")
		(net "FM_BATTERY_SENSE_EN_N")
	)
	(segment
		(start 401.420838 -34.576004)
		(end 401.994878 -35.150044)
		(width 0.089408)
		(layer "In4.Cu")
		(net "FM_BATTERY_SENSE_EN_N")
	)
	(segment
		(start 408.122628 -36.89731)
		(end 408.134566 -36.909248)
		(width 0.089408)
		(layer "In4.Cu")
		(net "FM_BATTERY_SENSE_EN_N")
	)
	(segment
		(start 411.678882 -36.949888)
		(end 411.91561 -37.186616)
		(width 0.089408)
		(layer "In4.Cu")
		(net "FM_BATTERY_SENSE_EN_N")
	)
	(segment
		(start 411.91561 -37.186616)
		(end 411.91561 -37.693346)
		(width 0.089408)
		(layer "In4.Cu")
		(net "FM_BATTERY_SENSE_EN_N")
	)
	(segment
		(start 388.480046 -34.901632)
		(end 388.480046 -34.90976)
		(width 0.089408)
		(layer "In4.Cu")
		(net "FM_BATTERY_SENSE_EN_N")
	)
	(segment
		(start 408.72918 -36.365434)
		(end 408.948382 -36.146232)
		(width 0.089408)
		(layer "In4.Cu")
		(net "FM_BATTERY_SENSE_EN_N")
	)
	(segment
		(start 392.75639 -33.46323)
		(end 394.175996 -34.882836)
		(width 0.089408)
		(layer "In4.Cu")
		(net "FM_BATTERY_SENSE_EN_N")
	)
	(segment
		(start 456.328018 -39.574978)
		(end 454.958196 -38.205156)
		(width 0.089408)
		(layer "In11.Cu")
		(net "FM_BATTERY_SENSE_EN_N")
	)
	(segment
		(start 447.72834 -39.796974)
		(end 444.767462 -39.796974)
		(width 0.089408)
		(layer "In11.Cu")
		(net "FM_BATTERY_SENSE_EN_N")
	)
	(segment
		(start 418.856668 -38.516052)
		(end 418.545772 -38.516052)
		(width 0.089408)
		(layer "In11.Cu")
		(net "FM_BATTERY_SENSE_EN_N")
	)
	(segment
		(start 475.07144 -12.781788)
		(end 475.07144 -17.539716)
		(width 0.089408)
		(layer "In11.Cu")
		(net "FM_BATTERY_SENSE_EN_N")
	)
	(segment
		(start 434.401214 -40.068754)
		(end 434.284882 -39.952422)
		(width 0.089408)
		(layer "In11.Cu")
		(net "FM_BATTERY_SENSE_EN_N")
	)
	(segment
		(start 454.958196 -38.205156)
		(end 449.320158 -38.205156)
		(width 0.089408)
		(layer "In11.Cu")
		(net "FM_BATTERY_SENSE_EN_N")
	)
	(segment
		(start 478.205292 -37.604192)
		(end 479.064574 -38.463474)
		(width 0.089408)
		(layer "In11.Cu")
		(net "FM_BATTERY_SENSE_EN_N")
	)
	(segment
		(start 476.302578 -10.505694)
		(end 476.302578 -11.55065)
		(width 0.089408)
		(layer "In11.Cu")
		(net "FM_BATTERY_SENSE_EN_N")
	)
	(segment
		(start 476.145606 -25.27046)
		(end 476.50019 -25.625044)
		(width 0.089408)
		(layer "In11.Cu")
		(net "FM_BATTERY_SENSE_EN_N")
	)
	(segment
		(start 444.16853 -40.068754)
		(end 434.401214 -40.068754)
		(width 0.089408)
		(layer "In11.Cu")
		(net "FM_BATTERY_SENSE_EN_N")
	)
	(segment
		(start 477.037908 -28.70327)
		(end 477.21012 -28.875482)
		(width 0.089408)
		(layer "In11.Cu")
		(net "FM_BATTERY_SENSE_EN_N")
	)
	(segment
		(start 476.302324 -8.541512)
		(end 476.302324 -10.50544)
		(width 0.089408)
		(layer "In11.Cu")
		(net "FM_BATTERY_SENSE_EN_N")
	)
	(segment
		(start 467.077552 -42.802556)
		(end 467.077552 -41.672002)
		(width 0.089408)
		(layer "In11.Cu")
		(net "FM_BATTERY_SENSE_EN_N")
	)
	(segment
		(start 470.22258 -1.83642)
		(end 470.452196 -2.066036)
		(width 0.089408)
		(layer "In11.Cu")
		(net "FM_BATTERY_SENSE_EN_N")
	)
	(segment
		(start 467.2584 0.540258)
		(end 469.635078 -1.83642)
		(width 0.089408)
		(layer "In11.Cu")
		(net "FM_BATTERY_SENSE_EN_N")
	)
	(segment
		(start 478.205292 -33.788858)
		(end 478.205292 -37.604192)
		(width 0.089408)
		(layer "In11.Cu")
		(net "FM_BATTERY_SENSE_EN_N")
	)
	(segment
		(start 476.302578 -11.55065)
		(end 475.07144 -12.781788)
		(width 0.089408)
		(layer "In11.Cu")
		(net "FM_BATTERY_SENSE_EN_N")
	)
	(segment
		(start 477.21012 -28.875482)
		(end 477.21012 -32.793686)
		(width 0.089408)
		(layer "In11.Cu")
		(net "FM_BATTERY_SENSE_EN_N")
	)
	(segment
		(start 461.105504 -38.916864)
		(end 458.891132 -38.916864)
		(width 0.089408)
		(layer "In11.Cu")
		(net "FM_BATTERY_SENSE_EN_N")
	)
	(segment
		(start 469.635078 -1.83642)
		(end 470.22258 -1.83642)
		(width 0.089408)
		(layer "In11.Cu")
		(net "FM_BATTERY_SENSE_EN_N")
	)
	(segment
		(start 466.576664 -43.303444)
		(end 467.077552 -42.802556)
		(width 0.089408)
		(layer "In11.Cu")
		(net "FM_BATTERY_SENSE_EN_N")
	)
	(segment
		(start 462.199482 -38.915086)
		(end 462.197704 -38.916864)
		(width 0.089408)
		(layer "In11.Cu")
		(net "FM_BATTERY_SENSE_EN_N")
	)
	(segment
		(start 444.302896 -39.934388)
		(end 444.16853 -40.068754)
		(width 0.089408)
		(layer "In11.Cu")
		(net "FM_BATTERY_SENSE_EN_N")
	)
	(segment
		(start 475.07144 -17.539716)
		(end 476.145606 -18.613882)
		(width 0.089408)
		(layer "In11.Cu")
		(net "FM_BATTERY_SENSE_EN_N")
	)
	(segment
		(start 476.763588 -8.080248)
		(end 476.302324 -8.541512)
		(width 0.089408)
		(layer "In11.Cu")
		(net "FM_BATTERY_SENSE_EN_N")
	)
	(segment
		(start 461.107282 -38.915086)
		(end 461.105504 -38.916864)
		(width 0.089408)
		(layer "In11.Cu")
		(net "FM_BATTERY_SENSE_EN_N")
	)
	(segment
		(start 444.767462 -39.796974)
		(end 444.630048 -39.934388)
		(width 0.089408)
		(layer "In11.Cu")
		(net "FM_BATTERY_SENSE_EN_N")
	)
	(segment
		(start 418.545772 -38.516052)
		(end 418.54247 -38.51275)
		(width 0.089408)
		(layer "In11.Cu")
		(net "FM_BATTERY_SENSE_EN_N")
	)
	(segment
		(start 472.134184 -2.066036)
		(end 474.189044 -4.120896)
		(width 0.089408)
		(layer "In11.Cu")
		(net "FM_BATTERY_SENSE_EN_N")
	)
	(segment
		(start 467.077552 -41.672002)
		(end 465.746338 -40.340788)
		(width 0.089408)
		(layer "In11.Cu")
		(net "FM_BATTERY_SENSE_EN_N")
	)
	(segment
		(start 461.597502 -38.915086)
		(end 461.107282 -38.915086)
		(width 0.089408)
		(layer "In11.Cu")
		(net "FM_BATTERY_SENSE_EN_N")
	)
	(segment
		(start 476.50019 -26.04389)
		(end 477.037908 -26.581608)
		(width 0.089408)
		(layer "In11.Cu")
		(net "FM_BATTERY_SENSE_EN_N")
	)
	(segment
		(start 458.233018 -39.574978)
		(end 456.328018 -39.574978)
		(width 0.089408)
		(layer "In11.Cu")
		(net "FM_BATTERY_SENSE_EN_N")
	)
	(segment
		(start 422.98366 -38.51275)
		(end 418.85997 -38.51275)
		(width 0.089408)
		(layer "In11.Cu")
		(net "FM_BATTERY_SENSE_EN_N")
	)
	(segment
		(start 476.302324 -10.50544)
		(end 476.302578 -10.505694)
		(width 0.089408)
		(layer "In11.Cu")
		(net "FM_BATTERY_SENSE_EN_N")
	)
	(segment
		(start 449.320158 -38.205156)
		(end 447.72834 -39.796974)
		(width 0.089408)
		(layer "In11.Cu")
		(net "FM_BATTERY_SENSE_EN_N")
	)
	(segment
		(start 466.5218 4.8006)
		(end 467.2584 4.064)
		(width 0.089408)
		(layer "In11.Cu")
		(net "FM_BATTERY_SENSE_EN_N")
	)
	(segment
		(start 476.50019 -25.625044)
		(end 476.50019 -26.04389)
		(width 0.089408)
		(layer "In11.Cu")
		(net "FM_BATTERY_SENSE_EN_N")
	)
	(segment
		(start 418.54247 -38.51275)
		(end 412.66745 -38.51275)
		(width 0.089408)
		(layer "In11.Cu")
		(net "FM_BATTERY_SENSE_EN_N")
	)
	(segment
		(start 418.85997 -38.51275)
		(end 418.856668 -38.516052)
		(width 0.089408)
		(layer "In11.Cu")
		(net "FM_BATTERY_SENSE_EN_N")
	)
	(segment
		(start 476.145606 -18.613882)
		(end 476.145606 -25.27046)
		(width 0.089408)
		(layer "In11.Cu")
		(net "FM_BATTERY_SENSE_EN_N")
	)
	(segment
		(start 465.746338 -40.340788)
		(end 464.245452 -40.340788)
		(width 0.089408)
		(layer "In11.Cu")
		(net "FM_BATTERY_SENSE_EN_N")
	)
	(segment
		(start 424.19651 -38.903402)
		(end 423.374312 -38.903402)
		(width 0.089408)
		(layer "In11.Cu")
		(net "FM_BATTERY_SENSE_EN_N")
	)
	(segment
		(start 479.064574 -38.463474)
		(end 479.0567 -38.463474)
		(width 0.089408)
		(layer "In11.Cu")
		(net "FM_BATTERY_SENSE_EN_N")
	)
	(segment
		(start 462.821528 -38.916864)
		(end 462.69148 -38.916864)
		(width 0.089408)
		(layer "In11.Cu")
		(net "FM_BATTERY_SENSE_EN_N")
	)
	(segment
		(start 474.189044 -4.120896)
		(end 474.327982 -4.120896)
		(width 0.089408)
		(layer "In11.Cu")
		(net "FM_BATTERY_SENSE_EN_N")
	)
	(segment
		(start 462.69148 -38.916864)
		(end 462.689702 -38.915086)
		(width 0.089408)
		(layer "In11.Cu")
		(net "FM_BATTERY_SENSE_EN_N")
	)
	(segment
		(start 464.245452 -40.340788)
		(end 462.821528 -38.916864)
		(width 0.089408)
		(layer "In11.Cu")
		(net "FM_BATTERY_SENSE_EN_N")
	)
	(segment
		(start 462.197704 -38.916864)
		(end 461.59928 -38.916864)
		(width 0.089408)
		(layer "In11.Cu")
		(net "FM_BATTERY_SENSE_EN_N")
	)
	(segment
		(start 458.891132 -38.916864)
		(end 458.233018 -39.574978)
		(width 0.089408)
		(layer "In11.Cu")
		(net "FM_BATTERY_SENSE_EN_N")
	)
	(segment
		(start 475.794832 -5.97535)
		(end 476.763588 -6.944106)
		(width 0.089408)
		(layer "In11.Cu")
		(net "FM_BATTERY_SENSE_EN_N")
	)
	(segment
		(start 434.284882 -39.952422)
		(end 425.24553 -39.952422)
		(width 0.089408)
		(layer "In11.Cu")
		(net "FM_BATTERY_SENSE_EN_N")
	)
	(segment
		(start 466.580728 -43.303444)
		(end 466.576664 -43.303444)
		(width 0.089408)
		(layer "In11.Cu")
		(net "FM_BATTERY_SENSE_EN_N")
	)
	(segment
		(start 477.037908 -26.581608)
		(end 477.037908 -28.70327)
		(width 0.089408)
		(layer "In11.Cu")
		(net "FM_BATTERY_SENSE_EN_N")
	)
	(segment
		(start 461.59928 -38.916864)
		(end 461.597502 -38.915086)
		(width 0.089408)
		(layer "In11.Cu")
		(net "FM_BATTERY_SENSE_EN_N")
	)
	(segment
		(start 477.21012 -32.793686)
		(end 478.205292 -33.788858)
		(width 0.089408)
		(layer "In11.Cu")
		(net "FM_BATTERY_SENSE_EN_N")
	)
	(segment
		(start 474.327982 -4.120896)
		(end 475.794832 -5.587746)
		(width 0.089408)
		(layer "In11.Cu")
		(net "FM_BATTERY_SENSE_EN_N")
	)
	(segment
		(start 462.689702 -38.915086)
		(end 462.199482 -38.915086)
		(width 0.089408)
		(layer "In11.Cu")
		(net "FM_BATTERY_SENSE_EN_N")
	)
	(segment
		(start 444.630048 -39.934388)
		(end 444.302896 -39.934388)
		(width 0.089408)
		(layer "In11.Cu")
		(net "FM_BATTERY_SENSE_EN_N")
	)
	(segment
		(start 423.374312 -38.903402)
		(end 422.98366 -38.51275)
		(width 0.089408)
		(layer "In11.Cu")
		(net "FM_BATTERY_SENSE_EN_N")
	)
	(segment
		(start 475.794832 -5.587746)
		(end 475.794832 -5.97535)
		(width 0.089408)
		(layer "In11.Cu")
		(net "FM_BATTERY_SENSE_EN_N")
	)
	(segment
		(start 470.452196 -2.066036)
		(end 472.134184 -2.066036)
		(width 0.089408)
		(layer "In11.Cu")
		(net "FM_BATTERY_SENSE_EN_N")
	)
	(segment
		(start 467.2584 4.064)
		(end 467.2584 0.540258)
		(width 0.089408)
		(layer "In11.Cu")
		(net "FM_BATTERY_SENSE_EN_N")
	)
	(segment
		(start 476.763588 -6.944106)
		(end 476.763588 -8.080248)
		(width 0.089408)
		(layer "In11.Cu")
		(net "FM_BATTERY_SENSE_EN_N")
	)
	(segment
		(start 412.66745 -38.51275)
		(end 412.2928 -38.8874)
		(width 0.089408)
		(layer "In11.Cu")
		(net "FM_BATTERY_SENSE_EN_N")
	)
	(segment
		(start 425.24553 -39.952422)
		(end 424.19651 -38.903402)
		(width 0.089408)
		(layer "In11.Cu")
		(net "FM_BATTERY_SENSE_EN_N")
	)
	(segment
		(start 386.800344 -105.142538)
		(end 386.888482 -105.0544)
		(width 0.12446)
		(layer "F.Cu")
		(net "P3V3_RTC_STBY")
	)
	(segment
		(start 386.800344 -105.317544)
		(end 386.800344 -105.142538)
		(width 0.12446)
		(layer "F.Cu")
		(net "P3V3_RTC_STBY")
	)
	(segment
		(start 386.888482 -105.0544)
		(end 387.3373 -105.0544)
		(width 0.12446)
		(layer "F.Cu")
		(net "P3V3_RTC_STBY")
	)
	(segment
		(start 386.93725 -105.45445)
		(end 386.800344 -105.317544)
		(width 0.12446)
		(layer "F.Cu")
		(net "P3V3_RTC_STBY")
	)
	(via
		(at 380.307342 -103.53294)
		(size 0.508)
		(drill 0.254)
		(layers "F.Cu" "B.Cu")
		(net "P3V3_RTC_STBY")
	)
	(via
		(at 368.7699 -99.76866)
		(size 0.6604)
		(drill 0.3302)
		(layers "F.Cu" "B.Cu")
		(net "P3V3_RTC_STBY")
	)
	(via
		(at 371.098064 -91.43111)
		(size 0.508)
		(drill 0.254)
		(layers "F.Cu" "B.Cu")
		(net "P3V3_RTC_STBY")
	)
	(via
		(at 375.453402 -90.15476)
		(size 0.508)
		(drill 0.254)
		(layers "F.Cu" "B.Cu")
		(net "P3V3_RTC_STBY")
	)
	(via
		(at 387.237478 -22.437344)
		(size 0.508)
		(drill 0.254)
		(layers "F.Cu" "B.Cu")
		(net "P3V3_RTC_STBY")
	)
	(via
		(at 387.3373 -105.0544)
		(size 0.508)
		(drill 0.254)
		(layers "F.Cu" "B.Cu")
		(net "P3V3_RTC_STBY")
	)
	(segment
		(start 365.88319 5.4102)
		(end 410.9974 5.4102)
		(width 0.254)
		(layer "B.Cu")
		(net "P3V3_RTC_STBY")
	)
	(segment
		(start 375.43232 -90.15476)
		(end 375.35358 -90.2335)
		(width 0.254)
		(layer "B.Cu")
		(net "P3V3_RTC_STBY")
	)
	(segment
		(start 369.352322 -101.03485)
		(end 368.7699 -100.452428)
		(width 0.254)
		(layer "B.Cu")
		(net "P3V3_RTC_STBY")
	)
	(segment
		(start 423.422318 1.595882)
		(end 424.8658 0.1524)
		(width 0.254)
		(layer "B.Cu")
		(net "P3V3_RTC_STBY")
	)
	(segment
		(start 412.481268 3.926332)
		(end 412.481268 3.29057)
		(width 0.254)
		(layer "B.Cu")
		(net "P3V3_RTC_STBY")
	)
	(segment
		(start 385.15163 -22.047454)
		(end 385.15163 -21.660866)
		(width 0.254)
		(layer "B.Cu")
		(net "P3V3_RTC_STBY")
	)
	(segment
		(start 449.7324 -11.8872)
		(end 447.9544 -11.8872)
		(width 0.254)
		(layer "B.Cu")
		(net "P3V3_RTC_STBY")
	)
	(segment
		(start 374.160034 -102.583234)
		(end 374.160034 -101.900482)
		(width 0.254)
		(layer "B.Cu")
		(net "P3V3_RTC_STBY")
	)
	(segment
		(start 375.453402 -90.15476)
		(end 375.43232 -90.15476)
		(width 0.254)
		(layer "B.Cu")
		(net "P3V3_RTC_STBY")
	)
	(segment
		(start 387.237478 -22.437344)
		(end 385.54152 -22.437344)
		(width 0.254)
		(layer "B.Cu")
		(net "P3V3_RTC_STBY")
	)
	(segment
		(start 374.4976 -102.9208)
		(end 374.160034 -102.583234)
		(width 0.254)
		(layer "B.Cu")
		(net "P3V3_RTC_STBY")
	)
	(segment
		(start 365.2012 0.286766)
		(end 365.2012 4.72821)
		(width 0.254)
		(layer "B.Cu")
		(net "P3V3_RTC_STBY")
	)
	(segment
		(start 442.079634 -3.6322)
		(end 443.442344 -3.6322)
		(width 0.254)
		(layer "B.Cu")
		(net "P3V3_RTC_STBY")
	)
	(segment
		(start 368.477292 -93.775022)
		(end 369.719606 -92.532708)
		(width 0.254)
		(layer "B.Cu")
		(net "P3V3_RTC_STBY")
	)
	(segment
		(start 374.007634 -99.08159)
		(end 374.777 -99.850956)
		(width 0.254)
		(layer "B.Cu")
		(net "P3V3_RTC_STBY")
	)
	(segment
		(start 385.15163 -21.660866)
		(end 383.9337 -20.442936)
		(width 0.254)
		(layer "B.Cu")
		(net "P3V3_RTC_STBY")
	)
	(segment
		(start 443.442344 -3.6322)
		(end 444.98895 -5.178806)
		(width 0.254)
		(layer "B.Cu")
		(net "P3V3_RTC_STBY")
	)
	(segment
		(start 383.286 -10.287)
		(end 368.5032 -10.287)
		(width 0.254)
		(layer "B.Cu")
		(net "P3V3_RTC_STBY")
	)
	(segment
		(start 440.386978 -1.3208)
		(end 441.198 -2.131822)
		(width 0.254)
		(layer "B.Cu")
		(net "P3V3_RTC_STBY")
	)
	(segment
		(start 383.9337 -20.442936)
		(end 383.9337 -10.9347)
		(width 0.254)
		(layer "B.Cu")
		(net "P3V3_RTC_STBY")
	)
	(segment
		(start 368.7699 -100.452428)
		(end 368.7699 -99.76866)
		(width 0.254)
		(layer "B.Cu")
		(net "P3V3_RTC_STBY")
	)
	(segment
		(start 368.7699 -95.299784)
		(end 368.477292 -95.007176)
		(width 0.254)
		(layer "B.Cu")
		(net "P3V3_RTC_STBY")
	)
	(segment
		(start 364.989872 -6.773672)
		(end 364.989872 -2.764536)
		(width 0.254)
		(layer "B.Cu")
		(net "P3V3_RTC_STBY")
	)
	(segment
		(start 374.777 -99.850956)
		(end 374.777 -100.3046)
		(width 0.254)
		(layer "B.Cu")
		(net "P3V3_RTC_STBY")
	)
	(segment
		(start 441.198 -2.131822)
		(end 441.198 -2.750566)
		(width 0.254)
		(layer "B.Cu")
		(net "P3V3_RTC_STBY")
	)
	(segment
		(start 371.006878 -101.03485)
		(end 369.352322 -101.03485)
		(width 0.254)
		(layer "B.Cu")
		(net "P3V3_RTC_STBY")
	)
	(segment
		(start 365.43615 -2.318258)
		(end 365.43615 0.051816)
		(width 0.254)
		(layer "B.Cu")
		(net "P3V3_RTC_STBY")
	)
	(segment
		(start 383.9337 -10.9347)
		(end 383.286 -10.287)
		(width 0.254)
		(layer "B.Cu")
		(net "P3V3_RTC_STBY")
	)
	(segment
		(start 412.481268 3.29057)
		(end 414.175956 1.595882)
		(width 0.254)
		(layer "B.Cu")
		(net "P3V3_RTC_STBY")
	)
	(segment
		(start 374.160034 -101.900482)
		(end 373.808752 -101.5492)
		(width 0.254)
		(layer "B.Cu")
		(net "P3V3_RTC_STBY")
	)
	(segment
		(start 365.2012 4.72821)
		(end 365.88319 5.4102)
		(width 0.254)
		(layer "B.Cu")
		(net "P3V3_RTC_STBY")
	)
	(segment
		(start 371.098064 -91.959938)
		(end 371.098064 -91.43111)
		(width 0.254)
		(layer "B.Cu")
		(net "P3V3_RTC_STBY")
	)
	(segment
		(start 370.525294 -92.532708)
		(end 371.098064 -91.959938)
		(width 0.254)
		(layer "B.Cu")
		(net "P3V3_RTC_STBY")
	)
	(segment
		(start 441.198 -2.750566)
		(end 442.079634 -3.6322)
		(width 0.254)
		(layer "B.Cu")
		(net "P3V3_RTC_STBY")
	)
	(segment
		(start 385.54152 -22.437344)
		(end 385.15163 -22.047454)
		(width 0.254)
		(layer "B.Cu")
		(net "P3V3_RTC_STBY")
	)
	(segment
		(start 447.948304 -7.142734)
		(end 447.948304 -10.967212)
		(width 0.254)
		(layer "B.Cu")
		(net "P3V3_RTC_STBY")
	)
	(segment
		(start 368.7699 -99.76866)
		(end 368.7699 -95.299784)
		(width 0.254)
		(layer "B.Cu")
		(net "P3V3_RTC_STBY")
	)
	(segment
		(start 373.808752 -101.5492)
		(end 371.521228 -101.5492)
		(width 0.254)
		(layer "B.Cu")
		(net "P3V3_RTC_STBY")
	)
	(segment
		(start 445.28613 -6.112764)
		(end 446.918334 -6.112764)
		(width 0.254)
		(layer "B.Cu")
		(net "P3V3_RTC_STBY")
	)
	(segment
		(start 373.18061 -99.08159)
		(end 374.007634 -99.08159)
		(width 0.254)
		(layer "B.Cu")
		(net "P3V3_RTC_STBY")
	)
	(segment
		(start 410.9974 5.4102)
		(end 412.481268 3.926332)
		(width 0.254)
		(layer "B.Cu")
		(net "P3V3_RTC_STBY")
	)
	(segment
		(start 365.43615 0.051816)
		(end 365.2012 0.286766)
		(width 0.254)
		(layer "B.Cu")
		(net "P3V3_RTC_STBY")
	)
	(segment
		(start 368.7699 -99.76866)
		(end 372.49354 -99.76866)
		(width 0.254)
		(layer "B.Cu")
		(net "P3V3_RTC_STBY")
	)
	(segment
		(start 368.5032 -10.287)
		(end 364.989872 -6.773672)
		(width 0.254)
		(layer "B.Cu")
		(net "P3V3_RTC_STBY")
	)
	(segment
		(start 372.49354 -99.76866)
		(end 373.18061 -99.08159)
		(width 0.254)
		(layer "B.Cu")
		(net "P3V3_RTC_STBY")
	)
	(segment
		(start 430.657 0.1524)
		(end 432.1302 -1.3208)
		(width 0.254)
		(layer "B.Cu")
		(net "P3V3_RTC_STBY")
	)
	(segment
		(start 444.98895 -5.815584)
		(end 445.28613 -6.112764)
		(width 0.254)
		(layer "B.Cu")
		(net "P3V3_RTC_STBY")
	)
	(segment
		(start 447.6242 -11.291316)
		(end 447.6242 -12.2174)
		(width 0.254)
		(layer "B.Cu")
		(net "P3V3_RTC_STBY")
	)
	(segment
		(start 375.158 -102.9208)
		(end 374.4976 -102.9208)
		(width 0.254)
		(layer "B.Cu")
		(net "P3V3_RTC_STBY")
	)
	(segment
		(start 447.948304 -10.967212)
		(end 447.6242 -11.291316)
		(width 0.254)
		(layer "B.Cu")
		(net "P3V3_RTC_STBY")
	)
	(segment
		(start 424.8658 0.1524)
		(end 430.657 0.1524)
		(width 0.254)
		(layer "B.Cu")
		(net "P3V3_RTC_STBY")
	)
	(segment
		(start 375.35358 -90.2335)
		(end 374.777 -90.2335)
		(width 0.254)
		(layer "B.Cu")
		(net "P3V3_RTC_STBY")
	)
	(segment
		(start 447.9544 -11.8872)
		(end 447.6242 -12.2174)
		(width 0.254)
		(layer "B.Cu")
		(net "P3V3_RTC_STBY")
	)
	(segment
		(start 444.98895 -5.178806)
		(end 444.98895 -5.815584)
		(width 0.254)
		(layer "B.Cu")
		(net "P3V3_RTC_STBY")
	)
	(segment
		(start 432.1302 -1.3208)
		(end 440.386978 -1.3208)
		(width 0.254)
		(layer "B.Cu")
		(net "P3V3_RTC_STBY")
	)
	(segment
		(start 368.477292 -95.007176)
		(end 368.477292 -93.775022)
		(width 0.254)
		(layer "B.Cu")
		(net "P3V3_RTC_STBY")
	)
	(segment
		(start 371.521228 -101.5492)
		(end 371.006878 -101.03485)
		(width 0.254)
		(layer "B.Cu")
		(net "P3V3_RTC_STBY")
	)
	(segment
		(start 414.175956 1.595882)
		(end 423.422318 1.595882)
		(width 0.254)
		(layer "B.Cu")
		(net "P3V3_RTC_STBY")
	)
	(segment
		(start 369.719606 -92.532708)
		(end 370.525294 -92.532708)
		(width 0.254)
		(layer "B.Cu")
		(net "P3V3_RTC_STBY")
	)
	(segment
		(start 364.989872 -2.764536)
		(end 365.43615 -2.318258)
		(width 0.254)
		(layer "B.Cu")
		(net "P3V3_RTC_STBY")
	)
	(segment
		(start 446.918334 -6.112764)
		(end 447.948304 -7.142734)
		(width 0.254)
		(layer "B.Cu")
		(net "P3V3_RTC_STBY")
	)
	(segment
		(start 380.65964 -103.53294)
		(end 380.307342 -103.53294)
		(width 0.127)
		(layer "In2.Cu")
		(net "P3V3_RTC_STBY")
	)
	(segment
		(start 380.54788 -102.32644)
		(end 384.07848 -102.32644)
		(width 0.127)
		(layer "In2.Cu")
		(net "P3V3_RTC_STBY")
	)
	(segment
		(start 384.06324 -103.17988)
		(end 381.0127 -103.17988)
		(width 0.127)
		(layer "In2.Cu")
		(net "P3V3_RTC_STBY")
	)
	(segment
		(start 386.3848 -103.14178)
		(end 386.3848 -104.5464)
		(width 0.254)
		(layer "In2.Cu")
		(net "P3V3_RTC_STBY")
	)
	(segment
		(start 380.307342 -102.566978)
		(end 380.54788 -102.32644)
		(width 0.127)
		(layer "In2.Cu")
		(net "P3V3_RTC_STBY")
	)
	(segment
		(start 385.98856 -102.74554)
		(end 386.3848 -103.14178)
		(width 0.254)
		(layer "In2.Cu")
		(net "P3V3_RTC_STBY")
	)
	(segment
		(start 381.0127 -103.17988)
		(end 380.65964 -103.53294)
		(width 0.127)
		(layer "In2.Cu")
		(net "P3V3_RTC_STBY")
	)
	(segment
		(start 380.307342 -103.53294)
		(end 380.307342 -102.566978)
		(width 0.127)
		(layer "In2.Cu")
		(net "P3V3_RTC_STBY")
	)
	(segment
		(start 386.3848 -104.5464)
		(end 386.8928 -105.0544)
		(width 0.254)
		(layer "In2.Cu")
		(net "P3V3_RTC_STBY")
	)
	(segment
		(start 384.49758 -102.74554)
		(end 384.06324 -103.17988)
		(width 0.127)
		(layer "In2.Cu")
		(net "P3V3_RTC_STBY")
	)
	(segment
		(start 384.49758 -102.74554)
		(end 385.98856 -102.74554)
		(width 0.254)
		(layer "In2.Cu")
		(net "P3V3_RTC_STBY")
	)
	(segment
		(start 384.07848 -102.32644)
		(end 384.49758 -102.74554)
		(width 0.127)
		(layer "In2.Cu")
		(net "P3V3_RTC_STBY")
	)
	(segment
		(start 386.8928 -105.0544)
		(end 387.3373 -105.0544)
		(width 0.254)
		(layer "In2.Cu")
		(net "P3V3_RTC_STBY")
	)
	(segment
		(start 373.55018 -91.6813)
		(end 375.06148 -90.17)
		(width 0.254)
		(layer "In4.Cu")
		(net "P3V3_RTC_STBY")
	)
	(segment
		(start 372.2116 -91.948)
		(end 372.4783 -91.6813)
		(width 0.254)
		(layer "In4.Cu")
		(net "P3V3_RTC_STBY")
	)
	(segment
		(start 371.9576 -92.583)
		(end 372.2116 -92.329)
		(width 0.254)
		(layer "In4.Cu")
		(net "P3V3_RTC_STBY")
	)
	(segment
		(start 372.4783 -91.6813)
		(end 373.55018 -91.6813)
		(width 0.254)
		(layer "In4.Cu")
		(net "P3V3_RTC_STBY")
	)
	(segment
		(start 375.06148 -90.17)
		(end 375.41708 -90.17)
		(width 0.254)
		(layer "In4.Cu")
		(net "P3V3_RTC_STBY")
	)
	(segment
		(start 375.41708 -90.17)
		(end 375.43232 -90.15476)
		(width 0.254)
		(layer "In4.Cu")
		(net "P3V3_RTC_STBY")
	)
	(segment
		(start 372.2116 -92.329)
		(end 372.2116 -91.948)
		(width 0.254)
		(layer "In4.Cu")
		(net "P3V3_RTC_STBY")
	)
	(segment
		(start 371.3988 -92.583)
		(end 371.9576 -92.583)
		(width 0.254)
		(layer "In4.Cu")
		(net "P3V3_RTC_STBY")
	)
	(segment
		(start 371.098064 -92.282264)
		(end 371.3988 -92.583)
		(width 0.254)
		(layer "In4.Cu")
		(net "P3V3_RTC_STBY")
	)
	(segment
		(start 375.43232 -90.15476)
		(end 375.453402 -90.15476)
		(width 0.254)
		(layer "In4.Cu")
		(net "P3V3_RTC_STBY")
	)
	(segment
		(start 371.098064 -91.43111)
		(end 371.098064 -92.282264)
		(width 0.254)
		(layer "In4.Cu")
		(net "P3V3_RTC_STBY")
	)
	(segment
		(start 381.110744 -80.478376)
		(end 379.85954 -81.72958)
		(width 0.254)
		(layer "In9.Cu")
		(net "P3V3_RTC_STBY")
	)
	(segment
		(start 385.57835 -34.669222)
		(end 385.57835 -45.610526)
		(width 0.254)
		(layer "In9.Cu")
		(net "P3V3_RTC_STBY")
	)
	(segment
		(start 384.298444 -70.102984)
		(end 384.005836 -70.102984)
		(width 0.254)
		(layer "In9.Cu")
		(net "P3V3_RTC_STBY")
	)
	(segment
		(start 378.46762 -86.595966)
		(end 376.696986 -88.3666)
		(width 0.254)
		(layer "In9.Cu")
		(net "P3V3_RTC_STBY")
	)
	(segment
		(start 385.702302 -59.46013)
		(end 385.702302 -61.79693)
		(width 0.254)
		(layer "In9.Cu")
		(net "P3V3_RTC_STBY")
	)
	(segment
		(start 382.61798 -75.946254)
		(end 381.308102 -77.256132)
		(width 0.254)
		(layer "In9.Cu")
		(net "P3V3_RTC_STBY")
	)
	(segment
		(start 382.617726 -75.71994)
		(end 382.61798 -75.720194)
		(width 0.254)
		(layer "In9.Cu")
		(net "P3V3_RTC_STBY")
	)
	(segment
		(start 387.237478 -22.437344)
		(end 386.907786 -22.437344)
		(width 0.254)
		(layer "In9.Cu")
		(net "P3V3_RTC_STBY")
	)
	(segment
		(start 375.666 -88.725248)
		(end 375.666 -89.92108)
		(width 0.254)
		(layer "In9.Cu")
		(net "P3V3_RTC_STBY")
	)
	(segment
		(start 385.4069 -62.092332)
		(end 385.4069 -68.994528)
		(width 0.254)
		(layer "In9.Cu")
		(net "P3V3_RTC_STBY")
	)
	(segment
		(start 386.951982 -52.941728)
		(end 386.951982 -53.846222)
		(width 0.254)
		(layer "In9.Cu")
		(net "P3V3_RTC_STBY")
	)
	(segment
		(start 381.110744 -80.471518)
		(end 381.110744 -80.478376)
		(width 0.254)
		(layer "In9.Cu")
		(net "P3V3_RTC_STBY")
	)
	(segment
		(start 379.85954 -81.731866)
		(end 379.807216 -81.78419)
		(width 0.254)
		(layer "In9.Cu")
		(net "P3V3_RTC_STBY")
	)
	(segment
		(start 381.308102 -80.27416)
		(end 381.110744 -80.471518)
		(width 0.254)
		(layer "In9.Cu")
		(net "P3V3_RTC_STBY")
	)
	(segment
		(start 375.666 -89.92108)
		(end 375.43232 -90.15476)
		(width 0.254)
		(layer "In9.Cu")
		(net "P3V3_RTC_STBY")
	)
	(segment
		(start 382.61798 -75.720194)
		(end 382.61798 -75.946254)
		(width 0.254)
		(layer "In9.Cu")
		(net "P3V3_RTC_STBY")
	)
	(segment
		(start 386.7912 -33.456372)
		(end 385.57835 -34.669222)
		(width 0.254)
		(layer "In9.Cu")
		(net "P3V3_RTC_STBY")
	)
	(segment
		(start 379.807216 -81.78419)
		(end 379.807216 -83.570064)
		(width 0.254)
		(layer "In9.Cu")
		(net "P3V3_RTC_STBY")
	)
	(segment
		(start 386.951982 -53.846222)
		(end 387.4262 -54.32044)
		(width 0.254)
		(layer "In9.Cu")
		(net "P3V3_RTC_STBY")
	)
	(segment
		(start 382.617726 -72.753474)
		(end 382.617726 -75.71994)
		(width 0.254)
		(layer "In9.Cu")
		(net "P3V3_RTC_STBY")
	)
	(segment
		(start 386.69214 -52.681886)
		(end 386.951982 -52.941728)
		(width 0.254)
		(layer "In9.Cu")
		(net "P3V3_RTC_STBY")
	)
	(segment
		(start 387.4262 -54.32044)
		(end 387.4262 -55.626762)
		(width 0.254)
		(layer "In9.Cu")
		(net "P3V3_RTC_STBY")
	)
	(segment
		(start 378.46762 -84.90966)
		(end 378.46762 -86.595966)
		(width 0.254)
		(layer "In9.Cu")
		(net "P3V3_RTC_STBY")
	)
	(segment
		(start 383.348992 -70.759828)
		(end 383.348992 -72.022208)
		(width 0.254)
		(layer "In9.Cu")
		(net "P3V3_RTC_STBY")
	)
	(segment
		(start 386.461762 -22.883368)
		(end 386.461762 -28.899358)
		(width 0.254)
		(layer "In9.Cu")
		(net "P3V3_RTC_STBY")
	)
	(segment
		(start 375.43232 -90.15476)
		(end 375.453402 -90.15476)
		(width 0.254)
		(layer "In9.Cu")
		(net "P3V3_RTC_STBY")
	)
	(segment
		(start 383.348992 -72.022208)
		(end 382.617726 -72.753474)
		(width 0.254)
		(layer "In9.Cu")
		(net "P3V3_RTC_STBY")
	)
	(segment
		(start 385.4069 -68.994528)
		(end 384.298444 -70.102984)
		(width 0.254)
		(layer "In9.Cu")
		(net "P3V3_RTC_STBY")
	)
	(segment
		(start 386.20827 -29.15285)
		(end 386.20827 -31.75127)
		(width 0.254)
		(layer "In9.Cu")
		(net "P3V3_RTC_STBY")
	)
	(segment
		(start 385.57835 -45.610526)
		(end 386.69214 -46.724316)
		(width 0.254)
		(layer "In9.Cu")
		(net "P3V3_RTC_STBY")
	)
	(segment
		(start 387.4262 -55.626762)
		(end 386.93598 -56.116982)
		(width 0.254)
		(layer "In9.Cu")
		(net "P3V3_RTC_STBY")
	)
	(segment
		(start 376.024648 -88.3666)
		(end 375.666 -88.725248)
		(width 0.254)
		(layer "In9.Cu")
		(net "P3V3_RTC_STBY")
	)
	(segment
		(start 386.907786 -22.437344)
		(end 386.461762 -22.883368)
		(width 0.254)
		(layer "In9.Cu")
		(net "P3V3_RTC_STBY")
	)
	(segment
		(start 386.461762 -28.899358)
		(end 386.20827 -29.15285)
		(width 0.254)
		(layer "In9.Cu")
		(net "P3V3_RTC_STBY")
	)
	(segment
		(start 386.93598 -56.116982)
		(end 386.93598 -58.226452)
		(width 0.254)
		(layer "In9.Cu")
		(net "P3V3_RTC_STBY")
	)
	(segment
		(start 386.93598 -58.226452)
		(end 385.702302 -59.46013)
		(width 0.254)
		(layer "In9.Cu")
		(net "P3V3_RTC_STBY")
	)
	(segment
		(start 376.696986 -88.3666)
		(end 376.024648 -88.3666)
		(width 0.254)
		(layer "In9.Cu")
		(net "P3V3_RTC_STBY")
	)
	(segment
		(start 386.69214 -46.724316)
		(end 386.69214 -52.681886)
		(width 0.254)
		(layer "In9.Cu")
		(net "P3V3_RTC_STBY")
	)
	(segment
		(start 384.005836 -70.102984)
		(end 383.348992 -70.759828)
		(width 0.254)
		(layer "In9.Cu")
		(net "P3V3_RTC_STBY")
	)
	(segment
		(start 381.308102 -77.256132)
		(end 381.308102 -80.27416)
		(width 0.254)
		(layer "In9.Cu")
		(net "P3V3_RTC_STBY")
	)
	(segment
		(start 386.20827 -31.75127)
		(end 386.7912 -32.3342)
		(width 0.254)
		(layer "In9.Cu")
		(net "P3V3_RTC_STBY")
	)
	(segment
		(start 379.85954 -81.72958)
		(end 379.85954 -81.731866)
		(width 0.254)
		(layer "In9.Cu")
		(net "P3V3_RTC_STBY")
	)
	(segment
		(start 385.702302 -61.79693)
		(end 385.4069 -62.092332)
		(width 0.254)
		(layer "In9.Cu")
		(net "P3V3_RTC_STBY")
	)
	(segment
		(start 386.7912 -32.3342)
		(end 386.7912 -33.456372)
		(width 0.254)
		(layer "In9.Cu")
		(net "P3V3_RTC_STBY")
	)
	(segment
		(start 379.807216 -83.570064)
		(end 378.46762 -84.90966)
		(width 0.254)
		(layer "In9.Cu")
		(net "P3V3_RTC_STBY")
	)
	(segment
		(start 132.806694 -67.296538)
		(end 133.378194 -67.296538)
		(width 0.10795)
		(layer "F.Cu")
		(net "TP_CPU1_RSVD_TEST_4")
	)
	(via
		(at 133.378194 -67.296538)
		(size 0.508)
		(drill 0.254)
		(layers "F.Cu" "B.Cu")
		(net "TP_CPU1_RSVD_TEST_4")
	)
	(segment
		(start 131.948174 -66.800984)
		(end 132.519674 -66.800984)
		(width 0.10795)
		(layer "F.Cu")
		(net "TP_CPU1_RSVD_TEST_3")
	)
	(via
		(at 132.519674 -66.800984)
		(size 0.508)
		(drill 0.254)
		(layers "F.Cu" "B.Cu")
		(net "TP_CPU1_RSVD_TEST_3")
	)
	(segment
		(start 297.807126 -67.296538)
		(end 298.378626 -67.296538)
		(width 0.10795)
		(layer "F.Cu")
		(net "TP_CPU0_RSVD_TEST_4")
	)
	(via
		(at 298.378626 -67.296538)
		(size 0.508)
		(drill 0.254)
		(layers "F.Cu" "B.Cu")
		(net "TP_CPU0_RSVD_TEST_4")
	)
	(segment
		(start 296.948606 -66.800984)
		(end 297.520106 -66.800984)
		(width 0.10795)
		(layer "F.Cu")
		(net "TP_CPU0_RSVD_TEST_3")
	)
	(via
		(at 297.520106 -66.800984)
		(size 0.508)
		(drill 0.254)
		(layers "F.Cu" "B.Cu")
		(net "TP_CPU0_RSVD_TEST_3")
	)
	(segment
		(start 367.145316 -67.895216)
		(end 367.545112 -68.295012)
		(width 0.10795)
		(layer "F.Cu")
		(net "TP_CPLD1_PT24B")
	)
	(via
		(at 367.145316 -67.895216)
		(size 0.4572)
		(drill 0.2032)
		(layers "F.Cu" "B.Cu")
		(net "TP_CPLD1_PT24B")
	)
	(via
		(at 367.016792 -67.18427)
		(size 0.6604)
		(drill 0.3302)
		(layers "F.Cu" "B.Cu")
		(net "TP_CPLD1_PT24B")
	)
	(segment
		(start 367.016792 -67.18427)
		(end 367.145316 -67.312794)
		(width 0.10795)
		(layer "B.Cu")
		(net "TP_CPLD1_PT24B")
	)
	(segment
		(start 367.145316 -67.312794)
		(end 367.145316 -67.895216)
		(width 0.10795)
		(layer "B.Cu")
		(net "TP_CPLD1_PT24B")
	)
	(segment
		(start 372.573042 -80.52308)
		(end 372.34495 -80.294988)
		(width 0.10795)
		(layer "F.Cu")
		(net "TP_CPLD1_PB16A_PCLKT2_1")
	)
	(segment
		(start 372.573042 -81.302352)
		(end 372.573042 -80.52308)
		(width 0.10795)
		(layer "F.Cu")
		(net "TP_CPLD1_PB16A_PCLKT2_1")
	)
	(segment
		(start 372.61038 -81.33969)
		(end 372.573042 -81.302352)
		(width 0.10795)
		(layer "F.Cu")
		(net "TP_CPLD1_PB16A_PCLKT2_1")
	)
	(via
		(at 372.61038 -81.33969)
		(size 0.508)
		(drill 0.254)
		(layers "F.Cu" "B.Cu")
		(net "TP_CPLD1_PB16A_PCLKT2_1")
	)
	(segment
		(start 379.349 -77.3176)
		(end 379.126496 -77.095096)
		(width 0.10795)
		(layer "F.Cu")
		(net "RST_RSMRST_DLY")
	)
	(segment
		(start 418.9603 -60.6425)
		(end 424.17746 -55.42534)
		(width 0.10795)
		(layer "F.Cu")
		(net "RST_RSMRST_DLY")
	)
	(segment
		(start 424.17746 -55.42534)
		(end 424.17746 -53.670962)
		(width 0.10795)
		(layer "F.Cu")
		(net "RST_RSMRST_DLY")
	)
	(segment
		(start 423.30243 -52.795932)
		(end 421.63619 -52.795932)
		(width 0.10795)
		(layer "F.Cu")
		(net "RST_RSMRST_DLY")
	)
	(segment
		(start 379.126496 -77.095096)
		(end 378.744988 -77.095096)
		(width 0.10795)
		(layer "F.Cu")
		(net "RST_RSMRST_DLY")
	)
	(segment
		(start 416.248342 -62.347856)
		(end 416.248342 -61.675772)
		(width 0.10795)
		(layer "F.Cu")
		(net "RST_RSMRST_DLY")
	)
	(segment
		(start 416.106864 -62.489334)
		(end 416.248342 -62.347856)
		(width 0.10795)
		(layer "F.Cu")
		(net "RST_RSMRST_DLY")
	)
	(segment
		(start 417.281614 -60.6425)
		(end 418.9603 -60.6425)
		(width 0.10795)
		(layer "F.Cu")
		(net "RST_RSMRST_DLY")
	)
	(segment
		(start 424.17746 -53.670962)
		(end 423.30243 -52.795932)
		(width 0.10795)
		(layer "F.Cu")
		(net "RST_RSMRST_DLY")
	)
	(segment
		(start 416.248342 -61.675772)
		(end 417.281614 -60.6425)
		(width 0.10795)
		(layer "F.Cu")
		(net "RST_RSMRST_DLY")
	)
	(via
		(at 385.4958 -76.982828)
		(size 0.6604)
		(drill 0.3302)
		(layers "F.Cu" "B.Cu")
		(net "RST_RSMRST_DLY")
	)
	(via
		(at 379.349 -77.3176)
		(size 0.4572)
		(drill 0.2032)
		(layers "F.Cu" "B.Cu")
		(net "RST_RSMRST_DLY")
	)
	(via
		(at 416.106864 -62.489334)
		(size 0.508)
		(drill 0.254)
		(layers "F.Cu" "B.Cu")
		(net "RST_RSMRST_DLY")
	)
	(segment
		(start 403.545548 -68.234306)
		(end 405.915114 -65.86474)
		(width 0.10795)
		(layer "B.Cu")
		(net "RST_RSMRST_DLY")
	)
	(segment
		(start 412.84652 -65.448942)
		(end 412.84652 -65.077594)
		(width 0.10795)
		(layer "B.Cu")
		(net "RST_RSMRST_DLY")
	)
	(segment
		(start 388.324598 -72.93229)
		(end 388.324598 -72.900794)
		(width 0.10795)
		(layer "B.Cu")
		(net "RST_RSMRST_DLY")
	)
	(segment
		(start 396.515844 -70.40245)
		(end 396.735046 -70.40245)
		(width 0.10795)
		(layer "B.Cu")
		(net "RST_RSMRST_DLY")
	)
	(segment
		(start 393.141454 -73.77684)
		(end 396.515844 -70.40245)
		(width 0.10795)
		(layer "B.Cu")
		(net "RST_RSMRST_DLY")
	)
	(segment
		(start 381.80264 -76.982828)
		(end 380.551436 -78.234032)
		(width 0.10795)
		(layer "B.Cu")
		(net "RST_RSMRST_DLY")
	)
	(segment
		(start 385.4958 -76.982828)
		(end 386.433568 -76.982828)
		(width 0.10795)
		(layer "B.Cu")
		(net "RST_RSMRST_DLY")
	)
	(segment
		(start 388.324598 -72.900794)
		(end 388.571486 -72.653906)
		(width 0.10795)
		(layer "B.Cu")
		(net "RST_RSMRST_DLY")
	)
	(segment
		(start 388.571486 -72.653906)
		(end 388.602982 -72.653906)
		(width 0.10795)
		(layer "B.Cu")
		(net "RST_RSMRST_DLY")
	)
	(segment
		(start 408.838654 -67.82181)
		(end 409.28925 -67.82181)
		(width 0.10795)
		(layer "B.Cu")
		(net "RST_RSMRST_DLY")
	)
	(segment
		(start 413.805624 -64.790574)
		(end 416.106864 -62.489334)
		(width 0.10795)
		(layer "B.Cu")
		(net "RST_RSMRST_DLY")
	)
	(segment
		(start 379.349 -77.468984)
		(end 379.349 -77.3176)
		(width 0.10795)
		(layer "B.Cu")
		(net "RST_RSMRST_DLY")
	)
	(segment
		(start 396.735046 -70.40245)
		(end 396.7353 -70.402704)
		(width 0.10795)
		(layer "B.Cu")
		(net "RST_RSMRST_DLY")
	)
	(segment
		(start 407.975308 -65.86474)
		(end 408.591258 -66.48069)
		(width 0.10795)
		(layer "B.Cu")
		(net "RST_RSMRST_DLY")
	)
	(segment
		(start 388.602982 -72.653906)
		(end 389.128762 -72.128126)
		(width 0.10795)
		(layer "B.Cu")
		(net "RST_RSMRST_DLY")
	)
	(segment
		(start 408.591258 -67.574414)
		(end 408.838654 -67.82181)
		(width 0.10795)
		(layer "B.Cu")
		(net "RST_RSMRST_DLY")
	)
	(segment
		(start 392.158728 -73.77684)
		(end 393.141454 -73.77684)
		(width 0.10795)
		(layer "B.Cu")
		(net "RST_RSMRST_DLY")
	)
	(segment
		(start 408.591258 -66.48069)
		(end 408.591258 -67.574414)
		(width 0.10795)
		(layer "B.Cu")
		(net "RST_RSMRST_DLY")
	)
	(segment
		(start 409.28925 -67.82181)
		(end 409.754324 -67.356736)
		(width 0.10795)
		(layer "B.Cu")
		(net "RST_RSMRST_DLY")
	)
	(segment
		(start 409.754324 -67.356736)
		(end 410.938726 -67.356736)
		(width 0.10795)
		(layer "B.Cu")
		(net "RST_RSMRST_DLY")
	)
	(segment
		(start 396.7353 -70.402704)
		(end 397.098266 -70.402704)
		(width 0.10795)
		(layer "B.Cu")
		(net "RST_RSMRST_DLY")
	)
	(segment
		(start 380.551436 -78.234032)
		(end 380.114048 -78.234032)
		(width 0.10795)
		(layer "B.Cu")
		(net "RST_RSMRST_DLY")
	)
	(segment
		(start 385.4958 -76.982828)
		(end 381.80264 -76.982828)
		(width 0.10795)
		(layer "B.Cu")
		(net "RST_RSMRST_DLY")
	)
	(segment
		(start 388.255002 -73.001886)
		(end 388.324598 -72.93229)
		(width 0.10795)
		(layer "B.Cu")
		(net "RST_RSMRST_DLY")
	)
	(segment
		(start 397.564102 -69.936868)
		(end 398.381982 -69.936868)
		(width 0.10795)
		(layer "B.Cu")
		(net "RST_RSMRST_DLY")
	)
	(segment
		(start 413.13354 -64.790574)
		(end 413.805624 -64.790574)
		(width 0.10795)
		(layer "B.Cu")
		(net "RST_RSMRST_DLY")
	)
	(segment
		(start 390.510014 -72.128126)
		(end 392.158728 -73.77684)
		(width 0.10795)
		(layer "B.Cu")
		(net "RST_RSMRST_DLY")
	)
	(segment
		(start 389.128762 -72.128126)
		(end 390.510014 -72.128126)
		(width 0.10795)
		(layer "B.Cu")
		(net "RST_RSMRST_DLY")
	)
	(segment
		(start 397.098266 -70.402704)
		(end 397.564102 -69.936868)
		(width 0.10795)
		(layer "B.Cu")
		(net "RST_RSMRST_DLY")
	)
	(segment
		(start 386.433568 -76.982828)
		(end 388.255002 -75.161394)
		(width 0.10795)
		(layer "B.Cu")
		(net "RST_RSMRST_DLY")
	)
	(segment
		(start 412.84652 -65.077594)
		(end 413.13354 -64.790574)
		(width 0.10795)
		(layer "B.Cu")
		(net "RST_RSMRST_DLY")
	)
	(segment
		(start 398.381982 -69.936868)
		(end 400.084544 -68.234306)
		(width 0.10795)
		(layer "B.Cu")
		(net "RST_RSMRST_DLY")
	)
	(segment
		(start 388.255002 -75.161394)
		(end 388.255002 -73.001886)
		(width 0.10795)
		(layer "B.Cu")
		(net "RST_RSMRST_DLY")
	)
	(segment
		(start 405.915114 -65.86474)
		(end 407.975308 -65.86474)
		(width 0.10795)
		(layer "B.Cu")
		(net "RST_RSMRST_DLY")
	)
	(segment
		(start 410.938726 -67.356736)
		(end 412.84652 -65.448942)
		(width 0.10795)
		(layer "B.Cu")
		(net "RST_RSMRST_DLY")
	)
	(segment
		(start 400.084544 -68.234306)
		(end 403.545548 -68.234306)
		(width 0.10795)
		(layer "B.Cu")
		(net "RST_RSMRST_DLY")
	)
	(segment
		(start 380.114048 -78.234032)
		(end 379.349 -77.468984)
		(width 0.10795)
		(layer "B.Cu")
		(net "RST_RSMRST_DLY")
	)
	(segment
		(start 400.880072 -107.354878)
		(end 402.217128 -107.354878)
		(width 0.0889)
		(layer "F.Cu")
		(net "FM_SLT_CFG2_R")
	)
	(segment
		(start 489.84662 -52.48402)
		(end 491.05566 -51.27498)
		(width 0.10795)
		(layer "F.Cu")
		(net "FM_SLT_CFG2_R")
	)
	(segment
		(start 489.711492 -52.48402)
		(end 489.84662 -52.48402)
		(width 0.10795)
		(layer "F.Cu")
		(net "FM_SLT_CFG2_R")
	)
	(segment
		(start 402.51634 -107.65409)
		(end 403.239986 -107.65409)
		(width 0.0889)
		(layer "F.Cu")
		(net "FM_SLT_CFG2_R")
	)
	(segment
		(start 489.474256 -52.721256)
		(end 489.711492 -52.48402)
		(width 0.10795)
		(layer "F.Cu")
		(net "FM_SLT_CFG2_R")
	)
	(segment
		(start 402.217128 -107.354878)
		(end 402.51634 -107.65409)
		(width 0.0889)
		(layer "F.Cu")
		(net "FM_SLT_CFG2_R")
	)
	(via
		(at 489.474256 -52.721256)
		(size 0.508)
		(drill 0.254)
		(layers "F.Cu" "B.Cu")
		(net "FM_SLT_CFG2_R")
	)
	(via
		(at 491.05566 -51.27498)
		(size 0.762)
		(drill 0.381)
		(layers "F.Cu" "B.Cu")
		(net "FM_SLT_CFG2_R")
	)
	(via
		(at 465.541868 -3.429)
		(size 0.508)
		(drill 0.254)
		(layers "F.Cu" "B.Cu")
		(net "FM_SLT_CFG2_R")
	)
	(via
		(at 403.239986 -107.65409)
		(size 0.508)
		(drill 0.254)
		(layers "F.Cu" "B.Cu")
		(net "FM_SLT_CFG2_R")
	)
	(segment
		(start 465.3915 -4.445)
		(end 465.3915 -3.5941)
		(width 0.10795)
		(layer "B.Cu")
		(net "FM_SLT_CFG2_R")
	)
	(segment
		(start 465.3915 -3.5941)
		(end 465.541868 -3.443732)
		(width 0.10795)
		(layer "B.Cu")
		(net "FM_SLT_CFG2_R")
	)
	(segment
		(start 465.3915 -4.445)
		(end 466.1535 -4.445)
		(width 0.10795)
		(layer "B.Cu")
		(net "FM_SLT_CFG2_R")
	)
	(segment
		(start 465.541868 -3.443732)
		(end 465.541868 -3.429)
		(width 0.10795)
		(layer "B.Cu")
		(net "FM_SLT_CFG2_R")
	)
	(segment
		(start 401.509992 -77.446886)
		(end 401.509738 -77.44714)
		(width 0.089408)
		(layer "In2.Cu")
		(net "FM_SLT_CFG2_R")
	)
	(segment
		(start 407.204418 -67.54114)
		(end 406.997662 -67.747896)
		(width 0.089408)
		(layer "In2.Cu")
		(net "FM_SLT_CFG2_R")
	)
	(segment
		(start 472.30538 -51.415442)
		(end 472.30411 -51.416712)
		(width 0.089408)
		(layer "In2.Cu")
		(net "FM_SLT_CFG2_R")
	)
	(segment
		(start 401.509738 -78.080616)
		(end 401.509992 -78.08087)
		(width 0.089408)
		(layer "In2.Cu")
		(net "FM_SLT_CFG2_R")
	)
	(segment
		(start 473.157296 -49.957482)
		(end 473.157296 -50.618898)
		(width 0.089408)
		(layer "In2.Cu")
		(net "FM_SLT_CFG2_R")
	)
	(segment
		(start 401.509992 -77.40904)
		(end 401.509992 -77.446886)
		(width 0.089408)
		(layer "In2.Cu")
		(net "FM_SLT_CFG2_R")
	)
	(segment
		(start 407.204418 -62.573916)
		(end 407.204418 -67.54114)
		(width 0.089408)
		(layer "In2.Cu")
		(net "FM_SLT_CFG2_R")
	)
	(segment
		(start 400.22907 -99.899978)
		(end 400.115532 -100.013516)
		(width 0.089408)
		(layer "In2.Cu")
		(net "FM_SLT_CFG2_R")
	)
	(segment
		(start 481.242624 -50.057304)
		(end 480.522026 -49.336706)
		(width 0.089408)
		(layer "In2.Cu")
		(net "FM_SLT_CFG2_R")
	)
	(segment
		(start 470.55786 -51.415442)
		(end 470.152476 -51.415442)
		(width 0.089408)
		(layer "In2.Cu")
		(net "FM_SLT_CFG2_R")
	)
	(segment
		(start 424.996864 -51.792124)
		(end 424.824906 -51.620166)
		(width 0.089408)
		(layer "In2.Cu")
		(net "FM_SLT_CFG2_R")
	)
	(segment
		(start 401.113244 -88.2015)
		(end 401.113244 -92.02547)
		(width 0.089408)
		(layer "In2.Cu")
		(net "FM_SLT_CFG2_R")
	)
	(segment
		(start 406.932892 -59.523376)
		(end 406.28316 -60.173108)
		(width 0.089408)
		(layer "In2.Cu")
		(net "FM_SLT_CFG2_R")
	)
	(segment
		(start 470.152476 -51.415442)
		(end 469.655398 -50.918364)
		(width 0.089408)
		(layer "In2.Cu")
		(net "FM_SLT_CFG2_R")
	)
	(segment
		(start 436.70347 -52.66182)
		(end 426.871384 -52.66182)
		(width 0.089408)
		(layer "In2.Cu")
		(net "FM_SLT_CFG2_R")
	)
	(segment
		(start 489.056426 -52.303426)
		(end 486.581704 -52.303426)
		(width 0.089408)
		(layer "In2.Cu")
		(net "FM_SLT_CFG2_R")
	)
	(segment
		(start 402.68398 -86.630764)
		(end 401.113244 -88.2015)
		(width 0.089408)
		(layer "In2.Cu")
		(net "FM_SLT_CFG2_R")
	)
	(segment
		(start 484.211376 -49.933098)
		(end 482.001068 -49.933098)
		(width 0.089408)
		(layer "In2.Cu")
		(net "FM_SLT_CFG2_R")
	)
	(segment
		(start 401.509738 -77.44714)
		(end 401.509738 -78.080616)
		(width 0.089408)
		(layer "In2.Cu")
		(net "FM_SLT_CFG2_R")
	)
	(segment
		(start 467.87689 -50.918364)
		(end 466.976968 -51.818286)
		(width 0.089408)
		(layer "In2.Cu")
		(net "FM_SLT_CFG2_R")
	)
	(segment
		(start 489.474256 -52.721256)
		(end 489.056426 -52.303426)
		(width 0.089408)
		(layer "In2.Cu")
		(net "FM_SLT_CFG2_R")
	)
	(segment
		(start 486.581704 -52.303426)
		(end 484.211376 -49.933098)
		(width 0.089408)
		(layer "In2.Cu")
		(net "FM_SLT_CFG2_R")
	)
	(segment
		(start 406.997662 -67.747896)
		(end 406.997662 -68.213478)
		(width 0.089408)
		(layer "In2.Cu")
		(net "FM_SLT_CFG2_R")
	)
	(segment
		(start 402.171662 -107.65409)
		(end 403.239986 -107.65409)
		(width 0.089408)
		(layer "In2.Cu")
		(net "FM_SLT_CFG2_R")
	)
	(segment
		(start 437.547004 -51.818286)
		(end 436.70347 -52.66182)
		(width 0.089408)
		(layer "In2.Cu")
		(net "FM_SLT_CFG2_R")
	)
	(segment
		(start 401.509992 -78.08087)
		(end 401.509992 -78.68793)
		(width 0.089408)
		(layer "In2.Cu")
		(net "FM_SLT_CFG2_R")
	)
	(segment
		(start 401.646898 -74.569828)
		(end 401.646898 -74.737976)
		(width 0.089408)
		(layer "In2.Cu")
		(net "FM_SLT_CFG2_R")
	)
	(segment
		(start 402.68398 -83.925664)
		(end 402.68398 -86.630764)
		(width 0.089408)
		(layer "In2.Cu")
		(net "FM_SLT_CFG2_R")
	)
	(segment
		(start 409.33116 -51.849528)
		(end 406.932892 -54.247796)
		(width 0.089408)
		(layer "In2.Cu")
		(net "FM_SLT_CFG2_R")
	)
	(segment
		(start 480.522026 -49.336706)
		(end 473.778072 -49.336706)
		(width 0.089408)
		(layer "In2.Cu")
		(net "FM_SLT_CFG2_R")
	)
	(segment
		(start 407.361136 -68.576952)
		(end 407.361136 -68.85559)
		(width 0.089408)
		(layer "In2.Cu")
		(net "FM_SLT_CFG2_R")
	)
	(segment
		(start 469.655398 -50.918364)
		(end 467.87689 -50.918364)
		(width 0.089408)
		(layer "In2.Cu")
		(net "FM_SLT_CFG2_R")
	)
	(segment
		(start 466.976968 -51.818286)
		(end 437.547004 -51.818286)
		(width 0.089408)
		(layer "In2.Cu")
		(net "FM_SLT_CFG2_R")
	)
	(segment
		(start 401.19554 -77.094588)
		(end 401.509992 -77.40904)
		(width 0.089408)
		(layer "In2.Cu")
		(net "FM_SLT_CFG2_R")
	)
	(segment
		(start 472.30411 -51.416712)
		(end 470.55913 -51.416712)
		(width 0.089408)
		(layer "In2.Cu")
		(net "FM_SLT_CFG2_R")
	)
	(segment
		(start 424.824906 -51.620166)
		(end 419.80485 -51.620166)
		(width 0.089408)
		(layer "In2.Cu")
		(net "FM_SLT_CFG2_R")
	)
	(segment
		(start 407.361136 -68.85559)
		(end 401.646898 -74.569828)
		(width 0.089408)
		(layer "In2.Cu")
		(net "FM_SLT_CFG2_R")
	)
	(segment
		(start 473.157296 -50.618898)
		(end 472.360752 -51.415442)
		(width 0.089408)
		(layer "In2.Cu")
		(net "FM_SLT_CFG2_R")
	)
	(segment
		(start 426.001688 -51.792124)
		(end 424.996864 -51.792124)
		(width 0.089408)
		(layer "In2.Cu")
		(net "FM_SLT_CFG2_R")
	)
	(segment
		(start 400.115532 -105.59796)
		(end 402.171662 -107.65409)
		(width 0.089408)
		(layer "In2.Cu")
		(net "FM_SLT_CFG2_R")
	)
	(segment
		(start 401.646898 -74.737976)
		(end 401.19554 -75.189334)
		(width 0.089408)
		(layer "In2.Cu")
		(net "FM_SLT_CFG2_R")
	)
	(segment
		(start 406.28316 -60.173108)
		(end 406.28316 -61.652658)
		(width 0.089408)
		(layer "In2.Cu")
		(net "FM_SLT_CFG2_R")
	)
	(segment
		(start 470.55913 -51.416712)
		(end 470.55786 -51.415442)
		(width 0.089408)
		(layer "In2.Cu")
		(net "FM_SLT_CFG2_R")
	)
	(segment
		(start 401.113244 -92.02547)
		(end 400.765772 -92.372942)
		(width 0.089408)
		(layer "In2.Cu")
		(net "FM_SLT_CFG2_R")
	)
	(segment
		(start 482.001068 -49.933098)
		(end 481.876862 -50.057304)
		(width 0.089408)
		(layer "In2.Cu")
		(net "FM_SLT_CFG2_R")
	)
	(segment
		(start 406.997662 -68.213478)
		(end 407.361136 -68.576952)
		(width 0.089408)
		(layer "In2.Cu")
		(net "FM_SLT_CFG2_R")
	)
	(segment
		(start 401.19554 -75.189334)
		(end 401.19554 -77.094588)
		(width 0.089408)
		(layer "In2.Cu")
		(net "FM_SLT_CFG2_R")
	)
	(segment
		(start 472.360752 -51.415442)
		(end 472.30538 -51.415442)
		(width 0.089408)
		(layer "In2.Cu")
		(net "FM_SLT_CFG2_R")
	)
	(segment
		(start 400.765772 -99.35464)
		(end 400.22907 -99.891342)
		(width 0.089408)
		(layer "In2.Cu")
		(net "FM_SLT_CFG2_R")
	)
	(segment
		(start 406.932892 -54.247796)
		(end 406.932892 -59.523376)
		(width 0.089408)
		(layer "In2.Cu")
		(net "FM_SLT_CFG2_R")
	)
	(segment
		(start 400.115532 -100.013516)
		(end 400.115532 -105.59796)
		(width 0.089408)
		(layer "In2.Cu")
		(net "FM_SLT_CFG2_R")
	)
	(segment
		(start 400.22907 -99.891342)
		(end 400.22907 -99.899978)
		(width 0.089408)
		(layer "In2.Cu")
		(net "FM_SLT_CFG2_R")
	)
	(segment
		(start 401.509992 -78.68793)
		(end 400.861784 -79.336138)
		(width 0.089408)
		(layer "In2.Cu")
		(net "FM_SLT_CFG2_R")
	)
	(segment
		(start 406.28316 -61.652658)
		(end 407.204418 -62.573916)
		(width 0.089408)
		(layer "In2.Cu")
		(net "FM_SLT_CFG2_R")
	)
	(segment
		(start 473.778072 -49.336706)
		(end 473.157296 -49.957482)
		(width 0.089408)
		(layer "In2.Cu")
		(net "FM_SLT_CFG2_R")
	)
	(segment
		(start 419.575488 -51.849528)
		(end 409.33116 -51.849528)
		(width 0.089408)
		(layer "In2.Cu")
		(net "FM_SLT_CFG2_R")
	)
	(segment
		(start 481.876862 -50.057304)
		(end 481.242624 -50.057304)
		(width 0.089408)
		(layer "In2.Cu")
		(net "FM_SLT_CFG2_R")
	)
	(segment
		(start 400.861784 -79.336138)
		(end 400.861784 -82.103468)
		(width 0.089408)
		(layer "In2.Cu")
		(net "FM_SLT_CFG2_R")
	)
	(segment
		(start 400.861784 -82.103468)
		(end 402.68398 -83.925664)
		(width 0.089408)
		(layer "In2.Cu")
		(net "FM_SLT_CFG2_R")
	)
	(segment
		(start 426.871384 -52.66182)
		(end 426.001688 -51.792124)
		(width 0.089408)
		(layer "In2.Cu")
		(net "FM_SLT_CFG2_R")
	)
	(segment
		(start 419.80485 -51.620166)
		(end 419.575488 -51.849528)
		(width 0.089408)
		(layer "In2.Cu")
		(net "FM_SLT_CFG2_R")
	)
	(segment
		(start 400.765772 -92.372942)
		(end 400.765772 -99.35464)
		(width 0.089408)
		(layer "In2.Cu")
		(net "FM_SLT_CFG2_R")
	)
	(segment
		(start 494.293652 -41.82237)
		(end 494.469928 -41.646094)
		(width 0.089408)
		(layer "In9.Cu")
		(net "FM_SLT_CFG2_R")
	)
	(segment
		(start 475.352618 -9.095232)
		(end 474.200728 -7.943342)
		(width 0.089408)
		(layer "In9.Cu")
		(net "FM_SLT_CFG2_R")
	)
	(segment
		(start 468.363046 -5.929884)
		(end 468.363046 -5.151374)
		(width 0.089408)
		(layer "In9.Cu")
		(net "FM_SLT_CFG2_R")
	)
	(segment
		(start 492.786924 -38.264338)
		(end 492.786924 -36.806124)
		(width 0.089408)
		(layer "In9.Cu")
		(net "FM_SLT_CFG2_R")
	)
	(segment
		(start 494.293652 -43.071288)
		(end 494.293652 -41.82237)
		(width 0.089408)
		(layer "In9.Cu")
		(net "FM_SLT_CFG2_R")
	)
	(segment
		(start 493.007904 -46.646084)
		(end 492.89081 -46.52899)
		(width 0.089408)
		(layer "In9.Cu")
		(net "FM_SLT_CFG2_R")
	)
	(segment
		(start 491.8456 -29.4132)
		(end 489.553758 -27.121358)
		(width 0.089408)
		(layer "In9.Cu")
		(net "FM_SLT_CFG2_R")
	)
	(segment
		(start 490.84611 -52.721256)
		(end 493.007904 -50.559462)
		(width 0.089408)
		(layer "In9.Cu")
		(net "FM_SLT_CFG2_R")
	)
	(segment
		(start 482.46538 -17.13738)
		(end 480.108006 -17.13738)
		(width 0.089408)
		(layer "In9.Cu")
		(net "FM_SLT_CFG2_R")
	)
	(segment
		(start 492.89081 -46.52899)
		(end 492.89081 -44.47413)
		(width 0.089408)
		(layer "In9.Cu")
		(net "FM_SLT_CFG2_R")
	)
	(segment
		(start 467.02345 -3.811778)
		(end 465.924646 -3.811778)
		(width 0.089408)
		(layer "In9.Cu")
		(net "FM_SLT_CFG2_R")
	)
	(segment
		(start 494.469928 -41.646094)
		(end 494.469928 -39.947342)
		(width 0.089408)
		(layer "In9.Cu")
		(net "FM_SLT_CFG2_R")
	)
	(segment
		(start 489.553758 -27.121358)
		(end 489.553758 -24.352758)
		(width 0.089408)
		(layer "In9.Cu")
		(net "FM_SLT_CFG2_R")
	)
	(segment
		(start 477.85401 -9.095232)
		(end 475.352618 -9.095232)
		(width 0.089408)
		(layer "In9.Cu")
		(net "FM_SLT_CFG2_R")
	)
	(segment
		(start 468.363046 -5.151374)
		(end 467.02345 -3.811778)
		(width 0.089408)
		(layer "In9.Cu")
		(net "FM_SLT_CFG2_R")
	)
	(segment
		(start 492.786924 -36.806124)
		(end 491.8456 -35.8648)
		(width 0.089408)
		(layer "In9.Cu")
		(net "FM_SLT_CFG2_R")
	)
	(segment
		(start 468.362792 -5.930138)
		(end 468.363046 -5.929884)
		(width 0.089408)
		(layer "In9.Cu")
		(net "FM_SLT_CFG2_R")
	)
	(segment
		(start 488.334304 -23.133304)
		(end 488.334304 -20.222718)
		(width 0.089408)
		(layer "In9.Cu")
		(net "FM_SLT_CFG2_R")
	)
	(segment
		(start 478.85604 -10.097262)
		(end 477.85401 -9.095232)
		(width 0.089408)
		(layer "In9.Cu")
		(net "FM_SLT_CFG2_R")
	)
	(segment
		(start 474.200728 -7.943342)
		(end 469.591644 -7.943342)
		(width 0.089408)
		(layer "In9.Cu")
		(net "FM_SLT_CFG2_R")
	)
	(segment
		(start 489.553758 -24.352758)
		(end 488.334304 -23.133304)
		(width 0.089408)
		(layer "In9.Cu")
		(net "FM_SLT_CFG2_R")
	)
	(segment
		(start 492.89081 -44.47413)
		(end 494.293652 -43.071288)
		(width 0.089408)
		(layer "In9.Cu")
		(net "FM_SLT_CFG2_R")
	)
	(segment
		(start 493.007904 -50.559462)
		(end 493.007904 -46.646084)
		(width 0.089408)
		(layer "In9.Cu")
		(net "FM_SLT_CFG2_R")
	)
	(segment
		(start 489.474256 -52.721256)
		(end 490.84611 -52.721256)
		(width 0.089408)
		(layer "In9.Cu")
		(net "FM_SLT_CFG2_R")
	)
	(segment
		(start 494.469928 -39.947342)
		(end 492.786924 -38.264338)
		(width 0.089408)
		(layer "In9.Cu")
		(net "FM_SLT_CFG2_R")
	)
	(segment
		(start 488.334304 -20.222718)
		(end 485.764586 -17.653)
		(width 0.089408)
		(layer "In9.Cu")
		(net "FM_SLT_CFG2_R")
	)
	(segment
		(start 482.981 -17.653)
		(end 482.46538 -17.13738)
		(width 0.089408)
		(layer "In9.Cu")
		(net "FM_SLT_CFG2_R")
	)
	(segment
		(start 469.591644 -7.943342)
		(end 468.362792 -6.71449)
		(width 0.089408)
		(layer "In9.Cu")
		(net "FM_SLT_CFG2_R")
	)
	(segment
		(start 491.8456 -35.8648)
		(end 491.8456 -29.4132)
		(width 0.089408)
		(layer "In9.Cu")
		(net "FM_SLT_CFG2_R")
	)
	(segment
		(start 478.85604 -15.885414)
		(end 478.85604 -10.097262)
		(width 0.089408)
		(layer "In9.Cu")
		(net "FM_SLT_CFG2_R")
	)
	(segment
		(start 485.764586 -17.653)
		(end 482.981 -17.653)
		(width 0.089408)
		(layer "In9.Cu")
		(net "FM_SLT_CFG2_R")
	)
	(segment
		(start 465.924646 -3.811778)
		(end 465.541868 -3.429)
		(width 0.089408)
		(layer "In9.Cu")
		(net "FM_SLT_CFG2_R")
	)
	(segment
		(start 480.108006 -17.13738)
		(end 478.85604 -15.885414)
		(width 0.089408)
		(layer "In9.Cu")
		(net "FM_SLT_CFG2_R")
	)
	(segment
		(start 468.362792 -6.71449)
		(end 468.362792 -5.930138)
		(width 0.089408)
		(layer "In9.Cu")
		(net "FM_SLT_CFG2_R")
	)
	(segment
		(start 467.0679 -3.34264)
		(end 467.0679 -3.4925)
		(width 0.10795)
		(layer "F.Cu")
		(net "FM_PWRBRK_SLOT_N")
	)
	(segment
		(start 466.879178 -3.681222)
		(end 466.879178 -4.386072)
		(width 0.10795)
		(layer "F.Cu")
		(net "FM_PWRBRK_SLOT_N")
	)
	(segment
		(start 467.0679 -3.4925)
		(end 466.879178 -3.681222)
		(width 0.10795)
		(layer "F.Cu")
		(net "FM_PWRBRK_SLOT_N")
	)
	(via
		(at 466.2424 -3.302)
		(size 0.6604)
		(drill 0.3302)
		(layers "F.Cu" "B.Cu")
		(net "FM_PWRBRK_SLOT_N")
	)
	(via
		(at 467.0679 -3.34264)
		(size 0.508)
		(drill 0.254)
		(layers "F.Cu" "B.Cu")
		(net "FM_PWRBRK_SLOT_N")
	)
	(segment
		(start 467.02726 -3.302)
		(end 467.0679 -3.34264)
		(width 0.10795)
		(layer "B.Cu")
		(net "FM_PWRBRK_SLOT_N")
	)
	(segment
		(start 466.5599 -3.80492)
		(end 466.852 -3.80492)
		(width 0.10795)
		(layer "B.Cu")
		(net "FM_PWRBRK_SLOT_N")
	)
	(segment
		(start 466.852 -3.80492)
		(end 467.0425 -3.99542)
		(width 0.10795)
		(layer "B.Cu")
		(net "FM_PWRBRK_SLOT_N")
	)
	(segment
		(start 466.2424 -3.302)
		(end 466.2424 -3.48742)
		(width 0.10795)
		(layer "B.Cu")
		(net "FM_PWRBRK_SLOT_N")
	)
	(segment
		(start 467.21776 -3.4925)
		(end 467.0679 -3.34264)
		(width 0.10795)
		(layer "B.Cu")
		(net "FM_PWRBRK_SLOT_N")
	)
	(segment
		(start 466.2424 -3.302)
		(end 467.02726 -3.302)
		(width 0.10795)
		(layer "B.Cu")
		(net "FM_PWRBRK_SLOT_N")
	)
	(segment
		(start 467.868 -3.4925)
		(end 467.21776 -3.4925)
		(width 0.10795)
		(layer "B.Cu")
		(net "FM_PWRBRK_SLOT_N")
	)
	(segment
		(start 466.2424 -3.48742)
		(end 466.5599 -3.80492)
		(width 0.10795)
		(layer "B.Cu")
		(net "FM_PWRBRK_SLOT_N")
	)
	(segment
		(start 467.0425 -3.99542)
		(end 467.0425 -4.445)
		(width 0.10795)
		(layer "B.Cu")
		(net "FM_PWRBRK_SLOT_N")
	)
	(segment
		(start 383.27965 -97.83572)
		(end 383.77495 -97.605596)
		(width 0.10795)
		(layer "F.Cu")
		(net "H_CPU1_MEMKLM_MEMHOT_PCH_N")
	)
	(via
		(at 383.77495 -97.605596)
		(size 0.508)
		(drill 0.254)
		(layers "F.Cu" "B.Cu")
		(net "H_CPU1_MEMKLM_MEMHOT_PCH_N")
	)
	(via
		(at 411.7594 -17.6784)
		(size 0.508)
		(drill 0.254)
		(layers "F.Cu" "B.Cu")
		(net "H_CPU1_MEMKLM_MEMHOT_PCH_N")
	)
	(segment
		(start 412.6865 -17.526)
		(end 412.242 -17.526)
		(width 0.10795)
		(layer "B.Cu")
		(net "H_CPU1_MEMKLM_MEMHOT_PCH_N")
	)
	(segment
		(start 412.0896 -17.6784)
		(end 411.7594 -17.6784)
		(width 0.10795)
		(layer "B.Cu")
		(net "H_CPU1_MEMKLM_MEMHOT_PCH_N")
	)
	(segment
		(start 412.242 -17.526)
		(end 412.0896 -17.6784)
		(width 0.10795)
		(layer "B.Cu")
		(net "H_CPU1_MEMKLM_MEMHOT_PCH_N")
	)
	(segment
		(start 391.013696 -66.686938)
		(end 391.013696 -68.62445)
		(width 0.089408)
		(layer "In9.Cu")
		(net "H_CPU1_MEMKLM_MEMHOT_PCH_N")
	)
	(segment
		(start 383.6797 -96.7359)
		(end 383.6797 -96.768666)
		(width 0.0889)
		(layer "In9.Cu")
		(net "H_CPU1_MEMKLM_MEMHOT_PCH_N")
	)
	(segment
		(start 393.469114 -33.357058)
		(end 393.469114 -34.106358)
		(width 0.089408)
		(layer "In9.Cu")
		(net "H_CPU1_MEMKLM_MEMHOT_PCH_N")
	)
	(segment
		(start 384.321304 -87.965788)
		(end 383.39395 -88.893142)
		(width 0.0889)
		(layer "In9.Cu")
		(net "H_CPU1_MEMKLM_MEMHOT_PCH_N")
	)
	(segment
		(start 390.925304 -75.018392)
		(end 388.874254 -77.069442)
		(width 0.089408)
		(layer "In9.Cu")
		(net "H_CPU1_MEMKLM_MEMHOT_PCH_N")
	)
	(segment
		(start 389.1534 -79.371444)
		(end 389.1534 -81.459832)
		(width 0.089408)
		(layer "In9.Cu")
		(net "H_CPU1_MEMKLM_MEMHOT_PCH_N")
	)
	(segment
		(start 391.013696 -68.62445)
		(end 391.24636 -68.857114)
		(width 0.089408)
		(layer "In9.Cu")
		(net "H_CPU1_MEMKLM_MEMHOT_PCH_N")
	)
	(segment
		(start 393.060936 -64.639698)
		(end 391.013696 -66.686938)
		(width 0.089408)
		(layer "In9.Cu")
		(net "H_CPU1_MEMKLM_MEMHOT_PCH_N")
	)
	(segment
		(start 390.851898 -72.110346)
		(end 390.851898 -73.963022)
		(width 0.089408)
		(layer "In9.Cu")
		(net "H_CPU1_MEMKLM_MEMHOT_PCH_N")
	)
	(segment
		(start 385.683252 -86.60384)
		(end 384.321304 -87.965788)
		(width 0.089408)
		(layer "In9.Cu")
		(net "H_CPU1_MEMKLM_MEMHOT_PCH_N")
	)
	(segment
		(start 394.506958 -36.07181)
		(end 394.506958 -37.954204)
		(width 0.089408)
		(layer "In9.Cu")
		(net "H_CPU1_MEMKLM_MEMHOT_PCH_N")
	)
	(segment
		(start 388.967726 -84.235798)
		(end 387.59511 -85.608414)
		(width 0.089408)
		(layer "In9.Cu")
		(net "H_CPU1_MEMKLM_MEMHOT_PCH_N")
	)
	(segment
		(start 393.940538 -44.983908)
		(end 393.940538 -49.548542)
		(width 0.089408)
		(layer "In9.Cu")
		(net "H_CPU1_MEMKLM_MEMHOT_PCH_N")
	)
	(segment
		(start 394.424154 -24.36368)
		(end 394.424154 -29.879036)
		(width 0.089408)
		(layer "In9.Cu")
		(net "H_CPU1_MEMKLM_MEMHOT_PCH_N")
	)
	(segment
		(start 390.851898 -73.963022)
		(end 390.925304 -74.036428)
		(width 0.089408)
		(layer "In9.Cu")
		(net "H_CPU1_MEMKLM_MEMHOT_PCH_N")
	)
	(segment
		(start 391.24636 -68.857114)
		(end 391.24636 -71.715884)
		(width 0.089408)
		(layer "In9.Cu")
		(net "H_CPU1_MEMKLM_MEMHOT_PCH_N")
	)
	(segment
		(start 394.424154 -29.879036)
		(end 393.575032 -30.728158)
		(width 0.089408)
		(layer "In9.Cu")
		(net "H_CPU1_MEMKLM_MEMHOT_PCH_N")
	)
	(segment
		(start 394.012928 -53.689504)
		(end 394.012928 -62.314328)
		(width 0.089408)
		(layer "In9.Cu")
		(net "H_CPU1_MEMKLM_MEMHOT_PCH_N")
	)
	(segment
		(start 403.039834 -21.863304)
		(end 402.425916 -21.249386)
		(width 0.089408)
		(layer "In9.Cu")
		(net "H_CPU1_MEMKLM_MEMHOT_PCH_N")
	)
	(segment
		(start 394.506958 -37.954204)
		(end 395.535404 -38.98265)
		(width 0.089408)
		(layer "In9.Cu")
		(net "H_CPU1_MEMKLM_MEMHOT_PCH_N")
	)
	(segment
		(start 383.39395 -89.22512)
		(end 383.44348 -89.27465)
		(width 0.0889)
		(layer "In9.Cu")
		(net "H_CPU1_MEMKLM_MEMHOT_PCH_N")
	)
	(segment
		(start 401.956016 -21.249386)
		(end 401.29079 -20.58416)
		(width 0.089408)
		(layer "In9.Cu")
		(net "H_CPU1_MEMKLM_MEMHOT_PCH_N")
	)
	(segment
		(start 395.535658 -42.332148)
		(end 394.757656 -43.11015)
		(width 0.089408)
		(layer "In9.Cu")
		(net "H_CPU1_MEMKLM_MEMHOT_PCH_N")
	)
	(segment
		(start 395.535658 -41.278556)
		(end 395.535658 -42.332148)
		(width 0.089408)
		(layer "In9.Cu")
		(net "H_CPU1_MEMKLM_MEMHOT_PCH_N")
	)
	(segment
		(start 383.39395 -88.893142)
		(end 383.39395 -89.22512)
		(width 0.0889)
		(layer "In9.Cu")
		(net "H_CPU1_MEMKLM_MEMHOT_PCH_N")
	)
	(segment
		(start 393.629642 -43.456352)
		(end 393.629642 -44.673012)
		(width 0.089408)
		(layer "In9.Cu")
		(net "H_CPU1_MEMKLM_MEMHOT_PCH_N")
	)
	(segment
		(start 393.629642 -44.673012)
		(end 393.940538 -44.983908)
		(width 0.089408)
		(layer "In9.Cu")
		(net "H_CPU1_MEMKLM_MEMHOT_PCH_N")
	)
	(segment
		(start 393.575032 -33.25114)
		(end 393.469114 -33.357058)
		(width 0.089408)
		(layer "In9.Cu")
		(net "H_CPU1_MEMKLM_MEMHOT_PCH_N")
	)
	(segment
		(start 401.29079 -20.58416)
		(end 398.203674 -20.58416)
		(width 0.089408)
		(layer "In9.Cu")
		(net "H_CPU1_MEMKLM_MEMHOT_PCH_N")
	)
	(segment
		(start 388.437374 -82.175858)
		(end 388.437374 -82.898234)
		(width 0.089408)
		(layer "In9.Cu")
		(net "H_CPU1_MEMKLM_MEMHOT_PCH_N")
	)
	(segment
		(start 388.874254 -77.069442)
		(end 388.874254 -79.092298)
		(width 0.089408)
		(layer "In9.Cu")
		(net "H_CPU1_MEMKLM_MEMHOT_PCH_N")
	)
	(segment
		(start 394.757656 -43.11015)
		(end 393.975844 -43.11015)
		(width 0.089408)
		(layer "In9.Cu")
		(net "H_CPU1_MEMKLM_MEMHOT_PCH_N")
	)
	(segment
		(start 388.874254 -79.092298)
		(end 389.1534 -79.371444)
		(width 0.089408)
		(layer "In9.Cu")
		(net "H_CPU1_MEMKLM_MEMHOT_PCH_N")
	)
	(segment
		(start 407.518108 -21.14931)
		(end 407.518108 -21.419058)
		(width 0.089408)
		(layer "In9.Cu")
		(net "H_CPU1_MEMKLM_MEMHOT_PCH_N")
	)
	(segment
		(start 383.1844 -94.5896)
		(end 383.1844 -95.910146)
		(width 0.0889)
		(layer "In9.Cu")
		(net "H_CPU1_MEMKLM_MEMHOT_PCH_N")
	)
	(segment
		(start 391.24636 -71.715884)
		(end 390.851898 -72.110346)
		(width 0.089408)
		(layer "In9.Cu")
		(net "H_CPU1_MEMKLM_MEMHOT_PCH_N")
	)
	(segment
		(start 393.575032 -30.728158)
		(end 393.575032 -33.25114)
		(width 0.089408)
		(layer "In9.Cu")
		(net "H_CPU1_MEMKLM_MEMHOT_PCH_N")
	)
	(segment
		(start 383.44348 -91.671394)
		(end 383.642616 -91.87053)
		(width 0.0889)
		(layer "In9.Cu")
		(net "H_CPU1_MEMKLM_MEMHOT_PCH_N")
	)
	(segment
		(start 395.535404 -41.278302)
		(end 395.535658 -41.278556)
		(width 0.089408)
		(layer "In9.Cu")
		(net "H_CPU1_MEMKLM_MEMHOT_PCH_N")
	)
	(segment
		(start 398.203674 -20.58416)
		(end 394.424154 -24.36368)
		(width 0.089408)
		(layer "In9.Cu")
		(net "H_CPU1_MEMKLM_MEMHOT_PCH_N")
	)
	(segment
		(start 390.925304 -74.036428)
		(end 390.925304 -75.018392)
		(width 0.089408)
		(layer "In9.Cu")
		(net "H_CPU1_MEMKLM_MEMHOT_PCH_N")
	)
	(segment
		(start 387.59511 -85.608414)
		(end 386.443728 -85.608414)
		(width 0.089408)
		(layer "In9.Cu")
		(net "H_CPU1_MEMKLM_MEMHOT_PCH_N")
	)
	(segment
		(start 393.575032 -35.139884)
		(end 394.506958 -36.07181)
		(width 0.089408)
		(layer "In9.Cu")
		(net "H_CPU1_MEMKLM_MEMHOT_PCH_N")
	)
	(segment
		(start 411.7594 -17.6784)
		(end 411.418786 -17.6784)
		(width 0.089408)
		(layer "In9.Cu")
		(net "H_CPU1_MEMKLM_MEMHOT_PCH_N")
	)
	(segment
		(start 393.575032 -34.212276)
		(end 393.575032 -35.139884)
		(width 0.089408)
		(layer "In9.Cu")
		(net "H_CPU1_MEMKLM_MEMHOT_PCH_N")
	)
	(segment
		(start 385.683252 -86.36889)
		(end 385.683252 -86.60384)
		(width 0.089408)
		(layer "In9.Cu")
		(net "H_CPU1_MEMKLM_MEMHOT_PCH_N")
	)
	(segment
		(start 393.469114 -34.106358)
		(end 393.575032 -34.212276)
		(width 0.089408)
		(layer "In9.Cu")
		(net "H_CPU1_MEMKLM_MEMHOT_PCH_N")
	)
	(segment
		(start 383.44348 -89.27465)
		(end 383.44348 -91.671394)
		(width 0.0889)
		(layer "In9.Cu")
		(net "H_CPU1_MEMKLM_MEMHOT_PCH_N")
	)
	(segment
		(start 393.940538 -49.548542)
		(end 394.022326 -49.63033)
		(width 0.089408)
		(layer "In9.Cu")
		(net "H_CPU1_MEMKLM_MEMHOT_PCH_N")
	)
	(segment
		(start 383.642616 -94.131384)
		(end 383.1844 -94.5896)
		(width 0.0889)
		(layer "In9.Cu")
		(net "H_CPU1_MEMKLM_MEMHOT_PCH_N")
	)
	(segment
		(start 408.612086 -20.4851)
		(end 408.182318 -20.4851)
		(width 0.089408)
		(layer "In9.Cu")
		(net "H_CPU1_MEMKLM_MEMHOT_PCH_N")
	)
	(segment
		(start 393.250674 -50.912268)
		(end 393.250674 -52.92725)
		(width 0.089408)
		(layer "In9.Cu")
		(net "H_CPU1_MEMKLM_MEMHOT_PCH_N")
	)
	(segment
		(start 393.060936 -63.26632)
		(end 393.060936 -64.639698)
		(width 0.089408)
		(layer "In9.Cu")
		(net "H_CPU1_MEMKLM_MEMHOT_PCH_N")
	)
	(segment
		(start 386.443728 -85.608414)
		(end 385.683252 -86.36889)
		(width 0.089408)
		(layer "In9.Cu")
		(net "H_CPU1_MEMKLM_MEMHOT_PCH_N")
	)
	(segment
		(start 389.1534 -81.459832)
		(end 388.437374 -82.175858)
		(width 0.089408)
		(layer "In9.Cu")
		(net "H_CPU1_MEMKLM_MEMHOT_PCH_N")
	)
	(segment
		(start 394.012928 -62.314328)
		(end 393.060936 -63.26632)
		(width 0.089408)
		(layer "In9.Cu")
		(net "H_CPU1_MEMKLM_MEMHOT_PCH_N")
	)
	(segment
		(start 393.975844 -43.11015)
		(end 393.629642 -43.456352)
		(width 0.089408)
		(layer "In9.Cu")
		(net "H_CPU1_MEMKLM_MEMHOT_PCH_N")
	)
	(segment
		(start 394.022326 -49.63033)
		(end 394.022326 -50.140616)
		(width 0.089408)
		(layer "In9.Cu")
		(net "H_CPU1_MEMKLM_MEMHOT_PCH_N")
	)
	(segment
		(start 407.518108 -21.419058)
		(end 407.073862 -21.863304)
		(width 0.089408)
		(layer "In9.Cu")
		(net "H_CPU1_MEMKLM_MEMHOT_PCH_N")
	)
	(segment
		(start 394.022326 -50.140616)
		(end 393.250674 -50.912268)
		(width 0.089408)
		(layer "In9.Cu")
		(net "H_CPU1_MEMKLM_MEMHOT_PCH_N")
	)
	(segment
		(start 402.425916 -21.249386)
		(end 401.956016 -21.249386)
		(width 0.089408)
		(layer "In9.Cu")
		(net "H_CPU1_MEMKLM_MEMHOT_PCH_N")
	)
	(segment
		(start 395.535404 -38.98265)
		(end 395.535404 -41.278302)
		(width 0.089408)
		(layer "In9.Cu")
		(net "H_CPU1_MEMKLM_MEMHOT_PCH_N")
	)
	(segment
		(start 388.967726 -83.428586)
		(end 388.967726 -84.235798)
		(width 0.089408)
		(layer "In9.Cu")
		(net "H_CPU1_MEMKLM_MEMHOT_PCH_N")
	)
	(segment
		(start 408.182318 -20.4851)
		(end 407.518108 -21.14931)
		(width 0.089408)
		(layer "In9.Cu")
		(net "H_CPU1_MEMKLM_MEMHOT_PCH_N")
	)
	(segment
		(start 411.418786 -17.6784)
		(end 408.612086 -20.4851)
		(width 0.089408)
		(layer "In9.Cu")
		(net "H_CPU1_MEMKLM_MEMHOT_PCH_N")
	)
	(segment
		(start 407.073862 -21.863304)
		(end 403.039834 -21.863304)
		(width 0.089408)
		(layer "In9.Cu")
		(net "H_CPU1_MEMKLM_MEMHOT_PCH_N")
	)
	(segment
		(start 383.642616 -91.87053)
		(end 383.642616 -94.131384)
		(width 0.0889)
		(layer "In9.Cu")
		(net "H_CPU1_MEMKLM_MEMHOT_PCH_N")
	)
	(segment
		(start 393.250674 -52.92725)
		(end 394.012928 -53.689504)
		(width 0.089408)
		(layer "In9.Cu")
		(net "H_CPU1_MEMKLM_MEMHOT_PCH_N")
	)
	(segment
		(start 388.437374 -82.898234)
		(end 388.967726 -83.428586)
		(width 0.089408)
		(layer "In9.Cu")
		(net "H_CPU1_MEMKLM_MEMHOT_PCH_N")
	)
	(arc
		(start 383.6797 -96.768666)
		(mid 383.703588 -97.189833)
		(end 383.77495 -97.605596)
		(width 0.0889)
		(layer "In9.Cu")
		(net "H_CPU1_MEMKLM_MEMHOT_PCH_N")
	)
	(arc
		(start 383.1844 -95.910146)
		(mid 383.268681 -96.193363)
		(end 383.479548 -96.400366)
		(width 0.0889)
		(layer "In9.Cu")
		(net "H_CPU1_MEMKLM_MEMHOT_PCH_N")
	)
	(arc
		(start 383.479548 -96.400366)
		(mid 383.623352 -96.542049)
		(end 383.6797 -96.7359)
		(width 0.0889)
		(layer "In9.Cu")
		(net "H_CPU1_MEMKLM_MEMHOT_PCH_N")
	)
	(segment
		(start 383.77495 -98.69424)
		(end 384.27025 -98.464116)
		(width 0.10795)
		(layer "F.Cu")
		(net "H_CPU1_MEMGHJ_MEMHOT_PCH_N")
	)
	(via
		(at 382.9812 -93.1164)
		(size 0.6604)
		(drill 0.3302)
		(layers "F.Cu" "B.Cu")
		(net "H_CPU1_MEMGHJ_MEMHOT_PCH_N")
	)
	(via
		(at 384.27025 -98.464116)
		(size 0.508)
		(drill 0.254)
		(layers "F.Cu" "B.Cu")
		(net "H_CPU1_MEMGHJ_MEMHOT_PCH_N")
	)
	(segment
		(start 383.8702 -98.442526)
		(end 383.8702 -98.475292)
		(width 0.0889)
		(layer "B.Cu")
		(net "H_CPU1_MEMGHJ_MEMHOT_PCH_N")
	)
	(segment
		(start 382.9812 -93.1164)
		(end 382.9812 -94.919292)
		(width 0.10795)
		(layer "B.Cu")
		(net "H_CPU1_MEMGHJ_MEMHOT_PCH_N")
	)
	(segment
		(start 383.60096 -82.39252)
		(end 383.2606 -82.73288)
		(width 0.10795)
		(layer "B.Cu")
		(net "H_CPU1_MEMGHJ_MEMHOT_PCH_N")
	)
	(segment
		(start 383.86258 -85.60308)
		(end 383.29235 -86.17331)
		(width 0.10795)
		(layer "B.Cu")
		(net "H_CPU1_MEMGHJ_MEMHOT_PCH_N")
	)
	(segment
		(start 383.29235 -88.613996)
		(end 383.109724 -88.796622)
		(width 0.10795)
		(layer "B.Cu")
		(net "H_CPU1_MEMGHJ_MEMHOT_PCH_N")
	)
	(segment
		(start 383.50698 -84.40674)
		(end 383.71907 -84.40674)
		(width 0.10795)
		(layer "B.Cu")
		(net "H_CPU1_MEMGHJ_MEMHOT_PCH_N")
	)
	(segment
		(start 383.2606 -84.16036)
		(end 383.50698 -84.40674)
		(width 0.10795)
		(layer "B.Cu")
		(net "H_CPU1_MEMGHJ_MEMHOT_PCH_N")
	)
	(segment
		(start 384.0226 -98.778314)
		(end 384.10134 -98.757232)
		(width 0.0889)
		(layer "B.Cu")
		(net "H_CPU1_MEMGHJ_MEMHOT_PCH_N")
	)
	(segment
		(start 383.160778 -95.09887)
		(end 383.3749 -95.312992)
		(width 0.0889)
		(layer "B.Cu")
		(net "H_CPU1_MEMGHJ_MEMHOT_PCH_N")
	)
	(segment
		(start 383.29235 -86.17331)
		(end 383.29235 -88.613996)
		(width 0.10795)
		(layer "B.Cu")
		(net "H_CPU1_MEMGHJ_MEMHOT_PCH_N")
	)
	(segment
		(start 387.77164 -81.39684)
		(end 386.77596 -82.39252)
		(width 0.10795)
		(layer "B.Cu")
		(net "H_CPU1_MEMGHJ_MEMHOT_PCH_N")
	)
	(segment
		(start 383.109724 -88.796622)
		(end 383.109724 -89.358724)
		(width 0.10795)
		(layer "B.Cu")
		(net "H_CPU1_MEMGHJ_MEMHOT_PCH_N")
	)
	(segment
		(start 383.286 -91.8464)
		(end 382.9812 -92.1512)
		(width 0.10795)
		(layer "B.Cu")
		(net "H_CPU1_MEMGHJ_MEMHOT_PCH_N")
	)
	(segment
		(start 383.86258 -84.55025)
		(end 383.86258 -85.60308)
		(width 0.10795)
		(layer "B.Cu")
		(net "H_CPU1_MEMGHJ_MEMHOT_PCH_N")
	)
	(segment
		(start 384.10134 -98.757232)
		(end 384.27025 -98.464116)
		(width 0.0889)
		(layer "B.Cu")
		(net "H_CPU1_MEMGHJ_MEMHOT_PCH_N")
	)
	(segment
		(start 382.8796 -96.7359)
		(end 382.8796 -96.758252)
		(width 0.0889)
		(layer "B.Cu")
		(net "H_CPU1_MEMGHJ_MEMHOT_PCH_N")
	)
	(segment
		(start 383.3749 -97.584006)
		(end 383.3749 -97.616772)
		(width 0.0889)
		(layer "B.Cu")
		(net "H_CPU1_MEMGHJ_MEMHOT_PCH_N")
	)
	(segment
		(start 383.2606 -82.73288)
		(end 383.2606 -84.16036)
		(width 0.10795)
		(layer "B.Cu")
		(net "H_CPU1_MEMGHJ_MEMHOT_PCH_N")
	)
	(segment
		(start 387.77164 -80.2386)
		(end 387.77164 -81.39684)
		(width 0.10795)
		(layer "B.Cu")
		(net "H_CPU1_MEMGHJ_MEMHOT_PCH_N")
	)
	(segment
		(start 382.9812 -94.919292)
		(end 383.160778 -95.09887)
		(width 0.10795)
		(layer "B.Cu")
		(net "H_CPU1_MEMGHJ_MEMHOT_PCH_N")
	)
	(segment
		(start 382.9812 -92.1512)
		(end 382.9812 -93.1164)
		(width 0.10795)
		(layer "B.Cu")
		(net "H_CPU1_MEMGHJ_MEMHOT_PCH_N")
	)
	(segment
		(start 383.109724 -89.358724)
		(end 383.286 -89.535)
		(width 0.10795)
		(layer "B.Cu")
		(net "H_CPU1_MEMGHJ_MEMHOT_PCH_N")
	)
	(segment
		(start 383.286 -89.535)
		(end 383.286 -91.8464)
		(width 0.10795)
		(layer "B.Cu")
		(net "H_CPU1_MEMGHJ_MEMHOT_PCH_N")
	)
	(segment
		(start 386.77596 -82.39252)
		(end 383.60096 -82.39252)
		(width 0.10795)
		(layer "B.Cu")
		(net "H_CPU1_MEMGHJ_MEMHOT_PCH_N")
	)
	(segment
		(start 383.71907 -84.40674)
		(end 383.86258 -84.55025)
		(width 0.10795)
		(layer "B.Cu")
		(net "H_CPU1_MEMGHJ_MEMHOT_PCH_N")
	)
	(segment
		(start 383.3749 -95.312992)
		(end 383.3749 -95.910146)
		(width 0.0889)
		(layer "B.Cu")
		(net "H_CPU1_MEMGHJ_MEMHOT_PCH_N")
	)
	(arc
		(start 383.3749 -95.910146)
		(mid 383.290619 -96.193363)
		(end 383.079752 -96.400366)
		(width 0.0889)
		(layer "B.Cu")
		(net "H_CPU1_MEMGHJ_MEMHOT_PCH_N")
	)
	(arc
		(start 383.3749 -97.616772)
		(mid 383.43125 -97.810622)
		(end 383.575052 -97.952306)
		(width 0.0889)
		(layer "B.Cu")
		(net "H_CPU1_MEMGHJ_MEMHOT_PCH_N")
	)
	(arc
		(start 383.8702 -98.475292)
		(mid 383.912733 -98.643729)
		(end 384.0226 -98.778314)
		(width 0.0889)
		(layer "B.Cu")
		(net "H_CPU1_MEMGHJ_MEMHOT_PCH_N")
	)
	(arc
		(start 382.8796 -96.758252)
		(mid 382.93595 -96.952102)
		(end 383.079752 -97.093786)
		(width 0.0889)
		(layer "B.Cu")
		(net "H_CPU1_MEMGHJ_MEMHOT_PCH_N")
	)
	(arc
		(start 383.079752 -96.400366)
		(mid 382.935948 -96.542049)
		(end 382.8796 -96.7359)
		(width 0.0889)
		(layer "B.Cu")
		(net "H_CPU1_MEMGHJ_MEMHOT_PCH_N")
	)
	(arc
		(start 383.575052 -97.952306)
		(mid 383.785916 -98.15931)
		(end 383.8702 -98.442526)
		(width 0.0889)
		(layer "B.Cu")
		(net "H_CPU1_MEMGHJ_MEMHOT_PCH_N")
	)
	(arc
		(start 383.079752 -97.093786)
		(mid 383.290616 -97.30079)
		(end 383.3749 -97.584006)
		(width 0.0889)
		(layer "B.Cu")
		(net "H_CPU1_MEMGHJ_MEMHOT_PCH_N")
	)
	(segment
		(start 384.76555 -98.69424)
		(end 385.26085 -98.464116)
		(width 0.10795)
		(layer "F.Cu")
		(net "H_CPU0_MEMDEF_MEMHOT_PCH_N")
	)
	(via
		(at 421.435784 -17.853914)
		(size 0.508)
		(drill 0.254)
		(layers "F.Cu" "B.Cu")
		(net "H_CPU0_MEMDEF_MEMHOT_PCH_N")
	)
	(via
		(at 423.132504 -15.899384)
		(size 0.6604)
		(drill 0.3302)
		(layers "F.Cu" "B.Cu")
		(net "H_CPU0_MEMDEF_MEMHOT_PCH_N")
	)
	(via
		(at 385.26085 -98.464116)
		(size 0.508)
		(drill 0.254)
		(layers "F.Cu" "B.Cu")
		(net "H_CPU0_MEMDEF_MEMHOT_PCH_N")
	)
	(segment
		(start 421.435784 -17.596104)
		(end 423.132504 -15.899384)
		(width 0.10795)
		(layer "B.Cu")
		(net "H_CPU0_MEMDEF_MEMHOT_PCH_N")
	)
	(segment
		(start 423.132504 -15.899384)
		(end 423.969688 -15.0622)
		(width 0.10795)
		(layer "B.Cu")
		(net "H_CPU0_MEMDEF_MEMHOT_PCH_N")
	)
	(segment
		(start 423.969688 -15.0622)
		(end 424.6118 -15.0622)
		(width 0.10795)
		(layer "B.Cu")
		(net "H_CPU0_MEMDEF_MEMHOT_PCH_N")
	)
	(segment
		(start 421.435784 -17.853914)
		(end 421.435784 -17.596104)
		(width 0.10795)
		(layer "B.Cu")
		(net "H_CPU0_MEMDEF_MEMHOT_PCH_N")
	)
	(segment
		(start 389.750554 -76.560426)
		(end 389.750554 -77.679042)
		(width 0.089408)
		(layer "In9.Cu")
		(net "H_CPU0_MEMDEF_MEMHOT_PCH_N")
	)
	(segment
		(start 393.82065 -44.593764)
		(end 394.131546 -44.90466)
		(width 0.089408)
		(layer "In9.Cu")
		(net "H_CPU0_MEMDEF_MEMHOT_PCH_N")
	)
	(segment
		(start 383.8702 -96.725486)
		(end 383.8702 -96.758252)
		(width 0.0889)
		(layer "In9.Cu")
		(net "H_CPU0_MEMDEF_MEMHOT_PCH_N")
	)
	(segment
		(start 393.441682 -50.991516)
		(end 393.441682 -52.848002)
		(width 0.089408)
		(layer "In9.Cu")
		(net "H_CPU0_MEMDEF_MEMHOT_PCH_N")
	)
	(segment
		(start 391.204704 -75.106276)
		(end 389.750554 -76.560426)
		(width 0.089408)
		(layer "In9.Cu")
		(net "H_CPU0_MEMDEF_MEMHOT_PCH_N")
	)
	(segment
		(start 394.055092 -43.301158)
		(end 393.82065 -43.5356)
		(width 0.089408)
		(layer "In9.Cu")
		(net "H_CPU0_MEMDEF_MEMHOT_PCH_N")
	)
	(segment
		(start 402.81352 -22.094952)
		(end 402.306282 -21.587714)
		(width 0.089408)
		(layer "In9.Cu")
		(net "H_CPU0_MEMDEF_MEMHOT_PCH_N")
	)
	(segment
		(start 391.437368 -71.795132)
		(end 391.042906 -72.189594)
		(width 0.089408)
		(layer "In9.Cu")
		(net "H_CPU0_MEMDEF_MEMHOT_PCH_N")
	)
	(segment
		(start 389.344408 -79.292196)
		(end 389.344408 -81.53908)
		(width 0.089408)
		(layer "In9.Cu")
		(net "H_CPU0_MEMDEF_MEMHOT_PCH_N")
	)
	(segment
		(start 388.628382 -82.255106)
		(end 388.628382 -82.818986)
		(width 0.089408)
		(layer "In9.Cu")
		(net "H_CPU0_MEMDEF_MEMHOT_PCH_N")
	)
	(segment
		(start 394.006324 -33.190688)
		(end 393.660122 -33.53689)
		(width 0.089408)
		(layer "In9.Cu")
		(net "H_CPU0_MEMDEF_MEMHOT_PCH_N")
	)
	(segment
		(start 384.3655 -97.584006)
		(end 384.3655 -97.616772)
		(width 0.0889)
		(layer "In9.Cu")
		(net "H_CPU0_MEMDEF_MEMHOT_PCH_N")
	)
	(segment
		(start 383.83337 -91.791282)
		(end 383.83337 -94.384622)
		(width 0.089408)
		(layer "In9.Cu")
		(net "H_CPU0_MEMDEF_MEMHOT_PCH_N")
	)
	(segment
		(start 384.25628 -88.36787)
		(end 384.25628 -89.18194)
		(width 0.089408)
		(layer "In9.Cu")
		(net "H_CPU0_MEMDEF_MEMHOT_PCH_N")
	)
	(segment
		(start 396.208504 -32.934148)
		(end 395.944344 -33.198308)
		(width 0.089408)
		(layer "In9.Cu")
		(net "H_CPU0_MEMDEF_MEMHOT_PCH_N")
	)
	(segment
		(start 407.709116 -21.537422)
		(end 407.151586 -22.094952)
		(width 0.089408)
		(layer "In9.Cu")
		(net "H_CPU0_MEMDEF_MEMHOT_PCH_N")
	)
	(segment
		(start 411.322266 -18.273268)
		(end 408.919426 -20.676108)
		(width 0.089408)
		(layer "In9.Cu")
		(net "H_CPU0_MEMDEF_MEMHOT_PCH_N")
	)
	(segment
		(start 393.660122 -34.02711)
		(end 394.378688 -34.745676)
		(width 0.089408)
		(layer "In9.Cu")
		(net "H_CPU0_MEMDEF_MEMHOT_PCH_N")
	)
	(segment
		(start 389.344408 -81.53908)
		(end 388.628382 -82.255106)
		(width 0.089408)
		(layer "In9.Cu")
		(net "H_CPU0_MEMDEF_MEMHOT_PCH_N")
	)
	(segment
		(start 395.726666 -42.411396)
		(end 394.836904 -43.301158)
		(width 0.089408)
		(layer "In9.Cu")
		(net "H_CPU0_MEMDEF_MEMHOT_PCH_N")
	)
	(segment
		(start 389.065262 -78.364334)
		(end 389.065262 -79.01305)
		(width 0.089408)
		(layer "In9.Cu")
		(net "H_CPU0_MEMDEF_MEMHOT_PCH_N")
	)
	(segment
		(start 394.697966 -37.874956)
		(end 395.726412 -38.903402)
		(width 0.089408)
		(layer "In9.Cu")
		(net "H_CPU0_MEMDEF_MEMHOT_PCH_N")
	)
	(segment
		(start 395.726412 -41.199054)
		(end 395.726666 -41.199308)
		(width 0.089408)
		(layer "In9.Cu")
		(net "H_CPU0_MEMDEF_MEMHOT_PCH_N")
	)
	(segment
		(start 394.504164 -33.198308)
		(end 394.496544 -33.190688)
		(width 0.089408)
		(layer "In9.Cu")
		(net "H_CPU0_MEMDEF_MEMHOT_PCH_N")
	)
	(segment
		(start 393.441682 -52.848002)
		(end 394.203936 -53.610256)
		(width 0.089408)
		(layer "In9.Cu")
		(net "H_CPU0_MEMDEF_MEMHOT_PCH_N")
	)
	(segment
		(start 383.634234 -89.803986)
		(end 383.634234 -91.592146)
		(width 0.089408)
		(layer "In9.Cu")
		(net "H_CPU0_MEMDEF_MEMHOT_PCH_N")
	)
	(segment
		(start 384.922776 -98.464116)
		(end 385.26085 -98.464116)
		(width 0.0889)
		(layer "In9.Cu")
		(net "H_CPU0_MEMDEF_MEMHOT_PCH_N")
	)
	(segment
		(start 389.750554 -77.679042)
		(end 389.065262 -78.364334)
		(width 0.089408)
		(layer "In9.Cu")
		(net "H_CPU0_MEMDEF_MEMHOT_PCH_N")
	)
	(segment
		(start 394.131546 -44.90466)
		(end 394.131546 -49.469294)
		(width 0.089408)
		(layer "In9.Cu")
		(net "H_CPU0_MEMDEF_MEMHOT_PCH_N")
	)
	(segment
		(start 388.628382 -82.818986)
		(end 389.158734 -83.349338)
		(width 0.089408)
		(layer "In9.Cu")
		(net "H_CPU0_MEMDEF_MEMHOT_PCH_N")
	)
	(segment
		(start 412.213806 -18.273268)
		(end 411.322266 -18.273268)
		(width 0.089408)
		(layer "In9.Cu")
		(net "H_CPU0_MEMDEF_MEMHOT_PCH_N")
	)
	(segment
		(start 394.378688 -35.55111)
		(end 394.697966 -35.870388)
		(width 0.089408)
		(layer "In9.Cu")
		(net "H_CPU0_MEMDEF_MEMHOT_PCH_N")
	)
	(segment
		(start 408.261566 -20.676108)
		(end 407.709116 -21.228558)
		(width 0.089408)
		(layer "In9.Cu")
		(net "H_CPU0_MEMDEF_MEMHOT_PCH_N")
	)
	(segment
		(start 396.450312 -31.10611)
		(end 396.208504 -31.347918)
		(width 0.089408)
		(layer "In9.Cu")
		(net "H_CPU0_MEMDEF_MEMHOT_PCH_N")
	)
	(segment
		(start 407.709116 -21.228558)
		(end 407.709116 -21.537422)
		(width 0.089408)
		(layer "In9.Cu")
		(net "H_CPU0_MEMDEF_MEMHOT_PCH_N")
	)
	(segment
		(start 394.697966 -35.870388)
		(end 394.697966 -37.874956)
		(width 0.089408)
		(layer "In9.Cu")
		(net "H_CPU0_MEMDEF_MEMHOT_PCH_N")
	)
	(segment
		(start 389.158734 -84.315046)
		(end 387.674358 -85.799422)
		(width 0.089408)
		(layer "In9.Cu")
		(net "H_CPU0_MEMDEF_MEMHOT_PCH_N")
	)
	(segment
		(start 391.437368 -70.685152)
		(end 391.437368 -71.795132)
		(width 0.089408)
		(layer "In9.Cu")
		(net "H_CPU0_MEMDEF_MEMHOT_PCH_N")
	)
	(segment
		(start 394.836904 -43.301158)
		(end 394.055092 -43.301158)
		(width 0.089408)
		(layer "In9.Cu")
		(net "H_CPU0_MEMDEF_MEMHOT_PCH_N")
	)
	(segment
		(start 401.042632 -20.775168)
		(end 398.528286 -20.775168)
		(width 0.089408)
		(layer "In9.Cu")
		(net "H_CPU0_MEMDEF_MEMHOT_PCH_N")
	)
	(segment
		(start 395.726666 -41.199308)
		(end 395.726666 -42.411396)
		(width 0.089408)
		(layer "In9.Cu")
		(net "H_CPU0_MEMDEF_MEMHOT_PCH_N")
	)
	(segment
		(start 385.87426 -86.448138)
		(end 385.87426 -86.74989)
		(width 0.089408)
		(layer "In9.Cu")
		(net "H_CPU0_MEMDEF_MEMHOT_PCH_N")
	)
	(segment
		(start 394.131546 -49.469294)
		(end 394.29436 -49.632108)
		(width 0.089408)
		(layer "In9.Cu")
		(net "H_CPU0_MEMDEF_MEMHOT_PCH_N")
	)
	(segment
		(start 398.528286 -20.775168)
		(end 396.450312 -22.853142)
		(width 0.089408)
		(layer "In9.Cu")
		(net "H_CPU0_MEMDEF_MEMHOT_PCH_N")
	)
	(segment
		(start 383.3749 -94.843092)
		(end 383.3749 -95.899732)
		(width 0.0889)
		(layer "In9.Cu")
		(net "H_CPU0_MEMDEF_MEMHOT_PCH_N")
	)
	(segment
		(start 407.151586 -22.094952)
		(end 402.81352 -22.094952)
		(width 0.089408)
		(layer "In9.Cu")
		(net "H_CPU0_MEMDEF_MEMHOT_PCH_N")
	)
	(segment
		(start 394.29436 -49.632108)
		(end 394.29436 -50.138838)
		(width 0.089408)
		(layer "In9.Cu")
		(net "H_CPU0_MEMDEF_MEMHOT_PCH_N")
	)
	(segment
		(start 408.919426 -20.676108)
		(end 408.261566 -20.676108)
		(width 0.089408)
		(layer "In9.Cu")
		(net "H_CPU0_MEMDEF_MEMHOT_PCH_N")
	)
	(segment
		(start 394.29436 -50.138838)
		(end 393.441682 -50.991516)
		(width 0.089408)
		(layer "In9.Cu")
		(net "H_CPU0_MEMDEF_MEMHOT_PCH_N")
	)
	(segment
		(start 389.158734 -83.349338)
		(end 389.158734 -84.315046)
		(width 0.089408)
		(layer "In9.Cu")
		(net "H_CPU0_MEMDEF_MEMHOT_PCH_N")
	)
	(segment
		(start 401.855178 -21.587714)
		(end 401.042632 -20.775168)
		(width 0.089408)
		(layer "In9.Cu")
		(net "H_CPU0_MEMDEF_MEMHOT_PCH_N")
	)
	(segment
		(start 394.496544 -33.190688)
		(end 394.006324 -33.190688)
		(width 0.089408)
		(layer "In9.Cu")
		(net "H_CPU0_MEMDEF_MEMHOT_PCH_N")
	)
	(segment
		(start 385.87426 -86.74989)
		(end 384.25628 -88.36787)
		(width 0.089408)
		(layer "In9.Cu")
		(net "H_CPU0_MEMDEF_MEMHOT_PCH_N")
	)
	(segment
		(start 391.204704 -74.045572)
		(end 391.204704 -75.106276)
		(width 0.089408)
		(layer "In9.Cu")
		(net "H_CPU0_MEMDEF_MEMHOT_PCH_N")
	)
	(segment
		(start 394.378688 -34.745676)
		(end 394.378688 -35.55111)
		(width 0.089408)
		(layer "In9.Cu")
		(net "H_CPU0_MEMDEF_MEMHOT_PCH_N")
	)
	(segment
		(start 386.522976 -85.799422)
		(end 385.87426 -86.448138)
		(width 0.089408)
		(layer "In9.Cu")
		(net "H_CPU0_MEMDEF_MEMHOT_PCH_N")
	)
	(segment
		(start 383.37617 -94.841822)
		(end 383.3749 -94.843092)
		(width 0.0889)
		(layer "In9.Cu")
		(net "H_CPU0_MEMDEF_MEMHOT_PCH_N")
	)
	(segment
		(start 387.674358 -85.799422)
		(end 386.522976 -85.799422)
		(width 0.089408)
		(layer "In9.Cu")
		(net "H_CPU0_MEMDEF_MEMHOT_PCH_N")
	)
	(segment
		(start 383.634234 -91.592146)
		(end 383.83337 -91.791282)
		(width 0.089408)
		(layer "In9.Cu")
		(net "H_CPU0_MEMDEF_MEMHOT_PCH_N")
	)
	(segment
		(start 393.82065 -43.5356)
		(end 393.82065 -44.593764)
		(width 0.089408)
		(layer "In9.Cu")
		(net "H_CPU0_MEMDEF_MEMHOT_PCH_N")
	)
	(segment
		(start 395.726412 -38.903402)
		(end 395.726412 -41.199054)
		(width 0.089408)
		(layer "In9.Cu")
		(net "H_CPU0_MEMDEF_MEMHOT_PCH_N")
	)
	(segment
		(start 395.944344 -33.198308)
		(end 394.504164 -33.198308)
		(width 0.089408)
		(layer "In9.Cu")
		(net "H_CPU0_MEMDEF_MEMHOT_PCH_N")
	)
	(segment
		(start 383.83337 -94.384622)
		(end 383.37617 -94.841822)
		(width 0.089408)
		(layer "In9.Cu")
		(net "H_CPU0_MEMDEF_MEMHOT_PCH_N")
	)
	(segment
		(start 396.450312 -22.853142)
		(end 396.450312 -31.10611)
		(width 0.089408)
		(layer "In9.Cu")
		(net "H_CPU0_MEMDEF_MEMHOT_PCH_N")
	)
	(segment
		(start 402.306282 -21.587714)
		(end 401.855178 -21.587714)
		(width 0.089408)
		(layer "In9.Cu")
		(net "H_CPU0_MEMDEF_MEMHOT_PCH_N")
	)
	(segment
		(start 396.208504 -31.347918)
		(end 396.208504 -32.934148)
		(width 0.089408)
		(layer "In9.Cu")
		(net "H_CPU0_MEMDEF_MEMHOT_PCH_N")
	)
	(segment
		(start 393.339828 -68.782692)
		(end 391.437368 -70.685152)
		(width 0.089408)
		(layer "In9.Cu")
		(net "H_CPU0_MEMDEF_MEMHOT_PCH_N")
	)
	(segment
		(start 393.339828 -63.257684)
		(end 393.339828 -68.782692)
		(width 0.089408)
		(layer "In9.Cu")
		(net "H_CPU0_MEMDEF_MEMHOT_PCH_N")
	)
	(segment
		(start 393.660122 -33.53689)
		(end 393.660122 -34.02711)
		(width 0.089408)
		(layer "In9.Cu")
		(net "H_CPU0_MEMDEF_MEMHOT_PCH_N")
	)
	(segment
		(start 394.203936 -53.610256)
		(end 394.203936 -62.393576)
		(width 0.089408)
		(layer "In9.Cu")
		(net "H_CPU0_MEMDEF_MEMHOT_PCH_N")
	)
	(segment
		(start 389.065262 -79.01305)
		(end 389.344408 -79.292196)
		(width 0.089408)
		(layer "In9.Cu")
		(net "H_CPU0_MEMDEF_MEMHOT_PCH_N")
	)
	(segment
		(start 421.435784 -17.853914)
		(end 412.63316 -17.853914)
		(width 0.089408)
		(layer "In9.Cu")
		(net "H_CPU0_MEMDEF_MEMHOT_PCH_N")
	)
	(segment
		(start 391.042906 -73.883774)
		(end 391.204704 -74.045572)
		(width 0.089408)
		(layer "In9.Cu")
		(net "H_CPU0_MEMDEF_MEMHOT_PCH_N")
	)
	(segment
		(start 384.25628 -89.18194)
		(end 383.634234 -89.803986)
		(width 0.089408)
		(layer "In9.Cu")
		(net "H_CPU0_MEMDEF_MEMHOT_PCH_N")
	)
	(segment
		(start 384.857752 -98.399092)
		(end 384.922776 -98.464116)
		(width 0.0889)
		(layer "In9.Cu")
		(net "H_CPU0_MEMDEF_MEMHOT_PCH_N")
	)
	(segment
		(start 391.042906 -72.189594)
		(end 391.042906 -73.883774)
		(width 0.089408)
		(layer "In9.Cu")
		(net "H_CPU0_MEMDEF_MEMHOT_PCH_N")
	)
	(segment
		(start 394.203936 -62.393576)
		(end 393.339828 -63.257684)
		(width 0.089408)
		(layer "In9.Cu")
		(net "H_CPU0_MEMDEF_MEMHOT_PCH_N")
	)
	(segment
		(start 412.63316 -17.853914)
		(end 412.213806 -18.273268)
		(width 0.089408)
		(layer "In9.Cu")
		(net "H_CPU0_MEMDEF_MEMHOT_PCH_N")
	)
	(arc
		(start 384.565652 -97.952306)
		(mid 384.765025 -98.140834)
		(end 384.857752 -98.399092)
		(width 0.0889)
		(layer "In9.Cu")
		(net "H_CPU0_MEMDEF_MEMHOT_PCH_N")
	)
	(arc
		(start 383.3749 -95.899732)
		(mid 383.43125 -96.093582)
		(end 383.575052 -96.235266)
		(width 0.0889)
		(layer "In9.Cu")
		(net "H_CPU0_MEMDEF_MEMHOT_PCH_N")
	)
	(arc
		(start 383.575052 -96.235266)
		(mid 383.785916 -96.44227)
		(end 383.8702 -96.725486)
		(width 0.0889)
		(layer "In9.Cu")
		(net "H_CPU0_MEMDEF_MEMHOT_PCH_N")
	)
	(arc
		(start 383.8702 -96.758252)
		(mid 383.92655 -96.952102)
		(end 384.070352 -97.093786)
		(width 0.0889)
		(layer "In9.Cu")
		(net "H_CPU0_MEMDEF_MEMHOT_PCH_N")
	)
	(arc
		(start 384.070352 -97.093786)
		(mid 384.281216 -97.30079)
		(end 384.3655 -97.584006)
		(width 0.0889)
		(layer "In9.Cu")
		(net "H_CPU0_MEMDEF_MEMHOT_PCH_N")
	)
	(arc
		(start 384.3655 -97.616772)
		(mid 384.42185 -97.810622)
		(end 384.565652 -97.952306)
		(width 0.0889)
		(layer "In9.Cu")
		(net "H_CPU0_MEMDEF_MEMHOT_PCH_N")
	)
	(segment
		(start 383.27965 -99.55276)
		(end 383.77495 -99.322636)
		(width 0.10795)
		(layer "F.Cu")
		(net "H_CPU0_MEMABC_MEMHOT_PCH_N")
	)
	(via
		(at 383.77495 -99.322636)
		(size 0.508)
		(drill 0.254)
		(layers "F.Cu" "B.Cu")
		(net "H_CPU0_MEMABC_MEMHOT_PCH_N")
	)
	(via
		(at 382.1684 -94.5388)
		(size 0.6604)
		(drill 0.3302)
		(layers "F.Cu" "B.Cu")
		(net "H_CPU0_MEMABC_MEMHOT_PCH_N")
	)
	(segment
		(start 382.495298 -92.915232)
		(end 382.495298 -93.153738)
		(width 0.10795)
		(layer "B.Cu")
		(net "H_CPU0_MEMABC_MEMHOT_PCH_N")
	)
	(segment
		(start 382.8034 -88.42756)
		(end 382.176782 -89.054178)
		(width 0.10795)
		(layer "B.Cu")
		(net "H_CPU0_MEMABC_MEMHOT_PCH_N")
	)
	(segment
		(start 382.176782 -89.054178)
		(end 382.176782 -89.229946)
		(width 0.10795)
		(layer "B.Cu")
		(net "H_CPU0_MEMABC_MEMHOT_PCH_N")
	)
	(segment
		(start 383.00152 -95.516192)
		(end 383.1844 -95.699072)
		(width 0.0889)
		(layer "B.Cu")
		(net "H_CPU0_MEMABC_MEMHOT_PCH_N")
	)
	(segment
		(start 382.485138 -86.227412)
		(end 382.510792 -86.227412)
		(width 0.10795)
		(layer "B.Cu")
		(net "H_CPU0_MEMABC_MEMHOT_PCH_N")
	)
	(segment
		(start 382.1684 -94.5388)
		(end 382.1684 -94.683072)
		(width 0.10795)
		(layer "B.Cu")
		(net "H_CPU0_MEMABC_MEMHOT_PCH_N")
	)
	(segment
		(start 383.1844 -97.59442)
		(end 383.1844 -97.627186)
		(width 0.0889)
		(layer "B.Cu")
		(net "H_CPU0_MEMABC_MEMHOT_PCH_N")
	)
	(segment
		(start 382.15316 -89.253568)
		(end 382.15316 -90.40114)
		(width 0.10795)
		(layer "B.Cu")
		(net "H_CPU0_MEMABC_MEMHOT_PCH_N")
	)
	(segment
		(start 383.6797 -98.45294)
		(end 383.6797 -98.485706)
		(width 0.0889)
		(layer "B.Cu")
		(net "H_CPU0_MEMABC_MEMHOT_PCH_N")
	)
	(segment
		(start 382.176782 -89.229946)
		(end 382.15316 -89.253568)
		(width 0.10795)
		(layer "B.Cu")
		(net "H_CPU0_MEMABC_MEMHOT_PCH_N")
	)
	(segment
		(start 382.495298 -93.153738)
		(end 382.1684 -93.480636)
		(width 0.10795)
		(layer "B.Cu")
		(net "H_CPU0_MEMABC_MEMHOT_PCH_N")
	)
	(segment
		(start 382.4986 -92.041472)
		(end 382.4986 -92.91193)
		(width 0.10795)
		(layer "B.Cu")
		(net "H_CPU0_MEMABC_MEMHOT_PCH_N")
	)
	(segment
		(start 382.1684 -93.480636)
		(end 382.1684 -94.5388)
		(width 0.10795)
		(layer "B.Cu")
		(net "H_CPU0_MEMABC_MEMHOT_PCH_N")
	)
	(segment
		(start 383.91973 -98.940112)
		(end 383.94386 -99.02952)
		(width 0.0889)
		(layer "B.Cu")
		(net "H_CPU0_MEMABC_MEMHOT_PCH_N")
	)
	(segment
		(start 382.510792 -86.227412)
		(end 382.8034 -86.52002)
		(width 0.10795)
		(layer "B.Cu")
		(net "H_CPU0_MEMABC_MEMHOT_PCH_N")
	)
	(segment
		(start 382.15316 -90.40114)
		(end 382.2446 -90.49258)
		(width 0.10795)
		(layer "B.Cu")
		(net "H_CPU0_MEMABC_MEMHOT_PCH_N")
	)
	(segment
		(start 383.1844 -95.699072)
		(end 383.1844 -95.899732)
		(width 0.0889)
		(layer "B.Cu")
		(net "H_CPU0_MEMABC_MEMHOT_PCH_N")
	)
	(segment
		(start 381.830326 -85.5726)
		(end 382.485138 -86.227412)
		(width 0.10795)
		(layer "B.Cu")
		(net "H_CPU0_MEMABC_MEMHOT_PCH_N")
	)
	(segment
		(start 382.1684 -94.683072)
		(end 383.00152 -95.516192)
		(width 0.10795)
		(layer "B.Cu")
		(net "H_CPU0_MEMABC_MEMHOT_PCH_N")
	)
	(segment
		(start 381.7239 -85.5726)
		(end 381.830326 -85.5726)
		(width 0.10795)
		(layer "B.Cu")
		(net "H_CPU0_MEMABC_MEMHOT_PCH_N")
	)
	(segment
		(start 382.6891 -96.725486)
		(end 382.6891 -96.768666)
		(width 0.0889)
		(layer "B.Cu")
		(net "H_CPU0_MEMABC_MEMHOT_PCH_N")
	)
	(segment
		(start 382.8034 -86.52002)
		(end 382.8034 -88.42756)
		(width 0.10795)
		(layer "B.Cu")
		(net "H_CPU0_MEMABC_MEMHOT_PCH_N")
	)
	(segment
		(start 383.94386 -99.02952)
		(end 383.77495 -99.322636)
		(width 0.0889)
		(layer "B.Cu")
		(net "H_CPU0_MEMABC_MEMHOT_PCH_N")
	)
	(segment
		(start 382.2446 -90.49258)
		(end 382.2446 -91.787472)
		(width 0.10795)
		(layer "B.Cu")
		(net "H_CPU0_MEMABC_MEMHOT_PCH_N")
	)
	(segment
		(start 382.2446 -91.787472)
		(end 382.4986 -92.041472)
		(width 0.10795)
		(layer "B.Cu")
		(net "H_CPU0_MEMABC_MEMHOT_PCH_N")
	)
	(segment
		(start 382.4986 -92.91193)
		(end 382.495298 -92.915232)
		(width 0.10795)
		(layer "B.Cu")
		(net "H_CPU0_MEMABC_MEMHOT_PCH_N")
	)
	(arc
		(start 383.479548 -98.117406)
		(mid 383.623352 -98.259089)
		(end 383.6797 -98.45294)
		(width 0.0889)
		(layer "B.Cu")
		(net "H_CPU0_MEMABC_MEMHOT_PCH_N")
	)
	(arc
		(start 383.1844 -95.899732)
		(mid 383.12805 -96.093582)
		(end 382.984248 -96.235266)
		(width 0.0889)
		(layer "B.Cu")
		(net "H_CPU0_MEMABC_MEMHOT_PCH_N")
	)
	(arc
		(start 383.1844 -97.627186)
		(mid 383.268681 -97.910403)
		(end 383.479548 -98.117406)
		(width 0.0889)
		(layer "B.Cu")
		(net "H_CPU0_MEMABC_MEMHOT_PCH_N")
	)
	(arc
		(start 382.984248 -97.258886)
		(mid 383.128052 -97.400569)
		(end 383.1844 -97.59442)
		(width 0.0889)
		(layer "B.Cu")
		(net "H_CPU0_MEMABC_MEMHOT_PCH_N")
	)
	(arc
		(start 383.6797 -98.485706)
		(mid 383.747729 -98.740371)
		(end 383.91973 -98.940112)
		(width 0.0889)
		(layer "B.Cu")
		(net "H_CPU0_MEMABC_MEMHOT_PCH_N")
	)
	(arc
		(start 382.984248 -96.235266)
		(mid 382.773384 -96.44227)
		(end 382.6891 -96.725486)
		(width 0.0889)
		(layer "B.Cu")
		(net "H_CPU0_MEMABC_MEMHOT_PCH_N")
	)
	(arc
		(start 382.6891 -96.768666)
		(mid 382.773381 -97.051883)
		(end 382.984248 -97.258886)
		(width 0.0889)
		(layer "B.Cu")
		(net "H_CPU0_MEMABC_MEMHOT_PCH_N")
	)
	(segment
		(start 398.63395 -100.41128)
		(end 399.12925 -100.181156)
		(width 0.10795)
		(layer "F.Cu")
		(net "FM_USB_P0_EN_BOOT_BIOS_STRAP_N")
	)
	(via
		(at 401.384262 -97.4598)
		(size 0.6604)
		(drill 0.3302)
		(layers "F.Cu" "B.Cu")
		(net "FM_USB_P0_EN_BOOT_BIOS_STRAP_N")
	)
	(via
		(at 399.12925 -100.181156)
		(size 0.508)
		(drill 0.254)
		(layers "F.Cu" "B.Cu")
		(net "FM_USB_P0_EN_BOOT_BIOS_STRAP_N")
	)
	(via
		(at 420.321486 -102.01783)
		(size 0.508)
		(drill 0.254)
		(layers "F.Cu" "B.Cu")
		(net "FM_USB_P0_EN_BOOT_BIOS_STRAP_N")
	)
	(segment
		(start 402.267674 -96.784668)
		(end 402.267674 -96.98482)
		(width 0.10795)
		(layer "B.Cu")
		(net "FM_USB_P0_EN_BOOT_BIOS_STRAP_N")
	)
	(segment
		(start 468.506048 -124.37872)
		(end 468.884 -124.756672)
		(width 0.10795)
		(layer "B.Cu")
		(net "FM_USB_P0_EN_BOOT_BIOS_STRAP_N")
	)
	(segment
		(start 469.607392 -115.095528)
		(end 469.607392 -115.584478)
		(width 0.10795)
		(layer "B.Cu")
		(net "FM_USB_P0_EN_BOOT_BIOS_STRAP_N")
	)
	(segment
		(start 420.321486 -102.01783)
		(end 420.521892 -102.218236)
		(width 0.10795)
		(layer "B.Cu")
		(net "FM_USB_P0_EN_BOOT_BIOS_STRAP_N")
	)
	(segment
		(start 441.27547 -113.344452)
		(end 448.41414 -113.344452)
		(width 0.10795)
		(layer "B.Cu")
		(net "FM_USB_P0_EN_BOOT_BIOS_STRAP_N")
	)
	(segment
		(start 468.884 -124.756672)
		(end 468.884 -125.984)
		(width 0.10795)
		(layer "B.Cu")
		(net "FM_USB_P0_EN_BOOT_BIOS_STRAP_N")
	)
	(segment
		(start 448.764406 -113.344198)
		(end 448.76466 -113.344452)
		(width 0.10795)
		(layer "B.Cu")
		(net "FM_USB_P0_EN_BOOT_BIOS_STRAP_N")
	)
	(segment
		(start 398.46504 -98.914458)
		(end 398.225772 -99.153726)
		(width 0.10795)
		(layer "B.Cu")
		(net "FM_USB_P0_EN_BOOT_BIOS_STRAP_N")
	)
	(segment
		(start 402.267674 -96.98482)
		(end 401.792694 -97.4598)
		(width 0.10795)
		(layer "B.Cu")
		(net "FM_USB_P0_EN_BOOT_BIOS_STRAP_N")
	)
	(segment
		(start 466.9536 -113.344452)
		(end 468.493348 -114.8842)
		(width 0.10795)
		(layer "B.Cu")
		(net "FM_USB_P0_EN_BOOT_BIOS_STRAP_N")
	)
	(segment
		(start 401.792694 -97.4598)
		(end 401.384262 -97.4598)
		(width 0.10795)
		(layer "B.Cu")
		(net "FM_USB_P0_EN_BOOT_BIOS_STRAP_N")
	)
	(segment
		(start 401.384262 -97.4598)
		(end 399.929604 -98.914458)
		(width 0.10795)
		(layer "B.Cu")
		(net "FM_USB_P0_EN_BOOT_BIOS_STRAP_N")
	)
	(segment
		(start 398.719802 -100.181156)
		(end 399.12925 -100.181156)
		(width 0.10795)
		(layer "B.Cu")
		(net "FM_USB_P0_EN_BOOT_BIOS_STRAP_N")
	)
	(segment
		(start 398.225772 -99.153726)
		(end 398.225772 -99.687126)
		(width 0.10795)
		(layer "B.Cu")
		(net "FM_USB_P0_EN_BOOT_BIOS_STRAP_N")
	)
	(segment
		(start 420.521892 -102.218236)
		(end 420.521892 -117.224048)
		(width 0.10795)
		(layer "B.Cu")
		(net "FM_USB_P0_EN_BOOT_BIOS_STRAP_N")
	)
	(segment
		(start 468.493348 -114.8842)
		(end 469.396064 -114.8842)
		(width 0.10795)
		(layer "B.Cu")
		(net "FM_USB_P0_EN_BOOT_BIOS_STRAP_N")
	)
	(segment
		(start 438.323736 -121.8311)
		(end 440.064144 -120.090692)
		(width 0.10795)
		(layer "B.Cu")
		(net "FM_USB_P0_EN_BOOT_BIOS_STRAP_N")
	)
	(segment
		(start 458.040994 -113.344198)
		(end 458.391006 -113.344198)
		(width 0.10795)
		(layer "B.Cu")
		(net "FM_USB_P0_EN_BOOT_BIOS_STRAP_N")
	)
	(segment
		(start 458.39126 -113.344452)
		(end 466.9536 -113.344452)
		(width 0.10795)
		(layer "B.Cu")
		(net "FM_USB_P0_EN_BOOT_BIOS_STRAP_N")
	)
	(segment
		(start 402.659342 -96.393)
		(end 402.267674 -96.784668)
		(width 0.10795)
		(layer "B.Cu")
		(net "FM_USB_P0_EN_BOOT_BIOS_STRAP_N")
	)
	(segment
		(start 458.04074 -113.344452)
		(end 458.040994 -113.344198)
		(width 0.10795)
		(layer "B.Cu")
		(net "FM_USB_P0_EN_BOOT_BIOS_STRAP_N")
	)
	(segment
		(start 469.147398 -116.044472)
		(end 469.147398 -122.376184)
		(width 0.10795)
		(layer "B.Cu")
		(net "FM_USB_P0_EN_BOOT_BIOS_STRAP_N")
	)
	(segment
		(start 468.464646 -124.333)
		(end 468.506048 -124.374402)
		(width 0.10795)
		(layer "B.Cu")
		(net "FM_USB_P0_EN_BOOT_BIOS_STRAP_N")
	)
	(segment
		(start 468.464646 -123.058936)
		(end 468.464646 -124.333)
		(width 0.10795)
		(layer "B.Cu")
		(net "FM_USB_P0_EN_BOOT_BIOS_STRAP_N")
	)
	(segment
		(start 468.506048 -124.374402)
		(end 468.506048 -124.37872)
		(width 0.10795)
		(layer "B.Cu")
		(net "FM_USB_P0_EN_BOOT_BIOS_STRAP_N")
	)
	(segment
		(start 469.147398 -122.376184)
		(end 468.464646 -123.058936)
		(width 0.10795)
		(layer "B.Cu")
		(net "FM_USB_P0_EN_BOOT_BIOS_STRAP_N")
	)
	(segment
		(start 440.064144 -114.555778)
		(end 441.27547 -113.344452)
		(width 0.10795)
		(layer "B.Cu")
		(net "FM_USB_P0_EN_BOOT_BIOS_STRAP_N")
	)
	(segment
		(start 399.929604 -98.914458)
		(end 398.46504 -98.914458)
		(width 0.10795)
		(layer "B.Cu")
		(net "FM_USB_P0_EN_BOOT_BIOS_STRAP_N")
	)
	(segment
		(start 420.521892 -117.224048)
		(end 425.128944 -121.8311)
		(width 0.10795)
		(layer "B.Cu")
		(net "FM_USB_P0_EN_BOOT_BIOS_STRAP_N")
	)
	(segment
		(start 440.064144 -120.090692)
		(end 440.064144 -114.555778)
		(width 0.10795)
		(layer "B.Cu")
		(net "FM_USB_P0_EN_BOOT_BIOS_STRAP_N")
	)
	(segment
		(start 448.414394 -113.344198)
		(end 448.764406 -113.344198)
		(width 0.10795)
		(layer "B.Cu")
		(net "FM_USB_P0_EN_BOOT_BIOS_STRAP_N")
	)
	(segment
		(start 425.128944 -121.8311)
		(end 438.323736 -121.8311)
		(width 0.10795)
		(layer "B.Cu")
		(net "FM_USB_P0_EN_BOOT_BIOS_STRAP_N")
	)
	(segment
		(start 469.396064 -114.8842)
		(end 469.607392 -115.095528)
		(width 0.10795)
		(layer "B.Cu")
		(net "FM_USB_P0_EN_BOOT_BIOS_STRAP_N")
	)
	(segment
		(start 469.607392 -115.584478)
		(end 469.147398 -116.044472)
		(width 0.10795)
		(layer "B.Cu")
		(net "FM_USB_P0_EN_BOOT_BIOS_STRAP_N")
	)
	(segment
		(start 398.225772 -99.687126)
		(end 398.719802 -100.181156)
		(width 0.10795)
		(layer "B.Cu")
		(net "FM_USB_P0_EN_BOOT_BIOS_STRAP_N")
	)
	(segment
		(start 448.41414 -113.344452)
		(end 448.414394 -113.344198)
		(width 0.10795)
		(layer "B.Cu")
		(net "FM_USB_P0_EN_BOOT_BIOS_STRAP_N")
	)
	(segment
		(start 403.6695 -96.393)
		(end 402.659342 -96.393)
		(width 0.10795)
		(layer "B.Cu")
		(net "FM_USB_P0_EN_BOOT_BIOS_STRAP_N")
	)
	(segment
		(start 458.391006 -113.344198)
		(end 458.39126 -113.344452)
		(width 0.10795)
		(layer "B.Cu")
		(net "FM_USB_P0_EN_BOOT_BIOS_STRAP_N")
	)
	(segment
		(start 448.76466 -113.344452)
		(end 458.04074 -113.344452)
		(width 0.10795)
		(layer "B.Cu")
		(net "FM_USB_P0_EN_BOOT_BIOS_STRAP_N")
	)
	(segment
		(start 399.12925 -100.181156)
		(end 400.260566 -100.181156)
		(width 0.089408)
		(layer "In4.Cu")
		(net "FM_USB_P0_EN_BOOT_BIOS_STRAP_N")
	)
	(segment
		(start 413.460946 -102.3112)
		(end 413.537146 -102.3874)
		(width 0.089408)
		(layer "In4.Cu")
		(net "FM_USB_P0_EN_BOOT_BIOS_STRAP_N")
	)
	(segment
		(start 409.226004 -102.3112)
		(end 413.460946 -102.3112)
		(width 0.089408)
		(layer "In4.Cu")
		(net "FM_USB_P0_EN_BOOT_BIOS_STRAP_N")
	)
	(segment
		(start 419.951916 -102.3874)
		(end 420.321486 -102.01783)
		(width 0.089408)
		(layer "In4.Cu")
		(net "FM_USB_P0_EN_BOOT_BIOS_STRAP_N")
	)
	(segment
		(start 401.88769 -101.80828)
		(end 404.771352 -101.80828)
		(width 0.089408)
		(layer "In4.Cu")
		(net "FM_USB_P0_EN_BOOT_BIOS_STRAP_N")
	)
	(segment
		(start 405.90343 -102.940358)
		(end 408.596846 -102.940358)
		(width 0.089408)
		(layer "In4.Cu")
		(net "FM_USB_P0_EN_BOOT_BIOS_STRAP_N")
	)
	(segment
		(start 404.771352 -101.80828)
		(end 405.90343 -102.940358)
		(width 0.089408)
		(layer "In4.Cu")
		(net "FM_USB_P0_EN_BOOT_BIOS_STRAP_N")
	)
	(segment
		(start 408.596846 -102.940358)
		(end 409.226004 -102.3112)
		(width 0.089408)
		(layer "In4.Cu")
		(net "FM_USB_P0_EN_BOOT_BIOS_STRAP_N")
	)
	(segment
		(start 413.537146 -102.3874)
		(end 419.951916 -102.3874)
		(width 0.089408)
		(layer "In4.Cu")
		(net "FM_USB_P0_EN_BOOT_BIOS_STRAP_N")
	)
	(segment
		(start 400.260566 -100.181156)
		(end 401.88769 -101.80828)
		(width 0.089408)
		(layer "In4.Cu")
		(net "FM_USB_P0_EN_BOOT_BIOS_STRAP_N")
	)
	(segment
		(start 405.257 -47.5869)
		(end 404.66264 -47.5869)
		(width 0.10795)
		(layer "F.Cu")
		(net "FM_CPU_ERR1_PCH_N")
	)
	(segment
		(start 402.00326 -44.52874)
		(end 401.711668 -44.237148)
		(width 0.10795)
		(layer "F.Cu")
		(net "FM_CPU_ERR1_PCH_N")
	)
	(segment
		(start 402.98497 -44.52874)
		(end 402.00326 -44.52874)
		(width 0.10795)
		(layer "F.Cu")
		(net "FM_CPU_ERR1_PCH_N")
	)
	(segment
		(start 405.384 -47.7139)
		(end 405.257 -47.5869)
		(width 0.10795)
		(layer "F.Cu")
		(net "FM_CPU_ERR1_PCH_N")
	)
	(segment
		(start 398.41424 -43.45559)
		(end 397.535908 -43.45559)
		(width 0.10795)
		(layer "F.Cu")
		(net "FM_CPU_ERR1_PCH_N")
	)
	(segment
		(start 404.66264 -47.5869)
		(end 404.241 -47.16526)
		(width 0.10795)
		(layer "F.Cu")
		(net "FM_CPU_ERR1_PCH_N")
	)
	(segment
		(start 386.74675 -97.605596)
		(end 386.25145 -97.83572)
		(width 0.10795)
		(layer "F.Cu")
		(net "FM_CPU_ERR1_PCH_N")
	)
	(segment
		(start 404.241 -47.16526)
		(end 404.241 -45.974)
		(width 0.10795)
		(layer "F.Cu")
		(net "FM_CPU_ERR1_PCH_N")
	)
	(segment
		(start 397.535908 -43.45559)
		(end 396.630652 -44.360846)
		(width 0.10795)
		(layer "F.Cu")
		(net "FM_CPU_ERR1_PCH_N")
	)
	(segment
		(start 399.195798 -44.237148)
		(end 398.41424 -43.45559)
		(width 0.10795)
		(layer "F.Cu")
		(net "FM_CPU_ERR1_PCH_N")
	)
	(segment
		(start 401.711668 -44.237148)
		(end 399.195798 -44.237148)
		(width 0.10795)
		(layer "F.Cu")
		(net "FM_CPU_ERR1_PCH_N")
	)
	(segment
		(start 404.241 -45.78477)
		(end 402.98497 -44.52874)
		(width 0.10795)
		(layer "F.Cu")
		(net "FM_CPU_ERR1_PCH_N")
	)
	(segment
		(start 404.241 -45.974)
		(end 404.241 -45.78477)
		(width 0.10795)
		(layer "F.Cu")
		(net "FM_CPU_ERR1_PCH_N")
	)
	(via
		(at 386.74675 -97.605596)
		(size 0.508)
		(drill 0.254)
		(layers "F.Cu" "B.Cu")
		(net "FM_CPU_ERR1_PCH_N")
	)
	(via
		(at 396.630652 -44.360846)
		(size 0.508)
		(drill 0.254)
		(layers "F.Cu" "B.Cu")
		(net "FM_CPU_ERR1_PCH_N")
	)
	(via
		(at 404.241 -45.974)
		(size 0.762)
		(drill 0.381)
		(layers "F.Cu" "B.Cu")
		(net "FM_CPU_ERR1_PCH_N")
	)
	(segment
		(start 386.780278 -89.767156)
		(end 386.780278 -90.257376)
		(width 0.089408)
		(layer "In9.Cu")
		(net "FM_CPU_ERR1_PCH_N")
	)
	(segment
		(start 393.65428 -71.385938)
		(end 393.65428 -71.893938)
		(width 0.089408)
		(layer "In9.Cu")
		(net "FM_CPU_ERR1_PCH_N")
	)
	(segment
		(start 393.114784 -76.057252)
		(end 392.69289 -76.479146)
		(width 0.089408)
		(layer "In9.Cu")
		(net "FM_CPU_ERR1_PCH_N")
	)
	(segment
		(start 396.353792 -49.483264)
		(end 396.353792 -58.415936)
		(width 0.089408)
		(layer "In9.Cu")
		(net "FM_CPU_ERR1_PCH_N")
	)
	(segment
		(start 392.69289 -76.479146)
		(end 392.69289 -77.70368)
		(width 0.089408)
		(layer "In9.Cu")
		(net "FM_CPU_ERR1_PCH_N")
	)
	(segment
		(start 396.11427 -62.289436)
		(end 396.11427 -63.221616)
		(width 0.089408)
		(layer "In9.Cu")
		(net "FM_CPU_ERR1_PCH_N")
	)
	(segment
		(start 396.137638 -49.26711)
		(end 396.353792 -49.483264)
		(width 0.089408)
		(layer "In9.Cu")
		(net "FM_CPU_ERR1_PCH_N")
	)
	(segment
		(start 396.137638 -45.365924)
		(end 396.137638 -49.26711)
		(width 0.089408)
		(layer "In9.Cu")
		(net "FM_CPU_ERR1_PCH_N")
	)
	(segment
		(start 391.346436 -82.912458)
		(end 391.346436 -84.104988)
		(width 0.089408)
		(layer "In9.Cu")
		(net "FM_CPU_ERR1_PCH_N")
	)
	(segment
		(start 391.346436 -84.104988)
		(end 391.24128 -84.210144)
		(width 0.089408)
		(layer "In9.Cu")
		(net "FM_CPU_ERR1_PCH_N")
	)
	(segment
		(start 386.779008 -91.163902)
		(end 386.3086 -91.63431)
		(width 0.089408)
		(layer "In9.Cu")
		(net "FM_CPU_ERR1_PCH_N")
	)
	(segment
		(start 391.54862 -79.354172)
		(end 391.874248 -79.6798)
		(width 0.089408)
		(layer "In9.Cu")
		(net "FM_CPU_ERR1_PCH_N")
	)
	(segment
		(start 397.111728 -59.173872)
		(end 397.111728 -61.133482)
		(width 0.089408)
		(layer "In9.Cu")
		(net "FM_CPU_ERR1_PCH_N")
	)
	(segment
		(start 395.356334 -69.525388)
		(end 393.654026 -71.227696)
		(width 0.089408)
		(layer "In9.Cu")
		(net "FM_CPU_ERR1_PCH_N")
	)
	(segment
		(start 391.24128 -84.210144)
		(end 391.24128 -85.597238)
		(width 0.089408)
		(layer "In9.Cu")
		(net "FM_CPU_ERR1_PCH_N")
	)
	(segment
		(start 386.780278 -90.257376)
		(end 386.779008 -90.258646)
		(width 0.089408)
		(layer "In9.Cu")
		(net "FM_CPU_ERR1_PCH_N")
	)
	(segment
		(start 393.654026 -71.385684)
		(end 393.65428 -71.385938)
		(width 0.089408)
		(layer "In9.Cu")
		(net "FM_CPU_ERR1_PCH_N")
	)
	(segment
		(start 394.024866 -72.264524)
		(end 394.024866 -73.036176)
		(width 0.089408)
		(layer "In9.Cu")
		(net "FM_CPU_ERR1_PCH_N")
	)
	(segment
		(start 386.779008 -90.258646)
		(end 386.779008 -91.163902)
		(width 0.089408)
		(layer "In9.Cu")
		(net "FM_CPU_ERR1_PCH_N")
	)
	(segment
		(start 396.630652 -44.360846)
		(end 396.630652 -44.87291)
		(width 0.089408)
		(layer "In9.Cu")
		(net "FM_CPU_ERR1_PCH_N")
	)
	(segment
		(start 391.874248 -79.6798)
		(end 391.874248 -81.300574)
		(width 0.089408)
		(layer "In9.Cu")
		(net "FM_CPU_ERR1_PCH_N")
	)
	(segment
		(start 386.3086 -91.63431)
		(end 386.3086 -92.136976)
		(width 0.089408)
		(layer "In9.Cu")
		(net "FM_CPU_ERR1_PCH_N")
	)
	(segment
		(start 391.54862 -78.84795)
		(end 391.54862 -79.354172)
		(width 0.089408)
		(layer "In9.Cu")
		(net "FM_CPU_ERR1_PCH_N")
	)
	(segment
		(start 386.765292 -93.316298)
		(end 386.15493 -93.92666)
		(width 0.089408)
		(layer "In9.Cu")
		(net "FM_CPU_ERR1_PCH_N")
	)
	(segment
		(start 386.316474 -97.17532)
		(end 386.74675 -97.605596)
		(width 0.0889)
		(layer "In9.Cu")
		(net "FM_CPU_ERR1_PCH_N")
	)
	(segment
		(start 386.779008 -89.111582)
		(end 386.779008 -89.765886)
		(width 0.089408)
		(layer "In9.Cu")
		(net "FM_CPU_ERR1_PCH_N")
	)
	(segment
		(start 397.111728 -61.133482)
		(end 397.111982 -61.133736)
		(width 0.089408)
		(layer "In9.Cu")
		(net "FM_CPU_ERR1_PCH_N")
	)
	(segment
		(start 386.779008 -89.765886)
		(end 386.780278 -89.767156)
		(width 0.089408)
		(layer "In9.Cu")
		(net "FM_CPU_ERR1_PCH_N")
	)
	(segment
		(start 396.353792 -58.415936)
		(end 397.111728 -59.173872)
		(width 0.089408)
		(layer "In9.Cu")
		(net "FM_CPU_ERR1_PCH_N")
	)
	(segment
		(start 395.356334 -63.979552)
		(end 395.356334 -69.525388)
		(width 0.089408)
		(layer "In9.Cu")
		(net "FM_CPU_ERR1_PCH_N")
	)
	(segment
		(start 385.85267 -96.581722)
		(end 385.8514 -96.582992)
		(width 0.0889)
		(layer "In9.Cu")
		(net "FM_CPU_ERR1_PCH_N")
	)
	(segment
		(start 393.65428 -71.893938)
		(end 394.024866 -72.264524)
		(width 0.089408)
		(layer "In9.Cu")
		(net "FM_CPU_ERR1_PCH_N")
	)
	(segment
		(start 397.111982 -61.291724)
		(end 396.11427 -62.289436)
		(width 0.089408)
		(layer "In9.Cu")
		(net "FM_CPU_ERR1_PCH_N")
	)
	(segment
		(start 396.630652 -44.87291)
		(end 396.137638 -45.365924)
		(width 0.089408)
		(layer "In9.Cu")
		(net "FM_CPU_ERR1_PCH_N")
	)
	(segment
		(start 391.127488 -82.69351)
		(end 391.346436 -82.912458)
		(width 0.089408)
		(layer "In9.Cu")
		(net "FM_CPU_ERR1_PCH_N")
	)
	(segment
		(start 386.765292 -92.593668)
		(end 386.765292 -93.316298)
		(width 0.089408)
		(layer "In9.Cu")
		(net "FM_CPU_ERR1_PCH_N")
	)
	(segment
		(start 386.3086 -92.136976)
		(end 386.765292 -92.593668)
		(width 0.089408)
		(layer "In9.Cu")
		(net "FM_CPU_ERR1_PCH_N")
	)
	(segment
		(start 394.024866 -73.036176)
		(end 393.114784 -73.946258)
		(width 0.089408)
		(layer "In9.Cu")
		(net "FM_CPU_ERR1_PCH_N")
	)
	(segment
		(start 388.536688 -88.30183)
		(end 387.58876 -88.30183)
		(width 0.089408)
		(layer "In9.Cu")
		(net "FM_CPU_ERR1_PCH_N")
	)
	(segment
		(start 391.127488 -82.047334)
		(end 391.127488 -82.69351)
		(width 0.089408)
		(layer "In9.Cu")
		(net "FM_CPU_ERR1_PCH_N")
	)
	(segment
		(start 393.114784 -73.946258)
		(end 393.114784 -76.057252)
		(width 0.089408)
		(layer "In9.Cu")
		(net "FM_CPU_ERR1_PCH_N")
	)
	(segment
		(start 391.24128 -85.597238)
		(end 388.536688 -88.30183)
		(width 0.089408)
		(layer "In9.Cu")
		(net "FM_CPU_ERR1_PCH_N")
	)
	(segment
		(start 387.58876 -88.30183)
		(end 386.779008 -89.111582)
		(width 0.089408)
		(layer "In9.Cu")
		(net "FM_CPU_ERR1_PCH_N")
	)
	(segment
		(start 386.15493 -93.92666)
		(end 386.15493 -96.279462)
		(width 0.089408)
		(layer "In9.Cu")
		(net "FM_CPU_ERR1_PCH_N")
	)
	(segment
		(start 396.11427 -63.221616)
		(end 395.356334 -63.979552)
		(width 0.089408)
		(layer "In9.Cu")
		(net "FM_CPU_ERR1_PCH_N")
	)
	(segment
		(start 393.654026 -71.227696)
		(end 393.654026 -71.385684)
		(width 0.089408)
		(layer "In9.Cu")
		(net "FM_CPU_ERR1_PCH_N")
	)
	(segment
		(start 391.874248 -81.300574)
		(end 391.127488 -82.047334)
		(width 0.089408)
		(layer "In9.Cu")
		(net "FM_CPU_ERR1_PCH_N")
	)
	(segment
		(start 386.161026 -97.17532)
		(end 386.316474 -97.17532)
		(width 0.0889)
		(layer "In9.Cu")
		(net "FM_CPU_ERR1_PCH_N")
	)
	(segment
		(start 397.111982 -61.133736)
		(end 397.111982 -61.291724)
		(width 0.089408)
		(layer "In9.Cu")
		(net "FM_CPU_ERR1_PCH_N")
	)
	(segment
		(start 386.15493 -96.279462)
		(end 385.85267 -96.581722)
		(width 0.089408)
		(layer "In9.Cu")
		(net "FM_CPU_ERR1_PCH_N")
	)
	(segment
		(start 385.8514 -96.582992)
		(end 385.8514 -96.758252)
		(width 0.0889)
		(layer "In9.Cu")
		(net "FM_CPU_ERR1_PCH_N")
	)
	(segment
		(start 392.69289 -77.70368)
		(end 391.54862 -78.84795)
		(width 0.089408)
		(layer "In9.Cu")
		(net "FM_CPU_ERR1_PCH_N")
	)
	(arc
		(start 385.8514 -96.758252)
		(mid 385.90775 -96.952102)
		(end 386.051552 -97.093786)
		(width 0.0889)
		(layer "In9.Cu")
		(net "FM_CPU_ERR1_PCH_N")
	)
	(arc
		(start 386.051552 -97.093786)
		(mid 386.10865 -97.131383)
		(end 386.161026 -97.17532)
		(width 0.0889)
		(layer "In9.Cu")
		(net "FM_CPU_ERR1_PCH_N")
	)
	(segment
		(start 385.75615 -95.888556)
		(end 385.26085 -96.11868)
		(width 0.10795)
		(layer "F.Cu")
		(net "FM_CPU_ERR0_PCH_N")
	)
	(via
		(at 404.677372 -48.711104)
		(size 0.508)
		(drill 0.254)
		(layers "F.Cu" "B.Cu")
		(net "FM_CPU_ERR0_PCH_N")
	)
	(via
		(at 395.677898 -48.827944)
		(size 0.508)
		(drill 0.254)
		(layers "F.Cu" "B.Cu")
		(net "FM_CPU_ERR0_PCH_N")
	)
	(via
		(at 385.75615 -95.888556)
		(size 0.508)
		(drill 0.254)
		(layers "F.Cu" "B.Cu")
		(net "FM_CPU_ERR0_PCH_N")
	)
	(segment
		(start 410.760164 -50.8)
		(end 407.834592 -50.8)
		(width 0.10795)
		(layer "B.Cu")
		(net "FM_CPU_ERR0_PCH_N")
	)
	(segment
		(start 405.623522 -49.95545)
		(end 404.677372 -49.0093)
		(width 0.10795)
		(layer "B.Cu")
		(net "FM_CPU_ERR0_PCH_N")
	)
	(segment
		(start 407.247598 -50.213006)
		(end 407.247598 -50.207164)
		(width 0.10795)
		(layer "B.Cu")
		(net "FM_CPU_ERR0_PCH_N")
	)
	(segment
		(start 411.424374 -49.219866)
		(end 411.066742 -49.577498)
		(width 0.10795)
		(layer "B.Cu")
		(net "FM_CPU_ERR0_PCH_N")
	)
	(segment
		(start 406.995884 -49.95545)
		(end 405.623522 -49.95545)
		(width 0.10795)
		(layer "B.Cu")
		(net "FM_CPU_ERR0_PCH_N")
	)
	(segment
		(start 411.066742 -50.493422)
		(end 410.760164 -50.8)
		(width 0.10795)
		(layer "B.Cu")
		(net "FM_CPU_ERR0_PCH_N")
	)
	(segment
		(start 407.834592 -50.8)
		(end 407.247598 -50.213006)
		(width 0.10795)
		(layer "B.Cu")
		(net "FM_CPU_ERR0_PCH_N")
	)
	(segment
		(start 407.247598 -50.207164)
		(end 406.995884 -49.95545)
		(width 0.10795)
		(layer "B.Cu")
		(net "FM_CPU_ERR0_PCH_N")
	)
	(segment
		(start 411.066742 -49.577498)
		(end 411.066742 -50.493422)
		(width 0.10795)
		(layer "B.Cu")
		(net "FM_CPU_ERR0_PCH_N")
	)
	(segment
		(start 404.677372 -49.0093)
		(end 404.677372 -48.711104)
		(width 0.10795)
		(layer "B.Cu")
		(net "FM_CPU_ERR0_PCH_N")
	)
	(segment
		(start 411.424374 -48.687482)
		(end 411.424374 -49.219866)
		(width 0.10795)
		(layer "B.Cu")
		(net "FM_CPU_ERR0_PCH_N")
	)
	(segment
		(start 396.676626 -48.29556)
		(end 404.261828 -48.29556)
		(width 0.089408)
		(layer "In2.Cu")
		(net "FM_CPU_ERR0_PCH_N")
	)
	(segment
		(start 395.677898 -48.827944)
		(end 396.144242 -48.827944)
		(width 0.089408)
		(layer "In2.Cu")
		(net "FM_CPU_ERR0_PCH_N")
	)
	(segment
		(start 396.144242 -48.827944)
		(end 396.676626 -48.29556)
		(width 0.089408)
		(layer "In2.Cu")
		(net "FM_CPU_ERR0_PCH_N")
	)
	(segment
		(start 404.261828 -48.29556)
		(end 404.677372 -48.711104)
		(width 0.089408)
		(layer "In2.Cu")
		(net "FM_CPU_ERR0_PCH_N")
	)
	(segment
		(start 391.155428 -84.02574)
		(end 391.155428 -82.991706)
		(width 0.089408)
		(layer "In9.Cu")
		(net "FM_CPU_ERR0_PCH_N")
	)
	(segment
		(start 386.117592 -91.555062)
		(end 386.588 -91.084654)
		(width 0.089408)
		(layer "In9.Cu")
		(net "FM_CPU_ERR0_PCH_N")
	)
	(segment
		(start 391.155428 -82.991706)
		(end 390.93648 -82.772758)
		(width 0.089408)
		(layer "In9.Cu")
		(net "FM_CPU_ERR0_PCH_N")
	)
	(segment
		(start 393.833858 -72.343772)
		(end 393.463272 -71.973186)
		(width 0.089408)
		(layer "In9.Cu")
		(net "FM_CPU_ERR0_PCH_N")
	)
	(segment
		(start 388.45744 -88.110822)
		(end 390.749536 -85.818726)
		(width 0.089408)
		(layer "In9.Cu")
		(net "FM_CPU_ERR0_PCH_N")
	)
	(segment
		(start 392.923776 -73.86701)
		(end 393.833858 -72.956928)
		(width 0.089408)
		(layer "In9.Cu")
		(net "FM_CPU_ERR0_PCH_N")
	)
	(segment
		(start 385.75615 -95.888556)
		(end 385.75615 -93.982286)
		(width 0.089408)
		(layer "In9.Cu")
		(net "FM_CPU_ERR0_PCH_N")
	)
	(segment
		(start 386.117592 -92.21597)
		(end 386.117592 -91.555062)
		(width 0.089408)
		(layer "In9.Cu")
		(net "FM_CPU_ERR0_PCH_N")
	)
	(segment
		(start 396.1384 -58.4708)
		(end 396.1384 -49.538128)
		(width 0.089408)
		(layer "In9.Cu")
		(net "FM_CPU_ERR0_PCH_N")
	)
	(segment
		(start 386.58927 -89.846404)
		(end 386.588 -89.845134)
		(width 0.089408)
		(layer "In9.Cu")
		(net "FM_CPU_ERR0_PCH_N")
	)
	(segment
		(start 391.68324 -81.221326)
		(end 391.68324 -79.759048)
		(width 0.089408)
		(layer "In9.Cu")
		(net "FM_CPU_ERR0_PCH_N")
	)
	(segment
		(start 391.357612 -78.768702)
		(end 392.498072 -77.628242)
		(width 0.089408)
		(layer "In9.Cu")
		(net "FM_CPU_ERR0_PCH_N")
	)
	(segment
		(start 395.677898 -49.077626)
		(end 395.677898 -48.827944)
		(width 0.089408)
		(layer "In9.Cu")
		(net "FM_CPU_ERR0_PCH_N")
	)
	(segment
		(start 386.588 -89.845134)
		(end 386.588 -89.032334)
		(width 0.089408)
		(layer "In9.Cu")
		(net "FM_CPU_ERR0_PCH_N")
	)
	(segment
		(start 386.588 -89.032334)
		(end 387.509512 -88.110822)
		(width 0.089408)
		(layer "In9.Cu")
		(net "FM_CPU_ERR0_PCH_N")
	)
	(segment
		(start 386.574538 -92.672916)
		(end 386.117592 -92.21597)
		(width 0.089408)
		(layer "In9.Cu")
		(net "FM_CPU_ERR0_PCH_N")
	)
	(segment
		(start 386.588 -91.084654)
		(end 386.588 -90.179398)
		(width 0.089408)
		(layer "In9.Cu")
		(net "FM_CPU_ERR0_PCH_N")
	)
	(segment
		(start 391.357612 -79.43342)
		(end 391.357612 -78.768702)
		(width 0.089408)
		(layer "In9.Cu")
		(net "FM_CPU_ERR0_PCH_N")
	)
	(segment
		(start 386.58927 -90.178128)
		(end 386.58927 -89.846404)
		(width 0.089408)
		(layer "In9.Cu")
		(net "FM_CPU_ERR0_PCH_N")
	)
	(segment
		(start 392.498072 -76.392024)
		(end 392.923776 -75.96632)
		(width 0.089408)
		(layer "In9.Cu")
		(net "FM_CPU_ERR0_PCH_N")
	)
	(segment
		(start 395.165072 -65.085976)
		(end 395.165072 -64.769492)
		(width 0.089408)
		(layer "In9.Cu")
		(net "FM_CPU_ERR0_PCH_N")
	)
	(segment
		(start 386.588 -90.179398)
		(end 386.58927 -90.178128)
		(width 0.089408)
		(layer "In9.Cu")
		(net "FM_CPU_ERR0_PCH_N")
	)
	(segment
		(start 386.383784 -93.354652)
		(end 386.383784 -93.352874)
		(width 0.089408)
		(layer "In9.Cu")
		(net "FM_CPU_ERR0_PCH_N")
	)
	(segment
		(start 395.923262 -62.210188)
		(end 396.92072 -61.21273)
		(width 0.089408)
		(layer "In9.Cu")
		(net "FM_CPU_ERR0_PCH_N")
	)
	(segment
		(start 395.165072 -64.769492)
		(end 395.165326 -64.769238)
		(width 0.089408)
		(layer "In9.Cu")
		(net "FM_CPU_ERR0_PCH_N")
	)
	(segment
		(start 390.749536 -85.818726)
		(end 390.749536 -84.431632)
		(width 0.089408)
		(layer "In9.Cu")
		(net "FM_CPU_ERR0_PCH_N")
	)
	(segment
		(start 392.498072 -77.628242)
		(end 392.498072 -76.392024)
		(width 0.089408)
		(layer "In9.Cu")
		(net "FM_CPU_ERR0_PCH_N")
	)
	(segment
		(start 393.463272 -71.973186)
		(end 393.463272 -71.465186)
		(width 0.089408)
		(layer "In9.Cu")
		(net "FM_CPU_ERR0_PCH_N")
	)
	(segment
		(start 395.165326 -64.769238)
		(end 395.165326 -63.900304)
		(width 0.089408)
		(layer "In9.Cu")
		(net "FM_CPU_ERR0_PCH_N")
	)
	(segment
		(start 385.75615 -93.982286)
		(end 386.383784 -93.354652)
		(width 0.089408)
		(layer "In9.Cu")
		(net "FM_CPU_ERR0_PCH_N")
	)
	(segment
		(start 390.749536 -84.431632)
		(end 391.155428 -84.02574)
		(width 0.089408)
		(layer "In9.Cu")
		(net "FM_CPU_ERR0_PCH_N")
	)
	(segment
		(start 390.93648 -81.968086)
		(end 391.68324 -81.221326)
		(width 0.089408)
		(layer "In9.Cu")
		(net "FM_CPU_ERR0_PCH_N")
	)
	(segment
		(start 390.93648 -82.772758)
		(end 390.93648 -81.968086)
		(width 0.089408)
		(layer "In9.Cu")
		(net "FM_CPU_ERR0_PCH_N")
	)
	(segment
		(start 396.1384 -49.538128)
		(end 395.677898 -49.077626)
		(width 0.089408)
		(layer "In9.Cu")
		(net "FM_CPU_ERR0_PCH_N")
	)
	(segment
		(start 395.923262 -63.142368)
		(end 395.923262 -62.210188)
		(width 0.089408)
		(layer "In9.Cu")
		(net "FM_CPU_ERR0_PCH_N")
	)
	(segment
		(start 395.165326 -63.900304)
		(end 395.923262 -63.142368)
		(width 0.089408)
		(layer "In9.Cu")
		(net "FM_CPU_ERR0_PCH_N")
	)
	(segment
		(start 396.92072 -59.25312)
		(end 396.1384 -58.4708)
		(width 0.089408)
		(layer "In9.Cu")
		(net "FM_CPU_ERR0_PCH_N")
	)
	(segment
		(start 393.463272 -71.465186)
		(end 393.463018 -71.464932)
		(width 0.089408)
		(layer "In9.Cu")
		(net "FM_CPU_ERR0_PCH_N")
	)
	(segment
		(start 396.92072 -61.21273)
		(end 396.92072 -59.25312)
		(width 0.089408)
		(layer "In9.Cu")
		(net "FM_CPU_ERR0_PCH_N")
	)
	(segment
		(start 395.165326 -69.44614)
		(end 395.165326 -65.08623)
		(width 0.089408)
		(layer "In9.Cu")
		(net "FM_CPU_ERR0_PCH_N")
	)
	(segment
		(start 392.923776 -75.96632)
		(end 392.923776 -73.86701)
		(width 0.089408)
		(layer "In9.Cu")
		(net "FM_CPU_ERR0_PCH_N")
	)
	(segment
		(start 393.463018 -71.148448)
		(end 395.165326 -69.44614)
		(width 0.089408)
		(layer "In9.Cu")
		(net "FM_CPU_ERR0_PCH_N")
	)
	(segment
		(start 386.574538 -93.16212)
		(end 386.574538 -92.672916)
		(width 0.089408)
		(layer "In9.Cu")
		(net "FM_CPU_ERR0_PCH_N")
	)
	(segment
		(start 393.833858 -72.956928)
		(end 393.833858 -72.343772)
		(width 0.089408)
		(layer "In9.Cu")
		(net "FM_CPU_ERR0_PCH_N")
	)
	(segment
		(start 387.509512 -88.110822)
		(end 388.45744 -88.110822)
		(width 0.089408)
		(layer "In9.Cu")
		(net "FM_CPU_ERR0_PCH_N")
	)
	(segment
		(start 395.165326 -65.08623)
		(end 395.165072 -65.085976)
		(width 0.089408)
		(layer "In9.Cu")
		(net "FM_CPU_ERR0_PCH_N")
	)
	(segment
		(start 391.68324 -79.759048)
		(end 391.357612 -79.43342)
		(width 0.089408)
		(layer "In9.Cu")
		(net "FM_CPU_ERR0_PCH_N")
	)
	(segment
		(start 386.383784 -93.352874)
		(end 386.574538 -93.16212)
		(width 0.089408)
		(layer "In9.Cu")
		(net "FM_CPU_ERR0_PCH_N")
	)
	(segment
		(start 393.463018 -71.464932)
		(end 393.463018 -71.148448)
		(width 0.089408)
		(layer "In9.Cu")
		(net "FM_CPU_ERR0_PCH_N")
	)
	(segment
		(start 173.6852 -113.6396)
		(end 174.244 -114.1984)
		(width 0.10795)
		(layer "F.Cu")
		(net "FM_CPU_BMC_INIT")
	)
	(segment
		(start 162.70097 -87.89797)
		(end 160.879536 -86.076536)
		(width 0.10795)
		(layer "F.Cu")
		(net "FM_CPU_BMC_INIT")
	)
	(segment
		(start 427.096428 -18.449544)
		(end 426.6946 -18.851372)
		(width 0.10795)
		(layer "F.Cu")
		(net "FM_CPU_BMC_INIT")
	)
	(segment
		(start 384.893312 -92.300806)
		(end 384.893312 -93.453204)
		(width 0.0889)
		(layer "F.Cu")
		(net "FM_CPU_BMC_INIT")
	)
	(segment
		(start 175.081692 -98.917506)
		(end 173.294294 -98.917506)
		(width 0.10795)
		(layer "F.Cu")
		(net "FM_CPU_BMC_INIT")
	)
	(segment
		(start 173.832012 -90.291412)
		(end 163.731956 -90.291412)
		(width 0.10795)
		(layer "F.Cu")
		(net "FM_CPU_BMC_INIT")
	)
	(segment
		(start 165.3794 -110.4646)
		(end 164.8206 -111.0234)
		(width 0.10795)
		(layer "F.Cu")
		(net "FM_CPU_BMC_INIT")
	)
	(segment
		(start 281.01036 -81.96072)
		(end 281.01036 -82.1944)
		(width 0.10795)
		(layer "F.Cu")
		(net "FM_CPU_BMC_INIT")
	)
	(segment
		(start 165.83025 -108.54055)
		(end 165.3794 -108.9914)
		(width 0.10795)
		(layer "F.Cu")
		(net "FM_CPU_BMC_INIT")
	)
	(segment
		(start 185.928 -96.52)
		(end 185.71972 -96.31172)
		(width 0.10795)
		(layer "F.Cu")
		(net "FM_CPU_BMC_INIT")
	)
	(segment
		(start 163.2712 -109.9312)
		(end 159.8676 -109.9312)
		(width 0.10795)
		(layer "F.Cu")
		(net "FM_CPU_BMC_INIT")
	)
	(segment
		(start 281.01036 -82.1944)
		(end 281.39136 -82.5754)
		(width 0.10795)
		(layer "F.Cu")
		(net "FM_CPU_BMC_INIT")
	)
	(segment
		(start 162.70097 -89.260426)
		(end 162.70097 -87.89797)
		(width 0.10795)
		(layer "F.Cu")
		(net "FM_CPU_BMC_INIT")
	)
	(segment
		(start 163.731956 -90.291412)
		(end 162.70097 -89.260426)
		(width 0.10795)
		(layer "F.Cu")
		(net "FM_CPU_BMC_INIT")
	)
	(segment
		(start 176.1998 -121.4882)
		(end 174.361602 -123.326398)
		(width 0.10795)
		(layer "F.Cu")
		(net "FM_CPU_BMC_INIT")
	)
	(segment
		(start 170.526964 -108.458254)
		(end 165.913054 -108.458254)
		(width 0.10795)
		(layer "F.Cu")
		(net "FM_CPU_BMC_INIT")
	)
	(segment
		(start 179.5526 -128.9812)
		(end 180.226208 -128.9812)
		(width 0.10795)
		(layer "F.Cu")
		(net "FM_CPU_BMC_INIT")
	)
	(segment
		(start 172.2374 -99.9744)
		(end 172.2374 -106.8324)
		(width 0.10795)
		(layer "F.Cu")
		(net "FM_CPU_BMC_INIT")
	)
	(segment
		(start 177.27549 -96.72066)
		(end 177.038 -96.95815)
		(width 0.10795)
		(layer "F.Cu")
		(net "FM_CPU_BMC_INIT")
	)
	(segment
		(start 427.91888 -17.4244)
		(end 427.91888 -18.36039)
		(width 0.10795)
		(layer "F.Cu")
		(net "FM_CPU_BMC_INIT")
	)
	(segment
		(start 165.3794 -108.9914)
		(end 165.3794 -110.4646)
		(width 0.10795)
		(layer "F.Cu")
		(net "FM_CPU_BMC_INIT")
	)
	(segment
		(start 115.2144 -74.5998)
		(end 116.2812 -74.5998)
		(width 0.10795)
		(layer "F.Cu")
		(net "FM_CPU_BMC_INIT")
	)
	(segment
		(start 176.2506 -98.425)
		(end 175.574198 -98.425)
		(width 0.10795)
		(layer "F.Cu")
		(net "FM_CPU_BMC_INIT")
	)
	(segment
		(start 281.39136 -82.5754)
		(end 281.7368 -82.5754)
		(width 0.10795)
		(layer "F.Cu")
		(net "FM_CPU_BMC_INIT")
	)
	(segment
		(start 170.6118 -108.458)
		(end 170.527218 -108.458)
		(width 0.10795)
		(layer "F.Cu")
		(net "FM_CPU_BMC_INIT")
	)
	(segment
		(start 170.527218 -108.458)
		(end 170.526964 -108.458254)
		(width 0.10795)
		(layer "F.Cu")
		(net "FM_CPU_BMC_INIT")
	)
	(segment
		(start 427.829726 -18.449544)
		(end 427.096428 -18.449544)
		(width 0.10795)
		(layer "F.Cu")
		(net "FM_CPU_BMC_INIT")
	)
	(segment
		(start 174.244 -116.2304)
		(end 176.1998 -118.1862)
		(width 0.10795)
		(layer "F.Cu")
		(net "FM_CPU_BMC_INIT")
	)
	(segment
		(start 176.1998 -118.1862)
		(end 176.1998 -121.4882)
		(width 0.10795)
		(layer "F.Cu")
		(net "FM_CPU_BMC_INIT")
	)
	(segment
		(start 174.361602 -126.990602)
		(end 175.0568 -127.6858)
		(width 0.10795)
		(layer "F.Cu")
		(net "FM_CPU_BMC_INIT")
	)
	(segment
		(start 175.574198 -98.425)
		(end 175.081692 -98.917506)
		(width 0.10795)
		(layer "F.Cu")
		(net "FM_CPU_BMC_INIT")
	)
	(segment
		(start 159.8676 -109.9312)
		(end 159.1564 -110.6424)
		(width 0.10795)
		(layer "F.Cu")
		(net "FM_CPU_BMC_INIT")
	)
	(segment
		(start 165.830758 -108.54055)
		(end 165.83025 -108.54055)
		(width 0.10795)
		(layer "F.Cu")
		(net "FM_CPU_BMC_INIT")
	)
	(segment
		(start 165.913054 -108.458254)
		(end 165.830758 -108.54055)
		(width 0.10795)
		(layer "F.Cu")
		(net "FM_CPU_BMC_INIT")
	)
	(segment
		(start 185.71972 -96.31172)
		(end 183.568848 -96.31172)
		(width 0.10795)
		(layer "F.Cu")
		(net "FM_CPU_BMC_INIT")
	)
	(segment
		(start 174.361602 -123.326398)
		(end 174.361602 -126.990602)
		(width 0.10795)
		(layer "F.Cu")
		(net "FM_CPU_BMC_INIT")
	)
	(segment
		(start 174.244 -114.1984)
		(end 174.244 -116.2304)
		(width 0.10795)
		(layer "F.Cu")
		(net "FM_CPU_BMC_INIT")
	)
	(segment
		(start 160.879536 -84.459064)
		(end 161.5694 -83.7692)
		(width 0.10795)
		(layer "F.Cu")
		(net "FM_CPU_BMC_INIT")
	)
	(segment
		(start 427.91888 -18.36039)
		(end 427.829726 -18.449544)
		(width 0.10795)
		(layer "F.Cu")
		(net "FM_CPU_BMC_INIT")
	)
	(segment
		(start 426.6946 -18.851372)
		(end 426.6946 -18.923)
		(width 0.10795)
		(layer "F.Cu")
		(net "FM_CPU_BMC_INIT")
	)
	(segment
		(start 160.879536 -86.076536)
		(end 160.879536 -84.459064)
		(width 0.10795)
		(layer "F.Cu")
		(net "FM_CPU_BMC_INIT")
	)
	(segment
		(start 177.038 -97.6376)
		(end 176.2506 -98.425)
		(width 0.10795)
		(layer "F.Cu")
		(net "FM_CPU_BMC_INIT")
	)
	(segment
		(start 384.893312 -93.453204)
		(end 384.985006 -93.544898)
		(width 0.0889)
		(layer "F.Cu")
		(net "FM_CPU_BMC_INIT")
	)
	(segment
		(start 115.210844 -74.596244)
		(end 115.2144 -74.5998)
		(width 0.10795)
		(layer "F.Cu")
		(net "FM_CPU_BMC_INIT")
	)
	(segment
		(start 176.533556 -92.992956)
		(end 173.832012 -90.291412)
		(width 0.10795)
		(layer "F.Cu")
		(net "FM_CPU_BMC_INIT")
	)
	(segment
		(start 159.1564 -110.6424)
		(end 159.1564 -112.9538)
		(width 0.10795)
		(layer "F.Cu")
		(net "FM_CPU_BMC_INIT")
	)
	(segment
		(start 115.1636 -74.596244)
		(end 115.210844 -74.596244)
		(width 0.10795)
		(layer "F.Cu")
		(net "FM_CPU_BMC_INIT")
	)
	(segment
		(start 183.568848 -96.31172)
		(end 180.250084 -92.992956)
		(width 0.10795)
		(layer "F.Cu")
		(net "FM_CPU_BMC_INIT")
	)
	(segment
		(start 159.8422 -113.6396)
		(end 173.6852 -113.6396)
		(width 0.10795)
		(layer "F.Cu")
		(net "FM_CPU_BMC_INIT")
	)
	(segment
		(start 185.72734 -96.72066)
		(end 177.27549 -96.72066)
		(width 0.10795)
		(layer "F.Cu")
		(net "FM_CPU_BMC_INIT")
	)
	(segment
		(start 172.2374 -106.8324)
		(end 170.6118 -108.458)
		(width 0.10795)
		(layer "F.Cu")
		(net "FM_CPU_BMC_INIT")
	)
	(segment
		(start 159.1564 -112.9538)
		(end 159.8422 -113.6396)
		(width 0.10795)
		(layer "F.Cu")
		(net "FM_CPU_BMC_INIT")
	)
	(segment
		(start 164.8206 -111.0234)
		(end 164.3634 -111.0234)
		(width 0.10795)
		(layer "F.Cu")
		(net "FM_CPU_BMC_INIT")
	)
	(segment
		(start 181.525926 -130.280918)
		(end 181.612286 -130.280918)
		(width 0.10795)
		(layer "F.Cu")
		(net "FM_CPU_BMC_INIT")
	)
	(segment
		(start 180.250084 -92.992956)
		(end 176.533556 -92.992956)
		(width 0.10795)
		(layer "F.Cu")
		(net "FM_CPU_BMC_INIT")
	)
	(segment
		(start 177.038 -96.95815)
		(end 177.038 -97.6376)
		(width 0.10795)
		(layer "F.Cu")
		(net "FM_CPU_BMC_INIT")
	)
	(segment
		(start 180.226208 -128.9812)
		(end 181.525926 -130.280918)
		(width 0.10795)
		(layer "F.Cu")
		(net "FM_CPU_BMC_INIT")
	)
	(segment
		(start 185.928 -96.52)
		(end 185.72734 -96.72066)
		(width 0.10795)
		(layer "F.Cu")
		(net "FM_CPU_BMC_INIT")
	)
	(segment
		(start 164.3634 -111.0234)
		(end 163.2712 -109.9312)
		(width 0.10795)
		(layer "F.Cu")
		(net "FM_CPU_BMC_INIT")
	)
	(segment
		(start 175.0568 -127.6858)
		(end 178.2572 -127.6858)
		(width 0.10795)
		(layer "F.Cu")
		(net "FM_CPU_BMC_INIT")
	)
	(segment
		(start 178.2572 -127.6858)
		(end 179.5526 -128.9812)
		(width 0.10795)
		(layer "F.Cu")
		(net "FM_CPU_BMC_INIT")
	)
	(segment
		(start 173.294294 -98.917506)
		(end 172.2374 -99.9744)
		(width 0.10795)
		(layer "F.Cu")
		(net "FM_CPU_BMC_INIT")
	)
	(via
		(at 384.893312 -92.300806)
		(size 0.508)
		(drill 0.254)
		(layers "F.Cu" "B.Cu")
		(net "FM_CPU_BMC_INIT")
	)
	(via
		(at 185.928 -96.52)
		(size 0.508)
		(drill 0.254)
		(layers "F.Cu" "B.Cu")
		(net "FM_CPU_BMC_INIT")
	)
	(via
		(at 161.5694 -83.7692)
		(size 0.508)
		(drill 0.254)
		(layers "F.Cu" "B.Cu")
		(net "FM_CPU_BMC_INIT")
	)
	(via
		(at 426.6946 -18.923)
		(size 0.508)
		(drill 0.254)
		(layers "F.Cu" "B.Cu")
		(net "FM_CPU_BMC_INIT")
	)
	(via
		(at 281.7368 -82.5754)
		(size 0.508)
		(drill 0.254)
		(layers "F.Cu" "B.Cu")
		(net "FM_CPU_BMC_INIT")
	)
	(via
		(at 181.612286 -130.280918)
		(size 0.508)
		(drill 0.254)
		(layers "F.Cu" "B.Cu")
		(net "FM_CPU_BMC_INIT")
	)
	(via
		(at 371.007894 -123.162314)
		(size 0.508)
		(drill 0.254)
		(layers "F.Cu" "B.Cu")
		(net "FM_CPU_BMC_INIT")
	)
	(via
		(at 115.1636 -74.596244)
		(size 0.508)
		(drill 0.254)
		(layers "F.Cu" "B.Cu")
		(net "FM_CPU_BMC_INIT")
	)
	(via
		(at 162.70097 -87.89797)
		(size 0.762)
		(drill 0.381)
		(layers "F.Cu" "B.Cu")
		(net "FM_CPU_BMC_INIT")
	)
	(segment
		(start 378.4092 -102.5906)
		(end 378.4092 -102.9208)
		(width 0.089408)
		(layer "In4.Cu")
		(net "FM_CPU_BMC_INIT")
	)
	(segment
		(start 376.9106 -105.436416)
		(end 376.403616 -105.9434)
		(width 0.089408)
		(layer "In4.Cu")
		(net "FM_CPU_BMC_INIT")
	)
	(segment
		(start 120.463818 -86.212934)
		(end 119.772684 -85.5218)
		(width 0.089408)
		(layer "In4.Cu")
		(net "FM_CPU_BMC_INIT")
	)
	(segment
		(start 119.772684 -85.5218)
		(end 118.9736 -85.5218)
		(width 0.089408)
		(layer "In4.Cu")
		(net "FM_CPU_BMC_INIT")
	)
	(segment
		(start 376.275346 -105.9434)
		(end 375.746518 -106.472228)
		(width 0.089408)
		(layer "In4.Cu")
		(net "FM_CPU_BMC_INIT")
	)
	(segment
		(start 148.183854 -94.946978)
		(end 148.183854 -92.451428)
		(width 0.089408)
		(layer "In4.Cu")
		(net "FM_CPU_BMC_INIT")
	)
	(segment
		(start 144.522444 -87.205058)
		(end 143.4084 -87.205058)
		(width 0.0889)
		(layer "In4.Cu")
		(net "FM_CPU_BMC_INIT")
	)
	(segment
		(start 375.316496 -112.456722)
		(end 374.74652 -113.026698)
		(width 0.089408)
		(layer "In4.Cu")
		(net "FM_CPU_BMC_INIT")
	)
	(segment
		(start 113.0554 -79.6036)
		(end 113.0554 -76.2254)
		(width 0.089408)
		(layer "In4.Cu")
		(net "FM_CPU_BMC_INIT")
	)
	(segment
		(start 384.893312 -94.074488)
		(end 383.286 -95.6818)
		(width 0.089408)
		(layer "In4.Cu")
		(net "FM_CPU_BMC_INIT")
	)
	(segment
		(start 113.0554 -76.2254)
		(end 114.684556 -74.596244)
		(width 0.089408)
		(layer "In4.Cu")
		(net "FM_CPU_BMC_INIT")
	)
	(segment
		(start 157.327346 -95.862902)
		(end 149.099778 -95.862902)
		(width 0.089408)
		(layer "In4.Cu")
		(net "FM_CPU_BMC_INIT")
	)
	(segment
		(start 131.661408 -86.708488)
		(end 131.643628 -86.708488)
		(width 0.0889)
		(layer "In4.Cu")
		(net "FM_CPU_BMC_INIT")
	)
	(segment
		(start 378.42317 -97.440242)
		(end 378.42317 -97.77095)
		(width 0.089408)
		(layer "In4.Cu")
		(net "FM_CPU_BMC_INIT")
	)
	(segment
		(start 149.099778 -95.862902)
		(end 148.183854 -94.946978)
		(width 0.089408)
		(layer "In4.Cu")
		(net "FM_CPU_BMC_INIT")
	)
	(segment
		(start 378.72543 -100.475288)
		(end 378.42317 -100.777548)
		(width 0.089408)
		(layer "In4.Cu")
		(net "FM_CPU_BMC_INIT")
	)
	(segment
		(start 378.42317 -100.777548)
		(end 378.42317 -101.298756)
		(width 0.089408)
		(layer "In4.Cu")
		(net "FM_CPU_BMC_INIT")
	)
	(segment
		(start 378.72543 -102.27437)
		(end 378.4092 -102.5906)
		(width 0.089408)
		(layer "In4.Cu")
		(net "FM_CPU_BMC_INIT")
	)
	(segment
		(start 144.961864 -87.205058)
		(end 144.522444 -87.205058)
		(width 0.089408)
		(layer "In4.Cu")
		(net "FM_CPU_BMC_INIT")
	)
	(segment
		(start 383.286 -95.6818)
		(end 383.286 -95.95104)
		(width 0.089408)
		(layer "In4.Cu")
		(net "FM_CPU_BMC_INIT")
	)
	(segment
		(start 384.893312 -92.300806)
		(end 384.893312 -94.074488)
		(width 0.089408)
		(layer "In4.Cu")
		(net "FM_CPU_BMC_INIT")
	)
	(segment
		(start 378.72543 -99.79025)
		(end 378.72543 -100.475288)
		(width 0.089408)
		(layer "In4.Cu")
		(net "FM_CPU_BMC_INIT")
	)
	(segment
		(start 379.151896 -96.348296)
		(end 378.91847 -96.581722)
		(width 0.089408)
		(layer "In4.Cu")
		(net "FM_CPU_BMC_INIT")
	)
	(segment
		(start 120.847358 -86.413086)
		(end 120.844056 -86.407244)
		(width 0.0889)
		(layer "In4.Cu")
		(net "FM_CPU_BMC_INIT")
	)
	(segment
		(start 375.746518 -106.472228)
		(end 375.746518 -111.37646)
		(width 0.089408)
		(layer "In4.Cu")
		(net "FM_CPU_BMC_INIT")
	)
	(segment
		(start 376.9106 -104.5464)
		(end 376.9106 -105.436416)
		(width 0.089408)
		(layer "In4.Cu")
		(net "FM_CPU_BMC_INIT")
	)
	(segment
		(start 378.72543 -98.07321)
		(end 378.72543 -98.855022)
		(width 0.089408)
		(layer "In4.Cu")
		(net "FM_CPU_BMC_INIT")
	)
	(segment
		(start 378.42317 -101.298756)
		(end 378.72543 -101.601016)
		(width 0.089408)
		(layer "In4.Cu")
		(net "FM_CPU_BMC_INIT")
	)
	(segment
		(start 378.72543 -98.855022)
		(end 378.42317 -99.157282)
		(width 0.089408)
		(layer "In4.Cu")
		(net "FM_CPU_BMC_INIT")
	)
	(segment
		(start 132.541264 -87.203534)
		(end 132.494782 -87.203534)
		(width 0.0889)
		(layer "In4.Cu")
		(net "FM_CPU_BMC_INIT")
	)
	(segment
		(start 120.500902 -86.212934)
		(end 120.463818 -86.212934)
		(width 0.0889)
		(layer "In4.Cu")
		(net "FM_CPU_BMC_INIT")
	)
	(segment
		(start 159.548322 -83.7692)
		(end 158.000192 -85.31733)
		(width 0.089408)
		(layer "In4.Cu")
		(net "FM_CPU_BMC_INIT")
	)
	(segment
		(start 148.183854 -92.451428)
		(end 146.606514 -90.874088)
		(width 0.089408)
		(layer "In4.Cu")
		(net "FM_CPU_BMC_INIT")
	)
	(segment
		(start 158.000192 -95.190056)
		(end 157.327346 -95.862902)
		(width 0.089408)
		(layer "In4.Cu")
		(net "FM_CPU_BMC_INIT")
	)
	(segment
		(start 378.42317 -99.157282)
		(end 378.42317 -99.48799)
		(width 0.089408)
		(layer "In4.Cu")
		(net "FM_CPU_BMC_INIT")
	)
	(segment
		(start 374.74652 -113.026698)
		(end 374.74652 -119.423688)
		(width 0.089408)
		(layer "In4.Cu")
		(net "FM_CPU_BMC_INIT")
	)
	(segment
		(start 133.395974 -86.708488)
		(end 133.363208 -86.708488)
		(width 0.0889)
		(layer "In4.Cu")
		(net "FM_CPU_BMC_INIT")
	)
	(segment
		(start 375.316496 -111.806482)
		(end 375.316496 -112.456722)
		(width 0.089408)
		(layer "In4.Cu")
		(net "FM_CPU_BMC_INIT")
	)
	(segment
		(start 146.606514 -90.874088)
		(end 146.606514 -88.849708)
		(width 0.089408)
		(layer "In4.Cu")
		(net "FM_CPU_BMC_INIT")
	)
	(segment
		(start 375.746518 -111.37646)
		(end 375.316496 -111.806482)
		(width 0.089408)
		(layer "In4.Cu")
		(net "FM_CPU_BMC_INIT")
	)
	(segment
		(start 142.67053 -86.94547)
		(end 142.54353 -86.81847)
		(width 0.0889)
		(layer "In4.Cu")
		(net "FM_CPU_BMC_INIT")
	)
	(segment
		(start 158.000192 -85.31733)
		(end 158.000192 -95.190056)
		(width 0.089408)
		(layer "In4.Cu")
		(net "FM_CPU_BMC_INIT")
	)
	(segment
		(start 378.42317 -99.48799)
		(end 378.72543 -99.79025)
		(width 0.089408)
		(layer "In4.Cu")
		(net "FM_CPU_BMC_INIT")
	)
	(segment
		(start 161.5694 -83.7692)
		(end 159.548322 -83.7692)
		(width 0.089408)
		(layer "In4.Cu")
		(net "FM_CPU_BMC_INIT")
	)
	(segment
		(start 378.4092 -102.9208)
		(end 377.6726 -103.6574)
		(width 0.089408)
		(layer "In4.Cu")
		(net "FM_CPU_BMC_INIT")
	)
	(segment
		(start 378.91847 -96.581722)
		(end 378.91847 -96.944942)
		(width 0.089408)
		(layer "In4.Cu")
		(net "FM_CPU_BMC_INIT")
	)
	(segment
		(start 377.6726 -103.7844)
		(end 376.9106 -104.5464)
		(width 0.089408)
		(layer "In4.Cu")
		(net "FM_CPU_BMC_INIT")
	)
	(segment
		(start 378.72543 -101.601016)
		(end 378.72543 -102.27437)
		(width 0.089408)
		(layer "In4.Cu")
		(net "FM_CPU_BMC_INIT")
	)
	(segment
		(start 377.6726 -103.6574)
		(end 377.6726 -103.7844)
		(width 0.089408)
		(layer "In4.Cu")
		(net "FM_CPU_BMC_INIT")
	)
	(segment
		(start 118.9736 -85.5218)
		(end 113.0554 -79.6036)
		(width 0.089408)
		(layer "In4.Cu")
		(net "FM_CPU_BMC_INIT")
	)
	(segment
		(start 146.606514 -88.849708)
		(end 144.961864 -87.205058)
		(width 0.089408)
		(layer "In4.Cu")
		(net "FM_CPU_BMC_INIT")
	)
	(segment
		(start 376.403616 -105.9434)
		(end 376.275346 -105.9434)
		(width 0.089408)
		(layer "In4.Cu")
		(net "FM_CPU_BMC_INIT")
	)
	(segment
		(start 114.684556 -74.596244)
		(end 115.1636 -74.596244)
		(width 0.089408)
		(layer "In4.Cu")
		(net "FM_CPU_BMC_INIT")
	)
	(segment
		(start 132.007864 -86.90864)
		(end 132.004562 -86.902798)
		(width 0.0889)
		(layer "In4.Cu")
		(net "FM_CPU_BMC_INIT")
	)
	(segment
		(start 378.42317 -97.77095)
		(end 378.72543 -98.07321)
		(width 0.089408)
		(layer "In4.Cu")
		(net "FM_CPU_BMC_INIT")
	)
	(segment
		(start 378.91847 -96.944942)
		(end 378.42317 -97.440242)
		(width 0.089408)
		(layer "In4.Cu")
		(net "FM_CPU_BMC_INIT")
	)
	(segment
		(start 382.888744 -96.348296)
		(end 379.151896 -96.348296)
		(width 0.089408)
		(layer "In4.Cu")
		(net "FM_CPU_BMC_INIT")
	)
	(segment
		(start 383.286 -95.95104)
		(end 382.888744 -96.348296)
		(width 0.089408)
		(layer "In4.Cu")
		(net "FM_CPU_BMC_INIT")
	)
	(segment
		(start 374.74652 -119.423688)
		(end 371.007894 -123.162314)
		(width 0.089408)
		(layer "In4.Cu")
		(net "FM_CPU_BMC_INIT")
	)
	(arc
		(start 132.004562 -86.902798)
		(mid 131.858596 -86.760399)
		(end 131.661408 -86.708488)
		(width 0.0889)
		(layer "In4.Cu")
		(net "FM_CPU_BMC_INIT")
	)
	(arc
		(start 132.494782 -87.203534)
		(mid 132.213482 -87.118568)
		(end 132.007864 -86.90864)
		(width 0.0889)
		(layer "In4.Cu")
		(net "FM_CPU_BMC_INIT")
	)
	(arc
		(start 120.844056 -86.407244)
		(mid 120.69809 -86.264845)
		(end 120.500902 -86.212934)
		(width 0.0889)
		(layer "In4.Cu")
		(net "FM_CPU_BMC_INIT")
	)
	(arc
		(start 124.281438 -86.413086)
		(mid 123.934728 -86.212775)
		(end 123.588018 -86.413086)
		(width 0.0889)
		(layer "In4.Cu")
		(net "FM_CPU_BMC_INIT")
	)
	(arc
		(start 131.149598 -86.413086)
		(mid 130.802888 -86.212775)
		(end 130.456178 -86.413086)
		(width 0.0889)
		(layer "In4.Cu")
		(net "FM_CPU_BMC_INIT")
	)
	(arc
		(start 128.739138 -86.413086)
		(mid 128.227328 -86.708753)
		(end 127.715518 -86.413086)
		(width 0.0889)
		(layer "In4.Cu")
		(net "FM_CPU_BMC_INIT")
	)
	(arc
		(start 121.870978 -86.413086)
		(mid 121.359168 -86.708753)
		(end 120.847358 -86.413086)
		(width 0.0889)
		(layer "In4.Cu")
		(net "FM_CPU_BMC_INIT")
	)
	(arc
		(start 133.890004 -86.413086)
		(mid 133.681396 -86.625018)
		(end 133.395974 -86.708488)
		(width 0.0889)
		(layer "In4.Cu")
		(net "FM_CPU_BMC_INIT")
	)
	(arc
		(start 131.643628 -86.708488)
		(mid 131.358204 -86.625021)
		(end 131.149598 -86.413086)
		(width 0.0889)
		(layer "In4.Cu")
		(net "FM_CPU_BMC_INIT")
	)
	(arc
		(start 137.324084 -86.413086)
		(mid 136.812274 -86.708753)
		(end 136.300464 -86.413086)
		(width 0.0889)
		(layer "In4.Cu")
		(net "FM_CPU_BMC_INIT")
	)
	(arc
		(start 122.564398 -86.413086)
		(mid 122.217688 -86.212775)
		(end 121.870978 -86.413086)
		(width 0.0889)
		(layer "In4.Cu")
		(net "FM_CPU_BMC_INIT")
	)
	(arc
		(start 139.734544 -86.413086)
		(mid 139.387834 -86.212775)
		(end 139.041124 -86.413086)
		(width 0.0889)
		(layer "In4.Cu")
		(net "FM_CPU_BMC_INIT")
	)
	(arc
		(start 135.607044 -86.413086)
		(mid 135.095234 -86.708753)
		(end 134.583424 -86.413086)
		(width 0.0889)
		(layer "In4.Cu")
		(net "FM_CPU_BMC_INIT")
	)
	(arc
		(start 138.017504 -86.413086)
		(mid 137.670794 -86.212775)
		(end 137.324084 -86.413086)
		(width 0.0889)
		(layer "In4.Cu")
		(net "FM_CPU_BMC_INIT")
	)
	(arc
		(start 143.4084 -87.205058)
		(mid 143.017297 -87.138272)
		(end 142.67053 -86.94547)
		(width 0.0889)
		(layer "In4.Cu")
		(net "FM_CPU_BMC_INIT")
	)
	(arc
		(start 123.588018 -86.413086)
		(mid 123.076208 -86.708753)
		(end 122.564398 -86.413086)
		(width 0.0889)
		(layer "In4.Cu")
		(net "FM_CPU_BMC_INIT")
	)
	(arc
		(start 140.758164 -86.413086)
		(mid 140.246354 -86.708753)
		(end 139.734544 -86.413086)
		(width 0.0889)
		(layer "In4.Cu")
		(net "FM_CPU_BMC_INIT")
	)
	(arc
		(start 139.041124 -86.413086)
		(mid 138.529314 -86.708753)
		(end 138.017504 -86.413086)
		(width 0.0889)
		(layer "In4.Cu")
		(net "FM_CPU_BMC_INIT")
	)
	(arc
		(start 127.022098 -86.413086)
		(mid 126.510288 -86.708753)
		(end 125.998478 -86.413086)
		(width 0.0889)
		(layer "In4.Cu")
		(net "FM_CPU_BMC_INIT")
	)
	(arc
		(start 129.432558 -86.413086)
		(mid 129.085848 -86.212775)
		(end 128.739138 -86.413086)
		(width 0.0889)
		(layer "In4.Cu")
		(net "FM_CPU_BMC_INIT")
	)
	(arc
		(start 125.305058 -86.413086)
		(mid 124.793248 -86.708753)
		(end 124.281438 -86.413086)
		(width 0.0889)
		(layer "In4.Cu")
		(net "FM_CPU_BMC_INIT")
	)
	(arc
		(start 136.300464 -86.413086)
		(mid 135.953754 -86.212775)
		(end 135.607044 -86.413086)
		(width 0.0889)
		(layer "In4.Cu")
		(net "FM_CPU_BMC_INIT")
	)
	(arc
		(start 141.397736 -86.340188)
		(mid 141.059558 -86.215326)
		(end 140.758164 -86.413086)
		(width 0.0889)
		(layer "In4.Cu")
		(net "FM_CPU_BMC_INIT")
	)
	(arc
		(start 142.011908 -86.583774)
		(mid 141.687058 -86.50678)
		(end 141.397736 -86.340188)
		(width 0.0889)
		(layer "In4.Cu")
		(net "FM_CPU_BMC_INIT")
	)
	(arc
		(start 133.031484 -86.908386)
		(mid 132.82448 -87.11925)
		(end 132.541264 -87.203534)
		(width 0.0889)
		(layer "In4.Cu")
		(net "FM_CPU_BMC_INIT")
	)
	(arc
		(start 133.363208 -86.708488)
		(mid 133.171566 -86.765654)
		(end 133.031484 -86.908386)
		(width 0.0889)
		(layer "In4.Cu")
		(net "FM_CPU_BMC_INIT")
	)
	(arc
		(start 127.715518 -86.413086)
		(mid 127.368808 -86.212775)
		(end 127.022098 -86.413086)
		(width 0.0889)
		(layer "In4.Cu")
		(net "FM_CPU_BMC_INIT")
	)
	(arc
		(start 125.998478 -86.413086)
		(mid 125.651768 -86.212775)
		(end 125.305058 -86.413086)
		(width 0.0889)
		(layer "In4.Cu")
		(net "FM_CPU_BMC_INIT")
	)
	(arc
		(start 142.54353 -86.81847)
		(mid 142.302478 -86.64503)
		(end 142.011908 -86.583774)
		(width 0.0889)
		(layer "In4.Cu")
		(net "FM_CPU_BMC_INIT")
	)
	(arc
		(start 134.583424 -86.413086)
		(mid 134.236714 -86.212775)
		(end 133.890004 -86.413086)
		(width 0.0889)
		(layer "In4.Cu")
		(net "FM_CPU_BMC_INIT")
	)
	(arc
		(start 130.456178 -86.413086)
		(mid 129.944368 -86.708753)
		(end 129.432558 -86.413086)
		(width 0.0889)
		(layer "In4.Cu")
		(net "FM_CPU_BMC_INIT")
	)
	(segment
		(start 396.794736 -35.251136)
		(end 396.985744 -35.060128)
		(width 0.089408)
		(layer "In9.Cu")
		(net "FM_CPU_BMC_INIT")
	)
	(segment
		(start 394.104114 -63.574422)
		(end 394.968222 -62.710314)
		(width 0.089408)
		(layer "In9.Cu")
		(net "FM_CPU_BMC_INIT")
	)
	(segment
		(start 392.2014 -71.002144)
		(end 394.104114 -69.09943)
		(width 0.089408)
		(layer "In9.Cu")
		(net "FM_CPU_BMC_INIT")
	)
	(segment
		(start 386.519674 -87.205312)
		(end 386.865876 -86.85911)
		(width 0.089408)
		(layer "In9.Cu")
		(net "FM_CPU_BMC_INIT")
	)
	(segment
		(start 397.749522 -31.58109)
		(end 397.28648 -31.118048)
		(width 0.089408)
		(layer "In9.Cu")
		(net "FM_CPU_BMC_INIT")
	)
	(segment
		(start 189.67704 -142.053818)
		(end 189.009528 -142.053818)
		(width 0.089408)
		(layer "In9.Cu")
		(net "FM_CPU_BMC_INIT")
	)
	(segment
		(start 394.758672 -51.687476)
		(end 394.886688 -51.55946)
		(width 0.089408)
		(layer "In9.Cu")
		(net "FM_CPU_BMC_INIT")
	)
	(segment
		(start 397.749522 -32.543242)
		(end 397.749522 -31.58109)
		(width 0.089408)
		(layer "In9.Cu")
		(net "FM_CPU_BMC_INIT")
	)
	(segment
		(start 325.827136 -137.222992)
		(end 325.010272 -137.222992)
		(width 0.089408)
		(layer "In9.Cu")
		(net "FM_CPU_BMC_INIT")
	)
	(segment
		(start 394.968222 -54.561486)
		(end 394.968476 -54.561232)
		(width 0.089408)
		(layer "In9.Cu")
		(net "FM_CPU_BMC_INIT")
	)
	(segment
		(start 391.968736 -73.72858)
		(end 391.806938 -73.566782)
		(width 0.089408)
		(layer "In9.Cu")
		(net "FM_CPU_BMC_INIT")
	)
	(segment
		(start 389.741156 -82.285078)
		(end 389.741156 -79.148432)
		(width 0.089408)
		(layer "In9.Cu")
		(net "FM_CPU_BMC_INIT")
	)
	(segment
		(start 343.930478 -130.556)
		(end 342.719406 -129.344928)
		(width 0.089408)
		(layer "In9.Cu")
		(net "FM_CPU_BMC_INIT")
	)
	(segment
		(start 386.865876 -86.85911)
		(end 386.865876 -86.67877)
		(width 0.089408)
		(layer "In9.Cu")
		(net "FM_CPU_BMC_INIT")
	)
	(segment
		(start 398.59204 -22.214586)
		(end 400.769836 -22.214586)
		(width 0.089408)
		(layer "In9.Cu")
		(net "FM_CPU_BMC_INIT")
	)
	(segment
		(start 389.840216 -82.384138)
		(end 389.741156 -82.285078)
		(width 0.089408)
		(layer "In9.Cu")
		(net "FM_CPU_BMC_INIT")
	)
	(segment
		(start 397.28648 -24.342344)
		(end 397.286226 -24.34209)
		(width 0.089408)
		(layer "In9.Cu")
		(net "FM_CPU_BMC_INIT")
	)
	(segment
		(start 384.01625 -91.423744)
		(end 384.01625 -89.96807)
		(width 0.089408)
		(layer "In9.Cu")
		(net "FM_CPU_BMC_INIT")
	)
	(segment
		(start 418.821108 -19.29892)
		(end 421.738298 -19.29892)
		(width 0.089408)
		(layer "In9.Cu")
		(net "FM_CPU_BMC_INIT")
	)
	(segment
		(start 341.084154 -126.918212)
		(end 340.390988 -127.611378)
		(width 0.089408)
		(layer "In9.Cu")
		(net "FM_CPU_BMC_INIT")
	)
	(segment
		(start 394.758672 -52.60848)
		(end 394.758672 -51.687476)
		(width 0.089408)
		(layer "In9.Cu")
		(net "FM_CPU_BMC_INIT")
	)
	(segment
		(start 175.797972 -130.774186)
		(end 181.119018 -130.774186)
		(width 0.089408)
		(layer "In9.Cu")
		(net "FM_CPU_BMC_INIT")
	)
	(segment
		(start 394.968476 -53.293772)
		(end 394.758418 -53.083714)
		(width 0.089408)
		(layer "In9.Cu")
		(net "FM_CPU_BMC_INIT")
	)
	(segment
		(start 354.231956 -131.608576)
		(end 352.762566 -130.139186)
		(width 0.089408)
		(layer "In9.Cu")
		(net "FM_CPU_BMC_INIT")
	)
	(segment
		(start 414.099248 -19.575526)
		(end 418.544502 -19.575526)
		(width 0.089408)
		(layer "In9.Cu")
		(net "FM_CPU_BMC_INIT")
	)
	(segment
		(start 323.764656 -138.468608)
		(end 262.648192 -138.468608)
		(width 0.089408)
		(layer "In9.Cu")
		(net "FM_CPU_BMC_INIT")
	)
	(segment
		(start 166.043356 -131.503928)
		(end 175.06823 -131.503928)
		(width 0.089408)
		(layer "In9.Cu")
		(net "FM_CPU_BMC_INIT")
	)
	(segment
		(start 164.757862 -140.90904)
		(end 164.757862 -136.43102)
		(width 0.089408)
		(layer "In9.Cu")
		(net "FM_CPU_BMC_INIT")
	)
	(segment
		(start 389.741156 -79.148432)
		(end 389.447278 -78.854554)
		(width 0.089408)
		(layer "In9.Cu")
		(net "FM_CPU_BMC_INIT")
	)
	(segment
		(start 411.087824 -22.470618)
		(end 411.087824 -21.915628)
		(width 0.089408)
		(layer "In9.Cu")
		(net "FM_CPU_BMC_INIT")
	)
	(segment
		(start 387.363208 -86.181438)
		(end 388.135114 -86.181438)
		(width 0.089408)
		(layer "In9.Cu")
		(net "FM_CPU_BMC_INIT")
	)
	(segment
		(start 341.30361 -126.163324)
		(end 341.084154 -126.38278)
		(width 0.089408)
		(layer "In9.Cu")
		(net "FM_CPU_BMC_INIT")
	)
	(segment
		(start 394.758418 -53.083714)
		(end 394.758418 -52.608734)
		(width 0.089408)
		(layer "In9.Cu")
		(net "FM_CPU_BMC_INIT")
	)
	(segment
		(start 338.480908 -127.611378)
		(end 337.637882 -128.454404)
		(width 0.089408)
		(layer "In9.Cu")
		(net "FM_CPU_BMC_INIT")
	)
	(segment
		(start 394.70457 -49.23155)
		(end 394.70457 -44.569634)
		(width 0.089408)
		(layer "In9.Cu")
		(net "FM_CPU_BMC_INIT")
	)
	(segment
		(start 389.447278 -78.52283)
		(end 389.85063 -78.119478)
		(width 0.089408)
		(layer "In9.Cu")
		(net "FM_CPU_BMC_INIT")
	)
	(segment
		(start 389.85063 -78.119478)
		(end 390.635236 -78.119478)
		(width 0.089408)
		(layer "In9.Cu")
		(net "FM_CPU_BMC_INIT")
	)
	(segment
		(start 342.719406 -127.109474)
		(end 341.773256 -126.163324)
		(width 0.089408)
		(layer "In9.Cu")
		(net "FM_CPU_BMC_INIT")
	)
	(segment
		(start 401.72132 -23.16607)
		(end 402.785326 -23.16607)
		(width 0.089408)
		(layer "In9.Cu")
		(net "FM_CPU_BMC_INIT")
	)
	(segment
		(start 358.228138 -130.772154)
		(end 356.48138 -130.772154)
		(width 0.089408)
		(layer "In9.Cu")
		(net "FM_CPU_BMC_INIT")
	)
	(segment
		(start 389.558022 -82.998056)
		(end 389.840216 -82.715862)
		(width 0.089408)
		(layer "In9.Cu")
		(net "FM_CPU_BMC_INIT")
	)
	(segment
		(start 331.583538 -134.990078)
		(end 331.583538 -135.711438)
		(width 0.089408)
		(layer "In9.Cu")
		(net "FM_CPU_BMC_INIT")
	)
	(segment
		(start 396.985744 -33.30702)
		(end 397.749522 -32.543242)
		(width 0.089408)
		(layer "In9.Cu")
		(net "FM_CPU_BMC_INIT")
	)
	(segment
		(start 384.893312 -92.300806)
		(end 384.01625 -91.423744)
		(width 0.089408)
		(layer "In9.Cu")
		(net "FM_CPU_BMC_INIT")
	)
	(segment
		(start 355.644958 -131.608576)
		(end 354.231956 -131.608576)
		(width 0.089408)
		(layer "In9.Cu")
		(net "FM_CPU_BMC_INIT")
	)
	(segment
		(start 395.731746 -43.217084)
		(end 396.07617 -43.217084)
		(width 0.089408)
		(layer "In9.Cu")
		(net "FM_CPU_BMC_INIT")
	)
	(segment
		(start 394.886688 -49.53508)
		(end 394.885926 -49.534318)
		(width 0.089408)
		(layer "In9.Cu")
		(net "FM_CPU_BMC_INIT")
	)
	(segment
		(start 397.286226 -23.5204)
		(end 398.59204 -22.214586)
		(width 0.089408)
		(layer "In9.Cu")
		(net "FM_CPU_BMC_INIT")
	)
	(segment
		(start 412.089854 -20.913598)
		(end 413.032956 -20.913598)
		(width 0.089408)
		(layer "In9.Cu")
		(net "FM_CPU_BMC_INIT")
	)
	(segment
		(start 175.06823 -131.503928)
		(end 175.797972 -130.774186)
		(width 0.089408)
		(layer "In9.Cu")
		(net "FM_CPU_BMC_INIT")
	)
	(segment
		(start 193.161666 -138.569192)
		(end 189.67704 -142.053818)
		(width 0.089408)
		(layer "In9.Cu")
		(net "FM_CPU_BMC_INIT")
	)
	(segment
		(start 385.95935 -87.205312)
		(end 386.519674 -87.205312)
		(width 0.089408)
		(layer "In9.Cu")
		(net "FM_CPU_BMC_INIT")
	)
	(segment
		(start 342.719406 -129.344928)
		(end 342.719406 -127.109474)
		(width 0.089408)
		(layer "In9.Cu")
		(net "FM_CPU_BMC_INIT")
	)
	(segment
		(start 164.30752 -135.980678)
		(end 164.30752 -133.239764)
		(width 0.089408)
		(layer "In9.Cu")
		(net "FM_CPU_BMC_INIT")
	)
	(segment
		(start 391.968736 -75.423268)
		(end 391.968736 -73.72858)
		(width 0.089408)
		(layer "In9.Cu")
		(net "FM_CPU_BMC_INIT")
	)
	(segment
		(start 413.032956 -20.913598)
		(end 413.207708 -20.738846)
		(width 0.089408)
		(layer "In9.Cu")
		(net "FM_CPU_BMC_INIT")
	)
	(segment
		(start 260.174994 -139.847828)
		(end 258.896358 -138.569192)
		(width 0.089408)
		(layer "In9.Cu")
		(net "FM_CPU_BMC_INIT")
	)
	(segment
		(start 396.794736 -40.26027)
		(end 396.794736 -35.251136)
		(width 0.089408)
		(layer "In9.Cu")
		(net "FM_CPU_BMC_INIT")
	)
	(segment
		(start 392.2014 -72.112124)
		(end 392.2014 -71.002144)
		(width 0.089408)
		(layer "In9.Cu")
		(net "FM_CPU_BMC_INIT")
	)
	(segment
		(start 397.196818 -42.096436)
		(end 397.196818 -40.662352)
		(width 0.089408)
		(layer "In9.Cu")
		(net "FM_CPU_BMC_INIT")
	)
	(segment
		(start 384.638296 -89.346024)
		(end 384.638296 -88.526366)
		(width 0.089408)
		(layer "In9.Cu")
		(net "FM_CPU_BMC_INIT")
	)
	(segment
		(start 394.885926 -49.412906)
		(end 394.70457 -49.23155)
		(width 0.089408)
		(layer "In9.Cu")
		(net "FM_CPU_BMC_INIT")
	)
	(segment
		(start 337.637882 -128.454404)
		(end 337.637882 -130.168396)
		(width 0.089408)
		(layer "In9.Cu")
		(net "FM_CPU_BMC_INIT")
	)
	(segment
		(start 384.01625 -89.96807)
		(end 384.638296 -89.346024)
		(width 0.089408)
		(layer "In9.Cu")
		(net "FM_CPU_BMC_INIT")
	)
	(segment
		(start 391.806938 -73.566782)
		(end 391.806938 -72.506586)
		(width 0.089408)
		(layer "In9.Cu")
		(net "FM_CPU_BMC_INIT")
	)
	(segment
		(start 395.163802 -44.110402)
		(end 395.163802 -43.785028)
		(width 0.089408)
		(layer "In9.Cu")
		(net "FM_CPU_BMC_INIT")
	)
	(segment
		(start 164.757862 -136.43102)
		(end 164.30752 -135.980678)
		(width 0.089408)
		(layer "In9.Cu")
		(net "FM_CPU_BMC_INIT")
	)
	(segment
		(start 394.104114 -69.09943)
		(end 394.104114 -63.574422)
		(width 0.089408)
		(layer "In9.Cu")
		(net "FM_CPU_BMC_INIT")
	)
	(segment
		(start 388.135114 -86.181438)
		(end 389.558022 -84.75853)
		(width 0.089408)
		(layer "In9.Cu")
		(net "FM_CPU_BMC_INIT")
	)
	(segment
		(start 397.28648 -31.118048)
		(end 397.28648 -24.342344)
		(width 0.089408)
		(layer "In9.Cu")
		(net "FM_CPU_BMC_INIT")
	)
	(segment
		(start 426.33138 -18.55978)
		(end 426.6946 -18.923)
		(width 0.089408)
		(layer "In9.Cu")
		(net "FM_CPU_BMC_INIT")
	)
	(segment
		(start 386.865876 -86.67877)
		(end 387.363208 -86.181438)
		(width 0.089408)
		(layer "In9.Cu")
		(net "FM_CPU_BMC_INIT")
	)
	(segment
		(start 390.635236 -78.119478)
		(end 391.325608 -77.429106)
		(width 0.089408)
		(layer "In9.Cu")
		(net "FM_CPU_BMC_INIT")
	)
	(segment
		(start 391.325608 -77.429106)
		(end 391.325608 -76.066396)
		(width 0.089408)
		(layer "In9.Cu")
		(net "FM_CPU_BMC_INIT")
	)
	(segment
		(start 397.286226 -24.34209)
		(end 397.286226 -23.5204)
		(width 0.089408)
		(layer "In9.Cu")
		(net "FM_CPU_BMC_INIT")
	)
	(segment
		(start 384.638296 -88.526366)
		(end 385.95935 -87.205312)
		(width 0.089408)
		(layer "In9.Cu")
		(net "FM_CPU_BMC_INIT")
	)
	(segment
		(start 189.009528 -142.053818)
		(end 188.748162 -142.315184)
		(width 0.089408)
		(layer "In9.Cu")
		(net "FM_CPU_BMC_INIT")
	)
	(segment
		(start 261.268972 -139.847828)
		(end 260.174994 -139.847828)
		(width 0.089408)
		(layer "In9.Cu")
		(net "FM_CPU_BMC_INIT")
	)
	(segment
		(start 394.886434 -49.851818)
		(end 394.886688 -49.851564)
		(width 0.089408)
		(layer "In9.Cu")
		(net "FM_CPU_BMC_INIT")
	)
	(segment
		(start 394.968476 -54.561232)
		(end 394.968476 -53.293772)
		(width 0.089408)
		(layer "In9.Cu")
		(net "FM_CPU_BMC_INIT")
	)
	(segment
		(start 389.840216 -82.715862)
		(end 389.840216 -82.384138)
		(width 0.089408)
		(layer "In9.Cu")
		(net "FM_CPU_BMC_INIT")
	)
	(segment
		(start 396.07617 -43.217084)
		(end 397.196818 -42.096436)
		(width 0.089408)
		(layer "In9.Cu")
		(net "FM_CPU_BMC_INIT")
	)
	(segment
		(start 181.119018 -130.774186)
		(end 181.612286 -130.280918)
		(width 0.089408)
		(layer "In9.Cu")
		(net "FM_CPU_BMC_INIT")
	)
	(segment
		(start 397.196818 -40.662352)
		(end 396.794736 -40.26027)
		(width 0.089408)
		(layer "In9.Cu")
		(net "FM_CPU_BMC_INIT")
	)
	(segment
		(start 366.128554 -129.2733)
		(end 359.726992 -129.2733)
		(width 0.089408)
		(layer "In9.Cu")
		(net "FM_CPU_BMC_INIT")
	)
	(segment
		(start 341.773256 -126.163324)
		(end 341.30361 -126.163324)
		(width 0.089408)
		(layer "In9.Cu")
		(net "FM_CPU_BMC_INIT")
	)
	(segment
		(start 165.559486 -141.710664)
		(end 164.757862 -140.90904)
		(width 0.089408)
		(layer "In9.Cu")
		(net "FM_CPU_BMC_INIT")
	)
	(segment
		(start 371.007894 -123.162314)
		(end 370.5733 -123.596908)
		(width 0.089408)
		(layer "In9.Cu")
		(net "FM_CPU_BMC_INIT")
	)
	(segment
		(start 369.475512 -125.926342)
		(end 366.128554 -129.2733)
		(width 0.089408)
		(layer "In9.Cu")
		(net "FM_CPU_BMC_INIT")
	)
	(segment
		(start 258.896358 -138.569192)
		(end 193.161666 -138.569192)
		(width 0.089408)
		(layer "In9.Cu")
		(net "FM_CPU_BMC_INIT")
	)
	(segment
		(start 423.93743 -18.55978)
		(end 426.33138 -18.55978)
		(width 0.089408)
		(layer "In9.Cu")
		(net "FM_CPU_BMC_INIT")
	)
	(segment
		(start 394.886688 -51.55946)
		(end 394.886688 -49.962816)
		(width 0.089408)
		(layer "In9.Cu")
		(net "FM_CPU_BMC_INIT")
	)
	(segment
		(start 395.163802 -43.785028)
		(end 395.731746 -43.217084)
		(width 0.089408)
		(layer "In9.Cu")
		(net "FM_CPU_BMC_INIT")
	)
	(segment
		(start 391.325608 -76.066396)
		(end 391.968736 -75.423268)
		(width 0.089408)
		(layer "In9.Cu")
		(net "FM_CPU_BMC_INIT")
	)
	(segment
		(start 334.5307 -132.042916)
		(end 331.583538 -134.990078)
		(width 0.089408)
		(layer "In9.Cu")
		(net "FM_CPU_BMC_INIT")
	)
	(segment
		(start 369.475512 -125.770386)
		(end 369.475512 -125.926342)
		(width 0.089408)
		(layer "In9.Cu")
		(net "FM_CPU_BMC_INIT")
	)
	(segment
		(start 421.738298 -19.29892)
		(end 421.853868 -19.18335)
		(width 0.089408)
		(layer "In9.Cu")
		(net "FM_CPU_BMC_INIT")
	)
	(segment
		(start 325.010272 -137.222992)
		(end 323.764656 -138.468608)
		(width 0.089408)
		(layer "In9.Cu")
		(net "FM_CPU_BMC_INIT")
	)
	(segment
		(start 352.762566 -130.139186)
		(end 348.536514 -130.139186)
		(width 0.089408)
		(layer "In9.Cu")
		(net "FM_CPU_BMC_INIT")
	)
	(segment
		(start 166.632382 -141.710664)
		(end 165.559486 -141.710664)
		(width 0.089408)
		(layer "In9.Cu")
		(net "FM_CPU_BMC_INIT")
	)
	(segment
		(start 396.985744 -35.060128)
		(end 396.985744 -33.30702)
		(width 0.089408)
		(layer "In9.Cu")
		(net "FM_CPU_BMC_INIT")
	)
	(segment
		(start 410.512768 -23.045674)
		(end 411.087824 -22.470618)
		(width 0.089408)
		(layer "In9.Cu")
		(net "FM_CPU_BMC_INIT")
	)
	(segment
		(start 341.084154 -126.38278)
		(end 341.084154 -126.918212)
		(width 0.089408)
		(layer "In9.Cu")
		(net "FM_CPU_BMC_INIT")
	)
	(segment
		(start 188.748162 -142.315184)
		(end 167.236902 -142.315184)
		(width 0.089408)
		(layer "In9.Cu")
		(net "FM_CPU_BMC_INIT")
	)
	(segment
		(start 394.885926 -49.534318)
		(end 394.885926 -49.412906)
		(width 0.089408)
		(layer "In9.Cu")
		(net "FM_CPU_BMC_INIT")
	)
	(segment
		(start 262.648192 -138.468608)
		(end 261.268972 -139.847828)
		(width 0.089408)
		(layer "In9.Cu")
		(net "FM_CPU_BMC_INIT")
	)
	(segment
		(start 411.087824 -21.915628)
		(end 412.089854 -20.913598)
		(width 0.089408)
		(layer "In9.Cu")
		(net "FM_CPU_BMC_INIT")
	)
	(segment
		(start 402.905722 -23.045674)
		(end 410.512768 -23.045674)
		(width 0.089408)
		(layer "In9.Cu")
		(net "FM_CPU_BMC_INIT")
	)
	(segment
		(start 389.558022 -84.75853)
		(end 389.558022 -82.998056)
		(width 0.089408)
		(layer "In9.Cu")
		(net "FM_CPU_BMC_INIT")
	)
	(segment
		(start 391.806938 -72.506586)
		(end 392.2014 -72.112124)
		(width 0.089408)
		(layer "In9.Cu")
		(net "FM_CPU_BMC_INIT")
	)
	(segment
		(start 394.886688 -49.962816)
		(end 394.886434 -49.962562)
		(width 0.089408)
		(layer "In9.Cu")
		(net "FM_CPU_BMC_INIT")
	)
	(segment
		(start 423.31386 -19.18335)
		(end 423.93743 -18.55978)
		(width 0.089408)
		(layer "In9.Cu")
		(net "FM_CPU_BMC_INIT")
	)
	(segment
		(start 394.70457 -44.569634)
		(end 395.163802 -44.110402)
		(width 0.089408)
		(layer "In9.Cu")
		(net "FM_CPU_BMC_INIT")
	)
	(segment
		(start 340.390988 -127.611378)
		(end 338.480908 -127.611378)
		(width 0.089408)
		(layer "In9.Cu")
		(net "FM_CPU_BMC_INIT")
	)
	(segment
		(start 337.637882 -130.168396)
		(end 335.763362 -132.042916)
		(width 0.089408)
		(layer "In9.Cu")
		(net "FM_CPU_BMC_INIT")
	)
	(segment
		(start 331.583538 -135.711438)
		(end 329.582272 -137.712704)
		(width 0.089408)
		(layer "In9.Cu")
		(net "FM_CPU_BMC_INIT")
	)
	(segment
		(start 326.316848 -137.712704)
		(end 325.827136 -137.222992)
		(width 0.089408)
		(layer "In9.Cu")
		(net "FM_CPU_BMC_INIT")
	)
	(segment
		(start 413.207708 -20.738846)
		(end 413.207708 -20.467066)
		(width 0.089408)
		(layer "In9.Cu")
		(net "FM_CPU_BMC_INIT")
	)
	(segment
		(start 402.785326 -23.16607)
		(end 402.905722 -23.045674)
		(width 0.089408)
		(layer "In9.Cu")
		(net "FM_CPU_BMC_INIT")
	)
	(segment
		(start 394.758418 -52.608734)
		(end 394.758672 -52.60848)
		(width 0.089408)
		(layer "In9.Cu")
		(net "FM_CPU_BMC_INIT")
	)
	(segment
		(start 370.5733 -124.672598)
		(end 369.475512 -125.770386)
		(width 0.089408)
		(layer "In9.Cu")
		(net "FM_CPU_BMC_INIT")
	)
	(segment
		(start 394.968222 -62.710314)
		(end 394.968222 -54.561486)
		(width 0.089408)
		(layer "In9.Cu")
		(net "FM_CPU_BMC_INIT")
	)
	(segment
		(start 335.763362 -132.042916)
		(end 334.5307 -132.042916)
		(width 0.089408)
		(layer "In9.Cu")
		(net "FM_CPU_BMC_INIT")
	)
	(segment
		(start 356.48138 -130.772154)
		(end 355.644958 -131.608576)
		(width 0.089408)
		(layer "In9.Cu")
		(net "FM_CPU_BMC_INIT")
	)
	(segment
		(start 329.582272 -137.712704)
		(end 326.316848 -137.712704)
		(width 0.089408)
		(layer "In9.Cu")
		(net "FM_CPU_BMC_INIT")
	)
	(segment
		(start 400.769836 -22.214586)
		(end 401.72132 -23.16607)
		(width 0.089408)
		(layer "In9.Cu")
		(net "FM_CPU_BMC_INIT")
	)
	(segment
		(start 370.5733 -123.596908)
		(end 370.5733 -124.672598)
		(width 0.089408)
		(layer "In9.Cu")
		(net "FM_CPU_BMC_INIT")
	)
	(segment
		(start 348.536514 -130.139186)
		(end 348.1197 -130.556)
		(width 0.089408)
		(layer "In9.Cu")
		(net "FM_CPU_BMC_INIT")
	)
	(segment
		(start 421.853868 -19.18335)
		(end 423.31386 -19.18335)
		(width 0.089408)
		(layer "In9.Cu")
		(net "FM_CPU_BMC_INIT")
	)
	(segment
		(start 394.886434 -49.962562)
		(end 394.886434 -49.851818)
		(width 0.089408)
		(layer "In9.Cu")
		(net "FM_CPU_BMC_INIT")
	)
	(segment
		(start 418.544502 -19.575526)
		(end 418.821108 -19.29892)
		(width 0.089408)
		(layer "In9.Cu")
		(net "FM_CPU_BMC_INIT")
	)
	(segment
		(start 167.236902 -142.315184)
		(end 166.632382 -141.710664)
		(width 0.089408)
		(layer "In9.Cu")
		(net "FM_CPU_BMC_INIT")
	)
	(segment
		(start 359.726992 -129.2733)
		(end 358.228138 -130.772154)
		(width 0.089408)
		(layer "In9.Cu")
		(net "FM_CPU_BMC_INIT")
	)
	(segment
		(start 348.1197 -130.556)
		(end 343.930478 -130.556)
		(width 0.089408)
		(layer "In9.Cu")
		(net "FM_CPU_BMC_INIT")
	)
	(segment
		(start 389.447278 -78.854554)
		(end 389.447278 -78.52283)
		(width 0.089408)
		(layer "In9.Cu")
		(net "FM_CPU_BMC_INIT")
	)
	(segment
		(start 413.207708 -20.467066)
		(end 414.099248 -19.575526)
		(width 0.089408)
		(layer "In9.Cu")
		(net "FM_CPU_BMC_INIT")
	)
	(segment
		(start 164.30752 -133.239764)
		(end 166.043356 -131.503928)
		(width 0.089408)
		(layer "In9.Cu")
		(net "FM_CPU_BMC_INIT")
	)
	(segment
		(start 394.886688 -49.851564)
		(end 394.886688 -49.53508)
		(width 0.089408)
		(layer "In9.Cu")
		(net "FM_CPU_BMC_INIT")
	)
	(segment
		(start 207.040226 -98.648774)
		(end 203.9366 -101.7524)
		(width 0.089408)
		(layer "In11.Cu")
		(net "FM_CPU_BMC_INIT")
	)
	(segment
		(start 198.22922 -102.23754)
		(end 196.72554 -102.23754)
		(width 0.089408)
		(layer "In11.Cu")
		(net "FM_CPU_BMC_INIT")
	)
	(segment
		(start 235.839 -80.8228)
		(end 235.5342 -80.8228)
		(width 0.089408)
		(layer "In11.Cu")
		(net "FM_CPU_BMC_INIT")
	)
	(segment
		(start 241.046 -79.9084)
		(end 240.4872 -79.9084)
		(width 0.089408)
		(layer "In11.Cu")
		(net "FM_CPU_BMC_INIT")
	)
	(segment
		(start 252.089158 -84.414106)
		(end 251.829824 -84.414106)
		(width 0.089408)
		(layer "In11.Cu")
		(net "FM_CPU_BMC_INIT")
	)
	(segment
		(start 247.4214 -83.7692)
		(end 246.883936 -83.231736)
		(width 0.089408)
		(layer "In11.Cu")
		(net "FM_CPU_BMC_INIT")
	)
	(segment
		(start 239.2934 -79.883)
		(end 238.8108 -79.883)
		(width 0.089408)
		(layer "In11.Cu")
		(net "FM_CPU_BMC_INIT")
	)
	(segment
		(start 211.074 -96.312736)
		(end 211.074 -98.552)
		(width 0.089408)
		(layer "In11.Cu")
		(net "FM_CPU_BMC_INIT")
	)
	(segment
		(start 233.2228 -83.312)
		(end 232.791 -83.312)
		(width 0.089408)
		(layer "In11.Cu")
		(net "FM_CPU_BMC_INIT")
	)
	(segment
		(start 237.5154 -80.8228)
		(end 237.1344 -80.8228)
		(width 0.089408)
		(layer "In11.Cu")
		(net "FM_CPU_BMC_INIT")
	)
	(segment
		(start 256.23393 -88.87079)
		(end 256.19837 -88.87079)
		(width 0.0889)
		(layer "In11.Cu")
		(net "FM_CPU_BMC_INIT")
	)
	(segment
		(start 254.4572 -88.84158)
		(end 254.0762 -88.46058)
		(width 0.089408)
		(layer "In11.Cu")
		(net "FM_CPU_BMC_INIT")
	)
	(segment
		(start 270.0782 -89.281)
		(end 269.5702 -89.789)
		(width 0.089408)
		(layer "In11.Cu")
		(net "FM_CPU_BMC_INIT")
	)
	(segment
		(start 231.064816 -82.932016)
		(end 226.39528 -82.932016)
		(width 0.089408)
		(layer "In11.Cu")
		(net "FM_CPU_BMC_INIT")
	)
	(segment
		(start 234.0356 -82.8294)
		(end 233.7054 -82.8294)
		(width 0.089408)
		(layer "In11.Cu")
		(net "FM_CPU_BMC_INIT")
	)
	(segment
		(start 253.2126 -85.174582)
		(end 252.947678 -84.90966)
		(width 0.089408)
		(layer "In11.Cu")
		(net "FM_CPU_BMC_INIT")
	)
	(segment
		(start 211.074 -98.552)
		(end 210.977226 -98.648774)
		(width 0.089408)
		(layer "In11.Cu")
		(net "FM_CPU_BMC_INIT")
	)
	(segment
		(start 282.0162 -86.3346)
		(end 281.5082 -86.8426)
		(width 0.089408)
		(layer "In11.Cu")
		(net "FM_CPU_BMC_INIT")
	)
	(segment
		(start 234.823 -82.3468)
		(end 234.5182 -82.3468)
		(width 0.089408)
		(layer "In11.Cu")
		(net "FM_CPU_BMC_INIT")
	)
	(segment
		(start 242.2652 -80.8736)
		(end 241.7826 -80.391)
		(width 0.089408)
		(layer "In11.Cu")
		(net "FM_CPU_BMC_INIT")
	)
	(segment
		(start 254.7366 -88.84158)
		(end 254.4572 -88.84158)
		(width 0.089408)
		(layer "In11.Cu")
		(net "FM_CPU_BMC_INIT")
	)
	(segment
		(start 259.82549 -88.87079)
		(end 259.63245 -88.87079)
		(width 0.0889)
		(layer "In11.Cu")
		(net "FM_CPU_BMC_INIT")
	)
	(segment
		(start 235.1532 -81.2038)
		(end 235.1532 -82.0166)
		(width 0.089408)
		(layer "In11.Cu")
		(net "FM_CPU_BMC_INIT")
	)
	(segment
		(start 281.5082 -86.8426)
		(end 281.1526 -86.8426)
		(width 0.089408)
		(layer "In11.Cu")
		(net "FM_CPU_BMC_INIT")
	)
	(segment
		(start 250.040902 -84.222082)
		(end 249.66422 -83.8454)
		(width 0.089408)
		(layer "In11.Cu")
		(net "FM_CPU_BMC_INIT")
	)
	(segment
		(start 235.1532 -82.0166)
		(end 234.823 -82.3468)
		(width 0.089408)
		(layer "In11.Cu")
		(net "FM_CPU_BMC_INIT")
	)
	(segment
		(start 248.792746 -83.3374)
		(end 248.3612 -83.3374)
		(width 0.089408)
		(layer "In11.Cu")
		(net "FM_CPU_BMC_INIT")
	)
	(segment
		(start 250.899422 -83.918044)
		(end 250.595384 -84.222082)
		(width 0.089408)
		(layer "In11.Cu")
		(net "FM_CPU_BMC_INIT")
	)
	(segment
		(start 248.3612 -83.3374)
		(end 247.9294 -83.7692)
		(width 0.089408)
		(layer "In11.Cu")
		(net "FM_CPU_BMC_INIT")
	)
	(segment
		(start 246.198644 -82.927444)
		(end 245.93931 -82.927444)
		(width 0.089408)
		(layer "In11.Cu")
		(net "FM_CPU_BMC_INIT")
	)
	(segment
		(start 196.469 -101.981)
		(end 194.81038 -101.981)
		(width 0.089408)
		(layer "In11.Cu")
		(net "FM_CPU_BMC_INIT")
	)
	(segment
		(start 192.78346 -102.51186)
		(end 191.008 -100.7364)
		(width 0.089408)
		(layer "In11.Cu")
		(net "FM_CPU_BMC_INIT")
	)
	(segment
		(start 254.0762 -86.6648)
		(end 253.6952 -86.2838)
		(width 0.089408)
		(layer "In11.Cu")
		(net "FM_CPU_BMC_INIT")
	)
	(segment
		(start 199.57288 -103.5812)
		(end 198.22922 -102.23754)
		(width 0.089408)
		(layer "In11.Cu")
		(net "FM_CPU_BMC_INIT")
	)
	(segment
		(start 245.93931 -82.927444)
		(end 245.358666 -82.3468)
		(width 0.089408)
		(layer "In11.Cu")
		(net "FM_CPU_BMC_INIT")
	)
	(segment
		(start 253.2126 -86.0044)
		(end 253.2126 -85.174582)
		(width 0.089408)
		(layer "In11.Cu")
		(net "FM_CPU_BMC_INIT")
	)
	(segment
		(start 272.923 -89.281)
		(end 270.0782 -89.281)
		(width 0.089408)
		(layer "In11.Cu")
		(net "FM_CPU_BMC_INIT")
	)
	(segment
		(start 282.0162 -82.8548)
		(end 282.0162 -86.3346)
		(width 0.089408)
		(layer "In11.Cu")
		(net "FM_CPU_BMC_INIT")
	)
	(segment
		(start 260.76148 -89.19972)
		(end 260.15442 -89.19972)
		(width 0.0889)
		(layer "In11.Cu")
		(net "FM_CPU_BMC_INIT")
	)
	(segment
		(start 256.087372 -88.853264)
		(end 255.847596 -88.853264)
		(width 0.0889)
		(layer "In11.Cu")
		(net "FM_CPU_BMC_INIT")
	)
	(segment
		(start 236.728 -80.4164)
		(end 236.2454 -80.4164)
		(width 0.089408)
		(layer "In11.Cu")
		(net "FM_CPU_BMC_INIT")
	)
	(segment
		(start 232.791 -83.312)
		(end 232.37698 -83.72602)
		(width 0.089408)
		(layer "In11.Cu")
		(net "FM_CPU_BMC_INIT")
	)
	(segment
		(start 244.997224 -82.3468)
		(end 244.489224 -81.8388)
		(width 0.089408)
		(layer "In11.Cu")
		(net "FM_CPU_BMC_INIT")
	)
	(segment
		(start 244.0178 -81.8388)
		(end 243.4844 -81.3054)
		(width 0.089408)
		(layer "In11.Cu")
		(net "FM_CPU_BMC_INIT")
	)
	(segment
		(start 232.37698 -83.72602)
		(end 231.85882 -83.72602)
		(width 0.089408)
		(layer "In11.Cu")
		(net "FM_CPU_BMC_INIT")
	)
	(segment
		(start 213.773512 -92.78239)
		(end 211.651596 -94.904306)
		(width 0.089408)
		(layer "In11.Cu")
		(net "FM_CPU_BMC_INIT")
	)
	(segment
		(start 234.5182 -82.3468)
		(end 234.0356 -82.8294)
		(width 0.089408)
		(layer "In11.Cu")
		(net "FM_CPU_BMC_INIT")
	)
	(segment
		(start 252.947678 -84.90966)
		(end 252.584712 -84.90966)
		(width 0.089408)
		(layer "In11.Cu")
		(net "FM_CPU_BMC_INIT")
	)
	(segment
		(start 249.66422 -83.8454)
		(end 249.300746 -83.8454)
		(width 0.089408)
		(layer "In11.Cu")
		(net "FM_CPU_BMC_INIT")
	)
	(segment
		(start 255.0922 -89.19718)
		(end 254.7366 -88.84158)
		(width 0.089408)
		(layer "In11.Cu")
		(net "FM_CPU_BMC_INIT")
	)
	(segment
		(start 211.651596 -94.904306)
		(end 211.651596 -95.73514)
		(width 0.089408)
		(layer "In11.Cu")
		(net "FM_CPU_BMC_INIT")
	)
	(segment
		(start 247.9294 -83.7692)
		(end 247.4214 -83.7692)
		(width 0.089408)
		(layer "In11.Cu")
		(net "FM_CPU_BMC_INIT")
	)
	(segment
		(start 233.7054 -82.8294)
		(end 233.2228 -83.312)
		(width 0.089408)
		(layer "In11.Cu")
		(net "FM_CPU_BMC_INIT")
	)
	(segment
		(start 273.1262 -89.0778)
		(end 272.923 -89.281)
		(width 0.089408)
		(layer "In11.Cu")
		(net "FM_CPU_BMC_INIT")
	)
	(segment
		(start 252.584712 -84.90966)
		(end 252.089158 -84.414106)
		(width 0.089408)
		(layer "In11.Cu")
		(net "FM_CPU_BMC_INIT")
	)
	(segment
		(start 237.998 -80.3402)
		(end 237.5154 -80.8228)
		(width 0.089408)
		(layer "In11.Cu")
		(net "FM_CPU_BMC_INIT")
	)
	(segment
		(start 269.5702 -89.789)
		(end 269.113 -89.789)
		(width 0.089408)
		(layer "In11.Cu")
		(net "FM_CPU_BMC_INIT")
	)
	(segment
		(start 268.19606 -88.87206)
		(end 262.84174 -88.87206)
		(width 0.089408)
		(layer "In11.Cu")
		(net "FM_CPU_BMC_INIT")
	)
	(segment
		(start 245.358666 -82.3468)
		(end 244.997224 -82.3468)
		(width 0.089408)
		(layer "In11.Cu")
		(net "FM_CPU_BMC_INIT")
	)
	(segment
		(start 203.9366 -101.7524)
		(end 203.9366 -102.8446)
		(width 0.089408)
		(layer "In11.Cu")
		(net "FM_CPU_BMC_INIT")
	)
	(segment
		(start 238.8108 -79.883)
		(end 238.3536 -80.3402)
		(width 0.089408)
		(layer "In11.Cu")
		(net "FM_CPU_BMC_INIT")
	)
	(segment
		(start 238.3536 -80.3402)
		(end 237.998 -80.3402)
		(width 0.089408)
		(layer "In11.Cu")
		(net "FM_CPU_BMC_INIT")
	)
	(segment
		(start 242.697 -80.8736)
		(end 242.2652 -80.8736)
		(width 0.089408)
		(layer "In11.Cu")
		(net "FM_CPU_BMC_INIT")
	)
	(segment
		(start 240.1062 -80.2894)
		(end 239.6998 -80.2894)
		(width 0.089408)
		(layer "In11.Cu")
		(net "FM_CPU_BMC_INIT")
	)
	(segment
		(start 235.5342 -80.8228)
		(end 235.1532 -81.2038)
		(width 0.089408)
		(layer "In11.Cu")
		(net "FM_CPU_BMC_INIT")
	)
	(segment
		(start 262.0772 -89.2556)
		(end 261.692644 -88.871044)
		(width 0.0889)
		(layer "In11.Cu")
		(net "FM_CPU_BMC_INIT")
	)
	(segment
		(start 194.81038 -101.981)
		(end 194.27952 -102.51186)
		(width 0.089408)
		(layer "In11.Cu")
		(net "FM_CPU_BMC_INIT")
	)
	(segment
		(start 237.1344 -80.8228)
		(end 236.728 -80.4164)
		(width 0.089408)
		(layer "In11.Cu")
		(net "FM_CPU_BMC_INIT")
	)
	(segment
		(start 240.4872 -79.9084)
		(end 240.1062 -80.2894)
		(width 0.089408)
		(layer "In11.Cu")
		(net "FM_CPU_BMC_INIT")
	)
	(segment
		(start 243.1288 -81.3054)
		(end 242.697 -80.8736)
		(width 0.089408)
		(layer "In11.Cu")
		(net "FM_CPU_BMC_INIT")
	)
	(segment
		(start 244.489224 -81.8388)
		(end 244.0178 -81.8388)
		(width 0.089408)
		(layer "In11.Cu")
		(net "FM_CPU_BMC_INIT")
	)
	(segment
		(start 251.829824 -84.414106)
		(end 251.333762 -83.918044)
		(width 0.089408)
		(layer "In11.Cu")
		(net "FM_CPU_BMC_INIT")
	)
	(segment
		(start 254.0762 -88.46058)
		(end 254.0762 -86.6648)
		(width 0.089408)
		(layer "In11.Cu")
		(net "FM_CPU_BMC_INIT")
	)
	(segment
		(start 253.492 -86.2838)
		(end 253.2126 -86.0044)
		(width 0.089408)
		(layer "In11.Cu")
		(net "FM_CPU_BMC_INIT")
	)
	(segment
		(start 239.6998 -80.2894)
		(end 239.2934 -79.883)
		(width 0.089408)
		(layer "In11.Cu")
		(net "FM_CPU_BMC_INIT")
	)
	(segment
		(start 255.50368 -89.19718)
		(end 255.0922 -89.19718)
		(width 0.089408)
		(layer "In11.Cu")
		(net "FM_CPU_BMC_INIT")
	)
	(segment
		(start 246.502936 -83.231736)
		(end 246.198644 -82.927444)
		(width 0.089408)
		(layer "In11.Cu")
		(net "FM_CPU_BMC_INIT")
	)
	(segment
		(start 211.651596 -95.73514)
		(end 211.074 -96.312736)
		(width 0.089408)
		(layer "In11.Cu")
		(net "FM_CPU_BMC_INIT")
	)
	(segment
		(start 260.15442 -89.19972)
		(end 259.82549 -88.87079)
		(width 0.0889)
		(layer "In11.Cu")
		(net "FM_CPU_BMC_INIT")
	)
	(segment
		(start 253.6952 -86.2838)
		(end 253.492 -86.2838)
		(width 0.089408)
		(layer "In11.Cu")
		(net "FM_CPU_BMC_INIT")
	)
	(segment
		(start 250.595384 -84.222082)
		(end 250.040902 -84.222082)
		(width 0.089408)
		(layer "In11.Cu")
		(net "FM_CPU_BMC_INIT")
	)
	(segment
		(start 261.692644 -88.871044)
		(end 261.090156 -88.871044)
		(width 0.0889)
		(layer "In11.Cu")
		(net "FM_CPU_BMC_INIT")
	)
	(segment
		(start 262.84174 -88.87206)
		(end 262.4582 -89.2556)
		(width 0.089408)
		(layer "In11.Cu")
		(net "FM_CPU_BMC_INIT")
	)
	(segment
		(start 257.95097 -88.87079)
		(end 257.91541 -88.87079)
		(width 0.0889)
		(layer "In11.Cu")
		(net "FM_CPU_BMC_INIT")
	)
	(segment
		(start 210.977226 -98.648774)
		(end 207.040226 -98.648774)
		(width 0.089408)
		(layer "In11.Cu")
		(net "FM_CPU_BMC_INIT")
	)
	(segment
		(start 269.113 -89.789)
		(end 268.19606 -88.87206)
		(width 0.089408)
		(layer "In11.Cu")
		(net "FM_CPU_BMC_INIT")
	)
	(segment
		(start 231.85882 -83.72602)
		(end 231.064816 -82.932016)
		(width 0.089408)
		(layer "In11.Cu")
		(net "FM_CPU_BMC_INIT")
	)
	(segment
		(start 188.7728 -100.7364)
		(end 185.928 -97.8916)
		(width 0.089408)
		(layer "In11.Cu")
		(net "FM_CPU_BMC_INIT")
	)
	(segment
		(start 281.7368 -82.5754)
		(end 282.0162 -82.8548)
		(width 0.089408)
		(layer "In11.Cu")
		(net "FM_CPU_BMC_INIT")
	)
	(segment
		(start 262.4582 -89.2556)
		(end 262.0772 -89.2556)
		(width 0.089408)
		(layer "In11.Cu")
		(net "FM_CPU_BMC_INIT")
	)
	(segment
		(start 236.2454 -80.4164)
		(end 235.839 -80.8228)
		(width 0.089408)
		(layer "In11.Cu")
		(net "FM_CPU_BMC_INIT")
	)
	(segment
		(start 185.928 -97.8916)
		(end 185.928 -96.52)
		(width 0.089408)
		(layer "In11.Cu")
		(net "FM_CPU_BMC_INIT")
	)
	(segment
		(start 255.847596 -88.853264)
		(end 255.50368 -89.19718)
		(width 0.089408)
		(layer "In11.Cu")
		(net "FM_CPU_BMC_INIT")
	)
	(segment
		(start 203.9366 -102.8446)
		(end 203.2 -103.5812)
		(width 0.089408)
		(layer "In11.Cu")
		(net "FM_CPU_BMC_INIT")
	)
	(segment
		(start 191.008 -100.7364)
		(end 188.7728 -100.7364)
		(width 0.089408)
		(layer "In11.Cu")
		(net "FM_CPU_BMC_INIT")
	)
	(segment
		(start 216.544906 -92.78239)
		(end 213.773512 -92.78239)
		(width 0.089408)
		(layer "In11.Cu")
		(net "FM_CPU_BMC_INIT")
	)
	(segment
		(start 246.883936 -83.231736)
		(end 246.502936 -83.231736)
		(width 0.089408)
		(layer "In11.Cu")
		(net "FM_CPU_BMC_INIT")
	)
	(segment
		(start 194.27952 -102.51186)
		(end 192.78346 -102.51186)
		(width 0.089408)
		(layer "In11.Cu")
		(net "FM_CPU_BMC_INIT")
	)
	(segment
		(start 226.39528 -82.932016)
		(end 216.544906 -92.78239)
		(width 0.089408)
		(layer "In11.Cu")
		(net "FM_CPU_BMC_INIT")
	)
	(segment
		(start 278.9174 -89.0778)
		(end 273.1262 -89.0778)
		(width 0.089408)
		(layer "In11.Cu")
		(net "FM_CPU_BMC_INIT")
	)
	(segment
		(start 241.5286 -80.391)
		(end 241.046 -79.9084)
		(width 0.089408)
		(layer "In11.Cu")
		(net "FM_CPU_BMC_INIT")
	)
	(segment
		(start 261.090156 -88.871044)
		(end 260.76148 -89.19972)
		(width 0.0889)
		(layer "In11.Cu")
		(net "FM_CPU_BMC_INIT")
	)
	(segment
		(start 203.2 -103.5812)
		(end 199.57288 -103.5812)
		(width 0.089408)
		(layer "In11.Cu")
		(net "FM_CPU_BMC_INIT")
	)
	(segment
		(start 196.72554 -102.23754)
		(end 196.469 -101.981)
		(width 0.089408)
		(layer "In11.Cu")
		(net "FM_CPU_BMC_INIT")
	)
	(segment
		(start 249.300746 -83.8454)
		(end 248.792746 -83.3374)
		(width 0.089408)
		(layer "In11.Cu")
		(net "FM_CPU_BMC_INIT")
	)
	(segment
		(start 241.7826 -80.391)
		(end 241.5286 -80.391)
		(width 0.089408)
		(layer "In11.Cu")
		(net "FM_CPU_BMC_INIT")
	)
	(segment
		(start 243.4844 -81.3054)
		(end 243.1288 -81.3054)
		(width 0.089408)
		(layer "In11.Cu")
		(net "FM_CPU_BMC_INIT")
	)
	(segment
		(start 251.333762 -83.918044)
		(end 250.899422 -83.918044)
		(width 0.089408)
		(layer "In11.Cu")
		(net "FM_CPU_BMC_INIT")
	)
	(segment
		(start 281.1526 -86.8426)
		(end 278.9174 -89.0778)
		(width 0.089408)
		(layer "In11.Cu")
		(net "FM_CPU_BMC_INIT")
	)
	(arc
		(start 256.19837 -88.87079)
		(mid 256.142313 -88.865561)
		(end 256.087372 -88.853264)
		(width 0.0889)
		(layer "In11.Cu")
		(net "FM_CPU_BMC_INIT")
	)
	(arc
		(start 256.72796 -88.575388)
		(mid 256.519352 -88.78732)
		(end 256.23393 -88.87079)
		(width 0.0889)
		(layer "In11.Cu")
		(net "FM_CPU_BMC_INIT")
	)
	(arc
		(start 259.63245 -88.87079)
		(mid 259.347026 -88.787323)
		(end 259.13842 -88.575388)
		(width 0.0889)
		(layer "In11.Cu")
		(net "FM_CPU_BMC_INIT")
	)
	(arc
		(start 257.42138 -88.575388)
		(mid 257.07467 -88.375077)
		(end 256.72796 -88.575388)
		(width 0.0889)
		(layer "In11.Cu")
		(net "FM_CPU_BMC_INIT")
	)
	(arc
		(start 257.91541 -88.87079)
		(mid 257.629986 -88.787323)
		(end 257.42138 -88.575388)
		(width 0.0889)
		(layer "In11.Cu")
		(net "FM_CPU_BMC_INIT")
	)
	(arc
		(start 259.13842 -88.575388)
		(mid 258.79171 -88.375077)
		(end 258.445 -88.575388)
		(width 0.0889)
		(layer "In11.Cu")
		(net "FM_CPU_BMC_INIT")
	)
	(arc
		(start 258.445 -88.575388)
		(mid 258.236392 -88.78732)
		(end 257.95097 -88.87079)
		(width 0.0889)
		(layer "In11.Cu")
		(net "FM_CPU_BMC_INIT")
	)
	(segment
		(start 395.742668 -43.801792)
		(end 396.50797 -43.03649)
		(width 0.10795)
		(layer "F.Cu")
		(net "FM_CPU1_PROCHOT_PCH_N")
	)
	(segment
		(start 403.3266 -42.291)
		(end 403.504146 -42.113454)
		(width 0.10795)
		(layer "F.Cu")
		(net "FM_CPU1_PROCHOT_PCH_N")
	)
	(segment
		(start 383.77495 -96.9772)
		(end 384.27025 -96.747076)
		(width 0.10795)
		(layer "F.Cu")
		(net "FM_CPU1_PROCHOT_PCH_N")
	)
	(segment
		(start 399.20291 -43.651424)
		(end 400.636994 -43.651424)
		(width 0.10795)
		(layer "F.Cu")
		(net "FM_CPU1_PROCHOT_PCH_N")
	)
	(segment
		(start 401.997418 -42.291)
		(end 403.3266 -42.291)
		(width 0.10795)
		(layer "F.Cu")
		(net "FM_CPU1_PROCHOT_PCH_N")
	)
	(segment
		(start 398.587976 -43.03649)
		(end 399.20291 -43.651424)
		(width 0.10795)
		(layer "F.Cu")
		(net "FM_CPU1_PROCHOT_PCH_N")
	)
	(segment
		(start 403.504146 -42.113454)
		(end 403.504146 -41.792652)
		(width 0.10795)
		(layer "F.Cu")
		(net "FM_CPU1_PROCHOT_PCH_N")
	)
	(segment
		(start 400.636994 -43.651424)
		(end 401.997418 -42.291)
		(width 0.10795)
		(layer "F.Cu")
		(net "FM_CPU1_PROCHOT_PCH_N")
	)
	(segment
		(start 396.50797 -43.03649)
		(end 398.587976 -43.03649)
		(width 0.10795)
		(layer "F.Cu")
		(net "FM_CPU1_PROCHOT_PCH_N")
	)
	(via
		(at 395.742668 -43.801792)
		(size 0.508)
		(drill 0.254)
		(layers "F.Cu" "B.Cu")
		(net "FM_CPU1_PROCHOT_PCH_N")
	)
	(via
		(at 384.27025 -96.747076)
		(size 0.508)
		(drill 0.254)
		(layers "F.Cu" "B.Cu")
		(net "FM_CPU1_PROCHOT_PCH_N")
	)
	(segment
		(start 388.101586 -86.902036)
		(end 387.801612 -87.20201)
		(width 0.089408)
		(layer "In9.Cu")
		(net "FM_CPU1_PROCHOT_PCH_N")
	)
	(segment
		(start 392.392408 -71.09079)
		(end 392.392408 -72.191372)
		(width 0.089408)
		(layer "In9.Cu")
		(net "FM_CPU1_PROCHOT_PCH_N")
	)
	(segment
		(start 394.33119 -69.152008)
		(end 392.392408 -71.09079)
		(width 0.089408)
		(layer "In9.Cu")
		(net "FM_CPU1_PROCHOT_PCH_N")
	)
	(segment
		(start 395.159484 -54.64048)
		(end 395.15923 -54.640734)
		(width 0.089408)
		(layer "In9.Cu")
		(net "FM_CPU1_PROCHOT_PCH_N")
	)
	(segment
		(start 394.949426 -53.004466)
		(end 395.159484 -53.214524)
		(width 0.089408)
		(layer "In9.Cu")
		(net "FM_CPU1_PROCHOT_PCH_N")
	)
	(segment
		(start 390.03224 -82.846418)
		(end 389.781796 -83.096862)
		(width 0.089408)
		(layer "In9.Cu")
		(net "FM_CPU1_PROCHOT_PCH_N")
	)
	(segment
		(start 385.963414 -87.508334)
		(end 384.829304 -88.642444)
		(width 0.089408)
		(layer "In9.Cu")
		(net "FM_CPU1_PROCHOT_PCH_N")
	)
	(segment
		(start 391.524236 -77.505306)
		(end 390.56056 -78.468982)
		(width 0.089408)
		(layer "In9.Cu")
		(net "FM_CPU1_PROCHOT_PCH_N")
	)
	(segment
		(start 392.159744 -75.52309)
		(end 391.524236 -76.158598)
		(width 0.089408)
		(layer "In9.Cu")
		(net "FM_CPU1_PROCHOT_PCH_N")
	)
	(segment
		(start 385.292092 -92.46616)
		(end 385.18465 -92.573602)
		(width 0.089408)
		(layer "In9.Cu")
		(net "FM_CPU1_PROCHOT_PCH_N")
	)
	(segment
		(start 384.829304 -89.266776)
		(end 384.829558 -89.26703)
		(width 0.089408)
		(layer "In9.Cu")
		(net "FM_CPU1_PROCHOT_PCH_N")
	)
	(segment
		(start 394.94968 -52.687728)
		(end 394.949426 -52.687982)
		(width 0.089408)
		(layer "In9.Cu")
		(net "FM_CPU1_PROCHOT_PCH_N")
	)
	(segment
		(start 394.895578 -49.152302)
		(end 395.077696 -49.33442)
		(width 0.089408)
		(layer "In9.Cu")
		(net "FM_CPU1_PROCHOT_PCH_N")
	)
	(segment
		(start 390.03224 -81.997042)
		(end 390.03224 -82.846418)
		(width 0.089408)
		(layer "In9.Cu")
		(net "FM_CPU1_PROCHOT_PCH_N")
	)
	(segment
		(start 392.159744 -73.649332)
		(end 392.159744 -75.52309)
		(width 0.089408)
		(layer "In9.Cu")
		(net "FM_CPU1_PROCHOT_PCH_N")
	)
	(segment
		(start 385.292092 -91.965526)
		(end 385.292092 -92.46616)
		(width 0.089408)
		(layer "In9.Cu")
		(net "FM_CPU1_PROCHOT_PCH_N")
	)
	(segment
		(start 395.15923 -54.640734)
		(end 395.15923 -62.789562)
		(width 0.089408)
		(layer "In9.Cu")
		(net "FM_CPU1_PROCHOT_PCH_N")
	)
	(segment
		(start 384.829558 -89.26703)
		(end 384.829558 -89.426542)
		(width 0.089408)
		(layer "In9.Cu")
		(net "FM_CPU1_PROCHOT_PCH_N")
	)
	(segment
		(start 384.38709 -95.094298)
		(end 384.175762 -95.305626)
		(width 0.089408)
		(layer "In9.Cu")
		(net "FM_CPU1_PROCHOT_PCH_N")
	)
	(segment
		(start 384.212846 -90.043254)
		(end 384.212846 -91.26855)
		(width 0.089408)
		(layer "In9.Cu")
		(net "FM_CPU1_PROCHOT_PCH_N")
	)
	(segment
		(start 390.56056 -78.468982)
		(end 390.56056 -78.857094)
		(width 0.089408)
		(layer "In9.Cu")
		(net "FM_CPU1_PROCHOT_PCH_N")
	)
	(segment
		(start 394.33119 -63.617602)
		(end 394.33119 -69.152008)
		(width 0.089408)
		(layer "In9.Cu")
		(net "FM_CPU1_PROCHOT_PCH_N")
	)
	(segment
		(start 395.07795 -51.480466)
		(end 395.07795 -51.638454)
		(width 0.089408)
		(layer "In9.Cu")
		(net "FM_CPU1_PROCHOT_PCH_N")
	)
	(segment
		(start 389.781796 -83.096862)
		(end 389.781796 -84.826094)
		(width 0.089408)
		(layer "In9.Cu")
		(net "FM_CPU1_PROCHOT_PCH_N")
	)
	(segment
		(start 387.801612 -87.20201)
		(end 386.844286 -87.20201)
		(width 0.089408)
		(layer "In9.Cu")
		(net "FM_CPU1_PROCHOT_PCH_N")
	)
	(segment
		(start 394.895578 -44.648882)
		(end 394.895578 -49.152302)
		(width 0.089408)
		(layer "In9.Cu")
		(net "FM_CPU1_PROCHOT_PCH_N")
	)
	(segment
		(start 391.524236 -76.158598)
		(end 391.524236 -77.505306)
		(width 0.089408)
		(layer "In9.Cu")
		(net "FM_CPU1_PROCHOT_PCH_N")
	)
	(segment
		(start 394.94968 -51.766724)
		(end 394.94968 -52.687728)
		(width 0.089408)
		(layer "In9.Cu")
		(net "FM_CPU1_PROCHOT_PCH_N")
	)
	(segment
		(start 395.742668 -43.801792)
		(end 394.895578 -44.648882)
		(width 0.089408)
		(layer "In9.Cu")
		(net "FM_CPU1_PROCHOT_PCH_N")
	)
	(segment
		(start 385.181602 -91.855036)
		(end 385.292092 -91.965526)
		(width 0.089408)
		(layer "In9.Cu")
		(net "FM_CPU1_PROCHOT_PCH_N")
	)
	(segment
		(start 385.18465 -93.30055)
		(end 384.38709 -94.09811)
		(width 0.089408)
		(layer "In9.Cu")
		(net "FM_CPU1_PROCHOT_PCH_N")
	)
	(segment
		(start 384.829304 -88.642444)
		(end 384.829304 -89.266776)
		(width 0.089408)
		(layer "In9.Cu")
		(net "FM_CPU1_PROCHOT_PCH_N")
	)
	(segment
		(start 392.392408 -72.191372)
		(end 391.997946 -72.585834)
		(width 0.089408)
		(layer "In9.Cu")
		(net "FM_CPU1_PROCHOT_PCH_N")
	)
	(segment
		(start 389.971788 -79.445866)
		(end 389.971788 -81.93659)
		(width 0.089408)
		(layer "In9.Cu")
		(net "FM_CPU1_PROCHOT_PCH_N")
	)
	(segment
		(start 389.781796 -84.826094)
		(end 388.101586 -86.506304)
		(width 0.089408)
		(layer "In9.Cu")
		(net "FM_CPU1_PROCHOT_PCH_N")
	)
	(segment
		(start 384.38709 -94.09811)
		(end 384.38709 -95.094298)
		(width 0.089408)
		(layer "In9.Cu")
		(net "FM_CPU1_PROCHOT_PCH_N")
	)
	(segment
		(start 395.15923 -62.789562)
		(end 394.33119 -63.617602)
		(width 0.089408)
		(layer "In9.Cu")
		(net "FM_CPU1_PROCHOT_PCH_N")
	)
	(segment
		(start 390.56056 -78.857094)
		(end 389.971788 -79.445866)
		(width 0.089408)
		(layer "In9.Cu")
		(net "FM_CPU1_PROCHOT_PCH_N")
	)
	(segment
		(start 395.159484 -53.214524)
		(end 395.159484 -54.64048)
		(width 0.089408)
		(layer "In9.Cu")
		(net "FM_CPU1_PROCHOT_PCH_N")
	)
	(segment
		(start 384.212846 -91.26855)
		(end 384.799332 -91.855036)
		(width 0.089408)
		(layer "In9.Cu")
		(net "FM_CPU1_PROCHOT_PCH_N")
	)
	(segment
		(start 385.18465 -92.573602)
		(end 385.18465 -93.30055)
		(width 0.089408)
		(layer "In9.Cu")
		(net "FM_CPU1_PROCHOT_PCH_N")
	)
	(segment
		(start 384.829558 -89.426542)
		(end 384.212846 -90.043254)
		(width 0.089408)
		(layer "In9.Cu")
		(net "FM_CPU1_PROCHOT_PCH_N")
	)
	(segment
		(start 386.537962 -87.508334)
		(end 385.963414 -87.508334)
		(width 0.089408)
		(layer "In9.Cu")
		(net "FM_CPU1_PROCHOT_PCH_N")
	)
	(segment
		(start 384.175762 -96.652588)
		(end 384.27025 -96.747076)
		(width 0.089408)
		(layer "In9.Cu")
		(net "FM_CPU1_PROCHOT_PCH_N")
	)
	(segment
		(start 384.799332 -91.855036)
		(end 385.181602 -91.855036)
		(width 0.089408)
		(layer "In9.Cu")
		(net "FM_CPU1_PROCHOT_PCH_N")
	)
	(segment
		(start 395.077696 -49.33442)
		(end 395.077696 -51.480212)
		(width 0.089408)
		(layer "In9.Cu")
		(net "FM_CPU1_PROCHOT_PCH_N")
	)
	(segment
		(start 391.997946 -73.487534)
		(end 392.159744 -73.649332)
		(width 0.089408)
		(layer "In9.Cu")
		(net "FM_CPU1_PROCHOT_PCH_N")
	)
	(segment
		(start 395.07795 -51.638454)
		(end 394.94968 -51.766724)
		(width 0.089408)
		(layer "In9.Cu")
		(net "FM_CPU1_PROCHOT_PCH_N")
	)
	(segment
		(start 388.101586 -86.506304)
		(end 388.101586 -86.902036)
		(width 0.089408)
		(layer "In9.Cu")
		(net "FM_CPU1_PROCHOT_PCH_N")
	)
	(segment
		(start 394.949426 -52.687982)
		(end 394.949426 -53.004466)
		(width 0.089408)
		(layer "In9.Cu")
		(net "FM_CPU1_PROCHOT_PCH_N")
	)
	(segment
		(start 384.175762 -95.305626)
		(end 384.175762 -96.652588)
		(width 0.089408)
		(layer "In9.Cu")
		(net "FM_CPU1_PROCHOT_PCH_N")
	)
	(segment
		(start 386.844286 -87.20201)
		(end 386.537962 -87.508334)
		(width 0.089408)
		(layer "In9.Cu")
		(net "FM_CPU1_PROCHOT_PCH_N")
	)
	(segment
		(start 391.997946 -72.585834)
		(end 391.997946 -73.487534)
		(width 0.089408)
		(layer "In9.Cu")
		(net "FM_CPU1_PROCHOT_PCH_N")
	)
	(segment
		(start 395.077696 -51.480212)
		(end 395.07795 -51.480466)
		(width 0.089408)
		(layer "In9.Cu")
		(net "FM_CPU1_PROCHOT_PCH_N")
	)
	(segment
		(start 389.971788 -81.93659)
		(end 390.03224 -81.997042)
		(width 0.089408)
		(layer "In9.Cu")
		(net "FM_CPU1_PROCHOT_PCH_N")
	)
	(segment
		(start 403.319996 -44.15155)
		(end 401.938998 -44.15155)
		(width 0.10795)
		(layer "F.Cu")
		(net "FM_CPU0_PROCHOT_PCH_N")
	)
	(segment
		(start 397.098012 -43.24604)
		(end 396.116048 -44.228004)
		(width 0.10795)
		(layer "F.Cu")
		(net "FM_CPU0_PROCHOT_PCH_N")
	)
	(segment
		(start 395.421104 -44.228004)
		(end 395.41704 -44.232068)
		(width 0.10795)
		(layer "F.Cu")
		(net "FM_CPU0_PROCHOT_PCH_N")
	)
	(segment
		(start 398.501108 -43.24604)
		(end 397.098012 -43.24604)
		(width 0.10795)
		(layer "F.Cu")
		(net "FM_CPU0_PROCHOT_PCH_N")
	)
	(segment
		(start 395.41704 -44.232068)
		(end 395.41704 -44.245022)
		(width 0.10795)
		(layer "F.Cu")
		(net "FM_CPU0_PROCHOT_PCH_N")
	)
	(segment
		(start 395.41704 -44.245022)
		(end 392.689588 -46.972474)
		(width 0.10795)
		(layer "F.Cu")
		(net "FM_CPU0_PROCHOT_PCH_N")
	)
	(segment
		(start 403.530054 -43.729148)
		(end 403.530054 -43.941492)
		(width 0.10795)
		(layer "F.Cu")
		(net "FM_CPU0_PROCHOT_PCH_N")
	)
	(segment
		(start 393.106402 -50.198274)
		(end 394.224002 -51.315874)
		(width 0.10795)
		(layer "F.Cu")
		(net "FM_CPU0_PROCHOT_PCH_N")
	)
	(segment
		(start 393.106402 -49.083468)
		(end 393.106402 -50.198274)
		(width 0.10795)
		(layer "F.Cu")
		(net "FM_CPU0_PROCHOT_PCH_N")
	)
	(segment
		(start 399.180812 -43.925744)
		(end 398.501108 -43.24604)
		(width 0.10795)
		(layer "F.Cu")
		(net "FM_CPU0_PROCHOT_PCH_N")
	)
	(segment
		(start 401.938998 -44.15155)
		(end 401.713192 -43.925744)
		(width 0.10795)
		(layer "F.Cu")
		(net "FM_CPU0_PROCHOT_PCH_N")
	)
	(segment
		(start 401.713192 -43.925744)
		(end 399.180812 -43.925744)
		(width 0.10795)
		(layer "F.Cu")
		(net "FM_CPU0_PROCHOT_PCH_N")
	)
	(segment
		(start 392.689588 -48.666654)
		(end 393.106402 -49.083468)
		(width 0.10795)
		(layer "F.Cu")
		(net "FM_CPU0_PROCHOT_PCH_N")
	)
	(segment
		(start 403.530054 -43.941492)
		(end 403.319996 -44.15155)
		(width 0.10795)
		(layer "F.Cu")
		(net "FM_CPU0_PROCHOT_PCH_N")
	)
	(segment
		(start 383.77495 -95.888556)
		(end 383.27965 -96.11868)
		(width 0.10795)
		(layer "F.Cu")
		(net "FM_CPU0_PROCHOT_PCH_N")
	)
	(segment
		(start 392.689588 -46.972474)
		(end 392.689588 -48.666654)
		(width 0.10795)
		(layer "F.Cu")
		(net "FM_CPU0_PROCHOT_PCH_N")
	)
	(segment
		(start 396.116048 -44.228004)
		(end 395.421104 -44.228004)
		(width 0.10795)
		(layer "F.Cu")
		(net "FM_CPU0_PROCHOT_PCH_N")
	)
	(via
		(at 383.77495 -95.888556)
		(size 0.508)
		(drill 0.254)
		(layers "F.Cu" "B.Cu")
		(net "FM_CPU0_PROCHOT_PCH_N")
	)
	(via
		(at 394.224002 -51.315874)
		(size 0.508)
		(drill 0.254)
		(layers "F.Cu" "B.Cu")
		(net "FM_CPU0_PROCHOT_PCH_N")
	)
	(segment
		(start 386.185156 -87.01405)
		(end 386.18541 -87.014304)
		(width 0.089408)
		(layer "In9.Cu")
		(net "FM_CPU0_PROCHOT_PCH_N")
	)
	(segment
		(start 391.134346 -76.14539)
		(end 391.134346 -75.987402)
		(width 0.089408)
		(layer "In9.Cu")
		(net "FM_CPU0_PROCHOT_PCH_N")
	)
	(segment
		(start 394.777214 -62.631066)
		(end 394.777214 -54.482238)
		(width 0.089408)
		(layer "In9.Cu")
		(net "FM_CPU0_PROCHOT_PCH_N")
	)
	(segment
		(start 391.777728 -73.807828)
		(end 391.61593 -73.64603)
		(width 0.089408)
		(layer "In9.Cu")
		(net "FM_CPU0_PROCHOT_PCH_N")
	)
	(segment
		(start 384.0607 -91.748356)
		(end 383.825242 -91.512898)
		(width 0.089408)
		(layer "In9.Cu")
		(net "FM_CPU0_PROCHOT_PCH_N")
	)
	(segment
		(start 394.777468 -53.37302)
		(end 394.224002 -52.819554)
		(width 0.089408)
		(layer "In9.Cu")
		(net "FM_CPU0_PROCHOT_PCH_N")
	)
	(segment
		(start 393.913106 -69.020182)
		(end 393.913106 -63.65367)
		(width 0.089408)
		(layer "In9.Cu")
		(net "FM_CPU0_PROCHOT_PCH_N")
	)
	(segment
		(start 391.61593 -72.427338)
		(end 392.010392 -72.032876)
		(width 0.089408)
		(layer "In9.Cu")
		(net "FM_CPU0_PROCHOT_PCH_N")
	)
	(segment
		(start 394.777468 -54.481984)
		(end 394.777468 -53.37302)
		(width 0.089408)
		(layer "In9.Cu")
		(net "FM_CPU0_PROCHOT_PCH_N")
	)
	(segment
		(start 385.880102 -87.014304)
		(end 386.026914 -87.014304)
		(width 0.089408)
		(layer "In9.Cu")
		(net "FM_CPU0_PROCHOT_PCH_N")
	)
	(segment
		(start 384.447288 -88.447118)
		(end 385.880102 -87.014304)
		(width 0.089408)
		(layer "In9.Cu")
		(net "FM_CPU0_PROCHOT_PCH_N")
	)
	(segment
		(start 388.055866 -85.99043)
		(end 389.35914 -84.687156)
		(width 0.089408)
		(layer "In9.Cu")
		(net "FM_CPU0_PROCHOT_PCH_N")
	)
	(segment
		(start 386.026914 -87.014304)
		(end 386.027168 -87.01405)
		(width 0.089408)
		(layer "In9.Cu")
		(net "FM_CPU0_PROCHOT_PCH_N")
	)
	(segment
		(start 386.674868 -86.599522)
		(end 387.28396 -85.99043)
		(width 0.089408)
		(layer "In9.Cu")
		(net "FM_CPU0_PROCHOT_PCH_N")
	)
	(segment
		(start 389.535416 -79.212948)
		(end 389.25627 -78.933802)
		(width 0.089408)
		(layer "In9.Cu")
		(net "FM_CPU0_PROCHOT_PCH_N")
	)
	(segment
		(start 391.134346 -75.987402)
		(end 391.777728 -75.34402)
		(width 0.089408)
		(layer "In9.Cu")
		(net "FM_CPU0_PROCHOT_PCH_N")
	)
	(segment
		(start 383.825242 -91.512898)
		(end 383.825242 -89.887298)
		(width 0.089408)
		(layer "In9.Cu")
		(net "FM_CPU0_PROCHOT_PCH_N")
	)
	(segment
		(start 388.81939 -82.739738)
		(end 388.81939 -82.334354)
		(width 0.089408)
		(layer "In9.Cu")
		(net "FM_CPU0_PROCHOT_PCH_N")
	)
	(segment
		(start 393.912852 -63.495428)
		(end 394.777214 -62.631066)
		(width 0.089408)
		(layer "In9.Cu")
		(net "FM_CPU0_PROCHOT_PCH_N")
	)
	(segment
		(start 392.010392 -70.922896)
		(end 393.913106 -69.020182)
		(width 0.089408)
		(layer "In9.Cu")
		(net "FM_CPU0_PROCHOT_PCH_N")
	)
	(segment
		(start 391.1346 -77.349858)
		(end 391.1346 -76.145644)
		(width 0.089408)
		(layer "In9.Cu")
		(net "FM_CPU0_PROCHOT_PCH_N")
	)
	(segment
		(start 394.224002 -52.819554)
		(end 394.224002 -51.315874)
		(width 0.089408)
		(layer "In9.Cu")
		(net "FM_CPU0_PROCHOT_PCH_N")
	)
	(segment
		(start 389.35914 -84.687156)
		(end 389.35914 -83.279488)
		(width 0.089408)
		(layer "In9.Cu")
		(net "FM_CPU0_PROCHOT_PCH_N")
	)
	(segment
		(start 390.555988 -77.92847)
		(end 391.1346 -77.349858)
		(width 0.089408)
		(layer "In9.Cu")
		(net "FM_CPU0_PROCHOT_PCH_N")
	)
	(segment
		(start 391.61593 -73.64603)
		(end 391.61593 -72.427338)
		(width 0.089408)
		(layer "In9.Cu")
		(net "FM_CPU0_PROCHOT_PCH_N")
	)
	(segment
		(start 383.825242 -89.887298)
		(end 384.447288 -89.265252)
		(width 0.089408)
		(layer "In9.Cu")
		(net "FM_CPU0_PROCHOT_PCH_N")
	)
	(segment
		(start 389.771382 -77.92847)
		(end 390.555988 -77.92847)
		(width 0.089408)
		(layer "In9.Cu")
		(net "FM_CPU0_PROCHOT_PCH_N")
	)
	(segment
		(start 391.777728 -75.34402)
		(end 391.777728 -73.807828)
		(width 0.089408)
		(layer "In9.Cu")
		(net "FM_CPU0_PROCHOT_PCH_N")
	)
	(segment
		(start 384.447288 -89.265252)
		(end 384.447288 -88.447118)
		(width 0.089408)
		(layer "In9.Cu")
		(net "FM_CPU0_PROCHOT_PCH_N")
	)
	(segment
		(start 393.913106 -63.65367)
		(end 393.912852 -63.653416)
		(width 0.089408)
		(layer "In9.Cu")
		(net "FM_CPU0_PROCHOT_PCH_N")
	)
	(segment
		(start 389.35914 -83.279488)
		(end 388.81939 -82.739738)
		(width 0.089408)
		(layer "In9.Cu")
		(net "FM_CPU0_PROCHOT_PCH_N")
	)
	(segment
		(start 388.81939 -82.334354)
		(end 389.535416 -81.618328)
		(width 0.089408)
		(layer "In9.Cu")
		(net "FM_CPU0_PROCHOT_PCH_N")
	)
	(segment
		(start 393.912852 -63.653416)
		(end 393.912852 -63.495428)
		(width 0.089408)
		(layer "In9.Cu")
		(net "FM_CPU0_PROCHOT_PCH_N")
	)
	(segment
		(start 386.18541 -87.014304)
		(end 386.440426 -87.014304)
		(width 0.089408)
		(layer "In9.Cu")
		(net "FM_CPU0_PROCHOT_PCH_N")
	)
	(segment
		(start 386.674868 -86.779862)
		(end 386.674868 -86.599522)
		(width 0.089408)
		(layer "In9.Cu")
		(net "FM_CPU0_PROCHOT_PCH_N")
	)
	(segment
		(start 386.027168 -87.01405)
		(end 386.185156 -87.01405)
		(width 0.089408)
		(layer "In9.Cu")
		(net "FM_CPU0_PROCHOT_PCH_N")
	)
	(segment
		(start 389.535416 -81.618328)
		(end 389.535416 -79.212948)
		(width 0.089408)
		(layer "In9.Cu")
		(net "FM_CPU0_PROCHOT_PCH_N")
	)
	(segment
		(start 386.440426 -87.014304)
		(end 386.674868 -86.779862)
		(width 0.089408)
		(layer "In9.Cu")
		(net "FM_CPU0_PROCHOT_PCH_N")
	)
	(segment
		(start 383.77495 -95.093536)
		(end 384.0607 -94.807786)
		(width 0.089408)
		(layer "In9.Cu")
		(net "FM_CPU0_PROCHOT_PCH_N")
	)
	(segment
		(start 389.25627 -78.933802)
		(end 389.25627 -78.443582)
		(width 0.089408)
		(layer "In9.Cu")
		(net "FM_CPU0_PROCHOT_PCH_N")
	)
	(segment
		(start 394.777214 -54.482238)
		(end 394.777468 -54.481984)
		(width 0.089408)
		(layer "In9.Cu")
		(net "FM_CPU0_PROCHOT_PCH_N")
	)
	(segment
		(start 392.010392 -72.032876)
		(end 392.010392 -70.922896)
		(width 0.089408)
		(layer "In9.Cu")
		(net "FM_CPU0_PROCHOT_PCH_N")
	)
	(segment
		(start 387.28396 -85.99043)
		(end 388.055866 -85.99043)
		(width 0.089408)
		(layer "In9.Cu")
		(net "FM_CPU0_PROCHOT_PCH_N")
	)
	(segment
		(start 391.1346 -76.145644)
		(end 391.134346 -76.14539)
		(width 0.089408)
		(layer "In9.Cu")
		(net "FM_CPU0_PROCHOT_PCH_N")
	)
	(segment
		(start 383.77495 -95.888556)
		(end 383.77495 -95.093536)
		(width 0.089408)
		(layer "In9.Cu")
		(net "FM_CPU0_PROCHOT_PCH_N")
	)
	(segment
		(start 389.25627 -78.443582)
		(end 389.771382 -77.92847)
		(width 0.089408)
		(layer "In9.Cu")
		(net "FM_CPU0_PROCHOT_PCH_N")
	)
	(segment
		(start 384.0607 -94.807786)
		(end 384.0607 -91.748356)
		(width 0.089408)
		(layer "In9.Cu")
		(net "FM_CPU0_PROCHOT_PCH_N")
	)
	(segment
		(start 91.787218 -88.28024)
		(end 91.215718 -88.28024)
		(width 0.10795)
		(layer "F.Cu")
		(net "SMB_PIROM_CPU1_SDA")
	)
	(via
		(at 91.215718 -88.28024)
		(size 0.508)
		(drill 0.254)
		(layers "F.Cu" "B.Cu")
		(net "SMB_PIROM_CPU1_SDA")
	)
	(via
		(at 31.354014 -107.13593)
		(size 0.508)
		(drill 0.254)
		(layers "F.Cu" "B.Cu")
		(net "SMB_PIROM_CPU1_SDA")
	)
	(via
		(at 28.556458 -126.29515)
		(size 0.508)
		(drill 0.254)
		(layers "F.Cu" "B.Cu")
		(net "SMB_PIROM_CPU1_SDA")
	)
	(segment
		(start 28.6131 -127.39116)
		(end 26.933398 -127.39116)
		(width 0.10795)
		(layer "B.Cu")
		(net "SMB_PIROM_CPU1_SDA")
	)
	(segment
		(start 25.655778 -128.66878)
		(end 25.655524 -128.66878)
		(width 0.10795)
		(layer "B.Cu")
		(net "SMB_PIROM_CPU1_SDA")
	)
	(segment
		(start 25.632664 -128.69164)
		(end 22.84349 -128.69164)
		(width 0.10795)
		(layer "B.Cu")
		(net "SMB_PIROM_CPU1_SDA")
	)
	(segment
		(start 28.556458 -126.29515)
		(end 28.860496 -126.599188)
		(width 0.10795)
		(layer "B.Cu")
		(net "SMB_PIROM_CPU1_SDA")
	)
	(segment
		(start 26.933398 -127.39116)
		(end 25.655778 -128.66878)
		(width 0.10795)
		(layer "B.Cu")
		(net "SMB_PIROM_CPU1_SDA")
	)
	(segment
		(start 19.451066 -133.753606)
		(end 19.264884 -133.939788)
		(width 0.10795)
		(layer "B.Cu")
		(net "SMB_PIROM_CPU1_SDA")
	)
	(segment
		(start 28.860496 -126.599188)
		(end 28.860496 -127.143764)
		(width 0.10795)
		(layer "B.Cu")
		(net "SMB_PIROM_CPU1_SDA")
	)
	(segment
		(start 28.860496 -127.143764)
		(end 28.6131 -127.39116)
		(width 0.10795)
		(layer "B.Cu")
		(net "SMB_PIROM_CPU1_SDA")
	)
	(segment
		(start 22.84349 -128.69164)
		(end 22.037294 -129.497836)
		(width 0.10795)
		(layer "B.Cu")
		(net "SMB_PIROM_CPU1_SDA")
	)
	(segment
		(start 25.655524 -128.66878)
		(end 25.632664 -128.69164)
		(width 0.10795)
		(layer "B.Cu")
		(net "SMB_PIROM_CPU1_SDA")
	)
	(segment
		(start 22.037294 -132.31114)
		(end 20.594828 -133.753606)
		(width 0.10795)
		(layer "B.Cu")
		(net "SMB_PIROM_CPU1_SDA")
	)
	(segment
		(start 19.264884 -133.939788)
		(end 19.264884 -134.189978)
		(width 0.10795)
		(layer "B.Cu")
		(net "SMB_PIROM_CPU1_SDA")
	)
	(segment
		(start 20.594828 -133.753606)
		(end 19.451066 -133.753606)
		(width 0.10795)
		(layer "B.Cu")
		(net "SMB_PIROM_CPU1_SDA")
	)
	(segment
		(start 22.037294 -129.497836)
		(end 22.037294 -132.31114)
		(width 0.10795)
		(layer "B.Cu")
		(net "SMB_PIROM_CPU1_SDA")
	)
	(segment
		(start 68.174616 -77.97419)
		(end 68.986908 -77.97419)
		(width 0.0889)
		(layer "In4.Cu")
		(net "SMB_PIROM_CPU1_SDA")
	)
	(segment
		(start 88.618822 -86.394036)
		(end 88.640412 -86.394036)
		(width 0.0889)
		(layer "In4.Cu")
		(net "SMB_PIROM_CPU1_SDA")
	)
	(segment
		(start 87.764112 -85.89899)
		(end 87.796878 -85.89899)
		(width 0.0889)
		(layer "In4.Cu")
		(net "SMB_PIROM_CPU1_SDA")
	)
	(segment
		(start 49.402492 -94.55277)
		(end 49.402492 -93.25102)
		(width 0.089408)
		(layer "In4.Cu")
		(net "SMB_PIROM_CPU1_SDA")
	)
	(segment
		(start 43.361102 -100.16617)
		(end 44.170092 -100.16617)
		(width 0.089408)
		(layer "In4.Cu")
		(net "SMB_PIROM_CPU1_SDA")
	)
	(segment
		(start 90.487754 -87.351616)
		(end 90.648028 -87.51189)
		(width 0.0889)
		(layer "In4.Cu")
		(net "SMB_PIROM_CPU1_SDA")
	)
	(segment
		(start 31.516828 -104.830372)
		(end 32.17672 -104.17048)
		(width 0.089408)
		(layer "In4.Cu")
		(net "SMB_PIROM_CPU1_SDA")
	)
	(segment
		(start 85.184742 -84.412836)
		(end 85.217508 -84.412836)
		(width 0.0889)
		(layer "In4.Cu")
		(net "SMB_PIROM_CPU1_SDA")
	)
	(segment
		(start 45.52188 -98.814382)
		(end 45.52188 -98.433382)
		(width 0.089408)
		(layer "In4.Cu")
		(net "SMB_PIROM_CPU1_SDA")
	)
	(segment
		(start 44.170092 -100.16617)
		(end 45.52188 -98.814382)
		(width 0.089408)
		(layer "In4.Cu")
		(net "SMB_PIROM_CPU1_SDA")
	)
	(segment
		(start 90.720672 -87.614252)
		(end 91.215718 -88.28024)
		(width 0.0889)
		(layer "In4.Cu")
		(net "SMB_PIROM_CPU1_SDA")
	)
	(segment
		(start 78.31328 -81.441036)
		(end 78.359762 -81.441036)
		(width 0.0889)
		(layer "In4.Cu")
		(net "SMB_PIROM_CPU1_SDA")
	)
	(segment
		(start 90.299286 -87.351616)
		(end 90.487754 -87.351616)
		(width 0.0889)
		(layer "In4.Cu")
		(net "SMB_PIROM_CPU1_SDA")
	)
	(segment
		(start 73.165716 -79.459836)
		(end 73.198482 -79.459836)
		(width 0.0889)
		(layer "In4.Cu")
		(net "SMB_PIROM_CPU1_SDA")
	)
	(segment
		(start 88.983566 -86.588346)
		(end 88.986868 -86.594188)
		(width 0.0889)
		(layer "In4.Cu")
		(net "SMB_PIROM_CPU1_SDA")
	)
	(segment
		(start 80.898746 -80.94599)
		(end 80.928718 -80.94599)
		(width 0.0889)
		(layer "In4.Cu")
		(net "SMB_PIROM_CPU1_SDA")
	)
	(segment
		(start 50.842672 -91.81084)
		(end 50.842672 -91.402408)
		(width 0.089408)
		(layer "In4.Cu")
		(net "SMB_PIROM_CPU1_SDA")
	)
	(segment
		(start 69.534786 -78.469236)
		(end 69.764402 -78.469236)
		(width 0.0889)
		(layer "In4.Cu")
		(net "SMB_PIROM_CPU1_SDA")
	)
	(segment
		(start 89.480898 -86.88959)
		(end 89.513664 -86.88959)
		(width 0.0889)
		(layer "In4.Cu")
		(net "SMB_PIROM_CPU1_SDA")
	)
	(segment
		(start 70.593966 -78.96479)
		(end 70.626732 -78.96479)
		(width 0.0889)
		(layer "In4.Cu")
		(net "SMB_PIROM_CPU1_SDA")
	)
	(segment
		(start 36.352734 -104.17048)
		(end 38.464236 -102.058978)
		(width 0.089408)
		(layer "In4.Cu")
		(net "SMB_PIROM_CPU1_SDA")
	)
	(segment
		(start 86.047072 -84.90839)
		(end 86.079838 -84.90839)
		(width 0.0889)
		(layer "In4.Cu")
		(net "SMB_PIROM_CPU1_SDA")
	)
	(segment
		(start 81.750662 -81.441036)
		(end 81.783428 -81.441036)
		(width 0.0889)
		(layer "In4.Cu")
		(net "SMB_PIROM_CPU1_SDA")
	)
	(segment
		(start 45.52188 -98.433382)
		(end 49.402492 -94.55277)
		(width 0.089408)
		(layer "In4.Cu")
		(net "SMB_PIROM_CPU1_SDA")
	)
	(segment
		(start 50.842672 -91.402408)
		(end 62.730126 -79.492094)
		(width 0.089408)
		(layer "In4.Cu")
		(net "SMB_PIROM_CPU1_SDA")
	)
	(segment
		(start 82.612992 -81.93659)
		(end 82.645758 -81.93659)
		(width 0.0889)
		(layer "In4.Cu")
		(net "SMB_PIROM_CPU1_SDA")
	)
	(segment
		(start 72.3138 -78.96479)
		(end 72.343772 -78.96479)
		(width 0.0889)
		(layer "In4.Cu")
		(net "SMB_PIROM_CPU1_SDA")
	)
	(segment
		(start 32.17672 -104.17048)
		(end 36.352734 -104.17048)
		(width 0.089408)
		(layer "In4.Cu")
		(net "SMB_PIROM_CPU1_SDA")
	)
	(segment
		(start 74.028046 -79.95539)
		(end 74.060812 -79.95539)
		(width 0.0889)
		(layer "In4.Cu")
		(net "SMB_PIROM_CPU1_SDA")
	)
	(segment
		(start 71.448676 -79.459836)
		(end 71.491856 -79.459836)
		(width 0.0889)
		(layer "In4.Cu")
		(net "SMB_PIROM_CPU1_SDA")
	)
	(segment
		(start 65.558162 -78.734412)
		(end 65.579498 -78.728824)
		(width 0.0889)
		(layer "In4.Cu")
		(net "SMB_PIROM_CPU1_SDA")
	)
	(segment
		(start 76.599796 -80.450436)
		(end 76.632562 -80.450436)
		(width 0.0889)
		(layer "In4.Cu")
		(net "SMB_PIROM_CPU1_SDA")
	)
	(segment
		(start 83.476338 -82.43189)
		(end 83.500468 -82.43189)
		(width 0.0889)
		(layer "In4.Cu")
		(net "SMB_PIROM_CPU1_SDA")
	)
	(segment
		(start 31.516828 -106.973116)
		(end 31.516828 -104.830372)
		(width 0.089408)
		(layer "In4.Cu")
		(net "SMB_PIROM_CPU1_SDA")
	)
	(segment
		(start 62.730126 -79.492094)
		(end 65.558162 -78.734412)
		(width 0.089408)
		(layer "In4.Cu")
		(net "SMB_PIROM_CPU1_SDA")
	)
	(segment
		(start 90.703908 -87.584788)
		(end 90.720672 -87.614252)
		(width 0.0889)
		(layer "In4.Cu")
		(net "SMB_PIROM_CPU1_SDA")
	)
	(segment
		(start 77.462126 -80.94599)
		(end 77.479906 -80.94599)
		(width 0.0889)
		(layer "In4.Cu")
		(net "SMB_PIROM_CPU1_SDA")
	)
	(segment
		(start 41.468294 -102.058978)
		(end 43.361102 -100.16617)
		(width 0.089408)
		(layer "In4.Cu")
		(net "SMB_PIROM_CPU1_SDA")
	)
	(segment
		(start 65.61963 -78.659228)
		(end 68.174616 -77.97419)
		(width 0.0889)
		(layer "In4.Cu")
		(net "SMB_PIROM_CPU1_SDA")
	)
	(segment
		(start 49.402492 -93.25102)
		(end 50.842672 -91.81084)
		(width 0.089408)
		(layer "In4.Cu")
		(net "SMB_PIROM_CPU1_SDA")
	)
	(segment
		(start 77.82306 -81.1403)
		(end 77.826362 -81.146142)
		(width 0.0889)
		(layer "In4.Cu")
		(net "SMB_PIROM_CPU1_SDA")
	)
	(segment
		(start 65.579498 -78.728824)
		(end 65.61963 -78.659228)
		(width 0.0889)
		(layer "In4.Cu")
		(net "SMB_PIROM_CPU1_SDA")
	)
	(segment
		(start 38.464236 -102.058978)
		(end 41.468294 -102.058978)
		(width 0.089408)
		(layer "In4.Cu")
		(net "SMB_PIROM_CPU1_SDA")
	)
	(segment
		(start 84.330032 -83.91779)
		(end 84.362798 -83.91779)
		(width 0.0889)
		(layer "In4.Cu")
		(net "SMB_PIROM_CPU1_SDA")
	)
	(segment
		(start 31.354014 -107.13593)
		(end 31.516828 -106.973116)
		(width 0.089408)
		(layer "In4.Cu")
		(net "SMB_PIROM_CPU1_SDA")
	)
	(segment
		(start 86.901782 -85.403436)
		(end 86.934548 -85.403436)
		(width 0.0889)
		(layer "In4.Cu")
		(net "SMB_PIROM_CPU1_SDA")
	)
	(arc
		(start 79.543402 -81.145888)
		(mid 80.055212 -81.441427)
		(end 80.567022 -81.145888)
		(width 0.0889)
		(layer "In4.Cu")
		(net "SMB_PIROM_CPU1_SDA")
	)
	(arc
		(start 72.343772 -78.96479)
		(mid 72.535414 -79.021956)
		(end 72.675496 -79.164688)
		(width 0.0889)
		(layer "In4.Cu")
		(net "SMB_PIROM_CPU1_SDA")
	)
	(arc
		(start 70.626732 -78.96479)
		(mid 70.818374 -79.021956)
		(end 70.958456 -79.164688)
		(width 0.0889)
		(layer "In4.Cu")
		(net "SMB_PIROM_CPU1_SDA")
	)
	(arc
		(start 84.362798 -83.91779)
		(mid 84.55444 -83.974956)
		(end 84.694522 -84.117688)
		(width 0.0889)
		(layer "In4.Cu")
		(net "SMB_PIROM_CPU1_SDA")
	)
	(arc
		(start 88.128602 -86.098888)
		(mid 88.335606 -86.309752)
		(end 88.618822 -86.394036)
		(width 0.0889)
		(layer "In4.Cu")
		(net "SMB_PIROM_CPU1_SDA")
	)
	(arc
		(start 74.060812 -79.95539)
		(mid 74.252454 -80.012556)
		(end 74.392536 -80.155288)
		(width 0.0889)
		(layer "In4.Cu")
		(net "SMB_PIROM_CPU1_SDA")
	)
	(arc
		(start 80.567022 -81.145888)
		(mid 80.707101 -81.003152)
		(end 80.898746 -80.94599)
		(width 0.0889)
		(layer "In4.Cu")
		(net "SMB_PIROM_CPU1_SDA")
	)
	(arc
		(start 74.392536 -80.155288)
		(mid 74.904346 -80.450827)
		(end 75.416156 -80.155288)
		(width 0.0889)
		(layer "In4.Cu")
		(net "SMB_PIROM_CPU1_SDA")
	)
	(arc
		(start 81.260442 -81.145888)
		(mid 81.467446 -81.356752)
		(end 81.750662 -81.441036)
		(width 0.0889)
		(layer "In4.Cu")
		(net "SMB_PIROM_CPU1_SDA")
	)
	(arc
		(start 90.648028 -87.51189)
		(mid 90.678366 -87.546501)
		(end 90.703908 -87.584788)
		(width 0.0889)
		(layer "In4.Cu")
		(net "SMB_PIROM_CPU1_SDA")
	)
	(arc
		(start 68.986908 -77.97419)
		(mid 69.107651 -78.055004)
		(end 69.195442 -78.170786)
		(width 0.0889)
		(layer "In4.Cu")
		(net "SMB_PIROM_CPU1_SDA")
	)
	(arc
		(start 75.416156 -80.155288)
		(mid 75.762866 -79.955104)
		(end 76.109576 -80.155288)
		(width 0.0889)
		(layer "In4.Cu")
		(net "SMB_PIROM_CPU1_SDA")
	)
	(arc
		(start 88.986868 -86.594188)
		(mid 89.195476 -86.80612)
		(end 89.480898 -86.88959)
		(width 0.0889)
		(layer "In4.Cu")
		(net "SMB_PIROM_CPU1_SDA")
	)
	(arc
		(start 88.640412 -86.394036)
		(mid 88.837573 -86.445995)
		(end 88.983566 -86.588346)
		(width 0.0889)
		(layer "In4.Cu")
		(net "SMB_PIROM_CPU1_SDA")
	)
	(arc
		(start 78.849982 -81.145888)
		(mid 79.196692 -80.945704)
		(end 79.543402 -81.145888)
		(width 0.0889)
		(layer "In4.Cu")
		(net "SMB_PIROM_CPU1_SDA")
	)
	(arc
		(start 82.118962 -81.641188)
		(mid 82.32757 -81.85312)
		(end 82.612992 -81.93659)
		(width 0.0889)
		(layer "In4.Cu")
		(net "SMB_PIROM_CPU1_SDA")
	)
	(arc
		(start 71.982076 -79.164688)
		(mid 72.122155 -79.021952)
		(end 72.3138 -78.96479)
		(width 0.0889)
		(layer "In4.Cu")
		(net "SMB_PIROM_CPU1_SDA")
	)
	(arc
		(start 76.109576 -80.155288)
		(mid 76.31658 -80.366152)
		(end 76.599796 -80.450436)
		(width 0.0889)
		(layer "In4.Cu")
		(net "SMB_PIROM_CPU1_SDA")
	)
	(arc
		(start 82.645758 -81.93659)
		(mid 82.8374 -81.993756)
		(end 82.977482 -82.136488)
		(width 0.0889)
		(layer "In4.Cu")
		(net "SMB_PIROM_CPU1_SDA")
	)
	(arc
		(start 86.411562 -85.108288)
		(mid 86.618566 -85.319152)
		(end 86.901782 -85.403436)
		(width 0.0889)
		(layer "In4.Cu")
		(net "SMB_PIROM_CPU1_SDA")
	)
	(arc
		(start 83.500468 -82.43189)
		(mid 83.838583 -82.636592)
		(end 83.836002 -83.031838)
		(width 0.0889)
		(layer "In4.Cu")
		(net "SMB_PIROM_CPU1_SDA")
	)
	(arc
		(start 87.796878 -85.89899)
		(mid 87.98852 -85.956156)
		(end 88.128602 -86.098888)
		(width 0.0889)
		(layer "In4.Cu")
		(net "SMB_PIROM_CPU1_SDA")
	)
	(arc
		(start 72.675496 -79.164688)
		(mid 72.8825 -79.375552)
		(end 73.165716 -79.459836)
		(width 0.0889)
		(layer "In4.Cu")
		(net "SMB_PIROM_CPU1_SDA")
	)
	(arc
		(start 77.479906 -80.94599)
		(mid 77.677067 -80.997949)
		(end 77.82306 -81.1403)
		(width 0.0889)
		(layer "In4.Cu")
		(net "SMB_PIROM_CPU1_SDA")
	)
	(arc
		(start 86.079838 -84.90839)
		(mid 86.27148 -84.965556)
		(end 86.411562 -85.108288)
		(width 0.0889)
		(layer "In4.Cu")
		(net "SMB_PIROM_CPU1_SDA")
	)
	(arc
		(start 80.928718 -80.94599)
		(mid 81.12036 -81.003156)
		(end 81.260442 -81.145888)
		(width 0.0889)
		(layer "In4.Cu")
		(net "SMB_PIROM_CPU1_SDA")
	)
	(arc
		(start 81.783428 -81.441036)
		(mid 81.977278 -81.497386)
		(end 82.118962 -81.641188)
		(width 0.0889)
		(layer "In4.Cu")
		(net "SMB_PIROM_CPU1_SDA")
	)
	(arc
		(start 89.845388 -87.089488)
		(mid 90.037237 -87.281303)
		(end 90.299286 -87.351616)
		(width 0.0889)
		(layer "In4.Cu")
		(net "SMB_PIROM_CPU1_SDA")
	)
	(arc
		(start 87.270082 -85.603588)
		(mid 87.47869 -85.81552)
		(end 87.764112 -85.89899)
		(width 0.0889)
		(layer "In4.Cu")
		(net "SMB_PIROM_CPU1_SDA")
	)
	(arc
		(start 73.534016 -79.659988)
		(mid 73.742624 -79.87192)
		(end 74.028046 -79.95539)
		(width 0.0889)
		(layer "In4.Cu")
		(net "SMB_PIROM_CPU1_SDA")
	)
	(arc
		(start 82.977482 -82.136488)
		(mid 83.188195 -82.349567)
		(end 83.476338 -82.43189)
		(width 0.0889)
		(layer "In4.Cu")
		(net "SMB_PIROM_CPU1_SDA")
	)
	(arc
		(start 70.958456 -79.164688)
		(mid 71.16546 -79.375552)
		(end 71.448676 -79.459836)
		(width 0.0889)
		(layer "In4.Cu")
		(net "SMB_PIROM_CPU1_SDA")
	)
	(arc
		(start 70.099936 -78.669388)
		(mid 70.308544 -78.88132)
		(end 70.593966 -78.96479)
		(width 0.0889)
		(layer "In4.Cu")
		(net "SMB_PIROM_CPU1_SDA")
	)
	(arc
		(start 69.195442 -78.170786)
		(mid 69.33742 -78.351498)
		(end 69.534786 -78.469236)
		(width 0.0889)
		(layer "In4.Cu")
		(net "SMB_PIROM_CPU1_SDA")
	)
	(arc
		(start 86.934548 -85.403436)
		(mid 87.128398 -85.459786)
		(end 87.270082 -85.603588)
		(width 0.0889)
		(layer "In4.Cu")
		(net "SMB_PIROM_CPU1_SDA")
	)
	(arc
		(start 76.632562 -80.450436)
		(mid 76.826412 -80.506786)
		(end 76.968096 -80.650588)
		(width 0.0889)
		(layer "In4.Cu")
		(net "SMB_PIROM_CPU1_SDA")
	)
	(arc
		(start 85.553042 -84.612988)
		(mid 85.76165 -84.82492)
		(end 86.047072 -84.90839)
		(width 0.0889)
		(layer "In4.Cu")
		(net "SMB_PIROM_CPU1_SDA")
	)
	(arc
		(start 89.513664 -86.88959)
		(mid 89.705306 -86.946756)
		(end 89.845388 -87.089488)
		(width 0.0889)
		(layer "In4.Cu")
		(net "SMB_PIROM_CPU1_SDA")
	)
	(arc
		(start 71.491856 -79.459836)
		(mid 71.775073 -79.375555)
		(end 71.982076 -79.164688)
		(width 0.0889)
		(layer "In4.Cu")
		(net "SMB_PIROM_CPU1_SDA")
	)
	(arc
		(start 69.764402 -78.469236)
		(mid 69.958252 -78.525586)
		(end 70.099936 -78.669388)
		(width 0.0889)
		(layer "In4.Cu")
		(net "SMB_PIROM_CPU1_SDA")
	)
	(arc
		(start 73.198482 -79.459836)
		(mid 73.392332 -79.516186)
		(end 73.534016 -79.659988)
		(width 0.0889)
		(layer "In4.Cu")
		(net "SMB_PIROM_CPU1_SDA")
	)
	(arc
		(start 78.359762 -81.441036)
		(mid 78.642979 -81.356755)
		(end 78.849982 -81.145888)
		(width 0.0889)
		(layer "In4.Cu")
		(net "SMB_PIROM_CPU1_SDA")
	)
	(arc
		(start 83.836002 -83.031838)
		(mid 83.831673 -83.61501)
		(end 84.330032 -83.91779)
		(width 0.0889)
		(layer "In4.Cu")
		(net "SMB_PIROM_CPU1_SDA")
	)
	(arc
		(start 84.694522 -84.117688)
		(mid 84.901526 -84.328552)
		(end 85.184742 -84.412836)
		(width 0.0889)
		(layer "In4.Cu")
		(net "SMB_PIROM_CPU1_SDA")
	)
	(arc
		(start 77.826362 -81.146142)
		(mid 78.031983 -81.356065)
		(end 78.31328 -81.441036)
		(width 0.0889)
		(layer "In4.Cu")
		(net "SMB_PIROM_CPU1_SDA")
	)
	(arc
		(start 85.217508 -84.412836)
		(mid 85.411358 -84.469186)
		(end 85.553042 -84.612988)
		(width 0.0889)
		(layer "In4.Cu")
		(net "SMB_PIROM_CPU1_SDA")
	)
	(arc
		(start 76.968096 -80.650588)
		(mid 77.176704 -80.86252)
		(end 77.462126 -80.94599)
		(width 0.0889)
		(layer "In4.Cu")
		(net "SMB_PIROM_CPU1_SDA")
	)
	(segment
		(start 31.354014 -107.13593)
		(end 31.301436 -107.083352)
		(width 0.089408)
		(layer "In11.Cu")
		(net "SMB_PIROM_CPU1_SDA")
	)
	(segment
		(start 31.301436 -107.083352)
		(end 30.293056 -107.083352)
		(width 0.089408)
		(layer "In11.Cu")
		(net "SMB_PIROM_CPU1_SDA")
	)
	(segment
		(start 28.808426 -108.567982)
		(end 28.808426 -125.55982)
		(width 0.089408)
		(layer "In11.Cu")
		(net "SMB_PIROM_CPU1_SDA")
	)
	(segment
		(start 28.808426 -125.55982)
		(end 28.556458 -125.811788)
		(width 0.089408)
		(layer "In11.Cu")
		(net "SMB_PIROM_CPU1_SDA")
	)
	(segment
		(start 30.293056 -107.083352)
		(end 28.808426 -108.567982)
		(width 0.089408)
		(layer "In11.Cu")
		(net "SMB_PIROM_CPU1_SDA")
	)
	(segment
		(start 28.556458 -125.811788)
		(end 28.556458 -126.29515)
		(width 0.089408)
		(layer "In11.Cu")
		(net "SMB_PIROM_CPU1_SDA")
	)
	(segment
		(start 90.928698 -86.794086)
		(end 90.357198 -86.794086)
		(width 0.10795)
		(layer "F.Cu")
		(net "SMB_PIROM_CPU1_SCL")
	)
	(via
		(at 90.357198 -86.794086)
		(size 0.508)
		(drill 0.254)
		(layers "F.Cu" "B.Cu")
		(net "SMB_PIROM_CPU1_SCL")
	)
	(via
		(at 31.049468 -106.476546)
		(size 0.508)
		(drill 0.254)
		(layers "F.Cu" "B.Cu")
		(net "SMB_PIROM_CPU1_SCL")
	)
	(via
		(at 28.438094 -126.968758)
		(size 0.508)
		(drill 0.254)
		(layers "F.Cu" "B.Cu")
		(net "SMB_PIROM_CPU1_SCL")
	)
	(segment
		(start 18.686018 -133.808724)
		(end 18.686018 -134.755382)
		(width 0.10795)
		(layer "B.Cu")
		(net "SMB_PIROM_CPU1_SCL")
	)
	(segment
		(start 22.71649 -128.385062)
		(end 21.730716 -129.370836)
		(width 0.10795)
		(layer "B.Cu")
		(net "SMB_PIROM_CPU1_SCL")
	)
	(segment
		(start 26.787856 -126.968758)
		(end 25.371552 -128.385062)
		(width 0.10795)
		(layer "B.Cu")
		(net "SMB_PIROM_CPU1_SCL")
	)
	(segment
		(start 21.730716 -132.18414)
		(end 20.453096 -133.46176)
		(width 0.10795)
		(layer "B.Cu")
		(net "SMB_PIROM_CPU1_SCL")
	)
	(segment
		(start 18.686018 -134.755382)
		(end 18.89633 -134.965694)
		(width 0.10795)
		(layer "B.Cu")
		(net "SMB_PIROM_CPU1_SCL")
	)
	(segment
		(start 19.032982 -133.46176)
		(end 18.686018 -133.808724)
		(width 0.10795)
		(layer "B.Cu")
		(net "SMB_PIROM_CPU1_SCL")
	)
	(segment
		(start 20.453096 -133.46176)
		(end 19.032982 -133.46176)
		(width 0.10795)
		(layer "B.Cu")
		(net "SMB_PIROM_CPU1_SCL")
	)
	(segment
		(start 18.89633 -134.965694)
		(end 19.26082 -134.965694)
		(width 0.10795)
		(layer "B.Cu")
		(net "SMB_PIROM_CPU1_SCL")
	)
	(segment
		(start 21.730716 -129.370836)
		(end 21.730716 -132.18414)
		(width 0.10795)
		(layer "B.Cu")
		(net "SMB_PIROM_CPU1_SCL")
	)
	(segment
		(start 28.438094 -126.968758)
		(end 26.787856 -126.968758)
		(width 0.10795)
		(layer "B.Cu")
		(net "SMB_PIROM_CPU1_SCL")
	)
	(segment
		(start 25.371552 -128.385062)
		(end 22.71649 -128.385062)
		(width 0.10795)
		(layer "B.Cu")
		(net "SMB_PIROM_CPU1_SCL")
	)
	(segment
		(start 65.500758 -78.434184)
		(end 65.570608 -78.474824)
		(width 0.0889)
		(layer "In4.Cu")
		(net "SMB_PIROM_CPU1_SCL")
	)
	(segment
		(start 89.152222 -86.498938)
		(end 89.155524 -86.50478)
		(width 0.0889)
		(layer "In4.Cu")
		(net "SMB_PIROM_CPU1_SCL")
	)
	(segment
		(start 36.129722 -103.979472)
		(end 38.342824 -101.76637)
		(width 0.089408)
		(layer "In4.Cu")
		(net "SMB_PIROM_CPU1_SCL")
	)
	(segment
		(start 45.274992 -98.597974)
		(end 45.274992 -98.304858)
		(width 0.089408)
		(layer "In4.Cu")
		(net "SMB_PIROM_CPU1_SCL")
	)
	(segment
		(start 88.625426 -86.203536)
		(end 88.658192 -86.203536)
		(width 0.0889)
		(layer "In4.Cu")
		(net "SMB_PIROM_CPU1_SCL")
	)
	(segment
		(start 31.049468 -106.476546)
		(end 31.320232 -106.205782)
		(width 0.089408)
		(layer "In4.Cu")
		(net "SMB_PIROM_CPU1_SCL")
	)
	(segment
		(start 71.45528 -79.269336)
		(end 71.485252 -79.269336)
		(width 0.0889)
		(layer "In4.Cu")
		(net "SMB_PIROM_CPU1_SCL")
	)
	(segment
		(start 68.14947 -77.78369)
		(end 69.025008 -77.78369)
		(width 0.0889)
		(layer "In4.Cu")
		(net "SMB_PIROM_CPU1_SCL")
	)
	(segment
		(start 89.498678 -86.69909)
		(end 89.533476 -86.69909)
		(width 0.0889)
		(layer "In4.Cu")
		(net "SMB_PIROM_CPU1_SCL")
	)
	(segment
		(start 77.46873 -80.75549)
		(end 77.504798 -80.75549)
		(width 0.0889)
		(layer "In4.Cu")
		(net "SMB_PIROM_CPU1_SCL")
	)
	(segment
		(start 90.356944 -86.79434)
		(end 90.357198 -86.794086)
		(width 0.0889)
		(layer "In4.Cu")
		(net "SMB_PIROM_CPU1_SCL")
	)
	(segment
		(start 84.336636 -83.72729)
		(end 84.369402 -83.72729)
		(width 0.0889)
		(layer "In4.Cu")
		(net "SMB_PIROM_CPU1_SCL")
	)
	(segment
		(start 65.570608 -78.474824)
		(end 68.14947 -77.78369)
		(width 0.0889)
		(layer "In4.Cu")
		(net "SMB_PIROM_CPU1_SCL")
	)
	(segment
		(start 38.342824 -101.76637)
		(end 41.461182 -101.76637)
		(width 0.089408)
		(layer "In4.Cu")
		(net "SMB_PIROM_CPU1_SCL")
	)
	(segment
		(start 49.0982 -94.48165)
		(end 49.0982 -93.074236)
		(width 0.089408)
		(layer "In4.Cu")
		(net "SMB_PIROM_CPU1_SCL")
	)
	(segment
		(start 31.320232 -104.756712)
		(end 32.097472 -103.979472)
		(width 0.089408)
		(layer "In4.Cu")
		(net "SMB_PIROM_CPU1_SCL")
	)
	(segment
		(start 69.572886 -78.278736)
		(end 69.771006 -78.278736)
		(width 0.0889)
		(layer "In4.Cu")
		(net "SMB_PIROM_CPU1_SCL")
	)
	(segment
		(start 41.461182 -101.76637)
		(end 43.283378 -99.944174)
		(width 0.089408)
		(layer "In4.Cu")
		(net "SMB_PIROM_CPU1_SCL")
	)
	(segment
		(start 62.481714 -79.24292)
		(end 65.479422 -78.439772)
		(width 0.089408)
		(layer "In4.Cu")
		(net "SMB_PIROM_CPU1_SCL")
	)
	(segment
		(start 83.474306 -82.241136)
		(end 83.502246 -82.241136)
		(width 0.0889)
		(layer "In4.Cu")
		(net "SMB_PIROM_CPU1_SCL")
	)
	(segment
		(start 73.17232 -79.269336)
		(end 73.205086 -79.269336)
		(width 0.0889)
		(layer "In4.Cu")
		(net "SMB_PIROM_CPU1_SCL")
	)
	(segment
		(start 70.60057 -78.77429)
		(end 70.633336 -78.77429)
		(width 0.0889)
		(layer "In4.Cu")
		(net "SMB_PIROM_CPU1_SCL")
	)
	(segment
		(start 82.619596 -81.74609)
		(end 82.652362 -81.74609)
		(width 0.0889)
		(layer "In4.Cu")
		(net "SMB_PIROM_CPU1_SCL")
	)
	(segment
		(start 89.533476 -86.69909)
		(end 90.356944 -86.79434)
		(width 0.0889)
		(layer "In4.Cu")
		(net "SMB_PIROM_CPU1_SCL")
	)
	(segment
		(start 31.320232 -106.205782)
		(end 31.320232 -104.756712)
		(width 0.089408)
		(layer "In4.Cu")
		(net "SMB_PIROM_CPU1_SCL")
	)
	(segment
		(start 32.097472 -103.979472)
		(end 36.129722 -103.979472)
		(width 0.089408)
		(layer "In4.Cu")
		(net "SMB_PIROM_CPU1_SCL")
	)
	(segment
		(start 45.274992 -98.304858)
		(end 49.0982 -94.48165)
		(width 0.089408)
		(layer "In4.Cu")
		(net "SMB_PIROM_CPU1_SCL")
	)
	(segment
		(start 85.191346 -84.222336)
		(end 85.224112 -84.222336)
		(width 0.0889)
		(layer "In4.Cu")
		(net "SMB_PIROM_CPU1_SCL")
	)
	(segment
		(start 72.307196 -78.77429)
		(end 72.350376 -78.77429)
		(width 0.0889)
		(layer "In4.Cu")
		(net "SMB_PIROM_CPU1_SCL")
	)
	(segment
		(start 77.991716 -81.050384)
		(end 77.995018 -81.056226)
		(width 0.0889)
		(layer "In4.Cu")
		(net "SMB_PIROM_CPU1_SCL")
	)
	(segment
		(start 81.757266 -81.250536)
		(end 81.790032 -81.250536)
		(width 0.0889)
		(layer "In4.Cu")
		(net "SMB_PIROM_CPU1_SCL")
	)
	(segment
		(start 86.053676 -84.71789)
		(end 86.086442 -84.71789)
		(width 0.0889)
		(layer "In4.Cu")
		(net "SMB_PIROM_CPU1_SCL")
	)
	(segment
		(start 49.0982 -93.074236)
		(end 50.496216 -91.67622)
		(width 0.089408)
		(layer "In4.Cu")
		(net "SMB_PIROM_CPU1_SCL")
	)
	(segment
		(start 43.928792 -99.944174)
		(end 45.274992 -98.597974)
		(width 0.089408)
		(layer "In4.Cu")
		(net "SMB_PIROM_CPU1_SCL")
	)
	(segment
		(start 86.908386 -85.212936)
		(end 86.941152 -85.212936)
		(width 0.0889)
		(layer "In4.Cu")
		(net "SMB_PIROM_CPU1_SCL")
	)
	(segment
		(start 80.892142 -80.75549)
		(end 80.935322 -80.75549)
		(width 0.0889)
		(layer "In4.Cu")
		(net "SMB_PIROM_CPU1_SCL")
	)
	(segment
		(start 50.496216 -91.67622)
		(end 50.496216 -91.228418)
		(width 0.089408)
		(layer "In4.Cu")
		(net "SMB_PIROM_CPU1_SCL")
	)
	(segment
		(start 65.479422 -78.439772)
		(end 65.500758 -78.434184)
		(width 0.0889)
		(layer "In4.Cu")
		(net "SMB_PIROM_CPU1_SCL")
	)
	(segment
		(start 74.03465 -79.76489)
		(end 74.067416 -79.76489)
		(width 0.0889)
		(layer "In4.Cu")
		(net "SMB_PIROM_CPU1_SCL")
	)
	(segment
		(start 43.283378 -99.944174)
		(end 43.928792 -99.944174)
		(width 0.089408)
		(layer "In4.Cu")
		(net "SMB_PIROM_CPU1_SCL")
	)
	(segment
		(start 76.6064 -80.259936)
		(end 76.639166 -80.259936)
		(width 0.0889)
		(layer "In4.Cu")
		(net "SMB_PIROM_CPU1_SCL")
	)
	(segment
		(start 87.770716 -85.70849)
		(end 87.803482 -85.70849)
		(width 0.0889)
		(layer "In4.Cu")
		(net "SMB_PIROM_CPU1_SCL")
	)
	(segment
		(start 50.496216 -91.228418)
		(end 62.481714 -79.24292)
		(width 0.089408)
		(layer "In4.Cu")
		(net "SMB_PIROM_CPU1_SCL")
	)
	(arc
		(start 71.123556 -79.069438)
		(mid 71.263635 -79.212174)
		(end 71.45528 -79.269336)
		(width 0.0889)
		(layer "In4.Cu")
		(net "SMB_PIROM_CPU1_SCL")
	)
	(arc
		(start 84.369402 -83.72729)
		(mid 84.652619 -83.811571)
		(end 84.859622 -84.022438)
		(width 0.0889)
		(layer "In4.Cu")
		(net "SMB_PIROM_CPU1_SCL")
	)
	(arc
		(start 74.067416 -79.76489)
		(mid 74.350633 -79.849171)
		(end 74.557636 -80.060038)
		(width 0.0889)
		(layer "In4.Cu")
		(net "SMB_PIROM_CPU1_SCL")
	)
	(arc
		(start 84.001102 -83.127342)
		(mid 83.998519 -83.522589)
		(end 84.336636 -83.72729)
		(width 0.0889)
		(layer "In4.Cu")
		(net "SMB_PIROM_CPU1_SCL")
	)
	(arc
		(start 87.435182 -85.508338)
		(mid 87.576865 -85.652142)
		(end 87.770716 -85.70849)
		(width 0.0889)
		(layer "In4.Cu")
		(net "SMB_PIROM_CPU1_SCL")
	)
	(arc
		(start 77.995018 -81.056226)
		(mid 78.341608 -81.250796)
		(end 78.684882 -81.050638)
		(width 0.0889)
		(layer "In4.Cu")
		(net "SMB_PIROM_CPU1_SCL")
	)
	(arc
		(start 79.708502 -81.050638)
		(mid 80.055212 -81.250822)
		(end 80.401922 -81.050638)
		(width 0.0889)
		(layer "In4.Cu")
		(net "SMB_PIROM_CPU1_SCL")
	)
	(arc
		(start 88.658192 -86.203536)
		(mid 88.943616 -86.287003)
		(end 89.152222 -86.498938)
		(width 0.0889)
		(layer "In4.Cu")
		(net "SMB_PIROM_CPU1_SCL")
	)
	(arc
		(start 81.425542 -81.050638)
		(mid 81.565621 -81.193374)
		(end 81.757266 -81.250536)
		(width 0.0889)
		(layer "In4.Cu")
		(net "SMB_PIROM_CPU1_SCL")
	)
	(arc
		(start 73.205086 -79.269336)
		(mid 73.49051 -79.352803)
		(end 73.699116 -79.564738)
		(width 0.0889)
		(layer "In4.Cu")
		(net "SMB_PIROM_CPU1_SCL")
	)
	(arc
		(start 71.816976 -79.069438)
		(mid 72.02398 -78.858574)
		(end 72.307196 -78.77429)
		(width 0.0889)
		(layer "In4.Cu")
		(net "SMB_PIROM_CPU1_SCL")
	)
	(arc
		(start 70.633336 -78.77429)
		(mid 70.916553 -78.858571)
		(end 71.123556 -79.069438)
		(width 0.0889)
		(layer "In4.Cu")
		(net "SMB_PIROM_CPU1_SCL")
	)
	(arc
		(start 89.155524 -86.50478)
		(mid 89.30149 -86.647179)
		(end 89.498678 -86.69909)
		(width 0.0889)
		(layer "In4.Cu")
		(net "SMB_PIROM_CPU1_SCL")
	)
	(arc
		(start 73.699116 -79.564738)
		(mid 73.840799 -79.708542)
		(end 74.03465 -79.76489)
		(width 0.0889)
		(layer "In4.Cu")
		(net "SMB_PIROM_CPU1_SCL")
	)
	(arc
		(start 77.504798 -80.75549)
		(mid 77.786098 -80.840456)
		(end 77.991716 -81.050384)
		(width 0.0889)
		(layer "In4.Cu")
		(net "SMB_PIROM_CPU1_SCL")
	)
	(arc
		(start 85.224112 -84.222336)
		(mid 85.509536 -84.305803)
		(end 85.718142 -84.517738)
		(width 0.0889)
		(layer "In4.Cu")
		(net "SMB_PIROM_CPU1_SCL")
	)
	(arc
		(start 88.293702 -86.003638)
		(mid 88.433781 -86.146374)
		(end 88.625426 -86.203536)
		(width 0.0889)
		(layer "In4.Cu")
		(net "SMB_PIROM_CPU1_SCL")
	)
	(arc
		(start 69.025008 -77.78369)
		(mid 69.222385 -77.901417)
		(end 69.364352 -78.08214)
		(width 0.0889)
		(layer "In4.Cu")
		(net "SMB_PIROM_CPU1_SCL")
	)
	(arc
		(start 80.935322 -80.75549)
		(mid 81.218539 -80.839771)
		(end 81.425542 -81.050638)
		(width 0.0889)
		(layer "In4.Cu")
		(net "SMB_PIROM_CPU1_SCL")
	)
	(arc
		(start 83.142582 -82.041238)
		(mid 83.282661 -82.183974)
		(end 83.474306 -82.241136)
		(width 0.0889)
		(layer "In4.Cu")
		(net "SMB_PIROM_CPU1_SCL")
	)
	(arc
		(start 69.771006 -78.278736)
		(mid 70.05643 -78.362203)
		(end 70.265036 -78.574138)
		(width 0.0889)
		(layer "In4.Cu")
		(net "SMB_PIROM_CPU1_SCL")
	)
	(arc
		(start 82.652362 -81.74609)
		(mid 82.935579 -81.830371)
		(end 83.142582 -82.041238)
		(width 0.0889)
		(layer "In4.Cu")
		(net "SMB_PIROM_CPU1_SCL")
	)
	(arc
		(start 86.941152 -85.212936)
		(mid 87.226576 -85.296403)
		(end 87.435182 -85.508338)
		(width 0.0889)
		(layer "In4.Cu")
		(net "SMB_PIROM_CPU1_SCL")
	)
	(arc
		(start 87.803482 -85.70849)
		(mid 88.086699 -85.792771)
		(end 88.293702 -86.003638)
		(width 0.0889)
		(layer "In4.Cu")
		(net "SMB_PIROM_CPU1_SCL")
	)
	(arc
		(start 81.790032 -81.250536)
		(mid 82.075456 -81.334003)
		(end 82.284062 -81.545938)
		(width 0.0889)
		(layer "In4.Cu")
		(net "SMB_PIROM_CPU1_SCL")
	)
	(arc
		(start 85.718142 -84.517738)
		(mid 85.859825 -84.661542)
		(end 86.053676 -84.71789)
		(width 0.0889)
		(layer "In4.Cu")
		(net "SMB_PIROM_CPU1_SCL")
	)
	(arc
		(start 76.639166 -80.259936)
		(mid 76.92459 -80.343403)
		(end 77.133196 -80.555338)
		(width 0.0889)
		(layer "In4.Cu")
		(net "SMB_PIROM_CPU1_SCL")
	)
	(arc
		(start 71.485252 -79.269336)
		(mid 71.676894 -79.21217)
		(end 71.816976 -79.069438)
		(width 0.0889)
		(layer "In4.Cu")
		(net "SMB_PIROM_CPU1_SCL")
	)
	(arc
		(start 72.840596 -79.069438)
		(mid 72.980675 -79.212174)
		(end 73.17232 -79.269336)
		(width 0.0889)
		(layer "In4.Cu")
		(net "SMB_PIROM_CPU1_SCL")
	)
	(arc
		(start 82.284062 -81.545938)
		(mid 82.425745 -81.689742)
		(end 82.619596 -81.74609)
		(width 0.0889)
		(layer "In4.Cu")
		(net "SMB_PIROM_CPU1_SCL")
	)
	(arc
		(start 80.401922 -81.050638)
		(mid 80.608926 -80.839774)
		(end 80.892142 -80.75549)
		(width 0.0889)
		(layer "In4.Cu")
		(net "SMB_PIROM_CPU1_SCL")
	)
	(arc
		(start 78.684882 -81.050638)
		(mid 79.196692 -80.755099)
		(end 79.708502 -81.050638)
		(width 0.0889)
		(layer "In4.Cu")
		(net "SMB_PIROM_CPU1_SCL")
	)
	(arc
		(start 77.133196 -80.555338)
		(mid 77.274879 -80.699142)
		(end 77.46873 -80.75549)
		(width 0.0889)
		(layer "In4.Cu")
		(net "SMB_PIROM_CPU1_SCL")
	)
	(arc
		(start 86.576662 -85.013038)
		(mid 86.716741 -85.155774)
		(end 86.908386 -85.212936)
		(width 0.0889)
		(layer "In4.Cu")
		(net "SMB_PIROM_CPU1_SCL")
	)
	(arc
		(start 83.502246 -82.241136)
		(mid 84.004255 -82.54206)
		(end 84.001102 -83.127342)
		(width 0.0889)
		(layer "In4.Cu")
		(net "SMB_PIROM_CPU1_SCL")
	)
	(arc
		(start 69.364352 -78.08214)
		(mid 69.452101 -78.197967)
		(end 69.572886 -78.278736)
		(width 0.0889)
		(layer "In4.Cu")
		(net "SMB_PIROM_CPU1_SCL")
	)
	(arc
		(start 72.350376 -78.77429)
		(mid 72.633593 -78.858571)
		(end 72.840596 -79.069438)
		(width 0.0889)
		(layer "In4.Cu")
		(net "SMB_PIROM_CPU1_SCL")
	)
	(arc
		(start 74.557636 -80.060038)
		(mid 74.904346 -80.260222)
		(end 75.251056 -80.060038)
		(width 0.0889)
		(layer "In4.Cu")
		(net "SMB_PIROM_CPU1_SCL")
	)
	(arc
		(start 75.251056 -80.060038)
		(mid 75.762866 -79.764499)
		(end 76.274676 -80.060038)
		(width 0.0889)
		(layer "In4.Cu")
		(net "SMB_PIROM_CPU1_SCL")
	)
	(arc
		(start 84.859622 -84.022438)
		(mid 84.999701 -84.165174)
		(end 85.191346 -84.222336)
		(width 0.0889)
		(layer "In4.Cu")
		(net "SMB_PIROM_CPU1_SCL")
	)
	(arc
		(start 76.274676 -80.060038)
		(mid 76.414755 -80.202774)
		(end 76.6064 -80.259936)
		(width 0.0889)
		(layer "In4.Cu")
		(net "SMB_PIROM_CPU1_SCL")
	)
	(arc
		(start 70.265036 -78.574138)
		(mid 70.406719 -78.717942)
		(end 70.60057 -78.77429)
		(width 0.0889)
		(layer "In4.Cu")
		(net "SMB_PIROM_CPU1_SCL")
	)
	(arc
		(start 86.086442 -84.71789)
		(mid 86.369659 -84.802171)
		(end 86.576662 -85.013038)
		(width 0.0889)
		(layer "In4.Cu")
		(net "SMB_PIROM_CPU1_SCL")
	)
	(segment
		(start 28.542488 -125.278642)
		(end 28.070048 -125.751082)
		(width 0.089408)
		(layer "In11.Cu")
		(net "SMB_PIROM_CPU1_SCL")
	)
	(segment
		(start 28.070048 -125.751082)
		(end 28.070048 -126.600712)
		(width 0.089408)
		(layer "In11.Cu")
		(net "SMB_PIROM_CPU1_SCL")
	)
	(segment
		(start 28.070048 -126.600712)
		(end 28.438094 -126.968758)
		(width 0.089408)
		(layer "In11.Cu")
		(net "SMB_PIROM_CPU1_SCL")
	)
	(segment
		(start 31.027624 -106.49839)
		(end 30.56382 -106.49839)
		(width 0.089408)
		(layer "In11.Cu")
		(net "SMB_PIROM_CPU1_SCL")
	)
	(segment
		(start 31.049468 -106.476546)
		(end 31.027624 -106.49839)
		(width 0.089408)
		(layer "In11.Cu")
		(net "SMB_PIROM_CPU1_SCL")
	)
	(segment
		(start 30.56382 -106.49839)
		(end 28.542488 -108.519722)
		(width 0.089408)
		(layer "In11.Cu")
		(net "SMB_PIROM_CPU1_SCL")
	)
	(segment
		(start 28.542488 -108.519722)
		(end 28.542488 -125.278642)
		(width 0.089408)
		(layer "In11.Cu")
		(net "SMB_PIROM_CPU1_SCL")
	)
	(segment
		(start 187.20689 -139.176252)
		(end 187.20689 -141.593316)
		(width 0.10795)
		(layer "F.Cu")
		(net "SMB_PIROM_CPU0_SDA")
	)
	(segment
		(start 191.003174 -134.561326)
		(end 191.003174 -135.984742)
		(width 0.10795)
		(layer "F.Cu")
		(net "SMB_PIROM_CPU0_SDA")
	)
	(segment
		(start 191.003428 -136.17956)
		(end 189.260988 -137.922)
		(width 0.10795)
		(layer "F.Cu")
		(net "SMB_PIROM_CPU0_SDA")
	)
	(segment
		(start 188.377322 -133.055868)
		(end 189.497716 -133.055868)
		(width 0.10795)
		(layer "F.Cu")
		(net "SMB_PIROM_CPU0_SDA")
	)
	(segment
		(start 185.8264 -129.9464)
		(end 185.623708 -130.149092)
		(width 0.10795)
		(layer "F.Cu")
		(net "SMB_PIROM_CPU0_SDA")
	)
	(segment
		(start 256.78765 -88.28024)
		(end 256.21615 -88.28024)
		(width 0.10795)
		(layer "F.Cu")
		(net "SMB_PIROM_CPU0_SDA")
	)
	(segment
		(start 185.623708 -130.149092)
		(end 185.623708 -130.302254)
		(width 0.10795)
		(layer "F.Cu")
		(net "SMB_PIROM_CPU0_SDA")
	)
	(segment
		(start 181.58206 -143.28775)
		(end 179.870862 -144.998948)
		(width 0.10795)
		(layer "F.Cu")
		(net "SMB_PIROM_CPU0_SDA")
	)
	(segment
		(start 189.260988 -137.922)
		(end 188.461142 -137.922)
		(width 0.10795)
		(layer "F.Cu")
		(net "SMB_PIROM_CPU0_SDA")
	)
	(segment
		(start 189.497716 -133.055868)
		(end 191.003174 -134.561326)
		(width 0.10795)
		(layer "F.Cu")
		(net "SMB_PIROM_CPU0_SDA")
	)
	(segment
		(start 187.20689 -141.593316)
		(end 185.512456 -143.28775)
		(width 0.10795)
		(layer "F.Cu")
		(net "SMB_PIROM_CPU0_SDA")
	)
	(segment
		(start 191.003428 -135.984996)
		(end 191.003428 -136.17956)
		(width 0.10795)
		(layer "F.Cu")
		(net "SMB_PIROM_CPU0_SDA")
	)
	(segment
		(start 188.461142 -137.922)
		(end 187.20689 -139.176252)
		(width 0.10795)
		(layer "F.Cu")
		(net "SMB_PIROM_CPU0_SDA")
	)
	(segment
		(start 185.512456 -143.28775)
		(end 181.58206 -143.28775)
		(width 0.10795)
		(layer "F.Cu")
		(net "SMB_PIROM_CPU0_SDA")
	)
	(segment
		(start 191.003174 -135.984742)
		(end 191.003428 -135.984996)
		(width 0.10795)
		(layer "F.Cu")
		(net "SMB_PIROM_CPU0_SDA")
	)
	(segment
		(start 185.623708 -130.302254)
		(end 188.377322 -133.055868)
		(width 0.10795)
		(layer "F.Cu")
		(net "SMB_PIROM_CPU0_SDA")
	)
	(via
		(at 185.8264 -129.9464)
		(size 0.508)
		(drill 0.254)
		(layers "F.Cu" "B.Cu")
		(net "SMB_PIROM_CPU0_SDA")
	)
	(via
		(at 194.6148 -105.91927)
		(size 0.508)
		(drill 0.254)
		(layers "F.Cu" "B.Cu")
		(net "SMB_PIROM_CPU0_SDA")
	)
	(via
		(at 185.760106 -124.287026)
		(size 0.508)
		(drill 0.254)
		(layers "F.Cu" "B.Cu")
		(net "SMB_PIROM_CPU0_SDA")
	)
	(via
		(at 256.21615 -88.28024)
		(size 0.508)
		(drill 0.254)
		(layers "F.Cu" "B.Cu")
		(net "SMB_PIROM_CPU0_SDA")
	)
	(segment
		(start 186.4741 -126.11735)
		(end 186.4741 -127.7493)
		(width 0.089408)
		(layer "In2.Cu")
		(net "SMB_PIROM_CPU0_SDA")
	)
	(segment
		(start 185.560208 -129.680208)
		(end 185.8264 -129.9464)
		(width 0.089408)
		(layer "In2.Cu")
		(net "SMB_PIROM_CPU0_SDA")
	)
	(segment
		(start 186.4741 -127.7493)
		(end 185.560208 -128.663192)
		(width 0.089408)
		(layer "In2.Cu")
		(net "SMB_PIROM_CPU0_SDA")
	)
	(segment
		(start 185.349642 -124.992892)
		(end 186.4741 -126.11735)
		(width 0.089408)
		(layer "In2.Cu")
		(net "SMB_PIROM_CPU0_SDA")
	)
	(segment
		(start 185.560208 -128.663192)
		(end 185.560208 -129.680208)
		(width 0.089408)
		(layer "In2.Cu")
		(net "SMB_PIROM_CPU0_SDA")
	)
	(segment
		(start 185.349642 -124.445268)
		(end 185.349642 -124.992892)
		(width 0.089408)
		(layer "In2.Cu")
		(net "SMB_PIROM_CPU0_SDA")
	)
	(segment
		(start 185.760106 -124.287026)
		(end 185.507884 -124.287026)
		(width 0.089408)
		(layer "In2.Cu")
		(net "SMB_PIROM_CPU0_SDA")
	)
	(segment
		(start 185.507884 -124.287026)
		(end 185.349642 -124.445268)
		(width 0.089408)
		(layer "In2.Cu")
		(net "SMB_PIROM_CPU0_SDA")
	)
	(segment
		(start 194.6148 -105.91927)
		(end 194.97167 -105.5624)
		(width 0.089408)
		(layer "In4.Cu")
		(net "SMB_PIROM_CPU0_SDA")
	)
	(segment
		(start 240.748312 -78.96479)
		(end 240.778284 -78.96479)
		(width 0.0889)
		(layer "In4.Cu")
		(net "SMB_PIROM_CPU0_SDA")
	)
	(segment
		(start 237.311438 -78.96479)
		(end 237.346998 -78.96479)
		(width 0.0889)
		(layer "In4.Cu")
		(net "SMB_PIROM_CPU0_SDA")
	)
	(segment
		(start 248.468134 -80.450436)
		(end 248.5009 -80.450436)
		(width 0.0889)
		(layer "In4.Cu")
		(net "SMB_PIROM_CPU0_SDA")
	)
	(segment
		(start 255.33604 -87.384636)
		(end 255.368806 -87.384636)
		(width 0.0889)
		(layer "In4.Cu")
		(net "SMB_PIROM_CPU0_SDA")
	)
	(segment
		(start 252.264164 -84.60232)
		(end 252.270514 -84.612988)
		(width 0.0889)
		(layer "In4.Cu")
		(net "SMB_PIROM_CPU0_SDA")
	)
	(segment
		(start 252.270514 -84.612988)
		(end 252.27534 -84.621624)
		(width 0.0889)
		(layer "In4.Cu")
		(net "SMB_PIROM_CPU0_SDA")
	)
	(segment
		(start 250.185174 -81.441036)
		(end 250.21794 -81.441036)
		(width 0.0889)
		(layer "In4.Cu")
		(net "SMB_PIROM_CPU0_SDA")
	)
	(segment
		(start 246.751094 -79.459836)
		(end 246.78386 -79.459836)
		(width 0.0889)
		(layer "In4.Cu")
		(net "SMB_PIROM_CPU0_SDA")
	)
	(segment
		(start 234.573572 -78.469236)
		(end 234.764834 -78.469236)
		(width 0.0889)
		(layer "In4.Cu")
		(net "SMB_PIROM_CPU0_SDA")
	)
	(segment
		(start 245.899178 -78.96479)
		(end 245.92915 -78.96479)
		(width 0.0889)
		(layer "In4.Cu")
		(net "SMB_PIROM_CPU0_SDA")
	)
	(segment
		(start 195.164964 -105.5624)
		(end 195.919344 -106.31678)
		(width 0.089408)
		(layer "In4.Cu")
		(net "SMB_PIROM_CPU0_SDA")
	)
	(segment
		(start 252.270514 -83.622388)
		(end 252.27534 -83.631024)
		(width 0.0889)
		(layer "In4.Cu")
		(net "SMB_PIROM_CPU0_SDA")
	)
	(segment
		(start 252.264164 -83.61172)
		(end 252.270514 -83.622388)
		(width 0.0889)
		(layer "In4.Cu")
		(net "SMB_PIROM_CPU0_SDA")
	)
	(segment
		(start 251.047504 -81.93659)
		(end 251.08027 -81.93659)
		(width 0.0889)
		(layer "In4.Cu")
		(net "SMB_PIROM_CPU0_SDA")
	)
	(segment
		(start 239.883188 -79.459836)
		(end 239.926368 -79.459836)
		(width 0.0889)
		(layer "In4.Cu")
		(net "SMB_PIROM_CPU0_SDA")
	)
	(segment
		(start 254.48133 -86.88959)
		(end 254.514096 -86.88959)
		(width 0.0889)
		(layer "In4.Cu")
		(net "SMB_PIROM_CPU0_SDA")
	)
	(segment
		(start 242.823492 -79.1591)
		(end 242.826794 -79.164942)
		(width 0.0889)
		(layer "In4.Cu")
		(net "SMB_PIROM_CPU0_SDA")
	)
	(segment
		(start 194.97167 -105.5624)
		(end 195.164964 -105.5624)
		(width 0.089408)
		(layer "In4.Cu")
		(net "SMB_PIROM_CPU0_SDA")
	)
	(segment
		(start 202.164696 -106.649012)
		(end 203.680568 -106.649012)
		(width 0.089408)
		(layer "In4.Cu")
		(net "SMB_PIROM_CPU0_SDA")
	)
	(segment
		(start 241.600228 -79.459836)
		(end 241.643408 -79.459836)
		(width 0.0889)
		(layer "In4.Cu")
		(net "SMB_PIROM_CPU0_SDA")
	)
	(segment
		(start 244.179344 -79.95539)
		(end 244.214904 -79.95539)
		(width 0.0889)
		(layer "In4.Cu")
		(net "SMB_PIROM_CPU0_SDA")
	)
	(segment
		(start 249.330464 -80.94599)
		(end 249.36323 -80.94599)
		(width 0.0889)
		(layer "In4.Cu")
		(net "SMB_PIROM_CPU0_SDA")
	)
	(segment
		(start 238.176562 -78.469236)
		(end 238.198914 -78.469236)
		(width 0.0889)
		(layer "In4.Cu")
		(net "SMB_PIROM_CPU0_SDA")
	)
	(segment
		(start 252.264164 -85.59292)
		(end 252.270514 -85.603588)
		(width 0.0889)
		(layer "In4.Cu")
		(net "SMB_PIROM_CPU0_SDA")
	)
	(segment
		(start 211.657438 -96.93656)
		(end 216.15654 -92.437458)
		(width 0.089408)
		(layer "In4.Cu")
		(net "SMB_PIROM_CPU0_SDA")
	)
	(segment
		(start 216.15654 -90.964766)
		(end 227.466652 -79.654654)
		(width 0.089408)
		(layer "In4.Cu")
		(net "SMB_PIROM_CPU0_SDA")
	)
	(segment
		(start 227.466652 -79.654654)
		(end 233.995468 -79.654654)
		(width 0.0889)
		(layer "In4.Cu")
		(net "SMB_PIROM_CPU0_SDA")
	)
	(segment
		(start 242.465352 -78.96479)
		(end 242.480338 -78.96479)
		(width 0.0889)
		(layer "In4.Cu")
		(net "SMB_PIROM_CPU0_SDA")
	)
	(segment
		(start 235.594398 -78.96479)
		(end 235.629958 -78.96479)
		(width 0.0889)
		(layer "In4.Cu")
		(net "SMB_PIROM_CPU0_SDA")
	)
	(segment
		(start 216.15654 -92.437458)
		(end 216.15654 -90.964766)
		(width 0.089408)
		(layer "In4.Cu")
		(net "SMB_PIROM_CPU0_SDA")
	)
	(segment
		(start 211.657438 -98.672142)
		(end 211.657438 -96.93656)
		(width 0.089408)
		(layer "In4.Cu")
		(net "SMB_PIROM_CPU0_SDA")
	)
	(segment
		(start 236.459522 -78.469236)
		(end 236.481874 -78.469236)
		(width 0.0889)
		(layer "In4.Cu")
		(net "SMB_PIROM_CPU0_SDA")
	)
	(segment
		(start 245.044468 -79.459836)
		(end 245.077234 -79.459836)
		(width 0.0889)
		(layer "In4.Cu")
		(net "SMB_PIROM_CPU0_SDA")
	)
	(segment
		(start 203.680568 -106.649012)
		(end 211.657438 -98.672142)
		(width 0.089408)
		(layer "In4.Cu")
		(net "SMB_PIROM_CPU0_SDA")
	)
	(segment
		(start 252.764544 -85.89899)
		(end 252.79731 -85.89899)
		(width 0.0889)
		(layer "In4.Cu")
		(net "SMB_PIROM_CPU0_SDA")
	)
	(segment
		(start 247.613424 -79.95539)
		(end 247.64619 -79.95539)
		(width 0.0889)
		(layer "In4.Cu")
		(net "SMB_PIROM_CPU0_SDA")
	)
	(segment
		(start 234.314746 -79.335376)
		(end 234.314746 -78.86954)
		(width 0.0889)
		(layer "In4.Cu")
		(net "SMB_PIROM_CPU0_SDA")
	)
	(segment
		(start 233.995468 -79.654654)
		(end 234.314746 -79.335376)
		(width 0.0889)
		(layer "In4.Cu")
		(net "SMB_PIROM_CPU0_SDA")
	)
	(segment
		(start 253.619254 -86.394036)
		(end 253.640844 -86.394036)
		(width 0.0889)
		(layer "In4.Cu")
		(net "SMB_PIROM_CPU0_SDA")
	)
	(segment
		(start 197.914768 -108.855764)
		(end 199.957944 -108.855764)
		(width 0.089408)
		(layer "In4.Cu")
		(net "SMB_PIROM_CPU0_SDA")
	)
	(segment
		(start 243.313712 -79.459836)
		(end 243.34978 -79.459836)
		(width 0.0889)
		(layer "In4.Cu")
		(net "SMB_PIROM_CPU0_SDA")
	)
	(segment
		(start 195.919344 -106.31678)
		(end 195.919344 -106.86034)
		(width 0.089408)
		(layer "In4.Cu")
		(net "SMB_PIROM_CPU0_SDA")
	)
	(segment
		(start 239.028478 -78.96479)
		(end 239.061244 -78.96479)
		(width 0.0889)
		(layer "In4.Cu")
		(net "SMB_PIROM_CPU0_SDA")
	)
	(segment
		(start 199.957944 -108.855764)
		(end 202.164696 -106.649012)
		(width 0.089408)
		(layer "In4.Cu")
		(net "SMB_PIROM_CPU0_SDA")
	)
	(segment
		(start 251.91085 -82.43189)
		(end 251.93498 -82.43189)
		(width 0.0889)
		(layer "In4.Cu")
		(net "SMB_PIROM_CPU0_SDA")
	)
	(segment
		(start 253.983998 -86.588346)
		(end 253.9873 -86.594188)
		(width 0.0889)
		(layer "In4.Cu")
		(net "SMB_PIROM_CPU0_SDA")
	)
	(segment
		(start 195.919344 -106.86034)
		(end 197.914768 -108.855764)
		(width 0.089408)
		(layer "In4.Cu")
		(net "SMB_PIROM_CPU0_SDA")
	)
	(arc
		(start 245.077234 -79.459836)
		(mid 245.360451 -79.375555)
		(end 245.567454 -79.164688)
		(width 0.0889)
		(layer "In4.Cu")
		(net "SMB_PIROM_CPU0_SDA")
	)
	(arc
		(start 254.84582 -87.089488)
		(mid 255.052824 -87.300352)
		(end 255.33604 -87.384636)
		(width 0.0889)
		(layer "In4.Cu")
		(net "SMB_PIROM_CPU0_SDA")
	)
	(arc
		(start 252.270514 -85.013038)
		(mid 252.191292 -85.302156)
		(end 252.264164 -85.59292)
		(width 0.0889)
		(layer "In4.Cu")
		(net "SMB_PIROM_CPU0_SDA")
	)
	(arc
		(start 252.270514 -84.022438)
		(mid 252.191292 -84.311556)
		(end 252.264164 -84.60232)
		(width 0.0889)
		(layer "In4.Cu")
		(net "SMB_PIROM_CPU0_SDA")
	)
	(arc
		(start 235.629958 -78.96479)
		(mid 235.915382 -78.881323)
		(end 236.123988 -78.669388)
		(width 0.0889)
		(layer "In4.Cu")
		(net "SMB_PIROM_CPU0_SDA")
	)
	(arc
		(start 250.553474 -81.641188)
		(mid 250.762082 -81.85312)
		(end 251.047504 -81.93659)
		(width 0.0889)
		(layer "In4.Cu")
		(net "SMB_PIROM_CPU0_SDA")
	)
	(arc
		(start 251.411994 -82.136488)
		(mid 251.622707 -82.349567)
		(end 251.91085 -82.43189)
		(width 0.0889)
		(layer "In4.Cu")
		(net "SMB_PIROM_CPU0_SDA")
	)
	(arc
		(start 246.78386 -79.459836)
		(mid 246.97771 -79.516186)
		(end 247.119394 -79.659988)
		(width 0.0889)
		(layer "In4.Cu")
		(net "SMB_PIROM_CPU0_SDA")
	)
	(arc
		(start 255.368806 -87.384636)
		(mid 255.562656 -87.440986)
		(end 255.70434 -87.584788)
		(width 0.0889)
		(layer "In4.Cu")
		(net "SMB_PIROM_CPU0_SDA")
	)
	(arc
		(start 249.36323 -80.94599)
		(mid 249.554872 -81.003156)
		(end 249.694954 -81.145888)
		(width 0.0889)
		(layer "In4.Cu")
		(net "SMB_PIROM_CPU0_SDA")
	)
	(arc
		(start 253.9873 -86.594188)
		(mid 254.195908 -86.80612)
		(end 254.48133 -86.88959)
		(width 0.0889)
		(layer "In4.Cu")
		(net "SMB_PIROM_CPU0_SDA")
	)
	(arc
		(start 242.133628 -79.164688)
		(mid 242.273707 -79.021952)
		(end 242.465352 -78.96479)
		(width 0.0889)
		(layer "In4.Cu")
		(net "SMB_PIROM_CPU0_SDA")
	)
	(arc
		(start 248.5009 -80.450436)
		(mid 248.69475 -80.506786)
		(end 248.836434 -80.650588)
		(width 0.0889)
		(layer "In4.Cu")
		(net "SMB_PIROM_CPU0_SDA")
	)
	(arc
		(start 252.79731 -85.89899)
		(mid 252.988952 -85.956156)
		(end 253.129034 -86.098888)
		(width 0.0889)
		(layer "In4.Cu")
		(net "SMB_PIROM_CPU0_SDA")
	)
	(arc
		(start 255.70434 -87.584788)
		(mid 255.940835 -87.9468)
		(end 256.21615 -88.28024)
		(width 0.0889)
		(layer "In4.Cu")
		(net "SMB_PIROM_CPU0_SDA")
	)
	(arc
		(start 241.110008 -79.164688)
		(mid 241.317012 -79.375552)
		(end 241.600228 -79.459836)
		(width 0.0889)
		(layer "In4.Cu")
		(net "SMB_PIROM_CPU0_SDA")
	)
	(arc
		(start 253.129034 -86.098888)
		(mid 253.336038 -86.309752)
		(end 253.619254 -86.394036)
		(width 0.0889)
		(layer "In4.Cu")
		(net "SMB_PIROM_CPU0_SDA")
	)
	(arc
		(start 236.123988 -78.669388)
		(mid 236.265671 -78.525584)
		(end 236.459522 -78.469236)
		(width 0.0889)
		(layer "In4.Cu")
		(net "SMB_PIROM_CPU0_SDA")
	)
	(arc
		(start 246.260874 -79.164688)
		(mid 246.467878 -79.375552)
		(end 246.751094 -79.459836)
		(width 0.0889)
		(layer "In4.Cu")
		(net "SMB_PIROM_CPU0_SDA")
	)
	(arc
		(start 242.826794 -79.164942)
		(mid 243.032415 -79.374865)
		(end 243.313712 -79.459836)
		(width 0.0889)
		(layer "In4.Cu")
		(net "SMB_PIROM_CPU0_SDA")
	)
	(arc
		(start 237.841028 -78.669388)
		(mid 237.982711 -78.525584)
		(end 238.176562 -78.469236)
		(width 0.0889)
		(layer "In4.Cu")
		(net "SMB_PIROM_CPU0_SDA")
	)
	(arc
		(start 236.817408 -78.669388)
		(mid 237.026016 -78.88132)
		(end 237.311438 -78.96479)
		(width 0.0889)
		(layer "In4.Cu")
		(net "SMB_PIROM_CPU0_SDA")
	)
	(arc
		(start 250.21794 -81.441036)
		(mid 250.41179 -81.497386)
		(end 250.553474 -81.641188)
		(width 0.0889)
		(layer "In4.Cu")
		(net "SMB_PIROM_CPU0_SDA")
	)
	(arc
		(start 251.93498 -82.43189)
		(mid 252.12883 -82.48824)
		(end 252.270514 -82.632042)
		(width 0.0889)
		(layer "In4.Cu")
		(net "SMB_PIROM_CPU0_SDA")
	)
	(arc
		(start 237.346998 -78.96479)
		(mid 237.632422 -78.881323)
		(end 237.841028 -78.669388)
		(width 0.0889)
		(layer "In4.Cu")
		(net "SMB_PIROM_CPU0_SDA")
	)
	(arc
		(start 239.392968 -79.164688)
		(mid 239.599972 -79.375552)
		(end 239.883188 -79.459836)
		(width 0.0889)
		(layer "In4.Cu")
		(net "SMB_PIROM_CPU0_SDA")
	)
	(arc
		(start 245.567454 -79.164688)
		(mid 245.707533 -79.021952)
		(end 245.899178 -78.96479)
		(width 0.0889)
		(layer "In4.Cu")
		(net "SMB_PIROM_CPU0_SDA")
	)
	(arc
		(start 240.416588 -79.164688)
		(mid 240.556667 -79.021952)
		(end 240.748312 -78.96479)
		(width 0.0889)
		(layer "In4.Cu")
		(net "SMB_PIROM_CPU0_SDA")
	)
	(arc
		(start 244.214904 -79.95539)
		(mid 244.500328 -79.871923)
		(end 244.708934 -79.659988)
		(width 0.0889)
		(layer "In4.Cu")
		(net "SMB_PIROM_CPU0_SDA")
	)
	(arc
		(start 243.34978 -79.459836)
		(mid 243.54363 -79.516186)
		(end 243.685314 -79.659988)
		(width 0.0889)
		(layer "In4.Cu")
		(net "SMB_PIROM_CPU0_SDA")
	)
	(arc
		(start 247.64619 -79.95539)
		(mid 247.837832 -80.012556)
		(end 247.977914 -80.155288)
		(width 0.0889)
		(layer "In4.Cu")
		(net "SMB_PIROM_CPU0_SDA")
	)
	(arc
		(start 242.480338 -78.96479)
		(mid 242.677499 -79.016749)
		(end 242.823492 -79.1591)
		(width 0.0889)
		(layer "In4.Cu")
		(net "SMB_PIROM_CPU0_SDA")
	)
	(arc
		(start 247.119394 -79.659988)
		(mid 247.328002 -79.87192)
		(end 247.613424 -79.95539)
		(width 0.0889)
		(layer "In4.Cu")
		(net "SMB_PIROM_CPU0_SDA")
	)
	(arc
		(start 243.685314 -79.659988)
		(mid 243.893922 -79.87192)
		(end 244.179344 -79.95539)
		(width 0.0889)
		(layer "In4.Cu")
		(net "SMB_PIROM_CPU0_SDA")
	)
	(arc
		(start 234.764834 -78.469236)
		(mid 234.958684 -78.525586)
		(end 235.100368 -78.669388)
		(width 0.0889)
		(layer "In4.Cu")
		(net "SMB_PIROM_CPU0_SDA")
	)
	(arc
		(start 252.27534 -84.621624)
		(mid 252.324095 -84.817976)
		(end 252.270514 -85.013038)
		(width 0.0889)
		(layer "In4.Cu")
		(net "SMB_PIROM_CPU0_SDA")
	)
	(arc
		(start 253.640844 -86.394036)
		(mid 253.838005 -86.445995)
		(end 253.983998 -86.588346)
		(width 0.0889)
		(layer "In4.Cu")
		(net "SMB_PIROM_CPU0_SDA")
	)
	(arc
		(start 252.270514 -85.603588)
		(mid 252.479122 -85.81552)
		(end 252.764544 -85.89899)
		(width 0.0889)
		(layer "In4.Cu")
		(net "SMB_PIROM_CPU0_SDA")
	)
	(arc
		(start 234.314746 -78.86954)
		(mid 234.385094 -78.631204)
		(end 234.573572 -78.469236)
		(width 0.0889)
		(layer "In4.Cu")
		(net "SMB_PIROM_CPU0_SDA")
	)
	(arc
		(start 247.977914 -80.155288)
		(mid 248.184918 -80.366152)
		(end 248.468134 -80.450436)
		(width 0.0889)
		(layer "In4.Cu")
		(net "SMB_PIROM_CPU0_SDA")
	)
	(arc
		(start 252.270514 -83.031838)
		(mid 252.191292 -83.320956)
		(end 252.264164 -83.61172)
		(width 0.0889)
		(layer "In4.Cu")
		(net "SMB_PIROM_CPU0_SDA")
	)
	(arc
		(start 254.514096 -86.88959)
		(mid 254.705738 -86.946756)
		(end 254.84582 -87.089488)
		(width 0.0889)
		(layer "In4.Cu")
		(net "SMB_PIROM_CPU0_SDA")
	)
	(arc
		(start 245.92915 -78.96479)
		(mid 246.120792 -79.021956)
		(end 246.260874 -79.164688)
		(width 0.0889)
		(layer "In4.Cu")
		(net "SMB_PIROM_CPU0_SDA")
	)
	(arc
		(start 235.100368 -78.669388)
		(mid 235.308976 -78.88132)
		(end 235.594398 -78.96479)
		(width 0.0889)
		(layer "In4.Cu")
		(net "SMB_PIROM_CPU0_SDA")
	)
	(arc
		(start 249.694954 -81.145888)
		(mid 249.901958 -81.356752)
		(end 250.185174 -81.441036)
		(width 0.0889)
		(layer "In4.Cu")
		(net "SMB_PIROM_CPU0_SDA")
	)
	(arc
		(start 238.534448 -78.669388)
		(mid 238.743056 -78.88132)
		(end 239.028478 -78.96479)
		(width 0.0889)
		(layer "In4.Cu")
		(net "SMB_PIROM_CPU0_SDA")
	)
	(arc
		(start 251.08027 -81.93659)
		(mid 251.271912 -81.993756)
		(end 251.411994 -82.136488)
		(width 0.0889)
		(layer "In4.Cu")
		(net "SMB_PIROM_CPU0_SDA")
	)
	(arc
		(start 239.061244 -78.96479)
		(mid 239.252886 -79.021956)
		(end 239.392968 -79.164688)
		(width 0.0889)
		(layer "In4.Cu")
		(net "SMB_PIROM_CPU0_SDA")
	)
	(arc
		(start 239.926368 -79.459836)
		(mid 240.209585 -79.375555)
		(end 240.416588 -79.164688)
		(width 0.0889)
		(layer "In4.Cu")
		(net "SMB_PIROM_CPU0_SDA")
	)
	(arc
		(start 240.778284 -78.96479)
		(mid 240.969926 -79.021956)
		(end 241.110008 -79.164688)
		(width 0.0889)
		(layer "In4.Cu")
		(net "SMB_PIROM_CPU0_SDA")
	)
	(arc
		(start 248.836434 -80.650588)
		(mid 249.045042 -80.86252)
		(end 249.330464 -80.94599)
		(width 0.0889)
		(layer "In4.Cu")
		(net "SMB_PIROM_CPU0_SDA")
	)
	(arc
		(start 244.708934 -79.659988)
		(mid 244.850617 -79.516184)
		(end 245.044468 -79.459836)
		(width 0.0889)
		(layer "In4.Cu")
		(net "SMB_PIROM_CPU0_SDA")
	)
	(arc
		(start 241.643408 -79.459836)
		(mid 241.926625 -79.375555)
		(end 242.133628 -79.164688)
		(width 0.0889)
		(layer "In4.Cu")
		(net "SMB_PIROM_CPU0_SDA")
	)
	(arc
		(start 252.270514 -82.632042)
		(mid 252.324013 -82.83194)
		(end 252.270514 -83.031838)
		(width 0.0889)
		(layer "In4.Cu")
		(net "SMB_PIROM_CPU0_SDA")
	)
	(arc
		(start 238.198914 -78.469236)
		(mid 238.392764 -78.525586)
		(end 238.534448 -78.669388)
		(width 0.0889)
		(layer "In4.Cu")
		(net "SMB_PIROM_CPU0_SDA")
	)
	(arc
		(start 252.27534 -83.631024)
		(mid 252.324095 -83.827376)
		(end 252.270514 -84.022438)
		(width 0.0889)
		(layer "In4.Cu")
		(net "SMB_PIROM_CPU0_SDA")
	)
	(arc
		(start 236.481874 -78.469236)
		(mid 236.675724 -78.525586)
		(end 236.817408 -78.669388)
		(width 0.0889)
		(layer "In4.Cu")
		(net "SMB_PIROM_CPU0_SDA")
	)
	(segment
		(start 194.6148 -105.91927)
		(end 194.533774 -106.000296)
		(width 0.089408)
		(layer "In11.Cu")
		(net "SMB_PIROM_CPU0_SDA")
	)
	(segment
		(start 194.959732 -107.493054)
		(end 194.959732 -114.837718)
		(width 0.089408)
		(layer "In11.Cu")
		(net "SMB_PIROM_CPU0_SDA")
	)
	(segment
		(start 194.959732 -114.837718)
		(end 185.760106 -124.037344)
		(width 0.089408)
		(layer "In11.Cu")
		(net "SMB_PIROM_CPU0_SDA")
	)
	(segment
		(start 194.533774 -107.067096)
		(end 194.959732 -107.493054)
		(width 0.089408)
		(layer "In11.Cu")
		(net "SMB_PIROM_CPU0_SDA")
	)
	(segment
		(start 194.533774 -106.000296)
		(end 194.533774 -107.067096)
		(width 0.089408)
		(layer "In11.Cu")
		(net "SMB_PIROM_CPU0_SDA")
	)
	(segment
		(start 185.760106 -124.037344)
		(end 185.760106 -124.287026)
		(width 0.089408)
		(layer "In11.Cu")
		(net "SMB_PIROM_CPU0_SDA")
	)
	(segment
		(start 190.768224 -136.082278)
		(end 190.768224 -134.658862)
		(width 0.10795)
		(layer "F.Cu")
		(net "SMB_PIROM_CPU0_SCL")
	)
	(segment
		(start 185.38825 -130.399282)
		(end 185.38825 -130.14325)
		(width 0.10795)
		(layer "F.Cu")
		(net "SMB_PIROM_CPU0_SCL")
	)
	(segment
		(start 179.87137 -144.159224)
		(end 180.977794 -143.0528)
		(width 0.10795)
		(layer "F.Cu")
		(net "SMB_PIROM_CPU0_SCL")
	)
	(segment
		(start 186.97194 -141.49578)
		(end 186.97194 -139.078716)
		(width 0.10795)
		(layer "F.Cu")
		(net "SMB_PIROM_CPU0_SCL")
	)
	(segment
		(start 189.40018 -133.290818)
		(end 188.279786 -133.290818)
		(width 0.10795)
		(layer "F.Cu")
		(net "SMB_PIROM_CPU0_SCL")
	)
	(segment
		(start 190.768224 -134.658862)
		(end 189.40018 -133.290818)
		(width 0.10795)
		(layer "F.Cu")
		(net "SMB_PIROM_CPU0_SCL")
	)
	(segment
		(start 186.97194 -139.078716)
		(end 188.363606 -137.68705)
		(width 0.10795)
		(layer "F.Cu")
		(net "SMB_PIROM_CPU0_SCL")
	)
	(segment
		(start 188.363606 -137.68705)
		(end 189.163452 -137.68705)
		(width 0.10795)
		(layer "F.Cu")
		(net "SMB_PIROM_CPU0_SCL")
	)
	(segment
		(start 189.163452 -137.68705)
		(end 190.768224 -136.082278)
		(width 0.10795)
		(layer "F.Cu")
		(net "SMB_PIROM_CPU0_SCL")
	)
	(segment
		(start 185.38825 -130.14325)
		(end 185.166 -129.921)
		(width 0.10795)
		(layer "F.Cu")
		(net "SMB_PIROM_CPU0_SCL")
	)
	(segment
		(start 185.41492 -143.0528)
		(end 186.97194 -141.49578)
		(width 0.10795)
		(layer "F.Cu")
		(net "SMB_PIROM_CPU0_SCL")
	)
	(segment
		(start 255.92913 -86.794086)
		(end 255.35763 -86.794086)
		(width 0.10795)
		(layer "F.Cu")
		(net "SMB_PIROM_CPU0_SCL")
	)
	(segment
		(start 180.977794 -143.0528)
		(end 185.41492 -143.0528)
		(width 0.10795)
		(layer "F.Cu")
		(net "SMB_PIROM_CPU0_SCL")
	)
	(segment
		(start 188.279786 -133.290818)
		(end 185.38825 -130.399282)
		(width 0.10795)
		(layer "F.Cu")
		(net "SMB_PIROM_CPU0_SCL")
	)
	(via
		(at 185.166 -129.921)
		(size 0.508)
		(drill 0.254)
		(layers "F.Cu" "B.Cu")
		(net "SMB_PIROM_CPU0_SCL")
	)
	(via
		(at 194.664076 -105.256838)
		(size 0.508)
		(drill 0.254)
		(layers "F.Cu" "B.Cu")
		(net "SMB_PIROM_CPU0_SCL")
	)
	(via
		(at 255.35763 -86.794086)
		(size 0.508)
		(drill 0.254)
		(layers "F.Cu" "B.Cu")
		(net "SMB_PIROM_CPU0_SCL")
	)
	(via
		(at 185.006742 -124.042424)
		(size 0.508)
		(drill 0.254)
		(layers "F.Cu" "B.Cu")
		(net "SMB_PIROM_CPU0_SCL")
	)
	(segment
		(start 185.3692 -128.583944)
		(end 185.3692 -129.7178)
		(width 0.089408)
		(layer "In2.Cu")
		(net "SMB_PIROM_CPU0_SCL")
	)
	(segment
		(start 185.006742 -124.328936)
		(end 185.158634 -124.480828)
		(width 0.089408)
		(layer "In2.Cu")
		(net "SMB_PIROM_CPU0_SCL")
	)
	(segment
		(start 185.3692 -129.7178)
		(end 185.166 -129.921)
		(width 0.089408)
		(layer "In2.Cu")
		(net "SMB_PIROM_CPU0_SCL")
	)
	(segment
		(start 185.006742 -124.042424)
		(end 185.006742 -124.328936)
		(width 0.089408)
		(layer "In2.Cu")
		(net "SMB_PIROM_CPU0_SCL")
	)
	(segment
		(start 186.283092 -127.670052)
		(end 185.3692 -128.583944)
		(width 0.089408)
		(layer "In2.Cu")
		(net "SMB_PIROM_CPU0_SCL")
	)
	(segment
		(start 186.283092 -126.196598)
		(end 186.283092 -127.670052)
		(width 0.089408)
		(layer "In2.Cu")
		(net "SMB_PIROM_CPU0_SCL")
	)
	(segment
		(start 185.158634 -125.07214)
		(end 186.283092 -126.196598)
		(width 0.089408)
		(layer "In2.Cu")
		(net "SMB_PIROM_CPU0_SCL")
	)
	(segment
		(start 185.158634 -124.480828)
		(end 185.158634 -125.07214)
		(width 0.089408)
		(layer "In2.Cu")
		(net "SMB_PIROM_CPU0_SCL")
	)
	(segment
		(start 227.480622 -79.370428)
		(end 215.965532 -90.885518)
		(width 0.089408)
		(layer "In4.Cu")
		(net "SMB_PIROM_CPU0_SCL")
	)
	(segment
		(start 239.067848 -78.77429)
		(end 239.035082 -78.77429)
		(width 0.0889)
		(layer "In4.Cu")
		(net "SMB_PIROM_CPU0_SCL")
	)
	(segment
		(start 247.652794 -79.76489)
		(end 247.620028 -79.76489)
		(width 0.0889)
		(layer "In4.Cu")
		(net "SMB_PIROM_CPU0_SCL")
	)
	(segment
		(start 245.935754 -78.77429)
		(end 245.892574 -78.77429)
		(width 0.0889)
		(layer "In4.Cu")
		(net "SMB_PIROM_CPU0_SCL")
	)
	(segment
		(start 252.435614 -84.517738)
		(end 252.430788 -84.509102)
		(width 0.0889)
		(layer "In4.Cu")
		(net "SMB_PIROM_CPU0_SCL")
	)
	(segment
		(start 250.224544 -81.250536)
		(end 250.191778 -81.250536)
		(width 0.0889)
		(layer "In4.Cu")
		(net "SMB_PIROM_CPU0_SCL")
	)
	(segment
		(start 241.636804 -79.269336)
		(end 241.606832 -79.269336)
		(width 0.0889)
		(layer "In4.Cu")
		(net "SMB_PIROM_CPU0_SCL")
	)
	(segment
		(start 203.597256 -106.458004)
		(end 202.068176 -106.458004)
		(width 0.089408)
		(layer "In4.Cu")
		(net "SMB_PIROM_CPU0_SCL")
	)
	(segment
		(start 202.068176 -106.458004)
		(end 199.87006 -108.65612)
		(width 0.089408)
		(layer "In4.Cu")
		(net "SMB_PIROM_CPU0_SCL")
	)
	(segment
		(start 249.369834 -80.75549)
		(end 249.337068 -80.75549)
		(width 0.0889)
		(layer "In4.Cu")
		(net "SMB_PIROM_CPU0_SCL")
	)
	(segment
		(start 233.635042 -78.799944)
		(end 233.064558 -79.370428)
		(width 0.089408)
		(layer "In4.Cu")
		(net "SMB_PIROM_CPU0_SCL")
	)
	(segment
		(start 215.965532 -90.885518)
		(end 215.965532 -92.35821)
		(width 0.089408)
		(layer "In4.Cu")
		(net "SMB_PIROM_CPU0_SCL")
	)
	(segment
		(start 239.919764 -79.269336)
		(end 239.889792 -79.269336)
		(width 0.0889)
		(layer "In4.Cu")
		(net "SMB_PIROM_CPU0_SCL")
	)
	(segment
		(start 244.2083 -79.76489)
		(end 244.185948 -79.76489)
		(width 0.0889)
		(layer "In4.Cu")
		(net "SMB_PIROM_CPU0_SCL")
	)
	(segment
		(start 251.086874 -81.74609)
		(end 251.054108 -81.74609)
		(width 0.0889)
		(layer "In4.Cu")
		(net "SMB_PIROM_CPU0_SCL")
	)
	(segment
		(start 196.125084 -106.21518)
		(end 195.166742 -105.256838)
		(width 0.089408)
		(layer "In4.Cu")
		(net "SMB_PIROM_CPU0_SCL")
	)
	(segment
		(start 233.064558 -79.370428)
		(end 227.480622 -79.370428)
		(width 0.089408)
		(layer "In4.Cu")
		(net "SMB_PIROM_CPU0_SCL")
	)
	(segment
		(start 240.784888 -78.77429)
		(end 240.741708 -78.77429)
		(width 0.0889)
		(layer "In4.Cu")
		(net "SMB_PIROM_CPU0_SCL")
	)
	(segment
		(start 251.936758 -82.241136)
		(end 251.908818 -82.241136)
		(width 0.0889)
		(layer "In4.Cu")
		(net "SMB_PIROM_CPU0_SCL")
	)
	(segment
		(start 237.340394 -78.77429)
		(end 237.318042 -78.77429)
		(width 0.0889)
		(layer "In4.Cu")
		(net "SMB_PIROM_CPU0_SCL")
	)
	(segment
		(start 252.441964 -83.537806)
		(end 252.435614 -83.527138)
		(width 0.0889)
		(layer "In4.Cu")
		(net "SMB_PIROM_CPU0_SCL")
	)
	(segment
		(start 235.623354 -78.77429)
		(end 235.601002 -78.77429)
		(width 0.0889)
		(layer "In4.Cu")
		(net "SMB_PIROM_CPU0_SCL")
	)
	(segment
		(start 211.46643 -96.857312)
		(end 211.46643 -98.58883)
		(width 0.089408)
		(layer "In4.Cu")
		(net "SMB_PIROM_CPU0_SCL")
	)
	(segment
		(start 252.441964 -84.528406)
		(end 252.435614 -84.517738)
		(width 0.0889)
		(layer "In4.Cu")
		(net "SMB_PIROM_CPU0_SCL")
	)
	(segment
		(start 254.5207 -86.69909)
		(end 254.49911 -86.69909)
		(width 0.0889)
		(layer "In4.Cu")
		(net "SMB_PIROM_CPU0_SCL")
	)
	(segment
		(start 195.166742 -105.256838)
		(end 194.664076 -105.256838)
		(width 0.089408)
		(layer "In4.Cu")
		(net "SMB_PIROM_CPU0_SCL")
	)
	(segment
		(start 252.435614 -85.508338)
		(end 252.430788 -85.499702)
		(width 0.0889)
		(layer "In4.Cu")
		(net "SMB_PIROM_CPU0_SCL")
	)
	(segment
		(start 243.356384 -79.269336)
		(end 243.338604 -79.269336)
		(width 0.0889)
		(layer "In4.Cu")
		(net "SMB_PIROM_CPU0_SCL")
	)
	(segment
		(start 196.125084 -106.717846)
		(end 196.125084 -106.21518)
		(width 0.089408)
		(layer "In4.Cu")
		(net "SMB_PIROM_CPU0_SCL")
	)
	(segment
		(start 215.965532 -92.35821)
		(end 211.46643 -96.857312)
		(width 0.089408)
		(layer "In4.Cu")
		(net "SMB_PIROM_CPU0_SCL")
	)
	(segment
		(start 246.790464 -79.269336)
		(end 246.757698 -79.269336)
		(width 0.0889)
		(layer "In4.Cu")
		(net "SMB_PIROM_CPU0_SCL")
	)
	(segment
		(start 234.771438 -78.278736)
		(end 234.535472 -78.278736)
		(width 0.0889)
		(layer "In4.Cu")
		(net "SMB_PIROM_CPU0_SCL")
	)
	(segment
		(start 242.50523 -78.77429)
		(end 242.458748 -78.77429)
		(width 0.0889)
		(layer "In4.Cu")
		(net "SMB_PIROM_CPU0_SCL")
	)
	(segment
		(start 248.507504 -80.259936)
		(end 248.474738 -80.259936)
		(width 0.0889)
		(layer "In4.Cu")
		(net "SMB_PIROM_CPU0_SCL")
	)
	(segment
		(start 245.07063 -79.269336)
		(end 245.037864 -79.269336)
		(width 0.0889)
		(layer "In4.Cu")
		(net "SMB_PIROM_CPU0_SCL")
	)
	(segment
		(start 233.97337 -78.799944)
		(end 233.635042 -78.799944)
		(width 0.089408)
		(layer "In4.Cu")
		(net "SMB_PIROM_CPU0_SCL")
	)
	(segment
		(start 254.155956 -86.50478)
		(end 254.152654 -86.498938)
		(width 0.0889)
		(layer "In4.Cu")
		(net "SMB_PIROM_CPU0_SCL")
	)
	(segment
		(start 242.99545 -79.075026)
		(end 242.992148 -79.069184)
		(width 0.0889)
		(layer "In4.Cu")
		(net "SMB_PIROM_CPU0_SCL")
	)
	(segment
		(start 199.87006 -108.65612)
		(end 198.063358 -108.65612)
		(width 0.089408)
		(layer "In4.Cu")
		(net "SMB_PIROM_CPU0_SCL")
	)
	(segment
		(start 211.46643 -98.58883)
		(end 203.597256 -106.458004)
		(width 0.089408)
		(layer "In4.Cu")
		(net "SMB_PIROM_CPU0_SCL")
	)
	(segment
		(start 234.195874 -78.57744)
		(end 233.97337 -78.799944)
		(width 0.089408)
		(layer "In4.Cu")
		(net "SMB_PIROM_CPU0_SCL")
	)
	(segment
		(start 238.205518 -78.278736)
		(end 238.169958 -78.278736)
		(width 0.0889)
		(layer "In4.Cu")
		(net "SMB_PIROM_CPU0_SCL")
	)
	(segment
		(start 252.803914 -85.70849)
		(end 252.771148 -85.70849)
		(width 0.0889)
		(layer "In4.Cu")
		(net "SMB_PIROM_CPU0_SCL")
	)
	(segment
		(start 253.658624 -86.203536)
		(end 253.625858 -86.203536)
		(width 0.0889)
		(layer "In4.Cu")
		(net "SMB_PIROM_CPU0_SCL")
	)
	(segment
		(start 198.063358 -108.65612)
		(end 196.125084 -106.717846)
		(width 0.089408)
		(layer "In4.Cu")
		(net "SMB_PIROM_CPU0_SCL")
	)
	(segment
		(start 236.488478 -78.278736)
		(end 236.452918 -78.278736)
		(width 0.0889)
		(layer "In4.Cu")
		(net "SMB_PIROM_CPU0_SCL")
	)
	(arc
		(start 238.169958 -78.278736)
		(mid 237.884534 -78.362203)
		(end 237.675928 -78.574138)
		(width 0.0889)
		(layer "In4.Cu")
		(net "SMB_PIROM_CPU0_SCL")
	)
	(arc
		(start 252.435614 -84.117688)
		(mid 252.514836 -83.82857)
		(end 252.441964 -83.537806)
		(width 0.0889)
		(layer "In4.Cu")
		(net "SMB_PIROM_CPU0_SCL")
	)
	(arc
		(start 245.037864 -79.269336)
		(mid 244.75244 -79.352803)
		(end 244.543834 -79.564738)
		(width 0.0889)
		(layer "In4.Cu")
		(net "SMB_PIROM_CPU0_SCL")
	)
	(arc
		(start 249.860054 -81.050638)
		(mid 249.65305 -80.839774)
		(end 249.369834 -80.75549)
		(width 0.0889)
		(layer "In4.Cu")
		(net "SMB_PIROM_CPU0_SCL")
	)
	(arc
		(start 243.850414 -79.564738)
		(mid 243.641806 -79.352806)
		(end 243.356384 -79.269336)
		(width 0.0889)
		(layer "In4.Cu")
		(net "SMB_PIROM_CPU0_SCL")
	)
	(arc
		(start 252.430788 -84.509102)
		(mid 252.382033 -84.31275)
		(end 252.435614 -84.117688)
		(width 0.0889)
		(layer "In4.Cu")
		(net "SMB_PIROM_CPU0_SCL")
	)
	(arc
		(start 240.741708 -78.77429)
		(mid 240.458491 -78.858571)
		(end 240.251488 -79.069438)
		(width 0.0889)
		(layer "In4.Cu")
		(net "SMB_PIROM_CPU0_SCL")
	)
	(arc
		(start 248.143014 -80.060038)
		(mid 247.93601 -79.849174)
		(end 247.652794 -79.76489)
		(width 0.0889)
		(layer "In4.Cu")
		(net "SMB_PIROM_CPU0_SCL")
	)
	(arc
		(start 234.535472 -78.278736)
		(mid 234.337905 -78.396524)
		(end 234.195874 -78.57744)
		(width 0.0889)
		(layer "In4.Cu")
		(net "SMB_PIROM_CPU0_SCL")
	)
	(arc
		(start 235.265468 -78.574138)
		(mid 235.05686 -78.362206)
		(end 234.771438 -78.278736)
		(width 0.0889)
		(layer "In4.Cu")
		(net "SMB_PIROM_CPU0_SCL")
	)
	(arc
		(start 251.577094 -82.041238)
		(mid 251.37009 -81.830374)
		(end 251.086874 -81.74609)
		(width 0.0889)
		(layer "In4.Cu")
		(net "SMB_PIROM_CPU0_SCL")
	)
	(arc
		(start 237.318042 -78.77429)
		(mid 237.124192 -78.71794)
		(end 236.982508 -78.574138)
		(width 0.0889)
		(layer "In4.Cu")
		(net "SMB_PIROM_CPU0_SCL")
	)
	(arc
		(start 236.982508 -78.574138)
		(mid 236.7739 -78.362206)
		(end 236.488478 -78.278736)
		(width 0.0889)
		(layer "In4.Cu")
		(net "SMB_PIROM_CPU0_SCL")
	)
	(arc
		(start 251.054108 -81.74609)
		(mid 250.860258 -81.68974)
		(end 250.718574 -81.545938)
		(width 0.0889)
		(layer "In4.Cu")
		(net "SMB_PIROM_CPU0_SCL")
	)
	(arc
		(start 245.892574 -78.77429)
		(mid 245.609357 -78.858571)
		(end 245.402354 -79.069438)
		(width 0.0889)
		(layer "In4.Cu")
		(net "SMB_PIROM_CPU0_SCL")
	)
	(arc
		(start 252.435614 -83.127342)
		(mid 252.514745 -82.83194)
		(end 252.435614 -82.536538)
		(width 0.0889)
		(layer "In4.Cu")
		(net "SMB_PIROM_CPU0_SCL")
	)
	(arc
		(start 254.49911 -86.69909)
		(mid 254.301949 -86.647131)
		(end 254.155956 -86.50478)
		(width 0.0889)
		(layer "In4.Cu")
		(net "SMB_PIROM_CPU0_SCL")
	)
	(arc
		(start 235.958888 -78.574138)
		(mid 235.817205 -78.717942)
		(end 235.623354 -78.77429)
		(width 0.0889)
		(layer "In4.Cu")
		(net "SMB_PIROM_CPU0_SCL")
	)
	(arc
		(start 247.620028 -79.76489)
		(mid 247.426178 -79.70854)
		(end 247.284494 -79.564738)
		(width 0.0889)
		(layer "In4.Cu")
		(net "SMB_PIROM_CPU0_SCL")
	)
	(arc
		(start 239.889792 -79.269336)
		(mid 239.69815 -79.21217)
		(end 239.558068 -79.069438)
		(width 0.0889)
		(layer "In4.Cu")
		(net "SMB_PIROM_CPU0_SCL")
	)
	(arc
		(start 238.699548 -78.574138)
		(mid 238.49094 -78.362206)
		(end 238.205518 -78.278736)
		(width 0.0889)
		(layer "In4.Cu")
		(net "SMB_PIROM_CPU0_SCL")
	)
	(arc
		(start 235.601002 -78.77429)
		(mid 235.407152 -78.71794)
		(end 235.265468 -78.574138)
		(width 0.0889)
		(layer "In4.Cu")
		(net "SMB_PIROM_CPU0_SCL")
	)
	(arc
		(start 251.908818 -82.241136)
		(mid 251.717176 -82.18397)
		(end 251.577094 -82.041238)
		(width 0.0889)
		(layer "In4.Cu")
		(net "SMB_PIROM_CPU0_SCL")
	)
	(arc
		(start 236.452918 -78.278736)
		(mid 236.167494 -78.362203)
		(end 235.958888 -78.574138)
		(width 0.0889)
		(layer "In4.Cu")
		(net "SMB_PIROM_CPU0_SCL")
	)
	(arc
		(start 246.757698 -79.269336)
		(mid 246.566056 -79.21217)
		(end 246.425974 -79.069438)
		(width 0.0889)
		(layer "In4.Cu")
		(net "SMB_PIROM_CPU0_SCL")
	)
	(arc
		(start 246.425974 -79.069438)
		(mid 246.21897 -78.858574)
		(end 245.935754 -78.77429)
		(width 0.0889)
		(layer "In4.Cu")
		(net "SMB_PIROM_CPU0_SCL")
	)
	(arc
		(start 255.35763 -86.794086)
		(mid 255.284423 -87.067422)
		(end 255.01092 -86.994238)
		(width 0.0889)
		(layer "In4.Cu")
		(net "SMB_PIROM_CPU0_SCL")
	)
	(arc
		(start 241.968528 -79.069438)
		(mid 241.828449 -79.212174)
		(end 241.636804 -79.269336)
		(width 0.0889)
		(layer "In4.Cu")
		(net "SMB_PIROM_CPU0_SCL")
	)
	(arc
		(start 253.294134 -86.003638)
		(mid 253.08713 -85.792774)
		(end 252.803914 -85.70849)
		(width 0.0889)
		(layer "In4.Cu")
		(net "SMB_PIROM_CPU0_SCL")
	)
	(arc
		(start 252.435614 -82.536538)
		(mid 252.224901 -82.323459)
		(end 251.936758 -82.241136)
		(width 0.0889)
		(layer "In4.Cu")
		(net "SMB_PIROM_CPU0_SCL")
	)
	(arc
		(start 244.185948 -79.76489)
		(mid 243.992098 -79.70854)
		(end 243.850414 -79.564738)
		(width 0.0889)
		(layer "In4.Cu")
		(net "SMB_PIROM_CPU0_SCL")
	)
	(arc
		(start 248.474738 -80.259936)
		(mid 248.283096 -80.20277)
		(end 248.143014 -80.060038)
		(width 0.0889)
		(layer "In4.Cu")
		(net "SMB_PIROM_CPU0_SCL")
	)
	(arc
		(start 241.606832 -79.269336)
		(mid 241.41519 -79.21217)
		(end 241.275108 -79.069438)
		(width 0.0889)
		(layer "In4.Cu")
		(net "SMB_PIROM_CPU0_SCL")
	)
	(arc
		(start 239.558068 -79.069438)
		(mid 239.351064 -78.858574)
		(end 239.067848 -78.77429)
		(width 0.0889)
		(layer "In4.Cu")
		(net "SMB_PIROM_CPU0_SCL")
	)
	(arc
		(start 253.625858 -86.203536)
		(mid 253.434216 -86.14637)
		(end 253.294134 -86.003638)
		(width 0.0889)
		(layer "In4.Cu")
		(net "SMB_PIROM_CPU0_SCL")
	)
	(arc
		(start 241.275108 -79.069438)
		(mid 241.068104 -78.858574)
		(end 240.784888 -78.77429)
		(width 0.0889)
		(layer "In4.Cu")
		(net "SMB_PIROM_CPU0_SCL")
	)
	(arc
		(start 252.430788 -85.499702)
		(mid 252.382033 -85.30335)
		(end 252.435614 -85.108288)
		(width 0.0889)
		(layer "In4.Cu")
		(net "SMB_PIROM_CPU0_SCL")
	)
	(arc
		(start 237.675928 -78.574138)
		(mid 237.534245 -78.717942)
		(end 237.340394 -78.77429)
		(width 0.0889)
		(layer "In4.Cu")
		(net "SMB_PIROM_CPU0_SCL")
	)
	(arc
		(start 250.191778 -81.250536)
		(mid 250.000136 -81.19337)
		(end 249.860054 -81.050638)
		(width 0.0889)
		(layer "In4.Cu")
		(net "SMB_PIROM_CPU0_SCL")
	)
	(arc
		(start 249.001534 -80.555338)
		(mid 248.792926 -80.343406)
		(end 248.507504 -80.259936)
		(width 0.0889)
		(layer "In4.Cu")
		(net "SMB_PIROM_CPU0_SCL")
	)
	(arc
		(start 245.402354 -79.069438)
		(mid 245.262275 -79.212174)
		(end 245.07063 -79.269336)
		(width 0.0889)
		(layer "In4.Cu")
		(net "SMB_PIROM_CPU0_SCL")
	)
	(arc
		(start 247.284494 -79.564738)
		(mid 247.075886 -79.352806)
		(end 246.790464 -79.269336)
		(width 0.0889)
		(layer "In4.Cu")
		(net "SMB_PIROM_CPU0_SCL")
	)
	(arc
		(start 242.992148 -79.069184)
		(mid 242.786527 -78.859261)
		(end 242.50523 -78.77429)
		(width 0.0889)
		(layer "In4.Cu")
		(net "SMB_PIROM_CPU0_SCL")
	)
	(arc
		(start 255.01092 -86.994238)
		(mid 254.803916 -86.783374)
		(end 254.5207 -86.69909)
		(width 0.0889)
		(layer "In4.Cu")
		(net "SMB_PIROM_CPU0_SCL")
	)
	(arc
		(start 244.543834 -79.564738)
		(mid 244.402151 -79.708542)
		(end 244.2083 -79.76489)
		(width 0.0889)
		(layer "In4.Cu")
		(net "SMB_PIROM_CPU0_SCL")
	)
	(arc
		(start 252.435614 -85.108288)
		(mid 252.514836 -84.81917)
		(end 252.441964 -84.528406)
		(width 0.0889)
		(layer "In4.Cu")
		(net "SMB_PIROM_CPU0_SCL")
	)
	(arc
		(start 249.337068 -80.75549)
		(mid 249.143218 -80.69914)
		(end 249.001534 -80.555338)
		(width 0.0889)
		(layer "In4.Cu")
		(net "SMB_PIROM_CPU0_SCL")
	)
	(arc
		(start 239.035082 -78.77429)
		(mid 238.841232 -78.71794)
		(end 238.699548 -78.574138)
		(width 0.0889)
		(layer "In4.Cu")
		(net "SMB_PIROM_CPU0_SCL")
	)
	(arc
		(start 252.435614 -83.527138)
		(mid 252.382115 -83.32724)
		(end 252.435614 -83.127342)
		(width 0.0889)
		(layer "In4.Cu")
		(net "SMB_PIROM_CPU0_SCL")
	)
	(arc
		(start 242.458748 -78.77429)
		(mid 242.175531 -78.858571)
		(end 241.968528 -79.069438)
		(width 0.0889)
		(layer "In4.Cu")
		(net "SMB_PIROM_CPU0_SCL")
	)
	(arc
		(start 252.771148 -85.70849)
		(mid 252.577298 -85.65214)
		(end 252.435614 -85.508338)
		(width 0.0889)
		(layer "In4.Cu")
		(net "SMB_PIROM_CPU0_SCL")
	)
	(arc
		(start 240.251488 -79.069438)
		(mid 240.111409 -79.212174)
		(end 239.919764 -79.269336)
		(width 0.0889)
		(layer "In4.Cu")
		(net "SMB_PIROM_CPU0_SCL")
	)
	(arc
		(start 243.338604 -79.269336)
		(mid 243.141443 -79.217377)
		(end 242.99545 -79.075026)
		(width 0.0889)
		(layer "In4.Cu")
		(net "SMB_PIROM_CPU0_SCL")
	)
	(arc
		(start 250.718574 -81.545938)
		(mid 250.509966 -81.334006)
		(end 250.224544 -81.250536)
		(width 0.0889)
		(layer "In4.Cu")
		(net "SMB_PIROM_CPU0_SCL")
	)
	(arc
		(start 254.152654 -86.498938)
		(mid 253.944046 -86.287006)
		(end 253.658624 -86.203536)
		(width 0.0889)
		(layer "In4.Cu")
		(net "SMB_PIROM_CPU0_SCL")
	)
	(segment
		(start 194.664076 -105.256838)
		(end 194.214496 -105.706418)
		(width 0.089408)
		(layer "In11.Cu")
		(net "SMB_PIROM_CPU0_SCL")
	)
	(segment
		(start 194.214496 -107.260898)
		(end 194.59702 -107.643422)
		(width 0.089408)
		(layer "In11.Cu")
		(net "SMB_PIROM_CPU0_SCL")
	)
	(segment
		(start 194.214496 -105.706418)
		(end 194.214496 -107.260898)
		(width 0.089408)
		(layer "In11.Cu")
		(net "SMB_PIROM_CPU0_SCL")
	)
	(segment
		(start 194.59702 -114.68735)
		(end 185.241946 -124.042424)
		(width 0.089408)
		(layer "In11.Cu")
		(net "SMB_PIROM_CPU0_SCL")
	)
	(segment
		(start 194.59702 -107.643422)
		(end 194.59702 -114.68735)
		(width 0.089408)
		(layer "In11.Cu")
		(net "SMB_PIROM_CPU0_SCL")
	)
	(segment
		(start 185.241946 -124.042424)
		(end 185.006742 -124.042424)
		(width 0.089408)
		(layer "In11.Cu")
		(net "SMB_PIROM_CPU0_SCL")
	)
	(segment
		(start 30.327092 -103.212392)
		(end 30.327092 -103.327708)
		(width 0.10795)
		(layer "F.Cu")
		(net "PU_PIROM_CPU1_ADDR0")
	)
	(segment
		(start 29.8704 -103.7844)
		(end 29.6418 -103.7844)
		(width 0.10795)
		(layer "F.Cu")
		(net "PU_PIROM_CPU1_ADDR0")
	)
	(segment
		(start 91.787218 -87.28964)
		(end 91.215718 -87.28964)
		(width 0.10795)
		(layer "F.Cu")
		(net "PU_PIROM_CPU1_ADDR0")
	)
	(segment
		(start 30.327092 -103.327708)
		(end 29.8704 -103.7844)
		(width 0.10795)
		(layer "F.Cu")
		(net "PU_PIROM_CPU1_ADDR0")
	)
	(via
		(at 30.327092 -103.212392)
		(size 0.508)
		(drill 0.254)
		(layers "F.Cu" "B.Cu")
		(net "PU_PIROM_CPU1_ADDR0")
	)
	(via
		(at 91.215718 -87.28964)
		(size 0.508)
		(drill 0.254)
		(layers "F.Cu" "B.Cu")
		(net "PU_PIROM_CPU1_ADDR0")
	)
	(segment
		(start 74.882756 -78.469236)
		(end 74.925936 -78.469236)
		(width 0.0889)
		(layer "In11.Cu")
		(net "PU_PIROM_CPU1_ADDR0")
	)
	(segment
		(start 40.040052 -98.879152)
		(end 43.937428 -94.981776)
		(width 0.089408)
		(layer "In11.Cu")
		(net "PU_PIROM_CPU1_ADDR0")
	)
	(segment
		(start 37.070284 -101.848412)
		(end 40.039544 -98.879152)
		(width 0.089408)
		(layer "In11.Cu")
		(net "PU_PIROM_CPU1_ADDR0")
	)
	(segment
		(start 43.970448 -94.981522)
		(end 44.196508 -94.981522)
		(width 0.089408)
		(layer "In11.Cu")
		(net "PU_PIROM_CPU1_ADDR0")
	)
	(segment
		(start 82.612992 -81.93659)
		(end 82.645758 -81.93659)
		(width 0.0889)
		(layer "In11.Cu")
		(net "PU_PIROM_CPU1_ADDR0")
	)
	(segment
		(start 90.922602 -87.45855)
		(end 91.215718 -87.28964)
		(width 0.0889)
		(layer "In11.Cu")
		(net "PU_PIROM_CPU1_ADDR0")
	)
	(segment
		(start 90.90152 -87.53729)
		(end 90.922602 -87.45855)
		(width 0.0889)
		(layer "In11.Cu")
		(net "PU_PIROM_CPU1_ADDR0")
	)
	(segment
		(start 78.31328 -79.459836)
		(end 78.349348 -79.459836)
		(width 0.0889)
		(layer "In11.Cu")
		(net "PU_PIROM_CPU1_ADDR0")
	)
	(segment
		(start 73.17613 -78.469236)
		(end 73.208896 -78.469236)
		(width 0.0889)
		(layer "In11.Cu")
		(net "PU_PIROM_CPU1_ADDR0")
	)
	(segment
		(start 43.937428 -94.981776)
		(end 43.970194 -94.981776)
		(width 0.089408)
		(layer "In11.Cu")
		(net "PU_PIROM_CPU1_ADDR0")
	)
	(segment
		(start 85.184742 -83.42249)
		(end 85.224366 -83.42249)
		(width 0.0889)
		(layer "In11.Cu")
		(net "PU_PIROM_CPU1_ADDR0")
	)
	(segment
		(start 86.901782 -84.412836)
		(end 86.934548 -84.412836)
		(width 0.0889)
		(layer "In11.Cu")
		(net "PU_PIROM_CPU1_ADDR0")
	)
	(segment
		(start 67.421252 -80.705452)
		(end 67.421252 -80.704944)
		(width 0.0889)
		(layer "In11.Cu")
		(net "PU_PIROM_CPU1_ADDR0")
	)
	(segment
		(start 48.68926 -93.99143)
		(end 48.68926 -93.532452)
		(width 0.089408)
		(layer "In11.Cu")
		(net "PU_PIROM_CPU1_ADDR0")
	)
	(segment
		(start 86.047072 -83.91779)
		(end 86.079838 -83.91779)
		(width 0.0889)
		(layer "In11.Cu")
		(net "PU_PIROM_CPU1_ADDR0")
	)
	(segment
		(start 48.68926 -93.532452)
		(end 50.04181 -92.179902)
		(width 0.089408)
		(layer "In11.Cu")
		(net "PU_PIROM_CPU1_ADDR0")
	)
	(segment
		(start 88.618822 -85.403436)
		(end 88.640412 -85.403436)
		(width 0.0889)
		(layer "In11.Cu")
		(net "PU_PIROM_CPU1_ADDR0")
	)
	(segment
		(start 68.561204 -80.9244)
		(end 68.843398 -80.9244)
		(width 0.0889)
		(layer "In11.Cu")
		(net "PU_PIROM_CPU1_ADDR0")
	)
	(segment
		(start 40.039544 -98.879152)
		(end 40.040052 -98.879152)
		(width 0.089408)
		(layer "In11.Cu")
		(net "PU_PIROM_CPU1_ADDR0")
	)
	(segment
		(start 76.599796 -78.469236)
		(end 76.632562 -78.469236)
		(width 0.0889)
		(layer "In11.Cu")
		(net "PU_PIROM_CPU1_ADDR0")
	)
	(segment
		(start 68.06819 -80.431386)
		(end 68.561204 -80.9244)
		(width 0.0889)
		(layer "In11.Cu")
		(net "PU_PIROM_CPU1_ADDR0")
	)
	(segment
		(start 44.196762 -94.981268)
		(end 47.699422 -94.981268)
		(width 0.089408)
		(layer "In11.Cu")
		(net "PU_PIROM_CPU1_ADDR0")
	)
	(segment
		(start 80.033622 -80.450436)
		(end 80.066388 -80.450436)
		(width 0.0889)
		(layer "In11.Cu")
		(net "PU_PIROM_CPU1_ADDR0")
	)
	(segment
		(start 30.7213 -103.6066)
		(end 36.323524 -103.6066)
		(width 0.089408)
		(layer "In11.Cu")
		(net "PU_PIROM_CPU1_ADDR0")
	)
	(segment
		(start 89.480898 -85.89899)
		(end 89.513664 -85.89899)
		(width 0.0889)
		(layer "In11.Cu")
		(net "PU_PIROM_CPU1_ADDR0")
	)
	(segment
		(start 68.843398 -80.9244)
		(end 68.84543 -80.922114)
		(width 0.0889)
		(layer "In11.Cu")
		(net "PU_PIROM_CPU1_ADDR0")
	)
	(segment
		(start 90.335608 -86.394036)
		(end 90.368374 -86.394036)
		(width 0.0889)
		(layer "In11.Cu")
		(net "PU_PIROM_CPU1_ADDR0")
	)
	(segment
		(start 74.03084 -77.97419)
		(end 74.060812 -77.97419)
		(width 0.0889)
		(layer "In11.Cu")
		(net "PU_PIROM_CPU1_ADDR0")
	)
	(segment
		(start 77.82306 -79.1591)
		(end 77.826362 -79.164942)
		(width 0.0889)
		(layer "In11.Cu")
		(net "PU_PIROM_CPU1_ADDR0")
	)
	(segment
		(start 70.59676 -79.95539)
		(end 70.629526 -79.95539)
		(width 0.0889)
		(layer "In11.Cu")
		(net "PU_PIROM_CPU1_ADDR0")
	)
	(segment
		(start 30.327092 -103.212392)
		(end 30.7213 -103.6066)
		(width 0.089408)
		(layer "In11.Cu")
		(net "PU_PIROM_CPU1_ADDR0")
	)
	(segment
		(start 43.970194 -94.981776)
		(end 43.970448 -94.981522)
		(width 0.089408)
		(layer "In11.Cu")
		(net "PU_PIROM_CPU1_ADDR0")
	)
	(segment
		(start 72.3138 -78.96479)
		(end 72.346566 -78.96479)
		(width 0.0889)
		(layer "In11.Cu")
		(net "PU_PIROM_CPU1_ADDR0")
	)
	(segment
		(start 83.476338 -82.43189)
		(end 83.500468 -82.43189)
		(width 0.0889)
		(layer "In11.Cu")
		(net "PU_PIROM_CPU1_ADDR0")
	)
	(segment
		(start 50.04181 -92.179902)
		(end 52.756054 -92.179902)
		(width 0.089408)
		(layer "In11.Cu")
		(net "PU_PIROM_CPU1_ADDR0")
	)
	(segment
		(start 71.45909 -79.459836)
		(end 71.491856 -79.459836)
		(width 0.0889)
		(layer "In11.Cu")
		(net "PU_PIROM_CPU1_ADDR0")
	)
	(segment
		(start 67.421252 -80.704944)
		(end 67.69481 -80.431386)
		(width 0.0889)
		(layer "In11.Cu")
		(net "PU_PIROM_CPU1_ADDR0")
	)
	(segment
		(start 79.178912 -79.95539)
		(end 79.211678 -79.95539)
		(width 0.0889)
		(layer "In11.Cu")
		(net "PU_PIROM_CPU1_ADDR0")
	)
	(segment
		(start 81.750662 -81.441036)
		(end 81.783428 -81.441036)
		(width 0.0889)
		(layer "In11.Cu")
		(net "PU_PIROM_CPU1_ADDR0")
	)
	(segment
		(start 75.74788 -77.97419)
		(end 75.777852 -77.97419)
		(width 0.0889)
		(layer "In11.Cu")
		(net "PU_PIROM_CPU1_ADDR0")
	)
	(segment
		(start 77.462126 -78.96479)
		(end 77.479906 -78.96479)
		(width 0.0889)
		(layer "In11.Cu")
		(net "PU_PIROM_CPU1_ADDR0")
	)
	(segment
		(start 37.070284 -102.85984)
		(end 37.070284 -101.848412)
		(width 0.089408)
		(layer "In11.Cu")
		(net "PU_PIROM_CPU1_ADDR0")
	)
	(segment
		(start 36.323524 -103.6066)
		(end 37.070284 -102.85984)
		(width 0.089408)
		(layer "In11.Cu")
		(net "PU_PIROM_CPU1_ADDR0")
	)
	(segment
		(start 87.764112 -84.90839)
		(end 87.796878 -84.90839)
		(width 0.0889)
		(layer "In11.Cu")
		(net "PU_PIROM_CPU1_ADDR0")
	)
	(segment
		(start 68.84543 -80.922114)
		(end 69.017642 -80.90916)
		(width 0.0889)
		(layer "In11.Cu")
		(net "PU_PIROM_CPU1_ADDR0")
	)
	(segment
		(start 67.421252 -80.705706)
		(end 67.421252 -80.705452)
		(width 0.089408)
		(layer "In11.Cu")
		(net "PU_PIROM_CPU1_ADDR0")
	)
	(segment
		(start 44.196508 -94.981522)
		(end 44.196762 -94.981268)
		(width 0.089408)
		(layer "In11.Cu")
		(net "PU_PIROM_CPU1_ADDR0")
	)
	(segment
		(start 84.326222 -82.92719)
		(end 84.358988 -82.92719)
		(width 0.0889)
		(layer "In11.Cu")
		(net "PU_PIROM_CPU1_ADDR0")
	)
	(segment
		(start 80.895952 -80.94599)
		(end 80.928718 -80.94599)
		(width 0.0889)
		(layer "In11.Cu")
		(net "PU_PIROM_CPU1_ADDR0")
	)
	(segment
		(start 91.197938 -86.88959)
		(end 91.230704 -86.88959)
		(width 0.0889)
		(layer "In11.Cu")
		(net "PU_PIROM_CPU1_ADDR0")
	)
	(segment
		(start 64.46901 -83.65744)
		(end 67.421252 -80.705706)
		(width 0.089408)
		(layer "In11.Cu")
		(net "PU_PIROM_CPU1_ADDR0")
	)
	(segment
		(start 47.699422 -94.981268)
		(end 48.68926 -93.99143)
		(width 0.089408)
		(layer "In11.Cu")
		(net "PU_PIROM_CPU1_ADDR0")
	)
	(segment
		(start 61.278516 -83.65744)
		(end 64.46901 -83.65744)
		(width 0.089408)
		(layer "In11.Cu")
		(net "PU_PIROM_CPU1_ADDR0")
	)
	(segment
		(start 88.983566 -85.597746)
		(end 88.986868 -85.603588)
		(width 0.0889)
		(layer "In11.Cu")
		(net "PU_PIROM_CPU1_ADDR0")
	)
	(segment
		(start 67.69481 -80.431386)
		(end 68.06819 -80.431386)
		(width 0.0889)
		(layer "In11.Cu")
		(net "PU_PIROM_CPU1_ADDR0")
	)
	(segment
		(start 52.756054 -92.179902)
		(end 61.278516 -83.65744)
		(width 0.089408)
		(layer "In11.Cu")
		(net "PU_PIROM_CPU1_ADDR0")
	)
	(segment
		(start 69.556376 -80.450436)
		(end 69.774816 -80.450436)
		(width 0.0889)
		(layer "In11.Cu")
		(net "PU_PIROM_CPU1_ADDR0")
	)
	(arc
		(start 82.118962 -81.641188)
		(mid 82.32757 -81.85312)
		(end 82.612992 -81.93659)
		(width 0.0889)
		(layer "In11.Cu")
		(net "PU_PIROM_CPU1_ADDR0")
	)
	(arc
		(start 83.500468 -82.43189)
		(mid 83.694318 -82.48824)
		(end 83.836002 -82.632042)
		(width 0.0889)
		(layer "In11.Cu")
		(net "PU_PIROM_CPU1_ADDR0")
	)
	(arc
		(start 80.066388 -80.450436)
		(mid 80.260238 -80.506786)
		(end 80.401922 -80.650588)
		(width 0.0889)
		(layer "In11.Cu")
		(net "PU_PIROM_CPU1_ADDR0")
	)
	(arc
		(start 91.230704 -86.88959)
		(mid 91.572841 -87.471028)
		(end 90.90152 -87.53729)
		(width 0.0889)
		(layer "In11.Cu")
		(net "PU_PIROM_CPU1_ADDR0")
	)
	(arc
		(start 73.208896 -78.469236)
		(mid 73.492113 -78.384955)
		(end 73.699116 -78.174088)
		(width 0.0889)
		(layer "In11.Cu")
		(net "PU_PIROM_CPU1_ADDR0")
	)
	(arc
		(start 84.358988 -82.92719)
		(mid 84.552838 -82.98354)
		(end 84.694522 -83.127342)
		(width 0.0889)
		(layer "In11.Cu")
		(net "PU_PIROM_CPU1_ADDR0")
	)
	(arc
		(start 89.845388 -86.098888)
		(mid 90.052392 -86.309752)
		(end 90.335608 -86.394036)
		(width 0.0889)
		(layer "In11.Cu")
		(net "PU_PIROM_CPU1_ADDR0")
	)
	(arc
		(start 88.128602 -85.108288)
		(mid 88.335606 -85.319152)
		(end 88.618822 -85.403436)
		(width 0.0889)
		(layer "In11.Cu")
		(net "PU_PIROM_CPU1_ADDR0")
	)
	(arc
		(start 70.629526 -79.95539)
		(mid 70.91495 -79.871923)
		(end 71.123556 -79.659988)
		(width 0.0889)
		(layer "In11.Cu")
		(net "PU_PIROM_CPU1_ADDR0")
	)
	(arc
		(start 78.349348 -79.459836)
		(mid 78.543198 -79.516186)
		(end 78.684882 -79.659988)
		(width 0.0889)
		(layer "In11.Cu")
		(net "PU_PIROM_CPU1_ADDR0")
	)
	(arc
		(start 71.982076 -79.164688)
		(mid 72.122155 -79.021952)
		(end 72.3138 -78.96479)
		(width 0.0889)
		(layer "In11.Cu")
		(net "PU_PIROM_CPU1_ADDR0")
	)
	(arc
		(start 86.934548 -84.412836)
		(mid 87.128398 -84.469186)
		(end 87.270082 -84.612988)
		(width 0.0889)
		(layer "In11.Cu")
		(net "PU_PIROM_CPU1_ADDR0")
	)
	(arc
		(start 88.986868 -85.603588)
		(mid 89.195476 -85.81552)
		(end 89.480898 -85.89899)
		(width 0.0889)
		(layer "In11.Cu")
		(net "PU_PIROM_CPU1_ADDR0")
	)
	(arc
		(start 75.777852 -77.97419)
		(mid 75.969494 -78.031356)
		(end 76.109576 -78.174088)
		(width 0.0889)
		(layer "In11.Cu")
		(net "PU_PIROM_CPU1_ADDR0")
	)
	(arc
		(start 87.270082 -84.612988)
		(mid 87.47869 -84.82492)
		(end 87.764112 -84.90839)
		(width 0.0889)
		(layer "In11.Cu")
		(net "PU_PIROM_CPU1_ADDR0")
	)
	(arc
		(start 76.632562 -78.469236)
		(mid 76.826412 -78.525586)
		(end 76.968096 -78.669388)
		(width 0.0889)
		(layer "In11.Cu")
		(net "PU_PIROM_CPU1_ADDR0")
	)
	(arc
		(start 78.684882 -79.659988)
		(mid 78.89349 -79.87192)
		(end 79.178912 -79.95539)
		(width 0.0889)
		(layer "In11.Cu")
		(net "PU_PIROM_CPU1_ADDR0")
	)
	(arc
		(start 84.694522 -83.127342)
		(mid 84.901526 -83.338206)
		(end 85.184742 -83.42249)
		(width 0.0889)
		(layer "In11.Cu")
		(net "PU_PIROM_CPU1_ADDR0")
	)
	(arc
		(start 77.479906 -78.96479)
		(mid 77.677067 -79.016749)
		(end 77.82306 -79.1591)
		(width 0.0889)
		(layer "In11.Cu")
		(net "PU_PIROM_CPU1_ADDR0")
	)
	(arc
		(start 90.368374 -86.394036)
		(mid 90.562224 -86.450386)
		(end 90.703908 -86.594188)
		(width 0.0889)
		(layer "In11.Cu")
		(net "PU_PIROM_CPU1_ADDR0")
	)
	(arc
		(start 79.543402 -80.155288)
		(mid 79.750406 -80.366152)
		(end 80.033622 -80.450436)
		(width 0.0889)
		(layer "In11.Cu")
		(net "PU_PIROM_CPU1_ADDR0")
	)
	(arc
		(start 77.826362 -79.164942)
		(mid 78.031983 -79.374865)
		(end 78.31328 -79.459836)
		(width 0.0889)
		(layer "In11.Cu")
		(net "PU_PIROM_CPU1_ADDR0")
	)
	(arc
		(start 80.928718 -80.94599)
		(mid 81.12036 -81.003156)
		(end 81.260442 -81.145888)
		(width 0.0889)
		(layer "In11.Cu")
		(net "PU_PIROM_CPU1_ADDR0")
	)
	(arc
		(start 76.109576 -78.174088)
		(mid 76.31658 -78.384952)
		(end 76.599796 -78.469236)
		(width 0.0889)
		(layer "In11.Cu")
		(net "PU_PIROM_CPU1_ADDR0")
	)
	(arc
		(start 73.699116 -78.174088)
		(mid 73.839195 -78.031352)
		(end 74.03084 -77.97419)
		(width 0.0889)
		(layer "In11.Cu")
		(net "PU_PIROM_CPU1_ADDR0")
	)
	(arc
		(start 90.703908 -86.594188)
		(mid 90.912516 -86.80612)
		(end 91.197938 -86.88959)
		(width 0.0889)
		(layer "In11.Cu")
		(net "PU_PIROM_CPU1_ADDR0")
	)
	(arc
		(start 74.925936 -78.469236)
		(mid 75.209153 -78.384955)
		(end 75.416156 -78.174088)
		(width 0.0889)
		(layer "In11.Cu")
		(net "PU_PIROM_CPU1_ADDR0")
	)
	(arc
		(start 86.411562 -84.117688)
		(mid 86.618566 -84.328552)
		(end 86.901782 -84.412836)
		(width 0.0889)
		(layer "In11.Cu")
		(net "PU_PIROM_CPU1_ADDR0")
	)
	(arc
		(start 69.368162 -80.625696)
		(mid 69.449354 -80.524194)
		(end 69.556376 -80.450436)
		(width 0.0889)
		(layer "In11.Cu")
		(net "PU_PIROM_CPU1_ADDR0")
	)
	(arc
		(start 81.260442 -81.145888)
		(mid 81.467446 -81.356752)
		(end 81.750662 -81.441036)
		(width 0.0889)
		(layer "In11.Cu")
		(net "PU_PIROM_CPU1_ADDR0")
	)
	(arc
		(start 72.346566 -78.96479)
		(mid 72.63199 -78.881323)
		(end 72.840596 -78.669388)
		(width 0.0889)
		(layer "In11.Cu")
		(net "PU_PIROM_CPU1_ADDR0")
	)
	(arc
		(start 74.060812 -77.97419)
		(mid 74.252454 -78.031356)
		(end 74.392536 -78.174088)
		(width 0.0889)
		(layer "In11.Cu")
		(net "PU_PIROM_CPU1_ADDR0")
	)
	(arc
		(start 80.401922 -80.650588)
		(mid 80.61053 -80.86252)
		(end 80.895952 -80.94599)
		(width 0.0889)
		(layer "In11.Cu")
		(net "PU_PIROM_CPU1_ADDR0")
	)
	(arc
		(start 71.491856 -79.459836)
		(mid 71.775073 -79.375555)
		(end 71.982076 -79.164688)
		(width 0.0889)
		(layer "In11.Cu")
		(net "PU_PIROM_CPU1_ADDR0")
	)
	(arc
		(start 69.774816 -80.450436)
		(mid 70.058033 -80.366155)
		(end 70.265036 -80.155288)
		(width 0.0889)
		(layer "In11.Cu")
		(net "PU_PIROM_CPU1_ADDR0")
	)
	(arc
		(start 70.265036 -80.155288)
		(mid 70.405115 -80.012552)
		(end 70.59676 -79.95539)
		(width 0.0889)
		(layer "In11.Cu")
		(net "PU_PIROM_CPU1_ADDR0")
	)
	(arc
		(start 83.836002 -82.632042)
		(mid 84.043006 -82.842906)
		(end 84.326222 -82.92719)
		(width 0.0889)
		(layer "In11.Cu")
		(net "PU_PIROM_CPU1_ADDR0")
	)
	(arc
		(start 85.553042 -83.622388)
		(mid 85.76165 -83.83432)
		(end 86.047072 -83.91779)
		(width 0.0889)
		(layer "In11.Cu")
		(net "PU_PIROM_CPU1_ADDR0")
	)
	(arc
		(start 86.079838 -83.91779)
		(mid 86.27148 -83.974956)
		(end 86.411562 -84.117688)
		(width 0.0889)
		(layer "In11.Cu")
		(net "PU_PIROM_CPU1_ADDR0")
	)
	(arc
		(start 85.224366 -83.42249)
		(mid 85.414295 -83.48036)
		(end 85.553042 -83.622388)
		(width 0.0889)
		(layer "In11.Cu")
		(net "PU_PIROM_CPU1_ADDR0")
	)
	(arc
		(start 74.392536 -78.174088)
		(mid 74.59954 -78.384952)
		(end 74.882756 -78.469236)
		(width 0.0889)
		(layer "In11.Cu")
		(net "PU_PIROM_CPU1_ADDR0")
	)
	(arc
		(start 81.783428 -81.441036)
		(mid 81.977278 -81.497386)
		(end 82.118962 -81.641188)
		(width 0.0889)
		(layer "In11.Cu")
		(net "PU_PIROM_CPU1_ADDR0")
	)
	(arc
		(start 88.640412 -85.403436)
		(mid 88.837573 -85.455395)
		(end 88.983566 -85.597746)
		(width 0.0889)
		(layer "In11.Cu")
		(net "PU_PIROM_CPU1_ADDR0")
	)
	(arc
		(start 89.513664 -85.89899)
		(mid 89.705306 -85.956156)
		(end 89.845388 -86.098888)
		(width 0.0889)
		(layer "In11.Cu")
		(net "PU_PIROM_CPU1_ADDR0")
	)
	(arc
		(start 69.017642 -80.90916)
		(mid 69.218807 -80.799472)
		(end 69.368162 -80.625696)
		(width 0.0889)
		(layer "In11.Cu")
		(net "PU_PIROM_CPU1_ADDR0")
	)
	(arc
		(start 72.840596 -78.669388)
		(mid 72.982279 -78.525584)
		(end 73.17613 -78.469236)
		(width 0.0889)
		(layer "In11.Cu")
		(net "PU_PIROM_CPU1_ADDR0")
	)
	(arc
		(start 71.123556 -79.659988)
		(mid 71.265239 -79.516184)
		(end 71.45909 -79.459836)
		(width 0.0889)
		(layer "In11.Cu")
		(net "PU_PIROM_CPU1_ADDR0")
	)
	(arc
		(start 82.977482 -82.136488)
		(mid 83.188195 -82.349567)
		(end 83.476338 -82.43189)
		(width 0.0889)
		(layer "In11.Cu")
		(net "PU_PIROM_CPU1_ADDR0")
	)
	(arc
		(start 87.796878 -84.90839)
		(mid 87.98852 -84.965556)
		(end 88.128602 -85.108288)
		(width 0.0889)
		(layer "In11.Cu")
		(net "PU_PIROM_CPU1_ADDR0")
	)
	(arc
		(start 76.968096 -78.669388)
		(mid 77.176704 -78.88132)
		(end 77.462126 -78.96479)
		(width 0.0889)
		(layer "In11.Cu")
		(net "PU_PIROM_CPU1_ADDR0")
	)
	(arc
		(start 82.645758 -81.93659)
		(mid 82.8374 -81.993756)
		(end 82.977482 -82.136488)
		(width 0.0889)
		(layer "In11.Cu")
		(net "PU_PIROM_CPU1_ADDR0")
	)
	(arc
		(start 75.416156 -78.174088)
		(mid 75.556235 -78.031352)
		(end 75.74788 -77.97419)
		(width 0.0889)
		(layer "In11.Cu")
		(net "PU_PIROM_CPU1_ADDR0")
	)
	(arc
		(start 79.211678 -79.95539)
		(mid 79.40332 -80.012556)
		(end 79.543402 -80.155288)
		(width 0.0889)
		(layer "In11.Cu")
		(net "PU_PIROM_CPU1_ADDR0")
	)
	(segment
		(start 93.504258 -88.28024)
		(end 92.932758 -88.28024)
		(width 0.10795)
		(layer "F.Cu")
		(net "PD_PIROM_CPU1_ADDR2")
	)
	(segment
		(start 29.6164 -105.3338)
		(end 29.743146 -105.207054)
		(width 0.10795)
		(layer "F.Cu")
		(net "PD_PIROM_CPU1_ADDR2")
	)
	(segment
		(start 29.743146 -105.207054)
		(end 30.230064 -105.207054)
		(width 0.10795)
		(layer "F.Cu")
		(net "PD_PIROM_CPU1_ADDR2")
	)
	(via
		(at 30.230064 -105.207054)
		(size 0.508)
		(drill 0.254)
		(layers "F.Cu" "B.Cu")
		(net "PD_PIROM_CPU1_ADDR2")
	)
	(via
		(at 92.932758 -88.28024)
		(size 0.508)
		(drill 0.254)
		(layers "F.Cu" "B.Cu")
		(net "PD_PIROM_CPU1_ADDR2")
	)
	(via
		(at 29.4005 -104.68102)
		(size 0.6604)
		(drill 0.3302)
		(layers "F.Cu" "B.Cu")
		(net "PD_PIROM_CPU1_ADDR2")
	)
	(segment
		(start 29.926534 -105.207054)
		(end 29.4005 -104.68102)
		(width 0.10795)
		(layer "B.Cu")
		(net "PD_PIROM_CPU1_ADDR2")
	)
	(segment
		(start 30.230064 -105.207054)
		(end 29.926534 -105.207054)
		(width 0.10795)
		(layer "B.Cu")
		(net "PD_PIROM_CPU1_ADDR2")
	)
	(segment
		(start 82.641948 -82.92719)
		(end 82.609182 -82.92719)
		(width 0.0889)
		(layer "In11.Cu")
		(net "PD_PIROM_CPU1_ADDR2")
	)
	(segment
		(start 77.826362 -80.155542)
		(end 77.82306 -80.1497)
		(width 0.0889)
		(layer "In11.Cu")
		(net "PD_PIROM_CPU1_ADDR2")
	)
	(segment
		(start 91.233498 -88.87079)
		(end 91.197938 -88.87079)
		(width 0.0889)
		(layer "In11.Cu")
		(net "PD_PIROM_CPU1_ADDR2")
	)
	(segment
		(start 92.639642 -88.111076)
		(end 92.550234 -88.135206)
		(width 0.0889)
		(layer "In11.Cu")
		(net "PD_PIROM_CPU1_ADDR2")
	)
	(segment
		(start 84.362798 -83.91779)
		(end 84.330032 -83.91779)
		(width 0.0889)
		(layer "In11.Cu")
		(net "PD_PIROM_CPU1_ADDR2")
	)
	(segment
		(start 40.19804 -99.261168)
		(end 37.4523 -102.006908)
		(width 0.089408)
		(layer "In11.Cu")
		(net "PD_PIROM_CPU1_ADDR2")
	)
	(segment
		(start 73.208896 -79.459836)
		(end 73.17613 -79.459836)
		(width 0.0889)
		(layer "In11.Cu")
		(net "PD_PIROM_CPU1_ADDR2")
	)
	(segment
		(start 66.649092 -82.9056)
		(end 65.468754 -84.085938)
		(width 0.089408)
		(layer "In11.Cu")
		(net "PD_PIROM_CPU1_ADDR2")
	)
	(segment
		(start 68.252848 -82.410046)
		(end 67.567556 -82.410046)
		(width 0.0889)
		(layer "In11.Cu")
		(net "PD_PIROM_CPU1_ADDR2")
	)
	(segment
		(start 52.681632 -92.860368)
		(end 50.304954 -92.860368)
		(width 0.089408)
		(layer "In11.Cu")
		(net "PD_PIROM_CPU1_ADDR2")
	)
	(segment
		(start 37.4523 -102.006908)
		(end 37.4523 -103.018336)
		(width 0.089408)
		(layer "In11.Cu")
		(net "PD_PIROM_CPU1_ADDR2")
	)
	(segment
		(start 80.928718 -81.93659)
		(end 80.895952 -81.93659)
		(width 0.0889)
		(layer "In11.Cu")
		(net "PD_PIROM_CPU1_ADDR2")
	)
	(segment
		(start 69.774816 -81.441036)
		(end 69.74205 -81.441036)
		(width 0.0889)
		(layer "In11.Cu")
		(net "PD_PIROM_CPU1_ADDR2")
	)
	(segment
		(start 44.12869 -95.363792)
		(end 40.231314 -99.261168)
		(width 0.089408)
		(layer "In11.Cu")
		(net "PD_PIROM_CPU1_ADDR2")
	)
	(segment
		(start 67.4878 -82.410554)
		(end 66.992754 -82.9056)
		(width 0.0889)
		(layer "In11.Cu")
		(net "PD_PIROM_CPU1_ADDR2")
	)
	(segment
		(start 67.567556 -82.410046)
		(end 67.567048 -82.410554)
		(width 0.0889)
		(layer "In11.Cu")
		(net "PD_PIROM_CPU1_ADDR2")
	)
	(segment
		(start 49.497996 -93.667326)
		(end 49.497996 -93.79966)
		(width 0.089408)
		(layer "In11.Cu")
		(net "PD_PIROM_CPU1_ADDR2")
	)
	(segment
		(start 76.632562 -79.459836)
		(end 76.599796 -79.459836)
		(width 0.0889)
		(layer "In11.Cu")
		(net "PD_PIROM_CPU1_ADDR2")
	)
	(segment
		(start 86.079838 -84.90839)
		(end 86.047072 -84.90839)
		(width 0.0889)
		(layer "In11.Cu")
		(net "PD_PIROM_CPU1_ADDR2")
	)
	(segment
		(start 81.783428 -82.43189)
		(end 81.759298 -82.43189)
		(width 0.0889)
		(layer "In11.Cu")
		(net "PD_PIROM_CPU1_ADDR2")
	)
	(segment
		(start 72.346566 -79.95539)
		(end 72.3138 -79.95539)
		(width 0.0889)
		(layer "In11.Cu")
		(net "PD_PIROM_CPU1_ADDR2")
	)
	(segment
		(start 65.468754 -84.085938)
		(end 61.456062 -84.085938)
		(width 0.089408)
		(layer "In11.Cu")
		(net "PD_PIROM_CPU1_ADDR2")
	)
	(segment
		(start 40.231314 -99.261168)
		(end 40.19804 -99.261168)
		(width 0.089408)
		(layer "In11.Cu")
		(net "PD_PIROM_CPU1_ADDR2")
	)
	(segment
		(start 92.095828 -88.375236)
		(end 92.063062 -88.375236)
		(width 0.0889)
		(layer "In11.Cu")
		(net "PD_PIROM_CPU1_ADDR2")
	)
	(segment
		(start 87.796878 -85.89899)
		(end 87.764112 -85.89899)
		(width 0.0889)
		(layer "In11.Cu")
		(net "PD_PIROM_CPU1_ADDR2")
	)
	(segment
		(start 75.777852 -78.96479)
		(end 75.74788 -78.96479)
		(width 0.0889)
		(layer "In11.Cu")
		(net "PD_PIROM_CPU1_ADDR2")
	)
	(segment
		(start 83.507326 -83.42249)
		(end 83.467702 -83.42249)
		(width 0.0889)
		(layer "In11.Cu")
		(net "PD_PIROM_CPU1_ADDR2")
	)
	(segment
		(start 61.456062 -84.085938)
		(end 52.681632 -92.860368)
		(width 0.089408)
		(layer "In11.Cu")
		(net "PD_PIROM_CPU1_ADDR2")
	)
	(segment
		(start 85.217508 -84.412836)
		(end 85.184742 -84.412836)
		(width 0.0889)
		(layer "In11.Cu")
		(net "PD_PIROM_CPU1_ADDR2")
	)
	(segment
		(start 89.513664 -87.88019)
		(end 89.480898 -87.88019)
		(width 0.0889)
		(layer "In11.Cu")
		(net "PD_PIROM_CPU1_ADDR2")
	)
	(segment
		(start 92.932758 -88.28024)
		(end 92.639642 -88.111076)
		(width 0.0889)
		(layer "In11.Cu")
		(net "PD_PIROM_CPU1_ADDR2")
	)
	(segment
		(start 70.629526 -80.94599)
		(end 70.59676 -80.94599)
		(width 0.0889)
		(layer "In11.Cu")
		(net "PD_PIROM_CPU1_ADDR2")
	)
	(segment
		(start 31.171896 -105.207054)
		(end 30.230064 -105.207054)
		(width 0.089408)
		(layer "In11.Cu")
		(net "PD_PIROM_CPU1_ADDR2")
	)
	(segment
		(start 88.640412 -86.394036)
		(end 88.618822 -86.394036)
		(width 0.0889)
		(layer "In11.Cu")
		(net "PD_PIROM_CPU1_ADDR2")
	)
	(segment
		(start 90.368374 -88.375236)
		(end 90.335608 -88.375236)
		(width 0.0889)
		(layer "In11.Cu")
		(net "PD_PIROM_CPU1_ADDR2")
	)
	(segment
		(start 36.460176 -104.01046)
		(end 32.36849 -104.01046)
		(width 0.089408)
		(layer "In11.Cu")
		(net "PD_PIROM_CPU1_ADDR2")
	)
	(segment
		(start 68.726304 -81.93659)
		(end 68.252848 -82.410046)
		(width 0.0889)
		(layer "In11.Cu")
		(net "PD_PIROM_CPU1_ADDR2")
	)
	(segment
		(start 49.497996 -93.79966)
		(end 47.93361 -95.364046)
		(width 0.089408)
		(layer "In11.Cu")
		(net "PD_PIROM_CPU1_ADDR2")
	)
	(segment
		(start 86.934548 -85.403436)
		(end 86.901782 -85.403436)
		(width 0.0889)
		(layer "In11.Cu")
		(net "PD_PIROM_CPU1_ADDR2")
	)
	(segment
		(start 47.775368 -95.363792)
		(end 44.12869 -95.363792)
		(width 0.089408)
		(layer "In11.Cu")
		(net "PD_PIROM_CPU1_ADDR2")
	)
	(segment
		(start 71.491856 -80.450436)
		(end 71.45909 -80.450436)
		(width 0.0889)
		(layer "In11.Cu")
		(net "PD_PIROM_CPU1_ADDR2")
	)
	(segment
		(start 66.992754 -82.9056)
		(end 66.649092 -82.9056)
		(width 0.089408)
		(layer "In11.Cu")
		(net "PD_PIROM_CPU1_ADDR2")
	)
	(segment
		(start 32.36849 -104.01046)
		(end 31.171896 -105.207054)
		(width 0.089408)
		(layer "In11.Cu")
		(net "PD_PIROM_CPU1_ADDR2")
	)
	(segment
		(start 67.567048 -82.410554)
		(end 67.4878 -82.410554)
		(width 0.0889)
		(layer "In11.Cu")
		(net "PD_PIROM_CPU1_ADDR2")
	)
	(segment
		(start 77.479906 -79.95539)
		(end 77.462126 -79.95539)
		(width 0.0889)
		(layer "In11.Cu")
		(net "PD_PIROM_CPU1_ADDR2")
	)
	(segment
		(start 79.211678 -80.94599)
		(end 79.178912 -80.94599)
		(width 0.0889)
		(layer "In11.Cu")
		(net "PD_PIROM_CPU1_ADDR2")
	)
	(segment
		(start 68.912486 -81.93659)
		(end 68.726304 -81.93659)
		(width 0.0889)
		(layer "In11.Cu")
		(net "PD_PIROM_CPU1_ADDR2")
	)
	(segment
		(start 74.060812 -78.96479)
		(end 74.03084 -78.96479)
		(width 0.0889)
		(layer "In11.Cu")
		(net "PD_PIROM_CPU1_ADDR2")
	)
	(segment
		(start 50.304954 -92.860368)
		(end 49.497996 -93.667326)
		(width 0.089408)
		(layer "In11.Cu")
		(net "PD_PIROM_CPU1_ADDR2")
	)
	(segment
		(start 37.4523 -103.018336)
		(end 36.460176 -104.01046)
		(width 0.089408)
		(layer "In11.Cu")
		(net "PD_PIROM_CPU1_ADDR2")
	)
	(segment
		(start 47.775622 -95.364046)
		(end 47.775368 -95.363792)
		(width 0.089408)
		(layer "In11.Cu")
		(net "PD_PIROM_CPU1_ADDR2")
	)
	(segment
		(start 78.349348 -80.450436)
		(end 78.31328 -80.450436)
		(width 0.0889)
		(layer "In11.Cu")
		(net "PD_PIROM_CPU1_ADDR2")
	)
	(segment
		(start 80.066388 -81.441036)
		(end 80.033622 -81.441036)
		(width 0.0889)
		(layer "In11.Cu")
		(net "PD_PIROM_CPU1_ADDR2")
	)
	(segment
		(start 47.93361 -95.364046)
		(end 47.775622 -95.364046)
		(width 0.089408)
		(layer "In11.Cu")
		(net "PD_PIROM_CPU1_ADDR2")
	)
	(arc
		(start 85.553042 -84.612988)
		(mid 85.411359 -84.469184)
		(end 85.217508 -84.412836)
		(width 0.0889)
		(layer "In11.Cu")
		(net "PD_PIROM_CPU1_ADDR2")
	)
	(arc
		(start 89.480898 -87.88019)
		(mid 88.982377 -87.577306)
		(end 88.986868 -86.993984)
		(width 0.0889)
		(layer "In11.Cu")
		(net "PD_PIROM_CPU1_ADDR2")
	)
	(arc
		(start 70.59676 -80.94599)
		(mid 70.405118 -81.003156)
		(end 70.265036 -81.145888)
		(width 0.0889)
		(layer "In11.Cu")
		(net "PD_PIROM_CPU1_ADDR2")
	)
	(arc
		(start 77.82306 -80.1497)
		(mid 77.677094 -80.007301)
		(end 77.479906 -79.95539)
		(width 0.0889)
		(layer "In11.Cu")
		(net "PD_PIROM_CPU1_ADDR2")
	)
	(arc
		(start 73.17613 -79.459836)
		(mid 72.98228 -79.516186)
		(end 72.840596 -79.659988)
		(width 0.0889)
		(layer "In11.Cu")
		(net "PD_PIROM_CPU1_ADDR2")
	)
	(arc
		(start 90.703908 -88.575388)
		(mid 90.562225 -88.431584)
		(end 90.368374 -88.375236)
		(width 0.0889)
		(layer "In11.Cu")
		(net "PD_PIROM_CPU1_ADDR2")
	)
	(arc
		(start 90.335608 -88.375236)
		(mid 90.052391 -88.290955)
		(end 89.845388 -88.080088)
		(width 0.0889)
		(layer "In11.Cu")
		(net "PD_PIROM_CPU1_ADDR2")
	)
	(arc
		(start 71.123556 -80.650588)
		(mid 70.914948 -80.86252)
		(end 70.629526 -80.94599)
		(width 0.0889)
		(layer "In11.Cu")
		(net "PD_PIROM_CPU1_ADDR2")
	)
	(arc
		(start 82.118962 -82.632042)
		(mid 81.977279 -82.488238)
		(end 81.783428 -82.43189)
		(width 0.0889)
		(layer "In11.Cu")
		(net "PD_PIROM_CPU1_ADDR2")
	)
	(arc
		(start 91.197938 -88.87079)
		(mid 90.912514 -88.787323)
		(end 90.703908 -88.575388)
		(width 0.0889)
		(layer "In11.Cu")
		(net "PD_PIROM_CPU1_ADDR2")
	)
	(arc
		(start 82.977482 -83.127342)
		(mid 82.835799 -82.983538)
		(end 82.641948 -82.92719)
		(width 0.0889)
		(layer "In11.Cu")
		(net "PD_PIROM_CPU1_ADDR2")
	)
	(arc
		(start 88.128602 -86.098888)
		(mid 87.988523 -85.956152)
		(end 87.796878 -85.89899)
		(width 0.0889)
		(layer "In11.Cu")
		(net "PD_PIROM_CPU1_ADDR2")
	)
	(arc
		(start 72.3138 -79.95539)
		(mid 72.122158 -80.012556)
		(end 71.982076 -80.155288)
		(width 0.0889)
		(layer "In11.Cu")
		(net "PD_PIROM_CPU1_ADDR2")
	)
	(arc
		(start 76.109576 -79.164688)
		(mid 75.969497 -79.021952)
		(end 75.777852 -78.96479)
		(width 0.0889)
		(layer "In11.Cu")
		(net "PD_PIROM_CPU1_ADDR2")
	)
	(arc
		(start 69.74205 -81.441036)
		(mid 69.5482 -81.497386)
		(end 69.406516 -81.641188)
		(width 0.0889)
		(layer "In11.Cu")
		(net "PD_PIROM_CPU1_ADDR2")
	)
	(arc
		(start 74.03084 -78.96479)
		(mid 73.839198 -79.021956)
		(end 73.699116 -79.164688)
		(width 0.0889)
		(layer "In11.Cu")
		(net "PD_PIROM_CPU1_ADDR2")
	)
	(arc
		(start 73.699116 -79.164688)
		(mid 73.492112 -79.375552)
		(end 73.208896 -79.459836)
		(width 0.0889)
		(layer "In11.Cu")
		(net "PD_PIROM_CPU1_ADDR2")
	)
	(arc
		(start 88.986868 -86.993984)
		(mid 88.986785 -86.594043)
		(end 88.640412 -86.394036)
		(width 0.0889)
		(layer "In11.Cu")
		(net "PD_PIROM_CPU1_ADDR2")
	)
	(arc
		(start 86.901782 -85.403436)
		(mid 86.618565 -85.319155)
		(end 86.411562 -85.108288)
		(width 0.0889)
		(layer "In11.Cu")
		(net "PD_PIROM_CPU1_ADDR2")
	)
	(arc
		(start 84.694522 -84.117688)
		(mid 84.554443 -83.974952)
		(end 84.362798 -83.91779)
		(width 0.0889)
		(layer "In11.Cu")
		(net "PD_PIROM_CPU1_ADDR2")
	)
	(arc
		(start 85.184742 -84.412836)
		(mid 84.901525 -84.328555)
		(end 84.694522 -84.117688)
		(width 0.0889)
		(layer "In11.Cu")
		(net "PD_PIROM_CPU1_ADDR2")
	)
	(arc
		(start 86.047072 -84.90839)
		(mid 85.761648 -84.824923)
		(end 85.553042 -84.612988)
		(width 0.0889)
		(layer "In11.Cu")
		(net "PD_PIROM_CPU1_ADDR2")
	)
	(arc
		(start 74.392536 -79.164688)
		(mid 74.252457 -79.021952)
		(end 74.060812 -78.96479)
		(width 0.0889)
		(layer "In11.Cu")
		(net "PD_PIROM_CPU1_ADDR2")
	)
	(arc
		(start 82.609182 -82.92719)
		(mid 82.325965 -82.842909)
		(end 82.118962 -82.632042)
		(width 0.0889)
		(layer "In11.Cu")
		(net "PD_PIROM_CPU1_ADDR2")
	)
	(arc
		(start 80.895952 -81.93659)
		(mid 80.610528 -81.853123)
		(end 80.401922 -81.641188)
		(width 0.0889)
		(layer "In11.Cu")
		(net "PD_PIROM_CPU1_ADDR2")
	)
	(arc
		(start 84.330032 -83.91779)
		(mid 84.044608 -83.834323)
		(end 83.836002 -83.622388)
		(width 0.0889)
		(layer "In11.Cu")
		(net "PD_PIROM_CPU1_ADDR2")
	)
	(arc
		(start 75.416156 -79.164688)
		(mid 74.904346 -79.460227)
		(end 74.392536 -79.164688)
		(width 0.0889)
		(layer "In11.Cu")
		(net "PD_PIROM_CPU1_ADDR2")
	)
	(arc
		(start 91.727528 -88.575388)
		(mid 91.51892 -88.78732)
		(end 91.233498 -88.87079)
		(width 0.0889)
		(layer "In11.Cu")
		(net "PD_PIROM_CPU1_ADDR2")
	)
	(arc
		(start 76.599796 -79.459836)
		(mid 76.316579 -79.375555)
		(end 76.109576 -79.164688)
		(width 0.0889)
		(layer "In11.Cu")
		(net "PD_PIROM_CPU1_ADDR2")
	)
	(arc
		(start 81.260442 -82.136488)
		(mid 81.120363 -81.993752)
		(end 80.928718 -81.93659)
		(width 0.0889)
		(layer "In11.Cu")
		(net "PD_PIROM_CPU1_ADDR2")
	)
	(arc
		(start 72.840596 -79.659988)
		(mid 72.631988 -79.87192)
		(end 72.346566 -79.95539)
		(width 0.0889)
		(layer "In11.Cu")
		(net "PD_PIROM_CPU1_ADDR2")
	)
	(arc
		(start 87.764112 -85.89899)
		(mid 87.478688 -85.815523)
		(end 87.270082 -85.603588)
		(width 0.0889)
		(layer "In11.Cu")
		(net "PD_PIROM_CPU1_ADDR2")
	)
	(arc
		(start 71.982076 -80.155288)
		(mid 71.775072 -80.366152)
		(end 71.491856 -80.450436)
		(width 0.0889)
		(layer "In11.Cu")
		(net "PD_PIROM_CPU1_ADDR2")
	)
	(arc
		(start 75.74788 -78.96479)
		(mid 75.556238 -79.021956)
		(end 75.416156 -79.164688)
		(width 0.0889)
		(layer "In11.Cu")
		(net "PD_PIROM_CPU1_ADDR2")
	)
	(arc
		(start 86.411562 -85.108288)
		(mid 86.271483 -84.965552)
		(end 86.079838 -84.90839)
		(width 0.0889)
		(layer "In11.Cu")
		(net "PD_PIROM_CPU1_ADDR2")
	)
	(arc
		(start 79.543402 -81.145888)
		(mid 79.403323 -81.003152)
		(end 79.211678 -80.94599)
		(width 0.0889)
		(layer "In11.Cu")
		(net "PD_PIROM_CPU1_ADDR2")
	)
	(arc
		(start 78.684882 -80.650588)
		(mid 78.543199 -80.506784)
		(end 78.349348 -80.450436)
		(width 0.0889)
		(layer "In11.Cu")
		(net "PD_PIROM_CPU1_ADDR2")
	)
	(arc
		(start 79.178912 -80.94599)
		(mid 78.893488 -80.862523)
		(end 78.684882 -80.650588)
		(width 0.0889)
		(layer "In11.Cu")
		(net "PD_PIROM_CPU1_ADDR2")
	)
	(arc
		(start 70.265036 -81.145888)
		(mid 70.058032 -81.356752)
		(end 69.774816 -81.441036)
		(width 0.0889)
		(layer "In11.Cu")
		(net "PD_PIROM_CPU1_ADDR2")
	)
	(arc
		(start 69.406516 -81.641188)
		(mid 69.197908 -81.85312)
		(end 68.912486 -81.93659)
		(width 0.0889)
		(layer "In11.Cu")
		(net "PD_PIROM_CPU1_ADDR2")
	)
	(arc
		(start 83.836002 -83.622388)
		(mid 83.697258 -83.480355)
		(end 83.507326 -83.42249)
		(width 0.0889)
		(layer "In11.Cu")
		(net "PD_PIROM_CPU1_ADDR2")
	)
	(arc
		(start 76.968096 -79.659988)
		(mid 76.826413 -79.516184)
		(end 76.632562 -79.459836)
		(width 0.0889)
		(layer "In11.Cu")
		(net "PD_PIROM_CPU1_ADDR2")
	)
	(arc
		(start 89.845388 -88.080088)
		(mid 89.705309 -87.937352)
		(end 89.513664 -87.88019)
		(width 0.0889)
		(layer "In11.Cu")
		(net "PD_PIROM_CPU1_ADDR2")
	)
	(arc
		(start 92.550234 -88.135206)
		(mid 92.350489 -88.3072)
		(end 92.095828 -88.375236)
		(width 0.0889)
		(layer "In11.Cu")
		(net "PD_PIROM_CPU1_ADDR2")
	)
	(arc
		(start 77.462126 -79.95539)
		(mid 77.176702 -79.871923)
		(end 76.968096 -79.659988)
		(width 0.0889)
		(layer "In11.Cu")
		(net "PD_PIROM_CPU1_ADDR2")
	)
	(arc
		(start 78.31328 -80.450436)
		(mid 78.03198 -80.36547)
		(end 77.826362 -80.155542)
		(width 0.0889)
		(layer "In11.Cu")
		(net "PD_PIROM_CPU1_ADDR2")
	)
	(arc
		(start 80.401922 -81.641188)
		(mid 80.260239 -81.497384)
		(end 80.066388 -81.441036)
		(width 0.0889)
		(layer "In11.Cu")
		(net "PD_PIROM_CPU1_ADDR2")
	)
	(arc
		(start 80.033622 -81.441036)
		(mid 79.750405 -81.356755)
		(end 79.543402 -81.145888)
		(width 0.0889)
		(layer "In11.Cu")
		(net "PD_PIROM_CPU1_ADDR2")
	)
	(arc
		(start 88.618822 -86.394036)
		(mid 88.335605 -86.309755)
		(end 88.128602 -86.098888)
		(width 0.0889)
		(layer "In11.Cu")
		(net "PD_PIROM_CPU1_ADDR2")
	)
	(arc
		(start 81.759298 -82.43189)
		(mid 81.471153 -82.349571)
		(end 81.260442 -82.136488)
		(width 0.0889)
		(layer "In11.Cu")
		(net "PD_PIROM_CPU1_ADDR2")
	)
	(arc
		(start 87.270082 -85.603588)
		(mid 87.128399 -85.459784)
		(end 86.934548 -85.403436)
		(width 0.0889)
		(layer "In11.Cu")
		(net "PD_PIROM_CPU1_ADDR2")
	)
	(arc
		(start 92.063062 -88.375236)
		(mid 91.869212 -88.431586)
		(end 91.727528 -88.575388)
		(width 0.0889)
		(layer "In11.Cu")
		(net "PD_PIROM_CPU1_ADDR2")
	)
	(arc
		(start 71.45909 -80.450436)
		(mid 71.26524 -80.506786)
		(end 71.123556 -80.650588)
		(width 0.0889)
		(layer "In11.Cu")
		(net "PD_PIROM_CPU1_ADDR2")
	)
	(arc
		(start 83.467702 -83.42249)
		(mid 83.184485 -83.338209)
		(end 82.977482 -83.127342)
		(width 0.0889)
		(layer "In11.Cu")
		(net "PD_PIROM_CPU1_ADDR2")
	)
	(segment
		(start 92.645738 -87.784686)
		(end 92.074238 -87.784686)
		(width 0.10795)
		(layer "F.Cu")
		(net "PD_PIROM_CPU1_ADDR1")
	)
	(segment
		(start 30.226 -104.5718)
		(end 30.2514 -104.5464)
		(width 0.10795)
		(layer "F.Cu")
		(net "PD_PIROM_CPU1_ADDR1")
	)
	(segment
		(start 29.6164 -104.5718)
		(end 30.226 -104.5718)
		(width 0.10795)
		(layer "F.Cu")
		(net "PD_PIROM_CPU1_ADDR1")
	)
	(via
		(at 92.074238 -87.784686)
		(size 0.508)
		(drill 0.254)
		(layers "F.Cu" "B.Cu")
		(net "PD_PIROM_CPU1_ADDR1")
	)
	(via
		(at 30.2514 -104.5464)
		(size 0.508)
		(drill 0.254)
		(layers "F.Cu" "B.Cu")
		(net "PD_PIROM_CPU1_ADDR1")
	)
	(segment
		(start 44.016676 -95.172784)
		(end 40.1193 -99.07016)
		(width 0.089408)
		(layer "In11.Cu")
		(net "PD_PIROM_CPU1_ADDR1")
	)
	(segment
		(start 44.433998 -95.172784)
		(end 44.433744 -95.17253)
		(width 0.089408)
		(layer "In11.Cu")
		(net "PD_PIROM_CPU1_ADDR1")
	)
	(segment
		(start 79.218282 -80.75549)
		(end 79.185516 -80.75549)
		(width 0.0889)
		(layer "In11.Cu")
		(net "PD_PIROM_CPU1_ADDR1")
	)
	(segment
		(start 44.207938 -95.172784)
		(end 44.207684 -95.17253)
		(width 0.089408)
		(layer "In11.Cu")
		(net "PD_PIROM_CPU1_ADDR1")
	)
	(segment
		(start 47.854616 -95.172784)
		(end 44.433998 -95.172784)
		(width 0.089408)
		(layer "In11.Cu")
		(net "PD_PIROM_CPU1_ADDR1")
	)
	(segment
		(start 71.485252 -80.259936)
		(end 71.452486 -80.259936)
		(width 0.0889)
		(layer "In11.Cu")
		(net "PD_PIROM_CPU1_ADDR1")
	)
	(segment
		(start 81.785206 -82.241136)
		(end 81.757266 -82.241136)
		(width 0.0889)
		(layer "In11.Cu")
		(net "PD_PIROM_CPU1_ADDR1")
	)
	(segment
		(start 67.3608 -82.2198)
		(end 66.9036 -82.677)
		(width 0.089408)
		(layer "In11.Cu")
		(net "PD_PIROM_CPU1_ADDR1")
	)
	(segment
		(start 68.905882 -81.74609)
		(end 68.64731 -81.74609)
		(width 0.0889)
		(layer "In11.Cu")
		(net "PD_PIROM_CPU1_ADDR1")
	)
	(segment
		(start 80.072992 -81.250536)
		(end 80.040226 -81.250536)
		(width 0.0889)
		(layer "In11.Cu")
		(net "PD_PIROM_CPU1_ADDR1")
	)
	(segment
		(start 90.374978 -88.184736)
		(end 90.342212 -88.184736)
		(width 0.0889)
		(layer "In11.Cu")
		(net "PD_PIROM_CPU1_ADDR1")
	)
	(segment
		(start 49.306988 -93.588078)
		(end 49.306988 -93.720412)
		(width 0.089408)
		(layer "In11.Cu")
		(net "PD_PIROM_CPU1_ADDR1")
	)
	(segment
		(start 83.507072 -83.231736)
		(end 83.471258 -83.231736)
		(width 0.0889)
		(layer "In11.Cu")
		(net "PD_PIROM_CPU1_ADDR1")
	)
	(segment
		(start 65.3796 -83.8708)
		(end 61.366908 -83.8708)
		(width 0.089408)
		(layer "In11.Cu")
		(net "PD_PIROM_CPU1_ADDR1")
	)
	(segment
		(start 68.1736 -82.2198)
		(end 67.4878 -82.2198)
		(width 0.0889)
		(layer "In11.Cu")
		(net "PD_PIROM_CPU1_ADDR1")
	)
	(segment
		(start 72.339962 -79.76489)
		(end 72.307196 -79.76489)
		(width 0.0889)
		(layer "In11.Cu")
		(net "PD_PIROM_CPU1_ADDR1")
	)
	(segment
		(start 52.578508 -92.6592)
		(end 50.235866 -92.6592)
		(width 0.089408)
		(layer "In11.Cu")
		(net "PD_PIROM_CPU1_ADDR1")
	)
	(segment
		(start 44.433744 -95.17253)
		(end 44.275756 -95.17253)
		(width 0.089408)
		(layer "In11.Cu")
		(net "PD_PIROM_CPU1_ADDR1")
	)
	(segment
		(start 77.995018 -80.065626)
		(end 77.991716 -80.059784)
		(width 0.0889)
		(layer "In11.Cu")
		(net "PD_PIROM_CPU1_ADDR1")
	)
	(segment
		(start 66.9036 -82.677)
		(end 66.5734 -82.677)
		(width 0.089408)
		(layer "In11.Cu")
		(net "PD_PIROM_CPU1_ADDR1")
	)
	(segment
		(start 92.089224 -88.184736)
		(end 92.056458 -88.184736)
		(width 0.0889)
		(layer "In11.Cu")
		(net "PD_PIROM_CPU1_ADDR1")
	)
	(segment
		(start 76.639166 -79.269336)
		(end 76.6064 -79.269336)
		(width 0.0889)
		(layer "In11.Cu")
		(net "PD_PIROM_CPU1_ADDR1")
	)
	(segment
		(start 32.289242 -103.819452)
		(end 31.562294 -104.5464)
		(width 0.089408)
		(layer "In11.Cu")
		(net "PD_PIROM_CPU1_ADDR1")
	)
	(segment
		(start 89.520268 -87.68969)
		(end 89.498678 -87.68969)
		(width 0.0889)
		(layer "In11.Cu")
		(net "PD_PIROM_CPU1_ADDR1")
	)
	(segment
		(start 78.355952 -80.259936)
		(end 78.338172 -80.259936)
		(width 0.0889)
		(layer "In11.Cu")
		(net "PD_PIROM_CPU1_ADDR1")
	)
	(segment
		(start 37.261292 -101.92766)
		(end 37.261292 -102.939088)
		(width 0.089408)
		(layer "In11.Cu")
		(net "PD_PIROM_CPU1_ADDR1")
	)
	(segment
		(start 68.64731 -81.74609)
		(end 68.1736 -82.2198)
		(width 0.0889)
		(layer "In11.Cu")
		(net "PD_PIROM_CPU1_ADDR1")
	)
	(segment
		(start 84.369402 -83.72729)
		(end 84.336636 -83.72729)
		(width 0.0889)
		(layer "In11.Cu")
		(net "PD_PIROM_CPU1_ADDR1")
	)
	(segment
		(start 87.803482 -85.70849)
		(end 87.770716 -85.70849)
		(width 0.0889)
		(layer "In11.Cu")
		(net "PD_PIROM_CPU1_ADDR1")
	)
	(segment
		(start 66.5734 -82.677)
		(end 65.3796 -83.8708)
		(width 0.089408)
		(layer "In11.Cu")
		(net "PD_PIROM_CPU1_ADDR1")
	)
	(segment
		(start 31.562294 -104.5464)
		(end 30.2514 -104.5464)
		(width 0.089408)
		(layer "In11.Cu")
		(net "PD_PIROM_CPU1_ADDR1")
	)
	(segment
		(start 70.622922 -80.75549)
		(end 70.590156 -80.75549)
		(width 0.0889)
		(layer "In11.Cu")
		(net "PD_PIROM_CPU1_ADDR1")
	)
	(segment
		(start 44.275502 -95.172784)
		(end 44.207938 -95.172784)
		(width 0.089408)
		(layer "In11.Cu")
		(net "PD_PIROM_CPU1_ADDR1")
	)
	(segment
		(start 36.380928 -103.819452)
		(end 32.289242 -103.819452)
		(width 0.089408)
		(layer "In11.Cu")
		(net "PD_PIROM_CPU1_ADDR1")
	)
	(segment
		(start 37.261292 -102.939088)
		(end 36.380928 -103.819452)
		(width 0.089408)
		(layer "In11.Cu")
		(net "PD_PIROM_CPU1_ADDR1")
	)
	(segment
		(start 44.207684 -95.17253)
		(end 44.049696 -95.17253)
		(width 0.089408)
		(layer "In11.Cu")
		(net "PD_PIROM_CPU1_ADDR1")
	)
	(segment
		(start 80.935322 -81.74609)
		(end 80.902556 -81.74609)
		(width 0.0889)
		(layer "In11.Cu")
		(net "PD_PIROM_CPU1_ADDR1")
	)
	(segment
		(start 40.1193 -99.07016)
		(end 40.118792 -99.07016)
		(width 0.089408)
		(layer "In11.Cu")
		(net "PD_PIROM_CPU1_ADDR1")
	)
	(segment
		(start 92.367354 -87.95385)
		(end 92.388436 -88.03259)
		(width 0.0889)
		(layer "In11.Cu")
		(net "PD_PIROM_CPU1_ADDR1")
	)
	(segment
		(start 74.067416 -78.77429)
		(end 74.024236 -78.77429)
		(width 0.0889)
		(layer "In11.Cu")
		(net "PD_PIROM_CPU1_ADDR1")
	)
	(segment
		(start 67.4878 -82.2198)
		(end 67.3608 -82.2198)
		(width 0.089408)
		(layer "In11.Cu")
		(net "PD_PIROM_CPU1_ADDR1")
	)
	(segment
		(start 44.275756 -95.17253)
		(end 44.275502 -95.172784)
		(width 0.089408)
		(layer "In11.Cu")
		(net "PD_PIROM_CPU1_ADDR1")
	)
	(segment
		(start 75.784456 -78.77429)
		(end 75.741276 -78.77429)
		(width 0.0889)
		(layer "In11.Cu")
		(net "PD_PIROM_CPU1_ADDR1")
	)
	(segment
		(start 88.658192 -86.203536)
		(end 88.625426 -86.203536)
		(width 0.0889)
		(layer "In11.Cu")
		(net "PD_PIROM_CPU1_ADDR1")
	)
	(segment
		(start 73.202292 -79.269336)
		(end 73.169526 -79.269336)
		(width 0.0889)
		(layer "In11.Cu")
		(net "PD_PIROM_CPU1_ADDR1")
	)
	(segment
		(start 69.768212 -81.250536)
		(end 69.735446 -81.250536)
		(width 0.0889)
		(layer "In11.Cu")
		(net "PD_PIROM_CPU1_ADDR1")
	)
	(segment
		(start 44.049442 -95.172784)
		(end 44.016676 -95.172784)
		(width 0.089408)
		(layer "In11.Cu")
		(net "PD_PIROM_CPU1_ADDR1")
	)
	(segment
		(start 44.049696 -95.17253)
		(end 44.049442 -95.172784)
		(width 0.089408)
		(layer "In11.Cu")
		(net "PD_PIROM_CPU1_ADDR1")
	)
	(segment
		(start 85.224112 -84.222336)
		(end 85.191346 -84.222336)
		(width 0.0889)
		(layer "In11.Cu")
		(net "PD_PIROM_CPU1_ADDR1")
	)
	(segment
		(start 61.366908 -83.8708)
		(end 52.578508 -92.6592)
		(width 0.089408)
		(layer "In11.Cu")
		(net "PD_PIROM_CPU1_ADDR1")
	)
	(segment
		(start 40.118792 -99.07016)
		(end 37.261292 -101.92766)
		(width 0.089408)
		(layer "In11.Cu")
		(net "PD_PIROM_CPU1_ADDR1")
	)
	(segment
		(start 77.504798 -79.76489)
		(end 77.46873 -79.76489)
		(width 0.0889)
		(layer "In11.Cu")
		(net "PD_PIROM_CPU1_ADDR1")
	)
	(segment
		(start 82.652362 -82.73669)
		(end 82.619596 -82.73669)
		(width 0.0889)
		(layer "In11.Cu")
		(net "PD_PIROM_CPU1_ADDR1")
	)
	(segment
		(start 50.235866 -92.6592)
		(end 49.306988 -93.588078)
		(width 0.089408)
		(layer "In11.Cu")
		(net "PD_PIROM_CPU1_ADDR1")
	)
	(segment
		(start 49.306988 -93.720412)
		(end 47.854616 -95.172784)
		(width 0.089408)
		(layer "In11.Cu")
		(net "PD_PIROM_CPU1_ADDR1")
	)
	(segment
		(start 86.941152 -85.212936)
		(end 86.908386 -85.212936)
		(width 0.0889)
		(layer "In11.Cu")
		(net "PD_PIROM_CPU1_ADDR1")
	)
	(segment
		(start 92.074238 -87.784686)
		(end 92.367354 -87.95385)
		(width 0.0889)
		(layer "In11.Cu")
		(net "PD_PIROM_CPU1_ADDR1")
	)
	(segment
		(start 86.086442 -84.71789)
		(end 86.053676 -84.71789)
		(width 0.0889)
		(layer "In11.Cu")
		(net "PD_PIROM_CPU1_ADDR1")
	)
	(arc
		(start 85.191346 -84.222336)
		(mid 84.999704 -84.16517)
		(end 84.859622 -84.022438)
		(width 0.0889)
		(layer "In11.Cu")
		(net "PD_PIROM_CPU1_ADDR1")
	)
	(arc
		(start 69.241416 -81.545938)
		(mid 69.099733 -81.689742)
		(end 68.905882 -81.74609)
		(width 0.0889)
		(layer "In11.Cu")
		(net "PD_PIROM_CPU1_ADDR1")
	)
	(arc
		(start 72.675496 -79.564738)
		(mid 72.533813 -79.708542)
		(end 72.339962 -79.76489)
		(width 0.0889)
		(layer "In11.Cu")
		(net "PD_PIROM_CPU1_ADDR1")
	)
	(arc
		(start 80.040226 -81.250536)
		(mid 79.848584 -81.19337)
		(end 79.708502 -81.050638)
		(width 0.0889)
		(layer "In11.Cu")
		(net "PD_PIROM_CPU1_ADDR1")
	)
	(arc
		(start 79.708502 -81.050638)
		(mid 79.501498 -80.839774)
		(end 79.218282 -80.75549)
		(width 0.0889)
		(layer "In11.Cu")
		(net "PD_PIROM_CPU1_ADDR1")
	)
	(arc
		(start 88.293702 -86.003638)
		(mid 88.086698 -85.792774)
		(end 87.803482 -85.70849)
		(width 0.0889)
		(layer "In11.Cu")
		(net "PD_PIROM_CPU1_ADDR1")
	)
	(arc
		(start 74.024236 -78.77429)
		(mid 73.741019 -78.858571)
		(end 73.534016 -79.069438)
		(width 0.0889)
		(layer "In11.Cu")
		(net "PD_PIROM_CPU1_ADDR1")
	)
	(arc
		(start 89.498678 -87.68969)
		(mid 89.152252 -87.489713)
		(end 89.152222 -87.089742)
		(width 0.0889)
		(layer "In11.Cu")
		(net "PD_PIROM_CPU1_ADDR1")
	)
	(arc
		(start 72.307196 -79.76489)
		(mid 72.023979 -79.849171)
		(end 71.816976 -80.060038)
		(width 0.0889)
		(layer "In11.Cu")
		(net "PD_PIROM_CPU1_ADDR1")
	)
	(arc
		(start 92.056458 -88.184736)
		(mid 91.771034 -88.268203)
		(end 91.562428 -88.480138)
		(width 0.0889)
		(layer "In11.Cu")
		(net "PD_PIROM_CPU1_ADDR1")
	)
	(arc
		(start 76.6064 -79.269336)
		(mid 76.414758 -79.21217)
		(end 76.274676 -79.069438)
		(width 0.0889)
		(layer "In11.Cu")
		(net "PD_PIROM_CPU1_ADDR1")
	)
	(arc
		(start 87.770716 -85.70849)
		(mid 87.576866 -85.65214)
		(end 87.435182 -85.508338)
		(width 0.0889)
		(layer "In11.Cu")
		(net "PD_PIROM_CPU1_ADDR1")
	)
	(arc
		(start 75.251056 -79.069438)
		(mid 74.904346 -79.269622)
		(end 74.557636 -79.069438)
		(width 0.0889)
		(layer "In11.Cu")
		(net "PD_PIROM_CPU1_ADDR1")
	)
	(arc
		(start 75.741276 -78.77429)
		(mid 75.458059 -78.858571)
		(end 75.251056 -79.069438)
		(width 0.0889)
		(layer "In11.Cu")
		(net "PD_PIROM_CPU1_ADDR1")
	)
	(arc
		(start 86.908386 -85.212936)
		(mid 86.716744 -85.15577)
		(end 86.576662 -85.013038)
		(width 0.0889)
		(layer "In11.Cu")
		(net "PD_PIROM_CPU1_ADDR1")
	)
	(arc
		(start 77.991716 -80.059784)
		(mid 77.786095 -79.849861)
		(end 77.504798 -79.76489)
		(width 0.0889)
		(layer "In11.Cu")
		(net "PD_PIROM_CPU1_ADDR1")
	)
	(arc
		(start 90.010488 -87.984838)
		(mid 89.803484 -87.773974)
		(end 89.520268 -87.68969)
		(width 0.0889)
		(layer "In11.Cu")
		(net "PD_PIROM_CPU1_ADDR1")
	)
	(arc
		(start 77.133196 -79.564738)
		(mid 76.924588 -79.352806)
		(end 76.639166 -79.269336)
		(width 0.0889)
		(layer "In11.Cu")
		(net "PD_PIROM_CPU1_ADDR1")
	)
	(arc
		(start 80.902556 -81.74609)
		(mid 80.708706 -81.68974)
		(end 80.567022 -81.545938)
		(width 0.0889)
		(layer "In11.Cu")
		(net "PD_PIROM_CPU1_ADDR1")
	)
	(arc
		(start 74.557636 -79.069438)
		(mid 74.350632 -78.858574)
		(end 74.067416 -78.77429)
		(width 0.0889)
		(layer "In11.Cu")
		(net "PD_PIROM_CPU1_ADDR1")
	)
	(arc
		(start 82.284062 -82.536538)
		(mid 82.073349 -82.323459)
		(end 81.785206 -82.241136)
		(width 0.0889)
		(layer "In11.Cu")
		(net "PD_PIROM_CPU1_ADDR1")
	)
	(arc
		(start 89.152222 -87.089742)
		(mid 89.15655 -86.506566)
		(end 88.658192 -86.203536)
		(width 0.0889)
		(layer "In11.Cu")
		(net "PD_PIROM_CPU1_ADDR1")
	)
	(arc
		(start 69.735446 -81.250536)
		(mid 69.450022 -81.334003)
		(end 69.241416 -81.545938)
		(width 0.0889)
		(layer "In11.Cu")
		(net "PD_PIROM_CPU1_ADDR1")
	)
	(arc
		(start 84.859622 -84.022438)
		(mid 84.652618 -83.811574)
		(end 84.369402 -83.72729)
		(width 0.0889)
		(layer "In11.Cu")
		(net "PD_PIROM_CPU1_ADDR1")
	)
	(arc
		(start 83.142582 -83.031838)
		(mid 82.935578 -82.820974)
		(end 82.652362 -82.73669)
		(width 0.0889)
		(layer "In11.Cu")
		(net "PD_PIROM_CPU1_ADDR1")
	)
	(arc
		(start 82.619596 -82.73669)
		(mid 82.425746 -82.68034)
		(end 82.284062 -82.536538)
		(width 0.0889)
		(layer "In11.Cu")
		(net "PD_PIROM_CPU1_ADDR1")
	)
	(arc
		(start 73.534016 -79.069438)
		(mid 73.393937 -79.212174)
		(end 73.202292 -79.269336)
		(width 0.0889)
		(layer "In11.Cu")
		(net "PD_PIROM_CPU1_ADDR1")
	)
	(arc
		(start 91.562428 -88.480138)
		(mid 91.215718 -88.680449)
		(end 90.869008 -88.480138)
		(width 0.0889)
		(layer "In11.Cu")
		(net "PD_PIROM_CPU1_ADDR1")
	)
	(arc
		(start 88.625426 -86.203536)
		(mid 88.433784 -86.14637)
		(end 88.293702 -86.003638)
		(width 0.0889)
		(layer "In11.Cu")
		(net "PD_PIROM_CPU1_ADDR1")
	)
	(arc
		(start 70.099936 -81.050638)
		(mid 69.959857 -81.193374)
		(end 69.768212 -81.250536)
		(width 0.0889)
		(layer "In11.Cu")
		(net "PD_PIROM_CPU1_ADDR1")
	)
	(arc
		(start 78.849982 -80.555338)
		(mid 78.641374 -80.343406)
		(end 78.355952 -80.259936)
		(width 0.0889)
		(layer "In11.Cu")
		(net "PD_PIROM_CPU1_ADDR1")
	)
	(arc
		(start 81.757266 -82.241136)
		(mid 81.565624 -82.18397)
		(end 81.425542 -82.041238)
		(width 0.0889)
		(layer "In11.Cu")
		(net "PD_PIROM_CPU1_ADDR1")
	)
	(arc
		(start 92.388436 -88.03259)
		(mid 92.255555 -88.141573)
		(end 92.089224 -88.184736)
		(width 0.0889)
		(layer "In11.Cu")
		(net "PD_PIROM_CPU1_ADDR1")
	)
	(arc
		(start 78.338172 -80.259936)
		(mid 78.141011 -80.207977)
		(end 77.995018 -80.065626)
		(width 0.0889)
		(layer "In11.Cu")
		(net "PD_PIROM_CPU1_ADDR1")
	)
	(arc
		(start 86.576662 -85.013038)
		(mid 86.369658 -84.802174)
		(end 86.086442 -84.71789)
		(width 0.0889)
		(layer "In11.Cu")
		(net "PD_PIROM_CPU1_ADDR1")
	)
	(arc
		(start 85.718142 -84.517738)
		(mid 85.509534 -84.305806)
		(end 85.224112 -84.222336)
		(width 0.0889)
		(layer "In11.Cu")
		(net "PD_PIROM_CPU1_ADDR1")
	)
	(arc
		(start 79.185516 -80.75549)
		(mid 78.991666 -80.69914)
		(end 78.849982 -80.555338)
		(width 0.0889)
		(layer "In11.Cu")
		(net "PD_PIROM_CPU1_ADDR1")
	)
	(arc
		(start 71.452486 -80.259936)
		(mid 71.167062 -80.343403)
		(end 70.958456 -80.555338)
		(width 0.0889)
		(layer "In11.Cu")
		(net "PD_PIROM_CPU1_ADDR1")
	)
	(arc
		(start 76.274676 -79.069438)
		(mid 76.067672 -78.858574)
		(end 75.784456 -78.77429)
		(width 0.0889)
		(layer "In11.Cu")
		(net "PD_PIROM_CPU1_ADDR1")
	)
	(arc
		(start 80.567022 -81.545938)
		(mid 80.358414 -81.334006)
		(end 80.072992 -81.250536)
		(width 0.0889)
		(layer "In11.Cu")
		(net "PD_PIROM_CPU1_ADDR1")
	)
	(arc
		(start 71.816976 -80.060038)
		(mid 71.676897 -80.202774)
		(end 71.485252 -80.259936)
		(width 0.0889)
		(layer "In11.Cu")
		(net "PD_PIROM_CPU1_ADDR1")
	)
	(arc
		(start 90.869008 -88.480138)
		(mid 90.6604 -88.268206)
		(end 90.374978 -88.184736)
		(width 0.0889)
		(layer "In11.Cu")
		(net "PD_PIROM_CPU1_ADDR1")
	)
	(arc
		(start 84.001102 -83.527138)
		(mid 83.792494 -83.315206)
		(end 83.507072 -83.231736)
		(width 0.0889)
		(layer "In11.Cu")
		(net "PD_PIROM_CPU1_ADDR1")
	)
	(arc
		(start 87.435182 -85.508338)
		(mid 87.226574 -85.296406)
		(end 86.941152 -85.212936)
		(width 0.0889)
		(layer "In11.Cu")
		(net "PD_PIROM_CPU1_ADDR1")
	)
	(arc
		(start 70.958456 -80.555338)
		(mid 70.816773 -80.699142)
		(end 70.622922 -80.75549)
		(width 0.0889)
		(layer "In11.Cu")
		(net "PD_PIROM_CPU1_ADDR1")
	)
	(arc
		(start 73.169526 -79.269336)
		(mid 72.884102 -79.352803)
		(end 72.675496 -79.564738)
		(width 0.0889)
		(layer "In11.Cu")
		(net "PD_PIROM_CPU1_ADDR1")
	)
	(arc
		(start 83.471258 -83.231736)
		(mid 83.281329 -83.173866)
		(end 83.142582 -83.031838)
		(width 0.0889)
		(layer "In11.Cu")
		(net "PD_PIROM_CPU1_ADDR1")
	)
	(arc
		(start 77.46873 -79.76489)
		(mid 77.27488 -79.70854)
		(end 77.133196 -79.564738)
		(width 0.0889)
		(layer "In11.Cu")
		(net "PD_PIROM_CPU1_ADDR1")
	)
	(arc
		(start 90.342212 -88.184736)
		(mid 90.15057 -88.12757)
		(end 90.010488 -87.984838)
		(width 0.0889)
		(layer "In11.Cu")
		(net "PD_PIROM_CPU1_ADDR1")
	)
	(arc
		(start 86.053676 -84.71789)
		(mid 85.859826 -84.66154)
		(end 85.718142 -84.517738)
		(width 0.0889)
		(layer "In11.Cu")
		(net "PD_PIROM_CPU1_ADDR1")
	)
	(arc
		(start 81.425542 -82.041238)
		(mid 81.218538 -81.830374)
		(end 80.935322 -81.74609)
		(width 0.0889)
		(layer "In11.Cu")
		(net "PD_PIROM_CPU1_ADDR1")
	)
	(arc
		(start 70.590156 -80.75549)
		(mid 70.306939 -80.839771)
		(end 70.099936 -81.050638)
		(width 0.0889)
		(layer "In11.Cu")
		(net "PD_PIROM_CPU1_ADDR1")
	)
	(arc
		(start 84.336636 -83.72729)
		(mid 84.142786 -83.67094)
		(end 84.001102 -83.527138)
		(width 0.0889)
		(layer "In11.Cu")
		(net "PD_PIROM_CPU1_ADDR1")
	)
	(segment
		(start 258.50469 -88.28024)
		(end 257.93319 -88.28024)
		(width 0.10795)
		(layer "F.Cu")
		(net "PD_PIROM_CPU0_ADDR2")
	)
	(via
		(at 257.93319 -88.28024)
		(size 0.508)
		(drill 0.254)
		(layers "F.Cu" "B.Cu")
		(net "PD_PIROM_CPU0_ADDR2")
	)
	(via
		(at 195.09232 -106.37012)
		(size 0.508)
		(drill 0.254)
		(layers "F.Cu" "B.Cu")
		(net "PD_PIROM_CPU0_ADDR2")
	)
	(segment
		(start 195.240402 -106.222038)
		(end 195.09232 -106.37012)
		(width 0.10795)
		(layer "B.Cu")
		(net "PD_PIROM_CPU0_ADDR2")
	)
	(segment
		(start 195.240402 -104.454198)
		(end 195.240402 -106.222038)
		(width 0.10795)
		(layer "B.Cu")
		(net "PD_PIROM_CPU0_ADDR2")
	)
	(segment
		(start 195.4784 -104.2162)
		(end 195.240402 -104.454198)
		(width 0.10795)
		(layer "B.Cu")
		(net "PD_PIROM_CPU0_ADDR2")
	)
	(segment
		(start 195.4784 -103.5304)
		(end 195.4784 -104.2162)
		(width 0.10795)
		(layer "B.Cu")
		(net "PD_PIROM_CPU0_ADDR2")
	)
	(segment
		(start 202.27036 -106.84002)
		(end 203.759816 -106.84002)
		(width 0.089408)
		(layer "In4.Cu")
		(net "PD_PIROM_CPU0_ADDR2")
	)
	(segment
		(start 256.19837 -88.87079)
		(end 256.23393 -88.87079)
		(width 0.0889)
		(layer "In4.Cu")
		(net "PD_PIROM_CPU0_ADDR2")
	)
	(segment
		(start 238.176562 -79.459836)
		(end 238.198914 -79.459836)
		(width 0.0889)
		(layer "In4.Cu")
		(net "PD_PIROM_CPU0_ADDR2")
	)
	(segment
		(start 227.638356 -79.888588)
		(end 233.231436 -79.888588)
		(width 0.089408)
		(layer "In4.Cu")
		(net "PD_PIROM_CPU0_ADDR2")
	)
	(segment
		(start 251.411994 -84.517738)
		(end 251.405644 -84.528406)
		(width 0.0889)
		(layer "In4.Cu")
		(net "PD_PIROM_CPU0_ADDR2")
	)
	(segment
		(start 203.759816 -106.84002)
		(end 212.060028 -98.539808)
		(width 0.089408)
		(layer "In4.Cu")
		(net "PD_PIROM_CPU0_ADDR2")
	)
	(segment
		(start 251.043694 -82.92719)
		(end 251.07646 -82.92719)
		(width 0.0889)
		(layer "In4.Cu")
		(net "PD_PIROM_CPU0_ADDR2")
	)
	(segment
		(start 200.063608 -109.046772)
		(end 202.27036 -106.84002)
		(width 0.089408)
		(layer "In4.Cu")
		(net "PD_PIROM_CPU0_ADDR2")
	)
	(segment
		(start 251.411994 -83.527138)
		(end 251.405644 -83.537806)
		(width 0.0889)
		(layer "In4.Cu")
		(net "PD_PIROM_CPU0_ADDR2")
	)
	(segment
		(start 239.883188 -80.450436)
		(end 239.926368 -80.450436)
		(width 0.0889)
		(layer "In4.Cu")
		(net "PD_PIROM_CPU0_ADDR2")
	)
	(segment
		(start 197.768972 -109.046772)
		(end 200.063608 -109.046772)
		(width 0.089408)
		(layer "In4.Cu")
		(net "PD_PIROM_CPU0_ADDR2")
	)
	(segment
		(start 244.179344 -80.94599)
		(end 244.214904 -80.94599)
		(width 0.0889)
		(layer "In4.Cu")
		(net "PD_PIROM_CPU0_ADDR2")
	)
	(segment
		(start 249.330464 -81.93659)
		(end 249.36323 -81.93659)
		(width 0.0889)
		(layer "In4.Cu")
		(net "PD_PIROM_CPU0_ADDR2")
	)
	(segment
		(start 252.764544 -86.88959)
		(end 252.79731 -86.88959)
		(width 0.0889)
		(layer "In4.Cu")
		(net "PD_PIROM_CPU0_ADDR2")
	)
	(segment
		(start 240.748312 -79.95539)
		(end 240.778284 -79.95539)
		(width 0.0889)
		(layer "In4.Cu")
		(net "PD_PIROM_CPU0_ADDR2")
	)
	(segment
		(start 242.823492 -80.1497)
		(end 242.826794 -80.155542)
		(width 0.0889)
		(layer "In4.Cu")
		(net "PD_PIROM_CPU0_ADDR2")
	)
	(segment
		(start 243.313712 -80.450436)
		(end 243.34978 -80.450436)
		(width 0.0889)
		(layer "In4.Cu")
		(net "PD_PIROM_CPU0_ADDR2")
	)
	(segment
		(start 251.41682 -84.509102)
		(end 251.411994 -84.517738)
		(width 0.0889)
		(layer "In4.Cu")
		(net "PD_PIROM_CPU0_ADDR2")
	)
	(segment
		(start 216.436448 -91.090496)
		(end 227.638356 -79.888588)
		(width 0.089408)
		(layer "In4.Cu")
		(net "PD_PIROM_CPU0_ADDR2")
	)
	(segment
		(start 212.060028 -96.842834)
		(end 216.436448 -92.466414)
		(width 0.089408)
		(layer "In4.Cu")
		(net "PD_PIROM_CPU0_ADDR2")
	)
	(segment
		(start 235.594398 -79.95539)
		(end 235.629958 -79.95539)
		(width 0.0889)
		(layer "In4.Cu")
		(net "PD_PIROM_CPU0_ADDR2")
	)
	(segment
		(start 242.465352 -79.95539)
		(end 242.480338 -79.95539)
		(width 0.0889)
		(layer "In4.Cu")
		(net "PD_PIROM_CPU0_ADDR2")
	)
	(segment
		(start 253.619254 -87.384636)
		(end 253.640844 -87.384636)
		(width 0.0889)
		(layer "In4.Cu")
		(net "PD_PIROM_CPU0_ADDR2")
	)
	(segment
		(start 195.09232 -106.37012)
		(end 197.768972 -109.046772)
		(width 0.089408)
		(layer "In4.Cu")
		(net "PD_PIROM_CPU0_ADDR2")
	)
	(segment
		(start 233.231436 -79.888588)
		(end 234.12958 -79.888588)
		(width 0.0889)
		(layer "In4.Cu")
		(net "PD_PIROM_CPU0_ADDR2")
	)
	(segment
		(start 237.311438 -79.95539)
		(end 237.346998 -79.95539)
		(width 0.0889)
		(layer "In4.Cu")
		(net "PD_PIROM_CPU0_ADDR2")
	)
	(segment
		(start 253.983998 -87.578946)
		(end 253.9873 -87.584788)
		(width 0.0889)
		(layer "In4.Cu")
		(net "PD_PIROM_CPU0_ADDR2")
	)
	(segment
		(start 234.12958 -79.888588)
		(end 234.558332 -79.459836)
		(width 0.0889)
		(layer "In4.Cu")
		(net "PD_PIROM_CPU0_ADDR2")
	)
	(segment
		(start 239.028478 -79.95539)
		(end 239.061244 -79.95539)
		(width 0.0889)
		(layer "In4.Cu")
		(net "PD_PIROM_CPU0_ADDR2")
	)
	(segment
		(start 250.19381 -82.43189)
		(end 250.21794 -82.43189)
		(width 0.0889)
		(layer "In4.Cu")
		(net "PD_PIROM_CPU0_ADDR2")
	)
	(segment
		(start 256.650744 -88.65235)
		(end 256.780538 -88.47582)
		(width 0.0889)
		(layer "In4.Cu")
		(net "PD_PIROM_CPU0_ADDR2")
	)
	(segment
		(start 212.060028 -98.539808)
		(end 212.060028 -96.842834)
		(width 0.089408)
		(layer "In4.Cu")
		(net "PD_PIROM_CPU0_ADDR2")
	)
	(segment
		(start 216.436448 -92.466414)
		(end 216.436448 -91.090496)
		(width 0.089408)
		(layer "In4.Cu")
		(net "PD_PIROM_CPU0_ADDR2")
	)
	(segment
		(start 234.558332 -79.459836)
		(end 234.764834 -79.459836)
		(width 0.0889)
		(layer "In4.Cu")
		(net "PD_PIROM_CPU0_ADDR2")
	)
	(segment
		(start 247.613424 -80.94599)
		(end 247.64619 -80.94599)
		(width 0.0889)
		(layer "In4.Cu")
		(net "PD_PIROM_CPU0_ADDR2")
	)
	(segment
		(start 245.044468 -80.450436)
		(end 245.077234 -80.450436)
		(width 0.0889)
		(layer "In4.Cu")
		(net "PD_PIROM_CPU0_ADDR2")
	)
	(segment
		(start 248.468134 -81.441036)
		(end 248.5009 -81.441036)
		(width 0.0889)
		(layer "In4.Cu")
		(net "PD_PIROM_CPU0_ADDR2")
	)
	(segment
		(start 246.751094 -80.450436)
		(end 246.78386 -80.450436)
		(width 0.0889)
		(layer "In4.Cu")
		(net "PD_PIROM_CPU0_ADDR2")
	)
	(segment
		(start 245.899178 -79.95539)
		(end 245.92915 -79.95539)
		(width 0.0889)
		(layer "In4.Cu")
		(net "PD_PIROM_CPU0_ADDR2")
	)
	(segment
		(start 255.33604 -88.375236)
		(end 255.368806 -88.375236)
		(width 0.0889)
		(layer "In4.Cu")
		(net "PD_PIROM_CPU0_ADDR2")
	)
	(segment
		(start 251.411994 -85.508338)
		(end 251.405644 -85.519006)
		(width 0.0889)
		(layer "In4.Cu")
		(net "PD_PIROM_CPU0_ADDR2")
	)
	(segment
		(start 257.167126 -88.28024)
		(end 257.93319 -88.28024)
		(width 0.0889)
		(layer "In4.Cu")
		(net "PD_PIROM_CPU0_ADDR2")
	)
	(segment
		(start 254.48133 -87.88019)
		(end 254.514096 -87.88019)
		(width 0.0889)
		(layer "In4.Cu")
		(net "PD_PIROM_CPU0_ADDR2")
	)
	(segment
		(start 251.41682 -85.499702)
		(end 251.411994 -85.508338)
		(width 0.0889)
		(layer "In4.Cu")
		(net "PD_PIROM_CPU0_ADDR2")
	)
	(segment
		(start 236.459522 -79.459836)
		(end 236.481874 -79.459836)
		(width 0.0889)
		(layer "In4.Cu")
		(net "PD_PIROM_CPU0_ADDR2")
	)
	(segment
		(start 251.902214 -86.394036)
		(end 251.93498 -86.394036)
		(width 0.0889)
		(layer "In4.Cu")
		(net "PD_PIROM_CPU0_ADDR2")
	)
	(arc
		(start 246.260874 -80.155288)
		(mid 246.467878 -80.366152)
		(end 246.751094 -80.450436)
		(width 0.0889)
		(layer "In4.Cu")
		(net "PD_PIROM_CPU0_ADDR2")
	)
	(arc
		(start 247.64619 -80.94599)
		(mid 247.837832 -81.003156)
		(end 247.977914 -81.145888)
		(width 0.0889)
		(layer "In4.Cu")
		(net "PD_PIROM_CPU0_ADDR2")
	)
	(arc
		(start 242.133628 -80.155288)
		(mid 242.273707 -80.012552)
		(end 242.465352 -79.95539)
		(width 0.0889)
		(layer "In4.Cu")
		(net "PD_PIROM_CPU0_ADDR2")
	)
	(arc
		(start 251.405644 -83.537806)
		(mid 251.332846 -83.828569)
		(end 251.411994 -84.117688)
		(width 0.0889)
		(layer "In4.Cu")
		(net "PD_PIROM_CPU0_ADDR2")
	)
	(arc
		(start 240.778284 -79.95539)
		(mid 240.969926 -80.012556)
		(end 241.110008 -80.155288)
		(width 0.0889)
		(layer "In4.Cu")
		(net "PD_PIROM_CPU0_ADDR2")
	)
	(arc
		(start 248.836434 -81.641188)
		(mid 249.045042 -81.85312)
		(end 249.330464 -81.93659)
		(width 0.0889)
		(layer "In4.Cu")
		(net "PD_PIROM_CPU0_ADDR2")
	)
	(arc
		(start 249.36323 -81.93659)
		(mid 249.554872 -81.993756)
		(end 249.694954 -82.136488)
		(width 0.0889)
		(layer "In4.Cu")
		(net "PD_PIROM_CPU0_ADDR2")
	)
	(arc
		(start 251.411994 -84.117688)
		(mid 251.465464 -84.312751)
		(end 251.41682 -84.509102)
		(width 0.0889)
		(layer "In4.Cu")
		(net "PD_PIROM_CPU0_ADDR2")
	)
	(arc
		(start 245.077234 -80.450436)
		(mid 245.360451 -80.366155)
		(end 245.567454 -80.155288)
		(width 0.0889)
		(layer "In4.Cu")
		(net "PD_PIROM_CPU0_ADDR2")
	)
	(arc
		(start 236.123988 -79.659988)
		(mid 236.265671 -79.516184)
		(end 236.459522 -79.459836)
		(width 0.0889)
		(layer "In4.Cu")
		(net "PD_PIROM_CPU0_ADDR2")
	)
	(arc
		(start 253.640844 -87.384636)
		(mid 253.838005 -87.436595)
		(end 253.983998 -87.578946)
		(width 0.0889)
		(layer "In4.Cu")
		(net "PD_PIROM_CPU0_ADDR2")
	)
	(arc
		(start 236.481874 -79.459836)
		(mid 236.675724 -79.516186)
		(end 236.817408 -79.659988)
		(width 0.0889)
		(layer "In4.Cu")
		(net "PD_PIROM_CPU0_ADDR2")
	)
	(arc
		(start 255.368806 -88.375236)
		(mid 255.562656 -88.431586)
		(end 255.70434 -88.575388)
		(width 0.0889)
		(layer "In4.Cu")
		(net "PD_PIROM_CPU0_ADDR2")
	)
	(arc
		(start 235.629958 -79.95539)
		(mid 235.915382 -79.871923)
		(end 236.123988 -79.659988)
		(width 0.0889)
		(layer "In4.Cu")
		(net "PD_PIROM_CPU0_ADDR2")
	)
	(arc
		(start 256.780538 -88.47582)
		(mid 256.950503 -88.331884)
		(end 257.167126 -88.28024)
		(width 0.0889)
		(layer "In4.Cu")
		(net "PD_PIROM_CPU0_ADDR2")
	)
	(arc
		(start 238.198914 -79.459836)
		(mid 238.392764 -79.516186)
		(end 238.534448 -79.659988)
		(width 0.0889)
		(layer "In4.Cu")
		(net "PD_PIROM_CPU0_ADDR2")
	)
	(arc
		(start 235.100368 -79.659988)
		(mid 235.308976 -79.87192)
		(end 235.594398 -79.95539)
		(width 0.0889)
		(layer "In4.Cu")
		(net "PD_PIROM_CPU0_ADDR2")
	)
	(arc
		(start 237.841028 -79.659988)
		(mid 237.982711 -79.516184)
		(end 238.176562 -79.459836)
		(width 0.0889)
		(layer "In4.Cu")
		(net "PD_PIROM_CPU0_ADDR2")
	)
	(arc
		(start 254.84582 -88.080088)
		(mid 255.052824 -88.290952)
		(end 255.33604 -88.375236)
		(width 0.0889)
		(layer "In4.Cu")
		(net "PD_PIROM_CPU0_ADDR2")
	)
	(arc
		(start 243.34978 -80.450436)
		(mid 243.54363 -80.506786)
		(end 243.685314 -80.650588)
		(width 0.0889)
		(layer "In4.Cu")
		(net "PD_PIROM_CPU0_ADDR2")
	)
	(arc
		(start 238.534448 -79.659988)
		(mid 238.743056 -79.87192)
		(end 239.028478 -79.95539)
		(width 0.0889)
		(layer "In4.Cu")
		(net "PD_PIROM_CPU0_ADDR2")
	)
	(arc
		(start 247.119394 -80.650588)
		(mid 247.328002 -80.86252)
		(end 247.613424 -80.94599)
		(width 0.0889)
		(layer "In4.Cu")
		(net "PD_PIROM_CPU0_ADDR2")
	)
	(arc
		(start 247.977914 -81.145888)
		(mid 248.184918 -81.356752)
		(end 248.468134 -81.441036)
		(width 0.0889)
		(layer "In4.Cu")
		(net "PD_PIROM_CPU0_ADDR2")
	)
	(arc
		(start 251.411994 -86.098888)
		(mid 251.618998 -86.309752)
		(end 251.902214 -86.394036)
		(width 0.0889)
		(layer "In4.Cu")
		(net "PD_PIROM_CPU0_ADDR2")
	)
	(arc
		(start 255.70434 -88.575388)
		(mid 255.912948 -88.78732)
		(end 256.19837 -88.87079)
		(width 0.0889)
		(layer "In4.Cu")
		(net "PD_PIROM_CPU0_ADDR2")
	)
	(arc
		(start 239.392968 -80.155288)
		(mid 239.599972 -80.366152)
		(end 239.883188 -80.450436)
		(width 0.0889)
		(layer "In4.Cu")
		(net "PD_PIROM_CPU0_ADDR2")
	)
	(arc
		(start 236.817408 -79.659988)
		(mid 237.026016 -79.87192)
		(end 237.311438 -79.95539)
		(width 0.0889)
		(layer "In4.Cu")
		(net "PD_PIROM_CPU0_ADDR2")
	)
	(arc
		(start 252.79731 -86.88959)
		(mid 252.988952 -86.946756)
		(end 253.129034 -87.089488)
		(width 0.0889)
		(layer "In4.Cu")
		(net "PD_PIROM_CPU0_ADDR2")
	)
	(arc
		(start 244.708934 -80.650588)
		(mid 244.850617 -80.506784)
		(end 245.044468 -80.450436)
		(width 0.0889)
		(layer "In4.Cu")
		(net "PD_PIROM_CPU0_ADDR2")
	)
	(arc
		(start 251.411994 -85.108288)
		(mid 251.465464 -85.303351)
		(end 251.41682 -85.499702)
		(width 0.0889)
		(layer "In4.Cu")
		(net "PD_PIROM_CPU0_ADDR2")
	)
	(arc
		(start 242.480338 -79.95539)
		(mid 242.677499 -80.007349)
		(end 242.823492 -80.1497)
		(width 0.0889)
		(layer "In4.Cu")
		(net "PD_PIROM_CPU0_ADDR2")
	)
	(arc
		(start 253.9873 -87.584788)
		(mid 254.195908 -87.79672)
		(end 254.48133 -87.88019)
		(width 0.0889)
		(layer "In4.Cu")
		(net "PD_PIROM_CPU0_ADDR2")
	)
	(arc
		(start 245.567454 -80.155288)
		(mid 245.707533 -80.012552)
		(end 245.899178 -79.95539)
		(width 0.0889)
		(layer "In4.Cu")
		(net "PD_PIROM_CPU0_ADDR2")
	)
	(arc
		(start 251.93498 -86.394036)
		(mid 252.12883 -86.450386)
		(end 252.270514 -86.594188)
		(width 0.0889)
		(layer "In4.Cu")
		(net "PD_PIROM_CPU0_ADDR2")
	)
	(arc
		(start 250.21794 -82.43189)
		(mid 250.41179 -82.48824)
		(end 250.553474 -82.632042)
		(width 0.0889)
		(layer "In4.Cu")
		(net "PD_PIROM_CPU0_ADDR2")
	)
	(arc
		(start 241.110008 -80.155288)
		(mid 241.621818 -80.450827)
		(end 242.133628 -80.155288)
		(width 0.0889)
		(layer "In4.Cu")
		(net "PD_PIROM_CPU0_ADDR2")
	)
	(arc
		(start 239.926368 -80.450436)
		(mid 240.209585 -80.366155)
		(end 240.416588 -80.155288)
		(width 0.0889)
		(layer "In4.Cu")
		(net "PD_PIROM_CPU0_ADDR2")
	)
	(arc
		(start 242.826794 -80.155542)
		(mid 243.032415 -80.365465)
		(end 243.313712 -80.450436)
		(width 0.0889)
		(layer "In4.Cu")
		(net "PD_PIROM_CPU0_ADDR2")
	)
	(arc
		(start 243.685314 -80.650588)
		(mid 243.893922 -80.86252)
		(end 244.179344 -80.94599)
		(width 0.0889)
		(layer "In4.Cu")
		(net "PD_PIROM_CPU0_ADDR2")
	)
	(arc
		(start 253.129034 -87.089488)
		(mid 253.336038 -87.300352)
		(end 253.619254 -87.384636)
		(width 0.0889)
		(layer "In4.Cu")
		(net "PD_PIROM_CPU0_ADDR2")
	)
	(arc
		(start 251.405644 -85.519006)
		(mid 251.332846 -85.809769)
		(end 251.411994 -86.098888)
		(width 0.0889)
		(layer "In4.Cu")
		(net "PD_PIROM_CPU0_ADDR2")
	)
	(arc
		(start 234.764834 -79.459836)
		(mid 234.958684 -79.516186)
		(end 235.100368 -79.659988)
		(width 0.0889)
		(layer "In4.Cu")
		(net "PD_PIROM_CPU0_ADDR2")
	)
	(arc
		(start 244.214904 -80.94599)
		(mid 244.500328 -80.862523)
		(end 244.708934 -80.650588)
		(width 0.0889)
		(layer "In4.Cu")
		(net "PD_PIROM_CPU0_ADDR2")
	)
	(arc
		(start 251.07646 -82.92719)
		(mid 251.27031 -82.98354)
		(end 251.411994 -83.127342)
		(width 0.0889)
		(layer "In4.Cu")
		(net "PD_PIROM_CPU0_ADDR2")
	)
	(arc
		(start 256.23393 -88.87079)
		(mid 256.467556 -88.809663)
		(end 256.650744 -88.65235)
		(width 0.0889)
		(layer "In4.Cu")
		(net "PD_PIROM_CPU0_ADDR2")
	)
	(arc
		(start 245.92915 -79.95539)
		(mid 246.120792 -80.012556)
		(end 246.260874 -80.155288)
		(width 0.0889)
		(layer "In4.Cu")
		(net "PD_PIROM_CPU0_ADDR2")
	)
	(arc
		(start 240.416588 -80.155288)
		(mid 240.556667 -80.012552)
		(end 240.748312 -79.95539)
		(width 0.0889)
		(layer "In4.Cu")
		(net "PD_PIROM_CPU0_ADDR2")
	)
	(arc
		(start 254.514096 -87.88019)
		(mid 254.705738 -87.937356)
		(end 254.84582 -88.080088)
		(width 0.0889)
		(layer "In4.Cu")
		(net "PD_PIROM_CPU0_ADDR2")
	)
	(arc
		(start 248.5009 -81.441036)
		(mid 248.69475 -81.497386)
		(end 248.836434 -81.641188)
		(width 0.0889)
		(layer "In4.Cu")
		(net "PD_PIROM_CPU0_ADDR2")
	)
	(arc
		(start 249.694954 -82.136488)
		(mid 249.905667 -82.349567)
		(end 250.19381 -82.43189)
		(width 0.0889)
		(layer "In4.Cu")
		(net "PD_PIROM_CPU0_ADDR2")
	)
	(arc
		(start 251.405644 -84.528406)
		(mid 251.332846 -84.819169)
		(end 251.411994 -85.108288)
		(width 0.0889)
		(layer "In4.Cu")
		(net "PD_PIROM_CPU0_ADDR2")
	)
	(arc
		(start 250.553474 -82.632042)
		(mid 250.760478 -82.842906)
		(end 251.043694 -82.92719)
		(width 0.0889)
		(layer "In4.Cu")
		(net "PD_PIROM_CPU0_ADDR2")
	)
	(arc
		(start 239.061244 -79.95539)
		(mid 239.252886 -80.012556)
		(end 239.392968 -80.155288)
		(width 0.0889)
		(layer "In4.Cu")
		(net "PD_PIROM_CPU0_ADDR2")
	)
	(arc
		(start 251.411994 -83.127342)
		(mid 251.465493 -83.32724)
		(end 251.411994 -83.527138)
		(width 0.0889)
		(layer "In4.Cu")
		(net "PD_PIROM_CPU0_ADDR2")
	)
	(arc
		(start 246.78386 -80.450436)
		(mid 246.97771 -80.506786)
		(end 247.119394 -80.650588)
		(width 0.0889)
		(layer "In4.Cu")
		(net "PD_PIROM_CPU0_ADDR2")
	)
	(arc
		(start 252.270514 -86.594188)
		(mid 252.479122 -86.80612)
		(end 252.764544 -86.88959)
		(width 0.0889)
		(layer "In4.Cu")
		(net "PD_PIROM_CPU0_ADDR2")
	)
	(arc
		(start 237.346998 -79.95539)
		(mid 237.632422 -79.871923)
		(end 237.841028 -79.659988)
		(width 0.0889)
		(layer "In4.Cu")
		(net "PD_PIROM_CPU0_ADDR2")
	)
	(segment
		(start 257.64617 -87.784686)
		(end 257.07467 -87.784686)
		(width 0.10795)
		(layer "F.Cu")
		(net "PD_PIROM_CPU0_ADDR1")
	)
	(via
		(at 257.07467 -87.784686)
		(size 0.508)
		(drill 0.254)
		(layers "F.Cu" "B.Cu")
		(net "PD_PIROM_CPU0_ADDR1")
	)
	(via
		(at 193.819526 -105.268014)
		(size 0.508)
		(drill 0.254)
		(layers "F.Cu" "B.Cu")
		(net "PD_PIROM_CPU0_ADDR1")
	)
	(segment
		(start 193.819526 -105.268014)
		(end 194.6402 -104.44734)
		(width 0.10795)
		(layer "B.Cu")
		(net "PD_PIROM_CPU0_ADDR1")
	)
	(segment
		(start 194.6402 -104.44734)
		(end 194.6402 -103.5558)
		(width 0.10795)
		(layer "B.Cu")
		(net "PD_PIROM_CPU0_ADDR1")
	)
	(segment
		(start 254.48133 -85.89899)
		(end 254.514096 -85.89899)
		(width 0.0889)
		(layer "In4.Cu")
		(net "PD_PIROM_CPU0_ADDR1")
	)
	(segment
		(start 237.311438 -77.97419)
		(end 237.346998 -77.97419)
		(width 0.0889)
		(layer "In4.Cu")
		(net "PD_PIROM_CPU0_ADDR1")
	)
	(segment
		(start 250.185174 -80.450436)
		(end 250.21794 -80.450436)
		(width 0.0889)
		(layer "In4.Cu")
		(net "PD_PIROM_CPU0_ADDR1")
	)
	(segment
		(start 247.613424 -78.96479)
		(end 247.64619 -78.96479)
		(width 0.0889)
		(layer "In4.Cu")
		(net "PD_PIROM_CPU0_ADDR1")
	)
	(segment
		(start 239.883188 -78.469236)
		(end 239.926368 -78.469236)
		(width 0.0889)
		(layer "In4.Cu")
		(net "PD_PIROM_CPU0_ADDR1")
	)
	(segment
		(start 249.330464 -79.95539)
		(end 249.36323 -79.95539)
		(width 0.0889)
		(layer "In4.Cu")
		(net "PD_PIROM_CPU0_ADDR1")
	)
	(segment
		(start 234.07878 -77.973174)
		(end 234.351068 -77.700886)
		(width 0.0889)
		(layer "In4.Cu")
		(net "PD_PIROM_CPU0_ADDR1")
	)
	(segment
		(start 194.354704 -104.732836)
		(end 195.057014 -104.732836)
		(width 0.089408)
		(layer "In4.Cu")
		(net "PD_PIROM_CPU0_ADDR1")
	)
	(segment
		(start 251.902214 -81.441036)
		(end 251.93498 -81.441036)
		(width 0.0889)
		(layer "In4.Cu")
		(net "PD_PIROM_CPU0_ADDR1")
	)
	(segment
		(start 253.983998 -85.597746)
		(end 253.9873 -85.603588)
		(width 0.0889)
		(layer "In4.Cu")
		(net "PD_PIROM_CPU0_ADDR1")
	)
	(segment
		(start 201.91222 -106.2482)
		(end 203.536804 -106.2482)
		(width 0.089408)
		(layer "In4.Cu")
		(net "PD_PIROM_CPU0_ADDR1")
	)
	(segment
		(start 233.449876 -77.973174)
		(end 234.07878 -77.973174)
		(width 0.0889)
		(layer "In4.Cu")
		(net "PD_PIROM_CPU0_ADDR1")
	)
	(segment
		(start 197.539102 -104.947212)
		(end 197.967854 -104.51846)
		(width 0.089408)
		(layer "In4.Cu")
		(net "PD_PIROM_CPU0_ADDR1")
	)
	(segment
		(start 207.79613 -96.149922)
		(end 209.131662 -94.81439)
		(width 0.089408)
		(layer "In4.Cu")
		(net "PD_PIROM_CPU0_ADDR1")
	)
	(segment
		(start 203.536804 -106.2482)
		(end 206.883 -102.902004)
		(width 0.089408)
		(layer "In4.Cu")
		(net "PD_PIROM_CPU0_ADDR1")
	)
	(segment
		(start 243.313712 -78.469236)
		(end 243.34978 -78.469236)
		(width 0.0889)
		(layer "In4.Cu")
		(net "PD_PIROM_CPU0_ADDR1")
	)
	(segment
		(start 253.129034 -84.517738)
		(end 253.122684 -84.528406)
		(width 0.0889)
		(layer "In4.Cu")
		(net "PD_PIROM_CPU0_ADDR1")
	)
	(segment
		(start 234.351068 -77.700886)
		(end 234.36453 -77.674978)
		(width 0.0889)
		(layer "In4.Cu")
		(net "PD_PIROM_CPU0_ADDR1")
	)
	(segment
		(start 216.297002 -90.283792)
		(end 227.574348 -79.006446)
		(width 0.089408)
		(layer "In4.Cu")
		(net "PD_PIROM_CPU0_ADDR1")
	)
	(segment
		(start 251.047504 -80.94599)
		(end 251.08027 -80.94599)
		(width 0.0889)
		(layer "In4.Cu")
		(net "PD_PIROM_CPU0_ADDR1")
	)
	(segment
		(start 248.468134 -79.459836)
		(end 248.5009 -79.459836)
		(width 0.0889)
		(layer "In4.Cu")
		(net "PD_PIROM_CPU0_ADDR1")
	)
	(segment
		(start 235.594398 -77.97419)
		(end 235.629958 -77.97419)
		(width 0.0889)
		(layer "In4.Cu")
		(net "PD_PIROM_CPU0_ADDR1")
	)
	(segment
		(start 234.57281 -77.478382)
		(end 234.573572 -77.478382)
		(width 0.0889)
		(layer "In4.Cu")
		(net "PD_PIROM_CPU0_ADDR1")
	)
	(segment
		(start 245.899178 -77.97419)
		(end 245.92915 -77.97419)
		(width 0.0889)
		(layer "In4.Cu")
		(net "PD_PIROM_CPU0_ADDR1")
	)
	(segment
		(start 245.044468 -78.469236)
		(end 245.077234 -78.469236)
		(width 0.0889)
		(layer "In4.Cu")
		(net "PD_PIROM_CPU0_ADDR1")
	)
	(segment
		(start 227.574348 -79.006446)
		(end 232.416604 -79.006446)
		(width 0.089408)
		(layer "In4.Cu")
		(net "PD_PIROM_CPU0_ADDR1")
	)
	(segment
		(start 209.131662 -94.81439)
		(end 212.635084 -94.81439)
		(width 0.089408)
		(layer "In4.Cu")
		(net "PD_PIROM_CPU0_ADDR1")
	)
	(segment
		(start 255.33604 -86.394036)
		(end 255.368806 -86.394036)
		(width 0.0889)
		(layer "In4.Cu")
		(net "PD_PIROM_CPU0_ADDR1")
	)
	(segment
		(start 195.27139 -104.947212)
		(end 197.539102 -104.947212)
		(width 0.089408)
		(layer "In4.Cu")
		(net "PD_PIROM_CPU0_ADDR1")
	)
	(segment
		(start 232.416604 -79.006446)
		(end 233.20883 -78.21422)
		(width 0.089408)
		(layer "In4.Cu")
		(net "PD_PIROM_CPU0_ADDR1")
	)
	(segment
		(start 207.79613 -100.840794)
		(end 207.79613 -96.149922)
		(width 0.089408)
		(layer "In4.Cu")
		(net "PD_PIROM_CPU0_ADDR1")
	)
	(segment
		(start 241.600228 -78.469236)
		(end 241.643408 -78.469236)
		(width 0.0889)
		(layer "In4.Cu")
		(net "PD_PIROM_CPU0_ADDR1")
	)
	(segment
		(start 253.129034 -83.527138)
		(end 253.122684 -83.537806)
		(width 0.0889)
		(layer "In4.Cu")
		(net "PD_PIROM_CPU0_ADDR1")
	)
	(segment
		(start 252.764544 -81.93659)
		(end 252.79731 -81.93659)
		(width 0.0889)
		(layer "In4.Cu")
		(net "PD_PIROM_CPU0_ADDR1")
	)
	(segment
		(start 244.179344 -78.96479)
		(end 244.214904 -78.96479)
		(width 0.0889)
		(layer "In4.Cu")
		(net "PD_PIROM_CPU0_ADDR1")
	)
	(segment
		(start 234.573572 -77.478382)
		(end 234.573826 -77.478636)
		(width 0.0889)
		(layer "In4.Cu")
		(net "PD_PIROM_CPU0_ADDR1")
	)
	(segment
		(start 212.635084 -94.81439)
		(end 213.4362 -94.013274)
		(width 0.089408)
		(layer "In4.Cu")
		(net "PD_PIROM_CPU0_ADDR1")
	)
	(segment
		(start 236.459522 -77.478636)
		(end 236.481874 -77.478636)
		(width 0.0889)
		(layer "In4.Cu")
		(net "PD_PIROM_CPU0_ADDR1")
	)
	(segment
		(start 242.823492 -78.1685)
		(end 242.826794 -78.174342)
		(width 0.0889)
		(layer "In4.Cu")
		(net "PD_PIROM_CPU0_ADDR1")
	)
	(segment
		(start 255.864614 -87.480902)
		(end 255.86944 -87.489538)
		(width 0.0889)
		(layer "In4.Cu")
		(net "PD_PIROM_CPU0_ADDR1")
	)
	(segment
		(start 234.573826 -77.478636)
		(end 234.764834 -77.478636)
		(width 0.0889)
		(layer "In4.Cu")
		(net "PD_PIROM_CPU0_ADDR1")
	)
	(segment
		(start 253.13386 -84.509102)
		(end 253.129034 -84.517738)
		(width 0.0889)
		(layer "In4.Cu")
		(net "PD_PIROM_CPU0_ADDR1")
	)
	(segment
		(start 213.4362 -94.013274)
		(end 213.4362 -91.8718)
		(width 0.089408)
		(layer "In4.Cu")
		(net "PD_PIROM_CPU0_ADDR1")
	)
	(segment
		(start 213.4362 -91.8718)
		(end 215.024208 -90.283792)
		(width 0.089408)
		(layer "In4.Cu")
		(net "PD_PIROM_CPU0_ADDR1")
	)
	(segment
		(start 195.057014 -104.732836)
		(end 195.27139 -104.947212)
		(width 0.089408)
		(layer "In4.Cu")
		(net "PD_PIROM_CPU0_ADDR1")
	)
	(segment
		(start 240.748312 -77.97419)
		(end 240.778284 -77.97419)
		(width 0.0889)
		(layer "In4.Cu")
		(net "PD_PIROM_CPU0_ADDR1")
	)
	(segment
		(start 242.465352 -77.97419)
		(end 242.480338 -77.97419)
		(width 0.0889)
		(layer "In4.Cu")
		(net "PD_PIROM_CPU0_ADDR1")
	)
	(segment
		(start 253.13386 -82.527902)
		(end 253.129034 -82.536538)
		(width 0.0889)
		(layer "In4.Cu")
		(net "PD_PIROM_CPU0_ADDR1")
	)
	(segment
		(start 206.883 -102.902004)
		(end 206.883 -101.753924)
		(width 0.089408)
		(layer "In4.Cu")
		(net "PD_PIROM_CPU0_ADDR1")
	)
	(segment
		(start 233.20883 -78.21422)
		(end 233.449876 -77.973174)
		(width 0.0889)
		(layer "In4.Cu")
		(net "PD_PIROM_CPU0_ADDR1")
	)
	(segment
		(start 206.883 -101.753924)
		(end 207.79613 -100.840794)
		(width 0.089408)
		(layer "In4.Cu")
		(net "PD_PIROM_CPU0_ADDR1")
	)
	(segment
		(start 193.819526 -105.268014)
		(end 194.354704 -104.732836)
		(width 0.089408)
		(layer "In4.Cu")
		(net "PD_PIROM_CPU0_ADDR1")
	)
	(segment
		(start 200.18248 -104.51846)
		(end 201.91222 -106.2482)
		(width 0.089408)
		(layer "In4.Cu")
		(net "PD_PIROM_CPU0_ADDR1")
	)
	(segment
		(start 253.619254 -85.403436)
		(end 253.640844 -85.403436)
		(width 0.0889)
		(layer "In4.Cu")
		(net "PD_PIROM_CPU0_ADDR1")
	)
	(segment
		(start 197.967854 -104.51846)
		(end 200.18248 -104.51846)
		(width 0.089408)
		(layer "In4.Cu")
		(net "PD_PIROM_CPU0_ADDR1")
	)
	(segment
		(start 239.028478 -77.97419)
		(end 239.061244 -77.97419)
		(width 0.0889)
		(layer "In4.Cu")
		(net "PD_PIROM_CPU0_ADDR1")
	)
	(segment
		(start 215.024208 -90.283792)
		(end 216.297002 -90.283792)
		(width 0.089408)
		(layer "In4.Cu")
		(net "PD_PIROM_CPU0_ADDR1")
	)
	(segment
		(start 246.751094 -78.469236)
		(end 246.78386 -78.469236)
		(width 0.0889)
		(layer "In4.Cu")
		(net "PD_PIROM_CPU0_ADDR1")
	)
	(arc
		(start 242.826794 -78.174342)
		(mid 243.032415 -78.384265)
		(end 243.313712 -78.469236)
		(width 0.0889)
		(layer "In4.Cu")
		(net "PD_PIROM_CPU0_ADDR1")
	)
	(arc
		(start 246.260874 -78.174088)
		(mid 246.467878 -78.384952)
		(end 246.751094 -78.469236)
		(width 0.0889)
		(layer "In4.Cu")
		(net "PD_PIROM_CPU0_ADDR1")
	)
	(arc
		(start 250.21794 -80.450436)
		(mid 250.41179 -80.506786)
		(end 250.553474 -80.650588)
		(width 0.0889)
		(layer "In4.Cu")
		(net "PD_PIROM_CPU0_ADDR1")
	)
	(arc
		(start 239.392968 -78.174088)
		(mid 239.599972 -78.384952)
		(end 239.883188 -78.469236)
		(width 0.0889)
		(layer "In4.Cu")
		(net "PD_PIROM_CPU0_ADDR1")
	)
	(arc
		(start 241.643408 -78.469236)
		(mid 241.926625 -78.384955)
		(end 242.133628 -78.174088)
		(width 0.0889)
		(layer "In4.Cu")
		(net "PD_PIROM_CPU0_ADDR1")
	)
	(arc
		(start 247.977914 -79.164688)
		(mid 248.184918 -79.375552)
		(end 248.468134 -79.459836)
		(width 0.0889)
		(layer "In4.Cu")
		(net "PD_PIROM_CPU0_ADDR1")
	)
	(arc
		(start 243.685314 -78.669388)
		(mid 243.893922 -78.88132)
		(end 244.179344 -78.96479)
		(width 0.0889)
		(layer "In4.Cu")
		(net "PD_PIROM_CPU0_ADDR1")
	)
	(arc
		(start 240.416588 -78.174088)
		(mid 240.556667 -78.031352)
		(end 240.748312 -77.97419)
		(width 0.0889)
		(layer "In4.Cu")
		(net "PD_PIROM_CPU0_ADDR1")
	)
	(arc
		(start 236.481874 -77.478636)
		(mid 236.675724 -77.534986)
		(end 236.817408 -77.678788)
		(width 0.0889)
		(layer "In4.Cu")
		(net "PD_PIROM_CPU0_ADDR1")
	)
	(arc
		(start 241.110008 -78.174088)
		(mid 241.317012 -78.384952)
		(end 241.600228 -78.469236)
		(width 0.0889)
		(layer "In4.Cu")
		(net "PD_PIROM_CPU0_ADDR1")
	)
	(arc
		(start 251.93498 -81.441036)
		(mid 252.12883 -81.497386)
		(end 252.270514 -81.641188)
		(width 0.0889)
		(layer "In4.Cu")
		(net "PD_PIROM_CPU0_ADDR1")
	)
	(arc
		(start 250.553474 -80.650588)
		(mid 250.762082 -80.86252)
		(end 251.047504 -80.94599)
		(width 0.0889)
		(layer "In4.Cu")
		(net "PD_PIROM_CPU0_ADDR1")
	)
	(arc
		(start 247.64619 -78.96479)
		(mid 247.837832 -79.021956)
		(end 247.977914 -79.164688)
		(width 0.0889)
		(layer "In4.Cu")
		(net "PD_PIROM_CPU0_ADDR1")
	)
	(arc
		(start 249.36323 -79.95539)
		(mid 249.554872 -80.012556)
		(end 249.694954 -80.155288)
		(width 0.0889)
		(layer "In4.Cu")
		(net "PD_PIROM_CPU0_ADDR1")
	)
	(arc
		(start 236.123988 -77.678788)
		(mid 236.265671 -77.534984)
		(end 236.459522 -77.478636)
		(width 0.0889)
		(layer "In4.Cu")
		(net "PD_PIROM_CPU0_ADDR1")
	)
	(arc
		(start 253.129034 -83.127342)
		(mid 253.182533 -83.32724)
		(end 253.129034 -83.527138)
		(width 0.0889)
		(layer "In4.Cu")
		(net "PD_PIROM_CPU0_ADDR1")
	)
	(arc
		(start 249.694954 -80.155288)
		(mid 249.901958 -80.366152)
		(end 250.185174 -80.450436)
		(width 0.0889)
		(layer "In4.Cu")
		(net "PD_PIROM_CPU0_ADDR1")
	)
	(arc
		(start 235.100368 -77.678788)
		(mid 235.308976 -77.89072)
		(end 235.594398 -77.97419)
		(width 0.0889)
		(layer "In4.Cu")
		(net "PD_PIROM_CPU0_ADDR1")
	)
	(arc
		(start 255.70434 -86.594188)
		(mid 255.817701 -86.90419)
		(end 255.819656 -87.234268)
		(width 0.0889)
		(layer "In4.Cu")
		(net "PD_PIROM_CPU0_ADDR1")
	)
	(arc
		(start 243.34978 -78.469236)
		(mid 243.54363 -78.525586)
		(end 243.685314 -78.669388)
		(width 0.0889)
		(layer "In4.Cu")
		(net "PD_PIROM_CPU0_ADDR1")
	)
	(arc
		(start 239.061244 -77.97419)
		(mid 239.252886 -78.031356)
		(end 239.392968 -78.174088)
		(width 0.0889)
		(layer "In4.Cu")
		(net "PD_PIROM_CPU0_ADDR1")
	)
	(arc
		(start 253.122684 -83.537806)
		(mid 253.049886 -83.828569)
		(end 253.129034 -84.117688)
		(width 0.0889)
		(layer "In4.Cu")
		(net "PD_PIROM_CPU0_ADDR1")
	)
	(arc
		(start 255.86944 -87.489538)
		(mid 256.011123 -87.633342)
		(end 256.204974 -87.68969)
		(width 0.0889)
		(layer "In4.Cu")
		(net "PD_PIROM_CPU0_ADDR1")
	)
	(arc
		(start 242.480338 -77.97419)
		(mid 242.677499 -78.026149)
		(end 242.823492 -78.1685)
		(width 0.0889)
		(layer "In4.Cu")
		(net "PD_PIROM_CPU0_ADDR1")
	)
	(arc
		(start 253.640844 -85.403436)
		(mid 253.838005 -85.455395)
		(end 253.983998 -85.597746)
		(width 0.0889)
		(layer "In4.Cu")
		(net "PD_PIROM_CPU0_ADDR1")
	)
	(arc
		(start 253.129034 -85.108288)
		(mid 253.336038 -85.319152)
		(end 253.619254 -85.403436)
		(width 0.0889)
		(layer "In4.Cu")
		(net "PD_PIROM_CPU0_ADDR1")
	)
	(arc
		(start 253.129034 -84.117688)
		(mid 253.182504 -84.312751)
		(end 253.13386 -84.509102)
		(width 0.0889)
		(layer "In4.Cu")
		(net "PD_PIROM_CPU0_ADDR1")
	)
	(arc
		(start 245.077234 -78.469236)
		(mid 245.360451 -78.384955)
		(end 245.567454 -78.174088)
		(width 0.0889)
		(layer "In4.Cu")
		(net "PD_PIROM_CPU0_ADDR1")
	)
	(arc
		(start 247.119394 -78.669388)
		(mid 247.328002 -78.88132)
		(end 247.613424 -78.96479)
		(width 0.0889)
		(layer "In4.Cu")
		(net "PD_PIROM_CPU0_ADDR1")
	)
	(arc
		(start 234.36453 -77.674978)
		(mid 234.452206 -77.559242)
		(end 234.57281 -77.478382)
		(width 0.0889)
		(layer "In4.Cu")
		(net "PD_PIROM_CPU0_ADDR1")
	)
	(arc
		(start 255.819656 -87.234268)
		(mid 255.822336 -87.361193)
		(end 255.864614 -87.480902)
		(width 0.0889)
		(layer "In4.Cu")
		(net "PD_PIROM_CPU0_ADDR1")
	)
	(arc
		(start 239.926368 -78.469236)
		(mid 240.209585 -78.384955)
		(end 240.416588 -78.174088)
		(width 0.0889)
		(layer "In4.Cu")
		(net "PD_PIROM_CPU0_ADDR1")
	)
	(arc
		(start 240.778284 -77.97419)
		(mid 240.969926 -78.031356)
		(end 241.110008 -78.174088)
		(width 0.0889)
		(layer "In4.Cu")
		(net "PD_PIROM_CPU0_ADDR1")
	)
	(arc
		(start 245.92915 -77.97419)
		(mid 246.120792 -78.031356)
		(end 246.260874 -78.174088)
		(width 0.0889)
		(layer "In4.Cu")
		(net "PD_PIROM_CPU0_ADDR1")
	)
	(arc
		(start 251.08027 -80.94599)
		(mid 251.271912 -81.003156)
		(end 251.411994 -81.145888)
		(width 0.0889)
		(layer "In4.Cu")
		(net "PD_PIROM_CPU0_ADDR1")
	)
	(arc
		(start 242.133628 -78.174088)
		(mid 242.273707 -78.031352)
		(end 242.465352 -77.97419)
		(width 0.0889)
		(layer "In4.Cu")
		(net "PD_PIROM_CPU0_ADDR1")
	)
	(arc
		(start 244.214904 -78.96479)
		(mid 244.500328 -78.881323)
		(end 244.708934 -78.669388)
		(width 0.0889)
		(layer "In4.Cu")
		(net "PD_PIROM_CPU0_ADDR1")
	)
	(arc
		(start 253.9873 -85.603588)
		(mid 254.195908 -85.81552)
		(end 254.48133 -85.89899)
		(width 0.0889)
		(layer "In4.Cu")
		(net "PD_PIROM_CPU0_ADDR1")
	)
	(arc
		(start 236.817408 -77.678788)
		(mid 237.026016 -77.89072)
		(end 237.311438 -77.97419)
		(width 0.0889)
		(layer "In4.Cu")
		(net "PD_PIROM_CPU0_ADDR1")
	)
	(arc
		(start 252.79731 -81.93659)
		(mid 252.988952 -81.993756)
		(end 253.129034 -82.136488)
		(width 0.0889)
		(layer "In4.Cu")
		(net "PD_PIROM_CPU0_ADDR1")
	)
	(arc
		(start 253.122684 -84.528406)
		(mid 253.049886 -84.819169)
		(end 253.129034 -85.108288)
		(width 0.0889)
		(layer "In4.Cu")
		(net "PD_PIROM_CPU0_ADDR1")
	)
	(arc
		(start 253.129034 -82.536538)
		(mid 253.049903 -82.83194)
		(end 253.129034 -83.127342)
		(width 0.0889)
		(layer "In4.Cu")
		(net "PD_PIROM_CPU0_ADDR1")
	)
	(arc
		(start 248.836434 -79.659988)
		(mid 249.045042 -79.87192)
		(end 249.330464 -79.95539)
		(width 0.0889)
		(layer "In4.Cu")
		(net "PD_PIROM_CPU0_ADDR1")
	)
	(arc
		(start 253.129034 -82.136488)
		(mid 253.182504 -82.331551)
		(end 253.13386 -82.527902)
		(width 0.0889)
		(layer "In4.Cu")
		(net "PD_PIROM_CPU0_ADDR1")
	)
	(arc
		(start 245.567454 -78.174088)
		(mid 245.707533 -78.031352)
		(end 245.899178 -77.97419)
		(width 0.0889)
		(layer "In4.Cu")
		(net "PD_PIROM_CPU0_ADDR1")
	)
	(arc
		(start 252.270514 -81.641188)
		(mid 252.479122 -81.85312)
		(end 252.764544 -81.93659)
		(width 0.0889)
		(layer "In4.Cu")
		(net "PD_PIROM_CPU0_ADDR1")
	)
	(arc
		(start 254.84582 -86.098888)
		(mid 255.052824 -86.309752)
		(end 255.33604 -86.394036)
		(width 0.0889)
		(layer "In4.Cu")
		(net "PD_PIROM_CPU0_ADDR1")
	)
	(arc
		(start 237.346998 -77.97419)
		(mid 237.632422 -77.890723)
		(end 237.841028 -77.678788)
		(width 0.0889)
		(layer "In4.Cu")
		(net "PD_PIROM_CPU0_ADDR1")
	)
	(arc
		(start 246.78386 -78.469236)
		(mid 246.97771 -78.525586)
		(end 247.119394 -78.669388)
		(width 0.0889)
		(layer "In4.Cu")
		(net "PD_PIROM_CPU0_ADDR1")
	)
	(arc
		(start 237.841028 -77.678788)
		(mid 238.187738 -77.478477)
		(end 238.534448 -77.678788)
		(width 0.0889)
		(layer "In4.Cu")
		(net "PD_PIROM_CPU0_ADDR1")
	)
	(arc
		(start 248.5009 -79.459836)
		(mid 248.69475 -79.516186)
		(end 248.836434 -79.659988)
		(width 0.0889)
		(layer "In4.Cu")
		(net "PD_PIROM_CPU0_ADDR1")
	)
	(arc
		(start 254.514096 -85.89899)
		(mid 254.705738 -85.956156)
		(end 254.84582 -86.098888)
		(width 0.0889)
		(layer "In4.Cu")
		(net "PD_PIROM_CPU0_ADDR1")
	)
	(arc
		(start 235.629958 -77.97419)
		(mid 235.915382 -77.890723)
		(end 236.123988 -77.678788)
		(width 0.0889)
		(layer "In4.Cu")
		(net "PD_PIROM_CPU0_ADDR1")
	)
	(arc
		(start 256.204974 -87.68969)
		(mid 256.642408 -87.71351)
		(end 257.07467 -87.784686)
		(width 0.0889)
		(layer "In4.Cu")
		(net "PD_PIROM_CPU0_ADDR1")
	)
	(arc
		(start 244.708934 -78.669388)
		(mid 244.850617 -78.525584)
		(end 245.044468 -78.469236)
		(width 0.0889)
		(layer "In4.Cu")
		(net "PD_PIROM_CPU0_ADDR1")
	)
	(arc
		(start 255.368806 -86.394036)
		(mid 255.562656 -86.450386)
		(end 255.70434 -86.594188)
		(width 0.0889)
		(layer "In4.Cu")
		(net "PD_PIROM_CPU0_ADDR1")
	)
	(arc
		(start 238.534448 -77.678788)
		(mid 238.743056 -77.89072)
		(end 239.028478 -77.97419)
		(width 0.0889)
		(layer "In4.Cu")
		(net "PD_PIROM_CPU0_ADDR1")
	)
	(arc
		(start 251.411994 -81.145888)
		(mid 251.618998 -81.356752)
		(end 251.902214 -81.441036)
		(width 0.0889)
		(layer "In4.Cu")
		(net "PD_PIROM_CPU0_ADDR1")
	)
	(arc
		(start 234.764834 -77.478636)
		(mid 234.958684 -77.534986)
		(end 235.100368 -77.678788)
		(width 0.0889)
		(layer "In4.Cu")
		(net "PD_PIROM_CPU0_ADDR1")
	)
	(segment
		(start 256.78765 -87.28964)
		(end 256.21615 -87.28964)
		(width 0.10795)
		(layer "F.Cu")
		(net "PD_PIROM_CPU0_ADDR0")
	)
	(via
		(at 193.799206 -104.578912)
		(size 0.508)
		(drill 0.254)
		(layers "F.Cu" "B.Cu")
		(net "PD_PIROM_CPU0_ADDR0")
	)
	(via
		(at 256.21615 -87.28964)
		(size 0.508)
		(drill 0.254)
		(layers "F.Cu" "B.Cu")
		(net "PD_PIROM_CPU0_ADDR0")
	)
	(via
		(at 192.5701 -103.34752)
		(size 0.6604)
		(drill 0.3302)
		(layers "F.Cu" "B.Cu")
		(net "PD_PIROM_CPU0_ADDR0")
	)
	(segment
		(start 192.77838 -103.5558)
		(end 192.5701 -103.34752)
		(width 0.10795)
		(layer "B.Cu")
		(net "PD_PIROM_CPU0_ADDR0")
	)
	(segment
		(start 193.8528 -104.525318)
		(end 193.8528 -103.5558)
		(width 0.10795)
		(layer "B.Cu")
		(net "PD_PIROM_CPU0_ADDR0")
	)
	(segment
		(start 193.8528 -103.5558)
		(end 192.77838 -103.5558)
		(width 0.10795)
		(layer "B.Cu")
		(net "PD_PIROM_CPU0_ADDR0")
	)
	(segment
		(start 193.799206 -104.578912)
		(end 193.8528 -104.525318)
		(width 0.10795)
		(layer "B.Cu")
		(net "PD_PIROM_CPU0_ADDR0")
	)
	(segment
		(start 236.452918 -77.288136)
		(end 236.488478 -77.288136)
		(width 0.0889)
		(layer "In4.Cu")
		(net "PD_PIROM_CPU0_ADDR0")
	)
	(segment
		(start 240.741708 -77.78369)
		(end 240.784888 -77.78369)
		(width 0.0889)
		(layer "In4.Cu")
		(net "PD_PIROM_CPU0_ADDR0")
	)
	(segment
		(start 239.889792 -78.278736)
		(end 239.919764 -78.278736)
		(width 0.0889)
		(layer "In4.Cu")
		(net "PD_PIROM_CPU0_ADDR0")
	)
	(segment
		(start 197.762622 -104.327452)
		(end 200.261728 -104.327452)
		(width 0.089408)
		(layer "In4.Cu")
		(net "PD_PIROM_CPU0_ADDR0")
	)
	(segment
		(start 195.125594 -104.53116)
		(end 195.350638 -104.756204)
		(width 0.089408)
		(layer "In4.Cu")
		(net "PD_PIROM_CPU0_ADDR0")
	)
	(segment
		(start 197.33387 -104.756204)
		(end 197.762622 -104.327452)
		(width 0.089408)
		(layer "In4.Cu")
		(net "PD_PIROM_CPU0_ADDR0")
	)
	(segment
		(start 253.300484 -83.61172)
		(end 253.294134 -83.622388)
		(width 0.0889)
		(layer "In4.Cu")
		(net "PD_PIROM_CPU0_ADDR0")
	)
	(segment
		(start 253.300484 -84.60232)
		(end 253.294134 -84.612988)
		(width 0.0889)
		(layer "In4.Cu")
		(net "PD_PIROM_CPU0_ADDR0")
	)
	(segment
		(start 237.318042 -77.78369)
		(end 237.340394 -77.78369)
		(width 0.0889)
		(layer "In4.Cu")
		(net "PD_PIROM_CPU0_ADDR0")
	)
	(segment
		(start 253.294134 -83.622388)
		(end 253.289308 -83.631024)
		(width 0.0889)
		(layer "In4.Cu")
		(net "PD_PIROM_CPU0_ADDR0")
	)
	(segment
		(start 216.29878 -90.011758)
		(end 227.4951 -78.815438)
		(width 0.089408)
		(layer "In4.Cu")
		(net "PD_PIROM_CPU0_ADDR0")
	)
	(segment
		(start 193.846958 -104.53116)
		(end 195.125594 -104.53116)
		(width 0.089408)
		(layer "In4.Cu")
		(net "PD_PIROM_CPU0_ADDR0")
	)
	(segment
		(start 254.152654 -85.508338)
		(end 254.155956 -85.51418)
		(width 0.0889)
		(layer "In4.Cu")
		(net "PD_PIROM_CPU0_ADDR0")
	)
	(segment
		(start 245.892574 -77.78369)
		(end 245.935754 -77.78369)
		(width 0.0889)
		(layer "In4.Cu")
		(net "PD_PIROM_CPU0_ADDR0")
	)
	(segment
		(start 203.431902 -106.05262)
		(end 206.5528 -102.931722)
		(width 0.089408)
		(layer "In4.Cu")
		(net "PD_PIROM_CPU0_ADDR0")
	)
	(segment
		(start 239.035082 -77.78369)
		(end 239.067848 -77.78369)
		(width 0.0889)
		(layer "In4.Cu")
		(net "PD_PIROM_CPU0_ADDR0")
	)
	(segment
		(start 251.054108 -80.75549)
		(end 251.086874 -80.75549)
		(width 0.0889)
		(layer "In4.Cu")
		(net "PD_PIROM_CPU0_ADDR0")
	)
	(segment
		(start 207.580484 -100.665788)
		(end 207.580484 -95.97898)
		(width 0.089408)
		(layer "In4.Cu")
		(net "PD_PIROM_CPU0_ADDR0")
	)
	(segment
		(start 245.037864 -78.278736)
		(end 245.07063 -78.278736)
		(width 0.0889)
		(layer "In4.Cu")
		(net "PD_PIROM_CPU0_ADDR0")
	)
	(segment
		(start 253.625858 -85.212936)
		(end 253.658624 -85.212936)
		(width 0.0889)
		(layer "In4.Cu")
		(net "PD_PIROM_CPU0_ADDR0")
	)
	(segment
		(start 255.342644 -86.203536)
		(end 255.37541 -86.203536)
		(width 0.0889)
		(layer "In4.Cu")
		(net "PD_PIROM_CPU0_ADDR0")
	)
	(segment
		(start 206.5528 -102.931722)
		(end 206.5528 -101.693472)
		(width 0.089408)
		(layer "In4.Cu")
		(net "PD_PIROM_CPU0_ADDR0")
	)
	(segment
		(start 246.757698 -78.278736)
		(end 246.790464 -78.278736)
		(width 0.0889)
		(layer "In4.Cu")
		(net "PD_PIROM_CPU0_ADDR0")
	)
	(segment
		(start 193.799206 -104.578912)
		(end 193.846958 -104.53116)
		(width 0.089408)
		(layer "In4.Cu")
		(net "PD_PIROM_CPU0_ADDR0")
	)
	(segment
		(start 207.951578 -95.607886)
		(end 207.951578 -93.118178)
		(width 0.089408)
		(layer "In4.Cu")
		(net "PD_PIROM_CPU0_ADDR0")
	)
	(segment
		(start 208.400904 -92.668852)
		(end 212.000084 -92.668852)
		(width 0.089408)
		(layer "In4.Cu")
		(net "PD_PIROM_CPU0_ADDR0")
	)
	(segment
		(start 253.294134 -84.612988)
		(end 253.289308 -84.621624)
		(width 0.0889)
		(layer "In4.Cu")
		(net "PD_PIROM_CPU0_ADDR0")
	)
	(segment
		(start 247.620028 -78.77429)
		(end 247.652794 -78.77429)
		(width 0.0889)
		(layer "In4.Cu")
		(net "PD_PIROM_CPU0_ADDR0")
	)
	(segment
		(start 207.580484 -95.97898)
		(end 207.951578 -95.607886)
		(width 0.089408)
		(layer "In4.Cu")
		(net "PD_PIROM_CPU0_ADDR0")
	)
	(segment
		(start 242.458748 -77.78369)
		(end 242.50523 -77.78369)
		(width 0.0889)
		(layer "In4.Cu")
		(net "PD_PIROM_CPU0_ADDR0")
	)
	(segment
		(start 251.908818 -81.250536)
		(end 251.941584 -81.250536)
		(width 0.0889)
		(layer "In4.Cu")
		(net "PD_PIROM_CPU0_ADDR0")
	)
	(segment
		(start 249.337068 -79.76489)
		(end 249.369834 -79.76489)
		(width 0.0889)
		(layer "In4.Cu")
		(net "PD_PIROM_CPU0_ADDR0")
	)
	(segment
		(start 214.657178 -90.011758)
		(end 216.29878 -90.011758)
		(width 0.089408)
		(layer "In4.Cu")
		(net "PD_PIROM_CPU0_ADDR0")
	)
	(segment
		(start 232.337356 -78.815438)
		(end 233.073702 -78.079092)
		(width 0.089408)
		(layer "In4.Cu")
		(net "PD_PIROM_CPU0_ADDR0")
	)
	(segment
		(start 212.000084 -92.668852)
		(end 214.657178 -90.011758)
		(width 0.089408)
		(layer "In4.Cu")
		(net "PD_PIROM_CPU0_ADDR0")
	)
	(segment
		(start 233.369866 -77.782928)
		(end 233.999786 -77.782928)
		(width 0.0889)
		(layer "In4.Cu")
		(net "PD_PIROM_CPU0_ADDR0")
	)
	(segment
		(start 234.535472 -77.288136)
		(end 234.771438 -77.288136)
		(width 0.0889)
		(layer "In4.Cu")
		(net "PD_PIROM_CPU0_ADDR0")
	)
	(segment
		(start 252.771148 -81.74609)
		(end 252.803914 -81.74609)
		(width 0.0889)
		(layer "In4.Cu")
		(net "PD_PIROM_CPU0_ADDR0")
	)
	(segment
		(start 201.986896 -106.05262)
		(end 203.431902 -106.05262)
		(width 0.089408)
		(layer "In4.Cu")
		(net "PD_PIROM_CPU0_ADDR0")
	)
	(segment
		(start 200.261728 -104.327452)
		(end 201.986896 -106.05262)
		(width 0.089408)
		(layer "In4.Cu")
		(net "PD_PIROM_CPU0_ADDR0")
	)
	(segment
		(start 244.185948 -78.77429)
		(end 244.2083 -78.77429)
		(width 0.0889)
		(layer "In4.Cu")
		(net "PD_PIROM_CPU0_ADDR0")
	)
	(segment
		(start 235.601002 -77.78369)
		(end 235.623354 -77.78369)
		(width 0.0889)
		(layer "In4.Cu")
		(net "PD_PIROM_CPU0_ADDR0")
	)
	(segment
		(start 233.999786 -77.782928)
		(end 234.195874 -77.58684)
		(width 0.0889)
		(layer "In4.Cu")
		(net "PD_PIROM_CPU0_ADDR0")
	)
	(segment
		(start 195.350638 -104.756204)
		(end 197.33387 -104.756204)
		(width 0.089408)
		(layer "In4.Cu")
		(net "PD_PIROM_CPU0_ADDR0")
	)
	(segment
		(start 206.5528 -101.693472)
		(end 207.580484 -100.665788)
		(width 0.089408)
		(layer "In4.Cu")
		(net "PD_PIROM_CPU0_ADDR0")
	)
	(segment
		(start 250.191778 -80.259936)
		(end 250.224544 -80.259936)
		(width 0.0889)
		(layer "In4.Cu")
		(net "PD_PIROM_CPU0_ADDR0")
	)
	(segment
		(start 241.606832 -78.278736)
		(end 241.636804 -78.278736)
		(width 0.0889)
		(layer "In4.Cu")
		(net "PD_PIROM_CPU0_ADDR0")
	)
	(segment
		(start 233.073702 -78.079092)
		(end 233.369866 -77.782928)
		(width 0.0889)
		(layer "In4.Cu")
		(net "PD_PIROM_CPU0_ADDR0")
	)
	(segment
		(start 243.338604 -78.278736)
		(end 243.356384 -78.278736)
		(width 0.0889)
		(layer "In4.Cu")
		(net "PD_PIROM_CPU0_ADDR0")
	)
	(segment
		(start 227.4951 -78.815438)
		(end 232.337356 -78.815438)
		(width 0.089408)
		(layer "In4.Cu")
		(net "PD_PIROM_CPU0_ADDR0")
	)
	(segment
		(start 207.951578 -93.118178)
		(end 208.400904 -92.668852)
		(width 0.089408)
		(layer "In4.Cu")
		(net "PD_PIROM_CPU0_ADDR0")
	)
	(segment
		(start 254.49911 -85.70849)
		(end 254.5207 -85.70849)
		(width 0.0889)
		(layer "In4.Cu")
		(net "PD_PIROM_CPU0_ADDR0")
	)
	(segment
		(start 248.474738 -79.269336)
		(end 248.507504 -79.269336)
		(width 0.0889)
		(layer "In4.Cu")
		(net "PD_PIROM_CPU0_ADDR0")
	)
	(segment
		(start 242.992148 -78.078584)
		(end 242.99545 -78.084426)
		(width 0.0889)
		(layer "In4.Cu")
		(net "PD_PIROM_CPU0_ADDR0")
	)
	(arc
		(start 243.850414 -78.574138)
		(mid 243.992097 -78.717942)
		(end 244.185948 -78.77429)
		(width 0.0889)
		(layer "In4.Cu")
		(net "PD_PIROM_CPU0_ADDR0")
	)
	(arc
		(start 253.294134 -85.013038)
		(mid 253.434213 -85.155774)
		(end 253.625858 -85.212936)
		(width 0.0889)
		(layer "In4.Cu")
		(net "PD_PIROM_CPU0_ADDR0")
	)
	(arc
		(start 242.50523 -77.78369)
		(mid 242.78653 -77.868656)
		(end 242.992148 -78.078584)
		(width 0.0889)
		(layer "In4.Cu")
		(net "PD_PIROM_CPU0_ADDR0")
	)
	(arc
		(start 236.982508 -77.583538)
		(mid 237.124191 -77.727342)
		(end 237.318042 -77.78369)
		(width 0.0889)
		(layer "In4.Cu")
		(net "PD_PIROM_CPU0_ADDR0")
	)
	(arc
		(start 244.2083 -78.77429)
		(mid 244.40215 -78.71794)
		(end 244.543834 -78.574138)
		(width 0.0889)
		(layer "In4.Cu")
		(net "PD_PIROM_CPU0_ADDR0")
	)
	(arc
		(start 235.958888 -77.583538)
		(mid 236.167496 -77.371606)
		(end 236.452918 -77.288136)
		(width 0.0889)
		(layer "In4.Cu")
		(net "PD_PIROM_CPU0_ADDR0")
	)
	(arc
		(start 247.652794 -78.77429)
		(mid 247.936011 -78.858571)
		(end 248.143014 -79.069438)
		(width 0.0889)
		(layer "In4.Cu")
		(net "PD_PIROM_CPU0_ADDR0")
	)
	(arc
		(start 235.265468 -77.583538)
		(mid 235.407151 -77.727342)
		(end 235.601002 -77.78369)
		(width 0.0889)
		(layer "In4.Cu")
		(net "PD_PIROM_CPU0_ADDR0")
	)
	(arc
		(start 241.968528 -78.078838)
		(mid 242.175532 -77.867974)
		(end 242.458748 -77.78369)
		(width 0.0889)
		(layer "In4.Cu")
		(net "PD_PIROM_CPU0_ADDR0")
	)
	(arc
		(start 249.001534 -79.564738)
		(mid 249.143217 -79.708542)
		(end 249.337068 -79.76489)
		(width 0.0889)
		(layer "In4.Cu")
		(net "PD_PIROM_CPU0_ADDR0")
	)
	(arc
		(start 251.086874 -80.75549)
		(mid 251.370091 -80.839771)
		(end 251.577094 -81.050638)
		(width 0.0889)
		(layer "In4.Cu")
		(net "PD_PIROM_CPU0_ADDR0")
	)
	(arc
		(start 254.5207 -85.70849)
		(mid 254.803917 -85.792771)
		(end 255.01092 -86.003638)
		(width 0.0889)
		(layer "In4.Cu")
		(net "PD_PIROM_CPU0_ADDR0")
	)
	(arc
		(start 253.289308 -83.631024)
		(mid 253.240553 -83.827376)
		(end 253.294134 -84.022438)
		(width 0.0889)
		(layer "In4.Cu")
		(net "PD_PIROM_CPU0_ADDR0")
	)
	(arc
		(start 240.784888 -77.78369)
		(mid 241.068105 -77.867971)
		(end 241.275108 -78.078838)
		(width 0.0889)
		(layer "In4.Cu")
		(net "PD_PIROM_CPU0_ADDR0")
	)
	(arc
		(start 255.86944 -86.498938)
		(mid 256.064529 -86.884759)
		(end 256.21615 -87.28964)
		(width 0.0889)
		(layer "In4.Cu")
		(net "PD_PIROM_CPU0_ADDR0")
	)
	(arc
		(start 247.284494 -78.574138)
		(mid 247.426177 -78.717942)
		(end 247.620028 -78.77429)
		(width 0.0889)
		(layer "In4.Cu")
		(net "PD_PIROM_CPU0_ADDR0")
	)
	(arc
		(start 238.699548 -77.583538)
		(mid 238.841231 -77.727342)
		(end 239.035082 -77.78369)
		(width 0.0889)
		(layer "In4.Cu")
		(net "PD_PIROM_CPU0_ADDR0")
	)
	(arc
		(start 253.658624 -85.212936)
		(mid 253.944048 -85.296403)
		(end 254.152654 -85.508338)
		(width 0.0889)
		(layer "In4.Cu")
		(net "PD_PIROM_CPU0_ADDR0")
	)
	(arc
		(start 248.507504 -79.269336)
		(mid 248.792928 -79.352803)
		(end 249.001534 -79.564738)
		(width 0.0889)
		(layer "In4.Cu")
		(net "PD_PIROM_CPU0_ADDR0")
	)
	(arc
		(start 249.860054 -80.060038)
		(mid 250.000133 -80.202774)
		(end 250.191778 -80.259936)
		(width 0.0889)
		(layer "In4.Cu")
		(net "PD_PIROM_CPU0_ADDR0")
	)
	(arc
		(start 253.294134 -83.031838)
		(mid 253.373356 -83.320956)
		(end 253.300484 -83.61172)
		(width 0.0889)
		(layer "In4.Cu")
		(net "PD_PIROM_CPU0_ADDR0")
	)
	(arc
		(start 254.155956 -85.51418)
		(mid 254.301922 -85.656579)
		(end 254.49911 -85.70849)
		(width 0.0889)
		(layer "In4.Cu")
		(net "PD_PIROM_CPU0_ADDR0")
	)
	(arc
		(start 251.577094 -81.050638)
		(mid 251.717173 -81.193374)
		(end 251.908818 -81.250536)
		(width 0.0889)
		(layer "In4.Cu")
		(net "PD_PIROM_CPU0_ADDR0")
	)
	(arc
		(start 239.558068 -78.078838)
		(mid 239.698147 -78.221574)
		(end 239.889792 -78.278736)
		(width 0.0889)
		(layer "In4.Cu")
		(net "PD_PIROM_CPU0_ADDR0")
	)
	(arc
		(start 250.224544 -80.259936)
		(mid 250.509968 -80.343403)
		(end 250.718574 -80.555338)
		(width 0.0889)
		(layer "In4.Cu")
		(net "PD_PIROM_CPU0_ADDR0")
	)
	(arc
		(start 241.275108 -78.078838)
		(mid 241.415187 -78.221574)
		(end 241.606832 -78.278736)
		(width 0.0889)
		(layer "In4.Cu")
		(net "PD_PIROM_CPU0_ADDR0")
	)
	(arc
		(start 249.369834 -79.76489)
		(mid 249.653051 -79.849171)
		(end 249.860054 -80.060038)
		(width 0.0889)
		(layer "In4.Cu")
		(net "PD_PIROM_CPU0_ADDR0")
	)
	(arc
		(start 253.289308 -84.621624)
		(mid 253.240553 -84.817976)
		(end 253.294134 -85.013038)
		(width 0.0889)
		(layer "In4.Cu")
		(net "PD_PIROM_CPU0_ADDR0")
	)
	(arc
		(start 243.356384 -78.278736)
		(mid 243.641808 -78.362203)
		(end 243.850414 -78.574138)
		(width 0.0889)
		(layer "In4.Cu")
		(net "PD_PIROM_CPU0_ADDR0")
	)
	(arc
		(start 248.143014 -79.069438)
		(mid 248.283093 -79.212174)
		(end 248.474738 -79.269336)
		(width 0.0889)
		(layer "In4.Cu")
		(net "PD_PIROM_CPU0_ADDR0")
	)
	(arc
		(start 236.488478 -77.288136)
		(mid 236.773902 -77.371603)
		(end 236.982508 -77.583538)
		(width 0.0889)
		(layer "In4.Cu")
		(net "PD_PIROM_CPU0_ADDR0")
	)
	(arc
		(start 251.941584 -81.250536)
		(mid 252.227008 -81.334003)
		(end 252.435614 -81.545938)
		(width 0.0889)
		(layer "In4.Cu")
		(net "PD_PIROM_CPU0_ADDR0")
	)
	(arc
		(start 245.402354 -78.078838)
		(mid 245.609358 -77.867974)
		(end 245.892574 -77.78369)
		(width 0.0889)
		(layer "In4.Cu")
		(net "PD_PIROM_CPU0_ADDR0")
	)
	(arc
		(start 246.790464 -78.278736)
		(mid 247.075888 -78.362203)
		(end 247.284494 -78.574138)
		(width 0.0889)
		(layer "In4.Cu")
		(net "PD_PIROM_CPU0_ADDR0")
	)
	(arc
		(start 253.294134 -84.022438)
		(mid 253.373356 -84.311556)
		(end 253.300484 -84.60232)
		(width 0.0889)
		(layer "In4.Cu")
		(net "PD_PIROM_CPU0_ADDR0")
	)
	(arc
		(start 235.623354 -77.78369)
		(mid 235.817204 -77.72734)
		(end 235.958888 -77.583538)
		(width 0.0889)
		(layer "In4.Cu")
		(net "PD_PIROM_CPU0_ADDR0")
	)
	(arc
		(start 253.294134 -82.632042)
		(mid 253.240635 -82.83194)
		(end 253.294134 -83.031838)
		(width 0.0889)
		(layer "In4.Cu")
		(net "PD_PIROM_CPU0_ADDR0")
	)
	(arc
		(start 237.675928 -77.583538)
		(mid 238.187738 -77.287871)
		(end 238.699548 -77.583538)
		(width 0.0889)
		(layer "In4.Cu")
		(net "PD_PIROM_CPU0_ADDR0")
	)
	(arc
		(start 250.718574 -80.555338)
		(mid 250.860257 -80.699142)
		(end 251.054108 -80.75549)
		(width 0.0889)
		(layer "In4.Cu")
		(net "PD_PIROM_CPU0_ADDR0")
	)
	(arc
		(start 237.340394 -77.78369)
		(mid 237.534244 -77.72734)
		(end 237.675928 -77.583538)
		(width 0.0889)
		(layer "In4.Cu")
		(net "PD_PIROM_CPU0_ADDR0")
	)
	(arc
		(start 234.771438 -77.288136)
		(mid 235.056862 -77.371603)
		(end 235.265468 -77.583538)
		(width 0.0889)
		(layer "In4.Cu")
		(net "PD_PIROM_CPU0_ADDR0")
	)
	(arc
		(start 253.294134 -82.041238)
		(mid 253.373265 -82.33664)
		(end 253.294134 -82.632042)
		(width 0.0889)
		(layer "In4.Cu")
		(net "PD_PIROM_CPU0_ADDR0")
	)
	(arc
		(start 245.935754 -77.78369)
		(mid 246.218971 -77.867971)
		(end 246.425974 -78.078838)
		(width 0.0889)
		(layer "In4.Cu")
		(net "PD_PIROM_CPU0_ADDR0")
	)
	(arc
		(start 244.543834 -78.574138)
		(mid 244.752442 -78.362206)
		(end 245.037864 -78.278736)
		(width 0.0889)
		(layer "In4.Cu")
		(net "PD_PIROM_CPU0_ADDR0")
	)
	(arc
		(start 240.251488 -78.078838)
		(mid 240.458492 -77.867974)
		(end 240.741708 -77.78369)
		(width 0.0889)
		(layer "In4.Cu")
		(net "PD_PIROM_CPU0_ADDR0")
	)
	(arc
		(start 239.919764 -78.278736)
		(mid 240.111406 -78.22157)
		(end 240.251488 -78.078838)
		(width 0.0889)
		(layer "In4.Cu")
		(net "PD_PIROM_CPU0_ADDR0")
	)
	(arc
		(start 245.07063 -78.278736)
		(mid 245.262272 -78.22157)
		(end 245.402354 -78.078838)
		(width 0.0889)
		(layer "In4.Cu")
		(net "PD_PIROM_CPU0_ADDR0")
	)
	(arc
		(start 234.195874 -77.58684)
		(mid 234.337935 -77.405959)
		(end 234.535472 -77.288136)
		(width 0.0889)
		(layer "In4.Cu")
		(net "PD_PIROM_CPU0_ADDR0")
	)
	(arc
		(start 242.99545 -78.084426)
		(mid 243.141416 -78.226825)
		(end 243.338604 -78.278736)
		(width 0.0889)
		(layer "In4.Cu")
		(net "PD_PIROM_CPU0_ADDR0")
	)
	(arc
		(start 239.067848 -77.78369)
		(mid 239.351065 -77.867971)
		(end 239.558068 -78.078838)
		(width 0.0889)
		(layer "In4.Cu")
		(net "PD_PIROM_CPU0_ADDR0")
	)
	(arc
		(start 241.636804 -78.278736)
		(mid 241.828446 -78.22157)
		(end 241.968528 -78.078838)
		(width 0.0889)
		(layer "In4.Cu")
		(net "PD_PIROM_CPU0_ADDR0")
	)
	(arc
		(start 255.37541 -86.203536)
		(mid 255.660834 -86.287003)
		(end 255.86944 -86.498938)
		(width 0.0889)
		(layer "In4.Cu")
		(net "PD_PIROM_CPU0_ADDR0")
	)
	(arc
		(start 255.01092 -86.003638)
		(mid 255.150999 -86.146374)
		(end 255.342644 -86.203536)
		(width 0.0889)
		(layer "In4.Cu")
		(net "PD_PIROM_CPU0_ADDR0")
	)
	(arc
		(start 252.803914 -81.74609)
		(mid 253.087131 -81.830371)
		(end 253.294134 -82.041238)
		(width 0.0889)
		(layer "In4.Cu")
		(net "PD_PIROM_CPU0_ADDR0")
	)
	(arc
		(start 246.425974 -78.078838)
		(mid 246.566053 -78.221574)
		(end 246.757698 -78.278736)
		(width 0.0889)
		(layer "In4.Cu")
		(net "PD_PIROM_CPU0_ADDR0")
	)
	(arc
		(start 252.435614 -81.545938)
		(mid 252.577297 -81.689742)
		(end 252.771148 -81.74609)
		(width 0.0889)
		(layer "In4.Cu")
		(net "PD_PIROM_CPU0_ADDR0")
	)
	(segment
		(start 474.523816 -130.366008)
		(end 476.185992 -130.366008)
		(width 0.10795)
		(layer "F.Cu")
		(net "JTAG_MCP_TRST_N")
	)
	(segment
		(start 348.220792 -71.713598)
		(end 343.588594 -71.713598)
		(width 0.10795)
		(layer "F.Cu")
		(net "JTAG_MCP_TRST_N")
	)
	(segment
		(start 373.650256 -84.438998)
		(end 373.182642 -84.438998)
		(width 0.10795)
		(layer "F.Cu")
		(net "JTAG_MCP_TRST_N")
	)
	(segment
		(start 349.671386 -73.175368)
		(end 349.671386 -73.164192)
		(width 0.10795)
		(layer "F.Cu")
		(net "JTAG_MCP_TRST_N")
	)
	(segment
		(start 349.671386 -73.164192)
		(end 348.220792 -71.713598)
		(width 0.10795)
		(layer "F.Cu")
		(net "JTAG_MCP_TRST_N")
	)
	(segment
		(start 367.895886 -82.065114)
		(end 367.103152 -82.857848)
		(width 0.10795)
		(layer "F.Cu")
		(net "JTAG_MCP_TRST_N")
	)
	(segment
		(start 376.810524 -82.819494)
		(end 375.944892 -82.819494)
		(width 0.10795)
		(layer "F.Cu")
		(net "JTAG_MCP_TRST_N")
	)
	(segment
		(start 340.20125 -75.536552)
		(end 337.442048 -75.536552)
		(width 0.10795)
		(layer "F.Cu")
		(net "JTAG_MCP_TRST_N")
	)
	(segment
		(start 123.363228 -82.650584)
		(end 123.934728 -82.650584)
		(width 0.1016)
		(layer "F.Cu")
		(net "JTAG_MCP_TRST_N")
	)
	(segment
		(start 357.241856 -73.44791)
		(end 356.879144 -73.085198)
		(width 0.10795)
		(layer "F.Cu")
		(net "JTAG_MCP_TRST_N")
	)
	(segment
		(start 366.356392 -82.857848)
		(end 363.003338 -79.504794)
		(width 0.10795)
		(layer "F.Cu")
		(net "JTAG_MCP_TRST_N")
	)
	(segment
		(start 375.807986 -82.9564)
		(end 375.132854 -82.9564)
		(width 0.10795)
		(layer "F.Cu")
		(net "JTAG_MCP_TRST_N")
	)
	(segment
		(start 360.655616 -73.44791)
		(end 357.241856 -73.44791)
		(width 0.10795)
		(layer "F.Cu")
		(net "JTAG_MCP_TRST_N")
	)
	(segment
		(start 349.768668 -73.27265)
		(end 349.671386 -73.175368)
		(width 0.10795)
		(layer "F.Cu")
		(net "JTAG_MCP_TRST_N")
	)
	(segment
		(start 370.551964 -82.395568)
		(end 370.28882 -82.286602)
		(width 0.10795)
		(layer "F.Cu")
		(net "JTAG_MCP_TRST_N")
	)
	(segment
		(start 355.430836 -73.27265)
		(end 349.768668 -73.27265)
		(width 0.10795)
		(layer "F.Cu")
		(net "JTAG_MCP_TRST_N")
	)
	(segment
		(start 330.759562 -79.867506)
		(end 333.111094 -79.867506)
		(width 0.10795)
		(layer "F.Cu")
		(net "JTAG_MCP_TRST_N")
	)
	(segment
		(start 371.216174 -82.67065)
		(end 370.55298 -82.395822)
		(width 0.10795)
		(layer "F.Cu")
		(net "JTAG_MCP_TRST_N")
	)
	(segment
		(start 373.182642 -84.438998)
		(end 371.554502 -82.810858)
		(width 0.10795)
		(layer "F.Cu")
		(net "JTAG_MCP_TRST_N")
	)
	(segment
		(start 476.6056 -127.06731)
		(end 476.497142 -126.958852)
		(width 0.10795)
		(layer "F.Cu")
		(net "JTAG_MCP_TRST_N")
	)
	(segment
		(start 375.944892 -82.819494)
		(end 375.807986 -82.9564)
		(width 0.10795)
		(layer "F.Cu")
		(net "JTAG_MCP_TRST_N")
	)
	(segment
		(start 476.185992 -130.366008)
		(end 476.6056 -129.9464)
		(width 0.10795)
		(layer "F.Cu")
		(net "JTAG_MCP_TRST_N")
	)
	(segment
		(start 337.442048 -75.536552)
		(end 334.0989 -78.8797)
		(width 0.10795)
		(layer "F.Cu")
		(net "JTAG_MCP_TRST_N")
	)
	(segment
		(start 371.554502 -82.810858)
		(end 371.216174 -82.67065)
		(width 0.10795)
		(layer "F.Cu")
		(net "JTAG_MCP_TRST_N")
	)
	(segment
		(start 288.36366 -82.650584)
		(end 288.93516 -82.650584)
		(width 0.1016)
		(layer "F.Cu")
		(net "JTAG_MCP_TRST_N")
	)
	(segment
		(start 363.003338 -75.795632)
		(end 360.655616 -73.44791)
		(width 0.10795)
		(layer "F.Cu")
		(net "JTAG_MCP_TRST_N")
	)
	(segment
		(start 370.067332 -82.065114)
		(end 367.895886 -82.065114)
		(width 0.10795)
		(layer "F.Cu")
		(net "JTAG_MCP_TRST_N")
	)
	(segment
		(start 367.103152 -82.857848)
		(end 366.356392 -82.857848)
		(width 0.10795)
		(layer "F.Cu")
		(net "JTAG_MCP_TRST_N")
	)
	(segment
		(start 476.6056 -129.9464)
		(end 476.6056 -127.06731)
		(width 0.10795)
		(layer "F.Cu")
		(net "JTAG_MCP_TRST_N")
	)
	(segment
		(start 370.55298 -82.395822)
		(end 370.551964 -82.395568)
		(width 0.10795)
		(layer "F.Cu")
		(net "JTAG_MCP_TRST_N")
	)
	(segment
		(start 356.879144 -73.085198)
		(end 355.618288 -73.085198)
		(width 0.10795)
		(layer "F.Cu")
		(net "JTAG_MCP_TRST_N")
	)
	(segment
		(start 343.588594 -71.713598)
		(end 342.704674 -72.597518)
		(width 0.10795)
		(layer "F.Cu")
		(net "JTAG_MCP_TRST_N")
	)
	(segment
		(start 342.704674 -73.033128)
		(end 340.20125 -75.536552)
		(width 0.10795)
		(layer "F.Cu")
		(net "JTAG_MCP_TRST_N")
	)
	(segment
		(start 375.132854 -82.9564)
		(end 373.650256 -84.438998)
		(width 0.10795)
		(layer "F.Cu")
		(net "JTAG_MCP_TRST_N")
	)
	(segment
		(start 363.003338 -79.504794)
		(end 363.003338 -75.795632)
		(width 0.10795)
		(layer "F.Cu")
		(net "JTAG_MCP_TRST_N")
	)
	(segment
		(start 342.704674 -72.597518)
		(end 342.704674 -73.033128)
		(width 0.10795)
		(layer "F.Cu")
		(net "JTAG_MCP_TRST_N")
	)
	(segment
		(start 355.618288 -73.085198)
		(end 355.430836 -73.27265)
		(width 0.10795)
		(layer "F.Cu")
		(net "JTAG_MCP_TRST_N")
	)
	(segment
		(start 370.28882 -82.286602)
		(end 370.067332 -82.065114)
		(width 0.10795)
		(layer "F.Cu")
		(net "JTAG_MCP_TRST_N")
	)
	(segment
		(start 333.111094 -79.867506)
		(end 334.0989 -78.8797)
		(width 0.10795)
		(layer "F.Cu")
		(net "JTAG_MCP_TRST_N")
	)
	(via
		(at 476.497142 -126.958852)
		(size 0.508)
		(drill 0.254)
		(layers "F.Cu" "B.Cu")
		(net "JTAG_MCP_TRST_N")
	)
	(via
		(at 425.0817 -112.444784)
		(size 0.508)
		(drill 0.254)
		(layers "F.Cu" "B.Cu")
		(net "JTAG_MCP_TRST_N")
	)
	(via
		(at 330.759562 -79.867506)
		(size 0.508)
		(drill 0.254)
		(layers "F.Cu" "B.Cu")
		(net "JTAG_MCP_TRST_N")
	)
	(via
		(at 288.93516 -82.650584)
		(size 0.508)
		(drill 0.254)
		(layers "F.Cu" "B.Cu")
		(net "JTAG_MCP_TRST_N")
	)
	(via
		(at 376.810524 -82.819494)
		(size 0.508)
		(drill 0.254)
		(layers "F.Cu" "B.Cu")
		(net "JTAG_MCP_TRST_N")
	)
	(via
		(at 334.0989 -78.8797)
		(size 0.762)
		(drill 0.381)
		(layers "F.Cu" "B.Cu")
		(net "JTAG_MCP_TRST_N")
	)
	(via
		(at 123.934728 -82.650584)
		(size 0.508)
		(drill 0.254)
		(layers "F.Cu" "B.Cu")
		(net "JTAG_MCP_TRST_N")
	)
	(segment
		(start 471.9447 -128.1557)
		(end 471.5129 -127.7239)
		(width 0.10795)
		(layer "B.Cu")
		(net "JTAG_MCP_TRST_N")
	)
	(segment
		(start 425.0817 -112.444784)
		(end 424.9547 -112.317784)
		(width 0.10795)
		(layer "B.Cu")
		(net "JTAG_MCP_TRST_N")
	)
	(segment
		(start 424.46321 -110.287054)
		(end 424.46321 -80.663034)
		(width 0.10795)
		(layer "B.Cu")
		(net "JTAG_MCP_TRST_N")
	)
	(segment
		(start 397.714216 -70.298818)
		(end 397.24838 -70.764654)
		(width 0.10795)
		(layer "B.Cu")
		(net "JTAG_MCP_TRST_N")
	)
	(segment
		(start 392.052302 -74.182478)
		(end 391.326624 -73.4568)
		(width 0.10795)
		(layer "B.Cu")
		(net "JTAG_MCP_TRST_N")
	)
	(segment
		(start 422.549828 -65.016888)
		(end 421.636698 -64.103758)
		(width 0.10795)
		(layer "B.Cu")
		(net "JTAG_MCP_TRST_N")
	)
	(segment
		(start 380.011686 -81.1022)
		(end 377.225814 -81.1022)
		(width 0.10795)
		(layer "B.Cu")
		(net "JTAG_MCP_TRST_N")
	)
	(segment
		(start 409.492704 -68.18376)
		(end 408.68854 -68.18376)
		(width 0.10795)
		(layer "B.Cu")
		(net "JTAG_MCP_TRST_N")
	)
	(segment
		(start 391.326624 -73.4568)
		(end 390.40562 -73.4568)
		(width 0.10795)
		(layer "B.Cu")
		(net "JTAG_MCP_TRST_N")
	)
	(segment
		(start 413.141414 -67.88277)
		(end 413.035242 -67.776598)
		(width 0.10795)
		(layer "B.Cu")
		(net "JTAG_MCP_TRST_N")
	)
	(segment
		(start 416.290252 -65.152524)
		(end 415.349944 -65.152524)
		(width 0.10795)
		(layer "B.Cu")
		(net "JTAG_MCP_TRST_N")
	)
	(segment
		(start 376.810524 -81.51749)
		(end 376.810524 -82.819494)
		(width 0.10795)
		(layer "B.Cu")
		(net "JTAG_MCP_TRST_N")
	)
	(segment
		(start 413.035242 -67.776598)
		(end 409.899866 -67.776598)
		(width 0.10795)
		(layer "B.Cu")
		(net "JTAG_MCP_TRST_N")
	)
	(segment
		(start 475.817692 -126.279402)
		(end 476.497142 -126.958852)
		(width 0.10795)
		(layer "B.Cu")
		(net "JTAG_MCP_TRST_N")
	)
	(segment
		(start 386.42671 -77.50175)
		(end 384.49377 -77.50175)
		(width 0.10795)
		(layer "B.Cu")
		(net "JTAG_MCP_TRST_N")
	)
	(segment
		(start 424.233848 -80.433672)
		(end 424.233848 -73.804272)
		(width 0.10795)
		(layer "B.Cu")
		(net "JTAG_MCP_TRST_N")
	)
	(segment
		(start 423.9514 -72.213216)
		(end 422.549828 -70.811644)
		(width 0.10795)
		(layer "B.Cu")
		(net "JTAG_MCP_TRST_N")
	)
	(segment
		(start 397.24838 -70.764654)
		(end 396.665704 -70.764654)
		(width 0.10795)
		(layer "B.Cu")
		(net "JTAG_MCP_TRST_N")
	)
	(segment
		(start 424.46321 -80.663034)
		(end 424.233848 -80.433672)
		(width 0.10795)
		(layer "B.Cu")
		(net "JTAG_MCP_TRST_N")
	)
	(segment
		(start 471.47226 -126.715774)
		(end 471.908632 -126.279402)
		(width 0.10795)
		(layer "B.Cu")
		(net "JTAG_MCP_TRST_N")
	)
	(segment
		(start 398.532096 -70.298818)
		(end 397.714216 -70.298818)
		(width 0.10795)
		(layer "B.Cu")
		(net "JTAG_MCP_TRST_N")
	)
	(segment
		(start 417.339018 -64.103758)
		(end 416.290252 -65.152524)
		(width 0.10795)
		(layer "B.Cu")
		(net "JTAG_MCP_TRST_N")
	)
	(segment
		(start 471.9447 -128.6129)
		(end 471.9447 -128.39954)
		(width 0.10795)
		(layer "B.Cu")
		(net "JTAG_MCP_TRST_N")
	)
	(segment
		(start 423.9514 -73.521824)
		(end 423.9514 -72.213216)
		(width 0.10795)
		(layer "B.Cu")
		(net "JTAG_MCP_TRST_N")
	)
	(segment
		(start 471.5129 -127.7239)
		(end 471.5129 -127.6985)
		(width 0.10795)
		(layer "B.Cu")
		(net "JTAG_MCP_TRST_N")
	)
	(segment
		(start 408.229054 -67.724274)
		(end 408.229054 -66.63055)
		(width 0.10795)
		(layer "B.Cu")
		(net "JTAG_MCP_TRST_N")
	)
	(segment
		(start 414.35528 -67.55257)
		(end 414.02508 -67.88277)
		(width 0.10795)
		(layer "B.Cu")
		(net "JTAG_MCP_TRST_N")
	)
	(segment
		(start 424.9547 -112.317784)
		(end 424.9547 -110.778544)
		(width 0.10795)
		(layer "B.Cu")
		(net "JTAG_MCP_TRST_N")
	)
	(segment
		(start 471.47226 -127.65786)
		(end 471.47226 -126.715774)
		(width 0.10795)
		(layer "B.Cu")
		(net "JTAG_MCP_TRST_N")
	)
	(segment
		(start 388.77748 -75.08494)
		(end 388.77748 -75.15098)
		(width 0.10795)
		(layer "B.Cu")
		(net "JTAG_MCP_TRST_N")
	)
	(segment
		(start 422.549828 -70.811644)
		(end 422.549828 -65.016888)
		(width 0.10795)
		(layer "B.Cu")
		(net "JTAG_MCP_TRST_N")
	)
	(segment
		(start 471.9447 -128.39954)
		(end 471.9447 -128.1557)
		(width 0.10795)
		(layer "B.Cu")
		(net "JTAG_MCP_TRST_N")
	)
	(segment
		(start 384.49377 -77.50175)
		(end 382.8923 -79.10322)
		(width 0.10795)
		(layer "B.Cu")
		(net "JTAG_MCP_TRST_N")
	)
	(segment
		(start 424.233848 -73.804272)
		(end 423.9514 -73.521824)
		(width 0.10795)
		(layer "B.Cu")
		(net "JTAG_MCP_TRST_N")
	)
	(segment
		(start 471.908632 -126.279402)
		(end 475.817692 -126.279402)
		(width 0.10795)
		(layer "B.Cu")
		(net "JTAG_MCP_TRST_N")
	)
	(segment
		(start 471.95486 -128.62306)
		(end 471.9447 -128.6129)
		(width 0.10795)
		(layer "B.Cu")
		(net "JTAG_MCP_TRST_N")
	)
	(segment
		(start 382.397 -79.10322)
		(end 381.41402 -80.0862)
		(width 0.10795)
		(layer "B.Cu")
		(net "JTAG_MCP_TRST_N")
	)
	(segment
		(start 407.071322 -66.802762)
		(end 406.9588 -66.915284)
		(width 0.10795)
		(layer "B.Cu")
		(net "JTAG_MCP_TRST_N")
	)
	(segment
		(start 403.792944 -68.596256)
		(end 400.234658 -68.596256)
		(width 0.10795)
		(layer "B.Cu")
		(net "JTAG_MCP_TRST_N")
	)
	(segment
		(start 381.41402 -80.0862)
		(end 381.027686 -80.0862)
		(width 0.10795)
		(layer "B.Cu")
		(net "JTAG_MCP_TRST_N")
	)
	(segment
		(start 415.349944 -65.152524)
		(end 414.35528 -66.147188)
		(width 0.10795)
		(layer "B.Cu")
		(net "JTAG_MCP_TRST_N")
	)
	(segment
		(start 471.95486 -129.1844)
		(end 471.95486 -128.62306)
		(width 0.10795)
		(layer "B.Cu")
		(net "JTAG_MCP_TRST_N")
	)
	(segment
		(start 393.24788 -74.182478)
		(end 392.052302 -74.182478)
		(width 0.10795)
		(layer "B.Cu")
		(net "JTAG_MCP_TRST_N")
	)
	(segment
		(start 408.229054 -66.63055)
		(end 407.861262 -66.262758)
		(width 0.10795)
		(layer "B.Cu")
		(net "JTAG_MCP_TRST_N")
	)
	(segment
		(start 377.225814 -81.1022)
		(end 376.810524 -81.51749)
		(width 0.10795)
		(layer "B.Cu")
		(net "JTAG_MCP_TRST_N")
	)
	(segment
		(start 409.899866 -67.776598)
		(end 409.492704 -68.18376)
		(width 0.10795)
		(layer "B.Cu")
		(net "JTAG_MCP_TRST_N")
	)
	(segment
		(start 388.77748 -75.15098)
		(end 386.42671 -77.50175)
		(width 0.10795)
		(layer "B.Cu")
		(net "JTAG_MCP_TRST_N")
	)
	(segment
		(start 414.02508 -67.88277)
		(end 413.141414 -67.88277)
		(width 0.10795)
		(layer "B.Cu")
		(net "JTAG_MCP_TRST_N")
	)
	(segment
		(start 471.5129 -127.6985)
		(end 471.47226 -127.65786)
		(width 0.10795)
		(layer "B.Cu")
		(net "JTAG_MCP_TRST_N")
	)
	(segment
		(start 405.473916 -66.915284)
		(end 403.792944 -68.596256)
		(width 0.10795)
		(layer "B.Cu")
		(net "JTAG_MCP_TRST_N")
	)
	(segment
		(start 407.861262 -66.262758)
		(end 407.16073 -66.262758)
		(width 0.10795)
		(layer "B.Cu")
		(net "JTAG_MCP_TRST_N")
	)
	(segment
		(start 407.16073 -66.262758)
		(end 407.071322 -66.352166)
		(width 0.10795)
		(layer "B.Cu")
		(net "JTAG_MCP_TRST_N")
	)
	(segment
		(start 414.35528 -66.147188)
		(end 414.35528 -67.55257)
		(width 0.10795)
		(layer "B.Cu")
		(net "JTAG_MCP_TRST_N")
	)
	(segment
		(start 396.665704 -70.764654)
		(end 393.24788 -74.182478)
		(width 0.10795)
		(layer "B.Cu")
		(net "JTAG_MCP_TRST_N")
	)
	(segment
		(start 390.40562 -73.4568)
		(end 388.77748 -75.08494)
		(width 0.10795)
		(layer "B.Cu")
		(net "JTAG_MCP_TRST_N")
	)
	(segment
		(start 408.68854 -68.18376)
		(end 408.229054 -67.724274)
		(width 0.10795)
		(layer "B.Cu")
		(net "JTAG_MCP_TRST_N")
	)
	(segment
		(start 400.234658 -68.596256)
		(end 398.532096 -70.298818)
		(width 0.10795)
		(layer "B.Cu")
		(net "JTAG_MCP_TRST_N")
	)
	(segment
		(start 421.636698 -64.103758)
		(end 417.339018 -64.103758)
		(width 0.10795)
		(layer "B.Cu")
		(net "JTAG_MCP_TRST_N")
	)
	(segment
		(start 406.9588 -66.915284)
		(end 405.473916 -66.915284)
		(width 0.10795)
		(layer "B.Cu")
		(net "JTAG_MCP_TRST_N")
	)
	(segment
		(start 407.071322 -66.352166)
		(end 407.071322 -66.802762)
		(width 0.10795)
		(layer "B.Cu")
		(net "JTAG_MCP_TRST_N")
	)
	(segment
		(start 424.9547 -110.778544)
		(end 424.46321 -110.287054)
		(width 0.10795)
		(layer "B.Cu")
		(net "JTAG_MCP_TRST_N")
	)
	(segment
		(start 382.8923 -79.10322)
		(end 382.397 -79.10322)
		(width 0.10795)
		(layer "B.Cu")
		(net "JTAG_MCP_TRST_N")
	)
	(segment
		(start 381.027686 -80.0862)
		(end 380.011686 -81.1022)
		(width 0.10795)
		(layer "B.Cu")
		(net "JTAG_MCP_TRST_N")
	)
	(segment
		(start 428.39259 -117.86997)
		(end 427.381416 -116.858796)
		(width 0.089408)
		(layer "In4.Cu")
		(net "JTAG_MCP_TRST_N")
	)
	(segment
		(start 476.497142 -126.958852)
		(end 476.497142 -123.395232)
		(width 0.089408)
		(layer "In4.Cu")
		(net "JTAG_MCP_TRST_N")
	)
	(segment
		(start 471.699336 -117.397276)
		(end 470.48166 -116.1796)
		(width 0.089408)
		(layer "In4.Cu")
		(net "JTAG_MCP_TRST_N")
	)
	(segment
		(start 430.228502 -118.961408)
		(end 429.137064 -117.86997)
		(width 0.089408)
		(layer "In4.Cu")
		(net "JTAG_MCP_TRST_N")
	)
	(segment
		(start 470.48166 -116.1796)
		(end 465.8868 -116.1796)
		(width 0.089408)
		(layer "In4.Cu")
		(net "JTAG_MCP_TRST_N")
	)
	(segment
		(start 474.993208 -117.397276)
		(end 471.699336 -117.397276)
		(width 0.089408)
		(layer "In4.Cu")
		(net "JTAG_MCP_TRST_N")
	)
	(segment
		(start 427.23308 -113.54308)
		(end 426.674788 -113.54308)
		(width 0.089408)
		(layer "In4.Cu")
		(net "JTAG_MCP_TRST_N")
	)
	(segment
		(start 432.905662 -118.961408)
		(end 430.228502 -118.961408)
		(width 0.089408)
		(layer "In4.Cu")
		(net "JTAG_MCP_TRST_N")
	)
	(segment
		(start 464.881976 -115.174776)
		(end 442.352176 -115.174776)
		(width 0.089408)
		(layer "In4.Cu")
		(net "JTAG_MCP_TRST_N")
	)
	(segment
		(start 427.381416 -116.858796)
		(end 427.381416 -115.934236)
		(width 0.089408)
		(layer "In4.Cu")
		(net "JTAG_MCP_TRST_N")
	)
	(segment
		(start 425.089066 -112.437418)
		(end 425.0817 -112.444784)
		(width 0.089408)
		(layer "In4.Cu")
		(net "JTAG_MCP_TRST_N")
	)
	(segment
		(start 429.137064 -117.86997)
		(end 428.39259 -117.86997)
		(width 0.089408)
		(layer "In4.Cu")
		(net "JTAG_MCP_TRST_N")
	)
	(segment
		(start 427.609 -113.919)
		(end 427.23308 -113.54308)
		(width 0.089408)
		(layer "In4.Cu")
		(net "JTAG_MCP_TRST_N")
	)
	(segment
		(start 476.497142 -123.395232)
		(end 477.261682 -122.630692)
		(width 0.089408)
		(layer "In4.Cu")
		(net "JTAG_MCP_TRST_N")
	)
	(segment
		(start 477.261682 -119.66575)
		(end 474.993208 -117.397276)
		(width 0.089408)
		(layer "In4.Cu")
		(net "JTAG_MCP_TRST_N")
	)
	(segment
		(start 465.8868 -116.1796)
		(end 464.881976 -115.174776)
		(width 0.089408)
		(layer "In4.Cu")
		(net "JTAG_MCP_TRST_N")
	)
	(segment
		(start 425.569126 -112.437418)
		(end 425.089066 -112.437418)
		(width 0.089408)
		(layer "In4.Cu")
		(net "JTAG_MCP_TRST_N")
	)
	(segment
		(start 435.744366 -116.122704)
		(end 432.905662 -118.961408)
		(width 0.089408)
		(layer "In4.Cu")
		(net "JTAG_MCP_TRST_N")
	)
	(segment
		(start 426.674788 -113.54308)
		(end 425.569126 -112.437418)
		(width 0.089408)
		(layer "In4.Cu")
		(net "JTAG_MCP_TRST_N")
	)
	(segment
		(start 427.609 -115.706652)
		(end 427.609 -113.919)
		(width 0.089408)
		(layer "In4.Cu")
		(net "JTAG_MCP_TRST_N")
	)
	(segment
		(start 427.381416 -115.934236)
		(end 427.609 -115.706652)
		(width 0.089408)
		(layer "In4.Cu")
		(net "JTAG_MCP_TRST_N")
	)
	(segment
		(start 441.404248 -116.122704)
		(end 435.744366 -116.122704)
		(width 0.089408)
		(layer "In4.Cu")
		(net "JTAG_MCP_TRST_N")
	)
	(segment
		(start 477.261682 -122.630692)
		(end 477.261682 -119.66575)
		(width 0.089408)
		(layer "In4.Cu")
		(net "JTAG_MCP_TRST_N")
	)
	(segment
		(start 442.352176 -115.174776)
		(end 441.404248 -116.122704)
		(width 0.089408)
		(layer "In4.Cu")
		(net "JTAG_MCP_TRST_N")
	)
	(segment
		(start 292.715696 -96.31934)
		(end 292.720522 -96.327976)
		(width 0.089408)
		(layer "In11.Cu")
		(net "JTAG_MCP_TRST_N")
	)
	(segment
		(start 265.227054 -156.89326)
		(end 265.127486 -156.992828)
		(width 0.089408)
		(layer "In11.Cu")
		(net "JTAG_MCP_TRST_N")
	)
	(segment
		(start 290.62807 -91.166188)
		(end 290.659312 -91.166188)
		(width 0.089408)
		(layer "In11.Cu")
		(net "JTAG_MCP_TRST_N")
	)
	(segment
		(start 136.833864 -89.489788)
		(end 136.801098 -89.489788)
		(width 0.0889)
		(layer "In11.Cu")
		(net "JTAG_MCP_TRST_N")
	)
	(segment
		(start 265.22934 -156.89326)
		(end 265.227054 -156.89326)
		(width 0.089408)
		(layer "In11.Cu")
		(net "JTAG_MCP_TRST_N")
	)
	(segment
		(start 137.688574 -89.984834)
		(end 137.655808 -89.984834)
		(width 0.0889)
		(layer "In11.Cu")
		(net "JTAG_MCP_TRST_N")
	)
	(segment
		(start 166.15283 -116.612924)
		(end 161.662618 -116.612924)
		(width 0.089408)
		(layer "In11.Cu")
		(net "JTAG_MCP_TRST_N")
	)
	(segment
		(start 289.281616 -85.42274)
		(end 289.286442 -85.431376)
		(width 0.089408)
		(layer "In11.Cu")
		(net "JTAG_MCP_TRST_N")
	)
	(segment
		(start 141.686788 -91.470988)
		(end 140.235178 -91.470988)
		(width 0.0889)
		(layer "In11.Cu")
		(net "JTAG_MCP_TRST_N")
	)
	(segment
		(start 326.715628 -128.265428)
		(end 329.852528 -128.265428)
		(width 0.089408)
		(layer "In11.Cu")
		(net "JTAG_MCP_TRST_N")
	)
	(segment
		(start 320.53403 -124.198126)
		(end 321.709796 -125.373892)
		(width 0.089408)
		(layer "In11.Cu")
		(net "JTAG_MCP_TRST_N")
	)
	(segment
		(start 129.965958 -85.527388)
		(end 129.933192 -85.527388)
		(width 0.0889)
		(layer "In11.Cu")
		(net "JTAG_MCP_TRST_N")
	)
	(segment
		(start 303.903888 -80.6704)
		(end 310.238648 -80.6704)
		(width 0.089408)
		(layer "In11.Cu")
		(net "JTAG_MCP_TRST_N")
	)
	(segment
		(start 130.820668 -86.022434)
		(end 130.787902 -86.022434)
		(width 0.0889)
		(layer "In11.Cu")
		(net "JTAG_MCP_TRST_N")
	)
	(segment
		(start 297.834304 -103.694738)
		(end 301.600108 -107.460542)
		(width 0.089408)
		(layer "In11.Cu")
		(net "JTAG_MCP_TRST_N")
	)
	(segment
		(start 154.99461 -110.399068)
		(end 144.080992 -99.48545)
		(width 0.089408)
		(layer "In11.Cu")
		(net "JTAG_MCP_TRST_N")
	)
	(segment
		(start 144.0434 -93.8276)
		(end 141.686788 -91.470988)
		(width 0.0889)
		(layer "In11.Cu")
		(net "JTAG_MCP_TRST_N")
	)
	(segment
		(start 182.981092 -131.500626)
		(end 177.06848 -131.500626)
		(width 0.089408)
		(layer "In11.Cu")
		(net "JTAG_MCP_TRST_N")
	)
	(segment
		(start 172.078142 -128.117346)
		(end 172.078142 -127.72263)
		(width 0.089408)
		(layer "In11.Cu")
		(net "JTAG_MCP_TRST_N")
	)
	(segment
		(start 292.715696 -98.30054)
		(end 292.720522 -98.309176)
		(width 0.089408)
		(layer "In11.Cu")
		(net "JTAG_MCP_TRST_N")
	)
	(segment
		(start 292.709346 -97.299272)
		(end 292.715696 -97.30994)
		(width 0.089408)
		(layer "In11.Cu")
		(net "JTAG_MCP_TRST_N")
	)
	(segment
		(start 161.662618 -116.612924)
		(end 155.448762 -110.399068)
		(width 0.089408)
		(layer "In11.Cu")
		(net "JTAG_MCP_TRST_N")
	)
	(segment
		(start 290.040314 -80.675226)
		(end 290.445952 -80.269588)
		(width 0.089408)
		(layer "In11.Cu")
		(net "JTAG_MCP_TRST_N")
	)
	(segment
		(start 330.209398 -138.199622)
		(end 325.977504 -138.199622)
		(width 0.089408)
		(layer "In11.Cu")
		(net "JTAG_MCP_TRST_N")
	)
	(segment
		(start 191.964818 -132.014976)
		(end 191.964818 -130.175)
		(width 0.089408)
		(layer "In11.Cu")
		(net "JTAG_MCP_TRST_N")
	)
	(segment
		(start 289.347402 -81.82737)
		(end 289.347402 -80.896206)
		(width 0.089408)
		(layer "In11.Cu")
		(net "JTAG_MCP_TRST_N")
	)
	(segment
		(start 319.597532 -122.27687)
		(end 320.53403 -123.213368)
		(width 0.089408)
		(layer "In11.Cu")
		(net "JTAG_MCP_TRST_N")
	)
	(segment
		(start 289.281616 -88.39454)
		(end 289.286442 -88.403176)
		(width 0.089408)
		(layer "In11.Cu")
		(net "JTAG_MCP_TRST_N")
	)
	(segment
		(start 302.505618 -107.460542)
		(end 317.321946 -122.27687)
		(width 0.089408)
		(layer "In11.Cu")
		(net "JTAG_MCP_TRST_N")
	)
	(segment
		(start 288.93516 -82.650584)
		(end 289.264598 -83.41233)
		(width 0.089408)
		(layer "In11.Cu")
		(net "JTAG_MCP_TRST_N")
	)
	(segment
		(start 291.490146 -91.661742)
		(end 291.522912 -91.661742)
		(width 0.089408)
		(layer "In11.Cu")
		(net "JTAG_MCP_TRST_N")
	)
	(segment
		(start 289.275266 -88.383872)
		(end 289.281616 -88.39454)
		(width 0.089408)
		(layer "In11.Cu")
		(net "JTAG_MCP_TRST_N")
	)
	(segment
		(start 131.6863 -86.517988)
		(end 131.650232 -86.517988)
		(width 0.0889)
		(layer "In11.Cu")
		(net "JTAG_MCP_TRST_N")
	)
	(segment
		(start 134.254494 -88.003634)
		(end 134.221728 -88.003634)
		(width 0.0889)
		(layer "In11.Cu")
		(net "JTAG_MCP_TRST_N")
	)
	(segment
		(start 302.664114 -81.260188)
		(end 302.695356 -81.260188)
		(width 0.089408)
		(layer "In11.Cu")
		(net "JTAG_MCP_TRST_N")
	)
	(segment
		(start 289.773106 -90.671142)
		(end 289.805872 -90.671142)
		(width 0.089408)
		(layer "In11.Cu")
		(net "JTAG_MCP_TRST_N")
	)
	(segment
		(start 288.93516 -82.650584)
		(end 288.93516 -82.239612)
		(width 0.089408)
		(layer "In11.Cu")
		(net "JTAG_MCP_TRST_N")
	)
	(segment
		(start 320.53403 -123.213368)
		(end 320.53403 -124.198126)
		(width 0.089408)
		(layer "In11.Cu")
		(net "JTAG_MCP_TRST_N")
	)
	(segment
		(start 292.709346 -98.289872)
		(end 292.715696 -98.30054)
		(width 0.089408)
		(layer "In11.Cu")
		(net "JTAG_MCP_TRST_N")
	)
	(segment
		(start 299.216572 -82.250788)
		(end 299.25772 -82.250788)
		(width 0.089408)
		(layer "In11.Cu")
		(net "JTAG_MCP_TRST_N")
	)
	(segment
		(start 317.321946 -122.27687)
		(end 319.597532 -122.27687)
		(width 0.089408)
		(layer "In11.Cu")
		(net "JTAG_MCP_TRST_N")
	)
	(segment
		(start 128.248918 -84.536788)
		(end 128.216152 -84.536788)
		(width 0.0889)
		(layer "In11.Cu")
		(net "JTAG_MCP_TRST_N")
	)
	(segment
		(start 125.669548 -83.050634)
		(end 125.636782 -83.050634)
		(width 0.0889)
		(layer "In11.Cu")
		(net "JTAG_MCP_TRST_N")
	)
	(segment
		(start 297.173904 -81.46034)
		(end 297.179238 -81.450942)
		(width 0.089408)
		(layer "In11.Cu")
		(net "JTAG_MCP_TRST_N")
	)
	(segment
		(start 298.358052 -81.755742)
		(end 298.397422 -81.755742)
		(width 0.089408)
		(layer "In11.Cu")
		(net "JTAG_MCP_TRST_N")
	)
	(segment
		(start 289.281616 -84.43214)
		(end 289.286442 -84.440776)
		(width 0.089408)
		(layer "In11.Cu")
		(net "JTAG_MCP_TRST_N")
	)
	(segment
		(start 311.041542 -79.867506)
		(end 330.759562 -79.867506)
		(width 0.089408)
		(layer "In11.Cu")
		(net "JTAG_MCP_TRST_N")
	)
	(segment
		(start 132.537454 -87.013034)
		(end 132.519674 -87.013034)
		(width 0.0889)
		(layer "In11.Cu")
		(net "JTAG_MCP_TRST_N")
	)
	(segment
		(start 192.46215 -148.99132)
		(end 192.46215 -132.512308)
		(width 0.089408)
		(layer "In11.Cu")
		(net "JTAG_MCP_TRST_N")
	)
	(segment
		(start 289.275266 -85.412072)
		(end 289.281616 -85.42274)
		(width 0.089408)
		(layer "In11.Cu")
		(net "JTAG_MCP_TRST_N")
	)
	(segment
		(start 176.223168 -130.655314)
		(end 176.223168 -129.668778)
		(width 0.089408)
		(layer "In11.Cu")
		(net "JTAG_MCP_TRST_N")
	)
	(segment
		(start 129.103628 -85.031834)
		(end 129.070862 -85.031834)
		(width 0.0889)
		(layer "In11.Cu")
		(net "JTAG_MCP_TRST_N")
	)
	(segment
		(start 293.207186 -99.586542)
		(end 293.239952 -99.586542)
		(width 0.089408)
		(layer "In11.Cu")
		(net "JTAG_MCP_TRST_N")
	)
	(segment
		(start 301.79391 -81.755742)
		(end 301.83328 -81.755742)
		(width 0.089408)
		(layer "In11.Cu")
		(net "JTAG_MCP_TRST_N")
	)
	(segment
		(start 171.406566 -126.3142)
		(end 171.188634 -126.3142)
		(width 0.089408)
		(layer "In11.Cu")
		(net "JTAG_MCP_TRST_N")
	)
	(segment
		(start 289.281616 -83.44154)
		(end 289.286442 -83.450176)
		(width 0.089408)
		(layer "In11.Cu")
		(net "JTAG_MCP_TRST_N")
	)
	(segment
		(start 170.612816 -123.69038)
		(end 170.612816 -122.97918)
		(width 0.089408)
		(layer "In11.Cu")
		(net "JTAG_MCP_TRST_N")
	)
	(segment
		(start 294.06215 -81.260188)
		(end 294.093392 -81.260188)
		(width 0.089408)
		(layer "In11.Cu")
		(net "JTAG_MCP_TRST_N")
	)
	(segment
		(start 294.499538 -101.726492)
		(end 294.499538 -102.08895)
		(width 0.089408)
		(layer "In11.Cu")
		(net "JTAG_MCP_TRST_N")
	)
	(segment
		(start 289.568382 -80.675226)
		(end 290.040314 -80.675226)
		(width 0.089408)
		(layer "In11.Cu")
		(net "JTAG_MCP_TRST_N")
	)
	(segment
		(start 173.994064 -128.42621)
		(end 173.99381 -128.425956)
		(width 0.089408)
		(layer "In11.Cu")
		(net "JTAG_MCP_TRST_N")
	)
	(segment
		(start 292.709346 -96.308672)
		(end 292.715696 -96.31934)
		(width 0.089408)
		(layer "In11.Cu")
		(net "JTAG_MCP_TRST_N")
	)
	(segment
		(start 170.68292 -122.909076)
		(end 170.68292 -121.143014)
		(width 0.089408)
		(layer "In11.Cu")
		(net "JTAG_MCP_TRST_N")
	)
	(segment
		(start 127.386588 -84.041234)
		(end 127.353822 -84.041234)
		(width 0.0889)
		(layer "In11.Cu")
		(net "JTAG_MCP_TRST_N")
	)
	(segment
		(start 323.558154 -149.346412)
		(end 323.558154 -154.512772)
		(width 0.089408)
		(layer "In11.Cu")
		(net "JTAG_MCP_TRST_N")
	)
	(segment
		(start 172.256704 -127.544068)
		(end 172.256704 -127.164338)
		(width 0.089408)
		(layer "In11.Cu")
		(net "JTAG_MCP_TRST_N")
	)
	(segment
		(start 300.07687 -81.755742)
		(end 300.114462 -81.755742)
		(width 0.089408)
		(layer "In11.Cu")
		(net "JTAG_MCP_TRST_N")
	)
	(segment
		(start 332.301342 -132.975858)
		(end 332.301342 -136.107678)
		(width 0.089408)
		(layer "In11.Cu")
		(net "JTAG_MCP_TRST_N")
	)
	(segment
		(start 324.085712 -140.091414)
		(end 324.085712 -148.818854)
		(width 0.089408)
		(layer "In11.Cu")
		(net "JTAG_MCP_TRST_N")
	)
	(segment
		(start 323.558154 -154.512772)
		(end 321.494912 -156.576014)
		(width 0.089408)
		(layer "In11.Cu")
		(net "JTAG_MCP_TRST_N")
	)
	(segment
		(start 265.127486 -156.992828)
		(end 195.598542 -156.992828)
		(width 0.089408)
		(layer "In11.Cu")
		(net "JTAG_MCP_TRST_N")
	)
	(segment
		(start 329.852528 -128.265428)
		(end 332.9813 -131.3942)
		(width 0.089408)
		(layer "In11.Cu")
		(net "JTAG_MCP_TRST_N")
	)
	(segment
		(start 289.275266 -86.402672)
		(end 289.281616 -86.41334)
		(width 0.089408)
		(layer "In11.Cu")
		(net "JTAG_MCP_TRST_N")
	)
	(segment
		(start 289.275266 -87.393272)
		(end 289.281616 -87.40394)
		(width 0.089408)
		(layer "In11.Cu")
		(net "JTAG_MCP_TRST_N")
	)
	(segment
		(start 170.68292 -121.143014)
		(end 166.15283 -116.612924)
		(width 0.089408)
		(layer "In11.Cu")
		(net "JTAG_MCP_TRST_N")
	)
	(segment
		(start 325.833994 -127.383794)
		(end 326.715628 -128.265428)
		(width 0.089408)
		(layer "In11.Cu")
		(net "JTAG_MCP_TRST_N")
	)
	(segment
		(start 170.68292 -123.760484)
		(end 170.612816 -123.69038)
		(width 0.089408)
		(layer "In11.Cu")
		(net "JTAG_MCP_TRST_N")
	)
	(segment
		(start 126.531878 -83.546188)
		(end 126.499112 -83.546188)
		(width 0.0889)
		(layer "In11.Cu")
		(net "JTAG_MCP_TRST_N")
	)
	(segment
		(start 289.281616 -89.38514)
		(end 289.286442 -89.393776)
		(width 0.089408)
		(layer "In11.Cu")
		(net "JTAG_MCP_TRST_N")
	)
	(segment
		(start 172.078142 -127.72263)
		(end 172.256704 -127.544068)
		(width 0.089408)
		(layer "In11.Cu")
		(net "JTAG_MCP_TRST_N")
	)
	(segment
		(start 289.275266 -84.421472)
		(end 289.281616 -84.43214)
		(width 0.089408)
		(layer "In11.Cu")
		(net "JTAG_MCP_TRST_N")
	)
	(segment
		(start 322.312792 -125.572012)
		(end 323.287136 -125.572012)
		(width 0.089408)
		(layer "In11.Cu")
		(net "JTAG_MCP_TRST_N")
	)
	(segment
		(start 324.085712 -148.818854)
		(end 323.558154 -149.346412)
		(width 0.089408)
		(layer "In11.Cu")
		(net "JTAG_MCP_TRST_N")
	)
	(segment
		(start 193.413634 -154.80792)
		(end 193.413634 -149.942804)
		(width 0.089408)
		(layer "In11.Cu")
		(net "JTAG_MCP_TRST_N")
	)
	(segment
		(start 144.0434 -98.993706)
		(end 144.0434 -93.8276)
		(width 0.089408)
		(layer "In11.Cu")
		(net "JTAG_MCP_TRST_N")
	)
	(segment
		(start 288.93516 -82.239612)
		(end 289.347402 -81.82737)
		(width 0.089408)
		(layer "In11.Cu")
		(net "JTAG_MCP_TRST_N")
	)
	(segment
		(start 170.68292 -125.808486)
		(end 170.68292 -123.760484)
		(width 0.089408)
		(layer "In11.Cu")
		(net "JTAG_MCP_TRST_N")
	)
	(segment
		(start 292.715696 -93.34754)
		(end 292.720522 -93.356176)
		(width 0.089408)
		(layer "In11.Cu")
		(net "JTAG_MCP_TRST_N")
	)
	(segment
		(start 321.709796 -125.373892)
		(end 322.114672 -125.373892)
		(width 0.089408)
		(layer "In11.Cu")
		(net "JTAG_MCP_TRST_N")
	)
	(segment
		(start 300.933612 -82.250788)
		(end 300.97476 -82.250788)
		(width 0.089408)
		(layer "In11.Cu")
		(net "JTAG_MCP_TRST_N")
	)
	(segment
		(start 289.275266 -89.374472)
		(end 289.281616 -89.38514)
		(width 0.089408)
		(layer "In11.Cu")
		(net "JTAG_MCP_TRST_N")
	)
	(segment
		(start 301.600108 -107.460542)
		(end 302.505618 -107.460542)
		(width 0.089408)
		(layer "In11.Cu")
		(net "JTAG_MCP_TRST_N")
	)
	(segment
		(start 124.806202 -82.555334)
		(end 124.793248 -82.555334)
		(width 0.0889)
		(layer "In11.Cu")
		(net "JTAG_MCP_TRST_N")
	)
	(segment
		(start 135.116824 -88.499188)
		(end 135.084058 -88.499188)
		(width 0.0889)
		(layer "In11.Cu")
		(net "JTAG_MCP_TRST_N")
	)
	(segment
		(start 322.114672 -125.373892)
		(end 322.312792 -125.572012)
		(width 0.089408)
		(layer "In11.Cu")
		(net "JTAG_MCP_TRST_N")
	)
	(segment
		(start 133.399784 -87.508588)
		(end 133.367018 -87.508588)
		(width 0.0889)
		(layer "In11.Cu")
		(net "JTAG_MCP_TRST_N")
	)
	(segment
		(start 289.281616 -86.41334)
		(end 289.286442 -86.421976)
		(width 0.089408)
		(layer "In11.Cu")
		(net "JTAG_MCP_TRST_N")
	)
	(segment
		(start 171.188634 -126.3142)
		(end 170.68292 -125.808486)
		(width 0.089408)
		(layer "In11.Cu")
		(net "JTAG_MCP_TRST_N")
	)
	(segment
		(start 172.386752 -128.425956)
		(end 172.078142 -128.117346)
		(width 0.089408)
		(layer "In11.Cu")
		(net "JTAG_MCP_TRST_N")
	)
	(segment
		(start 170.612816 -122.97918)
		(end 170.68292 -122.909076)
		(width 0.089408)
		(layer "In11.Cu")
		(net "JTAG_MCP_TRST_N")
	)
	(segment
		(start 325.977504 -138.199622)
		(end 324.085712 -140.091414)
		(width 0.089408)
		(layer "In11.Cu")
		(net "JTAG_MCP_TRST_N")
	)
	(segment
		(start 296.105326 -103.694738)
		(end 297.834304 -103.694738)
		(width 0.089408)
		(layer "In11.Cu")
		(net "JTAG_MCP_TRST_N")
	)
	(segment
		(start 332.301342 -136.107678)
		(end 330.209398 -138.199622)
		(width 0.089408)
		(layer "In11.Cu")
		(net "JTAG_MCP_TRST_N")
	)
	(segment
		(start 132.17652 -86.818724)
		(end 132.173218 -86.812882)
		(width 0.0889)
		(layer "In11.Cu")
		(net "JTAG_MCP_TRST_N")
	)
	(segment
		(start 325.098918 -127.383794)
		(end 325.833994 -127.383794)
		(width 0.089408)
		(layer "In11.Cu")
		(net "JTAG_MCP_TRST_N")
	)
	(segment
		(start 290.445952 -80.269588)
		(end 290.659312 -80.269588)
		(width 0.089408)
		(layer "In11.Cu")
		(net "JTAG_MCP_TRST_N")
	)
	(segment
		(start 174.9806 -128.42621)
		(end 173.994064 -128.42621)
		(width 0.089408)
		(layer "In11.Cu")
		(net "JTAG_MCP_TRST_N")
	)
	(segment
		(start 293.207186 -80.765142)
		(end 293.239952 -80.765142)
		(width 0.089408)
		(layer "In11.Cu")
		(net "JTAG_MCP_TRST_N")
	)
	(segment
		(start 192.46215 -132.512308)
		(end 191.964818 -132.014976)
		(width 0.089408)
		(layer "In11.Cu")
		(net "JTAG_MCP_TRST_N")
	)
	(segment
		(start 303.809146 -80.765142)
		(end 303.903888 -80.6704)
		(width 0.089408)
		(layer "In11.Cu")
		(net "JTAG_MCP_TRST_N")
	)
	(segment
		(start 292.715696 -97.30994)
		(end 292.720522 -97.318576)
		(width 0.089408)
		(layer "In11.Cu")
		(net "JTAG_MCP_TRST_N")
	)
	(segment
		(start 144.080992 -99.48545)
		(end 144.080992 -99.031298)
		(width 0.089408)
		(layer "In11.Cu")
		(net "JTAG_MCP_TRST_N")
	)
	(segment
		(start 193.413634 -149.942804)
		(end 192.46215 -148.99132)
		(width 0.089408)
		(layer "In11.Cu")
		(net "JTAG_MCP_TRST_N")
	)
	(segment
		(start 289.264598 -83.41233)
		(end 289.281616 -83.44154)
		(width 0.089408)
		(layer "In11.Cu")
		(net "JTAG_MCP_TRST_N")
	)
	(segment
		(start 177.06848 -131.500626)
		(end 176.223168 -130.655314)
		(width 0.089408)
		(layer "In11.Cu")
		(net "JTAG_MCP_TRST_N")
	)
	(segment
		(start 292.720522 -94.729046)
		(end 292.715696 -94.737682)
		(width 0.089408)
		(layer "In11.Cu")
		(net "JTAG_MCP_TRST_N")
	)
	(segment
		(start 176.223168 -129.668778)
		(end 174.9806 -128.42621)
		(width 0.089408)
		(layer "In11.Cu")
		(net "JTAG_MCP_TRST_N")
	)
	(segment
		(start 310.238648 -80.6704)
		(end 311.041542 -79.867506)
		(width 0.089408)
		(layer "In11.Cu")
		(net "JTAG_MCP_TRST_N")
	)
	(segment
		(start 292.709346 -94.327472)
		(end 292.715696 -94.33814)
		(width 0.089408)
		(layer "In11.Cu")
		(net "JTAG_MCP_TRST_N")
	)
	(segment
		(start 185.622438 -128.85928)
		(end 182.981092 -131.500626)
		(width 0.089408)
		(layer "In11.Cu")
		(net "JTAG_MCP_TRST_N")
	)
	(segment
		(start 139.405614 -90.975434)
		(end 139.372848 -90.975434)
		(width 0.0889)
		(layer "In11.Cu")
		(net "JTAG_MCP_TRST_N")
	)
	(segment
		(start 292.34511 -92.156788)
		(end 292.376352 -92.156788)
		(width 0.089408)
		(layer "In11.Cu")
		(net "JTAG_MCP_TRST_N")
	)
	(segment
		(start 138.550904 -90.480388)
		(end 138.518138 -90.480388)
		(width 0.0889)
		(layer "In11.Cu")
		(net "JTAG_MCP_TRST_N")
	)
	(segment
		(start 323.287136 -125.572012)
		(end 325.098918 -127.383794)
		(width 0.089408)
		(layer "In11.Cu")
		(net "JTAG_MCP_TRST_N")
	)
	(segment
		(start 332.9813 -131.3942)
		(end 332.9813 -132.2959)
		(width 0.089408)
		(layer "In11.Cu")
		(net "JTAG_MCP_TRST_N")
	)
	(segment
		(start 296.641266 -81.755742)
		(end 296.682414 -81.755742)
		(width 0.089408)
		(layer "In11.Cu")
		(net "JTAG_MCP_TRST_N")
	)
	(segment
		(start 265.546586 -156.576014)
		(end 265.22934 -156.89326)
		(width 0.089408)
		(layer "In11.Cu")
		(net "JTAG_MCP_TRST_N")
	)
	(segment
		(start 332.9813 -132.2959)
		(end 332.301342 -132.975858)
		(width 0.089408)
		(layer "In11.Cu")
		(net "JTAG_MCP_TRST_N")
	)
	(segment
		(start 190.649098 -128.85928)
		(end 185.622438 -128.85928)
		(width 0.089408)
		(layer "In11.Cu")
		(net "JTAG_MCP_TRST_N")
	)
	(segment
		(start 289.347402 -80.896206)
		(end 289.568382 -80.675226)
		(width 0.089408)
		(layer "In11.Cu")
		(net "JTAG_MCP_TRST_N")
	)
	(segment
		(start 135.971534 -88.994234)
		(end 135.938768 -88.994234)
		(width 0.0889)
		(layer "In11.Cu")
		(net "JTAG_MCP_TRST_N")
	)
	(segment
		(start 294.108632 -101.335586)
		(end 294.499538 -101.726492)
		(width 0.089408)
		(layer "In11.Cu")
		(net "JTAG_MCP_TRST_N")
	)
	(segment
		(start 294.499538 -102.08895)
		(end 296.105326 -103.694738)
		(width 0.089408)
		(layer "In11.Cu")
		(net "JTAG_MCP_TRST_N")
	)
	(segment
		(start 289.281616 -87.40394)
		(end 289.286442 -87.412576)
		(width 0.089408)
		(layer "In11.Cu")
		(net "JTAG_MCP_TRST_N")
	)
	(segment
		(start 195.598542 -156.992828)
		(end 193.413634 -154.80792)
		(width 0.089408)
		(layer "In11.Cu")
		(net "JTAG_MCP_TRST_N")
	)
	(segment
		(start 191.964818 -130.175)
		(end 190.649098 -128.85928)
		(width 0.089408)
		(layer "In11.Cu")
		(net "JTAG_MCP_TRST_N")
	)
	(segment
		(start 172.256704 -127.164338)
		(end 171.406566 -126.3142)
		(width 0.089408)
		(layer "In11.Cu")
		(net "JTAG_MCP_TRST_N")
	)
	(segment
		(start 144.080992 -99.031298)
		(end 144.0434 -98.993706)
		(width 0.089408)
		(layer "In11.Cu")
		(net "JTAG_MCP_TRST_N")
	)
	(segment
		(start 294.924226 -81.755742)
		(end 294.965374 -81.755742)
		(width 0.089408)
		(layer "In11.Cu")
		(net "JTAG_MCP_TRST_N")
	)
	(segment
		(start 303.517554 -80.765142)
		(end 303.809146 -80.765142)
		(width 0.089408)
		(layer "In11.Cu")
		(net "JTAG_MCP_TRST_N")
	)
	(segment
		(start 292.709346 -93.336872)
		(end 292.715696 -93.34754)
		(width 0.089408)
		(layer "In11.Cu")
		(net "JTAG_MCP_TRST_N")
	)
	(segment
		(start 173.99381 -128.425956)
		(end 172.386752 -128.425956)
		(width 0.089408)
		(layer "In11.Cu")
		(net "JTAG_MCP_TRST_N")
	)
	(segment
		(start 321.494912 -156.576014)
		(end 265.546586 -156.576014)
		(width 0.089408)
		(layer "In11.Cu")
		(net "JTAG_MCP_TRST_N")
	)
	(segment
		(start 155.448762 -110.399068)
		(end 154.99461 -110.399068)
		(width 0.089408)
		(layer "In11.Cu")
		(net "JTAG_MCP_TRST_N")
	)
	(arc
		(start 289.286442 -84.440776)
		(mid 289.335106 -84.636874)
		(end 289.281616 -84.831682)
		(width 0.089408)
		(layer "In11.Cu")
		(net "JTAG_MCP_TRST_N")
	)
	(arc
		(start 139.041124 -90.775536)
		(mid 138.83412 -90.564672)
		(end 138.550904 -90.480388)
		(width 0.0889)
		(layer "In11.Cu")
		(net "JTAG_MCP_TRST_N")
	)
	(arc
		(start 290.998656 -91.36634)
		(mid 291.206185 -91.577624)
		(end 291.490146 -91.661742)
		(width 0.089408)
		(layer "In11.Cu")
		(net "JTAG_MCP_TRST_N")
	)
	(arc
		(start 292.720522 -93.356176)
		(mid 292.769186 -93.552274)
		(end 292.715696 -93.747082)
		(width 0.089408)
		(layer "In11.Cu")
		(net "JTAG_MCP_TRST_N")
	)
	(arc
		(start 139.899644 -91.270836)
		(mid 139.691036 -91.058904)
		(end 139.405614 -90.975434)
		(width 0.0889)
		(layer "In11.Cu")
		(net "JTAG_MCP_TRST_N")
	)
	(arc
		(start 292.715696 -94.33814)
		(mid 292.769073 -94.532949)
		(end 292.720522 -94.729046)
		(width 0.089408)
		(layer "In11.Cu")
		(net "JTAG_MCP_TRST_N")
	)
	(arc
		(start 292.715696 -96.718882)
		(mid 292.636381 -97.008254)
		(end 292.709346 -97.299272)
		(width 0.089408)
		(layer "In11.Cu")
		(net "JTAG_MCP_TRST_N")
	)
	(arc
		(start 129.933192 -85.527388)
		(mid 129.739342 -85.471038)
		(end 129.597658 -85.327236)
		(width 0.0889)
		(layer "In11.Cu")
		(net "JTAG_MCP_TRST_N")
	)
	(arc
		(start 292.720522 -97.318576)
		(mid 292.769186 -97.514674)
		(end 292.715696 -97.709482)
		(width 0.089408)
		(layer "In11.Cu")
		(net "JTAG_MCP_TRST_N")
	)
	(arc
		(start 289.281616 -85.822282)
		(mid 289.202301 -86.111654)
		(end 289.275266 -86.402672)
		(width 0.089408)
		(layer "In11.Cu")
		(net "JTAG_MCP_TRST_N")
	)
	(arc
		(start 137.655808 -89.984834)
		(mid 137.464166 -89.927668)
		(end 137.324084 -89.784936)
		(width 0.0889)
		(layer "In11.Cu")
		(net "JTAG_MCP_TRST_N")
	)
	(arc
		(start 132.519674 -87.013034)
		(mid 132.322513 -86.961075)
		(end 132.17652 -86.818724)
		(width 0.0889)
		(layer "In11.Cu")
		(net "JTAG_MCP_TRST_N")
	)
	(arc
		(start 125.636782 -83.050634)
		(mid 125.44514 -82.993468)
		(end 125.305058 -82.850736)
		(width 0.0889)
		(layer "In11.Cu")
		(net "JTAG_MCP_TRST_N")
	)
	(arc
		(start 289.286442 -85.431376)
		(mid 289.335106 -85.627474)
		(end 289.281616 -85.822282)
		(width 0.089408)
		(layer "In11.Cu")
		(net "JTAG_MCP_TRST_N")
	)
	(arc
		(start 294.965374 -81.755742)
		(mid 295.249335 -81.671624)
		(end 295.456864 -81.46034)
		(width 0.089408)
		(layer "In11.Cu")
		(net "JTAG_MCP_TRST_N")
	)
	(arc
		(start 296.682414 -81.755742)
		(mid 296.966375 -81.671624)
		(end 297.173904 -81.46034)
		(width 0.089408)
		(layer "In11.Cu")
		(net "JTAG_MCP_TRST_N")
	)
	(arc
		(start 293.574216 -80.96504)
		(mid 293.780253 -81.175318)
		(end 294.06215 -81.260188)
		(width 0.089408)
		(layer "In11.Cu")
		(net "JTAG_MCP_TRST_N")
	)
	(arc
		(start 134.748524 -88.299036)
		(mid 134.539916 -88.087104)
		(end 134.254494 -88.003634)
		(width 0.0889)
		(layer "In11.Cu")
		(net "JTAG_MCP_TRST_N")
	)
	(arc
		(start 291.522912 -91.661742)
		(mid 291.716015 -91.718261)
		(end 291.857176 -91.86164)
		(width 0.089408)
		(layer "In11.Cu")
		(net "JTAG_MCP_TRST_N")
	)
	(arc
		(start 132.173218 -86.812882)
		(mid 131.967597 -86.602959)
		(end 131.6863 -86.517988)
		(width 0.0889)
		(layer "In11.Cu")
		(net "JTAG_MCP_TRST_N")
	)
	(arc
		(start 292.715696 -95.728282)
		(mid 292.636381 -96.017654)
		(end 292.709346 -96.308672)
		(width 0.089408)
		(layer "In11.Cu")
		(net "JTAG_MCP_TRST_N")
	)
	(arc
		(start 128.216152 -84.536788)
		(mid 128.022302 -84.480438)
		(end 127.880618 -84.336636)
		(width 0.0889)
		(layer "In11.Cu")
		(net "JTAG_MCP_TRST_N")
	)
	(arc
		(start 130.787902 -86.022434)
		(mid 130.59626 -85.965268)
		(end 130.456178 -85.822536)
		(width 0.0889)
		(layer "In11.Cu")
		(net "JTAG_MCP_TRST_N")
	)
	(arc
		(start 299.74921 -81.955386)
		(mid 299.887538 -81.813709)
		(end 300.07687 -81.755742)
		(width 0.089408)
		(layer "In11.Cu")
		(net "JTAG_MCP_TRST_N")
	)
	(arc
		(start 140.235178 -91.470988)
		(mid 140.041328 -91.414638)
		(end 139.899644 -91.270836)
		(width 0.0889)
		(layer "In11.Cu")
		(net "JTAG_MCP_TRST_N")
	)
	(arc
		(start 125.305058 -82.850736)
		(mid 125.094345 -82.637657)
		(end 124.806202 -82.555334)
		(width 0.0889)
		(layer "In11.Cu")
		(net "JTAG_MCP_TRST_N")
	)
	(arc
		(start 294.432736 -81.46034)
		(mid 294.640265 -81.671624)
		(end 294.924226 -81.755742)
		(width 0.089408)
		(layer "In11.Cu")
		(net "JTAG_MCP_TRST_N")
	)
	(arc
		(start 292.715696 -80.46974)
		(mid 292.923225 -80.681024)
		(end 293.207186 -80.765142)
		(width 0.089408)
		(layer "In11.Cu")
		(net "JTAG_MCP_TRST_N")
	)
	(arc
		(start 302.695356 -81.260188)
		(mid 302.977258 -81.175325)
		(end 303.18329 -80.96504)
		(width 0.089408)
		(layer "In11.Cu")
		(net "JTAG_MCP_TRST_N")
	)
	(arc
		(start 292.715696 -95.328486)
		(mid 292.769229 -95.528384)
		(end 292.715696 -95.728282)
		(width 0.089408)
		(layer "In11.Cu")
		(net "JTAG_MCP_TRST_N")
	)
	(arc
		(start 293.574216 -100.77704)
		(mid 293.61196 -100.835004)
		(end 293.65575 -100.888546)
		(width 0.089408)
		(layer "In11.Cu")
		(net "JTAG_MCP_TRST_N")
	)
	(arc
		(start 295.456864 -81.46034)
		(mid 295.80332 -81.260122)
		(end 296.149776 -81.46034)
		(width 0.089408)
		(layer "In11.Cu")
		(net "JTAG_MCP_TRST_N")
	)
	(arc
		(start 302.32477 -81.46034)
		(mid 302.468081 -81.315569)
		(end 302.664114 -81.260188)
		(width 0.089408)
		(layer "In11.Cu")
		(net "JTAG_MCP_TRST_N")
	)
	(arc
		(start 127.880618 -84.336636)
		(mid 127.67201 -84.124704)
		(end 127.386588 -84.041234)
		(width 0.0889)
		(layer "In11.Cu")
		(net "JTAG_MCP_TRST_N")
	)
	(arc
		(start 129.597658 -85.327236)
		(mid 129.38905 -85.115304)
		(end 129.103628 -85.031834)
		(width 0.0889)
		(layer "In11.Cu")
		(net "JTAG_MCP_TRST_N")
	)
	(arc
		(start 292.715696 -93.747082)
		(mid 292.636381 -94.036454)
		(end 292.709346 -94.327472)
		(width 0.089408)
		(layer "In11.Cu")
		(net "JTAG_MCP_TRST_N")
	)
	(arc
		(start 289.281616 -86.812882)
		(mid 289.202301 -87.102254)
		(end 289.275266 -87.393272)
		(width 0.089408)
		(layer "In11.Cu")
		(net "JTAG_MCP_TRST_N")
	)
	(arc
		(start 136.801098 -89.489788)
		(mid 136.607248 -89.433438)
		(end 136.465564 -89.289636)
		(width 0.0889)
		(layer "In11.Cu")
		(net "JTAG_MCP_TRST_N")
	)
	(arc
		(start 136.465564 -89.289636)
		(mid 136.256956 -89.077704)
		(end 135.971534 -88.994234)
		(width 0.0889)
		(layer "In11.Cu")
		(net "JTAG_MCP_TRST_N")
	)
	(arc
		(start 289.286442 -83.450176)
		(mid 289.335106 -83.646274)
		(end 289.281616 -83.841082)
		(width 0.089408)
		(layer "In11.Cu")
		(net "JTAG_MCP_TRST_N")
	)
	(arc
		(start 296.149776 -81.46034)
		(mid 296.357305 -81.671624)
		(end 296.641266 -81.755742)
		(width 0.089408)
		(layer "In11.Cu")
		(net "JTAG_MCP_TRST_N")
	)
	(arc
		(start 289.286442 -87.412576)
		(mid 289.335106 -87.608674)
		(end 289.281616 -87.803482)
		(width 0.089408)
		(layer "In11.Cu")
		(net "JTAG_MCP_TRST_N")
	)
	(arc
		(start 299.25772 -82.250788)
		(mid 299.541681 -82.16667)
		(end 299.74921 -81.955386)
		(width 0.089408)
		(layer "In11.Cu")
		(net "JTAG_MCP_TRST_N")
	)
	(arc
		(start 131.314698 -86.317836)
		(mid 131.10609 -86.105904)
		(end 130.820668 -86.022434)
		(width 0.0889)
		(layer "In11.Cu")
		(net "JTAG_MCP_TRST_N")
	)
	(arc
		(start 293.574216 -100.186236)
		(mid 293.495119 -100.481638)
		(end 293.574216 -100.77704)
		(width 0.089408)
		(layer "In11.Cu")
		(net "JTAG_MCP_TRST_N")
	)
	(arc
		(start 135.607044 -88.794336)
		(mid 135.40004 -88.583472)
		(end 135.116824 -88.499188)
		(width 0.0889)
		(layer "In11.Cu")
		(net "JTAG_MCP_TRST_N")
	)
	(arc
		(start 293.65575 -100.888546)
		(mid 293.876318 -101.118016)
		(end 294.108632 -101.335586)
		(width 0.089408)
		(layer "In11.Cu")
		(net "JTAG_MCP_TRST_N")
	)
	(arc
		(start 292.715696 -94.737682)
		(mid 292.636599 -95.033084)
		(end 292.715696 -95.328486)
		(width 0.089408)
		(layer "In11.Cu")
		(net "JTAG_MCP_TRST_N")
	)
	(arc
		(start 290.659312 -80.269588)
		(mid 290.855344 -80.324972)
		(end 290.998656 -80.46974)
		(width 0.089408)
		(layer "In11.Cu")
		(net "JTAG_MCP_TRST_N")
	)
	(arc
		(start 297.179238 -81.450942)
		(mid 297.525573 -81.260159)
		(end 297.866562 -81.46034)
		(width 0.089408)
		(layer "In11.Cu")
		(net "JTAG_MCP_TRST_N")
	)
	(arc
		(start 135.084058 -88.499188)
		(mid 134.890208 -88.442838)
		(end 134.748524 -88.299036)
		(width 0.0889)
		(layer "In11.Cu")
		(net "JTAG_MCP_TRST_N")
	)
	(arc
		(start 300.442122 -81.955386)
		(mid 300.649651 -82.16667)
		(end 300.933612 -82.250788)
		(width 0.089408)
		(layer "In11.Cu")
		(net "JTAG_MCP_TRST_N")
	)
	(arc
		(start 289.281616 -88.794082)
		(mid 289.202301 -89.083454)
		(end 289.275266 -89.374472)
		(width 0.089408)
		(layer "In11.Cu")
		(net "JTAG_MCP_TRST_N")
	)
	(arc
		(start 127.353822 -84.041234)
		(mid 127.16218 -83.984068)
		(end 127.022098 -83.841336)
		(width 0.0889)
		(layer "In11.Cu")
		(net "JTAG_MCP_TRST_N")
	)
	(arc
		(start 291.857176 -91.86164)
		(mid 292.063213 -92.071918)
		(end 292.34511 -92.156788)
		(width 0.089408)
		(layer "In11.Cu")
		(net "JTAG_MCP_TRST_N")
	)
	(arc
		(start 131.650232 -86.517988)
		(mid 131.456382 -86.461638)
		(end 131.314698 -86.317836)
		(width 0.0889)
		(layer "In11.Cu")
		(net "JTAG_MCP_TRST_N")
	)
	(arc
		(start 289.286442 -89.393776)
		(mid 289.335106 -89.589874)
		(end 289.281616 -89.784682)
		(width 0.089408)
		(layer "In11.Cu")
		(net "JTAG_MCP_TRST_N")
	)
	(arc
		(start 127.022098 -83.841336)
		(mid 126.815094 -83.630472)
		(end 126.531878 -83.546188)
		(width 0.0889)
		(layer "In11.Cu")
		(net "JTAG_MCP_TRST_N")
	)
	(arc
		(start 126.499112 -83.546188)
		(mid 126.305262 -83.489838)
		(end 126.163578 -83.346036)
		(width 0.0889)
		(layer "In11.Cu")
		(net "JTAG_MCP_TRST_N")
	)
	(arc
		(start 293.239952 -80.765142)
		(mid 293.433055 -80.821661)
		(end 293.574216 -80.96504)
		(width 0.089408)
		(layer "In11.Cu")
		(net "JTAG_MCP_TRST_N")
	)
	(arc
		(start 290.998656 -80.46974)
		(mid 291.51072 -80.765499)
		(end 292.022784 -80.46974)
		(width 0.089408)
		(layer "In11.Cu")
		(net "JTAG_MCP_TRST_N")
	)
	(arc
		(start 294.093392 -81.260188)
		(mid 294.289424 -81.315572)
		(end 294.432736 -81.46034)
		(width 0.089408)
		(layer "In11.Cu")
		(net "JTAG_MCP_TRST_N")
	)
	(arc
		(start 297.866562 -81.46034)
		(mid 298.074091 -81.671624)
		(end 298.358052 -81.755742)
		(width 0.089408)
		(layer "In11.Cu")
		(net "JTAG_MCP_TRST_N")
	)
	(arc
		(start 139.372848 -90.975434)
		(mid 139.181206 -90.918268)
		(end 139.041124 -90.775536)
		(width 0.0889)
		(layer "In11.Cu")
		(net "JTAG_MCP_TRST_N")
	)
	(arc
		(start 290.140136 -90.87104)
		(mid 290.346173 -91.081318)
		(end 290.62807 -91.166188)
		(width 0.089408)
		(layer "In11.Cu")
		(net "JTAG_MCP_TRST_N")
	)
	(arc
		(start 292.715696 -98.700082)
		(mid 292.710618 -99.282419)
		(end 293.207186 -99.586542)
		(width 0.089408)
		(layer "In11.Cu")
		(net "JTAG_MCP_TRST_N")
	)
	(arc
		(start 124.793248 -82.555334)
		(mid 124.361354 -82.579219)
		(end 123.934728 -82.650584)
		(width 0.0889)
		(layer "In11.Cu")
		(net "JTAG_MCP_TRST_N")
	)
	(arc
		(start 303.18329 -80.96504)
		(mid 303.324447 -80.821655)
		(end 303.517554 -80.765142)
		(width 0.089408)
		(layer "In11.Cu")
		(net "JTAG_MCP_TRST_N")
	)
	(arc
		(start 289.286442 -88.403176)
		(mid 289.335106 -88.599274)
		(end 289.281616 -88.794082)
		(width 0.089408)
		(layer "In11.Cu")
		(net "JTAG_MCP_TRST_N")
	)
	(arc
		(start 298.397422 -81.755742)
		(mid 298.586751 -81.813713)
		(end 298.725082 -81.955386)
		(width 0.089408)
		(layer "In11.Cu")
		(net "JTAG_MCP_TRST_N")
	)
	(arc
		(start 138.182604 -90.280236)
		(mid 137.973996 -90.068304)
		(end 137.688574 -89.984834)
		(width 0.0889)
		(layer "In11.Cu")
		(net "JTAG_MCP_TRST_N")
	)
	(arc
		(start 292.715696 -92.756482)
		(mid 292.636381 -93.045854)
		(end 292.709346 -93.336872)
		(width 0.089408)
		(layer "In11.Cu")
		(net "JTAG_MCP_TRST_N")
	)
	(arc
		(start 301.83328 -81.755742)
		(mid 302.117241 -81.671624)
		(end 302.32477 -81.46034)
		(width 0.089408)
		(layer "In11.Cu")
		(net "JTAG_MCP_TRST_N")
	)
	(arc
		(start 137.324084 -89.784936)
		(mid 137.11708 -89.574072)
		(end 136.833864 -89.489788)
		(width 0.0889)
		(layer "In11.Cu")
		(net "JTAG_MCP_TRST_N")
	)
	(arc
		(start 133.367018 -87.508588)
		(mid 133.173168 -87.452238)
		(end 133.031484 -87.308436)
		(width 0.0889)
		(layer "In11.Cu")
		(net "JTAG_MCP_TRST_N")
	)
	(arc
		(start 300.114462 -81.755742)
		(mid 300.303791 -81.813713)
		(end 300.442122 -81.955386)
		(width 0.089408)
		(layer "In11.Cu")
		(net "JTAG_MCP_TRST_N")
	)
	(arc
		(start 128.739138 -84.831936)
		(mid 128.532134 -84.621072)
		(end 128.248918 -84.536788)
		(width 0.0889)
		(layer "In11.Cu")
		(net "JTAG_MCP_TRST_N")
	)
	(arc
		(start 298.725082 -81.955386)
		(mid 298.932611 -82.16667)
		(end 299.216572 -82.250788)
		(width 0.089408)
		(layer "In11.Cu")
		(net "JTAG_MCP_TRST_N")
	)
	(arc
		(start 289.805872 -90.671142)
		(mid 289.998975 -90.727661)
		(end 290.140136 -90.87104)
		(width 0.089408)
		(layer "In11.Cu")
		(net "JTAG_MCP_TRST_N")
	)
	(arc
		(start 133.031484 -87.308436)
		(mid 132.822876 -87.096504)
		(end 132.537454 -87.013034)
		(width 0.0889)
		(layer "In11.Cu")
		(net "JTAG_MCP_TRST_N")
	)
	(arc
		(start 292.715696 -97.709482)
		(mid 292.636381 -97.998854)
		(end 292.709346 -98.289872)
		(width 0.089408)
		(layer "In11.Cu")
		(net "JTAG_MCP_TRST_N")
	)
	(arc
		(start 289.281616 -83.841082)
		(mid 289.202301 -84.130454)
		(end 289.275266 -84.421472)
		(width 0.089408)
		(layer "In11.Cu")
		(net "JTAG_MCP_TRST_N")
	)
	(arc
		(start 300.97476 -82.250788)
		(mid 301.258721 -82.16667)
		(end 301.46625 -81.955386)
		(width 0.089408)
		(layer "In11.Cu")
		(net "JTAG_MCP_TRST_N")
	)
	(arc
		(start 293.239952 -99.586542)
		(mid 293.577135 -99.791602)
		(end 293.574216 -100.186236)
		(width 0.089408)
		(layer "In11.Cu")
		(net "JTAG_MCP_TRST_N")
	)
	(arc
		(start 130.456178 -85.822536)
		(mid 130.249174 -85.611672)
		(end 129.965958 -85.527388)
		(width 0.0889)
		(layer "In11.Cu")
		(net "JTAG_MCP_TRST_N")
	)
	(arc
		(start 290.659312 -91.166188)
		(mid 290.855344 -91.221572)
		(end 290.998656 -91.36634)
		(width 0.089408)
		(layer "In11.Cu")
		(net "JTAG_MCP_TRST_N")
	)
	(arc
		(start 292.720522 -96.327976)
		(mid 292.769186 -96.524074)
		(end 292.715696 -96.718882)
		(width 0.089408)
		(layer "In11.Cu")
		(net "JTAG_MCP_TRST_N")
	)
	(arc
		(start 138.518138 -90.480388)
		(mid 138.324288 -90.424038)
		(end 138.182604 -90.280236)
		(width 0.0889)
		(layer "In11.Cu")
		(net "JTAG_MCP_TRST_N")
	)
	(arc
		(start 292.376352 -92.156788)
		(mid 292.717265 -92.359694)
		(end 292.715696 -92.756482)
		(width 0.089408)
		(layer "In11.Cu")
		(net "JTAG_MCP_TRST_N")
	)
	(arc
		(start 133.890004 -87.803736)
		(mid 133.683 -87.592872)
		(end 133.399784 -87.508588)
		(width 0.0889)
		(layer "In11.Cu")
		(net "JTAG_MCP_TRST_N")
	)
	(arc
		(start 134.221728 -88.003634)
		(mid 134.030086 -87.946468)
		(end 133.890004 -87.803736)
		(width 0.0889)
		(layer "In11.Cu")
		(net "JTAG_MCP_TRST_N")
	)
	(arc
		(start 289.281616 -87.803482)
		(mid 289.202301 -88.092854)
		(end 289.275266 -88.383872)
		(width 0.089408)
		(layer "In11.Cu")
		(net "JTAG_MCP_TRST_N")
	)
	(arc
		(start 126.163578 -83.346036)
		(mid 125.95497 -83.134104)
		(end 125.669548 -83.050634)
		(width 0.0889)
		(layer "In11.Cu")
		(net "JTAG_MCP_TRST_N")
	)
	(arc
		(start 289.281616 -89.784682)
		(mid 289.276538 -90.367019)
		(end 289.773106 -90.671142)
		(width 0.089408)
		(layer "In11.Cu")
		(net "JTAG_MCP_TRST_N")
	)
	(arc
		(start 289.281616 -84.831682)
		(mid 289.202301 -85.121054)
		(end 289.275266 -85.412072)
		(width 0.089408)
		(layer "In11.Cu")
		(net "JTAG_MCP_TRST_N")
	)
	(arc
		(start 292.022784 -80.46974)
		(mid 292.36924 -80.269522)
		(end 292.715696 -80.46974)
		(width 0.089408)
		(layer "In11.Cu")
		(net "JTAG_MCP_TRST_N")
	)
	(arc
		(start 289.286442 -86.421976)
		(mid 289.335106 -86.618074)
		(end 289.281616 -86.812882)
		(width 0.089408)
		(layer "In11.Cu")
		(net "JTAG_MCP_TRST_N")
	)
	(arc
		(start 292.720522 -98.309176)
		(mid 292.769186 -98.505274)
		(end 292.715696 -98.700082)
		(width 0.089408)
		(layer "In11.Cu")
		(net "JTAG_MCP_TRST_N")
	)
	(arc
		(start 135.938768 -88.994234)
		(mid 135.747126 -88.937068)
		(end 135.607044 -88.794336)
		(width 0.0889)
		(layer "In11.Cu")
		(net "JTAG_MCP_TRST_N")
	)
	(arc
		(start 129.070862 -85.031834)
		(mid 128.87922 -84.974668)
		(end 128.739138 -84.831936)
		(width 0.0889)
		(layer "In11.Cu")
		(net "JTAG_MCP_TRST_N")
	)
	(arc
		(start 301.46625 -81.955386)
		(mid 301.604578 -81.813709)
		(end 301.79391 -81.755742)
		(width 0.089408)
		(layer "In11.Cu")
		(net "JTAG_MCP_TRST_N")
	)
	(via
		(at 449.961508 -127.493776)
		(size 0.6604)
		(drill 0.3302)
		(layers "F.Cu" "B.Cu")
		(net "JTAG_MCP_TMS_R1")
	)
	(segment
		(start 450.5706 -128.102868)
		(end 450.5706 -128.8542)
		(width 0.10795)
		(layer "B.Cu")
		(net "JTAG_MCP_TMS_R1")
	)
	(segment
		(start 449.961508 -127.493776)
		(end 450.5706 -128.102868)
		(width 0.10795)
		(layer "B.Cu")
		(net "JTAG_MCP_TMS_R1")
	)
	(segment
		(start 451.9422 -129.9464)
		(end 451.9422 -130.9624)
		(width 0.10795)
		(layer "B.Cu")
		(net "JTAG_MCP_TMS_R1")
	)
	(segment
		(start 450.5706 -128.8542)
		(end 451.6628 -129.9464)
		(width 0.10795)
		(layer "B.Cu")
		(net "JTAG_MCP_TMS_R1")
	)
	(segment
		(start 451.9422 -130.9624)
		(end 452.4502 -130.4544)
		(width 0.10795)
		(layer "B.Cu")
		(net "JTAG_MCP_TMS_R1")
	)
	(segment
		(start 452.4502 -130.4544)
		(end 453.182228 -130.4544)
		(width 0.10795)
		(layer "B.Cu")
		(net "JTAG_MCP_TMS_R1")
	)
	(segment
		(start 451.6628 -129.9464)
		(end 451.9422 -129.9464)
		(width 0.10795)
		(layer "B.Cu")
		(net "JTAG_MCP_TMS_R1")
	)
	(segment
		(start 469.059768 -130.366008)
		(end 470.282016 -130.366008)
		(width 0.10795)
		(layer "F.Cu")
		(net "JTAG_MCP_TMS_R")
	)
	(segment
		(start 468.52078 -129.82702)
		(end 469.059768 -130.366008)
		(width 0.10795)
		(layer "F.Cu")
		(net "JTAG_MCP_TMS_R")
	)
	(segment
		(start 467.21522 -130.302)
		(end 467.6902 -129.82702)
		(width 0.10795)
		(layer "F.Cu")
		(net "JTAG_MCP_TMS_R")
	)
	(segment
		(start 467.106 -130.302)
		(end 467.21522 -130.302)
		(width 0.10795)
		(layer "F.Cu")
		(net "JTAG_MCP_TMS_R")
	)
	(segment
		(start 467.6902 -129.82702)
		(end 468.52078 -129.82702)
		(width 0.10795)
		(layer "F.Cu")
		(net "JTAG_MCP_TMS_R")
	)
	(segment
		(start 122.504708 -83.146138)
		(end 123.076208 -83.146138)
		(width 0.1016)
		(layer "F.Cu")
		(net "JTAG_MCP_TMS")
	)
	(segment
		(start 287.50514 -83.146138)
		(end 288.07664 -83.146138)
		(width 0.1016)
		(layer "F.Cu")
		(net "JTAG_MCP_TMS")
	)
	(segment
		(start 468.43188 -129.413)
		(end 468.50046 -129.34442)
		(width 0.10795)
		(layer "F.Cu")
		(net "JTAG_MCP_TMS")
	)
	(segment
		(start 467.106 -129.413)
		(end 468.43188 -129.413)
		(width 0.10795)
		(layer "F.Cu")
		(net "JTAG_MCP_TMS")
	)
	(via
		(at 171.196 -127.3048)
		(size 0.508)
		(drill 0.254)
		(layers "F.Cu" "B.Cu")
		(net "JTAG_MCP_TMS")
	)
	(via
		(at 432.210718 -122.607324)
		(size 0.508)
		(drill 0.254)
		(layers "F.Cu" "B.Cu")
		(net "JTAG_MCP_TMS")
	)
	(via
		(at 343.027 -120.6754)
		(size 0.508)
		(drill 0.254)
		(layers "F.Cu" "B.Cu")
		(net "JTAG_MCP_TMS")
	)
	(via
		(at 453.644 -132.7404)
		(size 0.508)
		(drill 0.254)
		(layers "F.Cu" "B.Cu")
		(net "JTAG_MCP_TMS")
	)
	(via
		(at 322.327524 -125.988064)
		(size 0.508)
		(drill 0.254)
		(layers "F.Cu" "B.Cu")
		(net "JTAG_MCP_TMS")
	)
	(via
		(at 469.6206 -139.2428)
		(size 0.508)
		(drill 0.254)
		(layers "F.Cu" "B.Cu")
		(net "JTAG_MCP_TMS")
	)
	(via
		(at 123.076208 -83.146138)
		(size 0.508)
		(drill 0.254)
		(layers "F.Cu" "B.Cu")
		(net "JTAG_MCP_TMS")
	)
	(via
		(at 468.50046 -129.34442)
		(size 0.508)
		(drill 0.254)
		(layers "F.Cu" "B.Cu")
		(net "JTAG_MCP_TMS")
	)
	(via
		(at 288.07664 -83.146138)
		(size 0.508)
		(drill 0.254)
		(layers "F.Cu" "B.Cu")
		(net "JTAG_MCP_TMS")
	)
	(segment
		(start 452.9582 -132.0546)
		(end 452.9582 -131.8514)
		(width 0.10795)
		(layer "B.Cu")
		(net "JTAG_MCP_TMS")
	)
	(segment
		(start 453.644 -132.7404)
		(end 452.9582 -132.0546)
		(width 0.10795)
		(layer "B.Cu")
		(net "JTAG_MCP_TMS")
	)
	(segment
		(start 452.9582 -131.8514)
		(end 451.9422 -131.8514)
		(width 0.10795)
		(layer "B.Cu")
		(net "JTAG_MCP_TMS")
	)
	(segment
		(start 277.845266 -157.2387)
		(end 278.475186 -156.60878)
		(width 0.089408)
		(layer "In2.Cu")
		(net "JTAG_MCP_TMS")
	)
	(segment
		(start 324.192138 -133.285738)
		(end 321.7418 -130.8354)
		(width 0.089408)
		(layer "In2.Cu")
		(net "JTAG_MCP_TMS")
	)
	(segment
		(start 189.24016 -138.0998)
		(end 188.1886 -138.0998)
		(width 0.089408)
		(layer "In2.Cu")
		(net "JTAG_MCP_TMS")
	)
	(segment
		(start 322.109592 -128.548892)
		(end 323.40804 -127.250444)
		(width 0.089408)
		(layer "In2.Cu")
		(net "JTAG_MCP_TMS")
	)
	(segment
		(start 457.811886 -137.660888)
		(end 453.644 -133.493002)
		(width 0.089408)
		(layer "In2.Cu")
		(net "JTAG_MCP_TMS")
	)
	(segment
		(start 191.3128 -157.651958)
		(end 191.317118 -157.656276)
		(width 0.089408)
		(layer "In2.Cu")
		(net "JTAG_MCP_TMS")
	)
	(segment
		(start 185.21045 -131.737608)
		(end 186.57189 -131.737608)
		(width 0.089408)
		(layer "In2.Cu")
		(net "JTAG_MCP_TMS")
	)
	(segment
		(start 278.475186 -156.60878)
		(end 323.543422 -156.60878)
		(width 0.089408)
		(layer "In2.Cu")
		(net "JTAG_MCP_TMS")
	)
	(segment
		(start 182.096664 -127.723392)
		(end 183.013604 -128.640332)
		(width 0.089408)
		(layer "In2.Cu")
		(net "JTAG_MCP_TMS")
	)
	(segment
		(start 191.317118 -157.656276)
		(end 264.94613 -157.656276)
		(width 0.089408)
		(layer "In2.Cu")
		(net "JTAG_MCP_TMS")
	)
	(segment
		(start 186.57189 -131.737608)
		(end 188.205618 -133.371336)
		(width 0.089408)
		(layer "In2.Cu")
		(net "JTAG_MCP_TMS")
	)
	(segment
		(start 331.486256 -157.38983)
		(end 331.486256 -156.55036)
		(width 0.089408)
		(layer "In2.Cu")
		(net "JTAG_MCP_TMS")
	)
	(segment
		(start 189.222888 -157.651958)
		(end 191.3128 -157.651958)
		(width 0.089408)
		(layer "In2.Cu")
		(net "JTAG_MCP_TMS")
	)
	(segment
		(start 265.088878 -157.651958)
		(end 265.502136 -157.2387)
		(width 0.089408)
		(layer "In2.Cu")
		(net "JTAG_MCP_TMS")
	)
	(segment
		(start 188.205618 -133.371336)
		(end 189.973204 -133.371336)
		(width 0.089408)
		(layer "In2.Cu")
		(net "JTAG_MCP_TMS")
	)
	(segment
		(start 323.083428 -125.988064)
		(end 322.327524 -125.988064)
		(width 0.089408)
		(layer "In2.Cu")
		(net "JTAG_MCP_TMS")
	)
	(segment
		(start 323.543422 -156.60878)
		(end 324.871588 -157.936946)
		(width 0.089408)
		(layer "In2.Cu")
		(net "JTAG_MCP_TMS")
	)
	(segment
		(start 171.938442 -126.681992)
		(end 173.817534 -126.681992)
		(width 0.089408)
		(layer "In2.Cu")
		(net "JTAG_MCP_TMS")
	)
	(segment
		(start 187.25896 -153.138886)
		(end 187.25896 -155.68803)
		(width 0.089408)
		(layer "In2.Cu")
		(net "JTAG_MCP_TMS")
	)
	(segment
		(start 265.502136 -157.2387)
		(end 277.845266 -157.2387)
		(width 0.089408)
		(layer "In2.Cu")
		(net "JTAG_MCP_TMS")
	)
	(segment
		(start 330.93914 -157.936946)
		(end 331.486256 -157.38983)
		(width 0.089408)
		(layer "In2.Cu")
		(net "JTAG_MCP_TMS")
	)
	(segment
		(start 191.060324 -136.279636)
		(end 189.24016 -138.0998)
		(width 0.089408)
		(layer "In2.Cu")
		(net "JTAG_MCP_TMS")
	)
	(segment
		(start 323.40804 -126.312676)
		(end 323.083428 -125.988064)
		(width 0.089408)
		(layer "In2.Cu")
		(net "JTAG_MCP_TMS")
	)
	(segment
		(start 328.067162 -152.063704)
		(end 326.787764 -152.063704)
		(width 0.089408)
		(layer "In2.Cu")
		(net "JTAG_MCP_TMS")
	)
	(segment
		(start 323.40804 -127.250444)
		(end 323.40804 -126.312676)
		(width 0.089408)
		(layer "In2.Cu")
		(net "JTAG_MCP_TMS")
	)
	(segment
		(start 322.109592 -129.934208)
		(end 322.109592 -128.548892)
		(width 0.089408)
		(layer "In2.Cu")
		(net "JTAG_MCP_TMS")
	)
	(segment
		(start 174.858934 -127.723392)
		(end 182.096664 -127.723392)
		(width 0.089408)
		(layer "In2.Cu")
		(net "JTAG_MCP_TMS")
	)
	(segment
		(start 324.192138 -135.757158)
		(end 324.192138 -133.285738)
		(width 0.089408)
		(layer "In2.Cu")
		(net "JTAG_MCP_TMS")
	)
	(segment
		(start 469.124538 -139.2428)
		(end 467.542626 -137.660888)
		(width 0.089408)
		(layer "In2.Cu")
		(net "JTAG_MCP_TMS")
	)
	(segment
		(start 321.7418 -130.302)
		(end 322.109592 -129.934208)
		(width 0.089408)
		(layer "In2.Cu")
		(net "JTAG_MCP_TMS")
	)
	(segment
		(start 189.973204 -133.371336)
		(end 191.060324 -134.458456)
		(width 0.089408)
		(layer "In2.Cu")
		(net "JTAG_MCP_TMS")
	)
	(segment
		(start 321.7418 -130.8354)
		(end 321.7418 -130.302)
		(width 0.089408)
		(layer "In2.Cu")
		(net "JTAG_MCP_TMS")
	)
	(segment
		(start 325.014336 -141.390878)
		(end 323.890894 -140.267436)
		(width 0.089408)
		(layer "In2.Cu")
		(net "JTAG_MCP_TMS")
	)
	(segment
		(start 323.890894 -140.267436)
		(end 323.890894 -138.642344)
		(width 0.089408)
		(layer "In2.Cu")
		(net "JTAG_MCP_TMS")
	)
	(segment
		(start 184.156604 -129.291588)
		(end 184.156604 -130.650742)
		(width 0.089408)
		(layer "In2.Cu")
		(net "JTAG_MCP_TMS")
	)
	(segment
		(start 187.25896 -155.68803)
		(end 189.222888 -157.651958)
		(width 0.089408)
		(layer "In2.Cu")
		(net "JTAG_MCP_TMS")
	)
	(segment
		(start 330.142088 -155.206192)
		(end 330.142088 -154.13863)
		(width 0.089408)
		(layer "In2.Cu")
		(net "JTAG_MCP_TMS")
	)
	(segment
		(start 264.950448 -157.651958)
		(end 265.088878 -157.651958)
		(width 0.089408)
		(layer "In2.Cu")
		(net "JTAG_MCP_TMS")
	)
	(segment
		(start 171.196 -127.3048)
		(end 171.315634 -127.3048)
		(width 0.089408)
		(layer "In2.Cu")
		(net "JTAG_MCP_TMS")
	)
	(segment
		(start 184.897776 -131.424934)
		(end 185.21045 -131.737608)
		(width 0.089408)
		(layer "In2.Cu")
		(net "JTAG_MCP_TMS")
	)
	(segment
		(start 171.315634 -127.3048)
		(end 171.938442 -126.681992)
		(width 0.089408)
		(layer "In2.Cu")
		(net "JTAG_MCP_TMS")
	)
	(segment
		(start 325.014336 -150.290276)
		(end 325.014336 -141.390878)
		(width 0.089408)
		(layer "In2.Cu")
		(net "JTAG_MCP_TMS")
	)
	(segment
		(start 188.1886 -138.0998)
		(end 187.09513 -139.19327)
		(width 0.089408)
		(layer "In2.Cu")
		(net "JTAG_MCP_TMS")
	)
	(segment
		(start 326.787764 -152.063704)
		(end 325.014336 -150.290276)
		(width 0.089408)
		(layer "In2.Cu")
		(net "JTAG_MCP_TMS")
	)
	(segment
		(start 325.10603 -137.427208)
		(end 325.10603 -136.67105)
		(width 0.089408)
		(layer "In2.Cu")
		(net "JTAG_MCP_TMS")
	)
	(segment
		(start 323.890894 -138.642344)
		(end 325.10603 -137.427208)
		(width 0.089408)
		(layer "In2.Cu")
		(net "JTAG_MCP_TMS")
	)
	(segment
		(start 467.542626 -137.660888)
		(end 457.811886 -137.660888)
		(width 0.089408)
		(layer "In2.Cu")
		(net "JTAG_MCP_TMS")
	)
	(segment
		(start 191.060324 -134.458456)
		(end 191.060324 -136.279636)
		(width 0.089408)
		(layer "In2.Cu")
		(net "JTAG_MCP_TMS")
	)
	(segment
		(start 187.09513 -139.19327)
		(end 187.09513 -152.975056)
		(width 0.089408)
		(layer "In2.Cu")
		(net "JTAG_MCP_TMS")
	)
	(segment
		(start 453.644 -133.493002)
		(end 453.644 -132.7404)
		(width 0.089408)
		(layer "In2.Cu")
		(net "JTAG_MCP_TMS")
	)
	(segment
		(start 330.142088 -154.13863)
		(end 328.067162 -152.063704)
		(width 0.089408)
		(layer "In2.Cu")
		(net "JTAG_MCP_TMS")
	)
	(segment
		(start 184.156604 -130.650742)
		(end 184.897776 -131.391914)
		(width 0.089408)
		(layer "In2.Cu")
		(net "JTAG_MCP_TMS")
	)
	(segment
		(start 469.6206 -139.2428)
		(end 469.124538 -139.2428)
		(width 0.089408)
		(layer "In2.Cu")
		(net "JTAG_MCP_TMS")
	)
	(segment
		(start 331.486256 -156.55036)
		(end 330.142088 -155.206192)
		(width 0.089408)
		(layer "In2.Cu")
		(net "JTAG_MCP_TMS")
	)
	(segment
		(start 264.94613 -157.656276)
		(end 264.950448 -157.651958)
		(width 0.089408)
		(layer "In2.Cu")
		(net "JTAG_MCP_TMS")
	)
	(segment
		(start 183.013604 -128.640332)
		(end 183.505348 -128.640332)
		(width 0.089408)
		(layer "In2.Cu")
		(net "JTAG_MCP_TMS")
	)
	(segment
		(start 183.505348 -128.640332)
		(end 184.156604 -129.291588)
		(width 0.089408)
		(layer "In2.Cu")
		(net "JTAG_MCP_TMS")
	)
	(segment
		(start 184.897776 -131.391914)
		(end 184.897776 -131.424934)
		(width 0.089408)
		(layer "In2.Cu")
		(net "JTAG_MCP_TMS")
	)
	(segment
		(start 324.871588 -157.936946)
		(end 330.93914 -157.936946)
		(width 0.089408)
		(layer "In2.Cu")
		(net "JTAG_MCP_TMS")
	)
	(segment
		(start 325.10603 -136.67105)
		(end 324.192138 -135.757158)
		(width 0.089408)
		(layer "In2.Cu")
		(net "JTAG_MCP_TMS")
	)
	(segment
		(start 187.09513 -152.975056)
		(end 187.25896 -153.138886)
		(width 0.089408)
		(layer "In2.Cu")
		(net "JTAG_MCP_TMS")
	)
	(segment
		(start 173.817534 -126.681992)
		(end 174.858934 -127.723392)
		(width 0.089408)
		(layer "In2.Cu")
		(net "JTAG_MCP_TMS")
	)
	(segment
		(start 468.50046 -129.34442)
		(end 469.61044 -130.4544)
		(width 0.089408)
		(layer "In4.Cu")
		(net "JTAG_MCP_TMS")
	)
	(segment
		(start 469.61044 -137.50036)
		(end 469.0491 -138.0617)
		(width 0.089408)
		(layer "In4.Cu")
		(net "JTAG_MCP_TMS")
	)
	(segment
		(start 469.61044 -130.4544)
		(end 469.61044 -137.50036)
		(width 0.089408)
		(layer "In4.Cu")
		(net "JTAG_MCP_TMS")
	)
	(segment
		(start 469.0491 -138.0617)
		(end 469.0491 -138.6713)
		(width 0.089408)
		(layer "In4.Cu")
		(net "JTAG_MCP_TMS")
	)
	(segment
		(start 469.0491 -138.6713)
		(end 469.6206 -139.2428)
		(width 0.089408)
		(layer "In4.Cu")
		(net "JTAG_MCP_TMS")
	)
	(segment
		(start 439.674 -118.6942)
		(end 440.645296 -119.665496)
		(width 0.089408)
		(layer "In9.Cu")
		(net "JTAG_MCP_TMS")
	)
	(segment
		(start 455.99604 -125.33884)
		(end 457.6826 -127.0254)
		(width 0.089408)
		(layer "In9.Cu")
		(net "JTAG_MCP_TMS")
	)
	(segment
		(start 433.396898 -120.371616)
		(end 434.844444 -120.371616)
		(width 0.089408)
		(layer "In9.Cu")
		(net "JTAG_MCP_TMS")
	)
	(segment
		(start 449.408296 -119.665496)
		(end 449.7324 -119.9896)
		(width 0.089408)
		(layer "In9.Cu")
		(net "JTAG_MCP_TMS")
	)
	(segment
		(start 323.956934 -125.689106)
		(end 323.924422 -125.721618)
		(width 0.089408)
		(layer "In9.Cu")
		(net "JTAG_MCP_TMS")
	)
	(segment
		(start 467.8934 -139.2428)
		(end 469.6206 -139.2428)
		(width 0.089408)
		(layer "In9.Cu")
		(net "JTAG_MCP_TMS")
	)
	(segment
		(start 459.2574 -127.0254)
		(end 460.347314 -128.115314)
		(width 0.089408)
		(layer "In9.Cu")
		(net "JTAG_MCP_TMS")
	)
	(segment
		(start 434.844444 -120.371616)
		(end 436.52186 -118.6942)
		(width 0.089408)
		(layer "In9.Cu")
		(net "JTAG_MCP_TMS")
	)
	(segment
		(start 330.366116 -123.863608)
		(end 328.836782 -123.863608)
		(width 0.089408)
		(layer "In9.Cu")
		(net "JTAG_MCP_TMS")
	)
	(segment
		(start 449.7324 -119.9896)
		(end 449.7324 -120.591326)
		(width 0.089408)
		(layer "In9.Cu")
		(net "JTAG_MCP_TMS")
	)
	(segment
		(start 341.676228 -119.718582)
		(end 338.111338 -123.283472)
		(width 0.089408)
		(layer "In9.Cu")
		(net "JTAG_MCP_TMS")
	)
	(segment
		(start 452.5518 -123.410726)
		(end 452.5518 -124.99594)
		(width 0.089408)
		(layer "In9.Cu")
		(net "JTAG_MCP_TMS")
	)
	(segment
		(start 323.924422 -125.721618)
		(end 322.59397 -125.721618)
		(width 0.089408)
		(layer "In9.Cu")
		(net "JTAG_MCP_TMS")
	)
	(segment
		(start 328.836782 -123.863608)
		(end 328.61885 -124.08154)
		(width 0.089408)
		(layer "In9.Cu")
		(net "JTAG_MCP_TMS")
	)
	(segment
		(start 452.8947 -125.33884)
		(end 455.99604 -125.33884)
		(width 0.089408)
		(layer "In9.Cu")
		(net "JTAG_MCP_TMS")
	)
	(segment
		(start 457.6826 -127.0254)
		(end 459.2574 -127.0254)
		(width 0.089408)
		(layer "In9.Cu")
		(net "JTAG_MCP_TMS")
	)
	(segment
		(start 322.59397 -125.721618)
		(end 322.327524 -125.988064)
		(width 0.089408)
		(layer "In9.Cu")
		(net "JTAG_MCP_TMS")
	)
	(segment
		(start 432.210718 -122.607324)
		(end 432.210718 -121.557796)
		(width 0.089408)
		(layer "In9.Cu")
		(net "JTAG_MCP_TMS")
	)
	(segment
		(start 460.347314 -128.115314)
		(end 460.347314 -128.851914)
		(width 0.089408)
		(layer "In9.Cu")
		(net "JTAG_MCP_TMS")
	)
	(segment
		(start 460.347314 -128.851914)
		(end 467.0044 -135.509)
		(width 0.089408)
		(layer "In9.Cu")
		(net "JTAG_MCP_TMS")
	)
	(segment
		(start 432.210718 -121.557796)
		(end 433.396898 -120.371616)
		(width 0.089408)
		(layer "In9.Cu")
		(net "JTAG_MCP_TMS")
	)
	(segment
		(start 440.645296 -119.665496)
		(end 449.408296 -119.665496)
		(width 0.089408)
		(layer "In9.Cu")
		(net "JTAG_MCP_TMS")
	)
	(segment
		(start 343.027 -120.6754)
		(end 343.027 -120.3198)
		(width 0.089408)
		(layer "In9.Cu")
		(net "JTAG_MCP_TMS")
	)
	(segment
		(start 330.946252 -123.283472)
		(end 330.366116 -123.863608)
		(width 0.089408)
		(layer "In9.Cu")
		(net "JTAG_MCP_TMS")
	)
	(segment
		(start 449.7324 -120.591326)
		(end 452.5518 -123.410726)
		(width 0.089408)
		(layer "In9.Cu")
		(net "JTAG_MCP_TMS")
	)
	(segment
		(start 467.0044 -135.509)
		(end 467.0044 -138.3538)
		(width 0.089408)
		(layer "In9.Cu")
		(net "JTAG_MCP_TMS")
	)
	(segment
		(start 338.111338 -123.283472)
		(end 330.946252 -123.283472)
		(width 0.089408)
		(layer "In9.Cu")
		(net "JTAG_MCP_TMS")
	)
	(segment
		(start 452.5518 -124.99594)
		(end 452.8947 -125.33884)
		(width 0.089408)
		(layer "In9.Cu")
		(net "JTAG_MCP_TMS")
	)
	(segment
		(start 328.61885 -124.08154)
		(end 326.413114 -124.08154)
		(width 0.089408)
		(layer "In9.Cu")
		(net "JTAG_MCP_TMS")
	)
	(segment
		(start 326.413114 -124.08154)
		(end 324.805548 -125.689106)
		(width 0.089408)
		(layer "In9.Cu")
		(net "JTAG_MCP_TMS")
	)
	(segment
		(start 324.805548 -125.689106)
		(end 323.956934 -125.689106)
		(width 0.089408)
		(layer "In9.Cu")
		(net "JTAG_MCP_TMS")
	)
	(segment
		(start 436.52186 -118.6942)
		(end 439.674 -118.6942)
		(width 0.089408)
		(layer "In9.Cu")
		(net "JTAG_MCP_TMS")
	)
	(segment
		(start 343.027 -120.3198)
		(end 342.425782 -119.718582)
		(width 0.089408)
		(layer "In9.Cu")
		(net "JTAG_MCP_TMS")
	)
	(segment
		(start 467.0044 -138.3538)
		(end 467.8934 -139.2428)
		(width 0.089408)
		(layer "In9.Cu")
		(net "JTAG_MCP_TMS")
	)
	(segment
		(start 342.425782 -119.718582)
		(end 341.676228 -119.718582)
		(width 0.089408)
		(layer "In9.Cu")
		(net "JTAG_MCP_TMS")
	)
	(segment
		(start 130.820668 -88.003634)
		(end 130.787902 -88.003634)
		(width 0.0889)
		(layer "In11.Cu")
		(net "JTAG_MCP_TMS")
	)
	(segment
		(start 292.017958 -96.327976)
		(end 292.022784 -96.31934)
		(width 0.089408)
		(layer "In11.Cu")
		(net "JTAG_MCP_TMS")
	)
	(segment
		(start 126.531878 -85.527388)
		(end 126.499112 -85.527388)
		(width 0.0889)
		(layer "In11.Cu")
		(net "JTAG_MCP_TMS")
	)
	(segment
		(start 318.961516 -125.461522)
		(end 318.961516 -125.451616)
		(width 0.089408)
		(layer "In11.Cu")
		(net "JTAG_MCP_TMS")
	)
	(segment
		(start 169.399966 -120.57634)
		(end 166.459408 -117.635782)
		(width 0.089408)
		(layer "In11.Cu")
		(net "JTAG_MCP_TMS")
	)
	(segment
		(start 290.672774 -91.96578)
		(end 290.640008 -91.96578)
		(width 0.089408)
		(layer "In11.Cu")
		(net "JTAG_MCP_TMS")
	)
	(segment
		(start 319.90284 -125.75794)
		(end 319.26784 -125.75794)
		(width 0.089408)
		(layer "In11.Cu")
		(net "JTAG_MCP_TMS")
	)
	(segment
		(start 426.247306 -124.747528)
		(end 428.459138 -122.535696)
		(width 0.089408)
		(layer "In11.Cu")
		(net "JTAG_MCP_TMS")
	)
	(segment
		(start 139.405614 -92.956634)
		(end 139.372848 -92.956634)
		(width 0.0889)
		(layer "In11.Cu")
		(net "JTAG_MCP_TMS")
	)
	(segment
		(start 135.971534 -90.975434)
		(end 135.938768 -90.975434)
		(width 0.0889)
		(layer "In11.Cu")
		(net "JTAG_MCP_TMS")
	)
	(segment
		(start 140.8176 -93.57614)
		(end 140.612622 -93.452188)
		(width 0.0889)
		(layer "In11.Cu")
		(net "JTAG_MCP_TMS")
	)
	(segment
		(start 287.730184 -88.298782)
		(end 287.725358 -88.290146)
		(width 0.089408)
		(layer "In11.Cu")
		(net "JTAG_MCP_TMS")
	)
	(segment
		(start 374.207278 -128.404112)
		(end 378.861828 -128.404112)
		(width 0.089408)
		(layer "In11.Cu")
		(net "JTAG_MCP_TMS")
	)
	(segment
		(start 294.02532 -101.528118)
		(end 293.490142 -101.528118)
		(width 0.089408)
		(layer "In11.Cu")
		(net "JTAG_MCP_TMS")
	)
	(segment
		(start 378.861828 -128.404112)
		(end 379.09627 -128.638554)
		(width 0.089408)
		(layer "In11.Cu")
		(net "JTAG_MCP_TMS")
	)
	(segment
		(start 408.014424 -131.756912)
		(end 410.769816 -134.512304)
		(width 0.089408)
		(layer "In11.Cu")
		(net "JTAG_MCP_TMS")
	)
	(segment
		(start 412.70809 -134.97687)
		(end 414.793684 -134.97687)
		(width 0.089408)
		(layer "In11.Cu")
		(net "JTAG_MCP_TMS")
	)
	(segment
		(start 132.537454 -88.994234)
		(end 132.519674 -88.994234)
		(width 0.0889)
		(layer "In11.Cu")
		(net "JTAG_MCP_TMS")
	)
	(segment
		(start 292.022784 -99.29114)
		(end 292.029134 -99.280472)
		(width 0.089408)
		(layer "In11.Cu")
		(net "JTAG_MCP_TMS")
	)
	(segment
		(start 369.518438 -125.472444)
		(end 372.156736 -128.110742)
		(width 0.089408)
		(layer "In11.Cu")
		(net "JTAG_MCP_TMS")
	)
	(segment
		(start 425.235624 -127.850138)
		(end 426.150786 -126.934976)
		(width 0.089408)
		(layer "In11.Cu")
		(net "JTAG_MCP_TMS")
	)
	(segment
		(start 135.116824 -90.480388)
		(end 135.084058 -90.480388)
		(width 0.0889)
		(layer "In11.Cu")
		(net "JTAG_MCP_TMS")
	)
	(segment
		(start 405.136858 -131.756912)
		(end 408.014424 -131.756912)
		(width 0.089408)
		(layer "In11.Cu")
		(net "JTAG_MCP_TMS")
	)
	(segment
		(start 171.196 -127.3048)
		(end 170.8404 -126.9492)
		(width 0.089408)
		(layer "In11.Cu")
		(net "JTAG_MCP_TMS")
	)
	(segment
		(start 287.730184 -85.326982)
		(end 287.725358 -85.318346)
		(width 0.089408)
		(layer "In11.Cu")
		(net "JTAG_MCP_TMS")
	)
	(segment
		(start 380.319026 -131.546092)
		(end 381.353314 -131.546092)
		(width 0.089408)
		(layer "In11.Cu")
		(net "JTAG_MCP_TMS")
	)
	(segment
		(start 140.612622 -93.452188)
		(end 140.235178 -93.452188)
		(width 0.0889)
		(layer "In11.Cu")
		(net "JTAG_MCP_TMS")
	)
	(segment
		(start 319.26784 -125.75794)
		(end 319.205864 -125.695964)
		(width 0.089408)
		(layer "In11.Cu")
		(net "JTAG_MCP_TMS")
	)
	(segment
		(start 318.961516 -125.451616)
		(end 318.43726 -124.92736)
		(width 0.089408)
		(layer "In11.Cu")
		(net "JTAG_MCP_TMS")
	)
	(segment
		(start 170.8404 -126.9492)
		(end 170.8404 -126.650242)
		(width 0.089408)
		(layer "In11.Cu")
		(net "JTAG_MCP_TMS")
	)
	(segment
		(start 294.272462 -101.77526)
		(end 294.02532 -101.528118)
		(width 0.089408)
		(layer "In11.Cu")
		(net "JTAG_MCP_TMS")
	)
	(segment
		(start 124.814838 -84.536788)
		(end 124.782072 -84.536788)
		(width 0.0889)
		(layer "In11.Cu")
		(net "JTAG_MCP_TMS")
	)
	(segment
		(start 142.9512 -95.2246)
		(end 142.2654 -94.5388)
		(width 0.089408)
		(layer "In11.Cu")
		(net "JTAG_MCP_TMS")
	)
	(segment
		(start 292.022784 -94.33814)
		(end 292.029134 -94.327472)
		(width 0.089408)
		(layer "In11.Cu")
		(net "JTAG_MCP_TMS")
	)
	(segment
		(start 169.399966 -122.025156)
		(end 169.399966 -120.57634)
		(width 0.089408)
		(layer "In11.Cu")
		(net "JTAG_MCP_TMS")
	)
	(segment
		(start 432.13909 -122.535696)
		(end 432.210718 -122.607324)
		(width 0.089408)
		(layer "In11.Cu")
		(net "JTAG_MCP_TMS")
	)
	(segment
		(start 292.022784 -96.31934)
		(end 292.029134 -96.308672)
		(width 0.089408)
		(layer "In11.Cu")
		(net "JTAG_MCP_TMS")
	)
	(segment
		(start 141.656562 -94.245684)
		(end 141.530578 -94.007686)
		(width 0.0889)
		(layer "In11.Cu")
		(net "JTAG_MCP_TMS")
	)
	(segment
		(start 132.17652 -88.799924)
		(end 132.173218 -88.794082)
		(width 0.0889)
		(layer "In11.Cu")
		(net "JTAG_MCP_TMS")
	)
	(segment
		(start 168.40708 -123.018042)
		(end 169.399966 -122.025156)
		(width 0.089408)
		(layer "In11.Cu")
		(net "JTAG_MCP_TMS")
	)
	(segment
		(start 127.386588 -86.022434)
		(end 127.353822 -86.022434)
		(width 0.0889)
		(layer "In11.Cu")
		(net "JTAG_MCP_TMS")
	)
	(segment
		(start 345.175078 -119.930164)
		(end 366.833658 -119.930164)
		(width 0.089408)
		(layer "In11.Cu")
		(net "JTAG_MCP_TMS")
	)
	(segment
		(start 292.022784 -98.30054)
		(end 292.029134 -98.289872)
		(width 0.089408)
		(layer "In11.Cu")
		(net "JTAG_MCP_TMS")
	)
	(segment
		(start 382.205992 -130.693414)
		(end 383.821686 -130.693414)
		(width 0.089408)
		(layer "In11.Cu")
		(net "JTAG_MCP_TMS")
	)
	(segment
		(start 288.10077 -90.480134)
		(end 288.069528 -90.480134)
		(width 0.089408)
		(layer "In11.Cu")
		(net "JTAG_MCP_TMS")
	)
	(segment
		(start 287.746694 -83.908646)
		(end 288.07664 -83.146138)
		(width 0.089408)
		(layer "In11.Cu")
		(net "JTAG_MCP_TMS")
	)
	(segment
		(start 343.767156 -119.789702)
		(end 345.034616 -119.789702)
		(width 0.089408)
		(layer "In11.Cu")
		(net "JTAG_MCP_TMS")
	)
	(segment
		(start 322.327524 -125.93701)
		(end 322.064634 -125.67412)
		(width 0.089408)
		(layer "In11.Cu")
		(net "JTAG_MCP_TMS")
	)
	(segment
		(start 288.955734 -90.97518)
		(end 288.922968 -90.97518)
		(width 0.089408)
		(layer "In11.Cu")
		(net "JTAG_MCP_TMS")
	)
	(segment
		(start 318.43726 -123.734322)
		(end 302.405288 -107.70235)
		(width 0.089408)
		(layer "In11.Cu")
		(net "JTAG_MCP_TMS")
	)
	(segment
		(start 287.736534 -88.30945)
		(end 287.730184 -88.298782)
		(width 0.089408)
		(layer "In11.Cu")
		(net "JTAG_MCP_TMS")
	)
	(segment
		(start 389.126984 -135.998712)
		(end 399.788888 -135.998712)
		(width 0.089408)
		(layer "In11.Cu")
		(net "JTAG_MCP_TMS")
	)
	(segment
		(start 143.597376 -99.68611)
		(end 143.597376 -99.518724)
		(width 0.089408)
		(layer "In11.Cu")
		(net "JTAG_MCP_TMS")
	)
	(segment
		(start 381.353314 -131.546092)
		(end 382.205992 -130.693414)
		(width 0.089408)
		(layer "In11.Cu")
		(net "JTAG_MCP_TMS")
	)
	(segment
		(start 287.730184 -87.308182)
		(end 287.725358 -87.299546)
		(width 0.089408)
		(layer "In11.Cu")
		(net "JTAG_MCP_TMS")
	)
	(segment
		(start 426.160438 -126.934976)
		(end 426.247306 -126.848108)
		(width 0.089408)
		(layer "In11.Cu")
		(net "JTAG_MCP_TMS")
	)
	(segment
		(start 129.965958 -87.508588)
		(end 129.933192 -87.508588)
		(width 0.0889)
		(layer "In11.Cu")
		(net "JTAG_MCP_TMS")
	)
	(segment
		(start 292.017958 -99.299776)
		(end 292.022784 -99.29114)
		(width 0.089408)
		(layer "In11.Cu")
		(net "JTAG_MCP_TMS")
	)
	(segment
		(start 292.380416 -99.89058)
		(end 292.357048 -99.89058)
		(width 0.089408)
		(layer "In11.Cu")
		(net "JTAG_MCP_TMS")
	)
	(segment
		(start 292.022784 -97.30994)
		(end 292.029134 -97.299272)
		(width 0.089408)
		(layer "In11.Cu")
		(net "JTAG_MCP_TMS")
	)
	(segment
		(start 292.022784 -94.737682)
		(end 292.017958 -94.729046)
		(width 0.089408)
		(layer "In11.Cu")
		(net "JTAG_MCP_TMS")
	)
	(segment
		(start 400.53133 -135.25627)
		(end 401.634452 -135.25627)
		(width 0.089408)
		(layer "In11.Cu")
		(net "JTAG_MCP_TMS")
	)
	(segment
		(start 170.8404 -126.650242)
		(end 168.40708 -124.216922)
		(width 0.089408)
		(layer "In11.Cu")
		(net "JTAG_MCP_TMS")
	)
	(segment
		(start 137.688574 -91.966034)
		(end 137.655808 -91.966034)
		(width 0.0889)
		(layer "In11.Cu")
		(net "JTAG_MCP_TMS")
	)
	(segment
		(start 343.027 -120.529858)
		(end 343.767156 -119.789702)
		(width 0.089408)
		(layer "In11.Cu")
		(net "JTAG_MCP_TMS")
	)
	(segment
		(start 161.714434 -117.635782)
		(end 154.961336 -110.882684)
		(width 0.089408)
		(layer "In11.Cu")
		(net "JTAG_MCP_TMS")
	)
	(segment
		(start 136.833864 -91.470988)
		(end 136.801098 -91.470988)
		(width 0.0889)
		(layer "In11.Cu")
		(net "JTAG_MCP_TMS")
	)
	(segment
		(start 287.730184 -86.317582)
		(end 287.725358 -86.308946)
		(width 0.089408)
		(layer "In11.Cu")
		(net "JTAG_MCP_TMS")
	)
	(segment
		(start 142.9512 -98.872548)
		(end 142.9512 -95.2246)
		(width 0.089408)
		(layer "In11.Cu")
		(net "JTAG_MCP_TMS")
	)
	(segment
		(start 415.411158 -133.356858)
		(end 415.990278 -132.777738)
		(width 0.089408)
		(layer "In11.Cu")
		(net "JTAG_MCP_TMS")
	)
	(segment
		(start 419.062662 -132.777738)
		(end 423.990262 -127.850138)
		(width 0.089408)
		(layer "In11.Cu")
		(net "JTAG_MCP_TMS")
	)
	(segment
		(start 128.248918 -86.517988)
		(end 128.216152 -86.517988)
		(width 0.0889)
		(layer "In11.Cu")
		(net "JTAG_MCP_TMS")
	)
	(segment
		(start 292.017958 -97.318576)
		(end 292.022784 -97.30994)
		(width 0.089408)
		(layer "In11.Cu")
		(net "JTAG_MCP_TMS")
	)
	(segment
		(start 129.103628 -87.013034)
		(end 129.070862 -87.013034)
		(width 0.0889)
		(layer "In11.Cu")
		(net "JTAG_MCP_TMS")
	)
	(segment
		(start 379.09627 -130.323336)
		(end 380.319026 -131.546092)
		(width 0.089408)
		(layer "In11.Cu")
		(net "JTAG_MCP_TMS")
	)
	(segment
		(start 141.530578 -94.007686)
		(end 140.8176 -93.57614)
		(width 0.0889)
		(layer "In11.Cu")
		(net "JTAG_MCP_TMS")
	)
	(segment
		(start 287.736534 -89.30005)
		(end 287.730184 -89.289382)
		(width 0.089408)
		(layer "In11.Cu")
		(net "JTAG_MCP_TMS")
	)
	(segment
		(start 134.254494 -89.984834)
		(end 134.221728 -89.984834)
		(width 0.0889)
		(layer "In11.Cu")
		(net "JTAG_MCP_TMS")
	)
	(segment
		(start 287.736534 -85.33765)
		(end 287.730184 -85.326982)
		(width 0.089408)
		(layer "In11.Cu")
		(net "JTAG_MCP_TMS")
	)
	(segment
		(start 412.243524 -134.512304)
		(end 412.70809 -134.97687)
		(width 0.089408)
		(layer "In11.Cu")
		(net "JTAG_MCP_TMS")
	)
	(segment
		(start 142.2654 -94.5388)
		(end 141.840966 -94.5388)
		(width 0.0889)
		(layer "In11.Cu")
		(net "JTAG_MCP_TMS")
	)
	(segment
		(start 141.840966 -94.5388)
		(end 141.717014 -94.414848)
		(width 0.0889)
		(layer "In11.Cu")
		(net "JTAG_MCP_TMS")
	)
	(segment
		(start 289.81781 -91.470734)
		(end 289.786568 -91.470734)
		(width 0.089408)
		(layer "In11.Cu")
		(net "JTAG_MCP_TMS")
	)
	(segment
		(start 166.459408 -117.635782)
		(end 161.714434 -117.635782)
		(width 0.089408)
		(layer "In11.Cu")
		(net "JTAG_MCP_TMS")
	)
	(segment
		(start 415.990278 -132.777738)
		(end 419.062662 -132.777738)
		(width 0.089408)
		(layer "In11.Cu")
		(net "JTAG_MCP_TMS")
	)
	(segment
		(start 319.195958 -125.695964)
		(end 318.961516 -125.461522)
		(width 0.089408)
		(layer "In11.Cu")
		(net "JTAG_MCP_TMS")
	)
	(segment
		(start 292.017958 -98.309176)
		(end 292.022784 -98.30054)
		(width 0.089408)
		(layer "In11.Cu")
		(net "JTAG_MCP_TMS")
	)
	(segment
		(start 401.634452 -135.25627)
		(end 405.136858 -131.756912)
		(width 0.089408)
		(layer "In11.Cu")
		(net "JTAG_MCP_TMS")
	)
	(segment
		(start 287.736534 -87.31885)
		(end 287.730184 -87.308182)
		(width 0.089408)
		(layer "In11.Cu")
		(net "JTAG_MCP_TMS")
	)
	(segment
		(start 125.669548 -85.031834)
		(end 125.636782 -85.031834)
		(width 0.0889)
		(layer "In11.Cu")
		(net "JTAG_MCP_TMS")
	)
	(segment
		(start 410.769816 -134.512304)
		(end 412.243524 -134.512304)
		(width 0.089408)
		(layer "In11.Cu")
		(net "JTAG_MCP_TMS")
	)
	(segment
		(start 143.597376 -99.518724)
		(end 142.9512 -98.872548)
		(width 0.089408)
		(layer "In11.Cu")
		(net "JTAG_MCP_TMS")
	)
	(segment
		(start 366.833658 -119.930164)
		(end 369.518438 -122.614944)
		(width 0.089408)
		(layer "In11.Cu")
		(net "JTAG_MCP_TMS")
	)
	(segment
		(start 383.821686 -130.693414)
		(end 389.126984 -135.998712)
		(width 0.089408)
		(layer "In11.Cu")
		(net "JTAG_MCP_TMS")
	)
	(segment
		(start 373.913908 -128.110742)
		(end 374.207278 -128.404112)
		(width 0.089408)
		(layer "In11.Cu")
		(net "JTAG_MCP_TMS")
	)
	(segment
		(start 287.730184 -83.93684)
		(end 287.746694 -83.908646)
		(width 0.089408)
		(layer "In11.Cu")
		(net "JTAG_MCP_TMS")
	)
	(segment
		(start 369.518438 -122.614944)
		(end 369.518438 -125.472444)
		(width 0.089408)
		(layer "In11.Cu")
		(net "JTAG_MCP_TMS")
	)
	(segment
		(start 294.272462 -102.169976)
		(end 294.272462 -101.77526)
		(width 0.089408)
		(layer "In11.Cu")
		(net "JTAG_MCP_TMS")
	)
	(segment
		(start 426.150786 -126.934976)
		(end 426.160438 -126.934976)
		(width 0.089408)
		(layer "In11.Cu")
		(net "JTAG_MCP_TMS")
	)
	(segment
		(start 426.247306 -126.848108)
		(end 426.247306 -124.747528)
		(width 0.089408)
		(layer "In11.Cu")
		(net "JTAG_MCP_TMS")
	)
	(segment
		(start 131.6863 -88.499188)
		(end 131.650232 -88.499188)
		(width 0.0889)
		(layer "In11.Cu")
		(net "JTAG_MCP_TMS")
	)
	(segment
		(start 399.788888 -135.998712)
		(end 400.53133 -135.25627)
		(width 0.089408)
		(layer "In11.Cu")
		(net "JTAG_MCP_TMS")
	)
	(segment
		(start 414.793684 -134.97687)
		(end 415.411158 -134.359396)
		(width 0.089408)
		(layer "In11.Cu")
		(net "JTAG_MCP_TMS")
	)
	(segment
		(start 123.534424 -83.6422)
		(end 123.076208 -83.146138)
		(width 0.0889)
		(layer "In11.Cu")
		(net "JTAG_MCP_TMS")
	)
	(segment
		(start 343.027 -120.6754)
		(end 343.027 -120.529858)
		(width 0.089408)
		(layer "In11.Cu")
		(net "JTAG_MCP_TMS")
	)
	(segment
		(start 319.98666 -125.67412)
		(end 319.90284 -125.75794)
		(width 0.089408)
		(layer "In11.Cu")
		(net "JTAG_MCP_TMS")
	)
	(segment
		(start 287.736534 -86.32825)
		(end 287.730184 -86.317582)
		(width 0.089408)
		(layer "In11.Cu")
		(net "JTAG_MCP_TMS")
	)
	(segment
		(start 291.53485 -92.461334)
		(end 291.503608 -92.461334)
		(width 0.089408)
		(layer "In11.Cu")
		(net "JTAG_MCP_TMS")
	)
	(segment
		(start 372.156736 -128.110742)
		(end 373.913908 -128.110742)
		(width 0.089408)
		(layer "In11.Cu")
		(net "JTAG_MCP_TMS")
	)
	(segment
		(start 292.017958 -93.356176)
		(end 292.022784 -93.34754)
		(width 0.089408)
		(layer "In11.Cu")
		(net "JTAG_MCP_TMS")
	)
	(segment
		(start 287.730184 -89.289382)
		(end 287.725358 -89.280746)
		(width 0.089408)
		(layer "In11.Cu")
		(net "JTAG_MCP_TMS")
	)
	(segment
		(start 138.550904 -92.461588)
		(end 138.518138 -92.461588)
		(width 0.0889)
		(layer "In11.Cu")
		(net "JTAG_MCP_TMS")
	)
	(segment
		(start 322.064634 -125.67412)
		(end 319.98666 -125.67412)
		(width 0.089408)
		(layer "In11.Cu")
		(net "JTAG_MCP_TMS")
	)
	(segment
		(start 296.001948 -103.899462)
		(end 294.272462 -102.169976)
		(width 0.089408)
		(layer "In11.Cu")
		(net "JTAG_MCP_TMS")
	)
	(segment
		(start 302.405288 -107.70235)
		(end 301.499778 -107.70235)
		(width 0.089408)
		(layer "In11.Cu")
		(net "JTAG_MCP_TMS")
	)
	(segment
		(start 415.411158 -134.359396)
		(end 415.411158 -133.356858)
		(width 0.089408)
		(layer "In11.Cu")
		(net "JTAG_MCP_TMS")
	)
	(segment
		(start 123.952508 -84.041234)
		(end 123.919742 -84.041234)
		(width 0.0889)
		(layer "In11.Cu")
		(net "JTAG_MCP_TMS")
	)
	(segment
		(start 292.022784 -93.34754)
		(end 292.029134 -93.336872)
		(width 0.089408)
		(layer "In11.Cu")
		(net "JTAG_MCP_TMS")
	)
	(segment
		(start 154.961336 -110.882684)
		(end 154.79395 -110.882684)
		(width 0.089408)
		(layer "In11.Cu")
		(net "JTAG_MCP_TMS")
	)
	(segment
		(start 319.205864 -125.695964)
		(end 319.195958 -125.695964)
		(width 0.089408)
		(layer "In11.Cu")
		(net "JTAG_MCP_TMS")
	)
	(segment
		(start 428.459138 -122.535696)
		(end 432.13909 -122.535696)
		(width 0.089408)
		(layer "In11.Cu")
		(net "JTAG_MCP_TMS")
	)
	(segment
		(start 287.736534 -84.34705)
		(end 287.730184 -84.336382)
		(width 0.089408)
		(layer "In11.Cu")
		(net "JTAG_MCP_TMS")
	)
	(segment
		(start 423.990262 -127.850138)
		(end 425.235624 -127.850138)
		(width 0.089408)
		(layer "In11.Cu")
		(net "JTAG_MCP_TMS")
	)
	(segment
		(start 168.40708 -124.216922)
		(end 168.40708 -123.018042)
		(width 0.089408)
		(layer "In11.Cu")
		(net "JTAG_MCP_TMS")
	)
	(segment
		(start 154.79395 -110.882684)
		(end 143.597376 -99.68611)
		(width 0.089408)
		(layer "In11.Cu")
		(net "JTAG_MCP_TMS")
	)
	(segment
		(start 345.034616 -119.789702)
		(end 345.175078 -119.930164)
		(width 0.089408)
		(layer "In11.Cu")
		(net "JTAG_MCP_TMS")
	)
	(segment
		(start 379.09627 -128.638554)
		(end 379.09627 -130.323336)
		(width 0.089408)
		(layer "In11.Cu")
		(net "JTAG_MCP_TMS")
	)
	(segment
		(start 318.43726 -124.92736)
		(end 318.43726 -123.734322)
		(width 0.089408)
		(layer "In11.Cu")
		(net "JTAG_MCP_TMS")
	)
	(segment
		(start 287.730184 -84.336382)
		(end 287.725358 -84.327746)
		(width 0.089408)
		(layer "In11.Cu")
		(net "JTAG_MCP_TMS")
	)
	(segment
		(start 133.399784 -89.489788)
		(end 133.367018 -89.489788)
		(width 0.0889)
		(layer "In11.Cu")
		(net "JTAG_MCP_TMS")
	)
	(segment
		(start 322.327524 -125.988064)
		(end 322.327524 -125.93701)
		(width 0.089408)
		(layer "In11.Cu")
		(net "JTAG_MCP_TMS")
	)
	(segment
		(start 297.69689 -103.899462)
		(end 296.001948 -103.899462)
		(width 0.089408)
		(layer "In11.Cu")
		(net "JTAG_MCP_TMS")
	)
	(segment
		(start 301.499778 -107.70235)
		(end 297.69689 -103.899462)
		(width 0.089408)
		(layer "In11.Cu")
		(net "JTAG_MCP_TMS")
	)
	(arc
		(start 287.730184 -85.91804)
		(mid 287.809499 -85.628668)
		(end 287.736534 -85.33765)
		(width 0.089408)
		(layer "In11.Cu")
		(net "JTAG_MCP_TMS")
	)
	(arc
		(start 287.725358 -88.290146)
		(mid 287.676694 -88.094048)
		(end 287.730184 -87.89924)
		(width 0.089408)
		(layer "In11.Cu")
		(net "JTAG_MCP_TMS")
	)
	(arc
		(start 129.597658 -87.308436)
		(mid 129.38905 -87.096504)
		(end 129.103628 -87.013034)
		(width 0.0889)
		(layer "In11.Cu")
		(net "JTAG_MCP_TMS")
	)
	(arc
		(start 123.919742 -84.041234)
		(mid 123.646755 -83.919277)
		(end 123.534424 -83.6422)
		(width 0.0889)
		(layer "In11.Cu")
		(net "JTAG_MCP_TMS")
	)
	(arc
		(start 292.022784 -96.718882)
		(mid 291.969407 -96.524073)
		(end 292.017958 -96.327976)
		(width 0.089408)
		(layer "In11.Cu")
		(net "JTAG_MCP_TMS")
	)
	(arc
		(start 290.640008 -91.96578)
		(mid 290.446905 -91.909261)
		(end 290.305744 -91.765882)
		(width 0.089408)
		(layer "In11.Cu")
		(net "JTAG_MCP_TMS")
	)
	(arc
		(start 132.519674 -88.994234)
		(mid 132.322513 -88.942275)
		(end 132.17652 -88.799924)
		(width 0.0889)
		(layer "In11.Cu")
		(net "JTAG_MCP_TMS")
	)
	(arc
		(start 139.372848 -92.956634)
		(mid 139.181206 -92.899468)
		(end 139.041124 -92.756736)
		(width 0.0889)
		(layer "In11.Cu")
		(net "JTAG_MCP_TMS")
	)
	(arc
		(start 292.029134 -93.336872)
		(mid 292.025797 -92.761411)
		(end 291.53485 -92.461334)
		(width 0.089408)
		(layer "In11.Cu")
		(net "JTAG_MCP_TMS")
	)
	(arc
		(start 291.503608 -92.461334)
		(mid 291.307576 -92.40595)
		(end 291.164264 -92.261182)
		(width 0.089408)
		(layer "In11.Cu")
		(net "JTAG_MCP_TMS")
	)
	(arc
		(start 292.029134 -98.289872)
		(mid 292.102023 -97.998855)
		(end 292.022784 -97.709482)
		(width 0.089408)
		(layer "In11.Cu")
		(net "JTAG_MCP_TMS")
	)
	(arc
		(start 133.367018 -89.489788)
		(mid 133.173168 -89.433438)
		(end 133.031484 -89.289636)
		(width 0.0889)
		(layer "In11.Cu")
		(net "JTAG_MCP_TMS")
	)
	(arc
		(start 291.164264 -92.261182)
		(mid 290.956735 -92.049898)
		(end 290.672774 -91.96578)
		(width 0.089408)
		(layer "In11.Cu")
		(net "JTAG_MCP_TMS")
	)
	(arc
		(start 292.357048 -99.89058)
		(mid 292.022355 -99.689923)
		(end 292.017958 -99.299776)
		(width 0.089408)
		(layer "In11.Cu")
		(net "JTAG_MCP_TMS")
	)
	(arc
		(start 129.070862 -87.013034)
		(mid 128.87922 -86.955868)
		(end 128.739138 -86.813136)
		(width 0.0889)
		(layer "In11.Cu")
		(net "JTAG_MCP_TMS")
	)
	(arc
		(start 134.221728 -89.984834)
		(mid 134.030086 -89.927668)
		(end 133.890004 -89.784936)
		(width 0.0889)
		(layer "In11.Cu")
		(net "JTAG_MCP_TMS")
	)
	(arc
		(start 131.314698 -88.299036)
		(mid 131.10609 -88.087104)
		(end 130.820668 -88.003634)
		(width 0.0889)
		(layer "In11.Cu")
		(net "JTAG_MCP_TMS")
	)
	(arc
		(start 292.022784 -98.700082)
		(mid 291.969407 -98.505273)
		(end 292.017958 -98.309176)
		(width 0.089408)
		(layer "In11.Cu")
		(net "JTAG_MCP_TMS")
	)
	(arc
		(start 292.029134 -99.280472)
		(mid 292.102023 -98.989455)
		(end 292.022784 -98.700082)
		(width 0.089408)
		(layer "In11.Cu")
		(net "JTAG_MCP_TMS")
	)
	(arc
		(start 288.922968 -90.97518)
		(mid 288.729865 -90.918661)
		(end 288.588704 -90.775282)
		(width 0.089408)
		(layer "In11.Cu")
		(net "JTAG_MCP_TMS")
	)
	(arc
		(start 135.607044 -90.775536)
		(mid 135.40004 -90.564672)
		(end 135.116824 -90.480388)
		(width 0.0889)
		(layer "In11.Cu")
		(net "JTAG_MCP_TMS")
	)
	(arc
		(start 130.456178 -87.803736)
		(mid 130.249174 -87.592872)
		(end 129.965958 -87.508588)
		(width 0.0889)
		(layer "In11.Cu")
		(net "JTAG_MCP_TMS")
	)
	(arc
		(start 136.465564 -91.270836)
		(mid 136.256956 -91.058904)
		(end 135.971534 -90.975434)
		(width 0.0889)
		(layer "In11.Cu")
		(net "JTAG_MCP_TMS")
	)
	(arc
		(start 289.786568 -91.470734)
		(mid 289.590536 -91.41535)
		(end 289.447224 -91.270582)
		(width 0.089408)
		(layer "In11.Cu")
		(net "JTAG_MCP_TMS")
	)
	(arc
		(start 287.730184 -86.90864)
		(mid 287.809499 -86.619268)
		(end 287.736534 -86.32825)
		(width 0.089408)
		(layer "In11.Cu")
		(net "JTAG_MCP_TMS")
	)
	(arc
		(start 136.801098 -91.470988)
		(mid 136.607248 -91.414638)
		(end 136.465564 -91.270836)
		(width 0.0889)
		(layer "In11.Cu")
		(net "JTAG_MCP_TMS")
	)
	(arc
		(start 139.899644 -93.252036)
		(mid 139.691036 -93.040104)
		(end 139.405614 -92.956634)
		(width 0.0889)
		(layer "In11.Cu")
		(net "JTAG_MCP_TMS")
	)
	(arc
		(start 292.881304 -100.77704)
		(mid 292.883921 -100.19082)
		(end 292.380416 -99.89058)
		(width 0.089408)
		(layer "In11.Cu")
		(net "JTAG_MCP_TMS")
	)
	(arc
		(start 133.031484 -89.289636)
		(mid 132.822876 -89.077704)
		(end 132.537454 -88.994234)
		(width 0.0889)
		(layer "In11.Cu")
		(net "JTAG_MCP_TMS")
	)
	(arc
		(start 141.717014 -94.414848)
		(mid 141.692893 -94.328085)
		(end 141.656562 -94.245684)
		(width 0.0889)
		(layer "In11.Cu")
		(net "JTAG_MCP_TMS")
	)
	(arc
		(start 124.446538 -84.336636)
		(mid 124.23793 -84.124704)
		(end 123.952508 -84.041234)
		(width 0.0889)
		(layer "In11.Cu")
		(net "JTAG_MCP_TMS")
	)
	(arc
		(start 133.890004 -89.784936)
		(mid 133.683 -89.574072)
		(end 133.399784 -89.489788)
		(width 0.0889)
		(layer "In11.Cu")
		(net "JTAG_MCP_TMS")
	)
	(arc
		(start 125.305058 -84.831936)
		(mid 125.098054 -84.621072)
		(end 124.814838 -84.536788)
		(width 0.0889)
		(layer "In11.Cu")
		(net "JTAG_MCP_TMS")
	)
	(arc
		(start 135.084058 -90.480388)
		(mid 134.890208 -90.424038)
		(end 134.748524 -90.280236)
		(width 0.0889)
		(layer "In11.Cu")
		(net "JTAG_MCP_TMS")
	)
	(arc
		(start 287.730184 -89.88044)
		(mid 287.809499 -89.591068)
		(end 287.736534 -89.30005)
		(width 0.089408)
		(layer "In11.Cu")
		(net "JTAG_MCP_TMS")
	)
	(arc
		(start 292.022784 -93.747082)
		(mid 291.969407 -93.552273)
		(end 292.017958 -93.356176)
		(width 0.089408)
		(layer "In11.Cu")
		(net "JTAG_MCP_TMS")
	)
	(arc
		(start 292.022784 -95.728282)
		(mid 291.969251 -95.528384)
		(end 292.022784 -95.328486)
		(width 0.089408)
		(layer "In11.Cu")
		(net "JTAG_MCP_TMS")
	)
	(arc
		(start 288.069528 -90.480134)
		(mid 287.728615 -90.277228)
		(end 287.730184 -89.88044)
		(width 0.089408)
		(layer "In11.Cu")
		(net "JTAG_MCP_TMS")
	)
	(arc
		(start 127.353822 -86.022434)
		(mid 127.16218 -85.965268)
		(end 127.022098 -85.822536)
		(width 0.0889)
		(layer "In11.Cu")
		(net "JTAG_MCP_TMS")
	)
	(arc
		(start 127.880618 -86.317836)
		(mid 127.67201 -86.105904)
		(end 127.386588 -86.022434)
		(width 0.0889)
		(layer "In11.Cu")
		(net "JTAG_MCP_TMS")
	)
	(arc
		(start 287.725358 -87.299546)
		(mid 287.676694 -87.103448)
		(end 287.730184 -86.90864)
		(width 0.089408)
		(layer "In11.Cu")
		(net "JTAG_MCP_TMS")
	)
	(arc
		(start 292.029134 -96.308672)
		(mid 292.102023 -96.017655)
		(end 292.022784 -95.728282)
		(width 0.089408)
		(layer "In11.Cu")
		(net "JTAG_MCP_TMS")
	)
	(arc
		(start 293.490142 -101.528118)
		(mid 293.138551 -101.433853)
		(end 292.881304 -101.176328)
		(width 0.089408)
		(layer "In11.Cu")
		(net "JTAG_MCP_TMS")
	)
	(arc
		(start 126.499112 -85.527388)
		(mid 126.305262 -85.471038)
		(end 126.163578 -85.327236)
		(width 0.0889)
		(layer "In11.Cu")
		(net "JTAG_MCP_TMS")
	)
	(arc
		(start 287.725358 -89.280746)
		(mid 287.676694 -89.084648)
		(end 287.730184 -88.88984)
		(width 0.089408)
		(layer "In11.Cu")
		(net "JTAG_MCP_TMS")
	)
	(arc
		(start 138.182604 -92.261436)
		(mid 137.973996 -92.049504)
		(end 137.688574 -91.966034)
		(width 0.0889)
		(layer "In11.Cu")
		(net "JTAG_MCP_TMS")
	)
	(arc
		(start 292.029134 -97.299272)
		(mid 292.102023 -97.008255)
		(end 292.022784 -96.718882)
		(width 0.089408)
		(layer "In11.Cu")
		(net "JTAG_MCP_TMS")
	)
	(arc
		(start 289.447224 -91.270582)
		(mid 289.239695 -91.059298)
		(end 288.955734 -90.97518)
		(width 0.089408)
		(layer "In11.Cu")
		(net "JTAG_MCP_TMS")
	)
	(arc
		(start 127.022098 -85.822536)
		(mid 126.815094 -85.611672)
		(end 126.531878 -85.527388)
		(width 0.0889)
		(layer "In11.Cu")
		(net "JTAG_MCP_TMS")
	)
	(arc
		(start 134.748524 -90.280236)
		(mid 134.539916 -90.068304)
		(end 134.254494 -89.984834)
		(width 0.0889)
		(layer "In11.Cu")
		(net "JTAG_MCP_TMS")
	)
	(arc
		(start 292.022784 -95.328486)
		(mid 292.101881 -95.033084)
		(end 292.022784 -94.737682)
		(width 0.089408)
		(layer "In11.Cu")
		(net "JTAG_MCP_TMS")
	)
	(arc
		(start 287.730184 -88.88984)
		(mid 287.809499 -88.600468)
		(end 287.736534 -88.30945)
		(width 0.089408)
		(layer "In11.Cu")
		(net "JTAG_MCP_TMS")
	)
	(arc
		(start 287.730184 -87.89924)
		(mid 287.809499 -87.609868)
		(end 287.736534 -87.31885)
		(width 0.089408)
		(layer "In11.Cu")
		(net "JTAG_MCP_TMS")
	)
	(arc
		(start 125.636782 -85.031834)
		(mid 125.44514 -84.974668)
		(end 125.305058 -84.831936)
		(width 0.0889)
		(layer "In11.Cu")
		(net "JTAG_MCP_TMS")
	)
	(arc
		(start 287.725358 -86.308946)
		(mid 287.676694 -86.112848)
		(end 287.730184 -85.91804)
		(width 0.089408)
		(layer "In11.Cu")
		(net "JTAG_MCP_TMS")
	)
	(arc
		(start 292.881304 -101.176328)
		(mid 292.827898 -100.976684)
		(end 292.881304 -100.77704)
		(width 0.089408)
		(layer "In11.Cu")
		(net "JTAG_MCP_TMS")
	)
	(arc
		(start 287.725358 -85.318346)
		(mid 287.676694 -85.122248)
		(end 287.730184 -84.92744)
		(width 0.089408)
		(layer "In11.Cu")
		(net "JTAG_MCP_TMS")
	)
	(arc
		(start 130.787902 -88.003634)
		(mid 130.59626 -87.946468)
		(end 130.456178 -87.803736)
		(width 0.0889)
		(layer "In11.Cu")
		(net "JTAG_MCP_TMS")
	)
	(arc
		(start 135.938768 -90.975434)
		(mid 135.747126 -90.918268)
		(end 135.607044 -90.775536)
		(width 0.0889)
		(layer "In11.Cu")
		(net "JTAG_MCP_TMS")
	)
	(arc
		(start 128.739138 -86.813136)
		(mid 128.532134 -86.602272)
		(end 128.248918 -86.517988)
		(width 0.0889)
		(layer "In11.Cu")
		(net "JTAG_MCP_TMS")
	)
	(arc
		(start 129.933192 -87.508588)
		(mid 129.739342 -87.452238)
		(end 129.597658 -87.308436)
		(width 0.0889)
		(layer "In11.Cu")
		(net "JTAG_MCP_TMS")
	)
	(arc
		(start 137.324084 -91.766136)
		(mid 137.11708 -91.555272)
		(end 136.833864 -91.470988)
		(width 0.0889)
		(layer "In11.Cu")
		(net "JTAG_MCP_TMS")
	)
	(arc
		(start 137.655808 -91.966034)
		(mid 137.464166 -91.908868)
		(end 137.324084 -91.766136)
		(width 0.0889)
		(layer "In11.Cu")
		(net "JTAG_MCP_TMS")
	)
	(arc
		(start 139.041124 -92.756736)
		(mid 138.83412 -92.545872)
		(end 138.550904 -92.461588)
		(width 0.0889)
		(layer "In11.Cu")
		(net "JTAG_MCP_TMS")
	)
	(arc
		(start 292.017958 -94.729046)
		(mid 291.969294 -94.532948)
		(end 292.022784 -94.33814)
		(width 0.089408)
		(layer "In11.Cu")
		(net "JTAG_MCP_TMS")
	)
	(arc
		(start 138.518138 -92.461588)
		(mid 138.324288 -92.405238)
		(end 138.182604 -92.261436)
		(width 0.0889)
		(layer "In11.Cu")
		(net "JTAG_MCP_TMS")
	)
	(arc
		(start 287.725358 -84.327746)
		(mid 287.676694 -84.131648)
		(end 287.730184 -83.93684)
		(width 0.089408)
		(layer "In11.Cu")
		(net "JTAG_MCP_TMS")
	)
	(arc
		(start 288.588704 -90.775282)
		(mid 288.382667 -90.565004)
		(end 288.10077 -90.480134)
		(width 0.089408)
		(layer "In11.Cu")
		(net "JTAG_MCP_TMS")
	)
	(arc
		(start 140.235178 -93.452188)
		(mid 140.041328 -93.395838)
		(end 139.899644 -93.252036)
		(width 0.0889)
		(layer "In11.Cu")
		(net "JTAG_MCP_TMS")
	)
	(arc
		(start 128.216152 -86.517988)
		(mid 128.022302 -86.461638)
		(end 127.880618 -86.317836)
		(width 0.0889)
		(layer "In11.Cu")
		(net "JTAG_MCP_TMS")
	)
	(arc
		(start 131.650232 -88.499188)
		(mid 131.456382 -88.442838)
		(end 131.314698 -88.299036)
		(width 0.0889)
		(layer "In11.Cu")
		(net "JTAG_MCP_TMS")
	)
	(arc
		(start 292.029134 -94.327472)
		(mid 292.102023 -94.036455)
		(end 292.022784 -93.747082)
		(width 0.089408)
		(layer "In11.Cu")
		(net "JTAG_MCP_TMS")
	)
	(arc
		(start 124.782072 -84.536788)
		(mid 124.588222 -84.480438)
		(end 124.446538 -84.336636)
		(width 0.0889)
		(layer "In11.Cu")
		(net "JTAG_MCP_TMS")
	)
	(arc
		(start 292.022784 -97.709482)
		(mid 291.969407 -97.514673)
		(end 292.017958 -97.318576)
		(width 0.089408)
		(layer "In11.Cu")
		(net "JTAG_MCP_TMS")
	)
	(arc
		(start 132.173218 -88.794082)
		(mid 131.967597 -88.584159)
		(end 131.6863 -88.499188)
		(width 0.0889)
		(layer "In11.Cu")
		(net "JTAG_MCP_TMS")
	)
	(arc
		(start 126.163578 -85.327236)
		(mid 125.95497 -85.115304)
		(end 125.669548 -85.031834)
		(width 0.0889)
		(layer "In11.Cu")
		(net "JTAG_MCP_TMS")
	)
	(arc
		(start 290.305744 -91.765882)
		(mid 290.099707 -91.555604)
		(end 289.81781 -91.470734)
		(width 0.089408)
		(layer "In11.Cu")
		(net "JTAG_MCP_TMS")
	)
	(arc
		(start 287.730184 -84.92744)
		(mid 287.809499 -84.638068)
		(end 287.736534 -84.34705)
		(width 0.089408)
		(layer "In11.Cu")
		(net "JTAG_MCP_TMS")
	)
	(segment
		(start 467.36 -135.255)
		(end 467.778592 -135.255)
		(width 0.10795)
		(layer "F.Cu")
		(net "JTAG_MCP_TCK_R")
	)
	(segment
		(start 467.778592 -135.255)
		(end 468.667592 -134.366)
		(width 0.10795)
		(layer "F.Cu")
		(net "JTAG_MCP_TCK_R")
	)
	(segment
		(start 468.667592 -134.366)
		(end 470.282016 -134.366)
		(width 0.10795)
		(layer "F.Cu")
		(net "JTAG_MCP_TCK_R")
	)
	(segment
		(start 465.836 -134.366)
		(end 465.2264 -134.366)
		(width 0.10795)
		(layer "F.Cu")
		(net "JTAG_MCP_TCK")
	)
	(segment
		(start 465.7598 -126.3142)
		(end 466.198204 -126.3142)
		(width 0.10795)
		(layer "F.Cu")
		(net "JTAG_MCP_TCK")
	)
	(segment
		(start 466.198204 -126.3142)
		(end 466.658198 -126.774194)
		(width 0.10795)
		(layer "F.Cu")
		(net "JTAG_MCP_TCK")
	)
	(segment
		(start 466.658198 -127.907796)
		(end 466.68055 -127.930148)
		(width 0.10795)
		(layer "F.Cu")
		(net "JTAG_MCP_TCK")
	)
	(segment
		(start 428.610522 -124.784612)
		(end 428.536608 -124.858526)
		(width 0.10795)
		(layer "F.Cu")
		(net "JTAG_MCP_TCK")
	)
	(segment
		(start 123.363228 -81.659984)
		(end 123.934728 -81.659984)
		(width 0.1016)
		(layer "F.Cu")
		(net "JTAG_MCP_TCK")
	)
	(segment
		(start 465.2264 -132.224526)
		(end 465.2264 -134.366)
		(width 0.10795)
		(layer "F.Cu")
		(net "JTAG_MCP_TCK")
	)
	(segment
		(start 465.550758 -131.900168)
		(end 465.2264 -132.224526)
		(width 0.10795)
		(layer "F.Cu")
		(net "JTAG_MCP_TCK")
	)
	(segment
		(start 466.658198 -126.774194)
		(end 466.658198 -127.907796)
		(width 0.10795)
		(layer "F.Cu")
		(net "JTAG_MCP_TCK")
	)
	(segment
		(start 466.68055 -127.930148)
		(end 466.68055 -130.673602)
		(width 0.10795)
		(layer "F.Cu")
		(net "JTAG_MCP_TCK")
	)
	(segment
		(start 288.36366 -81.659984)
		(end 288.93516 -81.659984)
		(width 0.1016)
		(layer "F.Cu")
		(net "JTAG_MCP_TCK")
	)
	(segment
		(start 466.68055 -130.673602)
		(end 465.550758 -131.803394)
		(width 0.10795)
		(layer "F.Cu")
		(net "JTAG_MCP_TCK")
	)
	(segment
		(start 465.550758 -131.803394)
		(end 465.550758 -131.900168)
		(width 0.10795)
		(layer "F.Cu")
		(net "JTAG_MCP_TCK")
	)
	(segment
		(start 465.836 -134.366)
		(end 467.36 -134.366)
		(width 0.10795)
		(layer "F.Cu")
		(net "JTAG_MCP_TCK")
	)
	(segment
		(start 428.610522 -123.749562)
		(end 428.610522 -124.784612)
		(width 0.10795)
		(layer "F.Cu")
		(net "JTAG_MCP_TCK")
	)
	(via
		(at 465.2264 -134.366)
		(size 0.508)
		(drill 0.254)
		(layers "F.Cu" "B.Cu")
		(net "JTAG_MCP_TCK")
	)
	(via
		(at 344.033348 -120.431814)
		(size 0.508)
		(drill 0.254)
		(layers "F.Cu" "B.Cu")
		(net "JTAG_MCP_TCK")
	)
	(via
		(at 288.93516 -81.659984)
		(size 0.508)
		(drill 0.254)
		(layers "F.Cu" "B.Cu")
		(net "JTAG_MCP_TCK")
	)
	(via
		(at 170.561 -127.3302)
		(size 0.508)
		(drill 0.254)
		(layers "F.Cu" "B.Cu")
		(net "JTAG_MCP_TCK")
	)
	(via
		(at 465.7598 -126.3142)
		(size 0.508)
		(drill 0.254)
		(layers "F.Cu" "B.Cu")
		(net "JTAG_MCP_TCK")
	)
	(via
		(at 428.536608 -124.858526)
		(size 0.762)
		(drill 0.381)
		(layers "F.Cu" "B.Cu")
		(net "JTAG_MCP_TCK")
	)
	(via
		(at 428.610522 -123.749562)
		(size 0.508)
		(drill 0.254)
		(layers "F.Cu" "B.Cu")
		(net "JTAG_MCP_TCK")
	)
	(via
		(at 321.605148 -126.086616)
		(size 0.508)
		(drill 0.254)
		(layers "F.Cu" "B.Cu")
		(net "JTAG_MCP_TCK")
	)
	(via
		(at 123.934728 -81.659984)
		(size 0.508)
		(drill 0.254)
		(layers "F.Cu" "B.Cu")
		(net "JTAG_MCP_TCK")
	)
	(segment
		(start 465.2264 -134.366)
		(end 464.4644 -134.366)
		(width 0.10795)
		(layer "B.Cu")
		(net "JTAG_MCP_TCK")
	)
	(segment
		(start 182.196994 -127.481584)
		(end 175.179228 -127.481584)
		(width 0.089408)
		(layer "In2.Cu")
		(net "JTAG_MCP_TCK")
	)
	(segment
		(start 184.433972 -130.585972)
		(end 184.433972 -129.226818)
		(width 0.089408)
		(layer "In2.Cu")
		(net "JTAG_MCP_TCK")
	)
	(segment
		(start 321.499992 -130.40233)
		(end 321.499992 -130.93573)
		(width 0.089408)
		(layer "In2.Cu")
		(net "JTAG_MCP_TCK")
	)
	(segment
		(start 321.188842 -127.612902)
		(end 321.867784 -128.291844)
		(width 0.089408)
		(layer "In2.Cu")
		(net "JTAG_MCP_TCK")
	)
	(segment
		(start 438.80913 -123.347226)
		(end 438.809384 -123.34748)
		(width 0.089408)
		(layer "In2.Cu")
		(net "JTAG_MCP_TCK")
	)
	(segment
		(start 428.610522 -123.749562)
		(end 429.626522 -124.765562)
		(width 0.089408)
		(layer "In2.Cu")
		(net "JTAG_MCP_TCK")
	)
	(segment
		(start 324.772528 -150.390606)
		(end 326.687434 -152.305512)
		(width 0.089408)
		(layer "In2.Cu")
		(net "JTAG_MCP_TCK")
	)
	(segment
		(start 189.338458 -138.34364)
		(end 191.302132 -136.379966)
		(width 0.089408)
		(layer "In2.Cu")
		(net "JTAG_MCP_TCK")
	)
	(segment
		(start 264.861548 -157.39872)
		(end 264.8458 -157.414468)
		(width 0.089408)
		(layer "In2.Cu")
		(net "JTAG_MCP_TCK")
	)
	(segment
		(start 439.696352 -123.347226)
		(end 440.327034 -122.716544)
		(width 0.089408)
		(layer "In2.Cu")
		(net "JTAG_MCP_TCK")
	)
	(segment
		(start 323.585078 -156.308298)
		(end 278.445722 -156.308298)
		(width 0.089408)
		(layer "In2.Cu")
		(net "JTAG_MCP_TCK")
	)
	(segment
		(start 321.499738 -130.201924)
		(end 321.499738 -130.402076)
		(width 0.089408)
		(layer "In2.Cu")
		(net "JTAG_MCP_TCK")
	)
	(segment
		(start 321.867784 -128.291844)
		(end 321.867784 -129.833878)
		(width 0.089408)
		(layer "In2.Cu")
		(net "JTAG_MCP_TCK")
	)
	(segment
		(start 450.551042 -127.361696)
		(end 456.05065 -127.361696)
		(width 0.089408)
		(layer "In2.Cu")
		(net "JTAG_MCP_TCK")
	)
	(segment
		(start 191.008 -157.00502)
		(end 191.007746 -157.004766)
		(width 0.089408)
		(layer "In2.Cu")
		(net "JTAG_MCP_TCK")
	)
	(segment
		(start 324.864222 -137.326878)
		(end 323.563488 -138.627612)
		(width 0.089408)
		(layer "In2.Cu")
		(net "JTAG_MCP_TCK")
	)
	(segment
		(start 456.05065 -127.361696)
		(end 457.275946 -126.1364)
		(width 0.089408)
		(layer "In2.Cu")
		(net "JTAG_MCP_TCK")
	)
	(segment
		(start 191.3509 -157.39872)
		(end 191.008 -157.05582)
		(width 0.089408)
		(layer "In2.Cu")
		(net "JTAG_MCP_TCK")
	)
	(segment
		(start 323.95033 -135.857488)
		(end 324.864222 -136.77138)
		(width 0.089408)
		(layer "In2.Cu")
		(net "JTAG_MCP_TCK")
	)
	(segment
		(start 191.302132 -134.358126)
		(end 190.073534 -133.129528)
		(width 0.089408)
		(layer "In2.Cu")
		(net "JTAG_MCP_TCK")
	)
	(segment
		(start 191.302132 -136.379966)
		(end 191.302132 -134.358126)
		(width 0.089408)
		(layer "In2.Cu")
		(net "JTAG_MCP_TCK")
	)
	(segment
		(start 440.327034 -122.716544)
		(end 445.90589 -122.716544)
		(width 0.089408)
		(layer "In2.Cu")
		(net "JTAG_MCP_TCK")
	)
	(segment
		(start 278.445214 -156.30779)
		(end 278.29383 -156.30779)
		(width 0.089408)
		(layer "In2.Cu")
		(net "JTAG_MCP_TCK")
	)
	(segment
		(start 190.073534 -133.129528)
		(end 188.305948 -133.129528)
		(width 0.089408)
		(layer "In2.Cu")
		(net "JTAG_MCP_TCK")
	)
	(segment
		(start 191.008 -157.05582)
		(end 191.008 -157.00502)
		(width 0.089408)
		(layer "In2.Cu")
		(net "JTAG_MCP_TCK")
	)
	(segment
		(start 323.563488 -140.282168)
		(end 324.772528 -141.491208)
		(width 0.089408)
		(layer "In2.Cu")
		(net "JTAG_MCP_TCK")
	)
	(segment
		(start 186.67222 -131.4958)
		(end 185.31078 -131.4958)
		(width 0.089408)
		(layer "In2.Cu")
		(net "JTAG_MCP_TCK")
	)
	(segment
		(start 187.336938 -152.414478)
		(end 187.336938 -139.408662)
		(width 0.089408)
		(layer "In2.Cu")
		(net "JTAG_MCP_TCK")
	)
	(segment
		(start 324.772528 -141.491208)
		(end 324.772528 -150.390606)
		(width 0.089408)
		(layer "In2.Cu")
		(net "JTAG_MCP_TCK")
	)
	(segment
		(start 445.90589 -122.716544)
		(end 450.551042 -127.361696)
		(width 0.089408)
		(layer "In2.Cu")
		(net "JTAG_MCP_TCK")
	)
	(segment
		(start 191.417448 -157.414468)
		(end 191.4017 -157.39872)
		(width 0.089408)
		(layer "In2.Cu")
		(net "JTAG_MCP_TCK")
	)
	(segment
		(start 189.901576 -152.81783)
		(end 187.74029 -152.81783)
		(width 0.089408)
		(layer "In2.Cu")
		(net "JTAG_MCP_TCK")
	)
	(segment
		(start 324.971918 -157.695138)
		(end 323.585078 -156.308298)
		(width 0.089408)
		(layer "In2.Cu")
		(net "JTAG_MCP_TCK")
	)
	(segment
		(start 187.74029 -152.81783)
		(end 187.336938 -152.414478)
		(width 0.089408)
		(layer "In2.Cu")
		(net "JTAG_MCP_TCK")
	)
	(segment
		(start 188.40196 -138.34364)
		(end 189.338458 -138.34364)
		(width 0.089408)
		(layer "In2.Cu")
		(net "JTAG_MCP_TCK")
	)
	(segment
		(start 329.90028 -155.306522)
		(end 331.244448 -156.65069)
		(width 0.089408)
		(layer "In2.Cu")
		(net "JTAG_MCP_TCK")
	)
	(segment
		(start 188.305948 -133.129528)
		(end 186.67222 -131.4958)
		(width 0.089408)
		(layer "In2.Cu")
		(net "JTAG_MCP_TCK")
	)
	(segment
		(start 277.71852 -156.8831)
		(end 265.399012 -156.8831)
		(width 0.089408)
		(layer "In2.Cu")
		(net "JTAG_MCP_TCK")
	)
	(segment
		(start 439.210196 -123.34748)
		(end 439.21045 -123.347226)
		(width 0.089408)
		(layer "In2.Cu")
		(net "JTAG_MCP_TCK")
	)
	(segment
		(start 171.004992 -126.886208)
		(end 170.561 -127.3302)
		(width 0.089408)
		(layer "In2.Cu")
		(net "JTAG_MCP_TCK")
	)
	(segment
		(start 264.8458 -157.414468)
		(end 191.417448 -157.414468)
		(width 0.089408)
		(layer "In2.Cu")
		(net "JTAG_MCP_TCK")
	)
	(segment
		(start 331.244448 -157.2895)
		(end 330.83881 -157.695138)
		(width 0.089408)
		(layer "In2.Cu")
		(net "JTAG_MCP_TCK")
	)
	(segment
		(start 329.90028 -154.23896)
		(end 329.90028 -155.306522)
		(width 0.089408)
		(layer "In2.Cu")
		(net "JTAG_MCP_TCK")
	)
	(segment
		(start 185.139584 -131.324604)
		(end 185.139584 -131.291584)
		(width 0.089408)
		(layer "In2.Cu")
		(net "JTAG_MCP_TCK")
	)
	(segment
		(start 331.244448 -156.65069)
		(end 331.244448 -157.2895)
		(width 0.089408)
		(layer "In2.Cu")
		(net "JTAG_MCP_TCK")
	)
	(segment
		(start 173.994572 -126.296928)
		(end 171.981368 -126.296928)
		(width 0.089408)
		(layer "In2.Cu")
		(net "JTAG_MCP_TCK")
	)
	(segment
		(start 321.867784 -129.833878)
		(end 321.499738 -130.201924)
		(width 0.089408)
		(layer "In2.Cu")
		(net "JTAG_MCP_TCK")
	)
	(segment
		(start 278.29383 -156.30779)
		(end 277.71852 -156.8831)
		(width 0.089408)
		(layer "In2.Cu")
		(net "JTAG_MCP_TCK")
	)
	(segment
		(start 184.433972 -129.226818)
		(end 183.605424 -128.39827)
		(width 0.089408)
		(layer "In2.Cu")
		(net "JTAG_MCP_TCK")
	)
	(segment
		(start 191.008 -153.924254)
		(end 189.901576 -152.81783)
		(width 0.089408)
		(layer "In2.Cu")
		(net "JTAG_MCP_TCK")
	)
	(segment
		(start 278.445722 -156.308298)
		(end 278.445214 -156.30779)
		(width 0.089408)
		(layer "In2.Cu")
		(net "JTAG_MCP_TCK")
	)
	(segment
		(start 435.824376 -123.347226)
		(end 438.80913 -123.347226)
		(width 0.089408)
		(layer "In2.Cu")
		(net "JTAG_MCP_TCK")
	)
	(segment
		(start 323.95033 -133.386068)
		(end 323.95033 -135.857488)
		(width 0.089408)
		(layer "In2.Cu")
		(net "JTAG_MCP_TCK")
	)
	(segment
		(start 191.007746 -157.004766)
		(end 191.007746 -156.76245)
		(width 0.089408)
		(layer "In2.Cu")
		(net "JTAG_MCP_TCK")
	)
	(segment
		(start 175.179228 -127.481584)
		(end 173.994572 -126.296928)
		(width 0.089408)
		(layer "In2.Cu")
		(net "JTAG_MCP_TCK")
	)
	(segment
		(start 324.864222 -136.77138)
		(end 324.864222 -137.326878)
		(width 0.089408)
		(layer "In2.Cu")
		(net "JTAG_MCP_TCK")
	)
	(segment
		(start 191.4017 -157.39872)
		(end 191.3509 -157.39872)
		(width 0.089408)
		(layer "In2.Cu")
		(net "JTAG_MCP_TCK")
	)
	(segment
		(start 183.605424 -128.39827)
		(end 183.11368 -128.39827)
		(width 0.089408)
		(layer "In2.Cu")
		(net "JTAG_MCP_TCK")
	)
	(segment
		(start 185.139584 -131.291584)
		(end 184.433972 -130.585972)
		(width 0.089408)
		(layer "In2.Cu")
		(net "JTAG_MCP_TCK")
	)
	(segment
		(start 321.499992 -130.93573)
		(end 323.95033 -133.386068)
		(width 0.089408)
		(layer "In2.Cu")
		(net "JTAG_MCP_TCK")
	)
	(segment
		(start 457.275946 -126.1364)
		(end 459.814168 -126.1364)
		(width 0.089408)
		(layer "In2.Cu")
		(net "JTAG_MCP_TCK")
	)
	(segment
		(start 438.809384 -123.34748)
		(end 439.210196 -123.34748)
		(width 0.089408)
		(layer "In2.Cu")
		(net "JTAG_MCP_TCK")
	)
	(segment
		(start 191.007746 -156.76245)
		(end 191.008 -156.762196)
		(width 0.089408)
		(layer "In2.Cu")
		(net "JTAG_MCP_TCK")
	)
	(segment
		(start 326.687434 -152.305512)
		(end 327.966832 -152.305512)
		(width 0.089408)
		(layer "In2.Cu")
		(net "JTAG_MCP_TCK")
	)
	(segment
		(start 265.399012 -156.8831)
		(end 264.883392 -157.39872)
		(width 0.089408)
		(layer "In2.Cu")
		(net "JTAG_MCP_TCK")
	)
	(segment
		(start 439.21045 -123.347226)
		(end 439.696352 -123.347226)
		(width 0.089408)
		(layer "In2.Cu")
		(net "JTAG_MCP_TCK")
	)
	(segment
		(start 264.883392 -157.39872)
		(end 264.861548 -157.39872)
		(width 0.089408)
		(layer "In2.Cu")
		(net "JTAG_MCP_TCK")
	)
	(segment
		(start 465.416392 -126.657608)
		(end 465.7598 -126.3142)
		(width 0.089408)
		(layer "In2.Cu")
		(net "JTAG_MCP_TCK")
	)
	(segment
		(start 191.008 -156.762196)
		(end 191.008 -153.924254)
		(width 0.089408)
		(layer "In2.Cu")
		(net "JTAG_MCP_TCK")
	)
	(segment
		(start 434.40604 -124.765562)
		(end 435.824376 -123.347226)
		(width 0.089408)
		(layer "In2.Cu")
		(net "JTAG_MCP_TCK")
	)
	(segment
		(start 321.499738 -130.402076)
		(end 321.499992 -130.40233)
		(width 0.089408)
		(layer "In2.Cu")
		(net "JTAG_MCP_TCK")
	)
	(segment
		(start 330.83881 -157.695138)
		(end 324.971918 -157.695138)
		(width 0.089408)
		(layer "In2.Cu")
		(net "JTAG_MCP_TCK")
	)
	(segment
		(start 183.11368 -128.39827)
		(end 182.196994 -127.481584)
		(width 0.089408)
		(layer "In2.Cu")
		(net "JTAG_MCP_TCK")
	)
	(segment
		(start 321.188842 -126.502922)
		(end 321.188842 -127.612902)
		(width 0.089408)
		(layer "In2.Cu")
		(net "JTAG_MCP_TCK")
	)
	(segment
		(start 185.31078 -131.4958)
		(end 185.139584 -131.324604)
		(width 0.089408)
		(layer "In2.Cu")
		(net "JTAG_MCP_TCK")
	)
	(segment
		(start 323.563488 -138.627612)
		(end 323.563488 -140.282168)
		(width 0.089408)
		(layer "In2.Cu")
		(net "JTAG_MCP_TCK")
	)
	(segment
		(start 460.335376 -126.657608)
		(end 465.416392 -126.657608)
		(width 0.089408)
		(layer "In2.Cu")
		(net "JTAG_MCP_TCK")
	)
	(segment
		(start 171.392088 -126.886208)
		(end 171.004992 -126.886208)
		(width 0.089408)
		(layer "In2.Cu")
		(net "JTAG_MCP_TCK")
	)
	(segment
		(start 171.981368 -126.296928)
		(end 171.392088 -126.886208)
		(width 0.089408)
		(layer "In2.Cu")
		(net "JTAG_MCP_TCK")
	)
	(segment
		(start 429.626522 -124.765562)
		(end 434.40604 -124.765562)
		(width 0.089408)
		(layer "In2.Cu")
		(net "JTAG_MCP_TCK")
	)
	(segment
		(start 321.605148 -126.086616)
		(end 321.188842 -126.502922)
		(width 0.089408)
		(layer "In2.Cu")
		(net "JTAG_MCP_TCK")
	)
	(segment
		(start 187.336938 -139.408662)
		(end 188.40196 -138.34364)
		(width 0.089408)
		(layer "In2.Cu")
		(net "JTAG_MCP_TCK")
	)
	(segment
		(start 459.814168 -126.1364)
		(end 460.335376 -126.657608)
		(width 0.089408)
		(layer "In2.Cu")
		(net "JTAG_MCP_TCK")
	)
	(segment
		(start 327.966832 -152.305512)
		(end 329.90028 -154.23896)
		(width 0.089408)
		(layer "In2.Cu")
		(net "JTAG_MCP_TCK")
	)
	(segment
		(start 323.817488 -125.477016)
		(end 323.864224 -125.43028)
		(width 0.089408)
		(layer "In9.Cu")
		(net "JTAG_MCP_TCK")
	)
	(segment
		(start 343.672414 -120.431814)
		(end 344.033348 -120.431814)
		(width 0.089408)
		(layer "In9.Cu")
		(net "JTAG_MCP_TCK")
	)
	(segment
		(start 337.889342 -123.041664)
		(end 341.48649 -119.444516)
		(width 0.089408)
		(layer "In9.Cu")
		(net "JTAG_MCP_TCK")
	)
	(segment
		(start 323.864224 -125.43028)
		(end 324.719188 -125.43028)
		(width 0.089408)
		(layer "In9.Cu")
		(net "JTAG_MCP_TCK")
	)
	(segment
		(start 330.265786 -123.6218)
		(end 330.845922 -123.041664)
		(width 0.089408)
		(layer "In9.Cu")
		(net "JTAG_MCP_TCK")
	)
	(segment
		(start 321.605148 -126.086616)
		(end 321.605148 -125.943868)
		(width 0.089408)
		(layer "In9.Cu")
		(net "JTAG_MCP_TCK")
	)
	(segment
		(start 342.685116 -119.444516)
		(end 343.672414 -120.431814)
		(width 0.089408)
		(layer "In9.Cu")
		(net "JTAG_MCP_TCK")
	)
	(segment
		(start 330.845922 -123.041664)
		(end 337.889342 -123.041664)
		(width 0.089408)
		(layer "In9.Cu")
		(net "JTAG_MCP_TCK")
	)
	(segment
		(start 322.072 -125.477016)
		(end 323.817488 -125.477016)
		(width 0.089408)
		(layer "In9.Cu")
		(net "JTAG_MCP_TCK")
	)
	(segment
		(start 328.51852 -123.839732)
		(end 328.736452 -123.6218)
		(width 0.089408)
		(layer "In9.Cu")
		(net "JTAG_MCP_TCK")
	)
	(segment
		(start 324.719188 -125.43028)
		(end 326.309736 -123.839732)
		(width 0.089408)
		(layer "In9.Cu")
		(net "JTAG_MCP_TCK")
	)
	(segment
		(start 326.309736 -123.839732)
		(end 328.51852 -123.839732)
		(width 0.089408)
		(layer "In9.Cu")
		(net "JTAG_MCP_TCK")
	)
	(segment
		(start 321.605148 -125.943868)
		(end 322.072 -125.477016)
		(width 0.089408)
		(layer "In9.Cu")
		(net "JTAG_MCP_TCK")
	)
	(segment
		(start 341.48649 -119.444516)
		(end 342.685116 -119.444516)
		(width 0.089408)
		(layer "In9.Cu")
		(net "JTAG_MCP_TCK")
	)
	(segment
		(start 328.736452 -123.6218)
		(end 330.265786 -123.6218)
		(width 0.089408)
		(layer "In9.Cu")
		(net "JTAG_MCP_TCK")
	)
	(segment
		(start 293.460932 -102.385876)
		(end 293.306246 -102.23119)
		(width 0.089408)
		(layer "In11.Cu")
		(net "JTAG_MCP_TCK")
	)
	(segment
		(start 124.0282 -86.0806)
		(end 124.5616 -86.614)
		(width 0.089408)
		(layer "In11.Cu")
		(net "JTAG_MCP_TCK")
	)
	(segment
		(start 412.50743 -135.460486)
		(end 414.994344 -135.460486)
		(width 0.089408)
		(layer "In11.Cu")
		(net "JTAG_MCP_TCK")
	)
	(segment
		(start 144.73428 -101.165152)
		(end 154.69362 -111.124492)
		(width 0.089408)
		(layer "In11.Cu")
		(net "JTAG_MCP_TCK")
	)
	(segment
		(start 130.8608 -89.9922)
		(end 131.445 -90.5764)
		(width 0.089408)
		(layer "In11.Cu")
		(net "JTAG_MCP_TCK")
	)
	(segment
		(start 122.8344 -85.6488)
		(end 123.2916 -85.6488)
		(width 0.089408)
		(layer "In11.Cu")
		(net "JTAG_MCP_TCK")
	)
	(segment
		(start 371.956076 -128.594358)
		(end 373.313452 -128.594358)
		(width 0.089408)
		(layer "In11.Cu")
		(net "JTAG_MCP_TCK")
	)
	(segment
		(start 375.468134 -130.187192)
		(end 378.260102 -130.187192)
		(width 0.089408)
		(layer "In11.Cu")
		(net "JTAG_MCP_TCK")
	)
	(segment
		(start 128.375918 -88.497918)
		(end 129.0066 -89.1286)
		(width 0.089408)
		(layer "In11.Cu")
		(net "JTAG_MCP_TCK")
	)
	(segment
		(start 124.5616 -86.614)
		(end 124.9172 -86.614)
		(width 0.089408)
		(layer "In11.Cu")
		(net "JTAG_MCP_TCK")
	)
	(segment
		(start 287.564576 -85.42274)
		(end 287.558226 -85.412072)
		(width 0.089408)
		(layer "In11.Cu")
		(net "JTAG_MCP_TCK")
	)
	(segment
		(start 133.0198 -91.5162)
		(end 133.4516 -91.5162)
		(width 0.089408)
		(layer "In11.Cu")
		(net "JTAG_MCP_TCK")
	)
	(segment
		(start 367.358422 -123.54687)
		(end 367.358422 -123.996704)
		(width 0.089408)
		(layer "In11.Cu")
		(net "JTAG_MCP_TCK")
	)
	(segment
		(start 428.610522 -125.169168)
		(end 428.610522 -123.749562)
		(width 0.089408)
		(layer "In11.Cu")
		(net "JTAG_MCP_TCK")
	)
	(segment
		(start 373.313452 -128.594358)
		(end 373.680228 -128.961134)
		(width 0.089408)
		(layer "In11.Cu")
		(net "JTAG_MCP_TCK")
	)
	(segment
		(start 136.127236 -92.947236)
		(end 136.6774 -93.4974)
		(width 0.089408)
		(layer "In11.Cu")
		(net "JTAG_MCP_TCK")
	)
	(segment
		(start 135.554974 -92.721938)
		(end 135.7884 -92.955364)
		(width 0.089408)
		(layer "In11.Cu")
		(net "JTAG_MCP_TCK")
	)
	(segment
		(start 301.399448 -107.944158)
		(end 297.551094 -104.095804)
		(width 0.089408)
		(layer "In11.Cu")
		(net "JTAG_MCP_TCK")
	)
	(segment
		(start 133.4516 -91.5162)
		(end 133.9596 -92.0242)
		(width 0.089408)
		(layer "In11.Cu")
		(net "JTAG_MCP_TCK")
	)
	(segment
		(start 382.252474 -132.032756)
		(end 383.050034 -132.830316)
		(width 0.089408)
		(layer "In11.Cu")
		(net "JTAG_MCP_TCK")
	)
	(segment
		(start 132.1562 -90.9574)
		(end 132.337556 -90.9574)
		(width 0.089408)
		(layer "In11.Cu")
		(net "JTAG_MCP_TCK")
	)
	(segment
		(start 131.7752 -90.5764)
		(end 132.1562 -90.9574)
		(width 0.089408)
		(layer "In11.Cu")
		(net "JTAG_MCP_TCK")
	)
	(segment
		(start 122.6312 -85.4456)
		(end 122.8344 -85.6488)
		(width 0.0889)
		(layer "In11.Cu")
		(net "JTAG_MCP_TCK")
	)
	(segment
		(start 400.11985 -136.482328)
		(end 400.862292 -135.739886)
		(width 0.089408)
		(layer "In11.Cu")
		(net "JTAG_MCP_TCK")
	)
	(segment
		(start 424.158156 -128.36652)
		(end 425.403518 -128.36652)
		(width 0.089408)
		(layer "In11.Cu")
		(net "JTAG_MCP_TCK")
	)
	(segment
		(start 128.032256 -88.4682)
		(end 128.061974 -88.497918)
		(width 0.089408)
		(layer "In11.Cu")
		(net "JTAG_MCP_TCK")
	)
	(segment
		(start 287.564576 -86.41334)
		(end 287.558226 -86.402672)
		(width 0.089408)
		(layer "In11.Cu")
		(net "JTAG_MCP_TCK")
	)
	(segment
		(start 320.08699 -125.915928)
		(end 320.00317 -125.999748)
		(width 0.089408)
		(layer "In11.Cu")
		(net "JTAG_MCP_TCK")
	)
	(segment
		(start 139.1158 -95.0468)
		(end 139.4968 -95.0468)
		(width 0.089408)
		(layer "In11.Cu")
		(net "JTAG_MCP_TCK")
	)
	(segment
		(start 141.5542 -100.066856)
		(end 142.652496 -101.165152)
		(width 0.089408)
		(layer "In11.Cu")
		(net "JTAG_MCP_TCK")
	)
	(segment
		(start 287.569402 -86.421976)
		(end 287.564576 -86.41334)
		(width 0.089408)
		(layer "In11.Cu")
		(net "JTAG_MCP_TCK")
	)
	(segment
		(start 367.358422 -123.996704)
		(end 371.956076 -128.594358)
		(width 0.089408)
		(layer "In11.Cu")
		(net "JTAG_MCP_TCK")
	)
	(segment
		(start 124.9172 -86.614)
		(end 125.5014 -87.1982)
		(width 0.089408)
		(layer "In11.Cu")
		(net "JTAG_MCP_TCK")
	)
	(segment
		(start 137.922 -94.1324)
		(end 138.3284 -94.5388)
		(width 0.089408)
		(layer "In11.Cu")
		(net "JTAG_MCP_TCK")
	)
	(segment
		(start 127.889 -88.4682)
		(end 128.032256 -88.4682)
		(width 0.089408)
		(layer "In11.Cu")
		(net "JTAG_MCP_TCK")
	)
	(segment
		(start 140.0048 -95.5548)
		(end 140.716 -95.5548)
		(width 0.089408)
		(layer "In11.Cu")
		(net "JTAG_MCP_TCK")
	)
	(segment
		(start 134.7724 -92.4052)
		(end 134.874762 -92.4052)
		(width 0.089408)
		(layer "In11.Cu")
		(net "JTAG_MCP_TCK")
	)
	(segment
		(start 321.43446 -125.915928)
		(end 320.08699 -125.915928)
		(width 0.089408)
		(layer "In11.Cu")
		(net "JTAG_MCP_TCK")
	)
	(segment
		(start 287.569402 -89.393776)
		(end 287.564576 -89.38514)
		(width 0.089408)
		(layer "In11.Cu")
		(net "JTAG_MCP_TCK")
	)
	(segment
		(start 135.260588 -92.460318)
		(end 135.29818 -92.42298)
		(width 0.089408)
		(layer "In11.Cu")
		(net "JTAG_MCP_TCK")
	)
	(segment
		(start 400.862292 -135.739886)
		(end 404.21179 -135.739886)
		(width 0.089408)
		(layer "In11.Cu")
		(net "JTAG_MCP_TCK")
	)
	(segment
		(start 388.926324 -136.482328)
		(end 400.11985 -136.482328)
		(width 0.089408)
		(layer "In11.Cu")
		(net "JTAG_MCP_TCK")
	)
	(segment
		(start 321.605148 -126.086616)
		(end 321.43446 -125.915928)
		(width 0.089408)
		(layer "In11.Cu")
		(net "JTAG_MCP_TCK")
	)
	(segment
		(start 123.087384 -82.555334)
		(end 123.063254 -82.555334)
		(width 0.0889)
		(layer "In11.Cu")
		(net "JTAG_MCP_TCK")
	)
	(segment
		(start 141.5542 -96.393)
		(end 141.5542 -100.066856)
		(width 0.089408)
		(layer "In11.Cu")
		(net "JTAG_MCP_TCK")
	)
	(segment
		(start 291.850826 -98.21545)
		(end 291.857176 -98.204782)
		(width 0.089408)
		(layer "In11.Cu")
		(net "JTAG_MCP_TCK")
	)
	(segment
		(start 366.651032 -120.431814)
		(end 367.258092 -121.038874)
		(width 0.089408)
		(layer "In11.Cu")
		(net "JTAG_MCP_TCK")
	)
	(segment
		(start 135.29818 -92.42298)
		(end 135.554974 -92.679774)
		(width 0.089408)
		(layer "In11.Cu")
		(net "JTAG_MCP_TCK")
	)
	(segment
		(start 134.92988 -92.460318)
		(end 135.260588 -92.460318)
		(width 0.089408)
		(layer "In11.Cu")
		(net "JTAG_MCP_TCK")
	)
	(segment
		(start 140.716 -95.5548)
		(end 141.5542 -96.393)
		(width 0.089408)
		(layer "In11.Cu")
		(net "JTAG_MCP_TCK")
	)
	(segment
		(start 132.35432 -90.974164)
		(end 132.477764 -90.974164)
		(width 0.089408)
		(layer "In11.Cu")
		(net "JTAG_MCP_TCK")
	)
	(segment
		(start 383.050034 -132.830316)
		(end 385.274312 -132.830316)
		(width 0.089408)
		(layer "In11.Cu")
		(net "JTAG_MCP_TCK")
	)
	(segment
		(start 127.508 -88.0872)
		(end 127.889 -88.4682)
		(width 0.089408)
		(layer "In11.Cu")
		(net "JTAG_MCP_TCK")
	)
	(segment
		(start 132.337556 -90.9574)
		(end 132.35432 -90.974164)
		(width 0.089408)
		(layer "In11.Cu")
		(net "JTAG_MCP_TCK")
	)
	(segment
		(start 133.9596 -92.0242)
		(end 134.3914 -92.0242)
		(width 0.089408)
		(layer "In11.Cu")
		(net "JTAG_MCP_TCK")
	)
	(segment
		(start 295.88714 -104.095804)
		(end 294.177212 -102.385876)
		(width 0.089408)
		(layer "In11.Cu")
		(net "JTAG_MCP_TCK")
	)
	(segment
		(start 378.260102 -130.187192)
		(end 380.105666 -132.032756)
		(width 0.089408)
		(layer "In11.Cu")
		(net "JTAG_MCP_TCK")
	)
	(segment
		(start 404.21179 -135.739886)
		(end 404.962868 -136.490964)
		(width 0.089408)
		(layer "In11.Cu")
		(net "JTAG_MCP_TCK")
	)
	(segment
		(start 288.43986 -82.325972)
		(end 288.93516 -81.659984)
		(width 0.089408)
		(layer "In11.Cu")
		(net "JTAG_MCP_TCK")
	)
	(segment
		(start 288.423096 -82.355182)
		(end 288.43986 -82.325972)
		(width 0.089408)
		(layer "In11.Cu")
		(net "JTAG_MCP_TCK")
	)
	(segment
		(start 291.857176 -97.214182)
		(end 291.862002 -97.205546)
		(width 0.089408)
		(layer "In11.Cu")
		(net "JTAG_MCP_TCK")
	)
	(segment
		(start 412.369508 -135.322564)
		(end 412.50743 -135.460486)
		(width 0.089408)
		(layer "In11.Cu")
		(net "JTAG_MCP_TCK")
	)
	(segment
		(start 414.994344 -135.460486)
		(end 415.334958 -135.119872)
		(width 0.089408)
		(layer "In11.Cu")
		(net "JTAG_MCP_TCK")
	)
	(segment
		(start 291.850826 -97.22485)
		(end 291.857176 -97.214182)
		(width 0.089408)
		(layer "In11.Cu")
		(net "JTAG_MCP_TCK")
	)
	(segment
		(start 297.551094 -104.095804)
		(end 295.88714 -104.095804)
		(width 0.089408)
		(layer "In11.Cu")
		(net "JTAG_MCP_TCK")
	)
	(segment
		(start 294.177212 -102.385876)
		(end 293.460932 -102.385876)
		(width 0.089408)
		(layer "In11.Cu")
		(net "JTAG_MCP_TCK")
	)
	(segment
		(start 415.334958 -135.119872)
		(end 417.404804 -135.119872)
		(width 0.089408)
		(layer "In11.Cu")
		(net "JTAG_MCP_TCK")
	)
	(segment
		(start 374.242076 -128.961134)
		(end 375.468134 -130.187192)
		(width 0.089408)
		(layer "In11.Cu")
		(net "JTAG_MCP_TCK")
	)
	(segment
		(start 287.564576 -84.43214)
		(end 287.558226 -84.421472)
		(width 0.089408)
		(layer "In11.Cu")
		(net "JTAG_MCP_TCK")
	)
	(segment
		(start 132.685028 -91.167204)
		(end 132.918454 -91.40063)
		(width 0.089408)
		(layer "In11.Cu")
		(net "JTAG_MCP_TCK")
	)
	(segment
		(start 162.074352 -118.337838)
		(end 166.730172 -118.337838)
		(width 0.089408)
		(layer "In11.Cu")
		(net "JTAG_MCP_TCK")
	)
	(segment
		(start 169.157904 -121.92508)
		(end 168.125394 -122.95759)
		(width 0.089408)
		(layer "In11.Cu")
		(net "JTAG_MCP_TCK")
	)
	(segment
		(start 287.564576 -89.38514)
		(end 287.558226 -89.374472)
		(width 0.089408)
		(layer "In11.Cu")
		(net "JTAG_MCP_TCK")
	)
	(segment
		(start 288.942272 -91.166188)
		(end 288.91103 -91.166188)
		(width 0.089408)
		(layer "In11.Cu")
		(net "JTAG_MCP_TCK")
	)
	(segment
		(start 168.125394 -124.277374)
		(end 170.2816 -126.43358)
		(width 0.089408)
		(layer "In11.Cu")
		(net "JTAG_MCP_TCK")
	)
	(segment
		(start 123.2916 -85.6488)
		(end 123.7234 -86.0806)
		(width 0.089408)
		(layer "In11.Cu")
		(net "JTAG_MCP_TCK")
	)
	(segment
		(start 287.569402 -88.403176)
		(end 287.564576 -88.39454)
		(width 0.089408)
		(layer "In11.Cu")
		(net "JTAG_MCP_TCK")
	)
	(segment
		(start 169.157904 -120.76557)
		(end 169.157904 -121.92508)
		(width 0.089408)
		(layer "In11.Cu")
		(net "JTAG_MCP_TCK")
	)
	(segment
		(start 291.857176 -98.204782)
		(end 291.862002 -98.196146)
		(width 0.089408)
		(layer "In11.Cu")
		(net "JTAG_MCP_TCK")
	)
	(segment
		(start 125.9586 -87.1982)
		(end 126.3142 -87.5538)
		(width 0.089408)
		(layer "In11.Cu")
		(net "JTAG_MCP_TCK")
	)
	(segment
		(start 170.2816 -126.43358)
		(end 170.2816 -127.0508)
		(width 0.089408)
		(layer "In11.Cu")
		(net "JTAG_MCP_TCK")
	)
	(segment
		(start 134.874762 -92.4052)
		(end 134.92988 -92.460318)
		(width 0.089408)
		(layer "In11.Cu")
		(net "JTAG_MCP_TCK")
	)
	(segment
		(start 291.850826 -95.24365)
		(end 291.857176 -95.232982)
		(width 0.089408)
		(layer "In11.Cu")
		(net "JTAG_MCP_TCK")
	)
	(segment
		(start 122.6312 -84.546186)
		(end 122.6312 -85.4456)
		(width 0.0889)
		(layer "In11.Cu")
		(net "JTAG_MCP_TCK")
	)
	(segment
		(start 287.564576 -83.44154)
		(end 287.558226 -83.430872)
		(width 0.089408)
		(layer "In11.Cu")
		(net "JTAG_MCP_TCK")
	)
	(segment
		(start 129.0066 -89.1286)
		(end 129.3368 -89.1286)
		(width 0.089408)
		(layer "In11.Cu")
		(net "JTAG_MCP_TCK")
	)
	(segment
		(start 290.659312 -92.156788)
		(end 290.62807 -92.156788)
		(width 0.089408)
		(layer "In11.Cu")
		(net "JTAG_MCP_TCK")
	)
	(segment
		(start 367.258092 -123.44654)
		(end 367.358422 -123.54687)
		(width 0.089408)
		(layer "In11.Cu")
		(net "JTAG_MCP_TCK")
	)
	(segment
		(start 409.746196 -135.322564)
		(end 412.369508 -135.322564)
		(width 0.089408)
		(layer "In11.Cu")
		(net "JTAG_MCP_TCK")
	)
	(segment
		(start 287.569402 -83.450176)
		(end 287.564576 -83.44154)
		(width 0.089408)
		(layer "In11.Cu")
		(net "JTAG_MCP_TCK")
	)
	(segment
		(start 136.6774 -93.4974)
		(end 136.9568 -93.4974)
		(width 0.089408)
		(layer "In11.Cu")
		(net "JTAG_MCP_TCK")
	)
	(segment
		(start 136.9568 -93.4974)
		(end 137.5918 -94.1324)
		(width 0.089408)
		(layer "In11.Cu")
		(net "JTAG_MCP_TCK")
	)
	(segment
		(start 122.53468 -83.38312)
		(end 122.589544 -83.49361)
		(width 0.0889)
		(layer "In11.Cu")
		(net "JTAG_MCP_TCK")
	)
	(segment
		(start 302.304958 -107.944158)
		(end 301.399448 -107.944158)
		(width 0.089408)
		(layer "In11.Cu")
		(net "JTAG_MCP_TCK")
	)
	(segment
		(start 128.061974 -88.497918)
		(end 128.375918 -88.497918)
		(width 0.089408)
		(layer "In11.Cu")
		(net "JTAG_MCP_TCK")
	)
	(segment
		(start 166.730172 -118.337838)
		(end 169.157904 -120.76557)
		(width 0.089408)
		(layer "In11.Cu")
		(net "JTAG_MCP_TCK")
	)
	(segment
		(start 126.5682 -87.5538)
		(end 127.1016 -88.0872)
		(width 0.089408)
		(layer "In11.Cu")
		(net "JTAG_MCP_TCK")
	)
	(segment
		(start 139.4968 -95.0468)
		(end 140.0048 -95.5548)
		(width 0.089408)
		(layer "In11.Cu")
		(net "JTAG_MCP_TCK")
	)
	(segment
		(start 291.850826 -99.20605)
		(end 291.857176 -99.195382)
		(width 0.089408)
		(layer "In11.Cu")
		(net "JTAG_MCP_TCK")
	)
	(segment
		(start 123.934728 -81.659984)
		(end 123.4948 -82.2198)
		(width 0.0889)
		(layer "In11.Cu")
		(net "JTAG_MCP_TCK")
	)
	(segment
		(start 154.69362 -111.124492)
		(end 154.861006 -111.124492)
		(width 0.089408)
		(layer "In11.Cu")
		(net "JTAG_MCP_TCK")
	)
	(segment
		(start 132.670804 -91.167204)
		(end 132.685028 -91.167204)
		(width 0.089408)
		(layer "In11.Cu")
		(net "JTAG_MCP_TCK")
	)
	(segment
		(start 154.861006 -111.124492)
		(end 162.074352 -118.337838)
		(width 0.089408)
		(layer "In11.Cu")
		(net "JTAG_MCP_TCK")
	)
	(segment
		(start 292.381432 -100.081842)
		(end 292.35273 -100.081842)
		(width 0.089408)
		(layer "In11.Cu")
		(net "JTAG_MCP_TCK")
	)
	(segment
		(start 404.962868 -136.490964)
		(end 407.037794 -136.490964)
		(width 0.089408)
		(layer "In11.Cu")
		(net "JTAG_MCP_TCK")
	)
	(segment
		(start 318.17564 -125.03912)
		(end 318.17564 -123.81484)
		(width 0.089408)
		(layer "In11.Cu")
		(net "JTAG_MCP_TCK")
	)
	(segment
		(start 168.125394 -122.95759)
		(end 168.125394 -124.277374)
		(width 0.089408)
		(layer "In11.Cu")
		(net "JTAG_MCP_TCK")
	)
	(segment
		(start 426.361098 -127.418592)
		(end 428.610522 -125.169168)
		(width 0.089408)
		(layer "In11.Cu")
		(net "JTAG_MCP_TCK")
	)
	(segment
		(start 319.136268 -125.999748)
		(end 318.17564 -125.03912)
		(width 0.089408)
		(layer "In11.Cu")
		(net "JTAG_MCP_TCK")
	)
	(segment
		(start 385.274312 -132.830316)
		(end 388.926324 -136.482328)
		(width 0.089408)
		(layer "In11.Cu")
		(net "JTAG_MCP_TCK")
	)
	(segment
		(start 291.850826 -93.26245)
		(end 291.857176 -93.251782)
		(width 0.089408)
		(layer "In11.Cu")
		(net "JTAG_MCP_TCK")
	)
	(segment
		(start 129.3368 -89.1286)
		(end 129.794 -89.5858)
		(width 0.089408)
		(layer "In11.Cu")
		(net "JTAG_MCP_TCK")
	)
	(segment
		(start 132.477764 -90.974164)
		(end 132.670804 -91.167204)
		(width 0.089408)
		(layer "In11.Cu")
		(net "JTAG_MCP_TCK")
	)
	(segment
		(start 130.5306 -89.9922)
		(end 130.8608 -89.9922)
		(width 0.089408)
		(layer "In11.Cu")
		(net "JTAG_MCP_TCK")
	)
	(segment
		(start 409.224734 -135.547354)
		(end 409.746196 -135.322564)
		(width 0.089408)
		(layer "In11.Cu")
		(net "JTAG_MCP_TCK")
	)
	(segment
		(start 426.351446 -127.418592)
		(end 426.361098 -127.418592)
		(width 0.089408)
		(layer "In11.Cu")
		(net "JTAG_MCP_TCK")
	)
	(segment
		(start 288.088832 -90.671142)
		(end 288.056066 -90.671142)
		(width 0.089408)
		(layer "In11.Cu")
		(net "JTAG_MCP_TCK")
	)
	(segment
		(start 287.564576 -87.40394)
		(end 287.558226 -87.393272)
		(width 0.089408)
		(layer "In11.Cu")
		(net "JTAG_MCP_TCK")
	)
	(segment
		(start 407.037794 -136.490964)
		(end 409.224734 -135.547354)
		(width 0.089408)
		(layer "In11.Cu")
		(net "JTAG_MCP_TCK")
	)
	(segment
		(start 367.258092 -121.038874)
		(end 367.258092 -123.44654)
		(width 0.089408)
		(layer "In11.Cu")
		(net "JTAG_MCP_TCK")
	)
	(segment
		(start 130.1242 -89.5858)
		(end 130.5306 -89.9922)
		(width 0.089408)
		(layer "In11.Cu")
		(net "JTAG_MCP_TCK")
	)
	(segment
		(start 135.554974 -92.679774)
		(end 135.554974 -92.721938)
		(width 0.089408)
		(layer "In11.Cu")
		(net "JTAG_MCP_TCK")
	)
	(segment
		(start 122.558048 -84.421218)
		(end 122.6312 -84.546186)
		(width 0.0889)
		(layer "In11.Cu")
		(net "JTAG_MCP_TCK")
	)
	(segment
		(start 170.2816 -127.0508)
		(end 170.561 -127.3302)
		(width 0.089408)
		(layer "In11.Cu")
		(net "JTAG_MCP_TCK")
	)
	(segment
		(start 320.00317 -125.999748)
		(end 319.136268 -125.999748)
		(width 0.089408)
		(layer "In11.Cu")
		(net "JTAG_MCP_TCK")
	)
	(segment
		(start 287.569402 -85.431376)
		(end 287.564576 -85.42274)
		(width 0.089408)
		(layer "In11.Cu")
		(net "JTAG_MCP_TCK")
	)
	(segment
		(start 134.3914 -92.0242)
		(end 134.7724 -92.4052)
		(width 0.089408)
		(layer "In11.Cu")
		(net "JTAG_MCP_TCK")
	)
	(segment
		(start 136.119108 -92.955364)
		(end 136.127236 -92.947236)
		(width 0.089408)
		(layer "In11.Cu")
		(net "JTAG_MCP_TCK")
	)
	(segment
		(start 126.3142 -87.5538)
		(end 126.5682 -87.5538)
		(width 0.089408)
		(layer "In11.Cu")
		(net "JTAG_MCP_TCK")
	)
	(segment
		(start 380.105666 -132.032756)
		(end 382.252474 -132.032756)
		(width 0.089408)
		(layer "In11.Cu")
		(net "JTAG_MCP_TCK")
	)
	(segment
		(start 287.569402 -87.412576)
		(end 287.564576 -87.40394)
		(width 0.089408)
		(layer "In11.Cu")
		(net "JTAG_MCP_TCK")
	)
	(segment
		(start 129.794 -89.5858)
		(end 130.1242 -89.5858)
		(width 0.089408)
		(layer "In11.Cu")
		(net "JTAG_MCP_TCK")
	)
	(segment
		(start 291.850826 -96.23425)
		(end 291.857176 -96.223582)
		(width 0.089408)
		(layer "In11.Cu")
		(net "JTAG_MCP_TCK")
	)
	(segment
		(start 142.652496 -101.165152)
		(end 144.73428 -101.165152)
		(width 0.089408)
		(layer "In11.Cu")
		(net "JTAG_MCP_TCK")
	)
	(segment
		(start 123.7234 -86.0806)
		(end 124.0282 -86.0806)
		(width 0.089408)
		(layer "In11.Cu")
		(net "JTAG_MCP_TCK")
	)
	(segment
		(start 137.5918 -94.1324)
		(end 137.922 -94.1324)
		(width 0.089408)
		(layer "In11.Cu")
		(net "JTAG_MCP_TCK")
	)
	(segment
		(start 288.06013 -82.55508)
		(end 288.088832 -82.55508)
		(width 0.089408)
		(layer "In11.Cu")
		(net "JTAG_MCP_TCK")
	)
	(segment
		(start 318.17564 -123.81484)
		(end 302.304958 -107.944158)
		(width 0.089408)
		(layer "In11.Cu")
		(net "JTAG_MCP_TCK")
	)
	(segment
		(start 425.403518 -128.36652)
		(end 426.351446 -127.418592)
		(width 0.089408)
		(layer "In11.Cu")
		(net "JTAG_MCP_TCK")
	)
	(segment
		(start 291.857176 -96.223582)
		(end 291.862002 -96.214946)
		(width 0.089408)
		(layer "In11.Cu")
		(net "JTAG_MCP_TCK")
	)
	(segment
		(start 127.1016 -88.0872)
		(end 127.508 -88.0872)
		(width 0.089408)
		(layer "In11.Cu")
		(net "JTAG_MCP_TCK")
	)
	(segment
		(start 123.4948 -82.2198)
		(end 123.422918 -82.355182)
		(width 0.0889)
		(layer "In11.Cu")
		(net "JTAG_MCP_TCK")
	)
	(segment
		(start 135.7884 -92.955364)
		(end 136.119108 -92.955364)
		(width 0.089408)
		(layer "In11.Cu")
		(net "JTAG_MCP_TCK")
	)
	(segment
		(start 291.857176 -99.195382)
		(end 291.862002 -99.186746)
		(width 0.089408)
		(layer "In11.Cu")
		(net "JTAG_MCP_TCK")
	)
	(segment
		(start 287.569402 -84.440776)
		(end 287.564576 -84.43214)
		(width 0.089408)
		(layer "In11.Cu")
		(net "JTAG_MCP_TCK")
	)
	(segment
		(start 417.404804 -135.119872)
		(end 424.158156 -128.36652)
		(width 0.089408)
		(layer "In11.Cu")
		(net "JTAG_MCP_TCK")
	)
	(segment
		(start 132.918454 -91.414854)
		(end 133.0198 -91.5162)
		(width 0.089408)
		(layer "In11.Cu")
		(net "JTAG_MCP_TCK")
	)
	(segment
		(start 132.918454 -91.40063)
		(end 132.918454 -91.414854)
		(width 0.089408)
		(layer "In11.Cu")
		(net "JTAG_MCP_TCK")
	)
	(segment
		(start 291.857176 -93.251782)
		(end 291.862002 -93.243146)
		(width 0.089408)
		(layer "In11.Cu")
		(net "JTAG_MCP_TCK")
	)
	(segment
		(start 293.306246 -102.23119)
		(end 293.306246 -101.949504)
		(width 0.089408)
		(layer "In11.Cu")
		(net "JTAG_MCP_TCK")
	)
	(segment
		(start 344.033348 -120.431814)
		(end 366.651032 -120.431814)
		(width 0.089408)
		(layer "In11.Cu")
		(net "JTAG_MCP_TCK")
	)
	(segment
		(start 287.564576 -88.39454)
		(end 287.558226 -88.383872)
		(width 0.089408)
		(layer "In11.Cu")
		(net "JTAG_MCP_TCK")
	)
	(segment
		(start 289.805872 -91.661742)
		(end 289.773106 -91.661742)
		(width 0.089408)
		(layer "In11.Cu")
		(net "JTAG_MCP_TCK")
	)
	(segment
		(start 138.3284 -94.5388)
		(end 138.6078 -94.5388)
		(width 0.089408)
		(layer "In11.Cu")
		(net "JTAG_MCP_TCK")
	)
	(segment
		(start 138.6078 -94.5388)
		(end 139.1158 -95.0468)
		(width 0.089408)
		(layer "In11.Cu")
		(net "JTAG_MCP_TCK")
	)
	(segment
		(start 373.680228 -128.961134)
		(end 374.242076 -128.961134)
		(width 0.089408)
		(layer "In11.Cu")
		(net "JTAG_MCP_TCK")
	)
	(segment
		(start 291.862002 -94.842076)
		(end 291.857176 -94.83344)
		(width 0.089408)
		(layer "In11.Cu")
		(net "JTAG_MCP_TCK")
	)
	(segment
		(start 292.715696 -100.681282)
		(end 292.720522 -100.672646)
		(width 0.089408)
		(layer "In11.Cu")
		(net "JTAG_MCP_TCK")
	)
	(segment
		(start 131.445 -90.5764)
		(end 131.7752 -90.5764)
		(width 0.089408)
		(layer "In11.Cu")
		(net "JTAG_MCP_TCK")
	)
	(segment
		(start 125.5014 -87.1982)
		(end 125.9586 -87.1982)
		(width 0.089408)
		(layer "In11.Cu")
		(net "JTAG_MCP_TCK")
	)
	(segment
		(start 291.522912 -92.652342)
		(end 291.490146 -92.652342)
		(width 0.089408)
		(layer "In11.Cu")
		(net "JTAG_MCP_TCK")
	)
	(arc
		(start 123.063254 -82.555334)
		(mid 122.578111 -82.828149)
		(end 122.53468 -83.38312)
		(width 0.0889)
		(layer "In11.Cu")
		(net "JTAG_MCP_TCK")
	)
	(arc
		(start 122.589544 -83.49361)
		(mid 122.616787 -83.670349)
		(end 122.564398 -83.841336)
		(width 0.0889)
		(layer "In11.Cu")
		(net "JTAG_MCP_TCK")
	)
	(arc
		(start 291.857176 -95.232982)
		(mid 291.910553 -95.038173)
		(end 291.862002 -94.842076)
		(width 0.089408)
		(layer "In11.Cu")
		(net "JTAG_MCP_TCK")
	)
	(arc
		(start 293.306246 -101.949504)
		(mid 293.190976 -101.740116)
		(end 293.012876 -101.580696)
		(width 0.089408)
		(layer "In11.Cu")
		(net "JTAG_MCP_TCK")
	)
	(arc
		(start 287.558226 -86.402672)
		(mid 287.485337 -86.111655)
		(end 287.564576 -85.822282)
		(width 0.089408)
		(layer "In11.Cu")
		(net "JTAG_MCP_TCK")
	)
	(arc
		(start 291.862002 -97.205546)
		(mid 291.910666 -97.009448)
		(end 291.857176 -96.81464)
		(width 0.089408)
		(layer "In11.Cu")
		(net "JTAG_MCP_TCK")
	)
	(arc
		(start 291.857176 -94.83344)
		(mid 291.778079 -94.538038)
		(end 291.857176 -94.242636)
		(width 0.089408)
		(layer "In11.Cu")
		(net "JTAG_MCP_TCK")
	)
	(arc
		(start 287.564576 -87.803482)
		(mid 287.617953 -87.608673)
		(end 287.569402 -87.412576)
		(width 0.089408)
		(layer "In11.Cu")
		(net "JTAG_MCP_TCK")
	)
	(arc
		(start 287.558226 -88.383872)
		(mid 287.485337 -88.092855)
		(end 287.564576 -87.803482)
		(width 0.089408)
		(layer "In11.Cu")
		(net "JTAG_MCP_TCK")
	)
	(arc
		(start 287.564576 -89.784682)
		(mid 287.617953 -89.589873)
		(end 287.569402 -89.393776)
		(width 0.089408)
		(layer "In11.Cu")
		(net "JTAG_MCP_TCK")
	)
	(arc
		(start 288.423096 -90.87104)
		(mid 288.281939 -90.727655)
		(end 288.088832 -90.671142)
		(width 0.089408)
		(layer "In11.Cu")
		(net "JTAG_MCP_TCK")
	)
	(arc
		(start 293.012876 -101.580696)
		(mid 292.845452 -101.444533)
		(end 292.715696 -101.272086)
		(width 0.089408)
		(layer "In11.Cu")
		(net "JTAG_MCP_TCK")
	)
	(arc
		(start 292.715696 -101.272086)
		(mid 292.636599 -100.976684)
		(end 292.715696 -100.681282)
		(width 0.089408)
		(layer "In11.Cu")
		(net "JTAG_MCP_TCK")
	)
	(arc
		(start 287.558226 -87.393272)
		(mid 287.485337 -87.102255)
		(end 287.564576 -86.812882)
		(width 0.089408)
		(layer "In11.Cu")
		(net "JTAG_MCP_TCK")
	)
	(arc
		(start 288.056066 -90.671142)
		(mid 287.559609 -90.366958)
		(end 287.564576 -89.784682)
		(width 0.089408)
		(layer "In11.Cu")
		(net "JTAG_MCP_TCK")
	)
	(arc
		(start 287.564576 -88.794082)
		(mid 287.617953 -88.599273)
		(end 287.569402 -88.403176)
		(width 0.089408)
		(layer "In11.Cu")
		(net "JTAG_MCP_TCK")
	)
	(arc
		(start 292.35273 -100.081842)
		(mid 291.856198 -99.78474)
		(end 291.850826 -99.20605)
		(width 0.089408)
		(layer "In11.Cu")
		(net "JTAG_MCP_TCK")
	)
	(arc
		(start 289.773106 -91.661742)
		(mid 289.489145 -91.577624)
		(end 289.281616 -91.36634)
		(width 0.089408)
		(layer "In11.Cu")
		(net "JTAG_MCP_TCK")
	)
	(arc
		(start 287.564576 -86.812882)
		(mid 287.617953 -86.618073)
		(end 287.569402 -86.421976)
		(width 0.089408)
		(layer "In11.Cu")
		(net "JTAG_MCP_TCK")
	)
	(arc
		(start 291.857176 -93.84284)
		(mid 291.777861 -93.553468)
		(end 291.850826 -93.26245)
		(width 0.089408)
		(layer "In11.Cu")
		(net "JTAG_MCP_TCK")
	)
	(arc
		(start 123.422918 -82.355182)
		(mid 123.281235 -82.498986)
		(end 123.087384 -82.555334)
		(width 0.0889)
		(layer "In11.Cu")
		(net "JTAG_MCP_TCK")
	)
	(arc
		(start 288.91103 -91.166188)
		(mid 288.629128 -91.081325)
		(end 288.423096 -90.87104)
		(width 0.089408)
		(layer "In11.Cu")
		(net "JTAG_MCP_TCK")
	)
	(arc
		(start 291.857176 -95.82404)
		(mid 291.777861 -95.534668)
		(end 291.850826 -95.24365)
		(width 0.089408)
		(layer "In11.Cu")
		(net "JTAG_MCP_TCK")
	)
	(arc
		(start 291.490146 -92.652342)
		(mid 291.206185 -92.568224)
		(end 290.998656 -92.35694)
		(width 0.089408)
		(layer "In11.Cu")
		(net "JTAG_MCP_TCK")
	)
	(arc
		(start 291.862002 -96.214946)
		(mid 291.910666 -96.018848)
		(end 291.857176 -95.82404)
		(width 0.089408)
		(layer "In11.Cu")
		(net "JTAG_MCP_TCK")
	)
	(arc
		(start 291.857176 -98.79584)
		(mid 291.777861 -98.506468)
		(end 291.850826 -98.21545)
		(width 0.089408)
		(layer "In11.Cu")
		(net "JTAG_MCP_TCK")
	)
	(arc
		(start 287.558226 -83.430872)
		(mid 287.563448 -82.852096)
		(end 288.06013 -82.55508)
		(width 0.089408)
		(layer "In11.Cu")
		(net "JTAG_MCP_TCK")
	)
	(arc
		(start 291.862002 -99.186746)
		(mid 291.910666 -98.990648)
		(end 291.857176 -98.79584)
		(width 0.089408)
		(layer "In11.Cu")
		(net "JTAG_MCP_TCK")
	)
	(arc
		(start 288.088832 -82.55508)
		(mid 288.281935 -82.498561)
		(end 288.423096 -82.355182)
		(width 0.089408)
		(layer "In11.Cu")
		(net "JTAG_MCP_TCK")
	)
	(arc
		(start 290.62807 -92.156788)
		(mid 290.346168 -92.071925)
		(end 290.140136 -91.86164)
		(width 0.089408)
		(layer "In11.Cu")
		(net "JTAG_MCP_TCK")
	)
	(arc
		(start 292.720522 -100.672646)
		(mid 292.716014 -100.282563)
		(end 292.381432 -100.081842)
		(width 0.089408)
		(layer "In11.Cu")
		(net "JTAG_MCP_TCK")
	)
	(arc
		(start 287.558226 -84.421472)
		(mid 287.485337 -84.130455)
		(end 287.564576 -83.841082)
		(width 0.089408)
		(layer "In11.Cu")
		(net "JTAG_MCP_TCK")
	)
	(arc
		(start 289.281616 -91.36634)
		(mid 289.138305 -91.221569)
		(end 288.942272 -91.166188)
		(width 0.089408)
		(layer "In11.Cu")
		(net "JTAG_MCP_TCK")
	)
	(arc
		(start 287.558226 -85.412072)
		(mid 287.485337 -85.121055)
		(end 287.564576 -84.831682)
		(width 0.089408)
		(layer "In11.Cu")
		(net "JTAG_MCP_TCK")
	)
	(arc
		(start 287.564576 -85.822282)
		(mid 287.617953 -85.627473)
		(end 287.569402 -85.431376)
		(width 0.089408)
		(layer "In11.Cu")
		(net "JTAG_MCP_TCK")
	)
	(arc
		(start 291.857176 -97.80524)
		(mid 291.777861 -97.515868)
		(end 291.850826 -97.22485)
		(width 0.089408)
		(layer "In11.Cu")
		(net "JTAG_MCP_TCK")
	)
	(arc
		(start 287.558226 -89.374472)
		(mid 287.485337 -89.083455)
		(end 287.564576 -88.794082)
		(width 0.089408)
		(layer "In11.Cu")
		(net "JTAG_MCP_TCK")
	)
	(arc
		(start 287.564576 -83.841082)
		(mid 287.617953 -83.646273)
		(end 287.569402 -83.450176)
		(width 0.089408)
		(layer "In11.Cu")
		(net "JTAG_MCP_TCK")
	)
	(arc
		(start 291.857176 -94.242636)
		(mid 291.910709 -94.042738)
		(end 291.857176 -93.84284)
		(width 0.089408)
		(layer "In11.Cu")
		(net "JTAG_MCP_TCK")
	)
	(arc
		(start 290.140136 -91.86164)
		(mid 289.998979 -91.718255)
		(end 289.805872 -91.661742)
		(width 0.089408)
		(layer "In11.Cu")
		(net "JTAG_MCP_TCK")
	)
	(arc
		(start 291.862002 -93.243146)
		(mid 291.857494 -92.853063)
		(end 291.522912 -92.652342)
		(width 0.089408)
		(layer "In11.Cu")
		(net "JTAG_MCP_TCK")
	)
	(arc
		(start 291.857176 -96.81464)
		(mid 291.777861 -96.525268)
		(end 291.850826 -96.23425)
		(width 0.089408)
		(layer "In11.Cu")
		(net "JTAG_MCP_TCK")
	)
	(arc
		(start 291.862002 -98.196146)
		(mid 291.910666 -98.000048)
		(end 291.857176 -97.80524)
		(width 0.089408)
		(layer "In11.Cu")
		(net "JTAG_MCP_TCK")
	)
	(arc
		(start 122.564398 -83.841336)
		(mid 122.485176 -84.130454)
		(end 122.558048 -84.421218)
		(width 0.0889)
		(layer "In11.Cu")
		(net "JTAG_MCP_TCK")
	)
	(arc
		(start 290.998656 -92.35694)
		(mid 290.855345 -92.212169)
		(end 290.659312 -92.156788)
		(width 0.089408)
		(layer "In11.Cu")
		(net "JTAG_MCP_TCK")
	)
	(arc
		(start 287.564576 -84.831682)
		(mid 287.617953 -84.636873)
		(end 287.569402 -84.440776)
		(width 0.089408)
		(layer "In11.Cu")
		(net "JTAG_MCP_TCK")
	)
	(segment
		(start 468.062056 -134.146544)
		(end 468.6046 -133.604)
		(width 0.10795)
		(layer "F.Cu")
		(net "JTAG_MCP_MUX_TDO")
	)
	(segment
		(start 467.82609 -133.910578)
		(end 468.062056 -134.146544)
		(width 0.10795)
		(layer "F.Cu")
		(net "JTAG_MCP_MUX_TDO")
	)
	(segment
		(start 467.36 -133.604)
		(end 467.689946 -133.604)
		(width 0.10795)
		(layer "F.Cu")
		(net "JTAG_MCP_MUX_TDO")
	)
	(segment
		(start 468.6046 -132.4864)
		(end 468.724996 -132.366004)
		(width 0.10795)
		(layer "F.Cu")
		(net "JTAG_MCP_MUX_TDO")
	)
	(segment
		(start 467.689946 -133.604)
		(end 467.82609 -133.740144)
		(width 0.10795)
		(layer "F.Cu")
		(net "JTAG_MCP_MUX_TDO")
	)
	(segment
		(start 467.82609 -133.740144)
		(end 467.82609 -133.910578)
		(width 0.10795)
		(layer "F.Cu")
		(net "JTAG_MCP_MUX_TDO")
	)
	(segment
		(start 468.724996 -132.366004)
		(end 470.282016 -132.366004)
		(width 0.10795)
		(layer "F.Cu")
		(net "JTAG_MCP_MUX_TDO")
	)
	(segment
		(start 468.6046 -133.604)
		(end 468.6046 -132.4864)
		(width 0.10795)
		(layer "F.Cu")
		(net "JTAG_MCP_MUX_TDO")
	)
	(via
		(at 468.062056 -134.146544)
		(size 0.508)
		(drill 0.254)
		(layers "F.Cu" "B.Cu")
		(net "JTAG_MCP_MUX_TDO")
	)
	(via
		(at 496.9002 -131.0386)
		(size 0.508)
		(drill 0.254)
		(layers "F.Cu" "B.Cu")
		(net "JTAG_MCP_MUX_TDO")
	)
	(via
		(at 497.6622 -133.477)
		(size 0.6604)
		(drill 0.3302)
		(layers "F.Cu" "B.Cu")
		(net "JTAG_MCP_MUX_TDO")
	)
	(segment
		(start 496.5192 -131.0386)
		(end 496.9002 -131.0386)
		(width 0.10795)
		(layer "B.Cu")
		(net "JTAG_MCP_MUX_TDO")
	)
	(segment
		(start 496.315492 -131.8895)
		(end 496.315492 -131.242308)
		(width 0.10795)
		(layer "B.Cu")
		(net "JTAG_MCP_MUX_TDO")
	)
	(segment
		(start 497.6622 -133.477)
		(end 496.9764 -132.7912)
		(width 0.10795)
		(layer "B.Cu")
		(net "JTAG_MCP_MUX_TDO")
	)
	(segment
		(start 496.594892 -132.7912)
		(end 496.315492 -132.5118)
		(width 0.10795)
		(layer "B.Cu")
		(net "JTAG_MCP_MUX_TDO")
	)
	(segment
		(start 496.9764 -132.7912)
		(end 496.594892 -132.7912)
		(width 0.10795)
		(layer "B.Cu")
		(net "JTAG_MCP_MUX_TDO")
	)
	(segment
		(start 496.315492 -132.5118)
		(end 496.315492 -131.8895)
		(width 0.10795)
		(layer "B.Cu")
		(net "JTAG_MCP_MUX_TDO")
	)
	(segment
		(start 496.315492 -131.242308)
		(end 496.5192 -131.0386)
		(width 0.10795)
		(layer "B.Cu")
		(net "JTAG_MCP_MUX_TDO")
	)
	(segment
		(start 468.062056 -134.146544)
		(end 468.766144 -134.146544)
		(width 0.089408)
		(layer "In9.Cu")
		(net "JTAG_MCP_MUX_TDO")
	)
	(segment
		(start 490.103668 -133.311646)
		(end 494.627154 -133.311646)
		(width 0.089408)
		(layer "In9.Cu")
		(net "JTAG_MCP_MUX_TDO")
	)
	(segment
		(start 469.1888 -134.5692)
		(end 475.5388 -134.5692)
		(width 0.089408)
		(layer "In9.Cu")
		(net "JTAG_MCP_MUX_TDO")
	)
	(segment
		(start 486.6005 -134.2517)
		(end 489.163614 -134.2517)
		(width 0.089408)
		(layer "In9.Cu")
		(net "JTAG_MCP_MUX_TDO")
	)
	(segment
		(start 489.163614 -134.2517)
		(end 490.103668 -133.311646)
		(width 0.089408)
		(layer "In9.Cu")
		(net "JTAG_MCP_MUX_TDO")
	)
	(segment
		(start 494.627154 -133.311646)
		(end 496.9002 -131.0386)
		(width 0.089408)
		(layer "In9.Cu")
		(net "JTAG_MCP_MUX_TDO")
	)
	(segment
		(start 484.37292 -136.47928)
		(end 486.6005 -134.2517)
		(width 0.089408)
		(layer "In9.Cu")
		(net "JTAG_MCP_MUX_TDO")
	)
	(segment
		(start 475.5388 -134.5692)
		(end 477.44888 -136.47928)
		(width 0.089408)
		(layer "In9.Cu")
		(net "JTAG_MCP_MUX_TDO")
	)
	(segment
		(start 468.766144 -134.146544)
		(end 469.1888 -134.5692)
		(width 0.089408)
		(layer "In9.Cu")
		(net "JTAG_MCP_MUX_TDO")
	)
	(segment
		(start 477.44888 -136.47928)
		(end 484.37292 -136.47928)
		(width 0.089408)
		(layer "In9.Cu")
		(net "JTAG_MCP_MUX_TDO")
	)
	(segment
		(start 471.930984 -126.366016)
		(end 472.44 -125.857)
		(width 0.10795)
		(layer "F.Cu")
		(net "JTAG_MCP_MUX_TDI")
	)
	(segment
		(start 470.282016 -126.366016)
		(end 471.930984 -126.366016)
		(width 0.10795)
		(layer "F.Cu")
		(net "JTAG_MCP_MUX_TDI")
	)
	(via
		(at 469.5952 -140.0556)
		(size 0.508)
		(drill 0.254)
		(layers "F.Cu" "B.Cu")
		(net "JTAG_MCP_MUX_TDI")
	)
	(via
		(at 472.44 -125.857)
		(size 0.508)
		(drill 0.254)
		(layers "F.Cu" "B.Cu")
		(net "JTAG_MCP_MUX_TDI")
	)
	(via
		(at 470.3064 -140.0556)
		(size 0.6604)
		(drill 0.3302)
		(layers "F.Cu" "B.Cu")
		(net "JTAG_MCP_MUX_TDI")
	)
	(via
		(at 447.72961 -132.35559)
		(size 0.508)
		(drill 0.254)
		(layers "F.Cu" "B.Cu")
		(net "JTAG_MCP_MUX_TDI")
	)
	(segment
		(start 447.72961 -132.35559)
		(end 448.31 -131.7752)
		(width 0.10795)
		(layer "B.Cu")
		(net "JTAG_MCP_MUX_TDI")
	)
	(segment
		(start 447.527172 -130.027172)
		(end 447.7258 -130.2258)
		(width 0.10795)
		(layer "B.Cu")
		(net "JTAG_MCP_MUX_TDI")
	)
	(segment
		(start 447.0146 -130.027172)
		(end 447.527172 -130.027172)
		(width 0.10795)
		(layer "B.Cu")
		(net "JTAG_MCP_MUX_TDI")
	)
	(segment
		(start 448.31 -131.7752)
		(end 448.31 -131.318)
		(width 0.10795)
		(layer "B.Cu")
		(net "JTAG_MCP_MUX_TDI")
	)
	(segment
		(start 447.7258 -130.9878)
		(end 448.056 -131.318)
		(width 0.10795)
		(layer "B.Cu")
		(net "JTAG_MCP_MUX_TDI")
	)
	(segment
		(start 447.7258 -130.2258)
		(end 447.7258 -130.9878)
		(width 0.10795)
		(layer "B.Cu")
		(net "JTAG_MCP_MUX_TDI")
	)
	(segment
		(start 469.5952 -140.0556)
		(end 470.3064 -140.0556)
		(width 0.10795)
		(layer "B.Cu")
		(net "JTAG_MCP_MUX_TDI")
	)
	(segment
		(start 448.056 -131.318)
		(end 448.31 -131.318)
		(width 0.10795)
		(layer "B.Cu")
		(net "JTAG_MCP_MUX_TDI")
	)
	(segment
		(start 467.442296 -137.902696)
		(end 469.5952 -140.0556)
		(width 0.089408)
		(layer "In2.Cu")
		(net "JTAG_MCP_MUX_TDI")
	)
	(segment
		(start 456.938634 -137.902696)
		(end 467.442296 -137.902696)
		(width 0.089408)
		(layer "In2.Cu")
		(net "JTAG_MCP_MUX_TDI")
	)
	(segment
		(start 448.502024 -131.481576)
		(end 450.517514 -131.481576)
		(width 0.089408)
		(layer "In2.Cu")
		(net "JTAG_MCP_MUX_TDI")
	)
	(segment
		(start 447.72961 -132.25399)
		(end 448.502024 -131.481576)
		(width 0.089408)
		(layer "In2.Cu")
		(net "JTAG_MCP_MUX_TDI")
	)
	(segment
		(start 447.72961 -132.35559)
		(end 447.72961 -132.25399)
		(width 0.089408)
		(layer "In2.Cu")
		(net "JTAG_MCP_MUX_TDI")
	)
	(segment
		(start 450.517514 -131.481576)
		(end 456.938634 -137.902696)
		(width 0.089408)
		(layer "In2.Cu")
		(net "JTAG_MCP_MUX_TDI")
	)
	(segment
		(start 470.020904 -139.629896)
		(end 469.5952 -140.0556)
		(width 0.089408)
		(layer "In4.Cu")
		(net "JTAG_MCP_MUX_TDI")
	)
	(segment
		(start 471.5764 -125.857)
		(end 470.020904 -127.412496)
		(width 0.089408)
		(layer "In4.Cu")
		(net "JTAG_MCP_MUX_TDI")
	)
	(segment
		(start 470.020904 -127.412496)
		(end 470.020904 -139.629896)
		(width 0.089408)
		(layer "In4.Cu")
		(net "JTAG_MCP_MUX_TDI")
	)
	(segment
		(start 472.44 -125.857)
		(end 471.5764 -125.857)
		(width 0.089408)
		(layer "In4.Cu")
		(net "JTAG_MCP_MUX_TDI")
	)
	(via
		(at 169.9641 -124.3203)
		(size 0.6604)
		(drill 0.3302)
		(layers "F.Cu" "B.Cu")
		(net "JTAG_MCP_CPU1_TDI_R")
	)
	(segment
		(start 169.418 -126.0348)
		(end 169.701972 -126.318772)
		(width 0.10795)
		(layer "B.Cu")
		(net "JTAG_MCP_CPU1_TDI_R")
	)
	(segment
		(start 169.701972 -126.318772)
		(end 169.701972 -127.127)
		(width 0.10795)
		(layer "B.Cu")
		(net "JTAG_MCP_CPU1_TDI_R")
	)
	(segment
		(start 169.418 -125.603)
		(end 169.418 -126.0348)
		(width 0.10795)
		(layer "B.Cu")
		(net "JTAG_MCP_CPU1_TDI_R")
	)
	(segment
		(start 169.418 -124.8664)
		(end 169.418 -125.603)
		(width 0.10795)
		(layer "B.Cu")
		(net "JTAG_MCP_CPU1_TDI_R")
	)
	(segment
		(start 169.710608 -127.127)
		(end 169.701972 -127.127)
		(width 0.10795)
		(layer "B.Cu")
		(net "JTAG_MCP_CPU1_TDI_R")
	)
	(segment
		(start 168.656 -125.603)
		(end 169.418 -125.603)
		(width 0.10795)
		(layer "B.Cu")
		(net "JTAG_MCP_CPU1_TDI_R")
	)
	(segment
		(start 169.9641 -124.3203)
		(end 169.418 -124.8664)
		(width 0.10795)
		(layer "B.Cu")
		(net "JTAG_MCP_CPU1_TDI_R")
	)
	(segment
		(start 171.059856 -127.961136)
		(end 170.544744 -127.961136)
		(width 0.10795)
		(layer "B.Cu")
		(net "JTAG_MCP_CPU1_TDI_R")
	)
	(segment
		(start 170.544744 -127.961136)
		(end 169.710608 -127.127)
		(width 0.10795)
		(layer "B.Cu")
		(net "JTAG_MCP_CPU1_TDI_R")
	)
	(segment
		(start 125.080268 -80.669384)
		(end 125.651768 -80.669384)
		(width 0.1016)
		(layer "F.Cu")
		(net "JTAG_MCP_CPU1_TDI")
	)
	(via
		(at 402.58238 -119.98198)
		(size 0.508)
		(drill 0.254)
		(layers "F.Cu" "B.Cu")
		(net "JTAG_MCP_CPU1_TDI")
	)
	(via
		(at 172.478446 -127.951484)
		(size 0.508)
		(drill 0.254)
		(layers "F.Cu" "B.Cu")
		(net "JTAG_MCP_CPU1_TDI")
	)
	(via
		(at 467.5378 -143.2052)
		(size 0.508)
		(drill 0.254)
		(layers "F.Cu" "B.Cu")
		(net "JTAG_MCP_CPU1_TDI")
	)
	(via
		(at 125.651768 -80.669384)
		(size 0.508)
		(drill 0.254)
		(layers "F.Cu" "B.Cu")
		(net "JTAG_MCP_CPU1_TDI")
	)
	(via
		(at 461.4672 -133.5278)
		(size 0.508)
		(drill 0.254)
		(layers "F.Cu" "B.Cu")
		(net "JTAG_MCP_CPU1_TDI")
	)
	(via
		(at 431.381916 -123.665742)
		(size 0.508)
		(drill 0.254)
		(layers "F.Cu" "B.Cu")
		(net "JTAG_MCP_CPU1_TDI")
	)
	(via
		(at 444.7032 -131.0894)
		(size 0.508)
		(drill 0.254)
		(layers "F.Cu" "B.Cu")
		(net "JTAG_MCP_CPU1_TDI")
	)
	(via
		(at 497.459 -135.89)
		(size 0.508)
		(drill 0.254)
		(layers "F.Cu" "B.Cu")
		(net "JTAG_MCP_CPU1_TDI")
	)
	(via
		(at 369.97386 -124.199904)
		(size 0.508)
		(drill 0.254)
		(layers "F.Cu" "B.Cu")
		(net "JTAG_MCP_CPU1_TDI")
	)
	(via
		(at 498.927374 -133.364478)
		(size 0.6604)
		(drill 0.3302)
		(layers "F.Cu" "B.Cu")
		(net "JTAG_MCP_CPU1_TDI")
	)
	(segment
		(start 498.927374 -133.364478)
		(end 498.927374 -134.89051)
		(width 0.10795)
		(layer "B.Cu")
		(net "JTAG_MCP_CPU1_TDI")
	)
	(segment
		(start 172.478446 -127.951484)
		(end 172.478446 -126.89205)
		(width 0.10795)
		(layer "B.Cu")
		(net "JTAG_MCP_CPU1_TDI")
	)
	(segment
		(start 498.328188 -131.007612)
		(end 498.328188 -130.30454)
		(width 0.10795)
		(layer "B.Cu")
		(net "JTAG_MCP_CPU1_TDI")
	)
	(segment
		(start 171.334684 -126.630684)
		(end 170.307 -125.603)
		(width 0.10795)
		(layer "B.Cu")
		(net "JTAG_MCP_CPU1_TDI")
	)
	(segment
		(start 172.21708 -126.630684)
		(end 171.334684 -126.630684)
		(width 0.10795)
		(layer "B.Cu")
		(net "JTAG_MCP_CPU1_TDI")
	)
	(segment
		(start 498.927374 -133.192774)
		(end 498.2464 -132.5118)
		(width 0.10795)
		(layer "B.Cu")
		(net "JTAG_MCP_CPU1_TDI")
	)
	(segment
		(start 498.2464 -131.0894)
		(end 498.328188 -131.007612)
		(width 0.10795)
		(layer "B.Cu")
		(net "JTAG_MCP_CPU1_TDI")
	)
	(segment
		(start 498.2464 -132.5118)
		(end 498.2464 -131.0894)
		(width 0.10795)
		(layer "B.Cu")
		(net "JTAG_MCP_CPU1_TDI")
	)
	(segment
		(start 497.927884 -135.89)
		(end 497.459 -135.89)
		(width 0.10795)
		(layer "B.Cu")
		(net "JTAG_MCP_CPU1_TDI")
	)
	(segment
		(start 172.478446 -126.89205)
		(end 172.21708 -126.630684)
		(width 0.10795)
		(layer "B.Cu")
		(net "JTAG_MCP_CPU1_TDI")
	)
	(segment
		(start 444.7032 -131.0894)
		(end 445.2366 -130.556)
		(width 0.10795)
		(layer "B.Cu")
		(net "JTAG_MCP_CPU1_TDI")
	)
	(segment
		(start 498.927374 -133.364478)
		(end 498.927374 -133.192774)
		(width 0.10795)
		(layer "B.Cu")
		(net "JTAG_MCP_CPU1_TDI")
	)
	(segment
		(start 498.927374 -134.89051)
		(end 497.927884 -135.89)
		(width 0.10795)
		(layer "B.Cu")
		(net "JTAG_MCP_CPU1_TDI")
	)
	(segment
		(start 445.2366 -130.556)
		(end 445.2366 -130.027172)
		(width 0.10795)
		(layer "B.Cu")
		(net "JTAG_MCP_CPU1_TDI")
	)
	(segment
		(start 484.16718 -149.515576)
		(end 479.622104 -144.9705)
		(width 0.089408)
		(layer "In2.Cu")
		(net "JTAG_MCP_CPU1_TDI")
	)
	(segment
		(start 426.7454 -125.765052)
		(end 426.7454 -124.591572)
		(width 0.089408)
		(layer "In2.Cu")
		(net "JTAG_MCP_CPU1_TDI")
	)
	(segment
		(start 431.381916 -123.61926)
		(end 431.381916 -123.665742)
		(width 0.089408)
		(layer "In2.Cu")
		(net "JTAG_MCP_CPU1_TDI")
	)
	(segment
		(start 491.661704 -142.322296)
		(end 490.899704 -142.322296)
		(width 0.089408)
		(layer "In2.Cu")
		(net "JTAG_MCP_CPU1_TDI")
	)
	(segment
		(start 494.530634 -140.443712)
		(end 493.540288 -140.443712)
		(width 0.089408)
		(layer "In2.Cu")
		(net "JTAG_MCP_CPU1_TDI")
	)
	(segment
		(start 468.110062 -143.777462)
		(end 467.5378 -143.2052)
		(width 0.089408)
		(layer "In2.Cu")
		(net "JTAG_MCP_CPU1_TDI")
	)
	(segment
		(start 489.870242 -150.30577)
		(end 488.404154 -151.771858)
		(width 0.089408)
		(layer "In2.Cu")
		(net "JTAG_MCP_CPU1_TDI")
	)
	(segment
		(start 403.054566 -119.509794)
		(end 405.855932 -119.509794)
		(width 0.089408)
		(layer "In2.Cu")
		(net "JTAG_MCP_CPU1_TDI")
	)
	(segment
		(start 426.7454 -124.591572)
		(end 428.000668 -123.336304)
		(width 0.089408)
		(layer "In2.Cu")
		(net "JTAG_MCP_CPU1_TDI")
	)
	(segment
		(start 470.525602 -143.750792)
		(end 469.909398 -143.750792)
		(width 0.089408)
		(layer "In2.Cu")
		(net "JTAG_MCP_CPU1_TDI")
	)
	(segment
		(start 407.131774 -121.500646)
		(end 409.589986 -123.958858)
		(width 0.089408)
		(layer "In2.Cu")
		(net "JTAG_MCP_CPU1_TDI")
	)
	(segment
		(start 473.03055 -143.777462)
		(end 470.552272 -143.777462)
		(width 0.089408)
		(layer "In2.Cu")
		(net "JTAG_MCP_CPU1_TDI")
	)
	(segment
		(start 470.552272 -143.777462)
		(end 470.525602 -143.750792)
		(width 0.089408)
		(layer "In2.Cu")
		(net "JTAG_MCP_CPU1_TDI")
	)
	(segment
		(start 479.622104 -144.9705)
		(end 474.223588 -144.9705)
		(width 0.089408)
		(layer "In2.Cu")
		(net "JTAG_MCP_CPU1_TDI")
	)
	(segment
		(start 402.58238 -119.98198)
		(end 403.054566 -119.509794)
		(width 0.089408)
		(layer "In2.Cu")
		(net "JTAG_MCP_CPU1_TDI")
	)
	(segment
		(start 489.870242 -149.186646)
		(end 489.870242 -150.30577)
		(width 0.089408)
		(layer "In2.Cu")
		(net "JTAG_MCP_CPU1_TDI")
	)
	(segment
		(start 409.790392 -123.958604)
		(end 411.709362 -123.958604)
		(width 0.089408)
		(layer "In2.Cu")
		(net "JTAG_MCP_CPU1_TDI")
	)
	(segment
		(start 488.404154 -151.771858)
		(end 485.404414 -151.771858)
		(width 0.089408)
		(layer "In2.Cu")
		(net "JTAG_MCP_CPU1_TDI")
	)
	(segment
		(start 424.4848 -127.4064)
		(end 425.104052 -127.4064)
		(width 0.089408)
		(layer "In2.Cu")
		(net "JTAG_MCP_CPU1_TDI")
	)
	(segment
		(start 407.034492 -120.688354)
		(end 407.034492 -121.395998)
		(width 0.089408)
		(layer "In2.Cu")
		(net "JTAG_MCP_CPU1_TDI")
	)
	(segment
		(start 489.895134 -143.326866)
		(end 489.895134 -149.161754)
		(width 0.089408)
		(layer "In2.Cu")
		(net "JTAG_MCP_CPU1_TDI")
	)
	(segment
		(start 425.104052 -127.4064)
		(end 426.7454 -125.765052)
		(width 0.089408)
		(layer "In2.Cu")
		(net "JTAG_MCP_CPU1_TDI")
	)
	(segment
		(start 485.404414 -151.771858)
		(end 484.16718 -150.534624)
		(width 0.089408)
		(layer "In2.Cu")
		(net "JTAG_MCP_CPU1_TDI")
	)
	(segment
		(start 484.16718 -150.534624)
		(end 484.16718 -149.515576)
		(width 0.089408)
		(layer "In2.Cu")
		(net "JTAG_MCP_CPU1_TDI")
	)
	(segment
		(start 490.899704 -142.322296)
		(end 489.895134 -143.326866)
		(width 0.089408)
		(layer "In2.Cu")
		(net "JTAG_MCP_CPU1_TDI")
	)
	(segment
		(start 430.88433 -123.121674)
		(end 431.381916 -123.61926)
		(width 0.089408)
		(layer "In2.Cu")
		(net "JTAG_MCP_CPU1_TDI")
	)
	(segment
		(start 417.051744 -123.30176)
		(end 418.840158 -125.090174)
		(width 0.089408)
		(layer "In2.Cu")
		(net "JTAG_MCP_CPU1_TDI")
	)
	(segment
		(start 469.909398 -143.750792)
		(end 469.882728 -143.777462)
		(width 0.089408)
		(layer "In2.Cu")
		(net "JTAG_MCP_CPU1_TDI")
	)
	(segment
		(start 407.034492 -121.395998)
		(end 407.131774 -121.49328)
		(width 0.089408)
		(layer "In2.Cu")
		(net "JTAG_MCP_CPU1_TDI")
	)
	(segment
		(start 493.540288 -140.443712)
		(end 491.661704 -142.322296)
		(width 0.089408)
		(layer "In2.Cu")
		(net "JTAG_MCP_CPU1_TDI")
	)
	(segment
		(start 489.895134 -149.161754)
		(end 489.870242 -149.186646)
		(width 0.089408)
		(layer "In2.Cu")
		(net "JTAG_MCP_CPU1_TDI")
	)
	(segment
		(start 497.1542 -136.1948)
		(end 497.1542 -137.820146)
		(width 0.089408)
		(layer "In2.Cu")
		(net "JTAG_MCP_CPU1_TDI")
	)
	(segment
		(start 409.589986 -123.958858)
		(end 409.790138 -123.958858)
		(width 0.089408)
		(layer "In2.Cu")
		(net "JTAG_MCP_CPU1_TDI")
	)
	(segment
		(start 409.790138 -123.958858)
		(end 409.790392 -123.958604)
		(width 0.089408)
		(layer "In2.Cu")
		(net "JTAG_MCP_CPU1_TDI")
	)
	(segment
		(start 407.131774 -121.49328)
		(end 407.131774 -121.500646)
		(width 0.089408)
		(layer "In2.Cu")
		(net "JTAG_MCP_CPU1_TDI")
	)
	(segment
		(start 422.168574 -125.090174)
		(end 424.4848 -127.4064)
		(width 0.089408)
		(layer "In2.Cu")
		(net "JTAG_MCP_CPU1_TDI")
	)
	(segment
		(start 412.366206 -123.30176)
		(end 417.051744 -123.30176)
		(width 0.089408)
		(layer "In2.Cu")
		(net "JTAG_MCP_CPU1_TDI")
	)
	(segment
		(start 428.000668 -123.336304)
		(end 428.790862 -123.336304)
		(width 0.089408)
		(layer "In2.Cu")
		(net "JTAG_MCP_CPU1_TDI")
	)
	(segment
		(start 405.855932 -119.509794)
		(end 407.034492 -120.688354)
		(width 0.089408)
		(layer "In2.Cu")
		(net "JTAG_MCP_CPU1_TDI")
	)
	(segment
		(start 429.005492 -123.121674)
		(end 430.88433 -123.121674)
		(width 0.089408)
		(layer "In2.Cu")
		(net "JTAG_MCP_CPU1_TDI")
	)
	(segment
		(start 428.790862 -123.336304)
		(end 429.005492 -123.121674)
		(width 0.089408)
		(layer "In2.Cu")
		(net "JTAG_MCP_CPU1_TDI")
	)
	(segment
		(start 497.459 -135.89)
		(end 497.1542 -136.1948)
		(width 0.089408)
		(layer "In2.Cu")
		(net "JTAG_MCP_CPU1_TDI")
	)
	(segment
		(start 474.223588 -144.9705)
		(end 473.03055 -143.777462)
		(width 0.089408)
		(layer "In2.Cu")
		(net "JTAG_MCP_CPU1_TDI")
	)
	(segment
		(start 497.1542 -137.820146)
		(end 494.530634 -140.443712)
		(width 0.089408)
		(layer "In2.Cu")
		(net "JTAG_MCP_CPU1_TDI")
	)
	(segment
		(start 411.709362 -123.958604)
		(end 412.366206 -123.30176)
		(width 0.089408)
		(layer "In2.Cu")
		(net "JTAG_MCP_CPU1_TDI")
	)
	(segment
		(start 469.882728 -143.777462)
		(end 468.110062 -143.777462)
		(width 0.089408)
		(layer "In2.Cu")
		(net "JTAG_MCP_CPU1_TDI")
	)
	(segment
		(start 418.840158 -125.090174)
		(end 422.168574 -125.090174)
		(width 0.089408)
		(layer "In2.Cu")
		(net "JTAG_MCP_CPU1_TDI")
	)
	(segment
		(start 371.256052 -123.944888)
		(end 372.657116 -122.543824)
		(width 0.089408)
		(layer "In4.Cu")
		(net "JTAG_MCP_CPU1_TDI")
	)
	(segment
		(start 398.468596 -121.705624)
		(end 400.858736 -121.705624)
		(width 0.089408)
		(layer "In4.Cu")
		(net "JTAG_MCP_CPU1_TDI")
	)
	(segment
		(start 400.858736 -121.705624)
		(end 402.58238 -119.98198)
		(width 0.089408)
		(layer "In4.Cu")
		(net "JTAG_MCP_CPU1_TDI")
	)
	(segment
		(start 375.200418 -122.82551)
		(end 376.844052 -122.82551)
		(width 0.089408)
		(layer "In4.Cu")
		(net "JTAG_MCP_CPU1_TDI")
	)
	(segment
		(start 397.792194 -122.543824)
		(end 398.095978 -122.24004)
		(width 0.089408)
		(layer "In4.Cu")
		(net "JTAG_MCP_CPU1_TDI")
	)
	(segment
		(start 398.095978 -122.24004)
		(end 398.095978 -122.078242)
		(width 0.089408)
		(layer "In4.Cu")
		(net "JTAG_MCP_CPU1_TDI")
	)
	(segment
		(start 376.844052 -122.82551)
		(end 377.125738 -122.543824)
		(width 0.089408)
		(layer "In4.Cu")
		(net "JTAG_MCP_CPU1_TDI")
	)
	(segment
		(start 370.228876 -123.944888)
		(end 371.256052 -123.944888)
		(width 0.089408)
		(layer "In4.Cu")
		(net "JTAG_MCP_CPU1_TDI")
	)
	(segment
		(start 369.97386 -124.199904)
		(end 370.228876 -123.944888)
		(width 0.089408)
		(layer "In4.Cu")
		(net "JTAG_MCP_CPU1_TDI")
	)
	(segment
		(start 374.918732 -122.543824)
		(end 375.200418 -122.82551)
		(width 0.089408)
		(layer "In4.Cu")
		(net "JTAG_MCP_CPU1_TDI")
	)
	(segment
		(start 372.657116 -122.543824)
		(end 374.918732 -122.543824)
		(width 0.089408)
		(layer "In4.Cu")
		(net "JTAG_MCP_CPU1_TDI")
	)
	(segment
		(start 398.095978 -122.078242)
		(end 398.468596 -121.705624)
		(width 0.089408)
		(layer "In4.Cu")
		(net "JTAG_MCP_CPU1_TDI")
	)
	(segment
		(start 377.125738 -122.543824)
		(end 397.792194 -122.543824)
		(width 0.089408)
		(layer "In4.Cu")
		(net "JTAG_MCP_CPU1_TDI")
	)
	(segment
		(start 431.381916 -123.665742)
		(end 431.59426 -123.878086)
		(width 0.089408)
		(layer "In9.Cu")
		(net "JTAG_MCP_CPU1_TDI")
	)
	(segment
		(start 187.325 -131.231132)
		(end 188.554868 -132.461)
		(width 0.089408)
		(layer "In9.Cu")
		(net "JTAG_MCP_CPU1_TDI")
	)
	(segment
		(start 322.1101 -136.271254)
		(end 322.1101 -134.9248)
		(width 0.089408)
		(layer "In9.Cu")
		(net "JTAG_MCP_CPU1_TDI")
	)
	(segment
		(start 368.711734 -126.005844)
		(end 368.711734 -125.46203)
		(width 0.089408)
		(layer "In9.Cu")
		(net "JTAG_MCP_CPU1_TDI")
	)
	(segment
		(start 437.929274 -123.878086)
		(end 439.558938 -125.50775)
		(width 0.089408)
		(layer "In9.Cu")
		(net "JTAG_MCP_CPU1_TDI")
	)
	(segment
		(start 262.679434 -137.192766)
		(end 321.188588 -137.192766)
		(width 0.089408)
		(layer "In9.Cu")
		(net "JTAG_MCP_CPU1_TDI")
	)
	(segment
		(start 182.647844 -128.322324)
		(end 183.458358 -128.322324)
		(width 0.089408)
		(layer "In9.Cu")
		(net "JTAG_MCP_CPU1_TDI")
	)
	(segment
		(start 182.33136 -128.00584)
		(end 182.647844 -128.322324)
		(width 0.089408)
		(layer "In9.Cu")
		(net "JTAG_MCP_CPU1_TDI")
	)
	(segment
		(start 350.294448 -129.222754)
		(end 353.442524 -129.222754)
		(width 0.089408)
		(layer "In9.Cu")
		(net "JTAG_MCP_CPU1_TDI")
	)
	(segment
		(start 353.442524 -129.222754)
		(end 353.45497 -129.2352)
		(width 0.089408)
		(layer "In9.Cu")
		(net "JTAG_MCP_CPU1_TDI")
	)
	(segment
		(start 458.611732 -131.679696)
		(end 451.094348 -131.679696)
		(width 0.089408)
		(layer "In9.Cu")
		(net "JTAG_MCP_CPU1_TDI")
	)
	(segment
		(start 343.686638 -127.444754)
		(end 345.105228 -128.863344)
		(width 0.089408)
		(layer "In9.Cu")
		(net "JTAG_MCP_CPU1_TDI")
	)
	(segment
		(start 177.443638 -127.842518)
		(end 182.023004 -127.842518)
		(width 0.089408)
		(layer "In9.Cu")
		(net "JTAG_MCP_CPU1_TDI")
	)
	(segment
		(start 172.478446 -127.951484)
		(end 174.435262 -125.994668)
		(width 0.089408)
		(layer "In9.Cu")
		(net "JTAG_MCP_CPU1_TDI")
	)
	(segment
		(start 449.620132 -133.153912)
		(end 446.767712 -133.153912)
		(width 0.089408)
		(layer "In9.Cu")
		(net "JTAG_MCP_CPU1_TDI")
	)
	(segment
		(start 323.755258 -133.978142)
		(end 325.3232 -132.4102)
		(width 0.089408)
		(layer "In9.Cu")
		(net "JTAG_MCP_CPU1_TDI")
	)
	(segment
		(start 342.33485 -125.196092)
		(end 343.686638 -126.54788)
		(width 0.089408)
		(layer "In9.Cu")
		(net "JTAG_MCP_CPU1_TDI")
	)
	(segment
		(start 461.270096 -133.330696)
		(end 460.262732 -133.330696)
		(width 0.089408)
		(layer "In9.Cu")
		(net "JTAG_MCP_CPU1_TDI")
	)
	(segment
		(start 191.700658 -134.271766)
		(end 191.700658 -134.357364)
		(width 0.089408)
		(layer "In9.Cu")
		(net "JTAG_MCP_CPU1_TDI")
	)
	(segment
		(start 328.0664 -132.4102)
		(end 328.7268 -131.7498)
		(width 0.089408)
		(layer "In9.Cu")
		(net "JTAG_MCP_CPU1_TDI")
	)
	(segment
		(start 444.7032 -129.737104)
		(end 444.7032 -131.0894)
		(width 0.089408)
		(layer "In9.Cu")
		(net "JTAG_MCP_CPU1_TDI")
	)
	(segment
		(start 329.0824 -128.81864)
		(end 329.741276 -128.81864)
		(width 0.089408)
		(layer "In9.Cu")
		(net "JTAG_MCP_CPU1_TDI")
	)
	(segment
		(start 183.458358 -128.322324)
		(end 184.091834 -128.9558)
		(width 0.089408)
		(layer "In9.Cu")
		(net "JTAG_MCP_CPU1_TDI")
	)
	(segment
		(start 182.023004 -127.842518)
		(end 182.186326 -128.00584)
		(width 0.089408)
		(layer "In9.Cu")
		(net "JTAG_MCP_CPU1_TDI")
	)
	(segment
		(start 461.4672 -133.5278)
		(end 461.270096 -133.330696)
		(width 0.089408)
		(layer "In9.Cu")
		(net "JTAG_MCP_CPU1_TDI")
	)
	(segment
		(start 187.325 -130.09626)
		(end 187.325 -131.231132)
		(width 0.089408)
		(layer "In9.Cu")
		(net "JTAG_MCP_CPU1_TDI")
	)
	(segment
		(start 335.003394 -125.94209)
		(end 337.44281 -125.94209)
		(width 0.089408)
		(layer "In9.Cu")
		(net "JTAG_MCP_CPU1_TDI")
	)
	(segment
		(start 440.473846 -125.50775)
		(end 444.7032 -129.737104)
		(width 0.089408)
		(layer "In9.Cu")
		(net "JTAG_MCP_CPU1_TDI")
	)
	(segment
		(start 186.18454 -128.9558)
		(end 187.325 -130.09626)
		(width 0.089408)
		(layer "In9.Cu")
		(net "JTAG_MCP_CPU1_TDI")
	)
	(segment
		(start 191.700658 -134.357364)
		(end 194.169538 -136.826244)
		(width 0.089408)
		(layer "In9.Cu")
		(net "JTAG_MCP_CPU1_TDI")
	)
	(segment
		(start 325.3232 -132.4102)
		(end 328.0664 -132.4102)
		(width 0.089408)
		(layer "In9.Cu")
		(net "JTAG_MCP_CPU1_TDI")
	)
	(segment
		(start 188.554868 -132.461)
		(end 189.889892 -132.461)
		(width 0.089408)
		(layer "In9.Cu")
		(net "JTAG_MCP_CPU1_TDI")
	)
	(segment
		(start 328.7268 -131.7498)
		(end 328.7268 -129.17424)
		(width 0.089408)
		(layer "In9.Cu")
		(net "JTAG_MCP_CPU1_TDI")
	)
	(segment
		(start 334.6323 -126.313184)
		(end 335.003394 -125.94209)
		(width 0.089408)
		(layer "In9.Cu")
		(net "JTAG_MCP_CPU1_TDI")
	)
	(segment
		(start 446.767712 -133.153912)
		(end 444.7032 -131.0894)
		(width 0.089408)
		(layer "In9.Cu")
		(net "JTAG_MCP_CPU1_TDI")
	)
	(segment
		(start 431.59426 -123.878086)
		(end 437.929274 -123.878086)
		(width 0.089408)
		(layer "In9.Cu")
		(net "JTAG_MCP_CPU1_TDI")
	)
	(segment
		(start 338.188808 -125.196092)
		(end 342.33485 -125.196092)
		(width 0.089408)
		(layer "In9.Cu")
		(net "JTAG_MCP_CPU1_TDI")
	)
	(segment
		(start 439.558938 -125.50775)
		(end 440.473846 -125.50775)
		(width 0.089408)
		(layer "In9.Cu")
		(net "JTAG_MCP_CPU1_TDI")
	)
	(segment
		(start 184.091834 -128.9558)
		(end 186.18454 -128.9558)
		(width 0.089408)
		(layer "In9.Cu")
		(net "JTAG_MCP_CPU1_TDI")
	)
	(segment
		(start 357.161338 -128.923542)
		(end 357.781098 -128.303782)
		(width 0.089408)
		(layer "In9.Cu")
		(net "JTAG_MCP_CPU1_TDI")
	)
	(segment
		(start 451.094348 -131.679696)
		(end 449.620132 -133.153912)
		(width 0.089408)
		(layer "In9.Cu")
		(net "JTAG_MCP_CPU1_TDI")
	)
	(segment
		(start 321.188588 -137.192766)
		(end 322.1101 -136.271254)
		(width 0.089408)
		(layer "In9.Cu")
		(net "JTAG_MCP_CPU1_TDI")
	)
	(segment
		(start 355.648514 -128.923542)
		(end 357.161338 -128.923542)
		(width 0.089408)
		(layer "In9.Cu")
		(net "JTAG_MCP_CPU1_TDI")
	)
	(segment
		(start 353.45497 -129.2352)
		(end 355.336856 -129.2352)
		(width 0.089408)
		(layer "In9.Cu")
		(net "JTAG_MCP_CPU1_TDI")
	)
	(segment
		(start 322.1101 -134.9248)
		(end 323.056758 -133.978142)
		(width 0.089408)
		(layer "In9.Cu")
		(net "JTAG_MCP_CPU1_TDI")
	)
	(segment
		(start 366.413796 -128.303782)
		(end 368.711734 -126.005844)
		(width 0.089408)
		(layer "In9.Cu")
		(net "JTAG_MCP_CPU1_TDI")
	)
	(segment
		(start 261.20725 -135.720582)
		(end 262.679434 -137.192766)
		(width 0.089408)
		(layer "In9.Cu")
		(net "JTAG_MCP_CPU1_TDI")
	)
	(segment
		(start 332.246732 -126.313184)
		(end 334.6323 -126.313184)
		(width 0.089408)
		(layer "In9.Cu")
		(net "JTAG_MCP_CPU1_TDI")
	)
	(segment
		(start 175.595788 -125.994668)
		(end 177.443638 -127.842518)
		(width 0.089408)
		(layer "In9.Cu")
		(net "JTAG_MCP_CPU1_TDI")
	)
	(segment
		(start 174.435262 -125.994668)
		(end 175.595788 -125.994668)
		(width 0.089408)
		(layer "In9.Cu")
		(net "JTAG_MCP_CPU1_TDI")
	)
	(segment
		(start 258.876292 -136.826244)
		(end 259.981954 -135.720582)
		(width 0.089408)
		(layer "In9.Cu")
		(net "JTAG_MCP_CPU1_TDI")
	)
	(segment
		(start 343.686638 -126.54788)
		(end 343.686638 -127.444754)
		(width 0.089408)
		(layer "In9.Cu")
		(net "JTAG_MCP_CPU1_TDI")
	)
	(segment
		(start 329.741276 -128.81864)
		(end 332.246732 -126.313184)
		(width 0.089408)
		(layer "In9.Cu")
		(net "JTAG_MCP_CPU1_TDI")
	)
	(segment
		(start 337.44281 -125.94209)
		(end 338.188808 -125.196092)
		(width 0.089408)
		(layer "In9.Cu")
		(net "JTAG_MCP_CPU1_TDI")
	)
	(segment
		(start 323.056758 -133.978142)
		(end 323.755258 -133.978142)
		(width 0.089408)
		(layer "In9.Cu")
		(net "JTAG_MCP_CPU1_TDI")
	)
	(segment
		(start 345.105228 -128.863344)
		(end 348.80804 -128.863344)
		(width 0.089408)
		(layer "In9.Cu")
		(net "JTAG_MCP_CPU1_TDI")
	)
	(segment
		(start 328.7268 -129.17424)
		(end 329.0824 -128.81864)
		(width 0.089408)
		(layer "In9.Cu")
		(net "JTAG_MCP_CPU1_TDI")
	)
	(segment
		(start 368.711734 -125.46203)
		(end 369.97386 -124.199904)
		(width 0.089408)
		(layer "In9.Cu")
		(net "JTAG_MCP_CPU1_TDI")
	)
	(segment
		(start 349.02394 -129.079244)
		(end 350.150938 -129.079244)
		(width 0.089408)
		(layer "In9.Cu")
		(net "JTAG_MCP_CPU1_TDI")
	)
	(segment
		(start 259.981954 -135.720582)
		(end 261.20725 -135.720582)
		(width 0.089408)
		(layer "In9.Cu")
		(net "JTAG_MCP_CPU1_TDI")
	)
	(segment
		(start 194.169538 -136.826244)
		(end 258.876292 -136.826244)
		(width 0.089408)
		(layer "In9.Cu")
		(net "JTAG_MCP_CPU1_TDI")
	)
	(segment
		(start 357.781098 -128.303782)
		(end 366.413796 -128.303782)
		(width 0.089408)
		(layer "In9.Cu")
		(net "JTAG_MCP_CPU1_TDI")
	)
	(segment
		(start 460.262732 -133.330696)
		(end 458.611732 -131.679696)
		(width 0.089408)
		(layer "In9.Cu")
		(net "JTAG_MCP_CPU1_TDI")
	)
	(segment
		(start 350.150938 -129.079244)
		(end 350.294448 -129.222754)
		(width 0.089408)
		(layer "In9.Cu")
		(net "JTAG_MCP_CPU1_TDI")
	)
	(segment
		(start 355.336856 -129.2352)
		(end 355.648514 -128.923542)
		(width 0.089408)
		(layer "In9.Cu")
		(net "JTAG_MCP_CPU1_TDI")
	)
	(segment
		(start 182.186326 -128.00584)
		(end 182.33136 -128.00584)
		(width 0.089408)
		(layer "In9.Cu")
		(net "JTAG_MCP_CPU1_TDI")
	)
	(segment
		(start 348.80804 -128.863344)
		(end 349.02394 -129.079244)
		(width 0.089408)
		(layer "In9.Cu")
		(net "JTAG_MCP_CPU1_TDI")
	)
	(segment
		(start 189.889892 -132.461)
		(end 191.700658 -134.271766)
		(width 0.089408)
		(layer "In9.Cu")
		(net "JTAG_MCP_CPU1_TDI")
	)
	(segment
		(start 125.652784 -80.669384)
		(end 125.9586 -80.9752)
		(width 0.089408)
		(layer "In11.Cu")
		(net "JTAG_MCP_CPU1_TDI")
	)
	(segment
		(start 125.9586 -80.9752)
		(end 125.9586 -81.2546)
		(width 0.089408)
		(layer "In11.Cu")
		(net "JTAG_MCP_CPU1_TDI")
	)
	(segment
		(start 467.99754 -138.241532)
		(end 467.0425 -137.286492)
		(width 0.089408)
		(layer "In11.Cu")
		(net "JTAG_MCP_CPU1_TDI")
	)
	(segment
		(start 466.532976 -134.8232)
		(end 464.2612 -134.8232)
		(width 0.089408)
		(layer "In11.Cu")
		(net "JTAG_MCP_CPU1_TDI")
	)
	(segment
		(start 136.0678 -88.0364)
		(end 136.6266 -88.5952)
		(width 0.089408)
		(layer "In11.Cu")
		(net "JTAG_MCP_CPU1_TDI")
	)
	(segment
		(start 130.937 -85.1154)
		(end 131.3434 -85.5218)
		(width 0.089408)
		(layer "In11.Cu")
		(net "JTAG_MCP_CPU1_TDI")
	)
	(segment
		(start 128.3462 -83.6422)
		(end 128.778 -84.074)
		(width 0.089408)
		(layer "In11.Cu")
		(net "JTAG_MCP_CPU1_TDI")
	)
	(segment
		(start 133.5786 -86.614)
		(end 134.0358 -87.0712)
		(width 0.089408)
		(layer "In11.Cu")
		(net "JTAG_MCP_CPU1_TDI")
	)
	(segment
		(start 126.0856 -81.3816)
		(end 126.0856 -82.3976)
		(width 0.089408)
		(layer "In11.Cu")
		(net "JTAG_MCP_CPU1_TDI")
	)
	(segment
		(start 130.556 -85.1154)
		(end 130.937 -85.1154)
		(width 0.089408)
		(layer "In11.Cu")
		(net "JTAG_MCP_CPU1_TDI")
	)
	(segment
		(start 139.9032 -90.4748)
		(end 141.0462 -90.4748)
		(width 0.089408)
		(layer "In11.Cu")
		(net "JTAG_MCP_CPU1_TDI")
	)
	(segment
		(start 141.0462 -90.4748)
		(end 144.3228 -93.7514)
		(width 0.089408)
		(layer "In11.Cu")
		(net "JTAG_MCP_CPU1_TDI")
	)
	(segment
		(start 126.0856 -82.3976)
		(end 126.3142 -82.6262)
		(width 0.089408)
		(layer "In11.Cu")
		(net "JTAG_MCP_CPU1_TDI")
	)
	(segment
		(start 132.2324 -86.0298)
		(end 132.6642 -86.0298)
		(width 0.089408)
		(layer "In11.Cu")
		(net "JTAG_MCP_CPU1_TDI")
	)
	(segment
		(start 135.2296 -87.6046)
		(end 135.6614 -88.0364)
		(width 0.089408)
		(layer "In11.Cu")
		(net "JTAG_MCP_CPU1_TDI")
	)
	(segment
		(start 133.2484 -86.614)
		(end 133.5786 -86.614)
		(width 0.089408)
		(layer "In11.Cu")
		(net "JTAG_MCP_CPU1_TDI")
	)
	(segment
		(start 128.0922 -83.6422)
		(end 128.3462 -83.6422)
		(width 0.089408)
		(layer "In11.Cu")
		(net "JTAG_MCP_CPU1_TDI")
	)
	(segment
		(start 130.048 -84.6074)
		(end 130.556 -85.1154)
		(width 0.089408)
		(layer "In11.Cu")
		(net "JTAG_MCP_CPU1_TDI")
	)
	(segment
		(start 467.0425 -135.332724)
		(end 466.532976 -134.8232)
		(width 0.089408)
		(layer "In11.Cu")
		(net "JTAG_MCP_CPU1_TDI")
	)
	(segment
		(start 134.3152 -87.0712)
		(end 134.8486 -87.6046)
		(width 0.089408)
		(layer "In11.Cu")
		(net "JTAG_MCP_CPU1_TDI")
	)
	(segment
		(start 464.2612 -134.8232)
		(end 462.9658 -133.5278)
		(width 0.089408)
		(layer "In11.Cu")
		(net "JTAG_MCP_CPU1_TDI")
	)
	(segment
		(start 137.8458 -89.1032)
		(end 138.2522 -89.5096)
		(width 0.089408)
		(layer "In11.Cu")
		(net "JTAG_MCP_CPU1_TDI")
	)
	(segment
		(start 126.5936 -82.6262)
		(end 127.0508 -83.0834)
		(width 0.089408)
		(layer "In11.Cu")
		(net "JTAG_MCP_CPU1_TDI")
	)
	(segment
		(start 165.92804 -110.15726)
		(end 173.37024 -117.59946)
		(width 0.089408)
		(layer "In11.Cu")
		(net "JTAG_MCP_CPU1_TDI")
	)
	(segment
		(start 134.8486 -87.6046)
		(end 135.2296 -87.6046)
		(width 0.089408)
		(layer "In11.Cu")
		(net "JTAG_MCP_CPU1_TDI")
	)
	(segment
		(start 155.09494 -110.15726)
		(end 165.92804 -110.15726)
		(width 0.089408)
		(layer "In11.Cu")
		(net "JTAG_MCP_CPU1_TDI")
	)
	(segment
		(start 134.0358 -87.0712)
		(end 134.3152 -87.0712)
		(width 0.089408)
		(layer "In11.Cu")
		(net "JTAG_MCP_CPU1_TDI")
	)
	(segment
		(start 139.1158 -89.9922)
		(end 139.4206 -89.9922)
		(width 0.089408)
		(layer "In11.Cu")
		(net "JTAG_MCP_CPU1_TDI")
	)
	(segment
		(start 127.5334 -83.0834)
		(end 128.0922 -83.6422)
		(width 0.089408)
		(layer "In11.Cu")
		(net "JTAG_MCP_CPU1_TDI")
	)
	(segment
		(start 462.9658 -133.5278)
		(end 461.4672 -133.5278)
		(width 0.089408)
		(layer "In11.Cu")
		(net "JTAG_MCP_CPU1_TDI")
	)
	(segment
		(start 172.498512 -126.92126)
		(end 172.498512 -127.931418)
		(width 0.089408)
		(layer "In11.Cu")
		(net "JTAG_MCP_CPU1_TDI")
	)
	(segment
		(start 173.37024 -117.59946)
		(end 173.37024 -126.049532)
		(width 0.089408)
		(layer "In11.Cu")
		(net "JTAG_MCP_CPU1_TDI")
	)
	(segment
		(start 131.7244 -85.5218)
		(end 132.2324 -86.0298)
		(width 0.089408)
		(layer "In11.Cu")
		(net "JTAG_MCP_CPU1_TDI")
	)
	(segment
		(start 126.3142 -82.6262)
		(end 126.5936 -82.6262)
		(width 0.089408)
		(layer "In11.Cu")
		(net "JTAG_MCP_CPU1_TDI")
	)
	(segment
		(start 131.3434 -85.5218)
		(end 131.7244 -85.5218)
		(width 0.089408)
		(layer "In11.Cu")
		(net "JTAG_MCP_CPU1_TDI")
	)
	(segment
		(start 144.3228 -99.38512)
		(end 155.09494 -110.15726)
		(width 0.089408)
		(layer "In11.Cu")
		(net "JTAG_MCP_CPU1_TDI")
	)
	(segment
		(start 128.778 -84.074)
		(end 129.1844 -84.074)
		(width 0.089408)
		(layer "In11.Cu")
		(net "JTAG_MCP_CPU1_TDI")
	)
	(segment
		(start 467.99754 -142.74546)
		(end 467.99754 -138.241532)
		(width 0.089408)
		(layer "In11.Cu")
		(net "JTAG_MCP_CPU1_TDI")
	)
	(segment
		(start 129.7178 -84.6074)
		(end 130.048 -84.6074)
		(width 0.089408)
		(layer "In11.Cu")
		(net "JTAG_MCP_CPU1_TDI")
	)
	(segment
		(start 139.4206 -89.9922)
		(end 139.9032 -90.4748)
		(width 0.089408)
		(layer "In11.Cu")
		(net "JTAG_MCP_CPU1_TDI")
	)
	(segment
		(start 125.651768 -80.669384)
		(end 125.652784 -80.669384)
		(width 0.089408)
		(layer "In11.Cu")
		(net "JTAG_MCP_CPU1_TDI")
	)
	(segment
		(start 125.9586 -81.2546)
		(end 126.0856 -81.3816)
		(width 0.089408)
		(layer "In11.Cu")
		(net "JTAG_MCP_CPU1_TDI")
	)
	(segment
		(start 132.6642 -86.0298)
		(end 133.2484 -86.614)
		(width 0.089408)
		(layer "In11.Cu")
		(net "JTAG_MCP_CPU1_TDI")
	)
	(segment
		(start 135.6614 -88.0364)
		(end 136.0678 -88.0364)
		(width 0.089408)
		(layer "In11.Cu")
		(net "JTAG_MCP_CPU1_TDI")
	)
	(segment
		(start 138.2522 -89.5096)
		(end 138.6332 -89.5096)
		(width 0.089408)
		(layer "In11.Cu")
		(net "JTAG_MCP_CPU1_TDI")
	)
	(segment
		(start 173.37024 -126.049532)
		(end 172.498512 -126.92126)
		(width 0.089408)
		(layer "In11.Cu")
		(net "JTAG_MCP_CPU1_TDI")
	)
	(segment
		(start 144.3228 -93.7514)
		(end 144.3228 -99.38512)
		(width 0.089408)
		(layer "In11.Cu")
		(net "JTAG_MCP_CPU1_TDI")
	)
	(segment
		(start 172.498512 -127.931418)
		(end 172.478446 -127.951484)
		(width 0.089408)
		(layer "In11.Cu")
		(net "JTAG_MCP_CPU1_TDI")
	)
	(segment
		(start 136.6266 -88.5952)
		(end 136.9568 -88.5952)
		(width 0.089408)
		(layer "In11.Cu")
		(net "JTAG_MCP_CPU1_TDI")
	)
	(segment
		(start 467.5378 -143.2052)
		(end 467.99754 -142.74546)
		(width 0.089408)
		(layer "In11.Cu")
		(net "JTAG_MCP_CPU1_TDI")
	)
	(segment
		(start 127.0508 -83.0834)
		(end 127.5334 -83.0834)
		(width 0.089408)
		(layer "In11.Cu")
		(net "JTAG_MCP_CPU1_TDI")
	)
	(segment
		(start 136.9568 -88.5952)
		(end 137.4648 -89.1032)
		(width 0.089408)
		(layer "In11.Cu")
		(net "JTAG_MCP_CPU1_TDI")
	)
	(segment
		(start 467.0425 -137.286492)
		(end 467.0425 -135.332724)
		(width 0.089408)
		(layer "In11.Cu")
		(net "JTAG_MCP_CPU1_TDI")
	)
	(segment
		(start 137.4648 -89.1032)
		(end 137.8458 -89.1032)
		(width 0.089408)
		(layer "In11.Cu")
		(net "JTAG_MCP_CPU1_TDI")
	)
	(segment
		(start 129.1844 -84.074)
		(end 129.7178 -84.6074)
		(width 0.089408)
		(layer "In11.Cu")
		(net "JTAG_MCP_CPU1_TDI")
	)
	(segment
		(start 138.6332 -89.5096)
		(end 139.1158 -89.9922)
		(width 0.089408)
		(layer "In11.Cu")
		(net "JTAG_MCP_CPU1_TDI")
	)
	(via
		(at 326.39 -53.594)
		(size 0.6604)
		(drill 0.3302)
		(layers "F.Cu" "B.Cu")
		(net "JTAG_MCP_CPU0_TDI_R")
	)
	(segment
		(start 328.803 -55.353712)
		(end 328.803 -55.626)
		(width 0.10795)
		(layer "B.Cu")
		(net "JTAG_MCP_CPU0_TDI_R")
	)
	(segment
		(start 328.047096 -54.235096)
		(end 328.047096 -54.597808)
		(width 0.10795)
		(layer "B.Cu")
		(net "JTAG_MCP_CPU0_TDI_R")
	)
	(segment
		(start 328.047096 -54.597808)
		(end 328.803 -55.353712)
		(width 0.10795)
		(layer "B.Cu")
		(net "JTAG_MCP_CPU0_TDI_R")
	)
	(segment
		(start 327.578466 -56.395874)
		(end 328.041 -55.93334)
		(width 0.10795)
		(layer "B.Cu")
		(net "JTAG_MCP_CPU0_TDI_R")
	)
	(segment
		(start 326.39 -53.594)
		(end 327.406 -53.594)
		(width 0.10795)
		(layer "B.Cu")
		(net "JTAG_MCP_CPU0_TDI_R")
	)
	(segment
		(start 328.041 -55.93334)
		(end 328.041 -55.626)
		(width 0.10795)
		(layer "B.Cu")
		(net "JTAG_MCP_CPU0_TDI_R")
	)
	(segment
		(start 327.406 -53.594)
		(end 328.047096 -54.235096)
		(width 0.10795)
		(layer "B.Cu")
		(net "JTAG_MCP_CPU0_TDI_R")
	)
	(segment
		(start 328.041 -55.626)
		(end 328.803 -55.626)
		(width 0.10795)
		(layer "B.Cu")
		(net "JTAG_MCP_CPU0_TDI_R")
	)
	(segment
		(start 327.578466 -56.616346)
		(end 327.578466 -56.395874)
		(width 0.10795)
		(layer "B.Cu")
		(net "JTAG_MCP_CPU0_TDI_R")
	)
	(segment
		(start 290.0807 -80.669384)
		(end 290.6522 -80.669384)
		(width 0.1016)
		(layer "F.Cu")
		(net "JTAG_MCP_CPU0_TDI")
	)
	(via
		(at 418.98443 -130.86461)
		(size 0.508)
		(drill 0.254)
		(layers "F.Cu" "B.Cu")
		(net "JTAG_MCP_CPU0_TDI")
	)
	(via
		(at 326.06488 -56.86298)
		(size 0.508)
		(drill 0.254)
		(layers "F.Cu" "B.Cu")
		(net "JTAG_MCP_CPU0_TDI")
	)
	(via
		(at 290.6522 -80.669384)
		(size 0.508)
		(drill 0.254)
		(layers "F.Cu" "B.Cu")
		(net "JTAG_MCP_CPU0_TDI")
	)
	(via
		(at 435.734206 -125.44806)
		(size 0.6604)
		(drill 0.3302)
		(layers "F.Cu" "B.Cu")
		(net "JTAG_MCP_CPU0_TDI")
	)
	(via
		(at 325.27113 -126.095506)
		(size 0.508)
		(drill 0.254)
		(layers "F.Cu" "B.Cu")
		(net "JTAG_MCP_CPU0_TDI")
	)
	(via
		(at 342.187784 -120.127014)
		(size 0.508)
		(drill 0.254)
		(layers "F.Cu" "B.Cu")
		(net "JTAG_MCP_CPU0_TDI")
	)
	(segment
		(start 326.06488 -56.290718)
		(end 326.06488 -56.86298)
		(width 0.10795)
		(layer "B.Cu")
		(net "JTAG_MCP_CPU0_TDI")
	)
	(segment
		(start 418.98443 -130.86461)
		(end 419.099492 -130.749548)
		(width 0.10795)
		(layer "B.Cu")
		(net "JTAG_MCP_CPU0_TDI")
	)
	(segment
		(start 434.937916 -124.65177)
		(end 435.734206 -125.44806)
		(width 0.10795)
		(layer "B.Cu")
		(net "JTAG_MCP_CPU0_TDI")
	)
	(segment
		(start 428.103538 -124.65177)
		(end 434.937916 -124.65177)
		(width 0.10795)
		(layer "B.Cu")
		(net "JTAG_MCP_CPU0_TDI")
	)
	(segment
		(start 425.268644 -127.486664)
		(end 428.103538 -124.65177)
		(width 0.10795)
		(layer "B.Cu")
		(net "JTAG_MCP_CPU0_TDI")
	)
	(segment
		(start 327.152 -55.626)
		(end 326.729598 -55.626)
		(width 0.10795)
		(layer "B.Cu")
		(net "JTAG_MCP_CPU0_TDI")
	)
	(segment
		(start 326.729598 -55.626)
		(end 326.06488 -56.290718)
		(width 0.10795)
		(layer "B.Cu")
		(net "JTAG_MCP_CPU0_TDI")
	)
	(segment
		(start 435.734206 -125.44806)
		(end 439.013346 -128.7272)
		(width 0.10795)
		(layer "B.Cu")
		(net "JTAG_MCP_CPU0_TDI")
	)
	(segment
		(start 419.099492 -130.749548)
		(end 420.355776 -130.749548)
		(width 0.10795)
		(layer "B.Cu")
		(net "JTAG_MCP_CPU0_TDI")
	)
	(segment
		(start 423.61866 -127.486664)
		(end 425.268644 -127.486664)
		(width 0.10795)
		(layer "B.Cu")
		(net "JTAG_MCP_CPU0_TDI")
	)
	(segment
		(start 439.013346 -128.7272)
		(end 445.2366 -128.7272)
		(width 0.10795)
		(layer "B.Cu")
		(net "JTAG_MCP_CPU0_TDI")
	)
	(segment
		(start 420.355776 -130.749548)
		(end 423.61866 -127.486664)
		(width 0.10795)
		(layer "B.Cu")
		(net "JTAG_MCP_CPU0_TDI")
	)
	(segment
		(start 301.349918 -79.891382)
		(end 302.137572 -79.564992)
		(width 0.089408)
		(layer "In2.Cu")
		(net "JTAG_MCP_CPU0_TDI")
	)
	(segment
		(start 294.178736 -81.073752)
		(end 294.364156 -80.997044)
		(width 0.089408)
		(layer "In2.Cu")
		(net "JTAG_MCP_CPU0_TDI")
	)
	(segment
		(start 297.608498 -81.079594)
		(end 297.85564 -80.977232)
		(width 0.089408)
		(layer "In2.Cu")
		(net "JTAG_MCP_CPU0_TDI")
	)
	(segment
		(start 297.433492 -81.079594)
		(end 297.608498 -81.079594)
		(width 0.089408)
		(layer "In2.Cu")
		(net "JTAG_MCP_CPU0_TDI")
	)
	(segment
		(start 293.743126 -80.97393)
		(end 293.984426 -81.073752)
		(width 0.089408)
		(layer "In2.Cu")
		(net "JTAG_MCP_CPU0_TDI")
	)
	(segment
		(start 301.043848 -80.197452)
		(end 301.349918 -79.891382)
		(width 0.089408)
		(layer "In2.Cu")
		(net "JTAG_MCP_CPU0_TDI")
	)
	(segment
		(start 297.85564 -80.977232)
		(end 297.938698 -80.894174)
		(width 0.089408)
		(layer "In2.Cu")
		(net "JTAG_MCP_CPU0_TDI")
	)
	(segment
		(start 297.13809 -80.925162)
		(end 297.1927 -80.979772)
		(width 0.089408)
		(layer "In2.Cu")
		(net "JTAG_MCP_CPU0_TDI")
	)
	(segment
		(start 303.664366 -78.784958)
		(end 303.874678 -78.87208)
		(width 0.089408)
		(layer "In2.Cu")
		(net "JTAG_MCP_CPU0_TDI")
	)
	(segment
		(start 295.726612 -81.082388)
		(end 295.881552 -81.082388)
		(width 0.089408)
		(layer "In2.Cu")
		(net "JTAG_MCP_CPU0_TDI")
	)
	(segment
		(start 293.124382 -80.76438)
		(end 293.325296 -80.76438)
		(width 0.089408)
		(layer "In2.Cu")
		(net "JTAG_MCP_CPU0_TDI")
	)
	(segment
		(start 296.159682 -80.93075)
		(end 296.556684 -80.766412)
		(width 0.0889)
		(layer "In2.Cu")
		(net "JTAG_MCP_CPU0_TDI")
	)
	(segment
		(start 292.800532 -80.898492)
		(end 293.124382 -80.76438)
		(width 0.089408)
		(layer "In2.Cu")
		(net "JTAG_MCP_CPU0_TDI")
	)
	(segment
		(start 291.911024 -80.885792)
		(end 292.070536 -81.045304)
		(width 0.089408)
		(layer "In2.Cu")
		(net "JTAG_MCP_CPU0_TDI")
	)
	(segment
		(start 299.277786 -81.090008)
		(end 299.838872 -80.857598)
		(width 0.089408)
		(layer "In2.Cu")
		(net "JTAG_MCP_CPU0_TDI")
	)
	(segment
		(start 297.1927 -80.979772)
		(end 297.433492 -81.079594)
		(width 0.089408)
		(layer "In2.Cu")
		(net "JTAG_MCP_CPU0_TDI")
	)
	(segment
		(start 292.070536 -81.045304)
		(end 292.221158 -81.107788)
		(width 0.089408)
		(layer "In2.Cu")
		(net "JTAG_MCP_CPU0_TDI")
	)
	(segment
		(start 291.099494 -80.669384)
		(end 291.654992 -80.779874)
		(width 0.089408)
		(layer "In2.Cu")
		(net "JTAG_MCP_CPU0_TDI")
	)
	(segment
		(start 303.419002 -78.784958)
		(end 303.664366 -78.784958)
		(width 0.089408)
		(layer "In2.Cu")
		(net "JTAG_MCP_CPU0_TDI")
	)
	(segment
		(start 292.671246 -81.027778)
		(end 292.800532 -80.898492)
		(width 0.089408)
		(layer "In2.Cu")
		(net "JTAG_MCP_CPU0_TDI")
	)
	(segment
		(start 326.06488 -59.240674)
		(end 326.06488 -56.86298)
		(width 0.089408)
		(layer "In2.Cu")
		(net "JTAG_MCP_CPU0_TDI")
	)
	(segment
		(start 300.471332 -80.434688)
		(end 300.736 -80.32496)
		(width 0.089408)
		(layer "In2.Cu")
		(net "JTAG_MCP_CPU0_TDI")
	)
	(segment
		(start 313.2582 -78.504288)
		(end 313.2582 -73.904856)
		(width 0.089408)
		(layer "In2.Cu")
		(net "JTAG_MCP_CPU0_TDI")
	)
	(segment
		(start 298.263056 -80.759808)
		(end 298.465748 -80.759808)
		(width 0.089408)
		(layer "In2.Cu")
		(net "JTAG_MCP_CPU0_TDI")
	)
	(segment
		(start 300.270164 -80.635856)
		(end 300.471332 -80.434688)
		(width 0.089408)
		(layer "In2.Cu")
		(net "JTAG_MCP_CPU0_TDI")
	)
	(segment
		(start 312.666634 -79.095854)
		(end 313.2582 -78.504288)
		(width 0.089408)
		(layer "In2.Cu")
		(net "JTAG_MCP_CPU0_TDI")
	)
	(segment
		(start 303.096422 -78.918562)
		(end 303.419002 -78.784958)
		(width 0.089408)
		(layer "In2.Cu")
		(net "JTAG_MCP_CPU0_TDI")
	)
	(segment
		(start 303.874678 -78.87208)
		(end 304.098452 -79.095854)
		(width 0.089408)
		(layer "In2.Cu")
		(net "JTAG_MCP_CPU0_TDI")
	)
	(segment
		(start 299.912278 -80.784192)
		(end 300.270164 -80.635856)
		(width 0.089408)
		(layer "In2.Cu")
		(net "JTAG_MCP_CPU0_TDI")
	)
	(segment
		(start 293.325296 -80.76438)
		(end 293.680896 -80.9117)
		(width 0.089408)
		(layer "In2.Cu")
		(net "JTAG_MCP_CPU0_TDI")
	)
	(segment
		(start 297.938698 -80.894174)
		(end 298.263056 -80.759808)
		(width 0.089408)
		(layer "In2.Cu")
		(net "JTAG_MCP_CPU0_TDI")
	)
	(segment
		(start 295.325038 -80.876394)
		(end 295.392856 -80.944212)
		(width 0.089408)
		(layer "In2.Cu")
		(net "JTAG_MCP_CPU0_TDI")
	)
	(segment
		(start 295.881552 -81.082388)
		(end 296.097452 -80.99298)
		(width 0.089408)
		(layer "In2.Cu")
		(net "JTAG_MCP_CPU0_TDI")
	)
	(segment
		(start 296.556684 -80.766412)
		(end 296.754804 -80.766412)
		(width 0.0889)
		(layer "In2.Cu")
		(net "JTAG_MCP_CPU0_TDI")
	)
	(segment
		(start 292.221158 -81.107788)
		(end 292.478206 -81.107788)
		(width 0.089408)
		(layer "In2.Cu")
		(net "JTAG_MCP_CPU0_TDI")
	)
	(segment
		(start 295.054274 -80.764126)
		(end 295.325038 -80.876394)
		(width 0.089408)
		(layer "In2.Cu")
		(net "JTAG_MCP_CPU0_TDI")
	)
	(segment
		(start 319.51295 -67.650106)
		(end 319.51295 -65.792604)
		(width 0.089408)
		(layer "In2.Cu")
		(net "JTAG_MCP_CPU0_TDI")
	)
	(segment
		(start 302.923956 -79.091028)
		(end 303.096422 -78.918562)
		(width 0.089408)
		(layer "In2.Cu")
		(net "JTAG_MCP_CPU0_TDI")
	)
	(segment
		(start 298.986956 -81.090008)
		(end 299.277786 -81.090008)
		(width 0.089408)
		(layer "In2.Cu")
		(net "JTAG_MCP_CPU0_TDI")
	)
	(segment
		(start 293.680896 -80.9117)
		(end 293.743126 -80.97393)
		(width 0.089408)
		(layer "In2.Cu")
		(net "JTAG_MCP_CPU0_TDI")
	)
	(segment
		(start 298.791884 -80.894936)
		(end 298.986956 -81.090008)
		(width 0.089408)
		(layer "In2.Cu")
		(net "JTAG_MCP_CPU0_TDI")
	)
	(segment
		(start 294.364156 -80.997044)
		(end 294.425116 -80.936084)
		(width 0.089408)
		(layer "In2.Cu")
		(net "JTAG_MCP_CPU0_TDI")
	)
	(segment
		(start 292.478206 -81.107788)
		(end 292.671246 -81.027778)
		(width 0.089408)
		(layer "In2.Cu")
		(net "JTAG_MCP_CPU0_TDI")
	)
	(segment
		(start 319.51295 -65.792604)
		(end 326.06488 -59.240674)
		(width 0.089408)
		(layer "In2.Cu")
		(net "JTAG_MCP_CPU0_TDI")
	)
	(segment
		(start 291.654992 -80.779874)
		(end 291.911024 -80.885792)
		(width 0.089408)
		(layer "In2.Cu")
		(net "JTAG_MCP_CPU0_TDI")
	)
	(segment
		(start 294.425116 -80.936084)
		(end 294.840406 -80.764126)
		(width 0.089408)
		(layer "In2.Cu")
		(net "JTAG_MCP_CPU0_TDI")
	)
	(segment
		(start 299.838872 -80.857598)
		(end 299.912278 -80.784192)
		(width 0.089408)
		(layer "In2.Cu")
		(net "JTAG_MCP_CPU0_TDI")
	)
	(segment
		(start 300.736 -80.32496)
		(end 301.043848 -80.197452)
		(width 0.089408)
		(layer "In2.Cu")
		(net "JTAG_MCP_CPU0_TDI")
	)
	(segment
		(start 313.2582 -73.904856)
		(end 319.51295 -67.650106)
		(width 0.089408)
		(layer "In2.Cu")
		(net "JTAG_MCP_CPU0_TDI")
	)
	(segment
		(start 294.840406 -80.764126)
		(end 295.054274 -80.764126)
		(width 0.089408)
		(layer "In2.Cu")
		(net "JTAG_MCP_CPU0_TDI")
	)
	(segment
		(start 304.098452 -79.095854)
		(end 312.666634 -79.095854)
		(width 0.089408)
		(layer "In2.Cu")
		(net "JTAG_MCP_CPU0_TDI")
	)
	(segment
		(start 302.390556 -79.312008)
		(end 302.923956 -79.091028)
		(width 0.089408)
		(layer "In2.Cu")
		(net "JTAG_MCP_CPU0_TDI")
	)
	(segment
		(start 293.984426 -81.073752)
		(end 294.178736 -81.073752)
		(width 0.089408)
		(layer "In2.Cu")
		(net "JTAG_MCP_CPU0_TDI")
	)
	(segment
		(start 290.6522 -80.669384)
		(end 291.099494 -80.669384)
		(width 0.089408)
		(layer "In2.Cu")
		(net "JTAG_MCP_CPU0_TDI")
	)
	(segment
		(start 298.465748 -80.759808)
		(end 298.791884 -80.894936)
		(width 0.089408)
		(layer "In2.Cu")
		(net "JTAG_MCP_CPU0_TDI")
	)
	(segment
		(start 296.754804 -80.766412)
		(end 297.13809 -80.925162)
		(width 0.0889)
		(layer "In2.Cu")
		(net "JTAG_MCP_CPU0_TDI")
	)
	(segment
		(start 296.097452 -80.99298)
		(end 296.159682 -80.93075)
		(width 0.089408)
		(layer "In2.Cu")
		(net "JTAG_MCP_CPU0_TDI")
	)
	(segment
		(start 302.137572 -79.564992)
		(end 302.390556 -79.312008)
		(width 0.089408)
		(layer "In2.Cu")
		(net "JTAG_MCP_CPU0_TDI")
	)
	(segment
		(start 295.392856 -80.944212)
		(end 295.726612 -81.082388)
		(width 0.089408)
		(layer "In2.Cu")
		(net "JTAG_MCP_CPU0_TDI")
	)
	(segment
		(start 330.466446 -124.105416)
		(end 328.937112 -124.105416)
		(width 0.089408)
		(layer "In9.Cu")
		(net "JTAG_MCP_CPU0_TDI")
	)
	(segment
		(start 338.789518 -123.52528)
		(end 331.046582 -123.52528)
		(width 0.089408)
		(layer "In9.Cu")
		(net "JTAG_MCP_CPU0_TDI")
	)
	(segment
		(start 328.937112 -124.105416)
		(end 328.71918 -124.323348)
		(width 0.089408)
		(layer "In9.Cu")
		(net "JTAG_MCP_CPU0_TDI")
	)
	(segment
		(start 342.187784 -120.127014)
		(end 338.789518 -123.52528)
		(width 0.089408)
		(layer "In9.Cu")
		(net "JTAG_MCP_CPU0_TDI")
	)
	(segment
		(start 328.71918 -124.323348)
		(end 327.36282 -124.323348)
		(width 0.089408)
		(layer "In9.Cu")
		(net "JTAG_MCP_CPU0_TDI")
	)
	(segment
		(start 325.590662 -126.095506)
		(end 325.27113 -126.095506)
		(width 0.089408)
		(layer "In9.Cu")
		(net "JTAG_MCP_CPU0_TDI")
	)
	(segment
		(start 331.046582 -123.52528)
		(end 330.466446 -124.105416)
		(width 0.089408)
		(layer "In9.Cu")
		(net "JTAG_MCP_CPU0_TDI")
	)
	(segment
		(start 327.36282 -124.323348)
		(end 325.590662 -126.095506)
		(width 0.089408)
		(layer "In9.Cu")
		(net "JTAG_MCP_CPU0_TDI")
	)
	(segment
		(start 290.133786 -82.36585)
		(end 290.140136 -82.355182)
		(width 0.089408)
		(layer "In11.Cu")
		(net "JTAG_MCP_CPU0_TDI")
	)
	(segment
		(start 321.017646 -123.997466)
		(end 321.017646 -122.935746)
		(width 0.089408)
		(layer "In11.Cu")
		(net "JTAG_MCP_CPU0_TDI")
	)
	(segment
		(start 374.250204 -127.36449)
		(end 374.627394 -127.74168)
		(width 0.089408)
		(layer "In11.Cu")
		(net "JTAG_MCP_CPU0_TDI")
	)
	(segment
		(start 293.567866 -96.23425)
		(end 293.574216 -96.223582)
		(width 0.089408)
		(layer "In11.Cu")
		(net "JTAG_MCP_CPU0_TDI")
	)
	(segment
		(start 290.140136 -84.336382)
		(end 290.144962 -84.327746)
		(width 0.089408)
		(layer "In11.Cu")
		(net "JTAG_MCP_CPU0_TDI")
	)
	(segment
		(start 410.163264 -132.773166)
		(end 412.736284 -132.773166)
		(width 0.089408)
		(layer "In11.Cu")
		(net "JTAG_MCP_CPU0_TDI")
	)
	(segment
		(start 321.897248 -124.877068)
		(end 321.017646 -123.997466)
		(width 0.089408)
		(layer "In11.Cu")
		(net "JTAG_MCP_CPU0_TDI")
	)
	(segment
		(start 367.288318 -119.180356)
		(end 370.072412 -121.96445)
		(width 0.089408)
		(layer "In11.Cu")
		(net "JTAG_MCP_CPU0_TDI")
	)
	(segment
		(start 290.156392 -81.33588)
		(end 290.6522 -80.669384)
		(width 0.089408)
		(layer "In11.Cu")
		(net "JTAG_MCP_CPU0_TDI")
	)
	(segment
		(start 399.098516 -135.248904)
		(end 399.840958 -134.506462)
		(width 0.089408)
		(layer "In11.Cu")
		(net "JTAG_MCP_CPU0_TDI")
	)
	(segment
		(start 290.659312 -90.175588)
		(end 290.62807 -90.175588)
		(width 0.089408)
		(layer "In11.Cu")
		(net "JTAG_MCP_CPU0_TDI")
	)
	(segment
		(start 317.522606 -121.793254)
		(end 302.706278 -106.976926)
		(width 0.089408)
		(layer "In11.Cu")
		(net "JTAG_MCP_CPU0_TDI")
	)
	(segment
		(start 384.014472 -128.57607)
		(end 384.483356 -129.044954)
		(width 0.089408)
		(layer "In11.Cu")
		(net "JTAG_MCP_CPU0_TDI")
	)
	(segment
		(start 412.890462 -132.927344)
		(end 414.381442 -132.927344)
		(width 0.089408)
		(layer "In11.Cu")
		(net "JTAG_MCP_CPU0_TDI")
	)
	(segment
		(start 293.574216 -96.223582)
		(end 293.579042 -96.214946)
		(width 0.089408)
		(layer "In11.Cu")
		(net "JTAG_MCP_CPU0_TDI")
	)
	(segment
		(start 401.323556 -134.506462)
		(end 404.825962 -131.007104)
		(width 0.089408)
		(layer "In11.Cu")
		(net "JTAG_MCP_CPU0_TDI")
	)
	(segment
		(start 384.483356 -129.044954)
		(end 384.483356 -129.555748)
		(width 0.089408)
		(layer "In11.Cu")
		(net "JTAG_MCP_CPU0_TDI")
	)
	(segment
		(start 295.35882 -100.894134)
		(end 295.291256 -100.77704)
		(width 0.089408)
		(layer "In11.Cu")
		(net "JTAG_MCP_CPU0_TDI")
	)
	(segment
		(start 345.485974 -119.180356)
		(end 367.288318 -119.180356)
		(width 0.089408)
		(layer "In11.Cu")
		(net "JTAG_MCP_CPU0_TDI")
	)
	(segment
		(start 384.483356 -129.555748)
		(end 390.176512 -135.248904)
		(width 0.089408)
		(layer "In11.Cu")
		(net "JTAG_MCP_CPU0_TDI")
	)
	(segment
		(start 412.736284 -132.773166)
		(end 412.890462 -132.927344)
		(width 0.089408)
		(layer "In11.Cu")
		(net "JTAG_MCP_CPU0_TDI")
	)
	(segment
		(start 374.627394 -127.74168)
		(end 382.13284 -127.74168)
		(width 0.089408)
		(layer "In11.Cu")
		(net "JTAG_MCP_CPU0_TDI")
	)
	(segment
		(start 417.789614 -131.7498)
		(end 418.674804 -130.86461)
		(width 0.089408)
		(layer "In11.Cu")
		(net "JTAG_MCP_CPU0_TDI")
	)
	(segment
		(start 290.133786 -87.31885)
		(end 290.140136 -87.308182)
		(width 0.089408)
		(layer "In11.Cu")
		(net "JTAG_MCP_CPU0_TDI")
	)
	(segment
		(start 293.574216 -98.204782)
		(end 293.579042 -98.196146)
		(width 0.089408)
		(layer "In11.Cu")
		(net "JTAG_MCP_CPU0_TDI")
	)
	(segment
		(start 293.239952 -91.661742)
		(end 293.207186 -91.661742)
		(width 0.089408)
		(layer "In11.Cu")
		(net "JTAG_MCP_CPU0_TDI")
	)
	(segment
		(start 290.140136 -83.345782)
		(end 290.144962 -83.337146)
		(width 0.089408)
		(layer "In11.Cu")
		(net "JTAG_MCP_CPU0_TDI")
	)
	(segment
		(start 418.674804 -130.86461)
		(end 418.98443 -130.86461)
		(width 0.089408)
		(layer "In11.Cu")
		(net "JTAG_MCP_CPU0_TDI")
	)
	(segment
		(start 293.567866 -97.22485)
		(end 293.574216 -97.214182)
		(width 0.089408)
		(layer "In11.Cu")
		(net "JTAG_MCP_CPU0_TDI")
	)
	(segment
		(start 390.176512 -135.248904)
		(end 399.098516 -135.248904)
		(width 0.089408)
		(layer "In11.Cu")
		(net "JTAG_MCP_CPU0_TDI")
	)
	(segment
		(start 297.173904 -102.748842)
		(end 297.173904 -102.662482)
		(width 0.089408)
		(layer "In11.Cu")
		(net "JTAG_MCP_CPU0_TDI")
	)
	(segment
		(start 370.845842 -121.96445)
		(end 371.705886 -122.824494)
		(width 0.089408)
		(layer "In11.Cu")
		(net "JTAG_MCP_CPU0_TDI")
	)
	(segment
		(start 290.133786 -89.30005)
		(end 290.140136 -89.289382)
		(width 0.089408)
		(layer "In11.Cu")
		(net "JTAG_MCP_CPU0_TDI")
	)
	(segment
		(start 290.140136 -86.317582)
		(end 290.144962 -86.308946)
		(width 0.089408)
		(layer "In11.Cu")
		(net "JTAG_MCP_CPU0_TDI")
	)
	(segment
		(start 324.649592 -125.473968)
		(end 324.233286 -125.473968)
		(width 0.089408)
		(layer "In11.Cu")
		(net "JTAG_MCP_CPU0_TDI")
	)
	(segment
		(start 293.567866 -95.24365)
		(end 293.574216 -95.232982)
		(width 0.089408)
		(layer "In11.Cu")
		(net "JTAG_MCP_CPU0_TDI")
	)
	(segment
		(start 322.49745 -125.053598)
		(end 322.32092 -124.877068)
		(width 0.089408)
		(layer "In11.Cu")
		(net "JTAG_MCP_CPU0_TDI")
	)
	(segment
		(start 290.140136 -85.326982)
		(end 290.144962 -85.318346)
		(width 0.089408)
		(layer "In11.Cu")
		(net "JTAG_MCP_CPU0_TDI")
	)
	(segment
		(start 293.567866 -98.21545)
		(end 293.574216 -98.204782)
		(width 0.089408)
		(layer "In11.Cu")
		(net "JTAG_MCP_CPU0_TDI")
	)
	(segment
		(start 291.522912 -90.671142)
		(end 291.490146 -90.671142)
		(width 0.089408)
		(layer "In11.Cu")
		(net "JTAG_MCP_CPU0_TDI")
	)
	(segment
		(start 324.233286 -125.473968)
		(end 323.812916 -125.053598)
		(width 0.089408)
		(layer "In11.Cu")
		(net "JTAG_MCP_CPU0_TDI")
	)
	(segment
		(start 293.574216 -93.251782)
		(end 293.579042 -93.243146)
		(width 0.089408)
		(layer "In11.Cu")
		(net "JTAG_MCP_CPU0_TDI")
	)
	(segment
		(start 343.274904 -119.039894)
		(end 345.345512 -119.039894)
		(width 0.089408)
		(layer "In11.Cu")
		(net "JTAG_MCP_CPU0_TDI")
	)
	(segment
		(start 321.017646 -122.935746)
		(end 319.875154 -121.793254)
		(width 0.089408)
		(layer "In11.Cu")
		(net "JTAG_MCP_CPU0_TDI")
	)
	(segment
		(start 293.574216 -92.261182)
		(end 293.579042 -92.252546)
		(width 0.089408)
		(layer "In11.Cu")
		(net "JTAG_MCP_CPU0_TDI")
	)
	(segment
		(start 302.706278 -106.976926)
		(end 301.800768 -106.976926)
		(width 0.089408)
		(layer "In11.Cu")
		(net "JTAG_MCP_CPU0_TDI")
	)
	(segment
		(start 404.825962 -131.007104)
		(end 408.397202 -131.007104)
		(width 0.089408)
		(layer "In11.Cu")
		(net "JTAG_MCP_CPU0_TDI")
	)
	(segment
		(start 322.32092 -124.877068)
		(end 321.897248 -124.877068)
		(width 0.089408)
		(layer "In11.Cu")
		(net "JTAG_MCP_CPU0_TDI")
	)
	(segment
		(start 290.140136 -89.289382)
		(end 290.144962 -89.280746)
		(width 0.089408)
		(layer "In11.Cu")
		(net "JTAG_MCP_CPU0_TDI")
	)
	(segment
		(start 296.68597 -102.367334)
		(end 296.66184 -102.367334)
		(width 0.089408)
		(layer "In11.Cu")
		(net "JTAG_MCP_CPU0_TDI")
	)
	(segment
		(start 290.133786 -85.33765)
		(end 290.140136 -85.326982)
		(width 0.089408)
		(layer "In11.Cu")
		(net "JTAG_MCP_CPU0_TDI")
	)
	(segment
		(start 345.345512 -119.039894)
		(end 345.485974 -119.180356)
		(width 0.089408)
		(layer "In11.Cu")
		(net "JTAG_MCP_CPU0_TDI")
	)
	(segment
		(start 294.093392 -99.090988)
		(end 294.06215 -99.090988)
		(width 0.089408)
		(layer "In11.Cu")
		(net "JTAG_MCP_CPU0_TDI")
	)
	(segment
		(start 290.133786 -84.34705)
		(end 290.140136 -84.336382)
		(width 0.089408)
		(layer "In11.Cu")
		(net "JTAG_MCP_CPU0_TDI")
	)
	(segment
		(start 290.133786 -83.35645)
		(end 290.140136 -83.345782)
		(width 0.089408)
		(layer "In11.Cu")
		(net "JTAG_MCP_CPU0_TDI")
	)
	(segment
		(start 297.321478 -102.896416)
		(end 297.173904 -102.748842)
		(width 0.089408)
		(layer "In11.Cu")
		(net "JTAG_MCP_CPU0_TDI")
	)
	(segment
		(start 290.133786 -86.32825)
		(end 290.140136 -86.317582)
		(width 0.089408)
		(layer "In11.Cu")
		(net "JTAG_MCP_CPU0_TDI")
	)
	(segment
		(start 296.66184 -102.367334)
		(end 296.66184 -102.367588)
		(width 0.089408)
		(layer "In11.Cu")
		(net "JTAG_MCP_CPU0_TDI")
	)
	(segment
		(start 323.812916 -125.053598)
		(end 322.49745 -125.053598)
		(width 0.089408)
		(layer "In11.Cu")
		(net "JTAG_MCP_CPU0_TDI")
	)
	(segment
		(start 296.66184 -102.367588)
		(end 296.650664 -102.367588)
		(width 0.089408)
		(layer "In11.Cu")
		(net "JTAG_MCP_CPU0_TDI")
	)
	(segment
		(start 295.460166 -101.677724)
		(end 295.35882 -101.4984)
		(width 0.089408)
		(layer "In11.Cu")
		(net "JTAG_MCP_CPU0_TDI")
	)
	(segment
		(start 371.705886 -126.02718)
		(end 373.043196 -127.36449)
		(width 0.089408)
		(layer "In11.Cu")
		(net "JTAG_MCP_CPU0_TDI")
	)
	(segment
		(start 290.140136 -87.308182)
		(end 290.144962 -87.299546)
		(width 0.089408)
		(layer "In11.Cu")
		(net "JTAG_MCP_CPU0_TDI")
	)
	(segment
		(start 382.13284 -127.74168)
		(end 382.96723 -128.57607)
		(width 0.089408)
		(layer "In11.Cu")
		(net "JTAG_MCP_CPU0_TDI")
	)
	(segment
		(start 415.558986 -131.7498)
		(end 417.789614 -131.7498)
		(width 0.089408)
		(layer "In11.Cu")
		(net "JTAG_MCP_CPU0_TDI")
	)
	(segment
		(start 295.35882 -101.4984)
		(end 295.35882 -100.894134)
		(width 0.089408)
		(layer "In11.Cu")
		(net "JTAG_MCP_CPU0_TDI")
	)
	(segment
		(start 325.27113 -126.095506)
		(end 324.649592 -125.473968)
		(width 0.089408)
		(layer "In11.Cu")
		(net "JTAG_MCP_CPU0_TDI")
	)
	(segment
		(start 301.800768 -106.976926)
		(end 297.720258 -102.896416)
		(width 0.089408)
		(layer "In11.Cu")
		(net "JTAG_MCP_CPU0_TDI")
	)
	(segment
		(start 382.96723 -128.57607)
		(end 384.014472 -128.57607)
		(width 0.089408)
		(layer "In11.Cu")
		(net "JTAG_MCP_CPU0_TDI")
	)
	(segment
		(start 290.133786 -88.30945)
		(end 290.140136 -88.298782)
		(width 0.089408)
		(layer "In11.Cu")
		(net "JTAG_MCP_CPU0_TDI")
	)
	(segment
		(start 293.579042 -94.842076)
		(end 293.574216 -94.83344)
		(width 0.089408)
		(layer "In11.Cu")
		(net "JTAG_MCP_CPU0_TDI")
	)
	(segment
		(start 399.840958 -134.506462)
		(end 401.323556 -134.506462)
		(width 0.089408)
		(layer "In11.Cu")
		(net "JTAG_MCP_CPU0_TDI")
	)
	(segment
		(start 293.567866 -92.27185)
		(end 293.574216 -92.261182)
		(width 0.089408)
		(layer "In11.Cu")
		(net "JTAG_MCP_CPU0_TDI")
	)
	(segment
		(start 297.720258 -102.896416)
		(end 297.321478 -102.896416)
		(width 0.089408)
		(layer "In11.Cu")
		(net "JTAG_MCP_CPU0_TDI")
	)
	(segment
		(start 290.140136 -88.298782)
		(end 290.144962 -88.290146)
		(width 0.089408)
		(layer "In11.Cu")
		(net "JTAG_MCP_CPU0_TDI")
	)
	(segment
		(start 293.567866 -93.26245)
		(end 293.574216 -93.251782)
		(width 0.089408)
		(layer "In11.Cu")
		(net "JTAG_MCP_CPU0_TDI")
	)
	(segment
		(start 319.875154 -121.793254)
		(end 317.522606 -121.793254)
		(width 0.089408)
		(layer "In11.Cu")
		(net "JTAG_MCP_CPU0_TDI")
	)
	(segment
		(start 371.705886 -122.824494)
		(end 371.705886 -126.02718)
		(width 0.089408)
		(layer "In11.Cu")
		(net "JTAG_MCP_CPU0_TDI")
	)
	(segment
		(start 293.574216 -97.214182)
		(end 293.579042 -97.205546)
		(width 0.089408)
		(layer "In11.Cu")
		(net "JTAG_MCP_CPU0_TDI")
	)
	(segment
		(start 370.072412 -121.96445)
		(end 370.845842 -121.96445)
		(width 0.089408)
		(layer "In11.Cu")
		(net "JTAG_MCP_CPU0_TDI")
	)
	(segment
		(start 408.397202 -131.007104)
		(end 410.163264 -132.773166)
		(width 0.089408)
		(layer "In11.Cu")
		(net "JTAG_MCP_CPU0_TDI")
	)
	(segment
		(start 373.043196 -127.36449)
		(end 374.250204 -127.36449)
		(width 0.089408)
		(layer "In11.Cu")
		(net "JTAG_MCP_CPU0_TDI")
	)
	(segment
		(start 414.381442 -132.927344)
		(end 415.558986 -131.7498)
		(width 0.089408)
		(layer "In11.Cu")
		(net "JTAG_MCP_CPU0_TDI")
	)
	(segment
		(start 290.140136 -81.364582)
		(end 290.156392 -81.33588)
		(width 0.089408)
		(layer "In11.Cu")
		(net "JTAG_MCP_CPU0_TDI")
	)
	(segment
		(start 342.187784 -120.127014)
		(end 343.274904 -119.039894)
		(width 0.089408)
		(layer "In11.Cu")
		(net "JTAG_MCP_CPU0_TDI")
	)
	(segment
		(start 292.376352 -91.166188)
		(end 292.34511 -91.166188)
		(width 0.089408)
		(layer "In11.Cu")
		(net "JTAG_MCP_CPU0_TDI")
	)
	(segment
		(start 295.8211 -101.872034)
		(end 295.80332 -101.872034)
		(width 0.089408)
		(layer "In11.Cu")
		(net "JTAG_MCP_CPU0_TDI")
	)
	(arc
		(start 290.998656 -90.37574)
		(mid 290.855345 -90.230969)
		(end 290.659312 -90.175588)
		(width 0.089408)
		(layer "In11.Cu")
		(net "JTAG_MCP_CPU0_TDI")
	)
	(arc
		(start 294.06215 -99.090988)
		(mid 293.571347 -98.79083)
		(end 293.567866 -98.21545)
		(width 0.089408)
		(layer "In11.Cu")
		(net "JTAG_MCP_CPU0_TDI")
	)
	(arc
		(start 293.579042 -98.196146)
		(mid 293.627706 -98.000048)
		(end 293.574216 -97.80524)
		(width 0.089408)
		(layer "In11.Cu")
		(net "JTAG_MCP_CPU0_TDI")
	)
	(arc
		(start 291.857176 -90.87104)
		(mid 291.716019 -90.727655)
		(end 291.522912 -90.671142)
		(width 0.089408)
		(layer "In11.Cu")
		(net "JTAG_MCP_CPU0_TDI")
	)
	(arc
		(start 293.574216 -95.232982)
		(mid 293.627593 -95.038173)
		(end 293.579042 -94.842076)
		(width 0.089408)
		(layer "In11.Cu")
		(net "JTAG_MCP_CPU0_TDI")
	)
	(arc
		(start 290.144962 -84.327746)
		(mid 290.193626 -84.131648)
		(end 290.140136 -83.93684)
		(width 0.089408)
		(layer "In11.Cu")
		(net "JTAG_MCP_CPU0_TDI")
	)
	(arc
		(start 290.144962 -85.318346)
		(mid 290.193626 -85.122248)
		(end 290.140136 -84.92744)
		(width 0.089408)
		(layer "In11.Cu")
		(net "JTAG_MCP_CPU0_TDI")
	)
	(arc
		(start 292.34511 -91.166188)
		(mid 292.063208 -91.081325)
		(end 291.857176 -90.87104)
		(width 0.089408)
		(layer "In11.Cu")
		(net "JTAG_MCP_CPU0_TDI")
	)
	(arc
		(start 295.80332 -101.872034)
		(mid 295.606159 -101.820075)
		(end 295.460166 -101.677724)
		(width 0.089408)
		(layer "In11.Cu")
		(net "JTAG_MCP_CPU0_TDI")
	)
	(arc
		(start 292.715696 -91.36634)
		(mid 292.572385 -91.221569)
		(end 292.376352 -91.166188)
		(width 0.089408)
		(layer "In11.Cu")
		(net "JTAG_MCP_CPU0_TDI")
	)
	(arc
		(start 293.574216 -95.82404)
		(mid 293.494901 -95.534668)
		(end 293.567866 -95.24365)
		(width 0.089408)
		(layer "In11.Cu")
		(net "JTAG_MCP_CPU0_TDI")
	)
	(arc
		(start 290.140136 -84.92744)
		(mid 290.060821 -84.638068)
		(end 290.133786 -84.34705)
		(width 0.089408)
		(layer "In11.Cu")
		(net "JTAG_MCP_CPU0_TDI")
	)
	(arc
		(start 290.140136 -86.90864)
		(mid 290.060821 -86.619268)
		(end 290.133786 -86.32825)
		(width 0.089408)
		(layer "In11.Cu")
		(net "JTAG_MCP_CPU0_TDI")
	)
	(arc
		(start 290.140136 -87.89924)
		(mid 290.060821 -87.609868)
		(end 290.133786 -87.31885)
		(width 0.089408)
		(layer "In11.Cu")
		(net "JTAG_MCP_CPU0_TDI")
	)
	(arc
		(start 290.140136 -82.355182)
		(mid 290.193669 -82.155284)
		(end 290.140136 -81.955386)
		(width 0.089408)
		(layer "In11.Cu")
		(net "JTAG_MCP_CPU0_TDI")
	)
	(arc
		(start 290.140136 -81.955386)
		(mid 290.061039 -81.659984)
		(end 290.140136 -81.364582)
		(width 0.089408)
		(layer "In11.Cu")
		(net "JTAG_MCP_CPU0_TDI")
	)
	(arc
		(start 290.140136 -85.91804)
		(mid 290.060821 -85.628668)
		(end 290.133786 -85.33765)
		(width 0.089408)
		(layer "In11.Cu")
		(net "JTAG_MCP_CPU0_TDI")
	)
	(arc
		(start 290.144962 -88.290146)
		(mid 290.193626 -88.094048)
		(end 290.140136 -87.89924)
		(width 0.089408)
		(layer "In11.Cu")
		(net "JTAG_MCP_CPU0_TDI")
	)
	(arc
		(start 293.574216 -94.83344)
		(mid 293.495119 -94.538038)
		(end 293.574216 -94.242636)
		(width 0.089408)
		(layer "In11.Cu")
		(net "JTAG_MCP_CPU0_TDI")
	)
	(arc
		(start 290.140136 -88.88984)
		(mid 290.060821 -88.600468)
		(end 290.133786 -88.30945)
		(width 0.089408)
		(layer "In11.Cu")
		(net "JTAG_MCP_CPU0_TDI")
	)
	(arc
		(start 293.574216 -92.85224)
		(mid 293.494901 -92.562868)
		(end 293.567866 -92.27185)
		(width 0.089408)
		(layer "In11.Cu")
		(net "JTAG_MCP_CPU0_TDI")
	)
	(arc
		(start 296.31513 -102.167436)
		(mid 296.106522 -101.955504)
		(end 295.8211 -101.872034)
		(width 0.089408)
		(layer "In11.Cu")
		(net "JTAG_MCP_CPU0_TDI")
	)
	(arc
		(start 294.432736 -99.690682)
		(mid 294.434418 -99.29383)
		(end 294.093392 -99.090988)
		(width 0.089408)
		(layer "In11.Cu")
		(net "JTAG_MCP_CPU0_TDI")
	)
	(arc
		(start 293.579042 -93.243146)
		(mid 293.627706 -93.047048)
		(end 293.574216 -92.85224)
		(width 0.089408)
		(layer "In11.Cu")
		(net "JTAG_MCP_CPU0_TDI")
	)
	(arc
		(start 296.650664 -102.367588)
		(mid 296.456814 -102.311238)
		(end 296.31513 -102.167436)
		(width 0.089408)
		(layer "In11.Cu")
		(net "JTAG_MCP_CPU0_TDI")
	)
	(arc
		(start 293.574216 -94.242636)
		(mid 293.627749 -94.042738)
		(end 293.574216 -93.84284)
		(width 0.089408)
		(layer "In11.Cu")
		(net "JTAG_MCP_CPU0_TDI")
	)
	(arc
		(start 295.291256 -100.77704)
		(mid 295.119619 -100.555851)
		(end 294.847518 -100.49002)
		(width 0.089408)
		(layer "In11.Cu")
		(net "JTAG_MCP_CPU0_TDI")
	)
	(arc
		(start 293.574216 -93.84284)
		(mid 293.494901 -93.553468)
		(end 293.567866 -93.26245)
		(width 0.089408)
		(layer "In11.Cu")
		(net "JTAG_MCP_CPU0_TDI")
	)
	(arc
		(start 293.574216 -96.81464)
		(mid 293.494901 -96.525268)
		(end 293.567866 -96.23425)
		(width 0.089408)
		(layer "In11.Cu")
		(net "JTAG_MCP_CPU0_TDI")
	)
	(arc
		(start 294.847518 -100.49002)
		(mid 294.59778 -100.439627)
		(end 294.419528 -100.25761)
		(width 0.089408)
		(layer "In11.Cu")
		(net "JTAG_MCP_CPU0_TDI")
	)
	(arc
		(start 293.579042 -92.252546)
		(mid 293.574534 -91.862463)
		(end 293.239952 -91.661742)
		(width 0.089408)
		(layer "In11.Cu")
		(net "JTAG_MCP_CPU0_TDI")
	)
	(arc
		(start 290.140136 -82.94624)
		(mid 290.060821 -82.656868)
		(end 290.133786 -82.36585)
		(width 0.089408)
		(layer "In11.Cu")
		(net "JTAG_MCP_CPU0_TDI")
	)
	(arc
		(start 291.490146 -90.671142)
		(mid 291.206185 -90.587024)
		(end 290.998656 -90.37574)
		(width 0.089408)
		(layer "In11.Cu")
		(net "JTAG_MCP_CPU0_TDI")
	)
	(arc
		(start 293.574216 -97.80524)
		(mid 293.494901 -97.515868)
		(end 293.567866 -97.22485)
		(width 0.089408)
		(layer "In11.Cu")
		(net "JTAG_MCP_CPU0_TDI")
	)
	(arc
		(start 293.579042 -97.205546)
		(mid 293.627706 -97.009448)
		(end 293.574216 -96.81464)
		(width 0.089408)
		(layer "In11.Cu")
		(net "JTAG_MCP_CPU0_TDI")
	)
	(arc
		(start 290.62807 -90.175588)
		(mid 290.137267 -89.87543)
		(end 290.133786 -89.30005)
		(width 0.089408)
		(layer "In11.Cu")
		(net "JTAG_MCP_CPU0_TDI")
	)
	(arc
		(start 290.144962 -87.299546)
		(mid 290.193626 -87.103448)
		(end 290.140136 -86.90864)
		(width 0.089408)
		(layer "In11.Cu")
		(net "JTAG_MCP_CPU0_TDI")
	)
	(arc
		(start 294.419528 -100.25761)
		(mid 294.353778 -99.972474)
		(end 294.432736 -99.690682)
		(width 0.089408)
		(layer "In11.Cu")
		(net "JTAG_MCP_CPU0_TDI")
	)
	(arc
		(start 290.144962 -86.308946)
		(mid 290.193626 -86.112848)
		(end 290.140136 -85.91804)
		(width 0.089408)
		(layer "In11.Cu")
		(net "JTAG_MCP_CPU0_TDI")
	)
	(arc
		(start 290.144962 -83.337146)
		(mid 290.193626 -83.141048)
		(end 290.140136 -82.94624)
		(width 0.089408)
		(layer "In11.Cu")
		(net "JTAG_MCP_CPU0_TDI")
	)
	(arc
		(start 290.140136 -83.93684)
		(mid 290.060821 -83.647468)
		(end 290.133786 -83.35645)
		(width 0.089408)
		(layer "In11.Cu")
		(net "JTAG_MCP_CPU0_TDI")
	)
	(arc
		(start 293.579042 -96.214946)
		(mid 293.627706 -96.018848)
		(end 293.574216 -95.82404)
		(width 0.089408)
		(layer "In11.Cu")
		(net "JTAG_MCP_CPU0_TDI")
	)
	(arc
		(start 297.173904 -102.662482)
		(mid 296.967867 -102.452204)
		(end 296.68597 -102.367334)
		(width 0.089408)
		(layer "In11.Cu")
		(net "JTAG_MCP_CPU0_TDI")
	)
	(arc
		(start 293.207186 -91.661742)
		(mid 292.923225 -91.577624)
		(end 292.715696 -91.36634)
		(width 0.089408)
		(layer "In11.Cu")
		(net "JTAG_MCP_CPU0_TDI")
	)
	(arc
		(start 290.144962 -89.280746)
		(mid 290.193626 -89.084648)
		(end 290.140136 -88.88984)
		(width 0.089408)
		(layer "In11.Cu")
		(net "JTAG_MCP_CPU0_TDI")
	)
	(segment
		(start 416.402012 -50.938176)
		(end 416.454082 -50.886106)
		(width 0.10795)
		(layer "F.Cu")
		(net "FM_OCP_MEZZC_PRES_1V05_PCH_N")
	)
	(segment
		(start 417.46678 -47.592742)
		(end 417.35883 -47.484792)
		(width 0.10795)
		(layer "F.Cu")
		(net "FM_OCP_MEZZC_PRES_1V05_PCH_N")
	)
	(segment
		(start 417.46678 -48.904906)
		(end 417.46678 -47.592742)
		(width 0.10795)
		(layer "F.Cu")
		(net "FM_OCP_MEZZC_PRES_1V05_PCH_N")
	)
	(segment
		(start 416.454082 -50.886106)
		(end 416.454082 -50.780188)
		(width 0.10795)
		(layer "F.Cu")
		(net "FM_OCP_MEZZC_PRES_1V05_PCH_N")
	)
	(segment
		(start 416.402012 -51.43881)
		(end 416.402012 -50.938176)
		(width 0.10795)
		(layer "F.Cu")
		(net "FM_OCP_MEZZC_PRES_1V05_PCH_N")
	)
	(segment
		(start 417.35883 -47.484792)
		(end 417.184078 -47.484792)
		(width 0.10795)
		(layer "F.Cu")
		(net "FM_OCP_MEZZC_PRES_1V05_PCH_N")
	)
	(segment
		(start 384.76555 -100.41128)
		(end 385.26085 -100.181156)
		(width 0.10795)
		(layer "F.Cu")
		(net "FM_OCP_MEZZC_PRES_1V05_PCH_N")
	)
	(segment
		(start 416.454082 -50.780188)
		(end 416.769296 -50.464974)
		(width 0.10795)
		(layer "F.Cu")
		(net "FM_OCP_MEZZC_PRES_1V05_PCH_N")
	)
	(segment
		(start 416.769296 -49.60239)
		(end 417.46678 -48.904906)
		(width 0.10795)
		(layer "F.Cu")
		(net "FM_OCP_MEZZC_PRES_1V05_PCH_N")
	)
	(segment
		(start 416.769296 -50.464974)
		(end 416.769296 -49.60239)
		(width 0.10795)
		(layer "F.Cu")
		(net "FM_OCP_MEZZC_PRES_1V05_PCH_N")
	)
	(via
		(at 393.622022 -49.963578)
		(size 0.508)
		(drill 0.254)
		(layers "F.Cu" "B.Cu")
		(net "FM_OCP_MEZZC_PRES_1V05_PCH_N")
	)
	(via
		(at 385.26085 -100.181156)
		(size 0.508)
		(drill 0.254)
		(layers "F.Cu" "B.Cu")
		(net "FM_OCP_MEZZC_PRES_1V05_PCH_N")
	)
	(via
		(at 383.4892 -94.5642)
		(size 0.6604)
		(drill 0.3302)
		(layers "F.Cu" "B.Cu")
		(net "FM_OCP_MEZZC_PRES_1V05_PCH_N")
	)
	(via
		(at 417.184078 -47.484792)
		(size 0.508)
		(drill 0.254)
		(layers "F.Cu" "B.Cu")
		(net "FM_OCP_MEZZC_PRES_1V05_PCH_N")
	)
	(segment
		(start 383.4892 -94.5642)
		(end 383.543048 -94.510352)
		(width 0.10795)
		(layer "B.Cu")
		(net "FM_OCP_MEZZC_PRES_1V05_PCH_N")
	)
	(segment
		(start 383.543048 -89.438988)
		(end 383.36728 -89.26322)
		(width 0.10795)
		(layer "B.Cu")
		(net "FM_OCP_MEZZC_PRES_1V05_PCH_N")
	)
	(segment
		(start 385.1656 -99.31146)
		(end 385.1656 -99.344226)
		(width 0.0889)
		(layer "B.Cu")
		(net "FM_OCP_MEZZC_PRES_1V05_PCH_N")
	)
	(segment
		(start 385.40563 -99.798632)
		(end 385.42976 -99.88804)
		(width 0.0889)
		(layer "B.Cu")
		(net "FM_OCP_MEZZC_PRES_1V05_PCH_N")
	)
	(segment
		(start 383.6797 -96.725486)
		(end 383.6797 -96.768666)
		(width 0.0889)
		(layer "B.Cu")
		(net "FM_OCP_MEZZC_PRES_1V05_PCH_N")
	)
	(segment
		(start 384.178556 -86.635844)
		(end 384.178556 -85.73008)
		(width 0.10795)
		(layer "B.Cu")
		(net "FM_OCP_MEZZC_PRES_1V05_PCH_N")
	)
	(segment
		(start 384.178556 -85.73008)
		(end 384.289808 -85.618828)
		(width 0.10795)
		(layer "B.Cu")
		(net "FM_OCP_MEZZC_PRES_1V05_PCH_N")
	)
	(segment
		(start 383.4892 -94.5642)
		(end 383.9972 -95.0722)
		(width 0.10795)
		(layer "B.Cu")
		(net "FM_OCP_MEZZC_PRES_1V05_PCH_N")
	)
	(segment
		(start 383.53365 -88.71585)
		(end 383.53365 -87.28075)
		(width 0.10795)
		(layer "B.Cu")
		(net "FM_OCP_MEZZC_PRES_1V05_PCH_N")
	)
	(segment
		(start 384.175 -95.450406)
		(end 384.175 -95.899732)
		(width 0.0889)
		(layer "B.Cu")
		(net "FM_OCP_MEZZC_PRES_1V05_PCH_N")
	)
	(segment
		(start 383.36728 -88.88222)
		(end 383.53365 -88.71585)
		(width 0.10795)
		(layer "B.Cu")
		(net "FM_OCP_MEZZC_PRES_1V05_PCH_N")
	)
	(segment
		(start 384.175 -97.59442)
		(end 384.175 -97.627186)
		(width 0.0889)
		(layer "B.Cu")
		(net "FM_OCP_MEZZC_PRES_1V05_PCH_N")
	)
	(segment
		(start 383.36728 -89.26322)
		(end 383.36728 -88.88222)
		(width 0.10795)
		(layer "B.Cu")
		(net "FM_OCP_MEZZC_PRES_1V05_PCH_N")
	)
	(segment
		(start 383.543048 -94.510352)
		(end 383.543048 -89.438988)
		(width 0.10795)
		(layer "B.Cu")
		(net "FM_OCP_MEZZC_PRES_1V05_PCH_N")
	)
	(segment
		(start 383.9972 -95.0722)
		(end 383.9972 -95.272606)
		(width 0.10795)
		(layer "B.Cu")
		(net "FM_OCP_MEZZC_PRES_1V05_PCH_N")
	)
	(segment
		(start 384.6703 -98.45294)
		(end 384.6703 -98.485706)
		(width 0.0889)
		(layer "B.Cu")
		(net "FM_OCP_MEZZC_PRES_1V05_PCH_N")
	)
	(segment
		(start 385.42976 -99.88804)
		(end 385.26085 -100.181156)
		(width 0.0889)
		(layer "B.Cu")
		(net "FM_OCP_MEZZC_PRES_1V05_PCH_N")
	)
	(segment
		(start 383.53365 -87.28075)
		(end 384.178556 -86.635844)
		(width 0.10795)
		(layer "B.Cu")
		(net "FM_OCP_MEZZC_PRES_1V05_PCH_N")
	)
	(segment
		(start 383.9972 -95.272606)
		(end 384.175 -95.450406)
		(width 0.0889)
		(layer "B.Cu")
		(net "FM_OCP_MEZZC_PRES_1V05_PCH_N")
	)
	(arc
		(start 383.6797 -96.768666)
		(mid 383.763981 -97.051883)
		(end 383.974848 -97.258886)
		(width 0.0889)
		(layer "B.Cu")
		(net "FM_OCP_MEZZC_PRES_1V05_PCH_N")
	)
	(arc
		(start 384.6703 -98.485706)
		(mid 384.754581 -98.768923)
		(end 384.965448 -98.975926)
		(width 0.0889)
		(layer "B.Cu")
		(net "FM_OCP_MEZZC_PRES_1V05_PCH_N")
	)
	(arc
		(start 385.1656 -99.344226)
		(mid 385.233629 -99.598891)
		(end 385.40563 -99.798632)
		(width 0.0889)
		(layer "B.Cu")
		(net "FM_OCP_MEZZC_PRES_1V05_PCH_N")
	)
	(arc
		(start 384.470148 -98.117406)
		(mid 384.613952 -98.259089)
		(end 384.6703 -98.45294)
		(width 0.0889)
		(layer "B.Cu")
		(net "FM_OCP_MEZZC_PRES_1V05_PCH_N")
	)
	(arc
		(start 384.965448 -98.975926)
		(mid 385.109252 -99.117609)
		(end 385.1656 -99.31146)
		(width 0.0889)
		(layer "B.Cu")
		(net "FM_OCP_MEZZC_PRES_1V05_PCH_N")
	)
	(arc
		(start 383.974848 -96.235266)
		(mid 383.763984 -96.44227)
		(end 383.6797 -96.725486)
		(width 0.0889)
		(layer "B.Cu")
		(net "FM_OCP_MEZZC_PRES_1V05_PCH_N")
	)
	(arc
		(start 383.974848 -97.258886)
		(mid 384.118652 -97.400569)
		(end 384.175 -97.59442)
		(width 0.0889)
		(layer "B.Cu")
		(net "FM_OCP_MEZZC_PRES_1V05_PCH_N")
	)
	(arc
		(start 384.175 -97.627186)
		(mid 384.259281 -97.910403)
		(end 384.470148 -98.117406)
		(width 0.0889)
		(layer "B.Cu")
		(net "FM_OCP_MEZZC_PRES_1V05_PCH_N")
	)
	(arc
		(start 384.175 -95.899732)
		(mid 384.11865 -96.093582)
		(end 383.974848 -96.235266)
		(width 0.0889)
		(layer "B.Cu")
		(net "FM_OCP_MEZZC_PRES_1V05_PCH_N")
	)
	(segment
		(start 403.218142 -47.507398)
		(end 404.42134 -46.3042)
		(width 0.089408)
		(layer "In2.Cu")
		(net "FM_OCP_MEZZC_PRES_1V05_PCH_N")
	)
	(segment
		(start 415.785808 -47.252128)
		(end 416.103816 -47.570136)
		(width 0.089408)
		(layer "In2.Cu")
		(net "FM_OCP_MEZZC_PRES_1V05_PCH_N")
	)
	(segment
		(start 407.913078 -45.553376)
		(end 408.851608 -45.553376)
		(width 0.089408)
		(layer "In2.Cu")
		(net "FM_OCP_MEZZC_PRES_1V05_PCH_N")
	)
	(segment
		(start 411.300422 -45.781976)
		(end 411.479746 -45.9613)
		(width 0.089408)
		(layer "In2.Cu")
		(net "FM_OCP_MEZZC_PRES_1V05_PCH_N")
	)
	(segment
		(start 411.300168 -45.781976)
		(end 411.300422 -45.781976)
		(width 0.089408)
		(layer "In2.Cu")
		(net "FM_OCP_MEZZC_PRES_1V05_PCH_N")
	)
	(segment
		(start 394.4112 -49.1744)
		(end 394.4112 -48.5648)
		(width 0.089408)
		(layer "In2.Cu")
		(net "FM_OCP_MEZZC_PRES_1V05_PCH_N")
	)
	(segment
		(start 415.326322 -45.639228)
		(end 415.785808 -46.098714)
		(width 0.089408)
		(layer "In2.Cu")
		(net "FM_OCP_MEZZC_PRES_1V05_PCH_N")
	)
	(segment
		(start 411.479746 -45.9613)
		(end 412.624016 -45.9613)
		(width 0.089408)
		(layer "In2.Cu")
		(net "FM_OCP_MEZZC_PRES_1V05_PCH_N")
	)
	(segment
		(start 394.4112 -48.5648)
		(end 395.468602 -47.507398)
		(width 0.089408)
		(layer "In2.Cu")
		(net "FM_OCP_MEZZC_PRES_1V05_PCH_N")
	)
	(segment
		(start 416.103816 -47.570136)
		(end 417.098734 -47.570136)
		(width 0.089408)
		(layer "In2.Cu")
		(net "FM_OCP_MEZZC_PRES_1V05_PCH_N")
	)
	(segment
		(start 407.162254 -46.3042)
		(end 407.913078 -45.553376)
		(width 0.089408)
		(layer "In2.Cu")
		(net "FM_OCP_MEZZC_PRES_1V05_PCH_N")
	)
	(segment
		(start 417.098734 -47.570136)
		(end 417.184078 -47.484792)
		(width 0.089408)
		(layer "In2.Cu")
		(net "FM_OCP_MEZZC_PRES_1V05_PCH_N")
	)
	(segment
		(start 410.933138 -45.74667)
		(end 411.264862 -45.74667)
		(width 0.089408)
		(layer "In2.Cu")
		(net "FM_OCP_MEZZC_PRES_1V05_PCH_N")
	)
	(segment
		(start 404.42134 -46.3042)
		(end 407.162254 -46.3042)
		(width 0.089408)
		(layer "In2.Cu")
		(net "FM_OCP_MEZZC_PRES_1V05_PCH_N")
	)
	(segment
		(start 410.546296 -46.133512)
		(end 410.933138 -45.74667)
		(width 0.089408)
		(layer "In2.Cu")
		(net "FM_OCP_MEZZC_PRES_1V05_PCH_N")
	)
	(segment
		(start 393.622022 -49.963578)
		(end 394.4112 -49.1744)
		(width 0.089408)
		(layer "In2.Cu")
		(net "FM_OCP_MEZZC_PRES_1V05_PCH_N")
	)
	(segment
		(start 408.851608 -45.553376)
		(end 409.431744 -46.133512)
		(width 0.089408)
		(layer "In2.Cu")
		(net "FM_OCP_MEZZC_PRES_1V05_PCH_N")
	)
	(segment
		(start 412.946088 -45.639228)
		(end 415.326322 -45.639228)
		(width 0.089408)
		(layer "In2.Cu")
		(net "FM_OCP_MEZZC_PRES_1V05_PCH_N")
	)
	(segment
		(start 415.785808 -46.098714)
		(end 415.785808 -47.252128)
		(width 0.089408)
		(layer "In2.Cu")
		(net "FM_OCP_MEZZC_PRES_1V05_PCH_N")
	)
	(segment
		(start 395.468602 -47.507398)
		(end 403.218142 -47.507398)
		(width 0.089408)
		(layer "In2.Cu")
		(net "FM_OCP_MEZZC_PRES_1V05_PCH_N")
	)
	(segment
		(start 411.264862 -45.74667)
		(end 411.300168 -45.781976)
		(width 0.089408)
		(layer "In2.Cu")
		(net "FM_OCP_MEZZC_PRES_1V05_PCH_N")
	)
	(segment
		(start 412.624016 -45.9613)
		(end 412.946088 -45.639228)
		(width 0.089408)
		(layer "In2.Cu")
		(net "FM_OCP_MEZZC_PRES_1V05_PCH_N")
	)
	(segment
		(start 409.431744 -46.133512)
		(end 410.546296 -46.133512)
		(width 0.089408)
		(layer "In2.Cu")
		(net "FM_OCP_MEZZC_PRES_1V05_PCH_N")
	)
	(segment
		(start 383.451608 -92.332302)
		(end 383.232406 -92.1131)
		(width 0.089408)
		(layer "In9.Cu")
		(net "FM_OCP_MEZZC_PRES_1V05_PCH_N")
	)
	(segment
		(start 382.83261 -93.97619)
		(end 383.452116 -93.356684)
		(width 0.089408)
		(layer "In9.Cu")
		(net "FM_OCP_MEZZC_PRES_1V05_PCH_N")
	)
	(segment
		(start 386.331968 -85.417406)
		(end 387.515862 -85.417406)
		(width 0.089408)
		(layer "In9.Cu")
		(net "FM_OCP_MEZZC_PRES_1V05_PCH_N")
	)
	(segment
		(start 382.3843 -95.899732)
		(end 382.3843 -95.377)
		(width 0.0889)
		(layer "In9.Cu")
		(net "FM_OCP_MEZZC_PRES_1V05_PCH_N")
	)
	(segment
		(start 388.683246 -79.171546)
		(end 388.683246 -76.967588)
		(width 0.089408)
		(layer "In9.Cu")
		(net "FM_OCP_MEZZC_PRES_1V05_PCH_N")
	)
	(segment
		(start 388.246366 -82.977482)
		(end 388.246366 -82.09661)
		(width 0.089408)
		(layer "In9.Cu")
		(net "FM_OCP_MEZZC_PRES_1V05_PCH_N")
	)
	(segment
		(start 388.962392 -79.450692)
		(end 388.683246 -79.171546)
		(width 0.089408)
		(layer "In9.Cu")
		(net "FM_OCP_MEZZC_PRES_1V05_PCH_N")
	)
	(segment
		(start 388.776718 -84.15655)
		(end 388.776718 -83.507834)
		(width 0.089408)
		(layer "In9.Cu")
		(net "FM_OCP_MEZZC_PRES_1V05_PCH_N")
	)
	(segment
		(start 383.8702 -98.475292)
		(end 383.8702 -98.442526)
		(width 0.0889)
		(layer "In9.Cu")
		(net "FM_OCP_MEZZC_PRES_1V05_PCH_N")
	)
	(segment
		(start 382.3843 -95.377)
		(end 382.83261 -94.92869)
		(width 0.089408)
		(layer "In9.Cu")
		(net "FM_OCP_MEZZC_PRES_1V05_PCH_N")
	)
	(segment
		(start 393.622022 -50.270664)
		(end 393.622022 -49.963578)
		(width 0.089408)
		(layer "In9.Cu")
		(net "FM_OCP_MEZZC_PRES_1V05_PCH_N")
	)
	(segment
		(start 390.2202 -75.430634)
		(end 390.2202 -74.784966)
		(width 0.089408)
		(layer "In9.Cu")
		(net "FM_OCP_MEZZC_PRES_1V05_PCH_N")
	)
	(segment
		(start 384.3655 -99.333812)
		(end 384.3655 -99.301046)
		(width 0.0889)
		(layer "In9.Cu")
		(net "FM_OCP_MEZZC_PRES_1V05_PCH_N")
	)
	(segment
		(start 383.232406 -92.1131)
		(end 383.232406 -89.379806)
		(width 0.089408)
		(layer "In9.Cu")
		(net "FM_OCP_MEZZC_PRES_1V05_PCH_N")
	)
	(segment
		(start 390.124696 -74.689462)
		(end 390.124696 -74.205338)
		(width 0.089408)
		(layer "In9.Cu")
		(net "FM_OCP_MEZZC_PRES_1V05_PCH_N")
	)
	(segment
		(start 384.922776 -100.181156)
		(end 384.857752 -100.116132)
		(width 0.0889)
		(layer "In9.Cu")
		(net "FM_OCP_MEZZC_PRES_1V05_PCH_N")
	)
	(segment
		(start 383.452116 -93.356684)
		(end 383.452116 -92.49029)
		(width 0.089408)
		(layer "In9.Cu")
		(net "FM_OCP_MEZZC_PRES_1V05_PCH_N")
	)
	(segment
		(start 391.055352 -68.936362)
		(end 390.267698 -68.148708)
		(width 0.089408)
		(layer "In9.Cu")
		(net "FM_OCP_MEZZC_PRES_1V05_PCH_N")
	)
	(segment
		(start 393.82192 -62.23508)
		(end 393.82192 -53.768752)
		(width 0.089408)
		(layer "In9.Cu")
		(net "FM_OCP_MEZZC_PRES_1V05_PCH_N")
	)
	(segment
		(start 385.492244 -86.524592)
		(end 385.492244 -86.25713)
		(width 0.089408)
		(layer "In9.Cu")
		(net "FM_OCP_MEZZC_PRES_1V05_PCH_N")
	)
	(segment
		(start 385.26085 -100.181156)
		(end 384.922776 -100.181156)
		(width 0.0889)
		(layer "In9.Cu")
		(net "FM_OCP_MEZZC_PRES_1V05_PCH_N")
	)
	(segment
		(start 388.776718 -83.507834)
		(end 388.246366 -82.977482)
		(width 0.089408)
		(layer "In9.Cu")
		(net "FM_OCP_MEZZC_PRES_1V05_PCH_N")
	)
	(segment
		(start 390.2202 -74.784966)
		(end 390.124696 -74.689462)
		(width 0.089408)
		(layer "In9.Cu")
		(net "FM_OCP_MEZZC_PRES_1V05_PCH_N")
	)
	(segment
		(start 383.232406 -89.379806)
		(end 383.1844 -89.3318)
		(width 0.089408)
		(layer "In9.Cu")
		(net "FM_OCP_MEZZC_PRES_1V05_PCH_N")
	)
	(segment
		(start 382.83261 -94.92869)
		(end 382.83261 -93.97619)
		(width 0.089408)
		(layer "In9.Cu")
		(net "FM_OCP_MEZZC_PRES_1V05_PCH_N")
	)
	(segment
		(start 390.602724 -73.72731)
		(end 390.602724 -72.089264)
		(width 0.089408)
		(layer "In9.Cu")
		(net "FM_OCP_MEZZC_PRES_1V05_PCH_N")
	)
	(segment
		(start 388.962392 -81.380584)
		(end 388.962392 -79.450692)
		(width 0.089408)
		(layer "In9.Cu")
		(net "FM_OCP_MEZZC_PRES_1V05_PCH_N")
	)
	(segment
		(start 385.492244 -86.25713)
		(end 386.331968 -85.417406)
		(width 0.089408)
		(layer "In9.Cu")
		(net "FM_OCP_MEZZC_PRES_1V05_PCH_N")
	)
	(segment
		(start 393.059666 -53.006498)
		(end 393.059666 -50.83302)
		(width 0.089408)
		(layer "In9.Cu")
		(net "FM_OCP_MEZZC_PRES_1V05_PCH_N")
	)
	(segment
		(start 391.055352 -71.636636)
		(end 391.055352 -68.936362)
		(width 0.089408)
		(layer "In9.Cu")
		(net "FM_OCP_MEZZC_PRES_1V05_PCH_N")
	)
	(segment
		(start 393.059666 -50.83302)
		(end 393.622022 -50.270664)
		(width 0.089408)
		(layer "In9.Cu")
		(net "FM_OCP_MEZZC_PRES_1V05_PCH_N")
	)
	(segment
		(start 390.267698 -67.16268)
		(end 392.869928 -64.56045)
		(width 0.089408)
		(layer "In9.Cu")
		(net "FM_OCP_MEZZC_PRES_1V05_PCH_N")
	)
	(segment
		(start 383.451862 -92.411296)
		(end 383.451608 -92.411042)
		(width 0.089408)
		(layer "In9.Cu")
		(net "FM_OCP_MEZZC_PRES_1V05_PCH_N")
	)
	(segment
		(start 390.124696 -74.205338)
		(end 390.602724 -73.72731)
		(width 0.089408)
		(layer "In9.Cu")
		(net "FM_OCP_MEZZC_PRES_1V05_PCH_N")
	)
	(segment
		(start 390.602724 -72.089264)
		(end 391.055352 -71.636636)
		(width 0.089408)
		(layer "In9.Cu")
		(net "FM_OCP_MEZZC_PRES_1V05_PCH_N")
	)
	(segment
		(start 388.246366 -82.09661)
		(end 388.962392 -81.380584)
		(width 0.089408)
		(layer "In9.Cu")
		(net "FM_OCP_MEZZC_PRES_1V05_PCH_N")
	)
	(segment
		(start 383.451862 -92.490036)
		(end 383.451862 -92.411296)
		(width 0.089408)
		(layer "In9.Cu")
		(net "FM_OCP_MEZZC_PRES_1V05_PCH_N")
	)
	(segment
		(start 383.1844 -88.832436)
		(end 385.492244 -86.524592)
		(width 0.089408)
		(layer "In9.Cu")
		(net "FM_OCP_MEZZC_PRES_1V05_PCH_N")
	)
	(segment
		(start 382.8796 -96.758252)
		(end 382.8796 -96.725486)
		(width 0.0889)
		(layer "In9.Cu")
		(net "FM_OCP_MEZZC_PRES_1V05_PCH_N")
	)
	(segment
		(start 383.452116 -92.49029)
		(end 383.451862 -92.490036)
		(width 0.089408)
		(layer "In9.Cu")
		(net "FM_OCP_MEZZC_PRES_1V05_PCH_N")
	)
	(segment
		(start 392.869928 -64.56045)
		(end 392.869928 -63.187072)
		(width 0.089408)
		(layer "In9.Cu")
		(net "FM_OCP_MEZZC_PRES_1V05_PCH_N")
	)
	(segment
		(start 390.267698 -68.148708)
		(end 390.267698 -67.16268)
		(width 0.089408)
		(layer "In9.Cu")
		(net "FM_OCP_MEZZC_PRES_1V05_PCH_N")
	)
	(segment
		(start 383.3749 -97.616772)
		(end 383.3749 -97.584006)
		(width 0.0889)
		(layer "In9.Cu")
		(net "FM_OCP_MEZZC_PRES_1V05_PCH_N")
	)
	(segment
		(start 387.515862 -85.417406)
		(end 388.776718 -84.15655)
		(width 0.089408)
		(layer "In9.Cu")
		(net "FM_OCP_MEZZC_PRES_1V05_PCH_N")
	)
	(segment
		(start 383.451608 -92.411042)
		(end 383.451608 -92.332302)
		(width 0.089408)
		(layer "In9.Cu")
		(net "FM_OCP_MEZZC_PRES_1V05_PCH_N")
	)
	(segment
		(start 388.683246 -76.967588)
		(end 390.2202 -75.430634)
		(width 0.089408)
		(layer "In9.Cu")
		(net "FM_OCP_MEZZC_PRES_1V05_PCH_N")
	)
	(segment
		(start 392.869928 -63.187072)
		(end 393.82192 -62.23508)
		(width 0.089408)
		(layer "In9.Cu")
		(net "FM_OCP_MEZZC_PRES_1V05_PCH_N")
	)
	(segment
		(start 383.1844 -89.3318)
		(end 383.1844 -88.832436)
		(width 0.089408)
		(layer "In9.Cu")
		(net "FM_OCP_MEZZC_PRES_1V05_PCH_N")
	)
	(segment
		(start 393.82192 -53.768752)
		(end 393.059666 -53.006498)
		(width 0.089408)
		(layer "In9.Cu")
		(net "FM_OCP_MEZZC_PRES_1V05_PCH_N")
	)
	(arc
		(start 384.070352 -98.810826)
		(mid 383.926548 -98.669143)
		(end 383.8702 -98.475292)
		(width 0.0889)
		(layer "In9.Cu")
		(net "FM_OCP_MEZZC_PRES_1V05_PCH_N")
	)
	(arc
		(start 384.565652 -99.669346)
		(mid 384.421848 -99.527663)
		(end 384.3655 -99.333812)
		(width 0.0889)
		(layer "In9.Cu")
		(net "FM_OCP_MEZZC_PRES_1V05_PCH_N")
	)
	(arc
		(start 383.3749 -97.584006)
		(mid 383.290619 -97.300789)
		(end 383.079752 -97.093786)
		(width 0.0889)
		(layer "In9.Cu")
		(net "FM_OCP_MEZZC_PRES_1V05_PCH_N")
	)
	(arc
		(start 382.8796 -96.725486)
		(mid 382.795319 -96.442269)
		(end 382.584452 -96.235266)
		(width 0.0889)
		(layer "In9.Cu")
		(net "FM_OCP_MEZZC_PRES_1V05_PCH_N")
	)
	(arc
		(start 384.857752 -100.116132)
		(mid 384.765044 -99.857862)
		(end 384.565652 -99.669346)
		(width 0.0889)
		(layer "In9.Cu")
		(net "FM_OCP_MEZZC_PRES_1V05_PCH_N")
	)
	(arc
		(start 382.584452 -96.235266)
		(mid 382.440648 -96.093583)
		(end 382.3843 -95.899732)
		(width 0.0889)
		(layer "In9.Cu")
		(net "FM_OCP_MEZZC_PRES_1V05_PCH_N")
	)
	(arc
		(start 384.3655 -99.301046)
		(mid 384.281219 -99.017829)
		(end 384.070352 -98.810826)
		(width 0.0889)
		(layer "In9.Cu")
		(net "FM_OCP_MEZZC_PRES_1V05_PCH_N")
	)
	(arc
		(start 383.8702 -98.442526)
		(mid 383.785919 -98.159309)
		(end 383.575052 -97.952306)
		(width 0.0889)
		(layer "In9.Cu")
		(net "FM_OCP_MEZZC_PRES_1V05_PCH_N")
	)
	(arc
		(start 383.079752 -97.093786)
		(mid 382.935948 -96.952103)
		(end 382.8796 -96.758252)
		(width 0.0889)
		(layer "In9.Cu")
		(net "FM_OCP_MEZZC_PRES_1V05_PCH_N")
	)
	(arc
		(start 383.575052 -97.952306)
		(mid 383.431248 -97.810623)
		(end 383.3749 -97.616772)
		(width 0.0889)
		(layer "In9.Cu")
		(net "FM_OCP_MEZZC_PRES_1V05_PCH_N")
	)
	(segment
		(start 378.29109 -70.348856)
		(end 378.888244 -70.348856)
		(width 0.10795)
		(layer "F.Cu")
		(net "FM_MEM_EVENT_FUNC")
	)
	(segment
		(start 377.944888 -70.695058)
		(end 378.29109 -70.348856)
		(width 0.10795)
		(layer "F.Cu")
		(net "FM_MEM_EVENT_FUNC")
	)
	(segment
		(start 378.973588 -70.4342)
		(end 380.08433 -70.4342)
		(width 0.10795)
		(layer "F.Cu")
		(net "FM_MEM_EVENT_FUNC")
	)
	(segment
		(start 378.888244 -70.348856)
		(end 378.973588 -70.4342)
		(width 0.10795)
		(layer "F.Cu")
		(net "FM_MEM_EVENT_FUNC")
	)
	(segment
		(start 380.08433 -70.4342)
		(end 380.258828 -70.608698)
		(width 0.10795)
		(layer "F.Cu")
		(net "FM_MEM_EVENT_FUNC")
	)
	(via
		(at 380.258828 -70.608698)
		(size 0.508)
		(drill 0.254)
		(layers "F.Cu" "B.Cu")
		(net "FM_MEM_EVENT_FUNC")
	)
	(via
		(at 380.9746 -70.3834)
		(size 0.6604)
		(drill 0.3302)
		(layers "F.Cu" "B.Cu")
		(net "FM_MEM_EVENT_FUNC")
	)
	(segment
		(start 381.887984 -71.296276)
		(end 381.887984 -70.839584)
		(width 0.10795)
		(layer "B.Cu")
		(net "FM_MEM_EVENT_FUNC")
	)
	(segment
		(start 381.887984 -71.622158)
		(end 381.893826 -71.628)
		(width 0.10795)
		(layer "B.Cu")
		(net "FM_MEM_EVENT_FUNC")
	)
	(segment
		(start 381.893826 -71.628)
		(end 381.893826 -72.058276)
		(width 0.10795)
		(layer "B.Cu")
		(net "FM_MEM_EVENT_FUNC")
	)
	(segment
		(start 380.484126 -70.3834)
		(end 380.258828 -70.608698)
		(width 0.10795)
		(layer "B.Cu")
		(net "FM_MEM_EVENT_FUNC")
	)
	(segment
		(start 381.4318 -70.3834)
		(end 380.9746 -70.3834)
		(width 0.10795)
		(layer "B.Cu")
		(net "FM_MEM_EVENT_FUNC")
	)
	(segment
		(start 380.9746 -70.3834)
		(end 380.484126 -70.3834)
		(width 0.10795)
		(layer "B.Cu")
		(net "FM_MEM_EVENT_FUNC")
	)
	(segment
		(start 381.887984 -71.296276)
		(end 381.887984 -71.622158)
		(width 0.10795)
		(layer "B.Cu")
		(net "FM_MEM_EVENT_FUNC")
	)
	(segment
		(start 381.887984 -70.839584)
		(end 381.4318 -70.3834)
		(width 0.10795)
		(layer "B.Cu")
		(net "FM_MEM_EVENT_FUNC")
	)
	(segment
		(start 371.145308 -71.895208)
		(end 371.545104 -72.295004)
		(width 0.10795)
		(layer "F.Cu")
		(net "FM_CPU1_CD_PRES_N")
	)
	(via
		(at 426.4914 -70.846696)
		(size 0.508)
		(drill 0.254)
		(layers "F.Cu" "B.Cu")
		(net "FM_CPU1_CD_PRES_N")
	)
	(via
		(at 403.0853 -63.821818)
		(size 0.508)
		(drill 0.254)
		(layers "F.Cu" "B.Cu")
		(net "FM_CPU1_CD_PRES_N")
	)
	(via
		(at 469.138 -123.825)
		(size 0.508)
		(drill 0.254)
		(layers "F.Cu" "B.Cu")
		(net "FM_CPU1_CD_PRES_N")
	)
	(via
		(at 371.145308 -71.895208)
		(size 0.4572)
		(drill 0.2032)
		(layers "F.Cu" "B.Cu")
		(net "FM_CPU1_CD_PRES_N")
	)
	(via
		(at 423.291 -58.9026)
		(size 0.6604)
		(drill 0.3302)
		(layers "F.Cu" "B.Cu")
		(net "FM_CPU1_CD_PRES_N")
	)
	(segment
		(start 408.14244 -64.732154)
		(end 407.947876 -64.732154)
		(width 0.10795)
		(layer "B.Cu")
		(net "FM_CPU1_CD_PRES_N")
	)
	(segment
		(start 425.730416 -60.142628)
		(end 424.490388 -58.9026)
		(width 0.10795)
		(layer "B.Cu")
		(net "FM_CPU1_CD_PRES_N")
	)
	(segment
		(start 426.262292 -67.351148)
		(end 426.262292 -67.030854)
		(width 0.10795)
		(layer "B.Cu")
		(net "FM_CPU1_CD_PRES_N")
	)
	(segment
		(start 486.49128 -124.99848)
		(end 484.5812 -123.0884)
		(width 0.10795)
		(layer "B.Cu")
		(net "FM_CPU1_CD_PRES_N")
	)
	(segment
		(start 407.947876 -64.732154)
		(end 407.611072 -64.39535)
		(width 0.10795)
		(layer "B.Cu")
		(net "FM_CPU1_CD_PRES_N")
	)
	(segment
		(start 407.611072 -64.39535)
		(end 405.340312 -64.39535)
		(width 0.10795)
		(layer "B.Cu")
		(net "FM_CPU1_CD_PRES_N")
	)
	(segment
		(start 411.182312 -62.68339)
		(end 409.133548 -64.732154)
		(width 0.10795)
		(layer "B.Cu")
		(net "FM_CPU1_CD_PRES_N")
	)
	(segment
		(start 469.138 -123.444)
		(end 469.138 -123.825)
		(width 0.10795)
		(layer "B.Cu")
		(net "FM_CPU1_CD_PRES_N")
	)
	(segment
		(start 424.490388 -58.9026)
		(end 423.291 -58.9026)
		(width 0.10795)
		(layer "B.Cu")
		(net "FM_CPU1_CD_PRES_N")
	)
	(segment
		(start 408.938984 -64.732154)
		(end 408.93873 -64.7319)
		(width 0.10795)
		(layer "B.Cu")
		(net "FM_CPU1_CD_PRES_N")
	)
	(segment
		(start 405.340312 -64.39535)
		(end 404.283926 -63.338964)
		(width 0.10795)
		(layer "B.Cu")
		(net "FM_CPU1_CD_PRES_N")
	)
	(segment
		(start 426.262292 -67.030854)
		(end 426.262546 -67.0306)
		(width 0.10795)
		(layer "B.Cu")
		(net "FM_CPU1_CD_PRES_N")
	)
	(segment
		(start 473.492068 -122.63755)
		(end 469.94445 -122.63755)
		(width 0.10795)
		(layer "B.Cu")
		(net "FM_CPU1_CD_PRES_N")
	)
	(segment
		(start 417.744656 -60.525152)
		(end 415.83864 -60.525152)
		(width 0.10795)
		(layer "B.Cu")
		(net "FM_CPU1_CD_PRES_N")
	)
	(segment
		(start 426.262546 -66.857372)
		(end 426.262292 -66.857118)
		(width 0.10795)
		(layer "B.Cu")
		(net "FM_CPU1_CD_PRES_N")
	)
	(segment
		(start 408.142694 -64.7319)
		(end 408.14244 -64.732154)
		(width 0.10795)
		(layer "B.Cu")
		(net "FM_CPU1_CD_PRES_N")
	)
	(segment
		(start 476.188532 -122.390154)
		(end 475.927928 -122.12955)
		(width 0.10795)
		(layer "B.Cu")
		(net "FM_CPU1_CD_PRES_N")
	)
	(segment
		(start 423.291 -58.9026)
		(end 419.367208 -58.9026)
		(width 0.10795)
		(layer "B.Cu")
		(net "FM_CPU1_CD_PRES_N")
	)
	(segment
		(start 426.262292 -63.067946)
		(end 425.730416 -62.53607)
		(width 0.10795)
		(layer "B.Cu")
		(net "FM_CPU1_CD_PRES_N")
	)
	(segment
		(start 415.83864 -60.525152)
		(end 413.680402 -62.68339)
		(width 0.10795)
		(layer "B.Cu")
		(net "FM_CPU1_CD_PRES_N")
	)
	(segment
		(start 483.107746 -123.0884)
		(end 482.599746 -122.5804)
		(width 0.10795)
		(layer "B.Cu")
		(net "FM_CPU1_CD_PRES_N")
	)
	(segment
		(start 475.927928 -122.12955)
		(end 474.000068 -122.12955)
		(width 0.10795)
		(layer "B.Cu")
		(net "FM_CPU1_CD_PRES_N")
	)
	(segment
		(start 426.262292 -66.857118)
		(end 426.262292 -63.067946)
		(width 0.10795)
		(layer "B.Cu")
		(net "FM_CPU1_CD_PRES_N")
	)
	(segment
		(start 494.15192 -127.71374)
		(end 493.8141 -127.37592)
		(width 0.10795)
		(layer "B.Cu")
		(net "FM_CPU1_CD_PRES_N")
	)
	(segment
		(start 493.8141 -127.37592)
		(end 493.09274 -127.37592)
		(width 0.10795)
		(layer "B.Cu")
		(net "FM_CPU1_CD_PRES_N")
	)
	(segment
		(start 484.5812 -123.0884)
		(end 483.107746 -123.0884)
		(width 0.10795)
		(layer "B.Cu")
		(net "FM_CPU1_CD_PRES_N")
	)
	(segment
		(start 482.599746 -122.5804)
		(end 477.411796 -122.5804)
		(width 0.10795)
		(layer "B.Cu")
		(net "FM_CPU1_CD_PRES_N")
	)
	(segment
		(start 404.283926 -63.338964)
		(end 403.568154 -63.338964)
		(width 0.10795)
		(layer "B.Cu")
		(net "FM_CPU1_CD_PRES_N")
	)
	(segment
		(start 425.364656 -68.248784)
		(end 426.262292 -67.351148)
		(width 0.10795)
		(layer "B.Cu")
		(net "FM_CPU1_CD_PRES_N")
	)
	(segment
		(start 492.50854 -125.5903)
		(end 491.91672 -124.99848)
		(width 0.10795)
		(layer "B.Cu")
		(net "FM_CPU1_CD_PRES_N")
	)
	(segment
		(start 469.94445 -122.63755)
		(end 469.138 -123.444)
		(width 0.10795)
		(layer "B.Cu")
		(net "FM_CPU1_CD_PRES_N")
	)
	(segment
		(start 494.15192 -128.64592)
		(end 494.15192 -127.71374)
		(width 0.10795)
		(layer "B.Cu")
		(net "FM_CPU1_CD_PRES_N")
	)
	(segment
		(start 408.93873 -64.7319)
		(end 408.142694 -64.7319)
		(width 0.10795)
		(layer "B.Cu")
		(net "FM_CPU1_CD_PRES_N")
	)
	(segment
		(start 409.133548 -64.732154)
		(end 408.938984 -64.732154)
		(width 0.10795)
		(layer "B.Cu")
		(net "FM_CPU1_CD_PRES_N")
	)
	(segment
		(start 426.262546 -67.0306)
		(end 426.262546 -66.857372)
		(width 0.10795)
		(layer "B.Cu")
		(net "FM_CPU1_CD_PRES_N")
	)
	(segment
		(start 425.730416 -62.53607)
		(end 425.730416 -60.142628)
		(width 0.10795)
		(layer "B.Cu")
		(net "FM_CPU1_CD_PRES_N")
	)
	(segment
		(start 477.411796 -122.5804)
		(end 477.22155 -122.390154)
		(width 0.10795)
		(layer "B.Cu")
		(net "FM_CPU1_CD_PRES_N")
	)
	(segment
		(start 492.50854 -126.79172)
		(end 492.50854 -125.5903)
		(width 0.10795)
		(layer "B.Cu")
		(net "FM_CPU1_CD_PRES_N")
	)
	(segment
		(start 419.367208 -58.9026)
		(end 417.744656 -60.525152)
		(width 0.10795)
		(layer "B.Cu")
		(net "FM_CPU1_CD_PRES_N")
	)
	(segment
		(start 413.680402 -62.68339)
		(end 411.182312 -62.68339)
		(width 0.10795)
		(layer "B.Cu")
		(net "FM_CPU1_CD_PRES_N")
	)
	(segment
		(start 491.91672 -124.99848)
		(end 486.49128 -124.99848)
		(width 0.10795)
		(layer "B.Cu")
		(net "FM_CPU1_CD_PRES_N")
	)
	(segment
		(start 403.568154 -63.338964)
		(end 403.0853 -63.821818)
		(width 0.10795)
		(layer "B.Cu")
		(net "FM_CPU1_CD_PRES_N")
	)
	(segment
		(start 477.22155 -122.390154)
		(end 476.188532 -122.390154)
		(width 0.10795)
		(layer "B.Cu")
		(net "FM_CPU1_CD_PRES_N")
	)
	(segment
		(start 425.364656 -69.719952)
		(end 425.364656 -68.248784)
		(width 0.10795)
		(layer "B.Cu")
		(net "FM_CPU1_CD_PRES_N")
	)
	(segment
		(start 493.09274 -127.37592)
		(end 492.50854 -126.79172)
		(width 0.10795)
		(layer "B.Cu")
		(net "FM_CPU1_CD_PRES_N")
	)
	(segment
		(start 495.01552 -131.8895)
		(end 495.01552 -129.50952)
		(width 0.10795)
		(layer "B.Cu")
		(net "FM_CPU1_CD_PRES_N")
	)
	(segment
		(start 495.01552 -129.50952)
		(end 494.15192 -128.64592)
		(width 0.10795)
		(layer "B.Cu")
		(net "FM_CPU1_CD_PRES_N")
	)
	(segment
		(start 474.000068 -122.12955)
		(end 473.492068 -122.63755)
		(width 0.10795)
		(layer "B.Cu")
		(net "FM_CPU1_CD_PRES_N")
	)
	(segment
		(start 426.4914 -70.846696)
		(end 425.364656 -69.719952)
		(width 0.10795)
		(layer "B.Cu")
		(net "FM_CPU1_CD_PRES_N")
	)
	(segment
		(start 373.681244 -65.658746)
		(end 373.623078 -65.716912)
		(width 0.089408)
		(layer "In4.Cu")
		(net "FM_CPU1_CD_PRES_N")
	)
	(segment
		(start 373.623078 -65.716912)
		(end 371.367812 -65.716912)
		(width 0.089408)
		(layer "In4.Cu")
		(net "FM_CPU1_CD_PRES_N")
	)
	(segment
		(start 469.138 -123.825)
		(end 469.138 -118.311168)
		(width 0.089408)
		(layer "In4.Cu")
		(net "FM_CPU1_CD_PRES_N")
	)
	(segment
		(start 427.645068 -120.726708)
		(end 427.644814 -120.726454)
		(width 0.089408)
		(layer "In4.Cu")
		(net "FM_CPU1_CD_PRES_N")
	)
	(segment
		(start 423.841672 -110.73257)
		(end 424.270678 -110.303564)
		(width 0.089408)
		(layer "In4.Cu")
		(net "FM_CPU1_CD_PRES_N")
	)
	(segment
		(start 427.644814 -120.726454)
		(end 424.548046 -120.726454)
		(width 0.089408)
		(layer "In4.Cu")
		(net "FM_CPU1_CD_PRES_N")
	)
	(segment
		(start 423.757598 -116.991638)
		(end 421.587168 -116.991638)
		(width 0.089408)
		(layer "In4.Cu")
		(net "FM_CPU1_CD_PRES_N")
	)
	(segment
		(start 434.009546 -120.726454)
		(end 428.20463 -120.726454)
		(width 0.089408)
		(layer "In4.Cu")
		(net "FM_CPU1_CD_PRES_N")
	)
	(segment
		(start 424.355006 -120.533414)
		(end 424.355006 -119.856504)
		(width 0.089408)
		(layer "In4.Cu")
		(net "FM_CPU1_CD_PRES_N")
	)
	(segment
		(start 377.980448 -64.957452)
		(end 377.324874 -64.957452)
		(width 0.089408)
		(layer "In4.Cu")
		(net "FM_CPU1_CD_PRES_N")
	)
	(segment
		(start 377.324874 -64.957452)
		(end 377.18111 -64.813688)
		(width 0.089408)
		(layer "In4.Cu")
		(net "FM_CPU1_CD_PRES_N")
	)
	(segment
		(start 421.587168 -116.991638)
		(end 421.259 -116.66347)
		(width 0.089408)
		(layer "In4.Cu")
		(net "FM_CPU1_CD_PRES_N")
	)
	(segment
		(start 399.391886 -63.385192)
		(end 398.23771 -62.231016)
		(width 0.089408)
		(layer "In4.Cu")
		(net "FM_CPU1_CD_PRES_N")
	)
	(segment
		(start 423.039794 -110.537752)
		(end 423.234612 -110.73257)
		(width 0.089408)
		(layer "In4.Cu")
		(net "FM_CPU1_CD_PRES_N")
	)
	(segment
		(start 367.571782 -67.996816)
		(end 367.300002 -68.268596)
		(width 0.089408)
		(layer "In4.Cu")
		(net "FM_CPU1_CD_PRES_N")
	)
	(segment
		(start 368.705892 -67.20332)
		(end 368.538252 -67.37096)
		(width 0.089408)
		(layer "In4.Cu")
		(net "FM_CPU1_CD_PRES_N")
	)
	(segment
		(start 442.341 -117.729)
		(end 437.007 -117.729)
		(width 0.089408)
		(layer "In4.Cu")
		(net "FM_CPU1_CD_PRES_N")
	)
	(segment
		(start 423.91584 -116.991384)
		(end 423.757852 -116.991384)
		(width 0.089408)
		(layer "In4.Cu")
		(net "FM_CPU1_CD_PRES_N")
	)
	(segment
		(start 424.82897 -119.38254)
		(end 424.82897 -117.817646)
		(width 0.089408)
		(layer "In4.Cu")
		(net "FM_CPU1_CD_PRES_N")
	)
	(segment
		(start 368.538252 -67.37096)
		(end 367.941352 -67.37096)
		(width 0.089408)
		(layer "In4.Cu")
		(net "FM_CPU1_CD_PRES_N")
	)
	(segment
		(start 463.360516 -117.019832)
		(end 443.050168 -117.019832)
		(width 0.089408)
		(layer "In4.Cu")
		(net "FM_CPU1_CD_PRES_N")
	)
	(segment
		(start 403.0853 -63.821818)
		(end 402.648674 -63.385192)
		(width 0.089408)
		(layer "In4.Cu")
		(net "FM_CPU1_CD_PRES_N")
	)
	(segment
		(start 423.234612 -110.73257)
		(end 423.841672 -110.73257)
		(width 0.089408)
		(layer "In4.Cu")
		(net "FM_CPU1_CD_PRES_N")
	)
	(segment
		(start 428.20463 -120.726454)
		(end 428.204376 -120.726708)
		(width 0.089408)
		(layer "In4.Cu")
		(net "FM_CPU1_CD_PRES_N")
	)
	(segment
		(start 378.752608 -64.185292)
		(end 377.980448 -64.957452)
		(width 0.089408)
		(layer "In4.Cu")
		(net "FM_CPU1_CD_PRES_N")
	)
	(segment
		(start 367.300002 -68.268596)
		(end 366.243616 -68.268596)
		(width 0.089408)
		(layer "In4.Cu")
		(net "FM_CPU1_CD_PRES_N")
	)
	(segment
		(start 424.270678 -108.513118)
		(end 425.216828 -107.566968)
		(width 0.089408)
		(layer "In4.Cu")
		(net "FM_CPU1_CD_PRES_N")
	)
	(segment
		(start 389.20039 -63.829438)
		(end 386.664708 -63.829438)
		(width 0.089408)
		(layer "In4.Cu")
		(net "FM_CPU1_CD_PRES_N")
	)
	(segment
		(start 366.720882 -72.268842)
		(end 370.771674 -72.268842)
		(width 0.089408)
		(layer "In4.Cu")
		(net "FM_CPU1_CD_PRES_N")
	)
	(segment
		(start 443.050168 -117.019832)
		(end 442.341 -117.729)
		(width 0.089408)
		(layer "In4.Cu")
		(net "FM_CPU1_CD_PRES_N")
	)
	(segment
		(start 402.648674 -63.385192)
		(end 399.391886 -63.385192)
		(width 0.089408)
		(layer "In4.Cu")
		(net "FM_CPU1_CD_PRES_N")
	)
	(segment
		(start 365.781082 -71.329042)
		(end 366.720882 -72.268842)
		(width 0.089408)
		(layer "In4.Cu")
		(net "FM_CPU1_CD_PRES_N")
	)
	(segment
		(start 393.895326 -63.65748)
		(end 389.372348 -63.65748)
		(width 0.089408)
		(layer "In4.Cu")
		(net "FM_CPU1_CD_PRES_N")
	)
	(segment
		(start 425.216828 -107.566968)
		(end 425.216828 -72.121268)
		(width 0.089408)
		(layer "In4.Cu")
		(net "FM_CPU1_CD_PRES_N")
	)
	(segment
		(start 383.220976 -65.034668)
		(end 381.934212 -65.034668)
		(width 0.089408)
		(layer "In4.Cu")
		(net "FM_CPU1_CD_PRES_N")
	)
	(segment
		(start 381.084836 -64.185292)
		(end 378.752608 -64.185292)
		(width 0.089408)
		(layer "In4.Cu")
		(net "FM_CPU1_CD_PRES_N")
	)
	(segment
		(start 367.941352 -67.37096)
		(end 367.571782 -67.74053)
		(width 0.089408)
		(layer "In4.Cu")
		(net "FM_CPU1_CD_PRES_N")
	)
	(segment
		(start 424.355006 -119.856504)
		(end 424.82897 -119.38254)
		(width 0.089408)
		(layer "In4.Cu")
		(net "FM_CPU1_CD_PRES_N")
	)
	(segment
		(start 425.216828 -72.121268)
		(end 426.4914 -70.846696)
		(width 0.089408)
		(layer "In4.Cu")
		(net "FM_CPU1_CD_PRES_N")
	)
	(segment
		(start 367.571782 -67.74053)
		(end 367.571782 -67.996816)
		(width 0.089408)
		(layer "In4.Cu")
		(net "FM_CPU1_CD_PRES_N")
	)
	(segment
		(start 371.367812 -65.716912)
		(end 369.881404 -67.20332)
		(width 0.089408)
		(layer "In4.Cu")
		(net "FM_CPU1_CD_PRES_N")
	)
	(segment
		(start 428.204376 -120.726708)
		(end 427.645068 -120.726708)
		(width 0.089408)
		(layer "In4.Cu")
		(net "FM_CPU1_CD_PRES_N")
	)
	(segment
		(start 385.075684 -65.418462)
		(end 383.60477 -65.418462)
		(width 0.089408)
		(layer "In4.Cu")
		(net "FM_CPU1_CD_PRES_N")
	)
	(segment
		(start 469.138 -118.311168)
		(end 468.989664 -118.162832)
		(width 0.089408)
		(layer "In4.Cu")
		(net "FM_CPU1_CD_PRES_N")
	)
	(segment
		(start 386.664708 -63.829438)
		(end 385.075684 -65.418462)
		(width 0.089408)
		(layer "In4.Cu")
		(net "FM_CPU1_CD_PRES_N")
	)
	(segment
		(start 366.243616 -68.268596)
		(end 365.781082 -68.73113)
		(width 0.089408)
		(layer "In4.Cu")
		(net "FM_CPU1_CD_PRES_N")
	)
	(segment
		(start 369.881404 -67.20332)
		(end 368.705892 -67.20332)
		(width 0.089408)
		(layer "In4.Cu")
		(net "FM_CPU1_CD_PRES_N")
	)
	(segment
		(start 370.771674 -72.268842)
		(end 371.145308 -71.895208)
		(width 0.089408)
		(layer "In4.Cu")
		(net "FM_CPU1_CD_PRES_N")
	)
	(segment
		(start 421.259 -111.07928)
		(end 421.800528 -110.537752)
		(width 0.089408)
		(layer "In4.Cu")
		(net "FM_CPU1_CD_PRES_N")
	)
	(segment
		(start 421.800528 -110.537752)
		(end 423.039794 -110.537752)
		(width 0.089408)
		(layer "In4.Cu")
		(net "FM_CPU1_CD_PRES_N")
	)
	(segment
		(start 437.007 -117.729)
		(end 434.009546 -120.726454)
		(width 0.089408)
		(layer "In4.Cu")
		(net "FM_CPU1_CD_PRES_N")
	)
	(segment
		(start 398.23771 -62.231016)
		(end 395.32179 -62.231016)
		(width 0.089408)
		(layer "In4.Cu")
		(net "FM_CPU1_CD_PRES_N")
	)
	(segment
		(start 468.989664 -118.162832)
		(end 464.503516 -118.162832)
		(width 0.089408)
		(layer "In4.Cu")
		(net "FM_CPU1_CD_PRES_N")
	)
	(segment
		(start 424.002962 -116.991638)
		(end 423.916094 -116.991638)
		(width 0.089408)
		(layer "In4.Cu")
		(net "FM_CPU1_CD_PRES_N")
	)
	(segment
		(start 464.503516 -118.162832)
		(end 463.360516 -117.019832)
		(width 0.089408)
		(layer "In4.Cu")
		(net "FM_CPU1_CD_PRES_N")
	)
	(segment
		(start 375.59869 -65.658746)
		(end 373.681244 -65.658746)
		(width 0.089408)
		(layer "In4.Cu")
		(net "FM_CPU1_CD_PRES_N")
	)
	(segment
		(start 424.270678 -110.303564)
		(end 424.270678 -108.513118)
		(width 0.089408)
		(layer "In4.Cu")
		(net "FM_CPU1_CD_PRES_N")
	)
	(segment
		(start 389.372348 -63.65748)
		(end 389.20039 -63.829438)
		(width 0.089408)
		(layer "In4.Cu")
		(net "FM_CPU1_CD_PRES_N")
	)
	(segment
		(start 395.32179 -62.231016)
		(end 393.895326 -63.65748)
		(width 0.089408)
		(layer "In4.Cu")
		(net "FM_CPU1_CD_PRES_N")
	)
	(segment
		(start 421.259 -116.66347)
		(end 421.259 -111.07928)
		(width 0.089408)
		(layer "In4.Cu")
		(net "FM_CPU1_CD_PRES_N")
	)
	(segment
		(start 424.82897 -117.817646)
		(end 424.002962 -116.991638)
		(width 0.089408)
		(layer "In4.Cu")
		(net "FM_CPU1_CD_PRES_N")
	)
	(segment
		(start 376.443748 -64.813688)
		(end 375.59869 -65.658746)
		(width 0.089408)
		(layer "In4.Cu")
		(net "FM_CPU1_CD_PRES_N")
	)
	(segment
		(start 383.60477 -65.418462)
		(end 383.220976 -65.034668)
		(width 0.089408)
		(layer "In4.Cu")
		(net "FM_CPU1_CD_PRES_N")
	)
	(segment
		(start 365.781082 -68.73113)
		(end 365.781082 -71.329042)
		(width 0.089408)
		(layer "In4.Cu")
		(net "FM_CPU1_CD_PRES_N")
	)
	(segment
		(start 424.548046 -120.726454)
		(end 424.355006 -120.533414)
		(width 0.089408)
		(layer "In4.Cu")
		(net "FM_CPU1_CD_PRES_N")
	)
	(segment
		(start 381.934212 -65.034668)
		(end 381.084836 -64.185292)
		(width 0.089408)
		(layer "In4.Cu")
		(net "FM_CPU1_CD_PRES_N")
	)
	(segment
		(start 423.757852 -116.991384)
		(end 423.757598 -116.991638)
		(width 0.089408)
		(layer "In4.Cu")
		(net "FM_CPU1_CD_PRES_N")
	)
	(segment
		(start 423.916094 -116.991638)
		(end 423.91584 -116.991384)
		(width 0.089408)
		(layer "In4.Cu")
		(net "FM_CPU1_CD_PRES_N")
	)
	(segment
		(start 377.18111 -64.813688)
		(end 376.443748 -64.813688)
		(width 0.089408)
		(layer "In4.Cu")
		(net "FM_CPU1_CD_PRES_N")
	)
	(segment
		(start 425.704 -74.9554)
		(end 426.4914 -74.168)
		(width 0.10795)
		(layer "F.Cu")
		(net "FM_CPU0_OR_CPU1_MCP_PRES")
	)
	(segment
		(start 465.8868 -139.573)
		(end 466.09 -139.7762)
		(width 0.10795)
		(layer "F.Cu")
		(net "FM_CPU0_OR_CPU1_MCP_PRES")
	)
	(segment
		(start 426.438314 -109.691678)
		(end 426.438314 -78.67396)
		(width 0.10795)
		(layer "F.Cu")
		(net "FM_CPU0_OR_CPU1_MCP_PRES")
	)
	(segment
		(start 437.989726 -112.166654)
		(end 436.597298 -110.774226)
		(width 0.10795)
		(layer "F.Cu")
		(net "FM_CPU0_OR_CPU1_MCP_PRES")
	)
	(segment
		(start 427.520862 -110.774226)
		(end 426.438314 -109.691678)
		(width 0.10795)
		(layer "F.Cu")
		(net "FM_CPU0_OR_CPU1_MCP_PRES")
	)
	(segment
		(start 370.745004 -68.295012)
		(end 370.357908 -68.682108)
		(width 0.10795)
		(layer "F.Cu")
		(net "FM_CPU0_OR_CPU1_MCP_PRES")
	)
	(segment
		(start 466.344 -137.033)
		(end 466.344 -137.7188)
		(width 0.10795)
		(layer "F.Cu")
		(net "FM_CPU0_OR_CPU1_MCP_PRES")
	)
	(segment
		(start 426.438314 -78.67396)
		(end 425.704 -77.939646)
		(width 0.10795)
		(layer "F.Cu")
		(net "FM_CPU0_OR_CPU1_MCP_PRES")
	)
	(segment
		(start 425.704 -77.939646)
		(end 425.704 -74.9554)
		(width 0.10795)
		(layer "F.Cu")
		(net "FM_CPU0_OR_CPU1_MCP_PRES")
	)
	(segment
		(start 436.597298 -110.774226)
		(end 427.520862 -110.774226)
		(width 0.10795)
		(layer "F.Cu")
		(net "FM_CPU0_OR_CPU1_MCP_PRES")
	)
	(segment
		(start 465.8868 -138.176)
		(end 465.8868 -139.573)
		(width 0.10795)
		(layer "F.Cu")
		(net "FM_CPU0_OR_CPU1_MCP_PRES")
	)
	(segment
		(start 466.344 -137.7188)
		(end 465.8868 -138.176)
		(width 0.10795)
		(layer "F.Cu")
		(net "FM_CPU0_OR_CPU1_MCP_PRES")
	)
	(via
		(at 437.989726 -112.166654)
		(size 0.508)
		(drill 0.254)
		(layers "F.Cu" "B.Cu")
		(net "FM_CPU0_OR_CPU1_MCP_PRES")
	)
	(via
		(at 461.7593 -131.445)
		(size 0.6604)
		(drill 0.3302)
		(layers "F.Cu" "B.Cu")
		(net "FM_CPU0_OR_CPU1_MCP_PRES")
	)
	(via
		(at 492.72063 -113.04397)
		(size 0.508)
		(drill 0.254)
		(layers "F.Cu" "B.Cu")
		(net "FM_CPU0_OR_CPU1_MCP_PRES")
	)
	(via
		(at 409.01366 -67.399408)
		(size 0.508)
		(drill 0.254)
		(layers "F.Cu" "B.Cu")
		(net "FM_CPU0_OR_CPU1_MCP_PRES")
	)
	(via
		(at 426.4914 -74.168)
		(size 0.508)
		(drill 0.254)
		(layers "F.Cu" "B.Cu")
		(net "FM_CPU0_OR_CPU1_MCP_PRES")
	)
	(via
		(at 370.357908 -68.682108)
		(size 0.4572)
		(drill 0.2032)
		(layers "F.Cu" "B.Cu")
		(net "FM_CPU0_OR_CPU1_MCP_PRES")
	)
	(via
		(at 464.3628 -131.826)
		(size 0.508)
		(drill 0.254)
		(layers "F.Cu" "B.Cu")
		(net "FM_CPU0_OR_CPU1_MCP_PRES")
	)
	(via
		(at 466.09 -139.7762)
		(size 0.508)
		(drill 0.254)
		(layers "F.Cu" "B.Cu")
		(net "FM_CPU0_OR_CPU1_MCP_PRES")
	)
	(segment
		(start 464.3374 -131.8514)
		(end 463.423 -131.8514)
		(width 0.10795)
		(layer "B.Cu")
		(net "FM_CPU0_OR_CPU1_MCP_PRES")
	)
	(segment
		(start 424.581066 -62.99327)
		(end 424.81119 -63.223394)
		(width 0.10795)
		(layer "B.Cu")
		(net "FM_CPU0_OR_CPU1_MCP_PRES")
	)
	(segment
		(start 454.7616 -129.5908)
		(end 454.4822 -129.3114)
		(width 0.10795)
		(layer "B.Cu")
		(net "FM_CPU0_OR_CPU1_MCP_PRES")
	)
	(segment
		(start 455.7268 -130.708146)
		(end 455.7268 -130.048)
		(width 0.10795)
		(layer "B.Cu")
		(net "FM_CPU0_OR_CPU1_MCP_PRES")
	)
	(segment
		(start 413.112204 -63.914782)
		(end 414.078166 -63.914782)
		(width 0.10795)
		(layer "B.Cu")
		(net "FM_CPU0_OR_CPU1_MCP_PRES")
	)
	(segment
		(start 424.240706 -67.78244)
		(end 424.240706 -70.53199)
		(width 0.10795)
		(layer "B.Cu")
		(net "FM_CPU0_OR_CPU1_MCP_PRES")
	)
	(segment
		(start 414.078166 -63.914782)
		(end 416.080448 -61.9125)
		(width 0.10795)
		(layer "B.Cu")
		(net "FM_CPU0_OR_CPU1_MCP_PRES")
	)
	(segment
		(start 426.4914 -74.130408)
		(end 426.4914 -74.168)
		(width 0.10795)
		(layer "B.Cu")
		(net "FM_CPU0_OR_CPU1_MCP_PRES")
	)
	(segment
		(start 424.581066 -61.040518)
		(end 424.581066 -62.99327)
		(width 0.10795)
		(layer "B.Cu")
		(net "FM_CPU0_OR_CPU1_MCP_PRES")
	)
	(segment
		(start 455.2696 -129.5908)
		(end 454.7616 -129.5908)
		(width 0.10795)
		(layer "B.Cu")
		(net "FM_CPU0_OR_CPU1_MCP_PRES")
	)
	(segment
		(start 424.81119 -63.223394)
		(end 424.81119 -67.211956)
		(width 0.10795)
		(layer "B.Cu")
		(net "FM_CPU0_OR_CPU1_MCP_PRES")
	)
	(segment
		(start 455.7268 -130.048)
		(end 455.2696 -129.5908)
		(width 0.10795)
		(layer "B.Cu")
		(net "FM_CPU0_OR_CPU1_MCP_PRES")
	)
	(segment
		(start 409.302458 -67.11061)
		(end 410.80817 -67.11061)
		(width 0.10795)
		(layer "B.Cu")
		(net "FM_CPU0_OR_CPU1_MCP_PRES")
	)
	(segment
		(start 412.5341 -64.492886)
		(end 413.112204 -63.914782)
		(width 0.10795)
		(layer "B.Cu")
		(net "FM_CPU0_OR_CPU1_MCP_PRES")
	)
	(segment
		(start 425.31665 -71.607934)
		(end 425.31665 -72.955658)
		(width 0.10795)
		(layer "B.Cu")
		(net "FM_CPU0_OR_CPU1_MCP_PRES")
	)
	(segment
		(start 461.7593 -131.445)
		(end 460.8322 -131.445)
		(width 0.10795)
		(layer "B.Cu")
		(net "FM_CPU0_OR_CPU1_MCP_PRES")
	)
	(segment
		(start 409.01366 -67.399408)
		(end 409.302458 -67.11061)
		(width 0.10795)
		(layer "B.Cu")
		(net "FM_CPU0_OR_CPU1_MCP_PRES")
	)
	(segment
		(start 460.4766 -131.8006)
		(end 456.819254 -131.8006)
		(width 0.10795)
		(layer "B.Cu")
		(net "FM_CPU0_OR_CPU1_MCP_PRES")
	)
	(segment
		(start 463.423 -131.8514)
		(end 463.0166 -131.445)
		(width 0.10795)
		(layer "B.Cu")
		(net "FM_CPU0_OR_CPU1_MCP_PRES")
	)
	(segment
		(start 422.105582 -60.680346)
		(end 424.220894 -60.680346)
		(width 0.10795)
		(layer "B.Cu")
		(net "FM_CPU0_OR_CPU1_MCP_PRES")
	)
	(segment
		(start 456.819254 -131.8006)
		(end 455.7268 -130.708146)
		(width 0.10795)
		(layer "B.Cu")
		(net "FM_CPU0_OR_CPU1_MCP_PRES")
	)
	(segment
		(start 424.81119 -67.211956)
		(end 424.240706 -67.78244)
		(width 0.10795)
		(layer "B.Cu")
		(net "FM_CPU0_OR_CPU1_MCP_PRES")
	)
	(segment
		(start 425.31665 -72.955658)
		(end 426.4914 -74.130408)
		(width 0.10795)
		(layer "B.Cu")
		(net "FM_CPU0_OR_CPU1_MCP_PRES")
	)
	(segment
		(start 424.220894 -60.680346)
		(end 424.581066 -61.040518)
		(width 0.10795)
		(layer "B.Cu")
		(net "FM_CPU0_OR_CPU1_MCP_PRES")
	)
	(segment
		(start 416.080448 -61.9125)
		(end 420.873428 -61.9125)
		(width 0.10795)
		(layer "B.Cu")
		(net "FM_CPU0_OR_CPU1_MCP_PRES")
	)
	(segment
		(start 454.4822 -129.3114)
		(end 454.4822 -128.6764)
		(width 0.10795)
		(layer "B.Cu")
		(net "FM_CPU0_OR_CPU1_MCP_PRES")
	)
	(segment
		(start 412.5341 -65.38468)
		(end 412.5341 -64.492886)
		(width 0.10795)
		(layer "B.Cu")
		(net "FM_CPU0_OR_CPU1_MCP_PRES")
	)
	(segment
		(start 464.3628 -131.826)
		(end 464.3374 -131.8514)
		(width 0.10795)
		(layer "B.Cu")
		(net "FM_CPU0_OR_CPU1_MCP_PRES")
	)
	(segment
		(start 424.240706 -70.53199)
		(end 425.31665 -71.607934)
		(width 0.10795)
		(layer "B.Cu")
		(net "FM_CPU0_OR_CPU1_MCP_PRES")
	)
	(segment
		(start 460.8322 -131.445)
		(end 460.4766 -131.8006)
		(width 0.10795)
		(layer "B.Cu")
		(net "FM_CPU0_OR_CPU1_MCP_PRES")
	)
	(segment
		(start 410.80817 -67.11061)
		(end 412.5341 -65.38468)
		(width 0.10795)
		(layer "B.Cu")
		(net "FM_CPU0_OR_CPU1_MCP_PRES")
	)
	(segment
		(start 463.0166 -131.445)
		(end 461.7593 -131.445)
		(width 0.10795)
		(layer "B.Cu")
		(net "FM_CPU0_OR_CPU1_MCP_PRES")
	)
	(segment
		(start 420.873428 -61.9125)
		(end 422.105582 -60.680346)
		(width 0.10795)
		(layer "B.Cu")
		(net "FM_CPU0_OR_CPU1_MCP_PRES")
	)
	(segment
		(start 491.982252 -112.305592)
		(end 471.074242 -112.305592)
		(width 0.089408)
		(layer "In4.Cu")
		(net "FM_CPU0_OR_CPU1_MCP_PRES")
	)
	(segment
		(start 401.721574 -66.93027)
		(end 400.428968 -65.637664)
		(width 0.089408)
		(layer "In4.Cu")
		(net "FM_CPU0_OR_CPU1_MCP_PRES")
	)
	(segment
		(start 380.530862 -66.023998)
		(end 378.596398 -66.023998)
		(width 0.089408)
		(layer "In4.Cu")
		(net "FM_CPU0_OR_CPU1_MCP_PRES")
	)
	(segment
		(start 439.96102 -111.33836)
		(end 439.132726 -112.166654)
		(width 0.089408)
		(layer "In4.Cu")
		(net "FM_CPU0_OR_CPU1_MCP_PRES")
	)
	(segment
		(start 375.998486 -65.847976)
		(end 375.8057 -66.040762)
		(width 0.089408)
		(layer "In4.Cu")
		(net "FM_CPU0_OR_CPU1_MCP_PRES")
	)
	(segment
		(start 464.3628 -131.826)
		(end 464.3628 -135.128)
		(width 0.089408)
		(layer "In4.Cu")
		(net "FM_CPU0_OR_CPU1_MCP_PRES")
	)
	(segment
		(start 396.159736 -64.61252)
		(end 394.291566 -64.61252)
		(width 0.089408)
		(layer "In4.Cu")
		(net "FM_CPU0_OR_CPU1_MCP_PRES")
	)
	(segment
		(start 393.340844 -64.612774)
		(end 393.34059 -64.61252)
		(width 0.089408)
		(layer "In4.Cu")
		(net "FM_CPU0_OR_CPU1_MCP_PRES")
	)
	(segment
		(start 373.717566 -66.736976)
		(end 373.717312 -66.736722)
		(width 0.089408)
		(layer "In4.Cu")
		(net "FM_CPU0_OR_CPU1_MCP_PRES")
	)
	(segment
		(start 399.534888 -64.567816)
		(end 399.072862 -64.567816)
		(width 0.089408)
		(layer "In4.Cu")
		(net "FM_CPU0_OR_CPU1_MCP_PRES")
	)
	(segment
		(start 390.43864 -64.61252)
		(end 390.122664 -64.928496)
		(width 0.089408)
		(layer "In4.Cu")
		(net "FM_CPU0_OR_CPU1_MCP_PRES")
	)
	(segment
		(start 466.09 -136.8552)
		(end 466.09 -139.7762)
		(width 0.089408)
		(layer "In4.Cu")
		(net "FM_CPU0_OR_CPU1_MCP_PRES")
	)
	(segment
		(start 393.34059 -64.61252)
		(end 390.43864 -64.61252)
		(width 0.089408)
		(layer "In4.Cu")
		(net "FM_CPU0_OR_CPU1_MCP_PRES")
	)
	(segment
		(start 409.01366 -67.399408)
		(end 408.473656 -67.399408)
		(width 0.089408)
		(layer "In4.Cu")
		(net "FM_CPU0_OR_CPU1_MCP_PRES")
	)
	(segment
		(start 402.038058 -66.93027)
		(end 401.721574 -66.93027)
		(width 0.089408)
		(layer "In4.Cu")
		(net "FM_CPU0_OR_CPU1_MCP_PRES")
	)
	(segment
		(start 373.875554 -66.736976)
		(end 373.717566 -66.736976)
		(width 0.089408)
		(layer "In4.Cu")
		(net "FM_CPU0_OR_CPU1_MCP_PRES")
	)
	(segment
		(start 464.3628 -135.128)
		(end 466.09 -136.8552)
		(width 0.089408)
		(layer "In4.Cu")
		(net "FM_CPU0_OR_CPU1_MCP_PRES")
	)
	(segment
		(start 397.589502 -64.35598)
		(end 396.416276 -64.35598)
		(width 0.089408)
		(layer "In4.Cu")
		(net "FM_CPU0_OR_CPU1_MCP_PRES")
	)
	(segment
		(start 373.875808 -66.736722)
		(end 373.875554 -66.736976)
		(width 0.089408)
		(layer "In4.Cu")
		(net "FM_CPU0_OR_CPU1_MCP_PRES")
	)
	(segment
		(start 406.988518 -65.91427)
		(end 406.349454 -65.91427)
		(width 0.089408)
		(layer "In4.Cu")
		(net "FM_CPU0_OR_CPU1_MCP_PRES")
	)
	(segment
		(start 399.072862 -64.567816)
		(end 398.906492 -64.734186)
		(width 0.089408)
		(layer "In4.Cu")
		(net "FM_CPU0_OR_CPU1_MCP_PRES")
	)
	(segment
		(start 397.967454 -64.733932)
		(end 397.589502 -64.35598)
		(width 0.089408)
		(layer "In4.Cu")
		(net "FM_CPU0_OR_CPU1_MCP_PRES")
	)
	(segment
		(start 402.038312 -66.930016)
		(end 402.038058 -66.93027)
		(width 0.089408)
		(layer "In4.Cu")
		(net "FM_CPU0_OR_CPU1_MCP_PRES")
	)
	(segment
		(start 394.291058 -64.613028)
		(end 393.499086 -64.613028)
		(width 0.089408)
		(layer "In4.Cu")
		(net "FM_CPU0_OR_CPU1_MCP_PRES")
	)
	(segment
		(start 470.10701 -111.33836)
		(end 439.96102 -111.33836)
		(width 0.089408)
		(layer "In4.Cu")
		(net "FM_CPU0_OR_CPU1_MCP_PRES")
	)
	(segment
		(start 406.349454 -65.91427)
		(end 406.294844 -65.96888)
		(width 0.089408)
		(layer "In4.Cu")
		(net "FM_CPU0_OR_CPU1_MCP_PRES")
	)
	(segment
		(start 394.291566 -64.61252)
		(end 394.291058 -64.613028)
		(width 0.089408)
		(layer "In4.Cu")
		(net "FM_CPU0_OR_CPU1_MCP_PRES")
	)
	(segment
		(start 381.281432 -66.774568)
		(end 380.530862 -66.023998)
		(width 0.089408)
		(layer "In4.Cu")
		(net "FM_CPU0_OR_CPU1_MCP_PRES")
	)
	(segment
		(start 387.130544 -64.928496)
		(end 385.284472 -66.774568)
		(width 0.089408)
		(layer "In4.Cu")
		(net "FM_CPU0_OR_CPU1_MCP_PRES")
	)
	(segment
		(start 370.471954 -67.3227)
		(end 370.471954 -68.568062)
		(width 0.089408)
		(layer "In4.Cu")
		(net "FM_CPU0_OR_CPU1_MCP_PRES")
	)
	(segment
		(start 471.074242 -112.305592)
		(end 470.10701 -111.33836)
		(width 0.089408)
		(layer "In4.Cu")
		(net "FM_CPU0_OR_CPU1_MCP_PRES")
	)
	(segment
		(start 373.717312 -66.736722)
		(end 371.057678 -66.736722)
		(width 0.089408)
		(layer "In4.Cu")
		(net "FM_CPU0_OR_CPU1_MCP_PRES")
	)
	(segment
		(start 385.284472 -66.774568)
		(end 381.281432 -66.774568)
		(width 0.089408)
		(layer "In4.Cu")
		(net "FM_CPU0_OR_CPU1_MCP_PRES")
	)
	(segment
		(start 406.294844 -65.96888)
		(end 405.96312 -65.96888)
		(width 0.089408)
		(layer "In4.Cu")
		(net "FM_CPU0_OR_CPU1_MCP_PRES")
	)
	(segment
		(start 370.611146 -67.183254)
		(end 370.611146 -67.183508)
		(width 0.089408)
		(layer "In4.Cu")
		(net "FM_CPU0_OR_CPU1_MCP_PRES")
	)
	(segment
		(start 439.132726 -112.166654)
		(end 437.989726 -112.166654)
		(width 0.089408)
		(layer "In4.Cu")
		(net "FM_CPU0_OR_CPU1_MCP_PRES")
	)
	(segment
		(start 393.498832 -64.612774)
		(end 393.340844 -64.612774)
		(width 0.089408)
		(layer "In4.Cu")
		(net "FM_CPU0_OR_CPU1_MCP_PRES")
	)
	(segment
		(start 408.473656 -67.399408)
		(end 406.988518 -65.91427)
		(width 0.089408)
		(layer "In4.Cu")
		(net "FM_CPU0_OR_CPU1_MCP_PRES")
	)
	(segment
		(start 400.428968 -65.461896)
		(end 399.534888 -64.567816)
		(width 0.089408)
		(layer "In4.Cu")
		(net "FM_CPU0_OR_CPU1_MCP_PRES")
	)
	(segment
		(start 370.471954 -68.568062)
		(end 370.357908 -68.682108)
		(width 0.089408)
		(layer "In4.Cu")
		(net "FM_CPU0_OR_CPU1_MCP_PRES")
	)
	(segment
		(start 374.039892 -66.736722)
		(end 373.875808 -66.736722)
		(width 0.089408)
		(layer "In4.Cu")
		(net "FM_CPU0_OR_CPU1_MCP_PRES")
	)
	(segment
		(start 396.416276 -64.35598)
		(end 396.159736 -64.61252)
		(width 0.089408)
		(layer "In4.Cu")
		(net "FM_CPU0_OR_CPU1_MCP_PRES")
	)
	(segment
		(start 393.499086 -64.613028)
		(end 393.498832 -64.612774)
		(width 0.089408)
		(layer "In4.Cu")
		(net "FM_CPU0_OR_CPU1_MCP_PRES")
	)
	(segment
		(start 398.450562 -64.733932)
		(end 397.967454 -64.733932)
		(width 0.089408)
		(layer "In4.Cu")
		(net "FM_CPU0_OR_CPU1_MCP_PRES")
	)
	(segment
		(start 371.057678 -66.736722)
		(end 370.611146 -67.183254)
		(width 0.089408)
		(layer "In4.Cu")
		(net "FM_CPU0_OR_CPU1_MCP_PRES")
	)
	(segment
		(start 405.001984 -66.930016)
		(end 402.038312 -66.930016)
		(width 0.089408)
		(layer "In4.Cu")
		(net "FM_CPU0_OR_CPU1_MCP_PRES")
	)
	(segment
		(start 398.450816 -64.734186)
		(end 398.450562 -64.733932)
		(width 0.089408)
		(layer "In4.Cu")
		(net "FM_CPU0_OR_CPU1_MCP_PRES")
	)
	(segment
		(start 378.596398 -66.023998)
		(end 378.420376 -65.847976)
		(width 0.089408)
		(layer "In4.Cu")
		(net "FM_CPU0_OR_CPU1_MCP_PRES")
	)
	(segment
		(start 492.72063 -113.04397)
		(end 491.982252 -112.305592)
		(width 0.089408)
		(layer "In4.Cu")
		(net "FM_CPU0_OR_CPU1_MCP_PRES")
	)
	(segment
		(start 398.906492 -64.734186)
		(end 398.450816 -64.734186)
		(width 0.089408)
		(layer "In4.Cu")
		(net "FM_CPU0_OR_CPU1_MCP_PRES")
	)
	(segment
		(start 370.611146 -67.183508)
		(end 370.471954 -67.3227)
		(width 0.089408)
		(layer "In4.Cu")
		(net "FM_CPU0_OR_CPU1_MCP_PRES")
	)
	(segment
		(start 400.428968 -65.637664)
		(end 400.428968 -65.461896)
		(width 0.089408)
		(layer "In4.Cu")
		(net "FM_CPU0_OR_CPU1_MCP_PRES")
	)
	(segment
		(start 405.96312 -65.96888)
		(end 405.001984 -66.930016)
		(width 0.089408)
		(layer "In4.Cu")
		(net "FM_CPU0_OR_CPU1_MCP_PRES")
	)
	(segment
		(start 390.122664 -64.928496)
		(end 387.130544 -64.928496)
		(width 0.089408)
		(layer "In4.Cu")
		(net "FM_CPU0_OR_CPU1_MCP_PRES")
	)
	(segment
		(start 375.8057 -66.040762)
		(end 374.735852 -66.040762)
		(width 0.089408)
		(layer "In4.Cu")
		(net "FM_CPU0_OR_CPU1_MCP_PRES")
	)
	(segment
		(start 374.735852 -66.040762)
		(end 374.039892 -66.736722)
		(width 0.089408)
		(layer "In4.Cu")
		(net "FM_CPU0_OR_CPU1_MCP_PRES")
	)
	(segment
		(start 378.420376 -65.847976)
		(end 375.998486 -65.847976)
		(width 0.089408)
		(layer "In4.Cu")
		(net "FM_CPU0_OR_CPU1_MCP_PRES")
	)
	(segment
		(start 490.36478 -132.1054)
		(end 488.860592 -130.601212)
		(width 0.089408)
		(layer "In9.Cu")
		(net "FM_CPU0_OR_CPU1_MCP_PRES")
	)
	(segment
		(start 492.72063 -113.04397)
		(end 493.962182 -114.285522)
		(width 0.089408)
		(layer "In9.Cu")
		(net "FM_CPU0_OR_CPU1_MCP_PRES")
	)
	(segment
		(start 487.953812 -130.601212)
		(end 486.3338 -128.9812)
		(width 0.089408)
		(layer "In9.Cu")
		(net "FM_CPU0_OR_CPU1_MCP_PRES")
	)
	(segment
		(start 464.30565 -127.095504)
		(end 462.879186 -128.521968)
		(width 0.089408)
		(layer "In9.Cu")
		(net "FM_CPU0_OR_CPU1_MCP_PRES")
	)
	(segment
		(start 468.712296 -127.095504)
		(end 464.30565 -127.095504)
		(width 0.089408)
		(layer "In9.Cu")
		(net "FM_CPU0_OR_CPU1_MCP_PRES")
	)
	(segment
		(start 495.12982 -125.105414)
		(end 495.12982 -130.56616)
		(width 0.089408)
		(layer "In9.Cu")
		(net "FM_CPU0_OR_CPU1_MCP_PRES")
	)
	(segment
		(start 486.3338 -128.9812)
		(end 483.272338 -128.9812)
		(width 0.089408)
		(layer "In9.Cu")
		(net "FM_CPU0_OR_CPU1_MCP_PRES")
	)
	(segment
		(start 478.13722 -127.7747)
		(end 476.697294 -126.334774)
		(width 0.089408)
		(layer "In9.Cu")
		(net "FM_CPU0_OR_CPU1_MCP_PRES")
	)
	(segment
		(start 469.473026 -126.334774)
		(end 468.712296 -127.095504)
		(width 0.089408)
		(layer "In9.Cu")
		(net "FM_CPU0_OR_CPU1_MCP_PRES")
	)
	(segment
		(start 482.065838 -127.7747)
		(end 478.13722 -127.7747)
		(width 0.089408)
		(layer "In9.Cu")
		(net "FM_CPU0_OR_CPU1_MCP_PRES")
	)
	(segment
		(start 463.786474 -131.826)
		(end 464.3628 -131.826)
		(width 0.089408)
		(layer "In9.Cu")
		(net "FM_CPU0_OR_CPU1_MCP_PRES")
	)
	(segment
		(start 483.272338 -128.9812)
		(end 482.065838 -127.7747)
		(width 0.089408)
		(layer "In9.Cu")
		(net "FM_CPU0_OR_CPU1_MCP_PRES")
	)
	(segment
		(start 493.59058 -132.1054)
		(end 490.36478 -132.1054)
		(width 0.089408)
		(layer "In9.Cu")
		(net "FM_CPU0_OR_CPU1_MCP_PRES")
	)
	(segment
		(start 495.12982 -130.56616)
		(end 493.59058 -132.1054)
		(width 0.089408)
		(layer "In9.Cu")
		(net "FM_CPU0_OR_CPU1_MCP_PRES")
	)
	(segment
		(start 496.2652 -123.970034)
		(end 495.12982 -125.105414)
		(width 0.089408)
		(layer "In9.Cu")
		(net "FM_CPU0_OR_CPU1_MCP_PRES")
	)
	(segment
		(start 493.962182 -118.6942)
		(end 496.2652 -120.997218)
		(width 0.089408)
		(layer "In9.Cu")
		(net "FM_CPU0_OR_CPU1_MCP_PRES")
	)
	(segment
		(start 496.2652 -120.997218)
		(end 496.2652 -123.970034)
		(width 0.089408)
		(layer "In9.Cu")
		(net "FM_CPU0_OR_CPU1_MCP_PRES")
	)
	(segment
		(start 462.879186 -130.918712)
		(end 463.786474 -131.826)
		(width 0.089408)
		(layer "In9.Cu")
		(net "FM_CPU0_OR_CPU1_MCP_PRES")
	)
	(segment
		(start 493.962182 -114.285522)
		(end 493.962182 -118.6942)
		(width 0.089408)
		(layer "In9.Cu")
		(net "FM_CPU0_OR_CPU1_MCP_PRES")
	)
	(segment
		(start 488.860592 -130.601212)
		(end 487.953812 -130.601212)
		(width 0.089408)
		(layer "In9.Cu")
		(net "FM_CPU0_OR_CPU1_MCP_PRES")
	)
	(segment
		(start 462.879186 -128.521968)
		(end 462.879186 -130.918712)
		(width 0.089408)
		(layer "In9.Cu")
		(net "FM_CPU0_OR_CPU1_MCP_PRES")
	)
	(segment
		(start 476.697294 -126.334774)
		(end 469.473026 -126.334774)
		(width 0.089408)
		(layer "In9.Cu")
		(net "FM_CPU0_OR_CPU1_MCP_PRES")
	)
	(segment
		(start 437.48071 -119.861584)
		(end 437.48071 -119.839994)
		(width 0.10795)
		(layer "F.Cu")
		(net "FM_CPU0_CD_PRES")
	)
	(segment
		(start 436.963058 -119.343932)
		(end 437.48071 -119.861584)
		(width 0.10795)
		(layer "F.Cu")
		(net "FM_CPU0_CD_PRES")
	)
	(segment
		(start 437.48071 -119.839994)
		(end 437.476138 -119.839994)
		(width 0.10795)
		(layer "F.Cu")
		(net "FM_CPU0_CD_PRES")
	)
	(segment
		(start 436.963058 -112.511078)
		(end 436.963058 -119.343932)
		(width 0.10795)
		(layer "F.Cu")
		(net "FM_CPU0_CD_PRES")
	)
	(segment
		(start 436.706518 -112.254538)
		(end 436.963058 -112.511078)
		(width 0.10795)
		(layer "F.Cu")
		(net "FM_CPU0_CD_PRES")
	)
	(segment
		(start 370.345208 -69.495162)
		(end 370.745004 -69.894958)
		(width 0.10795)
		(layer "F.Cu")
		(net "FM_CPU0_CD_PRES")
	)
	(via
		(at 437.476138 -119.839994)
		(size 0.508)
		(drill 0.254)
		(layers "F.Cu" "B.Cu")
		(net "FM_CPU0_CD_PRES")
	)
	(via
		(at 436.706518 -112.254538)
		(size 0.508)
		(drill 0.254)
		(layers "F.Cu" "B.Cu")
		(net "FM_CPU0_CD_PRES")
	)
	(via
		(at 370.345208 -69.495162)
		(size 0.4572)
		(drill 0.2032)
		(layers "F.Cu" "B.Cu")
		(net "FM_CPU0_CD_PRES")
	)
	(via
		(at 427.865286 -62.390274)
		(size 0.508)
		(drill 0.254)
		(layers "F.Cu" "B.Cu")
		(net "FM_CPU0_CD_PRES")
	)
	(via
		(at 449.1228 -128.4478)
		(size 0.6604)
		(drill 0.3302)
		(layers "F.Cu" "B.Cu")
		(net "FM_CPU0_CD_PRES")
	)
	(via
		(at 451.28053 -130.21056)
		(size 0.508)
		(drill 0.254)
		(layers "F.Cu" "B.Cu")
		(net "FM_CPU0_CD_PRES")
	)
	(segment
		(start 448.437 -128.7272)
		(end 447.0146 -128.7272)
		(width 0.10795)
		(layer "B.Cu")
		(net "FM_CPU0_CD_PRES")
	)
	(segment
		(start 449.1228 -128.4478)
		(end 449.51777 -128.4478)
		(width 0.10795)
		(layer "B.Cu")
		(net "FM_CPU0_CD_PRES")
	)
	(segment
		(start 448.7164 -128.4478)
		(end 448.437 -128.7272)
		(width 0.10795)
		(layer "B.Cu")
		(net "FM_CPU0_CD_PRES")
	)
	(segment
		(start 449.1228 -128.4478)
		(end 448.7164 -128.4478)
		(width 0.10795)
		(layer "B.Cu")
		(net "FM_CPU0_CD_PRES")
	)
	(segment
		(start 449.51777 -128.4478)
		(end 451.28053 -130.21056)
		(width 0.10795)
		(layer "B.Cu")
		(net "FM_CPU0_CD_PRES")
	)
	(segment
		(start 426.18152 -113.843562)
		(end 426.18152 -114.413538)
		(width 0.089408)
		(layer "In2.Cu")
		(net "FM_CPU0_CD_PRES")
	)
	(segment
		(start 422.974008 -93.503496)
		(end 422.974008 -80.104234)
		(width 0.089408)
		(layer "In2.Cu")
		(net "FM_CPU0_CD_PRES")
	)
	(segment
		(start 420.9288 -104.1781)
		(end 421.412924 -103.693976)
		(width 0.089408)
		(layer "In2.Cu")
		(net "FM_CPU0_CD_PRES")
	)
	(segment
		(start 423.43324 -114.816382)
		(end 420.9288 -112.311942)
		(width 0.089408)
		(layer "In2.Cu")
		(net "FM_CPU0_CD_PRES")
	)
	(segment
		(start 422.078404 -79.20863)
		(end 422.078404 -65.77584)
		(width 0.089408)
		(layer "In2.Cu")
		(net "FM_CPU0_CD_PRES")
	)
	(segment
		(start 422.078404 -65.77584)
		(end 425.071794 -62.78245)
		(width 0.089408)
		(layer "In2.Cu")
		(net "FM_CPU0_CD_PRES")
	)
	(segment
		(start 424.794934 -114.708686)
		(end 424.687238 -114.816382)
		(width 0.089408)
		(layer "In2.Cu")
		(net "FM_CPU0_CD_PRES")
	)
	(segment
		(start 427.770544 -112.254538)
		(end 426.18152 -113.843562)
		(width 0.089408)
		(layer "In2.Cu")
		(net "FM_CPU0_CD_PRES")
	)
	(segment
		(start 425.886372 -114.708686)
		(end 424.794934 -114.708686)
		(width 0.089408)
		(layer "In2.Cu")
		(net "FM_CPU0_CD_PRES")
	)
	(segment
		(start 420.678356 -99.316032)
		(end 420.678356 -95.799148)
		(width 0.089408)
		(layer "In2.Cu")
		(net "FM_CPU0_CD_PRES")
	)
	(segment
		(start 420.678356 -95.799148)
		(end 422.974008 -93.503496)
		(width 0.089408)
		(layer "In2.Cu")
		(net "FM_CPU0_CD_PRES")
	)
	(segment
		(start 421.412924 -100.0506)
		(end 420.678356 -99.316032)
		(width 0.089408)
		(layer "In2.Cu")
		(net "FM_CPU0_CD_PRES")
	)
	(segment
		(start 425.071794 -62.78245)
		(end 427.47311 -62.78245)
		(width 0.089408)
		(layer "In2.Cu")
		(net "FM_CPU0_CD_PRES")
	)
	(segment
		(start 427.47311 -62.78245)
		(end 427.865286 -62.390274)
		(width 0.089408)
		(layer "In2.Cu")
		(net "FM_CPU0_CD_PRES")
	)
	(segment
		(start 436.706518 -112.254538)
		(end 427.770544 -112.254538)
		(width 0.089408)
		(layer "In2.Cu")
		(net "FM_CPU0_CD_PRES")
	)
	(segment
		(start 421.412924 -103.693976)
		(end 421.412924 -100.0506)
		(width 0.089408)
		(layer "In2.Cu")
		(net "FM_CPU0_CD_PRES")
	)
	(segment
		(start 424.687238 -114.816382)
		(end 423.43324 -114.816382)
		(width 0.089408)
		(layer "In2.Cu")
		(net "FM_CPU0_CD_PRES")
	)
	(segment
		(start 426.18152 -114.413538)
		(end 425.886372 -114.708686)
		(width 0.089408)
		(layer "In2.Cu")
		(net "FM_CPU0_CD_PRES")
	)
	(segment
		(start 420.9288 -112.311942)
		(end 420.9288 -104.1781)
		(width 0.089408)
		(layer "In2.Cu")
		(net "FM_CPU0_CD_PRES")
	)
	(segment
		(start 422.974008 -80.104234)
		(end 422.078404 -79.20863)
		(width 0.089408)
		(layer "In2.Cu")
		(net "FM_CPU0_CD_PRES")
	)
	(segment
		(start 375.075958 -66.613786)
		(end 376.091958 -66.613786)
		(width 0.089408)
		(layer "In4.Cu")
		(net "FM_CPU0_CD_PRES")
	)
	(segment
		(start 408.045412 -67.551808)
		(end 408.324304 -67.8307)
		(width 0.089408)
		(layer "In4.Cu")
		(net "FM_CPU0_CD_PRES")
	)
	(segment
		(start 421.108378 -61.241432)
		(end 421.867584 -61.241432)
		(width 0.089408)
		(layer "In4.Cu")
		(net "FM_CPU0_CD_PRES")
	)
	(segment
		(start 424.335702 -61.064394)
		(end 426.255942 -62.984634)
		(width 0.089408)
		(layer "In4.Cu")
		(net "FM_CPU0_CD_PRES")
	)
	(segment
		(start 393.261088 -65.185798)
		(end 393.261342 -65.186052)
		(width 0.089408)
		(layer "In4.Cu")
		(net "FM_CPU0_CD_PRES")
	)
	(segment
		(start 381.043688 -67.347592)
		(end 388.515352 -67.347592)
		(width 0.089408)
		(layer "In4.Cu")
		(net "FM_CPU0_CD_PRES")
	)
	(segment
		(start 414.291272 -65.530984)
		(end 415.648648 -64.173608)
		(width 0.089408)
		(layer "In4.Cu")
		(net "FM_CPU0_CD_PRES")
	)
	(segment
		(start 378.173488 -66.421)
		(end 378.351288 -66.5988)
		(width 0.089408)
		(layer "In4.Cu")
		(net "FM_CPU0_CD_PRES")
	)
	(segment
		(start 418.176202 -64.173608)
		(end 421.108378 -61.241432)
		(width 0.089408)
		(layer "In4.Cu")
		(net "FM_CPU0_CD_PRES")
	)
	(segment
		(start 374.268492 -67.421506)
		(end 374.585738 -67.10426)
		(width 0.089408)
		(layer "In4.Cu")
		(net "FM_CPU0_CD_PRES")
	)
	(segment
		(start 414.291272 -67.555872)
		(end 414.291272 -65.530984)
		(width 0.089408)
		(layer "In4.Cu")
		(net "FM_CPU0_CD_PRES")
	)
	(segment
		(start 397.704818 -65.321688)
		(end 398.008602 -65.321688)
		(width 0.089408)
		(layer "In4.Cu")
		(net "FM_CPU0_CD_PRES")
	)
	(segment
		(start 371.481604 -69.121782)
		(end 373.18188 -67.421506)
		(width 0.089408)
		(layer "In4.Cu")
		(net "FM_CPU0_CD_PRES")
	)
	(segment
		(start 400.721576 -67.614038)
		(end 400.845274 -67.614038)
		(width 0.089408)
		(layer "In4.Cu")
		(net "FM_CPU0_CD_PRES")
	)
	(segment
		(start 408.324304 -67.8307)
		(end 411.451044 -67.8307)
		(width 0.089408)
		(layer "In4.Cu")
		(net "FM_CPU0_CD_PRES")
	)
	(segment
		(start 394.528802 -65.186052)
		(end 394.52931 -65.185544)
		(width 0.089408)
		(layer "In4.Cu")
		(net "FM_CPU0_CD_PRES")
	)
	(segment
		(start 406.794716 -68.060316)
		(end 407.303224 -67.551808)
		(width 0.089408)
		(layer "In4.Cu")
		(net "FM_CPU0_CD_PRES")
	)
	(segment
		(start 393.261342 -65.186052)
		(end 394.528802 -65.186052)
		(width 0.089408)
		(layer "In4.Cu")
		(net "FM_CPU0_CD_PRES")
	)
	(segment
		(start 390.6774 -65.185544)
		(end 393.102846 -65.185544)
		(width 0.089408)
		(layer "In4.Cu")
		(net "FM_CPU0_CD_PRES")
	)
	(segment
		(start 427.270926 -62.984634)
		(end 427.865286 -62.390274)
		(width 0.089408)
		(layer "In4.Cu")
		(net "FM_CPU0_CD_PRES")
	)
	(segment
		(start 370.718588 -69.121782)
		(end 371.481604 -69.121782)
		(width 0.089408)
		(layer "In4.Cu")
		(net "FM_CPU0_CD_PRES")
	)
	(segment
		(start 394.52931 -65.185544)
		(end 396.39748 -65.185544)
		(width 0.089408)
		(layer "In4.Cu")
		(net "FM_CPU0_CD_PRES")
	)
	(segment
		(start 398.008602 -65.321688)
		(end 398.010634 -65.32372)
		(width 0.089408)
		(layer "In4.Cu")
		(net "FM_CPU0_CD_PRES")
	)
	(segment
		(start 388.515352 -67.347592)
		(end 390.6774 -65.185544)
		(width 0.089408)
		(layer "In4.Cu")
		(net "FM_CPU0_CD_PRES")
	)
	(segment
		(start 411.451806 -67.829938)
		(end 411.609794 -67.829938)
		(width 0.089408)
		(layer "In4.Cu")
		(net "FM_CPU0_CD_PRES")
	)
	(segment
		(start 378.351288 -66.5988)
		(end 380.294896 -66.5988)
		(width 0.089408)
		(layer "In4.Cu")
		(net "FM_CPU0_CD_PRES")
	)
	(segment
		(start 411.610048 -67.830192)
		(end 413.92856 -67.830192)
		(width 0.089408)
		(layer "In4.Cu")
		(net "FM_CPU0_CD_PRES")
	)
	(segment
		(start 397.332962 -64.949832)
		(end 397.704818 -65.321688)
		(width 0.089408)
		(layer "In4.Cu")
		(net "FM_CPU0_CD_PRES")
	)
	(segment
		(start 411.609794 -67.829938)
		(end 411.610048 -67.830192)
		(width 0.089408)
		(layer "In4.Cu")
		(net "FM_CPU0_CD_PRES")
	)
	(segment
		(start 411.451044 -67.8307)
		(end 411.451806 -67.829938)
		(width 0.089408)
		(layer "In4.Cu")
		(net "FM_CPU0_CD_PRES")
	)
	(segment
		(start 374.585738 -67.10426)
		(end 374.585738 -67.104006)
		(width 0.089408)
		(layer "In4.Cu")
		(net "FM_CPU0_CD_PRES")
	)
	(segment
		(start 400.845274 -67.614038)
		(end 401.291552 -68.060316)
		(width 0.089408)
		(layer "In4.Cu")
		(net "FM_CPU0_CD_PRES")
	)
	(segment
		(start 426.255942 -62.984634)
		(end 427.270926 -62.984634)
		(width 0.089408)
		(layer "In4.Cu")
		(net "FM_CPU0_CD_PRES")
	)
	(segment
		(start 373.18188 -67.421506)
		(end 374.268492 -67.421506)
		(width 0.089408)
		(layer "In4.Cu")
		(net "FM_CPU0_CD_PRES")
	)
	(segment
		(start 380.294896 -66.5988)
		(end 381.043688 -67.347592)
		(width 0.089408)
		(layer "In4.Cu")
		(net "FM_CPU0_CD_PRES")
	)
	(segment
		(start 396.633192 -64.949832)
		(end 397.332962 -64.949832)
		(width 0.089408)
		(layer "In4.Cu")
		(net "FM_CPU0_CD_PRES")
	)
	(segment
		(start 370.345208 -69.495162)
		(end 370.718588 -69.121782)
		(width 0.089408)
		(layer "In4.Cu")
		(net "FM_CPU0_CD_PRES")
	)
	(segment
		(start 415.648648 -64.173608)
		(end 418.176202 -64.173608)
		(width 0.089408)
		(layer "In4.Cu")
		(net "FM_CPU0_CD_PRES")
	)
	(segment
		(start 413.92856 -67.830192)
		(end 413.928814 -67.829938)
		(width 0.089408)
		(layer "In4.Cu")
		(net "FM_CPU0_CD_PRES")
	)
	(segment
		(start 398.431258 -65.32372)
		(end 400.721576 -67.614038)
		(width 0.089408)
		(layer "In4.Cu")
		(net "FM_CPU0_CD_PRES")
	)
	(segment
		(start 401.291552 -68.060316)
		(end 406.794716 -68.060316)
		(width 0.089408)
		(layer "In4.Cu")
		(net "FM_CPU0_CD_PRES")
	)
	(segment
		(start 413.928814 -67.829938)
		(end 414.017206 -67.829938)
		(width 0.089408)
		(layer "In4.Cu")
		(net "FM_CPU0_CD_PRES")
	)
	(segment
		(start 393.102846 -65.185544)
		(end 393.1031 -65.185798)
		(width 0.089408)
		(layer "In4.Cu")
		(net "FM_CPU0_CD_PRES")
	)
	(segment
		(start 407.303224 -67.551808)
		(end 408.045412 -67.551808)
		(width 0.089408)
		(layer "In4.Cu")
		(net "FM_CPU0_CD_PRES")
	)
	(segment
		(start 374.585738 -67.104006)
		(end 375.075958 -66.613786)
		(width 0.089408)
		(layer "In4.Cu")
		(net "FM_CPU0_CD_PRES")
	)
	(segment
		(start 393.1031 -65.185798)
		(end 393.261088 -65.185798)
		(width 0.089408)
		(layer "In4.Cu")
		(net "FM_CPU0_CD_PRES")
	)
	(segment
		(start 396.39748 -65.185544)
		(end 396.633192 -64.949832)
		(width 0.089408)
		(layer "In4.Cu")
		(net "FM_CPU0_CD_PRES")
	)
	(segment
		(start 421.867584 -61.241432)
		(end 422.044622 -61.064394)
		(width 0.089408)
		(layer "In4.Cu")
		(net "FM_CPU0_CD_PRES")
	)
	(segment
		(start 414.017206 -67.829938)
		(end 414.291272 -67.555872)
		(width 0.089408)
		(layer "In4.Cu")
		(net "FM_CPU0_CD_PRES")
	)
	(segment
		(start 422.044622 -61.064394)
		(end 424.335702 -61.064394)
		(width 0.089408)
		(layer "In4.Cu")
		(net "FM_CPU0_CD_PRES")
	)
	(segment
		(start 376.284744 -66.421)
		(end 378.173488 -66.421)
		(width 0.089408)
		(layer "In4.Cu")
		(net "FM_CPU0_CD_PRES")
	)
	(segment
		(start 398.010634 -65.32372)
		(end 398.431258 -65.32372)
		(width 0.089408)
		(layer "In4.Cu")
		(net "FM_CPU0_CD_PRES")
	)
	(segment
		(start 376.091958 -66.613786)
		(end 376.284744 -66.421)
		(width 0.089408)
		(layer "In4.Cu")
		(net "FM_CPU0_CD_PRES")
	)
	(segment
		(start 447.967862 -124.495306)
		(end 447.967608 -124.49556)
		(width 0.089408)
		(layer "In9.Cu")
		(net "FM_CPU0_CD_PRES")
	)
	(segment
		(start 449.22313 -128.15316)
		(end 451.28053 -130.21056)
		(width 0.089408)
		(layer "In9.Cu")
		(net "FM_CPU0_CD_PRES")
	)
	(segment
		(start 437.476138 -119.839994)
		(end 437.48071 -119.839994)
		(width 0.089408)
		(layer "In9.Cu")
		(net "FM_CPU0_CD_PRES")
	)
	(segment
		(start 437.48071 -119.839994)
		(end 437.48071 -119.93499)
		(width 0.089408)
		(layer "In9.Cu")
		(net "FM_CPU0_CD_PRES")
	)
	(segment
		(start 449.22313 -126.01321)
		(end 449.22313 -128.15316)
		(width 0.089408)
		(layer "In9.Cu")
		(net "FM_CPU0_CD_PRES")
	)
	(segment
		(start 447.967608 -124.49556)
		(end 447.967608 -124.757688)
		(width 0.089408)
		(layer "In9.Cu")
		(net "FM_CPU0_CD_PRES")
	)
	(segment
		(start 447.967862 -124.25299)
		(end 447.967862 -124.495306)
		(width 0.089408)
		(layer "In9.Cu")
		(net "FM_CPU0_CD_PRES")
	)
	(segment
		(start 446.192656 -122.477784)
		(end 447.967862 -124.25299)
		(width 0.089408)
		(layer "In9.Cu")
		(net "FM_CPU0_CD_PRES")
	)
	(segment
		(start 440.023504 -122.477784)
		(end 446.192656 -122.477784)
		(width 0.089408)
		(layer "In9.Cu")
		(net "FM_CPU0_CD_PRES")
	)
	(segment
		(start 437.48071 -119.93499)
		(end 440.023504 -122.477784)
		(width 0.089408)
		(layer "In9.Cu")
		(net "FM_CPU0_CD_PRES")
	)
	(segment
		(start 447.967608 -124.757688)
		(end 449.22313 -126.01321)
		(width 0.089408)
		(layer "In9.Cu")
		(net "FM_CPU0_CD_PRES")
	)
	(segment
		(start 370.345208 -70.295262)
		(end 370.745004 -70.695058)
		(width 0.10795)
		(layer "F.Cu")
		(net "FM_CPU0_AND_CPU1_MCP_PRES")
	)
	(via
		(at 426.4914 -72.159622)
		(size 0.508)
		(drill 0.254)
		(layers "F.Cu" "B.Cu")
		(net "FM_CPU0_AND_CPU1_MCP_PRES")
	)
	(via
		(at 370.345208 -70.295262)
		(size 0.4572)
		(drill 0.2032)
		(layers "F.Cu" "B.Cu")
		(net "FM_CPU0_AND_CPU1_MCP_PRES")
	)
	(via
		(at 420.578534 -60.084716)
		(size 0.6604)
		(drill 0.3302)
		(layers "F.Cu" "B.Cu")
		(net "FM_CPU0_AND_CPU1_MCP_PRES")
	)
	(via
		(at 499.96725 -129.38125)
		(size 0.508)
		(drill 0.254)
		(layers "F.Cu" "B.Cu")
		(net "FM_CPU0_AND_CPU1_MCP_PRES")
	)
	(segment
		(start 380.455678 -64.30772)
		(end 380.88824 -64.30772)
		(width 0.10795)
		(layer "B.Cu")
		(net "FM_CPU0_AND_CPU1_MCP_PRES")
	)
	(segment
		(start 397.00073 -70.167754)
		(end 397.466566 -69.701918)
		(width 0.10795)
		(layer "B.Cu")
		(net "FM_CPU0_AND_CPU1_MCP_PRES")
	)
	(segment
		(start 388.089902 -72.8345)
		(end 388.089902 -72.803004)
		(width 0.10795)
		(layer "B.Cu")
		(net "FM_CPU0_AND_CPU1_MCP_PRES")
	)
	(segment
		(start 425.759626 -67.260978)
		(end 424.945556 -68.075048)
		(width 0.10795)
		(layer "B.Cu")
		(net "FM_CPU0_AND_CPU1_MCP_PRES")
	)
	(segment
		(start 380.88824 -64.30772)
		(end 381.32385 -64.74333)
		(width 0.10795)
		(layer "B.Cu")
		(net "FM_CPU0_AND_CPU1_MCP_PRES")
	)
	(segment
		(start 375.83237 -63.299848)
		(end 376.183906 -63.651384)
		(width 0.10795)
		(layer "B.Cu")
		(net "FM_CPU0_AND_CPU1_MCP_PRES")
	)
	(segment
		(start 425.285916 -62.684406)
		(end 425.759626 -63.158116)
		(width 0.10795)
		(layer "B.Cu")
		(net "FM_CPU0_AND_CPU1_MCP_PRES")
	)
	(segment
		(start 372.744492 -67.549522)
		(end 373.086884 -67.20713)
		(width 0.10795)
		(layer "B.Cu")
		(net "FM_CPU0_AND_CPU1_MCP_PRES")
	)
	(segment
		(start 389.031226 -71.893176)
		(end 390.745726 -71.893176)
		(width 0.10795)
		(layer "B.Cu")
		(net "FM_CPU0_AND_CPU1_MCP_PRES")
	)
	(segment
		(start 373.086884 -67.20713)
		(end 373.086884 -65.089532)
		(width 0.10795)
		(layer "B.Cu")
		(net "FM_CPU0_AND_CPU1_MCP_PRES")
	)
	(segment
		(start 393.047728 -73.53808)
		(end 396.418308 -70.1675)
		(width 0.10795)
		(layer "B.Cu")
		(net "FM_CPU0_AND_CPU1_MCP_PRES")
	)
	(segment
		(start 381.32385 -64.74333)
		(end 381.32385 -68.988178)
		(width 0.10795)
		(layer "B.Cu")
		(net "FM_CPU0_AND_CPU1_MCP_PRES")
	)
	(segment
		(start 413.854138 -63.10249)
		(end 416.012376 -60.944252)
		(width 0.10795)
		(layer "B.Cu")
		(net "FM_CPU0_AND_CPU1_MCP_PRES")
	)
	(segment
		(start 388.505446 -72.418956)
		(end 389.031226 -71.893176)
		(width 0.10795)
		(layer "B.Cu")
		(net "FM_CPU0_AND_CPU1_MCP_PRES")
	)
	(segment
		(start 396.418308 -70.1675)
		(end 396.832582 -70.1675)
		(width 0.10795)
		(layer "B.Cu")
		(net "FM_CPU0_AND_CPU1_MCP_PRES")
	)
	(segment
		(start 376.183906 -63.651384)
		(end 376.822208 -63.651384)
		(width 0.10795)
		(layer "B.Cu")
		(net "FM_CPU0_AND_CPU1_MCP_PRES")
	)
	(segment
		(start 421.372284 -60.084716)
		(end 421.692324 -59.764676)
		(width 0.10795)
		(layer "B.Cu")
		(net "FM_CPU0_AND_CPU1_MCP_PRES")
	)
	(segment
		(start 375.205752 -63.299848)
		(end 375.83237 -63.299848)
		(width 0.10795)
		(layer "B.Cu")
		(net "FM_CPU0_AND_CPU1_MCP_PRES")
	)
	(segment
		(start 378.991622 -71.298816)
		(end 378.991622 -71.857362)
		(width 0.10795)
		(layer "B.Cu")
		(net "FM_CPU0_AND_CPU1_MCP_PRES")
	)
	(segment
		(start 416.012376 -60.944252)
		(end 419.449504 -60.944252)
		(width 0.10795)
		(layer "B.Cu")
		(net "FM_CPU0_AND_CPU1_MCP_PRES")
	)
	(segment
		(start 426.311822 -72.159622)
		(end 426.4914 -72.159622)
		(width 0.10795)
		(layer "B.Cu")
		(net "FM_CPU0_AND_CPU1_MCP_PRES")
	)
	(segment
		(start 388.47395 -72.418956)
		(end 388.505446 -72.418956)
		(width 0.10795)
		(layer "B.Cu")
		(net "FM_CPU0_AND_CPU1_MCP_PRES")
	)
	(segment
		(start 379.94463 -63.796672)
		(end 380.455678 -64.30772)
		(width 0.10795)
		(layer "B.Cu")
		(net "FM_CPU0_AND_CPU1_MCP_PRES")
	)
	(segment
		(start 403.346412 -67.950588)
		(end 405.70531 -65.59169)
		(width 0.10795)
		(layer "B.Cu")
		(net "FM_CPU0_AND_CPU1_MCP_PRES")
	)
	(segment
		(start 499.62816 -129.04216)
		(end 499.62816 -128.52654)
		(width 0.10795)
		(layer "B.Cu")
		(net "FM_CPU0_AND_CPU1_MCP_PRES")
	)
	(segment
		(start 373.086884 -65.089532)
		(end 373.463312 -64.713104)
		(width 0.10795)
		(layer "B.Cu")
		(net "FM_CPU0_AND_CPU1_MCP_PRES")
	)
	(segment
		(start 372.806722 -68.10248)
		(end 372.744492 -68.04025)
		(width 0.10795)
		(layer "B.Cu")
		(net "FM_CPU0_AND_CPU1_MCP_PRES")
	)
	(segment
		(start 392.39063 -73.53808)
		(end 393.047728 -73.53808)
		(width 0.10795)
		(layer "B.Cu")
		(net "FM_CPU0_AND_CPU1_MCP_PRES")
	)
	(segment
		(start 376.822208 -63.651384)
		(end 376.938794 -63.534798)
		(width 0.10795)
		(layer "B.Cu")
		(net "FM_CPU0_AND_CPU1_MCP_PRES")
	)
	(segment
		(start 378.991622 -71.857362)
		(end 379.735334 -72.601074)
		(width 0.10795)
		(layer "B.Cu")
		(net "FM_CPU0_AND_CPU1_MCP_PRES")
	)
	(segment
		(start 379.735334 -73.551542)
		(end 381.672592 -75.4888)
		(width 0.10795)
		(layer "B.Cu")
		(net "FM_CPU0_AND_CPU1_MCP_PRES")
	)
	(segment
		(start 398.284446 -69.701918)
		(end 400.035776 -67.950588)
		(width 0.10795)
		(layer "B.Cu")
		(net "FM_CPU0_AND_CPU1_MCP_PRES")
	)
	(segment
		(start 372.10619 -69.912484)
		(end 372.806722 -69.211952)
		(width 0.10795)
		(layer "B.Cu")
		(net "FM_CPU0_AND_CPU1_MCP_PRES")
	)
	(segment
		(start 408.953208 -65.59169)
		(end 411.442408 -63.10249)
		(width 0.10795)
		(layer "B.Cu")
		(net "FM_CPU0_AND_CPU1_MCP_PRES")
	)
	(segment
		(start 424.945556 -68.075048)
		(end 424.945556 -70.200774)
		(width 0.10795)
		(layer "B.Cu")
		(net "FM_CPU0_AND_CPU1_MCP_PRES")
	)
	(segment
		(start 400.035776 -67.950588)
		(end 403.346412 -67.950588)
		(width 0.10795)
		(layer "B.Cu")
		(net "FM_CPU0_AND_CPU1_MCP_PRES")
	)
	(segment
		(start 379.735334 -72.601074)
		(end 379.735334 -73.551542)
		(width 0.10795)
		(layer "B.Cu")
		(net "FM_CPU0_AND_CPU1_MCP_PRES")
	)
	(segment
		(start 385.435602 -75.4888)
		(end 388.089902 -72.8345)
		(width 0.10795)
		(layer "B.Cu")
		(net "FM_CPU0_AND_CPU1_MCP_PRES")
	)
	(segment
		(start 374.423432 -63.4492)
		(end 375.0564 -63.4492)
		(width 0.10795)
		(layer "B.Cu")
		(net "FM_CPU0_AND_CPU1_MCP_PRES")
	)
	(segment
		(start 380.125732 -70.186296)
		(end 380.104142 -70.186296)
		(width 0.10795)
		(layer "B.Cu")
		(net "FM_CPU0_AND_CPU1_MCP_PRES")
	)
	(segment
		(start 499.96725 -129.38125)
		(end 499.62816 -129.04216)
		(width 0.10795)
		(layer "B.Cu")
		(net "FM_CPU0_AND_CPU1_MCP_PRES")
	)
	(segment
		(start 424.945556 -70.200774)
		(end 425.148502 -70.40372)
		(width 0.10795)
		(layer "B.Cu")
		(net "FM_CPU0_AND_CPU1_MCP_PRES")
	)
	(segment
		(start 420.578534 -60.084716)
		(end 421.372284 -60.084716)
		(width 0.10795)
		(layer "B.Cu")
		(net "FM_CPU0_AND_CPU1_MCP_PRES")
	)
	(segment
		(start 373.728488 -64.713104)
		(end 374.043702 -64.39789)
		(width 0.10795)
		(layer "B.Cu")
		(net "FM_CPU0_AND_CPU1_MCP_PRES")
	)
	(segment
		(start 419.449504 -60.944252)
		(end 420.30904 -60.084716)
		(width 0.10795)
		(layer "B.Cu")
		(net "FM_CPU0_AND_CPU1_MCP_PRES")
	)
	(segment
		(start 381.32385 -68.988178)
		(end 380.125732 -70.186296)
		(width 0.10795)
		(layer "B.Cu")
		(net "FM_CPU0_AND_CPU1_MCP_PRES")
	)
	(segment
		(start 426.0342 -71.882)
		(end 426.311822 -72.159622)
		(width 0.10795)
		(layer "B.Cu")
		(net "FM_CPU0_AND_CPU1_MCP_PRES")
	)
	(segment
		(start 388.089902 -72.803004)
		(end 388.47395 -72.418956)
		(width 0.10795)
		(layer "B.Cu")
		(net "FM_CPU0_AND_CPU1_MCP_PRES")
	)
	(segment
		(start 376.938794 -63.534798)
		(end 377.3424 -63.534798)
		(width 0.10795)
		(layer "B.Cu")
		(net "FM_CPU0_AND_CPU1_MCP_PRES")
	)
	(segment
		(start 396.832836 -70.167754)
		(end 397.00073 -70.167754)
		(width 0.10795)
		(layer "B.Cu")
		(net "FM_CPU0_AND_CPU1_MCP_PRES")
	)
	(segment
		(start 372.806722 -69.211952)
		(end 372.806722 -68.10248)
		(width 0.10795)
		(layer "B.Cu")
		(net "FM_CPU0_AND_CPU1_MCP_PRES")
	)
	(segment
		(start 370.727986 -69.912484)
		(end 372.10619 -69.912484)
		(width 0.10795)
		(layer "B.Cu")
		(net "FM_CPU0_AND_CPU1_MCP_PRES")
	)
	(segment
		(start 421.692324 -59.764676)
		(end 424.488864 -59.764676)
		(width 0.10795)
		(layer "B.Cu")
		(net "FM_CPU0_AND_CPU1_MCP_PRES")
	)
	(segment
		(start 374.043702 -64.39789)
		(end 374.043702 -63.82893)
		(width 0.10795)
		(layer "B.Cu")
		(net "FM_CPU0_AND_CPU1_MCP_PRES")
	)
	(segment
		(start 425.759626 -63.158116)
		(end 425.759626 -67.260978)
		(width 0.10795)
		(layer "B.Cu")
		(net "FM_CPU0_AND_CPU1_MCP_PRES")
	)
	(segment
		(start 377.3424 -63.534798)
		(end 377.604274 -63.796672)
		(width 0.10795)
		(layer "B.Cu")
		(net "FM_CPU0_AND_CPU1_MCP_PRES")
	)
	(segment
		(start 420.30904 -60.084716)
		(end 420.578534 -60.084716)
		(width 0.10795)
		(layer "B.Cu")
		(net "FM_CPU0_AND_CPU1_MCP_PRES")
	)
	(segment
		(start 424.488864 -59.764676)
		(end 425.285916 -60.561728)
		(width 0.10795)
		(layer "B.Cu")
		(net "FM_CPU0_AND_CPU1_MCP_PRES")
	)
	(segment
		(start 370.345208 -70.295262)
		(end 370.727986 -69.912484)
		(width 0.10795)
		(layer "B.Cu")
		(net "FM_CPU0_AND_CPU1_MCP_PRES")
	)
	(segment
		(start 405.70531 -65.59169)
		(end 408.953208 -65.59169)
		(width 0.10795)
		(layer "B.Cu")
		(net "FM_CPU0_AND_CPU1_MCP_PRES")
	)
	(segment
		(start 396.832582 -70.1675)
		(end 396.832836 -70.167754)
		(width 0.10795)
		(layer "B.Cu")
		(net "FM_CPU0_AND_CPU1_MCP_PRES")
	)
	(segment
		(start 411.442408 -63.10249)
		(end 413.854138 -63.10249)
		(width 0.10795)
		(layer "B.Cu")
		(net "FM_CPU0_AND_CPU1_MCP_PRES")
	)
	(segment
		(start 373.463312 -64.713104)
		(end 373.728488 -64.713104)
		(width 0.10795)
		(layer "B.Cu")
		(net "FM_CPU0_AND_CPU1_MCP_PRES")
	)
	(segment
		(start 374.043702 -63.82893)
		(end 374.423432 -63.4492)
		(width 0.10795)
		(layer "B.Cu")
		(net "FM_CPU0_AND_CPU1_MCP_PRES")
	)
	(segment
		(start 390.745726 -71.893176)
		(end 392.39063 -73.53808)
		(width 0.10795)
		(layer "B.Cu")
		(net "FM_CPU0_AND_CPU1_MCP_PRES")
	)
	(segment
		(start 425.148502 -70.416674)
		(end 426.0342 -71.302372)
		(width 0.10795)
		(layer "B.Cu")
		(net "FM_CPU0_AND_CPU1_MCP_PRES")
	)
	(segment
		(start 397.466566 -69.701918)
		(end 398.284446 -69.701918)
		(width 0.10795)
		(layer "B.Cu")
		(net "FM_CPU0_AND_CPU1_MCP_PRES")
	)
	(segment
		(start 375.0564 -63.4492)
		(end 375.205752 -63.299848)
		(width 0.10795)
		(layer "B.Cu")
		(net "FM_CPU0_AND_CPU1_MCP_PRES")
	)
	(segment
		(start 426.0342 -71.302372)
		(end 426.0342 -71.882)
		(width 0.10795)
		(layer "B.Cu")
		(net "FM_CPU0_AND_CPU1_MCP_PRES")
	)
	(segment
		(start 425.285916 -60.561728)
		(end 425.285916 -62.684406)
		(width 0.10795)
		(layer "B.Cu")
		(net "FM_CPU0_AND_CPU1_MCP_PRES")
	)
	(segment
		(start 372.744492 -68.04025)
		(end 372.744492 -67.549522)
		(width 0.10795)
		(layer "B.Cu")
		(net "FM_CPU0_AND_CPU1_MCP_PRES")
	)
	(segment
		(start 425.148502 -70.40372)
		(end 425.148502 -70.416674)
		(width 0.10795)
		(layer "B.Cu")
		(net "FM_CPU0_AND_CPU1_MCP_PRES")
	)
	(segment
		(start 377.604274 -63.796672)
		(end 379.94463 -63.796672)
		(width 0.10795)
		(layer "B.Cu")
		(net "FM_CPU0_AND_CPU1_MCP_PRES")
	)
	(segment
		(start 380.104142 -70.186296)
		(end 378.991622 -71.298816)
		(width 0.10795)
		(layer "B.Cu")
		(net "FM_CPU0_AND_CPU1_MCP_PRES")
	)
	(segment
		(start 381.672592 -75.4888)
		(end 385.435602 -75.4888)
		(width 0.10795)
		(layer "B.Cu")
		(net "FM_CPU0_AND_CPU1_MCP_PRES")
	)
	(segment
		(start 499.96725 -129.38125)
		(end 499.96725 -128.90373)
		(width 0.089408)
		(layer "In4.Cu")
		(net "FM_CPU0_AND_CPU1_MCP_PRES")
	)
	(segment
		(start 427.381162 -110.933992)
		(end 426.313346 -109.866176)
		(width 0.089408)
		(layer "In4.Cu")
		(net "FM_CPU0_AND_CPU1_MCP_PRES")
	)
	(segment
		(start 494.1824 -118.3894)
		(end 494.1824 -113.7666)
		(width 0.089408)
		(layer "In4.Cu")
		(net "FM_CPU0_AND_CPU1_MCP_PRES")
	)
	(segment
		(start 426.313346 -109.866176)
		(end 426.313346 -78.551024)
		(width 0.089408)
		(layer "In4.Cu")
		(net "FM_CPU0_AND_CPU1_MCP_PRES")
	)
	(segment
		(start 470.04478 -110.933992)
		(end 427.381162 -110.933992)
		(width 0.089408)
		(layer "In4.Cu")
		(net "FM_CPU0_AND_CPU1_MCP_PRES")
	)
	(segment
		(start 496.1128 -120.3198)
		(end 494.1824 -118.3894)
		(width 0.089408)
		(layer "In4.Cu")
		(net "FM_CPU0_AND_CPU1_MCP_PRES")
	)
	(segment
		(start 499.96725 -128.90373)
		(end 496.1128 -125.04928)
		(width 0.089408)
		(layer "In4.Cu")
		(net "FM_CPU0_AND_CPU1_MCP_PRES")
	)
	(segment
		(start 492.479584 -112.063784)
		(end 471.174572 -112.063784)
		(width 0.089408)
		(layer "In4.Cu")
		(net "FM_CPU0_AND_CPU1_MCP_PRES")
	)
	(segment
		(start 425.70908 -77.946758)
		(end 425.70908 -72.941942)
		(width 0.089408)
		(layer "In4.Cu")
		(net "FM_CPU0_AND_CPU1_MCP_PRES")
	)
	(segment
		(start 426.313346 -78.551024)
		(end 425.70908 -77.946758)
		(width 0.089408)
		(layer "In4.Cu")
		(net "FM_CPU0_AND_CPU1_MCP_PRES")
	)
	(segment
		(start 494.1824 -113.7666)
		(end 492.479584 -112.063784)
		(width 0.089408)
		(layer "In4.Cu")
		(net "FM_CPU0_AND_CPU1_MCP_PRES")
	)
	(segment
		(start 471.174572 -112.063784)
		(end 470.04478 -110.933992)
		(width 0.089408)
		(layer "In4.Cu")
		(net "FM_CPU0_AND_CPU1_MCP_PRES")
	)
	(segment
		(start 496.1128 -125.04928)
		(end 496.1128 -120.3198)
		(width 0.089408)
		(layer "In4.Cu")
		(net "FM_CPU0_AND_CPU1_MCP_PRES")
	)
	(segment
		(start 425.70908 -72.941942)
		(end 426.4914 -72.159622)
		(width 0.089408)
		(layer "In4.Cu")
		(net "FM_CPU0_AND_CPU1_MCP_PRES")
	)
	(segment
		(start 429.847248 -49.755044)
		(end 429.847248 -48.813466)
		(width 0.10795)
		(layer "F.Cu")
		(net "PU_24M_OSC_OE")
	)
	(segment
		(start 427.8884 -49.276)
		(end 428.6504 -49.276)
		(width 0.10795)
		(layer "F.Cu")
		(net "PU_24M_OSC_OE")
	)
	(segment
		(start 428.6504 -49.276)
		(end 429.112934 -48.813466)
		(width 0.10795)
		(layer "F.Cu")
		(net "PU_24M_OSC_OE")
	)
	(segment
		(start 429.112934 -48.813466)
		(end 429.847248 -48.813466)
		(width 0.10795)
		(layer "F.Cu")
		(net "PU_24M_OSC_OE")
	)
	(segment
		(start 430.083468 -49.991264)
		(end 429.847248 -49.755044)
		(width 0.10795)
		(layer "F.Cu")
		(net "PU_24M_OSC_OE")
	)
	(segment
		(start 430.083468 -50.482246)
		(end 430.083468 -49.991264)
		(width 0.10795)
		(layer "F.Cu")
		(net "PU_24M_OSC_OE")
	)
	(via
		(at 427.8884 -49.276)
		(size 0.762)
		(drill 0.381)
		(layers "F.Cu" "B.Cu")
		(net "PU_24M_OSC_OE")
	)
	(segment
		(start 431.766472 -45.499528)
		(end 431.447194 -45.818806)
		(width 0.10795)
		(layer "F.Cu")
		(net "CLK_24M_BMC_CLKIN_R")
	)
	(segment
		(start 431.766472 -45.05452)
		(end 431.766472 -45.499528)
		(width 0.10795)
		(layer "F.Cu")
		(net "CLK_24M_BMC_CLKIN_R")
	)
	(segment
		(start 431.447194 -45.818806)
		(end 431.447194 -46.613572)
		(width 0.10795)
		(layer "F.Cu")
		(net "CLK_24M_BMC_CLKIN_R")
	)
	(segment
		(start 429.625506 -44.34713)
		(end 429.625506 -44.285916)
		(width 0.10795)
		(layer "F.Cu")
		(net "CLK_24M_25M_BMC_CLKIN")
	)
	(segment
		(start 421.49014 -40.13454)
		(end 421.89019 -39.73449)
		(width 0.089408)
		(layer "F.Cu")
		(net "CLK_24M_25M_BMC_CLKIN")
	)
	(segment
		(start 430.109122 -45.054774)
		(end 429.909224 -44.854876)
		(width 0.10795)
		(layer "F.Cu")
		(net "CLK_24M_25M_BMC_CLKIN")
	)
	(segment
		(start 430.109376 -45.05452)
		(end 430.109122 -45.054774)
		(width 0.10795)
		(layer "F.Cu")
		(net "CLK_24M_25M_BMC_CLKIN")
	)
	(segment
		(start 430.877472 -45.05452)
		(end 430.109376 -45.05452)
		(width 0.10795)
		(layer "F.Cu")
		(net "CLK_24M_25M_BMC_CLKIN")
	)
	(segment
		(start 429.909224 -44.854876)
		(end 429.909224 -44.630848)
		(width 0.10795)
		(layer "F.Cu")
		(net "CLK_24M_25M_BMC_CLKIN")
	)
	(segment
		(start 429.909224 -44.630848)
		(end 429.625506 -44.34713)
		(width 0.10795)
		(layer "F.Cu")
		(net "CLK_24M_25M_BMC_CLKIN")
	)
	(via
		(at 429.625506 -44.285916)
		(size 0.508)
		(drill 0.254)
		(layers "F.Cu" "B.Cu")
		(net "CLK_24M_25M_BMC_CLKIN")
	)
	(via
		(at 421.89019 -39.73449)
		(size 0.4572)
		(drill 0.2032)
		(layers "F.Cu" "B.Cu")
		(net "CLK_24M_25M_BMC_CLKIN")
	)
	(segment
		(start 424.166792 -42.266616)
		(end 422.077388 -40.177212)
		(width 0.089408)
		(layer "In2.Cu")
		(net "CLK_24M_25M_BMC_CLKIN")
	)
	(segment
		(start 422.077388 -40.177212)
		(end 422.077388 -39.921688)
		(width 0.089408)
		(layer "In2.Cu")
		(net "CLK_24M_25M_BMC_CLKIN")
	)
	(segment
		(start 422.077388 -39.921688)
		(end 421.89019 -39.73449)
		(width 0.089408)
		(layer "In2.Cu")
		(net "CLK_24M_25M_BMC_CLKIN")
	)
	(segment
		(start 429.625506 -44.285916)
		(end 429.30699 -44.285916)
		(width 0.089408)
		(layer "In2.Cu")
		(net "CLK_24M_25M_BMC_CLKIN")
	)
	(segment
		(start 428.274734 -43.773598)
		(end 426.767752 -42.266616)
		(width 0.089408)
		(layer "In2.Cu")
		(net "CLK_24M_25M_BMC_CLKIN")
	)
	(segment
		(start 428.794672 -43.773598)
		(end 428.274734 -43.773598)
		(width 0.089408)
		(layer "In2.Cu")
		(net "CLK_24M_25M_BMC_CLKIN")
	)
	(segment
		(start 429.30699 -44.285916)
		(end 428.794672 -43.773598)
		(width 0.089408)
		(layer "In2.Cu")
		(net "CLK_24M_25M_BMC_CLKIN")
	)
	(segment
		(start 426.767752 -42.266616)
		(end 424.166792 -42.266616)
		(width 0.089408)
		(layer "In2.Cu")
		(net "CLK_24M_25M_BMC_CLKIN")
	)
	(segment
		(start 419.090094 -28.934664)
		(end 419.490144 -28.534614)
		(width 0.10795)
		(layer "F.Cu")
		(net "FM_PWRBRK_N")
	)
	(via
		(at 461.370172 -32.505904)
		(size 0.508)
		(drill 0.254)
		(layers "F.Cu" "B.Cu")
		(net "FM_PWRBRK_N")
	)
	(via
		(at 419.490144 -28.534614)
		(size 0.4572)
		(drill 0.2032)
		(layers "F.Cu" "B.Cu")
		(net "FM_PWRBRK_N")
	)
	(via
		(at 391.524236 -35.527234)
		(size 0.508)
		(drill 0.254)
		(layers "F.Cu" "B.Cu")
		(net "FM_PWRBRK_N")
	)
	(via
		(at 389.975852 -35.912044)
		(size 0.6604)
		(drill 0.3302)
		(layers "F.Cu" "B.Cu")
		(net "FM_PWRBRK_N")
	)
	(via
		(at 456.65136 -12.62888)
		(size 0.6604)
		(drill 0.3302)
		(layers "F.Cu" "B.Cu")
		(net "FM_PWRBRK_N")
	)
	(segment
		(start 456.55484 -12.7254)
		(end 456.65136 -12.62888)
		(width 0.10795)
		(layer "B.Cu")
		(net "FM_PWRBRK_N")
	)
	(segment
		(start 460.56169 -7.35711)
		(end 459.867 -8.0518)
		(width 0.10795)
		(layer "B.Cu")
		(net "FM_PWRBRK_N")
	)
	(segment
		(start 385.809744 -37.13988)
		(end 385.809744 -38.741858)
		(width 0.10795)
		(layer "B.Cu")
		(net "FM_PWRBRK_N")
	)
	(segment
		(start 463.17535 -3.761232)
		(end 462.047082 -4.8895)
		(width 0.10795)
		(layer "B.Cu")
		(net "FM_PWRBRK_N")
	)
	(segment
		(start 458.331824 -28.462224)
		(end 457.97978 -28.462224)
		(width 0.10795)
		(layer "B.Cu")
		(net "FM_PWRBRK_N")
	)
	(segment
		(start 453.753728 -15.285974)
		(end 453.753728 -14.831568)
		(width 0.10795)
		(layer "B.Cu")
		(net "FM_PWRBRK_N")
	)
	(segment
		(start 378.974858 -40.660574)
		(end 378.72035 -40.915082)
		(width 0.10795)
		(layer "B.Cu")
		(net "FM_PWRBRK_N")
	)
	(segment
		(start 456.637898 -27.120342)
		(end 456.637898 -22.408642)
		(width 0.10795)
		(layer "B.Cu")
		(net "FM_PWRBRK_N")
	)
	(segment
		(start 459.867 -8.0518)
		(end 459.015846 -8.0518)
		(width 0.10795)
		(layer "B.Cu")
		(net "FM_PWRBRK_N")
	)
	(segment
		(start 463.17535 -3.248152)
		(end 463.17535 -3.761232)
		(width 0.10795)
		(layer "B.Cu")
		(net "FM_PWRBRK_N")
	)
	(segment
		(start 454.197212 -15.729458)
		(end 453.753728 -15.285974)
		(width 0.10795)
		(layer "B.Cu")
		(net "FM_PWRBRK_N")
	)
	(segment
		(start 385.809998 -39.131748)
		(end 385.809744 -39.132002)
		(width 0.10795)
		(layer "B.Cu")
		(net "FM_PWRBRK_N")
	)
	(segment
		(start 458.6224 -28.7528)
		(end 458.331824 -28.462224)
		(width 0.10795)
		(layer "B.Cu")
		(net "FM_PWRBRK_N")
	)
	(segment
		(start 379.72365 -39.906194)
		(end 378.974858 -40.654986)
		(width 0.10795)
		(layer "B.Cu")
		(net "FM_PWRBRK_N")
	)
	(segment
		(start 456.637898 -22.408642)
		(end 456.362562 -22.133306)
		(width 0.10795)
		(layer "B.Cu")
		(net "FM_PWRBRK_N")
	)
	(segment
		(start 457.97978 -28.462224)
		(end 456.637898 -27.120342)
		(width 0.10795)
		(layer "B.Cu")
		(net "FM_PWRBRK_N")
	)
	(segment
		(start 385.809998 -38.742112)
		(end 385.809998 -39.131748)
		(width 0.10795)
		(layer "B.Cu")
		(net "FM_PWRBRK_N")
	)
	(segment
		(start 391.524236 -35.527234)
		(end 391.512298 -35.515296)
		(width 0.10795)
		(layer "B.Cu")
		(net "FM_PWRBRK_N")
	)
	(segment
		(start 379.876558 -39.906194)
		(end 379.72365 -39.906194)
		(width 0.10795)
		(layer "B.Cu")
		(net "FM_PWRBRK_N")
	)
	(segment
		(start 378.72035 -40.915082)
		(end 378.72035 -41.728136)
		(width 0.10795)
		(layer "B.Cu")
		(net "FM_PWRBRK_N")
	)
	(segment
		(start 468.290402 -4.217924)
		(end 468.290402 -3.168904)
		(width 0.10795)
		(layer "B.Cu")
		(net "FM_PWRBRK_N")
	)
	(segment
		(start 378.72035 -41.728136)
		(end 378.2314 -42.217086)
		(width 0.10795)
		(layer "B.Cu")
		(net "FM_PWRBRK_N")
	)
	(segment
		(start 468.290402 -3.168904)
		(end 468.191596 -3.070098)
		(width 0.10795)
		(layer "B.Cu")
		(net "FM_PWRBRK_N")
	)
	(segment
		(start 460.5655 -7.271004)
		(end 460.56169 -7.274814)
		(width 0.10795)
		(layer "B.Cu")
		(net "FM_PWRBRK_N")
	)
	(segment
		(start 457.577952 -11.702288)
		(end 456.65136 -12.62888)
		(width 0.10795)
		(layer "B.Cu")
		(net "FM_PWRBRK_N")
	)
	(segment
		(start 467.868 -4.656328)
		(end 467.868 -4.3815)
		(width 0.10795)
		(layer "B.Cu")
		(net "FM_PWRBRK_N")
	)
	(segment
		(start 453.753728 -14.831568)
		(end 455.859896 -12.7254)
		(width 0.10795)
		(layer "B.Cu")
		(net "FM_PWRBRK_N")
	)
	(segment
		(start 378.2314 -42.217086)
		(end 378.2314 -42.799)
		(width 0.10795)
		(layer "B.Cu")
		(net "FM_PWRBRK_N")
	)
	(segment
		(start 380.601982 -40.631618)
		(end 379.876558 -39.906194)
		(width 0.10795)
		(layer "B.Cu")
		(net "FM_PWRBRK_N")
	)
	(segment
		(start 454.197212 -16.374364)
		(end 454.197212 -15.729458)
		(width 0.10795)
		(layer "B.Cu")
		(net "FM_PWRBRK_N")
	)
	(segment
		(start 466.5472 -2.8956)
		(end 465.7598 -2.1082)
		(width 0.10795)
		(layer "B.Cu")
		(net "FM_PWRBRK_N")
	)
	(segment
		(start 460.56169 -7.274814)
		(end 460.56169 -7.35711)
		(width 0.10795)
		(layer "B.Cu")
		(net "FM_PWRBRK_N")
	)
	(segment
		(start 384.58648 -40.631618)
		(end 380.601982 -40.631618)
		(width 0.10795)
		(layer "B.Cu")
		(net "FM_PWRBRK_N")
	)
	(segment
		(start 465.7598 -2.1082)
		(end 464.315302 -2.1082)
		(width 0.10795)
		(layer "B.Cu")
		(net "FM_PWRBRK_N")
	)
	(segment
		(start 460.8957 -4.8895)
		(end 460.5655 -5.2197)
		(width 0.10795)
		(layer "B.Cu")
		(net "FM_PWRBRK_N")
	)
	(segment
		(start 378.974858 -40.654986)
		(end 378.974858 -40.660574)
		(width 0.10795)
		(layer "B.Cu")
		(net "FM_PWRBRK_N")
	)
	(segment
		(start 385.809744 -39.132002)
		(end 385.809744 -39.408354)
		(width 0.10795)
		(layer "B.Cu")
		(net "FM_PWRBRK_N")
	)
	(segment
		(start 388.531608 -36.792154)
		(end 386.15747 -36.792154)
		(width 0.10795)
		(layer "B.Cu")
		(net "FM_PWRBRK_N")
	)
	(segment
		(start 456.362562 -22.133306)
		(end 456.362562 -19.724878)
		(width 0.10795)
		(layer "B.Cu")
		(net "FM_PWRBRK_N")
	)
	(segment
		(start 389.411718 -35.912044)
		(end 388.531608 -36.792154)
		(width 0.10795)
		(layer "B.Cu")
		(net "FM_PWRBRK_N")
	)
	(segment
		(start 467.233 -2.8956)
		(end 466.5472 -2.8956)
		(width 0.10795)
		(layer "B.Cu")
		(net "FM_PWRBRK_N")
	)
	(segment
		(start 460.4004 -31.086044)
		(end 458.6224 -29.308044)
		(width 0.10795)
		(layer "B.Cu")
		(net "FM_PWRBRK_N")
	)
	(segment
		(start 467.407498 -3.070098)
		(end 467.233 -2.8956)
		(width 0.10795)
		(layer "B.Cu")
		(net "FM_PWRBRK_N")
	)
	(segment
		(start 456.362562 -19.724878)
		(end 454.853548 -18.215864)
		(width 0.10795)
		(layer "B.Cu")
		(net "FM_PWRBRK_N")
	)
	(segment
		(start 385.809744 -39.408354)
		(end 384.58648 -40.631618)
		(width 0.10795)
		(layer "B.Cu")
		(net "FM_PWRBRK_N")
	)
	(segment
		(start 455.859896 -12.7254)
		(end 456.55484 -12.7254)
		(width 0.10795)
		(layer "B.Cu")
		(net "FM_PWRBRK_N")
	)
	(segment
		(start 460.5655 -5.2197)
		(end 460.5655 -7.271004)
		(width 0.10795)
		(layer "B.Cu")
		(net "FM_PWRBRK_N")
	)
	(segment
		(start 389.975852 -35.912044)
		(end 389.411718 -35.912044)
		(width 0.10795)
		(layer "B.Cu")
		(net "FM_PWRBRK_N")
	)
	(segment
		(start 385.809744 -38.741858)
		(end 385.809998 -38.742112)
		(width 0.10795)
		(layer "B.Cu")
		(net "FM_PWRBRK_N")
	)
	(segment
		(start 459.015846 -8.0518)
		(end 457.577952 -9.489694)
		(width 0.10795)
		(layer "B.Cu")
		(net "FM_PWRBRK_N")
	)
	(segment
		(start 454.853548 -18.215864)
		(end 454.853548 -17.0307)
		(width 0.10795)
		(layer "B.Cu")
		(net "FM_PWRBRK_N")
	)
	(segment
		(start 464.315302 -2.1082)
		(end 463.17535 -3.248152)
		(width 0.10795)
		(layer "B.Cu")
		(net "FM_PWRBRK_N")
	)
	(segment
		(start 468.191596 -3.070098)
		(end 467.407498 -3.070098)
		(width 0.10795)
		(layer "B.Cu")
		(net "FM_PWRBRK_N")
	)
	(segment
		(start 467.868 -4.3815)
		(end 468.126826 -4.3815)
		(width 0.10795)
		(layer "B.Cu")
		(net "FM_PWRBRK_N")
	)
	(segment
		(start 454.853548 -17.0307)
		(end 454.197212 -16.374364)
		(width 0.10795)
		(layer "B.Cu")
		(net "FM_PWRBRK_N")
	)
	(segment
		(start 462.047082 -4.8895)
		(end 460.8957 -4.8895)
		(width 0.10795)
		(layer "B.Cu")
		(net "FM_PWRBRK_N")
	)
	(segment
		(start 468.126826 -4.3815)
		(end 468.290402 -4.217924)
		(width 0.10795)
		(layer "B.Cu")
		(net "FM_PWRBRK_N")
	)
	(segment
		(start 390.3726 -35.515296)
		(end 389.975852 -35.912044)
		(width 0.10795)
		(layer "B.Cu")
		(net "FM_PWRBRK_N")
	)
	(segment
		(start 457.577952 -9.489694)
		(end 457.577952 -11.702288)
		(width 0.10795)
		(layer "B.Cu")
		(net "FM_PWRBRK_N")
	)
	(segment
		(start 468.58809 -5.122672)
		(end 468.334344 -5.122672)
		(width 0.10795)
		(layer "B.Cu")
		(net "FM_PWRBRK_N")
	)
	(segment
		(start 458.6224 -29.308044)
		(end 458.6224 -28.7528)
		(width 0.10795)
		(layer "B.Cu")
		(net "FM_PWRBRK_N")
	)
	(segment
		(start 386.15747 -36.792154)
		(end 385.809744 -37.13988)
		(width 0.10795)
		(layer "B.Cu")
		(net "FM_PWRBRK_N")
	)
	(segment
		(start 468.334344 -5.122672)
		(end 467.868 -4.656328)
		(width 0.10795)
		(layer "B.Cu")
		(net "FM_PWRBRK_N")
	)
	(segment
		(start 460.4004 -31.536132)
		(end 460.4004 -31.086044)
		(width 0.10795)
		(layer "B.Cu")
		(net "FM_PWRBRK_N")
	)
	(segment
		(start 461.370172 -32.505904)
		(end 460.4004 -31.536132)
		(width 0.10795)
		(layer "B.Cu")
		(net "FM_PWRBRK_N")
	)
	(segment
		(start 391.512298 -35.515296)
		(end 390.3726 -35.515296)
		(width 0.10795)
		(layer "B.Cu")
		(net "FM_PWRBRK_N")
	)
	(segment
		(start 398.93875 -31.417006)
		(end 396.487396 -33.86836)
		(width 0.089408)
		(layer "In2.Cu")
		(net "FM_PWRBRK_N")
	)
	(segment
		(start 419.490144 -28.534614)
		(end 419.09238 -28.13685)
		(width 0.089408)
		(layer "In2.Cu")
		(net "FM_PWRBRK_N")
	)
	(segment
		(start 405.384 -31.496)
		(end 404.629112 -32.250888)
		(width 0.089408)
		(layer "In2.Cu")
		(net "FM_PWRBRK_N")
	)
	(segment
		(start 395.903196 -36.644834)
		(end 394.109448 -36.644834)
		(width 0.089408)
		(layer "In2.Cu")
		(net "FM_PWRBRK_N")
	)
	(segment
		(start 411.701996 -28.960064)
		(end 410.919422 -29.742638)
		(width 0.089408)
		(layer "In2.Cu")
		(net "FM_PWRBRK_N")
	)
	(segment
		(start 394.109448 -36.644834)
		(end 392.97991 -35.515296)
		(width 0.089408)
		(layer "In2.Cu")
		(net "FM_PWRBRK_N")
	)
	(segment
		(start 396.487396 -36.060634)
		(end 395.903196 -36.644834)
		(width 0.089408)
		(layer "In2.Cu")
		(net "FM_PWRBRK_N")
	)
	(segment
		(start 391.536174 -35.515296)
		(end 391.524236 -35.527234)
		(width 0.089408)
		(layer "In2.Cu")
		(net "FM_PWRBRK_N")
	)
	(segment
		(start 402.353018 -32.250888)
		(end 401.519136 -31.417006)
		(width 0.089408)
		(layer "In2.Cu")
		(net "FM_PWRBRK_N")
	)
	(segment
		(start 401.519136 -31.417006)
		(end 398.93875 -31.417006)
		(width 0.089408)
		(layer "In2.Cu")
		(net "FM_PWRBRK_N")
	)
	(segment
		(start 407.227024 -30.154118)
		(end 407.227024 -30.927548)
		(width 0.089408)
		(layer "In2.Cu")
		(net "FM_PWRBRK_N")
	)
	(segment
		(start 404.629112 -32.250888)
		(end 402.353018 -32.250888)
		(width 0.089408)
		(layer "In2.Cu")
		(net "FM_PWRBRK_N")
	)
	(segment
		(start 419.09238 -28.13685)
		(end 415.881058 -28.13685)
		(width 0.089408)
		(layer "In2.Cu")
		(net "FM_PWRBRK_N")
	)
	(segment
		(start 407.227024 -30.927548)
		(end 406.658572 -31.496)
		(width 0.089408)
		(layer "In2.Cu")
		(net "FM_PWRBRK_N")
	)
	(segment
		(start 415.057844 -28.960064)
		(end 411.701996 -28.960064)
		(width 0.089408)
		(layer "In2.Cu")
		(net "FM_PWRBRK_N")
	)
	(segment
		(start 396.487396 -33.86836)
		(end 396.487396 -36.060634)
		(width 0.089408)
		(layer "In2.Cu")
		(net "FM_PWRBRK_N")
	)
	(segment
		(start 406.658572 -31.496)
		(end 405.384 -31.496)
		(width 0.089408)
		(layer "In2.Cu")
		(net "FM_PWRBRK_N")
	)
	(segment
		(start 392.97991 -35.515296)
		(end 391.536174 -35.515296)
		(width 0.089408)
		(layer "In2.Cu")
		(net "FM_PWRBRK_N")
	)
	(segment
		(start 415.881058 -28.13685)
		(end 415.057844 -28.960064)
		(width 0.089408)
		(layer "In2.Cu")
		(net "FM_PWRBRK_N")
	)
	(segment
		(start 407.638504 -29.742638)
		(end 407.227024 -30.154118)
		(width 0.089408)
		(layer "In2.Cu")
		(net "FM_PWRBRK_N")
	)
	(segment
		(start 410.919422 -29.742638)
		(end 407.638504 -29.742638)
		(width 0.089408)
		(layer "In2.Cu")
		(net "FM_PWRBRK_N")
	)
	(segment
		(start 420.398702 -28.1559)
		(end 420.6748 -27.879802)
		(width 0.089408)
		(layer "In4.Cu")
		(net "FM_PWRBRK_N")
	)
	(segment
		(start 436.930292 -22.62632)
		(end 444.051944 -22.62632)
		(width 0.089408)
		(layer "In4.Cu")
		(net "FM_PWRBRK_N")
	)
	(segment
		(start 460.928466 -32.94761)
		(end 461.370172 -32.505904)
		(width 0.089408)
		(layer "In4.Cu")
		(net "FM_PWRBRK_N")
	)
	(segment
		(start 444.051944 -22.62632)
		(end 446.222628 -24.797004)
		(width 0.089408)
		(layer "In4.Cu")
		(net "FM_PWRBRK_N")
	)
	(segment
		(start 420.6748 -27.61996)
		(end 421.380158 -26.914602)
		(width 0.089408)
		(layer "In4.Cu")
		(net "FM_PWRBRK_N")
	)
	(segment
		(start 458.716888 -31.996888)
		(end 459.373478 -31.996888)
		(width 0.089408)
		(layer "In4.Cu")
		(net "FM_PWRBRK_N")
	)
	(segment
		(start 435.656228 -23.13178)
		(end 436.424832 -23.13178)
		(width 0.089408)
		(layer "In4.Cu")
		(net "FM_PWRBRK_N")
	)
	(segment
		(start 431.259488 -26.05532)
		(end 432.732688 -26.05532)
		(width 0.089408)
		(layer "In4.Cu")
		(net "FM_PWRBRK_N")
	)
	(segment
		(start 436.424832 -23.13178)
		(end 436.930292 -22.62632)
		(width 0.089408)
		(layer "In4.Cu")
		(net "FM_PWRBRK_N")
	)
	(segment
		(start 419.490144 -28.534614)
		(end 419.643306 -28.534614)
		(width 0.089408)
		(layer "In4.Cu")
		(net "FM_PWRBRK_N")
	)
	(segment
		(start 420.6748 -27.879802)
		(end 420.6748 -27.61996)
		(width 0.089408)
		(layer "In4.Cu")
		(net "FM_PWRBRK_N")
	)
	(segment
		(start 426.450252 -27.491182)
		(end 429.823626 -27.491182)
		(width 0.089408)
		(layer "In4.Cu")
		(net "FM_PWRBRK_N")
	)
	(segment
		(start 459.400148 -32.008318)
		(end 460.33944 -32.94761)
		(width 0.089408)
		(layer "In4.Cu")
		(net "FM_PWRBRK_N")
	)
	(segment
		(start 421.380158 -26.914602)
		(end 422.769538 -26.914602)
		(width 0.089408)
		(layer "In4.Cu")
		(net "FM_PWRBRK_N")
	)
	(segment
		(start 458.283818 -31.563818)
		(end 458.716888 -31.996888)
		(width 0.089408)
		(layer "In4.Cu")
		(net "FM_PWRBRK_N")
	)
	(segment
		(start 460.33944 -32.94761)
		(end 460.928466 -32.94761)
		(width 0.089408)
		(layer "In4.Cu")
		(net "FM_PWRBRK_N")
	)
	(segment
		(start 446.222628 -25.531572)
		(end 450.719952 -30.028896)
		(width 0.089408)
		(layer "In4.Cu")
		(net "FM_PWRBRK_N")
	)
	(segment
		(start 432.732688 -26.05532)
		(end 435.656228 -23.13178)
		(width 0.089408)
		(layer "In4.Cu")
		(net "FM_PWRBRK_N")
	)
	(segment
		(start 426.37075 -27.490674)
		(end 426.371004 -27.490928)
		(width 0.089408)
		(layer "In4.Cu")
		(net "FM_PWRBRK_N")
	)
	(segment
		(start 459.384908 -32.008318)
		(end 459.400148 -32.008318)
		(width 0.089408)
		(layer "In4.Cu")
		(net "FM_PWRBRK_N")
	)
	(segment
		(start 420.02202 -28.1559)
		(end 420.398702 -28.1559)
		(width 0.089408)
		(layer "In4.Cu")
		(net "FM_PWRBRK_N")
	)
	(segment
		(start 446.222628 -24.797004)
		(end 446.222628 -25.531572)
		(width 0.089408)
		(layer "In4.Cu")
		(net "FM_PWRBRK_N")
	)
	(segment
		(start 423.34561 -27.490674)
		(end 426.37075 -27.490674)
		(width 0.089408)
		(layer "In4.Cu")
		(net "FM_PWRBRK_N")
	)
	(segment
		(start 419.643306 -28.534614)
		(end 420.02202 -28.1559)
		(width 0.089408)
		(layer "In4.Cu")
		(net "FM_PWRBRK_N")
	)
	(segment
		(start 426.371004 -27.490928)
		(end 426.449998 -27.490928)
		(width 0.089408)
		(layer "In4.Cu")
		(net "FM_PWRBRK_N")
	)
	(segment
		(start 459.373478 -31.996888)
		(end 459.384908 -32.008318)
		(width 0.089408)
		(layer "In4.Cu")
		(net "FM_PWRBRK_N")
	)
	(segment
		(start 450.719952 -30.028896)
		(end 452.753984 -30.028896)
		(width 0.089408)
		(layer "In4.Cu")
		(net "FM_PWRBRK_N")
	)
	(segment
		(start 452.753984 -30.028896)
		(end 454.288906 -31.563818)
		(width 0.089408)
		(layer "In4.Cu")
		(net "FM_PWRBRK_N")
	)
	(segment
		(start 429.823626 -27.491182)
		(end 431.259488 -26.05532)
		(width 0.089408)
		(layer "In4.Cu")
		(net "FM_PWRBRK_N")
	)
	(segment
		(start 426.449998 -27.490928)
		(end 426.450252 -27.491182)
		(width 0.089408)
		(layer "In4.Cu")
		(net "FM_PWRBRK_N")
	)
	(segment
		(start 454.288906 -31.563818)
		(end 458.283818 -31.563818)
		(width 0.089408)
		(layer "In4.Cu")
		(net "FM_PWRBRK_N")
	)
	(segment
		(start 422.769538 -26.914602)
		(end 423.34561 -27.490674)
		(width 0.089408)
		(layer "In4.Cu")
		(net "FM_PWRBRK_N")
	)
	(segment
		(start 183.665114 -115.55095)
		(end 183.665114 -117.405912)
		(width 0.10795)
		(layer "F.Cu")
		(net "FM_PVCCIOMCP_CPU1_EN")
	)
	(segment
		(start 181.8894 -119.181626)
		(end 181.8894 -121.98604)
		(width 0.10795)
		(layer "F.Cu")
		(net "FM_PVCCIOMCP_CPU1_EN")
	)
	(segment
		(start 183.665114 -117.405912)
		(end 181.8894 -119.181626)
		(width 0.10795)
		(layer "F.Cu")
		(net "FM_PVCCIOMCP_CPU1_EN")
	)
	(segment
		(start 181.353968 -127.950468)
		(end 181.353968 -123.194826)
		(width 0.10795)
		(layer "F.Cu")
		(net "FM_PVCCIOMCP_CPU1_EN")
	)
	(segment
		(start 181.353968 -123.194826)
		(end 181.556914 -122.99188)
		(width 0.10795)
		(layer "F.Cu")
		(net "FM_PVCCIOMCP_CPU1_EN")
	)
	(segment
		(start 374.344692 -79.094838)
		(end 373.944896 -78.695042)
		(width 0.1016)
		(layer "F.Cu")
		(net "FM_PVCCIOMCP_CPU1_EN")
	)
	(segment
		(start 181.556914 -122.318526)
		(end 181.8894 -121.98604)
		(width 0.10795)
		(layer "F.Cu")
		(net "FM_PVCCIOMCP_CPU1_EN")
	)
	(segment
		(start 181.8386 -128.4351)
		(end 181.353968 -127.950468)
		(width 0.10795)
		(layer "F.Cu")
		(net "FM_PVCCIOMCP_CPU1_EN")
	)
	(segment
		(start 181.556914 -122.99188)
		(end 181.556914 -122.318526)
		(width 0.10795)
		(layer "F.Cu")
		(net "FM_PVCCIOMCP_CPU1_EN")
	)
	(via
		(at 374.344692 -79.094838)
		(size 0.4572)
		(drill 0.2032)
		(layers "F.Cu" "B.Cu")
		(net "FM_PVCCIOMCP_CPU1_EN")
	)
	(via
		(at 335.3562 -126.5682)
		(size 0.508)
		(drill 0.254)
		(layers "F.Cu" "B.Cu")
		(net "FM_PVCCIOMCP_CPU1_EN")
	)
	(via
		(at 181.8894 -121.98604)
		(size 0.762)
		(drill 0.381)
		(layers "F.Cu" "B.Cu")
		(net "FM_PVCCIOMCP_CPU1_EN")
	)
	(via
		(at 181.8386 -128.4351)
		(size 0.508)
		(drill 0.254)
		(layers "F.Cu" "B.Cu")
		(net "FM_PVCCIOMCP_CPU1_EN")
	)
	(segment
		(start 337.998562 -75.934316)
		(end 338.822538 -75.11034)
		(width 0.089408)
		(layer "In4.Cu")
		(net "FM_PVCCIOMCP_CPU1_EN")
	)
	(segment
		(start 366.21085 -77.089)
		(end 366.46739 -77.089)
		(width 0.089408)
		(layer "In4.Cu")
		(net "FM_PVCCIOMCP_CPU1_EN")
	)
	(segment
		(start 367.011458 -77.8891)
		(end 372.611142 -77.8891)
		(width 0.089408)
		(layer "In4.Cu")
		(net "FM_PVCCIOMCP_CPU1_EN")
	)
	(segment
		(start 345.04757 -73.11263)
		(end 345.6432 -72.517)
		(width 0.089408)
		(layer "In4.Cu")
		(net "FM_PVCCIOMCP_CPU1_EN")
	)
	(segment
		(start 342.535764 -74.063098)
		(end 343.486232 -73.11263)
		(width 0.089408)
		(layer "In4.Cu")
		(net "FM_PVCCIOMCP_CPU1_EN")
	)
	(segment
		(start 357.001572 -70.930516)
		(end 358.230932 -72.159876)
		(width 0.089408)
		(layer "In4.Cu")
		(net "FM_PVCCIOMCP_CPU1_EN")
	)
	(segment
		(start 332.365604 -123.577604)
		(end 329.894438 -123.577604)
		(width 0.089408)
		(layer "In4.Cu")
		(net "FM_PVCCIOMCP_CPU1_EN")
	)
	(segment
		(start 334.352646 -86.831424)
		(end 334.352646 -84.930234)
		(width 0.089408)
		(layer "In4.Cu")
		(net "FM_PVCCIOMCP_CPU1_EN")
	)
	(segment
		(start 329.33894 -112.44961)
		(end 328.435462 -111.546132)
		(width 0.089408)
		(layer "In4.Cu")
		(net "FM_PVCCIOMCP_CPU1_EN")
	)
	(segment
		(start 341.933784 -74.063098)
		(end 341.934038 -74.062844)
		(width 0.089408)
		(layer "In4.Cu")
		(net "FM_PVCCIOMCP_CPU1_EN")
	)
	(segment
		(start 328.435462 -111.546132)
		(end 328.435462 -92.748608)
		(width 0.089408)
		(layer "In4.Cu")
		(net "FM_PVCCIOMCP_CPU1_EN")
	)
	(segment
		(start 328.435462 -92.748608)
		(end 334.352646 -86.831424)
		(width 0.089408)
		(layer "In4.Cu")
		(net "FM_PVCCIOMCP_CPU1_EN")
	)
	(segment
		(start 366.46739 -77.089)
		(end 366.771936 -77.393546)
		(width 0.089408)
		(layer "In4.Cu")
		(net "FM_PVCCIOMCP_CPU1_EN")
	)
	(segment
		(start 365.51743 -74.806302)
		(end 365.51743 -76.39558)
		(width 0.089408)
		(layer "In4.Cu")
		(net "FM_PVCCIOMCP_CPU1_EN")
	)
	(segment
		(start 334.352646 -84.930234)
		(end 337.456526 -81.817972)
		(width 0.089408)
		(layer "In4.Cu")
		(net "FM_PVCCIOMCP_CPU1_EN")
	)
	(segment
		(start 373.39016 -78.668118)
		(end 373.701056 -78.668118)
		(width 0.089408)
		(layer "In4.Cu")
		(net "FM_PVCCIOMCP_CPU1_EN")
	)
	(segment
		(start 362.871004 -72.159876)
		(end 365.51743 -74.806302)
		(width 0.089408)
		(layer "In4.Cu")
		(net "FM_PVCCIOMCP_CPU1_EN")
	)
	(segment
		(start 342.092026 -74.062844)
		(end 342.09228 -74.063098)
		(width 0.089408)
		(layer "In4.Cu")
		(net "FM_PVCCIOMCP_CPU1_EN")
	)
	(segment
		(start 373.701056 -78.668118)
		(end 374.127776 -79.094838)
		(width 0.089408)
		(layer "In4.Cu")
		(net "FM_PVCCIOMCP_CPU1_EN")
	)
	(segment
		(start 329.33894 -123.022106)
		(end 329.33894 -112.44961)
		(width 0.089408)
		(layer "In4.Cu")
		(net "FM_PVCCIOMCP_CPU1_EN")
	)
	(segment
		(start 341.934038 -74.062844)
		(end 342.092026 -74.062844)
		(width 0.089408)
		(layer "In4.Cu")
		(net "FM_PVCCIOMCP_CPU1_EN")
	)
	(segment
		(start 338.98078 -75.110594)
		(end 340.34095 -75.110594)
		(width 0.089408)
		(layer "In4.Cu")
		(net "FM_PVCCIOMCP_CPU1_EN")
	)
	(segment
		(start 329.894438 -123.577604)
		(end 329.33894 -123.022106)
		(width 0.089408)
		(layer "In4.Cu")
		(net "FM_PVCCIOMCP_CPU1_EN")
	)
	(segment
		(start 365.51743 -76.39558)
		(end 366.21085 -77.089)
		(width 0.089408)
		(layer "In4.Cu")
		(net "FM_PVCCIOMCP_CPU1_EN")
	)
	(segment
		(start 372.611142 -77.8891)
		(end 373.39016 -78.668118)
		(width 0.089408)
		(layer "In4.Cu")
		(net "FM_PVCCIOMCP_CPU1_EN")
	)
	(segment
		(start 351.9551 -71.31304)
		(end 352.150426 -71.508366)
		(width 0.089408)
		(layer "In4.Cu")
		(net "FM_PVCCIOMCP_CPU1_EN")
	)
	(segment
		(start 358.230932 -72.159876)
		(end 362.871004 -72.159876)
		(width 0.089408)
		(layer "In4.Cu")
		(net "FM_PVCCIOMCP_CPU1_EN")
	)
	(segment
		(start 338.980526 -75.11034)
		(end 338.98078 -75.110594)
		(width 0.089408)
		(layer "In4.Cu")
		(net "FM_PVCCIOMCP_CPU1_EN")
	)
	(segment
		(start 343.486232 -73.11263)
		(end 345.04757 -73.11263)
		(width 0.089408)
		(layer "In4.Cu")
		(net "FM_PVCCIOMCP_CPU1_EN")
	)
	(segment
		(start 352.150426 -71.508366)
		(end 354.307648 -71.508366)
		(width 0.089408)
		(layer "In4.Cu")
		(net "FM_PVCCIOMCP_CPU1_EN")
	)
	(segment
		(start 345.6432 -72.517)
		(end 345.6432 -72.230488)
		(width 0.089408)
		(layer "In4.Cu")
		(net "FM_PVCCIOMCP_CPU1_EN")
	)
	(segment
		(start 337.456526 -78.613254)
		(end 337.998562 -78.071218)
		(width 0.089408)
		(layer "In4.Cu")
		(net "FM_PVCCIOMCP_CPU1_EN")
	)
	(segment
		(start 346.560648 -71.31304)
		(end 351.9551 -71.31304)
		(width 0.089408)
		(layer "In4.Cu")
		(net "FM_PVCCIOMCP_CPU1_EN")
	)
	(segment
		(start 354.307648 -71.508366)
		(end 354.885498 -70.930516)
		(width 0.089408)
		(layer "In4.Cu")
		(net "FM_PVCCIOMCP_CPU1_EN")
	)
	(segment
		(start 366.771936 -77.649578)
		(end 367.011458 -77.8891)
		(width 0.089408)
		(layer "In4.Cu")
		(net "FM_PVCCIOMCP_CPU1_EN")
	)
	(segment
		(start 335.3562 -126.5682)
		(end 332.365604 -123.577604)
		(width 0.089408)
		(layer "In4.Cu")
		(net "FM_PVCCIOMCP_CPU1_EN")
	)
	(segment
		(start 337.998562 -78.071218)
		(end 337.998562 -75.934316)
		(width 0.089408)
		(layer "In4.Cu")
		(net "FM_PVCCIOMCP_CPU1_EN")
	)
	(segment
		(start 341.388446 -74.063098)
		(end 341.933784 -74.063098)
		(width 0.089408)
		(layer "In4.Cu")
		(net "FM_PVCCIOMCP_CPU1_EN")
	)
	(segment
		(start 366.771936 -77.393546)
		(end 366.771936 -77.649578)
		(width 0.089408)
		(layer "In4.Cu")
		(net "FM_PVCCIOMCP_CPU1_EN")
	)
	(segment
		(start 342.09228 -74.063098)
		(end 342.535764 -74.063098)
		(width 0.089408)
		(layer "In4.Cu")
		(net "FM_PVCCIOMCP_CPU1_EN")
	)
	(segment
		(start 340.34095 -75.110594)
		(end 341.388446 -74.063098)
		(width 0.089408)
		(layer "In4.Cu")
		(net "FM_PVCCIOMCP_CPU1_EN")
	)
	(segment
		(start 338.822538 -75.11034)
		(end 338.980526 -75.11034)
		(width 0.089408)
		(layer "In4.Cu")
		(net "FM_PVCCIOMCP_CPU1_EN")
	)
	(segment
		(start 337.456526 -81.817972)
		(end 337.456526 -78.613254)
		(width 0.089408)
		(layer "In4.Cu")
		(net "FM_PVCCIOMCP_CPU1_EN")
	)
	(segment
		(start 345.6432 -72.230488)
		(end 346.560648 -71.31304)
		(width 0.089408)
		(layer "In4.Cu")
		(net "FM_PVCCIOMCP_CPU1_EN")
	)
	(segment
		(start 354.885498 -70.930516)
		(end 357.001572 -70.930516)
		(width 0.089408)
		(layer "In4.Cu")
		(net "FM_PVCCIOMCP_CPU1_EN")
	)
	(segment
		(start 374.127776 -79.094838)
		(end 374.344692 -79.094838)
		(width 0.089408)
		(layer "In4.Cu")
		(net "FM_PVCCIOMCP_CPU1_EN")
	)
	(segment
		(start 181.916832 -128.513332)
		(end 182.496714 -128.513332)
		(width 0.089408)
		(layer "In9.Cu")
		(net "FM_PVCCIOMCP_CPU1_EN")
	)
	(segment
		(start 186.741816 -130.992118)
		(end 188.458602 -132.708904)
		(width 0.089408)
		(layer "In9.Cu")
		(net "FM_PVCCIOMCP_CPU1_EN")
	)
	(segment
		(start 182.496714 -128.513332)
		(end 182.547514 -128.564132)
		(width 0.089408)
		(layer "In9.Cu")
		(net "FM_PVCCIOMCP_CPU1_EN")
	)
	(segment
		(start 261.10692 -135.96239)
		(end 262.579104 -137.434574)
		(width 0.089408)
		(layer "In9.Cu")
		(net "FM_PVCCIOMCP_CPU1_EN")
	)
	(segment
		(start 182.547514 -128.564132)
		(end 183.358028 -128.564132)
		(width 0.089408)
		(layer "In9.Cu")
		(net "FM_PVCCIOMCP_CPU1_EN")
	)
	(segment
		(start 335.64576 -127.999744)
		(end 335.64576 -126.85776)
		(width 0.089408)
		(layer "In9.Cu")
		(net "FM_PVCCIOMCP_CPU1_EN")
	)
	(segment
		(start 335.64576 -126.85776)
		(end 335.3562 -126.5682)
		(width 0.089408)
		(layer "In9.Cu")
		(net "FM_PVCCIOMCP_CPU1_EN")
	)
	(segment
		(start 181.8386 -128.4351)
		(end 181.916832 -128.513332)
		(width 0.089408)
		(layer "In9.Cu")
		(net "FM_PVCCIOMCP_CPU1_EN")
	)
	(segment
		(start 334.740504 -128.905)
		(end 335.64576 -127.999744)
		(width 0.089408)
		(layer "In9.Cu")
		(net "FM_PVCCIOMCP_CPU1_EN")
	)
	(segment
		(start 184.063386 -129.197608)
		(end 184.08777 -129.221992)
		(width 0.089408)
		(layer "In9.Cu")
		(net "FM_PVCCIOMCP_CPU1_EN")
	)
	(segment
		(start 321.683126 -137.399776)
		(end 322.929504 -136.153398)
		(width 0.089408)
		(layer "In9.Cu")
		(net "FM_PVCCIOMCP_CPU1_EN")
	)
	(segment
		(start 258.94284 -137.191496)
		(end 260.171946 -135.96239)
		(width 0.089408)
		(layer "In9.Cu")
		(net "FM_PVCCIOMCP_CPU1_EN")
	)
	(segment
		(start 184.08777 -129.221992)
		(end 186.05881 -129.221992)
		(width 0.089408)
		(layer "In9.Cu")
		(net "FM_PVCCIOMCP_CPU1_EN")
	)
	(segment
		(start 322.929504 -136.153398)
		(end 322.929504 -135.511032)
		(width 0.089408)
		(layer "In9.Cu")
		(net "FM_PVCCIOMCP_CPU1_EN")
	)
	(segment
		(start 194.264534 -137.191496)
		(end 258.94284 -137.191496)
		(width 0.089408)
		(layer "In9.Cu")
		(net "FM_PVCCIOMCP_CPU1_EN")
	)
	(segment
		(start 332.472538 -128.905)
		(end 334.740504 -128.905)
		(width 0.089408)
		(layer "In9.Cu")
		(net "FM_PVCCIOMCP_CPU1_EN")
	)
	(segment
		(start 191.45885 -134.457694)
		(end 194.069208 -137.068052)
		(width 0.089408)
		(layer "In9.Cu")
		(net "FM_PVCCIOMCP_CPU1_EN")
	)
	(segment
		(start 189.795658 -132.708904)
		(end 191.45885 -134.372096)
		(width 0.089408)
		(layer "In9.Cu")
		(net "FM_PVCCIOMCP_CPU1_EN")
	)
	(segment
		(start 330.857606 -130.519932)
		(end 332.472538 -128.905)
		(width 0.089408)
		(layer "In9.Cu")
		(net "FM_PVCCIOMCP_CPU1_EN")
	)
	(segment
		(start 329.703938 -132.740654)
		(end 330.857606 -131.586986)
		(width 0.089408)
		(layer "In9.Cu")
		(net "FM_PVCCIOMCP_CPU1_EN")
	)
	(segment
		(start 321.288918 -137.434574)
		(end 321.323716 -137.399776)
		(width 0.089408)
		(layer "In9.Cu")
		(net "FM_PVCCIOMCP_CPU1_EN")
	)
	(segment
		(start 186.741816 -129.904998)
		(end 186.741816 -130.992118)
		(width 0.089408)
		(layer "In9.Cu")
		(net "FM_PVCCIOMCP_CPU1_EN")
	)
	(segment
		(start 330.857606 -131.586986)
		(end 330.857606 -130.519932)
		(width 0.089408)
		(layer "In9.Cu")
		(net "FM_PVCCIOMCP_CPU1_EN")
	)
	(segment
		(start 188.458602 -132.708904)
		(end 189.795658 -132.708904)
		(width 0.089408)
		(layer "In9.Cu")
		(net "FM_PVCCIOMCP_CPU1_EN")
	)
	(segment
		(start 183.358028 -128.564132)
		(end 183.991504 -129.197608)
		(width 0.089408)
		(layer "In9.Cu")
		(net "FM_PVCCIOMCP_CPU1_EN")
	)
	(segment
		(start 262.579104 -137.434574)
		(end 321.288918 -137.434574)
		(width 0.089408)
		(layer "In9.Cu")
		(net "FM_PVCCIOMCP_CPU1_EN")
	)
	(segment
		(start 183.991504 -129.197608)
		(end 184.063386 -129.197608)
		(width 0.089408)
		(layer "In9.Cu")
		(net "FM_PVCCIOMCP_CPU1_EN")
	)
	(segment
		(start 191.45885 -134.372096)
		(end 191.45885 -134.457694)
		(width 0.089408)
		(layer "In9.Cu")
		(net "FM_PVCCIOMCP_CPU1_EN")
	)
	(segment
		(start 260.171946 -135.96239)
		(end 261.10692 -135.96239)
		(width 0.089408)
		(layer "In9.Cu")
		(net "FM_PVCCIOMCP_CPU1_EN")
	)
	(segment
		(start 325.699882 -132.740654)
		(end 329.703938 -132.740654)
		(width 0.089408)
		(layer "In9.Cu")
		(net "FM_PVCCIOMCP_CPU1_EN")
	)
	(segment
		(start 194.069208 -137.068052)
		(end 194.14109 -137.068052)
		(width 0.089408)
		(layer "In9.Cu")
		(net "FM_PVCCIOMCP_CPU1_EN")
	)
	(segment
		(start 186.05881 -129.221992)
		(end 186.741816 -129.904998)
		(width 0.089408)
		(layer "In9.Cu")
		(net "FM_PVCCIOMCP_CPU1_EN")
	)
	(segment
		(start 322.929504 -135.511032)
		(end 325.699882 -132.740654)
		(width 0.089408)
		(layer "In9.Cu")
		(net "FM_PVCCIOMCP_CPU1_EN")
	)
	(segment
		(start 194.14109 -137.068052)
		(end 194.264534 -137.191496)
		(width 0.089408)
		(layer "In9.Cu")
		(net "FM_PVCCIOMCP_CPU1_EN")
	)
	(segment
		(start 321.323716 -137.399776)
		(end 321.683126 -137.399776)
		(width 0.089408)
		(layer "In9.Cu")
		(net "FM_PVCCIOMCP_CPU1_EN")
	)
	(via
		(at 362.4834 -40.4114)
		(size 0.6604)
		(drill 0.3302)
		(layers "F.Cu" "B.Cu")
		(net "FM_CPU_ERR0_LVT3_K_N")
	)
	(segment
		(start 362.270294 -41.480486)
		(end 362.270294 -41.135554)
		(width 0.10795)
		(layer "B.Cu")
		(net "FM_CPU_ERR0_LVT3_K_N")
	)
	(segment
		(start 361.888024 -40.4114)
		(end 362.4834 -40.4114)
		(width 0.10795)
		(layer "B.Cu")
		(net "FM_CPU_ERR0_LVT3_K_N")
	)
	(segment
		(start 361.444794 -40.85463)
		(end 361.888024 -40.4114)
		(width 0.10795)
		(layer "B.Cu")
		(net "FM_CPU_ERR0_LVT3_K_N")
	)
	(segment
		(start 362.4834 -40.922448)
		(end 362.4834 -40.4114)
		(width 0.10795)
		(layer "B.Cu")
		(net "FM_CPU_ERR0_LVT3_K_N")
	)
	(segment
		(start 361.444794 -42.305986)
		(end 361.444794 -41.543986)
		(width 0.10795)
		(layer "B.Cu")
		(net "FM_CPU_ERR0_LVT3_K_N")
	)
	(segment
		(start 361.444794 -41.543986)
		(end 361.444794 -40.85463)
		(width 0.10795)
		(layer "B.Cu")
		(net "FM_CPU_ERR0_LVT3_K_N")
	)
	(segment
		(start 362.270294 -41.135554)
		(end 362.4834 -40.922448)
		(width 0.10795)
		(layer "B.Cu")
		(net "FM_CPU_ERR0_LVT3_K_N")
	)
	(via
		(at 362.062522 -48.24984)
		(size 0.508)
		(drill 0.254)
		(layers "F.Cu" "B.Cu")
		(net "FM_CPU1_PROCHOT_LVT3_K_N")
	)
	(segment
		(start 361.444794 -47.258986)
		(end 361.444794 -47.985934)
		(width 0.10795)
		(layer "B.Cu")
		(net "FM_CPU1_PROCHOT_LVT3_K_N")
	)
	(segment
		(start 362.062522 -48.24984)
		(end 362.61167 -48.24984)
		(width 0.10795)
		(layer "B.Cu")
		(net "FM_CPU1_PROCHOT_LVT3_K_N")
	)
	(segment
		(start 361.444794 -47.258986)
		(end 361.444794 -46.496986)
		(width 0.10795)
		(layer "B.Cu")
		(net "FM_CPU1_PROCHOT_LVT3_K_N")
	)
	(segment
		(start 362.71962 -47.430436)
		(end 362.61167 -47.322486)
		(width 0.10795)
		(layer "B.Cu")
		(net "FM_CPU1_PROCHOT_LVT3_K_N")
	)
	(segment
		(start 361.444794 -47.985934)
		(end 361.7087 -48.24984)
		(width 0.10795)
		(layer "B.Cu")
		(net "FM_CPU1_PROCHOT_LVT3_K_N")
	)
	(segment
		(start 362.61167 -48.24984)
		(end 362.71962 -48.14189)
		(width 0.10795)
		(layer "B.Cu")
		(net "FM_CPU1_PROCHOT_LVT3_K_N")
	)
	(segment
		(start 362.61167 -47.322486)
		(end 362.270294 -47.322486)
		(width 0.10795)
		(layer "B.Cu")
		(net "FM_CPU1_PROCHOT_LVT3_K_N")
	)
	(segment
		(start 361.7087 -48.24984)
		(end 362.062522 -48.24984)
		(width 0.10795)
		(layer "B.Cu")
		(net "FM_CPU1_PROCHOT_LVT3_K_N")
	)
	(segment
		(start 362.71962 -48.14189)
		(end 362.71962 -47.430436)
		(width 0.10795)
		(layer "B.Cu")
		(net "FM_CPU1_PROCHOT_LVT3_K_N")
	)
	(via
		(at 359.618026 -46.223174)
		(size 0.6604)
		(drill 0.3302)
		(layers "F.Cu" "B.Cu")
		(net "FM_CPU0_PROCHOT_LVT3_K_N")
	)
	(segment
		(start 361.790234 -44.845986)
		(end 361.444794 -44.845986)
		(width 0.10795)
		(layer "B.Cu")
		(net "FM_CPU0_PROCHOT_LVT3_K_N")
	)
	(segment
		(start 362.270294 -44.782486)
		(end 361.853734 -44.782486)
		(width 0.10795)
		(layer "B.Cu")
		(net "FM_CPU0_PROCHOT_LVT3_K_N")
	)
	(segment
		(start 361.444794 -45.607986)
		(end 361.444794 -44.845986)
		(width 0.10795)
		(layer "B.Cu")
		(net "FM_CPU0_PROCHOT_LVT3_K_N")
	)
	(segment
		(start 361.853734 -44.782486)
		(end 361.790234 -44.845986)
		(width 0.10795)
		(layer "B.Cu")
		(net "FM_CPU0_PROCHOT_LVT3_K_N")
	)
	(segment
		(start 359.79227 -46.04893)
		(end 359.618026 -46.223174)
		(width 0.10795)
		(layer "B.Cu")
		(net "FM_CPU0_PROCHOT_LVT3_K_N")
	)
	(segment
		(start 361.444794 -45.607986)
		(end 361.444794 -45.777912)
		(width 0.10795)
		(layer "B.Cu")
		(net "FM_CPU0_PROCHOT_LVT3_K_N")
	)
	(segment
		(start 361.444794 -45.777912)
		(end 361.173776 -46.04893)
		(width 0.10795)
		(layer "B.Cu")
		(net "FM_CPU0_PROCHOT_LVT3_K_N")
	)
	(segment
		(start 361.173776 -46.04893)
		(end 359.79227 -46.04893)
		(width 0.10795)
		(layer "B.Cu")
		(net "FM_CPU0_PROCHOT_LVT3_K_N")
	)
	(via
		(at 428.76724 -11.1506)
		(size 0.6604)
		(drill 0.3302)
		(layers "F.Cu" "B.Cu")
		(net "H_CPU0_MEMABC_MEMHOT_LVT3_K_N")
	)
	(segment
		(start 428.879 -11.1506)
		(end 429.0822 -11.3538)
		(width 0.10795)
		(layer "B.Cu")
		(net "H_CPU0_MEMABC_MEMHOT_LVT3_K_N")
	)
	(segment
		(start 427.7995 -11.176)
		(end 427.8249 -11.1506)
		(width 0.10795)
		(layer "B.Cu")
		(net "H_CPU0_MEMABC_MEMHOT_LVT3_K_N")
	)
	(segment
		(start 427.8249 -11.1506)
		(end 428.76724 -11.1506)
		(width 0.10795)
		(layer "B.Cu")
		(net "H_CPU0_MEMABC_MEMHOT_LVT3_K_N")
	)
	(segment
		(start 429.0822 -11.3538)
		(end 429.0822 -12.2047)
		(width 0.10795)
		(layer "B.Cu")
		(net "H_CPU0_MEMABC_MEMHOT_LVT3_K_N")
	)
	(segment
		(start 427.795944 -11.179556)
		(end 427.7995 -11.176)
		(width 0.10795)
		(layer "B.Cu")
		(net "H_CPU0_MEMABC_MEMHOT_LVT3_K_N")
	)
	(segment
		(start 428.76724 -11.1506)
		(end 428.879 -11.1506)
		(width 0.10795)
		(layer "B.Cu")
		(net "H_CPU0_MEMABC_MEMHOT_LVT3_K_N")
	)
	(segment
		(start 427.795944 -11.947906)
		(end 427.795944 -11.179556)
		(width 0.10795)
		(layer "B.Cu")
		(net "H_CPU0_MEMABC_MEMHOT_LVT3_K_N")
	)
	(segment
		(start 429.0822 -12.2047)
		(end 429.3235 -12.446)
		(width 0.10795)
		(layer "B.Cu")
		(net "H_CPU0_MEMABC_MEMHOT_LVT3_K_N")
	)
	(segment
		(start 434.6702 -17.5006)
		(end 435.229 -17.5006)
		(width 0.10795)
		(layer "F.Cu")
		(net "H_CPU1_MEMKLM_MEMHOT_LVT3_K_N")
	)
	(segment
		(start 435.229 -17.5006)
		(end 435.6354 -17.907)
		(width 0.10795)
		(layer "F.Cu")
		(net "H_CPU1_MEMKLM_MEMHOT_LVT3_K_N")
	)
	(via
		(at 435.6354 -17.907)
		(size 0.508)
		(drill 0.254)
		(layers "F.Cu" "B.Cu")
		(net "H_CPU1_MEMKLM_MEMHOT_LVT3_K_N")
	)
	(segment
		(start 434.6575 -17.399)
		(end 434.6575 -18.288)
		(width 0.10795)
		(layer "B.Cu")
		(net "H_CPU1_MEMKLM_MEMHOT_LVT3_K_N")
	)
	(segment
		(start 434.6575 -18.288)
		(end 435.2544 -18.288)
		(width 0.10795)
		(layer "B.Cu")
		(net "H_CPU1_MEMKLM_MEMHOT_LVT3_K_N")
	)
	(segment
		(start 435.2544 -18.288)
		(end 435.6354 -17.907)
		(width 0.10795)
		(layer "B.Cu")
		(net "H_CPU1_MEMKLM_MEMHOT_LVT3_K_N")
	)
	(via
		(at 429.88738 -17.71396)
		(size 0.6604)
		(drill 0.3302)
		(layers "F.Cu" "B.Cu")
		(net "H_CPU1_MEMGHJ_MEMHOT_LVT3_K_N")
	)
	(segment
		(start 429.837088 -15.280894)
		(end 429.046894 -15.280894)
		(width 0.10795)
		(layer "B.Cu")
		(net "H_CPU1_MEMGHJ_MEMHOT_LVT3_K_N")
	)
	(segment
		(start 429.88738 -17.20342)
		(end 429.046894 -16.362934)
		(width 0.10795)
		(layer "B.Cu")
		(net "H_CPU1_MEMGHJ_MEMHOT_LVT3_K_N")
	)
	(segment
		(start 429.88738 -17.71396)
		(end 429.88738 -17.20342)
		(width 0.10795)
		(layer "B.Cu")
		(net "H_CPU1_MEMGHJ_MEMHOT_LVT3_K_N")
	)
	(segment
		(start 429.046894 -16.362934)
		(end 429.046894 -16.042894)
		(width 0.10795)
		(layer "B.Cu")
		(net "H_CPU1_MEMGHJ_MEMHOT_LVT3_K_N")
	)
	(segment
		(start 429.046894 -15.280894)
		(end 429.046894 -16.042894)
		(width 0.10795)
		(layer "B.Cu")
		(net "H_CPU1_MEMGHJ_MEMHOT_LVT3_K_N")
	)
	(segment
		(start 428.279052 -13.013944)
		(end 428.27575 -13.010642)
		(width 0.10795)
		(layer "B.Cu")
		(net "H_CPU0_MEMDEF_MEMHOT_LVT3_K_N")
	)
	(segment
		(start 428.279052 -13.794994)
		(end 428.279052 -13.013944)
		(width 0.10795)
		(layer "B.Cu")
		(net "H_CPU0_MEMDEF_MEMHOT_LVT3_K_N")
	)
	(segment
		(start 428.279052 -13.794994)
		(end 428.595282 -13.794994)
		(width 0.10795)
		(layer "B.Cu")
		(net "H_CPU0_MEMDEF_MEMHOT_LVT3_K_N")
	)
	(segment
		(start 428.595282 -13.794994)
		(end 428.674276 -13.716)
		(width 0.10795)
		(layer "B.Cu")
		(net "H_CPU0_MEMDEF_MEMHOT_LVT3_K_N")
	)
	(segment
		(start 428.674276 -13.716)
		(end 429.1965 -13.716)
		(width 0.10795)
		(layer "B.Cu")
		(net "H_CPU0_MEMDEF_MEMHOT_LVT3_K_N")
	)
	(segment
		(start 412.690056 -28.934664)
		(end 412.690056 -28.914344)
		(width 0.10795)
		(layer "F.Cu")
		(net "H_CPU1_MEMKLM_MEMHOT_LVT3_BMC_N")
	)
	(segment
		(start 412.690056 -28.914344)
		(end 413.0802 -28.5242)
		(width 0.10795)
		(layer "F.Cu")
		(net "H_CPU1_MEMKLM_MEMHOT_LVT3_BMC_N")
	)
	(via
		(at 413.712152 -24.8412)
		(size 0.508)
		(drill 0.254)
		(layers "F.Cu" "B.Cu")
		(net "H_CPU1_MEMKLM_MEMHOT_LVT3_BMC_N")
	)
	(via
		(at 414.0962 -25.8826)
		(size 0.6604)
		(drill 0.3302)
		(layers "F.Cu" "B.Cu")
		(net "H_CPU1_MEMKLM_MEMHOT_LVT3_BMC_N")
	)
	(via
		(at 413.0802 -28.5242)
		(size 0.4572)
		(drill 0.2032)
		(layers "F.Cu" "B.Cu")
		(net "H_CPU1_MEMKLM_MEMHOT_LVT3_BMC_N")
	)
	(segment
		(start 413.215582 -20.756626)
		(end 413.215582 -19.48815)
		(width 0.10795)
		(layer "B.Cu")
		(net "H_CPU1_MEMKLM_MEMHOT_LVT3_BMC_N")
	)
	(segment
		(start 413.78505 -24.768302)
		(end 413.78505 -22.65045)
		(width 0.10795)
		(layer "B.Cu")
		(net "H_CPU1_MEMKLM_MEMHOT_LVT3_BMC_N")
	)
	(segment
		(start 412.959804 -18.98523)
		(end 412.6865 -18.711926)
		(width 0.10795)
		(layer "B.Cu")
		(net "H_CPU1_MEMKLM_MEMHOT_LVT3_BMC_N")
	)
	(segment
		(start 414.0962 -25.8826)
		(end 413.712152 -25.498552)
		(width 0.10795)
		(layer "B.Cu")
		(net "H_CPU1_MEMKLM_MEMHOT_LVT3_BMC_N")
	)
	(segment
		(start 412.959804 -19.232372)
		(end 412.959804 -18.98523)
		(width 0.10795)
		(layer "B.Cu")
		(net "H_CPU1_MEMKLM_MEMHOT_LVT3_BMC_N")
	)
	(segment
		(start 413.215582 -19.48815)
		(end 412.959804 -19.232372)
		(width 0.10795)
		(layer "B.Cu")
		(net "H_CPU1_MEMKLM_MEMHOT_LVT3_BMC_N")
	)
	(segment
		(start 413.5374 -21.078444)
		(end 413.215582 -20.756626)
		(width 0.10795)
		(layer "B.Cu")
		(net "H_CPU1_MEMKLM_MEMHOT_LVT3_BMC_N")
	)
	(segment
		(start 412.6865 -18.711926)
		(end 412.6865 -18.288)
		(width 0.10795)
		(layer "B.Cu")
		(net "H_CPU1_MEMKLM_MEMHOT_LVT3_BMC_N")
	)
	(segment
		(start 413.78505 -22.65045)
		(end 413.5374 -22.4028)
		(width 0.10795)
		(layer "B.Cu")
		(net "H_CPU1_MEMKLM_MEMHOT_LVT3_BMC_N")
	)
	(segment
		(start 413.712152 -25.498552)
		(end 413.712152 -24.8412)
		(width 0.10795)
		(layer "B.Cu")
		(net "H_CPU1_MEMKLM_MEMHOT_LVT3_BMC_N")
	)
	(segment
		(start 413.712152 -24.8412)
		(end 413.78505 -24.768302)
		(width 0.10795)
		(layer "B.Cu")
		(net "H_CPU1_MEMKLM_MEMHOT_LVT3_BMC_N")
	)
	(segment
		(start 413.5374 -22.4028)
		(end 413.5374 -21.078444)
		(width 0.10795)
		(layer "B.Cu")
		(net "H_CPU1_MEMKLM_MEMHOT_LVT3_BMC_N")
	)
	(segment
		(start 412.6484 -25.904952)
		(end 413.712152 -24.8412)
		(width 0.089408)
		(layer "In9.Cu")
		(net "H_CPU1_MEMKLM_MEMHOT_LVT3_BMC_N")
	)
	(segment
		(start 413.0802 -28.5242)
		(end 412.6484 -28.0924)
		(width 0.089408)
		(layer "In9.Cu")
		(net "H_CPU1_MEMKLM_MEMHOT_LVT3_BMC_N")
	)
	(segment
		(start 412.6484 -28.0924)
		(end 412.6484 -25.904952)
		(width 0.089408)
		(layer "In9.Cu")
		(net "H_CPU1_MEMKLM_MEMHOT_LVT3_BMC_N")
	)
	(segment
		(start 412.690056 -28.134564)
		(end 413.090106 -27.734514)
		(width 0.10795)
		(layer "F.Cu")
		(net "H_CPU1_MEMGHJ_MEMHOT_LVT3_BMC_N")
	)
	(via
		(at 426.963332 -17.003268)
		(size 0.6604)
		(drill 0.3302)
		(layers "F.Cu" "B.Cu")
		(net "H_CPU1_MEMGHJ_MEMHOT_LVT3_BMC_N")
	)
	(via
		(at 429.387 -18.7833)
		(size 0.508)
		(drill 0.254)
		(layers "F.Cu" "B.Cu")
		(net "H_CPU1_MEMGHJ_MEMHOT_LVT3_BMC_N")
	)
	(via
		(at 413.090106 -27.734514)
		(size 0.4572)
		(drill 0.2032)
		(layers "F.Cu" "B.Cu")
		(net "H_CPU1_MEMGHJ_MEMHOT_LVT3_BMC_N")
	)
	(segment
		(start 427.2788 -16.6878)
		(end 426.963332 -17.003268)
		(width 0.10795)
		(layer "B.Cu")
		(net "H_CPU1_MEMGHJ_MEMHOT_LVT3_BMC_N")
	)
	(segment
		(start 425.8056 -17.653)
		(end 426.3136 -17.653)
		(width 0.10795)
		(layer "B.Cu")
		(net "H_CPU1_MEMGHJ_MEMHOT_LVT3_BMC_N")
	)
	(segment
		(start 426.3136 -17.653)
		(end 426.963332 -17.003268)
		(width 0.10795)
		(layer "B.Cu")
		(net "H_CPU1_MEMGHJ_MEMHOT_LVT3_BMC_N")
	)
	(segment
		(start 429.387 -17.036034)
		(end 429.038766 -16.6878)
		(width 0.10795)
		(layer "B.Cu")
		(net "H_CPU1_MEMGHJ_MEMHOT_LVT3_BMC_N")
	)
	(segment
		(start 429.038766 -16.6878)
		(end 427.2788 -16.6878)
		(width 0.10795)
		(layer "B.Cu")
		(net "H_CPU1_MEMGHJ_MEMHOT_LVT3_BMC_N")
	)
	(segment
		(start 429.387 -18.7833)
		(end 429.387 -17.036034)
		(width 0.10795)
		(layer "B.Cu")
		(net "H_CPU1_MEMGHJ_MEMHOT_LVT3_BMC_N")
	)
	(segment
		(start 416.595306 -22.29739)
		(end 418.889942 -22.29739)
		(width 0.089408)
		(layer "In11.Cu")
		(net "H_CPU1_MEMGHJ_MEMHOT_LVT3_BMC_N")
	)
	(segment
		(start 413.090106 -24.577294)
		(end 414.1978 -23.4696)
		(width 0.089408)
		(layer "In11.Cu")
		(net "H_CPU1_MEMGHJ_MEMHOT_LVT3_BMC_N")
	)
	(segment
		(start 428.7139 -18.7833)
		(end 429.387 -18.7833)
		(width 0.089408)
		(layer "In11.Cu")
		(net "H_CPU1_MEMGHJ_MEMHOT_LVT3_BMC_N")
	)
	(segment
		(start 421.131746 -20.055586)
		(end 427.441614 -20.055586)
		(width 0.089408)
		(layer "In11.Cu")
		(net "H_CPU1_MEMGHJ_MEMHOT_LVT3_BMC_N")
	)
	(segment
		(start 415.423096 -23.4696)
		(end 416.595306 -22.29739)
		(width 0.089408)
		(layer "In11.Cu")
		(net "H_CPU1_MEMGHJ_MEMHOT_LVT3_BMC_N")
	)
	(segment
		(start 414.1978 -23.4696)
		(end 415.423096 -23.4696)
		(width 0.089408)
		(layer "In11.Cu")
		(net "H_CPU1_MEMGHJ_MEMHOT_LVT3_BMC_N")
	)
	(segment
		(start 418.889942 -22.29739)
		(end 421.131746 -20.055586)
		(width 0.089408)
		(layer "In11.Cu")
		(net "H_CPU1_MEMGHJ_MEMHOT_LVT3_BMC_N")
	)
	(segment
		(start 427.441614 -20.055586)
		(end 428.7139 -18.7833)
		(width 0.089408)
		(layer "In11.Cu")
		(net "H_CPU1_MEMGHJ_MEMHOT_LVT3_BMC_N")
	)
	(segment
		(start 413.090106 -27.734514)
		(end 413.090106 -24.577294)
		(width 0.089408)
		(layer "In11.Cu")
		(net "H_CPU1_MEMGHJ_MEMHOT_LVT3_BMC_N")
	)
	(segment
		(start 410.63164 -21.028914)
		(end 411.352492 -20.308062)
		(width 0.089408)
		(layer "F.Cu")
		(net "H_CPU0_MEMDEF_MEMHOT_LVT3_BMC_N")
	)
	(segment
		(start 411.236668 -25.053036)
		(end 411.236668 -23.820882)
		(width 0.089408)
		(layer "F.Cu")
		(net "H_CPU0_MEMDEF_MEMHOT_LVT3_BMC_N")
	)
	(segment
		(start 413.446722 -20.347432)
		(end 413.446722 -19.750278)
		(width 0.089408)
		(layer "F.Cu")
		(net "H_CPU0_MEMDEF_MEMHOT_LVT3_BMC_N")
	)
	(segment
		(start 411.452314 -20.308062)
		(end 411.541214 -20.219162)
		(width 0.089408)
		(layer "F.Cu")
		(net "H_CPU0_MEMDEF_MEMHOT_LVT3_BMC_N")
	)
	(segment
		(start 411.541214 -20.219162)
		(end 411.958028 -20.219162)
		(width 0.089408)
		(layer "F.Cu")
		(net "H_CPU0_MEMDEF_MEMHOT_LVT3_BMC_N")
	)
	(segment
		(start 413.446722 -19.750278)
		(end 414.528 -18.669)
		(width 0.089408)
		(layer "F.Cu")
		(net "H_CPU0_MEMDEF_MEMHOT_LVT3_BMC_N")
	)
	(segment
		(start 411.89021 -26.534618)
		(end 411.89021 -25.706578)
		(width 0.089408)
		(layer "F.Cu")
		(net "H_CPU0_MEMDEF_MEMHOT_LVT3_BMC_N")
	)
	(segment
		(start 411.89021 -25.706578)
		(end 411.236668 -25.053036)
		(width 0.089408)
		(layer "F.Cu")
		(net "H_CPU0_MEMDEF_MEMHOT_LVT3_BMC_N")
	)
	(segment
		(start 412.598362 -20.859496)
		(end 412.934658 -20.859496)
		(width 0.089408)
		(layer "F.Cu")
		(net "H_CPU0_MEMDEF_MEMHOT_LVT3_BMC_N")
	)
	(segment
		(start 411.236668 -23.820882)
		(end 411.01899 -23.603204)
		(width 0.089408)
		(layer "F.Cu")
		(net "H_CPU0_MEMDEF_MEMHOT_LVT3_BMC_N")
	)
	(segment
		(start 412.934658 -20.859496)
		(end 413.446722 -20.347432)
		(width 0.089408)
		(layer "F.Cu")
		(net "H_CPU0_MEMDEF_MEMHOT_LVT3_BMC_N")
	)
	(segment
		(start 410.8577 -23.603204)
		(end 410.574744 -23.320248)
		(width 0.089408)
		(layer "F.Cu")
		(net "H_CPU0_MEMDEF_MEMHOT_LVT3_BMC_N")
	)
	(segment
		(start 411.01899 -23.603204)
		(end 410.8577 -23.603204)
		(width 0.089408)
		(layer "F.Cu")
		(net "H_CPU0_MEMDEF_MEMHOT_LVT3_BMC_N")
	)
	(segment
		(start 410.63164 -22.61616)
		(end 410.63164 -21.028914)
		(width 0.089408)
		(layer "F.Cu")
		(net "H_CPU0_MEMDEF_MEMHOT_LVT3_BMC_N")
	)
	(segment
		(start 411.352492 -20.308062)
		(end 411.452314 -20.308062)
		(width 0.089408)
		(layer "F.Cu")
		(net "H_CPU0_MEMDEF_MEMHOT_LVT3_BMC_N")
	)
	(segment
		(start 411.958028 -20.219162)
		(end 412.598362 -20.859496)
		(width 0.089408)
		(layer "F.Cu")
		(net "H_CPU0_MEMDEF_MEMHOT_LVT3_BMC_N")
	)
	(segment
		(start 410.574744 -22.673056)
		(end 410.63164 -22.61616)
		(width 0.089408)
		(layer "F.Cu")
		(net "H_CPU0_MEMDEF_MEMHOT_LVT3_BMC_N")
	)
	(segment
		(start 410.574744 -23.320248)
		(end 410.574744 -22.673056)
		(width 0.089408)
		(layer "F.Cu")
		(net "H_CPU0_MEMDEF_MEMHOT_LVT3_BMC_N")
	)
	(via
		(at 414.528 -18.669)
		(size 0.508)
		(drill 0.254)
		(layers "F.Cu" "B.Cu")
		(net "H_CPU0_MEMDEF_MEMHOT_LVT3_BMC_N")
	)
	(via
		(at 416.19932 -19.431)
		(size 0.6604)
		(drill 0.3302)
		(layers "F.Cu" "B.Cu")
		(net "H_CPU0_MEMDEF_MEMHOT_LVT3_BMC_N")
	)
	(segment
		(start 425.110402 -13.382498)
		(end 424.6118 -13.8811)
		(width 0.10795)
		(layer "B.Cu")
		(net "H_CPU0_MEMDEF_MEMHOT_LVT3_BMC_N")
	)
	(segment
		(start 417.7284 -12.96289)
		(end 417.83635 -12.85494)
		(width 0.10795)
		(layer "B.Cu")
		(net "H_CPU0_MEMDEF_MEMHOT_LVT3_BMC_N")
	)
	(segment
		(start 417.471098 -18.875502)
		(end 417.471098 -13.730986)
		(width 0.10795)
		(layer "B.Cu")
		(net "H_CPU0_MEMDEF_MEMHOT_LVT3_BMC_N")
	)
	(segment
		(start 421.64 -12.117832)
		(end 422.327832 -11.43)
		(width 0.10795)
		(layer "B.Cu")
		(net "H_CPU0_MEMDEF_MEMHOT_LVT3_BMC_N")
	)
	(segment
		(start 417.83635 -12.85494)
		(end 419.267132 -12.85494)
		(width 0.10795)
		(layer "B.Cu")
		(net "H_CPU0_MEMDEF_MEMHOT_LVT3_BMC_N")
	)
	(segment
		(start 425.110402 -12.513056)
		(end 425.110402 -13.382498)
		(width 0.10795)
		(layer "B.Cu")
		(net "H_CPU0_MEMDEF_MEMHOT_LVT3_BMC_N")
	)
	(segment
		(start 414.528 -18.669)
		(end 415.29 -19.431)
		(width 0.10795)
		(layer "B.Cu")
		(net "H_CPU0_MEMDEF_MEMHOT_LVT3_BMC_N")
	)
	(segment
		(start 424.6118 -13.8811)
		(end 424.6118 -14.1732)
		(width 0.10795)
		(layer "B.Cu")
		(net "H_CPU0_MEMDEF_MEMHOT_LVT3_BMC_N")
	)
	(segment
		(start 420.199312 -12.117832)
		(end 421.64 -12.117832)
		(width 0.10795)
		(layer "B.Cu")
		(net "H_CPU0_MEMDEF_MEMHOT_LVT3_BMC_N")
	)
	(segment
		(start 415.29 -19.431)
		(end 416.19932 -19.431)
		(width 0.10795)
		(layer "B.Cu")
		(net "H_CPU0_MEMDEF_MEMHOT_LVT3_BMC_N")
	)
	(segment
		(start 419.267386 -12.855194)
		(end 419.46195 -12.855194)
		(width 0.10795)
		(layer "B.Cu")
		(net "H_CPU0_MEMDEF_MEMHOT_LVT3_BMC_N")
	)
	(segment
		(start 417.7284 -13.473684)
		(end 417.7284 -12.96289)
		(width 0.10795)
		(layer "B.Cu")
		(net "H_CPU0_MEMDEF_MEMHOT_LVT3_BMC_N")
	)
	(segment
		(start 417.471098 -13.730986)
		(end 417.7284 -13.473684)
		(width 0.10795)
		(layer "B.Cu")
		(net "H_CPU0_MEMDEF_MEMHOT_LVT3_BMC_N")
	)
	(segment
		(start 419.267132 -12.85494)
		(end 419.267386 -12.855194)
		(width 0.10795)
		(layer "B.Cu")
		(net "H_CPU0_MEMDEF_MEMHOT_LVT3_BMC_N")
	)
	(segment
		(start 422.327832 -11.43)
		(end 424.027346 -11.43)
		(width 0.10795)
		(layer "B.Cu")
		(net "H_CPU0_MEMDEF_MEMHOT_LVT3_BMC_N")
	)
	(segment
		(start 419.46195 -12.855194)
		(end 420.199312 -12.117832)
		(width 0.10795)
		(layer "B.Cu")
		(net "H_CPU0_MEMDEF_MEMHOT_LVT3_BMC_N")
	)
	(segment
		(start 416.9156 -19.431)
		(end 417.471098 -18.875502)
		(width 0.10795)
		(layer "B.Cu")
		(net "H_CPU0_MEMDEF_MEMHOT_LVT3_BMC_N")
	)
	(segment
		(start 416.19932 -19.431)
		(end 416.9156 -19.431)
		(width 0.10795)
		(layer "B.Cu")
		(net "H_CPU0_MEMDEF_MEMHOT_LVT3_BMC_N")
	)
	(segment
		(start 424.027346 -11.43)
		(end 425.110402 -12.513056)
		(width 0.10795)
		(layer "B.Cu")
		(net "H_CPU0_MEMDEF_MEMHOT_LVT3_BMC_N")
	)
	(segment
		(start 412.690056 -29.734764)
		(end 413.090106 -30.134814)
		(width 0.10795)
		(layer "F.Cu")
		(net "H_CPU0_MEMABC_MEMHOT_LVT3_BMC_N")
	)
	(segment
		(start 413.090106 -30.134814)
		(end 413.090106 -30.137354)
		(width 0.10795)
		(layer "F.Cu")
		(net "H_CPU0_MEMABC_MEMHOT_LVT3_BMC_N")
	)
	(via
		(at 413.090106 -30.137354)
		(size 0.4572)
		(drill 0.2032)
		(layers "F.Cu" "B.Cu")
		(net "H_CPU0_MEMABC_MEMHOT_LVT3_BMC_N")
	)
	(via
		(at 416.56 -15.24)
		(size 0.6604)
		(drill 0.3302)
		(layers "F.Cu" "B.Cu")
		(net "H_CPU0_MEMABC_MEMHOT_LVT3_BMC_N")
	)
	(via
		(at 414.53308 -24.859234)
		(size 0.508)
		(drill 0.254)
		(layers "F.Cu" "B.Cu")
		(net "H_CPU0_MEMABC_MEMHOT_LVT3_BMC_N")
	)
	(segment
		(start 416.694366 -18.229834)
		(end 414.323276 -18.229834)
		(width 0.10795)
		(layer "B.Cu")
		(net "H_CPU0_MEMABC_MEMHOT_LVT3_BMC_N")
	)
	(segment
		(start 414.728406 -22.5806)
		(end 414.02 -23.289006)
		(width 0.10795)
		(layer "B.Cu")
		(net "H_CPU0_MEMABC_MEMHOT_LVT3_BMC_N")
	)
	(segment
		(start 414.02 -24.346154)
		(end 414.53308 -24.859234)
		(width 0.10795)
		(layer "B.Cu")
		(net "H_CPU0_MEMABC_MEMHOT_LVT3_BMC_N")
	)
	(segment
		(start 424.6245 -11.176)
		(end 422.223946 -11.176)
		(width 0.10795)
		(layer "B.Cu")
		(net "H_CPU0_MEMABC_MEMHOT_LVT3_BMC_N")
	)
	(segment
		(start 417.236148 -17.688052)
		(end 416.694366 -18.229834)
		(width 0.10795)
		(layer "B.Cu")
		(net "H_CPU0_MEMABC_MEMHOT_LVT3_BMC_N")
	)
	(segment
		(start 417.454588 -12.61999)
		(end 416.56 -13.514578)
		(width 0.10795)
		(layer "B.Cu")
		(net "H_CPU0_MEMABC_MEMHOT_LVT3_BMC_N")
	)
	(segment
		(start 419.364668 -12.61999)
		(end 417.454588 -12.61999)
		(width 0.10795)
		(layer "B.Cu")
		(net "H_CPU0_MEMABC_MEMHOT_LVT3_BMC_N")
	)
	(segment
		(start 414.086802 -18.989802)
		(end 415.0868 -19.9898)
		(width 0.10795)
		(layer "B.Cu")
		(net "H_CPU0_MEMABC_MEMHOT_LVT3_BMC_N")
	)
	(segment
		(start 417.236148 -15.916148)
		(end 417.236148 -17.688052)
		(width 0.10795)
		(layer "B.Cu")
		(net "H_CPU0_MEMABC_MEMHOT_LVT3_BMC_N")
	)
	(segment
		(start 421.517064 -11.882882)
		(end 420.101776 -11.882882)
		(width 0.10795)
		(layer "B.Cu")
		(net "H_CPU0_MEMABC_MEMHOT_LVT3_BMC_N")
	)
	(segment
		(start 425.1325 -11.684)
		(end 424.6245 -11.176)
		(width 0.10795)
		(layer "B.Cu")
		(net "H_CPU0_MEMABC_MEMHOT_LVT3_BMC_N")
	)
	(segment
		(start 414.323276 -18.229834)
		(end 414.086802 -18.466308)
		(width 0.10795)
		(layer "B.Cu")
		(net "H_CPU0_MEMABC_MEMHOT_LVT3_BMC_N")
	)
	(segment
		(start 420.101776 -11.882882)
		(end 419.364668 -12.61999)
		(width 0.10795)
		(layer "B.Cu")
		(net "H_CPU0_MEMABC_MEMHOT_LVT3_BMC_N")
	)
	(segment
		(start 414.086802 -18.466308)
		(end 414.086802 -18.989802)
		(width 0.10795)
		(layer "B.Cu")
		(net "H_CPU0_MEMABC_MEMHOT_LVT3_BMC_N")
	)
	(segment
		(start 422.223946 -11.176)
		(end 421.517064 -11.882882)
		(width 0.10795)
		(layer "B.Cu")
		(net "H_CPU0_MEMABC_MEMHOT_LVT3_BMC_N")
	)
	(segment
		(start 415.0868 -21.25218)
		(end 414.728406 -21.610574)
		(width 0.10795)
		(layer "B.Cu")
		(net "H_CPU0_MEMABC_MEMHOT_LVT3_BMC_N")
	)
	(segment
		(start 415.0868 -19.9898)
		(end 415.0868 -21.25218)
		(width 0.10795)
		(layer "B.Cu")
		(net "H_CPU0_MEMABC_MEMHOT_LVT3_BMC_N")
	)
	(segment
		(start 414.728406 -21.610574)
		(end 414.728406 -22.5806)
		(width 0.10795)
		(layer "B.Cu")
		(net "H_CPU0_MEMABC_MEMHOT_LVT3_BMC_N")
	)
	(segment
		(start 416.56 -13.514578)
		(end 416.56 -15.24)
		(width 0.10795)
		(layer "B.Cu")
		(net "H_CPU0_MEMABC_MEMHOT_LVT3_BMC_N")
	)
	(segment
		(start 414.02 -23.289006)
		(end 414.02 -24.346154)
		(width 0.10795)
		(layer "B.Cu")
		(net "H_CPU0_MEMABC_MEMHOT_LVT3_BMC_N")
	)
	(segment
		(start 416.56 -15.24)
		(end 417.236148 -15.916148)
		(width 0.10795)
		(layer "B.Cu")
		(net "H_CPU0_MEMABC_MEMHOT_LVT3_BMC_N")
	)
	(segment
		(start 413.092646 -30.134814)
		(end 413.092646 -29.908754)
		(width 0.089408)
		(layer "In9.Cu")
		(net "H_CPU0_MEMABC_MEMHOT_LVT3_BMC_N")
	)
	(segment
		(start 414.53308 -24.88692)
		(end 414.53308 -24.859234)
		(width 0.089408)
		(layer "In9.Cu")
		(net "H_CPU0_MEMABC_MEMHOT_LVT3_BMC_N")
	)
	(segment
		(start 413.090106 -30.137354)
		(end 413.092646 -30.134814)
		(width 0.089408)
		(layer "In9.Cu")
		(net "H_CPU0_MEMABC_MEMHOT_LVT3_BMC_N")
	)
	(segment
		(start 413.4866 -29.5148)
		(end 413.4866 -25.9334)
		(width 0.089408)
		(layer "In9.Cu")
		(net "H_CPU0_MEMABC_MEMHOT_LVT3_BMC_N")
	)
	(segment
		(start 413.092646 -29.908754)
		(end 413.4866 -29.5148)
		(width 0.089408)
		(layer "In9.Cu")
		(net "H_CPU0_MEMABC_MEMHOT_LVT3_BMC_N")
	)
	(segment
		(start 413.4866 -25.9334)
		(end 414.53308 -24.88692)
		(width 0.089408)
		(layer "In9.Cu")
		(net "H_CPU0_MEMABC_MEMHOT_LVT3_BMC_N")
	)
	(segment
		(start 406.385014 -47.7139)
		(end 406.146 -47.7139)
		(width 0.10795)
		(layer "F.Cu")
		(net "FM_CPU_ERR1_LVT3_BMC_N")
	)
	(segment
		(start 407.20264 -46.28896)
		(end 406.68194 -46.80966)
		(width 0.10795)
		(layer "F.Cu")
		(net "FM_CPU_ERR1_LVT3_BMC_N")
	)
	(segment
		(start 408.690064 -42.80916)
		(end 408.26182 -43.237404)
		(width 0.10795)
		(layer "F.Cu")
		(net "FM_CPU_ERR1_LVT3_BMC_N")
	)
	(segment
		(start 407.797 -46.102524)
		(end 407.610564 -46.28896)
		(width 0.10795)
		(layer "F.Cu")
		(net "FM_CPU_ERR1_LVT3_BMC_N")
	)
	(segment
		(start 408.26182 -43.237404)
		(end 408.26182 -43.490642)
		(width 0.10795)
		(layer "F.Cu")
		(net "FM_CPU_ERR1_LVT3_BMC_N")
	)
	(segment
		(start 408.0637 -43.688762)
		(end 408.0637 -44.127928)
		(width 0.10795)
		(layer "F.Cu")
		(net "FM_CPU_ERR1_LVT3_BMC_N")
	)
	(segment
		(start 407.610564 -46.28896)
		(end 407.20264 -46.28896)
		(width 0.10795)
		(layer "F.Cu")
		(net "FM_CPU_ERR1_LVT3_BMC_N")
	)
	(segment
		(start 408.0637 -44.127928)
		(end 407.797 -44.394628)
		(width 0.10795)
		(layer "F.Cu")
		(net "FM_CPU_ERR1_LVT3_BMC_N")
	)
	(segment
		(start 406.68194 -47.416974)
		(end 406.385014 -47.7139)
		(width 0.10795)
		(layer "F.Cu")
		(net "FM_CPU_ERR1_LVT3_BMC_N")
	)
	(segment
		(start 408.690064 -42.534586)
		(end 408.690064 -42.80916)
		(width 0.10795)
		(layer "F.Cu")
		(net "FM_CPU_ERR1_LVT3_BMC_N")
	)
	(segment
		(start 407.797 -44.394628)
		(end 407.797 -46.102524)
		(width 0.10795)
		(layer "F.Cu")
		(net "FM_CPU_ERR1_LVT3_BMC_N")
	)
	(segment
		(start 406.68194 -46.80966)
		(end 406.68194 -47.416974)
		(width 0.10795)
		(layer "F.Cu")
		(net "FM_CPU_ERR1_LVT3_BMC_N")
	)
	(segment
		(start 408.26182 -43.490642)
		(end 408.0637 -43.688762)
		(width 0.10795)
		(layer "F.Cu")
		(net "FM_CPU_ERR1_LVT3_BMC_N")
	)
	(via
		(at 407.610564 -46.28896)
		(size 0.762)
		(drill 0.381)
		(layers "F.Cu" "B.Cu")
		(net "FM_CPU_ERR1_LVT3_BMC_N")
	)
	(segment
		(start 411.49016 -40.53459)
		(end 411.89021 -40.13454)
		(width 0.10795)
		(layer "F.Cu")
		(net "FM_CPU_ERR0_LVT3_BMC_N")
	)
	(via
		(at 410.737812 -42.9514)
		(size 0.6604)
		(drill 0.3302)
		(layers "F.Cu" "B.Cu")
		(net "FM_CPU_ERR0_LVT3_BMC_N")
	)
	(via
		(at 411.49016 -40.53459)
		(size 0.4572)
		(drill 0.2032)
		(layers "F.Cu" "B.Cu")
		(net "FM_CPU_ERR0_LVT3_BMC_N")
	)
	(segment
		(start 411.648402 -44.338748)
		(end 411.409896 -44.100242)
		(width 0.10795)
		(layer "B.Cu")
		(net "FM_CPU_ERR0_LVT3_BMC_N")
	)
	(segment
		(start 411.898846 -41.498012)
		(end 411.898846 -41.183814)
		(width 0.10795)
		(layer "B.Cu")
		(net "FM_CPU_ERR0_LVT3_BMC_N")
	)
	(segment
		(start 410.737812 -42.667174)
		(end 411.080712 -42.324274)
		(width 0.10795)
		(layer "B.Cu")
		(net "FM_CPU_ERR0_LVT3_BMC_N")
	)
	(segment
		(start 410.8704 -47.25162)
		(end 410.8704 -46.73092)
		(width 0.10795)
		(layer "B.Cu")
		(net "FM_CPU_ERR0_LVT3_BMC_N")
	)
	(segment
		(start 410.737812 -42.993056)
		(end 410.737812 -42.9514)
		(width 0.10795)
		(layer "B.Cu")
		(net "FM_CPU_ERR0_LVT3_BMC_N")
	)
	(segment
		(start 411.080712 -41.984168)
		(end 411.323028 -41.741852)
		(width 0.10795)
		(layer "B.Cu")
		(net "FM_CPU_ERR0_LVT3_BMC_N")
	)
	(segment
		(start 411.648402 -46.307756)
		(end 411.648402 -44.338748)
		(width 0.10795)
		(layer "B.Cu")
		(net "FM_CPU_ERR0_LVT3_BMC_N")
	)
	(segment
		(start 411.409896 -44.100242)
		(end 411.409896 -43.66514)
		(width 0.10795)
		(layer "B.Cu")
		(net "FM_CPU_ERR0_LVT3_BMC_N")
	)
	(segment
		(start 411.323028 -41.741852)
		(end 411.655006 -41.741852)
		(width 0.10795)
		(layer "B.Cu")
		(net "FM_CPU_ERR0_LVT3_BMC_N")
	)
	(segment
		(start 411.04185 -46.55947)
		(end 411.396688 -46.55947)
		(width 0.10795)
		(layer "B.Cu")
		(net "FM_CPU_ERR0_LVT3_BMC_N")
	)
	(segment
		(start 411.49016 -40.775128)
		(end 411.49016 -40.53459)
		(width 0.10795)
		(layer "B.Cu")
		(net "FM_CPU_ERR0_LVT3_BMC_N")
	)
	(segment
		(start 410.8704 -46.73092)
		(end 411.04185 -46.55947)
		(width 0.10795)
		(layer "B.Cu")
		(net "FM_CPU_ERR0_LVT3_BMC_N")
	)
	(segment
		(start 411.440884 -47.822104)
		(end 410.8704 -47.25162)
		(width 0.10795)
		(layer "B.Cu")
		(net "FM_CPU_ERR0_LVT3_BMC_N")
	)
	(segment
		(start 411.409896 -43.66514)
		(end 410.737812 -42.993056)
		(width 0.10795)
		(layer "B.Cu")
		(net "FM_CPU_ERR0_LVT3_BMC_N")
	)
	(segment
		(start 410.737812 -42.9514)
		(end 410.737812 -42.667174)
		(width 0.10795)
		(layer "B.Cu")
		(net "FM_CPU_ERR0_LVT3_BMC_N")
	)
	(segment
		(start 411.655006 -41.741852)
		(end 411.898846 -41.498012)
		(width 0.10795)
		(layer "B.Cu")
		(net "FM_CPU_ERR0_LVT3_BMC_N")
	)
	(segment
		(start 411.080712 -42.324274)
		(end 411.080712 -41.984168)
		(width 0.10795)
		(layer "B.Cu")
		(net "FM_CPU_ERR0_LVT3_BMC_N")
	)
	(segment
		(start 411.898846 -41.183814)
		(end 411.49016 -40.775128)
		(width 0.10795)
		(layer "B.Cu")
		(net "FM_CPU_ERR0_LVT3_BMC_N")
	)
	(segment
		(start 411.396688 -46.55947)
		(end 411.648402 -46.307756)
		(width 0.10795)
		(layer "B.Cu")
		(net "FM_CPU_ERR0_LVT3_BMC_N")
	)
	(segment
		(start 403.479254 -40.862758)
		(end 403.479254 -40.985948)
		(width 0.10795)
		(layer "F.Cu")
		(net "FM_CPU1_PROCHOT_LVT3_BMC_N")
	)
	(segment
		(start 402.982938 -39.741856)
		(end 402.982938 -40.366442)
		(width 0.10795)
		(layer "F.Cu")
		(net "FM_CPU1_PROCHOT_LVT3_BMC_N")
	)
	(segment
		(start 403.479254 -40.985948)
		(end 403.780244 -41.286938)
		(width 0.10795)
		(layer "F.Cu")
		(net "FM_CPU1_PROCHOT_LVT3_BMC_N")
	)
	(segment
		(start 402.982938 -40.366442)
		(end 403.479254 -40.862758)
		(width 0.10795)
		(layer "F.Cu")
		(net "FM_CPU1_PROCHOT_LVT3_BMC_N")
	)
	(segment
		(start 403.463506 -39.261288)
		(end 402.982938 -39.741856)
		(width 0.10795)
		(layer "F.Cu")
		(net "FM_CPU1_PROCHOT_LVT3_BMC_N")
	)
	(segment
		(start 403.780244 -41.286938)
		(end 407.53792 -41.286938)
		(width 0.10795)
		(layer "F.Cu")
		(net "FM_CPU1_PROCHOT_LVT3_BMC_N")
	)
	(segment
		(start 407.53792 -41.286938)
		(end 407.890218 -40.93464)
		(width 0.10795)
		(layer "F.Cu")
		(net "FM_CPU1_PROCHOT_LVT3_BMC_N")
	)
	(via
		(at 403.463506 -39.261288)
		(size 0.762)
		(drill 0.381)
		(layers "F.Cu" "B.Cu")
		(net "FM_CPU1_PROCHOT_LVT3_BMC_N")
	)
	(segment
		(start 403.504146 -42.935652)
		(end 404.398988 -42.935652)
		(width 0.10795)
		(layer "F.Cu")
		(net "FM_CPU0_PROCHOT_LVT3_BMC_N")
	)
	(segment
		(start 404.677372 -42.178732)
		(end 405.121364 -41.73474)
		(width 0.10795)
		(layer "F.Cu")
		(net "FM_CPU0_PROCHOT_LVT3_BMC_N")
	)
	(segment
		(start 405.121364 -41.73474)
		(end 407.090118 -41.73474)
		(width 0.10795)
		(layer "F.Cu")
		(net "FM_CPU0_PROCHOT_LVT3_BMC_N")
	)
	(segment
		(start 404.398988 -42.935652)
		(end 404.4823 -42.85234)
		(width 0.10795)
		(layer "F.Cu")
		(net "FM_CPU0_PROCHOT_LVT3_BMC_N")
	)
	(segment
		(start 404.677372 -42.657268)
		(end 404.677372 -42.178732)
		(width 0.10795)
		(layer "F.Cu")
		(net "FM_CPU0_PROCHOT_LVT3_BMC_N")
	)
	(segment
		(start 404.4823 -42.85234)
		(end 404.677372 -42.657268)
		(width 0.10795)
		(layer "F.Cu")
		(net "FM_CPU0_PROCHOT_LVT3_BMC_N")
	)
	(via
		(at 404.4823 -42.85234)
		(size 0.762)
		(drill 0.381)
		(layers "F.Cu" "B.Cu")
		(net "FM_CPU0_PROCHOT_LVT3_BMC_N")
	)
	(segment
		(start 384.76555 -102.12832)
		(end 385.26085 -101.898196)
		(width 0.10795)
		(layer "F.Cu")
		(net "TP_PCH_GPP_L11")
	)
	(via
		(at 385.26085 -101.898196)
		(size 0.508)
		(drill 0.254)
		(layers "F.Cu" "B.Cu")
		(net "TP_PCH_GPP_L11")
	)
	(segment
		(start 385.75615 -102.12832)
		(end 386.25145 -101.898196)
		(width 0.10795)
		(layer "F.Cu")
		(net "TP_PCH_GPP_L10")
	)
	(via
		(at 386.25145 -101.898196)
		(size 0.508)
		(drill 0.254)
		(layers "F.Cu" "B.Cu")
		(net "TP_PCH_GPP_L10")
	)
	(segment
		(start 454.708768 -31.677102)
		(end 454.708768 -32.10941)
		(width 0.10795)
		(layer "F.Cu")
		(net "RST_BMC_DDR3_BUF_IN_N")
	)
	(segment
		(start 453.992742 -30.961076)
		(end 454.708768 -31.677102)
		(width 0.10795)
		(layer "F.Cu")
		(net "RST_BMC_DDR3_BUF_IN_N")
	)
	(segment
		(start 453.992742 -30.527752)
		(end 453.992742 -30.961076)
		(width 0.10795)
		(layer "F.Cu")
		(net "RST_BMC_DDR3_BUF_IN_N")
	)
	(segment
		(start 454.984358 -32.385)
		(end 457.2 -32.385)
		(width 0.10795)
		(layer "F.Cu")
		(net "RST_BMC_DDR3_BUF_IN_N")
	)
	(segment
		(start 454.708768 -32.10941)
		(end 454.984358 -32.385)
		(width 0.10795)
		(layer "F.Cu")
		(net "RST_BMC_DDR3_BUF_IN_N")
	)
	(via
		(at 453.992742 -30.527752)
		(size 0.508)
		(drill 0.254)
		(layers "F.Cu" "B.Cu")
		(net "RST_BMC_DDR3_BUF_IN_N")
	)
	(via
		(at 454.152 -29.083)
		(size 0.6604)
		(drill 0.3302)
		(layers "F.Cu" "B.Cu")
		(net "RST_BMC_DDR3_BUF_IN_N")
	)
	(segment
		(start 454.311258 -31.237174)
		(end 454.311258 -30.846268)
		(width 0.10795)
		(layer "B.Cu")
		(net "RST_BMC_DDR3_BUF_IN_N")
	)
	(segment
		(start 453.992742 -29.242258)
		(end 454.152 -29.083)
		(width 0.10795)
		(layer "B.Cu")
		(net "RST_BMC_DDR3_BUF_IN_N")
	)
	(segment
		(start 454.311258 -30.846268)
		(end 453.992742 -30.527752)
		(width 0.10795)
		(layer "B.Cu")
		(net "RST_BMC_DDR3_BUF_IN_N")
	)
	(segment
		(start 453.992742 -30.527752)
		(end 453.992742 -29.242258)
		(width 0.10795)
		(layer "B.Cu")
		(net "RST_BMC_DDR3_BUF_IN_N")
	)
	(segment
		(start 380.618746 -39.032434)
		(end 380.618746 -39.236904)
		(width 0.10795)
		(layer "F.Cu")
		(net "H_CPU_ERR1_PCH_N")
	)
	(segment
		(start 381.151638 -38.499542)
		(end 380.618746 -39.032434)
		(width 0.10795)
		(layer "F.Cu")
		(net "H_CPU_ERR1_PCH_N")
	)
	(segment
		(start 381.429006 -37.922454)
		(end 381.151638 -38.199822)
		(width 0.10795)
		(layer "F.Cu")
		(net "H_CPU_ERR1_PCH_N")
	)
	(segment
		(start 378.971302 -39.62908)
		(end 378.971302 -39.52494)
		(width 0.10795)
		(layer "F.Cu")
		(net "H_CPU_ERR1_PCH_N")
	)
	(segment
		(start 381.151638 -38.199822)
		(end 381.151638 -38.499542)
		(width 0.10795)
		(layer "F.Cu")
		(net "H_CPU_ERR1_PCH_N")
	)
	(segment
		(start 381.429006 -37.543994)
		(end 381.429006 -37.922454)
		(width 0.10795)
		(layer "F.Cu")
		(net "H_CPU_ERR1_PCH_N")
	)
	(segment
		(start 379.855984 -39.999666)
		(end 379.341888 -39.999666)
		(width 0.10795)
		(layer "F.Cu")
		(net "H_CPU_ERR1_PCH_N")
	)
	(segment
		(start 381.508 -37.465)
		(end 381.429006 -37.543994)
		(width 0.10795)
		(layer "F.Cu")
		(net "H_CPU_ERR1_PCH_N")
	)
	(segment
		(start 379.341888 -39.999666)
		(end 378.971302 -39.62908)
		(width 0.10795)
		(layer "F.Cu")
		(net "H_CPU_ERR1_PCH_N")
	)
	(segment
		(start 380.618746 -39.236904)
		(end 379.855984 -39.999666)
		(width 0.10795)
		(layer "F.Cu")
		(net "H_CPU_ERR1_PCH_N")
	)
	(via
		(at 370.223288 -34.16554)
		(size 0.6604)
		(drill 0.3302)
		(layers "F.Cu" "B.Cu")
		(net "H_CPU_ERR1_PCH_N")
	)
	(via
		(at 378.971302 -39.52494)
		(size 0.508)
		(drill 0.254)
		(layers "F.Cu" "B.Cu")
		(net "H_CPU_ERR1_PCH_N")
	)
	(via
		(at 381.508 -37.465)
		(size 0.508)
		(drill 0.254)
		(layers "F.Cu" "B.Cu")
		(net "H_CPU_ERR1_PCH_N")
	)
	(segment
		(start 381.508 -37.465)
		(end 381.429006 -37.386006)
		(width 0.10795)
		(layer "B.Cu")
		(net "H_CPU_ERR1_PCH_N")
	)
	(segment
		(start 377.698254 -40.64)
		(end 378.384562 -40.64)
		(width 0.10795)
		(layer "B.Cu")
		(net "H_CPU_ERR1_PCH_N")
	)
	(segment
		(start 375.388632 -34.578798)
		(end 370.636546 -34.578798)
		(width 0.10795)
		(layer "B.Cu")
		(net "H_CPU_ERR1_PCH_N")
	)
	(segment
		(start 378.543058 -40.481504)
		(end 378.543058 -40.427656)
		(width 0.10795)
		(layer "B.Cu")
		(net "H_CPU_ERR1_PCH_N")
	)
	(segment
		(start 359.475278 -40.652192)
		(end 366.337342 -33.790128)
		(width 0.10795)
		(layer "B.Cu")
		(net "H_CPU_ERR1_PCH_N")
	)
	(segment
		(start 359.475278 -43.280584)
		(end 359.475278 -40.652192)
		(width 0.10795)
		(layer "B.Cu")
		(net "H_CPU_ERR1_PCH_N")
	)
	(segment
		(start 378.971302 -39.999412)
		(end 378.971302 -39.52494)
		(width 0.10795)
		(layer "B.Cu")
		(net "H_CPU_ERR1_PCH_N")
	)
	(segment
		(start 376.280934 -35.4711)
		(end 375.388632 -34.578798)
		(width 0.10795)
		(layer "B.Cu")
		(net "H_CPU_ERR1_PCH_N")
	)
	(segment
		(start 360.555794 -43.956986)
		(end 360.15168 -43.956986)
		(width 0.10795)
		(layer "B.Cu")
		(net "H_CPU_ERR1_PCH_N")
	)
	(segment
		(start 369.847876 -33.790128)
		(end 370.223288 -34.16554)
		(width 0.10795)
		(layer "B.Cu")
		(net "H_CPU_ERR1_PCH_N")
	)
	(segment
		(start 366.337342 -33.790128)
		(end 369.847876 -33.790128)
		(width 0.10795)
		(layer "B.Cu")
		(net "H_CPU_ERR1_PCH_N")
	)
	(segment
		(start 376.170952 -43.224958)
		(end 376.593354 -43.224958)
		(width 0.10795)
		(layer "B.Cu")
		(net "H_CPU_ERR1_PCH_N")
	)
	(segment
		(start 378.543058 -40.427656)
		(end 378.971302 -39.999412)
		(width 0.10795)
		(layer "B.Cu")
		(net "H_CPU_ERR1_PCH_N")
	)
	(segment
		(start 370.636546 -34.578798)
		(end 370.223288 -34.16554)
		(width 0.10795)
		(layer "B.Cu")
		(net "H_CPU_ERR1_PCH_N")
	)
	(segment
		(start 379.588776 -35.4711)
		(end 376.280934 -35.4711)
		(width 0.10795)
		(layer "B.Cu")
		(net "H_CPU_ERR1_PCH_N")
	)
	(segment
		(start 381.429006 -37.386006)
		(end 381.429006 -37.31133)
		(width 0.10795)
		(layer "B.Cu")
		(net "H_CPU_ERR1_PCH_N")
	)
	(segment
		(start 378.384562 -40.64)
		(end 378.543058 -40.481504)
		(width 0.10795)
		(layer "B.Cu")
		(net "H_CPU_ERR1_PCH_N")
	)
	(segment
		(start 376.593354 -43.224958)
		(end 376.7582 -43.060112)
		(width 0.10795)
		(layer "B.Cu")
		(net "H_CPU_ERR1_PCH_N")
	)
	(segment
		(start 360.15168 -43.956986)
		(end 359.475278 -43.280584)
		(width 0.10795)
		(layer "B.Cu")
		(net "H_CPU_ERR1_PCH_N")
	)
	(segment
		(start 381.429006 -37.31133)
		(end 379.588776 -35.4711)
		(width 0.10795)
		(layer "B.Cu")
		(net "H_CPU_ERR1_PCH_N")
	)
	(segment
		(start 376.7582 -43.060112)
		(end 376.7582 -41.580054)
		(width 0.10795)
		(layer "B.Cu")
		(net "H_CPU_ERR1_PCH_N")
	)
	(segment
		(start 376.7582 -41.580054)
		(end 377.698254 -40.64)
		(width 0.10795)
		(layer "B.Cu")
		(net "H_CPU_ERR1_PCH_N")
	)
	(via
		(at 364.109 -38.460426)
		(size 0.6604)
		(drill 0.3302)
		(layers "F.Cu" "B.Cu")
		(net "H_CPU_ERR0_PCH_N")
	)
	(segment
		(start 370.59743 -40.617648)
		(end 370.986558 -40.617648)
		(width 0.10795)
		(layer "B.Cu")
		(net "H_CPU_ERR0_PCH_N")
	)
	(segment
		(start 367.609374 -38.5064)
		(end 368.7953 -39.692326)
		(width 0.10795)
		(layer "B.Cu")
		(net "H_CPU_ERR0_PCH_N")
	)
	(segment
		(start 370.480082 -40.5003)
		(end 370.59743 -40.617648)
		(width 0.10795)
		(layer "B.Cu")
		(net "H_CPU_ERR0_PCH_N")
	)
	(segment
		(start 363.185202 -38.460426)
		(end 364.109 -38.460426)
		(width 0.10795)
		(layer "B.Cu")
		(net "H_CPU_ERR0_PCH_N")
	)
	(segment
		(start 360.555794 -41.089834)
		(end 363.185202 -38.460426)
		(width 0.10795)
		(layer "B.Cu")
		(net "H_CPU_ERR0_PCH_N")
	)
	(segment
		(start 367.489232 -38.5064)
		(end 367.609374 -38.5064)
		(width 0.10795)
		(layer "B.Cu")
		(net "H_CPU_ERR0_PCH_N")
	)
	(segment
		(start 366.983772 -38.460426)
		(end 367.026444 -38.503098)
		(width 0.10795)
		(layer "B.Cu")
		(net "H_CPU_ERR0_PCH_N")
	)
	(segment
		(start 367.48593 -38.503098)
		(end 367.489232 -38.5064)
		(width 0.10795)
		(layer "B.Cu")
		(net "H_CPU_ERR0_PCH_N")
	)
	(segment
		(start 364.109 -38.460426)
		(end 366.983772 -38.460426)
		(width 0.10795)
		(layer "B.Cu")
		(net "H_CPU_ERR0_PCH_N")
	)
	(segment
		(start 360.555794 -41.543986)
		(end 360.555794 -41.089834)
		(width 0.10795)
		(layer "B.Cu")
		(net "H_CPU_ERR0_PCH_N")
	)
	(segment
		(start 368.7953 -40.271954)
		(end 369.023646 -40.5003)
		(width 0.10795)
		(layer "B.Cu")
		(net "H_CPU_ERR0_PCH_N")
	)
	(segment
		(start 367.026444 -38.503098)
		(end 367.48593 -38.503098)
		(width 0.10795)
		(layer "B.Cu")
		(net "H_CPU_ERR0_PCH_N")
	)
	(segment
		(start 369.023646 -40.5003)
		(end 370.480082 -40.5003)
		(width 0.10795)
		(layer "B.Cu")
		(net "H_CPU_ERR0_PCH_N")
	)
	(segment
		(start 368.7953 -39.692326)
		(end 368.7953 -40.271954)
		(width 0.10795)
		(layer "B.Cu")
		(net "H_CPU_ERR0_PCH_N")
	)
	(segment
		(start 370.290852 -46.138338)
		(end 371.989858 -46.138338)
		(width 0.10795)
		(layer "B.Cu")
		(net "H_CPU1_PROCHOT_G_R_N")
	)
	(segment
		(start 371.989858 -46.138338)
		(end 372.169436 -46.317916)
		(width 0.10795)
		(layer "B.Cu")
		(net "H_CPU1_PROCHOT_G_R_N")
	)
	(segment
		(start 372.169436 -46.317916)
		(end 372.169436 -46.547532)
		(width 0.10795)
		(layer "B.Cu")
		(net "H_CPU1_PROCHOT_G_R_N")
	)
	(via
		(at 359.6132 -47.9044)
		(size 0.6604)
		(drill 0.3302)
		(layers "F.Cu" "B.Cu")
		(net "H_CPU1_PROCHOT_G_PCH_N")
	)
	(segment
		(start 368.304064 -48.56607)
		(end 369.002818 -49.264824)
		(width 0.10795)
		(layer "B.Cu")
		(net "H_CPU1_PROCHOT_G_PCH_N")
	)
	(segment
		(start 359.6132 -47.9044)
		(end 359.6132 -47.068994)
		(width 0.10795)
		(layer "B.Cu")
		(net "H_CPU1_PROCHOT_G_PCH_N")
	)
	(segment
		(start 359.6132 -47.068994)
		(end 360.185208 -46.496986)
		(width 0.10795)
		(layer "B.Cu")
		(net "H_CPU1_PROCHOT_G_PCH_N")
	)
	(segment
		(start 359.6132 -47.9044)
		(end 360.455464 -48.746664)
		(width 0.10795)
		(layer "B.Cu")
		(net "H_CPU1_PROCHOT_G_PCH_N")
	)
	(segment
		(start 370.785644 -49.264824)
		(end 371.362986 -48.687482)
		(width 0.10795)
		(layer "B.Cu")
		(net "H_CPU1_PROCHOT_G_PCH_N")
	)
	(segment
		(start 360.185208 -46.496986)
		(end 360.555794 -46.496986)
		(width 0.10795)
		(layer "B.Cu")
		(net "H_CPU1_PROCHOT_G_PCH_N")
	)
	(segment
		(start 361.832144 -49.308004)
		(end 365.926116 -49.308004)
		(width 0.10795)
		(layer "B.Cu")
		(net "H_CPU1_PROCHOT_G_PCH_N")
	)
	(segment
		(start 360.455464 -48.746664)
		(end 361.270804 -48.746664)
		(width 0.10795)
		(layer "B.Cu")
		(net "H_CPU1_PROCHOT_G_PCH_N")
	)
	(segment
		(start 365.926116 -49.308004)
		(end 366.66805 -48.56607)
		(width 0.10795)
		(layer "B.Cu")
		(net "H_CPU1_PROCHOT_G_PCH_N")
	)
	(segment
		(start 361.270804 -48.746664)
		(end 361.832144 -49.308004)
		(width 0.10795)
		(layer "B.Cu")
		(net "H_CPU1_PROCHOT_G_PCH_N")
	)
	(segment
		(start 366.66805 -48.56607)
		(end 368.304064 -48.56607)
		(width 0.10795)
		(layer "B.Cu")
		(net "H_CPU1_PROCHOT_G_PCH_N")
	)
	(segment
		(start 369.002818 -49.264824)
		(end 370.785644 -49.264824)
		(width 0.10795)
		(layer "B.Cu")
		(net "H_CPU1_PROCHOT_G_PCH_N")
	)
	(segment
		(start 440.3344 -16.51)
		(end 439.7375 -16.51)
		(width 0.10795)
		(layer "F.Cu")
		(net "H_CPU1_MEMKLM_MEMHOT_G_R_N")
	)
	(segment
		(start 440.3344 -15.6464)
		(end 440.3344 -16.51)
		(width 0.10795)
		(layer "F.Cu")
		(net "H_CPU1_MEMKLM_MEMHOT_G_R_N")
	)
	(segment
		(start 439.7375 -16.51)
		(end 439.3565 -16.129)
		(width 0.10795)
		(layer "F.Cu")
		(net "H_CPU1_MEMKLM_MEMHOT_G_R_N")
	)
	(segment
		(start 440.0931 -15.4051)
		(end 440.3344 -15.6464)
		(width 0.10795)
		(layer "F.Cu")
		(net "H_CPU1_MEMKLM_MEMHOT_G_R_N")
	)
	(via
		(at 440.3344 -16.51)
		(size 0.762)
		(drill 0.381)
		(layers "F.Cu" "B.Cu")
		(net "H_CPU1_MEMKLM_MEMHOT_G_R_N")
	)
	(via
		(at 440.0931 -15.4051)
		(size 0.508)
		(drill 0.254)
		(layers "F.Cu" "B.Cu")
		(net "H_CPU1_MEMKLM_MEMHOT_G_R_N")
	)
	(segment
		(start 439.95848 -15.27048)
		(end 440.0931 -15.4051)
		(width 0.10795)
		(layer "B.Cu")
		(net "H_CPU1_MEMKLM_MEMHOT_G_R_N")
	)
	(segment
		(start 438.5945 -15.27048)
		(end 439.95848 -15.27048)
		(width 0.10795)
		(layer "B.Cu")
		(net "H_CPU1_MEMKLM_MEMHOT_G_R_N")
	)
	(segment
		(start 435.8767 -17.018)
		(end 435.5592 -17.018)
		(width 0.10795)
		(layer "F.Cu")
		(net "H_CPU1_MEMKLM_MEMHOT_G_PCH_N")
	)
	(segment
		(start 435.5592 -17.018)
		(end 435.1528 -16.6116)
		(width 0.10795)
		(layer "F.Cu")
		(net "H_CPU1_MEMKLM_MEMHOT_G_PCH_N")
	)
	(segment
		(start 436.2704 -17.018)
		(end 436.3974 -16.891)
		(width 0.10795)
		(layer "F.Cu")
		(net "H_CPU1_MEMKLM_MEMHOT_G_PCH_N")
	)
	(segment
		(start 435.1528 -16.6116)
		(end 434.6702 -16.6116)
		(width 0.10795)
		(layer "F.Cu")
		(net "H_CPU1_MEMKLM_MEMHOT_G_PCH_N")
	)
	(segment
		(start 436.3974 -16.891)
		(end 436.8165 -16.891)
		(width 0.10795)
		(layer "F.Cu")
		(net "H_CPU1_MEMKLM_MEMHOT_G_PCH_N")
	)
	(segment
		(start 435.8767 -17.018)
		(end 436.2704 -17.018)
		(width 0.10795)
		(layer "F.Cu")
		(net "H_CPU1_MEMKLM_MEMHOT_G_PCH_N")
	)
	(via
		(at 435.8767 -17.018)
		(size 0.762)
		(drill 0.381)
		(layers "F.Cu" "B.Cu")
		(net "H_CPU1_MEMKLM_MEMHOT_G_PCH_N")
	)
	(segment
		(start 439.3565 -15.367)
		(end 439.3565 -14.9733)
		(width 0.10795)
		(layer "F.Cu")
		(net "H_CPU1_MEMGHJ_MEMHOT_G_R_N")
	)
	(segment
		(start 439.5597 -14.7701)
		(end 440.0931 -14.7701)
		(width 0.10795)
		(layer "F.Cu")
		(net "H_CPU1_MEMGHJ_MEMHOT_G_R_N")
	)
	(segment
		(start 439.3565 -14.9733)
		(end 439.5597 -14.7701)
		(width 0.10795)
		(layer "F.Cu")
		(net "H_CPU1_MEMGHJ_MEMHOT_G_R_N")
	)
	(via
		(at 440.0931 -14.7701)
		(size 0.508)
		(drill 0.254)
		(layers "F.Cu" "B.Cu")
		(net "H_CPU1_MEMGHJ_MEMHOT_G_R_N")
	)
	(segment
		(start 439.94324 -14.62024)
		(end 440.0931 -14.7701)
		(width 0.10795)
		(layer "B.Cu")
		(net "H_CPU1_MEMGHJ_MEMHOT_G_R_N")
	)
	(segment
		(start 438.5945 -14.62024)
		(end 439.94324 -14.62024)
		(width 0.10795)
		(layer "B.Cu")
		(net "H_CPU1_MEMGHJ_MEMHOT_G_R_N")
	)
	(segment
		(start 436.8165 -13.726668)
		(end 436.8165 -14.605)
		(width 0.10795)
		(layer "F.Cu")
		(net "H_CPU1_MEMGHJ_MEMHOT_G_PCH_N")
	)
	(segment
		(start 428.256446 -13.95603)
		(end 430.343056 -13.95603)
		(width 0.10795)
		(layer "F.Cu")
		(net "H_CPU1_MEMGHJ_MEMHOT_G_PCH_N")
	)
	(segment
		(start 436.00878 -12.918948)
		(end 436.8165 -13.726668)
		(width 0.10795)
		(layer "F.Cu")
		(net "H_CPU1_MEMGHJ_MEMHOT_G_PCH_N")
	)
	(segment
		(start 430.343056 -13.95603)
		(end 431.380138 -12.918948)
		(width 0.10795)
		(layer "F.Cu")
		(net "H_CPU1_MEMGHJ_MEMHOT_G_PCH_N")
	)
	(segment
		(start 427.798992 -14.413484)
		(end 428.256446 -13.95603)
		(width 0.10795)
		(layer "F.Cu")
		(net "H_CPU1_MEMGHJ_MEMHOT_G_PCH_N")
	)
	(segment
		(start 431.380138 -12.918948)
		(end 436.00878 -12.918948)
		(width 0.10795)
		(layer "F.Cu")
		(net "H_CPU1_MEMGHJ_MEMHOT_G_PCH_N")
	)
	(via
		(at 427.268132 -15.22857)
		(size 0.6604)
		(drill 0.3302)
		(layers "F.Cu" "B.Cu")
		(net "H_CPU1_MEMGHJ_MEMHOT_G_PCH_N")
	)
	(via
		(at 427.798992 -14.413484)
		(size 0.508)
		(drill 0.254)
		(layers "F.Cu" "B.Cu")
		(net "H_CPU1_MEMGHJ_MEMHOT_G_PCH_N")
	)
	(segment
		(start 427.212506 -14.648434)
		(end 427.212506 -15.172944)
		(width 0.10795)
		(layer "B.Cu")
		(net "H_CPU1_MEMGHJ_MEMHOT_G_PCH_N")
	)
	(segment
		(start 427.447456 -14.413484)
		(end 427.212506 -14.648434)
		(width 0.10795)
		(layer "B.Cu")
		(net "H_CPU1_MEMGHJ_MEMHOT_G_PCH_N")
	)
	(segment
		(start 427.212506 -15.172944)
		(end 427.268132 -15.22857)
		(width 0.10795)
		(layer "B.Cu")
		(net "H_CPU1_MEMGHJ_MEMHOT_G_PCH_N")
	)
	(segment
		(start 427.268132 -15.22857)
		(end 427.320456 -15.280894)
		(width 0.10795)
		(layer "B.Cu")
		(net "H_CPU1_MEMGHJ_MEMHOT_G_PCH_N")
	)
	(segment
		(start 427.320456 -15.280894)
		(end 428.157894 -15.280894)
		(width 0.10795)
		(layer "B.Cu")
		(net "H_CPU1_MEMGHJ_MEMHOT_G_PCH_N")
	)
	(segment
		(start 427.798992 -14.413484)
		(end 427.447456 -14.413484)
		(width 0.10795)
		(layer "B.Cu")
		(net "H_CPU1_MEMGHJ_MEMHOT_G_PCH_N")
	)
	(segment
		(start 370.290852 -45.488098)
		(end 371.928898 -45.488098)
		(width 0.10795)
		(layer "B.Cu")
		(net "H_CPU0_PROCHOT_G_R_N")
	)
	(segment
		(start 371.928898 -45.488098)
		(end 372.5164 -46.0756)
		(width 0.10795)
		(layer "B.Cu")
		(net "H_CPU0_PROCHOT_G_R_N")
	)
	(segment
		(start 372.5164 -46.0756)
		(end 372.9482 -46.0756)
		(width 0.10795)
		(layer "B.Cu")
		(net "H_CPU0_PROCHOT_G_R_N")
	)
	(via
		(at 372.4656 -49.591722)
		(size 0.6604)
		(drill 0.3302)
		(layers "F.Cu" "B.Cu")
		(net "H_CPU0_PROCHOT_G_PCH_N")
	)
	(segment
		(start 367.832386 -48.99787)
		(end 368.53114 -49.696624)
		(width 0.10795)
		(layer "B.Cu")
		(net "H_CPU0_PROCHOT_G_PCH_N")
	)
	(segment
		(start 361.653074 -49.739804)
		(end 365.810038 -49.739804)
		(width 0.10795)
		(layer "B.Cu")
		(net "H_CPU0_PROCHOT_G_PCH_N")
	)
	(segment
		(start 361.091734 -49.178464)
		(end 361.653074 -49.739804)
		(width 0.10795)
		(layer "B.Cu")
		(net "H_CPU0_PROCHOT_G_PCH_N")
	)
	(segment
		(start 360.008424 -49.178464)
		(end 361.091734 -49.178464)
		(width 0.10795)
		(layer "B.Cu")
		(net "H_CPU0_PROCHOT_G_PCH_N")
	)
	(segment
		(start 372.4656 -49.6062)
		(end 372.4656 -49.591722)
		(width 0.10795)
		(layer "B.Cu")
		(net "H_CPU0_PROCHOT_G_PCH_N")
	)
	(segment
		(start 359.44556 -45.607986)
		(end 358.6988 -46.354746)
		(width 0.10795)
		(layer "B.Cu")
		(net "H_CPU0_PROCHOT_G_PCH_N")
	)
	(segment
		(start 365.810038 -49.739804)
		(end 365.811816 -49.741582)
		(width 0.10795)
		(layer "B.Cu")
		(net "H_CPU0_PROCHOT_G_PCH_N")
	)
	(segment
		(start 373.175022 -48.8823)
		(end 374.866154 -48.8823)
		(width 0.10795)
		(layer "B.Cu")
		(net "H_CPU0_PROCHOT_G_PCH_N")
	)
	(segment
		(start 360.555794 -45.607986)
		(end 359.44556 -45.607986)
		(width 0.10795)
		(layer "B.Cu")
		(net "H_CPU0_PROCHOT_G_PCH_N")
	)
	(segment
		(start 374.866154 -48.8823)
		(end 375.270268 -48.478186)
		(width 0.10795)
		(layer "B.Cu")
		(net "H_CPU0_PROCHOT_G_PCH_N")
	)
	(segment
		(start 365.811816 -49.741582)
		(end 366.103408 -49.741582)
		(width 0.10795)
		(layer "B.Cu")
		(net "H_CPU0_PROCHOT_G_PCH_N")
	)
	(segment
		(start 375.270268 -48.478186)
		(end 375.270268 -48.328326)
		(width 0.10795)
		(layer "B.Cu")
		(net "H_CPU0_PROCHOT_G_PCH_N")
	)
	(segment
		(start 358.6988 -47.86884)
		(end 360.008424 -49.178464)
		(width 0.10795)
		(layer "B.Cu")
		(net "H_CPU0_PROCHOT_G_PCH_N")
	)
	(segment
		(start 372.375176 -49.696624)
		(end 372.4656 -49.6062)
		(width 0.10795)
		(layer "B.Cu")
		(net "H_CPU0_PROCHOT_G_PCH_N")
	)
	(segment
		(start 368.53114 -49.696624)
		(end 372.375176 -49.696624)
		(width 0.10795)
		(layer "B.Cu")
		(net "H_CPU0_PROCHOT_G_PCH_N")
	)
	(segment
		(start 366.103408 -49.741582)
		(end 366.84712 -48.99787)
		(width 0.10795)
		(layer "B.Cu")
		(net "H_CPU0_PROCHOT_G_PCH_N")
	)
	(segment
		(start 366.84712 -48.99787)
		(end 367.832386 -48.99787)
		(width 0.10795)
		(layer "B.Cu")
		(net "H_CPU0_PROCHOT_G_PCH_N")
	)
	(segment
		(start 372.4656 -49.591722)
		(end 373.175022 -48.8823)
		(width 0.10795)
		(layer "B.Cu")
		(net "H_CPU0_PROCHOT_G_PCH_N")
	)
	(segment
		(start 358.6988 -46.354746)
		(end 358.6988 -47.86884)
		(width 0.10795)
		(layer "B.Cu")
		(net "H_CPU0_PROCHOT_G_PCH_N")
	)
	(segment
		(start 437.769 -12.954)
		(end 437.37276 -12.954)
		(width 0.10795)
		(layer "F.Cu")
		(net "H_CPU0_MEMDEF_MEMHOT_G_R_N")
	)
	(segment
		(start 437.37276 -12.954)
		(end 437.007 -13.31976)
		(width 0.10795)
		(layer "F.Cu")
		(net "H_CPU0_MEMDEF_MEMHOT_G_R_N")
	)
	(via
		(at 437.007 -13.31976)
		(size 0.508)
		(drill 0.254)
		(layers "F.Cu" "B.Cu")
		(net "H_CPU0_MEMDEF_MEMHOT_G_R_N")
	)
	(via
		(at 440.9059 -12.6111)
		(size 0.6604)
		(drill 0.3302)
		(layers "F.Cu" "B.Cu")
		(net "H_CPU0_MEMDEF_MEMHOT_G_R_N")
	)
	(segment
		(start 438.5945 -13.31976)
		(end 437.007 -13.31976)
		(width 0.10795)
		(layer "B.Cu")
		(net "H_CPU0_MEMDEF_MEMHOT_G_R_N")
	)
	(segment
		(start 439.68924 -13.31976)
		(end 440.1947 -12.8143)
		(width 0.10795)
		(layer "B.Cu")
		(net "H_CPU0_MEMDEF_MEMHOT_G_R_N")
	)
	(segment
		(start 440.1947 -12.8143)
		(end 440.7027 -12.8143)
		(width 0.10795)
		(layer "B.Cu")
		(net "H_CPU0_MEMDEF_MEMHOT_G_R_N")
	)
	(segment
		(start 438.5945 -13.31976)
		(end 439.68924 -13.31976)
		(width 0.10795)
		(layer "B.Cu")
		(net "H_CPU0_MEMDEF_MEMHOT_G_R_N")
	)
	(segment
		(start 440.7027 -12.8143)
		(end 440.9059 -12.6111)
		(width 0.10795)
		(layer "B.Cu")
		(net "H_CPU0_MEMDEF_MEMHOT_G_R_N")
	)
	(segment
		(start 438.531 -12.2682)
		(end 437.9722 -11.7094)
		(width 0.10795)
		(layer "F.Cu")
		(net "H_CPU0_MEMDEF_MEMHOT_G_PCH_N")
	)
	(segment
		(start 438.531 -12.954)
		(end 438.531 -12.2682)
		(width 0.10795)
		(layer "F.Cu")
		(net "H_CPU0_MEMDEF_MEMHOT_G_PCH_N")
	)
	(segment
		(start 437.9722 -11.7094)
		(end 436.9054 -11.7094)
		(width 0.10795)
		(layer "F.Cu")
		(net "H_CPU0_MEMDEF_MEMHOT_G_PCH_N")
	)
	(via
		(at 426.371258 -13.872464)
		(size 0.508)
		(drill 0.254)
		(layers "F.Cu" "B.Cu")
		(net "H_CPU0_MEMDEF_MEMHOT_G_PCH_N")
	)
	(via
		(at 436.9054 -11.7094)
		(size 0.508)
		(drill 0.254)
		(layers "F.Cu" "B.Cu")
		(net "H_CPU0_MEMDEF_MEMHOT_G_PCH_N")
	)
	(via
		(at 426.459396 -13.113004)
		(size 0.6604)
		(drill 0.3302)
		(layers "F.Cu" "B.Cu")
		(net "H_CPU0_MEMDEF_MEMHOT_G_PCH_N")
	)
	(segment
		(start 426.371258 -13.201142)
		(end 426.459396 -13.113004)
		(width 0.10795)
		(layer "B.Cu")
		(net "H_CPU0_MEMDEF_MEMHOT_G_PCH_N")
	)
	(segment
		(start 426.459396 -13.113004)
		(end 426.561758 -13.010642)
		(width 0.10795)
		(layer "B.Cu")
		(net "H_CPU0_MEMDEF_MEMHOT_G_PCH_N")
	)
	(segment
		(start 426.561758 -13.010642)
		(end 427.38675 -13.010642)
		(width 0.10795)
		(layer "B.Cu")
		(net "H_CPU0_MEMDEF_MEMHOT_G_PCH_N")
	)
	(segment
		(start 426.371258 -13.872464)
		(end 426.371258 -13.201142)
		(width 0.10795)
		(layer "B.Cu")
		(net "H_CPU0_MEMDEF_MEMHOT_G_PCH_N")
	)
	(segment
		(start 436.471568 -12.143232)
		(end 428.336456 -12.143232)
		(width 0.089408)
		(layer "In11.Cu")
		(net "H_CPU0_MEMDEF_MEMHOT_G_PCH_N")
	)
	(segment
		(start 436.9054 -11.7094)
		(end 436.471568 -12.143232)
		(width 0.089408)
		(layer "In11.Cu")
		(net "H_CPU0_MEMDEF_MEMHOT_G_PCH_N")
	)
	(segment
		(start 428.336456 -12.143232)
		(end 426.607224 -13.872464)
		(width 0.089408)
		(layer "In11.Cu")
		(net "H_CPU0_MEMDEF_MEMHOT_G_PCH_N")
	)
	(segment
		(start 426.607224 -13.872464)
		(end 426.371258 -13.872464)
		(width 0.089408)
		(layer "In11.Cu")
		(net "H_CPU0_MEMDEF_MEMHOT_G_PCH_N")
	)
	(segment
		(start 444.142876 -12.244324)
		(end 444.3476 -12.0396)
		(width 0.10795)
		(layer "F.Cu")
		(net "H_CPU0_MEMABC_MEMHOT_G_R_N")
	)
	(segment
		(start 444.3476 -12.0396)
		(end 444.6016 -12.0396)
		(width 0.10795)
		(layer "F.Cu")
		(net "H_CPU0_MEMABC_MEMHOT_G_R_N")
	)
	(segment
		(start 444.142876 -12.599924)
		(end 444.142876 -12.244324)
		(width 0.10795)
		(layer "F.Cu")
		(net "H_CPU0_MEMABC_MEMHOT_G_R_N")
	)
	(via
		(at 441.0964 -11.3538)
		(size 0.6604)
		(drill 0.3302)
		(layers "F.Cu" "B.Cu")
		(net "H_CPU0_MEMABC_MEMHOT_G_R_N")
	)
	(via
		(at 444.6016 -12.0396)
		(size 0.508)
		(drill 0.254)
		(layers "F.Cu" "B.Cu")
		(net "H_CPU0_MEMABC_MEMHOT_G_R_N")
	)
	(segment
		(start 440.055 -12.3952)
		(end 439.78068 -12.66952)
		(width 0.10795)
		(layer "B.Cu")
		(net "H_CPU0_MEMABC_MEMHOT_G_R_N")
	)
	(segment
		(start 443.8142 -12.0396)
		(end 443.4586 -12.3952)
		(width 0.10795)
		(layer "B.Cu")
		(net "H_CPU0_MEMABC_MEMHOT_G_R_N")
	)
	(segment
		(start 444.6016 -12.0396)
		(end 443.8142 -12.0396)
		(width 0.10795)
		(layer "B.Cu")
		(net "H_CPU0_MEMABC_MEMHOT_G_R_N")
	)
	(segment
		(start 441.0964 -11.3538)
		(end 440.309 -11.3538)
		(width 0.10795)
		(layer "B.Cu")
		(net "H_CPU0_MEMABC_MEMHOT_G_R_N")
	)
	(segment
		(start 441.3504 -11.3538)
		(end 441.0964 -11.3538)
		(width 0.10795)
		(layer "B.Cu")
		(net "H_CPU0_MEMABC_MEMHOT_G_R_N")
	)
	(segment
		(start 440.055 -11.6078)
		(end 440.055 -12.3952)
		(width 0.10795)
		(layer "B.Cu")
		(net "H_CPU0_MEMABC_MEMHOT_G_R_N")
	)
	(segment
		(start 443.4586 -12.3952)
		(end 442.3918 -12.3952)
		(width 0.10795)
		(layer "B.Cu")
		(net "H_CPU0_MEMABC_MEMHOT_G_R_N")
	)
	(segment
		(start 442.3918 -12.3952)
		(end 441.3504 -11.3538)
		(width 0.10795)
		(layer "B.Cu")
		(net "H_CPU0_MEMABC_MEMHOT_G_R_N")
	)
	(segment
		(start 439.78068 -12.66952)
		(end 438.5945 -12.66952)
		(width 0.10795)
		(layer "B.Cu")
		(net "H_CPU0_MEMABC_MEMHOT_G_R_N")
	)
	(segment
		(start 440.309 -11.3538)
		(end 440.055 -11.6078)
		(width 0.10795)
		(layer "B.Cu")
		(net "H_CPU0_MEMABC_MEMHOT_G_R_N")
	)
	(segment
		(start 442.618876 -11.964924)
		(end 442.364876 -12.218924)
		(width 0.10795)
		(layer "F.Cu")
		(net "H_CPU0_MEMABC_MEMHOT_G_PCH_N")
	)
	(segment
		(start 442.364876 -12.218924)
		(end 442.364876 -13.361924)
		(width 0.10795)
		(layer "F.Cu")
		(net "H_CPU0_MEMABC_MEMHOT_G_PCH_N")
	)
	(via
		(at 442.618876 -11.964924)
		(size 0.508)
		(drill 0.254)
		(layers "F.Cu" "B.Cu")
		(net "H_CPU0_MEMABC_MEMHOT_G_PCH_N")
	)
	(via
		(at 442.8744 -11.1506)
		(size 0.6604)
		(drill 0.3302)
		(layers "F.Cu" "B.Cu")
		(net "H_CPU0_MEMABC_MEMHOT_G_PCH_N")
	)
	(segment
		(start 426.9105 -11.176)
		(end 426.9105 -10.8331)
		(width 0.10795)
		(layer "B.Cu")
		(net "H_CPU0_MEMABC_MEMHOT_G_PCH_N")
	)
	(segment
		(start 442.722254 -10.795)
		(end 442.8744 -10.947146)
		(width 0.10795)
		(layer "B.Cu")
		(net "H_CPU0_MEMABC_MEMHOT_G_PCH_N")
	)
	(segment
		(start 431.0634 -10.795)
		(end 442.722254 -10.795)
		(width 0.10795)
		(layer "B.Cu")
		(net "H_CPU0_MEMABC_MEMHOT_G_PCH_N")
	)
	(segment
		(start 442.618876 -11.964924)
		(end 442.8744 -11.7094)
		(width 0.10795)
		(layer "B.Cu")
		(net "H_CPU0_MEMABC_MEMHOT_G_PCH_N")
	)
	(segment
		(start 427.1899 -10.5537)
		(end 430.8221 -10.5537)
		(width 0.10795)
		(layer "B.Cu")
		(net "H_CPU0_MEMABC_MEMHOT_G_PCH_N")
	)
	(segment
		(start 426.9105 -10.8331)
		(end 427.1899 -10.5537)
		(width 0.10795)
		(layer "B.Cu")
		(net "H_CPU0_MEMABC_MEMHOT_G_PCH_N")
	)
	(segment
		(start 442.8744 -10.947146)
		(end 442.8744 -11.1506)
		(width 0.10795)
		(layer "B.Cu")
		(net "H_CPU0_MEMABC_MEMHOT_G_PCH_N")
	)
	(segment
		(start 442.8744 -11.7094)
		(end 442.8744 -11.1506)
		(width 0.10795)
		(layer "B.Cu")
		(net "H_CPU0_MEMABC_MEMHOT_G_PCH_N")
	)
	(segment
		(start 430.8221 -10.5537)
		(end 431.0634 -10.795)
		(width 0.10795)
		(layer "B.Cu")
		(net "H_CPU0_MEMABC_MEMHOT_G_PCH_N")
	)
	(segment
		(start 363.081062 -46.138338)
		(end 362.785914 -46.433486)
		(width 0.10795)
		(layer "B.Cu")
		(net "FM_CPU1_PROCHOT_LVT3_R_N")
	)
	(segment
		(start 362.785914 -46.433486)
		(end 362.270294 -46.433486)
		(width 0.10795)
		(layer "B.Cu")
		(net "FM_CPU1_PROCHOT_LVT3_R_N")
	)
	(segment
		(start 364.321852 -46.138338)
		(end 363.081062 -46.138338)
		(width 0.10795)
		(layer "B.Cu")
		(net "FM_CPU1_PROCHOT_LVT3_R_N")
	)
	(segment
		(start 362.709714 -45.671486)
		(end 362.270294 -45.671486)
		(width 0.10795)
		(layer "B.Cu")
		(net "FM_CPU0_PROCHOT_LVT3_R_N")
	)
	(segment
		(start 364.321852 -45.488098)
		(end 362.893102 -45.488098)
		(width 0.10795)
		(layer "B.Cu")
		(net "FM_CPU0_PROCHOT_LVT3_R_N")
	)
	(segment
		(start 362.893102 -45.488098)
		(end 362.709714 -45.671486)
		(width 0.10795)
		(layer "B.Cu")
		(net "FM_CPU0_PROCHOT_LVT3_R_N")
	)
	(segment
		(start 290.0807 -65.810384)
		(end 290.6522 -65.810384)
		(width 0.127)
		(layer "F.Cu")
		(net "VSENSE_P1V8MCP_CPU0_SKT_VSEN")
	)
	(segment
		(start 329.594972 -40.094408)
		(end 329.057 -40.63238)
		(width 0.127)
		(layer "F.Cu")
		(net "VSENSE_P1V8MCP_CPU0_SKT_VSEN")
	)
	(segment
		(start 329.594972 -39.99103)
		(end 329.594972 -40.094408)
		(width 0.127)
		(layer "F.Cu")
		(net "VSENSE_P1V8MCP_CPU0_SKT_VSEN")
	)
	(via
		(at 329.057 -40.63238)
		(size 0.508)
		(drill 0.254)
		(layers "F.Cu" "B.Cu")
		(net "VSENSE_P1V8MCP_CPU0_SKT_VSEN")
	)
	(via
		(at 290.6522 -65.810384)
		(size 0.508)
		(drill 0.254)
		(layers "F.Cu" "B.Cu")
		(net "VSENSE_P1V8MCP_CPU0_SKT_VSEN")
	)
	(segment
		(start 302.653446 -67.201034)
		(end 302.689006 -67.201034)
		(width 0.0889)
		(layer "In2.Cu")
		(net "VSENSE_P1V8MCP_CPU0_SKT_VSEN")
	)
	(segment
		(start 306.949856 -66.306192)
		(end 307.407818 -65.769236)
		(width 0.127)
		(layer "In2.Cu")
		(net "VSENSE_P1V8MCP_CPU0_SKT_VSEN")
	)
	(segment
		(start 290.6522 -65.810384)
		(end 290.945316 -65.979548)
		(width 0.0889)
		(layer "In2.Cu")
		(net "VSENSE_P1V8MCP_CPU0_SKT_VSEN")
	)
	(segment
		(start 298.36745 -66.705988)
		(end 298.400216 -66.705988)
		(width 0.0889)
		(layer "In2.Cu")
		(net "VSENSE_P1V8MCP_CPU0_SKT_VSEN")
	)
	(segment
		(start 294.073326 -64.229488)
		(end 294.091106 -64.229488)
		(width 0.0889)
		(layer "In2.Cu")
		(net "VSENSE_P1V8MCP_CPU0_SKT_VSEN")
	)
	(segment
		(start 296.650664 -63.734188)
		(end 296.686732 -63.734188)
		(width 0.0889)
		(layer "In2.Cu")
		(net "VSENSE_P1V8MCP_CPU0_SKT_VSEN")
	)
	(segment
		(start 329.311762 -41.264332)
		(end 329.438 -41.138094)
		(width 0.127)
		(layer "In2.Cu")
		(net "VSENSE_P1V8MCP_CPU0_SKT_VSEN")
	)
	(segment
		(start 308.417976 -45.407326)
		(end 310.093106 -43.732196)
		(width 0.127)
		(layer "In2.Cu")
		(net "VSENSE_P1V8MCP_CPU0_SKT_VSEN")
	)
	(segment
		(start 293.20617 -64.724788)
		(end 293.22776 -64.724788)
		(width 0.0889)
		(layer "In2.Cu")
		(net "VSENSE_P1V8MCP_CPU0_SKT_VSEN")
	)
	(segment
		(start 323.35343 -41.84777)
		(end 323.936868 -41.264332)
		(width 0.127)
		(layer "In2.Cu")
		(net "VSENSE_P1V8MCP_CPU0_SKT_VSEN")
	)
	(segment
		(start 294.92321 -63.734188)
		(end 294.955976 -63.734188)
		(width 0.0889)
		(layer "In2.Cu")
		(net "VSENSE_P1V8MCP_CPU0_SKT_VSEN")
	)
	(segment
		(start 297.520106 -64.229234)
		(end 297.537886 -64.229234)
		(width 0.0889)
		(layer "In2.Cu")
		(net "VSENSE_P1V8MCP_CPU0_SKT_VSEN")
	)
	(segment
		(start 292.35146 -65.219834)
		(end 292.384226 -65.219834)
		(width 0.0889)
		(layer "In2.Cu")
		(net "VSENSE_P1V8MCP_CPU0_SKT_VSEN")
	)
	(segment
		(start 306.83708 -66.457068)
		(end 306.949856 -66.306192)
		(width 0.127)
		(layer "In2.Cu")
		(net "VSENSE_P1V8MCP_CPU0_SKT_VSEN")
	)
	(segment
		(start 298.02709 -65.5066)
		(end 298.031916 -65.515236)
		(width 0.0889)
		(layer "In2.Cu")
		(net "VSENSE_P1V8MCP_CPU0_SKT_VSEN")
	)
	(segment
		(start 300.936406 -67.201034)
		(end 300.971966 -67.201034)
		(width 0.0889)
		(layer "In2.Cu")
		(net "VSENSE_P1V8MCP_CPU0_SKT_VSEN")
	)
	(segment
		(start 308.791864 -64.384428)
		(end 308.79161 -64.384428)
		(width 0.127)
		(layer "In2.Cu")
		(net "VSENSE_P1V8MCP_CPU0_SKT_VSEN")
	)
	(segment
		(start 297.17365 -64.029082)
		(end 297.176952 -64.034924)
		(width 0.0889)
		(layer "In2.Cu")
		(net "VSENSE_P1V8MCP_CPU0_SKT_VSEN")
	)
	(segment
		(start 310.500776 -62.211204)
		(end 310.500776 -57.749186)
		(width 0.127)
		(layer "In2.Cu")
		(net "VSENSE_P1V8MCP_CPU0_SKT_VSEN")
	)
	(segment
		(start 314.042044 -41.84777)
		(end 323.35343 -41.84777)
		(width 0.127)
		(layer "In2.Cu")
		(net "VSENSE_P1V8MCP_CPU0_SKT_VSEN")
	)
	(segment
		(start 290.945316 -65.979548)
		(end 291.034724 -65.955418)
		(width 0.0889)
		(layer "In2.Cu")
		(net "VSENSE_P1V8MCP_CPU0_SKT_VSEN")
	)
	(segment
		(start 291.48913 -65.715388)
		(end 291.521896 -65.715388)
		(width 0.0889)
		(layer "In2.Cu")
		(net "VSENSE_P1V8MCP_CPU0_SKT_VSEN")
	)
	(segment
		(start 306.827936 -66.501772)
		(end 306.823872 -66.474848)
		(width 0.0889)
		(layer "In2.Cu")
		(net "VSENSE_P1V8MCP_CPU0_SKT_VSEN")
	)
	(segment
		(start 295.78554 -63.238634)
		(end 295.8211 -63.238634)
		(width 0.0889)
		(layer "In2.Cu")
		(net "VSENSE_P1V8MCP_CPU0_SKT_VSEN")
	)
	(segment
		(start 306.823872 -66.474848)
		(end 306.83708 -66.457068)
		(width 0.0889)
		(layer "In2.Cu")
		(net "VSENSE_P1V8MCP_CPU0_SKT_VSEN")
	)
	(segment
		(start 308.417976 -55.666386)
		(end 308.417976 -45.407326)
		(width 0.127)
		(layer "In2.Cu")
		(net "VSENSE_P1V8MCP_CPU0_SKT_VSEN")
	)
	(segment
		(start 310.093106 -43.732196)
		(end 312.157618 -43.732196)
		(width 0.127)
		(layer "In2.Cu")
		(net "VSENSE_P1V8MCP_CPU0_SKT_VSEN")
	)
	(segment
		(start 304.370486 -67.201034)
		(end 304.406046 -67.201034)
		(width 0.0889)
		(layer "In2.Cu")
		(net "VSENSE_P1V8MCP_CPU0_SKT_VSEN")
	)
	(segment
		(start 310.500776 -57.749186)
		(end 308.417976 -55.666386)
		(width 0.127)
		(layer "In2.Cu")
		(net "VSENSE_P1V8MCP_CPU0_SKT_VSEN")
	)
	(segment
		(start 306.545996 -66.878708)
		(end 306.827936 -66.501772)
		(width 0.0889)
		(layer "In2.Cu")
		(net "VSENSE_P1V8MCP_CPU0_SKT_VSEN")
	)
	(segment
		(start 323.936868 -41.264332)
		(end 329.311762 -41.264332)
		(width 0.127)
		(layer "In2.Cu")
		(net "VSENSE_P1V8MCP_CPU0_SKT_VSEN")
	)
	(segment
		(start 329.438 -41.01338)
		(end 329.057 -40.63238)
		(width 0.127)
		(layer "In2.Cu")
		(net "VSENSE_P1V8MCP_CPU0_SKT_VSEN")
	)
	(segment
		(start 308.79161 -64.384428)
		(end 310.500776 -62.211204)
		(width 0.127)
		(layer "In2.Cu")
		(net "VSENSE_P1V8MCP_CPU0_SKT_VSEN")
	)
	(segment
		(start 307.407818 -65.769236)
		(end 308.791864 -64.384428)
		(width 0.127)
		(layer "In2.Cu")
		(net "VSENSE_P1V8MCP_CPU0_SKT_VSEN")
	)
	(segment
		(start 312.157618 -43.732196)
		(end 314.042044 -41.84777)
		(width 0.127)
		(layer "In2.Cu")
		(net "VSENSE_P1V8MCP_CPU0_SKT_VSEN")
	)
	(segment
		(start 298.031916 -65.515236)
		(end 298.038266 -65.525904)
		(width 0.0889)
		(layer "In2.Cu")
		(net "VSENSE_P1V8MCP_CPU0_SKT_VSEN")
	)
	(segment
		(start 306.087526 -67.201034)
		(end 306.120292 -67.201034)
		(width 0.0889)
		(layer "In2.Cu")
		(net "VSENSE_P1V8MCP_CPU0_SKT_VSEN")
	)
	(segment
		(start 329.438 -41.138094)
		(end 329.438 -41.01338)
		(width 0.127)
		(layer "In2.Cu")
		(net "VSENSE_P1V8MCP_CPU0_SKT_VSEN")
	)
	(segment
		(start 299.22216 -67.201034)
		(end 299.254926 -67.201034)
		(width 0.0889)
		(layer "In2.Cu")
		(net "VSENSE_P1V8MCP_CPU0_SKT_VSEN")
	)
	(segment
		(start 300.095666 -67.696588)
		(end 300.106842 -67.696588)
		(width 0.0889)
		(layer "In2.Cu")
		(net "VSENSE_P1V8MCP_CPU0_SKT_VSEN")
	)
	(arc
		(start 306.451762 -67.00139)
		(mid 306.494853 -66.936957)
		(end 306.545996 -66.878708)
		(width 0.0889)
		(layer "In2.Cu")
		(net "VSENSE_P1V8MCP_CPU0_SKT_VSEN")
	)
	(arc
		(start 304.900076 -67.496436)
		(mid 305.04661 -67.64298)
		(end 305.246786 -67.696588)
		(width 0.0889)
		(layer "In2.Cu")
		(net "VSENSE_P1V8MCP_CPU0_SKT_VSEN")
	)
	(arc
		(start 298.038266 -65.525904)
		(mid 298.111064 -65.816667)
		(end 298.031916 -66.105786)
		(width 0.0889)
		(layer "In2.Cu")
		(net "VSENSE_P1V8MCP_CPU0_SKT_VSEN")
	)
	(arc
		(start 300.971966 -67.201034)
		(mid 301.25739 -67.284501)
		(end 301.465996 -67.496436)
		(width 0.0889)
		(layer "In2.Cu")
		(net "VSENSE_P1V8MCP_CPU0_SKT_VSEN")
	)
	(arc
		(start 303.876456 -67.496436)
		(mid 304.085064 -67.284504)
		(end 304.370486 -67.201034)
		(width 0.0889)
		(layer "In2.Cu")
		(net "VSENSE_P1V8MCP_CPU0_SKT_VSEN")
	)
	(arc
		(start 303.183036 -67.496436)
		(mid 303.324392 -67.640045)
		(end 303.517808 -67.696588)
		(width 0.0889)
		(layer "In2.Cu")
		(net "VSENSE_P1V8MCP_CPU0_SKT_VSEN")
	)
	(arc
		(start 297.537886 -64.229234)
		(mid 298.036137 -64.532074)
		(end 298.031916 -65.115186)
		(width 0.0889)
		(layer "In2.Cu")
		(net "VSENSE_P1V8MCP_CPU0_SKT_VSEN")
	)
	(arc
		(start 301.800768 -67.696588)
		(mid 301.812706 -67.696766)
		(end 301.824644 -67.696588)
		(width 0.0889)
		(layer "In2.Cu")
		(net "VSENSE_P1V8MCP_CPU0_SKT_VSEN")
	)
	(arc
		(start 305.246786 -67.696588)
		(mid 305.446946 -67.642953)
		(end 305.593496 -67.496436)
		(width 0.0889)
		(layer "In2.Cu")
		(net "VSENSE_P1V8MCP_CPU0_SKT_VSEN")
	)
	(arc
		(start 298.400216 -66.705988)
		(mid 298.683433 -66.790269)
		(end 298.890436 -67.001136)
		(width 0.0889)
		(layer "In2.Cu")
		(net "VSENSE_P1V8MCP_CPU0_SKT_VSEN")
	)
	(arc
		(start 303.541684 -67.696588)
		(mid 303.73511 -67.640061)
		(end 303.876456 -67.496436)
		(width 0.0889)
		(layer "In2.Cu")
		(net "VSENSE_P1V8MCP_CPU0_SKT_VSEN")
	)
	(arc
		(start 302.689006 -67.201034)
		(mid 302.97443 -67.284501)
		(end 303.183036 -67.496436)
		(width 0.0889)
		(layer "In2.Cu")
		(net "VSENSE_P1V8MCP_CPU0_SKT_VSEN")
	)
	(arc
		(start 297.176952 -64.034924)
		(mid 297.322918 -64.177323)
		(end 297.520106 -64.229234)
		(width 0.0889)
		(layer "In2.Cu")
		(net "VSENSE_P1V8MCP_CPU0_SKT_VSEN")
	)
	(arc
		(start 305.593496 -67.496436)
		(mid 305.802104 -67.284504)
		(end 306.087526 -67.201034)
		(width 0.0889)
		(layer "In2.Cu")
		(net "VSENSE_P1V8MCP_CPU0_SKT_VSEN")
	)
	(arc
		(start 301.465996 -67.496436)
		(mid 301.607352 -67.640045)
		(end 301.800768 -67.696588)
		(width 0.0889)
		(layer "In2.Cu")
		(net "VSENSE_P1V8MCP_CPU0_SKT_VSEN")
	)
	(arc
		(start 296.686732 -63.734188)
		(mid 296.968032 -63.819154)
		(end 297.17365 -64.029082)
		(width 0.0889)
		(layer "In2.Cu")
		(net "VSENSE_P1V8MCP_CPU0_SKT_VSEN")
	)
	(arc
		(start 298.890436 -67.001136)
		(mid 299.030515 -67.143872)
		(end 299.22216 -67.201034)
		(width 0.0889)
		(layer "In2.Cu")
		(net "VSENSE_P1V8MCP_CPU0_SKT_VSEN")
	)
	(arc
		(start 292.71595 -65.019936)
		(mid 292.922954 -64.809072)
		(end 293.20617 -64.724788)
		(width 0.0889)
		(layer "In2.Cu")
		(net "VSENSE_P1V8MCP_CPU0_SKT_VSEN")
	)
	(arc
		(start 302.159416 -67.496436)
		(mid 302.368024 -67.284504)
		(end 302.653446 -67.201034)
		(width 0.0889)
		(layer "In2.Cu")
		(net "VSENSE_P1V8MCP_CPU0_SKT_VSEN")
	)
	(arc
		(start 291.85743 -65.515236)
		(mid 292.066038 -65.303304)
		(end 292.35146 -65.219834)
		(width 0.0889)
		(layer "In2.Cu")
		(net "VSENSE_P1V8MCP_CPU0_SKT_VSEN")
	)
	(arc
		(start 293.22776 -64.724788)
		(mid 293.427856 -64.671229)
		(end 293.57447 -64.52489)
		(width 0.0889)
		(layer "In2.Cu")
		(net "VSENSE_P1V8MCP_CPU0_SKT_VSEN")
	)
	(arc
		(start 294.43299 -64.029336)
		(mid 294.639994 -63.818472)
		(end 294.92321 -63.734188)
		(width 0.0889)
		(layer "In2.Cu")
		(net "VSENSE_P1V8MCP_CPU0_SKT_VSEN")
	)
	(arc
		(start 303.517808 -67.696588)
		(mid 303.529746 -67.696766)
		(end 303.541684 -67.696588)
		(width 0.0889)
		(layer "In2.Cu")
		(net "VSENSE_P1V8MCP_CPU0_SKT_VSEN")
	)
	(arc
		(start 295.8211 -63.238634)
		(mid 296.106524 -63.322101)
		(end 296.31513 -63.534036)
		(width 0.0889)
		(layer "In2.Cu")
		(net "VSENSE_P1V8MCP_CPU0_SKT_VSEN")
	)
	(arc
		(start 292.384226 -65.219834)
		(mid 292.575868 -65.162668)
		(end 292.71595 -65.019936)
		(width 0.0889)
		(layer "In2.Cu")
		(net "VSENSE_P1V8MCP_CPU0_SKT_VSEN")
	)
	(arc
		(start 306.120292 -67.201034)
		(mid 306.311786 -67.143957)
		(end 306.451762 -67.00139)
		(width 0.0889)
		(layer "In2.Cu")
		(net "VSENSE_P1V8MCP_CPU0_SKT_VSEN")
	)
	(arc
		(start 304.406046 -67.201034)
		(mid 304.69147 -67.284501)
		(end 304.900076 -67.496436)
		(width 0.0889)
		(layer "In2.Cu")
		(net "VSENSE_P1V8MCP_CPU0_SKT_VSEN")
	)
	(arc
		(start 300.442376 -67.496436)
		(mid 300.650984 -67.284504)
		(end 300.936406 -67.201034)
		(width 0.0889)
		(layer "In2.Cu")
		(net "VSENSE_P1V8MCP_CPU0_SKT_VSEN")
	)
	(arc
		(start 299.254926 -67.201034)
		(mid 299.54035 -67.284501)
		(end 299.748956 -67.496436)
		(width 0.0889)
		(layer "In2.Cu")
		(net "VSENSE_P1V8MCP_CPU0_SKT_VSEN")
	)
	(arc
		(start 294.955976 -63.734188)
		(mid 295.149826 -63.677838)
		(end 295.29151 -63.534036)
		(width 0.0889)
		(layer "In2.Cu")
		(net "VSENSE_P1V8MCP_CPU0_SKT_VSEN")
	)
	(arc
		(start 298.031916 -66.105786)
		(mid 298.029168 -66.501253)
		(end 298.36745 -66.705988)
		(width 0.0889)
		(layer "In2.Cu")
		(net "VSENSE_P1V8MCP_CPU0_SKT_VSEN")
	)
	(arc
		(start 293.57447 -64.52489)
		(mid 293.785183 -64.311811)
		(end 294.073326 -64.229488)
		(width 0.0889)
		(layer "In2.Cu")
		(net "VSENSE_P1V8MCP_CPU0_SKT_VSEN")
	)
	(arc
		(start 294.091106 -64.229488)
		(mid 294.288541 -64.174665)
		(end 294.43299 -64.029336)
		(width 0.0889)
		(layer "In2.Cu")
		(net "VSENSE_P1V8MCP_CPU0_SKT_VSEN")
	)
	(arc
		(start 291.034724 -65.955418)
		(mid 291.234469 -65.783424)
		(end 291.48913 -65.715388)
		(width 0.0889)
		(layer "In2.Cu")
		(net "VSENSE_P1V8MCP_CPU0_SKT_VSEN")
	)
	(arc
		(start 291.521896 -65.715388)
		(mid 291.715746 -65.659038)
		(end 291.85743 -65.515236)
		(width 0.0889)
		(layer "In2.Cu")
		(net "VSENSE_P1V8MCP_CPU0_SKT_VSEN")
	)
	(arc
		(start 300.106842 -67.696588)
		(mid 300.302181 -67.642744)
		(end 300.442376 -67.496436)
		(width 0.0889)
		(layer "In2.Cu")
		(net "VSENSE_P1V8MCP_CPU0_SKT_VSEN")
	)
	(arc
		(start 301.824644 -67.696588)
		(mid 302.01807 -67.640061)
		(end 302.159416 -67.496436)
		(width 0.0889)
		(layer "In2.Cu")
		(net "VSENSE_P1V8MCP_CPU0_SKT_VSEN")
	)
	(arc
		(start 299.748956 -67.496436)
		(mid 299.89549 -67.64298)
		(end 300.095666 -67.696588)
		(width 0.0889)
		(layer "In2.Cu")
		(net "VSENSE_P1V8MCP_CPU0_SKT_VSEN")
	)
	(arc
		(start 298.031916 -65.115186)
		(mid 297.978446 -65.310249)
		(end 298.02709 -65.5066)
		(width 0.0889)
		(layer "In2.Cu")
		(net "VSENSE_P1V8MCP_CPU0_SKT_VSEN")
	)
	(arc
		(start 296.31513 -63.534036)
		(mid 296.456813 -63.67784)
		(end 296.650664 -63.734188)
		(width 0.0889)
		(layer "In2.Cu")
		(net "VSENSE_P1V8MCP_CPU0_SKT_VSEN")
	)
	(arc
		(start 295.29151 -63.534036)
		(mid 295.500118 -63.322104)
		(end 295.78554 -63.238634)
		(width 0.0889)
		(layer "In2.Cu")
		(net "VSENSE_P1V8MCP_CPU0_SKT_VSEN")
	)
	(segment
		(start 290.93922 -66.305938)
		(end 291.51072 -66.305938)
		(width 0.127)
		(layer "F.Cu")
		(net "VSENSE_P1V8MCP_CPU0_SKT_VRTN")
	)
	(segment
		(start 330.864972 -39.99103)
		(end 330.77658 -39.99103)
		(width 0.127)
		(layer "F.Cu")
		(net "VSENSE_P1V8MCP_CPU0_SKT_VRTN")
	)
	(segment
		(start 330.77658 -39.99103)
		(end 330.176378 -40.591232)
		(width 0.127)
		(layer "F.Cu")
		(net "VSENSE_P1V8MCP_CPU0_SKT_VRTN")
	)
	(via
		(at 291.51072 -66.305938)
		(size 0.508)
		(drill 0.254)
		(layers "F.Cu" "B.Cu")
		(net "VSENSE_P1V8MCP_CPU0_SKT_VRTN")
	)
	(via
		(at 330.176378 -40.591232)
		(size 0.508)
		(drill 0.254)
		(layers "F.Cu" "B.Cu")
		(net "VSENSE_P1V8MCP_CPU0_SKT_VRTN")
	)
	(segment
		(start 307.37175 -66.203322)
		(end 307.37175 -66.203068)
		(width 0.127)
		(layer "In2.Cu")
		(net "VSENSE_P1V8MCP_CPU0_SKT_VRTN")
	)
	(segment
		(start 306.68087 -67.013582)
		(end 306.776374 -66.931286)
		(width 0.0889)
		(layer "In2.Cu")
		(net "VSENSE_P1V8MCP_CPU0_SKT_VRTN")
	)
	(segment
		(start 303.511966 -67.887088)
		(end 303.547526 -67.887088)
		(width 0.0889)
		(layer "In2.Cu")
		(net "VSENSE_P1V8MCP_CPU0_SKT_VRTN")
	)
	(segment
		(start 292.358064 -65.410334)
		(end 292.39083 -65.410334)
		(width 0.0889)
		(layer "In2.Cu")
		(net "VSENSE_P1V8MCP_CPU0_SKT_VRTN")
	)
	(segment
		(start 306.09413 -67.391534)
		(end 306.126896 -67.391534)
		(width 0.0889)
		(layer "In2.Cu")
		(net "VSENSE_P1V8MCP_CPU0_SKT_VRTN")
	)
	(segment
		(start 312.263028 -43.986196)
		(end 314.147454 -42.10177)
		(width 0.127)
		(layer "In2.Cu")
		(net "VSENSE_P1V8MCP_CPU0_SKT_VRTN")
	)
	(segment
		(start 296.64406 -63.924688)
		(end 296.66184 -63.924688)
		(width 0.0889)
		(layer "In2.Cu")
		(net "VSENSE_P1V8MCP_CPU0_SKT_VRTN")
	)
	(segment
		(start 307.00091 -66.631312)
		(end 307.001418 -66.63055)
		(width 0.0889)
		(layer "In2.Cu")
		(net "VSENSE_P1V8MCP_CPU0_SKT_VRTN")
	)
	(segment
		(start 307.37175 -66.203068)
		(end 307.594762 -65.941956)
		(width 0.127)
		(layer "In2.Cu")
		(net "VSENSE_P1V8MCP_CPU0_SKT_VRTN")
	)
	(segment
		(start 297.007788 -64.123824)
		(end 297.008296 -64.12484)
		(width 0.0889)
		(layer "In2.Cu")
		(net "VSENSE_P1V8MCP_CPU0_SKT_VRTN")
	)
	(segment
		(start 310.754776 -57.643776)
		(end 308.671976 -55.560976)
		(width 0.127)
		(layer "In2.Cu")
		(net "VSENSE_P1V8MCP_CPU0_SKT_VRTN")
	)
	(segment
		(start 299.215556 -67.391534)
		(end 299.248322 -67.391534)
		(width 0.0889)
		(layer "In2.Cu")
		(net "VSENSE_P1V8MCP_CPU0_SKT_VRTN")
	)
	(segment
		(start 329.6666 -41.268904)
		(end 329.6666 -41.10101)
		(width 0.127)
		(layer "In2.Cu")
		(net "VSENSE_P1V8MCP_CPU0_SKT_VRTN")
	)
	(segment
		(start 297.860466 -65.599818)
		(end 297.866816 -65.610486)
		(width 0.0889)
		(layer "In2.Cu")
		(net "VSENSE_P1V8MCP_CPU0_SKT_VRTN")
	)
	(segment
		(start 306.776374 -66.931286)
		(end 307.00091 -66.631312)
		(width 0.0889)
		(layer "In2.Cu")
		(net "VSENSE_P1V8MCP_CPU0_SKT_VRTN")
	)
	(segment
		(start 291.495734 -65.905888)
		(end 291.5285 -65.905888)
		(width 0.0889)
		(layer "In2.Cu")
		(net "VSENSE_P1V8MCP_CPU0_SKT_VRTN")
	)
	(segment
		(start 329.417172 -41.518332)
		(end 329.6666 -41.268904)
		(width 0.127)
		(layer "In2.Cu")
		(net "VSENSE_P1V8MCP_CPU0_SKT_VRTN")
	)
	(segment
		(start 307.594762 -65.941956)
		(end 308.98211 -64.553592)
		(width 0.127)
		(layer "In2.Cu")
		(net "VSENSE_P1V8MCP_CPU0_SKT_VRTN")
	)
	(segment
		(start 298.360846 -66.896488)
		(end 298.393612 -66.896488)
		(width 0.0889)
		(layer "In2.Cu")
		(net "VSENSE_P1V8MCP_CPU0_SKT_VRTN")
	)
	(segment
		(start 297.000168 -64.110616)
		(end 297.007788 -64.123824)
		(width 0.0889)
		(layer "In2.Cu")
		(net "VSENSE_P1V8MCP_CPU0_SKT_VRTN")
	)
	(segment
		(start 324.042278 -41.518332)
		(end 329.417172 -41.518332)
		(width 0.127)
		(layer "In2.Cu")
		(net "VSENSE_P1V8MCP_CPU0_SKT_VRTN")
	)
	(segment
		(start 307.027326 -66.626994)
		(end 307.040534 -66.609214)
		(width 0.0889)
		(layer "In2.Cu")
		(net "VSENSE_P1V8MCP_CPU0_SKT_VRTN")
	)
	(segment
		(start 297.866816 -65.610486)
		(end 297.871642 -65.619122)
		(width 0.0889)
		(layer "In2.Cu")
		(net "VSENSE_P1V8MCP_CPU0_SKT_VRTN")
	)
	(segment
		(start 297.495214 -64.419734)
		(end 297.531282 -64.419734)
		(width 0.0889)
		(layer "In2.Cu")
		(net "VSENSE_P1V8MCP_CPU0_SKT_VRTN")
	)
	(segment
		(start 323.45884 -42.10177)
		(end 324.042278 -41.518332)
		(width 0.127)
		(layer "In2.Cu")
		(net "VSENSE_P1V8MCP_CPU0_SKT_VRTN")
	)
	(segment
		(start 301.794926 -67.887088)
		(end 301.830486 -67.887088)
		(width 0.0889)
		(layer "In2.Cu")
		(net "VSENSE_P1V8MCP_CPU0_SKT_VRTN")
	)
	(segment
		(start 291.51072 -66.305938)
		(end 291.217604 -66.136774)
		(width 0.0889)
		(layer "In2.Cu")
		(net "VSENSE_P1V8MCP_CPU0_SKT_VRTN")
	)
	(segment
		(start 310.198516 -43.986196)
		(end 312.263028 -43.986196)
		(width 0.127)
		(layer "In2.Cu")
		(net "VSENSE_P1V8MCP_CPU0_SKT_VRTN")
	)
	(segment
		(start 291.217604 -66.136774)
		(end 291.196522 -66.058034)
		(width 0.0889)
		(layer "In2.Cu")
		(net "VSENSE_P1V8MCP_CPU0_SKT_VRTN")
	)
	(segment
		(start 294.929814 -63.924688)
		(end 294.96258 -63.924688)
		(width 0.0889)
		(layer "In2.Cu")
		(net "VSENSE_P1V8MCP_CPU0_SKT_VRTN")
	)
	(segment
		(start 308.671976 -45.512736)
		(end 310.198516 -43.986196)
		(width 0.127)
		(layer "In2.Cu")
		(net "VSENSE_P1V8MCP_CPU0_SKT_VRTN")
	)
	(segment
		(start 300.095666 -67.887088)
		(end 300.113446 -67.887088)
		(width 0.0889)
		(layer "In2.Cu")
		(net "VSENSE_P1V8MCP_CPU0_SKT_VRTN")
	)
	(segment
		(start 307.040534 -66.609214)
		(end 307.148738 -66.464942)
		(width 0.127)
		(layer "In2.Cu")
		(net "VSENSE_P1V8MCP_CPU0_SKT_VRTN")
	)
	(segment
		(start 314.147454 -42.10177)
		(end 323.45884 -42.10177)
		(width 0.127)
		(layer "In2.Cu")
		(net "VSENSE_P1V8MCP_CPU0_SKT_VRTN")
	)
	(segment
		(start 293.212774 -64.915288)
		(end 293.22776 -64.915288)
		(width 0.0889)
		(layer "In2.Cu")
		(net "VSENSE_P1V8MCP_CPU0_SKT_VRTN")
	)
	(segment
		(start 310.754776 -62.299342)
		(end 310.754776 -57.643776)
		(width 0.127)
		(layer "In2.Cu")
		(net "VSENSE_P1V8MCP_CPU0_SKT_VRTN")
	)
	(segment
		(start 294.081454 -64.419988)
		(end 294.099234 -64.419988)
		(width 0.0889)
		(layer "In2.Cu")
		(net "VSENSE_P1V8MCP_CPU0_SKT_VRTN")
	)
	(segment
		(start 305.229006 -67.887088)
		(end 305.246786 -67.887088)
		(width 0.0889)
		(layer "In2.Cu")
		(net "VSENSE_P1V8MCP_CPU0_SKT_VRTN")
	)
	(segment
		(start 308.671976 -55.560976)
		(end 308.671976 -45.512736)
		(width 0.127)
		(layer "In2.Cu")
		(net "VSENSE_P1V8MCP_CPU0_SKT_VRTN")
	)
	(segment
		(start 307.148738 -66.464942)
		(end 307.37175 -66.203322)
		(width 0.127)
		(layer "In2.Cu")
		(net "VSENSE_P1V8MCP_CPU0_SKT_VRTN")
	)
	(segment
		(start 307.001418 -66.63055)
		(end 307.027326 -66.626994)
		(width 0.0889)
		(layer "In2.Cu")
		(net "VSENSE_P1V8MCP_CPU0_SKT_VRTN")
	)
	(segment
		(start 329.6666 -41.10101)
		(end 330.176378 -40.591232)
		(width 0.127)
		(layer "In2.Cu")
		(net "VSENSE_P1V8MCP_CPU0_SKT_VRTN")
	)
	(segment
		(start 308.98211 -64.553592)
		(end 310.754776 -62.299342)
		(width 0.127)
		(layer "In2.Cu")
		(net "VSENSE_P1V8MCP_CPU0_SKT_VRTN")
	)
	(arc
		(start 296.66184 -63.924688)
		(mid 296.854868 -63.97423)
		(end 297.000168 -64.110616)
		(width 0.0889)
		(layer "In2.Cu")
		(net "VSENSE_P1V8MCP_CPU0_SKT_VRTN")
	)
	(arc
		(start 305.246786 -67.887088)
		(mid 305.542254 -67.807936)
		(end 305.758596 -67.591686)
		(width 0.0889)
		(layer "In2.Cu")
		(net "VSENSE_P1V8MCP_CPU0_SKT_VRTN")
	)
	(arc
		(start 292.88105 -65.115186)
		(mid 293.021129 -64.97245)
		(end 293.212774 -64.915288)
		(width 0.0889)
		(layer "In2.Cu")
		(net "VSENSE_P1V8MCP_CPU0_SKT_VRTN")
	)
	(arc
		(start 300.607476 -67.591686)
		(mid 300.748832 -67.448077)
		(end 300.942248 -67.391534)
		(width 0.0889)
		(layer "In2.Cu")
		(net "VSENSE_P1V8MCP_CPU0_SKT_VRTN")
	)
	(arc
		(start 292.02253 -65.610486)
		(mid 292.164213 -65.466682)
		(end 292.358064 -65.410334)
		(width 0.0889)
		(layer "In2.Cu")
		(net "VSENSE_P1V8MCP_CPU0_SKT_VRTN")
	)
	(arc
		(start 296.15003 -63.629286)
		(mid 296.358638 -63.841218)
		(end 296.64406 -63.924688)
		(width 0.0889)
		(layer "In2.Cu")
		(net "VSENSE_P1V8MCP_CPU0_SKT_VRTN")
	)
	(arc
		(start 291.196522 -66.058034)
		(mid 291.329403 -65.949051)
		(end 291.495734 -65.905888)
		(width 0.0889)
		(layer "In2.Cu")
		(net "VSENSE_P1V8MCP_CPU0_SKT_VRTN")
	)
	(arc
		(start 299.583856 -67.591686)
		(mid 299.800193 -67.807945)
		(end 300.095666 -67.887088)
		(width 0.0889)
		(layer "In2.Cu")
		(net "VSENSE_P1V8MCP_CPU0_SKT_VRTN")
	)
	(arc
		(start 297.866816 -66.010536)
		(mid 297.862487 -66.593708)
		(end 298.360846 -66.896488)
		(width 0.0889)
		(layer "In2.Cu")
		(net "VSENSE_P1V8MCP_CPU0_SKT_VRTN")
	)
	(arc
		(start 302.683164 -67.391534)
		(mid 302.87659 -67.448061)
		(end 303.017936 -67.591686)
		(width 0.0889)
		(layer "In2.Cu")
		(net "VSENSE_P1V8MCP_CPU0_SKT_VRTN")
	)
	(arc
		(start 298.393612 -66.896488)
		(mid 298.585254 -66.953654)
		(end 298.725336 -67.096386)
		(width 0.0889)
		(layer "In2.Cu")
		(net "VSENSE_P1V8MCP_CPU0_SKT_VRTN")
	)
	(arc
		(start 293.22776 -64.915288)
		(mid 293.523165 -64.836212)
		(end 293.73957 -64.62014)
		(width 0.0889)
		(layer "In2.Cu")
		(net "VSENSE_P1V8MCP_CPU0_SKT_VRTN")
	)
	(arc
		(start 299.248322 -67.391534)
		(mid 299.442172 -67.447884)
		(end 299.583856 -67.591686)
		(width 0.0889)
		(layer "In2.Cu")
		(net "VSENSE_P1V8MCP_CPU0_SKT_VRTN")
	)
	(arc
		(start 305.758596 -67.591686)
		(mid 305.900279 -67.447882)
		(end 306.09413 -67.391534)
		(width 0.0889)
		(layer "In2.Cu")
		(net "VSENSE_P1V8MCP_CPU0_SKT_VRTN")
	)
	(arc
		(start 304.041556 -67.591686)
		(mid 304.182912 -67.448077)
		(end 304.376328 -67.391534)
		(width 0.0889)
		(layer "In2.Cu")
		(net "VSENSE_P1V8MCP_CPU0_SKT_VRTN")
	)
	(arc
		(start 298.725336 -67.096386)
		(mid 298.93234 -67.30725)
		(end 299.215556 -67.391534)
		(width 0.0889)
		(layer "In2.Cu")
		(net "VSENSE_P1V8MCP_CPU0_SKT_VRTN")
	)
	(arc
		(start 294.96258 -63.924688)
		(mid 295.248004 -63.841221)
		(end 295.45661 -63.629286)
		(width 0.0889)
		(layer "In2.Cu")
		(net "VSENSE_P1V8MCP_CPU0_SKT_VRTN")
	)
	(arc
		(start 292.39083 -65.410334)
		(mid 292.674047 -65.326053)
		(end 292.88105 -65.115186)
		(width 0.0889)
		(layer "In2.Cu")
		(net "VSENSE_P1V8MCP_CPU0_SKT_VRTN")
	)
	(arc
		(start 306.617116 -67.096386)
		(mid 306.646282 -67.052897)
		(end 306.68087 -67.013582)
		(width 0.0889)
		(layer "In2.Cu")
		(net "VSENSE_P1V8MCP_CPU0_SKT_VRTN")
	)
	(arc
		(start 294.099234 -64.419988)
		(mid 294.387379 -64.337669)
		(end 294.59809 -64.124586)
		(width 0.0889)
		(layer "In2.Cu")
		(net "VSENSE_P1V8MCP_CPU0_SKT_VRTN")
	)
	(arc
		(start 295.45661 -63.629286)
		(mid 295.597966 -63.485677)
		(end 295.791382 -63.429134)
		(width 0.0889)
		(layer "In2.Cu")
		(net "VSENSE_P1V8MCP_CPU0_SKT_VRTN")
	)
	(arc
		(start 306.126896 -67.391534)
		(mid 306.410113 -67.307253)
		(end 306.617116 -67.096386)
		(width 0.0889)
		(layer "In2.Cu")
		(net "VSENSE_P1V8MCP_CPU0_SKT_VRTN")
	)
	(arc
		(start 304.734976 -67.591686)
		(mid 304.943584 -67.803618)
		(end 305.229006 -67.887088)
		(width 0.0889)
		(layer "In2.Cu")
		(net "VSENSE_P1V8MCP_CPU0_SKT_VRTN")
	)
	(arc
		(start 295.815258 -63.429134)
		(mid 296.008684 -63.485661)
		(end 296.15003 -63.629286)
		(width 0.0889)
		(layer "In2.Cu")
		(net "VSENSE_P1V8MCP_CPU0_SKT_VRTN")
	)
	(arc
		(start 303.017936 -67.591686)
		(mid 303.226544 -67.803618)
		(end 303.511966 -67.887088)
		(width 0.0889)
		(layer "In2.Cu")
		(net "VSENSE_P1V8MCP_CPU0_SKT_VRTN")
	)
	(arc
		(start 295.791382 -63.429134)
		(mid 295.80332 -63.428956)
		(end 295.815258 -63.429134)
		(width 0.0889)
		(layer "In2.Cu")
		(net "VSENSE_P1V8MCP_CPU0_SKT_VRTN")
	)
	(arc
		(start 297.531282 -64.419734)
		(mid 297.869451 -64.624532)
		(end 297.866816 -65.019936)
		(width 0.0889)
		(layer "In2.Cu")
		(net "VSENSE_P1V8MCP_CPU0_SKT_VRTN")
	)
	(arc
		(start 297.866816 -65.019936)
		(mid 297.787594 -65.309054)
		(end 297.860466 -65.599818)
		(width 0.0889)
		(layer "In2.Cu")
		(net "VSENSE_P1V8MCP_CPU0_SKT_VRTN")
	)
	(arc
		(start 303.547526 -67.887088)
		(mid 303.83295 -67.803621)
		(end 304.041556 -67.591686)
		(width 0.0889)
		(layer "In2.Cu")
		(net "VSENSE_P1V8MCP_CPU0_SKT_VRTN")
	)
	(arc
		(start 291.5285 -65.905888)
		(mid 291.813924 -65.822421)
		(end 292.02253 -65.610486)
		(width 0.0889)
		(layer "In2.Cu")
		(net "VSENSE_P1V8MCP_CPU0_SKT_VRTN")
	)
	(arc
		(start 297.871642 -65.619122)
		(mid 297.920397 -65.815474)
		(end 297.866816 -66.010536)
		(width 0.0889)
		(layer "In2.Cu")
		(net "VSENSE_P1V8MCP_CPU0_SKT_VRTN")
	)
	(arc
		(start 301.830486 -67.887088)
		(mid 302.11591 -67.803621)
		(end 302.324516 -67.591686)
		(width 0.0889)
		(layer "In2.Cu")
		(net "VSENSE_P1V8MCP_CPU0_SKT_VRTN")
	)
	(arc
		(start 297.008296 -64.12484)
		(mid 297.213917 -64.334763)
		(end 297.495214 -64.419734)
		(width 0.0889)
		(layer "In2.Cu")
		(net "VSENSE_P1V8MCP_CPU0_SKT_VRTN")
	)
	(arc
		(start 300.942248 -67.391534)
		(mid 300.954186 -67.391356)
		(end 300.966124 -67.391534)
		(width 0.0889)
		(layer "In2.Cu")
		(net "VSENSE_P1V8MCP_CPU0_SKT_VRTN")
	)
	(arc
		(start 304.376328 -67.391534)
		(mid 304.388266 -67.391356)
		(end 304.400204 -67.391534)
		(width 0.0889)
		(layer "In2.Cu")
		(net "VSENSE_P1V8MCP_CPU0_SKT_VRTN")
	)
	(arc
		(start 304.400204 -67.391534)
		(mid 304.59363 -67.448061)
		(end 304.734976 -67.591686)
		(width 0.0889)
		(layer "In2.Cu")
		(net "VSENSE_P1V8MCP_CPU0_SKT_VRTN")
	)
	(arc
		(start 293.73957 -64.62014)
		(mid 293.884018 -64.474809)
		(end 294.081454 -64.419988)
		(width 0.0889)
		(layer "In2.Cu")
		(net "VSENSE_P1V8MCP_CPU0_SKT_VRTN")
	)
	(arc
		(start 302.324516 -67.591686)
		(mid 302.465872 -67.448077)
		(end 302.659288 -67.391534)
		(width 0.0889)
		(layer "In2.Cu")
		(net "VSENSE_P1V8MCP_CPU0_SKT_VRTN")
	)
	(arc
		(start 300.113446 -67.887088)
		(mid 300.401255 -67.807607)
		(end 300.607476 -67.591686)
		(width 0.0889)
		(layer "In2.Cu")
		(net "VSENSE_P1V8MCP_CPU0_SKT_VRTN")
	)
	(arc
		(start 294.59809 -64.124586)
		(mid 294.738169 -63.98185)
		(end 294.929814 -63.924688)
		(width 0.0889)
		(layer "In2.Cu")
		(net "VSENSE_P1V8MCP_CPU0_SKT_VRTN")
	)
	(arc
		(start 302.659288 -67.391534)
		(mid 302.671226 -67.391356)
		(end 302.683164 -67.391534)
		(width 0.0889)
		(layer "In2.Cu")
		(net "VSENSE_P1V8MCP_CPU0_SKT_VRTN")
	)
	(arc
		(start 301.300896 -67.591686)
		(mid 301.509504 -67.803618)
		(end 301.794926 -67.887088)
		(width 0.0889)
		(layer "In2.Cu")
		(net "VSENSE_P1V8MCP_CPU0_SKT_VRTN")
	)
	(arc
		(start 300.966124 -67.391534)
		(mid 301.15955 -67.448061)
		(end 301.300896 -67.591686)
		(width 0.0889)
		(layer "In2.Cu")
		(net "VSENSE_P1V8MCP_CPU0_SKT_VRTN")
	)
	(segment
		(start 176.045114 -109.20095)
		(end 176.045114 -107.723686)
		(width 0.10795)
		(layer "F.Cu")
		(net "VR_PVCCMCP_CPU1_XADDR2")
	)
	(segment
		(start 176.0728 -107.696)
		(end 176.0728 -106.74985)
		(width 0.10795)
		(layer "F.Cu")
		(net "VR_PVCCMCP_CPU1_XADDR2")
	)
	(segment
		(start 176.045114 -107.723686)
		(end 176.0728 -107.696)
		(width 0.10795)
		(layer "F.Cu")
		(net "VR_PVCCMCP_CPU1_XADDR2")
	)
	(segment
		(start 341.0204 -106.4514)
		(end 340.995 -106.426)
		(width 0.10795)
		(layer "F.Cu")
		(net "VR_PVCCMCP_CPU0_XADDR2")
	)
	(segment
		(start 341.0204 -109.20095)
		(end 341.0204 -106.4514)
		(width 0.10795)
		(layer "F.Cu")
		(net "VR_PVCCMCP_CPU0_XADDR2")
	)
	(segment
		(start 341.024972 -109.20095)
		(end 341.0204 -109.20095)
		(width 0.10795)
		(layer "F.Cu")
		(net "VR_PVCCMCP_CPU0_XADDR2")
	)
	(segment
		(start 341.024972 -110.47095)
		(end 341.00135 -110.47095)
		(width 0.10795)
		(layer "F.Cu")
		(net "VR_PVCCIOMCP_CPU0_XADDR1")
	)
	(segment
		(start 341.00135 -110.47095)
		(end 340.3854 -109.855)
		(width 0.10795)
		(layer "F.Cu")
		(net "VR_PVCCIOMCP_CPU0_XADDR1")
	)
	(via
		(at 338.34705 -111.4044)
		(size 0.6604)
		(drill 0.3302)
		(layers "F.Cu" "B.Cu")
		(net "VR_PVCCIOMCP_CPU0_XADDR1")
	)
	(via
		(at 340.3854 -109.855)
		(size 0.508)
		(drill 0.254)
		(layers "F.Cu" "B.Cu")
		(net "VR_PVCCIOMCP_CPU0_XADDR1")
	)
	(segment
		(start 339.7504 -111.4044)
		(end 340.106 -111.4044)
		(width 0.1143)
		(layer "B.Cu")
		(net "VR_PVCCIOMCP_CPU0_XADDR1")
	)
	(segment
		(start 340.106 -111.4044)
		(end 340.3854 -111.125)
		(width 0.1143)
		(layer "B.Cu")
		(net "VR_PVCCIOMCP_CPU0_XADDR1")
	)
	(segment
		(start 340.3854 -111.125)
		(end 340.3854 -109.855)
		(width 0.1143)
		(layer "B.Cu")
		(net "VR_PVCCIOMCP_CPU0_XADDR1")
	)
	(segment
		(start 338.34705 -111.4044)
		(end 339.7504 -111.4044)
		(width 0.1143)
		(layer "B.Cu")
		(net "VR_PVCCIOMCP_CPU0_XADDR1")
	)
	(segment
		(start 193.4464 -63.25108)
		(end 192.247266 -63.25108)
		(width 0.10795)
		(layer "F.Cu")
		(net "VR_PVCCIN_CPU0_PH2_OCSET")
	)
	(segment
		(start 193.82232 -63.627)
		(end 194.817746 -63.627)
		(width 0.1016)
		(layer "F.Cu")
		(net "VR_PVCCIN_CPU0_PH2_OCSET")
	)
	(segment
		(start 195.574412 -64.06769)
		(end 196.030342 -64.06769)
		(width 0.1016)
		(layer "F.Cu")
		(net "VR_PVCCIN_CPU0_PH2_OCSET")
	)
	(segment
		(start 193.4464 -63.25108)
		(end 193.82232 -63.627)
		(width 0.1016)
		(layer "F.Cu")
		(net "VR_PVCCIN_CPU0_PH2_OCSET")
	)
	(segment
		(start 194.817746 -63.627)
		(end 194.992752 -63.802006)
		(width 0.1016)
		(layer "F.Cu")
		(net "VR_PVCCIN_CPU0_PH2_OCSET")
	)
	(segment
		(start 195.308728 -63.802006)
		(end 195.574412 -64.06769)
		(width 0.1016)
		(layer "F.Cu")
		(net "VR_PVCCIN_CPU0_PH2_OCSET")
	)
	(segment
		(start 194.992752 -63.802006)
		(end 195.308728 -63.802006)
		(width 0.1016)
		(layer "F.Cu")
		(net "VR_PVCCIN_CPU0_PH2_OCSET")
	)
	(segment
		(start 192.247266 -63.25108)
		(end 192.186306 -63.19012)
		(width 0.10795)
		(layer "F.Cu")
		(net "VR_PVCCIN_CPU0_PH2_OCSET")
	)
	(via
		(at 192.186306 -63.19012)
		(size 0.762)
		(drill 0.381)
		(layers "F.Cu" "B.Cu")
		(net "VR_PVCCIN_CPU0_PH2_OCSET")
	)
	(segment
		(start 398.2339 -153.197052)
		(end 398.561052 -153.197052)
		(width 0.1016)
		(layer "F.Cu")
		(net "VID_PCH_CORE_PVNN_AUX_VID_1")
	)
	(segment
		(start 395.66215 -96.9772)
		(end 396.15745 -96.747076)
		(width 0.10795)
		(layer "F.Cu")
		(net "VID_PCH_CORE_PVNN_AUX_VID_1")
	)
	(segment
		(start 398.561052 -153.197052)
		(end 398.6022 -153.2382)
		(width 0.1016)
		(layer "F.Cu")
		(net "VID_PCH_CORE_PVNN_AUX_VID_1")
	)
	(segment
		(start 398.6022 -153.2382)
		(end 399.17624 -153.2382)
		(width 0.1016)
		(layer "F.Cu")
		(net "VID_PCH_CORE_PVNN_AUX_VID_1")
	)
	(segment
		(start 399.17624 -153.2382)
		(end 399.60804 -152.8064)
		(width 0.1016)
		(layer "F.Cu")
		(net "VID_PCH_CORE_PVNN_AUX_VID_1")
	)
	(via
		(at 414.0962 -100.4062)
		(size 0.508)
		(drill 0.254)
		(layers "F.Cu" "B.Cu")
		(net "VID_PCH_CORE_PVNN_AUX_VID_1")
	)
	(via
		(at 399.60804 -152.8064)
		(size 0.508)
		(drill 0.254)
		(layers "F.Cu" "B.Cu")
		(net "VID_PCH_CORE_PVNN_AUX_VID_1")
	)
	(via
		(at 447.563748 -149.74697)
		(size 0.508)
		(drill 0.254)
		(layers "F.Cu" "B.Cu")
		(net "VID_PCH_CORE_PVNN_AUX_VID_1")
	)
	(via
		(at 416.793934 -153.754836)
		(size 0.508)
		(drill 0.254)
		(layers "F.Cu" "B.Cu")
		(net "VID_PCH_CORE_PVNN_AUX_VID_1")
	)
	(via
		(at 414.80105 -119.424196)
		(size 0.508)
		(drill 0.254)
		(layers "F.Cu" "B.Cu")
		(net "VID_PCH_CORE_PVNN_AUX_VID_1")
	)
	(via
		(at 396.15745 -96.747076)
		(size 0.508)
		(drill 0.254)
		(layers "F.Cu" "B.Cu")
		(net "VID_PCH_CORE_PVNN_AUX_VID_1")
	)
	(segment
		(start 414.10382 -103.990394)
		(end 414.67786 -104.564434)
		(width 0.10795)
		(layer "B.Cu")
		(net "VID_PCH_CORE_PVNN_AUX_VID_1")
	)
	(segment
		(start 414.0962 -100.4062)
		(end 414.0962 -100.6348)
		(width 0.10795)
		(layer "B.Cu")
		(net "VID_PCH_CORE_PVNN_AUX_VID_1")
	)
	(segment
		(start 415.623502 -106.652314)
		(end 414.783016 -107.4928)
		(width 0.10795)
		(layer "B.Cu")
		(net "VID_PCH_CORE_PVNN_AUX_VID_1")
	)
	(segment
		(start 400.591782 -152.8064)
		(end 401.074382 -153.289)
		(width 0.10795)
		(layer "B.Cu")
		(net "VID_PCH_CORE_PVNN_AUX_VID_1")
	)
	(segment
		(start 413.086804 -114.45875)
		(end 413.4612 -114.833146)
		(width 0.10795)
		(layer "B.Cu")
		(net "VID_PCH_CORE_PVNN_AUX_VID_1")
	)
	(segment
		(start 414.677098 -104.565196)
		(end 414.677098 -105.161842)
		(width 0.10795)
		(layer "B.Cu")
		(net "VID_PCH_CORE_PVNN_AUX_VID_1")
	)
	(segment
		(start 413.65424 -103.990394)
		(end 414.10382 -103.990394)
		(width 0.10795)
		(layer "B.Cu")
		(net "VID_PCH_CORE_PVNN_AUX_VID_1")
	)
	(segment
		(start 413.086804 -101.644196)
		(end 413.086804 -103.422958)
		(width 0.10795)
		(layer "B.Cu")
		(net "VID_PCH_CORE_PVNN_AUX_VID_1")
	)
	(segment
		(start 413.4612 -118.084346)
		(end 414.80105 -119.424196)
		(width 0.10795)
		(layer "B.Cu")
		(net "VID_PCH_CORE_PVNN_AUX_VID_1")
	)
	(segment
		(start 414.0962 -100.6348)
		(end 413.086804 -101.644196)
		(width 0.10795)
		(layer "B.Cu")
		(net "VID_PCH_CORE_PVNN_AUX_VID_1")
	)
	(segment
		(start 413.086804 -103.422958)
		(end 413.65424 -103.990394)
		(width 0.10795)
		(layer "B.Cu")
		(net "VID_PCH_CORE_PVNN_AUX_VID_1")
	)
	(segment
		(start 414.783016 -107.4928)
		(end 414.517586 -107.4928)
		(width 0.10795)
		(layer "B.Cu")
		(net "VID_PCH_CORE_PVNN_AUX_VID_1")
	)
	(segment
		(start 413.086804 -108.923582)
		(end 413.086804 -114.45875)
		(width 0.10795)
		(layer "B.Cu")
		(net "VID_PCH_CORE_PVNN_AUX_VID_1")
	)
	(segment
		(start 414.67786 -104.564434)
		(end 414.677098 -104.565196)
		(width 0.10795)
		(layer "B.Cu")
		(net "VID_PCH_CORE_PVNN_AUX_VID_1")
	)
	(segment
		(start 414.677098 -105.161842)
		(end 415.623502 -106.108246)
		(width 0.10795)
		(layer "B.Cu")
		(net "VID_PCH_CORE_PVNN_AUX_VID_1")
	)
	(segment
		(start 415.623502 -106.108246)
		(end 415.623502 -106.652314)
		(width 0.10795)
		(layer "B.Cu")
		(net "VID_PCH_CORE_PVNN_AUX_VID_1")
	)
	(segment
		(start 414.517586 -107.4928)
		(end 413.086804 -108.923582)
		(width 0.10795)
		(layer "B.Cu")
		(net "VID_PCH_CORE_PVNN_AUX_VID_1")
	)
	(segment
		(start 399.60804 -152.8064)
		(end 400.591782 -152.8064)
		(width 0.10795)
		(layer "B.Cu")
		(net "VID_PCH_CORE_PVNN_AUX_VID_1")
	)
	(segment
		(start 413.4612 -114.833146)
		(end 413.4612 -118.084346)
		(width 0.10795)
		(layer "B.Cu")
		(net "VID_PCH_CORE_PVNN_AUX_VID_1")
	)
	(segment
		(start 401.074382 -153.289)
		(end 401.574 -153.289)
		(width 0.10795)
		(layer "B.Cu")
		(net "VID_PCH_CORE_PVNN_AUX_VID_1")
	)
	(segment
		(start 447.563748 -149.74697)
		(end 447.500756 -149.809962)
		(width 0.089408)
		(layer "In2.Cu")
		(net "VID_PCH_CORE_PVNN_AUX_VID_1")
	)
	(segment
		(start 442.040264 -146.534632)
		(end 441.532264 -146.534632)
		(width 0.089408)
		(layer "In2.Cu")
		(net "VID_PCH_CORE_PVNN_AUX_VID_1")
	)
	(segment
		(start 447.500756 -149.809962)
		(end 445.315594 -149.809962)
		(width 0.089408)
		(layer "In2.Cu")
		(net "VID_PCH_CORE_PVNN_AUX_VID_1")
	)
	(segment
		(start 431.051208 -144.870424)
		(end 430.026064 -145.895568)
		(width 0.089408)
		(layer "In2.Cu")
		(net "VID_PCH_CORE_PVNN_AUX_VID_1")
	)
	(segment
		(start 432.616102 -141.654784)
		(end 431.051208 -143.219678)
		(width 0.089408)
		(layer "In2.Cu")
		(net "VID_PCH_CORE_PVNN_AUX_VID_1")
	)
	(segment
		(start 445.315594 -149.809962)
		(end 442.040264 -146.534632)
		(width 0.089408)
		(layer "In2.Cu")
		(net "VID_PCH_CORE_PVNN_AUX_VID_1")
	)
	(segment
		(start 420.291768 -148.213064)
		(end 420.291768 -152.74798)
		(width 0.089408)
		(layer "In2.Cu")
		(net "VID_PCH_CORE_PVNN_AUX_VID_1")
	)
	(segment
		(start 438.216294 -145.940018)
		(end 433.93106 -141.654784)
		(width 0.089408)
		(layer "In2.Cu")
		(net "VID_PCH_CORE_PVNN_AUX_VID_1")
	)
	(segment
		(start 430.026064 -145.895568)
		(end 422.609264 -145.895568)
		(width 0.089408)
		(layer "In2.Cu")
		(net "VID_PCH_CORE_PVNN_AUX_VID_1")
	)
	(segment
		(start 433.93106 -141.654784)
		(end 432.616102 -141.654784)
		(width 0.089408)
		(layer "In2.Cu")
		(net "VID_PCH_CORE_PVNN_AUX_VID_1")
	)
	(segment
		(start 431.051208 -143.219678)
		(end 431.051208 -144.870424)
		(width 0.089408)
		(layer "In2.Cu")
		(net "VID_PCH_CORE_PVNN_AUX_VID_1")
	)
	(segment
		(start 422.609264 -145.895568)
		(end 420.291768 -148.213064)
		(width 0.089408)
		(layer "In2.Cu")
		(net "VID_PCH_CORE_PVNN_AUX_VID_1")
	)
	(segment
		(start 420.291768 -152.74798)
		(end 419.93439 -153.105358)
		(width 0.089408)
		(layer "In2.Cu")
		(net "VID_PCH_CORE_PVNN_AUX_VID_1")
	)
	(segment
		(start 417.443412 -153.105358)
		(end 416.793934 -153.754836)
		(width 0.089408)
		(layer "In2.Cu")
		(net "VID_PCH_CORE_PVNN_AUX_VID_1")
	)
	(segment
		(start 441.532264 -146.534632)
		(end 440.93765 -145.940018)
		(width 0.089408)
		(layer "In2.Cu")
		(net "VID_PCH_CORE_PVNN_AUX_VID_1")
	)
	(segment
		(start 419.93439 -153.105358)
		(end 417.443412 -153.105358)
		(width 0.089408)
		(layer "In2.Cu")
		(net "VID_PCH_CORE_PVNN_AUX_VID_1")
	)
	(segment
		(start 440.93765 -145.940018)
		(end 438.216294 -145.940018)
		(width 0.089408)
		(layer "In2.Cu")
		(net "VID_PCH_CORE_PVNN_AUX_VID_1")
	)
	(segment
		(start 401.94738 -97.70364)
		(end 409.08732 -97.70364)
		(width 0.089408)
		(layer "In4.Cu")
		(net "VID_PCH_CORE_PVNN_AUX_VID_1")
	)
	(segment
		(start 409.33878 -97.9551)
		(end 409.33878 -99.68738)
		(width 0.089408)
		(layer "In4.Cu")
		(net "VID_PCH_CORE_PVNN_AUX_VID_1")
	)
	(segment
		(start 412.2166 -99.949)
		(end 412.6738 -100.4062)
		(width 0.089408)
		(layer "In4.Cu")
		(net "VID_PCH_CORE_PVNN_AUX_VID_1")
	)
	(segment
		(start 412.6738 -100.4062)
		(end 414.0962 -100.4062)
		(width 0.089408)
		(layer "In4.Cu")
		(net "VID_PCH_CORE_PVNN_AUX_VID_1")
	)
	(segment
		(start 396.487396 -95.489776)
		(end 399.733516 -95.489776)
		(width 0.089408)
		(layer "In4.Cu")
		(net "VID_PCH_CORE_PVNN_AUX_VID_1")
	)
	(segment
		(start 409.08732 -97.70364)
		(end 409.33878 -97.9551)
		(width 0.089408)
		(layer "In4.Cu")
		(net "VID_PCH_CORE_PVNN_AUX_VID_1")
	)
	(segment
		(start 396.15745 -95.819722)
		(end 396.487396 -95.489776)
		(width 0.089408)
		(layer "In4.Cu")
		(net "VID_PCH_CORE_PVNN_AUX_VID_1")
	)
	(segment
		(start 396.15745 -96.747076)
		(end 396.15745 -95.819722)
		(width 0.089408)
		(layer "In4.Cu")
		(net "VID_PCH_CORE_PVNN_AUX_VID_1")
	)
	(segment
		(start 409.33878 -99.68738)
		(end 409.6004 -99.949)
		(width 0.089408)
		(layer "In4.Cu")
		(net "VID_PCH_CORE_PVNN_AUX_VID_1")
	)
	(segment
		(start 399.733516 -95.489776)
		(end 401.94738 -97.70364)
		(width 0.089408)
		(layer "In4.Cu")
		(net "VID_PCH_CORE_PVNN_AUX_VID_1")
	)
	(segment
		(start 409.6004 -99.949)
		(end 412.2166 -99.949)
		(width 0.089408)
		(layer "In4.Cu")
		(net "VID_PCH_CORE_PVNN_AUX_VID_1")
	)
	(segment
		(start 438.572656 -152.343104)
		(end 444.392304 -152.343104)
		(width 0.089408)
		(layer "In9.Cu")
		(net "VID_PCH_CORE_PVNN_AUX_VID_1")
	)
	(segment
		(start 426.868336 -132.126482)
		(end 429.662336 -134.920482)
		(width 0.089408)
		(layer "In9.Cu")
		(net "VID_PCH_CORE_PVNN_AUX_VID_1")
	)
	(segment
		(start 424.29811 -132.126482)
		(end 426.868336 -132.126482)
		(width 0.089408)
		(layer "In9.Cu")
		(net "VID_PCH_CORE_PVNN_AUX_VID_1")
	)
	(segment
		(start 418.466778 -126.29515)
		(end 424.29811 -132.126482)
		(width 0.089408)
		(layer "In9.Cu")
		(net "VID_PCH_CORE_PVNN_AUX_VID_1")
	)
	(segment
		(start 438.103264 -136.228328)
		(end 438.103264 -142.192248)
		(width 0.089408)
		(layer "In9.Cu")
		(net "VID_PCH_CORE_PVNN_AUX_VID_1")
	)
	(segment
		(start 414.80105 -119.424196)
		(end 414.829244 -119.424196)
		(width 0.089408)
		(layer "In9.Cu")
		(net "VID_PCH_CORE_PVNN_AUX_VID_1")
	)
	(segment
		(start 415.33445 -121.829068)
		(end 417.742624 -124.237242)
		(width 0.089408)
		(layer "In9.Cu")
		(net "VID_PCH_CORE_PVNN_AUX_VID_1")
	)
	(segment
		(start 429.662336 -134.920482)
		(end 436.795418 -134.920482)
		(width 0.089408)
		(layer "In9.Cu")
		(net "VID_PCH_CORE_PVNN_AUX_VID_1")
	)
	(segment
		(start 438.103264 -142.192248)
		(end 438.323736 -142.41272)
		(width 0.089408)
		(layer "In9.Cu")
		(net "VID_PCH_CORE_PVNN_AUX_VID_1")
	)
	(segment
		(start 437.468264 -144.605248)
		(end 437.468264 -151.238712)
		(width 0.089408)
		(layer "In9.Cu")
		(net "VID_PCH_CORE_PVNN_AUX_VID_1")
	)
	(segment
		(start 438.323736 -142.41272)
		(end 438.323736 -143.749776)
		(width 0.089408)
		(layer "In9.Cu")
		(net "VID_PCH_CORE_PVNN_AUX_VID_1")
	)
	(segment
		(start 418.466778 -125.401832)
		(end 418.466778 -126.29515)
		(width 0.089408)
		(layer "In9.Cu")
		(net "VID_PCH_CORE_PVNN_AUX_VID_1")
	)
	(segment
		(start 438.323736 -143.749776)
		(end 437.468264 -144.605248)
		(width 0.089408)
		(layer "In9.Cu")
		(net "VID_PCH_CORE_PVNN_AUX_VID_1")
	)
	(segment
		(start 436.795418 -134.920482)
		(end 438.103264 -136.228328)
		(width 0.089408)
		(layer "In9.Cu")
		(net "VID_PCH_CORE_PVNN_AUX_VID_1")
	)
	(segment
		(start 437.468264 -151.238712)
		(end 438.572656 -152.343104)
		(width 0.089408)
		(layer "In9.Cu")
		(net "VID_PCH_CORE_PVNN_AUX_VID_1")
	)
	(segment
		(start 417.742624 -124.237242)
		(end 417.742624 -124.677678)
		(width 0.089408)
		(layer "In9.Cu")
		(net "VID_PCH_CORE_PVNN_AUX_VID_1")
	)
	(segment
		(start 444.392304 -152.343104)
		(end 446.988438 -149.74697)
		(width 0.089408)
		(layer "In9.Cu")
		(net "VID_PCH_CORE_PVNN_AUX_VID_1")
	)
	(segment
		(start 415.33445 -119.929402)
		(end 415.33445 -121.829068)
		(width 0.089408)
		(layer "In9.Cu")
		(net "VID_PCH_CORE_PVNN_AUX_VID_1")
	)
	(segment
		(start 446.988438 -149.74697)
		(end 447.563748 -149.74697)
		(width 0.089408)
		(layer "In9.Cu")
		(net "VID_PCH_CORE_PVNN_AUX_VID_1")
	)
	(segment
		(start 414.829244 -119.424196)
		(end 415.33445 -119.929402)
		(width 0.089408)
		(layer "In9.Cu")
		(net "VID_PCH_CORE_PVNN_AUX_VID_1")
	)
	(segment
		(start 417.742624 -124.677678)
		(end 418.466778 -125.401832)
		(width 0.089408)
		(layer "In9.Cu")
		(net "VID_PCH_CORE_PVNN_AUX_VID_1")
	)
	(segment
		(start 399.60804 -152.8064)
		(end 400.16176 -152.25268)
		(width 0.089408)
		(layer "In11.Cu")
		(net "VID_PCH_CORE_PVNN_AUX_VID_1")
	)
	(segment
		(start 412.5976 -154.1272)
		(end 416.42157 -154.1272)
		(width 0.089408)
		(layer "In11.Cu")
		(net "VID_PCH_CORE_PVNN_AUX_VID_1")
	)
	(segment
		(start 405.544528 -157.587696)
		(end 405.801068 -157.844236)
		(width 0.089408)
		(layer "In11.Cu")
		(net "VID_PCH_CORE_PVNN_AUX_VID_1")
	)
	(segment
		(start 405.801068 -157.844236)
		(end 409.817316 -157.844236)
		(width 0.089408)
		(layer "In11.Cu")
		(net "VID_PCH_CORE_PVNN_AUX_VID_1")
	)
	(segment
		(start 404.014432 -152.6032)
		(end 405.544528 -154.133296)
		(width 0.089408)
		(layer "In11.Cu")
		(net "VID_PCH_CORE_PVNN_AUX_VID_1")
	)
	(segment
		(start 405.544528 -154.133296)
		(end 405.544528 -157.587696)
		(width 0.089408)
		(layer "In11.Cu")
		(net "VID_PCH_CORE_PVNN_AUX_VID_1")
	)
	(segment
		(start 410.8196 -155.9052)
		(end 412.5976 -154.1272)
		(width 0.089408)
		(layer "In11.Cu")
		(net "VID_PCH_CORE_PVNN_AUX_VID_1")
	)
	(segment
		(start 400.16176 -152.25268)
		(end 401.652232 -152.25268)
		(width 0.089408)
		(layer "In11.Cu")
		(net "VID_PCH_CORE_PVNN_AUX_VID_1")
	)
	(segment
		(start 410.8196 -156.841952)
		(end 410.8196 -155.9052)
		(width 0.089408)
		(layer "In11.Cu")
		(net "VID_PCH_CORE_PVNN_AUX_VID_1")
	)
	(segment
		(start 402.002752 -152.6032)
		(end 404.014432 -152.6032)
		(width 0.089408)
		(layer "In11.Cu")
		(net "VID_PCH_CORE_PVNN_AUX_VID_1")
	)
	(segment
		(start 401.652232 -152.25268)
		(end 402.002752 -152.6032)
		(width 0.089408)
		(layer "In11.Cu")
		(net "VID_PCH_CORE_PVNN_AUX_VID_1")
	)
	(segment
		(start 409.817316 -157.844236)
		(end 410.8196 -156.841952)
		(width 0.089408)
		(layer "In11.Cu")
		(net "VID_PCH_CORE_PVNN_AUX_VID_1")
	)
	(segment
		(start 416.42157 -154.1272)
		(end 416.793934 -153.754836)
		(width 0.089408)
		(layer "In11.Cu")
		(net "VID_PCH_CORE_PVNN_AUX_VID_1")
	)
	(segment
		(start 397.14805 -96.11868)
		(end 397.558768 -95.927926)
		(width 0.10795)
		(layer "F.Cu")
		(net "VID_PCH_CORE_PVNN_AUX_VID_0")
	)
	(segment
		(start 398.2339 -152.797002)
		(end 398.94764 -152.797002)
		(width 0.1016)
		(layer "F.Cu")
		(net "VID_PCH_CORE_PVNN_AUX_VID_0")
	)
	(segment
		(start 397.558768 -95.927926)
		(end 397.64335 -95.888556)
		(width 0.10795)
		(layer "F.Cu")
		(net "VID_PCH_CORE_PVNN_AUX_VID_0")
	)
	(via
		(at 414.873186 -120.106186)
		(size 0.508)
		(drill 0.254)
		(layers "F.Cu" "B.Cu")
		(net "VID_PCH_CORE_PVNN_AUX_VID_0")
	)
	(via
		(at 398.94764 -152.797002)
		(size 0.508)
		(drill 0.254)
		(layers "F.Cu" "B.Cu")
		(net "VID_PCH_CORE_PVNN_AUX_VID_0")
	)
	(via
		(at 447.563748 -150.38197)
		(size 0.508)
		(drill 0.254)
		(layers "F.Cu" "B.Cu")
		(net "VID_PCH_CORE_PVNN_AUX_VID_0")
	)
	(via
		(at 398.0942 -152.8318)
		(size 0.6604)
		(drill 0.3302)
		(layers "F.Cu" "B.Cu")
		(net "VID_PCH_CORE_PVNN_AUX_VID_0")
	)
	(via
		(at 397.64335 -95.888556)
		(size 0.508)
		(drill 0.254)
		(layers "F.Cu" "B.Cu")
		(net "VID_PCH_CORE_PVNN_AUX_VID_0")
	)
	(via
		(at 417.793424 -153.65222)
		(size 0.508)
		(drill 0.254)
		(layers "F.Cu" "B.Cu")
		(net "VID_PCH_CORE_PVNN_AUX_VID_0")
	)
	(segment
		(start 398.0942 -152.8318)
		(end 398.128998 -152.797002)
		(width 0.10795)
		(layer "B.Cu")
		(net "VID_PCH_CORE_PVNN_AUX_VID_0")
	)
	(segment
		(start 398.94764 -152.797002)
		(end 399.522442 -152.2222)
		(width 0.10795)
		(layer "B.Cu")
		(net "VID_PCH_CORE_PVNN_AUX_VID_0")
	)
	(segment
		(start 400.812 -152.2222)
		(end 401.1168 -152.527)
		(width 0.10795)
		(layer "B.Cu")
		(net "VID_PCH_CORE_PVNN_AUX_VID_0")
	)
	(segment
		(start 398.128998 -152.797002)
		(end 398.94764 -152.797002)
		(width 0.10795)
		(layer "B.Cu")
		(net "VID_PCH_CORE_PVNN_AUX_VID_0")
	)
	(segment
		(start 401.1168 -152.527)
		(end 401.574 -152.527)
		(width 0.10795)
		(layer "B.Cu")
		(net "VID_PCH_CORE_PVNN_AUX_VID_0")
	)
	(segment
		(start 399.522442 -152.2222)
		(end 400.812 -152.2222)
		(width 0.10795)
		(layer "B.Cu")
		(net "VID_PCH_CORE_PVNN_AUX_VID_0")
	)
	(segment
		(start 420.6494 -148.3614)
		(end 420.6494 -152.896316)
		(width 0.089408)
		(layer "In2.Cu")
		(net "VID_PCH_CORE_PVNN_AUX_VID_0")
	)
	(segment
		(start 440.556904 -146.29765)
		(end 438.067958 -146.29765)
		(width 0.089408)
		(layer "In2.Cu")
		(net "VID_PCH_CORE_PVNN_AUX_VID_0")
	)
	(segment
		(start 447.349372 -150.167594)
		(end 445.167258 -150.167594)
		(width 0.089408)
		(layer "In2.Cu")
		(net "VID_PCH_CORE_PVNN_AUX_VID_0")
	)
	(segment
		(start 432.764438 -142.012416)
		(end 431.40884 -143.368014)
		(width 0.089408)
		(layer "In2.Cu")
		(net "VID_PCH_CORE_PVNN_AUX_VID_0")
	)
	(segment
		(start 445.167258 -150.167594)
		(end 442.827664 -147.828)
		(width 0.089408)
		(layer "In2.Cu")
		(net "VID_PCH_CORE_PVNN_AUX_VID_0")
	)
	(segment
		(start 447.563748 -150.38197)
		(end 447.349372 -150.167594)
		(width 0.089408)
		(layer "In2.Cu")
		(net "VID_PCH_CORE_PVNN_AUX_VID_0")
	)
	(segment
		(start 422.7576 -146.2532)
		(end 420.6494 -148.3614)
		(width 0.089408)
		(layer "In2.Cu")
		(net "VID_PCH_CORE_PVNN_AUX_VID_0")
	)
	(segment
		(start 438.067958 -146.29765)
		(end 433.782724 -142.012416)
		(width 0.089408)
		(layer "In2.Cu")
		(net "VID_PCH_CORE_PVNN_AUX_VID_0")
	)
	(segment
		(start 431.40884 -143.368014)
		(end 431.40884 -145.01876)
		(width 0.089408)
		(layer "In2.Cu")
		(net "VID_PCH_CORE_PVNN_AUX_VID_0")
	)
	(segment
		(start 419.893496 -153.65222)
		(end 417.793424 -153.65222)
		(width 0.089408)
		(layer "In2.Cu")
		(net "VID_PCH_CORE_PVNN_AUX_VID_0")
	)
	(segment
		(start 420.6494 -152.896316)
		(end 419.893496 -153.65222)
		(width 0.089408)
		(layer "In2.Cu")
		(net "VID_PCH_CORE_PVNN_AUX_VID_0")
	)
	(segment
		(start 442.827664 -147.828)
		(end 442.087254 -147.828)
		(width 0.089408)
		(layer "In2.Cu")
		(net "VID_PCH_CORE_PVNN_AUX_VID_0")
	)
	(segment
		(start 442.087254 -147.828)
		(end 440.556904 -146.29765)
		(width 0.089408)
		(layer "In2.Cu")
		(net "VID_PCH_CORE_PVNN_AUX_VID_0")
	)
	(segment
		(start 430.1744 -146.2532)
		(end 422.7576 -146.2532)
		(width 0.089408)
		(layer "In2.Cu")
		(net "VID_PCH_CORE_PVNN_AUX_VID_0")
	)
	(segment
		(start 431.40884 -145.01876)
		(end 430.1744 -146.2532)
		(width 0.089408)
		(layer "In2.Cu")
		(net "VID_PCH_CORE_PVNN_AUX_VID_0")
	)
	(segment
		(start 433.782724 -142.012416)
		(end 432.764438 -142.012416)
		(width 0.089408)
		(layer "In2.Cu")
		(net "VID_PCH_CORE_PVNN_AUX_VID_0")
	)
	(segment
		(start 381.959104 -100.640896)
		(end 381.628396 -100.640896)
		(width 0.089408)
		(layer "In4.Cu")
		(net "VID_PCH_CORE_PVNN_AUX_VID_0")
	)
	(segment
		(start 389.057896 -96.348296)
		(end 388.82447 -96.581722)
		(width 0.089408)
		(layer "In4.Cu")
		(net "VID_PCH_CORE_PVNN_AUX_VID_0")
	)
	(segment
		(start 390.6774 -119.629428)
		(end 390.6774 -119.49176)
		(width 0.089408)
		(layer "In4.Cu")
		(net "VID_PCH_CORE_PVNN_AUX_VID_0")
	)
	(segment
		(start 377.829572 -112.968024)
		(end 376.893328 -113.904268)
		(width 0.089408)
		(layer "In4.Cu")
		(net "VID_PCH_CORE_PVNN_AUX_VID_0")
	)
	(segment
		(start 377.739402 -108.498132)
		(end 377.739402 -111.022638)
		(width 0.089408)
		(layer "In4.Cu")
		(net "VID_PCH_CORE_PVNN_AUX_VID_0")
	)
	(segment
		(start 384.86207 -98.661982)
		(end 384.36677 -99.157282)
		(width 0.089408)
		(layer "In4.Cu")
		(net "VID_PCH_CORE_PVNN_AUX_VID_0")
	)
	(segment
		(start 375.674636 -114.639598)
		(end 375.674636 -120.165876)
		(width 0.089408)
		(layer "In4.Cu")
		(net "VID_PCH_CORE_PVNN_AUX_VID_0")
	)
	(segment
		(start 378.309378 -111.592614)
		(end 378.309378 -111.94669)
		(width 0.089408)
		(layer "In4.Cu")
		(net "VID_PCH_CORE_PVNN_AUX_VID_0")
	)
	(segment
		(start 388.82447 -96.71939)
		(end 388.398004 -97.145856)
		(width 0.089408)
		(layer "In4.Cu")
		(net "VID_PCH_CORE_PVNN_AUX_VID_0")
	)
	(segment
		(start 378.717556 -105.731056)
		(end 378.42317 -106.025442)
		(width 0.089408)
		(layer "In4.Cu")
		(net "VID_PCH_CORE_PVNN_AUX_VID_0")
	)
	(segment
		(start 382.157732 -100.839524)
		(end 381.959104 -100.640896)
		(width 0.089408)
		(layer "In4.Cu")
		(net "VID_PCH_CORE_PVNN_AUX_VID_0")
	)
	(segment
		(start 396.74927 -96.581722)
		(end 396.74927 -96.71939)
		(width 0.089408)
		(layer "In4.Cu")
		(net "VID_PCH_CORE_PVNN_AUX_VID_0")
	)
	(segment
		(start 395.992096 -97.145856)
		(end 395.699742 -96.853502)
		(width 0.089408)
		(layer "In4.Cu")
		(net "VID_PCH_CORE_PVNN_AUX_VID_0")
	)
	(segment
		(start 411.98927 -116.508022)
		(end 413.742886 -118.261638)
		(width 0.089408)
		(layer "In4.Cu")
		(net "VID_PCH_CORE_PVNN_AUX_VID_0")
	)
	(segment
		(start 381.20193 -102.36581)
		(end 381.20193 -102.92207)
		(width 0.089408)
		(layer "In4.Cu")
		(net "VID_PCH_CORE_PVNN_AUX_VID_0")
	)
	(segment
		(start 381.39497 -101.237542)
		(end 380.89967 -101.732842)
		(width 0.089408)
		(layer "In4.Cu")
		(net "VID_PCH_CORE_PVNN_AUX_VID_0")
	)
	(segment
		(start 389.97763 -120.808496)
		(end 390.241536 -120.54459)
		(width 0.089408)
		(layer "In4.Cu")
		(net "VID_PCH_CORE_PVNN_AUX_VID_0")
	)
	(segment
		(start 376.409966 -113.904268)
		(end 375.674636 -114.639598)
		(width 0.089408)
		(layer "In4.Cu")
		(net "VID_PCH_CORE_PVNN_AUX_VID_0")
	)
	(segment
		(start 395.699742 -96.853502)
		(end 395.699742 -96.715834)
		(width 0.089408)
		(layer "In4.Cu")
		(net "VID_PCH_CORE_PVNN_AUX_VID_0")
	)
	(segment
		(start 414.74517 -120.106186)
		(end 414.873186 -120.106186)
		(width 0.089408)
		(layer "In4.Cu")
		(net "VID_PCH_CORE_PVNN_AUX_VID_0")
	)
	(segment
		(start 377.92787 -106.883962)
		(end 377.92787 -107.21467)
		(width 0.089408)
		(layer "In4.Cu")
		(net "VID_PCH_CORE_PVNN_AUX_VID_0")
	)
	(segment
		(start 390.6774 -119.49176)
		(end 391.06856 -119.1006)
		(width 0.089408)
		(layer "In4.Cu")
		(net "VID_PCH_CORE_PVNN_AUX_VID_0")
	)
	(segment
		(start 382.88087 -100.742242)
		(end 382.783588 -100.839524)
		(width 0.089408)
		(layer "In4.Cu")
		(net "VID_PCH_CORE_PVNN_AUX_VID_0")
	)
	(segment
		(start 384.36677 -99.29495)
		(end 383.879344 -99.782376)
		(width 0.089408)
		(layer "In4.Cu")
		(net "VID_PCH_CORE_PVNN_AUX_VID_0")
	)
	(segment
		(start 377.739402 -111.022638)
		(end 378.309378 -111.592614)
		(width 0.089408)
		(layer "In4.Cu")
		(net "VID_PCH_CORE_PVNN_AUX_VID_0")
	)
	(segment
		(start 378.22378 -108.013754)
		(end 377.739402 -108.498132)
		(width 0.089408)
		(layer "In4.Cu")
		(net "VID_PCH_CORE_PVNN_AUX_VID_0")
	)
	(segment
		(start 383.114296 -99.782376)
		(end 382.88087 -100.015802)
		(width 0.089408)
		(layer "In4.Cu")
		(net "VID_PCH_CORE_PVNN_AUX_VID_0")
	)
	(segment
		(start 377.829572 -112.426496)
		(end 377.829572 -112.968024)
		(width 0.089408)
		(layer "In4.Cu")
		(net "VID_PCH_CORE_PVNN_AUX_VID_0")
	)
	(segment
		(start 413.742886 -118.261638)
		(end 413.742886 -119.103902)
		(width 0.089408)
		(layer "In4.Cu")
		(net "VID_PCH_CORE_PVNN_AUX_VID_0")
	)
	(segment
		(start 396.322804 -97.145856)
		(end 395.992096 -97.145856)
		(width 0.089408)
		(layer "In4.Cu")
		(net "VID_PCH_CORE_PVNN_AUX_VID_0")
	)
	(segment
		(start 385.651756 -97.145856)
		(end 385.35737 -97.440242)
		(width 0.089408)
		(layer "In4.Cu")
		(net "VID_PCH_CORE_PVNN_AUX_VID_0")
	)
	(segment
		(start 390.241536 -120.065292)
		(end 390.6774 -119.629428)
		(width 0.089408)
		(layer "In4.Cu")
		(net "VID_PCH_CORE_PVNN_AUX_VID_0")
	)
	(segment
		(start 379.71603 -105.13441)
		(end 379.71603 -105.49763)
		(width 0.089408)
		(layer "In4.Cu")
		(net "VID_PCH_CORE_PVNN_AUX_VID_0")
	)
	(segment
		(start 378.42317 -106.025442)
		(end 378.42317 -106.388662)
		(width 0.089408)
		(layer "In4.Cu")
		(net "VID_PCH_CORE_PVNN_AUX_VID_0")
	)
	(segment
		(start 382.783588 -100.839524)
		(end 382.157732 -100.839524)
		(width 0.089408)
		(layer "In4.Cu")
		(net "VID_PCH_CORE_PVNN_AUX_VID_0")
	)
	(segment
		(start 385.35737 -97.440242)
		(end 385.35737 -97.803462)
		(width 0.089408)
		(layer "In4.Cu")
		(net "VID_PCH_CORE_PVNN_AUX_VID_0")
	)
	(segment
		(start 388.398004 -97.145856)
		(end 385.651756 -97.145856)
		(width 0.089408)
		(layer "In4.Cu")
		(net "VID_PCH_CORE_PVNN_AUX_VID_0")
	)
	(segment
		(start 383.879344 -99.782376)
		(end 383.114296 -99.782376)
		(width 0.089408)
		(layer "In4.Cu")
		(net "VID_PCH_CORE_PVNN_AUX_VID_0")
	)
	(segment
		(start 376.893328 -113.904268)
		(end 376.409966 -113.904268)
		(width 0.089408)
		(layer "In4.Cu")
		(net "VID_PCH_CORE_PVNN_AUX_VID_0")
	)
	(segment
		(start 379.482604 -105.731056)
		(end 378.717556 -105.731056)
		(width 0.089408)
		(layer "In4.Cu")
		(net "VID_PCH_CORE_PVNN_AUX_VID_0")
	)
	(segment
		(start 397.442436 -95.888556)
		(end 396.74927 -96.581722)
		(width 0.089408)
		(layer "In4.Cu")
		(net "VID_PCH_CORE_PVNN_AUX_VID_0")
	)
	(segment
		(start 390.241536 -120.54459)
		(end 390.241536 -120.065292)
		(width 0.089408)
		(layer "In4.Cu")
		(net "VID_PCH_CORE_PVNN_AUX_VID_0")
	)
	(segment
		(start 381.628396 -100.640896)
		(end 381.39497 -100.874322)
		(width 0.089408)
		(layer "In4.Cu")
		(net "VID_PCH_CORE_PVNN_AUX_VID_0")
	)
	(segment
		(start 382.88087 -100.015802)
		(end 382.88087 -100.742242)
		(width 0.089408)
		(layer "In4.Cu")
		(net "VID_PCH_CORE_PVNN_AUX_VID_0")
	)
	(segment
		(start 381.20193 -102.92207)
		(end 380.746 -103.378)
		(width 0.089408)
		(layer "In4.Cu")
		(net "VID_PCH_CORE_PVNN_AUX_VID_0")
	)
	(segment
		(start 408.174698 -116.508022)
		(end 411.98927 -116.508022)
		(width 0.089408)
		(layer "In4.Cu")
		(net "VID_PCH_CORE_PVNN_AUX_VID_0")
	)
	(segment
		(start 375.674636 -120.165876)
		(end 376.317256 -120.808496)
		(width 0.089408)
		(layer "In4.Cu")
		(net "VID_PCH_CORE_PVNN_AUX_VID_0")
	)
	(segment
		(start 396.74927 -96.71939)
		(end 396.322804 -97.145856)
		(width 0.089408)
		(layer "In4.Cu")
		(net "VID_PCH_CORE_PVNN_AUX_VID_0")
	)
	(segment
		(start 395.332204 -96.348296)
		(end 389.057896 -96.348296)
		(width 0.089408)
		(layer "In4.Cu")
		(net "VID_PCH_CORE_PVNN_AUX_VID_0")
	)
	(segment
		(start 405.58212 -119.1006)
		(end 408.174698 -116.508022)
		(width 0.089408)
		(layer "In4.Cu")
		(net "VID_PCH_CORE_PVNN_AUX_VID_0")
	)
	(segment
		(start 395.699742 -96.715834)
		(end 395.332204 -96.348296)
		(width 0.089408)
		(layer "In4.Cu")
		(net "VID_PCH_CORE_PVNN_AUX_VID_0")
	)
	(segment
		(start 380.89967 -101.732842)
		(end 380.89967 -102.06355)
		(width 0.089408)
		(layer "In4.Cu")
		(net "VID_PCH_CORE_PVNN_AUX_VID_0")
	)
	(segment
		(start 388.82447 -96.581722)
		(end 388.82447 -96.71939)
		(width 0.089408)
		(layer "In4.Cu")
		(net "VID_PCH_CORE_PVNN_AUX_VID_0")
	)
	(segment
		(start 385.35737 -97.803462)
		(end 384.86207 -98.298762)
		(width 0.089408)
		(layer "In4.Cu")
		(net "VID_PCH_CORE_PVNN_AUX_VID_0")
	)
	(segment
		(start 380.21133 -104.19588)
		(end 380.21133 -104.63911)
		(width 0.089408)
		(layer "In4.Cu")
		(net "VID_PCH_CORE_PVNN_AUX_VID_0")
	)
	(segment
		(start 376.317256 -120.808496)
		(end 389.97763 -120.808496)
		(width 0.089408)
		(layer "In4.Cu")
		(net "VID_PCH_CORE_PVNN_AUX_VID_0")
	)
	(segment
		(start 378.42317 -106.388662)
		(end 377.92787 -106.883962)
		(width 0.089408)
		(layer "In4.Cu")
		(net "VID_PCH_CORE_PVNN_AUX_VID_0")
	)
	(segment
		(start 397.64335 -95.888556)
		(end 397.442436 -95.888556)
		(width 0.089408)
		(layer "In4.Cu")
		(net "VID_PCH_CORE_PVNN_AUX_VID_0")
	)
	(segment
		(start 381.39497 -100.874322)
		(end 381.39497 -101.237542)
		(width 0.089408)
		(layer "In4.Cu")
		(net "VID_PCH_CORE_PVNN_AUX_VID_0")
	)
	(segment
		(start 380.89967 -102.06355)
		(end 381.20193 -102.36581)
		(width 0.089408)
		(layer "In4.Cu")
		(net "VID_PCH_CORE_PVNN_AUX_VID_0")
	)
	(segment
		(start 391.06856 -119.1006)
		(end 405.58212 -119.1006)
		(width 0.089408)
		(layer "In4.Cu")
		(net "VID_PCH_CORE_PVNN_AUX_VID_0")
	)
	(segment
		(start 380.21133 -104.63911)
		(end 379.71603 -105.13441)
		(width 0.089408)
		(layer "In4.Cu")
		(net "VID_PCH_CORE_PVNN_AUX_VID_0")
	)
	(segment
		(start 384.86207 -98.298762)
		(end 384.86207 -98.661982)
		(width 0.089408)
		(layer "In4.Cu")
		(net "VID_PCH_CORE_PVNN_AUX_VID_0")
	)
	(segment
		(start 378.309378 -111.94669)
		(end 377.829572 -112.426496)
		(width 0.089408)
		(layer "In4.Cu")
		(net "VID_PCH_CORE_PVNN_AUX_VID_0")
	)
	(segment
		(start 377.92787 -107.21467)
		(end 378.22378 -107.51058)
		(width 0.089408)
		(layer "In4.Cu")
		(net "VID_PCH_CORE_PVNN_AUX_VID_0")
	)
	(segment
		(start 379.71603 -105.49763)
		(end 379.482604 -105.731056)
		(width 0.089408)
		(layer "In4.Cu")
		(net "VID_PCH_CORE_PVNN_AUX_VID_0")
	)
	(segment
		(start 384.36677 -99.157282)
		(end 384.36677 -99.29495)
		(width 0.089408)
		(layer "In4.Cu")
		(net "VID_PCH_CORE_PVNN_AUX_VID_0")
	)
	(segment
		(start 380.746 -103.378)
		(end 380.746 -103.66121)
		(width 0.089408)
		(layer "In4.Cu")
		(net "VID_PCH_CORE_PVNN_AUX_VID_0")
	)
	(segment
		(start 413.742886 -119.103902)
		(end 414.74517 -120.106186)
		(width 0.089408)
		(layer "In4.Cu")
		(net "VID_PCH_CORE_PVNN_AUX_VID_0")
	)
	(segment
		(start 380.746 -103.66121)
		(end 380.21133 -104.19588)
		(width 0.089408)
		(layer "In4.Cu")
		(net "VID_PCH_CORE_PVNN_AUX_VID_0")
	)
	(segment
		(start 378.22378 -107.51058)
		(end 378.22378 -108.013754)
		(width 0.089408)
		(layer "In4.Cu")
		(net "VID_PCH_CORE_PVNN_AUX_VID_0")
	)
	(segment
		(start 416.840416 -124.575824)
		(end 416.840416 -124.658882)
		(width 0.089408)
		(layer "In9.Cu")
		(net "VID_PCH_CORE_PVNN_AUX_VID_0")
	)
	(segment
		(start 426.72 -132.484114)
		(end 429.514 -135.278114)
		(width 0.089408)
		(layer "In9.Cu")
		(net "VID_PCH_CORE_PVNN_AUX_VID_0")
	)
	(segment
		(start 424.446192 -132.484368)
		(end 424.446446 -132.484114)
		(width 0.089408)
		(layer "In9.Cu")
		(net "VID_PCH_CORE_PVNN_AUX_VID_0")
	)
	(segment
		(start 438.42432 -152.700736)
		(end 444.54064 -152.700736)
		(width 0.089408)
		(layer "In9.Cu")
		(net "VID_PCH_CORE_PVNN_AUX_VID_0")
	)
	(segment
		(start 429.514 -135.278114)
		(end 436.647082 -135.278114)
		(width 0.089408)
		(layer "In9.Cu")
		(net "VID_PCH_CORE_PVNN_AUX_VID_0")
	)
	(segment
		(start 417.104576 -124.923042)
		(end 417.48202 -124.923042)
		(width 0.089408)
		(layer "In9.Cu")
		(net "VID_PCH_CORE_PVNN_AUX_VID_0")
	)
	(segment
		(start 437.110632 -144.419828)
		(end 437.110632 -151.387048)
		(width 0.089408)
		(layer "In9.Cu")
		(net "VID_PCH_CORE_PVNN_AUX_VID_0")
	)
	(segment
		(start 418.109146 -126.443486)
		(end 424.150028 -132.484368)
		(width 0.089408)
		(layer "In9.Cu")
		(net "VID_PCH_CORE_PVNN_AUX_VID_0")
	)
	(segment
		(start 444.54064 -152.700736)
		(end 446.859406 -150.38197)
		(width 0.089408)
		(layer "In9.Cu")
		(net "VID_PCH_CORE_PVNN_AUX_VID_0")
	)
	(segment
		(start 417.48202 -124.923042)
		(end 418.109146 -125.550168)
		(width 0.089408)
		(layer "In9.Cu")
		(net "VID_PCH_CORE_PVNN_AUX_VID_0")
	)
	(segment
		(start 437.966104 -143.564356)
		(end 437.110632 -144.419828)
		(width 0.089408)
		(layer "In9.Cu")
		(net "VID_PCH_CORE_PVNN_AUX_VID_0")
	)
	(segment
		(start 446.859406 -150.38197)
		(end 447.563748 -150.38197)
		(width 0.089408)
		(layer "In9.Cu")
		(net "VID_PCH_CORE_PVNN_AUX_VID_0")
	)
	(segment
		(start 416.526472 -124.297186)
		(end 416.561778 -124.297186)
		(width 0.089408)
		(layer "In9.Cu")
		(net "VID_PCH_CORE_PVNN_AUX_VID_0")
	)
	(segment
		(start 414.873186 -120.106186)
		(end 414.873186 -122.6439)
		(width 0.089408)
		(layer "In9.Cu")
		(net "VID_PCH_CORE_PVNN_AUX_VID_0")
	)
	(segment
		(start 437.745632 -142.340584)
		(end 437.966104 -142.561056)
		(width 0.089408)
		(layer "In9.Cu")
		(net "VID_PCH_CORE_PVNN_AUX_VID_0")
	)
	(segment
		(start 418.109146 -125.550168)
		(end 418.109146 -126.443486)
		(width 0.089408)
		(layer "In9.Cu")
		(net "VID_PCH_CORE_PVNN_AUX_VID_0")
	)
	(segment
		(start 424.446446 -132.484114)
		(end 426.72 -132.484114)
		(width 0.089408)
		(layer "In9.Cu")
		(net "VID_PCH_CORE_PVNN_AUX_VID_0")
	)
	(segment
		(start 436.647082 -135.278114)
		(end 437.745632 -136.376664)
		(width 0.089408)
		(layer "In9.Cu")
		(net "VID_PCH_CORE_PVNN_AUX_VID_0")
	)
	(segment
		(start 414.873186 -122.6439)
		(end 416.526472 -124.297186)
		(width 0.089408)
		(layer "In9.Cu")
		(net "VID_PCH_CORE_PVNN_AUX_VID_0")
	)
	(segment
		(start 416.840416 -124.658882)
		(end 417.104576 -124.923042)
		(width 0.089408)
		(layer "In9.Cu")
		(net "VID_PCH_CORE_PVNN_AUX_VID_0")
	)
	(segment
		(start 437.966104 -142.561056)
		(end 437.966104 -143.564356)
		(width 0.089408)
		(layer "In9.Cu")
		(net "VID_PCH_CORE_PVNN_AUX_VID_0")
	)
	(segment
		(start 424.150028 -132.484368)
		(end 424.446192 -132.484368)
		(width 0.089408)
		(layer "In9.Cu")
		(net "VID_PCH_CORE_PVNN_AUX_VID_0")
	)
	(segment
		(start 416.561778 -124.297186)
		(end 416.840416 -124.575824)
		(width 0.089408)
		(layer "In9.Cu")
		(net "VID_PCH_CORE_PVNN_AUX_VID_0")
	)
	(segment
		(start 437.110632 -151.387048)
		(end 438.42432 -152.700736)
		(width 0.089408)
		(layer "In9.Cu")
		(net "VID_PCH_CORE_PVNN_AUX_VID_0")
	)
	(segment
		(start 437.745632 -136.376664)
		(end 437.745632 -142.340584)
		(width 0.089408)
		(layer "In9.Cu")
		(net "VID_PCH_CORE_PVNN_AUX_VID_0")
	)
	(segment
		(start 398.94764 -152.797002)
		(end 399.876518 -151.868124)
		(width 0.089408)
		(layer "In11.Cu")
		(net "VID_PCH_CORE_PVNN_AUX_VID_0")
	)
	(segment
		(start 407.752804 -156.848556)
		(end 407.464514 -156.560266)
		(width 0.089408)
		(layer "In11.Cu")
		(net "VID_PCH_CORE_PVNN_AUX_VID_0")
	)
	(segment
		(start 404.0632 -152.146)
		(end 405.90216 -153.98496)
		(width 0.089408)
		(layer "In11.Cu")
		(net "VID_PCH_CORE_PVNN_AUX_VID_0")
	)
	(segment
		(start 407.464514 -155.299918)
		(end 408.51455 -154.249882)
		(width 0.089408)
		(layer "In11.Cu")
		(net "VID_PCH_CORE_PVNN_AUX_VID_0")
	)
	(segment
		(start 402.153628 -152.146)
		(end 404.0632 -152.146)
		(width 0.089408)
		(layer "In11.Cu")
		(net "VID_PCH_CORE_PVNN_AUX_VID_0")
	)
	(segment
		(start 407.488644 -157.486604)
		(end 407.752804 -157.222444)
		(width 0.089408)
		(layer "In11.Cu")
		(net "VID_PCH_CORE_PVNN_AUX_VID_0")
	)
	(segment
		(start 416.980878 -153.303732)
		(end 417.329366 -153.65222)
		(width 0.089408)
		(layer "In11.Cu")
		(net "VID_PCH_CORE_PVNN_AUX_VID_0")
	)
	(segment
		(start 416.60699 -153.303732)
		(end 416.980878 -153.303732)
		(width 0.089408)
		(layer "In11.Cu")
		(net "VID_PCH_CORE_PVNN_AUX_VID_0")
	)
	(segment
		(start 401.875752 -151.868124)
		(end 402.153628 -152.146)
		(width 0.089408)
		(layer "In11.Cu")
		(net "VID_PCH_CORE_PVNN_AUX_VID_0")
	)
	(segment
		(start 411.918404 -154.249882)
		(end 412.498286 -153.67)
		(width 0.089408)
		(layer "In11.Cu")
		(net "VID_PCH_CORE_PVNN_AUX_VID_0")
	)
	(segment
		(start 405.90216 -157.1244)
		(end 406.264364 -157.486604)
		(width 0.089408)
		(layer "In11.Cu")
		(net "VID_PCH_CORE_PVNN_AUX_VID_0")
	)
	(segment
		(start 406.264364 -157.486604)
		(end 407.488644 -157.486604)
		(width 0.089408)
		(layer "In11.Cu")
		(net "VID_PCH_CORE_PVNN_AUX_VID_0")
	)
	(segment
		(start 405.90216 -153.98496)
		(end 405.90216 -157.1244)
		(width 0.089408)
		(layer "In11.Cu")
		(net "VID_PCH_CORE_PVNN_AUX_VID_0")
	)
	(segment
		(start 407.752804 -157.222444)
		(end 407.752804 -156.848556)
		(width 0.089408)
		(layer "In11.Cu")
		(net "VID_PCH_CORE_PVNN_AUX_VID_0")
	)
	(segment
		(start 412.498286 -153.67)
		(end 416.240722 -153.67)
		(width 0.089408)
		(layer "In11.Cu")
		(net "VID_PCH_CORE_PVNN_AUX_VID_0")
	)
	(segment
		(start 416.240722 -153.67)
		(end 416.60699 -153.303732)
		(width 0.089408)
		(layer "In11.Cu")
		(net "VID_PCH_CORE_PVNN_AUX_VID_0")
	)
	(segment
		(start 399.876518 -151.868124)
		(end 401.875752 -151.868124)
		(width 0.089408)
		(layer "In11.Cu")
		(net "VID_PCH_CORE_PVNN_AUX_VID_0")
	)
	(segment
		(start 407.464514 -156.560266)
		(end 407.464514 -155.299918)
		(width 0.089408)
		(layer "In11.Cu")
		(net "VID_PCH_CORE_PVNN_AUX_VID_0")
	)
	(segment
		(start 408.51455 -154.249882)
		(end 411.918404 -154.249882)
		(width 0.089408)
		(layer "In11.Cu")
		(net "VID_PCH_CORE_PVNN_AUX_VID_0")
	)
	(segment
		(start 417.329366 -153.65222)
		(end 417.793424 -153.65222)
		(width 0.089408)
		(layer "In11.Cu")
		(net "VID_PCH_CORE_PVNN_AUX_VID_0")
	)
	(segment
		(start 9.033002 -2.782062)
		(end 9.033002 -2.20345)
		(width 0.10795)
		(layer "F.Cu")
		(net "TP_PVDDQ_GHJ_MP2")
	)
	(segment
		(start 8.818626 -3.357118)
		(end 8.818626 -2.996438)
		(width 0.10795)
		(layer "F.Cu")
		(net "TP_PVDDQ_GHJ_MP2")
	)
	(segment
		(start 8.818626 -2.996438)
		(end 9.033002 -2.782062)
		(width 0.10795)
		(layer "F.Cu")
		(net "TP_PVDDQ_GHJ_MP2")
	)
	(segment
		(start 362.53928 -139.55268)
		(end 362.53928 -139.776708)
		(width 0.10795)
		(layer "F.Cu")
		(net "TP_PVDDQ_DEF_MP2")
	)
	(segment
		(start 362.53928 -139.776708)
		(end 362.950252 -140.18768)
		(width 0.10795)
		(layer "F.Cu")
		(net "TP_PVDDQ_DEF_MP2")
	)
	(segment
		(start 362.950252 -140.18768)
		(end 363.46892 -140.18768)
		(width 0.10795)
		(layer "F.Cu")
		(net "TP_PVDDQ_DEF_MP2")
	)
	(segment
		(start 361.74934 -139.164568)
		(end 362.151168 -139.164568)
		(width 0.10795)
		(layer "F.Cu")
		(net "TP_PVDDQ_DEF_MP2")
	)
	(segment
		(start 363.46892 -140.18768)
		(end 363.5756 -140.081)
		(width 0.10795)
		(layer "F.Cu")
		(net "TP_PVDDQ_DEF_MP2")
	)
	(segment
		(start 362.151168 -139.164568)
		(end 362.53928 -139.55268)
		(width 0.10795)
		(layer "F.Cu")
		(net "TP_PVDDQ_DEF_MP2")
	)
	(segment
		(start 363.5756 -140.081)
		(end 363.855 -140.081)
		(width 0.10795)
		(layer "F.Cu")
		(net "TP_PVDDQ_DEF_MP2")
	)
	(segment
		(start 339.3948 -14.732)
		(end 338.836 -14.732)
		(width 0.10795)
		(layer "F.Cu")
		(net "TP_PVDDQ_ABC_MP2")
	)
	(segment
		(start 342.2269 -14.367002)
		(end 339.759798 -14.367002)
		(width 0.10795)
		(layer "F.Cu")
		(net "TP_PVDDQ_ABC_MP2")
	)
	(segment
		(start 339.759798 -14.367002)
		(end 339.3948 -14.732)
		(width 0.10795)
		(layer "F.Cu")
		(net "TP_PVDDQ_ABC_MP2")
	)
	(segment
		(start 376.744738 -76.694792)
		(end 376.344942 -76.294996)
		(width 0.10795)
		(layer "F.Cu")
		(net "PWRGD_PVCCMCP_CPU1")
	)
	(segment
		(start 189.85865 -111.74095)
		(end 190.119 -111.4806)
		(width 0.10795)
		(layer "F.Cu")
		(net "PWRGD_PVCCMCP_CPU1")
	)
	(segment
		(start 188.745114 -111.74095)
		(end 189.85865 -111.74095)
		(width 0.10795)
		(layer "F.Cu")
		(net "PWRGD_PVCCMCP_CPU1")
	)
	(via
		(at 376.744738 -76.694792)
		(size 0.4572)
		(drill 0.2032)
		(layers "F.Cu" "B.Cu")
		(net "PWRGD_PVCCMCP_CPU1")
	)
	(via
		(at 320.8782 -43.79976)
		(size 0.6604)
		(drill 0.3302)
		(layers "F.Cu" "B.Cu")
		(net "PWRGD_PVCCMCP_CPU1")
	)
	(via
		(at 320.8782 -43.0403)
		(size 0.508)
		(drill 0.254)
		(layers "F.Cu" "B.Cu")
		(net "PWRGD_PVCCMCP_CPU1")
	)
	(via
		(at 374.420384 -65.203324)
		(size 0.508)
		(drill 0.254)
		(layers "F.Cu" "B.Cu")
		(net "PWRGD_PVCCMCP_CPU1")
	)
	(via
		(at 185.90514 -23.56866)
		(size 0.508)
		(drill 0.254)
		(layers "F.Cu" "B.Cu")
		(net "PWRGD_PVCCMCP_CPU1")
	)
	(via
		(at 184.121552 -47.98822)
		(size 0.508)
		(drill 0.254)
		(layers "F.Cu" "B.Cu")
		(net "PWRGD_PVCCMCP_CPU1")
	)
	(via
		(at 190.119 -111.4806)
		(size 0.508)
		(drill 0.254)
		(layers "F.Cu" "B.Cu")
		(net "PWRGD_PVCCMCP_CPU1")
	)
	(segment
		(start 320.8782 -43.79976)
		(end 320.8782 -43.0403)
		(width 0.10795)
		(layer "B.Cu")
		(net "PWRGD_PVCCMCP_CPU1")
	)
	(segment
		(start 186.15279 -24.537416)
		(end 185.969656 -24.354282)
		(width 0.089408)
		(layer "In2.Cu")
		(net "PWRGD_PVCCMCP_CPU1")
	)
	(segment
		(start 184.387744 -46.277276)
		(end 186.15279 -44.51223)
		(width 0.089408)
		(layer "In2.Cu")
		(net "PWRGD_PVCCMCP_CPU1")
	)
	(segment
		(start 185.972704 -23.636224)
		(end 185.90514 -23.56866)
		(width 0.089408)
		(layer "In2.Cu")
		(net "PWRGD_PVCCMCP_CPU1")
	)
	(segment
		(start 185.969656 -24.022558)
		(end 185.972704 -24.01951)
		(width 0.089408)
		(layer "In2.Cu")
		(net "PWRGD_PVCCMCP_CPU1")
	)
	(segment
		(start 184.387744 -47.722028)
		(end 184.387744 -46.277276)
		(width 0.089408)
		(layer "In2.Cu")
		(net "PWRGD_PVCCMCP_CPU1")
	)
	(segment
		(start 185.972704 -24.01951)
		(end 185.972704 -23.636224)
		(width 0.089408)
		(layer "In2.Cu")
		(net "PWRGD_PVCCMCP_CPU1")
	)
	(segment
		(start 186.15279 -44.51223)
		(end 186.15279 -24.537416)
		(width 0.089408)
		(layer "In2.Cu")
		(net "PWRGD_PVCCMCP_CPU1")
	)
	(segment
		(start 185.969656 -24.354282)
		(end 185.969656 -24.022558)
		(width 0.089408)
		(layer "In2.Cu")
		(net "PWRGD_PVCCMCP_CPU1")
	)
	(segment
		(start 184.121552 -47.98822)
		(end 184.387744 -47.722028)
		(width 0.089408)
		(layer "In2.Cu")
		(net "PWRGD_PVCCMCP_CPU1")
	)
	(segment
		(start 303.420272 -32.110172)
		(end 264.43051 -32.110172)
		(width 0.089408)
		(layer "In9.Cu")
		(net "PWRGD_PVCCMCP_CPU1")
	)
	(segment
		(start 372.9609 -67.642486)
		(end 372.9609 -68.062094)
		(width 0.089408)
		(layer "In9.Cu")
		(net "PWRGD_PVCCMCP_CPU1")
	)
	(segment
		(start 320.039492 -43.879008)
		(end 317.767208 -43.879008)
		(width 0.089408)
		(layer "In9.Cu")
		(net "PWRGD_PVCCMCP_CPU1")
	)
	(segment
		(start 259.827014 -29.120592)
		(end 242.667536 -29.120592)
		(width 0.089408)
		(layer "In9.Cu")
		(net "PWRGD_PVCCMCP_CPU1")
	)
	(segment
		(start 264.43051 -32.110172)
		(end 262.732266 -30.411928)
		(width 0.089408)
		(layer "In9.Cu")
		(net "PWRGD_PVCCMCP_CPU1")
	)
	(segment
		(start 373.171466 -73.843896)
		(end 373.918226 -74.590656)
		(width 0.089408)
		(layer "In9.Cu")
		(net "PWRGD_PVCCMCP_CPU1")
	)
	(segment
		(start 185.90514 -24.48814)
		(end 185.90514 -23.56866)
		(width 0.089408)
		(layer "In9.Cu")
		(net "PWRGD_PVCCMCP_CPU1")
	)
	(segment
		(start 373.171466 -68.27266)
		(end 373.171466 -73.843896)
		(width 0.089408)
		(layer "In9.Cu")
		(net "PWRGD_PVCCMCP_CPU1")
	)
	(segment
		(start 262.732266 -30.411928)
		(end 261.11835 -30.411928)
		(width 0.089408)
		(layer "In9.Cu")
		(net "PWRGD_PVCCMCP_CPU1")
	)
	(segment
		(start 374.2436 -66.359786)
		(end 372.9609 -67.642486)
		(width 0.089408)
		(layer "In9.Cu")
		(net "PWRGD_PVCCMCP_CPU1")
	)
	(segment
		(start 188.583316 -28.266136)
		(end 187.66409 -27.34691)
		(width 0.089408)
		(layer "In9.Cu")
		(net "PWRGD_PVCCMCP_CPU1")
	)
	(segment
		(start 373.918226 -76.796392)
		(end 374.19026 -77.068426)
		(width 0.089408)
		(layer "In9.Cu")
		(net "PWRGD_PVCCMCP_CPU1")
	)
	(segment
		(start 187.66409 -26.24709)
		(end 185.90514 -24.48814)
		(width 0.089408)
		(layer "In9.Cu")
		(net "PWRGD_PVCCMCP_CPU1")
	)
	(segment
		(start 261.11835 -30.411928)
		(end 259.827014 -29.120592)
		(width 0.089408)
		(layer "In9.Cu")
		(net "PWRGD_PVCCMCP_CPU1")
	)
	(segment
		(start 317.767208 -43.879008)
		(end 317.06058 -43.17238)
		(width 0.089408)
		(layer "In9.Cu")
		(net "PWRGD_PVCCMCP_CPU1")
	)
	(segment
		(start 241.880644 -29.907484)
		(end 223.675702 -29.907484)
		(width 0.089408)
		(layer "In9.Cu")
		(net "PWRGD_PVCCMCP_CPU1")
	)
	(segment
		(start 374.420384 -65.203324)
		(end 374.2436 -65.380108)
		(width 0.089408)
		(layer "In9.Cu")
		(net "PWRGD_PVCCMCP_CPU1")
	)
	(segment
		(start 374.19026 -77.068426)
		(end 376.371104 -77.068426)
		(width 0.089408)
		(layer "In9.Cu")
		(net "PWRGD_PVCCMCP_CPU1")
	)
	(segment
		(start 223.675702 -29.907484)
		(end 222.034354 -28.266136)
		(width 0.089408)
		(layer "In9.Cu")
		(net "PWRGD_PVCCMCP_CPU1")
	)
	(segment
		(start 187.66409 -27.34691)
		(end 187.66409 -26.24709)
		(width 0.089408)
		(layer "In9.Cu")
		(net "PWRGD_PVCCMCP_CPU1")
	)
	(segment
		(start 376.371104 -77.068426)
		(end 376.744738 -76.694792)
		(width 0.089408)
		(layer "In9.Cu")
		(net "PWRGD_PVCCMCP_CPU1")
	)
	(segment
		(start 320.8782 -43.0403)
		(end 320.039492 -43.879008)
		(width 0.089408)
		(layer "In9.Cu")
		(net "PWRGD_PVCCMCP_CPU1")
	)
	(segment
		(start 374.2436 -65.380108)
		(end 374.2436 -66.359786)
		(width 0.089408)
		(layer "In9.Cu")
		(net "PWRGD_PVCCMCP_CPU1")
	)
	(segment
		(start 222.034354 -28.266136)
		(end 188.583316 -28.266136)
		(width 0.089408)
		(layer "In9.Cu")
		(net "PWRGD_PVCCMCP_CPU1")
	)
	(segment
		(start 242.667536 -29.120592)
		(end 241.880644 -29.907484)
		(width 0.089408)
		(layer "In9.Cu")
		(net "PWRGD_PVCCMCP_CPU1")
	)
	(segment
		(start 372.9609 -68.062094)
		(end 373.171466 -68.27266)
		(width 0.089408)
		(layer "In9.Cu")
		(net "PWRGD_PVCCMCP_CPU1")
	)
	(segment
		(start 317.06058 -43.17238)
		(end 314.48248 -43.17238)
		(width 0.089408)
		(layer "In9.Cu")
		(net "PWRGD_PVCCMCP_CPU1")
	)
	(segment
		(start 314.48248 -43.17238)
		(end 303.420272 -32.110172)
		(width 0.089408)
		(layer "In9.Cu")
		(net "PWRGD_PVCCMCP_CPU1")
	)
	(segment
		(start 373.918226 -74.590656)
		(end 373.918226 -76.796392)
		(width 0.089408)
		(layer "In9.Cu")
		(net "PWRGD_PVCCMCP_CPU1")
	)
	(segment
		(start 168.88333 -59.35599)
		(end 168.88333 -51.200558)
		(width 0.089408)
		(layer "In11.Cu")
		(net "PWRGD_PVCCMCP_CPU1")
	)
	(segment
		(start 177.03546 -72.009)
		(end 176.61382 -71.58736)
		(width 0.089408)
		(layer "In11.Cu")
		(net "PWRGD_PVCCMCP_CPU1")
	)
	(segment
		(start 359.678986 -51.455828)
		(end 357.317548 -49.09439)
		(width 0.089408)
		(layer "In11.Cu")
		(net "PWRGD_PVCCMCP_CPU1")
	)
	(segment
		(start 179.59324 -84.29244)
		(end 179.59324 -81.67116)
		(width 0.089408)
		(layer "In11.Cu")
		(net "PWRGD_PVCCMCP_CPU1")
	)
	(segment
		(start 183.863996 -47.730664)
		(end 184.121552 -47.98822)
		(width 0.089408)
		(layer "In11.Cu")
		(net "PWRGD_PVCCMCP_CPU1")
	)
	(segment
		(start 176.61382 -71.58736)
		(end 176.61382 -70.0405)
		(width 0.089408)
		(layer "In11.Cu")
		(net "PWRGD_PVCCMCP_CPU1")
	)
	(segment
		(start 187.9219 -109.2835)
		(end 187.9219 -109.0295)
		(width 0.089408)
		(layer "In11.Cu")
		(net "PWRGD_PVCCMCP_CPU1")
	)
	(segment
		(start 366.461294 -55.261256)
		(end 364.723426 -55.261256)
		(width 0.089408)
		(layer "In11.Cu")
		(net "PWRGD_PVCCMCP_CPU1")
	)
	(segment
		(start 323.466206 -43.786044)
		(end 321.102736 -43.786044)
		(width 0.089408)
		(layer "In11.Cu")
		(net "PWRGD_PVCCMCP_CPU1")
	)
	(segment
		(start 364.723426 -55.261256)
		(end 360.917998 -51.455828)
		(width 0.089408)
		(layer "In11.Cu")
		(net "PWRGD_PVCCMCP_CPU1")
	)
	(segment
		(start 187.9219 -109.0295)
		(end 183.1594 -104.267)
		(width 0.089408)
		(layer "In11.Cu")
		(net "PWRGD_PVCCMCP_CPU1")
	)
	(segment
		(start 328.774552 -49.09439)
		(end 323.466206 -43.786044)
		(width 0.089408)
		(layer "In11.Cu")
		(net "PWRGD_PVCCMCP_CPU1")
	)
	(segment
		(start 169.322496 -59.795156)
		(end 168.88333 -59.35599)
		(width 0.089408)
		(layer "In11.Cu")
		(net "PWRGD_PVCCMCP_CPU1")
	)
	(segment
		(start 175.83531 -77.91323)
		(end 175.83531 -75.71613)
		(width 0.089408)
		(layer "In11.Cu")
		(net "PWRGD_PVCCMCP_CPU1")
	)
	(segment
		(start 357.317548 -49.09439)
		(end 328.774552 -49.09439)
		(width 0.089408)
		(layer "In11.Cu")
		(net "PWRGD_PVCCMCP_CPU1")
	)
	(segment
		(start 173.570646 -64.491108)
		(end 173.994826 -64.066928)
		(width 0.089408)
		(layer "In11.Cu")
		(net "PWRGD_PVCCMCP_CPU1")
	)
	(segment
		(start 374.18772 -63.01232)
		(end 374.18772 -62.090046)
		(width 0.089408)
		(layer "In11.Cu")
		(net "PWRGD_PVCCMCP_CPU1")
	)
	(segment
		(start 321.102736 -43.786044)
		(end 320.8782 -43.561508)
		(width 0.089408)
		(layer "In11.Cu")
		(net "PWRGD_PVCCMCP_CPU1")
	)
	(segment
		(start 173.570646 -68.76034)
		(end 173.570646 -64.491108)
		(width 0.089408)
		(layer "In11.Cu")
		(net "PWRGD_PVCCMCP_CPU1")
	)
	(segment
		(start 320.8782 -43.561508)
		(end 320.8782 -43.0403)
		(width 0.089408)
		(layer "In11.Cu")
		(net "PWRGD_PVCCMCP_CPU1")
	)
	(segment
		(start 173.994826 -62.36335)
		(end 171.426632 -59.795156)
		(width 0.089408)
		(layer "In11.Cu")
		(net "PWRGD_PVCCMCP_CPU1")
	)
	(segment
		(start 374.364504 -61.913262)
		(end 374.364504 -61.505338)
		(width 0.089408)
		(layer "In11.Cu")
		(net "PWRGD_PVCCMCP_CPU1")
	)
	(segment
		(start 183.1594 -87.8586)
		(end 179.59324 -84.29244)
		(width 0.089408)
		(layer "In11.Cu")
		(net "PWRGD_PVCCMCP_CPU1")
	)
	(segment
		(start 374.364504 -61.505338)
		(end 374.019572 -61.160406)
		(width 0.089408)
		(layer "In11.Cu")
		(net "PWRGD_PVCCMCP_CPU1")
	)
	(segment
		(start 179.59324 -81.67116)
		(end 175.83531 -77.91323)
		(width 0.089408)
		(layer "In11.Cu")
		(net "PWRGD_PVCCMCP_CPU1")
	)
	(segment
		(start 176.61382 -70.0405)
		(end 175.88992 -69.3166)
		(width 0.089408)
		(layer "In11.Cu")
		(net "PWRGD_PVCCMCP_CPU1")
	)
	(segment
		(start 374.420384 -65.203324)
		(end 374.0404 -64.82334)
		(width 0.089408)
		(layer "In11.Cu")
		(net "PWRGD_PVCCMCP_CPU1")
	)
	(segment
		(start 177.03546 -74.51598)
		(end 177.03546 -72.009)
		(width 0.089408)
		(layer "In11.Cu")
		(net "PWRGD_PVCCMCP_CPU1")
	)
	(segment
		(start 360.917998 -51.455828)
		(end 359.678986 -51.455828)
		(width 0.089408)
		(layer "In11.Cu")
		(net "PWRGD_PVCCMCP_CPU1")
	)
	(segment
		(start 190.119 -111.4806)
		(end 187.9219 -109.2835)
		(width 0.089408)
		(layer "In11.Cu")
		(net "PWRGD_PVCCMCP_CPU1")
	)
	(segment
		(start 372.360952 -61.160406)
		(end 366.461294 -55.261256)
		(width 0.089408)
		(layer "In11.Cu")
		(net "PWRGD_PVCCMCP_CPU1")
	)
	(segment
		(start 374.019572 -61.160406)
		(end 372.360952 -61.160406)
		(width 0.089408)
		(layer "In11.Cu")
		(net "PWRGD_PVCCMCP_CPU1")
	)
	(segment
		(start 174.126906 -69.3166)
		(end 173.570646 -68.76034)
		(width 0.089408)
		(layer "In11.Cu")
		(net "PWRGD_PVCCMCP_CPU1")
	)
	(segment
		(start 171.426632 -59.795156)
		(end 169.322496 -59.795156)
		(width 0.089408)
		(layer "In11.Cu")
		(net "PWRGD_PVCCMCP_CPU1")
	)
	(segment
		(start 183.1594 -104.267)
		(end 183.1594 -87.8586)
		(width 0.089408)
		(layer "In11.Cu")
		(net "PWRGD_PVCCMCP_CPU1")
	)
	(segment
		(start 374.0404 -64.82334)
		(end 374.0404 -63.15964)
		(width 0.089408)
		(layer "In11.Cu")
		(net "PWRGD_PVCCMCP_CPU1")
	)
	(segment
		(start 175.88992 -69.3166)
		(end 174.126906 -69.3166)
		(width 0.089408)
		(layer "In11.Cu")
		(net "PWRGD_PVCCMCP_CPU1")
	)
	(segment
		(start 175.83531 -75.71613)
		(end 177.03546 -74.51598)
		(width 0.089408)
		(layer "In11.Cu")
		(net "PWRGD_PVCCMCP_CPU1")
	)
	(segment
		(start 173.994826 -64.066928)
		(end 173.994826 -62.36335)
		(width 0.089408)
		(layer "In11.Cu")
		(net "PWRGD_PVCCMCP_CPU1")
	)
	(segment
		(start 168.88333 -51.200558)
		(end 172.353224 -47.730664)
		(width 0.089408)
		(layer "In11.Cu")
		(net "PWRGD_PVCCMCP_CPU1")
	)
	(segment
		(start 172.353224 -47.730664)
		(end 183.863996 -47.730664)
		(width 0.089408)
		(layer "In11.Cu")
		(net "PWRGD_PVCCMCP_CPU1")
	)
	(segment
		(start 374.0404 -63.15964)
		(end 374.18772 -63.01232)
		(width 0.089408)
		(layer "In11.Cu")
		(net "PWRGD_PVCCMCP_CPU1")
	)
	(segment
		(start 374.18772 -62.090046)
		(end 374.364504 -61.913262)
		(width 0.089408)
		(layer "In11.Cu")
		(net "PWRGD_PVCCMCP_CPU1")
	)
	(segment
		(start 365.732314 -90.8685)
		(end 368.91722 -90.8685)
		(width 0.10795)
		(layer "F.Cu")
		(net "PWRGD_PVCCMCP_CPU0")
	)
	(segment
		(start 356.180898 -114.043968)
		(end 359.5243 -114.043968)
		(width 0.10795)
		(layer "F.Cu")
		(net "PWRGD_PVCCMCP_CPU0")
	)
	(segment
		(start 364.2106 -97.917)
		(end 363.982 -97.6884)
		(width 0.10795)
		(layer "F.Cu")
		(net "PWRGD_PVCCMCP_CPU0")
	)
	(segment
		(start 369.125754 -90.659966)
		(end 369.125754 -90.595704)
		(width 0.10795)
		(layer "F.Cu")
		(net "PWRGD_PVCCMCP_CPU0")
	)
	(segment
		(start 364.4138 -98.1202)
		(end 364.2106 -97.917)
		(width 0.10795)
		(layer "F.Cu")
		(net "PWRGD_PVCCMCP_CPU0")
	)
	(segment
		(start 360.380788 -113.18748)
		(end 360.380788 -111.510572)
		(width 0.10795)
		(layer "F.Cu")
		(net "PWRGD_PVCCMCP_CPU0")
	)
	(segment
		(start 353.724972 -111.74095)
		(end 353.724972 -112.234726)
		(width 0.10795)
		(layer "F.Cu")
		(net "PWRGD_PVCCMCP_CPU0")
	)
	(segment
		(start 359.5243 -114.043968)
		(end 360.380788 -113.18748)
		(width 0.10795)
		(layer "F.Cu")
		(net "PWRGD_PVCCMCP_CPU0")
	)
	(segment
		(start 368.91722 -90.8685)
		(end 369.125754 -90.659966)
		(width 0.10795)
		(layer "F.Cu")
		(net "PWRGD_PVCCMCP_CPU0")
	)
	(segment
		(start 363.852206 -104.9528)
		(end 364.4138 -104.391206)
		(width 0.10795)
		(layer "F.Cu")
		(net "PWRGD_PVCCMCP_CPU0")
	)
	(segment
		(start 364.4138 -104.391206)
		(end 364.4138 -98.1202)
		(width 0.10795)
		(layer "F.Cu")
		(net "PWRGD_PVCCMCP_CPU0")
	)
	(segment
		(start 353.724972 -112.234726)
		(end 354.139246 -112.649)
		(width 0.10795)
		(layer "F.Cu")
		(net "PWRGD_PVCCMCP_CPU0")
	)
	(segment
		(start 354.139246 -112.649)
		(end 354.78593 -112.649)
		(width 0.10795)
		(layer "F.Cu")
		(net "PWRGD_PVCCMCP_CPU0")
	)
	(segment
		(start 360.380788 -111.510572)
		(end 363.852206 -108.039154)
		(width 0.10795)
		(layer "F.Cu")
		(net "PWRGD_PVCCMCP_CPU0")
	)
	(segment
		(start 354.78593 -112.649)
		(end 356.180898 -114.043968)
		(width 0.10795)
		(layer "F.Cu")
		(net "PWRGD_PVCCMCP_CPU0")
	)
	(segment
		(start 375.944892 -79.094838)
		(end 375.545096 -78.695042)
		(width 0.10795)
		(layer "F.Cu")
		(net "PWRGD_PVCCMCP_CPU0")
	)
	(segment
		(start 363.852206 -108.039154)
		(end 363.852206 -104.9528)
		(width 0.10795)
		(layer "F.Cu")
		(net "PWRGD_PVCCMCP_CPU0")
	)
	(segment
		(start 363.982 -97.6884)
		(end 363.982 -92.618814)
		(width 0.10795)
		(layer "F.Cu")
		(net "PWRGD_PVCCMCP_CPU0")
	)
	(segment
		(start 363.982 -92.618814)
		(end 365.732314 -90.8685)
		(width 0.10795)
		(layer "F.Cu")
		(net "PWRGD_PVCCMCP_CPU0")
	)
	(via
		(at 369.125754 -90.595704)
		(size 0.508)
		(drill 0.254)
		(layers "F.Cu" "B.Cu")
		(net "PWRGD_PVCCMCP_CPU0")
	)
	(via
		(at 364.2106 -97.917)
		(size 0.762)
		(drill 0.381)
		(layers "F.Cu" "B.Cu")
		(net "PWRGD_PVCCMCP_CPU0")
	)
	(via
		(at 375.944892 -79.094838)
		(size 0.4572)
		(drill 0.2032)
		(layers "F.Cu" "B.Cu")
		(net "PWRGD_PVCCMCP_CPU0")
	)
	(segment
		(start 375.508012 -79.587852)
		(end 375.944892 -79.150972)
		(width 0.089408)
		(layer "In9.Cu")
		(net "PWRGD_PVCCMCP_CPU0")
	)
	(segment
		(start 369.125754 -90.595704)
		(end 369.125754 -90.481912)
		(width 0.089408)
		(layer "In9.Cu")
		(net "PWRGD_PVCCMCP_CPU0")
	)
	(segment
		(start 369.125754 -90.481912)
		(end 369.690904 -89.916762)
		(width 0.089408)
		(layer "In9.Cu")
		(net "PWRGD_PVCCMCP_CPU0")
	)
	(segment
		(start 369.690904 -89.265506)
		(end 370.464842 -88.491568)
		(width 0.089408)
		(layer "In9.Cu")
		(net "PWRGD_PVCCMCP_CPU0")
	)
	(segment
		(start 371.113304 -88.491568)
		(end 371.358668 -88.246204)
		(width 0.089408)
		(layer "In9.Cu")
		(net "PWRGD_PVCCMCP_CPU0")
	)
	(segment
		(start 373.50827 -88.246204)
		(end 375.055384 -86.69909)
		(width 0.089408)
		(layer "In9.Cu")
		(net "PWRGD_PVCCMCP_CPU0")
	)
	(segment
		(start 375.918476 -80.845914)
		(end 375.508012 -80.43545)
		(width 0.089408)
		(layer "In9.Cu")
		(net "PWRGD_PVCCMCP_CPU0")
	)
	(segment
		(start 370.464842 -88.491568)
		(end 371.113304 -88.491568)
		(width 0.089408)
		(layer "In9.Cu")
		(net "PWRGD_PVCCMCP_CPU0")
	)
	(segment
		(start 375.944892 -79.150972)
		(end 375.944892 -79.094838)
		(width 0.089408)
		(layer "In9.Cu")
		(net "PWRGD_PVCCMCP_CPU0")
	)
	(segment
		(start 375.055384 -82.018378)
		(end 375.918476 -81.155286)
		(width 0.089408)
		(layer "In9.Cu")
		(net "PWRGD_PVCCMCP_CPU0")
	)
	(segment
		(start 371.358668 -88.246204)
		(end 373.50827 -88.246204)
		(width 0.089408)
		(layer "In9.Cu")
		(net "PWRGD_PVCCMCP_CPU0")
	)
	(segment
		(start 369.690904 -89.916762)
		(end 369.690904 -89.265506)
		(width 0.089408)
		(layer "In9.Cu")
		(net "PWRGD_PVCCMCP_CPU0")
	)
	(segment
		(start 375.918476 -81.155286)
		(end 375.918476 -80.845914)
		(width 0.089408)
		(layer "In9.Cu")
		(net "PWRGD_PVCCMCP_CPU0")
	)
	(segment
		(start 375.508012 -80.43545)
		(end 375.508012 -79.587852)
		(width 0.089408)
		(layer "In9.Cu")
		(net "PWRGD_PVCCMCP_CPU0")
	)
	(segment
		(start 375.055384 -86.69909)
		(end 375.055384 -82.018378)
		(width 0.089408)
		(layer "In9.Cu")
		(net "PWRGD_PVCCMCP_CPU0")
	)
	(segment
		(start 182.4482 -119.13489)
		(end 184.2008 -117.38229)
		(width 0.10795)
		(layer "F.Cu")
		(net "PWRGD_PVCCIOMCP_CPU1")
	)
	(segment
		(start 181.58968 -127.588772)
		(end 181.58968 -123.2916)
		(width 0.10795)
		(layer "F.Cu")
		(net "PWRGD_PVCCIOMCP_CPU1")
	)
	(segment
		(start 181.58968 -123.2916)
		(end 182.4482 -122.43308)
		(width 0.10795)
		(layer "F.Cu")
		(net "PWRGD_PVCCIOMCP_CPU1")
	)
	(segment
		(start 181.61 -128.8542)
		(end 181.660292 -128.8542)
		(width 0.10795)
		(layer "F.Cu")
		(net "PWRGD_PVCCIOMCP_CPU1")
	)
	(segment
		(start 184.2008 -114.816636)
		(end 183.665114 -114.28095)
		(width 0.10795)
		(layer "F.Cu")
		(net "PWRGD_PVCCIOMCP_CPU1")
	)
	(segment
		(start 181.660292 -128.8542)
		(end 181.663594 -128.857502)
		(width 0.10795)
		(layer "F.Cu")
		(net "PWRGD_PVCCIOMCP_CPU1")
	)
	(segment
		(start 184.2008 -117.38229)
		(end 184.2008 -114.816636)
		(width 0.10795)
		(layer "F.Cu")
		(net "PWRGD_PVCCIOMCP_CPU1")
	)
	(segment
		(start 182.261002 -128.660906)
		(end 182.261002 -128.260094)
		(width 0.10795)
		(layer "F.Cu")
		(net "PWRGD_PVCCIOMCP_CPU1")
	)
	(segment
		(start 182.4482 -122.43308)
		(end 182.4482 -119.13489)
		(width 0.10795)
		(layer "F.Cu")
		(net "PWRGD_PVCCIOMCP_CPU1")
	)
	(segment
		(start 181.663594 -128.857502)
		(end 182.064406 -128.857502)
		(width 0.10795)
		(layer "F.Cu")
		(net "PWRGD_PVCCIOMCP_CPU1")
	)
	(segment
		(start 181.1528 -128.397)
		(end 181.61 -128.8542)
		(width 0.10795)
		(layer "F.Cu")
		(net "PWRGD_PVCCIOMCP_CPU1")
	)
	(segment
		(start 182.261002 -128.260094)
		(end 181.58968 -127.588772)
		(width 0.10795)
		(layer "F.Cu")
		(net "PWRGD_PVCCIOMCP_CPU1")
	)
	(segment
		(start 182.064406 -128.857502)
		(end 182.261002 -128.660906)
		(width 0.10795)
		(layer "F.Cu")
		(net "PWRGD_PVCCIOMCP_CPU1")
	)
	(segment
		(start 375.545096 -81.0006)
		(end 375.545096 -80.294988)
		(width 0.10795)
		(layer "F.Cu")
		(net "PWRGD_PVCCIOMCP_CPU1")
	)
	(via
		(at 359.664 -85.8774)
		(size 0.508)
		(drill 0.254)
		(layers "F.Cu" "B.Cu")
		(net "PWRGD_PVCCIOMCP_CPU1")
	)
	(via
		(at 181.1528 -128.397)
		(size 0.508)
		(drill 0.254)
		(layers "F.Cu" "B.Cu")
		(net "PWRGD_PVCCIOMCP_CPU1")
	)
	(via
		(at 354.59289 -130.775202)
		(size 0.508)
		(drill 0.254)
		(layers "F.Cu" "B.Cu")
		(net "PWRGD_PVCCIOMCP_CPU1")
	)
	(via
		(at 362.160312 -88.373712)
		(size 0.6604)
		(drill 0.3302)
		(layers "F.Cu" "B.Cu")
		(net "PWRGD_PVCCIOMCP_CPU1")
	)
	(via
		(at 375.545096 -81.0006)
		(size 0.4572)
		(drill 0.2032)
		(layers "F.Cu" "B.Cu")
		(net "PWRGD_PVCCIOMCP_CPU1")
	)
	(via
		(at 373.126 -87.8459)
		(size 0.508)
		(drill 0.254)
		(layers "F.Cu" "B.Cu")
		(net "PWRGD_PVCCIOMCP_CPU1")
	)
	(segment
		(start 359.664 -85.8774)
		(end 362.160312 -88.373712)
		(width 0.10795)
		(layer "B.Cu")
		(net "PWRGD_PVCCIOMCP_CPU1")
	)
	(segment
		(start 373.126 -87.8459)
		(end 372.787164 -87.8459)
		(width 0.10795)
		(layer "B.Cu")
		(net "PWRGD_PVCCIOMCP_CPU1")
	)
	(segment
		(start 370.286534 -90.08872)
		(end 369.303554 -91.0717)
		(width 0.10795)
		(layer "B.Cu")
		(net "PWRGD_PVCCIOMCP_CPU1")
	)
	(segment
		(start 371.3734 -89.259664)
		(end 371.3734 -89.8398)
		(width 0.10795)
		(layer "B.Cu")
		(net "PWRGD_PVCCIOMCP_CPU1")
	)
	(segment
		(start 372.787164 -87.8459)
		(end 371.3734 -89.259664)
		(width 0.10795)
		(layer "B.Cu")
		(net "PWRGD_PVCCIOMCP_CPU1")
	)
	(segment
		(start 369.303554 -91.0717)
		(end 364.8583 -91.0717)
		(width 0.10795)
		(layer "B.Cu")
		(net "PWRGD_PVCCIOMCP_CPU1")
	)
	(segment
		(start 371.12448 -90.08872)
		(end 370.286534 -90.08872)
		(width 0.10795)
		(layer "B.Cu")
		(net "PWRGD_PVCCIOMCP_CPU1")
	)
	(segment
		(start 364.8583 -91.0717)
		(end 362.160312 -88.373712)
		(width 0.10795)
		(layer "B.Cu")
		(net "PWRGD_PVCCIOMCP_CPU1")
	)
	(segment
		(start 371.3734 -89.8398)
		(end 371.12448 -90.08872)
		(width 0.10795)
		(layer "B.Cu")
		(net "PWRGD_PVCCIOMCP_CPU1")
	)
	(segment
		(start 346.636594 -116.854224)
		(end 346.056712 -116.274342)
		(width 0.089408)
		(layer "In4.Cu")
		(net "PWRGD_PVCCIOMCP_CPU1")
	)
	(segment
		(start 346.636594 -120.714516)
		(end 346.636594 -116.854224)
		(width 0.089408)
		(layer "In4.Cu")
		(net "PWRGD_PVCCIOMCP_CPU1")
	)
	(segment
		(start 348.810834 -105.9434)
		(end 351.728278 -105.9434)
		(width 0.089408)
		(layer "In4.Cu")
		(net "PWRGD_PVCCIOMCP_CPU1")
	)
	(segment
		(start 346.056712 -116.274342)
		(end 346.056712 -108.697522)
		(width 0.089408)
		(layer "In4.Cu")
		(net "PWRGD_PVCCIOMCP_CPU1")
	)
	(segment
		(start 354.017072 -130.199384)
		(end 349.353632 -130.199384)
		(width 0.089408)
		(layer "In4.Cu")
		(net "PWRGD_PVCCIOMCP_CPU1")
	)
	(segment
		(start 354.59289 -130.775202)
		(end 354.017072 -130.199384)
		(width 0.089408)
		(layer "In4.Cu")
		(net "PWRGD_PVCCIOMCP_CPU1")
	)
	(segment
		(start 359.664 -87.9221)
		(end 359.664 -85.8774)
		(width 0.089408)
		(layer "In4.Cu")
		(net "PWRGD_PVCCIOMCP_CPU1")
	)
	(segment
		(start 346.056712 -108.697522)
		(end 348.810834 -105.9434)
		(width 0.089408)
		(layer "In4.Cu")
		(net "PWRGD_PVCCIOMCP_CPU1")
	)
	(segment
		(start 357.928926 -89.657174)
		(end 359.664 -87.9221)
		(width 0.089408)
		(layer "In4.Cu")
		(net "PWRGD_PVCCIOMCP_CPU1")
	)
	(segment
		(start 357.928926 -99.742752)
		(end 357.928926 -89.657174)
		(width 0.089408)
		(layer "In4.Cu")
		(net "PWRGD_PVCCIOMCP_CPU1")
	)
	(segment
		(start 345.17711 -126.022862)
		(end 345.17711 -122.174)
		(width 0.089408)
		(layer "In4.Cu")
		(net "PWRGD_PVCCIOMCP_CPU1")
	)
	(segment
		(start 345.17711 -122.174)
		(end 346.636594 -120.714516)
		(width 0.089408)
		(layer "In4.Cu")
		(net "PWRGD_PVCCIOMCP_CPU1")
	)
	(segment
		(start 349.353632 -130.199384)
		(end 345.17711 -126.022862)
		(width 0.089408)
		(layer "In4.Cu")
		(net "PWRGD_PVCCIOMCP_CPU1")
	)
	(segment
		(start 351.728278 -105.9434)
		(end 357.928926 -99.742752)
		(width 0.089408)
		(layer "In4.Cu")
		(net "PWRGD_PVCCIOMCP_CPU1")
	)
	(segment
		(start 260.342888 -136.255252)
		(end 260.985762 -136.255252)
		(width 0.089408)
		(layer "In9.Cu")
		(net "PWRGD_PVCCIOMCP_CPU1")
	)
	(segment
		(start 331.099414 -130.620262)
		(end 332.509622 -129.210054)
		(width 0.089408)
		(layer "In9.Cu")
		(net "PWRGD_PVCCIOMCP_CPU1")
	)
	(segment
		(start 260.985762 -136.255252)
		(end 262.372094 -137.641584)
		(width 0.089408)
		(layer "In9.Cu")
		(net "PWRGD_PVCCIOMCP_CPU1")
	)
	(segment
		(start 347.747844 -129.797556)
		(end 348.150688 -129.394712)
		(width 0.089408)
		(layer "In9.Cu")
		(net "PWRGD_PVCCIOMCP_CPU1")
	)
	(segment
		(start 353.321112 -129.515362)
		(end 353.333812 -129.528062)
		(width 0.089408)
		(layer "In9.Cu")
		(net "PWRGD_PVCCIOMCP_CPU1")
	)
	(segment
		(start 323.215 -136.21004)
		(end 323.215 -135.567674)
		(width 0.089408)
		(layer "In9.Cu")
		(net "PWRGD_PVCCIOMCP_CPU1")
	)
	(segment
		(start 342.213438 -125.4887)
		(end 343.39403 -126.669292)
		(width 0.089408)
		(layer "In9.Cu")
		(net "PWRGD_PVCCIOMCP_CPU1")
	)
	(segment
		(start 181.1528 -128.397)
		(end 181.7116 -128.9558)
		(width 0.089408)
		(layer "In9.Cu")
		(net "PWRGD_PVCCIOMCP_CPU1")
	)
	(segment
		(start 373.638318 -87.8459)
		(end 373.126 -87.8459)
		(width 0.089408)
		(layer "In9.Cu")
		(net "PWRGD_PVCCIOMCP_CPU1")
	)
	(segment
		(start 181.934866 -128.9558)
		(end 182.135526 -128.75514)
		(width 0.089408)
		(layer "In9.Cu")
		(net "PWRGD_PVCCIOMCP_CPU1")
	)
	(segment
		(start 181.7116 -128.9558)
		(end 181.934866 -128.9558)
		(width 0.089408)
		(layer "In9.Cu")
		(net "PWRGD_PVCCIOMCP_CPU1")
	)
	(segment
		(start 259.098034 -137.500106)
		(end 260.342888 -136.255252)
		(width 0.089408)
		(layer "In9.Cu")
		(net "PWRGD_PVCCIOMCP_CPU1")
	)
	(segment
		(start 375.545096 -81.0006)
		(end 375.545096 -81.169764)
		(width 0.089408)
		(layer "In9.Cu")
		(net "PWRGD_PVCCIOMCP_CPU1")
	)
	(segment
		(start 188.358272 -132.950712)
		(end 189.76721 -132.950712)
		(width 0.089408)
		(layer "In9.Cu")
		(net "PWRGD_PVCCIOMCP_CPU1")
	)
	(segment
		(start 338.498942 -125.4887)
		(end 342.213438 -125.4887)
		(width 0.089408)
		(layer "In9.Cu")
		(net "PWRGD_PVCCIOMCP_CPU1")
	)
	(segment
		(start 329.804268 -132.982462)
		(end 331.099414 -131.687316)
		(width 0.089408)
		(layer "In9.Cu")
		(net "PWRGD_PVCCIOMCP_CPU1")
	)
	(segment
		(start 348.150688 -129.394712)
		(end 350.052386 -129.394712)
		(width 0.089408)
		(layer "In9.Cu")
		(net "PWRGD_PVCCIOMCP_CPU1")
	)
	(segment
		(start 350.052386 -129.394712)
		(end 350.173036 -129.515362)
		(width 0.089408)
		(layer "In9.Cu")
		(net "PWRGD_PVCCIOMCP_CPU1")
	)
	(segment
		(start 331.099414 -131.687316)
		(end 331.099414 -130.620262)
		(width 0.089408)
		(layer "In9.Cu")
		(net "PWRGD_PVCCIOMCP_CPU1")
	)
	(segment
		(start 182.135526 -128.75514)
		(end 183.27878 -128.75514)
		(width 0.089408)
		(layer "In9.Cu")
		(net "PWRGD_PVCCIOMCP_CPU1")
	)
	(segment
		(start 374.762776 -86.721442)
		(end 373.638318 -87.8459)
		(width 0.089408)
		(layer "In9.Cu")
		(net "PWRGD_PVCCIOMCP_CPU1")
	)
	(segment
		(start 353.333812 -129.528062)
		(end 353.34575 -129.528062)
		(width 0.089408)
		(layer "In9.Cu")
		(net "PWRGD_PVCCIOMCP_CPU1")
	)
	(segment
		(start 183.27878 -128.75514)
		(end 183.98744 -129.4638)
		(width 0.089408)
		(layer "In9.Cu")
		(net "PWRGD_PVCCIOMCP_CPU1")
	)
	(segment
		(start 374.762776 -81.952084)
		(end 374.762776 -86.721442)
		(width 0.089408)
		(layer "In9.Cu")
		(net "PWRGD_PVCCIOMCP_CPU1")
	)
	(segment
		(start 185.95848 -129.4638)
		(end 186.436 -129.94132)
		(width 0.089408)
		(layer "In9.Cu")
		(net "PWRGD_PVCCIOMCP_CPU1")
	)
	(segment
		(start 321.783456 -137.641584)
		(end 323.215 -136.21004)
		(width 0.089408)
		(layer "In9.Cu")
		(net "PWRGD_PVCCIOMCP_CPU1")
	)
	(segment
		(start 325.800212 -132.982462)
		(end 329.804268 -132.982462)
		(width 0.089408)
		(layer "In9.Cu")
		(net "PWRGD_PVCCIOMCP_CPU1")
	)
	(segment
		(start 183.98744 -129.4638)
		(end 185.95848 -129.4638)
		(width 0.089408)
		(layer "In9.Cu")
		(net "PWRGD_PVCCIOMCP_CPU1")
	)
	(segment
		(start 323.215 -135.567674)
		(end 325.800212 -132.982462)
		(width 0.089408)
		(layer "In9.Cu")
		(net "PWRGD_PVCCIOMCP_CPU1")
	)
	(segment
		(start 343.39403 -128.992884)
		(end 344.198702 -129.797556)
		(width 0.089408)
		(layer "In9.Cu")
		(net "PWRGD_PVCCIOMCP_CPU1")
	)
	(segment
		(start 332.509622 -129.210054)
		(end 334.777588 -129.210054)
		(width 0.089408)
		(layer "In9.Cu")
		(net "PWRGD_PVCCIOMCP_CPU1")
	)
	(segment
		(start 191.267842 -134.536942)
		(end 194.231006 -137.500106)
		(width 0.089408)
		(layer "In9.Cu")
		(net "PWRGD_PVCCIOMCP_CPU1")
	)
	(segment
		(start 344.198702 -129.797556)
		(end 347.747844 -129.797556)
		(width 0.089408)
		(layer "In9.Cu")
		(net "PWRGD_PVCCIOMCP_CPU1")
	)
	(segment
		(start 186.436 -129.94132)
		(end 186.436 -131.02844)
		(width 0.089408)
		(layer "In9.Cu")
		(net "PWRGD_PVCCIOMCP_CPU1")
	)
	(segment
		(start 189.76721 -132.950712)
		(end 191.267842 -134.451344)
		(width 0.089408)
		(layer "In9.Cu")
		(net "PWRGD_PVCCIOMCP_CPU1")
	)
	(segment
		(start 343.39403 -126.669292)
		(end 343.39403 -128.992884)
		(width 0.089408)
		(layer "In9.Cu")
		(net "PWRGD_PVCCIOMCP_CPU1")
	)
	(segment
		(start 262.372094 -137.641584)
		(end 321.783456 -137.641584)
		(width 0.089408)
		(layer "In9.Cu")
		(net "PWRGD_PVCCIOMCP_CPU1")
	)
	(segment
		(start 353.34575 -129.528062)
		(end 354.59289 -130.775202)
		(width 0.089408)
		(layer "In9.Cu")
		(net "PWRGD_PVCCIOMCP_CPU1")
	)
	(segment
		(start 186.436 -131.02844)
		(end 188.358272 -132.950712)
		(width 0.089408)
		(layer "In9.Cu")
		(net "PWRGD_PVCCIOMCP_CPU1")
	)
	(segment
		(start 375.545096 -81.169764)
		(end 374.762776 -81.952084)
		(width 0.089408)
		(layer "In9.Cu")
		(net "PWRGD_PVCCIOMCP_CPU1")
	)
	(segment
		(start 191.267842 -134.451344)
		(end 191.267842 -134.536942)
		(width 0.089408)
		(layer "In9.Cu")
		(net "PWRGD_PVCCIOMCP_CPU1")
	)
	(segment
		(start 194.231006 -137.500106)
		(end 259.098034 -137.500106)
		(width 0.089408)
		(layer "In9.Cu")
		(net "PWRGD_PVCCIOMCP_CPU1")
	)
	(segment
		(start 350.173036 -129.515362)
		(end 353.321112 -129.515362)
		(width 0.089408)
		(layer "In9.Cu")
		(net "PWRGD_PVCCIOMCP_CPU1")
	)
	(segment
		(start 334.777588 -129.210054)
		(end 338.498942 -125.4887)
		(width 0.089408)
		(layer "In9.Cu")
		(net "PWRGD_PVCCIOMCP_CPU1")
	)
	(segment
		(start 362.6358 -107.100624)
		(end 362.6358 -91.7194)
		(width 0.10795)
		(layer "F.Cu")
		(net "PWRGD_P1V8MCP_CPU0")
	)
	(segment
		(start 364.415832 -89.711022)
		(end 367.415318 -89.711022)
		(width 0.10795)
		(layer "F.Cu")
		(net "PWRGD_P1V8MCP_CPU0")
	)
	(segment
		(start 357.951532 -111.0488)
		(end 358.687624 -111.0488)
		(width 0.10795)
		(layer "F.Cu")
		(net "PWRGD_P1V8MCP_CPU0")
	)
	(segment
		(start 347.38945 -114.28095)
		(end 348.0054 -113.665)
		(width 0.10795)
		(layer "F.Cu")
		(net "PWRGD_P1V8MCP_CPU0")
	)
	(segment
		(start 367.415318 -89.711022)
		(end 367.71199 -89.41435)
		(width 0.10795)
		(layer "F.Cu")
		(net "PWRGD_P1V8MCP_CPU0")
	)
	(segment
		(start 362.6358 -91.7194)
		(end 362.6358 -91.491054)
		(width 0.10795)
		(layer "F.Cu")
		(net "PWRGD_P1V8MCP_CPU0")
	)
	(segment
		(start 358.687624 -111.0488)
		(end 362.6358 -107.100624)
		(width 0.10795)
		(layer "F.Cu")
		(net "PWRGD_P1V8MCP_CPU0")
	)
	(segment
		(start 357.68915 -111.311182)
		(end 357.951532 -111.0488)
		(width 0.10795)
		(layer "F.Cu")
		(net "PWRGD_P1V8MCP_CPU0")
	)
	(segment
		(start 362.6358 -91.491054)
		(end 364.415832 -89.711022)
		(width 0.10795)
		(layer "F.Cu")
		(net "PWRGD_P1V8MCP_CPU0")
	)
	(segment
		(start 367.145316 -70.295262)
		(end 367.545112 -70.695058)
		(width 0.1016)
		(layer "F.Cu")
		(net "PWRGD_P1V8MCP_CPU0")
	)
	(segment
		(start 347.374972 -114.28095)
		(end 347.38945 -114.28095)
		(width 0.10795)
		(layer "F.Cu")
		(net "PWRGD_P1V8MCP_CPU0")
	)
	(via
		(at 362.6358 -91.7194)
		(size 0.762)
		(drill 0.381)
		(layers "F.Cu" "B.Cu")
		(net "PWRGD_P1V8MCP_CPU0")
	)
	(via
		(at 357.68915 -111.311182)
		(size 0.508)
		(drill 0.254)
		(layers "F.Cu" "B.Cu")
		(net "PWRGD_P1V8MCP_CPU0")
	)
	(via
		(at 367.71199 -89.41435)
		(size 0.508)
		(drill 0.254)
		(layers "F.Cu" "B.Cu")
		(net "PWRGD_P1V8MCP_CPU0")
	)
	(via
		(at 367.145316 -70.295262)
		(size 0.4572)
		(drill 0.2032)
		(layers "F.Cu" "B.Cu")
		(net "PWRGD_P1V8MCP_CPU0")
	)
	(via
		(at 348.0054 -113.665)
		(size 0.508)
		(drill 0.254)
		(layers "F.Cu" "B.Cu")
		(net "PWRGD_P1V8MCP_CPU0")
	)
	(segment
		(start 357.39451 -111.379)
		(end 357.621332 -111.379)
		(width 0.089408)
		(layer "In9.Cu")
		(net "PWRGD_P1V8MCP_CPU0")
	)
	(segment
		(start 348.550992 -112.02416)
		(end 348.87916 -111.695992)
		(width 0.089408)
		(layer "In9.Cu")
		(net "PWRGD_P1V8MCP_CPU0")
	)
	(segment
		(start 352.726752 -111.695992)
		(end 353.424744 -110.998)
		(width 0.089408)
		(layer "In9.Cu")
		(net "PWRGD_P1V8MCP_CPU0")
	)
	(segment
		(start 348.0054 -113.665)
		(end 348.550992 -113.119408)
		(width 0.089408)
		(layer "In9.Cu")
		(net "PWRGD_P1V8MCP_CPU0")
	)
	(segment
		(start 357.01351 -110.998)
		(end 357.39451 -111.379)
		(width 0.089408)
		(layer "In9.Cu")
		(net "PWRGD_P1V8MCP_CPU0")
	)
	(segment
		(start 357.621332 -111.379)
		(end 357.68915 -111.311182)
		(width 0.089408)
		(layer "In9.Cu")
		(net "PWRGD_P1V8MCP_CPU0")
	)
	(segment
		(start 348.87916 -111.695992)
		(end 352.726752 -111.695992)
		(width 0.089408)
		(layer "In9.Cu")
		(net "PWRGD_P1V8MCP_CPU0")
	)
	(segment
		(start 348.550992 -113.119408)
		(end 348.550992 -112.02416)
		(width 0.089408)
		(layer "In9.Cu")
		(net "PWRGD_P1V8MCP_CPU0")
	)
	(segment
		(start 353.424744 -110.998)
		(end 357.01351 -110.998)
		(width 0.089408)
		(layer "In9.Cu")
		(net "PWRGD_P1V8MCP_CPU0")
	)
	(segment
		(start 366.828578 -70.612)
		(end 367.145316 -70.295262)
		(width 0.089408)
		(layer "In11.Cu")
		(net "PWRGD_P1V8MCP_CPU0")
	)
	(segment
		(start 366.760506 -78.448916)
		(end 366.760506 -73.027032)
		(width 0.089408)
		(layer "In11.Cu")
		(net "PWRGD_P1V8MCP_CPU0")
	)
	(segment
		(start 366.300258 -70.612)
		(end 366.828578 -70.612)
		(width 0.089408)
		(layer "In11.Cu")
		(net "PWRGD_P1V8MCP_CPU0")
	)
	(segment
		(start 366.25149 -83.117944)
		(end 366.25149 -81.76895)
		(width 0.089408)
		(layer "In11.Cu")
		(net "PWRGD_P1V8MCP_CPU0")
	)
	(segment
		(start 366.248696 -83.120738)
		(end 366.25149 -83.117944)
		(width 0.089408)
		(layer "In11.Cu")
		(net "PWRGD_P1V8MCP_CPU0")
	)
	(segment
		(start 367.71199 -89.41435)
		(end 367.71199 -88.361774)
		(width 0.089408)
		(layer "In11.Cu")
		(net "PWRGD_P1V8MCP_CPU0")
	)
	(segment
		(start 365.61522 -80.08493)
		(end 365.95304 -79.74711)
		(width 0.089408)
		(layer "In11.Cu")
		(net "PWRGD_P1V8MCP_CPU0")
	)
	(segment
		(start 366.531906 -78.677516)
		(end 366.760506 -78.448916)
		(width 0.089408)
		(layer "In11.Cu")
		(net "PWRGD_P1V8MCP_CPU0")
	)
	(segment
		(start 366.760506 -73.027032)
		(end 365.960152 -72.226678)
		(width 0.089408)
		(layer "In11.Cu")
		(net "PWRGD_P1V8MCP_CPU0")
	)
	(segment
		(start 365.95304 -79.74711)
		(end 365.95304 -78.960726)
		(width 0.089408)
		(layer "In11.Cu")
		(net "PWRGD_P1V8MCP_CPU0")
	)
	(segment
		(start 366.192308 -78.721458)
		(end 366.23625 -78.677516)
		(width 0.089408)
		(layer "In11.Cu")
		(net "PWRGD_P1V8MCP_CPU0")
	)
	(segment
		(start 366.25149 -81.76895)
		(end 365.61522 -81.13268)
		(width 0.089408)
		(layer "In11.Cu")
		(net "PWRGD_P1V8MCP_CPU0")
	)
	(segment
		(start 366.620044 -87.269828)
		(end 366.620044 -83.885532)
		(width 0.089408)
		(layer "In11.Cu")
		(net "PWRGD_P1V8MCP_CPU0")
	)
	(segment
		(start 365.971836 -78.94193)
		(end 365.971836 -78.940152)
		(width 0.089408)
		(layer "In11.Cu")
		(net "PWRGD_P1V8MCP_CPU0")
	)
	(segment
		(start 366.25149 -83.455256)
		(end 366.248696 -83.452462)
		(width 0.089408)
		(layer "In11.Cu")
		(net "PWRGD_P1V8MCP_CPU0")
	)
	(segment
		(start 366.25149 -83.516978)
		(end 366.25149 -83.455256)
		(width 0.089408)
		(layer "In11.Cu")
		(net "PWRGD_P1V8MCP_CPU0")
	)
	(segment
		(start 366.23625 -78.677516)
		(end 366.531906 -78.677516)
		(width 0.089408)
		(layer "In11.Cu")
		(net "PWRGD_P1V8MCP_CPU0")
	)
	(segment
		(start 365.960152 -70.952106)
		(end 366.300258 -70.612)
		(width 0.089408)
		(layer "In11.Cu")
		(net "PWRGD_P1V8MCP_CPU0")
	)
	(segment
		(start 365.95304 -78.960726)
		(end 365.971836 -78.94193)
		(width 0.089408)
		(layer "In11.Cu")
		(net "PWRGD_P1V8MCP_CPU0")
	)
	(segment
		(start 366.620044 -83.885532)
		(end 366.25149 -83.516978)
		(width 0.089408)
		(layer "In11.Cu")
		(net "PWRGD_P1V8MCP_CPU0")
	)
	(segment
		(start 366.19053 -78.721458)
		(end 366.192308 -78.721458)
		(width 0.089408)
		(layer "In11.Cu")
		(net "PWRGD_P1V8MCP_CPU0")
	)
	(segment
		(start 365.61522 -81.13268)
		(end 365.61522 -80.08493)
		(width 0.089408)
		(layer "In11.Cu")
		(net "PWRGD_P1V8MCP_CPU0")
	)
	(segment
		(start 367.71199 -88.361774)
		(end 366.620044 -87.269828)
		(width 0.089408)
		(layer "In11.Cu")
		(net "PWRGD_P1V8MCP_CPU0")
	)
	(segment
		(start 365.960152 -72.226678)
		(end 365.960152 -70.952106)
		(width 0.089408)
		(layer "In11.Cu")
		(net "PWRGD_P1V8MCP_CPU0")
	)
	(segment
		(start 365.971836 -78.940152)
		(end 366.19053 -78.721458)
		(width 0.089408)
		(layer "In11.Cu")
		(net "PWRGD_P1V8MCP_CPU0")
	)
	(segment
		(start 366.248696 -83.452462)
		(end 366.248696 -83.120738)
		(width 0.089408)
		(layer "In11.Cu")
		(net "PWRGD_P1V8MCP_CPU0")
	)
	(segment
		(start 285.7881 -84.136738)
		(end 286.3596 -84.136738)
		(width 0.254)
		(layer "F.Cu")
		(net "PVCCMCP_CPU0")
	)
	(segment
		(start 289.22218 -67.296538)
		(end 289.79368 -67.296538)
		(width 0.254)
		(layer "F.Cu")
		(net "PVCCMCP_CPU0")
	)
	(segment
		(start 287.50514 -90.080338)
		(end 288.07664 -90.080338)
		(width 0.254)
		(layer "F.Cu")
		(net "PVCCMCP_CPU0")
	)
	(segment
		(start 292.65626 -75.221338)
		(end 293.22776 -75.221338)
		(width 0.254)
		(layer "F.Cu")
		(net "PVCCMCP_CPU0")
	)
	(segment
		(start 285.7881 -68.287138)
		(end 286.283146 -68.782184)
		(width 0.254)
		(layer "F.Cu")
		(net "PVCCMCP_CPU0")
	)
	(segment
		(start 287.50514 -91.070938)
		(end 288.07664 -91.070938)
		(width 0.254)
		(layer "F.Cu")
		(net "PVCCMCP_CPU0")
	)
	(segment
		(start 290.93922 -68.287138)
		(end 291.51072 -68.287138)
		(width 0.254)
		(layer "F.Cu")
		(net "PVCCMCP_CPU0")
	)
	(segment
		(start 296.66184 -73.240138)
		(end 296.09034 -73.240138)
		(width 0.254)
		(layer "F.Cu")
		(net "PVCCMCP_CPU0")
	)
	(segment
		(start 288.36366 -85.622384)
		(end 288.93516 -85.622384)
		(width 0.254)
		(layer "F.Cu")
		(net "PVCCMCP_CPU0")
	)
	(segment
		(start 290.93922 -84.918804)
		(end 290.93922 -85.127338)
		(width 0.254)
		(layer "F.Cu")
		(net "PVCCMCP_CPU0")
	)
	(segment
		(start 291.79774 -82.650584)
		(end 292.36924 -82.650584)
		(width 0.254)
		(layer "F.Cu")
		(net "PVCCMCP_CPU0")
	)
	(segment
		(start 294.9448 -75.221338)
		(end 294.3733 -75.221338)
		(width 0.254)
		(layer "F.Cu")
		(net "PVCCMCP_CPU0")
	)
	(segment
		(start 297.807126 -73.240138)
		(end 298.378626 -73.240138)
		(width 0.254)
		(layer "F.Cu")
		(net "PVCCMCP_CPU0")
	)
	(segment
		(start 290.0807 -79.678784)
		(end 290.6522 -79.678784)
		(width 0.254)
		(layer "F.Cu")
		(net "PVCCMCP_CPU0")
	)
	(segment
		(start 290.0807 -81.659984)
		(end 290.6522 -81.659984)
		(width 0.254)
		(layer "F.Cu")
		(net "PVCCMCP_CPU0")
	)
	(segment
		(start 290.0807 -82.650584)
		(end 290.6522 -82.650584)
		(width 0.254)
		(layer "F.Cu")
		(net "PVCCMCP_CPU0")
	)
	(segment
		(start 290.6522 -84.631784)
		(end 290.6522 -84.423758)
		(width 0.254)
		(layer "F.Cu")
		(net "PVCCMCP_CPU0")
	)
	(segment
		(start 288.36366 -89.584784)
		(end 288.93516 -89.584784)
		(width 0.254)
		(layer "F.Cu")
		(net "PVCCMCP_CPU0")
	)
	(segment
		(start 289.22218 -78.193138)
		(end 289.79368 -78.193138)
		(width 0.254)
		(layer "F.Cu")
		(net "PVCCMCP_CPU0")
	)
	(segment
		(start 296.66184 -76.211938)
		(end 296.09034 -76.211938)
		(width 0.254)
		(layer "F.Cu")
		(net "PVCCMCP_CPU0")
	)
	(segment
		(start 287.50514 -67.296538)
		(end 286.93364 -67.296538)
		(width 0.254)
		(layer "F.Cu")
		(net "PVCCMCP_CPU0")
	)
	(segment
		(start 291.79774 -80.669384)
		(end 292.36924 -80.669384)
		(width 0.254)
		(layer "F.Cu")
		(net "PVCCMCP_CPU0")
	)
	(segment
		(start 291.79774 -74.725784)
		(end 292.36924 -74.725784)
		(width 0.254)
		(layer "F.Cu")
		(net "PVCCMCP_CPU0")
	)
	(segment
		(start 290.0807 -83.641184)
		(end 290.6522 -83.641184)
		(width 0.254)
		(layer "F.Cu")
		(net "PVCCMCP_CPU0")
	)
	(segment
		(start 296.948606 -75.716384)
		(end 297.520106 -75.716384)
		(width 0.254)
		(layer "F.Cu")
		(net "PVCCMCP_CPU0")
	)
	(segment
		(start 290.6522 -84.423758)
		(end 290.93922 -84.136738)
		(width 0.254)
		(layer "F.Cu")
		(net "PVCCMCP_CPU0")
	)
	(segment
		(start 290.93922 -85.127338)
		(end 291.51072 -85.127338)
		(width 0.254)
		(layer "F.Cu")
		(net "PVCCMCP_CPU0")
	)
	(segment
		(start 290.93922 -79.183738)
		(end 291.51072 -79.183738)
		(width 0.254)
		(layer "F.Cu")
		(net "PVCCMCP_CPU0")
	)
	(segment
		(start 291.79774 -81.659984)
		(end 292.36924 -81.659984)
		(width 0.254)
		(layer "F.Cu")
		(net "PVCCMCP_CPU0")
	)
	(segment
		(start 297.807126 -74.230738)
		(end 298.378626 -74.230738)
		(width 0.254)
		(layer "F.Cu")
		(net "PVCCMCP_CPU0")
	)
	(segment
		(start 285.2166 -68.287138)
		(end 285.7881 -68.287138)
		(width 0.254)
		(layer "F.Cu")
		(net "PVCCMCP_CPU0")
	)
	(segment
		(start 296.66184 -74.230738)
		(end 296.09034 -74.230738)
		(width 0.254)
		(layer "F.Cu")
		(net "PVCCMCP_CPU0")
	)
	(segment
		(start 290.93922 -80.174338)
		(end 291.51072 -80.174338)
		(width 0.254)
		(layer "F.Cu")
		(net "PVCCMCP_CPU0")
	)
	(segment
		(start 289.22218 -79.183738)
		(end 289.79368 -79.183738)
		(width 0.254)
		(layer "F.Cu")
		(net "PVCCMCP_CPU0")
	)
	(segment
		(start 288.36366 -67.791584)
		(end 288.93516 -67.791584)
		(width 0.254)
		(layer "F.Cu")
		(net "PVCCMCP_CPU0")
	)
	(segment
		(start 287.21812 -90.575384)
		(end 286.64662 -90.575384)
		(width 0.254)
		(layer "F.Cu")
		(net "PVCCMCP_CPU0")
	)
	(segment
		(start 287.50514 -87.108538)
		(end 288.07664 -87.108538)
		(width 0.254)
		(layer "F.Cu")
		(net "PVCCMCP_CPU0")
	)
	(segment
		(start 291.79774 -76.706984)
		(end 292.36924 -76.706984)
		(width 0.1016)
		(layer "F.Cu")
		(net "PVCCMCP_CPU0")
	)
	(segment
		(start 295.80332 -75.716384)
		(end 295.23182 -75.716384)
		(width 0.254)
		(layer "F.Cu")
		(net "PVCCMCP_CPU0")
	)
	(segment
		(start 286.3596 -86.117938)
		(end 285.7881 -86.117938)
		(width 0.254)
		(layer "F.Cu")
		(net "PVCCMCP_CPU0")
	)
	(segment
		(start 296.948606 -73.735184)
		(end 297.520106 -73.735184)
		(width 0.254)
		(layer "F.Cu")
		(net "PVCCMCP_CPU0")
	)
	(segment
		(start 293.51478 -75.716384)
		(end 294.08628 -75.716384)
		(width 0.254)
		(layer "F.Cu")
		(net "PVCCMCP_CPU0")
	)
	(segment
		(start 286.07512 -67.791584)
		(end 286.64662 -67.791584)
		(width 0.254)
		(layer "F.Cu")
		(net "PVCCMCP_CPU0")
	)
	(segment
		(start 296.948606 -72.744584)
		(end 297.520106 -72.744584)
		(width 0.254)
		(layer "F.Cu")
		(net "PVCCMCP_CPU0")
	)
	(segment
		(start 285.7881 -85.127338)
		(end 286.3596 -85.127338)
		(width 0.254)
		(layer "F.Cu")
		(net "PVCCMCP_CPU0")
	)
	(segment
		(start 288.93516 -68.782184)
		(end 288.36366 -68.782184)
		(width 0.254)
		(layer "F.Cu")
		(net "PVCCMCP_CPU0")
	)
	(segment
		(start 287.50514 -78.193138)
		(end 288.07664 -78.193138)
		(width 0.254)
		(layer "F.Cu")
		(net "PVCCMCP_CPU0")
	)
	(segment
		(start 287.21812 -85.622384)
		(end 286.64662 -85.622384)
		(width 0.254)
		(layer "F.Cu")
		(net "PVCCMCP_CPU0")
	)
	(segment
		(start 290.93922 -82.155284)
		(end 291.51072 -82.155284)
		(width 0.254)
		(layer "F.Cu")
		(net "PVCCMCP_CPU0")
	)
	(segment
		(start 285.2166 -67.296538)
		(end 285.7881 -67.296538)
		(width 0.254)
		(layer "F.Cu")
		(net "PVCCMCP_CPU0")
	)
	(segment
		(start 290.0807 -84.840318)
		(end 289.79368 -85.127338)
		(width 0.254)
		(layer "F.Cu")
		(net "PVCCMCP_CPU0")
	)
	(segment
		(start 289.22218 -68.287138)
		(end 289.79368 -68.287138)
		(width 0.254)
		(layer "F.Cu")
		(net "PVCCMCP_CPU0")
	)
	(segment
		(start 290.0807 -84.631784)
		(end 290.0807 -84.840318)
		(width 0.254)
		(layer "F.Cu")
		(net "PVCCMCP_CPU0")
	)
	(segment
		(start 287.50514 -85.127338)
		(end 288.07664 -85.127338)
		(width 0.254)
		(layer "F.Cu")
		(net "PVCCMCP_CPU0")
	)
	(segment
		(start 286.07512 -66.800984)
		(end 286.64662 -66.800984)
		(width 0.254)
		(layer "F.Cu")
		(net "PVCCMCP_CPU0")
	)
	(segment
		(start 292.65626 -67.296538)
		(end 293.22776 -67.296538)
		(width 0.254)
		(layer "F.Cu")
		(net "PVCCMCP_CPU0")
	)
	(segment
		(start 291.79774 -79.678784)
		(end 292.36924 -79.678784)
		(width 0.254)
		(layer "F.Cu")
		(net "PVCCMCP_CPU0")
	)
	(segment
		(start 290.0807 -66.800984)
		(end 290.6522 -66.800984)
		(width 0.254)
		(layer "F.Cu")
		(net "PVCCMCP_CPU0")
	)
	(segment
		(start 288.36366 -84.631784)
		(end 288.93516 -84.631784)
		(width 0.254)
		(layer "F.Cu")
		(net "PVCCMCP_CPU0")
	)
	(segment
		(start 288.36366 -83.641184)
		(end 288.93516 -83.641184)
		(width 0.254)
		(layer "F.Cu")
		(net "PVCCMCP_CPU0")
	)
	(segment
		(start 289.79368 -85.127338)
		(end 289.22218 -85.127338)
		(width 0.254)
		(layer "F.Cu")
		(net "PVCCMCP_CPU0")
	)
	(segment
		(start 287.21812 -86.612984)
		(end 286.64662 -86.612984)
		(width 0.254)
		(layer "F.Cu")
		(net "PVCCMCP_CPU0")
	)
	(segment
		(start 290.6522 -84.631784)
		(end 290.93922 -84.918804)
		(width 0.254)
		(layer "F.Cu")
		(net "PVCCMCP_CPU0")
	)
	(segment
		(start 288.93516 -88.594184)
		(end 288.36366 -88.594184)
		(width 0.254)
		(layer "F.Cu")
		(net "PVCCMCP_CPU0")
	)
	(segment
		(start 288.36366 -87.603584)
		(end 288.93516 -87.603584)
		(width 0.254)
		(layer "F.Cu")
		(net "PVCCMCP_CPU0")
	)
	(segment
		(start 290.0807 -77.697584)
		(end 290.6522 -77.697584)
		(width 0.254)
		(layer "F.Cu")
		(net "PVCCMCP_CPU0")
	)
	(segment
		(start 289.22218 -83.146138)
		(end 289.79368 -83.146138)
		(width 0.254)
		(layer "F.Cu")
		(net "PVCCMCP_CPU0")
	)
	(segment
		(start 297.807126 -75.221338)
		(end 298.378626 -75.221338)
		(width 0.254)
		(layer "F.Cu")
		(net "PVCCMCP_CPU0")
	)
	(segment
		(start 296.948606 -74.725784)
		(end 297.520106 -74.725784)
		(width 0.254)
		(layer "F.Cu")
		(net "PVCCMCP_CPU0")
	)
	(segment
		(start 296.66184 -75.221338)
		(end 296.09034 -75.221338)
		(width 0.254)
		(layer "F.Cu")
		(net "PVCCMCP_CPU0")
	)
	(segment
		(start 298.665646 -73.735184)
		(end 299.237146 -73.735184)
		(width 0.254)
		(layer "F.Cu")
		(net "PVCCMCP_CPU0")
	)
	(segment
		(start 290.93922 -84.136738)
		(end 291.51072 -84.136738)
		(width 0.254)
		(layer "F.Cu")
		(net "PVCCMCP_CPU0")
	)
	(segment
		(start 290.0807 -84.631784)
		(end 290.6522 -84.631784)
		(width 0.254)
		(layer "F.Cu")
		(net "PVCCMCP_CPU0")
	)
	(segment
		(start 289.22218 -81.164938)
		(end 289.79368 -81.164938)
		(width 0.254)
		(layer "F.Cu")
		(net "PVCCMCP_CPU0")
	)
	(segment
		(start 288.36366 -86.612984)
		(end 288.93516 -86.612984)
		(width 0.254)
		(layer "F.Cu")
		(net "PVCCMCP_CPU0")
	)
	(segment
		(start 287.50514 -89.089738)
		(end 288.07664 -89.089738)
		(width 0.254)
		(layer "F.Cu")
		(net "PVCCMCP_CPU0")
	)
	(segment
		(start 290.93922 -75.221338)
		(end 291.51072 -75.221338)
		(width 0.254)
		(layer "F.Cu")
		(net "PVCCMCP_CPU0")
	)
	(segment
		(start 291.79774 -83.641184)
		(end 292.36924 -83.641184)
		(width 0.254)
		(layer "F.Cu")
		(net "PVCCMCP_CPU0")
	)
	(segment
		(start 290.93922 -76.211938)
		(end 291.51072 -76.211938)
		(width 0.254)
		(layer "F.Cu")
		(net "PVCCMCP_CPU0")
	)
	(segment
		(start 286.283146 -68.782184)
		(end 286.64662 -68.782184)
		(width 0.254)
		(layer "F.Cu")
		(net "PVCCMCP_CPU0")
	)
	(segment
		(start 287.50514 -86.117938)
		(end 288.07664 -86.117938)
		(width 0.254)
		(layer "F.Cu")
		(net "PVCCMCP_CPU0")
	)
	(via
		(at 288.07664 -91.070938)
		(size 0.508)
		(drill 0.254)
		(layers "F.Cu" "B.Cu")
		(net "PVCCMCP_CPU0")
	)
	(via
		(at 275.717508 -78.715616)
		(size 0.508)
		(drill 0.254)
		(layers "F.Cu" "B.Cu")
		(net "PVCCMCP_CPU0")
	)
	(via
		(at 288.93516 -87.603584)
		(size 0.508)
		(drill 0.254)
		(layers "F.Cu" "B.Cu")
		(net "PVCCMCP_CPU0")
	)
	(via
		(at 321.006216 -49.864772)
		(size 0.508)
		(drill 0.254)
		(layers "F.Cu" "B.Cu")
		(net "PVCCMCP_CPU0")
	)
	(via
		(at 319.917572 -50.154586)
		(size 0.508)
		(drill 0.254)
		(layers "F.Cu" "B.Cu")
		(net "PVCCMCP_CPU0")
	)
	(via
		(at 288.93516 -89.584784)
		(size 0.508)
		(drill 0.254)
		(layers "F.Cu" "B.Cu")
		(net "PVCCMCP_CPU0")
	)
	(via
		(at 320.07556 -48.68418)
		(size 0.508)
		(drill 0.254)
		(layers "F.Cu" "B.Cu")
		(net "PVCCMCP_CPU0")
	)
	(via
		(at 346.7354 -41.91)
		(size 0.508)
		(drill 0.254)
		(layers "F.Cu" "B.Cu")
		(net "PVCCMCP_CPU0")
	)
	(via
		(at 344.1954 -43.18)
		(size 0.508)
		(drill 0.254)
		(layers "F.Cu" "B.Cu")
		(net "PVCCMCP_CPU0")
	)
	(via
		(at 273.888708 -78.715616)
		(size 0.508)
		(drill 0.254)
		(layers "F.Cu" "B.Cu")
		(net "PVCCMCP_CPU0")
	)
	(via
		(at 318.59474 -51.52136)
		(size 0.508)
		(drill 0.254)
		(layers "F.Cu" "B.Cu")
		(net "PVCCMCP_CPU0")
	)
	(via
		(at 320.81216 -49.25822)
		(size 0.508)
		(drill 0.254)
		(layers "F.Cu" "B.Cu")
		(net "PVCCMCP_CPU0")
	)
	(via
		(at 320.552572 -50.281586)
		(size 0.508)
		(drill 0.254)
		(layers "F.Cu" "B.Cu")
		(net "PVCCMCP_CPU0")
	)
	(via
		(at 322.30822 -51.26228)
		(size 0.508)
		(drill 0.254)
		(layers "F.Cu" "B.Cu")
		(net "PVCCMCP_CPU0")
	)
	(via
		(at 321.10172 -50.67554)
		(size 0.508)
		(drill 0.254)
		(layers "F.Cu" "B.Cu")
		(net "PVCCMCP_CPU0")
	)
	(via
		(at 321.492372 -51.170586)
		(size 0.508)
		(drill 0.254)
		(layers "F.Cu" "B.Cu")
		(net "PVCCMCP_CPU0")
	)
	(via
		(at 276.784308 -74.397616)
		(size 0.508)
		(drill 0.254)
		(layers "F.Cu" "B.Cu")
		(net "PVCCMCP_CPU0")
	)
	(via
		(at 297.520106 -75.716384)
		(size 0.508)
		(drill 0.254)
		(layers "F.Cu" "B.Cu")
		(net "PVCCMCP_CPU0")
	)
	(via
		(at 288.07664 -85.127338)
		(size 0.508)
		(drill 0.254)
		(layers "F.Cu" "B.Cu")
		(net "PVCCMCP_CPU0")
	)
	(via
		(at 320.6115 -51.111658)
		(size 0.508)
		(drill 0.254)
		(layers "F.Cu" "B.Cu")
		(net "PVCCMCP_CPU0")
	)
	(via
		(at 345.4654 -41.91)
		(size 0.508)
		(drill 0.254)
		(layers "F.Cu" "B.Cu")
		(net "PVCCMCP_CPU0")
	)
	(via
		(at 295.80332 -75.716384)
		(size 0.508)
		(drill 0.254)
		(layers "F.Cu" "B.Cu")
		(net "PVCCMCP_CPU0")
	)
	(via
		(at 319.87744 -49.2633)
		(size 0.508)
		(drill 0.254)
		(layers "F.Cu" "B.Cu")
		(net "PVCCMCP_CPU0")
	)
	(via
		(at 318.394334 -49.699164)
		(size 0.508)
		(drill 0.254)
		(layers "F.Cu" "B.Cu")
		(net "PVCCMCP_CPU0")
	)
	(via
		(at 285.2166 -68.287138)
		(size 0.508)
		(drill 0.254)
		(layers "F.Cu" "B.Cu")
		(net "PVCCMCP_CPU0")
	)
	(via
		(at 319.33134 -48.85436)
		(size 0.508)
		(drill 0.254)
		(layers "F.Cu" "B.Cu")
		(net "PVCCMCP_CPU0")
	)
	(via
		(at 337.8454 -41.91)
		(size 0.508)
		(drill 0.254)
		(layers "F.Cu" "B.Cu")
		(net "PVCCMCP_CPU0")
	)
	(via
		(at 315.6712 -51.8541)
		(size 0.508)
		(drill 0.254)
		(layers "F.Cu" "B.Cu")
		(net "PVCCMCP_CPU0")
	)
	(via
		(at 316.233556 -52.17287)
		(size 0.508)
		(drill 0.254)
		(layers "F.Cu" "B.Cu")
		(net "PVCCMCP_CPU0")
	)
	(via
		(at 336.5754 -43.18)
		(size 0.508)
		(drill 0.254)
		(layers "F.Cu" "B.Cu")
		(net "PVCCMCP_CPU0")
	)
	(via
		(at 342.9254 -41.91)
		(size 0.508)
		(drill 0.254)
		(layers "F.Cu" "B.Cu")
		(net "PVCCMCP_CPU0")
	)
	(via
		(at 321.941444 -50.721514)
		(size 0.508)
		(drill 0.254)
		(layers "F.Cu" "B.Cu")
		(net "PVCCMCP_CPU0")
	)
	(via
		(at 316.07252 -51.34864)
		(size 0.508)
		(drill 0.254)
		(layers "F.Cu" "B.Cu")
		(net "PVCCMCP_CPU0")
	)
	(via
		(at 318.84874 -49.2379)
		(size 0.508)
		(drill 0.254)
		(layers "F.Cu" "B.Cu")
		(net "PVCCMCP_CPU0")
	)
	(via
		(at 293.22776 -75.221338)
		(size 0.508)
		(drill 0.254)
		(layers "F.Cu" "B.Cu")
		(net "PVCCMCP_CPU0")
	)
	(via
		(at 339.1154 -43.18)
		(size 0.508)
		(drill 0.254)
		(layers "F.Cu" "B.Cu")
		(net "PVCCMCP_CPU0")
	)
	(via
		(at 349.2754 -41.91)
		(size 0.508)
		(drill 0.254)
		(layers "F.Cu" "B.Cu")
		(net "PVCCMCP_CPU0")
	)
	(via
		(at 290.6522 -84.631784)
		(size 0.508)
		(drill 0.254)
		(layers "F.Cu" "B.Cu")
		(net "PVCCMCP_CPU0")
	)
	(via
		(at 323.220588 -51.356514)
		(size 0.508)
		(drill 0.254)
		(layers "F.Cu" "B.Cu")
		(net "PVCCMCP_CPU0")
	)
	(via
		(at 317.391034 -49.966372)
		(size 0.508)
		(drill 0.254)
		(layers "F.Cu" "B.Cu")
		(net "PVCCMCP_CPU0")
	)
	(via
		(at 296.66184 -73.240138)
		(size 0.508)
		(drill 0.254)
		(layers "F.Cu" "B.Cu")
		(net "PVCCMCP_CPU0")
	)
	(via
		(at 294.08628 -75.716384)
		(size 0.508)
		(drill 0.254)
		(layers "F.Cu" "B.Cu")
		(net "PVCCMCP_CPU0")
	)
	(via
		(at 321.4243 -53.152802)
		(size 0.508)
		(drill 0.254)
		(layers "F.Cu" "B.Cu")
		(net "PVCCMCP_CPU0")
	)
	(via
		(at 322.322444 -52.254658)
		(size 0.508)
		(drill 0.254)
		(layers "F.Cu" "B.Cu")
		(net "PVCCMCP_CPU0")
	)
	(via
		(at 315.074808 -53.52796)
		(size 0.508)
		(drill 0.254)
		(layers "F.Cu" "B.Cu")
		(net "PVCCMCP_CPU0")
	)
	(via
		(at 318.53251 -50.594514)
		(size 0.508)
		(drill 0.254)
		(layers "F.Cu" "B.Cu")
		(net "PVCCMCP_CPU0")
	)
	(via
		(at 319.22974 -51.64836)
		(size 0.508)
		(drill 0.254)
		(layers "F.Cu" "B.Cu")
		(net "PVCCMCP_CPU0")
	)
	(via
		(at 290.6522 -83.641184)
		(size 0.508)
		(drill 0.254)
		(layers "F.Cu" "B.Cu")
		(net "PVCCMCP_CPU0")
	)
	(via
		(at 321.45478 -49.40554)
		(size 0.508)
		(drill 0.254)
		(layers "F.Cu" "B.Cu")
		(net "PVCCMCP_CPU0")
	)
	(via
		(at 289.79368 -83.146138)
		(size 0.508)
		(drill 0.254)
		(layers "F.Cu" "B.Cu")
		(net "PVCCMCP_CPU0")
	)
	(via
		(at 297.520106 -73.735184)
		(size 0.508)
		(drill 0.254)
		(layers "F.Cu" "B.Cu")
		(net "PVCCMCP_CPU0")
	)
	(via
		(at 286.07512 -67.791584)
		(size 0.508)
		(drill 0.254)
		(layers "F.Cu" "B.Cu")
		(net "PVCCMCP_CPU0")
	)
	(via
		(at 318.09182 -51.06162)
		(size 0.508)
		(drill 0.254)
		(layers "F.Cu" "B.Cu")
		(net "PVCCMCP_CPU0")
	)
	(via
		(at 272.059908 -74.397616)
		(size 0.508)
		(drill 0.254)
		(layers "F.Cu" "B.Cu")
		(net "PVCCMCP_CPU0")
	)
	(via
		(at 292.36924 -82.650584)
		(size 0.508)
		(drill 0.254)
		(layers "F.Cu" "B.Cu")
		(net "PVCCMCP_CPU0")
	)
	(via
		(at 297.520106 -72.744584)
		(size 0.508)
		(drill 0.254)
		(layers "F.Cu" "B.Cu")
		(net "PVCCMCP_CPU0")
	)
	(via
		(at 318.064134 -58.081672)
		(size 0.508)
		(drill 0.254)
		(layers "F.Cu" "B.Cu")
		(net "PVCCMCP_CPU0")
	)
	(via
		(at 344.1954 -41.91)
		(size 0.508)
		(drill 0.254)
		(layers "F.Cu" "B.Cu")
		(net "PVCCMCP_CPU0")
	)
	(via
		(at 316.941962 -50.415444)
		(size 0.508)
		(drill 0.254)
		(layers "F.Cu" "B.Cu")
		(net "PVCCMCP_CPU0")
	)
	(via
		(at 320.82232 -48.59528)
		(size 0.508)
		(drill 0.254)
		(layers "F.Cu" "B.Cu")
		(net "PVCCMCP_CPU0")
	)
	(via
		(at 289.79368 -79.183738)
		(size 0.508)
		(drill 0.254)
		(layers "F.Cu" "B.Cu")
		(net "PVCCMCP_CPU0")
	)
	(via
		(at 348.0054 -41.91)
		(size 0.508)
		(drill 0.254)
		(layers "F.Cu" "B.Cu")
		(net "PVCCMCP_CPU0")
	)
	(via
		(at 292.36924 -74.725784)
		(size 0.508)
		(drill 0.254)
		(layers "F.Cu" "B.Cu")
		(net "PVCCMCP_CPU0")
	)
	(via
		(at 288.93516 -86.612984)
		(size 0.508)
		(drill 0.254)
		(layers "F.Cu" "B.Cu")
		(net "PVCCMCP_CPU0")
	)
	(via
		(at 345.4654 -43.18)
		(size 0.508)
		(drill 0.254)
		(layers "F.Cu" "B.Cu")
		(net "PVCCMCP_CPU0")
	)
	(via
		(at 315.7982 -56.6674)
		(size 0.508)
		(drill 0.254)
		(layers "F.Cu" "B.Cu")
		(net "PVCCMCP_CPU0")
	)
	(via
		(at 274.955508 -78.715616)
		(size 0.508)
		(drill 0.254)
		(layers "F.Cu" "B.Cu")
		(net "PVCCMCP_CPU0")
	)
	(via
		(at 273.126708 -78.715616)
		(size 0.508)
		(drill 0.254)
		(layers "F.Cu" "B.Cu")
		(net "PVCCMCP_CPU0")
	)
	(via
		(at 289.79368 -85.127338)
		(size 0.508)
		(drill 0.254)
		(layers "F.Cu" "B.Cu")
		(net "PVCCMCP_CPU0")
	)
	(via
		(at 319.430654 -49.69637)
		(size 0.508)
		(drill 0.254)
		(layers "F.Cu" "B.Cu")
		(net "PVCCMCP_CPU0")
	)
	(via
		(at 290.6522 -77.697584)
		(size 0.508)
		(drill 0.254)
		(layers "F.Cu" "B.Cu")
		(net "PVCCMCP_CPU0")
	)
	(via
		(at 270.231108 -78.715616)
		(size 0.508)
		(drill 0.254)
		(layers "F.Cu" "B.Cu")
		(net "PVCCMCP_CPU0")
	)
	(via
		(at 296.66184 -76.211938)
		(size 0.508)
		(drill 0.254)
		(layers "F.Cu" "B.Cu")
		(net "PVCCMCP_CPU0")
	)
	(via
		(at 317.85433 -57.498742)
		(size 0.508)
		(drill 0.254)
		(layers "F.Cu" "B.Cu")
		(net "PVCCMCP_CPU0")
	)
	(via
		(at 287.21812 -90.575384)
		(size 0.508)
		(drill 0.254)
		(layers "F.Cu" "B.Cu")
		(net "PVCCMCP_CPU0")
	)
	(via
		(at 288.07664 -90.080338)
		(size 0.508)
		(drill 0.254)
		(layers "F.Cu" "B.Cu")
		(net "PVCCMCP_CPU0")
	)
	(via
		(at 321.958716 -49.764442)
		(size 0.508)
		(drill 0.254)
		(layers "F.Cu" "B.Cu")
		(net "PVCCMCP_CPU0")
	)
	(via
		(at 317.65875 -51.512216)
		(size 0.508)
		(drill 0.254)
		(layers "F.Cu" "B.Cu")
		(net "PVCCMCP_CPU0")
	)
	(via
		(at 298.378626 -73.240138)
		(size 0.508)
		(drill 0.254)
		(layers "F.Cu" "B.Cu")
		(net "PVCCMCP_CPU0")
	)
	(via
		(at 288.07664 -78.193138)
		(size 0.508)
		(drill 0.254)
		(layers "F.Cu" "B.Cu")
		(net "PVCCMCP_CPU0")
	)
	(via
		(at 321.873372 -52.70373)
		(size 0.508)
		(drill 0.254)
		(layers "F.Cu" "B.Cu")
		(net "PVCCMCP_CPU0")
	)
	(via
		(at 321.509644 -50.213514)
		(size 0.508)
		(drill 0.254)
		(layers "F.Cu" "B.Cu")
		(net "PVCCMCP_CPU0")
	)
	(via
		(at 274.955508 -74.397616)
		(size 0.508)
		(drill 0.254)
		(layers "F.Cu" "B.Cu")
		(net "PVCCMCP_CPU0")
	)
	(via
		(at 275.717508 -74.397616)
		(size 0.508)
		(drill 0.254)
		(layers "F.Cu" "B.Cu")
		(net "PVCCMCP_CPU0")
	)
	(via
		(at 270.231108 -74.397616)
		(size 0.508)
		(drill 0.254)
		(layers "F.Cu" "B.Cu")
		(net "PVCCMCP_CPU0")
	)
	(via
		(at 291.51072 -80.174338)
		(size 0.508)
		(drill 0.254)
		(layers "F.Cu" "B.Cu")
		(net "PVCCMCP_CPU0")
	)
	(via
		(at 286.07512 -66.800984)
		(size 0.508)
		(drill 0.254)
		(layers "F.Cu" "B.Cu")
		(net "PVCCMCP_CPU0")
	)
	(via
		(at 292.36924 -76.706984)
		(size 0.508)
		(drill 0.254)
		(layers "F.Cu" "B.Cu")
		(net "PVCCMCP_CPU0")
	)
	(via
		(at 276.784308 -78.715616)
		(size 0.508)
		(drill 0.254)
		(layers "F.Cu" "B.Cu")
		(net "PVCCMCP_CPU0")
	)
	(via
		(at 288.93516 -83.641184)
		(size 0.508)
		(drill 0.254)
		(layers "F.Cu" "B.Cu")
		(net "PVCCMCP_CPU0")
	)
	(via
		(at 294.9448 -75.221338)
		(size 0.508)
		(drill 0.254)
		(layers "F.Cu" "B.Cu")
		(net "PVCCMCP_CPU0")
	)
	(via
		(at 317.55969 -50.632868)
		(size 0.508)
		(drill 0.254)
		(layers "F.Cu" "B.Cu")
		(net "PVCCMCP_CPU0")
	)
	(via
		(at 350.5454 -41.91)
		(size 0.508)
		(drill 0.254)
		(layers "F.Cu" "B.Cu")
		(net "PVCCMCP_CPU0")
	)
	(via
		(at 317.06566 -51.23688)
		(size 0.508)
		(drill 0.254)
		(layers "F.Cu" "B.Cu")
		(net "PVCCMCP_CPU0")
	)
	(via
		(at 317.99276 -50.17262)
		(size 0.508)
		(drill 0.254)
		(layers "F.Cu" "B.Cu")
		(net "PVCCMCP_CPU0")
	)
	(via
		(at 290.6522 -82.650584)
		(size 0.508)
		(drill 0.254)
		(layers "F.Cu" "B.Cu")
		(net "PVCCMCP_CPU0")
	)
	(via
		(at 317.776606 -49.48174)
		(size 0.508)
		(drill 0.254)
		(layers "F.Cu" "B.Cu")
		(net "PVCCMCP_CPU0")
	)
	(via
		(at 291.51072 -82.155284)
		(size 0.508)
		(drill 0.254)
		(layers "F.Cu" "B.Cu")
		(net "PVCCMCP_CPU0")
	)
	(via
		(at 289.79368 -67.296538)
		(size 0.508)
		(drill 0.254)
		(layers "F.Cu" "B.Cu")
		(net "PVCCMCP_CPU0")
	)
	(via
		(at 288.93516 -68.782184)
		(size 0.508)
		(drill 0.254)
		(layers "F.Cu" "B.Cu")
		(net "PVCCMCP_CPU0")
	)
	(via
		(at 271.297908 -78.715616)
		(size 0.508)
		(drill 0.254)
		(layers "F.Cu" "B.Cu")
		(net "PVCCMCP_CPU0")
	)
	(via
		(at 292.36924 -79.678784)
		(size 0.508)
		(drill 0.254)
		(layers "F.Cu" "B.Cu")
		(net "PVCCMCP_CPU0")
	)
	(via
		(at 340.3854 -43.18)
		(size 0.508)
		(drill 0.254)
		(layers "F.Cu" "B.Cu")
		(net "PVCCMCP_CPU0")
	)
	(via
		(at 319.47358 -50.5841)
		(size 0.508)
		(drill 0.254)
		(layers "F.Cu" "B.Cu")
		(net "PVCCMCP_CPU0")
	)
	(via
		(at 286.3596 -85.127338)
		(size 0.508)
		(drill 0.254)
		(layers "F.Cu" "B.Cu")
		(net "PVCCMCP_CPU0")
	)
	(via
		(at 291.51072 -68.287138)
		(size 0.508)
		(drill 0.254)
		(layers "F.Cu" "B.Cu")
		(net "PVCCMCP_CPU0")
	)
	(via
		(at 315.074808 -54.16296)
		(size 0.508)
		(drill 0.254)
		(layers "F.Cu" "B.Cu")
		(net "PVCCMCP_CPU0")
	)
	(via
		(at 277.546308 -74.397616)
		(size 0.508)
		(drill 0.254)
		(layers "F.Cu" "B.Cu")
		(net "PVCCMCP_CPU0")
	)
	(via
		(at 350.5454 -43.18)
		(size 0.508)
		(drill 0.254)
		(layers "F.Cu" "B.Cu")
		(net "PVCCMCP_CPU0")
	)
	(via
		(at 316.64148 -51.70678)
		(size 0.508)
		(drill 0.254)
		(layers "F.Cu" "B.Cu")
		(net "PVCCMCP_CPU0")
	)
	(via
		(at 342.9254 -43.18)
		(size 0.508)
		(drill 0.254)
		(layers "F.Cu" "B.Cu")
		(net "PVCCMCP_CPU0")
	)
	(via
		(at 316.3062 -57.0992)
		(size 0.508)
		(drill 0.254)
		(layers "F.Cu" "B.Cu")
		(net "PVCCMCP_CPU0")
	)
	(via
		(at 286.93364 -67.296538)
		(size 0.508)
		(drill 0.254)
		(layers "F.Cu" "B.Cu")
		(net "PVCCMCP_CPU0")
	)
	(via
		(at 288.93516 -88.594184)
		(size 0.508)
		(drill 0.254)
		(layers "F.Cu" "B.Cu")
		(net "PVCCMCP_CPU0")
	)
	(via
		(at 288.93516 -85.622384)
		(size 0.508)
		(drill 0.254)
		(layers "F.Cu" "B.Cu")
		(net "PVCCMCP_CPU0")
	)
	(via
		(at 269.469108 -78.715616)
		(size 0.508)
		(drill 0.254)
		(layers "F.Cu" "B.Cu")
		(net "PVCCMCP_CPU0")
	)
	(via
		(at 322.771516 -51.805586)
		(size 0.508)
		(drill 0.254)
		(layers "F.Cu" "B.Cu")
		(net "PVCCMCP_CPU0")
	)
	(via
		(at 289.79368 -78.193138)
		(size 0.508)
		(drill 0.254)
		(layers "F.Cu" "B.Cu")
		(net "PVCCMCP_CPU0")
	)
	(via
		(at 321.0433 -51.619658)
		(size 0.508)
		(drill 0.254)
		(layers "F.Cu" "B.Cu")
		(net "PVCCMCP_CPU0")
	)
	(via
		(at 287.21812 -85.622384)
		(size 0.508)
		(drill 0.254)
		(layers "F.Cu" "B.Cu")
		(net "PVCCMCP_CPU0")
	)
	(via
		(at 316.50686 -50.88382)
		(size 0.508)
		(drill 0.254)
		(layers "F.Cu" "B.Cu")
		(net "PVCCMCP_CPU0")
	)
	(via
		(at 286.3596 -86.117938)
		(size 0.508)
		(drill 0.254)
		(layers "F.Cu" "B.Cu")
		(net "PVCCMCP_CPU0")
	)
	(via
		(at 348.0054 -43.18)
		(size 0.508)
		(drill 0.254)
		(layers "F.Cu" "B.Cu")
		(net "PVCCMCP_CPU0")
	)
	(via
		(at 272.059908 -78.715616)
		(size 0.508)
		(drill 0.254)
		(layers "F.Cu" "B.Cu")
		(net "PVCCMCP_CPU0")
	)
	(via
		(at 269.469108 -74.397616)
		(size 0.508)
		(drill 0.254)
		(layers "F.Cu" "B.Cu")
		(net "PVCCMCP_CPU0")
	)
	(via
		(at 292.36924 -80.669384)
		(size 0.508)
		(drill 0.254)
		(layers "F.Cu" "B.Cu")
		(net "PVCCMCP_CPU0")
	)
	(via
		(at 277.560024 -78.699614)
		(size 0.508)
		(drill 0.254)
		(layers "F.Cu" "B.Cu")
		(net "PVCCMCP_CPU0")
	)
	(via
		(at 286.3596 -84.136738)
		(size 0.508)
		(drill 0.254)
		(layers "F.Cu" "B.Cu")
		(net "PVCCMCP_CPU0")
	)
	(via
		(at 289.79368 -68.287138)
		(size 0.508)
		(drill 0.254)
		(layers "F.Cu" "B.Cu")
		(net "PVCCMCP_CPU0")
	)
	(via
		(at 288.93516 -84.631784)
		(size 0.508)
		(drill 0.254)
		(layers "F.Cu" "B.Cu")
		(net "PVCCMCP_CPU0")
	)
	(via
		(at 291.51072 -84.136738)
		(size 0.508)
		(drill 0.254)
		(layers "F.Cu" "B.Cu")
		(net "PVCCMCP_CPU0")
	)
	(via
		(at 349.2754 -43.18)
		(size 0.508)
		(drill 0.254)
		(layers "F.Cu" "B.Cu")
		(net "PVCCMCP_CPU0")
	)
	(via
		(at 320.97472 -52.61864)
		(size 0.508)
		(drill 0.254)
		(layers "F.Cu" "B.Cu")
		(net "PVCCMCP_CPU0")
	)
	(via
		(at 340.3854 -41.91)
		(size 0.508)
		(drill 0.254)
		(layers "F.Cu" "B.Cu")
		(net "PVCCMCP_CPU0")
	)
	(via
		(at 296.66184 -75.221338)
		(size 0.508)
		(drill 0.254)
		(layers "F.Cu" "B.Cu")
		(net "PVCCMCP_CPU0")
	)
	(via
		(at 337.8454 -43.18)
		(size 0.508)
		(drill 0.254)
		(layers "F.Cu" "B.Cu")
		(net "PVCCMCP_CPU0")
	)
	(via
		(at 320.16954 -52.53736)
		(size 0.508)
		(drill 0.254)
		(layers "F.Cu" "B.Cu")
		(net "PVCCMCP_CPU0")
	)
	(via
		(at 318.462914 -57.461912)
		(size 0.508)
		(drill 0.254)
		(layers "F.Cu" "B.Cu")
		(net "PVCCMCP_CPU0")
	)
	(via
		(at 287.21812 -86.612984)
		(size 0.508)
		(drill 0.254)
		(layers "F.Cu" "B.Cu")
		(net "PVCCMCP_CPU0")
	)
	(via
		(at 341.6554 -43.18)
		(size 0.508)
		(drill 0.254)
		(layers "F.Cu" "B.Cu")
		(net "PVCCMCP_CPU0")
	)
	(via
		(at 297.520106 -74.725784)
		(size 0.508)
		(drill 0.254)
		(layers "F.Cu" "B.Cu")
		(net "PVCCMCP_CPU0")
	)
	(via
		(at 318.981582 -50.145442)
		(size 0.508)
		(drill 0.254)
		(layers "F.Cu" "B.Cu")
		(net "PVCCMCP_CPU0")
	)
	(via
		(at 291.51072 -75.221338)
		(size 0.508)
		(drill 0.254)
		(layers "F.Cu" "B.Cu")
		(net "PVCCMCP_CPU0")
	)
	(via
		(at 320.34988 -49.6951)
		(size 0.508)
		(drill 0.254)
		(layers "F.Cu" "B.Cu")
		(net "PVCCMCP_CPU0")
	)
	(via
		(at 320.19748 -51.59502)
		(size 0.508)
		(drill 0.254)
		(layers "F.Cu" "B.Cu")
		(net "PVCCMCP_CPU0")
	)
	(via
		(at 335.3054 -41.91)
		(size 0.508)
		(drill 0.254)
		(layers "F.Cu" "B.Cu")
		(net "PVCCMCP_CPU0")
	)
	(via
		(at 291.51072 -79.183738)
		(size 0.508)
		(drill 0.254)
		(layers "F.Cu" "B.Cu")
		(net "PVCCMCP_CPU0")
	)
	(via
		(at 319.73774 -52.02936)
		(size 0.508)
		(drill 0.254)
		(layers "F.Cu" "B.Cu")
		(net "PVCCMCP_CPU0")
	)
	(via
		(at 290.6522 -81.659984)
		(size 0.508)
		(drill 0.254)
		(layers "F.Cu" "B.Cu")
		(net "PVCCMCP_CPU0")
	)
	(via
		(at 322.81622 -50.85588)
		(size 0.508)
		(drill 0.254)
		(layers "F.Cu" "B.Cu")
		(net "PVCCMCP_CPU0")
	)
	(via
		(at 298.378626 -75.221338)
		(size 0.508)
		(drill 0.254)
		(layers "F.Cu" "B.Cu")
		(net "PVCCMCP_CPU0")
	)
	(via
		(at 336.5754 -41.91)
		(size 0.508)
		(drill 0.254)
		(layers "F.Cu" "B.Cu")
		(net "PVCCMCP_CPU0")
	)
	(via
		(at 288.93516 -67.791584)
		(size 0.508)
		(drill 0.254)
		(layers "F.Cu" "B.Cu")
		(net "PVCCMCP_CPU0")
	)
	(via
		(at 299.237146 -73.735184)
		(size 0.508)
		(drill 0.254)
		(layers "F.Cu" "B.Cu")
		(net "PVCCMCP_CPU0")
	)
	(via
		(at 317.162688 -57.529476)
		(size 0.508)
		(drill 0.254)
		(layers "F.Cu" "B.Cu")
		(net "PVCCMCP_CPU0")
	)
	(via
		(at 335.3054 -43.18)
		(size 0.508)
		(drill 0.254)
		(layers "F.Cu" "B.Cu")
		(net "PVCCMCP_CPU0")
	)
	(via
		(at 288.07664 -89.089738)
		(size 0.508)
		(drill 0.254)
		(layers "F.Cu" "B.Cu")
		(net "PVCCMCP_CPU0")
	)
	(via
		(at 321.87388 -51.7144)
		(size 0.508)
		(drill 0.254)
		(layers "F.Cu" "B.Cu")
		(net "PVCCMCP_CPU0")
	)
	(via
		(at 322.390516 -50.272442)
		(size 0.508)
		(drill 0.254)
		(layers "F.Cu" "B.Cu")
		(net "PVCCMCP_CPU0")
	)
	(via
		(at 288.07664 -86.117938)
		(size 0.508)
		(drill 0.254)
		(layers "F.Cu" "B.Cu")
		(net "PVCCMCP_CPU0")
	)
	(via
		(at 298.378626 -74.230738)
		(size 0.508)
		(drill 0.254)
		(layers "F.Cu" "B.Cu")
		(net "PVCCMCP_CPU0")
	)
	(via
		(at 321.41668 -52.1716)
		(size 0.508)
		(drill 0.254)
		(layers "F.Cu" "B.Cu")
		(net "PVCCMCP_CPU0")
	)
	(via
		(at 318.24422 -49.09058)
		(size 0.508)
		(drill 0.254)
		(layers "F.Cu" "B.Cu")
		(net "PVCCMCP_CPU0")
	)
	(via
		(at 319.019428 -51.05273)
		(size 0.508)
		(drill 0.254)
		(layers "F.Cu" "B.Cu")
		(net "PVCCMCP_CPU0")
	)
	(via
		(at 289.79368 -81.164938)
		(size 0.508)
		(drill 0.254)
		(layers "F.Cu" "B.Cu")
		(net "PVCCMCP_CPU0")
	)
	(via
		(at 319.654428 -51.17973)
		(size 0.508)
		(drill 0.254)
		(layers "F.Cu" "B.Cu")
		(net "PVCCMCP_CPU0")
	)
	(via
		(at 320.986912 -53.706776)
		(size 0.508)
		(drill 0.254)
		(layers "F.Cu" "B.Cu")
		(net "PVCCMCP_CPU0")
	)
	(via
		(at 320.594228 -52.06873)
		(size 0.508)
		(drill 0.254)
		(layers "F.Cu" "B.Cu")
		(net "PVCCMCP_CPU0")
	)
	(via
		(at 315.074808 -52.89296)
		(size 0.508)
		(drill 0.254)
		(layers "F.Cu" "B.Cu")
		(net "PVCCMCP_CPU0")
	)
	(via
		(at 341.6554 -41.91)
		(size 0.508)
		(drill 0.254)
		(layers "F.Cu" "B.Cu")
		(net "PVCCMCP_CPU0")
	)
	(via
		(at 320.56832 -53.12156)
		(size 0.508)
		(drill 0.254)
		(layers "F.Cu" "B.Cu")
		(net "PVCCMCP_CPU0")
	)
	(via
		(at 290.6522 -79.678784)
		(size 0.508)
		(drill 0.254)
		(layers "F.Cu" "B.Cu")
		(net "PVCCMCP_CPU0")
	)
	(via
		(at 290.6522 -66.800984)
		(size 0.508)
		(drill 0.254)
		(layers "F.Cu" "B.Cu")
		(net "PVCCMCP_CPU0")
	)
	(via
		(at 339.1154 -41.91)
		(size 0.508)
		(drill 0.254)
		(layers "F.Cu" "B.Cu")
		(net "PVCCMCP_CPU0")
	)
	(via
		(at 292.36924 -83.641184)
		(size 0.508)
		(drill 0.254)
		(layers "F.Cu" "B.Cu")
		(net "PVCCMCP_CPU0")
	)
	(via
		(at 346.7354 -43.18)
		(size 0.508)
		(drill 0.254)
		(layers "F.Cu" "B.Cu")
		(net "PVCCMCP_CPU0")
	)
	(via
		(at 291.51072 -76.211938)
		(size 0.508)
		(drill 0.254)
		(layers "F.Cu" "B.Cu")
		(net "PVCCMCP_CPU0")
	)
	(via
		(at 293.22776 -67.296538)
		(size 0.508)
		(drill 0.254)
		(layers "F.Cu" "B.Cu")
		(net "PVCCMCP_CPU0")
	)
	(via
		(at 315.074808 -54.79796)
		(size 0.508)
		(drill 0.254)
		(layers "F.Cu" "B.Cu")
		(net "PVCCMCP_CPU0")
	)
	(via
		(at 315.087 -55.4228)
		(size 0.508)
		(drill 0.254)
		(layers "F.Cu" "B.Cu")
		(net "PVCCMCP_CPU0")
	)
	(via
		(at 288.07664 -87.108538)
		(size 0.508)
		(drill 0.254)
		(layers "F.Cu" "B.Cu")
		(net "PVCCMCP_CPU0")
	)
	(via
		(at 296.66184 -74.230738)
		(size 0.508)
		(drill 0.254)
		(layers "F.Cu" "B.Cu")
		(net "PVCCMCP_CPU0")
	)
	(via
		(at 292.36924 -81.659984)
		(size 0.508)
		(drill 0.254)
		(layers "F.Cu" "B.Cu")
		(net "PVCCMCP_CPU0")
	)
	(via
		(at 273.126708 -74.397616)
		(size 0.508)
		(drill 0.254)
		(layers "F.Cu" "B.Cu")
		(net "PVCCMCP_CPU0")
	)
	(via
		(at 315.771784 -52.578508)
		(size 0.508)
		(drill 0.254)
		(layers "F.Cu" "B.Cu")
		(net "PVCCMCP_CPU0")
	)
	(via
		(at 320.10604 -50.764948)
		(size 0.508)
		(drill 0.254)
		(layers "F.Cu" "B.Cu")
		(net "PVCCMCP_CPU0")
	)
	(via
		(at 271.297908 -74.397616)
		(size 0.508)
		(drill 0.254)
		(layers "F.Cu" "B.Cu")
		(net "PVCCMCP_CPU0")
	)
	(via
		(at 291.51072 -85.127338)
		(size 0.508)
		(drill 0.254)
		(layers "F.Cu" "B.Cu")
		(net "PVCCMCP_CPU0")
	)
	(via
		(at 285.2166 -67.296538)
		(size 0.508)
		(drill 0.254)
		(layers "F.Cu" "B.Cu")
		(net "PVCCMCP_CPU0")
	)
	(via
		(at 273.888708 -74.397616)
		(size 0.508)
		(drill 0.254)
		(layers "F.Cu" "B.Cu")
		(net "PVCCMCP_CPU0")
	)
	(segment
		(start 292.65626 -79.183738)
		(end 293.22776 -79.183738)
		(width 0.254)
		(layer "F.Cu")
		(net "PVCCIOMCP_CPU0")
	)
	(segment
		(start 295.23182 -79.678784)
		(end 295.80332 -79.678784)
		(width 0.254)
		(layer "F.Cu")
		(net "PVCCIOMCP_CPU0")
	)
	(segment
		(start 296.66184 -77.202538)
		(end 296.09034 -77.202538)
		(width 0.254)
		(layer "F.Cu")
		(net "PVCCIOMCP_CPU0")
	)
	(segment
		(start 298.665646 -77.697584)
		(end 299.237146 -77.697584)
		(width 0.254)
		(layer "F.Cu")
		(net "PVCCIOMCP_CPU0")
	)
	(segment
		(start 296.948606 -78.688438)
		(end 297.520106 -78.688438)
		(width 0.254)
		(layer "F.Cu")
		(net "PVCCIOMCP_CPU0")
	)
	(segment
		(start 296.66184 -78.193138)
		(end 296.09034 -78.193138)
		(width 0.254)
		(layer "F.Cu")
		(net "PVCCIOMCP_CPU0")
	)
	(segment
		(start 298.665646 -78.688438)
		(end 299.237146 -78.688438)
		(width 0.254)
		(layer "F.Cu")
		(net "PVCCIOMCP_CPU0")
	)
	(segment
		(start 297.520106 -77.697584)
		(end 296.948606 -77.697584)
		(width 0.254)
		(layer "F.Cu")
		(net "PVCCIOMCP_CPU0")
	)
	(segment
		(start 292.65626 -77.202538)
		(end 293.22776 -77.202538)
		(width 0.254)
		(layer "F.Cu")
		(net "PVCCIOMCP_CPU0")
	)
	(segment
		(start 298.665646 -79.678784)
		(end 299.237146 -79.678784)
		(width 0.254)
		(layer "F.Cu")
		(net "PVCCIOMCP_CPU0")
	)
	(segment
		(start 293.51478 -77.697584)
		(end 294.08628 -77.697584)
		(width 0.1016)
		(layer "F.Cu")
		(net "PVCCIOMCP_CPU0")
	)
	(segment
		(start 297.807126 -79.183738)
		(end 298.378626 -79.183738)
		(width 0.254)
		(layer "F.Cu")
		(net "PVCCIOMCP_CPU0")
	)
	(segment
		(start 298.378626 -78.193138)
		(end 297.807126 -78.193138)
		(width 0.254)
		(layer "F.Cu")
		(net "PVCCIOMCP_CPU0")
	)
	(segment
		(start 297.807126 -77.202538)
		(end 298.378626 -77.202538)
		(width 0.254)
		(layer "F.Cu")
		(net "PVCCIOMCP_CPU0")
	)
	(segment
		(start 296.66184 -79.183738)
		(end 296.09034 -79.183738)
		(width 0.254)
		(layer "F.Cu")
		(net "PVCCIOMCP_CPU0")
	)
	(segment
		(start 295.23182 -77.697584)
		(end 295.80332 -77.697584)
		(width 0.254)
		(layer "F.Cu")
		(net "PVCCIOMCP_CPU0")
	)
	(segment
		(start 298.665646 -76.706984)
		(end 299.237146 -76.706984)
		(width 0.254)
		(layer "F.Cu")
		(net "PVCCIOMCP_CPU0")
	)
	(segment
		(start 295.23182 -78.688438)
		(end 295.80332 -78.688438)
		(width 0.254)
		(layer "F.Cu")
		(net "PVCCIOMCP_CPU0")
	)
	(segment
		(start 293.51478 -76.706984)
		(end 294.08628 -76.706984)
		(width 0.254)
		(layer "F.Cu")
		(net "PVCCIOMCP_CPU0")
	)
	(segment
		(start 296.948606 -79.678784)
		(end 297.520106 -79.678784)
		(width 0.254)
		(layer "F.Cu")
		(net "PVCCIOMCP_CPU0")
	)
	(segment
		(start 292.65626 -76.211938)
		(end 293.22776 -76.211938)
		(width 0.254)
		(layer "F.Cu")
		(net "PVCCIOMCP_CPU0")
	)
	(via
		(at 295.80332 -77.697584)
		(size 0.508)
		(drill 0.254)
		(layers "F.Cu" "B.Cu")
		(net "PVCCIOMCP_CPU0")
	)
	(via
		(at 293.22776 -79.183738)
		(size 0.508)
		(drill 0.254)
		(layers "F.Cu" "B.Cu")
		(net "PVCCIOMCP_CPU0")
	)
	(via
		(at 297.520106 -79.678784)
		(size 0.508)
		(drill 0.254)
		(layers "F.Cu" "B.Cu")
		(net "PVCCIOMCP_CPU0")
	)
	(via
		(at 297.520106 -77.697584)
		(size 0.508)
		(drill 0.254)
		(layers "F.Cu" "B.Cu")
		(net "PVCCIOMCP_CPU0")
	)
	(via
		(at 294.08628 -77.697584)
		(size 0.508)
		(drill 0.254)
		(layers "F.Cu" "B.Cu")
		(net "PVCCIOMCP_CPU0")
	)
	(via
		(at 353.0854 -109.855)
		(size 0.508)
		(drill 0.254)
		(layers "F.Cu" "B.Cu")
		(net "PVCCIOMCP_CPU0")
	)
	(via
		(at 299.237146 -78.688438)
		(size 0.508)
		(drill 0.254)
		(layers "F.Cu" "B.Cu")
		(net "PVCCIOMCP_CPU0")
	)
	(via
		(at 346.7354 -109.855)
		(size 0.508)
		(drill 0.254)
		(layers "F.Cu" "B.Cu")
		(net "PVCCIOMCP_CPU0")
	)
	(via
		(at 346.7354 -108.585)
		(size 0.508)
		(drill 0.254)
		(layers "F.Cu" "B.Cu")
		(net "PVCCIOMCP_CPU0")
	)
	(via
		(at 351.8154 -109.855)
		(size 0.508)
		(drill 0.254)
		(layers "F.Cu" "B.Cu")
		(net "PVCCIOMCP_CPU0")
	)
	(via
		(at 298.378626 -77.202538)
		(size 0.508)
		(drill 0.254)
		(layers "F.Cu" "B.Cu")
		(net "PVCCIOMCP_CPU0")
	)
	(via
		(at 346.7354 -111.125)
		(size 0.508)
		(drill 0.254)
		(layers "F.Cu" "B.Cu")
		(net "PVCCIOMCP_CPU0")
	)
	(via
		(at 299.237146 -76.706984)
		(size 0.508)
		(drill 0.254)
		(layers "F.Cu" "B.Cu")
		(net "PVCCIOMCP_CPU0")
	)
	(via
		(at 298.378626 -79.183738)
		(size 0.508)
		(drill 0.254)
		(layers "F.Cu" "B.Cu")
		(net "PVCCIOMCP_CPU0")
	)
	(via
		(at 295.80332 -78.688438)
		(size 0.508)
		(drill 0.254)
		(layers "F.Cu" "B.Cu")
		(net "PVCCIOMCP_CPU0")
	)
	(via
		(at 348.0054 -111.125)
		(size 0.508)
		(drill 0.254)
		(layers "F.Cu" "B.Cu")
		(net "PVCCIOMCP_CPU0")
	)
	(via
		(at 295.80332 -79.678784)
		(size 0.508)
		(drill 0.254)
		(layers "F.Cu" "B.Cu")
		(net "PVCCIOMCP_CPU0")
	)
	(via
		(at 297.520106 -78.688438)
		(size 0.508)
		(drill 0.254)
		(layers "F.Cu" "B.Cu")
		(net "PVCCIOMCP_CPU0")
	)
	(via
		(at 351.8154 -112.395)
		(size 0.508)
		(drill 0.254)
		(layers "F.Cu" "B.Cu")
		(net "PVCCIOMCP_CPU0")
	)
	(via
		(at 296.66184 -78.193138)
		(size 0.508)
		(drill 0.254)
		(layers "F.Cu" "B.Cu")
		(net "PVCCIOMCP_CPU0")
	)
	(via
		(at 350.5454 -111.125)
		(size 0.508)
		(drill 0.254)
		(layers "F.Cu" "B.Cu")
		(net "PVCCIOMCP_CPU0")
	)
	(via
		(at 299.237146 -77.697584)
		(size 0.508)
		(drill 0.254)
		(layers "F.Cu" "B.Cu")
		(net "PVCCIOMCP_CPU0")
	)
	(via
		(at 351.8154 -111.125)
		(size 0.508)
		(drill 0.254)
		(layers "F.Cu" "B.Cu")
		(net "PVCCIOMCP_CPU0")
	)
	(via
		(at 353.0346 -108.5596)
		(size 0.508)
		(drill 0.254)
		(layers "F.Cu" "B.Cu")
		(net "PVCCIOMCP_CPU0")
	)
	(via
		(at 294.08628 -76.706984)
		(size 0.508)
		(drill 0.254)
		(layers "F.Cu" "B.Cu")
		(net "PVCCIOMCP_CPU0")
	)
	(via
		(at 298.378626 -78.193138)
		(size 0.508)
		(drill 0.254)
		(layers "F.Cu" "B.Cu")
		(net "PVCCIOMCP_CPU0")
	)
	(via
		(at 349.2754 -111.125)
		(size 0.508)
		(drill 0.254)
		(layers "F.Cu" "B.Cu")
		(net "PVCCIOMCP_CPU0")
	)
	(via
		(at 299.237146 -79.678784)
		(size 0.508)
		(drill 0.254)
		(layers "F.Cu" "B.Cu")
		(net "PVCCIOMCP_CPU0")
	)
	(via
		(at 350.5454 -112.395)
		(size 0.508)
		(drill 0.254)
		(layers "F.Cu" "B.Cu")
		(net "PVCCIOMCP_CPU0")
	)
	(via
		(at 293.22776 -76.211938)
		(size 0.508)
		(drill 0.254)
		(layers "F.Cu" "B.Cu")
		(net "PVCCIOMCP_CPU0")
	)
	(via
		(at 351.8154 -108.585)
		(size 0.508)
		(drill 0.254)
		(layers "F.Cu" "B.Cu")
		(net "PVCCIOMCP_CPU0")
	)
	(via
		(at 293.22776 -77.202538)
		(size 0.508)
		(drill 0.254)
		(layers "F.Cu" "B.Cu")
		(net "PVCCIOMCP_CPU0")
	)
	(via
		(at 296.66184 -79.183738)
		(size 0.508)
		(drill 0.254)
		(layers "F.Cu" "B.Cu")
		(net "PVCCIOMCP_CPU0")
	)
	(via
		(at 296.66184 -77.202538)
		(size 0.508)
		(drill 0.254)
		(layers "F.Cu" "B.Cu")
		(net "PVCCIOMCP_CPU0")
	)
	(segment
		(start 472.746324 -132.366004)
		(end 472.51112 -132.1308)
		(width 0.254)
		(layer "F.Cu")
		(net "P1V8_MCP_CPU0")
	)
	(segment
		(start 284.929834 -79.678784)
		(end 284.358334 -79.678784)
		(width 0.381)
		(layer "F.Cu")
		(net "P1V8_MCP_CPU0")
	)
	(segment
		(start 284.929834 -78.688438)
		(end 284.358334 -78.688438)
		(width 0.1016)
		(layer "F.Cu")
		(net "P1V8_MCP_CPU0")
	)
	(segment
		(start 466.725 -132.715)
		(end 466.4964 -132.4864)
		(width 0.254)
		(layer "F.Cu")
		(net "P1V8_MCP_CPU0")
	)
	(segment
		(start 474.523816 -132.366004)
		(end 472.746324 -132.366004)
		(width 0.254)
		(layer "F.Cu")
		(net "P1V8_MCP_CPU0")
	)
	(segment
		(start 467.36 -132.715)
		(end 466.725 -132.715)
		(width 0.254)
		(layer "F.Cu")
		(net "P1V8_MCP_CPU0")
	)
	(segment
		(start 285.7881 -79.183738)
		(end 286.3596 -79.183738)
		(width 0.1016)
		(layer "F.Cu")
		(net "P1V8_MCP_CPU0")
	)
	(segment
		(start 284.929834 -80.669384)
		(end 284.358334 -80.669384)
		(width 0.381)
		(layer "F.Cu")
		(net "P1V8_MCP_CPU0")
	)
	(via
		(at 310.02732 -45.67174)
		(size 0.508)
		(drill 0.254)
		(layers "F.Cu" "B.Cu")
		(net "P1V8_MCP_CPU0")
	)
	(via
		(at 311.636156 -46.915832)
		(size 0.508)
		(drill 0.254)
		(layers "F.Cu" "B.Cu")
		(net "P1V8_MCP_CPU0")
	)
	(via
		(at 311.60212 -45.46092)
		(size 0.508)
		(drill 0.254)
		(layers "F.Cu" "B.Cu")
		(net "P1V8_MCP_CPU0")
	)
	(via
		(at 334.785716 -116.968778)
		(size 0.508)
		(drill 0.254)
		(layers "F.Cu" "B.Cu")
		(net "P1V8_MCP_CPU0")
	)
	(via
		(at 315.6712 -44.5008)
		(size 0.508)
		(drill 0.254)
		(layers "F.Cu" "B.Cu")
		(net "P1V8_MCP_CPU0")
	)
	(via
		(at 311.60212 -46.22292)
		(size 0.508)
		(drill 0.254)
		(layers "F.Cu" "B.Cu")
		(net "P1V8_MCP_CPU0")
	)
	(via
		(at 336.04962 -54.998874)
		(size 0.508)
		(drill 0.254)
		(layers "F.Cu" "B.Cu")
		(net "P1V8_MCP_CPU0")
	)
	(via
		(at 332.78445 -39.292784)
		(size 0.508)
		(drill 0.254)
		(layers "F.Cu" "B.Cu")
		(net "P1V8_MCP_CPU0")
	)
	(via
		(at 313.12612 -46.22292)
		(size 0.508)
		(drill 0.254)
		(layers "F.Cu" "B.Cu")
		(net "P1V8_MCP_CPU0")
	)
	(via
		(at 328.10069 -38.115494)
		(size 0.508)
		(drill 0.254)
		(layers "F.Cu" "B.Cu")
		(net "P1V8_MCP_CPU0")
	)
	(via
		(at 284.358334 -78.688438)
		(size 0.508)
		(drill 0.254)
		(layers "F.Cu" "B.Cu")
		(net "P1V8_MCP_CPU0")
	)
	(via
		(at 328.99096 -38.05682)
		(size 0.508)
		(drill 0.254)
		(layers "F.Cu" "B.Cu")
		(net "P1V8_MCP_CPU0")
	)
	(via
		(at 316.08014 -43.9801)
		(size 0.508)
		(drill 0.254)
		(layers "F.Cu" "B.Cu")
		(net "P1V8_MCP_CPU0")
	)
	(via
		(at 433.264818 -122.538236)
		(size 0.508)
		(drill 0.254)
		(layers "F.Cu" "B.Cu")
		(net "P1V8_MCP_CPU0")
	)
	(via
		(at 328.973688 -39.03218)
		(size 0.508)
		(drill 0.254)
		(layers "F.Cu" "B.Cu")
		(net "P1V8_MCP_CPU0")
	)
	(via
		(at 466.4964 -132.4864)
		(size 0.508)
		(drill 0.254)
		(layers "F.Cu" "B.Cu")
		(net "P1V8_MCP_CPU0")
	)
	(via
		(at 328.50709 -37.636958)
		(size 0.508)
		(drill 0.254)
		(layers "F.Cu" "B.Cu")
		(net "P1V8_MCP_CPU0")
	)
	(via
		(at 328.110088 -39.038276)
		(size 0.508)
		(drill 0.254)
		(layers "F.Cu" "B.Cu")
		(net "P1V8_MCP_CPU0")
	)
	(via
		(at 328.559922 -38.546024)
		(size 0.508)
		(drill 0.254)
		(layers "F.Cu" "B.Cu")
		(net "P1V8_MCP_CPU0")
	)
	(via
		(at 312.36412 -45.46092)
		(size 0.508)
		(drill 0.254)
		(layers "F.Cu" "B.Cu")
		(net "P1V8_MCP_CPU0")
	)
	(via
		(at 472.51112 -132.1308)
		(size 0.508)
		(drill 0.254)
		(layers "F.Cu" "B.Cu")
		(net "P1V8_MCP_CPU0")
	)
	(via
		(at 312.36412 -46.22292)
		(size 0.508)
		(drill 0.254)
		(layers "F.Cu" "B.Cu")
		(net "P1V8_MCP_CPU0")
	)
	(via
		(at 316.71514 -43.9801)
		(size 0.508)
		(drill 0.254)
		(layers "F.Cu" "B.Cu")
		(net "P1V8_MCP_CPU0")
	)
	(via
		(at 448.5894 -132.365496)
		(size 0.508)
		(drill 0.254)
		(layers "F.Cu" "B.Cu")
		(net "P1V8_MCP_CPU0")
	)
	(via
		(at 286.3596 -79.183738)
		(size 0.508)
		(drill 0.254)
		(layers "F.Cu" "B.Cu")
		(net "P1V8_MCP_CPU0")
	)
	(via
		(at 313.12612 -45.46092)
		(size 0.508)
		(drill 0.254)
		(layers "F.Cu" "B.Cu")
		(net "P1V8_MCP_CPU0")
	)
	(via
		(at 284.358334 -80.669384)
		(size 0.508)
		(drill 0.254)
		(layers "F.Cu" "B.Cu")
		(net "P1V8_MCP_CPU0")
	)
	(via
		(at 284.358334 -79.678784)
		(size 0.508)
		(drill 0.254)
		(layers "F.Cu" "B.Cu")
		(net "P1V8_MCP_CPU0")
	)
	(via
		(at 454.4822 -132.08)
		(size 0.508)
		(drill 0.254)
		(layers "F.Cu" "B.Cu")
		(net "P1V8_MCP_CPU0")
	)
	(segment
		(start 466.777832 -132.204968)
		(end 472.436952 -132.204968)
		(width 0.254)
		(layer "B.Cu")
		(net "P1V8_MCP_CPU0")
	)
	(segment
		(start 448.5894 -132.365496)
		(end 448.5894 -132.3086)
		(width 0.254)
		(layer "B.Cu")
		(net "P1V8_MCP_CPU0")
	)
	(segment
		(start 449.199 -131.699)
		(end 449.199 -131.318)
		(width 0.254)
		(layer "B.Cu")
		(net "P1V8_MCP_CPU0")
	)
	(segment
		(start 453.832214 -128.6764)
		(end 453.832214 -131.836414)
		(width 0.254)
		(layer "B.Cu")
		(net "P1V8_MCP_CPU0")
	)
	(segment
		(start 472.436952 -132.204968)
		(end 472.51112 -132.1308)
		(width 0.254)
		(layer "B.Cu")
		(net "P1V8_MCP_CPU0")
	)
	(segment
		(start 336.04962 -55.850028)
		(end 336.04962 -54.998874)
		(width 0.254)
		(layer "B.Cu")
		(net "P1V8_MCP_CPU0")
	)
	(segment
		(start 453.8472 -131.8514)
		(end 454.0758 -132.08)
		(width 0.254)
		(layer "B.Cu")
		(net "P1V8_MCP_CPU0")
	)
	(segment
		(start 326.638158 -57.524904)
		(end 323.614796 -57.524904)
		(width 0.254)
		(layer "B.Cu")
		(net "P1V8_MCP_CPU0")
	)
	(segment
		(start 472.51112 -132.1308)
		(end 472.858592 -131.783328)
		(width 0.254)
		(layer "B.Cu")
		(net "P1V8_MCP_CPU0")
	)
	(segment
		(start 335.530952 -56.368696)
		(end 336.04962 -55.850028)
		(width 0.254)
		(layer "B.Cu")
		(net "P1V8_MCP_CPU0")
	)
	(segment
		(start 310.782716 -55.188104)
		(end 311.501536 -55.906924)
		(width 0.254)
		(layer "B.Cu")
		(net "P1V8_MCP_CPU0")
	)
	(segment
		(start 310.782716 -47.941738)
		(end 310.782716 -55.188104)
		(width 0.254)
		(layer "B.Cu")
		(net "P1V8_MCP_CPU0")
	)
	(segment
		(start 472.858592 -130.977132)
		(end 471.95486 -130.0734)
		(width 0.254)
		(layer "B.Cu")
		(net "P1V8_MCP_CPU0")
	)
	(segment
		(start 472.858592 -131.783328)
		(end 472.858592 -130.977132)
		(width 0.254)
		(layer "B.Cu")
		(net "P1V8_MCP_CPU0")
	)
	(segment
		(start 329.356466 -57.266332)
		(end 330.927202 -57.266332)
		(width 0.254)
		(layer "B.Cu")
		(net "P1V8_MCP_CPU0")
	)
	(segment
		(start 471.14206 -130.0734)
		(end 471.95486 -130.0734)
		(width 0.254)
		(layer "B.Cu")
		(net "P1V8_MCP_CPU0")
	)
	(segment
		(start 310.02732 -47.186342)
		(end 310.782716 -47.941738)
		(width 0.254)
		(layer "B.Cu")
		(net "P1V8_MCP_CPU0")
	)
	(segment
		(start 317.438024 -58.633614)
		(end 322.506086 -58.633614)
		(width 0.254)
		(layer "B.Cu")
		(net "P1V8_MCP_CPU0")
	)
	(segment
		(start 313.831478 -55.906924)
		(end 315.541914 -57.61736)
		(width 0.254)
		(layer "B.Cu")
		(net "P1V8_MCP_CPU0")
	)
	(segment
		(start 330.927202 -57.266332)
		(end 331.824838 -56.368696)
		(width 0.254)
		(layer "B.Cu")
		(net "P1V8_MCP_CPU0")
	)
	(segment
		(start 466.4964 -132.4864)
		(end 466.777832 -132.204968)
		(width 0.254)
		(layer "B.Cu")
		(net "P1V8_MCP_CPU0")
	)
	(segment
		(start 310.02732 -45.67174)
		(end 310.02732 -47.186342)
		(width 0.254)
		(layer "B.Cu")
		(net "P1V8_MCP_CPU0")
	)
	(segment
		(start 316.42177 -57.61736)
		(end 317.438024 -58.633614)
		(width 0.254)
		(layer "B.Cu")
		(net "P1V8_MCP_CPU0")
	)
	(segment
		(start 454.0758 -132.08)
		(end 454.4822 -132.08)
		(width 0.254)
		(layer "B.Cu")
		(net "P1V8_MCP_CPU0")
	)
	(segment
		(start 311.501536 -55.906924)
		(end 313.831478 -55.906924)
		(width 0.254)
		(layer "B.Cu")
		(net "P1V8_MCP_CPU0")
	)
	(segment
		(start 315.541914 -57.61736)
		(end 316.42177 -57.61736)
		(width 0.254)
		(layer "B.Cu")
		(net "P1V8_MCP_CPU0")
	)
	(segment
		(start 326.541892 -54.597808)
		(end 327.158096 -54.597808)
		(width 0.254)
		(layer "B.Cu")
		(net "P1V8_MCP_CPU0")
	)
	(segment
		(start 323.614796 -57.524904)
		(end 326.541892 -54.597808)
		(width 0.254)
		(layer "B.Cu")
		(net "P1V8_MCP_CPU0")
	)
	(segment
		(start 326.89673 -57.266332)
		(end 326.638158 -57.524904)
		(width 0.254)
		(layer "B.Cu")
		(net "P1V8_MCP_CPU0")
	)
	(segment
		(start 329.356466 -57.266332)
		(end 326.89673 -57.266332)
		(width 0.254)
		(layer "B.Cu")
		(net "P1V8_MCP_CPU0")
	)
	(segment
		(start 448.5894 -132.3086)
		(end 449.199 -131.699)
		(width 0.254)
		(layer "B.Cu")
		(net "P1V8_MCP_CPU0")
	)
	(segment
		(start 453.832214 -131.836414)
		(end 453.8472 -131.8514)
		(width 0.254)
		(layer "B.Cu")
		(net "P1V8_MCP_CPU0")
	)
	(segment
		(start 322.506086 -58.633614)
		(end 323.614796 -57.524904)
		(width 0.254)
		(layer "B.Cu")
		(net "P1V8_MCP_CPU0")
	)
	(segment
		(start 331.824838 -56.368696)
		(end 335.530952 -56.368696)
		(width 0.254)
		(layer "B.Cu")
		(net "P1V8_MCP_CPU0")
	)
	(segment
		(start 462.166462 -132.728462)
		(end 462.9912 -133.5532)
		(width 0.254)
		(layer "In2.Cu")
		(net "P1V8_MCP_CPU0")
	)
	(segment
		(start 465.0994 -132.4864)
		(end 466.4964 -132.4864)
		(width 0.254)
		(layer "In2.Cu")
		(net "P1V8_MCP_CPU0")
	)
	(segment
		(start 462.9912 -133.5532)
		(end 464.0326 -133.5532)
		(width 0.254)
		(layer "In2.Cu")
		(net "P1V8_MCP_CPU0")
	)
	(segment
		(start 454.7108 -131.8514)
		(end 459.023212 -131.8514)
		(width 0.254)
		(layer "In2.Cu")
		(net "P1V8_MCP_CPU0")
	)
	(segment
		(start 459.900274 -132.728462)
		(end 462.166462 -132.728462)
		(width 0.254)
		(layer "In2.Cu")
		(net "P1V8_MCP_CPU0")
	)
	(segment
		(start 464.0326 -133.5532)
		(end 465.0994 -132.4864)
		(width 0.254)
		(layer "In2.Cu")
		(net "P1V8_MCP_CPU0")
	)
	(segment
		(start 454.4822 -132.08)
		(end 454.7108 -131.8514)
		(width 0.254)
		(layer "In2.Cu")
		(net "P1V8_MCP_CPU0")
	)
	(segment
		(start 459.023212 -131.8514)
		(end 459.900274 -132.728462)
		(width 0.254)
		(layer "In2.Cu")
		(net "P1V8_MCP_CPU0")
	)
	(segment
		(start 450.3166 -132.08)
		(end 449.5292 -132.8674)
		(width 0.254)
		(layer "In4.Cu")
		(net "P1V8_MCP_CPU0")
	)
	(segment
		(start 449.5292 -132.8674)
		(end 448.8434 -132.8674)
		(width 0.254)
		(layer "In4.Cu")
		(net "P1V8_MCP_CPU0")
	)
	(segment
		(start 448.8434 -132.8674)
		(end 448.5894 -132.6134)
		(width 0.254)
		(layer "In4.Cu")
		(net "P1V8_MCP_CPU0")
	)
	(segment
		(start 448.5894 -132.6134)
		(end 448.5894 -132.365496)
		(width 0.254)
		(layer "In4.Cu")
		(net "P1V8_MCP_CPU0")
	)
	(segment
		(start 454.4822 -132.08)
		(end 450.3166 -132.08)
		(width 0.254)
		(layer "In4.Cu")
		(net "P1V8_MCP_CPU0")
	)
	(segment
		(start 331.400404 -73.10882)
		(end 331.400404 -68.928488)
		(width 0.254)
		(layer "In9.Cu")
		(net "P1V8_MCP_CPU0")
	)
	(segment
		(start 333.035656 -89.449656)
		(end 332.195932 -88.609932)
		(width 0.254)
		(layer "In9.Cu")
		(net "P1V8_MCP_CPU0")
	)
	(segment
		(start 447.7766 -130.5052)
		(end 448.5894 -131.318)
		(width 0.254)
		(layer "In9.Cu")
		(net "P1V8_MCP_CPU0")
	)
	(segment
		(start 333.375 -108.3564)
		(end 332.831948 -107.813348)
		(width 0.254)
		(layer "In9.Cu")
		(net "P1V8_MCP_CPU0")
	)
	(segment
		(start 332.643988 -78.02499)
		(end 332.643988 -74.352404)
		(width 0.254)
		(layer "In9.Cu")
		(net "P1V8_MCP_CPU0")
	)
	(segment
		(start 447.7766 -125.826012)
		(end 447.7766 -130.5052)
		(width 0.254)
		(layer "In9.Cu")
		(net "P1V8_MCP_CPU0")
	)
	(segment
		(start 332.643988 -74.352404)
		(end 331.400404 -73.10882)
		(width 0.254)
		(layer "In9.Cu")
		(net "P1V8_MCP_CPU0")
	)
	(segment
		(start 333.375 -92.896944)
		(end 333.035656 -92.5576)
		(width 0.254)
		(layer "In9.Cu")
		(net "P1V8_MCP_CPU0")
	)
	(segment
		(start 331.400404 -68.928488)
		(end 334.455262 -65.87363)
		(width 0.254)
		(layer "In9.Cu")
		(net "P1V8_MCP_CPU0")
	)
	(segment
		(start 334.455262 -65.87363)
		(end 334.455262 -64.121538)
		(width 0.254)
		(layer "In9.Cu")
		(net "P1V8_MCP_CPU0")
	)
	(segment
		(start 334.785716 -116.968778)
		(end 334.785716 -116.486178)
		(width 0.254)
		(layer "In9.Cu")
		(net "P1V8_MCP_CPU0")
	)
	(segment
		(start 446.874138 -124.92355)
		(end 447.7766 -125.826012)
		(width 0.254)
		(layer "In9.Cu")
		(net "P1V8_MCP_CPU0")
	)
	(segment
		(start 332.195932 -78.473046)
		(end 332.643988 -78.02499)
		(width 0.254)
		(layer "In9.Cu")
		(net "P1V8_MCP_CPU0")
	)
	(segment
		(start 333.375 -105.354628)
		(end 333.375 -92.896944)
		(width 0.254)
		(layer "In9.Cu")
		(net "P1V8_MCP_CPU0")
	)
	(segment
		(start 448.5894 -131.318)
		(end 448.5894 -132.365496)
		(width 0.254)
		(layer "In9.Cu")
		(net "P1V8_MCP_CPU0")
	)
	(segment
		(start 333.375 -110.109)
		(end 333.375 -108.3564)
		(width 0.254)
		(layer "In9.Cu")
		(net "P1V8_MCP_CPU0")
	)
	(segment
		(start 334.7847 -111.5187)
		(end 333.375 -110.109)
		(width 0.254)
		(layer "In9.Cu")
		(net "P1V8_MCP_CPU0")
	)
	(segment
		(start 333.035656 -92.5576)
		(end 333.035656 -89.449656)
		(width 0.254)
		(layer "In9.Cu")
		(net "P1V8_MCP_CPU0")
	)
	(segment
		(start 334.7847 -116.485162)
		(end 334.7847 -111.5187)
		(width 0.254)
		(layer "In9.Cu")
		(net "P1V8_MCP_CPU0")
	)
	(segment
		(start 336.04962 -62.52718)
		(end 336.04962 -54.998874)
		(width 0.254)
		(layer "In9.Cu")
		(net "P1V8_MCP_CPU0")
	)
	(segment
		(start 437.444388 -122.538236)
		(end 439.829702 -124.92355)
		(width 0.254)
		(layer "In9.Cu")
		(net "P1V8_MCP_CPU0")
	)
	(segment
		(start 332.195932 -88.609932)
		(end 332.195932 -78.473046)
		(width 0.254)
		(layer "In9.Cu")
		(net "P1V8_MCP_CPU0")
	)
	(segment
		(start 334.455262 -64.121538)
		(end 336.04962 -62.52718)
		(width 0.254)
		(layer "In9.Cu")
		(net "P1V8_MCP_CPU0")
	)
	(segment
		(start 439.829702 -124.92355)
		(end 446.874138 -124.92355)
		(width 0.254)
		(layer "In9.Cu")
		(net "P1V8_MCP_CPU0")
	)
	(segment
		(start 332.831948 -107.813348)
		(end 332.831948 -105.898696)
		(width 0.254)
		(layer "In9.Cu")
		(net "P1V8_MCP_CPU0")
	)
	(segment
		(start 433.264818 -122.538236)
		(end 437.444388 -122.538236)
		(width 0.254)
		(layer "In9.Cu")
		(net "P1V8_MCP_CPU0")
	)
	(segment
		(start 334.785716 -116.486178)
		(end 334.7847 -116.485162)
		(width 0.254)
		(layer "In9.Cu")
		(net "P1V8_MCP_CPU0")
	)
	(segment
		(start 332.831948 -105.898696)
		(end 333.375 -105.354628)
		(width 0.254)
		(layer "In9.Cu")
		(net "P1V8_MCP_CPU0")
	)
	(segment
		(start 370.679218 -123.730258)
		(end 370.679218 -124.885958)
		(width 0.254)
		(layer "In11.Cu")
		(net "P1V8_MCP_CPU0")
	)
	(segment
		(start 374.409208 -128.029208)
		(end 379.017276 -128.029208)
		(width 0.254)
		(layer "In11.Cu")
		(net "P1V8_MCP_CPU0")
	)
	(segment
		(start 412.93542 -134.601966)
		(end 414.638236 -134.601966)
		(width 0.254)
		(layer "In11.Cu")
		(net "P1V8_MCP_CPU0")
	)
	(segment
		(start 380.50978 -129.794508)
		(end 381.837438 -129.794508)
		(width 0.254)
		(layer "In11.Cu")
		(net "P1V8_MCP_CPU0")
	)
	(segment
		(start 425.775882 -124.6886)
		(end 428.339758 -122.124724)
		(width 0.254)
		(layer "In11.Cu")
		(net "P1V8_MCP_CPU0")
	)
	(segment
		(start 381.837438 -129.794508)
		(end 382.28016 -130.23723)
		(width 0.254)
		(layer "In11.Cu")
		(net "P1V8_MCP_CPU0")
	)
	(segment
		(start 432.851306 -122.124724)
		(end 433.264818 -122.538236)
		(width 0.254)
		(layer "In11.Cu")
		(net "P1V8_MCP_CPU0")
	)
	(segment
		(start 418.732208 -132.190236)
		(end 423.465244 -127.4572)
		(width 0.254)
		(layer "In11.Cu")
		(net "P1V8_MCP_CPU0")
	)
	(segment
		(start 370.479574 -122.973846)
		(end 370.479574 -123.530614)
		(width 0.254)
		(layer "In11.Cu")
		(net "P1V8_MCP_CPU0")
	)
	(segment
		(start 415.684462 -132.190236)
		(end 418.732208 -132.190236)
		(width 0.254)
		(layer "In11.Cu")
		(net "P1V8_MCP_CPU0")
	)
	(segment
		(start 401.479004 -134.881366)
		(end 404.98141 -131.382008)
		(width 0.254)
		(layer "In11.Cu")
		(net "P1V8_MCP_CPU0")
	)
	(segment
		(start 415.036 -134.204202)
		(end 415.036 -132.838698)
		(width 0.254)
		(layer "In11.Cu")
		(net "P1V8_MCP_CPU0")
	)
	(segment
		(start 404.98141 -131.382008)
		(end 408.169872 -131.382008)
		(width 0.254)
		(layer "In11.Cu")
		(net "P1V8_MCP_CPU0")
	)
	(segment
		(start 334.785716 -116.968778)
		(end 334.785716 -118.172992)
		(width 0.254)
		(layer "In11.Cu")
		(net "P1V8_MCP_CPU0")
	)
	(segment
		(start 372.834154 -127.6858)
		(end 374.0658 -127.6858)
		(width 0.254)
		(layer "In11.Cu")
		(net "P1V8_MCP_CPU0")
	)
	(segment
		(start 428.339758 -122.124724)
		(end 432.851306 -122.124724)
		(width 0.254)
		(layer "In11.Cu")
		(net "P1V8_MCP_CPU0")
	)
	(segment
		(start 415.036 -132.838698)
		(end 415.684462 -132.190236)
		(width 0.254)
		(layer "In11.Cu")
		(net "P1V8_MCP_CPU0")
	)
	(segment
		(start 345.330526 -119.55526)
		(end 367.060988 -119.55526)
		(width 0.254)
		(layer "In11.Cu")
		(net "P1V8_MCP_CPU0")
	)
	(segment
		(start 370.902484 -125.109224)
		(end 370.902484 -125.75413)
		(width 0.254)
		(layer "In11.Cu")
		(net "P1V8_MCP_CPU0")
	)
	(segment
		(start 379.017276 -128.029208)
		(end 379.6792 -128.691132)
		(width 0.254)
		(layer "In11.Cu")
		(net "P1V8_MCP_CPU0")
	)
	(segment
		(start 410.874464 -134.0866)
		(end 412.420054 -134.0866)
		(width 0.254)
		(layer "In11.Cu")
		(net "P1V8_MCP_CPU0")
	)
	(segment
		(start 337.222338 -120.609614)
		(end 342.409018 -120.609614)
		(width 0.254)
		(layer "In11.Cu")
		(net "P1V8_MCP_CPU0")
	)
	(segment
		(start 370.479574 -123.530614)
		(end 370.679218 -123.730258)
		(width 0.254)
		(layer "In11.Cu")
		(net "P1V8_MCP_CPU0")
	)
	(segment
		(start 384.109976 -130.23723)
		(end 389.496554 -135.623808)
		(width 0.254)
		(layer "In11.Cu")
		(net "P1V8_MCP_CPU0")
	)
	(segment
		(start 345.190064 -119.414798)
		(end 345.330526 -119.55526)
		(width 0.254)
		(layer "In11.Cu")
		(net "P1V8_MCP_CPU0")
	)
	(segment
		(start 379.6792 -128.963928)
		(end 380.50978 -129.794508)
		(width 0.254)
		(layer "In11.Cu")
		(net "P1V8_MCP_CPU0")
	)
	(segment
		(start 342.409018 -120.609614)
		(end 343.603834 -119.414798)
		(width 0.254)
		(layer "In11.Cu")
		(net "P1V8_MCP_CPU0")
	)
	(segment
		(start 370.679218 -124.885958)
		(end 370.902484 -125.109224)
		(width 0.254)
		(layer "In11.Cu")
		(net "P1V8_MCP_CPU0")
	)
	(segment
		(start 400.264122 -134.881366)
		(end 401.479004 -134.881366)
		(width 0.254)
		(layer "In11.Cu")
		(net "P1V8_MCP_CPU0")
	)
	(segment
		(start 408.169872 -131.382008)
		(end 410.874464 -134.0866)
		(width 0.254)
		(layer "In11.Cu")
		(net "P1V8_MCP_CPU0")
	)
	(segment
		(start 423.465244 -127.4572)
		(end 425.09821 -127.4572)
		(width 0.254)
		(layer "In11.Cu")
		(net "P1V8_MCP_CPU0")
	)
	(segment
		(start 412.420054 -134.0866)
		(end 412.93542 -134.601966)
		(width 0.254)
		(layer "In11.Cu")
		(net "P1V8_MCP_CPU0")
	)
	(segment
		(start 379.6792 -128.691132)
		(end 379.6792 -128.963928)
		(width 0.254)
		(layer "In11.Cu")
		(net "P1V8_MCP_CPU0")
	)
	(segment
		(start 389.496554 -135.623808)
		(end 399.52168 -135.623808)
		(width 0.254)
		(layer "In11.Cu")
		(net "P1V8_MCP_CPU0")
	)
	(segment
		(start 374.0658 -127.6858)
		(end 374.409208 -128.029208)
		(width 0.254)
		(layer "In11.Cu")
		(net "P1V8_MCP_CPU0")
	)
	(segment
		(start 382.28016 -130.23723)
		(end 384.109976 -130.23723)
		(width 0.254)
		(layer "In11.Cu")
		(net "P1V8_MCP_CPU0")
	)
	(segment
		(start 399.52168 -135.623808)
		(end 400.264122 -134.881366)
		(width 0.254)
		(layer "In11.Cu")
		(net "P1V8_MCP_CPU0")
	)
	(segment
		(start 414.638236 -134.601966)
		(end 415.036 -134.204202)
		(width 0.254)
		(layer "In11.Cu")
		(net "P1V8_MCP_CPU0")
	)
	(segment
		(start 334.785716 -118.172992)
		(end 337.222338 -120.609614)
		(width 0.254)
		(layer "In11.Cu")
		(net "P1V8_MCP_CPU0")
	)
	(segment
		(start 425.09821 -127.4572)
		(end 425.775882 -126.779528)
		(width 0.254)
		(layer "In11.Cu")
		(net "P1V8_MCP_CPU0")
	)
	(segment
		(start 367.060988 -119.55526)
		(end 370.479574 -122.973846)
		(width 0.254)
		(layer "In11.Cu")
		(net "P1V8_MCP_CPU0")
	)
	(segment
		(start 343.603834 -119.414798)
		(end 345.190064 -119.414798)
		(width 0.254)
		(layer "In11.Cu")
		(net "P1V8_MCP_CPU0")
	)
	(segment
		(start 370.902484 -125.75413)
		(end 372.834154 -127.6858)
		(width 0.254)
		(layer "In11.Cu")
		(net "P1V8_MCP_CPU0")
	)
	(segment
		(start 425.775882 -126.779528)
		(end 425.775882 -124.6886)
		(width 0.254)
		(layer "In11.Cu")
		(net "P1V8_MCP_CPU0")
	)
	(segment
		(start 407.750264 -92.028772)
		(end 406.50922 -92.028772)
		(width 0.10795)
		(layer "F.Cu")
		(net "LED_GBE_P3_0")
	)
	(segment
		(start 458.149706 -62.002924)
		(end 458.149706 -63.31077)
		(width 0.10795)
		(layer "F.Cu")
		(net "LED_GBE_P3_0")
	)
	(segment
		(start 409.485084 -92.813378)
		(end 408.88539 -92.813378)
		(width 0.10795)
		(layer "F.Cu")
		(net "LED_GBE_P3_0")
	)
	(segment
		(start 404.709376 -93.828616)
		(end 404.709376 -96.254824)
		(width 0.10795)
		(layer "F.Cu")
		(net "LED_GBE_P3_0")
	)
	(segment
		(start 406.50922 -92.028772)
		(end 404.709376 -93.828616)
		(width 0.10795)
		(layer "F.Cu")
		(net "LED_GBE_P3_0")
	)
	(segment
		(start 401.796504 -98.456496)
		(end 401.397978 -98.855022)
		(width 0.10795)
		(layer "F.Cu")
		(net "LED_GBE_P3_0")
	)
	(segment
		(start 409.991306 -93.3196)
		(end 409.485084 -92.813378)
		(width 0.10795)
		(layer "F.Cu")
		(net "LED_GBE_P3_0")
	)
	(segment
		(start 410.0576 -93.3196)
		(end 410.692346 -92.684854)
		(width 0.10795)
		(layer "F.Cu")
		(net "LED_GBE_P3_0")
	)
	(segment
		(start 408.020774 -92.299282)
		(end 407.750264 -92.028772)
		(width 0.10795)
		(layer "F.Cu")
		(net "LED_GBE_P3_0")
	)
	(segment
		(start 404.709376 -96.254824)
		(end 402.507704 -98.456496)
		(width 0.10795)
		(layer "F.Cu")
		(net "LED_GBE_P3_0")
	)
	(segment
		(start 408.88539 -92.813378)
		(end 408.371294 -92.299282)
		(width 0.10795)
		(layer "F.Cu")
		(net "LED_GBE_P3_0")
	)
	(segment
		(start 414.005776 -82.67065)
		(end 414.005776 -82.355944)
		(width 0.10795)
		(layer "F.Cu")
		(net "LED_GBE_P3_0")
	)
	(segment
		(start 414.005776 -82.355944)
		(end 414.005776 -81.370424)
		(width 0.10795)
		(layer "F.Cu")
		(net "LED_GBE_P3_0")
	)
	(segment
		(start 415.968434 -79.242158)
		(end 416.410902 -78.79969)
		(width 0.10795)
		(layer "F.Cu")
		(net "LED_GBE_P3_0")
	)
	(segment
		(start 458.149706 -63.31077)
		(end 458.314552 -63.475616)
		(width 0.10795)
		(layer "F.Cu")
		(net "LED_GBE_P3_0")
	)
	(segment
		(start 410.692346 -84.26323)
		(end 411.258512 -83.697064)
		(width 0.10795)
		(layer "F.Cu")
		(net "LED_GBE_P3_0")
	)
	(segment
		(start 411.258512 -83.697064)
		(end 412.979362 -83.697064)
		(width 0.10795)
		(layer "F.Cu")
		(net "LED_GBE_P3_0")
	)
	(segment
		(start 402.507704 -98.456496)
		(end 401.796504 -98.456496)
		(width 0.10795)
		(layer "F.Cu")
		(net "LED_GBE_P3_0")
	)
	(segment
		(start 415.968434 -79.407766)
		(end 415.968434 -79.242158)
		(width 0.10795)
		(layer "F.Cu")
		(net "LED_GBE_P3_0")
	)
	(segment
		(start 408.371294 -92.299282)
		(end 408.020774 -92.299282)
		(width 0.10795)
		(layer "F.Cu")
		(net "LED_GBE_P3_0")
	)
	(segment
		(start 410.692346 -92.684854)
		(end 410.692346 -84.26323)
		(width 0.10795)
		(layer "F.Cu")
		(net "LED_GBE_P3_0")
	)
	(segment
		(start 401.397978 -98.855022)
		(end 401.295108 -98.855022)
		(width 0.10795)
		(layer "F.Cu")
		(net "LED_GBE_P3_0")
	)
	(segment
		(start 412.979362 -83.697064)
		(end 414.005776 -82.67065)
		(width 0.10795)
		(layer "F.Cu")
		(net "LED_GBE_P3_0")
	)
	(segment
		(start 458.14996 -62.00267)
		(end 458.149706 -62.002924)
		(width 0.10795)
		(layer "F.Cu")
		(net "LED_GBE_P3_0")
	)
	(segment
		(start 410.0576 -93.3196)
		(end 409.991306 -93.3196)
		(width 0.10795)
		(layer "F.Cu")
		(net "LED_GBE_P3_0")
	)
	(segment
		(start 414.005776 -81.370424)
		(end 415.968434 -79.407766)
		(width 0.10795)
		(layer "F.Cu")
		(net "LED_GBE_P3_0")
	)
	(via
		(at 458.314552 -63.475616)
		(size 0.508)
		(drill 0.254)
		(layers "F.Cu" "B.Cu")
		(net "LED_GBE_P3_0")
	)
	(via
		(at 416.410902 -78.79969)
		(size 0.508)
		(drill 0.254)
		(layers "F.Cu" "B.Cu")
		(net "LED_GBE_P3_0")
	)
	(via
		(at 414.005776 -82.355944)
		(size 0.762)
		(drill 0.381)
		(layers "F.Cu" "B.Cu")
		(net "LED_GBE_P3_0")
	)
	(via
		(at 410.0576 -93.3196)
		(size 0.762)
		(drill 0.381)
		(layers "F.Cu" "B.Cu")
		(net "LED_GBE_P3_0")
	)
	(segment
		(start 458.314552 -63.562992)
		(end 457.245466 -64.632078)
		(width 0.089408)
		(layer "In4.Cu")
		(net "LED_GBE_P3_0")
	)
	(segment
		(start 423.356278 -63.968884)
		(end 422.65981 -64.665352)
		(width 0.089408)
		(layer "In4.Cu")
		(net "LED_GBE_P3_0")
	)
	(segment
		(start 458.314552 -63.475616)
		(end 458.314552 -63.562992)
		(width 0.089408)
		(layer "In4.Cu")
		(net "LED_GBE_P3_0")
	)
	(segment
		(start 416.996626 -70.26148)
		(end 416.996626 -78.213966)
		(width 0.089408)
		(layer "In4.Cu")
		(net "LED_GBE_P3_0")
	)
	(segment
		(start 457.245466 -64.632078)
		(end 425.913296 -64.632078)
		(width 0.089408)
		(layer "In4.Cu")
		(net "LED_GBE_P3_0")
	)
	(segment
		(start 421.154098 -64.665352)
		(end 418.636958 -67.182492)
		(width 0.089408)
		(layer "In4.Cu")
		(net "LED_GBE_P3_0")
	)
	(segment
		(start 418.636958 -67.182492)
		(end 418.636958 -68.621148)
		(width 0.089408)
		(layer "In4.Cu")
		(net "LED_GBE_P3_0")
	)
	(segment
		(start 416.996626 -78.213966)
		(end 416.410902 -78.79969)
		(width 0.089408)
		(layer "In4.Cu")
		(net "LED_GBE_P3_0")
	)
	(segment
		(start 418.636958 -68.621148)
		(end 416.996626 -70.26148)
		(width 0.089408)
		(layer "In4.Cu")
		(net "LED_GBE_P3_0")
	)
	(segment
		(start 425.913296 -64.632078)
		(end 425.250102 -63.968884)
		(width 0.089408)
		(layer "In4.Cu")
		(net "LED_GBE_P3_0")
	)
	(segment
		(start 422.65981 -64.665352)
		(end 421.154098 -64.665352)
		(width 0.089408)
		(layer "In4.Cu")
		(net "LED_GBE_P3_0")
	)
	(segment
		(start 425.250102 -63.968884)
		(end 423.356278 -63.968884)
		(width 0.089408)
		(layer "In4.Cu")
		(net "LED_GBE_P3_0")
	)
	(segment
		(start 407.527506 -81.366106)
		(end 406.276048 -80.114648)
		(width 0.10795)
		(layer "F.Cu")
		(net "LED_GBE_P2_1")
	)
	(segment
		(start 402.795994 -90.611198)
		(end 403.994874 -90.611198)
		(width 0.10795)
		(layer "F.Cu")
		(net "LED_GBE_P2_1")
	)
	(segment
		(start 407.527506 -82.4484)
		(end 407.527506 -81.366106)
		(width 0.10795)
		(layer "F.Cu")
		(net "LED_GBE_P2_1")
	)
	(segment
		(start 406.9842 -84.869528)
		(end 407.527506 -84.326222)
		(width 0.10795)
		(layer "F.Cu")
		(net "LED_GBE_P2_1")
	)
	(segment
		(start 401.332446 -93.597984)
		(end 401.332446 -92.074746)
		(width 0.10795)
		(layer "F.Cu")
		(net "LED_GBE_P2_1")
	)
	(segment
		(start 451.749922 -59.01055)
		(end 452.124064 -59.384692)
		(width 0.10795)
		(layer "F.Cu")
		(net "LED_GBE_P2_1")
	)
	(segment
		(start 408.110182 -72.737472)
		(end 411.979872 -72.737472)
		(width 0.10795)
		(layer "F.Cu")
		(net "LED_GBE_P2_1")
	)
	(segment
		(start 406.9842 -87.621872)
		(end 406.9842 -84.869528)
		(width 0.10795)
		(layer "F.Cu")
		(net "LED_GBE_P2_1")
	)
	(segment
		(start 413.523684 -74.281284)
		(end 415.752788 -74.281284)
		(width 0.10795)
		(layer "F.Cu")
		(net "LED_GBE_P2_1")
	)
	(segment
		(start 406.276048 -80.114648)
		(end 406.276048 -79.028798)
		(width 0.10795)
		(layer "F.Cu")
		(net "LED_GBE_P2_1")
	)
	(segment
		(start 452.124064 -59.384692)
		(end 453.02932 -59.384692)
		(width 0.10795)
		(layer "F.Cu")
		(net "LED_GBE_P2_1")
	)
	(segment
		(start 400.856958 -94.495112)
		(end 400.856958 -94.073472)
		(width 0.0889)
		(layer "F.Cu")
		(net "LED_GBE_P2_1")
	)
	(segment
		(start 400.435064 -94.724728)
		(end 400.627342 -94.724728)
		(width 0.0889)
		(layer "F.Cu")
		(net "LED_GBE_P2_1")
	)
	(segment
		(start 405.44115 -78.1939)
		(end 405.44115 -75.406504)
		(width 0.10795)
		(layer "F.Cu")
		(net "LED_GBE_P2_1")
	)
	(segment
		(start 405.44115 -75.406504)
		(end 408.110182 -72.737472)
		(width 0.10795)
		(layer "F.Cu")
		(net "LED_GBE_P2_1")
	)
	(segment
		(start 403.994874 -90.611198)
		(end 406.9842 -87.621872)
		(width 0.10795)
		(layer "F.Cu")
		(net "LED_GBE_P2_1")
	)
	(segment
		(start 451.749922 -57.596024)
		(end 451.749922 -59.01055)
		(width 0.10795)
		(layer "F.Cu")
		(net "LED_GBE_P2_1")
	)
	(segment
		(start 453.02932 -59.384692)
		(end 453.24776 -59.166252)
		(width 0.10795)
		(layer "F.Cu")
		(net "LED_GBE_P2_1")
	)
	(segment
		(start 400.627342 -94.724728)
		(end 400.856958 -94.495112)
		(width 0.0889)
		(layer "F.Cu")
		(net "LED_GBE_P2_1")
	)
	(segment
		(start 406.276048 -79.028798)
		(end 405.44115 -78.1939)
		(width 0.10795)
		(layer "F.Cu")
		(net "LED_GBE_P2_1")
	)
	(segment
		(start 399.634964 -95.855028)
		(end 399.634964 -95.524828)
		(width 0.0889)
		(layer "F.Cu")
		(net "LED_GBE_P2_1")
	)
	(segment
		(start 411.979872 -72.737472)
		(end 413.523684 -74.281284)
		(width 0.10795)
		(layer "F.Cu")
		(net "LED_GBE_P2_1")
	)
	(segment
		(start 407.527506 -84.326222)
		(end 407.527506 -82.4484)
		(width 0.10795)
		(layer "F.Cu")
		(net "LED_GBE_P2_1")
	)
	(segment
		(start 399.634964 -95.524828)
		(end 400.435064 -94.724728)
		(width 0.0889)
		(layer "F.Cu")
		(net "LED_GBE_P2_1")
	)
	(segment
		(start 400.856958 -94.073472)
		(end 401.332446 -93.597984)
		(width 0.0889)
		(layer "F.Cu")
		(net "LED_GBE_P2_1")
	)
	(segment
		(start 401.332446 -92.074746)
		(end 402.795994 -90.611198)
		(width 0.10795)
		(layer "F.Cu")
		(net "LED_GBE_P2_1")
	)
	(via
		(at 407.527506 -82.4484)
		(size 0.762)
		(drill 0.381)
		(layers "F.Cu" "B.Cu")
		(net "LED_GBE_P2_1")
	)
	(via
		(at 453.24776 -59.166252)
		(size 0.508)
		(drill 0.254)
		(layers "F.Cu" "B.Cu")
		(net "LED_GBE_P2_1")
	)
	(via
		(at 415.752788 -74.281284)
		(size 0.508)
		(drill 0.254)
		(layers "F.Cu" "B.Cu")
		(net "LED_GBE_P2_1")
	)
	(segment
		(start 436.058564 -57.628282)
		(end 434.339238 -55.908956)
		(width 0.089408)
		(layer "In2.Cu")
		(net "LED_GBE_P2_1")
	)
	(segment
		(start 434.339238 -55.908956)
		(end 430.413668 -55.908956)
		(width 0.089408)
		(layer "In2.Cu")
		(net "LED_GBE_P2_1")
	)
	(segment
		(start 416.651694 -70.679564)
		(end 416.651694 -71.775574)
		(width 0.089408)
		(layer "In2.Cu")
		(net "LED_GBE_P2_1")
	)
	(segment
		(start 415.690812 -72.388222)
		(end 415.346896 -72.732138)
		(width 0.089408)
		(layer "In2.Cu")
		(net "LED_GBE_P2_1")
	)
	(segment
		(start 416.651694 -62.229746)
		(end 416.651694 -63.76416)
		(width 0.089408)
		(layer "In2.Cu")
		(net "LED_GBE_P2_1")
	)
	(segment
		(start 416.651694 -63.76416)
		(end 416.88385 -63.996316)
		(width 0.089408)
		(layer "In2.Cu")
		(net "LED_GBE_P2_1")
	)
	(segment
		(start 418.21862 -61.86424)
		(end 417.0172 -61.86424)
		(width 0.089408)
		(layer "In2.Cu")
		(net "LED_GBE_P2_1")
	)
	(segment
		(start 416.039046 -72.388222)
		(end 415.690812 -72.388222)
		(width 0.089408)
		(layer "In2.Cu")
		(net "LED_GBE_P2_1")
	)
	(segment
		(start 422.95699 -57.12587)
		(end 418.21862 -61.86424)
		(width 0.089408)
		(layer "In2.Cu")
		(net "LED_GBE_P2_1")
	)
	(segment
		(start 417.0172 -61.86424)
		(end 416.651694 -62.229746)
		(width 0.089408)
		(layer "In2.Cu")
		(net "LED_GBE_P2_1")
	)
	(segment
		(start 415.346896 -73.875392)
		(end 415.752788 -74.281284)
		(width 0.089408)
		(layer "In2.Cu")
		(net "LED_GBE_P2_1")
	)
	(segment
		(start 448.303396 -59.53379)
		(end 445.18199 -59.53379)
		(width 0.089408)
		(layer "In2.Cu")
		(net "LED_GBE_P2_1")
	)
	(segment
		(start 430.413668 -55.908956)
		(end 429.196754 -57.12587)
		(width 0.089408)
		(layer "In2.Cu")
		(net "LED_GBE_P2_1")
	)
	(segment
		(start 444.763652 -58.879232)
		(end 443.512702 -57.628282)
		(width 0.089408)
		(layer "In2.Cu")
		(net "LED_GBE_P2_1")
	)
	(segment
		(start 416.88385 -63.996316)
		(end 416.88385 -64.3128)
		(width 0.089408)
		(layer "In2.Cu")
		(net "LED_GBE_P2_1")
	)
	(segment
		(start 449.637404 -59.530996)
		(end 449.404486 -59.763914)
		(width 0.089408)
		(layer "In2.Cu")
		(net "LED_GBE_P2_1")
	)
	(segment
		(start 444.763652 -59.115452)
		(end 444.763652 -58.879232)
		(width 0.089408)
		(layer "In2.Cu")
		(net "LED_GBE_P2_1")
	)
	(segment
		(start 415.346896 -72.732138)
		(end 415.346896 -73.875392)
		(width 0.089408)
		(layer "In2.Cu")
		(net "LED_GBE_P2_1")
	)
	(segment
		(start 416.883596 -64.313054)
		(end 416.883596 -70.447662)
		(width 0.089408)
		(layer "In2.Cu")
		(net "LED_GBE_P2_1")
	)
	(segment
		(start 449.404486 -59.763914)
		(end 448.53352 -59.763914)
		(width 0.089408)
		(layer "In2.Cu")
		(net "LED_GBE_P2_1")
	)
	(segment
		(start 416.88385 -64.3128)
		(end 416.883596 -64.313054)
		(width 0.089408)
		(layer "In2.Cu")
		(net "LED_GBE_P2_1")
	)
	(segment
		(start 416.883596 -70.447662)
		(end 416.651694 -70.679564)
		(width 0.089408)
		(layer "In2.Cu")
		(net "LED_GBE_P2_1")
	)
	(segment
		(start 445.18199 -59.53379)
		(end 444.763652 -59.115452)
		(width 0.089408)
		(layer "In2.Cu")
		(net "LED_GBE_P2_1")
	)
	(segment
		(start 453.24776 -59.166252)
		(end 452.883016 -59.530996)
		(width 0.089408)
		(layer "In2.Cu")
		(net "LED_GBE_P2_1")
	)
	(segment
		(start 443.512702 -57.628282)
		(end 436.058564 -57.628282)
		(width 0.089408)
		(layer "In2.Cu")
		(net "LED_GBE_P2_1")
	)
	(segment
		(start 416.651694 -71.775574)
		(end 416.039046 -72.388222)
		(width 0.089408)
		(layer "In2.Cu")
		(net "LED_GBE_P2_1")
	)
	(segment
		(start 452.883016 -59.530996)
		(end 449.637404 -59.530996)
		(width 0.089408)
		(layer "In2.Cu")
		(net "LED_GBE_P2_1")
	)
	(segment
		(start 429.196754 -57.12587)
		(end 422.95699 -57.12587)
		(width 0.089408)
		(layer "In2.Cu")
		(net "LED_GBE_P2_1")
	)
	(segment
		(start 448.53352 -59.763914)
		(end 448.303396 -59.53379)
		(width 0.089408)
		(layer "In2.Cu")
		(net "LED_GBE_P2_1")
	)
	(segment
		(start 398.9959 -89.191846)
		(end 397.06296 -91.124786)
		(width 0.10795)
		(layer "F.Cu")
		(net "LED_GBE_P2_0")
	)
	(segment
		(start 404.614634 -79.716884)
		(end 404.614634 -80.532732)
		(width 0.10795)
		(layer "F.Cu")
		(net "LED_GBE_P2_0")
	)
	(segment
		(start 412.719774 -70.485)
		(end 408.176222 -70.485)
		(width 0.10795)
		(layer "F.Cu")
		(net "LED_GBE_P2_0")
	)
	(segment
		(start 396.867888 -93.885512)
		(end 396.867888 -94.257876)
		(width 0.0889)
		(layer "F.Cu")
		(net "LED_GBE_P2_0")
	)
	(segment
		(start 403.723602 -74.93762)
		(end 403.723602 -78.825852)
		(width 0.10795)
		(layer "F.Cu")
		(net "LED_GBE_P2_0")
	)
	(segment
		(start 400.805904 -87.739728)
		(end 399.353786 -89.191846)
		(width 0.10795)
		(layer "F.Cu")
		(net "LED_GBE_P2_0")
	)
	(segment
		(start 415.717736 -71.917814)
		(end 414.152588 -71.917814)
		(width 0.10795)
		(layer "F.Cu")
		(net "LED_GBE_P2_0")
	)
	(segment
		(start 396.699232 -93.363542)
		(end 396.699232 -93.716856)
		(width 0.0889)
		(layer "F.Cu")
		(net "LED_GBE_P2_0")
	)
	(segment
		(start 404.614634 -80.532732)
		(end 405.296624 -81.214722)
		(width 0.10795)
		(layer "F.Cu")
		(net "LED_GBE_P2_0")
	)
	(segment
		(start 399.353786 -89.191846)
		(end 398.9959 -89.191846)
		(width 0.10795)
		(layer "F.Cu")
		(net "LED_GBE_P2_0")
	)
	(segment
		(start 396.815564 -92.445586)
		(end 396.815564 -93.24721)
		(width 0.0889)
		(layer "F.Cu")
		(net "LED_GBE_P2_0")
	)
	(segment
		(start 408.176222 -70.485)
		(end 403.723602 -74.93762)
		(width 0.10795)
		(layer "F.Cu")
		(net "LED_GBE_P2_0")
	)
	(segment
		(start 450.657722 -59.523122)
		(end 450.105272 -59.523122)
		(width 0.10795)
		(layer "F.Cu")
		(net "LED_GBE_P2_0")
	)
	(segment
		(start 450.950076 -57.596024)
		(end 450.950076 -59.230768)
		(width 0.10795)
		(layer "F.Cu")
		(net "LED_GBE_P2_0")
	)
	(segment
		(start 396.815564 -93.24721)
		(end 396.699232 -93.363542)
		(width 0.0889)
		(layer "F.Cu")
		(net "LED_GBE_P2_0")
	)
	(segment
		(start 396.815564 -91.857576)
		(end 396.815564 -92.445586)
		(width 0.10795)
		(layer "F.Cu")
		(net "LED_GBE_P2_0")
	)
	(segment
		(start 449.479924 -58.897774)
		(end 448.786758 -58.897774)
		(width 0.10795)
		(layer "F.Cu")
		(net "LED_GBE_P2_0")
	)
	(segment
		(start 405.296624 -86.274402)
		(end 403.831298 -87.739728)
		(width 0.10795)
		(layer "F.Cu")
		(net "LED_GBE_P2_0")
	)
	(segment
		(start 450.105272 -59.523122)
		(end 449.479924 -58.897774)
		(width 0.10795)
		(layer "F.Cu")
		(net "LED_GBE_P2_0")
	)
	(segment
		(start 448.786758 -58.897774)
		(end 448.583558 -59.100974)
		(width 0.10795)
		(layer "F.Cu")
		(net "LED_GBE_P2_0")
	)
	(segment
		(start 450.950076 -59.230768)
		(end 450.657722 -59.523122)
		(width 0.10795)
		(layer "F.Cu")
		(net "LED_GBE_P2_0")
	)
	(segment
		(start 396.699232 -93.716856)
		(end 396.867888 -93.885512)
		(width 0.0889)
		(layer "F.Cu")
		(net "LED_GBE_P2_0")
	)
	(segment
		(start 396.867888 -94.257876)
		(end 396.984982 -94.37497)
		(width 0.0889)
		(layer "F.Cu")
		(net "LED_GBE_P2_0")
	)
	(segment
		(start 403.723602 -78.825852)
		(end 404.614634 -79.716884)
		(width 0.10795)
		(layer "F.Cu")
		(net "LED_GBE_P2_0")
	)
	(segment
		(start 403.831298 -87.739728)
		(end 400.805904 -87.739728)
		(width 0.10795)
		(layer "F.Cu")
		(net "LED_GBE_P2_0")
	)
	(segment
		(start 405.296624 -81.214722)
		(end 405.296624 -86.274402)
		(width 0.10795)
		(layer "F.Cu")
		(net "LED_GBE_P2_0")
	)
	(segment
		(start 397.06296 -91.61018)
		(end 396.815564 -91.857576)
		(width 0.10795)
		(layer "F.Cu")
		(net "LED_GBE_P2_0")
	)
	(segment
		(start 414.152588 -71.917814)
		(end 412.719774 -70.485)
		(width 0.10795)
		(layer "F.Cu")
		(net "LED_GBE_P2_0")
	)
	(segment
		(start 397.06296 -91.124786)
		(end 397.06296 -91.61018)
		(width 0.10795)
		(layer "F.Cu")
		(net "LED_GBE_P2_0")
	)
	(via
		(at 448.583558 -59.100974)
		(size 0.508)
		(drill 0.254)
		(layers "F.Cu" "B.Cu")
		(net "LED_GBE_P2_0")
	)
	(via
		(at 415.717736 -71.917814)
		(size 0.508)
		(drill 0.254)
		(layers "F.Cu" "B.Cu")
		(net "LED_GBE_P2_0")
	)
	(segment
		(start 422.927272 -56.885332)
		(end 418.139626 -61.672978)
		(width 0.089408)
		(layer "In2.Cu")
		(net "LED_GBE_P2_0")
	)
	(segment
		(start 416.460686 -70.600316)
		(end 416.460686 -71.174864)
		(width 0.089408)
		(layer "In2.Cu")
		(net "LED_GBE_P2_0")
	)
	(segment
		(start 430.33442 -55.717948)
		(end 429.167036 -56.885332)
		(width 0.089408)
		(layer "In2.Cu")
		(net "LED_GBE_P2_0")
	)
	(segment
		(start 416.692588 -64.233806)
		(end 416.692588 -70.368414)
		(width 0.089408)
		(layer "In2.Cu")
		(net "LED_GBE_P2_0")
	)
	(segment
		(start 416.692588 -70.368414)
		(end 416.460686 -70.600316)
		(width 0.089408)
		(layer "In2.Cu")
		(net "LED_GBE_P2_0")
	)
	(segment
		(start 447.946018 -57.397142)
		(end 436.09768 -57.397142)
		(width 0.089408)
		(layer "In2.Cu")
		(net "LED_GBE_P2_0")
	)
	(segment
		(start 436.09768 -57.397142)
		(end 434.418486 -55.717948)
		(width 0.089408)
		(layer "In2.Cu")
		(net "LED_GBE_P2_0")
	)
	(segment
		(start 434.418486 -55.717948)
		(end 430.33442 -55.717948)
		(width 0.089408)
		(layer "In2.Cu")
		(net "LED_GBE_P2_0")
	)
	(segment
		(start 418.139626 -61.672978)
		(end 416.218116 -61.672978)
		(width 0.089408)
		(layer "In2.Cu")
		(net "LED_GBE_P2_0")
	)
	(segment
		(start 416.692842 -64.233552)
		(end 416.692588 -64.233806)
		(width 0.089408)
		(layer "In2.Cu")
		(net "LED_GBE_P2_0")
	)
	(segment
		(start 416.218116 -61.672978)
		(end 415.651188 -62.239906)
		(width 0.089408)
		(layer "In2.Cu")
		(net "LED_GBE_P2_0")
	)
	(segment
		(start 448.583558 -59.100974)
		(end 448.583558 -58.034682)
		(width 0.089408)
		(layer "In2.Cu")
		(net "LED_GBE_P2_0")
	)
	(segment
		(start 416.692842 -64.075564)
		(end 416.692842 -64.233552)
		(width 0.089408)
		(layer "In2.Cu")
		(net "LED_GBE_P2_0")
	)
	(segment
		(start 415.651188 -63.03391)
		(end 416.692842 -64.075564)
		(width 0.089408)
		(layer "In2.Cu")
		(net "LED_GBE_P2_0")
	)
	(segment
		(start 415.651188 -62.239906)
		(end 415.651188 -63.03391)
		(width 0.089408)
		(layer "In2.Cu")
		(net "LED_GBE_P2_0")
	)
	(segment
		(start 416.460686 -71.174864)
		(end 415.717736 -71.917814)
		(width 0.089408)
		(layer "In2.Cu")
		(net "LED_GBE_P2_0")
	)
	(segment
		(start 429.167036 -56.885332)
		(end 422.927272 -56.885332)
		(width 0.089408)
		(layer "In2.Cu")
		(net "LED_GBE_P2_0")
	)
	(segment
		(start 448.583558 -58.034682)
		(end 447.946018 -57.397142)
		(width 0.089408)
		(layer "In2.Cu")
		(net "LED_GBE_P2_0")
	)
	(segment
		(start 364.7948 -95.8596)
		(end 364.6932 -95.758)
		(width 0.10795)
		(layer "F.Cu")
		(net "FM_PVCCMCP_CPU0_EN")
	)
	(segment
		(start 379.29566 -73.147936)
		(end 378.921264 -73.522332)
		(width 0.1016)
		(layer "F.Cu")
		(net "FM_PVCCMCP_CPU0_EN")
	)
	(segment
		(start 360.742738 -113.337594)
		(end 360.742738 -111.669322)
		(width 0.10795)
		(layer "F.Cu")
		(net "FM_PVCCMCP_CPU0_EN")
	)
	(segment
		(start 359.631996 -114.448336)
		(end 360.742738 -113.337594)
		(width 0.10795)
		(layer "F.Cu")
		(net "FM_PVCCMCP_CPU0_EN")
	)
	(segment
		(start 364.6932 -95.758)
		(end 364.6932 -92.2401)
		(width 0.10795)
		(layer "F.Cu")
		(net "FM_PVCCMCP_CPU0_EN")
	)
	(segment
		(start 369.088416 -91.23045)
		(end 369.793266 -90.5256)
		(width 0.10795)
		(layer "F.Cu")
		(net "FM_PVCCMCP_CPU0_EN")
	)
	(segment
		(start 370.615464 -90.513662)
		(end 370.614194 -90.513662)
		(width 0.10795)
		(layer "F.Cu")
		(net "FM_PVCCMCP_CPU0_EN")
	)
	(segment
		(start 364.087156 -108.324904)
		(end 364.087156 -105.2322)
		(width 0.10795)
		(layer "F.Cu")
		(net "FM_PVCCMCP_CPU0_EN")
	)
	(segment
		(start 356.073202 -114.448336)
		(end 359.631996 -114.448336)
		(width 0.10795)
		(layer "F.Cu")
		(net "FM_PVCCMCP_CPU0_EN")
	)
	(segment
		(start 364.087156 -105.2322)
		(end 364.7948 -104.524556)
		(width 0.10795)
		(layer "F.Cu")
		(net "FM_PVCCMCP_CPU0_EN")
	)
	(segment
		(start 364.6932 -92.2401)
		(end 365.70285 -91.23045)
		(width 0.10795)
		(layer "F.Cu")
		(net "FM_PVCCMCP_CPU0_EN")
	)
	(segment
		(start 370.615464 -90.476324)
		(end 370.615464 -90.513662)
		(width 0.10795)
		(layer "F.Cu")
		(net "FM_PVCCMCP_CPU0_EN")
	)
	(segment
		(start 369.793266 -90.5256)
		(end 370.566188 -90.5256)
		(width 0.10795)
		(layer "F.Cu")
		(net "FM_PVCCMCP_CPU0_EN")
	)
	(segment
		(start 378.921264 -73.522332)
		(end 378.317506 -73.522332)
		(width 0.1016)
		(layer "F.Cu")
		(net "FM_PVCCMCP_CPU0_EN")
	)
	(segment
		(start 378.317506 -73.522332)
		(end 377.944888 -73.89495)
		(width 0.1016)
		(layer "F.Cu")
		(net "FM_PVCCMCP_CPU0_EN")
	)
	(segment
		(start 364.7948 -104.524556)
		(end 364.7948 -95.8596)
		(width 0.10795)
		(layer "F.Cu")
		(net "FM_PVCCMCP_CPU0_EN")
	)
	(segment
		(start 370.566188 -90.5256)
		(end 370.615464 -90.476324)
		(width 0.10795)
		(layer "F.Cu")
		(net "FM_PVCCMCP_CPU0_EN")
	)
	(segment
		(start 353.724972 -113.01095)
		(end 354.635816 -113.01095)
		(width 0.10795)
		(layer "F.Cu")
		(net "FM_PVCCMCP_CPU0_EN")
	)
	(segment
		(start 354.635816 -113.01095)
		(end 356.073202 -114.448336)
		(width 0.10795)
		(layer "F.Cu")
		(net "FM_PVCCMCP_CPU0_EN")
	)
	(segment
		(start 365.70285 -91.23045)
		(end 369.088416 -91.23045)
		(width 0.10795)
		(layer "F.Cu")
		(net "FM_PVCCMCP_CPU0_EN")
	)
	(segment
		(start 360.742738 -111.669322)
		(end 364.087156 -108.324904)
		(width 0.10795)
		(layer "F.Cu")
		(net "FM_PVCCMCP_CPU0_EN")
	)
	(via
		(at 364.6932 -95.758)
		(size 0.762)
		(drill 0.381)
		(layers "F.Cu" "B.Cu")
		(net "FM_PVCCMCP_CPU0_EN")
	)
	(via
		(at 379.29566 -73.147936)
		(size 0.508)
		(drill 0.254)
		(layers "F.Cu" "B.Cu")
		(net "FM_PVCCMCP_CPU0_EN")
	)
	(via
		(at 370.614194 -90.513662)
		(size 0.508)
		(drill 0.254)
		(layers "F.Cu" "B.Cu")
		(net "FM_PVCCMCP_CPU0_EN")
	)
	(segment
		(start 375.857516 -82.42808)
		(end 375.857516 -87.155782)
		(width 0.089408)
		(layer "In9.Cu")
		(net "FM_PVCCMCP_CPU0_EN")
	)
	(segment
		(start 370.781834 -89.2556)
		(end 370.541296 -89.496138)
		(width 0.089408)
		(layer "In9.Cu")
		(net "FM_PVCCMCP_CPU0_EN")
	)
	(segment
		(start 370.541296 -90.083386)
		(end 370.614194 -90.156284)
		(width 0.089408)
		(layer "In9.Cu")
		(net "FM_PVCCMCP_CPU0_EN")
	)
	(segment
		(start 376.622056 -81.66354)
		(end 375.857516 -82.42808)
		(width 0.089408)
		(layer "In9.Cu")
		(net "FM_PVCCMCP_CPU0_EN")
	)
	(segment
		(start 377.217686 -81.66354)
		(end 376.622056 -81.66354)
		(width 0.089408)
		(layer "In9.Cu")
		(net "FM_PVCCMCP_CPU0_EN")
	)
	(segment
		(start 378.27585 -77.291692)
		(end 378.27585 -77.699616)
		(width 0.089408)
		(layer "In9.Cu")
		(net "FM_PVCCMCP_CPU0_EN")
	)
	(segment
		(start 373.757698 -89.2556)
		(end 370.781834 -89.2556)
		(width 0.089408)
		(layer "In9.Cu")
		(net "FM_PVCCMCP_CPU0_EN")
	)
	(segment
		(start 370.614194 -90.156284)
		(end 370.614194 -90.513662)
		(width 0.089408)
		(layer "In9.Cu")
		(net "FM_PVCCMCP_CPU0_EN")
	)
	(segment
		(start 377.971304 -78.004162)
		(end 377.971304 -80.909922)
		(width 0.089408)
		(layer "In9.Cu")
		(net "FM_PVCCMCP_CPU0_EN")
	)
	(segment
		(start 379.29566 -73.147936)
		(end 378.751846 -73.69175)
		(width 0.089408)
		(layer "In9.Cu")
		(net "FM_PVCCMCP_CPU0_EN")
	)
	(segment
		(start 377.971304 -80.909922)
		(end 377.217686 -81.66354)
		(width 0.089408)
		(layer "In9.Cu")
		(net "FM_PVCCMCP_CPU0_EN")
	)
	(segment
		(start 378.751846 -73.69175)
		(end 378.751846 -76.815696)
		(width 0.089408)
		(layer "In9.Cu")
		(net "FM_PVCCMCP_CPU0_EN")
	)
	(segment
		(start 370.541296 -89.496138)
		(end 370.541296 -90.083386)
		(width 0.089408)
		(layer "In9.Cu")
		(net "FM_PVCCMCP_CPU0_EN")
	)
	(segment
		(start 378.751846 -76.815696)
		(end 378.27585 -77.291692)
		(width 0.089408)
		(layer "In9.Cu")
		(net "FM_PVCCMCP_CPU0_EN")
	)
	(segment
		(start 375.857516 -87.155782)
		(end 373.757698 -89.2556)
		(width 0.089408)
		(layer "In9.Cu")
		(net "FM_PVCCMCP_CPU0_EN")
	)
	(segment
		(start 378.27585 -77.699616)
		(end 377.971304 -78.004162)
		(width 0.089408)
		(layer "In9.Cu")
		(net "FM_PVCCMCP_CPU0_EN")
	)
	(segment
		(start 370.9416 -89.662)
		(end 370.8273 -89.7763)
		(width 0.10795)
		(layer "F.Cu")
		(net "FM_PVCCIOMCP_CPU0_EN")
	)
	(segment
		(start 360.0069 -111.39678)
		(end 358.74325 -112.66043)
		(width 0.10795)
		(layer "F.Cu")
		(net "FM_PVCCIOMCP_CPU0_EN")
	)
	(segment
		(start 363.8804 -101.0412)
		(end 363.8296 -101.092)
		(width 0.10795)
		(layer "F.Cu")
		(net "FM_PVCCIOMCP_CPU0_EN")
	)
	(segment
		(start 369.738402 -90.173302)
		(end 368.94389 -90.173302)
		(width 0.10795)
		(layer "F.Cu")
		(net "FM_PVCCIOMCP_CPU0_EN")
	)
	(segment
		(start 363.617256 -104.7242)
		(end 363.617256 -107.76204)
		(width 0.10795)
		(layer "F.Cu")
		(net "FM_PVCCIOMCP_CPU0_EN")
	)
	(segment
		(start 363.8296 -101.092)
		(end 364.0836 -101.346)
		(width 0.10795)
		(layer "F.Cu")
		(net "FM_PVCCIOMCP_CPU0_EN")
	)
	(segment
		(start 370.8273 -89.7763)
		(end 370.135404 -89.7763)
		(width 0.10795)
		(layer "F.Cu")
		(net "FM_PVCCIOMCP_CPU0_EN")
	)
	(segment
		(start 363.6518 -92.2655)
		(end 363.6518 -99.2886)
		(width 0.10795)
		(layer "F.Cu")
		(net "FM_PVCCIOMCP_CPU0_EN")
	)
	(segment
		(start 360.0069 -111.372396)
		(end 360.0069 -111.39678)
		(width 0.10795)
		(layer "F.Cu")
		(net "FM_PVCCIOMCP_CPU0_EN")
	)
	(segment
		(start 370.135404 -89.7763)
		(end 369.738402 -90.173302)
		(width 0.10795)
		(layer "F.Cu")
		(net "FM_PVCCIOMCP_CPU0_EN")
	)
	(segment
		(start 368.94389 -90.173302)
		(end 368.610642 -90.50655)
		(width 0.10795)
		(layer "F.Cu")
		(net "FM_PVCCIOMCP_CPU0_EN")
	)
	(segment
		(start 363.6518 -99.2886)
		(end 363.8804 -99.5172)
		(width 0.10795)
		(layer "F.Cu")
		(net "FM_PVCCIOMCP_CPU0_EN")
	)
	(segment
		(start 363.617256 -107.76204)
		(end 360.0069 -111.372396)
		(width 0.10795)
		(layer "F.Cu")
		(net "FM_PVCCIOMCP_CPU0_EN")
	)
	(segment
		(start 378.744988 -75.494896)
		(end 379.786896 -75.494896)
		(width 0.10795)
		(layer "F.Cu")
		(net "FM_PVCCIOMCP_CPU0_EN")
	)
	(segment
		(start 379.786896 -75.494896)
		(end 379.8062 -75.5142)
		(width 0.10795)
		(layer "F.Cu")
		(net "FM_PVCCIOMCP_CPU0_EN")
	)
	(segment
		(start 364.0836 -104.257856)
		(end 363.617256 -104.7242)
		(width 0.10795)
		(layer "F.Cu")
		(net "FM_PVCCIOMCP_CPU0_EN")
	)
	(segment
		(start 348.644972 -115.55095)
		(end 349.2754 -114.935)
		(width 0.10795)
		(layer "F.Cu")
		(net "FM_PVCCIOMCP_CPU0_EN")
	)
	(segment
		(start 364.0836 -101.346)
		(end 364.0836 -104.257856)
		(width 0.10795)
		(layer "F.Cu")
		(net "FM_PVCCIOMCP_CPU0_EN")
	)
	(segment
		(start 363.8804 -99.5172)
		(end 363.8804 -101.0412)
		(width 0.10795)
		(layer "F.Cu")
		(net "FM_PVCCIOMCP_CPU0_EN")
	)
	(segment
		(start 368.610642 -90.50655)
		(end 365.41075 -90.50655)
		(width 0.10795)
		(layer "F.Cu")
		(net "FM_PVCCIOMCP_CPU0_EN")
	)
	(segment
		(start 365.41075 -90.50655)
		(end 363.6518 -92.2655)
		(width 0.10795)
		(layer "F.Cu")
		(net "FM_PVCCIOMCP_CPU0_EN")
	)
	(via
		(at 363.8296 -101.092)
		(size 0.762)
		(drill 0.381)
		(layers "F.Cu" "B.Cu")
		(net "FM_PVCCIOMCP_CPU0_EN")
	)
	(via
		(at 358.74325 -112.66043)
		(size 0.508)
		(drill 0.254)
		(layers "F.Cu" "B.Cu")
		(net "FM_PVCCIOMCP_CPU0_EN")
	)
	(via
		(at 379.8062 -75.5142)
		(size 0.4572)
		(drill 0.2032)
		(layers "F.Cu" "B.Cu")
		(net "FM_PVCCIOMCP_CPU0_EN")
	)
	(via
		(at 370.9416 -89.662)
		(size 0.508)
		(drill 0.254)
		(layers "F.Cu" "B.Cu")
		(net "FM_PVCCIOMCP_CPU0_EN")
	)
	(via
		(at 349.2754 -114.935)
		(size 0.508)
		(drill 0.254)
		(layers "F.Cu" "B.Cu")
		(net "FM_PVCCIOMCP_CPU0_EN")
	)
	(segment
		(start 354.6602 -113.1062)
		(end 355.33838 -113.78438)
		(width 0.089408)
		(layer "In9.Cu")
		(net "FM_PVCCIOMCP_CPU0_EN")
	)
	(segment
		(start 349.2754 -114.570256)
		(end 349.999808 -113.845848)
		(width 0.089408)
		(layer "In9.Cu")
		(net "FM_PVCCIOMCP_CPU0_EN")
	)
	(segment
		(start 349.999808 -113.439448)
		(end 350.333056 -113.1062)
		(width 0.089408)
		(layer "In9.Cu")
		(net "FM_PVCCIOMCP_CPU0_EN")
	)
	(segment
		(start 379.8062 -76.448666)
		(end 379.8062 -75.5142)
		(width 0.089408)
		(layer "In9.Cu")
		(net "FM_PVCCIOMCP_CPU0_EN")
	)
	(segment
		(start 378.95911 -78.235556)
		(end 378.95911 -77.179424)
		(width 0.089408)
		(layer "In9.Cu")
		(net "FM_PVCCIOMCP_CPU0_EN")
	)
	(segment
		(start 349.999808 -113.845848)
		(end 349.999808 -113.439448)
		(width 0.089408)
		(layer "In9.Cu")
		(net "FM_PVCCIOMCP_CPU0_EN")
	)
	(segment
		(start 377.720352 -81.854548)
		(end 378.718064 -80.856836)
		(width 0.089408)
		(layer "In9.Cu")
		(net "FM_PVCCIOMCP_CPU0_EN")
	)
	(segment
		(start 350.333056 -113.1062)
		(end 354.6602 -113.1062)
		(width 0.089408)
		(layer "In9.Cu")
		(net "FM_PVCCIOMCP_CPU0_EN")
	)
	(segment
		(start 370.9416 -89.662)
		(end 371.3734 -89.662)
		(width 0.089408)
		(layer "In9.Cu")
		(net "FM_PVCCIOMCP_CPU0_EN")
	)
	(segment
		(start 376.048524 -82.507328)
		(end 376.701304 -81.854548)
		(width 0.089408)
		(layer "In9.Cu")
		(net "FM_PVCCIOMCP_CPU0_EN")
	)
	(segment
		(start 349.2754 -114.935)
		(end 349.2754 -114.570256)
		(width 0.089408)
		(layer "In9.Cu")
		(net "FM_PVCCIOMCP_CPU0_EN")
	)
	(segment
		(start 378.95911 -77.179424)
		(end 379.194314 -76.94422)
		(width 0.089408)
		(layer "In9.Cu")
		(net "FM_PVCCIOMCP_CPU0_EN")
	)
	(segment
		(start 376.701304 -81.854548)
		(end 377.720352 -81.854548)
		(width 0.089408)
		(layer "In9.Cu")
		(net "FM_PVCCIOMCP_CPU0_EN")
	)
	(segment
		(start 357.020876 -113.78438)
		(end 358.144826 -112.66043)
		(width 0.089408)
		(layer "In9.Cu")
		(net "FM_PVCCIOMCP_CPU0_EN")
	)
	(segment
		(start 378.718064 -80.856836)
		(end 378.718064 -78.476602)
		(width 0.089408)
		(layer "In9.Cu")
		(net "FM_PVCCIOMCP_CPU0_EN")
	)
	(segment
		(start 379.310646 -76.94422)
		(end 379.8062 -76.448666)
		(width 0.089408)
		(layer "In9.Cu")
		(net "FM_PVCCIOMCP_CPU0_EN")
	)
	(segment
		(start 371.5766 -89.4588)
		(end 373.824754 -89.4588)
		(width 0.089408)
		(layer "In9.Cu")
		(net "FM_PVCCIOMCP_CPU0_EN")
	)
	(segment
		(start 371.3734 -89.662)
		(end 371.5766 -89.4588)
		(width 0.089408)
		(layer "In9.Cu")
		(net "FM_PVCCIOMCP_CPU0_EN")
	)
	(segment
		(start 373.824754 -89.4588)
		(end 376.048524 -87.23503)
		(width 0.089408)
		(layer "In9.Cu")
		(net "FM_PVCCIOMCP_CPU0_EN")
	)
	(segment
		(start 355.33838 -113.78438)
		(end 357.020876 -113.78438)
		(width 0.089408)
		(layer "In9.Cu")
		(net "FM_PVCCIOMCP_CPU0_EN")
	)
	(segment
		(start 376.048524 -87.23503)
		(end 376.048524 -82.507328)
		(width 0.089408)
		(layer "In9.Cu")
		(net "FM_PVCCIOMCP_CPU0_EN")
	)
	(segment
		(start 358.144826 -112.66043)
		(end 358.74325 -112.66043)
		(width 0.089408)
		(layer "In9.Cu")
		(net "FM_PVCCIOMCP_CPU0_EN")
	)
	(segment
		(start 378.718064 -78.476602)
		(end 378.95911 -78.235556)
		(width 0.089408)
		(layer "In9.Cu")
		(net "FM_PVCCIOMCP_CPU0_EN")
	)
	(segment
		(start 379.194314 -76.94422)
		(end 379.310646 -76.94422)
		(width 0.089408)
		(layer "In9.Cu")
		(net "FM_PVCCIOMCP_CPU0_EN")
	)
	(segment
		(start 366.345216 -71.095108)
		(end 366.745012 -71.494904)
		(width 0.1016)
		(layer "F.Cu")
		(net "FM_P1V8MCP_CPU0_EN")
	)
	(segment
		(start 363.2708 -104.4194)
		(end 363.474 -104.2162)
		(width 0.10795)
		(layer "F.Cu")
		(net "FM_P1V8MCP_CPU0_EN")
	)
	(segment
		(start 363.474 -103.251)
		(end 363.474 -102.4128)
		(width 0.10795)
		(layer "F.Cu")
		(net "FM_P1V8MCP_CPU0_EN")
	)
	(segment
		(start 363.474 -104.2162)
		(end 363.474 -103.251)
		(width 0.10795)
		(layer "F.Cu")
		(net "FM_P1V8MCP_CPU0_EN")
	)
	(segment
		(start 347.374972 -115.55095)
		(end 348.0054 -114.935)
		(width 0.10795)
		(layer "F.Cu")
		(net "FM_P1V8MCP_CPU0_EN")
	)
	(segment
		(start 368.107976 -90.285824)
		(end 368.4016 -89.9922)
		(width 0.10795)
		(layer "F.Cu")
		(net "FM_P1V8MCP_CPU0_EN")
	)
	(segment
		(start 358.770936 -111.949992)
		(end 363.2708 -107.450128)
		(width 0.10795)
		(layer "F.Cu")
		(net "FM_P1V8MCP_CPU0_EN")
	)
	(segment
		(start 365.23803 -90.285824)
		(end 368.107976 -90.285824)
		(width 0.10795)
		(layer "F.Cu")
		(net "FM_P1V8MCP_CPU0_EN")
	)
	(segment
		(start 363.2708 -102.2096)
		(end 363.2708 -92.253054)
		(width 0.10795)
		(layer "F.Cu")
		(net "FM_P1V8MCP_CPU0_EN")
	)
	(segment
		(start 363.2708 -92.253054)
		(end 365.23803 -90.285824)
		(width 0.10795)
		(layer "F.Cu")
		(net "FM_P1V8MCP_CPU0_EN")
	)
	(segment
		(start 363.474 -102.4128)
		(end 363.2708 -102.2096)
		(width 0.10795)
		(layer "F.Cu")
		(net "FM_P1V8MCP_CPU0_EN")
	)
	(segment
		(start 363.2708 -107.450128)
		(end 363.2708 -104.4194)
		(width 0.10795)
		(layer "F.Cu")
		(net "FM_P1V8MCP_CPU0_EN")
	)
	(via
		(at 358.770936 -111.949992)
		(size 0.508)
		(drill 0.254)
		(layers "F.Cu" "B.Cu")
		(net "FM_P1V8MCP_CPU0_EN")
	)
	(via
		(at 348.0054 -114.935)
		(size 0.508)
		(drill 0.254)
		(layers "F.Cu" "B.Cu")
		(net "FM_P1V8MCP_CPU0_EN")
	)
	(via
		(at 363.474 -103.251)
		(size 0.762)
		(drill 0.381)
		(layers "F.Cu" "B.Cu")
		(net "FM_P1V8MCP_CPU0_EN")
	)
	(via
		(at 368.4016 -89.9922)
		(size 0.508)
		(drill 0.254)
		(layers "F.Cu" "B.Cu")
		(net "FM_P1V8MCP_CPU0_EN")
	)
	(via
		(at 366.345216 -71.095108)
		(size 0.4572)
		(drill 0.2032)
		(layers "F.Cu" "B.Cu")
		(net "FM_P1V8MCP_CPU0_EN")
	)
	(segment
		(start 349.8088 -113.3602)
		(end 350.253808 -112.915192)
		(width 0.089408)
		(layer "In9.Cu")
		(net "FM_P1V8MCP_CPU0_EN")
	)
	(segment
		(start 348.6404 -114.935)
		(end 349.8088 -113.7666)
		(width 0.089408)
		(layer "In9.Cu")
		(net "FM_P1V8MCP_CPU0_EN")
	)
	(segment
		(start 348.0054 -114.935)
		(end 348.6404 -114.935)
		(width 0.089408)
		(layer "In9.Cu")
		(net "FM_P1V8MCP_CPU0_EN")
	)
	(segment
		(start 358.585008 -111.949992)
		(end 358.770936 -111.949992)
		(width 0.089408)
		(layer "In9.Cu")
		(net "FM_P1V8MCP_CPU0_EN")
	)
	(segment
		(start 350.253808 -112.915192)
		(end 354.739448 -112.915192)
		(width 0.089408)
		(layer "In9.Cu")
		(net "FM_P1V8MCP_CPU0_EN")
	)
	(segment
		(start 349.8088 -113.7666)
		(end 349.8088 -113.3602)
		(width 0.089408)
		(layer "In9.Cu")
		(net "FM_P1V8MCP_CPU0_EN")
	)
	(segment
		(start 354.739448 -112.915192)
		(end 355.417628 -113.593372)
		(width 0.089408)
		(layer "In9.Cu")
		(net "FM_P1V8MCP_CPU0_EN")
	)
	(segment
		(start 356.941628 -113.593372)
		(end 358.585008 -111.949992)
		(width 0.089408)
		(layer "In9.Cu")
		(net "FM_P1V8MCP_CPU0_EN")
	)
	(segment
		(start 355.417628 -113.593372)
		(end 356.941628 -113.593372)
		(width 0.089408)
		(layer "In9.Cu")
		(net "FM_P1V8MCP_CPU0_EN")
	)
	(segment
		(start 366.36452 -79.611728)
		(end 366.771936 -79.204312)
		(width 0.089408)
		(layer "In11.Cu")
		(net "FM_P1V8MCP_CPU0_EN")
	)
	(segment
		(start 368.4016 -89.9922)
		(end 368.4016 -88.748616)
		(width 0.089408)
		(layer "In11.Cu")
		(net "FM_P1V8MCP_CPU0_EN")
	)
	(segment
		(start 366.771936 -78.940152)
		(end 366.919002 -78.793086)
		(width 0.089408)
		(layer "In11.Cu")
		(net "FM_P1V8MCP_CPU0_EN")
	)
	(segment
		(start 368.4016 -88.748616)
		(end 366.811052 -87.158068)
		(width 0.089408)
		(layer "In11.Cu")
		(net "FM_P1V8MCP_CPU0_EN")
	)
	(segment
		(start 366.45469 -82.554826)
		(end 366.45469 -82.223102)
		(width 0.089408)
		(layer "In11.Cu")
		(net "FM_P1V8MCP_CPU0_EN")
	)
	(segment
		(start 367.049304 -83.62315)
		(end 367.049304 -83.057746)
		(width 0.089408)
		(layer "In11.Cu")
		(net "FM_P1V8MCP_CPU0_EN")
	)
	(segment
		(start 367.554256 -78.556866)
		(end 367.554256 -72.304148)
		(width 0.089408)
		(layer "In11.Cu")
		(net "FM_P1V8MCP_CPU0_EN")
	)
	(segment
		(start 366.919002 -78.793086)
		(end 366.919002 -78.787498)
		(width 0.089408)
		(layer "In11.Cu")
		(net "FM_P1V8MCP_CPU0_EN")
	)
	(segment
		(start 367.00841 -78.69809)
		(end 367.413032 -78.69809)
		(width 0.089408)
		(layer "In11.Cu")
		(net "FM_P1V8MCP_CPU0_EN")
	)
	(segment
		(start 366.877854 -82.886296)
		(end 366.78616 -82.886296)
		(width 0.089408)
		(layer "In11.Cu")
		(net "FM_P1V8MCP_CPU0_EN")
	)
	(segment
		(start 366.811052 -83.861402)
		(end 367.049304 -83.62315)
		(width 0.089408)
		(layer "In11.Cu")
		(net "FM_P1V8MCP_CPU0_EN")
	)
	(segment
		(start 366.575594 -82.102198)
		(end 366.575594 -81.327752)
		(width 0.089408)
		(layer "In11.Cu")
		(net "FM_P1V8MCP_CPU0_EN")
	)
	(segment
		(start 366.811052 -87.158068)
		(end 366.811052 -83.861402)
		(width 0.089408)
		(layer "In11.Cu")
		(net "FM_P1V8MCP_CPU0_EN")
	)
	(segment
		(start 366.919002 -78.787498)
		(end 367.00841 -78.69809)
		(width 0.089408)
		(layer "In11.Cu")
		(net "FM_P1V8MCP_CPU0_EN")
	)
	(segment
		(start 367.049304 -83.057746)
		(end 366.877854 -82.886296)
		(width 0.089408)
		(layer "In11.Cu")
		(net "FM_P1V8MCP_CPU0_EN")
	)
	(segment
		(start 367.413032 -78.69809)
		(end 367.554256 -78.556866)
		(width 0.089408)
		(layer "In11.Cu")
		(net "FM_P1V8MCP_CPU0_EN")
	)
	(segment
		(start 366.575594 -81.327752)
		(end 366.36452 -81.116678)
		(width 0.089408)
		(layer "In11.Cu")
		(net "FM_P1V8MCP_CPU0_EN")
	)
	(segment
		(start 366.45469 -82.223102)
		(end 366.575594 -82.102198)
		(width 0.089408)
		(layer "In11.Cu")
		(net "FM_P1V8MCP_CPU0_EN")
	)
	(segment
		(start 366.36452 -81.116678)
		(end 366.36452 -79.611728)
		(width 0.089408)
		(layer "In11.Cu")
		(net "FM_P1V8MCP_CPU0_EN")
	)
	(segment
		(start 367.554256 -72.304148)
		(end 366.345216 -71.095108)
		(width 0.089408)
		(layer "In11.Cu")
		(net "FM_P1V8MCP_CPU0_EN")
	)
	(segment
		(start 366.78616 -82.886296)
		(end 366.45469 -82.554826)
		(width 0.089408)
		(layer "In11.Cu")
		(net "FM_P1V8MCP_CPU0_EN")
	)
	(segment
		(start 366.771936 -79.204312)
		(end 366.771936 -78.940152)
		(width 0.089408)
		(layer "In11.Cu")
		(net "FM_P1V8MCP_CPU0_EN")
	)
	(segment
		(start 378.751338 -78.695042)
		(end 378.744988 -78.695042)
		(width 0.10795)
		(layer "F.Cu")
		(net "FM_GLOBAL_RST_WARN_N")
	)
	(segment
		(start 379.1458 -79.089504)
		(end 378.751338 -78.695042)
		(width 0.10795)
		(layer "F.Cu")
		(net "FM_GLOBAL_RST_WARN_N")
	)
	(segment
		(start 413.382206 -19.03984)
		(end 412.66237 -19.759676)
		(width 0.10795)
		(layer "F.Cu")
		(net "FM_GLOBAL_RST_WARN_N")
	)
	(segment
		(start 397.14805 -101.2698)
		(end 397.558768 -101.079046)
		(width 0.10795)
		(layer "F.Cu")
		(net "FM_GLOBAL_RST_WARN_N")
	)
	(segment
		(start 409.786836 -21.234146)
		(end 409.786836 -21.644864)
		(width 0.10795)
		(layer "F.Cu")
		(net "FM_GLOBAL_RST_WARN_N")
	)
	(segment
		(start 410.048964 -21.906992)
		(end 410.048964 -22.181566)
		(width 0.10795)
		(layer "F.Cu")
		(net "FM_GLOBAL_RST_WARN_N")
	)
	(segment
		(start 397.558768 -101.079046)
		(end 397.64335 -101.039676)
		(width 0.10795)
		(layer "F.Cu")
		(net "FM_GLOBAL_RST_WARN_N")
	)
	(segment
		(start 411.261306 -19.759676)
		(end 411.257496 -19.759676)
		(width 0.10795)
		(layer "F.Cu")
		(net "FM_GLOBAL_RST_WARN_N")
	)
	(segment
		(start 409.786836 -21.644864)
		(end 410.048964 -21.906992)
		(width 0.10795)
		(layer "F.Cu")
		(net "FM_GLOBAL_RST_WARN_N")
	)
	(segment
		(start 412.66237 -19.759676)
		(end 411.261306 -19.759676)
		(width 0.10795)
		(layer "F.Cu")
		(net "FM_GLOBAL_RST_WARN_N")
	)
	(segment
		(start 411.261306 -19.759676)
		(end 409.786836 -21.234146)
		(width 0.10795)
		(layer "F.Cu")
		(net "FM_GLOBAL_RST_WARN_N")
	)
	(via
		(at 411.257496 -19.759676)
		(size 0.762)
		(drill 0.381)
		(layers "F.Cu" "B.Cu")
		(net "FM_GLOBAL_RST_WARN_N")
	)
	(via
		(at 376.850656 -92.180156)
		(size 0.508)
		(drill 0.254)
		(layers "F.Cu" "B.Cu")
		(net "FM_GLOBAL_RST_WARN_N")
	)
	(via
		(at 379.1458 -79.089504)
		(size 0.4572)
		(drill 0.2032)
		(layers "F.Cu" "B.Cu")
		(net "FM_GLOBAL_RST_WARN_N")
	)
	(via
		(at 397.64335 -101.039676)
		(size 0.508)
		(drill 0.254)
		(layers "F.Cu" "B.Cu")
		(net "FM_GLOBAL_RST_WARN_N")
	)
	(via
		(at 390.150858 -77.482192)
		(size 0.508)
		(drill 0.254)
		(layers "F.Cu" "B.Cu")
		(net "FM_GLOBAL_RST_WARN_N")
	)
	(via
		(at 413.382206 -19.03984)
		(size 0.508)
		(drill 0.254)
		(layers "F.Cu" "B.Cu")
		(net "FM_GLOBAL_RST_WARN_N")
	)
	(segment
		(start 395.428216 -94.336616)
		(end 396.06093 -94.96933)
		(width 0.089408)
		(layer "In2.Cu")
		(net "FM_GLOBAL_RST_WARN_N")
	)
	(segment
		(start 396.621 -98.679)
		(end 396.24 -99.06)
		(width 0.089408)
		(layer "In2.Cu")
		(net "FM_GLOBAL_RST_WARN_N")
	)
	(segment
		(start 376.850656 -92.180156)
		(end 376.41022 -92.620592)
		(width 0.089408)
		(layer "In2.Cu")
		(net "FM_GLOBAL_RST_WARN_N")
	)
	(segment
		(start 396.748 -100.457)
		(end 397.330676 -101.039676)
		(width 0.089408)
		(layer "In2.Cu")
		(net "FM_GLOBAL_RST_WARN_N")
	)
	(segment
		(start 376.942096 -93.266006)
		(end 378.012706 -94.336616)
		(width 0.089408)
		(layer "In2.Cu")
		(net "FM_GLOBAL_RST_WARN_N")
	)
	(segment
		(start 376.41022 -92.620592)
		(end 376.41022 -93.01861)
		(width 0.089408)
		(layer "In2.Cu")
		(net "FM_GLOBAL_RST_WARN_N")
	)
	(segment
		(start 396.621 -98.269806)
		(end 396.621 -98.679)
		(width 0.089408)
		(layer "In2.Cu")
		(net "FM_GLOBAL_RST_WARN_N")
	)
	(segment
		(start 396.06093 -94.96933)
		(end 396.06093 -95.889572)
		(width 0.089408)
		(layer "In2.Cu")
		(net "FM_GLOBAL_RST_WARN_N")
	)
	(segment
		(start 396.061946 -95.888556)
		(end 396.061946 -95.90913)
		(width 0.089408)
		(layer "In2.Cu")
		(net "FM_GLOBAL_RST_WARN_N")
	)
	(segment
		(start 378.012706 -94.336616)
		(end 395.428216 -94.336616)
		(width 0.089408)
		(layer "In2.Cu")
		(net "FM_GLOBAL_RST_WARN_N")
	)
	(segment
		(start 396.357348 -98.11766)
		(end 396.621 -98.269806)
		(width 0.089408)
		(layer "In2.Cu")
		(net "FM_GLOBAL_RST_WARN_N")
	)
	(segment
		(start 376.657616 -93.266006)
		(end 376.942096 -93.266006)
		(width 0.089408)
		(layer "In2.Cu")
		(net "FM_GLOBAL_RST_WARN_N")
	)
	(segment
		(start 397.330676 -101.039676)
		(end 397.64335 -101.039676)
		(width 0.089408)
		(layer "In2.Cu")
		(net "FM_GLOBAL_RST_WARN_N")
	)
	(segment
		(start 396.24 -99.568)
		(end 396.748 -100.076)
		(width 0.089408)
		(layer "In2.Cu")
		(net "FM_GLOBAL_RST_WARN_N")
	)
	(segment
		(start 396.06093 -95.889572)
		(end 396.061946 -95.888556)
		(width 0.089408)
		(layer "In2.Cu")
		(net "FM_GLOBAL_RST_WARN_N")
	)
	(segment
		(start 396.748 -100.076)
		(end 396.748 -100.457)
		(width 0.089408)
		(layer "In2.Cu")
		(net "FM_GLOBAL_RST_WARN_N")
	)
	(segment
		(start 376.41022 -93.01861)
		(end 376.657616 -93.266006)
		(width 0.089408)
		(layer "In2.Cu")
		(net "FM_GLOBAL_RST_WARN_N")
	)
	(segment
		(start 396.24 -99.06)
		(end 396.24 -99.568)
		(width 0.089408)
		(layer "In2.Cu")
		(net "FM_GLOBAL_RST_WARN_N")
	)
	(segment
		(start 396.061946 -97.585022)
		(end 396.061946 -97.62617)
		(width 0.089408)
		(layer "In2.Cu")
		(net "FM_GLOBAL_RST_WARN_N")
	)
	(segment
		(start 396.557246 -96.734884)
		(end 396.557246 -96.759268)
		(width 0.089408)
		(layer "In2.Cu")
		(net "FM_GLOBAL_RST_WARN_N")
	)
	(arc
		(start 396.357348 -97.093532)
		(mid 396.146064 -97.301061)
		(end 396.061946 -97.585022)
		(width 0.089408)
		(layer "In2.Cu")
		(net "FM_GLOBAL_RST_WARN_N")
	)
	(arc
		(start 396.557246 -96.759268)
		(mid 396.500727 -96.952371)
		(end 396.357348 -97.093532)
		(width 0.089408)
		(layer "In2.Cu")
		(net "FM_GLOBAL_RST_WARN_N")
	)
	(arc
		(start 396.357348 -96.40062)
		(mid 396.500733 -96.541777)
		(end 396.557246 -96.734884)
		(width 0.089408)
		(layer "In2.Cu")
		(net "FM_GLOBAL_RST_WARN_N")
	)
	(arc
		(start 396.061946 -95.90913)
		(mid 396.146064 -96.193091)
		(end 396.357348 -96.40062)
		(width 0.089408)
		(layer "In2.Cu")
		(net "FM_GLOBAL_RST_WARN_N")
	)
	(arc
		(start 396.061946 -97.62617)
		(mid 396.146064 -97.910131)
		(end 396.357348 -98.11766)
		(width 0.089408)
		(layer "In2.Cu")
		(net "FM_GLOBAL_RST_WARN_N")
	)
	(segment
		(start 379.525784 -78.70952)
		(end 379.1458 -79.089504)
		(width 0.089408)
		(layer "In4.Cu")
		(net "FM_GLOBAL_RST_WARN_N")
	)
	(segment
		(start 386.372862 -76.947268)
		(end 381.894842 -76.947268)
		(width 0.089408)
		(layer "In4.Cu")
		(net "FM_GLOBAL_RST_WARN_N")
	)
	(segment
		(start 390.150858 -77.482192)
		(end 389.941562 -77.691488)
		(width 0.089408)
		(layer "In4.Cu")
		(net "FM_GLOBAL_RST_WARN_N")
	)
	(segment
		(start 381.002794 -78.15453)
		(end 381.00254 -78.15453)
		(width 0.089408)
		(layer "In4.Cu")
		(net "FM_GLOBAL_RST_WARN_N")
	)
	(segment
		(start 381.243332 -77.756766)
		(end 381.243586 -77.75702)
		(width 0.089408)
		(layer "In4.Cu")
		(net "FM_GLOBAL_RST_WARN_N")
	)
	(segment
		(start 389.103362 -77.691488)
		(end 388.60095 -77.189076)
		(width 0.089408)
		(layer "In4.Cu")
		(net "FM_GLOBAL_RST_WARN_N")
	)
	(segment
		(start 388.60095 -77.189076)
		(end 386.61467 -77.189076)
		(width 0.089408)
		(layer "In4.Cu")
		(net "FM_GLOBAL_RST_WARN_N")
	)
	(segment
		(start 381.243332 -77.598778)
		(end 381.243332 -77.756766)
		(width 0.089408)
		(layer "In4.Cu")
		(net "FM_GLOBAL_RST_WARN_N")
	)
	(segment
		(start 381.894842 -76.947268)
		(end 381.243332 -77.598778)
		(width 0.089408)
		(layer "In4.Cu")
		(net "FM_GLOBAL_RST_WARN_N")
	)
	(segment
		(start 381.00254 -78.15453)
		(end 380.44755 -78.70952)
		(width 0.089408)
		(layer "In4.Cu")
		(net "FM_GLOBAL_RST_WARN_N")
	)
	(segment
		(start 380.44755 -78.70952)
		(end 379.525784 -78.70952)
		(width 0.089408)
		(layer "In4.Cu")
		(net "FM_GLOBAL_RST_WARN_N")
	)
	(segment
		(start 381.243586 -77.75702)
		(end 381.243586 -77.913738)
		(width 0.089408)
		(layer "In4.Cu")
		(net "FM_GLOBAL_RST_WARN_N")
	)
	(segment
		(start 381.243586 -77.913738)
		(end 381.002794 -78.15453)
		(width 0.089408)
		(layer "In4.Cu")
		(net "FM_GLOBAL_RST_WARN_N")
	)
	(segment
		(start 389.941562 -77.691488)
		(end 389.103362 -77.691488)
		(width 0.089408)
		(layer "In4.Cu")
		(net "FM_GLOBAL_RST_WARN_N")
	)
	(segment
		(start 386.61467 -77.189076)
		(end 386.372862 -76.947268)
		(width 0.089408)
		(layer "In4.Cu")
		(net "FM_GLOBAL_RST_WARN_N")
	)
	(segment
		(start 398.607534 -20.966176)
		(end 400.455638 -20.966176)
		(width 0.089408)
		(layer "In9.Cu")
		(net "FM_GLOBAL_RST_WARN_N")
	)
	(segment
		(start 391.628376 -71.87438)
		(end 391.628376 -70.7644)
		(width 0.089408)
		(layer "In9.Cu")
		(net "FM_GLOBAL_RST_WARN_N")
	)
	(segment
		(start 394.781786 -43.626532)
		(end 395.917674 -42.490644)
		(width 0.089408)
		(layer "In9.Cu")
		(net "FM_GLOBAL_RST_WARN_N")
	)
	(segment
		(start 402.602446 -22.428708)
		(end 408.236928 -22.428708)
		(width 0.089408)
		(layer "In9.Cu")
		(net "FM_GLOBAL_RST_WARN_N")
	)
	(segment
		(start 394.485368 -49.55286)
		(end 394.322554 -49.390046)
		(width 0.089408)
		(layer "In9.Cu")
		(net "FM_GLOBAL_RST_WARN_N")
	)
	(segment
		(start 396.023592 -33.389316)
		(end 396.399512 -33.013396)
		(width 0.089408)
		(layer "In9.Cu")
		(net "FM_GLOBAL_RST_WARN_N")
	)
	(segment
		(start 393.85113 -33.947862)
		(end 393.85113 -33.616138)
		(width 0.089408)
		(layer "In9.Cu")
		(net "FM_GLOBAL_RST_WARN_N")
	)
	(segment
		(start 391.395712 -75.185524)
		(end 391.395712 -73.966324)
		(width 0.089408)
		(layer "In9.Cu")
		(net "FM_GLOBAL_RST_WARN_N")
	)
	(segment
		(start 393.530836 -68.86194)
		(end 393.530836 -63.336932)
		(width 0.089408)
		(layer "In9.Cu")
		(net "FM_GLOBAL_RST_WARN_N")
	)
	(segment
		(start 394.424916 -33.389316)
		(end 396.023592 -33.389316)
		(width 0.089408)
		(layer "In9.Cu")
		(net "FM_GLOBAL_RST_WARN_N")
	)
	(segment
		(start 394.394944 -53.531008)
		(end 393.63269 -52.768754)
		(width 0.089408)
		(layer "In9.Cu")
		(net "FM_GLOBAL_RST_WARN_N")
	)
	(segment
		(start 402.478748 -22.552406)
		(end 402.602446 -22.428708)
		(width 0.089408)
		(layer "In9.Cu")
		(net "FM_GLOBAL_RST_WARN_N")
	)
	(segment
		(start 394.485368 -50.218086)
		(end 394.485368 -49.55286)
		(width 0.089408)
		(layer "In9.Cu")
		(net "FM_GLOBAL_RST_WARN_N")
	)
	(segment
		(start 396.641574 -31.185104)
		(end 396.641574 -22.932136)
		(width 0.089408)
		(layer "In9.Cu")
		(net "FM_GLOBAL_RST_WARN_N")
	)
	(segment
		(start 400.455638 -20.966176)
		(end 402.041868 -22.552406)
		(width 0.089408)
		(layer "In9.Cu")
		(net "FM_GLOBAL_RST_WARN_N")
	)
	(segment
		(start 394.888974 -37.795708)
		(end 394.888974 -35.79114)
		(width 0.089408)
		(layer "In9.Cu")
		(net "FM_GLOBAL_RST_WARN_N")
	)
	(segment
		(start 394.322554 -44.411138)
		(end 394.781786 -43.951906)
		(width 0.089408)
		(layer "In9.Cu")
		(net "FM_GLOBAL_RST_WARN_N")
	)
	(segment
		(start 393.63269 -52.768754)
		(end 393.63269 -51.070764)
		(width 0.089408)
		(layer "In9.Cu")
		(net "FM_GLOBAL_RST_WARN_N")
	)
	(segment
		(start 410.175964 -20.489672)
		(end 410.175964 -19.93519)
		(width 0.089408)
		(layer "In9.Cu")
		(net "FM_GLOBAL_RST_WARN_N")
	)
	(segment
		(start 394.322554 -49.390046)
		(end 394.322554 -44.411138)
		(width 0.089408)
		(layer "In9.Cu")
		(net "FM_GLOBAL_RST_WARN_N")
	)
	(segment
		(start 390.150858 -77.482192)
		(end 390.150858 -76.430378)
		(width 0.089408)
		(layer "In9.Cu")
		(net "FM_GLOBAL_RST_WARN_N")
	)
	(segment
		(start 410.175964 -19.93519)
		(end 411.50032 -18.610834)
		(width 0.089408)
		(layer "In9.Cu")
		(net "FM_GLOBAL_RST_WARN_N")
	)
	(segment
		(start 391.395712 -73.966324)
		(end 391.233914 -73.804526)
		(width 0.089408)
		(layer "In9.Cu")
		(net "FM_GLOBAL_RST_WARN_N")
	)
	(segment
		(start 394.569696 -35.471862)
		(end 394.569696 -34.666428)
		(width 0.089408)
		(layer "In9.Cu")
		(net "FM_GLOBAL_RST_WARN_N")
	)
	(segment
		(start 408.236928 -22.428708)
		(end 410.175964 -20.489672)
		(width 0.089408)
		(layer "In9.Cu")
		(net "FM_GLOBAL_RST_WARN_N")
	)
	(segment
		(start 391.628376 -70.7644)
		(end 393.530836 -68.86194)
		(width 0.089408)
		(layer "In9.Cu")
		(net "FM_GLOBAL_RST_WARN_N")
	)
	(segment
		(start 395.91742 -41.119806)
		(end 395.91742 -38.824154)
		(width 0.089408)
		(layer "In9.Cu")
		(net "FM_GLOBAL_RST_WARN_N")
	)
	(segment
		(start 396.641574 -22.932136)
		(end 398.607534 -20.966176)
		(width 0.089408)
		(layer "In9.Cu")
		(net "FM_GLOBAL_RST_WARN_N")
	)
	(segment
		(start 394.417296 -33.381696)
		(end 394.424916 -33.389316)
		(width 0.089408)
		(layer "In9.Cu")
		(net "FM_GLOBAL_RST_WARN_N")
	)
	(segment
		(start 394.085572 -33.381696)
		(end 394.417296 -33.381696)
		(width 0.089408)
		(layer "In9.Cu")
		(net "FM_GLOBAL_RST_WARN_N")
	)
	(segment
		(start 394.394944 -62.472824)
		(end 394.394944 -53.531008)
		(width 0.089408)
		(layer "In9.Cu")
		(net "FM_GLOBAL_RST_WARN_N")
	)
	(segment
		(start 412.9532 -18.610834)
		(end 413.382206 -19.03984)
		(width 0.089408)
		(layer "In9.Cu")
		(net "FM_GLOBAL_RST_WARN_N")
	)
	(segment
		(start 391.233914 -73.804526)
		(end 391.233914 -72.268842)
		(width 0.089408)
		(layer "In9.Cu")
		(net "FM_GLOBAL_RST_WARN_N")
	)
	(segment
		(start 393.530836 -63.336932)
		(end 394.394944 -62.472824)
		(width 0.089408)
		(layer "In9.Cu")
		(net "FM_GLOBAL_RST_WARN_N")
	)
	(segment
		(start 395.91742 -38.824154)
		(end 394.888974 -37.795708)
		(width 0.089408)
		(layer "In9.Cu")
		(net "FM_GLOBAL_RST_WARN_N")
	)
	(segment
		(start 390.150858 -76.430378)
		(end 391.395712 -75.185524)
		(width 0.089408)
		(layer "In9.Cu")
		(net "FM_GLOBAL_RST_WARN_N")
	)
	(segment
		(start 411.50032 -18.610834)
		(end 412.9532 -18.610834)
		(width 0.089408)
		(layer "In9.Cu")
		(net "FM_GLOBAL_RST_WARN_N")
	)
	(segment
		(start 393.63269 -51.070764)
		(end 394.485368 -50.218086)
		(width 0.089408)
		(layer "In9.Cu")
		(net "FM_GLOBAL_RST_WARN_N")
	)
	(segment
		(start 396.399512 -31.427166)
		(end 396.641574 -31.185104)
		(width 0.089408)
		(layer "In9.Cu")
		(net "FM_GLOBAL_RST_WARN_N")
	)
	(segment
		(start 402.041868 -22.552406)
		(end 402.478748 -22.552406)
		(width 0.089408)
		(layer "In9.Cu")
		(net "FM_GLOBAL_RST_WARN_N")
	)
	(segment
		(start 393.85113 -33.616138)
		(end 394.085572 -33.381696)
		(width 0.089408)
		(layer "In9.Cu")
		(net "FM_GLOBAL_RST_WARN_N")
	)
	(segment
		(start 396.399512 -33.013396)
		(end 396.399512 -31.427166)
		(width 0.089408)
		(layer "In9.Cu")
		(net "FM_GLOBAL_RST_WARN_N")
	)
	(segment
		(start 391.233914 -72.268842)
		(end 391.628376 -71.87438)
		(width 0.089408)
		(layer "In9.Cu")
		(net "FM_GLOBAL_RST_WARN_N")
	)
	(segment
		(start 394.888974 -35.79114)
		(end 394.569696 -35.471862)
		(width 0.089408)
		(layer "In9.Cu")
		(net "FM_GLOBAL_RST_WARN_N")
	)
	(segment
		(start 395.917674 -42.490644)
		(end 395.917674 -41.12006)
		(width 0.089408)
		(layer "In9.Cu")
		(net "FM_GLOBAL_RST_WARN_N")
	)
	(segment
		(start 394.569696 -34.666428)
		(end 393.85113 -33.947862)
		(width 0.089408)
		(layer "In9.Cu")
		(net "FM_GLOBAL_RST_WARN_N")
	)
	(segment
		(start 395.917674 -41.12006)
		(end 395.91742 -41.119806)
		(width 0.089408)
		(layer "In9.Cu")
		(net "FM_GLOBAL_RST_WARN_N")
	)
	(segment
		(start 394.781786 -43.951906)
		(end 394.781786 -43.626532)
		(width 0.089408)
		(layer "In9.Cu")
		(net "FM_GLOBAL_RST_WARN_N")
	)
	(segment
		(start 377.615704 -90.47861)
		(end 377.897644 -90.19667)
		(width 0.089408)
		(layer "In11.Cu")
		(net "FM_GLOBAL_RST_WARN_N")
	)
	(segment
		(start 377.897644 -90.19667)
		(end 377.897644 -88.477344)
		(width 0.089408)
		(layer "In11.Cu")
		(net "FM_GLOBAL_RST_WARN_N")
	)
	(segment
		(start 378.7394 -81.004918)
		(end 378.7394 -79.495904)
		(width 0.089408)
		(layer "In11.Cu")
		(net "FM_GLOBAL_RST_WARN_N")
	)
	(segment
		(start 378.7394 -79.495904)
		(end 379.1458 -79.089504)
		(width 0.089408)
		(layer "In11.Cu")
		(net "FM_GLOBAL_RST_WARN_N")
	)
	(segment
		(start 378.1425 -81.601818)
		(end 378.7394 -81.004918)
		(width 0.089408)
		(layer "In11.Cu")
		(net "FM_GLOBAL_RST_WARN_N")
	)
	(segment
		(start 376.12574 -86.70544)
		(end 376.12574 -82.26552)
		(width 0.089408)
		(layer "In11.Cu")
		(net "FM_GLOBAL_RST_WARN_N")
	)
	(segment
		(start 377.897644 -88.477344)
		(end 376.12574 -86.70544)
		(width 0.089408)
		(layer "In11.Cu")
		(net "FM_GLOBAL_RST_WARN_N")
	)
	(segment
		(start 376.850656 -92.180156)
		(end 376.849386 -92.180156)
		(width 0.089408)
		(layer "In11.Cu")
		(net "FM_GLOBAL_RST_WARN_N")
	)
	(segment
		(start 376.789442 -81.601818)
		(end 378.1425 -81.601818)
		(width 0.089408)
		(layer "In11.Cu")
		(net "FM_GLOBAL_RST_WARN_N")
	)
	(segment
		(start 376.849386 -92.180156)
		(end 376.849386 -92.065856)
		(width 0.089408)
		(layer "In11.Cu")
		(net "FM_GLOBAL_RST_WARN_N")
	)
	(segment
		(start 376.12574 -82.26552)
		(end 376.789442 -81.601818)
		(width 0.089408)
		(layer "In11.Cu")
		(net "FM_GLOBAL_RST_WARN_N")
	)
	(segment
		(start 376.849386 -92.065856)
		(end 377.615704 -91.299538)
		(width 0.089408)
		(layer "In11.Cu")
		(net "FM_GLOBAL_RST_WARN_N")
	)
	(segment
		(start 377.615704 -91.299538)
		(end 377.615704 -90.47861)
		(width 0.089408)
		(layer "In11.Cu")
		(net "FM_GLOBAL_RST_WARN_N")
	)
	(segment
		(start 402.384006 -106.484166)
		(end 402.47062 -106.397552)
		(width 0.0889)
		(layer "F.Cu")
		(net "FM_CPU1_RC_EN")
	)
	(segment
		(start 403.656292 -106.397552)
		(end 404.327614 -107.068874)
		(width 0.0889)
		(layer "F.Cu")
		(net "FM_CPU1_RC_EN")
	)
	(segment
		(start 404.57374 -107.315)
		(end 406.908254 -107.315)
		(width 0.10795)
		(layer "F.Cu")
		(net "FM_CPU1_RC_EN")
	)
	(segment
		(start 407.162 -107.434634)
		(end 407.784046 -107.434634)
		(width 0.10795)
		(layer "F.Cu")
		(net "FM_CPU1_RC_EN")
	)
	(segment
		(start 406.908254 -107.315)
		(end 407.027888 -107.434634)
		(width 0.10795)
		(layer "F.Cu")
		(net "FM_CPU1_RC_EN")
	)
	(segment
		(start 401.510754 -106.331258)
		(end 401.558252 -106.378756)
		(width 0.0889)
		(layer "F.Cu")
		(net "FM_CPU1_RC_EN")
	)
	(segment
		(start 401.558506 -106.378756)
		(end 401.663916 -106.484166)
		(width 0.0889)
		(layer "F.Cu")
		(net "FM_CPU1_RC_EN")
	)
	(segment
		(start 407.027888 -107.434634)
		(end 407.162 -107.434634)
		(width 0.10795)
		(layer "F.Cu")
		(net "FM_CPU1_RC_EN")
	)
	(segment
		(start 401.663916 -106.484166)
		(end 402.384006 -106.484166)
		(width 0.0889)
		(layer "F.Cu")
		(net "FM_CPU1_RC_EN")
	)
	(segment
		(start 400.880072 -106.35488)
		(end 400.903694 -106.331258)
		(width 0.0889)
		(layer "F.Cu")
		(net "FM_CPU1_RC_EN")
	)
	(segment
		(start 400.903694 -106.331258)
		(end 401.510754 -106.331258)
		(width 0.0889)
		(layer "F.Cu")
		(net "FM_CPU1_RC_EN")
	)
	(segment
		(start 376.744738 -79.094838)
		(end 376.344942 -78.695042)
		(width 0.10795)
		(layer "F.Cu")
		(net "FM_CPU1_RC_EN")
	)
	(segment
		(start 402.47062 -106.397552)
		(end 403.656292 -106.397552)
		(width 0.0889)
		(layer "F.Cu")
		(net "FM_CPU1_RC_EN")
	)
	(segment
		(start 404.327614 -107.068874)
		(end 404.57374 -107.315)
		(width 0.10795)
		(layer "F.Cu")
		(net "FM_CPU1_RC_EN")
	)
	(segment
		(start 401.558252 -106.378756)
		(end 401.558506 -106.378756)
		(width 0.0889)
		(layer "F.Cu")
		(net "FM_CPU1_RC_EN")
	)
	(via
		(at 407.162 -107.434634)
		(size 0.508)
		(drill 0.254)
		(layers "F.Cu" "B.Cu")
		(net "FM_CPU1_RC_EN")
	)
	(via
		(at 376.744738 -79.094838)
		(size 0.4572)
		(drill 0.2032)
		(layers "F.Cu" "B.Cu")
		(net "FM_CPU1_RC_EN")
	)
	(via
		(at 410.287978 -118.536466)
		(size 0.6604)
		(drill 0.3302)
		(layers "F.Cu" "B.Cu")
		(net "FM_CPU1_RC_EN")
	)
	(via
		(at 410.225494 -117.641878)
		(size 0.508)
		(drill 0.254)
		(layers "F.Cu" "B.Cu")
		(net "FM_CPU1_RC_EN")
	)
	(segment
		(start 410.225494 -117.641878)
		(end 410.225494 -118.473982)
		(width 0.10795)
		(layer "B.Cu")
		(net "FM_CPU1_RC_EN")
	)
	(segment
		(start 410.225494 -118.473982)
		(end 410.287978 -118.536466)
		(width 0.10795)
		(layer "B.Cu")
		(net "FM_CPU1_RC_EN")
	)
	(segment
		(start 407.753312 -113.751614)
		(end 407.753312 -114.800126)
		(width 0.089408)
		(layer "In2.Cu")
		(net "FM_CPU1_RC_EN")
	)
	(segment
		(start 407.6319 -109.6645)
		(end 407.6319 -112.440212)
		(width 0.089408)
		(layer "In2.Cu")
		(net "FM_CPU1_RC_EN")
	)
	(segment
		(start 407.753312 -112.561624)
		(end 407.753312 -112.959134)
		(width 0.089408)
		(layer "In2.Cu")
		(net "FM_CPU1_RC_EN")
	)
	(segment
		(start 407.753312 -112.959134)
		(end 407.753058 -112.959388)
		(width 0.089408)
		(layer "In2.Cu")
		(net "FM_CPU1_RC_EN")
	)
	(segment
		(start 407.753312 -114.800126)
		(end 410.225494 -117.272308)
		(width 0.089408)
		(layer "In2.Cu")
		(net "FM_CPU1_RC_EN")
	)
	(segment
		(start 407.753058 -113.75136)
		(end 407.753312 -113.751614)
		(width 0.089408)
		(layer "In2.Cu")
		(net "FM_CPU1_RC_EN")
	)
	(segment
		(start 407.543 -107.815634)
		(end 407.543 -109.5756)
		(width 0.089408)
		(layer "In2.Cu")
		(net "FM_CPU1_RC_EN")
	)
	(segment
		(start 407.753058 -112.959388)
		(end 407.753058 -113.75136)
		(width 0.089408)
		(layer "In2.Cu")
		(net "FM_CPU1_RC_EN")
	)
	(segment
		(start 410.225494 -117.272308)
		(end 410.225494 -117.641878)
		(width 0.089408)
		(layer "In2.Cu")
		(net "FM_CPU1_RC_EN")
	)
	(segment
		(start 407.543 -109.5756)
		(end 407.6319 -109.6645)
		(width 0.089408)
		(layer "In2.Cu")
		(net "FM_CPU1_RC_EN")
	)
	(segment
		(start 407.6319 -112.440212)
		(end 407.753312 -112.561624)
		(width 0.089408)
		(layer "In2.Cu")
		(net "FM_CPU1_RC_EN")
	)
	(segment
		(start 407.162 -107.434634)
		(end 407.543 -107.815634)
		(width 0.089408)
		(layer "In2.Cu")
		(net "FM_CPU1_RC_EN")
	)
	(segment
		(start 373.72798 -97.325688)
		(end 373.72798 -97.708974)
		(width 0.089408)
		(layer "In9.Cu")
		(net "FM_CPU1_RC_EN")
	)
	(segment
		(start 378.431044 -98.004376)
		(end 378.91847 -98.491802)
		(width 0.089408)
		(layer "In9.Cu")
		(net "FM_CPU1_RC_EN")
	)
	(segment
		(start 383.187702 -103.7209)
		(end 383.3749 -103.7209)
		(width 0.089408)
		(layer "In9.Cu")
		(net "FM_CPU1_RC_EN")
	)
	(segment
		(start 384.744468 -103.066596)
		(end 385.363974 -103.686102)
		(width 0.0889)
		(layer "In9.Cu")
		(net "FM_CPU1_RC_EN")
	)
	(segment
		(start 383.3749 -103.7209)
		(end 384.029204 -103.066596)
		(width 0.089408)
		(layer "In9.Cu")
		(net "FM_CPU1_RC_EN")
	)
	(segment
		(start 381.446786 -104.327706)
		(end 382.580896 -104.327706)
		(width 0.089408)
		(layer "In9.Cu")
		(net "FM_CPU1_RC_EN")
	)
	(segment
		(start 388.306056 -104.67467)
		(end 388.88289 -104.67467)
		(width 0.0889)
		(layer "In9.Cu")
		(net "FM_CPU1_RC_EN")
	)
	(segment
		(start 388.88289 -104.67467)
		(end 388.95782 -104.59974)
		(width 0.0889)
		(layer "In9.Cu")
		(net "FM_CPU1_RC_EN")
	)
	(segment
		(start 399.39976 -116.63934)
		(end 399.39976 -116.817394)
		(width 0.0889)
		(layer "In9.Cu")
		(net "FM_CPU1_RC_EN")
	)
	(segment
		(start 373.68734 -92.61094)
		(end 375.48566 -94.40926)
		(width 0.089408)
		(layer "In9.Cu")
		(net "FM_CPU1_RC_EN")
	)
	(segment
		(start 395.56563 -116.26977)
		(end 395.26337 -116.57203)
		(width 0.089408)
		(layer "In9.Cu")
		(net "FM_CPU1_RC_EN")
	)
	(segment
		(start 380.89967 -103.41737)
		(end 380.89967 -103.78059)
		(width 0.089408)
		(layer "In9.Cu")
		(net "FM_CPU1_RC_EN")
	)
	(segment
		(start 394.7033 -111.0615)
		(end 395.224 -111.5822)
		(width 0.089408)
		(layer "In9.Cu")
		(net "FM_CPU1_RC_EN")
	)
	(segment
		(start 395.233398 -116.787676)
		(end 395.266164 -117.011196)
		(width 0.0889)
		(layer "In9.Cu")
		(net "FM_CPU1_RC_EN")
	)
	(segment
		(start 375.48566 -96.31426)
		(end 374.71604 -97.08388)
		(width 0.089408)
		(layer "In9.Cu")
		(net "FM_CPU1_RC_EN")
	)
	(segment
		(start 393.52855 -107.131358)
		(end 394.100812 -107.70362)
		(width 0.089408)
		(layer "In9.Cu")
		(net "FM_CPU1_RC_EN")
	)
	(segment
		(start 408.402282 -118.838218)
		(end 409.2575 -117.983)
		(width 0.089408)
		(layer "In9.Cu")
		(net "FM_CPU1_RC_EN")
	)
	(segment
		(start 394.100812 -108.166408)
		(end 393.77112 -108.4961)
		(width 0.089408)
		(layer "In9.Cu")
		(net "FM_CPU1_RC_EN")
	)
	(segment
		(start 373.72798 -97.708974)
		(end 373.961406 -97.9424)
		(width 0.089408)
		(layer "In9.Cu")
		(net "FM_CPU1_RC_EN")
	)
	(segment
		(start 391.172446 -104.65308)
		(end 392.75766 -104.65308)
		(width 0.089408)
		(layer "In9.Cu")
		(net "FM_CPU1_RC_EN")
	)
	(segment
		(start 386.830824 -104.655874)
		(end 387.949948 -104.655874)
		(width 0.0889)
		(layer "In9.Cu")
		(net "FM_CPU1_RC_EN")
	)
	(segment
		(start 377.665996 -98.004376)
		(end 378.431044 -98.004376)
		(width 0.089408)
		(layer "In9.Cu")
		(net "FM_CPU1_RC_EN")
	)
	(segment
		(start 380.89967 -101.822504)
		(end 380.89967 -102.289102)
		(width 0.089408)
		(layer "In9.Cu")
		(net "FM_CPU1_RC_EN")
	)
	(segment
		(start 377.118118 -79.713328)
		(end 377.118118 -80.887062)
		(width 0.089408)
		(layer "In9.Cu")
		(net "FM_CPU1_RC_EN")
	)
	(segment
		(start 370.172996 -90.772996)
		(end 370.62664 -91.22664)
		(width 0.089408)
		(layer "In9.Cu")
		(net "FM_CPU1_RC_EN")
	)
	(segment
		(start 395.266164 -116.574824)
		(end 395.233398 -116.60759)
		(width 0.0889)
		(layer "In9.Cu")
		(net "FM_CPU1_RC_EN")
	)
	(segment
		(start 409.2575 -117.983)
		(end 409.884372 -117.983)
		(width 0.089408)
		(layer "In9.Cu")
		(net "FM_CPU1_RC_EN")
	)
	(segment
		(start 393.77112 -109.07014)
		(end 394.22324 -109.52226)
		(width 0.089408)
		(layer "In9.Cu")
		(net "FM_CPU1_RC_EN")
	)
	(segment
		(start 375.666508 -82.338672)
		(end 375.666508 -87.076534)
		(width 0.089408)
		(layer "In9.Cu")
		(net "FM_CPU1_RC_EN")
	)
	(segment
		(start 373.67845 -89.064592)
		(end 370.702586 -89.064592)
		(width 0.089408)
		(layer "In9.Cu")
		(net "FM_CPU1_RC_EN")
	)
	(segment
		(start 373.961406 -97.9424)
		(end 377.60402 -97.9424)
		(width 0.089408)
		(layer "In9.Cu")
		(net "FM_CPU1_RC_EN")
	)
	(segment
		(start 394.100812 -107.70362)
		(end 394.100812 -108.166408)
		(width 0.089408)
		(layer "In9.Cu")
		(net "FM_CPU1_RC_EN")
	)
	(segment
		(start 393.52855 -106.803698)
		(end 393.52855 -107.131358)
		(width 0.089408)
		(layer "In9.Cu")
		(net "FM_CPU1_RC_EN")
	)
	(segment
		(start 370.172996 -90.359738)
		(end 370.172996 -90.772996)
		(width 0.089408)
		(layer "In9.Cu")
		(net "FM_CPU1_RC_EN")
	)
	(segment
		(start 370.293392 -90.239342)
		(end 370.172996 -90.359738)
		(width 0.089408)
		(layer "In9.Cu")
		(net "FM_CPU1_RC_EN")
	)
	(segment
		(start 381.20193 -103.11511)
		(end 380.89967 -103.41737)
		(width 0.089408)
		(layer "In9.Cu")
		(net "FM_CPU1_RC_EN")
	)
	(segment
		(start 377.60402 -97.9424)
		(end 377.665996 -98.004376)
		(width 0.089408)
		(layer "In9.Cu")
		(net "FM_CPU1_RC_EN")
	)
	(segment
		(start 373.68734 -92.33662)
		(end 373.68734 -92.61094)
		(width 0.089408)
		(layer "In9.Cu")
		(net "FM_CPU1_RC_EN")
	)
	(segment
		(start 384.029204 -103.066596)
		(end 384.744468 -103.066596)
		(width 0.0889)
		(layer "In9.Cu")
		(net "FM_CPU1_RC_EN")
	)
	(segment
		(start 395.56563 -112.49533)
		(end 395.56563 -112.99317)
		(width 0.089408)
		(layer "In9.Cu")
		(net "FM_CPU1_RC_EN")
	)
	(segment
		(start 370.62664 -91.22664)
		(end 370.62664 -91.85402)
		(width 0.089408)
		(layer "In9.Cu")
		(net "FM_CPU1_RC_EN")
	)
	(segment
		(start 399.39976 -116.817394)
		(end 399.92554 -117.343174)
		(width 0.0889)
		(layer "In9.Cu")
		(net "FM_CPU1_RC_EN")
	)
	(segment
		(start 401.420584 -118.838218)
		(end 408.402282 -118.838218)
		(width 0.089408)
		(layer "In9.Cu")
		(net "FM_CPU1_RC_EN")
	)
	(segment
		(start 375.666508 -87.076534)
		(end 373.67845 -89.064592)
		(width 0.089408)
		(layer "In9.Cu")
		(net "FM_CPU1_RC_EN")
	)
	(segment
		(start 395.26337 -116.57203)
		(end 395.266164 -116.574824)
		(width 0.0889)
		(layer "In9.Cu")
		(net "FM_CPU1_RC_EN")
	)
	(segment
		(start 395.56563 -115.84813)
		(end 395.56563 -116.26977)
		(width 0.089408)
		(layer "In9.Cu")
		(net "FM_CPU1_RC_EN")
	)
	(segment
		(start 379.838712 -99.912932)
		(end 379.838712 -100.276152)
		(width 0.089408)
		(layer "In9.Cu")
		(net "FM_CPU1_RC_EN")
	)
	(segment
		(start 387.949948 -104.655874)
		(end 387.9723 -104.678226)
		(width 0.0889)
		(layer "In9.Cu")
		(net "FM_CPU1_RC_EN")
	)
	(segment
		(start 378.91847 -98.62947)
		(end 379.41377 -99.12477)
		(width 0.089408)
		(layer "In9.Cu")
		(net "FM_CPU1_RC_EN")
	)
	(segment
		(start 385.861052 -103.686102)
		(end 386.830824 -104.655874)
		(width 0.0889)
		(layer "In9.Cu")
		(net "FM_CPU1_RC_EN")
	)
	(segment
		(start 394.22324 -109.79658)
		(end 394.7033 -110.27664)
		(width 0.089408)
		(layer "In9.Cu")
		(net "FM_CPU1_RC_EN")
	)
	(segment
		(start 395.224 -112.1537)
		(end 395.56563 -112.49533)
		(width 0.089408)
		(layer "In9.Cu")
		(net "FM_CPU1_RC_EN")
	)
	(segment
		(start 395.2494 -113.3094)
		(end 395.2494 -115.5319)
		(width 0.089408)
		(layer "In9.Cu")
		(net "FM_CPU1_RC_EN")
	)
	(segment
		(start 409.884372 -117.983)
		(end 410.225494 -117.641878)
		(width 0.089408)
		(layer "In9.Cu")
		(net "FM_CPU1_RC_EN")
	)
	(segment
		(start 385.363974 -103.686102)
		(end 385.861052 -103.686102)
		(width 0.0889)
		(layer "In9.Cu")
		(net "FM_CPU1_RC_EN")
	)
	(segment
		(start 394.7033 -110.27664)
		(end 394.7033 -111.0615)
		(width 0.089408)
		(layer "In9.Cu")
		(net "FM_CPU1_RC_EN")
	)
	(segment
		(start 387.9723 -104.678226)
		(end 388.3025 -104.678226)
		(width 0.0889)
		(layer "In9.Cu")
		(net "FM_CPU1_RC_EN")
	)
	(segment
		(start 379.838712 -100.276152)
		(end 380.40437 -100.84181)
		(width 0.089408)
		(layer "In9.Cu")
		(net "FM_CPU1_RC_EN")
	)
	(segment
		(start 380.89967 -102.289102)
		(end 381.20193 -102.591362)
		(width 0.089408)
		(layer "In9.Cu")
		(net "FM_CPU1_RC_EN")
	)
	(segment
		(start 394.22324 -109.52226)
		(end 394.22324 -109.79658)
		(width 0.089408)
		(layer "In9.Cu")
		(net "FM_CPU1_RC_EN")
	)
	(segment
		(start 378.91847 -98.491802)
		(end 378.91847 -98.62947)
		(width 0.089408)
		(layer "In9.Cu")
		(net "FM_CPU1_RC_EN")
	)
	(segment
		(start 370.293392 -89.473786)
		(end 370.293392 -90.239342)
		(width 0.089408)
		(layer "In9.Cu")
		(net "FM_CPU1_RC_EN")
	)
	(segment
		(start 371.18798 -92.41536)
		(end 371.89664 -92.41536)
		(width 0.089408)
		(layer "In9.Cu")
		(net "FM_CPU1_RC_EN")
	)
	(segment
		(start 381.20193 -102.591362)
		(end 381.20193 -103.11511)
		(width 0.089408)
		(layer "In9.Cu")
		(net "FM_CPU1_RC_EN")
	)
	(segment
		(start 382.580896 -104.327706)
		(end 383.187702 -103.7209)
		(width 0.089408)
		(layer "In9.Cu")
		(net "FM_CPU1_RC_EN")
	)
	(segment
		(start 370.702586 -89.064592)
		(end 370.293392 -89.473786)
		(width 0.089408)
		(layer "In9.Cu")
		(net "FM_CPU1_RC_EN")
	)
	(segment
		(start 395.2494 -115.5319)
		(end 395.56563 -115.84813)
		(width 0.089408)
		(layer "In9.Cu")
		(net "FM_CPU1_RC_EN")
	)
	(segment
		(start 374.71604 -97.08388)
		(end 373.969788 -97.08388)
		(width 0.089408)
		(layer "In9.Cu")
		(net "FM_CPU1_RC_EN")
	)
	(segment
		(start 392.75766 -104.65308)
		(end 393.37488 -105.2703)
		(width 0.089408)
		(layer "In9.Cu")
		(net "FM_CPU1_RC_EN")
	)
	(segment
		(start 391.119106 -104.59974)
		(end 391.172446 -104.65308)
		(width 0.089408)
		(layer "In9.Cu")
		(net "FM_CPU1_RC_EN")
	)
	(segment
		(start 380.40437 -100.84181)
		(end 380.40437 -101.327204)
		(width 0.089408)
		(layer "In9.Cu")
		(net "FM_CPU1_RC_EN")
	)
	(segment
		(start 380.89967 -103.78059)
		(end 381.446786 -104.327706)
		(width 0.089408)
		(layer "In9.Cu")
		(net "FM_CPU1_RC_EN")
	)
	(segment
		(start 395.224 -111.5822)
		(end 395.224 -112.1537)
		(width 0.089408)
		(layer "In9.Cu")
		(net "FM_CPU1_RC_EN")
	)
	(segment
		(start 379.41377 -99.12477)
		(end 379.41377 -99.48799)
		(width 0.089408)
		(layer "In9.Cu")
		(net "FM_CPU1_RC_EN")
	)
	(segment
		(start 370.62664 -91.85402)
		(end 371.18798 -92.41536)
		(width 0.089408)
		(layer "In9.Cu")
		(net "FM_CPU1_RC_EN")
	)
	(segment
		(start 388.95782 -104.59974)
		(end 391.119106 -104.59974)
		(width 0.089408)
		(layer "In9.Cu")
		(net "FM_CPU1_RC_EN")
	)
	(segment
		(start 388.3025 -104.678226)
		(end 388.306056 -104.67467)
		(width 0.0889)
		(layer "In9.Cu")
		(net "FM_CPU1_RC_EN")
	)
	(segment
		(start 393.37488 -106.650028)
		(end 393.52855 -106.803698)
		(width 0.089408)
		(layer "In9.Cu")
		(net "FM_CPU1_RC_EN")
	)
	(segment
		(start 399.254218 -116.493798)
		(end 399.39976 -116.63934)
		(width 0.0889)
		(layer "In9.Cu")
		(net "FM_CPU1_RC_EN")
	)
	(segment
		(start 377.118118 -80.887062)
		(end 375.666508 -82.338672)
		(width 0.089408)
		(layer "In9.Cu")
		(net "FM_CPU1_RC_EN")
	)
	(segment
		(start 379.41377 -99.48799)
		(end 379.838712 -99.912932)
		(width 0.089408)
		(layer "In9.Cu")
		(net "FM_CPU1_RC_EN")
	)
	(segment
		(start 380.40437 -101.327204)
		(end 380.89967 -101.822504)
		(width 0.089408)
		(layer "In9.Cu")
		(net "FM_CPU1_RC_EN")
	)
	(segment
		(start 376.744738 -79.094838)
		(end 376.744738 -79.339948)
		(width 0.089408)
		(layer "In9.Cu")
		(net "FM_CPU1_RC_EN")
	)
	(segment
		(start 395.56563 -112.99317)
		(end 395.2494 -113.3094)
		(width 0.089408)
		(layer "In9.Cu")
		(net "FM_CPU1_RC_EN")
	)
	(segment
		(start 396.0622 -116.96446)
		(end 396.0622 -116.931694)
		(width 0.0889)
		(layer "In9.Cu")
		(net "FM_CPU1_RC_EN")
	)
	(segment
		(start 373.969788 -97.08388)
		(end 373.72798 -97.325688)
		(width 0.089408)
		(layer "In9.Cu")
		(net "FM_CPU1_RC_EN")
	)
	(segment
		(start 393.77112 -108.4961)
		(end 393.77112 -109.07014)
		(width 0.089408)
		(layer "In9.Cu")
		(net "FM_CPU1_RC_EN")
	)
	(segment
		(start 371.89664 -92.41536)
		(end 372.52148 -91.79052)
		(width 0.089408)
		(layer "In9.Cu")
		(net "FM_CPU1_RC_EN")
	)
	(segment
		(start 373.14124 -91.79052)
		(end 373.68734 -92.33662)
		(width 0.089408)
		(layer "In9.Cu")
		(net "FM_CPU1_RC_EN")
	)
	(segment
		(start 372.52148 -91.79052)
		(end 373.14124 -91.79052)
		(width 0.089408)
		(layer "In9.Cu")
		(net "FM_CPU1_RC_EN")
	)
	(segment
		(start 399.92554 -117.343174)
		(end 401.420584 -118.838218)
		(width 0.089408)
		(layer "In9.Cu")
		(net "FM_CPU1_RC_EN")
	)
	(segment
		(start 376.744738 -79.339948)
		(end 377.118118 -79.713328)
		(width 0.089408)
		(layer "In9.Cu")
		(net "FM_CPU1_RC_EN")
	)
	(segment
		(start 393.37488 -105.2703)
		(end 393.37488 -106.650028)
		(width 0.089408)
		(layer "In9.Cu")
		(net "FM_CPU1_RC_EN")
	)
	(segment
		(start 395.233398 -116.60759)
		(end 395.233398 -116.787676)
		(width 0.0889)
		(layer "In9.Cu")
		(net "FM_CPU1_RC_EN")
	)
	(segment
		(start 399.158968 -116.493798)
		(end 399.254218 -116.493798)
		(width 0.0889)
		(layer "In9.Cu")
		(net "FM_CPU1_RC_EN")
	)
	(segment
		(start 375.48566 -94.40926)
		(end 375.48566 -96.31426)
		(width 0.089408)
		(layer "In9.Cu")
		(net "FM_CPU1_RC_EN")
	)
	(arc
		(start 395.862048 -117.299994)
		(mid 396.005852 -117.158311)
		(end 396.0622 -116.96446)
		(width 0.0889)
		(layer "In9.Cu")
		(net "FM_CPU1_RC_EN")
	)
	(arc
		(start 396.0622 -116.931694)
		(mid 396.146481 -116.648477)
		(end 396.357348 -116.441474)
		(width 0.0889)
		(layer "In9.Cu")
		(net "FM_CPU1_RC_EN")
	)
	(arc
		(start 396.357348 -116.441474)
		(mid 396.65275 -116.362343)
		(end 396.948152 -116.441474)
		(width 0.0889)
		(layer "In9.Cu")
		(net "FM_CPU1_RC_EN")
	)
	(arc
		(start 395.266164 -117.011196)
		(mid 395.331064 -117.178097)
		(end 395.462252 -117.299994)
		(width 0.0889)
		(layer "In9.Cu")
		(net "FM_CPU1_RC_EN")
	)
	(arc
		(start 396.948152 -116.441474)
		(mid 397.14805 -116.494973)
		(end 397.347948 -116.441474)
		(width 0.0889)
		(layer "In9.Cu")
		(net "FM_CPU1_RC_EN")
	)
	(arc
		(start 397.347948 -116.441474)
		(mid 397.64335 -116.362343)
		(end 397.938752 -116.441474)
		(width 0.0889)
		(layer "In9.Cu")
		(net "FM_CPU1_RC_EN")
	)
	(arc
		(start 398.338548 -116.441474)
		(mid 398.63395 -116.362343)
		(end 398.929352 -116.441474)
		(width 0.0889)
		(layer "In9.Cu")
		(net "FM_CPU1_RC_EN")
	)
	(arc
		(start 395.462252 -117.299994)
		(mid 395.66215 -117.353493)
		(end 395.862048 -117.299994)
		(width 0.0889)
		(layer "In9.Cu")
		(net "FM_CPU1_RC_EN")
	)
	(arc
		(start 398.929352 -116.441474)
		(mid 399.040221 -116.484945)
		(end 399.158968 -116.493798)
		(width 0.0889)
		(layer "In9.Cu")
		(net "FM_CPU1_RC_EN")
	)
	(arc
		(start 397.938752 -116.441474)
		(mid 398.13865 -116.494973)
		(end 398.338548 -116.441474)
		(width 0.0889)
		(layer "In9.Cu")
		(net "FM_CPU1_RC_EN")
	)
	(segment
		(start 377.544838 -79.894684)
		(end 377.145042 -79.494888)
		(width 0.10795)
		(layer "F.Cu")
		(net "FM_CPU0_RC_EN")
	)
	(segment
		(start 393.68095 -102.12832)
		(end 394.17625 -101.898196)
		(width 0.10795)
		(layer "F.Cu")
		(net "FM_CPU0_RC_EN")
	)
	(via
		(at 394.17625 -101.898196)
		(size 0.508)
		(drill 0.254)
		(layers "F.Cu" "B.Cu")
		(net "FM_CPU0_RC_EN")
	)
	(via
		(at 399.185892 -90.28049)
		(size 0.6604)
		(drill 0.3302)
		(layers "F.Cu" "B.Cu")
		(net "FM_CPU0_RC_EN")
	)
	(via
		(at 377.544838 -79.894684)
		(size 0.4572)
		(drill 0.2032)
		(layers "F.Cu" "B.Cu")
		(net "FM_CPU0_RC_EN")
	)
	(segment
		(start 394.21181 -99.162616)
		(end 394.21181 -99.43719)
		(width 0.10795)
		(layer "B.Cu")
		(net "FM_CPU0_RC_EN")
	)
	(segment
		(start 394.63091 -96.931226)
		(end 394.224764 -97.337372)
		(width 0.10795)
		(layer "B.Cu")
		(net "FM_CPU0_RC_EN")
	)
	(segment
		(start 400.308318 -89.7636)
		(end 399.702782 -89.7636)
		(width 0.10795)
		(layer "B.Cu")
		(net "FM_CPU0_RC_EN")
	)
	(segment
		(start 399.702782 -89.7636)
		(end 399.185892 -90.28049)
		(width 0.10795)
		(layer "B.Cu")
		(net "FM_CPU0_RC_EN")
	)
	(segment
		(start 397.969232 -93.681042)
		(end 397.024352 -93.681042)
		(width 0.10795)
		(layer "B.Cu")
		(net "FM_CPU0_RC_EN")
	)
	(segment
		(start 395.156182 -96.088962)
		(end 394.63091 -96.614234)
		(width 0.10795)
		(layer "B.Cu")
		(net "FM_CPU0_RC_EN")
	)
	(segment
		(start 393.724384 -98.259138)
		(end 393.724384 -98.67519)
		(width 0.10795)
		(layer "B.Cu")
		(net "FM_CPU0_RC_EN")
	)
	(segment
		(start 394.224764 -97.337372)
		(end 394.224764 -97.758758)
		(width 0.10795)
		(layer "B.Cu")
		(net "FM_CPU0_RC_EN")
	)
	(segment
		(start 395.156182 -95.157544)
		(end 395.156182 -96.088962)
		(width 0.10795)
		(layer "B.Cu")
		(net "FM_CPU0_RC_EN")
	)
	(segment
		(start 393.7 -99.949)
		(end 393.7 -100.457)
		(width 0.10795)
		(layer "B.Cu")
		(net "FM_CPU0_RC_EN")
	)
	(segment
		(start 399.185892 -90.28049)
		(end 398.525492 -90.94089)
		(width 0.10795)
		(layer "B.Cu")
		(net "FM_CPU0_RC_EN")
	)
	(segment
		(start 402.336 -88.2015)
		(end 401.533106 -89.004394)
		(width 0.10795)
		(layer "B.Cu")
		(net "FM_CPU0_RC_EN")
	)
	(segment
		(start 393.724384 -98.67519)
		(end 394.21181 -99.162616)
		(width 0.10795)
		(layer "B.Cu")
		(net "FM_CPU0_RC_EN")
	)
	(segment
		(start 398.525492 -90.94089)
		(end 398.525492 -93.124782)
		(width 0.10795)
		(layer "B.Cu")
		(net "FM_CPU0_RC_EN")
	)
	(segment
		(start 401.067524 -89.004394)
		(end 400.308318 -89.7636)
		(width 0.10795)
		(layer "B.Cu")
		(net "FM_CPU0_RC_EN")
	)
	(segment
		(start 398.525492 -93.124782)
		(end 397.969232 -93.681042)
		(width 0.10795)
		(layer "B.Cu")
		(net "FM_CPU0_RC_EN")
	)
	(segment
		(start 394.224764 -97.758758)
		(end 393.724384 -98.259138)
		(width 0.10795)
		(layer "B.Cu")
		(net "FM_CPU0_RC_EN")
	)
	(segment
		(start 394.21181 -99.43719)
		(end 393.7 -99.949)
		(width 0.10795)
		(layer "B.Cu")
		(net "FM_CPU0_RC_EN")
	)
	(segment
		(start 401.533106 -89.004394)
		(end 401.067524 -89.004394)
		(width 0.10795)
		(layer "B.Cu")
		(net "FM_CPU0_RC_EN")
	)
	(segment
		(start 396.434564 -94.27083)
		(end 396.042896 -94.27083)
		(width 0.10795)
		(layer "B.Cu")
		(net "FM_CPU0_RC_EN")
	)
	(segment
		(start 394.17625 -100.93325)
		(end 394.17625 -101.898196)
		(width 0.10795)
		(layer "B.Cu")
		(net "FM_CPU0_RC_EN")
	)
	(segment
		(start 396.042896 -94.27083)
		(end 395.156182 -95.157544)
		(width 0.10795)
		(layer "B.Cu")
		(net "FM_CPU0_RC_EN")
	)
	(segment
		(start 397.024352 -93.681042)
		(end 396.434564 -94.27083)
		(width 0.10795)
		(layer "B.Cu")
		(net "FM_CPU0_RC_EN")
	)
	(segment
		(start 394.63091 -96.614234)
		(end 394.63091 -96.931226)
		(width 0.10795)
		(layer "B.Cu")
		(net "FM_CPU0_RC_EN")
	)
	(segment
		(start 393.7 -100.457)
		(end 394.17625 -100.93325)
		(width 0.10795)
		(layer "B.Cu")
		(net "FM_CPU0_RC_EN")
	)
	(segment
		(start 393.91082 -100.5967)
		(end 393.03706 -100.5967)
		(width 0.089408)
		(layer "In2.Cu")
		(net "FM_CPU0_RC_EN")
	)
	(segment
		(start 377.171204 -81.007204)
		(end 377.171204 -80.512412)
		(width 0.089408)
		(layer "In2.Cu")
		(net "FM_CPU0_RC_EN")
	)
	(segment
		(start 394.17625 -100.86213)
		(end 393.91082 -100.5967)
		(width 0.089408)
		(layer "In2.Cu")
		(net "FM_CPU0_RC_EN")
	)
	(segment
		(start 394.57503 -96.71939)
		(end 394.57503 -96.581722)
		(width 0.089408)
		(layer "In2.Cu")
		(net "FM_CPU0_RC_EN")
	)
	(segment
		(start 395.07033 -97.91827)
		(end 395.07033 -97.21469)
		(width 0.089408)
		(layer "In2.Cu")
		(net "FM_CPU0_RC_EN")
	)
	(segment
		(start 394.17625 -101.898196)
		(end 394.17625 -100.86213)
		(width 0.089408)
		(layer "In2.Cu")
		(net "FM_CPU0_RC_EN")
	)
	(segment
		(start 394.208 -95.851472)
		(end 393.632436 -95.275908)
		(width 0.089408)
		(layer "In2.Cu")
		(net "FM_CPU0_RC_EN")
	)
	(segment
		(start 393.37996 -98.88982)
		(end 394.42898 -98.88982)
		(width 0.089408)
		(layer "In2.Cu")
		(net "FM_CPU0_RC_EN")
	)
	(segment
		(start 375.053098 -89.454736)
		(end 376.008138 -88.499696)
		(width 0.089408)
		(layer "In2.Cu")
		(net "FM_CPU0_RC_EN")
	)
	(segment
		(start 375.12752 -92.989654)
		(end 375.12752 -92.479622)
		(width 0.089408)
		(layer "In2.Cu")
		(net "FM_CPU0_RC_EN")
	)
	(segment
		(start 376.472704 -88.499696)
		(end 378.32792 -86.64448)
		(width 0.089408)
		(layer "In2.Cu")
		(net "FM_CPU0_RC_EN")
	)
	(segment
		(start 393.03706 -100.5967)
		(end 392.78687 -100.34651)
		(width 0.089408)
		(layer "In2.Cu")
		(net "FM_CPU0_RC_EN")
	)
	(segment
		(start 394.208 -96.214692)
		(end 394.208 -95.851472)
		(width 0.089408)
		(layer "In2.Cu")
		(net "FM_CPU0_RC_EN")
	)
	(segment
		(start 394.716 -98.6028)
		(end 394.716 -98.2726)
		(width 0.089408)
		(layer "In2.Cu")
		(net "FM_CPU0_RC_EN")
	)
	(segment
		(start 393.1412 -99.53244)
		(end 393.1412 -99.12858)
		(width 0.089408)
		(layer "In2.Cu")
		(net "FM_CPU0_RC_EN")
	)
	(segment
		(start 375.053098 -92.4052)
		(end 375.053098 -89.454736)
		(width 0.089408)
		(layer "In2.Cu")
		(net "FM_CPU0_RC_EN")
	)
	(segment
		(start 377.171204 -80.512412)
		(end 377.544838 -80.138778)
		(width 0.089408)
		(layer "In2.Cu")
		(net "FM_CPU0_RC_EN")
	)
	(segment
		(start 377.413774 -95.275908)
		(end 375.12752 -92.989654)
		(width 0.089408)
		(layer "In2.Cu")
		(net "FM_CPU0_RC_EN")
	)
	(segment
		(start 392.78687 -99.88677)
		(end 393.1412 -99.53244)
		(width 0.089408)
		(layer "In2.Cu")
		(net "FM_CPU0_RC_EN")
	)
	(segment
		(start 378.32792 -83.684872)
		(end 377.5964 -82.953352)
		(width 0.089408)
		(layer "In2.Cu")
		(net "FM_CPU0_RC_EN")
	)
	(segment
		(start 378.32792 -86.64448)
		(end 378.32792 -83.684872)
		(width 0.089408)
		(layer "In2.Cu")
		(net "FM_CPU0_RC_EN")
	)
	(segment
		(start 376.008138 -88.499696)
		(end 376.472704 -88.499696)
		(width 0.089408)
		(layer "In2.Cu")
		(net "FM_CPU0_RC_EN")
	)
	(segment
		(start 394.42898 -98.88982)
		(end 394.716 -98.6028)
		(width 0.089408)
		(layer "In2.Cu")
		(net "FM_CPU0_RC_EN")
	)
	(segment
		(start 394.716 -98.2726)
		(end 395.07033 -97.91827)
		(width 0.089408)
		(layer "In2.Cu")
		(net "FM_CPU0_RC_EN")
	)
	(segment
		(start 394.57503 -96.581722)
		(end 394.208 -96.214692)
		(width 0.089408)
		(layer "In2.Cu")
		(net "FM_CPU0_RC_EN")
	)
	(segment
		(start 375.12752 -92.479622)
		(end 375.053098 -92.4052)
		(width 0.089408)
		(layer "In2.Cu")
		(net "FM_CPU0_RC_EN")
	)
	(segment
		(start 377.544838 -80.138778)
		(end 377.544838 -79.894684)
		(width 0.089408)
		(layer "In2.Cu")
		(net "FM_CPU0_RC_EN")
	)
	(segment
		(start 393.1412 -99.12858)
		(end 393.37996 -98.88982)
		(width 0.089408)
		(layer "In2.Cu")
		(net "FM_CPU0_RC_EN")
	)
	(segment
		(start 377.5964 -81.4324)
		(end 377.171204 -81.007204)
		(width 0.089408)
		(layer "In2.Cu")
		(net "FM_CPU0_RC_EN")
	)
	(segment
		(start 392.78687 -100.34651)
		(end 392.78687 -99.88677)
		(width 0.089408)
		(layer "In2.Cu")
		(net "FM_CPU0_RC_EN")
	)
	(segment
		(start 377.5964 -82.953352)
		(end 377.5964 -81.4324)
		(width 0.089408)
		(layer "In2.Cu")
		(net "FM_CPU0_RC_EN")
	)
	(segment
		(start 395.07033 -97.21469)
		(end 394.57503 -96.71939)
		(width 0.089408)
		(layer "In2.Cu")
		(net "FM_CPU0_RC_EN")
	)
	(segment
		(start 393.632436 -95.275908)
		(end 377.413774 -95.275908)
		(width 0.089408)
		(layer "In2.Cu")
		(net "FM_CPU0_RC_EN")
	)
	(segment
		(start 412.0896 -103.0986)
		(end 412.369 -103.378)
		(width 0.10795)
		(layer "F.Cu")
		(net "FM_CPU1_RC_ERROR_N")
	)
	(segment
		(start 412.369 -103.378)
		(end 412.5468 -103.378)
		(width 0.10795)
		(layer "F.Cu")
		(net "FM_CPU1_RC_ERROR_N")
	)
	(segment
		(start 123.363228 -60.857384)
		(end 122.791728 -60.857384)
		(width 0.10795)
		(layer "F.Cu")
		(net "FM_CPU1_RC_ERROR_N")
	)
	(segment
		(start 426.285152 -27.0891)
		(end 428.237904 -25.136348)
		(width 0.10795)
		(layer "F.Cu")
		(net "FM_CPU1_RC_ERROR_N")
	)
	(segment
		(start 405.3332 -103.0986)
		(end 406.8572 -103.0986)
		(width 0.10795)
		(layer "F.Cu")
		(net "FM_CPU1_RC_ERROR_N")
	)
	(segment
		(start 412.0896 -102.6668)
		(end 412.0896 -103.0986)
		(width 0.10795)
		(layer "F.Cu")
		(net "FM_CPU1_RC_ERROR_N")
	)
	(segment
		(start 428.237904 -25.136348)
		(end 428.466504 -25.136348)
		(width 0.10795)
		(layer "F.Cu")
		(net "FM_CPU1_RC_ERROR_N")
	)
	(segment
		(start 424.058588 -27.334718)
		(end 424.304206 -27.0891)
		(width 0.10795)
		(layer "F.Cu")
		(net "FM_CPU1_RC_ERROR_N")
	)
	(segment
		(start 407.4922 -102.4636)
		(end 410.6926 -102.4636)
		(width 0.10795)
		(layer "F.Cu")
		(net "FM_CPU1_RC_ERROR_N")
	)
	(segment
		(start 406.8572 -103.0986)
		(end 407.4922 -102.4636)
		(width 0.10795)
		(layer "F.Cu")
		(net "FM_CPU1_RC_ERROR_N")
	)
	(segment
		(start 411.6578 -102.4636)
		(end 411.8864 -102.4636)
		(width 0.10795)
		(layer "F.Cu")
		(net "FM_CPU1_RC_ERROR_N")
	)
	(segment
		(start 411.8864 -102.4636)
		(end 412.0896 -102.6668)
		(width 0.10795)
		(layer "F.Cu")
		(net "FM_CPU1_RC_ERROR_N")
	)
	(segment
		(start 423.890186 -27.334718)
		(end 424.058588 -27.334718)
		(width 0.10795)
		(layer "F.Cu")
		(net "FM_CPU1_RC_ERROR_N")
	)
	(segment
		(start 411.6578 -102.4636)
		(end 410.6926 -102.4636)
		(width 0.10795)
		(layer "F.Cu")
		(net "FM_CPU1_RC_ERROR_N")
	)
	(segment
		(start 424.304206 -27.0891)
		(end 426.285152 -27.0891)
		(width 0.10795)
		(layer "F.Cu")
		(net "FM_CPU1_RC_ERROR_N")
	)
	(via
		(at 428.466504 -25.136348)
		(size 0.508)
		(drill 0.254)
		(layers "F.Cu" "B.Cu")
		(net "FM_CPU1_RC_ERROR_N")
	)
	(via
		(at 316.65037 -44.80433)
		(size 0.508)
		(drill 0.254)
		(layers "F.Cu" "B.Cu")
		(net "FM_CPU1_RC_ERROR_N")
	)
	(via
		(at 405.3332 -103.0986)
		(size 0.508)
		(drill 0.254)
		(layers "F.Cu" "B.Cu")
		(net "FM_CPU1_RC_ERROR_N")
	)
	(via
		(at 122.791728 -60.857384)
		(size 0.4826)
		(drill 0.254)
		(layers "F.Cu" "B.Cu")
		(net "FM_CPU1_RC_ERROR_N")
	)
	(via
		(at 154.808428 -31.640272)
		(size 0.508)
		(drill 0.254)
		(layers "F.Cu" "B.Cu")
		(net "FM_CPU1_RC_ERROR_N")
	)
	(via
		(at 327.09866 -39.77005)
		(size 0.508)
		(drill 0.254)
		(layers "F.Cu" "B.Cu")
		(net "FM_CPU1_RC_ERROR_N")
	)
	(via
		(at 356.11308 -42.052494)
		(size 0.508)
		(drill 0.254)
		(layers "F.Cu" "B.Cu")
		(net "FM_CPU1_RC_ERROR_N")
	)
	(via
		(at 376.54357 -31.552388)
		(size 0.508)
		(drill 0.254)
		(layers "F.Cu" "B.Cu")
		(net "FM_CPU1_RC_ERROR_N")
	)
	(segment
		(start 356.414832 -42.052494)
		(end 357.157274 -41.310052)
		(width 0.10795)
		(layer "B.Cu")
		(net "FM_CPU1_RC_ERROR_N")
	)
	(segment
		(start 356.11308 -42.052494)
		(end 356.414832 -42.052494)
		(width 0.10795)
		(layer "B.Cu")
		(net "FM_CPU1_RC_ERROR_N")
	)
	(segment
		(start 373.331232 -29.217366)
		(end 374.339104 -29.217366)
		(width 0.10795)
		(layer "B.Cu")
		(net "FM_CPU1_RC_ERROR_N")
	)
	(segment
		(start 357.157274 -41.310052)
		(end 357.157274 -39.378128)
		(width 0.10795)
		(layer "B.Cu")
		(net "FM_CPU1_RC_ERROR_N")
	)
	(segment
		(start 374.339104 -29.217366)
		(end 376.54357 -31.421832)
		(width 0.10795)
		(layer "B.Cu")
		(net "FM_CPU1_RC_ERROR_N")
	)
	(segment
		(start 371.722396 -30.826202)
		(end 373.331232 -29.217366)
		(width 0.10795)
		(layer "B.Cu")
		(net "FM_CPU1_RC_ERROR_N")
	)
	(segment
		(start 365.7092 -30.826202)
		(end 371.722396 -30.826202)
		(width 0.10795)
		(layer "B.Cu")
		(net "FM_CPU1_RC_ERROR_N")
	)
	(segment
		(start 376.54357 -31.421832)
		(end 376.54357 -31.552388)
		(width 0.10795)
		(layer "B.Cu")
		(net "FM_CPU1_RC_ERROR_N")
	)
	(segment
		(start 357.157274 -39.378128)
		(end 365.7092 -30.826202)
		(width 0.10795)
		(layer "B.Cu")
		(net "FM_CPU1_RC_ERROR_N")
	)
	(segment
		(start 332.22819 -44.516802)
		(end 331.517752 -45.22724)
		(width 0.089408)
		(layer "In2.Cu")
		(net "FM_CPU1_RC_ERROR_N")
	)
	(segment
		(start 318.0207 -45.22724)
		(end 317.59779 -44.80433)
		(width 0.089408)
		(layer "In2.Cu")
		(net "FM_CPU1_RC_ERROR_N")
	)
	(segment
		(start 327.09866 -39.77005)
		(end 330.569062 -39.77005)
		(width 0.089408)
		(layer "In2.Cu")
		(net "FM_CPU1_RC_ERROR_N")
	)
	(segment
		(start 332.22819 -42.850308)
		(end 332.22819 -44.516802)
		(width 0.089408)
		(layer "In2.Cu")
		(net "FM_CPU1_RC_ERROR_N")
	)
	(segment
		(start 331.627988 -42.550334)
		(end 331.928216 -42.550334)
		(width 0.089408)
		(layer "In2.Cu")
		(net "FM_CPU1_RC_ERROR_N")
	)
	(segment
		(start 330.569062 -39.77005)
		(end 331.093572 -40.29456)
		(width 0.089408)
		(layer "In2.Cu")
		(net "FM_CPU1_RC_ERROR_N")
	)
	(segment
		(start 331.517752 -45.22724)
		(end 318.0207 -45.22724)
		(width 0.089408)
		(layer "In2.Cu")
		(net "FM_CPU1_RC_ERROR_N")
	)
	(segment
		(start 331.928216 -42.550334)
		(end 332.22819 -42.850308)
		(width 0.089408)
		(layer "In2.Cu")
		(net "FM_CPU1_RC_ERROR_N")
	)
	(segment
		(start 331.093572 -40.29456)
		(end 331.093572 -42.015918)
		(width 0.089408)
		(layer "In2.Cu")
		(net "FM_CPU1_RC_ERROR_N")
	)
	(segment
		(start 331.093572 -42.015918)
		(end 331.627988 -42.550334)
		(width 0.089408)
		(layer "In2.Cu")
		(net "FM_CPU1_RC_ERROR_N")
	)
	(segment
		(start 317.59779 -44.80433)
		(end 316.65037 -44.80433)
		(width 0.089408)
		(layer "In2.Cu")
		(net "FM_CPU1_RC_ERROR_N")
	)
	(segment
		(start 380.2761 -27.873198)
		(end 380.2761 -27.361134)
		(width 0.089408)
		(layer "In4.Cu")
		(net "FM_CPU1_RC_ERROR_N")
	)
	(segment
		(start 427.796198 -25.806654)
		(end 428.466504 -25.136348)
		(width 0.089408)
		(layer "In4.Cu")
		(net "FM_CPU1_RC_ERROR_N")
	)
	(segment
		(start 379.681232 -28.477464)
		(end 380.22022 -27.938476)
		(width 0.089408)
		(layer "In4.Cu")
		(net "FM_CPU1_RC_ERROR_N")
	)
	(segment
		(start 124.2822 -55.5498)
		(end 125.3744 -54.4576)
		(width 0.089408)
		(layer "In4.Cu")
		(net "FM_CPU1_RC_ERROR_N")
	)
	(segment
		(start 419.852348 -24.753062)
		(end 419.852602 -24.753316)
		(width 0.089408)
		(layer "In4.Cu")
		(net "FM_CPU1_RC_ERROR_N")
	)
	(segment
		(start 385.45389 -28.72105)
		(end 386.509006 -28.72105)
		(width 0.089408)
		(layer "In4.Cu")
		(net "FM_CPU1_RC_ERROR_N")
	)
	(segment
		(start 408.134566 -26.560018)
		(end 408.823922 -26.560018)
		(width 0.089408)
		(layer "In4.Cu")
		(net "FM_CPU1_RC_ERROR_N")
	)
	(segment
		(start 423.445686 -25.53462)
		(end 424.346878 -25.53462)
		(width 0.089408)
		(layer "In4.Cu")
		(net "FM_CPU1_RC_ERROR_N")
	)
	(segment
		(start 125.3744 -54.4576)
		(end 125.7808 -54.4576)
		(width 0.089408)
		(layer "In4.Cu")
		(net "FM_CPU1_RC_ERROR_N")
	)
	(segment
		(start 151.369776 -32.094424)
		(end 154.354276 -32.094424)
		(width 0.089408)
		(layer "In4.Cu")
		(net "FM_CPU1_RC_ERROR_N")
	)
	(segment
		(start 420.918386 -25.813512)
		(end 423.166794 -25.813512)
		(width 0.089408)
		(layer "In4.Cu")
		(net "FM_CPU1_RC_ERROR_N")
	)
	(segment
		(start 416.894518 -25.677876)
		(end 417.819078 -24.753316)
		(width 0.089408)
		(layer "In4.Cu")
		(net "FM_CPU1_RC_ERROR_N")
	)
	(segment
		(start 401.215352 -27.728418)
		(end 401.215606 -27.728672)
		(width 0.089408)
		(layer "In4.Cu")
		(net "FM_CPU1_RC_ERROR_N")
	)
	(segment
		(start 404.11273 -28.0416)
		(end 404.774654 -28.703524)
		(width 0.089408)
		(layer "In4.Cu")
		(net "FM_CPU1_RC_ERROR_N")
	)
	(segment
		(start 402.120862 -27.514296)
		(end 402.648166 -28.0416)
		(width 0.089408)
		(layer "In4.Cu")
		(net "FM_CPU1_RC_ERROR_N")
	)
	(segment
		(start 424.346878 -25.53462)
		(end 424.574208 -25.76195)
		(width 0.089408)
		(layer "In4.Cu")
		(net "FM_CPU1_RC_ERROR_N")
	)
	(segment
		(start 125.7808 -54.4576)
		(end 126.365 -53.8734)
		(width 0.089408)
		(layer "In4.Cu")
		(net "FM_CPU1_RC_ERROR_N")
	)
	(segment
		(start 122.791728 -60.857384)
		(end 123.902216 -60.857384)
		(width 0.089408)
		(layer "In4.Cu")
		(net "FM_CPU1_RC_ERROR_N")
	)
	(segment
		(start 388.4676 -27.800808)
		(end 396.525496 -27.800808)
		(width 0.089408)
		(layer "In4.Cu")
		(net "FM_CPU1_RC_ERROR_N")
	)
	(segment
		(start 376.54357 -31.552388)
		(end 377.726956 -31.552388)
		(width 0.089408)
		(layer "In4.Cu")
		(net "FM_CPU1_RC_ERROR_N")
	)
	(segment
		(start 426.524166 -25.806654)
		(end 427.796198 -25.806654)
		(width 0.089408)
		(layer "In4.Cu")
		(net "FM_CPU1_RC_ERROR_N")
	)
	(segment
		(start 419.852602 -24.753316)
		(end 419.85819 -24.753316)
		(width 0.089408)
		(layer "In4.Cu")
		(net "FM_CPU1_RC_ERROR_N")
	)
	(segment
		(start 154.354276 -32.094424)
		(end 154.808428 -31.640272)
		(width 0.089408)
		(layer "In4.Cu")
		(net "FM_CPU1_RC_ERROR_N")
	)
	(segment
		(start 387.10362 -28.126436)
		(end 388.141972 -28.126436)
		(width 0.089408)
		(layer "In4.Cu")
		(net "FM_CPU1_RC_ERROR_N")
	)
	(segment
		(start 407.733754 -26.96083)
		(end 408.134566 -26.560018)
		(width 0.089408)
		(layer "In4.Cu")
		(net "FM_CPU1_RC_ERROR_N")
	)
	(segment
		(start 405.340312 -28.532328)
		(end 406.65781 -28.532328)
		(width 0.089408)
		(layer "In4.Cu")
		(net "FM_CPU1_RC_ERROR_N")
	)
	(segment
		(start 404.857712 -28.703524)
		(end 404.857966 -28.703778)
		(width 0.089408)
		(layer "In4.Cu")
		(net "FM_CPU1_RC_ERROR_N")
	)
	(segment
		(start 419.699694 -24.753316)
		(end 419.699948 -24.753062)
		(width 0.089408)
		(layer "In4.Cu")
		(net "FM_CPU1_RC_ERROR_N")
	)
	(segment
		(start 386.509006 -28.72105)
		(end 387.10362 -28.126436)
		(width 0.089408)
		(layer "In4.Cu")
		(net "FM_CPU1_RC_ERROR_N")
	)
	(segment
		(start 399.832322 -27.728672)
		(end 400.898614 -27.728672)
		(width 0.089408)
		(layer "In4.Cu")
		(net "FM_CPU1_RC_ERROR_N")
	)
	(segment
		(start 401.789138 -27.514296)
		(end 402.120862 -27.514296)
		(width 0.089408)
		(layer "In4.Cu")
		(net "FM_CPU1_RC_ERROR_N")
	)
	(segment
		(start 419.85819 -24.753316)
		(end 420.918386 -25.813512)
		(width 0.089408)
		(layer "In4.Cu")
		(net "FM_CPU1_RC_ERROR_N")
	)
	(segment
		(start 423.166794 -25.813512)
		(end 423.445686 -25.53462)
		(width 0.089408)
		(layer "In4.Cu")
		(net "FM_CPU1_RC_ERROR_N")
	)
	(segment
		(start 407.733754 -27.456384)
		(end 407.733754 -26.96083)
		(width 0.089408)
		(layer "In4.Cu")
		(net "FM_CPU1_RC_ERROR_N")
	)
	(segment
		(start 380.2761 -27.361134)
		(end 380.669546 -26.967688)
		(width 0.089408)
		(layer "In4.Cu")
		(net "FM_CPU1_RC_ERROR_N")
	)
	(segment
		(start 424.574208 -25.76195)
		(end 426.479462 -25.76195)
		(width 0.089408)
		(layer "In4.Cu")
		(net "FM_CPU1_RC_ERROR_N")
	)
	(segment
		(start 380.22022 -27.938476)
		(end 380.22022 -27.929078)
		(width 0.089408)
		(layer "In4.Cu")
		(net "FM_CPU1_RC_ERROR_N")
	)
	(segment
		(start 380.669546 -26.967688)
		(end 381.652272 -26.967688)
		(width 0.089408)
		(layer "In4.Cu")
		(net "FM_CPU1_RC_ERROR_N")
	)
	(segment
		(start 382.874774 -28.19019)
		(end 384.92303 -28.19019)
		(width 0.089408)
		(layer "In4.Cu")
		(net "FM_CPU1_RC_ERROR_N")
	)
	(segment
		(start 377.726956 -31.552388)
		(end 379.681232 -29.593286)
		(width 0.089408)
		(layer "In4.Cu")
		(net "FM_CPU1_RC_ERROR_N")
	)
	(segment
		(start 405.168862 -28.703778)
		(end 405.340312 -28.532328)
		(width 0.089408)
		(layer "In4.Cu")
		(net "FM_CPU1_RC_ERROR_N")
	)
	(segment
		(start 123.902216 -60.857384)
		(end 124.2822 -60.4774)
		(width 0.089408)
		(layer "In4.Cu")
		(net "FM_CPU1_RC_ERROR_N")
	)
	(segment
		(start 388.141972 -28.126436)
		(end 388.4676 -27.800808)
		(width 0.089408)
		(layer "In4.Cu")
		(net "FM_CPU1_RC_ERROR_N")
	)
	(segment
		(start 379.681232 -29.593286)
		(end 379.681232 -28.477464)
		(width 0.089408)
		(layer "In4.Cu")
		(net "FM_CPU1_RC_ERROR_N")
	)
	(segment
		(start 396.952216 -27.374088)
		(end 399.477738 -27.374088)
		(width 0.089408)
		(layer "In4.Cu")
		(net "FM_CPU1_RC_ERROR_N")
	)
	(segment
		(start 409.706064 -25.677876)
		(end 416.894518 -25.677876)
		(width 0.089408)
		(layer "In4.Cu")
		(net "FM_CPU1_RC_ERROR_N")
	)
	(segment
		(start 126.365 -53.8734)
		(end 126.7206 -53.8734)
		(width 0.089408)
		(layer "In4.Cu")
		(net "FM_CPU1_RC_ERROR_N")
	)
	(segment
		(start 404.774654 -28.703524)
		(end 404.857712 -28.703524)
		(width 0.089408)
		(layer "In4.Cu")
		(net "FM_CPU1_RC_ERROR_N")
	)
	(segment
		(start 408.823922 -26.560018)
		(end 409.706064 -25.677876)
		(width 0.089408)
		(layer "In4.Cu")
		(net "FM_CPU1_RC_ERROR_N")
	)
	(segment
		(start 399.477738 -27.374088)
		(end 399.832322 -27.728672)
		(width 0.089408)
		(layer "In4.Cu")
		(net "FM_CPU1_RC_ERROR_N")
	)
	(segment
		(start 124.2822 -60.4774)
		(end 124.2822 -55.5498)
		(width 0.089408)
		(layer "In4.Cu")
		(net "FM_CPU1_RC_ERROR_N")
	)
	(segment
		(start 384.92303 -28.19019)
		(end 385.45389 -28.72105)
		(width 0.089408)
		(layer "In4.Cu")
		(net "FM_CPU1_RC_ERROR_N")
	)
	(segment
		(start 396.525496 -27.800808)
		(end 396.952216 -27.374088)
		(width 0.089408)
		(layer "In4.Cu")
		(net "FM_CPU1_RC_ERROR_N")
	)
	(segment
		(start 406.65781 -28.532328)
		(end 407.733754 -27.456384)
		(width 0.089408)
		(layer "In4.Cu")
		(net "FM_CPU1_RC_ERROR_N")
	)
	(segment
		(start 404.857966 -28.703778)
		(end 405.168862 -28.703778)
		(width 0.089408)
		(layer "In4.Cu")
		(net "FM_CPU1_RC_ERROR_N")
	)
	(segment
		(start 129.1844 -51.4096)
		(end 132.0546 -51.4096)
		(width 0.089408)
		(layer "In4.Cu")
		(net "FM_CPU1_RC_ERROR_N")
	)
	(segment
		(start 419.699948 -24.753062)
		(end 419.852348 -24.753062)
		(width 0.089408)
		(layer "In4.Cu")
		(net "FM_CPU1_RC_ERROR_N")
	)
	(segment
		(start 126.7206 -53.8734)
		(end 129.1844 -51.4096)
		(width 0.089408)
		(layer "In4.Cu")
		(net "FM_CPU1_RC_ERROR_N")
	)
	(segment
		(start 380.22022 -27.929078)
		(end 380.2761 -27.873198)
		(width 0.089408)
		(layer "In4.Cu")
		(net "FM_CPU1_RC_ERROR_N")
	)
	(segment
		(start 132.0546 -51.4096)
		(end 151.369776 -32.094424)
		(width 0.089408)
		(layer "In4.Cu")
		(net "FM_CPU1_RC_ERROR_N")
	)
	(segment
		(start 381.652272 -26.967688)
		(end 382.874774 -28.19019)
		(width 0.089408)
		(layer "In4.Cu")
		(net "FM_CPU1_RC_ERROR_N")
	)
	(segment
		(start 417.819078 -24.753316)
		(end 419.699694 -24.753316)
		(width 0.089408)
		(layer "In4.Cu")
		(net "FM_CPU1_RC_ERROR_N")
	)
	(segment
		(start 400.898614 -27.728672)
		(end 400.898868 -27.728418)
		(width 0.089408)
		(layer "In4.Cu")
		(net "FM_CPU1_RC_ERROR_N")
	)
	(segment
		(start 402.648166 -28.0416)
		(end 404.11273 -28.0416)
		(width 0.089408)
		(layer "In4.Cu")
		(net "FM_CPU1_RC_ERROR_N")
	)
	(segment
		(start 401.574762 -27.728672)
		(end 401.789138 -27.514296)
		(width 0.089408)
		(layer "In4.Cu")
		(net "FM_CPU1_RC_ERROR_N")
	)
	(segment
		(start 400.898868 -27.728418)
		(end 401.215352 -27.728418)
		(width 0.089408)
		(layer "In4.Cu")
		(net "FM_CPU1_RC_ERROR_N")
	)
	(segment
		(start 401.215606 -27.728672)
		(end 401.574762 -27.728672)
		(width 0.089408)
		(layer "In4.Cu")
		(net "FM_CPU1_RC_ERROR_N")
	)
	(segment
		(start 426.479462 -25.76195)
		(end 426.524166 -25.806654)
		(width 0.089408)
		(layer "In4.Cu")
		(net "FM_CPU1_RC_ERROR_N")
	)
	(segment
		(start 221.818454 -28.734512)
		(end 223.475296 -30.391354)
		(width 0.089408)
		(layer "In9.Cu")
		(net "FM_CPU1_RC_ERROR_N")
	)
	(segment
		(start 242.847622 -29.604208)
		(end 259.513578 -29.604208)
		(width 0.089408)
		(layer "In9.Cu")
		(net "FM_CPU1_RC_ERROR_N")
	)
	(segment
		(start 264.023094 -32.54121)
		(end 303.026572 -32.54121)
		(width 0.089408)
		(layer "In9.Cu")
		(net "FM_CPU1_RC_ERROR_N")
	)
	(segment
		(start 262.396986 -30.915102)
		(end 264.023094 -32.54121)
		(width 0.089408)
		(layer "In9.Cu")
		(net "FM_CPU1_RC_ERROR_N")
	)
	(segment
		(start 316.36716 -45.08754)
		(end 316.65037 -44.80433)
		(width 0.089408)
		(layer "In9.Cu")
		(net "FM_CPU1_RC_ERROR_N")
	)
	(segment
		(start 154.808428 -31.640272)
		(end 160.208976 -31.640272)
		(width 0.089408)
		(layer "In9.Cu")
		(net "FM_CPU1_RC_ERROR_N")
	)
	(segment
		(start 259.513578 -29.604208)
		(end 260.824472 -30.915102)
		(width 0.089408)
		(layer "In9.Cu")
		(net "FM_CPU1_RC_ERROR_N")
	)
	(segment
		(start 163.114736 -28.734512)
		(end 221.818454 -28.734512)
		(width 0.089408)
		(layer "In9.Cu")
		(net "FM_CPU1_RC_ERROR_N")
	)
	(segment
		(start 160.208976 -31.640272)
		(end 163.114736 -28.734512)
		(width 0.089408)
		(layer "In9.Cu")
		(net "FM_CPU1_RC_ERROR_N")
	)
	(segment
		(start 315.572902 -45.08754)
		(end 316.36716 -45.08754)
		(width 0.089408)
		(layer "In9.Cu")
		(net "FM_CPU1_RC_ERROR_N")
	)
	(segment
		(start 223.475296 -30.391354)
		(end 242.060476 -30.391354)
		(width 0.089408)
		(layer "In9.Cu")
		(net "FM_CPU1_RC_ERROR_N")
	)
	(segment
		(start 260.824472 -30.915102)
		(end 262.396986 -30.915102)
		(width 0.089408)
		(layer "In9.Cu")
		(net "FM_CPU1_RC_ERROR_N")
	)
	(segment
		(start 303.026572 -32.54121)
		(end 315.572902 -45.08754)
		(width 0.089408)
		(layer "In9.Cu")
		(net "FM_CPU1_RC_ERROR_N")
	)
	(segment
		(start 242.060476 -30.391354)
		(end 242.847622 -29.604208)
		(width 0.089408)
		(layer "In9.Cu")
		(net "FM_CPU1_RC_ERROR_N")
	)
	(segment
		(start 404.304246 -99.859846)
		(end 404.304246 -102.069646)
		(width 0.089408)
		(layer "In11.Cu")
		(net "FM_CPU1_RC_ERROR_N")
	)
	(segment
		(start 405.109426 -92.046298)
		(end 403.851872 -93.303852)
		(width 0.089408)
		(layer "In11.Cu")
		(net "FM_CPU1_RC_ERROR_N")
	)
	(segment
		(start 382.606042 -42.615104)
		(end 382.606296 -42.61485)
		(width 0.089408)
		(layer "In11.Cu")
		(net "FM_CPU1_RC_ERROR_N")
	)
	(segment
		(start 389.61695 -51.066954)
		(end 395.456918 -56.906922)
		(width 0.089408)
		(layer "In11.Cu")
		(net "FM_CPU1_RC_ERROR_N")
	)
	(segment
		(start 380.581662 -40.646096)
		(end 380.816104 -40.880538)
		(width 0.089408)
		(layer "In11.Cu")
		(net "FM_CPU1_RC_ERROR_N")
	)
	(segment
		(start 379.349 -38.175692)
		(end 379.349 -38.363144)
		(width 0.089408)
		(layer "In11.Cu")
		(net "FM_CPU1_RC_ERROR_N")
	)
	(segment
		(start 379.46711 -39.552372)
		(end 380.560834 -40.646096)
		(width 0.089408)
		(layer "In11.Cu")
		(net "FM_CPU1_RC_ERROR_N")
	)
	(segment
		(start 336.240628 -42.5196)
		(end 335.896712 -42.175684)
		(width 0.089408)
		(layer "In11.Cu")
		(net "FM_CPU1_RC_ERROR_N")
	)
	(segment
		(start 331.770228 -39.44112)
		(end 328.193146 -39.44112)
		(width 0.089408)
		(layer "In11.Cu")
		(net "FM_CPU1_RC_ERROR_N")
	)
	(segment
		(start 400.365468 -63.661036)
		(end 400.365468 -70.211188)
		(width 0.089408)
		(layer "In11.Cu")
		(net "FM_CPU1_RC_ERROR_N")
	)
	(segment
		(start 404.304246 -102.069646)
		(end 405.3332 -103.0986)
		(width 0.089408)
		(layer "In11.Cu")
		(net "FM_CPU1_RC_ERROR_N")
	)
	(segment
		(start 356.052882 -41.992296)
		(end 354.654104 -41.992296)
		(width 0.089408)
		(layer "In11.Cu")
		(net "FM_CPU1_RC_ERROR_N")
	)
	(segment
		(start 379.63983 -38.985698)
		(end 379.636782 -38.988746)
		(width 0.089408)
		(layer "In11.Cu")
		(net "FM_CPU1_RC_ERROR_N")
	)
	(segment
		(start 398.39265 -61.688218)
		(end 400.365468 -63.661036)
		(width 0.089408)
		(layer "In11.Cu")
		(net "FM_CPU1_RC_ERROR_N")
	)
	(segment
		(start 377.81992 -34.259012)
		(end 377.81992 -34.699448)
		(width 0.089408)
		(layer "In11.Cu")
		(net "FM_CPU1_RC_ERROR_N")
	)
	(segment
		(start 380.816104 -40.880538)
		(end 380.816104 -41.212262)
		(width 0.089408)
		(layer "In11.Cu")
		(net "FM_CPU1_RC_ERROR_N")
	)
	(segment
		(start 356.11308 -42.052494)
		(end 356.052882 -41.992296)
		(width 0.089408)
		(layer "In11.Cu")
		(net "FM_CPU1_RC_ERROR_N")
	)
	(segment
		(start 381.45085 -42.615104)
		(end 382.606042 -42.615104)
		(width 0.089408)
		(layer "In11.Cu")
		(net "FM_CPU1_RC_ERROR_N")
	)
	(segment
		(start 379.58649 -37.938202)
		(end 379.349 -38.175692)
		(width 0.089408)
		(layer "In11.Cu")
		(net "FM_CPU1_RC_ERROR_N")
	)
	(segment
		(start 335.896712 -42.175684)
		(end 335.896712 -41.66489)
		(width 0.089408)
		(layer "In11.Cu")
		(net "FM_CPU1_RC_ERROR_N")
	)
	(segment
		(start 334.376014 -40.144192)
		(end 332.4733 -40.144192)
		(width 0.089408)
		(layer "In11.Cu")
		(net "FM_CPU1_RC_ERROR_N")
	)
	(segment
		(start 403.20087 -79.83982)
		(end 403.20087 -84.572348)
		(width 0.089408)
		(layer "In11.Cu")
		(net "FM_CPU1_RC_ERROR_N")
	)
	(segment
		(start 388.367016 -48.024796)
		(end 388.367016 -49.052226)
		(width 0.089408)
		(layer "In11.Cu")
		(net "FM_CPU1_RC_ERROR_N")
	)
	(segment
		(start 328.193146 -39.44112)
		(end 327.864216 -39.77005)
		(width 0.089408)
		(layer "In11.Cu")
		(net "FM_CPU1_RC_ERROR_N")
	)
	(segment
		(start 380.763526 -41.333674)
		(end 380.73457 -41.36263)
		(width 0.089408)
		(layer "In11.Cu")
		(net "FM_CPU1_RC_ERROR_N")
	)
	(segment
		(start 379.349 -38.363144)
		(end 379.63983 -38.653974)
		(width 0.089408)
		(layer "In11.Cu")
		(net "FM_CPU1_RC_ERROR_N")
	)
	(segment
		(start 389.61695 -50.30216)
		(end 389.61695 -51.066954)
		(width 0.089408)
		(layer "In11.Cu")
		(net "FM_CPU1_RC_ERROR_N")
	)
	(segment
		(start 403.851872 -99.407472)
		(end 404.304246 -99.859846)
		(width 0.089408)
		(layer "In11.Cu")
		(net "FM_CPU1_RC_ERROR_N")
	)
	(segment
		(start 380.73457 -41.36263)
		(end 380.73457 -41.898824)
		(width 0.089408)
		(layer "In11.Cu")
		(net "FM_CPU1_RC_ERROR_N")
	)
	(segment
		(start 395.456918 -56.906922)
		(end 395.456918 -60.73521)
		(width 0.089408)
		(layer "In11.Cu")
		(net "FM_CPU1_RC_ERROR_N")
	)
	(segment
		(start 379.63983 -38.653974)
		(end 379.63983 -38.985698)
		(width 0.089408)
		(layer "In11.Cu")
		(net "FM_CPU1_RC_ERROR_N")
	)
	(segment
		(start 376.305318 -33.545018)
		(end 376.608594 -33.848294)
		(width 0.089408)
		(layer "In11.Cu")
		(net "FM_CPU1_RC_ERROR_N")
	)
	(segment
		(start 396.409926 -61.688218)
		(end 398.39265 -61.688218)
		(width 0.089408)
		(layer "In11.Cu")
		(net "FM_CPU1_RC_ERROR_N")
	)
	(segment
		(start 380.763526 -41.26484)
		(end 380.763526 -41.333674)
		(width 0.089408)
		(layer "In11.Cu")
		(net "FM_CPU1_RC_ERROR_N")
	)
	(segment
		(start 401.7518 -76.14666)
		(end 401.7518 -77.2668)
		(width 0.089408)
		(layer "In11.Cu")
		(net "FM_CPU1_RC_ERROR_N")
	)
	(segment
		(start 376.54357 -31.552388)
		(end 376.305318 -31.79064)
		(width 0.089408)
		(layer "In11.Cu")
		(net "FM_CPU1_RC_ERROR_N")
	)
	(segment
		(start 405.109426 -86.480904)
		(end 405.109426 -92.046298)
		(width 0.089408)
		(layer "In11.Cu")
		(net "FM_CPU1_RC_ERROR_N")
	)
	(segment
		(start 403.20087 -84.572348)
		(end 405.109426 -86.480904)
		(width 0.089408)
		(layer "In11.Cu")
		(net "FM_CPU1_RC_ERROR_N")
	)
	(segment
		(start 402.33346 -72.17918)
		(end 402.33346 -75.565)
		(width 0.089408)
		(layer "In11.Cu")
		(net "FM_CPU1_RC_ERROR_N")
	)
	(segment
		(start 379.46711 -39.158926)
		(end 379.46711 -39.552372)
		(width 0.089408)
		(layer "In11.Cu")
		(net "FM_CPU1_RC_ERROR_N")
	)
	(segment
		(start 402.33346 -75.565)
		(end 401.7518 -76.14666)
		(width 0.089408)
		(layer "In11.Cu")
		(net "FM_CPU1_RC_ERROR_N")
	)
	(segment
		(start 376.305318 -31.79064)
		(end 376.305318 -33.545018)
		(width 0.089408)
		(layer "In11.Cu")
		(net "FM_CPU1_RC_ERROR_N")
	)
	(segment
		(start 395.456918 -60.73521)
		(end 396.409926 -61.688218)
		(width 0.089408)
		(layer "In11.Cu")
		(net "FM_CPU1_RC_ERROR_N")
	)
	(segment
		(start 400.365468 -70.211188)
		(end 402.33346 -72.17918)
		(width 0.089408)
		(layer "In11.Cu")
		(net "FM_CPU1_RC_ERROR_N")
	)
	(segment
		(start 354.654104 -41.992296)
		(end 354.1268 -42.5196)
		(width 0.089408)
		(layer "In11.Cu")
		(net "FM_CPU1_RC_ERROR_N")
	)
	(segment
		(start 327.864216 -39.77005)
		(end 327.09866 -39.77005)
		(width 0.089408)
		(layer "In11.Cu")
		(net "FM_CPU1_RC_ERROR_N")
	)
	(segment
		(start 380.816104 -41.212262)
		(end 380.763526 -41.26484)
		(width 0.089408)
		(layer "In11.Cu")
		(net "FM_CPU1_RC_ERROR_N")
	)
	(segment
		(start 402.0058 -77.5208)
		(end 402.0058 -78.64475)
		(width 0.089408)
		(layer "In11.Cu")
		(net "FM_CPU1_RC_ERROR_N")
	)
	(segment
		(start 379.636782 -38.989254)
		(end 379.46711 -39.158926)
		(width 0.089408)
		(layer "In11.Cu")
		(net "FM_CPU1_RC_ERROR_N")
	)
	(segment
		(start 380.560834 -40.646096)
		(end 380.581662 -40.646096)
		(width 0.089408)
		(layer "In11.Cu")
		(net "FM_CPU1_RC_ERROR_N")
	)
	(segment
		(start 388.367016 -49.052226)
		(end 389.61695 -50.30216)
		(width 0.089408)
		(layer "In11.Cu")
		(net "FM_CPU1_RC_ERROR_N")
	)
	(segment
		(start 354.1268 -42.5196)
		(end 336.240628 -42.5196)
		(width 0.089408)
		(layer "In11.Cu")
		(net "FM_CPU1_RC_ERROR_N")
	)
	(segment
		(start 382.95707 -42.61485)
		(end 388.367016 -48.024796)
		(width 0.089408)
		(layer "In11.Cu")
		(net "FM_CPU1_RC_ERROR_N")
	)
	(segment
		(start 402.0058 -78.64475)
		(end 403.20087 -79.83982)
		(width 0.089408)
		(layer "In11.Cu")
		(net "FM_CPU1_RC_ERROR_N")
	)
	(segment
		(start 382.606296 -42.61485)
		(end 382.95707 -42.61485)
		(width 0.089408)
		(layer "In11.Cu")
		(net "FM_CPU1_RC_ERROR_N")
	)
	(segment
		(start 332.4733 -40.144192)
		(end 331.770228 -39.44112)
		(width 0.089408)
		(layer "In11.Cu")
		(net "FM_CPU1_RC_ERROR_N")
	)
	(segment
		(start 401.7518 -77.2668)
		(end 402.0058 -77.5208)
		(width 0.089408)
		(layer "In11.Cu")
		(net "FM_CPU1_RC_ERROR_N")
	)
	(segment
		(start 377.409202 -33.848294)
		(end 377.81992 -34.259012)
		(width 0.089408)
		(layer "In11.Cu")
		(net "FM_CPU1_RC_ERROR_N")
	)
	(segment
		(start 335.896712 -41.66489)
		(end 334.376014 -40.144192)
		(width 0.089408)
		(layer "In11.Cu")
		(net "FM_CPU1_RC_ERROR_N")
	)
	(segment
		(start 379.636782 -38.988746)
		(end 379.636782 -38.989254)
		(width 0.089408)
		(layer "In11.Cu")
		(net "FM_CPU1_RC_ERROR_N")
	)
	(segment
		(start 403.851872 -93.303852)
		(end 403.851872 -99.407472)
		(width 0.089408)
		(layer "In11.Cu")
		(net "FM_CPU1_RC_ERROR_N")
	)
	(segment
		(start 377.81992 -34.699448)
		(end 379.58649 -36.466018)
		(width 0.089408)
		(layer "In11.Cu")
		(net "FM_CPU1_RC_ERROR_N")
	)
	(segment
		(start 380.73457 -41.898824)
		(end 381.45085 -42.615104)
		(width 0.089408)
		(layer "In11.Cu")
		(net "FM_CPU1_RC_ERROR_N")
	)
	(segment
		(start 376.608594 -33.848294)
		(end 377.409202 -33.848294)
		(width 0.089408)
		(layer "In11.Cu")
		(net "FM_CPU1_RC_ERROR_N")
	)
	(segment
		(start 379.58649 -36.466018)
		(end 379.58649 -37.938202)
		(width 0.089408)
		(layer "In11.Cu")
		(net "FM_CPU1_RC_ERROR_N")
	)
	(segment
		(start 422.783508 -25.86101)
		(end 422.943274 -25.86101)
		(width 0.10795)
		(layer "F.Cu")
		(net "FM_CPU0_RC_ERROR_N")
	)
	(segment
		(start 425.043346 -24.416258)
		(end 425.043346 -22.533356)
		(width 0.10795)
		(layer "F.Cu")
		(net "FM_CPU0_RC_ERROR_N")
	)
	(segment
		(start 424.39463 -25.064974)
		(end 425.043346 -24.416258)
		(width 0.10795)
		(layer "F.Cu")
		(net "FM_CPU0_RC_ERROR_N")
	)
	(segment
		(start 413.58185 -115.48745)
		(end 414.0708 -115.48745)
		(width 0.10795)
		(layer "F.Cu")
		(net "FM_CPU0_RC_ERROR_N")
	)
	(segment
		(start 413.3342 -115.230402)
		(end 413.3342 -115.2398)
		(width 0.10795)
		(layer "F.Cu")
		(net "FM_CPU0_RC_ERROR_N")
	)
	(segment
		(start 371.9576 -99.2632)
		(end 371.5258 -99.695)
		(width 0.10795)
		(layer "F.Cu")
		(net "FM_CPU0_RC_ERROR_N")
	)
	(segment
		(start 422.29024 -26.534618)
		(end 422.29024 -26.354278)
		(width 0.10795)
		(layer "F.Cu")
		(net "FM_CPU0_RC_ERROR_N")
	)
	(segment
		(start 413.3342 -115.2398)
		(end 413.58185 -115.48745)
		(width 0.10795)
		(layer "F.Cu")
		(net "FM_CPU0_RC_ERROR_N")
	)
	(segment
		(start 287.79216 -60.857384)
		(end 288.36366 -60.857384)
		(width 0.10795)
		(layer "F.Cu")
		(net "FM_CPU0_RC_ERROR_N")
	)
	(segment
		(start 425.043346 -22.533356)
		(end 425.386246 -22.190456)
		(width 0.10795)
		(layer "F.Cu")
		(net "FM_CPU0_RC_ERROR_N")
	)
	(segment
		(start 422.29024 -26.354278)
		(end 422.783508 -25.86101)
		(width 0.10795)
		(layer "F.Cu")
		(net "FM_CPU0_RC_ERROR_N")
	)
	(segment
		(start 371.5258 -99.695)
		(end 370.967 -99.695)
		(width 0.10795)
		(layer "F.Cu")
		(net "FM_CPU0_RC_ERROR_N")
	)
	(segment
		(start 425.386246 -22.190456)
		(end 425.386246 -22.1107)
		(width 0.10795)
		(layer "F.Cu")
		(net "FM_CPU0_RC_ERROR_N")
	)
	(segment
		(start 413.3342 -114.2492)
		(end 413.3342 -115.230402)
		(width 0.10795)
		(layer "F.Cu")
		(net "FM_CPU0_RC_ERROR_N")
	)
	(segment
		(start 423.73931 -25.064974)
		(end 424.39463 -25.064974)
		(width 0.10795)
		(layer "F.Cu")
		(net "FM_CPU0_RC_ERROR_N")
	)
	(segment
		(start 422.943274 -25.86101)
		(end 423.73931 -25.064974)
		(width 0.10795)
		(layer "F.Cu")
		(net "FM_CPU0_RC_ERROR_N")
	)
	(via
		(at 287.79216 -60.857384)
		(size 0.508)
		(drill 0.254)
		(layers "F.Cu" "B.Cu")
		(net "FM_CPU0_RC_ERROR_N")
	)
	(via
		(at 317.25235 -33.13684)
		(size 0.508)
		(drill 0.254)
		(layers "F.Cu" "B.Cu")
		(net "FM_CPU0_RC_ERROR_N")
	)
	(via
		(at 371.9576 -99.2632)
		(size 0.508)
		(drill 0.254)
		(layers "F.Cu" "B.Cu")
		(net "FM_CPU0_RC_ERROR_N")
	)
	(via
		(at 395.9098 -64.008)
		(size 0.508)
		(drill 0.254)
		(layers "F.Cu" "B.Cu")
		(net "FM_CPU0_RC_ERROR_N")
	)
	(via
		(at 366.9919 -61.65342)
		(size 0.508)
		(drill 0.254)
		(layers "F.Cu" "B.Cu")
		(net "FM_CPU0_RC_ERROR_N")
	)
	(via
		(at 425.386246 -22.1107)
		(size 0.508)
		(drill 0.254)
		(layers "F.Cu" "B.Cu")
		(net "FM_CPU0_RC_ERROR_N")
	)
	(via
		(at 399.449036 -25.030684)
		(size 0.508)
		(drill 0.254)
		(layers "F.Cu" "B.Cu")
		(net "FM_CPU0_RC_ERROR_N")
	)
	(via
		(at 413.268922 -65.2526)
		(size 0.508)
		(drill 0.254)
		(layers "F.Cu" "B.Cu")
		(net "FM_CPU0_RC_ERROR_N")
	)
	(via
		(at 311.624218 -52.807616)
		(size 0.508)
		(drill 0.254)
		(layers "F.Cu" "B.Cu")
		(net "FM_CPU0_RC_ERROR_N")
	)
	(via
		(at 414.0708 -115.48745)
		(size 0.508)
		(drill 0.254)
		(layers "F.Cu" "B.Cu")
		(net "FM_CPU0_RC_ERROR_N")
	)
	(segment
		(start 316.569852 -39.343076)
		(end 316.070234 -39.842694)
		(width 0.10795)
		(layer "B.Cu")
		(net "FM_CPU0_RC_ERROR_N")
	)
	(segment
		(start 312.039 -48.58258)
		(end 312.039 -52.398422)
		(width 0.10795)
		(layer "B.Cu")
		(net "FM_CPU0_RC_ERROR_N")
	)
	(segment
		(start 311.623964 -52.813458)
		(end 311.623964 -52.807616)
		(width 0.10795)
		(layer "B.Cu")
		(net "FM_CPU0_RC_ERROR_N")
	)
	(segment
		(start 311.0484 -40.33012)
		(end 311.0484 -47.59198)
		(width 0.10795)
		(layer "B.Cu")
		(net "FM_CPU0_RC_ERROR_N")
	)
	(segment
		(start 317.25235 -33.13684)
		(end 317.04534 -33.13684)
		(width 0.10795)
		(layer "B.Cu")
		(net "FM_CPU0_RC_ERROR_N")
	)
	(segment
		(start 311.535826 -39.842694)
		(end 311.0484 -40.33012)
		(width 0.10795)
		(layer "B.Cu")
		(net "FM_CPU0_RC_ERROR_N")
	)
	(segment
		(start 316.070234 -39.842694)
		(end 311.535826 -39.842694)
		(width 0.10795)
		(layer "B.Cu")
		(net "FM_CPU0_RC_ERROR_N")
	)
	(segment
		(start 311.623964 -52.807616)
		(end 311.624218 -52.807616)
		(width 0.10795)
		(layer "B.Cu")
		(net "FM_CPU0_RC_ERROR_N")
	)
	(segment
		(start 317.04534 -33.13684)
		(end 316.569852 -33.612328)
		(width 0.10795)
		(layer "B.Cu")
		(net "FM_CPU0_RC_ERROR_N")
	)
	(segment
		(start 312.039 -52.398422)
		(end 311.623964 -52.813458)
		(width 0.10795)
		(layer "B.Cu")
		(net "FM_CPU0_RC_ERROR_N")
	)
	(segment
		(start 311.0484 -47.59198)
		(end 312.039 -48.58258)
		(width 0.10795)
		(layer "B.Cu")
		(net "FM_CPU0_RC_ERROR_N")
	)
	(segment
		(start 316.569852 -33.612328)
		(end 316.569852 -39.343076)
		(width 0.10795)
		(layer "B.Cu")
		(net "FM_CPU0_RC_ERROR_N")
	)
	(segment
		(start 412.373318 -73.005442)
		(end 412.373572 -73.005696)
		(width 0.089408)
		(layer "In2.Cu")
		(net "FM_CPU0_RC_ERROR_N")
	)
	(segment
		(start 410.668978 -87.084154)
		(end 410.972 -87.387176)
		(width 0.089408)
		(layer "In2.Cu")
		(net "FM_CPU0_RC_ERROR_N")
	)
	(segment
		(start 410.972 -97.6376)
		(end 411.039056 -97.704656)
		(width 0.089408)
		(layer "In2.Cu")
		(net "FM_CPU0_RC_ERROR_N")
	)
	(segment
		(start 412.630366 -100.565966)
		(end 412.630366 -108.380276)
		(width 0.089408)
		(layer "In2.Cu")
		(net "FM_CPU0_RC_ERROR_N")
	)
	(segment
		(start 412.61284 -70.32117)
		(end 412.61284 -71.149718)
		(width 0.089408)
		(layer "In2.Cu")
		(net "FM_CPU0_RC_ERROR_N")
	)
	(segment
		(start 413.268922 -65.513458)
		(end 412.221172 -66.561208)
		(width 0.089408)
		(layer "In2.Cu")
		(net "FM_CPU0_RC_ERROR_N")
	)
	(segment
		(start 413.52089 -77.13091)
		(end 413.52089 -77.922882)
		(width 0.089408)
		(layer "In2.Cu")
		(net "FM_CPU0_RC_ERROR_N")
	)
	(segment
		(start 412.373572 -71.79818)
		(end 412.373572 -72.8472)
		(width 0.089408)
		(layer "In2.Cu")
		(net "FM_CPU0_RC_ERROR_N")
	)
	(segment
		(start 410.669486 -86.76767)
		(end 410.669232 -86.767924)
		(width 0.089408)
		(layer "In2.Cu")
		(net "FM_CPU0_RC_ERROR_N")
	)
	(segment
		(start 412.61284 -71.149718)
		(end 412.612586 -71.149972)
		(width 0.089408)
		(layer "In2.Cu")
		(net "FM_CPU0_RC_ERROR_N")
	)
	(segment
		(start 410.669486 -86.223348)
		(end 410.669486 -86.76767)
		(width 0.089408)
		(layer "In2.Cu")
		(net "FM_CPU0_RC_ERROR_N")
	)
	(segment
		(start 410.668978 -86.926166)
		(end 410.668978 -87.084154)
		(width 0.089408)
		(layer "In2.Cu")
		(net "FM_CPU0_RC_ERROR_N")
	)
	(segment
		(start 411.861 -68.99148)
		(end 411.861 -69.56933)
		(width 0.089408)
		(layer "In2.Cu")
		(net "FM_CPU0_RC_ERROR_N")
	)
	(segment
		(start 412.612586 -71.149972)
		(end 412.612586 -71.40067)
		(width 0.089408)
		(layer "In2.Cu")
		(net "FM_CPU0_RC_ERROR_N")
	)
	(segment
		(start 410.669232 -86.925912)
		(end 410.668978 -86.926166)
		(width 0.089408)
		(layer "In2.Cu")
		(net "FM_CPU0_RC_ERROR_N")
	)
	(segment
		(start 412.373572 -74.257408)
		(end 413.52089 -75.404726)
		(width 0.089408)
		(layer "In2.Cu")
		(net "FM_CPU0_RC_ERROR_N")
	)
	(segment
		(start 413.3596 -109.10951)
		(end 413.3596 -114.77625)
		(width 0.089408)
		(layer "In2.Cu")
		(net "FM_CPU0_RC_ERROR_N")
	)
	(segment
		(start 410.665676 -82.564732)
		(end 410.665676 -86.219538)
		(width 0.089408)
		(layer "In2.Cu")
		(net "FM_CPU0_RC_ERROR_N")
	)
	(segment
		(start 413.521144 -75.916536)
		(end 413.521144 -77.130656)
		(width 0.089408)
		(layer "In2.Cu")
		(net "FM_CPU0_RC_ERROR_N")
	)
	(segment
		(start 412.612586 -71.40067)
		(end 412.373318 -71.639938)
		(width 0.089408)
		(layer "In2.Cu")
		(net "FM_CPU0_RC_ERROR_N")
	)
	(segment
		(start 412.373318 -71.639938)
		(end 412.373318 -71.797926)
		(width 0.089408)
		(layer "In2.Cu")
		(net "FM_CPU0_RC_ERROR_N")
	)
	(segment
		(start 412.221172 -66.561208)
		(end 412.221172 -68.631308)
		(width 0.089408)
		(layer "In2.Cu")
		(net "FM_CPU0_RC_ERROR_N")
	)
	(segment
		(start 413.521144 -77.923136)
		(end 413.521144 -78.787752)
		(width 0.089408)
		(layer "In2.Cu")
		(net "FM_CPU0_RC_ERROR_N")
	)
	(segment
		(start 413.52089 -78.788006)
		(end 413.52089 -79.421482)
		(width 0.089408)
		(layer "In2.Cu")
		(net "FM_CPU0_RC_ERROR_N")
	)
	(segment
		(start 410.669232 -86.767924)
		(end 410.669232 -86.925912)
		(width 0.089408)
		(layer "In2.Cu")
		(net "FM_CPU0_RC_ERROR_N")
	)
	(segment
		(start 413.521144 -77.130656)
		(end 413.52089 -77.13091)
		(width 0.089408)
		(layer "In2.Cu")
		(net "FM_CPU0_RC_ERROR_N")
	)
	(segment
		(start 412.221172 -68.631308)
		(end 411.861 -68.99148)
		(width 0.089408)
		(layer "In2.Cu")
		(net "FM_CPU0_RC_ERROR_N")
	)
	(segment
		(start 413.521144 -79.421736)
		(end 413.521144 -79.709264)
		(width 0.089408)
		(layer "In2.Cu")
		(net "FM_CPU0_RC_ERROR_N")
	)
	(segment
		(start 413.52089 -75.916282)
		(end 413.521144 -75.916536)
		(width 0.089408)
		(layer "In2.Cu")
		(net "FM_CPU0_RC_ERROR_N")
	)
	(segment
		(start 413.52089 -77.922882)
		(end 413.521144 -77.923136)
		(width 0.089408)
		(layer "In2.Cu")
		(net "FM_CPU0_RC_ERROR_N")
	)
	(segment
		(start 412.630366 -108.380276)
		(end 413.3596 -109.10951)
		(width 0.089408)
		(layer "In2.Cu")
		(net "FM_CPU0_RC_ERROR_N")
	)
	(segment
		(start 411.039056 -97.704656)
		(end 411.039056 -98.974656)
		(width 0.089408)
		(layer "In2.Cu")
		(net "FM_CPU0_RC_ERROR_N")
	)
	(segment
		(start 410.972 -87.387176)
		(end 410.972 -97.6376)
		(width 0.089408)
		(layer "In2.Cu")
		(net "FM_CPU0_RC_ERROR_N")
	)
	(segment
		(start 413.52089 -79.421482)
		(end 413.521144 -79.421736)
		(width 0.089408)
		(layer "In2.Cu")
		(net "FM_CPU0_RC_ERROR_N")
	)
	(segment
		(start 413.52089 -75.404726)
		(end 413.52089 -75.916282)
		(width 0.089408)
		(layer "In2.Cu")
		(net "FM_CPU0_RC_ERROR_N")
	)
	(segment
		(start 413.521144 -79.709264)
		(end 410.665676 -82.564732)
		(width 0.089408)
		(layer "In2.Cu")
		(net "FM_CPU0_RC_ERROR_N")
	)
	(segment
		(start 413.268922 -65.2526)
		(end 413.268922 -65.513458)
		(width 0.089408)
		(layer "In2.Cu")
		(net "FM_CPU0_RC_ERROR_N")
	)
	(segment
		(start 411.039056 -98.974656)
		(end 412.630366 -100.565966)
		(width 0.089408)
		(layer "In2.Cu")
		(net "FM_CPU0_RC_ERROR_N")
	)
	(segment
		(start 413.521144 -78.787752)
		(end 413.52089 -78.788006)
		(width 0.089408)
		(layer "In2.Cu")
		(net "FM_CPU0_RC_ERROR_N")
	)
	(segment
		(start 412.373572 -72.8472)
		(end 412.373318 -72.847454)
		(width 0.089408)
		(layer "In2.Cu")
		(net "FM_CPU0_RC_ERROR_N")
	)
	(segment
		(start 412.373318 -71.797926)
		(end 412.373572 -71.79818)
		(width 0.089408)
		(layer "In2.Cu")
		(net "FM_CPU0_RC_ERROR_N")
	)
	(segment
		(start 412.373572 -73.005696)
		(end 412.373572 -74.257408)
		(width 0.089408)
		(layer "In2.Cu")
		(net "FM_CPU0_RC_ERROR_N")
	)
	(segment
		(start 413.3596 -114.77625)
		(end 414.0708 -115.48745)
		(width 0.089408)
		(layer "In2.Cu")
		(net "FM_CPU0_RC_ERROR_N")
	)
	(segment
		(start 411.861 -69.56933)
		(end 412.61284 -70.32117)
		(width 0.089408)
		(layer "In2.Cu")
		(net "FM_CPU0_RC_ERROR_N")
	)
	(segment
		(start 412.373318 -72.847454)
		(end 412.373318 -73.005442)
		(width 0.089408)
		(layer "In2.Cu")
		(net "FM_CPU0_RC_ERROR_N")
	)
	(segment
		(start 410.665676 -86.219538)
		(end 410.669486 -86.223348)
		(width 0.089408)
		(layer "In2.Cu")
		(net "FM_CPU0_RC_ERROR_N")
	)
	(segment
		(start 375.04624 -60.8965)
		(end 375.39676 -61.24702)
		(width 0.089408)
		(layer "In4.Cu")
		(net "FM_CPU0_RC_ERROR_N")
	)
	(segment
		(start 292.676326 -52.874672)
		(end 292.293802 -52.874672)
		(width 0.089408)
		(layer "In4.Cu")
		(net "FM_CPU0_RC_ERROR_N")
	)
	(segment
		(start 405.531066 -25.7556)
		(end 406.92197 -24.364696)
		(width 0.089408)
		(layer "In4.Cu")
		(net "FM_CPU0_RC_ERROR_N")
	)
	(segment
		(start 386.2705 -60.32246)
		(end 386.9055 -60.95746)
		(width 0.089408)
		(layer "In4.Cu")
		(net "FM_CPU0_RC_ERROR_N")
	)
	(segment
		(start 407.25344 -63.02756)
		(end 407.25344 -64.39662)
		(width 0.089408)
		(layer "In4.Cu")
		(net "FM_CPU0_RC_ERROR_N")
	)
	(segment
		(start 411.709362 -64.30391)
		(end 411.714188 -64.308736)
		(width 0.089408)
		(layer "In4.Cu")
		(net "FM_CPU0_RC_ERROR_N")
	)
	(segment
		(start 291.807392 -53.895498)
		(end 291.290502 -53.895498)
		(width 0.089408)
		(layer "In4.Cu")
		(net "FM_CPU0_RC_ERROR_N")
	)
	(segment
		(start 421.708834 -21.024088)
		(end 422.249346 -21.5646)
		(width 0.089408)
		(layer "In4.Cu")
		(net "FM_CPU0_RC_ERROR_N")
	)
	(segment
		(start 399.890996 -62.162436)
		(end 406.388316 -62.162436)
		(width 0.089408)
		(layer "In4.Cu")
		(net "FM_CPU0_RC_ERROR_N")
	)
	(segment
		(start 392.46048 -60.65266)
		(end 392.66622 -60.44692)
		(width 0.089408)
		(layer "In4.Cu")
		(net "FM_CPU0_RC_ERROR_N")
	)
	(segment
		(start 290.703 -54.483)
		(end 289.941 -54.483)
		(width 0.089408)
		(layer "In4.Cu")
		(net "FM_CPU0_RC_ERROR_N")
	)
	(segment
		(start 409.59532 -65.17386)
		(end 410.46527 -64.30391)
		(width 0.089408)
		(layer "In4.Cu")
		(net "FM_CPU0_RC_ERROR_N")
	)
	(segment
		(start 296.7863 -50.8889)
		(end 294.662098 -50.8889)
		(width 0.089408)
		(layer "In4.Cu")
		(net "FM_CPU0_RC_ERROR_N")
	)
	(segment
		(start 397.69796 -63.715646)
		(end 397.69796 -63.92164)
		(width 0.089408)
		(layer "In4.Cu")
		(net "FM_CPU0_RC_ERROR_N")
	)
	(segment
		(start 398.1196 -64.34328)
		(end 398.756886 -64.34328)
		(width 0.089408)
		(layer "In4.Cu")
		(net "FM_CPU0_RC_ERROR_N")
	)
	(segment
		(start 298.609766 -49.987454)
		(end 297.687746 -49.987454)
		(width 0.089408)
		(layer "In4.Cu")
		(net "FM_CPU0_RC_ERROR_N")
	)
	(segment
		(start 399.693384 -64.1858)
		(end 400.811238 -65.303654)
		(width 0.089408)
		(layer "In4.Cu")
		(net "FM_CPU0_RC_ERROR_N")
	)
	(segment
		(start 292.293802 -52.874672)
		(end 292.1254 -53.043074)
		(width 0.089408)
		(layer "In4.Cu")
		(net "FM_CPU0_RC_ERROR_N")
	)
	(segment
		(start 382.34112 -61.42736)
		(end 383.44602 -60.32246)
		(width 0.089408)
		(layer "In4.Cu")
		(net "FM_CPU0_RC_ERROR_N")
	)
	(segment
		(start 380.7841 -61.42736)
		(end 382.34112 -61.42736)
		(width 0.089408)
		(layer "In4.Cu")
		(net "FM_CPU0_RC_ERROR_N")
	)
	(segment
		(start 393.93114 -60.44692)
		(end 394.556996 -61.072776)
		(width 0.089408)
		(layer "In4.Cu")
		(net "FM_CPU0_RC_ERROR_N")
	)
	(segment
		(start 378.32538 -61.90996)
		(end 380.3015 -61.90996)
		(width 0.089408)
		(layer "In4.Cu")
		(net "FM_CPU0_RC_ERROR_N")
	)
	(segment
		(start 411.714188 -64.308736)
		(end 411.714696 -64.308736)
		(width 0.089408)
		(layer "In4.Cu")
		(net "FM_CPU0_RC_ERROR_N")
	)
	(segment
		(start 412.929324 -22.592538)
		(end 413.91967 -21.602192)
		(width 0.089408)
		(layer "In4.Cu")
		(net "FM_CPU0_RC_ERROR_N")
	)
	(segment
		(start 408.03068 -65.17386)
		(end 409.59532 -65.17386)
		(width 0.089408)
		(layer "In4.Cu")
		(net "FM_CPU0_RC_ERROR_N")
	)
	(segment
		(start 383.44602 -60.32246)
		(end 386.2705 -60.32246)
		(width 0.089408)
		(layer "In4.Cu")
		(net "FM_CPU0_RC_ERROR_N")
	)
	(segment
		(start 407.147014 -65.532254)
		(end 407.561288 -65.946528)
		(width 0.089408)
		(layer "In4.Cu")
		(net "FM_CPU0_RC_ERROR_N")
	)
	(segment
		(start 407.594308 -24.2443)
		(end 408.21356 -24.2443)
		(width 0.089408)
		(layer "In4.Cu")
		(net "FM_CPU0_RC_ERROR_N")
	)
	(segment
		(start 422.249346 -21.5646)
		(end 424.840146 -21.5646)
		(width 0.089408)
		(layer "In4.Cu")
		(net "FM_CPU0_RC_ERROR_N")
	)
	(segment
		(start 399.449036 -25.030684)
		(end 399.545048 -25.126696)
		(width 0.089408)
		(layer "In4.Cu")
		(net "FM_CPU0_RC_ERROR_N")
	)
	(segment
		(start 404.146766 -25.7556)
		(end 405.531066 -25.7556)
		(width 0.089408)
		(layer "In4.Cu")
		(net "FM_CPU0_RC_ERROR_N")
	)
	(segment
		(start 407.473912 -24.364696)
		(end 407.594308 -24.2443)
		(width 0.089408)
		(layer "In4.Cu")
		(net "FM_CPU0_RC_ERROR_N")
	)
	(segment
		(start 289.179 -60.579)
		(end 288.900616 -60.857384)
		(width 0.089408)
		(layer "In4.Cu")
		(net "FM_CPU0_RC_ERROR_N")
	)
	(segment
		(start 395.9098 -63.97752)
		(end 396.57528 -63.31204)
		(width 0.089408)
		(layer "In4.Cu")
		(net "FM_CPU0_RC_ERROR_N")
	)
	(segment
		(start 377.66244 -61.24702)
		(end 378.32538 -61.90996)
		(width 0.089408)
		(layer "In4.Cu")
		(net "FM_CPU0_RC_ERROR_N")
	)
	(segment
		(start 410.46527 -64.30391)
		(end 411.709362 -64.30391)
		(width 0.089408)
		(layer "In4.Cu")
		(net "FM_CPU0_RC_ERROR_N")
	)
	(segment
		(start 317.053976 -33.13684)
		(end 316.457076 -33.73374)
		(width 0.089408)
		(layer "In4.Cu")
		(net "FM_CPU0_RC_ERROR_N")
	)
	(segment
		(start 413.91967 -21.602192)
		(end 416.983926 -21.602192)
		(width 0.089408)
		(layer "In4.Cu")
		(net "FM_CPU0_RC_ERROR_N")
	)
	(segment
		(start 409.861766 -22.592538)
		(end 412.929324 -22.592538)
		(width 0.089408)
		(layer "In4.Cu")
		(net "FM_CPU0_RC_ERROR_N")
	)
	(segment
		(start 409.250896 -23.203408)
		(end 409.861766 -22.592538)
		(width 0.089408)
		(layer "In4.Cu")
		(net "FM_CPU0_RC_ERROR_N")
	)
	(segment
		(start 390.95426 -60.95746)
		(end 391.25906 -60.65266)
		(width 0.089408)
		(layer "In4.Cu")
		(net "FM_CPU0_RC_ERROR_N")
	)
	(segment
		(start 407.561288 -65.946528)
		(end 412.411926 -65.946528)
		(width 0.089408)
		(layer "In4.Cu")
		(net "FM_CPU0_RC_ERROR_N")
	)
	(segment
		(start 406.190958 -65.532254)
		(end 407.147014 -65.532254)
		(width 0.089408)
		(layer "In4.Cu")
		(net "FM_CPU0_RC_ERROR_N")
	)
	(segment
		(start 412.65856 -65.2526)
		(end 413.105854 -65.2526)
		(width 0.089408)
		(layer "In4.Cu")
		(net "FM_CPU0_RC_ERROR_N")
	)
	(segment
		(start 406.92197 -24.364696)
		(end 407.473912 -24.364696)
		(width 0.089408)
		(layer "In4.Cu")
		(net "FM_CPU0_RC_ERROR_N")
	)
	(segment
		(start 289.179 -55.245)
		(end 289.179 -60.579)
		(width 0.089408)
		(layer "In4.Cu")
		(net "FM_CPU0_RC_ERROR_N")
	)
	(segment
		(start 394.556996 -61.072776)
		(end 398.801336 -61.072776)
		(width 0.089408)
		(layer "In4.Cu")
		(net "FM_CPU0_RC_ERROR_N")
	)
	(segment
		(start 317.25235 -33.13684)
		(end 317.053976 -33.13684)
		(width 0.089408)
		(layer "In4.Cu")
		(net "FM_CPU0_RC_ERROR_N")
	)
	(segment
		(start 398.756886 -64.34328)
		(end 398.914366 -64.1858)
		(width 0.089408)
		(layer "In4.Cu")
		(net "FM_CPU0_RC_ERROR_N")
	)
	(segment
		(start 314.86348 -33.73374)
		(end 298.609766 -49.987454)
		(width 0.089408)
		(layer "In4.Cu")
		(net "FM_CPU0_RC_ERROR_N")
	)
	(segment
		(start 366.9919 -61.65342)
		(end 367.74882 -60.8965)
		(width 0.089408)
		(layer "In4.Cu")
		(net "FM_CPU0_RC_ERROR_N")
	)
	(segment
		(start 396.57528 -63.31204)
		(end 397.294354 -63.31204)
		(width 0.089408)
		(layer "In4.Cu")
		(net "FM_CPU0_RC_ERROR_N")
	)
	(segment
		(start 386.9055 -60.95746)
		(end 390.95426 -60.95746)
		(width 0.089408)
		(layer "In4.Cu")
		(net "FM_CPU0_RC_ERROR_N")
	)
	(segment
		(start 424.840146 -21.5646)
		(end 425.386246 -22.1107)
		(width 0.089408)
		(layer "In4.Cu")
		(net "FM_CPU0_RC_ERROR_N")
	)
	(segment
		(start 399.545048 -25.126696)
		(end 403.517862 -25.126696)
		(width 0.089408)
		(layer "In4.Cu")
		(net "FM_CPU0_RC_ERROR_N")
	)
	(segment
		(start 292.1254 -53.043074)
		(end 292.1254 -53.57749)
		(width 0.089408)
		(layer "In4.Cu")
		(net "FM_CPU0_RC_ERROR_N")
	)
	(segment
		(start 403.517862 -25.126696)
		(end 404.146766 -25.7556)
		(width 0.089408)
		(layer "In4.Cu")
		(net "FM_CPU0_RC_ERROR_N")
	)
	(segment
		(start 400.811238 -65.479422)
		(end 401.879816 -66.548)
		(width 0.089408)
		(layer "In4.Cu")
		(net "FM_CPU0_RC_ERROR_N")
	)
	(segment
		(start 401.879816 -66.548)
		(end 404.843488 -66.548)
		(width 0.089408)
		(layer "In4.Cu")
		(net "FM_CPU0_RC_ERROR_N")
	)
	(segment
		(start 406.388316 -62.162436)
		(end 407.25344 -63.02756)
		(width 0.089408)
		(layer "In4.Cu")
		(net "FM_CPU0_RC_ERROR_N")
	)
	(segment
		(start 292.1254 -53.57749)
		(end 291.807392 -53.895498)
		(width 0.089408)
		(layer "In4.Cu")
		(net "FM_CPU0_RC_ERROR_N")
	)
	(segment
		(start 405.804624 -65.586864)
		(end 406.136348 -65.586864)
		(width 0.089408)
		(layer "In4.Cu")
		(net "FM_CPU0_RC_ERROR_N")
	)
	(segment
		(start 400.811238 -65.303654)
		(end 400.811238 -65.479422)
		(width 0.089408)
		(layer "In4.Cu")
		(net "FM_CPU0_RC_ERROR_N")
	)
	(segment
		(start 397.69796 -63.92164)
		(end 398.1196 -64.34328)
		(width 0.089408)
		(layer "In4.Cu")
		(net "FM_CPU0_RC_ERROR_N")
	)
	(segment
		(start 367.74882 -60.8965)
		(end 375.04624 -60.8965)
		(width 0.089408)
		(layer "In4.Cu")
		(net "FM_CPU0_RC_ERROR_N")
	)
	(segment
		(start 395.9098 -64.008)
		(end 395.9098 -63.97752)
		(width 0.089408)
		(layer "In4.Cu")
		(net "FM_CPU0_RC_ERROR_N")
	)
	(segment
		(start 398.914366 -64.1858)
		(end 399.693384 -64.1858)
		(width 0.089408)
		(layer "In4.Cu")
		(net "FM_CPU0_RC_ERROR_N")
	)
	(segment
		(start 291.290502 -53.895498)
		(end 290.703 -54.483)
		(width 0.089408)
		(layer "In4.Cu")
		(net "FM_CPU0_RC_ERROR_N")
	)
	(segment
		(start 398.801336 -61.072776)
		(end 399.890996 -62.162436)
		(width 0.089408)
		(layer "In4.Cu")
		(net "FM_CPU0_RC_ERROR_N")
	)
	(segment
		(start 417.56203 -21.024088)
		(end 421.708834 -21.024088)
		(width 0.089408)
		(layer "In4.Cu")
		(net "FM_CPU0_RC_ERROR_N")
	)
	(segment
		(start 380.3015 -61.90996)
		(end 380.7841 -61.42736)
		(width 0.089408)
		(layer "In4.Cu")
		(net "FM_CPU0_RC_ERROR_N")
	)
	(segment
		(start 413.105854 -65.2526)
		(end 413.268922 -65.2526)
		(width 0.089408)
		(layer "In4.Cu")
		(net "FM_CPU0_RC_ERROR_N")
	)
	(segment
		(start 375.39676 -61.24702)
		(end 377.66244 -61.24702)
		(width 0.089408)
		(layer "In4.Cu")
		(net "FM_CPU0_RC_ERROR_N")
	)
	(segment
		(start 397.294354 -63.31204)
		(end 397.69796 -63.715646)
		(width 0.089408)
		(layer "In4.Cu")
		(net "FM_CPU0_RC_ERROR_N")
	)
	(segment
		(start 411.714696 -64.308736)
		(end 412.65856 -65.2526)
		(width 0.089408)
		(layer "In4.Cu")
		(net "FM_CPU0_RC_ERROR_N")
	)
	(segment
		(start 407.25344 -64.39662)
		(end 408.03068 -65.17386)
		(width 0.089408)
		(layer "In4.Cu")
		(net "FM_CPU0_RC_ERROR_N")
	)
	(segment
		(start 288.900616 -60.857384)
		(end 287.79216 -60.857384)
		(width 0.089408)
		(layer "In4.Cu")
		(net "FM_CPU0_RC_ERROR_N")
	)
	(segment
		(start 404.843488 -66.548)
		(end 405.804624 -65.586864)
		(width 0.089408)
		(layer "In4.Cu")
		(net "FM_CPU0_RC_ERROR_N")
	)
	(segment
		(start 408.21356 -24.2443)
		(end 409.250896 -23.206964)
		(width 0.089408)
		(layer "In4.Cu")
		(net "FM_CPU0_RC_ERROR_N")
	)
	(segment
		(start 392.66622 -60.44692)
		(end 393.93114 -60.44692)
		(width 0.089408)
		(layer "In4.Cu")
		(net "FM_CPU0_RC_ERROR_N")
	)
	(segment
		(start 409.250896 -23.206964)
		(end 409.250896 -23.203408)
		(width 0.089408)
		(layer "In4.Cu")
		(net "FM_CPU0_RC_ERROR_N")
	)
	(segment
		(start 412.411926 -65.946528)
		(end 413.105854 -65.2526)
		(width 0.089408)
		(layer "In4.Cu")
		(net "FM_CPU0_RC_ERROR_N")
	)
	(segment
		(start 294.662098 -50.8889)
		(end 292.676326 -52.874672)
		(width 0.089408)
		(layer "In4.Cu")
		(net "FM_CPU0_RC_ERROR_N")
	)
	(segment
		(start 297.687746 -49.987454)
		(end 296.7863 -50.8889)
		(width 0.089408)
		(layer "In4.Cu")
		(net "FM_CPU0_RC_ERROR_N")
	)
	(segment
		(start 391.25906 -60.65266)
		(end 392.46048 -60.65266)
		(width 0.089408)
		(layer "In4.Cu")
		(net "FM_CPU0_RC_ERROR_N")
	)
	(segment
		(start 416.983926 -21.602192)
		(end 417.56203 -21.024088)
		(width 0.089408)
		(layer "In4.Cu")
		(net "FM_CPU0_RC_ERROR_N")
	)
	(segment
		(start 406.136348 -65.586864)
		(end 406.190958 -65.532254)
		(width 0.089408)
		(layer "In4.Cu")
		(net "FM_CPU0_RC_ERROR_N")
	)
	(segment
		(start 316.457076 -33.73374)
		(end 314.86348 -33.73374)
		(width 0.089408)
		(layer "In4.Cu")
		(net "FM_CPU0_RC_ERROR_N")
	)
	(segment
		(start 289.941 -54.483)
		(end 289.179 -55.245)
		(width 0.089408)
		(layer "In4.Cu")
		(net "FM_CPU0_RC_ERROR_N")
	)
	(segment
		(start 396.305278 -62.368684)
		(end 397.30299 -61.370972)
		(width 0.089408)
		(layer "In9.Cu")
		(net "FM_CPU0_RC_ERROR_N")
	)
	(segment
		(start 397.30299 -61.370972)
		(end 397.30299 -61.054488)
		(width 0.089408)
		(layer "In9.Cu")
		(net "FM_CPU0_RC_ERROR_N")
	)
	(segment
		(start 397.30299 -61.054488)
		(end 397.302736 -61.054234)
		(width 0.089408)
		(layer "In9.Cu")
		(net "FM_CPU0_RC_ERROR_N")
	)
	(segment
		(start 395.9098 -64.008)
		(end 396.305278 -63.612522)
		(width 0.089408)
		(layer "In9.Cu")
		(net "FM_CPU0_RC_ERROR_N")
	)
	(segment
		(start 398.850866 -31.101538)
		(end 398.438878 -30.68955)
		(width 0.089408)
		(layer "In9.Cu")
		(net "FM_CPU0_RC_ERROR_N")
	)
	(segment
		(start 397.099536 -43.679364)
		(end 397.995648 -42.783252)
		(width 0.089408)
		(layer "In9.Cu")
		(net "FM_CPU0_RC_ERROR_N")
	)
	(segment
		(start 396.328646 -45.445172)
		(end 397.099536 -44.674282)
		(width 0.089408)
		(layer "In9.Cu")
		(net "FM_CPU0_RC_ERROR_N")
	)
	(segment
		(start 396.5448 -49.404016)
		(end 396.328646 -49.187862)
		(width 0.089408)
		(layer "In9.Cu")
		(net "FM_CPU0_RC_ERROR_N")
	)
	(segment
		(start 398.364202 -26.08072)
		(end 399.414238 -25.030684)
		(width 0.089408)
		(layer "In9.Cu")
		(net "FM_CPU0_RC_ERROR_N")
	)
	(segment
		(start 397.099536 -44.674282)
		(end 397.099536 -43.679364)
		(width 0.089408)
		(layer "In9.Cu")
		(net "FM_CPU0_RC_ERROR_N")
	)
	(segment
		(start 398.850866 -36.64839)
		(end 398.850866 -31.101538)
		(width 0.089408)
		(layer "In9.Cu")
		(net "FM_CPU0_RC_ERROR_N")
	)
	(segment
		(start 398.438878 -28.63088)
		(end 398.364202 -28.556204)
		(width 0.089408)
		(layer "In9.Cu")
		(net "FM_CPU0_RC_ERROR_N")
	)
	(segment
		(start 398.364202 -28.556204)
		(end 398.364202 -26.08072)
		(width 0.089408)
		(layer "In9.Cu")
		(net "FM_CPU0_RC_ERROR_N")
	)
	(segment
		(start 396.328646 -49.187862)
		(end 396.328646 -45.445172)
		(width 0.089408)
		(layer "In9.Cu")
		(net "FM_CPU0_RC_ERROR_N")
	)
	(segment
		(start 396.5448 -58.336688)
		(end 396.5448 -49.404016)
		(width 0.089408)
		(layer "In9.Cu")
		(net "FM_CPU0_RC_ERROR_N")
	)
	(segment
		(start 397.995648 -37.503608)
		(end 398.850866 -36.64839)
		(width 0.089408)
		(layer "In9.Cu")
		(net "FM_CPU0_RC_ERROR_N")
	)
	(segment
		(start 397.302736 -59.094624)
		(end 396.5448 -58.336688)
		(width 0.089408)
		(layer "In9.Cu")
		(net "FM_CPU0_RC_ERROR_N")
	)
	(segment
		(start 396.305278 -63.612522)
		(end 396.305278 -62.368684)
		(width 0.089408)
		(layer "In9.Cu")
		(net "FM_CPU0_RC_ERROR_N")
	)
	(segment
		(start 397.995648 -42.783252)
		(end 397.995648 -37.503608)
		(width 0.089408)
		(layer "In9.Cu")
		(net "FM_CPU0_RC_ERROR_N")
	)
	(segment
		(start 397.302736 -61.054234)
		(end 397.302736 -59.094624)
		(width 0.089408)
		(layer "In9.Cu")
		(net "FM_CPU0_RC_ERROR_N")
	)
	(segment
		(start 399.414238 -25.030684)
		(end 399.449036 -25.030684)
		(width 0.089408)
		(layer "In9.Cu")
		(net "FM_CPU0_RC_ERROR_N")
	)
	(segment
		(start 398.438878 -30.68955)
		(end 398.438878 -28.63088)
		(width 0.089408)
		(layer "In9.Cu")
		(net "FM_CPU0_RC_ERROR_N")
	)
	(segment
		(start 364.448344 -60.3504)
		(end 359.214928 -55.116984)
		(width 0.089408)
		(layer "In11.Cu")
		(net "FM_CPU0_RC_ERROR_N")
	)
	(segment
		(start 368.935 -97.898966)
		(end 370.172234 -99.1362)
		(width 0.089408)
		(layer "In11.Cu")
		(net "FM_CPU0_RC_ERROR_N")
	)
	(segment
		(start 363.6518 -69.461634)
		(end 363.6518 -72.009)
		(width 0.089408)
		(layer "In11.Cu")
		(net "FM_CPU0_RC_ERROR_N")
	)
	(segment
		(start 368.681 -93.489272)
		(end 368.681 -95.7326)
		(width 0.089408)
		(layer "In11.Cu")
		(net "FM_CPU0_RC_ERROR_N")
	)
	(segment
		(start 370.172234 -99.1362)
		(end 371.8433 -99.1362)
		(width 0.089408)
		(layer "In11.Cu")
		(net "FM_CPU0_RC_ERROR_N")
	)
	(segment
		(start 354.321618 -55.39867)
		(end 352.620834 -53.697886)
		(width 0.089408)
		(layer "In11.Cu")
		(net "FM_CPU0_RC_ERROR_N")
	)
	(segment
		(start 367.61674 -64.8462)
		(end 367.875566 -64.8462)
		(width 0.089408)
		(layer "In11.Cu")
		(net "FM_CPU0_RC_ERROR_N")
	)
	(segment
		(start 367.875566 -64.8462)
		(end 368.319304 -65.289938)
		(width 0.089408)
		(layer "In11.Cu")
		(net "FM_CPU0_RC_ERROR_N")
	)
	(segment
		(start 311.166002 -53.265832)
		(end 311.624218 -52.807616)
		(width 0.089408)
		(layer "In11.Cu")
		(net "FM_CPU0_RC_ERROR_N")
	)
	(segment
		(start 351.078546 -53.697886)
		(end 349.111824 -55.664608)
		(width 0.089408)
		(layer "In11.Cu")
		(net "FM_CPU0_RC_ERROR_N")
	)
	(segment
		(start 366.82172 -64.05118)
		(end 367.61674 -64.8462)
		(width 0.089408)
		(layer "In11.Cu")
		(net "FM_CPU0_RC_ERROR_N")
	)
	(segment
		(start 371.8433 -99.1362)
		(end 371.9576 -99.2505)
		(width 0.089408)
		(layer "In11.Cu")
		(net "FM_CPU0_RC_ERROR_N")
	)
	(segment
		(start 359.214928 -55.116984)
		(end 355.53523 -55.116984)
		(width 0.089408)
		(layer "In11.Cu")
		(net "FM_CPU0_RC_ERROR_N")
	)
	(segment
		(start 311.166002 -54.775354)
		(end 311.166002 -53.265832)
		(width 0.089408)
		(layer "In11.Cu")
		(net "FM_CPU0_RC_ERROR_N")
	)
	(segment
		(start 368.935 -95.9866)
		(end 368.935 -97.898966)
		(width 0.089408)
		(layer "In11.Cu")
		(net "FM_CPU0_RC_ERROR_N")
	)
	(segment
		(start 365.68888 -60.3504)
		(end 364.448344 -60.3504)
		(width 0.089408)
		(layer "In11.Cu")
		(net "FM_CPU0_RC_ERROR_N")
	)
	(segment
		(start 364.851188 -83.405472)
		(end 365.5314 -84.085684)
		(width 0.089408)
		(layer "In11.Cu")
		(net "FM_CPU0_RC_ERROR_N")
	)
	(segment
		(start 365.3409 -73.6981)
		(end 365.3409 -77.361796)
		(width 0.089408)
		(layer "In11.Cu")
		(net "FM_CPU0_RC_ERROR_N")
	)
	(segment
		(start 349.111824 -55.664608)
		(end 322.618354 -55.664608)
		(width 0.089408)
		(layer "In11.Cu")
		(net "FM_CPU0_RC_ERROR_N")
	)
	(segment
		(start 366.82172 -61.8236)
		(end 366.82172 -64.05118)
		(width 0.089408)
		(layer "In11.Cu")
		(net "FM_CPU0_RC_ERROR_N")
	)
	(segment
		(start 364.851188 -79.81061)
		(end 364.851188 -83.405472)
		(width 0.089408)
		(layer "In11.Cu")
		(net "FM_CPU0_RC_ERROR_N")
	)
	(segment
		(start 368.319304 -65.621662)
		(end 367.189766 -66.7512)
		(width 0.089408)
		(layer "In11.Cu")
		(net "FM_CPU0_RC_ERROR_N")
	)
	(segment
		(start 366.9919 -61.65342)
		(end 365.68888 -60.3504)
		(width 0.089408)
		(layer "In11.Cu")
		(net "FM_CPU0_RC_ERROR_N")
	)
	(segment
		(start 355.253544 -55.39867)
		(end 354.321618 -55.39867)
		(width 0.089408)
		(layer "In11.Cu")
		(net "FM_CPU0_RC_ERROR_N")
	)
	(segment
		(start 365.5314 -90.339672)
		(end 368.681 -93.489272)
		(width 0.089408)
		(layer "In11.Cu")
		(net "FM_CPU0_RC_ERROR_N")
	)
	(segment
		(start 352.620834 -53.697886)
		(end 351.078546 -53.697886)
		(width 0.089408)
		(layer "In11.Cu")
		(net "FM_CPU0_RC_ERROR_N")
	)
	(segment
		(start 365.3409 -77.361796)
		(end 364.851188 -79.81061)
		(width 0.089408)
		(layer "In11.Cu")
		(net "FM_CPU0_RC_ERROR_N")
	)
	(segment
		(start 355.53523 -55.116984)
		(end 355.253544 -55.39867)
		(width 0.089408)
		(layer "In11.Cu")
		(net "FM_CPU0_RC_ERROR_N")
	)
	(segment
		(start 366.362234 -66.7512)
		(end 363.6518 -69.461634)
		(width 0.089408)
		(layer "In11.Cu")
		(net "FM_CPU0_RC_ERROR_N")
	)
	(segment
		(start 368.681 -95.7326)
		(end 368.935 -95.9866)
		(width 0.089408)
		(layer "In11.Cu")
		(net "FM_CPU0_RC_ERROR_N")
	)
	(segment
		(start 365.5314 -84.085684)
		(end 365.5314 -90.339672)
		(width 0.089408)
		(layer "In11.Cu")
		(net "FM_CPU0_RC_ERROR_N")
	)
	(segment
		(start 371.9576 -99.2505)
		(end 371.9576 -99.2632)
		(width 0.089408)
		(layer "In11.Cu")
		(net "FM_CPU0_RC_ERROR_N")
	)
	(segment
		(start 366.9919 -61.65342)
		(end 366.82172 -61.8236)
		(width 0.089408)
		(layer "In11.Cu")
		(net "FM_CPU0_RC_ERROR_N")
	)
	(segment
		(start 368.319304 -65.289938)
		(end 368.319304 -65.621662)
		(width 0.089408)
		(layer "In11.Cu")
		(net "FM_CPU0_RC_ERROR_N")
	)
	(segment
		(start 367.189766 -66.7512)
		(end 366.362234 -66.7512)
		(width 0.089408)
		(layer "In11.Cu")
		(net "FM_CPU0_RC_ERROR_N")
	)
	(segment
		(start 363.6518 -72.009)
		(end 365.3409 -73.6981)
		(width 0.089408)
		(layer "In11.Cu")
		(net "FM_CPU0_RC_ERROR_N")
	)
	(segment
		(start 316.03569 -59.645042)
		(end 311.166002 -54.775354)
		(width 0.089408)
		(layer "In11.Cu")
		(net "FM_CPU0_RC_ERROR_N")
	)
	(segment
		(start 322.618354 -55.664608)
		(end 318.63792 -59.645042)
		(width 0.089408)
		(layer "In11.Cu")
		(net "FM_CPU0_RC_ERROR_N")
	)
	(segment
		(start 318.63792 -59.645042)
		(end 316.03569 -59.645042)
		(width 0.089408)
		(layer "In11.Cu")
		(net "FM_CPU0_RC_ERROR_N")
	)
	(segment
		(start 156.6926 -62.07379)
		(end 156.6926 -61.534802)
		(width 0.127)
		(layer "F.Cu")
		(net "VSENSE_P1V8MCP_CPU1_SKT_VSEN")
	)
	(segment
		(start 148.9456 -57.7088)
		(end 148.9456 -47.6504)
		(width 0.127)
		(layer "F.Cu")
		(net "VSENSE_P1V8MCP_CPU1_SKT_VSEN")
	)
	(segment
		(start 125.080268 -65.810384)
		(end 125.651768 -65.810384)
		(width 0.1016)
		(layer "F.Cu")
		(net "VSENSE_P1V8MCP_CPU1_SKT_VSEN")
	)
	(segment
		(start 154.466798 -59.309)
		(end 150.5458 -59.309)
		(width 0.127)
		(layer "F.Cu")
		(net "VSENSE_P1V8MCP_CPU1_SKT_VSEN")
	)
	(segment
		(start 156.21 -40.386)
		(end 164.2364 -40.386)
		(width 0.127)
		(layer "F.Cu")
		(net "VSENSE_P1V8MCP_CPU1_SKT_VSEN")
	)
	(segment
		(start 156.071824 -62.218824)
		(end 156.547566 -62.218824)
		(width 0.127)
		(layer "F.Cu")
		(net "VSENSE_P1V8MCP_CPU1_SKT_VSEN")
	)
	(segment
		(start 156.6926 -61.534802)
		(end 154.466798 -59.309)
		(width 0.127)
		(layer "F.Cu")
		(net "VSENSE_P1V8MCP_CPU1_SKT_VSEN")
	)
	(segment
		(start 156.547566 -62.218824)
		(end 156.6926 -62.07379)
		(width 0.127)
		(layer "F.Cu")
		(net "VSENSE_P1V8MCP_CPU1_SKT_VSEN")
	)
	(segment
		(start 164.6174 -40.005)
		(end 164.615114 -39.99103)
		(width 0.127)
		(layer "F.Cu")
		(net "VSENSE_P1V8MCP_CPU1_SKT_VSEN")
	)
	(segment
		(start 148.9456 -47.6504)
		(end 156.21 -40.386)
		(width 0.127)
		(layer "F.Cu")
		(net "VSENSE_P1V8MCP_CPU1_SKT_VSEN")
	)
	(segment
		(start 150.5458 -59.309)
		(end 148.9456 -57.7088)
		(width 0.127)
		(layer "F.Cu")
		(net "VSENSE_P1V8MCP_CPU1_SKT_VSEN")
	)
	(segment
		(start 164.2364 -40.386)
		(end 164.6174 -40.005)
		(width 0.127)
		(layer "F.Cu")
		(net "VSENSE_P1V8MCP_CPU1_SKT_VSEN")
	)
	(via
		(at 125.651768 -65.810384)
		(size 0.508)
		(drill 0.254)
		(layers "F.Cu" "B.Cu")
		(net "VSENSE_P1V8MCP_CPU1_SKT_VSEN")
	)
	(via
		(at 156.071824 -62.218824)
		(size 0.508)
		(drill 0.254)
		(layers "F.Cu" "B.Cu")
		(net "VSENSE_P1V8MCP_CPU1_SKT_VSEN")
	)
	(segment
		(start 149.372828 -64.489076)
		(end 154.328114 -64.489076)
		(width 0.127)
		(layer "In4.Cu")
		(net "VSENSE_P1V8MCP_CPU1_SKT_VSEN")
	)
	(segment
		(start 154.328114 -64.489076)
		(end 156.071824 -62.745366)
		(width 0.127)
		(layer "In4.Cu")
		(net "VSENSE_P1V8MCP_CPU1_SKT_VSEN")
	)
	(segment
		(start 125.944884 -65.979548)
		(end 126.023624 -65.958212)
		(width 0.0889)
		(layer "In4.Cu")
		(net "VSENSE_P1V8MCP_CPU1_SKT_VSEN")
	)
	(segment
		(start 127.351028 -64.229234)
		(end 127.383794 -64.229234)
		(width 0.0889)
		(layer "In4.Cu")
		(net "VSENSE_P1V8MCP_CPU1_SKT_VSEN")
	)
	(segment
		(start 125.651768 -65.810384)
		(end 125.944884 -65.979548)
		(width 0.0889)
		(layer "In4.Cu")
		(net "VSENSE_P1V8MCP_CPU1_SKT_VSEN")
	)
	(segment
		(start 141.6304 -62.7126)
		(end 141.986 -62.662562)
		(width 0.0889)
		(layer "In4.Cu")
		(net "VSENSE_P1V8MCP_CPU1_SKT_VSEN")
	)
	(segment
		(start 141.540992 -62.851792)
		(end 141.6304 -62.7126)
		(width 0.0889)
		(layer "In4.Cu")
		(net "VSENSE_P1V8MCP_CPU1_SKT_VSEN")
	)
	(segment
		(start 156.071824 -62.745366)
		(end 156.071824 -62.218824)
		(width 0.127)
		(layer "In4.Cu")
		(net "VSENSE_P1V8MCP_CPU1_SKT_VSEN")
	)
	(segment
		(start 131.149598 -63.038736)
		(end 131.155948 -63.028068)
		(width 0.0889)
		(layer "In4.Cu")
		(net "VSENSE_P1V8MCP_CPU1_SKT_VSEN")
	)
	(segment
		(start 130.787902 -63.238634)
		(end 130.817874 -63.238634)
		(width 0.0889)
		(layer "In4.Cu")
		(net "VSENSE_P1V8MCP_CPU1_SKT_VSEN")
	)
	(segment
		(start 128.205738 -63.734188)
		(end 128.238504 -63.734188)
		(width 0.0889)
		(layer "In4.Cu")
		(net "VSENSE_P1V8MCP_CPU1_SKT_VSEN")
	)
	(segment
		(start 126.488698 -64.724788)
		(end 126.521464 -64.724788)
		(width 0.0889)
		(layer "In4.Cu")
		(net "VSENSE_P1V8MCP_CPU1_SKT_VSEN")
	)
	(segment
		(start 132.173218 -63.038482)
		(end 132.17652 -63.044324)
		(width 0.0889)
		(layer "In4.Cu")
		(net "VSENSE_P1V8MCP_CPU1_SKT_VSEN")
	)
	(segment
		(start 141.986 -62.662562)
		(end 147.546314 -62.662562)
		(width 0.127)
		(layer "In4.Cu")
		(net "VSENSE_P1V8MCP_CPU1_SKT_VSEN")
	)
	(segment
		(start 126.003304 -65.619122)
		(end 125.998478 -65.610486)
		(width 0.0889)
		(layer "In4.Cu")
		(net "VSENSE_P1V8MCP_CPU1_SKT_VSEN")
	)
	(segment
		(start 125.998478 -65.610486)
		(end 125.992128 -65.599818)
		(width 0.0889)
		(layer "In4.Cu")
		(net "VSENSE_P1V8MCP_CPU1_SKT_VSEN")
	)
	(segment
		(start 147.546314 -62.662562)
		(end 149.372828 -64.489076)
		(width 0.127)
		(layer "In4.Cu")
		(net "VSENSE_P1V8MCP_CPU1_SKT_VSEN")
	)
	(segment
		(start 141.451584 -63.038736)
		(end 141.540992 -62.851792)
		(width 0.0889)
		(layer "In4.Cu")
		(net "VSENSE_P1V8MCP_CPU1_SKT_VSEN")
	)
	(segment
		(start 129.068068 -63.238634)
		(end 129.100834 -63.238634)
		(width 0.0889)
		(layer "In4.Cu")
		(net "VSENSE_P1V8MCP_CPU1_SKT_VSEN")
	)
	(arc
		(start 131.155948 -63.028068)
		(mid 131.667505 -62.743265)
		(end 132.173218 -63.038482)
		(width 0.0889)
		(layer "In4.Cu")
		(net "VSENSE_P1V8MCP_CPU1_SKT_VSEN")
	)
	(arc
		(start 132.50291 -63.23838)
		(mid 132.518658 -63.23869)
		(end 132.534406 -63.23838)
		(width 0.0889)
		(layer "In4.Cu")
		(net "VSENSE_P1V8MCP_CPU1_SKT_VSEN")
	)
	(arc
		(start 127.383794 -64.229234)
		(mid 127.575436 -64.172068)
		(end 127.715518 -64.029336)
		(width 0.0889)
		(layer "In4.Cu")
		(net "VSENSE_P1V8MCP_CPU1_SKT_VSEN")
	)
	(arc
		(start 129.432558 -63.038736)
		(mid 129.944368 -62.743197)
		(end 130.456178 -63.038736)
		(width 0.0889)
		(layer "In4.Cu")
		(net "VSENSE_P1V8MCP_CPU1_SKT_VSEN")
	)
	(arc
		(start 140.758164 -63.038736)
		(mid 141.104874 -63.23892)
		(end 141.451584 -63.038736)
		(width 0.0889)
		(layer "In4.Cu")
		(net "VSENSE_P1V8MCP_CPU1_SKT_VSEN")
	)
	(arc
		(start 128.238504 -63.734188)
		(mid 128.432354 -63.677838)
		(end 128.574038 -63.534036)
		(width 0.0889)
		(layer "In4.Cu")
		(net "VSENSE_P1V8MCP_CPU1_SKT_VSEN")
	)
	(arc
		(start 132.866384 -63.038736)
		(mid 133.378194 -62.743197)
		(end 133.890004 -63.038736)
		(width 0.0889)
		(layer "In4.Cu")
		(net "VSENSE_P1V8MCP_CPU1_SKT_VSEN")
	)
	(arc
		(start 128.574038 -63.534036)
		(mid 128.782646 -63.322104)
		(end 129.068068 -63.238634)
		(width 0.0889)
		(layer "In4.Cu")
		(net "VSENSE_P1V8MCP_CPU1_SKT_VSEN")
	)
	(arc
		(start 132.534406 -63.23838)
		(mid 132.726181 -63.181418)
		(end 132.866384 -63.038736)
		(width 0.0889)
		(layer "In4.Cu")
		(net "VSENSE_P1V8MCP_CPU1_SKT_VSEN")
	)
	(arc
		(start 132.17652 -63.044324)
		(mid 132.315235 -63.182515)
		(end 132.50291 -63.23838)
		(width 0.0889)
		(layer "In4.Cu")
		(net "VSENSE_P1V8MCP_CPU1_SKT_VSEN")
	)
	(arc
		(start 125.992128 -65.599818)
		(mid 125.996159 -65.023636)
		(end 126.488698 -64.724788)
		(width 0.0889)
		(layer "In4.Cu")
		(net "VSENSE_P1V8MCP_CPU1_SKT_VSEN")
	)
	(arc
		(start 133.890004 -63.038736)
		(mid 134.236714 -63.23892)
		(end 134.583424 -63.038736)
		(width 0.0889)
		(layer "In4.Cu")
		(net "VSENSE_P1V8MCP_CPU1_SKT_VSEN")
	)
	(arc
		(start 135.607044 -63.038736)
		(mid 135.953754 -63.23892)
		(end 136.300464 -63.038736)
		(width 0.0889)
		(layer "In4.Cu")
		(net "VSENSE_P1V8MCP_CPU1_SKT_VSEN")
	)
	(arc
		(start 127.715518 -64.029336)
		(mid 127.922522 -63.818472)
		(end 128.205738 -63.734188)
		(width 0.0889)
		(layer "In4.Cu")
		(net "VSENSE_P1V8MCP_CPU1_SKT_VSEN")
	)
	(arc
		(start 126.521464 -64.724788)
		(mid 126.715314 -64.668438)
		(end 126.856998 -64.524636)
		(width 0.0889)
		(layer "In4.Cu")
		(net "VSENSE_P1V8MCP_CPU1_SKT_VSEN")
	)
	(arc
		(start 138.017504 -63.038736)
		(mid 138.529314 -62.743197)
		(end 139.041124 -63.038736)
		(width 0.0889)
		(layer "In4.Cu")
		(net "VSENSE_P1V8MCP_CPU1_SKT_VSEN")
	)
	(arc
		(start 126.023624 -65.958212)
		(mid 126.051194 -65.786409)
		(end 126.003304 -65.619122)
		(width 0.0889)
		(layer "In4.Cu")
		(net "VSENSE_P1V8MCP_CPU1_SKT_VSEN")
	)
	(arc
		(start 126.856998 -64.524636)
		(mid 127.065606 -64.312704)
		(end 127.351028 -64.229234)
		(width 0.0889)
		(layer "In4.Cu")
		(net "VSENSE_P1V8MCP_CPU1_SKT_VSEN")
	)
	(arc
		(start 139.734544 -63.038736)
		(mid 140.246354 -62.743197)
		(end 140.758164 -63.038736)
		(width 0.0889)
		(layer "In4.Cu")
		(net "VSENSE_P1V8MCP_CPU1_SKT_VSEN")
	)
	(arc
		(start 130.817874 -63.238634)
		(mid 131.009516 -63.181468)
		(end 131.149598 -63.038736)
		(width 0.0889)
		(layer "In4.Cu")
		(net "VSENSE_P1V8MCP_CPU1_SKT_VSEN")
	)
	(arc
		(start 130.456178 -63.038736)
		(mid 130.596257 -63.181472)
		(end 130.787902 -63.238634)
		(width 0.0889)
		(layer "In4.Cu")
		(net "VSENSE_P1V8MCP_CPU1_SKT_VSEN")
	)
	(arc
		(start 139.041124 -63.038736)
		(mid 139.387834 -63.23892)
		(end 139.734544 -63.038736)
		(width 0.0889)
		(layer "In4.Cu")
		(net "VSENSE_P1V8MCP_CPU1_SKT_VSEN")
	)
	(arc
		(start 134.583424 -63.038736)
		(mid 135.095234 -62.743197)
		(end 135.607044 -63.038736)
		(width 0.0889)
		(layer "In4.Cu")
		(net "VSENSE_P1V8MCP_CPU1_SKT_VSEN")
	)
	(arc
		(start 129.100834 -63.238634)
		(mid 129.292476 -63.181468)
		(end 129.432558 -63.038736)
		(width 0.0889)
		(layer "In4.Cu")
		(net "VSENSE_P1V8MCP_CPU1_SKT_VSEN")
	)
	(arc
		(start 136.300464 -63.038736)
		(mid 136.812274 -62.743197)
		(end 137.324084 -63.038736)
		(width 0.0889)
		(layer "In4.Cu")
		(net "VSENSE_P1V8MCP_CPU1_SKT_VSEN")
	)
	(arc
		(start 137.324084 -63.038736)
		(mid 137.670794 -63.23892)
		(end 138.017504 -63.038736)
		(width 0.0889)
		(layer "In4.Cu")
		(net "VSENSE_P1V8MCP_CPU1_SKT_VSEN")
	)
	(segment
		(start 125.938788 -66.305938)
		(end 126.510288 -66.305938)
		(width 0.1016)
		(layer "F.Cu")
		(net "VSENSE_P1V8MCP_CPU1_SKT_VRTN")
	)
	(segment
		(start 156.31541 -40.64)
		(end 165.2778 -40.64)
		(width 0.127)
		(layer "F.Cu")
		(net "VSENSE_P1V8MCP_CPU1_SKT_VRTN")
	)
	(segment
		(start 149.1996 -57.60339)
		(end 149.1996 -47.75581)
		(width 0.127)
		(layer "F.Cu")
		(net "VSENSE_P1V8MCP_CPU1_SKT_VRTN")
	)
	(segment
		(start 149.1996 -47.75581)
		(end 156.31541 -40.64)
		(width 0.127)
		(layer "F.Cu")
		(net "VSENSE_P1V8MCP_CPU1_SKT_VRTN")
	)
	(segment
		(start 150.65121 -59.055)
		(end 149.1996 -57.60339)
		(width 0.127)
		(layer "F.Cu")
		(net "VSENSE_P1V8MCP_CPU1_SKT_VRTN")
	)
	(segment
		(start 165.8874 -40.0304)
		(end 165.8874 -40.005)
		(width 0.127)
		(layer "F.Cu")
		(net "VSENSE_P1V8MCP_CPU1_SKT_VRTN")
	)
	(segment
		(start 156.9466 -62.1792)
		(end 156.9466 -61.429392)
		(width 0.127)
		(layer "F.Cu")
		(net "VSENSE_P1V8MCP_CPU1_SKT_VRTN")
	)
	(segment
		(start 156.9466 -61.429392)
		(end 154.572208 -59.055)
		(width 0.127)
		(layer "F.Cu")
		(net "VSENSE_P1V8MCP_CPU1_SKT_VRTN")
	)
	(segment
		(start 165.8874 -40.005)
		(end 165.885114 -39.99103)
		(width 0.127)
		(layer "F.Cu")
		(net "VSENSE_P1V8MCP_CPU1_SKT_VRTN")
	)
	(segment
		(start 156.6926 -62.4332)
		(end 156.9466 -62.1792)
		(width 0.127)
		(layer "F.Cu")
		(net "VSENSE_P1V8MCP_CPU1_SKT_VRTN")
	)
	(segment
		(start 156.6926 -62.8396)
		(end 156.6926 -62.4332)
		(width 0.127)
		(layer "F.Cu")
		(net "VSENSE_P1V8MCP_CPU1_SKT_VRTN")
	)
	(segment
		(start 165.2778 -40.64)
		(end 165.8874 -40.0304)
		(width 0.127)
		(layer "F.Cu")
		(net "VSENSE_P1V8MCP_CPU1_SKT_VRTN")
	)
	(segment
		(start 156.77769 -62.92469)
		(end 156.6926 -62.8396)
		(width 0.127)
		(layer "F.Cu")
		(net "VSENSE_P1V8MCP_CPU1_SKT_VRTN")
	)
	(segment
		(start 154.572208 -59.055)
		(end 150.65121 -59.055)
		(width 0.127)
		(layer "F.Cu")
		(net "VSENSE_P1V8MCP_CPU1_SKT_VRTN")
	)
	(via
		(at 126.510288 -66.305938)
		(size 0.508)
		(drill 0.254)
		(layers "F.Cu" "B.Cu")
		(net "VSENSE_P1V8MCP_CPU1_SKT_VRTN")
	)
	(via
		(at 156.77769 -62.92469)
		(size 0.508)
		(drill 0.254)
		(layers "F.Cu" "B.Cu")
		(net "VSENSE_P1V8MCP_CPU1_SKT_VRTN")
	)
	(segment
		(start 147.440904 -62.916562)
		(end 149.267418 -64.743076)
		(width 0.127)
		(layer "In4.Cu")
		(net "VSENSE_P1V8MCP_CPU1_SKT_VRTN")
	)
	(segment
		(start 126.510288 -66.305938)
		(end 126.217172 -66.136774)
		(width 0.0889)
		(layer "In4.Cu")
		(net "VSENSE_P1V8MCP_CPU1_SKT_VRTN")
	)
	(segment
		(start 141.6812 -63.0174)
		(end 141.7574 -62.9412)
		(width 0.0889)
		(layer "In4.Cu")
		(net "VSENSE_P1V8MCP_CPU1_SKT_VRTN")
	)
	(segment
		(start 149.267418 -64.743076)
		(end 154.433524 -64.743076)
		(width 0.127)
		(layer "In4.Cu")
		(net "VSENSE_P1V8MCP_CPU1_SKT_VRTN")
	)
	(segment
		(start 126.163578 -65.515236)
		(end 126.158752 -65.5066)
		(width 0.0889)
		(layer "In4.Cu")
		(net "VSENSE_P1V8MCP_CPU1_SKT_VRTN")
	)
	(segment
		(start 154.433524 -64.743076)
		(end 156.25191 -62.92469)
		(width 0.127)
		(layer "In4.Cu")
		(net "VSENSE_P1V8MCP_CPU1_SKT_VRTN")
	)
	(segment
		(start 156.25191 -62.92469)
		(end 156.77769 -62.92469)
		(width 0.127)
		(layer "In4.Cu")
		(net "VSENSE_P1V8MCP_CPU1_SKT_VRTN")
	)
	(segment
		(start 131.999736 -63.120016)
		(end 132.007864 -63.13424)
		(width 0.0889)
		(layer "In4.Cu")
		(net "VSENSE_P1V8MCP_CPU1_SKT_VRTN")
	)
	(segment
		(start 129.074672 -63.429134)
		(end 129.107438 -63.429134)
		(width 0.0889)
		(layer "In4.Cu")
		(net "VSENSE_P1V8MCP_CPU1_SKT_VRTN")
	)
	(segment
		(start 130.781298 -63.429134)
		(end 130.824478 -63.429134)
		(width 0.0889)
		(layer "In4.Cu")
		(net "VSENSE_P1V8MCP_CPU1_SKT_VRTN")
	)
	(segment
		(start 126.169928 -65.525904)
		(end 126.163578 -65.515236)
		(width 0.0889)
		(layer "In4.Cu")
		(net "VSENSE_P1V8MCP_CPU1_SKT_VRTN")
	)
	(segment
		(start 126.217172 -66.136774)
		(end 126.193296 -66.047366)
		(width 0.0889)
		(layer "In4.Cu")
		(net "VSENSE_P1V8MCP_CPU1_SKT_VRTN")
	)
	(segment
		(start 127.357632 -64.419734)
		(end 127.390398 -64.419734)
		(width 0.0889)
		(layer "In4.Cu")
		(net "VSENSE_P1V8MCP_CPU1_SKT_VRTN")
	)
	(segment
		(start 141.986 -62.916562)
		(end 147.440904 -62.916562)
		(width 0.127)
		(layer "In4.Cu")
		(net "VSENSE_P1V8MCP_CPU1_SKT_VRTN")
	)
	(segment
		(start 128.212342 -63.924688)
		(end 128.245108 -63.924688)
		(width 0.0889)
		(layer "In4.Cu")
		(net "VSENSE_P1V8MCP_CPU1_SKT_VRTN")
	)
	(segment
		(start 141.7574 -62.9412)
		(end 141.986 -62.916562)
		(width 0.0889)
		(layer "In4.Cu")
		(net "VSENSE_P1V8MCP_CPU1_SKT_VRTN")
	)
	(segment
		(start 132.519166 -63.429388)
		(end 132.519928 -63.429388)
		(width 0.0889)
		(layer "In4.Cu")
		(net "VSENSE_P1V8MCP_CPU1_SKT_VRTN")
	)
	(segment
		(start 126.495302 -64.915288)
		(end 126.528068 -64.915288)
		(width 0.0889)
		(layer "In4.Cu")
		(net "VSENSE_P1V8MCP_CPU1_SKT_VRTN")
	)
	(segment
		(start 141.616684 -63.133986)
		(end 141.6812 -63.0174)
		(width 0.0889)
		(layer "In4.Cu")
		(net "VSENSE_P1V8MCP_CPU1_SKT_VRTN")
	)
	(arc
		(start 127.880618 -64.124586)
		(mid 128.020697 -63.98185)
		(end 128.212342 -63.924688)
		(width 0.0889)
		(layer "In4.Cu")
		(net "VSENSE_P1V8MCP_CPU1_SKT_VRTN")
	)
	(arc
		(start 131.314698 -63.133986)
		(mid 131.653263 -62.933885)
		(end 131.999736 -63.120016)
		(width 0.0889)
		(layer "In4.Cu")
		(net "VSENSE_P1V8MCP_CPU1_SKT_VRTN")
	)
	(arc
		(start 126.528068 -64.915288)
		(mid 126.813492 -64.831821)
		(end 127.022098 -64.619886)
		(width 0.0889)
		(layer "In4.Cu")
		(net "VSENSE_P1V8MCP_CPU1_SKT_VRTN")
	)
	(arc
		(start 130.824478 -63.429134)
		(mid 131.107695 -63.344853)
		(end 131.314698 -63.133986)
		(width 0.0889)
		(layer "In4.Cu")
		(net "VSENSE_P1V8MCP_CPU1_SKT_VRTN")
	)
	(arc
		(start 132.519928 -63.429388)
		(mid 132.530598 -63.429232)
		(end 132.541264 -63.42888)
		(width 0.0889)
		(layer "In4.Cu")
		(net "VSENSE_P1V8MCP_CPU1_SKT_VRTN")
	)
	(arc
		(start 126.193296 -66.047366)
		(mid 126.242308 -65.783917)
		(end 126.169928 -65.525904)
		(width 0.0889)
		(layer "In4.Cu")
		(net "VSENSE_P1V8MCP_CPU1_SKT_VRTN")
	)
	(arc
		(start 138.876024 -63.133986)
		(mid 139.387834 -63.429525)
		(end 139.899644 -63.133986)
		(width 0.0889)
		(layer "In4.Cu")
		(net "VSENSE_P1V8MCP_CPU1_SKT_VRTN")
	)
	(arc
		(start 128.245108 -63.924688)
		(mid 128.530532 -63.841221)
		(end 128.739138 -63.629286)
		(width 0.0889)
		(layer "In4.Cu")
		(net "VSENSE_P1V8MCP_CPU1_SKT_VRTN")
	)
	(arc
		(start 132.541264 -63.42888)
		(mid 132.82444 -63.344723)
		(end 133.031484 -63.133986)
		(width 0.0889)
		(layer "In4.Cu")
		(net "VSENSE_P1V8MCP_CPU1_SKT_VRTN")
	)
	(arc
		(start 136.465564 -63.133986)
		(mid 136.812274 -62.933802)
		(end 137.158984 -63.133986)
		(width 0.0889)
		(layer "In4.Cu")
		(net "VSENSE_P1V8MCP_CPU1_SKT_VRTN")
	)
	(arc
		(start 133.031484 -63.133986)
		(mid 133.378194 -62.933802)
		(end 133.724904 -63.133986)
		(width 0.0889)
		(layer "In4.Cu")
		(net "VSENSE_P1V8MCP_CPU1_SKT_VRTN")
	)
	(arc
		(start 126.158752 -65.5066)
		(mid 126.162499 -65.117344)
		(end 126.495302 -64.915288)
		(width 0.0889)
		(layer "In4.Cu")
		(net "VSENSE_P1V8MCP_CPU1_SKT_VRTN")
	)
	(arc
		(start 137.158984 -63.133986)
		(mid 137.670794 -63.429525)
		(end 138.182604 -63.133986)
		(width 0.0889)
		(layer "In4.Cu")
		(net "VSENSE_P1V8MCP_CPU1_SKT_VRTN")
	)
	(arc
		(start 127.022098 -64.619886)
		(mid 127.163781 -64.476082)
		(end 127.357632 -64.419734)
		(width 0.0889)
		(layer "In4.Cu")
		(net "VSENSE_P1V8MCP_CPU1_SKT_VRTN")
	)
	(arc
		(start 138.182604 -63.133986)
		(mid 138.529314 -62.933802)
		(end 138.876024 -63.133986)
		(width 0.0889)
		(layer "In4.Cu")
		(net "VSENSE_P1V8MCP_CPU1_SKT_VRTN")
	)
	(arc
		(start 134.748524 -63.133986)
		(mid 135.095234 -62.933802)
		(end 135.441944 -63.133986)
		(width 0.0889)
		(layer "In4.Cu")
		(net "VSENSE_P1V8MCP_CPU1_SKT_VRTN")
	)
	(arc
		(start 133.724904 -63.133986)
		(mid 134.236714 -63.429525)
		(end 134.748524 -63.133986)
		(width 0.0889)
		(layer "In4.Cu")
		(net "VSENSE_P1V8MCP_CPU1_SKT_VRTN")
	)
	(arc
		(start 129.597658 -63.133986)
		(mid 129.944368 -62.933802)
		(end 130.291078 -63.133986)
		(width 0.0889)
		(layer "In4.Cu")
		(net "VSENSE_P1V8MCP_CPU1_SKT_VRTN")
	)
	(arc
		(start 130.291078 -63.133986)
		(mid 130.498082 -63.34485)
		(end 130.781298 -63.429134)
		(width 0.0889)
		(layer "In4.Cu")
		(net "VSENSE_P1V8MCP_CPU1_SKT_VRTN")
	)
	(arc
		(start 140.593064 -63.133986)
		(mid 141.104874 -63.429525)
		(end 141.616684 -63.133986)
		(width 0.0889)
		(layer "In4.Cu")
		(net "VSENSE_P1V8MCP_CPU1_SKT_VRTN")
	)
	(arc
		(start 129.107438 -63.429134)
		(mid 129.390655 -63.344853)
		(end 129.597658 -63.133986)
		(width 0.0889)
		(layer "In4.Cu")
		(net "VSENSE_P1V8MCP_CPU1_SKT_VRTN")
	)
	(arc
		(start 139.899644 -63.133986)
		(mid 140.246354 -62.933802)
		(end 140.593064 -63.133986)
		(width 0.0889)
		(layer "In4.Cu")
		(net "VSENSE_P1V8MCP_CPU1_SKT_VRTN")
	)
	(arc
		(start 128.739138 -63.629286)
		(mid 128.880821 -63.485482)
		(end 129.074672 -63.429134)
		(width 0.0889)
		(layer "In4.Cu")
		(net "VSENSE_P1V8MCP_CPU1_SKT_VRTN")
	)
	(arc
		(start 127.390398 -64.419734)
		(mid 127.673615 -64.335453)
		(end 127.880618 -64.124586)
		(width 0.0889)
		(layer "In4.Cu")
		(net "VSENSE_P1V8MCP_CPU1_SKT_VRTN")
	)
	(arc
		(start 135.441944 -63.133986)
		(mid 135.953754 -63.429525)
		(end 136.465564 -63.133986)
		(width 0.0889)
		(layer "In4.Cu")
		(net "VSENSE_P1V8MCP_CPU1_SKT_VRTN")
	)
	(arc
		(start 132.007864 -63.13424)
		(mid 132.223991 -63.350271)
		(end 132.519166 -63.429388)
		(width 0.0889)
		(layer "In4.Cu")
		(net "VSENSE_P1V8MCP_CPU1_SKT_VRTN")
	)
	(segment
		(start 176.7078 -108.025184)
		(end 176.8856 -107.847384)
		(width 0.10795)
		(layer "F.Cu")
		(net "VR_PVCCIOMCP_CPU1_XADDR1")
	)
	(segment
		(start 176.8856 -107.847384)
		(end 176.8856 -106.74985)
		(width 0.10795)
		(layer "F.Cu")
		(net "VR_PVCCIOMCP_CPU1_XADDR1")
	)
	(segment
		(start 176.045114 -110.47095)
		(end 176.7078 -109.808264)
		(width 0.10795)
		(layer "F.Cu")
		(net "VR_PVCCIOMCP_CPU1_XADDR1")
	)
	(segment
		(start 176.7078 -109.808264)
		(end 176.7078 -108.025184)
		(width 0.10795)
		(layer "F.Cu")
		(net "VR_PVCCIOMCP_CPU1_XADDR1")
	)
	(segment
		(start 401.114768 -97.127822)
		(end 400.841972 -96.855026)
		(width 0.0889)
		(layer "F.Cu")
		(net "SMB_PCH_MEZZ_LOM3_SDA")
	)
	(segment
		(start 425.0563 -67.329304)
		(end 425.0563 -72.54621)
		(width 0.10795)
		(layer "F.Cu")
		(net "SMB_PCH_MEZZ_LOM3_SDA")
	)
	(segment
		(start 402.516848 -96.74987)
		(end 402.052536 -97.214182)
		(width 0.0889)
		(layer "F.Cu")
		(net "SMB_PCH_MEZZ_LOM3_SDA")
	)
	(segment
		(start 464.939634 -59.944)
		(end 465.484464 -59.944)
		(width 0.10795)
		(layer "F.Cu")
		(net "SMB_PCH_MEZZ_LOM3_SDA")
	)
	(segment
		(start 463.750152 -57.596024)
		(end 463.750152 -58.75401)
		(width 0.10795)
		(layer "F.Cu")
		(net "SMB_PCH_MEZZ_LOM3_SDA")
	)
	(segment
		(start 411.353 -81.915)
		(end 409.575 -83.693)
		(width 0.10795)
		(layer "F.Cu")
		(net "SMB_PCH_MEZZ_LOM3_SDA")
	)
	(segment
		(start 414.860994 -78.903322)
		(end 411.849316 -81.915)
		(width 0.10795)
		(layer "F.Cu")
		(net "SMB_PCH_MEZZ_LOM3_SDA")
	)
	(segment
		(start 466.29955 -64.467486)
		(end 465.083906 -65.68313)
		(width 0.10795)
		(layer "F.Cu")
		(net "SMB_PCH_MEZZ_LOM3_SDA")
	)
	(segment
		(start 415.229548 -76.219558)
		(end 414.860994 -76.588112)
		(width 0.10795)
		(layer "F.Cu")
		(net "SMB_PCH_MEZZ_LOM3_SDA")
	)
	(segment
		(start 421.382952 -76.219558)
		(end 415.229548 -76.219558)
		(width 0.10795)
		(layer "F.Cu")
		(net "SMB_PCH_MEZZ_LOM3_SDA")
	)
	(segment
		(start 465.083906 -65.68313)
		(end 426.702474 -65.68313)
		(width 0.10795)
		(layer "F.Cu")
		(net "SMB_PCH_MEZZ_LOM3_SDA")
	)
	(segment
		(start 407.932128 -88.908128)
		(end 403.49551 -93.344746)
		(width 0.10795)
		(layer "F.Cu")
		(net "SMB_PCH_MEZZ_LOM3_SDA")
	)
	(segment
		(start 401.602702 -97.127822)
		(end 401.114768 -97.127822)
		(width 0.0889)
		(layer "F.Cu")
		(net "SMB_PCH_MEZZ_LOM3_SDA")
	)
	(segment
		(start 465.484464 -59.944)
		(end 466.29955 -60.759086)
		(width 0.10795)
		(layer "F.Cu")
		(net "SMB_PCH_MEZZ_LOM3_SDA")
	)
	(segment
		(start 414.860994 -76.588112)
		(end 414.860994 -78.903322)
		(width 0.10795)
		(layer "F.Cu")
		(net "SMB_PCH_MEZZ_LOM3_SDA")
	)
	(segment
		(start 403.49551 -95.771208)
		(end 402.516848 -96.74987)
		(width 0.10795)
		(layer "F.Cu")
		(net "SMB_PCH_MEZZ_LOM3_SDA")
	)
	(segment
		(start 463.972148 -58.976514)
		(end 464.939634 -59.944)
		(width 0.10795)
		(layer "F.Cu")
		(net "SMB_PCH_MEZZ_LOM3_SDA")
	)
	(segment
		(start 463.750152 -58.75401)
		(end 463.749898 -58.754264)
		(width 0.10795)
		(layer "F.Cu")
		(net "SMB_PCH_MEZZ_LOM3_SDA")
	)
	(segment
		(start 466.29955 -60.759086)
		(end 466.29955 -64.467486)
		(width 0.10795)
		(layer "F.Cu")
		(net "SMB_PCH_MEZZ_LOM3_SDA")
	)
	(segment
		(start 411.849316 -81.915)
		(end 411.353 -81.915)
		(width 0.10795)
		(layer "F.Cu")
		(net "SMB_PCH_MEZZ_LOM3_SDA")
	)
	(segment
		(start 426.702474 -65.68313)
		(end 425.0563 -67.329304)
		(width 0.10795)
		(layer "F.Cu")
		(net "SMB_PCH_MEZZ_LOM3_SDA")
	)
	(segment
		(start 400.841972 -96.855026)
		(end 400.465036 -96.855026)
		(width 0.0889)
		(layer "F.Cu")
		(net "SMB_PCH_MEZZ_LOM3_SDA")
	)
	(segment
		(start 409.575 -83.693)
		(end 409.575 -88.667336)
		(width 0.10795)
		(layer "F.Cu")
		(net "SMB_PCH_MEZZ_LOM3_SDA")
	)
	(segment
		(start 403.49551 -93.344746)
		(end 403.49551 -95.771208)
		(width 0.10795)
		(layer "F.Cu")
		(net "SMB_PCH_MEZZ_LOM3_SDA")
	)
	(segment
		(start 402.052536 -97.214182)
		(end 401.689062 -97.214182)
		(width 0.0889)
		(layer "F.Cu")
		(net "SMB_PCH_MEZZ_LOM3_SDA")
	)
	(segment
		(start 425.0563 -72.54621)
		(end 421.382952 -76.219558)
		(width 0.10795)
		(layer "F.Cu")
		(net "SMB_PCH_MEZZ_LOM3_SDA")
	)
	(segment
		(start 409.575 -88.667336)
		(end 409.334208 -88.908128)
		(width 0.10795)
		(layer "F.Cu")
		(net "SMB_PCH_MEZZ_LOM3_SDA")
	)
	(segment
		(start 401.689062 -97.214182)
		(end 401.602702 -97.127822)
		(width 0.0889)
		(layer "F.Cu")
		(net "SMB_PCH_MEZZ_LOM3_SDA")
	)
	(segment
		(start 463.749898 -58.754264)
		(end 463.972148 -58.976514)
		(width 0.10795)
		(layer "F.Cu")
		(net "SMB_PCH_MEZZ_LOM3_SDA")
	)
	(segment
		(start 409.334208 -88.908128)
		(end 407.932128 -88.908128)
		(width 0.10795)
		(layer "F.Cu")
		(net "SMB_PCH_MEZZ_LOM3_SDA")
	)
	(via
		(at 463.972148 -57.912)
		(size 0.6604)
		(drill 0.3302)
		(layers "F.Cu" "B.Cu")
		(net "SMB_PCH_MEZZ_LOM3_SDA")
	)
	(via
		(at 463.972148 -58.976514)
		(size 0.508)
		(drill 0.254)
		(layers "F.Cu" "B.Cu")
		(net "SMB_PCH_MEZZ_LOM3_SDA")
	)
	(segment
		(start 467.3092 -57.7088)
		(end 464.175348 -57.7088)
		(width 0.10795)
		(layer "B.Cu")
		(net "SMB_PCH_MEZZ_LOM3_SDA")
	)
	(segment
		(start 468.4014 -56.388)
		(end 467.9188 -56.8706)
		(width 0.10795)
		(layer "B.Cu")
		(net "SMB_PCH_MEZZ_LOM3_SDA")
	)
	(segment
		(start 469.138 -56.388)
		(end 468.4014 -56.388)
		(width 0.10795)
		(layer "B.Cu")
		(net "SMB_PCH_MEZZ_LOM3_SDA")
	)
	(segment
		(start 464.175348 -57.7088)
		(end 463.972148 -57.912)
		(width 0.10795)
		(layer "B.Cu")
		(net "SMB_PCH_MEZZ_LOM3_SDA")
	)
	(segment
		(start 467.9188 -57.0992)
		(end 467.3092 -57.7088)
		(width 0.10795)
		(layer "B.Cu")
		(net "SMB_PCH_MEZZ_LOM3_SDA")
	)
	(segment
		(start 463.972148 -58.976514)
		(end 463.972148 -57.912)
		(width 0.10795)
		(layer "B.Cu")
		(net "SMB_PCH_MEZZ_LOM3_SDA")
	)
	(segment
		(start 467.9188 -56.8706)
		(end 467.9188 -57.0992)
		(width 0.10795)
		(layer "B.Cu")
		(net "SMB_PCH_MEZZ_LOM3_SDA")
	)
	(segment
		(start 408.07005 -88.258142)
		(end 403.13356 -93.194632)
		(width 0.10795)
		(layer "F.Cu")
		(net "SMB_PCH_MEZZ_LOM3_SCL")
	)
	(segment
		(start 424.82135 -72.448674)
		(end 421.285416 -75.984608)
		(width 0.10795)
		(layer "F.Cu")
		(net "SMB_PCH_MEZZ_LOM3_SCL")
	)
	(segment
		(start 403.13356 -93.194632)
		(end 403.13356 -95.500952)
		(width 0.10795)
		(layer "F.Cu")
		(net "SMB_PCH_MEZZ_LOM3_SCL")
	)
	(segment
		(start 463.655664 -59.421014)
		(end 463.891376 -59.421014)
		(width 0.10795)
		(layer "F.Cu")
		(net "SMB_PCH_MEZZ_LOM3_SCL")
	)
	(segment
		(start 465.9376 -64.317372)
		(end 464.806792 -65.44818)
		(width 0.10795)
		(layer "F.Cu")
		(net "SMB_PCH_MEZZ_LOM3_SCL")
	)
	(segment
		(start 465.4042 -60.3758)
		(end 465.9376 -60.9092)
		(width 0.10795)
		(layer "F.Cu")
		(net "SMB_PCH_MEZZ_LOM3_SCL")
	)
	(segment
		(start 408.07005 -85.324696)
		(end 408.07005 -88.258142)
		(width 0.10795)
		(layer "F.Cu")
		(net "SMB_PCH_MEZZ_LOM3_SCL")
	)
	(segment
		(start 424.82135 -67.231768)
		(end 424.82135 -72.448674)
		(width 0.10795)
		(layer "F.Cu")
		(net "SMB_PCH_MEZZ_LOM3_SCL")
	)
	(segment
		(start 421.285416 -75.984608)
		(end 415.098992 -75.984608)
		(width 0.10795)
		(layer "F.Cu")
		(net "SMB_PCH_MEZZ_LOM3_SCL")
	)
	(segment
		(start 462.950052 -58.954924)
		(end 463.189574 -58.954924)
		(width 0.10795)
		(layer "F.Cu")
		(net "SMB_PCH_MEZZ_LOM3_SCL")
	)
	(segment
		(start 409.321 -83.566)
		(end 409.321 -84.073746)
		(width 0.10795)
		(layer "F.Cu")
		(net "SMB_PCH_MEZZ_LOM3_SCL")
	)
	(segment
		(start 402.257514 -96.376998)
		(end 401.087082 -96.376998)
		(width 0.0889)
		(layer "F.Cu")
		(net "SMB_PCH_MEZZ_LOM3_SCL")
	)
	(segment
		(start 426.604938 -65.44818)
		(end 424.82135 -67.231768)
		(width 0.10795)
		(layer "F.Cu")
		(net "SMB_PCH_MEZZ_LOM3_SCL")
	)
	(segment
		(start 464.846162 -60.3758)
		(end 465.4042 -60.3758)
		(width 0.10795)
		(layer "F.Cu")
		(net "SMB_PCH_MEZZ_LOM3_SCL")
	)
	(segment
		(start 411.226 -81.661)
		(end 409.321 -83.566)
		(width 0.10795)
		(layer "F.Cu")
		(net "SMB_PCH_MEZZ_LOM3_SCL")
	)
	(segment
		(start 465.9376 -60.9092)
		(end 465.9376 -64.317372)
		(width 0.10795)
		(layer "F.Cu")
		(net "SMB_PCH_MEZZ_LOM3_SCL")
	)
	(segment
		(start 403.13356 -95.500952)
		(end 402.558504 -96.076008)
		(width 0.10795)
		(layer "F.Cu")
		(net "SMB_PCH_MEZZ_LOM3_SCL")
	)
	(segment
		(start 409.321 -84.073746)
		(end 408.07005 -85.324696)
		(width 0.10795)
		(layer "F.Cu")
		(net "SMB_PCH_MEZZ_LOM3_SCL")
	)
	(segment
		(start 463.189574 -58.954924)
		(end 463.655664 -59.421014)
		(width 0.10795)
		(layer "F.Cu")
		(net "SMB_PCH_MEZZ_LOM3_SCL")
	)
	(segment
		(start 415.098992 -75.984608)
		(end 414.55975 -76.52385)
		(width 0.10795)
		(layer "F.Cu")
		(net "SMB_PCH_MEZZ_LOM3_SCL")
	)
	(segment
		(start 402.558504 -96.076008)
		(end 402.257514 -96.376998)
		(width 0.0889)
		(layer "F.Cu")
		(net "SMB_PCH_MEZZ_LOM3_SCL")
	)
	(segment
		(start 401.087082 -96.376998)
		(end 400.565112 -95.855028)
		(width 0.0889)
		(layer "F.Cu")
		(net "SMB_PCH_MEZZ_LOM3_SCL")
	)
	(segment
		(start 414.55975 -78.808326)
		(end 411.707076 -81.661)
		(width 0.10795)
		(layer "F.Cu")
		(net "SMB_PCH_MEZZ_LOM3_SCL")
	)
	(segment
		(start 463.891376 -59.421014)
		(end 464.846162 -60.3758)
		(width 0.10795)
		(layer "F.Cu")
		(net "SMB_PCH_MEZZ_LOM3_SCL")
	)
	(segment
		(start 462.950052 -58.954924)
		(end 462.950052 -57.596024)
		(width 0.10795)
		(layer "F.Cu")
		(net "SMB_PCH_MEZZ_LOM3_SCL")
	)
	(segment
		(start 414.55975 -76.52385)
		(end 414.55975 -78.808326)
		(width 0.10795)
		(layer "F.Cu")
		(net "SMB_PCH_MEZZ_LOM3_SCL")
	)
	(segment
		(start 411.707076 -81.661)
		(end 411.226 -81.661)
		(width 0.10795)
		(layer "F.Cu")
		(net "SMB_PCH_MEZZ_LOM3_SCL")
	)
	(segment
		(start 464.806792 -65.44818)
		(end 426.604938 -65.44818)
		(width 0.10795)
		(layer "F.Cu")
		(net "SMB_PCH_MEZZ_LOM3_SCL")
	)
	(via
		(at 462.950052 -58.954924)
		(size 0.508)
		(drill 0.254)
		(layers "F.Cu" "B.Cu")
		(net "SMB_PCH_MEZZ_LOM3_SCL")
	)
	(via
		(at 462.6864 -57.7088)
		(size 0.6604)
		(drill 0.3302)
		(layers "F.Cu" "B.Cu")
		(net "SMB_PCH_MEZZ_LOM3_SCL")
	)
	(segment
		(start 462.6864 -57.7088)
		(end 463.042 -57.3532)
		(width 0.10795)
		(layer "B.Cu")
		(net "SMB_PCH_MEZZ_LOM3_SCL")
	)
	(segment
		(start 462.6864 -57.7088)
		(end 462.6864 -58.691272)
		(width 0.089408)
		(layer "B.Cu")
		(net "SMB_PCH_MEZZ_LOM3_SCL")
	)
	(segment
		(start 466.344 -57.3532)
		(end 468.7062 -54.991)
		(width 0.10795)
		(layer "B.Cu")
		(net "SMB_PCH_MEZZ_LOM3_SCL")
	)
	(segment
		(start 463.042 -57.3532)
		(end 466.344 -57.3532)
		(width 0.10795)
		(layer "B.Cu")
		(net "SMB_PCH_MEZZ_LOM3_SCL")
	)
	(segment
		(start 462.6864 -58.691272)
		(end 462.950052 -58.954924)
		(width 0.089408)
		(layer "B.Cu")
		(net "SMB_PCH_MEZZ_LOM3_SCL")
	)
	(segment
		(start 468.7062 -54.991)
		(end 469.138 -54.991)
		(width 0.10795)
		(layer "B.Cu")
		(net "SMB_PCH_MEZZ_LOM3_SCL")
	)
	(segment
		(start 406.447752 -87.413592)
		(end 406.447752 -80.768952)
		(width 0.10795)
		(layer "F.Cu")
		(net "SMB_PCH_MEZZ_LOM2_SDA")
	)
	(segment
		(start 400.465036 -97.855024)
		(end 400.109944 -97.855024)
		(width 0.0889)
		(layer "F.Cu")
		(net "SMB_PCH_MEZZ_LOM2_SDA")
	)
	(segment
		(start 400.82216 -91.76004)
		(end 401.1676 -91.4146)
		(width 0.10795)
		(layer "F.Cu")
		(net "SMB_PCH_MEZZ_LOM2_SDA")
	)
	(segment
		(start 401.1676 -90.77325)
		(end 402.315934 -89.624916)
		(width 0.10795)
		(layer "F.Cu")
		(net "SMB_PCH_MEZZ_LOM2_SDA")
	)
	(segment
		(start 402.315934 -89.624916)
		(end 404.236428 -89.624916)
		(width 0.10795)
		(layer "F.Cu")
		(net "SMB_PCH_MEZZ_LOM2_SDA")
	)
	(segment
		(start 424.5864 -67.134232)
		(end 426.5422 -65.178432)
		(width 0.10795)
		(layer "F.Cu")
		(net "SMB_PCH_MEZZ_LOM2_SDA")
	)
	(segment
		(start 417.952936 -75.477116)
		(end 421.070278 -75.477116)
		(width 0.10795)
		(layer "F.Cu")
		(net "SMB_PCH_MEZZ_LOM2_SDA")
	)
	(segment
		(start 399.323814 -95.98406)
		(end 399.323814 -95.495872)
		(width 0.0889)
		(layer "F.Cu")
		(net "SMB_PCH_MEZZ_LOM2_SDA")
	)
	(segment
		(start 399.73885 -97.48393)
		(end 399.73885 -97.191322)
		(width 0.0889)
		(layer "F.Cu")
		(net "SMB_PCH_MEZZ_LOM2_SDA")
	)
	(segment
		(start 399.73885 -96.51873)
		(end 399.73885 -96.399096)
		(width 0.0889)
		(layer "F.Cu")
		(net "SMB_PCH_MEZZ_LOM2_SDA")
	)
	(segment
		(start 405.967184 -80.288384)
		(end 405.967184 -79.155798)
		(width 0.10795)
		(layer "F.Cu")
		(net "SMB_PCH_MEZZ_LOM2_SDA")
	)
	(segment
		(start 400.25066 -91.76004)
		(end 400.82216 -91.76004)
		(width 0.10795)
		(layer "F.Cu")
		(net "SMB_PCH_MEZZ_LOM2_SDA")
	)
	(segment
		(start 426.5422 -65.178432)
		(end 463.14233 -65.178432)
		(width 0.10795)
		(layer "F.Cu")
		(net "SMB_PCH_MEZZ_LOM2_SDA")
	)
	(segment
		(start 405.0792 -78.267814)
		(end 405.0792 -75.34021)
		(width 0.10795)
		(layer "F.Cu")
		(net "SMB_PCH_MEZZ_LOM2_SDA")
	)
	(segment
		(start 400.047968 -93.825822)
		(end 400.047968 -93.269816)
		(width 0.0889)
		(layer "F.Cu")
		(net "SMB_PCH_MEZZ_LOM2_SDA")
	)
	(segment
		(start 399.946114 -96.725994)
		(end 399.73885 -96.51873)
		(width 0.0889)
		(layer "F.Cu")
		(net "SMB_PCH_MEZZ_LOM2_SDA")
	)
	(segment
		(start 400.10588 -92.62618)
		(end 399.9738 -92.4941)
		(width 0.0889)
		(layer "F.Cu")
		(net "SMB_PCH_MEZZ_LOM2_SDA")
	)
	(segment
		(start 421.459914 -75.477624)
		(end 424.5864 -72.351138)
		(width 0.10795)
		(layer "F.Cu")
		(net "SMB_PCH_MEZZ_LOM2_SDA")
	)
	(segment
		(start 400.047968 -93.269816)
		(end 400.10588 -93.211904)
		(width 0.0889)
		(layer "F.Cu")
		(net "SMB_PCH_MEZZ_LOM2_SDA")
	)
	(segment
		(start 463.14233 -65.178432)
		(end 463.876898 -64.443864)
		(width 0.10795)
		(layer "F.Cu")
		(net "SMB_PCH_MEZZ_LOM2_SDA")
	)
	(segment
		(start 405.967184 -79.155798)
		(end 405.0792 -78.267814)
		(width 0.10795)
		(layer "F.Cu")
		(net "SMB_PCH_MEZZ_LOM2_SDA")
	)
	(segment
		(start 416.307016 -73.831196)
		(end 417.952936 -75.477116)
		(width 0.10795)
		(layer "F.Cu")
		(net "SMB_PCH_MEZZ_LOM2_SDA")
	)
	(segment
		(start 407.916888 -72.502522)
		(end 412.077408 -72.502522)
		(width 0.10795)
		(layer "F.Cu")
		(net "SMB_PCH_MEZZ_LOM2_SDA")
	)
	(segment
		(start 421.265096 -75.47737)
		(end 421.26535 -75.477624)
		(width 0.10795)
		(layer "F.Cu")
		(net "SMB_PCH_MEZZ_LOM2_SDA")
	)
	(segment
		(start 421.26535 -75.477624)
		(end 421.459914 -75.477624)
		(width 0.10795)
		(layer "F.Cu")
		(net "SMB_PCH_MEZZ_LOM2_SDA")
	)
	(segment
		(start 399.946114 -96.984058)
		(end 399.946114 -96.725994)
		(width 0.0889)
		(layer "F.Cu")
		(net "SMB_PCH_MEZZ_LOM2_SDA")
	)
	(segment
		(start 412.077408 -72.502522)
		(end 413.406082 -73.831196)
		(width 0.10795)
		(layer "F.Cu")
		(net "SMB_PCH_MEZZ_LOM2_SDA")
	)
	(segment
		(start 413.406082 -73.831196)
		(end 416.307016 -73.831196)
		(width 0.10795)
		(layer "F.Cu")
		(net "SMB_PCH_MEZZ_LOM2_SDA")
	)
	(segment
		(start 399.323814 -95.495872)
		(end 400.10588 -94.713806)
		(width 0.0889)
		(layer "F.Cu")
		(net "SMB_PCH_MEZZ_LOM2_SDA")
	)
	(segment
		(start 400.10588 -94.713806)
		(end 400.10588 -93.883734)
		(width 0.0889)
		(layer "F.Cu")
		(net "SMB_PCH_MEZZ_LOM2_SDA")
	)
	(segment
		(start 400.109944 -97.855024)
		(end 399.73885 -97.48393)
		(width 0.0889)
		(layer "F.Cu")
		(net "SMB_PCH_MEZZ_LOM2_SDA")
	)
	(segment
		(start 399.73885 -97.191322)
		(end 399.946114 -96.984058)
		(width 0.0889)
		(layer "F.Cu")
		(net "SMB_PCH_MEZZ_LOM2_SDA")
	)
	(segment
		(start 463.750152 -63.373254)
		(end 463.876898 -63.5)
		(width 0.10795)
		(layer "F.Cu")
		(net "SMB_PCH_MEZZ_LOM2_SDA")
	)
	(segment
		(start 400.10588 -93.211904)
		(end 400.10588 -92.62618)
		(width 0.0889)
		(layer "F.Cu")
		(net "SMB_PCH_MEZZ_LOM2_SDA")
	)
	(segment
		(start 463.750152 -62.00267)
		(end 463.750152 -63.373254)
		(width 0.10795)
		(layer "F.Cu")
		(net "SMB_PCH_MEZZ_LOM2_SDA")
	)
	(segment
		(start 400.10588 -93.883734)
		(end 400.047968 -93.825822)
		(width 0.0889)
		(layer "F.Cu")
		(net "SMB_PCH_MEZZ_LOM2_SDA")
	)
	(segment
		(start 421.070278 -75.477116)
		(end 421.070532 -75.47737)
		(width 0.10795)
		(layer "F.Cu")
		(net "SMB_PCH_MEZZ_LOM2_SDA")
	)
	(segment
		(start 401.1676 -91.4146)
		(end 401.1676 -90.77325)
		(width 0.10795)
		(layer "F.Cu")
		(net "SMB_PCH_MEZZ_LOM2_SDA")
	)
	(segment
		(start 406.447752 -80.768952)
		(end 405.967184 -80.288384)
		(width 0.10795)
		(layer "F.Cu")
		(net "SMB_PCH_MEZZ_LOM2_SDA")
	)
	(segment
		(start 405.0792 -75.34021)
		(end 407.916888 -72.502522)
		(width 0.10795)
		(layer "F.Cu")
		(net "SMB_PCH_MEZZ_LOM2_SDA")
	)
	(segment
		(start 421.070532 -75.47737)
		(end 421.265096 -75.47737)
		(width 0.10795)
		(layer "F.Cu")
		(net "SMB_PCH_MEZZ_LOM2_SDA")
	)
	(segment
		(start 424.5864 -72.351138)
		(end 424.5864 -67.134232)
		(width 0.10795)
		(layer "F.Cu")
		(net "SMB_PCH_MEZZ_LOM2_SDA")
	)
	(segment
		(start 399.73885 -96.399096)
		(end 399.323814 -95.98406)
		(width 0.0889)
		(layer "F.Cu")
		(net "SMB_PCH_MEZZ_LOM2_SDA")
	)
	(segment
		(start 399.9738 -92.0369)
		(end 400.25066 -91.76004)
		(width 0.0889)
		(layer "F.Cu")
		(net "SMB_PCH_MEZZ_LOM2_SDA")
	)
	(segment
		(start 463.876898 -64.443864)
		(end 463.876898 -63.5)
		(width 0.10795)
		(layer "F.Cu")
		(net "SMB_PCH_MEZZ_LOM2_SDA")
	)
	(segment
		(start 399.9738 -92.4941)
		(end 399.9738 -92.0369)
		(width 0.0889)
		(layer "F.Cu")
		(net "SMB_PCH_MEZZ_LOM2_SDA")
	)
	(segment
		(start 404.236428 -89.624916)
		(end 406.447752 -87.413592)
		(width 0.10795)
		(layer "F.Cu")
		(net "SMB_PCH_MEZZ_LOM2_SDA")
	)
	(via
		(at 466.3186 -62.1284)
		(size 0.6604)
		(drill 0.3302)
		(layers "F.Cu" "B.Cu")
		(net "SMB_PCH_MEZZ_LOM2_SDA")
	)
	(via
		(at 463.876898 -63.5)
		(size 0.508)
		(drill 0.254)
		(layers "F.Cu" "B.Cu")
		(net "SMB_PCH_MEZZ_LOM2_SDA")
	)
	(segment
		(start 465.4296 -63.0174)
		(end 466.3186 -62.1284)
		(width 0.10795)
		(layer "B.Cu")
		(net "SMB_PCH_MEZZ_LOM2_SDA")
	)
	(segment
		(start 467.020402 -61.426598)
		(end 468.842598 -61.426598)
		(width 0.10795)
		(layer "B.Cu")
		(net "SMB_PCH_MEZZ_LOM2_SDA")
	)
	(segment
		(start 464.359498 -63.0174)
		(end 465.4296 -63.0174)
		(width 0.10795)
		(layer "B.Cu")
		(net "SMB_PCH_MEZZ_LOM2_SDA")
	)
	(segment
		(start 468.842598 -61.426598)
		(end 469.138 -61.722)
		(width 0.10795)
		(layer "B.Cu")
		(net "SMB_PCH_MEZZ_LOM2_SDA")
	)
	(segment
		(start 463.876898 -63.5)
		(end 464.359498 -63.0174)
		(width 0.10795)
		(layer "B.Cu")
		(net "SMB_PCH_MEZZ_LOM2_SDA")
	)
	(segment
		(start 466.3186 -62.1284)
		(end 467.020402 -61.426598)
		(width 0.10795)
		(layer "B.Cu")
		(net "SMB_PCH_MEZZ_LOM2_SDA")
	)
	(segment
		(start 407.795984 -72.19315)
		(end 404.71725 -75.271884)
		(width 0.10795)
		(layer "F.Cu")
		(net "SMB_PCH_MEZZ_LOM2_SCL")
	)
	(segment
		(start 405.605234 -79.306166)
		(end 405.605234 -80.301592)
		(width 0.10795)
		(layer "F.Cu")
		(net "SMB_PCH_MEZZ_LOM2_SCL")
	)
	(segment
		(start 413.1691 -72.19315)
		(end 407.795984 -72.19315)
		(width 0.10795)
		(layer "F.Cu")
		(net "SMB_PCH_MEZZ_LOM2_SCL")
	)
	(segment
		(start 426.444664 -64.943482)
		(end 424.35145 -67.036696)
		(width 0.10795)
		(layer "F.Cu")
		(net "SMB_PCH_MEZZ_LOM2_SCL")
	)
	(segment
		(start 404.71725 -75.271884)
		(end 404.71725 -78.418182)
		(width 0.10795)
		(layer "F.Cu")
		(net "SMB_PCH_MEZZ_LOM2_SCL")
	)
	(segment
		(start 406.160224 -86.81212)
		(end 404.242016 -88.730328)
		(width 0.10795)
		(layer "F.Cu")
		(net "SMB_PCH_MEZZ_LOM2_SCL")
	)
	(segment
		(start 405.605234 -80.301592)
		(end 406.160224 -80.856582)
		(width 0.10795)
		(layer "F.Cu")
		(net "SMB_PCH_MEZZ_LOM2_SCL")
	)
	(segment
		(start 463.3722 -63.6778)
		(end 463.3722 -63.9572)
		(width 0.10795)
		(layer "F.Cu")
		(net "SMB_PCH_MEZZ_LOM2_SCL")
	)
	(segment
		(start 414.548066 -73.572116)
		(end 413.1691 -72.19315)
		(width 0.10795)
		(layer "F.Cu")
		(net "SMB_PCH_MEZZ_LOM2_SCL")
	)
	(segment
		(start 406.160224 -80.856582)
		(end 406.160224 -86.81212)
		(width 0.10795)
		(layer "F.Cu")
		(net "SMB_PCH_MEZZ_LOM2_SCL")
	)
	(segment
		(start 416.380422 -73.572116)
		(end 414.548066 -73.572116)
		(width 0.10795)
		(layer "F.Cu")
		(net "SMB_PCH_MEZZ_LOM2_SCL")
	)
	(segment
		(start 401.714208 -88.730328)
		(end 399.8468 -90.597736)
		(width 0.10795)
		(layer "F.Cu")
		(net "SMB_PCH_MEZZ_LOM2_SCL")
	)
	(segment
		(start 399.8468 -91.78671)
		(end 399.275808 -92.357702)
		(width 0.0889)
		(layer "F.Cu")
		(net "SMB_PCH_MEZZ_LOM2_SCL")
	)
	(segment
		(start 462.929732 -64.943482)
		(end 426.444664 -64.943482)
		(width 0.10795)
		(layer "F.Cu")
		(net "SMB_PCH_MEZZ_LOM2_SCL")
	)
	(segment
		(start 462.949798 -63.255398)
		(end 463.3722 -63.6778)
		(width 0.10795)
		(layer "F.Cu")
		(net "SMB_PCH_MEZZ_LOM2_SCL")
	)
	(segment
		(start 404.71725 -78.418182)
		(end 405.605234 -79.306166)
		(width 0.10795)
		(layer "F.Cu")
		(net "SMB_PCH_MEZZ_LOM2_SCL")
	)
	(segment
		(start 399.29308 -94.005146)
		(end 399.371058 -94.083124)
		(width 0.0889)
		(layer "F.Cu")
		(net "SMB_PCH_MEZZ_LOM2_SCL")
	)
	(segment
		(start 421.362632 -75.24242)
		(end 421.168068 -75.24242)
		(width 0.10795)
		(layer "F.Cu")
		(net "SMB_PCH_MEZZ_LOM2_SCL")
	)
	(segment
		(start 463.3722 -63.9572)
		(end 463.3722 -64.501014)
		(width 0.10795)
		(layer "F.Cu")
		(net "SMB_PCH_MEZZ_LOM2_SCL")
	)
	(segment
		(start 399.275808 -92.357702)
		(end 399.275808 -93.339412)
		(width 0.0889)
		(layer "F.Cu")
		(net "SMB_PCH_MEZZ_LOM2_SCL")
	)
	(segment
		(start 421.167814 -75.242166)
		(end 418.050472 -75.242166)
		(width 0.10795)
		(layer "F.Cu")
		(net "SMB_PCH_MEZZ_LOM2_SCL")
	)
	(segment
		(start 399.8468 -90.597736)
		(end 399.8468 -91.78671)
		(width 0.10795)
		(layer "F.Cu")
		(net "SMB_PCH_MEZZ_LOM2_SCL")
	)
	(segment
		(start 399.371058 -94.083124)
		(end 399.371058 -95.00362)
		(width 0.0889)
		(layer "F.Cu")
		(net "SMB_PCH_MEZZ_LOM2_SCL")
	)
	(segment
		(start 424.35145 -67.036696)
		(end 424.35145 -72.253602)
		(width 0.10795)
		(layer "F.Cu")
		(net "SMB_PCH_MEZZ_LOM2_SCL")
	)
	(segment
		(start 462.950052 -63.255144)
		(end 462.949798 -63.255398)
		(width 0.10795)
		(layer "F.Cu")
		(net "SMB_PCH_MEZZ_LOM2_SCL")
	)
	(segment
		(start 404.242016 -88.730328)
		(end 401.714208 -88.730328)
		(width 0.10795)
		(layer "F.Cu")
		(net "SMB_PCH_MEZZ_LOM2_SCL")
	)
	(segment
		(start 421.168068 -75.24242)
		(end 421.167814 -75.242166)
		(width 0.10795)
		(layer "F.Cu")
		(net "SMB_PCH_MEZZ_LOM2_SCL")
	)
	(segment
		(start 424.35145 -72.253602)
		(end 421.362632 -75.24242)
		(width 0.10795)
		(layer "F.Cu")
		(net "SMB_PCH_MEZZ_LOM2_SCL")
	)
	(segment
		(start 399.29308 -93.356684)
		(end 399.29308 -94.005146)
		(width 0.0889)
		(layer "F.Cu")
		(net "SMB_PCH_MEZZ_LOM2_SCL")
	)
	(segment
		(start 463.3722 -64.501014)
		(end 462.929732 -64.943482)
		(width 0.10795)
		(layer "F.Cu")
		(net "SMB_PCH_MEZZ_LOM2_SCL")
	)
	(segment
		(start 399.275808 -93.339412)
		(end 399.29308 -93.356684)
		(width 0.0889)
		(layer "F.Cu")
		(net "SMB_PCH_MEZZ_LOM2_SCL")
	)
	(segment
		(start 418.050472 -75.242166)
		(end 416.380422 -73.572116)
		(width 0.10795)
		(layer "F.Cu")
		(net "SMB_PCH_MEZZ_LOM2_SCL")
	)
	(segment
		(start 462.950052 -62.00267)
		(end 462.950052 -63.255144)
		(width 0.10795)
		(layer "F.Cu")
		(net "SMB_PCH_MEZZ_LOM2_SCL")
	)
	(via
		(at 465.963 -63.5)
		(size 0.6604)
		(drill 0.3302)
		(layers "F.Cu" "B.Cu")
		(net "SMB_PCH_MEZZ_LOM2_SCL")
	)
	(via
		(at 463.3722 -63.9572)
		(size 0.508)
		(drill 0.254)
		(layers "F.Cu" "B.Cu")
		(net "SMB_PCH_MEZZ_LOM2_SCL")
	)
	(segment
		(start 466.525102 -62.627002)
		(end 466.152484 -62.627002)
		(width 0.10795)
		(layer "B.Cu")
		(net "SMB_PCH_MEZZ_LOM2_SCL")
	)
	(segment
		(start 466.817202 -61.962284)
		(end 466.817202 -62.334902)
		(width 0.10795)
		(layer "B.Cu")
		(net "SMB_PCH_MEZZ_LOM2_SCL")
	)
	(segment
		(start 465.963 -62.816486)
		(end 465.963 -63.5)
		(width 0.10795)
		(layer "B.Cu")
		(net "SMB_PCH_MEZZ_LOM2_SCL")
	)
	(segment
		(start 466.817202 -62.334902)
		(end 466.525102 -62.627002)
		(width 0.10795)
		(layer "B.Cu")
		(net "SMB_PCH_MEZZ_LOM2_SCL")
	)
	(segment
		(start 468.715598 -61.904372)
		(end 468.472774 -61.661548)
		(width 0.10795)
		(layer "B.Cu")
		(net "SMB_PCH_MEZZ_LOM2_SCL")
	)
	(segment
		(start 463.5246 -64.1096)
		(end 463.3722 -63.9572)
		(width 0.10795)
		(layer "B.Cu")
		(net "SMB_PCH_MEZZ_LOM2_SCL")
	)
	(segment
		(start 465.963 -63.5)
		(end 465.9122 -63.5508)
		(width 0.10795)
		(layer "B.Cu")
		(net "SMB_PCH_MEZZ_LOM2_SCL")
	)
	(segment
		(start 465.9122 -63.5508)
		(end 465.0994 -63.5508)
		(width 0.10795)
		(layer "B.Cu")
		(net "SMB_PCH_MEZZ_LOM2_SCL")
	)
	(segment
		(start 468.715598 -62.350396)
		(end 468.715598 -61.904372)
		(width 0.10795)
		(layer "B.Cu")
		(net "SMB_PCH_MEZZ_LOM2_SCL")
	)
	(segment
		(start 467.117938 -61.661548)
		(end 466.817202 -61.962284)
		(width 0.10795)
		(layer "B.Cu")
		(net "SMB_PCH_MEZZ_LOM2_SCL")
	)
	(segment
		(start 465.0994 -63.5508)
		(end 464.5406 -64.1096)
		(width 0.10795)
		(layer "B.Cu")
		(net "SMB_PCH_MEZZ_LOM2_SCL")
	)
	(segment
		(start 468.472774 -61.661548)
		(end 467.117938 -61.661548)
		(width 0.10795)
		(layer "B.Cu")
		(net "SMB_PCH_MEZZ_LOM2_SCL")
	)
	(segment
		(start 468.849202 -62.484)
		(end 468.715598 -62.350396)
		(width 0.10795)
		(layer "B.Cu")
		(net "SMB_PCH_MEZZ_LOM2_SCL")
	)
	(segment
		(start 469.138 -62.484)
		(end 468.849202 -62.484)
		(width 0.10795)
		(layer "B.Cu")
		(net "SMB_PCH_MEZZ_LOM2_SCL")
	)
	(segment
		(start 464.5406 -64.1096)
		(end 463.5246 -64.1096)
		(width 0.10795)
		(layer "B.Cu")
		(net "SMB_PCH_MEZZ_LOM2_SCL")
	)
	(segment
		(start 466.152484 -62.627002)
		(end 465.963 -62.816486)
		(width 0.10795)
		(layer "B.Cu")
		(net "SMB_PCH_MEZZ_LOM2_SCL")
	)
	(segment
		(start 411.48 -81.407)
		(end 414.1978 -78.6892)
		(width 0.10795)
		(layer "F.Cu")
		(net "SMB_PCH_MEZZ_LOM1_SDA")
	)
	(segment
		(start 400.05 -95.894144)
		(end 400.425666 -95.518478)
		(width 0.0889)
		(layer "F.Cu")
		(net "SMB_PCH_MEZZ_LOM1_SDA")
	)
	(segment
		(start 402.89861 -94.809818)
		(end 402.89861 -93.097096)
		(width 0.10795)
		(layer "F.Cu")
		(net "SMB_PCH_MEZZ_LOM1_SDA")
	)
	(segment
		(start 407.7081 -85.1789)
		(end 409.067 -83.82)
		(width 0.10795)
		(layer "F.Cu")
		(net "SMB_PCH_MEZZ_LOM1_SDA")
	)
	(segment
		(start 411.099 -81.407)
		(end 411.48 -81.407)
		(width 0.10795)
		(layer "F.Cu")
		(net "SMB_PCH_MEZZ_LOM1_SDA")
	)
	(segment
		(start 463.475324 -59.60237)
		(end 463.47507 -59.60237)
		(width 0.10795)
		(layer "F.Cu")
		(net "SMB_PCH_MEZZ_LOM1_SDA")
	)
	(segment
		(start 409.067 -83.439)
		(end 411.099 -81.407)
		(width 0.10795)
		(layer "F.Cu")
		(net "SMB_PCH_MEZZ_LOM1_SDA")
	)
	(segment
		(start 409.067 -83.82)
		(end 409.067 -83.439)
		(width 0.10795)
		(layer "F.Cu")
		(net "SMB_PCH_MEZZ_LOM1_SDA")
	)
	(segment
		(start 401.101814 -95.556324)
		(end 402.152104 -95.556324)
		(width 0.0889)
		(layer "F.Cu")
		(net "SMB_PCH_MEZZ_LOM1_SDA")
	)
	(segment
		(start 463.47507 -59.60237)
		(end 463.343244 -59.470544)
		(width 0.10795)
		(layer "F.Cu")
		(net "SMB_PCH_MEZZ_LOM1_SDA")
	)
	(segment
		(start 463.82559 -59.952636)
		(end 463.475324 -59.60237)
		(width 0.10795)
		(layer "F.Cu")
		(net "SMB_PCH_MEZZ_LOM1_SDA")
	)
	(segment
		(start 463.343244 -59.470544)
		(end 461.751934 -59.470544)
		(width 0.10795)
		(layer "F.Cu")
		(net "SMB_PCH_MEZZ_LOM1_SDA")
	)
	(segment
		(start 414.1978 -76.3016)
		(end 414.948624 -75.550776)
		(width 0.10795)
		(layer "F.Cu")
		(net "SMB_PCH_MEZZ_LOM1_SDA")
	)
	(segment
		(start 402.89861 -93.097096)
		(end 407.7081 -88.287606)
		(width 0.10795)
		(layer "F.Cu")
		(net "SMB_PCH_MEZZ_LOM1_SDA")
	)
	(segment
		(start 461.350106 -59.068716)
		(end 461.350106 -57.596024)
		(width 0.10795)
		(layer "F.Cu")
		(net "SMB_PCH_MEZZ_LOM1_SDA")
	)
	(segment
		(start 414.948624 -75.550776)
		(end 415.77895 -75.550776)
		(width 0.10795)
		(layer "F.Cu")
		(net "SMB_PCH_MEZZ_LOM1_SDA")
	)
	(segment
		(start 414.1978 -78.6892)
		(end 414.1978 -76.3016)
		(width 0.10795)
		(layer "F.Cu")
		(net "SMB_PCH_MEZZ_LOM1_SDA")
	)
	(segment
		(start 401.063968 -95.518478)
		(end 401.101814 -95.556324)
		(width 0.0889)
		(layer "F.Cu")
		(net "SMB_PCH_MEZZ_LOM1_SDA")
	)
	(segment
		(start 400.425666 -95.518478)
		(end 401.063968 -95.518478)
		(width 0.0889)
		(layer "F.Cu")
		(net "SMB_PCH_MEZZ_LOM1_SDA")
	)
	(segment
		(start 407.7081 -88.287606)
		(end 407.7081 -85.1789)
		(width 0.10795)
		(layer "F.Cu")
		(net "SMB_PCH_MEZZ_LOM1_SDA")
	)
	(segment
		(start 461.751934 -59.470544)
		(end 461.350106 -59.068716)
		(width 0.10795)
		(layer "F.Cu")
		(net "SMB_PCH_MEZZ_LOM1_SDA")
	)
	(segment
		(start 402.152104 -95.556324)
		(end 402.89861 -94.809818)
		(width 0.10795)
		(layer "F.Cu")
		(net "SMB_PCH_MEZZ_LOM1_SDA")
	)
	(segment
		(start 400.05 -96.3549)
		(end 400.05 -95.894144)
		(width 0.0889)
		(layer "F.Cu")
		(net "SMB_PCH_MEZZ_LOM1_SDA")
	)
	(via
		(at 415.77895 -75.550776)
		(size 0.508)
		(drill 0.254)
		(layers "F.Cu" "B.Cu")
		(net "SMB_PCH_MEZZ_LOM1_SDA")
	)
	(via
		(at 463.82559 -59.952636)
		(size 0.508)
		(drill 0.254)
		(layers "F.Cu" "B.Cu")
		(net "SMB_PCH_MEZZ_LOM1_SDA")
	)
	(via
		(at 464.812634 -59.362848)
		(size 0.6604)
		(drill 0.3302)
		(layers "F.Cu" "B.Cu")
		(net "SMB_PCH_MEZZ_LOM1_SDA")
	)
	(segment
		(start 468.841074 -57.15)
		(end 469.138 -57.15)
		(width 0.10795)
		(layer "B.Cu")
		(net "SMB_PCH_MEZZ_LOM1_SDA")
	)
	(segment
		(start 466.009482 -58.166)
		(end 467.825074 -58.166)
		(width 0.10795)
		(layer "B.Cu")
		(net "SMB_PCH_MEZZ_LOM1_SDA")
	)
	(segment
		(start 464.222846 -59.952636)
		(end 464.812634 -59.362848)
		(width 0.10795)
		(layer "B.Cu")
		(net "SMB_PCH_MEZZ_LOM1_SDA")
	)
	(segment
		(start 463.82559 -59.952636)
		(end 464.222846 -59.952636)
		(width 0.10795)
		(layer "B.Cu")
		(net "SMB_PCH_MEZZ_LOM1_SDA")
	)
	(segment
		(start 464.812634 -59.362848)
		(end 466.009482 -58.166)
		(width 0.10795)
		(layer "B.Cu")
		(net "SMB_PCH_MEZZ_LOM1_SDA")
	)
	(segment
		(start 467.825074 -58.166)
		(end 468.841074 -57.15)
		(width 0.10795)
		(layer "B.Cu")
		(net "SMB_PCH_MEZZ_LOM1_SDA")
	)
	(segment
		(start 417.45662 -63.439548)
		(end 419.080188 -61.81598)
		(width 0.089408)
		(layer "In2.Cu")
		(net "SMB_PCH_MEZZ_LOM1_SDA")
	)
	(segment
		(start 435.873906 -58.254392)
		(end 443.044072 -58.254392)
		(width 0.089408)
		(layer "In2.Cu")
		(net "SMB_PCH_MEZZ_LOM1_SDA")
	)
	(segment
		(start 423.081704 -57.811924)
		(end 429.321468 -57.811924)
		(width 0.089408)
		(layer "In2.Cu")
		(net "SMB_PCH_MEZZ_LOM1_SDA")
	)
	(segment
		(start 443.044072 -58.254392)
		(end 443.5856 -58.79592)
		(width 0.089408)
		(layer "In2.Cu")
		(net "SMB_PCH_MEZZ_LOM1_SDA")
	)
	(segment
		(start 417.45662 -70.685406)
		(end 417.45662 -64.550798)
		(width 0.089408)
		(layer "In2.Cu")
		(net "SMB_PCH_MEZZ_LOM1_SDA")
	)
	(segment
		(start 454.253092 -60.306712)
		(end 463.471514 -60.306712)
		(width 0.089408)
		(layer "In2.Cu")
		(net "SMB_PCH_MEZZ_LOM1_SDA")
	)
	(segment
		(start 415.77895 -75.550776)
		(end 417.224718 -74.105008)
		(width 0.089408)
		(layer "In2.Cu")
		(net "SMB_PCH_MEZZ_LOM1_SDA")
	)
	(segment
		(start 453.859392 -59.913012)
		(end 454.253092 -60.306712)
		(width 0.089408)
		(layer "In2.Cu")
		(net "SMB_PCH_MEZZ_LOM1_SDA")
	)
	(segment
		(start 417.45662 -64.550798)
		(end 417.456874 -64.550544)
		(width 0.089408)
		(layer "In2.Cu")
		(net "SMB_PCH_MEZZ_LOM1_SDA")
	)
	(segment
		(start 429.321468 -57.811924)
		(end 430.651412 -56.48198)
		(width 0.089408)
		(layer "In2.Cu")
		(net "SMB_PCH_MEZZ_LOM1_SDA")
	)
	(segment
		(start 417.224718 -74.105008)
		(end 417.224718 -70.917308)
		(width 0.089408)
		(layer "In2.Cu")
		(net "SMB_PCH_MEZZ_LOM1_SDA")
	)
	(segment
		(start 443.5856 -59.465464)
		(end 444.035942 -59.915806)
		(width 0.089408)
		(layer "In2.Cu")
		(net "SMB_PCH_MEZZ_LOM1_SDA")
	)
	(segment
		(start 448.1449 -59.915806)
		(end 448.375024 -60.14593)
		(width 0.089408)
		(layer "In2.Cu")
		(net "SMB_PCH_MEZZ_LOM1_SDA")
	)
	(segment
		(start 419.080188 -61.81344)
		(end 423.081704 -57.811924)
		(width 0.089408)
		(layer "In2.Cu")
		(net "SMB_PCH_MEZZ_LOM1_SDA")
	)
	(segment
		(start 417.456874 -63.758572)
		(end 417.45662 -63.758318)
		(width 0.089408)
		(layer "In2.Cu")
		(net "SMB_PCH_MEZZ_LOM1_SDA")
	)
	(segment
		(start 434.101494 -56.48198)
		(end 435.873906 -58.254392)
		(width 0.089408)
		(layer "In2.Cu")
		(net "SMB_PCH_MEZZ_LOM1_SDA")
	)
	(segment
		(start 419.080188 -61.81598)
		(end 419.080188 -61.81344)
		(width 0.089408)
		(layer "In2.Cu")
		(net "SMB_PCH_MEZZ_LOM1_SDA")
	)
	(segment
		(start 443.5856 -58.79592)
		(end 443.5856 -59.465464)
		(width 0.089408)
		(layer "In2.Cu")
		(net "SMB_PCH_MEZZ_LOM1_SDA")
	)
	(segment
		(start 449.7959 -59.913012)
		(end 453.859392 -59.913012)
		(width 0.089408)
		(layer "In2.Cu")
		(net "SMB_PCH_MEZZ_LOM1_SDA")
	)
	(segment
		(start 417.456874 -64.550544)
		(end 417.456874 -63.758572)
		(width 0.089408)
		(layer "In2.Cu")
		(net "SMB_PCH_MEZZ_LOM1_SDA")
	)
	(segment
		(start 417.224718 -70.917308)
		(end 417.45662 -70.685406)
		(width 0.089408)
		(layer "In2.Cu")
		(net "SMB_PCH_MEZZ_LOM1_SDA")
	)
	(segment
		(start 417.45662 -63.758318)
		(end 417.45662 -63.439548)
		(width 0.089408)
		(layer "In2.Cu")
		(net "SMB_PCH_MEZZ_LOM1_SDA")
	)
	(segment
		(start 430.651412 -56.48198)
		(end 434.101494 -56.48198)
		(width 0.089408)
		(layer "In2.Cu")
		(net "SMB_PCH_MEZZ_LOM1_SDA")
	)
	(segment
		(start 448.375024 -60.14593)
		(end 449.562982 -60.14593)
		(width 0.089408)
		(layer "In2.Cu")
		(net "SMB_PCH_MEZZ_LOM1_SDA")
	)
	(segment
		(start 463.471514 -60.306712)
		(end 463.82559 -59.952636)
		(width 0.089408)
		(layer "In2.Cu")
		(net "SMB_PCH_MEZZ_LOM1_SDA")
	)
	(segment
		(start 444.035942 -59.915806)
		(end 448.1449 -59.915806)
		(width 0.089408)
		(layer "In2.Cu")
		(net "SMB_PCH_MEZZ_LOM1_SDA")
	)
	(segment
		(start 449.562982 -60.14593)
		(end 449.7959 -59.913012)
		(width 0.089408)
		(layer "In2.Cu")
		(net "SMB_PCH_MEZZ_LOM1_SDA")
	)
	(segment
		(start 401.643342 -94.799658)
		(end 400.83613 -94.799658)
		(width 0.0889)
		(layer "F.Cu")
		(net "SMB_PCH_MEZZ_LOM1_SCL")
	)
	(segment
		(start 461.65643 -59.906408)
		(end 460.550006 -58.799984)
		(width 0.10795)
		(layer "F.Cu")
		(net "SMB_PCH_MEZZ_LOM1_SCL")
	)
	(segment
		(start 400.83613 -94.799658)
		(end 400.565112 -95.070676)
		(width 0.0889)
		(layer "F.Cu")
		(net "SMB_PCH_MEZZ_LOM1_SCL")
	)
	(segment
		(start 408.813 -83.693)
		(end 407.34615 -85.15985)
		(width 0.10795)
		(layer "F.Cu")
		(net "SMB_PCH_MEZZ_LOM1_SCL")
	)
	(segment
		(start 460.550006 -58.799984)
		(end 460.550006 -57.596024)
		(width 0.10795)
		(layer "F.Cu")
		(net "SMB_PCH_MEZZ_LOM1_SCL")
	)
	(segment
		(start 413.8041 -78.7019)
		(end 411.353 -81.153)
		(width 0.10795)
		(layer "F.Cu")
		(net "SMB_PCH_MEZZ_LOM1_SCL")
	)
	(segment
		(start 402.363178 -91.933014)
		(end 402.363178 -94.384622)
		(width 0.10795)
		(layer "F.Cu")
		(net "SMB_PCH_MEZZ_LOM1_SCL")
	)
	(segment
		(start 402.1836 -94.5642)
		(end 401.8788 -94.5642)
		(width 0.0889)
		(layer "F.Cu")
		(net "SMB_PCH_MEZZ_LOM1_SCL")
	)
	(segment
		(start 401.8788 -94.5642)
		(end 401.643342 -94.799658)
		(width 0.0889)
		(layer "F.Cu")
		(net "SMB_PCH_MEZZ_LOM1_SCL")
	)
	(segment
		(start 413.8041 -76.0603)
		(end 413.8041 -78.7019)
		(width 0.10795)
		(layer "F.Cu")
		(net "SMB_PCH_MEZZ_LOM1_SCL")
	)
	(segment
		(start 407.34615 -87.916258)
		(end 403.806406 -91.456002)
		(width 0.10795)
		(layer "F.Cu")
		(net "SMB_PCH_MEZZ_LOM1_SCL")
	)
	(segment
		(start 408.813 -83.312)
		(end 408.813 -83.693)
		(width 0.10795)
		(layer "F.Cu")
		(net "SMB_PCH_MEZZ_LOM1_SCL")
	)
	(segment
		(start 411.353 -81.153)
		(end 410.972 -81.153)
		(width 0.10795)
		(layer "F.Cu")
		(net "SMB_PCH_MEZZ_LOM1_SCL")
	)
	(segment
		(start 403.806406 -91.456002)
		(end 402.84019 -91.456002)
		(width 0.10795)
		(layer "F.Cu")
		(net "SMB_PCH_MEZZ_LOM1_SCL")
	)
	(segment
		(start 414.948116 -74.916284)
		(end 413.8041 -76.0603)
		(width 0.10795)
		(layer "F.Cu")
		(net "SMB_PCH_MEZZ_LOM1_SCL")
	)
	(segment
		(start 407.34615 -85.15985)
		(end 407.34615 -87.916258)
		(width 0.10795)
		(layer "F.Cu")
		(net "SMB_PCH_MEZZ_LOM1_SCL")
	)
	(segment
		(start 402.84019 -91.456002)
		(end 402.363178 -91.933014)
		(width 0.10795)
		(layer "F.Cu")
		(net "SMB_PCH_MEZZ_LOM1_SCL")
	)
	(segment
		(start 415.752788 -74.916284)
		(end 414.948116 -74.916284)
		(width 0.10795)
		(layer "F.Cu")
		(net "SMB_PCH_MEZZ_LOM1_SCL")
	)
	(segment
		(start 463.010758 -59.906408)
		(end 461.65643 -59.906408)
		(width 0.10795)
		(layer "F.Cu")
		(net "SMB_PCH_MEZZ_LOM1_SCL")
	)
	(segment
		(start 410.972 -81.153)
		(end 408.813 -83.312)
		(width 0.10795)
		(layer "F.Cu")
		(net "SMB_PCH_MEZZ_LOM1_SCL")
	)
	(segment
		(start 402.363178 -94.384622)
		(end 402.1836 -94.5642)
		(width 0.10795)
		(layer "F.Cu")
		(net "SMB_PCH_MEZZ_LOM1_SCL")
	)
	(via
		(at 415.752788 -74.916284)
		(size 0.508)
		(drill 0.254)
		(layers "F.Cu" "B.Cu")
		(net "SMB_PCH_MEZZ_LOM1_SCL")
	)
	(via
		(at 463.010758 -59.906408)
		(size 0.508)
		(drill 0.254)
		(layers "F.Cu" "B.Cu")
		(net "SMB_PCH_MEZZ_LOM1_SCL")
	)
	(via
		(at 462.5594 -60.7568)
		(size 0.6604)
		(drill 0.3302)
		(layers "F.Cu" "B.Cu")
		(net "SMB_PCH_MEZZ_LOM1_SCL")
	)
	(segment
		(start 468.47125 -57.912)
		(end 467.9442 -58.43905)
		(width 0.10795)
		(layer "B.Cu")
		(net "SMB_PCH_MEZZ_LOM1_SCL")
	)
	(segment
		(start 462.8642 -61.0616)
		(end 462.5594 -60.7568)
		(width 0.10795)
		(layer "B.Cu")
		(net "SMB_PCH_MEZZ_LOM1_SCL")
	)
	(segment
		(start 463.8548 -61.0616)
		(end 462.8642 -61.0616)
		(width 0.10795)
		(layer "B.Cu")
		(net "SMB_PCH_MEZZ_LOM1_SCL")
	)
	(segment
		(start 462.5594 -60.7568)
		(end 462.5594 -60.357766)
		(width 0.10795)
		(layer "B.Cu")
		(net "SMB_PCH_MEZZ_LOM1_SCL")
	)
	(segment
		(start 462.5594 -60.357766)
		(end 463.010758 -59.906408)
		(width 0.10795)
		(layer "B.Cu")
		(net "SMB_PCH_MEZZ_LOM1_SCL")
	)
	(segment
		(start 466.47735 -58.43905)
		(end 463.8548 -61.0616)
		(width 0.10795)
		(layer "B.Cu")
		(net "SMB_PCH_MEZZ_LOM1_SCL")
	)
	(segment
		(start 469.138 -57.912)
		(end 468.47125 -57.912)
		(width 0.10795)
		(layer "B.Cu")
		(net "SMB_PCH_MEZZ_LOM1_SCL")
	)
	(segment
		(start 467.9442 -58.43905)
		(end 466.47735 -58.43905)
		(width 0.10795)
		(layer "B.Cu")
		(net "SMB_PCH_MEZZ_LOM1_SCL")
	)
	(segment
		(start 449.716652 -59.722004)
		(end 449.483734 -59.954922)
		(width 0.089408)
		(layer "In2.Cu")
		(net "SMB_PCH_MEZZ_LOM1_SCL")
	)
	(segment
		(start 417.265866 -64.471296)
		(end 417.265612 -64.47155)
		(width 0.089408)
		(layer "In2.Cu")
		(net "SMB_PCH_MEZZ_LOM1_SCL")
	)
	(segment
		(start 443.8142 -59.423808)
		(end 443.8142 -58.754264)
		(width 0.089408)
		(layer "In2.Cu")
		(net "SMB_PCH_MEZZ_LOM1_SCL")
	)
	(segment
		(start 417.265612 -64.47155)
		(end 417.265612 -70.606158)
		(width 0.089408)
		(layer "In2.Cu")
		(net "SMB_PCH_MEZZ_LOM1_SCL")
	)
	(segment
		(start 462.801462 -60.115704)
		(end 454.33234 -60.115704)
		(width 0.089408)
		(layer "In2.Cu")
		(net "SMB_PCH_MEZZ_LOM1_SCL")
	)
	(segment
		(start 443.072012 -58.012076)
		(end 435.901846 -58.012076)
		(width 0.089408)
		(layer "In2.Cu")
		(net "SMB_PCH_MEZZ_LOM1_SCL")
	)
	(segment
		(start 463.010758 -59.906408)
		(end 462.801462 -60.115704)
		(width 0.089408)
		(layer "In2.Cu")
		(net "SMB_PCH_MEZZ_LOM1_SCL")
	)
	(segment
		(start 454.33234 -60.115704)
		(end 453.93864 -59.722004)
		(width 0.089408)
		(layer "In2.Cu")
		(net "SMB_PCH_MEZZ_LOM1_SCL")
	)
	(segment
		(start 417.265612 -70.606158)
		(end 417.03371 -70.83806)
		(width 0.089408)
		(layer "In2.Cu")
		(net "SMB_PCH_MEZZ_LOM1_SCL")
	)
	(segment
		(start 417.265612 -63.3603)
		(end 417.265612 -63.837566)
		(width 0.089408)
		(layer "In2.Cu")
		(net "SMB_PCH_MEZZ_LOM1_SCL")
	)
	(segment
		(start 443.8142 -58.754264)
		(end 443.072012 -58.012076)
		(width 0.089408)
		(layer "In2.Cu")
		(net "SMB_PCH_MEZZ_LOM1_SCL")
	)
	(segment
		(start 417.03371 -73.635362)
		(end 415.752788 -74.916284)
		(width 0.089408)
		(layer "In2.Cu")
		(net "SMB_PCH_MEZZ_LOM1_SCL")
	)
	(segment
		(start 435.901846 -58.012076)
		(end 434.180742 -56.290972)
		(width 0.089408)
		(layer "In2.Cu")
		(net "SMB_PCH_MEZZ_LOM1_SCL")
	)
	(segment
		(start 453.93864 -59.722004)
		(end 449.716652 -59.722004)
		(width 0.089408)
		(layer "In2.Cu")
		(net "SMB_PCH_MEZZ_LOM1_SCL")
	)
	(segment
		(start 417.265612 -63.837566)
		(end 417.265866 -63.83782)
		(width 0.089408)
		(layer "In2.Cu")
		(net "SMB_PCH_MEZZ_LOM1_SCL")
	)
	(segment
		(start 417.265866 -63.83782)
		(end 417.265866 -64.471296)
		(width 0.089408)
		(layer "In2.Cu")
		(net "SMB_PCH_MEZZ_LOM1_SCL")
	)
	(segment
		(start 444.11519 -59.724798)
		(end 443.8142 -59.423808)
		(width 0.089408)
		(layer "In2.Cu")
		(net "SMB_PCH_MEZZ_LOM1_SCL")
	)
	(segment
		(start 418.88918 -61.736732)
		(end 417.265612 -63.3603)
		(width 0.089408)
		(layer "In2.Cu")
		(net "SMB_PCH_MEZZ_LOM1_SCL")
	)
	(segment
		(start 423.04335 -57.580022)
		(end 418.88918 -61.734192)
		(width 0.089408)
		(layer "In2.Cu")
		(net "SMB_PCH_MEZZ_LOM1_SCL")
	)
	(segment
		(start 430.572164 -56.290972)
		(end 429.283114 -57.580022)
		(width 0.089408)
		(layer "In2.Cu")
		(net "SMB_PCH_MEZZ_LOM1_SCL")
	)
	(segment
		(start 448.224148 -59.724798)
		(end 444.11519 -59.724798)
		(width 0.089408)
		(layer "In2.Cu")
		(net "SMB_PCH_MEZZ_LOM1_SCL")
	)
	(segment
		(start 429.283114 -57.580022)
		(end 423.04335 -57.580022)
		(width 0.089408)
		(layer "In2.Cu")
		(net "SMB_PCH_MEZZ_LOM1_SCL")
	)
	(segment
		(start 434.180742 -56.290972)
		(end 430.572164 -56.290972)
		(width 0.089408)
		(layer "In2.Cu")
		(net "SMB_PCH_MEZZ_LOM1_SCL")
	)
	(segment
		(start 418.88918 -61.734192)
		(end 418.88918 -61.736732)
		(width 0.089408)
		(layer "In2.Cu")
		(net "SMB_PCH_MEZZ_LOM1_SCL")
	)
	(segment
		(start 448.454272 -59.954922)
		(end 448.224148 -59.724798)
		(width 0.089408)
		(layer "In2.Cu")
		(net "SMB_PCH_MEZZ_LOM1_SCL")
	)
	(segment
		(start 449.483734 -59.954922)
		(end 448.454272 -59.954922)
		(width 0.089408)
		(layer "In2.Cu")
		(net "SMB_PCH_MEZZ_LOM1_SCL")
	)
	(segment
		(start 417.03371 -70.83806)
		(end 417.03371 -73.635362)
		(width 0.089408)
		(layer "In2.Cu")
		(net "SMB_PCH_MEZZ_LOM1_SCL")
	)
	(segment
		(start 456.54976 -58.74004)
		(end 455.5744 -59.7154)
		(width 0.10795)
		(layer "F.Cu")
		(net "SMB_PCH_MEZZ_LOM0_SDA")
	)
	(segment
		(start 397.867886 -94.257876)
		(end 397.867886 -93.885512)
		(width 0.0889)
		(layer "F.Cu")
		(net "SMB_PCH_MEZZ_LOM0_SDA")
	)
	(segment
		(start 397.648938 -93.161866)
		(end 397.648938 -92.656914)
		(width 0.0889)
		(layer "F.Cu")
		(net "SMB_PCH_MEZZ_LOM0_SDA")
	)
	(segment
		(start 456.54976 -57.596278)
		(end 456.54976 -58.74004)
		(width 0.10795)
		(layer "F.Cu")
		(net "SMB_PCH_MEZZ_LOM0_SDA")
	)
	(segment
		(start 397.867886 -93.885512)
		(end 397.712184 -93.72981)
		(width 0.0889)
		(layer "F.Cu")
		(net "SMB_PCH_MEZZ_LOM0_SDA")
	)
	(segment
		(start 397.712184 -93.72981)
		(end 397.712184 -93.225112)
		(width 0.0889)
		(layer "F.Cu")
		(net "SMB_PCH_MEZZ_LOM0_SDA")
	)
	(segment
		(start 397.712184 -93.225112)
		(end 397.648938 -93.161866)
		(width 0.0889)
		(layer "F.Cu")
		(net "SMB_PCH_MEZZ_LOM0_SDA")
	)
	(segment
		(start 397.648938 -92.656914)
		(end 398.048734 -92.257118)
		(width 0.0889)
		(layer "F.Cu")
		(net "SMB_PCH_MEZZ_LOM0_SDA")
	)
	(segment
		(start 397.98498 -94.37497)
		(end 397.867886 -94.257876)
		(width 0.0889)
		(layer "F.Cu")
		(net "SMB_PCH_MEZZ_LOM0_SDA")
	)
	(segment
		(start 456.550014 -57.596024)
		(end 456.54976 -57.596278)
		(width 0.10795)
		(layer "F.Cu")
		(net "SMB_PCH_MEZZ_LOM0_SDA")
	)
	(via
		(at 468.2744 -60.706)
		(size 0.508)
		(drill 0.254)
		(layers "F.Cu" "B.Cu")
		(net "SMB_PCH_MEZZ_LOM0_SDA")
	)
	(via
		(at 398.048734 -92.257118)
		(size 0.508)
		(drill 0.254)
		(layers "F.Cu" "B.Cu")
		(net "SMB_PCH_MEZZ_LOM0_SDA")
	)
	(via
		(at 411.9372 -98.1202)
		(size 0.508)
		(drill 0.254)
		(layers "F.Cu" "B.Cu")
		(net "SMB_PCH_MEZZ_LOM0_SDA")
	)
	(via
		(at 455.5744 -59.7154)
		(size 0.508)
		(drill 0.254)
		(layers "F.Cu" "B.Cu")
		(net "SMB_PCH_MEZZ_LOM0_SDA")
	)
	(segment
		(start 468.7824 -60.198)
		(end 468.2744 -60.706)
		(width 0.10795)
		(layer "B.Cu")
		(net "SMB_PCH_MEZZ_LOM0_SDA")
	)
	(segment
		(start 469.138 -60.198)
		(end 468.7824 -60.198)
		(width 0.10795)
		(layer "B.Cu")
		(net "SMB_PCH_MEZZ_LOM0_SDA")
	)
	(segment
		(start 416.050984 -61.290962)
		(end 415.269172 -62.072774)
		(width 0.089408)
		(layer "In2.Cu")
		(net "SMB_PCH_MEZZ_LOM0_SDA")
	)
	(segment
		(start 412.450026 -86.110318)
		(end 412.450026 -97.607374)
		(width 0.089408)
		(layer "In2.Cu")
		(net "SMB_PCH_MEZZ_LOM0_SDA")
	)
	(segment
		(start 414.286192 -82.476848)
		(end 414.870392 -83.061048)
		(width 0.089408)
		(layer "In2.Cu")
		(net "SMB_PCH_MEZZ_LOM0_SDA")
	)
	(segment
		(start 428.97552 -56.501538)
		(end 422.770554 -56.501538)
		(width 0.089408)
		(layer "In2.Cu")
		(net "SMB_PCH_MEZZ_LOM0_SDA")
	)
	(segment
		(start 430.141126 -55.335932)
		(end 428.97552 -56.501538)
		(width 0.089408)
		(layer "In2.Cu")
		(net "SMB_PCH_MEZZ_LOM0_SDA")
	)
	(segment
		(start 434.576982 -55.335932)
		(end 430.141126 -55.335932)
		(width 0.089408)
		(layer "In2.Cu")
		(net "SMB_PCH_MEZZ_LOM0_SDA")
	)
	(segment
		(start 414.870392 -68.841366)
		(end 414.870392 -70.135242)
		(width 0.089408)
		(layer "In2.Cu")
		(net "SMB_PCH_MEZZ_LOM0_SDA")
	)
	(segment
		(start 455.5744 -59.7154)
		(end 455.440288 -59.849512)
		(width 0.089408)
		(layer "In2.Cu")
		(net "SMB_PCH_MEZZ_LOM0_SDA")
	)
	(segment
		(start 436.218838 -56.977788)
		(end 434.576982 -55.335932)
		(width 0.089408)
		(layer "In2.Cu")
		(net "SMB_PCH_MEZZ_LOM0_SDA")
	)
	(segment
		(start 414.870392 -83.689952)
		(end 412.450026 -86.110318)
		(width 0.089408)
		(layer "In2.Cu")
		(net "SMB_PCH_MEZZ_LOM0_SDA")
	)
	(segment
		(start 455.440288 -59.849512)
		(end 454.504044 -59.849512)
		(width 0.089408)
		(layer "In2.Cu")
		(net "SMB_PCH_MEZZ_LOM0_SDA")
	)
	(segment
		(start 422.770554 -56.501538)
		(end 417.98113 -61.290962)
		(width 0.089408)
		(layer "In2.Cu")
		(net "SMB_PCH_MEZZ_LOM0_SDA")
	)
	(segment
		(start 454.504044 -59.849512)
		(end 453.1868 -58.532268)
		(width 0.089408)
		(layer "In2.Cu")
		(net "SMB_PCH_MEZZ_LOM0_SDA")
	)
	(segment
		(start 414.870392 -83.061048)
		(end 414.870392 -83.689952)
		(width 0.089408)
		(layer "In2.Cu")
		(net "SMB_PCH_MEZZ_LOM0_SDA")
	)
	(segment
		(start 415.269172 -62.072774)
		(end 415.269172 -68.442586)
		(width 0.089408)
		(layer "In2.Cu")
		(net "SMB_PCH_MEZZ_LOM0_SDA")
	)
	(segment
		(start 414.165796 -74.406506)
		(end 414.667192 -74.907902)
		(width 0.089408)
		(layer "In2.Cu")
		(net "SMB_PCH_MEZZ_LOM0_SDA")
	)
	(segment
		(start 453.1868 -58.532268)
		(end 453.1868 -57.386728)
		(width 0.089408)
		(layer "In2.Cu")
		(net "SMB_PCH_MEZZ_LOM0_SDA")
	)
	(segment
		(start 414.870392 -70.135242)
		(end 413.949896 -71.055738)
		(width 0.089408)
		(layer "In2.Cu")
		(net "SMB_PCH_MEZZ_LOM0_SDA")
	)
	(segment
		(start 452.77786 -56.977788)
		(end 436.218838 -56.977788)
		(width 0.089408)
		(layer "In2.Cu")
		(net "SMB_PCH_MEZZ_LOM0_SDA")
	)
	(segment
		(start 453.1868 -57.386728)
		(end 452.77786 -56.977788)
		(width 0.089408)
		(layer "In2.Cu")
		(net "SMB_PCH_MEZZ_LOM0_SDA")
	)
	(segment
		(start 414.286192 -80.565752)
		(end 414.286192 -82.476848)
		(width 0.089408)
		(layer "In2.Cu")
		(net "SMB_PCH_MEZZ_LOM0_SDA")
	)
	(segment
		(start 414.165796 -72.015604)
		(end 414.165796 -74.406506)
		(width 0.089408)
		(layer "In2.Cu")
		(net "SMB_PCH_MEZZ_LOM0_SDA")
	)
	(segment
		(start 413.949896 -71.799704)
		(end 414.165796 -72.015604)
		(width 0.089408)
		(layer "In2.Cu")
		(net "SMB_PCH_MEZZ_LOM0_SDA")
	)
	(segment
		(start 414.667192 -80.184752)
		(end 414.286192 -80.565752)
		(width 0.089408)
		(layer "In2.Cu")
		(net "SMB_PCH_MEZZ_LOM0_SDA")
	)
	(segment
		(start 412.450026 -97.607374)
		(end 411.9372 -98.1202)
		(width 0.089408)
		(layer "In2.Cu")
		(net "SMB_PCH_MEZZ_LOM0_SDA")
	)
	(segment
		(start 413.949896 -71.055738)
		(end 413.949896 -71.799704)
		(width 0.089408)
		(layer "In2.Cu")
		(net "SMB_PCH_MEZZ_LOM0_SDA")
	)
	(segment
		(start 415.269172 -68.442586)
		(end 414.870392 -68.841366)
		(width 0.089408)
		(layer "In2.Cu")
		(net "SMB_PCH_MEZZ_LOM0_SDA")
	)
	(segment
		(start 414.667192 -74.907902)
		(end 414.667192 -80.184752)
		(width 0.089408)
		(layer "In2.Cu")
		(net "SMB_PCH_MEZZ_LOM0_SDA")
	)
	(segment
		(start 417.98113 -61.290962)
		(end 416.050984 -61.290962)
		(width 0.089408)
		(layer "In2.Cu")
		(net "SMB_PCH_MEZZ_LOM0_SDA")
	)
	(segment
		(start 411.9372 -98.1202)
		(end 410.7688 -96.9518)
		(width 0.089408)
		(layer "In4.Cu")
		(net "SMB_PCH_MEZZ_LOM0_SDA")
	)
	(segment
		(start 405.53386 -92.70746)
		(end 403.52472 -94.7166)
		(width 0.089408)
		(layer "In4.Cu")
		(net "SMB_PCH_MEZZ_LOM0_SDA")
	)
	(segment
		(start 410.7688 -96.9518)
		(end 410.7688 -95.333312)
		(width 0.089408)
		(layer "In4.Cu")
		(net "SMB_PCH_MEZZ_LOM0_SDA")
	)
	(segment
		(start 400.508216 -94.7166)
		(end 398.048734 -92.257118)
		(width 0.089408)
		(layer "In4.Cu")
		(net "SMB_PCH_MEZZ_LOM0_SDA")
	)
	(segment
		(start 409.669488 -94.234)
		(end 407.53538 -94.234)
		(width 0.089408)
		(layer "In4.Cu")
		(net "SMB_PCH_MEZZ_LOM0_SDA")
	)
	(segment
		(start 407.53538 -94.234)
		(end 406.00884 -92.70746)
		(width 0.089408)
		(layer "In4.Cu")
		(net "SMB_PCH_MEZZ_LOM0_SDA")
	)
	(segment
		(start 403.52472 -94.7166)
		(end 400.508216 -94.7166)
		(width 0.089408)
		(layer "In4.Cu")
		(net "SMB_PCH_MEZZ_LOM0_SDA")
	)
	(segment
		(start 410.7688 -95.333312)
		(end 409.669488 -94.234)
		(width 0.089408)
		(layer "In4.Cu")
		(net "SMB_PCH_MEZZ_LOM0_SDA")
	)
	(segment
		(start 406.00884 -92.70746)
		(end 405.53386 -92.70746)
		(width 0.089408)
		(layer "In4.Cu")
		(net "SMB_PCH_MEZZ_LOM0_SDA")
	)
	(segment
		(start 457.770484 -61.182504)
		(end 467.602062 -61.182504)
		(width 0.089408)
		(layer "In11.Cu")
		(net "SMB_PCH_MEZZ_LOM0_SDA")
	)
	(segment
		(start 467.602062 -61.182504)
		(end 468.078566 -60.706)
		(width 0.089408)
		(layer "In11.Cu")
		(net "SMB_PCH_MEZZ_LOM0_SDA")
	)
	(segment
		(start 468.078566 -60.706)
		(end 468.2744 -60.706)
		(width 0.089408)
		(layer "In11.Cu")
		(net "SMB_PCH_MEZZ_LOM0_SDA")
	)
	(segment
		(start 455.5744 -59.7154)
		(end 456.30338 -59.7154)
		(width 0.089408)
		(layer "In11.Cu")
		(net "SMB_PCH_MEZZ_LOM0_SDA")
	)
	(segment
		(start 456.30338 -59.7154)
		(end 457.770484 -61.182504)
		(width 0.089408)
		(layer "In11.Cu")
		(net "SMB_PCH_MEZZ_LOM0_SDA")
	)
	(segment
		(start 397.485108 -94.427802)
		(end 397.162274 -94.104968)
		(width 0.0889)
		(layer "F.Cu")
		(net "SMB_PCH_MEZZ_LOM0_SCL")
	)
	(segment
		(start 397.234918 -92.122244)
		(end 397.256762 -92.1004)
		(width 0.0889)
		(layer "F.Cu")
		(net "SMB_PCH_MEZZ_LOM0_SCL")
	)
	(segment
		(start 397.278606 -93.726254)
		(end 397.278606 -93.330268)
		(width 0.0889)
		(layer "F.Cu")
		(net "SMB_PCH_MEZZ_LOM0_SCL")
	)
	(segment
		(start 397.278606 -93.330268)
		(end 397.234918 -93.28658)
		(width 0.0889)
		(layer "F.Cu")
		(net "SMB_PCH_MEZZ_LOM0_SCL")
	)
	(segment
		(start 397.162274 -94.104968)
		(end 397.162274 -93.842586)
		(width 0.0889)
		(layer "F.Cu")
		(net "SMB_PCH_MEZZ_LOM0_SCL")
	)
	(segment
		(start 455.749914 -58.904886)
		(end 455.5998 -59.055)
		(width 0.10795)
		(layer "F.Cu")
		(net "SMB_PCH_MEZZ_LOM0_SCL")
	)
	(segment
		(start 397.485108 -94.790006)
		(end 397.485108 -94.427802)
		(width 0.0889)
		(layer "F.Cu")
		(net "SMB_PCH_MEZZ_LOM0_SCL")
	)
	(segment
		(start 455.749914 -57.596278)
		(end 455.749914 -58.904886)
		(width 0.10795)
		(layer "F.Cu")
		(net "SMB_PCH_MEZZ_LOM0_SCL")
	)
	(segment
		(start 397.256762 -92.1004)
		(end 397.998188 -91.358974)
		(width 0.10795)
		(layer "F.Cu")
		(net "SMB_PCH_MEZZ_LOM0_SCL")
	)
	(segment
		(start 455.750168 -57.596024)
		(end 455.749914 -57.596278)
		(width 0.10795)
		(layer "F.Cu")
		(net "SMB_PCH_MEZZ_LOM0_SCL")
	)
	(segment
		(start 397.234918 -93.28658)
		(end 397.234918 -92.122244)
		(width 0.0889)
		(layer "F.Cu")
		(net "SMB_PCH_MEZZ_LOM0_SCL")
	)
	(segment
		(start 397.162274 -93.842586)
		(end 397.278606 -93.726254)
		(width 0.0889)
		(layer "F.Cu")
		(net "SMB_PCH_MEZZ_LOM0_SCL")
	)
	(via
		(at 455.5998 -59.055)
		(size 0.508)
		(drill 0.254)
		(layers "F.Cu" "B.Cu")
		(net "SMB_PCH_MEZZ_LOM0_SCL")
	)
	(via
		(at 411.9372 -96.901)
		(size 0.508)
		(drill 0.254)
		(layers "F.Cu" "B.Cu")
		(net "SMB_PCH_MEZZ_LOM0_SCL")
	)
	(via
		(at 467.4362 -60.7822)
		(size 0.508)
		(drill 0.254)
		(layers "F.Cu" "B.Cu")
		(net "SMB_PCH_MEZZ_LOM0_SCL")
	)
	(via
		(at 397.998188 -91.358974)
		(size 0.508)
		(drill 0.254)
		(layers "F.Cu" "B.Cu")
		(net "SMB_PCH_MEZZ_LOM0_SCL")
	)
	(segment
		(start 467.808056 -61.154056)
		(end 467.4362 -60.7822)
		(width 0.10795)
		(layer "B.Cu")
		(net "SMB_PCH_MEZZ_LOM0_SCL")
	)
	(segment
		(start 468.5792 -61.154056)
		(end 467.808056 -61.154056)
		(width 0.10795)
		(layer "B.Cu")
		(net "SMB_PCH_MEZZ_LOM0_SCL")
	)
	(segment
		(start 468.773256 -60.96)
		(end 468.5792 -61.154056)
		(width 0.10795)
		(layer "B.Cu")
		(net "SMB_PCH_MEZZ_LOM0_SCL")
	)
	(segment
		(start 469.138 -60.96)
		(end 468.773256 -60.96)
		(width 0.10795)
		(layer "B.Cu")
		(net "SMB_PCH_MEZZ_LOM0_SCL")
	)
	(segment
		(start 415.078164 -68.363338)
		(end 414.679384 -68.762118)
		(width 0.089408)
		(layer "In2.Cu")
		(net "SMB_PCH_MEZZ_LOM0_SCL")
	)
	(segment
		(start 453.377808 -58.45302)
		(end 453.377808 -57.30748)
		(width 0.089408)
		(layer "In2.Cu")
		(net "SMB_PCH_MEZZ_LOM0_SCL")
	)
	(segment
		(start 414.678114 -83.208114)
		(end 414.678114 -83.566762)
		(width 0.089408)
		(layer "In2.Cu")
		(net "SMB_PCH_MEZZ_LOM0_SCL")
	)
	(segment
		(start 414.095184 -80.486504)
		(end 414.095184 -82.625184)
		(width 0.089408)
		(layer "In2.Cu")
		(net "SMB_PCH_MEZZ_LOM0_SCL")
	)
	(segment
		(start 415.971736 -61.099954)
		(end 415.078164 -61.993526)
		(width 0.089408)
		(layer "In2.Cu")
		(net "SMB_PCH_MEZZ_LOM0_SCL")
	)
	(segment
		(start 414.476184 -80.105504)
		(end 414.095184 -80.486504)
		(width 0.089408)
		(layer "In2.Cu")
		(net "SMB_PCH_MEZZ_LOM0_SCL")
	)
	(segment
		(start 436.292498 -56.781192)
		(end 434.65623 -55.144924)
		(width 0.089408)
		(layer "In2.Cu")
		(net "SMB_PCH_MEZZ_LOM0_SCL")
	)
	(segment
		(start 417.901882 -61.099954)
		(end 415.971736 -61.099954)
		(width 0.089408)
		(layer "In2.Cu")
		(net "SMB_PCH_MEZZ_LOM0_SCL")
	)
	(segment
		(start 412.259018 -96.579182)
		(end 411.9372 -96.901)
		(width 0.089408)
		(layer "In2.Cu")
		(net "SMB_PCH_MEZZ_LOM0_SCL")
	)
	(segment
		(start 422.705022 -56.296814)
		(end 417.901882 -61.099954)
		(width 0.089408)
		(layer "In2.Cu")
		(net "SMB_PCH_MEZZ_LOM0_SCL")
	)
	(segment
		(start 414.679384 -68.762118)
		(end 414.679384 -70.055994)
		(width 0.089408)
		(layer "In2.Cu")
		(net "SMB_PCH_MEZZ_LOM0_SCL")
	)
	(segment
		(start 428.909988 -56.296814)
		(end 422.705022 -56.296814)
		(width 0.089408)
		(layer "In2.Cu")
		(net "SMB_PCH_MEZZ_LOM0_SCL")
	)
	(segment
		(start 413.974788 -72.094852)
		(end 413.974788 -74.485754)
		(width 0.089408)
		(layer "In2.Cu")
		(net "SMB_PCH_MEZZ_LOM0_SCL")
	)
	(segment
		(start 413.758888 -71.878952)
		(end 413.974788 -72.094852)
		(width 0.089408)
		(layer "In2.Cu")
		(net "SMB_PCH_MEZZ_LOM0_SCL")
	)
	(segment
		(start 413.758888 -70.97649)
		(end 413.758888 -71.878952)
		(width 0.089408)
		(layer "In2.Cu")
		(net "SMB_PCH_MEZZ_LOM0_SCL")
	)
	(segment
		(start 455.5998 -59.055)
		(end 454.996296 -59.658504)
		(width 0.089408)
		(layer "In2.Cu")
		(net "SMB_PCH_MEZZ_LOM0_SCL")
	)
	(segment
		(start 413.974788 -74.485754)
		(end 414.476184 -74.98715)
		(width 0.089408)
		(layer "In2.Cu")
		(net "SMB_PCH_MEZZ_LOM0_SCL")
	)
	(segment
		(start 412.259018 -85.985858)
		(end 412.259018 -96.579182)
		(width 0.089408)
		(layer "In2.Cu")
		(net "SMB_PCH_MEZZ_LOM0_SCL")
	)
	(segment
		(start 414.678114 -83.566762)
		(end 412.259018 -85.985858)
		(width 0.089408)
		(layer "In2.Cu")
		(net "SMB_PCH_MEZZ_LOM0_SCL")
	)
	(segment
		(start 430.061878 -55.144924)
		(end 428.909988 -56.296814)
		(width 0.089408)
		(layer "In2.Cu")
		(net "SMB_PCH_MEZZ_LOM0_SCL")
	)
	(segment
		(start 452.85152 -56.781192)
		(end 436.292498 -56.781192)
		(width 0.089408)
		(layer "In2.Cu")
		(net "SMB_PCH_MEZZ_LOM0_SCL")
	)
	(segment
		(start 434.65623 -55.144924)
		(end 430.061878 -55.144924)
		(width 0.089408)
		(layer "In2.Cu")
		(net "SMB_PCH_MEZZ_LOM0_SCL")
	)
	(segment
		(start 454.583292 -59.658504)
		(end 453.377808 -58.45302)
		(width 0.089408)
		(layer "In2.Cu")
		(net "SMB_PCH_MEZZ_LOM0_SCL")
	)
	(segment
		(start 415.078164 -61.993526)
		(end 415.078164 -68.363338)
		(width 0.089408)
		(layer "In2.Cu")
		(net "SMB_PCH_MEZZ_LOM0_SCL")
	)
	(segment
		(start 454.996296 -59.658504)
		(end 454.583292 -59.658504)
		(width 0.089408)
		(layer "In2.Cu")
		(net "SMB_PCH_MEZZ_LOM0_SCL")
	)
	(segment
		(start 414.476184 -74.98715)
		(end 414.476184 -80.105504)
		(width 0.089408)
		(layer "In2.Cu")
		(net "SMB_PCH_MEZZ_LOM0_SCL")
	)
	(segment
		(start 414.679384 -70.055994)
		(end 413.758888 -70.97649)
		(width 0.089408)
		(layer "In2.Cu")
		(net "SMB_PCH_MEZZ_LOM0_SCL")
	)
	(segment
		(start 414.095184 -82.625184)
		(end 414.678114 -83.208114)
		(width 0.089408)
		(layer "In2.Cu")
		(net "SMB_PCH_MEZZ_LOM0_SCL")
	)
	(segment
		(start 453.377808 -57.30748)
		(end 452.85152 -56.781192)
		(width 0.089408)
		(layer "In2.Cu")
		(net "SMB_PCH_MEZZ_LOM0_SCL")
	)
	(segment
		(start 398.787874 -92.595192)
		(end 398.787874 -92.385388)
		(width 0.089408)
		(layer "In4.Cu")
		(net "SMB_PCH_MEZZ_LOM0_SCL")
	)
	(segment
		(start 400.655282 -94.4626)
		(end 398.787874 -92.595192)
		(width 0.089408)
		(layer "In4.Cu")
		(net "SMB_PCH_MEZZ_LOM0_SCL")
	)
	(segment
		(start 411.9372 -96.19488)
		(end 409.78201 -94.03969)
		(width 0.089408)
		(layer "In4.Cu")
		(net "SMB_PCH_MEZZ_LOM0_SCL")
	)
	(segment
		(start 406.05202 -92.45854)
		(end 405.43988 -92.45854)
		(width 0.089408)
		(layer "In4.Cu")
		(net "SMB_PCH_MEZZ_LOM0_SCL")
	)
	(segment
		(start 398.787874 -92.385388)
		(end 397.998188 -91.595702)
		(width 0.089408)
		(layer "In4.Cu")
		(net "SMB_PCH_MEZZ_LOM0_SCL")
	)
	(segment
		(start 405.43988 -92.45854)
		(end 403.43582 -94.4626)
		(width 0.089408)
		(layer "In4.Cu")
		(net "SMB_PCH_MEZZ_LOM0_SCL")
	)
	(segment
		(start 407.63317 -94.03969)
		(end 406.05202 -92.45854)
		(width 0.089408)
		(layer "In4.Cu")
		(net "SMB_PCH_MEZZ_LOM0_SCL")
	)
	(segment
		(start 403.43582 -94.4626)
		(end 400.655282 -94.4626)
		(width 0.089408)
		(layer "In4.Cu")
		(net "SMB_PCH_MEZZ_LOM0_SCL")
	)
	(segment
		(start 397.998188 -91.595702)
		(end 397.998188 -91.358974)
		(width 0.089408)
		(layer "In4.Cu")
		(net "SMB_PCH_MEZZ_LOM0_SCL")
	)
	(segment
		(start 411.9372 -96.901)
		(end 411.9372 -96.19488)
		(width 0.089408)
		(layer "In4.Cu")
		(net "SMB_PCH_MEZZ_LOM0_SCL")
	)
	(segment
		(start 409.78201 -94.03969)
		(end 407.63317 -94.03969)
		(width 0.089408)
		(layer "In4.Cu")
		(net "SMB_PCH_MEZZ_LOM0_SCL")
	)
	(segment
		(start 456.057 -59.055)
		(end 455.5998 -59.055)
		(width 0.089408)
		(layer "In11.Cu")
		(net "SMB_PCH_MEZZ_LOM0_SCL")
	)
	(segment
		(start 457.988162 -60.986162)
		(end 456.057 -59.055)
		(width 0.089408)
		(layer "In11.Cu")
		(net "SMB_PCH_MEZZ_LOM0_SCL")
	)
	(segment
		(start 467.232238 -60.986162)
		(end 457.988162 -60.986162)
		(width 0.089408)
		(layer "In11.Cu")
		(net "SMB_PCH_MEZZ_LOM0_SCL")
	)
	(segment
		(start 467.4362 -60.7822)
		(end 467.232238 -60.986162)
		(width 0.089408)
		(layer "In11.Cu")
		(net "SMB_PCH_MEZZ_LOM0_SCL")
	)
	(via
		(at 412.3436 -4.445)
		(size 0.6604)
		(drill 0.3302)
		(layers "F.Cu" "B.Cu")
		(net "PWRGD_P5V_N")
	)
	(segment
		(start 413.639 -6.1976)
		(end 412.6992 -6.1976)
		(width 0.10795)
		(layer "B.Cu")
		(net "PWRGD_P5V_N")
	)
	(segment
		(start 410.455872 -6.0452)
		(end 410.9085 -6.0452)
		(width 0.10795)
		(layer "B.Cu")
		(net "PWRGD_P5V_N")
	)
	(segment
		(start 412.6992 -6.1976)
		(end 412.5976 -6.096)
		(width 0.10795)
		(layer "B.Cu")
		(net "PWRGD_P5V_N")
	)
	(segment
		(start 412.4833 -5.6515)
		(end 411.861 -5.6515)
		(width 0.10795)
		(layer "B.Cu")
		(net "PWRGD_P5V_N")
	)
	(segment
		(start 410.9085 -6.0452)
		(end 411.3022 -5.6515)
		(width 0.10795)
		(layer "B.Cu")
		(net "PWRGD_P5V_N")
	)
	(segment
		(start 412.3436 -4.5466)
		(end 411.861 -5.0292)
		(width 0.10795)
		(layer "B.Cu")
		(net "PWRGD_P5V_N")
	)
	(segment
		(start 411.861 -5.0292)
		(end 411.861 -5.6515)
		(width 0.10795)
		(layer "B.Cu")
		(net "PWRGD_P5V_N")
	)
	(segment
		(start 412.3436 -4.445)
		(end 412.3436 -4.5466)
		(width 0.10795)
		(layer "B.Cu")
		(net "PWRGD_P5V_N")
	)
	(segment
		(start 411.3022 -5.6515)
		(end 411.861 -5.6515)
		(width 0.10795)
		(layer "B.Cu")
		(net "PWRGD_P5V_N")
	)
	(segment
		(start 412.5976 -5.7658)
		(end 412.4833 -5.6515)
		(width 0.10795)
		(layer "B.Cu")
		(net "PWRGD_P5V_N")
	)
	(segment
		(start 412.5976 -6.096)
		(end 412.5976 -5.7658)
		(width 0.10795)
		(layer "B.Cu")
		(net "PWRGD_P5V_N")
	)
	(via
		(at 410.3116 -10.1092)
		(size 0.6604)
		(drill 0.3302)
		(layers "F.Cu" "B.Cu")
		(net "PWRGD_P12V_MAIN_R")
	)
	(segment
		(start 411.48 -8.3185)
		(end 411.861 -8.3185)
		(width 0.10795)
		(layer "B.Cu")
		(net "PWRGD_P12V_MAIN_R")
	)
	(segment
		(start 410.455872 -7.967472)
		(end 410.7307 -8.2423)
		(width 0.10795)
		(layer "B.Cu")
		(net "PWRGD_P12V_MAIN_R")
	)
	(segment
		(start 410.9847 -8.8138)
		(end 411.48 -8.3185)
		(width 0.10795)
		(layer "B.Cu")
		(net "PWRGD_P12V_MAIN_R")
	)
	(segment
		(start 410.7307 -8.2423)
		(end 410.7307 -8.8138)
		(width 0.10795)
		(layer "B.Cu")
		(net "PWRGD_P12V_MAIN_R")
	)
	(segment
		(start 410.455872 -7.1882)
		(end 410.455872 -7.967472)
		(width 0.10795)
		(layer "B.Cu")
		(net "PWRGD_P12V_MAIN_R")
	)
	(segment
		(start 410.7307 -8.8138)
		(end 410.7307 -9.6901)
		(width 0.10795)
		(layer "B.Cu")
		(net "PWRGD_P12V_MAIN_R")
	)
	(segment
		(start 410.7307 -8.8138)
		(end 410.9847 -8.8138)
		(width 0.10795)
		(layer "B.Cu")
		(net "PWRGD_P12V_MAIN_R")
	)
	(segment
		(start 410.7307 -9.6901)
		(end 410.3116 -10.1092)
		(width 0.10795)
		(layer "B.Cu")
		(net "PWRGD_P12V_MAIN_R")
	)
	(segment
		(start 121.646188 -86.612984)
		(end 122.217688 -86.612984)
		(width 0.254)
		(layer "F.Cu")
		(net "PVCCMCP_CPU1")
	)
	(segment
		(start 120.787668 -86.117938)
		(end 121.359168 -86.117938)
		(width 0.254)
		(layer "F.Cu")
		(net "PVCCMCP_CPU1")
	)
	(segment
		(start 128.514348 -75.716384)
		(end 129.085848 -75.716384)
		(width 0.254)
		(layer "F.Cu")
		(net "PVCCMCP_CPU1")
	)
	(segment
		(start 126.797308 -74.725784)
		(end 127.368808 -74.725784)
		(width 0.254)
		(layer "F.Cu")
		(net "PVCCMCP_CPU1")
	)
	(segment
		(start 125.938788 -75.221338)
		(end 126.510288 -75.221338)
		(width 0.254)
		(layer "F.Cu")
		(net "PVCCMCP_CPU1")
	)
	(segment
		(start 122.504708 -90.080338)
		(end 123.076208 -90.080338)
		(width 0.254)
		(layer "F.Cu")
		(net "PVCCMCP_CPU1")
	)
	(segment
		(start 126.797308 -83.641184)
		(end 127.368808 -83.641184)
		(width 0.254)
		(layer "F.Cu")
		(net "PVCCMCP_CPU1")
	)
	(segment
		(start 132.806694 -75.221338)
		(end 133.378194 -75.221338)
		(width 0.254)
		(layer "F.Cu")
		(net "PVCCMCP_CPU1")
	)
	(segment
		(start 123.363228 -85.622384)
		(end 123.934728 -85.622384)
		(width 0.254)
		(layer "F.Cu")
		(net "PVCCMCP_CPU1")
	)
	(segment
		(start 125.938788 -82.155284)
		(end 126.510288 -82.155284)
		(width 0.254)
		(layer "F.Cu")
		(net "PVCCMCP_CPU1")
	)
	(segment
		(start 122.504708 -87.108538)
		(end 123.076208 -87.108538)
		(width 0.254)
		(layer "F.Cu")
		(net "PVCCMCP_CPU1")
	)
	(segment
		(start 133.665214 -73.735184)
		(end 134.236714 -73.735184)
		(width 0.254)
		(layer "F.Cu")
		(net "PVCCMCP_CPU1")
	)
	(segment
		(start 127.655828 -75.221338)
		(end 128.227328 -75.221338)
		(width 0.254)
		(layer "F.Cu")
		(net "PVCCMCP_CPU1")
	)
	(segment
		(start 126.797308 -80.669384)
		(end 127.368808 -80.669384)
		(width 0.254)
		(layer "F.Cu")
		(net "PVCCMCP_CPU1")
	)
	(segment
		(start 127.655828 -67.296538)
		(end 128.227328 -67.296538)
		(width 0.254)
		(layer "F.Cu")
		(net "PVCCMCP_CPU1")
	)
	(segment
		(start 123.363228 -67.791584)
		(end 123.934728 -67.791584)
		(width 0.254)
		(layer "F.Cu")
		(net "PVCCMCP_CPU1")
	)
	(segment
		(start 125.938788 -76.211938)
		(end 126.510288 -76.211938)
		(width 0.254)
		(layer "F.Cu")
		(net "PVCCMCP_CPU1")
	)
	(segment
		(start 122.504708 -89.089738)
		(end 123.076208 -89.089738)
		(width 0.254)
		(layer "F.Cu")
		(net "PVCCMCP_CPU1")
	)
	(segment
		(start 122.504708 -78.193138)
		(end 123.076208 -78.193138)
		(width 0.254)
		(layer "F.Cu")
		(net "PVCCMCP_CPU1")
	)
	(segment
		(start 125.938788 -68.287138)
		(end 126.510288 -68.287138)
		(width 0.254)
		(layer "F.Cu")
		(net "PVCCMCP_CPU1")
	)
	(segment
		(start 125.080268 -81.659984)
		(end 125.651768 -81.659984)
		(width 0.254)
		(layer "F.Cu")
		(net "PVCCMCP_CPU1")
	)
	(segment
		(start 125.080268 -82.650584)
		(end 125.651768 -82.650584)
		(width 0.254)
		(layer "F.Cu")
		(net "PVCCMCP_CPU1")
	)
	(segment
		(start 122.504708 -91.070938)
		(end 123.076208 -91.070938)
		(width 0.254)
		(layer "F.Cu")
		(net "PVCCMCP_CPU1")
	)
	(segment
		(start 131.948174 -74.725784)
		(end 132.519674 -74.725784)
		(width 0.254)
		(layer "F.Cu")
		(net "PVCCMCP_CPU1")
	)
	(segment
		(start 131.948174 -73.735184)
		(end 132.519674 -73.735184)
		(width 0.254)
		(layer "F.Cu")
		(net "PVCCMCP_CPU1")
	)
	(segment
		(start 125.938788 -85.127338)
		(end 126.510288 -85.127338)
		(width 0.254)
		(layer "F.Cu")
		(net "PVCCMCP_CPU1")
	)
	(segment
		(start 125.938788 -84.136738)
		(end 126.510288 -84.136738)
		(width 0.254)
		(layer "F.Cu")
		(net "PVCCMCP_CPU1")
	)
	(segment
		(start 125.080268 -83.641184)
		(end 125.651768 -83.641184)
		(width 0.254)
		(layer "F.Cu")
		(net "PVCCMCP_CPU1")
	)
	(segment
		(start 131.948174 -75.716384)
		(end 132.519674 -75.716384)
		(width 0.254)
		(layer "F.Cu")
		(net "PVCCMCP_CPU1")
	)
	(segment
		(start 131.661408 -75.221338)
		(end 131.089908 -75.221338)
		(width 0.254)
		(layer "F.Cu")
		(net "PVCCMCP_CPU1")
	)
	(segment
		(start 124.221748 -79.183738)
		(end 124.793248 -79.183738)
		(width 0.254)
		(layer "F.Cu")
		(net "PVCCMCP_CPU1")
	)
	(segment
		(start 120.787668 -84.136738)
		(end 121.359168 -84.136738)
		(width 0.254)
		(layer "F.Cu")
		(net "PVCCMCP_CPU1")
	)
	(segment
		(start 123.363228 -87.603584)
		(end 123.934728 -87.603584)
		(width 0.254)
		(layer "F.Cu")
		(net "PVCCMCP_CPU1")
	)
	(segment
		(start 126.797308 -79.678784)
		(end 127.368808 -79.678784)
		(width 0.254)
		(layer "F.Cu")
		(net "PVCCMCP_CPU1")
	)
	(segment
		(start 126.797308 -76.706984)
		(end 127.368808 -76.706984)
		(width 0.254)
		(layer "F.Cu")
		(net "PVCCMCP_CPU1")
	)
	(segment
		(start 131.089908 -76.211938)
		(end 131.661408 -76.211938)
		(width 0.254)
		(layer "F.Cu")
		(net "PVCCMCP_CPU1")
	)
	(segment
		(start 123.363228 -89.584784)
		(end 123.934728 -89.584784)
		(width 0.254)
		(layer "F.Cu")
		(net "PVCCMCP_CPU1")
	)
	(segment
		(start 126.797308 -82.650584)
		(end 127.368808 -82.650584)
		(width 0.254)
		(layer "F.Cu")
		(net "PVCCMCP_CPU1")
	)
	(segment
		(start 131.089908 -73.240138)
		(end 131.661408 -73.240138)
		(width 0.254)
		(layer "F.Cu")
		(net "PVCCMCP_CPU1")
	)
	(segment
		(start 131.948174 -72.744584)
		(end 132.519674 -72.744584)
		(width 0.254)
		(layer "F.Cu")
		(net "PVCCMCP_CPU1")
	)
	(segment
		(start 124.793248 -68.287138)
		(end 124.221748 -68.287138)
		(width 0.254)
		(layer "F.Cu")
		(net "PVCCMCP_CPU1")
	)
	(segment
		(start 121.646188 -67.791584)
		(end 121.074688 -67.791584)
		(width 0.254)
		(layer "F.Cu")
		(net "PVCCMCP_CPU1")
	)
	(segment
		(start 122.504708 -86.117938)
		(end 123.076208 -86.117938)
		(width 0.254)
		(layer "F.Cu")
		(net "PVCCMCP_CPU1")
	)
	(segment
		(start 130.231388 -75.716384)
		(end 130.802888 -75.716384)
		(width 0.254)
		(layer "F.Cu")
		(net "PVCCMCP_CPU1")
	)
	(segment
		(start 129.372868 -75.221338)
		(end 129.944368 -75.221338)
		(width 0.254)
		(layer "F.Cu")
		(net "PVCCMCP_CPU1")
	)
	(segment
		(start 120.787668 -67.296538)
		(end 120.216168 -67.296538)
		(width 0.254)
		(layer "F.Cu")
		(net "PVCCMCP_CPU1")
	)
	(segment
		(start 122.504708 -67.296538)
		(end 121.933208 -67.296538)
		(width 0.254)
		(layer "F.Cu")
		(net "PVCCMCP_CPU1")
	)
	(segment
		(start 132.806694 -73.240138)
		(end 133.378194 -73.240138)
		(width 0.254)
		(layer "F.Cu")
		(net "PVCCMCP_CPU1")
	)
	(segment
		(start 123.363228 -84.631784)
		(end 123.934728 -84.631784)
		(width 0.254)
		(layer "F.Cu")
		(net "PVCCMCP_CPU1")
	)
	(segment
		(start 124.221748 -85.127338)
		(end 124.793248 -85.127338)
		(width 0.254)
		(layer "F.Cu")
		(net "PVCCMCP_CPU1")
	)
	(segment
		(start 120.787668 -68.287138)
		(end 120.216168 -68.287138)
		(width 0.254)
		(layer "F.Cu")
		(net "PVCCMCP_CPU1")
	)
	(segment
		(start 125.080268 -79.678784)
		(end 125.651768 -79.678784)
		(width 0.254)
		(layer "F.Cu")
		(net "PVCCMCP_CPU1")
	)
	(segment
		(start 123.363228 -83.641184)
		(end 123.934728 -83.641184)
		(width 0.254)
		(layer "F.Cu")
		(net "PVCCMCP_CPU1")
	)
	(segment
		(start 125.938788 -80.174338)
		(end 126.510288 -80.174338)
		(width 0.254)
		(layer "F.Cu")
		(net "PVCCMCP_CPU1")
	)
	(segment
		(start 120.787668 -85.127338)
		(end 121.359168 -85.127338)
		(width 0.254)
		(layer "F.Cu")
		(net "PVCCMCP_CPU1")
	)
	(segment
		(start 121.646188 -68.782184)
		(end 122.217688 -68.782184)
		(width 0.254)
		(layer "F.Cu")
		(net "PVCCMCP_CPU1")
	)
	(segment
		(start 122.504708 -85.127338)
		(end 123.076208 -85.127338)
		(width 0.254)
		(layer "F.Cu")
		(net "PVCCMCP_CPU1")
	)
	(segment
		(start 125.080268 -84.631784)
		(end 125.651768 -84.631784)
		(width 0.254)
		(layer "F.Cu")
		(net "PVCCMCP_CPU1")
	)
	(segment
		(start 124.221748 -78.193138)
		(end 124.793248 -78.193138)
		(width 0.254)
		(layer "F.Cu")
		(net "PVCCMCP_CPU1")
	)
	(segment
		(start 124.221748 -83.146138)
		(end 124.793248 -83.146138)
		(width 0.254)
		(layer "F.Cu")
		(net "PVCCMCP_CPU1")
	)
	(segment
		(start 123.363228 -88.594184)
		(end 123.934728 -88.594184)
		(width 0.254)
		(layer "F.Cu")
		(net "PVCCMCP_CPU1")
	)
	(segment
		(start 121.646188 -66.800984)
		(end 121.074688 -66.800984)
		(width 0.254)
		(layer "F.Cu")
		(net "PVCCMCP_CPU1")
	)
	(segment
		(start 123.363228 -86.612984)
		(end 123.934728 -86.612984)
		(width 0.254)
		(layer "F.Cu")
		(net "PVCCMCP_CPU1")
	)
	(segment
		(start 132.806694 -74.230738)
		(end 133.378194 -74.23023)
		(width 0.254)
		(layer "F.Cu")
		(net "PVCCMCP_CPU1")
	)
	(segment
		(start 125.080268 -77.697584)
		(end 125.651768 -77.697584)
		(width 0.254)
		(layer "F.Cu")
		(net "PVCCMCP_CPU1")
	)
	(segment
		(start 122.217688 -90.575384)
		(end 121.646188 -90.575384)
		(width 0.254)
		(layer "F.Cu")
		(net "PVCCMCP_CPU1")
	)
	(segment
		(start 131.089908 -74.230738)
		(end 131.661408 -74.23023)
		(width 0.254)
		(layer "F.Cu")
		(net "PVCCMCP_CPU1")
	)
	(segment
		(start 126.797308 -81.659984)
		(end 127.368808 -81.659984)
		(width 0.254)
		(layer "F.Cu")
		(net "PVCCMCP_CPU1")
	)
	(segment
		(start 123.363228 -68.782184)
		(end 123.934728 -68.782184)
		(width 0.254)
		(layer "F.Cu")
		(net "PVCCMCP_CPU1")
	)
	(segment
		(start 125.080268 -66.800984)
		(end 125.651768 -66.800984)
		(width 0.254)
		(layer "F.Cu")
		(net "PVCCMCP_CPU1")
	)
	(segment
		(start 124.221748 -67.296538)
		(end 124.793248 -67.296538)
		(width 0.254)
		(layer "F.Cu")
		(net "PVCCMCP_CPU1")
	)
	(segment
		(start 125.938788 -79.183738)
		(end 126.510288 -79.183738)
		(width 0.254)
		(layer "F.Cu")
		(net "PVCCMCP_CPU1")
	)
	(segment
		(start 124.221748 -81.164938)
		(end 124.793248 -81.164938)
		(width 0.254)
		(layer "F.Cu")
		(net "PVCCMCP_CPU1")
	)
	(segment
		(start 121.646188 -85.622384)
		(end 122.217688 -85.622384)
		(width 0.254)
		(layer "F.Cu")
		(net "PVCCMCP_CPU1")
	)
	(via
		(at 177.182272 -49.834038)
		(size 0.508)
		(drill 0.254)
		(layers "F.Cu" "B.Cu")
		(net "PVCCMCP_CPU1")
	)
	(via
		(at 134.236714 -73.735184)
		(size 0.508)
		(drill 0.254)
		(layers "F.Cu" "B.Cu")
		(net "PVCCMCP_CPU1")
	)
	(via
		(at 111.783876 -74.397616)
		(size 0.508)
		(drill 0.254)
		(layers "F.Cu" "B.Cu")
		(net "PVCCMCP_CPU1")
	)
	(via
		(at 108.888276 -78.715616)
		(size 0.508)
		(drill 0.254)
		(layers "F.Cu" "B.Cu")
		(net "PVCCMCP_CPU1")
	)
	(via
		(at 123.934728 -68.782184)
		(size 0.508)
		(drill 0.254)
		(layers "F.Cu" "B.Cu")
		(net "PVCCMCP_CPU1")
	)
	(via
		(at 133.378194 -75.221338)
		(size 0.508)
		(drill 0.254)
		(layers "F.Cu" "B.Cu")
		(net "PVCCMCP_CPU1")
	)
	(via
		(at 154.90444 -51.144424)
		(size 0.508)
		(drill 0.254)
		(layers "F.Cu" "B.Cu")
		(net "PVCCMCP_CPU1")
	)
	(via
		(at 158.406592 -57.656476)
		(size 0.508)
		(drill 0.254)
		(layers "F.Cu" "B.Cu")
		(net "PVCCMCP_CPU1")
	)
	(via
		(at 158.406592 -53.211476)
		(size 0.508)
		(drill 0.254)
		(layers "F.Cu" "B.Cu")
		(net "PVCCMCP_CPU1")
	)
	(via
		(at 157.136592 -55.751476)
		(size 0.508)
		(drill 0.254)
		(layers "F.Cu" "B.Cu")
		(net "PVCCMCP_CPU1")
	)
	(via
		(at 122.217688 -86.612984)
		(size 0.508)
		(drill 0.254)
		(layers "F.Cu" "B.Cu")
		(net "PVCCMCP_CPU1")
	)
	(via
		(at 125.651768 -81.659984)
		(size 0.508)
		(drill 0.254)
		(layers "F.Cu" "B.Cu")
		(net "PVCCMCP_CPU1")
	)
	(via
		(at 179.144168 -49.715166)
		(size 0.508)
		(drill 0.254)
		(layers "F.Cu" "B.Cu")
		(net "PVCCMCP_CPU1")
	)
	(via
		(at 121.074688 -66.800984)
		(size 0.508)
		(drill 0.254)
		(layers "F.Cu" "B.Cu")
		(net "PVCCMCP_CPU1")
	)
	(via
		(at 194.025774 -46.762162)
		(size 0.508)
		(drill 0.254)
		(layers "F.Cu" "B.Cu")
		(net "PVCCMCP_CPU1")
	)
	(via
		(at 124.793248 -68.287138)
		(size 0.508)
		(drill 0.254)
		(layers "F.Cu" "B.Cu")
		(net "PVCCMCP_CPU1")
	)
	(via
		(at 128.227328 -67.296538)
		(size 0.508)
		(drill 0.254)
		(layers "F.Cu" "B.Cu")
		(net "PVCCMCP_CPU1")
	)
	(via
		(at 187.868814 -48.421036)
		(size 0.508)
		(drill 0.254)
		(layers "F.Cu" "B.Cu")
		(net "PVCCMCP_CPU1")
	)
	(via
		(at 107.059476 -78.715616)
		(size 0.508)
		(drill 0.254)
		(layers "F.Cu" "B.Cu")
		(net "PVCCMCP_CPU1")
	)
	(via
		(at 123.934728 -88.594184)
		(size 0.508)
		(drill 0.254)
		(layers "F.Cu" "B.Cu")
		(net "PVCCMCP_CPU1")
	)
	(via
		(at 123.934728 -87.603584)
		(size 0.508)
		(drill 0.254)
		(layers "F.Cu" "B.Cu")
		(net "PVCCMCP_CPU1")
	)
	(via
		(at 122.217688 -90.575384)
		(size 0.508)
		(drill 0.254)
		(layers "F.Cu" "B.Cu")
		(net "PVCCMCP_CPU1")
	)
	(via
		(at 157.771592 -57.656476)
		(size 0.508)
		(drill 0.254)
		(layers "F.Cu" "B.Cu")
		(net "PVCCMCP_CPU1")
	)
	(via
		(at 155.231592 -56.386476)
		(size 0.508)
		(drill 0.254)
		(layers "F.Cu" "B.Cu")
		(net "PVCCMCP_CPU1")
	)
	(via
		(at 123.934728 -86.612984)
		(size 0.508)
		(drill 0.254)
		(layers "F.Cu" "B.Cu")
		(net "PVCCMCP_CPU1")
	)
	(via
		(at 123.076208 -89.089738)
		(size 0.508)
		(drill 0.254)
		(layers "F.Cu" "B.Cu")
		(net "PVCCMCP_CPU1")
	)
	(via
		(at 177.227484 -49.07407)
		(size 0.508)
		(drill 0.254)
		(layers "F.Cu" "B.Cu")
		(net "PVCCMCP_CPU1")
	)
	(via
		(at 155.866592 -51.941476)
		(size 0.508)
		(drill 0.254)
		(layers "F.Cu" "B.Cu")
		(net "PVCCMCP_CPU1")
	)
	(via
		(at 158.406592 -54.481476)
		(size 0.508)
		(drill 0.254)
		(layers "F.Cu" "B.Cu")
		(net "PVCCMCP_CPU1")
	)
	(via
		(at 125.651768 -82.650584)
		(size 0.508)
		(drill 0.254)
		(layers "F.Cu" "B.Cu")
		(net "PVCCMCP_CPU1")
	)
	(via
		(at 157.136592 -57.021476)
		(size 0.508)
		(drill 0.254)
		(layers "F.Cu" "B.Cu")
		(net "PVCCMCP_CPU1")
	)
	(via
		(at 108.126276 -78.715616)
		(size 0.508)
		(drill 0.254)
		(layers "F.Cu" "B.Cu")
		(net "PVCCMCP_CPU1")
	)
	(via
		(at 156.501592 -53.846476)
		(size 0.508)
		(drill 0.254)
		(layers "F.Cu" "B.Cu")
		(net "PVCCMCP_CPU1")
	)
	(via
		(at 154.596592 -57.656476)
		(size 0.508)
		(drill 0.254)
		(layers "F.Cu" "B.Cu")
		(net "PVCCMCP_CPU1")
	)
	(via
		(at 106.297476 -74.397616)
		(size 0.508)
		(drill 0.254)
		(layers "F.Cu" "B.Cu")
		(net "PVCCMCP_CPU1")
	)
	(via
		(at 126.510288 -68.287138)
		(size 0.508)
		(drill 0.254)
		(layers "F.Cu" "B.Cu")
		(net "PVCCMCP_CPU1")
	)
	(via
		(at 194.657472 -46.643544)
		(size 0.508)
		(drill 0.254)
		(layers "F.Cu" "B.Cu")
		(net "PVCCMCP_CPU1")
	)
	(via
		(at 126.510288 -82.155284)
		(size 0.508)
		(drill 0.254)
		(layers "F.Cu" "B.Cu")
		(net "PVCCMCP_CPU1")
	)
	(via
		(at 124.793248 -79.183738)
		(size 0.508)
		(drill 0.254)
		(layers "F.Cu" "B.Cu")
		(net "PVCCMCP_CPU1")
	)
	(via
		(at 131.661408 -74.23023)
		(size 0.508)
		(drill 0.254)
		(layers "F.Cu" "B.Cu")
		(net "PVCCMCP_CPU1")
	)
	(via
		(at 126.510288 -75.221338)
		(size 0.508)
		(drill 0.254)
		(layers "F.Cu" "B.Cu")
		(net "PVCCMCP_CPU1")
	)
	(via
		(at 155.866592 -55.116476)
		(size 0.508)
		(drill 0.254)
		(layers "F.Cu" "B.Cu")
		(net "PVCCMCP_CPU1")
	)
	(via
		(at 123.934728 -89.584784)
		(size 0.508)
		(drill 0.254)
		(layers "F.Cu" "B.Cu")
		(net "PVCCMCP_CPU1")
	)
	(via
		(at 194.367658 -47.285656)
		(size 0.508)
		(drill 0.254)
		(layers "F.Cu" "B.Cu")
		(net "PVCCMCP_CPU1")
	)
	(via
		(at 131.661408 -73.240138)
		(size 0.508)
		(drill 0.254)
		(layers "F.Cu" "B.Cu")
		(net "PVCCMCP_CPU1")
	)
	(via
		(at 129.944368 -75.221338)
		(size 0.508)
		(drill 0.254)
		(layers "F.Cu" "B.Cu")
		(net "PVCCMCP_CPU1")
	)
	(via
		(at 152.472644 -51.541934)
		(size 0.508)
		(drill 0.254)
		(layers "F.Cu" "B.Cu")
		(net "PVCCMCP_CPU1")
	)
	(via
		(at 127.368808 -81.659984)
		(size 0.508)
		(drill 0.254)
		(layers "F.Cu" "B.Cu")
		(net "PVCCMCP_CPU1")
	)
	(via
		(at 127.368808 -74.725784)
		(size 0.508)
		(drill 0.254)
		(layers "F.Cu" "B.Cu")
		(net "PVCCMCP_CPU1")
	)
	(via
		(at 132.519674 -72.744584)
		(size 0.508)
		(drill 0.254)
		(layers "F.Cu" "B.Cu")
		(net "PVCCMCP_CPU1")
	)
	(via
		(at 155.231592 -57.021476)
		(size 0.508)
		(drill 0.254)
		(layers "F.Cu" "B.Cu")
		(net "PVCCMCP_CPU1")
	)
	(via
		(at 189.211712 -47.863252)
		(size 0.508)
		(drill 0.254)
		(layers "F.Cu" "B.Cu")
		(net "PVCCMCP_CPU1")
	)
	(via
		(at 105.230676 -78.715616)
		(size 0.508)
		(drill 0.254)
		(layers "F.Cu" "B.Cu")
		(net "PVCCMCP_CPU1")
	)
	(via
		(at 194.938904 -47.834042)
		(size 0.508)
		(drill 0.254)
		(layers "F.Cu" "B.Cu")
		(net "PVCCMCP_CPU1")
	)
	(via
		(at 126.510288 -79.183738)
		(size 0.508)
		(drill 0.254)
		(layers "F.Cu" "B.Cu")
		(net "PVCCMCP_CPU1")
	)
	(via
		(at 155.866592 -57.656476)
		(size 0.508)
		(drill 0.254)
		(layers "F.Cu" "B.Cu")
		(net "PVCCMCP_CPU1")
	)
	(via
		(at 180.819044 -49.457356)
		(size 0.508)
		(drill 0.254)
		(layers "F.Cu" "B.Cu")
		(net "PVCCMCP_CPU1")
	)
	(via
		(at 155.722828 -50.971704)
		(size 0.508)
		(drill 0.254)
		(layers "F.Cu" "B.Cu")
		(net "PVCCMCP_CPU1")
	)
	(via
		(at 154.120342 -50.341784)
		(size 0.508)
		(drill 0.254)
		(layers "F.Cu" "B.Cu")
		(net "PVCCMCP_CPU1")
	)
	(via
		(at 178.086766 -48.794924)
		(size 0.508)
		(drill 0.254)
		(layers "F.Cu" "B.Cu")
		(net "PVCCMCP_CPU1")
	)
	(via
		(at 153.2382 -57.5818)
		(size 0.508)
		(drill 0.254)
		(layers "F.Cu" "B.Cu")
		(net "PVCCMCP_CPU1")
	)
	(via
		(at 188.491114 -47.836582)
		(size 0.508)
		(drill 0.254)
		(layers "F.Cu" "B.Cu")
		(net "PVCCMCP_CPU1")
	)
	(via
		(at 158.406592 -56.386476)
		(size 0.508)
		(drill 0.254)
		(layers "F.Cu" "B.Cu")
		(net "PVCCMCP_CPU1")
	)
	(via
		(at 124.793248 -81.164938)
		(size 0.508)
		(drill 0.254)
		(layers "F.Cu" "B.Cu")
		(net "PVCCMCP_CPU1")
	)
	(via
		(at 109.955076 -74.397616)
		(size 0.508)
		(drill 0.254)
		(layers "F.Cu" "B.Cu")
		(net "PVCCMCP_CPU1")
	)
	(via
		(at 107.059476 -74.397616)
		(size 0.508)
		(drill 0.254)
		(layers "F.Cu" "B.Cu")
		(net "PVCCMCP_CPU1")
	)
	(via
		(at 157.136592 -57.656476)
		(size 0.508)
		(drill 0.254)
		(layers "F.Cu" "B.Cu")
		(net "PVCCMCP_CPU1")
	)
	(via
		(at 126.510288 -76.211938)
		(size 0.508)
		(drill 0.254)
		(layers "F.Cu" "B.Cu")
		(net "PVCCMCP_CPU1")
	)
	(via
		(at 127.368808 -79.678784)
		(size 0.508)
		(drill 0.254)
		(layers "F.Cu" "B.Cu")
		(net "PVCCMCP_CPU1")
	)
	(via
		(at 155.866592 -53.211476)
		(size 0.508)
		(drill 0.254)
		(layers "F.Cu" "B.Cu")
		(net "PVCCMCP_CPU1")
	)
	(via
		(at 157.136592 -53.211476)
		(size 0.508)
		(drill 0.254)
		(layers "F.Cu" "B.Cu")
		(net "PVCCMCP_CPU1")
	)
	(via
		(at 120.216168 -67.296538)
		(size 0.508)
		(drill 0.254)
		(layers "F.Cu" "B.Cu")
		(net "PVCCMCP_CPU1")
	)
	(via
		(at 178.296824 -49.604676)
		(size 0.508)
		(drill 0.254)
		(layers "F.Cu" "B.Cu")
		(net "PVCCMCP_CPU1")
	)
	(via
		(at 180.1876 -49.723802)
		(size 0.508)
		(drill 0.254)
		(layers "F.Cu" "B.Cu")
		(net "PVCCMCP_CPU1")
	)
	(via
		(at 104.468676 -74.397616)
		(size 0.508)
		(drill 0.254)
		(layers "F.Cu" "B.Cu")
		(net "PVCCMCP_CPU1")
	)
	(via
		(at 110.717076 -78.715616)
		(size 0.508)
		(drill 0.254)
		(layers "F.Cu" "B.Cu")
		(net "PVCCMCP_CPU1")
	)
	(via
		(at 155.866592 -55.751476)
		(size 0.508)
		(drill 0.254)
		(layers "F.Cu" "B.Cu")
		(net "PVCCMCP_CPU1")
	)
	(via
		(at 124.793248 -78.193138)
		(size 0.508)
		(drill 0.254)
		(layers "F.Cu" "B.Cu")
		(net "PVCCMCP_CPU1")
	)
	(via
		(at 187.334144 -48.867568)
		(size 0.508)
		(drill 0.254)
		(layers "F.Cu" "B.Cu")
		(net "PVCCMCP_CPU1")
	)
	(via
		(at 123.076208 -90.080338)
		(size 0.508)
		(drill 0.254)
		(layers "F.Cu" "B.Cu")
		(net "PVCCMCP_CPU1")
	)
	(via
		(at 157.771592 -58.291476)
		(size 0.508)
		(drill 0.254)
		(layers "F.Cu" "B.Cu")
		(net "PVCCMCP_CPU1")
	)
	(via
		(at 121.074688 -67.791584)
		(size 0.508)
		(drill 0.254)
		(layers "F.Cu" "B.Cu")
		(net "PVCCMCP_CPU1")
	)
	(via
		(at 132.519674 -73.735184)
		(size 0.508)
		(drill 0.254)
		(layers "F.Cu" "B.Cu")
		(net "PVCCMCP_CPU1")
	)
	(via
		(at 112.559592 -78.699614)
		(size 0.508)
		(drill 0.254)
		(layers "F.Cu" "B.Cu")
		(net "PVCCMCP_CPU1")
	)
	(via
		(at 193.061336 -47.881032)
		(size 0.508)
		(drill 0.254)
		(layers "F.Cu" "B.Cu")
		(net "PVCCMCP_CPU1")
	)
	(via
		(at 127.368808 -82.650584)
		(size 0.508)
		(drill 0.254)
		(layers "F.Cu" "B.Cu")
		(net "PVCCMCP_CPU1")
	)
	(via
		(at 125.651768 -66.800984)
		(size 0.508)
		(drill 0.254)
		(layers "F.Cu" "B.Cu")
		(net "PVCCMCP_CPU1")
	)
	(via
		(at 152.5016 -57.6072)
		(size 0.508)
		(drill 0.254)
		(layers "F.Cu" "B.Cu")
		(net "PVCCMCP_CPU1")
	)
	(via
		(at 131.661408 -76.211938)
		(size 0.508)
		(drill 0.254)
		(layers "F.Cu" "B.Cu")
		(net "PVCCMCP_CPU1")
	)
	(via
		(at 110.717076 -74.397616)
		(size 0.508)
		(drill 0.254)
		(layers "F.Cu" "B.Cu")
		(net "PVCCMCP_CPU1")
	)
	(via
		(at 149.987 -54.102)
		(size 0.508)
		(drill 0.254)
		(layers "F.Cu" "B.Cu")
		(net "PVCCMCP_CPU1")
	)
	(via
		(at 122.217688 -68.782184)
		(size 0.508)
		(drill 0.254)
		(layers "F.Cu" "B.Cu")
		(net "PVCCMCP_CPU1")
	)
	(via
		(at 126.510288 -84.136738)
		(size 0.508)
		(drill 0.254)
		(layers "F.Cu" "B.Cu")
		(net "PVCCMCP_CPU1")
	)
	(via
		(at 186.849004 -47.74311)
		(size 0.508)
		(drill 0.254)
		(layers "F.Cu" "B.Cu")
		(net "PVCCMCP_CPU1")
	)
	(via
		(at 193.683382 -47.911004)
		(size 0.508)
		(drill 0.254)
		(layers "F.Cu" "B.Cu")
		(net "PVCCMCP_CPU1")
	)
	(via
		(at 154.596592 -57.021476)
		(size 0.508)
		(drill 0.254)
		(layers "F.Cu" "B.Cu")
		(net "PVCCMCP_CPU1")
	)
	(via
		(at 155.866592 -58.291476)
		(size 0.508)
		(drill 0.254)
		(layers "F.Cu" "B.Cu")
		(net "PVCCMCP_CPU1")
	)
	(via
		(at 126.510288 -80.174338)
		(size 0.508)
		(drill 0.254)
		(layers "F.Cu" "B.Cu")
		(net "PVCCMCP_CPU1")
	)
	(via
		(at 125.651768 -77.697584)
		(size 0.508)
		(drill 0.254)
		(layers "F.Cu" "B.Cu")
		(net "PVCCMCP_CPU1")
	)
	(via
		(at 157.771592 -56.386476)
		(size 0.508)
		(drill 0.254)
		(layers "F.Cu" "B.Cu")
		(net "PVCCMCP_CPU1")
	)
	(via
		(at 132.519674 -75.716384)
		(size 0.508)
		(drill 0.254)
		(layers "F.Cu" "B.Cu")
		(net "PVCCMCP_CPU1")
	)
	(via
		(at 179.712366 -49.0728)
		(size 0.508)
		(drill 0.254)
		(layers "F.Cu" "B.Cu")
		(net "PVCCMCP_CPU1")
	)
	(via
		(at 124.793248 -83.146138)
		(size 0.508)
		(drill 0.254)
		(layers "F.Cu" "B.Cu")
		(net "PVCCMCP_CPU1")
	)
	(via
		(at 155.866592 -57.021476)
		(size 0.508)
		(drill 0.254)
		(layers "F.Cu" "B.Cu")
		(net "PVCCMCP_CPU1")
	)
	(via
		(at 127.368808 -80.669384)
		(size 0.508)
		(drill 0.254)
		(layers "F.Cu" "B.Cu")
		(net "PVCCMCP_CPU1")
	)
	(via
		(at 155.866592 -54.481476)
		(size 0.508)
		(drill 0.254)
		(layers "F.Cu" "B.Cu")
		(net "PVCCMCP_CPU1")
	)
	(via
		(at 150.4442 -56.007)
		(size 0.508)
		(drill 0.254)
		(layers "F.Cu" "B.Cu")
		(net "PVCCMCP_CPU1")
	)
	(via
		(at 106.297476 -78.715616)
		(size 0.508)
		(drill 0.254)
		(layers "F.Cu" "B.Cu")
		(net "PVCCMCP_CPU1")
	)
	(via
		(at 156.501592 -57.656476)
		(size 0.508)
		(drill 0.254)
		(layers "F.Cu" "B.Cu")
		(net "PVCCMCP_CPU1")
	)
	(via
		(at 125.651768 -84.631784)
		(size 0.508)
		(drill 0.254)
		(layers "F.Cu" "B.Cu")
		(net "PVCCMCP_CPU1")
	)
	(via
		(at 121.359168 -84.136738)
		(size 0.508)
		(drill 0.254)
		(layers "F.Cu" "B.Cu")
		(net "PVCCMCP_CPU1")
	)
	(via
		(at 157.771592 -55.116476)
		(size 0.508)
		(drill 0.254)
		(layers "F.Cu" "B.Cu")
		(net "PVCCMCP_CPU1")
	)
	(via
		(at 192.444116 -47.869856)
		(size 0.508)
		(drill 0.254)
		(layers "F.Cu" "B.Cu")
		(net "PVCCMCP_CPU1")
	)
	(via
		(at 133.378194 -74.23023)
		(size 0.508)
		(drill 0.254)
		(layers "F.Cu" "B.Cu")
		(net "PVCCMCP_CPU1")
	)
	(via
		(at 133.378194 -73.240138)
		(size 0.508)
		(drill 0.254)
		(layers "F.Cu" "B.Cu")
		(net "PVCCMCP_CPU1")
	)
	(via
		(at 123.076208 -91.070938)
		(size 0.508)
		(drill 0.254)
		(layers "F.Cu" "B.Cu")
		(net "PVCCMCP_CPU1")
	)
	(via
		(at 123.934728 -85.622384)
		(size 0.508)
		(drill 0.254)
		(layers "F.Cu" "B.Cu")
		(net "PVCCMCP_CPU1")
	)
	(via
		(at 123.934728 -67.791584)
		(size 0.508)
		(drill 0.254)
		(layers "F.Cu" "B.Cu")
		(net "PVCCMCP_CPU1")
	)
	(via
		(at 123.076208 -85.127338)
		(size 0.508)
		(drill 0.254)
		(layers "F.Cu" "B.Cu")
		(net "PVCCMCP_CPU1")
	)
	(via
		(at 121.933208 -67.296538)
		(size 0.508)
		(drill 0.254)
		(layers "F.Cu" "B.Cu")
		(net "PVCCMCP_CPU1")
	)
	(via
		(at 153.531062 -51.557682)
		(size 0.508)
		(drill 0.254)
		(layers "F.Cu" "B.Cu")
		(net "PVCCMCP_CPU1")
	)
	(via
		(at 152.342342 -50.697384)
		(size 0.508)
		(drill 0.254)
		(layers "F.Cu" "B.Cu")
		(net "PVCCMCP_CPU1")
	)
	(via
		(at 158.406592 -57.021476)
		(size 0.508)
		(drill 0.254)
		(layers "F.Cu" "B.Cu")
		(net "PVCCMCP_CPU1")
	)
	(via
		(at 158.406592 -55.751476)
		(size 0.508)
		(drill 0.254)
		(layers "F.Cu" "B.Cu")
		(net "PVCCMCP_CPU1")
	)
	(via
		(at 123.076208 -78.193138)
		(size 0.508)
		(drill 0.254)
		(layers "F.Cu" "B.Cu")
		(net "PVCCMCP_CPU1")
	)
	(via
		(at 112.545876 -74.397616)
		(size 0.508)
		(drill 0.254)
		(layers "F.Cu" "B.Cu")
		(net "PVCCMCP_CPU1")
	)
	(via
		(at 190.542418 -47.87646)
		(size 0.508)
		(drill 0.254)
		(layers "F.Cu" "B.Cu")
		(net "PVCCMCP_CPU1")
	)
	(via
		(at 158.406592 -55.116476)
		(size 0.508)
		(drill 0.254)
		(layers "F.Cu" "B.Cu")
		(net "PVCCMCP_CPU1")
	)
	(via
		(at 155.009342 -50.163984)
		(size 0.508)
		(drill 0.254)
		(layers "F.Cu" "B.Cu")
		(net "PVCCMCP_CPU1")
	)
	(via
		(at 123.076208 -87.108538)
		(size 0.508)
		(drill 0.254)
		(layers "F.Cu" "B.Cu")
		(net "PVCCMCP_CPU1")
	)
	(via
		(at 123.076208 -86.117938)
		(size 0.508)
		(drill 0.254)
		(layers "F.Cu" "B.Cu")
		(net "PVCCMCP_CPU1")
	)
	(via
		(at 157.136592 -54.481476)
		(size 0.508)
		(drill 0.254)
		(layers "F.Cu" "B.Cu")
		(net "PVCCMCP_CPU1")
	)
	(via
		(at 123.934728 -84.631784)
		(size 0.508)
		(drill 0.254)
		(layers "F.Cu" "B.Cu")
		(net "PVCCMCP_CPU1")
	)
	(via
		(at 155.866592 -56.386476)
		(size 0.508)
		(drill 0.254)
		(layers "F.Cu" "B.Cu")
		(net "PVCCMCP_CPU1")
	)
	(via
		(at 183.417718 -49.631346)
		(size 0.508)
		(drill 0.254)
		(layers "F.Cu" "B.Cu")
		(net "PVCCMCP_CPU1")
	)
	(via
		(at 180.172614 -48.388778)
		(size 0.508)
		(drill 0.254)
		(layers "F.Cu" "B.Cu")
		(net "PVCCMCP_CPU1")
	)
	(via
		(at 191.187832 -47.86757)
		(size 0.508)
		(drill 0.254)
		(layers "F.Cu" "B.Cu")
		(net "PVCCMCP_CPU1")
	)
	(via
		(at 125.651768 -79.678784)
		(size 0.508)
		(drill 0.254)
		(layers "F.Cu" "B.Cu")
		(net "PVCCMCP_CPU1")
	)
	(via
		(at 149.987 -54.8132)
		(size 0.508)
		(drill 0.254)
		(layers "F.Cu" "B.Cu")
		(net "PVCCMCP_CPU1")
	)
	(via
		(at 123.934728 -83.641184)
		(size 0.508)
		(drill 0.254)
		(layers "F.Cu" "B.Cu")
		(net "PVCCMCP_CPU1")
	)
	(via
		(at 156.501592 -52.576476)
		(size 0.508)
		(drill 0.254)
		(layers "F.Cu" "B.Cu")
		(net "PVCCMCP_CPU1")
	)
	(via
		(at 157.771592 -52.576476)
		(size 0.508)
		(drill 0.254)
		(layers "F.Cu" "B.Cu")
		(net "PVCCMCP_CPU1")
	)
	(via
		(at 128.227328 -75.221338)
		(size 0.508)
		(drill 0.254)
		(layers "F.Cu" "B.Cu")
		(net "PVCCMCP_CPU1")
	)
	(via
		(at 109.955076 -78.715616)
		(size 0.508)
		(drill 0.254)
		(layers "F.Cu" "B.Cu")
		(net "PVCCMCP_CPU1")
	)
	(via
		(at 129.085848 -75.716384)
		(size 0.508)
		(drill 0.254)
		(layers "F.Cu" "B.Cu")
		(net "PVCCMCP_CPU1")
	)
	(via
		(at 186.325256 -48.079152)
		(size 0.508)
		(drill 0.254)
		(layers "F.Cu" "B.Cu")
		(net "PVCCMCP_CPU1")
	)
	(via
		(at 158.406592 -53.846476)
		(size 0.508)
		(drill 0.254)
		(layers "F.Cu" "B.Cu")
		(net "PVCCMCP_CPU1")
	)
	(via
		(at 191.832992 -47.845472)
		(size 0.508)
		(drill 0.254)
		(layers "F.Cu" "B.Cu")
		(net "PVCCMCP_CPU1")
	)
	(via
		(at 131.661408 -75.221338)
		(size 0.508)
		(drill 0.254)
		(layers "F.Cu" "B.Cu")
		(net "PVCCMCP_CPU1")
	)
	(via
		(at 181.98592 -49.4538)
		(size 0.508)
		(drill 0.254)
		(layers "F.Cu" "B.Cu")
		(net "PVCCMCP_CPU1")
	)
	(via
		(at 126.510288 -85.127338)
		(size 0.508)
		(drill 0.254)
		(layers "F.Cu" "B.Cu")
		(net "PVCCMCP_CPU1")
	)
	(via
		(at 157.771592 -53.846476)
		(size 0.508)
		(drill 0.254)
		(layers "F.Cu" "B.Cu")
		(net "PVCCMCP_CPU1")
	)
	(via
		(at 108.126276 -74.397616)
		(size 0.508)
		(drill 0.254)
		(layers "F.Cu" "B.Cu")
		(net "PVCCMCP_CPU1")
	)
	(via
		(at 187.279026 -48.200564)
		(size 0.508)
		(drill 0.254)
		(layers "F.Cu" "B.Cu")
		(net "PVCCMCP_CPU1")
	)
	(via
		(at 157.136592 -52.576476)
		(size 0.508)
		(drill 0.254)
		(layers "F.Cu" "B.Cu")
		(net "PVCCMCP_CPU1")
	)
	(via
		(at 156.501592 -55.116476)
		(size 0.508)
		(drill 0.254)
		(layers "F.Cu" "B.Cu")
		(net "PVCCMCP_CPU1")
	)
	(via
		(at 125.651768 -83.641184)
		(size 0.508)
		(drill 0.254)
		(layers "F.Cu" "B.Cu")
		(net "PVCCMCP_CPU1")
	)
	(via
		(at 194.311778 -47.900082)
		(size 0.508)
		(drill 0.254)
		(layers "F.Cu" "B.Cu")
		(net "PVCCMCP_CPU1")
	)
	(via
		(at 158.406592 -52.576476)
		(size 0.508)
		(drill 0.254)
		(layers "F.Cu" "B.Cu")
		(net "PVCCMCP_CPU1")
	)
	(via
		(at 185.71337 -48.071024)
		(size 0.508)
		(drill 0.254)
		(layers "F.Cu" "B.Cu")
		(net "PVCCMCP_CPU1")
	)
	(via
		(at 108.888276 -74.397616)
		(size 0.508)
		(drill 0.254)
		(layers "F.Cu" "B.Cu")
		(net "PVCCMCP_CPU1")
	)
	(via
		(at 153.961592 -58.291476)
		(size 0.508)
		(drill 0.254)
		(layers "F.Cu" "B.Cu")
		(net "PVCCMCP_CPU1")
	)
	(via
		(at 156.501592 -56.386476)
		(size 0.508)
		(drill 0.254)
		(layers "F.Cu" "B.Cu")
		(net "PVCCMCP_CPU1")
	)
	(via
		(at 121.359168 -86.117938)
		(size 0.508)
		(drill 0.254)
		(layers "F.Cu" "B.Cu")
		(net "PVCCMCP_CPU1")
	)
	(via
		(at 127.368808 -76.706984)
		(size 0.508)
		(drill 0.254)
		(layers "F.Cu" "B.Cu")
		(net "PVCCMCP_CPU1")
	)
	(via
		(at 157.136592 -58.291476)
		(size 0.508)
		(drill 0.254)
		(layers "F.Cu" "B.Cu")
		(net "PVCCMCP_CPU1")
	)
	(via
		(at 124.793248 -67.296538)
		(size 0.508)
		(drill 0.254)
		(layers "F.Cu" "B.Cu")
		(net "PVCCMCP_CPU1")
	)
	(via
		(at 155.231592 -52.576476)
		(size 0.508)
		(drill 0.254)
		(layers "F.Cu" "B.Cu")
		(net "PVCCMCP_CPU1")
	)
	(via
		(at 120.216168 -68.287138)
		(size 0.508)
		(drill 0.254)
		(layers "F.Cu" "B.Cu")
		(net "PVCCMCP_CPU1")
	)
	(via
		(at 193.105532 -47.263558)
		(size 0.508)
		(drill 0.254)
		(layers "F.Cu" "B.Cu")
		(net "PVCCMCP_CPU1")
	)
	(via
		(at 187.797186 -47.78375)
		(size 0.508)
		(drill 0.254)
		(layers "F.Cu" "B.Cu")
		(net "PVCCMCP_CPU1")
	)
	(via
		(at 132.519674 -74.725784)
		(size 0.508)
		(drill 0.254)
		(layers "F.Cu" "B.Cu")
		(net "PVCCMCP_CPU1")
	)
	(via
		(at 189.857126 -47.845472)
		(size 0.508)
		(drill 0.254)
		(layers "F.Cu" "B.Cu")
		(net "PVCCMCP_CPU1")
	)
	(via
		(at 179.046378 -48.676052)
		(size 0.508)
		(drill 0.254)
		(layers "F.Cu" "B.Cu")
		(net "PVCCMCP_CPU1")
	)
	(via
		(at 155.866592 -53.846476)
		(size 0.508)
		(drill 0.254)
		(layers "F.Cu" "B.Cu")
		(net "PVCCMCP_CPU1")
	)
	(via
		(at 124.793248 -85.127338)
		(size 0.508)
		(drill 0.254)
		(layers "F.Cu" "B.Cu")
		(net "PVCCMCP_CPU1")
	)
	(via
		(at 105.230676 -74.397616)
		(size 0.508)
		(drill 0.254)
		(layers "F.Cu" "B.Cu")
		(net "PVCCMCP_CPU1")
	)
	(via
		(at 155.898342 -49.986184)
		(size 0.508)
		(drill 0.254)
		(layers "F.Cu" "B.Cu")
		(net "PVCCMCP_CPU1")
	)
	(via
		(at 104.468676 -78.715616)
		(size 0.508)
		(drill 0.254)
		(layers "F.Cu" "B.Cu")
		(net "PVCCMCP_CPU1")
	)
	(via
		(at 121.359168 -85.127338)
		(size 0.508)
		(drill 0.254)
		(layers "F.Cu" "B.Cu")
		(net "PVCCMCP_CPU1")
	)
	(via
		(at 153.231342 -50.519584)
		(size 0.508)
		(drill 0.254)
		(layers "F.Cu" "B.Cu")
		(net "PVCCMCP_CPU1")
	)
	(via
		(at 193.717418 -47.291244)
		(size 0.508)
		(drill 0.254)
		(layers "F.Cu" "B.Cu")
		(net "PVCCMCP_CPU1")
	)
	(via
		(at 111.783876 -78.699614)
		(size 0.508)
		(drill 0.254)
		(layers "F.Cu" "B.Cu")
		(net "PVCCMCP_CPU1")
	)
	(via
		(at 154.596592 -51.941476)
		(size 0.508)
		(drill 0.254)
		(layers "F.Cu" "B.Cu")
		(net "PVCCMCP_CPU1")
	)
	(via
		(at 194.993768 -47.156116)
		(size 0.508)
		(drill 0.254)
		(layers "F.Cu" "B.Cu")
		(net "PVCCMCP_CPU1")
	)
	(via
		(at 130.802888 -75.716384)
		(size 0.508)
		(drill 0.254)
		(layers "F.Cu" "B.Cu")
		(net "PVCCMCP_CPU1")
	)
	(via
		(at 154.0256 -51.054)
		(size 0.508)
		(drill 0.254)
		(layers "F.Cu" "B.Cu")
		(net "PVCCMCP_CPU1")
	)
	(via
		(at 122.217688 -85.622384)
		(size 0.508)
		(drill 0.254)
		(layers "F.Cu" "B.Cu")
		(net "PVCCMCP_CPU1")
	)
	(via
		(at 181.390798 -49.703228)
		(size 0.508)
		(drill 0.254)
		(layers "F.Cu" "B.Cu")
		(net "PVCCMCP_CPU1")
	)
	(via
		(at 127.368808 -83.641184)
		(size 0.508)
		(drill 0.254)
		(layers "F.Cu" "B.Cu")
		(net "PVCCMCP_CPU1")
	)
	(via
		(at 155.231592 -58.291476)
		(size 0.508)
		(drill 0.254)
		(layers "F.Cu" "B.Cu")
		(net "PVCCMCP_CPU1")
	)
	(via
		(at 182.800244 -49.636934)
		(size 0.508)
		(drill 0.254)
		(layers "F.Cu" "B.Cu")
		(net "PVCCMCP_CPU1")
	)
	(segment
		(start 132.806694 -79.183738)
		(end 133.378194 -79.183738)
		(width 0.254)
		(layer "F.Cu")
		(net "PVCCIOMCP_CPU1")
	)
	(segment
		(start 127.655828 -79.183738)
		(end 128.227328 -79.183738)
		(width 0.254)
		(layer "F.Cu")
		(net "PVCCIOMCP_CPU1")
	)
	(segment
		(start 127.655828 -76.211938)
		(end 128.22682 -76.211938)
		(width 0.254)
		(layer "F.Cu")
		(net "PVCCIOMCP_CPU1")
	)
	(segment
		(start 133.665214 -79.678784)
		(end 134.236714 -79.678784)
		(width 0.254)
		(layer "F.Cu")
		(net "PVCCIOMCP_CPU1")
	)
	(segment
		(start 128.514348 -76.706984)
		(end 129.085848 -76.706984)
		(width 0.254)
		(layer "F.Cu")
		(net "PVCCIOMCP_CPU1")
	)
	(segment
		(start 127.655828 -77.202538)
		(end 128.227328 -77.202538)
		(width 0.254)
		(layer "F.Cu")
		(net "PVCCIOMCP_CPU1")
	)
	(segment
		(start 133.665214 -78.688438)
		(end 134.236714 -78.688438)
		(width 0.254)
		(layer "F.Cu")
		(net "PVCCIOMCP_CPU1")
	)
	(segment
		(start 134.236714 -77.697584)
		(end 133.665214 -77.697584)
		(width 0.254)
		(layer "F.Cu")
		(net "PVCCIOMCP_CPU1")
	)
	(segment
		(start 131.089908 -79.183738)
		(end 131.661408 -79.183738)
		(width 0.254)
		(layer "F.Cu")
		(net "PVCCIOMCP_CPU1")
	)
	(segment
		(start 128.22682 -76.211938)
		(end 128.227328 -76.21143)
		(width 0.254)
		(layer "F.Cu")
		(net "PVCCIOMCP_CPU1")
	)
	(segment
		(start 130.231388 -79.678784)
		(end 130.802888 -79.678784)
		(width 0.254)
		(layer "F.Cu")
		(net "PVCCIOMCP_CPU1")
	)
	(segment
		(start 131.089908 -77.202538)
		(end 131.661408 -77.202538)
		(width 0.254)
		(layer "F.Cu")
		(net "PVCCIOMCP_CPU1")
	)
	(segment
		(start 132.806694 -77.202538)
		(end 133.378194 -77.202538)
		(width 0.254)
		(layer "F.Cu")
		(net "PVCCIOMCP_CPU1")
	)
	(segment
		(start 128.514348 -77.697584)
		(end 129.085848 -77.697584)
		(width 0.254)
		(layer "F.Cu")
		(net "PVCCIOMCP_CPU1")
	)
	(segment
		(start 131.948174 -79.678784)
		(end 132.519674 -79.678784)
		(width 0.254)
		(layer "F.Cu")
		(net "PVCCIOMCP_CPU1")
	)
	(segment
		(start 130.231388 -78.688438)
		(end 130.802888 -78.688438)
		(width 0.254)
		(layer "F.Cu")
		(net "PVCCIOMCP_CPU1")
	)
	(segment
		(start 133.665214 -76.706984)
		(end 134.236714 -76.706984)
		(width 0.254)
		(layer "F.Cu")
		(net "PVCCIOMCP_CPU1")
	)
	(segment
		(start 132.806694 -78.193138)
		(end 133.378194 -78.193138)
		(width 0.254)
		(layer "F.Cu")
		(net "PVCCIOMCP_CPU1")
	)
	(segment
		(start 130.231388 -77.697584)
		(end 130.802888 -77.697584)
		(width 0.254)
		(layer "F.Cu")
		(net "PVCCIOMCP_CPU1")
	)
	(segment
		(start 131.948174 -77.697584)
		(end 132.519674 -77.697584)
		(width 0.254)
		(layer "F.Cu")
		(net "PVCCIOMCP_CPU1")
	)
	(segment
		(start 131.948174 -78.688438)
		(end 132.519674 -78.688438)
		(width 0.254)
		(layer "F.Cu")
		(net "PVCCIOMCP_CPU1")
	)
	(segment
		(start 131.089908 -78.193138)
		(end 131.661408 -78.193138)
		(width 0.254)
		(layer "F.Cu")
		(net "PVCCIOMCP_CPU1")
	)
	(via
		(at 132.519674 -77.697584)
		(size 0.508)
		(drill 0.254)
		(layers "F.Cu" "B.Cu")
		(net "PVCCIOMCP_CPU1")
	)
	(via
		(at 159.191198 -106.934)
		(size 0.508)
		(drill 0.254)
		(layers "F.Cu" "B.Cu")
		(net "PVCCIOMCP_CPU1")
	)
	(via
		(at 157.9372 -106.9594)
		(size 0.508)
		(drill 0.254)
		(layers "F.Cu" "B.Cu")
		(net "PVCCIOMCP_CPU1")
	)
	(via
		(at 193.122804 -105.198418)
		(size 0.508)
		(drill 0.254)
		(layers "F.Cu" "B.Cu")
		(net "PVCCIOMCP_CPU1")
	)
	(via
		(at 129.085848 -77.697584)
		(size 0.508)
		(drill 0.254)
		(layers "F.Cu" "B.Cu")
		(net "PVCCIOMCP_CPU1")
	)
	(via
		(at 158.6484 -106.5276)
		(size 0.508)
		(drill 0.254)
		(layers "F.Cu" "B.Cu")
		(net "PVCCIOMCP_CPU1")
	)
	(via
		(at 129.085848 -76.706984)
		(size 0.508)
		(drill 0.254)
		(layers "F.Cu" "B.Cu")
		(net "PVCCIOMCP_CPU1")
	)
	(via
		(at 133.378194 -79.183738)
		(size 0.508)
		(drill 0.254)
		(layers "F.Cu" "B.Cu")
		(net "PVCCIOMCP_CPU1")
	)
	(via
		(at 191.28359 -104.098852)
		(size 0.508)
		(drill 0.254)
		(layers "F.Cu" "B.Cu")
		(net "PVCCIOMCP_CPU1")
	)
	(via
		(at 157.4292 -105.7148)
		(size 0.508)
		(drill 0.254)
		(layers "F.Cu" "B.Cu")
		(net "PVCCIOMCP_CPU1")
	)
	(via
		(at 131.661408 -79.183738)
		(size 0.508)
		(drill 0.254)
		(layers "F.Cu" "B.Cu")
		(net "PVCCIOMCP_CPU1")
	)
	(via
		(at 128.227328 -79.183738)
		(size 0.508)
		(drill 0.254)
		(layers "F.Cu" "B.Cu")
		(net "PVCCIOMCP_CPU1")
	)
	(via
		(at 132.519674 -79.678784)
		(size 0.508)
		(drill 0.254)
		(layers "F.Cu" "B.Cu")
		(net "PVCCIOMCP_CPU1")
	)
	(via
		(at 130.802888 -77.697584)
		(size 0.508)
		(drill 0.254)
		(layers "F.Cu" "B.Cu")
		(net "PVCCIOMCP_CPU1")
	)
	(via
		(at 159.9184 -107.9754)
		(size 0.508)
		(drill 0.254)
		(layers "F.Cu" "B.Cu")
		(net "PVCCIOMCP_CPU1")
	)
	(via
		(at 158.0134 -106.1466)
		(size 0.508)
		(drill 0.254)
		(layers "F.Cu" "B.Cu")
		(net "PVCCIOMCP_CPU1")
	)
	(via
		(at 192.487804 -104.563418)
		(size 0.508)
		(drill 0.254)
		(layers "F.Cu" "B.Cu")
		(net "PVCCIOMCP_CPU1")
	)
	(via
		(at 134.236714 -78.688438)
		(size 0.508)
		(drill 0.254)
		(layers "F.Cu" "B.Cu")
		(net "PVCCIOMCP_CPU1")
	)
	(via
		(at 133.378194 -78.193138)
		(size 0.508)
		(drill 0.254)
		(layers "F.Cu" "B.Cu")
		(net "PVCCIOMCP_CPU1")
	)
	(via
		(at 193.122804 -104.563418)
		(size 0.508)
		(drill 0.254)
		(layers "F.Cu" "B.Cu")
		(net "PVCCIOMCP_CPU1")
	)
	(via
		(at 159.258 -107.552744)
		(size 0.508)
		(drill 0.254)
		(layers "F.Cu" "B.Cu")
		(net "PVCCIOMCP_CPU1")
	)
	(via
		(at 190.01359 -104.098852)
		(size 0.508)
		(drill 0.254)
		(layers "F.Cu" "B.Cu")
		(net "PVCCIOMCP_CPU1")
	)
	(via
		(at 134.236714 -76.706984)
		(size 0.508)
		(drill 0.254)
		(layers "F.Cu" "B.Cu")
		(net "PVCCIOMCP_CPU1")
	)
	(via
		(at 190.01359 -104.733852)
		(size 0.508)
		(drill 0.254)
		(layers "F.Cu" "B.Cu")
		(net "PVCCIOMCP_CPU1")
	)
	(via
		(at 157.39872 -107.3404)
		(size 0.508)
		(drill 0.254)
		(layers "F.Cu" "B.Cu")
		(net "PVCCIOMCP_CPU1")
	)
	(via
		(at 190.64859 -104.733852)
		(size 0.508)
		(drill 0.254)
		(layers "F.Cu" "B.Cu")
		(net "PVCCIOMCP_CPU1")
	)
	(via
		(at 142.898114 -88.594184)
		(size 0.508)
		(drill 0.254)
		(layers "F.Cu" "B.Cu")
		(net "PVCCIOMCP_CPU1")
	)
	(via
		(at 157.4038 -106.553)
		(size 0.508)
		(drill 0.254)
		(layers "F.Cu" "B.Cu")
		(net "PVCCIOMCP_CPU1")
	)
	(via
		(at 191.893698 -104.115362)
		(size 0.508)
		(drill 0.254)
		(layers "F.Cu" "B.Cu")
		(net "PVCCIOMCP_CPU1")
	)
	(via
		(at 158.2166 -107.7468)
		(size 0.508)
		(drill 0.254)
		(layers "F.Cu" "B.Cu")
		(net "PVCCIOMCP_CPU1")
	)
	(via
		(at 130.802888 -78.688438)
		(size 0.508)
		(drill 0.254)
		(layers "F.Cu" "B.Cu")
		(net "PVCCIOMCP_CPU1")
	)
	(via
		(at 128.227328 -76.21143)
		(size 0.508)
		(drill 0.254)
		(layers "F.Cu" "B.Cu")
		(net "PVCCIOMCP_CPU1")
	)
	(via
		(at 128.227328 -77.202538)
		(size 0.508)
		(drill 0.254)
		(layers "F.Cu" "B.Cu")
		(net "PVCCIOMCP_CPU1")
	)
	(via
		(at 131.661408 -77.202538)
		(size 0.508)
		(drill 0.254)
		(layers "F.Cu" "B.Cu")
		(net "PVCCIOMCP_CPU1")
	)
	(via
		(at 130.802888 -79.678784)
		(size 0.508)
		(drill 0.254)
		(layers "F.Cu" "B.Cu")
		(net "PVCCIOMCP_CPU1")
	)
	(via
		(at 133.378194 -77.202538)
		(size 0.508)
		(drill 0.254)
		(layers "F.Cu" "B.Cu")
		(net "PVCCIOMCP_CPU1")
	)
	(via
		(at 191.893698 -104.750362)
		(size 0.508)
		(drill 0.254)
		(layers "F.Cu" "B.Cu")
		(net "PVCCIOMCP_CPU1")
	)
	(via
		(at 192.487804 -105.198418)
		(size 0.508)
		(drill 0.254)
		(layers "F.Cu" "B.Cu")
		(net "PVCCIOMCP_CPU1")
	)
	(via
		(at 190.64859 -104.098852)
		(size 0.508)
		(drill 0.254)
		(layers "F.Cu" "B.Cu")
		(net "PVCCIOMCP_CPU1")
	)
	(via
		(at 132.519674 -78.688438)
		(size 0.508)
		(drill 0.254)
		(layers "F.Cu" "B.Cu")
		(net "PVCCIOMCP_CPU1")
	)
	(via
		(at 134.236714 -79.678784)
		(size 0.508)
		(drill 0.254)
		(layers "F.Cu" "B.Cu")
		(net "PVCCIOMCP_CPU1")
	)
	(via
		(at 158.5722 -107.2134)
		(size 0.508)
		(drill 0.254)
		(layers "F.Cu" "B.Cu")
		(net "PVCCIOMCP_CPU1")
	)
	(via
		(at 134.236714 -77.697584)
		(size 0.508)
		(drill 0.254)
		(layers "F.Cu" "B.Cu")
		(net "PVCCIOMCP_CPU1")
	)
	(via
		(at 191.28359 -104.733852)
		(size 0.508)
		(drill 0.254)
		(layers "F.Cu" "B.Cu")
		(net "PVCCIOMCP_CPU1")
	)
	(via
		(at 131.661408 -78.193138)
		(size 0.508)
		(drill 0.254)
		(layers "F.Cu" "B.Cu")
		(net "PVCCIOMCP_CPU1")
	)
	(via
		(at 158.8008 -108.0516)
		(size 0.508)
		(drill 0.254)
		(layers "F.Cu" "B.Cu")
		(net "PVCCIOMCP_CPU1")
	)
	(segment
		(start 146.7866 -48.006)
		(end 148.1582 -49.3776)
		(width 0.254)
		(layer "F.Cu")
		(net "P1V8_MCP_CPU1")
	)
	(segment
		(start 146.7866 -45.2628)
		(end 146.7866 -48.006)
		(width 0.254)
		(layer "F.Cu")
		(net "P1V8_MCP_CPU1")
	)
	(segment
		(start 148.1582 -57.912)
		(end 155.6131 -65.3669)
		(width 0.254)
		(layer "F.Cu")
		(net "P1V8_MCP_CPU1")
	)
	(segment
		(start 155.6131 -71.7931)
		(end 158.3817 -74.5617)
		(width 0.254)
		(layer "F.Cu")
		(net "P1V8_MCP_CPU1")
	)
	(segment
		(start 148.1582 -49.3776)
		(end 148.1582 -57.912)
		(width 0.254)
		(layer "F.Cu")
		(net "P1V8_MCP_CPU1")
	)
	(segment
		(start 119.929402 -80.669384)
		(end 119.357902 -80.669384)
		(width 0.381)
		(layer "F.Cu")
		(net "P1V8_MCP_CPU1")
	)
	(segment
		(start 119.929402 -79.678784)
		(end 119.357902 -79.678784)
		(width 0.381)
		(layer "F.Cu")
		(net "P1V8_MCP_CPU1")
	)
	(segment
		(start 119.929402 -78.688438)
		(end 119.357902 -78.688438)
		(width 0.1016)
		(layer "F.Cu")
		(net "P1V8_MCP_CPU1")
	)
	(segment
		(start 158.3817 -74.5617)
		(end 159.7533 -74.5617)
		(width 0.254)
		(layer "F.Cu")
		(net "P1V8_MCP_CPU1")
	)
	(segment
		(start 120.787668 -79.183738)
		(end 121.359168 -79.183738)
		(width 0.1016)
		(layer "F.Cu")
		(net "P1V8_MCP_CPU1")
	)
	(segment
		(start 155.6131 -65.3669)
		(end 155.6131 -71.7931)
		(width 0.254)
		(layer "F.Cu")
		(net "P1V8_MCP_CPU1")
	)
	(via
		(at 159.682942 -36.250372)
		(size 0.508)
		(drill 0.254)
		(layers "F.Cu" "B.Cu")
		(net "P1V8_MCP_CPU1")
	)
	(via
		(at 166.25697 -36.117022)
		(size 0.508)
		(drill 0.254)
		(layers "F.Cu" "B.Cu")
		(net "P1V8_MCP_CPU1")
	)
	(via
		(at 162.349942 -35.716972)
		(size 0.508)
		(drill 0.254)
		(layers "F.Cu" "B.Cu")
		(net "P1V8_MCP_CPU1")
	)
	(via
		(at 153.93924 -39.5097)
		(size 0.762)
		(drill 0.381)
		(layers "F.Cu" "B.Cu")
		(net "P1V8_MCP_CPU1")
	)
	(via
		(at 160.571942 -36.072572)
		(size 0.508)
		(drill 0.254)
		(layers "F.Cu" "B.Cu")
		(net "P1V8_MCP_CPU1")
	)
	(via
		(at 119.357902 -80.669384)
		(size 0.508)
		(drill 0.254)
		(layers "F.Cu" "B.Cu")
		(net "P1V8_MCP_CPU1")
	)
	(via
		(at 150.1013 -36.66236)
		(size 0.762)
		(drill 0.381)
		(layers "F.Cu" "B.Cu")
		(net "P1V8_MCP_CPU1")
	)
	(via
		(at 161.460942 -35.894772)
		(size 0.508)
		(drill 0.254)
		(layers "F.Cu" "B.Cu")
		(net "P1V8_MCP_CPU1")
	)
	(via
		(at 165.36797 -36.294822)
		(size 0.508)
		(drill 0.254)
		(layers "F.Cu" "B.Cu")
		(net "P1V8_MCP_CPU1")
	)
	(via
		(at 156.2862 -116.3066)
		(size 0.508)
		(drill 0.254)
		(layers "F.Cu" "B.Cu")
		(net "P1V8_MCP_CPU1")
	)
	(via
		(at 119.357902 -78.688438)
		(size 0.508)
		(drill 0.254)
		(layers "F.Cu" "B.Cu")
		(net "P1V8_MCP_CPU1")
	)
	(via
		(at 121.359168 -79.183738)
		(size 0.508)
		(drill 0.254)
		(layers "F.Cu" "B.Cu")
		(net "P1V8_MCP_CPU1")
	)
	(via
		(at 154.39136 -36.56076)
		(size 0.762)
		(drill 0.381)
		(layers "F.Cu" "B.Cu")
		(net "P1V8_MCP_CPU1")
	)
	(via
		(at 152.11552 -37.33546)
		(size 0.762)
		(drill 0.381)
		(layers "F.Cu" "B.Cu")
		(net "P1V8_MCP_CPU1")
	)
	(via
		(at 163.58997 -36.701222)
		(size 0.508)
		(drill 0.254)
		(layers "F.Cu" "B.Cu")
		(net "P1V8_MCP_CPU1")
	)
	(via
		(at 164.47897 -36.485322)
		(size 0.508)
		(drill 0.254)
		(layers "F.Cu" "B.Cu")
		(net "P1V8_MCP_CPU1")
	)
	(via
		(at 163.238942 -35.511994)
		(size 0.508)
		(drill 0.254)
		(layers "F.Cu" "B.Cu")
		(net "P1V8_MCP_CPU1")
	)
	(via
		(at 119.357902 -79.678784)
		(size 0.508)
		(drill 0.254)
		(layers "F.Cu" "B.Cu")
		(net "P1V8_MCP_CPU1")
	)
	(via
		(at 159.7533 -74.5617)
		(size 0.508)
		(drill 0.254)
		(layers "F.Cu" "B.Cu")
		(net "P1V8_MCP_CPU1")
	)
	(via
		(at 151.90978 -34.80816)
		(size 0.762)
		(drill 0.381)
		(layers "F.Cu" "B.Cu")
		(net "P1V8_MCP_CPU1")
	)
	(via
		(at 167.14597 -35.939222)
		(size 0.508)
		(drill 0.254)
		(layers "F.Cu" "B.Cu")
		(net "P1V8_MCP_CPU1")
	)
	(segment
		(start 165.402768 -131.0259)
		(end 165.1127 -130.735832)
		(width 0.254)
		(layer "B.Cu")
		(net "P1V8_MCP_CPU1")
	)
	(segment
		(start 171.059856 -129.093976)
		(end 169.127932 -131.0259)
		(width 0.254)
		(layer "B.Cu")
		(net "P1V8_MCP_CPU1")
	)
	(segment
		(start 161.750248 -121.441718)
		(end 164.154358 -121.441718)
		(width 0.254)
		(layer "B.Cu")
		(net "P1V8_MCP_CPU1")
	)
	(segment
		(start 159.831024 -120.8151)
		(end 161.12363 -120.8151)
		(width 0.254)
		(layer "B.Cu")
		(net "P1V8_MCP_CPU1")
	)
	(segment
		(start 169.051986 -128.335786)
		(end 169.051986 -128.905)
		(width 0.254)
		(layer "B.Cu")
		(net "P1V8_MCP_CPU1")
	)
	(segment
		(start 156.2862 -116.3066)
		(end 157.1498 -117.1702)
		(width 0.254)
		(layer "B.Cu")
		(net "P1V8_MCP_CPU1")
	)
	(segment
		(start 169.051986 -129.321814)
		(end 169.051986 -128.905)
		(width 0.254)
		(layer "B.Cu")
		(net "P1V8_MCP_CPU1")
	)
	(segment
		(start 161.12363 -120.8151)
		(end 161.750248 -121.441718)
		(width 0.254)
		(layer "B.Cu")
		(net "P1V8_MCP_CPU1")
	)
	(segment
		(start 169.127932 -131.0259)
		(end 165.402768 -131.0259)
		(width 0.254)
		(layer "B.Cu")
		(net "P1V8_MCP_CPU1")
	)
	(segment
		(start 159.09544 -118.20652)
		(end 159.09544 -120.079516)
		(width 0.254)
		(layer "B.Cu")
		(net "P1V8_MCP_CPU1")
	)
	(segment
		(start 166.751 -126.8984)
		(end 167.9448 -128.0922)
		(width 0.254)
		(layer "B.Cu")
		(net "P1V8_MCP_CPU1")
	)
	(segment
		(start 168.7068 -129.667)
		(end 169.051986 -129.321814)
		(width 0.254)
		(layer "B.Cu")
		(net "P1V8_MCP_CPU1")
	)
	(segment
		(start 167.9448 -128.0922)
		(end 168.8084 -128.0922)
		(width 0.254)
		(layer "B.Cu")
		(net "P1V8_MCP_CPU1")
	)
	(segment
		(start 171.059856 -128.850136)
		(end 171.059856 -129.093976)
		(width 0.254)
		(layer "B.Cu")
		(net "P1V8_MCP_CPU1")
	)
	(segment
		(start 164.154358 -121.441718)
		(end 165.885114 -123.172474)
		(width 0.254)
		(layer "B.Cu")
		(net "P1V8_MCP_CPU1")
	)
	(segment
		(start 159.09544 -120.079516)
		(end 159.831024 -120.8151)
		(width 0.254)
		(layer "B.Cu")
		(net "P1V8_MCP_CPU1")
	)
	(segment
		(start 165.885114 -124.889514)
		(end 166.751 -125.7554)
		(width 0.254)
		(layer "B.Cu")
		(net "P1V8_MCP_CPU1")
	)
	(segment
		(start 165.415468 -130.0226)
		(end 167.7162 -130.0226)
		(width 0.254)
		(layer "B.Cu")
		(net "P1V8_MCP_CPU1")
	)
	(segment
		(start 168.0718 -129.667)
		(end 168.7068 -129.667)
		(width 0.254)
		(layer "B.Cu")
		(net "P1V8_MCP_CPU1")
	)
	(segment
		(start 157.1498 -117.1702)
		(end 158.05912 -117.1702)
		(width 0.254)
		(layer "B.Cu")
		(net "P1V8_MCP_CPU1")
	)
	(segment
		(start 158.05912 -117.1702)
		(end 159.09544 -118.20652)
		(width 0.254)
		(layer "B.Cu")
		(net "P1V8_MCP_CPU1")
	)
	(segment
		(start 167.7162 -130.0226)
		(end 168.0718 -129.667)
		(width 0.254)
		(layer "B.Cu")
		(net "P1V8_MCP_CPU1")
	)
	(segment
		(start 166.751 -125.7554)
		(end 166.751 -126.8984)
		(width 0.254)
		(layer "B.Cu")
		(net "P1V8_MCP_CPU1")
	)
	(segment
		(start 165.1127 -130.325368)
		(end 165.415468 -130.0226)
		(width 0.254)
		(layer "B.Cu")
		(net "P1V8_MCP_CPU1")
	)
	(segment
		(start 165.1127 -130.735832)
		(end 165.1127 -130.325368)
		(width 0.254)
		(layer "B.Cu")
		(net "P1V8_MCP_CPU1")
	)
	(segment
		(start 165.885114 -123.172474)
		(end 165.885114 -124.889514)
		(width 0.254)
		(layer "B.Cu")
		(net "P1V8_MCP_CPU1")
	)
	(segment
		(start 168.8084 -128.0922)
		(end 169.051986 -128.335786)
		(width 0.254)
		(layer "B.Cu")
		(net "P1V8_MCP_CPU1")
	)
	(segment
		(start 161.004504 -101.568504)
		(end 161.004504 -108.30433)
		(width 0.254)
		(layer "In2.Cu")
		(net "P1V8_MCP_CPU1")
	)
	(segment
		(start 156.051504 -113.25733)
		(end 156.051504 -116.071904)
		(width 0.254)
		(layer "In2.Cu")
		(net "P1V8_MCP_CPU1")
	)
	(segment
		(start 156.051504 -116.071904)
		(end 156.2862 -116.3066)
		(width 0.254)
		(layer "In2.Cu")
		(net "P1V8_MCP_CPU1")
	)
	(segment
		(start 161.004504 -108.30433)
		(end 156.051504 -113.25733)
		(width 0.254)
		(layer "In2.Cu")
		(net "P1V8_MCP_CPU1")
	)
	(segment
		(start 158.540704 -99.104704)
		(end 161.004504 -101.568504)
		(width 0.254)
		(layer "In2.Cu")
		(net "P1V8_MCP_CPU1")
	)
	(segment
		(start 158.540704 -75.774296)
		(end 158.540704 -99.104704)
		(width 0.254)
		(layer "In2.Cu")
		(net "P1V8_MCP_CPU1")
	)
	(segment
		(start 159.7533 -74.5617)
		(end 158.540704 -75.774296)
		(width 0.254)
		(layer "In2.Cu")
		(net "P1V8_MCP_CPU1")
	)
	(segment
		(start 417.284916 -91.9988)
		(end 417.500816 -91.7829)
		(width 0.101854)
		(layer "F.Cu")
		(net "KR_P0_OCP_RX_C_DP")
	)
	(segment
		(start 416.627564 -91.567)
		(end 416.627564 -91.717622)
		(width 0.101854)
		(layer "F.Cu")
		(net "KR_P0_OCP_RX_C_DP")
	)
	(segment
		(start 417.500816 -91.7829)
		(end 417.9062 -91.7829)
		(width 0.101854)
		(layer "F.Cu")
		(net "KR_P0_OCP_RX_C_DP")
	)
	(segment
		(start 394.67155 -107.27944)
		(end 395.16685 -107.049316)
		(width 0.10033)
		(layer "F.Cu")
		(net "KR_P0_OCP_RX_C_DP")
	)
	(segment
		(start 416.908742 -91.9988)
		(end 417.284916 -91.9988)
		(width 0.101854)
		(layer "F.Cu")
		(net "KR_P0_OCP_RX_C_DP")
	)
	(segment
		(start 416.627564 -91.717622)
		(end 416.908742 -91.9988)
		(width 0.101854)
		(layer "F.Cu")
		(net "KR_P0_OCP_RX_C_DP")
	)
	(via
		(at 395.16685 -107.049316)
		(size 0.508)
		(drill 0.254)
		(layers "F.Cu" "B.Cu")
		(net "KR_P0_OCP_RX_C_DP")
	)
	(via
		(at 416.627564 -91.567)
		(size 0.508)
		(drill 0.254)
		(layers "F.Cu" "B.Cu")
		(net "KR_P0_OCP_RX_C_DP")
	)
	(segment
		(start 409.617926 -106.10088)
		(end 402.461476 -106.10088)
		(width 0.101346)
		(layer "In9.Cu")
		(net "KR_P0_OCP_RX_C_DP")
	)
	(segment
		(start 415.757614 -91.939872)
		(end 415.283142 -92.414344)
		(width 0.101346)
		(layer "In9.Cu")
		(net "KR_P0_OCP_RX_C_DP")
	)
	(segment
		(start 416.627564 -91.567)
		(end 416.627564 -91.838526)
		(width 0.101346)
		(layer "In9.Cu")
		(net "KR_P0_OCP_RX_C_DP")
	)
	(segment
		(start 399.625058 -107.316778)
		(end 399.624804 -107.316524)
		(width 0.089154)
		(layer "In9.Cu")
		(net "KR_P0_OCP_RX_C_DP")
	)
	(segment
		(start 413.103314 -99.281996)
		(end 413.103314 -102.615492)
		(width 0.101346)
		(layer "In9.Cu")
		(net "KR_P0_OCP_RX_C_DP")
	)
	(segment
		(start 413.103314 -102.615492)
		(end 409.617926 -106.10088)
		(width 0.101346)
		(layer "In9.Cu")
		(net "KR_P0_OCP_RX_C_DP")
	)
	(segment
		(start 416.526218 -91.939872)
		(end 415.757614 -91.939872)
		(width 0.101346)
		(layer "In9.Cu")
		(net "KR_P0_OCP_RX_C_DP")
	)
	(segment
		(start 416.627564 -91.838526)
		(end 416.526218 -91.939872)
		(width 0.101346)
		(layer "In9.Cu")
		(net "KR_P0_OCP_RX_C_DP")
	)
	(segment
		(start 401.367498 -107.194858)
		(end 400.083782 -107.194858)
		(width 0.101346)
		(layer "In9.Cu")
		(net "KR_P0_OCP_RX_C_DP")
	)
	(segment
		(start 395.504924 -107.049316)
		(end 395.16685 -107.049316)
		(width 0.089154)
		(layer "In9.Cu")
		(net "KR_P0_OCP_RX_C_DP")
	)
	(segment
		(start 415.283142 -95.987108)
		(end 414.540446 -96.729804)
		(width 0.101346)
		(layer "In9.Cu")
		(net "KR_P0_OCP_RX_C_DP")
	)
	(segment
		(start 399.329148 -107.396026)
		(end 399.329148 -107.395772)
		(width 0.089154)
		(layer "In9.Cu")
		(net "KR_P0_OCP_RX_C_DP")
	)
	(segment
		(start 402.461476 -106.10088)
		(end 401.367498 -107.194858)
		(width 0.101346)
		(layer "In9.Cu")
		(net "KR_P0_OCP_RX_C_DP")
	)
	(segment
		(start 414.540446 -96.729804)
		(end 414.540446 -97.844864)
		(width 0.101346)
		(layer "In9.Cu")
		(net "KR_P0_OCP_RX_C_DP")
	)
	(segment
		(start 399.961862 -107.316778)
		(end 399.625058 -107.316778)
		(width 0.089154)
		(layer "In9.Cu")
		(net "KR_P0_OCP_RX_C_DP")
	)
	(segment
		(start 415.283142 -92.414344)
		(end 415.283142 -95.987108)
		(width 0.101346)
		(layer "In9.Cu")
		(net "KR_P0_OCP_RX_C_DP")
	)
	(segment
		(start 395.569694 -106.984546)
		(end 395.504924 -107.049316)
		(width 0.089154)
		(layer "In9.Cu")
		(net "KR_P0_OCP_RX_C_DP")
	)
	(segment
		(start 400.083782 -107.194858)
		(end 399.961862 -107.316778)
		(width 0.089154)
		(layer "In9.Cu")
		(net "KR_P0_OCP_RX_C_DP")
	)
	(segment
		(start 399.624804 -107.316524)
		(end 399.624804 -107.316778)
		(width 0.089154)
		(layer "In9.Cu")
		(net "KR_P0_OCP_RX_C_DP")
	)
	(segment
		(start 399.624804 -107.316778)
		(end 399.62455 -107.316778)
		(width 0.089154)
		(layer "In9.Cu")
		(net "KR_P0_OCP_RX_C_DP")
	)
	(segment
		(start 414.540446 -97.844864)
		(end 413.103314 -99.281996)
		(width 0.101346)
		(layer "In9.Cu")
		(net "KR_P0_OCP_RX_C_DP")
	)
	(segment
		(start 396.748254 -107.061508)
		(end 396.748254 -107.028742)
		(width 0.089154)
		(layer "In9.Cu")
		(net "KR_P0_OCP_RX_C_DP")
	)
	(arc
		(start 397.347948 -107.395772)
		(mid 397.14805 -107.449305)
		(end 396.948152 -107.395772)
		(width 0.089154)
		(layer "In9.Cu")
		(net "KR_P0_OCP_RX_C_DP")
	)
	(arc
		(start 396.948152 -107.395772)
		(mid 396.804767 -107.254615)
		(end 396.748254 -107.061508)
		(width 0.089154)
		(layer "In9.Cu")
		(net "KR_P0_OCP_RX_C_DP")
	)
	(arc
		(start 398.929352 -107.395772)
		(mid 398.63395 -107.316675)
		(end 398.338548 -107.395772)
		(width 0.089154)
		(layer "In9.Cu")
		(net "KR_P0_OCP_RX_C_DP")
	)
	(arc
		(start 399.329148 -107.395772)
		(mid 399.12925 -107.449305)
		(end 398.929352 -107.395772)
		(width 0.089154)
		(layer "In9.Cu")
		(net "KR_P0_OCP_RX_C_DP")
	)
	(arc
		(start 396.748254 -107.028742)
		(mid 396.664136 -106.744781)
		(end 396.452852 -106.537252)
		(width 0.089154)
		(layer "In9.Cu")
		(net "KR_P0_OCP_RX_C_DP")
	)
	(arc
		(start 399.62455 -107.316778)
		(mid 399.471626 -107.336916)
		(end 399.329148 -107.396026)
		(width 0.089154)
		(layer "In9.Cu")
		(net "KR_P0_OCP_RX_C_DP")
	)
	(arc
		(start 397.938752 -107.395772)
		(mid 397.64335 -107.316675)
		(end 397.347948 -107.395772)
		(width 0.089154)
		(layer "In9.Cu")
		(net "KR_P0_OCP_RX_C_DP")
	)
	(arc
		(start 396.452852 -106.537252)
		(mid 396.15745 -106.458155)
		(end 395.862048 -106.537252)
		(width 0.089154)
		(layer "In9.Cu")
		(net "KR_P0_OCP_RX_C_DP")
	)
	(arc
		(start 398.338548 -107.395772)
		(mid 398.13865 -107.449305)
		(end 397.938752 -107.395772)
		(width 0.089154)
		(layer "In9.Cu")
		(net "KR_P0_OCP_RX_C_DP")
	)
	(arc
		(start 395.862048 -106.537252)
		(mid 395.662449 -106.725978)
		(end 395.569694 -106.984546)
		(width 0.089154)
		(layer "In9.Cu")
		(net "KR_P0_OCP_RX_C_DP")
	)
	(segment
		(start 417.500816 -92.6719)
		(end 417.9062 -92.6719)
		(width 0.101854)
		(layer "F.Cu")
		(net "KR_P0_OCP_RX_C_DN")
	)
	(segment
		(start 417.00704 -92.457524)
		(end 417.28644 -92.457524)
		(width 0.101854)
		(layer "F.Cu")
		(net "KR_P0_OCP_RX_C_DN")
	)
	(segment
		(start 395.66215 -107.27944)
		(end 396.15745 -107.049316)
		(width 0.10033)
		(layer "F.Cu")
		(net "KR_P0_OCP_RX_C_DN")
	)
	(segment
		(start 417.28644 -92.457524)
		(end 417.500816 -92.6719)
		(width 0.101854)
		(layer "F.Cu")
		(net "KR_P0_OCP_RX_C_DN")
	)
	(segment
		(start 416.627564 -92.837)
		(end 417.00704 -92.457524)
		(width 0.101854)
		(layer "F.Cu")
		(net "KR_P0_OCP_RX_C_DN")
	)
	(via
		(at 416.627564 -92.837)
		(size 0.508)
		(drill 0.254)
		(layers "F.Cu" "B.Cu")
		(net "KR_P0_OCP_RX_C_DN")
	)
	(via
		(at 396.15745 -107.049316)
		(size 0.508)
		(drill 0.254)
		(layers "F.Cu" "B.Cu")
		(net "KR_P0_OCP_RX_C_DN")
	)
	(segment
		(start 405.03348 -106.825542)
		(end 404.729442 -106.825542)
		(width 0.101346)
		(layer "In9.Cu")
		(net "KR_P0_OCP_RX_C_DN")
	)
	(segment
		(start 413.522668 -102.789228)
		(end 409.791662 -106.520234)
		(width 0.101346)
		(layer "In9.Cu")
		(net "KR_P0_OCP_RX_C_DN")
	)
	(segment
		(start 416.526218 -92.359226)
		(end 415.93135 -92.359226)
		(width 0.101346)
		(layer "In9.Cu")
		(net "KR_P0_OCP_RX_C_DN")
	)
	(segment
		(start 416.627564 -92.460572)
		(end 416.526218 -92.359226)
		(width 0.101346)
		(layer "In9.Cu")
		(net "KR_P0_OCP_RX_C_DN")
	)
	(segment
		(start 415.702496 -96.160844)
		(end 414.9598 -96.90354)
		(width 0.101346)
		(layer "In9.Cu")
		(net "KR_P0_OCP_RX_C_DN")
	)
	(segment
		(start 415.702496 -92.58808)
		(end 415.702496 -96.160844)
		(width 0.101346)
		(layer "In9.Cu")
		(net "KR_P0_OCP_RX_C_DN")
	)
	(segment
		(start 414.9598 -96.90354)
		(end 414.9598 -98.0186)
		(width 0.101346)
		(layer "In9.Cu")
		(net "KR_P0_OCP_RX_C_DN")
	)
	(segment
		(start 409.791662 -106.520234)
		(end 405.338788 -106.520234)
		(width 0.101346)
		(layer "In9.Cu")
		(net "KR_P0_OCP_RX_C_DN")
	)
	(segment
		(start 395.819376 -107.049316)
		(end 396.15745 -107.049316)
		(width 0.089154)
		(layer "In9.Cu")
		(net "KR_P0_OCP_RX_C_DN")
	)
	(segment
		(start 416.627564 -92.837)
		(end 416.627564 -92.460572)
		(width 0.101346)
		(layer "In9.Cu")
		(net "KR_P0_OCP_RX_C_DN")
	)
	(segment
		(start 401.541234 -107.614212)
		(end 400.083782 -107.614212)
		(width 0.101346)
		(layer "In9.Cu")
		(net "KR_P0_OCP_RX_C_DN")
	)
	(segment
		(start 400.083782 -107.614212)
		(end 399.977102 -107.507532)
		(width 0.089154)
		(layer "In9.Cu")
		(net "KR_P0_OCP_RX_C_DN")
	)
	(segment
		(start 399.977102 -107.507532)
		(end 399.62455 -107.507532)
		(width 0.089154)
		(layer "In9.Cu")
		(net "KR_P0_OCP_RX_C_DN")
	)
	(segment
		(start 404.424134 -106.520234)
		(end 402.635212 -106.520234)
		(width 0.101346)
		(layer "In9.Cu")
		(net "KR_P0_OCP_RX_C_DN")
	)
	(segment
		(start 415.93135 -92.359226)
		(end 415.702496 -92.58808)
		(width 0.101346)
		(layer "In9.Cu")
		(net "KR_P0_OCP_RX_C_DN")
	)
	(segment
		(start 413.522668 -99.455732)
		(end 413.522668 -102.789228)
		(width 0.101346)
		(layer "In9.Cu")
		(net "KR_P0_OCP_RX_C_DN")
	)
	(segment
		(start 405.338788 -106.520234)
		(end 405.03348 -106.825542)
		(width 0.101346)
		(layer "In9.Cu")
		(net "KR_P0_OCP_RX_C_DN")
	)
	(segment
		(start 402.635212 -106.520234)
		(end 401.541234 -107.614212)
		(width 0.101346)
		(layer "In9.Cu")
		(net "KR_P0_OCP_RX_C_DN")
	)
	(segment
		(start 395.761718 -106.991658)
		(end 395.819376 -107.049316)
		(width 0.089154)
		(layer "In9.Cu")
		(net "KR_P0_OCP_RX_C_DN")
	)
	(segment
		(start 414.9598 -98.0186)
		(end 413.522668 -99.455732)
		(width 0.101346)
		(layer "In9.Cu")
		(net "KR_P0_OCP_RX_C_DN")
	)
	(segment
		(start 404.729442 -106.825542)
		(end 404.424134 -106.520234)
		(width 0.101346)
		(layer "In9.Cu")
		(net "KR_P0_OCP_RX_C_DN")
	)
	(segment
		(start 396.557246 -107.06989)
		(end 396.557246 -107.037124)
		(width 0.089154)
		(layer "In9.Cu")
		(net "KR_P0_OCP_RX_C_DN")
	)
	(arc
		(start 397.843248 -107.56138)
		(mid 397.64335 -107.507847)
		(end 397.443452 -107.56138)
		(width 0.089154)
		(layer "In9.Cu")
		(net "KR_P0_OCP_RX_C_DN")
	)
	(arc
		(start 398.833848 -107.56138)
		(mid 398.63395 -107.507847)
		(end 398.434052 -107.56138)
		(width 0.089154)
		(layer "In9.Cu")
		(net "KR_P0_OCP_RX_C_DN")
	)
	(arc
		(start 395.957552 -106.70286)
		(mid 395.826442 -106.824762)
		(end 395.761718 -106.991658)
		(width 0.089154)
		(layer "In9.Cu")
		(net "KR_P0_OCP_RX_C_DN")
	)
	(arc
		(start 399.62455 -107.507532)
		(mid 399.521037 -107.521228)
		(end 399.424652 -107.56138)
		(width 0.089154)
		(layer "In9.Cu")
		(net "KR_P0_OCP_RX_C_DN")
	)
	(arc
		(start 398.434052 -107.56138)
		(mid 398.13865 -107.640477)
		(end 397.843248 -107.56138)
		(width 0.089154)
		(layer "In9.Cu")
		(net "KR_P0_OCP_RX_C_DN")
	)
	(arc
		(start 396.852648 -107.56138)
		(mid 396.641364 -107.353851)
		(end 396.557246 -107.06989)
		(width 0.089154)
		(layer "In9.Cu")
		(net "KR_P0_OCP_RX_C_DN")
	)
	(arc
		(start 396.357348 -106.70286)
		(mid 396.15745 -106.649327)
		(end 395.957552 -106.70286)
		(width 0.089154)
		(layer "In9.Cu")
		(net "KR_P0_OCP_RX_C_DN")
	)
	(arc
		(start 399.424652 -107.56138)
		(mid 399.12925 -107.640477)
		(end 398.833848 -107.56138)
		(width 0.089154)
		(layer "In9.Cu")
		(net "KR_P0_OCP_RX_C_DN")
	)
	(arc
		(start 396.557246 -107.037124)
		(mid 396.500727 -106.844021)
		(end 396.357348 -106.70286)
		(width 0.089154)
		(layer "In9.Cu")
		(net "KR_P0_OCP_RX_C_DN")
	)
	(arc
		(start 397.443452 -107.56138)
		(mid 397.14805 -107.640477)
		(end 396.852648 -107.56138)
		(width 0.089154)
		(layer "In9.Cu")
		(net "KR_P0_OCP_RX_C_DN")
	)
	(segment
		(start 466.871304 -64.530986)
		(end 466.871304 -64.620648)
		(width 0.10795)
		(layer "F.Cu")
		(net "FM_GBE3_LVC3_MOD_ABS")
	)
	(segment
		(start 415.724594 -79.261462)
		(end 415.724594 -78.813152)
		(width 0.10795)
		(layer "F.Cu")
		(net "FM_GBE3_LVC3_MOD_ABS")
	)
	(segment
		(start 421.094408 -77.8764)
		(end 418.5666 -77.8764)
		(width 0.10795)
		(layer "F.Cu")
		(net "FM_GBE3_LVC3_MOD_ABS")
	)
	(segment
		(start 408.72664 -91.45778)
		(end 409.93822 -91.45778)
		(width 0.10795)
		(layer "F.Cu")
		(net "FM_GBE3_LVC3_MOD_ABS")
	)
	(segment
		(start 421.452802 -77.518006)
		(end 421.094408 -77.8764)
		(width 0.10795)
		(layer "F.Cu")
		(net "FM_GBE3_LVC3_MOD_ABS")
	)
	(segment
		(start 404.499826 -93.89872)
		(end 404.499826 -93.741748)
		(width 0.10795)
		(layer "F.Cu")
		(net "FM_GBE3_LVC3_MOD_ABS")
	)
	(segment
		(start 407.177494 -91.06408)
		(end 408.33294 -91.06408)
		(width 0.10795)
		(layer "F.Cu")
		(net "FM_GBE3_LVC3_MOD_ABS")
	)
	(segment
		(start 427.119542 -66.127884)
		(end 425.5008 -67.746626)
		(width 0.10795)
		(layer "F.Cu")
		(net "FM_GBE3_LVC3_MOD_ABS")
	)
	(segment
		(start 408.33294 -91.06408)
		(end 408.72664 -91.45778)
		(width 0.10795)
		(layer "F.Cu")
		(net "FM_GBE3_LVC3_MOD_ABS")
	)
	(segment
		(start 466.87105 -64.530732)
		(end 466.871304 -64.530986)
		(width 0.10795)
		(layer "F.Cu")
		(net "FM_GBE3_LVC3_MOD_ABS")
	)
	(segment
		(start 404.499826 -93.741748)
		(end 407.177494 -91.06408)
		(width 0.10795)
		(layer "F.Cu")
		(net "FM_GBE3_LVC3_MOD_ABS")
	)
	(segment
		(start 404.495 -93.903546)
		(end 404.499826 -93.89872)
		(width 0.10795)
		(layer "F.Cu")
		(net "FM_GBE3_LVC3_MOD_ABS")
	)
	(segment
		(start 411.777942 -82.803746)
		(end 412.18231 -82.803746)
		(width 0.10795)
		(layer "F.Cu")
		(net "FM_GBE3_LVC3_MOD_ABS")
	)
	(segment
		(start 401.542504 -98.354896)
		(end 401.546822 -98.350578)
		(width 0.0889)
		(layer "F.Cu")
		(net "FM_GBE3_LVC3_MOD_ABS")
	)
	(segment
		(start 465.364322 -66.12763)
		(end 427.785276 -66.12763)
		(width 0.10795)
		(layer "F.Cu")
		(net "FM_GBE3_LVC3_MOD_ABS")
	)
	(segment
		(start 401.678648 -98.21926)
		(end 402.439886 -98.21926)
		(width 0.0889)
		(layer "F.Cu")
		(net "FM_GBE3_LVC3_MOD_ABS")
	)
	(segment
		(start 466.5726 -59.1058)
		(end 466.87105 -59.40425)
		(width 0.10795)
		(layer "F.Cu")
		(net "FM_GBE3_LVC3_MOD_ABS")
	)
	(segment
		(start 425.5008 -67.746626)
		(end 425.5008 -72.730614)
		(width 0.10795)
		(layer "F.Cu")
		(net "FM_GBE3_LVC3_MOD_ABS")
	)
	(segment
		(start 466.002624 -57.596024)
		(end 466.5726 -58.166)
		(width 0.10795)
		(layer "F.Cu")
		(net "FM_GBE3_LVC3_MOD_ABS")
	)
	(segment
		(start 466.5726 -58.166)
		(end 466.5726 -59.1058)
		(width 0.10795)
		(layer "F.Cu")
		(net "FM_GBE3_LVC3_MOD_ABS")
	)
	(segment
		(start 427.785276 -66.12763)
		(end 427.785022 -66.127884)
		(width 0.10795)
		(layer "F.Cu")
		(net "FM_GBE3_LVC3_MOD_ABS")
	)
	(segment
		(start 410.482796 -84.098892)
		(end 411.777942 -82.803746)
		(width 0.10795)
		(layer "F.Cu")
		(net "FM_GBE3_LVC3_MOD_ABS")
	)
	(segment
		(start 425.5008 -72.730614)
		(end 421.452802 -76.778612)
		(width 0.10795)
		(layer "F.Cu")
		(net "FM_GBE3_LVC3_MOD_ABS")
	)
	(segment
		(start 415.724594 -78.813152)
		(end 416.661346 -77.8764)
		(width 0.10795)
		(layer "F.Cu")
		(net "FM_GBE3_LVC3_MOD_ABS")
	)
	(segment
		(start 421.452802 -76.778612)
		(end 421.452802 -77.518006)
		(width 0.10795)
		(layer "F.Cu")
		(net "FM_GBE3_LVC3_MOD_ABS")
	)
	(segment
		(start 410.482796 -90.913204)
		(end 410.482796 -84.098892)
		(width 0.10795)
		(layer "F.Cu")
		(net "FM_GBE3_LVC3_MOD_ABS")
	)
	(segment
		(start 466.871304 -64.620648)
		(end 465.364322 -66.12763)
		(width 0.10795)
		(layer "F.Cu")
		(net "FM_GBE3_LVC3_MOD_ABS")
	)
	(segment
		(start 416.661346 -77.8764)
		(end 418.5666 -77.8764)
		(width 0.10795)
		(layer "F.Cu")
		(net "FM_GBE3_LVC3_MOD_ABS")
	)
	(segment
		(start 427.785022 -66.127884)
		(end 427.119542 -66.127884)
		(width 0.10795)
		(layer "F.Cu")
		(net "FM_GBE3_LVC3_MOD_ABS")
	)
	(segment
		(start 409.93822 -91.45778)
		(end 410.482796 -90.913204)
		(width 0.10795)
		(layer "F.Cu")
		(net "FM_GBE3_LVC3_MOD_ABS")
	)
	(segment
		(start 465.350098 -57.596024)
		(end 466.002624 -57.596024)
		(width 0.10795)
		(layer "F.Cu")
		(net "FM_GBE3_LVC3_MOD_ABS")
	)
	(segment
		(start 401.54733 -98.350578)
		(end 401.678648 -98.21926)
		(width 0.0889)
		(layer "F.Cu")
		(net "FM_GBE3_LVC3_MOD_ABS")
	)
	(segment
		(start 412.18231 -82.803746)
		(end 415.724594 -79.261462)
		(width 0.10795)
		(layer "F.Cu")
		(net "FM_GBE3_LVC3_MOD_ABS")
	)
	(segment
		(start 466.87105 -59.40425)
		(end 466.87105 -64.530732)
		(width 0.10795)
		(layer "F.Cu")
		(net "FM_GBE3_LVC3_MOD_ABS")
	)
	(segment
		(start 402.439886 -98.21926)
		(end 404.495 -96.164146)
		(width 0.10795)
		(layer "F.Cu")
		(net "FM_GBE3_LVC3_MOD_ABS")
	)
	(segment
		(start 400.880072 -98.354896)
		(end 401.542504 -98.354896)
		(width 0.0889)
		(layer "F.Cu")
		(net "FM_GBE3_LVC3_MOD_ABS")
	)
	(segment
		(start 404.495 -96.164146)
		(end 404.495 -93.903546)
		(width 0.10795)
		(layer "F.Cu")
		(net "FM_GBE3_LVC3_MOD_ABS")
	)
	(segment
		(start 401.546822 -98.350578)
		(end 401.54733 -98.350578)
		(width 0.0889)
		(layer "F.Cu")
		(net "FM_GBE3_LVC3_MOD_ABS")
	)
	(via
		(at 418.5666 -77.8764)
		(size 0.762)
		(drill 0.381)
		(layers "F.Cu" "B.Cu")
		(net "FM_GBE3_LVC3_MOD_ABS")
	)
	(via
		(at 466.5726 -59.1058)
		(size 0.508)
		(drill 0.254)
		(layers "F.Cu" "B.Cu")
		(net "FM_GBE3_LVC3_MOD_ABS")
	)
	(segment
		(start 467.0044 -58.674)
		(end 466.5726 -59.1058)
		(width 0.10795)
		(layer "B.Cu")
		(net "FM_GBE3_LVC3_MOD_ABS")
	)
	(segment
		(start 469.138 -58.674)
		(end 467.0044 -58.674)
		(width 0.10795)
		(layer "B.Cu")
		(net "FM_GBE3_LVC3_MOD_ABS")
	)
	(segment
		(start 426.80001 -65.91808)
		(end 425.29125 -67.42684)
		(width 0.10795)
		(layer "F.Cu")
		(net "FM_GBE2_LVC3_MOD_ABS")
	)
	(segment
		(start 401.012914 -98.034094)
		(end 401.129246 -98.150426)
		(width 0.10795)
		(layer "F.Cu")
		(net "FM_GBE2_LVC3_MOD_ABS")
	)
	(segment
		(start 417.49345 -77.66685)
		(end 418.3507 -76.8096)
		(width 0.10795)
		(layer "F.Cu")
		(net "FM_GBE2_LVC3_MOD_ABS")
	)
	(segment
		(start 400.465036 -98.855022)
		(end 400.465036 -98.316288)
		(width 0.10795)
		(layer "F.Cu")
		(net "FM_GBE2_LVC3_MOD_ABS")
	)
	(segment
		(start 464.549998 -57.596024)
		(end 464.549998 -59.14009)
		(width 0.10795)
		(layer "F.Cu")
		(net "FM_GBE2_LVC3_MOD_ABS")
	)
	(segment
		(start 401.464272 -98.150426)
		(end 401.642072 -97.972626)
		(width 0.10795)
		(layer "F.Cu")
		(net "FM_GBE2_LVC3_MOD_ABS")
	)
	(segment
		(start 415.515044 -79.174594)
		(end 415.515044 -78.718156)
		(width 0.10795)
		(layer "F.Cu")
		(net "FM_GBE2_LVC3_MOD_ABS")
	)
	(segment
		(start 412.095442 -82.594196)
		(end 415.515044 -79.174594)
		(width 0.10795)
		(layer "F.Cu")
		(net "FM_GBE2_LVC3_MOD_ABS")
	)
	(segment
		(start 401.642072 -97.972626)
		(end 402.38172 -97.972626)
		(width 0.10795)
		(layer "F.Cu")
		(net "FM_GBE2_LVC3_MOD_ABS")
	)
	(segment
		(start 410.273246 -84.012024)
		(end 411.691074 -82.594196)
		(width 0.10795)
		(layer "F.Cu")
		(net "FM_GBE2_LVC3_MOD_ABS")
	)
	(segment
		(start 408.174444 -89.770712)
		(end 409.576524 -89.770712)
		(width 0.10795)
		(layer "F.Cu")
		(net "FM_GBE2_LVC3_MOD_ABS")
	)
	(segment
		(start 401.129246 -98.150426)
		(end 401.464272 -98.150426)
		(width 0.10795)
		(layer "F.Cu")
		(net "FM_GBE2_LVC3_MOD_ABS")
	)
	(segment
		(start 466.066378 -59.58205)
		(end 466.327744 -59.843416)
		(width 0.10795)
		(layer "F.Cu")
		(net "FM_GBE2_LVC3_MOD_ABS")
	)
	(segment
		(start 402.38172 -97.972626)
		(end 404.27656 -96.077786)
		(width 0.10795)
		(layer "F.Cu")
		(net "FM_GBE2_LVC3_MOD_ABS")
	)
	(segment
		(start 466.6615 -64.534034)
		(end 465.277454 -65.91808)
		(width 0.10795)
		(layer "F.Cu")
		(net "FM_GBE2_LVC3_MOD_ABS")
	)
	(segment
		(start 409.576524 -89.770712)
		(end 410.273246 -89.07399)
		(width 0.10795)
		(layer "F.Cu")
		(net "FM_GBE2_LVC3_MOD_ABS")
	)
	(segment
		(start 425.29125 -72.643746)
		(end 421.125396 -76.8096)
		(width 0.10795)
		(layer "F.Cu")
		(net "FM_GBE2_LVC3_MOD_ABS")
	)
	(segment
		(start 400.74723 -98.034094)
		(end 401.012914 -98.034094)
		(width 0.10795)
		(layer "F.Cu")
		(net "FM_GBE2_LVC3_MOD_ABS")
	)
	(segment
		(start 466.327744 -59.843416)
		(end 466.6615 -60.177172)
		(width 0.10795)
		(layer "F.Cu")
		(net "FM_GBE2_LVC3_MOD_ABS")
	)
	(segment
		(start 400.465036 -98.316288)
		(end 400.74723 -98.034094)
		(width 0.10795)
		(layer "F.Cu")
		(net "FM_GBE2_LVC3_MOD_ABS")
	)
	(segment
		(start 404.27656 -93.668596)
		(end 408.174444 -89.770712)
		(width 0.10795)
		(layer "F.Cu")
		(net "FM_GBE2_LVC3_MOD_ABS")
	)
	(segment
		(start 404.27656 -96.077786)
		(end 404.27656 -93.668596)
		(width 0.10795)
		(layer "F.Cu")
		(net "FM_GBE2_LVC3_MOD_ABS")
	)
	(segment
		(start 418.3507 -76.8096)
		(end 420.3446 -76.8096)
		(width 0.10795)
		(layer "F.Cu")
		(net "FM_GBE2_LVC3_MOD_ABS")
	)
	(segment
		(start 415.515044 -78.718156)
		(end 416.56635 -77.66685)
		(width 0.10795)
		(layer "F.Cu")
		(net "FM_GBE2_LVC3_MOD_ABS")
	)
	(segment
		(start 464.549998 -59.14009)
		(end 464.549744 -59.140344)
		(width 0.10795)
		(layer "F.Cu")
		(net "FM_GBE2_LVC3_MOD_ABS")
	)
	(segment
		(start 421.125396 -76.8096)
		(end 420.3446 -76.8096)
		(width 0.10795)
		(layer "F.Cu")
		(net "FM_GBE2_LVC3_MOD_ABS")
	)
	(segment
		(start 465.277454 -65.91808)
		(end 426.80001 -65.91808)
		(width 0.10795)
		(layer "F.Cu")
		(net "FM_GBE2_LVC3_MOD_ABS")
	)
	(segment
		(start 425.29125 -67.42684)
		(end 425.29125 -72.643746)
		(width 0.10795)
		(layer "F.Cu")
		(net "FM_GBE2_LVC3_MOD_ABS")
	)
	(segment
		(start 416.56635 -77.66685)
		(end 417.49345 -77.66685)
		(width 0.10795)
		(layer "F.Cu")
		(net "FM_GBE2_LVC3_MOD_ABS")
	)
	(segment
		(start 464.99145 -59.58205)
		(end 466.066378 -59.58205)
		(width 0.10795)
		(layer "F.Cu")
		(net "FM_GBE2_LVC3_MOD_ABS")
	)
	(segment
		(start 411.691074 -82.594196)
		(end 412.095442 -82.594196)
		(width 0.10795)
		(layer "F.Cu")
		(net "FM_GBE2_LVC3_MOD_ABS")
	)
	(segment
		(start 464.549744 -59.140344)
		(end 464.99145 -59.58205)
		(width 0.10795)
		(layer "F.Cu")
		(net "FM_GBE2_LVC3_MOD_ABS")
	)
	(segment
		(start 466.6615 -60.177172)
		(end 466.6615 -64.534034)
		(width 0.10795)
		(layer "F.Cu")
		(net "FM_GBE2_LVC3_MOD_ABS")
	)
	(segment
		(start 410.273246 -89.07399)
		(end 410.273246 -84.012024)
		(width 0.10795)
		(layer "F.Cu")
		(net "FM_GBE2_LVC3_MOD_ABS")
	)
	(via
		(at 466.327744 -59.843416)
		(size 0.508)
		(drill 0.254)
		(layers "F.Cu" "B.Cu")
		(net "FM_GBE2_LVC3_MOD_ABS")
	)
	(via
		(at 420.3446 -76.8096)
		(size 0.762)
		(drill 0.381)
		(layers "F.Cu" "B.Cu")
		(net "FM_GBE2_LVC3_MOD_ABS")
	)
	(segment
		(start 468.249 -58.9026)
		(end 467.373208 -58.9026)
		(width 0.10795)
		(layer "B.Cu")
		(net "FM_GBE2_LVC3_MOD_ABS")
	)
	(segment
		(start 469.138 -59.436)
		(end 468.7824 -59.436)
		(width 0.10795)
		(layer "B.Cu")
		(net "FM_GBE2_LVC3_MOD_ABS")
	)
	(segment
		(start 468.7824 -59.436)
		(end 468.249 -58.9026)
		(width 0.10795)
		(layer "B.Cu")
		(net "FM_GBE2_LVC3_MOD_ABS")
	)
	(segment
		(start 466.432392 -59.843416)
		(end 466.327744 -59.843416)
		(width 0.10795)
		(layer "B.Cu")
		(net "FM_GBE2_LVC3_MOD_ABS")
	)
	(segment
		(start 467.373208 -58.9026)
		(end 466.432392 -59.843416)
		(width 0.10795)
		(layer "B.Cu")
		(net "FM_GBE2_LVC3_MOD_ABS")
	)
	(segment
		(start 403.85746 -95.81134)
		(end 402.615654 -97.053146)
		(width 0.10795)
		(layer "F.Cu")
		(net "FM_GBE1_LVC3_MOD_ABS")
	)
	(segment
		(start 409.854146 -88.900254)
		(end 409.484322 -89.270078)
		(width 0.10795)
		(layer "F.Cu")
		(net "FM_GBE1_LVC3_MOD_ABS")
	)
	(segment
		(start 444.550038 -62.00267)
		(end 444.550038 -62.991238)
		(width 0.10795)
		(layer "F.Cu")
		(net "FM_GBE1_LVC3_MOD_ABS")
	)
	(segment
		(start 411.517338 -82.175096)
		(end 409.854146 -83.838288)
		(width 0.10795)
		(layer "F.Cu")
		(net "FM_GBE1_LVC3_MOD_ABS")
	)
	(segment
		(start 402.183346 -97.485454)
		(end 401.691348 -97.485454)
		(width 0.0889)
		(layer "F.Cu")
		(net "FM_GBE1_LVC3_MOD_ABS")
	)
	(segment
		(start 400.904964 -97.330006)
		(end 400.880072 -97.354898)
		(width 0.0889)
		(layer "F.Cu")
		(net "FM_GBE1_LVC3_MOD_ABS")
	)
	(segment
		(start 402.615654 -97.053146)
		(end 402.183346 -97.485454)
		(width 0.0889)
		(layer "F.Cu")
		(net "FM_GBE1_LVC3_MOD_ABS")
	)
	(segment
		(start 401.610576 -97.404682)
		(end 401.610068 -97.404682)
		(width 0.0889)
		(layer "F.Cu")
		(net "FM_GBE1_LVC3_MOD_ABS")
	)
	(segment
		(start 403.85746 -93.49486)
		(end 403.85746 -95.81134)
		(width 0.10795)
		(layer "F.Cu")
		(net "FM_GBE1_LVC3_MOD_ABS")
	)
	(segment
		(start 401.691348 -97.485454)
		(end 401.610576 -97.404682)
		(width 0.0889)
		(layer "F.Cu")
		(net "FM_GBE1_LVC3_MOD_ABS")
	)
	(segment
		(start 444.550038 -62.991238)
		(end 444.9826 -63.4238)
		(width 0.10795)
		(layer "F.Cu")
		(net "FM_GBE1_LVC3_MOD_ABS")
	)
	(segment
		(start 409.484322 -89.270078)
		(end 408.082242 -89.270078)
		(width 0.10795)
		(layer "F.Cu")
		(net "FM_GBE1_LVC3_MOD_ABS")
	)
	(segment
		(start 411.921706 -82.175096)
		(end 411.517338 -82.175096)
		(width 0.10795)
		(layer "F.Cu")
		(net "FM_GBE1_LVC3_MOD_ABS")
	)
	(segment
		(start 415.778188 -76.857352)
		(end 415.095944 -77.539596)
		(width 0.10795)
		(layer "F.Cu")
		(net "FM_GBE1_LVC3_MOD_ABS")
	)
	(segment
		(start 409.854146 -83.838288)
		(end 409.854146 -88.900254)
		(width 0.10795)
		(layer "F.Cu")
		(net "FM_GBE1_LVC3_MOD_ABS")
	)
	(segment
		(start 401.610068 -97.404682)
		(end 401.535392 -97.330006)
		(width 0.0889)
		(layer "F.Cu")
		(net "FM_GBE1_LVC3_MOD_ABS")
	)
	(segment
		(start 401.535392 -97.330006)
		(end 400.904964 -97.330006)
		(width 0.0889)
		(layer "F.Cu")
		(net "FM_GBE1_LVC3_MOD_ABS")
	)
	(segment
		(start 415.095944 -77.539596)
		(end 415.095944 -79.000858)
		(width 0.10795)
		(layer "F.Cu")
		(net "FM_GBE1_LVC3_MOD_ABS")
	)
	(segment
		(start 408.082242 -89.270078)
		(end 403.85746 -93.49486)
		(width 0.10795)
		(layer "F.Cu")
		(net "FM_GBE1_LVC3_MOD_ABS")
	)
	(segment
		(start 415.095944 -79.000858)
		(end 411.921706 -82.175096)
		(width 0.10795)
		(layer "F.Cu")
		(net "FM_GBE1_LVC3_MOD_ABS")
	)
	(via
		(at 444.9826 -63.4238)
		(size 0.508)
		(drill 0.254)
		(layers "F.Cu" "B.Cu")
		(net "FM_GBE1_LVC3_MOD_ABS")
	)
	(via
		(at 441.0456 -60.2742)
		(size 0.508)
		(drill 0.254)
		(layers "F.Cu" "B.Cu")
		(net "FM_GBE1_LVC3_MOD_ABS")
	)
	(via
		(at 415.778188 -76.857352)
		(size 0.508)
		(drill 0.254)
		(layers "F.Cu" "B.Cu")
		(net "FM_GBE1_LVC3_MOD_ABS")
	)
	(segment
		(start 445.2112 -62.5856)
		(end 444.9826 -62.8142)
		(width 0.10795)
		(layer "B.Cu")
		(net "FM_GBE1_LVC3_MOD_ABS")
	)
	(segment
		(start 444.9826 -62.8142)
		(end 444.9826 -63.4238)
		(width 0.10795)
		(layer "B.Cu")
		(net "FM_GBE1_LVC3_MOD_ABS")
	)
	(segment
		(start 445.9986 -62.5856)
		(end 445.2112 -62.5856)
		(width 0.10795)
		(layer "B.Cu")
		(net "FM_GBE1_LVC3_MOD_ABS")
	)
	(segment
		(start 417.647628 -70.764654)
		(end 417.647628 -64.630046)
		(width 0.089408)
		(layer "In2.Cu")
		(net "FM_GBE1_LVC3_MOD_ABS")
	)
	(segment
		(start 417.415726 -70.996556)
		(end 417.647628 -70.764654)
		(width 0.089408)
		(layer "In2.Cu")
		(net "FM_GBE1_LVC3_MOD_ABS")
	)
	(segment
		(start 417.647882 -63.679324)
		(end 417.647628 -63.67907)
		(width 0.089408)
		(layer "In2.Cu")
		(net "FM_GBE1_LVC3_MOD_ABS")
	)
	(segment
		(start 440.54395 -59.77255)
		(end 441.0456 -60.2742)
		(width 0.089408)
		(layer "In2.Cu")
		(net "FM_GBE1_LVC3_MOD_ABS")
	)
	(segment
		(start 430.809908 -56.863996)
		(end 434.050186 -56.863996)
		(width 0.089408)
		(layer "In2.Cu")
		(net "FM_GBE1_LVC3_MOD_ABS")
	)
	(segment
		(start 417.647628 -63.518796)
		(end 423.163492 -58.002932)
		(width 0.089408)
		(layer "In2.Cu")
		(net "FM_GBE1_LVC3_MOD_ABS")
	)
	(segment
		(start 434.050186 -56.863996)
		(end 435.71668 -58.53049)
		(width 0.089408)
		(layer "In2.Cu")
		(net "FM_GBE1_LVC3_MOD_ABS")
	)
	(segment
		(start 417.415726 -75.219814)
		(end 417.415726 -70.996556)
		(width 0.089408)
		(layer "In2.Cu")
		(net "FM_GBE1_LVC3_MOD_ABS")
	)
	(segment
		(start 415.778188 -76.857352)
		(end 417.415726 -75.219814)
		(width 0.089408)
		(layer "In2.Cu")
		(net "FM_GBE1_LVC3_MOD_ABS")
	)
	(segment
		(start 417.647882 -64.629792)
		(end 417.647882 -63.679324)
		(width 0.089408)
		(layer "In2.Cu")
		(net "FM_GBE1_LVC3_MOD_ABS")
	)
	(segment
		(start 417.647628 -64.630046)
		(end 417.647882 -64.629792)
		(width 0.089408)
		(layer "In2.Cu")
		(net "FM_GBE1_LVC3_MOD_ABS")
	)
	(segment
		(start 423.163492 -58.002932)
		(end 429.670972 -58.002932)
		(width 0.089408)
		(layer "In2.Cu")
		(net "FM_GBE1_LVC3_MOD_ABS")
	)
	(segment
		(start 417.647628 -63.67907)
		(end 417.647628 -63.518796)
		(width 0.089408)
		(layer "In2.Cu")
		(net "FM_GBE1_LVC3_MOD_ABS")
	)
	(segment
		(start 439.89879 -59.77255)
		(end 440.54395 -59.77255)
		(width 0.089408)
		(layer "In2.Cu")
		(net "FM_GBE1_LVC3_MOD_ABS")
	)
	(segment
		(start 429.670972 -58.002932)
		(end 430.809908 -56.863996)
		(width 0.089408)
		(layer "In2.Cu")
		(net "FM_GBE1_LVC3_MOD_ABS")
	)
	(segment
		(start 435.71668 -58.53049)
		(end 438.65673 -58.53049)
		(width 0.089408)
		(layer "In2.Cu")
		(net "FM_GBE1_LVC3_MOD_ABS")
	)
	(segment
		(start 438.65673 -58.53049)
		(end 439.89879 -59.77255)
		(width 0.089408)
		(layer "In2.Cu")
		(net "FM_GBE1_LVC3_MOD_ABS")
	)
	(segment
		(start 442.5696 -61.0108)
		(end 441.7822 -61.0108)
		(width 0.089408)
		(layer "In11.Cu")
		(net "FM_GBE1_LVC3_MOD_ABS")
	)
	(segment
		(start 444.9826 -63.4238)
		(end 442.5696 -61.0108)
		(width 0.089408)
		(layer "In11.Cu")
		(net "FM_GBE1_LVC3_MOD_ABS")
	)
	(segment
		(start 441.7822 -61.0108)
		(end 441.0456 -60.2742)
		(width 0.089408)
		(layer "In11.Cu")
		(net "FM_GBE1_LVC3_MOD_ABS")
	)
	(segment
		(start 410.063696 -83.925156)
		(end 410.063696 -88.987122)
		(width 0.10795)
		(layer "F.Cu")
		(net "FM_GBE0_LVC3_MOD_ABS")
	)
	(segment
		(start 412.008574 -82.384646)
		(end 411.604206 -82.384646)
		(width 0.10795)
		(layer "F.Cu")
		(net "FM_GBE0_LVC3_MOD_ABS")
	)
	(segment
		(start 401.505928 -97.569528)
		(end 401.45208 -97.569528)
		(width 0.0889)
		(layer "F.Cu")
		(net "FM_GBE0_LVC3_MOD_ABS")
	)
	(segment
		(start 410.063696 -88.987122)
		(end 409.57119 -89.479628)
		(width 0.10795)
		(layer "F.Cu")
		(net "FM_GBE0_LVC3_MOD_ABS")
	)
	(segment
		(start 401.628864 -97.692464)
		(end 401.505928 -97.569528)
		(width 0.0889)
		(layer "F.Cu")
		(net "FM_GBE0_LVC3_MOD_ABS")
	)
	(segment
		(start 415.305494 -79.087726)
		(end 412.008574 -82.384646)
		(width 0.10795)
		(layer "F.Cu")
		(net "FM_GBE0_LVC3_MOD_ABS")
	)
	(segment
		(start 409.57119 -89.479628)
		(end 408.16911 -89.479628)
		(width 0.10795)
		(layer "F.Cu")
		(net "FM_GBE0_LVC3_MOD_ABS")
	)
	(segment
		(start 415.762694 -77.493114)
		(end 415.305494 -77.950314)
		(width 0.10795)
		(layer "F.Cu")
		(net "FM_GBE0_LVC3_MOD_ABS")
	)
	(segment
		(start 411.604206 -82.384646)
		(end 410.063696 -83.925156)
		(width 0.10795)
		(layer "F.Cu")
		(net "FM_GBE0_LVC3_MOD_ABS")
	)
	(segment
		(start 400.716242 -97.666048)
		(end 400.405092 -97.354898)
		(width 0.0889)
		(layer "F.Cu")
		(net "FM_GBE0_LVC3_MOD_ABS")
	)
	(segment
		(start 401.041616 -97.666048)
		(end 400.716242 -97.666048)
		(width 0.0889)
		(layer "F.Cu")
		(net "FM_GBE0_LVC3_MOD_ABS")
	)
	(segment
		(start 400.405092 -97.354898)
		(end 400.05 -97.354898)
		(width 0.0889)
		(layer "F.Cu")
		(net "FM_GBE0_LVC3_MOD_ABS")
	)
	(segment
		(start 443.749938 -62.00267)
		(end 443.749938 -63.412878)
		(width 0.10795)
		(layer "F.Cu")
		(net "FM_GBE0_LVC3_MOD_ABS")
	)
	(segment
		(start 404.06701 -93.581728)
		(end 404.06701 -95.95739)
		(width 0.10795)
		(layer "F.Cu")
		(net "FM_GBE0_LVC3_MOD_ABS")
	)
	(segment
		(start 404.06701 -95.95739)
		(end 402.331936 -97.692464)
		(width 0.10795)
		(layer "F.Cu")
		(net "FM_GBE0_LVC3_MOD_ABS")
	)
	(segment
		(start 401.45208 -97.569528)
		(end 401.451826 -97.569274)
		(width 0.0889)
		(layer "F.Cu")
		(net "FM_GBE0_LVC3_MOD_ABS")
	)
	(segment
		(start 401.13839 -97.569274)
		(end 401.041616 -97.666048)
		(width 0.0889)
		(layer "F.Cu")
		(net "FM_GBE0_LVC3_MOD_ABS")
	)
	(segment
		(start 402.331936 -97.692464)
		(end 401.628864 -97.692464)
		(width 0.0889)
		(layer "F.Cu")
		(net "FM_GBE0_LVC3_MOD_ABS")
	)
	(segment
		(start 408.16911 -89.479628)
		(end 404.06701 -93.581728)
		(width 0.10795)
		(layer "F.Cu")
		(net "FM_GBE0_LVC3_MOD_ABS")
	)
	(segment
		(start 415.305494 -77.950314)
		(end 415.305494 -79.087726)
		(width 0.10795)
		(layer "F.Cu")
		(net "FM_GBE0_LVC3_MOD_ABS")
	)
	(segment
		(start 401.451826 -97.569274)
		(end 401.13839 -97.569274)
		(width 0.0889)
		(layer "F.Cu")
		(net "FM_GBE0_LVC3_MOD_ABS")
	)
	(segment
		(start 443.749938 -63.412878)
		(end 443.7126 -63.450216)
		(width 0.10795)
		(layer "F.Cu")
		(net "FM_GBE0_LVC3_MOD_ABS")
	)
	(via
		(at 443.7126 -63.450216)
		(size 0.508)
		(drill 0.254)
		(layers "F.Cu" "B.Cu")
		(net "FM_GBE0_LVC3_MOD_ABS")
	)
	(via
		(at 440.4106 -60.2742)
		(size 0.508)
		(drill 0.254)
		(layers "F.Cu" "B.Cu")
		(net "FM_GBE0_LVC3_MOD_ABS")
	)
	(via
		(at 415.762694 -77.493114)
		(size 0.508)
		(drill 0.254)
		(layers "F.Cu" "B.Cu")
		(net "FM_GBE0_LVC3_MOD_ABS")
	)
	(segment
		(start 445.9986 -61.8236)
		(end 445.339216 -61.8236)
		(width 0.10795)
		(layer "B.Cu")
		(net "FM_GBE0_LVC3_MOD_ABS")
	)
	(segment
		(start 445.339216 -61.8236)
		(end 443.7126 -63.450216)
		(width 0.10795)
		(layer "B.Cu")
		(net "FM_GBE0_LVC3_MOD_ABS")
	)
	(segment
		(start 440.4106 -60.2742)
		(end 440.12104 -60.2742)
		(width 0.089408)
		(layer "In2.Cu")
		(net "FM_GBE0_LVC3_MOD_ABS")
	)
	(segment
		(start 436.502302 -58.721498)
		(end 436.245 -58.9788)
		(width 0.089408)
		(layer "In2.Cu")
		(net "FM_GBE0_LVC3_MOD_ABS")
	)
	(segment
		(start 417.838636 -64.709294)
		(end 417.838636 -70.843902)
		(width 0.089408)
		(layer "In2.Cu")
		(net "FM_GBE0_LVC3_MOD_ABS")
	)
	(segment
		(start 417.83889 -64.70904)
		(end 417.838636 -64.709294)
		(width 0.089408)
		(layer "In2.Cu")
		(net "FM_GBE0_LVC3_MOD_ABS")
	)
	(segment
		(start 428.97425 -61.023246)
		(end 428.97425 -58.728356)
		(width 0.089408)
		(layer "In2.Cu")
		(net "FM_GBE0_LVC3_MOD_ABS")
	)
	(segment
		(start 417.838636 -70.843902)
		(end 417.606734 -71.075804)
		(width 0.089408)
		(layer "In2.Cu")
		(net "FM_GBE0_LVC3_MOD_ABS")
	)
	(segment
		(start 417.606734 -75.649074)
		(end 415.762694 -77.493114)
		(width 0.089408)
		(layer "In2.Cu")
		(net "FM_GBE0_LVC3_MOD_ABS")
	)
	(segment
		(start 430.670208 -62.719204)
		(end 428.97425 -61.023246)
		(width 0.089408)
		(layer "In2.Cu")
		(net "FM_GBE0_LVC3_MOD_ABS")
	)
	(segment
		(start 428.527718 -58.281824)
		(end 423.154856 -58.281824)
		(width 0.089408)
		(layer "In2.Cu")
		(net "FM_GBE0_LVC3_MOD_ABS")
	)
	(segment
		(start 417.606734 -71.075804)
		(end 417.606734 -75.649074)
		(width 0.089408)
		(layer "In2.Cu")
		(net "FM_GBE0_LVC3_MOD_ABS")
	)
	(segment
		(start 417.83889 -63.59779)
		(end 417.83889 -64.70904)
		(width 0.089408)
		(layer "In2.Cu")
		(net "FM_GBE0_LVC3_MOD_ABS")
	)
	(segment
		(start 423.154856 -58.281824)
		(end 417.83889 -63.59779)
		(width 0.089408)
		(layer "In2.Cu")
		(net "FM_GBE0_LVC3_MOD_ABS")
	)
	(segment
		(start 436.245 -58.9788)
		(end 436.245 -59.090052)
		(width 0.089408)
		(layer "In2.Cu")
		(net "FM_GBE0_LVC3_MOD_ABS")
	)
	(segment
		(start 432.615848 -62.719204)
		(end 430.670208 -62.719204)
		(width 0.089408)
		(layer "In2.Cu")
		(net "FM_GBE0_LVC3_MOD_ABS")
	)
	(segment
		(start 428.97425 -58.728356)
		(end 428.527718 -58.281824)
		(width 0.089408)
		(layer "In2.Cu")
		(net "FM_GBE0_LVC3_MOD_ABS")
	)
	(segment
		(start 436.245 -59.090052)
		(end 432.615848 -62.719204)
		(width 0.089408)
		(layer "In2.Cu")
		(net "FM_GBE0_LVC3_MOD_ABS")
	)
	(segment
		(start 438.568338 -58.721498)
		(end 436.502302 -58.721498)
		(width 0.089408)
		(layer "In2.Cu")
		(net "FM_GBE0_LVC3_MOD_ABS")
	)
	(segment
		(start 440.12104 -60.2742)
		(end 438.568338 -58.721498)
		(width 0.089408)
		(layer "In2.Cu")
		(net "FM_GBE0_LVC3_MOD_ABS")
	)
	(segment
		(start 443.7126 -62.738)
		(end 442.3791 -61.4045)
		(width 0.089408)
		(layer "In11.Cu")
		(net "FM_GBE0_LVC3_MOD_ABS")
	)
	(segment
		(start 441.5409 -61.4045)
		(end 440.4106 -60.2742)
		(width 0.089408)
		(layer "In11.Cu")
		(net "FM_GBE0_LVC3_MOD_ABS")
	)
	(segment
		(start 442.3791 -61.4045)
		(end 441.5409 -61.4045)
		(width 0.089408)
		(layer "In11.Cu")
		(net "FM_GBE0_LVC3_MOD_ABS")
	)
	(segment
		(start 443.7126 -63.450216)
		(end 443.7126 -62.738)
		(width 0.089408)
		(layer "In11.Cu")
		(net "FM_GBE0_LVC3_MOD_ABS")
	)
	(via
		(at 406.7048 -5.08)
		(size 0.6604)
		(drill 0.3302)
		(layers "F.Cu" "B.Cu")
		(net "A_PG_P5V")
	)
	(segment
		(start 408.8765 -4.572)
		(end 408.8765 -5.0165)
		(width 0.254)
		(layer "B.Cu")
		(net "A_PG_P5V")
	)
	(segment
		(start 408.6225 -5.2705)
		(end 408.051 -5.2705)
		(width 0.254)
		(layer "B.Cu")
		(net "A_PG_P5V")
	)
	(segment
		(start 408.8765 -5.0165)
		(end 408.6225 -5.2705)
		(width 0.254)
		(layer "B.Cu")
		(net "A_PG_P5V")
	)
	(segment
		(start 408.3558 -6.0198)
		(end 408.051 -5.715)
		(width 0.254)
		(layer "B.Cu")
		(net "A_PG_P5V")
	)
	(segment
		(start 408.051 -5.715)
		(end 408.051 -5.2705)
		(width 0.254)
		(layer "B.Cu")
		(net "A_PG_P5V")
	)
	(segment
		(start 406.8953 -5.2705)
		(end 408.051 -5.2705)
		(width 0.254)
		(layer "B.Cu")
		(net "A_PG_P5V")
	)
	(segment
		(start 409.455874 -6.0198)
		(end 408.3558 -6.0198)
		(width 0.254)
		(layer "B.Cu")
		(net "A_PG_P5V")
	)
	(segment
		(start 406.7048 -5.08)
		(end 406.8953 -5.2705)
		(width 0.254)
		(layer "B.Cu")
		(net "A_PG_P5V")
	)
	(via
		(at 406.7048 -8.2042)
		(size 0.6604)
		(drill 0.3302)
		(layers "F.Cu" "B.Cu")
		(net "A_PG_P12V_MAIN")
	)
	(segment
		(start 408.051 -8.1788)
		(end 407.9113 -8.3185)
		(width 0.254)
		(layer "B.Cu")
		(net "A_PG_P12V_MAIN")
	)
	(segment
		(start 407.2636 -8.763)
		(end 407.9113 -8.763)
		(width 0.254)
		(layer "B.Cu")
		(net "A_PG_P12V_MAIN")
	)
	(segment
		(start 406.7048 -8.2042)
		(end 407.2636 -8.763)
		(width 0.254)
		(layer "B.Cu")
		(net "A_PG_P12V_MAIN")
	)
	(segment
		(start 409.455874 -7.574026)
		(end 409.455874 -7.1882)
		(width 0.254)
		(layer "B.Cu")
		(net "A_PG_P12V_MAIN")
	)
	(segment
		(start 408.051 -7.8105)
		(end 408.051 -8.1788)
		(width 0.254)
		(layer "B.Cu")
		(net "A_PG_P12V_MAIN")
	)
	(segment
		(start 407.9113 -8.3185)
		(end 407.9113 -8.763)
		(width 0.254)
		(layer "B.Cu")
		(net "A_PG_P12V_MAIN")
	)
	(segment
		(start 408.051 -7.8105)
		(end 409.2194 -7.8105)
		(width 0.254)
		(layer "B.Cu")
		(net "A_PG_P12V_MAIN")
	)
	(segment
		(start 409.2194 -7.8105)
		(end 409.455874 -7.574026)
		(width 0.254)
		(layer "B.Cu")
		(net "A_PG_P12V_MAIN")
	)
	(segment
		(start 29.69514 -95.97644)
		(end 29.86278 -95.97644)
		(width 0.10795)
		(layer "F.Cu")
		(net "VR_PVSA_CPU1_OCSET")
	)
	(segment
		(start 29.69514 -95.97644)
		(end 29.506926 -95.97644)
		(width 0.10795)
		(layer "F.Cu")
		(net "VR_PVSA_CPU1_OCSET")
	)
	(segment
		(start 29.291026 -96.19234)
		(end 28.85948 -96.19234)
		(width 0.10795)
		(layer "F.Cu")
		(net "VR_PVSA_CPU1_OCSET")
	)
	(segment
		(start 29.506926 -95.97644)
		(end 29.291026 -96.19234)
		(width 0.10795)
		(layer "F.Cu")
		(net "VR_PVSA_CPU1_OCSET")
	)
	(segment
		(start 29.86278 -95.97644)
		(end 30.46603 -96.57969)
		(width 0.10795)
		(layer "F.Cu")
		(net "VR_PVSA_CPU1_OCSET")
	)
	(segment
		(start 30.46603 -96.57969)
		(end 31.02991 -96.57969)
		(width 0.10795)
		(layer "F.Cu")
		(net "VR_PVSA_CPU1_OCSET")
	)
	(via
		(at 29.69514 -95.97644)
		(size 0.762)
		(drill 0.381)
		(layers "F.Cu" "B.Cu")
		(net "VR_PVSA_CPU1_OCSET")
	)
	(segment
		(start 193.662808 -96.624648)
		(end 193.662808 -96.707452)
		(width 0.1016)
		(layer "F.Cu")
		(net "VR_PVSA_CPU0_OCSET")
	)
	(segment
		(start 194.76466 -96.314006)
		(end 194.598036 -96.147382)
		(width 0.1016)
		(layer "F.Cu")
		(net "VR_PVSA_CPU0_OCSET")
	)
	(segment
		(start 195.561712 -96.57969)
		(end 195.296028 -96.314006)
		(width 0.1016)
		(layer "F.Cu")
		(net "VR_PVSA_CPU0_OCSET")
	)
	(segment
		(start 194.140074 -96.147382)
		(end 193.662808 -96.624648)
		(width 0.1016)
		(layer "F.Cu")
		(net "VR_PVSA_CPU0_OCSET")
	)
	(segment
		(start 195.296028 -96.314006)
		(end 194.76466 -96.314006)
		(width 0.1016)
		(layer "F.Cu")
		(net "VR_PVSA_CPU0_OCSET")
	)
	(segment
		(start 196.017642 -96.57969)
		(end 195.561712 -96.57969)
		(width 0.1016)
		(layer "F.Cu")
		(net "VR_PVSA_CPU0_OCSET")
	)
	(segment
		(start 194.598036 -96.147382)
		(end 194.140074 -96.147382)
		(width 0.1016)
		(layer "F.Cu")
		(net "VR_PVSA_CPU0_OCSET")
	)
	(segment
		(start 374.862598 -157.116272)
		(end 374.862598 -157.269434)
		(width 0.10795)
		(layer "F.Cu")
		(net "VR_PVNN_PCH_STBY_OCSET")
	)
	(segment
		(start 375.267474 -156.711396)
		(end 374.862598 -157.116272)
		(width 0.10795)
		(layer "F.Cu")
		(net "VR_PVNN_PCH_STBY_OCSET")
	)
	(segment
		(start 374.862598 -157.269434)
		(end 374.874282 -157.281118)
		(width 0.10795)
		(layer "F.Cu")
		(net "VR_PVNN_PCH_STBY_OCSET")
	)
	(segment
		(start 375.267474 -156.24302)
		(end 375.267474 -156.711396)
		(width 0.10795)
		(layer "F.Cu")
		(net "VR_PVNN_PCH_STBY_OCSET")
	)
	(via
		(at 376.371612 -156.137864)
		(size 0.6604)
		(drill 0.3302)
		(layers "F.Cu" "B.Cu")
		(net "VR_PVNN_PCH_STBY_OCSET")
	)
	(via
		(at 374.874282 -157.281118)
		(size 0.508)
		(drill 0.254)
		(layers "F.Cu" "B.Cu")
		(net "VR_PVNN_PCH_STBY_OCSET")
	)
	(segment
		(start 376.371612 -156.137864)
		(end 376.172476 -156.337)
		(width 0.10795)
		(layer "B.Cu")
		(net "VR_PVNN_PCH_STBY_OCSET")
	)
	(segment
		(start 376.172476 -156.337)
		(end 375.3612 -156.337)
		(width 0.10795)
		(layer "B.Cu")
		(net "VR_PVNN_PCH_STBY_OCSET")
	)
	(segment
		(start 375.3612 -156.68498)
		(end 374.874282 -157.171898)
		(width 0.10795)
		(layer "B.Cu")
		(net "VR_PVNN_PCH_STBY_OCSET")
	)
	(segment
		(start 375.3612 -156.337)
		(end 375.3612 -156.68498)
		(width 0.10795)
		(layer "B.Cu")
		(net "VR_PVNN_PCH_STBY_OCSET")
	)
	(segment
		(start 374.874282 -157.171898)
		(end 374.874282 -157.281118)
		(width 0.10795)
		(layer "B.Cu")
		(net "VR_PVNN_PCH_STBY_OCSET")
	)
	(segment
		(start -3.175 -144.8562)
		(end -3.175 -144.9451)
		(width 0.10795)
		(layer "F.Cu")
		(net "VR_PVDDQ_KLM_PH2_OCSET")
	)
	(segment
		(start -1.393952 -146.228308)
		(end -0.497586 -146.228308)
		(width 0.1016)
		(layer "F.Cu")
		(net "VR_PVDDQ_KLM_PH2_OCSET")
	)
	(segment
		(start -2.56794 -145.55216)
		(end -2.0701 -145.55216)
		(width 0.10795)
		(layer "F.Cu")
		(net "VR_PVDDQ_KLM_PH2_OCSET")
	)
	(segment
		(start -2.0701 -145.55216)
		(end -1.875282 -145.746978)
		(width 0.10795)
		(layer "F.Cu")
		(net "VR_PVDDQ_KLM_PH2_OCSET")
	)
	(segment
		(start -3.175 -144.9451)
		(end -2.56794 -145.55216)
		(width 0.10795)
		(layer "F.Cu")
		(net "VR_PVDDQ_KLM_PH2_OCSET")
	)
	(segment
		(start -1.875282 -145.746978)
		(end -1.393952 -146.228308)
		(width 0.10795)
		(layer "F.Cu")
		(net "VR_PVDDQ_KLM_PH2_OCSET")
	)
	(via
		(at -1.875282 -145.746978)
		(size 0.762)
		(drill 0.381)
		(layers "F.Cu" "B.Cu")
		(net "VR_PVDDQ_KLM_PH2_OCSET")
	)
	(segment
		(start -0.497586 -137.084308)
		(end -1.14808 -137.084308)
		(width 0.1016)
		(layer "F.Cu")
		(net "VR_PVDDQ_KLM_PH1_OCSET")
	)
	(segment
		(start -1.14808 -137.084308)
		(end -1.631188 -136.6012)
		(width 0.10795)
		(layer "F.Cu")
		(net "VR_PVDDQ_KLM_PH1_OCSET")
	)
	(segment
		(start -3.175 -136.068816)
		(end -2.642616 -136.6012)
		(width 0.10795)
		(layer "F.Cu")
		(net "VR_PVDDQ_KLM_PH1_OCSET")
	)
	(segment
		(start -3.175 -135.7122)
		(end -3.175 -136.068816)
		(width 0.10795)
		(layer "F.Cu")
		(net "VR_PVDDQ_KLM_PH1_OCSET")
	)
	(segment
		(start -2.642616 -136.6012)
		(end -1.86309 -136.6012)
		(width 0.10795)
		(layer "F.Cu")
		(net "VR_PVDDQ_KLM_PH1_OCSET")
	)
	(segment
		(start -1.631188 -136.6012)
		(end -1.86309 -136.6012)
		(width 0.10795)
		(layer "F.Cu")
		(net "VR_PVDDQ_KLM_PH1_OCSET")
	)
	(via
		(at -1.86309 -136.6012)
		(size 0.762)
		(drill 0.381)
		(layers "F.Cu" "B.Cu")
		(net "VR_PVDDQ_KLM_PH1_OCSET")
	)
	(segment
		(start 1.831848 -16.360902)
		(end 1.371346 -15.9004)
		(width 0.1016)
		(layer "F.Cu")
		(net "VR_PVDDQ_GHJ_PH2_OCSET")
	)
	(segment
		(start 1.371346 -15.9004)
		(end 0.23368 -15.9004)
		(width 0.1016)
		(layer "F.Cu")
		(net "VR_PVDDQ_GHJ_PH2_OCSET")
	)
	(segment
		(start 2.150364 -16.360902)
		(end 1.831848 -16.360902)
		(width 0.1016)
		(layer "F.Cu")
		(net "VR_PVDDQ_GHJ_PH2_OCSET")
	)
	(segment
		(start 0.23368 -15.9004)
		(end -0.27432 -15.3924)
		(width 0.1016)
		(layer "F.Cu")
		(net "VR_PVDDQ_GHJ_PH2_OCSET")
	)
	(segment
		(start 0.034544 -6.936486)
		(end 1.491742 -8.393684)
		(width 0.10795)
		(layer "F.Cu")
		(net "VR_PVDDQ_GHJ_PH1_OCSET")
	)
	(segment
		(start 1.491742 -8.393684)
		(end 2.067814 -8.393684)
		(width 0.10795)
		(layer "F.Cu")
		(net "VR_PVDDQ_GHJ_PH1_OCSET")
	)
	(segment
		(start -0.342138 -6.936486)
		(end 0.034544 -6.936486)
		(width 0.10795)
		(layer "F.Cu")
		(net "VR_PVDDQ_GHJ_PH1_OCSET")
	)
	(segment
		(start 350.771714 -146.393916)
		(end 350.97212 -146.594322)
		(width 0.10795)
		(layer "F.Cu")
		(net "VR_PVDDQ_DEF_PH2_OCSET")
	)
	(segment
		(start 350.357186 -146.393916)
		(end 350.771714 -146.393916)
		(width 0.10795)
		(layer "F.Cu")
		(net "VR_PVDDQ_DEF_PH2_OCSET")
	)
	(segment
		(start 350.97212 -146.594322)
		(end 351.603056 -146.594322)
		(width 0.10795)
		(layer "F.Cu")
		(net "VR_PVDDQ_DEF_PH2_OCSET")
	)
	(segment
		(start 351.913444 -147.193)
		(end 351.913444 -146.90471)
		(width 0.10795)
		(layer "F.Cu")
		(net "VR_PVDDQ_DEF_PH2_OCSET")
	)
	(segment
		(start 351.603056 -146.594322)
		(end 351.913444 -146.90471)
		(width 0.10795)
		(layer "F.Cu")
		(net "VR_PVDDQ_DEF_PH2_OCSET")
	)
	(segment
		(start 352.822764 -148.10232)
		(end 351.913444 -147.193)
		(width 0.10795)
		(layer "F.Cu")
		(net "VR_PVDDQ_DEF_PH2_OCSET")
	)
	(via
		(at 352.822764 -148.10232)
		(size 0.762)
		(drill 0.381)
		(layers "F.Cu" "B.Cu")
		(net "VR_PVDDQ_DEF_PH2_OCSET")
	)
	(segment
		(start 351.7265 -154.4193)
		(end 351.9932 -154.686)
		(width 0.10795)
		(layer "F.Cu")
		(net "VR_PVDDQ_DEF_PH1_OCSET")
	)
	(segment
		(start 350.711516 -154.318716)
		(end 350.8121 -154.4193)
		(width 0.10795)
		(layer "F.Cu")
		(net "VR_PVDDQ_DEF_PH1_OCSET")
	)
	(segment
		(start 350.8121 -154.4193)
		(end 351.7265 -154.4193)
		(width 0.10795)
		(layer "F.Cu")
		(net "VR_PVDDQ_DEF_PH1_OCSET")
	)
	(segment
		(start 350.357186 -154.318716)
		(end 350.711516 -154.318716)
		(width 0.10795)
		(layer "F.Cu")
		(net "VR_PVDDQ_DEF_PH1_OCSET")
	)
	(segment
		(start 350.529652 -0.328168)
		(end 351.0407 -0.328168)
		(width 0.10795)
		(layer "F.Cu")
		(net "VR_PVDDQ_ABC_PH2_OCSET")
	)
	(segment
		(start 349.55988 0.641604)
		(end 350.529652 -0.328168)
		(width 0.10795)
		(layer "F.Cu")
		(net "VR_PVDDQ_ABC_PH2_OCSET")
	)
	(segment
		(start 351.0407 -0.328168)
		(end 351.263204 -0.550672)
		(width 0.10795)
		(layer "F.Cu")
		(net "VR_PVDDQ_ABC_PH2_OCSET")
	)
	(segment
		(start 351.263204 -0.550672)
		(end 351.997772 -0.550672)
		(width 0.10795)
		(layer "F.Cu")
		(net "VR_PVDDQ_ABC_PH2_OCSET")
	)
	(segment
		(start 349.262192 0.641604)
		(end 349.55988 0.641604)
		(width 0.10795)
		(layer "F.Cu")
		(net "VR_PVDDQ_ABC_PH2_OCSET")
	)
	(segment
		(start 351.997772 -0.550672)
		(end 352.424238 -0.124206)
		(width 0.10795)
		(layer "F.Cu")
		(net "VR_PVDDQ_ABC_PH2_OCSET")
	)
	(segment
		(start 351.0534 -8.7503)
		(end 351.0534 -9.3599)
		(width 0.10795)
		(layer "F.Cu")
		(net "VR_PVDDQ_ABC_PH1_OCSET")
	)
	(segment
		(start 352.5012 -11.1506)
		(end 352.5012 -12.1412)
		(width 0.10795)
		(layer "F.Cu")
		(net "VR_PVDDQ_ABC_PH1_OCSET")
	)
	(segment
		(start 352.5012 -10.8077)
		(end 352.5012 -11.1506)
		(width 0.10795)
		(layer "F.Cu")
		(net "VR_PVDDQ_ABC_PH1_OCSET")
	)
	(segment
		(start 349.795592 -7.492492)
		(end 351.0534 -8.7503)
		(width 0.10795)
		(layer "F.Cu")
		(net "VR_PVDDQ_ABC_PH1_OCSET")
	)
	(segment
		(start 349.341186 -7.492492)
		(end 349.795592 -7.492492)
		(width 0.10795)
		(layer "F.Cu")
		(net "VR_PVDDQ_ABC_PH1_OCSET")
	)
	(segment
		(start 352.5012 -12.1412)
		(end 351.409 -13.2334)
		(width 0.10795)
		(layer "F.Cu")
		(net "VR_PVDDQ_ABC_PH1_OCSET")
	)
	(segment
		(start 351.0534 -9.3599)
		(end 352.5012 -10.8077)
		(width 0.10795)
		(layer "F.Cu")
		(net "VR_PVDDQ_ABC_PH1_OCSET")
	)
	(via
		(at 351.409 -13.2334)
		(size 0.762)
		(drill 0.381)
		(layers "F.Cu" "B.Cu")
		(net "VR_PVDDQ_ABC_PH1_OCSET")
	)
	(segment
		(start 180.862732 -55.447692)
		(end 181.204616 -55.789576)
		(width 0.1016)
		(layer "F.Cu")
		(net "VR_PVCCIO_CPU1_OCSET")
	)
	(segment
		(start 180.329586 -55.447692)
		(end 180.862732 -55.447692)
		(width 0.1016)
		(layer "F.Cu")
		(net "VR_PVCCIO_CPU1_OCSET")
	)
	(segment
		(start 181.204616 -55.789576)
		(end 181.519576 -55.789576)
		(width 0.1016)
		(layer "F.Cu")
		(net "VR_PVCCIO_CPU1_OCSET")
	)
	(segment
		(start 181.519576 -55.789576)
		(end 181.864 -56.134)
		(width 0.1016)
		(layer "F.Cu")
		(net "VR_PVCCIO_CPU1_OCSET")
	)
	(segment
		(start 181.864 -56.134)
		(end 182.372 -56.1594)
		(width 0.1016)
		(layer "F.Cu")
		(net "VR_PVCCIO_CPU1_OCSET")
	)
	(segment
		(start 352.09734 -99.03714)
		(end 351.8916 -98.8314)
		(width 0.1016)
		(layer "F.Cu")
		(net "VR_PVCCIO_CPU0_OCSET")
	)
	(segment
		(start 351.8916 -98.8314)
		(end 351.7646 -98.8314)
		(width 0.1016)
		(layer "F.Cu")
		(net "VR_PVCCIO_CPU0_OCSET")
	)
	(segment
		(start 350.38284 -98.8314)
		(end 350.196404 -98.644964)
		(width 0.1016)
		(layer "F.Cu")
		(net "VR_PVCCIO_CPU0_OCSET")
	)
	(segment
		(start 352.56343 -99.50323)
		(end 352.09734 -99.03714)
		(width 0.10795)
		(layer "F.Cu")
		(net "VR_PVCCIO_CPU0_OCSET")
	)
	(segment
		(start 351.256346 -98.8314)
		(end 350.38284 -98.8314)
		(width 0.1016)
		(layer "F.Cu")
		(net "VR_PVCCIO_CPU0_OCSET")
	)
	(segment
		(start 352.9838 -99.50323)
		(end 352.56343 -99.50323)
		(width 0.10795)
		(layer "F.Cu")
		(net "VR_PVCCIO_CPU0_OCSET")
	)
	(segment
		(start 350.196404 -98.644964)
		(end 349.927164 -98.644964)
		(width 0.1016)
		(layer "F.Cu")
		(net "VR_PVCCIO_CPU0_OCSET")
	)
	(segment
		(start 351.7646 -98.8314)
		(end 351.256346 -98.8314)
		(width 0.10795)
		(layer "F.Cu")
		(net "VR_PVCCIO_CPU0_OCSET")
	)
	(via
		(at 352.09734 -99.03714)
		(size 0.762)
		(drill 0.381)
		(layers "F.Cu" "B.Cu")
		(net "VR_PVCCIO_CPU0_OCSET")
	)
	(segment
		(start 28.743148 -55.771288)
		(end 28.98648 -56.01462)
		(width 0.10795)
		(layer "F.Cu")
		(net "VR_PVCCIN_CPU1_PH1_OCSET")
	)
	(segment
		(start 30.496764 -55.93969)
		(end 31.02991 -55.93969)
		(width 0.1016)
		(layer "F.Cu")
		(net "VR_PVCCIN_CPU1_PH1_OCSET")
	)
	(segment
		(start 27.990292 -55.771288)
		(end 28.743148 -55.771288)
		(width 0.10795)
		(layer "F.Cu")
		(net "VR_PVCCIN_CPU1_PH1_OCSET")
	)
	(segment
		(start 30.259274 -55.7022)
		(end 30.496764 -55.93969)
		(width 0.1016)
		(layer "F.Cu")
		(net "VR_PVCCIN_CPU1_PH1_OCSET")
	)
	(segment
		(start 28.98648 -56.01462)
		(end 29.2989 -55.7022)
		(width 0.1016)
		(layer "F.Cu")
		(net "VR_PVCCIN_CPU1_PH1_OCSET")
	)
	(segment
		(start 29.2989 -55.7022)
		(end 30.259274 -55.7022)
		(width 0.1016)
		(layer "F.Cu")
		(net "VR_PVCCIN_CPU1_PH1_OCSET")
	)
	(via
		(at 28.98648 -56.01462)
		(size 0.762)
		(drill 0.381)
		(layers "F.Cu" "B.Cu")
		(net "VR_PVCCIN_CPU1_PH1_OCSET")
	)
	(segment
		(start 193.6369 -88.19642)
		(end 193.80708 -88.19642)
		(width 0.10795)
		(layer "F.Cu")
		(net "VR_PVCCIN_CPU0_PH5_OCSET")
	)
	(segment
		(start 194.033648 -87.969852)
		(end 194.4878 -87.969852)
		(width 0.10795)
		(layer "F.Cu")
		(net "VR_PVCCIN_CPU0_PH5_OCSET")
	)
	(segment
		(start 195.180204 -88.105996)
		(end 195.525898 -88.45169)
		(width 0.10795)
		(layer "F.Cu")
		(net "VR_PVCCIN_CPU0_PH5_OCSET")
	)
	(segment
		(start 194.623944 -88.105996)
		(end 195.180204 -88.105996)
		(width 0.10795)
		(layer "F.Cu")
		(net "VR_PVCCIN_CPU0_PH5_OCSET")
	)
	(segment
		(start 193.80708 -88.19642)
		(end 194.033648 -87.969852)
		(width 0.10795)
		(layer "F.Cu")
		(net "VR_PVCCIN_CPU0_PH5_OCSET")
	)
	(segment
		(start 195.525898 -88.45169)
		(end 196.030342 -88.45169)
		(width 0.10795)
		(layer "F.Cu")
		(net "VR_PVCCIN_CPU0_PH5_OCSET")
	)
	(segment
		(start 194.4878 -87.969852)
		(end 194.623944 -88.105996)
		(width 0.10795)
		(layer "F.Cu")
		(net "VR_PVCCIN_CPU0_PH5_OCSET")
	)
	(segment
		(start 194.502278 -79.937356)
		(end 194.08013 -79.937356)
		(width 0.1016)
		(layer "F.Cu")
		(net "VR_PVCCIN_CPU0_PH4_OCSET")
	)
	(segment
		(start 194.622928 -80.058006)
		(end 194.502278 -79.937356)
		(width 0.1016)
		(layer "F.Cu")
		(net "VR_PVCCIN_CPU0_PH4_OCSET")
	)
	(segment
		(start 194.08013 -79.937356)
		(end 193.653918 -80.363568)
		(width 0.1016)
		(layer "F.Cu")
		(net "VR_PVCCIN_CPU0_PH4_OCSET")
	)
	(segment
		(start 193.0146 -78.533752)
		(end 193.653918 -79.17307)
		(width 0.10795)
		(layer "F.Cu")
		(net "VR_PVCCIN_CPU0_PH4_OCSET")
	)
	(segment
		(start 195.308728 -80.058006)
		(end 194.622928 -80.058006)
		(width 0.1016)
		(layer "F.Cu")
		(net "VR_PVCCIN_CPU0_PH4_OCSET")
	)
	(segment
		(start 193.653918 -79.17307)
		(end 193.653918 -80.363568)
		(width 0.10795)
		(layer "F.Cu")
		(net "VR_PVCCIN_CPU0_PH4_OCSET")
	)
	(segment
		(start 196.030342 -80.32369)
		(end 195.574412 -80.32369)
		(width 0.1016)
		(layer "F.Cu")
		(net "VR_PVCCIN_CPU0_PH4_OCSET")
	)
	(segment
		(start 195.574412 -80.32369)
		(end 195.308728 -80.058006)
		(width 0.1016)
		(layer "F.Cu")
		(net "VR_PVCCIN_CPU0_PH4_OCSET")
	)
	(via
		(at 193.0146 -78.533752)
		(size 0.762)
		(drill 0.381)
		(layers "F.Cu" "B.Cu")
		(net "VR_PVCCIN_CPU0_PH4_OCSET")
	)
	(segment
		(start 193.5099 -71.797672)
		(end 193.533268 -71.82104)
		(width 0.10795)
		(layer "F.Cu")
		(net "VR_PVCCIN_CPU0_PH3_OCSET")
	)
	(segment
		(start 195.30822 -71.81342)
		(end 193.540888 -71.81342)
		(width 0.10795)
		(layer "F.Cu")
		(net "VR_PVCCIN_CPU0_PH3_OCSET")
	)
	(segment
		(start 193.540888 -71.81342)
		(end 193.533268 -71.82104)
		(width 0.10795)
		(layer "F.Cu")
		(net "VR_PVCCIN_CPU0_PH3_OCSET")
	)
	(segment
		(start 193.5099 -70.88124)
		(end 193.5099 -71.797672)
		(width 0.10795)
		(layer "F.Cu")
		(net "VR_PVCCIN_CPU0_PH3_OCSET")
	)
	(segment
		(start 195.69049 -72.19569)
		(end 195.30822 -71.81342)
		(width 0.10795)
		(layer "F.Cu")
		(net "VR_PVCCIN_CPU0_PH3_OCSET")
	)
	(segment
		(start 196.030342 -72.19569)
		(end 195.69049 -72.19569)
		(width 0.10795)
		(layer "F.Cu")
		(net "VR_PVCCIN_CPU0_PH3_OCSET")
	)
	(via
		(at 193.533268 -71.82104)
		(size 0.762)
		(drill 0.381)
		(layers "F.Cu" "B.Cu")
		(net "VR_PVCCIN_CPU0_PH3_OCSET")
	)
	(segment
		(start 194.622928 -55.674006)
		(end 194.470528 -55.521606)
		(width 0.1016)
		(layer "F.Cu")
		(net "VR_PVCCIN_CPU0_PH1_OCSET")
	)
	(segment
		(start 194.357244 -55.521606)
		(end 194.129406 -55.521606)
		(width 0.10795)
		(layer "F.Cu")
		(net "VR_PVCCIN_CPU0_PH1_OCSET")
	)
	(segment
		(start 194.129406 -55.521606)
		(end 193.6242 -55.0164)
		(width 0.10795)
		(layer "F.Cu")
		(net "VR_PVCCIN_CPU0_PH1_OCSET")
	)
	(segment
		(start 196.030342 -55.93969)
		(end 195.574412 -55.93969)
		(width 0.1016)
		(layer "F.Cu")
		(net "VR_PVCCIN_CPU0_PH1_OCSET")
	)
	(segment
		(start 195.574412 -55.93969)
		(end 195.308728 -55.674006)
		(width 0.1016)
		(layer "F.Cu")
		(net "VR_PVCCIN_CPU0_PH1_OCSET")
	)
	(segment
		(start 195.308728 -55.674006)
		(end 194.622928 -55.674006)
		(width 0.1016)
		(layer "F.Cu")
		(net "VR_PVCCIN_CPU0_PH1_OCSET")
	)
	(segment
		(start 194.470528 -55.521606)
		(end 194.357244 -55.521606)
		(width 0.1016)
		(layer "F.Cu")
		(net "VR_PVCCIN_CPU0_PH1_OCSET")
	)
	(segment
		(start 384.294126 -156.565092)
		(end 384.294126 -157.045914)
		(width 0.10795)
		(layer "F.Cu")
		(net "VR_P1V05_PCH_STBY_OCSET")
	)
	(segment
		(start 384.294126 -157.045914)
		(end 383.845816 -157.494224)
		(width 0.10795)
		(layer "F.Cu")
		(net "VR_P1V05_PCH_STBY_OCSET")
	)
	(via
		(at 383.845816 -157.494224)
		(size 0.508)
		(drill 0.254)
		(layers "F.Cu" "B.Cu")
		(net "VR_P1V05_PCH_STBY_OCSET")
	)
	(via
		(at 385.104132 -156.472128)
		(size 0.6604)
		(drill 0.3302)
		(layers "F.Cu" "B.Cu")
		(net "VR_P1V05_PCH_STBY_OCSET")
	)
	(segment
		(start 384.170936 -156.472128)
		(end 384.0734 -156.569664)
		(width 0.10795)
		(layer "B.Cu")
		(net "VR_P1V05_PCH_STBY_OCSET")
	)
	(segment
		(start 384.0734 -157.26664)
		(end 384.0734 -156.569664)
		(width 0.10795)
		(layer "B.Cu")
		(net "VR_P1V05_PCH_STBY_OCSET")
	)
	(segment
		(start 385.104132 -156.472128)
		(end 384.170936 -156.472128)
		(width 0.10795)
		(layer "B.Cu")
		(net "VR_P1V05_PCH_STBY_OCSET")
	)
	(segment
		(start 383.845816 -157.494224)
		(end 384.0734 -157.26664)
		(width 0.10795)
		(layer "B.Cu")
		(net "VR_P1V05_PCH_STBY_OCSET")
	)
	(segment
		(start 185.1406 -75.4253)
		(end 185.1152 -75.3999)
		(width 0.254)
		(layer "F.Cu")
		(net "A_TSENSE_PVSA_CPU0")
	)
	(segment
		(start 195.057014 -96.593406)
		(end 194.317874 -96.593406)
		(width 0.254)
		(layer "F.Cu")
		(net "A_TSENSE_PVSA_CPU0")
	)
	(segment
		(start 184.8104 -73.787)
		(end 184.476898 -73.453498)
		(width 0.2032)
		(layer "F.Cu")
		(net "A_TSENSE_PVSA_CPU0")
	)
	(segment
		(start 184.476898 -73.453498)
		(end 184.476898 -72.7456)
		(width 0.2032)
		(layer "F.Cu")
		(net "A_TSENSE_PVSA_CPU0")
	)
	(segment
		(start 185.8264 -75.7174)
		(end 185.8264 -77.1398)
		(width 0.254)
		(layer "F.Cu")
		(net "A_TSENSE_PVSA_CPU0")
	)
	(segment
		(start 185.1152 -74.549)
		(end 184.8104 -74.2442)
		(width 0.2032)
		(layer "F.Cu")
		(net "A_TSENSE_PVSA_CPU0")
	)
	(segment
		(start 188.3918 -77.724)
		(end 188.8744 -77.2414)
		(width 0.254)
		(layer "F.Cu")
		(net "A_TSENSE_PVSA_CPU0")
	)
	(segment
		(start 186.4106 -77.724)
		(end 188.3918 -77.724)
		(width 0.254)
		(layer "F.Cu")
		(net "A_TSENSE_PVSA_CPU0")
	)
	(segment
		(start 184.8104 -74.2442)
		(end 184.8104 -73.787)
		(width 0.2032)
		(layer "F.Cu")
		(net "A_TSENSE_PVSA_CPU0")
	)
	(segment
		(start 194.317874 -96.593406)
		(end 194.299078 -96.612202)
		(width 0.254)
		(layer "F.Cu")
		(net "A_TSENSE_PVSA_CPU0")
	)
	(segment
		(start 196.017642 -97.029778)
		(end 195.493386 -97.029778)
		(width 0.254)
		(layer "F.Cu")
		(net "A_TSENSE_PVSA_CPU0")
	)
	(segment
		(start 185.1152 -74.7522)
		(end 185.1152 -74.549)
		(width 0.2032)
		(layer "F.Cu")
		(net "A_TSENSE_PVSA_CPU0")
	)
	(segment
		(start 185.1152 -75.3999)
		(end 185.1152 -74.7522)
		(width 0.254)
		(layer "F.Cu")
		(net "A_TSENSE_PVSA_CPU0")
	)
	(segment
		(start 195.493386 -97.029778)
		(end 195.057014 -96.593406)
		(width 0.254)
		(layer "F.Cu")
		(net "A_TSENSE_PVSA_CPU0")
	)
	(segment
		(start 185.1406 -75.4253)
		(end 185.5343 -75.4253)
		(width 0.254)
		(layer "F.Cu")
		(net "A_TSENSE_PVSA_CPU0")
	)
	(segment
		(start 185.5343 -75.4253)
		(end 185.8264 -75.7174)
		(width 0.254)
		(layer "F.Cu")
		(net "A_TSENSE_PVSA_CPU0")
	)
	(segment
		(start 185.8264 -77.1398)
		(end 186.4106 -77.724)
		(width 0.254)
		(layer "F.Cu")
		(net "A_TSENSE_PVSA_CPU0")
	)
	(via
		(at 188.8744 -77.2414)
		(size 0.508)
		(drill 0.254)
		(layers "F.Cu" "B.Cu")
		(net "A_TSENSE_PVSA_CPU0")
	)
	(via
		(at 194.299078 -96.612202)
		(size 0.508)
		(drill 0.254)
		(layers "F.Cu" "B.Cu")
		(net "A_TSENSE_PVSA_CPU0")
	)
	(segment
		(start 195.2244 -96.5708)
		(end 194.34048 -96.5708)
		(width 0.254)
		(layer "B.Cu")
		(net "A_TSENSE_PVSA_CPU0")
	)
	(segment
		(start 194.34048 -96.5708)
		(end 194.299078 -96.612202)
		(width 0.254)
		(layer "B.Cu")
		(net "A_TSENSE_PVSA_CPU0")
	)
	(segment
		(start 193.700908 -91.091766)
		(end 193.700908 -93.443044)
		(width 0.254)
		(layer "In11.Cu")
		(net "A_TSENSE_PVSA_CPU0")
	)
	(segment
		(start 188.8744 -77.2414)
		(end 189.0522 -77.4192)
		(width 0.254)
		(layer "In11.Cu")
		(net "A_TSENSE_PVSA_CPU0")
	)
	(segment
		(start 192.1764 -84.0486)
		(end 192.1764 -89.567258)
		(width 0.254)
		(layer "In11.Cu")
		(net "A_TSENSE_PVSA_CPU0")
	)
	(segment
		(start 189.0522 -80.9244)
		(end 192.1764 -84.0486)
		(width 0.254)
		(layer "In11.Cu")
		(net "A_TSENSE_PVSA_CPU0")
	)
	(segment
		(start 193.700908 -93.443044)
		(end 194.977004 -94.71914)
		(width 0.254)
		(layer "In11.Cu")
		(net "A_TSENSE_PVSA_CPU0")
	)
	(segment
		(start 189.0522 -77.4192)
		(end 189.0522 -80.9244)
		(width 0.254)
		(layer "In11.Cu")
		(net "A_TSENSE_PVSA_CPU0")
	)
	(segment
		(start 192.1764 -89.567258)
		(end 193.700908 -91.091766)
		(width 0.254)
		(layer "In11.Cu")
		(net "A_TSENSE_PVSA_CPU0")
	)
	(segment
		(start 194.977004 -95.934276)
		(end 194.299078 -96.612202)
		(width 0.254)
		(layer "In11.Cu")
		(net "A_TSENSE_PVSA_CPU0")
	)
	(segment
		(start 194.977004 -94.71914)
		(end 194.977004 -95.934276)
		(width 0.254)
		(layer "In11.Cu")
		(net "A_TSENSE_PVSA_CPU0")
	)
	(segment
		(start 392.6332 -154.1272)
		(end 392.119612 -154.1272)
		(width 0.1778)
		(layer "F.Cu")
		(net "A_TSENSE_PVNN_PCH_TMON")
	)
	(segment
		(start 375.717562 -156.920438)
		(end 375.717562 -156.24302)
		(width 0.254)
		(layer "F.Cu")
		(net "A_TSENSE_PVNN_PCH_TMON")
	)
	(segment
		(start 375.5136 -157.3276)
		(end 375.539 -157.3022)
		(width 0.254)
		(layer "F.Cu")
		(net "A_TSENSE_PVNN_PCH_TMON")
	)
	(segment
		(start 392.119612 -154.1272)
		(end 392.099038 -154.106626)
		(width 0.1778)
		(layer "F.Cu")
		(net "A_TSENSE_PVNN_PCH_TMON")
	)
	(segment
		(start 393.3317 -153.996898)
		(end 392.763502 -153.996898)
		(width 0.1778)
		(layer "F.Cu")
		(net "A_TSENSE_PVNN_PCH_TMON")
	)
	(segment
		(start 375.539 -157.099)
		(end 375.717562 -156.920438)
		(width 0.254)
		(layer "F.Cu")
		(net "A_TSENSE_PVNN_PCH_TMON")
	)
	(segment
		(start 392.763502 -153.996898)
		(end 392.6332 -154.1272)
		(width 0.1778)
		(layer "F.Cu")
		(net "A_TSENSE_PVNN_PCH_TMON")
	)
	(segment
		(start 375.539 -157.3022)
		(end 375.539 -157.099)
		(width 0.254)
		(layer "F.Cu")
		(net "A_TSENSE_PVNN_PCH_TMON")
	)
	(segment
		(start 375.5136 -158.2166)
		(end 375.5136 -157.3276)
		(width 0.254)
		(layer "F.Cu")
		(net "A_TSENSE_PVNN_PCH_TMON")
	)
	(via
		(at 375.539 -157.3022)
		(size 0.508)
		(drill 0.254)
		(layers "F.Cu" "B.Cu")
		(net "A_TSENSE_PVNN_PCH_TMON")
	)
	(via
		(at 392.099038 -154.106626)
		(size 0.508)
		(drill 0.254)
		(layers "F.Cu" "B.Cu")
		(net "A_TSENSE_PVNN_PCH_TMON")
	)
	(segment
		(start 392.099038 -154.106626)
		(end 392.099038 -153.910538)
		(width 0.254)
		(layer "B.Cu")
		(net "A_TSENSE_PVNN_PCH_TMON")
	)
	(segment
		(start 392.099038 -153.910538)
		(end 391.65022 -153.46172)
		(width 0.254)
		(layer "B.Cu")
		(net "A_TSENSE_PVNN_PCH_TMON")
	)
	(segment
		(start 386.46862 -153.797)
		(end 375.11228 -153.797)
		(width 0.254)
		(layer "In4.Cu")
		(net "A_TSENSE_PVNN_PCH_TMON")
	)
	(segment
		(start 374.36298 -154.5463)
		(end 374.36298 -155.685236)
		(width 0.254)
		(layer "In4.Cu")
		(net "A_TSENSE_PVNN_PCH_TMON")
	)
	(segment
		(start 386.864606 -153.401014)
		(end 386.46862 -153.797)
		(width 0.254)
		(layer "In4.Cu")
		(net "A_TSENSE_PVNN_PCH_TMON")
	)
	(segment
		(start 375.539 -156.861256)
		(end 375.539 -157.3022)
		(width 0.254)
		(layer "In4.Cu")
		(net "A_TSENSE_PVNN_PCH_TMON")
	)
	(segment
		(start 391.346944 -153.401014)
		(end 386.864606 -153.401014)
		(width 0.254)
		(layer "In4.Cu")
		(net "A_TSENSE_PVNN_PCH_TMON")
	)
	(segment
		(start 392.052556 -154.106626)
		(end 391.346944 -153.401014)
		(width 0.254)
		(layer "In4.Cu")
		(net "A_TSENSE_PVNN_PCH_TMON")
	)
	(segment
		(start 374.36298 -155.685236)
		(end 375.539 -156.861256)
		(width 0.254)
		(layer "In4.Cu")
		(net "A_TSENSE_PVNN_PCH_TMON")
	)
	(segment
		(start 392.099038 -154.106626)
		(end 392.052556 -154.106626)
		(width 0.254)
		(layer "In4.Cu")
		(net "A_TSENSE_PVNN_PCH_TMON")
	)
	(segment
		(start 375.11228 -153.797)
		(end 374.36298 -154.5463)
		(width 0.254)
		(layer "In4.Cu")
		(net "A_TSENSE_PVNN_PCH_TMON")
	)
	(segment
		(start -1.454404 -146.678396)
		(end -1.7526 -146.3802)
		(width 0.254)
		(layer "F.Cu")
		(net "A_TSENSE_PVDDQ_KLM")
	)
	(segment
		(start -3.751834 -137.2108)
		(end -3.802634 -137.16)
		(width 0.254)
		(layer "F.Cu")
		(net "A_TSENSE_PVDDQ_KLM")
	)
	(segment
		(start -3.302 -145.796)
		(end -4.445 -145.796)
		(width 0.254)
		(layer "F.Cu")
		(net "A_TSENSE_PVDDQ_KLM")
	)
	(segment
		(start -0.497586 -146.678396)
		(end -1.454404 -146.678396)
		(width 0.254)
		(layer "F.Cu")
		(net "A_TSENSE_PVDDQ_KLM")
	)
	(segment
		(start -2.7178 -146.3802)
		(end -3.302 -145.796)
		(width 0.254)
		(layer "F.Cu")
		(net "A_TSENSE_PVDDQ_KLM")
	)
	(segment
		(start 5.104384 -127.765302)
		(end 4.5085 -127.765302)
		(width 0.2032)
		(layer "F.Cu")
		(net "A_TSENSE_PVDDQ_KLM")
	)
	(segment
		(start 5.712714 -126.92634)
		(end 5.712714 -127.156972)
		(width 0.2032)
		(layer "F.Cu")
		(net "A_TSENSE_PVDDQ_KLM")
	)
	(segment
		(start -0.497586 -137.534396)
		(end -1.620774 -137.534396)
		(width 0.254)
		(layer "F.Cu")
		(net "A_TSENSE_PVDDQ_KLM")
	)
	(segment
		(start -1.620774 -137.534396)
		(end -1.94437 -137.2108)
		(width 0.254)
		(layer "F.Cu")
		(net "A_TSENSE_PVDDQ_KLM")
	)
	(segment
		(start -1.7526 -146.3802)
		(end -2.7178 -146.3802)
		(width 0.254)
		(layer "F.Cu")
		(net "A_TSENSE_PVDDQ_KLM")
	)
	(segment
		(start 6.35 -126.111)
		(end 6.35 -126.289054)
		(width 0.2032)
		(layer "F.Cu")
		(net "A_TSENSE_PVDDQ_KLM")
	)
	(segment
		(start 5.712714 -127.156972)
		(end 5.104384 -127.765302)
		(width 0.2032)
		(layer "F.Cu")
		(net "A_TSENSE_PVDDQ_KLM")
	)
	(segment
		(start 6.35 -126.289054)
		(end 5.712714 -126.92634)
		(width 0.2032)
		(layer "F.Cu")
		(net "A_TSENSE_PVDDQ_KLM")
	)
	(segment
		(start -1.94437 -137.2108)
		(end -3.751834 -137.2108)
		(width 0.254)
		(layer "F.Cu")
		(net "A_TSENSE_PVDDQ_KLM")
	)
	(via
		(at 5.712714 -127.156972)
		(size 0.508)
		(drill 0.254)
		(layers "F.Cu" "B.Cu")
		(net "A_TSENSE_PVDDQ_KLM")
	)
	(via
		(at -3.802634 -137.16)
		(size 0.508)
		(drill 0.254)
		(layers "F.Cu" "B.Cu")
		(net "A_TSENSE_PVDDQ_KLM")
	)
	(via
		(at -2.3368 -145.8976)
		(size 0.6604)
		(drill 0.3302)
		(layers "F.Cu" "B.Cu")
		(net "A_TSENSE_PVDDQ_KLM")
	)
	(via
		(at -2.413 -137.0076)
		(size 0.6604)
		(drill 0.3302)
		(layers "F.Cu" "B.Cu")
		(net "A_TSENSE_PVDDQ_KLM")
	)
	(via
		(at -4.445 -145.796)
		(size 0.508)
		(drill 0.254)
		(layers "F.Cu" "B.Cu")
		(net "A_TSENSE_PVDDQ_KLM")
	)
	(segment
		(start -1.951482 -137.0076)
		(end -1.189482 -137.7696)
		(width 0.254)
		(layer "B.Cu")
		(net "A_TSENSE_PVDDQ_KLM")
	)
	(segment
		(start -1.189482 -137.7696)
		(end -0.6604 -137.7696)
		(width 0.254)
		(layer "B.Cu")
		(net "A_TSENSE_PVDDQ_KLM")
	)
	(segment
		(start -2.2606 -145.8214)
		(end -1.3335 -145.8214)
		(width 0.254)
		(layer "B.Cu")
		(net "A_TSENSE_PVDDQ_KLM")
	)
	(segment
		(start -4.390898 -145.850102)
		(end -2.384298 -145.850102)
		(width 0.254)
		(layer "B.Cu")
		(net "A_TSENSE_PVDDQ_KLM")
	)
	(segment
		(start -3.802634 -137.16)
		(end -3.650234 -137.0076)
		(width 0.254)
		(layer "B.Cu")
		(net "A_TSENSE_PVDDQ_KLM")
	)
	(segment
		(start -4.445 -145.796)
		(end -4.390898 -145.850102)
		(width 0.254)
		(layer "B.Cu")
		(net "A_TSENSE_PVDDQ_KLM")
	)
	(segment
		(start -2.413 -137.0076)
		(end -1.951482 -137.0076)
		(width 0.254)
		(layer "B.Cu")
		(net "A_TSENSE_PVDDQ_KLM")
	)
	(segment
		(start -2.3368 -145.8976)
		(end -2.2606 -145.8214)
		(width 0.254)
		(layer "B.Cu")
		(net "A_TSENSE_PVDDQ_KLM")
	)
	(segment
		(start -3.650234 -137.0076)
		(end -2.413 -137.0076)
		(width 0.254)
		(layer "B.Cu")
		(net "A_TSENSE_PVDDQ_KLM")
	)
	(segment
		(start -2.384298 -145.850102)
		(end -2.3368 -145.8976)
		(width 0.254)
		(layer "B.Cu")
		(net "A_TSENSE_PVDDQ_KLM")
	)
	(segment
		(start -3.485388 -136.842754)
		(end -3.802634 -137.16)
		(width 0.254)
		(layer "In2.Cu")
		(net "A_TSENSE_PVDDQ_KLM")
	)
	(segment
		(start 0.04826 -131.37896)
		(end 0.04826 -132.0292)
		(width 0.254)
		(layer "In2.Cu")
		(net "A_TSENSE_PVDDQ_KLM")
	)
	(segment
		(start 3.26644 -127.3429)
		(end 2.52222 -128.08712)
		(width 0.254)
		(layer "In2.Cu")
		(net "A_TSENSE_PVDDQ_KLM")
	)
	(segment
		(start -3.802634 -137.16)
		(end -5.23494 -138.592306)
		(width 0.254)
		(layer "In2.Cu")
		(net "A_TSENSE_PVDDQ_KLM")
	)
	(segment
		(start -1.73228 -134.965694)
		(end -1.73228 -136.30656)
		(width 0.254)
		(layer "In2.Cu")
		(net "A_TSENSE_PVDDQ_KLM")
	)
	(segment
		(start 2.52222 -128.905)
		(end 0.04826 -131.37896)
		(width 0.254)
		(layer "In2.Cu")
		(net "A_TSENSE_PVDDQ_KLM")
	)
	(segment
		(start -2.268474 -136.842754)
		(end -3.485388 -136.842754)
		(width 0.254)
		(layer "In2.Cu")
		(net "A_TSENSE_PVDDQ_KLM")
	)
	(segment
		(start -5.23494 -138.592306)
		(end -5.23494 -145.00606)
		(width 0.254)
		(layer "In2.Cu")
		(net "A_TSENSE_PVDDQ_KLM")
	)
	(segment
		(start 2.52222 -128.08712)
		(end 2.52222 -128.905)
		(width 0.254)
		(layer "In2.Cu")
		(net "A_TSENSE_PVDDQ_KLM")
	)
	(segment
		(start -0.716026 -133.94944)
		(end -1.73228 -134.965694)
		(width 0.254)
		(layer "In2.Cu")
		(net "A_TSENSE_PVDDQ_KLM")
	)
	(segment
		(start 5.712714 -127.156972)
		(end 5.526786 -127.3429)
		(width 0.254)
		(layer "In2.Cu")
		(net "A_TSENSE_PVDDQ_KLM")
	)
	(segment
		(start 0.91694 -133.47954)
		(end 0.44704 -133.94944)
		(width 0.254)
		(layer "In2.Cu")
		(net "A_TSENSE_PVDDQ_KLM")
	)
	(segment
		(start -5.23494 -145.00606)
		(end -4.445 -145.796)
		(width 0.254)
		(layer "In2.Cu")
		(net "A_TSENSE_PVDDQ_KLM")
	)
	(segment
		(start 5.526786 -127.3429)
		(end 3.26644 -127.3429)
		(width 0.254)
		(layer "In2.Cu")
		(net "A_TSENSE_PVDDQ_KLM")
	)
	(segment
		(start -1.73228 -136.30656)
		(end -2.268474 -136.842754)
		(width 0.254)
		(layer "In2.Cu")
		(net "A_TSENSE_PVDDQ_KLM")
	)
	(segment
		(start 0.04826 -132.0292)
		(end 0.91694 -132.89788)
		(width 0.254)
		(layer "In2.Cu")
		(net "A_TSENSE_PVDDQ_KLM")
	)
	(segment
		(start 0.44704 -133.94944)
		(end -0.716026 -133.94944)
		(width 0.254)
		(layer "In2.Cu")
		(net "A_TSENSE_PVDDQ_KLM")
	)
	(segment
		(start 0.91694 -132.89788)
		(end 0.91694 -133.47954)
		(width 0.254)
		(layer "In2.Cu")
		(net "A_TSENSE_PVDDQ_KLM")
	)
	(segment
		(start 6.560058 4.307332)
		(end 7.333234 4.307332)
		(width 0.254)
		(layer "F.Cu")
		(net "A_TSENSE_PVDDQ_GHJ")
	)
	(segment
		(start 9.50214 4.1402)
		(end 9.335008 4.307332)
		(width 0.254)
		(layer "F.Cu")
		(net "A_TSENSE_PVDDQ_GHJ")
	)
	(segment
		(start 9.5758 4.06654)
		(end 9.50214 4.1402)
		(width 0.2032)
		(layer "F.Cu")
		(net "A_TSENSE_PVDDQ_GHJ")
	)
	(segment
		(start 1.0414 -8.636)
		(end 1.193546 -8.636)
		(width 0.254)
		(layer "F.Cu")
		(net "A_TSENSE_PVDDQ_GHJ")
	)
	(segment
		(start 9.5758 3.435604)
		(end 9.5758 4.06654)
		(width 0.2032)
		(layer "F.Cu")
		(net "A_TSENSE_PVDDQ_GHJ")
	)
	(segment
		(start 1.401318 -8.843772)
		(end 2.067814 -8.843772)
		(width 0.254)
		(layer "F.Cu")
		(net "A_TSENSE_PVDDQ_GHJ")
	)
	(segment
		(start 1.193546 -8.636)
		(end 1.401318 -8.843772)
		(width 0.254)
		(layer "F.Cu")
		(net "A_TSENSE_PVDDQ_GHJ")
	)
	(segment
		(start -0.37338 -16.23314)
		(end 1.19126 -16.23314)
		(width 0.254)
		(layer "F.Cu")
		(net "A_TSENSE_PVDDQ_GHJ")
	)
	(segment
		(start 1.76911 -16.81099)
		(end 2.150364 -16.81099)
		(width 0.254)
		(layer "F.Cu")
		(net "A_TSENSE_PVDDQ_GHJ")
	)
	(segment
		(start 0.152908 -7.747508)
		(end 1.0414 -8.636)
		(width 0.254)
		(layer "F.Cu")
		(net "A_TSENSE_PVDDQ_GHJ")
	)
	(segment
		(start 9.833102 3.178302)
		(end 9.5758 3.435604)
		(width 0.2032)
		(layer "F.Cu")
		(net "A_TSENSE_PVDDQ_GHJ")
	)
	(segment
		(start 9.335008 4.307332)
		(end 7.333234 4.307332)
		(width 0.254)
		(layer "F.Cu")
		(net "A_TSENSE_PVDDQ_GHJ")
	)
	(segment
		(start 1.19126 -16.23314)
		(end 1.76911 -16.81099)
		(width 0.254)
		(layer "F.Cu")
		(net "A_TSENSE_PVDDQ_GHJ")
	)
	(segment
		(start 9.833102 2.69875)
		(end 9.833102 3.178302)
		(width 0.2032)
		(layer "F.Cu")
		(net "A_TSENSE_PVDDQ_GHJ")
	)
	(via
		(at 6.560058 4.307332)
		(size 0.508)
		(drill 0.254)
		(layers "F.Cu" "B.Cu")
		(net "A_TSENSE_PVDDQ_GHJ")
	)
	(via
		(at 0.152908 -7.747508)
		(size 0.508)
		(drill 0.254)
		(layers "F.Cu" "B.Cu")
		(net "A_TSENSE_PVDDQ_GHJ")
	)
	(via
		(at -0.37338 -16.23314)
		(size 0.508)
		(drill 0.254)
		(layers "F.Cu" "B.Cu")
		(net "A_TSENSE_PVDDQ_GHJ")
	)
	(via
		(at 0.665734 -8.366506)
		(size 0.6604)
		(drill 0.3302)
		(layers "F.Cu" "B.Cu")
		(net "A_TSENSE_PVDDQ_GHJ")
	)
	(segment
		(start -0.37338 -16.23314)
		(end -0.09144 -15.9512)
		(width 0.254)
		(layer "B.Cu")
		(net "A_TSENSE_PVDDQ_GHJ")
	)
	(segment
		(start -0.09144 -15.9512)
		(end 1.27 -15.9512)
		(width 0.254)
		(layer "B.Cu")
		(net "A_TSENSE_PVDDQ_GHJ")
	)
	(segment
		(start 0.665734 -8.366506)
		(end 0.757428 -8.4582)
		(width 0.254)
		(layer "B.Cu")
		(net "A_TSENSE_PVDDQ_GHJ")
	)
	(segment
		(start 0.757428 -8.4582)
		(end 1.9304 -8.4582)
		(width 0.254)
		(layer "B.Cu")
		(net "A_TSENSE_PVDDQ_GHJ")
	)
	(segment
		(start 0.152908 -7.85368)
		(end 0.665734 -8.366506)
		(width 0.254)
		(layer "B.Cu")
		(net "A_TSENSE_PVDDQ_GHJ")
	)
	(segment
		(start 0.152908 -7.747508)
		(end 0.152908 -7.85368)
		(width 0.254)
		(layer "B.Cu")
		(net "A_TSENSE_PVDDQ_GHJ")
	)
	(segment
		(start -2.95148 -13.878814)
		(end -1.31318 -13.878814)
		(width 0.254)
		(layer "In4.Cu")
		(net "A_TSENSE_PVDDQ_GHJ")
	)
	(segment
		(start -0.6858 -15.92072)
		(end -0.37338 -16.23314)
		(width 0.254)
		(layer "In4.Cu")
		(net "A_TSENSE_PVDDQ_GHJ")
	)
	(segment
		(start -3.67284 -13.157454)
		(end -2.95148 -13.878814)
		(width 0.254)
		(layer "In4.Cu")
		(net "A_TSENSE_PVDDQ_GHJ")
	)
	(segment
		(start 6.339078 4.086352)
		(end -2.009648 4.086352)
		(width 0.254)
		(layer "In4.Cu")
		(net "A_TSENSE_PVDDQ_GHJ")
	)
	(segment
		(start -4.5974 1.4986)
		(end -4.5974 -2.9972)
		(width 0.254)
		(layer "In4.Cu")
		(net "A_TSENSE_PVDDQ_GHJ")
	)
	(segment
		(start -1.31318 -13.878814)
		(end -0.6858 -14.506194)
		(width 0.254)
		(layer "In4.Cu")
		(net "A_TSENSE_PVDDQ_GHJ")
	)
	(segment
		(start 0.152908 -7.747508)
		(end 0.152908 -8.909812)
		(width 0.254)
		(layer "In4.Cu")
		(net "A_TSENSE_PVDDQ_GHJ")
	)
	(segment
		(start -4.5974 -2.9972)
		(end 0.152908 -7.747508)
		(width 0.254)
		(layer "In4.Cu")
		(net "A_TSENSE_PVDDQ_GHJ")
	)
	(segment
		(start -2.009648 4.086352)
		(end -4.5974 1.4986)
		(width 0.254)
		(layer "In4.Cu")
		(net "A_TSENSE_PVDDQ_GHJ")
	)
	(segment
		(start -3.67284 -10.3632)
		(end -3.67284 -13.157454)
		(width 0.254)
		(layer "In4.Cu")
		(net "A_TSENSE_PVDDQ_GHJ")
	)
	(segment
		(start -0.6858 -14.506194)
		(end -0.6858 -15.92072)
		(width 0.254)
		(layer "In4.Cu")
		(net "A_TSENSE_PVDDQ_GHJ")
	)
	(segment
		(start 0.152908 -8.909812)
		(end -0.77724 -9.83996)
		(width 0.254)
		(layer "In4.Cu")
		(net "A_TSENSE_PVDDQ_GHJ")
	)
	(segment
		(start -0.77724 -9.83996)
		(end -3.1496 -9.83996)
		(width 0.254)
		(layer "In4.Cu")
		(net "A_TSENSE_PVDDQ_GHJ")
	)
	(segment
		(start 6.560058 4.307332)
		(end 6.339078 4.086352)
		(width 0.254)
		(layer "In4.Cu")
		(net "A_TSENSE_PVDDQ_GHJ")
	)
	(segment
		(start -3.1496 -9.83996)
		(end -3.67284 -10.3632)
		(width 0.254)
		(layer "In4.Cu")
		(net "A_TSENSE_PVDDQ_GHJ")
	)
	(segment
		(start 354.85324 -141.470888)
		(end 355.654864 -142.272512)
		(width 0.254)
		(layer "F.Cu")
		(net "A_TSENSE_PVDDQ_DEF")
	)
	(segment
		(start 354.89769 -139.81557)
		(end 356.348792 -138.364468)
		(width 0.2032)
		(layer "F.Cu")
		(net "A_TSENSE_PVDDQ_DEF")
	)
	(segment
		(start 354.85324 -140.009626)
		(end 354.85324 -141.470888)
		(width 0.254)
		(layer "F.Cu")
		(net "A_TSENSE_PVDDQ_DEF")
	)
	(segment
		(start 354.89769 -139.965176)
		(end 354.89769 -139.81557)
		(width 0.2032)
		(layer "F.Cu")
		(net "A_TSENSE_PVDDQ_DEF")
	)
	(segment
		(start 350.871028 -153.868628)
		(end 351.0026 -154.0002)
		(width 0.254)
		(layer "F.Cu")
		(net "A_TSENSE_PVDDQ_DEF")
	)
	(segment
		(start 350.357186 -145.943828)
		(end 350.947228 -145.943828)
		(width 0.254)
		(layer "F.Cu")
		(net "A_TSENSE_PVDDQ_DEF")
	)
	(segment
		(start 354.89769 -139.965176)
		(end 354.85324 -140.009626)
		(width 0.254)
		(layer "F.Cu")
		(net "A_TSENSE_PVDDQ_DEF")
	)
	(segment
		(start 351.0026 -154.0002)
		(end 351.0788 -154.0002)
		(width 0.254)
		(layer "F.Cu")
		(net "A_TSENSE_PVDDQ_DEF")
	)
	(segment
		(start 356.348792 -138.364468)
		(end 356.84714 -138.364468)
		(width 0.2032)
		(layer "F.Cu")
		(net "A_TSENSE_PVDDQ_DEF")
	)
	(segment
		(start 350.947228 -145.943828)
		(end 351.155 -146.1516)
		(width 0.254)
		(layer "F.Cu")
		(net "A_TSENSE_PVDDQ_DEF")
	)
	(segment
		(start 350.357186 -153.868628)
		(end 350.871028 -153.868628)
		(width 0.254)
		(layer "F.Cu")
		(net "A_TSENSE_PVDDQ_DEF")
	)
	(via
		(at 355.654864 -142.272512)
		(size 0.508)
		(drill 0.254)
		(layers "F.Cu" "B.Cu")
		(net "A_TSENSE_PVDDQ_DEF")
	)
	(via
		(at 351.0788 -154.0002)
		(size 0.508)
		(drill 0.254)
		(layers "F.Cu" "B.Cu")
		(net "A_TSENSE_PVDDQ_DEF")
	)
	(via
		(at 351.155 -146.1516)
		(size 0.508)
		(drill 0.254)
		(layers "F.Cu" "B.Cu")
		(net "A_TSENSE_PVDDQ_DEF")
	)
	(segment
		(start 350.2914 -145.923)
		(end 350.9264 -145.923)
		(width 0.254)
		(layer "B.Cu")
		(net "A_TSENSE_PVDDQ_DEF")
	)
	(segment
		(start 350.3168 -153.8732)
		(end 350.4438 -154.0002)
		(width 0.254)
		(layer "B.Cu")
		(net "A_TSENSE_PVDDQ_DEF")
	)
	(segment
		(start 350.4438 -154.0002)
		(end 351.0788 -154.0002)
		(width 0.254)
		(layer "B.Cu")
		(net "A_TSENSE_PVDDQ_DEF")
	)
	(segment
		(start 350.9264 -145.923)
		(end 351.155 -146.1516)
		(width 0.254)
		(layer "B.Cu")
		(net "A_TSENSE_PVDDQ_DEF")
	)
	(segment
		(start 352.1202 -147.12315)
		(end 351.235264 -146.238214)
		(width 0.254)
		(layer "In11.Cu")
		(net "A_TSENSE_PVDDQ_DEF")
	)
	(segment
		(start 352.1202 -151.816054)
		(end 352.1202 -147.12315)
		(width 0.254)
		(layer "In11.Cu")
		(net "A_TSENSE_PVDDQ_DEF")
	)
	(segment
		(start 351.09912 -146.09572)
		(end 351.09912 -145.089626)
		(width 0.254)
		(layer "In11.Cu")
		(net "A_TSENSE_PVDDQ_DEF")
	)
	(segment
		(start 351.235264 -146.238214)
		(end 351.235264 -146.231864)
		(width 0.254)
		(layer "In11.Cu")
		(net "A_TSENSE_PVDDQ_DEF")
	)
	(segment
		(start 351.0788 -154.0002)
		(end 351.0788 -152.857454)
		(width 0.254)
		(layer "In11.Cu")
		(net "A_TSENSE_PVDDQ_DEF")
	)
	(segment
		(start 351.235264 -146.231864)
		(end 351.155 -146.1516)
		(width 0.254)
		(layer "In11.Cu")
		(net "A_TSENSE_PVDDQ_DEF")
	)
	(segment
		(start 351.09912 -145.089626)
		(end 353.916234 -142.272512)
		(width 0.254)
		(layer "In11.Cu")
		(net "A_TSENSE_PVDDQ_DEF")
	)
	(segment
		(start 353.916234 -142.272512)
		(end 355.654864 -142.272512)
		(width 0.254)
		(layer "In11.Cu")
		(net "A_TSENSE_PVDDQ_DEF")
	)
	(segment
		(start 351.0788 -152.857454)
		(end 352.1202 -151.816054)
		(width 0.254)
		(layer "In11.Cu")
		(net "A_TSENSE_PVDDQ_DEF")
	)
	(segment
		(start 351.155 -146.1516)
		(end 351.09912 -146.09572)
		(width 0.254)
		(layer "In11.Cu")
		(net "A_TSENSE_PVDDQ_DEF")
	)
	(segment
		(start 350.232726 -7.493)
		(end 350.575372 -7.493)
		(width 0.254)
		(layer "F.Cu")
		(net "A_TSENSE_PVDDQ_ABC")
	)
	(segment
		(start 349.123 -14.097)
		(end 349.123 -13.843)
		(width 0.254)
		(layer "F.Cu")
		(net "A_TSENSE_PVDDQ_ABC")
	)
	(segment
		(start 351.134172 -8.0518)
		(end 350.7613 -7.678928)
		(width 0.254)
		(layer "F.Cu")
		(net "A_TSENSE_PVDDQ_ABC")
	)
	(segment
		(start 351.630234 -0.12192)
		(end 351.36074 -0.12192)
		(width 0.254)
		(layer "F.Cu")
		(net "A_TSENSE_PVDDQ_ABC")
	)
	(segment
		(start 349.78213 -7.042404)
		(end 350.232726 -7.493)
		(width 0.254)
		(layer "F.Cu")
		(net "A_TSENSE_PVDDQ_ABC")
	)
	(segment
		(start 349.656908 1.091692)
		(end 350.641412 0.107188)
		(width 0.254)
		(layer "F.Cu")
		(net "A_TSENSE_PVDDQ_ABC")
	)
	(segment
		(start 350.575372 -7.493)
		(end 350.7613 -7.678928)
		(width 0.254)
		(layer "F.Cu")
		(net "A_TSENSE_PVDDQ_ABC")
	)
	(segment
		(start 351.136204 0.102616)
		(end 350.696784 0.102616)
		(width 0.254)
		(layer "F.Cu")
		(net "A_TSENSE_PVDDQ_ABC")
	)
	(segment
		(start 350.641412 0.107188)
		(end 350.692212 0.107188)
		(width 0.254)
		(layer "F.Cu")
		(net "A_TSENSE_PVDDQ_ABC")
	)
	(segment
		(start 348.775528 -13.843)
		(end 349.123 -13.843)
		(width 0.2032)
		(layer "F.Cu")
		(net "A_TSENSE_PVDDQ_ABC")
	)
	(segment
		(start 347.491812 -15.167102)
		(end 347.7006 -14.958314)
		(width 0.2032)
		(layer "F.Cu")
		(net "A_TSENSE_PVDDQ_ABC")
	)
	(segment
		(start 351.058988 -14.351)
		(end 349.377 -14.351)
		(width 0.254)
		(layer "F.Cu")
		(net "A_TSENSE_PVDDQ_ABC")
	)
	(segment
		(start 351.36074 -0.12192)
		(end 351.136204 0.102616)
		(width 0.254)
		(layer "F.Cu")
		(net "A_TSENSE_PVDDQ_ABC")
	)
	(segment
		(start 349.341186 -7.042404)
		(end 349.78213 -7.042404)
		(width 0.254)
		(layer "F.Cu")
		(net "A_TSENSE_PVDDQ_ABC")
	)
	(segment
		(start 347.7006 -14.958314)
		(end 347.7006 -14.917928)
		(width 0.2032)
		(layer "F.Cu")
		(net "A_TSENSE_PVDDQ_ABC")
	)
	(segment
		(start 347.1291 -15.167102)
		(end 347.491812 -15.167102)
		(width 0.2032)
		(layer "F.Cu")
		(net "A_TSENSE_PVDDQ_ABC")
	)
	(segment
		(start 350.696784 0.102616)
		(end 350.692212 0.107188)
		(width 0.254)
		(layer "F.Cu")
		(net "A_TSENSE_PVDDQ_ABC")
	)
	(segment
		(start 351.5868 -8.0518)
		(end 351.134172 -8.0518)
		(width 0.254)
		(layer "F.Cu")
		(net "A_TSENSE_PVDDQ_ABC")
	)
	(segment
		(start 347.7006 -14.917928)
		(end 348.775528 -13.843)
		(width 0.2032)
		(layer "F.Cu")
		(net "A_TSENSE_PVDDQ_ABC")
	)
	(segment
		(start 351.325434 -14.617446)
		(end 351.058988 -14.351)
		(width 0.254)
		(layer "F.Cu")
		(net "A_TSENSE_PVDDQ_ABC")
	)
	(segment
		(start 349.262192 1.091692)
		(end 349.656908 1.091692)
		(width 0.254)
		(layer "F.Cu")
		(net "A_TSENSE_PVDDQ_ABC")
	)
	(segment
		(start 349.377 -14.351)
		(end 349.123 -14.097)
		(width 0.254)
		(layer "F.Cu")
		(net "A_TSENSE_PVDDQ_ABC")
	)
	(via
		(at 350.692212 0.107188)
		(size 0.508)
		(drill 0.254)
		(layers "F.Cu" "B.Cu")
		(net "A_TSENSE_PVDDQ_ABC")
	)
	(via
		(at 350.7613 -7.678928)
		(size 0.508)
		(drill 0.254)
		(layers "F.Cu" "B.Cu")
		(net "A_TSENSE_PVDDQ_ABC")
	)
	(via
		(at 351.325434 -14.617446)
		(size 0.508)
		(drill 0.254)
		(layers "F.Cu" "B.Cu")
		(net "A_TSENSE_PVDDQ_ABC")
	)
	(segment
		(start 351.569782 -8.48741)
		(end 351.569782 -12.308586)
		(width 0.254)
		(layer "In4.Cu")
		(net "A_TSENSE_PVDDQ_ABC")
	)
	(segment
		(start 351.325434 -12.552934)
		(end 351.325434 -14.617446)
		(width 0.254)
		(layer "In4.Cu")
		(net "A_TSENSE_PVDDQ_ABC")
	)
	(segment
		(start 352.24212 -1.44272)
		(end 350.692212 0.107188)
		(width 0.254)
		(layer "In4.Cu")
		(net "A_TSENSE_PVDDQ_ABC")
	)
	(segment
		(start 351.376996 -7.678928)
		(end 352.24212 -6.813804)
		(width 0.254)
		(layer "In4.Cu")
		(net "A_TSENSE_PVDDQ_ABC")
	)
	(segment
		(start 350.7613 -7.678928)
		(end 351.376996 -7.678928)
		(width 0.254)
		(layer "In4.Cu")
		(net "A_TSENSE_PVDDQ_ABC")
	)
	(segment
		(start 351.569782 -12.308586)
		(end 351.325434 -12.552934)
		(width 0.254)
		(layer "In4.Cu")
		(net "A_TSENSE_PVDDQ_ABC")
	)
	(segment
		(start 352.24212 -6.813804)
		(end 352.24212 -1.44272)
		(width 0.254)
		(layer "In4.Cu")
		(net "A_TSENSE_PVDDQ_ABC")
	)
	(segment
		(start 350.7613 -7.678928)
		(end 351.569782 -8.48741)
		(width 0.254)
		(layer "In4.Cu")
		(net "A_TSENSE_PVDDQ_ABC")
	)
	(segment
		(start 173.31944 -64.63538)
		(end 173.736 -64.63538)
		(width 0.2032)
		(layer "F.Cu")
		(net "A_TSENSE_PVCCIO_CPU1")
	)
	(segment
		(start 181.722776 -55.357776)
		(end 181.7878 -55.4228)
		(width 0.254)
		(layer "F.Cu")
		(net "A_TSENSE_PVCCIO_CPU1")
	)
	(segment
		(start 181.794658 -55.439818)
		(end 181.837076 -55.3974)
		(width 0.254)
		(layer "F.Cu")
		(net "A_TSENSE_PVCCIO_CPU1")
	)
	(segment
		(start 181.31663 -55.357776)
		(end 181.722776 -55.357776)
		(width 0.254)
		(layer "F.Cu")
		(net "A_TSENSE_PVCCIO_CPU1")
	)
	(segment
		(start 181.7878 -55.4228)
		(end 181.7878 -55.439818)
		(width 0.254)
		(layer "F.Cu")
		(net "A_TSENSE_PVCCIO_CPU1")
	)
	(segment
		(start 180.956458 -54.997604)
		(end 181.31663 -55.357776)
		(width 0.254)
		(layer "F.Cu")
		(net "A_TSENSE_PVCCIO_CPU1")
	)
	(segment
		(start 181.7878 -55.439818)
		(end 181.794658 -55.439818)
		(width 0.254)
		(layer "F.Cu")
		(net "A_TSENSE_PVCCIO_CPU1")
	)
	(segment
		(start 172.5422 -66.4718)
		(end 172.5422 -65.7606)
		(width 0.2032)
		(layer "F.Cu")
		(net "A_TSENSE_PVCCIO_CPU1")
	)
	(segment
		(start 181.837076 -55.3974)
		(end 182.5752 -55.3974)
		(width 0.254)
		(layer "F.Cu")
		(net "A_TSENSE_PVCCIO_CPU1")
	)
	(segment
		(start 173.16196 -64.79286)
		(end 173.31944 -64.63538)
		(width 0.2032)
		(layer "F.Cu")
		(net "A_TSENSE_PVCCIO_CPU1")
	)
	(segment
		(start 172.411898 -66.602102)
		(end 172.5422 -66.4718)
		(width 0.2032)
		(layer "F.Cu")
		(net "A_TSENSE_PVCCIO_CPU1")
	)
	(segment
		(start 171.6405 -66.602102)
		(end 172.411898 -66.602102)
		(width 0.2032)
		(layer "F.Cu")
		(net "A_TSENSE_PVCCIO_CPU1")
	)
	(segment
		(start 173.16196 -65.14084)
		(end 173.16196 -64.79286)
		(width 0.2032)
		(layer "F.Cu")
		(net "A_TSENSE_PVCCIO_CPU1")
	)
	(segment
		(start 172.5422 -65.7606)
		(end 173.16196 -65.14084)
		(width 0.2032)
		(layer "F.Cu")
		(net "A_TSENSE_PVCCIO_CPU1")
	)
	(segment
		(start 180.329586 -54.997604)
		(end 180.956458 -54.997604)
		(width 0.254)
		(layer "F.Cu")
		(net "A_TSENSE_PVCCIO_CPU1")
	)
	(via
		(at 181.794658 -55.439818)
		(size 0.508)
		(drill 0.254)
		(layers "F.Cu" "B.Cu")
		(net "A_TSENSE_PVCCIO_CPU1")
	)
	(via
		(at 172.5422 -66.4718)
		(size 0.508)
		(drill 0.254)
		(layers "F.Cu" "B.Cu")
		(net "A_TSENSE_PVCCIO_CPU1")
	)
	(segment
		(start 172.5422 -66.02476)
		(end 175.952912 -62.614048)
		(width 0.254)
		(layer "In2.Cu")
		(net "A_TSENSE_PVCCIO_CPU1")
	)
	(segment
		(start 175.952912 -62.614048)
		(end 175.952912 -58.387488)
		(width 0.254)
		(layer "In2.Cu")
		(net "A_TSENSE_PVCCIO_CPU1")
	)
	(segment
		(start 181.582822 -55.651654)
		(end 181.794658 -55.439818)
		(width 0.254)
		(layer "In2.Cu")
		(net "A_TSENSE_PVCCIO_CPU1")
	)
	(segment
		(start 181.568344 -55.637176)
		(end 181.582822 -55.651654)
		(width 0.254)
		(layer "In2.Cu")
		(net "A_TSENSE_PVCCIO_CPU1")
	)
	(segment
		(start 172.5422 -66.4718)
		(end 172.5422 -66.02476)
		(width 0.254)
		(layer "In2.Cu")
		(net "A_TSENSE_PVCCIO_CPU1")
	)
	(segment
		(start 175.952912 -58.387488)
		(end 177.8762 -56.4642)
		(width 0.254)
		(layer "In2.Cu")
		(net "A_TSENSE_PVCCIO_CPU1")
	)
	(segment
		(start 180.582824 -55.637176)
		(end 181.568344 -55.637176)
		(width 0.254)
		(layer "In2.Cu")
		(net "A_TSENSE_PVCCIO_CPU1")
	)
	(segment
		(start 179.7558 -56.4642)
		(end 180.582824 -55.637176)
		(width 0.254)
		(layer "In2.Cu")
		(net "A_TSENSE_PVCCIO_CPU1")
	)
	(segment
		(start 177.8762 -56.4642)
		(end 179.7558 -56.4642)
		(width 0.254)
		(layer "In2.Cu")
		(net "A_TSENSE_PVCCIO_CPU1")
	)
	(segment
		(start 353.009454 -98.730054)
		(end 354.27412 -98.730054)
		(width 0.254)
		(layer "F.Cu")
		(net "A_TSENSE_PVCCIO_CPU0")
	)
	(segment
		(start 350.52 -98.3996)
		(end 350.675702 -98.3996)
		(width 0.254)
		(layer "F.Cu")
		(net "A_TSENSE_PVCCIO_CPU0")
	)
	(segment
		(start 350.701102 -98.425)
		(end 352.7044 -98.425)
		(width 0.254)
		(layer "F.Cu")
		(net "A_TSENSE_PVCCIO_CPU0")
	)
	(segment
		(start 352.7044 -98.425)
		(end 352.7806 -98.5012)
		(width 0.254)
		(layer "F.Cu")
		(net "A_TSENSE_PVCCIO_CPU0")
	)
	(segment
		(start 349.927164 -98.194876)
		(end 350.315276 -98.194876)
		(width 0.254)
		(layer "F.Cu")
		(net "A_TSENSE_PVCCIO_CPU0")
	)
	(segment
		(start 352.7806 -98.5012)
		(end 353.009454 -98.730054)
		(width 0.254)
		(layer "F.Cu")
		(net "A_TSENSE_PVCCIO_CPU0")
	)
	(segment
		(start 350.675702 -98.3996)
		(end 350.701102 -98.425)
		(width 0.254)
		(layer "F.Cu")
		(net "A_TSENSE_PVCCIO_CPU0")
	)
	(segment
		(start 350.315276 -98.194876)
		(end 350.52 -98.3996)
		(width 0.254)
		(layer "F.Cu")
		(net "A_TSENSE_PVCCIO_CPU0")
	)
	(via
		(at 352.7806 -98.5012)
		(size 0.508)
		(drill 0.254)
		(layers "F.Cu" "B.Cu")
		(net "A_TSENSE_PVCCIO_CPU0")
	)
	(via
		(at 350.0628 -88.1126)
		(size 0.508)
		(drill 0.254)
		(layers "F.Cu" "B.Cu")
		(net "A_TSENSE_PVCCIO_CPU0")
	)
	(via
		(at 341.01278 -93.52788)
		(size 0.508)
		(drill 0.254)
		(layers "F.Cu" "B.Cu")
		(net "A_TSENSE_PVCCIO_CPU0")
	)
	(segment
		(start 350.0628 -88.1126)
		(end 349.602298 -87.652098)
		(width 0.2032)
		(layer "B.Cu")
		(net "A_TSENSE_PVCCIO_CPU0")
	)
	(segment
		(start 350.266 -88.6968)
		(end 350.266 -88.3158)
		(width 0.2032)
		(layer "B.Cu")
		(net "A_TSENSE_PVCCIO_CPU0")
	)
	(segment
		(start 350.636332 -89.067132)
		(end 350.266 -88.6968)
		(width 0.2032)
		(layer "B.Cu")
		(net "A_TSENSE_PVCCIO_CPU0")
	)
	(segment
		(start 351.13468 -89.067132)
		(end 350.839532 -89.067132)
		(width 0.254)
		(layer "B.Cu")
		(net "A_TSENSE_PVCCIO_CPU0")
	)
	(segment
		(start 350.266 -88.3158)
		(end 350.0628 -88.1126)
		(width 0.2032)
		(layer "B.Cu")
		(net "A_TSENSE_PVCCIO_CPU0")
	)
	(segment
		(start 349.602298 -87.652098)
		(end 348.9833 -87.652098)
		(width 0.2032)
		(layer "B.Cu")
		(net "A_TSENSE_PVCCIO_CPU0")
	)
	(segment
		(start 350.839532 -89.067132)
		(end 350.636332 -89.067132)
		(width 0.2032)
		(layer "B.Cu")
		(net "A_TSENSE_PVCCIO_CPU0")
	)
	(segment
		(start 344.22588 -93.52788)
		(end 345.49334 -92.26042)
		(width 0.254)
		(layer "In2.Cu")
		(net "A_TSENSE_PVCCIO_CPU0")
	)
	(segment
		(start 345.49334 -92.26042)
		(end 351.85096 -92.26042)
		(width 0.254)
		(layer "In2.Cu")
		(net "A_TSENSE_PVCCIO_CPU0")
	)
	(segment
		(start 355.03866 -95.44812)
		(end 355.03866 -98.2091)
		(width 0.254)
		(layer "In2.Cu")
		(net "A_TSENSE_PVCCIO_CPU0")
	)
	(segment
		(start 355.03866 -98.2091)
		(end 354.531168 -98.716592)
		(width 0.254)
		(layer "In2.Cu")
		(net "A_TSENSE_PVCCIO_CPU0")
	)
	(segment
		(start 354.531168 -98.716592)
		(end 352.995992 -98.716592)
		(width 0.254)
		(layer "In2.Cu")
		(net "A_TSENSE_PVCCIO_CPU0")
	)
	(segment
		(start 352.995992 -98.716592)
		(end 352.7806 -98.5012)
		(width 0.254)
		(layer "In2.Cu")
		(net "A_TSENSE_PVCCIO_CPU0")
	)
	(segment
		(start 341.01278 -93.52788)
		(end 344.22588 -93.52788)
		(width 0.254)
		(layer "In2.Cu")
		(net "A_TSENSE_PVCCIO_CPU0")
	)
	(segment
		(start 351.85096 -92.26042)
		(end 355.03866 -95.44812)
		(width 0.254)
		(layer "In2.Cu")
		(net "A_TSENSE_PVCCIO_CPU0")
	)
	(segment
		(start 340.05012 -90.95232)
		(end 340.05012 -92.02928)
		(width 0.254)
		(layer "In11.Cu")
		(net "A_TSENSE_PVCCIO_CPU0")
	)
	(segment
		(start 350.96704 -89.50198)
		(end 350.70034 -89.76868)
		(width 0.254)
		(layer "In11.Cu")
		(net "A_TSENSE_PVCCIO_CPU0")
	)
	(segment
		(start 350.0628 -88.0745)
		(end 350.3168 -87.8205)
		(width 0.254)
		(layer "In11.Cu")
		(net "A_TSENSE_PVCCIO_CPU0")
	)
	(segment
		(start 350.70034 -89.76868)
		(end 341.23376 -89.76868)
		(width 0.254)
		(layer "In11.Cu")
		(net "A_TSENSE_PVCCIO_CPU0")
	)
	(segment
		(start 350.96704 -88.03132)
		(end 350.96704 -89.50198)
		(width 0.254)
		(layer "In11.Cu")
		(net "A_TSENSE_PVCCIO_CPU0")
	)
	(segment
		(start 341.01278 -92.99194)
		(end 341.01278 -93.52788)
		(width 0.254)
		(layer "In11.Cu")
		(net "A_TSENSE_PVCCIO_CPU0")
	)
	(segment
		(start 350.0628 -88.1126)
		(end 350.0628 -88.0745)
		(width 0.254)
		(layer "In11.Cu")
		(net "A_TSENSE_PVCCIO_CPU0")
	)
	(segment
		(start 340.05012 -92.02928)
		(end 341.01278 -92.99194)
		(width 0.254)
		(layer "In11.Cu")
		(net "A_TSENSE_PVCCIO_CPU0")
	)
	(segment
		(start 350.75622 -87.8205)
		(end 350.96704 -88.03132)
		(width 0.254)
		(layer "In11.Cu")
		(net "A_TSENSE_PVCCIO_CPU0")
	)
	(segment
		(start 350.3168 -87.8205)
		(end 350.75622 -87.8205)
		(width 0.254)
		(layer "In11.Cu")
		(net "A_TSENSE_PVCCIO_CPU0")
	)
	(segment
		(start 341.23376 -89.76868)
		(end 340.05012 -90.95232)
		(width 0.254)
		(layer "In11.Cu")
		(net "A_TSENSE_PVCCIO_CPU0")
	)
	(segment
		(start 195.498466 -88.901778)
		(end 195.062094 -88.465406)
		(width 0.254)
		(layer "F.Cu")
		(net "A_TSENSE_PVCCIN_CPU0")
	)
	(segment
		(start 194.309238 -72.228202)
		(end 194.311778 -72.228202)
		(width 0.254)
		(layer "F.Cu")
		(net "A_TSENSE_PVCCIN_CPU0")
	)
	(segment
		(start 193.44132 -55.92064)
		(end 193.488056 -55.967376)
		(width 0.254)
		(layer "F.Cu")
		(net "A_TSENSE_PVCCIN_CPU0")
	)
	(segment
		(start 194.330574 -64.081406)
		(end 194.311778 -64.100202)
		(width 0.254)
		(layer "F.Cu")
		(net "A_TSENSE_PVCCIN_CPU0")
	)
	(segment
		(start 183.9722 -75.4253)
		(end 183.7182 -75.6793)
		(width 0.254)
		(layer "F.Cu")
		(net "A_TSENSE_PVCCIN_CPU0")
	)
	(segment
		(start 192.208404 -72.098662)
		(end 192.068704 -72.238362)
		(width 0.254)
		(layer "F.Cu")
		(net "A_TSENSE_PVCCIN_CPU0")
	)
	(segment
		(start 185.42 -81.1022)
		(end 186.182 -81.8642)
		(width 0.254)
		(layer "F.Cu")
		(net "A_TSENSE_PVCCIN_CPU0")
	)
	(segment
		(start 192.208404 -72.098662)
		(end 192.789556 -72.098662)
		(width 0.254)
		(layer "F.Cu")
		(net "A_TSENSE_PVCCIN_CPU0")
	)
	(segment
		(start 194.311778 -80.356202)
		(end 194.311778 -80.650588)
		(width 0.254)
		(layer "F.Cu")
		(net "A_TSENSE_PVCCIN_CPU0")
	)
	(segment
		(start 186.182 -81.8642)
		(end 188.0616 -81.8642)
		(width 0.254)
		(layer "F.Cu")
		(net "A_TSENSE_PVCCIN_CPU0")
	)
	(segment
		(start 193.4083 -88.83142)
		(end 193.96456 -88.83142)
		(width 0.254)
		(layer "F.Cu")
		(net "A_TSENSE_PVCCIN_CPU0")
	)
	(segment
		(start 194.026028 -72.511412)
		(end 194.309238 -72.228202)
		(width 0.254)
		(layer "F.Cu")
		(net "A_TSENSE_PVCCIN_CPU0")
	)
	(segment
		(start 188.0616 -81.8642)
		(end 189.40272 -80.52308)
		(width 0.254)
		(layer "F.Cu")
		(net "A_TSENSE_PVCCIN_CPU0")
	)
	(segment
		(start 194.330574 -80.337406)
		(end 194.311778 -80.356202)
		(width 0.254)
		(layer "F.Cu")
		(net "A_TSENSE_PVCCIN_CPU0")
	)
	(segment
		(start 191.874902 -65.282572)
		(end 191.874902 -66.620898)
		(width 0.254)
		(layer "F.Cu")
		(net "A_TSENSE_PVCCIN_CPU0")
	)
	(segment
		(start 192.278762 -63.846964)
		(end 192.532 -64.100202)
		(width 0.254)
		(layer "F.Cu")
		(net "A_TSENSE_PVCCIN_CPU0")
	)
	(segment
		(start 195.414646 -64.517778)
		(end 194.978274 -64.081406)
		(width 0.254)
		(layer "F.Cu")
		(net "A_TSENSE_PVCCIN_CPU0")
	)
	(segment
		(start 188.0616 -81.8642)
		(end 189.479428 -83.282028)
		(width 0.254)
		(layer "F.Cu")
		(net "A_TSENSE_PVCCIN_CPU0")
	)
	(segment
		(start 191.5668 -66.929)
		(end 191.5668 -68.035678)
		(width 0.254)
		(layer "F.Cu")
		(net "A_TSENSE_PVCCIN_CPU0")
	)
	(segment
		(start 196.030342 -72.645778)
		(end 195.640198 -72.645778)
		(width 0.254)
		(layer "F.Cu")
		(net "A_TSENSE_PVCCIN_CPU0")
	)
	(segment
		(start 195.062094 -88.465406)
		(end 194.330574 -88.465406)
		(width 0.254)
		(layer "F.Cu")
		(net "A_TSENSE_PVCCIN_CPU0")
	)
	(segment
		(start 194.992244 -55.967376)
		(end 195.414646 -56.389778)
		(width 0.254)
		(layer "F.Cu")
		(net "A_TSENSE_PVCCIN_CPU0")
	)
	(segment
		(start 191.786764 -63.846964)
		(end 192.278762 -63.846964)
		(width 0.254)
		(layer "F.Cu")
		(net "A_TSENSE_PVCCIN_CPU0")
	)
	(segment
		(start 183.7182 -77.002894)
		(end 185.42 -78.704694)
		(width 0.254)
		(layer "F.Cu")
		(net "A_TSENSE_PVCCIN_CPU0")
	)
	(segment
		(start 196.030342 -88.901778)
		(end 195.498466 -88.901778)
		(width 0.254)
		(layer "F.Cu")
		(net "A_TSENSE_PVCCIN_CPU0")
	)
	(segment
		(start 191.874902 -66.620898)
		(end 191.5668 -66.929)
		(width 0.254)
		(layer "F.Cu")
		(net "A_TSENSE_PVCCIN_CPU0")
	)
	(segment
		(start 192.640712 -55.92064)
		(end 193.44132 -55.92064)
		(width 0.254)
		(layer "F.Cu")
		(net "A_TSENSE_PVCCIN_CPU0")
	)
	(segment
		(start 192.417446 -64.214756)
		(end 192.417446 -64.740028)
		(width 0.254)
		(layer "F.Cu")
		(net "A_TSENSE_PVCCIN_CPU0")
	)
	(segment
		(start 190.8302 -62.8904)
		(end 191.786764 -63.846964)
		(width 0.254)
		(layer "F.Cu")
		(net "A_TSENSE_PVCCIN_CPU0")
	)
	(segment
		(start 192.417446 -64.740028)
		(end 191.874902 -65.282572)
		(width 0.254)
		(layer "F.Cu")
		(net "A_TSENSE_PVCCIN_CPU0")
	)
	(segment
		(start 192.84188 -70.396354)
		(end 191.995806 -71.242428)
		(width 0.254)
		(layer "F.Cu")
		(net "A_TSENSE_PVCCIN_CPU0")
	)
	(segment
		(start 191.5668 -68.035678)
		(end 192.84188 -69.310758)
		(width 0.254)
		(layer "F.Cu")
		(net "A_TSENSE_PVCCIN_CPU0")
	)
	(segment
		(start 191.007492 -83.282028)
		(end 193.056764 -85.3313)
		(width 0.254)
		(layer "F.Cu")
		(net "A_TSENSE_PVCCIN_CPU0")
	)
	(segment
		(start 192.789556 -72.098662)
		(end 193.202306 -72.511412)
		(width 0.254)
		(layer "F.Cu")
		(net "A_TSENSE_PVCCIN_CPU0")
	)
	(segment
		(start 191.995806 -71.886064)
		(end 192.208404 -72.098662)
		(width 0.254)
		(layer "F.Cu")
		(net "A_TSENSE_PVCCIN_CPU0")
	)
	(segment
		(start 193.202306 -72.511412)
		(end 194.026028 -72.511412)
		(width 0.254)
		(layer "F.Cu")
		(net "A_TSENSE_PVCCIN_CPU0")
	)
	(segment
		(start 195.203826 -72.209406)
		(end 194.330574 -72.209406)
		(width 0.254)
		(layer "F.Cu")
		(net "A_TSENSE_PVCCIN_CPU0")
	)
	(segment
		(start 192.84188 -69.310758)
		(end 192.84188 -70.396354)
		(width 0.254)
		(layer "F.Cu")
		(net "A_TSENSE_PVCCIN_CPU0")
	)
	(segment
		(start 193.834766 -81.1276)
		(end 191.133222 -81.1276)
		(width 0.254)
		(layer "F.Cu")
		(net "A_TSENSE_PVCCIN_CPU0")
	)
	(segment
		(start 194.330574 -88.465406)
		(end 194.311778 -88.484202)
		(width 0.254)
		(layer "F.Cu")
		(net "A_TSENSE_PVCCIN_CPU0")
	)
	(segment
		(start 191.076326 -79.975456)
		(end 190.528702 -80.52308)
		(width 0.254)
		(layer "F.Cu")
		(net "A_TSENSE_PVCCIN_CPU0")
	)
	(segment
		(start 194.978274 -64.081406)
		(end 194.330574 -64.081406)
		(width 0.254)
		(layer "F.Cu")
		(net "A_TSENSE_PVCCIN_CPU0")
	)
	(segment
		(start 184.077102 -73.536302)
		(end 184.077102 -72.7456)
		(width 0.2032)
		(layer "F.Cu")
		(net "A_TSENSE_PVCCIN_CPU0")
	)
	(segment
		(start 183.7182 -75.6793)
		(end 183.7182 -77.002894)
		(width 0.254)
		(layer "F.Cu")
		(net "A_TSENSE_PVCCIN_CPU0")
	)
	(segment
		(start 184.2516 -74.6506)
		(end 184.2516 -74.466196)
		(width 0.2032)
		(layer "F.Cu")
		(net "A_TSENSE_PVCCIN_CPU0")
	)
	(segment
		(start 191.133222 -81.1276)
		(end 190.528702 -80.52308)
		(width 0.254)
		(layer "F.Cu")
		(net "A_TSENSE_PVCCIN_CPU0")
	)
	(segment
		(start 189.40272 -80.52308)
		(end 190.528702 -80.52308)
		(width 0.254)
		(layer "F.Cu")
		(net "A_TSENSE_PVCCIN_CPU0")
	)
	(segment
		(start 193.96456 -88.83142)
		(end 194.311778 -88.484202)
		(width 0.254)
		(layer "F.Cu")
		(net "A_TSENSE_PVCCIN_CPU0")
	)
	(segment
		(start 184.2516 -75.4253)
		(end 184.2516 -74.6506)
		(width 0.254)
		(layer "F.Cu")
		(net "A_TSENSE_PVCCIN_CPU0")
	)
	(segment
		(start 195.414646 -80.773778)
		(end 194.978274 -80.337406)
		(width 0.254)
		(layer "F.Cu")
		(net "A_TSENSE_PVCCIN_CPU0")
	)
	(segment
		(start 193.056764 -88.479884)
		(end 193.4083 -88.83142)
		(width 0.254)
		(layer "F.Cu")
		(net "A_TSENSE_PVCCIN_CPU0")
	)
	(segment
		(start 189.479428 -83.282028)
		(end 191.007492 -83.282028)
		(width 0.254)
		(layer "F.Cu")
		(net "A_TSENSE_PVCCIN_CPU0")
	)
	(segment
		(start 190.8302 -62.8904)
		(end 190.8302 -57.731152)
		(width 0.254)
		(layer "F.Cu")
		(net "A_TSENSE_PVCCIN_CPU0")
	)
	(segment
		(start 184.3532 -74.364596)
		(end 184.3532 -73.8124)
		(width 0.2032)
		(layer "F.Cu")
		(net "A_TSENSE_PVCCIN_CPU0")
	)
	(segment
		(start 185.42 -78.704694)
		(end 185.42 -81.1022)
		(width 0.254)
		(layer "F.Cu")
		(net "A_TSENSE_PVCCIN_CPU0")
	)
	(segment
		(start 184.2516 -74.466196)
		(end 184.3532 -74.364596)
		(width 0.2032)
		(layer "F.Cu")
		(net "A_TSENSE_PVCCIN_CPU0")
	)
	(segment
		(start 194.311778 -80.650588)
		(end 193.834766 -81.1276)
		(width 0.254)
		(layer "F.Cu")
		(net "A_TSENSE_PVCCIN_CPU0")
	)
	(segment
		(start 191.076326 -73.869042)
		(end 191.076326 -79.975456)
		(width 0.254)
		(layer "F.Cu")
		(net "A_TSENSE_PVCCIN_CPU0")
	)
	(segment
		(start 195.414646 -56.389778)
		(end 196.030342 -56.389778)
		(width 0.254)
		(layer "F.Cu")
		(net "A_TSENSE_PVCCIN_CPU0")
	)
	(segment
		(start 191.995806 -71.242428)
		(end 191.995806 -71.886064)
		(width 0.254)
		(layer "F.Cu")
		(net "A_TSENSE_PVCCIN_CPU0")
	)
	(segment
		(start 192.532 -64.100202)
		(end 194.311778 -64.100202)
		(width 0.254)
		(layer "F.Cu")
		(net "A_TSENSE_PVCCIN_CPU0")
	)
	(segment
		(start 193.488056 -55.967376)
		(end 194.992244 -55.967376)
		(width 0.254)
		(layer "F.Cu")
		(net "A_TSENSE_PVCCIN_CPU0")
	)
	(segment
		(start 192.068704 -72.876664)
		(end 191.076326 -73.869042)
		(width 0.254)
		(layer "F.Cu")
		(net "A_TSENSE_PVCCIN_CPU0")
	)
	(segment
		(start 196.030342 -80.773778)
		(end 195.414646 -80.773778)
		(width 0.254)
		(layer "F.Cu")
		(net "A_TSENSE_PVCCIN_CPU0")
	)
	(segment
		(start 192.532 -64.100202)
		(end 192.417446 -64.214756)
		(width 0.254)
		(layer "F.Cu")
		(net "A_TSENSE_PVCCIN_CPU0")
	)
	(segment
		(start 192.068704 -72.238362)
		(end 192.068704 -72.876664)
		(width 0.254)
		(layer "F.Cu")
		(net "A_TSENSE_PVCCIN_CPU0")
	)
	(segment
		(start 194.978274 -80.337406)
		(end 194.330574 -80.337406)
		(width 0.254)
		(layer "F.Cu")
		(net "A_TSENSE_PVCCIN_CPU0")
	)
	(segment
		(start 184.2516 -75.4253)
		(end 183.9722 -75.4253)
		(width 0.254)
		(layer "F.Cu")
		(net "A_TSENSE_PVCCIN_CPU0")
	)
	(segment
		(start 195.640198 -72.645778)
		(end 195.203826 -72.209406)
		(width 0.254)
		(layer "F.Cu")
		(net "A_TSENSE_PVCCIN_CPU0")
	)
	(segment
		(start 196.030342 -64.517778)
		(end 195.414646 -64.517778)
		(width 0.254)
		(layer "F.Cu")
		(net "A_TSENSE_PVCCIN_CPU0")
	)
	(segment
		(start 193.056764 -85.3313)
		(end 193.056764 -88.479884)
		(width 0.254)
		(layer "F.Cu")
		(net "A_TSENSE_PVCCIN_CPU0")
	)
	(segment
		(start 184.3532 -73.8124)
		(end 184.077102 -73.536302)
		(width 0.2032)
		(layer "F.Cu")
		(net "A_TSENSE_PVCCIN_CPU0")
	)
	(segment
		(start 194.330574 -72.209406)
		(end 194.311778 -72.228202)
		(width 0.254)
		(layer "F.Cu")
		(net "A_TSENSE_PVCCIN_CPU0")
	)
	(segment
		(start 190.8302 -57.731152)
		(end 192.640712 -55.92064)
		(width 0.254)
		(layer "F.Cu")
		(net "A_TSENSE_PVCCIN_CPU0")
	)
	(via
		(at 193.44132 -55.92064)
		(size 0.508)
		(drill 0.254)
		(layers "F.Cu" "B.Cu")
		(net "A_TSENSE_PVCCIN_CPU0")
	)
	(via
		(at 194.311778 -64.100202)
		(size 0.508)
		(drill 0.254)
		(layers "F.Cu" "B.Cu")
		(net "A_TSENSE_PVCCIN_CPU0")
	)
	(via
		(at 194.311778 -72.228202)
		(size 0.508)
		(drill 0.254)
		(layers "F.Cu" "B.Cu")
		(net "A_TSENSE_PVCCIN_CPU0")
	)
	(via
		(at 190.8302 -62.8904)
		(size 0.762)
		(drill 0.381)
		(layers "F.Cu" "B.Cu")
		(net "A_TSENSE_PVCCIN_CPU0")
	)
	(via
		(at 194.311778 -88.484202)
		(size 0.508)
		(drill 0.254)
		(layers "F.Cu" "B.Cu")
		(net "A_TSENSE_PVCCIN_CPU0")
	)
	(via
		(at 194.311778 -80.356202)
		(size 0.508)
		(drill 0.254)
		(layers "F.Cu" "B.Cu")
		(net "A_TSENSE_PVCCIN_CPU0")
	)
	(segment
		(start 194.40398 -64.008)
		(end 195.2752 -64.008)
		(width 0.254)
		(layer "B.Cu")
		(net "A_TSENSE_PVCCIN_CPU0")
	)
	(segment
		(start 193.48196 -55.88)
		(end 195.2244 -55.88)
		(width 0.254)
		(layer "B.Cu")
		(net "A_TSENSE_PVCCIN_CPU0")
	)
	(segment
		(start 194.311778 -80.356202)
		(end 194.42938 -80.2386)
		(width 0.254)
		(layer "B.Cu")
		(net "A_TSENSE_PVCCIN_CPU0")
	)
	(segment
		(start 194.311778 -88.484202)
		(end 194.35318 -88.4428)
		(width 0.254)
		(layer "B.Cu")
		(net "A_TSENSE_PVCCIN_CPU0")
	)
	(segment
		(start 194.311778 -64.100202)
		(end 194.40398 -64.008)
		(width 0.254)
		(layer "B.Cu")
		(net "A_TSENSE_PVCCIN_CPU0")
	)
	(segment
		(start 194.311778 -72.228202)
		(end 194.37858 -72.1614)
		(width 0.254)
		(layer "B.Cu")
		(net "A_TSENSE_PVCCIN_CPU0")
	)
	(segment
		(start 193.44132 -55.92064)
		(end 193.48196 -55.88)
		(width 0.254)
		(layer "B.Cu")
		(net "A_TSENSE_PVCCIN_CPU0")
	)
	(segment
		(start 194.35318 -88.4428)
		(end 195.3006 -88.4428)
		(width 0.254)
		(layer "B.Cu")
		(net "A_TSENSE_PVCCIN_CPU0")
	)
	(segment
		(start 194.42938 -80.2386)
		(end 195.1736 -80.2386)
		(width 0.254)
		(layer "B.Cu")
		(net "A_TSENSE_PVCCIN_CPU0")
	)
	(segment
		(start 194.37858 -72.1614)
		(end 195.1736 -72.1614)
		(width 0.254)
		(layer "B.Cu")
		(net "A_TSENSE_PVCCIN_CPU0")
	)
	(segment
		(start 393.3317 -154.396948)
		(end 392.786108 -154.396948)
		(width 0.1778)
		(layer "F.Cu")
		(net "A_TSENSE_P1V05_PCH_STBY_TMON")
	)
	(segment
		(start 392.786108 -154.396948)
		(end 392.5951 -154.587956)
		(width 0.1778)
		(layer "F.Cu")
		(net "A_TSENSE_P1V05_PCH_STBY_TMON")
	)
	(segment
		(start 384.744214 -157.164786)
		(end 384.5052 -157.4038)
		(width 0.254)
		(layer "F.Cu")
		(net "A_TSENSE_P1V05_PCH_STBY_TMON")
	)
	(segment
		(start 392.5951 -154.587956)
		(end 391.632948 -154.587956)
		(width 0.1778)
		(layer "F.Cu")
		(net "A_TSENSE_P1V05_PCH_STBY_TMON")
	)
	(segment
		(start 384.5052 -157.4292)
		(end 384.4798 -157.4546)
		(width 0.254)
		(layer "F.Cu")
		(net "A_TSENSE_P1V05_PCH_STBY_TMON")
	)
	(segment
		(start 391.632948 -154.587956)
		(end 391.455148 -154.410156)
		(width 0.1778)
		(layer "F.Cu")
		(net "A_TSENSE_P1V05_PCH_STBY_TMON")
	)
	(segment
		(start 391.455148 -154.410156)
		(end 391.455148 -154.407362)
		(width 0.1778)
		(layer "F.Cu")
		(net "A_TSENSE_P1V05_PCH_STBY_TMON")
	)
	(segment
		(start 384.744214 -156.565092)
		(end 384.744214 -157.164786)
		(width 0.254)
		(layer "F.Cu")
		(net "A_TSENSE_P1V05_PCH_STBY_TMON")
	)
	(segment
		(start 384.5052 -157.4038)
		(end 384.5052 -157.4292)
		(width 0.254)
		(layer "F.Cu")
		(net "A_TSENSE_P1V05_PCH_STBY_TMON")
	)
	(via
		(at 391.455148 -154.407362)
		(size 0.508)
		(drill 0.254)
		(layers "F.Cu" "B.Cu")
		(net "A_TSENSE_P1V05_PCH_STBY_TMON")
	)
	(via
		(at 384.4798 -157.4546)
		(size 0.508)
		(drill 0.254)
		(layers "F.Cu" "B.Cu")
		(net "A_TSENSE_P1V05_PCH_STBY_TMON")
	)
	(segment
		(start 384.2512 -158.242)
		(end 384.10134 -158.242)
		(width 0.254)
		(layer "B.Cu")
		(net "A_TSENSE_P1V05_PCH_STBY_TMON")
	)
	(segment
		(start 390.5758 -154.278838)
		(end 390.981184 -154.278838)
		(width 0.127)
		(layer "B.Cu")
		(net "A_TSENSE_P1V05_PCH_STBY_TMON")
	)
	(segment
		(start 391.109708 -154.407362)
		(end 391.455148 -154.407362)
		(width 0.127)
		(layer "B.Cu")
		(net "A_TSENSE_P1V05_PCH_STBY_TMON")
	)
	(segment
		(start 384.10134 -158.242)
		(end 384.0734 -158.26994)
		(width 0.254)
		(layer "B.Cu")
		(net "A_TSENSE_P1V05_PCH_STBY_TMON")
	)
	(segment
		(start 390.981184 -154.278838)
		(end 391.109708 -154.407362)
		(width 0.127)
		(layer "B.Cu")
		(net "A_TSENSE_P1V05_PCH_STBY_TMON")
	)
	(segment
		(start 384.5052 -157.48)
		(end 384.5052 -157.988)
		(width 0.254)
		(layer "B.Cu")
		(net "A_TSENSE_P1V05_PCH_STBY_TMON")
	)
	(segment
		(start 384.4798 -157.4546)
		(end 384.5052 -157.48)
		(width 0.254)
		(layer "B.Cu")
		(net "A_TSENSE_P1V05_PCH_STBY_TMON")
	)
	(segment
		(start 384.5052 -157.988)
		(end 384.2512 -158.242)
		(width 0.254)
		(layer "B.Cu")
		(net "A_TSENSE_P1V05_PCH_STBY_TMON")
	)
	(segment
		(start 386.467604 -154.905456)
		(end 383.587498 -154.905456)
		(width 0.254)
		(layer "In4.Cu")
		(net "A_TSENSE_P1V05_PCH_STBY_TMON")
	)
	(segment
		(start 383.587498 -154.905456)
		(end 383.333498 -155.159456)
		(width 0.254)
		(layer "In4.Cu")
		(net "A_TSENSE_P1V05_PCH_STBY_TMON")
	)
	(segment
		(start 391.455148 -154.407362)
		(end 391.292842 -154.245056)
		(width 0.254)
		(layer "In4.Cu")
		(net "A_TSENSE_P1V05_PCH_STBY_TMON")
	)
	(segment
		(start 383.333498 -155.946094)
		(end 384.4798 -157.092396)
		(width 0.254)
		(layer "In4.Cu")
		(net "A_TSENSE_P1V05_PCH_STBY_TMON")
	)
	(segment
		(start 383.333498 -155.159456)
		(end 383.333498 -155.946094)
		(width 0.254)
		(layer "In4.Cu")
		(net "A_TSENSE_P1V05_PCH_STBY_TMON")
	)
	(segment
		(start 384.4798 -157.092396)
		(end 384.4798 -157.4546)
		(width 0.254)
		(layer "In4.Cu")
		(net "A_TSENSE_P1V05_PCH_STBY_TMON")
	)
	(segment
		(start 387.128004 -154.245056)
		(end 386.467604 -154.905456)
		(width 0.254)
		(layer "In4.Cu")
		(net "A_TSENSE_P1V05_PCH_STBY_TMON")
	)
	(segment
		(start 391.292842 -154.245056)
		(end 387.128004 -154.245056)
		(width 0.254)
		(layer "In4.Cu")
		(net "A_TSENSE_P1V05_PCH_STBY_TMON")
	)
	(segment
		(start 375.838212 -86.303612)
		(end 375.92 -86.3854)
		(width 0.10795)
		(layer "F.Cu")
		(net "SPI_PCH_CS0_N")
	)
	(segment
		(start 375.838212 -86.270592)
		(end 375.838212 -86.303612)
		(width 0.10795)
		(layer "F.Cu")
		(net "SPI_PCH_CS0_N")
	)
	(segment
		(start 376.526044 -85.579204)
		(end 376.22734 -85.877908)
		(width 0.10795)
		(layer "F.Cu")
		(net "SPI_PCH_CS0_N")
	)
	(segment
		(start 376.22734 -85.877908)
		(end 376.22734 -85.881464)
		(width 0.10795)
		(layer "F.Cu")
		(net "SPI_PCH_CS0_N")
	)
	(segment
		(start 375.92 -86.3854)
		(end 375.92 -87.3125)
		(width 0.10795)
		(layer "F.Cu")
		(net "SPI_PCH_CS0_N")
	)
	(segment
		(start 376.22734 -85.881464)
		(end 375.838212 -86.270592)
		(width 0.10795)
		(layer "F.Cu")
		(net "SPI_PCH_CS0_N")
	)
	(via
		(at 384.82524 -48.880522)
		(size 0.508)
		(drill 0.254)
		(layers "F.Cu" "B.Cu")
		(net "SPI_PCH_CS0_N")
	)
	(via
		(at 376.526044 -85.579204)
		(size 0.508)
		(drill 0.254)
		(layers "F.Cu" "B.Cu")
		(net "SPI_PCH_CS0_N")
	)
	(via
		(at 375.838212 -86.303612)
		(size 0.762)
		(drill 0.381)
		(layers "F.Cu" "B.Cu")
		(net "SPI_PCH_CS0_N")
	)
	(segment
		(start 380.1237 -51.6763)
		(end 380.1237 -50.197004)
		(width 0.10795)
		(layer "B.Cu")
		(net "SPI_PCH_CS0_N")
	)
	(segment
		(start 379.5014 -52.2986)
		(end 380.1237 -51.6763)
		(width 0.10795)
		(layer "B.Cu")
		(net "SPI_PCH_CS0_N")
	)
	(segment
		(start 380.691644 -49.62906)
		(end 384.077972 -49.62906)
		(width 0.10795)
		(layer "B.Cu")
		(net "SPI_PCH_CS0_N")
	)
	(segment
		(start 378.7902 -52.2986)
		(end 379.5014 -52.2986)
		(width 0.10795)
		(layer "B.Cu")
		(net "SPI_PCH_CS0_N")
	)
	(segment
		(start 384.077972 -49.62906)
		(end 384.82524 -48.881792)
		(width 0.10795)
		(layer "B.Cu")
		(net "SPI_PCH_CS0_N")
	)
	(segment
		(start 384.82524 -48.881792)
		(end 384.82524 -48.880522)
		(width 0.10795)
		(layer "B.Cu")
		(net "SPI_PCH_CS0_N")
	)
	(segment
		(start 378.1171 -51.6255)
		(end 378.7902 -52.2986)
		(width 0.10795)
		(layer "B.Cu")
		(net "SPI_PCH_CS0_N")
	)
	(segment
		(start 377.1265 -51.6255)
		(end 378.1171 -51.6255)
		(width 0.10795)
		(layer "B.Cu")
		(net "SPI_PCH_CS0_N")
	)
	(segment
		(start 380.1237 -50.197004)
		(end 380.691644 -49.62906)
		(width 0.10795)
		(layer "B.Cu")
		(net "SPI_PCH_CS0_N")
	)
	(segment
		(start 379.957838 -77.527404)
		(end 379.957838 -76.865226)
		(width 0.089408)
		(layer "In9.Cu")
		(net "SPI_PCH_CS0_N")
	)
	(segment
		(start 383.243328 -69.650864)
		(end 383.243328 -68.916296)
		(width 0.089408)
		(layer "In9.Cu")
		(net "SPI_PCH_CS0_N")
	)
	(segment
		(start 382.490472 -71.604378)
		(end 382.490472 -70.40372)
		(width 0.089408)
		(layer "In9.Cu")
		(net "SPI_PCH_CS0_N")
	)
	(segment
		(start 383.8956 -61.880242)
		(end 383.534666 -61.519308)
		(width 0.089408)
		(layer "In9.Cu")
		(net "SPI_PCH_CS0_N")
	)
	(segment
		(start 376.526044 -85.579204)
		(end 376.968004 -85.137244)
		(width 0.089408)
		(layer "In9.Cu")
		(net "SPI_PCH_CS0_N")
	)
	(segment
		(start 376.968004 -84.512404)
		(end 376.561096 -84.105496)
		(width 0.089408)
		(layer "In9.Cu")
		(net "SPI_PCH_CS0_N")
	)
	(segment
		(start 376.968004 -85.137244)
		(end 376.968004 -84.512404)
		(width 0.089408)
		(layer "In9.Cu")
		(net "SPI_PCH_CS0_N")
	)
	(segment
		(start 380.310644 -76.51242)
		(end 380.310644 -75.97521)
		(width 0.089408)
		(layer "In9.Cu")
		(net "SPI_PCH_CS0_N")
	)
	(segment
		(start 381.759206 -73.576688)
		(end 381.759206 -72.335644)
		(width 0.089408)
		(layer "In9.Cu")
		(net "SPI_PCH_CS0_N")
	)
	(segment
		(start 379.884686 -77.600556)
		(end 379.957838 -77.527404)
		(width 0.089408)
		(layer "In9.Cu")
		(net "SPI_PCH_CS0_N")
	)
	(segment
		(start 382.90881 -67.415664)
		(end 383.533142 -66.791332)
		(width 0.089408)
		(layer "In9.Cu")
		(net "SPI_PCH_CS0_N")
	)
	(segment
		(start 384.175 -56.768746)
		(end 385.223512 -55.720234)
		(width 0.089408)
		(layer "In9.Cu")
		(net "SPI_PCH_CS0_N")
	)
	(segment
		(start 376.770138 -83.376008)
		(end 376.991626 -83.376008)
		(width 0.089408)
		(layer "In9.Cu")
		(net "SPI_PCH_CS0_N")
	)
	(segment
		(start 384.9624 -51.2572)
		(end 384.9624 -49.115218)
		(width 0.089408)
		(layer "In9.Cu")
		(net "SPI_PCH_CS0_N")
	)
	(segment
		(start 380.935484 -74.40041)
		(end 381.759206 -73.576688)
		(width 0.089408)
		(layer "In9.Cu")
		(net "SPI_PCH_CS0_N")
	)
	(segment
		(start 380.935484 -75.35037)
		(end 380.935484 -74.40041)
		(width 0.089408)
		(layer "In9.Cu")
		(net "SPI_PCH_CS0_N")
	)
	(segment
		(start 385.223512 -55.720234)
		(end 385.223512 -55.084726)
		(width 0.089408)
		(layer "In9.Cu")
		(net "SPI_PCH_CS0_N")
	)
	(segment
		(start 384.175 -60.013088)
		(end 384.175 -56.768746)
		(width 0.089408)
		(layer "In9.Cu")
		(net "SPI_PCH_CS0_N")
	)
	(segment
		(start 383.533142 -65.952878)
		(end 383.9718 -65.51422)
		(width 0.089408)
		(layer "In9.Cu")
		(net "SPI_PCH_CS0_N")
	)
	(segment
		(start 384.7338 -51.4858)
		(end 384.9624 -51.2572)
		(width 0.089408)
		(layer "In9.Cu")
		(net "SPI_PCH_CS0_N")
	)
	(segment
		(start 384.7338 -54.595014)
		(end 384.7338 -51.4858)
		(width 0.089408)
		(layer "In9.Cu")
		(net "SPI_PCH_CS0_N")
	)
	(segment
		(start 383.9718 -64.42964)
		(end 383.8956 -64.35344)
		(width 0.089408)
		(layer "In9.Cu")
		(net "SPI_PCH_CS0_N")
	)
	(segment
		(start 384.82524 -48.978058)
		(end 384.82524 -48.880522)
		(width 0.089408)
		(layer "In9.Cu")
		(net "SPI_PCH_CS0_N")
	)
	(segment
		(start 379.884686 -78.187042)
		(end 379.884686 -77.600556)
		(width 0.089408)
		(layer "In9.Cu")
		(net "SPI_PCH_CS0_N")
	)
	(segment
		(start 384.9624 -49.115218)
		(end 384.82524 -48.978058)
		(width 0.089408)
		(layer "In9.Cu")
		(net "SPI_PCH_CS0_N")
	)
	(segment
		(start 376.561096 -84.105496)
		(end 376.561096 -83.58505)
		(width 0.089408)
		(layer "In9.Cu")
		(net "SPI_PCH_CS0_N")
	)
	(segment
		(start 380.310644 -75.97521)
		(end 380.935484 -75.35037)
		(width 0.089408)
		(layer "In9.Cu")
		(net "SPI_PCH_CS0_N")
	)
	(segment
		(start 383.243328 -68.916296)
		(end 382.90881 -68.581778)
		(width 0.089408)
		(layer "In9.Cu")
		(net "SPI_PCH_CS0_N")
	)
	(segment
		(start 383.534666 -60.653422)
		(end 384.175 -60.013088)
		(width 0.089408)
		(layer "In9.Cu")
		(net "SPI_PCH_CS0_N")
	)
	(segment
		(start 381.759206 -72.335644)
		(end 382.490472 -71.604378)
		(width 0.089408)
		(layer "In9.Cu")
		(net "SPI_PCH_CS0_N")
	)
	(segment
		(start 382.490472 -70.40372)
		(end 383.243328 -69.650864)
		(width 0.089408)
		(layer "In9.Cu")
		(net "SPI_PCH_CS0_N")
	)
	(segment
		(start 383.534666 -61.519308)
		(end 383.534666 -60.653422)
		(width 0.089408)
		(layer "In9.Cu")
		(net "SPI_PCH_CS0_N")
	)
	(segment
		(start 383.533142 -66.791332)
		(end 383.533142 -65.952878)
		(width 0.089408)
		(layer "In9.Cu")
		(net "SPI_PCH_CS0_N")
	)
	(segment
		(start 383.9718 -65.51422)
		(end 383.9718 -64.42964)
		(width 0.089408)
		(layer "In9.Cu")
		(net "SPI_PCH_CS0_N")
	)
	(segment
		(start 380.418848 -79.948786)
		(end 380.418848 -78.721204)
		(width 0.089408)
		(layer "In9.Cu")
		(net "SPI_PCH_CS0_N")
	)
	(segment
		(start 376.991626 -83.376008)
		(end 380.418848 -79.948786)
		(width 0.089408)
		(layer "In9.Cu")
		(net "SPI_PCH_CS0_N")
	)
	(segment
		(start 380.418848 -78.721204)
		(end 379.884686 -78.187042)
		(width 0.089408)
		(layer "In9.Cu")
		(net "SPI_PCH_CS0_N")
	)
	(segment
		(start 385.223512 -55.084726)
		(end 384.7338 -54.595014)
		(width 0.089408)
		(layer "In9.Cu")
		(net "SPI_PCH_CS0_N")
	)
	(segment
		(start 376.561096 -83.58505)
		(end 376.770138 -83.376008)
		(width 0.089408)
		(layer "In9.Cu")
		(net "SPI_PCH_CS0_N")
	)
	(segment
		(start 382.90881 -68.581778)
		(end 382.90881 -67.415664)
		(width 0.089408)
		(layer "In9.Cu")
		(net "SPI_PCH_CS0_N")
	)
	(segment
		(start 383.8956 -64.35344)
		(end 383.8956 -61.880242)
		(width 0.089408)
		(layer "In9.Cu")
		(net "SPI_PCH_CS0_N")
	)
	(segment
		(start 379.957838 -76.865226)
		(end 380.310644 -76.51242)
		(width 0.089408)
		(layer "In9.Cu")
		(net "SPI_PCH_CS0_N")
	)
	(segment
		(start 405.715724 -81.040986)
		(end 405.033734 -80.358996)
		(width 0.10795)
		(layer "F.Cu")
		(net "LED_GBE_P3_1")
	)
	(segment
		(start 397.904462 -91.824302)
		(end 398.109948 -91.824302)
		(width 0.10795)
		(layer "F.Cu")
		(net "LED_GBE_P3_1")
	)
	(segment
		(start 405.033734 -80.358996)
		(end 405.033734 -79.413608)
		(width 0.10795)
		(layer "F.Cu")
		(net "LED_GBE_P3_1")
	)
	(segment
		(start 398.456404 -91.477846)
		(end 398.456404 -90.909394)
		(width 0.10795)
		(layer "F.Cu")
		(net "LED_GBE_P3_1")
	)
	(segment
		(start 458.484732 -64.708532)
		(end 426.347128 -64.708532)
		(width 0.10795)
		(layer "F.Cu")
		(net "LED_GBE_P3_1")
	)
	(segment
		(start 405.715724 -86.448138)
		(end 405.715724 -81.040986)
		(width 0.10795)
		(layer "F.Cu")
		(net "LED_GBE_P3_1")
	)
	(segment
		(start 414.36544 -72.549766)
		(end 414.410652 -72.549766)
		(width 0.10795)
		(layer "F.Cu")
		(net "LED_GBE_P3_1")
	)
	(segment
		(start 414.191958 -72.55002)
		(end 414.365186 -72.55002)
		(width 0.10795)
		(layer "F.Cu")
		(net "LED_GBE_P3_1")
	)
	(segment
		(start 414.584134 -72.55002)
		(end 414.584388 -72.549766)
		(width 0.10795)
		(layer "F.Cu")
		(net "LED_GBE_P3_1")
	)
	(segment
		(start 424.1165 -66.93916)
		(end 424.1165 -72.156066)
		(width 0.10795)
		(layer "F.Cu")
		(net "LED_GBE_P3_1")
	)
	(segment
		(start 424.1165 -72.156066)
		(end 421.26535 -75.007216)
		(width 0.10795)
		(layer "F.Cu")
		(net "LED_GBE_P3_1")
	)
	(segment
		(start 414.365186 -72.55002)
		(end 414.36544 -72.549766)
		(width 0.10795)
		(layer "F.Cu")
		(net "LED_GBE_P3_1")
	)
	(segment
		(start 458.95006 -62.00267)
		(end 458.95006 -64.243204)
		(width 0.10795)
		(layer "F.Cu")
		(net "LED_GBE_P3_1")
	)
	(segment
		(start 404.14575 -75.176634)
		(end 407.614882 -71.707502)
		(width 0.10795)
		(layer "F.Cu")
		(net "LED_GBE_P3_1")
	)
	(segment
		(start 458.95006 -64.243204)
		(end 458.484732 -64.708532)
		(width 0.10795)
		(layer "F.Cu")
		(net "LED_GBE_P3_1")
	)
	(segment
		(start 397.49095 -92.378784)
		(end 397.49095 -92.237814)
		(width 0.10795)
		(layer "F.Cu")
		(net "LED_GBE_P3_1")
	)
	(segment
		(start 398.109948 -91.824302)
		(end 398.456404 -91.477846)
		(width 0.10795)
		(layer "F.Cu")
		(net "LED_GBE_P3_1")
	)
	(segment
		(start 398.456404 -90.909394)
		(end 401.20697 -88.158828)
		(width 0.10795)
		(layer "F.Cu")
		(net "LED_GBE_P3_1")
	)
	(segment
		(start 401.20697 -88.158828)
		(end 404.005034 -88.158828)
		(width 0.10795)
		(layer "F.Cu")
		(net "LED_GBE_P3_1")
	)
	(segment
		(start 414.584388 -72.549766)
		(end 416.18662 -72.549766)
		(width 0.10795)
		(layer "F.Cu")
		(net "LED_GBE_P3_1")
	)
	(segment
		(start 397.485108 -93.959934)
		(end 397.485108 -93.267276)
		(width 0.0889)
		(layer "F.Cu")
		(net "LED_GBE_P3_1")
	)
	(segment
		(start 418.64407 -75.007216)
		(end 416.964876 -73.328022)
		(width 0.10795)
		(layer "F.Cu")
		(net "LED_GBE_P3_1")
	)
	(segment
		(start 404.14575 -78.525624)
		(end 404.14575 -75.176634)
		(width 0.10795)
		(layer "F.Cu")
		(net "LED_GBE_P3_1")
	)
	(segment
		(start 414.410906 -72.55002)
		(end 414.584134 -72.55002)
		(width 0.10795)
		(layer "F.Cu")
		(net "LED_GBE_P3_1")
	)
	(segment
		(start 397.49095 -92.237814)
		(end 397.904462 -91.824302)
		(width 0.10795)
		(layer "F.Cu")
		(net "LED_GBE_P3_1")
	)
	(segment
		(start 404.005034 -88.158828)
		(end 405.715724 -86.448138)
		(width 0.10795)
		(layer "F.Cu")
		(net "LED_GBE_P3_1")
	)
	(segment
		(start 397.425418 -92.444316)
		(end 397.49095 -92.378784)
		(width 0.0889)
		(layer "F.Cu")
		(net "LED_GBE_P3_1")
	)
	(segment
		(start 426.347128 -64.708532)
		(end 424.1165 -66.93916)
		(width 0.10795)
		(layer "F.Cu")
		(net "LED_GBE_P3_1")
	)
	(segment
		(start 421.26535 -75.007216)
		(end 418.64407 -75.007216)
		(width 0.10795)
		(layer "F.Cu")
		(net "LED_GBE_P3_1")
	)
	(segment
		(start 407.614882 -71.707502)
		(end 413.34944 -71.707502)
		(width 0.10795)
		(layer "F.Cu")
		(net "LED_GBE_P3_1")
	)
	(segment
		(start 397.485108 -93.267276)
		(end 397.425418 -93.207586)
		(width 0.0889)
		(layer "F.Cu")
		(net "LED_GBE_P3_1")
	)
	(segment
		(start 416.18662 -72.549766)
		(end 416.964876 -73.328022)
		(width 0.10795)
		(layer "F.Cu")
		(net "LED_GBE_P3_1")
	)
	(segment
		(start 397.425418 -93.207586)
		(end 397.425418 -92.444316)
		(width 0.0889)
		(layer "F.Cu")
		(net "LED_GBE_P3_1")
	)
	(segment
		(start 413.34944 -71.707502)
		(end 414.191958 -72.55002)
		(width 0.10795)
		(layer "F.Cu")
		(net "LED_GBE_P3_1")
	)
	(segment
		(start 405.033734 -79.413608)
		(end 404.14575 -78.525624)
		(width 0.10795)
		(layer "F.Cu")
		(net "LED_GBE_P3_1")
	)
	(segment
		(start 414.410652 -72.549766)
		(end 414.410906 -72.55002)
		(width 0.10795)
		(layer "F.Cu")
		(net "LED_GBE_P3_1")
	)
	(via
		(at 416.964876 -73.328022)
		(size 0.762)
		(drill 0.381)
		(layers "F.Cu" "B.Cu")
		(net "LED_GBE_P3_1")
	)
	(segment
		(start 423.6974 -71.793608)
		(end 421.605456 -73.885552)
		(width 0.10795)
		(layer "F.Cu")
		(net "LED_GBE_P1_1")
	)
	(segment
		(start 396.48511 -93.959934)
		(end 396.48511 -93.27896)
		(width 0.0889)
		(layer "F.Cu")
		(net "LED_GBE_P1_1")
	)
	(segment
		(start 446.950084 -57.596024)
		(end 446.950084 -56.419242)
		(width 0.10795)
		(layer "F.Cu")
		(net "LED_GBE_P1_1")
	)
	(segment
		(start 402.87575 -78.09865)
		(end 403.5044 -77.47)
		(width 0.10795)
		(layer "F.Cu")
		(net "LED_GBE_P1_1")
	)
	(segment
		(start 439.409078 -64.289432)
		(end 426.173392 -64.289432)
		(width 0.10795)
		(layer "F.Cu")
		(net "LED_GBE_P1_1")
	)
	(segment
		(start 403.737318 -79.271114)
		(end 403.433788 -79.271114)
		(width 0.10795)
		(layer "F.Cu")
		(net "LED_GBE_P1_1")
	)
	(segment
		(start 420.420292 -73.885552)
		(end 418.030152 -71.495412)
		(width 0.10795)
		(layer "F.Cu")
		(net "LED_GBE_P1_1")
	)
	(segment
		(start 403.433788 -79.271114)
		(end 402.87575 -78.713076)
		(width 0.10795)
		(layer "F.Cu")
		(net "LED_GBE_P1_1")
	)
	(segment
		(start 415.30778 -71.495412)
		(end 417.40328 -71.495412)
		(width 0.10795)
		(layer "F.Cu")
		(net "LED_GBE_P1_1")
	)
	(segment
		(start 423.6974 -66.765424)
		(end 423.6974 -71.793608)
		(width 0.10795)
		(layer "F.Cu")
		(net "LED_GBE_P1_1")
	)
	(segment
		(start 396.583662 -91.20251)
		(end 398.937226 -88.848946)
		(width 0.10795)
		(layer "F.Cu")
		(net "LED_GBE_P1_1")
	)
	(segment
		(start 421.605456 -73.885552)
		(end 420.420292 -73.885552)
		(width 0.10795)
		(layer "F.Cu")
		(net "LED_GBE_P1_1")
	)
	(segment
		(start 400.719036 -87.530178)
		(end 403.74443 -87.530178)
		(width 0.10795)
		(layer "F.Cu")
		(net "LED_GBE_P1_1")
	)
	(segment
		(start 439.83148 -63.86703)
		(end 439.409078 -64.289432)
		(width 0.10795)
		(layer "F.Cu")
		(net "LED_GBE_P1_1")
	)
	(segment
		(start 396.535402 -93.228668)
		(end 396.535402 -93.223334)
		(width 0.0889)
		(layer "F.Cu")
		(net "LED_GBE_P1_1")
	)
	(segment
		(start 396.535402 -93.223334)
		(end 396.583662 -93.175074)
		(width 0.10795)
		(layer "F.Cu")
		(net "LED_GBE_P1_1")
	)
	(segment
		(start 403.5044 -77.47)
		(end 403.5044 -74.860404)
		(width 0.10795)
		(layer "F.Cu")
		(net "LED_GBE_P1_1")
	)
	(segment
		(start 408.228292 -70.136512)
		(end 413.94888 -70.136512)
		(width 0.10795)
		(layer "F.Cu")
		(net "LED_GBE_P1_1")
	)
	(segment
		(start 399.400268 -88.848946)
		(end 400.719036 -87.530178)
		(width 0.10795)
		(layer "F.Cu")
		(net "LED_GBE_P1_1")
	)
	(segment
		(start 426.173392 -64.289432)
		(end 423.6974 -66.765424)
		(width 0.10795)
		(layer "F.Cu")
		(net "LED_GBE_P1_1")
	)
	(segment
		(start 396.48511 -93.27896)
		(end 396.535402 -93.228668)
		(width 0.0889)
		(layer "F.Cu")
		(net "LED_GBE_P1_1")
	)
	(segment
		(start 398.937226 -88.848946)
		(end 399.400268 -88.848946)
		(width 0.10795)
		(layer "F.Cu")
		(net "LED_GBE_P1_1")
	)
	(segment
		(start 404.405084 -79.93888)
		(end 403.737318 -79.271114)
		(width 0.10795)
		(layer "F.Cu")
		(net "LED_GBE_P1_1")
	)
	(segment
		(start 405.087074 -86.187534)
		(end 405.087074 -81.30159)
		(width 0.10795)
		(layer "F.Cu")
		(net "LED_GBE_P1_1")
	)
	(segment
		(start 413.94888 -70.136512)
		(end 415.30778 -71.495412)
		(width 0.10795)
		(layer "F.Cu")
		(net "LED_GBE_P1_1")
	)
	(segment
		(start 403.5044 -74.860404)
		(end 408.228292 -70.136512)
		(width 0.10795)
		(layer "F.Cu")
		(net "LED_GBE_P1_1")
	)
	(segment
		(start 418.030152 -71.495412)
		(end 417.40328 -71.495412)
		(width 0.10795)
		(layer "F.Cu")
		(net "LED_GBE_P1_1")
	)
	(segment
		(start 439.83148 -56.53532)
		(end 439.83148 -63.86703)
		(width 0.10795)
		(layer "F.Cu")
		(net "LED_GBE_P1_1")
	)
	(segment
		(start 404.405084 -80.6196)
		(end 404.405084 -79.93888)
		(width 0.10795)
		(layer "F.Cu")
		(net "LED_GBE_P1_1")
	)
	(segment
		(start 440.171078 -56.195722)
		(end 439.83148 -56.53532)
		(width 0.10795)
		(layer "F.Cu")
		(net "LED_GBE_P1_1")
	)
	(segment
		(start 446.726564 -56.195722)
		(end 440.171078 -56.195722)
		(width 0.10795)
		(layer "F.Cu")
		(net "LED_GBE_P1_1")
	)
	(segment
		(start 405.087074 -81.30159)
		(end 404.405084 -80.6196)
		(width 0.10795)
		(layer "F.Cu")
		(net "LED_GBE_P1_1")
	)
	(segment
		(start 396.583662 -93.175074)
		(end 396.583662 -91.20251)
		(width 0.10795)
		(layer "F.Cu")
		(net "LED_GBE_P1_1")
	)
	(segment
		(start 403.74443 -87.530178)
		(end 405.087074 -86.187534)
		(width 0.10795)
		(layer "F.Cu")
		(net "LED_GBE_P1_1")
	)
	(segment
		(start 446.950084 -56.419242)
		(end 446.726564 -56.195722)
		(width 0.10795)
		(layer "F.Cu")
		(net "LED_GBE_P1_1")
	)
	(segment
		(start 402.87575 -78.713076)
		(end 402.87575 -78.09865)
		(width 0.10795)
		(layer "F.Cu")
		(net "LED_GBE_P1_1")
	)
	(via
		(at 417.40328 -71.495412)
		(size 0.762)
		(drill 0.381)
		(layers "F.Cu" "B.Cu")
		(net "LED_GBE_P1_1")
	)
	(segment
		(start 398.705578 -91.06916)
		(end 399.471134 -90.303604)
		(width 0.10795)
		(layer "F.Cu")
		(net "LED_GBE_P1_0")
	)
	(segment
		(start 405.314404 -80.343248)
		(end 405.314404 -79.355696)
		(width 0.10795)
		(layer "F.Cu")
		(net "LED_GBE_P1_0")
	)
	(segment
		(start 405.314404 -79.355696)
		(end 404.3553 -78.396592)
		(width 0.10795)
		(layer "F.Cu")
		(net "LED_GBE_P1_0")
	)
	(segment
		(start 446.14973 -57.596278)
		(end 446.14973 -58.75274)
		(width 0.10795)
		(layer "F.Cu")
		(net "LED_GBE_P1_0")
	)
	(segment
		(start 404.3553 -78.396592)
		(end 404.3553 -75.263502)
		(width 0.10795)
		(layer "F.Cu")
		(net "LED_GBE_P1_0")
	)
	(segment
		(start 446.14973 -58.75274)
		(end 445.525144 -59.377326)
		(width 0.10795)
		(layer "F.Cu")
		(net "LED_GBE_P1_0")
	)
	(segment
		(start 398.62633 -91.719654)
		(end 398.705578 -91.640406)
		(width 0.10795)
		(layer "F.Cu")
		(net "LED_GBE_P1_0")
	)
	(segment
		(start 407.660602 -71.9582)
		(end 413.30372 -71.9582)
		(width 0.10795)
		(layer "F.Cu")
		(net "LED_GBE_P1_0")
	)
	(segment
		(start 404.091902 -88.368378)
		(end 405.925274 -86.535006)
		(width 0.10795)
		(layer "F.Cu")
		(net "LED_GBE_P1_0")
	)
	(segment
		(start 398.485106 -91.860878)
		(end 398.62633 -91.719654)
		(width 0.0889)
		(layer "F.Cu")
		(net "LED_GBE_P1_0")
	)
	(segment
		(start 444.570104 -59.377326)
		(end 444.363348 -59.17057)
		(width 0.10795)
		(layer "F.Cu")
		(net "LED_GBE_P1_0")
	)
	(segment
		(start 445.525144 -59.377326)
		(end 444.570104 -59.377326)
		(width 0.10795)
		(layer "F.Cu")
		(net "LED_GBE_P1_0")
	)
	(segment
		(start 414.449514 -73.103994)
		(end 415.71037 -73.103994)
		(width 0.10795)
		(layer "F.Cu")
		(net "LED_GBE_P1_0")
	)
	(segment
		(start 415.71037 -73.103994)
		(end 415.7472 -73.140824)
		(width 0.10795)
		(layer "F.Cu")
		(net "LED_GBE_P1_0")
	)
	(segment
		(start 405.925274 -80.954118)
		(end 405.314404 -80.343248)
		(width 0.10795)
		(layer "F.Cu")
		(net "LED_GBE_P1_0")
	)
	(segment
		(start 404.3553 -75.263502)
		(end 407.660602 -71.9582)
		(width 0.10795)
		(layer "F.Cu")
		(net "LED_GBE_P1_0")
	)
	(segment
		(start 399.471388 -90.303604)
		(end 401.406614 -88.368378)
		(width 0.10795)
		(layer "F.Cu")
		(net "LED_GBE_P1_0")
	)
	(segment
		(start 401.406614 -88.368378)
		(end 404.091902 -88.368378)
		(width 0.10795)
		(layer "F.Cu")
		(net "LED_GBE_P1_0")
	)
	(segment
		(start 398.705578 -91.640406)
		(end 398.705578 -91.06916)
		(width 0.10795)
		(layer "F.Cu")
		(net "LED_GBE_P1_0")
	)
	(segment
		(start 399.471134 -90.303604)
		(end 399.471388 -90.303604)
		(width 0.10795)
		(layer "F.Cu")
		(net "LED_GBE_P1_0")
	)
	(segment
		(start 405.925274 -86.535006)
		(end 405.925274 -80.954118)
		(width 0.10795)
		(layer "F.Cu")
		(net "LED_GBE_P1_0")
	)
	(segment
		(start 413.30372 -71.9582)
		(end 414.449514 -73.103994)
		(width 0.10795)
		(layer "F.Cu")
		(net "LED_GBE_P1_0")
	)
	(segment
		(start 398.485106 -94.790006)
		(end 398.485106 -91.860878)
		(width 0.0889)
		(layer "F.Cu")
		(net "LED_GBE_P1_0")
	)
	(segment
		(start 446.149984 -57.596024)
		(end 446.14973 -57.596278)
		(width 0.10795)
		(layer "F.Cu")
		(net "LED_GBE_P1_0")
	)
	(via
		(at 444.363348 -59.17057)
		(size 0.508)
		(drill 0.254)
		(layers "F.Cu" "B.Cu")
		(net "LED_GBE_P1_0")
	)
	(via
		(at 415.7472 -73.140824)
		(size 0.508)
		(drill 0.254)
		(layers "F.Cu" "B.Cu")
		(net "LED_GBE_P1_0")
	)
	(segment
		(start 416.842702 -63.684912)
		(end 417.074858 -63.917068)
		(width 0.089408)
		(layer "In2.Cu")
		(net "LED_GBE_P1_0")
	)
	(segment
		(start 434.25999 -56.099964)
		(end 430.492916 -56.099964)
		(width 0.089408)
		(layer "In2.Cu")
		(net "LED_GBE_P1_0")
	)
	(segment
		(start 444.363348 -59.17057)
		(end 444.363348 -58.749184)
		(width 0.089408)
		(layer "In2.Cu")
		(net "LED_GBE_P1_0")
	)
	(segment
		(start 443.433454 -57.81929)
		(end 435.979316 -57.81929)
		(width 0.089408)
		(layer "In2.Cu")
		(net "LED_GBE_P1_0")
	)
	(segment
		(start 430.492916 -56.099964)
		(end 429.222408 -57.370472)
		(width 0.089408)
		(layer "In2.Cu")
		(net "LED_GBE_P1_0")
	)
	(segment
		(start 416.842702 -72.045322)
		(end 415.7472 -73.140824)
		(width 0.089408)
		(layer "In2.Cu")
		(net "LED_GBE_P1_0")
	)
	(segment
		(start 429.222408 -57.370472)
		(end 422.982644 -57.370472)
		(width 0.089408)
		(layer "In2.Cu")
		(net "LED_GBE_P1_0")
	)
	(segment
		(start 416.842702 -62.332616)
		(end 416.842702 -63.684912)
		(width 0.089408)
		(layer "In2.Cu")
		(net "LED_GBE_P1_0")
	)
	(segment
		(start 417.074604 -64.392302)
		(end 417.074604 -70.52691)
		(width 0.089408)
		(layer "In2.Cu")
		(net "LED_GBE_P1_0")
	)
	(segment
		(start 444.363348 -58.749184)
		(end 443.433454 -57.81929)
		(width 0.089408)
		(layer "In2.Cu")
		(net "LED_GBE_P1_0")
	)
	(segment
		(start 416.842702 -70.758812)
		(end 416.842702 -72.045322)
		(width 0.089408)
		(layer "In2.Cu")
		(net "LED_GBE_P1_0")
	)
	(segment
		(start 417.074858 -64.392048)
		(end 417.074604 -64.392302)
		(width 0.089408)
		(layer "In2.Cu")
		(net "LED_GBE_P1_0")
	)
	(segment
		(start 418.234622 -62.118494)
		(end 417.056824 -62.118494)
		(width 0.089408)
		(layer "In2.Cu")
		(net "LED_GBE_P1_0")
	)
	(segment
		(start 435.979316 -57.81929)
		(end 434.25999 -56.099964)
		(width 0.089408)
		(layer "In2.Cu")
		(net "LED_GBE_P1_0")
	)
	(segment
		(start 417.074858 -63.917068)
		(end 417.074858 -64.392048)
		(width 0.089408)
		(layer "In2.Cu")
		(net "LED_GBE_P1_0")
	)
	(segment
		(start 422.982644 -57.370472)
		(end 418.234622 -62.118494)
		(width 0.089408)
		(layer "In2.Cu")
		(net "LED_GBE_P1_0")
	)
	(segment
		(start 417.056824 -62.118494)
		(end 416.842702 -62.332616)
		(width 0.089408)
		(layer "In2.Cu")
		(net "LED_GBE_P1_0")
	)
	(segment
		(start 417.074604 -70.52691)
		(end 416.842702 -70.758812)
		(width 0.089408)
		(layer "In2.Cu")
		(net "LED_GBE_P1_0")
	)
	(segment
		(start 399.45437 -88.43645)
		(end 400.570192 -87.320628)
		(width 0.10795)
		(layer "F.Cu")
		(net "LED_GBE_P0_1")
	)
	(segment
		(start 396.28064 -93.194886)
		(end 396.38351 -93.092016)
		(width 0.0889)
		(layer "F.Cu")
		(net "LED_GBE_P0_1")
	)
	(segment
		(start 396.17396 -94.116652)
		(end 396.17396 -93.830902)
		(width 0.0889)
		(layer "F.Cu")
		(net "LED_GBE_P0_1")
	)
	(segment
		(start 414.096962 -69.926962)
		(end 408.141424 -69.926962)
		(width 0.10795)
		(layer "F.Cu")
		(net "LED_GBE_P0_1")
	)
	(segment
		(start 396.17396 -93.830902)
		(end 396.28064 -93.724222)
		(width 0.0889)
		(layer "F.Cu")
		(net "LED_GBE_P0_1")
	)
	(segment
		(start 403.738842 -80.540352)
		(end 403.491446 -80.292956)
		(width 0.10795)
		(layer "F.Cu")
		(net "LED_GBE_P0_1")
	)
	(segment
		(start 403.1996 -74.868786)
		(end 403.1996 -76.352654)
		(width 0.10795)
		(layer "F.Cu")
		(net "LED_GBE_P0_1")
	)
	(segment
		(start 396.28064 -93.724222)
		(end 396.28064 -93.194886)
		(width 0.0889)
		(layer "F.Cu")
		(net "LED_GBE_P0_1")
	)
	(segment
		(start 403.1996 -76.352654)
		(end 402.94179 -76.610464)
		(width 0.10795)
		(layer "F.Cu")
		(net "LED_GBE_P0_1")
	)
	(segment
		(start 396.38351 -90.683842)
		(end 398.630902 -88.43645)
		(width 0.10795)
		(layer "F.Cu")
		(net "LED_GBE_P0_1")
	)
	(segment
		(start 396.38351 -93.092016)
		(end 396.38351 -90.683842)
		(width 0.0889)
		(layer "F.Cu")
		(net "LED_GBE_P0_1")
	)
	(segment
		(start 403.491446 -80.00238)
		(end 402.6662 -79.177134)
		(width 0.10795)
		(layer "F.Cu")
		(net "LED_GBE_P0_1")
	)
	(segment
		(start 402.6662 -79.177134)
		(end 402.6662 -76.886054)
		(width 0.10795)
		(layer "F.Cu")
		(net "LED_GBE_P0_1")
	)
	(segment
		(start 408.141424 -69.926962)
		(end 403.1996 -74.868786)
		(width 0.10795)
		(layer "F.Cu")
		(net "LED_GBE_P0_1")
	)
	(segment
		(start 415.717736 -71.07301)
		(end 415.24301 -71.07301)
		(width 0.10795)
		(layer "F.Cu")
		(net "LED_GBE_P0_1")
	)
	(segment
		(start 398.630902 -88.43645)
		(end 399.45437 -88.43645)
		(width 0.10795)
		(layer "F.Cu")
		(net "LED_GBE_P0_1")
	)
	(segment
		(start 403.491446 -80.292956)
		(end 403.491446 -80.00238)
		(width 0.10795)
		(layer "F.Cu")
		(net "LED_GBE_P0_1")
	)
	(segment
		(start 396.48511 -94.427802)
		(end 396.17396 -94.116652)
		(width 0.0889)
		(layer "F.Cu")
		(net "LED_GBE_P0_1")
	)
	(segment
		(start 415.24301 -71.07301)
		(end 414.096962 -69.926962)
		(width 0.10795)
		(layer "F.Cu")
		(net "LED_GBE_P0_1")
	)
	(segment
		(start 402.206714 -87.320628)
		(end 404.877524 -84.649818)
		(width 0.10795)
		(layer "F.Cu")
		(net "LED_GBE_P0_1")
	)
	(segment
		(start 404.877524 -84.649818)
		(end 404.877524 -81.388458)
		(width 0.10795)
		(layer "F.Cu")
		(net "LED_GBE_P0_1")
	)
	(segment
		(start 404.877524 -81.388458)
		(end 404.029418 -80.540352)
		(width 0.10795)
		(layer "F.Cu")
		(net "LED_GBE_P0_1")
	)
	(segment
		(start 396.48511 -94.790006)
		(end 396.48511 -94.427802)
		(width 0.0889)
		(layer "F.Cu")
		(net "LED_GBE_P0_1")
	)
	(segment
		(start 400.570192 -87.320628)
		(end 402.206714 -87.320628)
		(width 0.10795)
		(layer "F.Cu")
		(net "LED_GBE_P0_1")
	)
	(segment
		(start 402.6662 -76.886054)
		(end 402.94179 -76.610464)
		(width 0.10795)
		(layer "F.Cu")
		(net "LED_GBE_P0_1")
	)
	(segment
		(start 449.35013 -62.00267)
		(end 449.35013 -59.445906)
		(width 0.10795)
		(layer "F.Cu")
		(net "LED_GBE_P0_1")
	)
	(segment
		(start 404.029418 -80.540352)
		(end 403.738842 -80.540352)
		(width 0.10795)
		(layer "F.Cu")
		(net "LED_GBE_P0_1")
	)
	(segment
		(start 449.35013 -59.445906)
		(end 449.2498 -59.345576)
		(width 0.10795)
		(layer "F.Cu")
		(net "LED_GBE_P0_1")
	)
	(via
		(at 402.94179 -76.610464)
		(size 0.762)
		(drill 0.381)
		(layers "F.Cu" "B.Cu")
		(net "LED_GBE_P0_1")
	)
	(via
		(at 415.717736 -71.07301)
		(size 0.508)
		(drill 0.254)
		(layers "F.Cu" "B.Cu")
		(net "LED_GBE_P0_1")
	)
	(via
		(at 449.2498 -59.345576)
		(size 0.508)
		(drill 0.254)
		(layers "F.Cu" "B.Cu")
		(net "LED_GBE_P0_1")
	)
	(segment
		(start 429.089566 -56.692546)
		(end 422.849802 -56.692546)
		(width 0.089408)
		(layer "In2.Cu")
		(net "LED_GBE_P0_1")
	)
	(segment
		(start 448.025266 -57.206134)
		(end 436.176928 -57.206134)
		(width 0.089408)
		(layer "In2.Cu")
		(net "LED_GBE_P0_1")
	)
	(segment
		(start 416.130486 -61.48197)
		(end 415.46018 -62.152276)
		(width 0.089408)
		(layer "In2.Cu")
		(net "LED_GBE_P0_1")
	)
	(segment
		(start 449.2498 -59.345576)
		(end 449.157852 -59.253628)
		(width 0.089408)
		(layer "In2.Cu")
		(net "LED_GBE_P0_1")
	)
	(segment
		(start 416.50158 -70.289166)
		(end 415.717736 -71.07301)
		(width 0.089408)
		(layer "In2.Cu")
		(net "LED_GBE_P0_1")
	)
	(segment
		(start 449.157852 -59.253628)
		(end 449.157852 -58.33872)
		(width 0.089408)
		(layer "In2.Cu")
		(net "LED_GBE_P0_1")
	)
	(segment
		(start 418.060378 -61.48197)
		(end 416.130486 -61.48197)
		(width 0.089408)
		(layer "In2.Cu")
		(net "LED_GBE_P0_1")
	)
	(segment
		(start 422.849802 -56.692546)
		(end 418.060378 -61.48197)
		(width 0.089408)
		(layer "In2.Cu")
		(net "LED_GBE_P0_1")
	)
	(segment
		(start 436.176928 -57.206134)
		(end 434.497734 -55.52694)
		(width 0.089408)
		(layer "In2.Cu")
		(net "LED_GBE_P0_1")
	)
	(segment
		(start 430.255172 -55.52694)
		(end 429.089566 -56.692546)
		(width 0.089408)
		(layer "In2.Cu")
		(net "LED_GBE_P0_1")
	)
	(segment
		(start 415.46018 -62.152276)
		(end 415.46018 -63.113158)
		(width 0.089408)
		(layer "In2.Cu")
		(net "LED_GBE_P0_1")
	)
	(segment
		(start 449.157852 -58.33872)
		(end 448.025266 -57.206134)
		(width 0.089408)
		(layer "In2.Cu")
		(net "LED_GBE_P0_1")
	)
	(segment
		(start 416.50158 -64.154558)
		(end 416.50158 -70.289166)
		(width 0.089408)
		(layer "In2.Cu")
		(net "LED_GBE_P0_1")
	)
	(segment
		(start 434.497734 -55.52694)
		(end 430.255172 -55.52694)
		(width 0.089408)
		(layer "In2.Cu")
		(net "LED_GBE_P0_1")
	)
	(segment
		(start 415.46018 -63.113158)
		(end 416.50158 -64.154558)
		(width 0.089408)
		(layer "In2.Cu")
		(net "LED_GBE_P0_1")
	)
	(segment
		(start 405.506174 -86.36127)
		(end 403.918166 -87.949278)
		(width 0.10795)
		(layer "F.Cu")
		(net "LED_GBE_P0_0")
	)
	(segment
		(start 420.539926 -74.797666)
		(end 419.021768 -73.279508)
		(width 0.10795)
		(layer "F.Cu")
		(net "LED_GBE_P0_0")
	)
	(segment
		(start 448.55003 -63.568072)
		(end 447.61912 -64.498982)
		(width 0.10795)
		(layer "F.Cu")
		(net "LED_GBE_P0_0")
	)
	(segment
		(start 397.44269 -91.599004)
		(end 397.037814 -92.00388)
		(width 0.0889)
		(layer "F.Cu")
		(net "LED_GBE_P0_0")
	)
	(segment
		(start 423.90695 -72.069198)
		(end 421.178482 -74.797666)
		(width 0.10795)
		(layer "F.Cu")
		(net "LED_GBE_P0_0")
	)
	(segment
		(start 419.021768 -73.279508)
		(end 418.082476 -72.340216)
		(width 0.10795)
		(layer "F.Cu")
		(net "LED_GBE_P0_0")
	)
	(segment
		(start 423.90695 -66.852292)
		(end 423.90695 -72.069198)
		(width 0.10795)
		(layer "F.Cu")
		(net "LED_GBE_P0_0")
	)
	(segment
		(start 418.082476 -72.340216)
		(end 414.278572 -72.340216)
		(width 0.10795)
		(layer "F.Cu")
		(net "LED_GBE_P0_0")
	)
	(segment
		(start 397.037814 -93.492066)
		(end 396.984982 -93.544898)
		(width 0.0889)
		(layer "F.Cu")
		(net "LED_GBE_P0_0")
	)
	(segment
		(start 397.890746 -90.950796)
		(end 397.829278 -90.950796)
		(width 0.10795)
		(layer "F.Cu")
		(net "LED_GBE_P0_0")
	)
	(segment
		(start 400.892772 -87.949278)
		(end 398.538446 -90.303604)
		(width 0.10795)
		(layer "F.Cu")
		(net "LED_GBE_P0_0")
	)
	(segment
		(start 404.824184 -79.561944)
		(end 404.824184 -80.445864)
		(width 0.10795)
		(layer "F.Cu")
		(net "LED_GBE_P0_0")
	)
	(segment
		(start 414.278572 -72.340216)
		(end 413.436308 -71.497952)
		(width 0.10795)
		(layer "F.Cu")
		(net "LED_GBE_P0_0")
	)
	(segment
		(start 407.528014 -71.497952)
		(end 403.9362 -75.089766)
		(width 0.10795)
		(layer "F.Cu")
		(net "LED_GBE_P0_0")
	)
	(segment
		(start 397.829278 -90.950796)
		(end 397.44269 -91.337384)
		(width 0.10795)
		(layer "F.Cu")
		(net "LED_GBE_P0_0")
	)
	(segment
		(start 398.328896 -90.5129)
		(end 398.328642 -90.5129)
		(width 0.10795)
		(layer "F.Cu")
		(net "LED_GBE_P0_0")
	)
	(segment
		(start 397.037814 -92.00388)
		(end 397.037814 -93.492066)
		(width 0.0889)
		(layer "F.Cu")
		(net "LED_GBE_P0_0")
	)
	(segment
		(start 397.44269 -91.337384)
		(end 397.44269 -91.599004)
		(width 0.10795)
		(layer "F.Cu")
		(net "LED_GBE_P0_0")
	)
	(segment
		(start 448.55003 -62.00267)
		(end 448.55003 -63.568072)
		(width 0.10795)
		(layer "F.Cu")
		(net "LED_GBE_P0_0")
	)
	(segment
		(start 403.918166 -87.949278)
		(end 400.892772 -87.949278)
		(width 0.10795)
		(layer "F.Cu")
		(net "LED_GBE_P0_0")
	)
	(segment
		(start 421.178482 -74.797666)
		(end 420.539926 -74.797666)
		(width 0.10795)
		(layer "F.Cu")
		(net "LED_GBE_P0_0")
	)
	(segment
		(start 398.538192 -90.303604)
		(end 398.328896 -90.5129)
		(width 0.10795)
		(layer "F.Cu")
		(net "LED_GBE_P0_0")
	)
	(segment
		(start 404.824184 -80.445864)
		(end 405.506174 -81.127854)
		(width 0.10795)
		(layer "F.Cu")
		(net "LED_GBE_P0_0")
	)
	(segment
		(start 447.61912 -64.498982)
		(end 426.26026 -64.498982)
		(width 0.10795)
		(layer "F.Cu")
		(net "LED_GBE_P0_0")
	)
	(segment
		(start 403.9362 -78.67396)
		(end 404.824184 -79.561944)
		(width 0.10795)
		(layer "F.Cu")
		(net "LED_GBE_P0_0")
	)
	(segment
		(start 398.538446 -90.303604)
		(end 398.538192 -90.303604)
		(width 0.10795)
		(layer "F.Cu")
		(net "LED_GBE_P0_0")
	)
	(segment
		(start 398.328642 -90.5129)
		(end 397.890746 -90.950796)
		(width 0.10795)
		(layer "F.Cu")
		(net "LED_GBE_P0_0")
	)
	(segment
		(start 403.9362 -75.089766)
		(end 403.9362 -78.67396)
		(width 0.10795)
		(layer "F.Cu")
		(net "LED_GBE_P0_0")
	)
	(segment
		(start 426.26026 -64.498982)
		(end 423.90695 -66.852292)
		(width 0.10795)
		(layer "F.Cu")
		(net "LED_GBE_P0_0")
	)
	(segment
		(start 413.436308 -71.497952)
		(end 407.528014 -71.497952)
		(width 0.10795)
		(layer "F.Cu")
		(net "LED_GBE_P0_0")
	)
	(segment
		(start 405.506174 -81.127854)
		(end 405.506174 -86.36127)
		(width 0.10795)
		(layer "F.Cu")
		(net "LED_GBE_P0_0")
	)
	(via
		(at 419.021768 -73.279508)
		(size 0.762)
		(drill 0.381)
		(layers "F.Cu" "B.Cu")
		(net "LED_GBE_P0_0")
	)
	(segment
		(start 455.519536 -63.626492)
		(end 455.822304 -63.626492)
		(width 0.1016)
		(layer "F.Cu")
		(net "KR_P0_OCP_RX_DP")
	)
	(segment
		(start 419.379654 -91.99626)
		(end 419.57244 -91.99626)
		(width 0.101854)
		(layer "F.Cu")
		(net "KR_P0_OCP_RX_DP")
	)
	(segment
		(start 455.923904 -63.219838)
		(end 455.750168 -63.046102)
		(width 0.1016)
		(layer "F.Cu")
		(net "KR_P0_OCP_RX_DP")
	)
	(segment
		(start 419.166294 -91.7829)
		(end 419.379654 -91.99626)
		(width 0.101854)
		(layer "F.Cu")
		(net "KR_P0_OCP_RX_DP")
	)
	(segment
		(start 419.655244 -91.913456)
		(end 419.655244 -91.5924)
		(width 0.101854)
		(layer "F.Cu")
		(net "KR_P0_OCP_RX_DP")
	)
	(segment
		(start 455.822304 -63.626492)
		(end 455.923904 -63.524892)
		(width 0.1016)
		(layer "F.Cu")
		(net "KR_P0_OCP_RX_DP")
	)
	(segment
		(start 455.923904 -63.524892)
		(end 455.923904 -63.219838)
		(width 0.1016)
		(layer "F.Cu")
		(net "KR_P0_OCP_RX_DP")
	)
	(segment
		(start 455.750168 -63.046102)
		(end 455.750168 -62.00267)
		(width 0.1016)
		(layer "F.Cu")
		(net "KR_P0_OCP_RX_DP")
	)
	(segment
		(start 418.7952 -91.7829)
		(end 419.166294 -91.7829)
		(width 0.101854)
		(layer "F.Cu")
		(net "KR_P0_OCP_RX_DP")
	)
	(segment
		(start 419.57244 -91.99626)
		(end 419.655244 -91.913456)
		(width 0.101854)
		(layer "F.Cu")
		(net "KR_P0_OCP_RX_DP")
	)
	(via
		(at 419.655244 -91.5924)
		(size 0.508)
		(drill 0.254)
		(layers "F.Cu" "B.Cu")
		(net "KR_P0_OCP_RX_DP")
	)
	(via
		(at 455.519536 -63.626492)
		(size 0.508)
		(drill 0.254)
		(layers "F.Cu" "B.Cu")
		(net "KR_P0_OCP_RX_DP")
	)
	(segment
		(start 440.034172 -62.651386)
		(end 438.615582 -61.232796)
		(width 0.101346)
		(layer "In9.Cu")
		(net "KR_P0_OCP_RX_DP")
	)
	(segment
		(start 438.615582 -61.232796)
		(end 437.243474 -61.232796)
		(width 0.101346)
		(layer "In9.Cu")
		(net "KR_P0_OCP_RX_DP")
	)
	(segment
		(start 425.96435 -59.63158)
		(end 422.902634 -59.63158)
		(width 0.101346)
		(layer "In9.Cu")
		(net "KR_P0_OCP_RX_DP")
	)
	(segment
		(start 419.695122 -86.847426)
		(end 419.389814 -87.152734)
		(width 0.101346)
		(layer "In9.Cu")
		(net "KR_P0_OCP_RX_DP")
	)
	(segment
		(start 448.695826 -62.956694)
		(end 448.391788 -62.956694)
		(width 0.101346)
		(layer "In9.Cu")
		(net "KR_P0_OCP_RX_DP")
	)
	(segment
		(start 436.938166 -61.538104)
		(end 436.634128 -61.538104)
		(width 0.101346)
		(layer "In9.Cu")
		(net "KR_P0_OCP_RX_DP")
	)
	(segment
		(start 419.655244 -91.91625)
		(end 419.655244 -91.5924)
		(width 0.101346)
		(layer "In9.Cu")
		(net "KR_P0_OCP_RX_DP")
	)
	(segment
		(start 422.902634 -59.63158)
		(end 420.55288 -61.981334)
		(width 0.101346)
		(layer "In9.Cu")
		(net "KR_P0_OCP_RX_DP")
	)
	(segment
		(start 434.05552 -56.845454)
		(end 430.444148 -56.845454)
		(width 0.101346)
		(layer "In9.Cu")
		(net "KR_P0_OCP_RX_DP")
	)
	(segment
		(start 446.258442 -62.956694)
		(end 445.954404 -62.956694)
		(width 0.101346)
		(layer "In9.Cu")
		(net "KR_P0_OCP_RX_DP")
	)
	(segment
		(start 447.782442 -62.651386)
		(end 447.477134 -62.956694)
		(width 0.101346)
		(layer "In9.Cu")
		(net "KR_P0_OCP_RX_DP")
	)
	(segment
		(start 450.219826 -62.651386)
		(end 449.914518 -62.956694)
		(width 0.101346)
		(layer "In9.Cu")
		(net "KR_P0_OCP_RX_DP")
	)
	(segment
		(start 419.695122 -85.324696)
		(end 419.695122 -85.628734)
		(width 0.101346)
		(layer "In9.Cu")
		(net "KR_P0_OCP_RX_DP")
	)
	(segment
		(start 437.243474 -61.232796)
		(end 436.938166 -61.538104)
		(width 0.101346)
		(layer "In9.Cu")
		(net "KR_P0_OCP_RX_DP")
	)
	(segment
		(start 420.55288 -61.981334)
		(end 420.55288 -63.94323)
		(width 0.101346)
		(layer "In9.Cu")
		(net "KR_P0_OCP_RX_DP")
	)
	(segment
		(start 428.674022 -58.61558)
		(end 426.98035 -58.61558)
		(width 0.101346)
		(layer "In9.Cu")
		(net "KR_P0_OCP_RX_DP")
	)
	(segment
		(start 448.391788 -62.956694)
		(end 448.08648 -62.651386)
		(width 0.101346)
		(layer "In9.Cu")
		(net "KR_P0_OCP_RX_DP")
	)
	(segment
		(start 419.389814 -86.23808)
		(end 419.695122 -86.543388)
		(width 0.101346)
		(layer "In9.Cu")
		(net "KR_P0_OCP_RX_DP")
	)
	(segment
		(start 426.98035 -58.61558)
		(end 425.96435 -59.63158)
		(width 0.101346)
		(layer "In9.Cu")
		(net "KR_P0_OCP_RX_DP")
	)
	(segment
		(start 419.953694 -64.889888)
		(end 419.953694 -80.137)
		(width 0.101346)
		(layer "In9.Cu")
		(net "KR_P0_OCP_RX_DP")
	)
	(segment
		(start 446.867788 -62.651386)
		(end 446.56375 -62.651386)
		(width 0.101346)
		(layer "In9.Cu")
		(net "KR_P0_OCP_RX_DP")
	)
	(segment
		(start 449.305172 -62.651386)
		(end 449.001134 -62.651386)
		(width 0.101346)
		(layer "In9.Cu")
		(net "KR_P0_OCP_RX_DP")
	)
	(segment
		(start 449.61048 -62.956694)
		(end 449.305172 -62.651386)
		(width 0.101346)
		(layer "In9.Cu")
		(net "KR_P0_OCP_RX_DP")
	)
	(segment
		(start 418.738558 -91.632532)
		(end 419.123622 -92.017596)
		(width 0.101346)
		(layer "In9.Cu")
		(net "KR_P0_OCP_RX_DP")
	)
	(segment
		(start 449.001134 -62.651386)
		(end 448.695826 -62.956694)
		(width 0.101346)
		(layer "In9.Cu")
		(net "KR_P0_OCP_RX_DP")
	)
	(segment
		(start 419.389814 -87.456772)
		(end 419.695122 -87.76208)
		(width 0.101346)
		(layer "In9.Cu")
		(net "KR_P0_OCP_RX_DP")
	)
	(segment
		(start 419.695122 -88.066118)
		(end 419.389814 -88.371426)
		(width 0.101346)
		(layer "In9.Cu")
		(net "KR_P0_OCP_RX_DP")
	)
	(segment
		(start 455.944732 -63.201296)
		(end 455.944732 -62.852554)
		(width 0.101346)
		(layer "In9.Cu")
		(net "KR_P0_OCP_RX_DP")
	)
	(segment
		(start 445.954404 -62.956694)
		(end 445.649096 -62.651386)
		(width 0.101346)
		(layer "In9.Cu")
		(net "KR_P0_OCP_RX_DP")
	)
	(segment
		(start 445.649096 -62.651386)
		(end 440.034172 -62.651386)
		(width 0.101346)
		(layer "In9.Cu")
		(net "KR_P0_OCP_RX_DP")
	)
	(segment
		(start 419.695122 -85.628734)
		(end 419.389814 -85.934042)
		(width 0.101346)
		(layer "In9.Cu")
		(net "KR_P0_OCP_RX_DP")
	)
	(segment
		(start 435.606444 -61.232796)
		(end 434.581808 -60.20816)
		(width 0.101346)
		(layer "In9.Cu")
		(net "KR_P0_OCP_RX_DP")
	)
	(segment
		(start 448.08648 -62.651386)
		(end 447.782442 -62.651386)
		(width 0.101346)
		(layer "In9.Cu")
		(net "KR_P0_OCP_RX_DP")
	)
	(segment
		(start 455.743564 -62.651386)
		(end 450.219826 -62.651386)
		(width 0.101346)
		(layer "In9.Cu")
		(net "KR_P0_OCP_RX_DP")
	)
	(segment
		(start 436.634128 -61.538104)
		(end 436.32882 -61.232796)
		(width 0.101346)
		(layer "In9.Cu")
		(net "KR_P0_OCP_RX_DP")
	)
	(segment
		(start 420.553134 -64.290448)
		(end 419.953694 -64.889888)
		(width 0.101346)
		(layer "In9.Cu")
		(net "KR_P0_OCP_RX_DP")
	)
	(segment
		(start 455.944732 -62.852554)
		(end 455.743564 -62.651386)
		(width 0.101346)
		(layer "In9.Cu")
		(net "KR_P0_OCP_RX_DP")
	)
	(segment
		(start 419.389814 -85.019388)
		(end 419.695122 -85.324696)
		(width 0.101346)
		(layer "In9.Cu")
		(net "KR_P0_OCP_RX_DP")
	)
	(segment
		(start 419.389814 -85.934042)
		(end 419.389814 -86.23808)
		(width 0.101346)
		(layer "In9.Cu")
		(net "KR_P0_OCP_RX_DP")
	)
	(segment
		(start 420.55288 -63.94323)
		(end 420.553134 -63.943484)
		(width 0.101346)
		(layer "In9.Cu")
		(net "KR_P0_OCP_RX_DP")
	)
	(segment
		(start 434.581808 -60.20816)
		(end 434.581808 -57.371742)
		(width 0.101346)
		(layer "In9.Cu")
		(net "KR_P0_OCP_RX_DP")
	)
	(segment
		(start 447.173096 -62.956694)
		(end 446.867788 -62.651386)
		(width 0.101346)
		(layer "In9.Cu")
		(net "KR_P0_OCP_RX_DP")
	)
	(segment
		(start 434.581808 -57.371742)
		(end 434.05552 -56.845454)
		(width 0.101346)
		(layer "In9.Cu")
		(net "KR_P0_OCP_RX_DP")
	)
	(segment
		(start 447.477134 -62.956694)
		(end 447.173096 -62.956694)
		(width 0.101346)
		(layer "In9.Cu")
		(net "KR_P0_OCP_RX_DP")
	)
	(segment
		(start 419.695122 -86.543388)
		(end 419.695122 -86.847426)
		(width 0.101346)
		(layer "In9.Cu")
		(net "KR_P0_OCP_RX_DP")
	)
	(segment
		(start 446.56375 -62.651386)
		(end 446.258442 -62.956694)
		(width 0.101346)
		(layer "In9.Cu")
		(net "KR_P0_OCP_RX_DP")
	)
	(segment
		(start 455.519536 -63.626492)
		(end 455.944732 -63.201296)
		(width 0.101346)
		(layer "In9.Cu")
		(net "KR_P0_OCP_RX_DP")
	)
	(segment
		(start 418.738558 -89.40927)
		(end 418.738558 -91.632532)
		(width 0.101346)
		(layer "In9.Cu")
		(net "KR_P0_OCP_RX_DP")
	)
	(segment
		(start 436.32882 -61.232796)
		(end 435.606444 -61.232796)
		(width 0.101346)
		(layer "In9.Cu")
		(net "KR_P0_OCP_RX_DP")
	)
	(segment
		(start 419.553898 -92.017596)
		(end 419.655244 -91.91625)
		(width 0.101346)
		(layer "In9.Cu")
		(net "KR_P0_OCP_RX_DP")
	)
	(segment
		(start 420.553134 -63.943484)
		(end 420.553134 -64.290448)
		(width 0.101346)
		(layer "In9.Cu")
		(net "KR_P0_OCP_RX_DP")
	)
	(segment
		(start 419.389814 -80.70088)
		(end 419.389814 -85.019388)
		(width 0.101346)
		(layer "In9.Cu")
		(net "KR_P0_OCP_RX_DP")
	)
	(segment
		(start 419.389814 -87.152734)
		(end 419.389814 -87.456772)
		(width 0.101346)
		(layer "In9.Cu")
		(net "KR_P0_OCP_RX_DP")
	)
	(segment
		(start 419.389814 -88.758014)
		(end 418.738558 -89.40927)
		(width 0.101346)
		(layer "In9.Cu")
		(net "KR_P0_OCP_RX_DP")
	)
	(segment
		(start 449.914518 -62.956694)
		(end 449.61048 -62.956694)
		(width 0.101346)
		(layer "In9.Cu")
		(net "KR_P0_OCP_RX_DP")
	)
	(segment
		(start 419.695122 -87.76208)
		(end 419.695122 -88.066118)
		(width 0.101346)
		(layer "In9.Cu")
		(net "KR_P0_OCP_RX_DP")
	)
	(segment
		(start 419.953694 -80.137)
		(end 419.389814 -80.70088)
		(width 0.101346)
		(layer "In9.Cu")
		(net "KR_P0_OCP_RX_DP")
	)
	(segment
		(start 430.444148 -56.845454)
		(end 428.674022 -58.61558)
		(width 0.101346)
		(layer "In9.Cu")
		(net "KR_P0_OCP_RX_DP")
	)
	(segment
		(start 419.123622 -92.017596)
		(end 419.553898 -92.017596)
		(width 0.101346)
		(layer "In9.Cu")
		(net "KR_P0_OCP_RX_DP")
	)
	(segment
		(start 419.389814 -88.371426)
		(end 419.389814 -88.758014)
		(width 0.101346)
		(layer "In9.Cu")
		(net "KR_P0_OCP_RX_DP")
	)
	(segment
		(start 456.550014 -63.029084)
		(end 456.550014 -62.00267)
		(width 0.10033)
		(layer "F.Cu")
		(net "KR_P0_OCP_RX_DN")
	)
	(segment
		(start 456.382374 -63.524638)
		(end 456.382374 -63.196724)
		(width 0.1016)
		(layer "F.Cu")
		(net "KR_P0_OCP_RX_DN")
	)
	(segment
		(start 419.578282 -92.454984)
		(end 419.372796 -92.454984)
		(width 0.101854)
		(layer "F.Cu")
		(net "KR_P0_OCP_RX_DN")
	)
	(segment
		(start 456.484228 -63.626492)
		(end 456.382374 -63.524638)
		(width 0.1016)
		(layer "F.Cu")
		(net "KR_P0_OCP_RX_DN")
	)
	(segment
		(start 419.372796 -92.454984)
		(end 419.15588 -92.6719)
		(width 0.101854)
		(layer "F.Cu")
		(net "KR_P0_OCP_RX_DN")
	)
	(segment
		(start 456.382374 -63.196724)
		(end 456.550014 -63.029084)
		(width 0.1016)
		(layer "F.Cu")
		(net "KR_P0_OCP_RX_DN")
	)
	(segment
		(start 456.789536 -63.626492)
		(end 456.484228 -63.626492)
		(width 0.1016)
		(layer "F.Cu")
		(net "KR_P0_OCP_RX_DN")
	)
	(segment
		(start 419.655244 -92.531946)
		(end 419.578282 -92.454984)
		(width 0.101854)
		(layer "F.Cu")
		(net "KR_P0_OCP_RX_DN")
	)
	(segment
		(start 419.15588 -92.6719)
		(end 418.7952 -92.6719)
		(width 0.101854)
		(layer "F.Cu")
		(net "KR_P0_OCP_RX_DN")
	)
	(segment
		(start 419.655244 -92.8624)
		(end 419.655244 -92.531946)
		(width 0.101854)
		(layer "F.Cu")
		(net "KR_P0_OCP_RX_DN")
	)
	(via
		(at 456.789536 -63.626492)
		(size 0.508)
		(drill 0.254)
		(layers "F.Cu" "B.Cu")
		(net "KR_P0_OCP_RX_DN")
	)
	(via
		(at 419.655244 -92.8624)
		(size 0.508)
		(drill 0.254)
		(layers "F.Cu" "B.Cu")
		(net "KR_P0_OCP_RX_DN")
	)
	(segment
		(start 419.53434 -64.716152)
		(end 419.53434 -79.963264)
		(width 0.101346)
		(layer "In9.Cu")
		(net "KR_P0_OCP_RX_DN")
	)
	(segment
		(start 418.319204 -91.806268)
		(end 418.949886 -92.43695)
		(width 0.101346)
		(layer "In9.Cu")
		(net "KR_P0_OCP_RX_DN")
	)
	(segment
		(start 435.78018 -60.813442)
		(end 435.001162 -60.034424)
		(width 0.101346)
		(layer "In9.Cu")
		(net "KR_P0_OCP_RX_DN")
	)
	(segment
		(start 418.97046 -88.584278)
		(end 418.319204 -89.235534)
		(width 0.101346)
		(layer "In9.Cu")
		(net "KR_P0_OCP_RX_DN")
	)
	(segment
		(start 435.001162 -57.198006)
		(end 434.229256 -56.4261)
		(width 0.101346)
		(layer "In9.Cu")
		(net "KR_P0_OCP_RX_DN")
	)
	(segment
		(start 430.270412 -56.4261)
		(end 428.500286 -58.196226)
		(width 0.101346)
		(layer "In9.Cu")
		(net "KR_P0_OCP_RX_DN")
	)
	(segment
		(start 418.949886 -92.43695)
		(end 419.541198 -92.43695)
		(width 0.101346)
		(layer "In9.Cu")
		(net "KR_P0_OCP_RX_DN")
	)
	(segment
		(start 419.541198 -92.43695)
		(end 419.655244 -92.550996)
		(width 0.101346)
		(layer "In9.Cu")
		(net "KR_P0_OCP_RX_DN")
	)
	(segment
		(start 426.806614 -58.196226)
		(end 425.790614 -59.212226)
		(width 0.101346)
		(layer "In9.Cu")
		(net "KR_P0_OCP_RX_DN")
	)
	(segment
		(start 456.364086 -63.201042)
		(end 456.364086 -62.678818)
		(width 0.101346)
		(layer "In9.Cu")
		(net "KR_P0_OCP_RX_DN")
	)
	(segment
		(start 420.133526 -64.116966)
		(end 419.53434 -64.716152)
		(width 0.101346)
		(layer "In9.Cu")
		(net "KR_P0_OCP_RX_DN")
	)
	(segment
		(start 440.207908 -62.232032)
		(end 438.789318 -60.813442)
		(width 0.101346)
		(layer "In9.Cu")
		(net "KR_P0_OCP_RX_DN")
	)
	(segment
		(start 422.728898 -59.212226)
		(end 420.133526 -61.807598)
		(width 0.101346)
		(layer "In9.Cu")
		(net "KR_P0_OCP_RX_DN")
	)
	(segment
		(start 435.001162 -60.034424)
		(end 435.001162 -57.198006)
		(width 0.101346)
		(layer "In9.Cu")
		(net "KR_P0_OCP_RX_DN")
	)
	(segment
		(start 455.9173 -62.232032)
		(end 440.207908 -62.232032)
		(width 0.101346)
		(layer "In9.Cu")
		(net "KR_P0_OCP_RX_DN")
	)
	(segment
		(start 425.790614 -59.212226)
		(end 422.728898 -59.212226)
		(width 0.101346)
		(layer "In9.Cu")
		(net "KR_P0_OCP_RX_DN")
	)
	(segment
		(start 434.229256 -56.4261)
		(end 430.270412 -56.4261)
		(width 0.101346)
		(layer "In9.Cu")
		(net "KR_P0_OCP_RX_DN")
	)
	(segment
		(start 456.364086 -62.678818)
		(end 455.9173 -62.232032)
		(width 0.101346)
		(layer "In9.Cu")
		(net "KR_P0_OCP_RX_DN")
	)
	(segment
		(start 419.655244 -92.550996)
		(end 419.655244 -92.8624)
		(width 0.101346)
		(layer "In9.Cu")
		(net "KR_P0_OCP_RX_DN")
	)
	(segment
		(start 438.789318 -60.813442)
		(end 435.78018 -60.813442)
		(width 0.101346)
		(layer "In9.Cu")
		(net "KR_P0_OCP_RX_DN")
	)
	(segment
		(start 456.789536 -63.626492)
		(end 456.364086 -63.201042)
		(width 0.101346)
		(layer "In9.Cu")
		(net "KR_P0_OCP_RX_DN")
	)
	(segment
		(start 428.500286 -58.196226)
		(end 426.806614 -58.196226)
		(width 0.101346)
		(layer "In9.Cu")
		(net "KR_P0_OCP_RX_DN")
	)
	(segment
		(start 419.53434 -79.963264)
		(end 418.97046 -80.527144)
		(width 0.101346)
		(layer "In9.Cu")
		(net "KR_P0_OCP_RX_DN")
	)
	(segment
		(start 420.133526 -61.807598)
		(end 420.133526 -64.116966)
		(width 0.101346)
		(layer "In9.Cu")
		(net "KR_P0_OCP_RX_DN")
	)
	(segment
		(start 418.319204 -89.235534)
		(end 418.319204 -91.806268)
		(width 0.101346)
		(layer "In9.Cu")
		(net "KR_P0_OCP_RX_DN")
	)
	(segment
		(start 418.97046 -80.527144)
		(end 418.97046 -88.584278)
		(width 0.101346)
		(layer "In9.Cu")
		(net "KR_P0_OCP_RX_DN")
	)
	(segment
		(start 374.81764 -156.566362)
		(end 374.124728 -157.259274)
		(width 0.127)
		(layer "F.Cu")
		(net "ISENSE_PVNN_PCH_PH1_IMON")
	)
	(segment
		(start 397.879316 -158.322264)
		(end 397.89608 -158.339028)
		(width 0.127)
		(layer "F.Cu")
		(net "ISENSE_PVNN_PCH_PH1_IMON")
	)
	(segment
		(start 397.879316 -157.664658)
		(end 397.879316 -158.322264)
		(width 0.127)
		(layer "F.Cu")
		(net "ISENSE_PVNN_PCH_PH1_IMON")
	)
	(segment
		(start 374.81764 -156.24302)
		(end 374.81764 -156.566362)
		(width 0.127)
		(layer "F.Cu")
		(net "ISENSE_PVNN_PCH_PH1_IMON")
	)
	(segment
		(start 397.182848 -156.2481)
		(end 397.182848 -156.711904)
		(width 0.127)
		(layer "F.Cu")
		(net "ISENSE_PVNN_PCH_PH1_IMON")
	)
	(segment
		(start 397.879316 -157.408372)
		(end 397.879316 -157.664658)
		(width 0.127)
		(layer "F.Cu")
		(net "ISENSE_PVNN_PCH_PH1_IMON")
	)
	(segment
		(start 397.182848 -156.711904)
		(end 397.879316 -157.408372)
		(width 0.127)
		(layer "F.Cu")
		(net "ISENSE_PVNN_PCH_PH1_IMON")
	)
	(via
		(at 374.124728 -157.259274)
		(size 0.508)
		(drill 0.254)
		(layers "F.Cu" "B.Cu")
		(net "ISENSE_PVNN_PCH_PH1_IMON")
	)
	(via
		(at 397.89608 -158.339028)
		(size 0.508)
		(drill 0.254)
		(layers "F.Cu" "B.Cu")
		(net "ISENSE_PVNN_PCH_PH1_IMON")
	)
	(segment
		(start 397.89608 -158.339028)
		(end 397.89608 -157.306772)
		(width 0.127)
		(layer "B.Cu")
		(net "ISENSE_PVNN_PCH_PH1_IMON")
	)
	(segment
		(start 397.89608 -157.306772)
		(end 397.702278 -157.11297)
		(width 0.127)
		(layer "B.Cu")
		(net "ISENSE_PVNN_PCH_PH1_IMON")
	)
	(segment
		(start 378.495814 -157.64129)
		(end 379.976126 -157.64129)
		(width 0.127)
		(layer "In2.Cu")
		(net "ISENSE_PVNN_PCH_PH1_IMON")
	)
	(segment
		(start 395.02207 -155.34894)
		(end 395.77899 -156.10586)
		(width 0.127)
		(layer "In2.Cu")
		(net "ISENSE_PVNN_PCH_PH1_IMON")
	)
	(segment
		(start 390.53008 -154.581606)
		(end 390.53008 -154.89809)
		(width 0.127)
		(layer "In2.Cu")
		(net "ISENSE_PVNN_PCH_PH1_IMON")
	)
	(segment
		(start 389.898128 -153.949654)
		(end 390.53008 -154.581606)
		(width 0.127)
		(layer "In2.Cu")
		(net "ISENSE_PVNN_PCH_PH1_IMON")
	)
	(segment
		(start 381.157988 -156.459428)
		(end 382.144778 -156.459428)
		(width 0.127)
		(layer "In2.Cu")
		(net "ISENSE_PVNN_PCH_PH1_IMON")
	)
	(segment
		(start 389.031988 -153.949654)
		(end 389.898128 -153.949654)
		(width 0.127)
		(layer "In2.Cu")
		(net "ISENSE_PVNN_PCH_PH1_IMON")
	)
	(segment
		(start 377.325382 -156.470858)
		(end 378.495814 -157.64129)
		(width 0.127)
		(layer "In2.Cu")
		(net "ISENSE_PVNN_PCH_PH1_IMON")
	)
	(segment
		(start 396.41907 -156.10586)
		(end 398.080992 -157.767782)
		(width 0.127)
		(layer "In2.Cu")
		(net "ISENSE_PVNN_PCH_PH1_IMON")
	)
	(segment
		(start 382.144778 -156.459428)
		(end 383.95656 -154.647646)
		(width 0.127)
		(layer "In2.Cu")
		(net "ISENSE_PVNN_PCH_PH1_IMON")
	)
	(segment
		(start 395.77899 -156.10586)
		(end 396.41907 -156.10586)
		(width 0.127)
		(layer "In2.Cu")
		(net "ISENSE_PVNN_PCH_PH1_IMON")
	)
	(segment
		(start 390.98093 -155.34894)
		(end 395.02207 -155.34894)
		(width 0.127)
		(layer "In2.Cu")
		(net "ISENSE_PVNN_PCH_PH1_IMON")
	)
	(segment
		(start 374.656096 -156.470858)
		(end 377.325382 -156.470858)
		(width 0.127)
		(layer "In2.Cu")
		(net "ISENSE_PVNN_PCH_PH1_IMON")
	)
	(segment
		(start 383.95656 -154.647646)
		(end 388.333996 -154.647646)
		(width 0.127)
		(layer "In2.Cu")
		(net "ISENSE_PVNN_PCH_PH1_IMON")
	)
	(segment
		(start 388.333996 -154.647646)
		(end 389.031988 -153.949654)
		(width 0.127)
		(layer "In2.Cu")
		(net "ISENSE_PVNN_PCH_PH1_IMON")
	)
	(segment
		(start 398.080992 -157.767782)
		(end 398.080992 -158.154116)
		(width 0.127)
		(layer "In2.Cu")
		(net "ISENSE_PVNN_PCH_PH1_IMON")
	)
	(segment
		(start 398.080992 -158.154116)
		(end 397.89608 -158.339028)
		(width 0.127)
		(layer "In2.Cu")
		(net "ISENSE_PVNN_PCH_PH1_IMON")
	)
	(segment
		(start 379.976126 -157.64129)
		(end 381.157988 -156.459428)
		(width 0.127)
		(layer "In2.Cu")
		(net "ISENSE_PVNN_PCH_PH1_IMON")
	)
	(segment
		(start 374.124728 -157.259274)
		(end 374.124728 -157.002226)
		(width 0.127)
		(layer "In2.Cu")
		(net "ISENSE_PVNN_PCH_PH1_IMON")
	)
	(segment
		(start 390.53008 -154.89809)
		(end 390.98093 -155.34894)
		(width 0.127)
		(layer "In2.Cu")
		(net "ISENSE_PVNN_PCH_PH1_IMON")
	)
	(segment
		(start 374.124728 -157.002226)
		(end 374.656096 -156.470858)
		(width 0.127)
		(layer "In2.Cu")
		(net "ISENSE_PVNN_PCH_PH1_IMON")
	)
	(segment
		(start -1.713992 -145.096738)
		(end -2.338324 -145.096738)
		(width 0.127)
		(layer "F.Cu")
		(net "ISENSE_PVDDQ_KLM_PH2_IMON")
	)
	(segment
		(start 1.577594 -123.20905)
		(end 1.577594 -122.55627)
		(width 0.127)
		(layer "F.Cu")
		(net "ISENSE_PVDDQ_KLM_PH2_IMON")
	)
	(segment
		(start 1.457452 -125.5141)
		(end 1.457452 -124.531882)
		(width 0.127)
		(layer "F.Cu")
		(net "ISENSE_PVDDQ_KLM_PH2_IMON")
	)
	(segment
		(start 1.457452 -124.531882)
		(end 1.613662 -124.375672)
		(width 0.127)
		(layer "F.Cu")
		(net "ISENSE_PVDDQ_KLM_PH2_IMON")
	)
	(segment
		(start 1.577594 -124.0409)
		(end 1.577594 -123.20905)
		(width 0.127)
		(layer "F.Cu")
		(net "ISENSE_PVDDQ_KLM_PH2_IMON")
	)
	(segment
		(start -1.032256 -145.778474)
		(end -1.713992 -145.096738)
		(width 0.127)
		(layer "F.Cu")
		(net "ISENSE_PVDDQ_KLM_PH2_IMON")
	)
	(segment
		(start -0.497586 -145.778474)
		(end -1.032256 -145.778474)
		(width 0.127)
		(layer "F.Cu")
		(net "ISENSE_PVDDQ_KLM_PH2_IMON")
	)
	(segment
		(start -2.338324 -145.096738)
		(end -2.357882 -145.116296)
		(width 0.127)
		(layer "F.Cu")
		(net "ISENSE_PVDDQ_KLM_PH2_IMON")
	)
	(segment
		(start 1.577594 -122.55627)
		(end 1.445006 -122.423682)
		(width 0.127)
		(layer "F.Cu")
		(net "ISENSE_PVDDQ_KLM_PH2_IMON")
	)
	(segment
		(start 1.613662 -124.076968)
		(end 1.577594 -124.0409)
		(width 0.127)
		(layer "F.Cu")
		(net "ISENSE_PVDDQ_KLM_PH2_IMON")
	)
	(segment
		(start 1.613662 -124.375672)
		(end 1.613662 -124.076968)
		(width 0.127)
		(layer "F.Cu")
		(net "ISENSE_PVDDQ_KLM_PH2_IMON")
	)
	(via
		(at 1.445006 -122.423682)
		(size 0.508)
		(drill 0.254)
		(layers "F.Cu" "B.Cu")
		(net "ISENSE_PVDDQ_KLM_PH2_IMON")
	)
	(via
		(at -2.357882 -145.116296)
		(size 0.508)
		(drill 0.254)
		(layers "F.Cu" "B.Cu")
		(net "ISENSE_PVDDQ_KLM_PH2_IMON")
	)
	(segment
		(start -3.023362 -133.937502)
		(end -2.628138 -134.332726)
		(width 0.127)
		(layer "In9.Cu")
		(net "ISENSE_PVDDQ_KLM_PH2_IMON")
	)
	(segment
		(start -2.91084 -146.11096)
		(end -2.1209 -146.11096)
		(width 0.127)
		(layer "In9.Cu")
		(net "ISENSE_PVDDQ_KLM_PH2_IMON")
	)
	(segment
		(start -1.586484 -134.7597)
		(end -1.586484 -136.35101)
		(width 0.127)
		(layer "In9.Cu")
		(net "ISENSE_PVDDQ_KLM_PH2_IMON")
	)
	(segment
		(start 1.178306 -123.413774)
		(end -2.70764 -127.29972)
		(width 0.127)
		(layer "In9.Cu")
		(net "ISENSE_PVDDQ_KLM_PH2_IMON")
	)
	(segment
		(start -1.862074 -136.6266)
		(end -3.17881 -136.6266)
		(width 0.127)
		(layer "In9.Cu")
		(net "ISENSE_PVDDQ_KLM_PH2_IMON")
	)
	(segment
		(start -2.013458 -134.332726)
		(end -1.586484 -134.7597)
		(width 0.127)
		(layer "In9.Cu")
		(net "ISENSE_PVDDQ_KLM_PH2_IMON")
	)
	(segment
		(start -2.628138 -134.332726)
		(end -2.013458 -134.332726)
		(width 0.127)
		(layer "In9.Cu")
		(net "ISENSE_PVDDQ_KLM_PH2_IMON")
	)
	(segment
		(start -2.70764 -127.29972)
		(end -2.70764 -132.22732)
		(width 0.127)
		(layer "In9.Cu")
		(net "ISENSE_PVDDQ_KLM_PH2_IMON")
	)
	(segment
		(start -2.70764 -132.22732)
		(end -3.023362 -132.543042)
		(width 0.127)
		(layer "In9.Cu")
		(net "ISENSE_PVDDQ_KLM_PH2_IMON")
	)
	(segment
		(start -4.21259 -136.525)
		(end -5.08 -137.39241)
		(width 0.127)
		(layer "In9.Cu")
		(net "ISENSE_PVDDQ_KLM_PH2_IMON")
	)
	(segment
		(start -3.28041 -136.525)
		(end -4.21259 -136.525)
		(width 0.127)
		(layer "In9.Cu")
		(net "ISENSE_PVDDQ_KLM_PH2_IMON")
	)
	(segment
		(start -5.08 -137.39241)
		(end -5.08 -143.9418)
		(width 0.127)
		(layer "In9.Cu")
		(net "ISENSE_PVDDQ_KLM_PH2_IMON")
	)
	(segment
		(start -1.82118 -145.116296)
		(end -2.357882 -145.116296)
		(width 0.127)
		(layer "In9.Cu")
		(net "ISENSE_PVDDQ_KLM_PH2_IMON")
	)
	(segment
		(start -3.023362 -132.543042)
		(end -3.023362 -133.937502)
		(width 0.127)
		(layer "In9.Cu")
		(net "ISENSE_PVDDQ_KLM_PH2_IMON")
	)
	(segment
		(start -3.17881 -136.6266)
		(end -3.28041 -136.525)
		(width 0.127)
		(layer "In9.Cu")
		(net "ISENSE_PVDDQ_KLM_PH2_IMON")
	)
	(segment
		(start -1.69418 -145.243296)
		(end -1.82118 -145.116296)
		(width 0.127)
		(layer "In9.Cu")
		(net "ISENSE_PVDDQ_KLM_PH2_IMON")
	)
	(segment
		(start -1.69418 -145.68424)
		(end -1.69418 -145.243296)
		(width 0.127)
		(layer "In9.Cu")
		(net "ISENSE_PVDDQ_KLM_PH2_IMON")
	)
	(segment
		(start 1.178306 -122.690382)
		(end 1.178306 -123.413774)
		(width 0.127)
		(layer "In9.Cu")
		(net "ISENSE_PVDDQ_KLM_PH2_IMON")
	)
	(segment
		(start 1.445006 -122.423682)
		(end 1.178306 -122.690382)
		(width 0.127)
		(layer "In9.Cu")
		(net "ISENSE_PVDDQ_KLM_PH2_IMON")
	)
	(segment
		(start -5.08 -143.9418)
		(end -2.91084 -146.11096)
		(width 0.127)
		(layer "In9.Cu")
		(net "ISENSE_PVDDQ_KLM_PH2_IMON")
	)
	(segment
		(start -1.586484 -136.35101)
		(end -1.862074 -136.6266)
		(width 0.127)
		(layer "In9.Cu")
		(net "ISENSE_PVDDQ_KLM_PH2_IMON")
	)
	(segment
		(start -2.1209 -146.11096)
		(end -1.69418 -145.68424)
		(width 0.127)
		(layer "In9.Cu")
		(net "ISENSE_PVDDQ_KLM_PH2_IMON")
	)
	(segment
		(start -0.497586 -136.634474)
		(end -1.032256 -136.634474)
		(width 0.127)
		(layer "F.Cu")
		(net "ISENSE_PVDDQ_KLM_PH1_IMON")
	)
	(segment
		(start 0.657352 -125.015752)
		(end -0.144526 -124.213874)
		(width 0.127)
		(layer "F.Cu")
		(net "ISENSE_PVDDQ_KLM_PH1_IMON")
	)
	(segment
		(start -0.341884 -122.617484)
		(end -0.2286 -122.5042)
		(width 0.127)
		(layer "F.Cu")
		(net "ISENSE_PVDDQ_KLM_PH1_IMON")
	)
	(segment
		(start 0.657352 -125.5141)
		(end 0.657352 -125.015752)
		(width 0.127)
		(layer "F.Cu")
		(net "ISENSE_PVDDQ_KLM_PH1_IMON")
	)
	(segment
		(start -0.144526 -124.213874)
		(end -0.144526 -124.073666)
		(width 0.127)
		(layer "F.Cu")
		(net "ISENSE_PVDDQ_KLM_PH1_IMON")
	)
	(segment
		(start -1.936242 -135.730488)
		(end -2.149348 -135.730488)
		(width 0.127)
		(layer "F.Cu")
		(net "ISENSE_PVDDQ_KLM_PH1_IMON")
	)
	(segment
		(start -0.144526 -124.073666)
		(end -0.144526 -123.407932)
		(width 0.127)
		(layer "F.Cu")
		(net "ISENSE_PVDDQ_KLM_PH1_IMON")
	)
	(segment
		(start -0.341884 -123.210574)
		(end -0.341884 -122.617484)
		(width 0.127)
		(layer "F.Cu")
		(net "ISENSE_PVDDQ_KLM_PH1_IMON")
	)
	(segment
		(start -1.032256 -136.634474)
		(end -1.936242 -135.730488)
		(width 0.127)
		(layer "F.Cu")
		(net "ISENSE_PVDDQ_KLM_PH1_IMON")
	)
	(segment
		(start -0.144526 -123.407932)
		(end -0.341884 -123.210574)
		(width 0.127)
		(layer "F.Cu")
		(net "ISENSE_PVDDQ_KLM_PH1_IMON")
	)
	(segment
		(start -2.149348 -135.730488)
		(end -2.359914 -135.941054)
		(width 0.127)
		(layer "F.Cu")
		(net "ISENSE_PVDDQ_KLM_PH1_IMON")
	)
	(via
		(at -0.2286 -122.5042)
		(size 0.508)
		(drill 0.254)
		(layers "F.Cu" "B.Cu")
		(net "ISENSE_PVDDQ_KLM_PH1_IMON")
	)
	(via
		(at -2.359914 -135.941054)
		(size 0.508)
		(drill 0.254)
		(layers "F.Cu" "B.Cu")
		(net "ISENSE_PVDDQ_KLM_PH1_IMON")
	)
	(segment
		(start -3.4036 -135.200644)
		(end -3.4036 -135.30961)
		(width 0.127)
		(layer "In9.Cu")
		(net "ISENSE_PVDDQ_KLM_PH1_IMON")
	)
	(segment
		(start -3.07721 -135.636)
		(end -2.664968 -135.636)
		(width 0.127)
		(layer "In9.Cu")
		(net "ISENSE_PVDDQ_KLM_PH1_IMON")
	)
	(segment
		(start -5.28574 -133.565392)
		(end -4.582922 -134.26821)
		(width 0.127)
		(layer "In9.Cu")
		(net "ISENSE_PVDDQ_KLM_PH1_IMON")
	)
	(segment
		(start -0.2286 -122.5042)
		(end -0.606552 -122.126248)
		(width 0.127)
		(layer "In9.Cu")
		(net "ISENSE_PVDDQ_KLM_PH1_IMON")
	)
	(segment
		(start -2.577846 -122.682)
		(end -4.00558 -122.682)
		(width 0.127)
		(layer "In9.Cu")
		(net "ISENSE_PVDDQ_KLM_PH1_IMON")
	)
	(segment
		(start -4.582922 -134.26821)
		(end -4.336034 -134.26821)
		(width 0.127)
		(layer "In9.Cu")
		(net "ISENSE_PVDDQ_KLM_PH1_IMON")
	)
	(segment
		(start -1.544066 -121.64822)
		(end -2.577846 -122.682)
		(width 0.127)
		(layer "In9.Cu")
		(net "ISENSE_PVDDQ_KLM_PH1_IMON")
	)
	(segment
		(start -2.664968 -135.636)
		(end -2.359914 -135.941054)
		(width 0.127)
		(layer "In9.Cu")
		(net "ISENSE_PVDDQ_KLM_PH1_IMON")
	)
	(segment
		(start -5.28574 -123.96216)
		(end -5.28574 -133.565392)
		(width 0.127)
		(layer "In9.Cu")
		(net "ISENSE_PVDDQ_KLM_PH1_IMON")
	)
	(segment
		(start -4.336034 -134.26821)
		(end -3.4036 -135.200644)
		(width 0.127)
		(layer "In9.Cu")
		(net "ISENSE_PVDDQ_KLM_PH1_IMON")
	)
	(segment
		(start -3.4036 -135.30961)
		(end -3.07721 -135.636)
		(width 0.127)
		(layer "In9.Cu")
		(net "ISENSE_PVDDQ_KLM_PH1_IMON")
	)
	(segment
		(start -4.00558 -122.682)
		(end -5.28574 -123.96216)
		(width 0.127)
		(layer "In9.Cu")
		(net "ISENSE_PVDDQ_KLM_PH1_IMON")
	)
	(segment
		(start -0.606552 -122.012202)
		(end -0.970534 -121.64822)
		(width 0.127)
		(layer "In9.Cu")
		(net "ISENSE_PVDDQ_KLM_PH1_IMON")
	)
	(segment
		(start -0.970534 -121.64822)
		(end -1.544066 -121.64822)
		(width 0.127)
		(layer "In9.Cu")
		(net "ISENSE_PVDDQ_KLM_PH1_IMON")
	)
	(segment
		(start -0.606552 -122.126248)
		(end -0.606552 -122.012202)
		(width 0.127)
		(layer "In9.Cu")
		(net "ISENSE_PVDDQ_KLM_PH1_IMON")
	)
	(segment
		(start 6.97484 -0.352298)
		(end 7.5819 -0.352298)
		(width 0.127)
		(layer "F.Cu")
		(net "ISENSE_PVDDQ_GHJ_PH2_IMON")
	)
	(segment
		(start 6.491732 2.780284)
		(end 6.353556 2.91846)
		(width 0.127)
		(layer "F.Cu")
		(net "ISENSE_PVDDQ_GHJ_PH2_IMON")
	)
	(segment
		(start 5.714746 4.922774)
		(end 5.519928 4.727956)
		(width 0.127)
		(layer "F.Cu")
		(net "ISENSE_PVDDQ_GHJ_PH2_IMON")
	)
	(segment
		(start 6.491732 1.614678)
		(end 6.243828 1.366774)
		(width 0.127)
		(layer "F.Cu")
		(net "ISENSE_PVDDQ_GHJ_PH2_IMON")
	)
	(segment
		(start 5.519928 4.727956)
		(end 5.519928 4.070096)
		(width 0.127)
		(layer "F.Cu")
		(net "ISENSE_PVDDQ_GHJ_PH2_IMON")
	)
	(segment
		(start 0.473202 -15.094204)
		(end 0.512064 -15.133066)
		(width 0.127)
		(layer "F.Cu")
		(net "ISENSE_PVDDQ_GHJ_PH2_IMON")
	)
	(segment
		(start 5.519928 4.070096)
		(end 6.0071 3.582924)
		(width 0.127)
		(layer "F.Cu")
		(net "ISENSE_PVDDQ_GHJ_PH2_IMON")
	)
	(segment
		(start 6.0071 3.582924)
		(end 6.0071 3.264916)
		(width 0.127)
		(layer "F.Cu")
		(net "ISENSE_PVDDQ_GHJ_PH2_IMON")
	)
	(segment
		(start 6.491732 2.141474)
		(end 6.491732 2.780284)
		(width 0.127)
		(layer "F.Cu")
		(net "ISENSE_PVDDQ_GHJ_PH2_IMON")
	)
	(segment
		(start 6.243828 0.378714)
		(end 6.97484 -0.352298)
		(width 0.127)
		(layer "F.Cu")
		(net "ISENSE_PVDDQ_GHJ_PH2_IMON")
	)
	(segment
		(start 6.491732 2.141474)
		(end 6.491732 1.614678)
		(width 0.127)
		(layer "F.Cu")
		(net "ISENSE_PVDDQ_GHJ_PH2_IMON")
	)
	(segment
		(start 0.512064 -15.133066)
		(end 0.985266 -15.133066)
		(width 0.127)
		(layer "F.Cu")
		(net "ISENSE_PVDDQ_GHJ_PH2_IMON")
	)
	(segment
		(start 6.0071 3.264916)
		(end 6.353556 2.91846)
		(width 0.127)
		(layer "F.Cu")
		(net "ISENSE_PVDDQ_GHJ_PH2_IMON")
	)
	(segment
		(start 0.985266 -15.133066)
		(end 1.763268 -15.911068)
		(width 0.127)
		(layer "F.Cu")
		(net "ISENSE_PVDDQ_GHJ_PH2_IMON")
	)
	(segment
		(start 6.243828 1.366774)
		(end 6.243828 0.775462)
		(width 0.127)
		(layer "F.Cu")
		(net "ISENSE_PVDDQ_GHJ_PH2_IMON")
	)
	(segment
		(start 6.243828 0.775462)
		(end 6.243828 0.378714)
		(width 0.127)
		(layer "F.Cu")
		(net "ISENSE_PVDDQ_GHJ_PH2_IMON")
	)
	(segment
		(start 1.763268 -15.911068)
		(end 2.150364 -15.911068)
		(width 0.127)
		(layer "F.Cu")
		(net "ISENSE_PVDDQ_GHJ_PH2_IMON")
	)
	(via
		(at 0.473202 -15.094204)
		(size 0.508)
		(drill 0.254)
		(layers "F.Cu" "B.Cu")
		(net "ISENSE_PVDDQ_GHJ_PH2_IMON")
	)
	(via
		(at 5.714746 4.922774)
		(size 0.508)
		(drill 0.254)
		(layers "F.Cu" "B.Cu")
		(net "ISENSE_PVDDQ_GHJ_PH2_IMON")
	)
	(via
		(at 6.243828 0.775462)
		(size 0.508)
		(drill 0.254)
		(layers "F.Cu" "B.Cu")
		(net "ISENSE_PVDDQ_GHJ_PH2_IMON")
	)
	(segment
		(start -4.3688 1.867916)
		(end -1.011174 5.225542)
		(width 0.127)
		(layer "In2.Cu")
		(net "ISENSE_PVDDQ_GHJ_PH2_IMON")
	)
	(segment
		(start -3.341878 -14.05382)
		(end -4.3688 -13.026898)
		(width 0.127)
		(layer "In2.Cu")
		(net "ISENSE_PVDDQ_GHJ_PH2_IMON")
	)
	(segment
		(start 0.346202 -14.905736)
		(end -0.179832 -14.905736)
		(width 0.127)
		(layer "In2.Cu")
		(net "ISENSE_PVDDQ_GHJ_PH2_IMON")
	)
	(segment
		(start -1.031748 -14.05382)
		(end -3.341878 -14.05382)
		(width 0.127)
		(layer "In2.Cu")
		(net "ISENSE_PVDDQ_GHJ_PH2_IMON")
	)
	(segment
		(start 0.473202 -15.032736)
		(end 0.346202 -14.905736)
		(width 0.127)
		(layer "In2.Cu")
		(net "ISENSE_PVDDQ_GHJ_PH2_IMON")
	)
	(segment
		(start -0.179832 -14.905736)
		(end -1.031748 -14.05382)
		(width 0.127)
		(layer "In2.Cu")
		(net "ISENSE_PVDDQ_GHJ_PH2_IMON")
	)
	(segment
		(start -4.3688 -13.026898)
		(end -4.3688 1.867916)
		(width 0.127)
		(layer "In2.Cu")
		(net "ISENSE_PVDDQ_GHJ_PH2_IMON")
	)
	(segment
		(start 0.473202 -15.094204)
		(end 0.473202 -15.032736)
		(width 0.127)
		(layer "In2.Cu")
		(net "ISENSE_PVDDQ_GHJ_PH2_IMON")
	)
	(segment
		(start -1.011174 5.225542)
		(end 5.411978 5.225542)
		(width 0.127)
		(layer "In2.Cu")
		(net "ISENSE_PVDDQ_GHJ_PH2_IMON")
	)
	(segment
		(start 5.411978 5.225542)
		(end 5.714746 4.922774)
		(width 0.127)
		(layer "In2.Cu")
		(net "ISENSE_PVDDQ_GHJ_PH2_IMON")
	)
	(segment
		(start 0.745236 -6.840982)
		(end 0.745236 -7.146036)
		(width 0.127)
		(layer "F.Cu")
		(net "ISENSE_PVDDQ_GHJ_PH1_IMON")
	)
	(segment
		(start 0.745236 -7.146036)
		(end 1.54305 -7.94385)
		(width 0.127)
		(layer "F.Cu")
		(net "ISENSE_PVDDQ_GHJ_PH1_IMON")
	)
	(segment
		(start 5.479288 -3.2258)
		(end 5.479288 -3.00101)
		(width 0.127)
		(layer "F.Cu")
		(net "ISENSE_PVDDQ_GHJ_PH1_IMON")
	)
	(segment
		(start 1.54305 -7.94385)
		(end 2.067814 -7.94385)
		(width 0.127)
		(layer "F.Cu")
		(net "ISENSE_PVDDQ_GHJ_PH1_IMON")
	)
	(segment
		(start 4.409948 -4.441952)
		(end 4.409948 -4.29514)
		(width 0.127)
		(layer "F.Cu")
		(net "ISENSE_PVDDQ_GHJ_PH1_IMON")
	)
	(segment
		(start 5.499608 -2.16281)
		(end 5.499608 -2.540762)
		(width 0.127)
		(layer "F.Cu")
		(net "ISENSE_PVDDQ_GHJ_PH1_IMON")
	)
	(segment
		(start 5.499608 -2.16281)
		(end 5.499608 -1.612392)
		(width 0.127)
		(layer "F.Cu")
		(net "ISENSE_PVDDQ_GHJ_PH1_IMON")
	)
	(segment
		(start 5.479288 -2.561082)
		(end 5.479288 -3.00101)
		(width 0.127)
		(layer "F.Cu")
		(net "ISENSE_PVDDQ_GHJ_PH1_IMON")
	)
	(segment
		(start 5.499608 -2.540762)
		(end 5.479288 -2.561082)
		(width 0.127)
		(layer "F.Cu")
		(net "ISENSE_PVDDQ_GHJ_PH1_IMON")
	)
	(segment
		(start 4.409948 -4.29514)
		(end 5.479288 -3.2258)
		(width 0.127)
		(layer "F.Cu")
		(net "ISENSE_PVDDQ_GHJ_PH1_IMON")
	)
	(segment
		(start 4.2037 -4.6482)
		(end 4.409948 -4.441952)
		(width 0.127)
		(layer "F.Cu")
		(net "ISENSE_PVDDQ_GHJ_PH1_IMON")
	)
	(segment
		(start 5.499608 -1.612392)
		(end 5.959602 -1.152398)
		(width 0.127)
		(layer "F.Cu")
		(net "ISENSE_PVDDQ_GHJ_PH1_IMON")
	)
	(segment
		(start 5.959602 -1.152398)
		(end 7.5819 -1.152398)
		(width 0.127)
		(layer "F.Cu")
		(net "ISENSE_PVDDQ_GHJ_PH1_IMON")
	)
	(via
		(at 4.2037 -4.6482)
		(size 0.508)
		(drill 0.254)
		(layers "F.Cu" "B.Cu")
		(net "ISENSE_PVDDQ_GHJ_PH1_IMON")
	)
	(via
		(at 0.745236 -6.840982)
		(size 0.508)
		(drill 0.254)
		(layers "F.Cu" "B.Cu")
		(net "ISENSE_PVDDQ_GHJ_PH1_IMON")
	)
	(segment
		(start 3.95732 -4.40182)
		(end 3.327654 -4.40182)
		(width 0.127)
		(layer "In9.Cu")
		(net "ISENSE_PVDDQ_GHJ_PH1_IMON")
	)
	(segment
		(start 2.020062 -5.179568)
		(end 0.745236 -6.454394)
		(width 0.127)
		(layer "In9.Cu")
		(net "ISENSE_PVDDQ_GHJ_PH1_IMON")
	)
	(segment
		(start 2.549906 -5.179568)
		(end 2.020062 -5.179568)
		(width 0.127)
		(layer "In9.Cu")
		(net "ISENSE_PVDDQ_GHJ_PH1_IMON")
	)
	(segment
		(start 3.327654 -4.40182)
		(end 2.549906 -5.179568)
		(width 0.127)
		(layer "In9.Cu")
		(net "ISENSE_PVDDQ_GHJ_PH1_IMON")
	)
	(segment
		(start 0.745236 -6.454394)
		(end 0.745236 -6.840982)
		(width 0.127)
		(layer "In9.Cu")
		(net "ISENSE_PVDDQ_GHJ_PH1_IMON")
	)
	(segment
		(start 4.2037 -4.6482)
		(end 3.95732 -4.40182)
		(width 0.127)
		(layer "In9.Cu")
		(net "ISENSE_PVDDQ_GHJ_PH1_IMON")
	)
	(segment
		(start 359.898188 -140.61567)
		(end 359.898188 -141.178534)
		(width 0.127)
		(layer "F.Cu")
		(net "ISENSE_PVDDQ_DEF_PH2_IMON")
	)
	(segment
		(start 359.733088 -142.03172)
		(end 359.733088 -142.802356)
		(width 0.127)
		(layer "F.Cu")
		(net "ISENSE_PVDDQ_DEF_PH2_IMON")
	)
	(segment
		(start 350.90735 -146.84375)
		(end 351.155 -147.0914)
		(width 0.127)
		(layer "F.Cu")
		(net "ISENSE_PVDDQ_DEF_PH2_IMON")
	)
	(segment
		(start 359.733088 -142.802356)
		(end 359.557828 -142.977616)
		(width 0.127)
		(layer "F.Cu")
		(net "ISENSE_PVDDQ_DEF_PH2_IMON")
	)
	(segment
		(start 350.357186 -146.84375)
		(end 350.90735 -146.84375)
		(width 0.127)
		(layer "F.Cu")
		(net "ISENSE_PVDDQ_DEF_PH2_IMON")
	)
	(segment
		(start 359.898188 -141.178534)
		(end 359.733088 -141.343634)
		(width 0.127)
		(layer "F.Cu")
		(net "ISENSE_PVDDQ_DEF_PH2_IMON")
	)
	(segment
		(start 359.733088 -141.343634)
		(end 359.733088 -142.03172)
		(width 0.127)
		(layer "F.Cu")
		(net "ISENSE_PVDDQ_DEF_PH2_IMON")
	)
	(via
		(at 351.155 -147.0914)
		(size 0.508)
		(drill 0.254)
		(layers "F.Cu" "B.Cu")
		(net "ISENSE_PVDDQ_DEF_PH2_IMON")
	)
	(via
		(at 359.557828 -142.977616)
		(size 0.508)
		(drill 0.254)
		(layers "F.Cu" "B.Cu")
		(net "ISENSE_PVDDQ_DEF_PH2_IMON")
	)
	(segment
		(start 359.7783 -141.833092)
		(end 359.7783 -142.757144)
		(width 0.127)
		(layer "B.Cu")
		(net "ISENSE_PVDDQ_DEF_PH2_IMON")
	)
	(segment
		(start 359.7783 -142.757144)
		(end 359.557828 -142.977616)
		(width 0.127)
		(layer "B.Cu")
		(net "ISENSE_PVDDQ_DEF_PH2_IMON")
	)
	(segment
		(start 351.408746 -147.32)
		(end 352.766376 -147.32)
		(width 0.127)
		(layer "In2.Cu")
		(net "ISENSE_PVDDQ_DEF_PH2_IMON")
	)
	(segment
		(start 351.180146 -147.0914)
		(end 351.408746 -147.32)
		(width 0.127)
		(layer "In2.Cu")
		(net "ISENSE_PVDDQ_DEF_PH2_IMON")
	)
	(segment
		(start 353.671124 -144.952466)
		(end 354.60051 -144.02308)
		(width 0.127)
		(layer "In2.Cu")
		(net "ISENSE_PVDDQ_DEF_PH2_IMON")
	)
	(segment
		(start 359.166922 -144.02308)
		(end 359.65892 -143.531082)
		(width 0.127)
		(layer "In2.Cu")
		(net "ISENSE_PVDDQ_DEF_PH2_IMON")
	)
	(segment
		(start 354.60051 -144.02308)
		(end 359.166922 -144.02308)
		(width 0.127)
		(layer "In2.Cu")
		(net "ISENSE_PVDDQ_DEF_PH2_IMON")
	)
	(segment
		(start 359.65892 -143.078708)
		(end 359.557828 -142.977616)
		(width 0.127)
		(layer "In2.Cu")
		(net "ISENSE_PVDDQ_DEF_PH2_IMON")
	)
	(segment
		(start 353.671124 -146.415252)
		(end 353.671124 -144.952466)
		(width 0.127)
		(layer "In2.Cu")
		(net "ISENSE_PVDDQ_DEF_PH2_IMON")
	)
	(segment
		(start 351.155 -147.0914)
		(end 351.180146 -147.0914)
		(width 0.127)
		(layer "In2.Cu")
		(net "ISENSE_PVDDQ_DEF_PH2_IMON")
	)
	(segment
		(start 359.65892 -143.531082)
		(end 359.65892 -143.078708)
		(width 0.127)
		(layer "In2.Cu")
		(net "ISENSE_PVDDQ_DEF_PH2_IMON")
	)
	(segment
		(start 352.766376 -147.32)
		(end 353.671124 -146.415252)
		(width 0.127)
		(layer "In2.Cu")
		(net "ISENSE_PVDDQ_DEF_PH2_IMON")
	)
	(segment
		(start 360.698288 -141.1986)
		(end 361.47756 -141.977872)
		(width 0.127)
		(layer "F.Cu")
		(net "ISENSE_PVDDQ_DEF_PH1_IMON")
	)
	(segment
		(start 361.47756 -142.71625)
		(end 361.47756 -142.045182)
		(width 0.127)
		(layer "F.Cu")
		(net "ISENSE_PVDDQ_DEF_PH1_IMON")
	)
	(segment
		(start 351.106486 -154.76855)
		(end 351.176844 -154.838908)
		(width 0.127)
		(layer "F.Cu")
		(net "ISENSE_PVDDQ_DEF_PH1_IMON")
	)
	(segment
		(start 350.357186 -154.76855)
		(end 351.106486 -154.76855)
		(width 0.127)
		(layer "F.Cu")
		(net "ISENSE_PVDDQ_DEF_PH1_IMON")
	)
	(segment
		(start 361.47756 -141.977872)
		(end 361.47756 -142.045182)
		(width 0.127)
		(layer "F.Cu")
		(net "ISENSE_PVDDQ_DEF_PH1_IMON")
	)
	(segment
		(start 361.07624 -143.11757)
		(end 361.47756 -142.71625)
		(width 0.127)
		(layer "F.Cu")
		(net "ISENSE_PVDDQ_DEF_PH1_IMON")
	)
	(segment
		(start 360.698288 -140.61567)
		(end 360.698288 -141.1986)
		(width 0.127)
		(layer "F.Cu")
		(net "ISENSE_PVDDQ_DEF_PH1_IMON")
	)
	(via
		(at 361.07624 -143.11757)
		(size 0.508)
		(drill 0.254)
		(layers "F.Cu" "B.Cu")
		(net "ISENSE_PVDDQ_DEF_PH1_IMON")
	)
	(via
		(at 351.176844 -154.838908)
		(size 0.508)
		(drill 0.254)
		(layers "F.Cu" "B.Cu")
		(net "ISENSE_PVDDQ_DEF_PH1_IMON")
	)
	(segment
		(start 361.785154 -141.84249)
		(end 361.785154 -142.408656)
		(width 0.127)
		(layer "B.Cu")
		(net "ISENSE_PVDDQ_DEF_PH1_IMON")
	)
	(segment
		(start 361.785154 -142.408656)
		(end 361.07624 -143.11757)
		(width 0.127)
		(layer "B.Cu")
		(net "ISENSE_PVDDQ_DEF_PH1_IMON")
	)
	(segment
		(start 352.6536 -152.8064)
		(end 352.6536 -149.9362)
		(width 0.127)
		(layer "In11.Cu")
		(net "ISENSE_PVDDQ_DEF_PH1_IMON")
	)
	(segment
		(start 354.1522 -148.4376)
		(end 354.1522 -145.373852)
		(width 0.127)
		(layer "In11.Cu")
		(net "ISENSE_PVDDQ_DEF_PH1_IMON")
	)
	(segment
		(start 351.366836 -155.0289)
		(end 352.103944 -155.0289)
		(width 0.127)
		(layer "In11.Cu")
		(net "ISENSE_PVDDQ_DEF_PH1_IMON")
	)
	(segment
		(start 361.244642 -143.764)
		(end 361.39374 -143.614902)
		(width 0.127)
		(layer "In11.Cu")
		(net "ISENSE_PVDDQ_DEF_PH1_IMON")
	)
	(segment
		(start 351.176844 -154.838908)
		(end 351.366836 -155.0289)
		(width 0.127)
		(layer "In11.Cu")
		(net "ISENSE_PVDDQ_DEF_PH1_IMON")
	)
	(segment
		(start 361.39374 -143.614902)
		(end 361.39374 -143.43507)
		(width 0.127)
		(layer "In11.Cu")
		(net "ISENSE_PVDDQ_DEF_PH1_IMON")
	)
	(segment
		(start 361.39374 -143.43507)
		(end 361.07624 -143.11757)
		(width 0.127)
		(layer "In11.Cu")
		(net "ISENSE_PVDDQ_DEF_PH1_IMON")
	)
	(segment
		(start 352.103944 -155.0289)
		(end 352.552 -154.580844)
		(width 0.127)
		(layer "In11.Cu")
		(net "ISENSE_PVDDQ_DEF_PH1_IMON")
	)
	(segment
		(start 352.552 -154.580844)
		(end 352.552 -152.908)
		(width 0.127)
		(layer "In11.Cu")
		(net "ISENSE_PVDDQ_DEF_PH1_IMON")
	)
	(segment
		(start 355.762052 -143.764)
		(end 361.244642 -143.764)
		(width 0.127)
		(layer "In11.Cu")
		(net "ISENSE_PVDDQ_DEF_PH1_IMON")
	)
	(segment
		(start 352.6536 -149.9362)
		(end 354.1522 -148.4376)
		(width 0.127)
		(layer "In11.Cu")
		(net "ISENSE_PVDDQ_DEF_PH1_IMON")
	)
	(segment
		(start 352.552 -152.908)
		(end 352.6536 -152.8064)
		(width 0.127)
		(layer "In11.Cu")
		(net "ISENSE_PVDDQ_DEF_PH1_IMON")
	)
	(segment
		(start 354.1522 -145.373852)
		(end 355.762052 -143.764)
		(width 0.127)
		(layer "In11.Cu")
		(net "ISENSE_PVDDQ_DEF_PH1_IMON")
	)
	(segment
		(start 344.163142 -12.29741)
		(end 344.163142 -11.839194)
		(width 0.127)
		(layer "F.Cu")
		(net "ISENSE_PVDDQ_ABC_PH2_IMON")
	)
	(segment
		(start 349.61068 0.19177)
		(end 350.550226 -0.747776)
		(width 0.127)
		(layer "F.Cu")
		(net "ISENSE_PVDDQ_ABC_PH2_IMON")
	)
	(segment
		(start 350.550226 -0.747776)
		(end 350.5962 -0.747776)
		(width 0.127)
		(layer "F.Cu")
		(net "ISENSE_PVDDQ_ABC_PH2_IMON")
	)
	(segment
		(start 344.078052 -12.3825)
		(end 344.163142 -12.29741)
		(width 0.127)
		(layer "F.Cu")
		(net "ISENSE_PVDDQ_ABC_PH2_IMON")
	)
	(segment
		(start 346.075 -11.654536)
		(end 346.119196 -11.698732)
		(width 0.127)
		(layer "F.Cu")
		(net "ISENSE_PVDDQ_ABC_PH2_IMON")
	)
	(segment
		(start 349.262192 0.19177)
		(end 349.61068 0.19177)
		(width 0.127)
		(layer "F.Cu")
		(net "ISENSE_PVDDQ_ABC_PH2_IMON")
	)
	(segment
		(start 344.163142 -11.839194)
		(end 344.42654 -11.575796)
		(width 0.127)
		(layer "F.Cu")
		(net "ISENSE_PVDDQ_ABC_PH2_IMON")
	)
	(segment
		(start 345.316048 -11.654536)
		(end 345.237308 -11.575796)
		(width 0.127)
		(layer "F.Cu")
		(net "ISENSE_PVDDQ_ABC_PH2_IMON")
	)
	(segment
		(start 345.237308 -11.575796)
		(end 344.42654 -11.575796)
		(width 0.127)
		(layer "F.Cu")
		(net "ISENSE_PVDDQ_ABC_PH2_IMON")
	)
	(segment
		(start 344.078052 -12.9159)
		(end 344.078052 -12.3825)
		(width 0.127)
		(layer "F.Cu")
		(net "ISENSE_PVDDQ_ABC_PH2_IMON")
	)
	(segment
		(start 345.316048 -11.654536)
		(end 346.075 -11.654536)
		(width 0.127)
		(layer "F.Cu")
		(net "ISENSE_PVDDQ_ABC_PH2_IMON")
	)
	(via
		(at 346.119196 -11.698732)
		(size 0.508)
		(drill 0.254)
		(layers "F.Cu" "B.Cu")
		(net "ISENSE_PVDDQ_ABC_PH2_IMON")
	)
	(via
		(at 350.5962 -0.747776)
		(size 0.508)
		(drill 0.254)
		(layers "F.Cu" "B.Cu")
		(net "ISENSE_PVDDQ_ABC_PH2_IMON")
	)
	(segment
		(start 346.924376 -11.49096)
		(end 346.326968 -11.49096)
		(width 0.127)
		(layer "In2.Cu")
		(net "ISENSE_PVDDQ_ABC_PH2_IMON")
	)
	(segment
		(start 352.797364 -8.18261)
		(end 350.103186 -10.876788)
		(width 0.127)
		(layer "In2.Cu")
		(net "ISENSE_PVDDQ_ABC_PH2_IMON")
	)
	(segment
		(start 352.797364 -2.782316)
		(end 352.797364 -8.18261)
		(width 0.127)
		(layer "In2.Cu")
		(net "ISENSE_PVDDQ_ABC_PH2_IMON")
	)
	(segment
		(start 346.326968 -11.49096)
		(end 346.119196 -11.698732)
		(width 0.127)
		(layer "In2.Cu")
		(net "ISENSE_PVDDQ_ABC_PH2_IMON")
	)
	(segment
		(start 350.5962 -0.747776)
		(end 350.853248 -1.004824)
		(width 0.127)
		(layer "In2.Cu")
		(net "ISENSE_PVDDQ_ABC_PH2_IMON")
	)
	(segment
		(start 350.103186 -10.876788)
		(end 347.538548 -10.876788)
		(width 0.127)
		(layer "In2.Cu")
		(net "ISENSE_PVDDQ_ABC_PH2_IMON")
	)
	(segment
		(start 351.019872 -1.004824)
		(end 352.797364 -2.782316)
		(width 0.127)
		(layer "In2.Cu")
		(net "ISENSE_PVDDQ_ABC_PH2_IMON")
	)
	(segment
		(start 347.538548 -10.876788)
		(end 346.924376 -11.49096)
		(width 0.127)
		(layer "In2.Cu")
		(net "ISENSE_PVDDQ_ABC_PH2_IMON")
	)
	(segment
		(start 350.853248 -1.004824)
		(end 351.019872 -1.004824)
		(width 0.127)
		(layer "In2.Cu")
		(net "ISENSE_PVDDQ_ABC_PH2_IMON")
	)
	(segment
		(start 342.885776 -11.798046)
		(end 342.885776 -11.374882)
		(width 0.127)
		(layer "F.Cu")
		(net "ISENSE_PVDDQ_ABC_PH1_IMON")
	)
	(segment
		(start 349.723964 -7.999984)
		(end 349.666306 -7.942326)
		(width 0.127)
		(layer "F.Cu")
		(net "ISENSE_PVDDQ_ABC_PH1_IMON")
	)
	(segment
		(start 343.277952 -12.468098)
		(end 342.885776 -12.075922)
		(width 0.127)
		(layer "F.Cu")
		(net "ISENSE_PVDDQ_ABC_PH1_IMON")
	)
	(segment
		(start 343.246964 -10.399776)
		(end 343.384632 -10.262108)
		(width 0.127)
		(layer "F.Cu")
		(net "ISENSE_PVDDQ_ABC_PH1_IMON")
	)
	(segment
		(start 350.509586 -8.54329)
		(end 349.96628 -7.999984)
		(width 0.127)
		(layer "F.Cu")
		(net "ISENSE_PVDDQ_ABC_PH1_IMON")
	)
	(segment
		(start 342.885776 -12.075922)
		(end 342.885776 -11.798046)
		(width 0.127)
		(layer "F.Cu")
		(net "ISENSE_PVDDQ_ABC_PH1_IMON")
	)
	(segment
		(start 350.17456 -11.13917)
		(end 350.509586 -10.804144)
		(width 0.127)
		(layer "F.Cu")
		(net "ISENSE_PVDDQ_ABC_PH1_IMON")
	)
	(segment
		(start 343.246964 -11.013694)
		(end 343.246964 -10.399776)
		(width 0.127)
		(layer "F.Cu")
		(net "ISENSE_PVDDQ_ABC_PH1_IMON")
	)
	(segment
		(start 349.96628 -7.999984)
		(end 349.723964 -7.999984)
		(width 0.127)
		(layer "F.Cu")
		(net "ISENSE_PVDDQ_ABC_PH1_IMON")
	)
	(segment
		(start 350.17456 -11.319002)
		(end 350.17456 -11.13917)
		(width 0.127)
		(layer "F.Cu")
		(net "ISENSE_PVDDQ_ABC_PH1_IMON")
	)
	(segment
		(start 349.666306 -7.942326)
		(end 349.341186 -7.942326)
		(width 0.127)
		(layer "F.Cu")
		(net "ISENSE_PVDDQ_ABC_PH1_IMON")
	)
	(segment
		(start 350.29394 -11.438382)
		(end 350.17456 -11.319002)
		(width 0.127)
		(layer "F.Cu")
		(net "ISENSE_PVDDQ_ABC_PH1_IMON")
	)
	(segment
		(start 350.509586 -10.804144)
		(end 350.509586 -8.54329)
		(width 0.127)
		(layer "F.Cu")
		(net "ISENSE_PVDDQ_ABC_PH1_IMON")
	)
	(segment
		(start 343.277952 -12.9159)
		(end 343.277952 -12.468098)
		(width 0.127)
		(layer "F.Cu")
		(net "ISENSE_PVDDQ_ABC_PH1_IMON")
	)
	(segment
		(start 342.885776 -11.374882)
		(end 343.246964 -11.013694)
		(width 0.127)
		(layer "F.Cu")
		(net "ISENSE_PVDDQ_ABC_PH1_IMON")
	)
	(via
		(at 350.29394 -11.438382)
		(size 0.508)
		(drill 0.254)
		(layers "F.Cu" "B.Cu")
		(net "ISENSE_PVDDQ_ABC_PH1_IMON")
	)
	(via
		(at 343.384632 -10.262108)
		(size 0.508)
		(drill 0.254)
		(layers "F.Cu" "B.Cu")
		(net "ISENSE_PVDDQ_ABC_PH1_IMON")
	)
	(segment
		(start 344.047826 -12.6238)
		(end 346.880688 -12.6238)
		(width 0.127)
		(layer "In2.Cu")
		(net "ISENSE_PVDDQ_ABC_PH1_IMON")
	)
	(segment
		(start 349.54083 -11.438382)
		(end 350.29394 -11.438382)
		(width 0.127)
		(layer "In2.Cu")
		(net "ISENSE_PVDDQ_ABC_PH1_IMON")
	)
	(segment
		(start 347.827854 -11.676634)
		(end 349.302578 -11.676634)
		(width 0.127)
		(layer "In2.Cu")
		(net "ISENSE_PVDDQ_ABC_PH1_IMON")
	)
	(segment
		(start 349.302578 -11.676634)
		(end 349.54083 -11.438382)
		(width 0.127)
		(layer "In2.Cu")
		(net "ISENSE_PVDDQ_ABC_PH1_IMON")
	)
	(segment
		(start 343.384632 -10.262108)
		(end 343.15019 -10.49655)
		(width 0.127)
		(layer "In2.Cu")
		(net "ISENSE_PVDDQ_ABC_PH1_IMON")
	)
	(segment
		(start 343.15019 -11.726164)
		(end 344.047826 -12.6238)
		(width 0.127)
		(layer "In2.Cu")
		(net "ISENSE_PVDDQ_ABC_PH1_IMON")
	)
	(segment
		(start 346.880688 -12.6238)
		(end 347.827854 -11.676634)
		(width 0.127)
		(layer "In2.Cu")
		(net "ISENSE_PVDDQ_ABC_PH1_IMON")
	)
	(segment
		(start 343.15019 -10.49655)
		(end 343.15019 -11.726164)
		(width 0.127)
		(layer "In2.Cu")
		(net "ISENSE_PVDDQ_ABC_PH1_IMON")
	)
	(segment
		(start 180.329586 -55.897526)
		(end 180.93055 -55.897526)
		(width 0.127)
		(layer "F.Cu")
		(net "ISENSE_PVCCIO_CPU1_PH1_IMON")
	)
	(segment
		(start 180.93055 -55.897526)
		(end 181.3052 -56.272176)
		(width 0.127)
		(layer "F.Cu")
		(net "ISENSE_PVCCIO_CPU1_PH1_IMON")
	)
	(segment
		(start 167.789352 -63.579248)
		(end 167.789352 -64.3509)
		(width 0.127)
		(layer "F.Cu")
		(net "ISENSE_PVCCIO_CPU1_PH1_IMON")
	)
	(via
		(at 167.789352 -63.579248)
		(size 0.508)
		(drill 0.254)
		(layers "F.Cu" "B.Cu")
		(net "ISENSE_PVCCIO_CPU1_PH1_IMON")
	)
	(via
		(at 170.620182 -64.406018)
		(size 0.6604)
		(drill 0.3302)
		(layers "F.Cu" "B.Cu")
		(net "ISENSE_PVCCIO_CPU1_PH1_IMON")
	)
	(via
		(at 181.3052 -56.272176)
		(size 0.508)
		(drill 0.254)
		(layers "F.Cu" "B.Cu")
		(net "ISENSE_PVCCIO_CPU1_PH1_IMON")
	)
	(segment
		(start 169.0624 -64.5795)
		(end 168.9989 -64.516)
		(width 0.127)
		(layer "B.Cu")
		(net "ISENSE_PVCCIO_CPU1_PH1_IMON")
	)
	(segment
		(start 170.620182 -64.406018)
		(end 170.4467 -64.5795)
		(width 0.127)
		(layer "B.Cu")
		(net "ISENSE_PVCCIO_CPU1_PH1_IMON")
	)
	(segment
		(start 168.529 -64.516)
		(end 167.87114 -64.516)
		(width 0.127)
		(layer "B.Cu")
		(net "ISENSE_PVCCIO_CPU1_PH1_IMON")
	)
	(segment
		(start 170.4467 -64.5795)
		(end 169.545 -64.5795)
		(width 0.127)
		(layer "B.Cu")
		(net "ISENSE_PVCCIO_CPU1_PH1_IMON")
	)
	(segment
		(start 168.9989 -64.516)
		(end 168.529 -64.516)
		(width 0.127)
		(layer "B.Cu")
		(net "ISENSE_PVCCIO_CPU1_PH1_IMON")
	)
	(segment
		(start 169.545 -64.5795)
		(end 169.0624 -64.5795)
		(width 0.127)
		(layer "B.Cu")
		(net "ISENSE_PVCCIO_CPU1_PH1_IMON")
	)
	(segment
		(start 167.635428 -63.733172)
		(end 167.789352 -63.579248)
		(width 0.127)
		(layer "B.Cu")
		(net "ISENSE_PVCCIO_CPU1_PH1_IMON")
	)
	(segment
		(start 167.635428 -64.280288)
		(end 167.635428 -63.733172)
		(width 0.127)
		(layer "B.Cu")
		(net "ISENSE_PVCCIO_CPU1_PH1_IMON")
	)
	(segment
		(start 167.87114 -64.516)
		(end 167.635428 -64.280288)
		(width 0.127)
		(layer "B.Cu")
		(net "ISENSE_PVCCIO_CPU1_PH1_IMON")
	)
	(segment
		(start 169.875454 -64.135)
		(end 170.713654 -63.2968)
		(width 0.127)
		(layer "In9.Cu")
		(net "ISENSE_PVCCIO_CPU1_PH1_IMON")
	)
	(segment
		(start 181.090824 -56.0578)
		(end 181.3052 -56.272176)
		(width 0.127)
		(layer "In9.Cu")
		(net "ISENSE_PVCCIO_CPU1_PH1_IMON")
	)
	(segment
		(start 167.540432 -63.828168)
		(end 167.540432 -64.008)
		(width 0.127)
		(layer "In9.Cu")
		(net "ISENSE_PVCCIO_CPU1_PH1_IMON")
	)
	(segment
		(start 180.1622 -56.0578)
		(end 181.090824 -56.0578)
		(width 0.127)
		(layer "In9.Cu")
		(net "ISENSE_PVCCIO_CPU1_PH1_IMON")
	)
	(segment
		(start 177.541936 -56.6674)
		(end 179.5526 -56.6674)
		(width 0.127)
		(layer "In9.Cu")
		(net "ISENSE_PVCCIO_CPU1_PH1_IMON")
	)
	(segment
		(start 167.667432 -64.135)
		(end 169.875454 -64.135)
		(width 0.127)
		(layer "In9.Cu")
		(net "ISENSE_PVCCIO_CPU1_PH1_IMON")
	)
	(segment
		(start 167.540432 -64.008)
		(end 167.667432 -64.135)
		(width 0.127)
		(layer "In9.Cu")
		(net "ISENSE_PVCCIO_CPU1_PH1_IMON")
	)
	(segment
		(start 172.3136 -63.2968)
		(end 172.90288 -62.70752)
		(width 0.127)
		(layer "In9.Cu")
		(net "ISENSE_PVCCIO_CPU1_PH1_IMON")
	)
	(segment
		(start 170.713654 -63.2968)
		(end 172.3136 -63.2968)
		(width 0.127)
		(layer "In9.Cu")
		(net "ISENSE_PVCCIO_CPU1_PH1_IMON")
	)
	(segment
		(start 172.90288 -61.306456)
		(end 177.541936 -56.6674)
		(width 0.127)
		(layer "In9.Cu")
		(net "ISENSE_PVCCIO_CPU1_PH1_IMON")
	)
	(segment
		(start 179.5526 -56.6674)
		(end 180.1622 -56.0578)
		(width 0.127)
		(layer "In9.Cu")
		(net "ISENSE_PVCCIO_CPU1_PH1_IMON")
	)
	(segment
		(start 167.789352 -63.579248)
		(end 167.540432 -63.828168)
		(width 0.127)
		(layer "In9.Cu")
		(net "ISENSE_PVCCIO_CPU1_PH1_IMON")
	)
	(segment
		(start 172.90288 -62.70752)
		(end 172.90288 -61.306456)
		(width 0.127)
		(layer "In9.Cu")
		(net "ISENSE_PVCCIO_CPU1_PH1_IMON")
	)
	(segment
		(start 349.927164 -99.094798)
		(end 350.910398 -99.094798)
		(width 0.127)
		(layer "F.Cu")
		(net "ISENSE_PVCCIO_CPU0_PH1_IMON")
	)
	(segment
		(start 350.910398 -99.094798)
		(end 351.4598 -99.6442)
		(width 0.127)
		(layer "F.Cu")
		(net "ISENSE_PVCCIO_CPU0_PH1_IMON")
	)
	(via
		(at 351.4598 -99.6442)
		(size 0.508)
		(drill 0.254)
		(layers "F.Cu" "B.Cu")
		(net "ISENSE_PVCCIO_CPU0_PH1_IMON")
	)
	(via
		(at 345.3384 -91.6432)
		(size 0.508)
		(drill 0.254)
		(layers "F.Cu" "B.Cu")
		(net "ISENSE_PVCCIO_CPU0_PH1_IMON")
	)
	(segment
		(start 345.3384 -91.6432)
		(end 344.839798 -92.141802)
		(width 0.127)
		(layer "B.Cu")
		(net "ISENSE_PVCCIO_CPU0_PH1_IMON")
	)
	(segment
		(start 345.350846 -91.630754)
		(end 345.3384 -91.6432)
		(width 0.127)
		(layer "B.Cu")
		(net "ISENSE_PVCCIO_CPU0_PH1_IMON")
	)
	(segment
		(start 345.132152 -89.9033)
		(end 345.132152 -90.483436)
		(width 0.127)
		(layer "B.Cu")
		(net "ISENSE_PVCCIO_CPU0_PH1_IMON")
	)
	(segment
		(start 345.350846 -90.97137)
		(end 345.350846 -91.630754)
		(width 0.127)
		(layer "B.Cu")
		(net "ISENSE_PVCCIO_CPU0_PH1_IMON")
	)
	(segment
		(start 345.132152 -90.483436)
		(end 345.350846 -90.70213)
		(width 0.127)
		(layer "B.Cu")
		(net "ISENSE_PVCCIO_CPU0_PH1_IMON")
	)
	(segment
		(start 343.30005 -92.141802)
		(end 342.622378 -91.46413)
		(width 0.127)
		(layer "B.Cu")
		(net "ISENSE_PVCCIO_CPU0_PH1_IMON")
	)
	(segment
		(start 345.350846 -90.70213)
		(end 345.350846 -90.97137)
		(width 0.127)
		(layer "B.Cu")
		(net "ISENSE_PVCCIO_CPU0_PH1_IMON")
	)
	(segment
		(start 344.839798 -92.141802)
		(end 343.30005 -92.141802)
		(width 0.127)
		(layer "B.Cu")
		(net "ISENSE_PVCCIO_CPU0_PH1_IMON")
	)
	(segment
		(start 351.22612 -99.41052)
		(end 351.4598 -99.6442)
		(width 0.127)
		(layer "In11.Cu")
		(net "ISENSE_PVCCIO_CPU0_PH1_IMON")
	)
	(segment
		(start 352.5012 -93.268546)
		(end 352.5012 -97.847658)
		(width 0.127)
		(layer "In11.Cu")
		(net "ISENSE_PVCCIO_CPU0_PH1_IMON")
	)
	(segment
		(start 345.3384 -91.6432)
		(end 345.757246 -92.062046)
		(width 0.127)
		(layer "In11.Cu")
		(net "ISENSE_PVCCIO_CPU0_PH1_IMON")
	)
	(segment
		(start 352.5012 -97.847658)
		(end 351.22612 -99.122738)
		(width 0.127)
		(layer "In11.Cu")
		(net "ISENSE_PVCCIO_CPU0_PH1_IMON")
	)
	(segment
		(start 345.757246 -92.062046)
		(end 351.2947 -92.062046)
		(width 0.127)
		(layer "In11.Cu")
		(net "ISENSE_PVCCIO_CPU0_PH1_IMON")
	)
	(segment
		(start 351.2947 -92.062046)
		(end 352.5012 -93.268546)
		(width 0.127)
		(layer "In11.Cu")
		(net "ISENSE_PVCCIO_CPU0_PH1_IMON")
	)
	(segment
		(start 351.22612 -99.122738)
		(end 351.22612 -99.41052)
		(width 0.127)
		(layer "In11.Cu")
		(net "ISENSE_PVCCIO_CPU0_PH1_IMON")
	)
	(segment
		(start 395.626082 -157.237684)
		(end 395.626082 -157.707076)
		(width 0.127)
		(layer "F.Cu")
		(net "ISENSE_P1V05_PCH_STBY_PH1_IMON")
	)
	(segment
		(start 395.626082 -157.707076)
		(end 395.626082 -158.381954)
		(width 0.127)
		(layer "F.Cu")
		(net "ISENSE_P1V05_PCH_STBY_PH1_IMON")
	)
	(segment
		(start 383.1717 -157.43174)
		(end 383.302256 -157.43174)
		(width 0.127)
		(layer "F.Cu")
		(net "ISENSE_P1V05_PCH_STBY_PH1_IMON")
	)
	(segment
		(start 383.302256 -157.43174)
		(end 383.844292 -156.889704)
		(width 0.127)
		(layer "F.Cu")
		(net "ISENSE_P1V05_PCH_STBY_PH1_IMON")
	)
	(segment
		(start 383.844292 -156.889704)
		(end 383.844292 -156.565092)
		(width 0.127)
		(layer "F.Cu")
		(net "ISENSE_P1V05_PCH_STBY_PH1_IMON")
	)
	(segment
		(start 395.626082 -158.381954)
		(end 395.62405 -158.383986)
		(width 0.127)
		(layer "F.Cu")
		(net "ISENSE_P1V05_PCH_STBY_PH1_IMON")
	)
	(segment
		(start 395.582902 -156.2481)
		(end 395.582902 -157.194504)
		(width 0.127)
		(layer "F.Cu")
		(net "ISENSE_P1V05_PCH_STBY_PH1_IMON")
	)
	(segment
		(start 395.582902 -157.194504)
		(end 395.626082 -157.237684)
		(width 0.127)
		(layer "F.Cu")
		(net "ISENSE_P1V05_PCH_STBY_PH1_IMON")
	)
	(via
		(at 383.1717 -157.43174)
		(size 0.508)
		(drill 0.254)
		(layers "F.Cu" "B.Cu")
		(net "ISENSE_P1V05_PCH_STBY_PH1_IMON")
	)
	(via
		(at 395.62405 -158.383986)
		(size 0.508)
		(drill 0.254)
		(layers "F.Cu" "B.Cu")
		(net "ISENSE_P1V05_PCH_STBY_PH1_IMON")
	)
	(segment
		(start 395.62405 -158.383986)
		(end 395.891766 -158.11627)
		(width 0.127)
		(layer "B.Cu")
		(net "ISENSE_P1V05_PCH_STBY_PH1_IMON")
	)
	(segment
		(start 395.574266 -157.575504)
		(end 395.574266 -157.117288)
		(width 0.127)
		(layer "B.Cu")
		(net "ISENSE_P1V05_PCH_STBY_PH1_IMON")
	)
	(segment
		(start 395.891766 -158.11627)
		(end 395.891766 -157.893004)
		(width 0.127)
		(layer "B.Cu")
		(net "ISENSE_P1V05_PCH_STBY_PH1_IMON")
	)
	(segment
		(start 395.891766 -157.893004)
		(end 395.574266 -157.575504)
		(width 0.127)
		(layer "B.Cu")
		(net "ISENSE_P1V05_PCH_STBY_PH1_IMON")
	)
	(segment
		(start 394.283184 -157.29204)
		(end 393.60094 -157.974284)
		(width 0.127)
		(layer "In2.Cu")
		(net "ISENSE_P1V05_PCH_STBY_PH1_IMON")
	)
	(segment
		(start 386.44195 -156.75356)
		(end 383.245614 -156.75356)
		(width 0.127)
		(layer "In2.Cu")
		(net "ISENSE_P1V05_PCH_STBY_PH1_IMON")
	)
	(segment
		(start 390.346946 -157.0482)
		(end 389.544306 -157.85084)
		(width 0.127)
		(layer "In2.Cu")
		(net "ISENSE_P1V05_PCH_STBY_PH1_IMON")
	)
	(segment
		(start 395.859 -158.149036)
		(end 395.859 -157.702504)
		(width 0.127)
		(layer "In2.Cu")
		(net "ISENSE_P1V05_PCH_STBY_PH1_IMON")
	)
	(segment
		(start 389.544306 -157.85084)
		(end 387.53923 -157.85084)
		(width 0.127)
		(layer "In2.Cu")
		(net "ISENSE_P1V05_PCH_STBY_PH1_IMON")
	)
	(segment
		(start 383.07264 -156.926534)
		(end 383.07264 -157.33268)
		(width 0.127)
		(layer "In2.Cu")
		(net "ISENSE_P1V05_PCH_STBY_PH1_IMON")
	)
	(segment
		(start 395.62405 -158.383986)
		(end 395.859 -158.149036)
		(width 0.127)
		(layer "In2.Cu")
		(net "ISENSE_P1V05_PCH_STBY_PH1_IMON")
	)
	(segment
		(start 383.245614 -156.75356)
		(end 383.07264 -156.926534)
		(width 0.127)
		(layer "In2.Cu")
		(net "ISENSE_P1V05_PCH_STBY_PH1_IMON")
	)
	(segment
		(start 393.60094 -157.974284)
		(end 392.49604 -157.974284)
		(width 0.127)
		(layer "In2.Cu")
		(net "ISENSE_P1V05_PCH_STBY_PH1_IMON")
	)
	(segment
		(start 391.569956 -157.0482)
		(end 390.346946 -157.0482)
		(width 0.127)
		(layer "In2.Cu")
		(net "ISENSE_P1V05_PCH_STBY_PH1_IMON")
	)
	(segment
		(start 395.448536 -157.29204)
		(end 394.283184 -157.29204)
		(width 0.127)
		(layer "In2.Cu")
		(net "ISENSE_P1V05_PCH_STBY_PH1_IMON")
	)
	(segment
		(start 392.49604 -157.974284)
		(end 391.569956 -157.0482)
		(width 0.127)
		(layer "In2.Cu")
		(net "ISENSE_P1V05_PCH_STBY_PH1_IMON")
	)
	(segment
		(start 383.07264 -157.33268)
		(end 383.1717 -157.43174)
		(width 0.127)
		(layer "In2.Cu")
		(net "ISENSE_P1V05_PCH_STBY_PH1_IMON")
	)
	(segment
		(start 395.859 -157.702504)
		(end 395.448536 -157.29204)
		(width 0.127)
		(layer "In2.Cu")
		(net "ISENSE_P1V05_PCH_STBY_PH1_IMON")
	)
	(segment
		(start 387.53923 -157.85084)
		(end 386.44195 -156.75356)
		(width 0.127)
		(layer "In2.Cu")
		(net "ISENSE_P1V05_PCH_STBY_PH1_IMON")
	)
	(segment
		(start 24.518112 -97.559368)
		(end 23.700232 -97.559368)
		(width 0.127)
		(layer "F.Cu")
		(net "VR_PVSA_CPU1_BIREF1")
	)
	(segment
		(start 22.112732 -96.323658)
		(end 22.726142 -96.323658)
		(width 0.127)
		(layer "F.Cu")
		(net "VR_PVSA_CPU1_BIREF1")
	)
	(segment
		(start 23.700232 -97.559368)
		(end 23.697184 -97.562416)
		(width 0.127)
		(layer "F.Cu")
		(net "VR_PVSA_CPU1_BIREF1")
	)
	(segment
		(start 28.986988 -94.814136)
		(end 27.948128 -94.814136)
		(width 0.127)
		(layer "F.Cu")
		(net "VR_PVSA_CPU1_BIREF1")
	)
	(segment
		(start 25.478232 -97.559368)
		(end 24.518112 -97.559368)
		(width 0.127)
		(layer "F.Cu")
		(net "VR_PVSA_CPU1_BIREF1")
	)
	(segment
		(start 23.175722 -97.040954)
		(end 23.697184 -97.562416)
		(width 0.127)
		(layer "F.Cu")
		(net "VR_PVSA_CPU1_BIREF1")
	)
	(segment
		(start 29.965904 -94.604332)
		(end 29.196792 -94.604332)
		(width 0.127)
		(layer "F.Cu")
		(net "VR_PVSA_CPU1_BIREF1")
	)
	(segment
		(start 22.726142 -96.323658)
		(end 23.175722 -96.773238)
		(width 0.127)
		(layer "F.Cu")
		(net "VR_PVSA_CPU1_BIREF1")
	)
	(segment
		(start 21.630894 -95.84182)
		(end 22.112732 -96.323658)
		(width 0.127)
		(layer "F.Cu")
		(net "VR_PVSA_CPU1_BIREF1")
	)
	(segment
		(start 30.635956 -95.679768)
		(end 31.02991 -95.679768)
		(width 0.127)
		(layer "F.Cu")
		(net "VR_PVSA_CPU1_BIREF1")
	)
	(segment
		(start 26.241756 -95.624904)
		(end 26.241756 -96.795844)
		(width 0.127)
		(layer "F.Cu")
		(net "VR_PVSA_CPU1_BIREF1")
	)
	(segment
		(start 27.052524 -94.814136)
		(end 26.241756 -95.624904)
		(width 0.127)
		(layer "F.Cu")
		(net "VR_PVSA_CPU1_BIREF1")
	)
	(segment
		(start 26.241756 -96.795844)
		(end 25.478232 -97.559368)
		(width 0.127)
		(layer "F.Cu")
		(net "VR_PVSA_CPU1_BIREF1")
	)
	(segment
		(start 21.630894 -95.3516)
		(end 21.630894 -95.84182)
		(width 0.127)
		(layer "F.Cu")
		(net "VR_PVSA_CPU1_BIREF1")
	)
	(segment
		(start 29.965904 -95.009716)
		(end 30.635956 -95.679768)
		(width 0.127)
		(layer "F.Cu")
		(net "VR_PVSA_CPU1_BIREF1")
	)
	(segment
		(start 29.196792 -94.604332)
		(end 28.986988 -94.814136)
		(width 0.127)
		(layer "F.Cu")
		(net "VR_PVSA_CPU1_BIREF1")
	)
	(segment
		(start 23.175722 -96.773238)
		(end 23.175722 -97.040954)
		(width 0.127)
		(layer "F.Cu")
		(net "VR_PVSA_CPU1_BIREF1")
	)
	(segment
		(start 27.948128 -94.814136)
		(end 27.052524 -94.814136)
		(width 0.127)
		(layer "F.Cu")
		(net "VR_PVSA_CPU1_BIREF1")
	)
	(segment
		(start 29.965904 -94.604332)
		(end 29.965904 -95.009716)
		(width 0.127)
		(layer "F.Cu")
		(net "VR_PVSA_CPU1_BIREF1")
	)
	(via
		(at 27.948128 -94.814136)
		(size 0.508)
		(drill 0.254)
		(layers "F.Cu" "B.Cu")
		(net "VR_PVSA_CPU1_BIREF1")
	)
	(segment
		(start 20.831556 -97.310956)
		(end 20.5232 -97.310956)
		(width 0.254)
		(layer "F.Cu")
		(net "A_TSENSE_PVSA_CPU1")
	)
	(segment
		(start 31.02991 -97.029778)
		(end 30.362398 -97.029778)
		(width 0.254)
		(layer "F.Cu")
		(net "A_TSENSE_PVSA_CPU1")
	)
	(segment
		(start 19.630898 -95.805498)
		(end 19.8882 -96.0628)
		(width 0.2032)
		(layer "F.Cu")
		(net "A_TSENSE_PVSA_CPU1")
	)
	(segment
		(start 30.155642 -96.823022)
		(end 30.131766 -96.823022)
		(width 0.254)
		(layer "F.Cu")
		(net "A_TSENSE_PVSA_CPU1")
	)
	(segment
		(start 21.082 -97.966276)
		(end 21.082 -97.5614)
		(width 0.254)
		(layer "F.Cu")
		(net "A_TSENSE_PVSA_CPU1")
	)
	(segment
		(start 19.630898 -95.3516)
		(end 19.630898 -95.805498)
		(width 0.2032)
		(layer "F.Cu")
		(net "A_TSENSE_PVSA_CPU1")
	)
	(segment
		(start 27.102816 -96.99752)
		(end 24.82088 -99.279456)
		(width 0.254)
		(layer "F.Cu")
		(net "A_TSENSE_PVSA_CPU1")
	)
	(segment
		(start 29.918152 -96.609408)
		(end 29.337 -96.609408)
		(width 0.254)
		(layer "F.Cu")
		(net "A_TSENSE_PVSA_CPU1")
	)
	(segment
		(start 19.8882 -96.675956)
		(end 20.5232 -97.310956)
		(width 0.2032)
		(layer "F.Cu")
		(net "A_TSENSE_PVSA_CPU1")
	)
	(segment
		(start 24.82088 -99.279456)
		(end 22.39518 -99.279456)
		(width 0.254)
		(layer "F.Cu")
		(net "A_TSENSE_PVSA_CPU1")
	)
	(segment
		(start 21.082 -97.5614)
		(end 20.831556 -97.310956)
		(width 0.254)
		(layer "F.Cu")
		(net "A_TSENSE_PVSA_CPU1")
	)
	(segment
		(start 29.337 -96.609408)
		(end 28.948888 -96.99752)
		(width 0.254)
		(layer "F.Cu")
		(net "A_TSENSE_PVSA_CPU1")
	)
	(segment
		(start 30.131766 -96.823022)
		(end 29.918152 -96.609408)
		(width 0.254)
		(layer "F.Cu")
		(net "A_TSENSE_PVSA_CPU1")
	)
	(segment
		(start 19.8882 -96.0628)
		(end 19.8882 -96.675956)
		(width 0.2032)
		(layer "F.Cu")
		(net "A_TSENSE_PVSA_CPU1")
	)
	(segment
		(start 22.39518 -99.279456)
		(end 21.082 -97.966276)
		(width 0.254)
		(layer "F.Cu")
		(net "A_TSENSE_PVSA_CPU1")
	)
	(segment
		(start 30.362398 -97.029778)
		(end 30.155642 -96.823022)
		(width 0.254)
		(layer "F.Cu")
		(net "A_TSENSE_PVSA_CPU1")
	)
	(segment
		(start 28.948888 -96.99752)
		(end 27.102816 -96.99752)
		(width 0.254)
		(layer "F.Cu")
		(net "A_TSENSE_PVSA_CPU1")
	)
	(via
		(at 30.131766 -96.823022)
		(size 0.508)
		(drill 0.254)
		(layers "F.Cu" "B.Cu")
		(net "A_TSENSE_PVSA_CPU1")
	)
	(segment
		(start 30.862778 -96.823022)
		(end 30.8864 -96.7994)
		(width 0.254)
		(layer "B.Cu")
		(net "A_TSENSE_PVSA_CPU1")
	)
	(segment
		(start 30.8864 -96.7994)
		(end 30.952948 -96.7994)
		(width 0.254)
		(layer "B.Cu")
		(net "A_TSENSE_PVSA_CPU1")
	)
	(segment
		(start 30.131766 -96.823022)
		(end 30.862778 -96.823022)
		(width 0.254)
		(layer "B.Cu")
		(net "A_TSENSE_PVSA_CPU1")
	)
	(segment
		(start 31.02991 -72.645778)
		(end 30.362398 -72.645778)
		(width 0.254)
		(layer "F.Cu")
		(net "A_TSENSE_PVCCIN_CPU1")
	)
	(segment
		(start 30.104334 -88.643714)
		(end 29.974032 -88.643714)
		(width 0.254)
		(layer "F.Cu")
		(net "A_TSENSE_PVCCIN_CPU1")
	)
	(segment
		(start 30.362398 -64.517778)
		(end 30.104334 -64.259714)
		(width 0.254)
		(layer "F.Cu")
		(net "A_TSENSE_PVCCIN_CPU1")
	)
	(segment
		(start 31.02991 -56.389778)
		(end 30.362398 -56.389778)
		(width 0.254)
		(layer "F.Cu")
		(net "A_TSENSE_PVCCIN_CPU1")
	)
	(segment
		(start 30.104334 -56.131714)
		(end 29.974032 -56.131714)
		(width 0.254)
		(layer "F.Cu")
		(net "A_TSENSE_PVCCIN_CPU1")
	)
	(segment
		(start 19.6342 -97.310956)
		(end 19.6342 -96.891348)
		(width 0.2032)
		(layer "F.Cu")
		(net "A_TSENSE_PVCCIN_CPU1")
	)
	(segment
		(start 31.02991 -64.517778)
		(end 30.362398 -64.517778)
		(width 0.254)
		(layer "F.Cu")
		(net "A_TSENSE_PVCCIN_CPU1")
	)
	(segment
		(start 30.362398 -56.389778)
		(end 30.104334 -56.131714)
		(width 0.254)
		(layer "F.Cu")
		(net "A_TSENSE_PVCCIN_CPU1")
	)
	(segment
		(start 19.231102 -95.837502)
		(end 19.231102 -95.3516)
		(width 0.2032)
		(layer "F.Cu")
		(net "A_TSENSE_PVCCIN_CPU1")
	)
	(segment
		(start 31.02991 -88.901778)
		(end 30.362398 -88.901778)
		(width 0.254)
		(layer "F.Cu")
		(net "A_TSENSE_PVCCIN_CPU1")
	)
	(segment
		(start 31.02991 -80.773778)
		(end 30.362398 -80.773778)
		(width 0.254)
		(layer "F.Cu")
		(net "A_TSENSE_PVCCIN_CPU1")
	)
	(segment
		(start 30.362398 -72.645778)
		(end 30.104334 -72.387714)
		(width 0.254)
		(layer "F.Cu")
		(net "A_TSENSE_PVCCIN_CPU1")
	)
	(segment
		(start 19.5326 -96.789748)
		(end 19.5326 -96.139)
		(width 0.2032)
		(layer "F.Cu")
		(net "A_TSENSE_PVCCIN_CPU1")
	)
	(segment
		(start 19.6342 -96.891348)
		(end 19.5326 -96.789748)
		(width 0.2032)
		(layer "F.Cu")
		(net "A_TSENSE_PVCCIN_CPU1")
	)
	(segment
		(start 30.362398 -88.901778)
		(end 30.104334 -88.643714)
		(width 0.254)
		(layer "F.Cu")
		(net "A_TSENSE_PVCCIN_CPU1")
	)
	(segment
		(start 30.104334 -72.387714)
		(end 29.974032 -72.387714)
		(width 0.254)
		(layer "F.Cu")
		(net "A_TSENSE_PVCCIN_CPU1")
	)
	(segment
		(start 19.5326 -96.139)
		(end 19.231102 -95.837502)
		(width 0.2032)
		(layer "F.Cu")
		(net "A_TSENSE_PVCCIN_CPU1")
	)
	(segment
		(start 30.104334 -80.515714)
		(end 29.974032 -80.515714)
		(width 0.254)
		(layer "F.Cu")
		(net "A_TSENSE_PVCCIN_CPU1")
	)
	(segment
		(start 30.104334 -64.259714)
		(end 29.974032 -64.259714)
		(width 0.254)
		(layer "F.Cu")
		(net "A_TSENSE_PVCCIN_CPU1")
	)
	(segment
		(start 30.362398 -80.773778)
		(end 30.104334 -80.515714)
		(width 0.254)
		(layer "F.Cu")
		(net "A_TSENSE_PVCCIN_CPU1")
	)
	(segment
		(start 19.6342 -97.310956)
		(end 18.9992 -97.310956)
		(width 0.254)
		(layer "F.Cu")
		(net "A_TSENSE_PVCCIN_CPU1")
	)
	(via
		(at 18.9992 -97.310956)
		(size 0.508)
		(drill 0.254)
		(layers "F.Cu" "B.Cu")
		(net "A_TSENSE_PVCCIN_CPU1")
	)
	(via
		(at 29.974032 -72.387714)
		(size 0.508)
		(drill 0.254)
		(layers "F.Cu" "B.Cu")
		(net "A_TSENSE_PVCCIN_CPU1")
	)
	(via
		(at 29.974032 -88.643714)
		(size 0.508)
		(drill 0.254)
		(layers "F.Cu" "B.Cu")
		(net "A_TSENSE_PVCCIN_CPU1")
	)
	(via
		(at 29.974032 -80.515714)
		(size 0.508)
		(drill 0.254)
		(layers "F.Cu" "B.Cu")
		(net "A_TSENSE_PVCCIN_CPU1")
	)
	(via
		(at 29.974032 -56.131714)
		(size 0.508)
		(drill 0.254)
		(layers "F.Cu" "B.Cu")
		(net "A_TSENSE_PVCCIN_CPU1")
	)
	(via
		(at 29.974032 -64.259714)
		(size 0.508)
		(drill 0.254)
		(layers "F.Cu" "B.Cu")
		(net "A_TSENSE_PVCCIN_CPU1")
	)
	(via
		(at 28.12796 -61.051694)
		(size 0.6604)
		(drill 0.3302)
		(layers "F.Cu" "B.Cu")
		(net "A_TSENSE_PVCCIN_CPU1")
	)
	(segment
		(start 28.66644 -86.4743)
		(end 27.8892 -85.69706)
		(width 0.254)
		(layer "B.Cu")
		(net "A_TSENSE_PVCCIN_CPU1")
	)
	(segment
		(start 29.722318 -72.136)
		(end 29.0068 -72.136)
		(width 0.254)
		(layer "B.Cu")
		(net "A_TSENSE_PVCCIN_CPU1")
	)
	(segment
		(start 29.974032 -88.643714)
		(end 29.619448 -88.28913)
		(width 0.254)
		(layer "B.Cu")
		(net "A_TSENSE_PVCCIN_CPU1")
	)
	(segment
		(start 27.8892 -84.2518)
		(end 28.7528 -83.3882)
		(width 0.254)
		(layer "B.Cu")
		(net "A_TSENSE_PVCCIN_CPU1")
	)
	(segment
		(start 29.974032 -64.259714)
		(end 29.764482 -64.050164)
		(width 0.254)
		(layer "B.Cu")
		(net "A_TSENSE_PVCCIN_CPU1")
	)
	(segment
		(start 30.3022 -62.073536)
		(end 30.3022 -62.947804)
		(width 0.254)
		(layer "B.Cu")
		(net "A_TSENSE_PVCCIN_CPU1")
	)
	(segment
		(start 27.8892 -85.69706)
		(end 27.8892 -84.2518)
		(width 0.254)
		(layer "B.Cu")
		(net "A_TSENSE_PVCCIN_CPU1")
	)
	(segment
		(start 28.115768 -56.856376)
		(end 29.085286 -55.886858)
		(width 0.254)
		(layer "B.Cu")
		(net "A_TSENSE_PVCCIN_CPU1")
	)
	(segment
		(start 28.66644 -87.69985)
		(end 28.66644 -86.4743)
		(width 0.254)
		(layer "B.Cu")
		(net "A_TSENSE_PVCCIN_CPU1")
	)
	(segment
		(start 31.0134 -79.761842)
		(end 31.0134 -80.4926)
		(width 0.254)
		(layer "B.Cu")
		(net "A_TSENSE_PVCCIN_CPU1")
	)
	(segment
		(start 30.471618 -64.262)
		(end 30.469332 -64.259714)
		(width 0.254)
		(layer "B.Cu")
		(net "A_TSENSE_PVCCIN_CPU1")
	)
	(segment
		(start 29.974032 -56.131714)
		(end 30.378146 -55.7276)
		(width 0.254)
		(layer "B.Cu")
		(net "A_TSENSE_PVCCIN_CPU1")
	)
	(segment
		(start 30.3022 -62.947804)
		(end 30.988 -63.633604)
		(width 0.254)
		(layer "B.Cu")
		(net "A_TSENSE_PVCCIN_CPU1")
	)
	(segment
		(start 28.803346 -66.878454)
		(end 29.562806 -67.637914)
		(width 0.254)
		(layer "B.Cu")
		(net "A_TSENSE_PVCCIN_CPU1")
	)
	(segment
		(start 28.508706 -61.43244)
		(end 29.661104 -61.43244)
		(width 0.254)
		(layer "B.Cu")
		(net "A_TSENSE_PVCCIN_CPU1")
	)
	(segment
		(start 28.7528 -83.3882)
		(end 28.7528 -80.5561)
		(width 0.254)
		(layer "B.Cu")
		(net "A_TSENSE_PVCCIN_CPU1")
	)
	(segment
		(start 30.052518 -88.7222)
		(end 29.974032 -88.643714)
		(width 0.254)
		(layer "B.Cu")
		(net "A_TSENSE_PVCCIN_CPU1")
	)
	(segment
		(start 29.085286 -55.886858)
		(end 29.729176 -55.886858)
		(width 0.254)
		(layer "B.Cu")
		(net "A_TSENSE_PVCCIN_CPU1")
	)
	(segment
		(start 29.661104 -61.43244)
		(end 30.3022 -62.073536)
		(width 0.254)
		(layer "B.Cu")
		(net "A_TSENSE_PVCCIN_CPU1")
	)
	(segment
		(start 29.997146 -80.4926)
		(end 29.974032 -80.515714)
		(width 0.254)
		(layer "B.Cu")
		(net "A_TSENSE_PVCCIN_CPU1")
	)
	(segment
		(start 30.40634 -71.04634)
		(end 31.0134 -71.6534)
		(width 0.254)
		(layer "B.Cu")
		(net "A_TSENSE_PVCCIN_CPU1")
	)
	(segment
		(start 30.40634 -69.887084)
		(end 30.40634 -71.04634)
		(width 0.254)
		(layer "B.Cu")
		(net "A_TSENSE_PVCCIN_CPU1")
	)
	(segment
		(start 28.7528 -80.5561)
		(end 29.0449 -80.264)
		(width 0.254)
		(layer "B.Cu")
		(net "A_TSENSE_PVCCIN_CPU1")
	)
	(segment
		(start 30.988 -63.633604)
		(end 30.988 -64.262)
		(width 0.254)
		(layer "B.Cu")
		(net "A_TSENSE_PVCCIN_CPU1")
	)
	(segment
		(start 29.25572 -88.28913)
		(end 28.66644 -87.69985)
		(width 0.254)
		(layer "B.Cu")
		(net "A_TSENSE_PVCCIN_CPU1")
	)
	(segment
		(start 29.562806 -67.637914)
		(end 29.562806 -69.04355)
		(width 0.254)
		(layer "B.Cu")
		(net "A_TSENSE_PVCCIN_CPU1")
	)
	(segment
		(start 31.0134 -71.6534)
		(end 31.0134 -72.1614)
		(width 0.254)
		(layer "B.Cu")
		(net "A_TSENSE_PVCCIN_CPU1")
	)
	(segment
		(start 30.9372 -88.7222)
		(end 30.052518 -88.7222)
		(width 0.254)
		(layer "B.Cu")
		(net "A_TSENSE_PVCCIN_CPU1")
	)
	(segment
		(start 30.282388 -77.801216)
		(end 30.282388 -79.03083)
		(width 0.254)
		(layer "B.Cu")
		(net "A_TSENSE_PVCCIN_CPU1")
	)
	(segment
		(start 29.974032 -72.387714)
		(end 29.722318 -72.136)
		(width 0.254)
		(layer "B.Cu")
		(net "A_TSENSE_PVCCIN_CPU1")
	)
	(segment
		(start 30.469332 -64.259714)
		(end 29.974032 -64.259714)
		(width 0.254)
		(layer "B.Cu")
		(net "A_TSENSE_PVCCIN_CPU1")
	)
	(segment
		(start 28.12796 -61.051694)
		(end 28.508706 -61.43244)
		(width 0.254)
		(layer "B.Cu")
		(net "A_TSENSE_PVCCIN_CPU1")
	)
	(segment
		(start 28.115768 -61.039502)
		(end 28.115768 -56.856376)
		(width 0.254)
		(layer "B.Cu")
		(net "A_TSENSE_PVCCIN_CPU1")
	)
	(segment
		(start 29.562806 -69.04355)
		(end 30.40634 -69.887084)
		(width 0.254)
		(layer "B.Cu")
		(net "A_TSENSE_PVCCIN_CPU1")
	)
	(segment
		(start 29.0068 -72.136)
		(end 28.7528 -72.39)
		(width 0.254)
		(layer "B.Cu")
		(net "A_TSENSE_PVCCIN_CPU1")
	)
	(segment
		(start 30.988 -64.262)
		(end 30.471618 -64.262)
		(width 0.254)
		(layer "B.Cu")
		(net "A_TSENSE_PVCCIN_CPU1")
	)
	(segment
		(start 29.0449 -80.264)
		(end 29.722318 -80.264)
		(width 0.254)
		(layer "B.Cu")
		(net "A_TSENSE_PVCCIN_CPU1")
	)
	(segment
		(start 28.12796 -61.051694)
		(end 28.115768 -61.039502)
		(width 0.254)
		(layer "B.Cu")
		(net "A_TSENSE_PVCCIN_CPU1")
	)
	(segment
		(start 29.198316 -64.050164)
		(end 28.803346 -64.445134)
		(width 0.254)
		(layer "B.Cu")
		(net "A_TSENSE_PVCCIN_CPU1")
	)
	(segment
		(start 31.0134 -80.4926)
		(end 29.997146 -80.4926)
		(width 0.254)
		(layer "B.Cu")
		(net "A_TSENSE_PVCCIN_CPU1")
	)
	(segment
		(start 28.7528 -76.271628)
		(end 30.282388 -77.801216)
		(width 0.254)
		(layer "B.Cu")
		(net "A_TSENSE_PVCCIN_CPU1")
	)
	(segment
		(start 29.722318 -80.264)
		(end 29.974032 -80.515714)
		(width 0.254)
		(layer "B.Cu")
		(net "A_TSENSE_PVCCIN_CPU1")
	)
	(segment
		(start 29.974032 -72.387714)
		(end 30.200346 -72.1614)
		(width 0.254)
		(layer "B.Cu")
		(net "A_TSENSE_PVCCIN_CPU1")
	)
	(segment
		(start 29.619448 -88.28913)
		(end 29.25572 -88.28913)
		(width 0.254)
		(layer "B.Cu")
		(net "A_TSENSE_PVCCIN_CPU1")
	)
	(segment
		(start 28.7528 -72.39)
		(end 28.7528 -76.271628)
		(width 0.254)
		(layer "B.Cu")
		(net "A_TSENSE_PVCCIN_CPU1")
	)
	(segment
		(start 29.729176 -55.886858)
		(end 29.974032 -56.131714)
		(width 0.254)
		(layer "B.Cu")
		(net "A_TSENSE_PVCCIN_CPU1")
	)
	(segment
		(start 30.378146 -55.7276)
		(end 30.988 -55.7276)
		(width 0.254)
		(layer "B.Cu")
		(net "A_TSENSE_PVCCIN_CPU1")
	)
	(segment
		(start 29.764482 -64.050164)
		(end 29.198316 -64.050164)
		(width 0.254)
		(layer "B.Cu")
		(net "A_TSENSE_PVCCIN_CPU1")
	)
	(segment
		(start 30.282388 -79.03083)
		(end 31.0134 -79.761842)
		(width 0.254)
		(layer "B.Cu")
		(net "A_TSENSE_PVCCIN_CPU1")
	)
	(segment
		(start 28.803346 -64.445134)
		(end 28.803346 -66.878454)
		(width 0.254)
		(layer "B.Cu")
		(net "A_TSENSE_PVCCIN_CPU1")
	)
	(segment
		(start 30.200346 -72.1614)
		(end 31.0134 -72.1614)
		(width 0.254)
		(layer "B.Cu")
		(net "A_TSENSE_PVCCIN_CPU1")
	)
	(segment
		(start 29.083 -91.95308)
		(end 29.3116 -92.18168)
		(width 0.254)
		(layer "In9.Cu")
		(net "A_TSENSE_PVCCIN_CPU1")
	)
	(segment
		(start 28.39847 -96.18853)
		(end 27.2796 -97.3074)
		(width 0.254)
		(layer "In9.Cu")
		(net "A_TSENSE_PVCCIN_CPU1")
	)
	(segment
		(start 28.39847 -94.96933)
		(end 28.39847 -96.18853)
		(width 0.254)
		(layer "In9.Cu")
		(net "A_TSENSE_PVCCIN_CPU1")
	)
	(segment
		(start 29.083 -90.859864)
		(end 29.083 -91.95308)
		(width 0.254)
		(layer "In9.Cu")
		(net "A_TSENSE_PVCCIN_CPU1")
	)
	(segment
		(start 30.24886 -88.918542)
		(end 30.24886 -90.033856)
		(width 0.254)
		(layer "In9.Cu")
		(net "A_TSENSE_PVCCIN_CPU1")
	)
	(segment
		(start 29.3116 -92.18168)
		(end 29.3116 -94.0562)
		(width 0.254)
		(layer "In9.Cu")
		(net "A_TSENSE_PVCCIN_CPU1")
	)
	(segment
		(start 19.002756 -97.3074)
		(end 18.9992 -97.310956)
		(width 0.254)
		(layer "In9.Cu")
		(net "A_TSENSE_PVCCIN_CPU1")
	)
	(segment
		(start 29.858716 -90.424)
		(end 29.518864 -90.424)
		(width 0.254)
		(layer "In9.Cu")
		(net "A_TSENSE_PVCCIN_CPU1")
	)
	(segment
		(start 27.2796 -97.3074)
		(end 19.002756 -97.3074)
		(width 0.254)
		(layer "In9.Cu")
		(net "A_TSENSE_PVCCIN_CPU1")
	)
	(segment
		(start 29.974032 -88.643714)
		(end 30.24886 -88.918542)
		(width 0.254)
		(layer "In9.Cu")
		(net "A_TSENSE_PVCCIN_CPU1")
	)
	(segment
		(start 30.24886 -90.033856)
		(end 29.858716 -90.424)
		(width 0.254)
		(layer "In9.Cu")
		(net "A_TSENSE_PVCCIN_CPU1")
	)
	(segment
		(start 29.3116 -94.0562)
		(end 28.39847 -94.96933)
		(width 0.254)
		(layer "In9.Cu")
		(net "A_TSENSE_PVCCIN_CPU1")
	)
	(segment
		(start 29.518864 -90.424)
		(end 29.083 -90.859864)
		(width 0.254)
		(layer "In9.Cu")
		(net "A_TSENSE_PVCCIN_CPU1")
	)
	(segment
		(start 397.64335 -121.01576)
		(end 398.13865 -121.245884)
		(width 0.10795)
		(layer "F.Cu")
		(net "TP_USB3_P06_TXP")
	)
	(via
		(at 398.13865 -121.245884)
		(size 0.508)
		(drill 0.254)
		(layers "F.Cu" "B.Cu")
		(net "TP_USB3_P06_TXP")
	)
	(segment
		(start 397.558768 -120.347994)
		(end 397.64335 -120.387364)
		(width 0.10795)
		(layer "F.Cu")
		(net "TP_USB3_P06_TXN")
	)
	(segment
		(start 397.470376 -120.3071)
		(end 397.558768 -120.347994)
		(width 0.10795)
		(layer "F.Cu")
		(net "TP_USB3_P06_TXN")
	)
	(segment
		(start 397.14805 -120.15724)
		(end 397.470376 -120.3071)
		(width 0.10795)
		(layer "F.Cu")
		(net "TP_USB3_P06_TXN")
	)
	(via
		(at 397.64335 -120.387364)
		(size 0.508)
		(drill 0.254)
		(layers "F.Cu" "B.Cu")
		(net "TP_USB3_P06_TXN")
	)
	(segment
		(start 393.7508 -126.593346)
		(end 393.7508 -129.184654)
		(width 0.0889)
		(layer "F.Cu")
		(net "TP_USB3_P06_RXP")
	)
	(segment
		(start 393.953746 -129.3876)
		(end 394.6017 -129.3876)
		(width 0.0889)
		(layer "F.Cu")
		(net "TP_USB3_P06_RXP")
	)
	(segment
		(start 393.7508 -129.184654)
		(end 393.953746 -129.3876)
		(width 0.0889)
		(layer "F.Cu")
		(net "TP_USB3_P06_RXP")
	)
	(segment
		(start 393.984988 -125.33503)
		(end 393.968986 -125.38075)
		(width 0.0889)
		(layer "F.Cu")
		(net "TP_USB3_P06_RXP")
	)
	(segment
		(start 393.697714 -125.994668)
		(end 393.697714 -126.34087)
		(width 0.0889)
		(layer "F.Cu")
		(net "TP_USB3_P06_RXP")
	)
	(segment
		(start 393.968986 -125.38075)
		(end 393.93241 -125.485652)
		(width 0.0889)
		(layer "F.Cu")
		(net "TP_USB3_P06_RXP")
	)
	(segment
		(start 393.93241 -125.485652)
		(end 393.785344 -125.907038)
		(width 0.0889)
		(layer "F.Cu")
		(net "TP_USB3_P06_RXP")
	)
	(segment
		(start 394.6017 -129.3876)
		(end 395.081252 -129.468118)
		(width 0.0889)
		(layer "F.Cu")
		(net "TP_USB3_P06_RXP")
	)
	(segment
		(start 393.697714 -126.34087)
		(end 393.7508 -126.593346)
		(width 0.0889)
		(layer "F.Cu")
		(net "TP_USB3_P06_RXP")
	)
	(segment
		(start 393.785344 -125.907038)
		(end 393.697714 -125.994668)
		(width 0.0889)
		(layer "F.Cu")
		(net "TP_USB3_P06_RXP")
	)
	(via
		(at 395.081252 -129.468118)
		(size 0.508)
		(drill 0.254)
		(layers "F.Cu" "B.Cu")
		(net "TP_USB3_P06_RXP")
	)
	(segment
		(start 393.984988 -127.476758)
		(end 393.984988 -127.298958)
		(width 0.0889)
		(layer "F.Cu")
		(net "TP_USB3_P06_RXN")
	)
	(segment
		(start 393.984988 -128.94183)
		(end 394.081 -128.845818)
		(width 0.0889)
		(layer "F.Cu")
		(net "TP_USB3_P06_RXN")
	)
	(segment
		(start 393.984988 -126.06274)
		(end 393.984988 -126.165102)
		(width 0.0889)
		(layer "F.Cu")
		(net "TP_USB3_P06_RXN")
	)
	(segment
		(start 393.984988 -128.572006)
		(end 393.984988 -128.394206)
		(width 0.0889)
		(layer "F.Cu")
		(net "TP_USB3_P06_RXN")
	)
	(segment
		(start 393.984988 -129.149348)
		(end 393.984988 -128.94183)
		(width 0.0889)
		(layer "F.Cu")
		(net "TP_USB3_P06_RXN")
	)
	(segment
		(start 394.111988 -126.5428)
		(end 394.199618 -126.5428)
		(width 0.0889)
		(layer "F.Cu")
		(net "TP_USB3_P06_RXN")
	)
	(segment
		(start 394.081 -128.298194)
		(end 394.081 -128.120394)
		(width 0.0889)
		(layer "F.Cu")
		(net "TP_USB3_P06_RXN")
	)
	(segment
		(start 393.984988 -126.929134)
		(end 393.984988 -126.6698)
		(width 0.0889)
		(layer "F.Cu")
		(net "TP_USB3_P06_RXN")
	)
	(segment
		(start 394.71727 -129.1971)
		(end 394.03274 -129.1971)
		(width 0.0889)
		(layer "F.Cu")
		(net "TP_USB3_P06_RXN")
	)
	(segment
		(start 394.081 -127.202946)
		(end 394.081 -127.025146)
		(width 0.0889)
		(layer "F.Cu")
		(net "TP_USB3_P06_RXN")
	)
	(segment
		(start 394.288518 -126.06274)
		(end 394.199618 -125.97384)
		(width 0.0889)
		(layer "F.Cu")
		(net "TP_USB3_P06_RXN")
	)
	(segment
		(start 394.199618 -125.97384)
		(end 394.073888 -125.97384)
		(width 0.0889)
		(layer "F.Cu")
		(net "TP_USB3_P06_RXN")
	)
	(segment
		(start 393.984988 -127.298958)
		(end 394.081 -127.202946)
		(width 0.0889)
		(layer "F.Cu")
		(net "TP_USB3_P06_RXN")
	)
	(segment
		(start 394.081 -127.75057)
		(end 394.081 -127.57277)
		(width 0.0889)
		(layer "F.Cu")
		(net "TP_USB3_P06_RXN")
	)
	(segment
		(start 393.984988 -127.846582)
		(end 394.081 -127.75057)
		(width 0.0889)
		(layer "F.Cu")
		(net "TP_USB3_P06_RXN")
	)
	(segment
		(start 394.081 -127.57277)
		(end 393.984988 -127.476758)
		(width 0.0889)
		(layer "F.Cu")
		(net "TP_USB3_P06_RXN")
	)
	(segment
		(start 394.03274 -129.1971)
		(end 393.984988 -129.149348)
		(width 0.0889)
		(layer "F.Cu")
		(net "TP_USB3_P06_RXN")
	)
	(segment
		(start 394.081 -128.120394)
		(end 393.984988 -128.024382)
		(width 0.0889)
		(layer "F.Cu")
		(net "TP_USB3_P06_RXN")
	)
	(segment
		(start 393.984988 -126.6698)
		(end 394.111988 -126.5428)
		(width 0.0889)
		(layer "F.Cu")
		(net "TP_USB3_P06_RXN")
	)
	(segment
		(start 394.288518 -126.4539)
		(end 394.288518 -126.06274)
		(width 0.0889)
		(layer "F.Cu")
		(net "TP_USB3_P06_RXN")
	)
	(segment
		(start 394.073888 -125.97384)
		(end 393.984988 -126.06274)
		(width 0.0889)
		(layer "F.Cu")
		(net "TP_USB3_P06_RXN")
	)
	(segment
		(start 394.081 -127.025146)
		(end 393.984988 -126.929134)
		(width 0.0889)
		(layer "F.Cu")
		(net "TP_USB3_P06_RXN")
	)
	(segment
		(start 394.081 -128.845818)
		(end 394.081 -128.668018)
		(width 0.0889)
		(layer "F.Cu")
		(net "TP_USB3_P06_RXN")
	)
	(segment
		(start 393.984988 -128.024382)
		(end 393.984988 -127.846582)
		(width 0.0889)
		(layer "F.Cu")
		(net "TP_USB3_P06_RXN")
	)
	(segment
		(start 395.081252 -128.833118)
		(end 394.71727 -129.1971)
		(width 0.0889)
		(layer "F.Cu")
		(net "TP_USB3_P06_RXN")
	)
	(segment
		(start 394.199618 -126.5428)
		(end 394.288518 -126.4539)
		(width 0.0889)
		(layer "F.Cu")
		(net "TP_USB3_P06_RXN")
	)
	(segment
		(start 394.081 -128.668018)
		(end 393.984988 -128.572006)
		(width 0.0889)
		(layer "F.Cu")
		(net "TP_USB3_P06_RXN")
	)
	(segment
		(start 393.984988 -128.394206)
		(end 394.081 -128.298194)
		(width 0.0889)
		(layer "F.Cu")
		(net "TP_USB3_P06_RXN")
	)
	(via
		(at 395.081252 -128.833118)
		(size 0.508)
		(drill 0.254)
		(layers "F.Cu" "B.Cu")
		(net "TP_USB3_P06_RXN")
	)
	(segment
		(start 396.15745 -120.15724)
		(end 396.65275 -120.387364)
		(width 0.10795)
		(layer "F.Cu")
		(net "TP_USB3_P05_TXP")
	)
	(via
		(at 396.65275 -120.387364)
		(size 0.508)
		(drill 0.254)
		(layers "F.Cu" "B.Cu")
		(net "TP_USB3_P05_TXP")
	)
	(segment
		(start 396.65275 -119.29872)
		(end 397.14805 -119.528844)
		(width 0.10795)
		(layer "F.Cu")
		(net "TP_USB3_P05_TXN")
	)
	(via
		(at 397.14805 -119.528844)
		(size 0.508)
		(drill 0.254)
		(layers "F.Cu" "B.Cu")
		(net "TP_USB3_P05_TXN")
	)
	(segment
		(start 394.485114 -124.919994)
		(end 394.696442 -125.485652)
		(width 0.0889)
		(layer "F.Cu")
		(net "TP_USB3_P05_RXP")
	)
	(segment
		(start 394.716254 -125.538992)
		(end 394.79855 -125.621288)
		(width 0.0889)
		(layer "F.Cu")
		(net "TP_USB3_P05_RXP")
	)
	(segment
		(start 394.79855 -125.621288)
		(end 394.79855 -125.900688)
		(width 0.0889)
		(layer "F.Cu")
		(net "TP_USB3_P05_RXP")
	)
	(segment
		(start 394.9065 -126.53772)
		(end 394.9065 -126.659894)
		(width 0.0889)
		(layer "F.Cu")
		(net "TP_USB3_P05_RXP")
	)
	(segment
		(start 394.696442 -125.485652)
		(end 394.716254 -125.538992)
		(width 0.0889)
		(layer "F.Cu")
		(net "TP_USB3_P05_RXP")
	)
	(segment
		(start 394.68298 -126.3142)
		(end 394.9065 -126.53772)
		(width 0.0889)
		(layer "F.Cu")
		(net "TP_USB3_P05_RXP")
	)
	(segment
		(start 394.79855 -125.900688)
		(end 394.68298 -126.016258)
		(width 0.0889)
		(layer "F.Cu")
		(net "TP_USB3_P05_RXP")
	)
	(segment
		(start 394.68298 -126.016258)
		(end 394.68298 -126.3142)
		(width 0.0889)
		(layer "F.Cu")
		(net "TP_USB3_P05_RXP")
	)
	(segment
		(start 395.09954 -126.807722)
		(end 395.09954 -126.86665)
		(width 0.0889)
		(layer "F.Cu")
		(net "TP_USB3_P05_RXP")
	)
	(segment
		(start 394.9954 -126.748794)
		(end 395.040612 -126.748794)
		(width 0.0889)
		(layer "F.Cu")
		(net "TP_USB3_P05_RXP")
	)
	(segment
		(start 394.9065 -126.659894)
		(end 394.9954 -126.748794)
		(width 0.0889)
		(layer "F.Cu")
		(net "TP_USB3_P05_RXP")
	)
	(segment
		(start 395.040612 -126.748794)
		(end 395.09954 -126.807722)
		(width 0.0889)
		(layer "F.Cu")
		(net "TP_USB3_P05_RXP")
	)
	(via
		(at 395.09954 -126.86665)
		(size 0.508)
		(drill 0.254)
		(layers "F.Cu" "B.Cu")
		(net "TP_USB3_P05_RXP")
	)
	(segment
		(start 394.6525 -127.121666)
		(end 394.797534 -127.2667)
		(width 0.0889)
		(layer "F.Cu")
		(net "TP_USB3_P05_RXN")
	)
	(segment
		(start 394.485114 -125.750066)
		(end 394.49248 -125.757432)
		(width 0.0889)
		(layer "F.Cu")
		(net "TP_USB3_P05_RXN")
	)
	(segment
		(start 394.6525 -126.812294)
		(end 394.6525 -127.121666)
		(width 0.0889)
		(layer "F.Cu")
		(net "TP_USB3_P05_RXN")
	)
	(segment
		(start 395.0335 -127.2667)
		(end 395.09954 -127.33274)
		(width 0.0889)
		(layer "F.Cu")
		(net "TP_USB3_P05_RXN")
	)
	(segment
		(start 395.09954 -127.33274)
		(end 395.09954 -127.50165)
		(width 0.0889)
		(layer "F.Cu")
		(net "TP_USB3_P05_RXN")
	)
	(segment
		(start 394.716 -126.748794)
		(end 394.6525 -126.812294)
		(width 0.0889)
		(layer "F.Cu")
		(net "TP_USB3_P05_RXN")
	)
	(segment
		(start 394.797534 -127.2667)
		(end 395.0335 -127.2667)
		(width 0.0889)
		(layer "F.Cu")
		(net "TP_USB3_P05_RXN")
	)
	(segment
		(start 394.716 -126.616714)
		(end 394.716 -126.748794)
		(width 0.0889)
		(layer "F.Cu")
		(net "TP_USB3_P05_RXN")
	)
	(segment
		(start 394.49248 -126.393194)
		(end 394.716 -126.616714)
		(width 0.0889)
		(layer "F.Cu")
		(net "TP_USB3_P05_RXN")
	)
	(segment
		(start 394.49248 -125.757432)
		(end 394.49248 -126.393194)
		(width 0.0889)
		(layer "F.Cu")
		(net "TP_USB3_P05_RXN")
	)
	(via
		(at 395.09954 -127.50165)
		(size 0.508)
		(drill 0.254)
		(layers "F.Cu" "B.Cu")
		(net "TP_USB3_P05_RXN")
	)
	(segment
		(start 31.02991 -88.45169)
		(end 30.430724 -88.45169)
		(width 0.1016)
		(layer "F.Cu")
		(net "VR_PVCCIN_CPU1_PH5_OCSET")
	)
	(segment
		(start 30.430724 -88.45169)
		(end 30.160214 -88.18118)
		(width 0.1016)
		(layer "F.Cu")
		(net "VR_PVCCIN_CPU1_PH5_OCSET")
	)
	(segment
		(start 28.3464 -89.1794)
		(end 28.794964 -88.730836)
		(width 0.10795)
		(layer "F.Cu")
		(net "VR_PVCCIN_CPU1_PH5_OCSET")
	)
	(segment
		(start 27.05354 -89.1794)
		(end 28.3464 -89.1794)
		(width 0.10795)
		(layer "F.Cu")
		(net "VR_PVCCIN_CPU1_PH5_OCSET")
	)
	(segment
		(start 29.24683 -88.540844)
		(end 28.794964 -88.540844)
		(width 0.1016)
		(layer "F.Cu")
		(net "VR_PVCCIN_CPU1_PH5_OCSET")
	)
	(segment
		(start 29.606494 -88.18118)
		(end 29.24683 -88.540844)
		(width 0.1016)
		(layer "F.Cu")
		(net "VR_PVCCIN_CPU1_PH5_OCSET")
	)
	(segment
		(start 28.794964 -88.730836)
		(end 28.794964 -88.540844)
		(width 0.10795)
		(layer "F.Cu")
		(net "VR_PVCCIN_CPU1_PH5_OCSET")
	)
	(segment
		(start 30.160214 -88.18118)
		(end 29.606494 -88.18118)
		(width 0.1016)
		(layer "F.Cu")
		(net "VR_PVCCIN_CPU1_PH5_OCSET")
	)
	(via
		(at 27.05354 -89.1794)
		(size 0.762)
		(drill 0.381)
		(layers "F.Cu" "B.Cu")
		(net "VR_PVCCIN_CPU1_PH5_OCSET")
	)
	(segment
		(start 29.53004 -79.94396)
		(end 29.31414 -80.15986)
		(width 0.1016)
		(layer "F.Cu")
		(net "VR_PVCCIN_CPU1_PH4_OCSET")
	)
	(segment
		(start 29.31414 -80.15986)
		(end 29.2989 -80.15986)
		(width 0.1016)
		(layer "F.Cu")
		(net "VR_PVCCIN_CPU1_PH4_OCSET")
	)
	(segment
		(start 30.117034 -79.94396)
		(end 29.53004 -79.94396)
		(width 0.1016)
		(layer "F.Cu")
		(net "VR_PVCCIN_CPU1_PH4_OCSET")
	)
	(segment
		(start 28.438348 -80.3148)
		(end 29.14396 -80.3148)
		(width 0.1016)
		(layer "F.Cu")
		(net "VR_PVCCIN_CPU1_PH4_OCSET")
	)
	(segment
		(start 30.496764 -80.32369)
		(end 30.117034 -79.94396)
		(width 0.1016)
		(layer "F.Cu")
		(net "VR_PVCCIN_CPU1_PH4_OCSET")
	)
	(segment
		(start 31.02991 -80.32369)
		(end 30.496764 -80.32369)
		(width 0.1016)
		(layer "F.Cu")
		(net "VR_PVCCIN_CPU1_PH4_OCSET")
	)
	(segment
		(start 29.14396 -80.3148)
		(end 29.2989 -80.15986)
		(width 0.1016)
		(layer "F.Cu")
		(net "VR_PVCCIN_CPU1_PH4_OCSET")
	)
	(via
		(at 29.2989 -80.15986)
		(size 0.762)
		(drill 0.381)
		(layers "F.Cu" "B.Cu")
		(net "VR_PVCCIN_CPU1_PH4_OCSET")
	)
	(segment
		(start 367.945162 -78.294738)
		(end 368.344958 -77.894942)
		(width 0.10795)
		(layer "F.Cu")
		(net "FM_CPU1_VRM_OSC_EN")
	)
	(via
		(at 367.945162 -78.294738)
		(size 0.4572)
		(drill 0.2032)
		(layers "F.Cu" "B.Cu")
		(net "FM_CPU1_VRM_OSC_EN")
	)
	(via
		(at 366.75822 -78.69936)
		(size 0.508)
		(drill 0.254)
		(layers "F.Cu" "B.Cu")
		(net "FM_CPU1_VRM_OSC_EN")
	)
	(segment
		(start 367.729262 -78.294738)
		(end 367.945162 -78.294738)
		(width 0.10795)
		(layer "B.Cu")
		(net "FM_CPU1_VRM_OSC_EN")
	)
	(segment
		(start 365.506 -79.0956)
		(end 365.506 -78.3336)
		(width 0.10795)
		(layer "B.Cu")
		(net "FM_CPU1_VRM_OSC_EN")
	)
	(segment
		(start 365.829596 -78.3336)
		(end 366.195356 -78.69936)
		(width 0.10795)
		(layer "B.Cu")
		(net "FM_CPU1_VRM_OSC_EN")
	)
	(segment
		(start 367.32464 -78.69936)
		(end 367.729262 -78.294738)
		(width 0.10795)
		(layer "B.Cu")
		(net "FM_CPU1_VRM_OSC_EN")
	)
	(segment
		(start 365.506 -78.3336)
		(end 365.829596 -78.3336)
		(width 0.10795)
		(layer "B.Cu")
		(net "FM_CPU1_VRM_OSC_EN")
	)
	(segment
		(start 366.75822 -78.69936)
		(end 367.32464 -78.69936)
		(width 0.10795)
		(layer "B.Cu")
		(net "FM_CPU1_VRM_OSC_EN")
	)
	(segment
		(start 366.195356 -78.69936)
		(end 366.75822 -78.69936)
		(width 0.10795)
		(layer "B.Cu")
		(net "FM_CPU1_VRM_OSC_EN")
	)
	(segment
		(start 163.59251 -109.655102)
		(end 164.408358 -110.47095)
		(width 0.10795)
		(layer "F.Cu")
		(net "FM_CPU1_VRM_322M_156M_OSC_EN")
	)
	(segment
		(start 164.408358 -110.47095)
		(end 164.615114 -110.47095)
		(width 0.10795)
		(layer "F.Cu")
		(net "FM_CPU1_VRM_322M_156M_OSC_EN")
	)
	(segment
		(start 158.878778 -109.655102)
		(end 163.59251 -109.655102)
		(width 0.10795)
		(layer "F.Cu")
		(net "FM_CPU1_VRM_322M_156M_OSC_EN")
	)
	(segment
		(start 155.3972 -114.00663)
		(end 155.3972 -113.13668)
		(width 0.10795)
		(layer "F.Cu")
		(net "FM_CPU1_VRM_322M_156M_OSC_EN")
	)
	(segment
		(start 155.3972 -113.13668)
		(end 158.878778 -109.655102)
		(width 0.10795)
		(layer "F.Cu")
		(net "FM_CPU1_VRM_322M_156M_OSC_EN")
	)
	(segment
		(start 154.734514 -114.669316)
		(end 155.3972 -114.00663)
		(width 0.10795)
		(layer "F.Cu")
		(net "FM_CPU1_VRM_322M_156M_OSC_EN")
	)
	(via
		(at 334.899 -137.1346)
		(size 0.508)
		(drill 0.254)
		(layers "F.Cu" "B.Cu")
		(net "FM_CPU1_VRM_322M_156M_OSC_EN")
	)
	(via
		(at 154.734514 -114.669316)
		(size 0.508)
		(drill 0.254)
		(layers "F.Cu" "B.Cu")
		(net "FM_CPU1_VRM_322M_156M_OSC_EN")
	)
	(via
		(at 373.445278 -81.769966)
		(size 0.508)
		(drill 0.254)
		(layers "F.Cu" "B.Cu")
		(net "FM_CPU1_VRM_322M_156M_OSC_EN")
	)
	(via
		(at 372.2878 -144.907)
		(size 0.508)
		(drill 0.254)
		(layers "F.Cu" "B.Cu")
		(net "FM_CPU1_VRM_322M_156M_OSC_EN")
	)
	(via
		(at 373.329454 -80.8228)
		(size 0.6604)
		(drill 0.3302)
		(layers "F.Cu" "B.Cu")
		(net "FM_CPU1_VRM_322M_156M_OSC_EN")
	)
	(via
		(at 377.83135 -122.104404)
		(size 0.508)
		(drill 0.254)
		(layers "F.Cu" "B.Cu")
		(net "FM_CPU1_VRM_322M_156M_OSC_EN")
	)
	(segment
		(start 373.329454 -81.654142)
		(end 373.445278 -81.769966)
		(width 0.10795)
		(layer "B.Cu")
		(net "FM_CPU1_VRM_322M_156M_OSC_EN")
	)
	(segment
		(start 367.562384 -78.936342)
		(end 367.786666 -78.71206)
		(width 0.10795)
		(layer "B.Cu")
		(net "FM_CPU1_VRM_322M_156M_OSC_EN")
	)
	(segment
		(start 371.786404 -77.91196)
		(end 372.103396 -77.91196)
		(width 0.10795)
		(layer "B.Cu")
		(net "FM_CPU1_VRM_322M_156M_OSC_EN")
	)
	(segment
		(start 373.162068 -79.736188)
		(end 373.162068 -80.05318)
		(width 0.10795)
		(layer "B.Cu")
		(net "FM_CPU1_VRM_322M_156M_OSC_EN")
	)
	(segment
		(start 368.903758 -78.71206)
		(end 369.1382 -78.946502)
		(width 0.10795)
		(layer "B.Cu")
		(net "FM_CPU1_VRM_322M_156M_OSC_EN")
	)
	(segment
		(start 369.1382 -79.229204)
		(end 369.386612 -79.477616)
		(width 0.10795)
		(layer "B.Cu")
		(net "FM_CPU1_VRM_322M_156M_OSC_EN")
	)
	(segment
		(start 372.994682 -78.60665)
		(end 373.100092 -78.71206)
		(width 0.10795)
		(layer "B.Cu")
		(net "FM_CPU1_VRM_322M_156M_OSC_EN")
	)
	(segment
		(start 364.683802 -79.518002)
		(end 367.263426 -79.518002)
		(width 0.10795)
		(layer "B.Cu")
		(net "FM_CPU1_VRM_322M_156M_OSC_EN")
	)
	(segment
		(start 370.503704 -79.477616)
		(end 370.7384 -79.24292)
		(width 0.10795)
		(layer "B.Cu")
		(net "FM_CPU1_VRM_322M_156M_OSC_EN")
	)
	(segment
		(start 373.164354 -80.055466)
		(end 373.164354 -80.6577)
		(width 0.10795)
		(layer "B.Cu")
		(net "FM_CPU1_VRM_322M_156M_OSC_EN")
	)
	(segment
		(start 372.103396 -77.91196)
		(end 372.327678 -78.136242)
		(width 0.10795)
		(layer "B.Cu")
		(net "FM_CPU1_VRM_322M_156M_OSC_EN")
	)
	(segment
		(start 373.162068 -80.05318)
		(end 373.164354 -80.055466)
		(width 0.10795)
		(layer "B.Cu")
		(net "FM_CPU1_VRM_322M_156M_OSC_EN")
	)
	(segment
		(start 373.927624 -78.936342)
		(end 373.927624 -79.253334)
		(width 0.10795)
		(layer "B.Cu")
		(net "FM_CPU1_VRM_322M_156M_OSC_EN")
	)
	(segment
		(start 372.327678 -78.136242)
		(end 372.327678 -78.359)
		(width 0.10795)
		(layer "B.Cu")
		(net "FM_CPU1_VRM_322M_156M_OSC_EN")
	)
	(segment
		(start 370.7384 -78.959964)
		(end 371.786404 -77.91196)
		(width 0.10795)
		(layer "B.Cu")
		(net "FM_CPU1_VRM_322M_156M_OSC_EN")
	)
	(segment
		(start 372.575328 -78.60665)
		(end 372.994682 -78.60665)
		(width 0.10795)
		(layer "B.Cu")
		(net "FM_CPU1_VRM_322M_156M_OSC_EN")
	)
	(segment
		(start 364.617 -79.4512)
		(end 364.683802 -79.518002)
		(width 0.10795)
		(layer "B.Cu")
		(net "FM_CPU1_VRM_322M_156M_OSC_EN")
	)
	(segment
		(start 373.100092 -78.71206)
		(end 373.703342 -78.71206)
		(width 0.10795)
		(layer "B.Cu")
		(net "FM_CPU1_VRM_322M_156M_OSC_EN")
	)
	(segment
		(start 373.927624 -79.253334)
		(end 373.703342 -79.477616)
		(width 0.10795)
		(layer "B.Cu")
		(net "FM_CPU1_VRM_322M_156M_OSC_EN")
	)
	(segment
		(start 373.703342 -78.71206)
		(end 373.927624 -78.936342)
		(width 0.10795)
		(layer "B.Cu")
		(net "FM_CPU1_VRM_322M_156M_OSC_EN")
	)
	(segment
		(start 372.327678 -78.359)
		(end 372.575328 -78.60665)
		(width 0.10795)
		(layer "B.Cu")
		(net "FM_CPU1_VRM_322M_156M_OSC_EN")
	)
	(segment
		(start 373.329454 -80.8228)
		(end 373.329454 -81.654142)
		(width 0.10795)
		(layer "B.Cu")
		(net "FM_CPU1_VRM_322M_156M_OSC_EN")
	)
	(segment
		(start 364.617 -79.0956)
		(end 364.617 -79.4512)
		(width 0.10795)
		(layer "B.Cu")
		(net "FM_CPU1_VRM_322M_156M_OSC_EN")
	)
	(segment
		(start 373.164354 -80.6577)
		(end 373.329454 -80.8228)
		(width 0.10795)
		(layer "B.Cu")
		(net "FM_CPU1_VRM_322M_156M_OSC_EN")
	)
	(segment
		(start 370.7384 -79.24292)
		(end 370.7384 -78.959964)
		(width 0.10795)
		(layer "B.Cu")
		(net "FM_CPU1_VRM_322M_156M_OSC_EN")
	)
	(segment
		(start 369.386612 -79.477616)
		(end 370.503704 -79.477616)
		(width 0.10795)
		(layer "B.Cu")
		(net "FM_CPU1_VRM_322M_156M_OSC_EN")
	)
	(segment
		(start 367.562384 -79.219044)
		(end 367.562384 -78.936342)
		(width 0.10795)
		(layer "B.Cu")
		(net "FM_CPU1_VRM_322M_156M_OSC_EN")
	)
	(segment
		(start 369.1382 -78.946502)
		(end 369.1382 -79.229204)
		(width 0.10795)
		(layer "B.Cu")
		(net "FM_CPU1_VRM_322M_156M_OSC_EN")
	)
	(segment
		(start 367.263426 -79.518002)
		(end 367.562384 -79.219044)
		(width 0.10795)
		(layer "B.Cu")
		(net "FM_CPU1_VRM_322M_156M_OSC_EN")
	)
	(segment
		(start 373.42064 -79.477616)
		(end 373.162068 -79.736188)
		(width 0.10795)
		(layer "B.Cu")
		(net "FM_CPU1_VRM_322M_156M_OSC_EN")
	)
	(segment
		(start 373.703342 -79.477616)
		(end 373.42064 -79.477616)
		(width 0.10795)
		(layer "B.Cu")
		(net "FM_CPU1_VRM_322M_156M_OSC_EN")
	)
	(segment
		(start 367.786666 -78.71206)
		(end 368.903758 -78.71206)
		(width 0.10795)
		(layer "B.Cu")
		(net "FM_CPU1_VRM_322M_156M_OSC_EN")
	)
	(segment
		(start 354.560124 -143.91894)
		(end 359.31602 -143.91894)
		(width 0.089408)
		(layer "In4.Cu")
		(net "FM_CPU1_VRM_322M_156M_OSC_EN")
	)
	(segment
		(start 362.554774 -144.980152)
		(end 364.052104 -144.980152)
		(width 0.089408)
		(layer "In4.Cu")
		(net "FM_CPU1_VRM_322M_156M_OSC_EN")
	)
	(segment
		(start 369.038378 -147.620736)
		(end 371.14734 -145.511774)
		(width 0.089408)
		(layer "In4.Cu")
		(net "FM_CPU1_VRM_322M_156M_OSC_EN")
	)
	(segment
		(start 341.456772 -139.035028)
		(end 341.457026 -139.034774)
		(width 0.089408)
		(layer "In4.Cu")
		(net "FM_CPU1_VRM_322M_156M_OSC_EN")
	)
	(segment
		(start 341.75319 -139.034774)
		(end 343.777824 -141.059408)
		(width 0.089408)
		(layer "In4.Cu")
		(net "FM_CPU1_VRM_322M_156M_OSC_EN")
	)
	(segment
		(start 361.719368 -144.144746)
		(end 362.554774 -144.980152)
		(width 0.089408)
		(layer "In4.Cu")
		(net "FM_CPU1_VRM_322M_156M_OSC_EN")
	)
	(segment
		(start 351.700592 -141.059408)
		(end 354.560124 -143.91894)
		(width 0.089408)
		(layer "In4.Cu")
		(net "FM_CPU1_VRM_322M_156M_OSC_EN")
	)
	(segment
		(start 343.777824 -141.059408)
		(end 351.700592 -141.059408)
		(width 0.089408)
		(layer "In4.Cu")
		(net "FM_CPU1_VRM_322M_156M_OSC_EN")
	)
	(segment
		(start 337.979512 -138.056366)
		(end 338.958174 -139.035028)
		(width 0.089408)
		(layer "In4.Cu")
		(net "FM_CPU1_VRM_322M_156M_OSC_EN")
	)
	(segment
		(start 371.662198 -145.511774)
		(end 371.672612 -145.522188)
		(width 0.089408)
		(layer "In4.Cu")
		(net "FM_CPU1_VRM_322M_156M_OSC_EN")
	)
	(segment
		(start 334.899 -137.1346)
		(end 335.820766 -138.056366)
		(width 0.089408)
		(layer "In4.Cu")
		(net "FM_CPU1_VRM_322M_156M_OSC_EN")
	)
	(segment
		(start 338.958174 -139.035028)
		(end 341.456772 -139.035028)
		(width 0.089408)
		(layer "In4.Cu")
		(net "FM_CPU1_VRM_322M_156M_OSC_EN")
	)
	(segment
		(start 359.31602 -143.91894)
		(end 359.541826 -144.144746)
		(width 0.089408)
		(layer "In4.Cu")
		(net "FM_CPU1_VRM_322M_156M_OSC_EN")
	)
	(segment
		(start 359.541826 -144.144746)
		(end 361.719368 -144.144746)
		(width 0.089408)
		(layer "In4.Cu")
		(net "FM_CPU1_VRM_322M_156M_OSC_EN")
	)
	(segment
		(start 366.692688 -147.620736)
		(end 369.038378 -147.620736)
		(width 0.089408)
		(layer "In4.Cu")
		(net "FM_CPU1_VRM_322M_156M_OSC_EN")
	)
	(segment
		(start 341.457026 -139.034774)
		(end 341.75319 -139.034774)
		(width 0.089408)
		(layer "In4.Cu")
		(net "FM_CPU1_VRM_322M_156M_OSC_EN")
	)
	(segment
		(start 364.052104 -144.980152)
		(end 366.692688 -147.620736)
		(width 0.089408)
		(layer "In4.Cu")
		(net "FM_CPU1_VRM_322M_156M_OSC_EN")
	)
	(segment
		(start 335.820766 -138.056366)
		(end 337.979512 -138.056366)
		(width 0.089408)
		(layer "In4.Cu")
		(net "FM_CPU1_VRM_322M_156M_OSC_EN")
	)
	(segment
		(start 371.14734 -145.511774)
		(end 371.662198 -145.511774)
		(width 0.089408)
		(layer "In4.Cu")
		(net "FM_CPU1_VRM_322M_156M_OSC_EN")
	)
	(segment
		(start 371.672612 -145.522188)
		(end 372.2878 -144.907)
		(width 0.089408)
		(layer "In4.Cu")
		(net "FM_CPU1_VRM_322M_156M_OSC_EN")
	)
	(segment
		(start 373.584978 -124.410216)
		(end 373.849646 -124.145548)
		(width 0.089408)
		(layer "In9.Cu")
		(net "FM_CPU1_VRM_322M_156M_OSC_EN")
	)
	(segment
		(start 372.2878 -144.907)
		(end 372.32336 -144.87144)
		(width 0.089408)
		(layer "In9.Cu")
		(net "FM_CPU1_VRM_322M_156M_OSC_EN")
	)
	(segment
		(start 371.094 -138.176)
		(end 370.022374 -137.104374)
		(width 0.089408)
		(layer "In9.Cu")
		(net "FM_CPU1_VRM_322M_156M_OSC_EN")
	)
	(segment
		(start 372.66626 -126.060708)
		(end 373.237252 -125.489716)
		(width 0.089408)
		(layer "In9.Cu")
		(net "FM_CPU1_VRM_322M_156M_OSC_EN")
	)
	(segment
		(start 373.584978 -124.41047)
		(end 373.584978 -124.410216)
		(width 0.089408)
		(layer "In9.Cu")
		(net "FM_CPU1_VRM_322M_156M_OSC_EN")
	)
	(segment
		(start 370.022374 -137.104374)
		(end 370.022374 -132.694426)
		(width 0.089408)
		(layer "In9.Cu")
		(net "FM_CPU1_VRM_322M_156M_OSC_EN")
	)
	(segment
		(start 373.872252 -124.145548)
		(end 374.94718 -123.07062)
		(width 0.089408)
		(layer "In9.Cu")
		(net "FM_CPU1_VRM_322M_156M_OSC_EN")
	)
	(segment
		(start 373.237252 -124.758196)
		(end 373.584978 -124.41047)
		(width 0.089408)
		(layer "In9.Cu")
		(net "FM_CPU1_VRM_322M_156M_OSC_EN")
	)
	(segment
		(start 374.94718 -123.07062)
		(end 376.865134 -123.07062)
		(width 0.089408)
		(layer "In9.Cu")
		(net "FM_CPU1_VRM_322M_156M_OSC_EN")
	)
	(segment
		(start 376.865134 -123.07062)
		(end 377.83135 -122.104404)
		(width 0.089408)
		(layer "In9.Cu")
		(net "FM_CPU1_VRM_322M_156M_OSC_EN")
	)
	(segment
		(start 370.5352 -132.1816)
		(end 370.9416 -132.1816)
		(width 0.089408)
		(layer "In9.Cu")
		(net "FM_CPU1_VRM_322M_156M_OSC_EN")
	)
	(segment
		(start 371.094 -140.8176)
		(end 371.094 -138.176)
		(width 0.089408)
		(layer "In9.Cu")
		(net "FM_CPU1_VRM_322M_156M_OSC_EN")
	)
	(segment
		(start 372.32336 -142.04696)
		(end 371.094 -140.8176)
		(width 0.089408)
		(layer "In9.Cu")
		(net "FM_CPU1_VRM_322M_156M_OSC_EN")
	)
	(segment
		(start 370.9416 -132.1816)
		(end 372.66626 -130.45694)
		(width 0.089408)
		(layer "In9.Cu")
		(net "FM_CPU1_VRM_322M_156M_OSC_EN")
	)
	(segment
		(start 373.237252 -125.489716)
		(end 373.237252 -124.758196)
		(width 0.089408)
		(layer "In9.Cu")
		(net "FM_CPU1_VRM_322M_156M_OSC_EN")
	)
	(segment
		(start 372.32336 -144.87144)
		(end 372.32336 -142.04696)
		(width 0.089408)
		(layer "In9.Cu")
		(net "FM_CPU1_VRM_322M_156M_OSC_EN")
	)
	(segment
		(start 372.66626 -130.45694)
		(end 372.66626 -126.060708)
		(width 0.089408)
		(layer "In9.Cu")
		(net "FM_CPU1_VRM_322M_156M_OSC_EN")
	)
	(segment
		(start 373.849646 -124.145548)
		(end 373.872252 -124.145548)
		(width 0.089408)
		(layer "In9.Cu")
		(net "FM_CPU1_VRM_322M_156M_OSC_EN")
	)
	(segment
		(start 370.022374 -132.694426)
		(end 370.5352 -132.1816)
		(width 0.089408)
		(layer "In9.Cu")
		(net "FM_CPU1_VRM_322M_156M_OSC_EN")
	)
	(segment
		(start 191.550798 -136.804654)
		(end 191.550798 -134.585202)
		(width 0.089408)
		(layer "In11.Cu")
		(net "FM_CPU1_VRM_322M_156M_OSC_EN")
	)
	(segment
		(start 195.498212 -157.234636)
		(end 193.171572 -154.907996)
		(width 0.089408)
		(layer "In11.Cu")
		(net "FM_CPU1_VRM_322M_156M_OSC_EN")
	)
	(segment
		(start 376.584464 -93.501464)
		(end 376.181112 -93.098112)
		(width 0.089408)
		(layer "In11.Cu")
		(net "FM_CPU1_VRM_322M_156M_OSC_EN")
	)
	(segment
		(start 380.21133 -96.279462)
		(end 380.21133 -95.723202)
		(width 0.089408)
		(layer "In11.Cu")
		(net "FM_CPU1_VRM_322M_156M_OSC_EN")
	)
	(segment
		(start 174.44085 -128.98755)
		(end 171.58335 -128.98755)
		(width 0.089408)
		(layer "In11.Cu")
		(net "FM_CPU1_VRM_322M_156M_OSC_EN")
	)
	(segment
		(start 378.23013 -112.00003)
		(end 378.23013 -111.63681)
		(width 0.089408)
		(layer "In11.Cu")
		(net "FM_CPU1_VRM_322M_156M_OSC_EN")
	)
	(segment
		(start 378.23013 -120.308624)
		(end 378.775722 -119.763032)
		(width 0.089408)
		(layer "In11.Cu")
		(net "FM_CPU1_VRM_322M_156M_OSC_EN")
	)
	(segment
		(start 265.646916 -156.817822)
		(end 265.32967 -157.135068)
		(width 0.089408)
		(layer "In11.Cu")
		(net "FM_CPU1_VRM_322M_156M_OSC_EN")
	)
	(segment
		(start 378.425964 -118.935246)
		(end 378.425964 -118.934992)
		(width 0.089408)
		(layer "In11.Cu")
		(net "FM_CPU1_VRM_322M_156M_OSC_EN")
	)
	(segment
		(start 378.72543 -112.826038)
		(end 378.72543 -112.49533)
		(width 0.089408)
		(layer "In11.Cu")
		(net "FM_CPU1_VRM_322M_156M_OSC_EN")
	)
	(segment
		(start 382.19253 -99.157282)
		(end 381.959104 -98.923856)
		(width 0.089408)
		(layer "In11.Cu")
		(net "FM_CPU1_VRM_322M_156M_OSC_EN")
	)
	(segment
		(start 377.775978 -116.24056)
		(end 377.775978 -115.921536)
		(width 0.089408)
		(layer "In11.Cu")
		(net "FM_CPU1_VRM_322M_156M_OSC_EN")
	)
	(segment
		(start 379.90907 -96.919542)
		(end 379.90907 -96.581722)
		(width 0.089408)
		(layer "In11.Cu")
		(net "FM_CPU1_VRM_322M_156M_OSC_EN")
	)
	(segment
		(start 377.990354 -108.24718)
		(end 378.22378 -108.013754)
		(width 0.089408)
		(layer "In11.Cu")
		(net "FM_CPU1_VRM_322M_156M_OSC_EN")
	)
	(segment
		(start 373.717312 -82.042)
		(end 373.445278 -81.769966)
		(width 0.089408)
		(layer "In11.Cu")
		(net "FM_CPU1_VRM_322M_156M_OSC_EN")
	)
	(segment
		(start 166.594536 -122.101356)
		(end 163.130992 -118.637812)
		(width 0.089408)
		(layer "In11.Cu")
		(net "FM_CPU1_VRM_322M_156M_OSC_EN")
	)
	(segment
		(start 378.763276 -117.497352)
		(end 378.340112 -117.074188)
		(width 0.089408)
		(layer "In11.Cu")
		(net "FM_CPU1_VRM_322M_156M_OSC_EN")
	)
	(segment
		(start 382.19253 -101.430582)
		(end 382.19253 -100.86213)
		(width 0.089408)
		(layer "In11.Cu")
		(net "FM_CPU1_VRM_322M_156M_OSC_EN")
	)
	(segment
		(start 321.595242 -156.817822)
		(end 265.646916 -156.817822)
		(width 0.089408)
		(layer "In11.Cu")
		(net "FM_CPU1_VRM_322M_156M_OSC_EN")
	)
	(segment
		(start 378.763276 -118.050818)
		(end 378.763276 -117.497352)
		(width 0.089408)
		(layer "In11.Cu")
		(net "FM_CPU1_VRM_322M_156M_OSC_EN")
	)
	(segment
		(start 193.171572 -154.707844)
		(end 193.171826 -154.70759)
		(width 0.089408)
		(layer "In11.Cu")
		(net "FM_CPU1_VRM_322M_156M_OSC_EN")
	)
	(segment
		(start 378.23013 -115.467384)
		(end 378.23013 -114.922808)
		(width 0.089408)
		(layer "In11.Cu")
		(net "FM_CPU1_VRM_322M_156M_OSC_EN")
	)
	(segment
		(start 158.845504 -115.6208)
		(end 155.685998 -115.6208)
		(width 0.089408)
		(layer "In11.Cu")
		(net "FM_CPU1_VRM_322M_156M_OSC_EN")
	)
	(segment
		(start 375.0056 -82.982816)
		(end 374.064784 -82.042)
		(width 0.089408)
		(layer "In11.Cu")
		(net "FM_CPU1_VRM_322M_156M_OSC_EN")
	)
	(segment
		(start 381.89027 -100.55987)
		(end 381.89027 -100.015802)
		(width 0.089408)
		(layer "In11.Cu")
		(net "FM_CPU1_VRM_322M_156M_OSC_EN")
	)
	(segment
		(start 377.852686 -108.24718)
		(end 377.990354 -108.24718)
		(width 0.089408)
		(layer "In11.Cu")
		(net "FM_CPU1_VRM_322M_156M_OSC_EN")
	)
	(segment
		(start 378.23013 -114.922808)
		(end 377.843034 -114.535712)
		(width 0.089408)
		(layer "In11.Cu")
		(net "FM_CPU1_VRM_322M_156M_OSC_EN")
	)
	(segment
		(start 380.732792 -103.314246)
		(end 379.73 -102.311454)
		(width 0.089408)
		(layer "In11.Cu")
		(net "FM_CPU1_VRM_322M_156M_OSC_EN")
	)
	(segment
		(start 167.804084 -122.886978)
		(end 167.018462 -122.101356)
		(width 0.089408)
		(layer "In11.Cu")
		(net "FM_CPU1_VRM_322M_156M_OSC_EN")
	)
	(segment
		(start 378.492004 -113.059464)
		(end 378.72543 -112.826038)
		(width 0.089408)
		(layer "In11.Cu")
		(net "FM_CPU1_VRM_322M_156M_OSC_EN")
	)
	(segment
		(start 382.19253 -100.86213)
		(end 381.89027 -100.55987)
		(width 0.089408)
		(layer "In11.Cu")
		(net "FM_CPU1_VRM_322M_156M_OSC_EN")
	)
	(segment
		(start 186.40806 -131.784344)
		(end 176.904904 -131.784344)
		(width 0.089408)
		(layer "In11.Cu")
		(net "FM_CPU1_VRM_322M_156M_OSC_EN")
	)
	(segment
		(start 168.287954 -124.782072)
		(end 167.804084 -124.298202)
		(width 0.089408)
		(layer "In11.Cu")
		(net "FM_CPU1_VRM_322M_156M_OSC_EN")
	)
	(segment
		(start 380.3396 -104.2162)
		(end 380.732792 -103.823008)
		(width 0.089408)
		(layer "In11.Cu")
		(net "FM_CPU1_VRM_322M_156M_OSC_EN")
	)
	(segment
		(start 161.862516 -118.637812)
		(end 158.845504 -115.6208)
		(width 0.089408)
		(layer "In11.Cu")
		(net "FM_CPU1_VRM_322M_156M_OSC_EN")
	)
	(segment
		(start 378.72543 -112.49533)
		(end 378.23013 -112.00003)
		(width 0.089408)
		(layer "In11.Cu")
		(net "FM_CPU1_VRM_322M_156M_OSC_EN")
	)
	(segment
		(start 378.340112 -117.074188)
		(end 378.340112 -116.804694)
		(width 0.089408)
		(layer "In11.Cu")
		(net "FM_CPU1_VRM_322M_156M_OSC_EN")
	)
	(segment
		(start 380.746 -105.82148)
		(end 380.746 -105.0544)
		(width 0.089408)
		(layer "In11.Cu")
		(net "FM_CPU1_VRM_322M_156M_OSC_EN")
	)
	(segment
		(start 378.358654 -118.45544)
		(end 378.763276 -118.050818)
		(width 0.089408)
		(layer "In11.Cu")
		(net "FM_CPU1_VRM_322M_156M_OSC_EN")
	)
	(segment
		(start 265.327384 -157.135068)
		(end 265.227816 -157.234636)
		(width 0.089408)
		(layer "In11.Cu")
		(net "FM_CPU1_VRM_322M_156M_OSC_EN")
	)
	(segment
		(start 167.804084 -124.298202)
		(end 167.804084 -122.886978)
		(width 0.089408)
		(layer "In11.Cu")
		(net "FM_CPU1_VRM_322M_156M_OSC_EN")
	)
	(segment
		(start 380.732792 -103.823008)
		(end 380.732792 -103.314246)
		(width 0.089408)
		(layer "In11.Cu")
		(net "FM_CPU1_VRM_322M_156M_OSC_EN")
	)
	(segment
		(start 378.340112 -116.804694)
		(end 377.775978 -116.24056)
		(width 0.089408)
		(layer "In11.Cu")
		(net "FM_CPU1_VRM_322M_156M_OSC_EN")
	)
	(segment
		(start 379.73 -102.311454)
		(end 379.73 -101.854)
		(width 0.089408)
		(layer "In11.Cu")
		(net "FM_CPU1_VRM_322M_156M_OSC_EN")
	)
	(segment
		(start 381.89027 -98.42627)
		(end 381.508 -98.044)
		(width 0.089408)
		(layer "In11.Cu")
		(net "FM_CPU1_VRM_322M_156M_OSC_EN")
	)
	(segment
		(start 167.018462 -122.101356)
		(end 166.594536 -122.101356)
		(width 0.089408)
		(layer "In11.Cu")
		(net "FM_CPU1_VRM_322M_156M_OSC_EN")
	)
	(segment
		(start 189.872874 -132.907278)
		(end 187.530994 -132.907278)
		(width 0.089408)
		(layer "In11.Cu")
		(net "FM_CPU1_VRM_322M_156M_OSC_EN")
	)
	(segment
		(start 379.482604 -107.448096)
		(end 379.71603 -107.21467)
		(width 0.089408)
		(layer "In11.Cu")
		(net "FM_CPU1_VRM_322M_156M_OSC_EN")
	)
	(segment
		(start 379.71603 -106.85145)
		(end 380.746 -105.82148)
		(width 0.089408)
		(layer "In11.Cu")
		(net "FM_CPU1_VRM_322M_156M_OSC_EN")
	)
	(segment
		(start 191.550798 -134.585202)
		(end 189.872874 -132.907278)
		(width 0.089408)
		(layer "In11.Cu")
		(net "FM_CPU1_VRM_322M_156M_OSC_EN")
	)
	(segment
		(start 380.3396 -104.648)
		(end 380.3396 -104.2162)
		(width 0.089408)
		(layer "In11.Cu")
		(net "FM_CPU1_VRM_322M_156M_OSC_EN")
	)
	(segment
		(start 378.775722 -119.763032)
		(end 378.775722 -119.285004)
		(width 0.089408)
		(layer "In11.Cu")
		(net "FM_CPU1_VRM_322M_156M_OSC_EN")
	)
	(segment
		(start 168.287954 -125.692154)
		(end 168.287954 -124.782072)
		(width 0.089408)
		(layer "In11.Cu")
		(net "FM_CPU1_VRM_322M_156M_OSC_EN")
	)
	(segment
		(start 176.904904 -131.784344)
		(end 175.5013 -130.38074)
		(width 0.089408)
		(layer "In11.Cu")
		(net "FM_CPU1_VRM_322M_156M_OSC_EN")
	)
	(segment
		(start 376.181112 -93.098112)
		(end 376.181112 -89.973658)
		(width 0.089408)
		(layer "In11.Cu")
		(net "FM_CPU1_VRM_322M_156M_OSC_EN")
	)
	(segment
		(start 192.220342 -149.09165)
		(end 192.220342 -137.474198)
		(width 0.089408)
		(layer "In11.Cu")
		(net "FM_CPU1_VRM_322M_156M_OSC_EN")
	)
	(segment
		(start 175.5013 -130.048)
		(end 174.44085 -128.98755)
		(width 0.089408)
		(layer "In11.Cu")
		(net "FM_CPU1_VRM_322M_156M_OSC_EN")
	)
	(segment
		(start 193.171826 -154.70759)
		(end 193.171826 -150.043134)
		(width 0.089408)
		(layer "In11.Cu")
		(net "FM_CPU1_VRM_322M_156M_OSC_EN")
	)
	(segment
		(start 377.83135 -120.951498)
		(end 378.23013 -120.552718)
		(width 0.089408)
		(layer "In11.Cu")
		(net "FM_CPU1_VRM_322M_156M_OSC_EN")
	)
	(segment
		(start 193.171572 -154.907996)
		(end 193.171572 -154.707844)
		(width 0.089408)
		(layer "In11.Cu")
		(net "FM_CPU1_VRM_322M_156M_OSC_EN")
	)
	(segment
		(start 381.89027 -100.015802)
		(end 382.19253 -99.713542)
		(width 0.089408)
		(layer "In11.Cu")
		(net "FM_CPU1_VRM_322M_156M_OSC_EN")
	)
	(segment
		(start 332.056232 -136.694926)
		(end 330.309728 -138.44143)
		(width 0.089408)
		(layer "In11.Cu")
		(net "FM_CPU1_VRM_322M_156M_OSC_EN")
	)
	(segment
		(start 265.32967 -157.135068)
		(end 265.327384 -157.135068)
		(width 0.089408)
		(layer "In11.Cu")
		(net "FM_CPU1_VRM_322M_156M_OSC_EN")
	)
	(segment
		(start 380.21133 -97.954592)
		(end 380.21133 -97.221802)
		(width 0.089408)
		(layer "In11.Cu")
		(net "FM_CPU1_VRM_322M_156M_OSC_EN")
	)
	(segment
		(start 377.683522 -111.090202)
		(end 377.683522 -108.416344)
		(width 0.089408)
		(layer "In11.Cu")
		(net "FM_CPU1_VRM_322M_156M_OSC_EN")
	)
	(segment
		(start 378.331984 -113.059464)
		(end 378.492004 -113.059464)
		(width 0.089408)
		(layer "In11.Cu")
		(net "FM_CPU1_VRM_322M_156M_OSC_EN")
	)
	(segment
		(start 381.89027 -98.62947)
		(end 381.89027 -98.42627)
		(width 0.089408)
		(layer "In11.Cu")
		(net "FM_CPU1_VRM_322M_156M_OSC_EN")
	)
	(segment
		(start 187.530994 -132.907278)
		(end 186.40806 -131.784344)
		(width 0.089408)
		(layer "In11.Cu")
		(net "FM_CPU1_VRM_322M_156M_OSC_EN")
	)
	(segment
		(start 381.959104 -98.698304)
		(end 381.89027 -98.62947)
		(width 0.089408)
		(layer "In11.Cu")
		(net "FM_CPU1_VRM_322M_156M_OSC_EN")
	)
	(segment
		(start 374.064784 -82.042)
		(end 373.717312 -82.042)
		(width 0.089408)
		(layer "In11.Cu")
		(net "FM_CPU1_VRM_322M_156M_OSC_EN")
	)
	(segment
		(start 378.384562 -107.448096)
		(end 379.482604 -107.448096)
		(width 0.089408)
		(layer "In11.Cu")
		(net "FM_CPU1_VRM_322M_156M_OSC_EN")
	)
	(segment
		(start 378.23013 -111.63681)
		(end 377.683522 -111.090202)
		(width 0.089408)
		(layer "In11.Cu")
		(net "FM_CPU1_VRM_322M_156M_OSC_EN")
	)
	(segment
		(start 265.227816 -157.234636)
		(end 195.498212 -157.234636)
		(width 0.089408)
		(layer "In11.Cu")
		(net "FM_CPU1_VRM_322M_156M_OSC_EN")
	)
	(segment
		(start 378.775722 -119.285004)
		(end 378.425964 -118.935246)
		(width 0.089408)
		(layer "In11.Cu")
		(net "FM_CPU1_VRM_322M_156M_OSC_EN")
	)
	(segment
		(start 192.220342 -137.474198)
		(end 191.550798 -136.804654)
		(width 0.089408)
		(layer "In11.Cu")
		(net "FM_CPU1_VRM_322M_156M_OSC_EN")
	)
	(segment
		(start 381.508 -101.473)
		(end 381.638556 -101.603556)
		(width 0.089408)
		(layer "In11.Cu")
		(net "FM_CPU1_VRM_322M_156M_OSC_EN")
	)
	(segment
		(start 381.508 -98.044)
		(end 380.300738 -98.044)
		(width 0.089408)
		(layer "In11.Cu")
		(net "FM_CPU1_VRM_322M_156M_OSC_EN")
	)
	(segment
		(start 380.746 -105.0544)
		(end 380.3396 -104.648)
		(width 0.089408)
		(layer "In11.Cu")
		(net "FM_CPU1_VRM_322M_156M_OSC_EN")
	)
	(segment
		(start 324.32752 -140.191744)
		(end 324.32752 -149.09546)
		(width 0.089408)
		(layer "In11.Cu")
		(net "FM_CPU1_VRM_322M_156M_OSC_EN")
	)
	(segment
		(start 377.775978 -115.921536)
		(end 378.23013 -115.467384)
		(width 0.089408)
		(layer "In11.Cu")
		(net "FM_CPU1_VRM_322M_156M_OSC_EN")
	)
	(segment
		(start 382.19253 -99.713542)
		(end 382.19253 -99.157282)
		(width 0.089408)
		(layer "In11.Cu")
		(net "FM_CPU1_VRM_322M_156M_OSC_EN")
	)
	(segment
		(start 377.843034 -114.535712)
		(end 377.843034 -113.548414)
		(width 0.089408)
		(layer "In11.Cu")
		(net "FM_CPU1_VRM_322M_156M_OSC_EN")
	)
	(segment
		(start 380.111 -101.473)
		(end 381.508 -101.473)
		(width 0.089408)
		(layer "In11.Cu")
		(net "FM_CPU1_VRM_322M_156M_OSC_EN")
	)
	(segment
		(start 377.83135 -122.104404)
		(end 377.83135 -120.951498)
		(width 0.089408)
		(layer "In11.Cu")
		(net "FM_CPU1_VRM_322M_156M_OSC_EN")
	)
	(segment
		(start 378.425964 -118.934992)
		(end 378.358654 -118.867682)
		(width 0.089408)
		(layer "In11.Cu")
		(net "FM_CPU1_VRM_322M_156M_OSC_EN")
	)
	(segment
		(start 378.22378 -108.013754)
		(end 378.22378 -107.608878)
		(width 0.089408)
		(layer "In11.Cu")
		(net "FM_CPU1_VRM_322M_156M_OSC_EN")
	)
	(segment
		(start 380.21133 -95.723202)
		(end 377.989592 -93.501464)
		(width 0.089408)
		(layer "In11.Cu")
		(net "FM_CPU1_VRM_322M_156M_OSC_EN")
	)
	(segment
		(start 163.130992 -118.637812)
		(end 161.862516 -118.637812)
		(width 0.089408)
		(layer "In11.Cu")
		(net "FM_CPU1_VRM_322M_156M_OSC_EN")
	)
	(segment
		(start 381.638556 -101.603556)
		(end 382.019556 -101.603556)
		(width 0.089408)
		(layer "In11.Cu")
		(net "FM_CPU1_VRM_322M_156M_OSC_EN")
	)
	(segment
		(start 193.171826 -150.043134)
		(end 192.220342 -149.09165)
		(width 0.089408)
		(layer "In11.Cu")
		(net "FM_CPU1_VRM_322M_156M_OSC_EN")
	)
	(segment
		(start 377.683522 -108.416344)
		(end 377.852686 -108.24718)
		(width 0.089408)
		(layer "In11.Cu")
		(net "FM_CPU1_VRM_322M_156M_OSC_EN")
	)
	(segment
		(start 175.5013 -130.38074)
		(end 175.5013 -130.048)
		(width 0.089408)
		(layer "In11.Cu")
		(net "FM_CPU1_VRM_322M_156M_OSC_EN")
	)
	(segment
		(start 377.989592 -93.501464)
		(end 376.584464 -93.501464)
		(width 0.089408)
		(layer "In11.Cu")
		(net "FM_CPU1_VRM_322M_156M_OSC_EN")
	)
	(segment
		(start 323.829426 -149.593554)
		(end 323.829426 -154.583638)
		(width 0.089408)
		(layer "In11.Cu")
		(net "FM_CPU1_VRM_322M_156M_OSC_EN")
	)
	(segment
		(start 155.685998 -115.6208)
		(end 154.734514 -114.669316)
		(width 0.089408)
		(layer "In11.Cu")
		(net "FM_CPU1_VRM_322M_156M_OSC_EN")
	)
	(segment
		(start 334.459326 -136.694926)
		(end 332.056232 -136.694926)
		(width 0.089408)
		(layer "In11.Cu")
		(net "FM_CPU1_VRM_322M_156M_OSC_EN")
	)
	(segment
		(start 382.019556 -101.603556)
		(end 382.19253 -101.430582)
		(width 0.089408)
		(layer "In11.Cu")
		(net "FM_CPU1_VRM_322M_156M_OSC_EN")
	)
	(segment
		(start 377.843034 -113.548414)
		(end 378.331984 -113.059464)
		(width 0.089408)
		(layer "In11.Cu")
		(net "FM_CPU1_VRM_322M_156M_OSC_EN")
	)
	(segment
		(start 326.077834 -138.44143)
		(end 324.32752 -140.191744)
		(width 0.089408)
		(layer "In11.Cu")
		(net "FM_CPU1_VRM_322M_156M_OSC_EN")
	)
	(segment
		(start 324.32752 -149.09546)
		(end 323.829426 -149.593554)
		(width 0.089408)
		(layer "In11.Cu")
		(net "FM_CPU1_VRM_322M_156M_OSC_EN")
	)
	(segment
		(start 375.0056 -88.798146)
		(end 375.0056 -82.982816)
		(width 0.089408)
		(layer "In11.Cu")
		(net "FM_CPU1_VRM_322M_156M_OSC_EN")
	)
	(segment
		(start 378.23013 -120.552718)
		(end 378.23013 -120.308624)
		(width 0.089408)
		(layer "In11.Cu")
		(net "FM_CPU1_VRM_322M_156M_OSC_EN")
	)
	(segment
		(start 334.899 -137.1346)
		(end 334.459326 -136.694926)
		(width 0.089408)
		(layer "In11.Cu")
		(net "FM_CPU1_VRM_322M_156M_OSC_EN")
	)
	(segment
		(start 380.300738 -98.044)
		(end 380.21133 -97.954592)
		(width 0.089408)
		(layer "In11.Cu")
		(net "FM_CPU1_VRM_322M_156M_OSC_EN")
	)
	(segment
		(start 379.71603 -107.21467)
		(end 379.71603 -106.85145)
		(width 0.089408)
		(layer "In11.Cu")
		(net "FM_CPU1_VRM_322M_156M_OSC_EN")
	)
	(segment
		(start 171.58335 -128.98755)
		(end 168.287954 -125.692154)
		(width 0.089408)
		(layer "In11.Cu")
		(net "FM_CPU1_VRM_322M_156M_OSC_EN")
	)
	(segment
		(start 378.358654 -118.867682)
		(end 378.358654 -118.45544)
		(width 0.089408)
		(layer "In11.Cu")
		(net "FM_CPU1_VRM_322M_156M_OSC_EN")
	)
	(segment
		(start 381.959104 -98.923856)
		(end 381.959104 -98.698304)
		(width 0.089408)
		(layer "In11.Cu")
		(net "FM_CPU1_VRM_322M_156M_OSC_EN")
	)
	(segment
		(start 379.90907 -96.581722)
		(end 380.21133 -96.279462)
		(width 0.089408)
		(layer "In11.Cu")
		(net "FM_CPU1_VRM_322M_156M_OSC_EN")
	)
	(segment
		(start 376.181112 -89.973658)
		(end 375.0056 -88.798146)
		(width 0.089408)
		(layer "In11.Cu")
		(net "FM_CPU1_VRM_322M_156M_OSC_EN")
	)
	(segment
		(start 380.21133 -97.221802)
		(end 379.90907 -96.919542)
		(width 0.089408)
		(layer "In11.Cu")
		(net "FM_CPU1_VRM_322M_156M_OSC_EN")
	)
	(segment
		(start 323.829426 -154.583638)
		(end 321.595242 -156.817822)
		(width 0.089408)
		(layer "In11.Cu")
		(net "FM_CPU1_VRM_322M_156M_OSC_EN")
	)
	(segment
		(start 378.22378 -107.608878)
		(end 378.384562 -107.448096)
		(width 0.089408)
		(layer "In11.Cu")
		(net "FM_CPU1_VRM_322M_156M_OSC_EN")
	)
	(segment
		(start 330.309728 -138.44143)
		(end 326.077834 -138.44143)
		(width 0.089408)
		(layer "In11.Cu")
		(net "FM_CPU1_VRM_322M_156M_OSC_EN")
	)
	(segment
		(start 379.73 -101.854)
		(end 380.111 -101.473)
		(width 0.089408)
		(layer "In11.Cu")
		(net "FM_CPU1_VRM_322M_156M_OSC_EN")
	)
	(segment
		(start 159.9184 -30.226)
		(end 157.652974 -32.491426)
		(width 0.10795)
		(layer "F.Cu")
		(net "FM_CPU1_STL_BRD_OSC_EN")
	)
	(segment
		(start 160.9852 -30.226)
		(end 159.9184 -30.226)
		(width 0.10795)
		(layer "F.Cu")
		(net "FM_CPU1_STL_BRD_OSC_EN")
	)
	(segment
		(start 151.911558 -32.491426)
		(end 150.585932 -31.1658)
		(width 0.10795)
		(layer "F.Cu")
		(net "FM_CPU1_STL_BRD_OSC_EN")
	)
	(segment
		(start 150.585932 -31.1658)
		(end 149.7711 -31.1658)
		(width 0.10795)
		(layer "F.Cu")
		(net "FM_CPU1_STL_BRD_OSC_EN")
	)
	(segment
		(start 157.652974 -32.491426)
		(end 151.911558 -32.491426)
		(width 0.10795)
		(layer "F.Cu")
		(net "FM_CPU1_STL_BRD_OSC_EN")
	)
	(via
		(at 160.9852 -30.226)
		(size 0.508)
		(drill 0.254)
		(layers "F.Cu" "B.Cu")
		(net "FM_CPU1_STL_BRD_OSC_EN")
	)
	(via
		(at 364.394496 -74.873358)
		(size 0.6604)
		(drill 0.3302)
		(layers "F.Cu" "B.Cu")
		(net "FM_CPU1_STL_BRD_OSC_EN")
	)
	(via
		(at 315.310774 -43.69816)
		(size 0.508)
		(drill 0.254)
		(layers "F.Cu" "B.Cu")
		(net "FM_CPU1_STL_BRD_OSC_EN")
	)
	(via
		(at 361.237784 -55.385208)
		(size 0.508)
		(drill 0.254)
		(layers "F.Cu" "B.Cu")
		(net "FM_CPU1_STL_BRD_OSC_EN")
	)
	(segment
		(start 360.397552 -58.21934)
		(end 359.992676 -58.624216)
		(width 0.10795)
		(layer "B.Cu")
		(net "FM_CPU1_STL_BRD_OSC_EN")
	)
	(segment
		(start 354.85832 -72.799194)
		(end 362.320332 -72.799194)
		(width 0.10795)
		(layer "B.Cu")
		(net "FM_CPU1_STL_BRD_OSC_EN")
	)
	(segment
		(start 359.992676 -58.624216)
		(end 359.992676 -64.44742)
		(width 0.10795)
		(layer "B.Cu")
		(net "FM_CPU1_STL_BRD_OSC_EN")
	)
	(segment
		(start 361.237784 -55.385208)
		(end 361.033314 -55.385208)
		(width 0.10795)
		(layer "B.Cu")
		(net "FM_CPU1_STL_BRD_OSC_EN")
	)
	(segment
		(start 364.617 -77.5716)
		(end 364.617 -75.095862)
		(width 0.10795)
		(layer "B.Cu")
		(net "FM_CPU1_STL_BRD_OSC_EN")
	)
	(segment
		(start 360.397552 -56.02097)
		(end 360.397552 -58.21934)
		(width 0.10795)
		(layer "B.Cu")
		(net "FM_CPU1_STL_BRD_OSC_EN")
	)
	(segment
		(start 361.033314 -55.385208)
		(end 360.397552 -56.02097)
		(width 0.10795)
		(layer "B.Cu")
		(net "FM_CPU1_STL_BRD_OSC_EN")
	)
	(segment
		(start 364.617 -75.095862)
		(end 364.394496 -74.873358)
		(width 0.10795)
		(layer "B.Cu")
		(net "FM_CPU1_STL_BRD_OSC_EN")
	)
	(segment
		(start 362.320332 -72.799194)
		(end 364.394496 -74.873358)
		(width 0.10795)
		(layer "B.Cu")
		(net "FM_CPU1_STL_BRD_OSC_EN")
	)
	(segment
		(start 354.282248 -72.223122)
		(end 354.85832 -72.799194)
		(width 0.10795)
		(layer "B.Cu")
		(net "FM_CPU1_STL_BRD_OSC_EN")
	)
	(segment
		(start 359.992676 -64.44742)
		(end 354.282248 -70.157848)
		(width 0.10795)
		(layer "B.Cu")
		(net "FM_CPU1_STL_BRD_OSC_EN")
	)
	(segment
		(start 364.617 -78.3336)
		(end 364.617 -77.5716)
		(width 0.10795)
		(layer "B.Cu")
		(net "FM_CPU1_STL_BRD_OSC_EN")
	)
	(segment
		(start 354.282248 -70.157848)
		(end 354.282248 -72.223122)
		(width 0.10795)
		(layer "B.Cu")
		(net "FM_CPU1_STL_BRD_OSC_EN")
	)
	(segment
		(start 221.846902 -28.492704)
		(end 162.718496 -28.492704)
		(width 0.089408)
		(layer "In9.Cu")
		(net "FM_CPU1_STL_BRD_OSC_EN")
	)
	(segment
		(start 264.220198 -32.350202)
		(end 262.544052 -30.674056)
		(width 0.089408)
		(layer "In9.Cu")
		(net "FM_CPU1_STL_BRD_OSC_EN")
	)
	(segment
		(start 262.544052 -30.674056)
		(end 260.991858 -30.674056)
		(width 0.089408)
		(layer "In9.Cu")
		(net "FM_CPU1_STL_BRD_OSC_EN")
	)
	(segment
		(start 241.981228 -30.200346)
		(end 223.554544 -30.200346)
		(width 0.089408)
		(layer "In9.Cu")
		(net "FM_CPU1_STL_BRD_OSC_EN")
	)
	(segment
		(start 314.591446 -43.69816)
		(end 303.243488 -32.350202)
		(width 0.089408)
		(layer "In9.Cu")
		(net "FM_CPU1_STL_BRD_OSC_EN")
	)
	(segment
		(start 259.731002 -29.4132)
		(end 242.768374 -29.4132)
		(width 0.089408)
		(layer "In9.Cu")
		(net "FM_CPU1_STL_BRD_OSC_EN")
	)
	(segment
		(start 242.768374 -29.4132)
		(end 241.981228 -30.200346)
		(width 0.089408)
		(layer "In9.Cu")
		(net "FM_CPU1_STL_BRD_OSC_EN")
	)
	(segment
		(start 260.991858 -30.674056)
		(end 259.731002 -29.4132)
		(width 0.089408)
		(layer "In9.Cu")
		(net "FM_CPU1_STL_BRD_OSC_EN")
	)
	(segment
		(start 162.718496 -28.492704)
		(end 160.9852 -30.226)
		(width 0.089408)
		(layer "In9.Cu")
		(net "FM_CPU1_STL_BRD_OSC_EN")
	)
	(segment
		(start 315.310774 -43.69816)
		(end 314.591446 -43.69816)
		(width 0.089408)
		(layer "In9.Cu")
		(net "FM_CPU1_STL_BRD_OSC_EN")
	)
	(segment
		(start 303.243488 -32.350202)
		(end 264.220198 -32.350202)
		(width 0.089408)
		(layer "In9.Cu")
		(net "FM_CPU1_STL_BRD_OSC_EN")
	)
	(segment
		(start 223.554544 -30.200346)
		(end 221.846902 -28.492704)
		(width 0.089408)
		(layer "In9.Cu")
		(net "FM_CPU1_STL_BRD_OSC_EN")
	)
	(segment
		(start 349.90024 -52.81676)
		(end 355.10851 -52.81676)
		(width 0.089408)
		(layer "In11.Cu")
		(net "FM_CPU1_STL_BRD_OSC_EN")
	)
	(segment
		(start 326.233282 -52.350162)
		(end 339.852762 -52.350162)
		(width 0.089408)
		(layer "In11.Cu")
		(net "FM_CPU1_STL_BRD_OSC_EN")
	)
	(segment
		(start 317.524892 -46.920658)
		(end 320.803778 -46.920658)
		(width 0.089408)
		(layer "In11.Cu")
		(net "FM_CPU1_STL_BRD_OSC_EN")
	)
	(segment
		(start 315.270896 -44.666662)
		(end 317.524892 -46.920658)
		(width 0.089408)
		(layer "In11.Cu")
		(net "FM_CPU1_STL_BRD_OSC_EN")
	)
	(segment
		(start 341.16899 -54.496208)
		(end 348.220792 -54.496208)
		(width 0.089408)
		(layer "In11.Cu")
		(net "FM_CPU1_STL_BRD_OSC_EN")
	)
	(segment
		(start 361.237784 -55.292752)
		(end 361.237784 -55.385208)
		(width 0.089408)
		(layer "In11.Cu")
		(net "FM_CPU1_STL_BRD_OSC_EN")
	)
	(segment
		(start 355.931724 -53.639974)
		(end 359.585006 -53.639974)
		(width 0.089408)
		(layer "In11.Cu")
		(net "FM_CPU1_STL_BRD_OSC_EN")
	)
	(segment
		(start 348.220792 -54.496208)
		(end 349.90024 -52.81676)
		(width 0.089408)
		(layer "In11.Cu")
		(net "FM_CPU1_STL_BRD_OSC_EN")
	)
	(segment
		(start 340.702392 -53.199792)
		(end 340.702392 -54.02961)
		(width 0.089408)
		(layer "In11.Cu")
		(net "FM_CPU1_STL_BRD_OSC_EN")
	)
	(segment
		(start 339.852762 -52.350162)
		(end 340.702392 -53.199792)
		(width 0.089408)
		(layer "In11.Cu")
		(net "FM_CPU1_STL_BRD_OSC_EN")
	)
	(segment
		(start 315.310774 -43.69816)
		(end 315.270896 -43.738038)
		(width 0.089408)
		(layer "In11.Cu")
		(net "FM_CPU1_STL_BRD_OSC_EN")
	)
	(segment
		(start 340.702392 -54.02961)
		(end 341.16899 -54.496208)
		(width 0.089408)
		(layer "In11.Cu")
		(net "FM_CPU1_STL_BRD_OSC_EN")
	)
	(segment
		(start 320.803778 -46.920658)
		(end 326.233282 -52.350162)
		(width 0.089408)
		(layer "In11.Cu")
		(net "FM_CPU1_STL_BRD_OSC_EN")
	)
	(segment
		(start 359.585006 -53.639974)
		(end 361.237784 -55.292752)
		(width 0.089408)
		(layer "In11.Cu")
		(net "FM_CPU1_STL_BRD_OSC_EN")
	)
	(segment
		(start 355.10851 -52.81676)
		(end 355.931724 -53.639974)
		(width 0.089408)
		(layer "In11.Cu")
		(net "FM_CPU1_STL_BRD_OSC_EN")
	)
	(segment
		(start 315.270896 -43.738038)
		(end 315.270896 -44.666662)
		(width 0.089408)
		(layer "In11.Cu")
		(net "FM_CPU1_STL_BRD_OSC_EN")
	)
	(segment
		(start 368.745262 -79.894684)
		(end 369.145058 -79.494888)
		(width 0.10795)
		(layer "F.Cu")
		(net "FM_CPU0_VRM_OSC_EN")
	)
	(via
		(at 353.2632 -70.866)
		(size 0.6604)
		(drill 0.3302)
		(layers "F.Cu" "B.Cu")
		(net "FM_CPU0_VRM_OSC_EN")
	)
	(via
		(at 368.745262 -79.894684)
		(size 0.4572)
		(drill 0.2032)
		(layers "F.Cu" "B.Cu")
		(net "FM_CPU0_VRM_OSC_EN")
	)
	(segment
		(start 361.588558 -73.52919)
		(end 363.691932 -75.632564)
		(width 0.10795)
		(layer "B.Cu")
		(net "FM_CPU0_VRM_OSC_EN")
	)
	(segment
		(start 352.8949 -71.2343)
		(end 352.8949 -72.0344)
		(width 0.10795)
		(layer "B.Cu")
		(net "FM_CPU0_VRM_OSC_EN")
	)
	(segment
		(start 363.691932 -75.632564)
		(end 363.691932 -80.471518)
		(width 0.10795)
		(layer "B.Cu")
		(net "FM_CPU0_VRM_OSC_EN")
	)
	(segment
		(start 353.883468 -72.8218)
		(end 354.590858 -73.52919)
		(width 0.10795)
		(layer "B.Cu")
		(net "FM_CPU0_VRM_OSC_EN")
	)
	(segment
		(start 364.043214 -80.8228)
		(end 366.481614 -80.8228)
		(width 0.10795)
		(layer "B.Cu")
		(net "FM_CPU0_VRM_OSC_EN")
	)
	(segment
		(start 366.481614 -80.8228)
		(end 366.992408 -80.312006)
		(width 0.10795)
		(layer "B.Cu")
		(net "FM_CPU0_VRM_OSC_EN")
	)
	(segment
		(start 363.691932 -80.471518)
		(end 364.043214 -80.8228)
		(width 0.10795)
		(layer "B.Cu")
		(net "FM_CPU0_VRM_OSC_EN")
	)
	(segment
		(start 368.290602 -80.312006)
		(end 368.707924 -79.894684)
		(width 0.10795)
		(layer "B.Cu")
		(net "FM_CPU0_VRM_OSC_EN")
	)
	(segment
		(start 366.992408 -80.312006)
		(end 368.290602 -80.312006)
		(width 0.10795)
		(layer "B.Cu")
		(net "FM_CPU0_VRM_OSC_EN")
	)
	(segment
		(start 352.8949 -72.8218)
		(end 353.883468 -72.8218)
		(width 0.10795)
		(layer "B.Cu")
		(net "FM_CPU0_VRM_OSC_EN")
	)
	(segment
		(start 368.707924 -79.894684)
		(end 368.745262 -79.894684)
		(width 0.10795)
		(layer "B.Cu")
		(net "FM_CPU0_VRM_OSC_EN")
	)
	(segment
		(start 354.590858 -73.52919)
		(end 361.588558 -73.52919)
		(width 0.10795)
		(layer "B.Cu")
		(net "FM_CPU0_VRM_OSC_EN")
	)
	(segment
		(start 352.8949 -72.8218)
		(end 352.8949 -72.0344)
		(width 0.10795)
		(layer "B.Cu")
		(net "FM_CPU0_VRM_OSC_EN")
	)
	(segment
		(start 353.2632 -70.866)
		(end 352.8949 -71.2343)
		(width 0.10795)
		(layer "B.Cu")
		(net "FM_CPU0_VRM_OSC_EN")
	)
	(segment
		(start 329.822556 -110.47095)
		(end 330.311252 -109.982254)
		(width 0.10795)
		(layer "F.Cu")
		(net "FM_CPU0_VRM_322M_156M_OSC_EN")
	)
	(segment
		(start 329.594972 -110.47095)
		(end 329.822556 -110.47095)
		(width 0.10795)
		(layer "F.Cu")
		(net "FM_CPU0_VRM_322M_156M_OSC_EN")
	)
	(via
		(at 350.883474 -72.201786)
		(size 0.508)
		(drill 0.254)
		(layers "F.Cu" "B.Cu")
		(net "FM_CPU0_VRM_322M_156M_OSC_EN")
	)
	(via
		(at 330.311252 -109.982254)
		(size 0.508)
		(drill 0.254)
		(layers "F.Cu" "B.Cu")
		(net "FM_CPU0_VRM_322M_156M_OSC_EN")
	)
	(segment
		(start 351.05086 -72.0344)
		(end 352.0059 -72.0344)
		(width 0.10795)
		(layer "B.Cu")
		(net "FM_CPU0_VRM_322M_156M_OSC_EN")
	)
	(segment
		(start 350.883474 -72.201786)
		(end 351.05086 -72.0344)
		(width 0.10795)
		(layer "B.Cu")
		(net "FM_CPU0_VRM_322M_156M_OSC_EN")
	)
	(segment
		(start 341.710518 -74.839322)
		(end 340.663022 -75.886818)
		(width 0.089408)
		(layer "In4.Cu")
		(net "FM_CPU0_VRM_322M_156M_OSC_EN")
	)
	(segment
		(start 338.9376 -76.093574)
		(end 338.9376 -82.792316)
		(width 0.089408)
		(layer "In4.Cu")
		(net "FM_CPU0_VRM_322M_156M_OSC_EN")
	)
	(segment
		(start 349.031814 -72.201786)
		(end 348.19209 -73.04151)
		(width 0.089408)
		(layer "In4.Cu")
		(net "FM_CPU0_VRM_322M_156M_OSC_EN")
	)
	(segment
		(start 329.83043 -93.454474)
		(end 329.83043 -109.501432)
		(width 0.089408)
		(layer "In4.Cu")
		(net "FM_CPU0_VRM_322M_156M_OSC_EN")
	)
	(segment
		(start 340.663022 -75.886818)
		(end 339.144356 -75.886818)
		(width 0.089408)
		(layer "In4.Cu")
		(net "FM_CPU0_VRM_322M_156M_OSC_EN")
	)
	(segment
		(start 339.144356 -75.886818)
		(end 338.9376 -76.093574)
		(width 0.089408)
		(layer "In4.Cu")
		(net "FM_CPU0_VRM_322M_156M_OSC_EN")
	)
	(segment
		(start 342.857836 -74.839322)
		(end 341.710518 -74.839322)
		(width 0.089408)
		(layer "In4.Cu")
		(net "FM_CPU0_VRM_322M_156M_OSC_EN")
	)
	(segment
		(start 348.19209 -73.04151)
		(end 346.386912 -73.04151)
		(width 0.089408)
		(layer "In4.Cu")
		(net "FM_CPU0_VRM_322M_156M_OSC_EN")
	)
	(segment
		(start 336.418428 -86.866476)
		(end 329.83043 -93.454474)
		(width 0.089408)
		(layer "In4.Cu")
		(net "FM_CPU0_VRM_322M_156M_OSC_EN")
	)
	(segment
		(start 350.883474 -72.201786)
		(end 349.031814 -72.201786)
		(width 0.089408)
		(layer "In4.Cu")
		(net "FM_CPU0_VRM_322M_156M_OSC_EN")
	)
	(segment
		(start 336.418428 -85.448902)
		(end 336.418428 -86.866476)
		(width 0.089408)
		(layer "In4.Cu")
		(net "FM_CPU0_VRM_322M_156M_OSC_EN")
	)
	(segment
		(start 329.83043 -109.501432)
		(end 330.311252 -109.982254)
		(width 0.089408)
		(layer "In4.Cu")
		(net "FM_CPU0_VRM_322M_156M_OSC_EN")
	)
	(segment
		(start 343.808304 -73.888854)
		(end 342.857836 -74.839322)
		(width 0.089408)
		(layer "In4.Cu")
		(net "FM_CPU0_VRM_322M_156M_OSC_EN")
	)
	(segment
		(start 346.386912 -73.04151)
		(end 345.539568 -73.888854)
		(width 0.089408)
		(layer "In4.Cu")
		(net "FM_CPU0_VRM_322M_156M_OSC_EN")
	)
	(segment
		(start 338.741004 -82.988912)
		(end 338.741004 -83.126326)
		(width 0.089408)
		(layer "In4.Cu")
		(net "FM_CPU0_VRM_322M_156M_OSC_EN")
	)
	(segment
		(start 345.539568 -73.888854)
		(end 343.808304 -73.888854)
		(width 0.089408)
		(layer "In4.Cu")
		(net "FM_CPU0_VRM_322M_156M_OSC_EN")
	)
	(segment
		(start 338.741004 -83.126326)
		(end 336.418428 -85.448902)
		(width 0.089408)
		(layer "In4.Cu")
		(net "FM_CPU0_VRM_322M_156M_OSC_EN")
	)
	(segment
		(start 338.9376 -82.792316)
		(end 338.741004 -82.988912)
		(width 0.089408)
		(layer "In4.Cu")
		(net "FM_CPU0_VRM_322M_156M_OSC_EN")
	)
	(segment
		(start 316.906402 -32.714438)
		(end 317.427356 -32.714438)
		(width 0.10795)
		(layer "F.Cu")
		(net "FM_CPU0_STL_BRD_OSC_EN")
	)
	(segment
		(start 312.650124 -30.944566)
		(end 313.47537 -31.769812)
		(width 0.10795)
		(layer "F.Cu")
		(net "FM_CPU0_STL_BRD_OSC_EN")
	)
	(segment
		(start 317.427356 -32.714438)
		(end 318.118998 -33.40608)
		(width 0.10795)
		(layer "F.Cu")
		(net "FM_CPU0_STL_BRD_OSC_EN")
	)
	(segment
		(start 315.961776 -31.769812)
		(end 316.906402 -32.714438)
		(width 0.10795)
		(layer "F.Cu")
		(net "FM_CPU0_STL_BRD_OSC_EN")
	)
	(segment
		(start 318.118998 -33.40608)
		(end 318.118998 -35.608768)
		(width 0.10795)
		(layer "F.Cu")
		(net "FM_CPU0_STL_BRD_OSC_EN")
	)
	(segment
		(start 312.650124 -30.26537)
		(end 312.650124 -30.944566)
		(width 0.10795)
		(layer "F.Cu")
		(net "FM_CPU0_STL_BRD_OSC_EN")
	)
	(segment
		(start 313.47537 -31.769812)
		(end 315.961776 -31.769812)
		(width 0.10795)
		(layer "F.Cu")
		(net "FM_CPU0_STL_BRD_OSC_EN")
	)
	(via
		(at 318.118998 -35.608768)
		(size 0.508)
		(drill 0.254)
		(layers "F.Cu" "B.Cu")
		(net "FM_CPU0_STL_BRD_OSC_EN")
	)
	(via
		(at 357.694738 -52.39258)
		(size 0.508)
		(drill 0.254)
		(layers "F.Cu" "B.Cu")
		(net "FM_CPU0_STL_BRD_OSC_EN")
	)
	(segment
		(start 350.3676 -71.830946)
		(end 350.3676 -72.563736)
		(width 0.10795)
		(layer "B.Cu")
		(net "FM_CPU0_STL_BRD_OSC_EN")
	)
	(segment
		(start 350.625664 -72.8218)
		(end 352.0059 -72.8218)
		(width 0.10795)
		(layer "B.Cu")
		(net "FM_CPU0_STL_BRD_OSC_EN")
	)
	(segment
		(start 352.16338 -71.221854)
		(end 351.990152 -71.221854)
		(width 0.10795)
		(layer "B.Cu")
		(net "FM_CPU0_STL_BRD_OSC_EN")
	)
	(segment
		(start 350.3676 -72.563736)
		(end 350.625664 -72.8218)
		(width 0.10795)
		(layer "B.Cu")
		(net "FM_CPU0_STL_BRD_OSC_EN")
	)
	(segment
		(start 351.989898 -71.2216)
		(end 350.976946 -71.2216)
		(width 0.10795)
		(layer "B.Cu")
		(net "FM_CPU0_STL_BRD_OSC_EN")
	)
	(segment
		(start 357.694738 -52.39258)
		(end 357.694738 -53.58003)
		(width 0.10795)
		(layer "B.Cu")
		(net "FM_CPU0_STL_BRD_OSC_EN")
	)
	(segment
		(start 357.694738 -53.58003)
		(end 359.692702 -55.577994)
		(width 0.10795)
		(layer "B.Cu")
		(net "FM_CPU0_STL_BRD_OSC_EN")
	)
	(segment
		(start 359.692702 -55.577994)
		(end 359.692702 -57.926732)
		(width 0.10795)
		(layer "B.Cu")
		(net "FM_CPU0_STL_BRD_OSC_EN")
	)
	(segment
		(start 359.287826 -58.331608)
		(end 359.287826 -64.097408)
		(width 0.10795)
		(layer "B.Cu")
		(net "FM_CPU0_STL_BRD_OSC_EN")
	)
	(segment
		(start 351.990152 -71.221854)
		(end 351.989898 -71.2216)
		(width 0.10795)
		(layer "B.Cu")
		(net "FM_CPU0_STL_BRD_OSC_EN")
	)
	(segment
		(start 359.692702 -57.926732)
		(end 359.287826 -58.331608)
		(width 0.10795)
		(layer "B.Cu")
		(net "FM_CPU0_STL_BRD_OSC_EN")
	)
	(segment
		(start 350.976946 -71.2216)
		(end 350.3676 -71.830946)
		(width 0.10795)
		(layer "B.Cu")
		(net "FM_CPU0_STL_BRD_OSC_EN")
	)
	(segment
		(start 359.287826 -64.097408)
		(end 352.16338 -71.221854)
		(width 0.10795)
		(layer "B.Cu")
		(net "FM_CPU0_STL_BRD_OSC_EN")
	)
	(segment
		(start 352.0059 -72.8218)
		(end 352.0059 -73.5838)
		(width 0.10795)
		(layer "B.Cu")
		(net "FM_CPU0_STL_BRD_OSC_EN")
	)
	(segment
		(start 317.285116 -42.902886)
		(end 317.285116 -36.293044)
		(width 0.089408)
		(layer "In11.Cu")
		(net "FM_CPU0_STL_BRD_OSC_EN")
	)
	(segment
		(start 341.81542 -52.327048)
		(end 340.590632 -51.10226)
		(width 0.089408)
		(layer "In11.Cu")
		(net "FM_CPU0_STL_BRD_OSC_EN")
	)
	(segment
		(start 317.879476 -44.462954)
		(end 317.879476 -43.497246)
		(width 0.089408)
		(layer "In11.Cu")
		(net "FM_CPU0_STL_BRD_OSC_EN")
	)
	(segment
		(start 347.198442 -53.541168)
		(end 345.984322 -52.327048)
		(width 0.089408)
		(layer "In11.Cu")
		(net "FM_CPU0_STL_BRD_OSC_EN")
	)
	(segment
		(start 340.590632 -51.10226)
		(end 337.69554 -51.10226)
		(width 0.089408)
		(layer "In11.Cu")
		(net "FM_CPU0_STL_BRD_OSC_EN")
	)
	(segment
		(start 318.728344 -45.78731)
		(end 317.810896 -44.869862)
		(width 0.089408)
		(layer "In11.Cu")
		(net "FM_CPU0_STL_BRD_OSC_EN")
	)
	(segment
		(start 323.305424 -45.78731)
		(end 318.728344 -45.78731)
		(width 0.089408)
		(layer "In11.Cu")
		(net "FM_CPU0_STL_BRD_OSC_EN")
	)
	(segment
		(start 347.735906 -53.541168)
		(end 347.198442 -53.541168)
		(width 0.089408)
		(layer "In11.Cu")
		(net "FM_CPU0_STL_BRD_OSC_EN")
	)
	(segment
		(start 317.810896 -44.869862)
		(end 317.810896 -44.531534)
		(width 0.089408)
		(layer "In11.Cu")
		(net "FM_CPU0_STL_BRD_OSC_EN")
	)
	(segment
		(start 357.694738 -51.945032)
		(end 356.486206 -50.7365)
		(width 0.089408)
		(layer "In11.Cu")
		(net "FM_CPU0_STL_BRD_OSC_EN")
	)
	(segment
		(start 350.540574 -50.7365)
		(end 347.735906 -53.541168)
		(width 0.089408)
		(layer "In11.Cu")
		(net "FM_CPU0_STL_BRD_OSC_EN")
	)
	(segment
		(start 356.486206 -50.7365)
		(end 350.540574 -50.7365)
		(width 0.089408)
		(layer "In11.Cu")
		(net "FM_CPU0_STL_BRD_OSC_EN")
	)
	(segment
		(start 345.984322 -52.327048)
		(end 341.81542 -52.327048)
		(width 0.089408)
		(layer "In11.Cu")
		(net "FM_CPU0_STL_BRD_OSC_EN")
	)
	(segment
		(start 317.920878 -35.657282)
		(end 318.070484 -35.657282)
		(width 0.089408)
		(layer "In11.Cu")
		(net "FM_CPU0_STL_BRD_OSC_EN")
	)
	(segment
		(start 357.694738 -52.39258)
		(end 357.694738 -51.945032)
		(width 0.089408)
		(layer "In11.Cu")
		(net "FM_CPU0_STL_BRD_OSC_EN")
	)
	(segment
		(start 337.69554 -51.10226)
		(end 337.695286 -51.102514)
		(width 0.089408)
		(layer "In11.Cu")
		(net "FM_CPU0_STL_BRD_OSC_EN")
	)
	(segment
		(start 317.879476 -43.497246)
		(end 317.285116 -42.902886)
		(width 0.089408)
		(layer "In11.Cu")
		(net "FM_CPU0_STL_BRD_OSC_EN")
	)
	(segment
		(start 317.285116 -36.293044)
		(end 317.920878 -35.657282)
		(width 0.089408)
		(layer "In11.Cu")
		(net "FM_CPU0_STL_BRD_OSC_EN")
	)
	(segment
		(start 328.620628 -51.102514)
		(end 323.305424 -45.78731)
		(width 0.089408)
		(layer "In11.Cu")
		(net "FM_CPU0_STL_BRD_OSC_EN")
	)
	(segment
		(start 317.810896 -44.531534)
		(end 317.879476 -44.462954)
		(width 0.089408)
		(layer "In11.Cu")
		(net "FM_CPU0_STL_BRD_OSC_EN")
	)
	(segment
		(start 318.070484 -35.657282)
		(end 318.118998 -35.608768)
		(width 0.089408)
		(layer "In11.Cu")
		(net "FM_CPU0_STL_BRD_OSC_EN")
	)
	(segment
		(start 337.695286 -51.102514)
		(end 328.620628 -51.102514)
		(width 0.089408)
		(layer "In11.Cu")
		(net "FM_CPU0_STL_BRD_OSC_EN")
	)
	(segment
		(start 373.544846 -78.294738)
		(end 373.14505 -77.894942)
		(width 0.1016)
		(layer "F.Cu")
		(net "FM_156M_CPU1_BRD_OSC_EN")
	)
	(via
		(at 372.773702 -77.736192)
		(size 0.6604)
		(drill 0.3302)
		(layers "F.Cu" "B.Cu")
		(net "FM_156M_CPU1_BRD_OSC_EN")
	)
	(via
		(at 373.544846 -78.294738)
		(size 0.4572)
		(drill 0.2032)
		(layers "F.Cu" "B.Cu")
		(net "FM_156M_CPU1_BRD_OSC_EN")
	)
	(segment
		(start 366.14227 -77.87767)
		(end 365.8362 -77.5716)
		(width 0.10795)
		(layer "B.Cu")
		(net "FM_156M_CPU1_BRD_OSC_EN")
	)
	(segment
		(start 373.544846 -78.294738)
		(end 372.9863 -77.736192)
		(width 0.10795)
		(layer "B.Cu")
		(net "FM_156M_CPU1_BRD_OSC_EN")
	)
	(segment
		(start 372.9863 -77.736192)
		(end 372.773702 -77.736192)
		(width 0.10795)
		(layer "B.Cu")
		(net "FM_156M_CPU1_BRD_OSC_EN")
	)
	(segment
		(start 372.149624 -77.112114)
		(end 371.786658 -77.112114)
		(width 0.10795)
		(layer "B.Cu")
		(net "FM_156M_CPU1_BRD_OSC_EN")
	)
	(segment
		(start 370.541804 -78.691232)
		(end 369.317778 -78.691232)
		(width 0.10795)
		(layer "B.Cu")
		(net "FM_156M_CPU1_BRD_OSC_EN")
	)
	(segment
		(start 371.562376 -77.336396)
		(end 371.562376 -77.653388)
		(width 0.10795)
		(layer "B.Cu")
		(net "FM_156M_CPU1_BRD_OSC_EN")
	)
	(segment
		(start 372.773702 -77.736192)
		(end 372.149624 -77.112114)
		(width 0.10795)
		(layer "B.Cu")
		(net "FM_156M_CPU1_BRD_OSC_EN")
	)
	(segment
		(start 371.786658 -77.112114)
		(end 371.562376 -77.336396)
		(width 0.10795)
		(layer "B.Cu")
		(net "FM_156M_CPU1_BRD_OSC_EN")
	)
	(segment
		(start 371.31625 -77.899514)
		(end 370.961666 -77.899514)
		(width 0.10795)
		(layer "B.Cu")
		(net "FM_156M_CPU1_BRD_OSC_EN")
	)
	(segment
		(start 368.504216 -77.87767)
		(end 366.14227 -77.87767)
		(width 0.10795)
		(layer "B.Cu")
		(net "FM_156M_CPU1_BRD_OSC_EN")
	)
	(segment
		(start 369.317778 -78.691232)
		(end 368.504216 -77.87767)
		(width 0.10795)
		(layer "B.Cu")
		(net "FM_156M_CPU1_BRD_OSC_EN")
	)
	(segment
		(start 365.8362 -77.5716)
		(end 365.506 -77.5716)
		(width 0.10795)
		(layer "B.Cu")
		(net "FM_156M_CPU1_BRD_OSC_EN")
	)
	(segment
		(start 371.562376 -77.653388)
		(end 371.31625 -77.899514)
		(width 0.10795)
		(layer "B.Cu")
		(net "FM_156M_CPU1_BRD_OSC_EN")
	)
	(segment
		(start 370.76253 -78.09865)
		(end 370.76253 -78.470506)
		(width 0.10795)
		(layer "B.Cu")
		(net "FM_156M_CPU1_BRD_OSC_EN")
	)
	(segment
		(start 370.76253 -78.470506)
		(end 370.541804 -78.691232)
		(width 0.10795)
		(layer "B.Cu")
		(net "FM_156M_CPU1_BRD_OSC_EN")
	)
	(segment
		(start 370.961666 -77.899514)
		(end 370.76253 -78.09865)
		(width 0.10795)
		(layer "B.Cu")
		(net "FM_156M_CPU1_BRD_OSC_EN")
	)
	(segment
		(start 371.545104 -80.294988)
		(end 371.545104 -80.8228)
		(width 0.10795)
		(layer "F.Cu")
		(net "FM_156M_CPU0_BRD_OSC_EN")
	)
	(via
		(at 353.734878 -73.3806)
		(size 0.6604)
		(drill 0.3302)
		(layers "F.Cu" "B.Cu")
		(net "FM_156M_CPU0_BRD_OSC_EN")
	)
	(via
		(at 371.545104 -80.8228)
		(size 0.4572)
		(drill 0.2032)
		(layers "F.Cu" "B.Cu")
		(net "FM_156M_CPU0_BRD_OSC_EN")
	)
	(segment
		(start 371.238526 -80.516222)
		(end 371.545104 -80.8228)
		(width 0.10795)
		(layer "B.Cu")
		(net "FM_156M_CPU0_BRD_OSC_EN")
	)
	(segment
		(start 353.734878 -73.3806)
		(end 353.995736 -73.3806)
		(width 0.10795)
		(layer "B.Cu")
		(net "FM_156M_CPU0_BRD_OSC_EN")
	)
	(segment
		(start 363.482382 -75.938888)
		(end 363.482382 -80.558386)
		(width 0.10795)
		(layer "B.Cu")
		(net "FM_156M_CPU0_BRD_OSC_EN")
	)
	(segment
		(start 353.995736 -73.3806)
		(end 354.398834 -73.783698)
		(width 0.10795)
		(layer "B.Cu")
		(net "FM_156M_CPU0_BRD_OSC_EN")
	)
	(segment
		(start 363.482382 -80.558386)
		(end 364.040166 -81.11617)
		(width 0.10795)
		(layer "B.Cu")
		(net "FM_156M_CPU0_BRD_OSC_EN")
	)
	(segment
		(start 369.96878 -80.884776)
		(end 369.96878 -80.71231)
		(width 0.10795)
		(layer "B.Cu")
		(net "FM_156M_CPU0_BRD_OSC_EN")
	)
	(segment
		(start 354.398834 -73.783698)
		(end 361.327192 -73.783698)
		(width 0.10795)
		(layer "B.Cu")
		(net "FM_156M_CPU0_BRD_OSC_EN")
	)
	(segment
		(start 353.734878 -73.3806)
		(end 353.3902 -73.3806)
		(width 0.10795)
		(layer "B.Cu")
		(net "FM_156M_CPU0_BRD_OSC_EN")
	)
	(segment
		(start 369.96878 -80.71231)
		(end 370.164868 -80.516222)
		(width 0.10795)
		(layer "B.Cu")
		(net "FM_156M_CPU0_BRD_OSC_EN")
	)
	(segment
		(start 369.737386 -81.11617)
		(end 369.96878 -80.884776)
		(width 0.10795)
		(layer "B.Cu")
		(net "FM_156M_CPU0_BRD_OSC_EN")
	)
	(segment
		(start 353.187 -73.5838)
		(end 352.8949 -73.5838)
		(width 0.10795)
		(layer "B.Cu")
		(net "FM_156M_CPU0_BRD_OSC_EN")
	)
	(segment
		(start 353.3902 -73.3806)
		(end 353.187 -73.5838)
		(width 0.10795)
		(layer "B.Cu")
		(net "FM_156M_CPU0_BRD_OSC_EN")
	)
	(segment
		(start 370.164868 -80.516222)
		(end 371.238526 -80.516222)
		(width 0.10795)
		(layer "B.Cu")
		(net "FM_156M_CPU0_BRD_OSC_EN")
	)
	(segment
		(start 361.327192 -73.783698)
		(end 363.482382 -75.938888)
		(width 0.10795)
		(layer "B.Cu")
		(net "FM_156M_CPU0_BRD_OSC_EN")
	)
	(segment
		(start 364.040166 -81.11617)
		(end 369.737386 -81.11617)
		(width 0.10795)
		(layer "B.Cu")
		(net "FM_156M_CPU0_BRD_OSC_EN")
	)
	(segment
		(start 169.695114 -38.72103)
		(end 169.6974 -38.735)
		(width 0.127)
		(layer "F.Cu")
		(net "CLK_322M_156M_CPU1_OSC_VRM_DP")
	)
	(segment
		(start 169.6974 -38.735)
		(end 170.3324 -38.1)
		(width 0.127)
		(layer "F.Cu")
		(net "CLK_322M_156M_CPU1_OSC_VRM_DP")
	)
	(segment
		(start 155.612846 -27.9908)
		(end 155.854908 -27.748738)
		(width 0.127)
		(layer "F.Cu")
		(net "CLK_322M_156M_CPU1_OSC_VRM_DP")
	)
	(segment
		(start 155.194 -27.9908)
		(end 155.612846 -27.9908)
		(width 0.127)
		(layer "F.Cu")
		(net "CLK_322M_156M_CPU1_OSC_VRM_DP")
	)
	(via
		(at 155.854908 -27.748738)
		(size 0.508)
		(drill 0.254)
		(layers "F.Cu" "B.Cu")
		(net "CLK_322M_156M_CPU1_OSC_VRM_DP")
	)
	(via
		(at 170.3324 -38.1)
		(size 0.508)
		(drill 0.254)
		(layers "F.Cu" "B.Cu")
		(net "CLK_322M_156M_CPU1_OSC_VRM_DP")
	)
	(segment
		(start 164.924486 -28.384754)
		(end 165.038786 -28.499054)
		(width 0.1143)
		(layer "In4.Cu")
		(net "CLK_322M_156M_CPU1_OSC_VRM_DP")
	)
	(segment
		(start 165.038786 -28.499054)
		(end 168.612312 -28.499054)
		(width 0.1143)
		(layer "In4.Cu")
		(net "CLK_322M_156M_CPU1_OSC_VRM_DP")
	)
	(segment
		(start 162.587686 -28.6131)
		(end 162.701986 -28.7274)
		(width 0.1143)
		(layer "In4.Cu")
		(net "CLK_322M_156M_CPU1_OSC_VRM_DP")
	)
	(segment
		(start 169.3037 -34.067242)
		(end 171.170346 -35.933888)
		(width 0.1143)
		(layer "In4.Cu")
		(net "CLK_322M_156M_CPU1_OSC_VRM_DP")
	)
	(segment
		(start 170.311826 -38.079426)
		(end 170.3324 -38.1)
		(width 0.1143)
		(layer "In4.Cu")
		(net "CLK_322M_156M_CPU1_OSC_VRM_DP")
	)
	(segment
		(start 161.127186 -28.667456)
		(end 161.127186 -25.405842)
		(width 0.1143)
		(layer "In4.Cu")
		(net "CLK_322M_156M_CPU1_OSC_VRM_DP")
	)
	(segment
		(start 161.012886 -28.781756)
		(end 161.127186 -28.667456)
		(width 0.1143)
		(layer "In4.Cu")
		(net "CLK_322M_156M_CPU1_OSC_VRM_DP")
	)
	(segment
		(start 163.349686 -28.7274)
		(end 163.463986 -28.6131)
		(width 0.1143)
		(layer "In4.Cu")
		(net "CLK_322M_156M_CPU1_OSC_VRM_DP")
	)
	(segment
		(start 155.854908 -27.748738)
		(end 155.854908 -28.5623)
		(width 0.1143)
		(layer "In4.Cu")
		(net "CLK_322M_156M_CPU1_OSC_VRM_DP")
	)
	(segment
		(start 162.587686 -25.405842)
		(end 162.587686 -28.6131)
		(width 0.1143)
		(layer "In4.Cu")
		(net "CLK_322M_156M_CPU1_OSC_VRM_DP")
	)
	(segment
		(start 171.170346 -35.933888)
		(end 171.170346 -37.281358)
		(width 0.1143)
		(layer "In4.Cu")
		(net "CLK_322M_156M_CPU1_OSC_VRM_DP")
	)
	(segment
		(start 160.250886 -28.667456)
		(end 160.365186 -28.781756)
		(width 0.1143)
		(layer "In4.Cu")
		(net "CLK_322M_156M_CPU1_OSC_VRM_DP")
	)
	(segment
		(start 170.311826 -37.803074)
		(end 170.311826 -38.079426)
		(width 0.1143)
		(layer "In4.Cu")
		(net "CLK_322M_156M_CPU1_OSC_VRM_DP")
	)
	(segment
		(start 170.392852 -37.722048)
		(end 170.311826 -37.803074)
		(width 0.1143)
		(layer "In4.Cu")
		(net "CLK_322M_156M_CPU1_OSC_VRM_DP")
	)
	(segment
		(start 162.701986 -28.7274)
		(end 163.349686 -28.7274)
		(width 0.1143)
		(layer "In4.Cu")
		(net "CLK_322M_156M_CPU1_OSC_VRM_DP")
	)
	(segment
		(start 162.302444 -25.1206)
		(end 162.587686 -25.405842)
		(width 0.1143)
		(layer "In4.Cu")
		(net "CLK_322M_156M_CPU1_OSC_VRM_DP")
	)
	(segment
		(start 160.365186 -28.781756)
		(end 161.012886 -28.781756)
		(width 0.1143)
		(layer "In4.Cu")
		(net "CLK_322M_156M_CPU1_OSC_VRM_DP")
	)
	(segment
		(start 168.612312 -28.499054)
		(end 169.3037 -29.190442)
		(width 0.1143)
		(layer "In4.Cu")
		(net "CLK_322M_156M_CPU1_OSC_VRM_DP")
	)
	(segment
		(start 170.729656 -37.722048)
		(end 170.392852 -37.722048)
		(width 0.1143)
		(layer "In4.Cu")
		(net "CLK_322M_156M_CPU1_OSC_VRM_DP")
	)
	(segment
		(start 163.463986 -25.431242)
		(end 163.749228 -25.146)
		(width 0.1143)
		(layer "In4.Cu")
		(net "CLK_322M_156M_CPU1_OSC_VRM_DP")
	)
	(segment
		(start 160.250886 -28.047442)
		(end 160.250886 -28.667456)
		(width 0.1143)
		(layer "In4.Cu")
		(net "CLK_322M_156M_CPU1_OSC_VRM_DP")
	)
	(segment
		(start 161.127186 -25.405842)
		(end 161.412428 -25.1206)
		(width 0.1143)
		(layer "In4.Cu")
		(net "CLK_322M_156M_CPU1_OSC_VRM_DP")
	)
	(segment
		(start 163.463986 -28.6131)
		(end 163.463986 -25.431242)
		(width 0.1143)
		(layer "In4.Cu")
		(net "CLK_322M_156M_CPU1_OSC_VRM_DP")
	)
	(segment
		(start 156.3751 -28.6893)
		(end 157.3022 -27.7622)
		(width 0.1143)
		(layer "In4.Cu")
		(net "CLK_322M_156M_CPU1_OSC_VRM_DP")
	)
	(segment
		(start 161.412428 -25.1206)
		(end 162.302444 -25.1206)
		(width 0.1143)
		(layer "In4.Cu")
		(net "CLK_322M_156M_CPU1_OSC_VRM_DP")
	)
	(segment
		(start 159.965644 -27.7622)
		(end 160.250886 -28.047442)
		(width 0.1143)
		(layer "In4.Cu")
		(net "CLK_322M_156M_CPU1_OSC_VRM_DP")
	)
	(segment
		(start 157.3022 -27.7622)
		(end 159.965644 -27.7622)
		(width 0.1143)
		(layer "In4.Cu")
		(net "CLK_322M_156M_CPU1_OSC_VRM_DP")
	)
	(segment
		(start 169.3037 -29.190442)
		(end 169.3037 -34.067242)
		(width 0.1143)
		(layer "In4.Cu")
		(net "CLK_322M_156M_CPU1_OSC_VRM_DP")
	)
	(segment
		(start 155.854908 -28.5623)
		(end 155.981908 -28.6893)
		(width 0.1143)
		(layer "In4.Cu")
		(net "CLK_322M_156M_CPU1_OSC_VRM_DP")
	)
	(segment
		(start 155.981908 -28.6893)
		(end 156.3751 -28.6893)
		(width 0.1143)
		(layer "In4.Cu")
		(net "CLK_322M_156M_CPU1_OSC_VRM_DP")
	)
	(segment
		(start 171.170346 -37.281358)
		(end 170.729656 -37.722048)
		(width 0.1143)
		(layer "In4.Cu")
		(net "CLK_322M_156M_CPU1_OSC_VRM_DP")
	)
	(segment
		(start 163.749228 -25.146)
		(end 164.639244 -25.146)
		(width 0.1143)
		(layer "In4.Cu")
		(net "CLK_322M_156M_CPU1_OSC_VRM_DP")
	)
	(segment
		(start 164.924486 -25.431242)
		(end 164.924486 -28.384754)
		(width 0.1143)
		(layer "In4.Cu")
		(net "CLK_322M_156M_CPU1_OSC_VRM_DP")
	)
	(segment
		(start 164.639244 -25.146)
		(end 164.924486 -25.431242)
		(width 0.1143)
		(layer "In4.Cu")
		(net "CLK_322M_156M_CPU1_OSC_VRM_DP")
	)
	(segment
		(start 155.854908 -29.983938)
		(end 155.308046 -30.5308)
		(width 0.127)
		(layer "F.Cu")
		(net "CLK_322M_156M_CPU1_OSC_VRM_DN")
	)
	(segment
		(start 169.6974 -37.465)
		(end 170.3324 -36.83)
		(width 0.127)
		(layer "F.Cu")
		(net "CLK_322M_156M_CPU1_OSC_VRM_DN")
	)
	(segment
		(start 170.3324 -36.83)
		(end 170.3324 -36.8046)
		(width 0.127)
		(layer "F.Cu")
		(net "CLK_322M_156M_CPU1_OSC_VRM_DN")
	)
	(segment
		(start 169.695114 -37.45103)
		(end 169.6974 -37.465)
		(width 0.127)
		(layer "F.Cu")
		(net "CLK_322M_156M_CPU1_OSC_VRM_DN")
	)
	(segment
		(start 155.308046 -30.5308)
		(end 155.194 -30.5308)
		(width 0.127)
		(layer "F.Cu")
		(net "CLK_322M_156M_CPU1_OSC_VRM_DN")
	)
	(via
		(at 155.854908 -29.983938)
		(size 0.508)
		(drill 0.254)
		(layers "F.Cu" "B.Cu")
		(net "CLK_322M_156M_CPU1_OSC_VRM_DN")
	)
	(via
		(at 170.3324 -36.8046)
		(size 0.508)
		(drill 0.254)
		(layers "F.Cu" "B.Cu")
		(net "CLK_322M_156M_CPU1_OSC_VRM_DN")
	)
	(segment
		(start 159.958786 -28.788614)
		(end 160.244028 -29.073856)
		(width 0.1143)
		(layer "In4.Cu")
		(net "CLK_322M_156M_CPU1_OSC_VRM_DN")
	)
	(segment
		(start 162.295586 -28.734258)
		(end 162.580828 -29.0195)
		(width 0.1143)
		(layer "In4.Cu")
		(net "CLK_322M_156M_CPU1_OSC_VRM_DN")
	)
	(segment
		(start 169.0116 -31.8135)
		(end 169.0116 -32.1564)
		(width 0.1143)
		(layer "In4.Cu")
		(net "CLK_322M_156M_CPU1_OSC_VRM_DN")
	)
	(segment
		(start 169.0116 -31.1404)
		(end 168.8465 -31.3055)
		(width 0.1143)
		(layer "In4.Cu")
		(net "CLK_322M_156M_CPU1_OSC_VRM_DN")
	)
	(segment
		(start 164.632386 -25.5524)
		(end 164.632386 -28.505912)
		(width 0.1143)
		(layer "In4.Cu")
		(net "CLK_322M_156M_CPU1_OSC_VRM_DN")
	)
	(segment
		(start 156.496258 -28.9814)
		(end 157.423358 -28.0543)
		(width 0.1143)
		(layer "In4.Cu")
		(net "CLK_322M_156M_CPU1_OSC_VRM_DN")
	)
	(segment
		(start 161.134044 -29.073856)
		(end 161.419286 -28.788614)
		(width 0.1143)
		(layer "In4.Cu")
		(net "CLK_322M_156M_CPU1_OSC_VRM_DN")
	)
	(segment
		(start 169.0116 -34.1884)
		(end 170.878246 -36.055046)
		(width 0.1143)
		(layer "In4.Cu")
		(net "CLK_322M_156M_CPU1_OSC_VRM_DN")
	)
	(segment
		(start 169.0116 -32.1564)
		(end 168.8465 -32.3215)
		(width 0.1143)
		(layer "In4.Cu")
		(net "CLK_322M_156M_CPU1_OSC_VRM_DN")
	)
	(segment
		(start 161.419286 -28.788614)
		(end 161.419286 -25.527)
		(width 0.1143)
		(layer "In4.Cu")
		(net "CLK_322M_156M_CPU1_OSC_VRM_DN")
	)
	(segment
		(start 168.8465 -31.3055)
		(end 168.8465 -31.6484)
		(width 0.1143)
		(layer "In4.Cu")
		(net "CLK_322M_156M_CPU1_OSC_VRM_DN")
	)
	(segment
		(start 157.423358 -28.0543)
		(end 159.844486 -28.0543)
		(width 0.1143)
		(layer "In4.Cu")
		(net "CLK_322M_156M_CPU1_OSC_VRM_DN")
	)
	(segment
		(start 170.608498 -37.429948)
		(end 170.4467 -37.429948)
		(width 0.1143)
		(layer "In4.Cu")
		(net "CLK_322M_156M_CPU1_OSC_VRM_DN")
	)
	(segment
		(start 162.295586 -25.527)
		(end 162.295586 -28.734258)
		(width 0.1143)
		(layer "In4.Cu")
		(net "CLK_322M_156M_CPU1_OSC_VRM_DN")
	)
	(segment
		(start 163.470844 -29.0195)
		(end 163.756086 -28.734258)
		(width 0.1143)
		(layer "In4.Cu")
		(net "CLK_322M_156M_CPU1_OSC_VRM_DN")
	)
	(segment
		(start 162.181286 -25.4127)
		(end 162.295586 -25.527)
		(width 0.1143)
		(layer "In4.Cu")
		(net "CLK_322M_156M_CPU1_OSC_VRM_DN")
	)
	(segment
		(start 164.917628 -28.791154)
		(end 168.491154 -28.791154)
		(width 0.1143)
		(layer "In4.Cu")
		(net "CLK_322M_156M_CPU1_OSC_VRM_DN")
	)
	(segment
		(start 168.8465 -31.6484)
		(end 169.0116 -31.8135)
		(width 0.1143)
		(layer "In4.Cu")
		(net "CLK_322M_156M_CPU1_OSC_VRM_DN")
	)
	(segment
		(start 159.958786 -28.1686)
		(end 159.958786 -28.788614)
		(width 0.1143)
		(layer "In4.Cu")
		(net "CLK_322M_156M_CPU1_OSC_VRM_DN")
	)
	(segment
		(start 168.8465 -33.6804)
		(end 169.0116 -33.8455)
		(width 0.1143)
		(layer "In4.Cu")
		(net "CLK_322M_156M_CPU1_OSC_VRM_DN")
	)
	(segment
		(start 168.8465 -33.3375)
		(end 168.8465 -33.6804)
		(width 0.1143)
		(layer "In4.Cu")
		(net "CLK_322M_156M_CPU1_OSC_VRM_DN")
	)
	(segment
		(start 155.981908 -28.9814)
		(end 156.496258 -28.9814)
		(width 0.1143)
		(layer "In4.Cu")
		(net "CLK_322M_156M_CPU1_OSC_VRM_DN")
	)
	(segment
		(start 170.878246 -37.1602)
		(end 170.608498 -37.429948)
		(width 0.1143)
		(layer "In4.Cu")
		(net "CLK_322M_156M_CPU1_OSC_VRM_DN")
	)
	(segment
		(start 155.854908 -29.983938)
		(end 155.854908 -29.1084)
		(width 0.1143)
		(layer "In4.Cu")
		(net "CLK_322M_156M_CPU1_OSC_VRM_DN")
	)
	(segment
		(start 159.844486 -28.0543)
		(end 159.958786 -28.1686)
		(width 0.1143)
		(layer "In4.Cu")
		(net "CLK_322M_156M_CPU1_OSC_VRM_DN")
	)
	(segment
		(start 170.4467 -37.429948)
		(end 170.3324 -37.315648)
		(width 0.1143)
		(layer "In4.Cu")
		(net "CLK_322M_156M_CPU1_OSC_VRM_DN")
	)
	(segment
		(start 162.580828 -29.0195)
		(end 163.470844 -29.0195)
		(width 0.1143)
		(layer "In4.Cu")
		(net "CLK_322M_156M_CPU1_OSC_VRM_DN")
	)
	(segment
		(start 164.632386 -28.505912)
		(end 164.917628 -28.791154)
		(width 0.1143)
		(layer "In4.Cu")
		(net "CLK_322M_156M_CPU1_OSC_VRM_DN")
	)
	(segment
		(start 168.8465 -30.2895)
		(end 168.8465 -30.6324)
		(width 0.1143)
		(layer "In4.Cu")
		(net "CLK_322M_156M_CPU1_OSC_VRM_DN")
	)
	(segment
		(start 169.0116 -32.8295)
		(end 169.0116 -33.1724)
		(width 0.1143)
		(layer "In4.Cu")
		(net "CLK_322M_156M_CPU1_OSC_VRM_DN")
	)
	(segment
		(start 161.419286 -25.527)
		(end 161.533586 -25.4127)
		(width 0.1143)
		(layer "In4.Cu")
		(net "CLK_322M_156M_CPU1_OSC_VRM_DN")
	)
	(segment
		(start 164.518086 -25.4381)
		(end 164.632386 -25.5524)
		(width 0.1143)
		(layer "In4.Cu")
		(net "CLK_322M_156M_CPU1_OSC_VRM_DN")
	)
	(segment
		(start 170.3324 -37.315648)
		(end 170.3324 -36.8046)
		(width 0.1143)
		(layer "In4.Cu")
		(net "CLK_322M_156M_CPU1_OSC_VRM_DN")
	)
	(segment
		(start 161.533586 -25.4127)
		(end 162.181286 -25.4127)
		(width 0.1143)
		(layer "In4.Cu")
		(net "CLK_322M_156M_CPU1_OSC_VRM_DN")
	)
	(segment
		(start 163.870386 -25.4381)
		(end 164.518086 -25.4381)
		(width 0.1143)
		(layer "In4.Cu")
		(net "CLK_322M_156M_CPU1_OSC_VRM_DN")
	)
	(segment
		(start 160.244028 -29.073856)
		(end 161.134044 -29.073856)
		(width 0.1143)
		(layer "In4.Cu")
		(net "CLK_322M_156M_CPU1_OSC_VRM_DN")
	)
	(segment
		(start 163.756086 -28.734258)
		(end 163.756086 -25.5524)
		(width 0.1143)
		(layer "In4.Cu")
		(net "CLK_322M_156M_CPU1_OSC_VRM_DN")
	)
	(segment
		(start 168.8465 -32.6644)
		(end 169.0116 -32.8295)
		(width 0.1143)
		(layer "In4.Cu")
		(net "CLK_322M_156M_CPU1_OSC_VRM_DN")
	)
	(segment
		(start 168.8465 -32.3215)
		(end 168.8465 -32.6644)
		(width 0.1143)
		(layer "In4.Cu")
		(net "CLK_322M_156M_CPU1_OSC_VRM_DN")
	)
	(segment
		(start 169.0116 -33.1724)
		(end 168.8465 -33.3375)
		(width 0.1143)
		(layer "In4.Cu")
		(net "CLK_322M_156M_CPU1_OSC_VRM_DN")
	)
	(segment
		(start 163.756086 -25.5524)
		(end 163.870386 -25.4381)
		(width 0.1143)
		(layer "In4.Cu")
		(net "CLK_322M_156M_CPU1_OSC_VRM_DN")
	)
	(segment
		(start 169.0116 -30.1244)
		(end 168.8465 -30.2895)
		(width 0.1143)
		(layer "In4.Cu")
		(net "CLK_322M_156M_CPU1_OSC_VRM_DN")
	)
	(segment
		(start 168.8465 -30.6324)
		(end 169.0116 -30.7975)
		(width 0.1143)
		(layer "In4.Cu")
		(net "CLK_322M_156M_CPU1_OSC_VRM_DN")
	)
	(segment
		(start 169.0116 -33.8455)
		(end 169.0116 -34.1884)
		(width 0.1143)
		(layer "In4.Cu")
		(net "CLK_322M_156M_CPU1_OSC_VRM_DN")
	)
	(segment
		(start 155.854908 -29.1084)
		(end 155.981908 -28.9814)
		(width 0.1143)
		(layer "In4.Cu")
		(net "CLK_322M_156M_CPU1_OSC_VRM_DN")
	)
	(segment
		(start 170.878246 -36.055046)
		(end 170.878246 -37.1602)
		(width 0.1143)
		(layer "In4.Cu")
		(net "CLK_322M_156M_CPU1_OSC_VRM_DN")
	)
	(segment
		(start 168.491154 -28.791154)
		(end 169.0116 -29.3116)
		(width 0.1143)
		(layer "In4.Cu")
		(net "CLK_322M_156M_CPU1_OSC_VRM_DN")
	)
	(segment
		(start 169.0116 -30.7975)
		(end 169.0116 -31.1404)
		(width 0.1143)
		(layer "In4.Cu")
		(net "CLK_322M_156M_CPU1_OSC_VRM_DN")
	)
	(segment
		(start 169.0116 -29.3116)
		(end 169.0116 -30.1244)
		(width 0.1143)
		(layer "In4.Cu")
		(net "CLK_322M_156M_CPU1_OSC_VRM_DN")
	)
	(segment
		(start 336.17789 -37.928042)
		(end 336.390234 -37.715698)
		(width 0.127)
		(layer "F.Cu")
		(net "CLK_322M_156M_CPU0_OSC_VRM_DP")
	)
	(segment
		(start 334.6704 -38.735)
		(end 334.98155 -38.42385)
		(width 0.127)
		(layer "F.Cu")
		(net "CLK_322M_156M_CPU0_OSC_VRM_DP")
	)
	(segment
		(start 334.98155 -38.42385)
		(end 336.17789 -37.928042)
		(width 0.127)
		(layer "F.Cu")
		(net "CLK_322M_156M_CPU0_OSC_VRM_DP")
	)
	(segment
		(start 336.5754 -37.268404)
		(end 336.5754 -36.83)
		(width 0.127)
		(layer "F.Cu")
		(net "CLK_322M_156M_CPU0_OSC_VRM_DP")
	)
	(segment
		(start 334.674972 -38.72103)
		(end 334.6704 -38.735)
		(width 0.127)
		(layer "F.Cu")
		(net "CLK_322M_156M_CPU0_OSC_VRM_DP")
	)
	(segment
		(start 318.8716 -28.045918)
		(end 318.8716 -27.432)
		(width 0.127)
		(layer "F.Cu")
		(net "CLK_322M_156M_CPU0_OSC_VRM_DP")
	)
	(segment
		(start 336.390234 -37.715698)
		(end 336.5754 -37.268404)
		(width 0.127)
		(layer "F.Cu")
		(net "CLK_322M_156M_CPU0_OSC_VRM_DP")
	)
	(via
		(at 336.5754 -36.83)
		(size 0.508)
		(drill 0.254)
		(layers "F.Cu" "B.Cu")
		(net "CLK_322M_156M_CPU0_OSC_VRM_DP")
	)
	(via
		(at 318.8716 -27.432)
		(size 0.508)
		(drill 0.254)
		(layers "F.Cu" "B.Cu")
		(net "CLK_322M_156M_CPU0_OSC_VRM_DP")
	)
	(segment
		(start 330.513436 -35.842956)
		(end 328.19848 -35.842956)
		(width 0.1143)
		(layer "In2.Cu")
		(net "CLK_322M_156M_CPU0_OSC_VRM_DP")
	)
	(segment
		(start 318.129158 -29.038042)
		(end 318.4144 -28.7528)
		(width 0.1143)
		(layer "In2.Cu")
		(net "CLK_322M_156M_CPU0_OSC_VRM_DP")
	)
	(segment
		(start 323.913754 -36.718494)
		(end 323.021706 -36.718494)
		(width 0.1143)
		(layer "In2.Cu")
		(net "CLK_322M_156M_CPU0_OSC_VRM_DP")
	)
	(segment
		(start 319.106042 -31.43885)
		(end 318.129158 -30.461966)
		(width 0.1143)
		(layer "In2.Cu")
		(net "CLK_322M_156M_CPU0_OSC_VRM_DP")
	)
	(segment
		(start 335.74355 -37.68344)
		(end 333.525622 -37.68344)
		(width 0.1143)
		(layer "In2.Cu")
		(net "CLK_322M_156M_CPU0_OSC_VRM_DP")
	)
	(segment
		(start 333.525622 -37.68344)
		(end 333.180944 -37.338762)
		(width 0.1143)
		(layer "In2.Cu")
		(net "CLK_322M_156M_CPU0_OSC_VRM_DP")
	)
	(segment
		(start 324.778878 -36.385246)
		(end 324.247002 -36.385246)
		(width 0.1143)
		(layer "In2.Cu")
		(net "CLK_322M_156M_CPU0_OSC_VRM_DP")
	)
	(segment
		(start 323.021706 -36.718494)
		(end 322.776342 -36.963858)
		(width 0.1143)
		(layer "In2.Cu")
		(net "CLK_322M_156M_CPU0_OSC_VRM_DP")
	)
	(segment
		(start 336.132932 -37.294058)
		(end 335.74355 -37.68344)
		(width 0.1143)
		(layer "In2.Cu")
		(net "CLK_322M_156M_CPU0_OSC_VRM_DP")
	)
	(segment
		(start 319.106042 -34.727642)
		(end 319.106042 -31.43885)
		(width 0.1143)
		(layer "In2.Cu")
		(net "CLK_322M_156M_CPU0_OSC_VRM_DP")
	)
	(segment
		(start 333.180944 -37.338762)
		(end 332.009242 -37.338762)
		(width 0.1143)
		(layer "In2.Cu")
		(net "CLK_322M_156M_CPU0_OSC_VRM_DP")
	)
	(segment
		(start 336.132932 -36.9443)
		(end 336.132932 -37.294058)
		(width 0.1143)
		(layer "In2.Cu")
		(net "CLK_322M_156M_CPU0_OSC_VRM_DP")
	)
	(segment
		(start 324.247002 -36.385246)
		(end 323.913754 -36.718494)
		(width 0.1143)
		(layer "In2.Cu")
		(net "CLK_322M_156M_CPU0_OSC_VRM_DP")
	)
	(segment
		(start 318.129158 -30.461966)
		(end 318.129158 -29.038042)
		(width 0.1143)
		(layer "In2.Cu")
		(net "CLK_322M_156M_CPU0_OSC_VRM_DP")
	)
	(segment
		(start 326.773794 -37.267642)
		(end 325.661274 -37.267642)
		(width 0.1143)
		(layer "In2.Cu")
		(net "CLK_322M_156M_CPU0_OSC_VRM_DP")
	)
	(segment
		(start 332.009242 -37.338762)
		(end 330.513436 -35.842956)
		(width 0.1143)
		(layer "In2.Cu")
		(net "CLK_322M_156M_CPU0_OSC_VRM_DP")
	)
	(segment
		(start 336.5754 -36.83)
		(end 336.247232 -36.83)
		(width 0.1143)
		(layer "In2.Cu")
		(net "CLK_322M_156M_CPU0_OSC_VRM_DP")
	)
	(segment
		(start 321.342258 -36.963858)
		(end 319.106042 -34.727642)
		(width 0.1143)
		(layer "In2.Cu")
		(net "CLK_322M_156M_CPU0_OSC_VRM_DP")
	)
	(segment
		(start 328.19848 -35.842956)
		(end 326.773794 -37.267642)
		(width 0.1143)
		(layer "In2.Cu")
		(net "CLK_322M_156M_CPU0_OSC_VRM_DP")
	)
	(segment
		(start 318.7446 -28.7528)
		(end 318.8716 -28.6258)
		(width 0.1143)
		(layer "In2.Cu")
		(net "CLK_322M_156M_CPU0_OSC_VRM_DP")
	)
	(segment
		(start 336.247232 -36.83)
		(end 336.132932 -36.9443)
		(width 0.1143)
		(layer "In2.Cu")
		(net "CLK_322M_156M_CPU0_OSC_VRM_DP")
	)
	(segment
		(start 318.4144 -28.7528)
		(end 318.7446 -28.7528)
		(width 0.1143)
		(layer "In2.Cu")
		(net "CLK_322M_156M_CPU0_OSC_VRM_DP")
	)
	(segment
		(start 318.8716 -28.6258)
		(end 318.8716 -27.432)
		(width 0.1143)
		(layer "In2.Cu")
		(net "CLK_322M_156M_CPU0_OSC_VRM_DP")
	)
	(segment
		(start 322.776342 -36.963858)
		(end 321.342258 -36.963858)
		(width 0.1143)
		(layer "In2.Cu")
		(net "CLK_322M_156M_CPU0_OSC_VRM_DP")
	)
	(segment
		(start 325.661274 -37.267642)
		(end 324.778878 -36.385246)
		(width 0.1143)
		(layer "In2.Cu")
		(net "CLK_322M_156M_CPU0_OSC_VRM_DP")
	)
	(segment
		(start 319.383918 -30.585918)
		(end 319.4812 -30.6832)
		(width 0.127)
		(layer "F.Cu")
		(net "CLK_322M_156M_CPU0_OSC_VRM_DN")
	)
	(segment
		(start 334.674972 -37.45103)
		(end 334.5942 -37.370258)
		(width 0.127)
		(layer "F.Cu")
		(net "CLK_322M_156M_CPU0_OSC_VRM_DN")
	)
	(segment
		(start 335.407 -36.109148)
		(end 335.407 -36.83)
		(width 0.127)
		(layer "F.Cu")
		(net "CLK_322M_156M_CPU0_OSC_VRM_DN")
	)
	(segment
		(start 318.8716 -30.585918)
		(end 319.383918 -30.585918)
		(width 0.127)
		(layer "F.Cu")
		(net "CLK_322M_156M_CPU0_OSC_VRM_DN")
	)
	(segment
		(start 334.801972 -35.924998)
		(end 335.22285 -35.924998)
		(width 0.127)
		(layer "F.Cu")
		(net "CLK_322M_156M_CPU0_OSC_VRM_DN")
	)
	(segment
		(start 335.22285 -35.924998)
		(end 335.407 -36.109148)
		(width 0.127)
		(layer "F.Cu")
		(net "CLK_322M_156M_CPU0_OSC_VRM_DN")
	)
	(segment
		(start 334.5942 -36.13277)
		(end 334.801972 -35.924998)
		(width 0.127)
		(layer "F.Cu")
		(net "CLK_322M_156M_CPU0_OSC_VRM_DN")
	)
	(segment
		(start 334.5942 -37.370258)
		(end 334.5942 -36.13277)
		(width 0.127)
		(layer "F.Cu")
		(net "CLK_322M_156M_CPU0_OSC_VRM_DN")
	)
	(via
		(at 319.4812 -30.6832)
		(size 0.508)
		(drill 0.254)
		(layers "F.Cu" "B.Cu")
		(net "CLK_322M_156M_CPU0_OSC_VRM_DN")
	)
	(via
		(at 335.407 -36.83)
		(size 0.508)
		(drill 0.254)
		(layers "F.Cu" "B.Cu")
		(net "CLK_322M_156M_CPU0_OSC_VRM_DN")
	)
	(segment
		(start 319.398142 -31.317692)
		(end 318.421258 -30.340808)
		(width 0.1143)
		(layer "In2.Cu")
		(net "CLK_322M_156M_CPU0_OSC_VRM_DN")
	)
	(segment
		(start 326.652636 -36.975542)
		(end 325.782432 -36.975542)
		(width 0.1143)
		(layer "In2.Cu")
		(net "CLK_322M_156M_CPU0_OSC_VRM_DN")
	)
	(segment
		(start 330.634594 -35.550856)
		(end 328.077322 -35.550856)
		(width 0.1143)
		(layer "In2.Cu")
		(net "CLK_322M_156M_CPU0_OSC_VRM_DN")
	)
	(segment
		(start 319.563242 -33.755584)
		(end 319.398142 -33.590484)
		(width 0.1143)
		(layer "In2.Cu")
		(net "CLK_322M_156M_CPU0_OSC_VRM_DN")
	)
	(segment
		(start 335.840832 -37.1729)
		(end 335.622392 -37.39134)
		(width 0.1143)
		(layer "In2.Cu")
		(net "CLK_322M_156M_CPU0_OSC_VRM_DN")
	)
	(segment
		(start 319.563242 -33.082484)
		(end 319.563242 -32.739584)
		(width 0.1143)
		(layer "In2.Cu")
		(net "CLK_322M_156M_CPU0_OSC_VRM_DN")
	)
	(segment
		(start 332.1304 -37.046662)
		(end 330.634594 -35.550856)
		(width 0.1143)
		(layer "In2.Cu")
		(net "CLK_322M_156M_CPU0_OSC_VRM_DN")
	)
	(segment
		(start 319.398142 -32.574484)
		(end 319.398142 -32.231584)
		(width 0.1143)
		(layer "In2.Cu")
		(net "CLK_322M_156M_CPU0_OSC_VRM_DN")
	)
	(segment
		(start 333.64678 -37.39134)
		(end 333.302102 -37.046662)
		(width 0.1143)
		(layer "In2.Cu")
		(net "CLK_322M_156M_CPU0_OSC_VRM_DN")
	)
	(segment
		(start 319.563242 -31.723584)
		(end 319.398142 -31.558484)
		(width 0.1143)
		(layer "In2.Cu")
		(net "CLK_322M_156M_CPU0_OSC_VRM_DN")
	)
	(segment
		(start 322.655184 -36.671758)
		(end 321.463416 -36.671758)
		(width 0.1143)
		(layer "In2.Cu")
		(net "CLK_322M_156M_CPU0_OSC_VRM_DN")
	)
	(segment
		(start 335.840832 -36.957)
		(end 335.840832 -37.1729)
		(width 0.1143)
		(layer "In2.Cu")
		(net "CLK_322M_156M_CPU0_OSC_VRM_DN")
	)
	(segment
		(start 319.398142 -33.590484)
		(end 319.398142 -33.247584)
		(width 0.1143)
		(layer "In2.Cu")
		(net "CLK_322M_156M_CPU0_OSC_VRM_DN")
	)
	(segment
		(start 318.951356 -29.746702)
		(end 319.4812 -30.276546)
		(width 0.1143)
		(layer "In2.Cu")
		(net "CLK_322M_156M_CPU0_OSC_VRM_DN")
	)
	(segment
		(start 319.398142 -33.247584)
		(end 319.563242 -33.082484)
		(width 0.1143)
		(layer "In2.Cu")
		(net "CLK_322M_156M_CPU0_OSC_VRM_DN")
	)
	(segment
		(start 319.563242 -34.098484)
		(end 319.563242 -33.755584)
		(width 0.1143)
		(layer "In2.Cu")
		(net "CLK_322M_156M_CPU0_OSC_VRM_DN")
	)
	(segment
		(start 318.7446 -29.0449)
		(end 318.951356 -29.251656)
		(width 0.1143)
		(layer "In2.Cu")
		(net "CLK_322M_156M_CPU0_OSC_VRM_DN")
	)
	(segment
		(start 319.398142 -32.231584)
		(end 319.563242 -32.066484)
		(width 0.1143)
		(layer "In2.Cu")
		(net "CLK_322M_156M_CPU0_OSC_VRM_DN")
	)
	(segment
		(start 321.463416 -36.671758)
		(end 319.398142 -34.606484)
		(width 0.1143)
		(layer "In2.Cu")
		(net "CLK_322M_156M_CPU0_OSC_VRM_DN")
	)
	(segment
		(start 318.421258 -30.340808)
		(end 318.421258 -29.1592)
		(width 0.1143)
		(layer "In2.Cu")
		(net "CLK_322M_156M_CPU0_OSC_VRM_DN")
	)
	(segment
		(start 335.713832 -36.83)
		(end 335.840832 -36.957)
		(width 0.1143)
		(layer "In2.Cu")
		(net "CLK_322M_156M_CPU0_OSC_VRM_DN")
	)
	(segment
		(start 333.302102 -37.046662)
		(end 332.1304 -37.046662)
		(width 0.1143)
		(layer "In2.Cu")
		(net "CLK_322M_156M_CPU0_OSC_VRM_DN")
	)
	(segment
		(start 322.900548 -36.426394)
		(end 322.655184 -36.671758)
		(width 0.1143)
		(layer "In2.Cu")
		(net "CLK_322M_156M_CPU0_OSC_VRM_DN")
	)
	(segment
		(start 318.535558 -29.0449)
		(end 318.7446 -29.0449)
		(width 0.1143)
		(layer "In2.Cu")
		(net "CLK_322M_156M_CPU0_OSC_VRM_DN")
	)
	(segment
		(start 318.421258 -29.1592)
		(end 318.535558 -29.0449)
		(width 0.1143)
		(layer "In2.Cu")
		(net "CLK_322M_156M_CPU0_OSC_VRM_DN")
	)
	(segment
		(start 324.125844 -36.093146)
		(end 323.792596 -36.426394)
		(width 0.1143)
		(layer "In2.Cu")
		(net "CLK_322M_156M_CPU0_OSC_VRM_DN")
	)
	(segment
		(start 319.398142 -31.558484)
		(end 319.398142 -31.317692)
		(width 0.1143)
		(layer "In2.Cu")
		(net "CLK_322M_156M_CPU0_OSC_VRM_DN")
	)
	(segment
		(start 335.622392 -37.39134)
		(end 333.64678 -37.39134)
		(width 0.1143)
		(layer "In2.Cu")
		(net "CLK_322M_156M_CPU0_OSC_VRM_DN")
	)
	(segment
		(start 319.398142 -34.263584)
		(end 319.563242 -34.098484)
		(width 0.1143)
		(layer "In2.Cu")
		(net "CLK_322M_156M_CPU0_OSC_VRM_DN")
	)
	(segment
		(start 319.398142 -34.606484)
		(end 319.398142 -34.263584)
		(width 0.1143)
		(layer "In2.Cu")
		(net "CLK_322M_156M_CPU0_OSC_VRM_DN")
	)
	(segment
		(start 328.077322 -35.550856)
		(end 326.652636 -36.975542)
		(width 0.1143)
		(layer "In2.Cu")
		(net "CLK_322M_156M_CPU0_OSC_VRM_DN")
	)
	(segment
		(start 319.563242 -32.739584)
		(end 319.398142 -32.574484)
		(width 0.1143)
		(layer "In2.Cu")
		(net "CLK_322M_156M_CPU0_OSC_VRM_DN")
	)
	(segment
		(start 319.4812 -30.276546)
		(end 319.4812 -30.6832)
		(width 0.1143)
		(layer "In2.Cu")
		(net "CLK_322M_156M_CPU0_OSC_VRM_DN")
	)
	(segment
		(start 324.900036 -36.093146)
		(end 324.125844 -36.093146)
		(width 0.1143)
		(layer "In2.Cu")
		(net "CLK_322M_156M_CPU0_OSC_VRM_DN")
	)
	(segment
		(start 318.951356 -29.251656)
		(end 318.951356 -29.746702)
		(width 0.1143)
		(layer "In2.Cu")
		(net "CLK_322M_156M_CPU0_OSC_VRM_DN")
	)
	(segment
		(start 335.407 -36.83)
		(end 335.713832 -36.83)
		(width 0.1143)
		(layer "In2.Cu")
		(net "CLK_322M_156M_CPU0_OSC_VRM_DN")
	)
	(segment
		(start 325.782432 -36.975542)
		(end 324.900036 -36.093146)
		(width 0.1143)
		(layer "In2.Cu")
		(net "CLK_322M_156M_CPU0_OSC_VRM_DN")
	)
	(segment
		(start 319.563242 -32.066484)
		(end 319.563242 -31.723584)
		(width 0.1143)
		(layer "In2.Cu")
		(net "CLK_322M_156M_CPU0_OSC_VRM_DN")
	)
	(segment
		(start 323.792596 -36.426394)
		(end 322.900548 -36.426394)
		(width 0.1143)
		(layer "In2.Cu")
		(net "CLK_322M_156M_CPU0_OSC_VRM_DN")
	)
	(segment
		(start 153.3398 -29.1084)
		(end 154.0764 -29.1084)
		(width 0.127)
		(layer "F.Cu")
		(net "CLK_156M_OSC_BRD_CPU1_DP")
	)
	(segment
		(start 154.0764 -29.1084)
		(end 154.305 -28.8798)
		(width 0.127)
		(layer "F.Cu")
		(net "CLK_156M_OSC_BRD_CPU1_DP")
	)
	(segment
		(start 152.4381 -28.6258)
		(end 152.8572 -28.6258)
		(width 0.127)
		(layer "F.Cu")
		(net "CLK_156M_OSC_BRD_CPU1_DP")
	)
	(segment
		(start 152.8572 -28.6258)
		(end 153.3398 -29.1084)
		(width 0.127)
		(layer "F.Cu")
		(net "CLK_156M_OSC_BRD_CPU1_DP")
	)
	(segment
		(start 152.4381 -29.8958)
		(end 152.8826 -29.8958)
		(width 0.127)
		(layer "F.Cu")
		(net "CLK_156M_OSC_BRD_CPU1_DN")
	)
	(segment
		(start 153.3652 -29.4132)
		(end 154.0764 -29.4132)
		(width 0.127)
		(layer "F.Cu")
		(net "CLK_156M_OSC_BRD_CPU1_DN")
	)
	(segment
		(start 154.0764 -29.4132)
		(end 154.305 -29.6418)
		(width 0.127)
		(layer "F.Cu")
		(net "CLK_156M_OSC_BRD_CPU1_DN")
	)
	(segment
		(start 152.8826 -29.8958)
		(end 153.3652 -29.4132)
		(width 0.127)
		(layer "F.Cu")
		(net "CLK_156M_OSC_BRD_CPU1_DN")
	)
	(segment
		(start 317.451232 -29.154628)
		(end 317.76289 -29.154628)
		(width 0.127)
		(layer "F.Cu")
		(net "CLK_156M_OSC_BRD_CPU0_DP")
	)
	(segment
		(start 316.29604 -27.72537)
		(end 316.42304 -27.85237)
		(width 0.127)
		(layer "F.Cu")
		(net "CLK_156M_OSC_BRD_CPU0_DP")
	)
	(segment
		(start 317.233808 -28.937204)
		(end 317.451232 -29.154628)
		(width 0.127)
		(layer "F.Cu")
		(net "CLK_156M_OSC_BRD_CPU0_DP")
	)
	(segment
		(start 316.55004 -28.20797)
		(end 316.856364 -28.20797)
		(width 0.127)
		(layer "F.Cu")
		(net "CLK_156M_OSC_BRD_CPU0_DP")
	)
	(segment
		(start 317.76289 -29.154628)
		(end 317.9826 -28.934918)
		(width 0.127)
		(layer "F.Cu")
		(net "CLK_156M_OSC_BRD_CPU0_DP")
	)
	(segment
		(start 316.42304 -28.08097)
		(end 316.55004 -28.20797)
		(width 0.127)
		(layer "F.Cu")
		(net "CLK_156M_OSC_BRD_CPU0_DP")
	)
	(segment
		(start 316.42304 -27.85237)
		(end 316.42304 -28.08097)
		(width 0.127)
		(layer "F.Cu")
		(net "CLK_156M_OSC_BRD_CPU0_DP")
	)
	(segment
		(start 315.317124 -27.72537)
		(end 316.29604 -27.72537)
		(width 0.127)
		(layer "F.Cu")
		(net "CLK_156M_OSC_BRD_CPU0_DP")
	)
	(segment
		(start 316.856364 -28.20797)
		(end 317.233808 -28.585414)
		(width 0.127)
		(layer "F.Cu")
		(net "CLK_156M_OSC_BRD_CPU0_DP")
	)
	(segment
		(start 317.233808 -28.585414)
		(end 317.233808 -28.937204)
		(width 0.127)
		(layer "F.Cu")
		(net "CLK_156M_OSC_BRD_CPU0_DP")
	)
	(segment
		(start 316.729872 -28.51277)
		(end 316.55004 -28.51277)
		(width 0.127)
		(layer "F.Cu")
		(net "CLK_156M_OSC_BRD_CPU0_DN")
	)
	(segment
		(start 317.74511 -29.459428)
		(end 317.32474 -29.459428)
		(width 0.127)
		(layer "F.Cu")
		(net "CLK_156M_OSC_BRD_CPU0_DN")
	)
	(segment
		(start 316.55004 -28.51277)
		(end 316.42304 -28.63977)
		(width 0.127)
		(layer "F.Cu")
		(net "CLK_156M_OSC_BRD_CPU0_DN")
	)
	(segment
		(start 317.32474 -29.459428)
		(end 317.126874 -29.261562)
		(width 0.127)
		(layer "F.Cu")
		(net "CLK_156M_OSC_BRD_CPU0_DN")
	)
	(segment
		(start 316.42304 -28.63977)
		(end 316.42304 -28.86837)
		(width 0.127)
		(layer "F.Cu")
		(net "CLK_156M_OSC_BRD_CPU0_DN")
	)
	(segment
		(start 316.929008 -29.063696)
		(end 316.929008 -28.711906)
		(width 0.127)
		(layer "F.Cu")
		(net "CLK_156M_OSC_BRD_CPU0_DN")
	)
	(segment
		(start 316.42304 -28.86837)
		(end 316.29604 -28.99537)
		(width 0.127)
		(layer "F.Cu")
		(net "CLK_156M_OSC_BRD_CPU0_DN")
	)
	(segment
		(start 317.9826 -29.696918)
		(end 317.74511 -29.459428)
		(width 0.127)
		(layer "F.Cu")
		(net "CLK_156M_OSC_BRD_CPU0_DN")
	)
	(segment
		(start 317.126874 -29.261562)
		(end 316.929008 -29.063696)
		(width 0.127)
		(layer "F.Cu")
		(net "CLK_156M_OSC_BRD_CPU0_DN")
	)
	(segment
		(start 316.29604 -28.99537)
		(end 315.317124 -28.99537)
		(width 0.127)
		(layer "F.Cu")
		(net "CLK_156M_OSC_BRD_CPU0_DN")
	)
	(segment
		(start 316.929008 -28.711906)
		(end 316.729872 -28.51277)
		(width 0.127)
		(layer "F.Cu")
		(net "CLK_156M_OSC_BRD_CPU0_DN")
	)
	(via
		(at 317.126874 -29.261562)
		(size 0.508)
		(drill 0.254)
		(layers "F.Cu" "B.Cu")
		(net "CLK_156M_OSC_BRD_CPU0_DN")
	)
	(segment
		(start 403.486112 -123.7742)
		(end 403.86 -123.7742)
		(width 0.1016)
		(layer "F.Cu")
		(net "A_USB2_VBUS")
	)
	(segment
		(start 400.05 -123.952)
		(end 400.05 -123.825)
		(width 0.1016)
		(layer "F.Cu")
		(net "A_USB2_VBUS")
	)
	(segment
		(start 401.2184 -122.4788)
		(end 402.190712 -122.4788)
		(width 0.1016)
		(layer "F.Cu")
		(net "A_USB2_VBUS")
	)
	(segment
		(start 402.190712 -122.4788)
		(end 403.486112 -123.7742)
		(width 0.1016)
		(layer "F.Cu")
		(net "A_USB2_VBUS")
	)
	(segment
		(start 400.812 -122.8852)
		(end 401.2184 -122.4788)
		(width 0.1016)
		(layer "F.Cu")
		(net "A_USB2_VBUS")
	)
	(segment
		(start 398.876012 -124.211334)
		(end 399.790666 -124.211334)
		(width 0.1016)
		(layer "F.Cu")
		(net "A_USB2_VBUS")
	)
	(segment
		(start 399.790666 -124.211334)
		(end 400.05 -123.952)
		(width 0.1016)
		(layer "F.Cu")
		(net "A_USB2_VBUS")
	)
	(segment
		(start 400.05 -123.825)
		(end 400.812 -123.063)
		(width 0.1016)
		(layer "F.Cu")
		(net "A_USB2_VBUS")
	)
	(segment
		(start 400.812 -123.063)
		(end 400.812 -122.8852)
		(width 0.1016)
		(layer "F.Cu")
		(net "A_USB2_VBUS")
	)
	(segment
		(start 29.56687 -72.03313)
		(end 29.036518 -72.03313)
		(width 0.10795)
		(layer "F.Cu")
		(net "VR_PVCCIN_CPU1_PH3_OCSET")
	)
	(segment
		(start 29.036518 -71.683118)
		(end 29.036518 -72.03313)
		(width 0.10795)
		(layer "F.Cu")
		(net "VR_PVCCIN_CPU1_PH3_OCSET")
	)
	(segment
		(start 30.16758 -71.92518)
		(end 29.67482 -71.92518)
		(width 0.10795)
		(layer "F.Cu")
		(net "VR_PVCCIN_CPU1_PH3_OCSET")
	)
	(segment
		(start 28.7274 -70.739)
		(end 28.7274 -71.374)
		(width 0.10795)
		(layer "F.Cu")
		(net "VR_PVCCIN_CPU1_PH3_OCSET")
	)
	(segment
		(start 28.7274 -71.374)
		(end 29.036518 -71.683118)
		(width 0.10795)
		(layer "F.Cu")
		(net "VR_PVCCIN_CPU1_PH3_OCSET")
	)
	(segment
		(start 29.67482 -71.92518)
		(end 29.56687 -72.03313)
		(width 0.10795)
		(layer "F.Cu")
		(net "VR_PVCCIN_CPU1_PH3_OCSET")
	)
	(segment
		(start 31.02991 -72.19569)
		(end 30.43809 -72.19569)
		(width 0.10795)
		(layer "F.Cu")
		(net "VR_PVCCIN_CPU1_PH3_OCSET")
	)
	(segment
		(start 28.5496 -70.5612)
		(end 28.7274 -70.739)
		(width 0.10795)
		(layer "F.Cu")
		(net "VR_PVCCIN_CPU1_PH3_OCSET")
	)
	(segment
		(start 30.43809 -72.19569)
		(end 30.16758 -71.92518)
		(width 0.10795)
		(layer "F.Cu")
		(net "VR_PVCCIN_CPU1_PH3_OCSET")
	)
	(via
		(at 28.5496 -70.5612)
		(size 0.762)
		(drill 0.381)
		(layers "F.Cu" "B.Cu")
		(net "VR_PVCCIN_CPU1_PH3_OCSET")
	)
	(segment
		(start 30.191202 -63.832232)
		(end 30.42666 -64.06769)
		(width 0.1016)
		(layer "F.Cu")
		(net "VR_PVCCIN_CPU1_PH2_OCSET")
	)
	(segment
		(start 28.4988 -62.7888)
		(end 28.851352 -63.141352)
		(width 0.10795)
		(layer "F.Cu")
		(net "VR_PVCCIN_CPU1_PH2_OCSET")
	)
	(segment
		(start 29.690568 -63.832232)
		(end 30.191202 -63.832232)
		(width 0.1016)
		(layer "F.Cu")
		(net "VR_PVCCIN_CPU1_PH2_OCSET")
	)
	(segment
		(start 30.42666 -64.06769)
		(end 31.02991 -64.06769)
		(width 0.1016)
		(layer "F.Cu")
		(net "VR_PVCCIN_CPU1_PH2_OCSET")
	)
	(segment
		(start 28.851352 -64.089788)
		(end 29.433012 -64.089788)
		(width 0.1016)
		(layer "F.Cu")
		(net "VR_PVCCIN_CPU1_PH2_OCSET")
	)
	(segment
		(start 28.851352 -63.141352)
		(end 28.851352 -64.089788)
		(width 0.10795)
		(layer "F.Cu")
		(net "VR_PVCCIN_CPU1_PH2_OCSET")
	)
	(segment
		(start 29.433012 -64.089788)
		(end 29.690568 -63.832232)
		(width 0.1016)
		(layer "F.Cu")
		(net "VR_PVCCIN_CPU1_PH2_OCSET")
	)
	(via
		(at 28.4988 -62.7888)
		(size 0.762)
		(drill 0.381)
		(layers "F.Cu" "B.Cu")
		(net "VR_PVCCIN_CPU1_PH2_OCSET")
	)
	(segment
		(start 397.231108 -83.388454)
		(end 397.467074 -83.62442)
		(width 0.10795)
		(layer "F.Cu")
		(net "FM_PCH_BMC_THERMTRIP_EXI_STRAP_")
	)
	(segment
		(start 396.246096 -83.6168)
		(end 396.474442 -83.388454)
		(width 0.10795)
		(layer "F.Cu")
		(net "FM_PCH_BMC_THERMTRIP_EXI_STRAP_")
	)
	(segment
		(start 397.64335 -102.12832)
		(end 398.13865 -101.898196)
		(width 0.10795)
		(layer "F.Cu")
		(net "FM_PCH_BMC_THERMTRIP_EXI_STRAP_")
	)
	(segment
		(start 397.467074 -83.62442)
		(end 397.467074 -84.309204)
		(width 0.10795)
		(layer "F.Cu")
		(net "FM_PCH_BMC_THERMTRIP_EXI_STRAP_")
	)
	(segment
		(start 396.474442 -83.388454)
		(end 397.231108 -83.388454)
		(width 0.10795)
		(layer "F.Cu")
		(net "FM_PCH_BMC_THERMTRIP_EXI_STRAP_")
	)
	(via
		(at 396.246096 -83.6168)
		(size 0.508)
		(drill 0.254)
		(layers "F.Cu" "B.Cu")
		(net "FM_PCH_BMC_THERMTRIP_EXI_STRAP_")
	)
	(via
		(at 398.13865 -101.898196)
		(size 0.508)
		(drill 0.254)
		(layers "F.Cu" "B.Cu")
		(net "FM_PCH_BMC_THERMTRIP_EXI_STRAP_")
	)
	(via
		(at 401.0025 -99.32924)
		(size 0.6604)
		(drill 0.3302)
		(layers "F.Cu" "B.Cu")
		(net "FM_PCH_BMC_THERMTRIP_EXI_STRAP_")
	)
	(segment
		(start 402.014182 -97.917)
		(end 403.6695 -97.917)
		(width 0.10795)
		(layer "B.Cu")
		(net "FM_PCH_BMC_THERMTRIP_EXI_STRAP_")
	)
	(segment
		(start 398.407636 -100.59035)
		(end 399.352516 -100.59035)
		(width 0.10795)
		(layer "B.Cu")
		(net "FM_PCH_BMC_THERMTRIP_EXI_STRAP_")
	)
	(segment
		(start 401.245324 -98.685858)
		(end 402.014182 -97.917)
		(width 0.10795)
		(layer "B.Cu")
		(net "FM_PCH_BMC_THERMTRIP_EXI_STRAP_")
	)
	(segment
		(start 401.245324 -99.086416)
		(end 401.245324 -98.685858)
		(width 0.10795)
		(layer "B.Cu")
		(net "FM_PCH_BMC_THERMTRIP_EXI_STRAP_")
	)
	(segment
		(start 399.352516 -100.59035)
		(end 400.22145 -99.721416)
		(width 0.10795)
		(layer "B.Cu")
		(net "FM_PCH_BMC_THERMTRIP_EXI_STRAP_")
	)
	(segment
		(start 400.610324 -99.721416)
		(end 401.0025 -99.32924)
		(width 0.10795)
		(layer "B.Cu")
		(net "FM_PCH_BMC_THERMTRIP_EXI_STRAP_")
	)
	(segment
		(start 398.13865 -100.859336)
		(end 398.407636 -100.59035)
		(width 0.10795)
		(layer "B.Cu")
		(net "FM_PCH_BMC_THERMTRIP_EXI_STRAP_")
	)
	(segment
		(start 401.0025 -99.32924)
		(end 401.245324 -99.086416)
		(width 0.10795)
		(layer "B.Cu")
		(net "FM_PCH_BMC_THERMTRIP_EXI_STRAP_")
	)
	(segment
		(start 398.13865 -101.898196)
		(end 398.13865 -100.859336)
		(width 0.10795)
		(layer "B.Cu")
		(net "FM_PCH_BMC_THERMTRIP_EXI_STRAP_")
	)
	(segment
		(start 400.22145 -99.721416)
		(end 400.610324 -99.721416)
		(width 0.10795)
		(layer "B.Cu")
		(net "FM_PCH_BMC_THERMTRIP_EXI_STRAP_")
	)
	(segment
		(start 398.745964 -100.362004)
		(end 398.745964 -100.439728)
		(width 0.089408)
		(layer "In2.Cu")
		(net "FM_PCH_BMC_THERMTRIP_EXI_STRAP_")
	)
	(segment
		(start 397.582898 -93.70822)
		(end 399.853912 -95.979234)
		(width 0.089408)
		(layer "In2.Cu")
		(net "FM_PCH_BMC_THERMTRIP_EXI_STRAP_")
	)
	(segment
		(start 398.028414 -88.65362)
		(end 398.028414 -90.286586)
		(width 0.089408)
		(layer "In2.Cu")
		(net "FM_PCH_BMC_THERMTRIP_EXI_STRAP_")
	)
	(segment
		(start 399.128488 -100.822252)
		(end 399.128488 -101.135688)
		(width 0.089408)
		(layer "In2.Cu")
		(net "FM_PCH_BMC_THERMTRIP_EXI_STRAP_")
	)
	(segment
		(start 398.95272 -98.05924)
		(end 398.73047 -98.28149)
		(width 0.089408)
		(layer "In2.Cu")
		(net "FM_PCH_BMC_THERMTRIP_EXI_STRAP_")
	)
	(segment
		(start 396.246096 -83.6168)
		(end 396.6464 -84.017104)
		(width 0.089408)
		(layer "In2.Cu")
		(net "FM_PCH_BMC_THERMTRIP_EXI_STRAP_")
	)
	(segment
		(start 398.028414 -90.286586)
		(end 397.582898 -90.732102)
		(width 0.089408)
		(layer "In2.Cu")
		(net "FM_PCH_BMC_THERMTRIP_EXI_STRAP_")
	)
	(segment
		(start 396.6464 -86.403434)
		(end 396.601696 -86.448138)
		(width 0.089408)
		(layer "In2.Cu")
		(net "FM_PCH_BMC_THERMTRIP_EXI_STRAP_")
	)
	(segment
		(start 399.128488 -101.135688)
		(end 398.36598 -101.898196)
		(width 0.089408)
		(layer "In2.Cu")
		(net "FM_PCH_BMC_THERMTRIP_EXI_STRAP_")
	)
	(segment
		(start 399.14322 -99.603052)
		(end 398.73047 -100.015802)
		(width 0.089408)
		(layer "In2.Cu")
		(net "FM_PCH_BMC_THERMTRIP_EXI_STRAP_")
	)
	(segment
		(start 398.73047 -98.70059)
		(end 399.14322 -99.11334)
		(width 0.089408)
		(layer "In2.Cu")
		(net "FM_PCH_BMC_THERMTRIP_EXI_STRAP_")
	)
	(segment
		(start 399.853912 -95.979234)
		(end 399.853912 -97.371662)
		(width 0.089408)
		(layer "In2.Cu")
		(net "FM_PCH_BMC_THERMTRIP_EXI_STRAP_")
	)
	(segment
		(start 396.6464 -84.017104)
		(end 396.6464 -86.403434)
		(width 0.089408)
		(layer "In2.Cu")
		(net "FM_PCH_BMC_THERMTRIP_EXI_STRAP_")
	)
	(segment
		(start 397.582898 -90.732102)
		(end 397.582898 -93.70822)
		(width 0.089408)
		(layer "In2.Cu")
		(net "FM_PCH_BMC_THERMTRIP_EXI_STRAP_")
	)
	(segment
		(start 398.73047 -98.28149)
		(end 398.73047 -98.70059)
		(width 0.089408)
		(layer "In2.Cu")
		(net "FM_PCH_BMC_THERMTRIP_EXI_STRAP_")
	)
	(segment
		(start 398.73047 -100.34651)
		(end 398.745964 -100.362004)
		(width 0.089408)
		(layer "In2.Cu")
		(net "FM_PCH_BMC_THERMTRIP_EXI_STRAP_")
	)
	(segment
		(start 396.601696 -87.226902)
		(end 398.028414 -88.65362)
		(width 0.089408)
		(layer "In2.Cu")
		(net "FM_PCH_BMC_THERMTRIP_EXI_STRAP_")
	)
	(segment
		(start 396.601696 -86.448138)
		(end 396.601696 -87.226902)
		(width 0.089408)
		(layer "In2.Cu")
		(net "FM_PCH_BMC_THERMTRIP_EXI_STRAP_")
	)
	(segment
		(start 399.14322 -99.11334)
		(end 399.14322 -99.603052)
		(width 0.089408)
		(layer "In2.Cu")
		(net "FM_PCH_BMC_THERMTRIP_EXI_STRAP_")
	)
	(segment
		(start 398.73047 -100.015802)
		(end 398.73047 -100.34651)
		(width 0.089408)
		(layer "In2.Cu")
		(net "FM_PCH_BMC_THERMTRIP_EXI_STRAP_")
	)
	(segment
		(start 398.36598 -101.898196)
		(end 398.13865 -101.898196)
		(width 0.089408)
		(layer "In2.Cu")
		(net "FM_PCH_BMC_THERMTRIP_EXI_STRAP_")
	)
	(segment
		(start 398.745964 -100.439728)
		(end 399.128488 -100.822252)
		(width 0.089408)
		(layer "In2.Cu")
		(net "FM_PCH_BMC_THERMTRIP_EXI_STRAP_")
	)
	(segment
		(start 399.166334 -98.05924)
		(end 398.95272 -98.05924)
		(width 0.089408)
		(layer "In2.Cu")
		(net "FM_PCH_BMC_THERMTRIP_EXI_STRAP_")
	)
	(segment
		(start 399.853912 -97.371662)
		(end 399.166334 -98.05924)
		(width 0.089408)
		(layer "In2.Cu")
		(net "FM_PCH_BMC_THERMTRIP_EXI_STRAP_")
	)
	(segment
		(start 167.672512 -85.330792)
		(end 167.672512 -85.832188)
		(width 0.10795)
		(layer "F.Cu")
		(net "FM_DB1200ZL_BCLKS_EN_N")
	)
	(segment
		(start 174.7774 -78.3463)
		(end 174.7774 -78.3844)
		(width 0.10795)
		(layer "F.Cu")
		(net "FM_DB1200ZL_BCLKS_EN_N")
	)
	(segment
		(start 167.172386 -85.330792)
		(end 167.172386 -85.955886)
		(width 0.10795)
		(layer "F.Cu")
		(net "FM_DB1200ZL_BCLKS_EN_N")
	)
	(segment
		(start 174.7774 -78.3971)
		(end 174.7774 -78.3844)
		(width 0.10795)
		(layer "F.Cu")
		(net "FM_DB1200ZL_BCLKS_EN_N")
	)
	(segment
		(start 370.345208 -79.894684)
		(end 370.745004 -79.494888)
		(width 0.10795)
		(layer "F.Cu")
		(net "FM_DB1200ZL_BCLKS_EN_N")
	)
	(segment
		(start 167.672512 -85.832188)
		(end 167.3606 -86.1441)
		(width 0.10795)
		(layer "F.Cu")
		(net "FM_DB1200ZL_BCLKS_EN_N")
	)
	(segment
		(start 174.462948 -78.711552)
		(end 174.7774 -78.3971)
		(width 0.10795)
		(layer "F.Cu")
		(net "FM_DB1200ZL_BCLKS_EN_N")
	)
	(segment
		(start 165.054026 -83.212686)
		(end 164.865558 -83.212686)
		(width 0.10795)
		(layer "F.Cu")
		(net "FM_DB1200ZL_BCLKS_EN_N")
	)
	(segment
		(start 173.791626 -82.71256)
		(end 174.46244 -82.71256)
		(width 0.10795)
		(layer "F.Cu")
		(net "FM_DB1200ZL_BCLKS_EN_N")
	)
	(segment
		(start 164.157152 -83.505802)
		(end 164.153088 -83.5152)
		(width 0.10795)
		(layer "F.Cu")
		(net "FM_DB1200ZL_BCLKS_EN_N")
	)
	(segment
		(start 174.642526 -78.211426)
		(end 174.7774 -78.3463)
		(width 0.10795)
		(layer "F.Cu")
		(net "FM_DB1200ZL_BCLKS_EN_N")
	)
	(segment
		(start 173.791626 -78.211426)
		(end 174.642526 -78.211426)
		(width 0.10795)
		(layer "F.Cu")
		(net "FM_DB1200ZL_BCLKS_EN_N")
	)
	(segment
		(start 174.46244 -82.71256)
		(end 174.5742 -82.6008)
		(width 0.10795)
		(layer "F.Cu")
		(net "FM_DB1200ZL_BCLKS_EN_N")
	)
	(segment
		(start 164.865558 -83.212686)
		(end 164.157152 -83.505802)
		(width 0.10795)
		(layer "F.Cu")
		(net "FM_DB1200ZL_BCLKS_EN_N")
	)
	(segment
		(start 173.791626 -78.711552)
		(end 174.462948 -78.711552)
		(width 0.10795)
		(layer "F.Cu")
		(net "FM_DB1200ZL_BCLKS_EN_N")
	)
	(segment
		(start 167.172386 -85.955886)
		(end 167.3606 -86.1441)
		(width 0.10795)
		(layer "F.Cu")
		(net "FM_DB1200ZL_BCLKS_EN_N")
	)
	(via
		(at 174.5742 -82.6008)
		(size 0.508)
		(drill 0.254)
		(layers "F.Cu" "B.Cu")
		(net "FM_DB1200ZL_BCLKS_EN_N")
	)
	(via
		(at 164.153088 -83.5152)
		(size 0.508)
		(drill 0.254)
		(layers "F.Cu" "B.Cu")
		(net "FM_DB1200ZL_BCLKS_EN_N")
	)
	(via
		(at 370.345208 -79.894684)
		(size 0.4572)
		(drill 0.2032)
		(layers "F.Cu" "B.Cu")
		(net "FM_DB1200ZL_BCLKS_EN_N")
	)
	(via
		(at 368.7699 -66.5988)
		(size 0.508)
		(drill 0.254)
		(layers "F.Cu" "B.Cu")
		(net "FM_DB1200ZL_BCLKS_EN_N")
	)
	(via
		(at 167.3606 -86.1441)
		(size 0.508)
		(drill 0.254)
		(layers "F.Cu" "B.Cu")
		(net "FM_DB1200ZL_BCLKS_EN_N")
	)
	(via
		(at 177.9778 -77.2922)
		(size 0.6604)
		(drill 0.3302)
		(layers "F.Cu" "B.Cu")
		(net "FM_DB1200ZL_BCLKS_EN_N")
	)
	(via
		(at 174.7774 -78.3844)
		(size 0.508)
		(drill 0.254)
		(layers "F.Cu" "B.Cu")
		(net "FM_DB1200ZL_BCLKS_EN_N")
	)
	(segment
		(start 177.2158 -78.6892)
		(end 177.673 -78.232)
		(width 0.10795)
		(layer "B.Cu")
		(net "FM_DB1200ZL_BCLKS_EN_N")
	)
	(segment
		(start 174.7774 -78.3844)
		(end 175.0822 -78.6892)
		(width 0.10795)
		(layer "B.Cu")
		(net "FM_DB1200ZL_BCLKS_EN_N")
	)
	(segment
		(start 177.673 -78.232)
		(end 177.927 -78.232)
		(width 0.10795)
		(layer "B.Cu")
		(net "FM_DB1200ZL_BCLKS_EN_N")
	)
	(segment
		(start 177.9778 -77.7494)
		(end 177.927 -77.8002)
		(width 0.10795)
		(layer "B.Cu")
		(net "FM_DB1200ZL_BCLKS_EN_N")
	)
	(segment
		(start 177.9778 -77.2922)
		(end 177.9778 -77.7494)
		(width 0.10795)
		(layer "B.Cu")
		(net "FM_DB1200ZL_BCLKS_EN_N")
	)
	(segment
		(start 175.0822 -78.6892)
		(end 177.2158 -78.6892)
		(width 0.10795)
		(layer "B.Cu")
		(net "FM_DB1200ZL_BCLKS_EN_N")
	)
	(segment
		(start 177.927 -77.8002)
		(end 177.927 -78.232)
		(width 0.10795)
		(layer "B.Cu")
		(net "FM_DB1200ZL_BCLKS_EN_N")
	)
	(segment
		(start 281.253946 -156.438346)
		(end 281.708606 -156.893006)
		(width 0.089408)
		(layer "In4.Cu")
		(net "FM_DB1200ZL_BCLKS_EN_N")
	)
	(segment
		(start 328.978768 -137.718038)
		(end 330.312776 -136.38403)
		(width 0.089408)
		(layer "In4.Cu")
		(net "FM_DB1200ZL_BCLKS_EN_N")
	)
	(segment
		(start 161.20999 -128.6129)
		(end 160.011872 -129.811018)
		(width 0.089408)
		(layer "In4.Cu")
		(net "FM_DB1200ZL_BCLKS_EN_N")
	)
	(segment
		(start 176.149 -84.836)
		(end 177.038 -85.725)
		(width 0.089408)
		(layer "In4.Cu")
		(net "FM_DB1200ZL_BCLKS_EN_N")
	)
	(segment
		(start 326.425052 -122.504708)
		(end 326.425052 -118.213632)
		(width 0.089408)
		(layer "In4.Cu")
		(net "FM_DB1200ZL_BCLKS_EN_N")
	)
	(segment
		(start 354.41001 -69.784468)
		(end 357.47706 -69.784468)
		(width 0.089408)
		(layer "In4.Cu")
		(net "FM_DB1200ZL_BCLKS_EN_N")
	)
	(segment
		(start 336.16265 -74.42835)
		(end 338.89696 -71.69404)
		(width 0.089408)
		(layer "In4.Cu")
		(net "FM_DB1200ZL_BCLKS_EN_N")
	)
	(segment
		(start 324.366128 -139.890754)
		(end 326.538844 -137.718038)
		(width 0.089408)
		(layer "In4.Cu")
		(net "FM_DB1200ZL_BCLKS_EN_N")
	)
	(segment
		(start 176.149 -84.1756)
		(end 176.149 -84.836)
		(width 0.089408)
		(layer "In4.Cu")
		(net "FM_DB1200ZL_BCLKS_EN_N")
	)
	(segment
		(start 176.552352 -144.916906)
		(end 177.489358 -145.853912)
		(width 0.089408)
		(layer "In4.Cu")
		(net "FM_DB1200ZL_BCLKS_EN_N")
	)
	(segment
		(start 335.370932 -79.585312)
		(end 335.370932 -78.5368)
		(width 0.089408)
		(layer "In4.Cu")
		(net "FM_DB1200ZL_BCLKS_EN_N")
	)
	(segment
		(start 171.725336 -129.972562)
		(end 169.80789 -129.972562)
		(width 0.089408)
		(layer "In4.Cu")
		(net "FM_DB1200ZL_BCLKS_EN_N")
	)
	(segment
		(start 346.084906 -70.166992)
		(end 352.430588 -70.166992)
		(width 0.089408)
		(layer "In4.Cu")
		(net "FM_DB1200ZL_BCLKS_EN_N")
	)
	(segment
		(start 281.708606 -156.893006)
		(end 321.879976 -156.893006)
		(width 0.089408)
		(layer "In4.Cu")
		(net "FM_DB1200ZL_BCLKS_EN_N")
	)
	(segment
		(start 363.835188 -69.606414)
		(end 366.452912 -66.98869)
		(width 0.089408)
		(layer "In4.Cu")
		(net "FM_DB1200ZL_BCLKS_EN_N")
	)
	(segment
		(start 169.80789 -129.972562)
		(end 168.448228 -128.6129)
		(width 0.089408)
		(layer "In4.Cu")
		(net "FM_DB1200ZL_BCLKS_EN_N")
	)
	(segment
		(start 366.452912 -66.98869)
		(end 366.6109 -66.98869)
		(width 0.089408)
		(layer "In4.Cu")
		(net "FM_DB1200ZL_BCLKS_EN_N")
	)
	(segment
		(start 176.911 -100.584)
		(end 177.3682 -101.0412)
		(width 0.089408)
		(layer "In4.Cu")
		(net "FM_DB1200ZL_BCLKS_EN_N")
	)
	(segment
		(start 177.489358 -145.853912)
		(end 184.972198 -145.853912)
		(width 0.089408)
		(layer "In4.Cu")
		(net "FM_DB1200ZL_BCLKS_EN_N")
	)
	(segment
		(start 339.324442 -71.69404)
		(end 340.066122 -70.95236)
		(width 0.089408)
		(layer "In4.Cu")
		(net "FM_DB1200ZL_BCLKS_EN_N")
	)
	(segment
		(start 176.911 -98.425)
		(end 176.911 -100.584)
		(width 0.089408)
		(layer "In4.Cu")
		(net "FM_DB1200ZL_BCLKS_EN_N")
	)
	(segment
		(start 169.359326 -144.556734)
		(end 172.037248 -144.556734)
		(width 0.089408)
		(layer "In4.Cu")
		(net "FM_DB1200ZL_BCLKS_EN_N")
	)
	(segment
		(start 186.5376 -145.666206)
		(end 186.5376 -146.97456)
		(width 0.089408)
		(layer "In4.Cu")
		(net "FM_DB1200ZL_BCLKS_EN_N")
	)
	(segment
		(start 168.448228 -128.6129)
		(end 161.20999 -128.6129)
		(width 0.089408)
		(layer "In4.Cu")
		(net "FM_DB1200ZL_BCLKS_EN_N")
	)
	(segment
		(start 175.801782 -129.3241)
		(end 172.373798 -129.3241)
		(width 0.089408)
		(layer "In4.Cu")
		(net "FM_DB1200ZL_BCLKS_EN_N")
	)
	(segment
		(start 187.287408 -150.429722)
		(end 190.733426 -153.87574)
		(width 0.089408)
		(layer "In4.Cu")
		(net "FM_DB1200ZL_BCLKS_EN_N")
	)
	(segment
		(start 354.40874 -69.785484)
		(end 354.408994 -69.785484)
		(width 0.089408)
		(layer "In4.Cu")
		(net "FM_DB1200ZL_BCLKS_EN_N")
	)
	(segment
		(start 172.373798 -129.3241)
		(end 171.725336 -129.972562)
		(width 0.089408)
		(layer "In4.Cu")
		(net "FM_DB1200ZL_BCLKS_EN_N")
	)
	(segment
		(start 191.14008 -156.72308)
		(end 264.464546 -156.72308)
		(width 0.089408)
		(layer "In4.Cu")
		(net "FM_DB1200ZL_BCLKS_EN_N")
	)
	(segment
		(start 264.74928 -156.438346)
		(end 281.253946 -156.438346)
		(width 0.089408)
		(layer "In4.Cu")
		(net "FM_DB1200ZL_BCLKS_EN_N")
	)
	(segment
		(start 176.77384 -94.536006)
		(end 176.77384 -98.28784)
		(width 0.089408)
		(layer "In4.Cu")
		(net "FM_DB1200ZL_BCLKS_EN_N")
	)
	(segment
		(start 161.25952 -142.088108)
		(end 166.8907 -142.088108)
		(width 0.089408)
		(layer "In4.Cu")
		(net "FM_DB1200ZL_BCLKS_EN_N")
	)
	(segment
		(start 190.733426 -156.316426)
		(end 191.14008 -156.72308)
		(width 0.089408)
		(layer "In4.Cu")
		(net "FM_DB1200ZL_BCLKS_EN_N")
	)
	(segment
		(start 177.7492 -124.2314)
		(end 177.7492 -127.376682)
		(width 0.089408)
		(layer "In4.Cu")
		(net "FM_DB1200ZL_BCLKS_EN_N")
	)
	(segment
		(start 174.5742 -82.6008)
		(end 176.149 -84.1756)
		(width 0.089408)
		(layer "In4.Cu")
		(net "FM_DB1200ZL_BCLKS_EN_N")
	)
	(segment
		(start 331.18552 -129.739644)
		(end 327.707498 -126.261622)
		(width 0.089408)
		(layer "In4.Cu")
		(net "FM_DB1200ZL_BCLKS_EN_N")
	)
	(segment
		(start 186.25439 -145.382996)
		(end 186.5376 -145.666206)
		(width 0.089408)
		(layer "In4.Cu")
		(net "FM_DB1200ZL_BCLKS_EN_N")
	)
	(segment
		(start 325.283322 -115.202716)
		(end 325.283322 -92.48394)
		(width 0.089408)
		(layer "In4.Cu")
		(net "FM_DB1200ZL_BCLKS_EN_N")
	)
	(segment
		(start 326.538844 -137.718038)
		(end 328.978768 -137.718038)
		(width 0.089408)
		(layer "In4.Cu")
		(net "FM_DB1200ZL_BCLKS_EN_N")
	)
	(segment
		(start 184.972198 -145.853912)
		(end 185.443114 -145.382996)
		(width 0.089408)
		(layer "In4.Cu")
		(net "FM_DB1200ZL_BCLKS_EN_N")
	)
	(segment
		(start 177.7492 -127.376682)
		(end 175.801782 -129.3241)
		(width 0.089408)
		(layer "In4.Cu")
		(net "FM_DB1200ZL_BCLKS_EN_N")
	)
	(segment
		(start 330.312776 -135.416544)
		(end 331.18552 -134.5438)
		(width 0.089408)
		(layer "In4.Cu")
		(net "FM_DB1200ZL_BCLKS_EN_N")
	)
	(segment
		(start 352.62566 -70.362064)
		(end 353.83216 -70.362064)
		(width 0.089408)
		(layer "In4.Cu")
		(net "FM_DB1200ZL_BCLKS_EN_N")
	)
	(segment
		(start 363.835188 -69.90842)
		(end 363.835188 -69.606414)
		(width 0.089408)
		(layer "In4.Cu")
		(net "FM_DB1200ZL_BCLKS_EN_N")
	)
	(segment
		(start 325.98106 -115.900454)
		(end 325.283322 -115.202716)
		(width 0.089408)
		(layer "In4.Cu")
		(net "FM_DB1200ZL_BCLKS_EN_N")
	)
	(segment
		(start 353.83216 -70.362064)
		(end 354.40874 -69.785484)
		(width 0.089408)
		(layer "In4.Cu")
		(net "FM_DB1200ZL_BCLKS_EN_N")
	)
	(segment
		(start 332.334616 -85.432646)
		(end 332.334616 -82.621628)
		(width 0.089408)
		(layer "In4.Cu")
		(net "FM_DB1200ZL_BCLKS_EN_N")
	)
	(segment
		(start 177.3682 -123.8504)
		(end 177.7492 -124.2314)
		(width 0.089408)
		(layer "In4.Cu")
		(net "FM_DB1200ZL_BCLKS_EN_N")
	)
	(segment
		(start 358.70642 -71.013828)
		(end 362.72978 -71.013828)
		(width 0.089408)
		(layer "In4.Cu")
		(net "FM_DB1200ZL_BCLKS_EN_N")
	)
	(segment
		(start 366.6109 -66.98869)
		(end 366.611154 -66.988944)
		(width 0.089408)
		(layer "In4.Cu")
		(net "FM_DB1200ZL_BCLKS_EN_N")
	)
	(segment
		(start 178.008788 -93.301058)
		(end 176.77384 -94.536006)
		(width 0.089408)
		(layer "In4.Cu")
		(net "FM_DB1200ZL_BCLKS_EN_N")
	)
	(segment
		(start 176.77384 -98.28784)
		(end 176.911 -98.425)
		(width 0.089408)
		(layer "In4.Cu")
		(net "FM_DB1200ZL_BCLKS_EN_N")
	)
	(segment
		(start 177.3682 -101.0412)
		(end 177.3682 -123.8504)
		(width 0.089408)
		(layer "In4.Cu")
		(net "FM_DB1200ZL_BCLKS_EN_N")
	)
	(segment
		(start 354.408994 -69.785484)
		(end 354.41001 -69.784468)
		(width 0.089408)
		(layer "In4.Cu")
		(net "FM_DB1200ZL_BCLKS_EN_N")
	)
	(segment
		(start 324.366128 -154.406854)
		(end 324.366128 -139.890754)
		(width 0.089408)
		(layer "In4.Cu")
		(net "FM_DB1200ZL_BCLKS_EN_N")
	)
	(segment
		(start 177.038 -86.4108)
		(end 178.008788 -87.381588)
		(width 0.089408)
		(layer "In4.Cu")
		(net "FM_DB1200ZL_BCLKS_EN_N")
	)
	(segment
		(start 190.733426 -153.87574)
		(end 190.733426 -156.316426)
		(width 0.089408)
		(layer "In4.Cu")
		(net "FM_DB1200ZL_BCLKS_EN_N")
	)
	(segment
		(start 325.283322 -92.48394)
		(end 332.334616 -85.432646)
		(width 0.089408)
		(layer "In4.Cu")
		(net "FM_DB1200ZL_BCLKS_EN_N")
	)
	(segment
		(start 172.39742 -144.916906)
		(end 176.552352 -144.916906)
		(width 0.089408)
		(layer "In4.Cu")
		(net "FM_DB1200ZL_BCLKS_EN_N")
	)
	(segment
		(start 177.038 -85.725)
		(end 177.038 -86.4108)
		(width 0.089408)
		(layer "In4.Cu")
		(net "FM_DB1200ZL_BCLKS_EN_N")
	)
	(segment
		(start 345.299538 -70.95236)
		(end 346.084906 -70.166992)
		(width 0.089408)
		(layer "In4.Cu")
		(net "FM_DB1200ZL_BCLKS_EN_N")
	)
	(segment
		(start 325.98106 -117.76964)
		(end 325.98106 -115.900454)
		(width 0.089408)
		(layer "In4.Cu")
		(net "FM_DB1200ZL_BCLKS_EN_N")
	)
	(segment
		(start 362.72978 -71.013828)
		(end 363.835188 -69.90842)
		(width 0.089408)
		(layer "In4.Cu")
		(net "FM_DB1200ZL_BCLKS_EN_N")
	)
	(segment
		(start 160.011872 -140.84046)
		(end 161.25952 -142.088108)
		(width 0.089408)
		(layer "In4.Cu")
		(net "FM_DB1200ZL_BCLKS_EN_N")
	)
	(segment
		(start 368.379756 -66.988944)
		(end 368.7699 -66.5988)
		(width 0.089408)
		(layer "In4.Cu")
		(net "FM_DB1200ZL_BCLKS_EN_N")
	)
	(segment
		(start 327.707498 -126.261622)
		(end 327.707498 -123.787154)
		(width 0.089408)
		(layer "In4.Cu")
		(net "FM_DB1200ZL_BCLKS_EN_N")
	)
	(segment
		(start 327.707498 -123.787154)
		(end 326.425052 -122.504708)
		(width 0.089408)
		(layer "In4.Cu")
		(net "FM_DB1200ZL_BCLKS_EN_N")
	)
	(segment
		(start 166.8907 -142.088108)
		(end 169.359326 -144.556734)
		(width 0.089408)
		(layer "In4.Cu")
		(net "FM_DB1200ZL_BCLKS_EN_N")
	)
	(segment
		(start 332.334616 -82.621628)
		(end 335.370932 -79.585312)
		(width 0.089408)
		(layer "In4.Cu")
		(net "FM_DB1200ZL_BCLKS_EN_N")
	)
	(segment
		(start 330.312776 -136.38403)
		(end 330.312776 -135.416544)
		(width 0.089408)
		(layer "In4.Cu")
		(net "FM_DB1200ZL_BCLKS_EN_N")
	)
	(segment
		(start 185.443114 -145.382996)
		(end 186.25439 -145.382996)
		(width 0.089408)
		(layer "In4.Cu")
		(net "FM_DB1200ZL_BCLKS_EN_N")
	)
	(segment
		(start 335.370932 -78.5368)
		(end 336.16265 -77.745082)
		(width 0.089408)
		(layer "In4.Cu")
		(net "FM_DB1200ZL_BCLKS_EN_N")
	)
	(segment
		(start 338.89696 -71.69404)
		(end 339.324442 -71.69404)
		(width 0.089408)
		(layer "In4.Cu")
		(net "FM_DB1200ZL_BCLKS_EN_N")
	)
	(segment
		(start 172.037248 -144.556734)
		(end 172.39742 -144.916906)
		(width 0.089408)
		(layer "In4.Cu")
		(net "FM_DB1200ZL_BCLKS_EN_N")
	)
	(segment
		(start 331.18552 -134.5438)
		(end 331.18552 -129.739644)
		(width 0.089408)
		(layer "In4.Cu")
		(net "FM_DB1200ZL_BCLKS_EN_N")
	)
	(segment
		(start 186.5376 -146.97456)
		(end 187.287408 -147.724368)
		(width 0.089408)
		(layer "In4.Cu")
		(net "FM_DB1200ZL_BCLKS_EN_N")
	)
	(segment
		(start 187.287408 -147.724368)
		(end 187.287408 -150.429722)
		(width 0.089408)
		(layer "In4.Cu")
		(net "FM_DB1200ZL_BCLKS_EN_N")
	)
	(segment
		(start 326.425052 -118.213632)
		(end 325.98106 -117.76964)
		(width 0.089408)
		(layer "In4.Cu")
		(net "FM_DB1200ZL_BCLKS_EN_N")
	)
	(segment
		(start 160.011872 -129.811018)
		(end 160.011872 -140.84046)
		(width 0.089408)
		(layer "In4.Cu")
		(net "FM_DB1200ZL_BCLKS_EN_N")
	)
	(segment
		(start 366.611154 -66.988944)
		(end 368.379756 -66.988944)
		(width 0.089408)
		(layer "In4.Cu")
		(net "FM_DB1200ZL_BCLKS_EN_N")
	)
	(segment
		(start 264.464546 -156.72308)
		(end 264.74928 -156.438346)
		(width 0.089408)
		(layer "In4.Cu")
		(net "FM_DB1200ZL_BCLKS_EN_N")
	)
	(segment
		(start 178.008788 -87.381588)
		(end 178.008788 -93.301058)
		(width 0.089408)
		(layer "In4.Cu")
		(net "FM_DB1200ZL_BCLKS_EN_N")
	)
	(segment
		(start 321.879976 -156.893006)
		(end 324.366128 -154.406854)
		(width 0.089408)
		(layer "In4.Cu")
		(net "FM_DB1200ZL_BCLKS_EN_N")
	)
	(segment
		(start 336.16265 -77.745082)
		(end 336.16265 -74.42835)
		(width 0.089408)
		(layer "In4.Cu")
		(net "FM_DB1200ZL_BCLKS_EN_N")
	)
	(segment
		(start 340.066122 -70.95236)
		(end 345.299538 -70.95236)
		(width 0.089408)
		(layer "In4.Cu")
		(net "FM_DB1200ZL_BCLKS_EN_N")
	)
	(segment
		(start 357.47706 -69.784468)
		(end 358.70642 -71.013828)
		(width 0.089408)
		(layer "In4.Cu")
		(net "FM_DB1200ZL_BCLKS_EN_N")
	)
	(segment
		(start 352.430588 -70.166992)
		(end 352.62566 -70.362064)
		(width 0.089408)
		(layer "In4.Cu")
		(net "FM_DB1200ZL_BCLKS_EN_N")
	)
	(segment
		(start 370.7384 -74.946002)
		(end 370.7384 -79.501492)
		(width 0.089408)
		(layer "In11.Cu")
		(net "FM_DB1200ZL_BCLKS_EN_N")
	)
	(segment
		(start 369.971828 -67.191128)
		(end 369.971828 -71.249794)
		(width 0.089408)
		(layer "In11.Cu")
		(net "FM_DB1200ZL_BCLKS_EN_N")
	)
	(segment
		(start 173.9011 -79.2734)
		(end 173.9011 -81.9023)
		(width 0.089408)
		(layer "In11.Cu")
		(net "FM_DB1200ZL_BCLKS_EN_N")
	)
	(segment
		(start 172.7962 -84.3788)
		(end 169.1259 -84.3788)
		(width 0.089408)
		(layer "In11.Cu")
		(net "FM_DB1200ZL_BCLKS_EN_N")
	)
	(segment
		(start 370.7384 -79.501492)
		(end 370.345208 -79.894684)
		(width 0.089408)
		(layer "In11.Cu")
		(net "FM_DB1200ZL_BCLKS_EN_N")
	)
	(segment
		(start 174.7774 -78.3971)
		(end 173.9011 -79.2734)
		(width 0.089408)
		(layer "In11.Cu")
		(net "FM_DB1200ZL_BCLKS_EN_N")
	)
	(segment
		(start 167.3606 -86.1441)
		(end 164.5539 -83.3374)
		(width 0.089408)
		(layer "In11.Cu")
		(net "FM_DB1200ZL_BCLKS_EN_N")
	)
	(segment
		(start 369.239038 -66.999104)
		(end 369.779804 -66.999104)
		(width 0.089408)
		(layer "In11.Cu")
		(net "FM_DB1200ZL_BCLKS_EN_N")
	)
	(segment
		(start 370.771928 -71.57593)
		(end 370.771928 -74.912474)
		(width 0.089408)
		(layer "In11.Cu")
		(net "FM_DB1200ZL_BCLKS_EN_N")
	)
	(segment
		(start 370.771928 -74.912474)
		(end 370.7384 -74.946002)
		(width 0.089408)
		(layer "In11.Cu")
		(net "FM_DB1200ZL_BCLKS_EN_N")
	)
	(segment
		(start 369.779804 -66.999104)
		(end 369.971828 -67.191128)
		(width 0.089408)
		(layer "In11.Cu")
		(net "FM_DB1200ZL_BCLKS_EN_N")
	)
	(segment
		(start 164.3634 -83.3374)
		(end 164.1856 -83.5152)
		(width 0.089408)
		(layer "In11.Cu")
		(net "FM_DB1200ZL_BCLKS_EN_N")
	)
	(segment
		(start 164.1856 -83.5152)
		(end 164.153088 -83.5152)
		(width 0.089408)
		(layer "In11.Cu")
		(net "FM_DB1200ZL_BCLKS_EN_N")
	)
	(segment
		(start 370.664486 -71.468488)
		(end 370.771928 -71.57593)
		(width 0.089408)
		(layer "In11.Cu")
		(net "FM_DB1200ZL_BCLKS_EN_N")
	)
	(segment
		(start 370.190522 -71.468488)
		(end 370.664486 -71.468488)
		(width 0.089408)
		(layer "In11.Cu")
		(net "FM_DB1200ZL_BCLKS_EN_N")
	)
	(segment
		(start 368.7699 -66.5988)
		(end 368.838734 -66.5988)
		(width 0.089408)
		(layer "In11.Cu")
		(net "FM_DB1200ZL_BCLKS_EN_N")
	)
	(segment
		(start 368.838734 -66.5988)
		(end 369.239038 -66.999104)
		(width 0.089408)
		(layer "In11.Cu")
		(net "FM_DB1200ZL_BCLKS_EN_N")
	)
	(segment
		(start 369.971828 -71.249794)
		(end 370.190522 -71.468488)
		(width 0.089408)
		(layer "In11.Cu")
		(net "FM_DB1200ZL_BCLKS_EN_N")
	)
	(segment
		(start 174.7774 -78.3844)
		(end 174.7774 -78.3971)
		(width 0.089408)
		(layer "In11.Cu")
		(net "FM_DB1200ZL_BCLKS_EN_N")
	)
	(segment
		(start 164.5539 -83.3374)
		(end 164.3634 -83.3374)
		(width 0.089408)
		(layer "In11.Cu")
		(net "FM_DB1200ZL_BCLKS_EN_N")
	)
	(segment
		(start 173.9011 -81.9023)
		(end 174.5742 -82.5754)
		(width 0.089408)
		(layer "In11.Cu")
		(net "FM_DB1200ZL_BCLKS_EN_N")
	)
	(segment
		(start 169.1259 -84.3788)
		(end 167.3606 -86.1441)
		(width 0.089408)
		(layer "In11.Cu")
		(net "FM_DB1200ZL_BCLKS_EN_N")
	)
	(segment
		(start 174.5742 -82.5754)
		(end 174.5742 -82.6008)
		(width 0.089408)
		(layer "In11.Cu")
		(net "FM_DB1200ZL_BCLKS_EN_N")
	)
	(segment
		(start 174.5742 -82.6008)
		(end 172.7962 -84.3788)
		(width 0.089408)
		(layer "In11.Cu")
		(net "FM_DB1200ZL_BCLKS_EN_N")
	)
	(segment
		(start 177.4444 -86.0806)
		(end 177.4444 -85.8266)
		(width 0.10795)
		(layer "F.Cu")
		(net "FM_CPU1_MCP_CLK_EN_N")
	)
	(segment
		(start 164.2618 -78.486)
		(end 164.2618 -78.4479)
		(width 0.10795)
		(layer "F.Cu")
		(net "FM_CPU1_MCP_CLK_EN_N")
	)
	(segment
		(start 357.909876 -71.297038)
		(end 359.420414 -71.297038)
		(width 0.10795)
		(layer "F.Cu")
		(net "FM_CPU1_MCP_CLK_EN_N")
	)
	(segment
		(start 349.271844 -71.77659)
		(end 348.510352 -71.015098)
		(width 0.10795)
		(layer "F.Cu")
		(net "FM_CPU1_MCP_CLK_EN_N")
	)
	(segment
		(start 356.235 -70.2437)
		(end 355.381052 -70.2437)
		(width 0.10795)
		(layer "F.Cu")
		(net "FM_CPU1_MCP_CLK_EN_N")
	)
	(segment
		(start 338.192364 -75.047602)
		(end 335.89722 -72.752458)
		(width 0.10795)
		(layer "F.Cu")
		(net "FM_CPU1_MCP_CLK_EN_N")
	)
	(segment
		(start 353.848162 -71.77659)
		(end 349.271844 -71.77659)
		(width 0.10795)
		(layer "F.Cu")
		(net "FM_CPU1_MCP_CLK_EN_N")
	)
	(segment
		(start 165.054026 -78.711552)
		(end 164.487352 -78.711552)
		(width 0.10795)
		(layer "F.Cu")
		(net "FM_CPU1_MCP_CLK_EN_N")
	)
	(segment
		(start 364.657132 -68.818506)
		(end 365.373412 -69.534786)
		(width 0.10795)
		(layer "F.Cu")
		(net "FM_CPU1_MCP_CLK_EN_N")
	)
	(segment
		(start 361.898946 -68.818506)
		(end 364.657132 -68.818506)
		(width 0.10795)
		(layer "F.Cu")
		(net "FM_CPU1_MCP_CLK_EN_N")
	)
	(segment
		(start 356.235 -70.2437)
		(end 356.856538 -70.2437)
		(width 0.10795)
		(layer "F.Cu")
		(net "FM_CPU1_MCP_CLK_EN_N")
	)
	(segment
		(start 177.4444 -85.8266)
		(end 178.054 -85.217)
		(width 0.10795)
		(layer "F.Cu")
		(net "FM_CPU1_MCP_CLK_EN_N")
	)
	(segment
		(start 366.39881 -72.295004)
		(end 366.745012 -72.295004)
		(width 0.10795)
		(layer "F.Cu")
		(net "FM_CPU1_MCP_CLK_EN_N")
	)
	(segment
		(start 165.054026 -82.71256)
		(end 164.465 -82.71256)
		(width 0.10795)
		(layer "F.Cu")
		(net "FM_CPU1_MCP_CLK_EN_N")
	)
	(segment
		(start 164.2618 -78.4098)
		(end 164.2618 -78.4479)
		(width 0.10795)
		(layer "F.Cu")
		(net "FM_CPU1_MCP_CLK_EN_N")
	)
	(segment
		(start 164.487352 -78.711552)
		(end 164.2618 -78.486)
		(width 0.10795)
		(layer "F.Cu")
		(net "FM_CPU1_MCP_CLK_EN_N")
	)
	(segment
		(start 355.381052 -70.2437)
		(end 353.848162 -71.77659)
		(width 0.10795)
		(layer "F.Cu")
		(net "FM_CPU1_MCP_CLK_EN_N")
	)
	(segment
		(start 165.054026 -78.211426)
		(end 164.460174 -78.211426)
		(width 0.10795)
		(layer "F.Cu")
		(net "FM_CPU1_MCP_CLK_EN_N")
	)
	(segment
		(start 356.856538 -70.2437)
		(end 357.909876 -71.297038)
		(width 0.10795)
		(layer "F.Cu")
		(net "FM_CPU1_MCP_CLK_EN_N")
	)
	(segment
		(start 365.373412 -71.269606)
		(end 366.39881 -72.295004)
		(width 0.10795)
		(layer "F.Cu")
		(net "FM_CPU1_MCP_CLK_EN_N")
	)
	(segment
		(start 365.373412 -69.534786)
		(end 365.373412 -71.269606)
		(width 0.10795)
		(layer "F.Cu")
		(net "FM_CPU1_MCP_CLK_EN_N")
	)
	(segment
		(start 339.998558 -75.047602)
		(end 338.192364 -75.047602)
		(width 0.10795)
		(layer "F.Cu")
		(net "FM_CPU1_MCP_CLK_EN_N")
	)
	(segment
		(start 340.9442 -74.10196)
		(end 339.998558 -75.047602)
		(width 0.10795)
		(layer "F.Cu")
		(net "FM_CPU1_MCP_CLK_EN_N")
	)
	(segment
		(start 342.579706 -71.015098)
		(end 340.9442 -72.650604)
		(width 0.10795)
		(layer "F.Cu")
		(net "FM_CPU1_MCP_CLK_EN_N")
	)
	(segment
		(start 164.460174 -78.211426)
		(end 164.2618 -78.4098)
		(width 0.10795)
		(layer "F.Cu")
		(net "FM_CPU1_MCP_CLK_EN_N")
	)
	(segment
		(start 335.89722 -72.752458)
		(end 333.957168 -72.752458)
		(width 0.10795)
		(layer "F.Cu")
		(net "FM_CPU1_MCP_CLK_EN_N")
	)
	(segment
		(start 359.420414 -71.297038)
		(end 361.898946 -68.818506)
		(width 0.10795)
		(layer "F.Cu")
		(net "FM_CPU1_MCP_CLK_EN_N")
	)
	(segment
		(start 340.9442 -72.650604)
		(end 340.9442 -74.10196)
		(width 0.10795)
		(layer "F.Cu")
		(net "FM_CPU1_MCP_CLK_EN_N")
	)
	(segment
		(start 348.510352 -71.015098)
		(end 342.579706 -71.015098)
		(width 0.10795)
		(layer "F.Cu")
		(net "FM_CPU1_MCP_CLK_EN_N")
	)
	(segment
		(start 164.465 -82.71256)
		(end 164.34816 -82.8294)
		(width 0.10795)
		(layer "F.Cu")
		(net "FM_CPU1_MCP_CLK_EN_N")
	)
	(segment
		(start 164.34816 -82.8294)
		(end 164.2872 -82.8294)
		(width 0.10795)
		(layer "F.Cu")
		(net "FM_CPU1_MCP_CLK_EN_N")
	)
	(via
		(at 177.4444 -86.0806)
		(size 0.508)
		(drill 0.254)
		(layers "F.Cu" "B.Cu")
		(net "FM_CPU1_MCP_CLK_EN_N")
	)
	(via
		(at 356.235 -70.2437)
		(size 0.762)
		(drill 0.381)
		(layers "F.Cu" "B.Cu")
		(net "FM_CPU1_MCP_CLK_EN_N")
	)
	(via
		(at 164.2872 -82.8294)
		(size 0.508)
		(drill 0.254)
		(layers "F.Cu" "B.Cu")
		(net "FM_CPU1_MCP_CLK_EN_N")
	)
	(via
		(at 194.5386 -149.1742)
		(size 0.508)
		(drill 0.254)
		(layers "F.Cu" "B.Cu")
		(net "FM_CPU1_MCP_CLK_EN_N")
	)
	(via
		(at 333.957168 -72.752458)
		(size 0.508)
		(drill 0.254)
		(layers "F.Cu" "B.Cu")
		(net "FM_CPU1_MCP_CLK_EN_N")
	)
	(via
		(at 164.2618 -78.4479)
		(size 0.508)
		(drill 0.254)
		(layers "F.Cu" "B.Cu")
		(net "FM_CPU1_MCP_CLK_EN_N")
	)
	(segment
		(start 324.355714 -130.939286)
		(end 323.655944 -131.639056)
		(width 0.089408)
		(layer "In4.Cu")
		(net "FM_CPU1_MCP_CLK_EN_N")
	)
	(segment
		(start 265.362944 -152.933908)
		(end 264.612628 -152.183592)
		(width 0.089408)
		(layer "In4.Cu")
		(net "FM_CPU1_MCP_CLK_EN_N")
	)
	(segment
		(start 324.787514 -119.088154)
		(end 324.787514 -123.404376)
		(width 0.089408)
		(layer "In4.Cu")
		(net "FM_CPU1_MCP_CLK_EN_N")
	)
	(segment
		(start 322.764912 -91.531948)
		(end 322.764912 -99.414076)
		(width 0.089408)
		(layer "In4.Cu")
		(net "FM_CPU1_MCP_CLK_EN_N")
	)
	(segment
		(start 333.008224 -79.506826)
		(end 329.984608 -82.530442)
		(width 0.089408)
		(layer "In4.Cu")
		(net "FM_CPU1_MCP_CLK_EN_N")
	)
	(segment
		(start 324.787514 -123.404376)
		(end 326.145652 -124.762514)
		(width 0.089408)
		(layer "In4.Cu")
		(net "FM_CPU1_MCP_CLK_EN_N")
	)
	(segment
		(start 195.2117 -149.8473)
		(end 194.5386 -149.1742)
		(width 0.089408)
		(layer "In4.Cu")
		(net "FM_CPU1_MCP_CLK_EN_N")
	)
	(segment
		(start 322.7324 -99.446588)
		(end 322.7324 -115.175792)
		(width 0.089408)
		(layer "In4.Cu")
		(net "FM_CPU1_MCP_CLK_EN_N")
	)
	(segment
		(start 321.358514 -152.933908)
		(end 265.362944 -152.933908)
		(width 0.089408)
		(layer "In4.Cu")
		(net "FM_CPU1_MCP_CLK_EN_N")
	)
	(segment
		(start 329.984608 -82.530442)
		(end 329.984608 -84.153756)
		(width 0.089408)
		(layer "In4.Cu")
		(net "FM_CPU1_MCP_CLK_EN_N")
	)
	(segment
		(start 322.764912 -99.414076)
		(end 322.7324 -99.446588)
		(width 0.089408)
		(layer "In4.Cu")
		(net "FM_CPU1_MCP_CLK_EN_N")
	)
	(segment
		(start 322.699888 -136.543288)
		(end 322.699888 -148.166074)
		(width 0.089408)
		(layer "In4.Cu")
		(net "FM_CPU1_MCP_CLK_EN_N")
	)
	(segment
		(start 323.655944 -131.639056)
		(end 323.655944 -135.587232)
		(width 0.089408)
		(layer "In4.Cu")
		(net "FM_CPU1_MCP_CLK_EN_N")
	)
	(segment
		(start 324.23227 -116.675662)
		(end 324.23227 -118.53291)
		(width 0.089408)
		(layer "In4.Cu")
		(net "FM_CPU1_MCP_CLK_EN_N")
	)
	(segment
		(start 329.984862 -84.311998)
		(end 322.764912 -91.531948)
		(width 0.089408)
		(layer "In4.Cu")
		(net "FM_CPU1_MCP_CLK_EN_N")
	)
	(segment
		(start 326.145652 -126.403608)
		(end 325.07174 -127.47752)
		(width 0.089408)
		(layer "In4.Cu")
		(net "FM_CPU1_MCP_CLK_EN_N")
	)
	(segment
		(start 333.957168 -73.017634)
		(end 333.008224 -73.966578)
		(width 0.089408)
		(layer "In4.Cu")
		(net "FM_CPU1_MCP_CLK_EN_N")
	)
	(segment
		(start 323.655944 -135.587232)
		(end 322.699888 -136.543288)
		(width 0.089408)
		(layer "In4.Cu")
		(net "FM_CPU1_MCP_CLK_EN_N")
	)
	(segment
		(start 326.145652 -124.762514)
		(end 326.145652 -126.403608)
		(width 0.089408)
		(layer "In4.Cu")
		(net "FM_CPU1_MCP_CLK_EN_N")
	)
	(segment
		(start 195.2117 -150.462488)
		(end 195.2117 -149.8473)
		(width 0.089408)
		(layer "In4.Cu")
		(net "FM_CPU1_MCP_CLK_EN_N")
	)
	(segment
		(start 323.272912 -148.739098)
		(end 323.272912 -151.01951)
		(width 0.089408)
		(layer "In4.Cu")
		(net "FM_CPU1_MCP_CLK_EN_N")
	)
	(segment
		(start 333.957168 -72.752458)
		(end 333.957168 -73.017634)
		(width 0.089408)
		(layer "In4.Cu")
		(net "FM_CPU1_MCP_CLK_EN_N")
	)
	(segment
		(start 262.700008 -152.183592)
		(end 262.066786 -152.816814)
		(width 0.089408)
		(layer "In4.Cu")
		(net "FM_CPU1_MCP_CLK_EN_N")
	)
	(segment
		(start 262.066786 -152.816814)
		(end 197.566026 -152.816814)
		(width 0.089408)
		(layer "In4.Cu")
		(net "FM_CPU1_MCP_CLK_EN_N")
	)
	(segment
		(start 197.566026 -152.816814)
		(end 195.2117 -150.462488)
		(width 0.089408)
		(layer "In4.Cu")
		(net "FM_CPU1_MCP_CLK_EN_N")
	)
	(segment
		(start 324.23227 -118.53291)
		(end 324.787514 -119.088154)
		(width 0.089408)
		(layer "In4.Cu")
		(net "FM_CPU1_MCP_CLK_EN_N")
	)
	(segment
		(start 325.07174 -128.046734)
		(end 324.355714 -128.76276)
		(width 0.089408)
		(layer "In4.Cu")
		(net "FM_CPU1_MCP_CLK_EN_N")
	)
	(segment
		(start 322.7324 -115.175792)
		(end 324.23227 -116.675662)
		(width 0.089408)
		(layer "In4.Cu")
		(net "FM_CPU1_MCP_CLK_EN_N")
	)
	(segment
		(start 323.272912 -151.01951)
		(end 321.358514 -152.933908)
		(width 0.089408)
		(layer "In4.Cu")
		(net "FM_CPU1_MCP_CLK_EN_N")
	)
	(segment
		(start 333.008224 -73.966578)
		(end 333.008224 -79.506826)
		(width 0.089408)
		(layer "In4.Cu")
		(net "FM_CPU1_MCP_CLK_EN_N")
	)
	(segment
		(start 329.984608 -84.153756)
		(end 329.984862 -84.15401)
		(width 0.089408)
		(layer "In4.Cu")
		(net "FM_CPU1_MCP_CLK_EN_N")
	)
	(segment
		(start 324.355714 -128.76276)
		(end 324.355714 -130.939286)
		(width 0.089408)
		(layer "In4.Cu")
		(net "FM_CPU1_MCP_CLK_EN_N")
	)
	(segment
		(start 322.699888 -148.166074)
		(end 323.272912 -148.739098)
		(width 0.089408)
		(layer "In4.Cu")
		(net "FM_CPU1_MCP_CLK_EN_N")
	)
	(segment
		(start 329.984862 -84.15401)
		(end 329.984862 -84.311998)
		(width 0.089408)
		(layer "In4.Cu")
		(net "FM_CPU1_MCP_CLK_EN_N")
	)
	(segment
		(start 325.07174 -127.47752)
		(end 325.07174 -128.046734)
		(width 0.089408)
		(layer "In4.Cu")
		(net "FM_CPU1_MCP_CLK_EN_N")
	)
	(segment
		(start 264.612628 -152.183592)
		(end 262.700008 -152.183592)
		(width 0.089408)
		(layer "In4.Cu")
		(net "FM_CPU1_MCP_CLK_EN_N")
	)
	(segment
		(start 181.5592 -103.5812)
		(end 181.5592 -96.647)
		(width 0.089408)
		(layer "In11.Cu")
		(net "FM_CPU1_MCP_CLK_EN_N")
	)
	(segment
		(start 194.5386 -148.2598)
		(end 193.444114 -147.165314)
		(width 0.089408)
		(layer "In11.Cu")
		(net "FM_CPU1_MCP_CLK_EN_N")
	)
	(segment
		(start 195.133468 -132.616448)
		(end 194.284854 -131.767834)
		(width 0.089408)
		(layer "In11.Cu")
		(net "FM_CPU1_MCP_CLK_EN_N")
	)
	(segment
		(start 164.2618 -78.4479)
		(end 164.7571 -78.4479)
		(width 0.089408)
		(layer "In11.Cu")
		(net "FM_CPU1_MCP_CLK_EN_N")
	)
	(segment
		(start 195.133468 -135.041132)
		(end 195.133468 -132.616448)
		(width 0.089408)
		(layer "In11.Cu")
		(net "FM_CPU1_MCP_CLK_EN_N")
	)
	(segment
		(start 164.2237 -79.5401)
		(end 164.2237 -78.486)
		(width 0.089408)
		(layer "In11.Cu")
		(net "FM_CPU1_MCP_CLK_EN_N")
	)
	(segment
		(start 194.638676 -130.992372)
		(end 194.638676 -126.247144)
		(width 0.089408)
		(layer "In11.Cu")
		(net "FM_CPU1_MCP_CLK_EN_N")
	)
	(segment
		(start 186.0042 -108.0262)
		(end 181.5592 -103.5812)
		(width 0.089408)
		(layer "In11.Cu")
		(net "FM_CPU1_MCP_CLK_EN_N")
	)
	(segment
		(start 194.6656 -140.30452)
		(end 194.6656 -138.8364)
		(width 0.089408)
		(layer "In11.Cu")
		(net "FM_CPU1_MCP_CLK_EN_N")
	)
	(segment
		(start 193.8528 -136.3218)
		(end 195.133468 -135.041132)
		(width 0.089408)
		(layer "In11.Cu")
		(net "FM_CPU1_MCP_CLK_EN_N")
	)
	(segment
		(start 194.284854 -131.767834)
		(end 194.284854 -131.346194)
		(width 0.089408)
		(layer "In11.Cu")
		(net "FM_CPU1_MCP_CLK_EN_N")
	)
	(segment
		(start 186.700668 -124.271532)
		(end 186.022234 -124.949966)
		(width 0.089408)
		(layer "In11.Cu")
		(net "FM_CPU1_MCP_CLK_EN_N")
	)
	(segment
		(start 164.2237 -78.486)
		(end 164.2618 -78.4479)
		(width 0.089408)
		(layer "In11.Cu")
		(net "FM_CPU1_MCP_CLK_EN_N")
	)
	(segment
		(start 177.4444 -86.0044)
		(end 177.4444 -86.0806)
		(width 0.089408)
		(layer "In11.Cu")
		(net "FM_CPU1_MCP_CLK_EN_N")
	)
	(segment
		(start 186.022234 -124.949966)
		(end 185.121042 -124.949966)
		(width 0.089408)
		(layer "In11.Cu")
		(net "FM_CPU1_MCP_CLK_EN_N")
	)
	(segment
		(start 179.1716 -94.2594)
		(end 179.1716 -86.0044)
		(width 0.089408)
		(layer "In11.Cu")
		(net "FM_CPU1_MCP_CLK_EN_N")
	)
	(segment
		(start 193.8528 -138.0236)
		(end 193.8528 -136.3218)
		(width 0.089408)
		(layer "In11.Cu")
		(net "FM_CPU1_MCP_CLK_EN_N")
	)
	(segment
		(start 177.8254 -85.6234)
		(end 177.4444 -86.0044)
		(width 0.089408)
		(layer "In11.Cu")
		(net "FM_CPU1_MCP_CLK_EN_N")
	)
	(segment
		(start 194.284854 -131.346194)
		(end 194.638676 -130.992372)
		(width 0.089408)
		(layer "In11.Cu")
		(net "FM_CPU1_MCP_CLK_EN_N")
	)
	(segment
		(start 164.2872 -82.8294)
		(end 164.719 -82.3976)
		(width 0.089408)
		(layer "In11.Cu")
		(net "FM_CPU1_MCP_CLK_EN_N")
	)
	(segment
		(start 194.5386 -149.1742)
		(end 194.5386 -148.2598)
		(width 0.089408)
		(layer "In11.Cu")
		(net "FM_CPU1_MCP_CLK_EN_N")
	)
	(segment
		(start 164.719 -80.0354)
		(end 164.2237 -79.5401)
		(width 0.089408)
		(layer "In11.Cu")
		(net "FM_CPU1_MCP_CLK_EN_N")
	)
	(segment
		(start 193.444114 -141.526006)
		(end 194.6656 -140.30452)
		(width 0.089408)
		(layer "In11.Cu")
		(net "FM_CPU1_MCP_CLK_EN_N")
	)
	(segment
		(start 164.719 -82.3976)
		(end 164.719 -80.0354)
		(width 0.089408)
		(layer "In11.Cu")
		(net "FM_CPU1_MCP_CLK_EN_N")
	)
	(segment
		(start 184.590436 -123.84151)
		(end 186.0042 -122.427746)
		(width 0.089408)
		(layer "In11.Cu")
		(net "FM_CPU1_MCP_CLK_EN_N")
	)
	(segment
		(start 174.225966 -77.2668)
		(end 175.177704 -78.218538)
		(width 0.089408)
		(layer "In11.Cu")
		(net "FM_CPU1_MCP_CLK_EN_N")
	)
	(segment
		(start 193.444114 -147.165314)
		(end 193.444114 -141.526006)
		(width 0.089408)
		(layer "In11.Cu")
		(net "FM_CPU1_MCP_CLK_EN_N")
	)
	(segment
		(start 178.7906 -85.6234)
		(end 177.8254 -85.6234)
		(width 0.089408)
		(layer "In11.Cu")
		(net "FM_CPU1_MCP_CLK_EN_N")
	)
	(segment
		(start 175.177704 -78.218538)
		(end 175.177704 -85.210904)
		(width 0.089408)
		(layer "In11.Cu")
		(net "FM_CPU1_MCP_CLK_EN_N")
	)
	(segment
		(start 164.7571 -78.4479)
		(end 164.7571 -78.4225)
		(width 0.089408)
		(layer "In11.Cu")
		(net "FM_CPU1_MCP_CLK_EN_N")
	)
	(segment
		(start 179.1716 -86.0044)
		(end 178.7906 -85.6234)
		(width 0.089408)
		(layer "In11.Cu")
		(net "FM_CPU1_MCP_CLK_EN_N")
	)
	(segment
		(start 194.638676 -126.247144)
		(end 192.663064 -124.271532)
		(width 0.089408)
		(layer "In11.Cu")
		(net "FM_CPU1_MCP_CLK_EN_N")
	)
	(segment
		(start 165.9128 -77.2668)
		(end 174.225966 -77.2668)
		(width 0.089408)
		(layer "In11.Cu")
		(net "FM_CPU1_MCP_CLK_EN_N")
	)
	(segment
		(start 175.177704 -85.210904)
		(end 176.4284 -86.4616)
		(width 0.089408)
		(layer "In11.Cu")
		(net "FM_CPU1_MCP_CLK_EN_N")
	)
	(segment
		(start 185.121042 -124.949966)
		(end 184.590436 -124.41936)
		(width 0.089408)
		(layer "In11.Cu")
		(net "FM_CPU1_MCP_CLK_EN_N")
	)
	(segment
		(start 186.0042 -122.427746)
		(end 186.0042 -108.0262)
		(width 0.089408)
		(layer "In11.Cu")
		(net "FM_CPU1_MCP_CLK_EN_N")
	)
	(segment
		(start 164.7571 -78.4225)
		(end 165.9128 -77.2668)
		(width 0.089408)
		(layer "In11.Cu")
		(net "FM_CPU1_MCP_CLK_EN_N")
	)
	(segment
		(start 181.5592 -96.647)
		(end 179.1716 -94.2594)
		(width 0.089408)
		(layer "In11.Cu")
		(net "FM_CPU1_MCP_CLK_EN_N")
	)
	(segment
		(start 192.663064 -124.271532)
		(end 186.700668 -124.271532)
		(width 0.089408)
		(layer "In11.Cu")
		(net "FM_CPU1_MCP_CLK_EN_N")
	)
	(segment
		(start 176.4284 -86.4616)
		(end 177.0634 -86.4616)
		(width 0.089408)
		(layer "In11.Cu")
		(net "FM_CPU1_MCP_CLK_EN_N")
	)
	(segment
		(start 177.0634 -86.4616)
		(end 177.4444 -86.0806)
		(width 0.089408)
		(layer "In11.Cu")
		(net "FM_CPU1_MCP_CLK_EN_N")
	)
	(segment
		(start 184.590436 -124.41936)
		(end 184.590436 -123.84151)
		(width 0.089408)
		(layer "In11.Cu")
		(net "FM_CPU1_MCP_CLK_EN_N")
	)
	(segment
		(start 194.6656 -138.8364)
		(end 193.8528 -138.0236)
		(width 0.089408)
		(layer "In11.Cu")
		(net "FM_CPU1_MCP_CLK_EN_N")
	)
	(segment
		(start 359.825798 -70.579488)
		(end 358.161844 -70.579488)
		(width 0.10795)
		(layer "F.Cu")
		(net "FM_CPU0_MCP_CLK_EN_N")
	)
	(segment
		(start 178.4096 -85.8774)
		(end 178.308 -85.8774)
		(width 0.10795)
		(layer "F.Cu")
		(net "FM_CPU0_MCP_CLK_EN_N")
	)
	(segment
		(start 349.922846 -71.501)
		(end 349.603822 -71.181976)
		(width 0.10795)
		(layer "F.Cu")
		(net "FM_CPU0_MCP_CLK_EN_N")
	)
	(segment
		(start 365.641382 -70.932548)
		(end 365.641382 -69.506338)
		(width 0.10795)
		(layer "F.Cu")
		(net "FM_CPU0_MCP_CLK_EN_N")
	)
	(segment
		(start 357.27005 -69.687694)
		(end 355.64064 -69.687694)
		(width 0.10795)
		(layer "F.Cu")
		(net "FM_CPU0_MCP_CLK_EN_N")
	)
	(segment
		(start 338.664804 -74.838052)
		(end 336.151728 -72.324976)
		(width 0.10795)
		(layer "F.Cu")
		(net "FM_CPU0_MCP_CLK_EN_N")
	)
	(segment
		(start 174.449486 -83.212686)
		(end 174.5996 -83.3628)
		(width 0.10795)
		(layer "F.Cu")
		(net "FM_CPU0_MCP_CLK_EN_N")
	)
	(segment
		(start 367.132108 -71.882)
		(end 366.590834 -71.882)
		(width 0.10795)
		(layer "F.Cu")
		(net "FM_CPU0_MCP_CLK_EN_N")
	)
	(segment
		(start 366.590834 -71.882)
		(end 365.641382 -70.932548)
		(width 0.10795)
		(layer "F.Cu")
		(net "FM_CPU0_MCP_CLK_EN_N")
	)
	(segment
		(start 355.64064 -69.687694)
		(end 353.827334 -71.501)
		(width 0.10795)
		(layer "F.Cu")
		(net "FM_CPU0_MCP_CLK_EN_N")
	)
	(segment
		(start 361.79633 -68.608956)
		(end 359.825798 -70.579488)
		(width 0.10795)
		(layer "F.Cu")
		(net "FM_CPU0_MCP_CLK_EN_N")
	)
	(segment
		(start 340.315804 -72.982582)
		(end 340.315804 -74.433938)
		(width 0.10795)
		(layer "F.Cu")
		(net "FM_CPU0_MCP_CLK_EN_N")
	)
	(segment
		(start 349.603822 -71.181976)
		(end 349.000064 -70.578218)
		(width 0.10795)
		(layer "F.Cu")
		(net "FM_CPU0_MCP_CLK_EN_N")
	)
	(segment
		(start 336.151728 -72.324976)
		(end 334.104488 -72.324976)
		(width 0.10795)
		(layer "F.Cu")
		(net "FM_CPU0_MCP_CLK_EN_N")
	)
	(segment
		(start 353.827334 -71.501)
		(end 349.922846 -71.501)
		(width 0.10795)
		(layer "F.Cu")
		(net "FM_CPU0_MCP_CLK_EN_N")
	)
	(segment
		(start 339.91169 -74.838052)
		(end 338.664804 -74.838052)
		(width 0.10795)
		(layer "F.Cu")
		(net "FM_CPU0_MCP_CLK_EN_N")
	)
	(segment
		(start 340.315804 -74.433938)
		(end 339.91169 -74.838052)
		(width 0.10795)
		(layer "F.Cu")
		(net "FM_CPU0_MCP_CLK_EN_N")
	)
	(segment
		(start 358.161844 -70.579488)
		(end 357.27005 -69.687694)
		(width 0.10795)
		(layer "F.Cu")
		(net "FM_CPU0_MCP_CLK_EN_N")
	)
	(segment
		(start 349.000064 -70.578218)
		(end 342.720168 -70.578218)
		(width 0.10795)
		(layer "F.Cu")
		(net "FM_CPU0_MCP_CLK_EN_N")
	)
	(segment
		(start 334.104488 -72.324976)
		(end 333.88046 -72.100948)
		(width 0.10795)
		(layer "F.Cu")
		(net "FM_CPU0_MCP_CLK_EN_N")
	)
	(segment
		(start 178.308 -85.8774)
		(end 178.0794 -86.106)
		(width 0.10795)
		(layer "F.Cu")
		(net "FM_CPU0_MCP_CLK_EN_N")
	)
	(segment
		(start 364.744 -68.608956)
		(end 361.79633 -68.608956)
		(width 0.10795)
		(layer "F.Cu")
		(net "FM_CPU0_MCP_CLK_EN_N")
	)
	(segment
		(start 171.67352 -85.85708)
		(end 171.3738 -86.1568)
		(width 0.10795)
		(layer "F.Cu")
		(net "FM_CPU0_MCP_CLK_EN_N")
	)
	(segment
		(start 342.720168 -70.578218)
		(end 340.315804 -72.982582)
		(width 0.10795)
		(layer "F.Cu")
		(net "FM_CPU0_MCP_CLK_EN_N")
	)
	(segment
		(start 179.07 -85.217)
		(end 178.4096 -85.8774)
		(width 0.10795)
		(layer "F.Cu")
		(net "FM_CPU0_MCP_CLK_EN_N")
	)
	(segment
		(start 171.173394 -85.956394)
		(end 171.3738 -86.1568)
		(width 0.10795)
		(layer "F.Cu")
		(net "FM_CPU0_MCP_CLK_EN_N")
	)
	(segment
		(start 171.173394 -85.330792)
		(end 171.173394 -85.956394)
		(width 0.10795)
		(layer "F.Cu")
		(net "FM_CPU0_MCP_CLK_EN_N")
	)
	(segment
		(start 367.545112 -72.295004)
		(end 367.132108 -71.882)
		(width 0.10795)
		(layer "F.Cu")
		(net "FM_CPU0_MCP_CLK_EN_N")
	)
	(segment
		(start 365.641382 -69.506338)
		(end 364.744 -68.608956)
		(width 0.10795)
		(layer "F.Cu")
		(net "FM_CPU0_MCP_CLK_EN_N")
	)
	(segment
		(start 171.67352 -85.330792)
		(end 171.67352 -85.85708)
		(width 0.10795)
		(layer "F.Cu")
		(net "FM_CPU0_MCP_CLK_EN_N")
	)
	(segment
		(start 173.791626 -83.212686)
		(end 174.449486 -83.212686)
		(width 0.10795)
		(layer "F.Cu")
		(net "FM_CPU0_MCP_CLK_EN_N")
	)
	(via
		(at 333.88046 -72.100948)
		(size 0.508)
		(drill 0.254)
		(layers "F.Cu" "B.Cu")
		(net "FM_CPU0_MCP_CLK_EN_N")
	)
	(via
		(at 171.3738 -86.1568)
		(size 0.508)
		(drill 0.254)
		(layers "F.Cu" "B.Cu")
		(net "FM_CPU0_MCP_CLK_EN_N")
	)
	(via
		(at 178.0794 -86.106)
		(size 0.508)
		(drill 0.254)
		(layers "F.Cu" "B.Cu")
		(net "FM_CPU0_MCP_CLK_EN_N")
	)
	(via
		(at 174.5996 -83.3628)
		(size 0.508)
		(drill 0.254)
		(layers "F.Cu" "B.Cu")
		(net "FM_CPU0_MCP_CLK_EN_N")
	)
	(via
		(at 193.9163 -148.6408)
		(size 0.508)
		(drill 0.254)
		(layers "F.Cu" "B.Cu")
		(net "FM_CPU0_MCP_CLK_EN_N")
	)
	(via
		(at 349.603822 -71.181976)
		(size 0.762)
		(drill 0.381)
		(layers "F.Cu" "B.Cu")
		(net "FM_CPU0_MCP_CLK_EN_N")
	)
	(segment
		(start 262.357616 -151.992584)
		(end 264.691876 -151.992584)
		(width 0.089408)
		(layer "In4.Cu")
		(net "FM_CPU0_MCP_CLK_EN_N")
	)
	(segment
		(start 195.402708 -149.472142)
		(end 195.402708 -150.38324)
		(width 0.089408)
		(layer "In4.Cu")
		(net "FM_CPU0_MCP_CLK_EN_N")
	)
	(segment
		(start 322.573904 -91.430094)
		(end 329.7936 -84.210398)
		(width 0.089408)
		(layer "In4.Cu")
		(net "FM_CPU0_MCP_CLK_EN_N")
	)
	(segment
		(start 321.798696 -144.862296)
		(end 321.798696 -140.243814)
		(width 0.089408)
		(layer "In4.Cu")
		(net "FM_CPU0_MCP_CLK_EN_N")
	)
	(segment
		(start 261.724394 -152.625806)
		(end 262.357616 -151.992584)
		(width 0.089408)
		(layer "In4.Cu")
		(net "FM_CPU0_MCP_CLK_EN_N")
	)
	(segment
		(start 193.9163 -148.6408)
		(end 194.049396 -148.773896)
		(width 0.089408)
		(layer "In4.Cu")
		(net "FM_CPU0_MCP_CLK_EN_N")
	)
	(segment
		(start 322.573904 -99.334828)
		(end 322.573904 -91.430094)
		(width 0.089408)
		(layer "In4.Cu")
		(net "FM_CPU0_MCP_CLK_EN_N")
	)
	(segment
		(start 194.049396 -148.773896)
		(end 194.704462 -148.773896)
		(width 0.089408)
		(layer "In4.Cu")
		(net "FM_CPU0_MCP_CLK_EN_N")
	)
	(segment
		(start 322.541392 -99.36734)
		(end 322.573904 -99.334828)
		(width 0.089408)
		(layer "In4.Cu")
		(net "FM_CPU0_MCP_CLK_EN_N")
	)
	(segment
		(start 324.041262 -118.646702)
		(end 324.041262 -116.75491)
		(width 0.089408)
		(layer "In4.Cu")
		(net "FM_CPU0_MCP_CLK_EN_N")
	)
	(segment
		(start 197.645274 -152.625806)
		(end 261.724394 -152.625806)
		(width 0.089408)
		(layer "In4.Cu")
		(net "FM_CPU0_MCP_CLK_EN_N")
	)
	(segment
		(start 324.880732 -127.967486)
		(end 324.880732 -127.398272)
		(width 0.089408)
		(layer "In4.Cu")
		(net "FM_CPU0_MCP_CLK_EN_N")
	)
	(segment
		(start 332.817216 -73.770236)
		(end 333.476854 -73.110598)
		(width 0.089408)
		(layer "In4.Cu")
		(net "FM_CPU0_MCP_CLK_EN_N")
	)
	(segment
		(start 324.596506 -123.483624)
		(end 324.596506 -119.201946)
		(width 0.089408)
		(layer "In4.Cu")
		(net "FM_CPU0_MCP_CLK_EN_N")
	)
	(segment
		(start 322.50888 -148.245322)
		(end 322.50888 -145.57248)
		(width 0.089408)
		(layer "In4.Cu")
		(net "FM_CPU0_MCP_CLK_EN_N")
	)
	(segment
		(start 324.164706 -128.683512)
		(end 324.880732 -127.967486)
		(width 0.089408)
		(layer "In4.Cu")
		(net "FM_CPU0_MCP_CLK_EN_N")
	)
	(segment
		(start 323.464936 -131.559808)
		(end 324.164706 -130.860038)
		(width 0.089408)
		(layer "In4.Cu")
		(net "FM_CPU0_MCP_CLK_EN_N")
	)
	(segment
		(start 333.476854 -73.110598)
		(end 333.476854 -72.504554)
		(width 0.089408)
		(layer "In4.Cu")
		(net "FM_CPU0_MCP_CLK_EN_N")
	)
	(segment
		(start 322.50888 -145.57248)
		(end 321.798696 -144.862296)
		(width 0.089408)
		(layer "In4.Cu")
		(net "FM_CPU0_MCP_CLK_EN_N")
	)
	(segment
		(start 321.798696 -140.243814)
		(end 322.428616 -139.613894)
		(width 0.089408)
		(layer "In4.Cu")
		(net "FM_CPU0_MCP_CLK_EN_N")
	)
	(segment
		(start 324.880732 -127.398272)
		(end 325.954644 -126.32436)
		(width 0.089408)
		(layer "In4.Cu")
		(net "FM_CPU0_MCP_CLK_EN_N")
	)
	(segment
		(start 322.428616 -136.523984)
		(end 323.464936 -135.487664)
		(width 0.089408)
		(layer "In4.Cu")
		(net "FM_CPU0_MCP_CLK_EN_N")
	)
	(segment
		(start 329.7936 -84.210398)
		(end 329.7936 -82.45094)
		(width 0.089408)
		(layer "In4.Cu")
		(net "FM_CPU0_MCP_CLK_EN_N")
	)
	(segment
		(start 324.596506 -119.201946)
		(end 324.041262 -118.646702)
		(width 0.089408)
		(layer "In4.Cu")
		(net "FM_CPU0_MCP_CLK_EN_N")
	)
	(segment
		(start 194.704462 -148.773896)
		(end 195.402708 -149.472142)
		(width 0.089408)
		(layer "In4.Cu")
		(net "FM_CPU0_MCP_CLK_EN_N")
	)
	(segment
		(start 333.476854 -72.504554)
		(end 333.88046 -72.100948)
		(width 0.089408)
		(layer "In4.Cu")
		(net "FM_CPU0_MCP_CLK_EN_N")
	)
	(segment
		(start 265.442192 -152.7429)
		(end 321.279266 -152.7429)
		(width 0.089408)
		(layer "In4.Cu")
		(net "FM_CPU0_MCP_CLK_EN_N")
	)
	(segment
		(start 264.691876 -151.992584)
		(end 265.442192 -152.7429)
		(width 0.089408)
		(layer "In4.Cu")
		(net "FM_CPU0_MCP_CLK_EN_N")
	)
	(segment
		(start 323.081904 -150.940262)
		(end 323.081904 -148.818346)
		(width 0.089408)
		(layer "In4.Cu")
		(net "FM_CPU0_MCP_CLK_EN_N")
	)
	(segment
		(start 332.817216 -79.427324)
		(end 332.817216 -73.770236)
		(width 0.089408)
		(layer "In4.Cu")
		(net "FM_CPU0_MCP_CLK_EN_N")
	)
	(segment
		(start 195.402708 -150.38324)
		(end 197.645274 -152.625806)
		(width 0.089408)
		(layer "In4.Cu")
		(net "FM_CPU0_MCP_CLK_EN_N")
	)
	(segment
		(start 325.954644 -124.841762)
		(end 324.596506 -123.483624)
		(width 0.089408)
		(layer "In4.Cu")
		(net "FM_CPU0_MCP_CLK_EN_N")
	)
	(segment
		(start 325.954644 -126.32436)
		(end 325.954644 -124.841762)
		(width 0.089408)
		(layer "In4.Cu")
		(net "FM_CPU0_MCP_CLK_EN_N")
	)
	(segment
		(start 323.464936 -135.487664)
		(end 323.464936 -131.559808)
		(width 0.089408)
		(layer "In4.Cu")
		(net "FM_CPU0_MCP_CLK_EN_N")
	)
	(segment
		(start 321.279266 -152.7429)
		(end 323.081904 -150.940262)
		(width 0.089408)
		(layer "In4.Cu")
		(net "FM_CPU0_MCP_CLK_EN_N")
	)
	(segment
		(start 323.081904 -148.818346)
		(end 322.50888 -148.245322)
		(width 0.089408)
		(layer "In4.Cu")
		(net "FM_CPU0_MCP_CLK_EN_N")
	)
	(segment
		(start 329.7936 -82.45094)
		(end 332.817216 -79.427324)
		(width 0.089408)
		(layer "In4.Cu")
		(net "FM_CPU0_MCP_CLK_EN_N")
	)
	(segment
		(start 322.541392 -115.25504)
		(end 322.541392 -99.36734)
		(width 0.089408)
		(layer "In4.Cu")
		(net "FM_CPU0_MCP_CLK_EN_N")
	)
	(segment
		(start 324.164706 -130.860038)
		(end 324.164706 -128.683512)
		(width 0.089408)
		(layer "In4.Cu")
		(net "FM_CPU0_MCP_CLK_EN_N")
	)
	(segment
		(start 324.041262 -116.75491)
		(end 322.541392 -115.25504)
		(width 0.089408)
		(layer "In4.Cu")
		(net "FM_CPU0_MCP_CLK_EN_N")
	)
	(segment
		(start 322.428616 -139.613894)
		(end 322.428616 -136.523984)
		(width 0.089408)
		(layer "In4.Cu")
		(net "FM_CPU0_MCP_CLK_EN_N")
	)
	(segment
		(start 194.447668 -126.326392)
		(end 192.621408 -124.500132)
		(width 0.089408)
		(layer "In11.Cu")
		(net "FM_CPU0_MCP_CLK_EN_N")
	)
	(segment
		(start 177.4952 -86.8426)
		(end 178.0794 -86.2584)
		(width 0.089408)
		(layer "In11.Cu")
		(net "FM_CPU0_MCP_CLK_EN_N")
	)
	(segment
		(start 185.7756 -122.333004)
		(end 185.7756 -108.120942)
		(width 0.089408)
		(layer "In11.Cu")
		(net "FM_CPU0_MCP_CLK_EN_N")
	)
	(segment
		(start 174.5996 -83.3628)
		(end 174.831756 -83.594956)
		(width 0.089408)
		(layer "In11.Cu")
		(net "FM_CPU0_MCP_CLK_EN_N")
	)
	(segment
		(start 185.0263 -125.178566)
		(end 184.361836 -124.514102)
		(width 0.089408)
		(layer "In11.Cu")
		(net "FM_CPU0_MCP_CLK_EN_N")
	)
	(segment
		(start 186.116976 -125.178566)
		(end 185.0263 -125.178566)
		(width 0.089408)
		(layer "In11.Cu")
		(net "FM_CPU0_MCP_CLK_EN_N")
	)
	(segment
		(start 184.361836 -124.514102)
		(end 184.361836 -123.746768)
		(width 0.089408)
		(layer "In11.Cu")
		(net "FM_CPU0_MCP_CLK_EN_N")
	)
	(segment
		(start 181.3306 -96.741742)
		(end 178.943 -94.354142)
		(width 0.089408)
		(layer "In11.Cu")
		(net "FM_CPU0_MCP_CLK_EN_N")
	)
	(segment
		(start 194.870324 -134.981188)
		(end 194.870324 -132.62356)
		(width 0.089408)
		(layer "In11.Cu")
		(net "FM_CPU0_MCP_CLK_EN_N")
	)
	(segment
		(start 172.7454 -84.7852)
		(end 173.1772 -84.7852)
		(width 0.089408)
		(layer "In11.Cu")
		(net "FM_CPU0_MCP_CLK_EN_N")
	)
	(segment
		(start 194.022472 -131.258056)
		(end 194.447668 -130.83286)
		(width 0.089408)
		(layer "In11.Cu")
		(net "FM_CPU0_MCP_CLK_EN_N")
	)
	(segment
		(start 175.8442 -86.8426)
		(end 177.4952 -86.8426)
		(width 0.089408)
		(layer "In11.Cu")
		(net "FM_CPU0_MCP_CLK_EN_N")
	)
	(segment
		(start 184.361836 -123.746768)
		(end 185.7756 -122.333004)
		(width 0.089408)
		(layer "In11.Cu")
		(net "FM_CPU0_MCP_CLK_EN_N")
	)
	(segment
		(start 178.943 -86.5632)
		(end 178.4858 -86.106)
		(width 0.089408)
		(layer "In11.Cu")
		(net "FM_CPU0_MCP_CLK_EN_N")
	)
	(segment
		(start 193.8528 -147.99056)
		(end 193.253106 -147.390866)
		(width 0.089408)
		(layer "In11.Cu")
		(net "FM_CPU0_MCP_CLK_EN_N")
	)
	(segment
		(start 178.0794 -86.2584)
		(end 178.0794 -86.106)
		(width 0.089408)
		(layer "In11.Cu")
		(net "FM_CPU0_MCP_CLK_EN_N")
	)
	(segment
		(start 174.831756 -85.830156)
		(end 175.8442 -86.8426)
		(width 0.089408)
		(layer "In11.Cu")
		(net "FM_CPU0_MCP_CLK_EN_N")
	)
	(segment
		(start 186.79541 -124.500132)
		(end 186.116976 -125.178566)
		(width 0.089408)
		(layer "In11.Cu")
		(net "FM_CPU0_MCP_CLK_EN_N")
	)
	(segment
		(start 193.6242 -136.227312)
		(end 194.870324 -134.981188)
		(width 0.089408)
		(layer "In11.Cu")
		(net "FM_CPU0_MCP_CLK_EN_N")
	)
	(segment
		(start 171.3738 -86.1568)
		(end 172.7454 -84.7852)
		(width 0.089408)
		(layer "In11.Cu")
		(net "FM_CPU0_MCP_CLK_EN_N")
	)
	(segment
		(start 173.1772 -84.7852)
		(end 174.5996 -83.3628)
		(width 0.089408)
		(layer "In11.Cu")
		(net "FM_CPU0_MCP_CLK_EN_N")
	)
	(segment
		(start 193.9163 -148.6408)
		(end 193.8528 -148.5773)
		(width 0.089408)
		(layer "In11.Cu")
		(net "FM_CPU0_MCP_CLK_EN_N")
	)
	(segment
		(start 178.943 -94.354142)
		(end 178.943 -86.5632)
		(width 0.089408)
		(layer "In11.Cu")
		(net "FM_CPU0_MCP_CLK_EN_N")
	)
	(segment
		(start 185.7756 -108.120942)
		(end 181.3306 -103.675942)
		(width 0.089408)
		(layer "In11.Cu")
		(net "FM_CPU0_MCP_CLK_EN_N")
	)
	(segment
		(start 194.447668 -130.83286)
		(end 194.447668 -126.326392)
		(width 0.089408)
		(layer "In11.Cu")
		(net "FM_CPU0_MCP_CLK_EN_N")
	)
	(segment
		(start 178.4858 -86.106)
		(end 178.0794 -86.106)
		(width 0.089408)
		(layer "In11.Cu")
		(net "FM_CPU0_MCP_CLK_EN_N")
	)
	(segment
		(start 181.3306 -103.675942)
		(end 181.3306 -96.741742)
		(width 0.089408)
		(layer "In11.Cu")
		(net "FM_CPU0_MCP_CLK_EN_N")
	)
	(segment
		(start 193.253106 -147.390866)
		(end 193.253106 -141.393672)
		(width 0.089408)
		(layer "In11.Cu")
		(net "FM_CPU0_MCP_CLK_EN_N")
	)
	(segment
		(start 192.621408 -124.500132)
		(end 186.79541 -124.500132)
		(width 0.089408)
		(layer "In11.Cu")
		(net "FM_CPU0_MCP_CLK_EN_N")
	)
	(segment
		(start 193.6242 -138.118342)
		(end 193.6242 -136.227312)
		(width 0.089408)
		(layer "In11.Cu")
		(net "FM_CPU0_MCP_CLK_EN_N")
	)
	(segment
		(start 194.437 -140.209778)
		(end 194.437 -138.931142)
		(width 0.089408)
		(layer "In11.Cu")
		(net "FM_CPU0_MCP_CLK_EN_N")
	)
	(segment
		(start 194.022472 -131.775708)
		(end 194.022472 -131.258056)
		(width 0.089408)
		(layer "In11.Cu")
		(net "FM_CPU0_MCP_CLK_EN_N")
	)
	(segment
		(start 193.8528 -148.5773)
		(end 193.8528 -147.99056)
		(width 0.089408)
		(layer "In11.Cu")
		(net "FM_CPU0_MCP_CLK_EN_N")
	)
	(segment
		(start 174.831756 -83.594956)
		(end 174.831756 -85.830156)
		(width 0.089408)
		(layer "In11.Cu")
		(net "FM_CPU0_MCP_CLK_EN_N")
	)
	(segment
		(start 193.253106 -141.393672)
		(end 194.437 -140.209778)
		(width 0.089408)
		(layer "In11.Cu")
		(net "FM_CPU0_MCP_CLK_EN_N")
	)
	(segment
		(start 194.437 -138.931142)
		(end 193.6242 -138.118342)
		(width 0.089408)
		(layer "In11.Cu")
		(net "FM_CPU0_MCP_CLK_EN_N")
	)
	(segment
		(start 194.870324 -132.62356)
		(end 194.022472 -131.775708)
		(width 0.089408)
		(layer "In11.Cu")
		(net "FM_CPU0_MCP_CLK_EN_N")
	)
	(segment
		(start 446.317878 -60.79744)
		(end 446.317878 -60.480702)
		(width 0.1016)
		(layer "F.Cu")
		(net "KR_P0_OCP_TX_DP")
	)
	(segment
		(start 446.216024 -60.378848)
		(end 445.910716 -60.378848)
		(width 0.1016)
		(layer "F.Cu")
		(net "KR_P0_OCP_TX_DP")
	)
	(segment
		(start 446.149984 -60.965334)
		(end 446.317878 -60.79744)
		(width 0.1016)
		(layer "F.Cu")
		(net "KR_P0_OCP_TX_DP")
	)
	(segment
		(start 398.63395 -105.5624)
		(end 398.13865 -105.332276)
		(width 0.10033)
		(layer "F.Cu")
		(net "KR_P0_OCP_TX_DP")
	)
	(segment
		(start 446.317878 -60.480702)
		(end 446.216024 -60.378848)
		(width 0.1016)
		(layer "F.Cu")
		(net "KR_P0_OCP_TX_DP")
	)
	(segment
		(start 446.149984 -62.00267)
		(end 446.149984 -60.965334)
		(width 0.1016)
		(layer "F.Cu")
		(net "KR_P0_OCP_TX_DP")
	)
	(via
		(at 445.910716 -60.378848)
		(size 0.508)
		(drill 0.254)
		(layers "F.Cu" "B.Cu")
		(net "KR_P0_OCP_TX_DP")
	)
	(via
		(at 398.13865 -105.332276)
		(size 0.508)
		(drill 0.254)
		(layers "F.Cu" "B.Cu")
		(net "KR_P0_OCP_TX_DP")
	)
	(segment
		(start 439.873644 -60.390786)
		(end 440.66079 -61.177932)
		(width 0.101346)
		(layer "In9.Cu")
		(net "KR_P0_OCP_TX_DP")
	)
	(segment
		(start 408.306778 -102.38613)
		(end 408.727656 -102.38613)
		(width 0.101346)
		(layer "In9.Cu")
		(net "KR_P0_OCP_TX_DP")
	)
	(segment
		(start 412.0896 -96.12249)
		(end 412.0896 -93.36024)
		(width 0.101346)
		(layer "In9.Cu")
		(net "KR_P0_OCP_TX_DP")
	)
	(segment
		(start 408.727656 -102.38613)
		(end 409.11526 -101.998526)
		(width 0.101346)
		(layer "In9.Cu")
		(net "KR_P0_OCP_TX_DP")
	)
	(segment
		(start 413.09925 -89.943686)
		(end 414.168336 -88.8746)
		(width 0.101346)
		(layer "In9.Cu")
		(net "KR_P0_OCP_TX_DP")
	)
	(segment
		(start 400.190462 -105.485438)
		(end 400.333972 -105.485438)
		(width 0.101346)
		(layer "In9.Cu")
		(net "KR_P0_OCP_TX_DP")
	)
	(segment
		(start 411.861 -92.776294)
		(end 412.0896 -92.547694)
		(width 0.101346)
		(layer "In9.Cu")
		(net "KR_P0_OCP_TX_DP")
	)
	(segment
		(start 446.23482 -60.378848)
		(end 445.910716 -60.378848)
		(width 0.101346)
		(layer "In9.Cu")
		(net "KR_P0_OCP_TX_DP")
	)
	(segment
		(start 409.761944 -101.351842)
		(end 409.976828 -101.136958)
		(width 0.101346)
		(layer "In9.Cu")
		(net "KR_P0_OCP_TX_DP")
	)
	(segment
		(start 438.787286 -56.905398)
		(end 439.873644 -57.991756)
		(width 0.101346)
		(layer "In9.Cu")
		(net "KR_P0_OCP_TX_DP")
	)
	(segment
		(start 412.635446 -98.200464)
		(end 412.635446 -96.668336)
		(width 0.101346)
		(layer "In9.Cu")
		(net "KR_P0_OCP_TX_DP")
	)
	(segment
		(start 398.13865 -105.332276)
		(end 397.800576 -105.332276)
		(width 0.089154)
		(layer "In9.Cu")
		(net "KR_P0_OCP_TX_DP")
	)
	(segment
		(start 404.589996 -103.117396)
		(end 405.218646 -103.746046)
		(width 0.101346)
		(layer "In9.Cu")
		(net "KR_P0_OCP_TX_DP")
	)
	(segment
		(start 399.62455 -105.599738)
		(end 400.054064 -105.599738)
		(width 0.089154)
		(layer "In9.Cu")
		(net "KR_P0_OCP_TX_DP")
	)
	(segment
		(start 436.23103 -56.905398)
		(end 438.787286 -56.905398)
		(width 0.101346)
		(layer "In9.Cu")
		(net "KR_P0_OCP_TX_DP")
	)
	(segment
		(start 405.218646 -103.746046)
		(end 407.36774 -103.746046)
		(width 0.101346)
		(layer "In9.Cu")
		(net "KR_P0_OCP_TX_DP")
	)
	(segment
		(start 426.369734 -57.142126)
		(end 428.063152 -57.142126)
		(width 0.101346)
		(layer "In9.Cu")
		(net "KR_P0_OCP_TX_DP")
	)
	(segment
		(start 422.284398 -58.1533)
		(end 425.35856 -58.1533)
		(width 0.101346)
		(layer "In9.Cu")
		(net "KR_P0_OCP_TX_DP")
	)
	(segment
		(start 408.055572 -102.637336)
		(end 408.306778 -102.38613)
		(width 0.101346)
		(layer "In9.Cu")
		(net "KR_P0_OCP_TX_DP")
	)
	(segment
		(start 446.336166 -60.480194)
		(end 446.23482 -60.378848)
		(width 0.101346)
		(layer "In9.Cu")
		(net "KR_P0_OCP_TX_DP")
	)
	(segment
		(start 400.168364 -105.485438)
		(end 400.190462 -105.485438)
		(width 0.089154)
		(layer "In9.Cu")
		(net "KR_P0_OCP_TX_DP")
	)
	(segment
		(start 412.0896 -93.36024)
		(end 411.861 -93.13164)
		(width 0.101346)
		(layer "In9.Cu")
		(net "KR_P0_OCP_TX_DP")
	)
	(segment
		(start 397.800576 -105.332276)
		(end 397.742918 -105.389934)
		(width 0.089154)
		(layer "In9.Cu")
		(net "KR_P0_OCP_TX_DP")
	)
	(segment
		(start 439.873644 -57.991756)
		(end 439.873644 -60.390786)
		(width 0.101346)
		(layer "In9.Cu")
		(net "KR_P0_OCP_TX_DP")
	)
	(segment
		(start 414.168336 -88.8746)
		(end 415.17824 -88.8746)
		(width 0.101346)
		(layer "In9.Cu")
		(net "KR_P0_OCP_TX_DP")
	)
	(segment
		(start 412.0896 -92.547694)
		(end 412.0896 -91.4654)
		(width 0.101346)
		(layer "In9.Cu")
		(net "KR_P0_OCP_TX_DP")
	)
	(segment
		(start 408.055572 -103.058214)
		(end 408.055572 -102.637336)
		(width 0.101346)
		(layer "In9.Cu")
		(net "KR_P0_OCP_TX_DP")
	)
	(segment
		(start 409.976828 -100.705158)
		(end 410.191966 -100.49002)
		(width 0.101346)
		(layer "In9.Cu")
		(net "KR_P0_OCP_TX_DP")
	)
	(segment
		(start 416.068256 -87.984584)
		(end 416.068256 -85.964776)
		(width 0.101346)
		(layer "In9.Cu")
		(net "KR_P0_OCP_TX_DP")
	)
	(segment
		(start 418.48024 -64.245236)
		(end 419.062662 -63.662814)
		(width 0.101346)
		(layer "In9.Cu")
		(net "KR_P0_OCP_TX_DP")
	)
	(segment
		(start 412.0896 -91.4654)
		(end 413.09925 -90.45575)
		(width 0.101346)
		(layer "In9.Cu")
		(net "KR_P0_OCP_TX_DP")
	)
	(segment
		(start 409.11526 -101.998526)
		(end 409.11526 -101.56698)
		(width 0.101346)
		(layer "In9.Cu")
		(net "KR_P0_OCP_TX_DP")
	)
	(segment
		(start 440.66079 -61.177932)
		(end 446.04559 -61.177932)
		(width 0.101346)
		(layer "In9.Cu")
		(net "KR_P0_OCP_TX_DP")
	)
	(segment
		(start 415.17824 -88.8746)
		(end 416.068256 -87.984584)
		(width 0.101346)
		(layer "In9.Cu")
		(net "KR_P0_OCP_TX_DP")
	)
	(segment
		(start 410.83865 -100.275136)
		(end 410.83865 -99.99726)
		(width 0.101346)
		(layer "In9.Cu")
		(net "KR_P0_OCP_TX_DP")
	)
	(segment
		(start 402.702014 -103.117396)
		(end 404.589996 -103.117396)
		(width 0.101346)
		(layer "In9.Cu")
		(net "KR_P0_OCP_TX_DP")
	)
	(segment
		(start 418.48024 -79.524606)
		(end 418.48024 -64.245236)
		(width 0.101346)
		(layer "In9.Cu")
		(net "KR_P0_OCP_TX_DP")
	)
	(segment
		(start 409.976828 -101.136958)
		(end 409.976828 -100.705158)
		(width 0.101346)
		(layer "In9.Cu")
		(net "KR_P0_OCP_TX_DP")
	)
	(segment
		(start 416.068256 -85.964776)
		(end 417.91636 -84.115656)
		(width 0.101346)
		(layer "In9.Cu")
		(net "KR_P0_OCP_TX_DP")
	)
	(segment
		(start 429.835564 -55.369968)
		(end 434.6956 -55.369968)
		(width 0.101346)
		(layer "In9.Cu")
		(net "KR_P0_OCP_TX_DP")
	)
	(segment
		(start 419.062662 -61.375036)
		(end 422.284398 -58.1533)
		(width 0.101346)
		(layer "In9.Cu")
		(net "KR_P0_OCP_TX_DP")
	)
	(segment
		(start 410.83865 -99.99726)
		(end 412.635446 -98.200464)
		(width 0.101346)
		(layer "In9.Cu")
		(net "KR_P0_OCP_TX_DP")
	)
	(segment
		(start 411.861 -93.13164)
		(end 411.861 -92.776294)
		(width 0.101346)
		(layer "In9.Cu")
		(net "KR_P0_OCP_TX_DP")
	)
	(segment
		(start 446.336166 -60.887356)
		(end 446.336166 -60.480194)
		(width 0.101346)
		(layer "In9.Cu")
		(net "KR_P0_OCP_TX_DP")
	)
	(segment
		(start 413.09925 -90.45575)
		(end 413.09925 -89.943686)
		(width 0.101346)
		(layer "In9.Cu")
		(net "KR_P0_OCP_TX_DP")
	)
	(segment
		(start 434.6956 -55.369968)
		(end 436.23103 -56.905398)
		(width 0.101346)
		(layer "In9.Cu")
		(net "KR_P0_OCP_TX_DP")
	)
	(segment
		(start 419.062662 -63.662814)
		(end 419.062662 -61.375036)
		(width 0.101346)
		(layer "In9.Cu")
		(net "KR_P0_OCP_TX_DP")
	)
	(segment
		(start 410.191966 -100.49002)
		(end 410.623766 -100.49002)
		(width 0.101346)
		(layer "In9.Cu")
		(net "KR_P0_OCP_TX_DP")
	)
	(segment
		(start 409.11526 -101.56698)
		(end 409.330144 -101.351842)
		(width 0.101346)
		(layer "In9.Cu")
		(net "KR_P0_OCP_TX_DP")
	)
	(segment
		(start 446.04559 -61.177932)
		(end 446.336166 -60.887356)
		(width 0.101346)
		(layer "In9.Cu")
		(net "KR_P0_OCP_TX_DP")
	)
	(segment
		(start 400.333972 -105.485438)
		(end 402.702014 -103.117396)
		(width 0.101346)
		(layer "In9.Cu")
		(net "KR_P0_OCP_TX_DP")
	)
	(segment
		(start 412.635446 -96.668336)
		(end 412.0896 -96.12249)
		(width 0.101346)
		(layer "In9.Cu")
		(net "KR_P0_OCP_TX_DP")
	)
	(segment
		(start 410.623766 -100.49002)
		(end 410.83865 -100.275136)
		(width 0.101346)
		(layer "In9.Cu")
		(net "KR_P0_OCP_TX_DP")
	)
	(segment
		(start 428.063152 -57.142126)
		(end 429.835564 -55.369968)
		(width 0.101346)
		(layer "In9.Cu")
		(net "KR_P0_OCP_TX_DP")
	)
	(segment
		(start 400.054064 -105.599738)
		(end 400.168364 -105.485438)
		(width 0.089154)
		(layer "In9.Cu")
		(net "KR_P0_OCP_TX_DP")
	)
	(segment
		(start 417.91636 -84.115656)
		(end 417.91636 -80.088486)
		(width 0.101346)
		(layer "In9.Cu")
		(net "KR_P0_OCP_TX_DP")
	)
	(segment
		(start 409.330144 -101.351842)
		(end 409.761944 -101.351842)
		(width 0.101346)
		(layer "In9.Cu")
		(net "KR_P0_OCP_TX_DP")
	)
	(segment
		(start 425.35856 -58.1533)
		(end 426.369734 -57.142126)
		(width 0.101346)
		(layer "In9.Cu")
		(net "KR_P0_OCP_TX_DP")
	)
	(segment
		(start 417.91636 -80.088486)
		(end 418.48024 -79.524606)
		(width 0.101346)
		(layer "In9.Cu")
		(net "KR_P0_OCP_TX_DP")
	)
	(segment
		(start 407.36774 -103.746046)
		(end 408.055572 -103.058214)
		(width 0.101346)
		(layer "In9.Cu")
		(net "KR_P0_OCP_TX_DP")
	)
	(arc
		(start 399.329148 -105.678732)
		(mid 399.471658 -105.619838)
		(end 399.62455 -105.599738)
		(width 0.089154)
		(layer "In9.Cu")
		(net "KR_P0_OCP_TX_DP")
	)
	(arc
		(start 398.338548 -105.678732)
		(mid 398.63395 -105.599635)
		(end 398.929352 -105.678732)
		(width 0.089154)
		(layer "In9.Cu")
		(net "KR_P0_OCP_TX_DP")
	)
	(arc
		(start 397.742918 -105.389934)
		(mid 397.807707 -105.556786)
		(end 397.938752 -105.678732)
		(width 0.089154)
		(layer "In9.Cu")
		(net "KR_P0_OCP_TX_DP")
	)
	(arc
		(start 398.929352 -105.678732)
		(mid 399.12925 -105.732265)
		(end 399.329148 -105.678732)
		(width 0.089154)
		(layer "In9.Cu")
		(net "KR_P0_OCP_TX_DP")
	)
	(arc
		(start 397.938752 -105.678732)
		(mid 398.13865 -105.732265)
		(end 398.338548 -105.678732)
		(width 0.089154)
		(layer "In9.Cu")
		(net "KR_P0_OCP_TX_DP")
	)
	(segment
		(start 397.14805 -105.332276)
		(end 397.558768 -105.52303)
		(width 0.10033)
		(layer "F.Cu")
		(net "KR_P0_OCP_TX_DN")
	)
	(segment
		(start 446.776348 -60.480448)
		(end 446.776348 -60.785502)
		(width 0.1016)
		(layer "F.Cu")
		(net "KR_P0_OCP_TX_DN")
	)
	(segment
		(start 446.950084 -60.959238)
		(end 446.950084 -62.00267)
		(width 0.1016)
		(layer "F.Cu")
		(net "KR_P0_OCP_TX_DN")
	)
	(segment
		(start 446.877948 -60.378848)
		(end 446.776348 -60.480448)
		(width 0.1016)
		(layer "F.Cu")
		(net "KR_P0_OCP_TX_DN")
	)
	(segment
		(start 397.558768 -105.52303)
		(end 397.64335 -105.5624)
		(width 0.10033)
		(layer "F.Cu")
		(net "KR_P0_OCP_TX_DN")
	)
	(segment
		(start 447.180716 -60.378848)
		(end 446.877948 -60.378848)
		(width 0.1016)
		(layer "F.Cu")
		(net "KR_P0_OCP_TX_DN")
	)
	(segment
		(start 446.776348 -60.785502)
		(end 446.950084 -60.959238)
		(width 0.1016)
		(layer "F.Cu")
		(net "KR_P0_OCP_TX_DN")
	)
	(via
		(at 397.14805 -105.332276)
		(size 0.508)
		(drill 0.254)
		(layers "F.Cu" "B.Cu")
		(net "KR_P0_OCP_TX_DN")
	)
	(via
		(at 447.180716 -60.378848)
		(size 0.508)
		(drill 0.254)
		(layers "F.Cu" "B.Cu")
		(net "KR_P0_OCP_TX_DN")
	)
	(segment
		(start 436.057294 -57.324752)
		(end 438.61355 -57.324752)
		(width 0.101346)
		(layer "In9.Cu")
		(net "KR_P0_OCP_TX_DN")
	)
	(segment
		(start 419.482016 -63.83655)
		(end 419.482016 -61.548772)
		(width 0.101346)
		(layer "In9.Cu")
		(net "KR_P0_OCP_TX_DN")
	)
	(segment
		(start 425.532296 -58.572654)
		(end 426.54347 -57.56148)
		(width 0.101346)
		(layer "In9.Cu")
		(net "KR_P0_OCP_TX_DN")
	)
	(segment
		(start 404.41626 -103.53675)
		(end 405.04491 -104.1654)
		(width 0.101346)
		(layer "In9.Cu")
		(net "KR_P0_OCP_TX_DN")
	)
	(segment
		(start 418.335714 -80.262222)
		(end 418.899594 -79.698342)
		(width 0.101346)
		(layer "In9.Cu")
		(net "KR_P0_OCP_TX_DN")
	)
	(segment
		(start 415.351976 -89.293954)
		(end 416.48761 -88.15832)
		(width 0.101346)
		(layer "In9.Cu")
		(net "KR_P0_OCP_TX_DN")
	)
	(segment
		(start 413.0548 -96.4946)
		(end 412.508954 -95.948754)
		(width 0.101346)
		(layer "In9.Cu")
		(net "KR_P0_OCP_TX_DN")
	)
	(segment
		(start 397.486124 -105.332276)
		(end 397.550894 -105.397046)
		(width 0.089154)
		(layer "In9.Cu")
		(net "KR_P0_OCP_TX_DN")
	)
	(segment
		(start 413.518604 -90.117422)
		(end 414.342072 -89.293954)
		(width 0.101346)
		(layer "In9.Cu")
		(net "KR_P0_OCP_TX_DN")
	)
	(segment
		(start 434.521864 -55.789322)
		(end 436.057294 -57.324752)
		(width 0.101346)
		(layer "In9.Cu")
		(net "KR_P0_OCP_TX_DN")
	)
	(segment
		(start 413.518604 -90.629486)
		(end 413.518604 -90.117422)
		(width 0.101346)
		(layer "In9.Cu")
		(net "KR_P0_OCP_TX_DN")
	)
	(segment
		(start 411.258004 -100.448872)
		(end 411.258004 -100.170996)
		(width 0.101346)
		(layer "In9.Cu")
		(net "KR_P0_OCP_TX_DN")
	)
	(segment
		(start 400.262344 -105.904792)
		(end 400.507708 -105.904792)
		(width 0.101346)
		(layer "In9.Cu")
		(net "KR_P0_OCP_TX_DN")
	)
	(segment
		(start 418.335714 -84.289392)
		(end 418.335714 -80.262222)
		(width 0.101346)
		(layer "In9.Cu")
		(net "KR_P0_OCP_TX_DN")
	)
	(segment
		(start 439.45429 -60.564522)
		(end 440.487054 -61.597286)
		(width 0.101346)
		(layer "In9.Cu")
		(net "KR_P0_OCP_TX_DN")
	)
	(segment
		(start 446.856866 -60.378848)
		(end 447.180716 -60.378848)
		(width 0.101346)
		(layer "In9.Cu")
		(net "KR_P0_OCP_TX_DN")
	)
	(segment
		(start 438.61355 -57.324752)
		(end 439.45429 -58.165492)
		(width 0.101346)
		(layer "In9.Cu")
		(net "KR_P0_OCP_TX_DN")
	)
	(segment
		(start 414.342072 -89.293954)
		(end 415.351976 -89.293954)
		(width 0.101346)
		(layer "In9.Cu")
		(net "KR_P0_OCP_TX_DN")
	)
	(segment
		(start 426.54347 -57.56148)
		(end 428.236888 -57.56148)
		(width 0.101346)
		(layer "In9.Cu")
		(net "KR_P0_OCP_TX_DN")
	)
	(segment
		(start 440.487054 -61.597286)
		(end 446.219326 -61.597286)
		(width 0.101346)
		(layer "In9.Cu")
		(net "KR_P0_OCP_TX_DN")
	)
	(segment
		(start 400.054064 -105.790492)
		(end 400.168364 -105.904792)
		(width 0.089154)
		(layer "In9.Cu")
		(net "KR_P0_OCP_TX_DN")
	)
	(segment
		(start 411.258004 -100.170996)
		(end 413.0548 -98.3742)
		(width 0.101346)
		(layer "In9.Cu")
		(net "KR_P0_OCP_TX_DN")
	)
	(segment
		(start 399.62455 -105.790492)
		(end 400.054064 -105.790492)
		(width 0.089154)
		(layer "In9.Cu")
		(net "KR_P0_OCP_TX_DN")
	)
	(segment
		(start 412.508954 -95.948754)
		(end 412.508954 -91.639136)
		(width 0.101346)
		(layer "In9.Cu")
		(net "KR_P0_OCP_TX_DN")
	)
	(segment
		(start 405.04491 -104.1654)
		(end 407.541476 -104.1654)
		(width 0.101346)
		(layer "In9.Cu")
		(net "KR_P0_OCP_TX_DN")
	)
	(segment
		(start 400.507708 -105.904792)
		(end 402.87575 -103.53675)
		(width 0.101346)
		(layer "In9.Cu")
		(net "KR_P0_OCP_TX_DN")
	)
	(segment
		(start 413.0548 -98.3742)
		(end 413.0548 -96.4946)
		(width 0.101346)
		(layer "In9.Cu")
		(net "KR_P0_OCP_TX_DN")
	)
	(segment
		(start 407.541476 -104.1654)
		(end 409.411678 -102.295198)
		(width 0.101346)
		(layer "In9.Cu")
		(net "KR_P0_OCP_TX_DN")
	)
	(segment
		(start 416.48761 -86.138512)
		(end 418.335714 -84.289392)
		(width 0.101346)
		(layer "In9.Cu")
		(net "KR_P0_OCP_TX_DN")
	)
	(segment
		(start 446.75552 -61.061092)
		(end 446.75552 -60.480194)
		(width 0.101346)
		(layer "In9.Cu")
		(net "KR_P0_OCP_TX_DN")
	)
	(segment
		(start 446.75552 -60.480194)
		(end 446.856866 -60.378848)
		(width 0.101346)
		(layer "In9.Cu")
		(net "KR_P0_OCP_TX_DN")
	)
	(segment
		(start 446.219326 -61.597286)
		(end 446.75552 -61.061092)
		(width 0.101346)
		(layer "In9.Cu")
		(net "KR_P0_OCP_TX_DN")
	)
	(segment
		(start 430.0093 -55.789322)
		(end 434.521864 -55.789322)
		(width 0.101346)
		(layer "In9.Cu")
		(net "KR_P0_OCP_TX_DN")
	)
	(segment
		(start 400.168364 -105.904792)
		(end 400.262344 -105.904792)
		(width 0.089154)
		(layer "In9.Cu")
		(net "KR_P0_OCP_TX_DN")
	)
	(segment
		(start 439.45429 -58.165492)
		(end 439.45429 -60.564522)
		(width 0.101346)
		(layer "In9.Cu")
		(net "KR_P0_OCP_TX_DN")
	)
	(segment
		(start 402.87575 -103.53675)
		(end 404.41626 -103.53675)
		(width 0.101346)
		(layer "In9.Cu")
		(net "KR_P0_OCP_TX_DN")
	)
	(segment
		(start 428.236888 -57.56148)
		(end 430.0093 -55.789322)
		(width 0.101346)
		(layer "In9.Cu")
		(net "KR_P0_OCP_TX_DN")
	)
	(segment
		(start 419.482016 -61.548772)
		(end 422.458134 -58.572654)
		(width 0.101346)
		(layer "In9.Cu")
		(net "KR_P0_OCP_TX_DN")
	)
	(segment
		(start 418.899594 -64.418972)
		(end 419.482016 -63.83655)
		(width 0.101346)
		(layer "In9.Cu")
		(net "KR_P0_OCP_TX_DN")
	)
	(segment
		(start 422.458134 -58.572654)
		(end 425.532296 -58.572654)
		(width 0.101346)
		(layer "In9.Cu")
		(net "KR_P0_OCP_TX_DN")
	)
	(segment
		(start 412.508954 -91.639136)
		(end 413.518604 -90.629486)
		(width 0.101346)
		(layer "In9.Cu")
		(net "KR_P0_OCP_TX_DN")
	)
	(segment
		(start 409.411678 -102.295198)
		(end 409.411678 -102.294944)
		(width 0.101346)
		(layer "In9.Cu")
		(net "KR_P0_OCP_TX_DN")
	)
	(segment
		(start 409.411678 -102.294944)
		(end 411.258004 -100.448872)
		(width 0.101346)
		(layer "In9.Cu")
		(net "KR_P0_OCP_TX_DN")
	)
	(segment
		(start 397.14805 -105.332276)
		(end 397.486124 -105.332276)
		(width 0.089154)
		(layer "In9.Cu")
		(net "KR_P0_OCP_TX_DN")
	)
	(segment
		(start 416.48761 -88.15832)
		(end 416.48761 -86.138512)
		(width 0.101346)
		(layer "In9.Cu")
		(net "KR_P0_OCP_TX_DN")
	)
	(segment
		(start 418.899594 -79.698342)
		(end 418.899594 -64.418972)
		(width 0.101346)
		(layer "In9.Cu")
		(net "KR_P0_OCP_TX_DN")
	)
	(arc
		(start 398.833848 -105.84434)
		(mid 399.12925 -105.923437)
		(end 399.424652 -105.84434)
		(width 0.089154)
		(layer "In9.Cu")
		(net "KR_P0_OCP_TX_DN")
	)
	(arc
		(start 397.550894 -105.397046)
		(mid 397.643626 -105.655629)
		(end 397.843248 -105.84434)
		(width 0.089154)
		(layer "In9.Cu")
		(net "KR_P0_OCP_TX_DN")
	)
	(arc
		(start 397.843248 -105.84434)
		(mid 398.13865 -105.923437)
		(end 398.434052 -105.84434)
		(width 0.089154)
		(layer "In9.Cu")
		(net "KR_P0_OCP_TX_DN")
	)
	(arc
		(start 399.424652 -105.84434)
		(mid 399.521039 -105.804195)
		(end 399.62455 -105.790492)
		(width 0.089154)
		(layer "In9.Cu")
		(net "KR_P0_OCP_TX_DN")
	)
	(arc
		(start 398.434052 -105.84434)
		(mid 398.63395 -105.790807)
		(end 398.833848 -105.84434)
		(width 0.089154)
		(layer "In9.Cu")
		(net "KR_P0_OCP_TX_DN")
	)
	(segment
		(start 144.647158 -51.682396)
		(end 144.629378 -51.861212)
		(width 0.10795)
		(layer "F.Cu")
		(net "TP_CPU1_RSVD_304")
	)
	(segment
		(start 146.979894 -55.791862)
		(end 147.06092 -55.710836)
		(width 0.10795)
		(layer "F.Cu")
		(net "TP_CPU1_RSVD_304")
	)
	(segment
		(start 146.370294 -55.362094)
		(end 146.800062 -55.791862)
		(width 0.10795)
		(layer "F.Cu")
		(net "TP_CPU1_RSVD_304")
	)
	(segment
		(start 145.922238 -54.353206)
		(end 146.19224 -55.005986)
		(width 0.10795)
		(layer "F.Cu")
		(net "TP_CPU1_RSVD_304")
	)
	(segment
		(start 145.990818 -54.187344)
		(end 145.922238 -54.353206)
		(width 0.10795)
		(layer "F.Cu")
		(net "TP_CPU1_RSVD_304")
	)
	(segment
		(start 143.700246 -50.9905)
		(end 144.177004 -51.309524)
		(width 0.10795)
		(layer "F.Cu")
		(net "TP_CPU1_RSVD_304")
	)
	(segment
		(start 144.629378 -51.861212)
		(end 145.155158 -52.502054)
		(width 0.10795)
		(layer "F.Cu")
		(net "TP_CPU1_RSVD_304")
	)
	(segment
		(start 145.737072 -53.907182)
		(end 145.903442 -53.975762)
		(width 0.10795)
		(layer "F.Cu")
		(net "TP_CPU1_RSVD_304")
	)
	(segment
		(start 145.57121 -53.174392)
		(end 145.658586 -53.38572)
		(width 0.10795)
		(layer "F.Cu")
		(net "TP_CPU1_RSVD_304")
	)
	(segment
		(start 139.674854 -51.446938)
		(end 139.956032 -51.446938)
		(width 0.10795)
		(layer "F.Cu")
		(net "TP_CPU1_RSVD_304")
	)
	(segment
		(start 145.155158 -52.502054)
		(end 145.405094 -53.105558)
		(width 0.10795)
		(layer "F.Cu")
		(net "TP_CPU1_RSVD_304")
	)
	(segment
		(start 145.658586 -53.38572)
		(end 145.590006 -53.551836)
		(width 0.10795)
		(layer "F.Cu")
		(net "TP_CPU1_RSVD_304")
	)
	(segment
		(start 145.903442 -53.975762)
		(end 145.990818 -54.187344)
		(width 0.10795)
		(layer "F.Cu")
		(net "TP_CPU1_RSVD_304")
	)
	(segment
		(start 144.177004 -51.309524)
		(end 144.323054 -51.487832)
		(width 0.10795)
		(layer "F.Cu")
		(net "TP_CPU1_RSVD_304")
	)
	(segment
		(start 145.405094 -53.105558)
		(end 145.57121 -53.174392)
		(width 0.10795)
		(layer "F.Cu")
		(net "TP_CPU1_RSVD_304")
	)
	(segment
		(start 147.06092 -55.710836)
		(end 147.06092 -55.342536)
		(width 0.10795)
		(layer "F.Cu")
		(net "TP_CPU1_RSVD_304")
	)
	(segment
		(start 146.19224 -55.005986)
		(end 146.370294 -55.362094)
		(width 0.10795)
		(layer "F.Cu")
		(net "TP_CPU1_RSVD_304")
	)
	(segment
		(start 144.323054 -51.487832)
		(end 144.502124 -51.505358)
		(width 0.10795)
		(layer "F.Cu")
		(net "TP_CPU1_RSVD_304")
	)
	(segment
		(start 145.590006 -53.551836)
		(end 145.737072 -53.907182)
		(width 0.10795)
		(layer "F.Cu")
		(net "TP_CPU1_RSVD_304")
	)
	(segment
		(start 146.800062 -55.791862)
		(end 146.979894 -55.791862)
		(width 0.10795)
		(layer "F.Cu")
		(net "TP_CPU1_RSVD_304")
	)
	(segment
		(start 139.956032 -51.446938)
		(end 140.41247 -50.9905)
		(width 0.10795)
		(layer "F.Cu")
		(net "TP_CPU1_RSVD_304")
	)
	(segment
		(start 144.502124 -51.505358)
		(end 144.647158 -51.682396)
		(width 0.10795)
		(layer "F.Cu")
		(net "TP_CPU1_RSVD_304")
	)
	(segment
		(start 140.41247 -50.9905)
		(end 143.700246 -50.9905)
		(width 0.10795)
		(layer "F.Cu")
		(net "TP_CPU1_RSVD_304")
	)
	(via
		(at 147.06092 -55.342536)
		(size 0.508)
		(drill 0.254)
		(layers "F.Cu" "B.Cu")
		(net "TP_CPU1_RSVD_304")
	)
	(segment
		(start 137.957814 -51.612038)
		(end 137.778998 -51.790854)
		(width 0.10795)
		(layer "F.Cu")
		(net "TP_CPU1_RSVD_303")
	)
	(segment
		(start 137.939018 -50.681636)
		(end 139.308586 -50.1142)
		(width 0.10795)
		(layer "F.Cu")
		(net "TP_CPU1_RSVD_303")
	)
	(segment
		(start 139.308586 -50.1142)
		(end 144.258538 -50.1142)
		(width 0.10795)
		(layer "F.Cu")
		(net "TP_CPU1_RSVD_303")
	)
	(segment
		(start 137.4775 -51.6509)
		(end 137.4775 -51.1429)
		(width 0.10795)
		(layer "F.Cu")
		(net "TP_CPU1_RSVD_303")
	)
	(segment
		(start 146.65325 -51.327304)
		(end 146.65325 -51.84775)
		(width 0.10795)
		(layer "F.Cu")
		(net "TP_CPU1_RSVD_303")
	)
	(segment
		(start 146.275806 -50.94986)
		(end 146.65325 -51.327304)
		(width 0.10795)
		(layer "F.Cu")
		(net "TP_CPU1_RSVD_303")
	)
	(segment
		(start 137.778998 -51.790854)
		(end 137.617454 -51.790854)
		(width 0.10795)
		(layer "F.Cu")
		(net "TP_CPU1_RSVD_303")
	)
	(segment
		(start 137.4775 -51.1429)
		(end 137.939018 -50.681636)
		(width 0.10795)
		(layer "F.Cu")
		(net "TP_CPU1_RSVD_303")
	)
	(segment
		(start 137.617454 -51.790854)
		(end 137.4775 -51.6509)
		(width 0.10795)
		(layer "F.Cu")
		(net "TP_CPU1_RSVD_303")
	)
	(segment
		(start 144.258538 -50.1142)
		(end 146.275806 -50.94986)
		(width 0.10795)
		(layer "F.Cu")
		(net "TP_CPU1_RSVD_303")
	)
	(segment
		(start 137.957814 -51.446938)
		(end 137.957814 -51.612038)
		(width 0.10795)
		(layer "F.Cu")
		(net "TP_CPU1_RSVD_303")
	)
	(via
		(at 146.65325 -51.84775)
		(size 0.508)
		(drill 0.254)
		(layers "F.Cu" "B.Cu")
		(net "TP_CPU1_RSVD_303")
	)
	(segment
		(start 144.945862 -52.62753)
		(end 145.987516 -55.142892)
		(width 0.10795)
		(layer "F.Cu")
		(net "TP_CPU1_RSVD_299")
	)
	(segment
		(start 140.533374 -51.941984)
		(end 140.309854 -51.941984)
		(width 0.10795)
		(layer "F.Cu")
		(net "TP_CPU1_RSVD_299")
	)
	(segment
		(start 140.309854 -51.941984)
		(end 140.1826 -51.81473)
		(width 0.10795)
		(layer "F.Cu")
		(net "TP_CPU1_RSVD_299")
	)
	(segment
		(start 146.17192 -55.505096)
		(end 146.699986 -56.033162)
		(width 0.10795)
		(layer "F.Cu")
		(net "TP_CPU1_RSVD_299")
	)
	(segment
		(start 145.987516 -55.142892)
		(end 145.99412 -55.149496)
		(width 0.10795)
		(layer "F.Cu")
		(net "TP_CPU1_RSVD_299")
	)
	(segment
		(start 140.1826 -51.81473)
		(end 140.1826 -51.561746)
		(width 0.10795)
		(layer "F.Cu")
		(net "TP_CPU1_RSVD_299")
	)
	(segment
		(start 147.07997 -56.033162)
		(end 147.231608 -55.881524)
		(width 0.10795)
		(layer "F.Cu")
		(net "TP_CPU1_RSVD_299")
	)
	(segment
		(start 146.699986 -56.033162)
		(end 147.07997 -56.033162)
		(width 0.10795)
		(layer "F.Cu")
		(net "TP_CPU1_RSVD_299")
	)
	(segment
		(start 147.231608 -55.881524)
		(end 147.599908 -55.881524)
		(width 0.10795)
		(layer "F.Cu")
		(net "TP_CPU1_RSVD_299")
	)
	(segment
		(start 140.512546 -51.2318)
		(end 143.62684 -51.2318)
		(width 0.10795)
		(layer "F.Cu")
		(net "TP_CPU1_RSVD_299")
	)
	(segment
		(start 144.01292 -51.490372)
		(end 144.945862 -52.62753)
		(width 0.10795)
		(layer "F.Cu")
		(net "TP_CPU1_RSVD_299")
	)
	(segment
		(start 145.99412 -55.149496)
		(end 146.17192 -55.505096)
		(width 0.10795)
		(layer "F.Cu")
		(net "TP_CPU1_RSVD_299")
	)
	(segment
		(start 140.1826 -51.561746)
		(end 140.512546 -51.2318)
		(width 0.10795)
		(layer "F.Cu")
		(net "TP_CPU1_RSVD_299")
	)
	(segment
		(start 143.62684 -51.2318)
		(end 144.01292 -51.490372)
		(width 0.10795)
		(layer "F.Cu")
		(net "TP_CPU1_RSVD_299")
	)
	(via
		(at 147.599908 -55.881524)
		(size 0.508)
		(drill 0.254)
		(layers "F.Cu" "B.Cu")
		(net "TP_CPU1_RSVD_299")
	)
	(segment
		(start 137.2362 -51.042824)
		(end 137.802112 -50.476912)
		(width 0.10795)
		(layer "F.Cu")
		(net "TP_CPU1_RSVD_298")
	)
	(segment
		(start 146.412712 -50.745136)
		(end 146.976338 -51.308762)
		(width 0.10795)
		(layer "F.Cu")
		(net "TP_CPU1_RSVD_298")
	)
	(segment
		(start 137.2362 -51.805332)
		(end 137.2362 -51.042824)
		(width 0.10795)
		(layer "F.Cu")
		(net "TP_CPU1_RSVD_298")
	)
	(segment
		(start 146.976338 -51.308762)
		(end 147.192238 -51.308762)
		(width 0.10795)
		(layer "F.Cu")
		(net "TP_CPU1_RSVD_298")
	)
	(segment
		(start 137.099294 -51.941984)
		(end 137.2362 -51.805332)
		(width 0.10795)
		(layer "F.Cu")
		(net "TP_CPU1_RSVD_298")
	)
	(segment
		(start 139.041378 -49.963578)
		(end 139.260326 -49.8729)
		(width 0.10795)
		(layer "F.Cu")
		(net "TP_CPU1_RSVD_298")
	)
	(segment
		(start 138.8872 -50.027332)
		(end 139.041378 -49.963578)
		(width 0.10795)
		(layer "F.Cu")
		(net "TP_CPU1_RSVD_298")
	)
	(segment
		(start 137.802112 -50.476912)
		(end 138.8872 -50.027332)
		(width 0.10795)
		(layer "F.Cu")
		(net "TP_CPU1_RSVD_298")
	)
	(segment
		(start 144.306544 -49.8729)
		(end 146.412712 -50.745136)
		(width 0.10795)
		(layer "F.Cu")
		(net "TP_CPU1_RSVD_298")
	)
	(segment
		(start 139.260326 -49.8729)
		(end 144.306544 -49.8729)
		(width 0.10795)
		(layer "F.Cu")
		(net "TP_CPU1_RSVD_298")
	)
	(via
		(at 147.192238 -51.308762)
		(size 0.508)
		(drill 0.254)
		(layers "F.Cu" "B.Cu")
		(net "TP_CPU1_RSVD_298")
	)
	(segment
		(start 138.8872 -52.926488)
		(end 138.816334 -52.932838)
		(width 0.10795)
		(layer "F.Cu")
		(net "TP_CPU1_RSVD_287")
	)
	(segment
		(start 140.4366 -52.4764)
		(end 140.36548 -52.526184)
		(width 0.10795)
		(layer "F.Cu")
		(net "TP_CPU1_RSVD_287")
	)
	(segment
		(start 139.84351 -52.83962)
		(end 138.8872 -52.926488)
		(width 0.10795)
		(layer "F.Cu")
		(net "TP_CPU1_RSVD_287")
	)
	(segment
		(start 142.719044 -52.197762)
		(end 142.591282 -52.07)
		(width 0.10795)
		(layer "F.Cu")
		(net "TP_CPU1_RSVD_287")
	)
	(segment
		(start 141.501114 -52.07)
		(end 140.4366 -52.4764)
		(width 0.10795)
		(layer "F.Cu")
		(net "TP_CPU1_RSVD_287")
	)
	(segment
		(start 140.36548 -52.526184)
		(end 139.84351 -52.83962)
		(width 0.10795)
		(layer "F.Cu")
		(net "TP_CPU1_RSVD_287")
	)
	(segment
		(start 142.591282 -52.07)
		(end 141.501114 -52.07)
		(width 0.10795)
		(layer "F.Cu")
		(net "TP_CPU1_RSVD_287")
	)
	(segment
		(start 142.966694 -52.197762)
		(end 142.719044 -52.197762)
		(width 0.10795)
		(layer "F.Cu")
		(net "TP_CPU1_RSVD_287")
	)
	(via
		(at 142.966694 -52.197762)
		(size 0.508)
		(drill 0.254)
		(layers "F.Cu" "B.Cu")
		(net "TP_CPU1_RSVD_287")
	)
	(segment
		(start 141.955012 -53.726588)
		(end 142.2273 -53.4543)
		(width 0.10795)
		(layer "F.Cu")
		(net "TP_CPU1_RSVD_283")
	)
	(segment
		(start 141.635734 -53.726588)
		(end 141.955012 -53.726588)
		(width 0.10795)
		(layer "F.Cu")
		(net "TP_CPU1_RSVD_283")
	)
	(segment
		(start 143.378174 -53.654198)
		(end 143.696182 -53.654198)
		(width 0.10795)
		(layer "F.Cu")
		(net "TP_CPU1_RSVD_283")
	)
	(segment
		(start 143.178276 -53.4543)
		(end 143.378174 -53.654198)
		(width 0.10795)
		(layer "F.Cu")
		(net "TP_CPU1_RSVD_283")
	)
	(segment
		(start 141.391894 -53.482748)
		(end 141.635734 -53.726588)
		(width 0.10795)
		(layer "F.Cu")
		(net "TP_CPU1_RSVD_283")
	)
	(segment
		(start 142.2273 -53.4543)
		(end 143.178276 -53.4543)
		(width 0.10795)
		(layer "F.Cu")
		(net "TP_CPU1_RSVD_283")
	)
	(segment
		(start 143.696182 -53.654198)
		(end 143.776954 -53.73497)
		(width 0.10795)
		(layer "F.Cu")
		(net "TP_CPU1_RSVD_283")
	)
	(segment
		(start 141.391894 -53.427884)
		(end 141.391894 -53.482748)
		(width 0.10795)
		(layer "F.Cu")
		(net "TP_CPU1_RSVD_283")
	)
	(via
		(at 143.776954 -53.73497)
		(size 0.508)
		(drill 0.254)
		(layers "F.Cu" "B.Cu")
		(net "TP_CPU1_RSVD_283")
	)
	(segment
		(start 140.0556 -53.086)
		(end 139.826746 -53.086)
		(width 0.10795)
		(layer "F.Cu")
		(net "TP_CPU1_RSVD_282")
	)
	(segment
		(start 142.582138 -52.402232)
		(end 142.491206 -52.3113)
		(width 0.10795)
		(layer "F.Cu")
		(net "TP_CPU1_RSVD_282")
	)
	(segment
		(start 140.753338 -53.404008)
		(end 140.373608 -53.404008)
		(width 0.10795)
		(layer "F.Cu")
		(net "TP_CPU1_RSVD_282")
	)
	(segment
		(start 141.9098 -52.730146)
		(end 141.655546 -52.9844)
		(width 0.10795)
		(layer "F.Cu")
		(net "TP_CPU1_RSVD_282")
	)
	(segment
		(start 139.674854 -53.237892)
		(end 139.674854 -53.427884)
		(width 0.10795)
		(layer "F.Cu")
		(net "TP_CPU1_RSVD_282")
	)
	(segment
		(start 141.655546 -52.9844)
		(end 141.172946 -52.9844)
		(width 0.10795)
		(layer "F.Cu")
		(net "TP_CPU1_RSVD_282")
	)
	(segment
		(start 142.582138 -52.582318)
		(end 142.582138 -52.402232)
		(width 0.10795)
		(layer "F.Cu")
		(net "TP_CPU1_RSVD_282")
	)
	(segment
		(start 141.9098 -52.4637)
		(end 141.9098 -52.730146)
		(width 0.10795)
		(layer "F.Cu")
		(net "TP_CPU1_RSVD_282")
	)
	(segment
		(start 142.427706 -52.73675)
		(end 142.582138 -52.582318)
		(width 0.10795)
		(layer "F.Cu")
		(net "TP_CPU1_RSVD_282")
	)
	(segment
		(start 142.491206 -52.3113)
		(end 142.0622 -52.3113)
		(width 0.10795)
		(layer "F.Cu")
		(net "TP_CPU1_RSVD_282")
	)
	(segment
		(start 140.373608 -53.404008)
		(end 140.0556 -53.086)
		(width 0.10795)
		(layer "F.Cu")
		(net "TP_CPU1_RSVD_282")
	)
	(segment
		(start 142.0622 -52.3113)
		(end 141.9098 -52.4637)
		(width 0.10795)
		(layer "F.Cu")
		(net "TP_CPU1_RSVD_282")
	)
	(segment
		(start 139.826746 -53.086)
		(end 139.674854 -53.237892)
		(width 0.10795)
		(layer "F.Cu")
		(net "TP_CPU1_RSVD_282")
	)
	(segment
		(start 141.172946 -52.9844)
		(end 140.753338 -53.404008)
		(width 0.10795)
		(layer "F.Cu")
		(net "TP_CPU1_RSVD_282")
	)
	(via
		(at 142.427706 -52.73675)
		(size 0.508)
		(drill 0.254)
		(layers "F.Cu" "B.Cu")
		(net "TP_CPU1_RSVD_282")
	)
	(segment
		(start 143.2306 -53.848)
		(end 143.0782 -53.6956)
		(width 0.10795)
		(layer "F.Cu")
		(net "TP_CPU1_RSVD_275")
	)
	(segment
		(start 142.055088 -53.967888)
		(end 141.637512 -53.967888)
		(width 0.10795)
		(layer "F.Cu")
		(net "TP_CPU1_RSVD_275")
	)
	(segment
		(start 143.2306 -54.229)
		(end 143.2306 -53.848)
		(width 0.10795)
		(layer "F.Cu")
		(net "TP_CPU1_RSVD_275")
	)
	(segment
		(start 141.637512 -53.967888)
		(end 141.391894 -54.213506)
		(width 0.10795)
		(layer "F.Cu")
		(net "TP_CPU1_RSVD_275")
	)
	(segment
		(start 143.0782 -53.6956)
		(end 142.327376 -53.6956)
		(width 0.10795)
		(layer "F.Cu")
		(net "TP_CPU1_RSVD_275")
	)
	(segment
		(start 141.391894 -54.213506)
		(end 141.391894 -54.418738)
		(width 0.10795)
		(layer "F.Cu")
		(net "TP_CPU1_RSVD_275")
	)
	(segment
		(start 142.327376 -53.6956)
		(end 142.055088 -53.967888)
		(width 0.10795)
		(layer "F.Cu")
		(net "TP_CPU1_RSVD_275")
	)
	(via
		(at 143.2306 -54.229)
		(size 0.508)
		(drill 0.254)
		(layers "F.Cu" "B.Cu")
		(net "TP_CPU1_RSVD_275")
	)
	(segment
		(start 311.3024 -50.7492)
		(end 311.531 -50.7492)
		(width 0.10795)
		(layer "F.Cu")
		(net "TP_CPU0_RSVD_304")
	)
	(segment
		(start 310.6166 -50.6476)
		(end 310.896 -50.927)
		(width 0.10795)
		(layer "F.Cu")
		(net "TP_CPU0_RSVD_304")
	)
	(segment
		(start 304.675286 -51.446938)
		(end 305.081686 -51.446938)
		(width 0.10795)
		(layer "F.Cu")
		(net "TP_CPU0_RSVD_304")
	)
	(segment
		(start 307.316124 -50.9143)
		(end 307.582824 -50.6476)
		(width 0.10795)
		(layer "F.Cu")
		(net "TP_CPU0_RSVD_304")
	)
	(segment
		(start 307.582824 -50.6476)
		(end 310.6166 -50.6476)
		(width 0.10795)
		(layer "F.Cu")
		(net "TP_CPU0_RSVD_304")
	)
	(segment
		(start 311.1246 -50.927)
		(end 311.3024 -50.7492)
		(width 0.10795)
		(layer "F.Cu")
		(net "TP_CPU0_RSVD_304")
	)
	(segment
		(start 305.614324 -50.9143)
		(end 307.316124 -50.9143)
		(width 0.10795)
		(layer "F.Cu")
		(net "TP_CPU0_RSVD_304")
	)
	(segment
		(start 310.896 -50.927)
		(end 311.1246 -50.927)
		(width 0.10795)
		(layer "F.Cu")
		(net "TP_CPU0_RSVD_304")
	)
	(segment
		(start 305.081686 -51.446938)
		(end 305.614324 -50.9143)
		(width 0.10795)
		(layer "F.Cu")
		(net "TP_CPU0_RSVD_304")
	)
	(via
		(at 311.531 -50.7492)
		(size 0.508)
		(drill 0.254)
		(layers "F.Cu" "B.Cu")
		(net "TP_CPU0_RSVD_304")
	)
	(segment
		(start 305.660552 -49.9872)
		(end 305.48072 -49.9872)
		(width 0.10795)
		(layer "F.Cu")
		(net "TP_CPU0_RSVD_303")
	)
	(segment
		(start 302.971708 -50.7111)
		(end 302.542702 -51.140106)
		(width 0.10795)
		(layer "F.Cu")
		(net "TP_CPU0_RSVD_303")
	)
	(segment
		(start 302.851566 -51.716686)
		(end 302.958246 -51.610006)
		(width 0.10795)
		(layer "F.Cu")
		(net "TP_CPU0_RSVD_303")
	)
	(segment
		(start 307.35778 -49.6062)
		(end 307.1114 -49.6062)
		(width 0.10795)
		(layer "F.Cu")
		(net "TP_CPU0_RSVD_303")
	)
	(segment
		(start 305.48072 -49.9872)
		(end 304.75682 -50.7111)
		(width 0.10795)
		(layer "F.Cu")
		(net "TP_CPU0_RSVD_303")
	)
	(segment
		(start 302.542702 -51.587654)
		(end 302.671734 -51.716686)
		(width 0.10795)
		(layer "F.Cu")
		(net "TP_CPU0_RSVD_303")
	)
	(segment
		(start 307.1114 -49.6062)
		(end 306.86248 -49.35728)
		(width 0.10795)
		(layer "F.Cu")
		(net "TP_CPU0_RSVD_303")
	)
	(segment
		(start 302.671734 -51.716686)
		(end 302.851566 -51.716686)
		(width 0.10795)
		(layer "F.Cu")
		(net "TP_CPU0_RSVD_303")
	)
	(segment
		(start 306.86248 -49.35728)
		(end 306.11064 -49.35728)
		(width 0.10795)
		(layer "F.Cu")
		(net "TP_CPU0_RSVD_303")
	)
	(segment
		(start 302.542702 -51.140106)
		(end 302.542702 -51.587654)
		(width 0.10795)
		(layer "F.Cu")
		(net "TP_CPU0_RSVD_303")
	)
	(segment
		(start 304.75682 -50.7111)
		(end 302.971708 -50.7111)
		(width 0.10795)
		(layer "F.Cu")
		(net "TP_CPU0_RSVD_303")
	)
	(segment
		(start 305.816 -49.831752)
		(end 305.660552 -49.9872)
		(width 0.10795)
		(layer "F.Cu")
		(net "TP_CPU0_RSVD_303")
	)
	(segment
		(start 302.958246 -51.610006)
		(end 302.958246 -51.446938)
		(width 0.10795)
		(layer "F.Cu")
		(net "TP_CPU0_RSVD_303")
	)
	(segment
		(start 305.816 -49.65192)
		(end 305.816 -49.831752)
		(width 0.10795)
		(layer "F.Cu")
		(net "TP_CPU0_RSVD_303")
	)
	(segment
		(start 306.11064 -49.35728)
		(end 305.816 -49.65192)
		(width 0.10795)
		(layer "F.Cu")
		(net "TP_CPU0_RSVD_303")
	)
	(via
		(at 307.35778 -49.6062)
		(size 0.508)
		(drill 0.254)
		(layers "F.Cu" "B.Cu")
		(net "TP_CPU0_RSVD_303")
	)
	(segment
		(start 311.3024 -51.4096)
		(end 311.0611 -51.1683)
		(width 0.10795)
		(layer "F.Cu")
		(net "TP_CPU0_RSVD_299")
	)
	(segment
		(start 305.3334 -51.741578)
		(end 305.533806 -51.941984)
		(width 0.10795)
		(layer "F.Cu")
		(net "TP_CPU0_RSVD_299")
	)
	(segment
		(start 308.0639 -50.8889)
		(end 307.6829 -50.8889)
		(width 0.10795)
		(layer "F.Cu")
		(net "TP_CPU0_RSVD_299")
	)
	(segment
		(start 308.5465 -50.8889)
		(end 308.4195 -51.0159)
		(width 0.10795)
		(layer "F.Cu")
		(net "TP_CPU0_RSVD_299")
	)
	(segment
		(start 311.531 -51.4096)
		(end 311.3024 -51.4096)
		(width 0.10795)
		(layer "F.Cu")
		(net "TP_CPU0_RSVD_299")
	)
	(segment
		(start 307.4162 -51.1556)
		(end 305.7144 -51.1556)
		(width 0.10795)
		(layer "F.Cu")
		(net "TP_CPU0_RSVD_299")
	)
	(segment
		(start 308.1909 -51.0159)
		(end 308.0639 -50.8889)
		(width 0.10795)
		(layer "F.Cu")
		(net "TP_CPU0_RSVD_299")
	)
	(segment
		(start 305.3334 -51.5366)
		(end 305.3334 -51.741578)
		(width 0.10795)
		(layer "F.Cu")
		(net "TP_CPU0_RSVD_299")
	)
	(segment
		(start 308.4195 -51.0159)
		(end 308.1909 -51.0159)
		(width 0.10795)
		(layer "F.Cu")
		(net "TP_CPU0_RSVD_299")
	)
	(segment
		(start 309.1307 -51.0159)
		(end 308.9021 -51.0159)
		(width 0.10795)
		(layer "F.Cu")
		(net "TP_CPU0_RSVD_299")
	)
	(segment
		(start 308.7751 -50.8889)
		(end 308.5465 -50.8889)
		(width 0.10795)
		(layer "F.Cu")
		(net "TP_CPU0_RSVD_299")
	)
	(segment
		(start 308.9021 -51.0159)
		(end 308.7751 -50.8889)
		(width 0.10795)
		(layer "F.Cu")
		(net "TP_CPU0_RSVD_299")
	)
	(segment
		(start 307.6829 -50.8889)
		(end 307.4162 -51.1556)
		(width 0.10795)
		(layer "F.Cu")
		(net "TP_CPU0_RSVD_299")
	)
	(segment
		(start 305.7144 -51.1556)
		(end 305.3334 -51.5366)
		(width 0.10795)
		(layer "F.Cu")
		(net "TP_CPU0_RSVD_299")
	)
	(segment
		(start 310.516524 -50.8889)
		(end 309.2577 -50.8889)
		(width 0.10795)
		(layer "F.Cu")
		(net "TP_CPU0_RSVD_299")
	)
	(segment
		(start 309.2577 -50.8889)
		(end 309.1307 -51.0159)
		(width 0.10795)
		(layer "F.Cu")
		(net "TP_CPU0_RSVD_299")
	)
	(segment
		(start 310.795924 -51.1683)
		(end 310.516524 -50.8889)
		(width 0.10795)
		(layer "F.Cu")
		(net "TP_CPU0_RSVD_299")
	)
	(segment
		(start 311.0611 -51.1683)
		(end 310.795924 -51.1683)
		(width 0.10795)
		(layer "F.Cu")
		(net "TP_CPU0_RSVD_299")
	)
	(via
		(at 311.531 -51.4096)
		(size 0.508)
		(drill 0.254)
		(layers "F.Cu" "B.Cu")
		(net "TP_CPU0_RSVD_299")
	)
	(segment
		(start 307.34 -48.895)
		(end 307.11902 -49.11598)
		(width 0.10795)
		(layer "F.Cu")
		(net "TP_CPU0_RSVD_298")
	)
	(segment
		(start 302.301402 -51.04003)
		(end 302.301402 -51.740308)
		(width 0.10795)
		(layer "F.Cu")
		(net "TP_CPU0_RSVD_298")
	)
	(segment
		(start 306.010564 -49.11598)
		(end 304.656744 -50.4698)
		(width 0.10795)
		(layer "F.Cu")
		(net "TP_CPU0_RSVD_298")
	)
	(segment
		(start 302.301402 -51.740308)
		(end 302.099726 -51.941984)
		(width 0.10795)
		(layer "F.Cu")
		(net "TP_CPU0_RSVD_298")
	)
	(segment
		(start 304.656744 -50.4698)
		(end 302.871632 -50.4698)
		(width 0.10795)
		(layer "F.Cu")
		(net "TP_CPU0_RSVD_298")
	)
	(segment
		(start 302.871632 -50.4698)
		(end 302.301402 -51.04003)
		(width 0.10795)
		(layer "F.Cu")
		(net "TP_CPU0_RSVD_298")
	)
	(segment
		(start 307.11902 -49.11598)
		(end 306.010564 -49.11598)
		(width 0.10795)
		(layer "F.Cu")
		(net "TP_CPU0_RSVD_298")
	)
	(via
		(at 307.34 -48.895)
		(size 0.508)
		(drill 0.254)
		(layers "F.Cu" "B.Cu")
		(net "TP_CPU0_RSVD_298")
	)
	(segment
		(start 304.884074 -52.775104)
		(end 305.645058 -52.344574)
		(width 0.10795)
		(layer "F.Cu")
		(net "TP_CPU0_RSVD_287")
	)
	(segment
		(start 309.5371 -52.3875)
		(end 309.7657 -52.3875)
		(width 0.10795)
		(layer "F.Cu")
		(net "TP_CPU0_RSVD_287")
	)
	(segment
		(start 309.9816 -52.1716)
		(end 310.2102 -52.1716)
		(width 0.10795)
		(layer "F.Cu")
		(net "TP_CPU0_RSVD_287")
	)
	(segment
		(start 305.645058 -52.344574)
		(end 305.7906 -52.2732)
		(width 0.10795)
		(layer "F.Cu")
		(net "TP_CPU0_RSVD_287")
	)
	(segment
		(start 309.118 -51.9684)
		(end 309.5371 -52.3875)
		(width 0.10795)
		(layer "F.Cu")
		(net "TP_CPU0_RSVD_287")
	)
	(segment
		(start 305.7906 -52.2732)
		(end 306.0954 -51.9684)
		(width 0.10795)
		(layer "F.Cu")
		(net "TP_CPU0_RSVD_287")
	)
	(segment
		(start 304.68951 -52.87391)
		(end 304.884074 -52.775104)
		(width 0.10795)
		(layer "F.Cu")
		(net "TP_CPU0_RSVD_287")
	)
	(segment
		(start 306.0954 -51.9684)
		(end 309.118 -51.9684)
		(width 0.10795)
		(layer "F.Cu")
		(net "TP_CPU0_RSVD_287")
	)
	(segment
		(start 303.816766 -52.932838)
		(end 304.68951 -52.87391)
		(width 0.10795)
		(layer "F.Cu")
		(net "TP_CPU0_RSVD_287")
	)
	(segment
		(start 309.7657 -52.3875)
		(end 309.9816 -52.1716)
		(width 0.10795)
		(layer "F.Cu")
		(net "TP_CPU0_RSVD_287")
	)
	(via
		(at 310.2102 -52.1716)
		(size 0.508)
		(drill 0.254)
		(layers "F.Cu" "B.Cu")
		(net "TP_CPU0_RSVD_287")
	)
	(segment
		(start 309.7784 -52.6288)
		(end 309.437024 -52.6288)
		(width 0.10795)
		(layer "F.Cu")
		(net "TP_CPU0_RSVD_282")
	)
	(segment
		(start 306.959 -52.2097)
		(end 306.832 -52.3367)
		(width 0.10795)
		(layer "F.Cu")
		(net "TP_CPU0_RSVD_282")
	)
	(segment
		(start 306.1462 -52.9336)
		(end 305.721004 -53.358796)
		(width 0.10795)
		(layer "F.Cu")
		(net "TP_CPU0_RSVD_282")
	)
	(segment
		(start 310.2102 -52.832)
		(end 309.9816 -52.832)
		(width 0.10795)
		(layer "F.Cu")
		(net "TP_CPU0_RSVD_282")
	)
	(segment
		(start 307.2511 -52.2097)
		(end 306.959 -52.2097)
		(width 0.10795)
		(layer "F.Cu")
		(net "TP_CPU0_RSVD_282")
	)
	(segment
		(start 305.101752 -53.0606)
		(end 304.926746 -53.0606)
		(width 0.10795)
		(layer "F.Cu")
		(net "TP_CPU0_RSVD_282")
	)
	(segment
		(start 307.3781 -52.3367)
		(end 307.2511 -52.2097)
		(width 0.10795)
		(layer "F.Cu")
		(net "TP_CPU0_RSVD_282")
	)
	(segment
		(start 309.437024 -52.6288)
		(end 309.017924 -52.2097)
		(width 0.10795)
		(layer "F.Cu")
		(net "TP_CPU0_RSVD_282")
	)
	(segment
		(start 305.721004 -53.358796)
		(end 305.399948 -53.358796)
		(width 0.10795)
		(layer "F.Cu")
		(net "TP_CPU0_RSVD_282")
	)
	(segment
		(start 305.399948 -53.358796)
		(end 305.101752 -53.0606)
		(width 0.10795)
		(layer "F.Cu")
		(net "TP_CPU0_RSVD_282")
	)
	(segment
		(start 307.7337 -52.2097)
		(end 307.6067 -52.3367)
		(width 0.10795)
		(layer "F.Cu")
		(net "TP_CPU0_RSVD_282")
	)
	(segment
		(start 304.675286 -53.31206)
		(end 304.675286 -53.427884)
		(width 0.10795)
		(layer "F.Cu")
		(net "TP_CPU0_RSVD_282")
	)
	(segment
		(start 307.6067 -52.3367)
		(end 307.3781 -52.3367)
		(width 0.10795)
		(layer "F.Cu")
		(net "TP_CPU0_RSVD_282")
	)
	(segment
		(start 309.9816 -52.832)
		(end 309.7784 -52.6288)
		(width 0.10795)
		(layer "F.Cu")
		(net "TP_CPU0_RSVD_282")
	)
	(segment
		(start 306.832 -52.3367)
		(end 306.832 -52.621688)
		(width 0.10795)
		(layer "F.Cu")
		(net "TP_CPU0_RSVD_282")
	)
	(segment
		(start 304.926746 -53.0606)
		(end 304.675286 -53.31206)
		(width 0.10795)
		(layer "F.Cu")
		(net "TP_CPU0_RSVD_282")
	)
	(segment
		(start 306.832 -52.621688)
		(end 306.520088 -52.9336)
		(width 0.10795)
		(layer "F.Cu")
		(net "TP_CPU0_RSVD_282")
	)
	(segment
		(start 309.017924 -52.2097)
		(end 307.7337 -52.2097)
		(width 0.10795)
		(layer "F.Cu")
		(net "TP_CPU0_RSVD_282")
	)
	(segment
		(start 306.520088 -52.9336)
		(end 306.1462 -52.9336)
		(width 0.10795)
		(layer "F.Cu")
		(net "TP_CPU0_RSVD_282")
	)
	(via
		(at 310.2102 -52.832)
		(size 0.508)
		(drill 0.254)
		(layers "F.Cu" "B.Cu")
		(net "TP_CPU0_RSVD_282")
	)
	(segment
		(start 311.60339 -54.102762)
		(end 306.708302 -54.102762)
		(width 0.10795)
		(layer "F.Cu")
		(net "TP_CPU0_RSVD_275")
	)
	(segment
		(start 306.708302 -54.102762)
		(end 306.392326 -54.418738)
		(width 0.10795)
		(layer "F.Cu")
		(net "TP_CPU0_RSVD_275")
	)
	(via
		(at 311.60339 -54.102762)
		(size 0.508)
		(drill 0.254)
		(layers "F.Cu" "B.Cu")
		(net "TP_CPU0_RSVD_275")
	)
	(segment
		(start 390.347454 -34.021014)
		(end 389.387334 -34.021014)
		(width 0.10795)
		(layer "F.Cu")
		(net "PU_M2_CLK_REQ_N")
	)
	(segment
		(start 389.387334 -34.021014)
		(end 389.046212 -34.362136)
		(width 0.10795)
		(layer "F.Cu")
		(net "PU_M2_CLK_REQ_N")
	)
	(via
		(at 392.557 -35.179)
		(size 0.6604)
		(drill 0.3302)
		(layers "F.Cu" "B.Cu")
		(net "PU_M2_CLK_REQ_N")
	)
	(via
		(at 389.046212 -34.362136)
		(size 0.508)
		(drill 0.254)
		(layers "F.Cu" "B.Cu")
		(net "PU_M2_CLK_REQ_N")
	)
	(segment
		(start 392.135106 -35.179)
		(end 392.557 -35.179)
		(width 0.10795)
		(layer "B.Cu")
		(net "PU_M2_CLK_REQ_N")
	)
	(segment
		(start 392.557 -35.179)
		(end 392.557 -35.972242)
		(width 0.10795)
		(layer "B.Cu")
		(net "PU_M2_CLK_REQ_N")
	)
	(segment
		(start 389.788908 -35.104832)
		(end 392.060938 -35.104832)
		(width 0.10795)
		(layer "B.Cu")
		(net "PU_M2_CLK_REQ_N")
	)
	(segment
		(start 392.060938 -35.104832)
		(end 392.135106 -35.179)
		(width 0.10795)
		(layer "B.Cu")
		(net "PU_M2_CLK_REQ_N")
	)
	(segment
		(start 392.557 -35.972242)
		(end 391.964926 -36.564316)
		(width 0.10795)
		(layer "B.Cu")
		(net "PU_M2_CLK_REQ_N")
	)
	(segment
		(start 389.046212 -34.362136)
		(end 389.788908 -35.104832)
		(width 0.10795)
		(layer "B.Cu")
		(net "PU_M2_CLK_REQ_N")
	)
	(segment
		(start 374.208294 -127.639826)
		(end 373.8499 -127.99822)
		(width 0.127)
		(layer "F.Cu")
		(net "A_EXTCLKP")
	)
	(segment
		(start 375.119646 -125.557026)
		(end 374.750838 -125.925834)
		(width 0.0889)
		(layer "F.Cu")
		(net "A_EXTCLKP")
	)
	(segment
		(start 375.7549 -124.2568)
		(end 375.7549 -124.8537)
		(width 0.0889)
		(layer "F.Cu")
		(net "A_EXTCLKP")
	)
	(segment
		(start 376.335036 -123.854972)
		(end 376.330972 -123.854972)
		(width 0.0889)
		(layer "F.Cu")
		(net "A_EXTCLKP")
	)
	(segment
		(start 375.6279 -124.9807)
		(end 375.24563 -124.9807)
		(width 0.0889)
		(layer "F.Cu")
		(net "A_EXTCLKP")
	)
	(segment
		(start 374.151144 -127.267462)
		(end 374.208294 -127.324612)
		(width 0.0889)
		(layer "F.Cu")
		(net "A_EXTCLKP")
	)
	(segment
		(start 375.7549 -124.8537)
		(end 375.6279 -124.9807)
		(width 0.0889)
		(layer "F.Cu")
		(net "A_EXTCLKP")
	)
	(segment
		(start 375.24563 -124.9807)
		(end 375.119646 -125.106684)
		(width 0.0889)
		(layer "F.Cu")
		(net "A_EXTCLKP")
	)
	(segment
		(start 375.119646 -125.106684)
		(end 375.119646 -125.557026)
		(width 0.0889)
		(layer "F.Cu")
		(net "A_EXTCLKP")
	)
	(segment
		(start 370.967 -128.2954)
		(end 370.7384 -128.524)
		(width 0.1016)
		(layer "F.Cu")
		(net "A_EXTCLKP")
	)
	(segment
		(start 376.330972 -123.854972)
		(end 376.1867 -123.7107)
		(width 0.0889)
		(layer "F.Cu")
		(net "A_EXTCLKP")
	)
	(segment
		(start 373.8499 -127.99822)
		(end 373.55272 -128.2954)
		(width 0.1016)
		(layer "F.Cu")
		(net "A_EXTCLKP")
	)
	(segment
		(start 375.9327 -123.827794)
		(end 375.9327 -124.079)
		(width 0.0889)
		(layer "F.Cu")
		(net "A_EXTCLKP")
	)
	(segment
		(start 374.750838 -125.925834)
		(end 374.750838 -126.13259)
		(width 0.0889)
		(layer "F.Cu")
		(net "A_EXTCLKP")
	)
	(segment
		(start 374.750838 -126.13259)
		(end 374.151144 -126.732284)
		(width 0.0889)
		(layer "F.Cu")
		(net "A_EXTCLKP")
	)
	(segment
		(start 374.208294 -127.324612)
		(end 374.208294 -127.639826)
		(width 0.127)
		(layer "F.Cu")
		(net "A_EXTCLKP")
	)
	(segment
		(start 374.151144 -126.732284)
		(end 374.151144 -127.267462)
		(width 0.0889)
		(layer "F.Cu")
		(net "A_EXTCLKP")
	)
	(segment
		(start 375.9327 -124.079)
		(end 375.7549 -124.2568)
		(width 0.0889)
		(layer "F.Cu")
		(net "A_EXTCLKP")
	)
	(segment
		(start 373.55272 -128.2954)
		(end 370.967 -128.2954)
		(width 0.1016)
		(layer "F.Cu")
		(net "A_EXTCLKP")
	)
	(segment
		(start 376.049794 -123.7107)
		(end 375.9327 -123.827794)
		(width 0.0889)
		(layer "F.Cu")
		(net "A_EXTCLKP")
	)
	(segment
		(start 376.1867 -123.7107)
		(end 376.049794 -123.7107)
		(width 0.0889)
		(layer "F.Cu")
		(net "A_EXTCLKP")
	)
	(segment
		(start 375.92 -123.571)
		(end 375.7422 -123.7488)
		(width 0.0889)
		(layer "F.Cu")
		(net "A_EXTCLKN")
	)
	(segment
		(start 374.526048 -124.916692)
		(end 374.456452 -124.945394)
		(width 0.0889)
		(layer "F.Cu")
		(net "A_EXTCLKN")
	)
	(segment
		(start 373.5451 -127.871728)
		(end 373.426228 -127.9906)
		(width 0.1016)
		(layer "F.Cu")
		(net "A_EXTCLKN")
	)
	(segment
		(start 373.94642 -125.838204)
		(end 373.94642 -126.195582)
		(width 0.0889)
		(layer "F.Cu")
		(net "A_EXTCLKN")
	)
	(segment
		(start 373.903494 -127.324612)
		(end 373.903494 -127.513334)
		(width 0.127)
		(layer "F.Cu")
		(net "A_EXTCLKN")
	)
	(segment
		(start 375.233184 -124.33427)
		(end 375.0564 -124.511054)
		(width 0.0889)
		(layer "F.Cu")
		(net "A_EXTCLKN")
	)
	(segment
		(start 375.7422 -123.7488)
		(end 375.7422 -124.000006)
		(width 0.0889)
		(layer "F.Cu")
		(net "A_EXTCLKN")
	)
	(segment
		(start 375.0564 -124.6759)
		(end 374.815608 -124.916692)
		(width 0.0889)
		(layer "F.Cu")
		(net "A_EXTCLKN")
	)
	(segment
		(start 374.456452 -124.945394)
		(end 374.217184 -125.184662)
		(width 0.0889)
		(layer "F.Cu")
		(net "A_EXTCLKN")
	)
	(segment
		(start 375.92 -123.3551)
		(end 375.92 -123.571)
		(width 0.0889)
		(layer "F.Cu")
		(net "A_EXTCLKN")
	)
	(segment
		(start 373.94642 -126.195582)
		(end 373.960644 -126.209806)
		(width 0.0889)
		(layer "F.Cu")
		(net "A_EXTCLKN")
	)
	(segment
		(start 375.0564 -124.511054)
		(end 375.0564 -124.6759)
		(width 0.0889)
		(layer "F.Cu")
		(net "A_EXTCLKN")
	)
	(segment
		(start 375.7422 -124.000006)
		(end 375.531634 -124.210572)
		(width 0.0889)
		(layer "F.Cu")
		(net "A_EXTCLKN")
	)
	(segment
		(start 374.815608 -124.916692)
		(end 374.526048 -124.916692)
		(width 0.0889)
		(layer "F.Cu")
		(net "A_EXTCLKN")
	)
	(segment
		(start 373.426228 -127.9906)
		(end 370.967 -127.9906)
		(width 0.1016)
		(layer "F.Cu")
		(net "A_EXTCLKN")
	)
	(segment
		(start 375.531634 -124.210572)
		(end 375.233184 -124.33427)
		(width 0.0889)
		(layer "F.Cu")
		(net "A_EXTCLKN")
	)
	(segment
		(start 373.960644 -126.209806)
		(end 373.960644 -127.267462)
		(width 0.0889)
		(layer "F.Cu")
		(net "A_EXTCLKN")
	)
	(segment
		(start 373.960644 -127.267462)
		(end 373.903494 -127.324612)
		(width 0.0889)
		(layer "F.Cu")
		(net "A_EXTCLKN")
	)
	(segment
		(start 374.217184 -125.184662)
		(end 373.94642 -125.838204)
		(width 0.0889)
		(layer "F.Cu")
		(net "A_EXTCLKN")
	)
	(segment
		(start 370.967 -127.9906)
		(end 370.7384 -127.762)
		(width 0.1016)
		(layer "F.Cu")
		(net "A_EXTCLKN")
	)
	(segment
		(start 373.903494 -127.513334)
		(end 373.5451 -127.871728)
		(width 0.127)
		(layer "F.Cu")
		(net "A_EXTCLKN")
	)
	(segment
		(start 481.500942 -38.5572)
		(end 481.500942 -39.5986)
		(width 0.254)
		(layer "F.Cu")
		(net "P3V3_STBY_P1V5_LAN_I210")
	)
	(via
		(at 481.500942 -38.5572)
		(size 0.508)
		(drill 0.254)
		(layers "F.Cu" "B.Cu")
		(net "P3V3_STBY_P1V5_LAN_I210")
	)
	(via
		(at 483.20198 -37.338)
		(size 0.6604)
		(drill 0.3302)
		(layers "F.Cu" "B.Cu")
		(net "P3V3_STBY_P1V5_LAN_I210")
	)
	(segment
		(start 480.857814 -37.9222)
		(end 481.492814 -38.5572)
		(width 0.254)
		(layer "B.Cu")
		(net "P3V3_STBY_P1V5_LAN_I210")
	)
	(segment
		(start 482.808534 -37.338)
		(end 483.20198 -37.338)
		(width 0.254)
		(layer "B.Cu")
		(net "P3V3_STBY_P1V5_LAN_I210")
	)
	(segment
		(start 482.15931 -37.987224)
		(end 482.808534 -37.338)
		(width 0.254)
		(layer "B.Cu")
		(net "P3V3_STBY_P1V5_LAN_I210")
	)
	(segment
		(start 482.15931 -38.302946)
		(end 482.15931 -37.987224)
		(width 0.254)
		(layer "B.Cu")
		(net "P3V3_STBY_P1V5_LAN_I210")
	)
	(segment
		(start 478.1169 -37.9222)
		(end 480.857814 -37.9222)
		(width 0.254)
		(layer "B.Cu")
		(net "P3V3_STBY_P1V5_LAN_I210")
	)
	(segment
		(start 481.500942 -38.5572)
		(end 481.905056 -38.5572)
		(width 0.254)
		(layer "B.Cu")
		(net "P3V3_STBY_P1V5_LAN_I210")
	)
	(segment
		(start 477.8121 -36.2712)
		(end 477.8121 -37.5412)
		(width 0.254)
		(layer "B.Cu")
		(net "P3V3_STBY_P1V5_LAN_I210")
	)
	(segment
		(start 481.905056 -38.5572)
		(end 482.15931 -38.302946)
		(width 0.254)
		(layer "B.Cu")
		(net "P3V3_STBY_P1V5_LAN_I210")
	)
	(segment
		(start 481.492814 -38.5572)
		(end 481.500942 -38.5572)
		(width 0.254)
		(layer "B.Cu")
		(net "P3V3_STBY_P1V5_LAN_I210")
	)
	(segment
		(start 477.8121 -37.5412)
		(end 478.1169 -37.9222)
		(width 0.254)
		(layer "B.Cu")
		(net "P3V3_STBY_P1V5_LAN_I210")
	)
	(segment
		(start 484.001064 -38.868096)
		(end 484.00716 -38.862)
		(width 0.3048)
		(layer "F.Cu")
		(net "P1V5_LAN_I210")
	)
	(segment
		(start 484.001064 -39.5986)
		(end 484.001064 -38.868096)
		(width 0.3048)
		(layer "F.Cu")
		(net "P1V5_LAN_I210")
	)
	(via
		(at 484.00716 -38.862)
		(size 0.508)
		(drill 0.254)
		(layers "F.Cu" "B.Cu")
		(net "P1V5_LAN_I210")
	)
	(via
		(at 482.9556 -40.9448)
		(size 0.6604)
		(drill 0.3302)
		(layers "F.Cu" "B.Cu")
		(net "P1V5_LAN_I210")
	)
	(segment
		(start 484.00716 -38.862)
		(end 484.00716 -39.61384)
		(width 0.254)
		(layer "B.Cu")
		(net "P1V5_LAN_I210")
	)
	(segment
		(start 482.9556 -39.8399)
		(end 482.9556 -40.9448)
		(width 0.254)
		(layer "B.Cu")
		(net "P1V5_LAN_I210")
	)
	(segment
		(start 483.7811 -39.8399)
		(end 482.9556 -39.8399)
		(width 0.254)
		(layer "B.Cu")
		(net "P1V5_LAN_I210")
	)
	(segment
		(start 484.00716 -39.61384)
		(end 483.7811 -39.8399)
		(width 0.254)
		(layer "B.Cu")
		(net "P1V5_LAN_I210")
	)
	(segment
		(start 479.8822 -45.217334)
		(end 479.318066 -45.217334)
		(width 0.254)
		(layer "F.Cu")
		(net "P0V9_LAN_I210")
	)
	(segment
		(start 479.318066 -45.217334)
		(end 479.1456 -45.3898)
		(width 0.254)
		(layer "F.Cu")
		(net "P0V9_LAN_I210")
	)
	(via
		(at 479.1456 -45.3898)
		(size 0.508)
		(drill 0.254)
		(layers "F.Cu" "B.Cu")
		(net "P0V9_LAN_I210")
	)
	(segment
		(start 480.2505 -46.5582)
		(end 479.7679 -46.5582)
		(width 0.508)
		(layer "B.Cu")
		(net "P0V9_LAN_I210")
	)
	(segment
		(start 479.7679 -46.5582)
		(end 479.1456 -45.9359)
		(width 0.508)
		(layer "B.Cu")
		(net "P0V9_LAN_I210")
	)
	(segment
		(start 479.1456 -45.9359)
		(end 479.1456 -45.3898)
		(width 0.508)
		(layer "B.Cu")
		(net "P0V9_LAN_I210")
	)
	(segment
		(start 0.199898 -34.058098)
		(end 0.199898 -33.710118)
		(width 0.10795)
		(layer "F.Cu")
		(net "FAN_TACH0_R")
	)
	(segment
		(start 12.450318 -87.378286)
		(end 11.961114 -87.378286)
		(width 0.10795)
		(layer "F.Cu")
		(net "FAN_TACH0_R")
	)
	(segment
		(start 11.961114 -87.378286)
		(end 10.668 -88.6714)
		(width 0.10795)
		(layer "F.Cu")
		(net "FAN_TACH0_R")
	)
	(segment
		(start 10.593832 -40.005)
		(end 9.933686 -39.344854)
		(width 0.10795)
		(layer "F.Cu")
		(net "FAN_TACH0_R")
	)
	(segment
		(start 10.668 -88.6714)
		(end 10.668 -99.3394)
		(width 0.10795)
		(layer "F.Cu")
		(net "FAN_TACH0_R")
	)
	(segment
		(start 9.933686 -37.261038)
		(end 7.539228 -34.86658)
		(width 0.10795)
		(layer "F.Cu")
		(net "FAN_TACH0_R")
	)
	(segment
		(start 12.2682 -40.005)
		(end 10.593832 -40.005)
		(width 0.10795)
		(layer "F.Cu")
		(net "FAN_TACH0_R")
	)
	(segment
		(start 9.933686 -39.344854)
		(end 9.933686 -37.261038)
		(width 0.10795)
		(layer "F.Cu")
		(net "FAN_TACH0_R")
	)
	(segment
		(start 10.668 -99.3394)
		(end 12.446 -101.1174)
		(width 0.10795)
		(layer "F.Cu")
		(net "FAN_TACH0_R")
	)
	(segment
		(start 7.539228 -34.86658)
		(end 1.00838 -34.86658)
		(width 0.10795)
		(layer "F.Cu")
		(net "FAN_TACH0_R")
	)
	(segment
		(start 1.00838 -34.86658)
		(end 0.199898 -34.058098)
		(width 0.10795)
		(layer "F.Cu")
		(net "FAN_TACH0_R")
	)
	(via
		(at 12.450318 -87.378286)
		(size 0.508)
		(drill 0.254)
		(layers "F.Cu" "B.Cu")
		(net "FAN_TACH0_R")
	)
	(via
		(at 9.933686 -39.344854)
		(size 0.508)
		(drill 0.254)
		(layers "F.Cu" "B.Cu")
		(net "FAN_TACH0_R")
	)
	(segment
		(start 11.7856 -84.31022)
		(end 12.635992 -83.459828)
		(width 0.089408)
		(layer "In4.Cu")
		(net "FAN_TACH0_R")
	)
	(segment
		(start 11.810238 -81.253838)
		(end 11.810238 -79.274924)
		(width 0.089408)
		(layer "In4.Cu")
		(net "FAN_TACH0_R")
	)
	(segment
		(start 11.91387 -71.695564)
		(end 12.36472 -71.244714)
		(width 0.089408)
		(layer "In4.Cu")
		(net "FAN_TACH0_R")
	)
	(segment
		(start 12.635992 -83.459828)
		(end 12.635992 -82.079592)
		(width 0.089408)
		(layer "In4.Cu")
		(net "FAN_TACH0_R")
	)
	(segment
		(start 12.635992 -82.079592)
		(end 11.810238 -81.253838)
		(width 0.089408)
		(layer "In4.Cu")
		(net "FAN_TACH0_R")
	)
	(segment
		(start 11.810238 -79.274924)
		(end 11.91387 -79.171292)
		(width 0.089408)
		(layer "In4.Cu")
		(net "FAN_TACH0_R")
	)
	(segment
		(start 12.36472 -68.142612)
		(end 11.74369 -67.521582)
		(width 0.089408)
		(layer "In4.Cu")
		(net "FAN_TACH0_R")
	)
	(segment
		(start 13.113004 -40.948356)
		(end 12.15517 -40.948356)
		(width 0.089408)
		(layer "In4.Cu")
		(net "FAN_TACH0_R")
	)
	(segment
		(start 11.7856 -86.8172)
		(end 11.7856 -84.31022)
		(width 0.089408)
		(layer "In4.Cu")
		(net "FAN_TACH0_R")
	)
	(segment
		(start 12.346686 -87.378286)
		(end 11.7856 -86.8172)
		(width 0.089408)
		(layer "In4.Cu")
		(net "FAN_TACH0_R")
	)
	(segment
		(start 11.74369 -67.521582)
		(end 11.74369 -49.771046)
		(width 0.089408)
		(layer "In4.Cu")
		(net "FAN_TACH0_R")
	)
	(segment
		(start 12.450318 -87.378286)
		(end 12.346686 -87.378286)
		(width 0.089408)
		(layer "In4.Cu")
		(net "FAN_TACH0_R")
	)
	(segment
		(start 10.551668 -39.344854)
		(end 9.933686 -39.344854)
		(width 0.089408)
		(layer "In4.Cu")
		(net "FAN_TACH0_R")
	)
	(segment
		(start 12.36472 -71.244714)
		(end 12.36472 -68.142612)
		(width 0.089408)
		(layer "In4.Cu")
		(net "FAN_TACH0_R")
	)
	(segment
		(start 12.15517 -40.948356)
		(end 10.551668 -39.344854)
		(width 0.089408)
		(layer "In4.Cu")
		(net "FAN_TACH0_R")
	)
	(segment
		(start 13.873734 -47.641002)
		(end 13.873734 -41.709086)
		(width 0.089408)
		(layer "In4.Cu")
		(net "FAN_TACH0_R")
	)
	(segment
		(start 11.74369 -49.771046)
		(end 13.873734 -47.641002)
		(width 0.089408)
		(layer "In4.Cu")
		(net "FAN_TACH0_R")
	)
	(segment
		(start 11.91387 -79.171292)
		(end 11.91387 -71.695564)
		(width 0.089408)
		(layer "In4.Cu")
		(net "FAN_TACH0_R")
	)
	(segment
		(start 13.873734 -41.709086)
		(end 13.113004 -40.948356)
		(width 0.089408)
		(layer "In4.Cu")
		(net "FAN_TACH0_R")
	)
	(segment
		(start 407.412698 -55.118)
		(end 409.148026 -56.853328)
		(width 0.10795)
		(layer "F.Cu")
		(net "SMB_SENSOR_STBY_LVC3_SDA_R2")
	)
	(segment
		(start 409.14828 -56.853582)
		(end 409.376626 -57.081928)
		(width 0.10795)
		(layer "F.Cu")
		(net "SMB_SENSOR_STBY_LVC3_SDA_R2")
	)
	(segment
		(start 410.041344 -57.081928)
		(end 410.226256 -57.26684)
		(width 0.10795)
		(layer "F.Cu")
		(net "SMB_SENSOR_STBY_LVC3_SDA_R2")
	)
	(segment
		(start 406.1968 -55.118)
		(end 407.412698 -55.118)
		(width 0.10795)
		(layer "F.Cu")
		(net "SMB_SENSOR_STBY_LVC3_SDA_R2")
	)
	(segment
		(start 409.148026 -56.853328)
		(end 409.14828 -56.853328)
		(width 0.10795)
		(layer "F.Cu")
		(net "SMB_SENSOR_STBY_LVC3_SDA_R2")
	)
	(segment
		(start 409.376626 -57.081928)
		(end 410.041344 -57.081928)
		(width 0.10795)
		(layer "F.Cu")
		(net "SMB_SENSOR_STBY_LVC3_SDA_R2")
	)
	(segment
		(start 409.14828 -56.853328)
		(end 409.14828 -56.853582)
		(width 0.10795)
		(layer "F.Cu")
		(net "SMB_SENSOR_STBY_LVC3_SDA_R2")
	)
	(via
		(at 409.14828 -56.853328)
		(size 0.508)
		(drill 0.254)
		(layers "F.Cu" "B.Cu")
		(net "SMB_SENSOR_STBY_LVC3_SDA_R2")
	)
	(segment
		(start 407.19121 -54.5084)
		(end 409.499308 -56.816498)
		(width 0.10795)
		(layer "F.Cu")
		(net "SMB_SENSOR_STBY_LVC3_SCL_R2")
	)
	(segment
		(start 406.1968 -53.848)
		(end 406.1968 -54.3941)
		(width 0.10795)
		(layer "F.Cu")
		(net "SMB_SENSOR_STBY_LVC3_SCL_R2")
	)
	(segment
		(start 409.914598 -56.816498)
		(end 410.226256 -56.50484)
		(width 0.10795)
		(layer "F.Cu")
		(net "SMB_SENSOR_STBY_LVC3_SCL_R2")
	)
	(segment
		(start 406.3111 -54.5084)
		(end 407.19121 -54.5084)
		(width 0.10795)
		(layer "F.Cu")
		(net "SMB_SENSOR_STBY_LVC3_SCL_R2")
	)
	(segment
		(start 406.1968 -54.3941)
		(end 406.3111 -54.5084)
		(width 0.10795)
		(layer "F.Cu")
		(net "SMB_SENSOR_STBY_LVC3_SCL_R2")
	)
	(segment
		(start 409.499308 -56.816498)
		(end 409.914598 -56.816498)
		(width 0.10795)
		(layer "F.Cu")
		(net "SMB_SENSOR_STBY_LVC3_SCL_R2")
	)
	(segment
		(start 172.280072 -74.172572)
		(end 172.280072 -73.839324)
		(width 0.10795)
		(layer "F.Cu")
		(net "SMB_HOST_STBY_LVC3_SDA_R2")
	)
	(segment
		(start 172.878496 -74.770996)
		(end 172.280072 -74.172572)
		(width 0.10795)
		(layer "F.Cu")
		(net "SMB_HOST_STBY_LVC3_SDA_R2")
	)
	(segment
		(start 172.50283 -75.43165)
		(end 172.878496 -75.055984)
		(width 0.10795)
		(layer "F.Cu")
		(net "SMB_HOST_STBY_LVC3_SDA_R2")
	)
	(segment
		(start 172.05833 -75.43165)
		(end 172.50283 -75.43165)
		(width 0.10795)
		(layer "F.Cu")
		(net "SMB_HOST_STBY_LVC3_SDA_R2")
	)
	(segment
		(start 171.173394 -76.593192)
		(end 171.173394 -76.316586)
		(width 0.10795)
		(layer "F.Cu")
		(net "SMB_HOST_STBY_LVC3_SDA_R2")
	)
	(segment
		(start 172.878496 -75.055984)
		(end 172.878496 -74.972672)
		(width 0.10795)
		(layer "F.Cu")
		(net "SMB_HOST_STBY_LVC3_SDA_R2")
	)
	(segment
		(start 172.878496 -74.972672)
		(end 172.878496 -74.770996)
		(width 0.10795)
		(layer "F.Cu")
		(net "SMB_HOST_STBY_LVC3_SDA_R2")
	)
	(segment
		(start 171.173394 -76.316586)
		(end 172.05833 -75.43165)
		(width 0.10795)
		(layer "F.Cu")
		(net "SMB_HOST_STBY_LVC3_SDA_R2")
	)
	(segment
		(start 174.058072 -72.539352)
		(end 173.523148 -72.539352)
		(width 0.10795)
		(layer "F.Cu")
		(net "SMB_HOST_STBY_LVC3_SCL_R2")
	)
	(segment
		(start 173.523148 -72.539352)
		(end 173.228 -72.8345)
		(width 0.10795)
		(layer "F.Cu")
		(net "SMB_HOST_STBY_LVC3_SCL_R2")
	)
	(segment
		(start 173.228 -72.8345)
		(end 173.228 -74.18832)
		(width 0.10795)
		(layer "F.Cu")
		(net "SMB_HOST_STBY_LVC3_SCL_R2")
	)
	(segment
		(start 173.750224 -75.004168)
		(end 172.996352 -75.75804)
		(width 0.10795)
		(layer "F.Cu")
		(net "SMB_HOST_STBY_LVC3_SCL_R2")
	)
	(segment
		(start 172.05706 -75.75804)
		(end 171.67352 -76.14158)
		(width 0.10795)
		(layer "F.Cu")
		(net "SMB_HOST_STBY_LVC3_SCL_R2")
	)
	(segment
		(start 173.750224 -74.710544)
		(end 173.750224 -75.004168)
		(width 0.10795)
		(layer "F.Cu")
		(net "SMB_HOST_STBY_LVC3_SCL_R2")
	)
	(segment
		(start 173.228 -74.18832)
		(end 173.750224 -74.710544)
		(width 0.10795)
		(layer "F.Cu")
		(net "SMB_HOST_STBY_LVC3_SCL_R2")
	)
	(segment
		(start 171.67352 -76.14158)
		(end 171.67352 -76.593192)
		(width 0.10795)
		(layer "F.Cu")
		(net "SMB_HOST_STBY_LVC3_SCL_R2")
	)
	(segment
		(start 172.996352 -75.75804)
		(end 172.05706 -75.75804)
		(width 0.10795)
		(layer "F.Cu")
		(net "SMB_HOST_STBY_LVC3_SCL_R2")
	)
	(via
		(at 455.168 -29.9974)
		(size 0.6604)
		(drill 0.3302)
		(layers "F.Cu" "B.Cu")
		(net "RST_BMC_SRST_R2_N")
	)
	(segment
		(start 455.200258 -31.237174)
		(end 455.200258 -31.999174)
		(width 0.10795)
		(layer "B.Cu")
		(net "RST_BMC_SRST_R2_N")
	)
	(segment
		(start 455.200258 -32.442658)
		(end 455.398632 -32.641032)
		(width 0.10795)
		(layer "B.Cu")
		(net "RST_BMC_SRST_R2_N")
	)
	(segment
		(start 455.398632 -33.264856)
		(end 455.52995 -33.396174)
		(width 0.10795)
		(layer "B.Cu")
		(net "RST_BMC_SRST_R2_N")
	)
	(segment
		(start 455.566526 -31.237174)
		(end 455.200258 -31.237174)
		(width 0.10795)
		(layer "B.Cu")
		(net "RST_BMC_SRST_R2_N")
	)
	(segment
		(start 455.630026 -31.173674)
		(end 455.566526 -31.237174)
		(width 0.10795)
		(layer "B.Cu")
		(net "RST_BMC_SRST_R2_N")
	)
	(segment
		(start 455.52995 -33.396174)
		(end 456.040744 -33.396174)
		(width 0.10795)
		(layer "B.Cu")
		(net "RST_BMC_SRST_R2_N")
	)
	(segment
		(start 455.200258 -31.999174)
		(end 455.200258 -32.442658)
		(width 0.10795)
		(layer "B.Cu")
		(net "RST_BMC_SRST_R2_N")
	)
	(segment
		(start 455.200258 -31.237174)
		(end 455.200258 -30.029658)
		(width 0.10795)
		(layer "B.Cu")
		(net "RST_BMC_SRST_R2_N")
	)
	(segment
		(start 456.025758 -31.173674)
		(end 455.630026 -31.173674)
		(width 0.10795)
		(layer "B.Cu")
		(net "RST_BMC_SRST_R2_N")
	)
	(segment
		(start 455.398632 -32.641032)
		(end 455.398632 -33.264856)
		(width 0.10795)
		(layer "B.Cu")
		(net "RST_BMC_SRST_R2_N")
	)
	(segment
		(start 455.200258 -30.029658)
		(end 455.168 -29.9974)
		(width 0.10795)
		(layer "B.Cu")
		(net "RST_BMC_SRST_R2_N")
	)
	(segment
		(start 419.989 -79.561944)
		(end 419.989 -79.254604)
		(width 0.10795)
		(layer "F.Cu")
		(net "IRQ_FORCE_NM_THROTTLE_R_N")
	)
	(segment
		(start 418.7571 -88.5825)
		(end 417.9951 -88.5825)
		(width 0.10795)
		(layer "F.Cu")
		(net "IRQ_FORCE_NM_THROTTLE_R_N")
	)
	(segment
		(start 421.259 -79.146654)
		(end 423.345102 -81.232756)
		(width 0.10795)
		(layer "F.Cu")
		(net "IRQ_FORCE_NM_THROTTLE_R_N")
	)
	(segment
		(start 420.09695 -79.146654)
		(end 421.259 -79.146654)
		(width 0.10795)
		(layer "F.Cu")
		(net "IRQ_FORCE_NM_THROTTLE_R_N")
	)
	(segment
		(start 419.989 -79.254604)
		(end 420.09695 -79.146654)
		(width 0.10795)
		(layer "F.Cu")
		(net "IRQ_FORCE_NM_THROTTLE_R_N")
	)
	(segment
		(start 422.548304 -88.011)
		(end 420.5224 -88.011)
		(width 0.10795)
		(layer "F.Cu")
		(net "IRQ_FORCE_NM_THROTTLE_R_N")
	)
	(segment
		(start 419.5953 -88.011)
		(end 420.5224 -88.011)
		(width 0.10795)
		(layer "F.Cu")
		(net "IRQ_FORCE_NM_THROTTLE_R_N")
	)
	(segment
		(start 418.973 -80.913986)
		(end 418.973 -80.577944)
		(width 0.10795)
		(layer "F.Cu")
		(net "IRQ_FORCE_NM_THROTTLE_R_N")
	)
	(segment
		(start 418.973 -80.577944)
		(end 419.989 -79.561944)
		(width 0.10795)
		(layer "F.Cu")
		(net "IRQ_FORCE_NM_THROTTLE_R_N")
	)
	(segment
		(start 418.7571 -88.5825)
		(end 419.0238 -88.5825)
		(width 0.10795)
		(layer "F.Cu")
		(net "IRQ_FORCE_NM_THROTTLE_R_N")
	)
	(segment
		(start 423.345102 -81.232756)
		(end 423.345102 -87.214202)
		(width 0.10795)
		(layer "F.Cu")
		(net "IRQ_FORCE_NM_THROTTLE_R_N")
	)
	(segment
		(start 423.345102 -87.214202)
		(end 422.548304 -88.011)
		(width 0.10795)
		(layer "F.Cu")
		(net "IRQ_FORCE_NM_THROTTLE_R_N")
	)
	(segment
		(start 419.0238 -88.5825)
		(end 419.5953 -88.011)
		(width 0.10795)
		(layer "F.Cu")
		(net "IRQ_FORCE_NM_THROTTLE_R_N")
	)
	(via
		(at 420.5224 -88.011)
		(size 0.762)
		(drill 0.381)
		(layers "F.Cu" "B.Cu")
		(net "IRQ_FORCE_NM_THROTTLE_R_N")
	)
	(via
		(at 397.130524 -36.317428)
		(size 0.6604)
		(drill 0.3302)
		(layers "F.Cu" "B.Cu")
		(net "FM_PCH_PWRBTN_R_N")
	)
	(segment
		(start 397.451834 -31.787338)
		(end 397.100552 -31.436056)
		(width 0.10795)
		(layer "B.Cu")
		(net "FM_PCH_PWRBTN_R_N")
	)
	(segment
		(start 396.822676 -29.244798)
		(end 396.4432 -29.244798)
		(width 0.10795)
		(layer "B.Cu")
		(net "FM_PCH_PWRBTN_R_N")
	)
	(segment
		(start 397.130524 -36.317428)
		(end 396.879572 -36.317428)
		(width 0.10795)
		(layer "B.Cu")
		(net "FM_PCH_PWRBTN_R_N")
	)
	(segment
		(start 397.172688 -32.56915)
		(end 397.451834 -32.290004)
		(width 0.10795)
		(layer "B.Cu")
		(net "FM_PCH_PWRBTN_R_N")
	)
	(segment
		(start 395.226032 -27.27452)
		(end 394.843 -27.27452)
		(width 0.10795)
		(layer "B.Cu")
		(net "FM_PCH_PWRBTN_R_N")
	)
	(segment
		(start 397.129508 -29.845)
		(end 397.129508 -29.55163)
		(width 0.10795)
		(layer "B.Cu")
		(net "FM_PCH_PWRBTN_R_N")
	)
	(segment
		(start 397.172688 -36.275264)
		(end 397.172688 -32.56915)
		(width 0.10795)
		(layer "B.Cu")
		(net "FM_PCH_PWRBTN_R_N")
	)
	(segment
		(start 397.129508 -29.845)
		(end 397.129508 -30.172152)
		(width 0.10795)
		(layer "B.Cu")
		(net "FM_PCH_PWRBTN_R_N")
	)
	(segment
		(start 397.451834 -32.290004)
		(end 397.451834 -31.787338)
		(width 0.10795)
		(layer "B.Cu")
		(net "FM_PCH_PWRBTN_R_N")
	)
	(segment
		(start 397.100552 -30.861)
		(end 396.867126 -30.627574)
		(width 0.10795)
		(layer "B.Cu")
		(net "FM_PCH_PWRBTN_R_N")
	)
	(segment
		(start 396.879572 -36.317428)
		(end 396.1384 -37.0586)
		(width 0.10795)
		(layer "B.Cu")
		(net "FM_PCH_PWRBTN_R_N")
	)
	(segment
		(start 397.100552 -31.436056)
		(end 397.100552 -30.861)
		(width 0.10795)
		(layer "B.Cu")
		(net "FM_PCH_PWRBTN_R_N")
	)
	(segment
		(start 396.040102 -28.08859)
		(end 395.226032 -27.27452)
		(width 0.10795)
		(layer "B.Cu")
		(net "FM_PCH_PWRBTN_R_N")
	)
	(segment
		(start 396.4432 -29.244798)
		(end 396.040102 -28.8417)
		(width 0.10795)
		(layer "B.Cu")
		(net "FM_PCH_PWRBTN_R_N")
	)
	(segment
		(start 397.129508 -30.172152)
		(end 396.674086 -30.627574)
		(width 0.10795)
		(layer "B.Cu")
		(net "FM_PCH_PWRBTN_R_N")
	)
	(segment
		(start 397.129508 -29.55163)
		(end 396.822676 -29.244798)
		(width 0.10795)
		(layer "B.Cu")
		(net "FM_PCH_PWRBTN_R_N")
	)
	(segment
		(start 396.1384 -37.0586)
		(end 395.61008 -37.0586)
		(width 0.10795)
		(layer "B.Cu")
		(net "FM_PCH_PWRBTN_R_N")
	)
	(segment
		(start 396.040102 -28.8417)
		(end 396.040102 -28.08859)
		(width 0.10795)
		(layer "B.Cu")
		(net "FM_PCH_PWRBTN_R_N")
	)
	(segment
		(start 396.867126 -30.627574)
		(end 396.674086 -30.627574)
		(width 0.10795)
		(layer "B.Cu")
		(net "FM_PCH_PWRBTN_R_N")
	)
	(segment
		(start 397.130524 -36.317428)
		(end 397.172688 -36.275264)
		(width 0.10795)
		(layer "B.Cu")
		(net "FM_PCH_PWRBTN_R_N")
	)
	(segment
		(start 161.9504 -77.596746)
		(end 162.077146 -77.47)
		(width 0.1143)
		(layer "F.Cu")
		(net "CLK_100M_CPU1_RC_REFCLK1_DP")
	)
	(segment
		(start 162.179 -77.47)
		(end 162.687 -77.978)
		(width 0.1143)
		(layer "F.Cu")
		(net "CLK_100M_CPU1_RC_REFCLK1_DP")
	)
	(segment
		(start 122.217688 -72.744584)
		(end 121.646188 -72.744584)
		(width 0.1143)
		(layer "F.Cu")
		(net "CLK_100M_CPU1_RC_REFCLK1_DP")
	)
	(segment
		(start 161.9504 -77.978)
		(end 161.9504 -77.596746)
		(width 0.1143)
		(layer "F.Cu")
		(net "CLK_100M_CPU1_RC_REFCLK1_DP")
	)
	(segment
		(start 162.077146 -77.47)
		(end 162.179 -77.47)
		(width 0.1143)
		(layer "F.Cu")
		(net "CLK_100M_CPU1_RC_REFCLK1_DP")
	)
	(via
		(at 161.9504 -77.978)
		(size 0.508)
		(drill 0.254)
		(layers "F.Cu" "B.Cu")
		(net "CLK_100M_CPU1_RC_REFCLK1_DP")
	)
	(via
		(at 122.217688 -72.744584)
		(size 0.508)
		(drill 0.254)
		(layers "F.Cu" "B.Cu")
		(net "CLK_100M_CPU1_RC_REFCLK1_DP")
	)
	(segment
		(start 161.9504 -77.582522)
		(end 161.9504 -77.978)
		(width 0.1143)
		(layer "B.Cu")
		(net "CLK_100M_CPU1_RC_REFCLK1_DP")
	)
	(segment
		(start 162.037522 -77.4954)
		(end 161.9504 -77.582522)
		(width 0.1143)
		(layer "B.Cu")
		(net "CLK_100M_CPU1_RC_REFCLK1_DP")
	)
	(segment
		(start 162.7886 -77.978)
		(end 162.306 -77.4954)
		(width 0.1143)
		(layer "B.Cu")
		(net "CLK_100M_CPU1_RC_REFCLK1_DP")
	)
	(segment
		(start 162.306 -77.4954)
		(end 162.037522 -77.4954)
		(width 0.1143)
		(layer "B.Cu")
		(net "CLK_100M_CPU1_RC_REFCLK1_DP")
	)
	(segment
		(start 135.11022 -71.849488)
		(end 135.080248 -71.849488)
		(width 0.0889)
		(layer "In4.Cu")
		(net "CLK_100M_CPU1_RC_REFCLK1_DP")
	)
	(segment
		(start 144.455388 -82.46491)
		(end 144.157192 -82.166714)
		(width 0.1143)
		(layer "In4.Cu")
		(net "CLK_100M_CPU1_RC_REFCLK1_DP")
	)
	(segment
		(start 145.275046 -79.73441)
		(end 157.426914 -79.73441)
		(width 0.1143)
		(layer "In4.Cu")
		(net "CLK_100M_CPU1_RC_REFCLK1_DP")
	)
	(segment
		(start 140.892276 -73.028556)
		(end 140.703808 -72.840088)
		(width 0.0889)
		(layer "In4.Cu")
		(net "CLK_100M_CPU1_RC_REFCLK1_DP")
	)
	(segment
		(start 157.712156 -80.019652)
		(end 157.712156 -80.530446)
		(width 0.1143)
		(layer "In4.Cu")
		(net "CLK_100M_CPU1_RC_REFCLK1_DP")
	)
	(segment
		(start 143.91767 -77.715872)
		(end 143.91767 -77.99451)
		(width 0.1143)
		(layer "In4.Cu")
		(net "CLK_100M_CPU1_RC_REFCLK1_DP")
	)
	(segment
		(start 157.712156 -80.530446)
		(end 157.403292 -80.83931)
		(width 0.1143)
		(layer "In4.Cu")
		(net "CLK_100M_CPU1_RC_REFCLK1_DP")
	)
	(segment
		(start 157.426914 -79.73441)
		(end 157.712156 -80.019652)
		(width 0.1143)
		(layer "In4.Cu")
		(net "CLK_100M_CPU1_RC_REFCLK1_DP")
	)
	(segment
		(start 142.838424 -74.974704)
		(end 141.206728 -73.343008)
		(width 0.0889)
		(layer "In4.Cu")
		(net "CLK_100M_CPU1_RC_REFCLK1_DP")
	)
	(segment
		(start 160.902904 -79.138018)
		(end 160.617662 -79.42326)
		(width 0.1143)
		(layer "In4.Cu")
		(net "CLK_100M_CPU1_RC_REFCLK1_DP")
	)
	(segment
		(start 142.749524 -76.083668)
		(end 142.838424 -75.994768)
		(width 0.0889)
		(layer "In4.Cu")
		(net "CLK_100M_CPU1_RC_REFCLK1_DP")
	)
	(segment
		(start 134.258304 -72.344534)
		(end 134.225538 -72.344534)
		(width 0.0889)
		(layer "In4.Cu")
		(net "CLK_100M_CPU1_RC_REFCLK1_DP")
	)
	(segment
		(start 160.902904 -77.60335)
		(end 160.902904 -79.138018)
		(width 0.1143)
		(layer "In4.Cu")
		(net "CLK_100M_CPU1_RC_REFCLK1_DP")
	)
	(segment
		(start 145.160746 -80.95361)
		(end 145.160746 -81.24571)
		(width 0.1143)
		(layer "In4.Cu")
		(net "CLK_100M_CPU1_RC_REFCLK1_DP")
	)
	(segment
		(start 156.113734 -77.58811)
		(end 144.045432 -77.58811)
		(width 0.1143)
		(layer "In4.Cu")
		(net "CLK_100M_CPU1_RC_REFCLK1_DP")
	)
	(segment
		(start 135.96493 -72.344534)
		(end 135.932164 -72.344534)
		(width 0.0889)
		(layer "In4.Cu")
		(net "CLK_100M_CPU1_RC_REFCLK1_DP")
	)
	(segment
		(start 122.217688 -72.40651)
		(end 122.217688 -72.744584)
		(width 0.0889)
		(layer "In4.Cu")
		(net "CLK_100M_CPU1_RC_REFCLK1_DP")
	)
	(segment
		(start 145.160746 -79.62011)
		(end 145.275046 -79.73441)
		(width 0.1143)
		(layer "In4.Cu")
		(net "CLK_100M_CPU1_RC_REFCLK1_DP")
	)
	(segment
		(start 155.70581 -81.36001)
		(end 156.011118 -81.665318)
		(width 0.1143)
		(layer "In4.Cu")
		(net "CLK_100M_CPU1_RC_REFCLK1_DP")
	)
	(segment
		(start 141.080998 -73.343008)
		(end 140.892276 -73.154286)
		(width 0.0889)
		(layer "In4.Cu")
		(net "CLK_100M_CPU1_RC_REFCLK1_DP")
	)
	(segment
		(start 161.8361 -77.48905)
		(end 161.017204 -77.48905)
		(width 0.1143)
		(layer "In4.Cu")
		(net "CLK_100M_CPU1_RC_REFCLK1_DP")
	)
	(segment
		(start 142.749524 -75.372468)
		(end 142.838424 -75.283568)
		(width 0.0889)
		(layer "In4.Cu")
		(net "CLK_100M_CPU1_RC_REFCLK1_DP")
	)
	(segment
		(start 157.403292 -80.83931)
		(end 145.275046 -80.83931)
		(width 0.1143)
		(layer "In4.Cu")
		(net "CLK_100M_CPU1_RC_REFCLK1_DP")
	)
	(segment
		(start 144.157192 -80.103472)
		(end 142.787624 -78.733904)
		(width 0.1143)
		(layer "In4.Cu")
		(net "CLK_100M_CPU1_RC_REFCLK1_DP")
	)
	(segment
		(start 145.275046 -81.36001)
		(end 155.70581 -81.36001)
		(width 0.1143)
		(layer "In4.Cu")
		(net "CLK_100M_CPU1_RC_REFCLK1_DP")
	)
	(segment
		(start 142.787624 -78.733904)
		(end 142.787624 -76.778866)
		(width 0.1143)
		(layer "In4.Cu")
		(net "CLK_100M_CPU1_RC_REFCLK1_DP")
	)
	(segment
		(start 160.617662 -79.42326)
		(end 157.948884 -79.42326)
		(width 0.1143)
		(layer "In4.Cu")
		(net "CLK_100M_CPU1_RC_REFCLK1_DP")
	)
	(segment
		(start 122.2756 -72.348598)
		(end 122.217688 -72.40651)
		(width 0.0889)
		(layer "In4.Cu")
		(net "CLK_100M_CPU1_RC_REFCLK1_DP")
	)
	(segment
		(start 156.01696 -78.9051)
		(end 155.70835 -79.21371)
		(width 0.1143)
		(layer "In4.Cu")
		(net "CLK_100M_CPU1_RC_REFCLK1_DP")
	)
	(segment
		(start 144.03197 -78.10881)
		(end 155.721558 -78.10881)
		(width 0.1143)
		(layer "In4.Cu")
		(net "CLK_100M_CPU1_RC_REFCLK1_DP")
	)
	(segment
		(start 161.9504 -77.60335)
		(end 161.8361 -77.48905)
		(width 0.1143)
		(layer "In4.Cu")
		(net "CLK_100M_CPU1_RC_REFCLK1_DP")
	)
	(segment
		(start 155.725876 -82.46491)
		(end 144.455388 -82.46491)
		(width 0.1143)
		(layer "In4.Cu")
		(net "CLK_100M_CPU1_RC_REFCLK1_DP")
	)
	(segment
		(start 156.011118 -81.665318)
		(end 156.011118 -82.179668)
		(width 0.1143)
		(layer "In4.Cu")
		(net "CLK_100M_CPU1_RC_REFCLK1_DP")
	)
	(segment
		(start 155.70835 -79.21371)
		(end 145.275046 -79.21371)
		(width 0.1143)
		(layer "In4.Cu")
		(net "CLK_100M_CPU1_RC_REFCLK1_DP")
	)
	(segment
		(start 142.838424 -76.439268)
		(end 142.749524 -76.350368)
		(width 0.0889)
		(layer "In4.Cu")
		(net "CLK_100M_CPU1_RC_REFCLK1_DP")
	)
	(segment
		(start 157.948884 -79.42326)
		(end 156.113734 -77.58811)
		(width 0.1143)
		(layer "In4.Cu")
		(net "CLK_100M_CPU1_RC_REFCLK1_DP")
	)
	(segment
		(start 155.721558 -78.10881)
		(end 156.01696 -78.404212)
		(width 0.1143)
		(layer "In4.Cu")
		(net "CLK_100M_CPU1_RC_REFCLK1_DP")
	)
	(segment
		(start 145.275046 -80.83931)
		(end 145.160746 -80.95361)
		(width 0.1143)
		(layer "In4.Cu")
		(net "CLK_100M_CPU1_RC_REFCLK1_DP")
	)
	(segment
		(start 143.91767 -77.99451)
		(end 144.03197 -78.10881)
		(width 0.1143)
		(layer "In4.Cu")
		(net "CLK_100M_CPU1_RC_REFCLK1_DP")
	)
	(segment
		(start 156.011118 -82.179668)
		(end 155.725876 -82.46491)
		(width 0.1143)
		(layer "In4.Cu")
		(net "CLK_100M_CPU1_RC_REFCLK1_DP")
	)
	(segment
		(start 144.157192 -82.166714)
		(end 144.157192 -80.103472)
		(width 0.1143)
		(layer "In4.Cu")
		(net "CLK_100M_CPU1_RC_REFCLK1_DP")
	)
	(segment
		(start 141.206728 -73.343008)
		(end 141.080998 -73.343008)
		(width 0.0889)
		(layer "In4.Cu")
		(net "CLK_100M_CPU1_RC_REFCLK1_DP")
	)
	(segment
		(start 132.179822 -72.533256)
		(end 132.173218 -72.544686)
		(width 0.0889)
		(layer "In4.Cu")
		(net "CLK_100M_CPU1_RC_REFCLK1_DP")
	)
	(segment
		(start 142.787624 -76.778866)
		(end 142.787624 -76.756768)
		(width 0.0889)
		(layer "In4.Cu")
		(net "CLK_100M_CPU1_RC_REFCLK1_DP")
	)
	(segment
		(start 156.01696 -78.404212)
		(end 156.01696 -78.9051)
		(width 0.1143)
		(layer "In4.Cu")
		(net "CLK_100M_CPU1_RC_REFCLK1_DP")
	)
	(segment
		(start 142.838424 -75.283568)
		(end 142.838424 -74.974704)
		(width 0.0889)
		(layer "In4.Cu")
		(net "CLK_100M_CPU1_RC_REFCLK1_DP")
	)
	(segment
		(start 145.160746 -79.32801)
		(end 145.160746 -79.62011)
		(width 0.1143)
		(layer "In4.Cu")
		(net "CLK_100M_CPU1_RC_REFCLK1_DP")
	)
	(segment
		(start 142.838424 -75.994768)
		(end 142.838424 -75.728068)
		(width 0.0889)
		(layer "In4.Cu")
		(net "CLK_100M_CPU1_RC_REFCLK1_DP")
	)
	(segment
		(start 161.9504 -77.978)
		(end 161.9504 -77.60335)
		(width 0.1143)
		(layer "In4.Cu")
		(net "CLK_100M_CPU1_RC_REFCLK1_DP")
	)
	(segment
		(start 142.749524 -75.639168)
		(end 142.749524 -75.372468)
		(width 0.0889)
		(layer "In4.Cu")
		(net "CLK_100M_CPU1_RC_REFCLK1_DP")
	)
	(segment
		(start 140.892276 -73.154286)
		(end 140.892276 -73.028556)
		(width 0.0889)
		(layer "In4.Cu")
		(net "CLK_100M_CPU1_RC_REFCLK1_DP")
	)
	(segment
		(start 142.787624 -76.756768)
		(end 142.838424 -76.705968)
		(width 0.0889)
		(layer "In4.Cu")
		(net "CLK_100M_CPU1_RC_REFCLK1_DP")
	)
	(segment
		(start 142.838424 -76.705968)
		(end 142.838424 -76.439268)
		(width 0.0889)
		(layer "In4.Cu")
		(net "CLK_100M_CPU1_RC_REFCLK1_DP")
	)
	(segment
		(start 142.749524 -76.350368)
		(end 142.749524 -76.083668)
		(width 0.0889)
		(layer "In4.Cu")
		(net "CLK_100M_CPU1_RC_REFCLK1_DP")
	)
	(segment
		(start 161.017204 -77.48905)
		(end 160.902904 -77.60335)
		(width 0.1143)
		(layer "In4.Cu")
		(net "CLK_100M_CPU1_RC_REFCLK1_DP")
	)
	(segment
		(start 144.045432 -77.58811)
		(end 143.91767 -77.715872)
		(width 0.1143)
		(layer "In4.Cu")
		(net "CLK_100M_CPU1_RC_REFCLK1_DP")
	)
	(segment
		(start 145.275046 -79.21371)
		(end 145.160746 -79.32801)
		(width 0.1143)
		(layer "In4.Cu")
		(net "CLK_100M_CPU1_RC_REFCLK1_DP")
	)
	(segment
		(start 142.838424 -75.728068)
		(end 142.749524 -75.639168)
		(width 0.0889)
		(layer "In4.Cu")
		(net "CLK_100M_CPU1_RC_REFCLK1_DP")
	)
	(segment
		(start 123.093988 -72.840088)
		(end 123.058428 -72.840088)
		(width 0.0889)
		(layer "In4.Cu")
		(net "CLK_100M_CPU1_RC_REFCLK1_DP")
	)
	(segment
		(start 140.703808 -72.840088)
		(end 140.228574 -72.840088)
		(width 0.0889)
		(layer "In4.Cu")
		(net "CLK_100M_CPU1_RC_REFCLK1_DP")
	)
	(segment
		(start 145.160746 -81.24571)
		(end 145.275046 -81.36001)
		(width 0.1143)
		(layer "In4.Cu")
		(net "CLK_100M_CPU1_RC_REFCLK1_DP")
	)
	(arc
		(start 135.080248 -71.849488)
		(mid 134.888606 -71.906654)
		(end 134.748524 -72.049386)
		(width 0.0889)
		(layer "In4.Cu")
		(net "CLK_100M_CPU1_RC_REFCLK1_DP")
	)
	(arc
		(start 137.324084 -72.544686)
		(mid 136.812274 -72.840353)
		(end 136.300464 -72.544686)
		(width 0.0889)
		(layer "In4.Cu")
		(net "CLK_100M_CPU1_RC_REFCLK1_DP")
	)
	(arc
		(start 123.946666 -72.344534)
		(mid 123.934728 -72.344356)
		(end 123.92279 -72.344534)
		(width 0.0889)
		(layer "In4.Cu")
		(net "CLK_100M_CPU1_RC_REFCLK1_DP")
	)
	(arc
		(start 134.225538 -72.344534)
		(mid 134.031688 -72.400884)
		(end 133.890004 -72.544686)
		(width 0.0889)
		(layer "In4.Cu")
		(net "CLK_100M_CPU1_RC_REFCLK1_DP")
	)
	(arc
		(start 135.441944 -72.049386)
		(mid 135.301865 -71.90665)
		(end 135.11022 -71.849488)
		(width 0.0889)
		(layer "In4.Cu")
		(net "CLK_100M_CPU1_RC_REFCLK1_DP")
	)
	(arc
		(start 134.748524 -72.049386)
		(mid 134.54152 -72.26025)
		(end 134.258304 -72.344534)
		(width 0.0889)
		(layer "In4.Cu")
		(net "CLK_100M_CPU1_RC_REFCLK1_DP")
	)
	(arc
		(start 130.456178 -72.544686)
		(mid 129.944368 -72.840353)
		(end 129.432558 -72.544686)
		(width 0.0889)
		(layer "In4.Cu")
		(net "CLK_100M_CPU1_RC_REFCLK1_DP")
	)
	(arc
		(start 122.564398 -72.544686)
		(mid 122.442507 -72.41349)
		(end 122.2756 -72.348598)
		(width 0.0889)
		(layer "In4.Cu")
		(net "CLK_100M_CPU1_RC_REFCLK1_DP")
	)
	(arc
		(start 124.281438 -72.544686)
		(mid 124.140082 -72.401077)
		(end 123.946666 -72.344534)
		(width 0.0889)
		(layer "In4.Cu")
		(net "CLK_100M_CPU1_RC_REFCLK1_DP")
	)
	(arc
		(start 131.149598 -72.544686)
		(mid 130.802888 -72.344375)
		(end 130.456178 -72.544686)
		(width 0.0889)
		(layer "In4.Cu")
		(net "CLK_100M_CPU1_RC_REFCLK1_DP")
	)
	(arc
		(start 123.92279 -72.344534)
		(mid 123.729364 -72.401061)
		(end 123.588018 -72.544686)
		(width 0.0889)
		(layer "In4.Cu")
		(net "CLK_100M_CPU1_RC_REFCLK1_DP")
	)
	(arc
		(start 125.998478 -72.544686)
		(mid 125.651768 -72.344375)
		(end 125.305058 -72.544686)
		(width 0.0889)
		(layer "In4.Cu")
		(net "CLK_100M_CPU1_RC_REFCLK1_DP")
	)
	(arc
		(start 128.739138 -72.544686)
		(mid 128.227328 -72.840353)
		(end 127.715518 -72.544686)
		(width 0.0889)
		(layer "In4.Cu")
		(net "CLK_100M_CPU1_RC_REFCLK1_DP")
	)
	(arc
		(start 123.588018 -72.544686)
		(mid 123.37941 -72.756618)
		(end 123.093988 -72.840088)
		(width 0.0889)
		(layer "In4.Cu")
		(net "CLK_100M_CPU1_RC_REFCLK1_DP")
	)
	(arc
		(start 139.041124 -72.544686)
		(mid 138.529314 -72.840353)
		(end 138.017504 -72.544686)
		(width 0.0889)
		(layer "In4.Cu")
		(net "CLK_100M_CPU1_RC_REFCLK1_DP")
	)
	(arc
		(start 139.734544 -72.544686)
		(mid 139.387834 -72.344375)
		(end 139.041124 -72.544686)
		(width 0.0889)
		(layer "In4.Cu")
		(net "CLK_100M_CPU1_RC_REFCLK1_DP")
	)
	(arc
		(start 127.022098 -72.544686)
		(mid 126.510288 -72.840353)
		(end 125.998478 -72.544686)
		(width 0.0889)
		(layer "In4.Cu")
		(net "CLK_100M_CPU1_RC_REFCLK1_DP")
	)
	(arc
		(start 133.890004 -72.544686)
		(mid 133.378194 -72.840353)
		(end 132.866384 -72.544686)
		(width 0.0889)
		(layer "In4.Cu")
		(net "CLK_100M_CPU1_RC_REFCLK1_DP")
	)
	(arc
		(start 127.715518 -72.544686)
		(mid 127.368808 -72.344375)
		(end 127.022098 -72.544686)
		(width 0.0889)
		(layer "In4.Cu")
		(net "CLK_100M_CPU1_RC_REFCLK1_DP")
	)
	(arc
		(start 129.432558 -72.544686)
		(mid 129.085848 -72.344375)
		(end 128.739138 -72.544686)
		(width 0.0889)
		(layer "In4.Cu")
		(net "CLK_100M_CPU1_RC_REFCLK1_DP")
	)
	(arc
		(start 125.305058 -72.544686)
		(mid 124.793248 -72.840353)
		(end 124.281438 -72.544686)
		(width 0.0889)
		(layer "In4.Cu")
		(net "CLK_100M_CPU1_RC_REFCLK1_DP")
	)
	(arc
		(start 135.932164 -72.344534)
		(mid 135.648947 -72.260253)
		(end 135.441944 -72.049386)
		(width 0.0889)
		(layer "In4.Cu")
		(net "CLK_100M_CPU1_RC_REFCLK1_DP")
	)
	(arc
		(start 138.017504 -72.544686)
		(mid 137.670794 -72.344375)
		(end 137.324084 -72.544686)
		(width 0.0889)
		(layer "In4.Cu")
		(net "CLK_100M_CPU1_RC_REFCLK1_DP")
	)
	(arc
		(start 136.300464 -72.544686)
		(mid 136.158781 -72.400882)
		(end 135.96493 -72.344534)
		(width 0.0889)
		(layer "In4.Cu")
		(net "CLK_100M_CPU1_RC_REFCLK1_DP")
	)
	(arc
		(start 132.173218 -72.544686)
		(mid 131.661408 -72.840353)
		(end 131.149598 -72.544686)
		(width 0.0889)
		(layer "In4.Cu")
		(net "CLK_100M_CPU1_RC_REFCLK1_DP")
	)
	(arc
		(start 132.866384 -72.544686)
		(mid 132.526339 -72.344431)
		(end 132.179822 -72.533256)
		(width 0.0889)
		(layer "In4.Cu")
		(net "CLK_100M_CPU1_RC_REFCLK1_DP")
	)
	(arc
		(start 123.058428 -72.840088)
		(mid 122.773004 -72.756621)
		(end 122.564398 -72.544686)
		(width 0.0889)
		(layer "In4.Cu")
		(net "CLK_100M_CPU1_RC_REFCLK1_DP")
	)
	(arc
		(start 140.228574 -72.840088)
		(mid 139.94315 -72.756621)
		(end 139.734544 -72.544686)
		(width 0.0889)
		(layer "In4.Cu")
		(net "CLK_100M_CPU1_RC_REFCLK1_DP")
	)
	(segment
		(start 122.217688 -71.753984)
		(end 121.646188 -71.753984)
		(width 0.1143)
		(layer "F.Cu")
		(net "CLK_100M_CPU1_RC_REFCLK1_DN")
	)
	(segment
		(start 161.9504 -76.708)
		(end 161.9504 -77.120496)
		(width 0.1143)
		(layer "F.Cu")
		(net "CLK_100M_CPU1_RC_REFCLK1_DN")
	)
	(segment
		(start 161.9504 -77.120496)
		(end 162.058604 -77.2287)
		(width 0.1143)
		(layer "F.Cu")
		(net "CLK_100M_CPU1_RC_REFCLK1_DN")
	)
	(segment
		(start 162.1663 -77.2287)
		(end 162.687 -76.708)
		(width 0.1143)
		(layer "F.Cu")
		(net "CLK_100M_CPU1_RC_REFCLK1_DN")
	)
	(segment
		(start 162.058604 -77.2287)
		(end 162.1663 -77.2287)
		(width 0.1143)
		(layer "F.Cu")
		(net "CLK_100M_CPU1_RC_REFCLK1_DN")
	)
	(via
		(at 122.217688 -71.753984)
		(size 0.508)
		(drill 0.254)
		(layers "F.Cu" "B.Cu")
		(net "CLK_100M_CPU1_RC_REFCLK1_DN")
	)
	(via
		(at 161.9504 -76.708)
		(size 0.508)
		(drill 0.254)
		(layers "F.Cu" "B.Cu")
		(net "CLK_100M_CPU1_RC_REFCLK1_DN")
	)
	(segment
		(start 162.306 -77.1906)
		(end 162.7886 -76.708)
		(width 0.1143)
		(layer "B.Cu")
		(net "CLK_100M_CPU1_RC_REFCLK1_DN")
	)
	(segment
		(start 161.9504 -77.097382)
		(end 162.043618 -77.1906)
		(width 0.1143)
		(layer "B.Cu")
		(net "CLK_100M_CPU1_RC_REFCLK1_DN")
	)
	(segment
		(start 162.043618 -77.1906)
		(end 162.306 -77.1906)
		(width 0.1143)
		(layer "B.Cu")
		(net "CLK_100M_CPU1_RC_REFCLK1_DN")
	)
	(segment
		(start 161.9504 -76.708)
		(end 161.9504 -77.097382)
		(width 0.1143)
		(layer "B.Cu")
		(net "CLK_100M_CPU1_RC_REFCLK1_DN")
	)
	(segment
		(start 158.070042 -79.13116)
		(end 157.67177 -78.732888)
		(width 0.1143)
		(layer "In4.Cu")
		(net "CLK_100M_CPU1_RC_REFCLK1_DN")
	)
	(segment
		(start 160.896046 -77.19695)
		(end 160.610804 -77.482192)
		(width 0.1143)
		(layer "In4.Cu")
		(net "CLK_100M_CPU1_RC_REFCLK1_DN")
	)
	(segment
		(start 145.153888 -81.65211)
		(end 155.584652 -81.65211)
		(width 0.1143)
		(layer "In4.Cu")
		(net "CLK_100M_CPU1_RC_REFCLK1_DN")
	)
	(segment
		(start 157.420056 -80.409288)
		(end 157.282134 -80.54721)
		(width 0.1143)
		(layer "In4.Cu")
		(net "CLK_100M_CPU1_RC_REFCLK1_DN")
	)
	(segment
		(start 132.007864 -72.449436)
		(end 132.00126 -72.460866)
		(width 0.0889)
		(layer "In4.Cu")
		(net "CLK_100M_CPU1_RC_REFCLK1_DN")
	)
	(segment
		(start 156.710888 -77.53858)
		(end 156.477462 -77.53858)
		(width 0.1143)
		(layer "In4.Cu")
		(net "CLK_100M_CPU1_RC_REFCLK1_DN")
	)
	(segment
		(start 144.449292 -79.982314)
		(end 143.079724 -78.612746)
		(width 0.1143)
		(layer "In4.Cu")
		(net "CLK_100M_CPU1_RC_REFCLK1_DN")
	)
	(segment
		(start 144.868646 -81.366868)
		(end 145.153888 -81.65211)
		(width 0.1143)
		(layer "In4.Cu")
		(net "CLK_100M_CPU1_RC_REFCLK1_DN")
	)
	(segment
		(start 143.028924 -74.89571)
		(end 140.782802 -72.649588)
		(width 0.0889)
		(layer "In4.Cu")
		(net "CLK_100M_CPU1_RC_REFCLK1_DN")
	)
	(segment
		(start 143.62557 -78.115668)
		(end 143.910812 -78.40091)
		(width 0.1143)
		(layer "In4.Cu")
		(net "CLK_100M_CPU1_RC_REFCLK1_DN")
	)
	(segment
		(start 155.719018 -82.05851)
		(end 155.604718 -82.17281)
		(width 0.1143)
		(layer "In4.Cu")
		(net "CLK_100M_CPU1_RC_REFCLK1_DN")
	)
	(segment
		(start 122.282966 -72.157336)
		(end 122.217688 -72.092058)
		(width 0.0889)
		(layer "In4.Cu")
		(net "CLK_100M_CPU1_RC_REFCLK1_DN")
	)
	(segment
		(start 135.116824 -71.658988)
		(end 135.073644 -71.658988)
		(width 0.0889)
		(layer "In4.Cu")
		(net "CLK_100M_CPU1_RC_REFCLK1_DN")
	)
	(segment
		(start 157.4292 -78.256892)
		(end 157.195774 -78.256892)
		(width 0.1143)
		(layer "In4.Cu")
		(net "CLK_100M_CPU1_RC_REFCLK1_DN")
	)
	(segment
		(start 140.782802 -72.649588)
		(end 140.235178 -72.649588)
		(width 0.0889)
		(layer "In4.Cu")
		(net "CLK_100M_CPU1_RC_REFCLK1_DN")
	)
	(segment
		(start 156.953204 -78.014322)
		(end 156.953204 -77.780896)
		(width 0.1143)
		(layer "In4.Cu")
		(net "CLK_100M_CPU1_RC_REFCLK1_DN")
	)
	(segment
		(start 123.952508 -72.154034)
		(end 123.916948 -72.154034)
		(width 0.0889)
		(layer "In4.Cu")
		(net "CLK_100M_CPU1_RC_REFCLK1_DN")
	)
	(segment
		(start 144.868646 -79.206852)
		(end 144.868646 -79.741268)
		(width 0.1143)
		(layer "In4.Cu")
		(net "CLK_100M_CPU1_RC_REFCLK1_DN")
	)
	(segment
		(start 145.153888 -80.54721)
		(end 144.868646 -80.832452)
		(width 0.1143)
		(layer "In4.Cu")
		(net "CLK_100M_CPU1_RC_REFCLK1_DN")
	)
	(segment
		(start 159.086042 -79.13116)
		(end 158.920942 -78.96606)
		(width 0.1143)
		(layer "In4.Cu")
		(net "CLK_100M_CPU1_RC_REFCLK1_DN")
	)
	(segment
		(start 144.868646 -79.741268)
		(end 145.153888 -80.02651)
		(width 0.1143)
		(layer "In4.Cu")
		(net "CLK_100M_CPU1_RC_REFCLK1_DN")
	)
	(segment
		(start 160.610804 -77.482192)
		(end 160.610804 -79.01686)
		(width 0.1143)
		(layer "In4.Cu")
		(net "CLK_100M_CPU1_RC_REFCLK1_DN")
	)
	(segment
		(start 144.449292 -82.045556)
		(end 144.449292 -79.982314)
		(width 0.1143)
		(layer "In4.Cu")
		(net "CLK_100M_CPU1_RC_REFCLK1_DN")
	)
	(segment
		(start 155.604718 -82.17281)
		(end 144.576546 -82.17281)
		(width 0.1143)
		(layer "In4.Cu")
		(net "CLK_100M_CPU1_RC_REFCLK1_DN")
	)
	(segment
		(start 157.67177 -78.732888)
		(end 157.67177 -78.499462)
		(width 0.1143)
		(layer "In4.Cu")
		(net "CLK_100M_CPU1_RC_REFCLK1_DN")
	)
	(segment
		(start 156.953204 -77.780896)
		(end 156.710888 -77.53858)
		(width 0.1143)
		(layer "In4.Cu")
		(net "CLK_100M_CPU1_RC_REFCLK1_DN")
	)
	(segment
		(start 143.028924 -76.705968)
		(end 143.028924 -74.89571)
		(width 0.0889)
		(layer "In4.Cu")
		(net "CLK_100M_CPU1_RC_REFCLK1_DN")
	)
	(segment
		(start 143.079724 -76.778866)
		(end 143.079724 -76.756768)
		(width 0.0889)
		(layer "In4.Cu")
		(net "CLK_100M_CPU1_RC_REFCLK1_DN")
	)
	(segment
		(start 134.2517 -72.154034)
		(end 134.218934 -72.154034)
		(width 0.0889)
		(layer "In4.Cu")
		(net "CLK_100M_CPU1_RC_REFCLK1_DN")
	)
	(segment
		(start 158.412942 -79.13116)
		(end 158.070042 -79.13116)
		(width 0.1143)
		(layer "In4.Cu")
		(net "CLK_100M_CPU1_RC_REFCLK1_DN")
	)
	(segment
		(start 155.72486 -78.52537)
		(end 155.72486 -78.783942)
		(width 0.1143)
		(layer "In4.Cu")
		(net "CLK_100M_CPU1_RC_REFCLK1_DN")
	)
	(segment
		(start 157.67177 -78.499462)
		(end 157.4292 -78.256892)
		(width 0.1143)
		(layer "In4.Cu")
		(net "CLK_100M_CPU1_RC_REFCLK1_DN")
	)
	(segment
		(start 158.578042 -78.96606)
		(end 158.412942 -79.13116)
		(width 0.1143)
		(layer "In4.Cu")
		(net "CLK_100M_CPU1_RC_REFCLK1_DN")
	)
	(segment
		(start 143.924274 -77.29601)
		(end 143.62557 -77.594714)
		(width 0.1143)
		(layer "In4.Cu")
		(net "CLK_100M_CPU1_RC_REFCLK1_DN")
	)
	(segment
		(start 161.8361 -77.19695)
		(end 160.896046 -77.19695)
		(width 0.1143)
		(layer "In4.Cu")
		(net "CLK_100M_CPU1_RC_REFCLK1_DN")
	)
	(segment
		(start 161.9504 -76.708)
		(end 161.9504 -77.08265)
		(width 0.1143)
		(layer "In4.Cu")
		(net "CLK_100M_CPU1_RC_REFCLK1_DN")
	)
	(segment
		(start 160.496504 -79.13116)
		(end 159.086042 -79.13116)
		(width 0.1143)
		(layer "In4.Cu")
		(net "CLK_100M_CPU1_RC_REFCLK1_DN")
	)
	(segment
		(start 143.079724 -76.756768)
		(end 143.028924 -76.705968)
		(width 0.0889)
		(layer "In4.Cu")
		(net "CLK_100M_CPU1_RC_REFCLK1_DN")
	)
	(segment
		(start 155.719018 -81.786476)
		(end 155.719018 -82.05851)
		(width 0.1143)
		(layer "In4.Cu")
		(net "CLK_100M_CPU1_RC_REFCLK1_DN")
	)
	(segment
		(start 143.62557 -77.594714)
		(end 143.62557 -78.115668)
		(width 0.1143)
		(layer "In4.Cu")
		(net "CLK_100M_CPU1_RC_REFCLK1_DN")
	)
	(segment
		(start 157.420056 -80.14081)
		(end 157.420056 -80.409288)
		(width 0.1143)
		(layer "In4.Cu")
		(net "CLK_100M_CPU1_RC_REFCLK1_DN")
	)
	(segment
		(start 156.477462 -77.53858)
		(end 156.234892 -77.29601)
		(width 0.1143)
		(layer "In4.Cu")
		(net "CLK_100M_CPU1_RC_REFCLK1_DN")
	)
	(segment
		(start 145.153888 -78.92161)
		(end 144.868646 -79.206852)
		(width 0.1143)
		(layer "In4.Cu")
		(net "CLK_100M_CPU1_RC_REFCLK1_DN")
	)
	(segment
		(start 135.971534 -72.154034)
		(end 135.938768 -72.154034)
		(width 0.0889)
		(layer "In4.Cu")
		(net "CLK_100M_CPU1_RC_REFCLK1_DN")
	)
	(segment
		(start 144.576546 -82.17281)
		(end 144.449292 -82.045556)
		(width 0.1143)
		(layer "In4.Cu")
		(net "CLK_100M_CPU1_RC_REFCLK1_DN")
	)
	(segment
		(start 144.868646 -80.832452)
		(end 144.868646 -81.366868)
		(width 0.1143)
		(layer "In4.Cu")
		(net "CLK_100M_CPU1_RC_REFCLK1_DN")
	)
	(segment
		(start 157.305756 -80.02651)
		(end 157.420056 -80.14081)
		(width 0.1143)
		(layer "In4.Cu")
		(net "CLK_100M_CPU1_RC_REFCLK1_DN")
	)
	(segment
		(start 143.910812 -78.40091)
		(end 155.6004 -78.40091)
		(width 0.1143)
		(layer "In4.Cu")
		(net "CLK_100M_CPU1_RC_REFCLK1_DN")
	)
	(segment
		(start 155.6004 -78.40091)
		(end 155.72486 -78.52537)
		(width 0.1143)
		(layer "In4.Cu")
		(net "CLK_100M_CPU1_RC_REFCLK1_DN")
	)
	(segment
		(start 145.153888 -80.02651)
		(end 157.305756 -80.02651)
		(width 0.1143)
		(layer "In4.Cu")
		(net "CLK_100M_CPU1_RC_REFCLK1_DN")
	)
	(segment
		(start 158.920942 -78.96606)
		(end 158.578042 -78.96606)
		(width 0.1143)
		(layer "In4.Cu")
		(net "CLK_100M_CPU1_RC_REFCLK1_DN")
	)
	(segment
		(start 122.217688 -72.092058)
		(end 122.217688 -71.753984)
		(width 0.0889)
		(layer "In4.Cu")
		(net "CLK_100M_CPU1_RC_REFCLK1_DN")
	)
	(segment
		(start 155.72486 -78.783942)
		(end 155.587192 -78.92161)
		(width 0.1143)
		(layer "In4.Cu")
		(net "CLK_100M_CPU1_RC_REFCLK1_DN")
	)
	(segment
		(start 157.195774 -78.256892)
		(end 156.953204 -78.014322)
		(width 0.1143)
		(layer "In4.Cu")
		(net "CLK_100M_CPU1_RC_REFCLK1_DN")
	)
	(segment
		(start 156.234892 -77.29601)
		(end 143.924274 -77.29601)
		(width 0.1143)
		(layer "In4.Cu")
		(net "CLK_100M_CPU1_RC_REFCLK1_DN")
	)
	(segment
		(start 155.584652 -81.65211)
		(end 155.719018 -81.786476)
		(width 0.1143)
		(layer "In4.Cu")
		(net "CLK_100M_CPU1_RC_REFCLK1_DN")
	)
	(segment
		(start 161.9504 -77.08265)
		(end 161.8361 -77.19695)
		(width 0.1143)
		(layer "In4.Cu")
		(net "CLK_100M_CPU1_RC_REFCLK1_DN")
	)
	(segment
		(start 143.079724 -78.612746)
		(end 143.079724 -76.778866)
		(width 0.1143)
		(layer "In4.Cu")
		(net "CLK_100M_CPU1_RC_REFCLK1_DN")
	)
	(segment
		(start 160.610804 -79.01686)
		(end 160.496504 -79.13116)
		(width 0.1143)
		(layer "In4.Cu")
		(net "CLK_100M_CPU1_RC_REFCLK1_DN")
	)
	(segment
		(start 155.587192 -78.92161)
		(end 145.153888 -78.92161)
		(width 0.1143)
		(layer "In4.Cu")
		(net "CLK_100M_CPU1_RC_REFCLK1_DN")
	)
	(segment
		(start 157.282134 -80.54721)
		(end 145.153888 -80.54721)
		(width 0.1143)
		(layer "In4.Cu")
		(net "CLK_100M_CPU1_RC_REFCLK1_DN")
	)
	(arc
		(start 123.088146 -72.649588)
		(mid 123.076208 -72.649766)
		(end 123.06427 -72.649588)
		(width 0.0889)
		(layer "In4.Cu")
		(net "CLK_100M_CPU1_RC_REFCLK1_DN")
	)
	(arc
		(start 123.916948 -72.154034)
		(mid 123.631524 -72.237501)
		(end 123.422918 -72.449436)
		(width 0.0889)
		(layer "In4.Cu")
		(net "CLK_100M_CPU1_RC_REFCLK1_DN")
	)
	(arc
		(start 123.422918 -72.449436)
		(mid 123.281562 -72.593045)
		(end 123.088146 -72.649588)
		(width 0.0889)
		(layer "In4.Cu")
		(net "CLK_100M_CPU1_RC_REFCLK1_DN")
	)
	(arc
		(start 126.856998 -72.449436)
		(mid 126.510288 -72.649747)
		(end 126.163578 -72.449436)
		(width 0.0889)
		(layer "In4.Cu")
		(net "CLK_100M_CPU1_RC_REFCLK1_DN")
	)
	(arc
		(start 125.139958 -72.449436)
		(mid 124.793248 -72.649747)
		(end 124.446538 -72.449436)
		(width 0.0889)
		(layer "In4.Cu")
		(net "CLK_100M_CPU1_RC_REFCLK1_DN")
	)
	(arc
		(start 129.597658 -72.449436)
		(mid 129.085848 -72.153769)
		(end 128.574038 -72.449436)
		(width 0.0889)
		(layer "In4.Cu")
		(net "CLK_100M_CPU1_RC_REFCLK1_DN")
	)
	(arc
		(start 128.574038 -72.449436)
		(mid 128.227328 -72.649747)
		(end 127.880618 -72.449436)
		(width 0.0889)
		(layer "In4.Cu")
		(net "CLK_100M_CPU1_RC_REFCLK1_DN")
	)
	(arc
		(start 134.218934 -72.154034)
		(mid 133.93351 -72.237501)
		(end 133.724904 -72.449436)
		(width 0.0889)
		(layer "In4.Cu")
		(net "CLK_100M_CPU1_RC_REFCLK1_DN")
	)
	(arc
		(start 133.724904 -72.449436)
		(mid 133.378194 -72.649747)
		(end 133.031484 -72.449436)
		(width 0.0889)
		(layer "In4.Cu")
		(net "CLK_100M_CPU1_RC_REFCLK1_DN")
	)
	(arc
		(start 123.06427 -72.649588)
		(mid 122.870844 -72.593061)
		(end 122.729498 -72.449436)
		(width 0.0889)
		(layer "In4.Cu")
		(net "CLK_100M_CPU1_RC_REFCLK1_DN")
	)
	(arc
		(start 139.899644 -72.449436)
		(mid 139.387834 -72.153769)
		(end 138.876024 -72.449436)
		(width 0.0889)
		(layer "In4.Cu")
		(net "CLK_100M_CPU1_RC_REFCLK1_DN")
	)
	(arc
		(start 132.00126 -72.460866)
		(mid 131.654743 -72.649681)
		(end 131.314698 -72.449436)
		(width 0.0889)
		(layer "In4.Cu")
		(net "CLK_100M_CPU1_RC_REFCLK1_DN")
	)
	(arc
		(start 133.031484 -72.449436)
		(mid 132.519674 -72.153769)
		(end 132.007864 -72.449436)
		(width 0.0889)
		(layer "In4.Cu")
		(net "CLK_100M_CPU1_RC_REFCLK1_DN")
	)
	(arc
		(start 135.073644 -71.658988)
		(mid 134.790427 -71.743269)
		(end 134.583424 -71.954136)
		(width 0.0889)
		(layer "In4.Cu")
		(net "CLK_100M_CPU1_RC_REFCLK1_DN")
	)
	(arc
		(start 126.163578 -72.449436)
		(mid 125.651768 -72.153769)
		(end 125.139958 -72.449436)
		(width 0.0889)
		(layer "In4.Cu")
		(net "CLK_100M_CPU1_RC_REFCLK1_DN")
	)
	(arc
		(start 140.235178 -72.649588)
		(mid 140.041328 -72.593238)
		(end 139.899644 -72.449436)
		(width 0.0889)
		(layer "In4.Cu")
		(net "CLK_100M_CPU1_RC_REFCLK1_DN")
	)
	(arc
		(start 138.182604 -72.449436)
		(mid 137.670794 -72.153769)
		(end 137.158984 -72.449436)
		(width 0.0889)
		(layer "In4.Cu")
		(net "CLK_100M_CPU1_RC_REFCLK1_DN")
	)
	(arc
		(start 135.607044 -71.954136)
		(mid 135.40004 -71.743272)
		(end 135.116824 -71.658988)
		(width 0.0889)
		(layer "In4.Cu")
		(net "CLK_100M_CPU1_RC_REFCLK1_DN")
	)
	(arc
		(start 137.158984 -72.449436)
		(mid 136.812274 -72.649747)
		(end 136.465564 -72.449436)
		(width 0.0889)
		(layer "In4.Cu")
		(net "CLK_100M_CPU1_RC_REFCLK1_DN")
	)
	(arc
		(start 136.465564 -72.449436)
		(mid 136.256956 -72.237504)
		(end 135.971534 -72.154034)
		(width 0.0889)
		(layer "In4.Cu")
		(net "CLK_100M_CPU1_RC_REFCLK1_DN")
	)
	(arc
		(start 138.876024 -72.449436)
		(mid 138.529314 -72.649747)
		(end 138.182604 -72.449436)
		(width 0.0889)
		(layer "In4.Cu")
		(net "CLK_100M_CPU1_RC_REFCLK1_DN")
	)
	(arc
		(start 130.291078 -72.449436)
		(mid 129.944368 -72.649747)
		(end 129.597658 -72.449436)
		(width 0.0889)
		(layer "In4.Cu")
		(net "CLK_100M_CPU1_RC_REFCLK1_DN")
	)
	(arc
		(start 122.729498 -72.449436)
		(mid 122.541075 -72.250132)
		(end 122.282966 -72.157336)
		(width 0.0889)
		(layer "In4.Cu")
		(net "CLK_100M_CPU1_RC_REFCLK1_DN")
	)
	(arc
		(start 134.583424 -71.954136)
		(mid 134.443345 -72.096872)
		(end 134.2517 -72.154034)
		(width 0.0889)
		(layer "In4.Cu")
		(net "CLK_100M_CPU1_RC_REFCLK1_DN")
	)
	(arc
		(start 135.938768 -72.154034)
		(mid 135.747126 -72.096868)
		(end 135.607044 -71.954136)
		(width 0.0889)
		(layer "In4.Cu")
		(net "CLK_100M_CPU1_RC_REFCLK1_DN")
	)
	(arc
		(start 127.880618 -72.449436)
		(mid 127.368808 -72.153769)
		(end 126.856998 -72.449436)
		(width 0.0889)
		(layer "In4.Cu")
		(net "CLK_100M_CPU1_RC_REFCLK1_DN")
	)
	(arc
		(start 131.314698 -72.449436)
		(mid 130.802888 -72.153769)
		(end 130.291078 -72.449436)
		(width 0.0889)
		(layer "In4.Cu")
		(net "CLK_100M_CPU1_RC_REFCLK1_DN")
	)
	(arc
		(start 124.446538 -72.449436)
		(mid 124.23793 -72.237504)
		(end 123.952508 -72.154034)
		(width 0.0889)
		(layer "In4.Cu")
		(net "CLK_100M_CPU1_RC_REFCLK1_DN")
	)
	(segment
		(start 376.744738 -72.695308)
		(end 376.344942 -73.095104)
		(width 0.10795)
		(layer "F.Cu")
		(net "RST_RSMRST_R_N")
	)
	(via
		(at 376.744738 -72.695308)
		(size 0.4572)
		(drill 0.2032)
		(layers "F.Cu" "B.Cu")
		(net "RST_RSMRST_R_N")
	)
	(via
		(at 378.704602 -70.174358)
		(size 0.6604)
		(drill 0.3302)
		(layers "F.Cu" "B.Cu")
		(net "RST_RSMRST_R_N")
	)
	(segment
		(start 377.75642 -67.2211)
		(end 378.5362 -67.2211)
		(width 0.10795)
		(layer "B.Cu")
		(net "RST_RSMRST_R_N")
	)
	(segment
		(start 378.73686 -67.691)
		(end 378.53874 -67.49288)
		(width 0.10795)
		(layer "B.Cu")
		(net "RST_RSMRST_R_N")
	)
	(segment
		(start 377.740926 -72.286622)
		(end 377.992894 -72.034654)
		(width 0.10795)
		(layer "B.Cu")
		(net "RST_RSMRST_R_N")
	)
	(segment
		(start 376.744738 -72.695308)
		(end 377.153424 -72.286622)
		(width 0.10795)
		(layer "B.Cu")
		(net "RST_RSMRST_R_N")
	)
	(segment
		(start 378.704602 -70.174358)
		(end 378.704602 -69.596508)
		(width 0.10795)
		(layer "B.Cu")
		(net "RST_RSMRST_R_N")
	)
	(segment
		(start 377.752356 -70.803262)
		(end 378.055378 -70.50024)
		(width 0.10795)
		(layer "B.Cu")
		(net "RST_RSMRST_R_N")
	)
	(segment
		(start 377.992894 -72.034654)
		(end 377.992894 -71.643494)
		(width 0.10795)
		(layer "B.Cu")
		(net "RST_RSMRST_R_N")
	)
	(segment
		(start 377.961906 -68.853812)
		(end 377.961906 -68.468494)
		(width 0.10795)
		(layer "B.Cu")
		(net "RST_RSMRST_R_N")
	)
	(segment
		(start 377.75261 -71.40321)
		(end 377.75261 -71.35495)
		(width 0.10795)
		(layer "B.Cu")
		(net "RST_RSMRST_R_N")
	)
	(segment
		(start 377.961906 -68.468494)
		(end 378.117862 -68.312538)
		(width 0.10795)
		(layer "B.Cu")
		(net "RST_RSMRST_R_N")
	)
	(segment
		(start 378.53874 -67.49288)
		(end 378.53874 -67.21856)
		(width 0.10795)
		(layer "B.Cu")
		(net "RST_RSMRST_R_N")
	)
	(segment
		(start 377.153424 -72.286622)
		(end 377.740926 -72.286622)
		(width 0.10795)
		(layer "B.Cu")
		(net "RST_RSMRST_R_N")
	)
	(segment
		(start 378.524262 -68.312538)
		(end 378.73686 -68.09994)
		(width 0.10795)
		(layer "B.Cu")
		(net "RST_RSMRST_R_N")
	)
	(segment
		(start 378.37872 -70.50024)
		(end 378.704602 -70.174358)
		(width 0.10795)
		(layer "B.Cu")
		(net "RST_RSMRST_R_N")
	)
	(segment
		(start 378.117862 -68.312538)
		(end 378.524262 -68.312538)
		(width 0.10795)
		(layer "B.Cu")
		(net "RST_RSMRST_R_N")
	)
	(segment
		(start 378.5362 -67.2211)
		(end 378.53874 -67.21856)
		(width 0.10795)
		(layer "B.Cu")
		(net "RST_RSMRST_R_N")
	)
	(segment
		(start 377.75261 -71.35495)
		(end 377.752356 -71.354696)
		(width 0.10795)
		(layer "B.Cu")
		(net "RST_RSMRST_R_N")
	)
	(segment
		(start 377.992894 -71.643494)
		(end 377.75261 -71.40321)
		(width 0.10795)
		(layer "B.Cu")
		(net "RST_RSMRST_R_N")
	)
	(segment
		(start 377.752356 -71.354696)
		(end 377.752356 -70.803262)
		(width 0.10795)
		(layer "B.Cu")
		(net "RST_RSMRST_R_N")
	)
	(segment
		(start 378.73686 -68.09994)
		(end 378.73686 -67.691)
		(width 0.10795)
		(layer "B.Cu")
		(net "RST_RSMRST_R_N")
	)
	(segment
		(start 378.704602 -69.596508)
		(end 377.961906 -68.853812)
		(width 0.10795)
		(layer "B.Cu")
		(net "RST_RSMRST_R_N")
	)
	(segment
		(start 378.055378 -70.50024)
		(end 378.37872 -70.50024)
		(width 0.10795)
		(layer "B.Cu")
		(net "RST_RSMRST_R_N")
	)
	(via
		(at 396.670022 -34.562796)
		(size 0.6604)
		(drill 0.3302)
		(layers "F.Cu" "B.Cu")
		(net "RST_BMC_SYSRST_BTN_OUT_B_R_N")
	)
	(segment
		(start 394.589 -29.308044)
		(end 394.843 -29.054044)
		(width 0.10795)
		(layer "B.Cu")
		(net "RST_BMC_SYSRST_BTN_OUT_B_R_N")
	)
	(segment
		(start 394.589 -30.136592)
		(end 394.805408 -30.353)
		(width 0.10795)
		(layer "B.Cu")
		(net "RST_BMC_SYSRST_BTN_OUT_B_R_N")
	)
	(segment
		(start 395.683994 -30.438598)
		(end 396.034006 -30.438598)
		(width 0.10795)
		(layer "B.Cu")
		(net "RST_BMC_SYSRST_BTN_OUT_B_R_N")
	)
	(segment
		(start 394.843 -29.054044)
		(end 394.843 -28.575)
		(width 0.10795)
		(layer "B.Cu")
		(net "RST_BMC_SYSRST_BTN_OUT_B_R_N")
	)
	(segment
		(start 393.550902 -37.0586)
		(end 393.474702 -37.1348)
		(width 0.10795)
		(layer "B.Cu")
		(net "RST_BMC_SYSRST_BTN_OUT_B_R_N")
	)
	(segment
		(start 394.425678 -36.358322)
		(end 396.028672 -36.358322)
		(width 0.10795)
		(layer "B.Cu")
		(net "RST_BMC_SYSRST_BTN_OUT_B_R_N")
	)
	(segment
		(start 396.623286 -35.308794)
		(end 396.670022 -35.262058)
		(width 0.10795)
		(layer "B.Cu")
		(net "RST_BMC_SYSRST_BTN_OUT_B_R_N")
	)
	(segment
		(start 394.3096 -37.0586)
		(end 394.3096 -36.4744)
		(width 0.10795)
		(layer "B.Cu")
		(net "RST_BMC_SYSRST_BTN_OUT_B_R_N")
	)
	(segment
		(start 394.3096 -36.4744)
		(end 394.425678 -36.358322)
		(width 0.10795)
		(layer "B.Cu")
		(net "RST_BMC_SYSRST_BTN_OUT_B_R_N")
	)
	(segment
		(start 394.589 -29.845)
		(end 394.589 -29.308044)
		(width 0.10795)
		(layer "B.Cu")
		(net "RST_BMC_SYSRST_BTN_OUT_B_R_N")
	)
	(segment
		(start 396.281402 -30.980888)
		(end 396.281402 -31.036006)
		(width 0.10795)
		(layer "B.Cu")
		(net "RST_BMC_SYSRST_BTN_OUT_B_R_N")
	)
	(segment
		(start 396.623286 -35.416744)
		(end 396.623286 -35.308794)
		(width 0.10795)
		(layer "B.Cu")
		(net "RST_BMC_SYSRST_BTN_OUT_B_R_N")
	)
	(segment
		(start 396.028672 -36.358322)
		(end 396.253208 -36.133786)
		(width 0.10795)
		(layer "B.Cu")
		(net "RST_BMC_SYSRST_BTN_OUT_B_R_N")
	)
	(segment
		(start 396.217902 -31.099506)
		(end 396.217902 -32.455612)
		(width 0.10795)
		(layer "B.Cu")
		(net "RST_BMC_SYSRST_BTN_OUT_B_R_N")
	)
	(segment
		(start 396.251684 -30.656276)
		(end 396.251684 -30.95117)
		(width 0.10795)
		(layer "B.Cu")
		(net "RST_BMC_SYSRST_BTN_OUT_B_R_N")
	)
	(segment
		(start 396.217902 -32.455612)
		(end 396.670022 -32.907732)
		(width 0.10795)
		(layer "B.Cu")
		(net "RST_BMC_SYSRST_BTN_OUT_B_R_N")
	)
	(segment
		(start 396.034006 -30.438598)
		(end 396.251684 -30.656276)
		(width 0.10795)
		(layer "B.Cu")
		(net "RST_BMC_SYSRST_BTN_OUT_B_R_N")
	)
	(segment
		(start 396.670022 -32.907732)
		(end 396.670022 -34.562796)
		(width 0.10795)
		(layer "B.Cu")
		(net "RST_BMC_SYSRST_BTN_OUT_B_R_N")
	)
	(segment
		(start 396.253208 -36.133786)
		(end 396.253208 -35.786822)
		(width 0.10795)
		(layer "B.Cu")
		(net "RST_BMC_SYSRST_BTN_OUT_B_R_N")
	)
	(segment
		(start 394.805408 -30.353)
		(end 395.598396 -30.353)
		(width 0.10795)
		(layer "B.Cu")
		(net "RST_BMC_SYSRST_BTN_OUT_B_R_N")
	)
	(segment
		(start 396.670022 -35.262058)
		(end 396.670022 -34.562796)
		(width 0.10795)
		(layer "B.Cu")
		(net "RST_BMC_SYSRST_BTN_OUT_B_R_N")
	)
	(segment
		(start 396.281402 -31.036006)
		(end 396.217902 -31.099506)
		(width 0.10795)
		(layer "B.Cu")
		(net "RST_BMC_SYSRST_BTN_OUT_B_R_N")
	)
	(segment
		(start 395.598396 -30.353)
		(end 395.683994 -30.438598)
		(width 0.10795)
		(layer "B.Cu")
		(net "RST_BMC_SYSRST_BTN_OUT_B_R_N")
	)
	(segment
		(start 394.3096 -37.0586)
		(end 393.550902 -37.0586)
		(width 0.10795)
		(layer "B.Cu")
		(net "RST_BMC_SYSRST_BTN_OUT_B_R_N")
	)
	(segment
		(start 393.474702 -37.1348)
		(end 393.0396 -37.1348)
		(width 0.10795)
		(layer "B.Cu")
		(net "RST_BMC_SYSRST_BTN_OUT_B_R_N")
	)
	(segment
		(start 394.589 -29.845)
		(end 394.589 -30.136592)
		(width 0.10795)
		(layer "B.Cu")
		(net "RST_BMC_SYSRST_BTN_OUT_B_R_N")
	)
	(segment
		(start 396.251684 -30.95117)
		(end 396.281402 -30.980888)
		(width 0.10795)
		(layer "B.Cu")
		(net "RST_BMC_SYSRST_BTN_OUT_B_R_N")
	)
	(segment
		(start 396.253208 -35.786822)
		(end 396.623286 -35.416744)
		(width 0.10795)
		(layer "B.Cu")
		(net "RST_BMC_SYSRST_BTN_OUT_B_R_N")
	)
	(segment
		(start 468.827612 -128.366012)
		(end 470.282016 -128.366012)
		(width 0.10795)
		(layer "F.Cu")
		(net "PWRGD_CPU0_G_R")
	)
	(segment
		(start 468.0458 -127.5842)
		(end 468.827612 -128.366012)
		(width 0.10795)
		(layer "F.Cu")
		(net "PWRGD_CPU0_G_R")
	)
	(segment
		(start 467.0806 -127.5842)
		(end 468.0458 -127.5842)
		(width 0.10795)
		(layer "F.Cu")
		(net "PWRGD_CPU0_G_R")
	)
	(segment
		(start 371.7417 -92.8243)
		(end 370.4463 -92.8243)
		(width 0.10795)
		(layer "F.Cu")
		(net "XDP_PCH_PWR_DEBUG_N")
	)
	(segment
		(start 372.237 -92.329)
		(end 371.7417 -92.8243)
		(width 0.10795)
		(layer "F.Cu")
		(net "XDP_PCH_PWR_DEBUG_N")
	)
	(segment
		(start 372.237 -91.7702)
		(end 372.237 -92.329)
		(width 0.10795)
		(layer "F.Cu")
		(net "XDP_PCH_PWR_DEBUG_N")
	)
	(segment
		(start 371.841268 -91.374468)
		(end 372.237 -91.7702)
		(width 0.10795)
		(layer "F.Cu")
		(net "XDP_PCH_PWR_DEBUG_N")
	)
	(segment
		(start 377.33605 -99.55276)
		(end 376.902472 -99.119182)
		(width 0.10795)
		(layer "F.Cu")
		(net "XDP_PCH_PWR_DEBUG_N")
	)
	(segment
		(start 370.444014 -92.826586)
		(end 370.4463 -92.8243)
		(width 0.10795)
		(layer "F.Cu")
		(net "XDP_PCH_PWR_DEBUG_N")
	)
	(segment
		(start 369.2652 -92.826586)
		(end 370.444014 -92.826586)
		(width 0.10795)
		(layer "F.Cu")
		(net "XDP_PCH_PWR_DEBUG_N")
	)
	(via
		(at 376.902472 -99.119182)
		(size 0.508)
		(drill 0.254)
		(layers "F.Cu" "B.Cu")
		(net "XDP_PCH_PWR_DEBUG_N")
	)
	(via
		(at 371.841268 -91.374468)
		(size 0.508)
		(drill 0.254)
		(layers "F.Cu" "B.Cu")
		(net "XDP_PCH_PWR_DEBUG_N")
	)
	(segment
		(start 373.044212 -93.573092)
		(end 373.04472 -93.5736)
		(width 0.089408)
		(layer "In11.Cu")
		(net "XDP_PCH_PWR_DEBUG_N")
	)
	(segment
		(start 372.922292 -93.573092)
		(end 373.044212 -93.573092)
		(width 0.089408)
		(layer "In11.Cu")
		(net "XDP_PCH_PWR_DEBUG_N")
	)
	(segment
		(start 372.076726 -91.609926)
		(end 372.076726 -92.484702)
		(width 0.089408)
		(layer "In11.Cu")
		(net "XDP_PCH_PWR_DEBUG_N")
	)
	(segment
		(start 374.1166 -93.5736)
		(end 375.399808 -94.856808)
		(width 0.089408)
		(layer "In11.Cu")
		(net "XDP_PCH_PWR_DEBUG_N")
	)
	(segment
		(start 373.04472 -93.5736)
		(end 374.1166 -93.5736)
		(width 0.089408)
		(layer "In11.Cu")
		(net "XDP_PCH_PWR_DEBUG_N")
	)
	(segment
		(start 375.399808 -98.285808)
		(end 376.233182 -99.119182)
		(width 0.089408)
		(layer "In11.Cu")
		(net "XDP_PCH_PWR_DEBUG_N")
	)
	(segment
		(start 372.076726 -92.484702)
		(end 372.076472 -92.484956)
		(width 0.089408)
		(layer "In11.Cu")
		(net "XDP_PCH_PWR_DEBUG_N")
	)
	(segment
		(start 375.399808 -94.856808)
		(end 375.399808 -98.285808)
		(width 0.089408)
		(layer "In11.Cu")
		(net "XDP_PCH_PWR_DEBUG_N")
	)
	(segment
		(start 372.076472 -92.727272)
		(end 372.922292 -93.573092)
		(width 0.089408)
		(layer "In11.Cu")
		(net "XDP_PCH_PWR_DEBUG_N")
	)
	(segment
		(start 371.841268 -91.374468)
		(end 372.076726 -91.609926)
		(width 0.089408)
		(layer "In11.Cu")
		(net "XDP_PCH_PWR_DEBUG_N")
	)
	(segment
		(start 372.076472 -92.484956)
		(end 372.076472 -92.727272)
		(width 0.089408)
		(layer "In11.Cu")
		(net "XDP_PCH_PWR_DEBUG_N")
	)
	(segment
		(start 376.233182 -99.119182)
		(end 376.902472 -99.119182)
		(width 0.089408)
		(layer "In11.Cu")
		(net "XDP_PCH_PWR_DEBUG_N")
	)
	(segment
		(start 494.000028 -153.849832)
		(end 494.670842 -153.179018)
		(width 0.254)
		(layer "F.Cu")
		(net "P5V_STBY_DGB_FS")
	)
	(segment
		(start 493.329214 -154.520646)
		(end 494.000028 -153.849832)
		(width 0.254)
		(layer "F.Cu")
		(net "P5V_STBY_DGB_FS")
	)
	(segment
		(start 494.000028 -153.849832)
		(end 494.670842 -154.520646)
		(width 0.254)
		(layer "F.Cu")
		(net "P5V_STBY_DGB_FS")
	)
	(segment
		(start 493.329214 -153.179018)
		(end 494.000028 -153.849832)
		(width 0.254)
		(layer "F.Cu")
		(net "P5V_STBY_DGB_FS")
	)
	(via
		(at 490.347 -157.2006)
		(size 0.508)
		(drill 0.254)
		(layers "F.Cu" "B.Cu")
		(net "P5V_STBY_DGB_FS")
	)
	(via
		(at 490.347 -156.4894)
		(size 0.508)
		(drill 0.254)
		(layers "F.Cu" "B.Cu")
		(net "P5V_STBY_DGB_FS")
	)
	(via
		(at 486.283 -155.8544)
		(size 0.6604)
		(drill 0.3302)
		(layers "F.Cu" "B.Cu")
		(net "P5V_STBY_DGB_FS")
	)
	(segment
		(start 494.000028 -153.849832)
		(end 494.670842 -154.520646)
		(width 0.254)
		(layer "B.Cu")
		(net "P5V_STBY_DGB_FS")
	)
	(segment
		(start 493.329214 -154.520646)
		(end 494.000028 -153.849832)
		(width 0.254)
		(layer "B.Cu")
		(net "P5V_STBY_DGB_FS")
	)
	(via
		(at 24.13 -80.0862)
		(size 0.6604)
		(drill 0.3302)
		(layers "F.Cu" "B.Cu")
		(net "A_HSC_INAP")
	)
	(segment
		(start 23.44674 -80.645)
		(end 24.00554 -80.0862)
		(width 0.254)
		(layer "B.Cu")
		(net "A_HSC_INAP")
	)
	(segment
		(start 23.114 -79.502)
		(end 23.114 -80.645)
		(width 0.254)
		(layer "B.Cu")
		(net "A_HSC_INAP")
	)
	(segment
		(start 24.2316 -80.0862)
		(end 24.7904 -80.645)
		(width 0.254)
		(layer "B.Cu")
		(net "A_HSC_INAP")
	)
	(segment
		(start 24.13 -80.0862)
		(end 24.2316 -80.0862)
		(width 0.254)
		(layer "B.Cu")
		(net "A_HSC_INAP")
	)
	(segment
		(start 24.00554 -80.0862)
		(end 24.13 -80.0862)
		(width 0.254)
		(layer "B.Cu")
		(net "A_HSC_INAP")
	)
	(segment
		(start 24.7904 -80.645)
		(end 25.009602 -80.645)
		(width 0.254)
		(layer "B.Cu")
		(net "A_HSC_INAP")
	)
	(segment
		(start 23.114 -80.645)
		(end 23.44674 -80.645)
		(width 0.254)
		(layer "B.Cu")
		(net "A_HSC_INAP")
	)
	(segment
		(start 375.944892 -68.695316)
		(end 375.545096 -69.095112)
		(width 0.1016)
		(layer "F.Cu")
		(net "PWRGD_P12V_MAIN")
	)
	(via
		(at 404.54961 -17.987518)
		(size 0.508)
		(drill 0.254)
		(layers "F.Cu" "B.Cu")
		(net "PWRGD_P12V_MAIN")
	)
	(via
		(at 375.944892 -68.695316)
		(size 0.4572)
		(drill 0.2032)
		(layers "F.Cu" "B.Cu")
		(net "PWRGD_P12V_MAIN")
	)
	(via
		(at 407.3906 -10.4902)
		(size 0.6604)
		(drill 0.3302)
		(layers "F.Cu" "B.Cu")
		(net "PWRGD_P12V_MAIN")
	)
	(segment
		(start 409.8417 -9.613646)
		(end 409.8417 -8.8138)
		(width 0.10795)
		(layer "B.Cu")
		(net "PWRGD_P12V_MAIN")
	)
	(segment
		(start 405.367998 -16.79829)
		(end 405.367998 -13.058902)
		(width 0.10795)
		(layer "B.Cu")
		(net "PWRGD_P12V_MAIN")
	)
	(segment
		(start 404.54961 -17.616678)
		(end 405.367998 -16.79829)
		(width 0.10795)
		(layer "B.Cu")
		(net "PWRGD_P12V_MAIN")
	)
	(segment
		(start 405.367998 -13.058902)
		(end 407.3906 -11.0363)
		(width 0.10795)
		(layer "B.Cu")
		(net "PWRGD_P12V_MAIN")
	)
	(segment
		(start 407.3906 -11.0363)
		(end 407.3906 -10.4902)
		(width 0.10795)
		(layer "B.Cu")
		(net "PWRGD_P12V_MAIN")
	)
	(segment
		(start 407.5557 -10.3251)
		(end 409.130246 -10.3251)
		(width 0.10795)
		(layer "B.Cu")
		(net "PWRGD_P12V_MAIN")
	)
	(segment
		(start 407.3906 -10.4902)
		(end 407.5557 -10.3251)
		(width 0.10795)
		(layer "B.Cu")
		(net "PWRGD_P12V_MAIN")
	)
	(segment
		(start 409.130246 -10.3251)
		(end 409.8417 -9.613646)
		(width 0.10795)
		(layer "B.Cu")
		(net "PWRGD_P12V_MAIN")
	)
	(segment
		(start 404.54961 -17.987518)
		(end 404.54961 -17.616678)
		(width 0.10795)
		(layer "B.Cu")
		(net "PWRGD_P12V_MAIN")
	)
	(segment
		(start 402.125688 -18.159222)
		(end 402.476716 -18.51025)
		(width 0.089408)
		(layer "In9.Cu")
		(net "PWRGD_P12V_MAIN")
	)
	(segment
		(start 379.055884 -40.90924)
		(end 379.055884 -40.30218)
		(width 0.089408)
		(layer "In9.Cu")
		(net "PWRGD_P12V_MAIN")
	)
	(segment
		(start 381.066294 -56.911748)
		(end 380.898146 -56.7436)
		(width 0.089408)
		(layer "In9.Cu")
		(net "PWRGD_P12V_MAIN")
	)
	(segment
		(start 385.84886 -19.57324)
		(end 386.333492 -19.57324)
		(width 0.089408)
		(layer "In9.Cu")
		(net "PWRGD_P12V_MAIN")
	)
	(segment
		(start 379.475238 -39.882826)
		(end 380.33198 -39.882826)
		(width 0.089408)
		(layer "In9.Cu")
		(net "PWRGD_P12V_MAIN")
	)
	(segment
		(start 396.69212 -18.155666)
		(end 398.343374 -18.155666)
		(width 0.089408)
		(layer "In9.Cu")
		(net "PWRGD_P12V_MAIN")
	)
	(segment
		(start 401.764754 -17.031208)
		(end 402.125688 -17.392142)
		(width 0.089408)
		(layer "In9.Cu")
		(net "PWRGD_P12V_MAIN")
	)
	(segment
		(start 376.535696 -66.776346)
		(end 376.535696 -65.043812)
		(width 0.089408)
		(layer "In9.Cu")
		(net "PWRGD_P12V_MAIN")
	)
	(segment
		(start 382.38049 -32.627824)
		(end 382.38049 -27.142694)
		(width 0.089408)
		(layer "In9.Cu")
		(net "PWRGD_P12V_MAIN")
	)
	(segment
		(start 385.313174 -21.183092)
		(end 385.313174 -20.623276)
		(width 0.089408)
		(layer "In9.Cu")
		(net "PWRGD_P12V_MAIN")
	)
	(segment
		(start 383.664714 -25.85847)
		(end 384.30708 -25.85847)
		(width 0.089408)
		(layer "In9.Cu")
		(net "PWRGD_P12V_MAIN")
	)
	(segment
		(start 381.066294 -57.367678)
		(end 381.066294 -56.911748)
		(width 0.089408)
		(layer "In9.Cu")
		(net "PWRGD_P12V_MAIN")
	)
	(segment
		(start 402.125688 -17.392142)
		(end 402.125688 -18.159222)
		(width 0.089408)
		(layer "In9.Cu")
		(net "PWRGD_P12V_MAIN")
	)
	(segment
		(start 381.00254 -34.54146)
		(end 381.635508 -34.54146)
		(width 0.089408)
		(layer "In9.Cu")
		(net "PWRGD_P12V_MAIN")
	)
	(segment
		(start 394.883894 -19.963892)
		(end 396.69212 -18.155666)
		(width 0.089408)
		(layer "In9.Cu")
		(net "PWRGD_P12V_MAIN")
	)
	(segment
		(start 402.476716 -18.51025)
		(end 404.026878 -18.51025)
		(width 0.089408)
		(layer "In9.Cu")
		(net "PWRGD_P12V_MAIN")
	)
	(segment
		(start 379.38075 -59.053222)
		(end 381.066294 -57.367678)
		(width 0.089408)
		(layer "In9.Cu")
		(net "PWRGD_P12V_MAIN")
	)
	(segment
		(start 392.673078 -19.963892)
		(end 394.883894 -19.963892)
		(width 0.089408)
		(layer "In9.Cu")
		(net "PWRGD_P12V_MAIN")
	)
	(segment
		(start 385.501642 -21.37156)
		(end 385.313174 -21.183092)
		(width 0.089408)
		(layer "In9.Cu")
		(net "PWRGD_P12V_MAIN")
	)
	(segment
		(start 375.571512 -67.74053)
		(end 376.535696 -66.776346)
		(width 0.089408)
		(layer "In9.Cu")
		(net "PWRGD_P12V_MAIN")
	)
	(segment
		(start 382.236726 -32.771588)
		(end 382.38049 -32.627824)
		(width 0.089408)
		(layer "In9.Cu")
		(net "PWRGD_P12V_MAIN")
	)
	(segment
		(start 380.613412 -39.601394)
		(end 380.613412 -37.309806)
		(width 0.089408)
		(layer "In9.Cu")
		(net "PWRGD_P12V_MAIN")
	)
	(segment
		(start 380.362714 -35.181286)
		(end 381.00254 -34.54146)
		(width 0.089408)
		(layer "In9.Cu")
		(net "PWRGD_P12V_MAIN")
	)
	(segment
		(start 385.666996 -24.498554)
		(end 385.666996 -22.867366)
		(width 0.089408)
		(layer "In9.Cu")
		(net "PWRGD_P12V_MAIN")
	)
	(segment
		(start 387.604 -21.553424)
		(end 387.71068 -21.660104)
		(width 0.089408)
		(layer "In9.Cu")
		(net "PWRGD_P12V_MAIN")
	)
	(segment
		(start 377.190762 -64.770508)
		(end 377.47194 -64.48933)
		(width 0.089408)
		(layer "In9.Cu")
		(net "PWRGD_P12V_MAIN")
	)
	(segment
		(start 376.535696 -65.043812)
		(end 376.809 -64.770508)
		(width 0.089408)
		(layer "In9.Cu")
		(net "PWRGD_P12V_MAIN")
	)
	(segment
		(start 390.976866 -21.660104)
		(end 392.673078 -19.963892)
		(width 0.089408)
		(layer "In9.Cu")
		(net "PWRGD_P12V_MAIN")
	)
	(segment
		(start 381.380238 -43.999404)
		(end 381.367792 -43.986958)
		(width 0.089408)
		(layer "In9.Cu")
		(net "PWRGD_P12V_MAIN")
	)
	(segment
		(start 398.849088 -17.649952)
		(end 400.094704 -17.649952)
		(width 0.089408)
		(layer "In9.Cu")
		(net "PWRGD_P12V_MAIN")
	)
	(segment
		(start 378.872496 -41.491662)
		(end 378.872496 -41.092628)
		(width 0.089408)
		(layer "In9.Cu")
		(net "PWRGD_P12V_MAIN")
	)
	(segment
		(start 380.16688 -46.771814)
		(end 381.380238 -45.558456)
		(width 0.089408)
		(layer "In9.Cu")
		(net "PWRGD_P12V_MAIN")
	)
	(segment
		(start 400.094704 -17.649952)
		(end 400.51482 -17.229836)
		(width 0.089408)
		(layer "In9.Cu")
		(net "PWRGD_P12V_MAIN")
	)
	(segment
		(start 378.571252 -62.532514)
		(end 379.38075 -61.723016)
		(width 0.089408)
		(layer "In9.Cu")
		(net "PWRGD_P12V_MAIN")
	)
	(segment
		(start 385.759452 -20.176998)
		(end 385.759452 -19.662648)
		(width 0.089408)
		(layer "In9.Cu")
		(net "PWRGD_P12V_MAIN")
	)
	(segment
		(start 385.759452 -19.662648)
		(end 385.84886 -19.57324)
		(width 0.089408)
		(layer "In9.Cu")
		(net "PWRGD_P12V_MAIN")
	)
	(segment
		(start 404.026878 -18.51025)
		(end 404.54961 -17.987518)
		(width 0.089408)
		(layer "In9.Cu")
		(net "PWRGD_P12V_MAIN")
	)
	(segment
		(start 378.571252 -63.05296)
		(end 378.571252 -62.532514)
		(width 0.089408)
		(layer "In9.Cu")
		(net "PWRGD_P12V_MAIN")
	)
	(segment
		(start 381.367792 -43.968162)
		(end 379.125734 -41.726104)
		(width 0.089408)
		(layer "In9.Cu")
		(net "PWRGD_P12V_MAIN")
	)
	(segment
		(start 379.125734 -41.726104)
		(end 379.106938 -41.726104)
		(width 0.089408)
		(layer "In9.Cu")
		(net "PWRGD_P12V_MAIN")
	)
	(segment
		(start 401.448778 -17.031208)
		(end 401.764754 -17.031208)
		(width 0.089408)
		(layer "In9.Cu")
		(net "PWRGD_P12V_MAIN")
	)
	(segment
		(start 380.898146 -51.838352)
		(end 380.16688 -51.107086)
		(width 0.089408)
		(layer "In9.Cu")
		(net "PWRGD_P12V_MAIN")
	)
	(segment
		(start 380.16688 -51.107086)
		(end 380.16688 -46.771814)
		(width 0.089408)
		(layer "In9.Cu")
		(net "PWRGD_P12V_MAIN")
	)
	(segment
		(start 386.615432 -20.710144)
		(end 387.458712 -21.553424)
		(width 0.089408)
		(layer "In9.Cu")
		(net "PWRGD_P12V_MAIN")
	)
	(segment
		(start 381.635508 -34.54146)
		(end 382.236726 -33.940242)
		(width 0.089408)
		(layer "In9.Cu")
		(net "PWRGD_P12V_MAIN")
	)
	(segment
		(start 377.47194 -64.152272)
		(end 378.571252 -63.05296)
		(width 0.089408)
		(layer "In9.Cu")
		(net "PWRGD_P12V_MAIN")
	)
	(segment
		(start 387.458712 -21.553424)
		(end 387.604 -21.553424)
		(width 0.089408)
		(layer "In9.Cu")
		(net "PWRGD_P12V_MAIN")
	)
	(segment
		(start 380.33198 -39.882826)
		(end 380.613412 -39.601394)
		(width 0.089408)
		(layer "In9.Cu")
		(net "PWRGD_P12V_MAIN")
	)
	(segment
		(start 377.47194 -64.48933)
		(end 377.47194 -64.152272)
		(width 0.089408)
		(layer "In9.Cu")
		(net "PWRGD_P12V_MAIN")
	)
	(segment
		(start 379.106938 -41.726104)
		(end 378.872496 -41.491662)
		(width 0.089408)
		(layer "In9.Cu")
		(net "PWRGD_P12V_MAIN")
	)
	(segment
		(start 379.38075 -61.723016)
		(end 379.38075 -59.053222)
		(width 0.089408)
		(layer "In9.Cu")
		(net "PWRGD_P12V_MAIN")
	)
	(segment
		(start 378.872496 -41.092628)
		(end 379.055884 -40.90924)
		(width 0.089408)
		(layer "In9.Cu")
		(net "PWRGD_P12V_MAIN")
	)
	(segment
		(start 386.615432 -19.85518)
		(end 386.615432 -20.710144)
		(width 0.089408)
		(layer "In9.Cu")
		(net "PWRGD_P12V_MAIN")
	)
	(segment
		(start 385.666996 -22.867366)
		(end 385.501642 -22.702012)
		(width 0.089408)
		(layer "In9.Cu")
		(net "PWRGD_P12V_MAIN")
	)
	(segment
		(start 384.30708 -25.85847)
		(end 385.666996 -24.498554)
		(width 0.089408)
		(layer "In9.Cu")
		(net "PWRGD_P12V_MAIN")
	)
	(segment
		(start 381.367792 -43.986958)
		(end 381.367792 -43.968162)
		(width 0.089408)
		(layer "In9.Cu")
		(net "PWRGD_P12V_MAIN")
	)
	(segment
		(start 380.613412 -37.309806)
		(end 380.362714 -37.059108)
		(width 0.089408)
		(layer "In9.Cu")
		(net "PWRGD_P12V_MAIN")
	)
	(segment
		(start 398.343374 -18.155666)
		(end 398.849088 -17.649952)
		(width 0.089408)
		(layer "In9.Cu")
		(net "PWRGD_P12V_MAIN")
	)
	(segment
		(start 380.898146 -56.7436)
		(end 380.898146 -51.838352)
		(width 0.089408)
		(layer "In9.Cu")
		(net "PWRGD_P12V_MAIN")
	)
	(segment
		(start 381.380238 -45.558456)
		(end 381.380238 -43.999404)
		(width 0.089408)
		(layer "In9.Cu")
		(net "PWRGD_P12V_MAIN")
	)
	(segment
		(start 382.236726 -33.940242)
		(end 382.236726 -32.771588)
		(width 0.089408)
		(layer "In9.Cu")
		(net "PWRGD_P12V_MAIN")
	)
	(segment
		(start 375.944892 -68.695316)
		(end 375.571512 -68.321936)
		(width 0.089408)
		(layer "In9.Cu")
		(net "PWRGD_P12V_MAIN")
	)
	(segment
		(start 400.51482 -17.229836)
		(end 401.448778 -17.031208)
		(width 0.089408)
		(layer "In9.Cu")
		(net "PWRGD_P12V_MAIN")
	)
	(segment
		(start 387.71068 -21.660104)
		(end 390.976866 -21.660104)
		(width 0.089408)
		(layer "In9.Cu")
		(net "PWRGD_P12V_MAIN")
	)
	(segment
		(start 376.809 -64.770508)
		(end 377.190762 -64.770508)
		(width 0.089408)
		(layer "In9.Cu")
		(net "PWRGD_P12V_MAIN")
	)
	(segment
		(start 380.362714 -37.059108)
		(end 380.362714 -35.181286)
		(width 0.089408)
		(layer "In9.Cu")
		(net "PWRGD_P12V_MAIN")
	)
	(segment
		(start 382.38049 -27.142694)
		(end 383.664714 -25.85847)
		(width 0.089408)
		(layer "In9.Cu")
		(net "PWRGD_P12V_MAIN")
	)
	(segment
		(start 386.333492 -19.57324)
		(end 386.615432 -19.85518)
		(width 0.089408)
		(layer "In9.Cu")
		(net "PWRGD_P12V_MAIN")
	)
	(segment
		(start 385.501642 -22.702012)
		(end 385.501642 -21.37156)
		(width 0.089408)
		(layer "In9.Cu")
		(net "PWRGD_P12V_MAIN")
	)
	(segment
		(start 385.313174 -20.623276)
		(end 385.759452 -20.176998)
		(width 0.089408)
		(layer "In9.Cu")
		(net "PWRGD_P12V_MAIN")
	)
	(segment
		(start 375.571512 -68.321936)
		(end 375.571512 -67.74053)
		(width 0.089408)
		(layer "In9.Cu")
		(net "PWRGD_P12V_MAIN")
	)
	(segment
		(start 379.055884 -40.30218)
		(end 379.475238 -39.882826)
		(width 0.089408)
		(layer "In9.Cu")
		(net "PWRGD_P12V_MAIN")
	)
	(segment
		(start 410.290264 -32.934656)
		(end 409.890214 -32.534606)
		(width 0.10795)
		(layer "F.Cu")
		(net "RMII_BMC_OCP_TXEN_R")
	)
	(via
		(at 409.890214 -32.534606)
		(size 0.4572)
		(drill 0.2032)
		(layers "F.Cu" "B.Cu")
		(net "RMII_BMC_OCP_TXEN_R")
	)
	(segment
		(start 407.654506 -32.661352)
		(end 407.91638 -32.661352)
		(width 0.10795)
		(layer "B.Cu")
		(net "RMII_BMC_OCP_TXEN_R")
	)
	(segment
		(start 408.700732 -31.877)
		(end 408.700732 -31.562548)
		(width 0.10795)
		(layer "B.Cu")
		(net "RMII_BMC_OCP_TXEN_R")
	)
	(segment
		(start 408.922474 -31.340806)
		(end 409.292044 -31.340806)
		(width 0.10795)
		(layer "B.Cu")
		(net "RMII_BMC_OCP_TXEN_R")
	)
	(segment
		(start 409.484576 -31.533338)
		(end 409.484576 -31.923482)
		(width 0.10795)
		(layer "B.Cu")
		(net "RMII_BMC_OCP_TXEN_R")
	)
	(segment
		(start 409.292044 -31.340806)
		(end 409.484576 -31.533338)
		(width 0.10795)
		(layer "B.Cu")
		(net "RMII_BMC_OCP_TXEN_R")
	)
	(segment
		(start 407.91638 -32.661352)
		(end 408.700732 -31.877)
		(width 0.10795)
		(layer "B.Cu")
		(net "RMII_BMC_OCP_TXEN_R")
	)
	(segment
		(start 409.484576 -31.923482)
		(end 409.890214 -32.32912)
		(width 0.10795)
		(layer "B.Cu")
		(net "RMII_BMC_OCP_TXEN_R")
	)
	(segment
		(start 409.890214 -32.32912)
		(end 409.890214 -32.534606)
		(width 0.10795)
		(layer "B.Cu")
		(net "RMII_BMC_OCP_TXEN_R")
	)
	(segment
		(start 408.700732 -31.562548)
		(end 408.922474 -31.340806)
		(width 0.10795)
		(layer "B.Cu")
		(net "RMII_BMC_OCP_TXEN_R")
	)
	(segment
		(start 379.31725 -97.83572)
		(end 379.81255 -97.605596)
		(width 0.10795)
		(layer "F.Cu")
		(net "RST_BMC_SRST_R_N")
	)
	(via
		(at 379.81255 -97.605596)
		(size 0.508)
		(drill 0.254)
		(layers "F.Cu" "B.Cu")
		(net "RST_BMC_SRST_R_N")
	)
	(via
		(at 374.555004 -92.079318)
		(size 0.6604)
		(drill 0.3302)
		(layers "F.Cu" "B.Cu")
		(net "RST_BMC_SRST_R_N")
	)
	(segment
		(start 379.336046 -95.375984)
		(end 379.4125 -95.452438)
		(width 0.0889)
		(layer "B.Cu")
		(net "RST_BMC_SRST_R_N")
	)
	(segment
		(start 374.932448 -92.456762)
		(end 374.932448 -93.174058)
		(width 0.10795)
		(layer "B.Cu")
		(net "RST_BMC_SRST_R_N")
	)
	(segment
		(start 379.66777 -97.223072)
		(end 379.64364 -97.31248)
		(width 0.0889)
		(layer "B.Cu")
		(net "RST_BMC_SRST_R_N")
	)
	(segment
		(start 376.153172 -93.276166)
		(end 376.57024 -93.693234)
		(width 0.10795)
		(layer "B.Cu")
		(net "RST_BMC_SRST_R_N")
	)
	(segment
		(start 373.662448 -90.952574)
		(end 373.662448 -90.955622)
		(width 0.10795)
		(layer "B.Cu")
		(net "RST_BMC_SRST_R_N")
	)
	(segment
		(start 373.4308 -90.805)
		(end 373.507 -90.805)
		(width 0.10795)
		(layer "B.Cu")
		(net "RST_BMC_SRST_R_N")
	)
	(segment
		(start 373.4308 -90.586814)
		(end 373.4308 -90.805)
		(width 0.10795)
		(layer "B.Cu")
		(net "RST_BMC_SRST_R_N")
	)
	(segment
		(start 377.55195 -94.253812)
		(end 378.213874 -94.253812)
		(width 0.10795)
		(layer "B.Cu")
		(net "RST_BMC_SRST_R_N")
	)
	(segment
		(start 373.156734 -90.312748)
		(end 373.4308 -90.586814)
		(width 0.10795)
		(layer "B.Cu")
		(net "RST_BMC_SRST_R_N")
	)
	(segment
		(start 373.662448 -90.955622)
		(end 374.555004 -91.848178)
		(width 0.10795)
		(layer "B.Cu")
		(net "RST_BMC_SRST_R_N")
	)
	(segment
		(start 376.991372 -93.693234)
		(end 377.55195 -94.253812)
		(width 0.10795)
		(layer "B.Cu")
		(net "RST_BMC_SRST_R_N")
	)
	(segment
		(start 369.078256 -92.100654)
		(end 369.082828 -92.096082)
		(width 0.10795)
		(layer "B.Cu")
		(net "RST_BMC_SRST_R_N")
	)
	(segment
		(start 379.9078 -96.725486)
		(end 379.9078 -96.768666)
		(width 0.0889)
		(layer "B.Cu")
		(net "RST_BMC_SRST_R_N")
	)
	(segment
		(start 376.57024 -93.693234)
		(end 376.991372 -93.693234)
		(width 0.10795)
		(layer "B.Cu")
		(net "RST_BMC_SRST_R_N")
	)
	(segment
		(start 379.64364 -97.31248)
		(end 379.81255 -97.605596)
		(width 0.0889)
		(layer "B.Cu")
		(net "RST_BMC_SRST_R_N")
	)
	(segment
		(start 370.233702 -92.096082)
		(end 370.463318 -91.866466)
		(width 0.10795)
		(layer "B.Cu")
		(net "RST_BMC_SRST_R_N")
	)
	(segment
		(start 371.537738 -90.312748)
		(end 373.156734 -90.312748)
		(width 0.10795)
		(layer "B.Cu")
		(net "RST_BMC_SRST_R_N")
	)
	(segment
		(start 375.034556 -93.276166)
		(end 376.153172 -93.276166)
		(width 0.10795)
		(layer "B.Cu")
		(net "RST_BMC_SRST_R_N")
	)
	(segment
		(start 378.213874 -94.253812)
		(end 379.336046 -95.375984)
		(width 0.10795)
		(layer "B.Cu")
		(net "RST_BMC_SRST_R_N")
	)
	(segment
		(start 373.660924 -90.95105)
		(end 373.662448 -90.952574)
		(width 0.10795)
		(layer "B.Cu")
		(net "RST_BMC_SRST_R_N")
	)
	(segment
		(start 369.082828 -92.096082)
		(end 370.233702 -92.096082)
		(width 0.10795)
		(layer "B.Cu")
		(net "RST_BMC_SRST_R_N")
	)
	(segment
		(start 374.555004 -91.848178)
		(end 374.555004 -92.079318)
		(width 0.10795)
		(layer "B.Cu")
		(net "RST_BMC_SRST_R_N")
	)
	(segment
		(start 379.4125 -95.452438)
		(end 379.4125 -95.899732)
		(width 0.0889)
		(layer "B.Cu")
		(net "RST_BMC_SRST_R_N")
	)
	(segment
		(start 373.507 -90.805)
		(end 373.65305 -90.95105)
		(width 0.10795)
		(layer "B.Cu")
		(net "RST_BMC_SRST_R_N")
	)
	(segment
		(start 370.463318 -91.387168)
		(end 371.537738 -90.312748)
		(width 0.10795)
		(layer "B.Cu")
		(net "RST_BMC_SRST_R_N")
	)
	(segment
		(start 374.555004 -92.079318)
		(end 374.932448 -92.456762)
		(width 0.10795)
		(layer "B.Cu")
		(net "RST_BMC_SRST_R_N")
	)
	(segment
		(start 373.65305 -90.95105)
		(end 373.660924 -90.95105)
		(width 0.10795)
		(layer "B.Cu")
		(net "RST_BMC_SRST_R_N")
	)
	(segment
		(start 370.463318 -91.866466)
		(end 370.463318 -91.387168)
		(width 0.10795)
		(layer "B.Cu")
		(net "RST_BMC_SRST_R_N")
	)
	(segment
		(start 374.932448 -93.174058)
		(end 375.034556 -93.276166)
		(width 0.10795)
		(layer "B.Cu")
		(net "RST_BMC_SRST_R_N")
	)
	(arc
		(start 379.9078 -96.768666)
		(mid 379.839771 -97.023331)
		(end 379.66777 -97.223072)
		(width 0.0889)
		(layer "B.Cu")
		(net "RST_BMC_SRST_R_N")
	)
	(arc
		(start 379.4125 -95.899732)
		(mid 379.46885 -96.093582)
		(end 379.612652 -96.235266)
		(width 0.0889)
		(layer "B.Cu")
		(net "RST_BMC_SRST_R_N")
	)
	(arc
		(start 379.612652 -96.235266)
		(mid 379.823516 -96.44227)
		(end 379.9078 -96.725486)
		(width 0.0889)
		(layer "B.Cu")
		(net "RST_BMC_SRST_R_N")
	)
	(via
		(at 390.4361 -58.226452)
		(size 0.6604)
		(drill 0.3302)
		(layers "F.Cu" "B.Cu")
		(net "SPI_SWITCH_MOSI_R1")
	)
	(segment
		(start 390.4361 -58.226452)
		(end 390.083802 -58.57875)
		(width 0.10795)
		(layer "B.Cu")
		(net "SPI_SWITCH_MOSI_R1")
	)
	(segment
		(start 390.083802 -58.57875)
		(end 388.346188 -58.57875)
		(width 0.10795)
		(layer "B.Cu")
		(net "SPI_SWITCH_MOSI_R1")
	)
	(segment
		(start 390.61136 -55.941214)
		(end 390.61136 -58.051192)
		(width 0.10795)
		(layer "B.Cu")
		(net "SPI_SWITCH_MOSI_R1")
	)
	(segment
		(start 390.61136 -58.051192)
		(end 390.4361 -58.226452)
		(width 0.10795)
		(layer "B.Cu")
		(net "SPI_SWITCH_MOSI_R1")
	)
	(segment
		(start 388.657846 -54.84368)
		(end 389.513826 -54.84368)
		(width 0.10795)
		(layer "B.Cu")
		(net "SPI_SWITCH_MOSI_R1")
	)
	(segment
		(start 389.513826 -54.84368)
		(end 390.61136 -55.941214)
		(width 0.10795)
		(layer "B.Cu")
		(net "SPI_SWITCH_MOSI_R1")
	)
	(segment
		(start 388.72795 -49.0982)
		(end 389.7376 -49.0982)
		(width 0.10795)
		(layer "F.Cu")
		(net "SPI_SWITCH_MOSI_R0")
	)
	(segment
		(start 389.8773 -50.311812)
		(end 390.035288 -50.4698)
		(width 0.10795)
		(layer "F.Cu")
		(net "SPI_SWITCH_MOSI_R0")
	)
	(segment
		(start 390.9568 -51.4858)
		(end 390.779 -51.6636)
		(width 0.10795)
		(layer "F.Cu")
		(net "SPI_SWITCH_MOSI_R0")
	)
	(segment
		(start 390.259062 -50.4698)
		(end 390.41705 -50.311812)
		(width 0.10795)
		(layer "F.Cu")
		(net "SPI_SWITCH_MOSI_R0")
	)
	(segment
		(start 388.543546 -48.49368)
		(end 388.543546 -48.913796)
		(width 0.10795)
		(layer "F.Cu")
		(net "SPI_SWITCH_MOSI_R0")
	)
	(segment
		(start 390.798812 -48.6918)
		(end 390.9568 -48.849788)
		(width 0.10795)
		(layer "F.Cu")
		(net "SPI_SWITCH_MOSI_R0")
	)
	(segment
		(start 389.7376 -49.0982)
		(end 389.8773 -49.2379)
		(width 0.10795)
		(layer "F.Cu")
		(net "SPI_SWITCH_MOSI_R0")
	)
	(segment
		(start 388.543546 -48.913796)
		(end 388.72795 -49.0982)
		(width 0.10795)
		(layer "F.Cu")
		(net "SPI_SWITCH_MOSI_R0")
	)
	(segment
		(start 390.9568 -48.849788)
		(end 390.9568 -51.4858)
		(width 0.10795)
		(layer "F.Cu")
		(net "SPI_SWITCH_MOSI_R0")
	)
	(segment
		(start 387.39953 -51.6636)
		(end 386.56133 -52.5018)
		(width 0.10795)
		(layer "F.Cu")
		(net "SPI_SWITCH_MOSI_R0")
	)
	(segment
		(start 386.56133 -52.5018)
		(end 385.8768 -52.5018)
		(width 0.10795)
		(layer "F.Cu")
		(net "SPI_SWITCH_MOSI_R0")
	)
	(segment
		(start 390.035288 -50.4698)
		(end 390.259062 -50.4698)
		(width 0.10795)
		(layer "F.Cu")
		(net "SPI_SWITCH_MOSI_R0")
	)
	(segment
		(start 390.575038 -48.6918)
		(end 390.798812 -48.6918)
		(width 0.10795)
		(layer "F.Cu")
		(net "SPI_SWITCH_MOSI_R0")
	)
	(segment
		(start 390.41705 -50.311812)
		(end 390.41705 -48.849788)
		(width 0.10795)
		(layer "F.Cu")
		(net "SPI_SWITCH_MOSI_R0")
	)
	(segment
		(start 389.8773 -49.2379)
		(end 389.8773 -50.311812)
		(width 0.10795)
		(layer "F.Cu")
		(net "SPI_SWITCH_MOSI_R0")
	)
	(segment
		(start 390.41705 -48.849788)
		(end 390.575038 -48.6918)
		(width 0.10795)
		(layer "F.Cu")
		(net "SPI_SWITCH_MOSI_R0")
	)
	(segment
		(start 390.779 -51.6636)
		(end 387.39953 -51.6636)
		(width 0.10795)
		(layer "F.Cu")
		(net "SPI_SWITCH_MOSI_R0")
	)
	(segment
		(start 387.380226 -92.59443)
		(end 387.380226 -91.33586)
		(width 0.0889)
		(layer "F.Cu")
		(net "RMII_PCH_SPRNGVLLE_ARB_OUT_R")
	)
	(segment
		(start 387.484874 -94.427802)
		(end 387.16204 -94.104968)
		(width 0.0889)
		(layer "F.Cu")
		(net "RMII_PCH_SPRNGVLLE_ARB_OUT_R")
	)
	(segment
		(start 387.16204 -94.104968)
		(end 387.16204 -93.842586)
		(width 0.0889)
		(layer "F.Cu")
		(net "RMII_PCH_SPRNGVLLE_ARB_OUT_R")
	)
	(segment
		(start 387.16204 -93.842586)
		(end 387.275832 -93.728794)
		(width 0.0889)
		(layer "F.Cu")
		(net "RMII_PCH_SPRNGVLLE_ARB_OUT_R")
	)
	(segment
		(start 387.484874 -94.790006)
		(end 387.484874 -94.427802)
		(width 0.0889)
		(layer "F.Cu")
		(net "RMII_PCH_SPRNGVLLE_ARB_OUT_R")
	)
	(segment
		(start 387.380226 -91.33586)
		(end 387.285484 -91.241118)
		(width 0.0889)
		(layer "F.Cu")
		(net "RMII_PCH_SPRNGVLLE_ARB_OUT_R")
	)
	(segment
		(start 387.275832 -93.728794)
		(end 387.275832 -92.698824)
		(width 0.0889)
		(layer "F.Cu")
		(net "RMII_PCH_SPRNGVLLE_ARB_OUT_R")
	)
	(segment
		(start 387.275832 -92.698824)
		(end 387.380226 -92.59443)
		(width 0.0889)
		(layer "F.Cu")
		(net "RMII_PCH_SPRNGVLLE_ARB_OUT_R")
	)
	(via
		(at 387.285484 -91.241118)
		(size 0.508)
		(drill 0.254)
		(layers "F.Cu" "B.Cu")
		(net "RMII_PCH_SPRNGVLLE_ARB_OUT_R")
	)
	(via
		(at 387.979412 -89.62644)
		(size 0.6604)
		(drill 0.3302)
		(layers "F.Cu" "B.Cu")
		(net "RMII_PCH_SPRNGVLLE_ARB_OUT_R")
	)
	(segment
		(start 388.586726 -88.663018)
		(end 388.366 -88.442292)
		(width 0.10795)
		(layer "B.Cu")
		(net "RMII_PCH_SPRNGVLLE_ARB_OUT_R")
	)
	(segment
		(start 387.717792 -89.88806)
		(end 387.979412 -89.62644)
		(width 0.10795)
		(layer "B.Cu")
		(net "RMII_PCH_SPRNGVLLE_ARB_OUT_R")
	)
	(segment
		(start 388.108444 -89.62644)
		(end 388.586726 -89.148158)
		(width 0.10795)
		(layer "B.Cu")
		(net "RMII_PCH_SPRNGVLLE_ARB_OUT_R")
	)
	(segment
		(start 387.717792 -90.80881)
		(end 387.717792 -89.88806)
		(width 0.10795)
		(layer "B.Cu")
		(net "RMII_PCH_SPRNGVLLE_ARB_OUT_R")
	)
	(segment
		(start 387.285484 -91.241118)
		(end 387.717792 -90.80881)
		(width 0.10795)
		(layer "B.Cu")
		(net "RMII_PCH_SPRNGVLLE_ARB_OUT_R")
	)
	(segment
		(start 387.979412 -89.62644)
		(end 388.108444 -89.62644)
		(width 0.10795)
		(layer "B.Cu")
		(net "RMII_PCH_SPRNGVLLE_ARB_OUT_R")
	)
	(segment
		(start 388.586726 -89.148158)
		(end 388.586726 -88.663018)
		(width 0.10795)
		(layer "B.Cu")
		(net "RMII_PCH_SPRNGVLLE_ARB_OUT_R")
	)
	(segment
		(start 388.366 -88.442292)
		(end 388.366 -88.2015)
		(width 0.10795)
		(layer "B.Cu")
		(net "RMII_PCH_SPRNGVLLE_ARB_OUT_R")
	)
	(segment
		(start 478.92716 -42.21734)
		(end 478.90811 -42.23639)
		(width 0.10795)
		(layer "F.Cu")
		(net "RMII_PCH_SPRNGVLLE_ARB_IN_R")
	)
	(segment
		(start 479.8822 -42.21734)
		(end 478.92716 -42.21734)
		(width 0.10795)
		(layer "F.Cu")
		(net "RMII_PCH_SPRNGVLLE_ARB_IN_R")
	)
	(segment
		(start 478.90811 -42.23639)
		(end 478.1931 -42.9514)
		(width 0.10795)
		(layer "F.Cu")
		(net "RMII_PCH_SPRNGVLLE_ARB_IN_R")
	)
	(via
		(at 478.90811 -42.23639)
		(size 0.508)
		(drill 0.254)
		(layers "F.Cu" "B.Cu")
		(net "RMII_PCH_SPRNGVLLE_ARB_IN_R")
	)
	(segment
		(start 386.598922 -90.934286)
		(end 386.29971 -91.233498)
		(width 0.10795)
		(layer "F.Cu")
		(net "RMII_BMC_PCH_SPRNGVLLE_RXER_R")
	)
	(segment
		(start 386.578348 -92.615258)
		(end 386.578348 -93.156532)
		(width 0.0889)
		(layer "F.Cu")
		(net "RMII_BMC_PCH_SPRNGVLLE_RXER_R")
	)
	(segment
		(start 386.842 -88.2015)
		(end 386.842 -89.341706)
		(width 0.10795)
		(layer "F.Cu")
		(net "RMII_BMC_PCH_SPRNGVLLE_RXER_R")
	)
	(segment
		(start 386.842 -89.341706)
		(end 386.598922 -89.584784)
		(width 0.10795)
		(layer "F.Cu")
		(net "RMII_BMC_PCH_SPRNGVLLE_RXER_R")
	)
	(segment
		(start 386.484876 -93.250004)
		(end 386.484876 -93.959934)
		(width 0.0889)
		(layer "F.Cu")
		(net "RMII_BMC_PCH_SPRNGVLLE_RXER_R")
	)
	(segment
		(start 386.29971 -91.233498)
		(end 386.29971 -91.821)
		(width 0.10795)
		(layer "F.Cu")
		(net "RMII_BMC_PCH_SPRNGVLLE_RXER_R")
	)
	(segment
		(start 386.29971 -92.33662)
		(end 386.578348 -92.615258)
		(width 0.0889)
		(layer "F.Cu")
		(net "RMII_BMC_PCH_SPRNGVLLE_RXER_R")
	)
	(segment
		(start 386.598922 -89.584784)
		(end 386.598922 -90.934286)
		(width 0.10795)
		(layer "F.Cu")
		(net "RMII_BMC_PCH_SPRNGVLLE_RXER_R")
	)
	(segment
		(start 386.578348 -93.156532)
		(end 386.484876 -93.250004)
		(width 0.0889)
		(layer "F.Cu")
		(net "RMII_BMC_PCH_SPRNGVLLE_RXER_R")
	)
	(segment
		(start 386.29971 -91.821)
		(end 386.29971 -92.33662)
		(width 0.0889)
		(layer "F.Cu")
		(net "RMII_BMC_PCH_SPRNGVLLE_RXER_R")
	)
	(segment
		(start 474.200982 -112.205516)
		(end 474.200982 -113.622582)
		(width 0.10795)
		(layer "F.Cu")
		(net "RMII_BMC_OCP_RXER_R")
	)
	(segment
		(start 474.200982 -113.622582)
		(end 474.345 -113.7666)
		(width 0.10795)
		(layer "F.Cu")
		(net "RMII_BMC_OCP_RXER_R")
	)
	(via
		(at 474.345 -113.7666)
		(size 0.508)
		(drill 0.254)
		(layers "F.Cu" "B.Cu")
		(net "RMII_BMC_OCP_RXER_R")
	)
	(segment
		(start 474.345 -113.7666)
		(end 472.7194 -112.141)
		(width 0.10795)
		(layer "B.Cu")
		(net "RMII_BMC_OCP_RXER_R")
	)
	(segment
		(start 472.7194 -112.141)
		(end 472.059 -112.141)
		(width 0.10795)
		(layer "B.Cu")
		(net "RMII_BMC_OCP_RXER_R")
	)
	(segment
		(start 470.20099 -116.993162)
		(end 470.20099 -118.641114)
		(width 0.10795)
		(layer "F.Cu")
		(net "RMII_BMC_OCP_RXD1_R")
	)
	(segment
		(start 470.20099 -118.641114)
		(end 471.222324 -119.662448)
		(width 0.10795)
		(layer "F.Cu")
		(net "RMII_BMC_OCP_RXD1_R")
	)
	(via
		(at 471.222324 -119.662448)
		(size 0.508)
		(drill 0.254)
		(layers "F.Cu" "B.Cu")
		(net "RMII_BMC_OCP_RXD1_R")
	)
	(segment
		(start 470.662 -117.729)
		(end 470.662 -119.102124)
		(width 0.10795)
		(layer "B.Cu")
		(net "RMII_BMC_OCP_RXD1_R")
	)
	(segment
		(start 470.662 -119.102124)
		(end 471.222324 -119.662448)
		(width 0.10795)
		(layer "B.Cu")
		(net "RMII_BMC_OCP_RXD1_R")
	)
	(segment
		(start 471.000836 -116.993162)
		(end 471.000836 -118.448836)
		(width 0.10795)
		(layer "F.Cu")
		(net "RMII_BMC_OCP_RXD0_R")
	)
	(segment
		(start 471.000836 -118.448836)
		(end 471.7923 -119.2403)
		(width 0.10795)
		(layer "F.Cu")
		(net "RMII_BMC_OCP_RXD0_R")
	)
	(segment
		(start 471.7923 -119.2403)
		(end 471.7923 -120.308116)
		(width 0.10795)
		(layer "F.Cu")
		(net "RMII_BMC_OCP_RXD0_R")
	)
	(via
		(at 471.7923 -120.308116)
		(size 0.508)
		(drill 0.254)
		(layers "F.Cu" "B.Cu")
		(net "RMII_BMC_OCP_RXD0_R")
	)
	(via
		(at 472.567 -119.3292)
		(size 0.6604)
		(drill 0.3302)
		(layers "F.Cu" "B.Cu")
		(net "RMII_BMC_OCP_RXD0_R")
	)
	(segment
		(start 472.197684 -120.308116)
		(end 472.567 -119.9388)
		(width 0.10795)
		(layer "B.Cu")
		(net "RMII_BMC_OCP_RXD0_R")
	)
	(segment
		(start 472.2368 -118.6942)
		(end 472.2368 -118.0592)
		(width 0.10795)
		(layer "B.Cu")
		(net "RMII_BMC_OCP_RXD0_R")
	)
	(segment
		(start 472.567 -119.3292)
		(end 472.567 -119.0244)
		(width 0.10795)
		(layer "B.Cu")
		(net "RMII_BMC_OCP_RXD0_R")
	)
	(segment
		(start 472.2368 -118.0592)
		(end 471.9066 -117.729)
		(width 0.10795)
		(layer "B.Cu")
		(net "RMII_BMC_OCP_RXD0_R")
	)
	(segment
		(start 472.567 -119.9388)
		(end 472.567 -119.3292)
		(width 0.10795)
		(layer "B.Cu")
		(net "RMII_BMC_OCP_RXD0_R")
	)
	(segment
		(start 471.9066 -117.729)
		(end 471.424 -117.729)
		(width 0.10795)
		(layer "B.Cu")
		(net "RMII_BMC_OCP_RXD0_R")
	)
	(segment
		(start 471.7923 -120.308116)
		(end 472.197684 -120.308116)
		(width 0.10795)
		(layer "B.Cu")
		(net "RMII_BMC_OCP_RXD0_R")
	)
	(segment
		(start 472.567 -119.0244)
		(end 472.2368 -118.6942)
		(width 0.10795)
		(layer "B.Cu")
		(net "RMII_BMC_OCP_RXD0_R")
	)
	(segment
		(start 477.400874 -116.993162)
		(end 477.399858 -116.993162)
		(width 0.10795)
		(layer "F.Cu")
		(net "RMII_BMC_OCP_CRSDV_R")
	)
	(segment
		(start 477.399858 -116.993162)
		(end 477.399858 -121.139204)
		(width 0.10795)
		(layer "F.Cu")
		(net "RMII_BMC_OCP_CRSDV_R")
	)
	(segment
		(start 477.399858 -121.139204)
		(end 476.861378 -121.677684)
		(width 0.10795)
		(layer "F.Cu")
		(net "RMII_BMC_OCP_CRSDV_R")
	)
	(via
		(at 476.861378 -121.677684)
		(size 0.508)
		(drill 0.254)
		(layers "F.Cu" "B.Cu")
		(net "RMII_BMC_OCP_CRSDV_R")
	)
	(segment
		(start 473.4052 -121.158254)
		(end 473.4052 -115.9256)
		(width 0.10795)
		(layer "B.Cu")
		(net "RMII_BMC_OCP_CRSDV_R")
	)
	(segment
		(start 472.923108 -114.596926)
		(end 472.923108 -113.813844)
		(width 0.10795)
		(layer "B.Cu")
		(net "RMII_BMC_OCP_CRSDV_R")
	)
	(segment
		(start 476.861378 -121.677684)
		(end 473.92463 -121.677684)
		(width 0.10795)
		(layer "B.Cu")
		(net "RMII_BMC_OCP_CRSDV_R")
	)
	(segment
		(start 472.923108 -113.813844)
		(end 472.164664 -113.0554)
		(width 0.10795)
		(layer "B.Cu")
		(net "RMII_BMC_OCP_CRSDV_R")
	)
	(segment
		(start 473.4052 -115.9256)
		(end 472.738196 -115.258596)
		(width 0.10795)
		(layer "B.Cu")
		(net "RMII_BMC_OCP_CRSDV_R")
	)
	(segment
		(start 473.92463 -121.677684)
		(end 473.4052 -121.158254)
		(width 0.10795)
		(layer "B.Cu")
		(net "RMII_BMC_OCP_CRSDV_R")
	)
	(segment
		(start 472.738196 -114.781838)
		(end 472.923108 -114.596926)
		(width 0.10795)
		(layer "B.Cu")
		(net "RMII_BMC_OCP_CRSDV_R")
	)
	(segment
		(start 472.164664 -113.0554)
		(end 472.059 -113.0554)
		(width 0.10795)
		(layer "B.Cu")
		(net "RMII_BMC_OCP_CRSDV_R")
	)
	(segment
		(start 472.738196 -115.258596)
		(end 472.738196 -114.781838)
		(width 0.10795)
		(layer "B.Cu")
		(net "RMII_BMC_OCP_CRSDV_R")
	)
	(segment
		(start 453.517 -156.718)
		(end 453.517 -156.13253)
		(width 0.10795)
		(layer "F.Cu")
		(net "XDP_CPU_TCK_BUF")
	)
	(segment
		(start 454.413874 -155.948126)
		(end 454.66 -155.702)
		(width 0.10795)
		(layer "F.Cu")
		(net "XDP_CPU_TCK_BUF")
	)
	(segment
		(start 456.692 -157.607)
		(end 456.057 -157.607)
		(width 0.10795)
		(layer "F.Cu")
		(net "XDP_CPU_TCK_BUF")
	)
	(segment
		(start 454.66 -155.067)
		(end 454.279 -154.686)
		(width 0.10795)
		(layer "F.Cu")
		(net "XDP_CPU_TCK_BUF")
	)
	(segment
		(start 453.756014 -156.957014)
		(end 453.517 -156.718)
		(width 0.10795)
		(layer "F.Cu")
		(net "XDP_CPU_TCK_BUF")
	)
	(segment
		(start 454.279 -156.957014)
		(end 456.057 -156.957014)
		(width 0.10795)
		(layer "F.Cu")
		(net "XDP_CPU_TCK_BUF")
	)
	(segment
		(start 452.257922 -154.686)
		(end 451.739 -154.686)
		(width 0.10795)
		(layer "F.Cu")
		(net "XDP_CPU_TCK_BUF")
	)
	(segment
		(start 454.279 -156.957014)
		(end 453.756014 -156.957014)
		(width 0.10795)
		(layer "F.Cu")
		(net "XDP_CPU_TCK_BUF")
	)
	(segment
		(start 453.701404 -155.948126)
		(end 454.413874 -155.948126)
		(width 0.10795)
		(layer "F.Cu")
		(net "XDP_CPU_TCK_BUF")
	)
	(segment
		(start 454.279 -154.686)
		(end 452.257922 -154.686)
		(width 0.10795)
		(layer "F.Cu")
		(net "XDP_CPU_TCK_BUF")
	)
	(segment
		(start 451.739 -154.686)
		(end 451.231 -154.178)
		(width 0.10795)
		(layer "F.Cu")
		(net "XDP_CPU_TCK_BUF")
	)
	(segment
		(start 456.057 -156.957014)
		(end 456.702414 -156.957014)
		(width 0.10795)
		(layer "F.Cu")
		(net "XDP_CPU_TCK_BUF")
	)
	(segment
		(start 454.66 -155.702)
		(end 454.66 -155.067)
		(width 0.10795)
		(layer "F.Cu")
		(net "XDP_CPU_TCK_BUF")
	)
	(segment
		(start 456.702414 -156.957014)
		(end 456.819 -157.0736)
		(width 0.10795)
		(layer "F.Cu")
		(net "XDP_CPU_TCK_BUF")
	)
	(segment
		(start 456.819 -157.48)
		(end 456.692 -157.607)
		(width 0.10795)
		(layer "F.Cu")
		(net "XDP_CPU_TCK_BUF")
	)
	(segment
		(start 453.517 -156.13253)
		(end 453.701404 -155.948126)
		(width 0.10795)
		(layer "F.Cu")
		(net "XDP_CPU_TCK_BUF")
	)
	(segment
		(start 456.819 -157.0736)
		(end 456.819 -157.48)
		(width 0.10795)
		(layer "F.Cu")
		(net "XDP_CPU_TCK_BUF")
	)
	(segment
		(start 451.231 -154.178)
		(end 451.231 -153.543)
		(width 0.10795)
		(layer "F.Cu")
		(net "XDP_CPU_TCK_BUF")
	)
	(via
		(at 452.257922 -154.686)
		(size 0.508)
		(drill 0.254)
		(layers "F.Cu" "B.Cu")
		(net "XDP_CPU_TCK_BUF")
	)
	(segment
		(start 396.65275 -98.69424)
		(end 397.14805 -98.464116)
		(width 0.10795)
		(layer "F.Cu")
		(net "FM_UART_ALERT_N")
	)
	(segment
		(start 378.344684 -79.094838)
		(end 377.944888 -78.695042)
		(width 0.1016)
		(layer "F.Cu")
		(net "FM_UART_ALERT_N")
	)
	(via
		(at 376.86996 -91.3257)
		(size 0.508)
		(drill 0.254)
		(layers "F.Cu" "B.Cu")
		(net "FM_UART_ALERT_N")
	)
	(via
		(at 397.14805 -98.464116)
		(size 0.508)
		(drill 0.254)
		(layers "F.Cu" "B.Cu")
		(net "FM_UART_ALERT_N")
	)
	(via
		(at 378.344684 -79.094838)
		(size 0.4572)
		(drill 0.2032)
		(layers "F.Cu" "B.Cu")
		(net "FM_UART_ALERT_N")
	)
	(segment
		(start 378.633482 -79.472282)
		(end 378.344684 -79.183484)
		(width 0.10795)
		(layer "B.Cu")
		(net "FM_UART_ALERT_N")
	)
	(segment
		(start 380.60122 -79.12354)
		(end 380.252478 -79.472282)
		(width 0.10795)
		(layer "B.Cu")
		(net "FM_UART_ALERT_N")
	)
	(segment
		(start 380.252478 -79.472282)
		(end 378.633482 -79.472282)
		(width 0.10795)
		(layer "B.Cu")
		(net "FM_UART_ALERT_N")
	)
	(segment
		(start 378.344684 -79.183484)
		(end 378.344684 -79.094838)
		(width 0.10795)
		(layer "B.Cu")
		(net "FM_UART_ALERT_N")
	)
	(segment
		(start 376.86996 -91.468194)
		(end 376.86996 -91.3257)
		(width 0.089408)
		(layer "In2.Cu")
		(net "FM_UART_ALERT_N")
	)
	(segment
		(start 397.14805 -98.464116)
		(end 396.885922 -98.201988)
		(width 0.089408)
		(layer "In2.Cu")
		(net "FM_UART_ALERT_N")
	)
	(segment
		(start 395.615414 -94.145862)
		(end 395.507718 -94.145862)
		(width 0.089408)
		(layer "In2.Cu")
		(net "FM_UART_ALERT_N")
	)
	(segment
		(start 396.252954 -94.783402)
		(end 395.615414 -94.145862)
		(width 0.089408)
		(layer "In2.Cu")
		(net "FM_UART_ALERT_N")
	)
	(segment
		(start 377.271788 -93.219016)
		(end 377.271788 -91.870022)
		(width 0.089408)
		(layer "In2.Cu")
		(net "FM_UART_ALERT_N")
	)
	(segment
		(start 377.271788 -91.870022)
		(end 376.86996 -91.468194)
		(width 0.089408)
		(layer "In2.Cu")
		(net "FM_UART_ALERT_N")
	)
	(segment
		(start 378.19838 -94.145608)
		(end 377.271788 -93.219016)
		(width 0.089408)
		(layer "In2.Cu")
		(net "FM_UART_ALERT_N")
	)
	(segment
		(start 395.507718 -94.145862)
		(end 395.507464 -94.145608)
		(width 0.089408)
		(layer "In2.Cu")
		(net "FM_UART_ALERT_N")
	)
	(segment
		(start 396.252954 -97.617788)
		(end 396.252954 -97.593404)
		(width 0.089408)
		(layer "In2.Cu")
		(net "FM_UART_ALERT_N")
	)
	(segment
		(start 396.885922 -98.201988)
		(end 396.452852 -97.952052)
		(width 0.089408)
		(layer "In2.Cu")
		(net "FM_UART_ALERT_N")
	)
	(segment
		(start 395.507464 -94.145608)
		(end 378.19838 -94.145608)
		(width 0.089408)
		(layer "In2.Cu")
		(net "FM_UART_ALERT_N")
	)
	(segment
		(start 396.252954 -95.900748)
		(end 396.252954 -94.783402)
		(width 0.089408)
		(layer "In2.Cu")
		(net "FM_UART_ALERT_N")
	)
	(segment
		(start 396.748254 -96.76765)
		(end 396.748254 -96.726502)
		(width 0.089408)
		(layer "In2.Cu")
		(net "FM_UART_ALERT_N")
	)
	(arc
		(start 396.452852 -97.952052)
		(mid 396.309467 -97.810895)
		(end 396.252954 -97.617788)
		(width 0.089408)
		(layer "In2.Cu")
		(net "FM_UART_ALERT_N")
	)
	(arc
		(start 396.252954 -97.593404)
		(mid 396.309473 -97.400301)
		(end 396.452852 -97.25914)
		(width 0.089408)
		(layer "In2.Cu")
		(net "FM_UART_ALERT_N")
	)
	(arc
		(start 396.452852 -96.235012)
		(mid 396.309467 -96.093855)
		(end 396.252954 -95.900748)
		(width 0.089408)
		(layer "In2.Cu")
		(net "FM_UART_ALERT_N")
	)
	(arc
		(start 396.748254 -96.726502)
		(mid 396.664136 -96.442541)
		(end 396.452852 -96.235012)
		(width 0.089408)
		(layer "In2.Cu")
		(net "FM_UART_ALERT_N")
	)
	(arc
		(start 396.452852 -97.25914)
		(mid 396.664136 -97.051611)
		(end 396.748254 -96.76765)
		(width 0.089408)
		(layer "In2.Cu")
		(net "FM_UART_ALERT_N")
	)
	(segment
		(start 377.61037 -90.06205)
		(end 377.61037 -88.479884)
		(width 0.089408)
		(layer "In11.Cu")
		(net "FM_UART_ALERT_N")
	)
	(segment
		(start 375.934732 -82.186272)
		(end 376.710194 -81.41081)
		(width 0.089408)
		(layer "In11.Cu")
		(net "FM_UART_ALERT_N")
	)
	(segment
		(start 377.61037 -88.479884)
		(end 375.934732 -86.804246)
		(width 0.089408)
		(layer "In11.Cu")
		(net "FM_UART_ALERT_N")
	)
	(segment
		(start 375.934732 -86.804246)
		(end 375.934732 -82.186272)
		(width 0.089408)
		(layer "In11.Cu")
		(net "FM_UART_ALERT_N")
	)
	(segment
		(start 377.64212 -81.41081)
		(end 377.952 -81.10093)
		(width 0.089408)
		(layer "In11.Cu")
		(net "FM_UART_ALERT_N")
	)
	(segment
		(start 377.952 -79.487522)
		(end 378.344684 -79.094838)
		(width 0.089408)
		(layer "In11.Cu")
		(net "FM_UART_ALERT_N")
	)
	(segment
		(start 377.952 -81.10093)
		(end 377.952 -79.487522)
		(width 0.089408)
		(layer "In11.Cu")
		(net "FM_UART_ALERT_N")
	)
	(segment
		(start 376.710194 -81.41081)
		(end 377.64212 -81.41081)
		(width 0.089408)
		(layer "In11.Cu")
		(net "FM_UART_ALERT_N")
	)
	(segment
		(start 376.929142 -91.3257)
		(end 377.424696 -90.830146)
		(width 0.089408)
		(layer "In11.Cu")
		(net "FM_UART_ALERT_N")
	)
	(segment
		(start 377.424696 -90.247724)
		(end 377.61037 -90.06205)
		(width 0.089408)
		(layer "In11.Cu")
		(net "FM_UART_ALERT_N")
	)
	(segment
		(start 376.86996 -91.3257)
		(end 376.929142 -91.3257)
		(width 0.089408)
		(layer "In11.Cu")
		(net "FM_UART_ALERT_N")
	)
	(segment
		(start 377.424696 -90.830146)
		(end 377.424696 -90.247724)
		(width 0.089408)
		(layer "In11.Cu")
		(net "FM_UART_ALERT_N")
	)
	(segment
		(start 82.343752 -87.784686)
		(end 81.772252 -87.784686)
		(width 0.10795)
		(layer "F.Cu")
		(net "TP_CPU1_RSVD_64")
	)
	(via
		(at 81.772252 -87.784686)
		(size 0.508)
		(drill 0.254)
		(layers "F.Cu" "B.Cu")
		(net "TP_CPU1_RSVD_64")
	)
	(segment
		(start 247.344184 -87.784686)
		(end 246.772684 -87.784686)
		(width 0.10795)
		(layer "F.Cu")
		(net "TP_CPU0_RSVD_64")
	)
	(via
		(at 246.772684 -87.784686)
		(size 0.508)
		(drill 0.254)
		(layers "F.Cu" "B.Cu")
		(net "TP_CPU0_RSVD_64")
	)
	(segment
		(start 398.768316 -158.218124)
		(end 398.65173 -158.33471)
		(width 0.127)
		(layer "F.Cu")
		(net "VR_PVNN_PCH_AIREF1")
	)
	(segment
		(start 373.470424 -157.541976)
		(end 373.1006 -157.9118)
		(width 0.127)
		(layer "F.Cu")
		(net "VR_PVNN_PCH_AIREF1")
	)
	(segment
		(start 397.582898 -156.562044)
		(end 397.985742 -156.964888)
		(width 0.127)
		(layer "F.Cu")
		(net "VR_PVNN_PCH_AIREF1")
	)
	(segment
		(start 397.582898 -156.2481)
		(end 397.582898 -156.562044)
		(width 0.127)
		(layer "F.Cu")
		(net "VR_PVNN_PCH_AIREF1")
	)
	(segment
		(start 373.470424 -156.972)
		(end 373.470424 -157.541976)
		(width 0.127)
		(layer "F.Cu")
		(net "VR_PVNN_PCH_AIREF1")
	)
	(segment
		(start 373.548656 -156.972)
		(end 373.470424 -156.972)
		(width 0.127)
		(layer "F.Cu")
		(net "VR_PVNN_PCH_AIREF1")
	)
	(segment
		(start 397.985742 -156.964888)
		(end 398.29867 -156.964888)
		(width 0.127)
		(layer "F.Cu")
		(net "VR_PVNN_PCH_AIREF1")
	)
	(segment
		(start 398.768316 -157.434534)
		(end 398.768316 -157.664658)
		(width 0.127)
		(layer "F.Cu")
		(net "VR_PVNN_PCH_AIREF1")
	)
	(segment
		(start 373.688356 -156.8323)
		(end 373.548656 -156.972)
		(width 0.127)
		(layer "F.Cu")
		(net "VR_PVNN_PCH_AIREF1")
	)
	(segment
		(start 398.768316 -157.664658)
		(end 398.768316 -158.218124)
		(width 0.127)
		(layer "F.Cu")
		(net "VR_PVNN_PCH_AIREF1")
	)
	(segment
		(start 398.29867 -156.964888)
		(end 398.768316 -157.434534)
		(width 0.127)
		(layer "F.Cu")
		(net "VR_PVNN_PCH_AIREF1")
	)
	(segment
		(start 374.367552 -156.568648)
		(end 374.1039 -156.8323)
		(width 0.127)
		(layer "F.Cu")
		(net "VR_PVNN_PCH_AIREF1")
	)
	(segment
		(start 374.1039 -156.8323)
		(end 373.688356 -156.8323)
		(width 0.127)
		(layer "F.Cu")
		(net "VR_PVNN_PCH_AIREF1")
	)
	(segment
		(start 374.367552 -156.24302)
		(end 374.367552 -156.568648)
		(width 0.127)
		(layer "F.Cu")
		(net "VR_PVNN_PCH_AIREF1")
	)
	(via
		(at 398.591278 -156.17317)
		(size 0.6604)
		(drill 0.3302)
		(layers "F.Cu" "B.Cu")
		(net "VR_PVNN_PCH_AIREF1")
	)
	(via
		(at 373.470424 -156.972)
		(size 0.508)
		(drill 0.254)
		(layers "F.Cu" "B.Cu")
		(net "VR_PVNN_PCH_AIREF1")
	)
	(via
		(at 398.65173 -158.33471)
		(size 0.508)
		(drill 0.254)
		(layers "F.Cu" "B.Cu")
		(net "VR_PVNN_PCH_AIREF1")
	)
	(segment
		(start 398.591278 -158.274258)
		(end 398.591278 -157.11297)
		(width 0.127)
		(layer "B.Cu")
		(net "VR_PVNN_PCH_AIREF1")
	)
	(segment
		(start 398.591278 -157.11297)
		(end 398.591278 -156.17317)
		(width 0.127)
		(layer "B.Cu")
		(net "VR_PVNN_PCH_AIREF1")
	)
	(segment
		(start 398.65173 -158.33471)
		(end 398.591278 -158.274258)
		(width 0.127)
		(layer "B.Cu")
		(net "VR_PVNN_PCH_AIREF1")
	)
	(segment
		(start 391.08634 -155.09494)
		(end 395.12748 -155.09494)
		(width 0.127)
		(layer "In2.Cu")
		(net "VR_PVNN_PCH_AIREF1")
	)
	(segment
		(start 378.601224 -157.38729)
		(end 379.870716 -157.38729)
		(width 0.127)
		(layer "In2.Cu")
		(net "VR_PVNN_PCH_AIREF1")
	)
	(segment
		(start 396.52448 -155.85186)
		(end 398.334992 -157.662372)
		(width 0.127)
		(layer "In2.Cu")
		(net "VR_PVNN_PCH_AIREF1")
	)
	(segment
		(start 398.334992 -158.017972)
		(end 398.65173 -158.33471)
		(width 0.127)
		(layer "In2.Cu")
		(net "VR_PVNN_PCH_AIREF1")
	)
	(segment
		(start 377.430792 -156.216858)
		(end 378.601224 -157.38729)
		(width 0.127)
		(layer "In2.Cu")
		(net "VR_PVNN_PCH_AIREF1")
	)
	(segment
		(start 398.334992 -157.662372)
		(end 398.334992 -158.017972)
		(width 0.127)
		(layer "In2.Cu")
		(net "VR_PVNN_PCH_AIREF1")
	)
	(segment
		(start 381.052578 -156.205428)
		(end 382.039368 -156.205428)
		(width 0.127)
		(layer "In2.Cu")
		(net "VR_PVNN_PCH_AIREF1")
	)
	(segment
		(start 383.85115 -154.393646)
		(end 388.228586 -154.393646)
		(width 0.127)
		(layer "In2.Cu")
		(net "VR_PVNN_PCH_AIREF1")
	)
	(segment
		(start 382.039368 -156.205428)
		(end 383.85115 -154.393646)
		(width 0.127)
		(layer "In2.Cu")
		(net "VR_PVNN_PCH_AIREF1")
	)
	(segment
		(start 390.003538 -153.695654)
		(end 390.78408 -154.476196)
		(width 0.127)
		(layer "In2.Cu")
		(net "VR_PVNN_PCH_AIREF1")
	)
	(segment
		(start 374.550686 -156.216858)
		(end 377.430792 -156.216858)
		(width 0.127)
		(layer "In2.Cu")
		(net "VR_PVNN_PCH_AIREF1")
	)
	(segment
		(start 390.78408 -154.79268)
		(end 391.08634 -155.09494)
		(width 0.127)
		(layer "In2.Cu")
		(net "VR_PVNN_PCH_AIREF1")
	)
	(segment
		(start 395.8844 -155.85186)
		(end 396.52448 -155.85186)
		(width 0.127)
		(layer "In2.Cu")
		(net "VR_PVNN_PCH_AIREF1")
	)
	(segment
		(start 395.12748 -155.09494)
		(end 395.8844 -155.85186)
		(width 0.127)
		(layer "In2.Cu")
		(net "VR_PVNN_PCH_AIREF1")
	)
	(segment
		(start 373.795544 -156.972)
		(end 374.550686 -156.216858)
		(width 0.127)
		(layer "In2.Cu")
		(net "VR_PVNN_PCH_AIREF1")
	)
	(segment
		(start 388.228586 -154.393646)
		(end 388.926578 -153.695654)
		(width 0.127)
		(layer "In2.Cu")
		(net "VR_PVNN_PCH_AIREF1")
	)
	(segment
		(start 390.78408 -154.476196)
		(end 390.78408 -154.79268)
		(width 0.127)
		(layer "In2.Cu")
		(net "VR_PVNN_PCH_AIREF1")
	)
	(segment
		(start 379.870716 -157.38729)
		(end 381.052578 -156.205428)
		(width 0.127)
		(layer "In2.Cu")
		(net "VR_PVNN_PCH_AIREF1")
	)
	(segment
		(start 373.470424 -156.972)
		(end 373.795544 -156.972)
		(width 0.127)
		(layer "In2.Cu")
		(net "VR_PVNN_PCH_AIREF1")
	)
	(segment
		(start 388.926578 -153.695654)
		(end 390.003538 -153.695654)
		(width 0.127)
		(layer "In2.Cu")
		(net "VR_PVNN_PCH_AIREF1")
	)
	(segment
		(start 0.724662 -124.076968)
		(end 0.688594 -124.0409)
		(width 0.127)
		(layer "F.Cu")
		(net "VR_PVDDQ_KLM_AIREF2")
	)
	(segment
		(start 1.057402 -125.5141)
		(end 1.057402 -124.875544)
		(width 0.127)
		(layer "F.Cu")
		(net "VR_PVDDQ_KLM_AIREF2")
	)
	(segment
		(start -1.667764 -144.364202)
		(end -1.667764 -144.652746)
		(width 0.127)
		(layer "F.Cu")
		(net "VR_PVDDQ_KLM_AIREF2")
	)
	(segment
		(start -1.667764 -144.652746)
		(end -0.992124 -145.328386)
		(width 0.127)
		(layer "F.Cu")
		(net "VR_PVDDQ_KLM_AIREF2")
	)
	(segment
		(start -2.1082 -143.923766)
		(end -1.667764 -144.364202)
		(width 0.127)
		(layer "F.Cu")
		(net "VR_PVDDQ_KLM_AIREF2")
	)
	(segment
		(start 0.688594 -124.0409)
		(end 0.688594 -123.20905)
		(width 0.127)
		(layer "F.Cu")
		(net "VR_PVDDQ_KLM_AIREF2")
	)
	(segment
		(start 0.688594 -122.45467)
		(end 0.657606 -122.423682)
		(width 0.127)
		(layer "F.Cu")
		(net "VR_PVDDQ_KLM_AIREF2")
	)
	(segment
		(start -2.1082 -143.256)
		(end -2.1082 -143.923766)
		(width 0.127)
		(layer "F.Cu")
		(net "VR_PVDDQ_KLM_AIREF2")
	)
	(segment
		(start -0.992124 -145.328386)
		(end -0.497586 -145.328386)
		(width 0.127)
		(layer "F.Cu")
		(net "VR_PVDDQ_KLM_AIREF2")
	)
	(segment
		(start 0.688594 -123.20905)
		(end 0.688594 -122.45467)
		(width 0.127)
		(layer "F.Cu")
		(net "VR_PVDDQ_KLM_AIREF2")
	)
	(segment
		(start 0.724662 -124.542804)
		(end 0.724662 -124.076968)
		(width 0.127)
		(layer "F.Cu")
		(net "VR_PVDDQ_KLM_AIREF2")
	)
	(segment
		(start 1.057402 -124.875544)
		(end 0.724662 -124.542804)
		(width 0.127)
		(layer "F.Cu")
		(net "VR_PVDDQ_KLM_AIREF2")
	)
	(via
		(at -1.667764 -144.364202)
		(size 0.508)
		(drill 0.254)
		(layers "F.Cu" "B.Cu")
		(net "VR_PVDDQ_KLM_AIREF2")
	)
	(via
		(at 0.657606 -122.423682)
		(size 0.508)
		(drill 0.254)
		(layers "F.Cu" "B.Cu")
		(net "VR_PVDDQ_KLM_AIREF2")
	)
	(segment
		(start -1.840484 -136.2456)
		(end -1.967484 -136.3726)
		(width 0.127)
		(layer "In9.Cu")
		(net "VR_PVDDQ_KLM_AIREF2")
	)
	(segment
		(start -4.318 -136.271)
		(end -5.334 -137.287)
		(width 0.127)
		(layer "In9.Cu")
		(net "VR_PVDDQ_KLM_AIREF2")
	)
	(segment
		(start 0.924306 -123.308364)
		(end -2.96164 -127.19431)
		(width 0.127)
		(layer "In9.Cu")
		(net "VR_PVDDQ_KLM_AIREF2")
	)
	(segment
		(start -1.840484 -134.86511)
		(end -1.840484 -136.2456)
		(width 0.127)
		(layer "In9.Cu")
		(net "VR_PVDDQ_KLM_AIREF2")
	)
	(segment
		(start -2.01549 -146.36496)
		(end -1.44018 -145.78965)
		(width 0.127)
		(layer "In9.Cu")
		(net "VR_PVDDQ_KLM_AIREF2")
	)
	(segment
		(start -1.667764 -144.772126)
		(end -1.667764 -144.364202)
		(width 0.127)
		(layer "In9.Cu")
		(net "VR_PVDDQ_KLM_AIREF2")
	)
	(segment
		(start -1.44018 -144.99971)
		(end -1.667764 -144.772126)
		(width 0.127)
		(layer "In9.Cu")
		(net "VR_PVDDQ_KLM_AIREF2")
	)
	(segment
		(start -2.733548 -134.586726)
		(end -2.118868 -134.586726)
		(width 0.127)
		(layer "In9.Cu")
		(net "VR_PVDDQ_KLM_AIREF2")
	)
	(segment
		(start -1.44018 -145.78965)
		(end -1.44018 -144.99971)
		(width 0.127)
		(layer "In9.Cu")
		(net "VR_PVDDQ_KLM_AIREF2")
	)
	(segment
		(start -3.277362 -134.042912)
		(end -2.733548 -134.586726)
		(width 0.127)
		(layer "In9.Cu")
		(net "VR_PVDDQ_KLM_AIREF2")
	)
	(segment
		(start -3.01625 -146.36496)
		(end -2.01549 -146.36496)
		(width 0.127)
		(layer "In9.Cu")
		(net "VR_PVDDQ_KLM_AIREF2")
	)
	(segment
		(start -2.118868 -134.586726)
		(end -1.840484 -134.86511)
		(width 0.127)
		(layer "In9.Cu")
		(net "VR_PVDDQ_KLM_AIREF2")
	)
	(segment
		(start 0.924306 -122.690382)
		(end 0.924306 -123.308364)
		(width 0.127)
		(layer "In9.Cu")
		(net "VR_PVDDQ_KLM_AIREF2")
	)
	(segment
		(start -5.334 -144.04721)
		(end -3.01625 -146.36496)
		(width 0.127)
		(layer "In9.Cu")
		(net "VR_PVDDQ_KLM_AIREF2")
	)
	(segment
		(start -5.334 -137.287)
		(end -5.334 -144.04721)
		(width 0.127)
		(layer "In9.Cu")
		(net "VR_PVDDQ_KLM_AIREF2")
	)
	(segment
		(start 0.657606 -122.423682)
		(end 0.924306 -122.690382)
		(width 0.127)
		(layer "In9.Cu")
		(net "VR_PVDDQ_KLM_AIREF2")
	)
	(segment
		(start -1.967484 -136.3726)
		(end -3.0734 -136.3726)
		(width 0.127)
		(layer "In9.Cu")
		(net "VR_PVDDQ_KLM_AIREF2")
	)
	(segment
		(start -2.96164 -132.12191)
		(end -3.277362 -132.437632)
		(width 0.127)
		(layer "In9.Cu")
		(net "VR_PVDDQ_KLM_AIREF2")
	)
	(segment
		(start -3.175 -136.271)
		(end -4.318 -136.271)
		(width 0.127)
		(layer "In9.Cu")
		(net "VR_PVDDQ_KLM_AIREF2")
	)
	(segment
		(start -2.96164 -127.19431)
		(end -2.96164 -132.12191)
		(width 0.127)
		(layer "In9.Cu")
		(net "VR_PVDDQ_KLM_AIREF2")
	)
	(segment
		(start -3.277362 -132.437632)
		(end -3.277362 -134.042912)
		(width 0.127)
		(layer "In9.Cu")
		(net "VR_PVDDQ_KLM_AIREF2")
	)
	(segment
		(start -3.0734 -136.3726)
		(end -3.175 -136.271)
		(width 0.127)
		(layer "In9.Cu")
		(net "VR_PVDDQ_KLM_AIREF2")
	)
	(segment
		(start -1.890776 -135.285734)
		(end -2.12979 -135.285734)
		(width 0.127)
		(layer "F.Cu")
		(net "VR_PVDDQ_KLM_AIREF1")
	)
	(segment
		(start -1.230884 -122.579384)
		(end -1.1049 -122.4534)
		(width 0.127)
		(layer "F.Cu")
		(net "VR_PVDDQ_KLM_AIREF1")
	)
	(segment
		(start -1.8796 -134.2898)
		(end -1.8542 -134.3152)
		(width 0.127)
		(layer "F.Cu")
		(net "VR_PVDDQ_KLM_AIREF1")
	)
	(segment
		(start -0.497586 -136.184386)
		(end -0.992124 -136.184386)
		(width 0.127)
		(layer "F.Cu")
		(net "VR_PVDDQ_KLM_AIREF1")
	)
	(segment
		(start -1.230884 -123.210574)
		(end -1.230884 -122.579384)
		(width 0.127)
		(layer "F.Cu")
		(net "VR_PVDDQ_KLM_AIREF1")
	)
	(segment
		(start -1.033526 -123.407932)
		(end -1.230884 -123.210574)
		(width 0.127)
		(layer "F.Cu")
		(net "VR_PVDDQ_KLM_AIREF1")
	)
	(segment
		(start -3.1242 -134.2898)
		(end -1.8796 -134.2898)
		(width 0.127)
		(layer "F.Cu")
		(net "VR_PVDDQ_KLM_AIREF1")
	)
	(segment
		(start -2.358898 -135.056626)
		(end -2.358898 -135.027416)
		(width 0.127)
		(layer "F.Cu")
		(net "VR_PVDDQ_KLM_AIREF1")
	)
	(segment
		(start -1.033526 -124.196094)
		(end -0.220472 -125.009148)
		(width 0.127)
		(layer "F.Cu")
		(net "VR_PVDDQ_KLM_AIREF1")
	)
	(segment
		(start -0.992124 -136.184386)
		(end -1.890776 -135.285734)
		(width 0.127)
		(layer "F.Cu")
		(net "VR_PVDDQ_KLM_AIREF1")
	)
	(segment
		(start -2.358898 -135.027416)
		(end -2.119376 -135.027416)
		(width 0.127)
		(layer "F.Cu")
		(net "VR_PVDDQ_KLM_AIREF1")
	)
	(segment
		(start -0.028194 -125.009148)
		(end 0.257302 -125.294644)
		(width 0.127)
		(layer "F.Cu")
		(net "VR_PVDDQ_KLM_AIREF1")
	)
	(segment
		(start -2.12979 -135.285734)
		(end -2.358898 -135.056626)
		(width 0.127)
		(layer "F.Cu")
		(net "VR_PVDDQ_KLM_AIREF1")
	)
	(segment
		(start -0.220472 -125.009148)
		(end -0.028194 -125.009148)
		(width 0.127)
		(layer "F.Cu")
		(net "VR_PVDDQ_KLM_AIREF1")
	)
	(segment
		(start 0.257302 -125.294644)
		(end 0.257302 -125.5141)
		(width 0.127)
		(layer "F.Cu")
		(net "VR_PVDDQ_KLM_AIREF1")
	)
	(segment
		(start -2.119376 -135.027416)
		(end -1.8542 -134.76224)
		(width 0.127)
		(layer "F.Cu")
		(net "VR_PVDDQ_KLM_AIREF1")
	)
	(segment
		(start -1.033526 -124.073666)
		(end -1.033526 -124.196094)
		(width 0.127)
		(layer "F.Cu")
		(net "VR_PVDDQ_KLM_AIREF1")
	)
	(segment
		(start -1.8542 -134.76224)
		(end -1.8542 -134.3152)
		(width 0.127)
		(layer "F.Cu")
		(net "VR_PVDDQ_KLM_AIREF1")
	)
	(segment
		(start -1.033526 -124.073666)
		(end -1.033526 -123.407932)
		(width 0.127)
		(layer "F.Cu")
		(net "VR_PVDDQ_KLM_AIREF1")
	)
	(segment
		(start -3.302 -134.4676)
		(end -3.1242 -134.2898)
		(width 0.127)
		(layer "F.Cu")
		(net "VR_PVDDQ_KLM_AIREF1")
	)
	(via
		(at -1.1049 -122.4534)
		(size 0.508)
		(drill 0.254)
		(layers "F.Cu" "B.Cu")
		(net "VR_PVDDQ_KLM_AIREF1")
	)
	(via
		(at -2.358898 -135.027416)
		(size 0.508)
		(drill 0.254)
		(layers "F.Cu" "B.Cu")
		(net "VR_PVDDQ_KLM_AIREF1")
	)
	(via
		(at -3.302 -134.4676)
		(size 0.762)
		(drill 0.381)
		(layers "F.Cu" "B.Cu")
		(net "VR_PVDDQ_KLM_AIREF1")
	)
	(segment
		(start -4.230624 -134.01421)
		(end -3.1496 -135.095234)
		(width 0.127)
		(layer "In9.Cu")
		(net "VR_PVDDQ_KLM_AIREF1")
	)
	(segment
		(start -1.1049 -122.4534)
		(end -0.860552 -122.209052)
		(width 0.127)
		(layer "In9.Cu")
		(net "VR_PVDDQ_KLM_AIREF1")
	)
	(segment
		(start -0.860552 -122.209052)
		(end -0.860552 -122.117612)
		(width 0.127)
		(layer "In9.Cu")
		(net "VR_PVDDQ_KLM_AIREF1")
	)
	(segment
		(start -2.713482 -135.382)
		(end -2.358898 -135.027416)
		(width 0.127)
		(layer "In9.Cu")
		(net "VR_PVDDQ_KLM_AIREF1")
	)
	(segment
		(start -2.9718 -135.382)
		(end -2.713482 -135.382)
		(width 0.127)
		(layer "In9.Cu")
		(net "VR_PVDDQ_KLM_AIREF1")
	)
	(segment
		(start -3.90017 -122.936)
		(end -5.03174 -124.06757)
		(width 0.127)
		(layer "In9.Cu")
		(net "VR_PVDDQ_KLM_AIREF1")
	)
	(segment
		(start -5.03174 -124.06757)
		(end -5.03174 -133.459982)
		(width 0.127)
		(layer "In9.Cu")
		(net "VR_PVDDQ_KLM_AIREF1")
	)
	(segment
		(start -3.1496 -135.095234)
		(end -3.1496 -135.2042)
		(width 0.127)
		(layer "In9.Cu")
		(net "VR_PVDDQ_KLM_AIREF1")
	)
	(segment
		(start -5.03174 -133.459982)
		(end -4.477512 -134.01421)
		(width 0.127)
		(layer "In9.Cu")
		(net "VR_PVDDQ_KLM_AIREF1")
	)
	(segment
		(start -0.860552 -122.117612)
		(end -1.075944 -121.90222)
		(width 0.127)
		(layer "In9.Cu")
		(net "VR_PVDDQ_KLM_AIREF1")
	)
	(segment
		(start -4.477512 -134.01421)
		(end -4.230624 -134.01421)
		(width 0.127)
		(layer "In9.Cu")
		(net "VR_PVDDQ_KLM_AIREF1")
	)
	(segment
		(start -2.472436 -122.936)
		(end -3.90017 -122.936)
		(width 0.127)
		(layer "In9.Cu")
		(net "VR_PVDDQ_KLM_AIREF1")
	)
	(segment
		(start -3.1496 -135.2042)
		(end -2.9718 -135.382)
		(width 0.127)
		(layer "In9.Cu")
		(net "VR_PVDDQ_KLM_AIREF1")
	)
	(segment
		(start -1.438656 -121.90222)
		(end -2.472436 -122.936)
		(width 0.127)
		(layer "In9.Cu")
		(net "VR_PVDDQ_KLM_AIREF1")
	)
	(segment
		(start -1.075944 -121.90222)
		(end -1.438656 -121.90222)
		(width 0.127)
		(layer "In9.Cu")
		(net "VR_PVDDQ_KLM_AIREF1")
	)
	(segment
		(start 1.69418 -15.46098)
		(end 2.150364 -15.46098)
		(width 0.127)
		(layer "F.Cu")
		(net "VR_PVDDQ_GHJ_AIREF2")
	)
	(segment
		(start 5.729224 3.50139)
		(end 5.265928 3.964686)
		(width 0.127)
		(layer "F.Cu")
		(net "VR_PVDDQ_GHJ_AIREF2")
	)
	(segment
		(start 0.570738 -14.337538)
		(end 0.463804 -14.337538)
		(width 0.127)
		(layer "F.Cu")
		(net "VR_PVDDQ_GHJ_AIREF2")
	)
	(segment
		(start 5.265928 4.567682)
		(end 5.060696 4.772914)
		(width 0.127)
		(layer "F.Cu")
		(net "VR_PVDDQ_GHJ_AIREF2")
	)
	(segment
		(start 1.148588 -14.695932)
		(end 1.085596 -14.63294)
		(width 0.127)
		(layer "F.Cu")
		(net "VR_PVDDQ_GHJ_AIREF2")
	)
	(segment
		(start 5.989828 1.375918)
		(end 5.989828 0.26416)
		(width 0.127)
		(layer "F.Cu")
		(net "VR_PVDDQ_GHJ_AIREF2")
	)
	(segment
		(start 5.602732 2.780284)
		(end 5.464556 2.91846)
		(width 0.127)
		(layer "F.Cu")
		(net "VR_PVDDQ_GHJ_AIREF2")
	)
	(segment
		(start 0.86614 -14.63294)
		(end 0.570738 -14.337538)
		(width 0.127)
		(layer "F.Cu")
		(net "VR_PVDDQ_GHJ_AIREF2")
	)
	(segment
		(start 5.729224 3.183128)
		(end 5.729224 3.50139)
		(width 0.127)
		(layer "F.Cu")
		(net "VR_PVDDQ_GHJ_AIREF2")
	)
	(segment
		(start 5.265928 3.964686)
		(end 5.265928 4.567682)
		(width 0.127)
		(layer "F.Cu")
		(net "VR_PVDDQ_GHJ_AIREF2")
	)
	(segment
		(start 5.602732 2.141474)
		(end 5.602732 2.780284)
		(width 0.127)
		(layer "F.Cu")
		(net "VR_PVDDQ_GHJ_AIREF2")
	)
	(segment
		(start 5.602732 2.141474)
		(end 5.602732 1.763014)
		(width 0.127)
		(layer "F.Cu")
		(net "VR_PVDDQ_GHJ_AIREF2")
	)
	(segment
		(start 5.060696 4.772914)
		(end 5.060696 4.79425)
		(width 0.127)
		(layer "F.Cu")
		(net "VR_PVDDQ_GHJ_AIREF2")
	)
	(segment
		(start 1.085596 -14.63294)
		(end 0.86614 -14.63294)
		(width 0.127)
		(layer "F.Cu")
		(net "VR_PVDDQ_GHJ_AIREF2")
	)
	(segment
		(start 5.989828 0.26416)
		(end 7.006336 -0.752348)
		(width 0.127)
		(layer "F.Cu")
		(net "VR_PVDDQ_GHJ_AIREF2")
	)
	(segment
		(start 5.602732 1.763014)
		(end 5.989828 1.375918)
		(width 0.127)
		(layer "F.Cu")
		(net "VR_PVDDQ_GHJ_AIREF2")
	)
	(segment
		(start 7.006336 -0.752348)
		(end 7.5819 -0.752348)
		(width 0.127)
		(layer "F.Cu")
		(net "VR_PVDDQ_GHJ_AIREF2")
	)
	(segment
		(start 5.464556 2.91846)
		(end 5.729224 3.183128)
		(width 0.127)
		(layer "F.Cu")
		(net "VR_PVDDQ_GHJ_AIREF2")
	)
	(segment
		(start 1.148588 -14.695932)
		(end 1.148588 -14.915388)
		(width 0.127)
		(layer "F.Cu")
		(net "VR_PVDDQ_GHJ_AIREF2")
	)
	(segment
		(start 1.148588 -14.915388)
		(end 1.69418 -15.46098)
		(width 0.127)
		(layer "F.Cu")
		(net "VR_PVDDQ_GHJ_AIREF2")
	)
	(via
		(at 5.060696 4.79425)
		(size 0.508)
		(drill 0.254)
		(layers "F.Cu" "B.Cu")
		(net "VR_PVDDQ_GHJ_AIREF2")
	)
	(via
		(at 0.463804 -14.337538)
		(size 0.508)
		(drill 0.254)
		(layers "F.Cu" "B.Cu")
		(net "VR_PVDDQ_GHJ_AIREF2")
	)
	(segment
		(start -4.1148 1.762506)
		(end -0.905764 4.971542)
		(width 0.127)
		(layer "In2.Cu")
		(net "VR_PVDDQ_GHJ_AIREF2")
	)
	(segment
		(start -0.905764 4.971542)
		(end 4.933696 4.971542)
		(width 0.127)
		(layer "In2.Cu")
		(net "VR_PVDDQ_GHJ_AIREF2")
	)
	(segment
		(start 5.060696 4.844542)
		(end 5.060696 4.79425)
		(width 0.127)
		(layer "In2.Cu")
		(net "VR_PVDDQ_GHJ_AIREF2")
	)
	(segment
		(start 0.463804 -14.337538)
		(end 0.463804 -14.522196)
		(width 0.127)
		(layer "In2.Cu")
		(net "VR_PVDDQ_GHJ_AIREF2")
	)
	(segment
		(start 0.463804 -14.522196)
		(end 0.334264 -14.651736)
		(width 0.127)
		(layer "In2.Cu")
		(net "VR_PVDDQ_GHJ_AIREF2")
	)
	(segment
		(start 0.334264 -14.651736)
		(end -0.074422 -14.651736)
		(width 0.127)
		(layer "In2.Cu")
		(net "VR_PVDDQ_GHJ_AIREF2")
	)
	(segment
		(start -0.926338 -13.79982)
		(end -3.236468 -13.79982)
		(width 0.127)
		(layer "In2.Cu")
		(net "VR_PVDDQ_GHJ_AIREF2")
	)
	(segment
		(start -3.236468 -13.79982)
		(end -4.1148 -12.921488)
		(width 0.127)
		(layer "In2.Cu")
		(net "VR_PVDDQ_GHJ_AIREF2")
	)
	(segment
		(start -4.1148 -12.921488)
		(end -4.1148 1.762506)
		(width 0.127)
		(layer "In2.Cu")
		(net "VR_PVDDQ_GHJ_AIREF2")
	)
	(segment
		(start 4.933696 4.971542)
		(end 5.060696 4.844542)
		(width 0.127)
		(layer "In2.Cu")
		(net "VR_PVDDQ_GHJ_AIREF2")
	)
	(segment
		(start -0.074422 -14.651736)
		(end -0.926338 -13.79982)
		(width 0.127)
		(layer "In2.Cu")
		(net "VR_PVDDQ_GHJ_AIREF2")
	)
	(segment
		(start 5.070856 -4.773422)
		(end 5.070856 -4.352544)
		(width 0.127)
		(layer "F.Cu")
		(net "VR_PVDDQ_GHJ_AIREF1")
	)
	(segment
		(start 0.729234 -5.788914)
		(end 1.438402 -6.498082)
		(width 0.127)
		(layer "F.Cu")
		(net "VR_PVDDQ_GHJ_AIREF1")
	)
	(segment
		(start 7.5819 -1.552448)
		(end 6.99897 -1.552448)
		(width 0.127)
		(layer "F.Cu")
		(net "VR_PVDDQ_GHJ_AIREF1")
	)
	(segment
		(start 5.070856 -4.352544)
		(end 5.3594 -4.064)
		(width 0.127)
		(layer "F.Cu")
		(net "VR_PVDDQ_GHJ_AIREF1")
	)
	(segment
		(start 6.368288 -2.52857)
		(end 6.368288 -3.00101)
		(width 0.127)
		(layer "F.Cu")
		(net "VR_PVDDQ_GHJ_AIREF1")
	)
	(segment
		(start 6.388608 -2.16281)
		(end 6.388608 -2.50825)
		(width 0.127)
		(layer "F.Cu")
		(net "VR_PVDDQ_GHJ_AIREF1")
	)
	(segment
		(start 1.438402 -6.498082)
		(end 1.438402 -7.366762)
		(width 0.127)
		(layer "F.Cu")
		(net "VR_PVDDQ_GHJ_AIREF1")
	)
	(segment
		(start 5.3594 -4.064)
		(end 6.368288 -3.055112)
		(width 0.127)
		(layer "F.Cu")
		(net "VR_PVDDQ_GHJ_AIREF1")
	)
	(segment
		(start 1.565402 -7.493762)
		(end 2.067814 -7.493762)
		(width 0.127)
		(layer "F.Cu")
		(net "VR_PVDDQ_GHJ_AIREF1")
	)
	(segment
		(start 1.438402 -7.366762)
		(end 1.565402 -7.493762)
		(width 0.127)
		(layer "F.Cu")
		(net "VR_PVDDQ_GHJ_AIREF1")
	)
	(segment
		(start 6.368288 -3.055112)
		(end 6.368288 -3.00101)
		(width 0.127)
		(layer "F.Cu")
		(net "VR_PVDDQ_GHJ_AIREF1")
	)
	(segment
		(start 6.388608 -2.50825)
		(end 6.368288 -2.52857)
		(width 0.127)
		(layer "F.Cu")
		(net "VR_PVDDQ_GHJ_AIREF1")
	)
	(segment
		(start 6.99897 -1.552448)
		(end 6.388608 -2.16281)
		(width 0.127)
		(layer "F.Cu")
		(net "VR_PVDDQ_GHJ_AIREF1")
	)
	(via
		(at 5.3594 -4.064)
		(size 0.508)
		(drill 0.254)
		(layers "F.Cu" "B.Cu")
		(net "VR_PVDDQ_GHJ_AIREF1")
	)
	(via
		(at 5.070856 -4.773422)
		(size 0.508)
		(drill 0.254)
		(layers "F.Cu" "B.Cu")
		(net "VR_PVDDQ_GHJ_AIREF1")
	)
	(via
		(at 0.729234 -5.788914)
		(size 0.508)
		(drill 0.254)
		(layers "F.Cu" "B.Cu")
		(net "VR_PVDDQ_GHJ_AIREF1")
	)
	(segment
		(start 1.38176 -5.35686)
		(end 1.161288 -5.35686)
		(width 0.127)
		(layer "B.Cu")
		(net "VR_PVDDQ_GHJ_AIREF1")
	)
	(segment
		(start 1.161288 -5.35686)
		(end 0.729234 -5.788914)
		(width 0.127)
		(layer "B.Cu")
		(net "VR_PVDDQ_GHJ_AIREF1")
	)
	(segment
		(start 1.914652 -4.925568)
		(end 1.162812 -5.677408)
		(width 0.127)
		(layer "In9.Cu")
		(net "VR_PVDDQ_GHJ_AIREF1")
	)
	(segment
		(start 0.84074 -5.677408)
		(end 0.729234 -5.788914)
		(width 0.127)
		(layer "In9.Cu")
		(net "VR_PVDDQ_GHJ_AIREF1")
	)
	(segment
		(start 2.444496 -4.925568)
		(end 1.914652 -4.925568)
		(width 0.127)
		(layer "In9.Cu")
		(net "VR_PVDDQ_GHJ_AIREF1")
	)
	(segment
		(start 3.222244 -4.14782)
		(end 2.444496 -4.925568)
		(width 0.127)
		(layer "In9.Cu")
		(net "VR_PVDDQ_GHJ_AIREF1")
	)
	(segment
		(start 1.162812 -5.677408)
		(end 0.84074 -5.677408)
		(width 0.127)
		(layer "In9.Cu")
		(net "VR_PVDDQ_GHJ_AIREF1")
	)
	(segment
		(start 5.070856 -4.773422)
		(end 4.445254 -4.14782)
		(width 0.127)
		(layer "In9.Cu")
		(net "VR_PVDDQ_GHJ_AIREF1")
	)
	(segment
		(start 4.445254 -4.14782)
		(end 3.222244 -4.14782)
		(width 0.127)
		(layer "In9.Cu")
		(net "VR_PVDDQ_GHJ_AIREF1")
	)
	(segment
		(start 360.298238 -140.61567)
		(end 360.298238 -141.416278)
		(width 0.127)
		(layer "F.Cu")
		(net "VR_PVDDQ_DEF_AIREF2")
	)
	(segment
		(start 351.300796 -147.818602)
		(end 351.285302 -147.818602)
		(width 0.127)
		(layer "F.Cu")
		(net "VR_PVDDQ_DEF_AIREF2")
	)
	(segment
		(start 360.622088 -142.558516)
		(end 360.274108 -142.906496)
		(width 0.127)
		(layer "F.Cu")
		(net "VR_PVDDQ_DEF_AIREF2")
	)
	(segment
		(start 360.622088 -142.03172)
		(end 360.622088 -142.558516)
		(width 0.127)
		(layer "F.Cu")
		(net "VR_PVDDQ_DEF_AIREF2")
	)
	(segment
		(start 360.298238 -141.416278)
		(end 360.622088 -141.740128)
		(width 0.127)
		(layer "F.Cu")
		(net "VR_PVDDQ_DEF_AIREF2")
	)
	(segment
		(start 351.285302 -147.818602)
		(end 350.760538 -147.293838)
		(width 0.127)
		(layer "F.Cu")
		(net "VR_PVDDQ_DEF_AIREF2")
	)
	(segment
		(start 351.83699 -148.05787)
		(end 351.597722 -147.818602)
		(width 0.127)
		(layer "F.Cu")
		(net "VR_PVDDQ_DEF_AIREF2")
	)
	(segment
		(start 350.760538 -147.293838)
		(end 350.357186 -147.293838)
		(width 0.127)
		(layer "F.Cu")
		(net "VR_PVDDQ_DEF_AIREF2")
	)
	(segment
		(start 360.622088 -141.740128)
		(end 360.622088 -142.03172)
		(width 0.127)
		(layer "F.Cu")
		(net "VR_PVDDQ_DEF_AIREF2")
	)
	(segment
		(start 351.83699 -148.646388)
		(end 351.83699 -148.05787)
		(width 0.127)
		(layer "F.Cu")
		(net "VR_PVDDQ_DEF_AIREF2")
	)
	(segment
		(start 351.597722 -147.818602)
		(end 351.300796 -147.818602)
		(width 0.127)
		(layer "F.Cu")
		(net "VR_PVDDQ_DEF_AIREF2")
	)
	(via
		(at 360.274108 -142.906496)
		(size 0.508)
		(drill 0.254)
		(layers "F.Cu" "B.Cu")
		(net "VR_PVDDQ_DEF_AIREF2")
	)
	(via
		(at 351.300796 -147.818602)
		(size 0.508)
		(drill 0.254)
		(layers "F.Cu" "B.Cu")
		(net "VR_PVDDQ_DEF_AIREF2")
	)
	(segment
		(start 360.6673 -141.833092)
		(end 360.6673 -142.513304)
		(width 0.127)
		(layer "B.Cu")
		(net "VR_PVDDQ_DEF_AIREF2")
	)
	(segment
		(start 360.6673 -142.513304)
		(end 360.274108 -142.906496)
		(width 0.127)
		(layer "B.Cu")
		(net "VR_PVDDQ_DEF_AIREF2")
	)
	(segment
		(start 359.246932 -144.30248)
		(end 359.91292 -143.636492)
		(width 0.127)
		(layer "In2.Cu")
		(net "VR_PVDDQ_DEF_AIREF2")
	)
	(segment
		(start 359.91292 -143.636492)
		(end 359.91292 -143.267684)
		(width 0.127)
		(layer "In2.Cu")
		(net "VR_PVDDQ_DEF_AIREF2")
	)
	(segment
		(start 359.91292 -143.267684)
		(end 360.274108 -142.906496)
		(width 0.127)
		(layer "In2.Cu")
		(net "VR_PVDDQ_DEF_AIREF2")
	)
	(segment
		(start 353.925124 -146.520662)
		(end 353.925124 -145.057876)
		(width 0.127)
		(layer "In2.Cu")
		(net "VR_PVDDQ_DEF_AIREF2")
	)
	(segment
		(start 354.68052 -144.30248)
		(end 359.246932 -144.30248)
		(width 0.127)
		(layer "In2.Cu")
		(net "VR_PVDDQ_DEF_AIREF2")
	)
	(segment
		(start 353.925124 -145.057876)
		(end 354.68052 -144.30248)
		(width 0.127)
		(layer "In2.Cu")
		(net "VR_PVDDQ_DEF_AIREF2")
	)
	(segment
		(start 351.545398 -147.574)
		(end 352.871786 -147.574)
		(width 0.127)
		(layer "In2.Cu")
		(net "VR_PVDDQ_DEF_AIREF2")
	)
	(segment
		(start 352.871786 -147.574)
		(end 353.925124 -146.520662)
		(width 0.127)
		(layer "In2.Cu")
		(net "VR_PVDDQ_DEF_AIREF2")
	)
	(segment
		(start 351.300796 -147.818602)
		(end 351.545398 -147.574)
		(width 0.127)
		(layer "In2.Cu")
		(net "VR_PVDDQ_DEF_AIREF2")
	)
	(segment
		(start 350.357186 -155.218638)
		(end 350.9264 -155.218638)
		(width 0.127)
		(layer "F.Cu")
		(net "VR_PVDDQ_DEF_AIREF1")
	)
	(segment
		(start 362.36656 -142.045182)
		(end 362.36656 -142.459202)
		(width 0.127)
		(layer "F.Cu")
		(net "VR_PVDDQ_DEF_AIREF1")
	)
	(segment
		(start 361.098338 -140.61567)
		(end 361.098338 -141.008608)
		(width 0.127)
		(layer "F.Cu")
		(net "VR_PVDDQ_DEF_AIREF1")
	)
	(segment
		(start 362.36656 -142.459202)
		(end 362.011722 -142.81404)
		(width 0.127)
		(layer "F.Cu")
		(net "VR_PVDDQ_DEF_AIREF1")
	)
	(segment
		(start 362.36656 -141.883892)
		(end 362.36656 -142.045182)
		(width 0.127)
		(layer "F.Cu")
		(net "VR_PVDDQ_DEF_AIREF1")
	)
	(segment
		(start 361.326684 -141.236954)
		(end 361.719622 -141.236954)
		(width 0.127)
		(layer "F.Cu")
		(net "VR_PVDDQ_DEF_AIREF1")
	)
	(segment
		(start 361.719622 -141.236954)
		(end 362.36656 -141.883892)
		(width 0.127)
		(layer "F.Cu")
		(net "VR_PVDDQ_DEF_AIREF1")
	)
	(segment
		(start 361.098338 -141.008608)
		(end 361.326684 -141.236954)
		(width 0.127)
		(layer "F.Cu")
		(net "VR_PVDDQ_DEF_AIREF1")
	)
	(segment
		(start 350.9264 -155.218638)
		(end 351.18167 -155.473908)
		(width 0.127)
		(layer "F.Cu")
		(net "VR_PVDDQ_DEF_AIREF1")
	)
	(segment
		(start 351.18167 -155.473908)
		(end 351.505266 -155.797504)
		(width 0.127)
		(layer "F.Cu")
		(net "VR_PVDDQ_DEF_AIREF1")
	)
	(segment
		(start 351.505266 -155.797504)
		(end 351.505266 -156.4005)
		(width 0.127)
		(layer "F.Cu")
		(net "VR_PVDDQ_DEF_AIREF1")
	)
	(via
		(at 362.7628 -143.129)
		(size 0.6604)
		(drill 0.3302)
		(layers "F.Cu" "B.Cu")
		(net "VR_PVDDQ_DEF_AIREF1")
	)
	(via
		(at 351.18167 -155.473908)
		(size 0.508)
		(drill 0.254)
		(layers "F.Cu" "B.Cu")
		(net "VR_PVDDQ_DEF_AIREF1")
	)
	(via
		(at 362.011722 -142.81404)
		(size 0.508)
		(drill 0.254)
		(layers "F.Cu" "B.Cu")
		(net "VR_PVDDQ_DEF_AIREF1")
	)
	(segment
		(start 362.7628 -143.129)
		(end 362.326682 -143.129)
		(width 0.127)
		(layer "B.Cu")
		(net "VR_PVDDQ_DEF_AIREF1")
	)
	(segment
		(start 362.7628 -142.748)
		(end 362.7628 -143.129)
		(width 0.127)
		(layer "B.Cu")
		(net "VR_PVDDQ_DEF_AIREF1")
	)
	(segment
		(start 362.674154 -142.659354)
		(end 362.7628 -142.748)
		(width 0.127)
		(layer "B.Cu")
		(net "VR_PVDDQ_DEF_AIREF1")
	)
	(segment
		(start 362.674154 -141.84249)
		(end 362.674154 -142.659354)
		(width 0.127)
		(layer "B.Cu")
		(net "VR_PVDDQ_DEF_AIREF1")
	)
	(segment
		(start 362.326682 -143.129)
		(end 362.011722 -142.81404)
		(width 0.127)
		(layer "B.Cu")
		(net "VR_PVDDQ_DEF_AIREF1")
	)
	(segment
		(start 362.05033 -142.852648)
		(end 362.011722 -142.81404)
		(width 0.127)
		(layer "In11.Cu")
		(net "VR_PVDDQ_DEF_AIREF1")
	)
	(segment
		(start 352.209354 -155.2829)
		(end 352.806 -154.686254)
		(width 0.127)
		(layer "In11.Cu")
		(net "VR_PVDDQ_DEF_AIREF1")
	)
	(segment
		(start 362.05033 -143.03248)
		(end 362.05033 -142.852648)
		(width 0.127)
		(layer "In11.Cu")
		(net "VR_PVDDQ_DEF_AIREF1")
	)
	(segment
		(start 352.806 -154.686254)
		(end 352.806 -153.01341)
		(width 0.127)
		(layer "In11.Cu")
		(net "VR_PVDDQ_DEF_AIREF1")
	)
	(segment
		(start 352.9076 -150.04161)
		(end 354.4062 -148.54301)
		(width 0.127)
		(layer "In11.Cu")
		(net "VR_PVDDQ_DEF_AIREF1")
	)
	(segment
		(start 355.867462 -144.018)
		(end 361.350052 -144.018)
		(width 0.127)
		(layer "In11.Cu")
		(net "VR_PVDDQ_DEF_AIREF1")
	)
	(segment
		(start 354.4062 -145.479262)
		(end 355.867462 -144.018)
		(width 0.127)
		(layer "In11.Cu")
		(net "VR_PVDDQ_DEF_AIREF1")
	)
	(segment
		(start 351.372678 -155.2829)
		(end 352.209354 -155.2829)
		(width 0.127)
		(layer "In11.Cu")
		(net "VR_PVDDQ_DEF_AIREF1")
	)
	(segment
		(start 361.64774 -143.43507)
		(end 362.05033 -143.03248)
		(width 0.127)
		(layer "In11.Cu")
		(net "VR_PVDDQ_DEF_AIREF1")
	)
	(segment
		(start 361.64774 -143.720312)
		(end 361.64774 -143.43507)
		(width 0.127)
		(layer "In11.Cu")
		(net "VR_PVDDQ_DEF_AIREF1")
	)
	(segment
		(start 361.350052 -144.018)
		(end 361.64774 -143.720312)
		(width 0.127)
		(layer "In11.Cu")
		(net "VR_PVDDQ_DEF_AIREF1")
	)
	(segment
		(start 352.806 -153.01341)
		(end 352.9076 -152.91181)
		(width 0.127)
		(layer "In11.Cu")
		(net "VR_PVDDQ_DEF_AIREF1")
	)
	(segment
		(start 352.9076 -152.91181)
		(end 352.9076 -150.04161)
		(width 0.127)
		(layer "In11.Cu")
		(net "VR_PVDDQ_DEF_AIREF1")
	)
	(segment
		(start 354.4062 -148.54301)
		(end 354.4062 -145.479262)
		(width 0.127)
		(layer "In11.Cu")
		(net "VR_PVDDQ_DEF_AIREF1")
	)
	(segment
		(start 351.18167 -155.473908)
		(end 351.372678 -155.2829)
		(width 0.127)
		(layer "In11.Cu")
		(net "VR_PVDDQ_DEF_AIREF1")
	)
	(segment
		(start 343.678002 -12.289536)
		(end 343.678002 -12.9159)
		(width 0.127)
		(layer "F.Cu")
		(net "VR_PVDDQ_ABC_AIREF2")
	)
	(segment
		(start 350.012 -1.121156)
		(end 350.012 -0.56896)
		(width 0.127)
		(layer "F.Cu")
		(net "VR_PVDDQ_ABC_AIREF2")
	)
	(segment
		(start 350.555052 -1.397)
		(end 350.287844 -1.397)
		(width 0.127)
		(layer "F.Cu")
		(net "VR_PVDDQ_ABC_AIREF2")
	)
	(segment
		(start 343.741756 -12.225782)
		(end 343.678002 -12.289536)
		(width 0.127)
		(layer "F.Cu")
		(net "VR_PVDDQ_ABC_AIREF2")
	)
	(segment
		(start 350.012 -0.56896)
		(end 349.701358 -0.258318)
		(width 0.127)
		(layer "F.Cu")
		(net "VR_PVDDQ_ABC_AIREF2")
	)
	(segment
		(start 343.742264 -11.200892)
		(end 343.742264 -11.392154)
		(width 0.127)
		(layer "F.Cu")
		(net "VR_PVDDQ_ABC_AIREF2")
	)
	(segment
		(start 351.339658 -1.261364)
		(end 351.204022 -1.397)
		(width 0.127)
		(layer "F.Cu")
		(net "VR_PVDDQ_ABC_AIREF2")
	)
	(segment
		(start 343.741756 -11.392662)
		(end 343.741756 -12.225782)
		(width 0.127)
		(layer "F.Cu")
		(net "VR_PVDDQ_ABC_AIREF2")
	)
	(segment
		(start 350.575626 -1.417574)
		(end 350.555052 -1.397)
		(width 0.127)
		(layer "F.Cu")
		(net "VR_PVDDQ_ABC_AIREF2")
	)
	(segment
		(start 345.237308 -10.686796)
		(end 345.316048 -10.765536)
		(width 0.127)
		(layer "F.Cu")
		(net "VR_PVDDQ_ABC_AIREF2")
	)
	(segment
		(start 344.42654 -10.686796)
		(end 344.25636 -10.686796)
		(width 0.127)
		(layer "F.Cu")
		(net "VR_PVDDQ_ABC_AIREF2")
	)
	(segment
		(start 349.701358 -0.258318)
		(end 349.262192 -0.258318)
		(width 0.127)
		(layer "F.Cu")
		(net "VR_PVDDQ_ABC_AIREF2")
	)
	(segment
		(start 350.5962 -1.397)
		(end 350.575626 -1.417574)
		(width 0.127)
		(layer "F.Cu")
		(net "VR_PVDDQ_ABC_AIREF2")
	)
	(segment
		(start 350.287844 -1.397)
		(end 350.012 -1.121156)
		(width 0.127)
		(layer "F.Cu")
		(net "VR_PVDDQ_ABC_AIREF2")
	)
	(segment
		(start 345.316048 -10.765536)
		(end 345.800426 -10.765536)
		(width 0.127)
		(layer "F.Cu")
		(net "VR_PVDDQ_ABC_AIREF2")
	)
	(segment
		(start 343.742264 -11.392154)
		(end 343.741756 -11.392662)
		(width 0.127)
		(layer "F.Cu")
		(net "VR_PVDDQ_ABC_AIREF2")
	)
	(segment
		(start 345.800426 -10.765536)
		(end 346.061792 -11.026902)
		(width 0.127)
		(layer "F.Cu")
		(net "VR_PVDDQ_ABC_AIREF2")
	)
	(segment
		(start 344.42654 -10.686796)
		(end 345.237308 -10.686796)
		(width 0.127)
		(layer "F.Cu")
		(net "VR_PVDDQ_ABC_AIREF2")
	)
	(segment
		(start 351.204022 -1.397)
		(end 350.5962 -1.397)
		(width 0.127)
		(layer "F.Cu")
		(net "VR_PVDDQ_ABC_AIREF2")
	)
	(segment
		(start 344.25636 -10.686796)
		(end 343.742264 -11.200892)
		(width 0.127)
		(layer "F.Cu")
		(net "VR_PVDDQ_ABC_AIREF2")
	)
	(via
		(at 350.575626 -1.417574)
		(size 0.508)
		(drill 0.254)
		(layers "F.Cu" "B.Cu")
		(net "VR_PVDDQ_ABC_AIREF2")
	)
	(via
		(at 346.061792 -11.026902)
		(size 0.508)
		(drill 0.254)
		(layers "F.Cu" "B.Cu")
		(net "VR_PVDDQ_ABC_AIREF2")
	)
	(segment
		(start 347.643958 -10.622788)
		(end 347.643704 -10.622534)
		(width 0.127)
		(layer "In2.Cu")
		(net "VR_PVDDQ_ABC_AIREF2")
	)
	(segment
		(start 352.543364 -2.887726)
		(end 352.543364 -8.0772)
		(width 0.127)
		(layer "In2.Cu")
		(net "VR_PVDDQ_ABC_AIREF2")
	)
	(segment
		(start 347.643704 -10.622534)
		(end 347.433392 -10.622534)
		(width 0.127)
		(layer "In2.Cu")
		(net "VR_PVDDQ_ABC_AIREF2")
	)
	(segment
		(start 347.433392 -10.622534)
		(end 346.818966 -11.23696)
		(width 0.127)
		(layer "In2.Cu")
		(net "VR_PVDDQ_ABC_AIREF2")
	)
	(segment
		(start 350.914462 -1.258824)
		(end 352.543364 -2.887726)
		(width 0.127)
		(layer "In2.Cu")
		(net "VR_PVDDQ_ABC_AIREF2")
	)
	(segment
		(start 349.997776 -10.622788)
		(end 347.643958 -10.622788)
		(width 0.127)
		(layer "In2.Cu")
		(net "VR_PVDDQ_ABC_AIREF2")
	)
	(segment
		(start 350.734376 -1.258824)
		(end 350.914462 -1.258824)
		(width 0.127)
		(layer "In2.Cu")
		(net "VR_PVDDQ_ABC_AIREF2")
	)
	(segment
		(start 352.543364 -8.0772)
		(end 349.997776 -10.622788)
		(width 0.127)
		(layer "In2.Cu")
		(net "VR_PVDDQ_ABC_AIREF2")
	)
	(segment
		(start 346.818966 -11.23696)
		(end 346.27185 -11.23696)
		(width 0.127)
		(layer "In2.Cu")
		(net "VR_PVDDQ_ABC_AIREF2")
	)
	(segment
		(start 350.575626 -1.417574)
		(end 350.734376 -1.258824)
		(width 0.127)
		(layer "In2.Cu")
		(net "VR_PVDDQ_ABC_AIREF2")
	)
	(segment
		(start 346.27185 -11.23696)
		(end 346.061792 -11.026902)
		(width 0.127)
		(layer "In2.Cu")
		(net "VR_PVDDQ_ABC_AIREF2")
	)
	(segment
		(start 342.63203 -10.227056)
		(end 342.357964 -10.501122)
		(width 0.127)
		(layer "F.Cu")
		(net "VR_PVDDQ_ABC_AIREF1")
	)
	(segment
		(start 341.996776 -11.798046)
		(end 341.996776 -12.03579)
		(width 0.127)
		(layer "F.Cu")
		(net "VR_PVDDQ_ABC_AIREF1")
	)
	(segment
		(start 349.07728 -11.252708)
		(end 349.755206 -11.930634)
		(width 0.127)
		(layer "F.Cu")
		(net "VR_PVDDQ_ABC_AIREF1")
	)
	(segment
		(start 341.996776 -12.03579)
		(end 342.293194 -12.332208)
		(width 0.127)
		(layer "F.Cu")
		(net "VR_PVDDQ_ABC_AIREF1")
	)
	(segment
		(start 349.07728 -11.14933)
		(end 349.80499 -11.14933)
		(width 0.127)
		(layer "F.Cu")
		(net "VR_PVDDQ_ABC_AIREF1")
	)
	(segment
		(start 341.996776 -11.374882)
		(end 342.357964 -11.013694)
		(width 0.127)
		(layer "F.Cu")
		(net "VR_PVDDQ_ABC_AIREF1")
	)
	(segment
		(start 342.293194 -12.332208)
		(end 342.63711 -12.332208)
		(width 0.127)
		(layer "F.Cu")
		(net "VR_PVDDQ_ABC_AIREF1")
	)
	(segment
		(start 349.570802 -8.392414)
		(end 349.341186 -8.392414)
		(width 0.127)
		(layer "F.Cu")
		(net "VR_PVDDQ_ABC_AIREF1")
	)
	(segment
		(start 350.255586 -8.6487)
		(end 349.86087 -8.253984)
		(width 0.127)
		(layer "F.Cu")
		(net "VR_PVDDQ_ABC_AIREF1")
	)
	(segment
		(start 341.996776 -11.798046)
		(end 341.996776 -11.374882)
		(width 0.127)
		(layer "F.Cu")
		(net "VR_PVDDQ_ABC_AIREF1")
	)
	(segment
		(start 342.357964 -10.501122)
		(end 342.357964 -11.013694)
		(width 0.127)
		(layer "F.Cu")
		(net "VR_PVDDQ_ABC_AIREF1")
	)
	(segment
		(start 350.255586 -10.698734)
		(end 350.255586 -8.6487)
		(width 0.127)
		(layer "F.Cu")
		(net "VR_PVDDQ_ABC_AIREF1")
	)
	(segment
		(start 342.877902 -12.573)
		(end 342.877902 -12.9159)
		(width 0.127)
		(layer "F.Cu")
		(net "VR_PVDDQ_ABC_AIREF1")
	)
	(segment
		(start 342.63711 -12.332208)
		(end 342.877902 -12.573)
		(width 0.127)
		(layer "F.Cu")
		(net "VR_PVDDQ_ABC_AIREF1")
	)
	(segment
		(start 349.07728 -11.14933)
		(end 349.07728 -11.252708)
		(width 0.127)
		(layer "F.Cu")
		(net "VR_PVDDQ_ABC_AIREF1")
	)
	(segment
		(start 349.80499 -11.14933)
		(end 350.255586 -10.698734)
		(width 0.127)
		(layer "F.Cu")
		(net "VR_PVDDQ_ABC_AIREF1")
	)
	(segment
		(start 349.709232 -8.253984)
		(end 349.570802 -8.392414)
		(width 0.127)
		(layer "F.Cu")
		(net "VR_PVDDQ_ABC_AIREF1")
	)
	(segment
		(start 349.86087 -8.253984)
		(end 349.709232 -8.253984)
		(width 0.127)
		(layer "F.Cu")
		(net "VR_PVDDQ_ABC_AIREF1")
	)
	(via
		(at 342.63203 -10.227056)
		(size 0.508)
		(drill 0.254)
		(layers "F.Cu" "B.Cu")
		(net "VR_PVDDQ_ABC_AIREF1")
	)
	(via
		(at 349.755206 -11.930634)
		(size 0.508)
		(drill 0.254)
		(layers "F.Cu" "B.Cu")
		(net "VR_PVDDQ_ABC_AIREF1")
	)
	(segment
		(start 349.755206 -11.930634)
		(end 347.933264 -11.930634)
		(width 0.127)
		(layer "In2.Cu")
		(net "VR_PVDDQ_ABC_AIREF1")
	)
	(segment
		(start 343.942416 -12.8778)
		(end 342.89619 -11.831574)
		(width 0.127)
		(layer "In2.Cu")
		(net "VR_PVDDQ_ABC_AIREF1")
	)
	(segment
		(start 347.933264 -11.930634)
		(end 346.986098 -12.8778)
		(width 0.127)
		(layer "In2.Cu")
		(net "VR_PVDDQ_ABC_AIREF1")
	)
	(segment
		(start 342.89619 -11.831574)
		(end 342.89619 -10.491216)
		(width 0.127)
		(layer "In2.Cu")
		(net "VR_PVDDQ_ABC_AIREF1")
	)
	(segment
		(start 346.986098 -12.8778)
		(end 343.942416 -12.8778)
		(width 0.127)
		(layer "In2.Cu")
		(net "VR_PVDDQ_ABC_AIREF1")
	)
	(segment
		(start 342.89619 -10.491216)
		(end 342.63203 -10.227056)
		(width 0.127)
		(layer "In2.Cu")
		(net "VR_PVDDQ_ABC_AIREF1")
	)
	(segment
		(start 180.329586 -56.347614)
		(end 180.694838 -56.347614)
		(width 0.127)
		(layer "F.Cu")
		(net "VR_PVCCIO_CPU1_AIREF1")
	)
	(segment
		(start 181.2798 -56.932576)
		(end 181.8132 -57.465976)
		(width 0.127)
		(layer "F.Cu")
		(net "VR_PVCCIO_CPU1_AIREF1")
	)
	(segment
		(start 167.389302 -64.3509)
		(end 167.389302 -63.87719)
		(width 0.127)
		(layer "F.Cu")
		(net "VR_PVCCIO_CPU1_AIREF1")
	)
	(segment
		(start 180.694838 -56.347614)
		(end 181.2798 -56.932576)
		(width 0.127)
		(layer "F.Cu")
		(net "VR_PVCCIO_CPU1_AIREF1")
	)
	(segment
		(start 167.389302 -63.87719)
		(end 167.0558 -63.543688)
		(width 0.127)
		(layer "F.Cu")
		(net "VR_PVCCIO_CPU1_AIREF1")
	)
	(segment
		(start 181.8132 -57.465976)
		(end 181.8132 -57.785)
		(width 0.127)
		(layer "F.Cu")
		(net "VR_PVCCIO_CPU1_AIREF1")
	)
	(via
		(at 181.2798 -56.932576)
		(size 0.508)
		(drill 0.254)
		(layers "F.Cu" "B.Cu")
		(net "VR_PVCCIO_CPU1_AIREF1")
	)
	(via
		(at 167.0558 -63.543688)
		(size 0.508)
		(drill 0.254)
		(layers "F.Cu" "B.Cu")
		(net "VR_PVCCIO_CPU1_AIREF1")
	)
	(segment
		(start 168.529 -65.405)
		(end 168.40073 -65.405)
		(width 0.127)
		(layer "B.Cu")
		(net "VR_PVCCIO_CPU1_AIREF1")
	)
	(segment
		(start 169.0243 -65.4685)
		(end 168.9608 -65.405)
		(width 0.127)
		(layer "B.Cu")
		(net "VR_PVCCIO_CPU1_AIREF1")
	)
	(segment
		(start 168.9608 -65.405)
		(end 168.529 -65.405)
		(width 0.127)
		(layer "B.Cu")
		(net "VR_PVCCIO_CPU1_AIREF1")
	)
	(segment
		(start 168.40073 -65.405)
		(end 167.350694 -64.354964)
		(width 0.127)
		(layer "B.Cu")
		(net "VR_PVCCIO_CPU1_AIREF1")
	)
	(segment
		(start 169.545 -65.4685)
		(end 169.0243 -65.4685)
		(width 0.127)
		(layer "B.Cu")
		(net "VR_PVCCIO_CPU1_AIREF1")
	)
	(segment
		(start 167.350694 -63.838582)
		(end 167.0558 -63.543688)
		(width 0.127)
		(layer "B.Cu")
		(net "VR_PVCCIO_CPU1_AIREF1")
	)
	(segment
		(start 167.350694 -64.354964)
		(end 167.350694 -63.838582)
		(width 0.127)
		(layer "B.Cu")
		(net "VR_PVCCIO_CPU1_AIREF1")
	)
	(segment
		(start 180.659024 -56.3118)
		(end 181.2798 -56.932576)
		(width 0.127)
		(layer "In9.Cu")
		(net "VR_PVCCIO_CPU1_AIREF1")
	)
	(segment
		(start 173.15688 -61.411866)
		(end 177.647346 -56.9214)
		(width 0.127)
		(layer "In9.Cu")
		(net "VR_PVCCIO_CPU1_AIREF1")
	)
	(segment
		(start 173.15688 -62.81293)
		(end 173.15688 -61.411866)
		(width 0.127)
		(layer "In9.Cu")
		(net "VR_PVCCIO_CPU1_AIREF1")
	)
	(segment
		(start 169.980864 -64.389)
		(end 170.819064 -63.5508)
		(width 0.127)
		(layer "In9.Cu")
		(net "VR_PVCCIO_CPU1_AIREF1")
	)
	(segment
		(start 180.26761 -56.3118)
		(end 180.659024 -56.3118)
		(width 0.127)
		(layer "In9.Cu")
		(net "VR_PVCCIO_CPU1_AIREF1")
	)
	(segment
		(start 167.562022 -64.389)
		(end 169.980864 -64.389)
		(width 0.127)
		(layer "In9.Cu")
		(net "VR_PVCCIO_CPU1_AIREF1")
	)
	(segment
		(start 179.65801 -56.9214)
		(end 180.26761 -56.3118)
		(width 0.127)
		(layer "In9.Cu")
		(net "VR_PVCCIO_CPU1_AIREF1")
	)
	(segment
		(start 167.286432 -63.77432)
		(end 167.286432 -64.11341)
		(width 0.127)
		(layer "In9.Cu")
		(net "VR_PVCCIO_CPU1_AIREF1")
	)
	(segment
		(start 167.286432 -64.11341)
		(end 167.562022 -64.389)
		(width 0.127)
		(layer "In9.Cu")
		(net "VR_PVCCIO_CPU1_AIREF1")
	)
	(segment
		(start 170.819064 -63.5508)
		(end 172.41901 -63.5508)
		(width 0.127)
		(layer "In9.Cu")
		(net "VR_PVCCIO_CPU1_AIREF1")
	)
	(segment
		(start 177.647346 -56.9214)
		(end 179.65801 -56.9214)
		(width 0.127)
		(layer "In9.Cu")
		(net "VR_PVCCIO_CPU1_AIREF1")
	)
	(segment
		(start 167.0558 -63.543688)
		(end 167.286432 -63.77432)
		(width 0.127)
		(layer "In9.Cu")
		(net "VR_PVCCIO_CPU1_AIREF1")
	)
	(segment
		(start 172.41901 -63.5508)
		(end 173.15688 -62.81293)
		(width 0.127)
		(layer "In9.Cu")
		(net "VR_PVCCIO_CPU1_AIREF1")
	)
	(segment
		(start 351.766124 -100.29063)
		(end 351.36963 -100.29063)
		(width 0.127)
		(layer "F.Cu")
		(net "VR_PVCCIO_CPU0_AIREF1")
	)
	(segment
		(start 349.927164 -99.544886)
		(end 350.623886 -99.544886)
		(width 0.127)
		(layer "F.Cu")
		(net "VR_PVCCIO_CPU0_AIREF1")
	)
	(segment
		(start 350.623886 -99.544886)
		(end 350.7232 -99.6442)
		(width 0.127)
		(layer "F.Cu")
		(net "VR_PVCCIO_CPU0_AIREF1")
	)
	(segment
		(start 352.7298 -100.29063)
		(end 351.766124 -100.29063)
		(width 0.127)
		(layer "F.Cu")
		(net "VR_PVCCIO_CPU0_AIREF1")
	)
	(segment
		(start 351.36963 -100.29063)
		(end 350.7232 -99.6442)
		(width 0.127)
		(layer "F.Cu")
		(net "VR_PVCCIO_CPU0_AIREF1")
	)
	(via
		(at 344.542364 -91.61272)
		(size 0.508)
		(drill 0.254)
		(layers "F.Cu" "B.Cu")
		(net "VR_PVCCIO_CPU0_AIREF1")
	)
	(via
		(at 351.766124 -100.29063)
		(size 0.508)
		(drill 0.254)
		(layers "F.Cu" "B.Cu")
		(net "VR_PVCCIO_CPU0_AIREF1")
	)
	(via
		(at 350.7232 -99.6442)
		(size 0.508)
		(drill 0.254)
		(layers "F.Cu" "B.Cu")
		(net "VR_PVCCIO_CPU0_AIREF1")
	)
	(segment
		(start 344.732102 -89.9033)
		(end 344.732102 -90.553286)
		(width 0.127)
		(layer "B.Cu")
		(net "VR_PVCCIO_CPU0_AIREF1")
	)
	(segment
		(start 344.390472 -91.764612)
		(end 343.81186 -91.764612)
		(width 0.127)
		(layer "B.Cu")
		(net "VR_PVCCIO_CPU0_AIREF1")
	)
	(segment
		(start 343.81186 -91.764612)
		(end 343.511378 -91.46413)
		(width 0.127)
		(layer "B.Cu")
		(net "VR_PVCCIO_CPU0_AIREF1")
	)
	(segment
		(start 344.461846 -90.97137)
		(end 344.461846 -91.40317)
		(width 0.127)
		(layer "B.Cu")
		(net "VR_PVCCIO_CPU0_AIREF1")
	)
	(segment
		(start 344.542364 -91.483688)
		(end 344.542364 -91.61272)
		(width 0.127)
		(layer "B.Cu")
		(net "VR_PVCCIO_CPU0_AIREF1")
	)
	(segment
		(start 344.461846 -91.40317)
		(end 344.542364 -91.483688)
		(width 0.127)
		(layer "B.Cu")
		(net "VR_PVCCIO_CPU0_AIREF1")
	)
	(segment
		(start 344.461846 -90.823542)
		(end 344.461846 -90.97137)
		(width 0.127)
		(layer "B.Cu")
		(net "VR_PVCCIO_CPU0_AIREF1")
	)
	(segment
		(start 344.732102 -90.553286)
		(end 344.461846 -90.823542)
		(width 0.127)
		(layer "B.Cu")
		(net "VR_PVCCIO_CPU0_AIREF1")
	)
	(segment
		(start 344.542364 -91.61272)
		(end 344.390472 -91.764612)
		(width 0.127)
		(layer "B.Cu")
		(net "VR_PVCCIO_CPU0_AIREF1")
	)
	(segment
		(start 344.542364 -91.61272)
		(end 345.24569 -92.316046)
		(width 0.127)
		(layer "In11.Cu")
		(net "VR_PVCCIO_CPU0_AIREF1")
	)
	(segment
		(start 351.18929 -92.316046)
		(end 352.2472 -93.373956)
		(width 0.127)
		(layer "In11.Cu")
		(net "VR_PVCCIO_CPU0_AIREF1")
	)
	(segment
		(start 352.2472 -97.742248)
		(end 350.97212 -99.017328)
		(width 0.127)
		(layer "In11.Cu")
		(net "VR_PVCCIO_CPU0_AIREF1")
	)
	(segment
		(start 345.24569 -92.316046)
		(end 351.18929 -92.316046)
		(width 0.127)
		(layer "In11.Cu")
		(net "VR_PVCCIO_CPU0_AIREF1")
	)
	(segment
		(start 350.97212 -99.017328)
		(end 350.97212 -99.39528)
		(width 0.127)
		(layer "In11.Cu")
		(net "VR_PVCCIO_CPU0_AIREF1")
	)
	(segment
		(start 352.2472 -93.373956)
		(end 352.2472 -97.742248)
		(width 0.127)
		(layer "In11.Cu")
		(net "VR_PVCCIO_CPU0_AIREF1")
	)
	(segment
		(start 350.97212 -99.39528)
		(end 350.7232 -99.6442)
		(width 0.127)
		(layer "In11.Cu")
		(net "VR_PVCCIO_CPU0_AIREF1")
	)
	(segment
		(start 25.778206 -93.4466)
		(end 25.04186 -93.4466)
		(width 0.127)
		(layer "F.Cu")
		(net "VR_PVCCIN_CPU1_AIREF5")
	)
	(segment
		(start 23.600156 -93.323156)
		(end 24.05634 -93.323156)
		(width 0.127)
		(layer "F.Cu")
		(net "VR_PVCCIN_CPU1_AIREF5")
	)
	(segment
		(start 22.932898 -92.655898)
		(end 23.600156 -93.323156)
		(width 0.127)
		(layer "F.Cu")
		(net "VR_PVCCIN_CPU1_AIREF5")
	)
	(segment
		(start 30.15488 -87.551768)
		(end 29.346144 -86.743032)
		(width 0.127)
		(layer "F.Cu")
		(net "VR_PVCCIN_CPU1_AIREF5")
	)
	(segment
		(start 25.87879 -93.547184)
		(end 25.778206 -93.4466)
		(width 0.127)
		(layer "F.Cu")
		(net "VR_PVCCIN_CPU1_AIREF5")
	)
	(segment
		(start 28.82773 -86.224618)
		(end 29.346144 -86.743032)
		(width 0.127)
		(layer "F.Cu")
		(net "VR_PVCCIN_CPU1_AIREF5")
	)
	(segment
		(start 24.438356 -93.323156)
		(end 24.5618 -93.4466)
		(width 0.127)
		(layer "F.Cu")
		(net "VR_PVCCIN_CPU1_AIREF5")
	)
	(segment
		(start 24.05634 -93.323156)
		(end 24.438356 -93.323156)
		(width 0.127)
		(layer "F.Cu")
		(net "VR_PVCCIN_CPU1_AIREF5")
	)
	(segment
		(start 22.3266 -92.655898)
		(end 22.932898 -92.655898)
		(width 0.127)
		(layer "F.Cu")
		(net "VR_PVCCIN_CPU1_AIREF5")
	)
	(segment
		(start 31.02991 -87.551768)
		(end 30.15488 -87.551768)
		(width 0.127)
		(layer "F.Cu")
		(net "VR_PVCCIN_CPU1_AIREF5")
	)
	(segment
		(start 25.89911 -93.547184)
		(end 25.87879 -93.547184)
		(width 0.127)
		(layer "F.Cu")
		(net "VR_PVCCIN_CPU1_AIREF5")
	)
	(segment
		(start 28.82773 -85.983318)
		(end 28.82773 -86.224618)
		(width 0.127)
		(layer "F.Cu")
		(net "VR_PVCCIN_CPU1_AIREF5")
	)
	(segment
		(start 24.5618 -93.4466)
		(end 25.04186 -93.4466)
		(width 0.127)
		(layer "F.Cu")
		(net "VR_PVCCIN_CPU1_AIREF5")
	)
	(via
		(at 29.346144 -86.743032)
		(size 0.508)
		(drill 0.254)
		(layers "F.Cu" "B.Cu")
		(net "VR_PVCCIN_CPU1_AIREF5")
	)
	(via
		(at 25.89911 -93.547184)
		(size 0.508)
		(drill 0.254)
		(layers "F.Cu" "B.Cu")
		(net "VR_PVCCIN_CPU1_AIREF5")
	)
	(segment
		(start 28.6385 -90.07729)
		(end 28.6385 -87.385398)
		(width 0.127)
		(layer "In4.Cu")
		(net "VR_PVCCIN_CPU1_AIREF5")
	)
	(segment
		(start 25.89911 -93.69806)
		(end 26.02611 -93.82506)
		(width 0.127)
		(layer "In4.Cu")
		(net "VR_PVCCIN_CPU1_AIREF5")
	)
	(segment
		(start 25.89911 -93.547184)
		(end 25.89911 -93.69806)
		(width 0.127)
		(layer "In4.Cu")
		(net "VR_PVCCIN_CPU1_AIREF5")
	)
	(segment
		(start 28.91409 -87.109808)
		(end 28.972256 -87.109808)
		(width 0.127)
		(layer "In4.Cu")
		(net "VR_PVCCIN_CPU1_AIREF5")
	)
	(segment
		(start 28.6385 -87.385398)
		(end 28.91409 -87.109808)
		(width 0.127)
		(layer "In4.Cu")
		(net "VR_PVCCIN_CPU1_AIREF5")
	)
	(segment
		(start 26.260044 -93.82506)
		(end 28.067 -92.018104)
		(width 0.127)
		(layer "In4.Cu")
		(net "VR_PVCCIN_CPU1_AIREF5")
	)
	(segment
		(start 28.972256 -87.109808)
		(end 29.346144 -86.743032)
		(width 0.127)
		(layer "In4.Cu")
		(net "VR_PVCCIN_CPU1_AIREF5")
	)
	(segment
		(start 28.067 -92.018104)
		(end 28.067 -90.64879)
		(width 0.127)
		(layer "In4.Cu")
		(net "VR_PVCCIN_CPU1_AIREF5")
	)
	(segment
		(start 26.02611 -93.82506)
		(end 26.260044 -93.82506)
		(width 0.127)
		(layer "In4.Cu")
		(net "VR_PVCCIN_CPU1_AIREF5")
	)
	(segment
		(start 28.067 -90.64879)
		(end 28.6385 -90.07729)
		(width 0.127)
		(layer "In4.Cu")
		(net "VR_PVCCIN_CPU1_AIREF5")
	)
	(segment
		(start 30.013656 -78.407006)
		(end 31.02991 -79.42326)
		(width 0.127)
		(layer "F.Cu")
		(net "VR_PVCCIN_CPU1_AIREF4")
	)
	(segment
		(start 29.346144 -78.615032)
		(end 29.623766 -78.33741)
		(width 0.127)
		(layer "F.Cu")
		(net "VR_PVCCIN_CPU1_AIREF4")
	)
	(segment
		(start 29.623766 -78.33741)
		(end 30.013656 -78.33741)
		(width 0.127)
		(layer "F.Cu")
		(net "VR_PVCCIN_CPU1_AIREF4")
	)
	(segment
		(start 23.259288 -91.856052)
		(end 22.3266 -91.856052)
		(width 0.127)
		(layer "F.Cu")
		(net "VR_PVCCIN_CPU1_AIREF4")
	)
	(segment
		(start 31.02991 -79.42326)
		(end 31.02991 -79.423768)
		(width 0.127)
		(layer "F.Cu")
		(net "VR_PVCCIN_CPU1_AIREF4")
	)
	(segment
		(start 24.03602 -91.36888)
		(end 23.74646 -91.36888)
		(width 0.127)
		(layer "F.Cu")
		(net "VR_PVCCIN_CPU1_AIREF4")
	)
	(segment
		(start 25.02408 -91.52382)
		(end 25.79116 -91.52382)
		(width 0.127)
		(layer "F.Cu")
		(net "VR_PVCCIN_CPU1_AIREF4")
	)
	(segment
		(start 24.86914 -91.36888)
		(end 25.02408 -91.52382)
		(width 0.127)
		(layer "F.Cu")
		(net "VR_PVCCIN_CPU1_AIREF4")
	)
	(segment
		(start 30.013656 -78.33741)
		(end 30.013656 -78.407006)
		(width 0.127)
		(layer "F.Cu")
		(net "VR_PVCCIN_CPU1_AIREF4")
	)
	(segment
		(start 23.74646 -91.36888)
		(end 23.259288 -91.856052)
		(width 0.127)
		(layer "F.Cu")
		(net "VR_PVCCIN_CPU1_AIREF4")
	)
	(segment
		(start 24.03602 -91.36888)
		(end 24.86914 -91.36888)
		(width 0.127)
		(layer "F.Cu")
		(net "VR_PVCCIN_CPU1_AIREF4")
	)
	(segment
		(start 25.79116 -91.52382)
		(end 25.8445 -91.47048)
		(width 0.127)
		(layer "F.Cu")
		(net "VR_PVCCIN_CPU1_AIREF4")
	)
	(via
		(at 29.346144 -78.615032)
		(size 0.508)
		(drill 0.254)
		(layers "F.Cu" "B.Cu")
		(net "VR_PVCCIN_CPU1_AIREF4")
	)
	(via
		(at 25.8445 -91.47048)
		(size 0.508)
		(drill 0.254)
		(layers "F.Cu" "B.Cu")
		(net "VR_PVCCIN_CPU1_AIREF4")
	)
	(segment
		(start 28.448 -79.272384)
		(end 28.448 -82.54873)
		(width 0.127)
		(layer "In4.Cu")
		(net "VR_PVCCIN_CPU1_AIREF4")
	)
	(segment
		(start 28.448 -82.54873)
		(end 28.03144 -82.96529)
		(width 0.127)
		(layer "In4.Cu")
		(net "VR_PVCCIN_CPU1_AIREF4")
	)
	(segment
		(start 28.03144 -82.96529)
		(end 28.03144 -86.56193)
		(width 0.127)
		(layer "In4.Cu")
		(net "VR_PVCCIN_CPU1_AIREF4")
	)
	(segment
		(start 28.828492 -78.891892)
		(end 28.448 -79.272384)
		(width 0.127)
		(layer "In4.Cu")
		(net "VR_PVCCIN_CPU1_AIREF4")
	)
	(segment
		(start 26.23312 -91.742514)
		(end 25.961086 -91.47048)
		(width 0.127)
		(layer "In4.Cu")
		(net "VR_PVCCIN_CPU1_AIREF4")
	)
	(segment
		(start 26.518616 -91.742514)
		(end 26.23312 -91.742514)
		(width 0.127)
		(layer "In4.Cu")
		(net "VR_PVCCIN_CPU1_AIREF4")
	)
	(segment
		(start 28.03144 -86.56193)
		(end 27.432 -87.16137)
		(width 0.127)
		(layer "In4.Cu")
		(net "VR_PVCCIN_CPU1_AIREF4")
	)
	(segment
		(start 29.346144 -78.615032)
		(end 29.069284 -78.891892)
		(width 0.127)
		(layer "In4.Cu")
		(net "VR_PVCCIN_CPU1_AIREF4")
	)
	(segment
		(start 27.432 -87.16137)
		(end 27.432 -90.82913)
		(width 0.127)
		(layer "In4.Cu")
		(net "VR_PVCCIN_CPU1_AIREF4")
	)
	(segment
		(start 27.432 -90.82913)
		(end 26.518616 -91.742514)
		(width 0.127)
		(layer "In4.Cu")
		(net "VR_PVCCIN_CPU1_AIREF4")
	)
	(segment
		(start 25.961086 -91.47048)
		(end 25.8445 -91.47048)
		(width 0.127)
		(layer "In4.Cu")
		(net "VR_PVCCIN_CPU1_AIREF4")
	)
	(segment
		(start 29.069284 -78.891892)
		(end 28.828492 -78.891892)
		(width 0.127)
		(layer "In4.Cu")
		(net "VR_PVCCIN_CPU1_AIREF4")
	)
	(segment
		(start 30.3276 -70.872858)
		(end 30.75051 -71.295768)
		(width 0.127)
		(layer "F.Cu")
		(net "VR_PVCCIN_CPU1_AIREF3")
	)
	(segment
		(start 24.03602 -89.7509)
		(end 24.892 -89.7509)
		(width 0.127)
		(layer "F.Cu")
		(net "VR_PVCCIN_CPU1_AIREF3")
	)
	(segment
		(start 22.884638 -91.055952)
		(end 23.41372 -90.52687)
		(width 0.127)
		(layer "F.Cu")
		(net "VR_PVCCIN_CPU1_AIREF3")
	)
	(segment
		(start 25.656286 -89.61374)
		(end 25.92324 -89.346786)
		(width 0.127)
		(layer "F.Cu")
		(net "VR_PVCCIN_CPU1_AIREF3")
	)
	(segment
		(start 23.41372 -90.52687)
		(end 23.41372 -90.144854)
		(width 0.127)
		(layer "F.Cu")
		(net "VR_PVCCIN_CPU1_AIREF3")
	)
	(segment
		(start 30.75051 -71.295768)
		(end 31.02991 -71.295768)
		(width 0.127)
		(layer "F.Cu")
		(net "VR_PVCCIN_CPU1_AIREF3")
	)
	(segment
		(start 22.3266 -91.055952)
		(end 22.884638 -91.055952)
		(width 0.127)
		(layer "F.Cu")
		(net "VR_PVCCIN_CPU1_AIREF3")
	)
	(segment
		(start 23.41372 -90.144854)
		(end 23.807674 -89.7509)
		(width 0.127)
		(layer "F.Cu")
		(net "VR_PVCCIN_CPU1_AIREF3")
	)
	(segment
		(start 30.3276 -69.8754)
		(end 30.3276 -70.872858)
		(width 0.127)
		(layer "F.Cu")
		(net "VR_PVCCIN_CPU1_AIREF3")
	)
	(segment
		(start 23.807674 -89.7509)
		(end 24.03602 -89.7509)
		(width 0.127)
		(layer "F.Cu")
		(net "VR_PVCCIN_CPU1_AIREF3")
	)
	(segment
		(start 29.957776 -69.8754)
		(end 30.3276 -69.8754)
		(width 0.127)
		(layer "F.Cu")
		(net "VR_PVCCIN_CPU1_AIREF3")
	)
	(segment
		(start 29.346144 -70.487032)
		(end 29.957776 -69.8754)
		(width 0.127)
		(layer "F.Cu")
		(net "VR_PVCCIN_CPU1_AIREF3")
	)
	(segment
		(start 24.892 -89.7509)
		(end 25.02916 -89.61374)
		(width 0.127)
		(layer "F.Cu")
		(net "VR_PVCCIN_CPU1_AIREF3")
	)
	(segment
		(start 25.02916 -89.61374)
		(end 25.656286 -89.61374)
		(width 0.127)
		(layer "F.Cu")
		(net "VR_PVCCIN_CPU1_AIREF3")
	)
	(via
		(at 25.92324 -89.346786)
		(size 0.508)
		(drill 0.254)
		(layers "F.Cu" "B.Cu")
		(net "VR_PVCCIN_CPU1_AIREF3")
	)
	(via
		(at 29.346144 -70.487032)
		(size 0.508)
		(drill 0.254)
		(layers "F.Cu" "B.Cu")
		(net "VR_PVCCIN_CPU1_AIREF3")
	)
	(segment
		(start 26.29916 -89.722706)
		(end 26.29916 -89.73312)
		(width 0.127)
		(layer "In4.Cu")
		(net "VR_PVCCIN_CPU1_AIREF3")
	)
	(segment
		(start 26.788364 -89.60612)
		(end 26.788364 -86.854792)
		(width 0.127)
		(layer "In4.Cu")
		(net "VR_PVCCIN_CPU1_AIREF3")
	)
	(segment
		(start 27.051 -74.72045)
		(end 28.44546 -73.32599)
		(width 0.127)
		(layer "In4.Cu")
		(net "VR_PVCCIN_CPU1_AIREF3")
	)
	(segment
		(start 26.788364 -86.854792)
		(end 27.38628 -86.256876)
		(width 0.127)
		(layer "In4.Cu")
		(net "VR_PVCCIN_CPU1_AIREF3")
	)
	(segment
		(start 28.44546 -73.32599)
		(end 28.44546 -70.973442)
		(width 0.127)
		(layer "In4.Cu")
		(net "VR_PVCCIN_CPU1_AIREF3")
	)
	(segment
		(start 26.661364 -89.73312)
		(end 26.788364 -89.60612)
		(width 0.127)
		(layer "In4.Cu")
		(net "VR_PVCCIN_CPU1_AIREF3")
	)
	(segment
		(start 28.72105 -70.697852)
		(end 29.135324 -70.697852)
		(width 0.127)
		(layer "In4.Cu")
		(net "VR_PVCCIN_CPU1_AIREF3")
	)
	(segment
		(start 26.29916 -89.73312)
		(end 26.661364 -89.73312)
		(width 0.127)
		(layer "In4.Cu")
		(net "VR_PVCCIN_CPU1_AIREF3")
	)
	(segment
		(start 25.92324 -89.346786)
		(end 26.29916 -89.722706)
		(width 0.127)
		(layer "In4.Cu")
		(net "VR_PVCCIN_CPU1_AIREF3")
	)
	(segment
		(start 29.135324 -70.697852)
		(end 29.346144 -70.487032)
		(width 0.127)
		(layer "In4.Cu")
		(net "VR_PVCCIN_CPU1_AIREF3")
	)
	(segment
		(start 27.38628 -86.256876)
		(end 27.38628 -81.25587)
		(width 0.127)
		(layer "In4.Cu")
		(net "VR_PVCCIN_CPU1_AIREF3")
	)
	(segment
		(start 27.38628 -81.25587)
		(end 27.051 -80.92059)
		(width 0.127)
		(layer "In4.Cu")
		(net "VR_PVCCIN_CPU1_AIREF3")
	)
	(segment
		(start 28.44546 -70.973442)
		(end 28.72105 -70.697852)
		(width 0.127)
		(layer "In4.Cu")
		(net "VR_PVCCIN_CPU1_AIREF3")
	)
	(segment
		(start 27.051 -80.92059)
		(end 27.051 -74.72045)
		(width 0.127)
		(layer "In4.Cu")
		(net "VR_PVCCIN_CPU1_AIREF3")
	)
	(segment
		(start 29.10586 -61.83122)
		(end 29.10586 -62.086998)
		(width 0.127)
		(layer "F.Cu")
		(net "VR_PVCCIN_CPU1_AIREF2")
	)
	(segment
		(start 29.635958 -61.716158)
		(end 29.220922 -61.716158)
		(width 0.127)
		(layer "F.Cu")
		(net "VR_PVCCIN_CPU1_AIREF2")
	)
	(segment
		(start 29.635958 -61.810138)
		(end 30.17393 -62.34811)
		(width 0.127)
		(layer "F.Cu")
		(net "VR_PVCCIN_CPU1_AIREF2")
	)
	(segment
		(start 29.220922 -61.716158)
		(end 29.10586 -61.83122)
		(width 0.127)
		(layer "F.Cu")
		(net "VR_PVCCIN_CPU1_AIREF2")
	)
	(segment
		(start 25.035002 -87.686134)
		(end 25.603454 -87.686134)
		(width 0.127)
		(layer "F.Cu")
		(net "VR_PVCCIN_CPU1_AIREF2")
	)
	(segment
		(start 29.10586 -62.086998)
		(end 29.34335 -62.324488)
		(width 0.127)
		(layer "F.Cu")
		(net "VR_PVCCIN_CPU1_AIREF2")
	)
	(segment
		(start 30.17393 -62.34811)
		(end 30.17393 -62.77991)
		(width 0.127)
		(layer "F.Cu")
		(net "VR_PVCCIN_CPU1_AIREF2")
	)
	(segment
		(start 24.879554 -87.841582)
		(end 25.035002 -87.686134)
		(width 0.127)
		(layer "F.Cu")
		(net "VR_PVCCIN_CPU1_AIREF2")
	)
	(segment
		(start 29.635958 -61.716158)
		(end 29.635958 -61.810138)
		(width 0.127)
		(layer "F.Cu")
		(net "VR_PVCCIN_CPU1_AIREF2")
	)
	(segment
		(start 30.17393 -62.77991)
		(end 30.561788 -63.167768)
		(width 0.127)
		(layer "F.Cu")
		(net "VR_PVCCIN_CPU1_AIREF2")
	)
	(segment
		(start 25.603454 -87.686134)
		(end 25.87752 -87.9602)
		(width 0.127)
		(layer "F.Cu")
		(net "VR_PVCCIN_CPU1_AIREF2")
	)
	(segment
		(start 24.007826 -87.841582)
		(end 24.879554 -87.841582)
		(width 0.127)
		(layer "F.Cu")
		(net "VR_PVCCIN_CPU1_AIREF2")
	)
	(segment
		(start 23.54834 -88.05672)
		(end 23.763478 -87.841582)
		(width 0.127)
		(layer "F.Cu")
		(net "VR_PVCCIN_CPU1_AIREF2")
	)
	(segment
		(start 22.3266 -90.215466)
		(end 23.54834 -88.993726)
		(width 0.127)
		(layer "F.Cu")
		(net "VR_PVCCIN_CPU1_AIREF2")
	)
	(segment
		(start 23.763478 -87.841582)
		(end 24.007826 -87.841582)
		(width 0.127)
		(layer "F.Cu")
		(net "VR_PVCCIN_CPU1_AIREF2")
	)
	(segment
		(start 23.54834 -88.993726)
		(end 23.54834 -88.05672)
		(width 0.127)
		(layer "F.Cu")
		(net "VR_PVCCIN_CPU1_AIREF2")
	)
	(segment
		(start 30.561788 -63.167768)
		(end 31.02991 -63.167768)
		(width 0.127)
		(layer "F.Cu")
		(net "VR_PVCCIN_CPU1_AIREF2")
	)
	(segment
		(start 22.3266 -90.256106)
		(end 22.3266 -90.215466)
		(width 0.127)
		(layer "F.Cu")
		(net "VR_PVCCIN_CPU1_AIREF2")
	)
	(via
		(at 29.34335 -62.324488)
		(size 0.508)
		(drill 0.254)
		(layers "F.Cu" "B.Cu")
		(net "VR_PVCCIN_CPU1_AIREF2")
	)
	(via
		(at 25.87752 -87.9602)
		(size 0.508)
		(drill 0.254)
		(layers "F.Cu" "B.Cu")
		(net "VR_PVCCIN_CPU1_AIREF2")
	)
	(segment
		(start 26.67254 -82.13725)
		(end 25.2984 -80.76311)
		(width 0.127)
		(layer "In4.Cu")
		(net "VR_PVCCIN_CPU1_AIREF2")
	)
	(segment
		(start 25.2984 -80.76311)
		(end 25.2984 -72.3646)
		(width 0.127)
		(layer "In4.Cu")
		(net "VR_PVCCIN_CPU1_AIREF2")
	)
	(segment
		(start 28.0289 -64.40297)
		(end 28.0289 -63.064136)
		(width 0.127)
		(layer "In4.Cu")
		(net "VR_PVCCIN_CPU1_AIREF2")
	)
	(segment
		(start 25.2984 -72.3646)
		(end 27.28722 -70.37578)
		(width 0.127)
		(layer "In4.Cu")
		(net "VR_PVCCIN_CPU1_AIREF2")
	)
	(segment
		(start 26.67254 -86.03107)
		(end 26.67254 -82.13725)
		(width 0.127)
		(layer "In4.Cu")
		(net "VR_PVCCIN_CPU1_AIREF2")
	)
	(segment
		(start 25.87752 -87.9602)
		(end 26.1239 -87.71382)
		(width 0.127)
		(layer "In4.Cu")
		(net "VR_PVCCIN_CPU1_AIREF2")
	)
	(segment
		(start 28.0289 -63.064136)
		(end 28.488386 -62.60465)
		(width 0.127)
		(layer "In4.Cu")
		(net "VR_PVCCIN_CPU1_AIREF2")
	)
	(segment
		(start 26.1239 -86.57971)
		(end 26.67254 -86.03107)
		(width 0.127)
		(layer "In4.Cu")
		(net "VR_PVCCIN_CPU1_AIREF2")
	)
	(segment
		(start 27.28722 -70.37578)
		(end 27.28722 -65.14465)
		(width 0.127)
		(layer "In4.Cu")
		(net "VR_PVCCIN_CPU1_AIREF2")
	)
	(segment
		(start 29.34335 -62.361826)
		(end 29.34335 -62.324488)
		(width 0.127)
		(layer "In4.Cu")
		(net "VR_PVCCIN_CPU1_AIREF2")
	)
	(segment
		(start 26.1239 -87.71382)
		(end 26.1239 -86.57971)
		(width 0.127)
		(layer "In4.Cu")
		(net "VR_PVCCIN_CPU1_AIREF2")
	)
	(segment
		(start 28.488386 -62.60465)
		(end 29.100526 -62.60465)
		(width 0.127)
		(layer "In4.Cu")
		(net "VR_PVCCIN_CPU1_AIREF2")
	)
	(segment
		(start 29.100526 -62.60465)
		(end 29.34335 -62.361826)
		(width 0.127)
		(layer "In4.Cu")
		(net "VR_PVCCIN_CPU1_AIREF2")
	)
	(segment
		(start 27.28722 -65.14465)
		(end 28.0289 -64.40297)
		(width 0.127)
		(layer "In4.Cu")
		(net "VR_PVCCIN_CPU1_AIREF2")
	)
	(segment
		(start 21.373592 -88.980772)
		(end 21.231098 -89.123266)
		(width 0.127)
		(layer "F.Cu")
		(net "VR_PVCCIN_CPU1_AIREF1")
	)
	(segment
		(start 29.21762 -53.42763)
		(end 29.636466 -53.42763)
		(width 0.127)
		(layer "F.Cu")
		(net "VR_PVCCIN_CPU1_AIREF1")
	)
	(segment
		(start 22.550882 -88.980772)
		(end 21.373592 -88.980772)
		(width 0.127)
		(layer "F.Cu")
		(net "VR_PVCCIN_CPU1_AIREF1")
	)
	(segment
		(start 30.635956 -55.039768)
		(end 31.02991 -55.039768)
		(width 0.127)
		(layer "F.Cu")
		(net "VR_PVCCIN_CPU1_AIREF1")
	)
	(segment
		(start 23.901908 -86.1568)
		(end 24.123142 -85.935566)
		(width 0.127)
		(layer "F.Cu")
		(net "VR_PVCCIN_CPU1_AIREF1")
	)
	(segment
		(start 30.230064 -54.633876)
		(end 30.635956 -55.039768)
		(width 0.127)
		(layer "F.Cu")
		(net "VR_PVCCIN_CPU1_AIREF1")
	)
	(segment
		(start 24.123142 -85.935566)
		(end 25.001474 -85.935566)
		(width 0.127)
		(layer "F.Cu")
		(net "VR_PVCCIN_CPU1_AIREF1")
	)
	(segment
		(start 22.82444 -86.36)
		(end 22.82444 -88.707214)
		(width 0.127)
		(layer "F.Cu")
		(net "VR_PVCCIN_CPU1_AIREF1")
	)
	(segment
		(start 30.230064 -54.443884)
		(end 30.230064 -54.633876)
		(width 0.127)
		(layer "F.Cu")
		(net "VR_PVCCIN_CPU1_AIREF1")
	)
	(segment
		(start 23.29434 -86.1568)
		(end 23.901908 -86.1568)
		(width 0.127)
		(layer "F.Cu")
		(net "VR_PVCCIN_CPU1_AIREF1")
	)
	(segment
		(start 21.231098 -89.123266)
		(end 21.231098 -89.5604)
		(width 0.127)
		(layer "F.Cu")
		(net "VR_PVCCIN_CPU1_AIREF1")
	)
	(segment
		(start 29.100018 -53.545232)
		(end 29.21762 -53.42763)
		(width 0.127)
		(layer "F.Cu")
		(net "VR_PVCCIN_CPU1_AIREF1")
	)
	(segment
		(start 29.100018 -53.984906)
		(end 29.100018 -53.545232)
		(width 0.127)
		(layer "F.Cu")
		(net "VR_PVCCIN_CPU1_AIREF1")
	)
	(segment
		(start 29.636466 -53.42763)
		(end 29.636466 -53.850286)
		(width 0.127)
		(layer "F.Cu")
		(net "VR_PVCCIN_CPU1_AIREF1")
	)
	(segment
		(start 22.82444 -88.707214)
		(end 22.550882 -88.980772)
		(width 0.127)
		(layer "F.Cu")
		(net "VR_PVCCIN_CPU1_AIREF1")
	)
	(segment
		(start 25.001474 -85.935566)
		(end 25.06472 -85.87232)
		(width 0.127)
		(layer "F.Cu")
		(net "VR_PVCCIN_CPU1_AIREF1")
	)
	(segment
		(start 29.636466 -53.850286)
		(end 30.230064 -54.443884)
		(width 0.127)
		(layer "F.Cu")
		(net "VR_PVCCIN_CPU1_AIREF1")
	)
	(segment
		(start 23.29434 -86.1568)
		(end 23.02764 -86.1568)
		(width 0.127)
		(layer "F.Cu")
		(net "VR_PVCCIN_CPU1_AIREF1")
	)
	(segment
		(start 29.346144 -54.231032)
		(end 29.100018 -53.984906)
		(width 0.127)
		(layer "F.Cu")
		(net "VR_PVCCIN_CPU1_AIREF1")
	)
	(segment
		(start 23.02764 -86.1568)
		(end 22.82444 -86.36)
		(width 0.127)
		(layer "F.Cu")
		(net "VR_PVCCIN_CPU1_AIREF1")
	)
	(via
		(at 29.346144 -54.231032)
		(size 0.508)
		(drill 0.254)
		(layers "F.Cu" "B.Cu")
		(net "VR_PVCCIN_CPU1_AIREF1")
	)
	(via
		(at 25.06472 -85.87232)
		(size 0.508)
		(drill 0.254)
		(layers "F.Cu" "B.Cu")
		(net "VR_PVCCIN_CPU1_AIREF1")
	)
	(segment
		(start 25.06472 -85.63483)
		(end 24.56942 -85.13953)
		(width 0.127)
		(layer "In4.Cu")
		(net "VR_PVCCIN_CPU1_AIREF1")
	)
	(segment
		(start 25.06472 -85.87232)
		(end 25.06472 -85.63483)
		(width 0.127)
		(layer "In4.Cu")
		(net "VR_PVCCIN_CPU1_AIREF1")
	)
	(segment
		(start 28.1686 -54.962552)
		(end 28.575 -54.556152)
		(width 0.127)
		(layer "In4.Cu")
		(net "VR_PVCCIN_CPU1_AIREF1")
	)
	(segment
		(start 26.65222 -58.99658)
		(end 28.1686 -57.4802)
		(width 0.127)
		(layer "In4.Cu")
		(net "VR_PVCCIN_CPU1_AIREF1")
	)
	(segment
		(start 24.56942 -80.70723)
		(end 24.078946 -80.216756)
		(width 0.127)
		(layer "In4.Cu")
		(net "VR_PVCCIN_CPU1_AIREF1")
	)
	(segment
		(start 24.4602 -70.519036)
		(end 26.65222 -68.327016)
		(width 0.127)
		(layer "In4.Cu")
		(net "VR_PVCCIN_CPU1_AIREF1")
	)
	(segment
		(start 24.078946 -80.216756)
		(end 24.078946 -75.800966)
		(width 0.127)
		(layer "In4.Cu")
		(net "VR_PVCCIN_CPU1_AIREF1")
	)
	(segment
		(start 29.021024 -54.556152)
		(end 29.346144 -54.231032)
		(width 0.127)
		(layer "In4.Cu")
		(net "VR_PVCCIN_CPU1_AIREF1")
	)
	(segment
		(start 24.078946 -75.800966)
		(end 24.4602 -75.419712)
		(width 0.127)
		(layer "In4.Cu")
		(net "VR_PVCCIN_CPU1_AIREF1")
	)
	(segment
		(start 24.4602 -75.419712)
		(end 24.4602 -70.519036)
		(width 0.127)
		(layer "In4.Cu")
		(net "VR_PVCCIN_CPU1_AIREF1")
	)
	(segment
		(start 28.575 -54.556152)
		(end 29.021024 -54.556152)
		(width 0.127)
		(layer "In4.Cu")
		(net "VR_PVCCIN_CPU1_AIREF1")
	)
	(segment
		(start 28.1686 -57.4802)
		(end 28.1686 -54.962552)
		(width 0.127)
		(layer "In4.Cu")
		(net "VR_PVCCIN_CPU1_AIREF1")
	)
	(segment
		(start 24.56942 -85.13953)
		(end 24.56942 -80.70723)
		(width 0.127)
		(layer "In4.Cu")
		(net "VR_PVCCIN_CPU1_AIREF1")
	)
	(segment
		(start 26.65222 -68.327016)
		(end 26.65222 -58.99658)
		(width 0.127)
		(layer "In4.Cu")
		(net "VR_PVCCIN_CPU1_AIREF1")
	)
	(segment
		(start 383.267204 -156.9974)
		(end 382.95326 -156.9974)
		(width 0.127)
		(layer "F.Cu")
		(net "VR_P1V05_PCH_BIREF1")
	)
	(segment
		(start 396.515082 -157.707076)
		(end 396.515082 -158.30296)
		(width 0.127)
		(layer "F.Cu")
		(net "VR_P1V05_PCH_BIREF1")
	)
	(segment
		(start 396.515082 -157.430216)
		(end 396.515082 -157.707076)
		(width 0.127)
		(layer "F.Cu")
		(net "VR_P1V05_PCH_BIREF1")
	)
	(segment
		(start 382.442466 -157.508194)
		(end 382.708404 -157.774132)
		(width 0.127)
		(layer "F.Cu")
		(net "VR_P1V05_PCH_BIREF1")
	)
	(segment
		(start 382.95326 -156.9974)
		(end 382.442466 -157.508194)
		(width 0.127)
		(layer "F.Cu")
		(net "VR_P1V05_PCH_BIREF1")
	)
	(segment
		(start 395.982698 -156.2481)
		(end 395.982698 -156.897832)
		(width 0.127)
		(layer "F.Cu")
		(net "VR_P1V05_PCH_BIREF1")
	)
	(segment
		(start 383.394204 -156.8704)
		(end 383.267204 -156.9974)
		(width 0.127)
		(layer "F.Cu")
		(net "VR_P1V05_PCH_BIREF1")
	)
	(segment
		(start 382.708404 -157.774132)
		(end 382.708404 -158.248858)
		(width 0.127)
		(layer "F.Cu")
		(net "VR_P1V05_PCH_BIREF1")
	)
	(segment
		(start 396.515082 -158.30296)
		(end 396.429738 -158.388304)
		(width 0.127)
		(layer "F.Cu")
		(net "VR_P1V05_PCH_BIREF1")
	)
	(segment
		(start 383.394204 -156.565092)
		(end 383.394204 -156.8704)
		(width 0.127)
		(layer "F.Cu")
		(net "VR_P1V05_PCH_BIREF1")
	)
	(segment
		(start 395.982698 -156.897832)
		(end 396.515082 -157.430216)
		(width 0.127)
		(layer "F.Cu")
		(net "VR_P1V05_PCH_BIREF1")
	)
	(via
		(at 382.442466 -157.508194)
		(size 0.508)
		(drill 0.254)
		(layers "F.Cu" "B.Cu")
		(net "VR_P1V05_PCH_BIREF1")
	)
	(via
		(at 396.429738 -158.388304)
		(size 0.508)
		(drill 0.254)
		(layers "F.Cu" "B.Cu")
		(net "VR_P1V05_PCH_BIREF1")
	)
	(segment
		(start 396.145766 -157.893004)
		(end 396.463266 -157.575504)
		(width 0.127)
		(layer "B.Cu")
		(net "VR_P1V05_PCH_BIREF1")
	)
	(segment
		(start 396.429738 -158.388304)
		(end 396.145766 -158.104332)
		(width 0.127)
		(layer "B.Cu")
		(net "VR_P1V05_PCH_BIREF1")
	)
	(segment
		(start 396.463266 -157.575504)
		(end 396.463266 -157.117288)
		(width 0.127)
		(layer "B.Cu")
		(net "VR_P1V05_PCH_BIREF1")
	)
	(segment
		(start 396.145766 -158.104332)
		(end 396.145766 -157.893004)
		(width 0.127)
		(layer "B.Cu")
		(net "VR_P1V05_PCH_BIREF1")
	)
	(segment
		(start 382.81864 -157.13202)
		(end 382.442466 -157.508194)
		(width 0.127)
		(layer "In2.Cu")
		(net "VR_P1V05_PCH_BIREF1")
	)
	(segment
		(start 386.54736 -156.49956)
		(end 383.140204 -156.49956)
		(width 0.127)
		(layer "In2.Cu")
		(net "VR_P1V05_PCH_BIREF1")
	)
	(segment
		(start 392.60145 -157.720284)
		(end 391.675366 -156.7942)
		(width 0.127)
		(layer "In2.Cu")
		(net "VR_P1V05_PCH_BIREF1")
	)
	(segment
		(start 389.438896 -157.59684)
		(end 387.64464 -157.59684)
		(width 0.127)
		(layer "In2.Cu")
		(net "VR_P1V05_PCH_BIREF1")
	)
	(segment
		(start 396.429738 -158.388304)
		(end 396.113 -158.071566)
		(width 0.127)
		(layer "In2.Cu")
		(net "VR_P1V05_PCH_BIREF1")
	)
	(segment
		(start 387.64464 -157.59684)
		(end 386.54736 -156.49956)
		(width 0.127)
		(layer "In2.Cu")
		(net "VR_P1V05_PCH_BIREF1")
	)
	(segment
		(start 382.81864 -156.821124)
		(end 382.81864 -157.13202)
		(width 0.127)
		(layer "In2.Cu")
		(net "VR_P1V05_PCH_BIREF1")
	)
	(segment
		(start 395.553946 -157.03804)
		(end 394.177774 -157.03804)
		(width 0.127)
		(layer "In2.Cu")
		(net "VR_P1V05_PCH_BIREF1")
	)
	(segment
		(start 396.113 -157.597094)
		(end 395.553946 -157.03804)
		(width 0.127)
		(layer "In2.Cu")
		(net "VR_P1V05_PCH_BIREF1")
	)
	(segment
		(start 390.241536 -156.7942)
		(end 389.438896 -157.59684)
		(width 0.127)
		(layer "In2.Cu")
		(net "VR_P1V05_PCH_BIREF1")
	)
	(segment
		(start 383.140204 -156.49956)
		(end 382.81864 -156.821124)
		(width 0.127)
		(layer "In2.Cu")
		(net "VR_P1V05_PCH_BIREF1")
	)
	(segment
		(start 391.675366 -156.7942)
		(end 390.241536 -156.7942)
		(width 0.127)
		(layer "In2.Cu")
		(net "VR_P1V05_PCH_BIREF1")
	)
	(segment
		(start 394.177774 -157.03804)
		(end 393.49553 -157.720284)
		(width 0.127)
		(layer "In2.Cu")
		(net "VR_P1V05_PCH_BIREF1")
	)
	(segment
		(start 396.113 -158.071566)
		(end 396.113 -157.597094)
		(width 0.127)
		(layer "In2.Cu")
		(net "VR_P1V05_PCH_BIREF1")
	)
	(segment
		(start 393.49553 -157.720284)
		(end 392.60145 -157.720284)
		(width 0.127)
		(layer "In2.Cu")
		(net "VR_P1V05_PCH_BIREF1")
	)
	(segment
		(start 188.2775 -74.186288)
		(end 187.948824 -73.857612)
		(width 0.127)
		(layer "F.Cu")
		(net "VR_PVSA_CPU0_BIREF1")
	)
	(segment
		(start 194.096386 -94.930722)
		(end 194.33921 -94.687898)
		(width 0.127)
		(layer "F.Cu")
		(net "VR_PVSA_CPU0_BIREF1")
	)
	(segment
		(start 187.948824 -73.837292)
		(end 187.481972 -73.37044)
		(width 0.127)
		(layer "F.Cu")
		(net "VR_PVSA_CPU0_BIREF1")
	)
	(segment
		(start 187.948824 -73.857612)
		(end 187.948824 -73.837292)
		(width 0.127)
		(layer "F.Cu")
		(net "VR_PVSA_CPU0_BIREF1")
	)
	(segment
		(start 188.2775 -74.295)
		(end 188.2775 -74.186288)
		(width 0.127)
		(layer "F.Cu")
		(net "VR_PVSA_CPU0_BIREF1")
	)
	(segment
		(start 186.603894 -73.37044)
		(end 186.476894 -73.24344)
		(width 0.127)
		(layer "F.Cu")
		(net "VR_PVSA_CPU0_BIREF1")
	)
	(segment
		(start 188.2775 -75.057)
		(end 188.2775 -74.295)
		(width 0.127)
		(layer "F.Cu")
		(net "VR_PVSA_CPU0_BIREF1")
	)
	(segment
		(start 194.346322 -94.930722)
		(end 194.096386 -94.930722)
		(width 0.127)
		(layer "F.Cu")
		(net "VR_PVSA_CPU0_BIREF1")
	)
	(segment
		(start 186.476894 -73.24344)
		(end 186.476894 -72.7456)
		(width 0.127)
		(layer "F.Cu")
		(net "VR_PVSA_CPU0_BIREF1")
	)
	(segment
		(start 188.2775 -75.057)
		(end 188.2775 -75.909424)
		(width 0.127)
		(layer "F.Cu")
		(net "VR_PVSA_CPU0_BIREF1")
	)
	(segment
		(start 195.095368 -95.679768)
		(end 194.346322 -94.930722)
		(width 0.127)
		(layer "F.Cu")
		(net "VR_PVSA_CPU0_BIREF1")
	)
	(segment
		(start 194.33921 -94.687898)
		(end 195.086986 -94.687898)
		(width 0.127)
		(layer "F.Cu")
		(net "VR_PVSA_CPU0_BIREF1")
	)
	(segment
		(start 196.017642 -95.679768)
		(end 195.095368 -95.679768)
		(width 0.127)
		(layer "F.Cu")
		(net "VR_PVSA_CPU0_BIREF1")
	)
	(segment
		(start 187.481972 -73.37044)
		(end 186.603894 -73.37044)
		(width 0.127)
		(layer "F.Cu")
		(net "VR_PVSA_CPU0_BIREF1")
	)
	(via
		(at 194.096386 -94.930722)
		(size 0.508)
		(drill 0.254)
		(layers "F.Cu" "B.Cu")
		(net "VR_PVSA_CPU0_BIREF1")
	)
	(via
		(at 188.2775 -75.909424)
		(size 0.508)
		(drill 0.254)
		(layers "F.Cu" "B.Cu")
		(net "VR_PVSA_CPU0_BIREF1")
	)
	(segment
		(start 193.952622 -95.074486)
		(end 194.096386 -94.930722)
		(width 0.127)
		(layer "In11.Cu")
		(net "VR_PVSA_CPU0_BIREF1")
	)
	(segment
		(start 193.421 -94.33179)
		(end 193.421 -94.945454)
		(width 0.127)
		(layer "In11.Cu")
		(net "VR_PVSA_CPU0_BIREF1")
	)
	(segment
		(start 188.2775 -75.909424)
		(end 187.959238 -76.227686)
		(width 0.127)
		(layer "In11.Cu")
		(net "VR_PVSA_CPU0_BIREF1")
	)
	(segment
		(start 187.6806 -84.074)
		(end 187.6806 -88.9762)
		(width 0.127)
		(layer "In11.Cu")
		(net "VR_PVSA_CPU0_BIREF1")
	)
	(segment
		(start 187.959238 -76.227686)
		(end 187.959238 -78.650084)
		(width 0.127)
		(layer "In11.Cu")
		(net "VR_PVSA_CPU0_BIREF1")
	)
	(segment
		(start 189.103 -90.3986)
		(end 191.316864 -90.3986)
		(width 0.127)
		(layer "In11.Cu")
		(net "VR_PVSA_CPU0_BIREF1")
	)
	(segment
		(start 193.550032 -95.074486)
		(end 193.952622 -95.074486)
		(width 0.127)
		(layer "In11.Cu")
		(net "VR_PVSA_CPU0_BIREF1")
	)
	(segment
		(start 192.3542 -91.435936)
		(end 192.3542 -93.26499)
		(width 0.127)
		(layer "In11.Cu")
		(net "VR_PVSA_CPU0_BIREF1")
	)
	(segment
		(start 186.5122 -82.9056)
		(end 187.6806 -84.074)
		(width 0.127)
		(layer "In11.Cu")
		(net "VR_PVSA_CPU0_BIREF1")
	)
	(segment
		(start 187.6806 -88.9762)
		(end 189.103 -90.3986)
		(width 0.127)
		(layer "In11.Cu")
		(net "VR_PVSA_CPU0_BIREF1")
	)
	(segment
		(start 187.959238 -78.650084)
		(end 186.5122 -80.097122)
		(width 0.127)
		(layer "In11.Cu")
		(net "VR_PVSA_CPU0_BIREF1")
	)
	(segment
		(start 193.421 -94.945454)
		(end 193.550032 -95.074486)
		(width 0.127)
		(layer "In11.Cu")
		(net "VR_PVSA_CPU0_BIREF1")
	)
	(segment
		(start 191.316864 -90.3986)
		(end 192.3542 -91.435936)
		(width 0.127)
		(layer "In11.Cu")
		(net "VR_PVSA_CPU0_BIREF1")
	)
	(segment
		(start 192.3542 -93.26499)
		(end 193.421 -94.33179)
		(width 0.127)
		(layer "In11.Cu")
		(net "VR_PVSA_CPU0_BIREF1")
	)
	(segment
		(start 186.5122 -80.097122)
		(end 186.5122 -82.9056)
		(width 0.127)
		(layer "In11.Cu")
		(net "VR_PVSA_CPU0_BIREF1")
	)
	(segment
		(start 187.6806 -70.1294)
		(end 187.88761 -70.1294)
		(width 0.127)
		(layer "F.Cu")
		(net "VR_PVCCIN_CPU0_AIREF5")
	)
	(segment
		(start 195.155312 -87.551768)
		(end 194.346576 -86.743032)
		(width 0.127)
		(layer "F.Cu")
		(net "VR_PVCCIN_CPU0_AIREF5")
	)
	(segment
		(start 196.030342 -87.551768)
		(end 195.155312 -87.551768)
		(width 0.127)
		(layer "F.Cu")
		(net "VR_PVCCIN_CPU0_AIREF5")
	)
	(segment
		(start 194.346576 -86.743032)
		(end 194.924934 -86.743032)
		(width 0.127)
		(layer "F.Cu")
		(net "VR_PVCCIN_CPU0_AIREF5")
	)
	(segment
		(start 187.88761 -70.1294)
		(end 188.33211 -70.5739)
		(width 0.127)
		(layer "F.Cu")
		(net "VR_PVCCIN_CPU0_AIREF5")
	)
	(segment
		(start 189.6237 -70.993)
		(end 190.2714 -70.993)
		(width 0.127)
		(layer "F.Cu")
		(net "VR_PVCCIN_CPU0_AIREF5")
	)
	(segment
		(start 187.1726 -70.049898)
		(end 187.601098 -70.049898)
		(width 0.127)
		(layer "F.Cu")
		(net "VR_PVCCIN_CPU0_AIREF5")
	)
	(segment
		(start 194.924934 -86.743032)
		(end 195.165218 -86.502748)
		(width 0.127)
		(layer "F.Cu")
		(net "VR_PVCCIN_CPU0_AIREF5")
	)
	(segment
		(start 188.33211 -70.5739)
		(end 188.5696 -70.5739)
		(width 0.127)
		(layer "F.Cu")
		(net "VR_PVCCIN_CPU0_AIREF5")
	)
	(segment
		(start 187.601098 -70.049898)
		(end 187.6806 -70.1294)
		(width 0.127)
		(layer "F.Cu")
		(net "VR_PVCCIN_CPU0_AIREF5")
	)
	(segment
		(start 188.5696 -70.5739)
		(end 189.2046 -70.5739)
		(width 0.127)
		(layer "F.Cu")
		(net "VR_PVCCIN_CPU0_AIREF5")
	)
	(segment
		(start 189.2046 -70.5739)
		(end 189.3316 -70.7009)
		(width 0.127)
		(layer "F.Cu")
		(net "VR_PVCCIN_CPU0_AIREF5")
	)
	(segment
		(start 189.3316 -70.7009)
		(end 189.6237 -70.993)
		(width 0.127)
		(layer "F.Cu")
		(net "VR_PVCCIN_CPU0_AIREF5")
	)
	(via
		(at 190.2714 -70.993)
		(size 0.508)
		(drill 0.254)
		(layers "F.Cu" "B.Cu")
		(net "VR_PVCCIN_CPU0_AIREF5")
	)
	(via
		(at 194.346576 -86.743032)
		(size 0.508)
		(drill 0.254)
		(layers "F.Cu" "B.Cu")
		(net "VR_PVCCIN_CPU0_AIREF5")
	)
	(segment
		(start 193.1924 -86.385654)
		(end 193.7639 -86.957154)
		(width 0.127)
		(layer "In11.Cu")
		(net "VR_PVCCIN_CPU0_AIREF5")
	)
	(segment
		(start 193.1924 -82.984594)
		(end 193.1924 -86.385654)
		(width 0.127)
		(layer "In11.Cu")
		(net "VR_PVCCIN_CPU0_AIREF5")
	)
	(segment
		(start 190.2714 -70.993)
		(end 190.5254 -70.993)
		(width 0.127)
		(layer "In11.Cu")
		(net "VR_PVCCIN_CPU0_AIREF5")
	)
	(segment
		(start 191.0461 -80.838294)
		(end 193.1924 -82.984594)
		(width 0.127)
		(layer "In11.Cu")
		(net "VR_PVCCIN_CPU0_AIREF5")
	)
	(segment
		(start 193.7639 -86.957154)
		(end 194.132454 -86.957154)
		(width 0.127)
		(layer "In11.Cu")
		(net "VR_PVCCIN_CPU0_AIREF5")
	)
	(segment
		(start 190.5254 -70.993)
		(end 191.0461 -71.5137)
		(width 0.127)
		(layer "In11.Cu")
		(net "VR_PVCCIN_CPU0_AIREF5")
	)
	(segment
		(start 191.0461 -71.5137)
		(end 191.0461 -80.838294)
		(width 0.127)
		(layer "In11.Cu")
		(net "VR_PVCCIN_CPU0_AIREF5")
	)
	(segment
		(start 194.132454 -86.957154)
		(end 194.346576 -86.743032)
		(width 0.127)
		(layer "In11.Cu")
		(net "VR_PVCCIN_CPU0_AIREF5")
	)
	(segment
		(start 190.9318 -69.4309)
		(end 191.707008 -69.4309)
		(width 0.127)
		(layer "F.Cu")
		(net "VR_PVCCIN_CPU0_AIREF4")
	)
	(segment
		(start 190.1698 -69.3039)
		(end 189.994032 -69.479668)
		(width 0.127)
		(layer "F.Cu")
		(net "VR_PVCCIN_CPU0_AIREF4")
	)
	(segment
		(start 189.28461 -69.2912)
		(end 187.833 -69.2912)
		(width 0.127)
		(layer "F.Cu")
		(net "VR_PVCCIN_CPU0_AIREF4")
	)
	(segment
		(start 195.155312 -79.423768)
		(end 194.346576 -78.615032)
		(width 0.127)
		(layer "F.Cu")
		(net "VR_PVCCIN_CPU0_AIREF4")
	)
	(segment
		(start 196.030342 -79.423768)
		(end 195.155312 -79.423768)
		(width 0.127)
		(layer "F.Cu")
		(net "VR_PVCCIN_CPU0_AIREF4")
	)
	(segment
		(start 187.833 -69.2912)
		(end 187.791852 -69.250052)
		(width 0.127)
		(layer "F.Cu")
		(net "VR_PVCCIN_CPU0_AIREF4")
	)
	(segment
		(start 189.473078 -69.479668)
		(end 189.28461 -69.2912)
		(width 0.127)
		(layer "F.Cu")
		(net "VR_PVCCIN_CPU0_AIREF4")
	)
	(segment
		(start 190.1698 -69.3039)
		(end 190.8048 -69.3039)
		(width 0.127)
		(layer "F.Cu")
		(net "VR_PVCCIN_CPU0_AIREF4")
	)
	(segment
		(start 194.457828 -78.50378)
		(end 194.457828 -78.000352)
		(width 0.127)
		(layer "F.Cu")
		(net "VR_PVCCIN_CPU0_AIREF4")
	)
	(segment
		(start 187.791852 -69.250052)
		(end 187.1726 -69.250052)
		(width 0.127)
		(layer "F.Cu")
		(net "VR_PVCCIN_CPU0_AIREF4")
	)
	(segment
		(start 190.8048 -69.3039)
		(end 190.9318 -69.4309)
		(width 0.127)
		(layer "F.Cu")
		(net "VR_PVCCIN_CPU0_AIREF4")
	)
	(segment
		(start 191.707008 -69.4309)
		(end 191.708532 -69.432424)
		(width 0.127)
		(layer "F.Cu")
		(net "VR_PVCCIN_CPU0_AIREF4")
	)
	(segment
		(start 194.346576 -78.615032)
		(end 194.457828 -78.50378)
		(width 0.127)
		(layer "F.Cu")
		(net "VR_PVCCIN_CPU0_AIREF4")
	)
	(segment
		(start 189.994032 -69.479668)
		(end 189.473078 -69.479668)
		(width 0.127)
		(layer "F.Cu")
		(net "VR_PVCCIN_CPU0_AIREF4")
	)
	(via
		(at 194.346576 -78.615032)
		(size 0.508)
		(drill 0.254)
		(layers "F.Cu" "B.Cu")
		(net "VR_PVCCIN_CPU0_AIREF4")
	)
	(via
		(at 191.708532 -69.432424)
		(size 0.508)
		(drill 0.254)
		(layers "F.Cu" "B.Cu")
		(net "VR_PVCCIN_CPU0_AIREF4")
	)
	(segment
		(start 192.015618 -69.73951)
		(end 192.371726 -69.73951)
		(width 0.127)
		(layer "In11.Cu")
		(net "VR_PVCCIN_CPU0_AIREF4")
	)
	(segment
		(start 191.708532 -69.432424)
		(end 192.015618 -69.73951)
		(width 0.127)
		(layer "In11.Cu")
		(net "VR_PVCCIN_CPU0_AIREF4")
	)
	(segment
		(start 194.114166 -78.847442)
		(end 194.346576 -78.615032)
		(width 0.127)
		(layer "In11.Cu")
		(net "VR_PVCCIN_CPU0_AIREF4")
	)
	(segment
		(start 192.289176 -73.575418)
		(end 192.532 -73.818242)
		(width 0.127)
		(layer "In11.Cu")
		(net "VR_PVCCIN_CPU0_AIREF4")
	)
	(segment
		(start 192.631822 -69.999606)
		(end 192.631822 -70.91172)
		(width 0.127)
		(layer "In11.Cu")
		(net "VR_PVCCIN_CPU0_AIREF4")
	)
	(segment
		(start 193.633852 -78.847442)
		(end 194.114166 -78.847442)
		(width 0.127)
		(layer "In11.Cu")
		(net "VR_PVCCIN_CPU0_AIREF4")
	)
	(segment
		(start 192.532 -73.818242)
		(end 192.532 -77.74559)
		(width 0.127)
		(layer "In11.Cu")
		(net "VR_PVCCIN_CPU0_AIREF4")
	)
	(segment
		(start 192.289176 -71.254366)
		(end 192.289176 -73.575418)
		(width 0.127)
		(layer "In11.Cu")
		(net "VR_PVCCIN_CPU0_AIREF4")
	)
	(segment
		(start 192.371726 -69.73951)
		(end 192.631822 -69.999606)
		(width 0.127)
		(layer "In11.Cu")
		(net "VR_PVCCIN_CPU0_AIREF4")
	)
	(segment
		(start 192.631822 -70.91172)
		(end 192.289176 -71.254366)
		(width 0.127)
		(layer "In11.Cu")
		(net "VR_PVCCIN_CPU0_AIREF4")
	)
	(segment
		(start 192.532 -77.74559)
		(end 193.633852 -78.847442)
		(width 0.127)
		(layer "In11.Cu")
		(net "VR_PVCCIN_CPU0_AIREF4")
	)
	(segment
		(start 194.346576 -70.487032)
		(end 194.344036 -70.484492)
		(width 0.127)
		(layer "F.Cu")
		(net "VR_PVCCIN_CPU0_AIREF3")
	)
	(segment
		(start 187.1726 -68.449952)
		(end 187.810648 -68.449952)
		(width 0.127)
		(layer "F.Cu")
		(net "VR_PVCCIN_CPU0_AIREF3")
	)
	(segment
		(start 188.500512 -67.920108)
		(end 189.165992 -67.920108)
		(width 0.127)
		(layer "F.Cu")
		(net "VR_PVCCIN_CPU0_AIREF3")
	)
	(segment
		(start 194.344036 -70.484492)
		(end 194.344036 -69.770244)
		(width 0.127)
		(layer "F.Cu")
		(net "VR_PVCCIN_CPU0_AIREF3")
	)
	(segment
		(start 187.810648 -68.449952)
		(end 188.340492 -67.920108)
		(width 0.127)
		(layer "F.Cu")
		(net "VR_PVCCIN_CPU0_AIREF3")
	)
	(segment
		(start 196.030342 -71.295768)
		(end 195.584318 -71.295768)
		(width 0.127)
		(layer "F.Cu")
		(net "VR_PVCCIN_CPU0_AIREF3")
	)
	(segment
		(start 194.902074 -71.04253)
		(end 194.346576 -70.487032)
		(width 0.127)
		(layer "F.Cu")
		(net "VR_PVCCIN_CPU0_AIREF3")
	)
	(segment
		(start 188.340492 -67.920108)
		(end 188.500512 -67.920108)
		(width 0.127)
		(layer "F.Cu")
		(net "VR_PVCCIN_CPU0_AIREF3")
	)
	(segment
		(start 195.33108 -71.04253)
		(end 194.902074 -71.04253)
		(width 0.127)
		(layer "F.Cu")
		(net "VR_PVCCIN_CPU0_AIREF3")
	)
	(segment
		(start 190.01486 -68.1609)
		(end 190.24346 -67.9323)
		(width 0.127)
		(layer "F.Cu")
		(net "VR_PVCCIN_CPU0_AIREF3")
	)
	(segment
		(start 195.584318 -71.295768)
		(end 195.33108 -71.04253)
		(width 0.127)
		(layer "F.Cu")
		(net "VR_PVCCIN_CPU0_AIREF3")
	)
	(segment
		(start 189.6364 -68.1609)
		(end 190.01486 -68.1609)
		(width 0.127)
		(layer "F.Cu")
		(net "VR_PVCCIN_CPU0_AIREF3")
	)
	(segment
		(start 189.165992 -67.920108)
		(end 189.2808 -67.8053)
		(width 0.127)
		(layer "F.Cu")
		(net "VR_PVCCIN_CPU0_AIREF3")
	)
	(segment
		(start 189.2808 -67.8053)
		(end 189.6364 -68.1609)
		(width 0.127)
		(layer "F.Cu")
		(net "VR_PVCCIN_CPU0_AIREF3")
	)
	(via
		(at 190.24346 -67.9323)
		(size 0.508)
		(drill 0.254)
		(layers "F.Cu" "B.Cu")
		(net "VR_PVCCIN_CPU0_AIREF3")
	)
	(via
		(at 194.346576 -70.487032)
		(size 0.508)
		(drill 0.254)
		(layers "F.Cu" "B.Cu")
		(net "VR_PVCCIN_CPU0_AIREF3")
	)
	(segment
		(start 190.44666 -68.1355)
		(end 192.76441 -68.1355)
		(width 0.127)
		(layer "In11.Cu")
		(net "VR_PVCCIN_CPU0_AIREF3")
	)
	(segment
		(start 192.76441 -68.1355)
		(end 193.04 -68.41109)
		(width 0.127)
		(layer "In11.Cu")
		(net "VR_PVCCIN_CPU0_AIREF3")
	)
	(segment
		(start 193.914014 -70.739762)
		(end 194.093846 -70.739762)
		(width 0.127)
		(layer "In11.Cu")
		(net "VR_PVCCIN_CPU0_AIREF3")
	)
	(segment
		(start 193.5734 -69.596)
		(end 193.5734 -70.399148)
		(width 0.127)
		(layer "In11.Cu")
		(net "VR_PVCCIN_CPU0_AIREF3")
	)
	(segment
		(start 194.093846 -70.739762)
		(end 194.346576 -70.487032)
		(width 0.127)
		(layer "In11.Cu")
		(net "VR_PVCCIN_CPU0_AIREF3")
	)
	(segment
		(start 193.04 -69.0626)
		(end 193.5734 -69.596)
		(width 0.127)
		(layer "In11.Cu")
		(net "VR_PVCCIN_CPU0_AIREF3")
	)
	(segment
		(start 193.5734 -70.399148)
		(end 193.914014 -70.739762)
		(width 0.127)
		(layer "In11.Cu")
		(net "VR_PVCCIN_CPU0_AIREF3")
	)
	(segment
		(start 190.24346 -67.9323)
		(end 190.44666 -68.1355)
		(width 0.127)
		(layer "In11.Cu")
		(net "VR_PVCCIN_CPU0_AIREF3")
	)
	(segment
		(start 193.04 -68.41109)
		(end 193.04 -69.0626)
		(width 0.127)
		(layer "In11.Cu")
		(net "VR_PVCCIN_CPU0_AIREF3")
	)
	(segment
		(start 190.629286 -66.080386)
		(end 190.7286 -66.1797)
		(width 0.127)
		(layer "F.Cu")
		(net "VR_PVCCIN_CPU0_AIREF2")
	)
	(segment
		(start 191.151002 -66.049398)
		(end 191.0207 -66.1797)
		(width 0.127)
		(layer "F.Cu")
		(net "VR_PVCCIN_CPU0_AIREF2")
	)
	(segment
		(start 189.963044 -66.080386)
		(end 190.629286 -66.080386)
		(width 0.127)
		(layer "F.Cu")
		(net "VR_PVCCIN_CPU0_AIREF2")
	)
	(segment
		(start 196.030342 -63.167768)
		(end 195.155312 -63.167768)
		(width 0.127)
		(layer "F.Cu")
		(net "VR_PVCCIN_CPU0_AIREF2")
	)
	(segment
		(start 194.142614 -62.15507)
		(end 194.346576 -62.359032)
		(width 0.127)
		(layer "F.Cu")
		(net "VR_PVCCIN_CPU0_AIREF2")
	)
	(segment
		(start 190.846202 -64.568578)
		(end 191.151002 -64.873378)
		(width 0.127)
		(layer "F.Cu")
		(net "VR_PVCCIN_CPU0_AIREF2")
	)
	(segment
		(start 189.611 -66.294)
		(end 189.824614 -66.080386)
		(width 0.127)
		(layer "F.Cu")
		(net "VR_PVCCIN_CPU0_AIREF2")
	)
	(segment
		(start 191.151002 -64.873378)
		(end 191.151002 -66.049398)
		(width 0.127)
		(layer "F.Cu")
		(net "VR_PVCCIN_CPU0_AIREF2")
	)
	(segment
		(start 194.142614 -61.732668)
		(end 194.142614 -62.15507)
		(width 0.127)
		(layer "F.Cu")
		(net "VR_PVCCIN_CPU0_AIREF2")
	)
	(segment
		(start 187.1726 -67.650106)
		(end 187.649104 -67.650106)
		(width 0.127)
		(layer "F.Cu")
		(net "VR_PVCCIN_CPU0_AIREF2")
	)
	(segment
		(start 189.09157 -66.294)
		(end 189.611 -66.294)
		(width 0.127)
		(layer "F.Cu")
		(net "VR_PVCCIN_CPU0_AIREF2")
	)
	(segment
		(start 191.0207 -66.1797)
		(end 190.7286 -66.1797)
		(width 0.127)
		(layer "F.Cu")
		(net "VR_PVCCIN_CPU0_AIREF2")
	)
	(segment
		(start 195.155312 -63.167768)
		(end 194.346576 -62.359032)
		(width 0.127)
		(layer "F.Cu")
		(net "VR_PVCCIN_CPU0_AIREF2")
	)
	(segment
		(start 188.75375 -66.54546)
		(end 188.84011 -66.54546)
		(width 0.127)
		(layer "F.Cu")
		(net "VR_PVCCIN_CPU0_AIREF2")
	)
	(segment
		(start 189.824614 -66.080386)
		(end 189.963044 -66.080386)
		(width 0.127)
		(layer "F.Cu")
		(net "VR_PVCCIN_CPU0_AIREF2")
	)
	(segment
		(start 187.649104 -67.650106)
		(end 188.75375 -66.54546)
		(width 0.127)
		(layer "F.Cu")
		(net "VR_PVCCIN_CPU0_AIREF2")
	)
	(segment
		(start 188.84011 -66.54546)
		(end 189.09157 -66.294)
		(width 0.127)
		(layer "F.Cu")
		(net "VR_PVCCIN_CPU0_AIREF2")
	)
	(via
		(at 190.846202 -64.568578)
		(size 0.508)
		(drill 0.254)
		(layers "F.Cu" "B.Cu")
		(net "VR_PVCCIN_CPU0_AIREF2")
	)
	(via
		(at 194.346576 -62.359032)
		(size 0.508)
		(drill 0.254)
		(layers "F.Cu" "B.Cu")
		(net "VR_PVCCIN_CPU0_AIREF2")
	)
	(segment
		(start 190.846202 -64.568578)
		(end 191.177418 -64.237362)
		(width 0.127)
		(layer "In11.Cu")
		(net "VR_PVCCIN_CPU0_AIREF2")
	)
	(segment
		(start 194.1322 -62.573408)
		(end 194.346576 -62.359032)
		(width 0.127)
		(layer "In11.Cu")
		(net "VR_PVCCIN_CPU0_AIREF2")
	)
	(segment
		(start 191.177418 -64.237362)
		(end 191.177418 -64.017652)
		(width 0.127)
		(layer "In11.Cu")
		(net "VR_PVCCIN_CPU0_AIREF2")
	)
	(segment
		(start 191.177418 -64.017652)
		(end 192.621662 -62.573408)
		(width 0.127)
		(layer "In11.Cu")
		(net "VR_PVCCIN_CPU0_AIREF2")
	)
	(segment
		(start 192.621662 -62.573408)
		(end 194.1322 -62.573408)
		(width 0.127)
		(layer "In11.Cu")
		(net "VR_PVCCIN_CPU0_AIREF2")
	)
	(segment
		(start 186.077098 -66.421)
		(end 187.222638 -65.27546)
		(width 0.127)
		(layer "F.Cu")
		(net "VR_PVCCIN_CPU0_AIREF1")
	)
	(segment
		(start 194.346576 -54.231032)
		(end 194.804538 -53.77307)
		(width 0.127)
		(layer "F.Cu")
		(net "VR_PVCCIN_CPU0_AIREF1")
	)
	(segment
		(start 195.155312 -55.039768)
		(end 194.346576 -54.231032)
		(width 0.127)
		(layer "F.Cu")
		(net "VR_PVCCIN_CPU0_AIREF1")
	)
	(segment
		(start 189.41161 -64.38265)
		(end 188.98108 -64.81318)
		(width 0.127)
		(layer "F.Cu")
		(net "VR_PVCCIN_CPU0_AIREF1")
	)
	(segment
		(start 188.247274 -65.27546)
		(end 188.137038 -65.27546)
		(width 0.127)
		(layer "F.Cu")
		(net "VR_PVCCIN_CPU0_AIREF1")
	)
	(segment
		(start 186.077098 -66.9544)
		(end 186.077098 -66.421)
		(width 0.127)
		(layer "F.Cu")
		(net "VR_PVCCIN_CPU0_AIREF1")
	)
	(segment
		(start 194.804538 -53.77307)
		(end 194.804538 -53.48478)
		(width 0.127)
		(layer "F.Cu")
		(net "VR_PVCCIN_CPU0_AIREF1")
	)
	(segment
		(start 187.222638 -65.27546)
		(end 188.137038 -65.27546)
		(width 0.127)
		(layer "F.Cu")
		(net "VR_PVCCIN_CPU0_AIREF1")
	)
	(segment
		(start 189.738 -64.516)
		(end 189.60465 -64.38265)
		(width 0.127)
		(layer "F.Cu")
		(net "VR_PVCCIN_CPU0_AIREF1")
	)
	(segment
		(start 188.98108 -64.81318)
		(end 188.98108 -64.82588)
		(width 0.127)
		(layer "F.Cu")
		(net "VR_PVCCIN_CPU0_AIREF1")
	)
	(segment
		(start 189.60465 -64.38265)
		(end 189.41161 -64.38265)
		(width 0.127)
		(layer "F.Cu")
		(net "VR_PVCCIN_CPU0_AIREF1")
	)
	(segment
		(start 188.696854 -64.82588)
		(end 188.247274 -65.27546)
		(width 0.127)
		(layer "F.Cu")
		(net "VR_PVCCIN_CPU0_AIREF1")
	)
	(segment
		(start 190.1698 -64.516)
		(end 189.738 -64.516)
		(width 0.127)
		(layer "F.Cu")
		(net "VR_PVCCIN_CPU0_AIREF1")
	)
	(segment
		(start 196.030342 -55.039768)
		(end 195.155312 -55.039768)
		(width 0.127)
		(layer "F.Cu")
		(net "VR_PVCCIN_CPU0_AIREF1")
	)
	(segment
		(start 188.98108 -64.82588)
		(end 188.696854 -64.82588)
		(width 0.127)
		(layer "F.Cu")
		(net "VR_PVCCIN_CPU0_AIREF1")
	)
	(via
		(at 190.1698 -64.516)
		(size 0.508)
		(drill 0.254)
		(layers "F.Cu" "B.Cu")
		(net "VR_PVCCIN_CPU0_AIREF1")
	)
	(via
		(at 194.346576 -54.231032)
		(size 0.508)
		(drill 0.254)
		(layers "F.Cu" "B.Cu")
		(net "VR_PVCCIN_CPU0_AIREF1")
	)
	(segment
		(start 189.992 -64.100202)
		(end 189.992 -64.3382)
		(width 0.127)
		(layer "In11.Cu")
		(net "VR_PVCCIN_CPU0_AIREF1")
	)
	(segment
		(start 195.03517 -58.1025)
		(end 192.546478 -58.1025)
		(width 0.127)
		(layer "In11.Cu")
		(net "VR_PVCCIN_CPU0_AIREF1")
	)
	(segment
		(start 192.057782 -62.03442)
		(end 189.992 -64.100202)
		(width 0.127)
		(layer "In11.Cu")
		(net "VR_PVCCIN_CPU0_AIREF1")
	)
	(segment
		(start 195.00723 -54.537864)
		(end 195.6308 -55.161434)
		(width 0.127)
		(layer "In11.Cu")
		(net "VR_PVCCIN_CPU0_AIREF1")
	)
	(segment
		(start 189.992 -64.3382)
		(end 190.1698 -64.516)
		(width 0.127)
		(layer "In11.Cu")
		(net "VR_PVCCIN_CPU0_AIREF1")
	)
	(segment
		(start 195.6308 -55.161434)
		(end 195.6308 -57.50687)
		(width 0.127)
		(layer "In11.Cu")
		(net "VR_PVCCIN_CPU0_AIREF1")
	)
	(segment
		(start 194.346576 -54.231032)
		(end 194.653408 -54.537864)
		(width 0.127)
		(layer "In11.Cu")
		(net "VR_PVCCIN_CPU0_AIREF1")
	)
	(segment
		(start 192.057782 -58.591196)
		(end 192.057782 -62.03442)
		(width 0.127)
		(layer "In11.Cu")
		(net "VR_PVCCIN_CPU0_AIREF1")
	)
	(segment
		(start 192.546478 -58.1025)
		(end 192.057782 -58.591196)
		(width 0.127)
		(layer "In11.Cu")
		(net "VR_PVCCIN_CPU0_AIREF1")
	)
	(segment
		(start 195.6308 -57.50687)
		(end 195.03517 -58.1025)
		(width 0.127)
		(layer "In11.Cu")
		(net "VR_PVCCIN_CPU0_AIREF1")
	)
	(segment
		(start 194.653408 -54.537864)
		(end 195.00723 -54.537864)
		(width 0.127)
		(layer "In11.Cu")
		(net "VR_PVCCIN_CPU0_AIREF1")
	)
	(segment
		(start 388.696454 -93.724222)
		(end 388.696454 -92.976446)
		(width 0.0889)
		(layer "F.Cu")
		(net "RMII_BMC_PCH_SPRNGVLLE_CRSDV_R1")
	)
	(segment
		(start 388.975092 -91.909646)
		(end 388.918958 -91.853512)
		(width 0.0889)
		(layer "F.Cu")
		(net "RMII_BMC_PCH_SPRNGVLLE_CRSDV_R1")
	)
	(segment
		(start 388.583678 -91.518232)
		(end 388.583678 -90.168984)
		(width 0.10795)
		(layer "F.Cu")
		(net "RMII_BMC_PCH_SPRNGVLLE_CRSDV_R1")
	)
	(segment
		(start 389.89 -88.646762)
		(end 389.89 -88.2015)
		(width 0.10795)
		(layer "F.Cu")
		(net "RMII_BMC_PCH_SPRNGVLLE_CRSDV_R1")
	)
	(segment
		(start 389.634222 -88.90254)
		(end 389.89 -88.646762)
		(width 0.10795)
		(layer "F.Cu")
		(net "RMII_BMC_PCH_SPRNGVLLE_CRSDV_R1")
	)
	(segment
		(start 388.696454 -92.976446)
		(end 388.975092 -92.697808)
		(width 0.0889)
		(layer "F.Cu")
		(net "RMII_BMC_PCH_SPRNGVLLE_CRSDV_R1")
	)
	(segment
		(start 388.984998 -94.37497)
		(end 388.984998 -94.012766)
		(width 0.0889)
		(layer "F.Cu")
		(net "RMII_BMC_PCH_SPRNGVLLE_CRSDV_R1")
	)
	(segment
		(start 388.975092 -92.697808)
		(end 388.975092 -91.909646)
		(width 0.0889)
		(layer "F.Cu")
		(net "RMII_BMC_PCH_SPRNGVLLE_CRSDV_R1")
	)
	(segment
		(start 388.583678 -90.168984)
		(end 389.634222 -89.11844)
		(width 0.10795)
		(layer "F.Cu")
		(net "RMII_BMC_PCH_SPRNGVLLE_CRSDV_R1")
	)
	(segment
		(start 388.918958 -91.853512)
		(end 388.583678 -91.518232)
		(width 0.10795)
		(layer "F.Cu")
		(net "RMII_BMC_PCH_SPRNGVLLE_CRSDV_R1")
	)
	(segment
		(start 388.984998 -94.012766)
		(end 388.696454 -93.724222)
		(width 0.0889)
		(layer "F.Cu")
		(net "RMII_BMC_PCH_SPRNGVLLE_CRSDV_R1")
	)
	(segment
		(start 389.634222 -89.11844)
		(end 389.634222 -88.90254)
		(width 0.10795)
		(layer "F.Cu")
		(net "RMII_BMC_PCH_SPRNGVLLE_CRSDV_R1")
	)
	(segment
		(start 388.984998 -92.957396)
		(end 389.1661 -92.776294)
		(width 0.0889)
		(layer "F.Cu")
		(net "RMII_SPRNGVLLE_BMC_PCH_RXD1_R1")
	)
	(segment
		(start 389.1661 -92.776294)
		(end 389.1661 -91.759532)
		(width 0.0889)
		(layer "F.Cu")
		(net "RMII_SPRNGVLLE_BMC_PCH_RXD1_R1")
	)
	(segment
		(start 389.1661 -91.759532)
		(end 389.090408 -91.68384)
		(width 0.0889)
		(layer "F.Cu")
		(net "RMII_SPRNGVLLE_BMC_PCH_RXD1_R1")
	)
	(segment
		(start 388.984998 -93.544898)
		(end 388.984998 -92.957396)
		(width 0.0889)
		(layer "F.Cu")
		(net "RMII_SPRNGVLLE_BMC_PCH_RXD1_R1")
	)
	(segment
		(start 390.031478 -89.127076)
		(end 390.652 -88.506554)
		(width 0.10795)
		(layer "F.Cu")
		(net "RMII_SPRNGVLLE_BMC_PCH_RXD1_R1")
	)
	(segment
		(start 388.81304 -90.345514)
		(end 390.031478 -89.127076)
		(width 0.10795)
		(layer "F.Cu")
		(net "RMII_SPRNGVLLE_BMC_PCH_RXD1_R1")
	)
	(segment
		(start 390.652 -88.506554)
		(end 390.652 -88.2015)
		(width 0.10795)
		(layer "F.Cu")
		(net "RMII_SPRNGVLLE_BMC_PCH_RXD1_R1")
	)
	(segment
		(start 388.81304 -91.406472)
		(end 388.81304 -90.345514)
		(width 0.10795)
		(layer "F.Cu")
		(net "RMII_SPRNGVLLE_BMC_PCH_RXD1_R1")
	)
	(segment
		(start 389.090408 -91.68384)
		(end 388.81304 -91.406472)
		(width 0.10795)
		(layer "F.Cu")
		(net "RMII_SPRNGVLLE_BMC_PCH_RXD1_R1")
	)
	(via
		(at 390.031478 -89.127076)
		(size 0.508)
		(drill 0.254)
		(layers "F.Cu" "B.Cu")
		(net "RMII_SPRNGVLLE_BMC_PCH_RXD1_R1")
	)
	(segment
		(start 387.97611 -93.262196)
		(end 387.97611 -91.853766)
		(width 0.0889)
		(layer "F.Cu")
		(net "RMII_SPRNGVLLE_BMC_PCH_RXD0_R1")
	)
	(segment
		(start 388.586726 -88.687402)
		(end 388.366 -88.466676)
		(width 0.10795)
		(layer "F.Cu")
		(net "RMII_SPRNGVLLE_BMC_PCH_RXD0_R1")
	)
	(segment
		(start 388.122668 -89.748868)
		(end 388.586726 -89.28481)
		(width 0.10795)
		(layer "F.Cu")
		(net "RMII_SPRNGVLLE_BMC_PCH_RXD0_R1")
	)
	(segment
		(start 387.985 -93.544898)
		(end 387.985 -93.271086)
		(width 0.0889)
		(layer "F.Cu")
		(net "RMII_SPRNGVLLE_BMC_PCH_RXD0_R1")
	)
	(segment
		(start 388.122668 -91.707208)
		(end 388.122668 -90.440002)
		(width 0.0889)
		(layer "F.Cu")
		(net "RMII_SPRNGVLLE_BMC_PCH_RXD0_R1")
	)
	(segment
		(start 387.985 -93.271086)
		(end 387.97611 -93.262196)
		(width 0.0889)
		(layer "F.Cu")
		(net "RMII_SPRNGVLLE_BMC_PCH_RXD0_R1")
	)
	(segment
		(start 388.122668 -90.440002)
		(end 388.122668 -89.748868)
		(width 0.10795)
		(layer "F.Cu")
		(net "RMII_SPRNGVLLE_BMC_PCH_RXD0_R1")
	)
	(segment
		(start 387.97611 -91.853766)
		(end 388.122668 -91.707208)
		(width 0.0889)
		(layer "F.Cu")
		(net "RMII_SPRNGVLLE_BMC_PCH_RXD0_R1")
	)
	(segment
		(start 388.366 -88.466676)
		(end 388.366 -88.2015)
		(width 0.10795)
		(layer "F.Cu")
		(net "RMII_SPRNGVLLE_BMC_PCH_RXD0_R1")
	)
	(segment
		(start 388.586726 -89.28481)
		(end 388.586726 -88.687402)
		(width 0.10795)
		(layer "F.Cu")
		(net "RMII_SPRNGVLLE_BMC_PCH_RXD0_R1")
	)
	(segment
		(start 465.6836 -0.2032)
		(end 466.217 -0.2032)
		(width 0.254)
		(layer "F.Cu")
		(net "A_P3V_BAT_SCALED")
	)
	(segment
		(start 413.090106 -29.334714)
		(end 412.29026 -29.334714)
		(width 0.127)
		(layer "F.Cu")
		(net "A_P3V_BAT_SCALED")
	)
	(segment
		(start 412.29026 -29.334714)
		(end 411.89021 -28.934664)
		(width 0.127)
		(layer "F.Cu")
		(net "A_P3V_BAT_SCALED")
	)
	(segment
		(start 465.328 0.293116)
		(end 465.328 -0.254)
		(width 0.254)
		(layer "F.Cu")
		(net "A_P3V_BAT_SCALED")
	)
	(segment
		(start 465.328 -0.254)
		(end 465.6328 -0.254)
		(width 0.254)
		(layer "F.Cu")
		(net "A_P3V_BAT_SCALED")
	)
	(segment
		(start 464.533996 1.08712)
		(end 465.328 0.293116)
		(width 0.254)
		(layer "F.Cu")
		(net "A_P3V_BAT_SCALED")
	)
	(segment
		(start 464.533996 1.51892)
		(end 464.533996 1.08712)
		(width 0.254)
		(layer "F.Cu")
		(net "A_P3V_BAT_SCALED")
	)
	(segment
		(start 465.6328 -0.254)
		(end 465.6836 -0.2032)
		(width 0.254)
		(layer "F.Cu")
		(net "A_P3V_BAT_SCALED")
	)
	(segment
		(start 466.217 -0.2032)
		(end 466.217 0.4318)
		(width 0.254)
		(layer "F.Cu")
		(net "A_P3V_BAT_SCALED")
	)
	(via
		(at 413.090106 -29.334714)
		(size 0.4572)
		(drill 0.2032)
		(layers "F.Cu" "B.Cu")
		(net "A_P3V_BAT_SCALED")
	)
	(via
		(at 451.97776 -13.2715)
		(size 0.6604)
		(drill 0.3302)
		(layers "F.Cu" "B.Cu")
		(net "A_P3V_BAT_SCALED")
	)
	(via
		(at 466.217 0.4318)
		(size 0.508)
		(drill 0.254)
		(layers "F.Cu" "B.Cu")
		(net "A_P3V_BAT_SCALED")
	)
	(via
		(at 450.85 -13.589)
		(size 0.508)
		(drill 0.254)
		(layers "F.Cu" "B.Cu")
		(net "A_P3V_BAT_SCALED")
	)
	(segment
		(start 451.66026 -13.589)
		(end 451.97776 -13.2715)
		(width 0.254)
		(layer "B.Cu")
		(net "A_P3V_BAT_SCALED")
	)
	(segment
		(start 463.136996 -0.048768)
		(end 463.427064 0.2413)
		(width 0.254)
		(layer "B.Cu")
		(net "A_P3V_BAT_SCALED")
	)
	(segment
		(start 461.493108 -1.59385)
		(end 461.905604 -1.59385)
		(width 0.254)
		(layer "B.Cu")
		(net "A_P3V_BAT_SCALED")
	)
	(segment
		(start 461.905604 -1.59385)
		(end 463.136996 -0.362458)
		(width 0.254)
		(layer "B.Cu")
		(net "A_P3V_BAT_SCALED")
	)
	(segment
		(start 455.8792 -8.2042)
		(end 460.15783 -3.92557)
		(width 0.254)
		(layer "B.Cu")
		(net "A_P3V_BAT_SCALED")
	)
	(segment
		(start 463.136996 -0.362458)
		(end 463.136996 -0.048768)
		(width 0.254)
		(layer "B.Cu")
		(net "A_P3V_BAT_SCALED")
	)
	(segment
		(start 451.97776 -13.2715)
		(end 453.879712 -11.369548)
		(width 0.254)
		(layer "B.Cu")
		(net "A_P3V_BAT_SCALED")
	)
	(segment
		(start 453.879712 -9.078976)
		(end 454.754488 -8.2042)
		(width 0.254)
		(layer "B.Cu")
		(net "A_P3V_BAT_SCALED")
	)
	(segment
		(start 460.15783 -3.92557)
		(end 460.15783 -2.47777)
		(width 0.254)
		(layer "B.Cu")
		(net "A_P3V_BAT_SCALED")
	)
	(segment
		(start 466.0265 0.2413)
		(end 466.217 0.4318)
		(width 0.254)
		(layer "B.Cu")
		(net "A_P3V_BAT_SCALED")
	)
	(segment
		(start 461.486758 -1.6002)
		(end 461.493108 -1.59385)
		(width 0.254)
		(layer "B.Cu")
		(net "A_P3V_BAT_SCALED")
	)
	(segment
		(start 453.879712 -11.369548)
		(end 453.879712 -9.078976)
		(width 0.254)
		(layer "B.Cu")
		(net "A_P3V_BAT_SCALED")
	)
	(segment
		(start 463.427064 0.2413)
		(end 466.0265 0.2413)
		(width 0.254)
		(layer "B.Cu")
		(net "A_P3V_BAT_SCALED")
	)
	(segment
		(start 460.15783 -2.47777)
		(end 461.0354 -1.6002)
		(width 0.254)
		(layer "B.Cu")
		(net "A_P3V_BAT_SCALED")
	)
	(segment
		(start 454.754488 -8.2042)
		(end 455.8792 -8.2042)
		(width 0.254)
		(layer "B.Cu")
		(net "A_P3V_BAT_SCALED")
	)
	(segment
		(start 461.0354 -1.6002)
		(end 461.486758 -1.6002)
		(width 0.254)
		(layer "B.Cu")
		(net "A_P3V_BAT_SCALED")
	)
	(segment
		(start 450.85 -13.589)
		(end 451.66026 -13.589)
		(width 0.254)
		(layer "B.Cu")
		(net "A_P3V_BAT_SCALED")
	)
	(segment
		(start 412.824168 -29.334714)
		(end 413.090106 -29.334714)
		(width 0.254)
		(layer "In11.Cu")
		(net "A_P3V_BAT_SCALED")
	)
	(segment
		(start 447.894202 -14.88059)
		(end 447.894202 -16.842994)
		(width 0.381)
		(layer "In11.Cu")
		(net "A_P3V_BAT_SCALED")
	)
	(segment
		(start 423.69359 -19.718782)
		(end 420.666164 -19.718782)
		(width 0.381)
		(layer "In11.Cu")
		(net "A_P3V_BAT_SCALED")
	)
	(segment
		(start 448.310762 -14.46403)
		(end 447.894202 -14.88059)
		(width 0.381)
		(layer "In11.Cu")
		(net "A_P3V_BAT_SCALED")
	)
	(segment
		(start 447.3702 -17.366996)
		(end 445.027304 -17.366996)
		(width 0.381)
		(layer "In11.Cu")
		(net "A_P3V_BAT_SCALED")
	)
	(segment
		(start 420.666164 -19.718782)
		(end 418.604446 -21.7805)
		(width 0.381)
		(layer "In11.Cu")
		(net "A_P3V_BAT_SCALED")
	)
	(segment
		(start 447.894202 -16.842994)
		(end 447.3702 -17.366996)
		(width 0.381)
		(layer "In11.Cu")
		(net "A_P3V_BAT_SCALED")
	)
	(segment
		(start 425.353988 -18.058384)
		(end 423.69359 -19.718782)
		(width 0.381)
		(layer "In11.Cu")
		(net "A_P3V_BAT_SCALED")
	)
	(segment
		(start 444.586868 -17.807432)
		(end 439.615834 -17.807432)
		(width 0.381)
		(layer "In11.Cu")
		(net "A_P3V_BAT_SCALED")
	)
	(segment
		(start 439.615834 -17.807432)
		(end 438.585102 -18.838164)
		(width 0.381)
		(layer "In11.Cu")
		(net "A_P3V_BAT_SCALED")
	)
	(segment
		(start 412.570168 -27.040332)
		(end 412.570168 -29.080714)
		(width 0.254)
		(layer "In11.Cu")
		(net "A_P3V_BAT_SCALED")
	)
	(segment
		(start 445.027304 -17.366996)
		(end 444.586868 -17.807432)
		(width 0.381)
		(layer "In11.Cu")
		(net "A_P3V_BAT_SCALED")
	)
	(segment
		(start 412.570168 -23.141432)
		(end 412.570168 -27.040332)
		(width 0.381)
		(layer "In11.Cu")
		(net "A_P3V_BAT_SCALED")
	)
	(segment
		(start 435.365652 -18.838164)
		(end 434.585872 -18.058384)
		(width 0.381)
		(layer "In11.Cu")
		(net "A_P3V_BAT_SCALED")
	)
	(segment
		(start 434.585872 -18.058384)
		(end 425.353988 -18.058384)
		(width 0.381)
		(layer "In11.Cu")
		(net "A_P3V_BAT_SCALED")
	)
	(segment
		(start 418.604446 -21.7805)
		(end 413.9311 -21.7805)
		(width 0.381)
		(layer "In11.Cu")
		(net "A_P3V_BAT_SCALED")
	)
	(segment
		(start 450.85 -13.589)
		(end 449.97497 -14.46403)
		(width 0.381)
		(layer "In11.Cu")
		(net "A_P3V_BAT_SCALED")
	)
	(segment
		(start 413.9311 -21.7805)
		(end 412.570168 -23.141432)
		(width 0.381)
		(layer "In11.Cu")
		(net "A_P3V_BAT_SCALED")
	)
	(segment
		(start 449.97497 -14.46403)
		(end 448.310762 -14.46403)
		(width 0.381)
		(layer "In11.Cu")
		(net "A_P3V_BAT_SCALED")
	)
	(segment
		(start 438.585102 -18.838164)
		(end 435.365652 -18.838164)
		(width 0.381)
		(layer "In11.Cu")
		(net "A_P3V_BAT_SCALED")
	)
	(segment
		(start 412.570168 -29.080714)
		(end 412.824168 -29.334714)
		(width 0.254)
		(layer "In11.Cu")
		(net "A_P3V_BAT_SCALED")
	)
	(via
		(at 453.939656 -7.902702)
		(size 0.6604)
		(drill 0.3302)
		(layers "F.Cu" "B.Cu")
		(net "A_P3V_BAT_R")
	)
	(segment
		(start 453.494902 -9.242298)
		(end 453.494902 -8.347456)
		(width 0.254)
		(layer "B.Cu")
		(net "A_P3V_BAT_R")
	)
	(segment
		(start 448.7164 -8.4328)
		(end 449.0974 -8.0518)
		(width 0.254)
		(layer "B.Cu")
		(net "A_P3V_BAT_R")
	)
	(segment
		(start 451.9676 -10.7696)
		(end 453.494902 -9.242298)
		(width 0.254)
		(layer "B.Cu")
		(net "A_P3V_BAT_R")
	)
	(segment
		(start 448.7164 -9.6012)
		(end 449.8848 -10.7696)
		(width 0.254)
		(layer "B.Cu")
		(net "A_P3V_BAT_R")
	)
	(segment
		(start 448.7164 -9.6012)
		(end 448.7164 -8.4328)
		(width 0.254)
		(layer "B.Cu")
		(net "A_P3V_BAT_R")
	)
	(segment
		(start 453.494902 -8.347456)
		(end 453.939656 -7.902702)
		(width 0.254)
		(layer "B.Cu")
		(net "A_P3V_BAT_R")
	)
	(segment
		(start 449.8848 -10.7696)
		(end 451.9676 -10.7696)
		(width 0.254)
		(layer "B.Cu")
		(net "A_P3V_BAT_R")
	)
	(segment
		(start 453.939656 -7.902702)
		(end 454.269602 -7.572756)
		(width 0.254)
		(layer "B.Cu")
		(net "A_P3V_BAT_R")
	)
	(segment
		(start 455.474324 -7.572756)
		(end 457.454 -5.59308)
		(width 0.254)
		(layer "B.Cu")
		(net "A_P3V_BAT_R")
	)
	(segment
		(start 457.454 -5.59308)
		(end 457.454 -4.2164)
		(width 0.254)
		(layer "B.Cu")
		(net "A_P3V_BAT_R")
	)
	(segment
		(start 454.269602 -7.572756)
		(end 455.474324 -7.572756)
		(width 0.254)
		(layer "B.Cu")
		(net "A_P3V_BAT_R")
	)
	(segment
		(start 389.71855 -100.41128)
		(end 389.7376 -100.40239)
		(width 0.10795)
		(layer "F.Cu")
		(net "IRQ_PCH_NIC_ALERT_N")
	)
	(segment
		(start 409.890214 -39.734744)
		(end 410.290264 -39.334694)
		(width 0.10795)
		(layer "F.Cu")
		(net "IRQ_PCH_NIC_ALERT_N")
	)
	(segment
		(start 389.7376 -100.40239)
		(end 390.21385 -100.181156)
		(width 0.10795)
		(layer "F.Cu")
		(net "IRQ_PCH_NIC_ALERT_N")
	)
	(segment
		(start 395.16685 -102.98684)
		(end 395.66215 -102.756716)
		(width 0.10795)
		(layer "F.Cu")
		(net "IRQ_PCH_NIC_ALERT_N")
	)
	(via
		(at 395.66215 -102.756716)
		(size 0.508)
		(drill 0.254)
		(layers "F.Cu" "B.Cu")
		(net "IRQ_PCH_NIC_ALERT_N")
	)
	(via
		(at 402.7551 -98.806254)
		(size 0.6604)
		(drill 0.3302)
		(layers "F.Cu" "B.Cu")
		(net "IRQ_PCH_NIC_ALERT_N")
	)
	(via
		(at 390.21385 -100.181156)
		(size 0.508)
		(drill 0.254)
		(layers "F.Cu" "B.Cu")
		(net "IRQ_PCH_NIC_ALERT_N")
	)
	(via
		(at 409.890214 -39.734744)
		(size 0.4572)
		(drill 0.2032)
		(layers "F.Cu" "B.Cu")
		(net "IRQ_PCH_NIC_ALERT_N")
	)
	(segment
		(start 401.4978 -98.787458)
		(end 401.4978 -99.54387)
		(width 0.10795)
		(layer "B.Cu")
		(net "IRQ_PCH_NIC_ALERT_N")
	)
	(segment
		(start 402.48332 -98.806254)
		(end 402.15185 -98.474784)
		(width 0.10795)
		(layer "B.Cu")
		(net "IRQ_PCH_NIC_ALERT_N")
	)
	(segment
		(start 403.2504 -98.679)
		(end 403.123146 -98.806254)
		(width 0.10795)
		(layer "B.Cu")
		(net "IRQ_PCH_NIC_ALERT_N")
	)
	(segment
		(start 398.320006 -102.38359)
		(end 396.035276 -102.38359)
		(width 0.10795)
		(layer "B.Cu")
		(net "IRQ_PCH_NIC_ALERT_N")
	)
	(segment
		(start 402.15185 -98.474784)
		(end 402.150326 -98.474784)
		(width 0.10795)
		(layer "B.Cu")
		(net "IRQ_PCH_NIC_ALERT_N")
	)
	(segment
		(start 401.811236 -98.474022)
		(end 401.4978 -98.787458)
		(width 0.10795)
		(layer "B.Cu")
		(net "IRQ_PCH_NIC_ALERT_N")
	)
	(segment
		(start 402.7551 -98.806254)
		(end 402.48332 -98.806254)
		(width 0.10795)
		(layer "B.Cu")
		(net "IRQ_PCH_NIC_ALERT_N")
	)
	(segment
		(start 402.150326 -98.474784)
		(end 402.149564 -98.474022)
		(width 0.10795)
		(layer "B.Cu")
		(net "IRQ_PCH_NIC_ALERT_N")
	)
	(segment
		(start 398.59966 -101.697028)
		(end 398.59966 -102.103936)
		(width 0.10795)
		(layer "B.Cu")
		(net "IRQ_PCH_NIC_ALERT_N")
	)
	(segment
		(start 400.994372 -100.047298)
		(end 400.24939 -100.047298)
		(width 0.10795)
		(layer "B.Cu")
		(net "IRQ_PCH_NIC_ALERT_N")
	)
	(segment
		(start 400.24939 -100.047298)
		(end 398.59966 -101.697028)
		(width 0.10795)
		(layer "B.Cu")
		(net "IRQ_PCH_NIC_ALERT_N")
	)
	(segment
		(start 401.4978 -99.54387)
		(end 400.994372 -100.047298)
		(width 0.10795)
		(layer "B.Cu")
		(net "IRQ_PCH_NIC_ALERT_N")
	)
	(segment
		(start 403.6695 -98.679)
		(end 403.2504 -98.679)
		(width 0.10795)
		(layer "B.Cu")
		(net "IRQ_PCH_NIC_ALERT_N")
	)
	(segment
		(start 402.149564 -98.474022)
		(end 401.811236 -98.474022)
		(width 0.10795)
		(layer "B.Cu")
		(net "IRQ_PCH_NIC_ALERT_N")
	)
	(segment
		(start 396.035276 -102.38359)
		(end 395.66215 -102.756716)
		(width 0.10795)
		(layer "B.Cu")
		(net "IRQ_PCH_NIC_ALERT_N")
	)
	(segment
		(start 403.123146 -98.806254)
		(end 402.7551 -98.806254)
		(width 0.10795)
		(layer "B.Cu")
		(net "IRQ_PCH_NIC_ALERT_N")
	)
	(segment
		(start 398.59966 -102.103936)
		(end 398.320006 -102.38359)
		(width 0.10795)
		(layer "B.Cu")
		(net "IRQ_PCH_NIC_ALERT_N")
	)
	(segment
		(start 390.74598 -102.10038)
		(end 390.95934 -102.31374)
		(width 0.089408)
		(layer "In2.Cu")
		(net "IRQ_PCH_NIC_ALERT_N")
	)
	(segment
		(start 395.219174 -102.31374)
		(end 395.66215 -102.756716)
		(width 0.089408)
		(layer "In2.Cu")
		(net "IRQ_PCH_NIC_ALERT_N")
	)
	(segment
		(start 390.95934 -102.31374)
		(end 395.219174 -102.31374)
		(width 0.089408)
		(layer "In2.Cu")
		(net "IRQ_PCH_NIC_ALERT_N")
	)
	(segment
		(start 390.21385 -100.181156)
		(end 390.21385 -101.22027)
		(width 0.089408)
		(layer "In2.Cu")
		(net "IRQ_PCH_NIC_ALERT_N")
	)
	(segment
		(start 390.74598 -101.7524)
		(end 390.74598 -102.10038)
		(width 0.089408)
		(layer "In2.Cu")
		(net "IRQ_PCH_NIC_ALERT_N")
	)
	(segment
		(start 390.21385 -101.22027)
		(end 390.74598 -101.7524)
		(width 0.089408)
		(layer "In2.Cu")
		(net "IRQ_PCH_NIC_ALERT_N")
	)
	(segment
		(start 398.476724 -77.077824)
		(end 398.476724 -76.747624)
		(width 0.089408)
		(layer "In9.Cu")
		(net "IRQ_PCH_NIC_ALERT_N")
	)
	(segment
		(start 394.518896 -87.039704)
		(end 394.518896 -86.473538)
		(width 0.089408)
		(layer "In9.Cu")
		(net "IRQ_PCH_NIC_ALERT_N")
	)
	(segment
		(start 408.935174 -40.159686)
		(end 409.231592 -40.159686)
		(width 0.089408)
		(layer "In9.Cu")
		(net "IRQ_PCH_NIC_ALERT_N")
	)
	(segment
		(start 393.472924 -90.095324)
		(end 392.8618 -89.4842)
		(width 0.089408)
		(layer "In9.Cu")
		(net "IRQ_PCH_NIC_ALERT_N")
	)
	(segment
		(start 388.82447 -96.95307)
		(end 388.82447 -96.35617)
		(width 0.089408)
		(layer "In9.Cu")
		(net "IRQ_PCH_NIC_ALERT_N")
	)
	(segment
		(start 392.8618 -89.4842)
		(end 392.8618 -88.6968)
		(width 0.089408)
		(layer "In9.Cu")
		(net "IRQ_PCH_NIC_ALERT_N")
	)
	(segment
		(start 403.349714 -44.902628)
		(end 404.34006 -43.912282)
		(width 0.089408)
		(layer "In9.Cu")
		(net "IRQ_PCH_NIC_ALERT_N")
	)
	(segment
		(start 398.976342 -68.619624)
		(end 401.184872 -66.411094)
		(width 0.089408)
		(layer "In9.Cu")
		(net "IRQ_PCH_NIC_ALERT_N")
	)
	(segment
		(start 396.951454 -78.169262)
		(end 397.235934 -77.884782)
		(width 0.089408)
		(layer "In9.Cu")
		(net "IRQ_PCH_NIC_ALERT_N")
	)
	(segment
		(start 409.231592 -40.159686)
		(end 409.656534 -39.734744)
		(width 0.089408)
		(layer "In9.Cu")
		(net "IRQ_PCH_NIC_ALERT_N")
	)
	(segment
		(start 388.82447 -98.855022)
		(end 388.82447 -98.07321)
		(width 0.089408)
		(layer "In9.Cu")
		(net "IRQ_PCH_NIC_ALERT_N")
	)
	(segment
		(start 389.12673 -99.157282)
		(end 388.82447 -98.855022)
		(width 0.089408)
		(layer "In9.Cu")
		(net "IRQ_PCH_NIC_ALERT_N")
	)
	(segment
		(start 395.097254 -85.992208)
		(end 396.951454 -84.138008)
		(width 0.089408)
		(layer "In9.Cu")
		(net "IRQ_PCH_NIC_ALERT_N")
	)
	(segment
		(start 398.976596 -68.936362)
		(end 398.976342 -68.936108)
		(width 0.089408)
		(layer "In9.Cu")
		(net "IRQ_PCH_NIC_ALERT_N")
	)
	(segment
		(start 398.326102 -71.938896)
		(end 398.976596 -71.288402)
		(width 0.089408)
		(layer "In9.Cu")
		(net "IRQ_PCH_NIC_ALERT_N")
	)
	(segment
		(start 399.2372 -75.987148)
		(end 399.2372 -73.761854)
		(width 0.089408)
		(layer "In9.Cu")
		(net "IRQ_PCH_NIC_ALERT_N")
	)
	(segment
		(start 388.82447 -96.35617)
		(end 389.12673 -96.05391)
		(width 0.089408)
		(layer "In9.Cu")
		(net "IRQ_PCH_NIC_ALERT_N")
	)
	(segment
		(start 397.235934 -77.884782)
		(end 397.669766 -77.884782)
		(width 0.089408)
		(layer "In9.Cu")
		(net "IRQ_PCH_NIC_ALERT_N")
	)
	(segment
		(start 399.2372 -73.761854)
		(end 398.326102 -72.850756)
		(width 0.089408)
		(layer "In9.Cu")
		(net "IRQ_PCH_NIC_ALERT_N")
	)
	(segment
		(start 396.951454 -84.138008)
		(end 396.951454 -78.169262)
		(width 0.089408)
		(layer "In9.Cu")
		(net "IRQ_PCH_NIC_ALERT_N")
	)
	(segment
		(start 407.436066 -40.909494)
		(end 408.445208 -40.909494)
		(width 0.089408)
		(layer "In9.Cu")
		(net "IRQ_PCH_NIC_ALERT_N")
	)
	(segment
		(start 404.34006 -43.735752)
		(end 404.590758 -43.485054)
		(width 0.089408)
		(layer "In9.Cu")
		(net "IRQ_PCH_NIC_ALERT_N")
	)
	(segment
		(start 395.000226 -85.992208)
		(end 395.097254 -85.992208)
		(width 0.089408)
		(layer "In9.Cu")
		(net "IRQ_PCH_NIC_ALERT_N")
	)
	(segment
		(start 404.590758 -43.4848)
		(end 405.134318 -42.94124)
		(width 0.089408)
		(layer "In9.Cu")
		(net "IRQ_PCH_NIC_ALERT_N")
	)
	(segment
		(start 393.472924 -90.687398)
		(end 393.472924 -90.095324)
		(width 0.089408)
		(layer "In9.Cu")
		(net "IRQ_PCH_NIC_ALERT_N")
	)
	(segment
		(start 390.012936 -100.181156)
		(end 389.12673 -99.29495)
		(width 0.089408)
		(layer "In9.Cu")
		(net "IRQ_PCH_NIC_ALERT_N")
	)
	(segment
		(start 409.656534 -39.734744)
		(end 409.890214 -39.734744)
		(width 0.089408)
		(layer "In9.Cu")
		(net "IRQ_PCH_NIC_ALERT_N")
	)
	(segment
		(start 402.525992 -57.946544)
		(end 400.878802 -56.299354)
		(width 0.089408)
		(layer "In9.Cu")
		(net "IRQ_PCH_NIC_ALERT_N")
	)
	(segment
		(start 404.590758 -43.485054)
		(end 404.590758 -43.4848)
		(width 0.089408)
		(layer "In9.Cu")
		(net "IRQ_PCH_NIC_ALERT_N")
	)
	(segment
		(start 389.12673 -97.25533)
		(end 388.82447 -96.95307)
		(width 0.089408)
		(layer "In9.Cu")
		(net "IRQ_PCH_NIC_ALERT_N")
	)
	(segment
		(start 400.879056 -55.665624)
		(end 400.879056 -48.24603)
		(width 0.089408)
		(layer "In9.Cu")
		(net "IRQ_PCH_NIC_ALERT_N")
	)
	(segment
		(start 408.71521 -40.37965)
		(end 408.935174 -40.159686)
		(width 0.089408)
		(layer "In9.Cu")
		(net "IRQ_PCH_NIC_ALERT_N")
	)
	(segment
		(start 389.12673 -95.64624)
		(end 390.73836 -94.03461)
		(width 0.089408)
		(layer "In9.Cu")
		(net "IRQ_PCH_NIC_ALERT_N")
	)
	(segment
		(start 401.184872 -66.411094)
		(end 401.184872 -63.56731)
		(width 0.089408)
		(layer "In9.Cu")
		(net "IRQ_PCH_NIC_ALERT_N")
	)
	(segment
		(start 392.606784 -92.728542)
		(end 392.606784 -91.553538)
		(width 0.089408)
		(layer "In9.Cu")
		(net "IRQ_PCH_NIC_ALERT_N")
	)
	(segment
		(start 402.5265 -62.225682)
		(end 402.5265 -61.116718)
		(width 0.089408)
		(layer "In9.Cu")
		(net "IRQ_PCH_NIC_ALERT_N")
	)
	(segment
		(start 402.5265 -61.116718)
		(end 402.526246 -61.116464)
		(width 0.089408)
		(layer "In9.Cu")
		(net "IRQ_PCH_NIC_ALERT_N")
	)
	(segment
		(start 389.12673 -96.05391)
		(end 389.12673 -95.64624)
		(width 0.089408)
		(layer "In9.Cu")
		(net "IRQ_PCH_NIC_ALERT_N")
	)
	(segment
		(start 392.8618 -88.6968)
		(end 394.518896 -87.039704)
		(width 0.089408)
		(layer "In9.Cu")
		(net "IRQ_PCH_NIC_ALERT_N")
	)
	(segment
		(start 391.300716 -94.03461)
		(end 392.606784 -92.728542)
		(width 0.089408)
		(layer "In9.Cu")
		(net "IRQ_PCH_NIC_ALERT_N")
	)
	(segment
		(start 403.349714 -45.775372)
		(end 403.349714 -44.902628)
		(width 0.089408)
		(layer "In9.Cu")
		(net "IRQ_PCH_NIC_ALERT_N")
	)
	(segment
		(start 405.134318 -42.94124)
		(end 405.40432 -42.94124)
		(width 0.089408)
		(layer "In9.Cu")
		(net "IRQ_PCH_NIC_ALERT_N")
	)
	(segment
		(start 390.73836 -94.03461)
		(end 391.300716 -94.03461)
		(width 0.089408)
		(layer "In9.Cu")
		(net "IRQ_PCH_NIC_ALERT_N")
	)
	(segment
		(start 401.184872 -63.56731)
		(end 402.5265 -62.225682)
		(width 0.089408)
		(layer "In9.Cu")
		(net "IRQ_PCH_NIC_ALERT_N")
	)
	(segment
		(start 408.71521 -40.639492)
		(end 408.71521 -40.37965)
		(width 0.089408)
		(layer "In9.Cu")
		(net "IRQ_PCH_NIC_ALERT_N")
	)
	(segment
		(start 398.476724 -76.747624)
		(end 399.2372 -75.987148)
		(width 0.089408)
		(layer "In9.Cu")
		(net "IRQ_PCH_NIC_ALERT_N")
	)
	(segment
		(start 394.518896 -86.473538)
		(end 395.000226 -85.992208)
		(width 0.089408)
		(layer "In9.Cu")
		(net "IRQ_PCH_NIC_ALERT_N")
	)
	(segment
		(start 390.21385 -100.181156)
		(end 390.012936 -100.181156)
		(width 0.089408)
		(layer "In9.Cu")
		(net "IRQ_PCH_NIC_ALERT_N")
	)
	(segment
		(start 398.326102 -72.850756)
		(end 398.326102 -71.938896)
		(width 0.089408)
		(layer "In9.Cu")
		(net "IRQ_PCH_NIC_ALERT_N")
	)
	(segment
		(start 398.976596 -71.288402)
		(end 398.976596 -68.936362)
		(width 0.089408)
		(layer "In9.Cu")
		(net "IRQ_PCH_NIC_ALERT_N")
	)
	(segment
		(start 389.12673 -99.29495)
		(end 389.12673 -99.157282)
		(width 0.089408)
		(layer "In9.Cu")
		(net "IRQ_PCH_NIC_ALERT_N")
	)
	(segment
		(start 400.878802 -56.299354)
		(end 400.878802 -55.665878)
		(width 0.089408)
		(layer "In9.Cu")
		(net "IRQ_PCH_NIC_ALERT_N")
	)
	(segment
		(start 405.40432 -42.94124)
		(end 407.436066 -40.909494)
		(width 0.089408)
		(layer "In9.Cu")
		(net "IRQ_PCH_NIC_ALERT_N")
	)
	(segment
		(start 400.879056 -48.24603)
		(end 403.349714 -45.775372)
		(width 0.089408)
		(layer "In9.Cu")
		(net "IRQ_PCH_NIC_ALERT_N")
	)
	(segment
		(start 408.445208 -40.909494)
		(end 408.71521 -40.639492)
		(width 0.089408)
		(layer "In9.Cu")
		(net "IRQ_PCH_NIC_ALERT_N")
	)
	(segment
		(start 397.669766 -77.884782)
		(end 398.476724 -77.077824)
		(width 0.089408)
		(layer "In9.Cu")
		(net "IRQ_PCH_NIC_ALERT_N")
	)
	(segment
		(start 402.526246 -60.641484)
		(end 402.525992 -60.64123)
		(width 0.089408)
		(layer "In9.Cu")
		(net "IRQ_PCH_NIC_ALERT_N")
	)
	(segment
		(start 402.526246 -61.116464)
		(end 402.526246 -60.641484)
		(width 0.089408)
		(layer "In9.Cu")
		(net "IRQ_PCH_NIC_ALERT_N")
	)
	(segment
		(start 389.12673 -97.77095)
		(end 389.12673 -97.25533)
		(width 0.089408)
		(layer "In9.Cu")
		(net "IRQ_PCH_NIC_ALERT_N")
	)
	(segment
		(start 388.82447 -98.07321)
		(end 389.12673 -97.77095)
		(width 0.089408)
		(layer "In9.Cu")
		(net "IRQ_PCH_NIC_ALERT_N")
	)
	(segment
		(start 392.606784 -91.553538)
		(end 393.472924 -90.687398)
		(width 0.089408)
		(layer "In9.Cu")
		(net "IRQ_PCH_NIC_ALERT_N")
	)
	(segment
		(start 398.976342 -68.936108)
		(end 398.976342 -68.619624)
		(width 0.089408)
		(layer "In9.Cu")
		(net "IRQ_PCH_NIC_ALERT_N")
	)
	(segment
		(start 400.878802 -55.665878)
		(end 400.879056 -55.665624)
		(width 0.089408)
		(layer "In9.Cu")
		(net "IRQ_PCH_NIC_ALERT_N")
	)
	(segment
		(start 404.34006 -43.912282)
		(end 404.34006 -43.735752)
		(width 0.089408)
		(layer "In9.Cu")
		(net "IRQ_PCH_NIC_ALERT_N")
	)
	(segment
		(start 402.525992 -60.64123)
		(end 402.525992 -57.946544)
		(width 0.089408)
		(layer "In9.Cu")
		(net "IRQ_PCH_NIC_ALERT_N")
	)
	(segment
		(start 410.2354 -113.1824)
		(end 411.645608 -113.1824)
		(width 0.10795)
		(layer "F.Cu")
		(net "IRQ_OOB_MGMT_RISER_ALERT_N")
	)
	(segment
		(start 411.645608 -113.1824)
		(end 411.791404 -113.036604)
		(width 0.10795)
		(layer "F.Cu")
		(net "IRQ_OOB_MGMT_RISER_ALERT_N")
	)
	(segment
		(start 468.73668 -3.38074)
		(end 468.479378 -3.638042)
		(width 0.10795)
		(layer "F.Cu")
		(net "IRQ_OOB_MGMT_RISER_ALERT_N")
	)
	(segment
		(start 404.76678 -112.66424)
		(end 405.52624 -113.4237)
		(width 0.10795)
		(layer "F.Cu")
		(net "IRQ_OOB_MGMT_RISER_ALERT_N")
	)
	(segment
		(start 401.13458 -112.150398)
		(end 402.803614 -112.150398)
		(width 0.10795)
		(layer "F.Cu")
		(net "IRQ_OOB_MGMT_RISER_ALERT_N")
	)
	(segment
		(start 405.52624 -113.4237)
		(end 406.018492 -113.4237)
		(width 0.10795)
		(layer "F.Cu")
		(net "IRQ_OOB_MGMT_RISER_ALERT_N")
	)
	(segment
		(start 409.685998 -113.731802)
		(end 410.2354 -113.1824)
		(width 0.10795)
		(layer "F.Cu")
		(net "IRQ_OOB_MGMT_RISER_ALERT_N")
	)
	(segment
		(start 400.74723 -112.03432)
		(end 401.018502 -112.03432)
		(width 0.10795)
		(layer "F.Cu")
		(net "IRQ_OOB_MGMT_RISER_ALERT_N")
	)
	(segment
		(start 412.179008 -112.649)
		(end 411.791404 -113.036604)
		(width 0.10795)
		(layer "F.Cu")
		(net "IRQ_OOB_MGMT_RISER_ALERT_N")
	)
	(segment
		(start 409.490164 -38.534594)
		(end 409.490418 -38.534594)
		(width 0.10795)
		(layer "F.Cu")
		(net "IRQ_OOB_MGMT_RISER_ALERT_N")
	)
	(segment
		(start 403.317456 -112.66424)
		(end 404.76678 -112.66424)
		(width 0.10795)
		(layer "F.Cu")
		(net "IRQ_OOB_MGMT_RISER_ALERT_N")
	)
	(segment
		(start 409.490418 -38.534594)
		(end 409.890214 -38.134798)
		(width 0.10795)
		(layer "F.Cu")
		(net "IRQ_OOB_MGMT_RISER_ALERT_N")
	)
	(segment
		(start 400.426428 -112.355122)
		(end 400.74723 -112.03432)
		(width 0.10795)
		(layer "F.Cu")
		(net "IRQ_OOB_MGMT_RISER_ALERT_N")
	)
	(segment
		(start 402.803614 -112.150398)
		(end 403.317456 -112.66424)
		(width 0.10795)
		(layer "F.Cu")
		(net "IRQ_OOB_MGMT_RISER_ALERT_N")
	)
	(segment
		(start 412.4325 -112.649)
		(end 412.179008 -112.649)
		(width 0.10795)
		(layer "F.Cu")
		(net "IRQ_OOB_MGMT_RISER_ALERT_N")
	)
	(segment
		(start 406.326594 -113.731802)
		(end 409.685998 -113.731802)
		(width 0.10795)
		(layer "F.Cu")
		(net "IRQ_OOB_MGMT_RISER_ALERT_N")
	)
	(segment
		(start 406.018492 -113.4237)
		(end 406.326594 -113.731802)
		(width 0.10795)
		(layer "F.Cu")
		(net "IRQ_OOB_MGMT_RISER_ALERT_N")
	)
	(segment
		(start 468.479378 -3.638042)
		(end 468.479378 -4.386072)
		(width 0.10795)
		(layer "F.Cu")
		(net "IRQ_OOB_MGMT_RISER_ALERT_N")
	)
	(segment
		(start 400.05 -112.355122)
		(end 400.426428 -112.355122)
		(width 0.10795)
		(layer "F.Cu")
		(net "IRQ_OOB_MGMT_RISER_ALERT_N")
	)
	(segment
		(start 401.018502 -112.03432)
		(end 401.13458 -112.150398)
		(width 0.10795)
		(layer "F.Cu")
		(net "IRQ_OOB_MGMT_RISER_ALERT_N")
	)
	(via
		(at 409.890214 -38.134798)
		(size 0.4572)
		(drill 0.2032)
		(layers "F.Cu" "B.Cu")
		(net "IRQ_OOB_MGMT_RISER_ALERT_N")
	)
	(via
		(at 411.988 -70.99173)
		(size 0.508)
		(drill 0.254)
		(layers "F.Cu" "B.Cu")
		(net "IRQ_OOB_MGMT_RISER_ALERT_N")
	)
	(via
		(at 468.73668 -3.38074)
		(size 0.508)
		(drill 0.254)
		(layers "F.Cu" "B.Cu")
		(net "IRQ_OOB_MGMT_RISER_ALERT_N")
	)
	(via
		(at 465.741766 -43.384978)
		(size 0.508)
		(drill 0.254)
		(layers "F.Cu" "B.Cu")
		(net "IRQ_OOB_MGMT_RISER_ALERT_N")
	)
	(via
		(at 411.791404 -113.036604)
		(size 0.508)
		(drill 0.254)
		(layers "F.Cu" "B.Cu")
		(net "IRQ_OOB_MGMT_RISER_ALERT_N")
	)
	(via
		(at 399.74266 -72.36333)
		(size 0.508)
		(drill 0.254)
		(layers "F.Cu" "B.Cu")
		(net "IRQ_OOB_MGMT_RISER_ALERT_N")
	)
	(segment
		(start 477.604074 -8.214868)
		(end 477.604074 -7.863586)
		(width 0.089408)
		(layer "In2.Cu")
		(net "IRQ_OOB_MGMT_RISER_ALERT_N")
	)
	(segment
		(start 409.194 -80.899)
		(end 409.829 -81.534)
		(width 0.089408)
		(layer "In2.Cu")
		(net "IRQ_OOB_MGMT_RISER_ALERT_N")
	)
	(segment
		(start 493.324642 -44.046902)
		(end 493.324642 -39.03472)
		(width 0.089408)
		(layer "In2.Cu")
		(net "IRQ_OOB_MGMT_RISER_ALERT_N")
	)
	(segment
		(start 411.7848 -113.03)
		(end 411.7848 -113.036604)
		(width 0.089408)
		(layer "In2.Cu")
		(net "IRQ_OOB_MGMT_RISER_ALERT_N")
	)
	(segment
		(start 495.131852 -34.764726)
		(end 492.5568 -32.189674)
		(width 0.089408)
		(layer "In2.Cu")
		(net "IRQ_OOB_MGMT_RISER_ALERT_N")
	)
	(segment
		(start 492.83112 -28.334462)
		(end 492.83112 -28.176474)
		(width 0.089408)
		(layer "In2.Cu")
		(net "IRQ_OOB_MGMT_RISER_ALERT_N")
	)
	(segment
		(start 480.593654 -43.0784)
		(end 485.784144 -43.0784)
		(width 0.089408)
		(layer "In2.Cu")
		(net "IRQ_OOB_MGMT_RISER_ALERT_N")
	)
	(segment
		(start 492.830866 -28.17622)
		(end 492.830866 -24.237696)
		(width 0.089408)
		(layer "In2.Cu")
		(net "IRQ_OOB_MGMT_RISER_ALERT_N")
	)
	(segment
		(start 478.397316 -41.817036)
		(end 479.33229 -41.817036)
		(width 0.089408)
		(layer "In2.Cu")
		(net "IRQ_OOB_MGMT_RISER_ALERT_N")
	)
	(segment
		(start 465.741766 -43.606466)
		(end 466.44433 -44.30903)
		(width 0.089408)
		(layer "In2.Cu")
		(net "IRQ_OOB_MGMT_RISER_ALERT_N")
	)
	(segment
		(start 410.758894 -97.69983)
		(end 410.845 -97.785936)
		(width 0.089408)
		(layer "In2.Cu")
		(net "IRQ_OOB_MGMT_RISER_ALERT_N")
	)
	(segment
		(start 405.78024 -75.622912)
		(end 405.78024 -78.144624)
		(width 0.089408)
		(layer "In2.Cu")
		(net "IRQ_OOB_MGMT_RISER_ALERT_N")
	)
	(segment
		(start 485.784144 -43.0784)
		(end 488.418632 -45.712888)
		(width 0.089408)
		(layer "In2.Cu")
		(net "IRQ_OOB_MGMT_RISER_ALERT_N")
	)
	(segment
		(start 474.5228 -44.5516)
		(end 475.662752 -44.5516)
		(width 0.089408)
		(layer "In2.Cu")
		(net "IRQ_OOB_MGMT_RISER_ALERT_N")
	)
	(segment
		(start 493.98428 -37.00272)
		(end 494.321846 -37.00272)
		(width 0.089408)
		(layer "In2.Cu")
		(net "IRQ_OOB_MGMT_RISER_ALERT_N")
	)
	(segment
		(start 477.604074 -7.863586)
		(end 474.216476 -4.475988)
		(width 0.089408)
		(layer "In2.Cu")
		(net "IRQ_OOB_MGMT_RISER_ALERT_N")
	)
	(segment
		(start 411.594808 -103.349552)
		(end 411.594808 -103.391208)
		(width 0.089408)
		(layer "In2.Cu")
		(net "IRQ_OOB_MGMT_RISER_ALERT_N")
	)
	(segment
		(start 410.860494 -112.105694)
		(end 411.7848 -113.03)
		(width 0.089408)
		(layer "In2.Cu")
		(net "IRQ_OOB_MGMT_RISER_ALERT_N")
	)
	(segment
		(start 492.469678 -45.712888)
		(end 493.014 -45.168566)
		(width 0.089408)
		(layer "In2.Cu")
		(net "IRQ_OOB_MGMT_RISER_ALERT_N")
	)
	(segment
		(start 473.742512 -43.771312)
		(end 474.5228 -44.5516)
		(width 0.089408)
		(layer "In2.Cu")
		(net "IRQ_OOB_MGMT_RISER_ALERT_N")
	)
	(segment
		(start 475.662752 -44.5516)
		(end 478.397316 -41.817036)
		(width 0.089408)
		(layer "In2.Cu")
		(net "IRQ_OOB_MGMT_RISER_ALERT_N")
	)
	(segment
		(start 492.830866 -28.40228)
		(end 492.830866 -28.334716)
		(width 0.089408)
		(layer "In2.Cu")
		(net "IRQ_OOB_MGMT_RISER_ALERT_N")
	)
	(segment
		(start 469.831928 -4.475988)
		(end 468.73668 -3.38074)
		(width 0.089408)
		(layer "In2.Cu")
		(net "IRQ_OOB_MGMT_RISER_ALERT_N")
	)
	(segment
		(start 410.860494 -105.267252)
		(end 410.860494 -112.105694)
		(width 0.089408)
		(layer "In2.Cu")
		(net "IRQ_OOB_MGMT_RISER_ALERT_N")
	)
	(segment
		(start 479.18497 -9.795764)
		(end 477.604074 -8.214868)
		(width 0.089408)
		(layer "In2.Cu")
		(net "IRQ_OOB_MGMT_RISER_ALERT_N")
	)
	(segment
		(start 407.302208 -80.899)
		(end 409.194 -80.899)
		(width 0.089408)
		(layer "In2.Cu")
		(net "IRQ_OOB_MGMT_RISER_ALERT_N")
	)
	(segment
		(start 480.791266 -17.143476)
		(end 479.18497 -15.53718)
		(width 0.089408)
		(layer "In2.Cu")
		(net "IRQ_OOB_MGMT_RISER_ALERT_N")
	)
	(segment
		(start 493.14608 -37.84092)
		(end 493.98428 -37.00272)
		(width 0.089408)
		(layer "In2.Cu")
		(net "IRQ_OOB_MGMT_RISER_ALERT_N")
	)
	(segment
		(start 409.829 -81.534)
		(end 409.829 -87.4776)
		(width 0.089408)
		(layer "In2.Cu")
		(net "IRQ_OOB_MGMT_RISER_ALERT_N")
	)
	(segment
		(start 492.83112 -28.176474)
		(end 492.830866 -28.17622)
		(width 0.089408)
		(layer "In2.Cu")
		(net "IRQ_OOB_MGMT_RISER_ALERT_N")
	)
	(segment
		(start 472.679268 -43.771312)
		(end 473.742512 -43.771312)
		(width 0.089408)
		(layer "In2.Cu")
		(net "IRQ_OOB_MGMT_RISER_ALERT_N")
	)
	(segment
		(start 488.418632 -45.712888)
		(end 492.469678 -45.712888)
		(width 0.089408)
		(layer "In2.Cu")
		(net "IRQ_OOB_MGMT_RISER_ALERT_N")
	)
	(segment
		(start 485.736646 -17.143476)
		(end 480.791266 -17.143476)
		(width 0.089408)
		(layer "In2.Cu")
		(net "IRQ_OOB_MGMT_RISER_ALERT_N")
	)
	(segment
		(start 494.945924 -35.553142)
		(end 495.131852 -35.367214)
		(width 0.089408)
		(layer "In2.Cu")
		(net "IRQ_OOB_MGMT_RISER_ALERT_N")
	)
	(segment
		(start 410.411422 -70.99173)
		(end 405.78024 -75.622912)
		(width 0.089408)
		(layer "In2.Cu")
		(net "IRQ_OOB_MGMT_RISER_ALERT_N")
	)
	(segment
		(start 406.279604 -78.643988)
		(end 406.279604 -79.876396)
		(width 0.089408)
		(layer "In2.Cu")
		(net "IRQ_OOB_MGMT_RISER_ALERT_N")
	)
	(segment
		(start 411.607 -103.4034)
		(end 411.607 -104.520746)
		(width 0.089408)
		(layer "In2.Cu")
		(net "IRQ_OOB_MGMT_RISER_ALERT_N")
	)
	(segment
		(start 474.216476 -4.475988)
		(end 469.831928 -4.475988)
		(width 0.089408)
		(layer "In2.Cu")
		(net "IRQ_OOB_MGMT_RISER_ALERT_N")
	)
	(segment
		(start 409.829 -87.4776)
		(end 410.758894 -88.407494)
		(width 0.089408)
		(layer "In2.Cu")
		(net "IRQ_OOB_MGMT_RISER_ALERT_N")
	)
	(segment
		(start 493.014 -45.168566)
		(end 493.014 -44.357544)
		(width 0.089408)
		(layer "In2.Cu")
		(net "IRQ_OOB_MGMT_RISER_ALERT_N")
	)
	(segment
		(start 406.279604 -79.876396)
		(end 407.302208 -80.899)
		(width 0.089408)
		(layer "In2.Cu")
		(net "IRQ_OOB_MGMT_RISER_ALERT_N")
	)
	(segment
		(start 493.014 -44.357544)
		(end 493.324642 -44.046902)
		(width 0.089408)
		(layer "In2.Cu")
		(net "IRQ_OOB_MGMT_RISER_ALERT_N")
	)
	(segment
		(start 411.594808 -103.391208)
		(end 411.607 -103.4034)
		(width 0.089408)
		(layer "In2.Cu")
		(net "IRQ_OOB_MGMT_RISER_ALERT_N")
	)
	(segment
		(start 479.18497 -15.53718)
		(end 479.18497 -9.795764)
		(width 0.089408)
		(layer "In2.Cu")
		(net "IRQ_OOB_MGMT_RISER_ALERT_N")
	)
	(segment
		(start 495.131852 -35.367214)
		(end 495.131852 -34.764726)
		(width 0.089408)
		(layer "In2.Cu")
		(net "IRQ_OOB_MGMT_RISER_ALERT_N")
	)
	(segment
		(start 410.845 -102.599744)
		(end 411.594808 -103.349552)
		(width 0.089408)
		(layer "In2.Cu")
		(net "IRQ_OOB_MGMT_RISER_ALERT_N")
	)
	(segment
		(start 492.5568 -28.676346)
		(end 492.830866 -28.40228)
		(width 0.089408)
		(layer "In2.Cu")
		(net "IRQ_OOB_MGMT_RISER_ALERT_N")
	)
	(segment
		(start 411.988 -70.99173)
		(end 410.411422 -70.99173)
		(width 0.089408)
		(layer "In2.Cu")
		(net "IRQ_OOB_MGMT_RISER_ALERT_N")
	)
	(segment
		(start 493.324642 -39.03472)
		(end 493.14608 -38.856158)
		(width 0.089408)
		(layer "In2.Cu")
		(net "IRQ_OOB_MGMT_RISER_ALERT_N")
	)
	(segment
		(start 410.758894 -88.407494)
		(end 410.758894 -97.69983)
		(width 0.089408)
		(layer "In2.Cu")
		(net "IRQ_OOB_MGMT_RISER_ALERT_N")
	)
	(segment
		(start 492.5568 -32.189674)
		(end 492.5568 -28.676346)
		(width 0.089408)
		(layer "In2.Cu")
		(net "IRQ_OOB_MGMT_RISER_ALERT_N")
	)
	(segment
		(start 405.78024 -78.144624)
		(end 406.279604 -78.643988)
		(width 0.089408)
		(layer "In2.Cu")
		(net "IRQ_OOB_MGMT_RISER_ALERT_N")
	)
	(segment
		(start 494.321846 -37.00272)
		(end 494.945924 -36.378642)
		(width 0.089408)
		(layer "In2.Cu")
		(net "IRQ_OOB_MGMT_RISER_ALERT_N")
	)
	(segment
		(start 492.830866 -28.334716)
		(end 492.83112 -28.334462)
		(width 0.089408)
		(layer "In2.Cu")
		(net "IRQ_OOB_MGMT_RISER_ALERT_N")
	)
	(segment
		(start 410.845 -97.785936)
		(end 410.845 -102.599744)
		(width 0.089408)
		(layer "In2.Cu")
		(net "IRQ_OOB_MGMT_RISER_ALERT_N")
	)
	(segment
		(start 411.607 -104.520746)
		(end 410.860494 -105.267252)
		(width 0.089408)
		(layer "In2.Cu")
		(net "IRQ_OOB_MGMT_RISER_ALERT_N")
	)
	(segment
		(start 494.945924 -36.378642)
		(end 494.945924 -35.553142)
		(width 0.089408)
		(layer "In2.Cu")
		(net "IRQ_OOB_MGMT_RISER_ALERT_N")
	)
	(segment
		(start 470.65438 -43.643804)
		(end 472.55176 -43.643804)
		(width 0.089408)
		(layer "In2.Cu")
		(net "IRQ_OOB_MGMT_RISER_ALERT_N")
	)
	(segment
		(start 479.33229 -41.817036)
		(end 480.593654 -43.0784)
		(width 0.089408)
		(layer "In2.Cu")
		(net "IRQ_OOB_MGMT_RISER_ALERT_N")
	)
	(segment
		(start 469.989154 -44.30903)
		(end 470.65438 -43.643804)
		(width 0.089408)
		(layer "In2.Cu")
		(net "IRQ_OOB_MGMT_RISER_ALERT_N")
	)
	(segment
		(start 493.14608 -38.856158)
		(end 493.14608 -37.84092)
		(width 0.089408)
		(layer "In2.Cu")
		(net "IRQ_OOB_MGMT_RISER_ALERT_N")
	)
	(segment
		(start 466.44433 -44.30903)
		(end 469.989154 -44.30903)
		(width 0.089408)
		(layer "In2.Cu")
		(net "IRQ_OOB_MGMT_RISER_ALERT_N")
	)
	(segment
		(start 411.7848 -113.036604)
		(end 411.791404 -113.036604)
		(width 0.089408)
		(layer "In2.Cu")
		(net "IRQ_OOB_MGMT_RISER_ALERT_N")
	)
	(segment
		(start 492.830866 -24.237696)
		(end 485.736646 -17.143476)
		(width 0.089408)
		(layer "In2.Cu")
		(net "IRQ_OOB_MGMT_RISER_ALERT_N")
	)
	(segment
		(start 472.55176 -43.643804)
		(end 472.679268 -43.771312)
		(width 0.089408)
		(layer "In2.Cu")
		(net "IRQ_OOB_MGMT_RISER_ALERT_N")
	)
	(segment
		(start 465.741766 -43.384978)
		(end 465.741766 -43.606466)
		(width 0.089408)
		(layer "In2.Cu")
		(net "IRQ_OOB_MGMT_RISER_ALERT_N")
	)
	(segment
		(start 409.346908 -71.12)
		(end 408.807412 -71.659496)
		(width 0.089408)
		(layer "In4.Cu")
		(net "IRQ_OOB_MGMT_RISER_ALERT_N")
	)
	(segment
		(start 399.897092 -72.360028)
		(end 399.745962 -72.360028)
		(width 0.089408)
		(layer "In4.Cu")
		(net "IRQ_OOB_MGMT_RISER_ALERT_N")
	)
	(segment
		(start 399.745962 -72.360028)
		(end 399.74266 -72.36333)
		(width 0.089408)
		(layer "In4.Cu")
		(net "IRQ_OOB_MGMT_RISER_ALERT_N")
	)
	(segment
		(start 411.988 -70.99173)
		(end 411.85973 -71.12)
		(width 0.089408)
		(layer "In4.Cu")
		(net "IRQ_OOB_MGMT_RISER_ALERT_N")
	)
	(segment
		(start 400.58848 -71.66864)
		(end 399.897092 -72.360028)
		(width 0.089408)
		(layer "In4.Cu")
		(net "IRQ_OOB_MGMT_RISER_ALERT_N")
	)
	(segment
		(start 411.85973 -71.12)
		(end 409.346908 -71.12)
		(width 0.089408)
		(layer "In4.Cu")
		(net "IRQ_OOB_MGMT_RISER_ALERT_N")
	)
	(segment
		(start 406.504648 -71.659496)
		(end 406.080976 -72.083168)
		(width 0.089408)
		(layer "In4.Cu")
		(net "IRQ_OOB_MGMT_RISER_ALERT_N")
	)
	(segment
		(start 402.07438 -72.083168)
		(end 401.928838 -71.937626)
		(width 0.089408)
		(layer "In4.Cu")
		(net "IRQ_OOB_MGMT_RISER_ALERT_N")
	)
	(segment
		(start 401.928838 -71.937626)
		(end 401.921472 -71.937626)
		(width 0.089408)
		(layer "In4.Cu")
		(net "IRQ_OOB_MGMT_RISER_ALERT_N")
	)
	(segment
		(start 406.080976 -72.083168)
		(end 402.07438 -72.083168)
		(width 0.089408)
		(layer "In4.Cu")
		(net "IRQ_OOB_MGMT_RISER_ALERT_N")
	)
	(segment
		(start 408.807412 -71.659496)
		(end 406.504648 -71.659496)
		(width 0.089408)
		(layer "In4.Cu")
		(net "IRQ_OOB_MGMT_RISER_ALERT_N")
	)
	(segment
		(start 401.652486 -71.66864)
		(end 400.58848 -71.66864)
		(width 0.089408)
		(layer "In4.Cu")
		(net "IRQ_OOB_MGMT_RISER_ALERT_N")
	)
	(segment
		(start 401.921472 -71.937626)
		(end 401.652486 -71.66864)
		(width 0.089408)
		(layer "In4.Cu")
		(net "IRQ_OOB_MGMT_RISER_ALERT_N")
	)
	(segment
		(start 408.71521 -41.179242)
		(end 408.934666 -40.959786)
		(width 0.089408)
		(layer "In9.Cu")
		(net "IRQ_OOB_MGMT_RISER_ALERT_N")
	)
	(segment
		(start 403.916896 -46.018704)
		(end 404.08606 -45.84954)
		(width 0.0889)
		(layer "In9.Cu")
		(net "IRQ_OOB_MGMT_RISER_ALERT_N")
	)
	(segment
		(start 401.45208 -50.127408)
		(end 401.490942 -50.088546)
		(width 0.089408)
		(layer "In9.Cu")
		(net "IRQ_OOB_MGMT_RISER_ALERT_N")
	)
	(segment
		(start 402.514054 -65.12687)
		(end 402.514054 -63.743586)
		(width 0.089408)
		(layer "In9.Cu")
		(net "IRQ_OOB_MGMT_RISER_ALERT_N")
	)
	(segment
		(start 409.749498 -40.109648)
		(end 410.045662 -40.109648)
		(width 0.089408)
		(layer "In9.Cu")
		(net "IRQ_OOB_MGMT_RISER_ALERT_N")
	)
	(segment
		(start 402.514054 -63.743586)
		(end 403.119844 -63.137034)
		(width 0.089408)
		(layer "In9.Cu")
		(net "IRQ_OOB_MGMT_RISER_ALERT_N")
	)
	(segment
		(start 401.490942 -50.088546)
		(end 401.490942 -48.444658)
		(width 0.089408)
		(layer "In9.Cu")
		(net "IRQ_OOB_MGMT_RISER_ALERT_N")
	)
	(segment
		(start 408.664918 -41.490138)
		(end 408.664918 -41.489884)
		(width 0.089408)
		(layer "In9.Cu")
		(net "IRQ_OOB_MGMT_RISER_ALERT_N")
	)
	(segment
		(start 408.664918 -41.489884)
		(end 408.691334 -41.463468)
		(width 0.089408)
		(layer "In9.Cu")
		(net "IRQ_OOB_MGMT_RISER_ALERT_N")
	)
	(segment
		(start 405.070056 -44.32046)
		(end 406.698704 -44.32046)
		(width 0.089408)
		(layer "In9.Cu")
		(net "IRQ_OOB_MGMT_RISER_ALERT_N")
	)
	(segment
		(start 404.08606 -45.304456)
		(end 405.070056 -44.32046)
		(width 0.089408)
		(layer "In9.Cu")
		(net "IRQ_OOB_MGMT_RISER_ALERT_N")
	)
	(segment
		(start 409.245308 -40.909494)
		(end 409.245562 -40.909494)
		(width 0.089408)
		(layer "In9.Cu")
		(net "IRQ_OOB_MGMT_RISER_ALERT_N")
	)
	(segment
		(start 401.451826 -55.903622)
		(end 401.45208 -55.903368)
		(width 0.089408)
		(layer "In9.Cu")
		(net "IRQ_OOB_MGMT_RISER_ALERT_N")
	)
	(segment
		(start 402.527516 -65.48755)
		(end 402.519642 -65.479676)
		(width 0.089408)
		(layer "In9.Cu")
		(net "IRQ_OOB_MGMT_RISER_ALERT_N")
	)
	(segment
		(start 401.451826 -56.06161)
		(end 401.451826 -55.903622)
		(width 0.089408)
		(layer "In9.Cu")
		(net "IRQ_OOB_MGMT_RISER_ALERT_N")
	)
	(segment
		(start 406.698704 -44.32046)
		(end 407.255726 -43.763438)
		(width 0.089408)
		(layer "In9.Cu")
		(net "IRQ_OOB_MGMT_RISER_ALERT_N")
	)
	(segment
		(start 401.490942 -48.444658)
		(end 403.916896 -46.018704)
		(width 0.089408)
		(layer "In9.Cu")
		(net "IRQ_OOB_MGMT_RISER_ALERT_N")
	)
	(segment
		(start 408.934666 -40.959786)
		(end 409.195016 -40.959786)
		(width 0.089408)
		(layer "In9.Cu")
		(net "IRQ_OOB_MGMT_RISER_ALERT_N")
	)
	(segment
		(start 402.519642 -65.479676)
		(end 402.519642 -65.132458)
		(width 0.089408)
		(layer "In9.Cu")
		(net "IRQ_OOB_MGMT_RISER_ALERT_N")
	)
	(segment
		(start 402.514054 -67.299078)
		(end 402.514054 -66.26098)
		(width 0.089408)
		(layer "In9.Cu")
		(net "IRQ_OOB_MGMT_RISER_ALERT_N")
	)
	(segment
		(start 409.245562 -40.909494)
		(end 409.465018 -40.690038)
		(width 0.089408)
		(layer "In9.Cu")
		(net "IRQ_OOB_MGMT_RISER_ALERT_N")
	)
	(segment
		(start 402.514054 -66.26098)
		(end 402.527516 -66.247518)
		(width 0.089408)
		(layer "In9.Cu")
		(net "IRQ_OOB_MGMT_RISER_ALERT_N")
	)
	(segment
		(start 409.465018 -40.394128)
		(end 409.749498 -40.109648)
		(width 0.089408)
		(layer "In9.Cu")
		(net "IRQ_OOB_MGMT_RISER_ALERT_N")
	)
	(segment
		(start 403.119844 -57.729628)
		(end 401.451826 -56.06161)
		(width 0.089408)
		(layer "In9.Cu")
		(net "IRQ_OOB_MGMT_RISER_ALERT_N")
	)
	(segment
		(start 409.465018 -40.690038)
		(end 409.465018 -40.394128)
		(width 0.089408)
		(layer "In9.Cu")
		(net "IRQ_OOB_MGMT_RISER_ALERT_N")
	)
	(segment
		(start 403.119844 -63.137034)
		(end 403.119844 -57.729628)
		(width 0.089408)
		(layer "In9.Cu")
		(net "IRQ_OOB_MGMT_RISER_ALERT_N")
	)
	(segment
		(start 402.519642 -65.132458)
		(end 402.514054 -65.12687)
		(width 0.089408)
		(layer "In9.Cu")
		(net "IRQ_OOB_MGMT_RISER_ALERT_N")
	)
	(segment
		(start 407.255726 -42.899076)
		(end 408.445208 -41.709594)
		(width 0.089408)
		(layer "In9.Cu")
		(net "IRQ_OOB_MGMT_RISER_ALERT_N")
	)
	(segment
		(start 408.71521 -41.17975)
		(end 408.71521 -41.179242)
		(width 0.089408)
		(layer "In9.Cu")
		(net "IRQ_OOB_MGMT_RISER_ALERT_N")
	)
	(segment
		(start 399.74266 -70.070472)
		(end 402.514054 -67.299078)
		(width 0.089408)
		(layer "In9.Cu")
		(net "IRQ_OOB_MGMT_RISER_ALERT_N")
	)
	(segment
		(start 410.045662 -40.109648)
		(end 410.265118 -39.890192)
		(width 0.089408)
		(layer "In9.Cu")
		(net "IRQ_OOB_MGMT_RISER_ALERT_N")
	)
	(segment
		(start 409.195016 -40.959786)
		(end 409.245308 -40.909494)
		(width 0.089408)
		(layer "In9.Cu")
		(net "IRQ_OOB_MGMT_RISER_ALERT_N")
	)
	(segment
		(start 410.2862 -39.868856)
		(end 410.2862 -38.530784)
		(width 0.089408)
		(layer "In9.Cu")
		(net "IRQ_OOB_MGMT_RISER_ALERT_N")
	)
	(segment
		(start 408.445462 -41.709594)
		(end 408.664918 -41.490138)
		(width 0.089408)
		(layer "In9.Cu")
		(net "IRQ_OOB_MGMT_RISER_ALERT_N")
	)
	(segment
		(start 410.2862 -38.530784)
		(end 409.890214 -38.134798)
		(width 0.089408)
		(layer "In9.Cu")
		(net "IRQ_OOB_MGMT_RISER_ALERT_N")
	)
	(segment
		(start 399.74266 -72.36333)
		(end 399.74266 -70.070472)
		(width 0.089408)
		(layer "In9.Cu")
		(net "IRQ_OOB_MGMT_RISER_ALERT_N")
	)
	(segment
		(start 410.265118 -39.889938)
		(end 410.2862 -39.868856)
		(width 0.089408)
		(layer "In9.Cu")
		(net "IRQ_OOB_MGMT_RISER_ALERT_N")
	)
	(segment
		(start 401.45208 -55.903368)
		(end 401.45208 -50.127408)
		(width 0.089408)
		(layer "In9.Cu")
		(net "IRQ_OOB_MGMT_RISER_ALERT_N")
	)
	(segment
		(start 410.265118 -39.890192)
		(end 410.265118 -39.889938)
		(width 0.089408)
		(layer "In9.Cu")
		(net "IRQ_OOB_MGMT_RISER_ALERT_N")
	)
	(segment
		(start 404.08606 -45.84954)
		(end 404.08606 -45.304456)
		(width 0.089408)
		(layer "In9.Cu")
		(net "IRQ_OOB_MGMT_RISER_ALERT_N")
	)
	(segment
		(start 408.445208 -41.709594)
		(end 408.445462 -41.709594)
		(width 0.089408)
		(layer "In9.Cu")
		(net "IRQ_OOB_MGMT_RISER_ALERT_N")
	)
	(segment
		(start 408.691334 -41.463468)
		(end 408.691334 -41.203626)
		(width 0.089408)
		(layer "In9.Cu")
		(net "IRQ_OOB_MGMT_RISER_ALERT_N")
	)
	(segment
		(start 408.691334 -41.203626)
		(end 408.71521 -41.17975)
		(width 0.089408)
		(layer "In9.Cu")
		(net "IRQ_OOB_MGMT_RISER_ALERT_N")
	)
	(segment
		(start 402.527516 -66.247518)
		(end 402.527516 -65.48755)
		(width 0.089408)
		(layer "In9.Cu")
		(net "IRQ_OOB_MGMT_RISER_ALERT_N")
	)
	(segment
		(start 407.255726 -43.763438)
		(end 407.255726 -42.899076)
		(width 0.089408)
		(layer "In9.Cu")
		(net "IRQ_OOB_MGMT_RISER_ALERT_N")
	)
	(segment
		(start 462.610454 -39.106094)
		(end 462.27873 -39.106094)
		(width 0.089408)
		(layer "In11.Cu")
		(net "IRQ_OOB_MGMT_RISER_ALERT_N")
	)
	(segment
		(start 435.242716 -41.19499)
		(end 434.210714 -40.162988)
		(width 0.089408)
		(layer "In11.Cu")
		(net "IRQ_OOB_MGMT_RISER_ALERT_N")
	)
	(segment
		(start 462.276952 -39.107872)
		(end 461.520032 -39.107872)
		(width 0.089408)
		(layer "In11.Cu")
		(net "IRQ_OOB_MGMT_RISER_ALERT_N")
	)
	(segment
		(start 447.247264 -40.767254)
		(end 444.872618 -40.767254)
		(width 0.089408)
		(layer "In11.Cu")
		(net "IRQ_OOB_MGMT_RISER_ALERT_N")
	)
	(segment
		(start 462.27873 -39.106094)
		(end 462.276952 -39.107872)
		(width 0.089408)
		(layer "In11.Cu")
		(net "IRQ_OOB_MGMT_RISER_ALERT_N")
	)
	(segment
		(start 463.78876 -42.397426)
		(end 463.78876 -40.154352)
		(width 0.089408)
		(layer "In11.Cu")
		(net "IRQ_OOB_MGMT_RISER_ALERT_N")
	)
	(segment
		(start 461.518254 -39.106094)
		(end 461.18653 -39.106094)
		(width 0.089408)
		(layer "In11.Cu")
		(net "IRQ_OOB_MGMT_RISER_ALERT_N")
	)
	(segment
		(start 424.718226 -40.162988)
		(end 423.874692 -39.319454)
		(width 0.089408)
		(layer "In11.Cu")
		(net "IRQ_OOB_MGMT_RISER_ALERT_N")
	)
	(segment
		(start 444.444882 -41.19499)
		(end 435.242716 -41.19499)
		(width 0.089408)
		(layer "In11.Cu")
		(net "IRQ_OOB_MGMT_RISER_ALERT_N")
	)
	(segment
		(start 459.10373 -39.107872)
		(end 458.445616 -39.765986)
		(width 0.089408)
		(layer "In11.Cu")
		(net "IRQ_OOB_MGMT_RISER_ALERT_N")
	)
	(segment
		(start 458.445616 -39.765986)
		(end 456.1078 -39.765986)
		(width 0.089408)
		(layer "In11.Cu")
		(net "IRQ_OOB_MGMT_RISER_ALERT_N")
	)
	(segment
		(start 464.776312 -43.384978)
		(end 463.78876 -42.397426)
		(width 0.089408)
		(layer "In11.Cu")
		(net "IRQ_OOB_MGMT_RISER_ALERT_N")
	)
	(segment
		(start 449.576444 -38.438074)
		(end 447.247264 -40.767254)
		(width 0.089408)
		(layer "In11.Cu")
		(net "IRQ_OOB_MGMT_RISER_ALERT_N")
	)
	(segment
		(start 423.874692 -39.319454)
		(end 411.340046 -39.319454)
		(width 0.089408)
		(layer "In11.Cu")
		(net "IRQ_OOB_MGMT_RISER_ALERT_N")
	)
	(segment
		(start 411.340046 -39.319454)
		(end 411.095444 -39.074852)
		(width 0.089408)
		(layer "In11.Cu")
		(net "IRQ_OOB_MGMT_RISER_ALERT_N")
	)
	(segment
		(start 465.741766 -43.384978)
		(end 464.776312 -43.384978)
		(width 0.089408)
		(layer "In11.Cu")
		(net "IRQ_OOB_MGMT_RISER_ALERT_N")
	)
	(segment
		(start 461.184752 -39.107872)
		(end 459.10373 -39.107872)
		(width 0.089408)
		(layer "In11.Cu")
		(net "IRQ_OOB_MGMT_RISER_ALERT_N")
	)
	(segment
		(start 461.520032 -39.107872)
		(end 461.518254 -39.106094)
		(width 0.089408)
		(layer "In11.Cu")
		(net "IRQ_OOB_MGMT_RISER_ALERT_N")
	)
	(segment
		(start 462.612232 -39.107872)
		(end 462.610454 -39.106094)
		(width 0.089408)
		(layer "In11.Cu")
		(net "IRQ_OOB_MGMT_RISER_ALERT_N")
	)
	(segment
		(start 462.74228 -39.107872)
		(end 462.612232 -39.107872)
		(width 0.089408)
		(layer "In11.Cu")
		(net "IRQ_OOB_MGMT_RISER_ALERT_N")
	)
	(segment
		(start 454.779888 -38.438074)
		(end 449.576444 -38.438074)
		(width 0.089408)
		(layer "In11.Cu")
		(net "IRQ_OOB_MGMT_RISER_ALERT_N")
	)
	(segment
		(start 411.095444 -39.074852)
		(end 411.095444 -38.752272)
		(width 0.089408)
		(layer "In11.Cu")
		(net "IRQ_OOB_MGMT_RISER_ALERT_N")
	)
	(segment
		(start 461.18653 -39.106094)
		(end 461.184752 -39.107872)
		(width 0.089408)
		(layer "In11.Cu")
		(net "IRQ_OOB_MGMT_RISER_ALERT_N")
	)
	(segment
		(start 410.868622 -38.52545)
		(end 410.530802 -38.52545)
		(width 0.089408)
		(layer "In11.Cu")
		(net "IRQ_OOB_MGMT_RISER_ALERT_N")
	)
	(segment
		(start 410.14015 -38.134798)
		(end 409.890214 -38.134798)
		(width 0.089408)
		(layer "In11.Cu")
		(net "IRQ_OOB_MGMT_RISER_ALERT_N")
	)
	(segment
		(start 456.1078 -39.765986)
		(end 454.779888 -38.438074)
		(width 0.089408)
		(layer "In11.Cu")
		(net "IRQ_OOB_MGMT_RISER_ALERT_N")
	)
	(segment
		(start 410.530802 -38.52545)
		(end 410.14015 -38.134798)
		(width 0.089408)
		(layer "In11.Cu")
		(net "IRQ_OOB_MGMT_RISER_ALERT_N")
	)
	(segment
		(start 434.210714 -40.162988)
		(end 424.718226 -40.162988)
		(width 0.089408)
		(layer "In11.Cu")
		(net "IRQ_OOB_MGMT_RISER_ALERT_N")
	)
	(segment
		(start 444.872618 -40.767254)
		(end 444.444882 -41.19499)
		(width 0.089408)
		(layer "In11.Cu")
		(net "IRQ_OOB_MGMT_RISER_ALERT_N")
	)
	(segment
		(start 463.78876 -40.154352)
		(end 462.74228 -39.107872)
		(width 0.089408)
		(layer "In11.Cu")
		(net "IRQ_OOB_MGMT_RISER_ALERT_N")
	)
	(segment
		(start 411.095444 -38.752272)
		(end 410.868622 -38.52545)
		(width 0.089408)
		(layer "In11.Cu")
		(net "IRQ_OOB_MGMT_RISER_ALERT_N")
	)
	(segment
		(start 368.745262 -79.094838)
		(end 369.145058 -78.695042)
		(width 0.10795)
		(layer "F.Cu")
		(net "TP_CPLD1_PB25B_SI_SISPI")
	)
	(via
		(at 368.745262 -79.094838)
		(size 0.4572)
		(drill 0.2032)
		(layers "F.Cu" "B.Cu")
		(net "TP_CPLD1_PB25B_SI_SISPI")
	)
	(segment
		(start 481.0125 -31.6103)
		(end 481.966778 -31.6103)
		(width 0.10795)
		(layer "F.Cu")
		(net "CLK_25M_CPLD_R")
	)
	(via
		(at 481.966778 -31.6103)
		(size 0.508)
		(drill 0.254)
		(layers "F.Cu" "B.Cu")
		(net "CLK_25M_CPLD_R")
	)
	(segment
		(start 481.965 -31.612078)
		(end 481.966778 -31.6103)
		(width 0.10795)
		(layer "B.Cu")
		(net "CLK_25M_CPLD_R")
	)
	(segment
		(start 481.965 -32.512)
		(end 481.965 -31.612078)
		(width 0.10795)
		(layer "B.Cu")
		(net "CLK_25M_CPLD_R")
	)
	(segment
		(start 378.344684 -76.694792)
		(end 377.944888 -76.294996)
		(width 0.1016)
		(layer "F.Cu")
		(net "CLK_25M_CPLD")
	)
	(via
		(at 481.34524 -34.569146)
		(size 0.508)
		(drill 0.254)
		(layers "F.Cu" "B.Cu")
		(net "CLK_25M_CPLD")
	)
	(via
		(at 382.905 -76.353924)
		(size 0.6604)
		(drill 0.3302)
		(layers "F.Cu" "B.Cu")
		(net "CLK_25M_CPLD")
	)
	(via
		(at 473.685616 -29.14269)
		(size 0.508)
		(drill 0.254)
		(layers "F.Cu" "B.Cu")
		(net "CLK_25M_CPLD")
	)
	(via
		(at 378.344684 -76.694792)
		(size 0.4572)
		(drill 0.2032)
		(layers "F.Cu" "B.Cu")
		(net "CLK_25M_CPLD")
	)
	(via
		(at 387.8326 -74.387964)
		(size 0.508)
		(drill 0.254)
		(layers "F.Cu" "B.Cu")
		(net "CLK_25M_CPLD")
	)
	(segment
		(start 382.905 -76.353924)
		(end 385.86664 -76.353924)
		(width 0.10795)
		(layer "B.Cu")
		(net "CLK_25M_CPLD")
	)
	(segment
		(start 481.424488 -34.569146)
		(end 481.965 -34.028634)
		(width 0.10795)
		(layer "B.Cu")
		(net "CLK_25M_CPLD")
	)
	(segment
		(start 381.567182 -76.353924)
		(end 380.531624 -77.389482)
		(width 0.10795)
		(layer "B.Cu")
		(net "CLK_25M_CPLD")
	)
	(segment
		(start 380.531624 -77.389482)
		(end 380.202948 -77.389482)
		(width 0.10795)
		(layer "B.Cu")
		(net "CLK_25M_CPLD")
	)
	(segment
		(start 379.68809 -76.874624)
		(end 378.524516 -76.874624)
		(width 0.10795)
		(layer "B.Cu")
		(net "CLK_25M_CPLD")
	)
	(segment
		(start 481.965 -34.028634)
		(end 481.965 -33.401)
		(width 0.10795)
		(layer "B.Cu")
		(net "CLK_25M_CPLD")
	)
	(segment
		(start 378.524516 -76.874624)
		(end 378.344684 -76.694792)
		(width 0.10795)
		(layer "B.Cu")
		(net "CLK_25M_CPLD")
	)
	(segment
		(start 380.202948 -77.389482)
		(end 379.68809 -76.874624)
		(width 0.10795)
		(layer "B.Cu")
		(net "CLK_25M_CPLD")
	)
	(segment
		(start 382.905 -76.353924)
		(end 381.567182 -76.353924)
		(width 0.10795)
		(layer "B.Cu")
		(net "CLK_25M_CPLD")
	)
	(segment
		(start 385.86664 -76.353924)
		(end 387.8326 -74.387964)
		(width 0.10795)
		(layer "B.Cu")
		(net "CLK_25M_CPLD")
	)
	(segment
		(start 481.34524 -34.569146)
		(end 481.424488 -34.569146)
		(width 0.10795)
		(layer "B.Cu")
		(net "CLK_25M_CPLD")
	)
	(segment
		(start 407.516584 -31.024068)
		(end 407.516584 -33.386776)
		(width 0.089408)
		(layer "In2.Cu")
		(net "CLK_25M_CPLD")
	)
	(segment
		(start 387.372352 -73.927716)
		(end 387.8326 -74.387964)
		(width 0.089408)
		(layer "In2.Cu")
		(net "CLK_25M_CPLD")
	)
	(segment
		(start 455.51598 -24.381968)
		(end 450.32295 -24.381968)
		(width 0.089408)
		(layer "In2.Cu")
		(net "CLK_25M_CPLD")
	)
	(segment
		(start 419.594792 -28.960064)
		(end 415.828226 -28.960064)
		(width 0.089408)
		(layer "In2.Cu")
		(net "CLK_25M_CPLD")
	)
	(segment
		(start 394.537692 -38.087808)
		(end 394.274548 -38.087808)
		(width 0.089408)
		(layer "In2.Cu")
		(net "CLK_25M_CPLD")
	)
	(segment
		(start 387.84657 -43.775376)
		(end 387.84657 -56.70677)
		(width 0.089408)
		(layer "In2.Cu")
		(net "CLK_25M_CPLD")
	)
	(segment
		(start 415.02838 -29.75991)
		(end 411.590744 -29.75991)
		(width 0.089408)
		(layer "In2.Cu")
		(net "CLK_25M_CPLD")
	)
	(segment
		(start 387.899656 -65.109344)
		(end 387.518656 -65.490344)
		(width 0.089408)
		(layer "In2.Cu")
		(net "CLK_25M_CPLD")
	)
	(segment
		(start 460.029306 -30.413706)
		(end 458.826108 -29.210508)
		(width 0.089408)
		(layer "In2.Cu")
		(net "CLK_25M_CPLD")
	)
	(segment
		(start 419.864794 -27.58059)
		(end 419.864794 -28.690062)
		(width 0.089408)
		(layer "In2.Cu")
		(net "CLK_25M_CPLD")
	)
	(segment
		(start 447.860928 -22.356826)
		(end 445.490346 -22.356826)
		(width 0.089408)
		(layer "In2.Cu")
		(net "CLK_25M_CPLD")
	)
	(segment
		(start 389.104886 -59.74461)
		(end 389.104632 -59.744864)
		(width 0.089408)
		(layer "In2.Cu")
		(net "CLK_25M_CPLD")
	)
	(segment
		(start 390.103614 -61.473588)
		(end 390.103614 -63.324994)
		(width 0.089408)
		(layer "In2.Cu")
		(net "CLK_25M_CPLD")
	)
	(segment
		(start 397.310864 -38.088062)
		(end 394.537946 -38.088062)
		(width 0.089408)
		(layer "In2.Cu")
		(net "CLK_25M_CPLD")
	)
	(segment
		(start 433.433728 -22.472142)
		(end 432.484784 -22.472142)
		(width 0.089408)
		(layer "In2.Cu")
		(net "CLK_25M_CPLD")
	)
	(segment
		(start 473.685616 -29.14269)
		(end 473.685616 -29.298138)
		(width 0.089408)
		(layer "In2.Cu")
		(net "CLK_25M_CPLD")
	)
	(segment
		(start 411.06471 -30.290262)
		(end 410.845508 -30.509464)
		(width 0.089408)
		(layer "In2.Cu")
		(net "CLK_25M_CPLD")
	)
	(segment
		(start 394.274548 -38.087808)
		(end 391.61974 -40.742616)
		(width 0.089408)
		(layer "In2.Cu")
		(net "CLK_25M_CPLD")
	)
	(segment
		(start 425.821856 -24.468074)
		(end 424.66768 -24.468074)
		(width 0.089408)
		(layer "In2.Cu")
		(net "CLK_25M_CPLD")
	)
	(segment
		(start 388.285228 -43.336718)
		(end 387.84657 -43.775376)
		(width 0.089408)
		(layer "In2.Cu")
		(net "CLK_25M_CPLD")
	)
	(segment
		(start 387.84657 -56.70677)
		(end 389.104886 -57.965086)
		(width 0.089408)
		(layer "In2.Cu")
		(net "CLK_25M_CPLD")
	)
	(segment
		(start 458.826108 -27.692096)
		(end 455.51598 -24.381968)
		(width 0.089408)
		(layer "In2.Cu")
		(net "CLK_25M_CPLD")
	)
	(segment
		(start 415.828226 -28.960064)
		(end 415.02838 -29.75991)
		(width 0.089408)
		(layer "In2.Cu")
		(net "CLK_25M_CPLD")
	)
	(segment
		(start 419.864794 -28.690062)
		(end 419.594792 -28.960064)
		(width 0.089408)
		(layer "In2.Cu")
		(net "CLK_25M_CPLD")
	)
	(segment
		(start 420.465758 -26.979626)
		(end 419.864794 -27.58059)
		(width 0.089408)
		(layer "In2.Cu")
		(net "CLK_25M_CPLD")
	)
	(segment
		(start 426.899832 -23.793958)
		(end 426.495972 -23.793958)
		(width 0.089408)
		(layer "In2.Cu")
		(net "CLK_25M_CPLD")
	)
	(segment
		(start 424.66768 -24.468074)
		(end 422.156128 -26.979626)
		(width 0.089408)
		(layer "In2.Cu")
		(net "CLK_25M_CPLD")
	)
	(segment
		(start 387.518656 -65.490344)
		(end 387.518656 -70.35292)
		(width 0.089408)
		(layer "In2.Cu")
		(net "CLK_25M_CPLD")
	)
	(segment
		(start 387.372352 -73.081134)
		(end 387.372098 -73.081388)
		(width 0.089408)
		(layer "In2.Cu")
		(net "CLK_25M_CPLD")
	)
	(segment
		(start 461.547972 -30.413706)
		(end 461.145128 -30.413706)
		(width 0.089408)
		(layer "In2.Cu")
		(net "CLK_25M_CPLD")
	)
	(segment
		(start 387.57352 -71.527416)
		(end 387.372352 -71.728584)
		(width 0.089408)
		(layer "In2.Cu")
		(net "CLK_25M_CPLD")
	)
	(segment
		(start 461.145128 -30.413706)
		(end 461.14208 -30.416754)
		(width 0.089408)
		(layer "In2.Cu")
		(net "CLK_25M_CPLD")
	)
	(segment
		(start 458.826108 -29.210508)
		(end 458.826108 -27.692096)
		(width 0.089408)
		(layer "In2.Cu")
		(net "CLK_25M_CPLD")
	)
	(segment
		(start 427.86427 -22.82952)
		(end 426.899832 -23.793958)
		(width 0.089408)
		(layer "In2.Cu")
		(net "CLK_25M_CPLD")
	)
	(segment
		(start 387.518656 -70.35292)
		(end 387.57352 -70.407784)
		(width 0.089408)
		(layer "In2.Cu")
		(net "CLK_25M_CPLD")
	)
	(segment
		(start 411.590744 -29.75991)
		(end 411.06471 -30.285944)
		(width 0.089408)
		(layer "In2.Cu")
		(net "CLK_25M_CPLD")
	)
	(segment
		(start 387.57352 -70.407784)
		(end 387.57352 -71.527416)
		(width 0.089408)
		(layer "In2.Cu")
		(net "CLK_25M_CPLD")
	)
	(segment
		(start 445.490346 -22.356826)
		(end 444.671958 -21.538438)
		(width 0.089408)
		(layer "In2.Cu")
		(net "CLK_25M_CPLD")
	)
	(segment
		(start 404.946358 -35.957002)
		(end 403.30755 -35.957002)
		(width 0.089408)
		(layer "In2.Cu")
		(net "CLK_25M_CPLD")
	)
	(segment
		(start 387.372098 -73.081388)
		(end 387.372098 -73.503028)
		(width 0.089408)
		(layer "In2.Cu")
		(net "CLK_25M_CPLD")
	)
	(segment
		(start 450.32295 -24.381968)
		(end 449.082922 -23.14194)
		(width 0.089408)
		(layer "In2.Cu")
		(net "CLK_25M_CPLD")
	)
	(segment
		(start 460.047086 -30.416754)
		(end 460.044038 -30.413706)
		(width 0.089408)
		(layer "In2.Cu")
		(net "CLK_25M_CPLD")
	)
	(segment
		(start 410.845508 -30.509464)
		(end 410.84119 -30.509464)
		(width 0.089408)
		(layer "In2.Cu")
		(net "CLK_25M_CPLD")
	)
	(segment
		(start 389.104632 -59.744864)
		(end 389.104632 -60.474606)
		(width 0.089408)
		(layer "In2.Cu")
		(net "CLK_25M_CPLD")
	)
	(segment
		(start 410.84119 -30.509464)
		(end 410.790644 -30.56001)
		(width 0.089408)
		(layer "In2.Cu")
		(net "CLK_25M_CPLD")
	)
	(segment
		(start 390.103614 -63.324994)
		(end 388.319264 -65.109344)
		(width 0.089408)
		(layer "In2.Cu")
		(net "CLK_25M_CPLD")
	)
	(segment
		(start 387.372098 -73.503028)
		(end 387.372352 -73.503282)
		(width 0.089408)
		(layer "In2.Cu")
		(net "CLK_25M_CPLD")
	)
	(segment
		(start 387.372352 -71.728584)
		(end 387.372352 -73.081134)
		(width 0.089408)
		(layer "In2.Cu")
		(net "CLK_25M_CPLD")
	)
	(segment
		(start 388.319264 -65.109344)
		(end 387.899656 -65.109344)
		(width 0.089408)
		(layer "In2.Cu")
		(net "CLK_25M_CPLD")
	)
	(segment
		(start 407.980642 -30.56001)
		(end 407.516584 -31.024068)
		(width 0.089408)
		(layer "In2.Cu")
		(net "CLK_25M_CPLD")
	)
	(segment
		(start 387.372352 -73.503282)
		(end 387.372352 -73.927716)
		(width 0.089408)
		(layer "In2.Cu")
		(net "CLK_25M_CPLD")
	)
	(segment
		(start 468.531956 -32.940498)
		(end 464.074764 -32.940498)
		(width 0.089408)
		(layer "In2.Cu")
		(net "CLK_25M_CPLD")
	)
	(segment
		(start 444.671958 -21.538438)
		(end 434.888132 -21.538438)
		(width 0.089408)
		(layer "In2.Cu")
		(net "CLK_25M_CPLD")
	)
	(segment
		(start 472.661234 -30.32252)
		(end 471.149934 -30.32252)
		(width 0.089408)
		(layer "In2.Cu")
		(net "CLK_25M_CPLD")
	)
	(segment
		(start 422.156128 -26.979626)
		(end 420.465758 -26.979626)
		(width 0.089408)
		(layer "In2.Cu")
		(net "CLK_25M_CPLD")
	)
	(segment
		(start 389.104886 -57.965086)
		(end 389.104886 -59.74461)
		(width 0.089408)
		(layer "In2.Cu")
		(net "CLK_25M_CPLD")
	)
	(segment
		(start 449.082922 -23.14194)
		(end 448.646042 -23.14194)
		(width 0.089408)
		(layer "In2.Cu")
		(net "CLK_25M_CPLD")
	)
	(segment
		(start 460.044038 -30.413706)
		(end 460.029306 -30.413706)
		(width 0.089408)
		(layer "In2.Cu")
		(net "CLK_25M_CPLD")
	)
	(segment
		(start 403.30755 -35.957002)
		(end 402.138134 -34.787586)
		(width 0.089408)
		(layer "In2.Cu")
		(net "CLK_25M_CPLD")
	)
	(segment
		(start 411.06471 -30.285944)
		(end 411.06471 -30.290262)
		(width 0.089408)
		(layer "In2.Cu")
		(net "CLK_25M_CPLD")
	)
	(segment
		(start 461.14208 -30.416754)
		(end 460.047086 -30.416754)
		(width 0.089408)
		(layer "In2.Cu")
		(net "CLK_25M_CPLD")
	)
	(segment
		(start 410.790644 -30.56001)
		(end 407.980642 -30.56001)
		(width 0.089408)
		(layer "In2.Cu")
		(net "CLK_25M_CPLD")
	)
	(segment
		(start 471.149934 -30.32252)
		(end 468.531956 -32.940498)
		(width 0.089408)
		(layer "In2.Cu")
		(net "CLK_25M_CPLD")
	)
	(segment
		(start 426.495972 -23.793958)
		(end 425.821856 -24.468074)
		(width 0.089408)
		(layer "In2.Cu")
		(net "CLK_25M_CPLD")
	)
	(segment
		(start 400.61134 -34.787586)
		(end 397.310864 -38.088062)
		(width 0.089408)
		(layer "In2.Cu")
		(net "CLK_25M_CPLD")
	)
	(segment
		(start 433.79898 -22.10689)
		(end 433.433728 -22.472142)
		(width 0.089408)
		(layer "In2.Cu")
		(net "CLK_25M_CPLD")
	)
	(segment
		(start 448.646042 -23.14194)
		(end 447.860928 -22.356826)
		(width 0.089408)
		(layer "In2.Cu")
		(net "CLK_25M_CPLD")
	)
	(segment
		(start 434.31968 -22.10689)
		(end 433.79898 -22.10689)
		(width 0.089408)
		(layer "In2.Cu")
		(net "CLK_25M_CPLD")
	)
	(segment
		(start 389.855202 -43.336718)
		(end 388.285228 -43.336718)
		(width 0.089408)
		(layer "In2.Cu")
		(net "CLK_25M_CPLD")
	)
	(segment
		(start 391.61974 -40.742616)
		(end 391.61974 -41.57218)
		(width 0.089408)
		(layer "In2.Cu")
		(net "CLK_25M_CPLD")
	)
	(segment
		(start 464.074764 -32.940498)
		(end 461.547972 -30.413706)
		(width 0.089408)
		(layer "In2.Cu")
		(net "CLK_25M_CPLD")
	)
	(segment
		(start 407.516584 -33.386776)
		(end 404.946358 -35.957002)
		(width 0.089408)
		(layer "In2.Cu")
		(net "CLK_25M_CPLD")
	)
	(segment
		(start 432.127406 -22.82952)
		(end 427.86427 -22.82952)
		(width 0.089408)
		(layer "In2.Cu")
		(net "CLK_25M_CPLD")
	)
	(segment
		(start 389.104632 -60.474606)
		(end 390.103614 -61.473588)
		(width 0.089408)
		(layer "In2.Cu")
		(net "CLK_25M_CPLD")
	)
	(segment
		(start 473.685616 -29.298138)
		(end 472.661234 -30.32252)
		(width 0.089408)
		(layer "In2.Cu")
		(net "CLK_25M_CPLD")
	)
	(segment
		(start 394.537946 -38.088062)
		(end 394.537692 -38.087808)
		(width 0.089408)
		(layer "In2.Cu")
		(net "CLK_25M_CPLD")
	)
	(segment
		(start 434.888132 -21.538438)
		(end 434.31968 -22.10689)
		(width 0.089408)
		(layer "In2.Cu")
		(net "CLK_25M_CPLD")
	)
	(segment
		(start 402.138134 -34.787586)
		(end 400.61134 -34.787586)
		(width 0.089408)
		(layer "In2.Cu")
		(net "CLK_25M_CPLD")
	)
	(segment
		(start 432.484784 -22.472142)
		(end 432.127406 -22.82952)
		(width 0.089408)
		(layer "In2.Cu")
		(net "CLK_25M_CPLD")
	)
	(segment
		(start 391.61974 -41.57218)
		(end 389.855202 -43.336718)
		(width 0.089408)
		(layer "In2.Cu")
		(net "CLK_25M_CPLD")
	)
	(segment
		(start 478.771712 -33.08096)
		(end 480.259898 -34.569146)
		(width 0.089408)
		(layer "In4.Cu")
		(net "CLK_25M_CPLD")
	)
	(segment
		(start 480.259898 -34.569146)
		(end 481.34524 -34.569146)
		(width 0.089408)
		(layer "In4.Cu")
		(net "CLK_25M_CPLD")
	)
	(segment
		(start 474.904816 -33.08096)
		(end 478.771712 -33.08096)
		(width 0.089408)
		(layer "In4.Cu")
		(net "CLK_25M_CPLD")
	)
	(segment
		(start 474.322648 -32.498792)
		(end 474.904816 -33.08096)
		(width 0.089408)
		(layer "In4.Cu")
		(net "CLK_25M_CPLD")
	)
	(segment
		(start 473.685616 -29.14269)
		(end 474.322648 -29.779722)
		(width 0.089408)
		(layer "In4.Cu")
		(net "CLK_25M_CPLD")
	)
	(segment
		(start 474.322648 -29.779722)
		(end 474.322648 -32.498792)
		(width 0.089408)
		(layer "In4.Cu")
		(net "CLK_25M_CPLD")
	)
	(via
		(at 483.3112 -152.1968)
		(size 0.6604)
		(drill 0.3302)
		(layers "F.Cu" "B.Cu")
		(net "FM_CPLD_DBG_PWR_EN")
	)
	(segment
		(start 477.9264 -148.874226)
		(end 477.29521 -148.874226)
		(width 0.10795)
		(layer "B.Cu")
		(net "FM_CPLD_DBG_PWR_EN")
	)
	(segment
		(start 482.97084 -150.1394)
		(end 482.5238 -150.1394)
		(width 0.10795)
		(layer "B.Cu")
		(net "FM_CPLD_DBG_PWR_EN")
	)
	(segment
		(start 477.94545 -149.524466)
		(end 478.0534 -149.416516)
		(width 0.10795)
		(layer "B.Cu")
		(net "FM_CPLD_DBG_PWR_EN")
	)
	(segment
		(start 478.0534 -149.001226)
		(end 478.145094 -148.909532)
		(width 0.10795)
		(layer "B.Cu")
		(net "FM_CPLD_DBG_PWR_EN")
	)
	(segment
		(start 478.145094 -148.909532)
		(end 480.7077 -148.909532)
		(width 0.10795)
		(layer "B.Cu")
		(net "FM_CPLD_DBG_PWR_EN")
	)
	(segment
		(start 483.3112 -152.1968)
		(end 483.3112 -151.484076)
		(width 0.10795)
		(layer "B.Cu")
		(net "FM_CPLD_DBG_PWR_EN")
	)
	(segment
		(start 480.7077 -148.909532)
		(end 481.937568 -150.1394)
		(width 0.10795)
		(layer "B.Cu")
		(net "FM_CPLD_DBG_PWR_EN")
	)
	(segment
		(start 481.937568 -150.1394)
		(end 482.5238 -150.1394)
		(width 0.10795)
		(layer "B.Cu")
		(net "FM_CPLD_DBG_PWR_EN")
	)
	(segment
		(start 483.11816 -150.28672)
		(end 482.97084 -150.1394)
		(width 0.10795)
		(layer "B.Cu")
		(net "FM_CPLD_DBG_PWR_EN")
	)
	(segment
		(start 478.0534 -149.001226)
		(end 477.9264 -148.874226)
		(width 0.10795)
		(layer "B.Cu")
		(net "FM_CPLD_DBG_PWR_EN")
	)
	(segment
		(start 483.11816 -151.291036)
		(end 483.11816 -150.28672)
		(width 0.10795)
		(layer "B.Cu")
		(net "FM_CPLD_DBG_PWR_EN")
	)
	(segment
		(start 477.29521 -149.524466)
		(end 477.94545 -149.524466)
		(width 0.10795)
		(layer "B.Cu")
		(net "FM_CPLD_DBG_PWR_EN")
	)
	(segment
		(start 483.3112 -151.484076)
		(end 483.11816 -151.291036)
		(width 0.10795)
		(layer "B.Cu")
		(net "FM_CPLD_DBG_PWR_EN")
	)
	(segment
		(start 478.0534 -149.416516)
		(end 478.0534 -149.001226)
		(width 0.10795)
		(layer "B.Cu")
		(net "FM_CPLD_DBG_PWR_EN")
	)
	(via
		(at 16.9926 -81.788)
		(size 0.508)
		(drill 0.254)
		(layers "F.Cu" "B.Cu")
		(net "A_P12V_STBY_FPH_GATE")
	)
	(via
		(at 24.0919 -81.4451)
		(size 0.6604)
		(drill 0.3302)
		(layers "F.Cu" "B.Cu")
		(net "A_P12V_STBY_FPH_GATE")
	)
	(via
		(at 23.389844 -82.361532)
		(size 0.508)
		(drill 0.254)
		(layers "F.Cu" "B.Cu")
		(net "A_P12V_STBY_FPH_GATE")
	)
	(segment
		(start 24.0919 -81.4451)
		(end 23.389844 -82.147156)
		(width 0.254)
		(layer "B.Cu")
		(net "A_P12V_STBY_FPH_GATE")
	)
	(segment
		(start 16.728186 -82.052414)
		(end 16.9926 -81.788)
		(width 0.254)
		(layer "B.Cu")
		(net "A_P12V_STBY_FPH_GATE")
	)
	(segment
		(start 22.0345 -83.312)
		(end 23.241 -83.312)
		(width 0.254)
		(layer "B.Cu")
		(net "A_P12V_STBY_FPH_GATE")
	)
	(segment
		(start 23.389844 -82.147156)
		(end 23.389844 -82.361532)
		(width 0.254)
		(layer "B.Cu")
		(net "A_P12V_STBY_FPH_GATE")
	)
	(segment
		(start 23.368 -82.383376)
		(end 23.389844 -82.361532)
		(width 0.254)
		(layer "B.Cu")
		(net "A_P12V_STBY_FPH_GATE")
	)
	(segment
		(start 16.728186 -82.677)
		(end 16.728186 -82.052414)
		(width 0.254)
		(layer "B.Cu")
		(net "A_P12V_STBY_FPH_GATE")
	)
	(segment
		(start 23.368 -83.185)
		(end 23.368 -82.383376)
		(width 0.254)
		(layer "B.Cu")
		(net "A_P12V_STBY_FPH_GATE")
	)
	(segment
		(start 23.241 -83.312)
		(end 23.368 -83.185)
		(width 0.254)
		(layer "B.Cu")
		(net "A_P12V_STBY_FPH_GATE")
	)
	(segment
		(start 17.4752 -82.4484)
		(end 16.9926 -81.9658)
		(width 0.254)
		(layer "In2.Cu")
		(net "A_P12V_STBY_FPH_GATE")
	)
	(segment
		(start 23.22322 -82.77098)
		(end 22.3012 -83.693)
		(width 0.254)
		(layer "In2.Cu")
		(net "A_P12V_STBY_FPH_GATE")
	)
	(segment
		(start 23.389844 -82.361532)
		(end 23.22322 -82.528156)
		(width 0.254)
		(layer "In2.Cu")
		(net "A_P12V_STBY_FPH_GATE")
	)
	(segment
		(start 22.3012 -83.693)
		(end 19.1262 -83.693)
		(width 0.254)
		(layer "In2.Cu")
		(net "A_P12V_STBY_FPH_GATE")
	)
	(segment
		(start 16.9926 -81.9658)
		(end 16.9926 -81.788)
		(width 0.254)
		(layer "In2.Cu")
		(net "A_P12V_STBY_FPH_GATE")
	)
	(segment
		(start 17.8816 -82.4484)
		(end 17.4752 -82.4484)
		(width 0.254)
		(layer "In2.Cu")
		(net "A_P12V_STBY_FPH_GATE")
	)
	(segment
		(start 19.1262 -83.693)
		(end 17.8816 -82.4484)
		(width 0.254)
		(layer "In2.Cu")
		(net "A_P12V_STBY_FPH_GATE")
	)
	(segment
		(start 23.22322 -82.528156)
		(end 23.22322 -82.77098)
		(width 0.254)
		(layer "In2.Cu")
		(net "A_P12V_STBY_FPH_GATE")
	)
	(via
		(at 496.17376 -125.7427)
		(size 0.6604)
		(drill 0.3302)
		(layers "F.Cu" "B.Cu")
		(net "LED_SATA_ACT_R_N")
	)
	(segment
		(start 496.17376 -124.9553)
		(end 496.17376 -125.7427)
		(width 0.10795)
		(layer "B.Cu")
		(net "LED_SATA_ACT_R_N")
	)
	(segment
		(start 494.75136 -126.5174)
		(end 494.75136 -125.4887)
		(width 0.10795)
		(layer "B.Cu")
		(net "LED_SATA_ACT_R_N")
	)
	(segment
		(start 494.75136 -125.4887)
		(end 495.28476 -124.9553)
		(width 0.10795)
		(layer "B.Cu")
		(net "LED_SATA_ACT_R_N")
	)
	(segment
		(start 495.28476 -124.9553)
		(end 496.17376 -124.9553)
		(width 0.10795)
		(layer "B.Cu")
		(net "LED_SATA_ACT_R_N")
	)
	(segment
		(start 494.101374 -125.226826)
		(end 494.3729 -124.9553)
		(width 0.10795)
		(layer "B.Cu")
		(net "LED_SAS_ACT_R_N")
	)
	(segment
		(start 494.101374 -126.5174)
		(end 494.101374 -125.226826)
		(width 0.10795)
		(layer "B.Cu")
		(net "LED_SAS_ACT_R_N")
	)
	(segment
		(start 493.55502 -124.9553)
		(end 493.5474 -124.94768)
		(width 0.10795)
		(layer "B.Cu")
		(net "LED_SAS_ACT_R_N")
	)
	(segment
		(start 494.3729 -124.9553)
		(end 493.55502 -124.9553)
		(width 0.10795)
		(layer "B.Cu")
		(net "LED_SAS_ACT_R_N")
	)
	(segment
		(start 486.497376 -136.652)
		(end 487.106976 -137.2616)
		(width 0.10795)
		(layer "F.Cu")
		(net "LED_P5V_STBY")
	)
	(segment
		(start 485.9274 -136.652)
		(end 486.497376 -136.652)
		(width 0.10795)
		(layer "F.Cu")
		(net "LED_P5V_STBY")
	)
	(segment
		(start 498.7544 -146.304)
		(end 499.872 -146.304)
		(width 0.10795)
		(layer "F.Cu")
		(net "FP_LED_HDD_ACTIVITY_AND_R_N")
	)
	(segment
		(start 498.475 -146.939)
		(end 498.475 -146.5834)
		(width 0.10795)
		(layer "F.Cu")
		(net "FP_LED_HDD_ACTIVITY_AND_R_N")
	)
	(segment
		(start 498.475 -146.5834)
		(end 498.7544 -146.304)
		(width 0.10795)
		(layer "F.Cu")
		(net "FP_LED_HDD_ACTIVITY_AND_R_N")
	)
	(via
		(at 498.475 -146.939)
		(size 0.508)
		(drill 0.254)
		(layers "F.Cu" "B.Cu")
		(net "FP_LED_HDD_ACTIVITY_AND_R_N")
	)
	(segment
		(start 498.5512 -146.8628)
		(end 498.475 -146.939)
		(width 0.10795)
		(layer "B.Cu")
		(net "FP_LED_HDD_ACTIVITY_AND_R_N")
	)
	(segment
		(start 499.2878 -146.8628)
		(end 498.5512 -146.8628)
		(width 0.10795)
		(layer "B.Cu")
		(net "FP_LED_HDD_ACTIVITY_AND_R_N")
	)
	(segment
		(start 497.459 -148.0566)
		(end 497.459 -139.956286)
		(width 0.10795)
		(layer "F.Cu")
		(net "FP_LED_HDD_ACTIVITY_AND_N")
	)
	(segment
		(start 499.872 -149.86)
		(end 499.2624 -149.86)
		(width 0.10795)
		(layer "F.Cu")
		(net "FP_LED_HDD_ACTIVITY_AND_N")
	)
	(segment
		(start 497.459 -139.956286)
		(end 496.872514 -139.3698)
		(width 0.10795)
		(layer "F.Cu")
		(net "FP_LED_HDD_ACTIVITY_AND_N")
	)
	(segment
		(start 499.2624 -149.86)
		(end 497.459 -148.0566)
		(width 0.10795)
		(layer "F.Cu")
		(net "FP_LED_HDD_ACTIVITY_AND_N")
	)
	(via
		(at 497.6114 -137.795)
		(size 0.6604)
		(drill 0.3302)
		(layers "F.Cu" "B.Cu")
		(net "FP_LED_HDD_ACTIVITY_AND_N")
	)
	(via
		(at 496.872514 -139.3698)
		(size 0.508)
		(drill 0.254)
		(layers "F.Cu" "B.Cu")
		(net "FP_LED_HDD_ACTIVITY_AND_N")
	)
	(segment
		(start 497.122196 -138.817604)
		(end 497.122196 -139.120118)
		(width 0.10795)
		(layer "B.Cu")
		(net "FP_LED_HDD_ACTIVITY_AND_N")
	)
	(segment
		(start 494.755424 -134.343902)
		(end 494.820194 -134.343902)
		(width 0.10795)
		(layer "B.Cu")
		(net "FP_LED_HDD_ACTIVITY_AND_N")
	)
	(segment
		(start 496.3414 -136.816846)
		(end 496.697254 -137.1727)
		(width 0.10795)
		(layer "B.Cu")
		(net "FP_LED_HDD_ACTIVITY_AND_N")
	)
	(segment
		(start 494.035842 -128.922526)
		(end 494.6396 -129.526284)
		(width 0.10795)
		(layer "B.Cu")
		(net "FP_LED_HDD_ACTIVITY_AND_N")
	)
	(segment
		(start 496.3414 -135.6868)
		(end 496.3414 -136.816846)
		(width 0.10795)
		(layer "B.Cu")
		(net "FP_LED_HDD_ACTIVITY_AND_N")
	)
	(segment
		(start 496.9891 -137.1727)
		(end 497.6114 -137.795)
		(width 0.10795)
		(layer "B.Cu")
		(net "FP_LED_HDD_ACTIVITY_AND_N")
	)
	(segment
		(start 493.451388 -128.2954)
		(end 493.451388 -128.6129)
		(width 0.10795)
		(layer "B.Cu")
		(net "FP_LED_HDD_ACTIVITY_AND_N")
	)
	(segment
		(start 494.6396 -129.526284)
		(end 494.6396 -134.228078)
		(width 0.10795)
		(layer "B.Cu")
		(net "FP_LED_HDD_ACTIVITY_AND_N")
	)
	(segment
		(start 497.6114 -137.795)
		(end 497.6114 -138.3284)
		(width 0.10795)
		(layer "B.Cu")
		(net "FP_LED_HDD_ACTIVITY_AND_N")
	)
	(segment
		(start 497.122196 -139.120118)
		(end 496.872514 -139.3698)
		(width 0.10795)
		(layer "B.Cu")
		(net "FP_LED_HDD_ACTIVITY_AND_N")
	)
	(segment
		(start 496.697254 -137.1727)
		(end 496.9891 -137.1727)
		(width 0.10795)
		(layer "B.Cu")
		(net "FP_LED_HDD_ACTIVITY_AND_N")
	)
	(segment
		(start 496.0366 -135.382)
		(end 496.3414 -135.6868)
		(width 0.10795)
		(layer "B.Cu")
		(net "FP_LED_HDD_ACTIVITY_AND_N")
	)
	(segment
		(start 493.451388 -128.6129)
		(end 493.761014 -128.922526)
		(width 0.10795)
		(layer "B.Cu")
		(net "FP_LED_HDD_ACTIVITY_AND_N")
	)
	(segment
		(start 493.761014 -128.922526)
		(end 494.035842 -128.922526)
		(width 0.10795)
		(layer "B.Cu")
		(net "FP_LED_HDD_ACTIVITY_AND_N")
	)
	(segment
		(start 494.820194 -134.343902)
		(end 495.858292 -135.382)
		(width 0.10795)
		(layer "B.Cu")
		(net "FP_LED_HDD_ACTIVITY_AND_N")
	)
	(segment
		(start 494.6396 -134.228078)
		(end 494.755424 -134.343902)
		(width 0.10795)
		(layer "B.Cu")
		(net "FP_LED_HDD_ACTIVITY_AND_N")
	)
	(segment
		(start 495.858292 -135.382)
		(end 496.0366 -135.382)
		(width 0.10795)
		(layer "B.Cu")
		(net "FP_LED_HDD_ACTIVITY_AND_N")
	)
	(segment
		(start 497.6114 -138.3284)
		(end 497.122196 -138.817604)
		(width 0.10795)
		(layer "B.Cu")
		(net "FP_LED_HDD_ACTIVITY_AND_N")
	)
	(segment
		(start 455.676 -27.686)
		(end 455.676 -27.976576)
		(width 0.10795)
		(layer "F.Cu")
		(net "FM_RED_LED_CATHODE")
	)
	(segment
		(start 457.47178 -28.052522)
		(end 457.47178 -27.432)
		(width 0.10795)
		(layer "F.Cu")
		(net "FM_RED_LED_CATHODE")
	)
	(segment
		(start 455.86523 -28.165806)
		(end 457.358496 -28.165806)
		(width 0.10795)
		(layer "F.Cu")
		(net "FM_RED_LED_CATHODE")
	)
	(segment
		(start 457.358496 -28.165806)
		(end 457.47178 -28.052522)
		(width 0.10795)
		(layer "F.Cu")
		(net "FM_RED_LED_CATHODE")
	)
	(segment
		(start 459.7146 -27.559)
		(end 458.1144 -27.559)
		(width 0.10795)
		(layer "F.Cu")
		(net "FM_RED_LED_CATHODE")
	)
	(segment
		(start 455.676 -27.976576)
		(end 455.86523 -28.165806)
		(width 0.10795)
		(layer "F.Cu")
		(net "FM_RED_LED_CATHODE")
	)
	(segment
		(start 454.914 -27.559)
		(end 455.549 -27.559)
		(width 0.10795)
		(layer "F.Cu")
		(net "FM_RED_LED_CATHODE")
	)
	(segment
		(start 457.9874 -27.432)
		(end 457.47178 -27.432)
		(width 0.10795)
		(layer "F.Cu")
		(net "FM_RED_LED_CATHODE")
	)
	(segment
		(start 458.1144 -27.559)
		(end 457.9874 -27.432)
		(width 0.10795)
		(layer "F.Cu")
		(net "FM_RED_LED_CATHODE")
	)
	(segment
		(start 455.549 -27.559)
		(end 455.676 -27.686)
		(width 0.10795)
		(layer "F.Cu")
		(net "FM_RED_LED_CATHODE")
	)
	(via
		(at 459.7146 -27.559)
		(size 0.762)
		(drill 0.381)
		(layers "F.Cu" "B.Cu")
		(net "FM_RED_LED_CATHODE")
	)
	(segment
		(start 454.7235 -30.1625)
		(end 454.914 -29.972)
		(width 0.10795)
		(layer "F.Cu")
		(net "FM_RED_LED_ANODE")
	)
	(segment
		(start 454.914 -29.337)
		(end 453.6186 -29.337)
		(width 0.10795)
		(layer "F.Cu")
		(net "FM_RED_LED_ANODE")
	)
	(segment
		(start 454.7235 -30.48)
		(end 454.7235 -30.1625)
		(width 0.10795)
		(layer "F.Cu")
		(net "FM_RED_LED_ANODE")
	)
	(segment
		(start 453.6186 -29.337)
		(end 453.1614 -29.7942)
		(width 0.10795)
		(layer "F.Cu")
		(net "FM_RED_LED_ANODE")
	)
	(segment
		(start 454.914 -29.972)
		(end 454.914 -29.337)
		(width 0.10795)
		(layer "F.Cu")
		(net "FM_RED_LED_ANODE")
	)
	(via
		(at 453.1614 -29.7942)
		(size 0.762)
		(drill 0.381)
		(layers "F.Cu" "B.Cu")
		(net "FM_RED_LED_ANODE")
	)
	(segment
		(start 456.244706 -28.509722)
		(end 456.745086 -28.509722)
		(width 0.10795)
		(layer "F.Cu")
		(net "FM_BMC_FAULT_LED")
	)
	(segment
		(start 456.745086 -28.509722)
		(end 456.82154 -28.586176)
		(width 0.10795)
		(layer "F.Cu")
		(net "FM_BMC_FAULT_LED")
	)
	(segment
		(start 456.1713 -28.583128)
		(end 456.244706 -28.509722)
		(width 0.10795)
		(layer "F.Cu")
		(net "FM_BMC_FAULT_LED")
	)
	(segment
		(start 459.706218 -32.098234)
		(end 458.996034 -32.098234)
		(width 0.10795)
		(layer "F.Cu")
		(net "FM_BMC_FAULT_LED")
	)
	(segment
		(start 456.1713 -29.21)
		(end 456.1713 -28.583128)
		(width 0.10795)
		(layer "F.Cu")
		(net "FM_BMC_FAULT_LED")
	)
	(segment
		(start 456.82154 -29.21)
		(end 456.82154 -29.823156)
		(width 0.10795)
		(layer "F.Cu")
		(net "FM_BMC_FAULT_LED")
	)
	(segment
		(start 458.996034 -32.098234)
		(end 457.8985 -31.0007)
		(width 0.10795)
		(layer "F.Cu")
		(net "FM_BMC_FAULT_LED")
	)
	(segment
		(start 456.82154 -29.823156)
		(end 456.954636 -29.956252)
		(width 0.10795)
		(layer "F.Cu")
		(net "FM_BMC_FAULT_LED")
	)
	(segment
		(start 457.8985 -31.0007)
		(end 457.8985 -30.48)
		(width 0.10795)
		(layer "F.Cu")
		(net "FM_BMC_FAULT_LED")
	)
	(segment
		(start 456.954636 -29.956252)
		(end 457.730098 -29.956252)
		(width 0.10795)
		(layer "F.Cu")
		(net "FM_BMC_FAULT_LED")
	)
	(segment
		(start 456.82154 -28.586176)
		(end 456.82154 -29.21)
		(width 0.10795)
		(layer "F.Cu")
		(net "FM_BMC_FAULT_LED")
	)
	(segment
		(start 457.8985 -30.124654)
		(end 457.8985 -30.48)
		(width 0.10795)
		(layer "F.Cu")
		(net "FM_BMC_FAULT_LED")
	)
	(segment
		(start 457.730098 -29.956252)
		(end 457.8985 -30.124654)
		(width 0.10795)
		(layer "F.Cu")
		(net "FM_BMC_FAULT_LED")
	)
	(via
		(at 459.706218 -32.098234)
		(size 0.762)
		(drill 0.381)
		(layers "F.Cu" "B.Cu")
		(net "FM_BMC_FAULT_LED")
	)
	(via
		(at 312.3184 -32.5882)
		(size 0.6604)
		(drill 0.3302)
		(layers "F.Cu" "B.Cu")
		(net "IRQ_DIMM_SAVE_R_N")
	)
	(segment
		(start 312.774076 -29.505148)
		(end 312.774076 -30.791658)
		(width 0.10795)
		(layer "B.Cu")
		(net "IRQ_DIMM_SAVE_R_N")
	)
	(segment
		(start 312.60415 -30.80385)
		(end 312.786268 -30.80385)
		(width 0.10795)
		(layer "B.Cu")
		(net "IRQ_DIMM_SAVE_R_N")
	)
	(segment
		(start 312.774076 -30.791658)
		(end 312.786268 -30.80385)
		(width 0.10795)
		(layer "B.Cu")
		(net "IRQ_DIMM_SAVE_R_N")
	)
	(segment
		(start 312.3184 -32.5882)
		(end 312.3184 -31.0896)
		(width 0.10795)
		(layer "B.Cu")
		(net "IRQ_DIMM_SAVE_R_N")
	)
	(segment
		(start 312.3184 -31.0896)
		(end 312.60415 -30.80385)
		(width 0.10795)
		(layer "B.Cu")
		(net "IRQ_DIMM_SAVE_R_N")
	)
	(segment
		(start 393.279122 -87.611204)
		(end 393.279122 -86.980522)
		(width 0.10795)
		(layer "F.Cu")
		(net "FM_OC_DETECT_EN_N")
	)
	(segment
		(start 393.369038 -87.70112)
		(end 393.279122 -87.611204)
		(width 0.0889)
		(layer "F.Cu")
		(net "FM_OC_DETECT_EN_N")
	)
	(segment
		(start 424.481244 -25.274524)
		(end 424.308016 -25.274524)
		(width 0.10795)
		(layer "F.Cu")
		(net "FM_OC_DETECT_EN_N")
	)
	(segment
		(start 393.662408 -90.177112)
		(end 393.662154 -90.176858)
		(width 0.0889)
		(layer "F.Cu")
		(net "FM_OC_DETECT_EN_N")
	)
	(segment
		(start 25.019 -75.819)
		(end 25.019 -76.2762)
		(width 0.10795)
		(layer "F.Cu")
		(net "FM_OC_DETECT_EN_N")
	)
	(segment
		(start 393.485116 -94.427802)
		(end 393.162282 -94.104968)
		(width 0.0889)
		(layer "F.Cu")
		(net "FM_OC_DETECT_EN_N")
	)
	(segment
		(start 25.019 -76.2762)
		(end 25.0698 -76.327)
		(width 0.10795)
		(layer "F.Cu")
		(net "FM_OC_DETECT_EN_N")
	)
	(segment
		(start 393.103354 -86.804754)
		(end 393.2174 -86.9188)
		(width 0.10795)
		(layer "F.Cu")
		(net "FM_OC_DETECT_EN_N")
	)
	(segment
		(start 425.118022 -24.641048)
		(end 424.4848 -25.27427)
		(width 0.10795)
		(layer "F.Cu")
		(net "FM_OC_DETECT_EN_N")
	)
	(segment
		(start 422.936162 -26.163016)
		(end 422.718484 -26.380694)
		(width 0.10795)
		(layer "F.Cu")
		(net "FM_OC_DETECT_EN_N")
	)
	(segment
		(start 424.307762 -25.27427)
		(end 423.826178 -25.27427)
		(width 0.10795)
		(layer "F.Cu")
		(net "FM_OC_DETECT_EN_N")
	)
	(segment
		(start 422.718484 -26.380694)
		(end 422.718484 -26.730198)
		(width 0.10795)
		(layer "F.Cu")
		(net "FM_OC_DETECT_EN_N")
	)
	(segment
		(start 393.349988 -91.642184)
		(end 393.662408 -91.329764)
		(width 0.0889)
		(layer "F.Cu")
		(net "FM_OC_DETECT_EN_N")
	)
	(segment
		(start 393.279122 -93.725746)
		(end 393.279122 -93.52026)
		(width 0.0889)
		(layer "F.Cu")
		(net "FM_OC_DETECT_EN_N")
	)
	(segment
		(start 393.662154 -90.176858)
		(end 393.662154 -89.9033)
		(width 0.0889)
		(layer "F.Cu")
		(net "FM_OC_DETECT_EN_N")
	)
	(segment
		(start 393.279122 -93.52026)
		(end 393.349988 -93.449394)
		(width 0.0889)
		(layer "F.Cu")
		(net "FM_OC_DETECT_EN_N")
	)
	(segment
		(start 425.465748 -24.29002)
		(end 425.118022 -24.637746)
		(width 0.10795)
		(layer "F.Cu")
		(net "FM_OC_DETECT_EN_N")
	)
	(segment
		(start 25.0698 -76.327)
		(end 25.0698 -77.1906)
		(width 0.10795)
		(layer "F.Cu")
		(net "FM_OC_DETECT_EN_N")
	)
	(segment
		(start 424.481498 -25.27427)
		(end 424.481244 -25.274524)
		(width 0.10795)
		(layer "F.Cu")
		(net "FM_OC_DETECT_EN_N")
	)
	(segment
		(start 393.662154 -89.9033)
		(end 393.369038 -89.610184)
		(width 0.0889)
		(layer "F.Cu")
		(net "FM_OC_DETECT_EN_N")
	)
	(segment
		(start 393.369038 -89.610184)
		(end 393.369038 -87.70112)
		(width 0.0889)
		(layer "F.Cu")
		(net "FM_OC_DETECT_EN_N")
	)
	(segment
		(start 25.69718 -75.34402)
		(end 25.1333 -75.34402)
		(width 0.10795)
		(layer "F.Cu")
		(net "FM_OC_DETECT_EN_N")
	)
	(segment
		(start 422.718484 -26.730198)
		(end 422.29024 -27.158442)
		(width 0.10795)
		(layer "F.Cu")
		(net "FM_OC_DETECT_EN_N")
	)
	(segment
		(start 424.4848 -25.27427)
		(end 424.481498 -25.27427)
		(width 0.10795)
		(layer "F.Cu")
		(net "FM_OC_DETECT_EN_N")
	)
	(segment
		(start 393.162282 -94.104968)
		(end 393.162282 -93.842586)
		(width 0.0889)
		(layer "F.Cu")
		(net "FM_OC_DETECT_EN_N")
	)
	(segment
		(start 422.937432 -26.163016)
		(end 422.936162 -26.163016)
		(width 0.10795)
		(layer "F.Cu")
		(net "FM_OC_DETECT_EN_N")
	)
	(segment
		(start 424.308016 -25.274524)
		(end 424.307762 -25.27427)
		(width 0.10795)
		(layer "F.Cu")
		(net "FM_OC_DETECT_EN_N")
	)
	(segment
		(start 393.349988 -93.449394)
		(end 393.349988 -91.642184)
		(width 0.0889)
		(layer "F.Cu")
		(net "FM_OC_DETECT_EN_N")
	)
	(segment
		(start 393.279122 -86.980522)
		(end 393.2174 -86.9188)
		(width 0.10795)
		(layer "F.Cu")
		(net "FM_OC_DETECT_EN_N")
	)
	(segment
		(start 393.103354 -86.295484)
		(end 393.103354 -86.804754)
		(width 0.10795)
		(layer "F.Cu")
		(net "FM_OC_DETECT_EN_N")
	)
	(segment
		(start 25.1333 -75.34402)
		(end 25.019 -75.45832)
		(width 0.10795)
		(layer "F.Cu")
		(net "FM_OC_DETECT_EN_N")
	)
	(segment
		(start 25.019 -75.45832)
		(end 25.019 -75.819)
		(width 0.10795)
		(layer "F.Cu")
		(net "FM_OC_DETECT_EN_N")
	)
	(segment
		(start 393.485116 -94.790006)
		(end 393.485116 -94.427802)
		(width 0.0889)
		(layer "F.Cu")
		(net "FM_OC_DETECT_EN_N")
	)
	(segment
		(start 425.465748 -23.169626)
		(end 425.465748 -24.29002)
		(width 0.10795)
		(layer "F.Cu")
		(net "FM_OC_DETECT_EN_N")
	)
	(segment
		(start 25.989788 -75.051412)
		(end 25.69718 -75.34402)
		(width 0.10795)
		(layer "F.Cu")
		(net "FM_OC_DETECT_EN_N")
	)
	(segment
		(start 393.162282 -93.842586)
		(end 393.279122 -93.725746)
		(width 0.0889)
		(layer "F.Cu")
		(net "FM_OC_DETECT_EN_N")
	)
	(segment
		(start 422.29024 -27.158442)
		(end 422.29024 -27.334718)
		(width 0.10795)
		(layer "F.Cu")
		(net "FM_OC_DETECT_EN_N")
	)
	(segment
		(start 423.826178 -25.27427)
		(end 422.937432 -26.163016)
		(width 0.10795)
		(layer "F.Cu")
		(net "FM_OC_DETECT_EN_N")
	)
	(segment
		(start 393.662408 -91.329764)
		(end 393.662408 -90.177112)
		(width 0.0889)
		(layer "F.Cu")
		(net "FM_OC_DETECT_EN_N")
	)
	(segment
		(start 425.118022 -24.637746)
		(end 425.118022 -24.641048)
		(width 0.10795)
		(layer "F.Cu")
		(net "FM_OC_DETECT_EN_N")
	)
	(via
		(at 408.729688 -86.26602)
		(size 0.508)
		(drill 0.254)
		(layers "F.Cu" "B.Cu")
		(net "FM_OC_DETECT_EN_N")
	)
	(via
		(at 327.0758 4.2418)
		(size 0.508)
		(drill 0.254)
		(layers "F.Cu" "B.Cu")
		(net "FM_OC_DETECT_EN_N")
	)
	(via
		(at 425.465748 -23.169626)
		(size 0.508)
		(drill 0.254)
		(layers "F.Cu" "B.Cu")
		(net "FM_OC_DETECT_EN_N")
	)
	(via
		(at 25.989788 -75.051412)
		(size 0.508)
		(drill 0.254)
		(layers "F.Cu" "B.Cu")
		(net "FM_OC_DETECT_EN_N")
	)
	(via
		(at 26.036778 -53.605938)
		(size 0.508)
		(drill 0.254)
		(layers "F.Cu" "B.Cu")
		(net "FM_OC_DETECT_EN_N")
	)
	(via
		(at 26.543 0.4699)
		(size 0.508)
		(drill 0.254)
		(layers "F.Cu" "B.Cu")
		(net "FM_OC_DETECT_EN_N")
	)
	(via
		(at 466.8266 -2.4638)
		(size 0.508)
		(drill 0.254)
		(layers "F.Cu" "B.Cu")
		(net "FM_OC_DETECT_EN_N")
	)
	(via
		(at 474.059504 -17.04467)
		(size 0.6604)
		(drill 0.3302)
		(layers "F.Cu" "B.Cu")
		(net "FM_OC_DETECT_EN_N")
	)
	(via
		(at 463.54746 -26.31948)
		(size 0.508)
		(drill 0.254)
		(layers "F.Cu" "B.Cu")
		(net "FM_OC_DETECT_EN_N")
	)
	(via
		(at 178.9303 -1.2573)
		(size 0.508)
		(drill 0.254)
		(layers "F.Cu" "B.Cu")
		(net "FM_OC_DETECT_EN_N")
	)
	(via
		(at 393.2174 -86.9188)
		(size 0.508)
		(drill 0.254)
		(layers "F.Cu" "B.Cu")
		(net "FM_OC_DETECT_EN_N")
	)
	(via
		(at 477.2152 -10.2108)
		(size 0.508)
		(drill 0.254)
		(layers "F.Cu" "B.Cu")
		(net "FM_OC_DETECT_EN_N")
	)
	(segment
		(start 477.2152 -10.2108)
		(end 478.2058 -11.2014)
		(width 0.10795)
		(layer "B.Cu")
		(net "FM_OC_DETECT_EN_N")
	)
	(segment
		(start 464.566 -22.7076)
		(end 463.423 -23.8506)
		(width 0.10795)
		(layer "B.Cu")
		(net "FM_OC_DETECT_EN_N")
	)
	(segment
		(start 465.455 -20.3962)
		(end 464.566 -21.2852)
		(width 0.10795)
		(layer "B.Cu")
		(net "FM_OC_DETECT_EN_N")
	)
	(segment
		(start 476.463106 -17.414494)
		(end 474.429328 -17.414494)
		(width 0.10795)
		(layer "B.Cu")
		(net "FM_OC_DETECT_EN_N")
	)
	(segment
		(start 478.2058 -11.2014)
		(end 478.2058 -15.6718)
		(width 0.10795)
		(layer "B.Cu")
		(net "FM_OC_DETECT_EN_N")
	)
	(segment
		(start 468.991442 -20.3962)
		(end 465.455 -20.3962)
		(width 0.10795)
		(layer "B.Cu")
		(net "FM_OC_DETECT_EN_N")
	)
	(segment
		(start 478.2058 -15.6718)
		(end 476.463106 -17.414494)
		(width 0.10795)
		(layer "B.Cu")
		(net "FM_OC_DETECT_EN_N")
	)
	(segment
		(start 469.997536 -19.390106)
		(end 468.991442 -20.3962)
		(width 0.10795)
		(layer "B.Cu")
		(net "FM_OC_DETECT_EN_N")
	)
	(segment
		(start 463.423 -26.19502)
		(end 463.54746 -26.31948)
		(width 0.10795)
		(layer "B.Cu")
		(net "FM_OC_DETECT_EN_N")
	)
	(segment
		(start 474.429328 -17.414494)
		(end 474.059504 -17.04467)
		(width 0.10795)
		(layer "B.Cu")
		(net "FM_OC_DETECT_EN_N")
	)
	(segment
		(start 469.997536 -18.443956)
		(end 469.997536 -19.390106)
		(width 0.10795)
		(layer "B.Cu")
		(net "FM_OC_DETECT_EN_N")
	)
	(segment
		(start 471.396822 -17.04467)
		(end 469.997536 -18.443956)
		(width 0.10795)
		(layer "B.Cu")
		(net "FM_OC_DETECT_EN_N")
	)
	(segment
		(start 474.059504 -17.04467)
		(end 471.396822 -17.04467)
		(width 0.10795)
		(layer "B.Cu")
		(net "FM_OC_DETECT_EN_N")
	)
	(segment
		(start 464.566 -21.2852)
		(end 464.566 -22.7076)
		(width 0.10795)
		(layer "B.Cu")
		(net "FM_OC_DETECT_EN_N")
	)
	(segment
		(start 463.423 -23.8506)
		(end 463.423 -26.19502)
		(width 0.10795)
		(layer "B.Cu")
		(net "FM_OC_DETECT_EN_N")
	)
	(segment
		(start 458.925422 -25.661366)
		(end 460.58074 -25.661366)
		(width 0.089408)
		(layer "In2.Cu")
		(net "FM_OC_DETECT_EN_N")
	)
	(segment
		(start 461.238854 -26.31948)
		(end 463.54746 -26.31948)
		(width 0.089408)
		(layer "In2.Cu")
		(net "FM_OC_DETECT_EN_N")
	)
	(segment
		(start 444.811658 -19.675094)
		(end 445.241426 -20.104862)
		(width 0.089408)
		(layer "In2.Cu")
		(net "FM_OC_DETECT_EN_N")
	)
	(segment
		(start 443.88278 -19.675094)
		(end 444.811658 -19.675094)
		(width 0.089408)
		(layer "In2.Cu")
		(net "FM_OC_DETECT_EN_N")
	)
	(segment
		(start 448.49034 -20.575016)
		(end 453.839072 -20.575016)
		(width 0.089408)
		(layer "In2.Cu")
		(net "FM_OC_DETECT_EN_N")
	)
	(segment
		(start 443.18809 -20.369784)
		(end 443.88278 -19.675094)
		(width 0.089408)
		(layer "In2.Cu")
		(net "FM_OC_DETECT_EN_N")
	)
	(segment
		(start 433.377848 -20.369784)
		(end 443.18809 -20.369784)
		(width 0.089408)
		(layer "In2.Cu")
		(net "FM_OC_DETECT_EN_N")
	)
	(segment
		(start 426.340016 -22.528276)
		(end 427.771306 -21.096986)
		(width 0.089408)
		(layer "In2.Cu")
		(net "FM_OC_DETECT_EN_N")
	)
	(segment
		(start 425.465748 -22.906482)
		(end 425.843954 -22.528276)
		(width 0.089408)
		(layer "In2.Cu")
		(net "FM_OC_DETECT_EN_N")
	)
	(segment
		(start 460.58074 -25.661366)
		(end 461.238854 -26.31948)
		(width 0.089408)
		(layer "In2.Cu")
		(net "FM_OC_DETECT_EN_N")
	)
	(segment
		(start 453.839072 -20.575016)
		(end 458.925422 -25.661366)
		(width 0.089408)
		(layer "In2.Cu")
		(net "FM_OC_DETECT_EN_N")
	)
	(segment
		(start 432.650646 -21.096986)
		(end 433.377848 -20.369784)
		(width 0.089408)
		(layer "In2.Cu")
		(net "FM_OC_DETECT_EN_N")
	)
	(segment
		(start 427.771306 -21.096986)
		(end 432.650646 -21.096986)
		(width 0.089408)
		(layer "In2.Cu")
		(net "FM_OC_DETECT_EN_N")
	)
	(segment
		(start 425.465748 -23.169626)
		(end 425.465748 -22.906482)
		(width 0.089408)
		(layer "In2.Cu")
		(net "FM_OC_DETECT_EN_N")
	)
	(segment
		(start 448.020186 -20.104862)
		(end 448.49034 -20.575016)
		(width 0.089408)
		(layer "In2.Cu")
		(net "FM_OC_DETECT_EN_N")
	)
	(segment
		(start 445.241426 -20.104862)
		(end 448.020186 -20.104862)
		(width 0.089408)
		(layer "In2.Cu")
		(net "FM_OC_DETECT_EN_N")
	)
	(segment
		(start 425.843954 -22.528276)
		(end 426.340016 -22.528276)
		(width 0.089408)
		(layer "In2.Cu")
		(net "FM_OC_DETECT_EN_N")
	)
	(segment
		(start 393.2174 -86.9188)
		(end 393.891262 -86.9188)
		(width 0.089408)
		(layer "In4.Cu")
		(net "FM_OC_DETECT_EN_N")
	)
	(segment
		(start 28.411932 5.158232)
		(end 26.543 3.2893)
		(width 0.089408)
		(layer "In4.Cu")
		(net "FM_OC_DETECT_EN_N")
	)
	(segment
		(start 165.297866 5.269992)
		(end 116.563648 5.269992)
		(width 0.089408)
		(layer "In4.Cu")
		(net "FM_OC_DETECT_EN_N")
	)
	(segment
		(start 400.64944 -85.098382)
		(end 402.637244 -85.098382)
		(width 0.089408)
		(layer "In4.Cu")
		(net "FM_OC_DETECT_EN_N")
	)
	(segment
		(start 178.4731 -2.229866)
		(end 178.4731 -2.2479)
		(width 0.089408)
		(layer "In4.Cu")
		(net "FM_OC_DETECT_EN_N")
	)
	(segment
		(start 170.2562 -1.7272)
		(end 168.646094 -0.117094)
		(width 0.089408)
		(layer "In4.Cu")
		(net "FM_OC_DETECT_EN_N")
	)
	(segment
		(start 396.669514 -85.363304)
		(end 398.845532 -85.363304)
		(width 0.089408)
		(layer "In4.Cu")
		(net "FM_OC_DETECT_EN_N")
	)
	(segment
		(start 398.845532 -85.363304)
		(end 399.278856 -84.92998)
		(width 0.089408)
		(layer "In4.Cu")
		(net "FM_OC_DETECT_EN_N")
	)
	(segment
		(start 402.637244 -85.098382)
		(end 402.91385 -85.374988)
		(width 0.089408)
		(layer "In4.Cu")
		(net "FM_OC_DETECT_EN_N")
	)
	(segment
		(start 178.4731 -1.7145)
		(end 178.4731 -1.884934)
		(width 0.089408)
		(layer "In4.Cu")
		(net "FM_OC_DETECT_EN_N")
	)
	(segment
		(start 407.147268 -86.26602)
		(end 408.729688 -86.26602)
		(width 0.089408)
		(layer "In4.Cu")
		(net "FM_OC_DETECT_EN_N")
	)
	(segment
		(start 399.278856 -84.92998)
		(end 400.481038 -84.92998)
		(width 0.089408)
		(layer "In4.Cu")
		(net "FM_OC_DETECT_EN_N")
	)
	(segment
		(start 178.091592 -2.629408)
		(end 173.467014 -2.629408)
		(width 0.089408)
		(layer "In4.Cu")
		(net "FM_OC_DETECT_EN_N")
	)
	(segment
		(start 405.331422 -85.838284)
		(end 406.719532 -85.838284)
		(width 0.089408)
		(layer "In4.Cu")
		(net "FM_OC_DETECT_EN_N")
	)
	(segment
		(start 406.719532 -85.838284)
		(end 407.147268 -86.26602)
		(width 0.089408)
		(layer "In4.Cu")
		(net "FM_OC_DETECT_EN_N")
	)
	(segment
		(start 402.91385 -85.374988)
		(end 404.868126 -85.374988)
		(width 0.089408)
		(layer "In4.Cu")
		(net "FM_OC_DETECT_EN_N")
	)
	(segment
		(start 115.895374 4.601718)
		(end 103.378762 4.601718)
		(width 0.089408)
		(layer "In4.Cu")
		(net "FM_OC_DETECT_EN_N")
	)
	(segment
		(start 167.4114 0.324358)
		(end 167.4114 0.7366)
		(width 0.089408)
		(layer "In4.Cu")
		(net "FM_OC_DETECT_EN_N")
	)
	(segment
		(start 173.467014 -2.629408)
		(end 172.564806 -1.7272)
		(width 0.089408)
		(layer "In4.Cu")
		(net "FM_OC_DETECT_EN_N")
	)
	(segment
		(start 178.479704 -1.891538)
		(end 178.479704 -2.223262)
		(width 0.089408)
		(layer "In4.Cu")
		(net "FM_OC_DETECT_EN_N")
	)
	(segment
		(start 400.481038 -84.92998)
		(end 400.64944 -85.098382)
		(width 0.089408)
		(layer "In4.Cu")
		(net "FM_OC_DETECT_EN_N")
	)
	(segment
		(start 166.56558 4.002278)
		(end 165.297866 5.269992)
		(width 0.089408)
		(layer "In4.Cu")
		(net "FM_OC_DETECT_EN_N")
	)
	(segment
		(start 178.479704 -2.223262)
		(end 178.4731 -2.229866)
		(width 0.089408)
		(layer "In4.Cu")
		(net "FM_OC_DETECT_EN_N")
	)
	(segment
		(start 168.646094 -0.117094)
		(end 167.852852 -0.117094)
		(width 0.089408)
		(layer "In4.Cu")
		(net "FM_OC_DETECT_EN_N")
	)
	(segment
		(start 396.146782 -85.886036)
		(end 396.669514 -85.363304)
		(width 0.089408)
		(layer "In4.Cu")
		(net "FM_OC_DETECT_EN_N")
	)
	(segment
		(start 167.4114 0.7366)
		(end 166.56558 1.58242)
		(width 0.089408)
		(layer "In4.Cu")
		(net "FM_OC_DETECT_EN_N")
	)
	(segment
		(start 393.891262 -86.9188)
		(end 394.924026 -85.886036)
		(width 0.089408)
		(layer "In4.Cu")
		(net "FM_OC_DETECT_EN_N")
	)
	(segment
		(start 178.4731 -1.884934)
		(end 178.479704 -1.891538)
		(width 0.089408)
		(layer "In4.Cu")
		(net "FM_OC_DETECT_EN_N")
	)
	(segment
		(start 167.852852 -0.117094)
		(end 167.4114 0.324358)
		(width 0.089408)
		(layer "In4.Cu")
		(net "FM_OC_DETECT_EN_N")
	)
	(segment
		(start 178.4731 -2.2479)
		(end 178.091592 -2.629408)
		(width 0.089408)
		(layer "In4.Cu")
		(net "FM_OC_DETECT_EN_N")
	)
	(segment
		(start 172.564806 -1.7272)
		(end 170.2562 -1.7272)
		(width 0.089408)
		(layer "In4.Cu")
		(net "FM_OC_DETECT_EN_N")
	)
	(segment
		(start 404.868126 -85.374988)
		(end 405.331422 -85.838284)
		(width 0.089408)
		(layer "In4.Cu")
		(net "FM_OC_DETECT_EN_N")
	)
	(segment
		(start 394.924026 -85.886036)
		(end 396.146782 -85.886036)
		(width 0.089408)
		(layer "In4.Cu")
		(net "FM_OC_DETECT_EN_N")
	)
	(segment
		(start 103.378762 4.601718)
		(end 102.822248 5.158232)
		(width 0.089408)
		(layer "In4.Cu")
		(net "FM_OC_DETECT_EN_N")
	)
	(segment
		(start 102.822248 5.158232)
		(end 28.411932 5.158232)
		(width 0.089408)
		(layer "In4.Cu")
		(net "FM_OC_DETECT_EN_N")
	)
	(segment
		(start 166.56558 1.58242)
		(end 166.56558 4.002278)
		(width 0.089408)
		(layer "In4.Cu")
		(net "FM_OC_DETECT_EN_N")
	)
	(segment
		(start 178.9303 -1.2573)
		(end 178.4731 -1.7145)
		(width 0.089408)
		(layer "In4.Cu")
		(net "FM_OC_DETECT_EN_N")
	)
	(segment
		(start 26.543 3.2893)
		(end 26.543 0.4699)
		(width 0.089408)
		(layer "In4.Cu")
		(net "FM_OC_DETECT_EN_N")
	)
	(segment
		(start 116.563648 5.269992)
		(end 115.895374 4.601718)
		(width 0.089408)
		(layer "In4.Cu")
		(net "FM_OC_DETECT_EN_N")
	)
	(segment
		(start 414.910524 -60.240672)
		(end 414.910524 -58.692542)
		(width 0.089408)
		(layer "In9.Cu")
		(net "FM_OC_DETECT_EN_N")
	)
	(segment
		(start 463.04327 -42.779188)
		(end 462.267046 -42.779188)
		(width 0.089408)
		(layer "In9.Cu")
		(net "FM_OC_DETECT_EN_N")
	)
	(segment
		(start 326.8726 4.445)
		(end 323.648832 4.445)
		(width 0.089408)
		(layer "In9.Cu")
		(net "FM_OC_DETECT_EN_N")
	)
	(segment
		(start 27.83586 -59.473592)
		(end 28.05938 -59.250072)
		(width 0.089408)
		(layer "In9.Cu")
		(net "FM_OC_DETECT_EN_N")
	)
	(segment
		(start 457.892912 -40.977312)
		(end 459.211172 -39.659052)
		(width 0.089408)
		(layer "In9.Cu")
		(net "FM_OC_DETECT_EN_N")
	)
	(segment
		(start 457.47432 -43.3324)
		(end 457.892912 -42.913808)
		(width 0.089408)
		(layer "In9.Cu")
		(net "FM_OC_DETECT_EN_N")
	)
	(segment
		(start 415.055304 -61.63564)
		(end 415.055304 -60.385452)
		(width 0.089408)
		(layer "In9.Cu")
		(net "FM_OC_DETECT_EN_N")
	)
	(segment
		(start 464.0834 -2.607056)
		(end 464.0834 -3.249422)
		(width 0.089408)
		(layer "In9.Cu")
		(net "FM_OC_DETECT_EN_N")
	)
	(segment
		(start 463.747104 -45.793152)
		(end 463.747104 -43.483022)
		(width 0.089408)
		(layer "In9.Cu")
		(net "FM_OC_DETECT_EN_N")
	)
	(segment
		(start 466.875114 -4.002786)
		(end 468.171784 -5.299456)
		(width 0.089408)
		(layer "In9.Cu")
		(net "FM_OC_DETECT_EN_N")
	)
	(segment
		(start 418.216588 -55.386478)
		(end 419.329362 -55.386478)
		(width 0.089408)
		(layer "In9.Cu")
		(net "FM_OC_DETECT_EN_N")
	)
	(segment
		(start 413.512 -70.992746)
		(end 414.138364 -70.366382)
		(width 0.089408)
		(layer "In9.Cu")
		(net "FM_OC_DETECT_EN_N")
	)
	(segment
		(start 408.729688 -83.553808)
		(end 413.76219 -78.521306)
		(width 0.089408)
		(layer "In9.Cu")
		(net "FM_OC_DETECT_EN_N")
	)
	(segment
		(start 459.211172 -39.45382)
		(end 460.6036 -38.061392)
		(width 0.089408)
		(layer "In9.Cu")
		(net "FM_OC_DETECT_EN_N")
	)
	(segment
		(start 469.372696 -8.13435)
		(end 474.097096 -8.13435)
		(width 0.089408)
		(layer "In9.Cu")
		(net "FM_OC_DETECT_EN_N")
	)
	(segment
		(start 457.633578 -44.095924)
		(end 457.47432 -43.936666)
		(width 0.089408)
		(layer "In9.Cu")
		(net "FM_OC_DETECT_EN_N")
	)
	(segment
		(start 464.0834 -3.249422)
		(end 464.836764 -4.002786)
		(width 0.089408)
		(layer "In9.Cu")
		(net "FM_OC_DETECT_EN_N")
	)
	(segment
		(start 464.836764 -4.002786)
		(end 466.875114 -4.002786)
		(width 0.089408)
		(layer "In9.Cu")
		(net "FM_OC_DETECT_EN_N")
	)
	(segment
		(start 414.910524 -58.692542)
		(end 418.216588 -55.386478)
		(width 0.089408)
		(layer "In9.Cu")
		(net "FM_OC_DETECT_EN_N")
	)
	(segment
		(start 179.6542 1.286256)
		(end 179.6542 -0.5334)
		(width 0.089408)
		(layer "In9.Cu")
		(net "FM_OC_DETECT_EN_N")
	)
	(segment
		(start 457.892912 -42.913808)
		(end 457.892912 -40.977312)
		(width 0.089408)
		(layer "In9.Cu")
		(net "FM_OC_DETECT_EN_N")
	)
	(segment
		(start 28.05938 -55.946548)
		(end 27.65552 -55.542688)
		(width 0.089408)
		(layer "In9.Cu")
		(net "FM_OC_DETECT_EN_N")
	)
	(segment
		(start 28.05938 -59.250072)
		(end 28.05938 -55.946548)
		(width 0.089408)
		(layer "In9.Cu")
		(net "FM_OC_DETECT_EN_N")
	)
	(segment
		(start 435.874414 -51.905916)
		(end 439.126122 -48.654208)
		(width 0.089408)
		(layer "In9.Cu")
		(net "FM_OC_DETECT_EN_N")
	)
	(segment
		(start 468.171784 -6.933438)
		(end 469.372696 -8.13435)
		(width 0.089408)
		(layer "In9.Cu")
		(net "FM_OC_DETECT_EN_N")
	)
	(segment
		(start 435.837076 -51.905916)
		(end 435.874414 -51.905916)
		(width 0.089408)
		(layer "In9.Cu")
		(net "FM_OC_DETECT_EN_N")
	)
	(segment
		(start 27.65552 -55.542688)
		(end 27.65552 -54.55412)
		(width 0.089408)
		(layer "In9.Cu")
		(net "FM_OC_DETECT_EN_N")
	)
	(segment
		(start 414.910524 -61.78042)
		(end 415.055304 -61.63564)
		(width 0.089408)
		(layer "In9.Cu")
		(net "FM_OC_DETECT_EN_N")
	)
	(segment
		(start 414.138364 -68.071238)
		(end 414.705038 -67.504564)
		(width 0.089408)
		(layer "In9.Cu")
		(net "FM_OC_DETECT_EN_N")
	)
	(segment
		(start 476.173546 -10.2108)
		(end 477.2152 -10.2108)
		(width 0.089408)
		(layer "In9.Cu")
		(net "FM_OC_DETECT_EN_N")
	)
	(segment
		(start 327.0758 4.2418)
		(end 326.8726 4.445)
		(width 0.089408)
		(layer "In9.Cu")
		(net "FM_OC_DETECT_EN_N")
	)
	(segment
		(start 474.097096 -8.13435)
		(end 476.173546 -10.2108)
		(width 0.089408)
		(layer "In9.Cu")
		(net "FM_OC_DETECT_EN_N")
	)
	(segment
		(start 27.10434 -73.65746)
		(end 27.10434 -67.775328)
		(width 0.089408)
		(layer "In9.Cu")
		(net "FM_OC_DETECT_EN_N")
	)
	(segment
		(start 408.729688 -86.26602)
		(end 408.729688 -83.553808)
		(width 0.089408)
		(layer "In9.Cu")
		(net "FM_OC_DETECT_EN_N")
	)
	(segment
		(start 181.088792 2.720848)
		(end 179.6542 1.286256)
		(width 0.089408)
		(layer "In9.Cu")
		(net "FM_OC_DETECT_EN_N")
	)
	(segment
		(start 414.910524 -63.693548)
		(end 414.910524 -61.78042)
		(width 0.089408)
		(layer "In9.Cu")
		(net "FM_OC_DETECT_EN_N")
	)
	(segment
		(start 26.707338 -53.605938)
		(end 26.036778 -53.605938)
		(width 0.089408)
		(layer "In9.Cu")
		(net "FM_OC_DETECT_EN_N")
	)
	(segment
		(start 28.436062 -62.52845)
		(end 27.83586 -61.928248)
		(width 0.089408)
		(layer "In9.Cu")
		(net "FM_OC_DETECT_EN_N")
	)
	(segment
		(start 462.267046 -42.779188)
		(end 461.319626 -43.726608)
		(width 0.089408)
		(layer "In9.Cu")
		(net "FM_OC_DETECT_EN_N")
	)
	(segment
		(start 413.76219 -72.25919)
		(end 413.512 -72.009)
		(width 0.089408)
		(layer "In9.Cu")
		(net "FM_OC_DETECT_EN_N")
	)
	(segment
		(start 464.531456 -2.159)
		(end 464.0834 -2.607056)
		(width 0.089408)
		(layer "In9.Cu")
		(net "FM_OC_DETECT_EN_N")
	)
	(segment
		(start 323.648832 4.445)
		(end 322.595748 5.498084)
		(width 0.089408)
		(layer "In9.Cu")
		(net "FM_OC_DETECT_EN_N")
	)
	(segment
		(start 25.989788 -75.051412)
		(end 25.989788 -74.772012)
		(width 0.089408)
		(layer "In9.Cu")
		(net "FM_OC_DETECT_EN_N")
	)
	(segment
		(start 423.670222 -54.765194)
		(end 424.67784 -53.757576)
		(width 0.089408)
		(layer "In9.Cu")
		(net "FM_OC_DETECT_EN_N")
	)
	(segment
		(start 468.171784 -5.299456)
		(end 468.171784 -6.933438)
		(width 0.089408)
		(layer "In9.Cu")
		(net "FM_OC_DETECT_EN_N")
	)
	(segment
		(start 25.989788 -74.772012)
		(end 27.10434 -73.65746)
		(width 0.089408)
		(layer "In9.Cu")
		(net "FM_OC_DETECT_EN_N")
	)
	(segment
		(start 460.886048 -48.654208)
		(end 463.747104 -45.793152)
		(width 0.089408)
		(layer "In9.Cu")
		(net "FM_OC_DETECT_EN_N")
	)
	(segment
		(start 27.10434 -67.775328)
		(end 28.436062 -66.443606)
		(width 0.089408)
		(layer "In9.Cu")
		(net "FM_OC_DETECT_EN_N")
	)
	(segment
		(start 419.950646 -54.765194)
		(end 423.670222 -54.765194)
		(width 0.089408)
		(layer "In9.Cu")
		(net "FM_OC_DETECT_EN_N")
	)
	(segment
		(start 439.126122 -48.654208)
		(end 460.886048 -48.654208)
		(width 0.089408)
		(layer "In9.Cu")
		(net "FM_OC_DETECT_EN_N")
	)
	(segment
		(start 466.5218 -2.159)
		(end 464.531456 -2.159)
		(width 0.089408)
		(layer "In9.Cu")
		(net "FM_OC_DETECT_EN_N")
	)
	(segment
		(start 463.54746 -27.6479)
		(end 463.54746 -26.31948)
		(width 0.089408)
		(layer "In9.Cu")
		(net "FM_OC_DETECT_EN_N")
	)
	(segment
		(start 461.319626 -43.726608)
		(end 460.285592 -43.726608)
		(width 0.089408)
		(layer "In9.Cu")
		(net "FM_OC_DETECT_EN_N")
	)
	(segment
		(start 460.6036 -36.31565)
		(end 462.734406 -34.184844)
		(width 0.089408)
		(layer "In9.Cu")
		(net "FM_OC_DETECT_EN_N")
	)
	(segment
		(start 322.595748 5.498084)
		(end 183.06542 5.498084)
		(width 0.089408)
		(layer "In9.Cu")
		(net "FM_OC_DETECT_EN_N")
	)
	(segment
		(start 27.65552 -54.55412)
		(end 26.707338 -53.605938)
		(width 0.089408)
		(layer "In9.Cu")
		(net "FM_OC_DETECT_EN_N")
	)
	(segment
		(start 463.747104 -43.483022)
		(end 463.04327 -42.779188)
		(width 0.089408)
		(layer "In9.Cu")
		(net "FM_OC_DETECT_EN_N")
	)
	(segment
		(start 179.6542 -0.5334)
		(end 178.9303 -1.2573)
		(width 0.089408)
		(layer "In9.Cu")
		(net "FM_OC_DETECT_EN_N")
	)
	(segment
		(start 459.916276 -44.095924)
		(end 457.633578 -44.095924)
		(width 0.089408)
		(layer "In9.Cu")
		(net "FM_OC_DETECT_EN_N")
	)
	(segment
		(start 460.285592 -43.726608)
		(end 459.916276 -44.095924)
		(width 0.089408)
		(layer "In9.Cu")
		(net "FM_OC_DETECT_EN_N")
	)
	(segment
		(start 414.705038 -67.504564)
		(end 414.705038 -63.899034)
		(width 0.089408)
		(layer "In9.Cu")
		(net "FM_OC_DETECT_EN_N")
	)
	(segment
		(start 414.138364 -70.366382)
		(end 414.138364 -68.071238)
		(width 0.089408)
		(layer "In9.Cu")
		(net "FM_OC_DETECT_EN_N")
	)
	(segment
		(start 183.06542 5.498084)
		(end 181.088792 3.521456)
		(width 0.089408)
		(layer "In9.Cu")
		(net "FM_OC_DETECT_EN_N")
	)
	(segment
		(start 466.8266 -2.4638)
		(end 466.5218 -2.159)
		(width 0.089408)
		(layer "In9.Cu")
		(net "FM_OC_DETECT_EN_N")
	)
	(segment
		(start 457.47432 -43.936666)
		(end 457.47432 -43.3324)
		(width 0.089408)
		(layer "In9.Cu")
		(net "FM_OC_DETECT_EN_N")
	)
	(segment
		(start 435.783482 -51.95951)
		(end 435.837076 -51.905916)
		(width 0.089408)
		(layer "In9.Cu")
		(net "FM_OC_DETECT_EN_N")
	)
	(segment
		(start 419.329362 -55.386478)
		(end 419.950646 -54.765194)
		(width 0.089408)
		(layer "In9.Cu")
		(net "FM_OC_DETECT_EN_N")
	)
	(segment
		(start 415.055304 -60.385452)
		(end 414.910524 -60.240672)
		(width 0.089408)
		(layer "In9.Cu")
		(net "FM_OC_DETECT_EN_N")
	)
	(segment
		(start 414.705038 -63.899034)
		(end 414.910524 -63.693548)
		(width 0.089408)
		(layer "In9.Cu")
		(net "FM_OC_DETECT_EN_N")
	)
	(segment
		(start 462.734406 -34.184844)
		(end 462.734406 -28.460954)
		(width 0.089408)
		(layer "In9.Cu")
		(net "FM_OC_DETECT_EN_N")
	)
	(segment
		(start 459.211172 -39.659052)
		(end 459.211172 -39.45382)
		(width 0.089408)
		(layer "In9.Cu")
		(net "FM_OC_DETECT_EN_N")
	)
	(segment
		(start 181.088792 3.521456)
		(end 181.088792 2.720848)
		(width 0.089408)
		(layer "In9.Cu")
		(net "FM_OC_DETECT_EN_N")
	)
	(segment
		(start 27.83586 -61.928248)
		(end 27.83586 -59.473592)
		(width 0.089408)
		(layer "In9.Cu")
		(net "FM_OC_DETECT_EN_N")
	)
	(segment
		(start 413.512 -72.009)
		(end 413.512 -70.992746)
		(width 0.089408)
		(layer "In9.Cu")
		(net "FM_OC_DETECT_EN_N")
	)
	(segment
		(start 427.748954 -51.95951)
		(end 435.783482 -51.95951)
		(width 0.089408)
		(layer "In9.Cu")
		(net "FM_OC_DETECT_EN_N")
	)
	(segment
		(start 413.76219 -78.521306)
		(end 413.76219 -72.25919)
		(width 0.089408)
		(layer "In9.Cu")
		(net "FM_OC_DETECT_EN_N")
	)
	(segment
		(start 460.6036 -38.061392)
		(end 460.6036 -36.31565)
		(width 0.089408)
		(layer "In9.Cu")
		(net "FM_OC_DETECT_EN_N")
	)
	(segment
		(start 462.734406 -28.460954)
		(end 463.54746 -27.6479)
		(width 0.089408)
		(layer "In9.Cu")
		(net "FM_OC_DETECT_EN_N")
	)
	(segment
		(start 424.67784 -53.757576)
		(end 425.950888 -53.757576)
		(width 0.089408)
		(layer "In9.Cu")
		(net "FM_OC_DETECT_EN_N")
	)
	(segment
		(start 425.950888 -53.757576)
		(end 427.748954 -51.95951)
		(width 0.089408)
		(layer "In9.Cu")
		(net "FM_OC_DETECT_EN_N")
	)
	(segment
		(start 28.436062 -66.443606)
		(end 28.436062 -62.52845)
		(width 0.089408)
		(layer "In9.Cu")
		(net "FM_OC_DETECT_EN_N")
	)
	(segment
		(start 448.343528 -3.76174)
		(end 447.271902 -3.76174)
		(width 0.089408)
		(layer "In11.Cu")
		(net "FM_OC_DETECT_EN_N")
	)
	(segment
		(start 364.012988 -27.726132)
		(end 355.592888 -36.146232)
		(width 0.089408)
		(layer "In11.Cu")
		(net "FM_OC_DETECT_EN_N")
	)
	(segment
		(start 403.85873 -7.769098)
		(end 403.700742 -7.769098)
		(width 0.089408)
		(layer "In11.Cu")
		(net "FM_OC_DETECT_EN_N")
	)
	(segment
		(start 460.699104 -1.464818)
		(end 460.088742 -1.464818)
		(width 0.089408)
		(layer "In11.Cu")
		(net "FM_OC_DETECT_EN_N")
	)
	(segment
		(start 395.979396 -7.768844)
		(end 393.074398 -10.673842)
		(width 0.089408)
		(layer "In11.Cu")
		(net "FM_OC_DETECT_EN_N")
	)
	(segment
		(start 461.617822 -0.578612)
		(end 461.617822 -0.94742)
		(width 0.089408)
		(layer "In11.Cu")
		(net "FM_OC_DETECT_EN_N")
	)
	(segment
		(start 29.0322 -22.048216)
		(end 29.0322 -29.0322)
		(width 0.089408)
		(layer "In11.Cu")
		(net "FM_OC_DETECT_EN_N")
	)
	(segment
		(start 332.733904 -12.133834)
		(end 330.607416 -10.007346)
		(width 0.089408)
		(layer "In11.Cu")
		(net "FM_OC_DETECT_EN_N")
	)
	(segment
		(start 26.69159 -31.37281)
		(end 26.69159 -43.58259)
		(width 0.089408)
		(layer "In11.Cu")
		(net "FM_OC_DETECT_EN_N")
	)
	(segment
		(start 418.10813 -4.801616)
		(end 416.826192 -6.083554)
		(width 0.089408)
		(layer "In11.Cu")
		(net "FM_OC_DETECT_EN_N")
	)
	(segment
		(start 336.425032 -35.88766)
		(end 331.696568 -31.159196)
		(width 0.089408)
		(layer "In11.Cu")
		(net "FM_OC_DETECT_EN_N")
	)
	(segment
		(start 461.10017 -1.465072)
		(end 460.699358 -1.465072)
		(width 0.089408)
		(layer "In11.Cu")
		(net "FM_OC_DETECT_EN_N")
	)
	(segment
		(start 424.50766 -4.801616)
		(end 418.10813 -4.801616)
		(width 0.089408)
		(layer "In11.Cu")
		(net "FM_OC_DETECT_EN_N")
	)
	(segment
		(start 378.389134 -10.673842)
		(end 375.730008 -8.014716)
		(width 0.089408)
		(layer "In11.Cu")
		(net "FM_OC_DETECT_EN_N")
	)
	(segment
		(start 463.6135 0.3937)
		(end 463.1309 0.3937)
		(width 0.089408)
		(layer "In11.Cu")
		(net "FM_OC_DETECT_EN_N")
	)
	(segment
		(start 464.120992 -0.113792)
		(end 463.6135 0.3937)
		(width 0.089408)
		(layer "In11.Cu")
		(net "FM_OC_DETECT_EN_N")
	)
	(segment
		(start 462.604104 -0.133096)
		(end 462.063338 -0.133096)
		(width 0.089408)
		(layer "In11.Cu")
		(net "FM_OC_DETECT_EN_N")
	)
	(segment
		(start 375.730008 -8.014716)
		(end 373.192294 -8.014716)
		(width 0.089408)
		(layer "In11.Cu")
		(net "FM_OC_DETECT_EN_N")
	)
	(segment
		(start 27.37485 -20.390866)
		(end 29.0322 -22.048216)
		(width 0.089408)
		(layer "In11.Cu")
		(net "FM_OC_DETECT_EN_N")
	)
	(segment
		(start 331.696568 -21.559266)
		(end 332.733904 -20.52193)
		(width 0.089408)
		(layer "In11.Cu")
		(net "FM_OC_DETECT_EN_N")
	)
	(segment
		(start 337.762342 -36.146232)
		(end 337.50377 -35.88766)
		(width 0.089408)
		(layer "In11.Cu")
		(net "FM_OC_DETECT_EN_N")
	)
	(segment
		(start 405.169878 -6.45795)
		(end 403.85873 -7.769098)
		(width 0.089408)
		(layer "In11.Cu")
		(net "FM_OC_DETECT_EN_N")
	)
	(segment
		(start 27.3685 -47.8155)
		(end 28.2702 -48.7172)
		(width 0.089408)
		(layer "In11.Cu")
		(net "FM_OC_DETECT_EN_N")
	)
	(segment
		(start 460.088742 -1.464818)
		(end 459.658212 -1.034288)
		(width 0.089408)
		(layer "In11.Cu")
		(net "FM_OC_DETECT_EN_N")
	)
	(segment
		(start 332.733904 -20.52193)
		(end 332.733904 -12.133834)
		(width 0.089408)
		(layer "In11.Cu")
		(net "FM_OC_DETECT_EN_N")
	)
	(segment
		(start 414.400238 -6.083554)
		(end 413.6517 -5.335016)
		(width 0.089408)
		(layer "In11.Cu")
		(net "FM_OC_DETECT_EN_N")
	)
	(segment
		(start 466.8266 -2.4638)
		(end 466.598 -2.2352)
		(width 0.089408)
		(layer "In11.Cu")
		(net "FM_OC_DETECT_EN_N")
	)
	(segment
		(start 413.6517 -5.335016)
		(end 405.57704 -5.335016)
		(width 0.089408)
		(layer "In11.Cu")
		(net "FM_OC_DETECT_EN_N")
	)
	(segment
		(start 461.617822 -0.94742)
		(end 461.10017 -1.465072)
		(width 0.089408)
		(layer "In11.Cu")
		(net "FM_OC_DETECT_EN_N")
	)
	(segment
		(start 440.838336 -3.761994)
		(end 440.255914 -4.344416)
		(width 0.089408)
		(layer "In11.Cu")
		(net "FM_OC_DETECT_EN_N")
	)
	(segment
		(start 26.595578 -53.605938)
		(end 26.036778 -53.605938)
		(width 0.089408)
		(layer "In11.Cu")
		(net "FM_OC_DETECT_EN_N")
	)
	(segment
		(start 466.598 -2.2352)
		(end 465.709 -2.2352)
		(width 0.089408)
		(layer "In11.Cu")
		(net "FM_OC_DETECT_EN_N")
	)
	(segment
		(start 405.169878 -5.742178)
		(end 405.169878 -6.45795)
		(width 0.089408)
		(layer "In11.Cu")
		(net "FM_OC_DETECT_EN_N")
	)
	(segment
		(start 28.2702 -51.931316)
		(end 26.595578 -53.605938)
		(width 0.089408)
		(layer "In11.Cu")
		(net "FM_OC_DETECT_EN_N")
	)
	(segment
		(start 29.0322 -29.0322)
		(end 26.69159 -31.37281)
		(width 0.089408)
		(layer "In11.Cu")
		(net "FM_OC_DETECT_EN_N")
	)
	(segment
		(start 327.0758 4.209034)
		(end 327.0758 4.2418)
		(width 0.089408)
		(layer "In11.Cu")
		(net "FM_OC_DETECT_EN_N")
	)
	(segment
		(start 26.496264 -14.956282)
		(end 27.37485 -15.834868)
		(width 0.089408)
		(layer "In11.Cu")
		(net "FM_OC_DETECT_EN_N")
	)
	(segment
		(start 372.553484 -8.653526)
		(end 372.553484 -11.176508)
		(width 0.089408)
		(layer "In11.Cu")
		(net "FM_OC_DETECT_EN_N")
	)
	(segment
		(start 372.553484 -11.176508)
		(end 364.012988 -19.717004)
		(width 0.089408)
		(layer "In11.Cu")
		(net "FM_OC_DETECT_EN_N")
	)
	(segment
		(start 364.012988 -19.717004)
		(end 364.012988 -27.726132)
		(width 0.089408)
		(layer "In11.Cu")
		(net "FM_OC_DETECT_EN_N")
	)
	(segment
		(start 451.07098 -1.034288)
		(end 448.343528 -3.76174)
		(width 0.089408)
		(layer "In11.Cu")
		(net "FM_OC_DETECT_EN_N")
	)
	(segment
		(start 464.120992 -1.105408)
		(end 464.120992 -0.113792)
		(width 0.089408)
		(layer "In11.Cu")
		(net "FM_OC_DETECT_EN_N")
	)
	(segment
		(start 26.496264 0.423164)
		(end 26.496264 -14.956282)
		(width 0.089408)
		(layer "In11.Cu")
		(net "FM_OC_DETECT_EN_N")
	)
	(segment
		(start 464.947 -1.4732)
		(end 464.488784 -1.4732)
		(width 0.089408)
		(layer "In11.Cu")
		(net "FM_OC_DETECT_EN_N")
	)
	(segment
		(start 416.826192 -6.083554)
		(end 414.400238 -6.083554)
		(width 0.089408)
		(layer "In11.Cu")
		(net "FM_OC_DETECT_EN_N")
	)
	(segment
		(start 330.607416 -10.007346)
		(end 330.607416 -6.006592)
		(width 0.089408)
		(layer "In11.Cu")
		(net "FM_OC_DETECT_EN_N")
	)
	(segment
		(start 405.57704 -5.335016)
		(end 405.169878 -5.742178)
		(width 0.089408)
		(layer "In11.Cu")
		(net "FM_OC_DETECT_EN_N")
	)
	(segment
		(start 26.69159 -43.58259)
		(end 27.3685 -44.2595)
		(width 0.089408)
		(layer "In11.Cu")
		(net "FM_OC_DETECT_EN_N")
	)
	(segment
		(start 460.699358 -1.465072)
		(end 460.699104 -1.464818)
		(width 0.089408)
		(layer "In11.Cu")
		(net "FM_OC_DETECT_EN_N")
	)
	(segment
		(start 393.074398 -10.673842)
		(end 378.389134 -10.673842)
		(width 0.089408)
		(layer "In11.Cu")
		(net "FM_OC_DETECT_EN_N")
	)
	(segment
		(start 447.271902 -3.76174)
		(end 447.271648 -3.761994)
		(width 0.089408)
		(layer "In11.Cu")
		(net "FM_OC_DETECT_EN_N")
	)
	(segment
		(start 440.255914 -4.344416)
		(end 424.96486 -4.344416)
		(width 0.089408)
		(layer "In11.Cu")
		(net "FM_OC_DETECT_EN_N")
	)
	(segment
		(start 464.488784 -1.4732)
		(end 464.120992 -1.105408)
		(width 0.089408)
		(layer "In11.Cu")
		(net "FM_OC_DETECT_EN_N")
	)
	(segment
		(start 337.50377 -35.88766)
		(end 336.425032 -35.88766)
		(width 0.089408)
		(layer "In11.Cu")
		(net "FM_OC_DETECT_EN_N")
	)
	(segment
		(start 403.700742 -7.769098)
		(end 403.700488 -7.768844)
		(width 0.089408)
		(layer "In11.Cu")
		(net "FM_OC_DETECT_EN_N")
	)
	(segment
		(start 27.3685 -44.2595)
		(end 27.3685 -47.8155)
		(width 0.089408)
		(layer "In11.Cu")
		(net "FM_OC_DETECT_EN_N")
	)
	(segment
		(start 462.063338 -0.133096)
		(end 461.617822 -0.578612)
		(width 0.089408)
		(layer "In11.Cu")
		(net "FM_OC_DETECT_EN_N")
	)
	(segment
		(start 27.37485 -15.834868)
		(end 27.37485 -20.390866)
		(width 0.089408)
		(layer "In11.Cu")
		(net "FM_OC_DETECT_EN_N")
	)
	(segment
		(start 331.696568 -31.159196)
		(end 331.696568 -21.559266)
		(width 0.089408)
		(layer "In11.Cu")
		(net "FM_OC_DETECT_EN_N")
	)
	(segment
		(start 447.271648 -3.761994)
		(end 440.838336 -3.761994)
		(width 0.089408)
		(layer "In11.Cu")
		(net "FM_OC_DETECT_EN_N")
	)
	(segment
		(start 465.709 -2.2352)
		(end 464.947 -1.4732)
		(width 0.089408)
		(layer "In11.Cu")
		(net "FM_OC_DETECT_EN_N")
	)
	(segment
		(start 463.1309 0.3937)
		(end 462.604104 -0.133096)
		(width 0.089408)
		(layer "In11.Cu")
		(net "FM_OC_DETECT_EN_N")
	)
	(segment
		(start 355.592888 -36.146232)
		(end 337.762342 -36.146232)
		(width 0.089408)
		(layer "In11.Cu")
		(net "FM_OC_DETECT_EN_N")
	)
	(segment
		(start 459.658212 -1.034288)
		(end 451.07098 -1.034288)
		(width 0.089408)
		(layer "In11.Cu")
		(net "FM_OC_DETECT_EN_N")
	)
	(segment
		(start 28.2702 -48.7172)
		(end 28.2702 -51.931316)
		(width 0.089408)
		(layer "In11.Cu")
		(net "FM_OC_DETECT_EN_N")
	)
	(segment
		(start 330.607416 -6.006592)
		(end 328.99096 -4.390136)
		(width 0.089408)
		(layer "In11.Cu")
		(net "FM_OC_DETECT_EN_N")
	)
	(segment
		(start 403.700488 -7.768844)
		(end 395.979396 -7.768844)
		(width 0.089408)
		(layer "In11.Cu")
		(net "FM_OC_DETECT_EN_N")
	)
	(segment
		(start 373.192294 -8.014716)
		(end 372.553484 -8.653526)
		(width 0.089408)
		(layer "In11.Cu")
		(net "FM_OC_DETECT_EN_N")
	)
	(segment
		(start 328.99096 2.293874)
		(end 327.0758 4.209034)
		(width 0.089408)
		(layer "In11.Cu")
		(net "FM_OC_DETECT_EN_N")
	)
	(segment
		(start 328.99096 -4.390136)
		(end 328.99096 2.293874)
		(width 0.089408)
		(layer "In11.Cu")
		(net "FM_OC_DETECT_EN_N")
	)
	(segment
		(start 424.96486 -4.344416)
		(end 424.50766 -4.801616)
		(width 0.089408)
		(layer "In11.Cu")
		(net "FM_OC_DETECT_EN_N")
	)
	(segment
		(start 26.543 0.4699)
		(end 26.496264 0.423164)
		(width 0.089408)
		(layer "In11.Cu")
		(net "FM_OC_DETECT_EN_N")
	)
	(segment
		(start 476.4024 -149.479)
		(end 476.433134 -149.448266)
		(width 0.10795)
		(layer "F.Cu")
		(net "FM_CPLD_DBG_PWR_EN_R_N")
	)
	(segment
		(start 476.433134 -149.448266)
		(end 477.184212 -149.448266)
		(width 0.10795)
		(layer "F.Cu")
		(net "FM_CPLD_DBG_PWR_EN_R_N")
	)
	(segment
		(start 477.264984 -149.367494)
		(end 477.978724 -149.367494)
		(width 0.10795)
		(layer "F.Cu")
		(net "FM_CPLD_DBG_PWR_EN_R_N")
	)
	(segment
		(start 477.184212 -149.448266)
		(end 477.264984 -149.367494)
		(width 0.10795)
		(layer "F.Cu")
		(net "FM_CPLD_DBG_PWR_EN_R_N")
	)
	(via
		(at 473.7862 -148.5773)
		(size 0.6604)
		(drill 0.3302)
		(layers "F.Cu" "B.Cu")
		(net "FM_CPLD_DBG_PWR_EN_R_N")
	)
	(via
		(at 476.4024 -149.479)
		(size 0.508)
		(drill 0.254)
		(layers "F.Cu" "B.Cu")
		(net "FM_CPLD_DBG_PWR_EN_R_N")
	)
	(segment
		(start 475.51721 -149.524466)
		(end 476.356934 -149.524466)
		(width 0.10795)
		(layer "B.Cu")
		(net "FM_CPLD_DBG_PWR_EN_R_N")
	)
	(segment
		(start 476.356934 -149.524466)
		(end 476.4024 -149.479)
		(width 0.10795)
		(layer "B.Cu")
		(net "FM_CPLD_DBG_PWR_EN_R_N")
	)
	(segment
		(start 473.7862 -148.5773)
		(end 474.2942 -148.5773)
		(width 0.10795)
		(layer "B.Cu")
		(net "FM_CPLD_DBG_PWR_EN_R_N")
	)
	(segment
		(start 474.589602 -148.872702)
		(end 474.589602 -149.253702)
		(width 0.10795)
		(layer "B.Cu")
		(net "FM_CPLD_DBG_PWR_EN_R_N")
	)
	(segment
		(start 474.2942 -148.5773)
		(end 474.589602 -148.872702)
		(width 0.10795)
		(layer "B.Cu")
		(net "FM_CPLD_DBG_PWR_EN_R_N")
	)
	(segment
		(start 474.589602 -149.253702)
		(end 474.860366 -149.524466)
		(width 0.10795)
		(layer "B.Cu")
		(net "FM_CPLD_DBG_PWR_EN_R_N")
	)
	(segment
		(start 474.860366 -149.524466)
		(end 475.51721 -149.524466)
		(width 0.10795)
		(layer "B.Cu")
		(net "FM_CPLD_DBG_PWR_EN_R_N")
	)
	(segment
		(start 375.372122 -100.175822)
		(end 375.637806 -100.175822)
		(width 0.10795)
		(layer "F.Cu")
		(net "FM_BMC_CPLD_MP_RST_N")
	)
	(segment
		(start 402.7805 -38.59276)
		(end 402.7805 -37.9984)
		(width 0.10795)
		(layer "F.Cu")
		(net "FM_BMC_CPLD_MP_RST_N")
	)
	(segment
		(start 394.71854 -43.560492)
		(end 394.721588 -43.560492)
		(width 0.10795)
		(layer "F.Cu")
		(net "FM_BMC_CPLD_MP_RST_N")
	)
	(segment
		(start 407.49855 -36.526216)
		(end 407.890218 -36.134548)
		(width 0.10795)
		(layer "F.Cu")
		(net "FM_BMC_CPLD_MP_RST_N")
	)
	(segment
		(start 394.71854 -43.955462)
		(end 394.71854 -43.758612)
		(width 0.10795)
		(layer "F.Cu")
		(net "FM_BMC_CPLD_MP_RST_N")
	)
	(segment
		(start 375.637806 -100.175822)
		(end 375.825766 -99.987862)
		(width 0.10795)
		(layer "F.Cu")
		(net "FM_BMC_CPLD_MP_RST_N")
	)
	(segment
		(start 402.7805 -37.9984)
		(end 403.68347 -37.9984)
		(width 0.10795)
		(layer "F.Cu")
		(net "FM_BMC_CPLD_MP_RST_N")
	)
	(segment
		(start 390.701022 -46.502828)
		(end 392.035538 -45.168312)
		(width 0.10795)
		(layer "F.Cu")
		(net "FM_BMC_CPLD_MP_RST_N")
	)
	(segment
		(start 385.341368 -48.519334)
		(end 387.357874 -46.502828)
		(width 0.10795)
		(layer "F.Cu")
		(net "FM_BMC_CPLD_MP_RST_N")
	)
	(segment
		(start 376.219212 -99.5172)
		(end 376.5042 -99.5172)
		(width 0.10795)
		(layer "F.Cu")
		(net "FM_BMC_CPLD_MP_RST_N")
	)
	(segment
		(start 398.231614 -40.905176)
		(end 400.468084 -40.905176)
		(width 0.10795)
		(layer "F.Cu")
		(net "FM_BMC_CPLD_MP_RST_N")
	)
	(segment
		(start 383.7432 -49.10582)
		(end 384.04038 -49.403)
		(width 0.10795)
		(layer "F.Cu")
		(net "FM_BMC_CPLD_MP_RST_N")
	)
	(segment
		(start 375.825766 -99.910646)
		(end 376.219212 -99.5172)
		(width 0.10795)
		(layer "F.Cu")
		(net "FM_BMC_CPLD_MP_RST_N")
	)
	(segment
		(start 400.468084 -40.905176)
		(end 401.82673 -39.54653)
		(width 0.10795)
		(layer "F.Cu")
		(net "FM_BMC_CPLD_MP_RST_N")
	)
	(segment
		(start 385.046474 -49.403)
		(end 385.341368 -49.108106)
		(width 0.10795)
		(layer "F.Cu")
		(net "FM_BMC_CPLD_MP_RST_N")
	)
	(segment
		(start 404.508462 -37.173408)
		(end 405.446992 -37.173408)
		(width 0.10795)
		(layer "F.Cu")
		(net "FM_BMC_CPLD_MP_RST_N")
	)
	(segment
		(start 375.2215 -100.0252)
		(end 375.372122 -100.175822)
		(width 0.10795)
		(layer "F.Cu")
		(net "FM_BMC_CPLD_MP_RST_N")
	)
	(segment
		(start 393.50569 -45.168312)
		(end 394.71854 -43.955462)
		(width 0.10795)
		(layer "F.Cu")
		(net "FM_BMC_CPLD_MP_RST_N")
	)
	(segment
		(start 394.721588 -43.560492)
		(end 396.225776 -42.056304)
		(width 0.10795)
		(layer "F.Cu")
		(net "FM_BMC_CPLD_MP_RST_N")
	)
	(segment
		(start 397.080486 -42.056304)
		(end 398.231614 -40.905176)
		(width 0.10795)
		(layer "F.Cu")
		(net "FM_BMC_CPLD_MP_RST_N")
	)
	(segment
		(start 392.035538 -45.168312)
		(end 393.50569 -45.168312)
		(width 0.10795)
		(layer "F.Cu")
		(net "FM_BMC_CPLD_MP_RST_N")
	)
	(segment
		(start 406.094184 -36.526216)
		(end 407.49855 -36.526216)
		(width 0.10795)
		(layer "F.Cu")
		(net "FM_BMC_CPLD_MP_RST_N")
	)
	(segment
		(start 394.71854 -43.56354)
		(end 394.71854 -43.560492)
		(width 0.10795)
		(layer "F.Cu")
		(net "FM_BMC_CPLD_MP_RST_N")
	)
	(segment
		(start 401.82673 -39.54653)
		(end 402.7805 -38.59276)
		(width 0.10795)
		(layer "F.Cu")
		(net "FM_BMC_CPLD_MP_RST_N")
	)
	(segment
		(start 376.744738 -79.894684)
		(end 376.344942 -79.494888)
		(width 0.10795)
		(layer "F.Cu")
		(net "FM_BMC_CPLD_MP_RST_N")
	)
	(segment
		(start 384.04038 -49.403)
		(end 385.046474 -49.403)
		(width 0.10795)
		(layer "F.Cu")
		(net "FM_BMC_CPLD_MP_RST_N")
	)
	(segment
		(start 376.5042 -99.5172)
		(end 377.0884 -100.1014)
		(width 0.10795)
		(layer "F.Cu")
		(net "FM_BMC_CPLD_MP_RST_N")
	)
	(segment
		(start 405.446992 -37.173408)
		(end 406.094184 -36.526216)
		(width 0.10795)
		(layer "F.Cu")
		(net "FM_BMC_CPLD_MP_RST_N")
	)
	(segment
		(start 385.341368 -49.108106)
		(end 385.341368 -48.519334)
		(width 0.10795)
		(layer "F.Cu")
		(net "FM_BMC_CPLD_MP_RST_N")
	)
	(segment
		(start 375.825766 -99.987862)
		(end 375.825766 -99.910646)
		(width 0.10795)
		(layer "F.Cu")
		(net "FM_BMC_CPLD_MP_RST_N")
	)
	(segment
		(start 394.71854 -43.758612)
		(end 394.718286 -43.758358)
		(width 0.10795)
		(layer "F.Cu")
		(net "FM_BMC_CPLD_MP_RST_N")
	)
	(segment
		(start 387.357874 -46.502828)
		(end 390.701022 -46.502828)
		(width 0.10795)
		(layer "F.Cu")
		(net "FM_BMC_CPLD_MP_RST_N")
	)
	(segment
		(start 403.68347 -37.9984)
		(end 404.508462 -37.173408)
		(width 0.10795)
		(layer "F.Cu")
		(net "FM_BMC_CPLD_MP_RST_N")
	)
	(segment
		(start 394.718286 -43.758358)
		(end 394.718286 -43.563794)
		(width 0.10795)
		(layer "F.Cu")
		(net "FM_BMC_CPLD_MP_RST_N")
	)
	(segment
		(start 374.674892 -99.85502)
		(end 374.845072 -100.0252)
		(width 0.10795)
		(layer "F.Cu")
		(net "FM_BMC_CPLD_MP_RST_N")
	)
	(segment
		(start 396.225776 -42.056304)
		(end 397.080486 -42.056304)
		(width 0.10795)
		(layer "F.Cu")
		(net "FM_BMC_CPLD_MP_RST_N")
	)
	(segment
		(start 374.845072 -100.0252)
		(end 375.2215 -100.0252)
		(width 0.10795)
		(layer "F.Cu")
		(net "FM_BMC_CPLD_MP_RST_N")
	)
	(segment
		(start 394.718286 -43.563794)
		(end 394.71854 -43.56354)
		(width 0.10795)
		(layer "F.Cu")
		(net "FM_BMC_CPLD_MP_RST_N")
	)
	(via
		(at 377.0884 -100.1014)
		(size 0.508)
		(drill 0.254)
		(layers "F.Cu" "B.Cu")
		(net "FM_BMC_CPLD_MP_RST_N")
	)
	(via
		(at 376.744738 -79.894684)
		(size 0.4572)
		(drill 0.2032)
		(layers "F.Cu" "B.Cu")
		(net "FM_BMC_CPLD_MP_RST_N")
	)
	(via
		(at 383.7432 -49.10582)
		(size 0.508)
		(drill 0.254)
		(layers "F.Cu" "B.Cu")
		(net "FM_BMC_CPLD_MP_RST_N")
	)
	(via
		(at 401.82673 -39.54653)
		(size 0.762)
		(drill 0.381)
		(layers "F.Cu" "B.Cu")
		(net "FM_BMC_CPLD_MP_RST_N")
	)
	(segment
		(start 377.918218 -78.940152)
		(end 377.699524 -78.721458)
		(width 0.089408)
		(layer "In2.Cu")
		(net "FM_BMC_CPLD_MP_RST_N")
	)
	(segment
		(start 382.09982 -74.11466)
		(end 382.09982 -75.665076)
		(width 0.089408)
		(layer "In2.Cu")
		(net "FM_BMC_CPLD_MP_RST_N")
	)
	(segment
		(start 383.18313 -51.82616)
		(end 383.170938 -51.838352)
		(width 0.089408)
		(layer "In2.Cu")
		(net "FM_BMC_CPLD_MP_RST_N")
	)
	(segment
		(start 381.15367 -72.309736)
		(end 381.658622 -72.814688)
		(width 0.089408)
		(layer "In2.Cu")
		(net "FM_BMC_CPLD_MP_RST_N")
	)
	(segment
		(start 381.620776 -69.812916)
		(end 380.542546 -70.891146)
		(width 0.089408)
		(layer "In2.Cu")
		(net "FM_BMC_CPLD_MP_RST_N")
	)
	(segment
		(start 380.477776 -78.344014)
		(end 380.477776 -79.028544)
		(width 0.089408)
		(layer "In2.Cu")
		(net "FM_BMC_CPLD_MP_RST_N")
	)
	(segment
		(start 381.620776 -69.60997)
		(end 381.620776 -69.812916)
		(width 0.089408)
		(layer "In2.Cu")
		(net "FM_BMC_CPLD_MP_RST_N")
	)
	(segment
		(start 383.3114 -55.856886)
		(end 383.02057 -56.147716)
		(width 0.089408)
		(layer "In2.Cu")
		(net "FM_BMC_CPLD_MP_RST_N")
	)
	(segment
		(start 383.716784 -63.85306)
		(end 383.716784 -67.513962)
		(width 0.089408)
		(layer "In2.Cu")
		(net "FM_BMC_CPLD_MP_RST_N")
	)
	(segment
		(start 380.542546 -70.907402)
		(end 380.51867 -70.931278)
		(width 0.089408)
		(layer "In2.Cu")
		(net "FM_BMC_CPLD_MP_RST_N")
	)
	(segment
		(start 383.02057 -61.688218)
		(end 382.859788 -61.849)
		(width 0.089408)
		(layer "In2.Cu")
		(net "FM_BMC_CPLD_MP_RST_N")
	)
	(segment
		(start 380.51867 -71.263002)
		(end 381.15367 -71.898002)
		(width 0.089408)
		(layer "In2.Cu")
		(net "FM_BMC_CPLD_MP_RST_N")
	)
	(segment
		(start 382.859788 -61.849)
		(end 382.859788 -62.996064)
		(width 0.089408)
		(layer "In2.Cu")
		(net "FM_BMC_CPLD_MP_RST_N")
	)
	(segment
		(start 382.859788 -62.996064)
		(end 383.716784 -63.85306)
		(width 0.089408)
		(layer "In2.Cu")
		(net "FM_BMC_CPLD_MP_RST_N")
	)
	(segment
		(start 381.658622 -72.814688)
		(end 381.658622 -73.673462)
		(width 0.089408)
		(layer "In2.Cu")
		(net "FM_BMC_CPLD_MP_RST_N")
	)
	(segment
		(start 380.038102 -79.468218)
		(end 378.189998 -79.468218)
		(width 0.089408)
		(layer "In2.Cu")
		(net "FM_BMC_CPLD_MP_RST_N")
	)
	(segment
		(start 381.15367 -71.898002)
		(end 381.15367 -72.309736)
		(width 0.089408)
		(layer "In2.Cu")
		(net "FM_BMC_CPLD_MP_RST_N")
	)
	(segment
		(start 383.182622 -50.73904)
		(end 383.18313 -50.739548)
		(width 0.089408)
		(layer "In2.Cu")
		(net "FM_BMC_CPLD_MP_RST_N")
	)
	(segment
		(start 383.3114 -53.826156)
		(end 383.3114 -55.856886)
		(width 0.089408)
		(layer "In2.Cu")
		(net "FM_BMC_CPLD_MP_RST_N")
	)
	(segment
		(start 383.02057 -56.147716)
		(end 383.02057 -61.688218)
		(width 0.089408)
		(layer "In2.Cu")
		(net "FM_BMC_CPLD_MP_RST_N")
	)
	(segment
		(start 377.171458 -78.940152)
		(end 377.171458 -79.467964)
		(width 0.089408)
		(layer "In2.Cu")
		(net "FM_BMC_CPLD_MP_RST_N")
	)
	(segment
		(start 377.390152 -78.721458)
		(end 377.171458 -78.940152)
		(width 0.089408)
		(layer "In2.Cu")
		(net "FM_BMC_CPLD_MP_RST_N")
	)
	(segment
		(start 381.658622 -73.673462)
		(end 382.09982 -74.11466)
		(width 0.089408)
		(layer "In2.Cu")
		(net "FM_BMC_CPLD_MP_RST_N")
	)
	(segment
		(start 383.7432 -50.031142)
		(end 383.182622 -50.59172)
		(width 0.089408)
		(layer "In2.Cu")
		(net "FM_BMC_CPLD_MP_RST_N")
	)
	(segment
		(start 377.171458 -79.467964)
		(end 376.744738 -79.894684)
		(width 0.089408)
		(layer "In2.Cu")
		(net "FM_BMC_CPLD_MP_RST_N")
	)
	(segment
		(start 383.7432 -49.10582)
		(end 383.7432 -50.031142)
		(width 0.089408)
		(layer "In2.Cu")
		(net "FM_BMC_CPLD_MP_RST_N")
	)
	(segment
		(start 383.716784 -67.513962)
		(end 381.620776 -69.60997)
		(width 0.089408)
		(layer "In2.Cu")
		(net "FM_BMC_CPLD_MP_RST_N")
	)
	(segment
		(start 380.887478 -77.934312)
		(end 380.477776 -78.344014)
		(width 0.089408)
		(layer "In2.Cu")
		(net "FM_BMC_CPLD_MP_RST_N")
	)
	(segment
		(start 383.170938 -51.838352)
		(end 383.170938 -53.685694)
		(width 0.089408)
		(layer "In2.Cu")
		(net "FM_BMC_CPLD_MP_RST_N")
	)
	(segment
		(start 377.699524 -78.721458)
		(end 377.390152 -78.721458)
		(width 0.089408)
		(layer "In2.Cu")
		(net "FM_BMC_CPLD_MP_RST_N")
	)
	(segment
		(start 383.170938 -53.685694)
		(end 383.3114 -53.826156)
		(width 0.089408)
		(layer "In2.Cu")
		(net "FM_BMC_CPLD_MP_RST_N")
	)
	(segment
		(start 383.18313 -50.739548)
		(end 383.18313 -51.82616)
		(width 0.089408)
		(layer "In2.Cu")
		(net "FM_BMC_CPLD_MP_RST_N")
	)
	(segment
		(start 380.542546 -70.891146)
		(end 380.542546 -70.907402)
		(width 0.089408)
		(layer "In2.Cu")
		(net "FM_BMC_CPLD_MP_RST_N")
	)
	(segment
		(start 383.182622 -50.59172)
		(end 383.182622 -50.73904)
		(width 0.089408)
		(layer "In2.Cu")
		(net "FM_BMC_CPLD_MP_RST_N")
	)
	(segment
		(start 377.918218 -79.196438)
		(end 377.918218 -78.940152)
		(width 0.089408)
		(layer "In2.Cu")
		(net "FM_BMC_CPLD_MP_RST_N")
	)
	(segment
		(start 380.477776 -79.028544)
		(end 380.038102 -79.468218)
		(width 0.089408)
		(layer "In2.Cu")
		(net "FM_BMC_CPLD_MP_RST_N")
	)
	(segment
		(start 378.189998 -79.468218)
		(end 377.918218 -79.196438)
		(width 0.089408)
		(layer "In2.Cu")
		(net "FM_BMC_CPLD_MP_RST_N")
	)
	(segment
		(start 380.887478 -76.877418)
		(end 380.887478 -77.934312)
		(width 0.089408)
		(layer "In2.Cu")
		(net "FM_BMC_CPLD_MP_RST_N")
	)
	(segment
		(start 380.51867 -70.931278)
		(end 380.51867 -71.263002)
		(width 0.089408)
		(layer "In2.Cu")
		(net "FM_BMC_CPLD_MP_RST_N")
	)
	(segment
		(start 382.09982 -75.665076)
		(end 380.887478 -76.877418)
		(width 0.089408)
		(layer "In2.Cu")
		(net "FM_BMC_CPLD_MP_RST_N")
	)
	(segment
		(start 373.732298 -93.519498)
		(end 374.7262 -94.5134)
		(width 0.089408)
		(layer "In9.Cu")
		(net "FM_BMC_CPLD_MP_RST_N")
	)
	(segment
		(start 376.346466 -81.350866)
		(end 375.4755 -82.221832)
		(width 0.089408)
		(layer "In9.Cu")
		(net "FM_BMC_CPLD_MP_RST_N")
	)
	(segment
		(start 373.345456 -96.545146)
		(end 373.345456 -97.866962)
		(width 0.089408)
		(layer "In9.Cu")
		(net "FM_BMC_CPLD_MP_RST_N")
	)
	(segment
		(start 369.981988 -90.254836)
		(end 369.981988 -90.939366)
		(width 0.089408)
		(layer "In9.Cu")
		(net "FM_BMC_CPLD_MP_RST_N")
	)
	(segment
		(start 373.908828 -95.98152)
		(end 373.842534 -96.047814)
		(width 0.089408)
		(layer "In9.Cu")
		(net "FM_BMC_CPLD_MP_RST_N")
	)
	(segment
		(start 370.623338 -88.873584)
		(end 370.07292 -89.424002)
		(width 0.089408)
		(layer "In9.Cu")
		(net "FM_BMC_CPLD_MP_RST_N")
	)
	(segment
		(start 370.07292 -90.163904)
		(end 369.981988 -90.254836)
		(width 0.089408)
		(layer "In9.Cu")
		(net "FM_BMC_CPLD_MP_RST_N")
	)
	(segment
		(start 375.4755 -86.931246)
		(end 373.533162 -88.873584)
		(width 0.089408)
		(layer "In9.Cu")
		(net "FM_BMC_CPLD_MP_RST_N")
	)
	(segment
		(start 370.415312 -91.995498)
		(end 371.458236 -93.038422)
		(width 0.089408)
		(layer "In9.Cu")
		(net "FM_BMC_CPLD_MP_RST_N")
	)
	(segment
		(start 374.7262 -95.81642)
		(end 374.5611 -95.98152)
		(width 0.089408)
		(layer "In9.Cu")
		(net "FM_BMC_CPLD_MP_RST_N")
	)
	(segment
		(start 374.7262 -94.5134)
		(end 374.7262 -95.81642)
		(width 0.089408)
		(layer "In9.Cu")
		(net "FM_BMC_CPLD_MP_RST_N")
	)
	(segment
		(start 376.744738 -80.001364)
		(end 376.346466 -80.399636)
		(width 0.089408)
		(layer "In9.Cu")
		(net "FM_BMC_CPLD_MP_RST_N")
	)
	(segment
		(start 376.346466 -80.399636)
		(end 376.346466 -81.350866)
		(width 0.089408)
		(layer "In9.Cu")
		(net "FM_BMC_CPLD_MP_RST_N")
	)
	(segment
		(start 375.4755 -82.221832)
		(end 375.4755 -86.931246)
		(width 0.089408)
		(layer "In9.Cu")
		(net "FM_BMC_CPLD_MP_RST_N")
	)
	(segment
		(start 373.842534 -96.048068)
		(end 373.345456 -96.545146)
		(width 0.089408)
		(layer "In9.Cu")
		(net "FM_BMC_CPLD_MP_RST_N")
	)
	(segment
		(start 370.415312 -91.37269)
		(end 370.415312 -91.995498)
		(width 0.089408)
		(layer "In9.Cu")
		(net "FM_BMC_CPLD_MP_RST_N")
	)
	(segment
		(start 373.533162 -88.873584)
		(end 370.623338 -88.873584)
		(width 0.089408)
		(layer "In9.Cu")
		(net "FM_BMC_CPLD_MP_RST_N")
	)
	(segment
		(start 373.803164 -98.32467)
		(end 375.31167 -98.32467)
		(width 0.089408)
		(layer "In9.Cu")
		(net "FM_BMC_CPLD_MP_RST_N")
	)
	(segment
		(start 376.744738 -79.894684)
		(end 376.744738 -80.001364)
		(width 0.089408)
		(layer "In9.Cu")
		(net "FM_BMC_CPLD_MP_RST_N")
	)
	(segment
		(start 371.988842 -93.038422)
		(end 372.469918 -93.519498)
		(width 0.089408)
		(layer "In9.Cu")
		(net "FM_BMC_CPLD_MP_RST_N")
	)
	(segment
		(start 371.458236 -93.038422)
		(end 371.988842 -93.038422)
		(width 0.089408)
		(layer "In9.Cu")
		(net "FM_BMC_CPLD_MP_RST_N")
	)
	(segment
		(start 373.345456 -97.866962)
		(end 373.803164 -98.32467)
		(width 0.089408)
		(layer "In9.Cu")
		(net "FM_BMC_CPLD_MP_RST_N")
	)
	(segment
		(start 369.981988 -90.939366)
		(end 370.415312 -91.37269)
		(width 0.089408)
		(layer "In9.Cu")
		(net "FM_BMC_CPLD_MP_RST_N")
	)
	(segment
		(start 373.842534 -96.047814)
		(end 373.842534 -96.048068)
		(width 0.089408)
		(layer "In9.Cu")
		(net "FM_BMC_CPLD_MP_RST_N")
	)
	(segment
		(start 375.31167 -98.32467)
		(end 377.0884 -100.1014)
		(width 0.089408)
		(layer "In9.Cu")
		(net "FM_BMC_CPLD_MP_RST_N")
	)
	(segment
		(start 374.5611 -95.98152)
		(end 373.908828 -95.98152)
		(width 0.089408)
		(layer "In9.Cu")
		(net "FM_BMC_CPLD_MP_RST_N")
	)
	(segment
		(start 370.07292 -89.424002)
		(end 370.07292 -90.163904)
		(width 0.089408)
		(layer "In9.Cu")
		(net "FM_BMC_CPLD_MP_RST_N")
	)
	(segment
		(start 372.469918 -93.519498)
		(end 373.732298 -93.519498)
		(width 0.089408)
		(layer "In9.Cu")
		(net "FM_BMC_CPLD_MP_RST_N")
	)
	(segment
		(start 175.598328 -128.848612)
		(end 176.9745 -130.224784)
		(width 0.254)
		(layer "F.Cu")
		(net "VR_COMP_PVPP_KLM_3")
	)
	(segment
		(start 176.423066 -134.0104)
		(end 176.423066 -133.197092)
		(width 0.254)
		(layer "F.Cu")
		(net "VR_COMP_PVPP_KLM_3")
	)
	(segment
		(start 176.9745 -130.224784)
		(end 176.9745 -131.318)
		(width 0.254)
		(layer "F.Cu")
		(net "VR_COMP_PVPP_KLM_3")
	)
	(segment
		(start 176.423066 -133.197092)
		(end 176.9745 -132.645658)
		(width 0.254)
		(layer "F.Cu")
		(net "VR_COMP_PVPP_KLM_3")
	)
	(segment
		(start 176.9745 -132.334)
		(end 176.9745 -131.318)
		(width 0.254)
		(layer "F.Cu")
		(net "VR_COMP_PVPP_KLM_3")
	)
	(segment
		(start 176.9745 -132.645658)
		(end 176.9745 -132.334)
		(width 0.254)
		(layer "F.Cu")
		(net "VR_COMP_PVPP_KLM_3")
	)
	(via
		(at 175.598328 -128.848612)
		(size 0.762)
		(drill 0.381)
		(layers "F.Cu" "B.Cu")
		(net "VR_COMP_PVPP_KLM_3")
	)
	(segment
		(start 176.9745 -6.571742)
		(end 176.987962 -6.55828)
		(width 0.254)
		(layer "F.Cu")
		(net "VR_COMP_PVPP_GHJ_3")
	)
	(segment
		(start 176.423066 -9.7028)
		(end 176.9745 -9.151366)
		(width 0.254)
		(layer "F.Cu")
		(net "VR_COMP_PVPP_GHJ_3")
	)
	(segment
		(start 176.423066 -10.5029)
		(end 176.423066 -9.7028)
		(width 0.254)
		(layer "F.Cu")
		(net "VR_COMP_PVPP_GHJ_3")
	)
	(segment
		(start 176.9745 -7.874)
		(end 176.9745 -6.571742)
		(width 0.254)
		(layer "F.Cu")
		(net "VR_COMP_PVPP_GHJ_3")
	)
	(segment
		(start 176.9745 -9.151366)
		(end 176.9745 -8.763)
		(width 0.254)
		(layer "F.Cu")
		(net "VR_COMP_PVPP_GHJ_3")
	)
	(segment
		(start 176.9745 -8.763)
		(end 176.9745 -7.874)
		(width 0.254)
		(layer "F.Cu")
		(net "VR_COMP_PVPP_GHJ_3")
	)
	(via
		(at 176.987962 -6.55828)
		(size 0.762)
		(drill 0.381)
		(layers "F.Cu" "B.Cu")
		(net "VR_COMP_PVPP_GHJ_3")
	)
	(segment
		(start 342.793066 -130.0226)
		(end 342.793066 -129.032)
		(width 0.254)
		(layer "F.Cu")
		(net "VR_COMP_PVPP_DEF_3")
	)
	(segment
		(start 342.646 -128.4732)
		(end 342.646 -128.2954)
		(width 0.254)
		(layer "F.Cu")
		(net "VR_COMP_PVPP_DEF_3")
	)
	(segment
		(start 343.3318 -126.746)
		(end 343.3318 -127.5588)
		(width 0.254)
		(layer "F.Cu")
		(net "VR_COMP_PVPP_DEF_3")
	)
	(segment
		(start 342.646 -128.2954)
		(end 342.9 -128.0414)
		(width 0.254)
		(layer "F.Cu")
		(net "VR_COMP_PVPP_DEF_3")
	)
	(segment
		(start 343.1794 -128.0414)
		(end 343.3318 -127.889)
		(width 0.254)
		(layer "F.Cu")
		(net "VR_COMP_PVPP_DEF_3")
	)
	(segment
		(start 342.9 -128.0414)
		(end 343.1794 -128.0414)
		(width 0.254)
		(layer "F.Cu")
		(net "VR_COMP_PVPP_DEF_3")
	)
	(segment
		(start 343.3318 -127.889)
		(end 343.3318 -127.5588)
		(width 0.254)
		(layer "F.Cu")
		(net "VR_COMP_PVPP_DEF_3")
	)
	(segment
		(start 342.793066 -129.032)
		(end 342.646 -128.884934)
		(width 0.254)
		(layer "F.Cu")
		(net "VR_COMP_PVPP_DEF_3")
	)
	(segment
		(start 342.646 -128.884934)
		(end 342.646 -128.4732)
		(width 0.254)
		(layer "F.Cu")
		(net "VR_COMP_PVPP_DEF_3")
	)
	(via
		(at 342.646 -128.4732)
		(size 0.508)
		(drill 0.254)
		(layers "F.Cu" "B.Cu")
		(net "VR_COMP_PVPP_DEF_3")
	)
	(segment
		(start 344.678 -24.7015)
		(end 344.678 -24.438102)
		(width 0.254)
		(layer "F.Cu")
		(net "VR_COMP_PVPP_ABC_3")
	)
	(segment
		(start 344.113866 -25.7302)
		(end 344.113866 -25.265634)
		(width 0.254)
		(layer "F.Cu")
		(net "VR_COMP_PVPP_ABC_3")
	)
	(segment
		(start 344.678 -22.64156)
		(end 344.678 -23.45436)
		(width 0.254)
		(layer "F.Cu")
		(net "VR_COMP_PVPP_ABC_3")
	)
	(segment
		(start 344.678 -24.438102)
		(end 344.678 -23.45436)
		(width 0.254)
		(layer "F.Cu")
		(net "VR_COMP_PVPP_ABC_3")
	)
	(segment
		(start 344.113866 -25.265634)
		(end 344.678 -24.7015)
		(width 0.254)
		(layer "F.Cu")
		(net "VR_COMP_PVPP_ABC_3")
	)
	(via
		(at 344.678 -24.438102)
		(size 0.508)
		(drill 0.254)
		(layers "F.Cu" "B.Cu")
		(net "VR_COMP_PVPP_ABC_3")
	)
	(segment
		(start -0.254 -121.666)
		(end -1.63068 -120.28932)
		(width 0.10795)
		(layer "F.Cu")
		(net "SMB_PEHPCPU1_STBY_LVC3_R_SDA")
	)
	(segment
		(start -2.22504 -120.28932)
		(end -2.855468 -120.919748)
		(width 0.10795)
		(layer "F.Cu")
		(net "SMB_PEHPCPU1_STBY_LVC3_R_SDA")
	)
	(segment
		(start -2.855468 -120.919748)
		(end -2.855468 -121.49836)
		(width 0.10795)
		(layer "F.Cu")
		(net "SMB_PEHPCPU1_STBY_LVC3_R_SDA")
	)
	(segment
		(start -1.63068 -120.28932)
		(end -2.22504 -120.28932)
		(width 0.10795)
		(layer "F.Cu")
		(net "SMB_PEHPCPU1_STBY_LVC3_R_SDA")
	)
	(via
		(at -0.254 -121.666)
		(size 0.508)
		(drill 0.254)
		(layers "F.Cu" "B.Cu")
		(net "SMB_PEHPCPU1_STBY_LVC3_R_SDA")
	)
	(segment
		(start -0.743712 -120.77954)
		(end -1.167892 -120.35536)
		(width 0.10795)
		(layer "B.Cu")
		(net "SMB_PEHPCPU1_STBY_LVC3_R_SDA")
	)
	(segment
		(start -1.44526 -121.2596)
		(end -1.44526 -120.35536)
		(width 0.10795)
		(layer "B.Cu")
		(net "SMB_PEHPCPU1_STBY_LVC3_R_SDA")
	)
	(segment
		(start -1.65862 -121.47296)
		(end -1.44526 -121.2596)
		(width 0.10795)
		(layer "B.Cu")
		(net "SMB_PEHPCPU1_STBY_LVC3_R_SDA")
	)
	(segment
		(start -1.167892 -120.35536)
		(end -1.44526 -120.35536)
		(width 0.10795)
		(layer "B.Cu")
		(net "SMB_PEHPCPU1_STBY_LVC3_R_SDA")
	)
	(segment
		(start -2.33426 -121.47296)
		(end -1.65862 -121.47296)
		(width 0.10795)
		(layer "B.Cu")
		(net "SMB_PEHPCPU1_STBY_LVC3_R_SDA")
	)
	(segment
		(start -0.743712 -121.176288)
		(end -0.743712 -120.77954)
		(width 0.10795)
		(layer "B.Cu")
		(net "SMB_PEHPCPU1_STBY_LVC3_R_SDA")
	)
	(segment
		(start -0.254 -121.666)
		(end -0.743712 -121.176288)
		(width 0.10795)
		(layer "B.Cu")
		(net "SMB_PEHPCPU1_STBY_LVC3_R_SDA")
	)
	(segment
		(start -3.505708 -120.942608)
		(end -2.91846 -120.35536)
		(width 0.10795)
		(layer "F.Cu")
		(net "SMB_PEHPCPU1_STBY_LVC3_R_SCL")
	)
	(segment
		(start -3.505708 -121.49836)
		(end -3.505708 -120.942608)
		(width 0.10795)
		(layer "F.Cu")
		(net "SMB_PEHPCPU1_STBY_LVC3_R_SCL")
	)
	(via
		(at -4.417568 -121.542048)
		(size 0.6604)
		(drill 0.3302)
		(layers "F.Cu" "B.Cu")
		(net "SMB_PEHPCPU1_STBY_LVC3_R_SCL")
	)
	(via
		(at -2.91846 -120.35536)
		(size 0.508)
		(drill 0.254)
		(layers "F.Cu" "B.Cu")
		(net "SMB_PEHPCPU1_STBY_LVC3_R_SCL")
	)
	(segment
		(start -3.283458 -121.533158)
		(end -3.22326 -121.47296)
		(width 0.10795)
		(layer "B.Cu")
		(net "SMB_PEHPCPU1_STBY_LVC3_R_SCL")
	)
	(segment
		(start -3.22326 -120.66016)
		(end -2.91846 -120.35536)
		(width 0.10795)
		(layer "B.Cu")
		(net "SMB_PEHPCPU1_STBY_LVC3_R_SCL")
	)
	(segment
		(start -3.22326 -121.47296)
		(end -3.22326 -120.66016)
		(width 0.10795)
		(layer "B.Cu")
		(net "SMB_PEHPCPU1_STBY_LVC3_R_SCL")
	)
	(segment
		(start -2.91846 -120.35536)
		(end -2.20726 -120.35536)
		(width 0.10795)
		(layer "B.Cu")
		(net "SMB_PEHPCPU1_STBY_LVC3_R_SCL")
	)
	(segment
		(start -4.408678 -121.533158)
		(end -3.283458 -121.533158)
		(width 0.10795)
		(layer "B.Cu")
		(net "SMB_PEHPCPU1_STBY_LVC3_R_SCL")
	)
	(segment
		(start -4.417568 -121.542048)
		(end -4.408678 -121.533158)
		(width 0.10795)
		(layer "B.Cu")
		(net "SMB_PEHPCPU1_STBY_LVC3_R_SCL")
	)
	(segment
		(start 394.7922 2.4638)
		(end 394.97 2.6416)
		(width 0.10795)
		(layer "F.Cu")
		(net "JTAG_TMS_R")
	)
	(segment
		(start 394.7922 1.5748)
		(end 394.7922 2.4638)
		(width 0.10795)
		(layer "F.Cu")
		(net "JTAG_TMS_R")
	)
	(segment
		(start 394.7922 1.5748)
		(end 394.0302 1.5748)
		(width 0.10795)
		(layer "F.Cu")
		(net "JTAG_TMS_R")
	)
	(segment
		(start 394.97 2.6416)
		(end 394.97 3.81)
		(width 0.10795)
		(layer "F.Cu")
		(net "JTAG_TMS_R")
	)
	(segment
		(start 376.744738 -69.495162)
		(end 376.344942 -69.894958)
		(width 0.1016)
		(layer "F.Cu")
		(net "FM_ADR_SMI_GPIO_R_N")
	)
	(via
		(at 376.744738 -69.495162)
		(size 0.4572)
		(drill 0.2032)
		(layers "F.Cu" "B.Cu")
		(net "FM_ADR_SMI_GPIO_R_N")
	)
	(via
		(at 375.5136 -67.945)
		(size 0.508)
		(drill 0.254)
		(layers "F.Cu" "B.Cu")
		(net "FM_ADR_SMI_GPIO_R_N")
	)
	(segment
		(start 376.337576 -69.088)
		(end 375.6914 -69.088)
		(width 0.10795)
		(layer "B.Cu")
		(net "FM_ADR_SMI_GPIO_R_N")
	)
	(segment
		(start 375.5136 -67.945)
		(end 375.5136 -67.7164)
		(width 0.10795)
		(layer "B.Cu")
		(net "FM_ADR_SMI_GPIO_R_N")
	)
	(segment
		(start 375.5136 -67.7164)
		(end 376.174 -67.056)
		(width 0.10795)
		(layer "B.Cu")
		(net "FM_ADR_SMI_GPIO_R_N")
	)
	(segment
		(start 375.539 -68.2498)
		(end 375.5136 -68.2244)
		(width 0.10795)
		(layer "B.Cu")
		(net "FM_ADR_SMI_GPIO_R_N")
	)
	(segment
		(start 376.174 -67.056)
		(end 376.174 -66.929)
		(width 0.10795)
		(layer "B.Cu")
		(net "FM_ADR_SMI_GPIO_R_N")
	)
	(segment
		(start 375.6914 -69.088)
		(end 375.539 -68.9356)
		(width 0.10795)
		(layer "B.Cu")
		(net "FM_ADR_SMI_GPIO_R_N")
	)
	(segment
		(start 375.539 -68.9356)
		(end 375.539 -68.2498)
		(width 0.10795)
		(layer "B.Cu")
		(net "FM_ADR_SMI_GPIO_R_N")
	)
	(segment
		(start 376.744738 -69.495162)
		(end 376.337576 -69.088)
		(width 0.10795)
		(layer "B.Cu")
		(net "FM_ADR_SMI_GPIO_R_N")
	)
	(segment
		(start 375.5136 -68.2244)
		(end 375.5136 -67.945)
		(width 0.10795)
		(layer "B.Cu")
		(net "FM_ADR_SMI_GPIO_R_N")
	)
	(segment
		(start 12.475718 -88.648286)
		(end 12.448032 -88.6206)
		(width 0.10795)
		(layer "F.Cu")
		(net "FAN_TACH3_R")
	)
	(segment
		(start 11.303 -89.1032)
		(end 11.303 -98.171)
		(width 0.10795)
		(layer "F.Cu")
		(net "FAN_TACH3_R")
	)
	(segment
		(start 12.448032 -88.6206)
		(end 11.7856 -88.6206)
		(width 0.10795)
		(layer "F.Cu")
		(net "FAN_TACH3_R")
	)
	(segment
		(start 11.303 -98.171)
		(end 14.224 -101.092)
		(width 0.10795)
		(layer "F.Cu")
		(net "FAN_TACH3_R")
	)
	(segment
		(start 11.7856 -88.6206)
		(end 11.303 -89.1032)
		(width 0.10795)
		(layer "F.Cu")
		(net "FAN_TACH3_R")
	)
	(via
		(at 12.475718 -88.648286)
		(size 0.508)
		(drill 0.254)
		(layers "F.Cu" "B.Cu")
		(net "FAN_TACH3_R")
	)
	(via
		(at -3.266694 -41.44391)
		(size 0.508)
		(drill 0.254)
		(layers "F.Cu" "B.Cu")
		(net "FAN_TACH3_R")
	)
	(segment
		(start -1.948688 -42.430954)
		(end -1.948688 -42.097198)
		(width 0.10795)
		(layer "B.Cu")
		(net "FAN_TACH3_R")
	)
	(segment
		(start 0.007112 -42.430954)
		(end 0.007112 -42.097198)
		(width 0.10795)
		(layer "B.Cu")
		(net "FAN_TACH3_R")
	)
	(segment
		(start 0.496062 -42.097198)
		(end 0.496062 -42.430954)
		(width 0.10795)
		(layer "B.Cu")
		(net "FAN_TACH3_R")
	)
	(segment
		(start -2.545588 -41.989248)
		(end -2.437638 -42.097198)
		(width 0.10795)
		(layer "B.Cu")
		(net "FAN_TACH3_R")
	)
	(segment
		(start -1.840738 -41.989248)
		(end -1.567688 -41.989248)
		(width 0.10795)
		(layer "B.Cu")
		(net "FAN_TACH3_R")
	)
	(segment
		(start 0.877062 -42.538904)
		(end 0.985012 -42.430954)
		(width 0.10795)
		(layer "B.Cu")
		(net "FAN_TACH3_R")
	)
	(segment
		(start -0.481838 -42.097198)
		(end -0.481838 -42.430954)
		(width 0.10795)
		(layer "B.Cu")
		(net "FAN_TACH3_R")
	)
	(segment
		(start -0.970788 -42.097198)
		(end -0.862838 -41.989248)
		(width 0.10795)
		(layer "B.Cu")
		(net "FAN_TACH3_R")
	)
	(segment
		(start -2.056638 -42.538904)
		(end -1.948688 -42.430954)
		(width 0.10795)
		(layer "B.Cu")
		(net "FAN_TACH3_R")
	)
	(segment
		(start -1.351788 -42.538904)
		(end -1.078738 -42.538904)
		(width 0.10795)
		(layer "B.Cu")
		(net "FAN_TACH3_R")
	)
	(segment
		(start -2.721356 -41.989248)
		(end -2.545588 -41.989248)
		(width 0.10795)
		(layer "B.Cu")
		(net "FAN_TACH3_R")
	)
	(segment
		(start -2.437638 -42.097198)
		(end -2.437638 -42.430954)
		(width 0.10795)
		(layer "B.Cu")
		(net "FAN_TACH3_R")
	)
	(segment
		(start 0.007112 -42.097198)
		(end 0.115062 -41.989248)
		(width 0.10795)
		(layer "B.Cu")
		(net "FAN_TACH3_R")
	)
	(segment
		(start -1.078738 -42.538904)
		(end -0.970788 -42.430954)
		(width 0.10795)
		(layer "B.Cu")
		(net "FAN_TACH3_R")
	)
	(segment
		(start -3.266694 -41.44391)
		(end -2.721356 -41.989248)
		(width 0.10795)
		(layer "B.Cu")
		(net "FAN_TACH3_R")
	)
	(segment
		(start -2.329688 -42.538904)
		(end -2.056638 -42.538904)
		(width 0.10795)
		(layer "B.Cu")
		(net "FAN_TACH3_R")
	)
	(segment
		(start -1.948688 -42.097198)
		(end -1.840738 -41.989248)
		(width 0.10795)
		(layer "B.Cu")
		(net "FAN_TACH3_R")
	)
	(segment
		(start 0.985012 -42.097198)
		(end 1.55321 -41.529)
		(width 0.10795)
		(layer "B.Cu")
		(net "FAN_TACH3_R")
	)
	(segment
		(start 0.985012 -42.430954)
		(end 0.985012 -42.097198)
		(width 0.10795)
		(layer "B.Cu")
		(net "FAN_TACH3_R")
	)
	(segment
		(start -0.100838 -42.538904)
		(end 0.007112 -42.430954)
		(width 0.10795)
		(layer "B.Cu")
		(net "FAN_TACH3_R")
	)
	(segment
		(start 8.7122 -41.529)
		(end 8.8646 -41.6814)
		(width 0.10795)
		(layer "B.Cu")
		(net "FAN_TACH3_R")
	)
	(segment
		(start -0.970788 -42.430954)
		(end -0.970788 -42.097198)
		(width 0.10795)
		(layer "B.Cu")
		(net "FAN_TACH3_R")
	)
	(segment
		(start -1.459738 -42.097198)
		(end -1.459738 -42.430954)
		(width 0.10795)
		(layer "B.Cu")
		(net "FAN_TACH3_R")
	)
	(segment
		(start 0.388112 -41.989248)
		(end 0.496062 -42.097198)
		(width 0.10795)
		(layer "B.Cu")
		(net "FAN_TACH3_R")
	)
	(segment
		(start 0.604012 -42.538904)
		(end 0.877062 -42.538904)
		(width 0.10795)
		(layer "B.Cu")
		(net "FAN_TACH3_R")
	)
	(segment
		(start -0.589788 -41.989248)
		(end -0.481838 -42.097198)
		(width 0.10795)
		(layer "B.Cu")
		(net "FAN_TACH3_R")
	)
	(segment
		(start 0.115062 -41.989248)
		(end 0.388112 -41.989248)
		(width 0.10795)
		(layer "B.Cu")
		(net "FAN_TACH3_R")
	)
	(segment
		(start 1.55321 -41.529)
		(end 8.7122 -41.529)
		(width 0.10795)
		(layer "B.Cu")
		(net "FAN_TACH3_R")
	)
	(segment
		(start -1.567688 -41.989248)
		(end -1.459738 -42.097198)
		(width 0.10795)
		(layer "B.Cu")
		(net "FAN_TACH3_R")
	)
	(segment
		(start -2.437638 -42.430954)
		(end -2.329688 -42.538904)
		(width 0.10795)
		(layer "B.Cu")
		(net "FAN_TACH3_R")
	)
	(segment
		(start 0.496062 -42.430954)
		(end 0.604012 -42.538904)
		(width 0.10795)
		(layer "B.Cu")
		(net "FAN_TACH3_R")
	)
	(segment
		(start -0.481838 -42.430954)
		(end -0.373888 -42.538904)
		(width 0.10795)
		(layer "B.Cu")
		(net "FAN_TACH3_R")
	)
	(segment
		(start -1.459738 -42.430954)
		(end -1.351788 -42.538904)
		(width 0.10795)
		(layer "B.Cu")
		(net "FAN_TACH3_R")
	)
	(segment
		(start -0.373888 -42.538904)
		(end -0.100838 -42.538904)
		(width 0.10795)
		(layer "B.Cu")
		(net "FAN_TACH3_R")
	)
	(segment
		(start -0.862838 -41.989248)
		(end -0.589788 -41.989248)
		(width 0.10795)
		(layer "B.Cu")
		(net "FAN_TACH3_R")
	)
	(segment
		(start -5.180584 -44.499784)
		(end -4.09829 -43.41749)
		(width 0.089408)
		(layer "In4.Cu")
		(net "FAN_TACH3_R")
	)
	(segment
		(start -3.792728 -41.669462)
		(end -4.14528 -41.669462)
		(width 0.089408)
		(layer "In4.Cu")
		(net "FAN_TACH3_R")
	)
	(segment
		(start -5.180584 -85.319616)
		(end -5.180584 -44.499784)
		(width 0.089408)
		(layer "In4.Cu")
		(net "FAN_TACH3_R")
	)
	(segment
		(start 1.6256 -88.011)
		(end 0.6096 -86.995)
		(width 0.089408)
		(layer "In4.Cu")
		(net "FAN_TACH3_R")
	)
	(segment
		(start -3.567176 -41.44391)
		(end -3.792728 -41.669462)
		(width 0.089408)
		(layer "In4.Cu")
		(net "FAN_TACH3_R")
	)
	(segment
		(start -4.405376 -41.409366)
		(end -4.405376 -40.96639)
		(width 0.089408)
		(layer "In4.Cu")
		(net "FAN_TACH3_R")
	)
	(segment
		(start -4.14528 -41.669462)
		(end -4.405376 -41.409366)
		(width 0.089408)
		(layer "In4.Cu")
		(net "FAN_TACH3_R")
	)
	(segment
		(start 9.8044 -88.011)
		(end 1.6256 -88.011)
		(width 0.089408)
		(layer "In4.Cu")
		(net "FAN_TACH3_R")
	)
	(segment
		(start -4.405376 -40.96639)
		(end -5.022088 -40.349678)
		(width 0.089408)
		(layer "In4.Cu")
		(net "FAN_TACH3_R")
	)
	(segment
		(start 0.6096 -86.995)
		(end -3.5052 -86.995)
		(width 0.089408)
		(layer "In4.Cu")
		(net "FAN_TACH3_R")
	)
	(segment
		(start -3.5052 -86.995)
		(end -5.180584 -85.319616)
		(width 0.089408)
		(layer "In4.Cu")
		(net "FAN_TACH3_R")
	)
	(segment
		(start -3.266694 -42.014902)
		(end -3.266694 -41.44391)
		(width 0.089408)
		(layer "In4.Cu")
		(net "FAN_TACH3_R")
	)
	(segment
		(start 10.441686 -88.648286)
		(end 9.8044 -88.011)
		(width 0.089408)
		(layer "In4.Cu")
		(net "FAN_TACH3_R")
	)
	(segment
		(start -3.266694 -41.44391)
		(end -3.567176 -41.44391)
		(width 0.089408)
		(layer "In4.Cu")
		(net "FAN_TACH3_R")
	)
	(segment
		(start -4.09829 -42.846498)
		(end -3.266694 -42.014902)
		(width 0.089408)
		(layer "In4.Cu")
		(net "FAN_TACH3_R")
	)
	(segment
		(start -4.09829 -43.41749)
		(end -4.09829 -42.846498)
		(width 0.089408)
		(layer "In4.Cu")
		(net "FAN_TACH3_R")
	)
	(segment
		(start -5.022088 -40.349678)
		(end -5.022088 -34.732214)
		(width 0.089408)
		(layer "In4.Cu")
		(net "FAN_TACH3_R")
	)
	(segment
		(start -5.022088 -34.732214)
		(end -3.999992 -33.710118)
		(width 0.089408)
		(layer "In4.Cu")
		(net "FAN_TACH3_R")
	)
	(segment
		(start 12.475718 -88.648286)
		(end 10.441686 -88.648286)
		(width 0.089408)
		(layer "In4.Cu")
		(net "FAN_TACH3_R")
	)
	(segment
		(start 10.97915 -88.86825)
		(end 10.97915 -98.73615)
		(width 0.10795)
		(layer "F.Cu")
		(net "FAN_TACH2_R")
	)
	(segment
		(start 10.97915 -98.73615)
		(end 13.335 -101.092)
		(width 0.10795)
		(layer "F.Cu")
		(net "FAN_TACH2_R")
	)
	(segment
		(start 12.450318 -88.013286)
		(end 11.834114 -88.013286)
		(width 0.10795)
		(layer "F.Cu")
		(net "FAN_TACH2_R")
	)
	(segment
		(start 11.834114 -88.013286)
		(end 10.97915 -88.86825)
		(width 0.10795)
		(layer "F.Cu")
		(net "FAN_TACH2_R")
	)
	(via
		(at 12.450318 -88.013286)
		(size 0.508)
		(drill 0.254)
		(layers "F.Cu" "B.Cu")
		(net "FAN_TACH2_R")
	)
	(via
		(at -4.005072 -41.128188)
		(size 0.508)
		(drill 0.254)
		(layers "F.Cu" "B.Cu")
		(net "FAN_TACH2_R")
	)
	(via
		(at 15.8496 -42.291)
		(size 0.6604)
		(drill 0.3302)
		(layers "F.Cu" "B.Cu")
		(net "FAN_TACH2_R")
	)
	(segment
		(start 10.197592 -40.804592)
		(end 11.684 -42.291)
		(width 0.10795)
		(layer "B.Cu")
		(net "FAN_TACH2_R")
	)
	(segment
		(start -5.153406 -41.72204)
		(end -4.598924 -41.72204)
		(width 0.10795)
		(layer "B.Cu")
		(net "FAN_TACH2_R")
	)
	(segment
		(start 1.613408 -40.804592)
		(end 10.197592 -40.804592)
		(width 0.10795)
		(layer "B.Cu")
		(net "FAN_TACH2_R")
	)
	(segment
		(start -2.599944 -33.710372)
		(end -3.302762 -34.41319)
		(width 0.10795)
		(layer "B.Cu")
		(net "FAN_TACH2_R")
	)
	(segment
		(start 1.091946 -41.326054)
		(end 1.613408 -40.804592)
		(width 0.10795)
		(layer "B.Cu")
		(net "FAN_TACH2_R")
	)
	(segment
		(start -2.560066 -40.959024)
		(end -2.193036 -41.326054)
		(width 0.10795)
		(layer "B.Cu")
		(net "FAN_TACH2_R")
	)
	(segment
		(start -2.193036 -41.326054)
		(end 1.091946 -41.326054)
		(width 0.10795)
		(layer "B.Cu")
		(net "FAN_TACH2_R")
	)
	(segment
		(start -4.598924 -41.72204)
		(end -4.005072 -41.128188)
		(width 0.10795)
		(layer "B.Cu")
		(net "FAN_TACH2_R")
	)
	(segment
		(start -5.352542 -34.871406)
		(end -5.352542 -41.522904)
		(width 0.10795)
		(layer "B.Cu")
		(net "FAN_TACH2_R")
	)
	(segment
		(start -4.005072 -41.128188)
		(end -3.835908 -40.959024)
		(width 0.10795)
		(layer "B.Cu")
		(net "FAN_TACH2_R")
	)
	(segment
		(start -2.599944 -33.710118)
		(end -2.599944 -33.710372)
		(width 0.10795)
		(layer "B.Cu")
		(net "FAN_TACH2_R")
	)
	(segment
		(start -4.894326 -34.41319)
		(end -5.352542 -34.871406)
		(width 0.10795)
		(layer "B.Cu")
		(net "FAN_TACH2_R")
	)
	(segment
		(start -3.302762 -34.41319)
		(end -4.894326 -34.41319)
		(width 0.10795)
		(layer "B.Cu")
		(net "FAN_TACH2_R")
	)
	(segment
		(start 11.684 -42.291)
		(end 15.8496 -42.291)
		(width 0.10795)
		(layer "B.Cu")
		(net "FAN_TACH2_R")
	)
	(segment
		(start -5.352542 -41.522904)
		(end -5.153406 -41.72204)
		(width 0.10795)
		(layer "B.Cu")
		(net "FAN_TACH2_R")
	)
	(segment
		(start -3.835908 -40.959024)
		(end -2.560066 -40.959024)
		(width 0.10795)
		(layer "B.Cu")
		(net "FAN_TACH2_R")
	)
	(segment
		(start 15.8496 -42.291)
		(end 16.764 -42.291)
		(width 0.10795)
		(layer "B.Cu")
		(net "FAN_TACH2_R")
	)
	(segment
		(start -2.891536 -41.252902)
		(end 12.881864 -41.252902)
		(width 0.089408)
		(layer "In4.Cu")
		(net "FAN_TACH2_R")
	)
	(segment
		(start -3.100832 -41.043606)
		(end -2.891536 -41.252902)
		(width 0.089408)
		(layer "In4.Cu")
		(net "FAN_TACH2_R")
	)
	(segment
		(start -4.005072 -41.128188)
		(end -3.517138 -41.128188)
		(width 0.089408)
		(layer "In4.Cu")
		(net "FAN_TACH2_R")
	)
	(segment
		(start 12.881864 -41.252902)
		(end 13.581126 -41.952164)
		(width 0.089408)
		(layer "In4.Cu")
		(net "FAN_TACH2_R")
	)
	(segment
		(start 13.581126 -47.50181)
		(end 11.451082 -49.631854)
		(width 0.089408)
		(layer "In4.Cu")
		(net "FAN_TACH2_R")
	)
	(segment
		(start -3.517138 -41.128188)
		(end -3.432556 -41.043606)
		(width 0.089408)
		(layer "In4.Cu")
		(net "FAN_TACH2_R")
	)
	(segment
		(start 11.451082 -49.631854)
		(end 11.451082 -67.642994)
		(width 0.089408)
		(layer "In4.Cu")
		(net "FAN_TACH2_R")
	)
	(segment
		(start 11.621262 -79.04988)
		(end 11.492992 -79.17815)
		(width 0.089408)
		(layer "In4.Cu")
		(net "FAN_TACH2_R")
	)
	(segment
		(start 11.451082 -67.642994)
		(end 12.072112 -68.264024)
		(width 0.089408)
		(layer "In4.Cu")
		(net "FAN_TACH2_R")
	)
	(segment
		(start 12.072112 -68.264024)
		(end 12.072112 -71.123302)
		(width 0.089408)
		(layer "In4.Cu")
		(net "FAN_TACH2_R")
	)
	(segment
		(start 13.581126 -41.952164)
		(end 13.581126 -47.50181)
		(width 0.089408)
		(layer "In4.Cu")
		(net "FAN_TACH2_R")
	)
	(segment
		(start 12.072112 -71.123302)
		(end 11.621262 -71.574152)
		(width 0.089408)
		(layer "In4.Cu")
		(net "FAN_TACH2_R")
	)
	(segment
		(start 11.621262 -71.574152)
		(end 11.621262 -79.04988)
		(width 0.089408)
		(layer "In4.Cu")
		(net "FAN_TACH2_R")
	)
	(segment
		(start -3.432556 -41.043606)
		(end -3.100832 -41.043606)
		(width 0.089408)
		(layer "In4.Cu")
		(net "FAN_TACH2_R")
	)
	(segment
		(start 11.492992 -87.05596)
		(end 12.450318 -88.013286)
		(width 0.089408)
		(layer "In4.Cu")
		(net "FAN_TACH2_R")
	)
	(segment
		(start 11.492992 -79.17815)
		(end 11.492992 -87.05596)
		(width 0.089408)
		(layer "In4.Cu")
		(net "FAN_TACH2_R")
	)
	(segment
		(start 12.469114 -89.283286)
		(end 11.935714 -89.283286)
		(width 0.10795)
		(layer "F.Cu")
		(net "FAN_TACH1_R")
	)
	(segment
		(start 11.935714 -89.283286)
		(end 11.6332 -89.5858)
		(width 0.10795)
		(layer "F.Cu")
		(net "FAN_TACH1_R")
	)
	(segment
		(start 11.6332 -89.5858)
		(end 11.6332 -97.6122)
		(width 0.10795)
		(layer "F.Cu")
		(net "FAN_TACH1_R")
	)
	(segment
		(start 11.6332 -97.6122)
		(end 15.113 -101.092)
		(width 0.10795)
		(layer "F.Cu")
		(net "FAN_TACH1_R")
	)
	(via
		(at 12.469114 -89.283286)
		(size 0.508)
		(drill 0.254)
		(layers "F.Cu" "B.Cu")
		(net "FAN_TACH1_R")
	)
	(via
		(at -4.87934 -41.282366)
		(size 0.508)
		(drill 0.254)
		(layers "F.Cu" "B.Cu")
		(net "FAN_TACH1_R")
	)
	(segment
		(start -4.248912 -40.651938)
		(end 1.24587 -40.651938)
		(width 0.10795)
		(layer "B.Cu")
		(net "FAN_TACH1_R")
	)
	(segment
		(start 1.302512 -40.595296)
		(end 8.020812 -40.595296)
		(width 0.10795)
		(layer "B.Cu")
		(net "FAN_TACH1_R")
	)
	(segment
		(start 1.24587 -40.651938)
		(end 1.302512 -40.595296)
		(width 0.10795)
		(layer "B.Cu")
		(net "FAN_TACH1_R")
	)
	(segment
		(start 8.42137 -40.194738)
		(end 10.517378 -40.194738)
		(width 0.10795)
		(layer "B.Cu")
		(net "FAN_TACH1_R")
	)
	(segment
		(start 11.72464 -41.402)
		(end 13.081 -41.402)
		(width 0.10795)
		(layer "B.Cu")
		(net "FAN_TACH1_R")
	)
	(segment
		(start 8.020812 -40.595296)
		(end 8.42137 -40.194738)
		(width 0.10795)
		(layer "B.Cu")
		(net "FAN_TACH1_R")
	)
	(segment
		(start -4.87934 -41.282366)
		(end -4.248912 -40.651938)
		(width 0.10795)
		(layer "B.Cu")
		(net "FAN_TACH1_R")
	)
	(segment
		(start 10.517378 -40.194738)
		(end 11.72464 -41.402)
		(width 0.10795)
		(layer "B.Cu")
		(net "FAN_TACH1_R")
	)
	(segment
		(start -3.626612 -87.287608)
		(end -5.473192 -85.441028)
		(width 0.089408)
		(layer "In4.Cu")
		(net "FAN_TACH1_R")
	)
	(segment
		(start -4.87934 -41.282366)
		(end -4.87934 -40.93464)
		(width 0.089408)
		(layer "In4.Cu")
		(net "FAN_TACH1_R")
	)
	(segment
		(start 12.469114 -89.283286)
		(end 10.568686 -89.283286)
		(width 0.089408)
		(layer "In4.Cu")
		(net "FAN_TACH1_R")
	)
	(segment
		(start -5.31876 -40.49522)
		(end -5.31876 -33.944052)
		(width 0.089408)
		(layer "In4.Cu")
		(net "FAN_TACH1_R")
	)
	(segment
		(start 1.504188 -88.303608)
		(end 0.488188 -87.287608)
		(width 0.089408)
		(layer "In4.Cu")
		(net "FAN_TACH1_R")
	)
	(segment
		(start -5.473192 -44.378372)
		(end -4.87934 -43.78452)
		(width 0.089408)
		(layer "In4.Cu")
		(net "FAN_TACH1_R")
	)
	(segment
		(start -4.87934 -40.93464)
		(end -5.31876 -40.49522)
		(width 0.089408)
		(layer "In4.Cu")
		(net "FAN_TACH1_R")
	)
	(segment
		(start -4.87934 -43.78452)
		(end -4.87934 -41.282366)
		(width 0.089408)
		(layer "In4.Cu")
		(net "FAN_TACH1_R")
	)
	(segment
		(start -1.20015 -33.709864)
		(end -1.20015 -33.710118)
		(width 0.089408)
		(layer "In4.Cu")
		(net "FAN_TACH1_R")
	)
	(segment
		(start 0.488188 -87.287608)
		(end -3.626612 -87.287608)
		(width 0.089408)
		(layer "In4.Cu")
		(net "FAN_TACH1_R")
	)
	(segment
		(start -5.31876 -33.944052)
		(end -4.13766 -32.762952)
		(width 0.089408)
		(layer "In4.Cu")
		(net "FAN_TACH1_R")
	)
	(segment
		(start -5.473192 -85.441028)
		(end -5.473192 -44.378372)
		(width 0.089408)
		(layer "In4.Cu")
		(net "FAN_TACH1_R")
	)
	(segment
		(start 10.568686 -89.283286)
		(end 9.589008 -88.303608)
		(width 0.089408)
		(layer "In4.Cu")
		(net "FAN_TACH1_R")
	)
	(segment
		(start 9.589008 -88.303608)
		(end 1.504188 -88.303608)
		(width 0.089408)
		(layer "In4.Cu")
		(net "FAN_TACH1_R")
	)
	(segment
		(start -2.147062 -32.762952)
		(end -1.20015 -33.709864)
		(width 0.089408)
		(layer "In4.Cu")
		(net "FAN_TACH1_R")
	)
	(segment
		(start -4.13766 -32.762952)
		(end -2.147062 -32.762952)
		(width 0.089408)
		(layer "In4.Cu")
		(net "FAN_TACH1_R")
	)
	(segment
		(start 10.249916 -36.490402)
		(end 10.249916 -36.640262)
		(width 0.10795)
		(layer "F.Cu")
		(net "FAN_PWM_OUT_SYS0_R1")
	)
	(segment
		(start 6.591808 -33.020508)
		(end 6.741922 -33.020508)
		(width 0.10795)
		(layer "F.Cu")
		(net "FAN_PWM_OUT_SYS0_R1")
	)
	(segment
		(start 5.40004 -32.91459)
		(end 5.40004 -32.42183)
		(width 0.10795)
		(layer "F.Cu")
		(net "FAN_PWM_OUT_SYS0_R1")
	)
	(segment
		(start 7.20979 -32.42183)
		(end 7.20979 -32.91459)
		(width 0.10795)
		(layer "F.Cu")
		(net "FAN_PWM_OUT_SYS0_R1")
	)
	(segment
		(start 9.844024 -36.23437)
		(end 9.993884 -36.23437)
		(width 0.10795)
		(layer "F.Cu")
		(net "FAN_PWM_OUT_SYS0_R1")
	)
	(segment
		(start 10.888726 -35.851592)
		(end 10.249916 -36.490402)
		(width 0.10795)
		(layer "F.Cu")
		(net "FAN_PWM_OUT_SYS0_R1")
	)
	(segment
		(start 9.21004 -32.44342)
		(end 9.21004 -34.074354)
		(width 0.10795)
		(layer "F.Cu")
		(net "FAN_PWM_OUT_SYS0_R1")
	)
	(segment
		(start 5.76199 -32.42183)
		(end 5.76199 -32.91459)
		(width 0.10795)
		(layer "F.Cu")
		(net "FAN_PWM_OUT_SYS0_R1")
	)
	(segment
		(start 7.93369 -32.91459)
		(end 8.039608 -33.020508)
		(width 0.10795)
		(layer "F.Cu")
		(net "FAN_PWM_OUT_SYS0_R1")
	)
	(segment
		(start 11.328654 -37.719)
		(end 13.2334 -37.719)
		(width 0.10795)
		(layer "F.Cu")
		(net "FAN_PWM_OUT_SYS0_R1")
	)
	(segment
		(start 7.57174 -32.91459)
		(end 7.57174 -32.42183)
		(width 0.10795)
		(layer "F.Cu")
		(net "FAN_PWM_OUT_SYS0_R1")
	)
	(segment
		(start 6.84784 -32.91459)
		(end 6.84784 -32.42183)
		(width 0.10795)
		(layer "F.Cu")
		(net "FAN_PWM_OUT_SYS0_R1")
	)
	(segment
		(start 5.505958 -32.315912)
		(end 5.656072 -32.315912)
		(width 0.10795)
		(layer "F.Cu")
		(net "FAN_PWM_OUT_SYS0_R1")
	)
	(segment
		(start 10.12063 -35.083496)
		(end 10.27049 -35.083496)
		(width 0.10795)
		(layer "F.Cu")
		(net "FAN_PWM_OUT_SYS0_R1")
	)
	(segment
		(start 7.103872 -32.315912)
		(end 7.20979 -32.42183)
		(width 0.10795)
		(layer "F.Cu")
		(net "FAN_PWM_OUT_SYS0_R1")
	)
	(segment
		(start 8.189722 -33.020508)
		(end 8.29564 -32.91459)
		(width 0.10795)
		(layer "F.Cu")
		(net "FAN_PWM_OUT_SYS0_R1")
	)
	(segment
		(start 8.777732 -35.168078)
		(end 9.33196 -35.722306)
		(width 0.10795)
		(layer "F.Cu")
		(net "FAN_PWM_OUT_SYS0_R1")
	)
	(segment
		(start 6.48589 -32.91459)
		(end 6.591808 -33.020508)
		(width 0.10795)
		(layer "F.Cu")
		(net "FAN_PWM_OUT_SYS0_R1")
	)
	(segment
		(start 6.953758 -32.315912)
		(end 7.103872 -32.315912)
		(width 0.10795)
		(layer "F.Cu")
		(net "FAN_PWM_OUT_SYS0_R1")
	)
	(segment
		(start 7.20979 -32.91459)
		(end 7.315708 -33.020508)
		(width 0.10795)
		(layer "F.Cu")
		(net "FAN_PWM_OUT_SYS0_R1")
	)
	(segment
		(start 6.379972 -32.315912)
		(end 6.48589 -32.42183)
		(width 0.10795)
		(layer "F.Cu")
		(net "FAN_PWM_OUT_SYS0_R1")
	)
	(segment
		(start 10.888726 -35.701732)
		(end 10.888726 -35.851592)
		(width 0.10795)
		(layer "F.Cu")
		(net "FAN_PWM_OUT_SYS0_R1")
	)
	(segment
		(start 6.018022 -33.020508)
		(end 6.12394 -32.91459)
		(width 0.10795)
		(layer "F.Cu")
		(net "FAN_PWM_OUT_SYS0_R1")
	)
	(segment
		(start 8.039608 -33.020508)
		(end 8.189722 -33.020508)
		(width 0.10795)
		(layer "F.Cu")
		(net "FAN_PWM_OUT_SYS0_R1")
	)
	(segment
		(start 10.376662 -35.339528)
		(end 9.737852 -35.978338)
		(width 0.10795)
		(layer "F.Cu")
		(net "FAN_PWM_OUT_SYS0_R1")
	)
	(segment
		(start 9.737852 -35.978338)
		(end 9.737852 -36.128198)
		(width 0.10795)
		(layer "F.Cu")
		(net "FAN_PWM_OUT_SYS0_R1")
	)
	(segment
		(start 7.677658 -32.315912)
		(end 7.827772 -32.315912)
		(width 0.10795)
		(layer "F.Cu")
		(net "FAN_PWM_OUT_SYS0_R1")
	)
	(segment
		(start 7.465822 -33.020508)
		(end 7.57174 -32.91459)
		(width 0.10795)
		(layer "F.Cu")
		(net "FAN_PWM_OUT_SYS0_R1")
	)
	(segment
		(start 6.741922 -33.020508)
		(end 6.84784 -32.91459)
		(width 0.10795)
		(layer "F.Cu")
		(net "FAN_PWM_OUT_SYS0_R1")
	)
	(segment
		(start 5.03809 -32.91459)
		(end 5.144008 -33.020508)
		(width 0.10795)
		(layer "F.Cu")
		(net "FAN_PWM_OUT_SYS0_R1")
	)
	(segment
		(start 8.777732 -34.506662)
		(end 8.777732 -35.168078)
		(width 0.10795)
		(layer "F.Cu")
		(net "FAN_PWM_OUT_SYS0_R1")
	)
	(segment
		(start 7.827772 -32.315912)
		(end 7.93369 -32.42183)
		(width 0.10795)
		(layer "F.Cu")
		(net "FAN_PWM_OUT_SYS0_R1")
	)
	(segment
		(start 6.12394 -32.42183)
		(end 6.229858 -32.315912)
		(width 0.10795)
		(layer "F.Cu")
		(net "FAN_PWM_OUT_SYS0_R1")
	)
	(segment
		(start 4.932172 -32.315912)
		(end 5.03809 -32.42183)
		(width 0.10795)
		(layer "F.Cu")
		(net "FAN_PWM_OUT_SYS0_R1")
	)
	(segment
		(start 7.315708 -33.020508)
		(end 7.465822 -33.020508)
		(width 0.10795)
		(layer "F.Cu")
		(net "FAN_PWM_OUT_SYS0_R1")
	)
	(segment
		(start 8.29564 -32.91459)
		(end 8.29564 -32.42183)
		(width 0.10795)
		(layer "F.Cu")
		(net "FAN_PWM_OUT_SYS0_R1")
	)
	(segment
		(start 9.993884 -36.23437)
		(end 10.632694 -35.59556)
		(width 0.10795)
		(layer "F.Cu")
		(net "FAN_PWM_OUT_SYS0_R1")
	)
	(segment
		(start 9.33196 -35.722306)
		(end 9.48182 -35.722306)
		(width 0.10795)
		(layer "F.Cu")
		(net "FAN_PWM_OUT_SYS0_R1")
	)
	(segment
		(start 2.999994 -33.710118)
		(end 2.999994 -32.70377)
		(width 0.10795)
		(layer "F.Cu")
		(net "FAN_PWM_OUT_SYS0_R1")
	)
	(segment
		(start 10.782554 -35.59556)
		(end 10.888726 -35.701732)
		(width 0.10795)
		(layer "F.Cu")
		(net "FAN_PWM_OUT_SYS0_R1")
	)
	(segment
		(start 5.76199 -32.91459)
		(end 5.867908 -33.020508)
		(width 0.10795)
		(layer "F.Cu")
		(net "FAN_PWM_OUT_SYS0_R1")
	)
	(segment
		(start 6.84784 -32.42183)
		(end 6.953758 -32.315912)
		(width 0.10795)
		(layer "F.Cu")
		(net "FAN_PWM_OUT_SYS0_R1")
	)
	(segment
		(start 3.387852 -32.315912)
		(end 4.932172 -32.315912)
		(width 0.10795)
		(layer "F.Cu")
		(net "FAN_PWM_OUT_SYS0_R1")
	)
	(segment
		(start 5.144008 -33.020508)
		(end 5.294122 -33.020508)
		(width 0.10795)
		(layer "F.Cu")
		(net "FAN_PWM_OUT_SYS0_R1")
	)
	(segment
		(start 10.376662 -35.189668)
		(end 10.376662 -35.339528)
		(width 0.10795)
		(layer "F.Cu")
		(net "FAN_PWM_OUT_SYS0_R1")
	)
	(segment
		(start 7.93369 -32.42183)
		(end 7.93369 -32.91459)
		(width 0.10795)
		(layer "F.Cu")
		(net "FAN_PWM_OUT_SYS0_R1")
	)
	(segment
		(start 10.27049 -35.083496)
		(end 10.376662 -35.189668)
		(width 0.10795)
		(layer "F.Cu")
		(net "FAN_PWM_OUT_SYS0_R1")
	)
	(segment
		(start 2.999994 -32.70377)
		(end 3.387852 -32.315912)
		(width 0.10795)
		(layer "F.Cu")
		(net "FAN_PWM_OUT_SYS0_R1")
	)
	(segment
		(start 5.867908 -33.020508)
		(end 6.018022 -33.020508)
		(width 0.10795)
		(layer "F.Cu")
		(net "FAN_PWM_OUT_SYS0_R1")
	)
	(segment
		(start 5.40004 -32.42183)
		(end 5.505958 -32.315912)
		(width 0.10795)
		(layer "F.Cu")
		(net "FAN_PWM_OUT_SYS0_R1")
	)
	(segment
		(start 8.29564 -32.42183)
		(end 8.401558 -32.315912)
		(width 0.10795)
		(layer "F.Cu")
		(net "FAN_PWM_OUT_SYS0_R1")
	)
	(segment
		(start 9.082532 -32.315912)
		(end 9.21004 -32.44342)
		(width 0.10795)
		(layer "F.Cu")
		(net "FAN_PWM_OUT_SYS0_R1")
	)
	(segment
		(start 10.249916 -36.640262)
		(end 11.328654 -37.719)
		(width 0.10795)
		(layer "F.Cu")
		(net "FAN_PWM_OUT_SYS0_R1")
	)
	(segment
		(start 8.401558 -32.315912)
		(end 9.082532 -32.315912)
		(width 0.10795)
		(layer "F.Cu")
		(net "FAN_PWM_OUT_SYS0_R1")
	)
	(segment
		(start 9.48182 -35.722306)
		(end 10.12063 -35.083496)
		(width 0.10795)
		(layer "F.Cu")
		(net "FAN_PWM_OUT_SYS0_R1")
	)
	(segment
		(start 5.03809 -32.42183)
		(end 5.03809 -32.91459)
		(width 0.10795)
		(layer "F.Cu")
		(net "FAN_PWM_OUT_SYS0_R1")
	)
	(segment
		(start 6.12394 -32.91459)
		(end 6.12394 -32.42183)
		(width 0.10795)
		(layer "F.Cu")
		(net "FAN_PWM_OUT_SYS0_R1")
	)
	(segment
		(start 5.294122 -33.020508)
		(end 5.40004 -32.91459)
		(width 0.10795)
		(layer "F.Cu")
		(net "FAN_PWM_OUT_SYS0_R1")
	)
	(segment
		(start 6.48589 -32.42183)
		(end 6.48589 -32.91459)
		(width 0.10795)
		(layer "F.Cu")
		(net "FAN_PWM_OUT_SYS0_R1")
	)
	(segment
		(start 9.21004 -34.074354)
		(end 8.777732 -34.506662)
		(width 0.10795)
		(layer "F.Cu")
		(net "FAN_PWM_OUT_SYS0_R1")
	)
	(segment
		(start 6.229858 -32.315912)
		(end 6.379972 -32.315912)
		(width 0.10795)
		(layer "F.Cu")
		(net "FAN_PWM_OUT_SYS0_R1")
	)
	(segment
		(start 7.57174 -32.42183)
		(end 7.677658 -32.315912)
		(width 0.10795)
		(layer "F.Cu")
		(net "FAN_PWM_OUT_SYS0_R1")
	)
	(segment
		(start 10.632694 -35.59556)
		(end 10.782554 -35.59556)
		(width 0.10795)
		(layer "F.Cu")
		(net "FAN_PWM_OUT_SYS0_R1")
	)
	(segment
		(start 5.656072 -32.315912)
		(end 5.76199 -32.42183)
		(width 0.10795)
		(layer "F.Cu")
		(net "FAN_PWM_OUT_SYS0_R1")
	)
	(segment
		(start 9.737852 -36.128198)
		(end 9.844024 -36.23437)
		(width 0.10795)
		(layer "F.Cu")
		(net "FAN_PWM_OUT_SYS0_R1")
	)
	(segment
		(start 1.96977 -34.740596)
		(end -4.722368 -34.740596)
		(width 0.10795)
		(layer "B.Cu")
		(net "FAN_PWM_OUT_SYS0_R1")
	)
	(segment
		(start 2.999994 -33.710372)
		(end 1.96977 -34.740596)
		(width 0.10795)
		(layer "B.Cu")
		(net "FAN_PWM_OUT_SYS0_R1")
	)
	(segment
		(start 1.143 -40.386)
		(end 7.689088 -40.386)
		(width 0.10795)
		(layer "B.Cu")
		(net "FAN_PWM_OUT_SYS0_R1")
	)
	(segment
		(start 8.21055 -39.864538)
		(end 10.756138 -39.864538)
		(width 0.10795)
		(layer "B.Cu")
		(net "FAN_PWM_OUT_SYS0_R1")
	)
	(segment
		(start -4.722368 -34.740596)
		(end -4.984496 -35.002724)
		(width 0.10795)
		(layer "B.Cu")
		(net "FAN_PWM_OUT_SYS0_R1")
	)
	(segment
		(start 1.094994 -40.337994)
		(end 1.143 -40.386)
		(width 0.10795)
		(layer "B.Cu")
		(net "FAN_PWM_OUT_SYS0_R1")
	)
	(segment
		(start 11.4046 -40.513)
		(end 13.081 -40.513)
		(width 0.10795)
		(layer "B.Cu")
		(net "FAN_PWM_OUT_SYS0_R1")
	)
	(segment
		(start -4.984496 -35.002724)
		(end -4.984496 -40.230044)
		(width 0.10795)
		(layer "B.Cu")
		(net "FAN_PWM_OUT_SYS0_R1")
	)
	(segment
		(start 10.756138 -39.864538)
		(end 11.4046 -40.513)
		(width 0.10795)
		(layer "B.Cu")
		(net "FAN_PWM_OUT_SYS0_R1")
	)
	(segment
		(start -4.984496 -40.230044)
		(end -4.876546 -40.337994)
		(width 0.10795)
		(layer "B.Cu")
		(net "FAN_PWM_OUT_SYS0_R1")
	)
	(segment
		(start 2.999994 -33.710118)
		(end 2.999994 -33.710372)
		(width 0.10795)
		(layer "B.Cu")
		(net "FAN_PWM_OUT_SYS0_R1")
	)
	(segment
		(start 7.689088 -40.386)
		(end 8.21055 -39.864538)
		(width 0.10795)
		(layer "B.Cu")
		(net "FAN_PWM_OUT_SYS0_R1")
	)
	(segment
		(start -4.876546 -40.337994)
		(end 1.094994 -40.337994)
		(width 0.10795)
		(layer "B.Cu")
		(net "FAN_PWM_OUT_SYS0_R1")
	)
	(segment
		(start 464.331558 -132.508498)
		(end 465.118958 -131.721098)
		(width 0.10795)
		(layer "F.Cu")
		(net "XDP_SPI_PCH_MOSI_BOOT_HALT_N")
	)
	(segment
		(start 455.91603 -134.243826)
		(end 456.441302 -133.718554)
		(width 0.10795)
		(layer "F.Cu")
		(net "XDP_SPI_PCH_MOSI_BOOT_HALT_N")
	)
	(segment
		(start 466.193886 -127.129032)
		(end 465.839556 -126.774702)
		(width 0.10795)
		(layer "F.Cu")
		(net "XDP_SPI_PCH_MOSI_BOOT_HALT_N")
	)
	(segment
		(start 465.839556 -126.774702)
		(end 465.569046 -126.774702)
		(width 0.10795)
		(layer "F.Cu")
		(net "XDP_SPI_PCH_MOSI_BOOT_HALT_N")
	)
	(segment
		(start 456.441302 -133.718554)
		(end 456.441302 -132.348732)
		(width 0.10795)
		(layer "F.Cu")
		(net "XDP_SPI_PCH_MOSI_BOOT_HALT_N")
	)
	(segment
		(start 406.197054 -64.921638)
		(end 406.197054 -64.298068)
		(width 0.10795)
		(layer "F.Cu")
		(net "XDP_SPI_PCH_MOSI_BOOT_HALT_N")
	)
	(segment
		(start 460.480156 -132.515356)
		(end 463.580988 -132.515356)
		(width 0.10795)
		(layer "F.Cu")
		(net "XDP_SPI_PCH_MOSI_BOOT_HALT_N")
	)
	(segment
		(start 459.986634 -132.021834)
		(end 460.480156 -132.515356)
		(width 0.10795)
		(layer "F.Cu")
		(net "XDP_SPI_PCH_MOSI_BOOT_HALT_N")
	)
	(segment
		(start 455.91603 -136.611868)
		(end 455.91603 -134.243826)
		(width 0.10795)
		(layer "F.Cu")
		(net "XDP_SPI_PCH_MOSI_BOOT_HALT_N")
	)
	(segment
		(start 456.7682 -132.021834)
		(end 459.986634 -132.021834)
		(width 0.10795)
		(layer "F.Cu")
		(net "XDP_SPI_PCH_MOSI_BOOT_HALT_N")
	)
	(segment
		(start 405.987504 -65.131188)
		(end 406.197054 -64.921638)
		(width 0.10795)
		(layer "F.Cu")
		(net "XDP_SPI_PCH_MOSI_BOOT_HALT_N")
	)
	(segment
		(start 463.587846 -132.508498)
		(end 464.331558 -132.508498)
		(width 0.10795)
		(layer "F.Cu")
		(net "XDP_SPI_PCH_MOSI_BOOT_HALT_N")
	)
	(segment
		(start 456.02398 -136.719818)
		(end 455.91603 -136.611868)
		(width 0.10795)
		(layer "F.Cu")
		(net "XDP_SPI_PCH_MOSI_BOOT_HALT_N")
	)
	(segment
		(start 466.444584 -124.293884)
		(end 466.444584 -122.262646)
		(width 0.10795)
		(layer "F.Cu")
		(net "XDP_SPI_PCH_MOSI_BOOT_HALT_N")
	)
	(segment
		(start 463.580988 -132.515356)
		(end 463.587846 -132.508498)
		(width 0.10795)
		(layer "F.Cu")
		(net "XDP_SPI_PCH_MOSI_BOOT_HALT_N")
	)
	(segment
		(start 456.441302 -132.348732)
		(end 456.7682 -132.021834)
		(width 0.10795)
		(layer "F.Cu")
		(net "XDP_SPI_PCH_MOSI_BOOT_HALT_N")
	)
	(segment
		(start 405.899112 -65.131188)
		(end 405.987504 -65.131188)
		(width 0.10795)
		(layer "F.Cu")
		(net "XDP_SPI_PCH_MOSI_BOOT_HALT_N")
	)
	(segment
		(start 465.118958 -131.721098)
		(end 465.118958 -131.624324)
		(width 0.10795)
		(layer "F.Cu")
		(net "XDP_SPI_PCH_MOSI_BOOT_HALT_N")
	)
	(segment
		(start 465.569046 -126.774702)
		(end 465.299298 -126.504954)
		(width 0.10795)
		(layer "F.Cu")
		(net "XDP_SPI_PCH_MOSI_BOOT_HALT_N")
	)
	(segment
		(start 465.299298 -126.504954)
		(end 465.299298 -125.43917)
		(width 0.10795)
		(layer "F.Cu")
		(net "XDP_SPI_PCH_MOSI_BOOT_HALT_N")
	)
	(segment
		(start 465.118958 -131.624324)
		(end 466.193886 -130.549396)
		(width 0.10795)
		(layer "F.Cu")
		(net "XDP_SPI_PCH_MOSI_BOOT_HALT_N")
	)
	(segment
		(start 466.193886 -130.549396)
		(end 466.193886 -127.129032)
		(width 0.10795)
		(layer "F.Cu")
		(net "XDP_SPI_PCH_MOSI_BOOT_HALT_N")
	)
	(segment
		(start 457.252578 -136.719818)
		(end 456.02398 -136.719818)
		(width 0.10795)
		(layer "F.Cu")
		(net "XDP_SPI_PCH_MOSI_BOOT_HALT_N")
	)
	(segment
		(start 465.299298 -125.43917)
		(end 466.444584 -124.293884)
		(width 0.10795)
		(layer "F.Cu")
		(net "XDP_SPI_PCH_MOSI_BOOT_HALT_N")
	)
	(via
		(at 400.322796 -91.3384)
		(size 0.508)
		(drill 0.254)
		(layers "F.Cu" "B.Cu")
		(net "XDP_SPI_PCH_MOSI_BOOT_HALT_N")
	)
	(via
		(at 428.686214 -118.614952)
		(size 0.508)
		(drill 0.254)
		(layers "F.Cu" "B.Cu")
		(net "XDP_SPI_PCH_MOSI_BOOT_HALT_N")
	)
	(via
		(at 405.899112 -65.131188)
		(size 0.508)
		(drill 0.254)
		(layers "F.Cu" "B.Cu")
		(net "XDP_SPI_PCH_MOSI_BOOT_HALT_N")
	)
	(via
		(at 414.2232 -96.139)
		(size 0.508)
		(drill 0.254)
		(layers "F.Cu" "B.Cu")
		(net "XDP_SPI_PCH_MOSI_BOOT_HALT_N")
	)
	(via
		(at 466.444584 -122.262646)
		(size 0.508)
		(drill 0.254)
		(layers "F.Cu" "B.Cu")
		(net "XDP_SPI_PCH_MOSI_BOOT_HALT_N")
	)
	(segment
		(start 399.798032 -74.1172)
		(end 399.798032 -77.214984)
		(width 0.089408)
		(layer "In2.Cu")
		(net "XDP_SPI_PCH_MOSI_BOOT_HALT_N")
	)
	(segment
		(start 424.999404 -118.202456)
		(end 424.471084 -117.674136)
		(width 0.089408)
		(layer "In2.Cu")
		(net "XDP_SPI_PCH_MOSI_BOOT_HALT_N")
	)
	(segment
		(start 414.865566 -116.386356)
		(end 414.865566 -116.090192)
		(width 0.089408)
		(layer "In2.Cu")
		(net "XDP_SPI_PCH_MOSI_BOOT_HALT_N")
	)
	(segment
		(start 414.593024 -111.852456)
		(end 414.593024 -109.163612)
		(width 0.089408)
		(layer "In2.Cu")
		(net "XDP_SPI_PCH_MOSI_BOOT_HALT_N")
	)
	(segment
		(start 414.86582 -112.738916)
		(end 414.59277 -112.465866)
		(width 0.089408)
		(layer "In2.Cu")
		(net "XDP_SPI_PCH_MOSI_BOOT_HALT_N")
	)
	(segment
		(start 425.00042 -118.202456)
		(end 424.999404 -118.202456)
		(width 0.089408)
		(layer "In2.Cu")
		(net "XDP_SPI_PCH_MOSI_BOOT_HALT_N")
	)
	(segment
		(start 427.970188 -118.288816)
		(end 425.08678 -118.288816)
		(width 0.089408)
		(layer "In2.Cu")
		(net "XDP_SPI_PCH_MOSI_BOOT_HALT_N")
	)
	(segment
		(start 399.382234 -82.450178)
		(end 400.322796 -83.39074)
		(width 0.089408)
		(layer "In2.Cu")
		(net "XDP_SPI_PCH_MOSI_BOOT_HALT_N")
	)
	(segment
		(start 401.4978 -63.8302)
		(end 401.4978 -64.60236)
		(width 0.089408)
		(layer "In2.Cu")
		(net "XDP_SPI_PCH_MOSI_BOOT_HALT_N")
	)
	(segment
		(start 396.127224 -70.446392)
		(end 399.798032 -74.1172)
		(width 0.089408)
		(layer "In2.Cu")
		(net "XDP_SPI_PCH_MOSI_BOOT_HALT_N")
	)
	(segment
		(start 423.293032 -117.674136)
		(end 422.722294 -118.244874)
		(width 0.089408)
		(layer "In2.Cu")
		(net "XDP_SPI_PCH_MOSI_BOOT_HALT_N")
	)
	(segment
		(start 428.603664 -118.532402)
		(end 428.213774 -118.532402)
		(width 0.089408)
		(layer "In2.Cu")
		(net "XDP_SPI_PCH_MOSI_BOOT_HALT_N")
	)
	(segment
		(start 399.38452 -66.71564)
		(end 396.197328 -66.71564)
		(width 0.089408)
		(layer "In2.Cu")
		(net "XDP_SPI_PCH_MOSI_BOOT_HALT_N")
	)
	(segment
		(start 399.952464 -77.369416)
		(end 399.952464 -80.42783)
		(width 0.089408)
		(layer "In2.Cu")
		(net "XDP_SPI_PCH_MOSI_BOOT_HALT_N")
	)
	(segment
		(start 401.957286 -63.370714)
		(end 401.4978 -63.8302)
		(width 0.089408)
		(layer "In2.Cu")
		(net "XDP_SPI_PCH_MOSI_BOOT_HALT_N")
	)
	(segment
		(start 428.213774 -118.532402)
		(end 427.970188 -118.288816)
		(width 0.089408)
		(layer "In2.Cu")
		(net "XDP_SPI_PCH_MOSI_BOOT_HALT_N")
	)
	(segment
		(start 399.382234 -80.99806)
		(end 399.382234 -82.450178)
		(width 0.089408)
		(layer "In2.Cu")
		(net "XDP_SPI_PCH_MOSI_BOOT_HALT_N")
	)
	(segment
		(start 415.159444 -103.406702)
		(end 415.159444 -97.075244)
		(width 0.089408)
		(layer "In2.Cu")
		(net "XDP_SPI_PCH_MOSI_BOOT_HALT_N")
	)
	(segment
		(start 401.4978 -64.60236)
		(end 399.38452 -66.71564)
		(width 0.089408)
		(layer "In2.Cu")
		(net "XDP_SPI_PCH_MOSI_BOOT_HALT_N")
	)
	(segment
		(start 399.798032 -77.214984)
		(end 399.952464 -77.369416)
		(width 0.089408)
		(layer "In2.Cu")
		(net "XDP_SPI_PCH_MOSI_BOOT_HALT_N")
	)
	(segment
		(start 414.816036 -108.04144)
		(end 413.563054 -106.788458)
		(width 0.089408)
		(layer "In2.Cu")
		(net "XDP_SPI_PCH_MOSI_BOOT_HALT_N")
	)
	(segment
		(start 414.59277 -111.85271)
		(end 414.593024 -111.852456)
		(width 0.089408)
		(layer "In2.Cu")
		(net "XDP_SPI_PCH_MOSI_BOOT_HALT_N")
	)
	(segment
		(start 428.686214 -118.614952)
		(end 428.603664 -118.532402)
		(width 0.089408)
		(layer "In2.Cu")
		(net "XDP_SPI_PCH_MOSI_BOOT_HALT_N")
	)
	(segment
		(start 413.563054 -106.788458)
		(end 413.563054 -105.003092)
		(width 0.089408)
		(layer "In2.Cu")
		(net "XDP_SPI_PCH_MOSI_BOOT_HALT_N")
	)
	(segment
		(start 414.86582 -116.089938)
		(end 414.86582 -112.738916)
		(width 0.089408)
		(layer "In2.Cu")
		(net "XDP_SPI_PCH_MOSI_BOOT_HALT_N")
	)
	(segment
		(start 414.865566 -116.090192)
		(end 414.86582 -116.089938)
		(width 0.089408)
		(layer "In2.Cu")
		(net "XDP_SPI_PCH_MOSI_BOOT_HALT_N")
	)
	(segment
		(start 405.745188 -65.131188)
		(end 403.984714 -63.370714)
		(width 0.089408)
		(layer "In2.Cu")
		(net "XDP_SPI_PCH_MOSI_BOOT_HALT_N")
	)
	(segment
		(start 396.127224 -66.785744)
		(end 396.127224 -70.446392)
		(width 0.089408)
		(layer "In2.Cu")
		(net "XDP_SPI_PCH_MOSI_BOOT_HALT_N")
	)
	(segment
		(start 405.899112 -65.131188)
		(end 405.745188 -65.131188)
		(width 0.089408)
		(layer "In2.Cu")
		(net "XDP_SPI_PCH_MOSI_BOOT_HALT_N")
	)
	(segment
		(start 414.59277 -112.465866)
		(end 414.59277 -111.85271)
		(width 0.089408)
		(layer "In2.Cu")
		(net "XDP_SPI_PCH_MOSI_BOOT_HALT_N")
	)
	(segment
		(start 396.197328 -66.71564)
		(end 396.127224 -66.785744)
		(width 0.089408)
		(layer "In2.Cu")
		(net "XDP_SPI_PCH_MOSI_BOOT_HALT_N")
	)
	(segment
		(start 400.322796 -83.39074)
		(end 400.322796 -91.3384)
		(width 0.089408)
		(layer "In2.Cu")
		(net "XDP_SPI_PCH_MOSI_BOOT_HALT_N")
	)
	(segment
		(start 413.563054 -105.003092)
		(end 415.159444 -103.406702)
		(width 0.089408)
		(layer "In2.Cu")
		(net "XDP_SPI_PCH_MOSI_BOOT_HALT_N")
	)
	(segment
		(start 424.471084 -117.674136)
		(end 423.293032 -117.674136)
		(width 0.089408)
		(layer "In2.Cu")
		(net "XDP_SPI_PCH_MOSI_BOOT_HALT_N")
	)
	(segment
		(start 425.08678 -118.288816)
		(end 425.00042 -118.202456)
		(width 0.089408)
		(layer "In2.Cu")
		(net "XDP_SPI_PCH_MOSI_BOOT_HALT_N")
	)
	(segment
		(start 414.593024 -109.163612)
		(end 414.816036 -108.9406)
		(width 0.089408)
		(layer "In2.Cu")
		(net "XDP_SPI_PCH_MOSI_BOOT_HALT_N")
	)
	(segment
		(start 422.722294 -118.244874)
		(end 416.724084 -118.244874)
		(width 0.089408)
		(layer "In2.Cu")
		(net "XDP_SPI_PCH_MOSI_BOOT_HALT_N")
	)
	(segment
		(start 414.816036 -108.9406)
		(end 414.816036 -108.04144)
		(width 0.089408)
		(layer "In2.Cu")
		(net "XDP_SPI_PCH_MOSI_BOOT_HALT_N")
	)
	(segment
		(start 403.984714 -63.370714)
		(end 401.957286 -63.370714)
		(width 0.089408)
		(layer "In2.Cu")
		(net "XDP_SPI_PCH_MOSI_BOOT_HALT_N")
	)
	(segment
		(start 399.952464 -80.42783)
		(end 399.382234 -80.99806)
		(width 0.089408)
		(layer "In2.Cu")
		(net "XDP_SPI_PCH_MOSI_BOOT_HALT_N")
	)
	(segment
		(start 416.724084 -118.244874)
		(end 414.865566 -116.386356)
		(width 0.089408)
		(layer "In2.Cu")
		(net "XDP_SPI_PCH_MOSI_BOOT_HALT_N")
	)
	(segment
		(start 415.159444 -97.075244)
		(end 414.2232 -96.139)
		(width 0.089408)
		(layer "In2.Cu")
		(net "XDP_SPI_PCH_MOSI_BOOT_HALT_N")
	)
	(segment
		(start 413.0548 -94.9706)
		(end 413.0548 -93.6879)
		(width 0.089408)
		(layer "In4.Cu")
		(net "XDP_SPI_PCH_MOSI_BOOT_HALT_N")
	)
	(segment
		(start 413.0548 -93.6879)
		(end 412.20898 -92.84208)
		(width 0.089408)
		(layer "In4.Cu")
		(net "XDP_SPI_PCH_MOSI_BOOT_HALT_N")
	)
	(segment
		(start 403.9616 -93.03004)
		(end 402.620734 -93.03004)
		(width 0.089408)
		(layer "In4.Cu")
		(net "XDP_SPI_PCH_MOSI_BOOT_HALT_N")
	)
	(segment
		(start 407.215594 -91.84386)
		(end 405.14778 -91.84386)
		(width 0.089408)
		(layer "In4.Cu")
		(net "XDP_SPI_PCH_MOSI_BOOT_HALT_N")
	)
	(segment
		(start 400.929094 -91.3384)
		(end 400.322796 -91.3384)
		(width 0.089408)
		(layer "In4.Cu")
		(net "XDP_SPI_PCH_MOSI_BOOT_HALT_N")
	)
	(segment
		(start 408.213814 -92.84208)
		(end 407.215594 -91.84386)
		(width 0.089408)
		(layer "In4.Cu")
		(net "XDP_SPI_PCH_MOSI_BOOT_HALT_N")
	)
	(segment
		(start 402.620734 -93.03004)
		(end 400.929094 -91.3384)
		(width 0.089408)
		(layer "In4.Cu")
		(net "XDP_SPI_PCH_MOSI_BOOT_HALT_N")
	)
	(segment
		(start 414.2232 -96.139)
		(end 413.0548 -94.9706)
		(width 0.089408)
		(layer "In4.Cu")
		(net "XDP_SPI_PCH_MOSI_BOOT_HALT_N")
	)
	(segment
		(start 412.20898 -92.84208)
		(end 408.213814 -92.84208)
		(width 0.089408)
		(layer "In4.Cu")
		(net "XDP_SPI_PCH_MOSI_BOOT_HALT_N")
	)
	(segment
		(start 405.14778 -91.84386)
		(end 403.9616 -93.03004)
		(width 0.089408)
		(layer "In4.Cu")
		(net "XDP_SPI_PCH_MOSI_BOOT_HALT_N")
	)
	(segment
		(start 463.352896 -119.939816)
		(end 464.409028 -119.939816)
		(width 0.089408)
		(layer "In9.Cu")
		(net "XDP_SPI_PCH_MOSI_BOOT_HALT_N")
	)
	(segment
		(start 434.857652 -119.800878)
		(end 436.979314 -117.679216)
		(width 0.089408)
		(layer "In9.Cu")
		(net "XDP_SPI_PCH_MOSI_BOOT_HALT_N")
	)
	(segment
		(start 429.87214 -119.800878)
		(end 434.857652 -119.800878)
		(width 0.089408)
		(layer "In9.Cu")
		(net "XDP_SPI_PCH_MOSI_BOOT_HALT_N")
	)
	(segment
		(start 463.331306 -119.961406)
		(end 463.352896 -119.939816)
		(width 0.089408)
		(layer "In9.Cu")
		(net "XDP_SPI_PCH_MOSI_BOOT_HALT_N")
	)
	(segment
		(start 464.409028 -119.939816)
		(end 466.444584 -121.975372)
		(width 0.089408)
		(layer "In9.Cu")
		(net "XDP_SPI_PCH_MOSI_BOOT_HALT_N")
	)
	(segment
		(start 459.620112 -119.11203)
		(end 460.469488 -119.961406)
		(width 0.089408)
		(layer "In9.Cu")
		(net "XDP_SPI_PCH_MOSI_BOOT_HALT_N")
	)
	(segment
		(start 441.73521 -119.11203)
		(end 459.620112 -119.11203)
		(width 0.089408)
		(layer "In9.Cu")
		(net "XDP_SPI_PCH_MOSI_BOOT_HALT_N")
	)
	(segment
		(start 466.444584 -121.975372)
		(end 466.444584 -122.262646)
		(width 0.089408)
		(layer "In9.Cu")
		(net "XDP_SPI_PCH_MOSI_BOOT_HALT_N")
	)
	(segment
		(start 460.469488 -119.961406)
		(end 463.331306 -119.961406)
		(width 0.089408)
		(layer "In9.Cu")
		(net "XDP_SPI_PCH_MOSI_BOOT_HALT_N")
	)
	(segment
		(start 436.979314 -117.679216)
		(end 440.302396 -117.679216)
		(width 0.089408)
		(layer "In9.Cu")
		(net "XDP_SPI_PCH_MOSI_BOOT_HALT_N")
	)
	(segment
		(start 428.686214 -118.614952)
		(end 429.87214 -119.800878)
		(width 0.089408)
		(layer "In9.Cu")
		(net "XDP_SPI_PCH_MOSI_BOOT_HALT_N")
	)
	(segment
		(start 440.302396 -117.679216)
		(end 441.73521 -119.11203)
		(width 0.089408)
		(layer "In9.Cu")
		(net "XDP_SPI_PCH_MOSI_BOOT_HALT_N")
	)
	(segment
		(start 399.6182 2.3368)
		(end 400.05 2.7686)
		(width 0.10795)
		(layer "F.Cu")
		(net "JTAG_TCK_R")
	)
	(segment
		(start 399.6182 1.7272)
		(end 399.6182 2.3368)
		(width 0.10795)
		(layer "F.Cu")
		(net "JTAG_TCK_R")
	)
	(segment
		(start 400.05 2.7686)
		(end 400.05 3.81)
		(width 0.10795)
		(layer "F.Cu")
		(net "JTAG_TCK_R")
	)
	(segment
		(start 398.8562 1.7272)
		(end 399.6182 1.7272)
		(width 0.10795)
		(layer "F.Cu")
		(net "JTAG_TCK_R")
	)
	(segment
		(start 387.35 2.8448)
		(end 388.239 1.9558)
		(width 0.10795)
		(layer "F.Cu")
		(net "JTAG_TDI_R")
	)
	(segment
		(start 389.382 1.651)
		(end 388.239 1.651)
		(width 0.10795)
		(layer "F.Cu")
		(net "JTAG_TDI_R")
	)
	(segment
		(start 388.239 1.9558)
		(end 388.239 1.651)
		(width 0.10795)
		(layer "F.Cu")
		(net "JTAG_TDI_R")
	)
	(segment
		(start 387.35 3.81)
		(end 387.35 2.8448)
		(width 0.10795)
		(layer "F.Cu")
		(net "JTAG_TDI_R")
	)
	(via
		(at 387.35 0.403098)
		(size 0.6604)
		(drill 0.3302)
		(layers "F.Cu" "B.Cu")
		(net "JTAG_TDI_R")
	)
	(segment
		(start 387.35 3.81)
		(end 387.35 0.403098)
		(width 0.10795)
		(layer "B.Cu")
		(net "JTAG_TDI_R")
	)
	(segment
		(start 384.81 2.8194)
		(end 384.81 3.81)
		(width 0.10795)
		(layer "F.Cu")
		(net "JTAG_TDO_R")
	)
	(segment
		(start 385.2164 2.413)
		(end 384.81 2.8194)
		(width 0.10795)
		(layer "F.Cu")
		(net "JTAG_TDO_R")
	)
	(segment
		(start 385.2164 1.651)
		(end 385.2164 2.413)
		(width 0.10795)
		(layer "F.Cu")
		(net "JTAG_TDO_R")
	)
	(segment
		(start 384.175 1.651)
		(end 385.2164 1.651)
		(width 0.10795)
		(layer "F.Cu")
		(net "JTAG_TDO_R")
	)
	(via
		(at 384.81 0.823468)
		(size 0.6604)
		(drill 0.3302)
		(layers "F.Cu" "B.Cu")
		(net "JTAG_TDO_R")
	)
	(segment
		(start 384.81 0.823468)
		(end 384.81 3.81)
		(width 0.10795)
		(layer "B.Cu")
		(net "JTAG_TDO_R")
	)
	(segment
		(start 70.324726 -100.662486)
		(end 69.753226 -100.662486)
		(width 0.10795)
		(layer "F.Cu")
		(net "TP_CPU1_RSVD_9")
	)
	(via
		(at 69.753226 -100.662486)
		(size 0.508)
		(drill 0.254)
		(layers "F.Cu" "B.Cu")
		(net "TP_CPU1_RSVD_9")
	)
	(segment
		(start 129.372868 -102.958138)
		(end 129.218182 -102.958138)
		(width 0.10795)
		(layer "F.Cu")
		(net "TP_CPU1_RSVD_8")
	)
	(segment
		(start 129.218182 -102.958138)
		(end 128.227328 -101.967284)
		(width 0.10795)
		(layer "F.Cu")
		(net "TP_CPU1_RSVD_8")
	)
	(via
		(at 128.227328 -101.967284)
		(size 0.4826)
		(drill 0.254)
		(layers "F.Cu" "B.Cu")
		(net "TP_CPU1_RSVD_8")
	)
	(segment
		(start 116.495322 -87.603584)
		(end 117.066822 -87.603584)
		(width 0.10795)
		(layer "F.Cu")
		(net "TP_CPU1_RSVD_73")
	)
	(via
		(at 117.066822 -87.603584)
		(size 0.508)
		(drill 0.254)
		(layers "F.Cu" "B.Cu")
		(net "TP_CPU1_RSVD_73")
	)
	(segment
		(start 90.070178 -86.29904)
		(end 89.498678 -86.29904)
		(width 0.10795)
		(layer "F.Cu")
		(net "TP_CPU1_RSVD_72")
	)
	(via
		(at 89.498678 -86.29904)
		(size 0.508)
		(drill 0.254)
		(layers "F.Cu" "B.Cu")
		(net "TP_CPU1_RSVD_72")
	)
	(segment
		(start 138.816334 -88.594184)
		(end 139.387834 -88.594184)
		(width 0.10795)
		(layer "F.Cu")
		(net "TP_CPU1_RSVD_70")
	)
	(via
		(at 139.387834 -88.594184)
		(size 0.4826)
		(drill 0.254)
		(layers "F.Cu" "B.Cu")
		(net "TP_CPU1_RSVD_70")
	)
	(segment
		(start 102.089204 -101.15804)
		(end 102.334568 -101.7016)
		(width 0.10795)
		(layer "F.Cu")
		(net "TP_CPU1_RSVD_7")
	)
	(via
		(at 102.334568 -101.7016)
		(size 0.508)
		(drill 0.254)
		(layers "F.Cu" "B.Cu")
		(net "TP_CPU1_RSVD_7")
	)
	(segment
		(start 82.343752 -86.794086)
		(end 81.772252 -86.794086)
		(width 0.10795)
		(layer "F.Cu")
		(net "TP_CPU1_RSVD_69")
	)
	(via
		(at 81.772252 -86.794086)
		(size 0.508)
		(drill 0.254)
		(layers "F.Cu" "B.Cu")
		(net "TP_CPU1_RSVD_69")
	)
	(segment
		(start 137.957814 -89.089738)
		(end 138.529314 -89.089738)
		(width 0.10795)
		(layer "F.Cu")
		(net "TP_CPU1_RSVD_67")
	)
	(via
		(at 138.529314 -89.089738)
		(size 0.4826)
		(drill 0.254)
		(layers "F.Cu" "B.Cu")
		(net "TP_CPU1_RSVD_67")
	)
	(segment
		(start 90.070178 -87.28964)
		(end 89.498678 -87.28964)
		(width 0.10795)
		(layer "F.Cu")
		(net "TP_CPU1_RSVD_66")
	)
	(via
		(at 89.498678 -87.28964)
		(size 0.508)
		(drill 0.254)
		(layers "F.Cu" "B.Cu")
		(net "TP_CPU1_RSVD_66")
	)
	(segment
		(start 90.070178 -88.28024)
		(end 89.498678 -88.28024)
		(width 0.10795)
		(layer "F.Cu")
		(net "TP_CPU1_RSVD_61")
	)
	(via
		(at 89.498678 -88.28024)
		(size 0.508)
		(drill 0.254)
		(layers "F.Cu" "B.Cu")
		(net "TP_CPU1_RSVD_61")
	)
	(segment
		(start 152.6032 -104.4702)
		(end 152.7302 -104.3432)
		(width 0.10795)
		(layer "F.Cu")
		(net "TP_CPU1_RSVD_6")
	)
	(segment
		(start 139.469876 -104.4702)
		(end 152.6032 -104.4702)
		(width 0.10795)
		(layer "F.Cu")
		(net "TP_CPU1_RSVD_6")
	)
	(segment
		(start 137.957814 -102.958138)
		(end 139.469876 -104.4702)
		(width 0.10795)
		(layer "F.Cu")
		(net "TP_CPU1_RSVD_6")
	)
	(via
		(at 152.7302 -104.3432)
		(size 0.762)
		(drill 0.381)
		(layers "F.Cu" "B.Cu")
		(net "TP_CPU1_RSVD_6")
	)
	(segment
		(start 71.183246 -101.15804)
		(end 70.611746 -101.15804)
		(width 0.10795)
		(layer "F.Cu")
		(net "TP_CPU1_RSVD_5")
	)
	(via
		(at 70.611746 -101.15804)
		(size 0.508)
		(drill 0.254)
		(layers "F.Cu" "B.Cu")
		(net "TP_CPU1_RSVD_5")
	)
	(segment
		(start 96.938338 -90.26144)
		(end 96.366838 -90.26144)
		(width 0.10795)
		(layer "F.Cu")
		(net "TP_CPU1_RSVD_46")
	)
	(via
		(at 96.366838 -90.26144)
		(size 0.508)
		(drill 0.254)
		(layers "F.Cu" "B.Cu")
		(net "TP_CPU1_RSVD_46")
	)
	(segment
		(start 97.796858 -90.756486)
		(end 97.225358 -90.756486)
		(width 0.10795)
		(layer "F.Cu")
		(net "TP_CPU1_RSVD_45")
	)
	(via
		(at 97.225358 -90.756486)
		(size 0.508)
		(drill 0.254)
		(layers "F.Cu" "B.Cu")
		(net "TP_CPU1_RSVD_45")
	)
	(segment
		(start 112.202722 -94.042738)
		(end 112.774222 -94.042738)
		(width 0.10795)
		(layer "F.Cu")
		(net "TP_CPU1_RSVD_44")
	)
	(via
		(at 112.774222 -94.042738)
		(size 0.508)
		(drill 0.254)
		(layers "F.Cu" "B.Cu")
		(net "TP_CPU1_RSVD_44")
	)
	(segment
		(start 86.636352 -92.24264)
		(end 86.064852 -92.24264)
		(width 0.10795)
		(layer "F.Cu")
		(net "TP_CPU1_RSVD_43")
	)
	(via
		(at 86.064852 -92.24264)
		(size 0.508)
		(drill 0.254)
		(layers "F.Cu" "B.Cu")
		(net "TP_CPU1_RSVD_43")
	)
	(segment
		(start 85.777832 -92.737686)
		(end 85.206332 -92.737686)
		(width 0.10795)
		(layer "F.Cu")
		(net "TP_CPU1_RSVD_42")
	)
	(via
		(at 85.206332 -92.737686)
		(size 0.508)
		(drill 0.254)
		(layers "F.Cu" "B.Cu")
		(net "TP_CPU1_RSVD_42")
	)
	(segment
		(start 112.773968 -95.033084)
		(end 112.774222 -95.033338)
		(width 0.10795)
		(layer "F.Cu")
		(net "TP_CPU1_RSVD_41")
	)
	(segment
		(start 112.202722 -95.033084)
		(end 112.773968 -95.033084)
		(width 0.10795)
		(layer "F.Cu")
		(net "TP_CPU1_RSVD_41")
	)
	(via
		(at 112.774222 -95.033338)
		(size 0.508)
		(drill 0.254)
		(layers "F.Cu" "B.Cu")
		(net "TP_CPU1_RSVD_41")
	)
	(segment
		(start 84.919312 -93.23324)
		(end 84.347812 -93.23324)
		(width 0.10795)
		(layer "F.Cu")
		(net "TP_CPU1_RSVD_40")
	)
	(via
		(at 84.347812 -93.23324)
		(size 0.508)
		(drill 0.254)
		(layers "F.Cu" "B.Cu")
		(net "TP_CPU1_RSVD_40")
	)
	(segment
		(start 69.466206 -101.15804)
		(end 68.894706 -101.15804)
		(width 0.10795)
		(layer "F.Cu")
		(net "TP_CPU1_RSVD_4")
	)
	(via
		(at 68.894706 -101.15804)
		(size 0.508)
		(drill 0.254)
		(layers "F.Cu" "B.Cu")
		(net "TP_CPU1_RSVD_4")
	)
	(segment
		(start 130.231388 -95.528384)
		(end 130.802888 -95.528384)
		(width 0.10795)
		(layer "F.Cu")
		(net "TP_CPU1_RSVD_39")
	)
	(via
		(at 130.802888 -95.528384)
		(size 0.4826)
		(drill 0.254)
		(layers "F.Cu" "B.Cu")
		(net "TP_CPU1_RSVD_39")
	)
	(segment
		(start 111.344202 -95.528384)
		(end 111.915702 -95.528384)
		(width 0.10795)
		(layer "F.Cu")
		(net "TP_CPU1_RSVD_38")
	)
	(via
		(at 111.915702 -95.528384)
		(size 0.508)
		(drill 0.254)
		(layers "F.Cu" "B.Cu")
		(net "TP_CPU1_RSVD_38")
	)
	(segment
		(start 85.777832 -93.72854)
		(end 85.206332 -93.72854)
		(width 0.10795)
		(layer "F.Cu")
		(net "TP_CPU1_RSVD_37")
	)
	(via
		(at 85.206332 -93.72854)
		(size 0.508)
		(drill 0.254)
		(layers "F.Cu" "B.Cu")
		(net "TP_CPU1_RSVD_37")
	)
	(segment
		(start 84.060792 -93.72854)
		(end 83.489292 -93.72854)
		(width 0.10795)
		(layer "F.Cu")
		(net "TP_CPU1_RSVD_36")
	)
	(via
		(at 83.489292 -93.72854)
		(size 0.508)
		(drill 0.254)
		(layers "F.Cu" "B.Cu")
		(net "TP_CPU1_RSVD_36")
	)
	(segment
		(start 110.485682 -96.023938)
		(end 111.057182 -96.023938)
		(width 0.10795)
		(layer "F.Cu")
		(net "TP_CPU1_RSVD_35")
	)
	(via
		(at 111.057182 -96.023938)
		(size 0.508)
		(drill 0.254)
		(layers "F.Cu" "B.Cu")
		(net "TP_CPU1_RSVD_35")
	)
	(segment
		(start 84.919312 -94.223586)
		(end 84.347812 -94.223586)
		(width 0.10795)
		(layer "F.Cu")
		(net "TP_CPU1_RSVD_34")
	)
	(via
		(at 84.347812 -94.223586)
		(size 0.508)
		(drill 0.254)
		(layers "F.Cu" "B.Cu")
		(net "TP_CPU1_RSVD_34")
	)
	(segment
		(start 84.060792 -94.718886)
		(end 83.489292 -94.718886)
		(width 0.10795)
		(layer "F.Cu")
		(net "TP_CPU1_RSVD_33")
	)
	(via
		(at 83.489292 -94.718886)
		(size 0.508)
		(drill 0.254)
		(layers "F.Cu" "B.Cu")
		(net "TP_CPU1_RSVD_33")
	)
	(segment
		(start 88.353392 -95.21444)
		(end 87.781892 -95.21444)
		(width 0.10795)
		(layer "F.Cu")
		(net "TP_CPU1_RSVD_32")
	)
	(via
		(at 87.781892 -95.21444)
		(size 0.508)
		(drill 0.254)
		(layers "F.Cu" "B.Cu")
		(net "TP_CPU1_RSVD_32")
	)
	(segment
		(start 84.919312 -95.21444)
		(end 84.347812 -95.21444)
		(width 0.10795)
		(layer "F.Cu")
		(net "TP_CPU1_RSVD_31")
	)
	(via
		(at 84.347812 -95.21444)
		(size 0.508)
		(drill 0.254)
		(layers "F.Cu" "B.Cu")
		(net "TP_CPU1_RSVD_31")
	)
	(segment
		(start 128.514348 -97.509584)
		(end 129.085848 -97.509584)
		(width 0.10795)
		(layer "F.Cu")
		(net "TP_CPU1_RSVD_30")
	)
	(via
		(at 129.085848 -97.509584)
		(size 0.4826)
		(drill 0.254)
		(layers "F.Cu" "B.Cu")
		(net "TP_CPU1_RSVD_30")
	)
	(segment
		(start 101.230684 -101.653086)
		(end 101.230684 -102.3366)
		(width 0.10795)
		(layer "F.Cu")
		(net "TP_CPU1_RSVD_3")
	)
	(via
		(at 101.230684 -102.3366)
		(size 0.508)
		(drill 0.254)
		(layers "F.Cu" "B.Cu")
		(net "TP_CPU1_RSVD_3")
	)
	(segment
		(start 85.777832 -95.709486)
		(end 85.206332 -95.709486)
		(width 0.10795)
		(layer "F.Cu")
		(net "TP_CPU1_RSVD_29")
	)
	(via
		(at 85.206332 -95.709486)
		(size 0.508)
		(drill 0.254)
		(layers "F.Cu" "B.Cu")
		(net "TP_CPU1_RSVD_29")
	)
	(segment
		(start 103.806244 -96.20504)
		(end 104.415844 -96.20504)
		(width 0.10795)
		(layer "F.Cu")
		(net "TP_CPU1_RSVD_28")
	)
	(via
		(at 104.415844 -96.20504)
		(size 0.508)
		(drill 0.254)
		(layers "F.Cu" "B.Cu")
		(net "TP_CPU1_RSVD_28")
	)
	(segment
		(start 80.626712 -96.700086)
		(end 80.055212 -96.700086)
		(width 0.10795)
		(layer "F.Cu")
		(net "TP_CPU1_RSVD_27")
	)
	(via
		(at 80.055212 -96.700086)
		(size 0.508)
		(drill 0.254)
		(layers "F.Cu" "B.Cu")
		(net "TP_CPU1_RSVD_27")
	)
	(segment
		(start 103.806244 -97.19564)
		(end 104.415844 -97.19564)
		(width 0.10795)
		(layer "F.Cu")
		(net "TP_CPU1_RSVD_26")
	)
	(via
		(at 104.415844 -97.19564)
		(size 0.508)
		(drill 0.254)
		(layers "F.Cu" "B.Cu")
		(net "TP_CPU1_RSVD_26")
	)
	(segment
		(start 89.211912 -97.690686)
		(end 88.640412 -97.690686)
		(width 0.10795)
		(layer "F.Cu")
		(net "TP_CPU1_RSVD_25")
	)
	(via
		(at 88.640412 -97.690686)
		(size 0.508)
		(drill 0.254)
		(layers "F.Cu" "B.Cu")
		(net "TP_CPU1_RSVD_25")
	)
	(segment
		(start 80.626712 -97.690686)
		(end 80.055212 -97.690686)
		(width 0.10795)
		(layer "F.Cu")
		(net "TP_CPU1_RSVD_24")
	)
	(via
		(at 80.055212 -97.690686)
		(size 0.508)
		(drill 0.254)
		(layers "F.Cu" "B.Cu")
		(net "TP_CPU1_RSVD_24")
	)
	(segment
		(start 103.806244 -98.18624)
		(end 104.415844 -98.18624)
		(width 0.10795)
		(layer "F.Cu")
		(net "TP_CPU1_RSVD_23")
	)
	(via
		(at 104.415844 -98.18624)
		(size 0.508)
		(drill 0.254)
		(layers "F.Cu" "B.Cu")
		(net "TP_CPU1_RSVD_23")
	)
	(segment
		(start 102.089204 -98.18624)
		(end 101.517704 -98.18624)
		(width 0.10795)
		(layer "F.Cu")
		(net "TP_CPU1_RSVD_22")
	)
	(via
		(at 101.517704 -98.18624)
		(size 0.508)
		(drill 0.254)
		(layers "F.Cu" "B.Cu")
		(net "TP_CPU1_RSVD_22")
	)
	(segment
		(start 140.533374 -100.481638)
		(end 140.743686 -100.481638)
		(width 0.10795)
		(layer "F.Cu")
		(net "TP_CPU1_RSVD_21")
	)
	(segment
		(start 140.743686 -100.481638)
		(end 141.112748 -100.8507)
		(width 0.10795)
		(layer "F.Cu")
		(net "TP_CPU1_RSVD_21")
	)
	(segment
		(start 141.112748 -100.8507)
		(end 142.41907 -100.8507)
		(width 0.10795)
		(layer "F.Cu")
		(net "TP_CPU1_RSVD_21")
	)
	(segment
		(start 142.86357 -101.2952)
		(end 151.506174 -101.2952)
		(width 0.10795)
		(layer "F.Cu")
		(net "TP_CPU1_RSVD_21")
	)
	(segment
		(start 142.41907 -100.8507)
		(end 142.86357 -101.2952)
		(width 0.10795)
		(layer "F.Cu")
		(net "TP_CPU1_RSVD_21")
	)
	(via
		(at 151.506174 -101.2952)
		(size 0.762)
		(drill 0.381)
		(layers "F.Cu" "B.Cu")
		(net "TP_CPU1_RSVD_21")
	)
	(segment
		(start 140.8176 -102.5652)
		(end 151.506174 -102.5652)
		(width 0.10795)
		(layer "F.Cu")
		(net "TP_CPU1_RSVD_20")
	)
	(segment
		(start 139.674854 -100.976684)
		(end 139.674854 -101.422454)
		(width 0.10795)
		(layer "F.Cu")
		(net "TP_CPU1_RSVD_20")
	)
	(segment
		(start 139.674854 -101.422454)
		(end 140.8176 -102.5652)
		(width 0.10795)
		(layer "F.Cu")
		(net "TP_CPU1_RSVD_20")
	)
	(via
		(at 151.506174 -102.5652)
		(size 0.762)
		(drill 0.381)
		(layers "F.Cu" "B.Cu")
		(net "TP_CPU1_RSVD_20")
	)
	(segment
		(start 75.475846 -101.653086)
		(end 74.904346 -101.653086)
		(width 0.10795)
		(layer "F.Cu")
		(net "TP_CPU1_RSVD_2")
	)
	(via
		(at 74.904346 -101.653086)
		(size 0.508)
		(drill 0.254)
		(layers "F.Cu" "B.Cu")
		(net "TP_CPU1_RSVD_2")
	)
	(segment
		(start 103.806244 -99.17684)
		(end 104.415844 -99.17684)
		(width 0.10795)
		(layer "F.Cu")
		(net "TP_CPU1_RSVD_19")
	)
	(via
		(at 105.537 -99.5426)
		(size 0.6604)
		(drill 0.3302)
		(layers "F.Cu" "B.Cu")
		(net "TP_CPU1_RSVD_19")
	)
	(via
		(at 104.415844 -99.17684)
		(size 0.508)
		(drill 0.254)
		(layers "F.Cu" "B.Cu")
		(net "TP_CPU1_RSVD_19")
	)
	(segment
		(start 104.415844 -99.17684)
		(end 105.17124 -99.17684)
		(width 0.10795)
		(layer "B.Cu")
		(net "TP_CPU1_RSVD_19")
	)
	(segment
		(start 105.17124 -99.17684)
		(end 105.537 -99.5426)
		(width 0.10795)
		(layer "B.Cu")
		(net "TP_CPU1_RSVD_19")
	)
	(segment
		(start 141.090904 -101.471984)
		(end 141.1605 -101.54158)
		(width 0.10795)
		(layer "F.Cu")
		(net "TP_CPU1_RSVD_18")
	)
	(segment
		(start 140.533374 -101.471984)
		(end 141.090904 -101.471984)
		(width 0.10795)
		(layer "F.Cu")
		(net "TP_CPU1_RSVD_18")
	)
	(via
		(at 141.1605 -101.54158)
		(size 0.508)
		(drill 0.254)
		(layers "F.Cu" "B.Cu")
		(net "TP_CPU1_RSVD_18")
	)
	(segment
		(start 138.3538 -102.6668)
		(end 139.5222 -103.8352)
		(width 0.10795)
		(layer "F.Cu")
		(net "TP_CPU1_RSVD_17")
	)
	(segment
		(start 139.5222 -103.8352)
		(end 151.506174 -103.8352)
		(width 0.10795)
		(layer "F.Cu")
		(net "TP_CPU1_RSVD_17")
	)
	(segment
		(start 138.3538 -102.354888)
		(end 138.3538 -102.6668)
		(width 0.10795)
		(layer "F.Cu")
		(net "TP_CPU1_RSVD_17")
	)
	(segment
		(start 138.816334 -101.892354)
		(end 138.3538 -102.354888)
		(width 0.10795)
		(layer "F.Cu")
		(net "TP_CPU1_RSVD_17")
	)
	(segment
		(start 138.816334 -101.471984)
		(end 138.816334 -101.892354)
		(width 0.10795)
		(layer "F.Cu")
		(net "TP_CPU1_RSVD_17")
	)
	(via
		(at 151.506174 -103.8352)
		(size 0.762)
		(drill 0.381)
		(layers "F.Cu" "B.Cu")
		(net "TP_CPU1_RSVD_17")
	)
	(segment
		(start 68.607686 -99.67214)
		(end 68.036186 -99.67214)
		(width 0.10795)
		(layer "F.Cu")
		(net "TP_CPU1_RSVD_16")
	)
	(via
		(at 68.036186 -99.67214)
		(size 0.508)
		(drill 0.254)
		(layers "F.Cu" "B.Cu")
		(net "TP_CPU1_RSVD_16")
	)
	(segment
		(start 129.372868 -101.967538)
		(end 129.944368 -101.967538)
		(width 0.10795)
		(layer "F.Cu")
		(net "TP_CPU1_RSVD_15")
	)
	(via
		(at 129.944368 -101.967538)
		(size 0.4826)
		(drill 0.254)
		(layers "F.Cu" "B.Cu")
		(net "TP_CPU1_RSVD_15")
	)
	(segment
		(start 152.572974 -103.251)
		(end 152.750774 -103.0732)
		(width 0.10795)
		(layer "F.Cu")
		(net "TP_CPU1_RSVD_14")
	)
	(segment
		(start 140.958316 -103.251)
		(end 152.572974 -103.251)
		(width 0.10795)
		(layer "F.Cu")
		(net "TP_CPU1_RSVD_14")
	)
	(segment
		(start 139.674854 -101.967538)
		(end 140.958316 -103.251)
		(width 0.10795)
		(layer "F.Cu")
		(net "TP_CPU1_RSVD_14")
	)
	(via
		(at 152.750774 -103.0732)
		(size 0.762)
		(drill 0.381)
		(layers "F.Cu" "B.Cu")
		(net "TP_CPU1_RSVD_14")
	)
	(segment
		(start 103.806244 -100.167186)
		(end 104.415844 -100.167186)
		(width 0.10795)
		(layer "F.Cu")
		(net "TP_CPU1_RSVD_13")
	)
	(via
		(at 104.415844 -100.167186)
		(size 0.508)
		(drill 0.254)
		(layers "F.Cu" "B.Cu")
		(net "TP_CPU1_RSVD_13")
	)
	(segment
		(start 69.466206 -100.167186)
		(end 68.894706 -100.167186)
		(width 0.10795)
		(layer "F.Cu")
		(net "TP_CPU1_RSVD_12")
	)
	(via
		(at 68.894706 -100.167186)
		(size 0.508)
		(drill 0.254)
		(layers "F.Cu" "B.Cu")
		(net "TP_CPU1_RSVD_12")
	)
	(segment
		(start 102.947724 -100.662486)
		(end 102.376224 -100.662486)
		(width 0.10795)
		(layer "F.Cu")
		(net "TP_CPU1_RSVD_11")
	)
	(via
		(at 102.376224 -100.662486)
		(size 0.508)
		(drill 0.254)
		(layers "F.Cu" "B.Cu")
		(net "TP_CPU1_RSVD_11")
	)
	(segment
		(start 138.816334 -102.462584)
		(end 139.373864 -102.462584)
		(width 0.10795)
		(layer "F.Cu")
		(net "TP_CPU1_RSVD_10")
	)
	(segment
		(start 139.373864 -102.462584)
		(end 139.44346 -102.53218)
		(width 0.10795)
		(layer "F.Cu")
		(net "TP_CPU1_RSVD_10")
	)
	(via
		(at 139.44346 -102.53218)
		(size 0.508)
		(drill 0.254)
		(layers "F.Cu" "B.Cu")
		(net "TP_CPU1_RSVD_10")
	)
	(segment
		(start 72.041766 -101.653086)
		(end 71.470266 -101.653086)
		(width 0.10795)
		(layer "F.Cu")
		(net "TP_CPU1_RSVD_1")
	)
	(via
		(at 71.470266 -101.653086)
		(size 0.508)
		(drill 0.254)
		(layers "F.Cu" "B.Cu")
		(net "TP_CPU1_RSVD_1")
	)
	(segment
		(start 70.324726 -101.653086)
		(end 69.753226 -101.653086)
		(width 0.10795)
		(layer "F.Cu")
		(net "TP_CPU1_RSVD_0")
	)
	(via
		(at 69.753226 -101.653086)
		(size 0.508)
		(drill 0.254)
		(layers "F.Cu" "B.Cu")
		(net "TP_CPU1_RSVD_0")
	)
	(segment
		(start 124.221748 -90.080338)
		(end 124.793248 -90.080338)
		(width 0.10795)
		(layer "F.Cu")
		(net "TP_CPU1_KTI2_DFX_DN")
	)
	(via
		(at 124.793248 -90.080338)
		(size 0.4826)
		(drill 0.254)
		(layers "F.Cu" "B.Cu")
		(net "TP_CPU1_KTI2_DFX_DN")
	)
	(segment
		(start 124.221748 -87.108538)
		(end 124.793248 -87.108538)
		(width 0.10795)
		(layer "F.Cu")
		(net "TP_CPU1_KTI2_AMONV")
	)
	(via
		(at 124.793248 -87.108538)
		(size 0.4826)
		(drill 0.254)
		(layers "F.Cu" "B.Cu")
		(net "TP_CPU1_KTI2_AMONV")
	)
	(segment
		(start 235.325158 -100.662486)
		(end 234.753658 -100.662486)
		(width 0.10795)
		(layer "F.Cu")
		(net "TP_CPU0_RSVD_9")
	)
	(via
		(at 234.753658 -100.662486)
		(size 0.508)
		(drill 0.254)
		(layers "F.Cu" "B.Cu")
		(net "TP_CPU0_RSVD_9")
	)
	(segment
		(start 293.801546 -102.386384)
		(end 293.801546 -101.967538)
		(width 0.10795)
		(layer "F.Cu")
		(net "TP_CPU0_RSVD_8")
	)
	(segment
		(start 294.3733 -102.958138)
		(end 293.801546 -102.386384)
		(width 0.10795)
		(layer "F.Cu")
		(net "TP_CPU0_RSVD_8")
	)
	(via
		(at 293.801546 -101.967538)
		(size 0.508)
		(drill 0.254)
		(layers "F.Cu" "B.Cu")
		(net "TP_CPU0_RSVD_8")
	)
	(segment
		(start 281.495754 -87.603584)
		(end 282.067254 -87.603584)
		(width 0.10795)
		(layer "F.Cu")
		(net "TP_CPU0_RSVD_73")
	)
	(via
		(at 282.067254 -87.603584)
		(size 0.508)
		(drill 0.254)
		(layers "F.Cu" "B.Cu")
		(net "TP_CPU0_RSVD_73")
	)
	(segment
		(start 255.07061 -86.29904)
		(end 254.49911 -86.29904)
		(width 0.10795)
		(layer "F.Cu")
		(net "TP_CPU0_RSVD_72")
	)
	(via
		(at 254.49911 -86.29904)
		(size 0.508)
		(drill 0.254)
		(layers "F.Cu" "B.Cu")
		(net "TP_CPU0_RSVD_72")
	)
	(segment
		(start 303.816766 -88.594184)
		(end 304.388266 -88.594184)
		(width 0.10795)
		(layer "F.Cu")
		(net "TP_CPU0_RSVD_70")
	)
	(via
		(at 304.388266 -88.594184)
		(size 0.508)
		(drill 0.254)
		(layers "F.Cu" "B.Cu")
		(net "TP_CPU0_RSVD_70")
	)
	(segment
		(start 267.136118 -101.261164)
		(end 267.335 -101.7016)
		(width 0.10795)
		(layer "F.Cu")
		(net "TP_CPU0_RSVD_7")
	)
	(segment
		(start 267.089636 -101.15804)
		(end 267.136118 -101.261164)
		(width 0.10795)
		(layer "F.Cu")
		(net "TP_CPU0_RSVD_7")
	)
	(via
		(at 267.335 -101.7016)
		(size 0.508)
		(drill 0.254)
		(layers "F.Cu" "B.Cu")
		(net "TP_CPU0_RSVD_7")
	)
	(segment
		(start 247.344184 -86.794086)
		(end 246.772684 -86.794086)
		(width 0.10795)
		(layer "F.Cu")
		(net "TP_CPU0_RSVD_69")
	)
	(via
		(at 246.772684 -86.794086)
		(size 0.508)
		(drill 0.254)
		(layers "F.Cu" "B.Cu")
		(net "TP_CPU0_RSVD_69")
	)
	(segment
		(start 303.529746 -89.089738)
		(end 302.958246 -89.089738)
		(width 0.10795)
		(layer "F.Cu")
		(net "TP_CPU0_RSVD_67")
	)
	(via
		(at 303.529746 -89.089738)
		(size 0.508)
		(drill 0.254)
		(layers "F.Cu" "B.Cu")
		(net "TP_CPU0_RSVD_67")
	)
	(segment
		(start 255.07061 -87.28964)
		(end 254.49911 -87.28964)
		(width 0.10795)
		(layer "F.Cu")
		(net "TP_CPU0_RSVD_66")
	)
	(via
		(at 254.49911 -87.28964)
		(size 0.508)
		(drill 0.254)
		(layers "F.Cu" "B.Cu")
		(net "TP_CPU0_RSVD_66")
	)
	(segment
		(start 255.07061 -88.28024)
		(end 254.49911 -88.28024)
		(width 0.10795)
		(layer "F.Cu")
		(net "TP_CPU0_RSVD_61")
	)
	(via
		(at 254.49911 -88.28024)
		(size 0.508)
		(drill 0.254)
		(layers "F.Cu" "B.Cu")
		(net "TP_CPU0_RSVD_61")
	)
	(segment
		(start 253.353824 -88.28024)
		(end 252.782324 -88.28024)
		(width 0.10795)
		(layer "F.Cu")
		(net "TP_CPU0_RSVD_60")
	)
	(via
		(at 252.782324 -88.28024)
		(size 0.508)
		(drill 0.254)
		(layers "F.Cu" "B.Cu")
		(net "TP_CPU0_RSVD_60")
	)
	(segment
		(start 303.682908 -103.6828)
		(end 304.0634 -103.6828)
		(width 0.10795)
		(layer "F.Cu")
		(net "TP_CPU0_RSVD_6")
	)
	(segment
		(start 302.958246 -102.958138)
		(end 303.682908 -103.6828)
		(width 0.10795)
		(layer "F.Cu")
		(net "TP_CPU0_RSVD_6")
	)
	(via
		(at 304.0634 -103.6828)
		(size 0.508)
		(drill 0.254)
		(layers "F.Cu" "B.Cu")
		(net "TP_CPU0_RSVD_6")
	)
	(segment
		(start 288.36366 -90.575384)
		(end 288.93516 -90.575384)
		(width 0.10795)
		(layer "F.Cu")
		(net "TP_CPU0_RSVD_59")
	)
	(via
		(at 288.93516 -90.575384)
		(size 0.508)
		(drill 0.254)
		(layers "F.Cu" "B.Cu")
		(net "TP_CPU0_RSVD_59")
	)
	(segment
		(start 274.627848 -90.575384)
		(end 275.199348 -90.575384)
		(width 0.10795)
		(layer "F.Cu")
		(net "TP_CPU0_RSVD_57")
	)
	(via
		(at 275.199348 -90.575384)
		(size 0.508)
		(drill 0.254)
		(layers "F.Cu" "B.Cu")
		(net "TP_CPU0_RSVD_57")
	)
	(segment
		(start 260.50875 -88.775286)
		(end 261.08025 -88.775286)
		(width 0.10795)
		(layer "F.Cu")
		(net "TP_CPU0_RSVD_56")
	)
	(via
		(at 260.50875 -88.775286)
		(size 0.508)
		(drill 0.254)
		(layers "F.Cu" "B.Cu")
		(net "TP_CPU0_RSVD_56")
	)
	(segment
		(start 257.64617 -88.775286)
		(end 257.07467 -88.775286)
		(width 0.10795)
		(layer "F.Cu")
		(net "TP_CPU0_RSVD_55")
	)
	(via
		(at 257.07467 -88.775286)
		(size 0.508)
		(drill 0.254)
		(layers "F.Cu" "B.Cu")
		(net "TP_CPU0_RSVD_55")
	)
	(segment
		(start 252.495304 -88.775286)
		(end 251.923804 -88.775286)
		(width 0.10795)
		(layer "F.Cu")
		(net "TP_CPU0_RSVD_54")
	)
	(via
		(at 251.923804 -88.775286)
		(size 0.508)
		(drill 0.254)
		(layers "F.Cu" "B.Cu")
		(net "TP_CPU0_RSVD_54")
	)
	(segment
		(start 243.910104 -88.775286)
		(end 243.338604 -88.775286)
		(width 0.10795)
		(layer "F.Cu")
		(net "TP_CPU0_RSVD_53")
	)
	(via
		(at 243.338604 -88.775286)
		(size 0.508)
		(drill 0.254)
		(layers "F.Cu" "B.Cu")
		(net "TP_CPU0_RSVD_53")
	)
	(segment
		(start 273.769328 -91.070938)
		(end 274.340828 -91.070938)
		(width 0.10795)
		(layer "F.Cu")
		(net "TP_CPU0_RSVD_51")
	)
	(via
		(at 274.340828 -91.070938)
		(size 0.508)
		(drill 0.254)
		(layers "F.Cu" "B.Cu")
		(net "TP_CPU0_RSVD_51")
	)
	(segment
		(start 261.93877 -89.27084)
		(end 261.36727 -89.27084)
		(width 0.10795)
		(layer "F.Cu")
		(net "TP_CPU0_RSVD_50")
	)
	(via
		(at 261.36727 -89.27084)
		(size 0.508)
		(drill 0.254)
		(layers "F.Cu" "B.Cu")
		(net "TP_CPU0_RSVD_50")
	)
	(segment
		(start 236.183678 -101.15804)
		(end 235.612178 -101.15804)
		(width 0.10795)
		(layer "F.Cu")
		(net "TP_CPU0_RSVD_5")
	)
	(via
		(at 235.612178 -101.15804)
		(size 0.508)
		(drill 0.254)
		(layers "F.Cu" "B.Cu")
		(net "TP_CPU0_RSVD_5")
	)
	(via
		(at 230.7971 -102.4763)
		(size 0.6604)
		(drill 0.3302)
		(layers "F.Cu" "B.Cu")
		(net "TP_CPU0_RSVD_5")
	)
	(segment
		(start 235.612178 -101.15804)
		(end 235.612178 -101.851968)
		(width 0.10795)
		(layer "B.Cu")
		(net "TP_CPU0_RSVD_5")
	)
	(segment
		(start 235.612178 -101.851968)
		(end 234.467146 -102.997)
		(width 0.10795)
		(layer "B.Cu")
		(net "TP_CPU0_RSVD_5")
	)
	(segment
		(start 234.467146 -102.997)
		(end 231.3178 -102.997)
		(width 0.10795)
		(layer "B.Cu")
		(net "TP_CPU0_RSVD_5")
	)
	(segment
		(start 231.3178 -102.997)
		(end 230.7971 -102.4763)
		(width 0.10795)
		(layer "B.Cu")
		(net "TP_CPU0_RSVD_5")
	)
	(segment
		(start 259.65023 -89.27084)
		(end 260.22173 -89.27084)
		(width 0.10795)
		(layer "F.Cu")
		(net "TP_CPU0_RSVD_49")
	)
	(via
		(at 259.65023 -89.27084)
		(size 0.508)
		(drill 0.254)
		(layers "F.Cu" "B.Cu")
		(net "TP_CPU0_RSVD_49")
	)
	(segment
		(start 258.50469 -89.27084)
		(end 257.93319 -89.27084)
		(width 0.10795)
		(layer "F.Cu")
		(net "TP_CPU0_RSVD_48")
	)
	(via
		(at 257.93319 -89.27084)
		(size 0.508)
		(drill 0.254)
		(layers "F.Cu" "B.Cu")
		(net "TP_CPU0_RSVD_48")
	)
	(segment
		(start 267.089636 -90.26144)
		(end 266.518136 -90.26144)
		(width 0.10795)
		(layer "F.Cu")
		(net "TP_CPU0_RSVD_47")
	)
	(via
		(at 266.518136 -90.26144)
		(size 0.508)
		(drill 0.254)
		(layers "F.Cu" "B.Cu")
		(net "TP_CPU0_RSVD_47")
	)
	(segment
		(start 261.93877 -90.26144)
		(end 261.36727 -90.26144)
		(width 0.10795)
		(layer "F.Cu")
		(net "TP_CPU0_RSVD_46")
	)
	(via
		(at 261.36727 -90.26144)
		(size 0.508)
		(drill 0.254)
		(layers "F.Cu" "B.Cu")
		(net "TP_CPU0_RSVD_46")
	)
	(segment
		(start 262.79729 -90.756486)
		(end 262.22579 -90.756486)
		(width 0.10795)
		(layer "F.Cu")
		(net "TP_CPU0_RSVD_45")
	)
	(via
		(at 262.22579 -90.756486)
		(size 0.508)
		(drill 0.254)
		(layers "F.Cu" "B.Cu")
		(net "TP_CPU0_RSVD_45")
	)
	(segment
		(start 277.203154 -94.042738)
		(end 277.774654 -94.042738)
		(width 0.10795)
		(layer "F.Cu")
		(net "TP_CPU0_RSVD_44")
	)
	(via
		(at 277.774654 -94.042738)
		(size 0.508)
		(drill 0.254)
		(layers "F.Cu" "B.Cu")
		(net "TP_CPU0_RSVD_44")
	)
	(segment
		(start 251.636784 -92.24264)
		(end 251.065284 -92.24264)
		(width 0.10795)
		(layer "F.Cu")
		(net "TP_CPU0_RSVD_43")
	)
	(via
		(at 251.065284 -92.24264)
		(size 0.508)
		(drill 0.254)
		(layers "F.Cu" "B.Cu")
		(net "TP_CPU0_RSVD_43")
	)
	(segment
		(start 250.778264 -92.737686)
		(end 250.206764 -92.737686)
		(width 0.10795)
		(layer "F.Cu")
		(net "TP_CPU0_RSVD_42")
	)
	(via
		(at 250.206764 -92.737686)
		(size 0.508)
		(drill 0.254)
		(layers "F.Cu" "B.Cu")
		(net "TP_CPU0_RSVD_42")
	)
	(segment
		(start 277.203154 -95.033084)
		(end 277.774654 -95.033084)
		(width 0.10795)
		(layer "F.Cu")
		(net "TP_CPU0_RSVD_41")
	)
	(via
		(at 277.774654 -95.033084)
		(size 0.508)
		(drill 0.254)
		(layers "F.Cu" "B.Cu")
		(net "TP_CPU0_RSVD_41")
	)
	(segment
		(start 249.919744 -93.23324)
		(end 249.348244 -93.23324)
		(width 0.10795)
		(layer "F.Cu")
		(net "TP_CPU0_RSVD_40")
	)
	(via
		(at 249.348244 -93.23324)
		(size 0.508)
		(drill 0.254)
		(layers "F.Cu" "B.Cu")
		(net "TP_CPU0_RSVD_40")
	)
	(segment
		(start 234.466638 -101.15804)
		(end 233.895138 -101.15804)
		(width 0.10795)
		(layer "F.Cu")
		(net "TP_CPU0_RSVD_4")
	)
	(via
		(at 233.895138 -101.15804)
		(size 0.508)
		(drill 0.254)
		(layers "F.Cu" "B.Cu")
		(net "TP_CPU0_RSVD_4")
	)
	(via
		(at 229.5017 -101.15804)
		(size 0.6604)
		(drill 0.3302)
		(layers "F.Cu" "B.Cu")
		(net "TP_CPU0_RSVD_4")
	)
	(segment
		(start 233.895138 -101.15804)
		(end 229.5017 -101.15804)
		(width 0.10795)
		(layer "B.Cu")
		(net "TP_CPU0_RSVD_4")
	)
	(segment
		(start 295.80332 -95.528384)
		(end 295.23182 -95.528384)
		(width 0.10795)
		(layer "F.Cu")
		(net "TP_CPU0_RSVD_39")
	)
	(via
		(at 295.80332 -95.528384)
		(size 0.508)
		(drill 0.254)
		(layers "F.Cu" "B.Cu")
		(net "TP_CPU0_RSVD_39")
	)
	(segment
		(start 276.344634 -95.528384)
		(end 276.916134 -95.528384)
		(width 0.10795)
		(layer "F.Cu")
		(net "TP_CPU0_RSVD_38")
	)
	(via
		(at 276.916134 -95.528384)
		(size 0.508)
		(drill 0.254)
		(layers "F.Cu" "B.Cu")
		(net "TP_CPU0_RSVD_38")
	)
	(segment
		(start 250.778264 -93.72854)
		(end 250.206764 -93.72854)
		(width 0.10795)
		(layer "F.Cu")
		(net "TP_CPU0_RSVD_37")
	)
	(via
		(at 250.206764 -93.72854)
		(size 0.508)
		(drill 0.254)
		(layers "F.Cu" "B.Cu")
		(net "TP_CPU0_RSVD_37")
	)
	(segment
		(start 249.061224 -93.72854)
		(end 248.489724 -93.72854)
		(width 0.10795)
		(layer "F.Cu")
		(net "TP_CPU0_RSVD_36")
	)
	(via
		(at 248.489724 -93.72854)
		(size 0.508)
		(drill 0.254)
		(layers "F.Cu" "B.Cu")
		(net "TP_CPU0_RSVD_36")
	)
	(segment
		(start 275.486114 -96.023938)
		(end 276.057614 -96.023938)
		(width 0.10795)
		(layer "F.Cu")
		(net "TP_CPU0_RSVD_35")
	)
	(via
		(at 276.057614 -96.023938)
		(size 0.508)
		(drill 0.254)
		(layers "F.Cu" "B.Cu")
		(net "TP_CPU0_RSVD_35")
	)
	(segment
		(start 249.919744 -94.223586)
		(end 249.348244 -94.223586)
		(width 0.10795)
		(layer "F.Cu")
		(net "TP_CPU0_RSVD_34")
	)
	(via
		(at 249.348244 -94.223586)
		(size 0.508)
		(drill 0.254)
		(layers "F.Cu" "B.Cu")
		(net "TP_CPU0_RSVD_34")
	)
	(segment
		(start 249.061224 -94.718886)
		(end 248.489724 -94.718886)
		(width 0.10795)
		(layer "F.Cu")
		(net "TP_CPU0_RSVD_33")
	)
	(via
		(at 248.489724 -94.718886)
		(size 0.508)
		(drill 0.254)
		(layers "F.Cu" "B.Cu")
		(net "TP_CPU0_RSVD_33")
	)
	(segment
		(start 253.353824 -95.21444)
		(end 252.782324 -95.21444)
		(width 0.10795)
		(layer "F.Cu")
		(net "TP_CPU0_RSVD_32")
	)
	(via
		(at 252.782324 -95.21444)
		(size 0.508)
		(drill 0.254)
		(layers "F.Cu" "B.Cu")
		(net "TP_CPU0_RSVD_32")
	)
	(segment
		(start 249.919744 -95.21444)
		(end 249.348244 -95.21444)
		(width 0.10795)
		(layer "F.Cu")
		(net "TP_CPU0_RSVD_31")
	)
	(via
		(at 249.348244 -95.21444)
		(size 0.508)
		(drill 0.254)
		(layers "F.Cu" "B.Cu")
		(net "TP_CPU0_RSVD_31")
	)
	(segment
		(start 293.51478 -97.509584)
		(end 294.08628 -97.509584)
		(width 0.10795)
		(layer "F.Cu")
		(net "TP_CPU0_RSVD_30")
	)
	(via
		(at 294.08628 -97.509584)
		(size 0.508)
		(drill 0.254)
		(layers "F.Cu" "B.Cu")
		(net "TP_CPU0_RSVD_30")
	)
	(segment
		(start 266.231116 -101.653086)
		(end 266.231116 -102.3366)
		(width 0.10795)
		(layer "F.Cu")
		(net "TP_CPU0_RSVD_3")
	)
	(via
		(at 266.231116 -102.3366)
		(size 0.508)
		(drill 0.254)
		(layers "F.Cu" "B.Cu")
		(net "TP_CPU0_RSVD_3")
	)
	(segment
		(start 250.778264 -95.709486)
		(end 250.206764 -95.709486)
		(width 0.10795)
		(layer "F.Cu")
		(net "TP_CPU0_RSVD_29")
	)
	(via
		(at 250.206764 -95.709486)
		(size 0.508)
		(drill 0.254)
		(layers "F.Cu" "B.Cu")
		(net "TP_CPU0_RSVD_29")
	)
	(segment
		(start 268.806676 -96.20504)
		(end 269.416276 -96.20504)
		(width 0.10795)
		(layer "F.Cu")
		(net "TP_CPU0_RSVD_28")
	)
	(via
		(at 269.416276 -96.20504)
		(size 0.508)
		(drill 0.254)
		(layers "F.Cu" "B.Cu")
		(net "TP_CPU0_RSVD_28")
	)
	(segment
		(start 245.627144 -96.700086)
		(end 245.055644 -96.700086)
		(width 0.10795)
		(layer "F.Cu")
		(net "TP_CPU0_RSVD_27")
	)
	(via
		(at 245.055644 -96.700086)
		(size 0.508)
		(drill 0.254)
		(layers "F.Cu" "B.Cu")
		(net "TP_CPU0_RSVD_27")
	)
	(segment
		(start 268.806676 -97.19564)
		(end 269.416276 -97.19564)
		(width 0.10795)
		(layer "F.Cu")
		(net "TP_CPU0_RSVD_26")
	)
	(via
		(at 269.416276 -97.19564)
		(size 0.508)
		(drill 0.254)
		(layers "F.Cu" "B.Cu")
		(net "TP_CPU0_RSVD_26")
	)
	(segment
		(start 254.212344 -97.690686)
		(end 253.640844 -97.690686)
		(width 0.10795)
		(layer "F.Cu")
		(net "TP_CPU0_RSVD_25")
	)
	(via
		(at 253.640844 -97.690686)
		(size 0.508)
		(drill 0.254)
		(layers "F.Cu" "B.Cu")
		(net "TP_CPU0_RSVD_25")
	)
	(segment
		(start 245.627144 -97.690686)
		(end 245.055644 -97.690686)
		(width 0.10795)
		(layer "F.Cu")
		(net "TP_CPU0_RSVD_24")
	)
	(via
		(at 245.055644 -97.690686)
		(size 0.508)
		(drill 0.254)
		(layers "F.Cu" "B.Cu")
		(net "TP_CPU0_RSVD_24")
	)
	(segment
		(start 268.806676 -98.18624)
		(end 269.416276 -98.18624)
		(width 0.10795)
		(layer "F.Cu")
		(net "TP_CPU0_RSVD_23")
	)
	(via
		(at 269.416276 -98.18624)
		(size 0.508)
		(drill 0.254)
		(layers "F.Cu" "B.Cu")
		(net "TP_CPU0_RSVD_23")
	)
	(segment
		(start 267.089636 -98.18624)
		(end 266.518136 -98.18624)
		(width 0.10795)
		(layer "F.Cu")
		(net "TP_CPU0_RSVD_22")
	)
	(via
		(at 266.518136 -98.18624)
		(size 0.508)
		(drill 0.254)
		(layers "F.Cu" "B.Cu")
		(net "TP_CPU0_RSVD_22")
	)
	(segment
		(start 240.476278 -101.653086)
		(end 239.904778 -101.653086)
		(width 0.10795)
		(layer "F.Cu")
		(net "TP_CPU0_RSVD_2")
	)
	(via
		(at 239.904778 -101.653086)
		(size 0.508)
		(drill 0.254)
		(layers "F.Cu" "B.Cu")
		(net "TP_CPU0_RSVD_2")
	)
	(segment
		(start 268.806676 -99.17684)
		(end 269.416276 -99.17684)
		(width 0.10795)
		(layer "F.Cu")
		(net "TP_CPU0_RSVD_19")
	)
	(via
		(at 269.416276 -99.17684)
		(size 0.508)
		(drill 0.254)
		(layers "F.Cu" "B.Cu")
		(net "TP_CPU0_RSVD_19")
	)
	(via
		(at 270.8402 -100.7618)
		(size 0.6604)
		(drill 0.3302)
		(layers "F.Cu" "B.Cu")
		(net "TP_CPU0_RSVD_19")
	)
	(segment
		(start 269.416276 -99.337876)
		(end 270.8402 -100.7618)
		(width 0.10795)
		(layer "B.Cu")
		(net "TP_CPU0_RSVD_19")
	)
	(segment
		(start 269.416276 -99.17684)
		(end 269.416276 -99.337876)
		(width 0.10795)
		(layer "B.Cu")
		(net "TP_CPU0_RSVD_19")
	)
	(segment
		(start 233.608118 -99.67214)
		(end 233.036618 -99.67214)
		(width 0.10795)
		(layer "F.Cu")
		(net "TP_CPU0_RSVD_16")
	)
	(via
		(at 233.036618 -99.67214)
		(size 0.508)
		(drill 0.254)
		(layers "F.Cu" "B.Cu")
		(net "TP_CPU0_RSVD_16")
	)
	(segment
		(start 294.3733 -101.967538)
		(end 294.945054 -101.967538)
		(width 0.10795)
		(layer "F.Cu")
		(net "TP_CPU0_RSVD_15")
	)
	(via
		(at 294.945054 -101.967538)
		(size 0.508)
		(drill 0.254)
		(layers "F.Cu" "B.Cu")
		(net "TP_CPU0_RSVD_15")
	)
	(segment
		(start 268.806676 -100.167186)
		(end 269.416276 -100.167186)
		(width 0.10795)
		(layer "F.Cu")
		(net "TP_CPU0_RSVD_13")
	)
	(via
		(at 269.416276 -100.167186)
		(size 0.508)
		(drill 0.254)
		(layers "F.Cu" "B.Cu")
		(net "TP_CPU0_RSVD_13")
	)
	(segment
		(start 234.466638 -100.167186)
		(end 233.895138 -100.167186)
		(width 0.10795)
		(layer "F.Cu")
		(net "TP_CPU0_RSVD_12")
	)
	(via
		(at 233.895138 -100.167186)
		(size 0.508)
		(drill 0.254)
		(layers "F.Cu" "B.Cu")
		(net "TP_CPU0_RSVD_12")
	)
	(via
		(at 231.0003 -100.457)
		(size 0.6604)
		(drill 0.3302)
		(layers "F.Cu" "B.Cu")
		(net "TP_CPU0_RSVD_12")
	)
	(segment
		(start 231.0003 -100.457)
		(end 233.605324 -100.457)
		(width 0.10795)
		(layer "B.Cu")
		(net "TP_CPU0_RSVD_12")
	)
	(segment
		(start 233.605324 -100.457)
		(end 233.895138 -100.167186)
		(width 0.10795)
		(layer "B.Cu")
		(net "TP_CPU0_RSVD_12")
	)
	(segment
		(start 267.948156 -100.662486)
		(end 267.376656 -100.662486)
		(width 0.10795)
		(layer "F.Cu")
		(net "TP_CPU0_RSVD_11")
	)
	(via
		(at 267.376656 -100.662486)
		(size 0.508)
		(drill 0.254)
		(layers "F.Cu" "B.Cu")
		(net "TP_CPU0_RSVD_11")
	)
	(segment
		(start 304.291238 -102.974394)
		(end 303.816766 -102.499922)
		(width 0.10795)
		(layer "F.Cu")
		(net "TP_CPU0_RSVD_10")
	)
	(segment
		(start 303.816766 -102.499922)
		(end 303.816766 -102.462584)
		(width 0.10795)
		(layer "F.Cu")
		(net "TP_CPU0_RSVD_10")
	)
	(segment
		(start 304.299366 -102.974394)
		(end 304.291238 -102.974394)
		(width 0.10795)
		(layer "F.Cu")
		(net "TP_CPU0_RSVD_10")
	)
	(via
		(at 304.299366 -102.974394)
		(size 0.508)
		(drill 0.254)
		(layers "F.Cu" "B.Cu")
		(net "TP_CPU0_RSVD_10")
	)
	(via
		(at 305.054 -102.1588)
		(size 0.6604)
		(drill 0.3302)
		(layers "F.Cu" "B.Cu")
		(net "TP_CPU0_RSVD_10")
	)
	(segment
		(start 304.299366 -102.974394)
		(end 304.299366 -102.913434)
		(width 0.10795)
		(layer "B.Cu")
		(net "TP_CPU0_RSVD_10")
	)
	(segment
		(start 304.299366 -102.913434)
		(end 305.054 -102.1588)
		(width 0.10795)
		(layer "B.Cu")
		(net "TP_CPU0_RSVD_10")
	)
	(segment
		(start 237.042198 -101.653086)
		(end 236.470698 -101.653086)
		(width 0.10795)
		(layer "F.Cu")
		(net "TP_CPU0_RSVD_1")
	)
	(via
		(at 236.470698 -101.653086)
		(size 0.508)
		(drill 0.254)
		(layers "F.Cu" "B.Cu")
		(net "TP_CPU0_RSVD_1")
	)
	(segment
		(start 235.325158 -101.653086)
		(end 234.753658 -101.653086)
		(width 0.10795)
		(layer "F.Cu")
		(net "TP_CPU0_RSVD_0")
	)
	(via
		(at 234.753658 -101.653086)
		(size 0.508)
		(drill 0.254)
		(layers "F.Cu" "B.Cu")
		(net "TP_CPU0_RSVD_0")
	)
	(via
		(at 232.8418 -102.4382)
		(size 0.6604)
		(drill 0.3302)
		(layers "F.Cu" "B.Cu")
		(net "TP_CPU0_RSVD_0")
	)
	(segment
		(start 232.8418 -102.4382)
		(end 233.626914 -101.653086)
		(width 0.10795)
		(layer "B.Cu")
		(net "TP_CPU0_RSVD_0")
	)
	(segment
		(start 233.626914 -101.653086)
		(end 234.753658 -101.653086)
		(width 0.10795)
		(layer "B.Cu")
		(net "TP_CPU0_RSVD_0")
	)
	(segment
		(start 289.22218 -90.080338)
		(end 289.79368 -90.080338)
		(width 0.10795)
		(layer "F.Cu")
		(net "TP_CPU0_KTI2_DFX_DN")
	)
	(via
		(at 289.79368 -90.080338)
		(size 0.508)
		(drill 0.254)
		(layers "F.Cu" "B.Cu")
		(net "TP_CPU0_KTI2_DFX_DN")
	)
	(segment
		(start 289.22218 -87.108538)
		(end 289.79368 -87.108538)
		(width 0.10795)
		(layer "F.Cu")
		(net "TP_CPU0_KTI2_AMONV")
	)
	(via
		(at 289.79368 -87.108538)
		(size 0.508)
		(drill 0.254)
		(layers "F.Cu" "B.Cu")
		(net "TP_CPU0_KTI2_AMONV")
	)
	(segment
		(start 362.371132 -69.660008)
		(end 362.371132 -72.998584)
		(width 0.10795)
		(layer "F.Cu")
		(net "PWRGD_PVCCIO_CPU1")
	)
	(segment
		(start 166.37 -71.5264)
		(end 166.37 -72.2884)
		(width 0.10795)
		(layer "F.Cu")
		(net "PWRGD_PVCCIO_CPU1")
	)
	(segment
		(start 366.344962 -76.695046)
		(end 366.745012 -76.294996)
		(width 0.10795)
		(layer "F.Cu")
		(net "PWRGD_PVCCIO_CPU1")
	)
	(segment
		(start 362.371132 -72.998584)
		(end 366.067594 -76.695046)
		(width 0.10795)
		(layer "F.Cu")
		(net "PWRGD_PVCCIO_CPU1")
	)
	(segment
		(start 366.067594 -76.695046)
		(end 366.344962 -76.695046)
		(width 0.10795)
		(layer "F.Cu")
		(net "PWRGD_PVCCIO_CPU1")
	)
	(via
		(at 318.008 -36.9062)
		(size 0.508)
		(drill 0.254)
		(layers "F.Cu" "B.Cu")
		(net "PWRGD_PVCCIO_CPU1")
	)
	(via
		(at 371.182392 -62.0649)
		(size 0.508)
		(drill 0.254)
		(layers "F.Cu" "B.Cu")
		(net "PWRGD_PVCCIO_CPU1")
	)
	(via
		(at 166.37 -72.2884)
		(size 0.508)
		(drill 0.254)
		(layers "F.Cu" "B.Cu")
		(net "PWRGD_PVCCIO_CPU1")
	)
	(via
		(at 362.371132 -69.660008)
		(size 0.508)
		(drill 0.254)
		(layers "F.Cu" "B.Cu")
		(net "PWRGD_PVCCIO_CPU1")
	)
	(via
		(at 194.03822 -21.6154)
		(size 0.508)
		(drill 0.254)
		(layers "F.Cu" "B.Cu")
		(net "PWRGD_PVCCIO_CPU1")
	)
	(segment
		(start 362.371132 -69.098668)
		(end 363.762036 -67.707764)
		(width 0.089408)
		(layer "In4.Cu")
		(net "PWRGD_PVCCIO_CPU1")
	)
	(segment
		(start 362.371132 -69.660008)
		(end 362.371132 -69.098668)
		(width 0.089408)
		(layer "In4.Cu")
		(net "PWRGD_PVCCIO_CPU1")
	)
	(segment
		(start 370.485162 -63.178182)
		(end 371.182392 -62.480952)
		(width 0.089408)
		(layer "In4.Cu")
		(net "PWRGD_PVCCIO_CPU1")
	)
	(segment
		(start 363.762036 -67.707764)
		(end 364.332774 -67.707764)
		(width 0.089408)
		(layer "In4.Cu")
		(net "PWRGD_PVCCIO_CPU1")
	)
	(segment
		(start 364.332774 -67.707764)
		(end 367.0808 -64.959738)
		(width 0.089408)
		(layer "In4.Cu")
		(net "PWRGD_PVCCIO_CPU1")
	)
	(segment
		(start 367.0808 -63.86068)
		(end 367.763298 -63.178182)
		(width 0.089408)
		(layer "In4.Cu")
		(net "PWRGD_PVCCIO_CPU1")
	)
	(segment
		(start 367.0808 -64.959738)
		(end 367.0808 -63.86068)
		(width 0.089408)
		(layer "In4.Cu")
		(net "PWRGD_PVCCIO_CPU1")
	)
	(segment
		(start 371.182392 -62.480952)
		(end 371.182392 -62.0649)
		(width 0.089408)
		(layer "In4.Cu")
		(net "PWRGD_PVCCIO_CPU1")
	)
	(segment
		(start 367.763298 -63.178182)
		(end 370.485162 -63.178182)
		(width 0.089408)
		(layer "In4.Cu")
		(net "PWRGD_PVCCIO_CPU1")
	)
	(segment
		(start 193.490596 -19.735038)
		(end 193.490596 -21.067776)
		(width 0.089408)
		(layer "In9.Cu")
		(net "PWRGD_PVCCIO_CPU1")
	)
	(segment
		(start 245.29288 -22.074378)
		(end 245.015766 -21.797264)
		(width 0.089408)
		(layer "In9.Cu")
		(net "PWRGD_PVCCIO_CPU1")
	)
	(segment
		(start 243.68506 -21.91766)
		(end 241.6175 -19.8501)
		(width 0.089408)
		(layer "In9.Cu")
		(net "PWRGD_PVCCIO_CPU1")
	)
	(segment
		(start 260.175756 -23.960582)
		(end 246.290338 -23.960582)
		(width 0.089408)
		(layer "In9.Cu")
		(net "PWRGD_PVCCIO_CPU1")
	)
	(segment
		(start 263.625838 -26.422604)
		(end 262.637778 -26.422604)
		(width 0.089408)
		(layer "In9.Cu")
		(net "PWRGD_PVCCIO_CPU1")
	)
	(segment
		(start 263.626092 -26.42235)
		(end 263.625838 -26.422604)
		(width 0.089408)
		(layer "In9.Cu")
		(net "PWRGD_PVCCIO_CPU1")
	)
	(segment
		(start 245.015766 -21.797264)
		(end 244.432836 -21.797264)
		(width 0.089408)
		(layer "In9.Cu")
		(net "PWRGD_PVCCIO_CPU1")
	)
	(segment
		(start 318.008 -36.9062)
		(end 314.035186 -32.933386)
		(width 0.089408)
		(layer "In9.Cu")
		(net "PWRGD_PVCCIO_CPU1")
	)
	(segment
		(start 314.035186 -32.933386)
		(end 314.035186 -32.448754)
		(width 0.089408)
		(layer "In9.Cu")
		(net "PWRGD_PVCCIO_CPU1")
	)
	(segment
		(start 314.035186 -32.448754)
		(end 306.687474 -25.101042)
		(width 0.089408)
		(layer "In9.Cu")
		(net "PWRGD_PVCCIO_CPU1")
	)
	(segment
		(start 262.637778 -26.422604)
		(end 260.175756 -23.960582)
		(width 0.089408)
		(layer "In9.Cu")
		(net "PWRGD_PVCCIO_CPU1")
	)
	(segment
		(start 244.432836 -21.797264)
		(end 244.31244 -21.91766)
		(width 0.089408)
		(layer "In9.Cu")
		(net "PWRGD_PVCCIO_CPU1")
	)
	(segment
		(start 275.226272 -28.901136)
		(end 266.347194 -28.901136)
		(width 0.089408)
		(layer "In9.Cu")
		(net "PWRGD_PVCCIO_CPU1")
	)
	(segment
		(start 245.950486 -23.66772)
		(end 245.29288 -23.010114)
		(width 0.089408)
		(layer "In9.Cu")
		(net "PWRGD_PVCCIO_CPU1")
	)
	(segment
		(start 245.29288 -23.010114)
		(end 245.29288 -22.074378)
		(width 0.089408)
		(layer "In9.Cu")
		(net "PWRGD_PVCCIO_CPU1")
	)
	(segment
		(start 193.490596 -21.067776)
		(end 194.03822 -21.6154)
		(width 0.089408)
		(layer "In9.Cu")
		(net "PWRGD_PVCCIO_CPU1")
	)
	(segment
		(start 306.687474 -25.101042)
		(end 279.026366 -25.101042)
		(width 0.089408)
		(layer "In9.Cu")
		(net "PWRGD_PVCCIO_CPU1")
	)
	(segment
		(start 241.6175 -19.8501)
		(end 195.5546 -19.8501)
		(width 0.089408)
		(layer "In9.Cu")
		(net "PWRGD_PVCCIO_CPU1")
	)
	(segment
		(start 246.290338 -23.960582)
		(end 245.997476 -23.66772)
		(width 0.089408)
		(layer "In9.Cu")
		(net "PWRGD_PVCCIO_CPU1")
	)
	(segment
		(start 195.5546 -19.8501)
		(end 195.192396 -19.487896)
		(width 0.089408)
		(layer "In9.Cu")
		(net "PWRGD_PVCCIO_CPU1")
	)
	(segment
		(start 193.737738 -19.487896)
		(end 193.490596 -19.735038)
		(width 0.089408)
		(layer "In9.Cu")
		(net "PWRGD_PVCCIO_CPU1")
	)
	(segment
		(start 279.026366 -25.101042)
		(end 275.226272 -28.901136)
		(width 0.089408)
		(layer "In9.Cu")
		(net "PWRGD_PVCCIO_CPU1")
	)
	(segment
		(start 195.192396 -19.487896)
		(end 193.737738 -19.487896)
		(width 0.089408)
		(layer "In9.Cu")
		(net "PWRGD_PVCCIO_CPU1")
	)
	(segment
		(start 244.31244 -21.91766)
		(end 243.68506 -21.91766)
		(width 0.089408)
		(layer "In9.Cu")
		(net "PWRGD_PVCCIO_CPU1")
	)
	(segment
		(start 245.997476 -23.66772)
		(end 245.950486 -23.66772)
		(width 0.089408)
		(layer "In9.Cu")
		(net "PWRGD_PVCCIO_CPU1")
	)
	(segment
		(start 266.347194 -28.901136)
		(end 263.868408 -26.42235)
		(width 0.089408)
		(layer "In9.Cu")
		(net "PWRGD_PVCCIO_CPU1")
	)
	(segment
		(start 263.868408 -26.42235)
		(end 263.626092 -26.42235)
		(width 0.089408)
		(layer "In9.Cu")
		(net "PWRGD_PVCCIO_CPU1")
	)
	(segment
		(start 166.37 -71.120508)
		(end 164.909246 -69.659754)
		(width 0.089408)
		(layer "In11.Cu")
		(net "PWRGD_PVCCIO_CPU1")
	)
	(segment
		(start 165.654228 -64.451992)
		(end 165.654228 -63.872618)
		(width 0.089408)
		(layer "In11.Cu")
		(net "PWRGD_PVCCIO_CPU1")
	)
	(segment
		(start 328.604118 -50.545492)
		(end 322.990718 -44.932092)
		(width 0.089408)
		(layer "In11.Cu")
		(net "PWRGD_PVCCIO_CPU1")
	)
	(segment
		(start 194.03822 -22.11578)
		(end 194.03822 -21.6154)
		(width 0.089408)
		(layer "In11.Cu")
		(net "PWRGD_PVCCIO_CPU1")
	)
	(segment
		(start 164.909246 -65.196974)
		(end 165.654228 -64.451992)
		(width 0.089408)
		(layer "In11.Cu")
		(net "PWRGD_PVCCIO_CPU1")
	)
	(segment
		(start 164.909246 -69.659754)
		(end 164.909246 -65.196974)
		(width 0.089408)
		(layer "In11.Cu")
		(net "PWRGD_PVCCIO_CPU1")
	)
	(segment
		(start 365.520478 -56.532272)
		(end 365.51997 -56.531764)
		(width 0.089408)
		(layer "In11.Cu")
		(net "PWRGD_PVCCIO_CPU1")
	)
	(segment
		(start 364.886748 -56.532018)
		(end 364.886494 -56.532272)
		(width 0.089408)
		(layer "In11.Cu")
		(net "PWRGD_PVCCIO_CPU1")
	)
	(segment
		(start 365.51997 -56.531764)
		(end 365.04499 -56.531764)
		(width 0.089408)
		(layer "In11.Cu")
		(net "PWRGD_PVCCIO_CPU1")
	)
	(segment
		(start 364.886494 -56.532272)
		(end 364.242858 -56.532272)
		(width 0.089408)
		(layer "In11.Cu")
		(net "PWRGD_PVCCIO_CPU1")
	)
	(segment
		(start 364.242858 -56.532272)
		(end 360.312462 -52.601876)
		(width 0.089408)
		(layer "In11.Cu")
		(net "PWRGD_PVCCIO_CPU1")
	)
	(segment
		(start 165.849554 -62.521846)
		(end 167.724074 -60.647326)
		(width 0.089408)
		(layer "In11.Cu")
		(net "PWRGD_PVCCIO_CPU1")
	)
	(segment
		(start 358.852216 -52.601876)
		(end 356.795832 -50.545492)
		(width 0.089408)
		(layer "In11.Cu")
		(net "PWRGD_PVCCIO_CPU1")
	)
	(segment
		(start 320.039492 -44.932092)
		(end 318.008 -42.9006)
		(width 0.089408)
		(layer "In11.Cu")
		(net "PWRGD_PVCCIO_CPU1")
	)
	(segment
		(start 188.2394 -24.8412)
		(end 191.3128 -24.8412)
		(width 0.089408)
		(layer "In11.Cu")
		(net "PWRGD_PVCCIO_CPU1")
	)
	(segment
		(start 322.990718 -44.932092)
		(end 320.039492 -44.932092)
		(width 0.089408)
		(layer "In11.Cu")
		(net "PWRGD_PVCCIO_CPU1")
	)
	(segment
		(start 366.088168 -56.532272)
		(end 365.520478 -56.532272)
		(width 0.089408)
		(layer "In11.Cu")
		(net "PWRGD_PVCCIO_CPU1")
	)
	(segment
		(start 167.724074 -60.647326)
		(end 167.724074 -50.327306)
		(width 0.089408)
		(layer "In11.Cu")
		(net "PWRGD_PVCCIO_CPU1")
	)
	(segment
		(start 365.04499 -56.531764)
		(end 365.044736 -56.532018)
		(width 0.089408)
		(layer "In11.Cu")
		(net "PWRGD_PVCCIO_CPU1")
	)
	(segment
		(start 187.6298 -30.42158)
		(end 187.6298 -25.4508)
		(width 0.089408)
		(layer "In11.Cu")
		(net "PWRGD_PVCCIO_CPU1")
	)
	(segment
		(start 365.044736 -56.532018)
		(end 364.886748 -56.532018)
		(width 0.089408)
		(layer "In11.Cu")
		(net "PWRGD_PVCCIO_CPU1")
	)
	(segment
		(start 191.3128 -24.8412)
		(end 194.03822 -22.11578)
		(width 0.089408)
		(layer "In11.Cu")
		(net "PWRGD_PVCCIO_CPU1")
	)
	(segment
		(start 360.312462 -52.601876)
		(end 358.852216 -52.601876)
		(width 0.089408)
		(layer "In11.Cu")
		(net "PWRGD_PVCCIO_CPU1")
	)
	(segment
		(start 166.37 -72.2884)
		(end 166.37 -71.120508)
		(width 0.089408)
		(layer "In11.Cu")
		(net "PWRGD_PVCCIO_CPU1")
	)
	(segment
		(start 356.795832 -50.545492)
		(end 328.604118 -50.545492)
		(width 0.089408)
		(layer "In11.Cu")
		(net "PWRGD_PVCCIO_CPU1")
	)
	(segment
		(start 165.654228 -63.872618)
		(end 165.849554 -63.677292)
		(width 0.089408)
		(layer "In11.Cu")
		(net "PWRGD_PVCCIO_CPU1")
	)
	(segment
		(start 371.182392 -62.0649)
		(end 371.182392 -61.625226)
		(width 0.089408)
		(layer "In11.Cu")
		(net "PWRGD_PVCCIO_CPU1")
	)
	(segment
		(start 371.182392 -61.625226)
		(end 366.088168 -56.532272)
		(width 0.089408)
		(layer "In11.Cu")
		(net "PWRGD_PVCCIO_CPU1")
	)
	(segment
		(start 167.724074 -50.327306)
		(end 187.6298 -30.42158)
		(width 0.089408)
		(layer "In11.Cu")
		(net "PWRGD_PVCCIO_CPU1")
	)
	(segment
		(start 165.849554 -63.677292)
		(end 165.849554 -62.521846)
		(width 0.089408)
		(layer "In11.Cu")
		(net "PWRGD_PVCCIO_CPU1")
	)
	(segment
		(start 318.008 -42.9006)
		(end 318.008 -36.9062)
		(width 0.089408)
		(layer "In11.Cu")
		(net "PWRGD_PVCCIO_CPU1")
	)
	(segment
		(start 187.6298 -25.4508)
		(end 188.2394 -24.8412)
		(width 0.089408)
		(layer "In11.Cu")
		(net "PWRGD_PVCCIO_CPU1")
	)
	(segment
		(start 369.9129 -92.0496)
		(end 369.7859 -92.1766)
		(width 0.10795)
		(layer "F.Cu")
		(net "PWRGD_PVCCIO_CPU0")
	)
	(segment
		(start 369.824 -91.6178)
		(end 369.9129 -91.7067)
		(width 0.10795)
		(layer "F.Cu")
		(net "PWRGD_PVCCIO_CPU0")
	)
	(segment
		(start 369.7859 -92.1766)
		(end 369.2652 -92.1766)
		(width 0.10795)
		(layer "F.Cu")
		(net "PWRGD_PVCCIO_CPU0")
	)
	(segment
		(start 373.544846 -76.694792)
		(end 373.14505 -76.294996)
		(width 0.10795)
		(layer "F.Cu")
		(net "PWRGD_PVCCIO_CPU0")
	)
	(segment
		(start 369.9129 -91.7067)
		(end 369.9129 -92.0496)
		(width 0.10795)
		(layer "F.Cu")
		(net "PWRGD_PVCCIO_CPU0")
	)
	(via
		(at 369.824 -91.6178)
		(size 0.508)
		(drill 0.254)
		(layers "F.Cu" "B.Cu")
		(net "PWRGD_PVCCIO_CPU0")
	)
	(via
		(at 362.9914 -91.7702)
		(size 0.6604)
		(drill 0.3302)
		(layers "F.Cu" "B.Cu")
		(net "PWRGD_PVCCIO_CPU0")
	)
	(via
		(at 344.2462 -81.70545)
		(size 0.508)
		(drill 0.254)
		(layers "F.Cu" "B.Cu")
		(net "PWRGD_PVCCIO_CPU0")
	)
	(via
		(at 359.0036 -91.7702)
		(size 0.508)
		(drill 0.254)
		(layers "F.Cu" "B.Cu")
		(net "PWRGD_PVCCIO_CPU0")
	)
	(via
		(at 373.544846 -76.694792)
		(size 0.4572)
		(drill 0.2032)
		(layers "F.Cu" "B.Cu")
		(net "PWRGD_PVCCIO_CPU0")
	)
	(segment
		(start 344.2462 -82.019394)
		(end 344.2462 -81.70545)
		(width 0.10795)
		(layer "B.Cu")
		(net "PWRGD_PVCCIO_CPU0")
	)
	(segment
		(start 343.789 -82.476594)
		(end 344.2462 -82.019394)
		(width 0.10795)
		(layer "B.Cu")
		(net "PWRGD_PVCCIO_CPU0")
	)
	(segment
		(start 363.1438 -91.6178)
		(end 369.824 -91.6178)
		(width 0.10795)
		(layer "B.Cu")
		(net "PWRGD_PVCCIO_CPU0")
	)
	(segment
		(start 359.0036 -91.7702)
		(end 362.9914 -91.7702)
		(width 0.10795)
		(layer "B.Cu")
		(net "PWRGD_PVCCIO_CPU0")
	)
	(segment
		(start 362.9914 -91.7702)
		(end 363.1438 -91.6178)
		(width 0.10795)
		(layer "B.Cu")
		(net "PWRGD_PVCCIO_CPU0")
	)
	(segment
		(start 343.789 -82.677)
		(end 343.789 -82.476594)
		(width 0.10795)
		(layer "B.Cu")
		(net "PWRGD_PVCCIO_CPU0")
	)
	(segment
		(start 359.796588 -83.977734)
		(end 360.130852 -84.311998)
		(width 0.089408)
		(layer "In4.Cu")
		(net "PWRGD_PVCCIO_CPU0")
	)
	(segment
		(start 359.961942 -90.811858)
		(end 359.0036 -91.7702)
		(width 0.089408)
		(layer "In4.Cu")
		(net "PWRGD_PVCCIO_CPU0")
	)
	(segment
		(start 357.819452 -82.893916)
		(end 358.200452 -82.893916)
		(width 0.089408)
		(layer "In4.Cu")
		(net "PWRGD_PVCCIO_CPU0")
	)
	(segment
		(start 351.160842 -81.954878)
		(end 351.885504 -82.67954)
		(width 0.089408)
		(layer "In4.Cu")
		(net "PWRGD_PVCCIO_CPU0")
	)
	(segment
		(start 351.885504 -82.67954)
		(end 354.530914 -82.67954)
		(width 0.089408)
		(layer "In4.Cu")
		(net "PWRGD_PVCCIO_CPU0")
	)
	(segment
		(start 358.200452 -82.893916)
		(end 359.28427 -83.977734)
		(width 0.089408)
		(layer "In4.Cu")
		(net "PWRGD_PVCCIO_CPU0")
	)
	(segment
		(start 349.503492 -81.954878)
		(end 351.160842 -81.954878)
		(width 0.089408)
		(layer "In4.Cu")
		(net "PWRGD_PVCCIO_CPU0")
	)
	(segment
		(start 359.28427 -83.977734)
		(end 359.796588 -83.977734)
		(width 0.089408)
		(layer "In4.Cu")
		(net "PWRGD_PVCCIO_CPU0")
	)
	(segment
		(start 355.08311 -82.127344)
		(end 357.05288 -82.127344)
		(width 0.089408)
		(layer "In4.Cu")
		(net "PWRGD_PVCCIO_CPU0")
	)
	(segment
		(start 349.021908 -82.436462)
		(end 349.503492 -81.954878)
		(width 0.089408)
		(layer "In4.Cu")
		(net "PWRGD_PVCCIO_CPU0")
	)
	(segment
		(start 354.530914 -82.67954)
		(end 355.08311 -82.127344)
		(width 0.089408)
		(layer "In4.Cu")
		(net "PWRGD_PVCCIO_CPU0")
	)
	(segment
		(start 359.961942 -86.951058)
		(end 359.961942 -90.811858)
		(width 0.089408)
		(layer "In4.Cu")
		(net "PWRGD_PVCCIO_CPU0")
	)
	(segment
		(start 360.130852 -84.311998)
		(end 360.130852 -86.782148)
		(width 0.089408)
		(layer "In4.Cu")
		(net "PWRGD_PVCCIO_CPU0")
	)
	(segment
		(start 357.05288 -82.127344)
		(end 357.819452 -82.893916)
		(width 0.089408)
		(layer "In4.Cu")
		(net "PWRGD_PVCCIO_CPU0")
	)
	(segment
		(start 344.2462 -81.70545)
		(end 344.2462 -81.972912)
		(width 0.089408)
		(layer "In4.Cu")
		(net "PWRGD_PVCCIO_CPU0")
	)
	(segment
		(start 344.2462 -81.972912)
		(end 344.70975 -82.436462)
		(width 0.089408)
		(layer "In4.Cu")
		(net "PWRGD_PVCCIO_CPU0")
	)
	(segment
		(start 360.130852 -86.782148)
		(end 359.961942 -86.951058)
		(width 0.089408)
		(layer "In4.Cu")
		(net "PWRGD_PVCCIO_CPU0")
	)
	(segment
		(start 344.70975 -82.436462)
		(end 349.021908 -82.436462)
		(width 0.089408)
		(layer "In4.Cu")
		(net "PWRGD_PVCCIO_CPU0")
	)
	(segment
		(start 369.179856 -91.6178)
		(end 369.824 -91.6178)
		(width 0.089408)
		(layer "In9.Cu")
		(net "PWRGD_PVCCIO_CPU0")
	)
	(segment
		(start 374.243092 -77.921358)
		(end 374.499378 -77.921358)
		(width 0.089408)
		(layer "In9.Cu")
		(net "PWRGD_PVCCIO_CPU0")
	)
	(segment
		(start 368.8207 -90.208354)
		(end 368.669062 -90.359992)
		(width 0.089408)
		(layer "In9.Cu")
		(net "PWRGD_PVCCIO_CPU0")
	)
	(segment
		(start 374.718072 -78.140052)
		(end 374.718072 -81.390236)
		(width 0.089408)
		(layer "In9.Cu")
		(net "PWRGD_PVCCIO_CPU0")
	)
	(segment
		(start 374.38076 -83.93684)
		(end 373.502682 -84.814918)
		(width 0.089408)
		(layer "In9.Cu")
		(net "PWRGD_PVCCIO_CPU0")
	)
	(segment
		(start 373.544846 -76.957682)
		(end 373.9388 -77.351636)
		(width 0.089408)
		(layer "In9.Cu")
		(net "PWRGD_PVCCIO_CPU0")
	)
	(segment
		(start 373.502682 -84.814918)
		(end 373.502682 -85.560662)
		(width 0.089408)
		(layer "In9.Cu")
		(net "PWRGD_PVCCIO_CPU0")
	)
	(segment
		(start 374.499378 -77.921358)
		(end 374.718072 -78.140052)
		(width 0.089408)
		(layer "In9.Cu")
		(net "PWRGD_PVCCIO_CPU0")
	)
	(segment
		(start 373.502682 -85.560662)
		(end 370.963952 -88.099392)
		(width 0.089408)
		(layer "In9.Cu")
		(net "PWRGD_PVCCIO_CPU0")
	)
	(segment
		(start 370.2685 -88.099392)
		(end 368.8207 -89.547192)
		(width 0.089408)
		(layer "In9.Cu")
		(net "PWRGD_PVCCIO_CPU0")
	)
	(segment
		(start 373.9388 -77.617066)
		(end 374.243092 -77.921358)
		(width 0.089408)
		(layer "In9.Cu")
		(net "PWRGD_PVCCIO_CPU0")
	)
	(segment
		(start 370.963952 -88.099392)
		(end 370.2685 -88.099392)
		(width 0.089408)
		(layer "In9.Cu")
		(net "PWRGD_PVCCIO_CPU0")
	)
	(segment
		(start 373.9388 -77.351636)
		(end 373.9388 -77.617066)
		(width 0.089408)
		(layer "In9.Cu")
		(net "PWRGD_PVCCIO_CPU0")
	)
	(segment
		(start 368.669062 -90.359992)
		(end 368.669062 -91.107006)
		(width 0.089408)
		(layer "In9.Cu")
		(net "PWRGD_PVCCIO_CPU0")
	)
	(segment
		(start 373.544846 -76.694792)
		(end 373.544846 -76.957682)
		(width 0.089408)
		(layer "In9.Cu")
		(net "PWRGD_PVCCIO_CPU0")
	)
	(segment
		(start 374.38076 -81.727548)
		(end 374.38076 -83.93684)
		(width 0.089408)
		(layer "In9.Cu")
		(net "PWRGD_PVCCIO_CPU0")
	)
	(segment
		(start 368.8207 -89.547192)
		(end 368.8207 -90.208354)
		(width 0.089408)
		(layer "In9.Cu")
		(net "PWRGD_PVCCIO_CPU0")
	)
	(segment
		(start 368.669062 -91.107006)
		(end 369.179856 -91.6178)
		(width 0.089408)
		(layer "In9.Cu")
		(net "PWRGD_PVCCIO_CPU0")
	)
	(segment
		(start 374.718072 -81.390236)
		(end 374.38076 -81.727548)
		(width 0.089408)
		(layer "In9.Cu")
		(net "PWRGD_PVCCIO_CPU0")
	)
	(segment
		(start 98.655378 -90.26144)
		(end 98.083878 -90.26144)
		(width 0.10795)
		(layer "F.Cu")
		(net "PD_CPU1_TEST14")
	)
	(via
		(at 80.89773 -88.5444)
		(size 0.6604)
		(drill 0.3302)
		(layers "F.Cu" "B.Cu")
		(net "PD_CPU1_TEST14")
	)
	(via
		(at 98.083878 -90.26144)
		(size 0.508)
		(drill 0.254)
		(layers "F.Cu" "B.Cu")
		(net "PD_CPU1_TEST14")
	)
	(segment
		(start 94.961456 -89.819988)
		(end 95.348044 -90.206576)
		(width 0.10795)
		(layer "B.Cu")
		(net "PD_CPU1_TEST14")
	)
	(segment
		(start 92.52458 -90.381836)
		(end 92.52458 -90.430604)
		(width 0.10795)
		(layer "B.Cu")
		(net "PD_CPU1_TEST14")
	)
	(segment
		(start 80.153002 -87.632286)
		(end 80.153002 -87.799672)
		(width 0.10795)
		(layer "B.Cu")
		(net "PD_CPU1_TEST14")
	)
	(segment
		(start 82.834226 -89.819226)
		(end 83.240372 -90.225372)
		(width 0.10795)
		(layer "B.Cu")
		(net "PD_CPU1_TEST14")
	)
	(segment
		(start 85.061298 -90.217498)
		(end 85.423502 -90.217498)
		(width 0.10795)
		(layer "B.Cu")
		(net "PD_CPU1_TEST14")
	)
	(segment
		(start 90.520012 -90.22715)
		(end 90.9066 -89.840562)
		(width 0.10795)
		(layer "B.Cu")
		(net "PD_CPU1_TEST14")
	)
	(segment
		(start 89.753948 -89.796874)
		(end 90.184224 -90.22715)
		(width 0.10795)
		(layer "B.Cu")
		(net "PD_CPU1_TEST14")
	)
	(segment
		(start 96.991424 -90.225118)
		(end 98.047556 -90.225118)
		(width 0.10795)
		(layer "B.Cu")
		(net "PD_CPU1_TEST14")
	)
	(segment
		(start 83.688428 -90.225372)
		(end 84.098892 -89.814908)
		(width 0.10795)
		(layer "B.Cu")
		(net "PD_CPU1_TEST14")
	)
	(segment
		(start 93.518736 -90.207084)
		(end 93.99905 -90.207084)
		(width 0.10795)
		(layer "B.Cu")
		(net "PD_CPU1_TEST14")
	)
	(segment
		(start 93.101922 -90.669618)
		(end 93.340936 -90.430604)
		(width 0.10795)
		(layer "B.Cu")
		(net "PD_CPU1_TEST14")
	)
	(segment
		(start 87.504016 -89.836244)
		(end 88.01989 -89.836244)
		(width 0.10795)
		(layer "B.Cu")
		(net "PD_CPU1_TEST14")
	)
	(segment
		(start 89.28735 -89.796874)
		(end 89.753948 -89.796874)
		(width 0.10795)
		(layer "B.Cu")
		(net "PD_CPU1_TEST14")
	)
	(segment
		(start 98.047556 -90.225118)
		(end 98.083878 -90.26144)
		(width 0.10795)
		(layer "B.Cu")
		(net "PD_CPU1_TEST14")
	)
	(segment
		(start 87.127842 -90.212418)
		(end 87.504016 -89.836244)
		(width 0.10795)
		(layer "B.Cu")
		(net "PD_CPU1_TEST14")
	)
	(segment
		(start 80.89773 -88.5444)
		(end 81.62163 -89.2683)
		(width 0.10795)
		(layer "B.Cu")
		(net "PD_CPU1_TEST14")
	)
	(segment
		(start 85.839046 -89.801954)
		(end 86.297262 -89.801954)
		(width 0.10795)
		(layer "B.Cu")
		(net "PD_CPU1_TEST14")
	)
	(segment
		(start 94.386146 -89.819988)
		(end 94.961456 -89.819988)
		(width 0.10795)
		(layer "B.Cu")
		(net "PD_CPU1_TEST14")
	)
	(segment
		(start 96.588834 -89.822528)
		(end 96.991424 -90.225118)
		(width 0.10795)
		(layer "B.Cu")
		(net "PD_CPU1_TEST14")
	)
	(segment
		(start 88.01989 -89.836244)
		(end 88.36533 -90.181684)
		(width 0.10795)
		(layer "B.Cu")
		(net "PD_CPU1_TEST14")
	)
	(segment
		(start 86.707726 -90.212418)
		(end 87.127842 -90.212418)
		(width 0.10795)
		(layer "B.Cu")
		(net "PD_CPU1_TEST14")
	)
	(segment
		(start 83.240372 -90.225372)
		(end 83.688428 -90.225372)
		(width 0.10795)
		(layer "B.Cu")
		(net "PD_CPU1_TEST14")
	)
	(segment
		(start 84.658708 -89.814908)
		(end 85.061298 -90.217498)
		(width 0.10795)
		(layer "B.Cu")
		(net "PD_CPU1_TEST14")
	)
	(segment
		(start 84.098892 -89.814908)
		(end 84.658708 -89.814908)
		(width 0.10795)
		(layer "B.Cu")
		(net "PD_CPU1_TEST14")
	)
	(segment
		(start 95.348044 -90.206576)
		(end 95.683832 -90.206576)
		(width 0.10795)
		(layer "B.Cu")
		(net "PD_CPU1_TEST14")
	)
	(segment
		(start 80.153002 -87.799672)
		(end 80.89773 -88.5444)
		(width 0.10795)
		(layer "B.Cu")
		(net "PD_CPU1_TEST14")
	)
	(segment
		(start 91.812618 -90.204036)
		(end 92.34678 -90.204036)
		(width 0.10795)
		(layer "B.Cu")
		(net "PD_CPU1_TEST14")
	)
	(segment
		(start 85.423502 -90.217498)
		(end 85.839046 -89.801954)
		(width 0.10795)
		(layer "B.Cu")
		(net "PD_CPU1_TEST14")
	)
	(segment
		(start 96.06788 -89.822528)
		(end 96.588834 -89.822528)
		(width 0.10795)
		(layer "B.Cu")
		(net "PD_CPU1_TEST14")
	)
	(segment
		(start 92.34678 -90.204036)
		(end 92.52458 -90.381836)
		(width 0.10795)
		(layer "B.Cu")
		(net "PD_CPU1_TEST14")
	)
	(segment
		(start 92.52458 -90.430604)
		(end 92.763594 -90.669618)
		(width 0.10795)
		(layer "B.Cu")
		(net "PD_CPU1_TEST14")
	)
	(segment
		(start 90.184224 -90.22715)
		(end 90.520012 -90.22715)
		(width 0.10795)
		(layer "B.Cu")
		(net "PD_CPU1_TEST14")
	)
	(segment
		(start 90.9066 -89.840562)
		(end 91.449144 -89.840562)
		(width 0.10795)
		(layer "B.Cu")
		(net "PD_CPU1_TEST14")
	)
	(segment
		(start 88.90254 -90.181684)
		(end 89.28735 -89.796874)
		(width 0.10795)
		(layer "B.Cu")
		(net "PD_CPU1_TEST14")
	)
	(segment
		(start 92.763594 -90.669618)
		(end 93.101922 -90.669618)
		(width 0.10795)
		(layer "B.Cu")
		(net "PD_CPU1_TEST14")
	)
	(segment
		(start 88.36533 -90.181684)
		(end 88.90254 -90.181684)
		(width 0.10795)
		(layer "B.Cu")
		(net "PD_CPU1_TEST14")
	)
	(segment
		(start 82.446114 -89.819226)
		(end 82.834226 -89.819226)
		(width 0.10795)
		(layer "B.Cu")
		(net "PD_CPU1_TEST14")
	)
	(segment
		(start 81.62163 -89.2683)
		(end 81.895188 -89.2683)
		(width 0.10795)
		(layer "B.Cu")
		(net "PD_CPU1_TEST14")
	)
	(segment
		(start 95.683832 -90.206576)
		(end 96.06788 -89.822528)
		(width 0.10795)
		(layer "B.Cu")
		(net "PD_CPU1_TEST14")
	)
	(segment
		(start 93.340936 -90.430604)
		(end 93.340936 -90.384884)
		(width 0.10795)
		(layer "B.Cu")
		(net "PD_CPU1_TEST14")
	)
	(segment
		(start 81.895188 -89.2683)
		(end 82.446114 -89.819226)
		(width 0.10795)
		(layer "B.Cu")
		(net "PD_CPU1_TEST14")
	)
	(segment
		(start 93.340936 -90.384884)
		(end 93.518736 -90.207084)
		(width 0.10795)
		(layer "B.Cu")
		(net "PD_CPU1_TEST14")
	)
	(segment
		(start 93.99905 -90.207084)
		(end 94.386146 -89.819988)
		(width 0.10795)
		(layer "B.Cu")
		(net "PD_CPU1_TEST14")
	)
	(segment
		(start 86.297262 -89.801954)
		(end 86.707726 -90.212418)
		(width 0.10795)
		(layer "B.Cu")
		(net "PD_CPU1_TEST14")
	)
	(segment
		(start 91.449144 -89.840562)
		(end 91.812618 -90.204036)
		(width 0.10795)
		(layer "B.Cu")
		(net "PD_CPU1_TEST14")
	)
	(segment
		(start 97.796858 -89.765886)
		(end 97.225358 -89.765886)
		(width 0.10795)
		(layer "F.Cu")
		(net "PD_CPU1_TEST13")
	)
	(via
		(at 97.225358 -89.765886)
		(size 0.508)
		(drill 0.254)
		(layers "F.Cu" "B.Cu")
		(net "PD_CPU1_TEST13")
	)
	(segment
		(start 95.65513 -89.22639)
		(end 95.372682 -89.22639)
		(width 0.10795)
		(layer "B.Cu")
		(net "PD_CPU1_TEST13")
	)
	(segment
		(start 87.089234 -89.212166)
		(end 86.748366 -89.212166)
		(width 0.10795)
		(layer "B.Cu")
		(net "PD_CPU1_TEST13")
	)
	(segment
		(start 85.876638 -88.83777)
		(end 85.522562 -89.191846)
		(width 0.10795)
		(layer "B.Cu")
		(net "PD_CPU1_TEST13")
	)
	(segment
		(start 84.094066 -88.752934)
		(end 83.642454 -89.204546)
		(width 0.10795)
		(layer "B.Cu")
		(net "PD_CPU1_TEST13")
	)
	(segment
		(start 90.543126 -89.212166)
		(end 90.151966 -89.212166)
		(width 0.10795)
		(layer "B.Cu")
		(net "PD_CPU1_TEST13")
	)
	(segment
		(start 81.28 -87.224108)
		(end 80.799178 -86.743286)
		(width 0.10795)
		(layer "B.Cu")
		(net "PD_CPU1_TEST13")
	)
	(segment
		(start 94.885764 -88.739472)
		(end 94.469458 -88.739472)
		(width 0.10795)
		(layer "B.Cu")
		(net "PD_CPU1_TEST13")
	)
	(segment
		(start 92.726256 -89.769188)
		(end 92.43441 -89.477342)
		(width 0.10795)
		(layer "B.Cu")
		(net "PD_CPU1_TEST13")
	)
	(segment
		(start 94.015814 -89.193116)
		(end 93.608906 -89.193116)
		(width 0.10795)
		(layer "B.Cu")
		(net "PD_CPU1_TEST13")
	)
	(segment
		(start 95.372682 -89.22639)
		(end 94.885764 -88.739472)
		(width 0.10795)
		(layer "B.Cu")
		(net "PD_CPU1_TEST13")
	)
	(segment
		(start 80.799178 -86.743286)
		(end 80.153002 -86.743286)
		(width 0.10795)
		(layer "B.Cu")
		(net "PD_CPU1_TEST13")
	)
	(segment
		(start 84.561934 -88.752934)
		(end 84.094066 -88.752934)
		(width 0.10795)
		(layer "B.Cu")
		(net "PD_CPU1_TEST13")
	)
	(segment
		(start 85.522562 -89.191846)
		(end 85.000846 -89.191846)
		(width 0.10795)
		(layer "B.Cu")
		(net "PD_CPU1_TEST13")
	)
	(segment
		(start 83.642454 -89.204546)
		(end 83.288378 -89.204546)
		(width 0.10795)
		(layer "B.Cu")
		(net "PD_CPU1_TEST13")
	)
	(segment
		(start 85.000846 -89.191846)
		(end 84.561934 -88.752934)
		(width 0.10795)
		(layer "B.Cu")
		(net "PD_CPU1_TEST13")
	)
	(segment
		(start 88.451182 -89.202006)
		(end 88.004142 -88.754966)
		(width 0.10795)
		(layer "B.Cu")
		(net "PD_CPU1_TEST13")
	)
	(segment
		(start 87.546434 -88.754966)
		(end 87.089234 -89.212166)
		(width 0.10795)
		(layer "B.Cu")
		(net "PD_CPU1_TEST13")
	)
	(segment
		(start 92.25661 -89.195402)
		(end 91.886786 -89.195402)
		(width 0.10795)
		(layer "B.Cu")
		(net "PD_CPU1_TEST13")
	)
	(segment
		(start 93.431106 -89.370916)
		(end 93.431106 -89.477342)
		(width 0.10795)
		(layer "B.Cu")
		(net "PD_CPU1_TEST13")
	)
	(segment
		(start 82.831432 -88.7476)
		(end 82.434176 -88.7476)
		(width 0.10795)
		(layer "B.Cu")
		(net "PD_CPU1_TEST13")
	)
	(segment
		(start 88.851994 -89.202006)
		(end 88.451182 -89.202006)
		(width 0.10795)
		(layer "B.Cu")
		(net "PD_CPU1_TEST13")
	)
	(segment
		(start 96.561402 -88.752934)
		(end 96.128586 -88.752934)
		(width 0.10795)
		(layer "B.Cu")
		(net "PD_CPU1_TEST13")
	)
	(segment
		(start 97.225358 -89.41689)
		(end 96.561402 -88.752934)
		(width 0.10795)
		(layer "B.Cu")
		(net "PD_CPU1_TEST13")
	)
	(segment
		(start 91.002612 -88.75268)
		(end 90.543126 -89.212166)
		(width 0.10795)
		(layer "B.Cu")
		(net "PD_CPU1_TEST13")
	)
	(segment
		(start 92.43441 -89.477342)
		(end 92.43441 -89.373202)
		(width 0.10795)
		(layer "B.Cu")
		(net "PD_CPU1_TEST13")
	)
	(segment
		(start 90.151966 -89.212166)
		(end 89.708228 -88.768428)
		(width 0.10795)
		(layer "B.Cu")
		(net "PD_CPU1_TEST13")
	)
	(segment
		(start 97.225358 -89.765886)
		(end 97.225358 -89.41689)
		(width 0.10795)
		(layer "B.Cu")
		(net "PD_CPU1_TEST13")
	)
	(segment
		(start 96.128586 -88.752934)
		(end 95.65513 -89.22639)
		(width 0.10795)
		(layer "B.Cu")
		(net "PD_CPU1_TEST13")
	)
	(segment
		(start 91.444064 -88.75268)
		(end 91.002612 -88.75268)
		(width 0.10795)
		(layer "B.Cu")
		(net "PD_CPU1_TEST13")
	)
	(segment
		(start 83.288378 -89.204546)
		(end 82.831432 -88.7476)
		(width 0.10795)
		(layer "B.Cu")
		(net "PD_CPU1_TEST13")
	)
	(segment
		(start 82.434176 -88.7476)
		(end 81.951576 -88.265)
		(width 0.10795)
		(layer "B.Cu")
		(net "PD_CPU1_TEST13")
	)
	(segment
		(start 81.951576 -88.265)
		(end 81.598008 -88.265)
		(width 0.10795)
		(layer "B.Cu")
		(net "PD_CPU1_TEST13")
	)
	(segment
		(start 86.37397 -88.83777)
		(end 85.876638 -88.83777)
		(width 0.10795)
		(layer "B.Cu")
		(net "PD_CPU1_TEST13")
	)
	(segment
		(start 89.285572 -88.768428)
		(end 88.851994 -89.202006)
		(width 0.10795)
		(layer "B.Cu")
		(net "PD_CPU1_TEST13")
	)
	(segment
		(start 89.708228 -88.768428)
		(end 89.285572 -88.768428)
		(width 0.10795)
		(layer "B.Cu")
		(net "PD_CPU1_TEST13")
	)
	(segment
		(start 92.43441 -89.373202)
		(end 92.25661 -89.195402)
		(width 0.10795)
		(layer "B.Cu")
		(net "PD_CPU1_TEST13")
	)
	(segment
		(start 86.748366 -89.212166)
		(end 86.37397 -88.83777)
		(width 0.10795)
		(layer "B.Cu")
		(net "PD_CPU1_TEST13")
	)
	(segment
		(start 94.469458 -88.739472)
		(end 94.015814 -89.193116)
		(width 0.10795)
		(layer "B.Cu")
		(net "PD_CPU1_TEST13")
	)
	(segment
		(start 93.608906 -89.193116)
		(end 93.431106 -89.370916)
		(width 0.10795)
		(layer "B.Cu")
		(net "PD_CPU1_TEST13")
	)
	(segment
		(start 81.598008 -88.265)
		(end 81.28 -87.946992)
		(width 0.10795)
		(layer "B.Cu")
		(net "PD_CPU1_TEST13")
	)
	(segment
		(start 81.28 -87.946992)
		(end 81.28 -87.224108)
		(width 0.10795)
		(layer "B.Cu")
		(net "PD_CPU1_TEST13")
	)
	(segment
		(start 93.431106 -89.477342)
		(end 93.13926 -89.769188)
		(width 0.10795)
		(layer "B.Cu")
		(net "PD_CPU1_TEST13")
	)
	(segment
		(start 88.004142 -88.754966)
		(end 87.546434 -88.754966)
		(width 0.10795)
		(layer "B.Cu")
		(net "PD_CPU1_TEST13")
	)
	(segment
		(start 91.886786 -89.195402)
		(end 91.444064 -88.75268)
		(width 0.10795)
		(layer "B.Cu")
		(net "PD_CPU1_TEST13")
	)
	(segment
		(start 93.13926 -89.769188)
		(end 92.726256 -89.769188)
		(width 0.10795)
		(layer "B.Cu")
		(net "PD_CPU1_TEST13")
	)
	(segment
		(start 117.505734 -77.089)
		(end 117.221 -77.089)
		(width 0.10795)
		(layer "F.Cu")
		(net "PD_CPU1_TEST12")
	)
	(segment
		(start 118.3894 -76.205334)
		(end 117.505734 -77.089)
		(width 0.10795)
		(layer "F.Cu")
		(net "PD_CPU1_TEST12")
	)
	(segment
		(start 127.368808 -70.763384)
		(end 126.797308 -70.763384)
		(width 0.10795)
		(layer "F.Cu")
		(net "PD_CPU1_TEST12")
	)
	(via
		(at 127.368808 -70.763384)
		(size 0.508)
		(drill 0.254)
		(layers "F.Cu" "B.Cu")
		(net "PD_CPU1_TEST12")
	)
	(via
		(at 118.3894 -76.205334)
		(size 0.508)
		(drill 0.254)
		(layers "F.Cu" "B.Cu")
		(net "PD_CPU1_TEST12")
	)
	(segment
		(start 124.958348 -71.657464)
		(end 125.260354 -71.355458)
		(width 0.0889)
		(layer "In2.Cu")
		(net "PD_CPU1_TEST12")
	)
	(segment
		(start 118.8974 -75.61326)
		(end 119.192802 -75.317858)
		(width 0.0889)
		(layer "In2.Cu")
		(net "PD_CPU1_TEST12")
	)
	(segment
		(start 122.052588 -72.15251)
		(end 122.382788 -72.15251)
		(width 0.0889)
		(layer "In2.Cu")
		(net "PD_CPU1_TEST12")
	)
	(segment
		(start 122.382788 -72.15251)
		(end 122.877834 -71.657464)
		(width 0.0889)
		(layer "In2.Cu")
		(net "PD_CPU1_TEST12")
	)
	(segment
		(start 119.192802 -75.317858)
		(end 119.329454 -75.317858)
		(width 0.0889)
		(layer "In2.Cu")
		(net "PD_CPU1_TEST12")
	)
	(segment
		(start 120.5992 -72.44588)
		(end 121.194068 -71.851012)
		(width 0.0889)
		(layer "In2.Cu")
		(net "PD_CPU1_TEST12")
	)
	(segment
		(start 126.345188 -71.657464)
		(end 126.675388 -71.657464)
		(width 0.0889)
		(layer "In2.Cu")
		(net "PD_CPU1_TEST12")
	)
	(segment
		(start 125.260354 -71.355458)
		(end 126.043182 -71.355458)
		(width 0.0889)
		(layer "In2.Cu")
		(net "PD_CPU1_TEST12")
	)
	(segment
		(start 118.8974 -75.697334)
		(end 118.8974 -75.61326)
		(width 0.0889)
		(layer "In2.Cu")
		(net "PD_CPU1_TEST12")
	)
	(segment
		(start 121.75109 -71.851012)
		(end 122.052588 -72.15251)
		(width 0.0889)
		(layer "In2.Cu")
		(net "PD_CPU1_TEST12")
	)
	(segment
		(start 123.241308 -71.657464)
		(end 123.543314 -71.355458)
		(width 0.0889)
		(layer "In2.Cu")
		(net "PD_CPU1_TEST12")
	)
	(segment
		(start 127.368808 -70.964044)
		(end 127.368808 -70.763384)
		(width 0.0889)
		(layer "In2.Cu")
		(net "PD_CPU1_TEST12")
	)
	(segment
		(start 121.194068 -71.851012)
		(end 121.75109 -71.851012)
		(width 0.0889)
		(layer "In2.Cu")
		(net "PD_CPU1_TEST12")
	)
	(segment
		(start 120.0658 -74.12736)
		(end 120.5992 -73.59396)
		(width 0.0889)
		(layer "In2.Cu")
		(net "PD_CPU1_TEST12")
	)
	(segment
		(start 122.877834 -71.657464)
		(end 123.241308 -71.657464)
		(width 0.0889)
		(layer "In2.Cu")
		(net "PD_CPU1_TEST12")
	)
	(segment
		(start 118.3894 -76.205334)
		(end 118.8974 -75.697334)
		(width 0.0889)
		(layer "In2.Cu")
		(net "PD_CPU1_TEST12")
	)
	(segment
		(start 119.329454 -75.317858)
		(end 120.0658 -74.581512)
		(width 0.0889)
		(layer "In2.Cu")
		(net "PD_CPU1_TEST12")
	)
	(segment
		(start 123.543314 -71.355458)
		(end 124.099828 -71.355458)
		(width 0.0889)
		(layer "In2.Cu")
		(net "PD_CPU1_TEST12")
	)
	(segment
		(start 120.0658 -74.581512)
		(end 120.0658 -74.12736)
		(width 0.0889)
		(layer "In2.Cu")
		(net "PD_CPU1_TEST12")
	)
	(segment
		(start 126.043182 -71.355458)
		(end 126.345188 -71.657464)
		(width 0.0889)
		(layer "In2.Cu")
		(net "PD_CPU1_TEST12")
	)
	(segment
		(start 126.675388 -71.657464)
		(end 127.368808 -70.964044)
		(width 0.0889)
		(layer "In2.Cu")
		(net "PD_CPU1_TEST12")
	)
	(segment
		(start 124.401834 -71.657464)
		(end 124.958348 -71.657464)
		(width 0.0889)
		(layer "In2.Cu")
		(net "PD_CPU1_TEST12")
	)
	(segment
		(start 120.5992 -73.59396)
		(end 120.5992 -72.44588)
		(width 0.0889)
		(layer "In2.Cu")
		(net "PD_CPU1_TEST12")
	)
	(segment
		(start 124.099828 -71.355458)
		(end 124.401834 -71.657464)
		(width 0.0889)
		(layer "In2.Cu")
		(net "PD_CPU1_TEST12")
	)
	(segment
		(start 119.070882 -87.108538)
		(end 119.642382 -87.108538)
		(width 0.10795)
		(layer "F.Cu")
		(net "PD_CPU1_MCP01_DMON")
	)
	(via
		(at 120.410478 -75.960478)
		(size 0.6604)
		(drill 0.3302)
		(layers "F.Cu" "B.Cu")
		(net "PD_CPU1_MCP01_DMON")
	)
	(via
		(at 119.642382 -87.108538)
		(size 0.508)
		(drill 0.254)
		(layers "F.Cu" "B.Cu")
		(net "PD_CPU1_MCP01_DMON")
	)
	(segment
		(start 121.688098 -81.906872)
		(end 121.767346 -81.98612)
		(width 0.10795)
		(layer "B.Cu")
		(net "PD_CPU1_MCP01_DMON")
	)
	(segment
		(start 121.688098 -82.403696)
		(end 121.688098 -82.897726)
		(width 0.10795)
		(layer "B.Cu")
		(net "PD_CPU1_MCP01_DMON")
	)
	(segment
		(start 121.688098 -82.897726)
		(end 121.767346 -82.976974)
		(width 0.10795)
		(layer "B.Cu")
		(net "PD_CPU1_MCP01_DMON")
	)
	(segment
		(start 119.642382 -86.87435)
		(end 119.642382 -87.108538)
		(width 0.10795)
		(layer "B.Cu")
		(net "PD_CPU1_MCP01_DMON")
	)
	(segment
		(start 121.566178 -76.7334)
		(end 121.767346 -76.934568)
		(width 0.10795)
		(layer "B.Cu")
		(net "PD_CPU1_MCP01_DMON")
	)
	(segment
		(start 121.688098 -80.916526)
		(end 121.767346 -80.995774)
		(width 0.10795)
		(layer "B.Cu")
		(net "PD_CPU1_MCP01_DMON")
	)
	(segment
		(start 121.19864 -83.601814)
		(end 120.675654 -84.1248)
		(width 0.10795)
		(layer "B.Cu")
		(net "PD_CPU1_MCP01_DMON")
	)
	(segment
		(start 117.221 -76.454)
		(end 117.313456 -76.454)
		(width 0.10795)
		(layer "B.Cu")
		(net "PD_CPU1_MCP01_DMON")
	)
	(segment
		(start 117.313456 -76.454)
		(end 118.22049 -75.546966)
		(width 0.10795)
		(layer "B.Cu")
		(net "PD_CPU1_MCP01_DMON")
	)
	(segment
		(start 120.045226 -84.442808)
		(end 120.045226 -85.690202)
		(width 0.10795)
		(layer "B.Cu")
		(net "PD_CPU1_MCP01_DMON")
	)
	(segment
		(start 121.767346 -80.995774)
		(end 121.767346 -81.334102)
		(width 0.10795)
		(layer "B.Cu")
		(net "PD_CPU1_MCP01_DMON")
	)
	(segment
		(start 118.86438 -75.546966)
		(end 119.201946 -75.2094)
		(width 0.10795)
		(layer "B.Cu")
		(net "PD_CPU1_MCP01_DMON")
	)
	(segment
		(start 120.093994 -86.422738)
		(end 119.642382 -86.87435)
		(width 0.10795)
		(layer "B.Cu")
		(net "PD_CPU1_MCP01_DMON")
	)
	(segment
		(start 121.767346 -81.334102)
		(end 121.688098 -81.41335)
		(width 0.10795)
		(layer "B.Cu")
		(net "PD_CPU1_MCP01_DMON")
	)
	(segment
		(start 119.6594 -75.2094)
		(end 120.410478 -75.960478)
		(width 0.10795)
		(layer "B.Cu")
		(net "PD_CPU1_MCP01_DMON")
	)
	(segment
		(start 119.201946 -75.2094)
		(end 119.6594 -75.2094)
		(width 0.10795)
		(layer "B.Cu")
		(net "PD_CPU1_MCP01_DMON")
	)
	(segment
		(start 118.22049 -75.546966)
		(end 118.86438 -75.546966)
		(width 0.10795)
		(layer "B.Cu")
		(net "PD_CPU1_MCP01_DMON")
	)
	(segment
		(start 120.410478 -75.960478)
		(end 121.1834 -76.7334)
		(width 0.10795)
		(layer "B.Cu")
		(net "PD_CPU1_MCP01_DMON")
	)
	(segment
		(start 121.688098 -80.42275)
		(end 121.688098 -80.916526)
		(width 0.10795)
		(layer "B.Cu")
		(net "PD_CPU1_MCP01_DMON")
	)
	(segment
		(start 120.18899 -86.03742)
		(end 120.18899 -86.193122)
		(width 0.10795)
		(layer "B.Cu")
		(net "PD_CPU1_MCP01_DMON")
	)
	(segment
		(start 121.767346 -82.324448)
		(end 121.688098 -82.403696)
		(width 0.10795)
		(layer "B.Cu")
		(net "PD_CPU1_MCP01_DMON")
	)
	(segment
		(start 121.767346 -83.382866)
		(end 121.548398 -83.601814)
		(width 0.10795)
		(layer "B.Cu")
		(net "PD_CPU1_MCP01_DMON")
	)
	(segment
		(start 121.767346 -81.98612)
		(end 121.767346 -82.324448)
		(width 0.10795)
		(layer "B.Cu")
		(net "PD_CPU1_MCP01_DMON")
	)
	(segment
		(start 121.767346 -76.934568)
		(end 121.767346 -80.343502)
		(width 0.10795)
		(layer "B.Cu")
		(net "PD_CPU1_MCP01_DMON")
	)
	(segment
		(start 121.1834 -76.7334)
		(end 121.566178 -76.7334)
		(width 0.10795)
		(layer "B.Cu")
		(net "PD_CPU1_MCP01_DMON")
	)
	(segment
		(start 121.767346 -80.343502)
		(end 121.688098 -80.42275)
		(width 0.10795)
		(layer "B.Cu")
		(net "PD_CPU1_MCP01_DMON")
	)
	(segment
		(start 121.688098 -81.41335)
		(end 121.688098 -81.906872)
		(width 0.10795)
		(layer "B.Cu")
		(net "PD_CPU1_MCP01_DMON")
	)
	(segment
		(start 121.767346 -82.976974)
		(end 121.767346 -83.382866)
		(width 0.10795)
		(layer "B.Cu")
		(net "PD_CPU1_MCP01_DMON")
	)
	(segment
		(start 120.18899 -86.193122)
		(end 120.093994 -86.422738)
		(width 0.10795)
		(layer "B.Cu")
		(net "PD_CPU1_MCP01_DMON")
	)
	(segment
		(start 120.045226 -85.690202)
		(end 120.18899 -86.03742)
		(width 0.10795)
		(layer "B.Cu")
		(net "PD_CPU1_MCP01_DMON")
	)
	(segment
		(start 120.363234 -84.1248)
		(end 120.045226 -84.442808)
		(width 0.10795)
		(layer "B.Cu")
		(net "PD_CPU1_MCP01_DMON")
	)
	(segment
		(start 120.675654 -84.1248)
		(end 120.363234 -84.1248)
		(width 0.10795)
		(layer "B.Cu")
		(net "PD_CPU1_MCP01_DMON")
	)
	(segment
		(start 121.548398 -83.601814)
		(end 121.19864 -83.601814)
		(width 0.10795)
		(layer "B.Cu")
		(net "PD_CPU1_MCP01_DMON")
	)
	(segment
		(start 263.65581 -90.26144)
		(end 263.08431 -90.26144)
		(width 0.10795)
		(layer "F.Cu")
		(net "PD_CPU0_TEST14")
	)
	(via
		(at 245.744492 -88.547194)
		(size 0.6604)
		(drill 0.3302)
		(layers "F.Cu" "B.Cu")
		(net "PD_CPU0_TEST14")
	)
	(via
		(at 263.08431 -90.26144)
		(size 0.508)
		(drill 0.254)
		(layers "F.Cu" "B.Cu")
		(net "PD_CPU0_TEST14")
	)
	(segment
		(start 250.844812 -88.789256)
		(end 251.232924 -88.789256)
		(width 0.10795)
		(layer "B.Cu")
		(net "PD_CPU0_TEST14")
	)
	(segment
		(start 261.19201 -91.7956)
		(end 261.5692 -91.7956)
		(width 0.10795)
		(layer "B.Cu")
		(net "PD_CPU0_TEST14")
	)
	(segment
		(start 259.05206 -92.291662)
		(end 259.463032 -92.702634)
		(width 0.10795)
		(layer "B.Cu")
		(net "PD_CPU0_TEST14")
	)
	(segment
		(start 255.505204 -91.164664)
		(end 256.09042 -91.74988)
		(width 0.10795)
		(layer "B.Cu")
		(net "PD_CPU0_TEST14")
	)
	(segment
		(start 261.9756 -92.202)
		(end 261.975854 -92.202)
		(width 0.10795)
		(layer "B.Cu")
		(net "PD_CPU0_TEST14")
	)
	(segment
		(start 256.34442 -91.74988)
		(end 256.83464 -92.2401)
		(width 0.10795)
		(layer "B.Cu")
		(net "PD_CPU0_TEST14")
	)
	(segment
		(start 245.744492 -88.547194)
		(end 246.062246 -88.547194)
		(width 0.10795)
		(layer "B.Cu")
		(net "PD_CPU0_TEST14")
	)
	(segment
		(start 257.8735 -91.716098)
		(end 258.05384 -91.716098)
		(width 0.10795)
		(layer "B.Cu")
		(net "PD_CPU0_TEST14")
	)
	(segment
		(start 245.706138 -88.547194)
		(end 245.744492 -88.547194)
		(width 0.10795)
		(layer "B.Cu")
		(net "PD_CPU0_TEST14")
	)
	(segment
		(start 262.9662 -90.7288)
		(end 262.9662 -90.37955)
		(width 0.10795)
		(layer "B.Cu")
		(net "PD_CPU0_TEST14")
	)
	(segment
		(start 260.696964 -92.290646)
		(end 261.19201 -91.7956)
		(width 0.10795)
		(layer "B.Cu")
		(net "PD_CPU0_TEST14")
	)
	(segment
		(start 260.254496 -92.290646)
		(end 260.696964 -92.290646)
		(width 0.10795)
		(layer "B.Cu")
		(net "PD_CPU0_TEST14")
	)
	(segment
		(start 257.349498 -92.2401)
		(end 257.8735 -91.716098)
		(width 0.10795)
		(layer "B.Cu")
		(net "PD_CPU0_TEST14")
	)
	(segment
		(start 254.262382 -90.747342)
		(end 254.696722 -90.747342)
		(width 0.10795)
		(layer "B.Cu")
		(net "PD_CPU0_TEST14")
	)
	(segment
		(start 259.463032 -92.702634)
		(end 259.842508 -92.702634)
		(width 0.10795)
		(layer "B.Cu")
		(net "PD_CPU0_TEST14")
	)
	(segment
		(start 253.7079 -90.19286)
		(end 254.262382 -90.747342)
		(width 0.10795)
		(layer "B.Cu")
		(net "PD_CPU0_TEST14")
	)
	(segment
		(start 249.576336 -88.756744)
		(end 249.988324 -88.344756)
		(width 0.10795)
		(layer "B.Cu")
		(net "PD_CPU0_TEST14")
	)
	(segment
		(start 248.297192 -88.323166)
		(end 248.720102 -88.323166)
		(width 0.10795)
		(layer "B.Cu")
		(net "PD_CPU0_TEST14")
	)
	(segment
		(start 247.045226 -88.339422)
		(end 247.430036 -88.724232)
		(width 0.10795)
		(layer "B.Cu")
		(net "PD_CPU0_TEST14")
	)
	(segment
		(start 254.696722 -90.747342)
		(end 255.114044 -91.164664)
		(width 0.10795)
		(layer "B.Cu")
		(net "PD_CPU0_TEST14")
	)
	(segment
		(start 253.46914 -90.19286)
		(end 253.7079 -90.19286)
		(width 0.10795)
		(layer "B.Cu")
		(net "PD_CPU0_TEST14")
	)
	(segment
		(start 262.763 -91.508072)
		(end 262.676132 -91.421204)
		(width 0.10795)
		(layer "B.Cu")
		(net "PD_CPU0_TEST14")
	)
	(segment
		(start 251.232924 -88.789256)
		(end 251.717302 -89.273634)
		(width 0.10795)
		(layer "B.Cu")
		(net "PD_CPU0_TEST14")
	)
	(segment
		(start 252.130306 -89.273634)
		(end 252.578616 -88.825324)
		(width 0.10795)
		(layer "B.Cu")
		(net "PD_CPU0_TEST14")
	)
	(segment
		(start 253.1999 -89.01938)
		(end 253.1999 -89.92362)
		(width 0.10795)
		(layer "B.Cu")
		(net "PD_CPU0_TEST14")
	)
	(segment
		(start 247.896126 -88.724232)
		(end 248.297192 -88.323166)
		(width 0.10795)
		(layer "B.Cu")
		(net "PD_CPU0_TEST14")
	)
	(segment
		(start 262.504174 -92.245434)
		(end 262.763 -91.986608)
		(width 0.10795)
		(layer "B.Cu")
		(net "PD_CPU0_TEST14")
	)
	(segment
		(start 249.988324 -88.344756)
		(end 250.400312 -88.344756)
		(width 0.10795)
		(layer "B.Cu")
		(net "PD_CPU0_TEST14")
	)
	(segment
		(start 261.975854 -92.202)
		(end 262.019288 -92.245434)
		(width 0.10795)
		(layer "B.Cu")
		(net "PD_CPU0_TEST14")
	)
	(segment
		(start 246.062246 -88.547194)
		(end 246.270018 -88.339422)
		(width 0.10795)
		(layer "B.Cu")
		(net "PD_CPU0_TEST14")
	)
	(segment
		(start 262.9662 -90.37955)
		(end 263.08431 -90.26144)
		(width 0.10795)
		(layer "B.Cu")
		(net "PD_CPU0_TEST14")
	)
	(segment
		(start 256.83464 -92.2401)
		(end 257.349498 -92.2401)
		(width 0.10795)
		(layer "B.Cu")
		(net "PD_CPU0_TEST14")
	)
	(segment
		(start 250.400312 -88.344756)
		(end 250.844812 -88.789256)
		(width 0.10795)
		(layer "B.Cu")
		(net "PD_CPU0_TEST14")
	)
	(segment
		(start 262.019288 -92.245434)
		(end 262.504174 -92.245434)
		(width 0.10795)
		(layer "B.Cu")
		(net "PD_CPU0_TEST14")
	)
	(segment
		(start 245.14302 -87.46236)
		(end 245.14302 -87.984076)
		(width 0.10795)
		(layer "B.Cu")
		(net "PD_CPU0_TEST14")
	)
	(segment
		(start 253.005844 -88.825324)
		(end 253.1999 -89.01938)
		(width 0.10795)
		(layer "B.Cu")
		(net "PD_CPU0_TEST14")
	)
	(segment
		(start 255.114044 -91.164664)
		(end 255.505204 -91.164664)
		(width 0.10795)
		(layer "B.Cu")
		(net "PD_CPU0_TEST14")
	)
	(segment
		(start 248.720102 -88.323166)
		(end 249.15368 -88.756744)
		(width 0.10795)
		(layer "B.Cu")
		(net "PD_CPU0_TEST14")
	)
	(segment
		(start 246.270018 -88.339422)
		(end 247.045226 -88.339422)
		(width 0.10795)
		(layer "B.Cu")
		(net "PD_CPU0_TEST14")
	)
	(segment
		(start 262.763 -91.986608)
		(end 262.763 -91.508072)
		(width 0.10795)
		(layer "B.Cu")
		(net "PD_CPU0_TEST14")
	)
	(segment
		(start 258.05384 -91.716098)
		(end 258.629404 -92.291662)
		(width 0.10795)
		(layer "B.Cu")
		(net "PD_CPU0_TEST14")
	)
	(segment
		(start 262.676132 -91.421204)
		(end 262.676132 -91.018868)
		(width 0.10795)
		(layer "B.Cu")
		(net "PD_CPU0_TEST14")
	)
	(segment
		(start 262.676132 -91.018868)
		(end 262.9662 -90.7288)
		(width 0.10795)
		(layer "B.Cu")
		(net "PD_CPU0_TEST14")
	)
	(segment
		(start 253.1999 -89.92362)
		(end 253.46914 -90.19286)
		(width 0.10795)
		(layer "B.Cu")
		(net "PD_CPU0_TEST14")
	)
	(segment
		(start 252.578616 -88.825324)
		(end 253.005844 -88.825324)
		(width 0.10795)
		(layer "B.Cu")
		(net "PD_CPU0_TEST14")
	)
	(segment
		(start 258.629404 -92.291662)
		(end 259.05206 -92.291662)
		(width 0.10795)
		(layer "B.Cu")
		(net "PD_CPU0_TEST14")
	)
	(segment
		(start 249.15368 -88.756744)
		(end 249.576336 -88.756744)
		(width 0.10795)
		(layer "B.Cu")
		(net "PD_CPU0_TEST14")
	)
	(segment
		(start 251.717302 -89.273634)
		(end 252.130306 -89.273634)
		(width 0.10795)
		(layer "B.Cu")
		(net "PD_CPU0_TEST14")
	)
	(segment
		(start 261.5692 -91.7956)
		(end 261.9756 -92.202)
		(width 0.10795)
		(layer "B.Cu")
		(net "PD_CPU0_TEST14")
	)
	(segment
		(start 245.14302 -87.984076)
		(end 245.706138 -88.547194)
		(width 0.10795)
		(layer "B.Cu")
		(net "PD_CPU0_TEST14")
	)
	(segment
		(start 256.09042 -91.74988)
		(end 256.34442 -91.74988)
		(width 0.10795)
		(layer "B.Cu")
		(net "PD_CPU0_TEST14")
	)
	(segment
		(start 259.842508 -92.702634)
		(end 260.254496 -92.290646)
		(width 0.10795)
		(layer "B.Cu")
		(net "PD_CPU0_TEST14")
	)
	(segment
		(start 247.430036 -88.724232)
		(end 247.896126 -88.724232)
		(width 0.10795)
		(layer "B.Cu")
		(net "PD_CPU0_TEST14")
	)
	(segment
		(start 262.79729 -89.765886)
		(end 262.22579 -89.765886)
		(width 0.10795)
		(layer "F.Cu")
		(net "PD_CPU0_TEST13")
	)
	(via
		(at 262.22579 -89.765886)
		(size 0.508)
		(drill 0.254)
		(layers "F.Cu" "B.Cu")
		(net "PD_CPU0_TEST13")
	)
	(via
		(at 245.82882 -86.57336)
		(size 0.6604)
		(drill 0.3302)
		(layers "F.Cu" "B.Cu")
		(net "PD_CPU0_TEST13")
	)
	(segment
		(start 248.62028 -87.293196)
		(end 248.318782 -87.293196)
		(width 0.10795)
		(layer "B.Cu")
		(net "PD_CPU0_TEST13")
	)
	(segment
		(start 256.36728 -90.75674)
		(end 256.0447 -90.75674)
		(width 0.10795)
		(layer "B.Cu")
		(net "PD_CPU0_TEST13")
	)
	(segment
		(start 262.043164 -89.948512)
		(end 262.043164 -90.234262)
		(width 0.10795)
		(layer "B.Cu")
		(net "PD_CPU0_TEST13")
	)
	(segment
		(start 250.87326 -87.824564)
		(end 250.363482 -87.314786)
		(width 0.10795)
		(layer "B.Cu")
		(net "PD_CPU0_TEST13")
	)
	(segment
		(start 249.133614 -87.80653)
		(end 248.62028 -87.293196)
		(width 0.10795)
		(layer "B.Cu")
		(net "PD_CPU0_TEST13")
	)
	(segment
		(start 262.043164 -90.234262)
		(end 261.727442 -90.549984)
		(width 0.10795)
		(layer "B.Cu")
		(net "PD_CPU0_TEST13")
	)
	(segment
		(start 247.465088 -87.750904)
		(end 246.953278 -87.239094)
		(width 0.10795)
		(layer "B.Cu")
		(net "PD_CPU0_TEST13")
	)
	(segment
		(start 254.776478 -89.775538)
		(end 254.357378 -89.775538)
		(width 0.10795)
		(layer "B.Cu")
		(net "PD_CPU0_TEST13")
	)
	(segment
		(start 258.563364 -91.22283)
		(end 258.108196 -90.767662)
		(width 0.10795)
		(layer "B.Cu")
		(net "PD_CPU0_TEST13")
	)
	(segment
		(start 256.81178 -91.20124)
		(end 256.36728 -90.75674)
		(width 0.10795)
		(layer "B.Cu")
		(net "PD_CPU0_TEST13")
	)
	(segment
		(start 255.966722 -90.747342)
		(end 255.47574 -90.25636)
		(width 0.10795)
		(layer "B.Cu")
		(net "PD_CPU0_TEST13")
	)
	(segment
		(start 251.267214 -87.824564)
		(end 250.87326 -87.824564)
		(width 0.10795)
		(layer "B.Cu")
		(net "PD_CPU0_TEST13")
	)
	(segment
		(start 260.751828 -91.191842)
		(end 260.334252 -91.191842)
		(width 0.10795)
		(layer "B.Cu")
		(net "PD_CPU0_TEST13")
	)
	(segment
		(start 252.118622 -87.309452)
		(end 251.782326 -87.309452)
		(width 0.10795)
		(layer "B.Cu")
		(net "PD_CPU0_TEST13")
	)
	(segment
		(start 248.318782 -87.293196)
		(end 247.861074 -87.750904)
		(width 0.10795)
		(layer "B.Cu")
		(net "PD_CPU0_TEST13")
	)
	(segment
		(start 259.018278 -91.22283)
		(end 258.563364 -91.22283)
		(width 0.10795)
		(layer "B.Cu")
		(net "PD_CPU0_TEST13")
	)
	(segment
		(start 246.530368 -87.239094)
		(end 245.864634 -86.57336)
		(width 0.10795)
		(layer "B.Cu")
		(net "PD_CPU0_TEST13")
	)
	(segment
		(start 252.574044 -87.764874)
		(end 252.118622 -87.309452)
		(width 0.10795)
		(layer "B.Cu")
		(net "PD_CPU0_TEST13")
	)
	(segment
		(start 255.2573 -90.25636)
		(end 254.776478 -89.775538)
		(width 0.10795)
		(layer "B.Cu")
		(net "PD_CPU0_TEST13")
	)
	(segment
		(start 252.993398 -87.764874)
		(end 252.574044 -87.764874)
		(width 0.10795)
		(layer "B.Cu")
		(net "PD_CPU0_TEST13")
	)
	(segment
		(start 255.47574 -90.25636)
		(end 255.2573 -90.25636)
		(width 0.10795)
		(layer "B.Cu")
		(net "PD_CPU0_TEST13")
	)
	(segment
		(start 254.0635 -88.610186)
		(end 253.75489 -88.301576)
		(width 0.10795)
		(layer "B.Cu")
		(net "PD_CPU0_TEST13")
	)
	(segment
		(start 253.75489 -88.301576)
		(end 253.5301 -88.301576)
		(width 0.10795)
		(layer "B.Cu")
		(net "PD_CPU0_TEST13")
	)
	(segment
		(start 254.0635 -89.48166)
		(end 254.0635 -88.610186)
		(width 0.10795)
		(layer "B.Cu")
		(net "PD_CPU0_TEST13")
	)
	(segment
		(start 251.782326 -87.309452)
		(end 251.267214 -87.824564)
		(width 0.10795)
		(layer "B.Cu")
		(net "PD_CPU0_TEST13")
	)
	(segment
		(start 257.28676 -91.20124)
		(end 256.81178 -91.20124)
		(width 0.10795)
		(layer "B.Cu")
		(net "PD_CPU0_TEST13")
	)
	(segment
		(start 261.727442 -90.570812)
		(end 261.465568 -90.832686)
		(width 0.10795)
		(layer "B.Cu")
		(net "PD_CPU0_TEST13")
	)
	(segment
		(start 256.035302 -90.747342)
		(end 255.966722 -90.747342)
		(width 0.10795)
		(layer "B.Cu")
		(net "PD_CPU0_TEST13")
	)
	(segment
		(start 249.545348 -87.80653)
		(end 249.133614 -87.80653)
		(width 0.10795)
		(layer "B.Cu")
		(net "PD_CPU0_TEST13")
	)
	(segment
		(start 261.727442 -90.549984)
		(end 261.727442 -90.570812)
		(width 0.10795)
		(layer "B.Cu")
		(net "PD_CPU0_TEST13")
	)
	(segment
		(start 250.037092 -87.314786)
		(end 249.545348 -87.80653)
		(width 0.10795)
		(layer "B.Cu")
		(net "PD_CPU0_TEST13")
	)
	(segment
		(start 260.334252 -91.191842)
		(end 259.820918 -91.705176)
		(width 0.10795)
		(layer "B.Cu")
		(net "PD_CPU0_TEST13")
	)
	(segment
		(start 259.820918 -91.705176)
		(end 259.500624 -91.705176)
		(width 0.10795)
		(layer "B.Cu")
		(net "PD_CPU0_TEST13")
	)
	(segment
		(start 250.363482 -87.314786)
		(end 250.037092 -87.314786)
		(width 0.10795)
		(layer "B.Cu")
		(net "PD_CPU0_TEST13")
	)
	(segment
		(start 245.864634 -86.57336)
		(end 245.82882 -86.57336)
		(width 0.10795)
		(layer "B.Cu")
		(net "PD_CPU0_TEST13")
	)
	(segment
		(start 256.0447 -90.75674)
		(end 256.035302 -90.747342)
		(width 0.10795)
		(layer "B.Cu")
		(net "PD_CPU0_TEST13")
	)
	(segment
		(start 257.720338 -90.767662)
		(end 257.28676 -91.20124)
		(width 0.10795)
		(layer "B.Cu")
		(net "PD_CPU0_TEST13")
	)
	(segment
		(start 258.108196 -90.767662)
		(end 257.720338 -90.767662)
		(width 0.10795)
		(layer "B.Cu")
		(net "PD_CPU0_TEST13")
	)
	(segment
		(start 262.22579 -89.765886)
		(end 262.043164 -89.948512)
		(width 0.10795)
		(layer "B.Cu")
		(net "PD_CPU0_TEST13")
	)
	(segment
		(start 245.82882 -86.57336)
		(end 245.14302 -86.57336)
		(width 0.10795)
		(layer "B.Cu")
		(net "PD_CPU0_TEST13")
	)
	(segment
		(start 246.953278 -87.239094)
		(end 246.530368 -87.239094)
		(width 0.10795)
		(layer "B.Cu")
		(net "PD_CPU0_TEST13")
	)
	(segment
		(start 247.861074 -87.750904)
		(end 247.465088 -87.750904)
		(width 0.10795)
		(layer "B.Cu")
		(net "PD_CPU0_TEST13")
	)
	(segment
		(start 253.5301 -88.301576)
		(end 252.993398 -87.764874)
		(width 0.10795)
		(layer "B.Cu")
		(net "PD_CPU0_TEST13")
	)
	(segment
		(start 259.500624 -91.705176)
		(end 259.018278 -91.22283)
		(width 0.10795)
		(layer "B.Cu")
		(net "PD_CPU0_TEST13")
	)
	(segment
		(start 261.465568 -90.832686)
		(end 261.110984 -90.832686)
		(width 0.10795)
		(layer "B.Cu")
		(net "PD_CPU0_TEST13")
	)
	(segment
		(start 261.110984 -90.832686)
		(end 260.751828 -91.191842)
		(width 0.10795)
		(layer "B.Cu")
		(net "PD_CPU0_TEST13")
	)
	(segment
		(start 254.357378 -89.775538)
		(end 254.0635 -89.48166)
		(width 0.10795)
		(layer "B.Cu")
		(net "PD_CPU0_TEST13")
	)
	(segment
		(start 291.79774 -70.763384)
		(end 292.36924 -70.763384)
		(width 0.10795)
		(layer "F.Cu")
		(net "PD_CPU0_TEST12")
	)
	(segment
		(start 283.488384 -75.693016)
		(end 282.3464 -76.835)
		(width 0.10795)
		(layer "F.Cu")
		(net "PD_CPU0_TEST12")
	)
	(segment
		(start 283.488384 -75.135486)
		(end 283.488384 -75.693016)
		(width 0.10795)
		(layer "F.Cu")
		(net "PD_CPU0_TEST12")
	)
	(segment
		(start 282.3464 -76.835)
		(end 282.067 -76.835)
		(width 0.10795)
		(layer "F.Cu")
		(net "PD_CPU0_TEST12")
	)
	(via
		(at 292.36924 -70.763384)
		(size 0.508)
		(drill 0.254)
		(layers "F.Cu" "B.Cu")
		(net "PD_CPU0_TEST12")
	)
	(via
		(at 283.488384 -75.135486)
		(size 0.508)
		(drill 0.254)
		(layers "F.Cu" "B.Cu")
		(net "PD_CPU0_TEST12")
	)
	(segment
		(start 288.923984 -71.353934)
		(end 288.946336 -71.353934)
		(width 0.0889)
		(layer "In2.Cu")
		(net "PD_CPU0_TEST12")
	)
	(segment
		(start 287.206944 -71.353934)
		(end 287.229296 -71.353934)
		(width 0.0889)
		(layer "In2.Cu")
		(net "PD_CPU0_TEST12")
	)
	(segment
		(start 283.488384 -73.833736)
		(end 284.17774 -73.14438)
		(width 0.0889)
		(layer "In2.Cu")
		(net "PD_CPU0_TEST12")
	)
	(segment
		(start 283.488384 -74.67727)
		(end 283.488384 -73.833736)
		(width 0.0889)
		(layer "In2.Cu")
		(net "PD_CPU0_TEST12")
	)
	(segment
		(start 291.495734 -70.858888)
		(end 292.273736 -70.858888)
		(width 0.0889)
		(layer "In2.Cu")
		(net "PD_CPU0_TEST12")
	)
	(segment
		(start 292.273736 -70.858888)
		(end 292.36924 -70.763384)
		(width 0.0889)
		(layer "In2.Cu")
		(net "PD_CPU0_TEST12")
	)
	(segment
		(start 285.85541 -72.20712)
		(end 286.01289 -72.04964)
		(width 0.0889)
		(layer "In2.Cu")
		(net "PD_CPU0_TEST12")
	)
	(segment
		(start 284.17774 -73.14438)
		(end 284.522926 -73.14438)
		(width 0.0889)
		(layer "In2.Cu")
		(net "PD_CPU0_TEST12")
	)
	(segment
		(start 284.522926 -73.14438)
		(end 285.460186 -72.20712)
		(width 0.0889)
		(layer "In2.Cu")
		(net "PD_CPU0_TEST12")
	)
	(segment
		(start 286.348424 -71.849488)
		(end 286.37738 -71.849488)
		(width 0.0889)
		(layer "In2.Cu")
		(net "PD_CPU0_TEST12")
	)
	(segment
		(start 285.460186 -72.20712)
		(end 285.85541 -72.20712)
		(width 0.0889)
		(layer "In2.Cu")
		(net "PD_CPU0_TEST12")
	)
	(segment
		(start 290.641024 -71.353934)
		(end 290.67379 -71.353934)
		(width 0.0889)
		(layer "In2.Cu")
		(net "PD_CPU0_TEST12")
	)
	(segment
		(start 289.7759 -71.849488)
		(end 289.81146 -71.849488)
		(width 0.0889)
		(layer "In2.Cu")
		(net "PD_CPU0_TEST12")
	)
	(segment
		(start 288.05886 -71.849488)
		(end 288.09442 -71.849488)
		(width 0.0889)
		(layer "In2.Cu")
		(net "PD_CPU0_TEST12")
	)
	(segment
		(start 283.488384 -75.135486)
		(end 283.488384 -74.67727)
		(width 0.089408)
		(layer "In2.Cu")
		(net "PD_CPU0_TEST12")
	)
	(arc
		(start 288.946336 -71.353934)
		(mid 289.140186 -71.410284)
		(end 289.28187 -71.554086)
		(width 0.0889)
		(layer "In2.Cu")
		(net "PD_CPU0_TEST12")
	)
	(arc
		(start 286.01289 -72.04964)
		(mid 286.154573 -71.905836)
		(end 286.348424 -71.849488)
		(width 0.0889)
		(layer "In2.Cu")
		(net "PD_CPU0_TEST12")
	)
	(arc
		(start 287.56483 -71.554086)
		(mid 287.773438 -71.766018)
		(end 288.05886 -71.849488)
		(width 0.0889)
		(layer "In2.Cu")
		(net "PD_CPU0_TEST12")
	)
	(arc
		(start 288.09442 -71.849488)
		(mid 288.379844 -71.766021)
		(end 288.58845 -71.554086)
		(width 0.0889)
		(layer "In2.Cu")
		(net "PD_CPU0_TEST12")
	)
	(arc
		(start 291.16401 -71.058786)
		(mid 291.304089 -70.91605)
		(end 291.495734 -70.858888)
		(width 0.0889)
		(layer "In2.Cu")
		(net "PD_CPU0_TEST12")
	)
	(arc
		(start 289.28187 -71.554086)
		(mid 289.490478 -71.766018)
		(end 289.7759 -71.849488)
		(width 0.0889)
		(layer "In2.Cu")
		(net "PD_CPU0_TEST12")
	)
	(arc
		(start 289.81146 -71.849488)
		(mid 290.096884 -71.766021)
		(end 290.30549 -71.554086)
		(width 0.0889)
		(layer "In2.Cu")
		(net "PD_CPU0_TEST12")
	)
	(arc
		(start 287.229296 -71.353934)
		(mid 287.423146 -71.410284)
		(end 287.56483 -71.554086)
		(width 0.0889)
		(layer "In2.Cu")
		(net "PD_CPU0_TEST12")
	)
	(arc
		(start 290.30549 -71.554086)
		(mid 290.447173 -71.410282)
		(end 290.641024 -71.353934)
		(width 0.0889)
		(layer "In2.Cu")
		(net "PD_CPU0_TEST12")
	)
	(arc
		(start 288.58845 -71.554086)
		(mid 288.730133 -71.410282)
		(end 288.923984 -71.353934)
		(width 0.0889)
		(layer "In2.Cu")
		(net "PD_CPU0_TEST12")
	)
	(arc
		(start 286.87141 -71.554086)
		(mid 287.013093 -71.410282)
		(end 287.206944 -71.353934)
		(width 0.0889)
		(layer "In2.Cu")
		(net "PD_CPU0_TEST12")
	)
	(arc
		(start 286.37738 -71.849488)
		(mid 286.662804 -71.766021)
		(end 286.87141 -71.554086)
		(width 0.0889)
		(layer "In2.Cu")
		(net "PD_CPU0_TEST12")
	)
	(arc
		(start 290.67379 -71.353934)
		(mid 290.957007 -71.269653)
		(end 291.16401 -71.058786)
		(width 0.0889)
		(layer "In2.Cu")
		(net "PD_CPU0_TEST12")
	)
	(segment
		(start 284.642814 -87.108538)
		(end 284.071314 -87.108538)
		(width 0.10795)
		(layer "F.Cu")
		(net "PD_CPU0_MCP01_DMON")
	)
	(via
		(at 284.642814 -87.108538)
		(size 0.508)
		(drill 0.254)
		(layers "F.Cu" "B.Cu")
		(net "PD_CPU0_MCP01_DMON")
	)
	(via
		(at 285.431738 -75.763882)
		(size 0.6604)
		(drill 0.3302)
		(layers "F.Cu" "B.Cu")
		(net "PD_CPU0_MCP01_DMON")
	)
	(segment
		(start 286.0294 -84.7598)
		(end 285.877 -84.9122)
		(width 0.10795)
		(layer "B.Cu")
		(net "PD_CPU0_MCP01_DMON")
	)
	(segment
		(start 287.620964 -81.974436)
		(end 287.600136 -81.995264)
		(width 0.10795)
		(layer "B.Cu")
		(net "PD_CPU0_MCP01_DMON")
	)
	(segment
		(start 286.207454 -83.6168)
		(end 285.9024 -83.921854)
		(width 0.10795)
		(layer "B.Cu")
		(net "PD_CPU0_MCP01_DMON")
	)
	(segment
		(start 282.2702 -76.4794)
		(end 282.7782 -76.4794)
		(width 0.10795)
		(layer "B.Cu")
		(net "PD_CPU0_MCP01_DMON")
	)
	(segment
		(start 285.9024 -84.328)
		(end 286.0294 -84.455)
		(width 0.10795)
		(layer "B.Cu")
		(net "PD_CPU0_MCP01_DMON")
	)
	(segment
		(start 283.5148 -75.7428)
		(end 283.675328 -75.7428)
		(width 0.10795)
		(layer "B.Cu")
		(net "PD_CPU0_MCP01_DMON")
	)
	(segment
		(start 287.858708 -80.66659)
		(end 288.283142 -80.66659)
		(width 0.10795)
		(layer "B.Cu")
		(net "PD_CPU0_MCP01_DMON")
	)
	(segment
		(start 286.0294 -84.455)
		(end 286.0294 -84.7598)
		(width 0.10795)
		(layer "B.Cu")
		(net "PD_CPU0_MCP01_DMON")
	)
	(segment
		(start 287.620964 -81.966308)
		(end 287.620964 -81.974436)
		(width 0.10795)
		(layer "B.Cu")
		(net "PD_CPU0_MCP01_DMON")
	)
	(segment
		(start 287.771332 -82.577432)
		(end 287.771332 -82.709512)
		(width 0.10795)
		(layer "B.Cu")
		(net "PD_CPU0_MCP01_DMON")
	)
	(segment
		(start 285.877 -85.3186)
		(end 286.004 -85.4456)
		(width 0.10795)
		(layer "B.Cu")
		(net "PD_CPU0_MCP01_DMON")
	)
	(segment
		(start 285.338266 -86.1314)
		(end 285.0388 -86.430866)
		(width 0.10795)
		(layer "B.Cu")
		(net "PD_CPU0_MCP01_DMON")
	)
	(segment
		(start 287.756092 -80.563974)
		(end 287.858708 -80.66659)
		(width 0.10795)
		(layer "B.Cu")
		(net "PD_CPU0_MCP01_DMON")
	)
	(segment
		(start 284.183328 -75.2348)
		(end 284.902656 -75.2348)
		(width 0.10795)
		(layer "B.Cu")
		(net "PD_CPU0_MCP01_DMON")
	)
	(segment
		(start 287.600136 -81.995264)
		(end 287.600136 -82.16392)
		(width 0.10795)
		(layer "B.Cu")
		(net "PD_CPU0_MCP01_DMON")
	)
	(segment
		(start 288.574988 -81.37144)
		(end 288.283142 -81.663286)
		(width 0.10795)
		(layer "B.Cu")
		(net "PD_CPU0_MCP01_DMON")
	)
	(segment
		(start 286.004 -85.776054)
		(end 285.648654 -86.1314)
		(width 0.10795)
		(layer "B.Cu")
		(net "PD_CPU0_MCP01_DMON")
	)
	(segment
		(start 287.5788 -78.3844)
		(end 287.673796 -78.479396)
		(width 0.10795)
		(layer "B.Cu")
		(net "PD_CPU0_MCP01_DMON")
	)
	(segment
		(start 287.697672 -77.693774)
		(end 287.697672 -77.884528)
		(width 0.10795)
		(layer "B.Cu")
		(net "PD_CPU0_MCP01_DMON")
	)
	(segment
		(start 287.350708 -77.197204)
		(end 287.591754 -77.43825)
		(width 0.10795)
		(layer "B.Cu")
		(net "PD_CPU0_MCP01_DMON")
	)
	(segment
		(start 287.451546 -83.190334)
		(end 286.963866 -83.190334)
		(width 0.10795)
		(layer "B.Cu")
		(net "PD_CPU0_MCP01_DMON")
	)
	(segment
		(start 285.7754 -76.4032)
		(end 286.119062 -76.746862)
		(width 0.10795)
		(layer "B.Cu")
		(net "PD_CPU0_MCP01_DMON")
	)
	(segment
		(start 285.648654 -86.1314)
		(end 285.338266 -86.1314)
		(width 0.10795)
		(layer "B.Cu")
		(net "PD_CPU0_MCP01_DMON")
	)
	(segment
		(start 284.902656 -75.2348)
		(end 285.431738 -75.763882)
		(width 0.10795)
		(layer "B.Cu")
		(net "PD_CPU0_MCP01_DMON")
	)
	(segment
		(start 287.732216 -82.804)
		(end 287.657286 -82.984594)
		(width 0.10795)
		(layer "B.Cu")
		(net "PD_CPU0_MCP01_DMON")
	)
	(segment
		(start 287.923986 -81.663286)
		(end 287.620964 -81.966308)
		(width 0.10795)
		(layer "B.Cu")
		(net "PD_CPU0_MCP01_DMON")
	)
	(segment
		(start 287.5788 -78.994)
		(end 287.5788 -79.3496)
		(width 0.10795)
		(layer "B.Cu")
		(net "PD_CPU0_MCP01_DMON")
	)
	(segment
		(start 285.431738 -75.763882)
		(end 285.7754 -76.107544)
		(width 0.10795)
		(layer "B.Cu")
		(net "PD_CPU0_MCP01_DMON")
	)
	(segment
		(start 286.963866 -83.190334)
		(end 286.5374 -83.6168)
		(width 0.10795)
		(layer "B.Cu")
		(net "PD_CPU0_MCP01_DMON")
	)
	(segment
		(start 286.5374 -83.6168)
		(end 286.207454 -83.6168)
		(width 0.10795)
		(layer "B.Cu")
		(net "PD_CPU0_MCP01_DMON")
	)
	(segment
		(start 286.548576 -76.746862)
		(end 286.998918 -77.197204)
		(width 0.10795)
		(layer "B.Cu")
		(net "PD_CPU0_MCP01_DMON")
	)
	(segment
		(start 287.697672 -77.884528)
		(end 287.5788 -78.0034)
		(width 0.10795)
		(layer "B.Cu")
		(net "PD_CPU0_MCP01_DMON")
	)
	(segment
		(start 287.771332 -82.709512)
		(end 287.732216 -82.804)
		(width 0.10795)
		(layer "B.Cu")
		(net "PD_CPU0_MCP01_DMON")
	)
	(segment
		(start 287.5788 -79.3496)
		(end 287.673796 -79.444596)
		(width 0.10795)
		(layer "B.Cu")
		(net "PD_CPU0_MCP01_DMON")
	)
	(segment
		(start 287.657286 -82.984594)
		(end 287.451546 -83.190334)
		(width 0.10795)
		(layer "B.Cu")
		(net "PD_CPU0_MCP01_DMON")
	)
	(segment
		(start 285.0388 -86.430866)
		(end 285.0388 -86.712552)
		(width 0.10795)
		(layer "B.Cu")
		(net "PD_CPU0_MCP01_DMON")
	)
	(segment
		(start 288.283142 -81.663286)
		(end 287.923986 -81.663286)
		(width 0.10795)
		(layer "B.Cu")
		(net "PD_CPU0_MCP01_DMON")
	)
	(segment
		(start 287.673796 -79.444596)
		(end 287.673796 -79.889604)
		(width 0.10795)
		(layer "B.Cu")
		(net "PD_CPU0_MCP01_DMON")
	)
	(segment
		(start 286.004 -85.4456)
		(end 286.004 -85.776054)
		(width 0.10795)
		(layer "B.Cu")
		(net "PD_CPU0_MCP01_DMON")
	)
	(segment
		(start 285.0388 -86.712552)
		(end 284.642814 -87.108538)
		(width 0.10795)
		(layer "B.Cu")
		(net "PD_CPU0_MCP01_DMON")
	)
	(segment
		(start 287.600136 -82.16392)
		(end 287.771332 -82.577432)
		(width 0.10795)
		(layer "B.Cu")
		(net "PD_CPU0_MCP01_DMON")
	)
	(segment
		(start 287.591754 -77.43825)
		(end 287.697672 -77.693774)
		(width 0.10795)
		(layer "B.Cu")
		(net "PD_CPU0_MCP01_DMON")
	)
	(segment
		(start 287.673796 -78.899004)
		(end 287.5788 -78.994)
		(width 0.10795)
		(layer "B.Cu")
		(net "PD_CPU0_MCP01_DMON")
	)
	(segment
		(start 287.673796 -78.479396)
		(end 287.673796 -78.899004)
		(width 0.10795)
		(layer "B.Cu")
		(net "PD_CPU0_MCP01_DMON")
	)
	(segment
		(start 283.675328 -75.7428)
		(end 284.183328 -75.2348)
		(width 0.10795)
		(layer "B.Cu")
		(net "PD_CPU0_MCP01_DMON")
	)
	(segment
		(start 287.604962 -80.05572)
		(end 287.604962 -80.198722)
		(width 0.10795)
		(layer "B.Cu")
		(net "PD_CPU0_MCP01_DMON")
	)
	(segment
		(start 285.877 -84.9122)
		(end 285.877 -85.3186)
		(width 0.10795)
		(layer "B.Cu")
		(net "PD_CPU0_MCP01_DMON")
	)
	(segment
		(start 286.998918 -77.197204)
		(end 287.350708 -77.197204)
		(width 0.10795)
		(layer "B.Cu")
		(net "PD_CPU0_MCP01_DMON")
	)
	(segment
		(start 286.119062 -76.746862)
		(end 286.548576 -76.746862)
		(width 0.10795)
		(layer "B.Cu")
		(net "PD_CPU0_MCP01_DMON")
	)
	(segment
		(start 285.9024 -83.921854)
		(end 285.9024 -84.328)
		(width 0.10795)
		(layer "B.Cu")
		(net "PD_CPU0_MCP01_DMON")
	)
	(segment
		(start 285.7754 -76.107544)
		(end 285.7754 -76.4032)
		(width 0.10795)
		(layer "B.Cu")
		(net "PD_CPU0_MCP01_DMON")
	)
	(segment
		(start 282.7782 -76.4794)
		(end 283.5148 -75.7428)
		(width 0.10795)
		(layer "B.Cu")
		(net "PD_CPU0_MCP01_DMON")
	)
	(segment
		(start 288.283142 -80.66659)
		(end 288.574988 -80.958436)
		(width 0.10795)
		(layer "B.Cu")
		(net "PD_CPU0_MCP01_DMON")
	)
	(segment
		(start 287.5788 -78.0034)
		(end 287.5788 -78.3844)
		(width 0.10795)
		(layer "B.Cu")
		(net "PD_CPU0_MCP01_DMON")
	)
	(segment
		(start 287.673796 -79.889604)
		(end 287.604962 -80.05572)
		(width 0.10795)
		(layer "B.Cu")
		(net "PD_CPU0_MCP01_DMON")
	)
	(segment
		(start 287.604962 -80.198722)
		(end 287.756092 -80.563974)
		(width 0.10795)
		(layer "B.Cu")
		(net "PD_CPU0_MCP01_DMON")
	)
	(segment
		(start 288.574988 -80.958436)
		(end 288.574988 -81.37144)
		(width 0.10795)
		(layer "B.Cu")
		(net "PD_CPU0_MCP01_DMON")
	)
	(segment
		(start 367.145316 -73.495154)
		(end 367.545112 -73.89495)
		(width 0.10795)
		(layer "F.Cu")
		(net "FM_PVDDQ_KLM_EN")
	)
	(via
		(at 21.8694 -128.3208)
		(size 0.508)
		(drill 0.254)
		(layers "F.Cu" "B.Cu")
		(net "FM_PVDDQ_KLM_EN")
	)
	(via
		(at 367.145316 -73.495154)
		(size 0.4572)
		(drill 0.2032)
		(layers "F.Cu" "B.Cu")
		(net "FM_PVDDQ_KLM_EN")
	)
	(via
		(at -4.111244 -131.903216)
		(size 0.508)
		(drill 0.254)
		(layers "F.Cu" "B.Cu")
		(net "FM_PVDDQ_KLM_EN")
	)
	(via
		(at 158.3944 -132.5118)
		(size 0.508)
		(drill 0.254)
		(layers "F.Cu" "B.Cu")
		(net "FM_PVDDQ_KLM_EN")
	)
	(via
		(at -3.10134 -132.3848)
		(size 0.6604)
		(drill 0.3302)
		(layers "F.Cu" "B.Cu")
		(net "FM_PVDDQ_KLM_EN")
	)
	(segment
		(start -3.10134 -132.3848)
		(end -3.163316 -132.446776)
		(width 0.10795)
		(layer "B.Cu")
		(net "FM_PVDDQ_KLM_EN")
	)
	(segment
		(start -3.567684 -132.446776)
		(end -4.111244 -131.903216)
		(width 0.10795)
		(layer "B.Cu")
		(net "FM_PVDDQ_KLM_EN")
	)
	(segment
		(start -0.889 -132.334)
		(end -3.05054 -132.334)
		(width 0.10795)
		(layer "B.Cu")
		(net "FM_PVDDQ_KLM_EN")
	)
	(segment
		(start -3.05054 -132.334)
		(end -3.10134 -132.3848)
		(width 0.10795)
		(layer "B.Cu")
		(net "FM_PVDDQ_KLM_EN")
	)
	(segment
		(start -3.163316 -132.446776)
		(end -3.567684 -132.446776)
		(width 0.10795)
		(layer "B.Cu")
		(net "FM_PVDDQ_KLM_EN")
	)
	(segment
		(start -0.93472 -129.450592)
		(end -0.845312 -129.361184)
		(width 0.089408)
		(layer "In2.Cu")
		(net "FM_PVDDQ_KLM_EN")
	)
	(segment
		(start -2.958846 -129.450592)
		(end -0.93472 -129.450592)
		(width 0.089408)
		(layer "In2.Cu")
		(net "FM_PVDDQ_KLM_EN")
	)
	(segment
		(start -4.111244 -131.903216)
		(end -3.862324 -131.654296)
		(width 0.089408)
		(layer "In2.Cu")
		(net "FM_PVDDQ_KLM_EN")
	)
	(segment
		(start 4.8006 -124.817632)
		(end 12.824968 -124.817632)
		(width 0.089408)
		(layer "In2.Cu")
		(net "FM_PVDDQ_KLM_EN")
	)
	(segment
		(start 0.041148 -124.817632)
		(end 1.270508 -124.817632)
		(width 0.089408)
		(layer "In2.Cu")
		(net "FM_PVDDQ_KLM_EN")
	)
	(segment
		(start -3.862324 -131.654296)
		(end -3.862324 -130.35407)
		(width 0.089408)
		(layer "In2.Cu")
		(net "FM_PVDDQ_KLM_EN")
	)
	(segment
		(start 17.868392 -124.319792)
		(end 21.8694 -128.3208)
		(width 0.089408)
		(layer "In2.Cu")
		(net "FM_PVDDQ_KLM_EN")
	)
	(segment
		(start -0.845312 -125.704092)
		(end 0.041148 -124.817632)
		(width 0.089408)
		(layer "In2.Cu")
		(net "FM_PVDDQ_KLM_EN")
	)
	(segment
		(start 12.824968 -124.817632)
		(end 13.322808 -124.319792)
		(width 0.089408)
		(layer "In2.Cu")
		(net "FM_PVDDQ_KLM_EN")
	)
	(segment
		(start 2.16154 -123.9266)
		(end 3.909568 -123.9266)
		(width 0.089408)
		(layer "In2.Cu")
		(net "FM_PVDDQ_KLM_EN")
	)
	(segment
		(start 1.270508 -124.817632)
		(end 2.16154 -123.9266)
		(width 0.089408)
		(layer "In2.Cu")
		(net "FM_PVDDQ_KLM_EN")
	)
	(segment
		(start 3.909568 -123.9266)
		(end 4.8006 -124.817632)
		(width 0.089408)
		(layer "In2.Cu")
		(net "FM_PVDDQ_KLM_EN")
	)
	(segment
		(start -3.862324 -130.35407)
		(end -2.958846 -129.450592)
		(width 0.089408)
		(layer "In2.Cu")
		(net "FM_PVDDQ_KLM_EN")
	)
	(segment
		(start -0.845312 -129.361184)
		(end -0.845312 -125.704092)
		(width 0.089408)
		(layer "In2.Cu")
		(net "FM_PVDDQ_KLM_EN")
	)
	(segment
		(start 13.322808 -124.319792)
		(end 17.868392 -124.319792)
		(width 0.089408)
		(layer "In2.Cu")
		(net "FM_PVDDQ_KLM_EN")
	)
	(segment
		(start 328.683112 -139.57427)
		(end 328.683112 -139.416282)
		(width 0.089408)
		(layer "In4.Cu")
		(net "FM_PVDDQ_KLM_EN")
	)
	(segment
		(start 326.596756 -157.77083)
		(end 328.975974 -155.391612)
		(width 0.089408)
		(layer "In4.Cu")
		(net "FM_PVDDQ_KLM_EN")
	)
	(segment
		(start 336.078068 -79.73695)
		(end 336.078068 -78.640432)
		(width 0.089408)
		(layer "In4.Cu")
		(net "FM_PVDDQ_KLM_EN")
	)
	(segment
		(start 280.75255 -157.31617)
		(end 281.20721 -157.77083)
		(width 0.089408)
		(layer "In4.Cu")
		(net "FM_PVDDQ_KLM_EN")
	)
	(segment
		(start 346.243402 -70.549008)
		(end 352.272092 -70.549008)
		(width 0.089408)
		(layer "In4.Cu")
		(net "FM_PVDDQ_KLM_EN")
	)
	(segment
		(start 352.467164 -70.74408)
		(end 353.990656 -70.74408)
		(width 0.089408)
		(layer "In4.Cu")
		(net "FM_PVDDQ_KLM_EN")
	)
	(segment
		(start 328.3712 -112.83315)
		(end 327.45299 -111.91494)
		(width 0.089408)
		(layer "In4.Cu")
		(net "FM_PVDDQ_KLM_EN")
	)
	(segment
		(start 333.092806 -82.722212)
		(end 336.078068 -79.73695)
		(width 0.089408)
		(layer "In4.Cu")
		(net "FM_PVDDQ_KLM_EN")
	)
	(segment
		(start 328.975974 -148.959824)
		(end 326.77735 -146.7612)
		(width 0.089408)
		(layer "In4.Cu")
		(net "FM_PVDDQ_KLM_EN")
	)
	(segment
		(start 354.568506 -70.166484)
		(end 357.318564 -70.166484)
		(width 0.089408)
		(layer "In4.Cu")
		(net "FM_PVDDQ_KLM_EN")
	)
	(segment
		(start 158.735522 -132.852922)
		(end 158.735522 -140.374878)
		(width 0.089408)
		(layer "In4.Cu")
		(net "FM_PVDDQ_KLM_EN")
	)
	(segment
		(start 158.3944 -132.5118)
		(end 158.735522 -132.852922)
		(width 0.089408)
		(layer "In4.Cu")
		(net "FM_PVDDQ_KLM_EN")
	)
	(segment
		(start 336.735674 -74.68616)
		(end 338.244434 -73.1774)
		(width 0.089408)
		(layer "In4.Cu")
		(net "FM_PVDDQ_KLM_EN")
	)
	(segment
		(start 181.251098 -150.4442)
		(end 182.673752 -151.866854)
		(width 0.089408)
		(layer "In4.Cu")
		(net "FM_PVDDQ_KLM_EN")
	)
	(segment
		(start 354.56749 -70.1675)
		(end 354.568506 -70.166484)
		(width 0.089408)
		(layer "In4.Cu")
		(net "FM_PVDDQ_KLM_EN")
	)
	(segment
		(start 364.819692 -72.948292)
		(end 366.598454 -72.948292)
		(width 0.089408)
		(layer "In4.Cu")
		(net "FM_PVDDQ_KLM_EN")
	)
	(segment
		(start 339.591904 -72.72655)
		(end 339.591904 -72.18553)
		(width 0.089408)
		(layer "In4.Cu")
		(net "FM_PVDDQ_KLM_EN")
	)
	(segment
		(start 338.244434 -73.1774)
		(end 339.141054 -73.1774)
		(width 0.089408)
		(layer "In4.Cu")
		(net "FM_PVDDQ_KLM_EN")
	)
	(segment
		(start 172.239178 -145.611088)
		(end 173.523148 -145.611088)
		(width 0.089408)
		(layer "In4.Cu")
		(net "FM_PVDDQ_KLM_EN")
	)
	(segment
		(start 330.9874 -135.552688)
		(end 331.758544 -134.781544)
		(width 0.089408)
		(layer "In4.Cu")
		(net "FM_PVDDQ_KLM_EN")
	)
	(segment
		(start 281.20721 -157.77083)
		(end 326.596756 -157.77083)
		(width 0.089408)
		(layer "In4.Cu")
		(net "FM_PVDDQ_KLM_EN")
	)
	(segment
		(start 336.735674 -77.982826)
		(end 336.735674 -74.68616)
		(width 0.089408)
		(layer "In4.Cu")
		(net "FM_PVDDQ_KLM_EN")
	)
	(segment
		(start 327.45299 -91.556332)
		(end 333.092806 -85.916516)
		(width 0.089408)
		(layer "In4.Cu")
		(net "FM_PVDDQ_KLM_EN")
	)
	(segment
		(start 326.04202 -146.7612)
		(end 325.006208 -145.725388)
		(width 0.089408)
		(layer "In4.Cu")
		(net "FM_PVDDQ_KLM_EN")
	)
	(segment
		(start 328.3712 -124.3711)
		(end 328.3712 -112.83315)
		(width 0.089408)
		(layer "In4.Cu")
		(net "FM_PVDDQ_KLM_EN")
	)
	(segment
		(start 366.598454 -72.948292)
		(end 367.145316 -73.495154)
		(width 0.089408)
		(layer "In4.Cu")
		(net "FM_PVDDQ_KLM_EN")
	)
	(segment
		(start 326.0852 -141.86027)
		(end 327.697592 -141.86027)
		(width 0.089408)
		(layer "In4.Cu")
		(net "FM_PVDDQ_KLM_EN")
	)
	(segment
		(start 328.975974 -155.391612)
		(end 328.975974 -148.959824)
		(width 0.089408)
		(layer "In4.Cu")
		(net "FM_PVDDQ_KLM_EN")
	)
	(segment
		(start 353.990656 -70.74408)
		(end 354.567236 -70.1675)
		(width 0.089408)
		(layer "In4.Cu")
		(net "FM_PVDDQ_KLM_EN")
	)
	(segment
		(start 182.673752 -151.866854)
		(end 182.673752 -154.904694)
		(width 0.089408)
		(layer "In4.Cu")
		(net "FM_PVDDQ_KLM_EN")
	)
	(segment
		(start 182.673752 -154.904694)
		(end 183.598058 -155.829)
		(width 0.089408)
		(layer "In4.Cu")
		(net "FM_PVDDQ_KLM_EN")
	)
	(segment
		(start 330.9874 -137.01522)
		(end 330.9874 -135.552688)
		(width 0.089408)
		(layer "In4.Cu")
		(net "FM_PVDDQ_KLM_EN")
	)
	(segment
		(start 328.683366 -139.574524)
		(end 328.683112 -139.57427)
		(width 0.089408)
		(layer "In4.Cu")
		(net "FM_PVDDQ_KLM_EN")
	)
	(segment
		(start 354.567236 -70.1675)
		(end 354.56749 -70.1675)
		(width 0.089408)
		(layer "In4.Cu")
		(net "FM_PVDDQ_KLM_EN")
	)
	(segment
		(start 336.078068 -78.640432)
		(end 336.735674 -77.982826)
		(width 0.089408)
		(layer "In4.Cu")
		(net "FM_PVDDQ_KLM_EN")
	)
	(segment
		(start 328.683366 -140.874496)
		(end 328.683366 -139.574524)
		(width 0.089408)
		(layer "In4.Cu")
		(net "FM_PVDDQ_KLM_EN")
	)
	(segment
		(start 177.992786 -150.4442)
		(end 181.251098 -150.4442)
		(width 0.089408)
		(layer "In4.Cu")
		(net "FM_PVDDQ_KLM_EN")
	)
	(segment
		(start 340.443058 -71.334376)
		(end 345.458034 -71.334376)
		(width 0.089408)
		(layer "In4.Cu")
		(net "FM_PVDDQ_KLM_EN")
	)
	(segment
		(start 352.272092 -70.549008)
		(end 352.467164 -70.74408)
		(width 0.089408)
		(layer "In4.Cu")
		(net "FM_PVDDQ_KLM_EN")
	)
	(segment
		(start 333.092806 -85.916516)
		(end 333.092806 -82.722212)
		(width 0.089408)
		(layer "In4.Cu")
		(net "FM_PVDDQ_KLM_EN")
	)
	(segment
		(start 166.642034 -142.666466)
		(end 169.10558 -145.130012)
		(width 0.089408)
		(layer "In4.Cu")
		(net "FM_PVDDQ_KLM_EN")
	)
	(segment
		(start 265.113516 -157.31617)
		(end 280.75255 -157.31617)
		(width 0.089408)
		(layer "In4.Cu")
		(net "FM_PVDDQ_KLM_EN")
	)
	(segment
		(start 173.523148 -145.611088)
		(end 174.98822 -147.07616)
		(width 0.089408)
		(layer "In4.Cu")
		(net "FM_PVDDQ_KLM_EN")
	)
	(segment
		(start 169.10558 -145.130012)
		(end 171.758102 -145.130012)
		(width 0.089408)
		(layer "In4.Cu")
		(net "FM_PVDDQ_KLM_EN")
	)
	(segment
		(start 339.591904 -72.18553)
		(end 340.443058 -71.334376)
		(width 0.089408)
		(layer "In4.Cu")
		(net "FM_PVDDQ_KLM_EN")
	)
	(segment
		(start 358.547924 -71.395844)
		(end 363.267244 -71.395844)
		(width 0.089408)
		(layer "In4.Cu")
		(net "FM_PVDDQ_KLM_EN")
	)
	(segment
		(start 328.683112 -139.416282)
		(end 328.683366 -139.416028)
		(width 0.089408)
		(layer "In4.Cu")
		(net "FM_PVDDQ_KLM_EN")
	)
	(segment
		(start 174.98822 -147.07616)
		(end 174.98822 -147.439634)
		(width 0.089408)
		(layer "In4.Cu")
		(net "FM_PVDDQ_KLM_EN")
	)
	(segment
		(start 331.758544 -134.781544)
		(end 331.758544 -129.5019)
		(width 0.089408)
		(layer "In4.Cu")
		(net "FM_PVDDQ_KLM_EN")
	)
	(segment
		(start 325.006208 -142.939262)
		(end 326.0852 -141.86027)
		(width 0.089408)
		(layer "In4.Cu")
		(net "FM_PVDDQ_KLM_EN")
	)
	(segment
		(start 183.598058 -155.829)
		(end 187.091828 -155.829)
		(width 0.089408)
		(layer "In4.Cu")
		(net "FM_PVDDQ_KLM_EN")
	)
	(segment
		(start 187.091828 -155.829)
		(end 188.904626 -157.641798)
		(width 0.089408)
		(layer "In4.Cu")
		(net "FM_PVDDQ_KLM_EN")
	)
	(segment
		(start 345.458034 -71.334376)
		(end 346.243402 -70.549008)
		(width 0.089408)
		(layer "In4.Cu")
		(net "FM_PVDDQ_KLM_EN")
	)
	(segment
		(start 327.697592 -141.86027)
		(end 328.683366 -140.874496)
		(width 0.089408)
		(layer "In4.Cu")
		(net "FM_PVDDQ_KLM_EN")
	)
	(segment
		(start 328.683366 -139.319254)
		(end 330.9874 -137.01522)
		(width 0.089408)
		(layer "In4.Cu")
		(net "FM_PVDDQ_KLM_EN")
	)
	(segment
		(start 328.683366 -139.416028)
		(end 328.683366 -139.319254)
		(width 0.089408)
		(layer "In4.Cu")
		(net "FM_PVDDQ_KLM_EN")
	)
	(segment
		(start 363.267244 -71.395844)
		(end 364.819692 -72.948292)
		(width 0.089408)
		(layer "In4.Cu")
		(net "FM_PVDDQ_KLM_EN")
	)
	(segment
		(start 357.318564 -70.166484)
		(end 358.547924 -71.395844)
		(width 0.089408)
		(layer "In4.Cu")
		(net "FM_PVDDQ_KLM_EN")
	)
	(segment
		(start 328.2823 -126.025656)
		(end 328.2823 -124.46)
		(width 0.089408)
		(layer "In4.Cu")
		(net "FM_PVDDQ_KLM_EN")
	)
	(segment
		(start 327.45299 -111.91494)
		(end 327.45299 -91.556332)
		(width 0.089408)
		(layer "In4.Cu")
		(net "FM_PVDDQ_KLM_EN")
	)
	(segment
		(start 339.141054 -73.1774)
		(end 339.591904 -72.72655)
		(width 0.089408)
		(layer "In4.Cu")
		(net "FM_PVDDQ_KLM_EN")
	)
	(segment
		(start 171.758102 -145.130012)
		(end 172.239178 -145.611088)
		(width 0.089408)
		(layer "In4.Cu")
		(net "FM_PVDDQ_KLM_EN")
	)
	(segment
		(start 174.98822 -147.439634)
		(end 177.992786 -150.4442)
		(width 0.089408)
		(layer "In4.Cu")
		(net "FM_PVDDQ_KLM_EN")
	)
	(segment
		(start 328.2823 -124.46)
		(end 328.3712 -124.3711)
		(width 0.089408)
		(layer "In4.Cu")
		(net "FM_PVDDQ_KLM_EN")
	)
	(segment
		(start 331.758544 -129.5019)
		(end 328.2823 -126.025656)
		(width 0.089408)
		(layer "In4.Cu")
		(net "FM_PVDDQ_KLM_EN")
	)
	(segment
		(start 264.787888 -157.641798)
		(end 265.113516 -157.31617)
		(width 0.089408)
		(layer "In4.Cu")
		(net "FM_PVDDQ_KLM_EN")
	)
	(segment
		(start 161.02711 -142.666466)
		(end 166.642034 -142.666466)
		(width 0.089408)
		(layer "In4.Cu")
		(net "FM_PVDDQ_KLM_EN")
	)
	(segment
		(start 325.006208 -145.725388)
		(end 325.006208 -142.939262)
		(width 0.089408)
		(layer "In4.Cu")
		(net "FM_PVDDQ_KLM_EN")
	)
	(segment
		(start 158.735522 -140.374878)
		(end 161.02711 -142.666466)
		(width 0.089408)
		(layer "In4.Cu")
		(net "FM_PVDDQ_KLM_EN")
	)
	(segment
		(start 326.77735 -146.7612)
		(end 326.04202 -146.7612)
		(width 0.089408)
		(layer "In4.Cu")
		(net "FM_PVDDQ_KLM_EN")
	)
	(segment
		(start 188.904626 -157.641798)
		(end 264.787888 -157.641798)
		(width 0.089408)
		(layer "In4.Cu")
		(net "FM_PVDDQ_KLM_EN")
	)
	(segment
		(start 22.19706 -127.53848)
		(end 21.8694 -127.86614)
		(width 0.089408)
		(layer "In9.Cu")
		(net "FM_PVDDQ_KLM_EN")
	)
	(segment
		(start 158.3944 -132.5118)
		(end 156.972 -133.9342)
		(width 0.089408)
		(layer "In9.Cu")
		(net "FM_PVDDQ_KLM_EN")
	)
	(segment
		(start 37.05225 -137.612628)
		(end 36.6522 -137.212578)
		(width 0.089408)
		(layer "In9.Cu")
		(net "FM_PVDDQ_KLM_EN")
	)
	(segment
		(start 95.222568 -139.2174)
		(end 93.617796 -137.612628)
		(width 0.089408)
		(layer "In9.Cu")
		(net "FM_PVDDQ_KLM_EN")
	)
	(segment
		(start 35.222434 -132.682234)
		(end 30.212792 -132.682234)
		(width 0.089408)
		(layer "In9.Cu")
		(net "FM_PVDDQ_KLM_EN")
	)
	(segment
		(start 96.185228 -139.2174)
		(end 95.222568 -139.2174)
		(width 0.089408)
		(layer "In9.Cu")
		(net "FM_PVDDQ_KLM_EN")
	)
	(segment
		(start 36.6522 -137.212578)
		(end 36.6522 -134.112)
		(width 0.089408)
		(layer "In9.Cu")
		(net "FM_PVDDQ_KLM_EN")
	)
	(segment
		(start 156.09697 -137.57783)
		(end 97.824798 -137.57783)
		(width 0.089408)
		(layer "In9.Cu")
		(net "FM_PVDDQ_KLM_EN")
	)
	(segment
		(start 25.069038 -127.53848)
		(end 22.19706 -127.53848)
		(width 0.089408)
		(layer "In9.Cu")
		(net "FM_PVDDQ_KLM_EN")
	)
	(segment
		(start 21.8694 -127.86614)
		(end 21.8694 -128.3208)
		(width 0.089408)
		(layer "In9.Cu")
		(net "FM_PVDDQ_KLM_EN")
	)
	(segment
		(start 30.212792 -132.682234)
		(end 25.069038 -127.53848)
		(width 0.089408)
		(layer "In9.Cu")
		(net "FM_PVDDQ_KLM_EN")
	)
	(segment
		(start 93.617796 -137.612628)
		(end 37.05225 -137.612628)
		(width 0.089408)
		(layer "In9.Cu")
		(net "FM_PVDDQ_KLM_EN")
	)
	(segment
		(start 156.972 -133.9342)
		(end 156.972 -136.7028)
		(width 0.089408)
		(layer "In9.Cu")
		(net "FM_PVDDQ_KLM_EN")
	)
	(segment
		(start 36.6522 -134.112)
		(end 35.222434 -132.682234)
		(width 0.089408)
		(layer "In9.Cu")
		(net "FM_PVDDQ_KLM_EN")
	)
	(segment
		(start 156.972 -136.7028)
		(end 156.09697 -137.57783)
		(width 0.089408)
		(layer "In9.Cu")
		(net "FM_PVDDQ_KLM_EN")
	)
	(segment
		(start 97.824798 -137.57783)
		(end 96.185228 -139.2174)
		(width 0.089408)
		(layer "In9.Cu")
		(net "FM_PVDDQ_KLM_EN")
	)
	(segment
		(start 368.745262 -73.495154)
		(end 369.145058 -73.89495)
		(width 0.1016)
		(layer "F.Cu")
		(net "FM_PVDDQ_GHJ_EN")
	)
	(via
		(at 178.0794 -2.0574)
		(size 0.508)
		(drill 0.254)
		(layers "F.Cu" "B.Cu")
		(net "FM_PVDDQ_GHJ_EN")
	)
	(via
		(at 368.745262 -73.495154)
		(size 0.4572)
		(drill 0.2032)
		(layers "F.Cu" "B.Cu")
		(net "FM_PVDDQ_GHJ_EN")
	)
	(via
		(at 13.793978 2.044954)
		(size 0.508)
		(drill 0.254)
		(layers "F.Cu" "B.Cu")
		(net "FM_PVDDQ_GHJ_EN")
	)
	(via
		(at 373.6213 -64.222884)
		(size 0.508)
		(drill 0.254)
		(layers "F.Cu" "B.Cu")
		(net "FM_PVDDQ_GHJ_EN")
	)
	(via
		(at 324.191884 2.6035)
		(size 0.508)
		(drill 0.254)
		(layers "F.Cu" "B.Cu")
		(net "FM_PVDDQ_GHJ_EN")
	)
	(segment
		(start 13.923264 2.17424)
		(end 13.793978 2.044954)
		(width 0.10795)
		(layer "B.Cu")
		(net "FM_PVDDQ_GHJ_EN")
	)
	(segment
		(start 13.923264 2.985516)
		(end 13.923264 2.17424)
		(width 0.10795)
		(layer "B.Cu")
		(net "FM_PVDDQ_GHJ_EN")
	)
	(segment
		(start 170.564556 -1.524)
		(end 168.3258 0.714756)
		(width 0.089408)
		(layer "In4.Cu")
		(net "FM_PVDDQ_GHJ_EN")
	)
	(segment
		(start 172.631862 -1.524)
		(end 170.564556 -1.524)
		(width 0.089408)
		(layer "In4.Cu")
		(net "FM_PVDDQ_GHJ_EN")
	)
	(segment
		(start 168.3258 0.9144)
		(end 168.021 1.2192)
		(width 0.089408)
		(layer "In4.Cu")
		(net "FM_PVDDQ_GHJ_EN")
	)
	(segment
		(start 178.0794 -2.0574)
		(end 177.6984 -2.4384)
		(width 0.089408)
		(layer "In4.Cu")
		(net "FM_PVDDQ_GHJ_EN")
	)
	(segment
		(start 16.802862 4.245102)
		(end 15.565374 4.245102)
		(width 0.089408)
		(layer "In4.Cu")
		(net "FM_PVDDQ_GHJ_EN")
	)
	(segment
		(start 168.3258 0.714756)
		(end 168.3258 0.9144)
		(width 0.089408)
		(layer "In4.Cu")
		(net "FM_PVDDQ_GHJ_EN")
	)
	(segment
		(start 15.565374 4.245102)
		(end 13.793978 2.473706)
		(width 0.089408)
		(layer "In4.Cu")
		(net "FM_PVDDQ_GHJ_EN")
	)
	(segment
		(start 115.816126 4.792726)
		(end 103.45801 4.792726)
		(width 0.089408)
		(layer "In4.Cu")
		(net "FM_PVDDQ_GHJ_EN")
	)
	(segment
		(start 173.546262 -2.4384)
		(end 172.631862 -1.524)
		(width 0.089408)
		(layer "In4.Cu")
		(net "FM_PVDDQ_GHJ_EN")
	)
	(segment
		(start 167.4114 1.2192)
		(end 166.791386 1.839214)
		(width 0.089408)
		(layer "In4.Cu")
		(net "FM_PVDDQ_GHJ_EN")
	)
	(segment
		(start 103.45801 4.792726)
		(end 102.901496 5.34924)
		(width 0.089408)
		(layer "In4.Cu")
		(net "FM_PVDDQ_GHJ_EN")
	)
	(segment
		(start 102.901496 5.34924)
		(end 17.907 5.34924)
		(width 0.089408)
		(layer "In4.Cu")
		(net "FM_PVDDQ_GHJ_EN")
	)
	(segment
		(start 17.907 5.34924)
		(end 16.802862 4.245102)
		(width 0.089408)
		(layer "In4.Cu")
		(net "FM_PVDDQ_GHJ_EN")
	)
	(segment
		(start 165.480746 5.461)
		(end 116.4844 5.461)
		(width 0.089408)
		(layer "In4.Cu")
		(net "FM_PVDDQ_GHJ_EN")
	)
	(segment
		(start 166.791386 1.839214)
		(end 166.791386 4.15036)
		(width 0.089408)
		(layer "In4.Cu")
		(net "FM_PVDDQ_GHJ_EN")
	)
	(segment
		(start 166.791386 4.15036)
		(end 165.480746 5.461)
		(width 0.089408)
		(layer "In4.Cu")
		(net "FM_PVDDQ_GHJ_EN")
	)
	(segment
		(start 116.4844 5.461)
		(end 115.816126 4.792726)
		(width 0.089408)
		(layer "In4.Cu")
		(net "FM_PVDDQ_GHJ_EN")
	)
	(segment
		(start 13.793978 2.473706)
		(end 13.793978 2.044954)
		(width 0.089408)
		(layer "In4.Cu")
		(net "FM_PVDDQ_GHJ_EN")
	)
	(segment
		(start 168.021 1.2192)
		(end 167.4114 1.2192)
		(width 0.089408)
		(layer "In4.Cu")
		(net "FM_PVDDQ_GHJ_EN")
	)
	(segment
		(start 177.6984 -2.4384)
		(end 173.546262 -2.4384)
		(width 0.089408)
		(layer "In4.Cu")
		(net "FM_PVDDQ_GHJ_EN")
	)
	(segment
		(start 370.935504 -65.686432)
		(end 370.935504 -64.2874)
		(width 0.089408)
		(layer "In9.Cu")
		(net "FM_PVDDQ_GHJ_EN")
	)
	(segment
		(start 369.996212 -68.509388)
		(end 369.996212 -66.625724)
		(width 0.089408)
		(layer "In9.Cu")
		(net "FM_PVDDQ_GHJ_EN")
	)
	(segment
		(start 181.2798 2.6416)
		(end 181.2798 3.442208)
		(width 0.089408)
		(layer "In9.Cu")
		(net "FM_PVDDQ_GHJ_EN")
	)
	(segment
		(start 178.4604 -1.6764)
		(end 179.077366 -1.6764)
		(width 0.089408)
		(layer "In9.Cu")
		(net "FM_PVDDQ_GHJ_EN")
	)
	(segment
		(start 369.9764 -68.5292)
		(end 369.996212 -68.509388)
		(width 0.089408)
		(layer "In9.Cu")
		(net "FM_PVDDQ_GHJ_EN")
	)
	(segment
		(start 369.1382 -73.102216)
		(end 369.1382 -69.374004)
		(width 0.089408)
		(layer "In9.Cu")
		(net "FM_PVDDQ_GHJ_EN")
	)
	(segment
		(start 369.443508 -69.068696)
		(end 369.699794 -69.068696)
		(width 0.089408)
		(layer "In9.Cu")
		(net "FM_PVDDQ_GHJ_EN")
	)
	(segment
		(start 369.699794 -69.068696)
		(end 369.9764 -68.79209)
		(width 0.089408)
		(layer "In9.Cu")
		(net "FM_PVDDQ_GHJ_EN")
	)
	(segment
		(start 179.8574 -0.896366)
		(end 179.8574 1.2192)
		(width 0.089408)
		(layer "In9.Cu")
		(net "FM_PVDDQ_GHJ_EN")
	)
	(segment
		(start 368.745262 -73.495154)
		(end 369.1382 -73.102216)
		(width 0.089408)
		(layer "In9.Cu")
		(net "FM_PVDDQ_GHJ_EN")
	)
	(segment
		(start 183.144668 5.307076)
		(end 322.010024 5.307076)
		(width 0.089408)
		(layer "In9.Cu")
		(net "FM_PVDDQ_GHJ_EN")
	)
	(segment
		(start 373.216424 -63.818008)
		(end 373.6213 -64.222884)
		(width 0.089408)
		(layer "In9.Cu")
		(net "FM_PVDDQ_GHJ_EN")
	)
	(segment
		(start 369.996212 -66.625724)
		(end 370.935504 -65.686432)
		(width 0.089408)
		(layer "In9.Cu")
		(net "FM_PVDDQ_GHJ_EN")
	)
	(segment
		(start 179.077366 -1.6764)
		(end 179.8574 -0.896366)
		(width 0.089408)
		(layer "In9.Cu")
		(net "FM_PVDDQ_GHJ_EN")
	)
	(segment
		(start 181.2798 3.442208)
		(end 183.144668 5.307076)
		(width 0.089408)
		(layer "In9.Cu")
		(net "FM_PVDDQ_GHJ_EN")
	)
	(segment
		(start 369.1382 -69.374004)
		(end 369.443508 -69.068696)
		(width 0.089408)
		(layer "In9.Cu")
		(net "FM_PVDDQ_GHJ_EN")
	)
	(segment
		(start 179.8574 1.2192)
		(end 181.2798 2.6416)
		(width 0.089408)
		(layer "In9.Cu")
		(net "FM_PVDDQ_GHJ_EN")
	)
	(segment
		(start 369.9764 -68.79209)
		(end 369.9764 -68.5292)
		(width 0.089408)
		(layer "In9.Cu")
		(net "FM_PVDDQ_GHJ_EN")
	)
	(segment
		(start 178.0794 -2.0574)
		(end 178.4604 -1.6764)
		(width 0.089408)
		(layer "In9.Cu")
		(net "FM_PVDDQ_GHJ_EN")
	)
	(segment
		(start 370.935504 -64.2874)
		(end 371.404896 -63.818008)
		(width 0.089408)
		(layer "In9.Cu")
		(net "FM_PVDDQ_GHJ_EN")
	)
	(segment
		(start 322.010024 5.307076)
		(end 324.191884 3.125216)
		(width 0.089408)
		(layer "In9.Cu")
		(net "FM_PVDDQ_GHJ_EN")
	)
	(segment
		(start 371.404896 -63.818008)
		(end 373.216424 -63.818008)
		(width 0.089408)
		(layer "In9.Cu")
		(net "FM_PVDDQ_GHJ_EN")
	)
	(segment
		(start 324.191884 3.125216)
		(end 324.191884 2.6035)
		(width 0.089408)
		(layer "In9.Cu")
		(net "FM_PVDDQ_GHJ_EN")
	)
	(segment
		(start 323.569076 -25.079198)
		(end 323.705728 -24.942546)
		(width 0.089408)
		(layer "In11.Cu")
		(net "FM_PVDDQ_GHJ_EN")
	)
	(segment
		(start 318.862964 -36.258246)
		(end 320.42354 -34.69767)
		(width 0.089408)
		(layer "In11.Cu")
		(net "FM_PVDDQ_GHJ_EN")
	)
	(segment
		(start 323.653912 -27.764994)
		(end 323.653912 -25.495758)
		(width 0.089408)
		(layer "In11.Cu")
		(net "FM_PVDDQ_GHJ_EN")
	)
	(segment
		(start 323.705728 -24.942546)
		(end 323.705728 2.117344)
		(width 0.089408)
		(layer "In11.Cu")
		(net "FM_PVDDQ_GHJ_EN")
	)
	(segment
		(start 323.569076 -25.410922)
		(end 323.569076 -25.079198)
		(width 0.089408)
		(layer "In11.Cu")
		(net "FM_PVDDQ_GHJ_EN")
	)
	(segment
		(start 371.875304 -61.777626)
		(end 366.230662 -56.133746)
		(width 0.089408)
		(layer "In11.Cu")
		(net "FM_PVDDQ_GHJ_EN")
	)
	(segment
		(start 372.834916 -63.5)
		(end 372.573296 -63.5)
		(width 0.089408)
		(layer "In11.Cu")
		(net "FM_PVDDQ_GHJ_EN")
	)
	(segment
		(start 324.962774 -29.073856)
		(end 323.653912 -27.764994)
		(width 0.089408)
		(layer "In11.Cu")
		(net "FM_PVDDQ_GHJ_EN")
	)
	(segment
		(start 323.149214 -44.550076)
		(end 320.279268 -44.550076)
		(width 0.089408)
		(layer "In11.Cu")
		(net "FM_PVDDQ_GHJ_EN")
	)
	(segment
		(start 318.862964 -43.133772)
		(end 318.862964 -36.258246)
		(width 0.089408)
		(layer "In11.Cu")
		(net "FM_PVDDQ_GHJ_EN")
	)
	(segment
		(start 323.705728 2.117344)
		(end 324.191884 2.6035)
		(width 0.089408)
		(layer "In11.Cu")
		(net "FM_PVDDQ_GHJ_EN")
	)
	(segment
		(start 360.601006 -52.21986)
		(end 359.21823 -52.21986)
		(width 0.089408)
		(layer "In11.Cu")
		(net "FM_PVDDQ_GHJ_EN")
	)
	(segment
		(start 328.559414 -49.960276)
		(end 323.149214 -44.550076)
		(width 0.089408)
		(layer "In11.Cu")
		(net "FM_PVDDQ_GHJ_EN")
	)
	(segment
		(start 323.653912 -25.495758)
		(end 323.569076 -25.410922)
		(width 0.089408)
		(layer "In11.Cu")
		(net "FM_PVDDQ_GHJ_EN")
	)
	(segment
		(start 371.875304 -62.802008)
		(end 371.875304 -61.777626)
		(width 0.089408)
		(layer "In11.Cu")
		(net "FM_PVDDQ_GHJ_EN")
	)
	(segment
		(start 359.21823 -52.21986)
		(end 356.958646 -49.960276)
		(width 0.089408)
		(layer "In11.Cu")
		(net "FM_PVDDQ_GHJ_EN")
	)
	(segment
		(start 320.42354 -34.69767)
		(end 321.495674 -34.69767)
		(width 0.089408)
		(layer "In11.Cu")
		(net "FM_PVDDQ_GHJ_EN")
	)
	(segment
		(start 373.6213 -64.222884)
		(end 373.5578 -64.222884)
		(width 0.089408)
		(layer "In11.Cu")
		(net "FM_PVDDQ_GHJ_EN")
	)
	(segment
		(start 366.230662 -56.133746)
		(end 364.514892 -56.133746)
		(width 0.089408)
		(layer "In11.Cu")
		(net "FM_PVDDQ_GHJ_EN")
	)
	(segment
		(start 321.495674 -34.69767)
		(end 324.962774 -31.23057)
		(width 0.089408)
		(layer "In11.Cu")
		(net "FM_PVDDQ_GHJ_EN")
	)
	(segment
		(start 373.5578 -64.222884)
		(end 372.834916 -63.5)
		(width 0.089408)
		(layer "In11.Cu")
		(net "FM_PVDDQ_GHJ_EN")
	)
	(segment
		(start 320.279268 -44.550076)
		(end 318.862964 -43.133772)
		(width 0.089408)
		(layer "In11.Cu")
		(net "FM_PVDDQ_GHJ_EN")
	)
	(segment
		(start 364.514892 -56.133746)
		(end 360.601006 -52.21986)
		(width 0.089408)
		(layer "In11.Cu")
		(net "FM_PVDDQ_GHJ_EN")
	)
	(segment
		(start 372.573296 -63.5)
		(end 371.875304 -62.802008)
		(width 0.089408)
		(layer "In11.Cu")
		(net "FM_PVDDQ_GHJ_EN")
	)
	(segment
		(start 356.958646 -49.960276)
		(end 328.559414 -49.960276)
		(width 0.089408)
		(layer "In11.Cu")
		(net "FM_PVDDQ_GHJ_EN")
	)
	(segment
		(start 324.962774 -31.23057)
		(end 324.962774 -29.073856)
		(width 0.089408)
		(layer "In11.Cu")
		(net "FM_PVDDQ_GHJ_EN")
	)
	(segment
		(start 367.145316 -75.894692)
		(end 367.545112 -75.494896)
		(width 0.1016)
		(layer "F.Cu")
		(net "FM_PVDDQ_DEF_EN")
	)
	(via
		(at 368.855752 -123.754642)
		(size 0.508)
		(drill 0.254)
		(layers "F.Cu" "B.Cu")
		(net "FM_PVDDQ_DEF_EN")
	)
	(via
		(at 367.145316 -75.894692)
		(size 0.4572)
		(drill 0.2032)
		(layers "F.Cu" "B.Cu")
		(net "FM_PVDDQ_DEF_EN")
	)
	(via
		(at 365.35106 -133.90245)
		(size 0.508)
		(drill 0.254)
		(layers "F.Cu" "B.Cu")
		(net "FM_PVDDQ_DEF_EN")
	)
	(via
		(at 361.725464 -131.694936)
		(size 0.6604)
		(drill 0.3302)
		(layers "F.Cu" "B.Cu")
		(net "FM_PVDDQ_DEF_EN")
	)
	(segment
		(start 365.35106 -133.017768)
		(end 363.905292 -131.572)
		(width 0.10795)
		(layer "B.Cu")
		(net "FM_PVDDQ_DEF_EN")
	)
	(segment
		(start 363.905292 -131.572)
		(end 361.8484 -131.572)
		(width 0.10795)
		(layer "B.Cu")
		(net "FM_PVDDQ_DEF_EN")
	)
	(segment
		(start 361.8484 -131.572)
		(end 361.725464 -131.694936)
		(width 0.10795)
		(layer "B.Cu")
		(net "FM_PVDDQ_DEF_EN")
	)
	(segment
		(start 365.35106 -133.90245)
		(end 365.35106 -133.017768)
		(width 0.10795)
		(layer "B.Cu")
		(net "FM_PVDDQ_DEF_EN")
	)
	(segment
		(start 361.725464 -131.694936)
		(end 361.188 -132.2324)
		(width 0.10795)
		(layer "B.Cu")
		(net "FM_PVDDQ_DEF_EN")
	)
	(segment
		(start 361.188 -132.2324)
		(end 361.188 -133.0198)
		(width 0.10795)
		(layer "B.Cu")
		(net "FM_PVDDQ_DEF_EN")
	)
	(segment
		(start 365.63427 -127.713994)
		(end 368.808 -124.540264)
		(width 0.089408)
		(layer "In2.Cu")
		(net "FM_PVDDQ_DEF_EN")
	)
	(segment
		(start 365.63427 -133.61924)
		(end 365.63427 -127.713994)
		(width 0.089408)
		(layer "In2.Cu")
		(net "FM_PVDDQ_DEF_EN")
	)
	(segment
		(start 368.808 -123.802394)
		(end 368.855752 -123.754642)
		(width 0.089408)
		(layer "In2.Cu")
		(net "FM_PVDDQ_DEF_EN")
	)
	(segment
		(start 368.808 -124.540264)
		(end 368.808 -123.802394)
		(width 0.089408)
		(layer "In2.Cu")
		(net "FM_PVDDQ_DEF_EN")
	)
	(segment
		(start 365.35106 -133.90245)
		(end 365.63427 -133.61924)
		(width 0.089408)
		(layer "In2.Cu")
		(net "FM_PVDDQ_DEF_EN")
	)
	(segment
		(start 367.772696 -90.480896)
		(end 367.772696 -89.957402)
		(width 0.089408)
		(layer "In9.Cu")
		(net "FM_PVDDQ_DEF_EN")
	)
	(segment
		(start 367.843562 -79.468218)
		(end 368.099848 -79.468218)
		(width 0.089408)
		(layer "In9.Cu")
		(net "FM_PVDDQ_DEF_EN")
	)
	(segment
		(start 373.311674 -85.481414)
		(end 373.311674 -84.73567)
		(width 0.089408)
		(layer "In9.Cu")
		(net "FM_PVDDQ_DEF_EN")
	)
	(segment
		(start 374.259348 -98.750374)
		(end 374.178576 -98.750374)
		(width 0.089408)
		(layer "In9.Cu")
		(net "FM_PVDDQ_DEF_EN")
	)
	(segment
		(start 374.0658 -116.290344)
		(end 375.3104 -115.045744)
		(width 0.089408)
		(layer "In9.Cu")
		(net "FM_PVDDQ_DEF_EN")
	)
	(segment
		(start 376.644408 -102.452932)
		(end 375.680478 -101.489002)
		(width 0.089408)
		(layer "In9.Cu")
		(net "FM_PVDDQ_DEF_EN")
	)
	(segment
		(start 374.178322 -98.75012)
		(end 373.499126 -98.75012)
		(width 0.089408)
		(layer "In9.Cu")
		(net "FM_PVDDQ_DEF_EN")
	)
	(segment
		(start 373.850408 -84.196936)
		(end 373.850408 -83.850734)
		(width 0.089408)
		(layer "In9.Cu")
		(net "FM_PVDDQ_DEF_EN")
	)
	(segment
		(start 378.42317 -106.16311)
		(end 378.42317 -105.79989)
		(width 0.089408)
		(layer "In9.Cu")
		(net "FM_PVDDQ_DEF_EN")
	)
	(segment
		(start 373.311674 -84.73567)
		(end 373.850408 -84.196936)
		(width 0.089408)
		(layer "In9.Cu")
		(net "FM_PVDDQ_DEF_EN")
	)
	(segment
		(start 368.88547 -122.723402)
		(end 370.006626 -121.602246)
		(width 0.089408)
		(layer "In9.Cu")
		(net "FM_PVDDQ_DEF_EN")
	)
	(segment
		(start 368.099848 -77.121512)
		(end 367.843816 -77.121512)
		(width 0.089408)
		(layer "In9.Cu")
		(net "FM_PVDDQ_DEF_EN")
	)
	(segment
		(start 370.505482 -121.602246)
		(end 374.0658 -118.041928)
		(width 0.089408)
		(layer "In9.Cu")
		(net "FM_PVDDQ_DEF_EN")
	)
	(segment
		(start 378.987304 -102.357936)
		(end 378.986796 -102.357936)
		(width 0.089408)
		(layer "In9.Cu")
		(net "FM_PVDDQ_DEF_EN")
	)
	(segment
		(start 372.869206 -98.1202)
		(end 372.869206 -96.474534)
		(width 0.089408)
		(layer "In9.Cu")
		(net "FM_PVDDQ_DEF_EN")
	)
	(segment
		(start 368.90579 -89.191846)
		(end 370.189252 -87.908384)
		(width 0.089408)
		(layer "In9.Cu")
		(net "FM_PVDDQ_DEF_EN")
	)
	(segment
		(start 378.986796 -102.357936)
		(end 378.930662 -102.301802)
		(width 0.089408)
		(layer "In9.Cu")
		(net "FM_PVDDQ_DEF_EN")
	)
	(segment
		(start 378.930662 -102.301802)
		(end 377.497086 -102.301802)
		(width 0.089408)
		(layer "In9.Cu")
		(net "FM_PVDDQ_DEF_EN")
	)
	(segment
		(start 378.72543 -105.13441)
		(end 379.22073 -104.63911)
		(width 0.089408)
		(layer "In9.Cu")
		(net "FM_PVDDQ_DEF_EN")
	)
	(segment
		(start 379.22073 -104.27589)
		(end 379.71603 -103.78059)
		(width 0.089408)
		(layer "In9.Cu")
		(net "FM_PVDDQ_DEF_EN")
	)
	(segment
		(start 379.22073 -102.591362)
		(end 378.987304 -102.357936)
		(width 0.089408)
		(layer "In9.Cu")
		(net "FM_PVDDQ_DEF_EN")
	)
	(segment
		(start 378.42317 -105.79989)
		(end 378.72543 -105.49763)
		(width 0.089408)
		(layer "In9.Cu")
		(net "FM_PVDDQ_DEF_EN")
	)
	(segment
		(start 368.337084 -80.814672)
		(end 368.337084 -80.55864)
		(width 0.089408)
		(layer "In9.Cu")
		(net "FM_PVDDQ_DEF_EN")
	)
	(segment
		(start 374.178576 -98.750374)
		(end 374.178322 -98.75012)
		(width 0.089408)
		(layer "In9.Cu")
		(net "FM_PVDDQ_DEF_EN")
	)
	(segment
		(start 375.680478 -101.489002)
		(end 375.680478 -100.171504)
		(width 0.089408)
		(layer "In9.Cu")
		(net "FM_PVDDQ_DEF_EN")
	)
	(segment
		(start 371.088412 -83.566)
		(end 368.337084 -80.814672)
		(width 0.089408)
		(layer "In9.Cu")
		(net "FM_PVDDQ_DEF_EN")
	)
	(segment
		(start 367.843816 -77.121512)
		(end 367.571782 -76.849478)
		(width 0.089408)
		(layer "In9.Cu")
		(net "FM_PVDDQ_DEF_EN")
	)
	(segment
		(start 372.869206 -96.474534)
		(end 373.486172 -95.857568)
		(width 0.089408)
		(layer "In9.Cu")
		(net "FM_PVDDQ_DEF_EN")
	)
	(segment
		(start 377.629928 -106.956352)
		(end 378.42317 -106.16311)
		(width 0.089408)
		(layer "In9.Cu")
		(net "FM_PVDDQ_DEF_EN")
	)
	(segment
		(start 373.499126 -98.75012)
		(end 372.869206 -98.1202)
		(width 0.089408)
		(layer "In9.Cu")
		(net "FM_PVDDQ_DEF_EN")
	)
	(segment
		(start 367.772696 -89.957402)
		(end 368.538252 -89.191846)
		(width 0.089408)
		(layer "In9.Cu")
		(net "FM_PVDDQ_DEF_EN")
	)
	(segment
		(start 379.22073 -102.851458)
		(end 379.22073 -102.591362)
		(width 0.089408)
		(layer "In9.Cu")
		(net "FM_PVDDQ_DEF_EN")
	)
	(segment
		(start 373.565674 -83.566)
		(end 371.088412 -83.566)
		(width 0.089408)
		(layer "In9.Cu")
		(net "FM_PVDDQ_DEF_EN")
	)
	(segment
		(start 374.0658 -118.041928)
		(end 374.0658 -116.290344)
		(width 0.089408)
		(layer "In9.Cu")
		(net "FM_PVDDQ_DEF_EN")
	)
	(segment
		(start 368.538252 -89.191846)
		(end 368.90579 -89.191846)
		(width 0.089408)
		(layer "In9.Cu")
		(net "FM_PVDDQ_DEF_EN")
	)
	(segment
		(start 373.486172 -95.857568)
		(end 373.486172 -95.0468)
		(width 0.089408)
		(layer "In9.Cu")
		(net "FM_PVDDQ_DEF_EN")
	)
	(segment
		(start 379.3744 -103.005128)
		(end 379.22073 -102.851458)
		(width 0.089408)
		(layer "In9.Cu")
		(net "FM_PVDDQ_DEF_EN")
	)
	(segment
		(start 367.571782 -79.739998)
		(end 367.843562 -79.468218)
		(width 0.089408)
		(layer "In9.Cu")
		(net "FM_PVDDQ_DEF_EN")
	)
	(segment
		(start 378.72543 -105.49763)
		(end 378.72543 -105.13441)
		(width 0.089408)
		(layer "In9.Cu")
		(net "FM_PVDDQ_DEF_EN")
	)
	(segment
		(start 370.006626 -121.602246)
		(end 370.505482 -121.602246)
		(width 0.089408)
		(layer "In9.Cu")
		(net "FM_PVDDQ_DEF_EN")
	)
	(segment
		(start 367.843816 -80.321404)
		(end 367.571782 -80.04937)
		(width 0.089408)
		(layer "In9.Cu")
		(net "FM_PVDDQ_DEF_EN")
	)
	(segment
		(start 368.337084 -80.55864)
		(end 368.099848 -80.321404)
		(width 0.089408)
		(layer "In9.Cu")
		(net "FM_PVDDQ_DEF_EN")
	)
	(segment
		(start 371.4496 -94.1578)
		(end 367.772696 -90.480896)
		(width 0.089408)
		(layer "In9.Cu")
		(net "FM_PVDDQ_DEF_EN")
	)
	(segment
		(start 368.855752 -123.754642)
		(end 368.88547 -123.754642)
		(width 0.089408)
		(layer "In9.Cu")
		(net "FM_PVDDQ_DEF_EN")
	)
	(segment
		(start 377.345956 -102.452932)
		(end 376.644408 -102.452932)
		(width 0.089408)
		(layer "In9.Cu")
		(net "FM_PVDDQ_DEF_EN")
	)
	(segment
		(start 368.318542 -79.249524)
		(end 368.318542 -77.340206)
		(width 0.089408)
		(layer "In9.Cu")
		(net "FM_PVDDQ_DEF_EN")
	)
	(segment
		(start 367.571782 -80.04937)
		(end 367.571782 -79.739998)
		(width 0.089408)
		(layer "In9.Cu")
		(net "FM_PVDDQ_DEF_EN")
	)
	(segment
		(start 367.571782 -76.849478)
		(end 367.571782 -76.321158)
		(width 0.089408)
		(layer "In9.Cu")
		(net "FM_PVDDQ_DEF_EN")
	)
	(segment
		(start 372.597172 -94.1578)
		(end 371.4496 -94.1578)
		(width 0.089408)
		(layer "In9.Cu")
		(net "FM_PVDDQ_DEF_EN")
	)
	(segment
		(start 368.88547 -123.754642)
		(end 368.88547 -122.723402)
		(width 0.089408)
		(layer "In9.Cu")
		(net "FM_PVDDQ_DEF_EN")
	)
	(segment
		(start 368.099848 -80.321404)
		(end 367.843816 -80.321404)
		(width 0.089408)
		(layer "In9.Cu")
		(net "FM_PVDDQ_DEF_EN")
	)
	(segment
		(start 368.099848 -79.468218)
		(end 368.318542 -79.249524)
		(width 0.089408)
		(layer "In9.Cu")
		(net "FM_PVDDQ_DEF_EN")
	)
	(segment
		(start 373.486172 -95.0468)
		(end 372.597172 -94.1578)
		(width 0.089408)
		(layer "In9.Cu")
		(net "FM_PVDDQ_DEF_EN")
	)
	(segment
		(start 379.71603 -103.78059)
		(end 379.71603 -103.449882)
		(width 0.089408)
		(layer "In9.Cu")
		(net "FM_PVDDQ_DEF_EN")
	)
	(segment
		(start 367.571782 -76.321158)
		(end 367.145316 -75.894692)
		(width 0.089408)
		(layer "In9.Cu")
		(net "FM_PVDDQ_DEF_EN")
	)
	(segment
		(start 368.318542 -77.340206)
		(end 368.099848 -77.121512)
		(width 0.089408)
		(layer "In9.Cu")
		(net "FM_PVDDQ_DEF_EN")
	)
	(segment
		(start 379.3744 -103.108252)
		(end 379.3744 -103.005128)
		(width 0.089408)
		(layer "In9.Cu")
		(net "FM_PVDDQ_DEF_EN")
	)
	(segment
		(start 377.497086 -102.301802)
		(end 377.345956 -102.452932)
		(width 0.089408)
		(layer "In9.Cu")
		(net "FM_PVDDQ_DEF_EN")
	)
	(segment
		(start 375.3104 -114.722148)
		(end 375.310654 -114.721894)
		(width 0.089408)
		(layer "In9.Cu")
		(net "FM_PVDDQ_DEF_EN")
	)
	(segment
		(start 375.310654 -107.360212)
		(end 375.714514 -106.956352)
		(width 0.089408)
		(layer "In9.Cu")
		(net "FM_PVDDQ_DEF_EN")
	)
	(segment
		(start 375.680478 -100.171504)
		(end 374.259348 -98.750374)
		(width 0.089408)
		(layer "In9.Cu")
		(net "FM_PVDDQ_DEF_EN")
	)
	(segment
		(start 370.884704 -87.908384)
		(end 373.311674 -85.481414)
		(width 0.089408)
		(layer "In9.Cu")
		(net "FM_PVDDQ_DEF_EN")
	)
	(segment
		(start 375.310654 -114.721894)
		(end 375.310654 -107.360212)
		(width 0.089408)
		(layer "In9.Cu")
		(net "FM_PVDDQ_DEF_EN")
	)
	(segment
		(start 379.71603 -103.449882)
		(end 379.3744 -103.108252)
		(width 0.089408)
		(layer "In9.Cu")
		(net "FM_PVDDQ_DEF_EN")
	)
	(segment
		(start 375.3104 -115.045744)
		(end 375.3104 -114.722148)
		(width 0.089408)
		(layer "In9.Cu")
		(net "FM_PVDDQ_DEF_EN")
	)
	(segment
		(start 379.22073 -104.63911)
		(end 379.22073 -104.27589)
		(width 0.089408)
		(layer "In9.Cu")
		(net "FM_PVDDQ_DEF_EN")
	)
	(segment
		(start 375.714514 -106.956352)
		(end 377.629928 -106.956352)
		(width 0.089408)
		(layer "In9.Cu")
		(net "FM_PVDDQ_DEF_EN")
	)
	(segment
		(start 373.850408 -83.850734)
		(end 373.565674 -83.566)
		(width 0.089408)
		(layer "In9.Cu")
		(net "FM_PVDDQ_DEF_EN")
	)
	(segment
		(start 370.189252 -87.908384)
		(end 370.884704 -87.908384)
		(width 0.089408)
		(layer "In9.Cu")
		(net "FM_PVDDQ_DEF_EN")
	)
	(segment
		(start 367.945162 -75.894692)
		(end 368.344958 -75.494896)
		(width 0.1016)
		(layer "F.Cu")
		(net "FM_PVDDQ_ABC_EN")
	)
	(segment
		(start 343.67216 -21.78812)
		(end 344.45956 -21.78812)
		(width 0.10795)
		(layer "F.Cu")
		(net "FM_PVDDQ_ABC_EN")
	)
	(segment
		(start 344.45956 -21.78812)
		(end 344.678 -22.00656)
		(width 0.10795)
		(layer "F.Cu")
		(net "FM_PVDDQ_ABC_EN")
	)
	(via
		(at 373.127016 -62.556898)
		(size 0.508)
		(drill 0.254)
		(layers "F.Cu" "B.Cu")
		(net "FM_PVDDQ_ABC_EN")
	)
	(via
		(at 367.945162 -75.894692)
		(size 0.4572)
		(drill 0.2032)
		(layers "F.Cu" "B.Cu")
		(net "FM_PVDDQ_ABC_EN")
	)
	(via
		(at 344.678 -22.00656)
		(size 0.508)
		(drill 0.254)
		(layers "F.Cu" "B.Cu")
		(net "FM_PVDDQ_ABC_EN")
	)
	(via
		(at 323.96938 -25.24506)
		(size 0.508)
		(drill 0.254)
		(layers "F.Cu" "B.Cu")
		(net "FM_PVDDQ_ABC_EN")
	)
	(segment
		(start 326.09536 -27.3812)
		(end 326.88276 -28.1686)
		(width 0.089408)
		(layer "In4.Cu")
		(net "FM_PVDDQ_ABC_EN")
	)
	(segment
		(start 324.104 -27.2288)
		(end 324.2564 -27.3812)
		(width 0.089408)
		(layer "In4.Cu")
		(net "FM_PVDDQ_ABC_EN")
	)
	(segment
		(start 338.925408 -20.636992)
		(end 338.925408 -19.189192)
		(width 0.089408)
		(layer "In4.Cu")
		(net "FM_PVDDQ_ABC_EN")
	)
	(segment
		(start 342.7476 -20.0406)
		(end 342.7476 -21.393912)
		(width 0.089408)
		(layer "In4.Cu")
		(net "FM_PVDDQ_ABC_EN")
	)
	(segment
		(start 338.925408 -19.189192)
		(end 339.217 -18.8976)
		(width 0.089408)
		(layer "In4.Cu")
		(net "FM_PVDDQ_ABC_EN")
	)
	(segment
		(start 328.4982 -28.1686)
		(end 329.958192 -29.628592)
		(width 0.089408)
		(layer "In4.Cu")
		(net "FM_PVDDQ_ABC_EN")
	)
	(segment
		(start 333.469488 -26.651712)
		(end 338.665312 -21.455888)
		(width 0.089408)
		(layer "In4.Cu")
		(net "FM_PVDDQ_ABC_EN")
	)
	(segment
		(start 331.679296 -30.39745)
		(end 331.679296 -27.657552)
		(width 0.089408)
		(layer "In4.Cu")
		(net "FM_PVDDQ_ABC_EN")
	)
	(segment
		(start 341.6046 -18.8976)
		(end 342.7476 -20.0406)
		(width 0.089408)
		(layer "In4.Cu")
		(net "FM_PVDDQ_ABC_EN")
	)
	(segment
		(start 326.88276 -28.1686)
		(end 328.4982 -28.1686)
		(width 0.089408)
		(layer "In4.Cu")
		(net "FM_PVDDQ_ABC_EN")
	)
	(segment
		(start 323.96938 -25.24506)
		(end 324.104 -25.37968)
		(width 0.089408)
		(layer "In4.Cu")
		(net "FM_PVDDQ_ABC_EN")
	)
	(segment
		(start 330.256642 -31.052262)
		(end 331.024484 -31.052262)
		(width 0.089408)
		(layer "In4.Cu")
		(net "FM_PVDDQ_ABC_EN")
	)
	(segment
		(start 343.360248 -22.00656)
		(end 344.678 -22.00656)
		(width 0.089408)
		(layer "In4.Cu")
		(net "FM_PVDDQ_ABC_EN")
	)
	(segment
		(start 338.665312 -21.455888)
		(end 338.665312 -20.897088)
		(width 0.089408)
		(layer "In4.Cu")
		(net "FM_PVDDQ_ABC_EN")
	)
	(segment
		(start 329.958192 -29.628592)
		(end 329.958192 -30.753812)
		(width 0.089408)
		(layer "In4.Cu")
		(net "FM_PVDDQ_ABC_EN")
	)
	(segment
		(start 324.104 -25.37968)
		(end 324.104 -27.2288)
		(width 0.089408)
		(layer "In4.Cu")
		(net "FM_PVDDQ_ABC_EN")
	)
	(segment
		(start 331.679296 -27.657552)
		(end 332.685136 -26.651712)
		(width 0.089408)
		(layer "In4.Cu")
		(net "FM_PVDDQ_ABC_EN")
	)
	(segment
		(start 329.958192 -30.753812)
		(end 330.256642 -31.052262)
		(width 0.089408)
		(layer "In4.Cu")
		(net "FM_PVDDQ_ABC_EN")
	)
	(segment
		(start 331.024484 -31.052262)
		(end 331.679296 -30.39745)
		(width 0.089408)
		(layer "In4.Cu")
		(net "FM_PVDDQ_ABC_EN")
	)
	(segment
		(start 339.217 -18.8976)
		(end 341.6046 -18.8976)
		(width 0.089408)
		(layer "In4.Cu")
		(net "FM_PVDDQ_ABC_EN")
	)
	(segment
		(start 342.7476 -21.393912)
		(end 343.360248 -22.00656)
		(width 0.089408)
		(layer "In4.Cu")
		(net "FM_PVDDQ_ABC_EN")
	)
	(segment
		(start 338.665312 -20.897088)
		(end 338.925408 -20.636992)
		(width 0.089408)
		(layer "In4.Cu")
		(net "FM_PVDDQ_ABC_EN")
	)
	(segment
		(start 324.2564 -27.3812)
		(end 326.09536 -27.3812)
		(width 0.089408)
		(layer "In4.Cu")
		(net "FM_PVDDQ_ABC_EN")
	)
	(segment
		(start 332.685136 -26.651712)
		(end 333.469488 -26.651712)
		(width 0.089408)
		(layer "In4.Cu")
		(net "FM_PVDDQ_ABC_EN")
	)
	(segment
		(start 366.771936 -67.307968)
		(end 366.771936 -73.64984)
		(width 0.089408)
		(layer "In9.Cu")
		(net "FM_PVDDQ_ABC_EN")
	)
	(segment
		(start 372.111778 -63.181992)
		(end 372.110762 -63.183008)
		(width 0.089408)
		(layer "In9.Cu")
		(net "FM_PVDDQ_ABC_EN")
	)
	(segment
		(start 367.103152 -65.562226)
		(end 367.103152 -66.976752)
		(width 0.089408)
		(layer "In9.Cu")
		(net "FM_PVDDQ_ABC_EN")
	)
	(segment
		(start 372.501922 -63.181992)
		(end 372.111778 -63.181992)
		(width 0.089408)
		(layer "In9.Cu")
		(net "FM_PVDDQ_ABC_EN")
	)
	(segment
		(start 366.771936 -73.64984)
		(end 366.99063 -73.868534)
		(width 0.089408)
		(layer "In9.Cu")
		(net "FM_PVDDQ_ABC_EN")
	)
	(segment
		(start 367.300002 -73.868534)
		(end 367.565178 -74.13371)
		(width 0.089408)
		(layer "In9.Cu")
		(net "FM_PVDDQ_ABC_EN")
	)
	(segment
		(start 368.859562 -63.964312)
		(end 368.859308 -63.964058)
		(width 0.089408)
		(layer "In9.Cu")
		(net "FM_PVDDQ_ABC_EN")
	)
	(segment
		(start 373.127016 -62.556898)
		(end 372.501922 -63.181992)
		(width 0.089408)
		(layer "In9.Cu")
		(net "FM_PVDDQ_ABC_EN")
	)
	(segment
		(start 367.565178 -75.514708)
		(end 367.945162 -75.894692)
		(width 0.089408)
		(layer "In9.Cu")
		(net "FM_PVDDQ_ABC_EN")
	)
	(segment
		(start 368.859308 -63.964058)
		(end 368.70132 -63.964058)
		(width 0.089408)
		(layer "In9.Cu")
		(net "FM_PVDDQ_ABC_EN")
	)
	(segment
		(start 372.110762 -63.183008)
		(end 370.954046 -63.183008)
		(width 0.089408)
		(layer "In9.Cu")
		(net "FM_PVDDQ_ABC_EN")
	)
	(segment
		(start 367.565178 -74.13371)
		(end 367.565178 -75.514708)
		(width 0.089408)
		(layer "In9.Cu")
		(net "FM_PVDDQ_ABC_EN")
	)
	(segment
		(start 370.954046 -63.183008)
		(end 370.172742 -63.964312)
		(width 0.089408)
		(layer "In9.Cu")
		(net "FM_PVDDQ_ABC_EN")
	)
	(segment
		(start 367.103152 -66.976752)
		(end 366.771936 -67.307968)
		(width 0.089408)
		(layer "In9.Cu")
		(net "FM_PVDDQ_ABC_EN")
	)
	(segment
		(start 370.172742 -63.964312)
		(end 368.859562 -63.964312)
		(width 0.089408)
		(layer "In9.Cu")
		(net "FM_PVDDQ_ABC_EN")
	)
	(segment
		(start 368.70132 -63.964058)
		(end 367.103152 -65.562226)
		(width 0.089408)
		(layer "In9.Cu")
		(net "FM_PVDDQ_ABC_EN")
	)
	(segment
		(start 366.99063 -73.868534)
		(end 367.300002 -73.868534)
		(width 0.089408)
		(layer "In9.Cu")
		(net "FM_PVDDQ_ABC_EN")
	)
	(segment
		(start 364.59414 -55.942738)
		(end 360.680254 -52.028852)
		(width 0.089408)
		(layer "In11.Cu")
		(net "FM_PVDDQ_ABC_EN")
	)
	(segment
		(start 359.297478 -52.028852)
		(end 357.037894 -49.769268)
		(width 0.089408)
		(layer "In11.Cu")
		(net "FM_PVDDQ_ABC_EN")
	)
	(segment
		(start 372.32336 -62.8269)
		(end 372.066312 -62.569852)
		(width 0.089408)
		(layer "In11.Cu")
		(net "FM_PVDDQ_ABC_EN")
	)
	(segment
		(start 323.228462 -44.359068)
		(end 320.358516 -44.359068)
		(width 0.089408)
		(layer "In11.Cu")
		(net "FM_PVDDQ_ABC_EN")
	)
	(segment
		(start 323.96938 -27.810206)
		(end 323.96938 -25.24506)
		(width 0.089408)
		(layer "In11.Cu")
		(net "FM_PVDDQ_ABC_EN")
	)
	(segment
		(start 320.358516 -44.359068)
		(end 319.053972 -43.054524)
		(width 0.089408)
		(layer "In11.Cu")
		(net "FM_PVDDQ_ABC_EN")
	)
	(segment
		(start 328.638662 -49.769268)
		(end 323.228462 -44.359068)
		(width 0.089408)
		(layer "In11.Cu")
		(net "FM_PVDDQ_ABC_EN")
	)
	(segment
		(start 372.066312 -61.698378)
		(end 366.310164 -55.942738)
		(width 0.089408)
		(layer "In11.Cu")
		(net "FM_PVDDQ_ABC_EN")
	)
	(segment
		(start 360.680254 -52.028852)
		(end 359.297478 -52.028852)
		(width 0.089408)
		(layer "In11.Cu")
		(net "FM_PVDDQ_ABC_EN")
	)
	(segment
		(start 373.127016 -62.556898)
		(end 372.857014 -62.8269)
		(width 0.089408)
		(layer "In11.Cu")
		(net "FM_PVDDQ_ABC_EN")
	)
	(segment
		(start 319.053972 -43.054524)
		(end 319.053972 -36.337494)
		(width 0.089408)
		(layer "In11.Cu")
		(net "FM_PVDDQ_ABC_EN")
	)
	(segment
		(start 366.310164 -55.942738)
		(end 364.59414 -55.942738)
		(width 0.089408)
		(layer "In11.Cu")
		(net "FM_PVDDQ_ABC_EN")
	)
	(segment
		(start 319.053972 -36.337494)
		(end 320.502788 -34.888678)
		(width 0.089408)
		(layer "In11.Cu")
		(net "FM_PVDDQ_ABC_EN")
	)
	(segment
		(start 325.153782 -28.994608)
		(end 323.96938 -27.810206)
		(width 0.089408)
		(layer "In11.Cu")
		(net "FM_PVDDQ_ABC_EN")
	)
	(segment
		(start 321.574922 -34.888678)
		(end 325.153782 -31.309818)
		(width 0.089408)
		(layer "In11.Cu")
		(net "FM_PVDDQ_ABC_EN")
	)
	(segment
		(start 372.857014 -62.8269)
		(end 372.32336 -62.8269)
		(width 0.089408)
		(layer "In11.Cu")
		(net "FM_PVDDQ_ABC_EN")
	)
	(segment
		(start 320.502788 -34.888678)
		(end 321.574922 -34.888678)
		(width 0.089408)
		(layer "In11.Cu")
		(net "FM_PVDDQ_ABC_EN")
	)
	(segment
		(start 372.066312 -62.569852)
		(end 372.066312 -61.698378)
		(width 0.089408)
		(layer "In11.Cu")
		(net "FM_PVDDQ_ABC_EN")
	)
	(segment
		(start 325.153782 -31.309818)
		(end 325.153782 -28.994608)
		(width 0.089408)
		(layer "In11.Cu")
		(net "FM_PVDDQ_ABC_EN")
	)
	(segment
		(start 357.037894 -49.769268)
		(end 328.638662 -49.769268)
		(width 0.089408)
		(layer "In11.Cu")
		(net "FM_PVDDQ_ABC_EN")
	)
	(segment
		(start 366.345216 -78.294738)
		(end 366.745012 -77.894942)
		(width 0.1016)
		(layer "F.Cu")
		(net "FM_PVCCIN_PVCCSA_CPU1_EN_LVC1")
	)
	(via
		(at 12.4714 -90.043)
		(size 0.508)
		(drill 0.254)
		(layers "F.Cu" "B.Cu")
		(net "FM_PVCCIN_PVCCSA_CPU1_EN_LVC1")
	)
	(via
		(at 366.345216 -78.294738)
		(size 0.4572)
		(drill 0.2032)
		(layers "F.Cu" "B.Cu")
		(net "FM_PVCCIN_PVCCSA_CPU1_EN_LVC1")
	)
	(via
		(at 330.0603 -123.1773)
		(size 0.508)
		(drill 0.254)
		(layers "F.Cu" "B.Cu")
		(net "FM_PVCCIN_PVCCSA_CPU1_EN_LVC1")
	)
	(segment
		(start 12.9286 -89.5858)
		(end 13.462 -89.5858)
		(width 0.10795)
		(layer "B.Cu")
		(net "FM_PVCCIN_PVCCSA_CPU1_EN_LVC1")
	)
	(segment
		(start 13.462 -89.5858)
		(end 13.843 -89.2048)
		(width 0.10795)
		(layer "B.Cu")
		(net "FM_PVCCIN_PVCCSA_CPU1_EN_LVC1")
	)
	(segment
		(start 13.843 -89.2048)
		(end 13.843 -89.154)
		(width 0.10795)
		(layer "B.Cu")
		(net "FM_PVCCIN_PVCCSA_CPU1_EN_LVC1")
	)
	(segment
		(start 12.4714 -90.043)
		(end 12.9286 -89.5858)
		(width 0.10795)
		(layer "B.Cu")
		(net "FM_PVCCIN_PVCCSA_CPU1_EN_LVC1")
	)
	(segment
		(start 356.922324 -71.121524)
		(end 358.151684 -72.350884)
		(width 0.089408)
		(layer "In4.Cu")
		(net "FM_PVCCIN_PVCCSA_CPU1_EN_LVC1")
	)
	(segment
		(start 328.638662 -92.815664)
		(end 334.543908 -86.910418)
		(width 0.089408)
		(layer "In4.Cu")
		(net "FM_PVCCIN_PVCCSA_CPU1_EN_LVC1")
	)
	(segment
		(start 354.386896 -71.699374)
		(end 354.964746 -71.121524)
		(width 0.089408)
		(layer "In4.Cu")
		(net "FM_PVCCIN_PVCCSA_CPU1_EN_LVC1")
	)
	(segment
		(start 345.834208 -72.596248)
		(end 345.834208 -72.30999)
		(width 0.089408)
		(layer "In4.Cu")
		(net "FM_PVCCIN_PVCCSA_CPU1_EN_LVC1")
	)
	(segment
		(start 362.791756 -72.350884)
		(end 365.326422 -74.88555)
		(width 0.089408)
		(layer "In4.Cu")
		(net "FM_PVCCIN_PVCCSA_CPU1_EN_LVC1")
	)
	(segment
		(start 338.18957 -76.013564)
		(end 338.901532 -75.301602)
		(width 0.089408)
		(layer "In4.Cu")
		(net "FM_PVCCIN_PVCCSA_CPU1_EN_LVC1")
	)
	(segment
		(start 365.326422 -74.88555)
		(end 365.326422 -77.275944)
		(width 0.089408)
		(layer "In4.Cu")
		(net "FM_PVCCIN_PVCCSA_CPU1_EN_LVC1")
	)
	(segment
		(start 343.56548 -73.303638)
		(end 345.126818 -73.303638)
		(width 0.089408)
		(layer "In4.Cu")
		(net "FM_PVCCIN_PVCCSA_CPU1_EN_LVC1")
	)
	(segment
		(start 334.543908 -86.910418)
		(end 334.543908 -85.216238)
		(width 0.089408)
		(layer "In4.Cu")
		(net "FM_PVCCIN_PVCCSA_CPU1_EN_LVC1")
	)
	(segment
		(start 342.615012 -74.254106)
		(end 343.56548 -73.303638)
		(width 0.089408)
		(layer "In4.Cu")
		(net "FM_PVCCIN_PVCCSA_CPU1_EN_LVC1")
	)
	(segment
		(start 340.420198 -75.301602)
		(end 341.467694 -74.254106)
		(width 0.089408)
		(layer "In4.Cu")
		(net "FM_PVCCIN_PVCCSA_CPU1_EN_LVC1")
	)
	(segment
		(start 338.901532 -75.301602)
		(end 340.420198 -75.301602)
		(width 0.089408)
		(layer "In4.Cu")
		(net "FM_PVCCIN_PVCCSA_CPU1_EN_LVC1")
	)
	(segment
		(start 337.647534 -82.112612)
		(end 337.647534 -78.692502)
		(width 0.089408)
		(layer "In4.Cu")
		(net "FM_PVCCIN_PVCCSA_CPU1_EN_LVC1")
	)
	(segment
		(start 330.0603 -123.1773)
		(end 329.529948 -122.646948)
		(width 0.089408)
		(layer "In4.Cu")
		(net "FM_PVCCIN_PVCCSA_CPU1_EN_LVC1")
	)
	(segment
		(start 352.034094 -71.699374)
		(end 354.386896 -71.699374)
		(width 0.089408)
		(layer "In4.Cu")
		(net "FM_PVCCIN_PVCCSA_CPU1_EN_LVC1")
	)
	(segment
		(start 338.18957 -78.150466)
		(end 338.18957 -76.013564)
		(width 0.089408)
		(layer "In4.Cu")
		(net "FM_PVCCIN_PVCCSA_CPU1_EN_LVC1")
	)
	(segment
		(start 328.638662 -111.479076)
		(end 328.638662 -92.815664)
		(width 0.089408)
		(layer "In4.Cu")
		(net "FM_PVCCIN_PVCCSA_CPU1_EN_LVC1")
	)
	(segment
		(start 329.529948 -122.646948)
		(end 329.529948 -112.370362)
		(width 0.089408)
		(layer "In4.Cu")
		(net "FM_PVCCIN_PVCCSA_CPU1_EN_LVC1")
	)
	(segment
		(start 329.529948 -112.370362)
		(end 328.638662 -111.479076)
		(width 0.089408)
		(layer "In4.Cu")
		(net "FM_PVCCIN_PVCCSA_CPU1_EN_LVC1")
	)
	(segment
		(start 358.151684 -72.350884)
		(end 362.791756 -72.350884)
		(width 0.089408)
		(layer "In4.Cu")
		(net "FM_PVCCIN_PVCCSA_CPU1_EN_LVC1")
	)
	(segment
		(start 354.964746 -71.121524)
		(end 356.922324 -71.121524)
		(width 0.089408)
		(layer "In4.Cu")
		(net "FM_PVCCIN_PVCCSA_CPU1_EN_LVC1")
	)
	(segment
		(start 346.64015 -71.504048)
		(end 351.838768 -71.504048)
		(width 0.089408)
		(layer "In4.Cu")
		(net "FM_PVCCIN_PVCCSA_CPU1_EN_LVC1")
	)
	(segment
		(start 345.834208 -72.30999)
		(end 346.64015 -71.504048)
		(width 0.089408)
		(layer "In4.Cu")
		(net "FM_PVCCIN_PVCCSA_CPU1_EN_LVC1")
	)
	(segment
		(start 341.467694 -74.254106)
		(end 342.615012 -74.254106)
		(width 0.089408)
		(layer "In4.Cu")
		(net "FM_PVCCIN_PVCCSA_CPU1_EN_LVC1")
	)
	(segment
		(start 334.543908 -85.216238)
		(end 337.647534 -82.112612)
		(width 0.089408)
		(layer "In4.Cu")
		(net "FM_PVCCIN_PVCCSA_CPU1_EN_LVC1")
	)
	(segment
		(start 345.126818 -73.303638)
		(end 345.834208 -72.596248)
		(width 0.089408)
		(layer "In4.Cu")
		(net "FM_PVCCIN_PVCCSA_CPU1_EN_LVC1")
	)
	(segment
		(start 337.647534 -78.692502)
		(end 338.18957 -78.150466)
		(width 0.089408)
		(layer "In4.Cu")
		(net "FM_PVCCIN_PVCCSA_CPU1_EN_LVC1")
	)
	(segment
		(start 365.326422 -77.275944)
		(end 366.345216 -78.294738)
		(width 0.089408)
		(layer "In4.Cu")
		(net "FM_PVCCIN_PVCCSA_CPU1_EN_LVC1")
	)
	(segment
		(start 351.838768 -71.504048)
		(end 352.034094 -71.699374)
		(width 0.089408)
		(layer "In4.Cu")
		(net "FM_PVCCIN_PVCCSA_CPU1_EN_LVC1")
	)
	(segment
		(start 321.708526 -125.209808)
		(end 321.174364 -125.74397)
		(width 0.089408)
		(layer "In9.Cu")
		(net "FM_PVCCIN_PVCCSA_CPU1_EN_LVC1")
	)
	(segment
		(start 325.23811 -123.597924)
		(end 323.626226 -125.209808)
		(width 0.089408)
		(layer "In9.Cu")
		(net "FM_PVCCIN_PVCCSA_CPU1_EN_LVC1")
	)
	(segment
		(start 320.585592 -127.160782)
		(end 309.9435 -127.160782)
		(width 0.089408)
		(layer "In9.Cu")
		(net "FM_PVCCIN_PVCCSA_CPU1_EN_LVC1")
	)
	(segment
		(start 264.966958 -123.470162)
		(end 264.065512 -124.371608)
		(width 0.089408)
		(layer "In9.Cu")
		(net "FM_PVCCIN_PVCCSA_CPU1_EN_LVC1")
	)
	(segment
		(start 330.0603 -123.1773)
		(end 328.838814 -123.1773)
		(width 0.089408)
		(layer "In9.Cu")
		(net "FM_PVCCIN_PVCCSA_CPU1_EN_LVC1")
	)
	(segment
		(start 176.71415 -126.75235)
		(end 175.6918 -125.73)
		(width 0.089408)
		(layer "In9.Cu")
		(net "FM_PVCCIN_PVCCSA_CPU1_EN_LVC1")
	)
	(segment
		(start 264.065512 -124.371608)
		(end 244.185948 -124.371608)
		(width 0.089408)
		(layer "In9.Cu")
		(net "FM_PVCCIN_PVCCSA_CPU1_EN_LVC1")
	)
	(segment
		(start 321.174364 -125.74397)
		(end 321.174364 -126.57201)
		(width 0.089408)
		(layer "In9.Cu")
		(net "FM_PVCCIN_PVCCSA_CPU1_EN_LVC1")
	)
	(segment
		(start 24.132794 -114.983514)
		(end 18.233136 -109.083856)
		(width 0.089408)
		(layer "In9.Cu")
		(net "FM_PVCCIN_PVCCSA_CPU1_EN_LVC1")
	)
	(segment
		(start 328.838814 -123.1773)
		(end 328.41819 -123.597924)
		(width 0.089408)
		(layer "In9.Cu")
		(net "FM_PVCCIN_PVCCSA_CPU1_EN_LVC1")
	)
	(segment
		(start 161.468308 -127.703072)
		(end 152.49144 -127.703072)
		(width 0.089408)
		(layer "In9.Cu")
		(net "FM_PVCCIN_PVCCSA_CPU1_EN_LVC1")
	)
	(segment
		(start 11.784076 -93.074236)
		(end 11.784076 -90.540332)
		(width 0.089408)
		(layer "In9.Cu")
		(net "FM_PVCCIN_PVCCSA_CPU1_EN_LVC1")
	)
	(segment
		(start 33.814766 -122.72518)
		(end 26.0731 -114.983514)
		(width 0.089408)
		(layer "In9.Cu")
		(net "FM_PVCCIN_PVCCSA_CPU1_EN_LVC1")
	)
	(segment
		(start 222.608648 -125.574552)
		(end 191.788288 -125.574552)
		(width 0.089408)
		(layer "In9.Cu")
		(net "FM_PVCCIN_PVCCSA_CPU1_EN_LVC1")
	)
	(segment
		(start 175.446182 -124.341382)
		(end 174.998888 -124.341382)
		(width 0.089408)
		(layer "In9.Cu")
		(net "FM_PVCCIN_PVCCSA_CPU1_EN_LVC1")
	)
	(segment
		(start 147.513548 -122.72518)
		(end 33.814766 -122.72518)
		(width 0.089408)
		(layer "In9.Cu")
		(net "FM_PVCCIN_PVCCSA_CPU1_EN_LVC1")
	)
	(segment
		(start 175.6918 -125.73)
		(end 175.6918 -124.587)
		(width 0.089408)
		(layer "In9.Cu")
		(net "FM_PVCCIN_PVCCSA_CPU1_EN_LVC1")
	)
	(segment
		(start 180.70068 -126.112016)
		(end 180.3654 -126.447296)
		(width 0.089408)
		(layer "In9.Cu")
		(net "FM_PVCCIN_PVCCSA_CPU1_EN_LVC1")
	)
	(segment
		(start 191.250824 -126.112016)
		(end 180.70068 -126.112016)
		(width 0.089408)
		(layer "In9.Cu")
		(net "FM_PVCCIN_PVCCSA_CPU1_EN_LVC1")
	)
	(segment
		(start 244.185948 -124.371608)
		(end 243.64188 -123.82754)
		(width 0.089408)
		(layer "In9.Cu")
		(net "FM_PVCCIN_PVCCSA_CPU1_EN_LVC1")
	)
	(segment
		(start 163.262564 -125.908816)
		(end 161.468308 -127.703072)
		(width 0.089408)
		(layer "In9.Cu")
		(net "FM_PVCCIN_PVCCSA_CPU1_EN_LVC1")
	)
	(segment
		(start 12.735052 -94.025212)
		(end 11.784076 -93.074236)
		(width 0.089408)
		(layer "In9.Cu")
		(net "FM_PVCCIN_PVCCSA_CPU1_EN_LVC1")
	)
	(segment
		(start 306.25288 -123.470162)
		(end 264.966958 -123.470162)
		(width 0.089408)
		(layer "In9.Cu")
		(net "FM_PVCCIN_PVCCSA_CPU1_EN_LVC1")
	)
	(segment
		(start 243.64188 -123.82754)
		(end 224.35566 -123.82754)
		(width 0.089408)
		(layer "In9.Cu")
		(net "FM_PVCCIN_PVCCSA_CPU1_EN_LVC1")
	)
	(segment
		(start 165.758114 -126.6952)
		(end 164.97173 -125.908816)
		(width 0.089408)
		(layer "In9.Cu")
		(net "FM_PVCCIN_PVCCSA_CPU1_EN_LVC1")
	)
	(segment
		(start 17.4371 -101.376734)
		(end 15.847568 -101.376734)
		(width 0.089408)
		(layer "In9.Cu")
		(net "FM_PVCCIN_PVCCSA_CPU1_EN_LVC1")
	)
	(segment
		(start 177.52695 -126.75235)
		(end 176.71415 -126.75235)
		(width 0.089408)
		(layer "In9.Cu")
		(net "FM_PVCCIN_PVCCSA_CPU1_EN_LVC1")
	)
	(segment
		(start 191.788288 -125.574552)
		(end 191.250824 -126.112016)
		(width 0.089408)
		(layer "In9.Cu")
		(net "FM_PVCCIN_PVCCSA_CPU1_EN_LVC1")
	)
	(segment
		(start 12.281408 -90.043)
		(end 12.4714 -90.043)
		(width 0.089408)
		(layer "In9.Cu")
		(net "FM_PVCCIN_PVCCSA_CPU1_EN_LVC1")
	)
	(segment
		(start 11.784076 -90.540332)
		(end 12.281408 -90.043)
		(width 0.089408)
		(layer "In9.Cu")
		(net "FM_PVCCIN_PVCCSA_CPU1_EN_LVC1")
	)
	(segment
		(start 152.49144 -127.703072)
		(end 147.513548 -122.72518)
		(width 0.089408)
		(layer "In9.Cu")
		(net "FM_PVCCIN_PVCCSA_CPU1_EN_LVC1")
	)
	(segment
		(start 224.35566 -123.82754)
		(end 222.608648 -125.574552)
		(width 0.089408)
		(layer "In9.Cu")
		(net "FM_PVCCIN_PVCCSA_CPU1_EN_LVC1")
	)
	(segment
		(start 177.832004 -126.447296)
		(end 177.52695 -126.75235)
		(width 0.089408)
		(layer "In9.Cu")
		(net "FM_PVCCIN_PVCCSA_CPU1_EN_LVC1")
	)
	(segment
		(start 174.998888 -124.341382)
		(end 172.64507 -126.6952)
		(width 0.089408)
		(layer "In9.Cu")
		(net "FM_PVCCIN_PVCCSA_CPU1_EN_LVC1")
	)
	(segment
		(start 15.847568 -101.376734)
		(end 12.735052 -98.264218)
		(width 0.089408)
		(layer "In9.Cu")
		(net "FM_PVCCIN_PVCCSA_CPU1_EN_LVC1")
	)
	(segment
		(start 18.233136 -102.17277)
		(end 17.4371 -101.376734)
		(width 0.089408)
		(layer "In9.Cu")
		(net "FM_PVCCIN_PVCCSA_CPU1_EN_LVC1")
	)
	(segment
		(start 180.3654 -126.447296)
		(end 177.832004 -126.447296)
		(width 0.089408)
		(layer "In9.Cu")
		(net "FM_PVCCIN_PVCCSA_CPU1_EN_LVC1")
	)
	(segment
		(start 18.233136 -109.083856)
		(end 18.233136 -102.17277)
		(width 0.089408)
		(layer "In9.Cu")
		(net "FM_PVCCIN_PVCCSA_CPU1_EN_LVC1")
	)
	(segment
		(start 321.174364 -126.57201)
		(end 320.585592 -127.160782)
		(width 0.089408)
		(layer "In9.Cu")
		(net "FM_PVCCIN_PVCCSA_CPU1_EN_LVC1")
	)
	(segment
		(start 309.9435 -127.160782)
		(end 306.25288 -123.470162)
		(width 0.089408)
		(layer "In9.Cu")
		(net "FM_PVCCIN_PVCCSA_CPU1_EN_LVC1")
	)
	(segment
		(start 175.6918 -124.587)
		(end 175.446182 -124.341382)
		(width 0.089408)
		(layer "In9.Cu")
		(net "FM_PVCCIN_PVCCSA_CPU1_EN_LVC1")
	)
	(segment
		(start 328.41819 -123.597924)
		(end 325.23811 -123.597924)
		(width 0.089408)
		(layer "In9.Cu")
		(net "FM_PVCCIN_PVCCSA_CPU1_EN_LVC1")
	)
	(segment
		(start 12.735052 -98.264218)
		(end 12.735052 -94.025212)
		(width 0.089408)
		(layer "In9.Cu")
		(net "FM_PVCCIN_PVCCSA_CPU1_EN_LVC1")
	)
	(segment
		(start 323.626226 -125.209808)
		(end 321.708526 -125.209808)
		(width 0.089408)
		(layer "In9.Cu")
		(net "FM_PVCCIN_PVCCSA_CPU1_EN_LVC1")
	)
	(segment
		(start 172.64507 -126.6952)
		(end 165.758114 -126.6952)
		(width 0.089408)
		(layer "In9.Cu")
		(net "FM_PVCCIN_PVCCSA_CPU1_EN_LVC1")
	)
	(segment
		(start 26.0731 -114.983514)
		(end 24.132794 -114.983514)
		(width 0.089408)
		(layer "In9.Cu")
		(net "FM_PVCCIN_PVCCSA_CPU1_EN_LVC1")
	)
	(segment
		(start 164.97173 -125.908816)
		(end 163.262564 -125.908816)
		(width 0.089408)
		(layer "In9.Cu")
		(net "FM_PVCCIN_PVCCSA_CPU1_EN_LVC1")
	)
	(segment
		(start 371.1956 -67.2338)
		(end 371.1956 -67.945508)
		(width 0.1016)
		(layer "F.Cu")
		(net "FM_PVCCIN_PVCCSA_CPU0_EN_LVC1")
	)
	(segment
		(start 371.1956 -67.945508)
		(end 371.545104 -68.295012)
		(width 0.1016)
		(layer "F.Cu")
		(net "FM_PVCCIN_PVCCSA_CPU0_EN_LVC1")
	)
	(via
		(at 371.1956 -67.2338)
		(size 0.4572)
		(drill 0.2032)
		(layers "F.Cu" "B.Cu")
		(net "FM_PVCCIN_PVCCSA_CPU0_EN_LVC1")
	)
	(via
		(at 376.798078 -62.120272)
		(size 0.508)
		(drill 0.254)
		(layers "F.Cu" "B.Cu")
		(net "FM_PVCCIN_PVCCSA_CPU0_EN_LVC1")
	)
	(via
		(at 322.53174 -39.217092)
		(size 0.508)
		(drill 0.254)
		(layers "F.Cu" "B.Cu")
		(net "FM_PVCCIN_PVCCSA_CPU0_EN_LVC1")
	)
	(via
		(at 192.2272 -25.908)
		(size 0.508)
		(drill 0.254)
		(layers "F.Cu" "B.Cu")
		(net "FM_PVCCIN_PVCCSA_CPU0_EN_LVC1")
	)
	(via
		(at 179.2732 -76.6064)
		(size 0.508)
		(drill 0.254)
		(layers "F.Cu" "B.Cu")
		(net "FM_PVCCIN_PVCCSA_CPU0_EN_LVC1")
	)
	(segment
		(start 179.52212 -76.6064)
		(end 179.92852 -76.2)
		(width 0.10795)
		(layer "B.Cu")
		(net "FM_PVCCIN_PVCCSA_CPU0_EN_LVC1")
	)
	(segment
		(start 179.2732 -76.6064)
		(end 179.52212 -76.6064)
		(width 0.10795)
		(layer "B.Cu")
		(net "FM_PVCCIN_PVCCSA_CPU0_EN_LVC1")
	)
	(segment
		(start 179.92852 -76.2)
		(end 180.086 -76.2)
		(width 0.10795)
		(layer "B.Cu")
		(net "FM_PVCCIN_PVCCSA_CPU0_EN_LVC1")
	)
	(segment
		(start 180.086 -76.2)
		(end 180.1114 -76.2254)
		(width 0.10795)
		(layer "B.Cu")
		(net "FM_PVCCIN_PVCCSA_CPU0_EN_LVC1")
	)
	(segment
		(start 261.708646 -28.661868)
		(end 260.503924 -27.457146)
		(width 0.089408)
		(layer "In9.Cu")
		(net "FM_PVCCIN_PVCCSA_CPU0_EN_LVC1")
	)
	(segment
		(start 321.319144 -40.046656)
		(end 313.697112 -40.046656)
		(width 0.089408)
		(layer "In9.Cu")
		(net "FM_PVCCIN_PVCCSA_CPU0_EN_LVC1")
	)
	(segment
		(start 374.456198 -64.580008)
		(end 374.138698 -64.580008)
		(width 0.089408)
		(layer "In9.Cu")
		(net "FM_PVCCIN_PVCCSA_CPU0_EN_LVC1")
	)
	(segment
		(start 374.928384 -63.60922)
		(end 374.928384 -64.107822)
		(width 0.089408)
		(layer "In9.Cu")
		(net "FM_PVCCIN_PVCCSA_CPU0_EN_LVC1")
	)
	(segment
		(start 246.269002 -27.457146)
		(end 244.71884 -25.906984)
		(width 0.089408)
		(layer "In9.Cu")
		(net "FM_PVCCIN_PVCCSA_CPU0_EN_LVC1")
	)
	(segment
		(start 263.196578 -28.661868)
		(end 261.708646 -28.661868)
		(width 0.089408)
		(layer "In9.Cu")
		(net "FM_PVCCIN_PVCCSA_CPU0_EN_LVC1")
	)
	(segment
		(start 265.422126 -30.887416)
		(end 263.196578 -28.661868)
		(width 0.089408)
		(layer "In9.Cu")
		(net "FM_PVCCIN_PVCCSA_CPU0_EN_LVC1")
	)
	(segment
		(start 192.722754 -25.908)
		(end 192.2272 -25.908)
		(width 0.089408)
		(layer "In9.Cu")
		(net "FM_PVCCIN_PVCCSA_CPU0_EN_LVC1")
	)
	(segment
		(start 304.537872 -30.887416)
		(end 265.422126 -30.887416)
		(width 0.089408)
		(layer "In9.Cu")
		(net "FM_PVCCIN_PVCCSA_CPU0_EN_LVC1")
	)
	(segment
		(start 322.53174 -39.217092)
		(end 322.148708 -39.217092)
		(width 0.089408)
		(layer "In9.Cu")
		(net "FM_PVCCIN_PVCCSA_CPU0_EN_LVC1")
	)
	(segment
		(start 244.71884 -25.906984)
		(end 243.762784 -25.906984)
		(width 0.089408)
		(layer "In9.Cu")
		(net "FM_PVCCIN_PVCCSA_CPU0_EN_LVC1")
	)
	(segment
		(start 313.697112 -40.046656)
		(end 304.537872 -30.887416)
		(width 0.089408)
		(layer "In9.Cu")
		(net "FM_PVCCIN_PVCCSA_CPU0_EN_LVC1")
	)
	(segment
		(start 260.503924 -27.457146)
		(end 246.269002 -27.457146)
		(width 0.089408)
		(layer "In9.Cu")
		(net "FM_PVCCIN_PVCCSA_CPU0_EN_LVC1")
	)
	(segment
		(start 243.762784 -25.906984)
		(end 243.358416 -25.502616)
		(width 0.089408)
		(layer "In9.Cu")
		(net "FM_PVCCIN_PVCCSA_CPU0_EN_LVC1")
	)
	(segment
		(start 376.417078 -62.120272)
		(end 375.031 -63.50635)
		(width 0.089408)
		(layer "In9.Cu")
		(net "FM_PVCCIN_PVCCSA_CPU0_EN_LVC1")
	)
	(segment
		(start 373.86641 -64.852296)
		(end 373.333772 -64.852296)
		(width 0.089408)
		(layer "In9.Cu")
		(net "FM_PVCCIN_PVCCSA_CPU0_EN_LVC1")
	)
	(segment
		(start 372.796816 -66.683128)
		(end 371.746272 -66.683128)
		(width 0.089408)
		(layer "In9.Cu")
		(net "FM_PVCCIN_PVCCSA_CPU0_EN_LVC1")
	)
	(segment
		(start 374.928384 -64.107822)
		(end 374.456198 -64.580008)
		(width 0.089408)
		(layer "In9.Cu")
		(net "FM_PVCCIN_PVCCSA_CPU0_EN_LVC1")
	)
	(segment
		(start 374.138698 -64.580008)
		(end 373.86641 -64.852296)
		(width 0.089408)
		(layer "In9.Cu")
		(net "FM_PVCCIN_PVCCSA_CPU0_EN_LVC1")
	)
	(segment
		(start 373.12092 -66.359024)
		(end 372.796816 -66.683128)
		(width 0.089408)
		(layer "In9.Cu")
		(net "FM_PVCCIN_PVCCSA_CPU0_EN_LVC1")
	)
	(segment
		(start 371.746272 -66.683128)
		(end 371.1956 -67.2338)
		(width 0.089408)
		(layer "In9.Cu")
		(net "FM_PVCCIN_PVCCSA_CPU0_EN_LVC1")
	)
	(segment
		(start 373.333772 -64.852296)
		(end 373.12092 -65.065148)
		(width 0.089408)
		(layer "In9.Cu")
		(net "FM_PVCCIN_PVCCSA_CPU0_EN_LVC1")
	)
	(segment
		(start 376.798078 -62.120272)
		(end 376.417078 -62.120272)
		(width 0.089408)
		(layer "In9.Cu")
		(net "FM_PVCCIN_PVCCSA_CPU0_EN_LVC1")
	)
	(segment
		(start 375.031 -63.50635)
		(end 375.031 -63.506604)
		(width 0.089408)
		(layer "In9.Cu")
		(net "FM_PVCCIN_PVCCSA_CPU0_EN_LVC1")
	)
	(segment
		(start 193.128138 -25.502616)
		(end 192.722754 -25.908)
		(width 0.089408)
		(layer "In9.Cu")
		(net "FM_PVCCIN_PVCCSA_CPU0_EN_LVC1")
	)
	(segment
		(start 243.358416 -25.502616)
		(end 193.128138 -25.502616)
		(width 0.089408)
		(layer "In9.Cu")
		(net "FM_PVCCIN_PVCCSA_CPU0_EN_LVC1")
	)
	(segment
		(start 373.12092 -65.065148)
		(end 373.12092 -66.359024)
		(width 0.089408)
		(layer "In9.Cu")
		(net "FM_PVCCIN_PVCCSA_CPU0_EN_LVC1")
	)
	(segment
		(start 375.031 -63.506604)
		(end 374.928384 -63.60922)
		(width 0.089408)
		(layer "In9.Cu")
		(net "FM_PVCCIN_PVCCSA_CPU0_EN_LVC1")
	)
	(segment
		(start 322.148708 -39.217092)
		(end 321.319144 -40.046656)
		(width 0.089408)
		(layer "In9.Cu")
		(net "FM_PVCCIN_PVCCSA_CPU0_EN_LVC1")
	)
	(segment
		(start 373.1768 -58.161682)
		(end 372.06809 -57.052972)
		(width 0.089408)
		(layer "In11.Cu")
		(net "FM_PVCCIN_PVCCSA_CPU0_EN_LVC1")
	)
	(segment
		(start 333.880206 -45.908468)
		(end 332.35519 -44.383452)
		(width 0.089408)
		(layer "In11.Cu")
		(net "FM_PVCCIN_PVCCSA_CPU0_EN_LVC1")
	)
	(segment
		(start 179.8574 -76.27112)
		(end 179.52212 -76.6064)
		(width 0.089408)
		(layer "In11.Cu")
		(net "FM_PVCCIN_PVCCSA_CPU0_EN_LVC1")
	)
	(segment
		(start 186.051444 -59.50331)
		(end 186.051444 -62.102238)
		(width 0.089408)
		(layer "In11.Cu")
		(net "FM_PVCCIN_PVCCSA_CPU0_EN_LVC1")
	)
	(segment
		(start 179.8574 -73.9902)
		(end 179.8574 -76.27112)
		(width 0.089408)
		(layer "In11.Cu")
		(net "FM_PVCCIN_PVCCSA_CPU0_EN_LVC1")
	)
	(segment
		(start 196.709792 -49.162208)
		(end 195.9102 -49.9618)
		(width 0.089408)
		(layer "In11.Cu")
		(net "FM_PVCCIN_PVCCSA_CPU0_EN_LVC1")
	)
	(segment
		(start 330.12634 -44.383452)
		(end 328.075544 -42.332656)
		(width 0.089408)
		(layer "In11.Cu")
		(net "FM_PVCCIN_PVCCSA_CPU0_EN_LVC1")
	)
	(segment
		(start 366.358932 -52.831746)
		(end 365.793274 -52.266088)
		(width 0.089408)
		(layer "In11.Cu")
		(net "FM_PVCCIN_PVCCSA_CPU0_EN_LVC1")
	)
	(segment
		(start 179.52212 -76.6064)
		(end 179.2732 -76.6064)
		(width 0.089408)
		(layer "In11.Cu")
		(net "FM_PVCCIN_PVCCSA_CPU0_EN_LVC1")
	)
	(segment
		(start 373.1768 -58.457592)
		(end 373.1768 -58.161682)
		(width 0.089408)
		(layer "In11.Cu")
		(net "FM_PVCCIN_PVCCSA_CPU0_EN_LVC1")
	)
	(segment
		(start 365.793274 -52.266088)
		(end 364.795562 -52.266088)
		(width 0.089408)
		(layer "In11.Cu")
		(net "FM_PVCCIN_PVCCSA_CPU0_EN_LVC1")
	)
	(segment
		(start 358.2797 -45.908214)
		(end 358.279446 -45.908468)
		(width 0.089408)
		(layer "In11.Cu")
		(net "FM_PVCCIN_PVCCSA_CPU0_EN_LVC1")
	)
	(segment
		(start 196.6976 -46.4312)
		(end 196.6976 -47.6758)
		(width 0.089408)
		(layer "In11.Cu")
		(net "FM_PVCCIN_PVCCSA_CPU0_EN_LVC1")
	)
	(segment
		(start 323.266816 -39.643812)
		(end 322.95846 -39.643812)
		(width 0.089408)
		(layer "In11.Cu")
		(net "FM_PVCCIN_PVCCSA_CPU0_EN_LVC1")
	)
	(segment
		(start 181.0512 -65.53708)
		(end 181.0512 -72.7964)
		(width 0.089408)
		(layer "In11.Cu")
		(net "FM_PVCCIN_PVCCSA_CPU0_EN_LVC1")
	)
	(segment
		(start 368.629692 -52.831746)
		(end 366.358932 -52.831746)
		(width 0.089408)
		(layer "In11.Cu")
		(net "FM_PVCCIN_PVCCSA_CPU0_EN_LVC1")
	)
	(segment
		(start 189.264544 -49.9618)
		(end 185.483754 -53.74259)
		(width 0.089408)
		(layer "In11.Cu")
		(net "FM_PVCCIN_PVCCSA_CPU0_EN_LVC1")
	)
	(segment
		(start 181.0512 -72.7964)
		(end 179.8574 -73.9902)
		(width 0.089408)
		(layer "In11.Cu")
		(net "FM_PVCCIN_PVCCSA_CPU0_EN_LVC1")
	)
	(segment
		(start 196.709792 -47.687992)
		(end 196.709792 -49.162208)
		(width 0.089408)
		(layer "In11.Cu")
		(net "FM_PVCCIN_PVCCSA_CPU0_EN_LVC1")
	)
	(segment
		(start 192.2272 -27.7622)
		(end 193.968624 -29.503624)
		(width 0.089408)
		(layer "In11.Cu")
		(net "FM_PVCCIN_PVCCSA_CPU0_EN_LVC1")
	)
	(segment
		(start 325.95566 -42.332656)
		(end 323.266816 -39.643812)
		(width 0.089408)
		(layer "In11.Cu")
		(net "FM_PVCCIN_PVCCSA_CPU0_EN_LVC1")
	)
	(segment
		(start 185.441844 -62.711838)
		(end 185.441844 -64.036956)
		(width 0.089408)
		(layer "In11.Cu")
		(net "FM_PVCCIN_PVCCSA_CPU0_EN_LVC1")
	)
	(segment
		(start 328.075544 -42.332656)
		(end 325.95566 -42.332656)
		(width 0.089408)
		(layer "In11.Cu")
		(net "FM_PVCCIN_PVCCSA_CPU0_EN_LVC1")
	)
	(segment
		(start 376.798078 -60.71743)
		(end 375.540016 -59.459368)
		(width 0.089408)
		(layer "In11.Cu")
		(net "FM_PVCCIN_PVCCSA_CPU0_EN_LVC1")
	)
	(segment
		(start 372.06809 -57.052972)
		(end 372.06809 -56.270144)
		(width 0.089408)
		(layer "In11.Cu")
		(net "FM_PVCCIN_PVCCSA_CPU0_EN_LVC1")
	)
	(segment
		(start 332.35519 -44.383452)
		(end 330.12634 -44.383452)
		(width 0.089408)
		(layer "In11.Cu")
		(net "FM_PVCCIN_PVCCSA_CPU0_EN_LVC1")
	)
	(segment
		(start 181.4322 -65.15608)
		(end 181.0512 -65.53708)
		(width 0.089408)
		(layer "In11.Cu")
		(net "FM_PVCCIN_PVCCSA_CPU0_EN_LVC1")
	)
	(segment
		(start 185.483754 -58.93562)
		(end 186.051444 -59.50331)
		(width 0.089408)
		(layer "In11.Cu")
		(net "FM_PVCCIN_PVCCSA_CPU0_EN_LVC1")
	)
	(segment
		(start 192.2272 -25.908)
		(end 192.2272 -27.7622)
		(width 0.089408)
		(layer "In11.Cu")
		(net "FM_PVCCIN_PVCCSA_CPU0_EN_LVC1")
	)
	(segment
		(start 193.968624 -29.503624)
		(end 193.968624 -43.702224)
		(width 0.089408)
		(layer "In11.Cu")
		(net "FM_PVCCIN_PVCCSA_CPU0_EN_LVC1")
	)
	(segment
		(start 185.483754 -53.74259)
		(end 185.483754 -58.93562)
		(width 0.089408)
		(layer "In11.Cu")
		(net "FM_PVCCIN_PVCCSA_CPU0_EN_LVC1")
	)
	(segment
		(start 372.06809 -56.270144)
		(end 368.629692 -52.831746)
		(width 0.089408)
		(layer "In11.Cu")
		(net "FM_PVCCIN_PVCCSA_CPU0_EN_LVC1")
	)
	(segment
		(start 193.968624 -43.702224)
		(end 196.6976 -46.4312)
		(width 0.089408)
		(layer "In11.Cu")
		(net "FM_PVCCIN_PVCCSA_CPU0_EN_LVC1")
	)
	(segment
		(start 185.441844 -64.036956)
		(end 184.32272 -65.15608)
		(width 0.089408)
		(layer "In11.Cu")
		(net "FM_PVCCIN_PVCCSA_CPU0_EN_LVC1")
	)
	(segment
		(start 186.051444 -62.102238)
		(end 185.441844 -62.711838)
		(width 0.089408)
		(layer "In11.Cu")
		(net "FM_PVCCIN_PVCCSA_CPU0_EN_LVC1")
	)
	(segment
		(start 358.437688 -45.908214)
		(end 358.2797 -45.908214)
		(width 0.089408)
		(layer "In11.Cu")
		(net "FM_PVCCIN_PVCCSA_CPU0_EN_LVC1")
	)
	(segment
		(start 364.795562 -52.266088)
		(end 358.437688 -45.908214)
		(width 0.089408)
		(layer "In11.Cu")
		(net "FM_PVCCIN_PVCCSA_CPU0_EN_LVC1")
	)
	(segment
		(start 195.9102 -49.9618)
		(end 189.264544 -49.9618)
		(width 0.089408)
		(layer "In11.Cu")
		(net "FM_PVCCIN_PVCCSA_CPU0_EN_LVC1")
	)
	(segment
		(start 376.798078 -62.120272)
		(end 376.798078 -60.71743)
		(width 0.089408)
		(layer "In11.Cu")
		(net "FM_PVCCIN_PVCCSA_CPU0_EN_LVC1")
	)
	(segment
		(start 374.178576 -59.459368)
		(end 373.1768 -58.457592)
		(width 0.089408)
		(layer "In11.Cu")
		(net "FM_PVCCIN_PVCCSA_CPU0_EN_LVC1")
	)
	(segment
		(start 358.279446 -45.908468)
		(end 333.880206 -45.908468)
		(width 0.089408)
		(layer "In11.Cu")
		(net "FM_PVCCIN_PVCCSA_CPU0_EN_LVC1")
	)
	(segment
		(start 184.32272 -65.15608)
		(end 181.4322 -65.15608)
		(width 0.089408)
		(layer "In11.Cu")
		(net "FM_PVCCIN_PVCCSA_CPU0_EN_LVC1")
	)
	(segment
		(start 196.6976 -47.6758)
		(end 196.709792 -47.687992)
		(width 0.089408)
		(layer "In11.Cu")
		(net "FM_PVCCIN_PVCCSA_CPU0_EN_LVC1")
	)
	(segment
		(start 322.95846 -39.643812)
		(end 322.53174 -39.217092)
		(width 0.089408)
		(layer "In11.Cu")
		(net "FM_PVCCIN_PVCCSA_CPU0_EN_LVC1")
	)
	(segment
		(start 375.540016 -59.459368)
		(end 374.178576 -59.459368)
		(width 0.089408)
		(layer "In11.Cu")
		(net "FM_PVCCIN_PVCCSA_CPU0_EN_LVC1")
	)
	(segment
		(start 397.64335 -110.71352)
		(end 398.13865 -110.943644)
		(width 0.10795)
		(layer "F.Cu")
		(net "FM_BMC_ENABLE_N")
	)
	(via
		(at 394.91285 -75.013312)
		(size 0.508)
		(drill 0.254)
		(layers "F.Cu" "B.Cu")
		(net "FM_BMC_ENABLE_N")
	)
	(via
		(at 457.401168 -31.163514)
		(size 0.508)
		(drill 0.254)
		(layers "F.Cu" "B.Cu")
		(net "FM_BMC_ENABLE_N")
	)
	(via
		(at 414.05048 -106.397298)
		(size 0.508)
		(drill 0.254)
		(layers "F.Cu" "B.Cu")
		(net "FM_BMC_ENABLE_N")
	)
	(via
		(at 416.01898 -49.549558)
		(size 0.508)
		(drill 0.254)
		(layers "F.Cu" "B.Cu")
		(net "FM_BMC_ENABLE_N")
	)
	(via
		(at 415.034476 -50.864516)
		(size 0.6604)
		(drill 0.3302)
		(layers "F.Cu" "B.Cu")
		(net "FM_BMC_ENABLE_N")
	)
	(via
		(at 398.13865 -110.943644)
		(size 0.508)
		(drill 0.254)
		(layers "F.Cu" "B.Cu")
		(net "FM_BMC_ENABLE_N")
	)
	(segment
		(start 416.01898 -49.549558)
		(end 415.4932 -50.075338)
		(width 0.10795)
		(layer "B.Cu")
		(net "FM_BMC_ENABLE_N")
	)
	(segment
		(start 415.4932 -50.405792)
		(end 415.034476 -50.864516)
		(width 0.10795)
		(layer "B.Cu")
		(net "FM_BMC_ENABLE_N")
	)
	(segment
		(start 415.19729 -51.02733)
		(end 415.034476 -50.864516)
		(width 0.10795)
		(layer "B.Cu")
		(net "FM_BMC_ENABLE_N")
	)
	(segment
		(start 416.788854 -51.02733)
		(end 415.19729 -51.02733)
		(width 0.10795)
		(layer "B.Cu")
		(net "FM_BMC_ENABLE_N")
	)
	(segment
		(start 413.882586 -106.565192)
		(end 414.05048 -106.397298)
		(width 0.10795)
		(layer "B.Cu")
		(net "FM_BMC_ENABLE_N")
	)
	(segment
		(start 413.075882 -106.565192)
		(end 413.882586 -106.565192)
		(width 0.10795)
		(layer "B.Cu")
		(net "FM_BMC_ENABLE_N")
	)
	(segment
		(start 456.787758 -31.173674)
		(end 457.391008 -31.173674)
		(width 0.10795)
		(layer "B.Cu")
		(net "FM_BMC_ENABLE_N")
	)
	(segment
		(start 415.4932 -50.075338)
		(end 415.4932 -50.405792)
		(width 0.10795)
		(layer "B.Cu")
		(net "FM_BMC_ENABLE_N")
	)
	(segment
		(start 457.391008 -31.173674)
		(end 457.401168 -31.163514)
		(width 0.10795)
		(layer "B.Cu")
		(net "FM_BMC_ENABLE_N")
	)
	(segment
		(start 397.656304 -57.847992)
		(end 397.656304 -61.474096)
		(width 0.089408)
		(layer "In2.Cu")
		(net "FM_BMC_ENABLE_N")
	)
	(segment
		(start 405.622252 -48.24984)
		(end 405.1046 -48.767492)
		(width 0.089408)
		(layer "In2.Cu")
		(net "FM_BMC_ENABLE_N")
	)
	(segment
		(start 412.451042 -46.674278)
		(end 412.451042 -47.171102)
		(width 0.089408)
		(layer "In2.Cu")
		(net "FM_BMC_ENABLE_N")
	)
	(segment
		(start 416.01898 -49.549558)
		(end 416.01898 -49.242726)
		(width 0.089408)
		(layer "In2.Cu")
		(net "FM_BMC_ENABLE_N")
	)
	(segment
		(start 411.257242 -47.44593)
		(end 410.95295 -47.141638)
		(width 0.089408)
		(layer "In2.Cu")
		(net "FM_BMC_ENABLE_N")
	)
	(segment
		(start 394.907008 -75.013312)
		(end 394.91285 -75.013312)
		(width 0.089408)
		(layer "In2.Cu")
		(net "FM_BMC_ENABLE_N")
	)
	(segment
		(start 406.897586 -48.24984)
		(end 405.622252 -48.24984)
		(width 0.089408)
		(layer "In2.Cu")
		(net "FM_BMC_ENABLE_N")
	)
	(segment
		(start 416.01898 -49.242726)
		(end 414.601152 -47.824898)
		(width 0.089408)
		(layer "In2.Cu")
		(net "FM_BMC_ENABLE_N")
	)
	(segment
		(start 394.432536 -70.781672)
		(end 394.036296 -71.177912)
		(width 0.089408)
		(layer "In2.Cu")
		(net "FM_BMC_ENABLE_N")
	)
	(segment
		(start 414.601152 -47.824898)
		(end 414.601152 -46.861476)
		(width 0.089408)
		(layer "In2.Cu")
		(net "FM_BMC_ENABLE_N")
	)
	(segment
		(start 410.95295 -47.141638)
		(end 410.95295 -47.002954)
		(width 0.089408)
		(layer "In2.Cu")
		(net "FM_BMC_ENABLE_N")
	)
	(segment
		(start 394.036296 -74.1426)
		(end 394.907008 -75.013312)
		(width 0.089408)
		(layer "In2.Cu")
		(net "FM_BMC_ENABLE_N")
	)
	(segment
		(start 414.601152 -46.861476)
		(end 413.760412 -46.020736)
		(width 0.089408)
		(layer "In2.Cu")
		(net "FM_BMC_ENABLE_N")
	)
	(segment
		(start 407.797 -46.675548)
		(end 407.797 -47.350426)
		(width 0.089408)
		(layer "In2.Cu")
		(net "FM_BMC_ENABLE_N")
	)
	(segment
		(start 405.1046 -50.399696)
		(end 397.656304 -57.847992)
		(width 0.089408)
		(layer "In2.Cu")
		(net "FM_BMC_ENABLE_N")
	)
	(segment
		(start 407.941018 -46.53153)
		(end 407.797 -46.675548)
		(width 0.089408)
		(layer "In2.Cu")
		(net "FM_BMC_ENABLE_N")
	)
	(segment
		(start 407.797 -47.350426)
		(end 406.897586 -48.24984)
		(width 0.089408)
		(layer "In2.Cu")
		(net "FM_BMC_ENABLE_N")
	)
	(segment
		(start 405.1046 -48.767492)
		(end 405.1046 -50.399696)
		(width 0.089408)
		(layer "In2.Cu")
		(net "FM_BMC_ENABLE_N")
	)
	(segment
		(start 413.760412 -46.020736)
		(end 413.104584 -46.020736)
		(width 0.089408)
		(layer "In2.Cu")
		(net "FM_BMC_ENABLE_N")
	)
	(segment
		(start 413.104584 -46.020736)
		(end 412.451042 -46.674278)
		(width 0.089408)
		(layer "In2.Cu")
		(net "FM_BMC_ENABLE_N")
	)
	(segment
		(start 410.95295 -47.002954)
		(end 410.481526 -46.53153)
		(width 0.089408)
		(layer "In2.Cu")
		(net "FM_BMC_ENABLE_N")
	)
	(segment
		(start 412.176214 -47.44593)
		(end 411.257242 -47.44593)
		(width 0.089408)
		(layer "In2.Cu")
		(net "FM_BMC_ENABLE_N")
	)
	(segment
		(start 412.451042 -47.171102)
		(end 412.176214 -47.44593)
		(width 0.089408)
		(layer "In2.Cu")
		(net "FM_BMC_ENABLE_N")
	)
	(segment
		(start 410.481526 -46.53153)
		(end 407.941018 -46.53153)
		(width 0.089408)
		(layer "In2.Cu")
		(net "FM_BMC_ENABLE_N")
	)
	(segment
		(start 397.656304 -61.474096)
		(end 394.432536 -64.697864)
		(width 0.089408)
		(layer "In2.Cu")
		(net "FM_BMC_ENABLE_N")
	)
	(segment
		(start 394.432536 -64.697864)
		(end 394.432536 -70.781672)
		(width 0.089408)
		(layer "In2.Cu")
		(net "FM_BMC_ENABLE_N")
	)
	(segment
		(start 394.036296 -71.177912)
		(end 394.036296 -74.1426)
		(width 0.089408)
		(layer "In2.Cu")
		(net "FM_BMC_ENABLE_N")
	)
	(segment
		(start 428.49927 -43.866562)
		(end 426.820076 -45.545756)
		(width 0.089408)
		(layer "In9.Cu")
		(net "FM_BMC_ENABLE_N")
	)
	(segment
		(start 457.401168 -31.163514)
		(end 458.49159 -32.253936)
		(width 0.089408)
		(layer "In9.Cu")
		(net "FM_BMC_ENABLE_N")
	)
	(segment
		(start 450.750178 -39.02837)
		(end 450.750178 -40.277542)
		(width 0.089408)
		(layer "In9.Cu")
		(net "FM_BMC_ENABLE_N")
	)
	(segment
		(start 450.750178 -40.277542)
		(end 449.339208 -41.688512)
		(width 0.089408)
		(layer "In9.Cu")
		(net "FM_BMC_ENABLE_N")
	)
	(segment
		(start 418.748464 -48.79848)
		(end 418.74821 -48.798226)
		(width 0.089408)
		(layer "In9.Cu")
		(net "FM_BMC_ENABLE_N")
	)
	(segment
		(start 426.820076 -45.545756)
		(end 426.165264 -45.545756)
		(width 0.089408)
		(layer "In9.Cu")
		(net "FM_BMC_ENABLE_N")
	)
	(segment
		(start 457.163424 -34.29)
		(end 456.665076 -34.29)
		(width 0.089408)
		(layer "In9.Cu")
		(net "FM_BMC_ENABLE_N")
	)
	(segment
		(start 418.329618 -49.057814)
		(end 416.510724 -49.057814)
		(width 0.089408)
		(layer "In9.Cu")
		(net "FM_BMC_ENABLE_N")
	)
	(segment
		(start 414.004252 -106.397298)
		(end 413.703262 -106.096308)
		(width 0.089408)
		(layer "In9.Cu")
		(net "FM_BMC_ENABLE_N")
	)
	(segment
		(start 434.55844 -42.77868)
		(end 433.044092 -42.77868)
		(width 0.089408)
		(layer "In9.Cu")
		(net "FM_BMC_ENABLE_N")
	)
	(segment
		(start 416.510724 -49.057814)
		(end 416.01898 -49.549558)
		(width 0.089408)
		(layer "In9.Cu")
		(net "FM_BMC_ENABLE_N")
	)
	(segment
		(start 426.058076 -45.652944)
		(end 423.544492 -45.652944)
		(width 0.089408)
		(layer "In9.Cu")
		(net "FM_BMC_ENABLE_N")
	)
	(segment
		(start 435.648608 -41.688512)
		(end 434.55844 -42.77868)
		(width 0.089408)
		(layer "In9.Cu")
		(net "FM_BMC_ENABLE_N")
	)
	(segment
		(start 423.008552 -45.117004)
		(end 422.362884 -45.117004)
		(width 0.089408)
		(layer "In9.Cu")
		(net "FM_BMC_ENABLE_N")
	)
	(segment
		(start 452.557642 -38.610286)
		(end 451.168262 -38.610286)
		(width 0.089408)
		(layer "In9.Cu")
		(net "FM_BMC_ENABLE_N")
	)
	(segment
		(start 455.263504 -35.691572)
		(end 455.263504 -39.187628)
		(width 0.089408)
		(layer "In9.Cu")
		(net "FM_BMC_ENABLE_N")
	)
	(segment
		(start 419.234366 -48.798734)
		(end 418.906706 -48.798734)
		(width 0.089408)
		(layer "In9.Cu")
		(net "FM_BMC_ENABLE_N")
	)
	(segment
		(start 418.589206 -48.798226)
		(end 418.329618 -49.057814)
		(width 0.089408)
		(layer "In9.Cu")
		(net "FM_BMC_ENABLE_N")
	)
	(segment
		(start 402.897594 -110.328202)
		(end 401.715224 -110.328202)
		(width 0.089408)
		(layer "In9.Cu")
		(net "FM_BMC_ENABLE_N")
	)
	(segment
		(start 458.49159 -32.961834)
		(end 457.163424 -34.29)
		(width 0.089408)
		(layer "In9.Cu")
		(net "FM_BMC_ENABLE_N")
	)
	(segment
		(start 429.13681 -43.486578)
		(end 428.756826 -43.866562)
		(width 0.089408)
		(layer "In9.Cu")
		(net "FM_BMC_ENABLE_N")
	)
	(segment
		(start 421.3987 -46.6344)
		(end 419.234366 -48.798734)
		(width 0.089408)
		(layer "In9.Cu")
		(net "FM_BMC_ENABLE_N")
	)
	(segment
		(start 401.715224 -110.328202)
		(end 401.603464 -110.439962)
		(width 0.089408)
		(layer "In9.Cu")
		(net "FM_BMC_ENABLE_N")
	)
	(segment
		(start 423.544492 -45.652944)
		(end 423.008552 -45.117004)
		(width 0.089408)
		(layer "In9.Cu")
		(net "FM_BMC_ENABLE_N")
	)
	(segment
		(start 398.517364 -110.439962)
		(end 398.13865 -110.818676)
		(width 0.089408)
		(layer "In9.Cu")
		(net "FM_BMC_ENABLE_N")
	)
	(segment
		(start 407.880312 -108.215938)
		(end 407.136346 -108.959904)
		(width 0.089408)
		(layer "In9.Cu")
		(net "FM_BMC_ENABLE_N")
	)
	(segment
		(start 418.74821 -48.798226)
		(end 418.590222 -48.798226)
		(width 0.089408)
		(layer "In9.Cu")
		(net "FM_BMC_ENABLE_N")
	)
	(segment
		(start 411.874208 -106.096308)
		(end 409.754578 -108.215938)
		(width 0.089408)
		(layer "In9.Cu")
		(net "FM_BMC_ENABLE_N")
	)
	(segment
		(start 453.76084 -39.813484)
		(end 452.557642 -38.610286)
		(width 0.089408)
		(layer "In9.Cu")
		(net "FM_BMC_ENABLE_N")
	)
	(segment
		(start 414.05048 -106.397298)
		(end 414.004252 -106.397298)
		(width 0.089408)
		(layer "In9.Cu")
		(net "FM_BMC_ENABLE_N")
	)
	(segment
		(start 405.14397 -110.491778)
		(end 403.06117 -110.491778)
		(width 0.089408)
		(layer "In9.Cu")
		(net "FM_BMC_ENABLE_N")
	)
	(segment
		(start 451.168262 -38.610286)
		(end 450.750178 -39.02837)
		(width 0.089408)
		(layer "In9.Cu")
		(net "FM_BMC_ENABLE_N")
	)
	(segment
		(start 418.590222 -48.798226)
		(end 418.589714 -48.798734)
		(width 0.089408)
		(layer "In9.Cu")
		(net "FM_BMC_ENABLE_N")
	)
	(segment
		(start 449.339208 -41.688512)
		(end 435.648608 -41.688512)
		(width 0.089408)
		(layer "In9.Cu")
		(net "FM_BMC_ENABLE_N")
	)
	(segment
		(start 426.165264 -45.545756)
		(end 426.058076 -45.652944)
		(width 0.089408)
		(layer "In9.Cu")
		(net "FM_BMC_ENABLE_N")
	)
	(segment
		(start 418.906706 -48.798734)
		(end 418.906452 -48.79848)
		(width 0.089408)
		(layer "In9.Cu")
		(net "FM_BMC_ENABLE_N")
	)
	(segment
		(start 406.675844 -108.959904)
		(end 405.14397 -110.491778)
		(width 0.089408)
		(layer "In9.Cu")
		(net "FM_BMC_ENABLE_N")
	)
	(segment
		(start 398.13865 -110.818676)
		(end 398.13865 -110.943644)
		(width 0.089408)
		(layer "In9.Cu")
		(net "FM_BMC_ENABLE_N")
	)
	(segment
		(start 413.703262 -106.096308)
		(end 411.874208 -106.096308)
		(width 0.089408)
		(layer "In9.Cu")
		(net "FM_BMC_ENABLE_N")
	)
	(segment
		(start 418.589714 -48.798734)
		(end 418.589206 -48.798226)
		(width 0.089408)
		(layer "In9.Cu")
		(net "FM_BMC_ENABLE_N")
	)
	(segment
		(start 456.665076 -34.29)
		(end 455.263504 -35.691572)
		(width 0.089408)
		(layer "In9.Cu")
		(net "FM_BMC_ENABLE_N")
	)
	(segment
		(start 422.362884 -45.117004)
		(end 421.3987 -46.081188)
		(width 0.089408)
		(layer "In9.Cu")
		(net "FM_BMC_ENABLE_N")
	)
	(segment
		(start 433.044092 -42.77868)
		(end 432.336194 -43.486578)
		(width 0.089408)
		(layer "In9.Cu")
		(net "FM_BMC_ENABLE_N")
	)
	(segment
		(start 454.637648 -39.813484)
		(end 453.76084 -39.813484)
		(width 0.089408)
		(layer "In9.Cu")
		(net "FM_BMC_ENABLE_N")
	)
	(segment
		(start 401.603464 -110.439962)
		(end 398.517364 -110.439962)
		(width 0.089408)
		(layer "In9.Cu")
		(net "FM_BMC_ENABLE_N")
	)
	(segment
		(start 403.06117 -110.491778)
		(end 402.897594 -110.328202)
		(width 0.089408)
		(layer "In9.Cu")
		(net "FM_BMC_ENABLE_N")
	)
	(segment
		(start 421.3987 -46.081188)
		(end 421.3987 -46.6344)
		(width 0.089408)
		(layer "In9.Cu")
		(net "FM_BMC_ENABLE_N")
	)
	(segment
		(start 432.336194 -43.486578)
		(end 429.13681 -43.486578)
		(width 0.089408)
		(layer "In9.Cu")
		(net "FM_BMC_ENABLE_N")
	)
	(segment
		(start 407.136346 -108.959904)
		(end 406.675844 -108.959904)
		(width 0.089408)
		(layer "In9.Cu")
		(net "FM_BMC_ENABLE_N")
	)
	(segment
		(start 409.754578 -108.215938)
		(end 407.880312 -108.215938)
		(width 0.089408)
		(layer "In9.Cu")
		(net "FM_BMC_ENABLE_N")
	)
	(segment
		(start 455.263504 -39.187628)
		(end 454.637648 -39.813484)
		(width 0.089408)
		(layer "In9.Cu")
		(net "FM_BMC_ENABLE_N")
	)
	(segment
		(start 418.906452 -48.79848)
		(end 418.748464 -48.79848)
		(width 0.089408)
		(layer "In9.Cu")
		(net "FM_BMC_ENABLE_N")
	)
	(segment
		(start 428.756826 -43.866562)
		(end 428.49927 -43.866562)
		(width 0.089408)
		(layer "In9.Cu")
		(net "FM_BMC_ENABLE_N")
	)
	(segment
		(start 458.49159 -32.253936)
		(end 458.49159 -32.961834)
		(width 0.089408)
		(layer "In9.Cu")
		(net "FM_BMC_ENABLE_N")
	)
	(segment
		(start 395.14018 -75.240642)
		(end 394.91285 -75.013312)
		(width 0.089408)
		(layer "In11.Cu")
		(net "FM_BMC_ENABLE_N")
	)
	(segment
		(start 397.24457 -109.319314)
		(end 397.643858 -108.920026)
		(width 0.089408)
		(layer "In11.Cu")
		(net "FM_BMC_ENABLE_N")
	)
	(segment
		(start 397.643858 -108.920026)
		(end 397.643858 -108.471462)
		(width 0.089408)
		(layer "In11.Cu")
		(net "FM_BMC_ENABLE_N")
	)
	(segment
		(start 397.73987 -98.855022)
		(end 397.73987 -98.07321)
		(width 0.089408)
		(layer "In11.Cu")
		(net "FM_BMC_ENABLE_N")
	)
	(segment
		(start 395.14018 -82.726276)
		(end 395.14018 -75.240642)
		(width 0.089408)
		(layer "In11.Cu")
		(net "FM_BMC_ENABLE_N")
	)
	(segment
		(start 398.04213 -107.742482)
		(end 397.73987 -107.440222)
		(width 0.089408)
		(layer "In11.Cu")
		(net "FM_BMC_ENABLE_N")
	)
	(segment
		(start 397.086328 -104.373934)
		(end 397.60144 -103.858822)
		(width 0.089408)
		(layer "In11.Cu")
		(net "FM_BMC_ENABLE_N")
	)
	(segment
		(start 397.086328 -104.604312)
		(end 397.086328 -104.373934)
		(width 0.089408)
		(layer "In11.Cu")
		(net "FM_BMC_ENABLE_N")
	)
	(segment
		(start 397.15948 -106.052112)
		(end 396.66672 -105.559352)
		(width 0.089408)
		(layer "In11.Cu")
		(net "FM_BMC_ENABLE_N")
	)
	(segment
		(start 396.97025 -88.585548)
		(end 396.522194 -88.137492)
		(width 0.089408)
		(layer "In11.Cu")
		(net "FM_BMC_ENABLE_N")
	)
	(segment
		(start 396.790926 -95.0976)
		(end 394.782548 -93.089222)
		(width 0.089408)
		(layer "In11.Cu")
		(net "FM_BMC_ENABLE_N")
	)
	(segment
		(start 396.97025 -89.30513)
		(end 396.97025 -88.585548)
		(width 0.089408)
		(layer "In11.Cu")
		(net "FM_BMC_ENABLE_N")
	)
	(segment
		(start 396.66672 -105.559352)
		(end 396.66672 -105.02392)
		(width 0.089408)
		(layer "In11.Cu")
		(net "FM_BMC_ENABLE_N")
	)
	(segment
		(start 398.04213 -100.874322)
		(end 397.73987 -100.572062)
		(width 0.089408)
		(layer "In11.Cu")
		(net "FM_BMC_ENABLE_N")
	)
	(segment
		(start 398.13865 -110.943644)
		(end 397.24457 -110.049564)
		(width 0.089408)
		(layer "In11.Cu")
		(net "FM_BMC_ENABLE_N")
	)
	(segment
		(start 397.643858 -108.471462)
		(end 398.04213 -108.07319)
		(width 0.089408)
		(layer "In11.Cu")
		(net "FM_BMC_ENABLE_N")
	)
	(segment
		(start 394.782548 -93.089222)
		(end 394.782548 -91.720162)
		(width 0.089408)
		(layer "In11.Cu")
		(net "FM_BMC_ENABLE_N")
	)
	(segment
		(start 398.04213 -96.178878)
		(end 398.04213 -95.723202)
		(width 0.089408)
		(layer "In11.Cu")
		(net "FM_BMC_ENABLE_N")
	)
	(segment
		(start 397.73987 -106.918252)
		(end 397.15948 -106.337862)
		(width 0.089408)
		(layer "In11.Cu")
		(net "FM_BMC_ENABLE_N")
	)
	(segment
		(start 398.04213 -97.440242)
		(end 397.73987 -97.137982)
		(width 0.089408)
		(layer "In11.Cu")
		(net "FM_BMC_ENABLE_N")
	)
	(segment
		(start 398.04213 -99.48799)
		(end 398.04213 -99.157282)
		(width 0.089408)
		(layer "In11.Cu")
		(net "FM_BMC_ENABLE_N")
	)
	(segment
		(start 397.73987 -99.79025)
		(end 398.04213 -99.48799)
		(width 0.089408)
		(layer "In11.Cu")
		(net "FM_BMC_ENABLE_N")
	)
	(segment
		(start 396.66672 -105.02392)
		(end 397.086328 -104.604312)
		(width 0.089408)
		(layer "In11.Cu")
		(net "FM_BMC_ENABLE_N")
	)
	(segment
		(start 397.73987 -97.137982)
		(end 397.73987 -96.481138)
		(width 0.089408)
		(layer "In11.Cu")
		(net "FM_BMC_ENABLE_N")
	)
	(segment
		(start 397.416528 -95.0976)
		(end 396.790926 -95.0976)
		(width 0.089408)
		(layer "In11.Cu")
		(net "FM_BMC_ENABLE_N")
	)
	(segment
		(start 396.522194 -88.137492)
		(end 395.58087 -88.137492)
		(width 0.089408)
		(layer "In11.Cu")
		(net "FM_BMC_ENABLE_N")
	)
	(segment
		(start 394.327888 -86.88451)
		(end 394.327888 -83.538568)
		(width 0.089408)
		(layer "In11.Cu")
		(net "FM_BMC_ENABLE_N")
	)
	(segment
		(start 398.04213 -95.723202)
		(end 397.416528 -95.0976)
		(width 0.089408)
		(layer "In11.Cu")
		(net "FM_BMC_ENABLE_N")
	)
	(segment
		(start 397.73987 -98.07321)
		(end 398.04213 -97.77095)
		(width 0.089408)
		(layer "In11.Cu")
		(net "FM_BMC_ENABLE_N")
	)
	(segment
		(start 394.782548 -91.720162)
		(end 394.782294 -91.719908)
		(width 0.089408)
		(layer "In11.Cu")
		(net "FM_BMC_ENABLE_N")
	)
	(segment
		(start 397.60144 -101.64572)
		(end 398.04213 -101.20503)
		(width 0.089408)
		(layer "In11.Cu")
		(net "FM_BMC_ENABLE_N")
	)
	(segment
		(start 397.73987 -100.572062)
		(end 397.73987 -99.79025)
		(width 0.089408)
		(layer "In11.Cu")
		(net "FM_BMC_ENABLE_N")
	)
	(segment
		(start 397.60144 -103.858822)
		(end 397.60144 -101.64572)
		(width 0.089408)
		(layer "In11.Cu")
		(net "FM_BMC_ENABLE_N")
	)
	(segment
		(start 397.24457 -110.049564)
		(end 397.24457 -109.319314)
		(width 0.089408)
		(layer "In11.Cu")
		(net "FM_BMC_ENABLE_N")
	)
	(segment
		(start 397.15948 -106.337862)
		(end 397.15948 -106.052112)
		(width 0.089408)
		(layer "In11.Cu")
		(net "FM_BMC_ENABLE_N")
	)
	(segment
		(start 398.04213 -101.20503)
		(end 398.04213 -100.874322)
		(width 0.089408)
		(layer "In11.Cu")
		(net "FM_BMC_ENABLE_N")
	)
	(segment
		(start 398.04213 -99.157282)
		(end 397.73987 -98.855022)
		(width 0.089408)
		(layer "In11.Cu")
		(net "FM_BMC_ENABLE_N")
	)
	(segment
		(start 397.73987 -107.440222)
		(end 397.73987 -106.918252)
		(width 0.089408)
		(layer "In11.Cu")
		(net "FM_BMC_ENABLE_N")
	)
	(segment
		(start 395.58087 -88.137492)
		(end 394.327888 -86.88451)
		(width 0.089408)
		(layer "In11.Cu")
		(net "FM_BMC_ENABLE_N")
	)
	(segment
		(start 394.327888 -83.538568)
		(end 395.14018 -82.726276)
		(width 0.089408)
		(layer "In11.Cu")
		(net "FM_BMC_ENABLE_N")
	)
	(segment
		(start 398.04213 -97.77095)
		(end 398.04213 -97.440242)
		(width 0.089408)
		(layer "In11.Cu")
		(net "FM_BMC_ENABLE_N")
	)
	(segment
		(start 394.782294 -91.719908)
		(end 394.782294 -91.493086)
		(width 0.089408)
		(layer "In11.Cu")
		(net "FM_BMC_ENABLE_N")
	)
	(segment
		(start 398.04213 -108.07319)
		(end 398.04213 -107.742482)
		(width 0.089408)
		(layer "In11.Cu")
		(net "FM_BMC_ENABLE_N")
	)
	(segment
		(start 397.73987 -96.481138)
		(end 398.04213 -96.178878)
		(width 0.089408)
		(layer "In11.Cu")
		(net "FM_BMC_ENABLE_N")
	)
	(segment
		(start 394.782294 -91.493086)
		(end 396.97025 -89.30513)
		(width 0.089408)
		(layer "In11.Cu")
		(net "FM_BMC_ENABLE_N")
	)
	(segment
		(start 367.945162 -76.694792)
		(end 368.344958 -76.294996)
		(width 0.10795)
		(layer "F.Cu")
		(net "TP_CPLD1_PR11B")
	)
	(via
		(at 367.945162 -76.694792)
		(size 0.4572)
		(drill 0.2032)
		(layers "F.Cu" "B.Cu")
		(net "TP_CPLD1_PR11B")
	)
	(segment
		(start 370.745004 -74.69505)
		(end 370.345208 -75.094846)
		(width 0.10795)
		(layer "F.Cu")
		(net "TP_CPLD1_PR10C")
	)
	(via
		(at 370.345208 -75.094846)
		(size 0.4572)
		(drill 0.2032)
		(layers "F.Cu" "B.Cu")
		(net "TP_CPLD1_PR10C")
	)
	(segment
		(start 88.353392 -88.28024)
		(end 87.781892 -88.28024)
		(width 0.10795)
		(layer "F.Cu")
		(net "TP_CPU1_RSVD_60")
	)
	(via
		(at 87.781892 -88.28024)
		(size 0.508)
		(drill 0.254)
		(layers "F.Cu" "B.Cu")
		(net "TP_CPU1_RSVD_60")
	)
	(segment
		(start 123.363228 -90.575384)
		(end 123.934728 -90.575384)
		(width 0.10795)
		(layer "F.Cu")
		(net "TP_CPU1_RSVD_59")
	)
	(via
		(at 123.934728 -90.575384)
		(size 0.4826)
		(drill 0.254)
		(layers "F.Cu" "B.Cu")
		(net "TP_CPU1_RSVD_59")
	)
	(segment
		(start 109.627416 -90.575384)
		(end 110.198916 -90.575384)
		(width 0.10795)
		(layer "F.Cu")
		(net "TP_CPU1_RSVD_57")
	)
	(via
		(at 110.198916 -90.575384)
		(size 0.508)
		(drill 0.254)
		(layers "F.Cu" "B.Cu")
		(net "TP_CPU1_RSVD_57")
	)
	(segment
		(start 96.079818 -88.775286)
		(end 95.508318 -88.775286)
		(width 0.10795)
		(layer "F.Cu")
		(net "TP_CPU1_RSVD_56")
	)
	(via
		(at 95.508318 -88.775286)
		(size 0.508)
		(drill 0.254)
		(layers "F.Cu" "B.Cu")
		(net "TP_CPU1_RSVD_56")
	)
	(segment
		(start 92.645738 -88.775286)
		(end 92.074238 -88.775286)
		(width 0.10795)
		(layer "F.Cu")
		(net "TP_CPU1_RSVD_55")
	)
	(via
		(at 92.074238 -88.775286)
		(size 0.508)
		(drill 0.254)
		(layers "F.Cu" "B.Cu")
		(net "TP_CPU1_RSVD_55")
	)
	(segment
		(start 87.494872 -88.775286)
		(end 86.923372 -88.775286)
		(width 0.10795)
		(layer "F.Cu")
		(net "TP_CPU1_RSVD_54")
	)
	(via
		(at 86.923372 -88.775286)
		(size 0.508)
		(drill 0.254)
		(layers "F.Cu" "B.Cu")
		(net "TP_CPU1_RSVD_54")
	)
	(segment
		(start 78.909672 -88.775286)
		(end 78.338172 -88.775286)
		(width 0.10795)
		(layer "F.Cu")
		(net "TP_CPU1_RSVD_53")
	)
	(via
		(at 78.338172 -88.775286)
		(size 0.508)
		(drill 0.254)
		(layers "F.Cu" "B.Cu")
		(net "TP_CPU1_RSVD_53")
	)
	(segment
		(start 108.768896 -91.070938)
		(end 109.340396 -91.070938)
		(width 0.10795)
		(layer "F.Cu")
		(net "TP_CPU1_RSVD_51")
	)
	(via
		(at 109.340396 -91.070938)
		(size 0.508)
		(drill 0.254)
		(layers "F.Cu" "B.Cu")
		(net "TP_CPU1_RSVD_51")
	)
	(segment
		(start 96.938338 -89.27084)
		(end 96.366838 -89.27084)
		(width 0.10795)
		(layer "F.Cu")
		(net "TP_CPU1_RSVD_50")
	)
	(via
		(at 96.366838 -89.27084)
		(size 0.508)
		(drill 0.254)
		(layers "F.Cu" "B.Cu")
		(net "TP_CPU1_RSVD_50")
	)
	(segment
		(start 94.649798 -89.27084)
		(end 95.221298 -89.27084)
		(width 0.10795)
		(layer "F.Cu")
		(net "TP_CPU1_RSVD_49")
	)
	(via
		(at 94.649798 -89.27084)
		(size 0.508)
		(drill 0.254)
		(layers "F.Cu" "B.Cu")
		(net "TP_CPU1_RSVD_49")
	)
	(segment
		(start 93.504258 -89.27084)
		(end 92.932758 -89.27084)
		(width 0.10795)
		(layer "F.Cu")
		(net "TP_CPU1_RSVD_48")
	)
	(via
		(at 92.932758 -89.27084)
		(size 0.508)
		(drill 0.254)
		(layers "F.Cu" "B.Cu")
		(net "TP_CPU1_RSVD_48")
	)
	(segment
		(start 102.089204 -90.26144)
		(end 101.517704 -90.26144)
		(width 0.10795)
		(layer "F.Cu")
		(net "TP_CPU1_RSVD_47")
	)
	(via
		(at 101.517704 -90.26144)
		(size 0.508)
		(drill 0.254)
		(layers "F.Cu" "B.Cu")
		(net "TP_CPU1_RSVD_47")
	)
	(segment
		(start 433.832762 2.413)
		(end 435.229762 3.81)
		(width 0.10795)
		(layer "F.Cu")
		(net "RST_BMC_SRST_N")
	)
	(segment
		(start 432.0032 2.413)
		(end 433.832762 2.413)
		(width 0.10795)
		(layer "F.Cu")
		(net "RST_BMC_SRST_N")
	)
	(segment
		(start 396.213076 -48.93945)
		(end 395.825726 -49.3268)
		(width 0.1016)
		(layer "F.Cu")
		(net "RST_BMC_SRST_N")
	)
	(segment
		(start 447.831972 -15.621)
		(end 447.831972 -14.732)
		(width 0.10795)
		(layer "F.Cu")
		(net "RST_BMC_SRST_N")
	)
	(segment
		(start 447.675 -15.777972)
		(end 447.831972 -15.621)
		(width 0.10795)
		(layer "F.Cu")
		(net "RST_BMC_SRST_N")
	)
	(segment
		(start 395.1224 -49.3268)
		(end 394.716 -48.9204)
		(width 0.1016)
		(layer "F.Cu")
		(net "RST_BMC_SRST_N")
	)
	(segment
		(start 395.825726 -49.3268)
		(end 395.1224 -49.3268)
		(width 0.1016)
		(layer "F.Cu")
		(net "RST_BMC_SRST_N")
	)
	(segment
		(start 447.675 -16.002)
		(end 447.675 -15.777972)
		(width 0.10795)
		(layer "F.Cu")
		(net "RST_BMC_SRST_N")
	)
	(segment
		(start 394.716 -48.9204)
		(end 394.716 -47.970948)
		(width 0.1016)
		(layer "F.Cu")
		(net "RST_BMC_SRST_N")
	)
	(segment
		(start 429.514 -0.762)
		(end 429.514 -0.0762)
		(width 0.10795)
		(layer "F.Cu")
		(net "RST_BMC_SRST_N")
	)
	(segment
		(start 397.981932 -44.705016)
		(end 397.981932 -44.498768)
		(width 0.1016)
		(layer "F.Cu")
		(net "RST_BMC_SRST_N")
	)
	(segment
		(start 419.890194 -40.13454)
		(end 419.890194 -40.172132)
		(width 0.089408)
		(layer "F.Cu")
		(net "RST_BMC_SRST_N")
	)
	(segment
		(start 447.675 -16.002)
		(end 452.755 -16.002)
		(width 0.10795)
		(layer "F.Cu")
		(net "RST_BMC_SRST_N")
	)
	(segment
		(start 394.716 -47.970948)
		(end 397.981932 -44.705016)
		(width 0.1016)
		(layer "F.Cu")
		(net "RST_BMC_SRST_N")
	)
	(segment
		(start 429.514 -0.0762)
		(end 432.0032 2.413)
		(width 0.10795)
		(layer "F.Cu")
		(net "RST_BMC_SRST_N")
	)
	(segment
		(start 419.890194 -40.172132)
		(end 420.278052 -40.55999)
		(width 0.089408)
		(layer "F.Cu")
		(net "RST_BMC_SRST_N")
	)
	(segment
		(start 452.755 -16.002)
		(end 453.222614 -16.469614)
		(width 0.10795)
		(layer "F.Cu")
		(net "RST_BMC_SRST_N")
	)
	(segment
		(start 396.72895 -48.93945)
		(end 396.213076 -48.93945)
		(width 0.1016)
		(layer "F.Cu")
		(net "RST_BMC_SRST_N")
	)
	(via
		(at 429.514 -0.762)
		(size 0.508)
		(drill 0.254)
		(layers "F.Cu" "B.Cu")
		(net "RST_BMC_SRST_N")
	)
	(via
		(at 396.72895 -48.93945)
		(size 0.508)
		(drill 0.254)
		(layers "F.Cu" "B.Cu")
		(net "RST_BMC_SRST_N")
	)
	(via
		(at 378.418852 -88.902794)
		(size 0.508)
		(drill 0.254)
		(layers "F.Cu" "B.Cu")
		(net "RST_BMC_SRST_N")
	)
	(via
		(at 446.91935 -14.3256)
		(size 0.6604)
		(drill 0.3302)
		(layers "F.Cu" "B.Cu")
		(net "RST_BMC_SRST_N")
	)
	(via
		(at 397.981932 -44.498768)
		(size 0.508)
		(drill 0.254)
		(layers "F.Cu" "B.Cu")
		(net "RST_BMC_SRST_N")
	)
	(via
		(at 377.927616 -85.725)
		(size 0.508)
		(drill 0.254)
		(layers "F.Cu" "B.Cu")
		(net "RST_BMC_SRST_N")
	)
	(via
		(at 434.132736 -22.557994)
		(size 0.508)
		(drill 0.254)
		(layers "F.Cu" "B.Cu")
		(net "RST_BMC_SRST_N")
	)
	(via
		(at 371.758718 -90.743786)
		(size 0.508)
		(drill 0.254)
		(layers "F.Cu" "B.Cu")
		(net "RST_BMC_SRST_N")
	)
	(via
		(at 453.222614 -16.469614)
		(size 0.508)
		(drill 0.254)
		(layers "F.Cu" "B.Cu")
		(net "RST_BMC_SRST_N")
	)
	(via
		(at 420.278052 -40.55999)
		(size 0.4572)
		(drill 0.2032)
		(layers "F.Cu" "B.Cu")
		(net "RST_BMC_SRST_N")
	)
	(segment
		(start 449.7197 -14.605)
		(end 452.355966 -14.605)
		(width 0.10795)
		(layer "B.Cu")
		(net "RST_BMC_SRST_N")
	)
	(segment
		(start 447.462402 -10.601198)
		(end 447.462402 -7.495286)
		(width 0.10795)
		(layer "B.Cu")
		(net "RST_BMC_SRST_N")
	)
	(segment
		(start 440.497468 -3.794252)
		(end 440.497468 -2.836926)
		(width 0.10795)
		(layer "B.Cu")
		(net "RST_BMC_SRST_N")
	)
	(segment
		(start 446.91935 -11.14425)
		(end 447.462402 -10.601198)
		(width 0.10795)
		(layer "B.Cu")
		(net "RST_BMC_SRST_N")
	)
	(segment
		(start 371.8687 -90.805)
		(end 372.5418 -90.805)
		(width 0.10795)
		(layer "B.Cu")
		(net "RST_BMC_SRST_N")
	)
	(segment
		(start 453.000872 -15.249906)
		(end 453.000872 -16.247872)
		(width 0.10795)
		(layer "B.Cu")
		(net "RST_BMC_SRST_N")
	)
	(segment
		(start 440.188096 -6.600444)
		(end 439.137298 -5.549646)
		(width 0.10795)
		(layer "B.Cu")
		(net "RST_BMC_SRST_N")
	)
	(segment
		(start 439.137298 -5.154422)
		(end 440.497468 -3.794252)
		(width 0.10795)
		(layer "B.Cu")
		(net "RST_BMC_SRST_N")
	)
	(segment
		(start 371.758718 -90.743786)
		(end 371.807486 -90.743786)
		(width 0.10795)
		(layer "B.Cu")
		(net "RST_BMC_SRST_N")
	)
	(segment
		(start 439.137298 -5.549646)
		(end 439.137298 -5.154422)
		(width 0.10795)
		(layer "B.Cu")
		(net "RST_BMC_SRST_N")
	)
	(segment
		(start 446.56756 -6.600444)
		(end 440.188096 -6.600444)
		(width 0.10795)
		(layer "B.Cu")
		(net "RST_BMC_SRST_N")
	)
	(segment
		(start 446.91935 -14.3256)
		(end 446.91935 -11.14425)
		(width 0.10795)
		(layer "B.Cu")
		(net "RST_BMC_SRST_N")
	)
	(segment
		(start 446.91935 -14.3256)
		(end 446.91935 -14.78915)
		(width 0.10795)
		(layer "B.Cu")
		(net "RST_BMC_SRST_N")
	)
	(segment
		(start 446.91935 -14.78915)
		(end 447.5734 -15.4432)
		(width 0.10795)
		(layer "B.Cu")
		(net "RST_BMC_SRST_N")
	)
	(segment
		(start 440.497468 -2.836926)
		(end 439.467244 -1.806702)
		(width 0.10795)
		(layer "B.Cu")
		(net "RST_BMC_SRST_N")
	)
	(segment
		(start 439.467244 -1.806702)
		(end 430.571402 -1.806702)
		(width 0.10795)
		(layer "B.Cu")
		(net "RST_BMC_SRST_N")
	)
	(segment
		(start 447.462402 -7.495286)
		(end 446.56756 -6.600444)
		(width 0.10795)
		(layer "B.Cu")
		(net "RST_BMC_SRST_N")
	)
	(segment
		(start 430.571402 -1.806702)
		(end 429.5267 -0.762)
		(width 0.10795)
		(layer "B.Cu")
		(net "RST_BMC_SRST_N")
	)
	(segment
		(start 371.807486 -90.743786)
		(end 371.8687 -90.805)
		(width 0.10795)
		(layer "B.Cu")
		(net "RST_BMC_SRST_N")
	)
	(segment
		(start 452.355966 -14.605)
		(end 453.000872 -15.249906)
		(width 0.10795)
		(layer "B.Cu")
		(net "RST_BMC_SRST_N")
	)
	(segment
		(start 429.5267 -0.762)
		(end 429.514 -0.762)
		(width 0.10795)
		(layer "B.Cu")
		(net "RST_BMC_SRST_N")
	)
	(segment
		(start 453.000872 -16.247872)
		(end 453.222614 -16.469614)
		(width 0.10795)
		(layer "B.Cu")
		(net "RST_BMC_SRST_N")
	)
	(segment
		(start 448.8815 -15.4432)
		(end 449.7197 -14.605)
		(width 0.10795)
		(layer "B.Cu")
		(net "RST_BMC_SRST_N")
	)
	(segment
		(start 447.5734 -15.4432)
		(end 448.8815 -15.4432)
		(width 0.10795)
		(layer "B.Cu")
		(net "RST_BMC_SRST_N")
	)
	(segment
		(start 416.962844 -40.132)
		(end 416.664902 -40.429942)
		(width 0.089408)
		(layer "In2.Cu")
		(net "RST_BMC_SRST_N")
	)
	(segment
		(start 391.3378 -92.964)
		(end 391.1346 -93.1672)
		(width 0.089408)
		(layer "In2.Cu")
		(net "RST_BMC_SRST_N")
	)
	(segment
		(start 404.947374 -41.871392)
		(end 402.319998 -44.498768)
		(width 0.089408)
		(layer "In2.Cu")
		(net "RST_BMC_SRST_N")
	)
	(segment
		(start 415.334704 -41.76014)
		(end 414.585404 -42.50944)
		(width 0.089408)
		(layer "In2.Cu")
		(net "RST_BMC_SRST_N")
	)
	(segment
		(start 406.731724 -41.969182)
		(end 406.633934 -41.871392)
		(width 0.089408)
		(layer "In2.Cu")
		(net "RST_BMC_SRST_N")
	)
	(segment
		(start 402.319998 -44.498768)
		(end 397.981932 -44.498768)
		(width 0.089408)
		(layer "In2.Cu")
		(net "RST_BMC_SRST_N")
	)
	(segment
		(start 416.185858 -40.90924)
		(end 415.887154 -41.207944)
		(width 0.089408)
		(layer "In2.Cu")
		(net "RST_BMC_SRST_N")
	)
	(segment
		(start 391.262108 -82.092546)
		(end 391.262108 -82.800952)
		(width 0.089408)
		(layer "In2.Cu")
		(net "RST_BMC_SRST_N")
	)
	(segment
		(start 391.549636 -84.805774)
		(end 391.262108 -85.093302)
		(width 0.089408)
		(layer "In2.Cu")
		(net "RST_BMC_SRST_N")
	)
	(segment
		(start 416.664902 -40.429942)
		(end 416.664902 -40.689784)
		(width 0.089408)
		(layer "In2.Cu")
		(net "RST_BMC_SRST_N")
	)
	(segment
		(start 396.72895 -48.93945)
		(end 397.465296 -49.675796)
		(width 0.089408)
		(layer "In2.Cu")
		(net "RST_BMC_SRST_N")
	)
	(segment
		(start 397.465296 -61.385704)
		(end 394.241528 -64.609472)
		(width 0.089408)
		(layer "In2.Cu")
		(net "RST_BMC_SRST_N")
	)
	(segment
		(start 394.241528 -70.702424)
		(end 393.845288 -71.098664)
		(width 0.089408)
		(layer "In2.Cu")
		(net "RST_BMC_SRST_N")
	)
	(segment
		(start 391.262108 -85.093302)
		(end 391.262108 -88.927178)
		(width 0.089408)
		(layer "In2.Cu")
		(net "RST_BMC_SRST_N")
	)
	(segment
		(start 419.115494 -39.629842)
		(end 418.845492 -39.35984)
		(width 0.089408)
		(layer "In2.Cu")
		(net "RST_BMC_SRST_N")
	)
	(segment
		(start 419.115494 -39.931086)
		(end 419.115494 -39.629842)
		(width 0.089408)
		(layer "In2.Cu")
		(net "RST_BMC_SRST_N")
	)
	(segment
		(start 420.117524 -40.55999)
		(end 419.689534 -40.132)
		(width 0.089408)
		(layer "In2.Cu")
		(net "RST_BMC_SRST_N")
	)
	(segment
		(start 414.585404 -42.50944)
		(end 408.020774 -42.50944)
		(width 0.089408)
		(layer "In2.Cu")
		(net "RST_BMC_SRST_N")
	)
	(segment
		(start 391.690352 -81.664302)
		(end 391.262108 -82.092546)
		(width 0.089408)
		(layer "In2.Cu")
		(net "RST_BMC_SRST_N")
	)
	(segment
		(start 418.30752 -39.92118)
		(end 418.0967 -40.132)
		(width 0.089408)
		(layer "In2.Cu")
		(net "RST_BMC_SRST_N")
	)
	(segment
		(start 418.46246 -39.35984)
		(end 418.30752 -39.51478)
		(width 0.089408)
		(layer "In2.Cu")
		(net "RST_BMC_SRST_N")
	)
	(segment
		(start 391.690352 -78.627478)
		(end 391.690352 -81.664302)
		(width 0.089408)
		(layer "In2.Cu")
		(net "RST_BMC_SRST_N")
	)
	(segment
		(start 391.549636 -83.08848)
		(end 391.549636 -84.805774)
		(width 0.089408)
		(layer "In2.Cu")
		(net "RST_BMC_SRST_N")
	)
	(segment
		(start 381.01016 -92.73032)
		(end 381.01016 -88.76284)
		(width 0.089408)
		(layer "In2.Cu")
		(net "RST_BMC_SRST_N")
	)
	(segment
		(start 416.664902 -40.689784)
		(end 416.445446 -40.90924)
		(width 0.089408)
		(layer "In2.Cu")
		(net "RST_BMC_SRST_N")
	)
	(segment
		(start 419.689534 -40.132)
		(end 419.316408 -40.132)
		(width 0.089408)
		(layer "In2.Cu")
		(net "RST_BMC_SRST_N")
	)
	(segment
		(start 381.635762 -93.355922)
		(end 381.01016 -92.73032)
		(width 0.089408)
		(layer "In2.Cu")
		(net "RST_BMC_SRST_N")
	)
	(segment
		(start 416.445446 -40.90924)
		(end 416.185858 -40.90924)
		(width 0.089408)
		(layer "In2.Cu")
		(net "RST_BMC_SRST_N")
	)
	(segment
		(start 378.891546 -88.4301)
		(end 378.418852 -88.902794)
		(width 0.089408)
		(layer "In2.Cu")
		(net "RST_BMC_SRST_N")
	)
	(segment
		(start 408.020774 -42.50944)
		(end 407.480516 -41.969182)
		(width 0.089408)
		(layer "In2.Cu")
		(net "RST_BMC_SRST_N")
	)
	(segment
		(start 381.01016 -88.76284)
		(end 380.67742 -88.4301)
		(width 0.089408)
		(layer "In2.Cu")
		(net "RST_BMC_SRST_N")
	)
	(segment
		(start 392.601704 -74.868786)
		(end 392.601704 -77.716126)
		(width 0.089408)
		(layer "In2.Cu")
		(net "RST_BMC_SRST_N")
	)
	(segment
		(start 391.3378 -89.00287)
		(end 391.3378 -92.964)
		(width 0.089408)
		(layer "In2.Cu")
		(net "RST_BMC_SRST_N")
	)
	(segment
		(start 391.262108 -88.927178)
		(end 391.3378 -89.00287)
		(width 0.089408)
		(layer "In2.Cu")
		(net "RST_BMC_SRST_N")
	)
	(segment
		(start 397.465296 -49.675796)
		(end 397.465296 -61.385704)
		(width 0.089408)
		(layer "In2.Cu")
		(net "RST_BMC_SRST_N")
	)
	(segment
		(start 387.093206 -92.595192)
		(end 386.332476 -93.355922)
		(width 0.089408)
		(layer "In2.Cu")
		(net "RST_BMC_SRST_N")
	)
	(segment
		(start 415.594546 -41.76014)
		(end 415.334704 -41.76014)
		(width 0.089408)
		(layer "In2.Cu")
		(net "RST_BMC_SRST_N")
	)
	(segment
		(start 418.30752 -39.51478)
		(end 418.30752 -39.92118)
		(width 0.089408)
		(layer "In2.Cu")
		(net "RST_BMC_SRST_N")
	)
	(segment
		(start 394.241528 -64.609472)
		(end 394.241528 -70.702424)
		(width 0.089408)
		(layer "In2.Cu")
		(net "RST_BMC_SRST_N")
	)
	(segment
		(start 390.2964 -93.1672)
		(end 389.724392 -92.595192)
		(width 0.089408)
		(layer "In2.Cu")
		(net "RST_BMC_SRST_N")
	)
	(segment
		(start 393.845288 -73.625202)
		(end 392.601704 -74.868786)
		(width 0.089408)
		(layer "In2.Cu")
		(net "RST_BMC_SRST_N")
	)
	(segment
		(start 391.262108 -82.800952)
		(end 391.549636 -83.08848)
		(width 0.089408)
		(layer "In2.Cu")
		(net "RST_BMC_SRST_N")
	)
	(segment
		(start 389.724392 -92.595192)
		(end 387.093206 -92.595192)
		(width 0.089408)
		(layer "In2.Cu")
		(net "RST_BMC_SRST_N")
	)
	(segment
		(start 419.316408 -40.132)
		(end 419.115494 -39.931086)
		(width 0.089408)
		(layer "In2.Cu")
		(net "RST_BMC_SRST_N")
	)
	(segment
		(start 420.278052 -40.55999)
		(end 420.117524 -40.55999)
		(width 0.089408)
		(layer "In2.Cu")
		(net "RST_BMC_SRST_N")
	)
	(segment
		(start 392.601704 -77.716126)
		(end 391.690352 -78.627478)
		(width 0.089408)
		(layer "In2.Cu")
		(net "RST_BMC_SRST_N")
	)
	(segment
		(start 393.845288 -71.098664)
		(end 393.845288 -73.625202)
		(width 0.089408)
		(layer "In2.Cu")
		(net "RST_BMC_SRST_N")
	)
	(segment
		(start 418.845492 -39.35984)
		(end 418.46246 -39.35984)
		(width 0.089408)
		(layer "In2.Cu")
		(net "RST_BMC_SRST_N")
	)
	(segment
		(start 418.0967 -40.132)
		(end 416.962844 -40.132)
		(width 0.089408)
		(layer "In2.Cu")
		(net "RST_BMC_SRST_N")
	)
	(segment
		(start 406.633934 -41.871392)
		(end 404.947374 -41.871392)
		(width 0.089408)
		(layer "In2.Cu")
		(net "RST_BMC_SRST_N")
	)
	(segment
		(start 386.332476 -93.355922)
		(end 381.635762 -93.355922)
		(width 0.089408)
		(layer "In2.Cu")
		(net "RST_BMC_SRST_N")
	)
	(segment
		(start 380.67742 -88.4301)
		(end 378.891546 -88.4301)
		(width 0.089408)
		(layer "In2.Cu")
		(net "RST_BMC_SRST_N")
	)
	(segment
		(start 415.887154 -41.207944)
		(end 415.887154 -41.467532)
		(width 0.089408)
		(layer "In2.Cu")
		(net "RST_BMC_SRST_N")
	)
	(segment
		(start 391.1346 -93.1672)
		(end 390.2964 -93.1672)
		(width 0.089408)
		(layer "In2.Cu")
		(net "RST_BMC_SRST_N")
	)
	(segment
		(start 415.887154 -41.467532)
		(end 415.594546 -41.76014)
		(width 0.089408)
		(layer "In2.Cu")
		(net "RST_BMC_SRST_N")
	)
	(segment
		(start 407.480516 -41.969182)
		(end 406.731724 -41.969182)
		(width 0.089408)
		(layer "In2.Cu")
		(net "RST_BMC_SRST_N")
	)
	(segment
		(start 373.455946 -90.678)
		(end 375.703846 -88.4301)
		(width 0.089408)
		(layer "In4.Cu")
		(net "RST_BMC_SRST_N")
	)
	(segment
		(start 371.824504 -90.678)
		(end 373.455946 -90.678)
		(width 0.089408)
		(layer "In4.Cu")
		(net "RST_BMC_SRST_N")
	)
	(segment
		(start 371.758718 -90.743786)
		(end 371.824504 -90.678)
		(width 0.089408)
		(layer "In4.Cu")
		(net "RST_BMC_SRST_N")
	)
	(segment
		(start 378.39904 -86.205568)
		(end 377.927616 -85.734144)
		(width 0.0889)
		(layer "In4.Cu")
		(net "RST_BMC_SRST_N")
	)
	(segment
		(start 377.927616 -85.734144)
		(end 377.927616 -85.725)
		(width 0.0889)
		(layer "In4.Cu")
		(net "RST_BMC_SRST_N")
	)
	(segment
		(start 376.446796 -87.68715)
		(end 377.467368 -87.68715)
		(width 0.0889)
		(layer "In4.Cu")
		(net "RST_BMC_SRST_N")
	)
	(segment
		(start 375.703846 -88.4301)
		(end 376.446796 -87.68715)
		(width 0.0889)
		(layer "In4.Cu")
		(net "RST_BMC_SRST_N")
	)
	(segment
		(start 378.39904 -86.755478)
		(end 378.39904 -86.205568)
		(width 0.0889)
		(layer "In4.Cu")
		(net "RST_BMC_SRST_N")
	)
	(segment
		(start 377.467368 -87.68715)
		(end 378.39904 -86.755478)
		(width 0.0889)
		(layer "In4.Cu")
		(net "RST_BMC_SRST_N")
	)
	(segment
		(start 420.664894 -40.173148)
		(end 420.278052 -40.55999)
		(width 0.089408)
		(layer "In9.Cu")
		(net "RST_BMC_SRST_N")
	)
	(segment
		(start 418.439346 -37.084254)
		(end 419.066472 -37.71138)
		(width 0.089408)
		(layer "In9.Cu")
		(net "RST_BMC_SRST_N")
	)
	(segment
		(start 418.723318 -33.307782)
		(end 418.439346 -33.591754)
		(width 0.089408)
		(layer "In9.Cu")
		(net "RST_BMC_SRST_N")
	)
	(segment
		(start 434.05425 -22.986492)
		(end 433.373784 -23.666958)
		(width 0.089408)
		(layer "In9.Cu")
		(net "RST_BMC_SRST_N")
	)
	(segment
		(start 420.53256 -37.71138)
		(end 420.664894 -37.843714)
		(width 0.089408)
		(layer "In9.Cu")
		(net "RST_BMC_SRST_N")
	)
	(segment
		(start 434.124608 -22.557994)
		(end 434.124608 -22.549866)
		(width 0.089408)
		(layer "In9.Cu")
		(net "RST_BMC_SRST_N")
	)
	(segment
		(start 426.610526 -24.36495)
		(end 426.338238 -24.637238)
		(width 0.089408)
		(layer "In9.Cu")
		(net "RST_BMC_SRST_N")
	)
	(segment
		(start 425.608496 -25.367234)
		(end 425.608496 -25.447498)
		(width 0.089408)
		(layer "In9.Cu")
		(net "RST_BMC_SRST_N")
	)
	(segment
		(start 427.22165 -24.36495)
		(end 426.610526 -24.36495)
		(width 0.089408)
		(layer "In9.Cu")
		(net "RST_BMC_SRST_N")
	)
	(segment
		(start 418.439346 -33.591754)
		(end 418.439346 -37.084254)
		(width 0.089408)
		(layer "In9.Cu")
		(net "RST_BMC_SRST_N")
	)
	(segment
		(start 424.857164 -26.004774)
		(end 424.857164 -27.798522)
		(width 0.089408)
		(layer "In9.Cu")
		(net "RST_BMC_SRST_N")
	)
	(segment
		(start 426.338238 -24.637238)
		(end 426.338238 -24.637492)
		(width 0.089408)
		(layer "In9.Cu")
		(net "RST_BMC_SRST_N")
	)
	(segment
		(start 432.532028 -23.666958)
		(end 432.361594 -23.496524)
		(width 0.089408)
		(layer "In9.Cu")
		(net "RST_BMC_SRST_N")
	)
	(segment
		(start 424.857164 -27.798522)
		(end 425.13885 -28.080208)
		(width 0.089408)
		(layer "In9.Cu")
		(net "RST_BMC_SRST_N")
	)
	(segment
		(start 425.608496 -25.447498)
		(end 425.323 -25.732994)
		(width 0.089408)
		(layer "In9.Cu")
		(net "RST_BMC_SRST_N")
	)
	(segment
		(start 433.373784 -23.666958)
		(end 432.532028 -23.666958)
		(width 0.089408)
		(layer "In9.Cu")
		(net "RST_BMC_SRST_N")
	)
	(segment
		(start 425.13885 -29.877512)
		(end 423.681652 -31.33471)
		(width 0.089408)
		(layer "In9.Cu")
		(net "RST_BMC_SRST_N")
	)
	(segment
		(start 418.723318 -31.757366)
		(end 418.723318 -33.307782)
		(width 0.089408)
		(layer "In9.Cu")
		(net "RST_BMC_SRST_N")
	)
	(segment
		(start 425.323 -25.732994)
		(end 425.128944 -25.732994)
		(width 0.089408)
		(layer "In9.Cu")
		(net "RST_BMC_SRST_N")
	)
	(segment
		(start 419.145974 -31.33471)
		(end 418.723318 -31.757366)
		(width 0.089408)
		(layer "In9.Cu")
		(net "RST_BMC_SRST_N")
	)
	(segment
		(start 426.338238 -24.637492)
		(end 425.608496 -25.367234)
		(width 0.089408)
		(layer "In9.Cu")
		(net "RST_BMC_SRST_N")
	)
	(segment
		(start 428.090076 -23.496524)
		(end 427.22165 -24.36495)
		(width 0.089408)
		(layer "In9.Cu")
		(net "RST_BMC_SRST_N")
	)
	(segment
		(start 434.132736 -22.557994)
		(end 434.124608 -22.557994)
		(width 0.089408)
		(layer "In9.Cu")
		(net "RST_BMC_SRST_N")
	)
	(segment
		(start 432.361594 -23.496524)
		(end 428.090076 -23.496524)
		(width 0.089408)
		(layer "In9.Cu")
		(net "RST_BMC_SRST_N")
	)
	(segment
		(start 425.13885 -28.080208)
		(end 425.13885 -29.877512)
		(width 0.089408)
		(layer "In9.Cu")
		(net "RST_BMC_SRST_N")
	)
	(segment
		(start 425.128944 -25.732994)
		(end 424.857164 -26.004774)
		(width 0.089408)
		(layer "In9.Cu")
		(net "RST_BMC_SRST_N")
	)
	(segment
		(start 419.066472 -37.71138)
		(end 420.53256 -37.71138)
		(width 0.089408)
		(layer "In9.Cu")
		(net "RST_BMC_SRST_N")
	)
	(segment
		(start 434.124608 -22.549866)
		(end 434.05425 -22.620224)
		(width 0.089408)
		(layer "In9.Cu")
		(net "RST_BMC_SRST_N")
	)
	(segment
		(start 420.664894 -37.843714)
		(end 420.664894 -40.173148)
		(width 0.089408)
		(layer "In9.Cu")
		(net "RST_BMC_SRST_N")
	)
	(segment
		(start 423.681652 -31.33471)
		(end 419.145974 -31.33471)
		(width 0.089408)
		(layer "In9.Cu")
		(net "RST_BMC_SRST_N")
	)
	(segment
		(start 434.05425 -22.620224)
		(end 434.05425 -22.986492)
		(width 0.089408)
		(layer "In9.Cu")
		(net "RST_BMC_SRST_N")
	)
	(segment
		(start 439.75909 -21.677122)
		(end 435.013608 -21.677122)
		(width 0.089408)
		(layer "In11.Cu")
		(net "RST_BMC_SRST_N")
	)
	(segment
		(start 378.210826 -86.017354)
		(end 378.418852 -86.22538)
		(width 0.089408)
		(layer "In11.Cu")
		(net "RST_BMC_SRST_N")
	)
	(segment
		(start 378.210826 -86.00821)
		(end 378.210826 -86.017354)
		(width 0.089408)
		(layer "In11.Cu")
		(net "RST_BMC_SRST_N")
	)
	(segment
		(start 444.898272 -21.190712)
		(end 440.2455 -21.190712)
		(width 0.089408)
		(layer "In11.Cu")
		(net "RST_BMC_SRST_N")
	)
	(segment
		(start 452.057008 -17.568418)
		(end 452.057008 -18.872962)
		(width 0.089408)
		(layer "In11.Cu")
		(net "RST_BMC_SRST_N")
	)
	(segment
		(start 453.155812 -16.469614)
		(end 452.057008 -17.568418)
		(width 0.089408)
		(layer "In11.Cu")
		(net "RST_BMC_SRST_N")
	)
	(segment
		(start 448.132454 -20.765008)
		(end 447.948304 -20.949158)
		(width 0.089408)
		(layer "In11.Cu")
		(net "RST_BMC_SRST_N")
	)
	(segment
		(start 440.2455 -21.190712)
		(end 439.75909 -21.677122)
		(width 0.089408)
		(layer "In11.Cu")
		(net "RST_BMC_SRST_N")
	)
	(segment
		(start 450.164962 -20.765008)
		(end 448.132454 -20.765008)
		(width 0.089408)
		(layer "In11.Cu")
		(net "RST_BMC_SRST_N")
	)
	(segment
		(start 447.948304 -20.949158)
		(end 445.139826 -20.949158)
		(width 0.089408)
		(layer "In11.Cu")
		(net "RST_BMC_SRST_N")
	)
	(segment
		(start 435.013608 -21.677122)
		(end 434.132736 -22.557994)
		(width 0.089408)
		(layer "In11.Cu")
		(net "RST_BMC_SRST_N")
	)
	(segment
		(start 378.418852 -86.22538)
		(end 378.418852 -88.902794)
		(width 0.089408)
		(layer "In11.Cu")
		(net "RST_BMC_SRST_N")
	)
	(segment
		(start 377.927616 -85.725)
		(end 378.210826 -86.00821)
		(width 0.089408)
		(layer "In11.Cu")
		(net "RST_BMC_SRST_N")
	)
	(segment
		(start 452.057008 -18.872962)
		(end 450.164962 -20.765008)
		(width 0.089408)
		(layer "In11.Cu")
		(net "RST_BMC_SRST_N")
	)
	(segment
		(start 453.222614 -16.469614)
		(end 453.155812 -16.469614)
		(width 0.089408)
		(layer "In11.Cu")
		(net "RST_BMC_SRST_N")
	)
	(segment
		(start 445.139826 -20.949158)
		(end 444.898272 -21.190712)
		(width 0.089408)
		(layer "In11.Cu")
		(net "RST_BMC_SRST_N")
	)
	(segment
		(start 340.080854 -74.336402)
		(end 340.080854 -72.885046)
		(width 0.10795)
		(layer "F.Cu")
		(net "PWRGD_P1V8MCP_CPU1")
	)
	(segment
		(start 181.10581 -123.110498)
		(end 181.10581 -127.123444)
		(width 0.10795)
		(layer "F.Cu")
		(net "PWRGD_P1V8MCP_CPU1")
	)
	(segment
		(start 182.395114 -114.28095)
		(end 182.3974 -114.3)
		(width 0.10795)
		(layer "F.Cu")
		(net "PWRGD_P1V8MCP_CPU1")
	)
	(segment
		(start 342.730074 -70.235826)
		(end 349.627952 -70.235826)
		(width 0.10795)
		(layer "F.Cu")
		(net "PWRGD_P1V8MCP_CPU1")
	)
	(segment
		(start 358.25938 -70.344538)
		(end 359.698544 -70.344538)
		(width 0.10795)
		(layer "F.Cu")
		(net "PWRGD_P1V8MCP_CPU1")
	)
	(segment
		(start 183.0324 -117.526308)
		(end 181.321964 -119.236744)
		(width 0.10795)
		(layer "F.Cu")
		(net "PWRGD_P1V8MCP_CPU1")
	)
	(segment
		(start 179.7939 -128.435354)
		(end 179.7939 -128.4478)
		(width 0.10795)
		(layer "F.Cu")
		(net "PWRGD_P1V8MCP_CPU1")
	)
	(segment
		(start 337.829906 -71.022972)
		(end 337.829906 -73.670668)
		(width 0.10795)
		(layer "F.Cu")
		(net "PWRGD_P1V8MCP_CPU1")
	)
	(segment
		(start 361.533694 -68.509134)
		(end 361.668822 -68.374006)
		(width 0.10795)
		(layer "F.Cu")
		(net "PWRGD_P1V8MCP_CPU1")
	)
	(segment
		(start 355.543104 -69.452744)
		(end 357.367586 -69.452744)
		(width 0.10795)
		(layer "F.Cu")
		(net "PWRGD_P1V8MCP_CPU1")
	)
	(segment
		(start 350.626426 -71.2343)
		(end 353.761548 -71.2343)
		(width 0.10795)
		(layer "F.Cu")
		(net "PWRGD_P1V8MCP_CPU1")
	)
	(segment
		(start 353.761548 -71.2343)
		(end 355.543104 -69.452744)
		(width 0.10795)
		(layer "F.Cu")
		(net "PWRGD_P1V8MCP_CPU1")
	)
	(segment
		(start 183.0324 -115.4938)
		(end 183.0324 -117.526308)
		(width 0.10795)
		(layer "F.Cu")
		(net "PWRGD_P1V8MCP_CPU1")
	)
	(segment
		(start 357.367586 -69.452744)
		(end 358.25938 -70.344538)
		(width 0.10795)
		(layer "F.Cu")
		(net "PWRGD_P1V8MCP_CPU1")
	)
	(segment
		(start 181.321964 -122.894344)
		(end 181.10581 -123.110498)
		(width 0.10795)
		(layer "F.Cu")
		(net "PWRGD_P1V8MCP_CPU1")
	)
	(segment
		(start 181.10581 -127.123444)
		(end 179.7939 -128.435354)
		(width 0.10795)
		(layer "F.Cu")
		(net "PWRGD_P1V8MCP_CPU1")
	)
	(segment
		(start 359.698544 -70.344538)
		(end 361.533694 -68.509134)
		(width 0.10795)
		(layer "F.Cu")
		(net "PWRGD_P1V8MCP_CPU1")
	)
	(segment
		(start 181.321964 -119.236744)
		(end 181.321964 -122.894344)
		(width 0.10795)
		(layer "F.Cu")
		(net "PWRGD_P1V8MCP_CPU1")
	)
	(segment
		(start 338.76234 -74.603102)
		(end 339.814154 -74.603102)
		(width 0.10795)
		(layer "F.Cu")
		(net "PWRGD_P1V8MCP_CPU1")
	)
	(segment
		(start 339.814154 -74.603102)
		(end 340.080854 -74.336402)
		(width 0.10795)
		(layer "F.Cu")
		(net "PWRGD_P1V8MCP_CPU1")
	)
	(segment
		(start 182.3974 -114.3)
		(end 182.3974 -114.8588)
		(width 0.10795)
		(layer "F.Cu")
		(net "PWRGD_P1V8MCP_CPU1")
	)
	(segment
		(start 349.627952 -70.235826)
		(end 350.626426 -71.2343)
		(width 0.10795)
		(layer "F.Cu")
		(net "PWRGD_P1V8MCP_CPU1")
	)
	(segment
		(start 365.945928 -69.478398)
		(end 365.945928 -69.895974)
		(width 0.10795)
		(layer "F.Cu")
		(net "PWRGD_P1V8MCP_CPU1")
	)
	(segment
		(start 365.945928 -69.895974)
		(end 366.745012 -70.695058)
		(width 0.10795)
		(layer "F.Cu")
		(net "PWRGD_P1V8MCP_CPU1")
	)
	(segment
		(start 337.829906 -73.670668)
		(end 338.76234 -74.603102)
		(width 0.10795)
		(layer "F.Cu")
		(net "PWRGD_P1V8MCP_CPU1")
	)
	(segment
		(start 361.668822 -68.374006)
		(end 364.841536 -68.374006)
		(width 0.10795)
		(layer "F.Cu")
		(net "PWRGD_P1V8MCP_CPU1")
	)
	(segment
		(start 182.3974 -114.8588)
		(end 183.0324 -115.4938)
		(width 0.10795)
		(layer "F.Cu")
		(net "PWRGD_P1V8MCP_CPU1")
	)
	(segment
		(start 340.080854 -72.885046)
		(end 342.730074 -70.235826)
		(width 0.10795)
		(layer "F.Cu")
		(net "PWRGD_P1V8MCP_CPU1")
	)
	(segment
		(start 364.841536 -68.374006)
		(end 365.945928 -69.478398)
		(width 0.10795)
		(layer "F.Cu")
		(net "PWRGD_P1V8MCP_CPU1")
	)
	(via
		(at 337.829906 -71.022972)
		(size 0.508)
		(drill 0.254)
		(layers "F.Cu" "B.Cu")
		(net "PWRGD_P1V8MCP_CPU1")
	)
	(via
		(at 179.7939 -128.4478)
		(size 0.508)
		(drill 0.254)
		(layers "F.Cu" "B.Cu")
		(net "PWRGD_P1V8MCP_CPU1")
	)
	(segment
		(start 189.98819 -133.18871)
		(end 191.073532 -134.274052)
		(width 0.089408)
		(layer "In4.Cu")
		(net "PWRGD_P1V8MCP_CPU1")
	)
	(segment
		(start 335.028032 -72.2884)
		(end 336.829654 -72.2884)
		(width 0.089408)
		(layer "In4.Cu")
		(net "PWRGD_P1V8MCP_CPU1")
	)
	(segment
		(start 183.3626 -128.8288)
		(end 187.72251 -133.18871)
		(width 0.089408)
		(layer "In4.Cu")
		(net "PWRGD_P1V8MCP_CPU1")
	)
	(segment
		(start 265.192002 -153.033222)
		(end 265.283696 -153.124916)
		(width 0.089408)
		(layer "In4.Cu")
		(net "PWRGD_P1V8MCP_CPU1")
	)
	(segment
		(start 326.33666 -126.482856)
		(end 326.33666 -124.683266)
		(width 0.089408)
		(layer "In4.Cu")
		(net "PWRGD_P1V8MCP_CPU1")
	)
	(segment
		(start 324.423278 -116.596414)
		(end 322.923408 -115.096544)
		(width 0.089408)
		(layer "In4.Cu")
		(net "PWRGD_P1V8MCP_CPU1")
	)
	(segment
		(start 325.262748 -127.556768)
		(end 326.33666 -126.482856)
		(width 0.089408)
		(layer "In4.Cu")
		(net "PWRGD_P1V8MCP_CPU1")
	)
	(segment
		(start 324.98665 -118.964456)
		(end 324.423278 -118.401084)
		(width 0.089408)
		(layer "In4.Cu")
		(net "PWRGD_P1V8MCP_CPU1")
	)
	(segment
		(start 321.437762 -153.124916)
		(end 323.46392 -151.098758)
		(width 0.089408)
		(layer "In4.Cu")
		(net "PWRGD_P1V8MCP_CPU1")
	)
	(segment
		(start 324.423278 -118.401084)
		(end 324.423278 -116.596414)
		(width 0.089408)
		(layer "In4.Cu")
		(net "PWRGD_P1V8MCP_CPU1")
	)
	(segment
		(start 323.846952 -135.66648)
		(end 323.846952 -131.879848)
		(width 0.089408)
		(layer "In4.Cu")
		(net "PWRGD_P1V8MCP_CPU1")
	)
	(segment
		(start 326.33666 -124.683266)
		(end 324.98665 -123.333256)
		(width 0.089408)
		(layer "In4.Cu")
		(net "PWRGD_P1V8MCP_CPU1")
	)
	(segment
		(start 182.0164 -129.0066)
		(end 182.1942 -128.8288)
		(width 0.089408)
		(layer "In4.Cu")
		(net "PWRGD_P1V8MCP_CPU1")
	)
	(segment
		(start 323.46392 -151.098758)
		(end 323.46392 -148.516086)
		(width 0.089408)
		(layer "In4.Cu")
		(net "PWRGD_P1V8MCP_CPU1")
	)
	(segment
		(start 324.98665 -123.333256)
		(end 324.98665 -118.964456)
		(width 0.089408)
		(layer "In4.Cu")
		(net "PWRGD_P1V8MCP_CPU1")
	)
	(segment
		(start 322.923408 -115.096544)
		(end 322.923408 -99.525836)
		(width 0.089408)
		(layer "In4.Cu")
		(net "PWRGD_P1V8MCP_CPU1")
	)
	(segment
		(start 323.46392 -148.516086)
		(end 322.890896 -147.943062)
		(width 0.089408)
		(layer "In4.Cu")
		(net "PWRGD_P1V8MCP_CPU1")
	)
	(segment
		(start 322.95592 -99.493324)
		(end 322.95592 -91.75496)
		(width 0.089408)
		(layer "In4.Cu")
		(net "PWRGD_P1V8MCP_CPU1")
	)
	(segment
		(start 262.282178 -153.109422)
		(end 262.9154 -152.4762)
		(width 0.089408)
		(layer "In4.Cu")
		(net "PWRGD_P1V8MCP_CPU1")
	)
	(segment
		(start 333.199232 -79.586074)
		(end 333.199232 -74.1172)
		(width 0.089408)
		(layer "In4.Cu")
		(net "PWRGD_P1V8MCP_CPU1")
	)
	(segment
		(start 180.3527 -129.0066)
		(end 182.0164 -129.0066)
		(width 0.089408)
		(layer "In4.Cu")
		(net "PWRGD_P1V8MCP_CPU1")
	)
	(segment
		(start 322.95592 -91.75496)
		(end 330.277216 -84.433664)
		(width 0.089408)
		(layer "In4.Cu")
		(net "PWRGD_P1V8MCP_CPU1")
	)
	(segment
		(start 322.890896 -136.622536)
		(end 323.846952 -135.66648)
		(width 0.089408)
		(layer "In4.Cu")
		(net "PWRGD_P1V8MCP_CPU1")
	)
	(segment
		(start 179.7939 -128.4478)
		(end 180.3527 -129.0066)
		(width 0.089408)
		(layer "In4.Cu")
		(net "PWRGD_P1V8MCP_CPU1")
	)
	(segment
		(start 325.262748 -128.125982)
		(end 325.262748 -127.556768)
		(width 0.089408)
		(layer "In4.Cu")
		(net "PWRGD_P1V8MCP_CPU1")
	)
	(segment
		(start 324.744334 -128.644396)
		(end 325.262748 -128.125982)
		(width 0.089408)
		(layer "In4.Cu")
		(net "PWRGD_P1V8MCP_CPU1")
	)
	(segment
		(start 262.9154 -152.4762)
		(end 264.491216 -152.4762)
		(width 0.089408)
		(layer "In4.Cu")
		(net "PWRGD_P1V8MCP_CPU1")
	)
	(segment
		(start 196.494146 -153.109422)
		(end 262.282178 -153.109422)
		(width 0.089408)
		(layer "In4.Cu")
		(net "PWRGD_P1V8MCP_CPU1")
	)
	(segment
		(start 182.1942 -128.8288)
		(end 183.3626 -128.8288)
		(width 0.089408)
		(layer "In4.Cu")
		(net "PWRGD_P1V8MCP_CPU1")
	)
	(segment
		(start 187.72251 -133.18871)
		(end 189.98819 -133.18871)
		(width 0.089408)
		(layer "In4.Cu")
		(net "PWRGD_P1V8MCP_CPU1")
	)
	(segment
		(start 337.829906 -71.288148)
		(end 337.829906 -71.022972)
		(width 0.089408)
		(layer "In4.Cu")
		(net "PWRGD_P1V8MCP_CPU1")
	)
	(segment
		(start 265.048238 -153.033222)
		(end 265.192002 -153.033222)
		(width 0.089408)
		(layer "In4.Cu")
		(net "PWRGD_P1V8MCP_CPU1")
	)
	(segment
		(start 336.829654 -72.2884)
		(end 337.829906 -71.288148)
		(width 0.089408)
		(layer "In4.Cu")
		(net "PWRGD_P1V8MCP_CPU1")
	)
	(segment
		(start 265.283696 -153.124916)
		(end 321.437762 -153.124916)
		(width 0.089408)
		(layer "In4.Cu")
		(net "PWRGD_P1V8MCP_CPU1")
	)
	(segment
		(start 322.923408 -99.525836)
		(end 322.95592 -99.493324)
		(width 0.089408)
		(layer "In4.Cu")
		(net "PWRGD_P1V8MCP_CPU1")
	)
	(segment
		(start 191.073532 -134.274052)
		(end 191.073532 -147.688808)
		(width 0.089408)
		(layer "In4.Cu")
		(net "PWRGD_P1V8MCP_CPU1")
	)
	(segment
		(start 264.491216 -152.4762)
		(end 265.048238 -153.033222)
		(width 0.089408)
		(layer "In4.Cu")
		(net "PWRGD_P1V8MCP_CPU1")
	)
	(segment
		(start 324.744334 -130.982466)
		(end 324.744334 -128.644396)
		(width 0.089408)
		(layer "In4.Cu")
		(net "PWRGD_P1V8MCP_CPU1")
	)
	(segment
		(start 322.890896 -147.943062)
		(end 322.890896 -136.622536)
		(width 0.089408)
		(layer "In4.Cu")
		(net "PWRGD_P1V8MCP_CPU1")
	)
	(segment
		(start 333.199232 -74.1172)
		(end 335.028032 -72.2884)
		(width 0.089408)
		(layer "In4.Cu")
		(net "PWRGD_P1V8MCP_CPU1")
	)
	(segment
		(start 191.073532 -147.688808)
		(end 196.494146 -153.109422)
		(width 0.089408)
		(layer "In4.Cu")
		(net "PWRGD_P1V8MCP_CPU1")
	)
	(segment
		(start 323.846952 -131.879848)
		(end 324.744334 -130.982466)
		(width 0.089408)
		(layer "In4.Cu")
		(net "PWRGD_P1V8MCP_CPU1")
	)
	(segment
		(start 330.277216 -84.433664)
		(end 330.277216 -82.50809)
		(width 0.089408)
		(layer "In4.Cu")
		(net "PWRGD_P1V8MCP_CPU1")
	)
	(segment
		(start 330.277216 -82.50809)
		(end 333.199232 -79.586074)
		(width 0.089408)
		(layer "In4.Cu")
		(net "PWRGD_P1V8MCP_CPU1")
	)
	(segment
		(start 180.53304 -123.32716)
		(end 180.960014 -122.900186)
		(width 0.10795)
		(layer "F.Cu")
		(net "FM_P1V8MCP_CPU1_EN")
	)
	(segment
		(start 180.960014 -122.900186)
		(end 180.960014 -118.985284)
		(width 0.10795)
		(layer "F.Cu")
		(net "FM_P1V8MCP_CPU1_EN")
	)
	(segment
		(start 180.960014 -118.985284)
		(end 182.3974 -117.547898)
		(width 0.10795)
		(layer "F.Cu")
		(net "FM_P1V8MCP_CPU1_EN")
	)
	(segment
		(start 180.680106 -124.723906)
		(end 180.53304 -124.57684)
		(width 0.10795)
		(layer "F.Cu")
		(net "FM_P1V8MCP_CPU1_EN")
	)
	(segment
		(start 182.3974 -115.57)
		(end 182.395114 -115.55095)
		(width 0.10795)
		(layer "F.Cu")
		(net "FM_P1V8MCP_CPU1_EN")
	)
	(segment
		(start 180.53304 -124.0028)
		(end 180.53304 -123.32716)
		(width 0.10795)
		(layer "F.Cu")
		(net "FM_P1V8MCP_CPU1_EN")
	)
	(segment
		(start 180.680106 -126.867412)
		(end 180.680106 -124.723906)
		(width 0.10795)
		(layer "F.Cu")
		(net "FM_P1V8MCP_CPU1_EN")
	)
	(segment
		(start 180.53304 -124.57684)
		(end 180.53304 -124.0028)
		(width 0.10795)
		(layer "F.Cu")
		(net "FM_P1V8MCP_CPU1_EN")
	)
	(segment
		(start 182.3974 -117.547898)
		(end 182.3974 -115.57)
		(width 0.10795)
		(layer "F.Cu")
		(net "FM_P1V8MCP_CPU1_EN")
	)
	(segment
		(start 369.545108 -71.895208)
		(end 369.944904 -72.295004)
		(width 0.1016)
		(layer "F.Cu")
		(net "FM_P1V8MCP_CPU1_EN")
	)
	(via
		(at 369.545108 -71.895208)
		(size 0.4572)
		(drill 0.2032)
		(layers "F.Cu" "B.Cu")
		(net "FM_P1V8MCP_CPU1_EN")
	)
	(via
		(at 369.4049 -66.5988)
		(size 0.508)
		(drill 0.254)
		(layers "F.Cu" "B.Cu")
		(net "FM_P1V8MCP_CPU1_EN")
	)
	(via
		(at 180.680106 -126.867412)
		(size 0.508)
		(drill 0.254)
		(layers "F.Cu" "B.Cu")
		(net "FM_P1V8MCP_CPU1_EN")
	)
	(via
		(at 180.53304 -124.0028)
		(size 0.762)
		(drill 0.381)
		(layers "F.Cu" "B.Cu")
		(net "FM_P1V8MCP_CPU1_EN")
	)
	(segment
		(start 369.12804 -68.627244)
		(end 369.134644 -68.633848)
		(width 0.10795)
		(layer "B.Cu")
		(net "FM_P1V8MCP_CPU1_EN")
	)
	(segment
		(start 369.134644 -68.633848)
		(end 369.134644 -71.484744)
		(width 0.10795)
		(layer "B.Cu")
		(net "FM_P1V8MCP_CPU1_EN")
	)
	(segment
		(start 369.4049 -66.5988)
		(end 369.4049 -66.694304)
		(width 0.10795)
		(layer "B.Cu")
		(net "FM_P1V8MCP_CPU1_EN")
	)
	(segment
		(start 368.362484 -67.73672)
		(end 368.362484 -68.053712)
		(width 0.10795)
		(layer "B.Cu")
		(net "FM_P1V8MCP_CPU1_EN")
	)
	(segment
		(start 368.792252 -68.291456)
		(end 368.813334 -68.312538)
		(width 0.10795)
		(layer "B.Cu")
		(net "FM_P1V8MCP_CPU1_EN")
	)
	(segment
		(start 368.362484 -68.053712)
		(end 368.586766 -68.277994)
		(width 0.10795)
		(layer "B.Cu")
		(net "FM_P1V8MCP_CPU1_EN")
	)
	(segment
		(start 369.134644 -71.484744)
		(end 369.545108 -71.895208)
		(width 0.10795)
		(layer "B.Cu")
		(net "FM_P1V8MCP_CPU1_EN")
	)
	(segment
		(start 368.614198 -68.291456)
		(end 368.792252 -68.291456)
		(width 0.10795)
		(layer "B.Cu")
		(net "FM_P1V8MCP_CPU1_EN")
	)
	(segment
		(start 368.903758 -68.312538)
		(end 369.12804 -68.53682)
		(width 0.10795)
		(layer "B.Cu")
		(net "FM_P1V8MCP_CPU1_EN")
	)
	(segment
		(start 369.12804 -68.53682)
		(end 369.12804 -68.627244)
		(width 0.10795)
		(layer "B.Cu")
		(net "FM_P1V8MCP_CPU1_EN")
	)
	(segment
		(start 368.813334 -68.312538)
		(end 368.903758 -68.312538)
		(width 0.10795)
		(layer "B.Cu")
		(net "FM_P1V8MCP_CPU1_EN")
	)
	(segment
		(start 368.586766 -68.277994)
		(end 368.600736 -68.277994)
		(width 0.10795)
		(layer "B.Cu")
		(net "FM_P1V8MCP_CPU1_EN")
	)
	(segment
		(start 368.600736 -68.277994)
		(end 368.614198 -68.291456)
		(width 0.10795)
		(layer "B.Cu")
		(net "FM_P1V8MCP_CPU1_EN")
	)
	(segment
		(start 369.4049 -66.694304)
		(end 368.362484 -67.73672)
		(width 0.10795)
		(layer "B.Cu")
		(net "FM_P1V8MCP_CPU1_EN")
	)
	(segment
		(start 276.648926 -155.30576)
		(end 276.765512 -155.189174)
		(width 0.089408)
		(layer "In4.Cu")
		(net "FM_P1V8MCP_CPU1_EN")
	)
	(segment
		(start 272.44548 -155.30576)
		(end 273.320256 -155.30576)
		(width 0.089408)
		(layer "In4.Cu")
		(net "FM_P1V8MCP_CPU1_EN")
	)
	(segment
		(start 269.122144 -155.30576)
		(end 269.872714 -155.30576)
		(width 0.089408)
		(layer "In4.Cu")
		(net "FM_P1V8MCP_CPU1_EN")
	)
	(segment
		(start 369.481862 -65.563496)
		(end 369.716304 -65.797938)
		(width 0.089408)
		(layer "In4.Cu")
		(net "FM_P1V8MCP_CPU1_EN")
	)
	(segment
		(start 352.589084 -69.784976)
		(end 352.784156 -69.980048)
		(width 0.089408)
		(layer "In4.Cu")
		(net "FM_P1V8MCP_CPU1_EN")
	)
	(segment
		(start 321.637152 -156.30779)
		(end 323.984112 -153.96083)
		(width 0.089408)
		(layer "In4.Cu")
		(net "FM_P1V8MCP_CPU1_EN")
	)
	(segment
		(start 192.673986 -150.89632)
		(end 192.673986 -153.797254)
		(width 0.089408)
		(layer "In4.Cu")
		(net "FM_P1V8MCP_CPU1_EN")
	)
	(segment
		(start 272.329656 -155.189936)
		(end 272.44548 -155.30576)
		(width 0.089408)
		(layer "In4.Cu")
		(net "FM_P1V8MCP_CPU1_EN")
	)
	(segment
		(start 369.716304 -66.287396)
		(end 369.4049 -66.5988)
		(width 0.089408)
		(layer "In4.Cu")
		(net "FM_P1V8MCP_CPU1_EN")
	)
	(segment
		(start 325.590662 -133.122924)
		(end 325.590662 -131.546854)
		(width 0.089408)
		(layer "In4.Cu")
		(net "FM_P1V8MCP_CPU1_EN")
	)
	(segment
		(start 324.419976 -135.904224)
		(end 324.419976 -134.29361)
		(width 0.089408)
		(layer "In4.Cu")
		(net "FM_P1V8MCP_CPU1_EN")
	)
	(segment
		(start 268.32433 -155.214574)
		(end 269.030958 -155.214574)
		(width 0.089408)
		(layer "In4.Cu")
		(net "FM_P1V8MCP_CPU1_EN")
	)
	(segment
		(start 368.674904 -65.563496)
		(end 369.481862 -65.563496)
		(width 0.089408)
		(layer "In4.Cu")
		(net "FM_P1V8MCP_CPU1_EN")
	)
	(segment
		(start 335.114392 -73.012808)
		(end 337.026504 -73.012808)
		(width 0.089408)
		(layer "In4.Cu")
		(net "FM_P1V8MCP_CPU1_EN")
	)
	(segment
		(start 261.72922 -156.249878)
		(end 261.743698 -156.2354)
		(width 0.089408)
		(layer "In4.Cu")
		(net "FM_P1V8MCP_CPU1_EN")
	)
	(segment
		(start 266.33424 -155.30576)
		(end 266.425172 -155.214828)
		(width 0.089408)
		(layer "In4.Cu")
		(net "FM_P1V8MCP_CPU1_EN")
	)
	(segment
		(start 172.435774 -129.53238)
		(end 171.747434 -130.22072)
		(width 0.089408)
		(layer "In4.Cu")
		(net "FM_P1V8MCP_CPU1_EN")
	)
	(segment
		(start 264.06348 -156.2354)
		(end 265.084052 -155.214828)
		(width 0.089408)
		(layer "In4.Cu")
		(net "FM_P1V8MCP_CPU1_EN")
	)
	(segment
		(start 171.747434 -130.22072)
		(end 169.785792 -130.22072)
		(width 0.089408)
		(layer "In4.Cu")
		(net "FM_P1V8MCP_CPU1_EN")
	)
	(segment
		(start 177.929032 -127.467106)
		(end 175.863758 -129.53238)
		(width 0.089408)
		(layer "In4.Cu")
		(net "FM_P1V8MCP_CPU1_EN")
	)
	(segment
		(start 270.817594 -155.30576)
		(end 271.582642 -155.30576)
		(width 0.089408)
		(layer "In4.Cu")
		(net "FM_P1V8MCP_CPU1_EN")
	)
	(segment
		(start 184.89295 -145.662904)
		(end 185.506868 -145.048986)
		(width 0.089408)
		(layer "In4.Cu")
		(net "FM_P1V8MCP_CPU1_EN")
	)
	(segment
		(start 323.699886 -138.624056)
		(end 324.2818 -138.042142)
		(width 0.089408)
		(layer "In4.Cu")
		(net "FM_P1V8MCP_CPU1_EN")
	)
	(segment
		(start 189.453266 -147.6756)
		(end 192.673986 -150.89632)
		(width 0.089408)
		(layer "In4.Cu")
		(net "FM_P1V8MCP_CPU1_EN")
	)
	(segment
		(start 264.040112 -156.255974)
		(end 264.060686 -156.2354)
		(width 0.089408)
		(layer "In4.Cu")
		(net "FM_P1V8MCP_CPU1_EN")
	)
	(segment
		(start 277.55596 -155.30576)
		(end 278.379936 -155.30576)
		(width 0.089408)
		(layer "In4.Cu")
		(net "FM_P1V8MCP_CPU1_EN")
	)
	(segment
		(start 362.57865 -70.624446)
		(end 363.453172 -69.749924)
		(width 0.089408)
		(layer "In4.Cu")
		(net "FM_P1V8MCP_CPU1_EN")
	)
	(segment
		(start 345.92641 -69.784976)
		(end 352.589084 -69.784976)
		(width 0.089408)
		(layer "In4.Cu")
		(net "FM_P1V8MCP_CPU1_EN")
	)
	(segment
		(start 325.559674 -118.61292)
		(end 325.217028 -118.270274)
		(width 0.089408)
		(layer "In4.Cu")
		(net "FM_P1V8MCP_CPU1_EN")
	)
	(segment
		(start 326.909684 -124.445522)
		(end 325.559674 -123.095512)
		(width 0.089408)
		(layer "In4.Cu")
		(net "FM_P1V8MCP_CPU1_EN")
	)
	(segment
		(start 333.772256 -79.823818)
		(end 333.772256 -74.354944)
		(width 0.089408)
		(layer "In4.Cu")
		(net "FM_P1V8MCP_CPU1_EN")
	)
	(segment
		(start 161.316416 -128.804162)
		(end 160.203134 -129.917444)
		(width 0.089408)
		(layer "In4.Cu")
		(net "FM_P1V8MCP_CPU1_EN")
	)
	(segment
		(start 268.233144 -155.30576)
		(end 268.32433 -155.214574)
		(width 0.089408)
		(layer "In4.Cu")
		(net "FM_P1V8MCP_CPU1_EN")
	)
	(segment
		(start 172.116496 -144.365726)
		(end 172.458126 -144.707356)
		(width 0.089408)
		(layer "In4.Cu")
		(net "FM_P1V8MCP_CPU1_EN")
	)
	(segment
		(start 261.397496 -156.249878)
		(end 261.72922 -156.249878)
		(width 0.089408)
		(layer "In4.Cu")
		(net "FM_P1V8MCP_CPU1_EN")
	)
	(segment
		(start 280.001218 -155.199842)
		(end 280.21788 -155.416504)
		(width 0.089408)
		(layer "In4.Cu")
		(net "FM_P1V8MCP_CPU1_EN")
	)
	(segment
		(start 358.85755 -70.624446)
		(end 362.57865 -70.624446)
		(width 0.089408)
		(layer "In4.Cu")
		(net "FM_P1V8MCP_CPU1_EN")
	)
	(segment
		(start 278.485854 -155.199842)
		(end 280.001218 -155.199842)
		(width 0.089408)
		(layer "In4.Cu")
		(net "FM_P1V8MCP_CPU1_EN")
	)
	(segment
		(start 271.698466 -155.189936)
		(end 272.329656 -155.189936)
		(width 0.089408)
		(layer "In4.Cu")
		(net "FM_P1V8MCP_CPU1_EN")
	)
	(segment
		(start 168.369234 -128.804162)
		(end 161.316416 -128.804162)
		(width 0.089408)
		(layer "In4.Cu")
		(net "FM_P1V8MCP_CPU1_EN")
	)
	(segment
		(start 269.030958 -155.214574)
		(end 269.122144 -155.30576)
		(width 0.089408)
		(layer "In4.Cu")
		(net "FM_P1V8MCP_CPU1_EN")
	)
	(segment
		(start 325.217028 -116.251228)
		(end 324.26529 -115.29949)
		(width 0.089408)
		(layer "In4.Cu")
		(net "FM_P1V8MCP_CPU1_EN")
	)
	(segment
		(start 192.673986 -153.797254)
		(end 195.112132 -156.2354)
		(width 0.089408)
		(layer "In4.Cu")
		(net "FM_P1V8MCP_CPU1_EN")
	)
	(segment
		(start 265.557254 -155.214828)
		(end 265.648186 -155.30576)
		(width 0.089408)
		(layer "In4.Cu")
		(net "FM_P1V8MCP_CPU1_EN")
	)
	(segment
		(start 166.969948 -141.8971)
		(end 169.438574 -144.365726)
		(width 0.089408)
		(layer "In4.Cu")
		(net "FM_P1V8MCP_CPU1_EN")
	)
	(segment
		(start 323.984112 -153.96083)
		(end 323.984112 -147.400772)
		(width 0.089408)
		(layer "In4.Cu")
		(net "FM_P1V8MCP_CPU1_EN")
	)
	(segment
		(start 265.084052 -155.214828)
		(end 265.557254 -155.214828)
		(width 0.089408)
		(layer "In4.Cu")
		(net "FM_P1V8MCP_CPU1_EN")
	)
	(segment
		(start 261.383018 -156.2354)
		(end 261.397496 -156.249878)
		(width 0.089408)
		(layer "In4.Cu")
		(net "FM_P1V8MCP_CPU1_EN")
	)
	(segment
		(start 354.250498 -69.403468)
		(end 354.251514 -69.402452)
		(width 0.089408)
		(layer "In4.Cu")
		(net "FM_P1V8MCP_CPU1_EN")
	)
	(segment
		(start 180.080412 -127.467106)
		(end 177.929032 -127.467106)
		(width 0.089408)
		(layer "In4.Cu")
		(net "FM_P1V8MCP_CPU1_EN")
	)
	(segment
		(start 274.018502 -155.214574)
		(end 274.109688 -155.30576)
		(width 0.089408)
		(layer "In4.Cu")
		(net "FM_P1V8MCP_CPU1_EN")
	)
	(segment
		(start 324.419976 -134.29361)
		(end 325.590662 -133.122924)
		(width 0.089408)
		(layer "In4.Cu")
		(net "FM_P1V8MCP_CPU1_EN")
	)
	(segment
		(start 266.425172 -155.214828)
		(end 267.346684 -155.214828)
		(width 0.089408)
		(layer "In4.Cu")
		(net "FM_P1V8MCP_CPU1_EN")
	)
	(segment
		(start 281.565858 -155.212542)
		(end 282.661106 -156.30779)
		(width 0.089408)
		(layer "In4.Cu")
		(net "FM_P1V8MCP_CPU1_EN")
	)
	(segment
		(start 324.2818 -137.541)
		(end 323.971412 -137.230612)
		(width 0.089408)
		(layer "In4.Cu")
		(net "FM_P1V8MCP_CPU1_EN")
	)
	(segment
		(start 274.109688 -155.30576)
		(end 275.066252 -155.30576)
		(width 0.089408)
		(layer "In4.Cu")
		(net "FM_P1V8MCP_CPU1_EN")
	)
	(segment
		(start 177.568606 -145.662904)
		(end 184.89295 -145.662904)
		(width 0.089408)
		(layer "In4.Cu")
		(net "FM_P1V8MCP_CPU1_EN")
	)
	(segment
		(start 185.506868 -145.048986)
		(end 186.333384 -145.048986)
		(width 0.089408)
		(layer "In4.Cu")
		(net "FM_P1V8MCP_CPU1_EN")
	)
	(segment
		(start 263.14019 -156.2354)
		(end 263.160764 -156.255974)
		(width 0.089408)
		(layer "In4.Cu")
		(net "FM_P1V8MCP_CPU1_EN")
	)
	(segment
		(start 275.965412 -155.30576)
		(end 276.648926 -155.30576)
		(width 0.089408)
		(layer "In4.Cu")
		(net "FM_P1V8MCP_CPU1_EN")
	)
	(segment
		(start 369.716304 -65.797938)
		(end 369.716304 -66.287396)
		(width 0.089408)
		(layer "In4.Cu")
		(net "FM_P1V8MCP_CPU1_EN")
	)
	(segment
		(start 186.333384 -145.048986)
		(end 188.959998 -147.6756)
		(width 0.089408)
		(layer "In4.Cu")
		(net "FM_P1V8MCP_CPU1_EN")
	)
	(segment
		(start 339.958426 -70.519544)
		(end 345.191842 -70.519544)
		(width 0.089408)
		(layer "In4.Cu")
		(net "FM_P1V8MCP_CPU1_EN")
	)
	(segment
		(start 270.726408 -155.214574)
		(end 270.817594 -155.30576)
		(width 0.089408)
		(layer "In4.Cu")
		(net "FM_P1V8MCP_CPU1_EN")
	)
	(segment
		(start 269.872714 -155.30576)
		(end 269.9639 -155.214574)
		(width 0.089408)
		(layer "In4.Cu")
		(net "FM_P1V8MCP_CPU1_EN")
	)
	(segment
		(start 188.959998 -147.6756)
		(end 189.453266 -147.6756)
		(width 0.089408)
		(layer "In4.Cu")
		(net "FM_P1V8MCP_CPU1_EN")
	)
	(segment
		(start 275.066252 -155.30576)
		(end 275.157438 -155.214574)
		(width 0.089408)
		(layer "In4.Cu")
		(net "FM_P1V8MCP_CPU1_EN")
	)
	(segment
		(start 276.765512 -155.189174)
		(end 277.439374 -155.189174)
		(width 0.089408)
		(layer "In4.Cu")
		(net "FM_P1V8MCP_CPU1_EN")
	)
	(segment
		(start 175.863758 -129.53238)
		(end 172.435774 -129.53238)
		(width 0.089408)
		(layer "In4.Cu")
		(net "FM_P1V8MCP_CPU1_EN")
	)
	(segment
		(start 363.453172 -69.749924)
		(end 363.453172 -69.447918)
		(width 0.089408)
		(layer "In4.Cu")
		(net "FM_P1V8MCP_CPU1_EN")
	)
	(segment
		(start 161.338768 -141.8971)
		(end 166.969948 -141.8971)
		(width 0.089408)
		(layer "In4.Cu")
		(net "FM_P1V8MCP_CPU1_EN")
	)
	(segment
		(start 367.8682 -66.3702)
		(end 368.674904 -65.563496)
		(width 0.089408)
		(layer "In4.Cu")
		(net "FM_P1V8MCP_CPU1_EN")
	)
	(segment
		(start 333.772256 -74.354944)
		(end 335.114392 -73.012808)
		(width 0.089408)
		(layer "In4.Cu")
		(net "FM_P1V8MCP_CPU1_EN")
	)
	(segment
		(start 265.648186 -155.30576)
		(end 266.33424 -155.30576)
		(width 0.089408)
		(layer "In4.Cu")
		(net "FM_P1V8MCP_CPU1_EN")
	)
	(segment
		(start 337.026504 -73.012808)
		(end 338.727288 -71.312024)
		(width 0.089408)
		(layer "In4.Cu")
		(net "FM_P1V8MCP_CPU1_EN")
	)
	(segment
		(start 325.317358 -128.88214)
		(end 325.835772 -128.363726)
		(width 0.089408)
		(layer "In4.Cu")
		(net "FM_P1V8MCP_CPU1_EN")
	)
	(segment
		(start 160.203134 -140.761466)
		(end 161.338768 -141.8971)
		(width 0.089408)
		(layer "In4.Cu")
		(net "FM_P1V8MCP_CPU1_EN")
	)
	(segment
		(start 324.26529 -91.864434)
		(end 331.316584 -84.81314)
		(width 0.089408)
		(layer "In4.Cu")
		(net "FM_P1V8MCP_CPU1_EN")
	)
	(segment
		(start 323.971412 -137.230612)
		(end 323.971412 -136.352788)
		(width 0.089408)
		(layer "In4.Cu")
		(net "FM_P1V8MCP_CPU1_EN")
	)
	(segment
		(start 325.217028 -118.270274)
		(end 325.217028 -116.251228)
		(width 0.089408)
		(layer "In4.Cu")
		(net "FM_P1V8MCP_CPU1_EN")
	)
	(segment
		(start 275.157438 -155.214574)
		(end 275.874226 -155.214574)
		(width 0.089408)
		(layer "In4.Cu")
		(net "FM_P1V8MCP_CPU1_EN")
	)
	(segment
		(start 160.203134 -129.917444)
		(end 160.203134 -140.761466)
		(width 0.089408)
		(layer "In4.Cu")
		(net "FM_P1V8MCP_CPU1_EN")
	)
	(segment
		(start 261.743698 -156.2354)
		(end 263.14019 -156.2354)
		(width 0.089408)
		(layer "In4.Cu")
		(net "FM_P1V8MCP_CPU1_EN")
	)
	(segment
		(start 267.346684 -155.214828)
		(end 267.437616 -155.30576)
		(width 0.089408)
		(layer "In4.Cu")
		(net "FM_P1V8MCP_CPU1_EN")
	)
	(segment
		(start 363.453172 -69.447918)
		(end 366.53089 -66.3702)
		(width 0.089408)
		(layer "In4.Cu")
		(net "FM_P1V8MCP_CPU1_EN")
	)
	(segment
		(start 331.316584 -82.27949)
		(end 333.772256 -79.823818)
		(width 0.089408)
		(layer "In4.Cu")
		(net "FM_P1V8MCP_CPU1_EN")
	)
	(segment
		(start 269.9639 -155.214574)
		(end 270.726408 -155.214574)
		(width 0.089408)
		(layer "In4.Cu")
		(net "FM_P1V8MCP_CPU1_EN")
	)
	(segment
		(start 277.439374 -155.189174)
		(end 277.55596 -155.30576)
		(width 0.089408)
		(layer "In4.Cu")
		(net "FM_P1V8MCP_CPU1_EN")
	)
	(segment
		(start 357.635556 -69.402452)
		(end 358.85755 -70.624446)
		(width 0.089408)
		(layer "In4.Cu")
		(net "FM_P1V8MCP_CPU1_EN")
	)
	(segment
		(start 352.784156 -69.980048)
		(end 353.673664 -69.980048)
		(width 0.089408)
		(layer "In4.Cu")
		(net "FM_P1V8MCP_CPU1_EN")
	)
	(segment
		(start 282.661106 -156.30779)
		(end 321.637152 -156.30779)
		(width 0.089408)
		(layer "In4.Cu")
		(net "FM_P1V8MCP_CPU1_EN")
	)
	(segment
		(start 273.320256 -155.30576)
		(end 273.411442 -155.214574)
		(width 0.089408)
		(layer "In4.Cu")
		(net "FM_P1V8MCP_CPU1_EN")
	)
	(segment
		(start 325.590662 -131.546854)
		(end 325.317358 -131.27355)
		(width 0.089408)
		(layer "In4.Cu")
		(net "FM_P1V8MCP_CPU1_EN")
	)
	(segment
		(start 323.699886 -147.116546)
		(end 323.699886 -138.624056)
		(width 0.089408)
		(layer "In4.Cu")
		(net "FM_P1V8MCP_CPU1_EN")
	)
	(segment
		(start 281.026362 -155.212542)
		(end 281.565858 -155.212542)
		(width 0.089408)
		(layer "In4.Cu")
		(net "FM_P1V8MCP_CPU1_EN")
	)
	(segment
		(start 267.437616 -155.30576)
		(end 268.233144 -155.30576)
		(width 0.089408)
		(layer "In4.Cu")
		(net "FM_P1V8MCP_CPU1_EN")
	)
	(segment
		(start 325.559674 -123.095512)
		(end 325.559674 -118.61292)
		(width 0.089408)
		(layer "In4.Cu")
		(net "FM_P1V8MCP_CPU1_EN")
	)
	(segment
		(start 324.26529 -115.29949)
		(end 324.26529 -91.864434)
		(width 0.089408)
		(layer "In4.Cu")
		(net "FM_P1V8MCP_CPU1_EN")
	)
	(segment
		(start 331.316584 -84.81314)
		(end 331.316584 -82.27949)
		(width 0.089408)
		(layer "In4.Cu")
		(net "FM_P1V8MCP_CPU1_EN")
	)
	(segment
		(start 195.112132 -156.2354)
		(end 261.383018 -156.2354)
		(width 0.089408)
		(layer "In4.Cu")
		(net "FM_P1V8MCP_CPU1_EN")
	)
	(segment
		(start 354.250244 -69.403468)
		(end 354.250498 -69.403468)
		(width 0.089408)
		(layer "In4.Cu")
		(net "FM_P1V8MCP_CPU1_EN")
	)
	(segment
		(start 180.680106 -126.867412)
		(end 180.080412 -127.467106)
		(width 0.089408)
		(layer "In4.Cu")
		(net "FM_P1V8MCP_CPU1_EN")
	)
	(segment
		(start 278.379936 -155.30576)
		(end 278.485854 -155.199842)
		(width 0.089408)
		(layer "In4.Cu")
		(net "FM_P1V8MCP_CPU1_EN")
	)
	(segment
		(start 325.835772 -128.363726)
		(end 325.835772 -127.895604)
		(width 0.089408)
		(layer "In4.Cu")
		(net "FM_P1V8MCP_CPU1_EN")
	)
	(segment
		(start 339.165946 -71.312024)
		(end 339.958426 -70.519544)
		(width 0.089408)
		(layer "In4.Cu")
		(net "FM_P1V8MCP_CPU1_EN")
	)
	(segment
		(start 273.411442 -155.214574)
		(end 274.018502 -155.214574)
		(width 0.089408)
		(layer "In4.Cu")
		(net "FM_P1V8MCP_CPU1_EN")
	)
	(segment
		(start 275.874226 -155.214574)
		(end 275.965412 -155.30576)
		(width 0.089408)
		(layer "In4.Cu")
		(net "FM_P1V8MCP_CPU1_EN")
	)
	(segment
		(start 324.2818 -138.042142)
		(end 324.2818 -137.541)
		(width 0.089408)
		(layer "In4.Cu")
		(net "FM_P1V8MCP_CPU1_EN")
	)
	(segment
		(start 263.160764 -156.255974)
		(end 264.040112 -156.255974)
		(width 0.089408)
		(layer "In4.Cu")
		(net "FM_P1V8MCP_CPU1_EN")
	)
	(segment
		(start 264.060686 -156.2354)
		(end 264.06348 -156.2354)
		(width 0.089408)
		(layer "In4.Cu")
		(net "FM_P1V8MCP_CPU1_EN")
	)
	(segment
		(start 345.191842 -70.519544)
		(end 345.92641 -69.784976)
		(width 0.089408)
		(layer "In4.Cu")
		(net "FM_P1V8MCP_CPU1_EN")
	)
	(segment
		(start 326.909684 -126.821692)
		(end 326.909684 -124.445522)
		(width 0.089408)
		(layer "In4.Cu")
		(net "FM_P1V8MCP_CPU1_EN")
	)
	(segment
		(start 280.21788 -155.416504)
		(end 280.8224 -155.416504)
		(width 0.089408)
		(layer "In4.Cu")
		(net "FM_P1V8MCP_CPU1_EN")
	)
	(segment
		(start 353.673664 -69.980048)
		(end 354.250244 -69.403468)
		(width 0.089408)
		(layer "In4.Cu")
		(net "FM_P1V8MCP_CPU1_EN")
	)
	(segment
		(start 176.613058 -144.707356)
		(end 177.568606 -145.662904)
		(width 0.089408)
		(layer "In4.Cu")
		(net "FM_P1V8MCP_CPU1_EN")
	)
	(segment
		(start 325.317358 -131.27355)
		(end 325.317358 -128.88214)
		(width 0.089408)
		(layer "In4.Cu")
		(net "FM_P1V8MCP_CPU1_EN")
	)
	(segment
		(start 338.727288 -71.312024)
		(end 339.165946 -71.312024)
		(width 0.089408)
		(layer "In4.Cu")
		(net "FM_P1V8MCP_CPU1_EN")
	)
	(segment
		(start 325.835772 -127.895604)
		(end 326.909684 -126.821692)
		(width 0.089408)
		(layer "In4.Cu")
		(net "FM_P1V8MCP_CPU1_EN")
	)
	(segment
		(start 172.458126 -144.707356)
		(end 176.613058 -144.707356)
		(width 0.089408)
		(layer "In4.Cu")
		(net "FM_P1V8MCP_CPU1_EN")
	)
	(segment
		(start 366.53089 -66.3702)
		(end 367.8682 -66.3702)
		(width 0.089408)
		(layer "In4.Cu")
		(net "FM_P1V8MCP_CPU1_EN")
	)
	(segment
		(start 169.438574 -144.365726)
		(end 172.116496 -144.365726)
		(width 0.089408)
		(layer "In4.Cu")
		(net "FM_P1V8MCP_CPU1_EN")
	)
	(segment
		(start 354.251514 -69.402452)
		(end 357.635556 -69.402452)
		(width 0.089408)
		(layer "In4.Cu")
		(net "FM_P1V8MCP_CPU1_EN")
	)
	(segment
		(start 271.582642 -155.30576)
		(end 271.698466 -155.189936)
		(width 0.089408)
		(layer "In4.Cu")
		(net "FM_P1V8MCP_CPU1_EN")
	)
	(segment
		(start 169.785792 -130.22072)
		(end 168.369234 -128.804162)
		(width 0.089408)
		(layer "In4.Cu")
		(net "FM_P1V8MCP_CPU1_EN")
	)
	(segment
		(start 323.984112 -147.400772)
		(end 323.699886 -147.116546)
		(width 0.089408)
		(layer "In4.Cu")
		(net "FM_P1V8MCP_CPU1_EN")
	)
	(segment
		(start 323.971412 -136.352788)
		(end 324.419976 -135.904224)
		(width 0.089408)
		(layer "In4.Cu")
		(net "FM_P1V8MCP_CPU1_EN")
	)
	(segment
		(start 280.8224 -155.416504)
		(end 281.026362 -155.212542)
		(width 0.089408)
		(layer "In4.Cu")
		(net "FM_P1V8MCP_CPU1_EN")
	)
	(segment
		(start 408.690064 -27.334718)
		(end 408.290014 -26.934668)
		(width 0.10795)
		(layer "F.Cu")
		(net "CLK_50M_CKMNG_BMC_2")
	)
	(segment
		(start 475.723712 -37.846)
		(end 476.041212 -37.5285)
		(width 0.10795)
		(layer "F.Cu")
		(net "CLK_50M_CKMNG_BMC_2")
	)
	(segment
		(start 476.041212 -37.5285)
		(end 476.377 -37.5285)
		(width 0.10795)
		(layer "F.Cu")
		(net "CLK_50M_CKMNG_BMC_2")
	)
	(segment
		(start 474.895672 -37.2745)
		(end 474.895672 -37.32022)
		(width 0.10795)
		(layer "F.Cu")
		(net "CLK_50M_CKMNG_BMC_2")
	)
	(segment
		(start 474.895672 -37.32022)
		(end 475.421452 -37.846)
		(width 0.10795)
		(layer "F.Cu")
		(net "CLK_50M_CKMNG_BMC_2")
	)
	(segment
		(start 475.421452 -37.846)
		(end 475.723712 -37.846)
		(width 0.10795)
		(layer "F.Cu")
		(net "CLK_50M_CKMNG_BMC_2")
	)
	(via
		(at 474.895672 -37.2745)
		(size 0.508)
		(drill 0.254)
		(layers "F.Cu" "B.Cu")
		(net "CLK_50M_CKMNG_BMC_2")
	)
	(via
		(at 408.290014 -26.934668)
		(size 0.4572)
		(drill 0.2032)
		(layers "F.Cu" "B.Cu")
		(net "CLK_50M_CKMNG_BMC_2")
	)
	(segment
		(start 473.733368 -36.527232)
		(end 474.148404 -36.527232)
		(width 0.089408)
		(layer "In4.Cu")
		(net "CLK_50M_CKMNG_BMC_2")
	)
	(segment
		(start 461.700372 -31.469584)
		(end 463.973418 -33.74263)
		(width 0.089408)
		(layer "In4.Cu")
		(net "CLK_50M_CKMNG_BMC_2")
	)
	(segment
		(start 420.86276 -26.028142)
		(end 423.269156 -26.028142)
		(width 0.089408)
		(layer "In4.Cu")
		(net "CLK_50M_CKMNG_BMC_2")
	)
	(segment
		(start 430.925986 -24.753062)
		(end 431.5587 -24.753062)
		(width 0.089408)
		(layer "In4.Cu")
		(net "CLK_50M_CKMNG_BMC_2")
	)
	(segment
		(start 452.59371 -29.278072)
		(end 456.90536 -29.278072)
		(width 0.089408)
		(layer "In4.Cu")
		(net "CLK_50M_CKMNG_BMC_2")
	)
	(segment
		(start 456.90536 -29.278072)
		(end 457.690474 -30.063186)
		(width 0.089408)
		(layer "In4.Cu")
		(net "CLK_50M_CKMNG_BMC_2")
	)
	(segment
		(start 434.930296 -22.160738)
		(end 435.164738 -21.926296)
		(width 0.089408)
		(layer "In4.Cu")
		(net "CLK_50M_CKMNG_BMC_2")
	)
	(segment
		(start 463.973418 -33.74263)
		(end 466.0138 -33.74263)
		(width 0.089408)
		(layer "In4.Cu")
		(net "CLK_50M_CKMNG_BMC_2")
	)
	(segment
		(start 430.903888 -24.77516)
		(end 430.925986 -24.753062)
		(width 0.089408)
		(layer "In4.Cu")
		(net "CLK_50M_CKMNG_BMC_2")
	)
	(segment
		(start 432.910234 -24.887428)
		(end 434.930296 -22.867366)
		(width 0.089408)
		(layer "In4.Cu")
		(net "CLK_50M_CKMNG_BMC_2")
	)
	(segment
		(start 474.148404 -36.527232)
		(end 474.895672 -37.2745)
		(width 0.089408)
		(layer "In4.Cu")
		(net "CLK_50M_CKMNG_BMC_2")
	)
	(segment
		(start 423.828464 -26.58745)
		(end 428.885604 -26.58745)
		(width 0.089408)
		(layer "In4.Cu")
		(net "CLK_50M_CKMNG_BMC_2")
	)
	(segment
		(start 460.433928 -31.469584)
		(end 461.700372 -31.469584)
		(width 0.089408)
		(layer "In4.Cu")
		(net "CLK_50M_CKMNG_BMC_2")
	)
	(segment
		(start 473.131896 -36.527232)
		(end 473.134944 -36.53028)
		(width 0.089408)
		(layer "In4.Cu")
		(net "CLK_50M_CKMNG_BMC_2")
	)
	(segment
		(start 444.418974 -21.926296)
		(end 446.922652 -24.429974)
		(width 0.089408)
		(layer "In4.Cu")
		(net "CLK_50M_CKMNG_BMC_2")
	)
	(segment
		(start 417.251896 -25.961848)
		(end 418.062156 -25.151588)
		(width 0.089408)
		(layer "In4.Cu")
		(net "CLK_50M_CKMNG_BMC_2")
	)
	(segment
		(start 446.922652 -24.429974)
		(end 446.922652 -24.57831)
		(width 0.089408)
		(layer "In4.Cu")
		(net "CLK_50M_CKMNG_BMC_2")
	)
	(segment
		(start 470.006172 -35.3568)
		(end 471.176604 -36.527232)
		(width 0.089408)
		(layer "In4.Cu")
		(net "CLK_50M_CKMNG_BMC_2")
	)
	(segment
		(start 449.357496 -26.041858)
		(end 452.59371 -29.278072)
		(width 0.089408)
		(layer "In4.Cu")
		(net "CLK_50M_CKMNG_BMC_2")
	)
	(segment
		(start 423.269156 -26.028142)
		(end 423.828464 -26.58745)
		(width 0.089408)
		(layer "In4.Cu")
		(net "CLK_50M_CKMNG_BMC_2")
	)
	(segment
		(start 431.693066 -24.887428)
		(end 432.910234 -24.887428)
		(width 0.089408)
		(layer "In4.Cu")
		(net "CLK_50M_CKMNG_BMC_2")
	)
	(segment
		(start 446.922652 -24.57831)
		(end 448.3862 -26.041858)
		(width 0.089408)
		(layer "In4.Cu")
		(net "CLK_50M_CKMNG_BMC_2")
	)
	(segment
		(start 409.792932 -25.961848)
		(end 417.251896 -25.961848)
		(width 0.089408)
		(layer "In4.Cu")
		(net "CLK_50M_CKMNG_BMC_2")
	)
	(segment
		(start 466.0138 -33.74263)
		(end 467.62797 -35.3568)
		(width 0.089408)
		(layer "In4.Cu")
		(net "CLK_50M_CKMNG_BMC_2")
	)
	(segment
		(start 431.5587 -24.753062)
		(end 431.693066 -24.887428)
		(width 0.089408)
		(layer "In4.Cu")
		(net "CLK_50M_CKMNG_BMC_2")
	)
	(segment
		(start 408.437334 -26.787348)
		(end 408.967432 -26.787348)
		(width 0.089408)
		(layer "In4.Cu")
		(net "CLK_50M_CKMNG_BMC_2")
	)
	(segment
		(start 435.164738 -21.926296)
		(end 444.418974 -21.926296)
		(width 0.089408)
		(layer "In4.Cu")
		(net "CLK_50M_CKMNG_BMC_2")
	)
	(segment
		(start 473.73032 -36.53028)
		(end 473.733368 -36.527232)
		(width 0.089408)
		(layer "In4.Cu")
		(net "CLK_50M_CKMNG_BMC_2")
	)
	(segment
		(start 459.02753 -30.063186)
		(end 460.433928 -31.469584)
		(width 0.089408)
		(layer "In4.Cu")
		(net "CLK_50M_CKMNG_BMC_2")
	)
	(segment
		(start 457.690474 -30.063186)
		(end 459.02753 -30.063186)
		(width 0.089408)
		(layer "In4.Cu")
		(net "CLK_50M_CKMNG_BMC_2")
	)
	(segment
		(start 428.885604 -26.58745)
		(end 430.697894 -24.77516)
		(width 0.089408)
		(layer "In4.Cu")
		(net "CLK_50M_CKMNG_BMC_2")
	)
	(segment
		(start 419.986206 -25.151588)
		(end 420.86276 -26.028142)
		(width 0.089408)
		(layer "In4.Cu")
		(net "CLK_50M_CKMNG_BMC_2")
	)
	(segment
		(start 471.176604 -36.527232)
		(end 473.131896 -36.527232)
		(width 0.089408)
		(layer "In4.Cu")
		(net "CLK_50M_CKMNG_BMC_2")
	)
	(segment
		(start 473.134944 -36.53028)
		(end 473.73032 -36.53028)
		(width 0.089408)
		(layer "In4.Cu")
		(net "CLK_50M_CKMNG_BMC_2")
	)
	(segment
		(start 418.062156 -25.151588)
		(end 419.986206 -25.151588)
		(width 0.089408)
		(layer "In4.Cu")
		(net "CLK_50M_CKMNG_BMC_2")
	)
	(segment
		(start 430.697894 -24.77516)
		(end 430.903888 -24.77516)
		(width 0.089408)
		(layer "In4.Cu")
		(net "CLK_50M_CKMNG_BMC_2")
	)
	(segment
		(start 408.967432 -26.787348)
		(end 409.792932 -25.961848)
		(width 0.089408)
		(layer "In4.Cu")
		(net "CLK_50M_CKMNG_BMC_2")
	)
	(segment
		(start 408.290014 -26.934668)
		(end 408.437334 -26.787348)
		(width 0.089408)
		(layer "In4.Cu")
		(net "CLK_50M_CKMNG_BMC_2")
	)
	(segment
		(start 448.3862 -26.041858)
		(end 449.357496 -26.041858)
		(width 0.089408)
		(layer "In4.Cu")
		(net "CLK_50M_CKMNG_BMC_2")
	)
	(segment
		(start 467.62797 -35.3568)
		(end 470.006172 -35.3568)
		(width 0.089408)
		(layer "In4.Cu")
		(net "CLK_50M_CKMNG_BMC_2")
	)
	(segment
		(start 434.930296 -22.867366)
		(end 434.930296 -22.160738)
		(width 0.089408)
		(layer "In4.Cu")
		(net "CLK_50M_CKMNG_BMC_2")
	)
	(segment
		(start 399.923 -150.4696)
		(end 399.5293 -150.8633)
		(width 0.10795)
		(layer "F.Cu")
		(net "VR_PVNN_PCH_VREN")
	)
	(segment
		(start 399.5293 -150.8633)
		(end 399.0467 -151.3459)
		(width 0.10795)
		(layer "F.Cu")
		(net "VR_PVNN_PCH_VREN")
	)
	(segment
		(start 399.923 -150.114)
		(end 399.923 -150.4696)
		(width 0.10795)
		(layer "F.Cu")
		(net "VR_PVNN_PCH_VREN")
	)
	(segment
		(start 399.0467 -151.3459)
		(end 397.582898 -151.3459)
		(width 0.10795)
		(layer "F.Cu")
		(net "VR_PVNN_PCH_VREN")
	)
	(via
		(at 399.05432 -150.22703)
		(size 0.6604)
		(drill 0.3302)
		(layers "F.Cu" "B.Cu")
		(net "VR_PVNN_PCH_VREN")
	)
	(via
		(at 399.5293 -150.8633)
		(size 0.508)
		(drill 0.254)
		(layers "F.Cu" "B.Cu")
		(net "VR_PVNN_PCH_VREN")
	)
	(segment
		(start 399.5293 -150.8633)
		(end 399.306796 -150.8633)
		(width 0.10795)
		(layer "B.Cu")
		(net "VR_PVNN_PCH_VREN")
	)
	(segment
		(start 399.05432 -150.610824)
		(end 399.05432 -150.22703)
		(width 0.10795)
		(layer "B.Cu")
		(net "VR_PVNN_PCH_VREN")
	)
	(segment
		(start 399.05432 -149.89302)
		(end 399.283428 -149.663912)
		(width 0.10795)
		(layer "B.Cu")
		(net "VR_PVNN_PCH_VREN")
	)
	(segment
		(start 399.306796 -150.8633)
		(end 399.05432 -150.610824)
		(width 0.10795)
		(layer "B.Cu")
		(net "VR_PVNN_PCH_VREN")
	)
	(segment
		(start 399.283428 -149.663912)
		(end 399.940526 -149.663912)
		(width 0.10795)
		(layer "B.Cu")
		(net "VR_PVNN_PCH_VREN")
	)
	(segment
		(start 399.05432 -150.22703)
		(end 399.05432 -149.89302)
		(width 0.10795)
		(layer "B.Cu")
		(net "VR_PVNN_PCH_VREN")
	)
	(segment
		(start -0.464566 -130.4163)
		(end -0.529082 -130.480816)
		(width 0.10795)
		(layer "F.Cu")
		(net "VR_PVDDQ_KLM_VREN")
	)
	(segment
		(start 0.257302 -130.4163)
		(end -0.464566 -130.4163)
		(width 0.10795)
		(layer "F.Cu")
		(net "VR_PVDDQ_KLM_VREN")
	)
	(via
		(at -0.529082 -130.480816)
		(size 0.508)
		(drill 0.254)
		(layers "F.Cu" "B.Cu")
		(net "VR_PVDDQ_KLM_VREN")
	)
	(segment
		(start -0.889 -131.445)
		(end -0.889 -130.840734)
		(width 0.10795)
		(layer "B.Cu")
		(net "VR_PVDDQ_KLM_VREN")
	)
	(segment
		(start -0.433324 -130.480816)
		(end -0.127 -130.78714)
		(width 0.10795)
		(layer "B.Cu")
		(net "VR_PVDDQ_KLM_VREN")
	)
	(segment
		(start -0.127 -130.78714)
		(end -0.127 -131.445)
		(width 0.10795)
		(layer "B.Cu")
		(net "VR_PVDDQ_KLM_VREN")
	)
	(segment
		(start -0.889 -130.840734)
		(end -0.529082 -130.480816)
		(width 0.10795)
		(layer "B.Cu")
		(net "VR_PVDDQ_KLM_VREN")
	)
	(segment
		(start -0.529082 -130.480816)
		(end -0.433324 -130.480816)
		(width 0.10795)
		(layer "B.Cu")
		(net "VR_PVDDQ_KLM_VREN")
	)
	(segment
		(start 12.4841 -1.552448)
		(end 12.824968 -1.552448)
		(width 0.10795)
		(layer "F.Cu")
		(net "VR_PVDDQ_GHJ_VREN")
	)
	(segment
		(start 12.824968 -1.552448)
		(end 12.97686 -1.70434)
		(width 0.10795)
		(layer "F.Cu")
		(net "VR_PVDDQ_GHJ_VREN")
	)
	(segment
		(start 12.97686 -1.70434)
		(end 12.97686 -2.05232)
		(width 0.10795)
		(layer "F.Cu")
		(net "VR_PVDDQ_GHJ_VREN")
	)
	(via
		(at 12.97686 -2.05232)
		(size 0.508)
		(drill 0.254)
		(layers "F.Cu" "B.Cu")
		(net "VR_PVDDQ_GHJ_VREN")
	)
	(segment
		(start 14.195298 -1.703832)
		(end 14.195298 0.293624)
		(width 0.10795)
		(layer "B.Cu")
		(net "VR_PVDDQ_GHJ_VREN")
	)
	(segment
		(start 13.162026 -2.237486)
		(end 13.661644 -2.237486)
		(width 0.10795)
		(layer "B.Cu")
		(net "VR_PVDDQ_GHJ_VREN")
	)
	(segment
		(start 14.195298 0.293624)
		(end 14.965426 1.063752)
		(width 0.10795)
		(layer "B.Cu")
		(net "VR_PVDDQ_GHJ_VREN")
	)
	(segment
		(start 14.965426 1.063752)
		(end 14.965426 2.409952)
		(width 0.10795)
		(layer "B.Cu")
		(net "VR_PVDDQ_GHJ_VREN")
	)
	(segment
		(start 14.812264 3.099816)
		(end 14.810232 3.101848)
		(width 0.10795)
		(layer "B.Cu")
		(net "VR_PVDDQ_GHJ_VREN")
	)
	(segment
		(start 14.812264 2.563114)
		(end 14.812264 2.985516)
		(width 0.10795)
		(layer "B.Cu")
		(net "VR_PVDDQ_GHJ_VREN")
	)
	(segment
		(start 14.810232 3.101848)
		(end 14.810232 3.752342)
		(width 0.10795)
		(layer "B.Cu")
		(net "VR_PVDDQ_GHJ_VREN")
	)
	(segment
		(start 14.965426 2.409952)
		(end 14.812264 2.563114)
		(width 0.10795)
		(layer "B.Cu")
		(net "VR_PVDDQ_GHJ_VREN")
	)
	(segment
		(start 13.661644 -2.237486)
		(end 14.195298 -1.703832)
		(width 0.10795)
		(layer "B.Cu")
		(net "VR_PVDDQ_GHJ_VREN")
	)
	(segment
		(start 14.812264 2.985516)
		(end 14.812264 3.099816)
		(width 0.10795)
		(layer "B.Cu")
		(net "VR_PVDDQ_GHJ_VREN")
	)
	(segment
		(start 12.97686 -2.05232)
		(end 13.162026 -2.237486)
		(width 0.10795)
		(layer "B.Cu")
		(net "VR_PVDDQ_GHJ_VREN")
	)
	(segment
		(start 361.51947 -135.71347)
		(end 361.6452 -135.8392)
		(width 0.10795)
		(layer "F.Cu")
		(net "VR_PVDDQ_DEF_VREN")
	)
	(segment
		(start 361.098338 -135.71347)
		(end 361.51947 -135.71347)
		(width 0.10795)
		(layer "F.Cu")
		(net "VR_PVDDQ_DEF_VREN")
	)
	(via
		(at 361.6452 -135.8392)
		(size 0.508)
		(drill 0.254)
		(layers "F.Cu" "B.Cu")
		(net "VR_PVDDQ_DEF_VREN")
	)
	(segment
		(start 361.188 -135.382)
		(end 361.188 -133.9088)
		(width 0.10795)
		(layer "B.Cu")
		(net "VR_PVDDQ_DEF_VREN")
	)
	(segment
		(start 361.6452 -135.8392)
		(end 361.188 -135.382)
		(width 0.10795)
		(layer "B.Cu")
		(net "VR_PVDDQ_DEF_VREN")
	)
	(segment
		(start 362.1024 -133.9088)
		(end 361.188 -133.9088)
		(width 0.10795)
		(layer "B.Cu")
		(net "VR_PVDDQ_DEF_VREN")
	)
	(segment
		(start 342.78316 -21.78812)
		(end 342.46312 -21.78812)
		(width 0.10795)
		(layer "F.Cu")
		(net "VR_PVDDQ_ABC_VREN")
	)
	(segment
		(start 340.7156 -21.209)
		(end 340.36 -21.209)
		(width 0.10795)
		(layer "F.Cu")
		(net "VR_PVDDQ_ABC_VREN")
	)
	(segment
		(start 341.242396 -18.945352)
		(end 340.36 -19.827748)
		(width 0.10795)
		(layer "F.Cu")
		(net "VR_PVDDQ_ABC_VREN")
	)
	(segment
		(start 342.46312 -21.78812)
		(end 342.2396 -21.5646)
		(width 0.10795)
		(layer "F.Cu")
		(net "VR_PVDDQ_ABC_VREN")
	)
	(segment
		(start 340.36 -19.827748)
		(end 340.36 -21.209)
		(width 0.10795)
		(layer "F.Cu")
		(net "VR_PVDDQ_ABC_VREN")
	)
	(segment
		(start 341.0712 -21.5646)
		(end 340.7156 -21.209)
		(width 0.10795)
		(layer "F.Cu")
		(net "VR_PVDDQ_ABC_VREN")
	)
	(segment
		(start 341.772494 -21.5646)
		(end 341.0712 -21.5646)
		(width 0.10795)
		(layer "F.Cu")
		(net "VR_PVDDQ_ABC_VREN")
	)
	(segment
		(start 342.293448 -18.945352)
		(end 341.242396 -18.945352)
		(width 0.10795)
		(layer "F.Cu")
		(net "VR_PVDDQ_ABC_VREN")
	)
	(segment
		(start 342.877902 -17.8181)
		(end 342.877902 -18.360898)
		(width 0.10795)
		(layer "F.Cu")
		(net "VR_PVDDQ_ABC_VREN")
	)
	(segment
		(start 342.877902 -18.360898)
		(end 342.293448 -18.945352)
		(width 0.10795)
		(layer "F.Cu")
		(net "VR_PVDDQ_ABC_VREN")
	)
	(segment
		(start 342.2396 -21.5646)
		(end 341.772494 -21.5646)
		(width 0.10795)
		(layer "F.Cu")
		(net "VR_PVDDQ_ABC_VREN")
	)
	(via
		(at 341.772494 -21.5646)
		(size 0.508)
		(drill 0.254)
		(layers "F.Cu" "B.Cu")
		(net "VR_PVDDQ_ABC_VREN")
	)
	(segment
		(start 167.132 -69.977)
		(end 166.6494 -69.977)
		(width 0.10795)
		(layer "F.Cu")
		(net "VR_PVCCIO_CPU1_EN")
	)
	(segment
		(start 167.389302 -69.719698)
		(end 167.132 -69.977)
		(width 0.10795)
		(layer "F.Cu")
		(net "VR_PVCCIO_CPU1_EN")
	)
	(segment
		(start 167.389302 -69.2531)
		(end 167.389302 -69.719698)
		(width 0.10795)
		(layer "F.Cu")
		(net "VR_PVCCIO_CPU1_EN")
	)
	(via
		(at 166.6494 -69.977)
		(size 0.508)
		(drill 0.254)
		(layers "F.Cu" "B.Cu")
		(net "VR_PVCCIO_CPU1_EN")
	)
	(segment
		(start 166.6494 -68.0466)
		(end 165.862 -67.2592)
		(width 0.1143)
		(layer "B.Cu")
		(net "VR_PVCCIO_CPU1_EN")
	)
	(segment
		(start 165.862 -66.3702)
		(end 165.862 -67.2592)
		(width 0.1143)
		(layer "B.Cu")
		(net "VR_PVCCIO_CPU1_EN")
	)
	(segment
		(start 166.6494 -69.977)
		(end 166.6494 -68.0466)
		(width 0.1143)
		(layer "B.Cu")
		(net "VR_PVCCIO_CPU1_EN")
	)
	(via
		(at 339.4964 -82.1436)
		(size 0.6604)
		(drill 0.3302)
		(layers "F.Cu" "B.Cu")
		(net "VR_PVCCIO_CPU0_EN")
	)
	(segment
		(start 343.902538 -83.988402)
		(end 342.560148 -83.988402)
		(width 0.10795)
		(layer "B.Cu")
		(net "VR_PVCCIO_CPU0_EN")
	)
	(segment
		(start 341.63 -82.36204)
		(end 341.63 -82.7024)
		(width 0.10795)
		(layer "B.Cu")
		(net "VR_PVCCIO_CPU0_EN")
	)
	(segment
		(start 341.63 -82.7024)
		(end 341.63 -83.5914)
		(width 0.10795)
		(layer "B.Cu")
		(net "VR_PVCCIO_CPU0_EN")
	)
	(segment
		(start 342.163146 -83.5914)
		(end 341.63 -83.5914)
		(width 0.10795)
		(layer "B.Cu")
		(net "VR_PVCCIO_CPU0_EN")
	)
	(segment
		(start 344.732102 -85.0011)
		(end 344.732102 -84.817966)
		(width 0.10795)
		(layer "B.Cu")
		(net "VR_PVCCIO_CPU0_EN")
	)
	(segment
		(start 344.732102 -84.817966)
		(end 343.902538 -83.988402)
		(width 0.10795)
		(layer "B.Cu")
		(net "VR_PVCCIO_CPU0_EN")
	)
	(segment
		(start 342.560148 -83.988402)
		(end 342.163146 -83.5914)
		(width 0.10795)
		(layer "B.Cu")
		(net "VR_PVCCIO_CPU0_EN")
	)
	(segment
		(start 339.4964 -82.1436)
		(end 341.41156 -82.1436)
		(width 0.10795)
		(layer "B.Cu")
		(net "VR_PVCCIO_CPU0_EN")
	)
	(segment
		(start 341.41156 -82.1436)
		(end 341.63 -82.36204)
		(width 0.10795)
		(layer "B.Cu")
		(net "VR_PVCCIO_CPU0_EN")
	)
	(segment
		(start 16.10614 -89.756234)
		(end 15.691104 -89.341198)
		(width 0.10795)
		(layer "F.Cu")
		(net "VR_PVCCIN_CPU1_VREN")
	)
	(segment
		(start 16.312388 -90.256106)
		(end 16.10614 -90.049858)
		(width 0.10795)
		(layer "F.Cu")
		(net "VR_PVCCIN_CPU1_VREN")
	)
	(segment
		(start 16.10614 -90.049858)
		(end 16.10614 -89.756234)
		(width 0.10795)
		(layer "F.Cu")
		(net "VR_PVCCIN_CPU1_VREN")
	)
	(segment
		(start 15.691104 -89.341198)
		(end 15.504414 -89.341198)
		(width 0.10795)
		(layer "F.Cu")
		(net "VR_PVCCIN_CPU1_VREN")
	)
	(segment
		(start 16.5354 -90.256106)
		(end 16.312388 -90.256106)
		(width 0.10795)
		(layer "F.Cu")
		(net "VR_PVCCIN_CPU1_VREN")
	)
	(via
		(at 14.3764 -90.5256)
		(size 0.6604)
		(drill 0.3302)
		(layers "F.Cu" "B.Cu")
		(net "VR_PVCCIN_CPU1_VREN")
	)
	(via
		(at 15.504414 -89.341198)
		(size 0.508)
		(drill 0.254)
		(layers "F.Cu" "B.Cu")
		(net "VR_PVCCIN_CPU1_VREN")
	)
	(segment
		(start 14.732 -89.154)
		(end 14.732 -90.17)
		(width 0.1143)
		(layer "B.Cu")
		(net "VR_PVCCIN_CPU1_VREN")
	)
	(segment
		(start 15.755366 -89.281)
		(end 16.51 -89.281)
		(width 0.1143)
		(layer "B.Cu")
		(net "VR_PVCCIN_CPU1_VREN")
	)
	(segment
		(start 14.732 -89.154)
		(end 15.122398 -89.154)
		(width 0.1143)
		(layer "B.Cu")
		(net "VR_PVCCIN_CPU1_VREN")
	)
	(segment
		(start 14.732 -90.17)
		(end 14.3764 -90.5256)
		(width 0.1143)
		(layer "B.Cu")
		(net "VR_PVCCIN_CPU1_VREN")
	)
	(segment
		(start 15.504414 -89.341198)
		(end 15.695168 -89.341198)
		(width 0.1143)
		(layer "B.Cu")
		(net "VR_PVCCIN_CPU1_VREN")
	)
	(segment
		(start 15.309596 -89.341198)
		(end 15.504414 -89.341198)
		(width 0.1143)
		(layer "B.Cu")
		(net "VR_PVCCIN_CPU1_VREN")
	)
	(segment
		(start 15.122398 -89.154)
		(end 15.309596 -89.341198)
		(width 0.1143)
		(layer "B.Cu")
		(net "VR_PVCCIN_CPU1_VREN")
	)
	(segment
		(start 15.695168 -89.341198)
		(end 15.755366 -89.281)
		(width 0.1143)
		(layer "B.Cu")
		(net "VR_PVCCIN_CPU1_VREN")
	)
	(segment
		(start 181.3814 -67.650106)
		(end 181.251606 -67.650106)
		(width 0.10795)
		(layer "F.Cu")
		(net "VR_PVCCIN_CPU0_VREN")
	)
	(segment
		(start 181.251606 -67.650106)
		(end 180.51145 -66.90995)
		(width 0.10795)
		(layer "F.Cu")
		(net "VR_PVCCIN_CPU0_VREN")
	)
	(via
		(at 178.435762 -75.349862)
		(size 0.6604)
		(drill 0.3302)
		(layers "F.Cu" "B.Cu")
		(net "VR_PVCCIN_CPU0_VREN")
	)
	(via
		(at 180.51145 -66.90995)
		(size 0.508)
		(drill 0.254)
		(layers "F.Cu" "B.Cu")
		(net "VR_PVCCIN_CPU0_VREN")
	)
	(segment
		(start 180.1114 -77.1144)
		(end 179.738274 -77.487526)
		(width 0.10795)
		(layer "B.Cu")
		(net "VR_PVCCIN_CPU0_VREN")
	)
	(segment
		(start 181.0004 -76.2254)
		(end 181.0004 -76.454)
		(width 0.10795)
		(layer "B.Cu")
		(net "VR_PVCCIN_CPU0_VREN")
	)
	(segment
		(start 182.057294 -72.239632)
		(end 178.947064 -75.349862)
		(width 0.10795)
		(layer "B.Cu")
		(net "VR_PVCCIN_CPU0_VREN")
	)
	(segment
		(start 180.1114 -76.849224)
		(end 180.1114 -77.1144)
		(width 0.10795)
		(layer "B.Cu")
		(net "VR_PVCCIN_CPU0_VREN")
	)
	(segment
		(start 179.151026 -77.487526)
		(end 178.435762 -76.772262)
		(width 0.10795)
		(layer "B.Cu")
		(net "VR_PVCCIN_CPU0_VREN")
	)
	(segment
		(start 181.0004 -76.454)
		(end 180.7972 -76.6572)
		(width 0.10795)
		(layer "B.Cu")
		(net "VR_PVCCIN_CPU0_VREN")
	)
	(segment
		(start 180.51145 -66.90995)
		(end 182.057294 -68.455794)
		(width 0.10795)
		(layer "B.Cu")
		(net "VR_PVCCIN_CPU0_VREN")
	)
	(segment
		(start 182.057294 -68.455794)
		(end 182.057294 -72.239632)
		(width 0.10795)
		(layer "B.Cu")
		(net "VR_PVCCIN_CPU0_VREN")
	)
	(segment
		(start 179.738274 -77.487526)
		(end 179.151026 -77.487526)
		(width 0.10795)
		(layer "B.Cu")
		(net "VR_PVCCIN_CPU0_VREN")
	)
	(segment
		(start 180.7972 -76.6572)
		(end 180.303424 -76.6572)
		(width 0.10795)
		(layer "B.Cu")
		(net "VR_PVCCIN_CPU0_VREN")
	)
	(segment
		(start 180.303424 -76.6572)
		(end 180.1114 -76.849224)
		(width 0.10795)
		(layer "B.Cu")
		(net "VR_PVCCIN_CPU0_VREN")
	)
	(segment
		(start 178.435762 -76.772262)
		(end 178.435762 -75.349862)
		(width 0.10795)
		(layer "B.Cu")
		(net "VR_PVCCIN_CPU0_VREN")
	)
	(segment
		(start 178.947064 -75.349862)
		(end 178.435762 -75.349862)
		(width 0.10795)
		(layer "B.Cu")
		(net "VR_PVCCIN_CPU0_VREN")
	)
	(segment
		(start 395.605 -66.677794)
		(end 395.605 -66.1416)
		(width 0.10795)
		(layer "F.Cu")
		(net "VR_P5V_STBY_EN")
	)
	(segment
		(start 395.09192 -67.190874)
		(end 395.605 -66.677794)
		(width 0.10795)
		(layer "F.Cu")
		(net "VR_P5V_STBY_EN")
	)
	(segment
		(start 393.8905 -67.190874)
		(end 395.09192 -67.190874)
		(width 0.10795)
		(layer "F.Cu")
		(net "VR_P5V_STBY_EN")
	)
	(segment
		(start 465.5947 -24.0157)
		(end 465.5947 -23.0759)
		(width 0.10795)
		(layer "F.Cu")
		(net "VR_P3V3_STBY_EN")
	)
	(segment
		(start 465.6201 -23.0505)
		(end 465.5947 -23.0759)
		(width 0.10795)
		(layer "F.Cu")
		(net "VR_P3V3_STBY_EN")
	)
	(segment
		(start 466.9536 -23.0505)
		(end 465.6201 -23.0505)
		(width 0.10795)
		(layer "F.Cu")
		(net "VR_P3V3_STBY_EN")
	)
	(via
		(at 484.43896 -155.04414)
		(size 0.6604)
		(drill 0.3302)
		(layers "F.Cu" "B.Cu")
		(net "P5V_STBY_DBG")
	)
	(segment
		(start 481.3554 -151.7904)
		(end 479.2218 -151.7904)
		(width 0.254)
		(layer "B.Cu")
		(net "P5V_STBY_DBG")
	)
	(segment
		(start 482.592888 -154.917902)
		(end 482.592888 -153.027888)
		(width 0.254)
		(layer "B.Cu")
		(net "P5V_STBY_DBG")
	)
	(segment
		(start 484.312722 -154.917902)
		(end 484.43896 -155.04414)
		(width 0.254)
		(layer "B.Cu")
		(net "P5V_STBY_DBG")
	)
	(segment
		(start 479.2218 -151.7904)
		(end 478.354898 -150.923498)
		(width 0.254)
		(layer "B.Cu")
		(net "P5V_STBY_DBG")
	)
	(segment
		(start 482.592888 -153.027888)
		(end 481.3554 -151.7904)
		(width 0.254)
		(layer "B.Cu")
		(net "P5V_STBY_DBG")
	)
	(segment
		(start 478.354898 -150.923498)
		(end 478.354898 -150.459694)
		(width 0.254)
		(layer "B.Cu")
		(net "P5V_STBY_DBG")
	)
	(segment
		(start 482.592888 -154.917902)
		(end 484.312722 -154.917902)
		(width 0.254)
		(layer "B.Cu")
		(net "P5V_STBY_DBG")
	)
	(segment
		(start 478.06991 -150.174706)
		(end 477.29521 -150.174706)
		(width 0.254)
		(layer "B.Cu")
		(net "P5V_STBY_DBG")
	)
	(segment
		(start 478.354898 -150.459694)
		(end 478.06991 -150.174706)
		(width 0.254)
		(layer "B.Cu")
		(net "P5V_STBY_DBG")
	)
	(via
		(at 447.5226 -128.0414)
		(size 0.762)
		(drill 0.381)
		(layers "F.Cu" "B.Cu")
		(net "P5V_HDD_SATA")
	)
	(via
		(at 452.332852 -132.730748)
		(size 0.508)
		(drill 0.254)
		(layers "F.Cu" "B.Cu")
		(net "P12V_HDD_SATA")
	)
	(via
		(at 447.6623 -126.4793)
		(size 0.762)
		(drill 0.381)
		(layers "F.Cu" "B.Cu")
		(net "P12V_HDD_SATA")
	)
	(via
		(at 452.9836 -132.715)
		(size 0.508)
		(drill 0.254)
		(layers "F.Cu" "B.Cu")
		(net "P12V_HDD_SATA")
	)
	(segment
		(start 173.5709 -132.4864)
		(end 173.2661 -132.4864)
		(width 0.10795)
		(layer "F.Cu")
		(net "FM_PVPP_PVDDQ_CPU1_EN_KLM")
	)
	(segment
		(start 174.244 -133.349746)
		(end 174.244 -133.1595)
		(width 0.10795)
		(layer "F.Cu")
		(net "FM_PVPP_PVDDQ_CPU1_EN_KLM")
	)
	(segment
		(start 174.8409 -133.946646)
		(end 174.244 -133.349746)
		(width 0.10795)
		(layer "F.Cu")
		(net "FM_PVPP_PVDDQ_CPU1_EN_KLM")
	)
	(segment
		(start 174.8409 -134.592568)
		(end 174.8409 -133.946646)
		(width 0.10795)
		(layer "F.Cu")
		(net "FM_PVPP_PVDDQ_CPU1_EN_KLM")
	)
	(segment
		(start 174.244 -133.1595)
		(end 173.5709 -132.4864)
		(width 0.10795)
		(layer "F.Cu")
		(net "FM_PVPP_PVDDQ_CPU1_EN_KLM")
	)
	(segment
		(start 174.342298 -9.954514)
		(end 174.342298 -9.81329)
		(width 0.10795)
		(layer "F.Cu")
		(net "FM_PVPP_PVDDQ_CPU1_EN_GHJ")
	)
	(segment
		(start 173.00702 -9.19099)
		(end 173.00702 -9.17702)
		(width 0.10795)
		(layer "F.Cu")
		(net "FM_PVPP_PVDDQ_CPU1_EN_GHJ")
	)
	(segment
		(start 174.8409 -11.085068)
		(end 174.8409 -10.453116)
		(width 0.10795)
		(layer "F.Cu")
		(net "FM_PVPP_PVDDQ_CPU1_EN_GHJ")
	)
	(segment
		(start 173.501558 -9.685528)
		(end 173.00702 -9.19099)
		(width 0.10795)
		(layer "F.Cu")
		(net "FM_PVPP_PVDDQ_CPU1_EN_GHJ")
	)
	(segment
		(start 174.214536 -9.685528)
		(end 173.501558 -9.685528)
		(width 0.10795)
		(layer "F.Cu")
		(net "FM_PVPP_PVDDQ_CPU1_EN_GHJ")
	)
	(segment
		(start 174.342298 -9.81329)
		(end 174.214536 -9.685528)
		(width 0.10795)
		(layer "F.Cu")
		(net "FM_PVPP_PVDDQ_CPU1_EN_GHJ")
	)
	(segment
		(start 174.8409 -10.453116)
		(end 174.342298 -9.954514)
		(width 0.10795)
		(layer "F.Cu")
		(net "FM_PVPP_PVDDQ_CPU1_EN_GHJ")
	)
	(segment
		(start 173.00702 -9.17702)
		(end 172.5422 -8.7122)
		(width 0.10795)
		(layer "F.Cu")
		(net "FM_PVPP_PVDDQ_CPU1_EN_GHJ")
	)
	(segment
		(start 172.5422 -8.7122)
		(end 172.5422 -8.6868)
		(width 0.10795)
		(layer "F.Cu")
		(net "FM_PVPP_PVDDQ_CPU1_EN_GHJ")
	)
	(segment
		(start 340.742016 -130.604768)
		(end 339.981032 -129.843784)
		(width 0.10795)
		(layer "F.Cu")
		(net "FM_PVPP_PVDDQ_CPU0_EN_DEF")
	)
	(segment
		(start 341.2109 -130.604768)
		(end 340.742016 -130.604768)
		(width 0.10795)
		(layer "F.Cu")
		(net "FM_PVPP_PVDDQ_CPU0_EN_DEF")
	)
	(segment
		(start 339.981032 -129.843784)
		(end 339.981032 -129.587498)
		(width 0.10795)
		(layer "F.Cu")
		(net "FM_PVPP_PVDDQ_CPU0_EN_DEF")
	)
	(segment
		(start 341.695278 -24.508206)
		(end 341.695278 -25.4)
		(width 0.10795)
		(layer "F.Cu")
		(net "FM_PVPP_PVDDQ_CPU0_EN_ABC")
	)
	(segment
		(start 342.034368 -26.312368)
		(end 341.695278 -25.973278)
		(width 0.10795)
		(layer "F.Cu")
		(net "FM_PVPP_PVDDQ_CPU0_EN_ABC")
	)
	(segment
		(start 342.5317 -26.312368)
		(end 342.034368 -26.312368)
		(width 0.10795)
		(layer "F.Cu")
		(net "FM_PVPP_PVDDQ_CPU0_EN_ABC")
	)
	(segment
		(start 341.695278 -25.973278)
		(end 341.695278 -25.4)
		(width 0.10795)
		(layer "F.Cu")
		(net "FM_PVPP_PVDDQ_CPU0_EN_ABC")
	)
	(via
		(at 341.695278 -25.4)
		(size 0.508)
		(drill 0.254)
		(layers "F.Cu" "B.Cu")
		(net "FM_PVPP_PVDDQ_CPU0_EN_ABC")
	)
	(segment
		(start 444.8048 -0.1778)
		(end 445.769746 -0.1778)
		(width 0.10795)
		(layer "F.Cu")
		(net "FM_CPLD_UART_CH_LOCK_N")
	)
	(segment
		(start 444.0936 0.5334)
		(end 444.8048 -0.1778)
		(width 0.10795)
		(layer "F.Cu")
		(net "FM_CPLD_UART_CH_LOCK_N")
	)
	(segment
		(start 371.945154 -77.494892)
		(end 372.34495 -77.095096)
		(width 0.1016)
		(layer "F.Cu")
		(net "FM_CPLD_UART_CH_LOCK_N")
	)
	(segment
		(start 445.769746 -0.1778)
		(end 446.0875 -0.495554)
		(width 0.10795)
		(layer "F.Cu")
		(net "FM_CPLD_UART_CH_LOCK_N")
	)
	(segment
		(start 446.0875 -0.495554)
		(end 446.0875 -1.143)
		(width 0.10795)
		(layer "F.Cu")
		(net "FM_CPLD_UART_CH_LOCK_N")
	)
	(segment
		(start 444.0936 2.5654)
		(end 444.0936 0.5334)
		(width 0.10795)
		(layer "F.Cu")
		(net "FM_CPLD_UART_CH_LOCK_N")
	)
	(segment
		(start 442.849762 3.81)
		(end 442.849 3.81)
		(width 0.10795)
		(layer "F.Cu")
		(net "FM_CPLD_UART_CH_LOCK_N")
	)
	(segment
		(start 442.849 3.81)
		(end 444.0936 2.5654)
		(width 0.10795)
		(layer "F.Cu")
		(net "FM_CPLD_UART_CH_LOCK_N")
	)
	(segment
		(start 446.0875 -2.114804)
		(end 445.897 -2.305304)
		(width 0.10795)
		(layer "F.Cu")
		(net "FM_CPLD_UART_CH_LOCK_N")
	)
	(segment
		(start 446.0875 -1.143)
		(end 446.0875 -2.114804)
		(width 0.10795)
		(layer "F.Cu")
		(net "FM_CPLD_UART_CH_LOCK_N")
	)
	(via
		(at 412.964884 -72.683116)
		(size 0.508)
		(drill 0.254)
		(layers "F.Cu" "B.Cu")
		(net "FM_CPLD_UART_CH_LOCK_N")
	)
	(via
		(at 477.265238 -9.536684)
		(size 0.508)
		(drill 0.254)
		(layers "F.Cu" "B.Cu")
		(net "FM_CPLD_UART_CH_LOCK_N")
	)
	(via
		(at 487.208322 -55.841392)
		(size 0.508)
		(drill 0.254)
		(layers "F.Cu" "B.Cu")
		(net "FM_CPLD_UART_CH_LOCK_N")
	)
	(via
		(at 445.897 -2.305304)
		(size 0.508)
		(drill 0.254)
		(layers "F.Cu" "B.Cu")
		(net "FM_CPLD_UART_CH_LOCK_N")
	)
	(via
		(at 475.440248 -9.928352)
		(size 0.6604)
		(drill 0.3302)
		(layers "F.Cu" "B.Cu")
		(net "FM_CPLD_UART_CH_LOCK_N")
	)
	(via
		(at 371.945154 -77.494892)
		(size 0.4572)
		(drill 0.2032)
		(layers "F.Cu" "B.Cu")
		(net "FM_CPLD_UART_CH_LOCK_N")
	)
	(segment
		(start 476.873316 -9.536684)
		(end 476.481648 -9.928352)
		(width 0.10795)
		(layer "B.Cu")
		(net "FM_CPLD_UART_CH_LOCK_N")
	)
	(segment
		(start 476.481648 -9.928352)
		(end 475.440248 -9.928352)
		(width 0.10795)
		(layer "B.Cu")
		(net "FM_CPLD_UART_CH_LOCK_N")
	)
	(segment
		(start 477.265238 -9.536684)
		(end 476.873316 -9.536684)
		(width 0.10795)
		(layer "B.Cu")
		(net "FM_CPLD_UART_CH_LOCK_N")
	)
	(segment
		(start 467.47811 -56.647842)
		(end 469.600788 -54.525164)
		(width 0.089408)
		(layer "In2.Cu")
		(net "FM_CPLD_UART_CH_LOCK_N")
	)
	(segment
		(start 422.398952 -55.52186)
		(end 428.603918 -55.52186)
		(width 0.089408)
		(layer "In2.Cu")
		(net "FM_CPLD_UART_CH_LOCK_N")
	)
	(segment
		(start 471.37447 -54.525164)
		(end 472.680538 -53.219096)
		(width 0.089408)
		(layer "In2.Cu")
		(net "FM_CPLD_UART_CH_LOCK_N")
	)
	(segment
		(start 462.726786 -6.882892)
		(end 463.68843 -6.882892)
		(width 0.089408)
		(layer "In2.Cu")
		(net "FM_CPLD_UART_CH_LOCK_N")
	)
	(segment
		(start 486.148126 -54.781196)
		(end 487.208322 -55.841392)
		(width 0.089408)
		(layer "In2.Cu")
		(net "FM_CPLD_UART_CH_LOCK_N")
	)
	(segment
		(start 451.80377 -0.367792)
		(end 456.212194 -0.367792)
		(width 0.089408)
		(layer "In2.Cu")
		(net "FM_CPLD_UART_CH_LOCK_N")
	)
	(segment
		(start 463.259932 -55.919116)
		(end 463.988658 -56.647842)
		(width 0.089408)
		(layer "In2.Cu")
		(net "FM_CPLD_UART_CH_LOCK_N")
	)
	(segment
		(start 467.028276 -8.659876)
		(end 467.2076 -8.8392)
		(width 0.089408)
		(layer "In2.Cu")
		(net "FM_CPLD_UART_CH_LOCK_N")
	)
	(segment
		(start 428.603918 -55.52186)
		(end 429.744886 -54.380892)
		(width 0.089408)
		(layer "In2.Cu")
		(net "FM_CPLD_UART_CH_LOCK_N")
	)
	(segment
		(start 472.680538 -53.219096)
		(end 474.151706 -53.219096)
		(width 0.089408)
		(layer "In2.Cu")
		(net "FM_CPLD_UART_CH_LOCK_N")
	)
	(segment
		(start 461.935576 -1.307846)
		(end 462.794096 -2.166366)
		(width 0.089408)
		(layer "In2.Cu")
		(net "FM_CPLD_UART_CH_LOCK_N")
	)
	(segment
		(start 459.91272 -0.596392)
		(end 460.624174 -1.307846)
		(width 0.089408)
		(layer "In2.Cu")
		(net "FM_CPLD_UART_CH_LOCK_N")
	)
	(segment
		(start 469.600788 -54.525164)
		(end 471.37447 -54.525164)
		(width 0.089408)
		(layer "In2.Cu")
		(net "FM_CPLD_UART_CH_LOCK_N")
	)
	(segment
		(start 412.994602 -71.783448)
		(end 412.994602 -71.308468)
		(width 0.089408)
		(layer "In2.Cu")
		(net "FM_CPLD_UART_CH_LOCK_N")
	)
	(segment
		(start 413.639 -70.015354)
		(end 413.639 -68.58)
		(width 0.089408)
		(layer "In2.Cu")
		(net "FM_CPLD_UART_CH_LOCK_N")
	)
	(segment
		(start 450.83984 -1.173734)
		(end 450.997828 -1.173734)
		(width 0.089408)
		(layer "In2.Cu")
		(net "FM_CPLD_UART_CH_LOCK_N")
	)
	(segment
		(start 473.917264 -8.072882)
		(end 474.679772 -8.83539)
		(width 0.089408)
		(layer "In2.Cu")
		(net "FM_CPLD_UART_CH_LOCK_N")
	)
	(segment
		(start 436.511446 -55.919116)
		(end 463.259932 -55.919116)
		(width 0.089408)
		(layer "In2.Cu")
		(net "FM_CPLD_UART_CH_LOCK_N")
	)
	(segment
		(start 474.151706 -53.219096)
		(end 474.335602 -53.402992)
		(width 0.089408)
		(layer "In2.Cu")
		(net "FM_CPLD_UART_CH_LOCK_N")
	)
	(segment
		(start 467.42985 -9.427464)
		(end 470.008458 -9.427464)
		(width 0.089408)
		(layer "In2.Cu")
		(net "FM_CPLD_UART_CH_LOCK_N")
	)
	(segment
		(start 463.06105 -4.09575)
		(end 461.8228 -5.334)
		(width 0.089408)
		(layer "In2.Cu")
		(net "FM_CPLD_UART_CH_LOCK_N")
	)
	(segment
		(start 415.654998 -60.335668)
		(end 416.288474 -60.335668)
		(width 0.089408)
		(layer "In2.Cu")
		(net "FM_CPLD_UART_CH_LOCK_N")
	)
	(segment
		(start 412.994856 -71.783702)
		(end 412.994602 -71.783448)
		(width 0.089408)
		(layer "In2.Cu")
		(net "FM_CPLD_UART_CH_LOCK_N")
	)
	(segment
		(start 412.994856 -70.659498)
		(end 413.639 -70.015354)
		(width 0.089408)
		(layer "In2.Cu")
		(net "FM_CPLD_UART_CH_LOCK_N")
	)
	(segment
		(start 416.288474 -60.335668)
		(end 416.288728 -60.335922)
		(width 0.089408)
		(layer "In2.Cu")
		(net "FM_CPLD_UART_CH_LOCK_N")
	)
	(segment
		(start 477.625664 -52.615592)
		(end 479.868484 -52.615592)
		(width 0.089408)
		(layer "In2.Cu")
		(net "FM_CPLD_UART_CH_LOCK_N")
	)
	(segment
		(start 467.2076 -8.8392)
		(end 467.2076 -9.205214)
		(width 0.089408)
		(layer "In2.Cu")
		(net "FM_CPLD_UART_CH_LOCK_N")
	)
	(segment
		(start 462.794096 -2.446782)
		(end 463.06105 -2.713736)
		(width 0.089408)
		(layer "In2.Cu")
		(net "FM_CPLD_UART_CH_LOCK_N")
	)
	(segment
		(start 463.68843 -6.882892)
		(end 465.465414 -8.659876)
		(width 0.089408)
		(layer "In2.Cu")
		(net "FM_CPLD_UART_CH_LOCK_N")
	)
	(segment
		(start 461.8228 -5.978906)
		(end 462.726786 -6.882892)
		(width 0.089408)
		(layer "In2.Cu")
		(net "FM_CPLD_UART_CH_LOCK_N")
	)
	(segment
		(start 462.794096 -2.166366)
		(end 462.794096 -2.446782)
		(width 0.089408)
		(layer "In2.Cu")
		(net "FM_CPLD_UART_CH_LOCK_N")
	)
	(segment
		(start 476.563944 -8.83539)
		(end 477.265238 -9.536684)
		(width 0.089408)
		(layer "In2.Cu")
		(net "FM_CPLD_UART_CH_LOCK_N")
	)
	(segment
		(start 467.2076 -9.205214)
		(end 467.42985 -9.427464)
		(width 0.089408)
		(layer "In2.Cu")
		(net "FM_CPLD_UART_CH_LOCK_N")
	)
	(segment
		(start 483.25405 -54.781196)
		(end 486.148126 -54.781196)
		(width 0.089408)
		(layer "In2.Cu")
		(net "FM_CPLD_UART_CH_LOCK_N")
	)
	(segment
		(start 434.973222 -54.380892)
		(end 436.511446 -55.919116)
		(width 0.089408)
		(layer "In2.Cu")
		(net "FM_CPLD_UART_CH_LOCK_N")
	)
	(segment
		(start 470.777062 -8.072882)
		(end 473.917264 -8.072882)
		(width 0.089408)
		(layer "In2.Cu")
		(net "FM_CPLD_UART_CH_LOCK_N")
	)
	(segment
		(start 480.883468 -53.630576)
		(end 482.10343 -53.630576)
		(width 0.089408)
		(layer "In2.Cu")
		(net "FM_CPLD_UART_CH_LOCK_N")
	)
	(segment
		(start 447.028824 -1.17348)
		(end 450.839586 -1.17348)
		(width 0.089408)
		(layer "In2.Cu")
		(net "FM_CPLD_UART_CH_LOCK_N")
	)
	(segment
		(start 479.868484 -52.615592)
		(end 480.883468 -53.630576)
		(width 0.089408)
		(layer "In2.Cu")
		(net "FM_CPLD_UART_CH_LOCK_N")
	)
	(segment
		(start 412.994856 -71.308214)
		(end 412.994856 -70.659498)
		(width 0.089408)
		(layer "In2.Cu")
		(net "FM_CPLD_UART_CH_LOCK_N")
	)
	(segment
		(start 474.335602 -53.402992)
		(end 476.838264 -53.402992)
		(width 0.089408)
		(layer "In2.Cu")
		(net "FM_CPLD_UART_CH_LOCK_N")
	)
	(segment
		(start 412.994856 -72.653144)
		(end 412.994856 -71.783702)
		(width 0.089408)
		(layer "In2.Cu")
		(net "FM_CPLD_UART_CH_LOCK_N")
	)
	(segment
		(start 470.321386 -8.528558)
		(end 470.777062 -8.072882)
		(width 0.089408)
		(layer "In2.Cu")
		(net "FM_CPLD_UART_CH_LOCK_N")
	)
	(segment
		(start 414.30448 -67.91452)
		(end 414.30448 -61.686186)
		(width 0.089408)
		(layer "In2.Cu")
		(net "FM_CPLD_UART_CH_LOCK_N")
	)
	(segment
		(start 412.964884 -72.683116)
		(end 412.994856 -72.653144)
		(width 0.089408)
		(layer "In2.Cu")
		(net "FM_CPLD_UART_CH_LOCK_N")
	)
	(segment
		(start 416.288728 -60.335922)
		(end 417.58489 -60.335922)
		(width 0.089408)
		(layer "In2.Cu")
		(net "FM_CPLD_UART_CH_LOCK_N")
	)
	(segment
		(start 456.212194 -0.367792)
		(end 456.440794 -0.596392)
		(width 0.089408)
		(layer "In2.Cu")
		(net "FM_CPLD_UART_CH_LOCK_N")
	)
	(segment
		(start 450.997828 -1.173734)
		(end 451.80377 -0.367792)
		(width 0.089408)
		(layer "In2.Cu")
		(net "FM_CPLD_UART_CH_LOCK_N")
	)
	(segment
		(start 463.06105 -2.713736)
		(end 463.06105 -4.09575)
		(width 0.089408)
		(layer "In2.Cu")
		(net "FM_CPLD_UART_CH_LOCK_N")
	)
	(segment
		(start 470.321386 -9.114536)
		(end 470.321386 -8.528558)
		(width 0.089408)
		(layer "In2.Cu")
		(net "FM_CPLD_UART_CH_LOCK_N")
	)
	(segment
		(start 460.624174 -1.307846)
		(end 461.935576 -1.307846)
		(width 0.089408)
		(layer "In2.Cu")
		(net "FM_CPLD_UART_CH_LOCK_N")
	)
	(segment
		(start 465.465414 -8.659876)
		(end 467.028276 -8.659876)
		(width 0.089408)
		(layer "In2.Cu")
		(net "FM_CPLD_UART_CH_LOCK_N")
	)
	(segment
		(start 476.838264 -53.402992)
		(end 477.625664 -52.615592)
		(width 0.089408)
		(layer "In2.Cu")
		(net "FM_CPLD_UART_CH_LOCK_N")
	)
	(segment
		(start 429.744886 -54.380892)
		(end 434.973222 -54.380892)
		(width 0.089408)
		(layer "In2.Cu")
		(net "FM_CPLD_UART_CH_LOCK_N")
	)
	(segment
		(start 461.8228 -5.334)
		(end 461.8228 -5.978906)
		(width 0.089408)
		(layer "In2.Cu")
		(net "FM_CPLD_UART_CH_LOCK_N")
	)
	(segment
		(start 482.10343 -53.630576)
		(end 483.25405 -54.781196)
		(width 0.089408)
		(layer "In2.Cu")
		(net "FM_CPLD_UART_CH_LOCK_N")
	)
	(segment
		(start 474.679772 -8.83539)
		(end 476.563944 -8.83539)
		(width 0.089408)
		(layer "In2.Cu")
		(net "FM_CPLD_UART_CH_LOCK_N")
	)
	(segment
		(start 463.988658 -56.647842)
		(end 467.47811 -56.647842)
		(width 0.089408)
		(layer "In2.Cu")
		(net "FM_CPLD_UART_CH_LOCK_N")
	)
	(segment
		(start 445.897 -2.305304)
		(end 447.028824 -1.17348)
		(width 0.089408)
		(layer "In2.Cu")
		(net "FM_CPLD_UART_CH_LOCK_N")
	)
	(segment
		(start 450.839586 -1.17348)
		(end 450.83984 -1.173734)
		(width 0.089408)
		(layer "In2.Cu")
		(net "FM_CPLD_UART_CH_LOCK_N")
	)
	(segment
		(start 414.30448 -61.686186)
		(end 415.654998 -60.335668)
		(width 0.089408)
		(layer "In2.Cu")
		(net "FM_CPLD_UART_CH_LOCK_N")
	)
	(segment
		(start 456.440794 -0.596392)
		(end 459.91272 -0.596392)
		(width 0.089408)
		(layer "In2.Cu")
		(net "FM_CPLD_UART_CH_LOCK_N")
	)
	(segment
		(start 417.58489 -60.335922)
		(end 422.398952 -55.52186)
		(width 0.089408)
		(layer "In2.Cu")
		(net "FM_CPLD_UART_CH_LOCK_N")
	)
	(segment
		(start 413.639 -68.58)
		(end 414.30448 -67.91452)
		(width 0.089408)
		(layer "In2.Cu")
		(net "FM_CPLD_UART_CH_LOCK_N")
	)
	(segment
		(start 470.008458 -9.427464)
		(end 470.321386 -9.114536)
		(width 0.089408)
		(layer "In2.Cu")
		(net "FM_CPLD_UART_CH_LOCK_N")
	)
	(segment
		(start 412.994602 -71.308468)
		(end 412.994856 -71.308214)
		(width 0.089408)
		(layer "In2.Cu")
		(net "FM_CPLD_UART_CH_LOCK_N")
	)
	(segment
		(start 407.297636 -73.008744)
		(end 412.639256 -73.008744)
		(width 0.089408)
		(layer "In4.Cu")
		(net "FM_CPLD_UART_CH_LOCK_N")
	)
	(segment
		(start 400.64309 -75.81011)
		(end 401.412456 -75.040744)
		(width 0.089408)
		(layer "In4.Cu")
		(net "FM_CPLD_UART_CH_LOCK_N")
	)
	(segment
		(start 390.569958 -77.882496)
		(end 391.511536 -76.940918)
		(width 0.089408)
		(layer "In4.Cu")
		(net "FM_CPLD_UART_CH_LOCK_N")
	)
	(segment
		(start 373.936768 -78.41488)
		(end 374.233694 -78.711806)
		(width 0.089408)
		(layer "In4.Cu")
		(net "FM_CPLD_UART_CH_LOCK_N")
	)
	(segment
		(start 389.024114 -77.882496)
		(end 390.569958 -77.882496)
		(width 0.089408)
		(layer "In4.Cu")
		(net "FM_CPLD_UART_CH_LOCK_N")
	)
	(segment
		(start 374.7643 -79.242412)
		(end 375.028206 -79.506318)
		(width 0.089408)
		(layer "In4.Cu")
		(net "FM_CPLD_UART_CH_LOCK_N")
	)
	(segment
		(start 381.434594 -77.677772)
		(end 381.97409 -77.138276)
		(width 0.089408)
		(layer "In4.Cu")
		(net "FM_CPLD_UART_CH_LOCK_N")
	)
	(segment
		(start 401.715224 -74.737976)
		(end 402.952712 -73.500488)
		(width 0.089408)
		(layer "In4.Cu")
		(net "FM_CPLD_UART_CH_LOCK_N")
	)
	(segment
		(start 401.412456 -74.972418)
		(end 401.646898 -74.737976)
		(width 0.089408)
		(layer "In4.Cu")
		(net "FM_CPLD_UART_CH_LOCK_N")
	)
	(segment
		(start 392.053826 -76.940918)
		(end 392.613896 -76.380848)
		(width 0.089408)
		(layer "In4.Cu")
		(net "FM_CPLD_UART_CH_LOCK_N")
	)
	(segment
		(start 401.412456 -75.040744)
		(end 401.412456 -74.972418)
		(width 0.089408)
		(layer "In4.Cu")
		(net "FM_CPLD_UART_CH_LOCK_N")
	)
	(segment
		(start 381.97409 -77.138276)
		(end 386.293614 -77.138276)
		(width 0.089408)
		(layer "In4.Cu")
		(net "FM_CPLD_UART_CH_LOCK_N")
	)
	(segment
		(start 380.236476 -79.506318)
		(end 381.434594 -78.3082)
		(width 0.089408)
		(layer "In4.Cu")
		(net "FM_CPLD_UART_CH_LOCK_N")
	)
	(segment
		(start 386.535422 -77.380084)
		(end 388.521702 -77.380084)
		(width 0.089408)
		(layer "In4.Cu")
		(net "FM_CPLD_UART_CH_LOCK_N")
	)
	(segment
		(start 373.936768 -78.158594)
		(end 373.936768 -78.41488)
		(width 0.089408)
		(layer "In4.Cu")
		(net "FM_CPLD_UART_CH_LOCK_N")
	)
	(segment
		(start 412.639256 -73.008744)
		(end 412.964884 -72.683116)
		(width 0.089408)
		(layer "In4.Cu")
		(net "FM_CPLD_UART_CH_LOCK_N")
	)
	(segment
		(start 386.293614 -77.138276)
		(end 386.535422 -77.380084)
		(width 0.089408)
		(layer "In4.Cu")
		(net "FM_CPLD_UART_CH_LOCK_N")
	)
	(segment
		(start 373.067326 -77.868272)
		(end 373.646446 -77.868272)
		(width 0.089408)
		(layer "In4.Cu")
		(net "FM_CPLD_UART_CH_LOCK_N")
	)
	(segment
		(start 381.434594 -78.3082)
		(end 381.434594 -77.677772)
		(width 0.089408)
		(layer "In4.Cu")
		(net "FM_CPLD_UART_CH_LOCK_N")
	)
	(segment
		(start 374.7643 -78.98638)
		(end 374.7643 -79.242412)
		(width 0.089408)
		(layer "In4.Cu")
		(net "FM_CPLD_UART_CH_LOCK_N")
	)
	(segment
		(start 391.511536 -76.940918)
		(end 392.053826 -76.940918)
		(width 0.089408)
		(layer "In4.Cu")
		(net "FM_CPLD_UART_CH_LOCK_N")
	)
	(segment
		(start 371.945154 -77.494892)
		(end 372.693946 -77.494892)
		(width 0.089408)
		(layer "In4.Cu")
		(net "FM_CPLD_UART_CH_LOCK_N")
	)
	(segment
		(start 373.646446 -77.868272)
		(end 373.936768 -78.158594)
		(width 0.089408)
		(layer "In4.Cu")
		(net "FM_CPLD_UART_CH_LOCK_N")
	)
	(segment
		(start 396.381986 -75.81011)
		(end 400.64309 -75.81011)
		(width 0.089408)
		(layer "In4.Cu")
		(net "FM_CPLD_UART_CH_LOCK_N")
	)
	(segment
		(start 375.028206 -79.506318)
		(end 380.236476 -79.506318)
		(width 0.089408)
		(layer "In4.Cu")
		(net "FM_CPLD_UART_CH_LOCK_N")
	)
	(segment
		(start 388.521702 -77.380084)
		(end 389.024114 -77.882496)
		(width 0.089408)
		(layer "In4.Cu")
		(net "FM_CPLD_UART_CH_LOCK_N")
	)
	(segment
		(start 395.811248 -76.380848)
		(end 396.381986 -75.81011)
		(width 0.089408)
		(layer "In4.Cu")
		(net "FM_CPLD_UART_CH_LOCK_N")
	)
	(segment
		(start 372.693946 -77.494892)
		(end 373.067326 -77.868272)
		(width 0.089408)
		(layer "In4.Cu")
		(net "FM_CPLD_UART_CH_LOCK_N")
	)
	(segment
		(start 374.489726 -78.711806)
		(end 374.7643 -78.98638)
		(width 0.089408)
		(layer "In4.Cu")
		(net "FM_CPLD_UART_CH_LOCK_N")
	)
	(segment
		(start 402.952712 -73.500488)
		(end 406.805892 -73.500488)
		(width 0.089408)
		(layer "In4.Cu")
		(net "FM_CPLD_UART_CH_LOCK_N")
	)
	(segment
		(start 401.646898 -74.737976)
		(end 401.715224 -74.737976)
		(width 0.089408)
		(layer "In4.Cu")
		(net "FM_CPLD_UART_CH_LOCK_N")
	)
	(segment
		(start 374.233694 -78.711806)
		(end 374.489726 -78.711806)
		(width 0.089408)
		(layer "In4.Cu")
		(net "FM_CPLD_UART_CH_LOCK_N")
	)
	(segment
		(start 406.805892 -73.500488)
		(end 407.297636 -73.008744)
		(width 0.089408)
		(layer "In4.Cu")
		(net "FM_CPLD_UART_CH_LOCK_N")
	)
	(segment
		(start 392.613896 -76.380848)
		(end 395.811248 -76.380848)
		(width 0.089408)
		(layer "In4.Cu")
		(net "FM_CPLD_UART_CH_LOCK_N")
	)
	(segment
		(start 477.265238 -9.536684)
		(end 478.663 -10.934446)
		(width 0.089408)
		(layer "In9.Cu")
		(net "FM_CPLD_UART_CH_LOCK_N")
	)
	(segment
		(start 490.389164 -48.904398)
		(end 490.389164 -49.236122)
		(width 0.089408)
		(layer "In9.Cu")
		(net "FM_CPLD_UART_CH_LOCK_N")
	)
	(segment
		(start 487.66857 -20.667218)
		(end 487.66857 -31.40329)
		(width 0.089408)
		(layer "In9.Cu")
		(net "FM_CPLD_UART_CH_LOCK_N")
	)
	(segment
		(start 490.0676 -35.775392)
		(end 490.0676 -39.0144)
		(width 0.089408)
		(layer "In9.Cu")
		(net "FM_CPLD_UART_CH_LOCK_N")
	)
	(segment
		(start 489.214668 -39.236142)
		(end 488.359196 -40.091614)
		(width 0.089408)
		(layer "In9.Cu")
		(net "FM_CPLD_UART_CH_LOCK_N")
	)
	(segment
		(start 478.663 -15.96263)
		(end 480.12477 -17.4244)
		(width 0.089408)
		(layer "In9.Cu")
		(net "FM_CPLD_UART_CH_LOCK_N")
	)
	(segment
		(start 487.22661 -55.85968)
		(end 487.22661 -55.841392)
		(width 0.089408)
		(layer "In9.Cu")
		(net "FM_CPLD_UART_CH_LOCK_N")
	)
	(segment
		(start 487.868976 -52.66563)
		(end 487.868976 -55.217314)
		(width 0.089408)
		(layer "In9.Cu")
		(net "FM_CPLD_UART_CH_LOCK_N")
	)
	(segment
		(start 490.0676 -39.0144)
		(end 489.845858 -39.236142)
		(width 0.089408)
		(layer "In9.Cu")
		(net "FM_CPLD_UART_CH_LOCK_N")
	)
	(segment
		(start 488.359196 -46.87443)
		(end 490.389164 -48.904398)
		(width 0.089408)
		(layer "In9.Cu")
		(net "FM_CPLD_UART_CH_LOCK_N")
	)
	(segment
		(start 489.058204 -32.792924)
		(end 489.058204 -34.765996)
		(width 0.089408)
		(layer "In9.Cu")
		(net "FM_CPLD_UART_CH_LOCK_N")
	)
	(segment
		(start 489.100114 -51.434492)
		(end 487.868976 -52.66563)
		(width 0.089408)
		(layer "In9.Cu")
		(net "FM_CPLD_UART_CH_LOCK_N")
	)
	(segment
		(start 488.359196 -40.091614)
		(end 488.359196 -46.87443)
		(width 0.089408)
		(layer "In9.Cu")
		(net "FM_CPLD_UART_CH_LOCK_N")
	)
	(segment
		(start 480.12477 -17.4244)
		(end 482.346 -17.4244)
		(width 0.089408)
		(layer "In9.Cu")
		(net "FM_CPLD_UART_CH_LOCK_N")
	)
	(segment
		(start 487.868976 -55.217314)
		(end 487.22661 -55.85968)
		(width 0.089408)
		(layer "In9.Cu")
		(net "FM_CPLD_UART_CH_LOCK_N")
	)
	(segment
		(start 487.66857 -31.40329)
		(end 489.058204 -32.792924)
		(width 0.089408)
		(layer "In9.Cu")
		(net "FM_CPLD_UART_CH_LOCK_N")
	)
	(segment
		(start 489.058204 -34.765996)
		(end 490.0676 -35.775392)
		(width 0.089408)
		(layer "In9.Cu")
		(net "FM_CPLD_UART_CH_LOCK_N")
	)
	(segment
		(start 490.389164 -49.236122)
		(end 489.100114 -50.525172)
		(width 0.089408)
		(layer "In9.Cu")
		(net "FM_CPLD_UART_CH_LOCK_N")
	)
	(segment
		(start 489.100114 -50.525172)
		(end 489.100114 -51.434492)
		(width 0.089408)
		(layer "In9.Cu")
		(net "FM_CPLD_UART_CH_LOCK_N")
	)
	(segment
		(start 478.663 -10.934446)
		(end 478.663 -15.96263)
		(width 0.089408)
		(layer "In9.Cu")
		(net "FM_CPLD_UART_CH_LOCK_N")
	)
	(segment
		(start 482.959156 -18.037556)
		(end 485.038908 -18.037556)
		(width 0.089408)
		(layer "In9.Cu")
		(net "FM_CPLD_UART_CH_LOCK_N")
	)
	(segment
		(start 485.038908 -18.037556)
		(end 487.66857 -20.667218)
		(width 0.089408)
		(layer "In9.Cu")
		(net "FM_CPLD_UART_CH_LOCK_N")
	)
	(segment
		(start 487.22661 -55.841392)
		(end 487.208322 -55.841392)
		(width 0.089408)
		(layer "In9.Cu")
		(net "FM_CPLD_UART_CH_LOCK_N")
	)
	(segment
		(start 482.346 -17.4244)
		(end 482.959156 -18.037556)
		(width 0.089408)
		(layer "In9.Cu")
		(net "FM_CPLD_UART_CH_LOCK_N")
	)
	(segment
		(start 489.845858 -39.236142)
		(end 489.214668 -39.236142)
		(width 0.089408)
		(layer "In9.Cu")
		(net "FM_CPLD_UART_CH_LOCK_N")
	)
	(segment
		(start 477.978724 -150.256494)
		(end 477.978724 -151.436324)
		(width 0.10795)
		(layer "F.Cu")
		(net "FM_CPLD_DBG_PWR_EN_N")
	)
	(segment
		(start 479.298 -156.845)
		(end 480.550728 -158.097728)
		(width 0.10795)
		(layer "F.Cu")
		(net "FM_CPLD_DBG_PWR_EN_N")
	)
	(segment
		(start 373.34063 -81.060798)
		(end 373.34063 -80.490568)
		(width 0.10795)
		(layer "F.Cu")
		(net "FM_CPLD_DBG_PWR_EN_N")
	)
	(segment
		(start 375.817892 -81.872074)
		(end 375.697496 -81.751678)
		(width 0.10795)
		(layer "F.Cu")
		(net "FM_CPLD_DBG_PWR_EN_N")
	)
	(segment
		(start 381.410464 -83.36915)
		(end 380.810008 -83.36915)
		(width 0.10795)
		(layer "F.Cu")
		(net "FM_CPLD_DBG_PWR_EN_N")
	)
	(segment
		(start 387.249924 -83.593432)
		(end 386.32638 -83.593432)
		(width 0.10795)
		(layer "F.Cu")
		(net "FM_CPLD_DBG_PWR_EN_N")
	)
	(segment
		(start 381.457454 -83.41614)
		(end 381.410464 -83.36915)
		(width 0.10795)
		(layer "F.Cu")
		(net "FM_CPLD_DBG_PWR_EN_N")
	)
	(segment
		(start 479.0948 -152.5524)
		(end 479.0948 -153.234136)
		(width 0.10795)
		(layer "F.Cu")
		(net "FM_CPLD_DBG_PWR_EN_N")
	)
	(segment
		(start 386.32638 -83.593432)
		(end 385.651502 -84.26831)
		(width 0.10795)
		(layer "F.Cu")
		(net "FM_CPLD_DBG_PWR_EN_N")
	)
	(segment
		(start 383.414524 -84.415122)
		(end 382.415542 -83.41614)
		(width 0.10795)
		(layer "F.Cu")
		(net "FM_CPLD_DBG_PWR_EN_N")
	)
	(segment
		(start 480.550728 -158.097728)
		(end 497.692172 -158.097728)
		(width 0.10795)
		(layer "F.Cu")
		(net "FM_CPLD_DBG_PWR_EN_N")
	)
	(segment
		(start 385.255516 -84.26831)
		(end 385.108704 -84.415122)
		(width 0.10795)
		(layer "F.Cu")
		(net "FM_CPLD_DBG_PWR_EN_N")
	)
	(segment
		(start 382.415542 -83.41614)
		(end 381.457454 -83.41614)
		(width 0.10795)
		(layer "F.Cu")
		(net "FM_CPLD_DBG_PWR_EN_N")
	)
	(segment
		(start 387.362954 -83.706462)
		(end 387.249924 -83.593432)
		(width 0.10795)
		(layer "F.Cu")
		(net "FM_CPLD_DBG_PWR_EN_N")
	)
	(segment
		(start 479.0948 -153.234136)
		(end 479.298 -153.437336)
		(width 0.10795)
		(layer "F.Cu")
		(net "FM_CPLD_DBG_PWR_EN_N")
	)
	(segment
		(start 373.34063 -80.490568)
		(end 373.14505 -80.294988)
		(width 0.10795)
		(layer "F.Cu")
		(net "FM_CPLD_DBG_PWR_EN_N")
	)
	(segment
		(start 375.697496 -81.751678)
		(end 374.03151 -81.751678)
		(width 0.10795)
		(layer "F.Cu")
		(net "FM_CPLD_DBG_PWR_EN_N")
	)
	(segment
		(start 379.312932 -81.872074)
		(end 375.817892 -81.872074)
		(width 0.10795)
		(layer "F.Cu")
		(net "FM_CPLD_DBG_PWR_EN_N")
	)
	(segment
		(start 498.2718 -157.5181)
		(end 498.2718 -157.353)
		(width 0.10795)
		(layer "F.Cu")
		(net "FM_CPLD_DBG_PWR_EN_N")
	)
	(segment
		(start 477.978724 -151.436324)
		(end 479.0948 -152.5524)
		(width 0.10795)
		(layer "F.Cu")
		(net "FM_CPLD_DBG_PWR_EN_N")
	)
	(segment
		(start 479.298 -153.437336)
		(end 479.298 -156.845)
		(width 0.10795)
		(layer "F.Cu")
		(net "FM_CPLD_DBG_PWR_EN_N")
	)
	(segment
		(start 385.651502 -84.26831)
		(end 385.255516 -84.26831)
		(width 0.10795)
		(layer "F.Cu")
		(net "FM_CPLD_DBG_PWR_EN_N")
	)
	(segment
		(start 380.810008 -83.36915)
		(end 379.312932 -81.872074)
		(width 0.10795)
		(layer "F.Cu")
		(net "FM_CPLD_DBG_PWR_EN_N")
	)
	(segment
		(start 497.692172 -158.097728)
		(end 498.2718 -157.5181)
		(width 0.10795)
		(layer "F.Cu")
		(net "FM_CPLD_DBG_PWR_EN_N")
	)
	(segment
		(start 385.108704 -84.415122)
		(end 383.414524 -84.415122)
		(width 0.10795)
		(layer "F.Cu")
		(net "FM_CPLD_DBG_PWR_EN_N")
	)
	(segment
		(start 374.03151 -81.751678)
		(end 373.34063 -81.060798)
		(width 0.10795)
		(layer "F.Cu")
		(net "FM_CPLD_DBG_PWR_EN_N")
	)
	(via
		(at 417.073588 -80.904842)
		(size 0.6604)
		(drill 0.3302)
		(layers "F.Cu" "B.Cu")
		(net "FM_CPLD_DBG_PWR_EN_N")
	)
	(via
		(at 498.2718 -157.353)
		(size 0.508)
		(drill 0.254)
		(layers "F.Cu" "B.Cu")
		(net "FM_CPLD_DBG_PWR_EN_N")
	)
	(via
		(at 387.362954 -83.706462)
		(size 0.508)
		(drill 0.254)
		(layers "F.Cu" "B.Cu")
		(net "FM_CPLD_DBG_PWR_EN_N")
	)
	(via
		(at 416.31616 -80.351122)
		(size 0.508)
		(drill 0.254)
		(layers "F.Cu" "B.Cu")
		(net "FM_CPLD_DBG_PWR_EN_N")
	)
	(via
		(at 421.877236 -98.522282)
		(size 0.508)
		(drill 0.254)
		(layers "F.Cu" "B.Cu")
		(net "FM_CPLD_DBG_PWR_EN_N")
	)
	(segment
		(start 417.738814 -81.570068)
		(end 417.073588 -80.904842)
		(width 0.10795)
		(layer "B.Cu")
		(net "FM_CPLD_DBG_PWR_EN_N")
	)
	(segment
		(start 421.045132 -86.014306)
		(end 421.045132 -85.577934)
		(width 0.10795)
		(layer "B.Cu")
		(net "FM_CPLD_DBG_PWR_EN_N")
	)
	(segment
		(start 419.895528 -85.378544)
		(end 417.738814 -83.22183)
		(width 0.10795)
		(layer "B.Cu")
		(net "FM_CPLD_DBG_PWR_EN_N")
	)
	(segment
		(start 421.045132 -85.577934)
		(end 420.845742 -85.378544)
		(width 0.10795)
		(layer "B.Cu")
		(net "FM_CPLD_DBG_PWR_EN_N")
	)
	(segment
		(start 421.877236 -98.522282)
		(end 421.552624 -98.19767)
		(width 0.10795)
		(layer "B.Cu")
		(net "FM_CPLD_DBG_PWR_EN_N")
	)
	(segment
		(start 421.552624 -94.7674)
		(end 421.917114 -94.40291)
		(width 0.10795)
		(layer "B.Cu")
		(net "FM_CPLD_DBG_PWR_EN_N")
	)
	(segment
		(start 421.917114 -94.40291)
		(end 421.917114 -86.886288)
		(width 0.10795)
		(layer "B.Cu")
		(net "FM_CPLD_DBG_PWR_EN_N")
	)
	(segment
		(start 417.073588 -80.904842)
		(end 416.519868 -80.351122)
		(width 0.10795)
		(layer "B.Cu")
		(net "FM_CPLD_DBG_PWR_EN_N")
	)
	(segment
		(start 417.738814 -83.22183)
		(end 417.738814 -81.570068)
		(width 0.10795)
		(layer "B.Cu")
		(net "FM_CPLD_DBG_PWR_EN_N")
	)
	(segment
		(start 420.845742 -85.378544)
		(end 419.895528 -85.378544)
		(width 0.10795)
		(layer "B.Cu")
		(net "FM_CPLD_DBG_PWR_EN_N")
	)
	(segment
		(start 416.519868 -80.351122)
		(end 416.31616 -80.351122)
		(width 0.10795)
		(layer "B.Cu")
		(net "FM_CPLD_DBG_PWR_EN_N")
	)
	(segment
		(start 421.917114 -86.886288)
		(end 421.045132 -86.014306)
		(width 0.10795)
		(layer "B.Cu")
		(net "FM_CPLD_DBG_PWR_EN_N")
	)
	(segment
		(start 421.552624 -98.19767)
		(end 421.552624 -94.7674)
		(width 0.10795)
		(layer "B.Cu")
		(net "FM_CPLD_DBG_PWR_EN_N")
	)
	(segment
		(start 393.2682 -80.01)
		(end 394.773912 -80.01)
		(width 0.089408)
		(layer "In4.Cu")
		(net "FM_CPLD_DBG_PWR_EN_N")
	)
	(segment
		(start 411.823154 -80.791558)
		(end 415.875724 -80.791558)
		(width 0.089408)
		(layer "In4.Cu")
		(net "FM_CPLD_DBG_PWR_EN_N")
	)
	(segment
		(start 387.732016 -83.3374)
		(end 389.516366 -83.3374)
		(width 0.089408)
		(layer "In4.Cu")
		(net "FM_CPLD_DBG_PWR_EN_N")
	)
	(segment
		(start 406.037542 -79.387446)
		(end 407.592784 -80.942688)
		(width 0.089408)
		(layer "In4.Cu")
		(net "FM_CPLD_DBG_PWR_EN_N")
	)
	(segment
		(start 387.362954 -83.706462)
		(end 387.732016 -83.3374)
		(width 0.089408)
		(layer "In4.Cu")
		(net "FM_CPLD_DBG_PWR_EN_N")
	)
	(segment
		(start 393.0142 -80.264)
		(end 393.2682 -80.01)
		(width 0.089408)
		(layer "In4.Cu")
		(net "FM_CPLD_DBG_PWR_EN_N")
	)
	(segment
		(start 389.516366 -83.3374)
		(end 390.309862 -82.543904)
		(width 0.089408)
		(layer "In4.Cu")
		(net "FM_CPLD_DBG_PWR_EN_N")
	)
	(segment
		(start 402.564346 -79.387446)
		(end 406.037542 -79.387446)
		(width 0.089408)
		(layer "In4.Cu")
		(net "FM_CPLD_DBG_PWR_EN_N")
	)
	(segment
		(start 390.309862 -82.543904)
		(end 390.901174 -82.543904)
		(width 0.089408)
		(layer "In4.Cu")
		(net "FM_CPLD_DBG_PWR_EN_N")
	)
	(segment
		(start 399.905474 -79.731616)
		(end 402.220176 -79.731616)
		(width 0.089408)
		(layer "In4.Cu")
		(net "FM_CPLD_DBG_PWR_EN_N")
	)
	(segment
		(start 407.592784 -80.942688)
		(end 411.672024 -80.942688)
		(width 0.089408)
		(layer "In4.Cu")
		(net "FM_CPLD_DBG_PWR_EN_N")
	)
	(segment
		(start 393.0142 -80.430878)
		(end 393.0142 -80.264)
		(width 0.089408)
		(layer "In4.Cu")
		(net "FM_CPLD_DBG_PWR_EN_N")
	)
	(segment
		(start 415.875724 -80.791558)
		(end 416.31616 -80.351122)
		(width 0.089408)
		(layer "In4.Cu")
		(net "FM_CPLD_DBG_PWR_EN_N")
	)
	(segment
		(start 394.773912 -80.01)
		(end 395.610334 -80.846422)
		(width 0.089408)
		(layer "In4.Cu")
		(net "FM_CPLD_DBG_PWR_EN_N")
	)
	(segment
		(start 402.220176 -79.731616)
		(end 402.564346 -79.387446)
		(width 0.089408)
		(layer "In4.Cu")
		(net "FM_CPLD_DBG_PWR_EN_N")
	)
	(segment
		(start 395.610334 -80.846422)
		(end 398.790668 -80.846422)
		(width 0.089408)
		(layer "In4.Cu")
		(net "FM_CPLD_DBG_PWR_EN_N")
	)
	(segment
		(start 398.790668 -80.846422)
		(end 399.905474 -79.731616)
		(width 0.089408)
		(layer "In4.Cu")
		(net "FM_CPLD_DBG_PWR_EN_N")
	)
	(segment
		(start 390.901174 -82.543904)
		(end 393.0142 -80.430878)
		(width 0.089408)
		(layer "In4.Cu")
		(net "FM_CPLD_DBG_PWR_EN_N")
	)
	(segment
		(start 411.672024 -80.942688)
		(end 411.823154 -80.791558)
		(width 0.089408)
		(layer "In4.Cu")
		(net "FM_CPLD_DBG_PWR_EN_N")
	)
	(segment
		(start 481.428552 -110.579408)
		(end 482.618796 -111.769652)
		(width 0.089408)
		(layer "In9.Cu")
		(net "FM_CPLD_DBG_PWR_EN_N")
	)
	(segment
		(start 500.372888 -133.92404)
		(end 500.372888 -155.251912)
		(width 0.089408)
		(layer "In9.Cu")
		(net "FM_CPLD_DBG_PWR_EN_N")
	)
	(segment
		(start 501.00992 -113.943384)
		(end 501.00992 -133.287008)
		(width 0.089408)
		(layer "In9.Cu")
		(net "FM_CPLD_DBG_PWR_EN_N")
	)
	(segment
		(start 426.3263 -109.394752)
		(end 427.510956 -110.579408)
		(width 0.089408)
		(layer "In9.Cu")
		(net "FM_CPLD_DBG_PWR_EN_N")
	)
	(segment
		(start 421.6908 -102.4382)
		(end 421.4114 -102.7176)
		(width 0.089408)
		(layer "In9.Cu")
		(net "FM_CPLD_DBG_PWR_EN_N")
	)
	(segment
		(start 421.965882 -98.522282)
		(end 422.529 -99.0854)
		(width 0.089408)
		(layer "In9.Cu")
		(net "FM_CPLD_DBG_PWR_EN_N")
	)
	(segment
		(start 500.372888 -155.251912)
		(end 498.2718 -157.353)
		(width 0.089408)
		(layer "In9.Cu")
		(net "FM_CPLD_DBG_PWR_EN_N")
	)
	(segment
		(start 492.349536 -110.674404)
		(end 497.74094 -110.674404)
		(width 0.089408)
		(layer "In9.Cu")
		(net "FM_CPLD_DBG_PWR_EN_N")
	)
	(segment
		(start 421.4114 -102.7176)
		(end 421.4114 -102.997)
		(width 0.089408)
		(layer "In9.Cu")
		(net "FM_CPLD_DBG_PWR_EN_N")
	)
	(segment
		(start 497.74094 -110.674404)
		(end 501.00992 -113.943384)
		(width 0.089408)
		(layer "In9.Cu")
		(net "FM_CPLD_DBG_PWR_EN_N")
	)
	(segment
		(start 501.00992 -133.287008)
		(end 500.372888 -133.92404)
		(width 0.089408)
		(layer "In9.Cu")
		(net "FM_CPLD_DBG_PWR_EN_N")
	)
	(segment
		(start 491.254288 -111.769652)
		(end 492.349536 -110.674404)
		(width 0.089408)
		(layer "In9.Cu")
		(net "FM_CPLD_DBG_PWR_EN_N")
	)
	(segment
		(start 422.529 -102.168452)
		(end 422.259252 -102.4382)
		(width 0.089408)
		(layer "In9.Cu")
		(net "FM_CPLD_DBG_PWR_EN_N")
	)
	(segment
		(start 421.4114 -102.997)
		(end 422.490392 -104.075992)
		(width 0.089408)
		(layer "In9.Cu")
		(net "FM_CPLD_DBG_PWR_EN_N")
	)
	(segment
		(start 422.259252 -102.4382)
		(end 421.6908 -102.4382)
		(width 0.089408)
		(layer "In9.Cu")
		(net "FM_CPLD_DBG_PWR_EN_N")
	)
	(segment
		(start 426.3263 -106.082846)
		(end 426.3263 -109.394752)
		(width 0.089408)
		(layer "In9.Cu")
		(net "FM_CPLD_DBG_PWR_EN_N")
	)
	(segment
		(start 422.490392 -104.075992)
		(end 424.319446 -104.075992)
		(width 0.089408)
		(layer "In9.Cu")
		(net "FM_CPLD_DBG_PWR_EN_N")
	)
	(segment
		(start 424.319446 -104.075992)
		(end 426.3263 -106.082846)
		(width 0.089408)
		(layer "In9.Cu")
		(net "FM_CPLD_DBG_PWR_EN_N")
	)
	(segment
		(start 482.618796 -111.769652)
		(end 491.254288 -111.769652)
		(width 0.089408)
		(layer "In9.Cu")
		(net "FM_CPLD_DBG_PWR_EN_N")
	)
	(segment
		(start 421.877236 -98.522282)
		(end 421.965882 -98.522282)
		(width 0.089408)
		(layer "In9.Cu")
		(net "FM_CPLD_DBG_PWR_EN_N")
	)
	(segment
		(start 422.529 -99.0854)
		(end 422.529 -102.168452)
		(width 0.089408)
		(layer "In9.Cu")
		(net "FM_CPLD_DBG_PWR_EN_N")
	)
	(segment
		(start 427.510956 -110.579408)
		(end 481.428552 -110.579408)
		(width 0.089408)
		(layer "In9.Cu")
		(net "FM_CPLD_DBG_PWR_EN_N")
	)
	(segment
		(start 421.221154 -56.2356)
		(end 421.3225 -56.2356)
		(width 0.10795)
		(layer "F.Cu")
		(net "RST_PLTRST_TOP_SWAP")
	)
	(segment
		(start 419.50005 -58.98515)
		(end 419.50005 -57.956704)
		(width 0.10795)
		(layer "F.Cu")
		(net "RST_PLTRST_TOP_SWAP")
	)
	(segment
		(start 417.9316 -58.0009)
		(end 418.4777 -58.0009)
		(width 0.10795)
		(layer "F.Cu")
		(net "RST_PLTRST_TOP_SWAP")
	)
	(segment
		(start 417.4363 -57.6961)
		(end 417.7411 -58.0009)
		(width 0.10795)
		(layer "F.Cu")
		(net "RST_PLTRST_TOP_SWAP")
	)
	(segment
		(start 419.1 -59.3852)
		(end 419.50005 -58.98515)
		(width 0.10795)
		(layer "F.Cu")
		(net "RST_PLTRST_TOP_SWAP")
	)
	(segment
		(start 417.7411 -58.0009)
		(end 417.9316 -58.0009)
		(width 0.10795)
		(layer "F.Cu")
		(net "RST_PLTRST_TOP_SWAP")
	)
	(segment
		(start 418.7444 -58.2676)
		(end 418.7444 -59.3852)
		(width 0.10795)
		(layer "F.Cu")
		(net "RST_PLTRST_TOP_SWAP")
	)
	(segment
		(start 418.4777 -58.0009)
		(end 418.7444 -58.2676)
		(width 0.10795)
		(layer "F.Cu")
		(net "RST_PLTRST_TOP_SWAP")
	)
	(segment
		(start 417.1696 -56.896)
		(end 417.4363 -57.1627)
		(width 0.10795)
		(layer "F.Cu")
		(net "RST_PLTRST_TOP_SWAP")
	)
	(segment
		(start 418.7444 -59.3852)
		(end 419.1 -59.3852)
		(width 0.10795)
		(layer "F.Cu")
		(net "RST_PLTRST_TOP_SWAP")
	)
	(segment
		(start 416.56 -56.896)
		(end 417.1696 -56.896)
		(width 0.10795)
		(layer "F.Cu")
		(net "RST_PLTRST_TOP_SWAP")
	)
	(segment
		(start 417.4363 -57.1627)
		(end 417.4363 -57.6961)
		(width 0.10795)
		(layer "F.Cu")
		(net "RST_PLTRST_TOP_SWAP")
	)
	(segment
		(start 419.50005 -57.956704)
		(end 421.221154 -56.2356)
		(width 0.10795)
		(layer "F.Cu")
		(net "RST_PLTRST_TOP_SWAP")
	)
	(via
		(at 418.7444 -59.3852)
		(size 0.762)
		(drill 0.381)
		(layers "F.Cu" "B.Cu")
		(net "RST_PLTRST_TOP_SWAP")
	)
	(segment
		(start 385.1021 -94.257876)
		(end 384.985006 -94.37497)
		(width 0.0889)
		(layer "F.Cu")
		(net "RST_PCH_SYSRST_BTN_OUT_N")
	)
	(segment
		(start 385.371848 -92.38869)
		(end 385.371848 -92.402152)
		(width 0.0889)
		(layer "F.Cu")
		(net "RST_PCH_SYSRST_BTN_OUT_N")
	)
	(segment
		(start 385.1021 -93.88856)
		(end 385.1021 -94.257876)
		(width 0.0889)
		(layer "F.Cu")
		(net "RST_PCH_SYSRST_BTN_OUT_N")
	)
	(segment
		(start 385.17703 -93.25356)
		(end 385.280662 -93.357192)
		(width 0.0889)
		(layer "F.Cu")
		(net "RST_PCH_SYSRST_BTN_OUT_N")
	)
	(segment
		(start 385.400296 -92.004642)
		(end 385.400296 -92.360242)
		(width 0.0889)
		(layer "F.Cu")
		(net "RST_PCH_SYSRST_BTN_OUT_N")
	)
	(segment
		(start 385.371848 -92.402152)
		(end 385.17703 -92.59697)
		(width 0.0889)
		(layer "F.Cu")
		(net "RST_PCH_SYSRST_BTN_OUT_N")
	)
	(segment
		(start 384.79095 -91.146376)
		(end 384.79095 -91.395296)
		(width 0.0889)
		(layer "F.Cu")
		(net "RST_PCH_SYSRST_BTN_OUT_N")
	)
	(segment
		(start 385.17703 -92.59697)
		(end 385.17703 -93.25356)
		(width 0.0889)
		(layer "F.Cu")
		(net "RST_PCH_SYSRST_BTN_OUT_N")
	)
	(segment
		(start 385.280662 -93.709998)
		(end 385.1021 -93.88856)
		(width 0.0889)
		(layer "F.Cu")
		(net "RST_PCH_SYSRST_BTN_OUT_N")
	)
	(segment
		(start 384.79095 -91.395296)
		(end 385.400296 -92.004642)
		(width 0.0889)
		(layer "F.Cu")
		(net "RST_PCH_SYSRST_BTN_OUT_N")
	)
	(segment
		(start 385.400296 -92.360242)
		(end 385.371848 -92.38869)
		(width 0.0889)
		(layer "F.Cu")
		(net "RST_PCH_SYSRST_BTN_OUT_N")
	)
	(segment
		(start 385.280662 -93.357192)
		(end 385.280662 -93.709998)
		(width 0.0889)
		(layer "F.Cu")
		(net "RST_PCH_SYSRST_BTN_OUT_N")
	)
	(via
		(at 392.435842 -41.06545)
		(size 0.508)
		(drill 0.254)
		(layers "F.Cu" "B.Cu")
		(net "RST_PCH_SYSRST_BTN_OUT_N")
	)
	(via
		(at 384.79095 -91.146376)
		(size 0.508)
		(drill 0.254)
		(layers "F.Cu" "B.Cu")
		(net "RST_PCH_SYSRST_BTN_OUT_N")
	)
	(via
		(at 387.994398 -83.832192)
		(size 0.508)
		(drill 0.254)
		(layers "F.Cu" "B.Cu")
		(net "RST_PCH_SYSRST_BTN_OUT_N")
	)
	(via
		(at 393.446 -40.767)
		(size 0.6604)
		(drill 0.3302)
		(layers "F.Cu" "B.Cu")
		(net "RST_PCH_SYSRST_BTN_OUT_N")
	)
	(segment
		(start 396.494 -38.735)
		(end 395.859 -38.1)
		(width 0.10795)
		(layer "B.Cu")
		(net "RST_PCH_SYSRST_BTN_OUT_N")
	)
	(segment
		(start 393.18565 -41.02735)
		(end 392.473942 -41.02735)
		(width 0.10795)
		(layer "B.Cu")
		(net "RST_PCH_SYSRST_BTN_OUT_N")
	)
	(segment
		(start 392.473942 -41.02735)
		(end 392.435842 -41.06545)
		(width 0.10795)
		(layer "B.Cu")
		(net "RST_PCH_SYSRST_BTN_OUT_N")
	)
	(segment
		(start 396.875 -38.735)
		(end 396.494 -38.735)
		(width 0.10795)
		(layer "B.Cu")
		(net "RST_PCH_SYSRST_BTN_OUT_N")
	)
	(segment
		(start 393.446 -40.767)
		(end 393.18565 -41.02735)
		(width 0.10795)
		(layer "B.Cu")
		(net "RST_PCH_SYSRST_BTN_OUT_N")
	)
	(segment
		(start 395.859 -38.1)
		(end 394.716 -38.1)
		(width 0.10795)
		(layer "B.Cu")
		(net "RST_PCH_SYSRST_BTN_OUT_N")
	)
	(segment
		(start 393.954 -39.8526)
		(end 393.954 -40.513)
		(width 0.10795)
		(layer "B.Cu")
		(net "RST_PCH_SYSRST_BTN_OUT_N")
	)
	(segment
		(start 394.3096 -38.9382)
		(end 394.3096 -39.497)
		(width 0.10795)
		(layer "B.Cu")
		(net "RST_PCH_SYSRST_BTN_OUT_N")
	)
	(segment
		(start 394.3096 -39.497)
		(end 393.954 -39.8526)
		(width 0.10795)
		(layer "B.Cu")
		(net "RST_PCH_SYSRST_BTN_OUT_N")
	)
	(segment
		(start 393.7 -40.767)
		(end 393.446 -40.767)
		(width 0.10795)
		(layer "B.Cu")
		(net "RST_PCH_SYSRST_BTN_OUT_N")
	)
	(segment
		(start 394.716 -38.1)
		(end 394.3096 -38.5064)
		(width 0.10795)
		(layer "B.Cu")
		(net "RST_PCH_SYSRST_BTN_OUT_N")
	)
	(segment
		(start 393.954 -40.513)
		(end 393.7 -40.767)
		(width 0.10795)
		(layer "B.Cu")
		(net "RST_PCH_SYSRST_BTN_OUT_N")
	)
	(segment
		(start 394.3096 -38.5064)
		(end 394.3096 -38.9382)
		(width 0.10795)
		(layer "B.Cu")
		(net "RST_PCH_SYSRST_BTN_OUT_N")
	)
	(segment
		(start 386.75183 -85.07476)
		(end 387.994398 -83.832192)
		(width 0.089408)
		(layer "In2.Cu")
		(net "RST_PCH_SYSRST_BTN_OUT_N")
	)
	(segment
		(start 384.79095 -91.146376)
		(end 385.096766 -91.146376)
		(width 0.089408)
		(layer "In2.Cu")
		(net "RST_PCH_SYSRST_BTN_OUT_N")
	)
	(segment
		(start 384.626612 -86.871556)
		(end 386.423408 -85.07476)
		(width 0.089408)
		(layer "In2.Cu")
		(net "RST_PCH_SYSRST_BTN_OUT_N")
	)
	(segment
		(start 385.096766 -91.146376)
		(end 385.186174 -91.056968)
		(width 0.089408)
		(layer "In2.Cu")
		(net "RST_PCH_SYSRST_BTN_OUT_N")
	)
	(segment
		(start 385.186174 -90.04808)
		(end 384.626612 -89.488518)
		(width 0.089408)
		(layer "In2.Cu")
		(net "RST_PCH_SYSRST_BTN_OUT_N")
	)
	(segment
		(start 384.626612 -89.488518)
		(end 384.626612 -86.871556)
		(width 0.089408)
		(layer "In2.Cu")
		(net "RST_PCH_SYSRST_BTN_OUT_N")
	)
	(segment
		(start 386.423408 -85.07476)
		(end 386.75183 -85.07476)
		(width 0.089408)
		(layer "In2.Cu")
		(net "RST_PCH_SYSRST_BTN_OUT_N")
	)
	(segment
		(start 385.186174 -91.056968)
		(end 385.186174 -90.04808)
		(width 0.089408)
		(layer "In2.Cu")
		(net "RST_PCH_SYSRST_BTN_OUT_N")
	)
	(segment
		(start 389.503666 -66.845688)
		(end 391.936224 -64.41313)
		(width 0.089408)
		(layer "In9.Cu")
		(net "RST_PCH_SYSRST_BTN_OUT_N")
	)
	(segment
		(start 390.29132 -69.253354)
		(end 389.503666 -68.4657)
		(width 0.089408)
		(layer "In9.Cu")
		(net "RST_PCH_SYSRST_BTN_OUT_N")
	)
	(segment
		(start 389.838692 -71.798688)
		(end 389.838692 -71.772272)
		(width 0.089408)
		(layer "In9.Cu")
		(net "RST_PCH_SYSRST_BTN_OUT_N")
	)
	(segment
		(start 386.548376 -78.214728)
		(end 386.548376 -77.898244)
		(width 0.089408)
		(layer "In9.Cu")
		(net "RST_PCH_SYSRST_BTN_OUT_N")
	)
	(segment
		(start 387.479794 -83.174332)
		(end 387.479794 -80.54086)
		(width 0.089408)
		(layer "In9.Cu")
		(net "RST_PCH_SYSRST_BTN_OUT_N")
	)
	(segment
		(start 389.838692 -71.772272)
		(end 390.29132 -71.319644)
		(width 0.089408)
		(layer "In9.Cu")
		(net "RST_PCH_SYSRST_BTN_OUT_N")
	)
	(segment
		(start 386.548376 -79.292958)
		(end 386.54863 -79.292704)
		(width 0.089408)
		(layer "In9.Cu")
		(net "RST_PCH_SYSRST_BTN_OUT_N")
	)
	(segment
		(start 391.300716 -42.455846)
		(end 391.30097 -42.455592)
		(width 0.089408)
		(layer "In9.Cu")
		(net "RST_PCH_SYSRST_BTN_OUT_N")
	)
	(segment
		(start 391.30097 -42.200322)
		(end 392.435842 -41.06545)
		(width 0.089408)
		(layer "In9.Cu")
		(net "RST_PCH_SYSRST_BTN_OUT_N")
	)
	(segment
		(start 391.015728 -47.501302)
		(end 390.770872 -47.256446)
		(width 0.089408)
		(layer "In9.Cu")
		(net "RST_PCH_SYSRST_BTN_OUT_N")
	)
	(segment
		(start 386.54863 -78.214982)
		(end 386.548376 -78.214728)
		(width 0.089408)
		(layer "In9.Cu")
		(net "RST_PCH_SYSRST_BTN_OUT_N")
	)
	(segment
		(start 391.015728 -51.997102)
		(end 391.015728 -47.501302)
		(width 0.089408)
		(layer "In9.Cu")
		(net "RST_PCH_SYSRST_BTN_OUT_N")
	)
	(segment
		(start 387.479794 -80.54086)
		(end 386.548376 -79.609442)
		(width 0.089408)
		(layer "In9.Cu")
		(net "RST_PCH_SYSRST_BTN_OUT_N")
	)
	(segment
		(start 386.548376 -77.898244)
		(end 388.764272 -75.682348)
		(width 0.089408)
		(layer "In9.Cu")
		(net "RST_PCH_SYSRST_BTN_OUT_N")
	)
	(segment
		(start 392.33602 -61.170566)
		(end 392.33602 -59.855354)
		(width 0.089408)
		(layer "In9.Cu")
		(net "RST_PCH_SYSRST_BTN_OUT_N")
	)
	(segment
		(start 386.548376 -79.609442)
		(end 386.548376 -79.292958)
		(width 0.089408)
		(layer "In9.Cu")
		(net "RST_PCH_SYSRST_BTN_OUT_N")
	)
	(segment
		(start 391.30097 -42.94124)
		(end 391.300716 -42.940986)
		(width 0.089408)
		(layer "In9.Cu")
		(net "RST_PCH_SYSRST_BTN_OUT_N")
	)
	(segment
		(start 386.54863 -79.292704)
		(end 386.54863 -78.214982)
		(width 0.089408)
		(layer "In9.Cu")
		(net "RST_PCH_SYSRST_BTN_OUT_N")
	)
	(segment
		(start 391.936224 -64.41313)
		(end 391.936224 -61.570362)
		(width 0.089408)
		(layer "In9.Cu")
		(net "RST_PCH_SYSRST_BTN_OUT_N")
	)
	(segment
		(start 389.503666 -68.4657)
		(end 389.503666 -66.845688)
		(width 0.089408)
		(layer "In9.Cu")
		(net "RST_PCH_SYSRST_BTN_OUT_N")
	)
	(segment
		(start 392.33602 -59.855354)
		(end 391.710418 -59.229752)
		(width 0.089408)
		(layer "In9.Cu")
		(net "RST_PCH_SYSRST_BTN_OUT_N")
	)
	(segment
		(start 390.29132 -71.319644)
		(end 390.29132 -69.253354)
		(width 0.089408)
		(layer "In9.Cu")
		(net "RST_PCH_SYSRST_BTN_OUT_N")
	)
	(segment
		(start 391.710418 -59.229752)
		(end 391.710418 -52.691792)
		(width 0.089408)
		(layer "In9.Cu")
		(net "RST_PCH_SYSRST_BTN_OUT_N")
	)
	(segment
		(start 391.30097 -42.455592)
		(end 391.30097 -42.200322)
		(width 0.089408)
		(layer "In9.Cu")
		(net "RST_PCH_SYSRST_BTN_OUT_N")
	)
	(segment
		(start 391.936224 -61.570362)
		(end 392.33602 -61.170566)
		(width 0.089408)
		(layer "In9.Cu")
		(net "RST_PCH_SYSRST_BTN_OUT_N")
	)
	(segment
		(start 391.30097 -45.2374)
		(end 391.30097 -42.94124)
		(width 0.089408)
		(layer "In9.Cu")
		(net "RST_PCH_SYSRST_BTN_OUT_N")
	)
	(segment
		(start 390.770872 -47.256446)
		(end 390.770872 -45.767498)
		(width 0.089408)
		(layer "In9.Cu")
		(net "RST_PCH_SYSRST_BTN_OUT_N")
	)
	(segment
		(start 391.300716 -42.940986)
		(end 391.300716 -42.455846)
		(width 0.089408)
		(layer "In9.Cu")
		(net "RST_PCH_SYSRST_BTN_OUT_N")
	)
	(segment
		(start 389.188452 -73.751694)
		(end 389.188452 -72.448928)
		(width 0.089408)
		(layer "In9.Cu")
		(net "RST_PCH_SYSRST_BTN_OUT_N")
	)
	(segment
		(start 390.770872 -45.767498)
		(end 391.30097 -45.2374)
		(width 0.089408)
		(layer "In9.Cu")
		(net "RST_PCH_SYSRST_BTN_OUT_N")
	)
	(segment
		(start 388.764272 -74.175874)
		(end 389.188452 -73.751694)
		(width 0.089408)
		(layer "In9.Cu")
		(net "RST_PCH_SYSRST_BTN_OUT_N")
	)
	(segment
		(start 387.994398 -83.832192)
		(end 387.994398 -83.688936)
		(width 0.089408)
		(layer "In9.Cu")
		(net "RST_PCH_SYSRST_BTN_OUT_N")
	)
	(segment
		(start 391.710418 -52.691792)
		(end 391.015728 -51.997102)
		(width 0.089408)
		(layer "In9.Cu")
		(net "RST_PCH_SYSRST_BTN_OUT_N")
	)
	(segment
		(start 388.764272 -75.682348)
		(end 388.764272 -74.175874)
		(width 0.089408)
		(layer "In9.Cu")
		(net "RST_PCH_SYSRST_BTN_OUT_N")
	)
	(segment
		(start 389.188452 -72.448928)
		(end 389.838692 -71.798688)
		(width 0.089408)
		(layer "In9.Cu")
		(net "RST_PCH_SYSRST_BTN_OUT_N")
	)
	(segment
		(start 387.994398 -83.688936)
		(end 387.479794 -83.174332)
		(width 0.089408)
		(layer "In9.Cu")
		(net "RST_PCH_SYSRST_BTN_OUT_N")
	)
	(segment
		(start 20.030948 -88.655652)
		(end 20.0914 -88.5952)
		(width 0.10795)
		(layer "F.Cu")
		(net "PU_VR_PVCCIN_CPU1_FLT1_SMBALT_N")
	)
	(segment
		(start 20.030948 -89.5604)
		(end 20.030948 -88.655652)
		(width 0.10795)
		(layer "F.Cu")
		(net "PU_VR_PVCCIN_CPU1_FLT1_SMBALT_N")
	)
	(segment
		(start 20.0914 -88.0872)
		(end 19.812 -87.8078)
		(width 0.10795)
		(layer "F.Cu")
		(net "PU_VR_PVCCIN_CPU1_FLT1_SMBALT_N")
	)
	(segment
		(start 20.0914 -88.5952)
		(end 20.0914 -88.138)
		(width 0.10795)
		(layer "F.Cu")
		(net "PU_VR_PVCCIN_CPU1_FLT1_SMBALT_N")
	)
	(segment
		(start 20.0914 -88.138)
		(end 20.0914 -88.0872)
		(width 0.10795)
		(layer "F.Cu")
		(net "PU_VR_PVCCIN_CPU1_FLT1_SMBALT_N")
	)
	(segment
		(start 19.812 -87.8078)
		(end 19.812 -87.5157)
		(width 0.10795)
		(layer "F.Cu")
		(net "PU_VR_PVCCIN_CPU1_FLT1_SMBALT_N")
	)
	(via
		(at 20.0914 -88.138)
		(size 0.508)
		(drill 0.254)
		(layers "F.Cu" "B.Cu")
		(net "PU_VR_PVCCIN_CPU1_FLT1_SMBALT_N")
	)
	(segment
		(start 185.10758 -64.99987)
		(end 185.42 -64.68745)
		(width 0.10795)
		(layer "F.Cu")
		(net "PU_VR_PVCCIN_CPU0_FLT1_SMBALT_N")
	)
	(segment
		(start 184.985914 -64.253364)
		(end 185.42 -64.68745)
		(width 0.10795)
		(layer "F.Cu")
		(net "PU_VR_PVCCIN_CPU0_FLT1_SMBALT_N")
	)
	(segment
		(start 184.876948 -65.810892)
		(end 185.10758 -65.58026)
		(width 0.10795)
		(layer "F.Cu")
		(net "PU_VR_PVCCIN_CPU0_FLT1_SMBALT_N")
	)
	(segment
		(start 184.985914 -62.865)
		(end 184.985914 -64.253364)
		(width 0.10795)
		(layer "F.Cu")
		(net "PU_VR_PVCCIN_CPU0_FLT1_SMBALT_N")
	)
	(segment
		(start 184.876948 -66.9544)
		(end 184.876948 -65.810892)
		(width 0.10795)
		(layer "F.Cu")
		(net "PU_VR_PVCCIN_CPU0_FLT1_SMBALT_N")
	)
	(segment
		(start 185.10758 -65.58026)
		(end 185.10758 -64.99987)
		(width 0.10795)
		(layer "F.Cu")
		(net "PU_VR_PVCCIN_CPU0_FLT1_SMBALT_N")
	)
	(via
		(at 185.42 -64.68745)
		(size 0.508)
		(drill 0.254)
		(layers "F.Cu" "B.Cu")
		(net "PU_VR_PVCCIN_CPU0_FLT1_SMBALT_N")
	)
	(via
		(at 376.4788 -80.9244)
		(size 0.6604)
		(drill 0.3302)
		(layers "F.Cu" "B.Cu")
		(net "FM_THERMTRIP_DLY_R")
	)
	(segment
		(start 375.991374 -82.986626)
		(end 376.047 -82.931)
		(width 0.10795)
		(layer "B.Cu")
		(net "FM_THERMTRIP_DLY_R")
	)
	(segment
		(start 376.4788 -80.9244)
		(end 376.047 -81.3562)
		(width 0.10795)
		(layer "B.Cu")
		(net "FM_THERMTRIP_DLY_R")
	)
	(segment
		(start 376.047 -81.3562)
		(end 376.047 -82.169)
		(width 0.10795)
		(layer "B.Cu")
		(net "FM_THERMTRIP_DLY_R")
	)
	(segment
		(start 375.991374 -83.86953)
		(end 375.991374 -82.986626)
		(width 0.10795)
		(layer "B.Cu")
		(net "FM_THERMTRIP_DLY_R")
	)
	(segment
		(start 376.047 -82.931)
		(end 376.047 -82.169)
		(width 0.10795)
		(layer "B.Cu")
		(net "FM_THERMTRIP_DLY_R")
	)
	(segment
		(start 395.16685 -99.55276)
		(end 395.66215 -99.322636)
		(width 0.10795)
		(layer "F.Cu")
		(net "FM_PCH_PWRBTN_OUT_N")
	)
	(via
		(at 413.670496 -57.230772)
		(size 0.508)
		(drill 0.254)
		(layers "F.Cu" "B.Cu")
		(net "FM_PCH_PWRBTN_OUT_N")
	)
	(via
		(at 398.145 -40.1574)
		(size 0.6604)
		(drill 0.3302)
		(layers "F.Cu" "B.Cu")
		(net "FM_PCH_PWRBTN_OUT_N")
	)
	(via
		(at 403.848316 -58.179716)
		(size 0.6604)
		(drill 0.3302)
		(layers "F.Cu" "B.Cu")
		(net "FM_PCH_PWRBTN_OUT_N")
	)
	(via
		(at 395.66215 -99.322636)
		(size 0.508)
		(drill 0.254)
		(layers "F.Cu" "B.Cu")
		(net "FM_PCH_PWRBTN_OUT_N")
	)
	(segment
		(start 396.11808 -40.005)
		(end 396.875 -40.005)
		(width 0.10795)
		(layer "B.Cu")
		(net "FM_PCH_PWRBTN_OUT_N")
	)
	(segment
		(start 403.848316 -58.179716)
		(end 411.59303 -58.179716)
		(width 0.10795)
		(layer "B.Cu")
		(net "FM_PCH_PWRBTN_OUT_N")
	)
	(segment
		(start 413.265366 -57.635902)
		(end 413.670496 -57.230772)
		(width 0.10795)
		(layer "B.Cu")
		(net "FM_PCH_PWRBTN_OUT_N")
	)
	(segment
		(start 397.637 -38.735)
		(end 398.018 -38.735)
		(width 0.10795)
		(layer "B.Cu")
		(net "FM_PCH_PWRBTN_OUT_N")
	)
	(segment
		(start 395.61008 -38.9382)
		(end 395.61008 -39.497)
		(width 0.10795)
		(layer "B.Cu")
		(net "FM_PCH_PWRBTN_OUT_N")
	)
	(segment
		(start 402.742146 -49.79924)
		(end 402.742146 -48.121316)
		(width 0.10795)
		(layer "B.Cu")
		(net "FM_PCH_PWRBTN_OUT_N")
	)
	(segment
		(start 395.61008 -39.497)
		(end 396.11808 -40.005)
		(width 0.10795)
		(layer "B.Cu")
		(net "FM_PCH_PWRBTN_OUT_N")
	)
	(segment
		(start 396.875 -40.005)
		(end 397.637 -39.243)
		(width 0.10795)
		(layer "B.Cu")
		(net "FM_PCH_PWRBTN_OUT_N")
	)
	(segment
		(start 398.145 -40.425116)
		(end 398.145 -40.1574)
		(width 0.10795)
		(layer "B.Cu")
		(net "FM_PCH_PWRBTN_OUT_N")
	)
	(segment
		(start 397.718788 -40.851328)
		(end 398.145 -40.425116)
		(width 0.10795)
		(layer "B.Cu")
		(net "FM_PCH_PWRBTN_OUT_N")
	)
	(segment
		(start 403.403816 -57.735216)
		(end 403.403816 -50.46091)
		(width 0.10795)
		(layer "B.Cu")
		(net "FM_PCH_PWRBTN_OUT_N")
	)
	(segment
		(start 403.848316 -58.179716)
		(end 403.403816 -57.735216)
		(width 0.10795)
		(layer "B.Cu")
		(net "FM_PCH_PWRBTN_OUT_N")
	)
	(segment
		(start 412.136844 -57.635902)
		(end 413.265366 -57.635902)
		(width 0.10795)
		(layer "B.Cu")
		(net "FM_PCH_PWRBTN_OUT_N")
	)
	(segment
		(start 398.018 -38.735)
		(end 398.145 -38.862)
		(width 0.10795)
		(layer "B.Cu")
		(net "FM_PCH_PWRBTN_OUT_N")
	)
	(segment
		(start 402.742146 -48.121316)
		(end 397.718788 -43.097958)
		(width 0.10795)
		(layer "B.Cu")
		(net "FM_PCH_PWRBTN_OUT_N")
	)
	(segment
		(start 411.59303 -58.179716)
		(end 412.136844 -57.635902)
		(width 0.10795)
		(layer "B.Cu")
		(net "FM_PCH_PWRBTN_OUT_N")
	)
	(segment
		(start 403.403816 -50.46091)
		(end 402.742146 -49.79924)
		(width 0.10795)
		(layer "B.Cu")
		(net "FM_PCH_PWRBTN_OUT_N")
	)
	(segment
		(start 397.637 -39.243)
		(end 397.637 -38.735)
		(width 0.10795)
		(layer "B.Cu")
		(net "FM_PCH_PWRBTN_OUT_N")
	)
	(segment
		(start 398.145 -38.862)
		(end 398.145 -40.1574)
		(width 0.10795)
		(layer "B.Cu")
		(net "FM_PCH_PWRBTN_OUT_N")
	)
	(segment
		(start 397.718788 -43.097958)
		(end 397.718788 -40.851328)
		(width 0.10795)
		(layer "B.Cu")
		(net "FM_PCH_PWRBTN_OUT_N")
	)
	(segment
		(start 401.088352 -92.169234)
		(end 401.088352 -90.120216)
		(width 0.089408)
		(layer "In9.Cu")
		(net "FM_PCH_PWRBTN_OUT_N")
	)
	(segment
		(start 412.242 -68.26377)
		(end 412.242 -66.81978)
		(width 0.089408)
		(layer "In9.Cu")
		(net "FM_PCH_PWRBTN_OUT_N")
	)
	(segment
		(start 395.724634 -96.480376)
		(end 396.067534 -96.137476)
		(width 0.089408)
		(layer "In9.Cu")
		(net "FM_PCH_PWRBTN_OUT_N")
	)
	(segment
		(start 406.07742 -78.982316)
		(end 405.5745 -78.479396)
		(width 0.089408)
		(layer "In9.Cu")
		(net "FM_PCH_PWRBTN_OUT_N")
	)
	(segment
		(start 412.712408 -63.200026)
		(end 412.712408 -62.883542)
		(width 0.089408)
		(layer "In9.Cu")
		(net "FM_PCH_PWRBTN_OUT_N")
	)
	(segment
		(start 405.5745 -75.116182)
		(end 410.059632 -70.63105)
		(width 0.089408)
		(layer "In9.Cu")
		(net "FM_PCH_PWRBTN_OUT_N")
	)
	(segment
		(start 401.088352 -90.120216)
		(end 405.441658 -85.76691)
		(width 0.089408)
		(layer "In9.Cu")
		(net "FM_PCH_PWRBTN_OUT_N")
	)
	(segment
		(start 396.063216 -96.133158)
		(end 396.063216 -95.448882)
		(width 0.089408)
		(layer "In9.Cu")
		(net "FM_PCH_PWRBTN_OUT_N")
	)
	(segment
		(start 405.441658 -85.76691)
		(end 405.441658 -85.63229)
		(width 0.089408)
		(layer "In9.Cu")
		(net "FM_PCH_PWRBTN_OUT_N")
	)
	(segment
		(start 412.081472 -59.933078)
		(end 412.081472 -59.1693)
		(width 0.089408)
		(layer "In9.Cu")
		(net "FM_PCH_PWRBTN_OUT_N")
	)
	(segment
		(start 397.286226 -94.225872)
		(end 399.031714 -94.225872)
		(width 0.089408)
		(layer "In9.Cu")
		(net "FM_PCH_PWRBTN_OUT_N")
	)
	(segment
		(start 412.711646 -66.341498)
		(end 412.711646 -65.862708)
		(width 0.089408)
		(layer "In9.Cu")
		(net "FM_PCH_PWRBTN_OUT_N")
	)
	(segment
		(start 412.7119 -63.358522)
		(end 412.712154 -63.358268)
		(width 0.089408)
		(layer "In9.Cu")
		(net "FM_PCH_PWRBTN_OUT_N")
	)
	(segment
		(start 410.059632 -70.63105)
		(end 410.870654 -70.63105)
		(width 0.089408)
		(layer "In9.Cu")
		(net "FM_PCH_PWRBTN_OUT_N")
	)
	(segment
		(start 406.07742 -84.996528)
		(end 406.07742 -78.982316)
		(width 0.089408)
		(layer "In9.Cu")
		(net "FM_PCH_PWRBTN_OUT_N")
	)
	(segment
		(start 405.441658 -85.63229)
		(end 406.07742 -84.996528)
		(width 0.089408)
		(layer "In9.Cu")
		(net "FM_PCH_PWRBTN_OUT_N")
	)
	(segment
		(start 396.063216 -95.448882)
		(end 397.286226 -94.225872)
		(width 0.089408)
		(layer "In9.Cu")
		(net "FM_PCH_PWRBTN_OUT_N")
	)
	(segment
		(start 411.640274 -69.86143)
		(end 411.640274 -68.865496)
		(width 0.089408)
		(layer "In9.Cu")
		(net "FM_PCH_PWRBTN_OUT_N")
	)
	(segment
		(start 412.712154 -63.358268)
		(end 412.712154 -63.20028)
		(width 0.089408)
		(layer "In9.Cu")
		(net "FM_PCH_PWRBTN_OUT_N")
	)
	(segment
		(start 396.063216 -97.256854)
		(end 395.724634 -96.918272)
		(width 0.089408)
		(layer "In9.Cu")
		(net "FM_PCH_PWRBTN_OUT_N")
	)
	(segment
		(start 396.067534 -96.137476)
		(end 396.063216 -96.133158)
		(width 0.089408)
		(layer "In9.Cu")
		(net "FM_PCH_PWRBTN_OUT_N")
	)
	(segment
		(start 413.670496 -57.580276)
		(end 413.670496 -57.230772)
		(width 0.089408)
		(layer "In9.Cu")
		(net "FM_PCH_PWRBTN_OUT_N")
	)
	(segment
		(start 412.712408 -62.883542)
		(end 412.298388 -62.469522)
		(width 0.089408)
		(layer "In9.Cu")
		(net "FM_PCH_PWRBTN_OUT_N")
	)
	(segment
		(start 399.031714 -94.225872)
		(end 401.088352 -92.169234)
		(width 0.089408)
		(layer "In9.Cu")
		(net "FM_PCH_PWRBTN_OUT_N")
	)
	(segment
		(start 412.7119 -65.707768)
		(end 412.711646 -65.707514)
		(width 0.089408)
		(layer "In9.Cu")
		(net "FM_PCH_PWRBTN_OUT_N")
	)
	(segment
		(start 410.870654 -70.63105)
		(end 411.640274 -69.86143)
		(width 0.089408)
		(layer "In9.Cu")
		(net "FM_PCH_PWRBTN_OUT_N")
	)
	(segment
		(start 412.7119 -63.51651)
		(end 412.7119 -63.358522)
		(width 0.089408)
		(layer "In9.Cu")
		(net "FM_PCH_PWRBTN_OUT_N")
	)
	(segment
		(start 412.298388 -60.149994)
		(end 412.081472 -59.933078)
		(width 0.089408)
		(layer "In9.Cu")
		(net "FM_PCH_PWRBTN_OUT_N")
	)
	(segment
		(start 411.640274 -68.865496)
		(end 412.242 -68.26377)
		(width 0.089408)
		(layer "In9.Cu")
		(net "FM_PCH_PWRBTN_OUT_N")
	)
	(segment
		(start 412.712154 -63.20028)
		(end 412.712408 -63.200026)
		(width 0.089408)
		(layer "In9.Cu")
		(net "FM_PCH_PWRBTN_OUT_N")
	)
	(segment
		(start 412.242 -66.81978)
		(end 412.685738 -66.376042)
		(width 0.089408)
		(layer "In9.Cu")
		(net "FM_PCH_PWRBTN_OUT_N")
	)
	(segment
		(start 412.711646 -65.862708)
		(end 412.7119 -65.862454)
		(width 0.089408)
		(layer "In9.Cu")
		(net "FM_PCH_PWRBTN_OUT_N")
	)
	(segment
		(start 405.5745 -78.479396)
		(end 405.5745 -75.116182)
		(width 0.089408)
		(layer "In9.Cu")
		(net "FM_PCH_PWRBTN_OUT_N")
	)
	(segment
		(start 412.711646 -65.707514)
		(end 412.711646 -63.516764)
		(width 0.089408)
		(layer "In9.Cu")
		(net "FM_PCH_PWRBTN_OUT_N")
	)
	(segment
		(start 412.7119 -65.862454)
		(end 412.7119 -65.707768)
		(width 0.089408)
		(layer "In9.Cu")
		(net "FM_PCH_PWRBTN_OUT_N")
	)
	(segment
		(start 395.724634 -96.918272)
		(end 395.724634 -96.480376)
		(width 0.089408)
		(layer "In9.Cu")
		(net "FM_PCH_PWRBTN_OUT_N")
	)
	(segment
		(start 412.711646 -63.516764)
		(end 412.7119 -63.51651)
		(width 0.089408)
		(layer "In9.Cu")
		(net "FM_PCH_PWRBTN_OUT_N")
	)
	(segment
		(start 412.081472 -59.1693)
		(end 413.670496 -57.580276)
		(width 0.089408)
		(layer "In9.Cu")
		(net "FM_PCH_PWRBTN_OUT_N")
	)
	(segment
		(start 396.063216 -97.951036)
		(end 396.063216 -97.256854)
		(width 0.089408)
		(layer "In9.Cu")
		(net "FM_PCH_PWRBTN_OUT_N")
	)
	(segment
		(start 395.66215 -99.322636)
		(end 395.756384 -99.228402)
		(width 0.089408)
		(layer "In9.Cu")
		(net "FM_PCH_PWRBTN_OUT_N")
	)
	(segment
		(start 412.298388 -62.469522)
		(end 412.298388 -60.149994)
		(width 0.089408)
		(layer "In9.Cu")
		(net "FM_PCH_PWRBTN_OUT_N")
	)
	(segment
		(start 412.685738 -66.376042)
		(end 412.685738 -66.367406)
		(width 0.089408)
		(layer "In9.Cu")
		(net "FM_PCH_PWRBTN_OUT_N")
	)
	(segment
		(start 395.756384 -99.228402)
		(end 395.756384 -98.257868)
		(width 0.089408)
		(layer "In9.Cu")
		(net "FM_PCH_PWRBTN_OUT_N")
	)
	(segment
		(start 395.756384 -98.257868)
		(end 396.063216 -97.951036)
		(width 0.089408)
		(layer "In9.Cu")
		(net "FM_PCH_PWRBTN_OUT_N")
	)
	(segment
		(start 412.685738 -66.367406)
		(end 412.711646 -66.341498)
		(width 0.089408)
		(layer "In9.Cu")
		(net "FM_PCH_PWRBTN_OUT_N")
	)
	(segment
		(start 388.23265 -99.55276)
		(end 388.72795 -99.322636)
		(width 0.10795)
		(layer "F.Cu")
		(net "FM_MEM_THERM_EVENT_PCH_N")
	)
	(segment
		(start 369.545108 -75.894692)
		(end 369.944904 -75.494896)
		(width 0.1016)
		(layer "F.Cu")
		(net "FM_MEM_THERM_EVENT_PCH_N")
	)
	(segment
		(start 417.490148 -28.934664)
		(end 417.890198 -28.534614)
		(width 0.10795)
		(layer "F.Cu")
		(net "FM_MEM_THERM_EVENT_PCH_N")
	)
	(via
		(at 369.545108 -75.894692)
		(size 0.4572)
		(drill 0.2032)
		(layers "F.Cu" "B.Cu")
		(net "FM_MEM_THERM_EVENT_PCH_N")
	)
	(via
		(at 380.69774 -27.50566)
		(size 0.508)
		(drill 0.254)
		(layers "F.Cu" "B.Cu")
		(net "FM_MEM_THERM_EVENT_PCH_N")
	)
	(via
		(at 417.890198 -28.534614)
		(size 0.4572)
		(drill 0.2032)
		(layers "F.Cu" "B.Cu")
		(net "FM_MEM_THERM_EVENT_PCH_N")
	)
	(via
		(at 388.72795 -99.322636)
		(size 0.508)
		(drill 0.254)
		(layers "F.Cu" "B.Cu")
		(net "FM_MEM_THERM_EVENT_PCH_N")
	)
	(segment
		(start 368.590576 -79.468218)
		(end 368.371882 -79.249524)
		(width 0.089408)
		(layer "In2.Cu")
		(net "FM_MEM_THERM_EVENT_PCH_N")
	)
	(segment
		(start 369.118642 -79.739998)
		(end 368.846862 -79.468218)
		(width 0.089408)
		(layer "In2.Cu")
		(net "FM_MEM_THERM_EVENT_PCH_N")
	)
	(segment
		(start 369.411758 -80.2894)
		(end 369.118642 -79.996284)
		(width 0.089408)
		(layer "In2.Cu")
		(net "FM_MEM_THERM_EVENT_PCH_N")
	)
	(segment
		(start 377.0376 -97.64776)
		(end 377.0376 -96.976946)
		(width 0.089408)
		(layer "In2.Cu")
		(net "FM_MEM_THERM_EVENT_PCH_N")
	)
	(segment
		(start 374.880632 -84.880958)
		(end 373.615966 -83.616292)
		(width 0.089408)
		(layer "In2.Cu")
		(net "FM_MEM_THERM_EVENT_PCH_N")
	)
	(segment
		(start 368.846862 -79.468218)
		(end 368.590576 -79.468218)
		(width 0.089408)
		(layer "In2.Cu")
		(net "FM_MEM_THERM_EVENT_PCH_N")
	)
	(segment
		(start 369.118388 -76.321412)
		(end 369.545108 -75.894692)
		(width 0.089408)
		(layer "In2.Cu")
		(net "FM_MEM_THERM_EVENT_PCH_N")
	)
	(segment
		(start 388.6327 -98.485706)
		(end 388.6327 -98.45294)
		(width 0.0889)
		(layer "In2.Cu")
		(net "FM_MEM_THERM_EVENT_PCH_N")
	)
	(segment
		(start 369.978178 -81.033366)
		(end 369.978178 -80.600042)
		(width 0.089408)
		(layer "In2.Cu")
		(net "FM_MEM_THERM_EVENT_PCH_N")
	)
	(segment
		(start 374.31091 -93.869256)
		(end 374.053608 -93.869256)
		(width 0.089408)
		(layer "In2.Cu")
		(net "FM_MEM_THERM_EVENT_PCH_N")
	)
	(segment
		(start 369.978178 -80.600042)
		(end 369.667536 -80.2894)
		(width 0.089408)
		(layer "In2.Cu")
		(net "FM_MEM_THERM_EVENT_PCH_N")
	)
	(segment
		(start 368.371882 -76.540106)
		(end 368.590576 -76.321412)
		(width 0.089408)
		(layer "In2.Cu")
		(net "FM_MEM_THERM_EVENT_PCH_N")
	)
	(segment
		(start 370.160804 -81.215738)
		(end 370.16055 -81.215738)
		(width 0.089408)
		(layer "In2.Cu")
		(net "FM_MEM_THERM_EVENT_PCH_N")
	)
	(segment
		(start 368.371882 -79.249524)
		(end 368.371882 -76.540106)
		(width 0.089408)
		(layer "In2.Cu")
		(net "FM_MEM_THERM_EVENT_PCH_N")
	)
	(segment
		(start 373.41302 -89.147396)
		(end 374.880632 -87.679784)
		(width 0.089408)
		(layer "In2.Cu")
		(net "FM_MEM_THERM_EVENT_PCH_N")
	)
	(segment
		(start 373.41302 -93.228668)
		(end 373.41302 -89.147396)
		(width 0.089408)
		(layer "In2.Cu")
		(net "FM_MEM_THERM_EVENT_PCH_N")
	)
	(segment
		(start 369.118642 -79.996284)
		(end 369.118642 -79.739998)
		(width 0.089408)
		(layer "In2.Cu")
		(net "FM_MEM_THERM_EVENT_PCH_N")
	)
	(segment
		(start 376.580654 -96.52)
		(end 376.580654 -96.139)
		(width 0.089408)
		(layer "In2.Cu")
		(net "FM_MEM_THERM_EVENT_PCH_N")
	)
	(segment
		(start 368.590576 -76.321412)
		(end 369.118388 -76.321412)
		(width 0.089408)
		(layer "In2.Cu")
		(net "FM_MEM_THERM_EVENT_PCH_N")
	)
	(segment
		(start 373.615966 -83.616292)
		(end 372.561358 -83.616292)
		(width 0.089408)
		(layer "In2.Cu")
		(net "FM_MEM_THERM_EVENT_PCH_N")
	)
	(segment
		(start 377.0376 -96.976946)
		(end 376.580654 -96.52)
		(width 0.089408)
		(layer "In2.Cu")
		(net "FM_MEM_THERM_EVENT_PCH_N")
	)
	(segment
		(start 376.580654 -96.139)
		(end 374.31091 -93.869256)
		(width 0.089408)
		(layer "In2.Cu")
		(net "FM_MEM_THERM_EVENT_PCH_N")
	)
	(segment
		(start 377.41352 -98.02368)
		(end 377.229624 -97.839784)
		(width 0.0889)
		(layer "In2.Cu")
		(net "FM_MEM_THERM_EVENT_PCH_N")
	)
	(segment
		(start 372.561358 -83.616292)
		(end 370.160804 -81.215738)
		(width 0.089408)
		(layer "In2.Cu")
		(net "FM_MEM_THERM_EVENT_PCH_N")
	)
	(segment
		(start 370.16055 -81.215738)
		(end 369.978178 -81.033366)
		(width 0.089408)
		(layer "In2.Cu")
		(net "FM_MEM_THERM_EVENT_PCH_N")
	)
	(segment
		(start 374.053608 -93.869256)
		(end 373.41302 -93.228668)
		(width 0.089408)
		(layer "In2.Cu")
		(net "FM_MEM_THERM_EVENT_PCH_N")
	)
	(segment
		(start 369.667536 -80.2894)
		(end 369.411758 -80.2894)
		(width 0.089408)
		(layer "In2.Cu")
		(net "FM_MEM_THERM_EVENT_PCH_N")
	)
	(segment
		(start 377.229624 -97.839784)
		(end 377.0376 -97.64776)
		(width 0.089408)
		(layer "In2.Cu")
		(net "FM_MEM_THERM_EVENT_PCH_N")
	)
	(segment
		(start 374.880632 -87.679784)
		(end 374.880632 -84.880958)
		(width 0.089408)
		(layer "In2.Cu")
		(net "FM_MEM_THERM_EVENT_PCH_N")
	)
	(arc
		(start 380.507748 -98.117406)
		(mid 380.30785 -98.063907)
		(end 380.107952 -98.117406)
		(width 0.0889)
		(layer "In2.Cu")
		(net "FM_MEM_THERM_EVENT_PCH_N")
	)
	(arc
		(start 382.488948 -98.117406)
		(mid 382.28905 -98.063907)
		(end 382.089152 -98.117406)
		(width 0.0889)
		(layer "In2.Cu")
		(net "FM_MEM_THERM_EVENT_PCH_N")
	)
	(arc
		(start 383.079752 -98.117406)
		(mid 382.78435 -98.196537)
		(end 382.488948 -98.117406)
		(width 0.0889)
		(layer "In2.Cu")
		(net "FM_MEM_THERM_EVENT_PCH_N")
	)
	(arc
		(start 386.051552 -98.117406)
		(mid 385.75615 -98.196537)
		(end 385.460748 -98.117406)
		(width 0.0889)
		(layer "In2.Cu")
		(net "FM_MEM_THERM_EVENT_PCH_N")
	)
	(arc
		(start 388.032752 -98.117406)
		(mid 387.73735 -98.196537)
		(end 387.441948 -98.117406)
		(width 0.0889)
		(layer "In2.Cu")
		(net "FM_MEM_THERM_EVENT_PCH_N")
	)
	(arc
		(start 385.460748 -98.117406)
		(mid 385.26085 -98.063907)
		(end 385.060952 -98.117406)
		(width 0.0889)
		(layer "In2.Cu")
		(net "FM_MEM_THERM_EVENT_PCH_N")
	)
	(arc
		(start 388.6327 -98.45294)
		(mid 388.427998 -98.114825)
		(end 388.032752 -98.117406)
		(width 0.0889)
		(layer "In2.Cu")
		(net "FM_MEM_THERM_EVENT_PCH_N")
	)
	(arc
		(start 384.470148 -98.117406)
		(mid 384.27025 -98.063907)
		(end 384.070352 -98.117406)
		(width 0.0889)
		(layer "In2.Cu")
		(net "FM_MEM_THERM_EVENT_PCH_N")
	)
	(arc
		(start 384.070352 -98.117406)
		(mid 383.77495 -98.196537)
		(end 383.479548 -98.117406)
		(width 0.0889)
		(layer "In2.Cu")
		(net "FM_MEM_THERM_EVENT_PCH_N")
	)
	(arc
		(start 377.454414 -98.060764)
		(mid 377.433533 -98.042701)
		(end 377.41352 -98.02368)
		(width 0.0889)
		(layer "In2.Cu")
		(net "FM_MEM_THERM_EVENT_PCH_N")
	)
	(arc
		(start 387.441948 -98.117406)
		(mid 387.24205 -98.063907)
		(end 387.042152 -98.117406)
		(width 0.0889)
		(layer "In2.Cu")
		(net "FM_MEM_THERM_EVENT_PCH_N")
	)
	(arc
		(start 388.72795 -99.322636)
		(mid 388.656591 -98.906872)
		(end 388.6327 -98.485706)
		(width 0.0889)
		(layer "In2.Cu")
		(net "FM_MEM_THERM_EVENT_PCH_N")
	)
	(arc
		(start 385.060952 -98.117406)
		(mid 384.76555 -98.196537)
		(end 384.470148 -98.117406)
		(width 0.0889)
		(layer "In2.Cu")
		(net "FM_MEM_THERM_EVENT_PCH_N")
	)
	(arc
		(start 383.479548 -98.117406)
		(mid 383.27965 -98.063907)
		(end 383.079752 -98.117406)
		(width 0.0889)
		(layer "In2.Cu")
		(net "FM_MEM_THERM_EVENT_PCH_N")
	)
	(arc
		(start 386.451348 -98.117406)
		(mid 386.25145 -98.063907)
		(end 386.051552 -98.117406)
		(width 0.0889)
		(layer "In2.Cu")
		(net "FM_MEM_THERM_EVENT_PCH_N")
	)
	(arc
		(start 387.042152 -98.117406)
		(mid 386.74675 -98.196537)
		(end 386.451348 -98.117406)
		(width 0.0889)
		(layer "In2.Cu")
		(net "FM_MEM_THERM_EVENT_PCH_N")
	)
	(arc
		(start 381.498348 -98.117406)
		(mid 381.29845 -98.063907)
		(end 381.098552 -98.117406)
		(width 0.0889)
		(layer "In2.Cu")
		(net "FM_MEM_THERM_EVENT_PCH_N")
	)
	(arc
		(start 382.089152 -98.117406)
		(mid 381.79375 -98.196537)
		(end 381.498348 -98.117406)
		(width 0.0889)
		(layer "In2.Cu")
		(net "FM_MEM_THERM_EVENT_PCH_N")
	)
	(arc
		(start 378.126752 -98.117406)
		(mid 377.781713 -98.194449)
		(end 377.454414 -98.060764)
		(width 0.0889)
		(layer "In2.Cu")
		(net "FM_MEM_THERM_EVENT_PCH_N")
	)
	(arc
		(start 378.526548 -98.117406)
		(mid 378.32665 -98.063907)
		(end 378.126752 -98.117406)
		(width 0.0889)
		(layer "In2.Cu")
		(net "FM_MEM_THERM_EVENT_PCH_N")
	)
	(arc
		(start 381.098552 -98.117406)
		(mid 380.80315 -98.196537)
		(end 380.507748 -98.117406)
		(width 0.0889)
		(layer "In2.Cu")
		(net "FM_MEM_THERM_EVENT_PCH_N")
	)
	(arc
		(start 379.117352 -98.117406)
		(mid 378.82195 -98.196537)
		(end 378.526548 -98.117406)
		(width 0.0889)
		(layer "In2.Cu")
		(net "FM_MEM_THERM_EVENT_PCH_N")
	)
	(arc
		(start 379.517148 -98.117406)
		(mid 379.31725 -98.063907)
		(end 379.117352 -98.117406)
		(width 0.0889)
		(layer "In2.Cu")
		(net "FM_MEM_THERM_EVENT_PCH_N")
	)
	(arc
		(start 380.107952 -98.117406)
		(mid 379.81255 -98.196537)
		(end 379.517148 -98.117406)
		(width 0.0889)
		(layer "In2.Cu")
		(net "FM_MEM_THERM_EVENT_PCH_N")
	)
	(segment
		(start 391.767568 -29.449268)
		(end 389.609076 -29.449268)
		(width 0.089408)
		(layer "In4.Cu")
		(net "FM_MEM_THERM_EVENT_PCH_N")
	)
	(segment
		(start 386.313934 -31.3563)
		(end 386.313934 -30.013148)
		(width 0.089408)
		(layer "In4.Cu")
		(net "FM_MEM_THERM_EVENT_PCH_N")
	)
	(segment
		(start 408.985974 -27.35961)
		(end 408.401774 -27.94381)
		(width 0.089408)
		(layer "In4.Cu")
		(net "FM_MEM_THERM_EVENT_PCH_N")
	)
	(segment
		(start 400.646138 -28.301696)
		(end 400.218402 -28.729432)
		(width 0.089408)
		(layer "In4.Cu")
		(net "FM_MEM_THERM_EVENT_PCH_N")
	)
	(segment
		(start 406.839674 -29.184854)
		(end 405.794464 -29.184854)
		(width 0.089408)
		(layer "In4.Cu")
		(net "FM_MEM_THERM_EVENT_PCH_N")
	)
	(segment
		(start 417.890198 -28.534614)
		(end 417.890198 -28.290012)
		(width 0.089408)
		(layer "In4.Cu")
		(net "FM_MEM_THERM_EVENT_PCH_N")
	)
	(segment
		(start 400.218402 -28.729432)
		(end 392.487404 -28.729432)
		(width 0.089408)
		(layer "In4.Cu")
		(net "FM_MEM_THERM_EVENT_PCH_N")
	)
	(segment
		(start 381.573024 -27.158696)
		(end 381.044704 -27.158696)
		(width 0.089408)
		(layer "In4.Cu")
		(net "FM_MEM_THERM_EVENT_PCH_N")
	)
	(segment
		(start 386.313934 -30.013148)
		(end 384.681984 -28.381198)
		(width 0.089408)
		(layer "In4.Cu")
		(net "FM_MEM_THERM_EVENT_PCH_N")
	)
	(segment
		(start 405.794464 -29.184854)
		(end 405.46401 -29.515308)
		(width 0.089408)
		(layer "In4.Cu")
		(net "FM_MEM_THERM_EVENT_PCH_N")
	)
	(segment
		(start 389.609076 -29.449268)
		(end 388.378192 -30.680152)
		(width 0.089408)
		(layer "In4.Cu")
		(net "FM_MEM_THERM_EVENT_PCH_N")
	)
	(segment
		(start 402.191474 -29.515308)
		(end 400.977862 -28.301696)
		(width 0.089408)
		(layer "In4.Cu")
		(net "FM_MEM_THERM_EVENT_PCH_N")
	)
	(segment
		(start 410.636212 -27.34818)
		(end 410.624782 -27.35961)
		(width 0.089408)
		(layer "In4.Cu")
		(net "FM_MEM_THERM_EVENT_PCH_N")
	)
	(segment
		(start 408.401774 -27.94381)
		(end 408.080718 -27.94381)
		(width 0.089408)
		(layer "In4.Cu")
		(net "FM_MEM_THERM_EVENT_PCH_N")
	)
	(segment
		(start 388.378192 -30.680152)
		(end 388.378192 -31.515558)
		(width 0.089408)
		(layer "In4.Cu")
		(net "FM_MEM_THERM_EVENT_PCH_N")
	)
	(segment
		(start 410.624782 -27.35961)
		(end 408.985974 -27.35961)
		(width 0.089408)
		(layer "In4.Cu")
		(net "FM_MEM_THERM_EVENT_PCH_N")
	)
	(segment
		(start 405.46401 -29.515308)
		(end 402.191474 -29.515308)
		(width 0.089408)
		(layer "In4.Cu")
		(net "FM_MEM_THERM_EVENT_PCH_N")
	)
	(segment
		(start 388.378192 -31.515558)
		(end 387.954774 -31.938976)
		(width 0.089408)
		(layer "In4.Cu")
		(net "FM_MEM_THERM_EVENT_PCH_N")
	)
	(segment
		(start 400.977862 -28.301696)
		(end 400.646138 -28.301696)
		(width 0.089408)
		(layer "In4.Cu")
		(net "FM_MEM_THERM_EVENT_PCH_N")
	)
	(segment
		(start 416.948366 -27.34818)
		(end 410.636212 -27.34818)
		(width 0.089408)
		(layer "In4.Cu")
		(net "FM_MEM_THERM_EVENT_PCH_N")
	)
	(segment
		(start 381.044704 -27.158696)
		(end 380.69774 -27.50566)
		(width 0.089408)
		(layer "In4.Cu")
		(net "FM_MEM_THERM_EVENT_PCH_N")
	)
	(segment
		(start 382.795526 -28.381198)
		(end 381.573024 -27.158696)
		(width 0.089408)
		(layer "In4.Cu")
		(net "FM_MEM_THERM_EVENT_PCH_N")
	)
	(segment
		(start 392.487404 -28.729432)
		(end 391.767568 -29.449268)
		(width 0.089408)
		(layer "In4.Cu")
		(net "FM_MEM_THERM_EVENT_PCH_N")
	)
	(segment
		(start 386.89661 -31.938976)
		(end 386.313934 -31.3563)
		(width 0.089408)
		(layer "In4.Cu")
		(net "FM_MEM_THERM_EVENT_PCH_N")
	)
	(segment
		(start 384.681984 -28.381198)
		(end 382.795526 -28.381198)
		(width 0.089408)
		(layer "In4.Cu")
		(net "FM_MEM_THERM_EVENT_PCH_N")
	)
	(segment
		(start 417.890198 -28.290012)
		(end 416.948366 -27.34818)
		(width 0.089408)
		(layer "In4.Cu")
		(net "FM_MEM_THERM_EVENT_PCH_N")
	)
	(segment
		(start 387.954774 -31.938976)
		(end 386.89661 -31.938976)
		(width 0.089408)
		(layer "In4.Cu")
		(net "FM_MEM_THERM_EVENT_PCH_N")
	)
	(segment
		(start 408.080718 -27.94381)
		(end 406.839674 -29.184854)
		(width 0.089408)
		(layer "In4.Cu")
		(net "FM_MEM_THERM_EVENT_PCH_N")
	)
	(segment
		(start 381.377952 -32.819594)
		(end 380.8984 -32.819594)
		(width 0.089408)
		(layer "In9.Cu")
		(net "FM_MEM_THERM_EVENT_PCH_N")
	)
	(segment
		(start 369.171728 -75.521312)
		(end 369.545108 -75.894692)
		(width 0.089408)
		(layer "In9.Cu")
		(net "FM_MEM_THERM_EVENT_PCH_N")
	)
	(segment
		(start 380.8984 -32.819594)
		(end 380.246636 -33.471358)
		(width 0.089408)
		(layer "In9.Cu")
		(net "FM_MEM_THERM_EVENT_PCH_N")
	)
	(segment
		(start 379.73 -44.67733)
		(end 380.075186 -45.022516)
		(width 0.089408)
		(layer "In9.Cu")
		(net "FM_MEM_THERM_EVENT_PCH_N")
	)
	(segment
		(start 379.181614 -57.27573)
		(end 379.181614 -57.746646)
		(width 0.089408)
		(layer "In9.Cu")
		(net "FM_MEM_THERM_EVENT_PCH_N")
	)
	(segment
		(start 368.371882 -69.340476)
		(end 368.371882 -73.963022)
		(width 0.089408)
		(layer "In9.Cu")
		(net "FM_MEM_THERM_EVENT_PCH_N")
	)
	(segment
		(start 379.73 -43.741086)
		(end 379.73 -44.67733)
		(width 0.089408)
		(layer "In9.Cu")
		(net "FM_MEM_THERM_EVENT_PCH_N")
	)
	(segment
		(start 375.416064 -61.8871)
		(end 374.4087 -61.8871)
		(width 0.089408)
		(layer "In9.Cu")
		(net "FM_MEM_THERM_EVENT_PCH_N")
	)
	(segment
		(start 379.184662 -43.195748)
		(end 379.73 -43.741086)
		(width 0.089408)
		(layer "In9.Cu")
		(net "FM_MEM_THERM_EVENT_PCH_N")
	)
	(segment
		(start 376.979434 -42.032428)
		(end 378.142754 -43.195748)
		(width 0.089408)
		(layer "In9.Cu")
		(net "FM_MEM_THERM_EVENT_PCH_N")
	)
	(segment
		(start 370.122704 -64.586358)
		(end 370.122704 -66.228976)
		(width 0.089408)
		(layer "In9.Cu")
		(net "FM_MEM_THERM_EVENT_PCH_N")
	)
	(segment
		(start 380.051056 -45.37837)
		(end 380.051056 -45.384974)
		(width 0.089408)
		(layer "In9.Cu")
		(net "FM_MEM_THERM_EVENT_PCH_N")
	)
	(segment
		(start 372.270274 -63.564008)
		(end 372.269258 -63.565024)
		(width 0.089408)
		(layer "In9.Cu")
		(net "FM_MEM_THERM_EVENT_PCH_N")
	)
	(segment
		(start 374.2182 -62.0776)
		(end 374.2182 -62.7888)
		(width 0.089408)
		(layer "In9.Cu")
		(net "FM_MEM_THERM_EVENT_PCH_N")
	)
	(segment
		(start 380.69774 -27.50566)
		(end 381.044704 -27.158696)
		(width 0.089408)
		(layer "In9.Cu")
		(net "FM_MEM_THERM_EVENT_PCH_N")
	)
	(segment
		(start 381.807466 -27.393138)
		(end 381.807466 -32.39008)
		(width 0.089408)
		(layer "In9.Cu")
		(net "FM_MEM_THERM_EVENT_PCH_N")
	)
	(segment
		(start 369.171728 -74.762868)
		(end 369.171728 -75.521312)
		(width 0.089408)
		(layer "In9.Cu")
		(net "FM_MEM_THERM_EVENT_PCH_N")
	)
	(segment
		(start 369.118642 -68.450714)
		(end 369.118642 -68.850002)
		(width 0.089408)
		(layer "In9.Cu")
		(net "FM_MEM_THERM_EVENT_PCH_N")
	)
	(segment
		(start 374.4087 -61.8871)
		(end 374.2182 -62.0776)
		(width 0.089408)
		(layer "In9.Cu")
		(net "FM_MEM_THERM_EVENT_PCH_N")
	)
	(segment
		(start 381.044704 -27.158696)
		(end 381.573024 -27.158696)
		(width 0.089408)
		(layer "In9.Cu")
		(net "FM_MEM_THERM_EVENT_PCH_N")
	)
	(segment
		(start 373.64797 -62.9666)
		(end 373.050562 -63.564008)
		(width 0.089408)
		(layer "In9.Cu")
		(net "FM_MEM_THERM_EVENT_PCH_N")
	)
	(segment
		(start 374.2182 -62.7888)
		(end 374.0404 -62.9666)
		(width 0.089408)
		(layer "In9.Cu")
		(net "FM_MEM_THERM_EVENT_PCH_N")
	)
	(segment
		(start 380.051056 -45.384974)
		(end 378.60224 -46.83379)
		(width 0.089408)
		(layer "In9.Cu")
		(net "FM_MEM_THERM_EVENT_PCH_N")
	)
	(segment
		(start 378.351288 -54.75986)
		(end 378.351288 -56.445404)
		(width 0.089408)
		(layer "In9.Cu")
		(net "FM_MEM_THERM_EVENT_PCH_N")
	)
	(segment
		(start 380.075186 -45.35424)
		(end 380.051056 -45.37837)
		(width 0.089408)
		(layer "In9.Cu")
		(net "FM_MEM_THERM_EVENT_PCH_N")
	)
	(segment
		(start 371.144038 -63.565024)
		(end 370.122704 -64.586358)
		(width 0.089408)
		(layer "In9.Cu")
		(net "FM_MEM_THERM_EVENT_PCH_N")
	)
	(segment
		(start 369.805204 -67.764152)
		(end 369.118642 -68.450714)
		(width 0.089408)
		(layer "In9.Cu")
		(net "FM_MEM_THERM_EVENT_PCH_N")
	)
	(segment
		(start 368.899948 -69.068696)
		(end 368.643662 -69.068696)
		(width 0.089408)
		(layer "In9.Cu")
		(net "FM_MEM_THERM_EVENT_PCH_N")
	)
	(segment
		(start 376.332242 -60.754514)
		(end 376.332242 -60.970922)
		(width 0.089408)
		(layer "In9.Cu")
		(net "FM_MEM_THERM_EVENT_PCH_N")
	)
	(segment
		(start 369.805204 -66.546476)
		(end 369.805204 -67.764152)
		(width 0.089408)
		(layer "In9.Cu")
		(net "FM_MEM_THERM_EVENT_PCH_N")
	)
	(segment
		(start 372.269258 -63.565024)
		(end 371.144038 -63.565024)
		(width 0.089408)
		(layer "In9.Cu")
		(net "FM_MEM_THERM_EVENT_PCH_N")
	)
	(segment
		(start 378.142754 -43.195748)
		(end 379.184662 -43.195748)
		(width 0.089408)
		(layer "In9.Cu")
		(net "FM_MEM_THERM_EVENT_PCH_N")
	)
	(segment
		(start 380.075186 -45.022516)
		(end 380.075186 -45.35424)
		(width 0.089408)
		(layer "In9.Cu")
		(net "FM_MEM_THERM_EVENT_PCH_N")
	)
	(segment
		(start 370.122704 -66.228976)
		(end 369.805204 -66.546476)
		(width 0.089408)
		(layer "In9.Cu")
		(net "FM_MEM_THERM_EVENT_PCH_N")
	)
	(segment
		(start 380.246636 -33.471358)
		(end 380.246636 -34.078418)
		(width 0.089408)
		(layer "In9.Cu")
		(net "FM_MEM_THERM_EVENT_PCH_N")
	)
	(segment
		(start 376.331988 -60.75426)
		(end 376.332242 -60.754514)
		(width 0.089408)
		(layer "In9.Cu")
		(net "FM_MEM_THERM_EVENT_PCH_N")
	)
	(segment
		(start 379.181614 -57.746646)
		(end 376.331988 -60.596272)
		(width 0.089408)
		(layer "In9.Cu")
		(net "FM_MEM_THERM_EVENT_PCH_N")
	)
	(segment
		(start 381.573024 -27.158696)
		(end 381.807466 -27.393138)
		(width 0.089408)
		(layer "In9.Cu")
		(net "FM_MEM_THERM_EVENT_PCH_N")
	)
	(segment
		(start 374.0404 -62.9666)
		(end 373.64797 -62.9666)
		(width 0.089408)
		(layer "In9.Cu")
		(net "FM_MEM_THERM_EVENT_PCH_N")
	)
	(segment
		(start 380.246636 -34.078418)
		(end 376.979434 -37.34562)
		(width 0.089408)
		(layer "In9.Cu")
		(net "FM_MEM_THERM_EVENT_PCH_N")
	)
	(segment
		(start 373.050562 -63.564008)
		(end 372.270274 -63.564008)
		(width 0.089408)
		(layer "In9.Cu")
		(net "FM_MEM_THERM_EVENT_PCH_N")
	)
	(segment
		(start 376.979434 -37.34562)
		(end 376.979434 -42.032428)
		(width 0.089408)
		(layer "In9.Cu")
		(net "FM_MEM_THERM_EVENT_PCH_N")
	)
	(segment
		(start 376.331988 -60.596272)
		(end 376.331988 -60.75426)
		(width 0.089408)
		(layer "In9.Cu")
		(net "FM_MEM_THERM_EVENT_PCH_N")
	)
	(segment
		(start 378.351288 -56.445404)
		(end 379.181614 -57.27573)
		(width 0.089408)
		(layer "In9.Cu")
		(net "FM_MEM_THERM_EVENT_PCH_N")
	)
	(segment
		(start 378.60224 -46.83379)
		(end 378.60224 -54.508908)
		(width 0.089408)
		(layer "In9.Cu")
		(net "FM_MEM_THERM_EVENT_PCH_N")
	)
	(segment
		(start 368.371882 -73.963022)
		(end 369.171728 -74.762868)
		(width 0.089408)
		(layer "In9.Cu")
		(net "FM_MEM_THERM_EVENT_PCH_N")
	)
	(segment
		(start 376.332242 -60.970922)
		(end 375.416064 -61.8871)
		(width 0.089408)
		(layer "In9.Cu")
		(net "FM_MEM_THERM_EVENT_PCH_N")
	)
	(segment
		(start 378.60224 -54.508908)
		(end 378.351288 -54.75986)
		(width 0.089408)
		(layer "In9.Cu")
		(net "FM_MEM_THERM_EVENT_PCH_N")
	)
	(segment
		(start 368.643662 -69.068696)
		(end 368.371882 -69.340476)
		(width 0.089408)
		(layer "In9.Cu")
		(net "FM_MEM_THERM_EVENT_PCH_N")
	)
	(segment
		(start 381.807466 -32.39008)
		(end 381.377952 -32.819594)
		(width 0.089408)
		(layer "In9.Cu")
		(net "FM_MEM_THERM_EVENT_PCH_N")
	)
	(segment
		(start 369.118642 -68.850002)
		(end 368.899948 -69.068696)
		(width 0.089408)
		(layer "In9.Cu")
		(net "FM_MEM_THERM_EVENT_PCH_N")
	)
	(segment
		(start 430.9491 -25.908)
		(end 430.9491 -25.230836)
		(width 0.10795)
		(layer "F.Cu")
		(net "FM_FLASH_DESC_OVERRIDE")
	)
	(segment
		(start 382.1684 -103.67137)
		(end 382.28905 -103.615236)
		(width 0.10795)
		(layer "F.Cu")
		(net "FM_FLASH_DESC_OVERRIDE")
	)
	(segment
		(start 430.9491 -25.230836)
		(end 431.014378 -25.165558)
		(width 0.10795)
		(layer "F.Cu")
		(net "FM_FLASH_DESC_OVERRIDE")
	)
	(segment
		(start 381.79375 -103.84536)
		(end 382.1684 -103.67137)
		(width 0.10795)
		(layer "F.Cu")
		(net "FM_FLASH_DESC_OVERRIDE")
	)
	(via
		(at 431.014378 -25.165558)
		(size 0.508)
		(drill 0.254)
		(layers "F.Cu" "B.Cu")
		(net "FM_FLASH_DESC_OVERRIDE")
	)
	(via
		(at 387.096 -31.3182)
		(size 0.508)
		(drill 0.254)
		(layers "F.Cu" "B.Cu")
		(net "FM_FLASH_DESC_OVERRIDE")
	)
	(via
		(at 382.28905 -103.615236)
		(size 0.508)
		(drill 0.254)
		(layers "F.Cu" "B.Cu")
		(net "FM_FLASH_DESC_OVERRIDE")
	)
	(segment
		(start 382.28905 -103.615236)
		(end 382.05537 -103.615236)
		(width 0.10795)
		(layer "B.Cu")
		(net "FM_FLASH_DESC_OVERRIDE")
	)
	(segment
		(start 381.584708 -104.085898)
		(end 381.584708 -104.314244)
		(width 0.10795)
		(layer "B.Cu")
		(net "FM_FLASH_DESC_OVERRIDE")
	)
	(segment
		(start 382.05537 -103.615236)
		(end 381.584708 -104.085898)
		(width 0.10795)
		(layer "B.Cu")
		(net "FM_FLASH_DESC_OVERRIDE")
	)
	(segment
		(start 431.014378 -25.165558)
		(end 431.014378 -25.39619)
		(width 0.089408)
		(layer "In4.Cu")
		(net "FM_FLASH_DESC_OVERRIDE")
	)
	(segment
		(start 396.913354 -27.731212)
		(end 396.628366 -28.0162)
		(width 0.089408)
		(layer "In4.Cu")
		(net "FM_FLASH_DESC_OVERRIDE")
	)
	(segment
		(start 403.997668 -28.2702)
		(end 402.165566 -28.2702)
		(width 0.089408)
		(layer "In4.Cu")
		(net "FM_FLASH_DESC_OVERRIDE")
	)
	(segment
		(start 387.28777 -31.12643)
		(end 387.096 -31.3182)
		(width 0.089408)
		(layer "In4.Cu")
		(net "FM_FLASH_DESC_OVERRIDE")
	)
	(segment
		(start 399.74266 -27.91968)
		(end 399.554192 -27.731212)
		(width 0.089408)
		(layer "In4.Cu")
		(net "FM_FLASH_DESC_OVERRIDE")
	)
	(segment
		(start 401.486878 -28.2702)
		(end 401.136358 -27.91968)
		(width 0.089408)
		(layer "In4.Cu")
		(net "FM_FLASH_DESC_OVERRIDE")
	)
	(segment
		(start 388.185406 -30.86227)
		(end 387.921246 -31.12643)
		(width 0.089408)
		(layer "In4.Cu")
		(net "FM_FLASH_DESC_OVERRIDE")
	)
	(segment
		(start 420.773606 -26.21915)
		(end 420.148766 -25.59431)
		(width 0.089408)
		(layer "In4.Cu")
		(net "FM_FLASH_DESC_OVERRIDE")
	)
	(segment
		(start 418.554154 -26.369264)
		(end 409.655772 -26.369264)
		(width 0.089408)
		(layer "In4.Cu")
		(net "FM_FLASH_DESC_OVERRIDE")
	)
	(segment
		(start 401.136358 -27.91968)
		(end 399.74266 -27.91968)
		(width 0.089408)
		(layer "In4.Cu")
		(net "FM_FLASH_DESC_OVERRIDE")
	)
	(segment
		(start 405.278336 -28.894532)
		(end 404.622 -28.894532)
		(width 0.089408)
		(layer "In4.Cu")
		(net "FM_FLASH_DESC_OVERRIDE")
	)
	(segment
		(start 405.414988 -28.75788)
		(end 405.278336 -28.894532)
		(width 0.089408)
		(layer "In4.Cu")
		(net "FM_FLASH_DESC_OVERRIDE")
	)
	(segment
		(start 423.876216 -26.905458)
		(end 423.189908 -26.21915)
		(width 0.089408)
		(layer "In4.Cu")
		(net "FM_FLASH_DESC_OVERRIDE")
	)
	(segment
		(start 409.046934 -26.978102)
		(end 408.827478 -26.978102)
		(width 0.089408)
		(layer "In4.Cu")
		(net "FM_FLASH_DESC_OVERRIDE")
	)
	(segment
		(start 390.771888 -28.0162)
		(end 388.185406 -30.602682)
		(width 0.089408)
		(layer "In4.Cu")
		(net "FM_FLASH_DESC_OVERRIDE")
	)
	(segment
		(start 401.744434 -28.2702)
		(end 401.486878 -28.2702)
		(width 0.089408)
		(layer "In4.Cu")
		(net "FM_FLASH_DESC_OVERRIDE")
	)
	(segment
		(start 431.014378 -25.39619)
		(end 429.50511 -26.905458)
		(width 0.089408)
		(layer "In4.Cu")
		(net "FM_FLASH_DESC_OVERRIDE")
	)
	(segment
		(start 407.898092 -27.562302)
		(end 406.702514 -28.75788)
		(width 0.089408)
		(layer "In4.Cu")
		(net "FM_FLASH_DESC_OVERRIDE")
	)
	(segment
		(start 406.702514 -28.75788)
		(end 405.414988 -28.75788)
		(width 0.089408)
		(layer "In4.Cu")
		(net "FM_FLASH_DESC_OVERRIDE")
	)
	(segment
		(start 419.329108 -25.59431)
		(end 418.554154 -26.369264)
		(width 0.089408)
		(layer "In4.Cu")
		(net "FM_FLASH_DESC_OVERRIDE")
	)
	(segment
		(start 408.243278 -27.562302)
		(end 407.898092 -27.562302)
		(width 0.089408)
		(layer "In4.Cu")
		(net "FM_FLASH_DESC_OVERRIDE")
	)
	(segment
		(start 388.185406 -30.602682)
		(end 388.185406 -30.86227)
		(width 0.089408)
		(layer "In4.Cu")
		(net "FM_FLASH_DESC_OVERRIDE")
	)
	(segment
		(start 409.655772 -26.369264)
		(end 409.046934 -26.978102)
		(width 0.089408)
		(layer "In4.Cu")
		(net "FM_FLASH_DESC_OVERRIDE")
	)
	(segment
		(start 420.148766 -25.59431)
		(end 419.329108 -25.59431)
		(width 0.089408)
		(layer "In4.Cu")
		(net "FM_FLASH_DESC_OVERRIDE")
	)
	(segment
		(start 423.189908 -26.21915)
		(end 420.773606 -26.21915)
		(width 0.089408)
		(layer "In4.Cu")
		(net "FM_FLASH_DESC_OVERRIDE")
	)
	(segment
		(start 396.628366 -28.0162)
		(end 390.771888 -28.0162)
		(width 0.089408)
		(layer "In4.Cu")
		(net "FM_FLASH_DESC_OVERRIDE")
	)
	(segment
		(start 404.622 -28.894532)
		(end 403.997668 -28.2702)
		(width 0.089408)
		(layer "In4.Cu")
		(net "FM_FLASH_DESC_OVERRIDE")
	)
	(segment
		(start 402.165566 -28.2702)
		(end 402.120862 -28.314904)
		(width 0.089408)
		(layer "In4.Cu")
		(net "FM_FLASH_DESC_OVERRIDE")
	)
	(segment
		(start 387.921246 -31.12643)
		(end 387.28777 -31.12643)
		(width 0.089408)
		(layer "In4.Cu")
		(net "FM_FLASH_DESC_OVERRIDE")
	)
	(segment
		(start 408.827478 -26.978102)
		(end 408.243278 -27.562302)
		(width 0.089408)
		(layer "In4.Cu")
		(net "FM_FLASH_DESC_OVERRIDE")
	)
	(segment
		(start 401.789138 -28.314904)
		(end 401.744434 -28.2702)
		(width 0.089408)
		(layer "In4.Cu")
		(net "FM_FLASH_DESC_OVERRIDE")
	)
	(segment
		(start 402.120862 -28.314904)
		(end 401.789138 -28.314904)
		(width 0.089408)
		(layer "In4.Cu")
		(net "FM_FLASH_DESC_OVERRIDE")
	)
	(segment
		(start 429.50511 -26.905458)
		(end 423.876216 -26.905458)
		(width 0.089408)
		(layer "In4.Cu")
		(net "FM_FLASH_DESC_OVERRIDE")
	)
	(segment
		(start 399.554192 -27.731212)
		(end 396.913354 -27.731212)
		(width 0.089408)
		(layer "In4.Cu")
		(net "FM_FLASH_DESC_OVERRIDE")
	)
	(segment
		(start 385.338574 -70.569074)
		(end 385.338574 -71.607426)
		(width 0.089408)
		(layer "In9.Cu")
		(net "FM_FLASH_DESC_OVERRIDE")
	)
	(segment
		(start 382.957832 -81.428082)
		(end 380.719584 -83.66633)
		(width 0.089408)
		(layer "In9.Cu")
		(net "FM_FLASH_DESC_OVERRIDE")
	)
	(segment
		(start 382.948942 -78.79334)
		(end 382.524508 -79.217774)
		(width 0.089408)
		(layer "In9.Cu")
		(net "FM_FLASH_DESC_OVERRIDE")
	)
	(segment
		(start 380.260352 -97.852484)
		(end 380.70663 -98.298762)
		(width 0.089408)
		(layer "In9.Cu")
		(net "FM_FLASH_DESC_OVERRIDE")
	)
	(segment
		(start 387.096 -31.3182)
		(end 387.096 -31.74619)
		(width 0.089408)
		(layer "In9.Cu")
		(net "FM_FLASH_DESC_OVERRIDE")
	)
	(segment
		(start 383.61747 -76.426822)
		(end 382.948942 -77.09535)
		(width 0.089408)
		(layer "In9.Cu")
		(net "FM_FLASH_DESC_OVERRIDE")
	)
	(segment
		(start 386.136642 -69.767958)
		(end 386.136642 -69.771006)
		(width 0.089408)
		(layer "In9.Cu")
		(net "FM_FLASH_DESC_OVERRIDE")
	)
	(segment
		(start 387.862826 -56.635142)
		(end 387.862826 -57.930542)
		(width 0.089408)
		(layer "In9.Cu")
		(net "FM_FLASH_DESC_OVERRIDE")
	)
	(segment
		(start 388.145274 -56.352694)
		(end 387.862826 -56.635142)
		(width 0.089408)
		(layer "In9.Cu")
		(net "FM_FLASH_DESC_OVERRIDE")
	)
	(segment
		(start 379.90907 -96.91243)
		(end 380.260352 -97.263712)
		(width 0.089408)
		(layer "In9.Cu")
		(net "FM_FLASH_DESC_OVERRIDE")
	)
	(segment
		(start 382.68783 -101.14407)
		(end 382.68783 -102.18674)
		(width 0.089408)
		(layer "In9.Cu")
		(net "FM_FLASH_DESC_OVERRIDE")
	)
	(segment
		(start 384.723132 -73.16089)
		(end 384.26771 -73.616312)
		(width 0.089408)
		(layer "In9.Cu")
		(net "FM_FLASH_DESC_OVERRIDE")
	)
	(segment
		(start 387.258052 -46.25086)
		(end 387.258052 -52.44719)
		(width 0.089408)
		(layer "In9.Cu")
		(net "FM_FLASH_DESC_OVERRIDE")
	)
	(segment
		(start 387.096 -31.74619)
		(end 387.465316 -32.115506)
		(width 0.089408)
		(layer "In9.Cu")
		(net "FM_FLASH_DESC_OVERRIDE")
	)
	(segment
		(start 389.70839 -35.21075)
		(end 389.359648 -35.559492)
		(width 0.089408)
		(layer "In9.Cu")
		(net "FM_FLASH_DESC_OVERRIDE")
	)
	(segment
		(start 382.524508 -79.217774)
		(end 382.524508 -79.827628)
		(width 0.089408)
		(layer "In9.Cu")
		(net "FM_FLASH_DESC_OVERRIDE")
	)
	(segment
		(start 386.723636 -34.890964)
		(end 386.144262 -35.470338)
		(width 0.089408)
		(layer "In9.Cu")
		(net "FM_FLASH_DESC_OVERRIDE")
	)
	(segment
		(start 381.89027 -100.34651)
		(end 382.68783 -101.14407)
		(width 0.089408)
		(layer "In9.Cu")
		(net "FM_FLASH_DESC_OVERRIDE")
	)
	(segment
		(start 388.145274 -58.21299)
		(end 388.145274 -60.52058)
		(width 0.089408)
		(layer "In9.Cu")
		(net "FM_FLASH_DESC_OVERRIDE")
	)
	(segment
		(start 387.62813 -34.890964)
		(end 386.723636 -34.890964)
		(width 0.089408)
		(layer "In9.Cu")
		(net "FM_FLASH_DESC_OVERRIDE")
	)
	(segment
		(start 386.308346 -69.596254)
		(end 386.136642 -69.767958)
		(width 0.089408)
		(layer "In9.Cu")
		(net "FM_FLASH_DESC_OVERRIDE")
	)
	(segment
		(start 383.61747 -74.142854)
		(end 383.61747 -76.426822)
		(width 0.089408)
		(layer "In9.Cu")
		(net "FM_FLASH_DESC_OVERRIDE")
	)
	(segment
		(start 387.258052 -52.44719)
		(end 387.517894 -52.707032)
		(width 0.089408)
		(layer "In9.Cu")
		(net "FM_FLASH_DESC_OVERRIDE")
	)
	(segment
		(start 387.517894 -52.707032)
		(end 387.517894 -53.611526)
		(width 0.089408)
		(layer "In9.Cu")
		(net "FM_FLASH_DESC_OVERRIDE")
	)
	(segment
		(start 386.136642 -69.771006)
		(end 385.338574 -70.569074)
		(width 0.089408)
		(layer "In9.Cu")
		(net "FM_FLASH_DESC_OVERRIDE")
	)
	(segment
		(start 382.28905 -102.58552)
		(end 382.28905 -103.615236)
		(width 0.089408)
		(layer "In9.Cu")
		(net "FM_FLASH_DESC_OVERRIDE")
	)
	(segment
		(start 387.862826 -57.930542)
		(end 388.145274 -58.21299)
		(width 0.089408)
		(layer "In9.Cu")
		(net "FM_FLASH_DESC_OVERRIDE")
	)
	(segment
		(start 386.144262 -35.470338)
		(end 386.144262 -45.13707)
		(width 0.089408)
		(layer "In9.Cu")
		(net "FM_FLASH_DESC_OVERRIDE")
	)
	(segment
		(start 380.70663 -98.661982)
		(end 381.39497 -99.350322)
		(width 0.089408)
		(layer "In9.Cu")
		(net "FM_FLASH_DESC_OVERRIDE")
	)
	(segment
		(start 387.465316 -32.115506)
		(end 388.361174 -32.115506)
		(width 0.089408)
		(layer "In9.Cu")
		(net "FM_FLASH_DESC_OVERRIDE")
	)
	(segment
		(start 387.517894 -53.611526)
		(end 388.145274 -54.238906)
		(width 0.089408)
		(layer "In9.Cu")
		(net "FM_FLASH_DESC_OVERRIDE")
	)
	(segment
		(start 382.948942 -77.09535)
		(end 382.948942 -78.79334)
		(width 0.089408)
		(layer "In9.Cu")
		(net "FM_FLASH_DESC_OVERRIDE")
	)
	(segment
		(start 384.723132 -72.222868)
		(end 384.723132 -73.16089)
		(width 0.089408)
		(layer "In9.Cu")
		(net "FM_FLASH_DESC_OVERRIDE")
	)
	(segment
		(start 389.70839 -33.462722)
		(end 389.70839 -35.21075)
		(width 0.089408)
		(layer "In9.Cu")
		(net "FM_FLASH_DESC_OVERRIDE")
	)
	(segment
		(start 388.296658 -35.559492)
		(end 387.62813 -34.890964)
		(width 0.089408)
		(layer "In9.Cu")
		(net "FM_FLASH_DESC_OVERRIDE")
	)
	(segment
		(start 380.70663 -98.298762)
		(end 380.70663 -98.661982)
		(width 0.089408)
		(layer "In9.Cu")
		(net "FM_FLASH_DESC_OVERRIDE")
	)
	(segment
		(start 388.145274 -54.238906)
		(end 388.145274 -56.352694)
		(width 0.089408)
		(layer "In9.Cu")
		(net "FM_FLASH_DESC_OVERRIDE")
	)
	(segment
		(start 381.89027 -99.98329)
		(end 381.89027 -100.34651)
		(width 0.089408)
		(layer "In9.Cu")
		(net "FM_FLASH_DESC_OVERRIDE")
	)
	(segment
		(start 387.640576 -61.025278)
		(end 387.640576 -61.897514)
		(width 0.089408)
		(layer "In9.Cu")
		(net "FM_FLASH_DESC_OVERRIDE")
	)
	(segment
		(start 379.327156 -85.31098)
		(end 379.327156 -94.631256)
		(width 0.089408)
		(layer "In9.Cu")
		(net "FM_FLASH_DESC_OVERRIDE")
	)
	(segment
		(start 385.338574 -71.607426)
		(end 384.723132 -72.222868)
		(width 0.089408)
		(layer "In9.Cu")
		(net "FM_FLASH_DESC_OVERRIDE")
	)
	(segment
		(start 379.41377 -94.71787)
		(end 379.41377 -96.05391)
		(width 0.089408)
		(layer "In9.Cu")
		(net "FM_FLASH_DESC_OVERRIDE")
	)
	(segment
		(start 382.524508 -79.827628)
		(end 382.957832 -80.260952)
		(width 0.089408)
		(layer "In9.Cu")
		(net "FM_FLASH_DESC_OVERRIDE")
	)
	(segment
		(start 379.90907 -96.54921)
		(end 379.90907 -96.91243)
		(width 0.089408)
		(layer "In9.Cu")
		(net "FM_FLASH_DESC_OVERRIDE")
	)
	(segment
		(start 386.144262 -45.13707)
		(end 387.258052 -46.25086)
		(width 0.089408)
		(layer "In9.Cu")
		(net "FM_FLASH_DESC_OVERRIDE")
	)
	(segment
		(start 388.361174 -32.115506)
		(end 389.70839 -33.462722)
		(width 0.089408)
		(layer "In9.Cu")
		(net "FM_FLASH_DESC_OVERRIDE")
	)
	(segment
		(start 379.41377 -96.05391)
		(end 379.90907 -96.54921)
		(width 0.089408)
		(layer "In9.Cu")
		(net "FM_FLASH_DESC_OVERRIDE")
	)
	(segment
		(start 388.145274 -60.52058)
		(end 387.640576 -61.025278)
		(width 0.089408)
		(layer "In9.Cu")
		(net "FM_FLASH_DESC_OVERRIDE")
	)
	(segment
		(start 389.359648 -35.559492)
		(end 388.296658 -35.559492)
		(width 0.089408)
		(layer "In9.Cu")
		(net "FM_FLASH_DESC_OVERRIDE")
	)
	(segment
		(start 384.144012 -73.616312)
		(end 383.61747 -74.142854)
		(width 0.089408)
		(layer "In9.Cu")
		(net "FM_FLASH_DESC_OVERRIDE")
	)
	(segment
		(start 381.39497 -99.350322)
		(end 381.39497 -99.48799)
		(width 0.089408)
		(layer "In9.Cu")
		(net "FM_FLASH_DESC_OVERRIDE")
	)
	(segment
		(start 382.68783 -102.18674)
		(end 382.28905 -102.58552)
		(width 0.089408)
		(layer "In9.Cu")
		(net "FM_FLASH_DESC_OVERRIDE")
	)
	(segment
		(start 380.719584 -83.918552)
		(end 379.327156 -85.31098)
		(width 0.089408)
		(layer "In9.Cu")
		(net "FM_FLASH_DESC_OVERRIDE")
	)
	(segment
		(start 379.327156 -94.631256)
		(end 379.41377 -94.71787)
		(width 0.089408)
		(layer "In9.Cu")
		(net "FM_FLASH_DESC_OVERRIDE")
	)
	(segment
		(start 384.26771 -73.616312)
		(end 384.144012 -73.616312)
		(width 0.089408)
		(layer "In9.Cu")
		(net "FM_FLASH_DESC_OVERRIDE")
	)
	(segment
		(start 386.308346 -63.229744)
		(end 386.308346 -69.596254)
		(width 0.089408)
		(layer "In9.Cu")
		(net "FM_FLASH_DESC_OVERRIDE")
	)
	(segment
		(start 381.39497 -99.48799)
		(end 381.89027 -99.98329)
		(width 0.089408)
		(layer "In9.Cu")
		(net "FM_FLASH_DESC_OVERRIDE")
	)
	(segment
		(start 380.260352 -97.263712)
		(end 380.260352 -97.852484)
		(width 0.089408)
		(layer "In9.Cu")
		(net "FM_FLASH_DESC_OVERRIDE")
	)
	(segment
		(start 387.640576 -61.897514)
		(end 386.308346 -63.229744)
		(width 0.089408)
		(layer "In9.Cu")
		(net "FM_FLASH_DESC_OVERRIDE")
	)
	(segment
		(start 380.719584 -83.66633)
		(end 380.719584 -83.918552)
		(width 0.089408)
		(layer "In9.Cu")
		(net "FM_FLASH_DESC_OVERRIDE")
	)
	(segment
		(start 382.957832 -80.260952)
		(end 382.957832 -81.428082)
		(width 0.089408)
		(layer "In9.Cu")
		(net "FM_FLASH_DESC_OVERRIDE")
	)
	(segment
		(start 393.68095 -96.9772)
		(end 394.17625 -96.747076)
		(width 0.10795)
		(layer "F.Cu")
		(net "FM_ADR_COMPLETE_R1")
	)
	(via
		(at 394.17625 -96.747076)
		(size 0.508)
		(drill 0.254)
		(layers "F.Cu" "B.Cu")
		(net "FM_ADR_COMPLETE_R1")
	)
	(via
		(at 394.7541 -94.310962)
		(size 0.6604)
		(drill 0.3302)
		(layers "F.Cu" "B.Cu")
		(net "FM_ADR_COMPLETE_R1")
	)
	(segment
		(start 396.365222 -93.844618)
		(end 397.289274 -92.920566)
		(width 0.10795)
		(layer "B.Cu")
		(net "FM_ADR_COMPLETE_R1")
	)
	(segment
		(start 394.17625 -96.747076)
		(end 394.17625 -94.888812)
		(width 0.10795)
		(layer "B.Cu")
		(net "FM_ADR_COMPLETE_R1")
	)
	(segment
		(start 395.220444 -93.844618)
		(end 396.365222 -93.844618)
		(width 0.10795)
		(layer "B.Cu")
		(net "FM_ADR_COMPLETE_R1")
	)
	(segment
		(start 400.6215 -89.154)
		(end 401.574 -88.2015)
		(width 0.10795)
		(layer "B.Cu")
		(net "FM_ADR_COMPLETE_R1")
	)
	(segment
		(start 397.289274 -92.920566)
		(end 397.289274 -91.15044)
		(width 0.10795)
		(layer "B.Cu")
		(net "FM_ADR_COMPLETE_R1")
	)
	(segment
		(start 397.289274 -91.15044)
		(end 399.285714 -89.154)
		(width 0.10795)
		(layer "B.Cu")
		(net "FM_ADR_COMPLETE_R1")
	)
	(segment
		(start 394.7541 -94.310962)
		(end 395.220444 -93.844618)
		(width 0.10795)
		(layer "B.Cu")
		(net "FM_ADR_COMPLETE_R1")
	)
	(segment
		(start 394.17625 -94.888812)
		(end 394.7541 -94.310962)
		(width 0.10795)
		(layer "B.Cu")
		(net "FM_ADR_COMPLETE_R1")
	)
	(segment
		(start 399.285714 -89.154)
		(end 400.6215 -89.154)
		(width 0.10795)
		(layer "B.Cu")
		(net "FM_ADR_COMPLETE_R1")
	)
	(segment
		(start 409.8671 -17.607534)
		(end 410.23921 -17.979644)
		(width 0.10795)
		(layer "F.Cu")
		(net "H_CPU0_FAST_WAKE_B_N")
	)
	(segment
		(start 404.2664 -19.2278)
		(end 404.774146 -18.720054)
		(width 0.10795)
		(layer "F.Cu")
		(net "H_CPU0_FAST_WAKE_B_N")
	)
	(segment
		(start 409.179014 -17.701514)
		(end 409.272994 -17.607534)
		(width 0.10795)
		(layer "F.Cu")
		(net "H_CPU0_FAST_WAKE_B_N")
	)
	(segment
		(start 406.450546 -17.701514)
		(end 408.190954 -17.701514)
		(width 0.10795)
		(layer "F.Cu")
		(net "H_CPU0_FAST_WAKE_B_N")
	)
	(segment
		(start 405.432006 -18.720054)
		(end 406.450546 -17.701514)
		(width 0.10795)
		(layer "F.Cu")
		(net "H_CPU0_FAST_WAKE_B_N")
	)
	(segment
		(start 408.190954 -17.701514)
		(end 409.179014 -17.701514)
		(width 0.10795)
		(layer "F.Cu")
		(net "H_CPU0_FAST_WAKE_B_N")
	)
	(segment
		(start 404.774146 -18.720054)
		(end 405.432006 -18.720054)
		(width 0.10795)
		(layer "F.Cu")
		(net "H_CPU0_FAST_WAKE_B_N")
	)
	(segment
		(start 409.272994 -17.607534)
		(end 409.8671 -17.607534)
		(width 0.10795)
		(layer "F.Cu")
		(net "H_CPU0_FAST_WAKE_B_N")
	)
	(via
		(at 392.77798 -21.38172)
		(size 0.508)
		(drill 0.254)
		(layers "F.Cu" "B.Cu")
		(net "H_CPU0_FAST_WAKE_B_N")
	)
	(via
		(at 404.2664 -19.2278)
		(size 0.508)
		(drill 0.254)
		(layers "F.Cu" "B.Cu")
		(net "H_CPU0_FAST_WAKE_B_N")
	)
	(via
		(at 410.23921 -17.979644)
		(size 0.508)
		(drill 0.254)
		(layers "F.Cu" "B.Cu")
		(net "H_CPU0_FAST_WAKE_B_N")
	)
	(via
		(at 408.190954 -17.701514)
		(size 0.762)
		(drill 0.381)
		(layers "F.Cu" "B.Cu")
		(net "H_CPU0_FAST_WAKE_B_N")
	)
	(via
		(at 374.578118 -28.03398)
		(size 0.508)
		(drill 0.254)
		(layers "F.Cu" "B.Cu")
		(net "H_CPU0_FAST_WAKE_B_N")
	)
	(segment
		(start 412.11373 -17.199102)
		(end 410.572966 -17.199102)
		(width 0.10795)
		(layer "B.Cu")
		(net "H_CPU0_FAST_WAKE_B_N")
	)
	(segment
		(start 329.95616 -59.69)
		(end 329.098402 -59.69)
		(width 0.10795)
		(layer "B.Cu")
		(net "H_CPU0_FAST_WAKE_B_N")
	)
	(segment
		(start 365.428276 -30.229302)
		(end 364.039404 -31.618174)
		(width 0.10795)
		(layer "B.Cu")
		(net "H_CPU0_FAST_WAKE_B_N")
	)
	(segment
		(start 374.578118 -28.03398)
		(end 373.670068 -28.03398)
		(width 0.10795)
		(layer "B.Cu")
		(net "H_CPU0_FAST_WAKE_B_N")
	)
	(segment
		(start 332.397862 -57.248298)
		(end 329.95616 -59.69)
		(width 0.10795)
		(layer "B.Cu")
		(net "H_CPU0_FAST_WAKE_B_N")
	)
	(segment
		(start 329.098402 -59.69)
		(end 328.463402 -60.325)
		(width 0.10795)
		(layer "B.Cu")
		(net "H_CPU0_FAST_WAKE_B_N")
	)
	(segment
		(start 328.463402 -60.325)
		(end 327.914 -60.325)
		(width 0.10795)
		(layer "B.Cu")
		(net "H_CPU0_FAST_WAKE_B_N")
	)
	(segment
		(start 413.01416 -16.298672)
		(end 412.11373 -17.199102)
		(width 0.10795)
		(layer "B.Cu")
		(net "H_CPU0_FAST_WAKE_B_N")
	)
	(segment
		(start 373.670068 -28.03398)
		(end 371.474746 -30.229302)
		(width 0.10795)
		(layer "B.Cu")
		(net "H_CPU0_FAST_WAKE_B_N")
	)
	(segment
		(start 355.259132 -38.795452)
		(end 354.580952 -39.473632)
		(width 0.10795)
		(layer "B.Cu")
		(net "H_CPU0_FAST_WAKE_B_N")
	)
	(segment
		(start 410.23921 -17.532858)
		(end 410.23921 -17.979644)
		(width 0.10795)
		(layer "B.Cu")
		(net "H_CPU0_FAST_WAKE_B_N")
	)
	(segment
		(start 354.580952 -39.473632)
		(end 354.580952 -45.673772)
		(width 0.10795)
		(layer "B.Cu")
		(net "H_CPU0_FAST_WAKE_B_N")
	)
	(segment
		(start 364.03026 -31.618174)
		(end 356.852982 -38.795452)
		(width 0.10795)
		(layer "B.Cu")
		(net "H_CPU0_FAST_WAKE_B_N")
	)
	(segment
		(start 340.219538 -49.129696)
		(end 337.2104 -52.138834)
		(width 0.10795)
		(layer "B.Cu")
		(net "H_CPU0_FAST_WAKE_B_N")
	)
	(segment
		(start 371.474746 -30.229302)
		(end 365.428276 -30.229302)
		(width 0.10795)
		(layer "B.Cu")
		(net "H_CPU0_FAST_WAKE_B_N")
	)
	(segment
		(start 337.368134 -56.344058)
		(end 336.463894 -57.248298)
		(width 0.10795)
		(layer "B.Cu")
		(net "H_CPU0_FAST_WAKE_B_N")
	)
	(segment
		(start 337.368134 -54.364636)
		(end 337.368134 -56.344058)
		(width 0.10795)
		(layer "B.Cu")
		(net "H_CPU0_FAST_WAKE_B_N")
	)
	(segment
		(start 337.2104 -52.138834)
		(end 337.2104 -54.206902)
		(width 0.10795)
		(layer "B.Cu")
		(net "H_CPU0_FAST_WAKE_B_N")
	)
	(segment
		(start 336.463894 -57.248298)
		(end 332.397862 -57.248298)
		(width 0.10795)
		(layer "B.Cu")
		(net "H_CPU0_FAST_WAKE_B_N")
	)
	(segment
		(start 413.01416 -15.357094)
		(end 413.01416 -16.298672)
		(width 0.10795)
		(layer "B.Cu")
		(net "H_CPU0_FAST_WAKE_B_N")
	)
	(segment
		(start 364.039404 -31.618174)
		(end 364.03026 -31.618174)
		(width 0.10795)
		(layer "B.Cu")
		(net "H_CPU0_FAST_WAKE_B_N")
	)
	(segment
		(start 418.8206 -11.587734)
		(end 416.78352 -11.587734)
		(width 0.10795)
		(layer "B.Cu")
		(net "H_CPU0_FAST_WAKE_B_N")
	)
	(segment
		(start 351.125028 -49.129696)
		(end 340.219538 -49.129696)
		(width 0.10795)
		(layer "B.Cu")
		(net "H_CPU0_FAST_WAKE_B_N")
	)
	(segment
		(start 416.78352 -11.587734)
		(end 413.01416 -15.357094)
		(width 0.10795)
		(layer "B.Cu")
		(net "H_CPU0_FAST_WAKE_B_N")
	)
	(segment
		(start 356.852982 -38.795452)
		(end 355.259132 -38.795452)
		(width 0.10795)
		(layer "B.Cu")
		(net "H_CPU0_FAST_WAKE_B_N")
	)
	(segment
		(start 337.2104 -54.206902)
		(end 337.368134 -54.364636)
		(width 0.10795)
		(layer "B.Cu")
		(net "H_CPU0_FAST_WAKE_B_N")
	)
	(segment
		(start 354.580952 -45.673772)
		(end 351.125028 -49.129696)
		(width 0.10795)
		(layer "B.Cu")
		(net "H_CPU0_FAST_WAKE_B_N")
	)
	(segment
		(start 410.572966 -17.199102)
		(end 410.23921 -17.532858)
		(width 0.10795)
		(layer "B.Cu")
		(net "H_CPU0_FAST_WAKE_B_N")
	)
	(segment
		(start 377.360434 -25.58542)
		(end 374.911874 -28.03398)
		(width 0.089408)
		(layer "In4.Cu")
		(net "H_CPU0_FAST_WAKE_B_N")
	)
	(segment
		(start 392.77798 -20.218146)
		(end 391.42035 -18.860516)
		(width 0.089408)
		(layer "In4.Cu")
		(net "H_CPU0_FAST_WAKE_B_N")
	)
	(segment
		(start 382.393444 -18.860516)
		(end 377.360434 -23.893526)
		(width 0.089408)
		(layer "In4.Cu")
		(net "H_CPU0_FAST_WAKE_B_N")
	)
	(segment
		(start 377.360434 -23.893526)
		(end 377.360434 -25.58542)
		(width 0.089408)
		(layer "In4.Cu")
		(net "H_CPU0_FAST_WAKE_B_N")
	)
	(segment
		(start 392.77798 -21.38172)
		(end 392.77798 -20.218146)
		(width 0.089408)
		(layer "In4.Cu")
		(net "H_CPU0_FAST_WAKE_B_N")
	)
	(segment
		(start 374.911874 -28.03398)
		(end 374.578118 -28.03398)
		(width 0.089408)
		(layer "In4.Cu")
		(net "H_CPU0_FAST_WAKE_B_N")
	)
	(segment
		(start 391.42035 -18.860516)
		(end 382.393444 -18.860516)
		(width 0.089408)
		(layer "In4.Cu")
		(net "H_CPU0_FAST_WAKE_B_N")
	)
	(segment
		(start 404.2664 -19.2278)
		(end 403.8854 -18.8468)
		(width 0.089408)
		(layer "In9.Cu")
		(net "H_CPU0_FAST_WAKE_B_N")
	)
	(segment
		(start 398.37106 -18.542)
		(end 395.535404 -21.377656)
		(width 0.089408)
		(layer "In9.Cu")
		(net "H_CPU0_FAST_WAKE_B_N")
	)
	(segment
		(start 402.094446 -18.542)
		(end 398.37106 -18.542)
		(width 0.089408)
		(layer "In9.Cu")
		(net "H_CPU0_FAST_WAKE_B_N")
	)
	(segment
		(start 402.399246 -18.8468)
		(end 402.094446 -18.542)
		(width 0.089408)
		(layer "In9.Cu")
		(net "H_CPU0_FAST_WAKE_B_N")
	)
	(segment
		(start 395.535404 -21.377656)
		(end 392.782044 -21.377656)
		(width 0.089408)
		(layer "In9.Cu")
		(net "H_CPU0_FAST_WAKE_B_N")
	)
	(segment
		(start 403.8854 -18.8468)
		(end 402.399246 -18.8468)
		(width 0.089408)
		(layer "In9.Cu")
		(net "H_CPU0_FAST_WAKE_B_N")
	)
	(segment
		(start 392.782044 -21.377656)
		(end 392.77798 -21.38172)
		(width 0.089408)
		(layer "In9.Cu")
		(net "H_CPU0_FAST_WAKE_B_N")
	)
	(segment
		(start 90.070178 -65.49644)
		(end 89.498678 -65.49644)
		(width 0.10795)
		(layer "F.Cu")
		(net "TP_CPU1_RSVD_199")
	)
	(via
		(at 89.498678 -65.49644)
		(size 0.508)
		(drill 0.254)
		(layers "F.Cu" "B.Cu")
		(net "TP_CPU1_RSVD_199")
	)
	(via
		(at 159.857186 -119.274082)
		(size 0.762)
		(drill 0.3048)
		(layers "F.Cu" "B.Cu")
		(net "TP_CPU1_RSVD_199")
	)
	(segment
		(start 113.772696 -80.395572)
		(end 92.866972 -80.395572)
		(width 0.0889)
		(layer "In9.Cu")
		(net "TP_CPU1_RSVD_199")
	)
	(segment
		(start 137.688574 -86.022434)
		(end 137.653014 -86.022434)
		(width 0.0889)
		(layer "In9.Cu")
		(net "TP_CPU1_RSVD_199")
	)
	(segment
		(start 90.005662 -66.790824)
		(end 90.010488 -66.782188)
		(width 0.0889)
		(layer "In9.Cu")
		(net "TP_CPU1_RSVD_199")
	)
	(segment
		(start 123.952508 -86.022434)
		(end 123.916948 -86.022434)
		(width 0.0889)
		(layer "In9.Cu")
		(net "TP_CPU1_RSVD_199")
	)
	(segment
		(start 127.386588 -86.022434)
		(end 127.351028 -86.022434)
		(width 0.0889)
		(layer "In9.Cu")
		(net "TP_CPU1_RSVD_199")
	)
	(segment
		(start 159.857186 -119.274082)
		(end 160.281112 -119.698008)
		(width 0.089408)
		(layer "In9.Cu")
		(net "TP_CPU1_RSVD_199")
	)
	(segment
		(start 122.235468 -86.022434)
		(end 122.199908 -86.022434)
		(width 0.0889)
		(layer "In9.Cu")
		(net "TP_CPU1_RSVD_199")
	)
	(segment
		(start 152.884124 -122.48388)
		(end 152.884124 -119.68988)
		(width 0.089408)
		(layer "In9.Cu")
		(net "TP_CPU1_RSVD_199")
	)
	(segment
		(start 142.129764 -86.517988)
		(end 141.952218 -86.517988)
		(width 0.0889)
		(layer "In9.Cu")
		(net "TP_CPU1_RSVD_199")
	)
	(segment
		(start 143.509238 -86.022434)
		(end 143.160496 -86.022434)
		(width 0.089408)
		(layer "In9.Cu")
		(net "TP_CPU1_RSVD_199")
	)
	(segment
		(start 153.62428 -123.224036)
		(end 152.884124 -122.48388)
		(width 0.089408)
		(layer "In9.Cu")
		(net "TP_CPU1_RSVD_199")
	)
	(segment
		(start 132.537454 -86.022434)
		(end 132.501894 -86.022434)
		(width 0.0889)
		(layer "In9.Cu")
		(net "TP_CPU1_RSVD_199")
	)
	(segment
		(start 129.103628 -86.022434)
		(end 129.068068 -86.022434)
		(width 0.0889)
		(layer "In9.Cu")
		(net "TP_CPU1_RSVD_199")
	)
	(segment
		(start 90.010488 -66.782188)
		(end 90.016838 -66.77152)
		(width 0.0889)
		(layer "In9.Cu")
		(net "TP_CPU1_RSVD_199")
	)
	(segment
		(start 134.254494 -86.022434)
		(end 134.218934 -86.022434)
		(width 0.0889)
		(layer "In9.Cu")
		(net "TP_CPU1_RSVD_199")
	)
	(segment
		(start 130.820668 -86.022434)
		(end 130.785108 -86.022434)
		(width 0.0889)
		(layer "In9.Cu")
		(net "TP_CPU1_RSVD_199")
	)
	(segment
		(start 92.866972 -80.395572)
		(end 91.24569 -78.77429)
		(width 0.0889)
		(layer "In9.Cu")
		(net "TP_CPU1_RSVD_199")
	)
	(segment
		(start 144.25041 -90.722958)
		(end 144.25041 -86.763606)
		(width 0.089408)
		(layer "In9.Cu")
		(net "TP_CPU1_RSVD_199")
	)
	(segment
		(start 153.740358 -123.224036)
		(end 153.62428 -123.224036)
		(width 0.089408)
		(layer "In9.Cu")
		(net "TP_CPU1_RSVD_199")
	)
	(segment
		(start 143.160496 -86.022434)
		(end 142.695422 -86.022434)
		(width 0.0889)
		(layer "In9.Cu")
		(net "TP_CPU1_RSVD_199")
	)
	(segment
		(start 146.049746 -92.522294)
		(end 144.25041 -90.722958)
		(width 0.089408)
		(layer "In9.Cu")
		(net "TP_CPU1_RSVD_199")
	)
	(segment
		(start 152.884124 -119.68988)
		(end 146.049746 -112.855502)
		(width 0.089408)
		(layer "In9.Cu")
		(net "TP_CPU1_RSVD_199")
	)
	(segment
		(start 120.163082 -85.83676)
		(end 120.089676 -85.720682)
		(width 0.0889)
		(layer "In9.Cu")
		(net "TP_CPU1_RSVD_199")
	)
	(segment
		(start 135.971534 -86.022434)
		(end 135.935974 -86.022434)
		(width 0.0889)
		(layer "In9.Cu")
		(net "TP_CPU1_RSVD_199")
	)
	(segment
		(start 154.473402 -123.95708)
		(end 153.740358 -123.224036)
		(width 0.089408)
		(layer "In9.Cu")
		(net "TP_CPU1_RSVD_199")
	)
	(segment
		(start 90.528902 -78.77429)
		(end 89.906602 -78.15199)
		(width 0.0889)
		(layer "In9.Cu")
		(net "TP_CPU1_RSVD_199")
	)
	(segment
		(start 146.049746 -112.855502)
		(end 146.049746 -92.522294)
		(width 0.089408)
		(layer "In9.Cu")
		(net "TP_CPU1_RSVD_199")
	)
	(segment
		(start 125.669548 -86.022434)
		(end 125.633988 -86.022434)
		(width 0.0889)
		(layer "In9.Cu")
		(net "TP_CPU1_RSVD_199")
	)
	(segment
		(start 156.727652 -123.69546)
		(end 156.466032 -123.95708)
		(width 0.089408)
		(layer "In9.Cu")
		(net "TP_CPU1_RSVD_199")
	)
	(segment
		(start 91.24569 -78.77429)
		(end 90.528902 -78.77429)
		(width 0.0889)
		(layer "In9.Cu")
		(net "TP_CPU1_RSVD_199")
	)
	(segment
		(start 120.089676 -85.720682)
		(end 119.876062 -85.507068)
		(width 0.0889)
		(layer "In9.Cu")
		(net "TP_CPU1_RSVD_199")
	)
	(segment
		(start 121.016014 -86.323678)
		(end 121.012712 -86.317836)
		(width 0.0889)
		(layer "In9.Cu")
		(net "TP_CPU1_RSVD_199")
	)
	(segment
		(start 132.007864 -86.317836)
		(end 132.004562 -86.323678)
		(width 0.0889)
		(layer "In9.Cu")
		(net "TP_CPU1_RSVD_199")
	)
	(segment
		(start 119.876062 -85.507068)
		(end 118.884192 -85.507068)
		(width 0.0889)
		(layer "In9.Cu")
		(net "TP_CPU1_RSVD_199")
	)
	(segment
		(start 90.010996 -67.771518)
		(end 90.01125 -67.771518)
		(width 0.0889)
		(layer "In9.Cu")
		(net "TP_CPU1_RSVD_199")
	)
	(segment
		(start 89.906602 -78.15199)
		(end 89.906602 -68.301616)
		(width 0.0889)
		(layer "In9.Cu")
		(net "TP_CPU1_RSVD_199")
	)
	(segment
		(start 139.405614 -86.022434)
		(end 139.370054 -86.022434)
		(width 0.0889)
		(layer "In9.Cu")
		(net "TP_CPU1_RSVD_199")
	)
	(segment
		(start 144.25041 -86.763606)
		(end 143.509238 -86.022434)
		(width 0.089408)
		(layer "In9.Cu")
		(net "TP_CPU1_RSVD_199")
	)
	(segment
		(start 89.205816 -65.66535)
		(end 89.498678 -65.49644)
		(width 0.0889)
		(layer "In9.Cu")
		(net "TP_CPU1_RSVD_199")
	)
	(segment
		(start 90.01125 -67.771518)
		(end 90.016838 -67.76212)
		(width 0.0889)
		(layer "In9.Cu")
		(net "TP_CPU1_RSVD_199")
	)
	(segment
		(start 90.010234 -67.772534)
		(end 90.010996 -67.771518)
		(width 0.0889)
		(layer "In9.Cu")
		(net "TP_CPU1_RSVD_199")
	)
	(segment
		(start 160.281112 -122.67311)
		(end 159.258762 -123.69546)
		(width 0.089408)
		(layer "In9.Cu")
		(net "TP_CPU1_RSVD_199")
	)
	(segment
		(start 89.184734 -65.74409)
		(end 89.205816 -65.66535)
		(width 0.0889)
		(layer "In9.Cu")
		(net "TP_CPU1_RSVD_199")
	)
	(segment
		(start 89.520268 -65.89649)
		(end 89.498678 -65.89649)
		(width 0.0889)
		(layer "In9.Cu")
		(net "TP_CPU1_RSVD_199")
	)
	(segment
		(start 141.122654 -86.022434)
		(end 141.087094 -86.022434)
		(width 0.0889)
		(layer "In9.Cu")
		(net "TP_CPU1_RSVD_199")
	)
	(segment
		(start 118.884192 -85.507068)
		(end 113.772696 -80.395572)
		(width 0.0889)
		(layer "In9.Cu")
		(net "TP_CPU1_RSVD_199")
	)
	(segment
		(start 120.518682 -86.022434)
		(end 120.485916 -86.022434)
		(width 0.0889)
		(layer "In9.Cu")
		(net "TP_CPU1_RSVD_199")
	)
	(segment
		(start 160.281112 -119.698008)
		(end 160.281112 -122.67311)
		(width 0.089408)
		(layer "In9.Cu")
		(net "TP_CPU1_RSVD_199")
	)
	(segment
		(start 159.258762 -123.69546)
		(end 156.727652 -123.69546)
		(width 0.089408)
		(layer "In9.Cu")
		(net "TP_CPU1_RSVD_199")
	)
	(segment
		(start 156.466032 -123.95708)
		(end 154.473402 -123.95708)
		(width 0.089408)
		(layer "In9.Cu")
		(net "TP_CPU1_RSVD_199")
	)
	(arc
		(start 131.314698 -86.317836)
		(mid 131.10609 -86.105904)
		(end 130.820668 -86.022434)
		(width 0.0889)
		(layer "In9.Cu")
		(net "TP_CPU1_RSVD_199")
	)
	(arc
		(start 120.485916 -86.022434)
		(mid 120.301613 -85.969411)
		(end 120.163082 -85.83676)
		(width 0.0889)
		(layer "In9.Cu")
		(net "TP_CPU1_RSVD_199")
	)
	(arc
		(start 138.876024 -86.317836)
		(mid 138.529314 -86.518147)
		(end 138.182604 -86.317836)
		(width 0.0889)
		(layer "In9.Cu")
		(net "TP_CPU1_RSVD_199")
	)
	(arc
		(start 123.422918 -86.317836)
		(mid 123.076208 -86.518147)
		(end 122.729498 -86.317836)
		(width 0.0889)
		(layer "In9.Cu")
		(net "TP_CPU1_RSVD_199")
	)
	(arc
		(start 127.351028 -86.022434)
		(mid 127.065604 -86.105901)
		(end 126.856998 -86.317836)
		(width 0.0889)
		(layer "In9.Cu")
		(net "TP_CPU1_RSVD_199")
	)
	(arc
		(start 125.633988 -86.022434)
		(mid 125.348564 -86.105901)
		(end 125.139958 -86.317836)
		(width 0.0889)
		(layer "In9.Cu")
		(net "TP_CPU1_RSVD_199")
	)
	(arc
		(start 142.695422 -86.022434)
		(mid 142.492524 -86.138294)
		(end 142.346426 -86.32063)
		(width 0.0889)
		(layer "In9.Cu")
		(net "TP_CPU1_RSVD_199")
	)
	(arc
		(start 134.218934 -86.022434)
		(mid 133.93351 -86.105901)
		(end 133.724904 -86.317836)
		(width 0.0889)
		(layer "In9.Cu")
		(net "TP_CPU1_RSVD_199")
	)
	(arc
		(start 132.501894 -86.022434)
		(mid 132.21647 -86.105901)
		(end 132.007864 -86.317836)
		(width 0.0889)
		(layer "In9.Cu")
		(net "TP_CPU1_RSVD_199")
	)
	(arc
		(start 124.446538 -86.317836)
		(mid 124.23793 -86.105904)
		(end 123.952508 -86.022434)
		(width 0.0889)
		(layer "In9.Cu")
		(net "TP_CPU1_RSVD_199")
	)
	(arc
		(start 123.916948 -86.022434)
		(mid 123.631524 -86.105901)
		(end 123.422918 -86.317836)
		(width 0.0889)
		(layer "In9.Cu")
		(net "TP_CPU1_RSVD_199")
	)
	(arc
		(start 139.899644 -86.317836)
		(mid 139.691036 -86.105904)
		(end 139.405614 -86.022434)
		(width 0.0889)
		(layer "In9.Cu")
		(net "TP_CPU1_RSVD_199")
	)
	(arc
		(start 141.952218 -86.517988)
		(mid 141.758368 -86.461638)
		(end 141.616684 -86.317836)
		(width 0.0889)
		(layer "In9.Cu")
		(net "TP_CPU1_RSVD_199")
	)
	(arc
		(start 125.139958 -86.317836)
		(mid 124.793248 -86.518147)
		(end 124.446538 -86.317836)
		(width 0.0889)
		(layer "In9.Cu")
		(net "TP_CPU1_RSVD_199")
	)
	(arc
		(start 126.163578 -86.317836)
		(mid 125.95497 -86.105904)
		(end 125.669548 -86.022434)
		(width 0.0889)
		(layer "In9.Cu")
		(net "TP_CPU1_RSVD_199")
	)
	(arc
		(start 122.199908 -86.022434)
		(mid 121.914484 -86.105901)
		(end 121.705878 -86.317836)
		(width 0.0889)
		(layer "In9.Cu")
		(net "TP_CPU1_RSVD_199")
	)
	(arc
		(start 141.616684 -86.317836)
		(mid 141.408076 -86.105904)
		(end 141.122654 -86.022434)
		(width 0.0889)
		(layer "In9.Cu")
		(net "TP_CPU1_RSVD_199")
	)
	(arc
		(start 90.016838 -66.77152)
		(mid 90.012807 -66.195338)
		(end 89.520268 -65.89649)
		(width 0.0889)
		(layer "In9.Cu")
		(net "TP_CPU1_RSVD_199")
	)
	(arc
		(start 130.291078 -86.317836)
		(mid 129.944368 -86.518147)
		(end 129.597658 -86.317836)
		(width 0.0889)
		(layer "In9.Cu")
		(net "TP_CPU1_RSVD_199")
	)
	(arc
		(start 135.441944 -86.317836)
		(mid 135.095234 -86.518147)
		(end 134.748524 -86.317836)
		(width 0.0889)
		(layer "In9.Cu")
		(net "TP_CPU1_RSVD_199")
	)
	(arc
		(start 133.724904 -86.317836)
		(mid 133.378194 -86.518147)
		(end 133.031484 -86.317836)
		(width 0.0889)
		(layer "In9.Cu")
		(net "TP_CPU1_RSVD_199")
	)
	(arc
		(start 138.182604 -86.317836)
		(mid 137.973996 -86.105904)
		(end 137.688574 -86.022434)
		(width 0.0889)
		(layer "In9.Cu")
		(net "TP_CPU1_RSVD_199")
	)
	(arc
		(start 122.729498 -86.317836)
		(mid 122.52089 -86.105904)
		(end 122.235468 -86.022434)
		(width 0.0889)
		(layer "In9.Cu")
		(net "TP_CPU1_RSVD_199")
	)
	(arc
		(start 134.748524 -86.317836)
		(mid 134.539916 -86.105904)
		(end 134.254494 -86.022434)
		(width 0.0889)
		(layer "In9.Cu")
		(net "TP_CPU1_RSVD_199")
	)
	(arc
		(start 129.068068 -86.022434)
		(mid 128.782644 -86.105901)
		(end 128.574038 -86.317836)
		(width 0.0889)
		(layer "In9.Cu")
		(net "TP_CPU1_RSVD_199")
	)
	(arc
		(start 128.574038 -86.317836)
		(mid 128.227328 -86.518147)
		(end 127.880618 -86.317836)
		(width 0.0889)
		(layer "In9.Cu")
		(net "TP_CPU1_RSVD_199")
	)
	(arc
		(start 136.465564 -86.317836)
		(mid 136.256956 -86.105904)
		(end 135.971534 -86.022434)
		(width 0.0889)
		(layer "In9.Cu")
		(net "TP_CPU1_RSVD_199")
	)
	(arc
		(start 139.370054 -86.022434)
		(mid 139.08463 -86.105901)
		(end 138.876024 -86.317836)
		(width 0.0889)
		(layer "In9.Cu")
		(net "TP_CPU1_RSVD_199")
	)
	(arc
		(start 90.010488 -67.182238)
		(mid 89.957018 -66.987175)
		(end 90.005662 -66.790824)
		(width 0.0889)
		(layer "In9.Cu")
		(net "TP_CPU1_RSVD_199")
	)
	(arc
		(start 129.597658 -86.317836)
		(mid 129.38905 -86.105904)
		(end 129.103628 -86.022434)
		(width 0.0889)
		(layer "In9.Cu")
		(net "TP_CPU1_RSVD_199")
	)
	(arc
		(start 132.004562 -86.323678)
		(mid 131.657989 -86.518028)
		(end 131.314698 -86.317836)
		(width 0.0889)
		(layer "In9.Cu")
		(net "TP_CPU1_RSVD_199")
	)
	(arc
		(start 89.906602 -68.301616)
		(mid 89.914362 -68.028444)
		(end 90.010234 -67.772534)
		(width 0.0889)
		(layer "In9.Cu")
		(net "TP_CPU1_RSVD_199")
	)
	(arc
		(start 130.785108 -86.022434)
		(mid 130.499684 -86.105901)
		(end 130.291078 -86.317836)
		(width 0.0889)
		(layer "In9.Cu")
		(net "TP_CPU1_RSVD_199")
	)
	(arc
		(start 90.016838 -67.76212)
		(mid 90.089636 -67.471357)
		(end 90.010488 -67.182238)
		(width 0.0889)
		(layer "In9.Cu")
		(net "TP_CPU1_RSVD_199")
	)
	(arc
		(start 137.158984 -86.317836)
		(mid 136.812274 -86.518147)
		(end 136.465564 -86.317836)
		(width 0.0889)
		(layer "In9.Cu")
		(net "TP_CPU1_RSVD_199")
	)
	(arc
		(start 133.031484 -86.317836)
		(mid 132.822876 -86.105904)
		(end 132.537454 -86.022434)
		(width 0.0889)
		(layer "In9.Cu")
		(net "TP_CPU1_RSVD_199")
	)
	(arc
		(start 121.705878 -86.317836)
		(mid 121.362588 -86.518132)
		(end 121.016014 -86.323678)
		(width 0.0889)
		(layer "In9.Cu")
		(net "TP_CPU1_RSVD_199")
	)
	(arc
		(start 135.935974 -86.022434)
		(mid 135.65055 -86.105901)
		(end 135.441944 -86.317836)
		(width 0.0889)
		(layer "In9.Cu")
		(net "TP_CPU1_RSVD_199")
	)
	(arc
		(start 137.653014 -86.022434)
		(mid 137.36759 -86.105901)
		(end 137.158984 -86.317836)
		(width 0.0889)
		(layer "In9.Cu")
		(net "TP_CPU1_RSVD_199")
	)
	(arc
		(start 126.856998 -86.317836)
		(mid 126.510288 -86.518147)
		(end 126.163578 -86.317836)
		(width 0.0889)
		(layer "In9.Cu")
		(net "TP_CPU1_RSVD_199")
	)
	(arc
		(start 89.498678 -65.89649)
		(mid 89.324217 -65.856321)
		(end 89.184734 -65.74409)
		(width 0.0889)
		(layer "In9.Cu")
		(net "TP_CPU1_RSVD_199")
	)
	(arc
		(start 140.593064 -86.317836)
		(mid 140.246354 -86.518147)
		(end 139.899644 -86.317836)
		(width 0.0889)
		(layer "In9.Cu")
		(net "TP_CPU1_RSVD_199")
	)
	(arc
		(start 141.087094 -86.022434)
		(mid 140.80167 -86.105901)
		(end 140.593064 -86.317836)
		(width 0.0889)
		(layer "In9.Cu")
		(net "TP_CPU1_RSVD_199")
	)
	(arc
		(start 127.880618 -86.317836)
		(mid 127.67201 -86.105904)
		(end 127.386588 -86.022434)
		(width 0.0889)
		(layer "In9.Cu")
		(net "TP_CPU1_RSVD_199")
	)
	(arc
		(start 121.012712 -86.317836)
		(mid 120.804104 -86.105904)
		(end 120.518682 -86.022434)
		(width 0.0889)
		(layer "In9.Cu")
		(net "TP_CPU1_RSVD_199")
	)
	(arc
		(start 142.346426 -86.32063)
		(mid 142.255312 -86.438222)
		(end 142.129764 -86.517988)
		(width 0.0889)
		(layer "In9.Cu")
		(net "TP_CPU1_RSVD_199")
	)
	(segment
		(start 88.353392 -65.49644)
		(end 87.781892 -65.49644)
		(width 0.10795)
		(layer "F.Cu")
		(net "TP_CPU1_RSVD_198")
	)
	(via
		(at 160.723834 -120.210326)
		(size 0.762)
		(drill 0.3048)
		(layers "F.Cu" "B.Cu")
		(net "TP_CPU1_RSVD_198")
	)
	(via
		(at 87.781892 -65.49644)
		(size 0.508)
		(drill 0.254)
		(layers "F.Cu" "B.Cu")
		(net "TP_CPU1_RSVD_198")
	)
	(segment
		(start 127.386588 -87.013034)
		(end 127.351028 -87.013034)
		(width 0.0889)
		(layer "In9.Cu")
		(net "TP_CPU1_RSVD_198")
	)
	(segment
		(start 143.792194 -87.548466)
		(end 143.256762 -87.013034)
		(width 0.089408)
		(layer "In9.Cu")
		(net "TP_CPU1_RSVD_198")
	)
	(segment
		(start 157.04058 -123.886468)
		(end 156.637736 -124.289312)
		(width 0.089408)
		(layer "In9.Cu")
		(net "TP_CPU1_RSVD_198")
	)
	(segment
		(start 135.971534 -87.013034)
		(end 135.935974 -87.013034)
		(width 0.0889)
		(layer "In9.Cu")
		(net "TP_CPU1_RSVD_198")
	)
	(segment
		(start 122.235468 -87.013034)
		(end 122.199908 -87.013034)
		(width 0.0889)
		(layer "In9.Cu")
		(net "TP_CPU1_RSVD_198")
	)
	(segment
		(start 158.927292 -123.886722)
		(end 158.927038 -123.886468)
		(width 0.089408)
		(layer "In9.Cu")
		(net "TP_CPU1_RSVD_198")
	)
	(segment
		(start 160.723834 -120.210326)
		(end 160.693354 -120.240806)
		(width 0.089408)
		(layer "In9.Cu")
		(net "TP_CPU1_RSVD_198")
	)
	(segment
		(start 92.657676 -80.800702)
		(end 91.621864 -79.76489)
		(width 0.0889)
		(layer "In9.Cu")
		(net "TP_CPU1_RSVD_198")
	)
	(segment
		(start 137.688574 -87.013034)
		(end 137.653014 -87.013034)
		(width 0.0889)
		(layer "In9.Cu")
		(net "TP_CPU1_RSVD_198")
	)
	(segment
		(start 116.743988 -84.211414)
		(end 115.60683 -83.074256)
		(width 0.0889)
		(layer "In9.Cu")
		(net "TP_CPU1_RSVD_198")
	)
	(segment
		(start 160.693354 -120.240806)
		(end 160.693354 -122.531124)
		(width 0.089408)
		(layer "In9.Cu")
		(net "TP_CPU1_RSVD_198")
	)
	(segment
		(start 153.366724 -124.289312)
		(end 152.425908 -123.348496)
		(width 0.089408)
		(layer "In9.Cu")
		(net "TP_CPU1_RSVD_198")
	)
	(segment
		(start 143.256762 -87.013034)
		(end 142.695422 -87.013034)
		(width 0.0889)
		(layer "In9.Cu")
		(net "TP_CPU1_RSVD_198")
	)
	(segment
		(start 152.425908 -123.348496)
		(end 152.425908 -119.879872)
		(width 0.089408)
		(layer "In9.Cu")
		(net "TP_CPU1_RSVD_198")
	)
	(segment
		(start 129.103628 -87.013034)
		(end 129.068068 -87.013034)
		(width 0.0889)
		(layer "In9.Cu")
		(net "TP_CPU1_RSVD_198")
	)
	(segment
		(start 143.792194 -90.91295)
		(end 143.792194 -87.548466)
		(width 0.089408)
		(layer "In9.Cu")
		(net "TP_CPU1_RSVD_198")
	)
	(segment
		(start 89.32672 -78.562708)
		(end 89.32672 -68.340478)
		(width 0.0889)
		(layer "In9.Cu")
		(net "TP_CPU1_RSVD_198")
	)
	(segment
		(start 117.534182 -85.89391)
		(end 116.743988 -85.103716)
		(width 0.0889)
		(layer "In9.Cu")
		(net "TP_CPU1_RSVD_198")
	)
	(segment
		(start 158.927038 -123.886468)
		(end 157.04058 -123.886468)
		(width 0.089408)
		(layer "In9.Cu")
		(net "TP_CPU1_RSVD_198")
	)
	(segment
		(start 87.781892 -65.834514)
		(end 87.781892 -65.49644)
		(width 0.0889)
		(layer "In9.Cu")
		(net "TP_CPU1_RSVD_198")
	)
	(segment
		(start 160.693354 -122.531124)
		(end 159.337756 -123.886722)
		(width 0.089408)
		(layer "In9.Cu")
		(net "TP_CPU1_RSVD_198")
	)
	(segment
		(start 130.820668 -87.013034)
		(end 130.785108 -87.013034)
		(width 0.0889)
		(layer "In9.Cu")
		(net "TP_CPU1_RSVD_198")
	)
	(segment
		(start 141.699488 -87.4522)
		(end 141.616684 -87.308436)
		(width 0.0889)
		(layer "In9.Cu")
		(net "TP_CPU1_RSVD_198")
	)
	(segment
		(start 115.60683 -83.074256)
		(end 113.147348 -83.074256)
		(width 0.0889)
		(layer "In9.Cu")
		(net "TP_CPU1_RSVD_198")
	)
	(segment
		(start 159.337756 -123.886722)
		(end 158.927292 -123.886722)
		(width 0.089408)
		(layer "In9.Cu")
		(net "TP_CPU1_RSVD_198")
	)
	(segment
		(start 119.231156 -86.215728)
		(end 118.909338 -85.89391)
		(width 0.0889)
		(layer "In9.Cu")
		(net "TP_CPU1_RSVD_198")
	)
	(segment
		(start 90.528902 -79.76489)
		(end 89.32672 -78.562708)
		(width 0.0889)
		(layer "In9.Cu")
		(net "TP_CPU1_RSVD_198")
	)
	(segment
		(start 113.147348 -83.074256)
		(end 110.873794 -80.800702)
		(width 0.0889)
		(layer "In9.Cu")
		(net "TP_CPU1_RSVD_198")
	)
	(segment
		(start 110.873794 -80.800702)
		(end 92.657676 -80.800702)
		(width 0.0889)
		(layer "In9.Cu")
		(net "TP_CPU1_RSVD_198")
	)
	(segment
		(start 145.59153 -113.045494)
		(end 145.59153 -92.712286)
		(width 0.089408)
		(layer "In9.Cu")
		(net "TP_CPU1_RSVD_198")
	)
	(segment
		(start 123.952508 -87.013034)
		(end 123.916948 -87.013034)
		(width 0.0889)
		(layer "In9.Cu")
		(net "TP_CPU1_RSVD_198")
	)
	(segment
		(start 134.254494 -87.013034)
		(end 134.218934 -87.013034)
		(width 0.0889)
		(layer "In9.Cu")
		(net "TP_CPU1_RSVD_198")
	)
	(segment
		(start 119.304562 -86.331806)
		(end 119.231156 -86.215728)
		(width 0.0889)
		(layer "In9.Cu")
		(net "TP_CPU1_RSVD_198")
	)
	(segment
		(start 120.518682 -87.013034)
		(end 120.485916 -87.013034)
		(width 0.0889)
		(layer "In9.Cu")
		(net "TP_CPU1_RSVD_198")
	)
	(segment
		(start 88.658192 -66.391536)
		(end 88.625426 -66.391536)
		(width 0.0889)
		(layer "In9.Cu")
		(net "TP_CPU1_RSVD_198")
	)
	(segment
		(start 116.743988 -85.103716)
		(end 116.743988 -84.211414)
		(width 0.0889)
		(layer "In9.Cu")
		(net "TP_CPU1_RSVD_198")
	)
	(segment
		(start 145.59153 -92.712286)
		(end 143.792194 -90.91295)
		(width 0.089408)
		(layer "In9.Cu")
		(net "TP_CPU1_RSVD_198")
	)
	(segment
		(start 87.846916 -65.899538)
		(end 87.781892 -65.834514)
		(width 0.0889)
		(layer "In9.Cu")
		(net "TP_CPU1_RSVD_198")
	)
	(segment
		(start 156.637736 -124.289312)
		(end 153.366724 -124.289312)
		(width 0.089408)
		(layer "In9.Cu")
		(net "TP_CPU1_RSVD_198")
	)
	(segment
		(start 125.669548 -87.013034)
		(end 125.633988 -87.013034)
		(width 0.0889)
		(layer "In9.Cu")
		(net "TP_CPU1_RSVD_198")
	)
	(segment
		(start 121.016014 -87.314278)
		(end 121.012712 -87.308436)
		(width 0.0889)
		(layer "In9.Cu")
		(net "TP_CPU1_RSVD_198")
	)
	(segment
		(start 118.909338 -85.89391)
		(end 117.534182 -85.89391)
		(width 0.0889)
		(layer "In9.Cu")
		(net "TP_CPU1_RSVD_198")
	)
	(segment
		(start 91.621864 -79.76489)
		(end 90.528902 -79.76489)
		(width 0.0889)
		(layer "In9.Cu")
		(net "TP_CPU1_RSVD_198")
	)
	(segment
		(start 152.425908 -119.879872)
		(end 145.59153 -113.045494)
		(width 0.089408)
		(layer "In9.Cu")
		(net "TP_CPU1_RSVD_198")
	)
	(segment
		(start 132.007864 -87.308436)
		(end 132.00126 -87.319866)
		(width 0.0889)
		(layer "In9.Cu")
		(net "TP_CPU1_RSVD_198")
	)
	(arc
		(start 128.574038 -87.308436)
		(mid 128.227328 -87.508747)
		(end 127.880618 -87.308436)
		(width 0.0889)
		(layer "In9.Cu")
		(net "TP_CPU1_RSVD_198")
	)
	(arc
		(start 119.733822 -86.524592)
		(mid 119.680765 -86.518698)
		(end 119.627396 -86.51748)
		(width 0.0889)
		(layer "In9.Cu")
		(net "TP_CPU1_RSVD_198")
	)
	(arc
		(start 126.856998 -87.308436)
		(mid 126.510288 -87.508747)
		(end 126.163578 -87.308436)
		(width 0.0889)
		(layer "In9.Cu")
		(net "TP_CPU1_RSVD_198")
	)
	(arc
		(start 130.785108 -87.013034)
		(mid 130.499684 -87.096501)
		(end 130.291078 -87.308436)
		(width 0.0889)
		(layer "In9.Cu")
		(net "TP_CPU1_RSVD_198")
	)
	(arc
		(start 130.291078 -87.308436)
		(mid 129.944368 -87.508747)
		(end 129.597658 -87.308436)
		(width 0.0889)
		(layer "In9.Cu")
		(net "TP_CPU1_RSVD_198")
	)
	(arc
		(start 138.182604 -87.308436)
		(mid 137.973996 -87.096504)
		(end 137.688574 -87.013034)
		(width 0.0889)
		(layer "In9.Cu")
		(net "TP_CPU1_RSVD_198")
	)
	(arc
		(start 121.012712 -87.308436)
		(mid 120.804104 -87.096504)
		(end 120.518682 -87.013034)
		(width 0.0889)
		(layer "In9.Cu")
		(net "TP_CPU1_RSVD_198")
	)
	(arc
		(start 129.597658 -87.308436)
		(mid 129.38905 -87.096504)
		(end 129.103628 -87.013034)
		(width 0.0889)
		(layer "In9.Cu")
		(net "TP_CPU1_RSVD_198")
	)
	(arc
		(start 120.154192 -86.813136)
		(mid 119.976798 -86.621101)
		(end 119.733822 -86.524592)
		(width 0.0889)
		(layer "In9.Cu")
		(net "TP_CPU1_RSVD_198")
	)
	(arc
		(start 131.314698 -87.308436)
		(mid 131.10609 -87.096504)
		(end 130.820668 -87.013034)
		(width 0.0889)
		(layer "In9.Cu")
		(net "TP_CPU1_RSVD_198")
	)
	(arc
		(start 142.695422 -87.013034)
		(mid 142.492524 -87.128894)
		(end 142.346426 -87.31123)
		(width 0.0889)
		(layer "In9.Cu")
		(net "TP_CPU1_RSVD_198")
	)
	(arc
		(start 133.031484 -87.308436)
		(mid 132.519674 -87.012769)
		(end 132.007864 -87.308436)
		(width 0.0889)
		(layer "In9.Cu")
		(net "TP_CPU1_RSVD_198")
	)
	(arc
		(start 123.422918 -87.308436)
		(mid 123.076208 -87.508747)
		(end 122.729498 -87.308436)
		(width 0.0889)
		(layer "In9.Cu")
		(net "TP_CPU1_RSVD_198")
	)
	(arc
		(start 88.625426 -66.391536)
		(mid 88.433784 -66.33437)
		(end 88.293702 -66.191638)
		(width 0.0889)
		(layer "In9.Cu")
		(net "TP_CPU1_RSVD_198")
	)
	(arc
		(start 119.627396 -86.51748)
		(mid 119.443093 -86.464457)
		(end 119.304562 -86.331806)
		(width 0.0889)
		(layer "In9.Cu")
		(net "TP_CPU1_RSVD_198")
	)
	(arc
		(start 140.593064 -87.308436)
		(mid 140.246354 -87.508747)
		(end 139.899644 -87.308436)
		(width 0.0889)
		(layer "In9.Cu")
		(net "TP_CPU1_RSVD_198")
	)
	(arc
		(start 142.346426 -87.31123)
		(mid 142.055681 -87.531953)
		(end 141.699488 -87.4522)
		(width 0.0889)
		(layer "In9.Cu")
		(net "TP_CPU1_RSVD_198")
	)
	(arc
		(start 134.748524 -87.308436)
		(mid 134.539916 -87.096504)
		(end 134.254494 -87.013034)
		(width 0.0889)
		(layer "In9.Cu")
		(net "TP_CPU1_RSVD_198")
	)
	(arc
		(start 139.899644 -87.308436)
		(mid 139.387834 -87.012769)
		(end 138.876024 -87.308436)
		(width 0.0889)
		(layer "In9.Cu")
		(net "TP_CPU1_RSVD_198")
	)
	(arc
		(start 125.139958 -87.308436)
		(mid 124.793248 -87.508747)
		(end 124.446538 -87.308436)
		(width 0.0889)
		(layer "In9.Cu")
		(net "TP_CPU1_RSVD_198")
	)
	(arc
		(start 122.729498 -87.308436)
		(mid 122.52089 -87.096504)
		(end 122.235468 -87.013034)
		(width 0.0889)
		(layer "In9.Cu")
		(net "TP_CPU1_RSVD_198")
	)
	(arc
		(start 135.441944 -87.308436)
		(mid 135.095234 -87.508747)
		(end 134.748524 -87.308436)
		(width 0.0889)
		(layer "In9.Cu")
		(net "TP_CPU1_RSVD_198")
	)
	(arc
		(start 135.935974 -87.013034)
		(mid 135.65055 -87.096501)
		(end 135.441944 -87.308436)
		(width 0.0889)
		(layer "In9.Cu")
		(net "TP_CPU1_RSVD_198")
	)
	(arc
		(start 120.485916 -87.013034)
		(mid 120.294274 -86.955868)
		(end 120.154192 -86.813136)
		(width 0.0889)
		(layer "In9.Cu")
		(net "TP_CPU1_RSVD_198")
	)
	(arc
		(start 137.158984 -87.308436)
		(mid 136.812274 -87.508747)
		(end 136.465564 -87.308436)
		(width 0.0889)
		(layer "In9.Cu")
		(net "TP_CPU1_RSVD_198")
	)
	(arc
		(start 137.653014 -87.013034)
		(mid 137.36759 -87.096501)
		(end 137.158984 -87.308436)
		(width 0.0889)
		(layer "In9.Cu")
		(net "TP_CPU1_RSVD_198")
	)
	(arc
		(start 133.724904 -87.308436)
		(mid 133.378194 -87.508747)
		(end 133.031484 -87.308436)
		(width 0.0889)
		(layer "In9.Cu")
		(net "TP_CPU1_RSVD_198")
	)
	(arc
		(start 89.32672 -68.340478)
		(mid 89.283664 -67.997379)
		(end 89.152222 -67.677538)
		(width 0.0889)
		(layer "In9.Cu")
		(net "TP_CPU1_RSVD_198")
	)
	(arc
		(start 136.465564 -87.308436)
		(mid 136.256956 -87.096504)
		(end 135.971534 -87.013034)
		(width 0.0889)
		(layer "In9.Cu")
		(net "TP_CPU1_RSVD_198")
	)
	(arc
		(start 123.916948 -87.013034)
		(mid 123.631524 -87.096501)
		(end 123.422918 -87.308436)
		(width 0.0889)
		(layer "In9.Cu")
		(net "TP_CPU1_RSVD_198")
	)
	(arc
		(start 125.633988 -87.013034)
		(mid 125.348564 -87.096501)
		(end 125.139958 -87.308436)
		(width 0.0889)
		(layer "In9.Cu")
		(net "TP_CPU1_RSVD_198")
	)
	(arc
		(start 89.152222 -67.277742)
		(mid 89.156747 -66.694401)
		(end 88.658192 -66.391536)
		(width 0.0889)
		(layer "In9.Cu")
		(net "TP_CPU1_RSVD_198")
	)
	(arc
		(start 89.152222 -67.677538)
		(mid 89.098689 -67.47764)
		(end 89.152222 -67.277742)
		(width 0.0889)
		(layer "In9.Cu")
		(net "TP_CPU1_RSVD_198")
	)
	(arc
		(start 127.351028 -87.013034)
		(mid 127.065604 -87.096501)
		(end 126.856998 -87.308436)
		(width 0.0889)
		(layer "In9.Cu")
		(net "TP_CPU1_RSVD_198")
	)
	(arc
		(start 126.163578 -87.308436)
		(mid 125.95497 -87.096504)
		(end 125.669548 -87.013034)
		(width 0.0889)
		(layer "In9.Cu")
		(net "TP_CPU1_RSVD_198")
	)
	(arc
		(start 141.616684 -87.308436)
		(mid 141.104874 -87.012769)
		(end 140.593064 -87.308436)
		(width 0.0889)
		(layer "In9.Cu")
		(net "TP_CPU1_RSVD_198")
	)
	(arc
		(start 124.446538 -87.308436)
		(mid 124.23793 -87.096504)
		(end 123.952508 -87.013034)
		(width 0.0889)
		(layer "In9.Cu")
		(net "TP_CPU1_RSVD_198")
	)
	(arc
		(start 121.705878 -87.308436)
		(mid 121.362588 -87.508732)
		(end 121.016014 -87.314278)
		(width 0.0889)
		(layer "In9.Cu")
		(net "TP_CPU1_RSVD_198")
	)
	(arc
		(start 88.293702 -66.191638)
		(mid 88.105174 -65.992265)
		(end 87.846916 -65.899538)
		(width 0.0889)
		(layer "In9.Cu")
		(net "TP_CPU1_RSVD_198")
	)
	(arc
		(start 129.068068 -87.013034)
		(mid 128.782644 -87.096501)
		(end 128.574038 -87.308436)
		(width 0.0889)
		(layer "In9.Cu")
		(net "TP_CPU1_RSVD_198")
	)
	(arc
		(start 122.199908 -87.013034)
		(mid 121.914484 -87.096501)
		(end 121.705878 -87.308436)
		(width 0.0889)
		(layer "In9.Cu")
		(net "TP_CPU1_RSVD_198")
	)
	(arc
		(start 134.218934 -87.013034)
		(mid 133.93351 -87.096501)
		(end 133.724904 -87.308436)
		(width 0.0889)
		(layer "In9.Cu")
		(net "TP_CPU1_RSVD_198")
	)
	(arc
		(start 127.880618 -87.308436)
		(mid 127.67201 -87.096504)
		(end 127.386588 -87.013034)
		(width 0.0889)
		(layer "In9.Cu")
		(net "TP_CPU1_RSVD_198")
	)
	(arc
		(start 132.00126 -87.319866)
		(mid 131.654743 -87.508681)
		(end 131.314698 -87.308436)
		(width 0.0889)
		(layer "In9.Cu")
		(net "TP_CPU1_RSVD_198")
	)
	(arc
		(start 138.876024 -87.308436)
		(mid 138.529314 -87.508747)
		(end 138.182604 -87.308436)
		(width 0.0889)
		(layer "In9.Cu")
		(net "TP_CPU1_RSVD_198")
	)
	(segment
		(start 89.211912 -65.991486)
		(end 88.640412 -65.991486)
		(width 0.10795)
		(layer "F.Cu")
		(net "TP_CPU1_RSVD_194")
	)
	(via
		(at 153.714704 -123.845574)
		(size 0.762)
		(drill 0.3048)
		(layers "F.Cu" "B.Cu")
		(net "TP_CPU1_RSVD_194")
	)
	(via
		(at 88.640412 -65.991486)
		(size 0.508)
		(drill 0.254)
		(layers "F.Cu" "B.Cu")
		(net "TP_CPU1_RSVD_194")
	)
	(segment
		(start 89.022682 -65.846706)
		(end 88.933274 -65.822576)
		(width 0.0889)
		(layer "In9.Cu")
		(net "TP_CPU1_RSVD_194")
	)
	(segment
		(start 144.059402 -90.802206)
		(end 144.059402 -86.842854)
		(width 0.089408)
		(layer "In9.Cu")
		(net "TP_CPU1_RSVD_194")
	)
	(segment
		(start 132.17652 -86.407244)
		(end 132.173218 -86.413086)
		(width 0.0889)
		(layer "In9.Cu")
		(net "TP_CPU1_RSVD_194")
	)
	(segment
		(start 133.395974 -86.708488)
		(end 133.360414 -86.708488)
		(width 0.0889)
		(layer "In9.Cu")
		(net "TP_CPU1_RSVD_194")
	)
	(segment
		(start 143.159988 -86.212934)
		(end 142.731744 -86.212934)
		(width 0.0889)
		(layer "In9.Cu")
		(net "TP_CPU1_RSVD_194")
	)
	(segment
		(start 142.166086 -86.708488)
		(end 141.945614 -86.708488)
		(width 0.0889)
		(layer "In9.Cu")
		(net "TP_CPU1_RSVD_194")
	)
	(segment
		(start 152.693116 -122.823986)
		(end 152.693116 -119.769128)
		(width 0.089408)
		(layer "In9.Cu")
		(net "TP_CPU1_RSVD_194")
	)
	(segment
		(start 119.936006 -85.836252)
		(end 119.797068 -85.697314)
		(width 0.0889)
		(layer "In9.Cu")
		(net "TP_CPU1_RSVD_194")
	)
	(segment
		(start 120.847358 -86.413086)
		(end 120.844056 -86.407244)
		(width 0.0889)
		(layer "In9.Cu")
		(net "TP_CPU1_RSVD_194")
	)
	(segment
		(start 126.528068 -86.708488)
		(end 126.492508 -86.708488)
		(width 0.0889)
		(layer "In9.Cu")
		(net "TP_CPU1_RSVD_194")
	)
	(segment
		(start 89.839038 -66.697606)
		(end 89.845388 -66.686938)
		(width 0.0889)
		(layer "In9.Cu")
		(net "TP_CPU1_RSVD_194")
	)
	(segment
		(start 129.962148 -86.708488)
		(end 129.926588 -86.708488)
		(width 0.0889)
		(layer "In9.Cu")
		(net "TP_CPU1_RSVD_194")
	)
	(segment
		(start 152.693116 -119.769128)
		(end 145.858738 -112.93475)
		(width 0.089408)
		(layer "In9.Cu")
		(net "TP_CPU1_RSVD_194")
	)
	(segment
		(start 113.693702 -80.585818)
		(end 92.787978 -80.585818)
		(width 0.0889)
		(layer "In9.Cu")
		(net "TP_CPU1_RSVD_194")
	)
	(segment
		(start 89.513664 -66.08699)
		(end 89.480898 -66.08699)
		(width 0.0889)
		(layer "In9.Cu")
		(net "TP_CPU1_RSVD_194")
	)
	(segment
		(start 140.264134 -86.708488)
		(end 140.228574 -86.708488)
		(width 0.0889)
		(layer "In9.Cu")
		(net "TP_CPU1_RSVD_194")
	)
	(segment
		(start 144.059402 -86.842854)
		(end 143.42999 -86.213442)
		(width 0.089408)
		(layer "In9.Cu")
		(net "TP_CPU1_RSVD_194")
	)
	(segment
		(start 131.679188 -86.708488)
		(end 131.643628 -86.708488)
		(width 0.0889)
		(layer "In9.Cu")
		(net "TP_CPU1_RSVD_194")
	)
	(segment
		(start 90.403172 -78.964536)
		(end 89.716356 -78.27772)
		(width 0.0889)
		(layer "In9.Cu")
		(net "TP_CPU1_RSVD_194")
	)
	(segment
		(start 117.084094 -83.97621)
		(end 113.693702 -80.585818)
		(width 0.0889)
		(layer "In9.Cu")
		(net "TP_CPU1_RSVD_194")
	)
	(segment
		(start 145.858738 -112.93475)
		(end 145.858738 -92.601542)
		(width 0.089408)
		(layer "In9.Cu")
		(net "TP_CPU1_RSVD_194")
	)
	(segment
		(start 117.084094 -85.174582)
		(end 117.084094 -83.97621)
		(width 0.0889)
		(layer "In9.Cu")
		(net "TP_CPU1_RSVD_194")
	)
	(segment
		(start 121.376948 -86.708488)
		(end 121.341388 -86.708488)
		(width 0.0889)
		(layer "In9.Cu")
		(net "TP_CPU1_RSVD_194")
	)
	(segment
		(start 153.714704 -123.845574)
		(end 152.693116 -122.823986)
		(width 0.089408)
		(layer "In9.Cu")
		(net "TP_CPU1_RSVD_194")
	)
	(segment
		(start 89.716356 -78.27772)
		(end 89.716356 -68.314062)
		(width 0.0889)
		(layer "In9.Cu")
		(net "TP_CPU1_RSVD_194")
	)
	(segment
		(start 138.547094 -86.708488)
		(end 138.511534 -86.708488)
		(width 0.0889)
		(layer "In9.Cu")
		(net "TP_CPU1_RSVD_194")
	)
	(segment
		(start 92.787978 -80.585818)
		(end 91.166696 -78.964536)
		(width 0.0889)
		(layer "In9.Cu")
		(net "TP_CPU1_RSVD_194")
	)
	(segment
		(start 117.606826 -85.697314)
		(end 117.084094 -85.174582)
		(width 0.0889)
		(layer "In9.Cu")
		(net "TP_CPU1_RSVD_194")
	)
	(segment
		(start 120.000268 -85.937852)
		(end 119.936006 -85.836252)
		(width 0.0889)
		(layer "In9.Cu")
		(net "TP_CPU1_RSVD_194")
	)
	(segment
		(start 128.245108 -86.708488)
		(end 128.209548 -86.708488)
		(width 0.0889)
		(layer "In9.Cu")
		(net "TP_CPU1_RSVD_194")
	)
	(segment
		(start 119.797068 -85.697314)
		(end 117.606826 -85.697314)
		(width 0.0889)
		(layer "In9.Cu")
		(net "TP_CPU1_RSVD_194")
	)
	(segment
		(start 89.845388 -66.686938)
		(end 89.850214 -66.678302)
		(width 0.0889)
		(layer "In9.Cu")
		(net "TP_CPU1_RSVD_194")
	)
	(segment
		(start 143.160496 -86.213442)
		(end 143.159988 -86.212934)
		(width 0.0889)
		(layer "In9.Cu")
		(net "TP_CPU1_RSVD_194")
	)
	(segment
		(start 91.166696 -78.964536)
		(end 90.403172 -78.964536)
		(width 0.0889)
		(layer "In9.Cu")
		(net "TP_CPU1_RSVD_194")
	)
	(segment
		(start 89.845388 -67.677538)
		(end 89.850214 -67.668902)
		(width 0.0889)
		(layer "In9.Cu")
		(net "TP_CPU1_RSVD_194")
	)
	(segment
		(start 124.811028 -86.708488)
		(end 124.775468 -86.708488)
		(width 0.0889)
		(layer "In9.Cu")
		(net "TP_CPU1_RSVD_194")
	)
	(segment
		(start 123.093988 -86.708488)
		(end 123.058428 -86.708488)
		(width 0.0889)
		(layer "In9.Cu")
		(net "TP_CPU1_RSVD_194")
	)
	(segment
		(start 145.858738 -92.601542)
		(end 144.059402 -90.802206)
		(width 0.089408)
		(layer "In9.Cu")
		(net "TP_CPU1_RSVD_194")
	)
	(segment
		(start 88.933274 -65.822576)
		(end 88.640412 -65.991486)
		(width 0.0889)
		(layer "In9.Cu")
		(net "TP_CPU1_RSVD_194")
	)
	(segment
		(start 135.113014 -86.708488)
		(end 135.077454 -86.708488)
		(width 0.0889)
		(layer "In9.Cu")
		(net "TP_CPU1_RSVD_194")
	)
	(segment
		(start 143.42999 -86.213442)
		(end 143.160496 -86.213442)
		(width 0.089408)
		(layer "In9.Cu")
		(net "TP_CPU1_RSVD_194")
	)
	(segment
		(start 120.500902 -86.212934)
		(end 120.479312 -86.212934)
		(width 0.0889)
		(layer "In9.Cu")
		(net "TP_CPU1_RSVD_194")
	)
	(segment
		(start 136.830054 -86.708488)
		(end 136.794494 -86.708488)
		(width 0.0889)
		(layer "In9.Cu")
		(net "TP_CPU1_RSVD_194")
	)
	(arc
		(start 122.564398 -86.413086)
		(mid 122.217688 -86.212775)
		(end 121.870978 -86.413086)
		(width 0.0889)
		(layer "In9.Cu")
		(net "TP_CPU1_RSVD_194")
	)
	(arc
		(start 130.456178 -86.413086)
		(mid 130.24757 -86.625018)
		(end 129.962148 -86.708488)
		(width 0.0889)
		(layer "In9.Cu")
		(net "TP_CPU1_RSVD_194")
	)
	(arc
		(start 89.716356 -68.314062)
		(mid 89.728965 -67.985276)
		(end 89.845388 -67.677538)
		(width 0.0889)
		(layer "In9.Cu")
		(net "TP_CPU1_RSVD_194")
	)
	(arc
		(start 133.890004 -86.413086)
		(mid 133.681396 -86.625018)
		(end 133.395974 -86.708488)
		(width 0.0889)
		(layer "In9.Cu")
		(net "TP_CPU1_RSVD_194")
	)
	(arc
		(start 89.845388 -67.277488)
		(mid 89.766166 -66.98837)
		(end 89.839038 -66.697606)
		(width 0.0889)
		(layer "In9.Cu")
		(net "TP_CPU1_RSVD_194")
	)
	(arc
		(start 128.209548 -86.708488)
		(mid 127.924124 -86.625021)
		(end 127.715518 -86.413086)
		(width 0.0889)
		(layer "In9.Cu")
		(net "TP_CPU1_RSVD_194")
	)
	(arc
		(start 139.734544 -86.413086)
		(mid 139.387834 -86.212775)
		(end 139.041124 -86.413086)
		(width 0.0889)
		(layer "In9.Cu")
		(net "TP_CPU1_RSVD_194")
	)
	(arc
		(start 123.588018 -86.413086)
		(mid 123.37941 -86.625018)
		(end 123.093988 -86.708488)
		(width 0.0889)
		(layer "In9.Cu")
		(net "TP_CPU1_RSVD_194")
	)
	(arc
		(start 127.715518 -86.413086)
		(mid 127.368808 -86.212775)
		(end 127.022098 -86.413086)
		(width 0.0889)
		(layer "In9.Cu")
		(net "TP_CPU1_RSVD_194")
	)
	(arc
		(start 140.228574 -86.708488)
		(mid 139.94315 -86.625021)
		(end 139.734544 -86.413086)
		(width 0.0889)
		(layer "In9.Cu")
		(net "TP_CPU1_RSVD_194")
	)
	(arc
		(start 128.739138 -86.413086)
		(mid 128.53053 -86.625018)
		(end 128.245108 -86.708488)
		(width 0.0889)
		(layer "In9.Cu")
		(net "TP_CPU1_RSVD_194")
	)
	(arc
		(start 133.360414 -86.708488)
		(mid 133.07499 -86.625021)
		(end 132.866384 -86.413086)
		(width 0.0889)
		(layer "In9.Cu")
		(net "TP_CPU1_RSVD_194")
	)
	(arc
		(start 126.492508 -86.708488)
		(mid 126.207084 -86.625021)
		(end 125.998478 -86.413086)
		(width 0.0889)
		(layer "In9.Cu")
		(net "TP_CPU1_RSVD_194")
	)
	(arc
		(start 89.850214 -67.668902)
		(mid 89.898969 -67.47255)
		(end 89.845388 -67.277488)
		(width 0.0889)
		(layer "In9.Cu")
		(net "TP_CPU1_RSVD_194")
	)
	(arc
		(start 123.058428 -86.708488)
		(mid 122.773004 -86.625021)
		(end 122.564398 -86.413086)
		(width 0.0889)
		(layer "In9.Cu")
		(net "TP_CPU1_RSVD_194")
	)
	(arc
		(start 129.926588 -86.708488)
		(mid 129.641164 -86.625021)
		(end 129.432558 -86.413086)
		(width 0.0889)
		(layer "In9.Cu")
		(net "TP_CPU1_RSVD_194")
	)
	(arc
		(start 124.775468 -86.708488)
		(mid 124.490044 -86.625021)
		(end 124.281438 -86.413086)
		(width 0.0889)
		(layer "In9.Cu")
		(net "TP_CPU1_RSVD_194")
	)
	(arc
		(start 140.758164 -86.413086)
		(mid 140.549556 -86.625018)
		(end 140.264134 -86.708488)
		(width 0.0889)
		(layer "In9.Cu")
		(net "TP_CPU1_RSVD_194")
	)
	(arc
		(start 131.149598 -86.413086)
		(mid 130.802888 -86.212775)
		(end 130.456178 -86.413086)
		(width 0.0889)
		(layer "In9.Cu")
		(net "TP_CPU1_RSVD_194")
	)
	(arc
		(start 131.643628 -86.708488)
		(mid 131.358204 -86.625021)
		(end 131.149598 -86.413086)
		(width 0.0889)
		(layer "In9.Cu")
		(net "TP_CPU1_RSVD_194")
	)
	(arc
		(start 120.844056 -86.407244)
		(mid 120.69809 -86.264845)
		(end 120.500902 -86.212934)
		(width 0.0889)
		(layer "In9.Cu")
		(net "TP_CPU1_RSVD_194")
	)
	(arc
		(start 142.731744 -86.212934)
		(mid 142.606257 -86.292767)
		(end 142.515082 -86.410292)
		(width 0.0889)
		(layer "In9.Cu")
		(net "TP_CPU1_RSVD_194")
	)
	(arc
		(start 138.511534 -86.708488)
		(mid 138.22611 -86.625021)
		(end 138.017504 -86.413086)
		(width 0.0889)
		(layer "In9.Cu")
		(net "TP_CPU1_RSVD_194")
	)
	(arc
		(start 129.432558 -86.413086)
		(mid 129.085848 -86.212775)
		(end 128.739138 -86.413086)
		(width 0.0889)
		(layer "In9.Cu")
		(net "TP_CPU1_RSVD_194")
	)
	(arc
		(start 125.305058 -86.413086)
		(mid 125.09645 -86.625018)
		(end 124.811028 -86.708488)
		(width 0.0889)
		(layer "In9.Cu")
		(net "TP_CPU1_RSVD_194")
	)
	(arc
		(start 121.870978 -86.413086)
		(mid 121.66237 -86.625018)
		(end 121.376948 -86.708488)
		(width 0.0889)
		(layer "In9.Cu")
		(net "TP_CPU1_RSVD_194")
	)
	(arc
		(start 138.017504 -86.413086)
		(mid 137.670794 -86.212775)
		(end 137.324084 -86.413086)
		(width 0.0889)
		(layer "In9.Cu")
		(net "TP_CPU1_RSVD_194")
	)
	(arc
		(start 142.515082 -86.410292)
		(mid 142.368982 -86.592626)
		(end 142.166086 -86.708488)
		(width 0.0889)
		(layer "In9.Cu")
		(net "TP_CPU1_RSVD_194")
	)
	(arc
		(start 135.077454 -86.708488)
		(mid 134.79203 -86.625021)
		(end 134.583424 -86.413086)
		(width 0.0889)
		(layer "In9.Cu")
		(net "TP_CPU1_RSVD_194")
	)
	(arc
		(start 120.479312 -86.212934)
		(mid 120.20575 -86.134672)
		(end 120.000268 -85.937852)
		(width 0.0889)
		(layer "In9.Cu")
		(net "TP_CPU1_RSVD_194")
	)
	(arc
		(start 127.022098 -86.413086)
		(mid 126.81349 -86.625018)
		(end 126.528068 -86.708488)
		(width 0.0889)
		(layer "In9.Cu")
		(net "TP_CPU1_RSVD_194")
	)
	(arc
		(start 141.451584 -86.413086)
		(mid 141.104874 -86.212775)
		(end 140.758164 -86.413086)
		(width 0.0889)
		(layer "In9.Cu")
		(net "TP_CPU1_RSVD_194")
	)
	(arc
		(start 132.866384 -86.413086)
		(mid 132.523094 -86.21279)
		(end 132.17652 -86.407244)
		(width 0.0889)
		(layer "In9.Cu")
		(net "TP_CPU1_RSVD_194")
	)
	(arc
		(start 121.341388 -86.708488)
		(mid 121.055964 -86.625021)
		(end 120.847358 -86.413086)
		(width 0.0889)
		(layer "In9.Cu")
		(net "TP_CPU1_RSVD_194")
	)
	(arc
		(start 89.850214 -66.678302)
		(mid 89.846467 -66.289046)
		(end 89.513664 -66.08699)
		(width 0.0889)
		(layer "In9.Cu")
		(net "TP_CPU1_RSVD_194")
	)
	(arc
		(start 135.607044 -86.413086)
		(mid 135.398436 -86.625018)
		(end 135.113014 -86.708488)
		(width 0.0889)
		(layer "In9.Cu")
		(net "TP_CPU1_RSVD_194")
	)
	(arc
		(start 141.945614 -86.708488)
		(mid 141.66019 -86.625021)
		(end 141.451584 -86.413086)
		(width 0.0889)
		(layer "In9.Cu")
		(net "TP_CPU1_RSVD_194")
	)
	(arc
		(start 139.041124 -86.413086)
		(mid 138.832516 -86.625018)
		(end 138.547094 -86.708488)
		(width 0.0889)
		(layer "In9.Cu")
		(net "TP_CPU1_RSVD_194")
	)
	(arc
		(start 132.173218 -86.413086)
		(mid 131.96461 -86.625018)
		(end 131.679188 -86.708488)
		(width 0.0889)
		(layer "In9.Cu")
		(net "TP_CPU1_RSVD_194")
	)
	(arc
		(start 136.794494 -86.708488)
		(mid 136.50907 -86.625021)
		(end 136.300464 -86.413086)
		(width 0.0889)
		(layer "In9.Cu")
		(net "TP_CPU1_RSVD_194")
	)
	(arc
		(start 124.281438 -86.413086)
		(mid 123.934728 -86.212775)
		(end 123.588018 -86.413086)
		(width 0.0889)
		(layer "In9.Cu")
		(net "TP_CPU1_RSVD_194")
	)
	(arc
		(start 125.998478 -86.413086)
		(mid 125.651768 -86.212775)
		(end 125.305058 -86.413086)
		(width 0.0889)
		(layer "In9.Cu")
		(net "TP_CPU1_RSVD_194")
	)
	(arc
		(start 137.324084 -86.413086)
		(mid 137.115476 -86.625018)
		(end 136.830054 -86.708488)
		(width 0.0889)
		(layer "In9.Cu")
		(net "TP_CPU1_RSVD_194")
	)
	(arc
		(start 89.480898 -66.08699)
		(mid 89.224076 -66.019689)
		(end 89.022682 -65.846706)
		(width 0.0889)
		(layer "In9.Cu")
		(net "TP_CPU1_RSVD_194")
	)
	(arc
		(start 136.300464 -86.413086)
		(mid 135.953754 -86.212775)
		(end 135.607044 -86.413086)
		(width 0.0889)
		(layer "In9.Cu")
		(net "TP_CPU1_RSVD_194")
	)
	(arc
		(start 134.583424 -86.413086)
		(mid 134.236714 -86.212775)
		(end 133.890004 -86.413086)
		(width 0.0889)
		(layer "In9.Cu")
		(net "TP_CPU1_RSVD_194")
	)
	(segment
		(start 372.365524 -67.3862)
		(end 372.365524 -67.361308)
		(width 0.10795)
		(layer "F.Cu")
		(net "PWRGD_PVTT_CPU1")
	)
	(segment
		(start 373.997982 -65.72885)
		(end 373.997982 -65.028318)
		(width 0.10795)
		(layer "F.Cu")
		(net "PWRGD_PVTT_CPU1")
	)
	(segment
		(start 177.47742 -148.64588)
		(end 176.0093 -150.114)
		(width 0.10795)
		(layer "F.Cu")
		(net "PWRGD_PVTT_CPU1")
	)
	(segment
		(start 339.842602 -71.713598)
		(end 339.1916 -72.3646)
		(width 0.10795)
		(layer "F.Cu")
		(net "PWRGD_PVTT_CPU1")
	)
	(segment
		(start 374.344692 -79.894684)
		(end 373.944896 -79.494888)
		(width 0.10795)
		(layer "F.Cu")
		(net "PWRGD_PVTT_CPU1")
	)
	(segment
		(start 350.580706 -70.612)
		(end 349.9231 -69.954394)
		(width 0.10795)
		(layer "F.Cu")
		(net "PWRGD_PVTT_CPU1")
	)
	(segment
		(start 340.919816 -71.713598)
		(end 339.842602 -71.713598)
		(width 0.10795)
		(layer "F.Cu")
		(net "PWRGD_PVTT_CPU1")
	)
	(segment
		(start 372.365524 -67.361308)
		(end 373.997982 -65.72885)
		(width 0.10795)
		(layer "F.Cu")
		(net "PWRGD_PVTT_CPU1")
	)
	(segment
		(start 170.2816 -6.6294)
		(end 170.5864 -6.9342)
		(width 0.10795)
		(layer "F.Cu")
		(net "PWRGD_PVTT_CPU1")
	)
	(segment
		(start 366.647984 -64.52997)
		(end 366.647984 -65.895728)
		(width 0.10795)
		(layer "F.Cu")
		(net "PWRGD_PVTT_CPU1")
	)
	(segment
		(start 353.913694 -70.612)
		(end 352.2345 -70.612)
		(width 0.10795)
		(layer "F.Cu")
		(net "PWRGD_PVTT_CPU1")
	)
	(segment
		(start 366.647984 -65.895728)
		(end 365.242856 -67.300856)
		(width 0.10795)
		(layer "F.Cu")
		(net "PWRGD_PVTT_CPU1")
	)
	(segment
		(start 176.0093 -150.114)
		(end 175.2473 -150.114)
		(width 0.10795)
		(layer "F.Cu")
		(net "PWRGD_PVTT_CPU1")
	)
	(segment
		(start 373.997982 -65.028318)
		(end 374.043702 -64.982598)
		(width 0.10795)
		(layer "F.Cu")
		(net "PWRGD_PVTT_CPU1")
	)
	(segment
		(start 349.9231 -69.954394)
		(end 342.67902 -69.954394)
		(width 0.10795)
		(layer "F.Cu")
		(net "PWRGD_PVTT_CPU1")
	)
	(segment
		(start 342.67902 -69.954394)
		(end 340.919816 -71.713598)
		(width 0.10795)
		(layer "F.Cu")
		(net "PWRGD_PVTT_CPU1")
	)
	(segment
		(start 373.6848 -63.688976)
		(end 368.471704 -63.688976)
		(width 0.10795)
		(layer "F.Cu")
		(net "PWRGD_PVTT_CPU1")
	)
	(segment
		(start 366.829594 -64.34836)
		(end 366.647984 -64.52997)
		(width 0.10795)
		(layer "F.Cu")
		(net "PWRGD_PVTT_CPU1")
	)
	(segment
		(start 367.40211 -64.356742)
		(end 367.393728 -64.34836)
		(width 0.10795)
		(layer "F.Cu")
		(net "PWRGD_PVTT_CPU1")
	)
	(segment
		(start 357.465122 -69.217794)
		(end 355.3079 -69.217794)
		(width 0.10795)
		(layer "F.Cu")
		(net "PWRGD_PVTT_CPU1")
	)
	(segment
		(start 368.471704 -63.688976)
		(end 367.81232 -64.34836)
		(width 0.10795)
		(layer "F.Cu")
		(net "PWRGD_PVTT_CPU1")
	)
	(segment
		(start 367.752122 -64.356742)
		(end 367.40211 -64.356742)
		(width 0.10795)
		(layer "F.Cu")
		(net "PWRGD_PVTT_CPU1")
	)
	(segment
		(start 367.81232 -64.34836)
		(end 367.760504 -64.34836)
		(width 0.10795)
		(layer "F.Cu")
		(net "PWRGD_PVTT_CPU1")
	)
	(segment
		(start 355.3079 -69.217794)
		(end 353.913694 -70.612)
		(width 0.10795)
		(layer "F.Cu")
		(net "PWRGD_PVTT_CPU1")
	)
	(segment
		(start 352.2345 -70.612)
		(end 350.580706 -70.612)
		(width 0.10795)
		(layer "F.Cu")
		(net "PWRGD_PVTT_CPU1")
	)
	(segment
		(start 367.760504 -64.34836)
		(end 367.752122 -64.356742)
		(width 0.10795)
		(layer "F.Cu")
		(net "PWRGD_PVTT_CPU1")
	)
	(segment
		(start 359.404666 -70.109588)
		(end 358.356916 -70.109588)
		(width 0.10795)
		(layer "F.Cu")
		(net "PWRGD_PVTT_CPU1")
	)
	(segment
		(start 358.356916 -70.109588)
		(end 357.465122 -69.217794)
		(width 0.10795)
		(layer "F.Cu")
		(net "PWRGD_PVTT_CPU1")
	)
	(segment
		(start 176.0728 -146.2786)
		(end 176.6824 -146.2786)
		(width 0.10795)
		(layer "F.Cu")
		(net "PWRGD_PVTT_CPU1")
	)
	(segment
		(start 177.47742 -147.07362)
		(end 177.47742 -148.64588)
		(width 0.10795)
		(layer "F.Cu")
		(net "PWRGD_PVTT_CPU1")
	)
	(segment
		(start 176.6824 -146.2786)
		(end 177.47742 -147.07362)
		(width 0.10795)
		(layer "F.Cu")
		(net "PWRGD_PVTT_CPU1")
	)
	(segment
		(start 367.393728 -64.34836)
		(end 366.829594 -64.34836)
		(width 0.10795)
		(layer "F.Cu")
		(net "PWRGD_PVTT_CPU1")
	)
	(segment
		(start 170.5864 -6.9342)
		(end 171.1579 -6.9342)
		(width 0.10795)
		(layer "F.Cu")
		(net "PWRGD_PVTT_CPU1")
	)
	(segment
		(start 374.043702 -64.982598)
		(end 374.043702 -64.047878)
		(width 0.10795)
		(layer "F.Cu")
		(net "PWRGD_PVTT_CPU1")
	)
	(segment
		(start 362.213398 -67.300856)
		(end 359.404666 -70.109588)
		(width 0.10795)
		(layer "F.Cu")
		(net "PWRGD_PVTT_CPU1")
	)
	(segment
		(start 365.242856 -67.300856)
		(end 362.213398 -67.300856)
		(width 0.10795)
		(layer "F.Cu")
		(net "PWRGD_PVTT_CPU1")
	)
	(segment
		(start 374.043702 -64.047878)
		(end 373.6848 -63.688976)
		(width 0.10795)
		(layer "F.Cu")
		(net "PWRGD_PVTT_CPU1")
	)
	(via
		(at 339.1916 -72.3646)
		(size 0.508)
		(drill 0.254)
		(layers "F.Cu" "B.Cu")
		(net "PWRGD_PVTT_CPU1")
	)
	(via
		(at 372.365524 -67.3862)
		(size 0.508)
		(drill 0.254)
		(layers "F.Cu" "B.Cu")
		(net "PWRGD_PVTT_CPU1")
	)
	(via
		(at 352.2345 -70.612)
		(size 0.762)
		(drill 0.381)
		(layers "F.Cu" "B.Cu")
		(net "PWRGD_PVTT_CPU1")
	)
	(via
		(at 176.0728 -146.2786)
		(size 0.508)
		(drill 0.254)
		(layers "F.Cu" "B.Cu")
		(net "PWRGD_PVTT_CPU1")
	)
	(via
		(at 374.344692 -79.894684)
		(size 0.4572)
		(drill 0.2032)
		(layers "F.Cu" "B.Cu")
		(net "PWRGD_PVTT_CPU1")
	)
	(via
		(at 170.2816 -6.6294)
		(size 0.508)
		(drill 0.254)
		(layers "F.Cu" "B.Cu")
		(net "PWRGD_PVTT_CPU1")
	)
	(segment
		(start 159.563562 -129.642362)
		(end 160.97504 -128.230884)
		(width 0.089408)
		(layer "In4.Cu")
		(net "PWRGD_PVTT_CPU1")
	)
	(segment
		(start 159.687514 -70.409054)
		(end 159.687514 -70.406006)
		(width 0.089408)
		(layer "In4.Cu")
		(net "PWRGD_PVTT_CPU1")
	)
	(segment
		(start 159.563562 -140.932662)
		(end 159.563562 -129.642362)
		(width 0.089408)
		(layer "In4.Cu")
		(net "PWRGD_PVTT_CPU1")
	)
	(segment
		(start 176.237392 -94.010988)
		(end 176.62779 -93.62059)
		(width 0.089408)
		(layer "In4.Cu")
		(net "PWRGD_PVTT_CPU1")
	)
	(segment
		(start 159.676592 -12.273788)
		(end 161.016442 -10.933938)
		(width 0.089408)
		(layer "In4.Cu")
		(net "PWRGD_PVTT_CPU1")
	)
	(segment
		(start 166.732458 -142.470378)
		(end 161.101278 -142.470378)
		(width 0.089408)
		(layer "In4.Cu")
		(net "PWRGD_PVTT_CPU1")
	)
	(segment
		(start 327.261982 -111.994188)
		(end 328.166476 -112.898682)
		(width 0.089408)
		(layer "In4.Cu")
		(net "PWRGD_PVTT_CPU1")
	)
	(segment
		(start 175.812704 -123.735084)
		(end 175.812704 -105.746296)
		(width 0.089408)
		(layer "In4.Cu")
		(net "PWRGD_PVTT_CPU1")
	)
	(segment
		(start 324.748144 -145.881344)
		(end 325.920608 -147.053808)
		(width 0.089408)
		(layer "In4.Cu")
		(net "PWRGD_PVTT_CPU1")
	)
	(segment
		(start 176.237392 -105.321608)
		(end 176.237392 -94.010988)
		(width 0.089408)
		(layer "In4.Cu")
		(net "PWRGD_PVTT_CPU1")
	)
	(segment
		(start 163.557712 -71.418196)
		(end 163.383214 -71.243698)
		(width 0.089408)
		(layer "In4.Cu")
		(net "PWRGD_PVTT_CPU1")
	)
	(segment
		(start 330.7842 -136.740646)
		(end 329.221592 -138.303254)
		(width 0.089408)
		(layer "In4.Cu")
		(net "PWRGD_PVTT_CPU1")
	)
	(segment
		(start 331.567536 -129.581148)
		(end 331.567536 -134.702296)
		(width 0.089408)
		(layer "In4.Cu")
		(net "PWRGD_PVTT_CPU1")
	)
	(segment
		(start 338.766912 -72.3646)
		(end 336.544666 -74.586846)
		(width 0.089408)
		(layer "In4.Cu")
		(net "PWRGD_PVTT_CPU1")
	)
	(segment
		(start 171.86275 -144.93875)
		(end 169.20083 -144.93875)
		(width 0.089408)
		(layer "In4.Cu")
		(net "PWRGD_PVTT_CPU1")
	)
	(segment
		(start 172.705776 -35.66287)
		(end 174.665132 -33.703514)
		(width 0.089408)
		(layer "In4.Cu")
		(net "PWRGD_PVTT_CPU1")
	)
	(segment
		(start 172.9232 -78.9178)
		(end 167.9702 -78.9178)
		(width 0.089408)
		(layer "In4.Cu")
		(net "PWRGD_PVTT_CPU1")
	)
	(segment
		(start 165.8112 -74.242422)
		(end 163.557712 -71.988934)
		(width 0.089408)
		(layer "In4.Cu")
		(net "PWRGD_PVTT_CPU1")
	)
	(segment
		(start 159.676592 -23.557992)
		(end 159.676592 -12.273788)
		(width 0.089408)
		(layer "In4.Cu")
		(net "PWRGD_PVTT_CPU1")
	)
	(segment
		(start 160.185354 -70.903846)
		(end 160.182306 -70.903846)
		(width 0.089408)
		(layer "In4.Cu")
		(net "PWRGD_PVTT_CPU1")
	)
	(segment
		(start 328.166476 -120.95607)
		(end 327.1774 -121.945146)
		(width 0.089408)
		(layer "In4.Cu")
		(net "PWRGD_PVTT_CPU1")
	)
	(segment
		(start 168.11498 -65.786)
		(end 170.3705 -63.53048)
		(width 0.089408)
		(layer "In4.Cu")
		(net "PWRGD_PVTT_CPU1")
	)
	(segment
		(start 173.0502 -83.30438)
		(end 173.0502 -79.0448)
		(width 0.089408)
		(layer "In4.Cu")
		(net "PWRGD_PVTT_CPU1")
	)
	(segment
		(start 170.298364 -8.133588)
		(end 170.896534 -7.535418)
		(width 0.089408)
		(layer "In4.Cu")
		(net "PWRGD_PVTT_CPU1")
	)
	(segment
		(start 163.148518 -71.009002)
		(end 163.116006 -70.97649)
		(width 0.089408)
		(layer "In4.Cu")
		(net "PWRGD_PVTT_CPU1")
	)
	(segment
		(start 281.328622 -157.478222)
		(end 280.873962 -157.023562)
		(width 0.089408)
		(layer "In4.Cu")
		(net "PWRGD_PVTT_CPU1")
	)
	(segment
		(start 328.089514 -126.103126)
		(end 331.567536 -129.581148)
		(width 0.089408)
		(layer "In4.Cu")
		(net "PWRGD_PVTT_CPU1")
	)
	(segment
		(start 177.423572 -91.3638)
		(end 177.423572 -87.677752)
		(width 0.089408)
		(layer "In4.Cu")
		(net "PWRGD_PVTT_CPU1")
	)
	(segment
		(start 170.3705 -63.53048)
		(end 173.19244 -63.53048)
		(width 0.089408)
		(layer "In4.Cu")
		(net "PWRGD_PVTT_CPU1")
	)
	(segment
		(start 326.475344 -157.478222)
		(end 281.328622 -157.478222)
		(width 0.089408)
		(layer "In4.Cu")
		(net "PWRGD_PVTT_CPU1")
	)
	(segment
		(start 172.776134 -52.564792)
		(end 171.111672 -50.90033)
		(width 0.089408)
		(layer "In4.Cu")
		(net "PWRGD_PVTT_CPU1")
	)
	(segment
		(start 166.27602 -65.786)
		(end 168.11498 -65.786)
		(width 0.089408)
		(layer "In4.Cu")
		(net "PWRGD_PVTT_CPU1")
	)
	(segment
		(start 175.007524 -146.678904)
		(end 173.68139 -145.35277)
		(width 0.089408)
		(layer "In4.Cu")
		(net "PWRGD_PVTT_CPU1")
	)
	(segment
		(start 332.818232 -82.701384)
		(end 332.818232 -85.77707)
		(width 0.089408)
		(layer "In4.Cu")
		(net "PWRGD_PVTT_CPU1")
	)
	(segment
		(start 264.666476 -157.34919)
		(end 189.032388 -157.34919)
		(width 0.089408)
		(layer "In4.Cu")
		(net "PWRGD_PVTT_CPU1")
	)
	(segment
		(start 166.034212 -65.544192)
		(end 166.27602 -65.786)
		(width 0.089408)
		(layer "In4.Cu")
		(net "PWRGD_PVTT_CPU1")
	)
	(segment
		(start 336.544666 -77.903578)
		(end 335.880456 -78.567788)
		(width 0.089408)
		(layer "In4.Cu")
		(net "PWRGD_PVTT_CPU1")
	)
	(segment
		(start 189.032388 -157.34919)
		(end 186.695334 -155.012136)
		(width 0.089408)
		(layer "In4.Cu")
		(net "PWRGD_PVTT_CPU1")
	)
	(segment
		(start 171.111672 -50.90033)
		(end 171.111672 -49.20996)
		(width 0.089408)
		(layer "In4.Cu")
		(net "PWRGD_PVTT_CPU1")
	)
	(segment
		(start 280.873962 -157.023562)
		(end 264.992104 -157.023562)
		(width 0.089408)
		(layer "In4.Cu")
		(net "PWRGD_PVTT_CPU1")
	)
	(segment
		(start 330.7842 -135.485632)
		(end 330.7842 -136.740646)
		(width 0.089408)
		(layer "In4.Cu")
		(net "PWRGD_PVTT_CPU1")
	)
	(segment
		(start 170.896534 -6.964934)
		(end 170.561 -6.6294)
		(width 0.089408)
		(layer "In4.Cu")
		(net "PWRGD_PVTT_CPU1")
	)
	(segment
		(start 160.97504 -128.230884)
		(end 168.606724 -128.230884)
		(width 0.089408)
		(layer "In4.Cu")
		(net "PWRGD_PVTT_CPU1")
	)
	(segment
		(start 186.695334 -155.012136)
		(end 186.695334 -150.90648)
		(width 0.089408)
		(layer "In4.Cu")
		(net "PWRGD_PVTT_CPU1")
	)
	(segment
		(start 163.383214 -71.243698)
		(end 163.383214 -71.243444)
		(width 0.089408)
		(layer "In4.Cu")
		(net "PWRGD_PVTT_CPU1")
	)
	(segment
		(start 331.567536 -134.702296)
		(end 330.7842 -135.485632)
		(width 0.089408)
		(layer "In4.Cu")
		(net "PWRGD_PVTT_CPU1")
	)
	(segment
		(start 335.880456 -79.63916)
		(end 332.818232 -82.701384)
		(width 0.089408)
		(layer "In4.Cu")
		(net "PWRGD_PVTT_CPU1")
	)
	(segment
		(start 328.089514 -123.628658)
		(end 328.089514 -126.103126)
		(width 0.089408)
		(layer "In4.Cu")
		(net "PWRGD_PVTT_CPU1")
	)
	(segment
		(start 264.992104 -157.023562)
		(end 264.666476 -157.34919)
		(width 0.089408)
		(layer "In4.Cu")
		(net "PWRGD_PVTT_CPU1")
	)
	(segment
		(start 171.111672 -49.20996)
		(end 172.705776 -47.615856)
		(width 0.089408)
		(layer "In4.Cu")
		(net "PWRGD_PVTT_CPU1")
	)
	(segment
		(start 339.1916 -72.3646)
		(end 338.766912 -72.3646)
		(width 0.089408)
		(layer "In4.Cu")
		(net "PWRGD_PVTT_CPU1")
	)
	(segment
		(start 325.920608 -147.053808)
		(end 326.655938 -147.053808)
		(width 0.089408)
		(layer "In4.Cu")
		(net "PWRGD_PVTT_CPU1")
	)
	(segment
		(start 327.261982 -91.33332)
		(end 327.261982 -111.994188)
		(width 0.089408)
		(layer "In4.Cu")
		(net "PWRGD_PVTT_CPU1")
	)
	(segment
		(start 163.383214 -71.243444)
		(end 163.148772 -71.009002)
		(width 0.089408)
		(layer "In4.Cu")
		(net "PWRGD_PVTT_CPU1")
	)
	(segment
		(start 160.558734 -24.440134)
		(end 159.676592 -23.557992)
		(width 0.089408)
		(layer "In4.Cu")
		(net "PWRGD_PVTT_CPU1")
	)
	(segment
		(start 329.221592 -138.303254)
		(end 326.49414 -138.303254)
		(width 0.089408)
		(layer "In4.Cu")
		(net "PWRGD_PVTT_CPU1")
	)
	(segment
		(start 174.665132 -28.914852)
		(end 170.190414 -24.440134)
		(width 0.089408)
		(layer "In4.Cu")
		(net "PWRGD_PVTT_CPU1")
	)
	(segment
		(start 159.4358 -70.154292)
		(end 159.4358 -66.929)
		(width 0.089408)
		(layer "In4.Cu")
		(net "PWRGD_PVTT_CPU1")
	)
	(segment
		(start 168.0972 -9.7028)
		(end 169.666412 -8.133588)
		(width 0.089408)
		(layer "In4.Cu")
		(net "PWRGD_PVTT_CPU1")
	)
	(segment
		(start 328.683366 -149.081236)
		(end 328.683366 -155.2702)
		(width 0.089408)
		(layer "In4.Cu")
		(net "PWRGD_PVTT_CPU1")
	)
	(segment
		(start 170.896534 -7.535418)
		(end 170.896534 -6.964934)
		(width 0.089408)
		(layer "In4.Cu")
		(net "PWRGD_PVTT_CPU1")
	)
	(segment
		(start 176.62779 -93.62059)
		(end 176.62779 -92.159582)
		(width 0.089408)
		(layer "In4.Cu")
		(net "PWRGD_PVTT_CPU1")
	)
	(segment
		(start 170.190414 -24.440134)
		(end 160.558734 -24.440134)
		(width 0.089408)
		(layer "In4.Cu")
		(net "PWRGD_PVTT_CPU1")
	)
	(segment
		(start 175.812704 -105.746296)
		(end 176.237392 -105.321608)
		(width 0.089408)
		(layer "In4.Cu")
		(net "PWRGD_PVTT_CPU1")
	)
	(segment
		(start 335.880456 -78.567788)
		(end 335.880456 -79.63916)
		(width 0.089408)
		(layer "In4.Cu")
		(net "PWRGD_PVTT_CPU1")
	)
	(segment
		(start 181.3814 -149.4536)
		(end 178.2064 -146.2786)
		(width 0.089408)
		(layer "In4.Cu")
		(net "PWRGD_PVTT_CPU1")
	)
	(segment
		(start 177.184304 -127.37338)
		(end 177.184304 -125.106684)
		(width 0.089408)
		(layer "In4.Cu")
		(net "PWRGD_PVTT_CPU1")
	)
	(segment
		(start 172.776134 -60.972954)
		(end 172.776134 -52.564792)
		(width 0.089408)
		(layer "In4.Cu")
		(net "PWRGD_PVTT_CPU1")
	)
	(segment
		(start 324.748144 -140.04925)
		(end 324.748144 -145.881344)
		(width 0.089408)
		(layer "In4.Cu")
		(net "PWRGD_PVTT_CPU1")
	)
	(segment
		(start 174.665132 -33.703514)
		(end 174.665132 -28.914852)
		(width 0.089408)
		(layer "In4.Cu")
		(net "PWRGD_PVTT_CPU1")
	)
	(segment
		(start 178.2064 -146.2786)
		(end 176.0728 -146.2786)
		(width 0.089408)
		(layer "In4.Cu")
		(net "PWRGD_PVTT_CPU1")
	)
	(segment
		(start 327.1774 -122.716544)
		(end 328.089514 -123.628658)
		(width 0.089408)
		(layer "In4.Cu")
		(net "PWRGD_PVTT_CPU1")
	)
	(segment
		(start 336.544666 -74.586846)
		(end 336.544666 -77.903578)
		(width 0.089408)
		(layer "In4.Cu")
		(net "PWRGD_PVTT_CPU1")
	)
	(segment
		(start 160.182306 -70.903846)
		(end 159.687514 -70.409054)
		(width 0.089408)
		(layer "In4.Cu")
		(net "PWRGD_PVTT_CPU1")
	)
	(segment
		(start 163.945316 -10.934192)
		(end 165.176708 -9.7028)
		(width 0.089408)
		(layer "In4.Cu")
		(net "PWRGD_PVTT_CPU1")
	)
	(segment
		(start 165.176708 -9.7028)
		(end 168.0972 -9.7028)
		(width 0.089408)
		(layer "In4.Cu")
		(net "PWRGD_PVTT_CPU1")
	)
	(segment
		(start 176.0728 -146.2786)
		(end 175.672496 -146.678904)
		(width 0.089408)
		(layer "In4.Cu")
		(net "PWRGD_PVTT_CPU1")
	)
	(segment
		(start 169.299128 -128.923288)
		(end 175.634396 -128.923288)
		(width 0.089408)
		(layer "In4.Cu")
		(net "PWRGD_PVTT_CPU1")
	)
	(segment
		(start 169.20083 -144.93875)
		(end 166.732458 -142.470378)
		(width 0.089408)
		(layer "In4.Cu")
		(net "PWRGD_PVTT_CPU1")
	)
	(segment
		(start 332.818232 -85.77707)
		(end 327.261982 -91.33332)
		(width 0.089408)
		(layer "In4.Cu")
		(net "PWRGD_PVTT_CPU1")
	)
	(segment
		(start 172.27677 -145.35277)
		(end 171.86275 -144.93875)
		(width 0.089408)
		(layer "In4.Cu")
		(net "PWRGD_PVTT_CPU1")
	)
	(segment
		(start 326.49414 -138.303254)
		(end 324.748144 -140.04925)
		(width 0.089408)
		(layer "In4.Cu")
		(net "PWRGD_PVTT_CPU1")
	)
	(segment
		(start 328.166476 -112.898682)
		(end 328.166476 -120.95607)
		(width 0.089408)
		(layer "In4.Cu")
		(net "PWRGD_PVTT_CPU1")
	)
	(segment
		(start 163.148772 -71.009002)
		(end 163.148518 -71.009002)
		(width 0.089408)
		(layer "In4.Cu")
		(net "PWRGD_PVTT_CPU1")
	)
	(segment
		(start 159.687514 -70.406006)
		(end 159.4358 -70.154292)
		(width 0.089408)
		(layer "In4.Cu")
		(net "PWRGD_PVTT_CPU1")
	)
	(segment
		(start 159.4358 -66.929)
		(end 160.820608 -65.544192)
		(width 0.089408)
		(layer "In4.Cu")
		(net "PWRGD_PVTT_CPU1")
	)
	(segment
		(start 176.62779 -92.159582)
		(end 177.423572 -91.3638)
		(width 0.089408)
		(layer "In4.Cu")
		(net "PWRGD_PVTT_CPU1")
	)
	(segment
		(start 160.820608 -65.544192)
		(end 166.034212 -65.544192)
		(width 0.089408)
		(layer "In4.Cu")
		(net "PWRGD_PVTT_CPU1")
	)
	(segment
		(start 168.606724 -128.230884)
		(end 169.299128 -128.923288)
		(width 0.089408)
		(layer "In4.Cu")
		(net "PWRGD_PVTT_CPU1")
	)
	(segment
		(start 167.9702 -78.9178)
		(end 165.8112 -76.7588)
		(width 0.089408)
		(layer "In4.Cu")
		(net "PWRGD_PVTT_CPU1")
	)
	(segment
		(start 185.242454 -149.4536)
		(end 181.3814 -149.4536)
		(width 0.089408)
		(layer "In4.Cu")
		(net "PWRGD_PVTT_CPU1")
	)
	(segment
		(start 173.0502 -79.0448)
		(end 172.9232 -78.9178)
		(width 0.089408)
		(layer "In4.Cu")
		(net "PWRGD_PVTT_CPU1")
	)
	(segment
		(start 163.557712 -71.988934)
		(end 163.557712 -71.418196)
		(width 0.089408)
		(layer "In4.Cu")
		(net "PWRGD_PVTT_CPU1")
	)
	(segment
		(start 186.695334 -150.90648)
		(end 185.242454 -149.4536)
		(width 0.089408)
		(layer "In4.Cu")
		(net "PWRGD_PVTT_CPU1")
	)
	(segment
		(start 177.184304 -125.106684)
		(end 175.812704 -123.735084)
		(width 0.089408)
		(layer "In4.Cu")
		(net "PWRGD_PVTT_CPU1")
	)
	(segment
		(start 160.257998 -70.97649)
		(end 160.185354 -70.903846)
		(width 0.089408)
		(layer "In4.Cu")
		(net "PWRGD_PVTT_CPU1")
	)
	(segment
		(start 165.8112 -76.7588)
		(end 165.8112 -74.242422)
		(width 0.089408)
		(layer "In4.Cu")
		(net "PWRGD_PVTT_CPU1")
	)
	(segment
		(start 177.423572 -87.677752)
		(end 173.0502 -83.30438)
		(width 0.089408)
		(layer "In4.Cu")
		(net "PWRGD_PVTT_CPU1")
	)
	(segment
		(start 327.1774 -121.945146)
		(end 327.1774 -122.716544)
		(width 0.089408)
		(layer "In4.Cu")
		(net "PWRGD_PVTT_CPU1")
	)
	(segment
		(start 161.259012 -10.934192)
		(end 163.945316 -10.934192)
		(width 0.089408)
		(layer "In4.Cu")
		(net "PWRGD_PVTT_CPU1")
	)
	(segment
		(start 326.655938 -147.053808)
		(end 328.683366 -149.081236)
		(width 0.089408)
		(layer "In4.Cu")
		(net "PWRGD_PVTT_CPU1")
	)
	(segment
		(start 175.634396 -128.923288)
		(end 177.184304 -127.37338)
		(width 0.089408)
		(layer "In4.Cu")
		(net "PWRGD_PVTT_CPU1")
	)
	(segment
		(start 173.736 -62.98692)
		(end 173.736 -61.93282)
		(width 0.089408)
		(layer "In4.Cu")
		(net "PWRGD_PVTT_CPU1")
	)
	(segment
		(start 173.68139 -145.35277)
		(end 172.27677 -145.35277)
		(width 0.089408)
		(layer "In4.Cu")
		(net "PWRGD_PVTT_CPU1")
	)
	(segment
		(start 170.561 -6.6294)
		(end 170.2816 -6.6294)
		(width 0.089408)
		(layer "In4.Cu")
		(net "PWRGD_PVTT_CPU1")
	)
	(segment
		(start 161.016442 -10.933938)
		(end 161.258758 -10.933938)
		(width 0.089408)
		(layer "In4.Cu")
		(net "PWRGD_PVTT_CPU1")
	)
	(segment
		(start 173.736 -61.93282)
		(end 172.776134 -60.972954)
		(width 0.089408)
		(layer "In4.Cu")
		(net "PWRGD_PVTT_CPU1")
	)
	(segment
		(start 163.116006 -70.97649)
		(end 160.257998 -70.97649)
		(width 0.089408)
		(layer "In4.Cu")
		(net "PWRGD_PVTT_CPU1")
	)
	(segment
		(start 161.258758 -10.933938)
		(end 161.259012 -10.934192)
		(width 0.089408)
		(layer "In4.Cu")
		(net "PWRGD_PVTT_CPU1")
	)
	(segment
		(start 175.672496 -146.678904)
		(end 175.007524 -146.678904)
		(width 0.089408)
		(layer "In4.Cu")
		(net "PWRGD_PVTT_CPU1")
	)
	(segment
		(start 173.19244 -63.53048)
		(end 173.736 -62.98692)
		(width 0.089408)
		(layer "In4.Cu")
		(net "PWRGD_PVTT_CPU1")
	)
	(segment
		(start 328.683366 -155.2702)
		(end 326.475344 -157.478222)
		(width 0.089408)
		(layer "In4.Cu")
		(net "PWRGD_PVTT_CPU1")
	)
	(segment
		(start 169.666412 -8.133588)
		(end 170.298364 -8.133588)
		(width 0.089408)
		(layer "In4.Cu")
		(net "PWRGD_PVTT_CPU1")
	)
	(segment
		(start 172.705776 -47.615856)
		(end 172.705776 -35.66287)
		(width 0.089408)
		(layer "In4.Cu")
		(net "PWRGD_PVTT_CPU1")
	)
	(segment
		(start 161.101278 -142.470378)
		(end 159.563562 -140.932662)
		(width 0.089408)
		(layer "In4.Cu")
		(net "PWRGD_PVTT_CPU1")
	)
	(segment
		(start 373.971312 -79.521304)
		(end 374.344692 -79.894684)
		(width 0.089408)
		(layer "In9.Cu")
		(net "PWRGD_PVTT_CPU1")
	)
	(segment
		(start 372.744238 -68.576952)
		(end 372.744238 -78.822296)
		(width 0.089408)
		(layer "In9.Cu")
		(net "PWRGD_PVTT_CPU1")
	)
	(segment
		(start 373.443246 -79.521304)
		(end 373.971312 -79.521304)
		(width 0.089408)
		(layer "In9.Cu")
		(net "PWRGD_PVTT_CPU1")
	)
	(segment
		(start 372.744238 -78.822296)
		(end 373.443246 -79.521304)
		(width 0.089408)
		(layer "In9.Cu")
		(net "PWRGD_PVTT_CPU1")
	)
	(segment
		(start 372.48084 -68.313554)
		(end 372.744238 -68.576952)
		(width 0.089408)
		(layer "In9.Cu")
		(net "PWRGD_PVTT_CPU1")
	)
	(segment
		(start 372.365524 -67.3862)
		(end 372.48084 -67.501516)
		(width 0.089408)
		(layer "In9.Cu")
		(net "PWRGD_PVTT_CPU1")
	)
	(segment
		(start 372.48084 -67.501516)
		(end 372.48084 -68.313554)
		(width 0.089408)
		(layer "In9.Cu")
		(net "PWRGD_PVTT_CPU1")
	)
	(segment
		(start 186.0804 -145.7833)
		(end 185.4454 -145.7833)
		(width 0.10795)
		(layer "F.Cu")
		(net "PWRGD_PVTT_CPU0")
	)
	(segment
		(start 376.744738 -68.695316)
		(end 376.344942 -69.095112)
		(width 0.1016)
		(layer "F.Cu")
		(net "PWRGD_PVTT_CPU0")
	)
	(segment
		(start 180.750464 -6.023864)
		(end 180.0606 -5.334)
		(width 0.10795)
		(layer "F.Cu")
		(net "PWRGD_PVTT_CPU0")
	)
	(segment
		(start 180.794914 -6.023864)
		(end 180.750464 -6.023864)
		(width 0.10795)
		(layer "F.Cu")
		(net "PWRGD_PVTT_CPU0")
	)
	(via
		(at 186.0804 -145.7833)
		(size 0.508)
		(drill 0.254)
		(layers "F.Cu" "B.Cu")
		(net "PWRGD_PVTT_CPU0")
	)
	(via
		(at 375.666 -64.643)
		(size 0.508)
		(drill 0.254)
		(layers "F.Cu" "B.Cu")
		(net "PWRGD_PVTT_CPU0")
	)
	(via
		(at 377.717812 -64.508888)
		(size 0.6604)
		(drill 0.3302)
		(layers "F.Cu" "B.Cu")
		(net "PWRGD_PVTT_CPU0")
	)
	(via
		(at 180.794914 -6.023864)
		(size 0.508)
		(drill 0.254)
		(layers "F.Cu" "B.Cu")
		(net "PWRGD_PVTT_CPU0")
	)
	(via
		(at 376.744738 -68.695316)
		(size 0.4572)
		(drill 0.2032)
		(layers "F.Cu" "B.Cu")
		(net "PWRGD_PVTT_CPU0")
	)
	(segment
		(start 375.666 -64.643)
		(end 376.423936 -64.643)
		(width 0.10795)
		(layer "B.Cu")
		(net "PWRGD_PVTT_CPU0")
	)
	(segment
		(start 376.423936 -64.643)
		(end 376.558048 -64.508888)
		(width 0.10795)
		(layer "B.Cu")
		(net "PWRGD_PVTT_CPU0")
	)
	(segment
		(start 376.558048 -64.508888)
		(end 377.717812 -64.508888)
		(width 0.10795)
		(layer "B.Cu")
		(net "PWRGD_PVTT_CPU0")
	)
	(segment
		(start 160.306766 -70.611238)
		(end 160.303718 -70.611238)
		(width 0.089408)
		(layer "In4.Cu")
		(net "PWRGD_PVTT_CPU0")
	)
	(segment
		(start 166.7002 -74.861166)
		(end 163.85032 -72.011286)
		(width 0.089408)
		(layer "In4.Cu")
		(net "PWRGD_PVTT_CPU0")
	)
	(segment
		(start 159.9692 -12.3952)
		(end 161.1376 -11.2268)
		(width 0.089408)
		(layer "In4.Cu")
		(net "PWRGD_PVTT_CPU0")
	)
	(segment
		(start 368.459004 -67.179952)
		(end 366.531906 -67.179952)
		(width 0.089408)
		(layer "In4.Cu")
		(net "PWRGD_PVTT_CPU0")
	)
	(segment
		(start 173.482 -83.32216)
		(end 173.482 -78.7146)
		(width 0.089408)
		(layer "In4.Cu")
		(net "PWRGD_PVTT_CPU0")
	)
	(segment
		(start 186.0804 -145.7833)
		(end 185.313066 -145.7833)
		(width 0.089408)
		(layer "In4.Cu")
		(net "PWRGD_PVTT_CPU0")
	)
	(segment
		(start 177.71618 -91.6432)
		(end 177.71618 -87.55634)
		(width 0.089408)
		(layer "In4.Cu")
		(net "PWRGD_PVTT_CPU0")
	)
	(segment
		(start 177.476912 -124.985272)
		(end 176.53 -124.03836)
		(width 0.089408)
		(layer "In4.Cu")
		(net "PWRGD_PVTT_CPU0")
	)
	(segment
		(start 281.096974 -156.832554)
		(end 264.769092 -156.832554)
		(width 0.089408)
		(layer "In4.Cu")
		(net "PWRGD_PVTT_CPU0")
	)
	(segment
		(start 362.809028 -71.204836)
		(end 358.627172 -71.204836)
		(width 0.089408)
		(layer "In4.Cu")
		(net "PWRGD_PVTT_CPU0")
	)
	(segment
		(start 327.898506 -126.182374)
		(end 331.376528 -129.660396)
		(width 0.089408)
		(layer "In4.Cu")
		(net "PWRGD_PVTT_CPU0")
	)
	(segment
		(start 159.9692 -23.3426)
		(end 159.9692 -12.3952)
		(width 0.089408)
		(layer "In4.Cu")
		(net "PWRGD_PVTT_CPU0")
	)
	(segment
		(start 358.627172 -71.204836)
		(end 357.397812 -69.975476)
		(width 0.089408)
		(layer "In4.Cu")
		(net "PWRGD_PVTT_CPU0")
	)
	(segment
		(start 160.9852 -65.8368)
		(end 165.9128 -65.8368)
		(width 0.089408)
		(layer "In4.Cu")
		(net "PWRGD_PVTT_CPU0")
	)
	(segment
		(start 161.180272 -142.279116)
		(end 159.754824 -140.853668)
		(width 0.089408)
		(layer "In4.Cu")
		(net "PWRGD_PVTT_CPU0")
	)
	(segment
		(start 357.397812 -69.975476)
		(end 354.489258 -69.975476)
		(width 0.089408)
		(layer "In4.Cu")
		(net "PWRGD_PVTT_CPU0")
	)
	(segment
		(start 372.345966 -65.5066)
		(end 371.164104 -65.5066)
		(width 0.089408)
		(layer "In4.Cu")
		(net "PWRGD_PVTT_CPU0")
	)
	(segment
		(start 169.280078 -144.747742)
		(end 166.811452 -142.279116)
		(width 0.089408)
		(layer "In4.Cu")
		(net "PWRGD_PVTT_CPU0")
	)
	(segment
		(start 173.313852 -63.823088)
		(end 174.028608 -63.108332)
		(width 0.089408)
		(layer "In4.Cu")
		(net "PWRGD_PVTT_CPU0")
	)
	(segment
		(start 326.61606 -118.1227)
		(end 326.61606 -122.42546)
		(width 0.089408)
		(layer "In4.Cu")
		(net "PWRGD_PVTT_CPU0")
	)
	(segment
		(start 364.089696 -69.622162)
		(end 364.089696 -69.924168)
		(width 0.089408)
		(layer "In4.Cu")
		(net "PWRGD_PVTT_CPU0")
	)
	(segment
		(start 177.476912 -127.378714)
		(end 177.476912 -124.985272)
		(width 0.089408)
		(layer "In4.Cu")
		(net "PWRGD_PVTT_CPU0")
	)
	(segment
		(start 170.41241 -24.24811)
		(end 160.87471 -24.24811)
		(width 0.089408)
		(layer "In4.Cu")
		(net "PWRGD_PVTT_CPU0")
	)
	(segment
		(start 354.487988 -69.976492)
		(end 353.911408 -70.553072)
		(width 0.089408)
		(layer "In4.Cu")
		(net "PWRGD_PVTT_CPU0")
	)
	(segment
		(start 163.22548 -70.67169)
		(end 160.367218 -70.67169)
		(width 0.089408)
		(layer "In4.Cu")
		(net "PWRGD_PVTT_CPU0")
	)
	(segment
		(start 179.1208 -8.5852)
		(end 180.794914 -6.911086)
		(width 0.089408)
		(layer "In4.Cu")
		(net "PWRGD_PVTT_CPU0")
	)
	(segment
		(start 160.87471 -24.24811)
		(end 159.9692 -23.3426)
		(width 0.089408)
		(layer "In4.Cu")
		(net "PWRGD_PVTT_CPU0")
	)
	(segment
		(start 264.687558 -156.914088)
		(end 189.011306 -156.914088)
		(width 0.089408)
		(layer "In4.Cu")
		(net "PWRGD_PVTT_CPU0")
	)
	(segment
		(start 340.14537 -71.143368)
		(end 339.40369 -71.885048)
		(width 0.089408)
		(layer "In4.Cu")
		(net "PWRGD_PVTT_CPU0")
	)
	(segment
		(start 169.6974 -10.0076)
		(end 171.1198 -8.5852)
		(width 0.089408)
		(layer "In4.Cu")
		(net "PWRGD_PVTT_CPU0")
	)
	(segment
		(start 366.531906 -67.179952)
		(end 364.089696 -69.622162)
		(width 0.089408)
		(layer "In4.Cu")
		(net "PWRGD_PVTT_CPU0")
	)
	(segment
		(start 326.61606 -122.42546)
		(end 327.898506 -123.707906)
		(width 0.089408)
		(layer "In4.Cu")
		(net "PWRGD_PVTT_CPU0")
	)
	(segment
		(start 175.74133 -129.114296)
		(end 177.476912 -127.378714)
		(width 0.089408)
		(layer "In4.Cu")
		(net "PWRGD_PVTT_CPU0")
	)
	(segment
		(start 332.525624 -85.655658)
		(end 325.957946 -92.223336)
		(width 0.089408)
		(layer "In4.Cu")
		(net "PWRGD_PVTT_CPU0")
	)
	(segment
		(start 159.7406 -70.045072)
		(end 159.7406 -67.0814)
		(width 0.089408)
		(layer "In4.Cu")
		(net "PWRGD_PVTT_CPU0")
	)
	(segment
		(start 338.976208 -71.885048)
		(end 336.353658 -74.507598)
		(width 0.089408)
		(layer "In4.Cu")
		(net "PWRGD_PVTT_CPU0")
	)
	(segment
		(start 159.754824 -140.853668)
		(end 159.754824 -129.742692)
		(width 0.089408)
		(layer "In4.Cu")
		(net "PWRGD_PVTT_CPU0")
	)
	(segment
		(start 369.658392 -67.012312)
		(end 368.626644 -67.012312)
		(width 0.089408)
		(layer "In4.Cu")
		(net "PWRGD_PVTT_CPU0")
	)
	(segment
		(start 163.850574 -71.575422)
		(end 163.850574 -71.296784)
		(width 0.089408)
		(layer "In4.Cu")
		(net "PWRGD_PVTT_CPU0")
	)
	(segment
		(start 326.172068 -115.821206)
		(end 326.172068 -117.678708)
		(width 0.089408)
		(layer "In4.Cu")
		(net "PWRGD_PVTT_CPU0")
	)
	(segment
		(start 160.367218 -70.67169)
		(end 160.306766 -70.611238)
		(width 0.089408)
		(layer "In4.Cu")
		(net "PWRGD_PVTT_CPU0")
	)
	(segment
		(start 174.028608 -61.7474)
		(end 172.967142 -60.685934)
		(width 0.089408)
		(layer "In4.Cu")
		(net "PWRGD_PVTT_CPU0")
	)
	(segment
		(start 164.084 -11.2268)
		(end 165.3032 -10.0076)
		(width 0.089408)
		(layer "In4.Cu")
		(net "PWRGD_PVTT_CPU0")
	)
	(segment
		(start 326.172068 -117.678708)
		(end 326.61606 -118.1227)
		(width 0.089408)
		(layer "In4.Cu")
		(net "PWRGD_PVTT_CPU0")
	)
	(segment
		(start 172.896784 -47.695104)
		(end 172.896784 -36.170616)
		(width 0.089408)
		(layer "In4.Cu")
		(net "PWRGD_PVTT_CPU0")
	)
	(segment
		(start 325.957946 -115.607084)
		(end 326.172068 -115.821206)
		(width 0.089408)
		(layer "In4.Cu")
		(net "PWRGD_PVTT_CPU0")
	)
	(segment
		(start 371.164104 -65.5066)
		(end 369.658392 -67.012312)
		(width 0.089408)
		(layer "In4.Cu")
		(net "PWRGD_PVTT_CPU0")
	)
	(segment
		(start 328.956416 -138.010646)
		(end 326.516492 -138.010646)
		(width 0.089408)
		(layer "In4.Cu")
		(net "PWRGD_PVTT_CPU0")
	)
	(segment
		(start 352.35134 -70.358)
		(end 346.164154 -70.358)
		(width 0.089408)
		(layer "In4.Cu")
		(net "PWRGD_PVTT_CPU0")
	)
	(segment
		(start 324.557136 -139.970002)
		(end 324.557136 -154.486102)
		(width 0.089408)
		(layer "In4.Cu")
		(net "PWRGD_PVTT_CPU0")
	)
	(segment
		(start 177.71618 -87.55634)
		(end 173.482 -83.32216)
		(width 0.089408)
		(layer "In4.Cu")
		(net "PWRGD_PVTT_CPU0")
	)
	(segment
		(start 161.075624 -128.421892)
		(end 168.527476 -128.421892)
		(width 0.089408)
		(layer "In4.Cu")
		(net "PWRGD_PVTT_CPU0")
	)
	(segment
		(start 173.355 -78.5876)
		(end 168.8592 -78.5876)
		(width 0.089408)
		(layer "In4.Cu")
		(net "PWRGD_PVTT_CPU0")
	)
	(segment
		(start 165.3032 -10.0076)
		(end 169.6974 -10.0076)
		(width 0.089408)
		(layer "In4.Cu")
		(net "PWRGD_PVTT_CPU0")
	)
	(segment
		(start 172.967142 -60.685934)
		(end 172.967142 -52.485544)
		(width 0.089408)
		(layer "In4.Cu")
		(net "PWRGD_PVTT_CPU0")
	)
	(segment
		(start 345.378786 -71.143368)
		(end 340.14537 -71.143368)
		(width 0.089408)
		(layer "In4.Cu")
		(net "PWRGD_PVTT_CPU0")
	)
	(segment
		(start 174.028608 -63.108332)
		(end 174.028608 -61.7474)
		(width 0.089408)
		(layer "In4.Cu")
		(net "PWRGD_PVTT_CPU0")
	)
	(segment
		(start 171.30268 -49.289208)
		(end 172.896784 -47.695104)
		(width 0.089408)
		(layer "In4.Cu")
		(net "PWRGD_PVTT_CPU0")
	)
	(segment
		(start 281.348434 -157.084014)
		(end 281.096974 -156.832554)
		(width 0.089408)
		(layer "In4.Cu")
		(net "PWRGD_PVTT_CPU0")
	)
	(segment
		(start 325.957946 -92.223336)
		(end 325.957946 -115.607084)
		(width 0.089408)
		(layer "In4.Cu")
		(net "PWRGD_PVTT_CPU0")
	)
	(segment
		(start 163.850574 -71.296784)
		(end 163.22548 -70.67169)
		(width 0.089408)
		(layer "In4.Cu")
		(net "PWRGD_PVTT_CPU0")
	)
	(segment
		(start 352.546412 -70.553072)
		(end 352.35134 -70.358)
		(width 0.089408)
		(layer "In4.Cu")
		(net "PWRGD_PVTT_CPU0")
	)
	(segment
		(start 364.089696 -69.924168)
		(end 362.809028 -71.204836)
		(width 0.089408)
		(layer "In4.Cu")
		(net "PWRGD_PVTT_CPU0")
	)
	(segment
		(start 264.769092 -156.832554)
		(end 264.687558 -156.914088)
		(width 0.089408)
		(layer "In4.Cu")
		(net "PWRGD_PVTT_CPU0")
	)
	(segment
		(start 331.376528 -134.623048)
		(end 330.549504 -135.450072)
		(width 0.089408)
		(layer "In4.Cu")
		(net "PWRGD_PVTT_CPU0")
	)
	(segment
		(start 335.680304 -78.497684)
		(end 335.680304 -79.569056)
		(width 0.089408)
		(layer "In4.Cu")
		(net "PWRGD_PVTT_CPU0")
	)
	(segment
		(start 166.811452 -142.279116)
		(end 161.180272 -142.279116)
		(width 0.089408)
		(layer "In4.Cu")
		(net "PWRGD_PVTT_CPU0")
	)
	(segment
		(start 168.527476 -128.421892)
		(end 169.21988 -129.114296)
		(width 0.089408)
		(layer "In4.Cu")
		(net "PWRGD_PVTT_CPU0")
	)
	(segment
		(start 165.9128 -65.8368)
		(end 166.154608 -66.078608)
		(width 0.089408)
		(layer "In4.Cu")
		(net "PWRGD_PVTT_CPU0")
	)
	(segment
		(start 368.626644 -67.012312)
		(end 368.459004 -67.179952)
		(width 0.089408)
		(layer "In4.Cu")
		(net "PWRGD_PVTT_CPU0")
	)
	(segment
		(start 339.40369 -71.885048)
		(end 338.976208 -71.885048)
		(width 0.089408)
		(layer "In4.Cu")
		(net "PWRGD_PVTT_CPU0")
	)
	(segment
		(start 336.353658 -77.82433)
		(end 335.680304 -78.497684)
		(width 0.089408)
		(layer "In4.Cu")
		(net "PWRGD_PVTT_CPU0")
	)
	(segment
		(start 353.911408 -70.553072)
		(end 352.546412 -70.553072)
		(width 0.089408)
		(layer "In4.Cu")
		(net "PWRGD_PVTT_CPU0")
	)
	(segment
		(start 335.680304 -79.569056)
		(end 332.525624 -82.723736)
		(width 0.089408)
		(layer "In4.Cu")
		(net "PWRGD_PVTT_CPU0")
	)
	(segment
		(start 186.9948 -154.897582)
		(end 186.9948 -147.84578)
		(width 0.089408)
		(layer "In4.Cu")
		(net "PWRGD_PVTT_CPU0")
	)
	(segment
		(start 321.959224 -157.084014)
		(end 281.348434 -157.084014)
		(width 0.089408)
		(layer "In4.Cu")
		(net "PWRGD_PVTT_CPU0")
	)
	(segment
		(start 327.898506 -123.707906)
		(end 327.898506 -126.182374)
		(width 0.089408)
		(layer "In4.Cu")
		(net "PWRGD_PVTT_CPU0")
	)
	(segment
		(start 172.967142 -52.485544)
		(end 171.30268 -50.821082)
		(width 0.089408)
		(layer "In4.Cu")
		(net "PWRGD_PVTT_CPU0")
	)
	(segment
		(start 176.473104 -145.107914)
		(end 172.318172 -145.107914)
		(width 0.089408)
		(layer "In4.Cu")
		(net "PWRGD_PVTT_CPU0")
	)
	(segment
		(start 173.482 -78.7146)
		(end 173.355 -78.5876)
		(width 0.089408)
		(layer "In4.Cu")
		(net "PWRGD_PVTT_CPU0")
	)
	(segment
		(start 177.41011 -146.04492)
		(end 176.473104 -145.107914)
		(width 0.089408)
		(layer "In4.Cu")
		(net "PWRGD_PVTT_CPU0")
	)
	(segment
		(start 326.516492 -138.010646)
		(end 324.557136 -139.970002)
		(width 0.089408)
		(layer "In4.Cu")
		(net "PWRGD_PVTT_CPU0")
	)
	(segment
		(start 171.1198 -8.5852)
		(end 179.1208 -8.5852)
		(width 0.089408)
		(layer "In4.Cu")
		(net "PWRGD_PVTT_CPU0")
	)
	(segment
		(start 159.7406 -67.0814)
		(end 160.9852 -65.8368)
		(width 0.089408)
		(layer "In4.Cu")
		(net "PWRGD_PVTT_CPU0")
	)
	(segment
		(start 336.353658 -74.507598)
		(end 336.353658 -77.82433)
		(width 0.089408)
		(layer "In4.Cu")
		(net "PWRGD_PVTT_CPU0")
	)
	(segment
		(start 354.489258 -69.975476)
		(end 354.488242 -69.976492)
		(width 0.089408)
		(layer "In4.Cu")
		(net "PWRGD_PVTT_CPU0")
	)
	(segment
		(start 375.56694 -64.74206)
		(end 373.110506 -64.74206)
		(width 0.089408)
		(layer "In4.Cu")
		(net "PWRGD_PVTT_CPU0")
	)
	(segment
		(start 172.318172 -145.107914)
		(end 171.958 -144.747742)
		(width 0.089408)
		(layer "In4.Cu")
		(net "PWRGD_PVTT_CPU0")
	)
	(segment
		(start 331.376528 -129.660396)
		(end 331.376528 -134.623048)
		(width 0.089408)
		(layer "In4.Cu")
		(net "PWRGD_PVTT_CPU0")
	)
	(segment
		(start 185.051446 -146.04492)
		(end 177.41011 -146.04492)
		(width 0.089408)
		(layer "In4.Cu")
		(net "PWRGD_PVTT_CPU0")
	)
	(segment
		(start 168.236392 -66.078608)
		(end 170.491912 -63.823088)
		(width 0.089408)
		(layer "In4.Cu")
		(net "PWRGD_PVTT_CPU0")
	)
	(segment
		(start 166.7002 -76.4286)
		(end 166.7002 -74.861166)
		(width 0.089408)
		(layer "In4.Cu")
		(net "PWRGD_PVTT_CPU0")
	)
	(segment
		(start 176.9364 -92.42298)
		(end 177.71618 -91.6432)
		(width 0.089408)
		(layer "In4.Cu")
		(net "PWRGD_PVTT_CPU0")
	)
	(segment
		(start 174.971456 -34.095944)
		(end 174.971456 -28.807156)
		(width 0.089408)
		(layer "In4.Cu")
		(net "PWRGD_PVTT_CPU0")
	)
	(segment
		(start 168.8592 -78.5876)
		(end 166.7002 -76.4286)
		(width 0.089408)
		(layer "In4.Cu")
		(net "PWRGD_PVTT_CPU0")
	)
	(segment
		(start 176.9364 -93.726)
		(end 176.9364 -92.42298)
		(width 0.089408)
		(layer "In4.Cu")
		(net "PWRGD_PVTT_CPU0")
	)
	(segment
		(start 185.313066 -145.7833)
		(end 185.051446 -146.04492)
		(width 0.089408)
		(layer "In4.Cu")
		(net "PWRGD_PVTT_CPU0")
	)
	(segment
		(start 176.53 -124.03836)
		(end 176.53 -94.1324)
		(width 0.089408)
		(layer "In4.Cu")
		(net "PWRGD_PVTT_CPU0")
	)
	(segment
		(start 159.754824 -129.742692)
		(end 161.075624 -128.421892)
		(width 0.089408)
		(layer "In4.Cu")
		(net "PWRGD_PVTT_CPU0")
	)
	(segment
		(start 174.971456 -28.807156)
		(end 170.41241 -24.24811)
		(width 0.089408)
		(layer "In4.Cu")
		(net "PWRGD_PVTT_CPU0")
	)
	(segment
		(start 354.488242 -69.976492)
		(end 354.487988 -69.976492)
		(width 0.089408)
		(layer "In4.Cu")
		(net "PWRGD_PVTT_CPU0")
	)
	(segment
		(start 161.1376 -11.2268)
		(end 164.084 -11.2268)
		(width 0.089408)
		(layer "In4.Cu")
		(net "PWRGD_PVTT_CPU0")
	)
	(segment
		(start 166.154608 -66.078608)
		(end 168.236392 -66.078608)
		(width 0.089408)
		(layer "In4.Cu")
		(net "PWRGD_PVTT_CPU0")
	)
	(segment
		(start 159.980122 -70.284594)
		(end 159.7406 -70.045072)
		(width 0.089408)
		(layer "In4.Cu")
		(net "PWRGD_PVTT_CPU0")
	)
	(segment
		(start 324.557136 -154.486102)
		(end 321.959224 -157.084014)
		(width 0.089408)
		(layer "In4.Cu")
		(net "PWRGD_PVTT_CPU0")
	)
	(segment
		(start 172.896784 -36.170616)
		(end 174.971456 -34.095944)
		(width 0.089408)
		(layer "In4.Cu")
		(net "PWRGD_PVTT_CPU0")
	)
	(segment
		(start 375.666 -64.643)
		(end 375.56694 -64.74206)
		(width 0.089408)
		(layer "In4.Cu")
		(net "PWRGD_PVTT_CPU0")
	)
	(segment
		(start 180.794914 -6.911086)
		(end 180.794914 -6.023864)
		(width 0.089408)
		(layer "In4.Cu")
		(net "PWRGD_PVTT_CPU0")
	)
	(segment
		(start 330.549504 -136.417558)
		(end 328.956416 -138.010646)
		(width 0.089408)
		(layer "In4.Cu")
		(net "PWRGD_PVTT_CPU0")
	)
	(segment
		(start 170.491912 -63.823088)
		(end 173.313852 -63.823088)
		(width 0.089408)
		(layer "In4.Cu")
		(net "PWRGD_PVTT_CPU0")
	)
	(segment
		(start 330.549504 -135.450072)
		(end 330.549504 -136.417558)
		(width 0.089408)
		(layer "In4.Cu")
		(net "PWRGD_PVTT_CPU0")
	)
	(segment
		(start 373.110506 -64.74206)
		(end 372.345966 -65.5066)
		(width 0.089408)
		(layer "In4.Cu")
		(net "PWRGD_PVTT_CPU0")
	)
	(segment
		(start 171.958 -144.747742)
		(end 169.280078 -144.747742)
		(width 0.089408)
		(layer "In4.Cu")
		(net "PWRGD_PVTT_CPU0")
	)
	(segment
		(start 332.525624 -82.723736)
		(end 332.525624 -85.655658)
		(width 0.089408)
		(layer "In4.Cu")
		(net "PWRGD_PVTT_CPU0")
	)
	(segment
		(start 171.30268 -50.821082)
		(end 171.30268 -49.289208)
		(width 0.089408)
		(layer "In4.Cu")
		(net "PWRGD_PVTT_CPU0")
	)
	(segment
		(start 186.9948 -147.84578)
		(end 186.0804 -146.93138)
		(width 0.089408)
		(layer "In4.Cu")
		(net "PWRGD_PVTT_CPU0")
	)
	(segment
		(start 186.0804 -146.93138)
		(end 186.0804 -145.7833)
		(width 0.089408)
		(layer "In4.Cu")
		(net "PWRGD_PVTT_CPU0")
	)
	(segment
		(start 160.303718 -70.611238)
		(end 159.980122 -70.287642)
		(width 0.089408)
		(layer "In4.Cu")
		(net "PWRGD_PVTT_CPU0")
	)
	(segment
		(start 346.164154 -70.358)
		(end 345.378786 -71.143368)
		(width 0.089408)
		(layer "In4.Cu")
		(net "PWRGD_PVTT_CPU0")
	)
	(segment
		(start 163.85032 -71.575676)
		(end 163.850574 -71.575422)
		(width 0.089408)
		(layer "In4.Cu")
		(net "PWRGD_PVTT_CPU0")
	)
	(segment
		(start 189.011306 -156.914088)
		(end 186.9948 -154.897582)
		(width 0.089408)
		(layer "In4.Cu")
		(net "PWRGD_PVTT_CPU0")
	)
	(segment
		(start 169.21988 -129.114296)
		(end 175.74133 -129.114296)
		(width 0.089408)
		(layer "In4.Cu")
		(net "PWRGD_PVTT_CPU0")
	)
	(segment
		(start 163.85032 -72.011286)
		(end 163.85032 -71.575676)
		(width 0.089408)
		(layer "In4.Cu")
		(net "PWRGD_PVTT_CPU0")
	)
	(segment
		(start 159.980122 -70.287642)
		(end 159.980122 -70.284594)
		(width 0.089408)
		(layer "In4.Cu")
		(net "PWRGD_PVTT_CPU0")
	)
	(segment
		(start 176.53 -94.1324)
		(end 176.9364 -93.726)
		(width 0.089408)
		(layer "In4.Cu")
		(net "PWRGD_PVTT_CPU0")
	)
	(segment
		(start 375.790206 -68.268596)
		(end 376.318018 -68.268596)
		(width 0.089408)
		(layer "In11.Cu")
		(net "PWRGD_PVTT_CPU0")
	)
	(segment
		(start 376.318018 -68.268596)
		(end 376.744738 -68.695316)
		(width 0.089408)
		(layer "In11.Cu")
		(net "PWRGD_PVTT_CPU0")
	)
	(segment
		(start 375.666 -64.643)
		(end 375.666 -67.646042)
		(width 0.089408)
		(layer "In11.Cu")
		(net "PWRGD_PVTT_CPU0")
	)
	(segment
		(start 375.571512 -68.049902)
		(end 375.790206 -68.268596)
		(width 0.089408)
		(layer "In11.Cu")
		(net "PWRGD_PVTT_CPU0")
	)
	(segment
		(start 375.666 -67.646042)
		(end 375.571512 -67.74053)
		(width 0.089408)
		(layer "In11.Cu")
		(net "PWRGD_PVTT_CPU0")
	)
	(segment
		(start 375.571512 -67.74053)
		(end 375.571512 -68.049902)
		(width 0.089408)
		(layer "In11.Cu")
		(net "PWRGD_PVTT_CPU0")
	)
	(segment
		(start 171.6532 -7.8232)
		(end 171.6532 -8.6868)
		(width 0.10795)
		(layer "F.Cu")
		(net "FM_PVPP_CPU1_EN")
	)
	(segment
		(start 172.2755 -131.5085)
		(end 172.0342 -131.2672)
		(width 0.10795)
		(layer "F.Cu")
		(net "FM_PVPP_CPU1_EN")
	)
	(segment
		(start 170.237658 -8.706358)
		(end 170.282616 -8.6614)
		(width 0.10795)
		(layer "F.Cu")
		(net "FM_PVPP_CPU1_EN")
	)
	(segment
		(start 171.261786 -127.802132)
		(end 170.423332 -127.802132)
		(width 0.10795)
		(layer "F.Cu")
		(net "FM_PVPP_CPU1_EN")
	)
	(segment
		(start 170.942 -8.6868)
		(end 171.6532 -8.6868)
		(width 0.10795)
		(layer "F.Cu")
		(net "FM_PVPP_CPU1_EN")
	)
	(segment
		(start 164.7952 -126.6444)
		(end 164.592 -126.4412)
		(width 0.10795)
		(layer "F.Cu")
		(net "FM_PVPP_CPU1_EN")
	)
	(segment
		(start 169.2656 -126.6444)
		(end 164.7952 -126.6444)
		(width 0.10795)
		(layer "F.Cu")
		(net "FM_PVPP_CPU1_EN")
	)
	(segment
		(start 366.345216 -79.094838)
		(end 366.745012 -78.695042)
		(width 0.1016)
		(layer "F.Cu")
		(net "FM_PVPP_CPU1_EN")
	)
	(segment
		(start 172.466 -131.5085)
		(end 172.2755 -131.5085)
		(width 0.10795)
		(layer "F.Cu")
		(net "FM_PVPP_CPU1_EN")
	)
	(segment
		(start 172.466 -131.5085)
		(end 172.466 -132.3975)
		(width 0.10795)
		(layer "F.Cu")
		(net "FM_PVPP_CPU1_EN")
	)
	(segment
		(start 172.0342 -131.2672)
		(end 172.0342 -128.574546)
		(width 0.10795)
		(layer "F.Cu")
		(net "FM_PVPP_CPU1_EN")
	)
	(segment
		(start 164.592 -126.4412)
		(end 163.2204 -126.4412)
		(width 0.10795)
		(layer "F.Cu")
		(net "FM_PVPP_CPU1_EN")
	)
	(segment
		(start 170.423332 -127.802132)
		(end 169.2656 -126.6444)
		(width 0.10795)
		(layer "F.Cu")
		(net "FM_PVPP_CPU1_EN")
	)
	(segment
		(start 172.466 -132.3975)
		(end 172.3771 -132.4864)
		(width 0.10795)
		(layer "F.Cu")
		(net "FM_PVPP_CPU1_EN")
	)
	(segment
		(start 170.9166 -8.6614)
		(end 170.942 -8.6868)
		(width 0.10795)
		(layer "F.Cu")
		(net "FM_PVPP_CPU1_EN")
	)
	(segment
		(start 163.2204 -126.4412)
		(end 162.356038 -125.576838)
		(width 0.10795)
		(layer "F.Cu")
		(net "FM_PVPP_CPU1_EN")
	)
	(segment
		(start 172.0342 -128.574546)
		(end 171.261786 -127.802132)
		(width 0.10795)
		(layer "F.Cu")
		(net "FM_PVPP_CPU1_EN")
	)
	(segment
		(start 162.356038 -125.576838)
		(end 162.356038 -124.553218)
		(width 0.10795)
		(layer "F.Cu")
		(net "FM_PVPP_CPU1_EN")
	)
	(segment
		(start 170.282616 -8.6614)
		(end 170.9166 -8.6614)
		(width 0.10795)
		(layer "F.Cu")
		(net "FM_PVPP_CPU1_EN")
	)
	(via
		(at 366.345216 -79.094838)
		(size 0.4572)
		(drill 0.2032)
		(layers "F.Cu" "B.Cu")
		(net "FM_PVPP_CPU1_EN")
	)
	(via
		(at 330.64958 -25.7302)
		(size 0.508)
		(drill 0.254)
		(layers "F.Cu" "B.Cu")
		(net "FM_PVPP_CPU1_EN")
	)
	(via
		(at 163.2204 -126.4412)
		(size 0.762)
		(drill 0.381)
		(layers "F.Cu" "B.Cu")
		(net "FM_PVPP_CPU1_EN")
	)
	(via
		(at 170.237658 -8.706358)
		(size 0.508)
		(drill 0.254)
		(layers "F.Cu" "B.Cu")
		(net "FM_PVPP_CPU1_EN")
	)
	(via
		(at 378.78131 -57.528968)
		(size 0.508)
		(drill 0.254)
		(layers "F.Cu" "B.Cu")
		(net "FM_PVPP_CPU1_EN")
	)
	(via
		(at 162.356038 -124.553218)
		(size 0.508)
		(drill 0.254)
		(layers "F.Cu" "B.Cu")
		(net "FM_PVPP_CPU1_EN")
	)
	(segment
		(start 159.2326 -123.7742)
		(end 157.669738 -122.211338)
		(width 0.089408)
		(layer "In2.Cu")
		(net "FM_PVPP_CPU1_EN")
	)
	(segment
		(start 165.9128 -19.6596)
		(end 164.973 -19.6596)
		(width 0.089408)
		(layer "In2.Cu")
		(net "FM_PVPP_CPU1_EN")
	)
	(segment
		(start 156.58338 -67.6021)
		(end 154.26436 -65.28308)
		(width 0.089408)
		(layer "In2.Cu")
		(net "FM_PVPP_CPU1_EN")
	)
	(segment
		(start 161.90849 -68.44665)
		(end 161.06394 -67.6021)
		(width 0.089408)
		(layer "In2.Cu")
		(net "FM_PVPP_CPU1_EN")
	)
	(segment
		(start 161.06394 -67.6021)
		(end 156.58338 -67.6021)
		(width 0.089408)
		(layer "In2.Cu")
		(net "FM_PVPP_CPU1_EN")
	)
	(segment
		(start 165.8493 -45.17644)
		(end 168.400476 -45.17644)
		(width 0.089408)
		(layer "In2.Cu")
		(net "FM_PVPP_CPU1_EN")
	)
	(segment
		(start 168.947084 -21.4249)
		(end 167.6781 -21.4249)
		(width 0.089408)
		(layer "In2.Cu")
		(net "FM_PVPP_CPU1_EN")
	)
	(segment
		(start 159.866584 -58.30824)
		(end 159.866584 -51.159156)
		(width 0.089408)
		(layer "In2.Cu")
		(net "FM_PVPP_CPU1_EN")
	)
	(segment
		(start 169.176954 -21.65477)
		(end 168.947084 -21.4249)
		(width 0.089408)
		(layer "In2.Cu")
		(net "FM_PVPP_CPU1_EN")
	)
	(segment
		(start 164.40277 -19.08937)
		(end 164.40277 -7.686802)
		(width 0.089408)
		(layer "In2.Cu")
		(net "FM_PVPP_CPU1_EN")
	)
	(segment
		(start 168.400476 -45.17644)
		(end 169.483532 -44.093384)
		(width 0.089408)
		(layer "In2.Cu")
		(net "FM_PVPP_CPU1_EN")
	)
	(segment
		(start 158.115 -73.991978)
		(end 161.90849 -70.198488)
		(width 0.089408)
		(layer "In2.Cu")
		(net "FM_PVPP_CPU1_EN")
	)
	(segment
		(start 158.062676 -60.110624)
		(end 158.0642 -60.110624)
		(width 0.089408)
		(layer "In2.Cu")
		(net "FM_PVPP_CPU1_EN")
	)
	(segment
		(start 158.115 -99.568)
		(end 158.115 -73.991978)
		(width 0.089408)
		(layer "In2.Cu")
		(net "FM_PVPP_CPU1_EN")
	)
	(segment
		(start 159.866584 -51.159156)
		(end 165.8493 -45.17644)
		(width 0.089408)
		(layer "In2.Cu")
		(net "FM_PVPP_CPU1_EN")
	)
	(segment
		(start 154.26436 -65.28308)
		(end 154.26436 -61.464444)
		(width 0.089408)
		(layer "In2.Cu")
		(net "FM_PVPP_CPU1_EN")
	)
	(segment
		(start 161.57702 -123.7742)
		(end 159.2326 -123.7742)
		(width 0.089408)
		(layer "In2.Cu")
		(net "FM_PVPP_CPU1_EN")
	)
	(segment
		(start 157.669738 -122.211338)
		(end 157.669738 -121.86666)
		(width 0.089408)
		(layer "In2.Cu")
		(net "FM_PVPP_CPU1_EN")
	)
	(segment
		(start 167.679878 -7.46252)
		(end 168.923716 -8.706358)
		(width 0.089408)
		(layer "In2.Cu")
		(net "FM_PVPP_CPU1_EN")
	)
	(segment
		(start 168.799002 -30.720284)
		(end 168.799002 -27.403044)
		(width 0.089408)
		(layer "In2.Cu")
		(net "FM_PVPP_CPU1_EN")
	)
	(segment
		(start 161.90849 -70.198488)
		(end 161.90849 -68.44665)
		(width 0.089408)
		(layer "In2.Cu")
		(net "FM_PVPP_CPU1_EN")
	)
	(segment
		(start 155.6258 -119.822722)
		(end 155.6258 -113.0808)
		(width 0.089408)
		(layer "In2.Cu")
		(net "FM_PVPP_CPU1_EN")
	)
	(segment
		(start 168.923716 -8.706358)
		(end 170.237658 -8.706358)
		(width 0.089408)
		(layer "In2.Cu")
		(net "FM_PVPP_CPU1_EN")
	)
	(segment
		(start 157.669738 -121.86666)
		(end 155.6258 -119.822722)
		(width 0.089408)
		(layer "In2.Cu")
		(net "FM_PVPP_CPU1_EN")
	)
	(segment
		(start 158.00324 -60.17006)
		(end 158.062676 -60.110624)
		(width 0.089408)
		(layer "In2.Cu")
		(net "FM_PVPP_CPU1_EN")
	)
	(segment
		(start 169.176954 -27.025092)
		(end 169.176954 -21.65477)
		(width 0.089408)
		(layer "In2.Cu")
		(net "FM_PVPP_CPU1_EN")
	)
	(segment
		(start 155.558744 -60.17006)
		(end 158.00324 -60.17006)
		(width 0.089408)
		(layer "In2.Cu")
		(net "FM_PVPP_CPU1_EN")
	)
	(segment
		(start 164.973 -19.6596)
		(end 164.40277 -19.08937)
		(width 0.089408)
		(layer "In2.Cu")
		(net "FM_PVPP_CPU1_EN")
	)
	(segment
		(start 169.483532 -31.404814)
		(end 168.799002 -30.720284)
		(width 0.089408)
		(layer "In2.Cu")
		(net "FM_PVPP_CPU1_EN")
	)
	(segment
		(start 164.40277 -7.686802)
		(end 164.627052 -7.46252)
		(width 0.089408)
		(layer "In2.Cu")
		(net "FM_PVPP_CPU1_EN")
	)
	(segment
		(start 167.6781 -21.4249)
		(end 165.9128 -19.6596)
		(width 0.089408)
		(layer "In2.Cu")
		(net "FM_PVPP_CPU1_EN")
	)
	(segment
		(start 158.0642 -60.110624)
		(end 159.866584 -58.30824)
		(width 0.089408)
		(layer "In2.Cu")
		(net "FM_PVPP_CPU1_EN")
	)
	(segment
		(start 155.6258 -113.0808)
		(end 160.5788 -108.1278)
		(width 0.089408)
		(layer "In2.Cu")
		(net "FM_PVPP_CPU1_EN")
	)
	(segment
		(start 154.26436 -61.464444)
		(end 155.558744 -60.17006)
		(width 0.089408)
		(layer "In2.Cu")
		(net "FM_PVPP_CPU1_EN")
	)
	(segment
		(start 162.356038 -124.553218)
		(end 161.57702 -123.7742)
		(width 0.089408)
		(layer "In2.Cu")
		(net "FM_PVPP_CPU1_EN")
	)
	(segment
		(start 160.5788 -102.0318)
		(end 158.115 -99.568)
		(width 0.089408)
		(layer "In2.Cu")
		(net "FM_PVPP_CPU1_EN")
	)
	(segment
		(start 164.627052 -7.46252)
		(end 167.679878 -7.46252)
		(width 0.089408)
		(layer "In2.Cu")
		(net "FM_PVPP_CPU1_EN")
	)
	(segment
		(start 160.5788 -108.1278)
		(end 160.5788 -102.0318)
		(width 0.089408)
		(layer "In2.Cu")
		(net "FM_PVPP_CPU1_EN")
	)
	(segment
		(start 169.483532 -44.093384)
		(end 169.483532 -31.404814)
		(width 0.089408)
		(layer "In2.Cu")
		(net "FM_PVPP_CPU1_EN")
	)
	(segment
		(start 168.799002 -27.403044)
		(end 169.176954 -27.025092)
		(width 0.089408)
		(layer "In2.Cu")
		(net "FM_PVPP_CPU1_EN")
	)
	(segment
		(start 183.832246 -5.3848)
		(end 184.795922 -4.421124)
		(width 0.089408)
		(layer "In4.Cu")
		(net "FM_PVPP_CPU1_EN")
	)
	(segment
		(start 179.552346 -5.3848)
		(end 183.832246 -5.3848)
		(width 0.089408)
		(layer "In4.Cu")
		(net "FM_PVPP_CPU1_EN")
	)
	(segment
		(start 193.9417 -0.583946)
		(end 194.04838 -0.477266)
		(width 0.089408)
		(layer "In4.Cu")
		(net "FM_PVPP_CPU1_EN")
	)
	(segment
		(start 256.3368 0.015748)
		(end 256.3368 0.9144)
		(width 0.089408)
		(layer "In4.Cu")
		(net "FM_PVPP_CPU1_EN")
	)
	(segment
		(start 170.739816 -8.2042)
		(end 174.899066 -8.2042)
		(width 0.089408)
		(layer "In4.Cu")
		(net "FM_PVPP_CPU1_EN")
	)
	(segment
		(start 170.237658 -8.706358)
		(end 170.739816 -8.2042)
		(width 0.089408)
		(layer "In4.Cu")
		(net "FM_PVPP_CPU1_EN")
	)
	(segment
		(start 264.428224 -0.356616)
		(end 322.010278 -0.356616)
		(width 0.089408)
		(layer "In4.Cu")
		(net "FM_PVPP_CPU1_EN")
	)
	(segment
		(start 188.011054 -0.826008)
		(end 190.106046 -0.826008)
		(width 0.089408)
		(layer "In4.Cu")
		(net "FM_PVPP_CPU1_EN")
	)
	(segment
		(start 323.414898 -22.755098)
		(end 326.39 -25.7302)
		(width 0.089408)
		(layer "In4.Cu")
		(net "FM_PVPP_CPU1_EN")
	)
	(segment
		(start 259.173726 0.896874)
		(end 261.326376 0.896874)
		(width 0.089408)
		(layer "In4.Cu")
		(net "FM_PVPP_CPU1_EN")
	)
	(segment
		(start 256.5146 1.0922)
		(end 258.9784 1.0922)
		(width 0.089408)
		(layer "In4.Cu")
		(net "FM_PVPP_CPU1_EN")
	)
	(segment
		(start 258.9784 1.0922)
		(end 259.173726 0.896874)
		(width 0.089408)
		(layer "In4.Cu")
		(net "FM_PVPP_CPU1_EN")
	)
	(segment
		(start 178.587146 -6.35)
		(end 179.552346 -5.3848)
		(width 0.089408)
		(layer "In4.Cu")
		(net "FM_PVPP_CPU1_EN")
	)
	(segment
		(start 185.103008 -4.107434)
		(end 185.103008 -3.734054)
		(width 0.089408)
		(layer "In4.Cu")
		(net "FM_PVPP_CPU1_EN")
	)
	(segment
		(start 197.714616 -0.492252)
		(end 255.8288 -0.492252)
		(width 0.089408)
		(layer "In4.Cu")
		(net "FM_PVPP_CPU1_EN")
	)
	(segment
		(start 322.010278 -0.356616)
		(end 323.414898 -1.761236)
		(width 0.089408)
		(layer "In4.Cu")
		(net "FM_PVPP_CPU1_EN")
	)
	(segment
		(start 261.326376 0.896874)
		(end 262.809482 -0.586232)
		(width 0.089408)
		(layer "In4.Cu")
		(net "FM_PVPP_CPU1_EN")
	)
	(segment
		(start 174.899066 -8.2042)
		(end 176.753266 -6.35)
		(width 0.089408)
		(layer "In4.Cu")
		(net "FM_PVPP_CPU1_EN")
	)
	(segment
		(start 326.39 -25.7302)
		(end 330.64958 -25.7302)
		(width 0.089408)
		(layer "In4.Cu")
		(net "FM_PVPP_CPU1_EN")
	)
	(segment
		(start 184.795922 -4.41452)
		(end 185.103008 -4.107434)
		(width 0.089408)
		(layer "In4.Cu")
		(net "FM_PVPP_CPU1_EN")
	)
	(segment
		(start 176.753266 -6.35)
		(end 178.587146 -6.35)
		(width 0.089408)
		(layer "In4.Cu")
		(net "FM_PVPP_CPU1_EN")
	)
	(segment
		(start 264.198608 -0.586232)
		(end 264.428224 -0.356616)
		(width 0.089408)
		(layer "In4.Cu")
		(net "FM_PVPP_CPU1_EN")
	)
	(segment
		(start 184.795922 -4.421124)
		(end 184.795922 -4.41452)
		(width 0.089408)
		(layer "In4.Cu")
		(net "FM_PVPP_CPU1_EN")
	)
	(segment
		(start 194.04838 -0.477266)
		(end 197.69963 -0.477266)
		(width 0.089408)
		(layer "In4.Cu")
		(net "FM_PVPP_CPU1_EN")
	)
	(segment
		(start 255.8288 -0.492252)
		(end 256.3368 0.015748)
		(width 0.089408)
		(layer "In4.Cu")
		(net "FM_PVPP_CPU1_EN")
	)
	(segment
		(start 262.809482 -0.586232)
		(end 264.198608 -0.586232)
		(width 0.089408)
		(layer "In4.Cu")
		(net "FM_PVPP_CPU1_EN")
	)
	(segment
		(start 185.103008 -3.734054)
		(end 188.011054 -0.826008)
		(width 0.089408)
		(layer "In4.Cu")
		(net "FM_PVPP_CPU1_EN")
	)
	(segment
		(start 190.106046 -0.826008)
		(end 190.348108 -0.583946)
		(width 0.089408)
		(layer "In4.Cu")
		(net "FM_PVPP_CPU1_EN")
	)
	(segment
		(start 197.69963 -0.477266)
		(end 197.714616 -0.492252)
		(width 0.089408)
		(layer "In4.Cu")
		(net "FM_PVPP_CPU1_EN")
	)
	(segment
		(start 323.414898 -1.761236)
		(end 323.414898 -22.755098)
		(width 0.089408)
		(layer "In4.Cu")
		(net "FM_PVPP_CPU1_EN")
	)
	(segment
		(start 190.348108 -0.583946)
		(end 193.9417 -0.583946)
		(width 0.089408)
		(layer "In4.Cu")
		(net "FM_PVPP_CPU1_EN")
	)
	(segment
		(start 256.3368 0.9144)
		(end 256.5146 1.0922)
		(width 0.089408)
		(layer "In4.Cu")
		(net "FM_PVPP_CPU1_EN")
	)
	(segment
		(start 366.721136 -66.68643)
		(end 365.788702 -67.618864)
		(width 0.089408)
		(layer "In9.Cu")
		(net "FM_PVPP_CPU1_EN")
	)
	(segment
		(start 374.268746 -59.817)
		(end 372.015004 -62.070742)
		(width 0.089408)
		(layer "In9.Cu")
		(net "FM_PVPP_CPU1_EN")
	)
	(segment
		(start 370.849398 -62.738)
		(end 370.074444 -63.512954)
		(width 0.089408)
		(layer "In9.Cu")
		(net "FM_PVPP_CPU1_EN")
	)
	(segment
		(start 370.074444 -63.512954)
		(end 367.90122 -63.512954)
		(width 0.089408)
		(layer "In9.Cu")
		(net "FM_PVPP_CPU1_EN")
	)
	(segment
		(start 366.74552 -78.694534)
		(end 366.345216 -79.094838)
		(width 0.089408)
		(layer "In9.Cu")
		(net "FM_PVPP_CPU1_EN")
	)
	(segment
		(start 366.543844 -73.910444)
		(end 366.74552 -74.11212)
		(width 0.089408)
		(layer "In9.Cu")
		(net "FM_PVPP_CPU1_EN")
	)
	(segment
		(start 365.788702 -73.558146)
		(end 366.141 -73.910444)
		(width 0.089408)
		(layer "In9.Cu")
		(net "FM_PVPP_CPU1_EN")
	)
	(segment
		(start 367.378742 -63.506096)
		(end 366.721136 -64.163702)
		(width 0.089408)
		(layer "In9.Cu")
		(net "FM_PVPP_CPU1_EN")
	)
	(segment
		(start 367.90122 -63.512954)
		(end 367.894362 -63.506096)
		(width 0.089408)
		(layer "In9.Cu")
		(net "FM_PVPP_CPU1_EN")
	)
	(segment
		(start 366.721136 -64.163702)
		(end 366.721136 -66.68643)
		(width 0.089408)
		(layer "In9.Cu")
		(net "FM_PVPP_CPU1_EN")
	)
	(segment
		(start 365.788702 -67.618864)
		(end 365.788702 -67.650106)
		(width 0.089408)
		(layer "In9.Cu")
		(net "FM_PVPP_CPU1_EN")
	)
	(segment
		(start 365.780574 -68.401184)
		(end 365.788702 -68.409312)
		(width 0.089408)
		(layer "In9.Cu")
		(net "FM_PVPP_CPU1_EN")
	)
	(segment
		(start 365.788702 -67.650106)
		(end 365.780574 -67.658234)
		(width 0.089408)
		(layer "In9.Cu")
		(net "FM_PVPP_CPU1_EN")
	)
	(segment
		(start 366.74552 -74.11212)
		(end 366.74552 -78.694534)
		(width 0.089408)
		(layer "In9.Cu")
		(net "FM_PVPP_CPU1_EN")
	)
	(segment
		(start 365.788702 -68.409312)
		(end 365.788702 -73.558146)
		(width 0.089408)
		(layer "In9.Cu")
		(net "FM_PVPP_CPU1_EN")
	)
	(segment
		(start 372.015004 -62.070742)
		(end 372.015004 -62.39764)
		(width 0.089408)
		(layer "In9.Cu")
		(net "FM_PVPP_CPU1_EN")
	)
	(segment
		(start 376.493278 -59.817)
		(end 374.268746 -59.817)
		(width 0.089408)
		(layer "In9.Cu")
		(net "FM_PVPP_CPU1_EN")
	)
	(segment
		(start 371.674644 -62.738)
		(end 370.849398 -62.738)
		(width 0.089408)
		(layer "In9.Cu")
		(net "FM_PVPP_CPU1_EN")
	)
	(segment
		(start 378.78131 -57.528968)
		(end 376.493278 -59.817)
		(width 0.089408)
		(layer "In9.Cu")
		(net "FM_PVPP_CPU1_EN")
	)
	(segment
		(start 366.141 -73.910444)
		(end 366.543844 -73.910444)
		(width 0.089408)
		(layer "In9.Cu")
		(net "FM_PVPP_CPU1_EN")
	)
	(segment
		(start 372.015004 -62.39764)
		(end 371.674644 -62.738)
		(width 0.089408)
		(layer "In9.Cu")
		(net "FM_PVPP_CPU1_EN")
	)
	(segment
		(start 367.894362 -63.506096)
		(end 367.378742 -63.506096)
		(width 0.089408)
		(layer "In9.Cu")
		(net "FM_PVPP_CPU1_EN")
	)
	(segment
		(start 365.780574 -67.658234)
		(end 365.780574 -68.401184)
		(width 0.089408)
		(layer "In9.Cu")
		(net "FM_PVPP_CPU1_EN")
	)
	(segment
		(start 331.299566 -33.339532)
		(end 331.299566 -36.069524)
		(width 0.089408)
		(layer "In11.Cu")
		(net "FM_PVPP_CPU1_EN")
	)
	(segment
		(start 332.931262 -37.31768)
		(end 332.931516 -37.317426)
		(width 0.089408)
		(layer "In11.Cu")
		(net "FM_PVPP_CPU1_EN")
	)
	(segment
		(start 330.64958 -26.54173)
		(end 329.875896 -27.315414)
		(width 0.089408)
		(layer "In11.Cu")
		(net "FM_PVPP_CPU1_EN")
	)
	(segment
		(start 372.755922 -52.787042)
		(end 374.490996 -54.522116)
		(width 0.089408)
		(layer "In11.Cu")
		(net "FM_PVPP_CPU1_EN")
	)
	(segment
		(start 332.931516 -37.317426)
		(end 333.089504 -37.317426)
		(width 0.089408)
		(layer "In11.Cu")
		(net "FM_PVPP_CPU1_EN")
	)
	(segment
		(start 376.22353 -54.538372)
		(end 378.307092 -56.621934)
		(width 0.089408)
		(layer "In11.Cu")
		(net "FM_PVPP_CPU1_EN")
	)
	(segment
		(start 366.44707 -47.211996)
		(end 367.66627 -47.211996)
		(width 0.089408)
		(layer "In11.Cu")
		(net "FM_PVPP_CPU1_EN")
	)
	(segment
		(start 367.66627 -47.211996)
		(end 372.755922 -52.301648)
		(width 0.089408)
		(layer "In11.Cu")
		(net "FM_PVPP_CPU1_EN")
	)
	(segment
		(start 353.1108 -39.8272)
		(end 355.342698 -37.595302)
		(width 0.089408)
		(layer "In11.Cu")
		(net "FM_PVPP_CPU1_EN")
	)
	(segment
		(start 329.875896 -31.915862)
		(end 331.299566 -33.339532)
		(width 0.089408)
		(layer "In11.Cu")
		(net "FM_PVPP_CPU1_EN")
	)
	(segment
		(start 331.299566 -36.069524)
		(end 332.547722 -37.31768)
		(width 0.089408)
		(layer "In11.Cu")
		(net "FM_PVPP_CPU1_EN")
	)
	(segment
		(start 372.755922 -52.301648)
		(end 372.755922 -52.787042)
		(width 0.089408)
		(layer "In11.Cu")
		(net "FM_PVPP_CPU1_EN")
	)
	(segment
		(start 330.64958 -25.7302)
		(end 330.64958 -26.54173)
		(width 0.089408)
		(layer "In11.Cu")
		(net "FM_PVPP_CPU1_EN")
	)
	(segment
		(start 332.547722 -37.31768)
		(end 332.931262 -37.31768)
		(width 0.089408)
		(layer "In11.Cu")
		(net "FM_PVPP_CPU1_EN")
	)
	(segment
		(start 336.423 -39.8272)
		(end 353.1108 -39.8272)
		(width 0.089408)
		(layer "In11.Cu")
		(net "FM_PVPP_CPU1_EN")
	)
	(segment
		(start 374.490996 -54.522116)
		(end 374.521984 -54.522116)
		(width 0.089408)
		(layer "In11.Cu")
		(net "FM_PVPP_CPU1_EN")
	)
	(segment
		(start 333.089504 -37.317426)
		(end 334.480662 -38.708584)
		(width 0.089408)
		(layer "In11.Cu")
		(net "FM_PVPP_CPU1_EN")
	)
	(segment
		(start 378.307092 -57.05475)
		(end 378.78131 -57.528968)
		(width 0.089408)
		(layer "In11.Cu")
		(net "FM_PVPP_CPU1_EN")
	)
	(segment
		(start 378.307092 -56.621934)
		(end 378.307092 -57.05475)
		(width 0.089408)
		(layer "In11.Cu")
		(net "FM_PVPP_CPU1_EN")
	)
	(segment
		(start 355.342698 -37.595302)
		(end 356.830376 -37.595302)
		(width 0.089408)
		(layer "In11.Cu")
		(net "FM_PVPP_CPU1_EN")
	)
	(segment
		(start 335.304384 -38.708584)
		(end 336.423 -39.8272)
		(width 0.089408)
		(layer "In11.Cu")
		(net "FM_PVPP_CPU1_EN")
	)
	(segment
		(start 329.875896 -27.315414)
		(end 329.875896 -31.915862)
		(width 0.089408)
		(layer "In11.Cu")
		(net "FM_PVPP_CPU1_EN")
	)
	(segment
		(start 334.480662 -38.708584)
		(end 335.304384 -38.708584)
		(width 0.089408)
		(layer "In11.Cu")
		(net "FM_PVPP_CPU1_EN")
	)
	(segment
		(start 374.521984 -54.522116)
		(end 374.53824 -54.538372)
		(width 0.089408)
		(layer "In11.Cu")
		(net "FM_PVPP_CPU1_EN")
	)
	(segment
		(start 374.53824 -54.538372)
		(end 376.22353 -54.538372)
		(width 0.089408)
		(layer "In11.Cu")
		(net "FM_PVPP_CPU1_EN")
	)
	(segment
		(start 356.830376 -37.595302)
		(end 366.44707 -47.211996)
		(width 0.089408)
		(layer "In11.Cu")
		(net "FM_PVPP_CPU1_EN")
	)
	(segment
		(start 339.1154 -128.3208)
		(end 339.1154 -128.9558)
		(width 0.10795)
		(layer "F.Cu")
		(net "FM_PVPP_CPU0_EN")
	)
	(segment
		(start 340.806278 -24.508206)
		(end 340.74735 -24.508206)
		(width 0.10795)
		(layer "F.Cu")
		(net "FM_PVPP_CPU0_EN")
	)
	(segment
		(start 336.4738 -20.853654)
		(end 335.838546 -20.2184)
		(width 0.10795)
		(layer "F.Cu")
		(net "FM_PVPP_CPU0_EN")
	)
	(segment
		(start 340.233 -23.993856)
		(end 340.233 -23.749)
		(width 0.10795)
		(layer "F.Cu")
		(net "FM_PVPP_CPU0_EN")
	)
	(segment
		(start 338.864448 -22.902926)
		(end 337.973924 -22.902926)
		(width 0.10795)
		(layer "F.Cu")
		(net "FM_PVPP_CPU0_EN")
	)
	(segment
		(start 340.233 -23.749)
		(end 339.710522 -23.749)
		(width 0.10795)
		(layer "F.Cu")
		(net "FM_PVPP_CPU0_EN")
	)
	(segment
		(start 335.838546 -20.2184)
		(end 332.3336 -20.2184)
		(width 0.10795)
		(layer "F.Cu")
		(net "FM_PVPP_CPU0_EN")
	)
	(segment
		(start 336.4738 -21.402802)
		(end 336.4738 -20.853654)
		(width 0.10795)
		(layer "F.Cu")
		(net "FM_PVPP_CPU0_EN")
	)
	(segment
		(start 367.145316 -79.094838)
		(end 367.545112 -78.695042)
		(width 0.1016)
		(layer "F.Cu")
		(net "FM_PVPP_CPU0_EN")
	)
	(segment
		(start 339.1154 -128.9558)
		(end 339.092032 -128.979168)
		(width 0.10795)
		(layer "F.Cu")
		(net "FM_PVPP_CPU0_EN")
	)
	(segment
		(start 340.233 -23.749)
		(end 341.249 -23.749)
		(width 0.10795)
		(layer "F.Cu")
		(net "FM_PVPP_CPU0_EN")
	)
	(segment
		(start 339.710522 -23.749)
		(end 338.864448 -22.902926)
		(width 0.10795)
		(layer "F.Cu")
		(net "FM_PVPP_CPU0_EN")
	)
	(segment
		(start 340.74735 -24.508206)
		(end 340.233 -23.993856)
		(width 0.10795)
		(layer "F.Cu")
		(net "FM_PVPP_CPU0_EN")
	)
	(segment
		(start 339.092032 -128.979168)
		(end 339.092032 -129.587498)
		(width 0.10795)
		(layer "F.Cu")
		(net "FM_PVPP_CPU0_EN")
	)
	(segment
		(start 337.973924 -22.902926)
		(end 336.4738 -21.402802)
		(width 0.10795)
		(layer "F.Cu")
		(net "FM_PVPP_CPU0_EN")
	)
	(via
		(at 367.145316 -79.094838)
		(size 0.4572)
		(drill 0.2032)
		(layers "F.Cu" "B.Cu")
		(net "FM_PVPP_CPU0_EN")
	)
	(via
		(at 339.1154 -128.9558)
		(size 0.508)
		(drill 0.254)
		(layers "F.Cu" "B.Cu")
		(net "FM_PVPP_CPU0_EN")
	)
	(via
		(at 366.854994 -82.388964)
		(size 0.508)
		(drill 0.254)
		(layers "F.Cu" "B.Cu")
		(net "FM_PVPP_CPU0_EN")
	)
	(via
		(at 359.664 -84.5566)
		(size 0.508)
		(drill 0.254)
		(layers "F.Cu" "B.Cu")
		(net "FM_PVPP_CPU0_EN")
	)
	(via
		(at 363.523276 -83.237578)
		(size 0.6604)
		(drill 0.3302)
		(layers "F.Cu" "B.Cu")
		(net "FM_PVPP_CPU0_EN")
	)
	(via
		(at 385.140454 -79.563976)
		(size 0.508)
		(drill 0.254)
		(layers "F.Cu" "B.Cu")
		(net "FM_PVPP_CPU0_EN")
	)
	(via
		(at 332.3336 -20.2184)
		(size 0.508)
		(drill 0.254)
		(layers "F.Cu" "B.Cu")
		(net "FM_PVPP_CPU0_EN")
	)
	(segment
		(start 359.8672 -84.3534)
		(end 359.664 -84.5566)
		(width 0.10795)
		(layer "B.Cu")
		(net "FM_PVPP_CPU0_EN")
	)
	(segment
		(start 363.523276 -83.237578)
		(end 362.407454 -84.3534)
		(width 0.10795)
		(layer "B.Cu")
		(net "FM_PVPP_CPU0_EN")
	)
	(segment
		(start 362.407454 -84.3534)
		(end 359.8672 -84.3534)
		(width 0.10795)
		(layer "B.Cu")
		(net "FM_PVPP_CPU0_EN")
	)
	(segment
		(start 366.854994 -82.388964)
		(end 364.37189 -82.388964)
		(width 0.10795)
		(layer "B.Cu")
		(net "FM_PVPP_CPU0_EN")
	)
	(segment
		(start 364.37189 -82.388964)
		(end 363.523276 -83.237578)
		(width 0.10795)
		(layer "B.Cu")
		(net "FM_PVPP_CPU0_EN")
	)
	(segment
		(start 371.29974 -80.268064)
		(end 371.309138 -80.258666)
		(width 0.089408)
		(layer "In4.Cu")
		(net "FM_PVPP_CPU0_EN")
	)
	(segment
		(start 385.140454 -80.18018)
		(end 385.140454 -79.563976)
		(width 0.089408)
		(layer "In4.Cu")
		(net "FM_PVPP_CPU0_EN")
	)
	(segment
		(start 334.939894 -110.05566)
		(end 334.905096 -110.020862)
		(width 0.089408)
		(layer "In4.Cu")
		(net "FM_PVPP_CPU0_EN")
	)
	(segment
		(start 342.57869 -117.12448)
		(end 341.770716 -117.12448)
		(width 0.089408)
		(layer "In4.Cu")
		(net "FM_PVPP_CPU0_EN")
	)
	(segment
		(start 340.0298 -121.156222)
		(end 343.02827 -118.157752)
		(width 0.089408)
		(layer "In4.Cu")
		(net "FM_PVPP_CPU0_EN")
	)
	(segment
		(start 375.478548 -81.786984)
		(end 382.551686 -81.786984)
		(width 0.089408)
		(layer "In4.Cu")
		(net "FM_PVPP_CPU0_EN")
	)
	(segment
		(start 341.30996 -116.663724)
		(end 340.277958 -116.663724)
		(width 0.089408)
		(layer "In4.Cu")
		(net "FM_PVPP_CPU0_EN")
	)
	(segment
		(start 341.770716 -117.12448)
		(end 341.30996 -116.663724)
		(width 0.089408)
		(layer "In4.Cu")
		(net "FM_PVPP_CPU0_EN")
	)
	(segment
		(start 359.59288 -84.5566)
		(end 359.664 -84.5566)
		(width 0.089408)
		(layer "In4.Cu")
		(net "FM_PVPP_CPU0_EN")
	)
	(segment
		(start 340.277958 -116.663724)
		(end 334.939894 -111.32566)
		(width 0.089408)
		(layer "In4.Cu")
		(net "FM_PVPP_CPU0_EN")
	)
	(segment
		(start 334.939894 -111.32566)
		(end 334.939894 -110.05566)
		(width 0.089408)
		(layer "In4.Cu")
		(net "FM_PVPP_CPU0_EN")
	)
	(segment
		(start 358.459532 -83.423252)
		(end 359.59288 -84.5566)
		(width 0.089408)
		(layer "In4.Cu")
		(net "FM_PVPP_CPU0_EN")
	)
	(segment
		(start 382.551686 -81.786984)
		(end 383.76733 -80.57134)
		(width 0.089408)
		(layer "In4.Cu")
		(net "FM_PVPP_CPU0_EN")
	)
	(segment
		(start 384.749294 -80.57134)
		(end 385.140454 -80.18018)
		(width 0.089408)
		(layer "In4.Cu")
		(net "FM_PVPP_CPU0_EN")
	)
	(segment
		(start 369.918488 -79.99603)
		(end 370.190522 -80.268064)
		(width 0.089408)
		(layer "In4.Cu")
		(net "FM_PVPP_CPU0_EN")
	)
	(segment
		(start 343.02827 -118.157752)
		(end 343.02827 -117.57406)
		(width 0.089408)
		(layer "In4.Cu")
		(net "FM_PVPP_CPU0_EN")
	)
	(segment
		(start 369.646708 -79.468218)
		(end 369.918488 -79.739998)
		(width 0.089408)
		(layer "In4.Cu")
		(net "FM_PVPP_CPU0_EN")
	)
	(segment
		(start 333.79029 -107.819444)
		(end 332.218538 -106.247692)
		(width 0.089408)
		(layer "In4.Cu")
		(net "FM_PVPP_CPU0_EN")
	)
	(segment
		(start 367.518696 -79.468218)
		(end 369.646708 -79.468218)
		(width 0.089408)
		(layer "In4.Cu")
		(net "FM_PVPP_CPU0_EN")
	)
	(segment
		(start 332.218538 -106.247692)
		(end 332.218538 -96.742504)
		(width 0.089408)
		(layer "In4.Cu")
		(net "FM_PVPP_CPU0_EN")
	)
	(segment
		(start 339.669628 -89.9922)
		(end 346.238576 -83.423252)
		(width 0.089408)
		(layer "In4.Cu")
		(net "FM_PVPP_CPU0_EN")
	)
	(segment
		(start 339.1154 -128.9558)
		(end 340.0298 -128.0414)
		(width 0.089408)
		(layer "In4.Cu")
		(net "FM_PVPP_CPU0_EN")
	)
	(segment
		(start 369.918488 -79.739998)
		(end 369.918488 -79.99603)
		(width 0.089408)
		(layer "In4.Cu")
		(net "FM_PVPP_CPU0_EN")
	)
	(segment
		(start 367.145316 -79.094838)
		(end 367.518696 -79.468218)
		(width 0.089408)
		(layer "In4.Cu")
		(net "FM_PVPP_CPU0_EN")
	)
	(segment
		(start 370.190522 -80.268064)
		(end 371.29974 -80.268064)
		(width 0.089408)
		(layer "In4.Cu")
		(net "FM_PVPP_CPU0_EN")
	)
	(segment
		(start 334.427322 -107.819444)
		(end 333.79029 -107.819444)
		(width 0.089408)
		(layer "In4.Cu")
		(net "FM_PVPP_CPU0_EN")
	)
	(segment
		(start 337.713066 -89.9922)
		(end 339.669628 -89.9922)
		(width 0.089408)
		(layer "In4.Cu")
		(net "FM_PVPP_CPU0_EN")
	)
	(segment
		(start 334.905096 -108.297218)
		(end 334.427322 -107.819444)
		(width 0.089408)
		(layer "In4.Cu")
		(net "FM_PVPP_CPU0_EN")
	)
	(segment
		(start 332.218538 -96.742504)
		(end 332.218284 -96.74225)
		(width 0.089408)
		(layer "In4.Cu")
		(net "FM_PVPP_CPU0_EN")
	)
	(segment
		(start 371.309138 -80.258666)
		(end 372.767098 -80.258666)
		(width 0.089408)
		(layer "In4.Cu")
		(net "FM_PVPP_CPU0_EN")
	)
	(segment
		(start 340.0298 -128.0414)
		(end 340.0298 -121.156222)
		(width 0.089408)
		(layer "In4.Cu")
		(net "FM_PVPP_CPU0_EN")
	)
	(segment
		(start 332.218284 -96.74225)
		(end 332.218284 -95.486982)
		(width 0.089408)
		(layer "In4.Cu")
		(net "FM_PVPP_CPU0_EN")
	)
	(segment
		(start 332.218284 -95.486982)
		(end 337.713066 -89.9922)
		(width 0.089408)
		(layer "In4.Cu")
		(net "FM_PVPP_CPU0_EN")
	)
	(segment
		(start 374.440196 -80.748632)
		(end 375.478548 -81.786984)
		(width 0.089408)
		(layer "In4.Cu")
		(net "FM_PVPP_CPU0_EN")
	)
	(segment
		(start 373.257064 -80.748632)
		(end 374.440196 -80.748632)
		(width 0.089408)
		(layer "In4.Cu")
		(net "FM_PVPP_CPU0_EN")
	)
	(segment
		(start 334.905096 -110.020862)
		(end 334.905096 -108.297218)
		(width 0.089408)
		(layer "In4.Cu")
		(net "FM_PVPP_CPU0_EN")
	)
	(segment
		(start 372.767098 -80.258666)
		(end 373.257064 -80.748632)
		(width 0.089408)
		(layer "In4.Cu")
		(net "FM_PVPP_CPU0_EN")
	)
	(segment
		(start 343.02827 -117.57406)
		(end 342.57869 -117.12448)
		(width 0.089408)
		(layer "In4.Cu")
		(net "FM_PVPP_CPU0_EN")
	)
	(segment
		(start 383.76733 -80.57134)
		(end 384.749294 -80.57134)
		(width 0.089408)
		(layer "In4.Cu")
		(net "FM_PVPP_CPU0_EN")
	)
	(segment
		(start 346.238576 -83.423252)
		(end 358.459532 -83.423252)
		(width 0.089408)
		(layer "In4.Cu")
		(net "FM_PVPP_CPU0_EN")
	)
	(segment
		(start 370.625878 -46.952662)
		(end 370.973096 -47.29988)
		(width 0.089408)
		(layer "In11.Cu")
		(net "FM_PVPP_CPU0_EN")
	)
	(segment
		(start 385.54787 -75.01509)
		(end 385.54787 -75.257406)
		(width 0.089408)
		(layer "In11.Cu")
		(net "FM_PVPP_CPU0_EN")
	)
	(segment
		(start 379.764036 -56.895746)
		(end 380.702312 -57.834022)
		(width 0.089408)
		(layer "In11.Cu")
		(net "FM_PVPP_CPU0_EN")
	)
	(segment
		(start 374.18391 -51.160426)
		(end 374.18391 -51.7779)
		(width 0.089408)
		(layer "In11.Cu")
		(net "FM_PVPP_CPU0_EN")
	)
	(segment
		(start 370.973096 -47.29988)
		(end 370.973096 -47.949612)
		(width 0.089408)
		(layer "In11.Cu")
		(net "FM_PVPP_CPU0_EN")
	)
	(segment
		(start 375.16689 -53.537358)
		(end 375.38914 -53.759608)
		(width 0.089408)
		(layer "In11.Cu")
		(net "FM_PVPP_CPU0_EN")
	)
	(segment
		(start 375.16689 -52.76088)
		(end 375.16689 -53.537358)
		(width 0.089408)
		(layer "In11.Cu")
		(net "FM_PVPP_CPU0_EN")
	)
	(segment
		(start 381.723392 -64.655446)
		(end 381.723392 -64.661796)
		(width 0.089408)
		(layer "In11.Cu")
		(net "FM_PVPP_CPU0_EN")
	)
	(segment
		(start 381.851916 -58.43143)
		(end 381.851916 -58.832242)
		(width 0.089408)
		(layer "In11.Cu")
		(net "FM_PVPP_CPU0_EN")
	)
	(segment
		(start 383.700274 -70.700138)
		(end 383.507742 -70.89267)
		(width 0.089408)
		(layer "In11.Cu")
		(net "FM_PVPP_CPU0_EN")
	)
	(segment
		(start 378.665486 -53.759608)
		(end 379.764036 -54.858158)
		(width 0.089408)
		(layer "In11.Cu")
		(net "FM_PVPP_CPU0_EN")
	)
	(segment
		(start 380.700026 -63.994284)
		(end 381.06223 -63.994284)
		(width 0.089408)
		(layer "In11.Cu")
		(net "FM_PVPP_CPU0_EN")
	)
	(segment
		(start 385.548124 -75.014836)
		(end 385.54787 -75.01509)
		(width 0.089408)
		(layer "In11.Cu")
		(net "FM_PVPP_CPU0_EN")
	)
	(segment
		(start 384.662934 -79.086456)
		(end 385.140454 -79.563976)
		(width 0.089408)
		(layer "In11.Cu")
		(net "FM_PVPP_CPU0_EN")
	)
	(segment
		(start 381.723646 -65.062862)
		(end 381.723392 -65.063116)
		(width 0.089408)
		(layer "In11.Cu")
		(net "FM_PVPP_CPU0_EN")
	)
	(segment
		(start 366.820704 -81.30286)
		(end 366.555274 -81.03743)
		(width 0.089408)
		(layer "In11.Cu")
		(net "FM_PVPP_CPU0_EN")
	)
	(segment
		(start 358.569006 -36.53282)
		(end 368.988848 -46.952662)
		(width 0.089408)
		(layer "In11.Cu")
		(net "FM_PVPP_CPU0_EN")
	)
	(segment
		(start 352.678746 -36.53282)
		(end 358.569006 -36.53282)
		(width 0.089408)
		(layer "In11.Cu")
		(net "FM_PVPP_CPU0_EN")
	)
	(segment
		(start 385.547616 -74.85634)
		(end 385.548124 -74.856848)
		(width 0.089408)
		(layer "In11.Cu")
		(net "FM_PVPP_CPU0_EN")
	)
	(segment
		(start 383.507742 -70.89267)
		(end 383.507742 -71.64197)
		(width 0.089408)
		(layer "In11.Cu")
		(net "FM_PVPP_CPU0_EN")
	)
	(segment
		(start 383.70002 -67.90436)
		(end 383.70002 -70.299072)
		(width 0.089408)
		(layer "In11.Cu")
		(net "FM_PVPP_CPU0_EN")
	)
	(segment
		(start 383.700274 -70.299326)
		(end 383.700274 -70.700138)
		(width 0.089408)
		(layer "In11.Cu")
		(net "FM_PVPP_CPU0_EN")
	)
	(segment
		(start 334.749648 -36.82746)
		(end 335.152492 -37.230304)
		(width 0.089408)
		(layer "In11.Cu")
		(net "FM_PVPP_CPU0_EN")
	)
	(segment
		(start 333.252318 -33.098232)
		(end 333.252318 -34.979864)
		(width 0.089408)
		(layer "In11.Cu")
		(net "FM_PVPP_CPU0_EN")
	)
	(segment
		(start 331.47 -31.315914)
		(end 333.252318 -33.098232)
		(width 0.089408)
		(layer "In11.Cu")
		(net "FM_PVPP_CPU0_EN")
	)
	(segment
		(start 381.851916 -58.832242)
		(end 381.851662 -58.832496)
		(width 0.089408)
		(layer "In11.Cu")
		(net "FM_PVPP_CPU0_EN")
	)
	(segment
		(start 384.771138 -72.905366)
		(end 384.771138 -73.240138)
		(width 0.089408)
		(layer "In11.Cu")
		(net "FM_PVPP_CPU0_EN")
	)
	(segment
		(start 381.06223 -63.994284)
		(end 381.723392 -64.655446)
		(width 0.089408)
		(layer "In11.Cu")
		(net "FM_PVPP_CPU0_EN")
	)
	(segment
		(start 334.749648 -36.477194)
		(end 334.749648 -36.82746)
		(width 0.089408)
		(layer "In11.Cu")
		(net "FM_PVPP_CPU0_EN")
	)
	(segment
		(start 335.152492 -37.230304)
		(end 351.981262 -37.230304)
		(width 0.089408)
		(layer "In11.Cu")
		(net "FM_PVPP_CPU0_EN")
	)
	(segment
		(start 381.723392 -64.661796)
		(end 381.723646 -64.66205)
		(width 0.089408)
		(layer "In11.Cu")
		(net "FM_PVPP_CPU0_EN")
	)
	(segment
		(start 381.723392 -65.927732)
		(end 383.70002 -67.90436)
		(width 0.089408)
		(layer "In11.Cu")
		(net "FM_PVPP_CPU0_EN")
	)
	(segment
		(start 370.973096 -47.949612)
		(end 374.18391 -51.160426)
		(width 0.089408)
		(layer "In11.Cu")
		(net "FM_PVPP_CPU0_EN")
	)
	(segment
		(start 375.38914 -53.759608)
		(end 378.665486 -53.759608)
		(width 0.089408)
		(layer "In11.Cu")
		(net "FM_PVPP_CPU0_EN")
	)
	(segment
		(start 332.3336 -20.2184)
		(end 331.47 -21.082)
		(width 0.089408)
		(layer "In11.Cu")
		(net "FM_PVPP_CPU0_EN")
	)
	(segment
		(start 368.988848 -46.952662)
		(end 370.625878 -46.952662)
		(width 0.089408)
		(layer "In11.Cu")
		(net "FM_PVPP_CPU0_EN")
	)
	(segment
		(start 380.465584 -63.759842)
		(end 380.700026 -63.994284)
		(width 0.089408)
		(layer "In11.Cu")
		(net "FM_PVPP_CPU0_EN")
	)
	(segment
		(start 351.981262 -37.230304)
		(end 352.678746 -36.53282)
		(width 0.089408)
		(layer "In11.Cu")
		(net "FM_PVPP_CPU0_EN")
	)
	(segment
		(start 381.254508 -57.834022)
		(end 381.851916 -58.43143)
		(width 0.089408)
		(layer "In11.Cu")
		(net "FM_PVPP_CPU0_EN")
	)
	(segment
		(start 380.465584 -63.374016)
		(end 380.465584 -63.759842)
		(width 0.089408)
		(layer "In11.Cu")
		(net "FM_PVPP_CPU0_EN")
	)
	(segment
		(start 366.555274 -79.948024)
		(end 367.145316 -79.357982)
		(width 0.089408)
		(layer "In11.Cu")
		(net "FM_PVPP_CPU0_EN")
	)
	(segment
		(start 381.2032 -60.597542)
		(end 381.2032 -62.6364)
		(width 0.089408)
		(layer "In11.Cu")
		(net "FM_PVPP_CPU0_EN")
	)
	(segment
		(start 379.764036 -54.858158)
		(end 379.764036 -56.895746)
		(width 0.089408)
		(layer "In11.Cu")
		(net "FM_PVPP_CPU0_EN")
	)
	(segment
		(start 384.662934 -76.142342)
		(end 384.662934 -79.086456)
		(width 0.089408)
		(layer "In11.Cu")
		(net "FM_PVPP_CPU0_EN")
	)
	(segment
		(start 385.54787 -75.257406)
		(end 384.662934 -76.142342)
		(width 0.089408)
		(layer "In11.Cu")
		(net "FM_PVPP_CPU0_EN")
	)
	(segment
		(start 366.555274 -81.03743)
		(end 366.555274 -79.948024)
		(width 0.089408)
		(layer "In11.Cu")
		(net "FM_PVPP_CPU0_EN")
	)
	(segment
		(start 380.702312 -57.834022)
		(end 381.254508 -57.834022)
		(width 0.089408)
		(layer "In11.Cu")
		(net "FM_PVPP_CPU0_EN")
	)
	(segment
		(start 381.851662 -58.832496)
		(end 381.851662 -59.94908)
		(width 0.089408)
		(layer "In11.Cu")
		(net "FM_PVPP_CPU0_EN")
	)
	(segment
		(start 367.145316 -79.357982)
		(end 367.145316 -79.094838)
		(width 0.089408)
		(layer "In11.Cu")
		(net "FM_PVPP_CPU0_EN")
	)
	(segment
		(start 385.548124 -74.856848)
		(end 385.548124 -75.014836)
		(width 0.089408)
		(layer "In11.Cu")
		(net "FM_PVPP_CPU0_EN")
	)
	(segment
		(start 381.2032 -62.6364)
		(end 380.465584 -63.374016)
		(width 0.089408)
		(layer "In11.Cu")
		(net "FM_PVPP_CPU0_EN")
	)
	(segment
		(start 333.252318 -34.979864)
		(end 334.749648 -36.477194)
		(width 0.089408)
		(layer "In11.Cu")
		(net "FM_PVPP_CPU0_EN")
	)
	(segment
		(start 366.854994 -82.388964)
		(end 366.820704 -82.354674)
		(width 0.089408)
		(layer "In11.Cu")
		(net "FM_PVPP_CPU0_EN")
	)
	(segment
		(start 385.547616 -74.016616)
		(end 385.547616 -74.85634)
		(width 0.089408)
		(layer "In11.Cu")
		(net "FM_PVPP_CPU0_EN")
	)
	(segment
		(start 381.723392 -65.063116)
		(end 381.723392 -65.927732)
		(width 0.089408)
		(layer "In11.Cu")
		(net "FM_PVPP_CPU0_EN")
	)
	(segment
		(start 374.18391 -51.7779)
		(end 375.16689 -52.76088)
		(width 0.089408)
		(layer "In11.Cu")
		(net "FM_PVPP_CPU0_EN")
	)
	(segment
		(start 383.507742 -71.64197)
		(end 384.771138 -72.905366)
		(width 0.089408)
		(layer "In11.Cu")
		(net "FM_PVPP_CPU0_EN")
	)
	(segment
		(start 381.851662 -59.94908)
		(end 381.2032 -60.597542)
		(width 0.089408)
		(layer "In11.Cu")
		(net "FM_PVPP_CPU0_EN")
	)
	(segment
		(start 381.723646 -64.66205)
		(end 381.723646 -65.062862)
		(width 0.089408)
		(layer "In11.Cu")
		(net "FM_PVPP_CPU0_EN")
	)
	(segment
		(start 331.47 -21.082)
		(end 331.47 -31.315914)
		(width 0.089408)
		(layer "In11.Cu")
		(net "FM_PVPP_CPU0_EN")
	)
	(segment
		(start 384.771138 -73.240138)
		(end 385.547616 -74.016616)
		(width 0.089408)
		(layer "In11.Cu")
		(net "FM_PVPP_CPU0_EN")
	)
	(segment
		(start 383.70002 -70.299072)
		(end 383.700274 -70.299326)
		(width 0.089408)
		(layer "In11.Cu")
		(net "FM_PVPP_CPU0_EN")
	)
	(segment
		(start 366.820704 -82.354674)
		(end 366.820704 -81.30286)
		(width 0.089408)
		(layer "In11.Cu")
		(net "FM_PVPP_CPU0_EN")
	)
	(segment
		(start 379.226064 -82.081624)
		(end 380.72314 -83.5787)
		(width 0.10795)
		(layer "F.Cu")
		(net "FM_CPLD_BMC_PWRDN_N")
	)
	(segment
		(start 372.798848 -78.34884)
		(end 372.798848 -80.438244)
		(width 0.10795)
		(layer "F.Cu")
		(net "FM_CPLD_BMC_PWRDN_N")
	)
	(segment
		(start 380.72314 -83.5787)
		(end 381.323596 -83.5787)
		(width 0.10795)
		(layer "F.Cu")
		(net "FM_CPLD_BMC_PWRDN_N")
	)
	(segment
		(start 394.439902 -80.514952)
		(end 394.439902 -82.546698)
		(width 0.10795)
		(layer "F.Cu")
		(net "FM_CPLD_BMC_PWRDN_N")
	)
	(segment
		(start 393.6746 -84.439252)
		(end 393.32281 -84.791042)
		(width 0.10795)
		(layer "F.Cu")
		(net "FM_CPLD_BMC_PWRDN_N")
	)
	(segment
		(start 391.758424 -81.22285)
		(end 392.002264 -81.22285)
		(width 0.10795)
		(layer "F.Cu")
		(net "FM_CPLD_BMC_PWRDN_N")
	)
	(segment
		(start 392.833098 -79.288386)
		(end 393.035282 -79.086202)
		(width 0.10795)
		(layer "F.Cu")
		(net "FM_CPLD_BMC_PWRDN_N")
	)
	(segment
		(start 400.581622 -111.73841)
		(end 400.961098 -111.73841)
		(width 0.0889)
		(layer "F.Cu")
		(net "FM_CPLD_BMC_PWRDN_N")
	)
	(segment
		(start 381.323596 -83.5787)
		(end 381.384556 -83.63966)
		(width 0.10795)
		(layer "F.Cu")
		(net "FM_CPLD_BMC_PWRDN_N")
	)
	(segment
		(start 393.6746 -83.721702)
		(end 393.6746 -84.439252)
		(width 0.10795)
		(layer "F.Cu")
		(net "FM_CPLD_BMC_PWRDN_N")
	)
	(segment
		(start 392.833098 -80.392016)
		(end 392.833098 -79.288386)
		(width 0.10795)
		(layer "F.Cu")
		(net "FM_CPLD_BMC_PWRDN_N")
	)
	(segment
		(start 375.553224 -82.192368)
		(end 375.663968 -82.081624)
		(width 0.10795)
		(layer "F.Cu")
		(net "FM_CPLD_BMC_PWRDN_N")
	)
	(segment
		(start 375.663968 -82.081624)
		(end 379.226064 -82.081624)
		(width 0.10795)
		(layer "F.Cu")
		(net "FM_CPLD_BMC_PWRDN_N")
	)
	(segment
		(start 393.827 -79.90205)
		(end 394.439902 -80.514952)
		(width 0.10795)
		(layer "F.Cu")
		(net "FM_CPLD_BMC_PWRDN_N")
	)
	(segment
		(start 388.12597 -84.492084)
		(end 390.289288 -82.328766)
		(width 0.10795)
		(layer "F.Cu")
		(net "FM_CPLD_BMC_PWRDN_N")
	)
	(segment
		(start 409.090114 -37.334698)
		(end 409.490164 -36.934648)
		(width 0.10795)
		(layer "F.Cu")
		(net "FM_CPLD_BMC_PWRDN_N")
	)
	(segment
		(start 393.827 -79.527908)
		(end 393.827 -79.90205)
		(width 0.10795)
		(layer "F.Cu")
		(net "FM_CPLD_BMC_PWRDN_N")
	)
	(segment
		(start 401.130262 -111.569246)
		(end 401.465796 -111.569246)
		(width 0.0889)
		(layer "F.Cu")
		(net "FM_CPLD_BMC_PWRDN_N")
	)
	(segment
		(start 382.33096 -83.63966)
		(end 383.315972 -84.624672)
		(width 0.10795)
		(layer "F.Cu")
		(net "FM_CPLD_BMC_PWRDN_N")
	)
	(segment
		(start 390.652508 -82.328766)
		(end 391.758424 -81.22285)
		(width 0.10795)
		(layer "F.Cu")
		(net "FM_CPLD_BMC_PWRDN_N")
	)
	(segment
		(start 393.32281 -84.791042)
		(end 393.039092 -84.791042)
		(width 0.10795)
		(layer "F.Cu")
		(net "FM_CPLD_BMC_PWRDN_N")
	)
	(segment
		(start 373.022876 -81.944972)
		(end 373.270272 -82.192368)
		(width 0.10795)
		(layer "F.Cu")
		(net "FM_CPLD_BMC_PWRDN_N")
	)
	(segment
		(start 381.384556 -83.63966)
		(end 382.33096 -83.63966)
		(width 0.10795)
		(layer "F.Cu")
		(net "FM_CPLD_BMC_PWRDN_N")
	)
	(segment
		(start 392.002264 -81.22285)
		(end 392.833098 -80.392016)
		(width 0.10795)
		(layer "F.Cu")
		(net "FM_CPLD_BMC_PWRDN_N")
	)
	(segment
		(start 372.798848 -80.438244)
		(end 373.022876 -80.662272)
		(width 0.10795)
		(layer "F.Cu")
		(net "FM_CPLD_BMC_PWRDN_N")
	)
	(segment
		(start 401.465796 -111.569246)
		(end 401.602194 -111.705644)
		(width 0.0889)
		(layer "F.Cu")
		(net "FM_CPLD_BMC_PWRDN_N")
	)
	(segment
		(start 390.289288 -82.328766)
		(end 390.652508 -82.328766)
		(width 0.10795)
		(layer "F.Cu")
		(net "FM_CPLD_BMC_PWRDN_N")
	)
	(segment
		(start 401.602194 -111.705644)
		(end 403.37994 -111.705644)
		(width 0.0889)
		(layer "F.Cu")
		(net "FM_CPLD_BMC_PWRDN_N")
	)
	(segment
		(start 393.385294 -79.086202)
		(end 393.827 -79.527908)
		(width 0.10795)
		(layer "F.Cu")
		(net "FM_CPLD_BMC_PWRDN_N")
	)
	(segment
		(start 403.37994 -111.705644)
		(end 403.57298 -111.898684)
		(width 0.0889)
		(layer "F.Cu")
		(net "FM_CPLD_BMC_PWRDN_N")
	)
	(segment
		(start 393.035282 -79.086202)
		(end 393.385294 -79.086202)
		(width 0.10795)
		(layer "F.Cu")
		(net "FM_CPLD_BMC_PWRDN_N")
	)
	(segment
		(start 400.465036 -111.854996)
		(end 400.581622 -111.73841)
		(width 0.0889)
		(layer "F.Cu")
		(net "FM_CPLD_BMC_PWRDN_N")
	)
	(segment
		(start 383.315972 -84.624672)
		(end 385.204208 -84.624672)
		(width 0.10795)
		(layer "F.Cu")
		(net "FM_CPLD_BMC_PWRDN_N")
	)
	(segment
		(start 372.34495 -77.894942)
		(end 372.798848 -78.34884)
		(width 0.10795)
		(layer "F.Cu")
		(net "FM_CPLD_BMC_PWRDN_N")
	)
	(segment
		(start 373.270272 -82.192368)
		(end 375.553224 -82.192368)
		(width 0.10795)
		(layer "F.Cu")
		(net "FM_CPLD_BMC_PWRDN_N")
	)
	(segment
		(start 394.208 -83.188302)
		(end 393.6746 -83.721702)
		(width 0.10795)
		(layer "F.Cu")
		(net "FM_CPLD_BMC_PWRDN_N")
	)
	(segment
		(start 394.439902 -82.546698)
		(end 394.208 -82.7786)
		(width 0.10795)
		(layer "F.Cu")
		(net "FM_CPLD_BMC_PWRDN_N")
	)
	(segment
		(start 385.336796 -84.492084)
		(end 388.12597 -84.492084)
		(width 0.10795)
		(layer "F.Cu")
		(net "FM_CPLD_BMC_PWRDN_N")
	)
	(segment
		(start 394.208 -82.7786)
		(end 394.208 -83.188302)
		(width 0.10795)
		(layer "F.Cu")
		(net "FM_CPLD_BMC_PWRDN_N")
	)
	(segment
		(start 373.022876 -80.662272)
		(end 373.022876 -81.944972)
		(width 0.10795)
		(layer "F.Cu")
		(net "FM_CPLD_BMC_PWRDN_N")
	)
	(segment
		(start 400.961098 -111.73841)
		(end 401.130262 -111.569246)
		(width 0.0889)
		(layer "F.Cu")
		(net "FM_CPLD_BMC_PWRDN_N")
	)
	(segment
		(start 385.204208 -84.624672)
		(end 385.336796 -84.492084)
		(width 0.10795)
		(layer "F.Cu")
		(net "FM_CPLD_BMC_PWRDN_N")
	)
	(via
		(at 403.904704 -84.288376)
		(size 0.508)
		(drill 0.254)
		(layers "F.Cu" "B.Cu")
		(net "FM_CPLD_BMC_PWRDN_N")
	)
	(via
		(at 403.57298 -111.898684)
		(size 0.508)
		(drill 0.254)
		(layers "F.Cu" "B.Cu")
		(net "FM_CPLD_BMC_PWRDN_N")
	)
	(via
		(at 393.039092 -84.791042)
		(size 0.508)
		(drill 0.254)
		(layers "F.Cu" "B.Cu")
		(net "FM_CPLD_BMC_PWRDN_N")
	)
	(via
		(at 409.090114 -37.334698)
		(size 0.4572)
		(drill 0.2032)
		(layers "F.Cu" "B.Cu")
		(net "FM_CPLD_BMC_PWRDN_N")
	)
	(via
		(at 394.208 -82.7786)
		(size 0.762)
		(drill 0.381)
		(layers "F.Cu" "B.Cu")
		(net "FM_CPLD_BMC_PWRDN_N")
	)
	(segment
		(start 393.699238 -83.743292)
		(end 393.016994 -83.743292)
		(width 0.10795)
		(layer "B.Cu")
		(net "FM_CPLD_BMC_PWRDN_N")
	)
	(segment
		(start 407.161238 -39.08425)
		(end 405.694388 -39.08425)
		(width 0.10795)
		(layer "B.Cu")
		(net "FM_CPLD_BMC_PWRDN_N")
	)
	(segment
		(start 395.305534 -82.136996)
		(end 393.699238 -83.743292)
		(width 0.10795)
		(layer "B.Cu")
		(net "FM_CPLD_BMC_PWRDN_N")
	)
	(segment
		(start 404.749 -40.41267)
		(end 404.562818 -40.598852)
		(width 0.10795)
		(layer "B.Cu")
		(net "FM_CPLD_BMC_PWRDN_N")
	)
	(segment
		(start 408.45994 -37.925248)
		(end 408.459686 -37.925502)
		(width 0.10795)
		(layer "B.Cu")
		(net "FM_CPLD_BMC_PWRDN_N")
	)
	(segment
		(start 409.090114 -37.645086)
		(end 408.98445 -37.75075)
		(width 0.10795)
		(layer "B.Cu")
		(net "FM_CPLD_BMC_PWRDN_N")
	)
	(segment
		(start 403.568916 -84.288376)
		(end 402.54682 -83.26628)
		(width 0.10795)
		(layer "B.Cu")
		(net "FM_CPLD_BMC_PWRDN_N")
	)
	(segment
		(start 408.319986 -37.925502)
		(end 407.161238 -39.08425)
		(width 0.10795)
		(layer "B.Cu")
		(net "FM_CPLD_BMC_PWRDN_N")
	)
	(segment
		(start 398.629632 -82.136996)
		(end 395.305534 -82.136996)
		(width 0.10795)
		(layer "B.Cu")
		(net "FM_CPLD_BMC_PWRDN_N")
	)
	(segment
		(start 404.749 -39.891208)
		(end 404.749 -40.41267)
		(width 0.10795)
		(layer "B.Cu")
		(net "FM_CPLD_BMC_PWRDN_N")
	)
	(segment
		(start 409.090114 -37.334698)
		(end 409.090114 -37.645086)
		(width 0.10795)
		(layer "B.Cu")
		(net "FM_CPLD_BMC_PWRDN_N")
	)
	(segment
		(start 405.694134 -39.084504)
		(end 405.555704 -39.084504)
		(width 0.10795)
		(layer "B.Cu")
		(net "FM_CPLD_BMC_PWRDN_N")
	)
	(segment
		(start 408.756612 -37.925248)
		(end 408.45994 -37.925248)
		(width 0.10795)
		(layer "B.Cu")
		(net "FM_CPLD_BMC_PWRDN_N")
	)
	(segment
		(start 393.016994 -83.743292)
		(end 392.769598 -83.990688)
		(width 0.10795)
		(layer "B.Cu")
		(net "FM_CPLD_BMC_PWRDN_N")
	)
	(segment
		(start 392.769598 -84.521548)
		(end 393.039092 -84.791042)
		(width 0.10795)
		(layer "B.Cu")
		(net "FM_CPLD_BMC_PWRDN_N")
	)
	(segment
		(start 399.758916 -83.26628)
		(end 398.629632 -82.136996)
		(width 0.10795)
		(layer "B.Cu")
		(net "FM_CPLD_BMC_PWRDN_N")
	)
	(segment
		(start 405.694388 -39.08425)
		(end 405.694134 -39.084504)
		(width 0.10795)
		(layer "B.Cu")
		(net "FM_CPLD_BMC_PWRDN_N")
	)
	(segment
		(start 402.54682 -83.26628)
		(end 399.758916 -83.26628)
		(width 0.10795)
		(layer "B.Cu")
		(net "FM_CPLD_BMC_PWRDN_N")
	)
	(segment
		(start 392.769598 -83.990688)
		(end 392.769598 -84.521548)
		(width 0.10795)
		(layer "B.Cu")
		(net "FM_CPLD_BMC_PWRDN_N")
	)
	(segment
		(start 403.904704 -84.288376)
		(end 403.568916 -84.288376)
		(width 0.10795)
		(layer "B.Cu")
		(net "FM_CPLD_BMC_PWRDN_N")
	)
	(segment
		(start 405.555704 -39.084504)
		(end 404.749 -39.891208)
		(width 0.10795)
		(layer "B.Cu")
		(net "FM_CPLD_BMC_PWRDN_N")
	)
	(segment
		(start 408.93111 -37.75075)
		(end 408.756612 -37.925248)
		(width 0.10795)
		(layer "B.Cu")
		(net "FM_CPLD_BMC_PWRDN_N")
	)
	(segment
		(start 408.98445 -37.75075)
		(end 408.93111 -37.75075)
		(width 0.10795)
		(layer "B.Cu")
		(net "FM_CPLD_BMC_PWRDN_N")
	)
	(segment
		(start 404.562818 -40.598852)
		(end 402.361146 -40.598852)
		(width 0.10795)
		(layer "B.Cu")
		(net "FM_CPLD_BMC_PWRDN_N")
	)
	(segment
		(start 408.459686 -37.925502)
		(end 408.319986 -37.925502)
		(width 0.10795)
		(layer "B.Cu")
		(net "FM_CPLD_BMC_PWRDN_N")
	)
	(segment
		(start 403.57298 -111.69142)
		(end 404.1902 -111.0742)
		(width 0.089408)
		(layer "In2.Cu")
		(net "FM_CPLD_BMC_PWRDN_N")
	)
	(segment
		(start 401.49526 -92.183966)
		(end 401.49526 -88.359996)
		(width 0.089408)
		(layer "In2.Cu")
		(net "FM_CPLD_BMC_PWRDN_N")
	)
	(segment
		(start 404.1902 -110.744254)
		(end 404.323296 -110.611158)
		(width 0.089408)
		(layer "In2.Cu")
		(net "FM_CPLD_BMC_PWRDN_N")
	)
	(segment
		(start 401.49526 -88.359996)
		(end 403.09165 -86.763606)
		(width 0.089408)
		(layer "In2.Cu")
		(net "FM_CPLD_BMC_PWRDN_N")
	)
	(segment
		(start 403.3012 -106.6038)
		(end 401.9804 -106.6038)
		(width 0.089408)
		(layer "In2.Cu")
		(net "FM_CPLD_BMC_PWRDN_N")
	)
	(segment
		(start 404.323296 -107.625896)
		(end 403.3012 -106.6038)
		(width 0.089408)
		(layer "In2.Cu")
		(net "FM_CPLD_BMC_PWRDN_N")
	)
	(segment
		(start 401.9804 -106.6038)
		(end 400.636994 -105.260394)
		(width 0.089408)
		(layer "In2.Cu")
		(net "FM_CPLD_BMC_PWRDN_N")
	)
	(segment
		(start 404.1902 -111.0742)
		(end 404.1902 -110.744254)
		(width 0.089408)
		(layer "In2.Cu")
		(net "FM_CPLD_BMC_PWRDN_N")
	)
	(segment
		(start 400.636994 -100.043742)
		(end 401.147788 -99.532948)
		(width 0.089408)
		(layer "In2.Cu")
		(net "FM_CPLD_BMC_PWRDN_N")
	)
	(segment
		(start 404.323296 -110.611158)
		(end 404.323296 -107.625896)
		(width 0.089408)
		(layer "In2.Cu")
		(net "FM_CPLD_BMC_PWRDN_N")
	)
	(segment
		(start 403.09165 -86.763606)
		(end 403.09165 -85.37575)
		(width 0.089408)
		(layer "In2.Cu")
		(net "FM_CPLD_BMC_PWRDN_N")
	)
	(segment
		(start 403.904704 -84.562696)
		(end 403.904704 -84.288376)
		(width 0.089408)
		(layer "In2.Cu")
		(net "FM_CPLD_BMC_PWRDN_N")
	)
	(segment
		(start 401.147788 -99.532948)
		(end 401.147788 -92.531438)
		(width 0.089408)
		(layer "In2.Cu")
		(net "FM_CPLD_BMC_PWRDN_N")
	)
	(segment
		(start 403.57298 -111.898684)
		(end 403.57298 -111.69142)
		(width 0.089408)
		(layer "In2.Cu")
		(net "FM_CPLD_BMC_PWRDN_N")
	)
	(segment
		(start 401.147788 -92.531438)
		(end 401.49526 -92.183966)
		(width 0.089408)
		(layer "In2.Cu")
		(net "FM_CPLD_BMC_PWRDN_N")
	)
	(segment
		(start 400.636994 -105.260394)
		(end 400.636994 -100.043742)
		(width 0.089408)
		(layer "In2.Cu")
		(net "FM_CPLD_BMC_PWRDN_N")
	)
	(segment
		(start 403.09165 -85.37575)
		(end 403.904704 -84.562696)
		(width 0.089408)
		(layer "In2.Cu")
		(net "FM_CPLD_BMC_PWRDN_N")
	)
	(segment
		(start 392.791696 -84.543646)
		(end 392.791696 -83.99907)
		(width 0.089408)
		(layer "In9.Cu")
		(net "FM_CPLD_BMC_PWRDN_N")
	)
	(segment
		(start 395.521688 -76.204064)
		(end 395.521688 -71.770494)
		(width 0.089408)
		(layer "In9.Cu")
		(net "FM_CPLD_BMC_PWRDN_N")
	)
	(segment
		(start 399.043144 -64.067182)
		(end 399.043144 -62.736222)
		(width 0.089408)
		(layer "In9.Cu")
		(net "FM_CPLD_BMC_PWRDN_N")
	)
	(segment
		(start 394.608812 -81.76641)
		(end 394.608812 -80.925924)
		(width 0.089408)
		(layer "In9.Cu")
		(net "FM_CPLD_BMC_PWRDN_N")
	)
	(segment
		(start 394.2461 -80.563212)
		(end 394.2461 -79.358998)
		(width 0.089408)
		(layer "In9.Cu")
		(net "FM_CPLD_BMC_PWRDN_N")
	)
	(segment
		(start 398.777968 -54.793896)
		(end 398.777968 -47.374302)
		(width 0.089408)
		(layer "In9.Cu")
		(net "FM_CPLD_BMC_PWRDN_N")
	)
	(segment
		(start 394.27912 -77.446632)
		(end 395.521688 -76.204064)
		(width 0.089408)
		(layer "In9.Cu")
		(net "FM_CPLD_BMC_PWRDN_N")
	)
	(segment
		(start 401.997926 -43.138852)
		(end 401.997926 -39.817802)
		(width 0.089408)
		(layer "In9.Cu")
		(net "FM_CPLD_BMC_PWRDN_N")
	)
	(segment
		(start 401.997926 -39.817802)
		(end 404.884382 -36.931346)
		(width 0.089408)
		(layer "In9.Cu")
		(net "FM_CPLD_BMC_PWRDN_N")
	)
	(segment
		(start 398.777714 -57.171082)
		(end 398.777714 -54.79415)
		(width 0.089408)
		(layer "In9.Cu")
		(net "FM_CPLD_BMC_PWRDN_N")
	)
	(segment
		(start 393.039092 -84.791042)
		(end 392.791696 -84.543646)
		(width 0.089408)
		(layer "In9.Cu")
		(net "FM_CPLD_BMC_PWRDN_N")
	)
	(segment
		(start 398.468596 -66.057018)
		(end 398.468596 -64.64173)
		(width 0.089408)
		(layer "In9.Cu")
		(net "FM_CPLD_BMC_PWRDN_N")
	)
	(segment
		(start 393.656312 -78.403704)
		(end 394.27912 -77.780896)
		(width 0.089408)
		(layer "In9.Cu")
		(net "FM_CPLD_BMC_PWRDN_N")
	)
	(segment
		(start 393.99972 -82.375502)
		(end 394.608812 -81.76641)
		(width 0.089408)
		(layer "In9.Cu")
		(net "FM_CPLD_BMC_PWRDN_N")
	)
	(segment
		(start 400.424904 -58.932572)
		(end 398.777968 -57.285636)
		(width 0.089408)
		(layer "In9.Cu")
		(net "FM_CPLD_BMC_PWRDN_N")
	)
	(segment
		(start 394.2461 -79.358998)
		(end 393.656312 -78.76921)
		(width 0.089408)
		(layer "In9.Cu")
		(net "FM_CPLD_BMC_PWRDN_N")
	)
	(segment
		(start 396.826486 -67.699128)
		(end 398.468596 -66.057018)
		(width 0.089408)
		(layer "In9.Cu")
		(net "FM_CPLD_BMC_PWRDN_N")
	)
	(segment
		(start 394.27912 -77.780896)
		(end 394.27912 -77.446632)
		(width 0.089408)
		(layer "In9.Cu")
		(net "FM_CPLD_BMC_PWRDN_N")
	)
	(segment
		(start 394.608812 -80.925924)
		(end 394.2461 -80.563212)
		(width 0.089408)
		(layer "In9.Cu")
		(net "FM_CPLD_BMC_PWRDN_N")
	)
	(segment
		(start 408.686762 -36.931346)
		(end 409.090114 -37.334698)
		(width 0.089408)
		(layer "In9.Cu")
		(net "FM_CPLD_BMC_PWRDN_N")
	)
	(segment
		(start 398.777714 -54.79415)
		(end 398.777968 -54.793896)
		(width 0.089408)
		(layer "In9.Cu")
		(net "FM_CPLD_BMC_PWRDN_N")
	)
	(segment
		(start 398.777968 -47.374302)
		(end 401.248626 -44.903644)
		(width 0.089408)
		(layer "In9.Cu")
		(net "FM_CPLD_BMC_PWRDN_N")
	)
	(segment
		(start 398.777968 -57.285636)
		(end 398.777968 -57.171336)
		(width 0.089408)
		(layer "In9.Cu")
		(net "FM_CPLD_BMC_PWRDN_N")
	)
	(segment
		(start 399.043144 -62.736222)
		(end 400.424904 -61.354462)
		(width 0.089408)
		(layer "In9.Cu")
		(net "FM_CPLD_BMC_PWRDN_N")
	)
	(segment
		(start 398.468596 -64.64173)
		(end 399.043144 -64.067182)
		(width 0.089408)
		(layer "In9.Cu")
		(net "FM_CPLD_BMC_PWRDN_N")
	)
	(segment
		(start 396.826486 -70.465696)
		(end 396.826486 -67.699128)
		(width 0.089408)
		(layer "In9.Cu")
		(net "FM_CPLD_BMC_PWRDN_N")
	)
	(segment
		(start 393.656312 -78.76921)
		(end 393.656312 -78.403704)
		(width 0.089408)
		(layer "In9.Cu")
		(net "FM_CPLD_BMC_PWRDN_N")
	)
	(segment
		(start 404.884382 -36.931346)
		(end 408.686762 -36.931346)
		(width 0.089408)
		(layer "In9.Cu")
		(net "FM_CPLD_BMC_PWRDN_N")
	)
	(segment
		(start 398.777968 -57.171336)
		(end 398.777714 -57.171082)
		(width 0.089408)
		(layer "In9.Cu")
		(net "FM_CPLD_BMC_PWRDN_N")
	)
	(segment
		(start 401.248626 -43.888152)
		(end 401.997926 -43.138852)
		(width 0.089408)
		(layer "In9.Cu")
		(net "FM_CPLD_BMC_PWRDN_N")
	)
	(segment
		(start 395.521688 -71.770494)
		(end 396.826486 -70.465696)
		(width 0.089408)
		(layer "In9.Cu")
		(net "FM_CPLD_BMC_PWRDN_N")
	)
	(segment
		(start 392.791696 -83.99907)
		(end 393.99972 -82.791046)
		(width 0.089408)
		(layer "In9.Cu")
		(net "FM_CPLD_BMC_PWRDN_N")
	)
	(segment
		(start 393.99972 -82.791046)
		(end 393.99972 -82.375502)
		(width 0.089408)
		(layer "In9.Cu")
		(net "FM_CPLD_BMC_PWRDN_N")
	)
	(segment
		(start 400.424904 -61.354462)
		(end 400.424904 -58.932572)
		(width 0.089408)
		(layer "In9.Cu")
		(net "FM_CPLD_BMC_PWRDN_N")
	)
	(segment
		(start 401.248626 -44.903644)
		(end 401.248626 -43.888152)
		(width 0.089408)
		(layer "In9.Cu")
		(net "FM_CPLD_BMC_PWRDN_N")
	)
	(segment
		(start 400.465036 -110.854998)
		(end 400.545808 -110.93577)
		(width 0.0889)
		(layer "F.Cu")
		(net "FM_BB_BMC_MP_GPIO")
	)
	(segment
		(start 408.690064 -36.134548)
		(end 408.290014 -36.534598)
		(width 0.10795)
		(layer "F.Cu")
		(net "FM_BB_BMC_MP_GPIO")
	)
	(segment
		(start 401.317714 -111.3282)
		(end 401.57527 -111.3282)
		(width 0.0889)
		(layer "F.Cu")
		(net "FM_BB_BMC_MP_GPIO")
	)
	(segment
		(start 401.57527 -111.3282)
		(end 401.71116 -111.46409)
		(width 0.0889)
		(layer "F.Cu")
		(net "FM_BB_BMC_MP_GPIO")
	)
	(segment
		(start 403.702012 -111.46409)
		(end 404.11781 -111.879888)
		(width 0.0889)
		(layer "F.Cu")
		(net "FM_BB_BMC_MP_GPIO")
	)
	(segment
		(start 400.545808 -110.93577)
		(end 400.925284 -110.93577)
		(width 0.0889)
		(layer "F.Cu")
		(net "FM_BB_BMC_MP_GPIO")
	)
	(segment
		(start 404.11781 -111.879888)
		(end 404.227284 -111.879888)
		(width 0.0889)
		(layer "F.Cu")
		(net "FM_BB_BMC_MP_GPIO")
	)
	(segment
		(start 401.71116 -111.46409)
		(end 403.702012 -111.46409)
		(width 0.0889)
		(layer "F.Cu")
		(net "FM_BB_BMC_MP_GPIO")
	)
	(segment
		(start 400.925284 -110.93577)
		(end 401.317714 -111.3282)
		(width 0.0889)
		(layer "F.Cu")
		(net "FM_BB_BMC_MP_GPIO")
	)
	(via
		(at 404.227284 -111.879888)
		(size 0.508)
		(drill 0.254)
		(layers "F.Cu" "B.Cu")
		(net "FM_BB_BMC_MP_GPIO")
	)
	(via
		(at 473.573856 -50.410364)
		(size 0.508)
		(drill 0.254)
		(layers "F.Cu" "B.Cu")
		(net "FM_BB_BMC_MP_GPIO")
	)
	(via
		(at 408.290014 -36.534598)
		(size 0.4572)
		(drill 0.2032)
		(layers "F.Cu" "B.Cu")
		(net "FM_BB_BMC_MP_GPIO")
	)
	(via
		(at 377.2154 -119.3546)
		(size 0.508)
		(drill 0.254)
		(layers "F.Cu" "B.Cu")
		(net "FM_BB_BMC_MP_GPIO")
	)
	(via
		(at 474.472 -50.5714)
		(size 0.6604)
		(drill 0.3302)
		(layers "F.Cu" "B.Cu")
		(net "FM_BB_BMC_MP_GPIO")
	)
	(segment
		(start 473.734892 -50.5714)
		(end 473.573856 -50.410364)
		(width 0.10795)
		(layer "B.Cu")
		(net "FM_BB_BMC_MP_GPIO")
	)
	(segment
		(start 474.472 -50.5714)
		(end 473.734892 -50.5714)
		(width 0.10795)
		(layer "B.Cu")
		(net "FM_BB_BMC_MP_GPIO")
	)
	(segment
		(start 401.2565 -79.481934)
		(end 401.2565 -81.704942)
		(width 0.089408)
		(layer "In2.Cu")
		(net "FM_BB_BMC_MP_GPIO")
	)
	(segment
		(start 401.948904 -75.741022)
		(end 401.5867 -76.103226)
		(width 0.089408)
		(layer "In2.Cu")
		(net "FM_BB_BMC_MP_GPIO")
	)
	(segment
		(start 401.686268 -88.439244)
		(end 401.686268 -92.26296)
		(width 0.089408)
		(layer "In2.Cu")
		(net "FM_BB_BMC_MP_GPIO")
	)
	(segment
		(start 408.14244 -68.614798)
		(end 403.213824 -73.543414)
		(width 0.089408)
		(layer "In2.Cu")
		(net "FM_BB_BMC_MP_GPIO")
	)
	(segment
		(start 405.123904 -110.983268)
		(end 404.227284 -111.879888)
		(width 0.089408)
		(layer "In2.Cu")
		(net "FM_BB_BMC_MP_GPIO")
	)
	(segment
		(start 401.892008 -77.922374)
		(end 401.892008 -78.846426)
		(width 0.089408)
		(layer "In2.Cu")
		(net "FM_BB_BMC_MP_GPIO")
	)
	(segment
		(start 401.5867 -76.103226)
		(end 401.5867 -76.945236)
		(width 0.089408)
		(layer "In2.Cu")
		(net "FM_BB_BMC_MP_GPIO")
	)
	(segment
		(start 401.891754 -77.605636)
		(end 401.891754 -77.92212)
		(width 0.089408)
		(layer "In2.Cu")
		(net "FM_BB_BMC_MP_GPIO")
	)
	(segment
		(start 404.305008 -84.122514)
		(end 404.305008 -86.471252)
		(width 0.089408)
		(layer "In2.Cu")
		(net "FM_BB_BMC_MP_GPIO")
	)
	(segment
		(start 402.600414 -75.234546)
		(end 402.093938 -75.741022)
		(width 0.089408)
		(layer "In2.Cu")
		(net "FM_BB_BMC_MP_GPIO")
	)
	(segment
		(start 437.631078 -52.416456)
		(end 437.003698 -53.043836)
		(width 0.089408)
		(layer "In2.Cu")
		(net "FM_BB_BMC_MP_GPIO")
	)
	(segment
		(start 401.339812 -92.609416)
		(end 401.339812 -99.61118)
		(width 0.089408)
		(layer "In2.Cu")
		(net "FM_BB_BMC_MP_GPIO")
	)
	(segment
		(start 402.92147 -87.204042)
		(end 401.686268 -88.439244)
		(width 0.089408)
		(layer "In2.Cu")
		(net "FM_BB_BMC_MP_GPIO")
	)
	(segment
		(start 407.654252 -65.942464)
		(end 408.14244 -66.430652)
		(width 0.089408)
		(layer "In2.Cu")
		(net "FM_BB_BMC_MP_GPIO")
	)
	(segment
		(start 473.55506 -50.42916)
		(end 473.55506 -50.59934)
		(width 0.089408)
		(layer "In2.Cu")
		(net "FM_BB_BMC_MP_GPIO")
	)
	(segment
		(start 401.892008 -78.846426)
		(end 401.2565 -79.481934)
		(width 0.089408)
		(layer "In2.Cu")
		(net "FM_BB_BMC_MP_GPIO")
	)
	(segment
		(start 409.878784 -52.276502)
		(end 408.183842 -53.971444)
		(width 0.089408)
		(layer "In2.Cu")
		(net "FM_BB_BMC_MP_GPIO")
	)
	(segment
		(start 408.183842 -53.971444)
		(end 408.183842 -54.987444)
		(width 0.089408)
		(layer "In2.Cu")
		(net "FM_BB_BMC_MP_GPIO")
	)
	(segment
		(start 401.339812 -99.61118)
		(end 400.828002 -100.12299)
		(width 0.089408)
		(layer "In2.Cu")
		(net "FM_BB_BMC_MP_GPIO")
	)
	(segment
		(start 473.55506 -50.59934)
		(end 472.537028 -51.617372)
		(width 0.089408)
		(layer "In2.Cu")
		(net "FM_BB_BMC_MP_GPIO")
	)
	(segment
		(start 402.093938 -75.741022)
		(end 401.948904 -75.741022)
		(width 0.089408)
		(layer "In2.Cu")
		(net "FM_BB_BMC_MP_GPIO")
	)
	(segment
		(start 407.433272 -59.563508)
		(end 406.665176 -60.331604)
		(width 0.089408)
		(layer "In2.Cu")
		(net "FM_BB_BMC_MP_GPIO")
	)
	(segment
		(start 469.527128 -51.617372)
		(end 468.728044 -52.416456)
		(width 0.089408)
		(layer "In2.Cu")
		(net "FM_BB_BMC_MP_GPIO")
	)
	(segment
		(start 422.87444 -52.002182)
		(end 420.255954 -52.002182)
		(width 0.089408)
		(layer "In2.Cu")
		(net "FM_BB_BMC_MP_GPIO")
	)
	(segment
		(start 401.686268 -92.26296)
		(end 401.339812 -92.609416)
		(width 0.089408)
		(layer "In2.Cu")
		(net "FM_BB_BMC_MP_GPIO")
	)
	(segment
		(start 401.5867 -76.945236)
		(end 401.892008 -77.250544)
		(width 0.089408)
		(layer "In2.Cu")
		(net "FM_BB_BMC_MP_GPIO")
	)
	(segment
		(start 400.828002 -105.112312)
		(end 402.128482 -106.412792)
		(width 0.089408)
		(layer "In2.Cu")
		(net "FM_BB_BMC_MP_GPIO")
	)
	(segment
		(start 405.123904 -108.156248)
		(end 405.123904 -110.983268)
		(width 0.089408)
		(layer "In2.Cu")
		(net "FM_BB_BMC_MP_GPIO")
	)
	(segment
		(start 403.43963 -83.888072)
		(end 404.070566 -83.888072)
		(width 0.089408)
		(layer "In2.Cu")
		(net "FM_BB_BMC_MP_GPIO")
	)
	(segment
		(start 401.891754 -77.92212)
		(end 401.892008 -77.922374)
		(width 0.089408)
		(layer "In2.Cu")
		(net "FM_BB_BMC_MP_GPIO")
	)
	(segment
		(start 406.665176 -61.488574)
		(end 407.654252 -62.47765)
		(width 0.089408)
		(layer "In2.Cu")
		(net "FM_BB_BMC_MP_GPIO")
	)
	(segment
		(start 401.2565 -81.704942)
		(end 403.43963 -83.888072)
		(width 0.089408)
		(layer "In2.Cu")
		(net "FM_BB_BMC_MP_GPIO")
	)
	(segment
		(start 419.981634 -52.276502)
		(end 409.878784 -52.276502)
		(width 0.089408)
		(layer "In2.Cu")
		(net "FM_BB_BMC_MP_GPIO")
	)
	(segment
		(start 426.661834 -53.791104)
		(end 424.663362 -53.791104)
		(width 0.089408)
		(layer "In2.Cu")
		(net "FM_BB_BMC_MP_GPIO")
	)
	(segment
		(start 402.128482 -106.412792)
		(end 403.380448 -106.412792)
		(width 0.089408)
		(layer "In2.Cu")
		(net "FM_BB_BMC_MP_GPIO")
	)
	(segment
		(start 403.572218 -87.204042)
		(end 402.92147 -87.204042)
		(width 0.089408)
		(layer "In2.Cu")
		(net "FM_BB_BMC_MP_GPIO")
	)
	(segment
		(start 437.003698 -53.043836)
		(end 427.409102 -53.043836)
		(width 0.089408)
		(layer "In2.Cu")
		(net "FM_BB_BMC_MP_GPIO")
	)
	(segment
		(start 403.213824 -73.543414)
		(end 403.213824 -73.865232)
		(width 0.089408)
		(layer "In2.Cu")
		(net "FM_BB_BMC_MP_GPIO")
	)
	(segment
		(start 406.665176 -60.331604)
		(end 406.665176 -61.488574)
		(width 0.089408)
		(layer "In2.Cu")
		(net "FM_BB_BMC_MP_GPIO")
	)
	(segment
		(start 468.728044 -52.416456)
		(end 437.631078 -52.416456)
		(width 0.089408)
		(layer "In2.Cu")
		(net "FM_BB_BMC_MP_GPIO")
	)
	(segment
		(start 403.213824 -73.865232)
		(end 402.600414 -74.478642)
		(width 0.089408)
		(layer "In2.Cu")
		(net "FM_BB_BMC_MP_GPIO")
	)
	(segment
		(start 472.537028 -51.617372)
		(end 469.527128 -51.617372)
		(width 0.089408)
		(layer "In2.Cu")
		(net "FM_BB_BMC_MP_GPIO")
	)
	(segment
		(start 424.663362 -53.791104)
		(end 422.87444 -52.002182)
		(width 0.089408)
		(layer "In2.Cu")
		(net "FM_BB_BMC_MP_GPIO")
	)
	(segment
		(start 404.070566 -83.888072)
		(end 404.305008 -84.122514)
		(width 0.089408)
		(layer "In2.Cu")
		(net "FM_BB_BMC_MP_GPIO")
	)
	(segment
		(start 400.828002 -100.12299)
		(end 400.828002 -105.112312)
		(width 0.089408)
		(layer "In2.Cu")
		(net "FM_BB_BMC_MP_GPIO")
	)
	(segment
		(start 404.305008 -86.471252)
		(end 403.572218 -87.204042)
		(width 0.089408)
		(layer "In2.Cu")
		(net "FM_BB_BMC_MP_GPIO")
	)
	(segment
		(start 401.892008 -77.605382)
		(end 401.891754 -77.605636)
		(width 0.089408)
		(layer "In2.Cu")
		(net "FM_BB_BMC_MP_GPIO")
	)
	(segment
		(start 407.433272 -55.738014)
		(end 407.433272 -59.563508)
		(width 0.089408)
		(layer "In2.Cu")
		(net "FM_BB_BMC_MP_GPIO")
	)
	(segment
		(start 403.380448 -106.412792)
		(end 405.123904 -108.156248)
		(width 0.089408)
		(layer "In2.Cu")
		(net "FM_BB_BMC_MP_GPIO")
	)
	(segment
		(start 402.600414 -74.478642)
		(end 402.600414 -75.234546)
		(width 0.089408)
		(layer "In2.Cu")
		(net "FM_BB_BMC_MP_GPIO")
	)
	(segment
		(start 408.14244 -66.430652)
		(end 408.14244 -68.614798)
		(width 0.089408)
		(layer "In2.Cu")
		(net "FM_BB_BMC_MP_GPIO")
	)
	(segment
		(start 427.409102 -53.043836)
		(end 426.661834 -53.791104)
		(width 0.089408)
		(layer "In2.Cu")
		(net "FM_BB_BMC_MP_GPIO")
	)
	(segment
		(start 407.654252 -62.47765)
		(end 407.654252 -65.942464)
		(width 0.089408)
		(layer "In2.Cu")
		(net "FM_BB_BMC_MP_GPIO")
	)
	(segment
		(start 473.573856 -50.410364)
		(end 473.55506 -50.42916)
		(width 0.089408)
		(layer "In2.Cu")
		(net "FM_BB_BMC_MP_GPIO")
	)
	(segment
		(start 401.892008 -77.250544)
		(end 401.892008 -77.605382)
		(width 0.089408)
		(layer "In2.Cu")
		(net "FM_BB_BMC_MP_GPIO")
	)
	(segment
		(start 408.183842 -54.987444)
		(end 407.433272 -55.738014)
		(width 0.089408)
		(layer "In2.Cu")
		(net "FM_BB_BMC_MP_GPIO")
	)
	(segment
		(start 420.255954 -52.002182)
		(end 419.981634 -52.276502)
		(width 0.089408)
		(layer "In2.Cu")
		(net "FM_BB_BMC_MP_GPIO")
	)
	(segment
		(start 389.711184 -117.98173)
		(end 389.711184 -117.616986)
		(width 0.089408)
		(layer "In4.Cu")
		(net "FM_BB_BMC_MP_GPIO")
	)
	(segment
		(start 411.065472 -35.839654)
		(end 412.145988 -36.92017)
		(width 0.089408)
		(layer "In4.Cu")
		(net "FM_BB_BMC_MP_GPIO")
	)
	(segment
		(start 402.172932 -114.135916)
		(end 402.843238 -113.46561)
		(width 0.089408)
		(layer "In4.Cu")
		(net "FM_BB_BMC_MP_GPIO")
	)
	(segment
		(start 408.290014 -36.005008)
		(end 408.93492 -35.360102)
		(width 0.089408)
		(layer "In4.Cu")
		(net "FM_BB_BMC_MP_GPIO")
	)
	(segment
		(start 377.782074 -119.098314)
		(end 388.982458 -119.098314)
		(width 0.089408)
		(layer "In4.Cu")
		(net "FM_BB_BMC_MP_GPIO")
	)
	(segment
		(start 472.720162 -44.442888)
		(end 472.87815 -44.442888)
		(width 0.089408)
		(layer "In4.Cu")
		(net "FM_BB_BMC_MP_GPIO")
	)
	(segment
		(start 467.78037 -40.301926)
		(end 467.855554 -40.37711)
		(width 0.089408)
		(layer "In4.Cu")
		(net "FM_BB_BMC_MP_GPIO")
	)
	(segment
		(start 391.23493 -117.08638)
		(end 391.23493 -116.804948)
		(width 0.089408)
		(layer "In4.Cu")
		(net "FM_BB_BMC_MP_GPIO")
	)
	(segment
		(start 467.855554 -40.37711)
		(end 467.855554 -40.968168)
		(width 0.089408)
		(layer "In4.Cu")
		(net "FM_BB_BMC_MP_GPIO")
	)
	(segment
		(start 389.925814 -117.402356)
		(end 390.918954 -117.402356)
		(width 0.089408)
		(layer "In4.Cu")
		(net "FM_BB_BMC_MP_GPIO")
	)
	(segment
		(start 396.503906 -114.798094)
		(end 401.510754 -114.798094)
		(width 0.0889)
		(layer "In4.Cu")
		(net "FM_BB_BMC_MP_GPIO")
	)
	(segment
		(start 465.05114 -39.207694)
		(end 465.252308 -39.408862)
		(width 0.089408)
		(layer "In4.Cu")
		(net "FM_BB_BMC_MP_GPIO")
	)
	(segment
		(start 377.2154 -119.3546)
		(end 377.525788 -119.3546)
		(width 0.089408)
		(layer "In4.Cu")
		(net "FM_BB_BMC_MP_GPIO")
	)
	(segment
		(start 442.72581 -38.7731)
		(end 443.32271 -38.1762)
		(width 0.089408)
		(layer "In4.Cu")
		(net "FM_BB_BMC_MP_GPIO")
	)
	(segment
		(start 392.318748 -116.5352)
		(end 392.59383 -116.260118)
		(width 0.089408)
		(layer "In4.Cu")
		(net "FM_BB_BMC_MP_GPIO")
	)
	(segment
		(start 472.878658 -44.44238)
		(end 472.91371 -44.44238)
		(width 0.089408)
		(layer "In4.Cu")
		(net "FM_BB_BMC_MP_GPIO")
	)
	(segment
		(start 419.374574 -38.54958)
		(end 420.134796 -39.309802)
		(width 0.089408)
		(layer "In4.Cu")
		(net "FM_BB_BMC_MP_GPIO")
	)
	(segment
		(start 463.023712 -38.1508)
		(end 463.066384 -38.1508)
		(width 0.089408)
		(layer "In4.Cu")
		(net "FM_BB_BMC_MP_GPIO")
	)
	(segment
		(start 465.05114 -38.127686)
		(end 465.05114 -39.207694)
		(width 0.089408)
		(layer "In4.Cu")
		(net "FM_BB_BMC_MP_GPIO")
	)
	(segment
		(start 391.504678 -116.5352)
		(end 392.318748 -116.5352)
		(width 0.089408)
		(layer "In4.Cu")
		(net "FM_BB_BMC_MP_GPIO")
	)
	(segment
		(start 389.711184 -117.616986)
		(end 389.925814 -117.402356)
		(width 0.089408)
		(layer "In4.Cu")
		(net "FM_BB_BMC_MP_GPIO")
	)
	(segment
		(start 412.674562 -38.39464)
		(end 412.829502 -38.54958)
		(width 0.089408)
		(layer "In4.Cu")
		(net "FM_BB_BMC_MP_GPIO")
	)
	(segment
		(start 472.91371 -44.44238)
		(end 473.856304 -45.384974)
		(width 0.089408)
		(layer "In4.Cu")
		(net "FM_BB_BMC_MP_GPIO")
	)
	(segment
		(start 472.87815 -44.442888)
		(end 472.878658 -44.44238)
		(width 0.089408)
		(layer "In4.Cu")
		(net "FM_BB_BMC_MP_GPIO")
	)
	(segment
		(start 408.93492 -35.360102)
		(end 410.82214 -35.360102)
		(width 0.089408)
		(layer "In4.Cu")
		(net "FM_BB_BMC_MP_GPIO")
	)
	(segment
		(start 408.290014 -36.534598)
		(end 408.290014 -36.005008)
		(width 0.089408)
		(layer "In4.Cu")
		(net "FM_BB_BMC_MP_GPIO")
	)
	(segment
		(start 391.23493 -116.804948)
		(end 391.504678 -116.5352)
		(width 0.089408)
		(layer "In4.Cu")
		(net "FM_BB_BMC_MP_GPIO")
	)
	(segment
		(start 469.127586 -42.2402)
		(end 470.275158 -42.2402)
		(width 0.089408)
		(layer "In4.Cu")
		(net "FM_BB_BMC_MP_GPIO")
	)
	(segment
		(start 465.252308 -39.408862)
		(end 467.547452 -39.408862)
		(width 0.089408)
		(layer "In4.Cu")
		(net "FM_BB_BMC_MP_GPIO")
	)
	(segment
		(start 467.855554 -40.968168)
		(end 469.127586 -42.2402)
		(width 0.089408)
		(layer "In4.Cu")
		(net "FM_BB_BMC_MP_GPIO")
	)
	(segment
		(start 411.065472 -35.603434)
		(end 411.065472 -35.839654)
		(width 0.089408)
		(layer "In4.Cu")
		(net "FM_BB_BMC_MP_GPIO")
	)
	(segment
		(start 389.275828 -118.804944)
		(end 389.275828 -118.417086)
		(width 0.089408)
		(layer "In4.Cu")
		(net "FM_BB_BMC_MP_GPIO")
	)
	(segment
		(start 412.145988 -36.92017)
		(end 412.5214 -36.92017)
		(width 0.089408)
		(layer "In4.Cu")
		(net "FM_BB_BMC_MP_GPIO")
	)
	(segment
		(start 388.982458 -119.098314)
		(end 389.275828 -118.804944)
		(width 0.089408)
		(layer "In4.Cu")
		(net "FM_BB_BMC_MP_GPIO")
	)
	(segment
		(start 412.674562 -37.073332)
		(end 412.674562 -38.39464)
		(width 0.089408)
		(layer "In4.Cu")
		(net "FM_BB_BMC_MP_GPIO")
	)
	(segment
		(start 473.856304 -45.384974)
		(end 473.856304 -50.127916)
		(width 0.089408)
		(layer "In4.Cu")
		(net "FM_BB_BMC_MP_GPIO")
	)
	(segment
		(start 425.302172 -37.425122)
		(end 433.875434 -37.425122)
		(width 0.089408)
		(layer "In4.Cu")
		(net "FM_BB_BMC_MP_GPIO")
	)
	(segment
		(start 412.829502 -38.54958)
		(end 419.374574 -38.54958)
		(width 0.089408)
		(layer "In4.Cu")
		(net "FM_BB_BMC_MP_GPIO")
	)
	(segment
		(start 402.843238 -112.940338)
		(end 403.333204 -112.450372)
		(width 0.089408)
		(layer "In4.Cu")
		(net "FM_BB_BMC_MP_GPIO")
	)
	(segment
		(start 395.917166 -114.8334)
		(end 395.973046 -114.88928)
		(width 0.089408)
		(layer "In4.Cu")
		(net "FM_BB_BMC_MP_GPIO")
	)
	(segment
		(start 456.372214 -35.91687)
		(end 458.333602 -35.91687)
		(width 0.089408)
		(layer "In4.Cu")
		(net "FM_BB_BMC_MP_GPIO")
	)
	(segment
		(start 435.223412 -38.7731)
		(end 442.72581 -38.7731)
		(width 0.089408)
		(layer "In4.Cu")
		(net "FM_BB_BMC_MP_GPIO")
	)
	(segment
		(start 463.011774 -38.138862)
		(end 463.023712 -38.1508)
		(width 0.089408)
		(layer "In4.Cu")
		(net "FM_BB_BMC_MP_GPIO")
	)
	(segment
		(start 463.756248 -37.460936)
		(end 464.38439 -37.460936)
		(width 0.089408)
		(layer "In4.Cu")
		(net "FM_BB_BMC_MP_GPIO")
	)
	(segment
		(start 447.48196 -36.07308)
		(end 456.216004 -36.07308)
		(width 0.089408)
		(layer "In4.Cu")
		(net "FM_BB_BMC_MP_GPIO")
	)
	(segment
		(start 402.843238 -113.46561)
		(end 402.843238 -112.940338)
		(width 0.089408)
		(layer "In4.Cu")
		(net "FM_BB_BMC_MP_GPIO")
	)
	(segment
		(start 473.856304 -50.127916)
		(end 473.573856 -50.410364)
		(width 0.089408)
		(layer "In4.Cu")
		(net "FM_BB_BMC_MP_GPIO")
	)
	(segment
		(start 423.417492 -39.309802)
		(end 425.302172 -37.425122)
		(width 0.089408)
		(layer "In4.Cu")
		(net "FM_BB_BMC_MP_GPIO")
	)
	(segment
		(start 392.9888 -114.8334)
		(end 395.917166 -114.8334)
		(width 0.089408)
		(layer "In4.Cu")
		(net "FM_BB_BMC_MP_GPIO")
	)
	(segment
		(start 460.555594 -38.138862)
		(end 463.011774 -38.138862)
		(width 0.089408)
		(layer "In4.Cu")
		(net "FM_BB_BMC_MP_GPIO")
	)
	(segment
		(start 472.477592 -44.442634)
		(end 472.719908 -44.442634)
		(width 0.089408)
		(layer "In4.Cu")
		(net "FM_BB_BMC_MP_GPIO")
	)
	(segment
		(start 445.37884 -38.1762)
		(end 447.48196 -36.07308)
		(width 0.089408)
		(layer "In4.Cu")
		(net "FM_BB_BMC_MP_GPIO")
	)
	(segment
		(start 470.275158 -42.2402)
		(end 472.477592 -44.442634)
		(width 0.089408)
		(layer "In4.Cu")
		(net "FM_BB_BMC_MP_GPIO")
	)
	(segment
		(start 377.525788 -119.3546)
		(end 377.782074 -119.098314)
		(width 0.089408)
		(layer "In4.Cu")
		(net "FM_BB_BMC_MP_GPIO")
	)
	(segment
		(start 392.59383 -116.260118)
		(end 392.59383 -115.22837)
		(width 0.089408)
		(layer "In4.Cu")
		(net "FM_BB_BMC_MP_GPIO")
	)
	(segment
		(start 403.333204 -112.450372)
		(end 403.6568 -112.450372)
		(width 0.089408)
		(layer "In4.Cu")
		(net "FM_BB_BMC_MP_GPIO")
	)
	(segment
		(start 472.719908 -44.442634)
		(end 472.720162 -44.442888)
		(width 0.089408)
		(layer "In4.Cu")
		(net "FM_BB_BMC_MP_GPIO")
	)
	(segment
		(start 403.6568 -112.450372)
		(end 404.227284 -111.879888)
		(width 0.089408)
		(layer "In4.Cu")
		(net "FM_BB_BMC_MP_GPIO")
	)
	(segment
		(start 410.82214 -35.360102)
		(end 411.065472 -35.603434)
		(width 0.089408)
		(layer "In4.Cu")
		(net "FM_BB_BMC_MP_GPIO")
	)
	(segment
		(start 464.38439 -37.460936)
		(end 465.05114 -38.127686)
		(width 0.089408)
		(layer "In4.Cu")
		(net "FM_BB_BMC_MP_GPIO")
	)
	(segment
		(start 467.78037 -39.64178)
		(end 467.78037 -40.301926)
		(width 0.089408)
		(layer "In4.Cu")
		(net "FM_BB_BMC_MP_GPIO")
	)
	(segment
		(start 395.973046 -114.88928)
		(end 396.41272 -114.88928)
		(width 0.089408)
		(layer "In4.Cu")
		(net "FM_BB_BMC_MP_GPIO")
	)
	(segment
		(start 420.134796 -39.309802)
		(end 423.417492 -39.309802)
		(width 0.089408)
		(layer "In4.Cu")
		(net "FM_BB_BMC_MP_GPIO")
	)
	(segment
		(start 458.333602 -35.91687)
		(end 460.555594 -38.138862)
		(width 0.089408)
		(layer "In4.Cu")
		(net "FM_BB_BMC_MP_GPIO")
	)
	(segment
		(start 389.275828 -118.417086)
		(end 389.711184 -117.98173)
		(width 0.089408)
		(layer "In4.Cu")
		(net "FM_BB_BMC_MP_GPIO")
	)
	(segment
		(start 401.510754 -114.798094)
		(end 402.172932 -114.135916)
		(width 0.0889)
		(layer "In4.Cu")
		(net "FM_BB_BMC_MP_GPIO")
	)
	(segment
		(start 412.5214 -36.92017)
		(end 412.674562 -37.073332)
		(width 0.089408)
		(layer "In4.Cu")
		(net "FM_BB_BMC_MP_GPIO")
	)
	(segment
		(start 456.216004 -36.07308)
		(end 456.372214 -35.91687)
		(width 0.089408)
		(layer "In4.Cu")
		(net "FM_BB_BMC_MP_GPIO")
	)
	(segment
		(start 463.066384 -38.1508)
		(end 463.756248 -37.460936)
		(width 0.089408)
		(layer "In4.Cu")
		(net "FM_BB_BMC_MP_GPIO")
	)
	(segment
		(start 467.547452 -39.408862)
		(end 467.78037 -39.64178)
		(width 0.089408)
		(layer "In4.Cu")
		(net "FM_BB_BMC_MP_GPIO")
	)
	(segment
		(start 433.875434 -37.425122)
		(end 435.223412 -38.7731)
		(width 0.089408)
		(layer "In4.Cu")
		(net "FM_BB_BMC_MP_GPIO")
	)
	(segment
		(start 392.59383 -115.22837)
		(end 392.9888 -114.8334)
		(width 0.089408)
		(layer "In4.Cu")
		(net "FM_BB_BMC_MP_GPIO")
	)
	(segment
		(start 396.41272 -114.88928)
		(end 396.503906 -114.798094)
		(width 0.089408)
		(layer "In4.Cu")
		(net "FM_BB_BMC_MP_GPIO")
	)
	(segment
		(start 443.32271 -38.1762)
		(end 445.37884 -38.1762)
		(width 0.089408)
		(layer "In4.Cu")
		(net "FM_BB_BMC_MP_GPIO")
	)
	(segment
		(start 390.918954 -117.402356)
		(end 391.23493 -117.08638)
		(width 0.089408)
		(layer "In4.Cu")
		(net "FM_BB_BMC_MP_GPIO")
	)
	(segment
		(start 347.757496 -139.215622)
		(end 350.914462 -139.215622)
		(width 0.089408)
		(layer "In9.Cu")
		(net "FM_BB_BMC_MP_GPIO")
	)
	(segment
		(start 355.752908 -140.087604)
		(end 357.994458 -137.846054)
		(width 0.089408)
		(layer "In9.Cu")
		(net "FM_BB_BMC_MP_GPIO")
	)
	(segment
		(start 18.90522 -121.83618)
		(end 16.64716 -124.09424)
		(width 0.089408)
		(layer "In9.Cu")
		(net "FM_BB_BMC_MP_GPIO")
	)
	(segment
		(start 343.926922 -138.767058)
		(end 347.308932 -138.767058)
		(width 0.089408)
		(layer "In9.Cu")
		(net "FM_BB_BMC_MP_GPIO")
	)
	(segment
		(start 264.235946 -156.134054)
		(end 325.861426 -156.134054)
		(width 0.089408)
		(layer "In9.Cu")
		(net "FM_BB_BMC_MP_GPIO")
	)
	(segment
		(start -1.20015 -98.769932)
		(end -0.069342 -99.90074)
		(width 0.089408)
		(layer "In9.Cu")
		(net "FM_BB_BMC_MP_GPIO")
	)
	(segment
		(start 336.806032 -137.586466)
		(end 337.719416 -137.586466)
		(width 0.089408)
		(layer "In9.Cu")
		(net "FM_BB_BMC_MP_GPIO")
	)
	(segment
		(start 18.694146 -133.35381)
		(end 21.92147 -136.581134)
		(width 0.089408)
		(layer "In9.Cu")
		(net "FM_BB_BMC_MP_GPIO")
	)
	(segment
		(start 181.755542 -152.080976)
		(end 184.360566 -154.686)
		(width 0.089408)
		(layer "In9.Cu")
		(net "FM_BB_BMC_MP_GPIO")
	)
	(segment
		(start 181.755542 -151.565356)
		(end 181.755542 -152.080976)
		(width 0.089408)
		(layer "In9.Cu")
		(net "FM_BB_BMC_MP_GPIO")
	)
	(segment
		(start 336.024474 -138.368024)
		(end 336.806032 -137.586466)
		(width 0.089408)
		(layer "In9.Cu")
		(net "FM_BB_BMC_MP_GPIO")
	)
	(segment
		(start 158.96844 -152.820116)
		(end 159.651192 -152.137364)
		(width 0.089408)
		(layer "In9.Cu")
		(net "FM_BB_BMC_MP_GPIO")
	)
	(segment
		(start 184.360566 -154.686)
		(end 186.659012 -154.686)
		(width 0.089408)
		(layer "In9.Cu")
		(net "FM_BB_BMC_MP_GPIO")
	)
	(segment
		(start 167.726614 -148.971)
		(end 176.691036 -148.971)
		(width 0.089408)
		(layer "In9.Cu")
		(net "FM_BB_BMC_MP_GPIO")
	)
	(segment
		(start 18.694146 -130.674364)
		(end 18.694146 -133.35381)
		(width 0.089408)
		(layer "In9.Cu")
		(net "FM_BB_BMC_MP_GPIO")
	)
	(segment
		(start 376.644154 -121.75998)
		(end 376.936 -121.468134)
		(width 0.089408)
		(layer "In9.Cu")
		(net "FM_BB_BMC_MP_GPIO")
	)
	(segment
		(start 353.05365 -140.087604)
		(end 355.752908 -140.087604)
		(width 0.089408)
		(layer "In9.Cu")
		(net "FM_BB_BMC_MP_GPIO")
	)
	(segment
		(start 336.836004 -139.808458)
		(end 336.024474 -138.996928)
		(width 0.089408)
		(layer "In9.Cu")
		(net "FM_BB_BMC_MP_GPIO")
	)
	(segment
		(start 337.89747 -137.76452)
		(end 342.924384 -137.76452)
		(width 0.089408)
		(layer "In9.Cu")
		(net "FM_BB_BMC_MP_GPIO")
	)
	(segment
		(start 372.580154 -125.248416)
		(end 372.580154 -123.638818)
		(width 0.089408)
		(layer "In9.Cu")
		(net "FM_BB_BMC_MP_GPIO")
	)
	(segment
		(start 9.25322 -103.81615)
		(end 7.782814 -105.286556)
		(width 0.089408)
		(layer "In9.Cu")
		(net "FM_BB_BMC_MP_GPIO")
	)
	(segment
		(start 357.994458 -137.846054)
		(end 360.578146 -137.846054)
		(width 0.089408)
		(layer "In9.Cu")
		(net "FM_BB_BMC_MP_GPIO")
	)
	(segment
		(start 336.836004 -155.042362)
		(end 336.836004 -139.808458)
		(width 0.089408)
		(layer "In9.Cu")
		(net "FM_BB_BMC_MP_GPIO")
	)
	(segment
		(start 7.782814 -108.381292)
		(end 18.90522 -119.503698)
		(width 0.089408)
		(layer "In9.Cu")
		(net "FM_BB_BMC_MP_GPIO")
	)
	(segment
		(start 9.25322 -101.77272)
		(end 9.25322 -103.81615)
		(width 0.089408)
		(layer "In9.Cu")
		(net "FM_BB_BMC_MP_GPIO")
	)
	(segment
		(start 363.353096 -136.4996)
		(end 371.79758 -128.055116)
		(width 0.089408)
		(layer "In9.Cu")
		(net "FM_BB_BMC_MP_GPIO")
	)
	(segment
		(start 28.7528 -152.820116)
		(end 158.96844 -152.820116)
		(width 0.089408)
		(layer "In9.Cu")
		(net "FM_BB_BMC_MP_GPIO")
	)
	(segment
		(start 351.1423 -139.44346)
		(end 352.409506 -139.44346)
		(width 0.089408)
		(layer "In9.Cu")
		(net "FM_BB_BMC_MP_GPIO")
	)
	(segment
		(start 16.64716 -128.627378)
		(end 18.694146 -130.674364)
		(width 0.089408)
		(layer "In9.Cu")
		(net "FM_BB_BMC_MP_GPIO")
	)
	(segment
		(start 180.956458 -150.766272)
		(end 181.755542 -151.565356)
		(width 0.089408)
		(layer "In9.Cu")
		(net "FM_BB_BMC_MP_GPIO")
	)
	(segment
		(start 21.92147 -136.581134)
		(end 21.92147 -150.030688)
		(width 0.089408)
		(layer "In9.Cu")
		(net "FM_BB_BMC_MP_GPIO")
	)
	(segment
		(start 176.691036 -148.971)
		(end 178.486308 -150.766272)
		(width 0.089408)
		(layer "In9.Cu")
		(net "FM_BB_BMC_MP_GPIO")
	)
	(segment
		(start 325.861426 -156.134054)
		(end 325.983346 -156.255974)
		(width 0.089408)
		(layer "In9.Cu")
		(net "FM_BB_BMC_MP_GPIO")
	)
	(segment
		(start 336.430366 -155.448)
		(end 336.836004 -155.042362)
		(width 0.089408)
		(layer "In9.Cu")
		(net "FM_BB_BMC_MP_GPIO")
	)
	(segment
		(start 178.486308 -150.766272)
		(end 180.956458 -150.766272)
		(width 0.089408)
		(layer "In9.Cu")
		(net "FM_BB_BMC_MP_GPIO")
	)
	(segment
		(start 347.308932 -138.767058)
		(end 347.757496 -139.215622)
		(width 0.089408)
		(layer "In9.Cu")
		(net "FM_BB_BMC_MP_GPIO")
	)
	(segment
		(start 16.64716 -124.09424)
		(end 16.64716 -128.627378)
		(width 0.089408)
		(layer "In9.Cu")
		(net "FM_BB_BMC_MP_GPIO")
	)
	(segment
		(start -0.069342 -99.90074)
		(end 7.38124 -99.90074)
		(width 0.089408)
		(layer "In9.Cu")
		(net "FM_BB_BMC_MP_GPIO")
	)
	(segment
		(start 188.512704 -156.539692)
		(end 263.830308 -156.539692)
		(width 0.089408)
		(layer "In9.Cu")
		(net "FM_BB_BMC_MP_GPIO")
	)
	(segment
		(start 328.071226 -156.255974)
		(end 328.8792 -155.448)
		(width 0.089408)
		(layer "In9.Cu")
		(net "FM_BB_BMC_MP_GPIO")
	)
	(segment
		(start 263.830308 -156.539692)
		(end 264.235946 -156.134054)
		(width 0.089408)
		(layer "In9.Cu")
		(net "FM_BB_BMC_MP_GPIO")
	)
	(segment
		(start 21.92147 -150.030688)
		(end 23.528782 -151.638)
		(width 0.089408)
		(layer "In9.Cu")
		(net "FM_BB_BMC_MP_GPIO")
	)
	(segment
		(start 374.458992 -121.75998)
		(end 376.644154 -121.75998)
		(width 0.089408)
		(layer "In9.Cu")
		(net "FM_BB_BMC_MP_GPIO")
	)
	(segment
		(start 159.651192 -152.137364)
		(end 164.56025 -152.137364)
		(width 0.089408)
		(layer "In9.Cu")
		(net "FM_BB_BMC_MP_GPIO")
	)
	(segment
		(start 376.936 -121.468134)
		(end 376.936 -119.634)
		(width 0.089408)
		(layer "In9.Cu")
		(net "FM_BB_BMC_MP_GPIO")
	)
	(segment
		(start 350.914462 -139.215622)
		(end 351.1423 -139.44346)
		(width 0.089408)
		(layer "In9.Cu")
		(net "FM_BB_BMC_MP_GPIO")
	)
	(segment
		(start 23.528782 -151.638)
		(end 27.570684 -151.638)
		(width 0.089408)
		(layer "In9.Cu")
		(net "FM_BB_BMC_MP_GPIO")
	)
	(segment
		(start 360.578146 -137.846054)
		(end 361.9246 -136.4996)
		(width 0.089408)
		(layer "In9.Cu")
		(net "FM_BB_BMC_MP_GPIO")
	)
	(segment
		(start 371.79758 -128.055116)
		(end 371.79758 -126.03099)
		(width 0.089408)
		(layer "In9.Cu")
		(net "FM_BB_BMC_MP_GPIO")
	)
	(segment
		(start 371.79758 -126.03099)
		(end 372.580154 -125.248416)
		(width 0.089408)
		(layer "In9.Cu")
		(net "FM_BB_BMC_MP_GPIO")
	)
	(segment
		(start 336.024474 -138.996928)
		(end 336.024474 -138.368024)
		(width 0.089408)
		(layer "In9.Cu")
		(net "FM_BB_BMC_MP_GPIO")
	)
	(segment
		(start 27.570684 -151.638)
		(end 28.7528 -152.820116)
		(width 0.089408)
		(layer "In9.Cu")
		(net "FM_BB_BMC_MP_GPIO")
	)
	(segment
		(start 7.782814 -105.286556)
		(end 7.782814 -108.381292)
		(width 0.089408)
		(layer "In9.Cu")
		(net "FM_BB_BMC_MP_GPIO")
	)
	(segment
		(start 328.8792 -155.448)
		(end 336.430366 -155.448)
		(width 0.089408)
		(layer "In9.Cu")
		(net "FM_BB_BMC_MP_GPIO")
	)
	(segment
		(start 376.936 -119.634)
		(end 377.2154 -119.3546)
		(width 0.089408)
		(layer "In9.Cu")
		(net "FM_BB_BMC_MP_GPIO")
	)
	(segment
		(start 186.659012 -154.686)
		(end 188.512704 -156.539692)
		(width 0.089408)
		(layer "In9.Cu")
		(net "FM_BB_BMC_MP_GPIO")
	)
	(segment
		(start 18.90522 -119.503698)
		(end 18.90522 -121.83618)
		(width 0.089408)
		(layer "In9.Cu")
		(net "FM_BB_BMC_MP_GPIO")
	)
	(segment
		(start 7.38124 -99.90074)
		(end 9.25322 -101.77272)
		(width 0.089408)
		(layer "In9.Cu")
		(net "FM_BB_BMC_MP_GPIO")
	)
	(segment
		(start 325.983346 -156.255974)
		(end 328.071226 -156.255974)
		(width 0.089408)
		(layer "In9.Cu")
		(net "FM_BB_BMC_MP_GPIO")
	)
	(segment
		(start 337.719416 -137.586466)
		(end 337.89747 -137.76452)
		(width 0.089408)
		(layer "In9.Cu")
		(net "FM_BB_BMC_MP_GPIO")
	)
	(segment
		(start 352.409506 -139.44346)
		(end 353.05365 -140.087604)
		(width 0.089408)
		(layer "In9.Cu")
		(net "FM_BB_BMC_MP_GPIO")
	)
	(segment
		(start 372.580154 -123.638818)
		(end 374.458992 -121.75998)
		(width 0.089408)
		(layer "In9.Cu")
		(net "FM_BB_BMC_MP_GPIO")
	)
	(segment
		(start 164.56025 -152.137364)
		(end 167.726614 -148.971)
		(width 0.089408)
		(layer "In9.Cu")
		(net "FM_BB_BMC_MP_GPIO")
	)
	(segment
		(start 361.9246 -136.4996)
		(end 363.353096 -136.4996)
		(width 0.089408)
		(layer "In9.Cu")
		(net "FM_BB_BMC_MP_GPIO")
	)
	(segment
		(start 342.924384 -137.76452)
		(end 343.926922 -138.767058)
		(width 0.089408)
		(layer "In9.Cu")
		(net "FM_BB_BMC_MP_GPIO")
	)
	(segment
		(start 396.65275 -114.1476)
		(end 396.975076 -114.29746)
		(width 0.10795)
		(layer "F.Cu")
		(net "FM_PWR_LED_N")
	)
	(segment
		(start 473.6465 -138.43)
		(end 474.5355 -139.319)
		(width 0.10795)
		(layer "F.Cu")
		(net "FM_PWR_LED_N")
	)
	(segment
		(start 396.975076 -114.29746)
		(end 397.14805 -114.377724)
		(width 0.10795)
		(layer "F.Cu")
		(net "FM_PWR_LED_N")
	)
	(segment
		(start 475.7928 -139.319)
		(end 475.87154 -139.24026)
		(width 0.10795)
		(layer "F.Cu")
		(net "FM_PWR_LED_N")
	)
	(segment
		(start 475.87154 -138.557)
		(end 475.87154 -137.59434)
		(width 0.10795)
		(layer "F.Cu")
		(net "FM_PWR_LED_N")
	)
	(segment
		(start 475.87154 -139.24026)
		(end 475.87154 -138.557)
		(width 0.10795)
		(layer "F.Cu")
		(net "FM_PWR_LED_N")
	)
	(segment
		(start 474.5355 -139.319)
		(end 475.7928 -139.319)
		(width 0.10795)
		(layer "F.Cu")
		(net "FM_PWR_LED_N")
	)
	(via
		(at 397.14805 -114.377724)
		(size 0.508)
		(drill 0.254)
		(layers "F.Cu" "B.Cu")
		(net "FM_PWR_LED_N")
	)
	(via
		(at 475.87154 -137.59434)
		(size 0.508)
		(drill 0.254)
		(layers "F.Cu" "B.Cu")
		(net "FM_PWR_LED_N")
	)
	(segment
		(start 411.555946 -123.499626)
		(end 412.186628 -122.868944)
		(width 0.089408)
		(layer "In2.Cu")
		(net "FM_PWR_LED_N")
	)
	(segment
		(start 459.464156 -121.204482)
		(end 460.678022 -119.990616)
		(width 0.089408)
		(layer "In2.Cu")
		(net "FM_PWR_LED_N")
	)
	(segment
		(start 417.231322 -122.868944)
		(end 419.019736 -124.657358)
		(width 0.089408)
		(layer "In2.Cu")
		(net "FM_PWR_LED_N")
	)
	(segment
		(start 452.20763 -121.558304)
		(end 453.344534 -120.4214)
		(width 0.089408)
		(layer "In2.Cu")
		(net "FM_PWR_LED_N")
	)
	(segment
		(start 399.07591 -114.80927)
		(end 399.429224 -114.80927)
		(width 0.0889)
		(layer "In2.Cu")
		(net "FM_PWR_LED_N")
	)
	(segment
		(start 399.828004 -116.46408)
		(end 402.43379 -119.069866)
		(width 0.089408)
		(layer "In2.Cu")
		(net "FM_PWR_LED_N")
	)
	(segment
		(start 456.129136 -120.4214)
		(end 456.912218 -121.204482)
		(width 0.089408)
		(layer "In2.Cu")
		(net "FM_PWR_LED_N")
	)
	(segment
		(start 409.743148 -123.499626)
		(end 411.555946 -123.499626)
		(width 0.089408)
		(layer "In2.Cu")
		(net "FM_PWR_LED_N")
	)
	(segment
		(start 431.302668 -122.239278)
		(end 431.55362 -121.988326)
		(width 0.089408)
		(layer "In2.Cu")
		(net "FM_PWR_LED_N")
	)
	(segment
		(start 424.080432 -124.270262)
		(end 426.454316 -124.270262)
		(width 0.089408)
		(layer "In2.Cu")
		(net "FM_PWR_LED_N")
	)
	(segment
		(start 453.344534 -120.4214)
		(end 456.129136 -120.4214)
		(width 0.089408)
		(layer "In2.Cu")
		(net "FM_PWR_LED_N")
	)
	(segment
		(start 470.45753 -121.807986)
		(end 474.971364 -126.32182)
		(width 0.089408)
		(layer "In2.Cu")
		(net "FM_PWR_LED_N")
	)
	(segment
		(start 476.066358 -137.399522)
		(end 475.87154 -137.59434)
		(width 0.089408)
		(layer "In2.Cu")
		(net "FM_PWR_LED_N")
	)
	(segment
		(start 460.678022 -119.990616)
		(end 464.36534 -119.990616)
		(width 0.089408)
		(layer "In2.Cu")
		(net "FM_PWR_LED_N")
	)
	(segment
		(start 466.18271 -121.807986)
		(end 470.45753 -121.807986)
		(width 0.089408)
		(layer "In2.Cu")
		(net "FM_PWR_LED_N")
	)
	(segment
		(start 426.454316 -124.270262)
		(end 428.4853 -122.239278)
		(width 0.089408)
		(layer "In2.Cu")
		(net "FM_PWR_LED_N")
	)
	(segment
		(start 412.186628 -122.868944)
		(end 417.231322 -122.868944)
		(width 0.089408)
		(layer "In2.Cu")
		(net "FM_PWR_LED_N")
	)
	(segment
		(start 476.066358 -129.544826)
		(end 476.066358 -137.399522)
		(width 0.089408)
		(layer "In2.Cu")
		(net "FM_PWR_LED_N")
	)
	(segment
		(start 477.005904 -128.60528)
		(end 476.066358 -129.544826)
		(width 0.089408)
		(layer "In2.Cu")
		(net "FM_PWR_LED_N")
	)
	(segment
		(start 428.4853 -122.239278)
		(end 431.302668 -122.239278)
		(width 0.089408)
		(layer "In2.Cu")
		(net "FM_PWR_LED_N")
	)
	(segment
		(start 464.36534 -119.990616)
		(end 466.18271 -121.807986)
		(width 0.089408)
		(layer "In2.Cu")
		(net "FM_PWR_LED_N")
	)
	(segment
		(start 399.828004 -115.20805)
		(end 399.828004 -116.46408)
		(width 0.089408)
		(layer "In2.Cu")
		(net "FM_PWR_LED_N")
	)
	(segment
		(start 407.56459 -121.321068)
		(end 409.743148 -123.499626)
		(width 0.089408)
		(layer "In2.Cu")
		(net "FM_PWR_LED_N")
	)
	(segment
		(start 398.929352 -114.724434)
		(end 399.07591 -114.80927)
		(width 0.0889)
		(layer "In2.Cu")
		(net "FM_PWR_LED_N")
	)
	(segment
		(start 399.429224 -114.80927)
		(end 399.828004 -115.20805)
		(width 0.0889)
		(layer "In2.Cu")
		(net "FM_PWR_LED_N")
	)
	(segment
		(start 439.416444 -121.988326)
		(end 439.846466 -121.558304)
		(width 0.089408)
		(layer "In2.Cu")
		(net "FM_PWR_LED_N")
	)
	(segment
		(start 477.005904 -126.901194)
		(end 477.005904 -128.60528)
		(width 0.089408)
		(layer "In2.Cu")
		(net "FM_PWR_LED_N")
	)
	(segment
		(start 476.42653 -126.32182)
		(end 477.005904 -126.901194)
		(width 0.089408)
		(layer "In2.Cu")
		(net "FM_PWR_LED_N")
	)
	(segment
		(start 456.912218 -121.204482)
		(end 459.464156 -121.204482)
		(width 0.089408)
		(layer "In2.Cu")
		(net "FM_PWR_LED_N")
	)
	(segment
		(start 474.971364 -126.32182)
		(end 476.42653 -126.32182)
		(width 0.089408)
		(layer "In2.Cu")
		(net "FM_PWR_LED_N")
	)
	(segment
		(start 402.43379 -119.069866)
		(end 406.028398 -119.069866)
		(width 0.089408)
		(layer "In2.Cu")
		(net "FM_PWR_LED_N")
	)
	(segment
		(start 397.31696 -114.67084)
		(end 397.406368 -114.694716)
		(width 0.0889)
		(layer "In2.Cu")
		(net "FM_PWR_LED_N")
	)
	(segment
		(start 406.028398 -119.069866)
		(end 407.56459 -120.606058)
		(width 0.089408)
		(layer "In2.Cu")
		(net "FM_PWR_LED_N")
	)
	(segment
		(start 407.56459 -120.606058)
		(end 407.56459 -121.321068)
		(width 0.089408)
		(layer "In2.Cu")
		(net "FM_PWR_LED_N")
	)
	(segment
		(start 397.14805 -114.377724)
		(end 397.31696 -114.67084)
		(width 0.0889)
		(layer "In2.Cu")
		(net "FM_PWR_LED_N")
	)
	(segment
		(start 431.55362 -121.988326)
		(end 439.416444 -121.988326)
		(width 0.089408)
		(layer "In2.Cu")
		(net "FM_PWR_LED_N")
	)
	(segment
		(start 423.693336 -124.657358)
		(end 424.080432 -124.270262)
		(width 0.089408)
		(layer "In2.Cu")
		(net "FM_PWR_LED_N")
	)
	(segment
		(start 419.019736 -124.657358)
		(end 423.693336 -124.657358)
		(width 0.089408)
		(layer "In2.Cu")
		(net "FM_PWR_LED_N")
	)
	(segment
		(start 439.846466 -121.558304)
		(end 452.20763 -121.558304)
		(width 0.089408)
		(layer "In2.Cu")
		(net "FM_PWR_LED_N")
	)
	(arc
		(start 397.938752 -114.724434)
		(mid 398.13865 -114.777933)
		(end 398.338548 -114.724434)
		(width 0.0889)
		(layer "In2.Cu")
		(net "FM_PWR_LED_N")
	)
	(arc
		(start 397.406368 -114.694716)
		(mid 397.676093 -114.646156)
		(end 397.938752 -114.724434)
		(width 0.0889)
		(layer "In2.Cu")
		(net "FM_PWR_LED_N")
	)
	(arc
		(start 398.338548 -114.724434)
		(mid 398.63395 -114.645303)
		(end 398.929352 -114.724434)
		(width 0.0889)
		(layer "In2.Cu")
		(net "FM_PWR_LED_N")
	)
	(segment
		(start 477.189038 -137.328402)
		(end 476.52178 -137.99566)
		(width 0.10795)
		(layer "F.Cu")
		(net "FM_PWR_LED_K")
	)
	(segment
		(start 476.52178 -137.99566)
		(end 476.52178 -138.557)
		(width 0.10795)
		(layer "F.Cu")
		(net "FM_PWR_LED_K")
	)
	(segment
		(start 478.19564 -137.328402)
		(end 477.189038 -137.328402)
		(width 0.10795)
		(layer "F.Cu")
		(net "FM_PWR_LED_K")
	)
	(segment
		(start 481.206048 -137.033)
		(end 481.6983 -137.033)
		(width 0.10795)
		(layer "F.Cu")
		(net "FM_PWR_LED_A")
	)
	(segment
		(start 480.22764 -137.328402)
		(end 480.910646 -137.328402)
		(width 0.10795)
		(layer "F.Cu")
		(net "FM_PWR_LED_A")
	)
	(segment
		(start 480.910646 -137.328402)
		(end 481.206048 -137.033)
		(width 0.10795)
		(layer "F.Cu")
		(net "FM_PWR_LED_A")
	)
	(segment
		(start 475.3102 -141.0462)
		(end 475.2213 -140.9573)
		(width 0.10795)
		(layer "F.Cu")
		(net "FM_PWR_LED")
	)
	(segment
		(start 475.87154 -140.94206)
		(end 475.7674 -141.0462)
		(width 0.10795)
		(layer "F.Cu")
		(net "FM_PWR_LED")
	)
	(segment
		(start 475.2213 -140.9573)
		(end 475.2213 -140.335)
		(width 0.10795)
		(layer "F.Cu")
		(net "FM_PWR_LED")
	)
	(segment
		(start 473.6465 -139.573)
		(end 475.107 -139.573)
		(width 0.10795)
		(layer "F.Cu")
		(net "FM_PWR_LED")
	)
	(segment
		(start 475.7674 -141.0462)
		(end 475.3102 -141.0462)
		(width 0.10795)
		(layer "F.Cu")
		(net "FM_PWR_LED")
	)
	(segment
		(start 475.107 -139.573)
		(end 475.2213 -139.6873)
		(width 0.10795)
		(layer "F.Cu")
		(net "FM_PWR_LED")
	)
	(segment
		(start 475.2213 -139.6873)
		(end 475.2213 -140.335)
		(width 0.10795)
		(layer "F.Cu")
		(net "FM_PWR_LED")
	)
	(segment
		(start 475.87154 -140.335)
		(end 475.87154 -140.94206)
		(width 0.10795)
		(layer "F.Cu")
		(net "FM_PWR_LED")
	)
	(segment
		(start 426.068998 -68.735194)
		(end 428.034958 -66.769234)
		(width 0.10795)
		(layer "F.Cu")
		(net "FM_PMBUS_ALERT_BUF_EN_N")
	)
	(segment
		(start 422.596056 -78.79588)
		(end 422.946068 -78.79588)
		(width 0.10795)
		(layer "F.Cu")
		(net "FM_PMBUS_ALERT_BUF_EN_N")
	)
	(segment
		(start 423.229278 -78.51267)
		(end 423.229278 -76.278994)
		(width 0.10795)
		(layer "F.Cu")
		(net "FM_PMBUS_ALERT_BUF_EN_N")
	)
	(segment
		(start 413.068008 -83.906614)
		(end 414.069276 -82.905346)
		(width 0.10795)
		(layer "F.Cu")
		(net "FM_PMBUS_ALERT_BUF_EN_N")
	)
	(segment
		(start 414.23336 -82.905346)
		(end 414.664398 -82.474308)
		(width 0.10795)
		(layer "F.Cu")
		(net "FM_PMBUS_ALERT_BUF_EN_N")
	)
	(segment
		(start 429.103536 -66.769234)
		(end 429.12157 -66.7512)
		(width 0.10795)
		(layer "F.Cu")
		(net "FM_PMBUS_ALERT_BUF_EN_N")
	)
	(segment
		(start 411.34538 -83.906614)
		(end 413.068008 -83.906614)
		(width 0.10795)
		(layer "F.Cu")
		(net "FM_PMBUS_ALERT_BUF_EN_N")
	)
	(segment
		(start 414.664398 -82.474308)
		(end 414.664398 -82.472276)
		(width 0.10795)
		(layer "F.Cu")
		(net "FM_PMBUS_ALERT_BUF_EN_N")
	)
	(segment
		(start 421.922956 -78.12278)
		(end 422.596056 -78.79588)
		(width 0.10795)
		(layer "F.Cu")
		(net "FM_PMBUS_ALERT_BUF_EN_N")
	)
	(segment
		(start 417.41979 -78.425802)
		(end 418.983668 -78.425802)
		(width 0.10795)
		(layer "F.Cu")
		(net "FM_PMBUS_ALERT_BUF_EN_N")
	)
	(segment
		(start 422.946068 -78.79588)
		(end 423.229278 -78.51267)
		(width 0.10795)
		(layer "F.Cu")
		(net "FM_PMBUS_ALERT_BUF_EN_N")
	)
	(segment
		(start 469.802464 -57.582054)
		(end 471.645996 -55.738522)
		(width 0.10795)
		(layer "F.Cu")
		(net "FM_PMBUS_ALERT_BUF_EN_N")
	)
	(segment
		(start 415.400998 -80.444594)
		(end 416.410902 -79.43469)
		(width 0.10795)
		(layer "F.Cu")
		(net "FM_PMBUS_ALERT_BUF_EN_N")
	)
	(segment
		(start 414.664398 -82.472276)
		(end 415.400998 -81.735676)
		(width 0.10795)
		(layer "F.Cu")
		(net "FM_PMBUS_ALERT_BUF_EN_N")
	)
	(segment
		(start 411.453838 -85.378544)
		(end 411.097984 -85.02269)
		(width 0.10795)
		(layer "F.Cu")
		(net "FM_PMBUS_ALERT_BUF_EN_N")
	)
	(segment
		(start 467.711028 -63.841884)
		(end 469.802464 -61.750448)
		(width 0.10795)
		(layer "F.Cu")
		(net "FM_PMBUS_ALERT_BUF_EN_N")
	)
	(segment
		(start 418.983668 -78.425802)
		(end 419.28669 -78.12278)
		(width 0.10795)
		(layer "F.Cu")
		(net "FM_PMBUS_ALERT_BUF_EN_N")
	)
	(segment
		(start 426.068998 -73.439274)
		(end 426.068998 -68.735194)
		(width 0.10795)
		(layer "F.Cu")
		(net "FM_PMBUS_ALERT_BUF_EN_N")
	)
	(segment
		(start 467.711028 -64.888618)
		(end 467.711028 -63.841884)
		(width 0.10795)
		(layer "F.Cu")
		(net "FM_PMBUS_ALERT_BUF_EN_N")
	)
	(segment
		(start 414.069276 -82.905346)
		(end 414.23336 -82.905346)
		(width 0.10795)
		(layer "F.Cu")
		(net "FM_PMBUS_ALERT_BUF_EN_N")
	)
	(segment
		(start 429.12157 -66.7512)
		(end 465.848446 -66.7512)
		(width 0.10795)
		(layer "F.Cu")
		(net "FM_PMBUS_ALERT_BUF_EN_N")
	)
	(segment
		(start 469.802464 -61.750448)
		(end 469.802464 -57.582054)
		(width 0.10795)
		(layer "F.Cu")
		(net "FM_PMBUS_ALERT_BUF_EN_N")
	)
	(segment
		(start 416.410902 -79.43469)
		(end 417.41979 -78.425802)
		(width 0.10795)
		(layer "F.Cu")
		(net "FM_PMBUS_ALERT_BUF_EN_N")
	)
	(segment
		(start 411.097984 -84.15401)
		(end 411.34538 -83.906614)
		(width 0.10795)
		(layer "F.Cu")
		(net "FM_PMBUS_ALERT_BUF_EN_N")
	)
	(segment
		(start 423.229278 -76.278994)
		(end 426.068998 -73.439274)
		(width 0.10795)
		(layer "F.Cu")
		(net "FM_PMBUS_ALERT_BUF_EN_N")
	)
	(segment
		(start 415.400998 -81.735676)
		(end 415.400998 -80.444594)
		(width 0.10795)
		(layer "F.Cu")
		(net "FM_PMBUS_ALERT_BUF_EN_N")
	)
	(segment
		(start 428.034958 -66.769234)
		(end 429.103536 -66.769234)
		(width 0.10795)
		(layer "F.Cu")
		(net "FM_PMBUS_ALERT_BUF_EN_N")
	)
	(segment
		(start 465.848446 -66.7512)
		(end 467.711028 -64.888618)
		(width 0.10795)
		(layer "F.Cu")
		(net "FM_PMBUS_ALERT_BUF_EN_N")
	)
	(segment
		(start 411.097984 -85.02269)
		(end 411.097984 -84.15401)
		(width 0.10795)
		(layer "F.Cu")
		(net "FM_PMBUS_ALERT_BUF_EN_N")
	)
	(segment
		(start 419.28669 -78.12278)
		(end 421.922956 -78.12278)
		(width 0.10795)
		(layer "F.Cu")
		(net "FM_PMBUS_ALERT_BUF_EN_N")
	)
	(via
		(at 424.7388 -28.4988)
		(size 0.508)
		(drill 0.254)
		(layers "F.Cu" "B.Cu")
		(net "FM_PMBUS_ALERT_BUF_EN_N")
	)
	(via
		(at 471.645996 -55.738522)
		(size 0.508)
		(drill 0.254)
		(layers "F.Cu" "B.Cu")
		(net "FM_PMBUS_ALERT_BUF_EN_N")
	)
	(via
		(at 422.0464 -84.6074)
		(size 0.6604)
		(drill 0.3302)
		(layers "F.Cu" "B.Cu")
		(net "FM_PMBUS_ALERT_BUF_EN_N")
	)
	(via
		(at 416.410902 -79.43469)
		(size 0.508)
		(drill 0.254)
		(layers "F.Cu" "B.Cu")
		(net "FM_PMBUS_ALERT_BUF_EN_N")
	)
	(via
		(at 411.453838 -85.378544)
		(size 0.508)
		(drill 0.254)
		(layers "F.Cu" "B.Cu")
		(net "FM_PMBUS_ALERT_BUF_EN_N")
	)
	(segment
		(start 421.1955 -79.9465)
		(end 420.3065 -79.9465)
		(width 0.10795)
		(layer "B.Cu")
		(net "FM_PMBUS_ALERT_BUF_EN_N")
	)
	(segment
		(start 393.581128 -88.314784)
		(end 393.581128 -87.745316)
		(width 0.10795)
		(layer "B.Cu")
		(net "FM_PMBUS_ALERT_BUF_EN_N")
	)
	(segment
		(start 422.2242 -83.1342)
		(end 422.2242 -84.4296)
		(width 0.10795)
		(layer "B.Cu")
		(net "FM_PMBUS_ALERT_BUF_EN_N")
	)
	(segment
		(start 417.38169 -78.463902)
		(end 416.410902 -79.43469)
		(width 0.10795)
		(layer "B.Cu")
		(net "FM_PMBUS_ALERT_BUF_EN_N")
	)
	(segment
		(start 407.057352 -84.9249)
		(end 407.58364 -84.398612)
		(width 0.10795)
		(layer "B.Cu")
		(net "FM_PMBUS_ALERT_BUF_EN_N")
	)
	(segment
		(start 398.308068 -82.672682)
		(end 400.024346 -84.38896)
		(width 0.10795)
		(layer "B.Cu")
		(net "FM_PMBUS_ALERT_BUF_EN_N")
	)
	(segment
		(start 421.8305 -80.5815)
		(end 422.2242 -80.9752)
		(width 0.10795)
		(layer "B.Cu")
		(net "FM_PMBUS_ALERT_BUF_EN_N")
	)
	(segment
		(start 421.513 -80.5815)
		(end 421.513 -80.264)
		(width 0.10795)
		(layer "B.Cu")
		(net "FM_PMBUS_ALERT_BUF_EN_N")
	)
	(segment
		(start 393.581128 -87.745316)
		(end 394.15339 -87.173054)
		(width 0.10795)
		(layer "B.Cu")
		(net "FM_PMBUS_ALERT_BUF_EN_N")
	)
	(segment
		(start 400.024346 -84.38896)
		(end 402.572728 -84.38896)
		(width 0.10795)
		(layer "B.Cu")
		(net "FM_PMBUS_ALERT_BUF_EN_N")
	)
	(segment
		(start 424.815 -28.4226)
		(end 424.7388 -28.4988)
		(width 0.089408)
		(layer "B.Cu")
		(net "FM_PMBUS_ALERT_BUF_EN_N")
	)
	(segment
		(start 394.15339 -84.10067)
		(end 395.581378 -82.672682)
		(width 0.10795)
		(layer "B.Cu")
		(net "FM_PMBUS_ALERT_BUF_EN_N")
	)
	(segment
		(start 424.815 -27.8892)
		(end 424.815 -28.4226)
		(width 0.089408)
		(layer "B.Cu")
		(net "FM_PMBUS_ALERT_BUF_EN_N")
	)
	(segment
		(start 395.581378 -82.672682)
		(end 398.308068 -82.672682)
		(width 0.10795)
		(layer "B.Cu")
		(net "FM_PMBUS_ALERT_BUF_EN_N")
	)
	(segment
		(start 421.513 -80.5815)
		(end 421.8305 -80.5815)
		(width 0.10795)
		(layer "B.Cu")
		(net "FM_PMBUS_ALERT_BUF_EN_N")
	)
	(segment
		(start 402.572728 -84.38896)
		(end 403.108668 -84.9249)
		(width 0.10795)
		(layer "B.Cu")
		(net "FM_PMBUS_ALERT_BUF_EN_N")
	)
	(segment
		(start 403.108668 -84.9249)
		(end 407.057352 -84.9249)
		(width 0.10795)
		(layer "B.Cu")
		(net "FM_PMBUS_ALERT_BUF_EN_N")
	)
	(segment
		(start 422.2242 -80.9752)
		(end 422.2242 -83.1342)
		(width 0.10795)
		(layer "B.Cu")
		(net "FM_PMBUS_ALERT_BUF_EN_N")
	)
	(segment
		(start 393.3952 -88.627712)
		(end 393.581128 -88.441784)
		(width 0.10795)
		(layer "B.Cu")
		(net "FM_PMBUS_ALERT_BUF_EN_N")
	)
	(segment
		(start 394.15339 -87.173054)
		(end 394.15339 -84.10067)
		(width 0.10795)
		(layer "B.Cu")
		(net "FM_PMBUS_ALERT_BUF_EN_N")
	)
	(segment
		(start 407.58364 -84.398612)
		(end 409.993846 -84.398612)
		(width 0.10795)
		(layer "B.Cu")
		(net "FM_PMBUS_ALERT_BUF_EN_N")
	)
	(segment
		(start 410.973778 -85.378544)
		(end 411.453838 -85.378544)
		(width 0.10795)
		(layer "B.Cu")
		(net "FM_PMBUS_ALERT_BUF_EN_N")
	)
	(segment
		(start 393.581128 -88.441784)
		(end 393.581128 -88.314784)
		(width 0.10795)
		(layer "B.Cu")
		(net "FM_PMBUS_ALERT_BUF_EN_N")
	)
	(segment
		(start 421.513 -80.264)
		(end 421.1955 -79.9465)
		(width 0.10795)
		(layer "B.Cu")
		(net "FM_PMBUS_ALERT_BUF_EN_N")
	)
	(segment
		(start 420.3065 -79.9465)
		(end 420.3065 -79.509366)
		(width 0.10795)
		(layer "B.Cu")
		(net "FM_PMBUS_ALERT_BUF_EN_N")
	)
	(segment
		(start 393.3952 -89.436956)
		(end 393.3952 -88.627712)
		(width 0.10795)
		(layer "B.Cu")
		(net "FM_PMBUS_ALERT_BUF_EN_N")
	)
	(segment
		(start 420.3065 -79.509366)
		(end 419.261036 -78.463902)
		(width 0.10795)
		(layer "B.Cu")
		(net "FM_PMBUS_ALERT_BUF_EN_N")
	)
	(segment
		(start 409.993846 -84.398612)
		(end 410.973778 -85.378544)
		(width 0.10795)
		(layer "B.Cu")
		(net "FM_PMBUS_ALERT_BUF_EN_N")
	)
	(segment
		(start 419.261036 -78.463902)
		(end 417.38169 -78.463902)
		(width 0.10795)
		(layer "B.Cu")
		(net "FM_PMBUS_ALERT_BUF_EN_N")
	)
	(segment
		(start 393.581128 -89.622884)
		(end 393.3952 -89.436956)
		(width 0.10795)
		(layer "B.Cu")
		(net "FM_PMBUS_ALERT_BUF_EN_N")
	)
	(segment
		(start 422.2242 -84.4296)
		(end 422.0464 -84.6074)
		(width 0.10795)
		(layer "B.Cu")
		(net "FM_PMBUS_ALERT_BUF_EN_N")
	)
	(segment
		(start 461.379062 -34.917634)
		(end 461.17891 -34.917634)
		(width 0.089408)
		(layer "In4.Cu")
		(net "FM_PMBUS_ALERT_BUF_EN_N")
	)
	(segment
		(start 430.0982 -28.243022)
		(end 430.088548 -28.243022)
		(width 0.089408)
		(layer "In4.Cu")
		(net "FM_PMBUS_ALERT_BUF_EN_N")
	)
	(segment
		(start 471.645996 -55.738522)
		(end 472.119452 -56.211978)
		(width 0.089408)
		(layer "In4.Cu")
		(net "FM_PMBUS_ALERT_BUF_EN_N")
	)
	(segment
		(start 471.381582 -39.222426)
		(end 470.632282 -38.473126)
		(width 0.089408)
		(layer "In4.Cu")
		(net "FM_PMBUS_ALERT_BUF_EN_N")
	)
	(segment
		(start 435.982872 -23.83155)
		(end 433.033678 -26.780744)
		(width 0.089408)
		(layer "In4.Cu")
		(net "FM_PMBUS_ALERT_BUF_EN_N")
	)
	(segment
		(start 474.442282 -53.808884)
		(end 474.442282 -53.134006)
		(width 0.089408)
		(layer "In4.Cu")
		(net "FM_PMBUS_ALERT_BUF_EN_N")
	)
	(segment
		(start 458.25283 -33.877758)
		(end 458.043026 -34.087562)
		(width 0.089408)
		(layer "In4.Cu")
		(net "FM_PMBUS_ALERT_BUF_EN_N")
	)
	(segment
		(start 447.87947 -30.122622)
		(end 447.212466 -29.455618)
		(width 0.089408)
		(layer "In4.Cu")
		(net "FM_PMBUS_ALERT_BUF_EN_N")
	)
	(segment
		(start 448.11061 -30.65653)
		(end 447.87947 -30.42539)
		(width 0.089408)
		(layer "In4.Cu")
		(net "FM_PMBUS_ALERT_BUF_EN_N")
	)
	(segment
		(start 473.85224 -56.211978)
		(end 474.42247 -55.641748)
		(width 0.089408)
		(layer "In4.Cu")
		(net "FM_PMBUS_ALERT_BUF_EN_N")
	)
	(segment
		(start 474.285818 -52.977542)
		(end 474.285818 -51.390296)
		(width 0.089408)
		(layer "In4.Cu")
		(net "FM_PMBUS_ALERT_BUF_EN_N")
	)
	(segment
		(start 462.65719 -34.917888)
		(end 461.537812 -34.917888)
		(width 0.089408)
		(layer "In4.Cu")
		(net "FM_PMBUS_ALERT_BUF_EN_N")
	)
	(segment
		(start 474.42247 -55.641748)
		(end 474.42247 -55.416958)
		(width 0.089408)
		(layer "In4.Cu")
		(net "FM_PMBUS_ALERT_BUF_EN_N")
	)
	(segment
		(start 447.212466 -29.455618)
		(end 446.340738 -29.455618)
		(width 0.089408)
		(layer "In4.Cu")
		(net "FM_PMBUS_ALERT_BUF_EN_N")
	)
	(segment
		(start 466.926422 -36.99637)
		(end 465.300568 -35.371278)
		(width 0.089408)
		(layer "In4.Cu")
		(net "FM_PMBUS_ALERT_BUF_EN_N")
	)
	(segment
		(start 433.033678 -26.780744)
		(end 431.560478 -26.780744)
		(width 0.089408)
		(layer "In4.Cu")
		(net "FM_PMBUS_ALERT_BUF_EN_N")
	)
	(segment
		(start 474.285818 -51.390296)
		(end 474.897958 -50.778156)
		(width 0.089408)
		(layer "In4.Cu")
		(net "FM_PMBUS_ALERT_BUF_EN_N")
	)
	(segment
		(start 431.560478 -26.780744)
		(end 430.0982 -28.243022)
		(width 0.089408)
		(layer "In4.Cu")
		(net "FM_PMBUS_ALERT_BUF_EN_N")
	)
	(segment
		(start 447.87947 -30.42539)
		(end 447.87947 -30.122622)
		(width 0.089408)
		(layer "In4.Cu")
		(net "FM_PMBUS_ALERT_BUF_EN_N")
	)
	(segment
		(start 441.308236 -24.097996)
		(end 437.991758 -24.097996)
		(width 0.089408)
		(layer "In4.Cu")
		(net "FM_PMBUS_ALERT_BUF_EN_N")
	)
	(segment
		(start 445.139064 -28.253944)
		(end 445.139064 -24.721312)
		(width 0.089408)
		(layer "In4.Cu")
		(net "FM_PMBUS_ALERT_BUF_EN_N")
	)
	(segment
		(start 472.598496 -43.420284)
		(end 472.598496 -39.558722)
		(width 0.089408)
		(layer "In4.Cu")
		(net "FM_PMBUS_ALERT_BUF_EN_N")
	)
	(segment
		(start 472.2622 -39.222426)
		(end 471.381582 -39.222426)
		(width 0.089408)
		(layer "In4.Cu")
		(net "FM_PMBUS_ALERT_BUF_EN_N")
	)
	(segment
		(start 472.8845 -43.706288)
		(end 472.598496 -43.420284)
		(width 0.089408)
		(layer "In4.Cu")
		(net "FM_PMBUS_ALERT_BUF_EN_N")
	)
	(segment
		(start 461.379316 -34.91738)
		(end 461.379062 -34.917634)
		(width 0.089408)
		(layer "In4.Cu")
		(net "FM_PMBUS_ALERT_BUF_EN_N")
	)
	(segment
		(start 468.805768 -38.473126)
		(end 467.329012 -36.99637)
		(width 0.089408)
		(layer "In4.Cu")
		(net "FM_PMBUS_ALERT_BUF_EN_N")
	)
	(segment
		(start 474.442282 -53.134006)
		(end 474.285818 -52.977542)
		(width 0.089408)
		(layer "In4.Cu")
		(net "FM_PMBUS_ALERT_BUF_EN_N")
	)
	(segment
		(start 474.897958 -44.584366)
		(end 474.01988 -43.706288)
		(width 0.089408)
		(layer "In4.Cu")
		(net "FM_PMBUS_ALERT_BUF_EN_N")
	)
	(segment
		(start 461.537304 -34.91738)
		(end 461.379316 -34.91738)
		(width 0.089408)
		(layer "In4.Cu")
		(net "FM_PMBUS_ALERT_BUF_EN_N")
	)
	(segment
		(start 470.632282 -38.473126)
		(end 468.805768 -38.473126)
		(width 0.089408)
		(layer "In4.Cu")
		(net "FM_PMBUS_ALERT_BUF_EN_N")
	)
	(segment
		(start 474.440504 -55.398924)
		(end 474.440504 -53.810662)
		(width 0.089408)
		(layer "In4.Cu")
		(net "FM_PMBUS_ALERT_BUF_EN_N")
	)
	(segment
		(start 459.757272 -33.877758)
		(end 458.25283 -33.877758)
		(width 0.089408)
		(layer "In4.Cu")
		(net "FM_PMBUS_ALERT_BUF_EN_N")
	)
	(segment
		(start 430.088548 -28.243022)
		(end 429.83277 -28.4988)
		(width 0.089408)
		(layer "In4.Cu")
		(net "FM_PMBUS_ALERT_BUF_EN_N")
	)
	(segment
		(start 461.537812 -34.917888)
		(end 461.537304 -34.91738)
		(width 0.089408)
		(layer "In4.Cu")
		(net "FM_PMBUS_ALERT_BUF_EN_N")
	)
	(segment
		(start 474.897958 -50.778156)
		(end 474.897958 -44.584366)
		(width 0.089408)
		(layer "In4.Cu")
		(net "FM_PMBUS_ALERT_BUF_EN_N")
	)
	(segment
		(start 442.094366 -23.311866)
		(end 441.308236 -24.097996)
		(width 0.089408)
		(layer "In4.Cu")
		(net "FM_PMBUS_ALERT_BUF_EN_N")
	)
	(segment
		(start 472.119452 -56.211978)
		(end 473.85224 -56.211978)
		(width 0.089408)
		(layer "In4.Cu")
		(net "FM_PMBUS_ALERT_BUF_EN_N")
	)
	(segment
		(start 437.725312 -23.83155)
		(end 435.982872 -23.83155)
		(width 0.089408)
		(layer "In4.Cu")
		(net "FM_PMBUS_ALERT_BUF_EN_N")
	)
	(segment
		(start 474.01988 -43.706288)
		(end 472.8845 -43.706288)
		(width 0.089408)
		(layer "In4.Cu")
		(net "FM_PMBUS_ALERT_BUF_EN_N")
	)
	(segment
		(start 445.139064 -24.721312)
		(end 443.729618 -23.311866)
		(width 0.089408)
		(layer "In4.Cu")
		(net "FM_PMBUS_ALERT_BUF_EN_N")
	)
	(segment
		(start 458.043026 -34.087562)
		(end 452.839074 -34.087562)
		(width 0.089408)
		(layer "In4.Cu")
		(net "FM_PMBUS_ALERT_BUF_EN_N")
	)
	(segment
		(start 449.408042 -30.65653)
		(end 448.11061 -30.65653)
		(width 0.089408)
		(layer "In4.Cu")
		(net "FM_PMBUS_ALERT_BUF_EN_N")
	)
	(segment
		(start 461.178656 -34.917888)
		(end 460.797402 -34.917888)
		(width 0.089408)
		(layer "In4.Cu")
		(net "FM_PMBUS_ALERT_BUF_EN_N")
	)
	(segment
		(start 429.83277 -28.4988)
		(end 424.7388 -28.4988)
		(width 0.089408)
		(layer "In4.Cu")
		(net "FM_PMBUS_ALERT_BUF_EN_N")
	)
	(segment
		(start 460.797402 -34.917888)
		(end 459.757272 -33.877758)
		(width 0.089408)
		(layer "In4.Cu")
		(net "FM_PMBUS_ALERT_BUF_EN_N")
	)
	(segment
		(start 465.300568 -35.371278)
		(end 463.11058 -35.371278)
		(width 0.089408)
		(layer "In4.Cu")
		(net "FM_PMBUS_ALERT_BUF_EN_N")
	)
	(segment
		(start 474.42247 -55.416958)
		(end 474.440504 -55.398924)
		(width 0.089408)
		(layer "In4.Cu")
		(net "FM_PMBUS_ALERT_BUF_EN_N")
	)
	(segment
		(start 463.11058 -35.371278)
		(end 462.65719 -34.917888)
		(width 0.089408)
		(layer "In4.Cu")
		(net "FM_PMBUS_ALERT_BUF_EN_N")
	)
	(segment
		(start 446.340738 -29.455618)
		(end 445.139064 -28.253944)
		(width 0.089408)
		(layer "In4.Cu")
		(net "FM_PMBUS_ALERT_BUF_EN_N")
	)
	(segment
		(start 443.729618 -23.311866)
		(end 442.094366 -23.311866)
		(width 0.089408)
		(layer "In4.Cu")
		(net "FM_PMBUS_ALERT_BUF_EN_N")
	)
	(segment
		(start 461.17891 -34.917634)
		(end 461.178656 -34.917888)
		(width 0.089408)
		(layer "In4.Cu")
		(net "FM_PMBUS_ALERT_BUF_EN_N")
	)
	(segment
		(start 467.329012 -36.99637)
		(end 466.926422 -36.99637)
		(width 0.089408)
		(layer "In4.Cu")
		(net "FM_PMBUS_ALERT_BUF_EN_N")
	)
	(segment
		(start 474.440504 -53.810662)
		(end 474.442282 -53.808884)
		(width 0.089408)
		(layer "In4.Cu")
		(net "FM_PMBUS_ALERT_BUF_EN_N")
	)
	(segment
		(start 452.839074 -34.087562)
		(end 449.408042 -30.65653)
		(width 0.089408)
		(layer "In4.Cu")
		(net "FM_PMBUS_ALERT_BUF_EN_N")
	)
	(segment
		(start 437.991758 -24.097996)
		(end 437.725312 -23.83155)
		(width 0.089408)
		(layer "In4.Cu")
		(net "FM_PMBUS_ALERT_BUF_EN_N")
	)
	(segment
		(start 472.598496 -39.558722)
		(end 472.2622 -39.222426)
		(width 0.089408)
		(layer "In4.Cu")
		(net "FM_PMBUS_ALERT_BUF_EN_N")
	)
	(segment
		(start 395.66215 -100.41128)
		(end 396.145004 -100.186998)
		(width 0.10795)
		(layer "F.Cu")
		(net "FM_FAST_PROCHOT_EN_N")
	)
	(segment
		(start 396.145004 -100.186998)
		(end 396.15745 -100.181156)
		(width 0.10795)
		(layer "F.Cu")
		(net "FM_FAST_PROCHOT_EN_N")
	)
	(segment
		(start 408.432 -25.2476)
		(end 408.690064 -25.505664)
		(width 0.10795)
		(layer "F.Cu")
		(net "FM_FAST_PROCHOT_EN_N")
	)
	(segment
		(start 408.690064 -25.505664)
		(end 408.690064 -26.534618)
		(width 0.10795)
		(layer "F.Cu")
		(net "FM_FAST_PROCHOT_EN_N")
	)
	(via
		(at 396.15745 -100.181156)
		(size 0.508)
		(drill 0.254)
		(layers "F.Cu" "B.Cu")
		(net "FM_FAST_PROCHOT_EN_N")
	)
	(via
		(at 468.749126 -34.417)
		(size 0.508)
		(drill 0.254)
		(layers "F.Cu" "B.Cu")
		(net "FM_FAST_PROCHOT_EN_N")
	)
	(via
		(at 408.432 -25.2476)
		(size 0.4572)
		(drill 0.2032)
		(layers "F.Cu" "B.Cu")
		(net "FM_FAST_PROCHOT_EN_N")
	)
	(via
		(at 415.866326 -67.162934)
		(size 0.508)
		(drill 0.254)
		(layers "F.Cu" "B.Cu")
		(net "FM_FAST_PROCHOT_EN_N")
	)
	(via
		(at 417.7538 -66.2686)
		(size 0.6604)
		(drill 0.3302)
		(layers "F.Cu" "B.Cu")
		(net "FM_FAST_PROCHOT_EN_N")
	)
	(segment
		(start 418.3634 -66.8782)
		(end 418.3634 -71.75881)
		(width 0.10795)
		(layer "B.Cu")
		(net "FM_FAST_PROCHOT_EN_N")
	)
	(segment
		(start 415.866326 -67.162934)
		(end 416.859466 -67.162934)
		(width 0.10795)
		(layer "B.Cu")
		(net "FM_FAST_PROCHOT_EN_N")
	)
	(segment
		(start 417.7538 -66.2686)
		(end 418.3634 -66.8782)
		(width 0.10795)
		(layer "B.Cu")
		(net "FM_FAST_PROCHOT_EN_N")
	)
	(segment
		(start 418.4142 -73.1647)
		(end 418.5793 -73.1647)
		(width 0.10795)
		(layer "B.Cu")
		(net "FM_FAST_PROCHOT_EN_N")
	)
	(segment
		(start 419.6715 -72.0725)
		(end 419.6715 -71.9455)
		(width 0.10795)
		(layer "B.Cu")
		(net "FM_FAST_PROCHOT_EN_N")
	)
	(segment
		(start 418.5793 -73.1647)
		(end 419.6715 -72.0725)
		(width 0.10795)
		(layer "B.Cu")
		(net "FM_FAST_PROCHOT_EN_N")
	)
	(segment
		(start 416.859466 -67.162934)
		(end 417.7538 -66.2686)
		(width 0.10795)
		(layer "B.Cu")
		(net "FM_FAST_PROCHOT_EN_N")
	)
	(segment
		(start 418.1602 -71.96201)
		(end 418.1602 -72.9107)
		(width 0.10795)
		(layer "B.Cu")
		(net "FM_FAST_PROCHOT_EN_N")
	)
	(segment
		(start 418.1602 -72.9107)
		(end 418.4142 -73.1647)
		(width 0.10795)
		(layer "B.Cu")
		(net "FM_FAST_PROCHOT_EN_N")
	)
	(segment
		(start 418.3634 -71.75881)
		(end 418.1602 -71.96201)
		(width 0.10795)
		(layer "B.Cu")
		(net "FM_FAST_PROCHOT_EN_N")
	)
	(segment
		(start 448.681856 -24.403304)
		(end 449.497196 -24.403304)
		(width 0.089408)
		(layer "In4.Cu")
		(net "FM_FAST_PROCHOT_EN_N")
	)
	(segment
		(start 445.119252 -20.892516)
		(end 445.253618 -20.75815)
		(width 0.089408)
		(layer "In4.Cu")
		(net "FM_FAST_PROCHOT_EN_N")
	)
	(segment
		(start 408.7368 -25.2476)
		(end 409.439872 -24.544528)
		(width 0.089408)
		(layer "In4.Cu")
		(net "FM_FAST_PROCHOT_EN_N")
	)
	(segment
		(start 462.35874 -30.834076)
		(end 464.631278 -33.106614)
		(width 0.089408)
		(layer "In4.Cu")
		(net "FM_FAST_PROCHOT_EN_N")
	)
	(segment
		(start 411.433518 -23.970996)
		(end 413.93618 -23.970996)
		(width 0.089408)
		(layer "In4.Cu")
		(net "FM_FAST_PROCHOT_EN_N")
	)
	(segment
		(start 410.859986 -24.544528)
		(end 411.433518 -23.970996)
		(width 0.089408)
		(layer "In4.Cu")
		(net "FM_FAST_PROCHOT_EN_N")
	)
	(segment
		(start 426.058584 -24.120856)
		(end 426.450252 -23.729188)
		(width 0.089408)
		(layer "In4.Cu")
		(net "FM_FAST_PROCHOT_EN_N")
	)
	(segment
		(start 467.43874 -33.106614)
		(end 468.749126 -34.417)
		(width 0.089408)
		(layer "In4.Cu")
		(net "FM_FAST_PROCHOT_EN_N")
	)
	(segment
		(start 460.534258 -27.768804)
		(end 462.35874 -29.593286)
		(width 0.089408)
		(layer "In4.Cu")
		(net "FM_FAST_PROCHOT_EN_N")
	)
	(segment
		(start 450.24675 -24.431752)
		(end 453.583802 -27.768804)
		(width 0.089408)
		(layer "In4.Cu")
		(net "FM_FAST_PROCHOT_EN_N")
	)
	(segment
		(start 447.749676 -23.471124)
		(end 448.681856 -24.403304)
		(width 0.089408)
		(layer "In4.Cu")
		(net "FM_FAST_PROCHOT_EN_N")
	)
	(segment
		(start 449.525644 -24.431752)
		(end 450.24675 -24.431752)
		(width 0.089408)
		(layer "In4.Cu")
		(net "FM_FAST_PROCHOT_EN_N")
	)
	(segment
		(start 426.450252 -23.729188)
		(end 427.386496 -23.729188)
		(width 0.089408)
		(layer "In4.Cu")
		(net "FM_FAST_PROCHOT_EN_N")
	)
	(segment
		(start 422.20769 -24.120856)
		(end 426.058584 -24.120856)
		(width 0.089408)
		(layer "In4.Cu")
		(net "FM_FAST_PROCHOT_EN_N")
	)
	(segment
		(start 427.859444 -23.25624)
		(end 431.350674 -23.25624)
		(width 0.089408)
		(layer "In4.Cu")
		(net "FM_FAST_PROCHOT_EN_N")
	)
	(segment
		(start 462.35874 -29.593286)
		(end 462.35874 -30.834076)
		(width 0.089408)
		(layer "In4.Cu")
		(net "FM_FAST_PROCHOT_EN_N")
	)
	(segment
		(start 414.339786 -23.56739)
		(end 421.654224 -23.56739)
		(width 0.089408)
		(layer "In4.Cu")
		(net "FM_FAST_PROCHOT_EN_N")
	)
	(segment
		(start 453.583802 -27.768804)
		(end 460.534258 -27.768804)
		(width 0.089408)
		(layer "In4.Cu")
		(net "FM_FAST_PROCHOT_EN_N")
	)
	(segment
		(start 431.350674 -23.25624)
		(end 433.714398 -20.892516)
		(width 0.089408)
		(layer "In4.Cu")
		(net "FM_FAST_PROCHOT_EN_N")
	)
	(segment
		(start 447.102484 -20.75815)
		(end 447.749676 -21.405342)
		(width 0.089408)
		(layer "In4.Cu")
		(net "FM_FAST_PROCHOT_EN_N")
	)
	(segment
		(start 409.439872 -24.544528)
		(end 410.859986 -24.544528)
		(width 0.089408)
		(layer "In4.Cu")
		(net "FM_FAST_PROCHOT_EN_N")
	)
	(segment
		(start 408.432 -25.2476)
		(end 408.7368 -25.2476)
		(width 0.089408)
		(layer "In4.Cu")
		(net "FM_FAST_PROCHOT_EN_N")
	)
	(segment
		(start 413.93618 -23.970996)
		(end 414.339786 -23.56739)
		(width 0.089408)
		(layer "In4.Cu")
		(net "FM_FAST_PROCHOT_EN_N")
	)
	(segment
		(start 447.749676 -21.405342)
		(end 447.749676 -23.471124)
		(width 0.089408)
		(layer "In4.Cu")
		(net "FM_FAST_PROCHOT_EN_N")
	)
	(segment
		(start 445.253618 -20.75815)
		(end 447.102484 -20.75815)
		(width 0.089408)
		(layer "In4.Cu")
		(net "FM_FAST_PROCHOT_EN_N")
	)
	(segment
		(start 433.714398 -20.892516)
		(end 445.119252 -20.892516)
		(width 0.089408)
		(layer "In4.Cu")
		(net "FM_FAST_PROCHOT_EN_N")
	)
	(segment
		(start 464.631278 -33.106614)
		(end 467.43874 -33.106614)
		(width 0.089408)
		(layer "In4.Cu")
		(net "FM_FAST_PROCHOT_EN_N")
	)
	(segment
		(start 421.654224 -23.56739)
		(end 422.20769 -24.120856)
		(width 0.089408)
		(layer "In4.Cu")
		(net "FM_FAST_PROCHOT_EN_N")
	)
	(segment
		(start 449.497196 -24.403304)
		(end 449.525644 -24.431752)
		(width 0.089408)
		(layer "In4.Cu")
		(net "FM_FAST_PROCHOT_EN_N")
	)
	(segment
		(start 427.386496 -23.729188)
		(end 427.859444 -23.25624)
		(width 0.089408)
		(layer "In4.Cu")
		(net "FM_FAST_PROCHOT_EN_N")
	)
	(segment
		(start 436.047642 -52.506118)
		(end 436.021226 -52.532534)
		(width 0.089408)
		(layer "In9.Cu")
		(net "FM_FAST_PROCHOT_EN_N")
	)
	(segment
		(start 462.0768 -36.043362)
		(end 462.0768 -37.74059)
		(width 0.089408)
		(layer "In9.Cu")
		(net "FM_FAST_PROCHOT_EN_N")
	)
	(segment
		(start 410.544518 -84.633562)
		(end 410.544518 -86.15807)
		(width 0.089408)
		(layer "In9.Cu")
		(net "FM_FAST_PROCHOT_EN_N")
	)
	(segment
		(start 463.702908 -34.417)
		(end 462.840324 -35.279584)
		(width 0.089408)
		(layer "In9.Cu")
		(net "FM_FAST_PROCHOT_EN_N")
	)
	(segment
		(start 415.542222 -67.487038)
		(end 415.542222 -67.931284)
		(width 0.089408)
		(layer "In9.Cu")
		(net "FM_FAST_PROCHOT_EN_N")
	)
	(segment
		(start 407.958036 -87.835994)
		(end 406.940258 -88.853772)
		(width 0.089408)
		(layer "In9.Cu")
		(net "FM_FAST_PROCHOT_EN_N")
	)
	(segment
		(start 414.526222 -72.403716)
		(end 414.526222 -78.838298)
		(width 0.089408)
		(layer "In9.Cu")
		(net "FM_FAST_PROCHOT_EN_N")
	)
	(segment
		(start 415.674556 -64.01054)
		(end 415.46907 -64.216026)
		(width 0.089408)
		(layer "In9.Cu")
		(net "FM_FAST_PROCHOT_EN_N")
	)
	(segment
		(start 402.614892 -97.53473)
		(end 400.136868 -100.012754)
		(width 0.089408)
		(layer "In9.Cu")
		(net "FM_FAST_PROCHOT_EN_N")
	)
	(segment
		(start 399.03273 -100.84181)
		(end 399.03273 -101.20503)
		(width 0.089408)
		(layer "In9.Cu")
		(net "FM_FAST_PROCHOT_EN_N")
	)
	(segment
		(start 415.866326 -67.162934)
		(end 415.542222 -67.487038)
		(width 0.089408)
		(layer "In9.Cu")
		(net "FM_FAST_PROCHOT_EN_N")
	)
	(segment
		(start 406.940258 -88.853772)
		(end 406.940258 -89.602818)
		(width 0.089408)
		(layer "In9.Cu")
		(net "FM_FAST_PROCHOT_EN_N")
	)
	(segment
		(start 468.749126 -34.417)
		(end 463.702908 -34.417)
		(width 0.089408)
		(layer "In9.Cu")
		(net "FM_FAST_PROCHOT_EN_N")
	)
	(segment
		(start 415.46907 -66.765678)
		(end 415.866326 -67.162934)
		(width 0.089408)
		(layer "In9.Cu")
		(net "FM_FAST_PROCHOT_EN_N")
	)
	(segment
		(start 462.840324 -35.279838)
		(end 462.0768 -36.043362)
		(width 0.089408)
		(layer "In9.Cu")
		(net "FM_FAST_PROCHOT_EN_N")
	)
	(segment
		(start 397.921226 -101.551486)
		(end 397.403828 -101.551486)
		(width 0.089408)
		(layer "In9.Cu")
		(net "FM_FAST_PROCHOT_EN_N")
	)
	(segment
		(start 400.136868 -100.012754)
		(end 399.861786 -100.012754)
		(width 0.089408)
		(layer "In9.Cu")
		(net "FM_FAST_PROCHOT_EN_N")
	)
	(segment
		(start 464.669632 -51.827176)
		(end 439.453782 -51.827176)
		(width 0.089408)
		(layer "In9.Cu")
		(net "FM_FAST_PROCHOT_EN_N")
	)
	(segment
		(start 465.88553 -50.611278)
		(end 464.669632 -51.827176)
		(width 0.089408)
		(layer "In9.Cu")
		(net "FM_FAST_PROCHOT_EN_N")
	)
	(segment
		(start 463.662014 -39.325804)
		(end 463.662014 -39.32682)
		(width 0.089408)
		(layer "In9.Cu")
		(net "FM_FAST_PROCHOT_EN_N")
	)
	(segment
		(start 397.078708 -101.226366)
		(end 397.078708 -100.837238)
		(width 0.089408)
		(layer "In9.Cu")
		(net "FM_FAST_PROCHOT_EN_N")
	)
	(segment
		(start 465.88553 -48.992282)
		(end 465.88553 -50.611278)
		(width 0.089408)
		(layer "In9.Cu")
		(net "FM_FAST_PROCHOT_EN_N")
	)
	(segment
		(start 426.155358 -54.363874)
		(end 425.838874 -54.363874)
		(width 0.089408)
		(layer "In9.Cu")
		(net "FM_FAST_PROCHOT_EN_N")
	)
	(segment
		(start 399.03273 -101.20503)
		(end 398.799304 -101.438456)
		(width 0.089408)
		(layer "In9.Cu")
		(net "FM_FAST_PROCHOT_EN_N")
	)
	(segment
		(start 399.861786 -100.012754)
		(end 399.03273 -100.84181)
		(width 0.089408)
		(layer "In9.Cu")
		(net "FM_FAST_PROCHOT_EN_N")
	)
	(segment
		(start 410.544518 -86.15807)
		(end 408.866594 -87.835994)
		(width 0.089408)
		(layer "In9.Cu")
		(net "FM_FAST_PROCHOT_EN_N")
	)
	(segment
		(start 413.862012 -79.503524)
		(end 413.498284 -79.867252)
		(width 0.089408)
		(layer "In9.Cu")
		(net "FM_FAST_PROCHOT_EN_N")
	)
	(segment
		(start 402.694394 -97.455228)
		(end 402.69414 -97.455228)
		(width 0.089408)
		(layer "In9.Cu")
		(net "FM_FAST_PROCHOT_EN_N")
	)
	(segment
		(start 403.362922 -93.180154)
		(end 403.362922 -96.7867)
		(width 0.089408)
		(layer "In9.Cu")
		(net "FM_FAST_PROCHOT_EN_N")
	)
	(segment
		(start 462.840324 -35.279584)
		(end 462.840324 -35.279838)
		(width 0.089408)
		(layer "In9.Cu")
		(net "FM_FAST_PROCHOT_EN_N")
	)
	(segment
		(start 465.280248 -43.993562)
		(end 465.280248 -48.387)
		(width 0.089408)
		(layer "In9.Cu")
		(net "FM_FAST_PROCHOT_EN_N")
	)
	(segment
		(start 414.526222 -78.838298)
		(end 413.862012 -79.502508)
		(width 0.089408)
		(layer "In9.Cu")
		(net "FM_FAST_PROCHOT_EN_N")
	)
	(segment
		(start 427.986698 -52.532534)
		(end 426.155358 -54.363874)
		(width 0.089408)
		(layer "In9.Cu")
		(net "FM_FAST_PROCHOT_EN_N")
	)
	(segment
		(start 415.13252 -68.340986)
		(end 415.13252 -71.797418)
		(width 0.089408)
		(layer "In9.Cu")
		(net "FM_FAST_PROCHOT_EN_N")
	)
	(segment
		(start 436.021226 -52.532534)
		(end 427.986698 -52.532534)
		(width 0.089408)
		(layer "In9.Cu")
		(net "FM_FAST_PROCHOT_EN_N")
	)
	(segment
		(start 415.819336 -61.952632)
		(end 415.674556 -62.097412)
		(width 0.089408)
		(layer "In9.Cu")
		(net "FM_FAST_PROCHOT_EN_N")
	)
	(segment
		(start 425.83862 -54.36362)
		(end 424.882564 -54.36362)
		(width 0.089408)
		(layer "In9.Cu")
		(net "FM_FAST_PROCHOT_EN_N")
	)
	(segment
		(start 465.280248 -48.387)
		(end 465.88553 -48.992282)
		(width 0.089408)
		(layer "In9.Cu")
		(net "FM_FAST_PROCHOT_EN_N")
	)
	(segment
		(start 463.703416 -42.41673)
		(end 465.280248 -43.993562)
		(width 0.089408)
		(layer "In9.Cu")
		(net "FM_FAST_PROCHOT_EN_N")
	)
	(segment
		(start 415.674556 -59.92368)
		(end 415.819336 -60.06846)
		(width 0.089408)
		(layer "In9.Cu")
		(net "FM_FAST_PROCHOT_EN_N")
	)
	(segment
		(start 408.866594 -87.835994)
		(end 407.958036 -87.835994)
		(width 0.089408)
		(layer "In9.Cu")
		(net "FM_FAST_PROCHOT_EN_N")
	)
	(segment
		(start 402.614892 -97.534476)
		(end 402.614892 -97.53473)
		(width 0.089408)
		(layer "In9.Cu")
		(net "FM_FAST_PROCHOT_EN_N")
	)
	(segment
		(start 402.69414 -97.455228)
		(end 402.614892 -97.534476)
		(width 0.089408)
		(layer "In9.Cu")
		(net "FM_FAST_PROCHOT_EN_N")
	)
	(segment
		(start 415.674556 -62.097412)
		(end 415.674556 -64.01054)
		(width 0.089408)
		(layer "In9.Cu")
		(net "FM_FAST_PROCHOT_EN_N")
	)
	(segment
		(start 438.77484 -52.506118)
		(end 436.047642 -52.506118)
		(width 0.089408)
		(layer "In9.Cu")
		(net "FM_FAST_PROCHOT_EN_N")
	)
	(segment
		(start 398.799304 -101.438456)
		(end 398.034256 -101.438456)
		(width 0.089408)
		(layer "In9.Cu")
		(net "FM_FAST_PROCHOT_EN_N")
	)
	(segment
		(start 420.070788 -56.334406)
		(end 418.378132 -56.334406)
		(width 0.089408)
		(layer "In9.Cu")
		(net "FM_FAST_PROCHOT_EN_N")
	)
	(segment
		(start 415.674556 -59.037982)
		(end 415.674556 -59.92368)
		(width 0.089408)
		(layer "In9.Cu")
		(net "FM_FAST_PROCHOT_EN_N")
	)
	(segment
		(start 413.498284 -79.867252)
		(end 413.498284 -83.627722)
		(width 0.089408)
		(layer "In9.Cu")
		(net "FM_FAST_PROCHOT_EN_N")
	)
	(segment
		(start 406.940258 -89.602818)
		(end 403.362922 -93.180154)
		(width 0.089408)
		(layer "In9.Cu")
		(net "FM_FAST_PROCHOT_EN_N")
	)
	(segment
		(start 397.078708 -100.837238)
		(end 396.422626 -100.181156)
		(width 0.089408)
		(layer "In9.Cu")
		(net "FM_FAST_PROCHOT_EN_N")
	)
	(segment
		(start 413.862012 -79.502508)
		(end 413.862012 -79.503524)
		(width 0.089408)
		(layer "In9.Cu")
		(net "FM_FAST_PROCHOT_EN_N")
	)
	(segment
		(start 411.35935 -83.81873)
		(end 410.544518 -84.633562)
		(width 0.089408)
		(layer "In9.Cu")
		(net "FM_FAST_PROCHOT_EN_N")
	)
	(segment
		(start 396.422626 -100.181156)
		(end 396.15745 -100.181156)
		(width 0.089408)
		(layer "In9.Cu")
		(net "FM_FAST_PROCHOT_EN_N")
	)
	(segment
		(start 413.307276 -83.81873)
		(end 411.35935 -83.81873)
		(width 0.089408)
		(layer "In9.Cu")
		(net "FM_FAST_PROCHOT_EN_N")
	)
	(segment
		(start 398.034256 -101.438456)
		(end 397.921226 -101.551486)
		(width 0.089408)
		(layer "In9.Cu")
		(net "FM_FAST_PROCHOT_EN_N")
	)
	(segment
		(start 397.403828 -101.551486)
		(end 397.078708 -101.226366)
		(width 0.089408)
		(layer "In9.Cu")
		(net "FM_FAST_PROCHOT_EN_N")
	)
	(segment
		(start 415.13252 -71.797418)
		(end 414.526222 -72.403716)
		(width 0.089408)
		(layer "In9.Cu")
		(net "FM_FAST_PROCHOT_EN_N")
	)
	(segment
		(start 413.498284 -83.627722)
		(end 413.307276 -83.81873)
		(width 0.089408)
		(layer "In9.Cu")
		(net "FM_FAST_PROCHOT_EN_N")
	)
	(segment
		(start 403.362922 -96.7867)
		(end 402.694394 -97.455228)
		(width 0.089408)
		(layer "In9.Cu")
		(net "FM_FAST_PROCHOT_EN_N")
	)
	(segment
		(start 463.662014 -39.32682)
		(end 463.703416 -39.368222)
		(width 0.089408)
		(layer "In9.Cu")
		(net "FM_FAST_PROCHOT_EN_N")
	)
	(segment
		(start 415.819336 -60.06846)
		(end 415.819336 -61.952632)
		(width 0.089408)
		(layer "In9.Cu")
		(net "FM_FAST_PROCHOT_EN_N")
	)
	(segment
		(start 463.703416 -39.368222)
		(end 463.703416 -42.41673)
		(width 0.089408)
		(layer "In9.Cu")
		(net "FM_FAST_PROCHOT_EN_N")
	)
	(segment
		(start 439.453782 -51.827176)
		(end 438.77484 -52.506118)
		(width 0.089408)
		(layer "In9.Cu")
		(net "FM_FAST_PROCHOT_EN_N")
	)
	(segment
		(start 425.838874 -54.363874)
		(end 425.83862 -54.36362)
		(width 0.089408)
		(layer "In9.Cu")
		(net "FM_FAST_PROCHOT_EN_N")
	)
	(segment
		(start 462.0768 -37.74059)
		(end 463.662014 -39.325804)
		(width 0.089408)
		(layer "In9.Cu")
		(net "FM_FAST_PROCHOT_EN_N")
	)
	(segment
		(start 424.882564 -54.36362)
		(end 423.847514 -55.39867)
		(width 0.089408)
		(layer "In9.Cu")
		(net "FM_FAST_PROCHOT_EN_N")
	)
	(segment
		(start 418.378132 -56.334406)
		(end 415.674556 -59.037982)
		(width 0.089408)
		(layer "In9.Cu")
		(net "FM_FAST_PROCHOT_EN_N")
	)
	(segment
		(start 415.542222 -67.931284)
		(end 415.13252 -68.340986)
		(width 0.089408)
		(layer "In9.Cu")
		(net "FM_FAST_PROCHOT_EN_N")
	)
	(segment
		(start 421.006524 -55.39867)
		(end 420.070788 -56.334406)
		(width 0.089408)
		(layer "In9.Cu")
		(net "FM_FAST_PROCHOT_EN_N")
	)
	(segment
		(start 415.46907 -64.216026)
		(end 415.46907 -66.765678)
		(width 0.089408)
		(layer "In9.Cu")
		(net "FM_FAST_PROCHOT_EN_N")
	)
	(segment
		(start 423.847514 -55.39867)
		(end 421.006524 -55.39867)
		(width 0.089408)
		(layer "In9.Cu")
		(net "FM_FAST_PROCHOT_EN_N")
	)
	(segment
		(start 486.797604 -38.072568)
		(end 486.74274 -38.017704)
		(width 0.10795)
		(layer "F.Cu")
		(net "FM_1GB_LOM_DISABLE_N")
	)
	(segment
		(start 486.500932 -39.279068)
		(end 486.797604 -38.982396)
		(width 0.10795)
		(layer "F.Cu")
		(net "FM_1GB_LOM_DISABLE_N")
	)
	(segment
		(start 409.65755 -103.879396)
		(end 409.67025 -103.879396)
		(width 0.10795)
		(layer "F.Cu")
		(net "FM_1GB_LOM_DISABLE_N")
	)
	(segment
		(start 486.797604 -38.982396)
		(end 486.797604 -38.072568)
		(width 0.10795)
		(layer "F.Cu")
		(net "FM_1GB_LOM_DISABLE_N")
	)
	(segment
		(start 409.613354 -103.8225)
		(end 408.813 -103.8225)
		(width 0.10795)
		(layer "F.Cu")
		(net "FM_1GB_LOM_DISABLE_N")
	)
	(segment
		(start 409.67025 -103.879396)
		(end 409.613354 -103.8225)
		(width 0.10795)
		(layer "F.Cu")
		(net "FM_1GB_LOM_DISABLE_N")
	)
	(segment
		(start 486.500932 -39.5986)
		(end 486.500932 -39.279068)
		(width 0.10795)
		(layer "F.Cu")
		(net "FM_1GB_LOM_DISABLE_N")
	)
	(via
		(at 409.65755 -103.879396)
		(size 0.508)
		(drill 0.254)
		(layers "F.Cu" "B.Cu")
		(net "FM_1GB_LOM_DISABLE_N")
	)
	(via
		(at 486.74274 -38.017704)
		(size 0.508)
		(drill 0.254)
		(layers "F.Cu" "B.Cu")
		(net "FM_1GB_LOM_DISABLE_N")
	)
	(via
		(at 423.508424 -54.126384)
		(size 0.508)
		(drill 0.254)
		(layers "F.Cu" "B.Cu")
		(net "FM_1GB_LOM_DISABLE_N")
	)
	(via
		(at 480.53752 -51.90998)
		(size 0.508)
		(drill 0.254)
		(layers "F.Cu" "B.Cu")
		(net "FM_1GB_LOM_DISABLE_N")
	)
	(segment
		(start 434.221128 -54.229)
		(end 429.59528 -54.229)
		(width 0.10795)
		(layer "B.Cu")
		(net "FM_1GB_LOM_DISABLE_N")
	)
	(segment
		(start 472.631516 -50.850292)
		(end 472.234006 -51.247802)
		(width 0.10795)
		(layer "B.Cu")
		(net "FM_1GB_LOM_DISABLE_N")
	)
	(segment
		(start 429.59528 -54.229)
		(end 428.874936 -54.949344)
		(width 0.10795)
		(layer "B.Cu")
		(net "FM_1GB_LOM_DISABLE_N")
	)
	(segment
		(start 480.34448 -52.10302)
		(end 477.94672 -52.10302)
		(width 0.10795)
		(layer "B.Cu")
		(net "FM_1GB_LOM_DISABLE_N")
	)
	(segment
		(start 428.874936 -54.949344)
		(end 424.073066 -54.949344)
		(width 0.10795)
		(layer "B.Cu")
		(net "FM_1GB_LOM_DISABLE_N")
	)
	(segment
		(start 435.73573 -55.743602)
		(end 434.221128 -54.229)
		(width 0.10795)
		(layer "B.Cu")
		(net "FM_1GB_LOM_DISABLE_N")
	)
	(segment
		(start 468.719662 -53.239162)
		(end 466.215222 -55.743602)
		(width 0.10795)
		(layer "B.Cu")
		(net "FM_1GB_LOM_DISABLE_N")
	)
	(segment
		(start 472.234006 -51.247802)
		(end 471.860118 -51.247802)
		(width 0.10795)
		(layer "B.Cu")
		(net "FM_1GB_LOM_DISABLE_N")
	)
	(segment
		(start 424.073066 -54.949344)
		(end 423.508424 -54.384702)
		(width 0.10795)
		(layer "B.Cu")
		(net "FM_1GB_LOM_DISABLE_N")
	)
	(segment
		(start 474.045788 -50.850292)
		(end 472.631516 -50.850292)
		(width 0.10795)
		(layer "B.Cu")
		(net "FM_1GB_LOM_DISABLE_N")
	)
	(segment
		(start 466.215222 -55.743602)
		(end 435.73573 -55.743602)
		(width 0.10795)
		(layer "B.Cu")
		(net "FM_1GB_LOM_DISABLE_N")
	)
	(segment
		(start 471.860118 -51.247802)
		(end 469.868758 -53.239162)
		(width 0.10795)
		(layer "B.Cu")
		(net "FM_1GB_LOM_DISABLE_N")
	)
	(segment
		(start 469.868758 -53.239162)
		(end 468.719662 -53.239162)
		(width 0.10795)
		(layer "B.Cu")
		(net "FM_1GB_LOM_DISABLE_N")
	)
	(segment
		(start 474.265498 -51.070002)
		(end 474.045788 -50.850292)
		(width 0.10795)
		(layer "B.Cu")
		(net "FM_1GB_LOM_DISABLE_N")
	)
	(segment
		(start 476.913702 -51.070002)
		(end 474.265498 -51.070002)
		(width 0.10795)
		(layer "B.Cu")
		(net "FM_1GB_LOM_DISABLE_N")
	)
	(segment
		(start 423.508424 -54.384702)
		(end 423.508424 -54.126384)
		(width 0.10795)
		(layer "B.Cu")
		(net "FM_1GB_LOM_DISABLE_N")
	)
	(segment
		(start 480.53752 -51.90998)
		(end 480.34448 -52.10302)
		(width 0.10795)
		(layer "B.Cu")
		(net "FM_1GB_LOM_DISABLE_N")
	)
	(segment
		(start 477.94672 -52.10302)
		(end 476.913702 -51.070002)
		(width 0.10795)
		(layer "B.Cu")
		(net "FM_1GB_LOM_DISABLE_N")
	)
	(segment
		(start 402.900896 -77.947774)
		(end 402.900896 -78.452472)
		(width 0.089408)
		(layer "In2.Cu")
		(net "FM_1GB_LOM_DISABLE_N")
	)
	(segment
		(start 423.508424 -54.126384)
		(end 423.508424 -54.16169)
		(width 0.089408)
		(layer "In2.Cu")
		(net "FM_1GB_LOM_DISABLE_N")
	)
	(segment
		(start 403.97176 -74.999088)
		(end 403.97176 -76.87691)
		(width 0.089408)
		(layer "In2.Cu")
		(net "FM_1GB_LOM_DISABLE_N")
	)
	(segment
		(start 414.333182 -54.901846)
		(end 412.238444 -54.901846)
		(width 0.089408)
		(layer "In2.Cu")
		(net "FM_1GB_LOM_DISABLE_N")
	)
	(segment
		(start 420.611808 -55.797704)
		(end 415.22904 -55.797704)
		(width 0.089408)
		(layer "In2.Cu")
		(net "FM_1GB_LOM_DISABLE_N")
	)
	(segment
		(start 421.854122 -54.55539)
		(end 420.611808 -55.797704)
		(width 0.089408)
		(layer "In2.Cu")
		(net "FM_1GB_LOM_DISABLE_N")
	)
	(segment
		(start 415.22904 -55.797704)
		(end 414.333182 -54.901846)
		(width 0.089408)
		(layer "In2.Cu")
		(net "FM_1GB_LOM_DISABLE_N")
	)
	(segment
		(start 405.858472 -82.668618)
		(end 405.858472 -90.314526)
		(width 0.089408)
		(layer "In2.Cu")
		(net "FM_1GB_LOM_DISABLE_N")
	)
	(segment
		(start 402.900896 -78.452472)
		(end 403.513544 -79.06512)
		(width 0.089408)
		(layer "In2.Cu")
		(net "FM_1GB_LOM_DISABLE_N")
	)
	(segment
		(start 403.513544 -80.32369)
		(end 405.858472 -82.668618)
		(width 0.089408)
		(layer "In2.Cu")
		(net "FM_1GB_LOM_DISABLE_N")
	)
	(segment
		(start 409.550616 -94.00667)
		(end 409.550616 -97.431352)
		(width 0.089408)
		(layer "In2.Cu")
		(net "FM_1GB_LOM_DISABLE_N")
	)
	(segment
		(start 423.114724 -54.55539)
		(end 421.854122 -54.55539)
		(width 0.089408)
		(layer "In2.Cu")
		(net "FM_1GB_LOM_DISABLE_N")
	)
	(segment
		(start 403.97176 -76.87691)
		(end 402.900896 -77.947774)
		(width 0.089408)
		(layer "In2.Cu")
		(net "FM_1GB_LOM_DISABLE_N")
	)
	(segment
		(start 423.508424 -54.16169)
		(end 423.114724 -54.55539)
		(width 0.089408)
		(layer "In2.Cu")
		(net "FM_1GB_LOM_DISABLE_N")
	)
	(segment
		(start 403.513544 -79.06512)
		(end 403.513544 -80.32369)
		(width 0.089408)
		(layer "In2.Cu")
		(net "FM_1GB_LOM_DISABLE_N")
	)
	(segment
		(start 404.60422 -74.366628)
		(end 403.97176 -74.999088)
		(width 0.089408)
		(layer "In2.Cu")
		(net "FM_1GB_LOM_DISABLE_N")
	)
	(segment
		(start 404.60422 -74.04481)
		(end 404.60422 -74.366628)
		(width 0.089408)
		(layer "In2.Cu")
		(net "FM_1GB_LOM_DISABLE_N")
	)
	(segment
		(start 405.858472 -90.314526)
		(end 409.550616 -94.00667)
		(width 0.089408)
		(layer "In2.Cu")
		(net "FM_1GB_LOM_DISABLE_N")
	)
	(segment
		(start 409.165298 -103.387144)
		(end 409.65755 -103.879396)
		(width 0.089408)
		(layer "In2.Cu")
		(net "FM_1GB_LOM_DISABLE_N")
	)
	(segment
		(start 410.294836 -56.845454)
		(end 410.294836 -68.354194)
		(width 0.089408)
		(layer "In2.Cu")
		(net "FM_1GB_LOM_DISABLE_N")
	)
	(segment
		(start 409.165298 -97.81667)
		(end 409.165298 -103.387144)
		(width 0.089408)
		(layer "In2.Cu")
		(net "FM_1GB_LOM_DISABLE_N")
	)
	(segment
		(start 410.294836 -68.354194)
		(end 404.60422 -74.04481)
		(width 0.089408)
		(layer "In2.Cu")
		(net "FM_1GB_LOM_DISABLE_N")
	)
	(segment
		(start 409.550616 -97.431352)
		(end 409.165298 -97.81667)
		(width 0.089408)
		(layer "In2.Cu")
		(net "FM_1GB_LOM_DISABLE_N")
	)
	(segment
		(start 412.238444 -54.901846)
		(end 410.294836 -56.845454)
		(width 0.089408)
		(layer "In2.Cu")
		(net "FM_1GB_LOM_DISABLE_N")
	)
	(segment
		(start 480.3521 -49.76114)
		(end 482.37648 -47.73676)
		(width 0.089408)
		(layer "In4.Cu")
		(net "FM_1GB_LOM_DISABLE_N")
	)
	(segment
		(start 489.5977 -47.73676)
		(end 491.1979 -46.13656)
		(width 0.089408)
		(layer "In4.Cu")
		(net "FM_1GB_LOM_DISABLE_N")
	)
	(segment
		(start 491.1979 -41.86682)
		(end 490.21746 -40.88638)
		(width 0.089408)
		(layer "In4.Cu")
		(net "FM_1GB_LOM_DISABLE_N")
	)
	(segment
		(start 480.53752 -51.90998)
		(end 480.3521 -51.72456)
		(width 0.089408)
		(layer "In4.Cu")
		(net "FM_1GB_LOM_DISABLE_N")
	)
	(segment
		(start 488.66298 -40.88638)
		(end 486.74274 -38.96614)
		(width 0.089408)
		(layer "In4.Cu")
		(net "FM_1GB_LOM_DISABLE_N")
	)
	(segment
		(start 486.74274 -38.96614)
		(end 486.74274 -38.017704)
		(width 0.089408)
		(layer "In4.Cu")
		(net "FM_1GB_LOM_DISABLE_N")
	)
	(segment
		(start 482.37648 -47.73676)
		(end 489.5977 -47.73676)
		(width 0.089408)
		(layer "In4.Cu")
		(net "FM_1GB_LOM_DISABLE_N")
	)
	(segment
		(start 491.1979 -46.13656)
		(end 491.1979 -41.86682)
		(width 0.089408)
		(layer "In4.Cu")
		(net "FM_1GB_LOM_DISABLE_N")
	)
	(segment
		(start 480.3521 -51.72456)
		(end 480.3521 -49.76114)
		(width 0.089408)
		(layer "In4.Cu")
		(net "FM_1GB_LOM_DISABLE_N")
	)
	(segment
		(start 490.21746 -40.88638)
		(end 488.66298 -40.88638)
		(width 0.089408)
		(layer "In4.Cu")
		(net "FM_1GB_LOM_DISABLE_N")
	)
	(segment
		(start 370.345208 -71.095108)
		(end 370.745004 -71.494904)
		(width 0.10795)
		(layer "F.Cu")
		(net "TP_CPLD1_PT19D")
	)
	(via
		(at 370.345208 -71.095108)
		(size 0.4572)
		(drill 0.2032)
		(layers "F.Cu" "B.Cu")
		(net "TP_CPLD1_PT19D")
	)
	(segment
		(start 490.488986 -139.431014)
		(end 490.488986 -138.811)
		(width 0.10795)
		(layer "B.Cu")
		(net "TP_FET_Q56_4")
	)
	(segment
		(start 490.3978 -139.5222)
		(end 490.488986 -139.431014)
		(width 0.10795)
		(layer "B.Cu")
		(net "TP_FET_Q56_4")
	)
	(segment
		(start 489.839 -138.811)
		(end 489.839 -139.4206)
		(width 0.10795)
		(layer "B.Cu")
		(net "TP_FET_Q56_4")
	)
	(segment
		(start 489.9406 -139.5222)
		(end 490.3978 -139.5222)
		(width 0.10795)
		(layer "B.Cu")
		(net "TP_FET_Q56_4")
	)
	(segment
		(start 489.839 -139.4206)
		(end 489.9406 -139.5222)
		(width 0.10795)
		(layer "B.Cu")
		(net "TP_FET_Q56_4")
	)
	(via
		(at 490.3724 -142.494)
		(size 0.6604)
		(drill 0.3302)
		(layers "F.Cu" "B.Cu")
		(net "TP_FET_Q56_3")
	)
	(segment
		(start 490.3724 -142.051786)
		(end 490.488986 -141.9352)
		(width 0.10795)
		(layer "B.Cu")
		(net "TP_FET_Q56_3")
	)
	(segment
		(start 490.488986 -141.9352)
		(end 490.488986 -140.589)
		(width 0.10795)
		(layer "B.Cu")
		(net "TP_FET_Q56_3")
	)
	(segment
		(start 490.3724 -142.494)
		(end 490.3724 -142.051786)
		(width 0.10795)
		(layer "B.Cu")
		(net "TP_FET_Q56_3")
	)
	(segment
		(start 409.35656 -111.782352)
		(end 409.513024 -111.782352)
		(width 0.10795)
		(layer "F.Cu")
		(net "FM_SLT_CFG1")
	)
	(segment
		(start 400.545808 -109.935772)
		(end 400.925284 -109.935772)
		(width 0.0889)
		(layer "F.Cu")
		(net "FM_SLT_CFG1")
	)
	(segment
		(start 405.725884 -111.506)
		(end 409.080208 -111.506)
		(width 0.10795)
		(layer "F.Cu")
		(net "FM_SLT_CFG1")
	)
	(segment
		(start 401.15363 -110.164118)
		(end 402.568918 -110.164118)
		(width 0.0889)
		(layer "F.Cu")
		(net "FM_SLT_CFG1")
	)
	(segment
		(start 467.4616 -2.4638)
		(end 467.679278 -2.681478)
		(width 0.10795)
		(layer "F.Cu")
		(net "FM_SLT_CFG1")
	)
	(segment
		(start 410.290264 -33.734756)
		(end 409.890214 -34.134806)
		(width 0.10795)
		(layer "F.Cu")
		(net "FM_SLT_CFG1")
	)
	(segment
		(start 409.513024 -111.782352)
		(end 409.662376 -111.633)
		(width 0.10795)
		(layer "F.Cu")
		(net "FM_SLT_CFG1")
	)
	(segment
		(start 402.7932 -110.3884)
		(end 402.929852 -110.525052)
		(width 0.10795)
		(layer "F.Cu")
		(net "FM_SLT_CFG1")
	)
	(segment
		(start 402.568918 -110.164118)
		(end 402.7932 -110.3884)
		(width 0.0889)
		(layer "F.Cu")
		(net "FM_SLT_CFG1")
	)
	(segment
		(start 400.925284 -109.935772)
		(end 401.15363 -110.164118)
		(width 0.0889)
		(layer "F.Cu")
		(net "FM_SLT_CFG1")
	)
	(segment
		(start 402.929852 -110.525052)
		(end 404.744936 -110.525052)
		(width 0.10795)
		(layer "F.Cu")
		(net "FM_SLT_CFG1")
	)
	(segment
		(start 400.465036 -109.855)
		(end 400.545808 -109.935772)
		(width 0.0889)
		(layer "F.Cu")
		(net "FM_SLT_CFG1")
	)
	(segment
		(start 409.080208 -111.506)
		(end 409.35656 -111.782352)
		(width 0.10795)
		(layer "F.Cu")
		(net "FM_SLT_CFG1")
	)
	(segment
		(start 404.744936 -110.525052)
		(end 405.725884 -111.506)
		(width 0.10795)
		(layer "F.Cu")
		(net "FM_SLT_CFG1")
	)
	(segment
		(start 409.662376 -111.633)
		(end 410.1465 -111.633)
		(width 0.10795)
		(layer "F.Cu")
		(net "FM_SLT_CFG1")
	)
	(segment
		(start 467.679278 -2.681478)
		(end 467.679278 -4.386072)
		(width 0.10795)
		(layer "F.Cu")
		(net "FM_SLT_CFG1")
	)
	(via
		(at 409.513024 -111.782352)
		(size 0.508)
		(drill 0.254)
		(layers "F.Cu" "B.Cu")
		(net "FM_SLT_CFG1")
	)
	(via
		(at 467.4616 -2.4638)
		(size 0.508)
		(drill 0.254)
		(layers "F.Cu" "B.Cu")
		(net "FM_SLT_CFG1")
	)
	(via
		(at 454.144126 -12.190222)
		(size 0.6604)
		(drill 0.3302)
		(layers "F.Cu" "B.Cu")
		(net "FM_SLT_CFG1")
	)
	(via
		(at 409.890214 -34.134806)
		(size 0.4572)
		(drill 0.2032)
		(layers "F.Cu" "B.Cu")
		(net "FM_SLT_CFG1")
	)
	(via
		(at 448.648582 -15.015464)
		(size 0.508)
		(drill 0.254)
		(layers "F.Cu" "B.Cu")
		(net "FM_SLT_CFG1")
	)
	(via
		(at 490.347 -53.203856)
		(size 0.508)
		(drill 0.254)
		(layers "F.Cu" "B.Cu")
		(net "FM_SLT_CFG1")
	)
	(segment
		(start 462.9658 -3.1496)
		(end 464.2358 -1.8796)
		(width 0.10795)
		(layer "B.Cu")
		(net "FM_SLT_CFG1")
	)
	(segment
		(start 467.0298 -2.032)
		(end 467.4616 -2.4638)
		(width 0.10795)
		(layer "B.Cu")
		(net "FM_SLT_CFG1")
	)
	(segment
		(start 462.9658 -3.674364)
		(end 462.9658 -3.3528)
		(width 0.10795)
		(layer "B.Cu")
		(net "FM_SLT_CFG1")
	)
	(segment
		(start 461.008222 -4.679696)
		(end 461.008476 -4.67995)
		(width 0.10795)
		(layer "B.Cu")
		(net "FM_SLT_CFG1")
	)
	(segment
		(start 453.83831 -12.190222)
		(end 454.144126 -12.190222)
		(width 0.10795)
		(layer "B.Cu")
		(net "FM_SLT_CFG1")
	)
	(segment
		(start 448.648582 -15.015464)
		(end 449.567046 -14.097)
		(width 0.10795)
		(layer "B.Cu")
		(net "FM_SLT_CFG1")
	)
	(segment
		(start 465.836 -1.8796)
		(end 465.9884 -2.032)
		(width 0.10795)
		(layer "B.Cu")
		(net "FM_SLT_CFG1")
	)
	(segment
		(start 458.85354 -7.82574)
		(end 459.796642 -7.82574)
		(width 0.10795)
		(layer "B.Cu")
		(net "FM_SLT_CFG1")
	)
	(segment
		(start 451.931532 -14.097)
		(end 453.83831 -12.190222)
		(width 0.10795)
		(layer "B.Cu")
		(net "FM_SLT_CFG1")
	)
	(segment
		(start 462.9404 -3.1496)
		(end 462.9658 -3.1496)
		(width 0.10795)
		(layer "B.Cu")
		(net "FM_SLT_CFG1")
	)
	(segment
		(start 460.35214 -7.270242)
		(end 460.35214 -7.187946)
		(width 0.10795)
		(layer "B.Cu")
		(net "FM_SLT_CFG1")
	)
	(segment
		(start 454.489058 -12.190222)
		(end 458.85354 -7.82574)
		(width 0.10795)
		(layer "B.Cu")
		(net "FM_SLT_CFG1")
	)
	(segment
		(start 449.567046 -14.097)
		(end 451.931532 -14.097)
		(width 0.10795)
		(layer "B.Cu")
		(net "FM_SLT_CFG1")
	)
	(segment
		(start 462.9404 -3.3274)
		(end 462.9404 -3.1496)
		(width 0.10795)
		(layer "B.Cu")
		(net "FM_SLT_CFG1")
	)
	(segment
		(start 461.008476 -4.67995)
		(end 461.960214 -4.67995)
		(width 0.10795)
		(layer "B.Cu")
		(net "FM_SLT_CFG1")
	)
	(segment
		(start 454.144126 -12.190222)
		(end 454.489058 -12.190222)
		(width 0.10795)
		(layer "B.Cu")
		(net "FM_SLT_CFG1")
	)
	(segment
		(start 460.35214 -7.187946)
		(end 460.35595 -7.184136)
		(width 0.10795)
		(layer "B.Cu")
		(net "FM_SLT_CFG1")
	)
	(segment
		(start 460.35595 -7.184136)
		(end 460.35595 -4.99364)
		(width 0.10795)
		(layer "B.Cu")
		(net "FM_SLT_CFG1")
	)
	(segment
		(start 464.2358 -1.8796)
		(end 465.836 -1.8796)
		(width 0.10795)
		(layer "B.Cu")
		(net "FM_SLT_CFG1")
	)
	(segment
		(start 462.9658 -3.3528)
		(end 462.9404 -3.3274)
		(width 0.10795)
		(layer "B.Cu")
		(net "FM_SLT_CFG1")
	)
	(segment
		(start 460.669894 -4.679696)
		(end 461.008222 -4.679696)
		(width 0.10795)
		(layer "B.Cu")
		(net "FM_SLT_CFG1")
	)
	(segment
		(start 459.796642 -7.82574)
		(end 460.35214 -7.270242)
		(width 0.10795)
		(layer "B.Cu")
		(net "FM_SLT_CFG1")
	)
	(segment
		(start 465.9884 -2.032)
		(end 467.0298 -2.032)
		(width 0.10795)
		(layer "B.Cu")
		(net "FM_SLT_CFG1")
	)
	(segment
		(start 461.960214 -4.67995)
		(end 462.9658 -3.674364)
		(width 0.10795)
		(layer "B.Cu")
		(net "FM_SLT_CFG1")
	)
	(segment
		(start 460.35595 -4.99364)
		(end 460.669894 -4.679696)
		(width 0.10795)
		(layer "B.Cu")
		(net "FM_SLT_CFG1")
	)
	(segment
		(start 407.329386 -81.308702)
		(end 407.32964 -81.308448)
		(width 0.089408)
		(layer "In2.Cu")
		(net "FM_SLT_CFG1")
	)
	(segment
		(start 411.77083 -66.685922)
		(end 411.77083 -67.707256)
		(width 0.089408)
		(layer "In2.Cu")
		(net "FM_SLT_CFG1")
	)
	(segment
		(start 411.77083 -67.707256)
		(end 411.771084 -67.70751)
		(width 0.089408)
		(layer "In2.Cu")
		(net "FM_SLT_CFG1")
	)
	(segment
		(start 475.086426 -52.977542)
		(end 474.851984 -53.211984)
		(width 0.089408)
		(layer "In2.Cu")
		(net "FM_SLT_CFG1")
	)
	(segment
		(start 411.770322 -66.685414)
		(end 411.77083 -66.685922)
		(width 0.089408)
		(layer "In2.Cu")
		(net "FM_SLT_CFG1")
	)
	(segment
		(start 405.827992 -78.732888)
		(end 405.827992 -79.8068)
		(width 0.089408)
		(layer "In2.Cu")
		(net "FM_SLT_CFG1")
	)
	(segment
		(start 468.6554 -54.993794)
		(end 467.19236 -56.456834)
		(width 0.089408)
		(layer "In2.Cu")
		(net "FM_SLT_CFG1")
	)
	(segment
		(start 412.64586 -64.315594)
		(end 412.64586 -65.58534)
		(width 0.089408)
		(layer "In2.Cu")
		(net "FM_SLT_CFG1")
	)
	(segment
		(start 415.576766 -60.143644)
		(end 413.917384 -61.803026)
		(width 0.089408)
		(layer "In2.Cu")
		(net "FM_SLT_CFG1")
	)
	(segment
		(start 410.671518 -70.609714)
		(end 410.252926 -70.609714)
		(width 0.089408)
		(layer "In2.Cu")
		(net "FM_SLT_CFG1")
	)
	(segment
		(start 464.170014 -56.456834)
		(end 463.3849 -55.67172)
		(width 0.089408)
		(layer "In2.Cu")
		(net "FM_SLT_CFG1")
	)
	(segment
		(start 481.131372 -52.330096)
		(end 475.423738 -52.330096)
		(width 0.089408)
		(layer "In2.Cu")
		(net "FM_SLT_CFG1")
	)
	(segment
		(start 413.917384 -61.803026)
		(end 413.917384 -63.04407)
		(width 0.089408)
		(layer "In2.Cu")
		(net "FM_SLT_CFG1")
	)
	(segment
		(start 488.926632 -53.455316)
		(end 487.79176 -54.590188)
		(width 0.089408)
		(layer "In2.Cu")
		(net "FM_SLT_CFG1")
	)
	(segment
		(start 475.423738 -52.330096)
		(end 475.086426 -52.667408)
		(width 0.089408)
		(layer "In2.Cu")
		(net "FM_SLT_CFG1")
	)
	(segment
		(start 474.460824 -53.211984)
		(end 474.276928 -53.028088)
		(width 0.089408)
		(layer "In2.Cu")
		(net "FM_SLT_CFG1")
	)
	(segment
		(start 410.252926 -70.609714)
		(end 405.38146 -75.48118)
		(width 0.089408)
		(layer "In2.Cu")
		(net "FM_SLT_CFG1")
	)
	(segment
		(start 405.38146 -75.48118)
		(end 405.38146 -78.286356)
		(width 0.089408)
		(layer "In2.Cu")
		(net "FM_SLT_CFG1")
	)
	(segment
		(start 405.38146 -78.286356)
		(end 405.827992 -78.732888)
		(width 0.089408)
		(layer "In2.Cu")
		(net "FM_SLT_CFG1")
	)
	(segment
		(start 409.321254 -81.72704)
		(end 409.321254 -87.519002)
		(width 0.089408)
		(layer "In2.Cu")
		(net "FM_SLT_CFG1")
	)
	(segment
		(start 490.09554 -53.455316)
		(end 488.926632 -53.455316)
		(width 0.089408)
		(layer "In2.Cu")
		(net "FM_SLT_CFG1")
	)
	(segment
		(start 411.443678 -69.837554)
		(end 410.671518 -70.609714)
		(width 0.089408)
		(layer "In2.Cu")
		(net "FM_SLT_CFG1")
	)
	(segment
		(start 408.902662 -81.308448)
		(end 409.321254 -81.72704)
		(width 0.089408)
		(layer "In2.Cu")
		(net "FM_SLT_CFG1")
	)
	(segment
		(start 410.33827 -88.536018)
		(end 410.33827 -97.892616)
		(width 0.089408)
		(layer "In2.Cu")
		(net "FM_SLT_CFG1")
	)
	(segment
		(start 490.347 -53.203856)
		(end 490.09554 -53.455316)
		(width 0.089408)
		(layer "In2.Cu")
		(net "FM_SLT_CFG1")
	)
	(segment
		(start 422.331134 -55.319422)
		(end 417.506912 -60.143644)
		(width 0.089408)
		(layer "In2.Cu")
		(net "FM_SLT_CFG1")
	)
	(segment
		(start 407.32964 -81.308448)
		(end 408.902662 -81.308448)
		(width 0.089408)
		(layer "In2.Cu")
		(net "FM_SLT_CFG1")
	)
	(segment
		(start 410.43987 -97.994216)
		(end 410.43987 -110.855506)
		(width 0.089408)
		(layer "In2.Cu")
		(net "FM_SLT_CFG1")
	)
	(segment
		(start 411.443678 -69.679566)
		(end 411.443678 -69.837554)
		(width 0.089408)
		(layer "In2.Cu")
		(net "FM_SLT_CFG1")
	)
	(segment
		(start 417.506912 -60.143644)
		(end 415.576766 -60.143644)
		(width 0.089408)
		(layer "In2.Cu")
		(net "FM_SLT_CFG1")
	)
	(segment
		(start 410.33827 -97.892616)
		(end 410.43987 -97.994216)
		(width 0.089408)
		(layer "In2.Cu")
		(net "FM_SLT_CFG1")
	)
	(segment
		(start 411.770322 -66.460878)
		(end 411.770322 -66.685414)
		(width 0.089408)
		(layer "In2.Cu")
		(net "FM_SLT_CFG1")
	)
	(segment
		(start 483.391464 -54.590188)
		(end 481.131372 -52.330096)
		(width 0.089408)
		(layer "In2.Cu")
		(net "FM_SLT_CFG1")
	)
	(segment
		(start 474.276928 -53.028088)
		(end 472.60002 -53.028088)
		(width 0.089408)
		(layer "In2.Cu")
		(net "FM_SLT_CFG1")
	)
	(segment
		(start 412.64586 -65.58534)
		(end 411.770322 -66.460878)
		(width 0.089408)
		(layer "In2.Cu")
		(net "FM_SLT_CFG1")
	)
	(segment
		(start 472.60002 -53.028088)
		(end 472.02217 -53.605938)
		(width 0.089408)
		(layer "In2.Cu")
		(net "FM_SLT_CFG1")
	)
	(segment
		(start 411.443424 -69.679312)
		(end 411.443678 -69.679566)
		(width 0.089408)
		(layer "In2.Cu")
		(net "FM_SLT_CFG1")
	)
	(segment
		(start 474.851984 -53.211984)
		(end 474.460824 -53.211984)
		(width 0.089408)
		(layer "In2.Cu")
		(net "FM_SLT_CFG1")
	)
	(segment
		(start 472.02217 -53.605938)
		(end 469.211406 -53.605938)
		(width 0.089408)
		(layer "In2.Cu")
		(net "FM_SLT_CFG1")
	)
	(segment
		(start 409.321254 -87.519002)
		(end 410.33827 -88.536018)
		(width 0.089408)
		(layer "In2.Cu")
		(net "FM_SLT_CFG1")
	)
	(segment
		(start 405.827738 -79.807054)
		(end 405.827738 -79.965042)
		(width 0.089408)
		(layer "In2.Cu")
		(net "FM_SLT_CFG1")
	)
	(segment
		(start 467.19236 -56.456834)
		(end 464.170014 -56.456834)
		(width 0.089408)
		(layer "In2.Cu")
		(net "FM_SLT_CFG1")
	)
	(segment
		(start 469.211406 -53.605938)
		(end 468.6554 -54.161944)
		(width 0.089408)
		(layer "In2.Cu")
		(net "FM_SLT_CFG1")
	)
	(segment
		(start 407.171398 -81.308702)
		(end 407.329386 -81.308702)
		(width 0.089408)
		(layer "In2.Cu")
		(net "FM_SLT_CFG1")
	)
	(segment
		(start 463.3849 -55.67172)
		(end 436.534306 -55.67172)
		(width 0.089408)
		(layer "In2.Cu")
		(net "FM_SLT_CFG1")
	)
	(segment
		(start 410.43987 -110.855506)
		(end 409.513024 -111.782352)
		(width 0.089408)
		(layer "In2.Cu")
		(net "FM_SLT_CFG1")
	)
	(segment
		(start 405.827738 -79.965042)
		(end 407.171398 -81.308702)
		(width 0.089408)
		(layer "In2.Cu")
		(net "FM_SLT_CFG1")
	)
	(segment
		(start 429.665638 -54.189884)
		(end 428.5361 -55.319422)
		(width 0.089408)
		(layer "In2.Cu")
		(net "FM_SLT_CFG1")
	)
	(segment
		(start 436.534306 -55.67172)
		(end 435.05247 -54.189884)
		(width 0.089408)
		(layer "In2.Cu")
		(net "FM_SLT_CFG1")
	)
	(segment
		(start 468.6554 -54.161944)
		(end 468.6554 -54.993794)
		(width 0.089408)
		(layer "In2.Cu")
		(net "FM_SLT_CFG1")
	)
	(segment
		(start 428.5361 -55.319422)
		(end 422.331134 -55.319422)
		(width 0.089408)
		(layer "In2.Cu")
		(net "FM_SLT_CFG1")
	)
	(segment
		(start 411.771084 -68.499482)
		(end 411.443424 -68.827142)
		(width 0.089408)
		(layer "In2.Cu")
		(net "FM_SLT_CFG1")
	)
	(segment
		(start 411.771084 -67.70751)
		(end 411.771084 -68.499482)
		(width 0.089408)
		(layer "In2.Cu")
		(net "FM_SLT_CFG1")
	)
	(segment
		(start 405.827992 -79.8068)
		(end 405.827738 -79.807054)
		(width 0.089408)
		(layer "In2.Cu")
		(net "FM_SLT_CFG1")
	)
	(segment
		(start 475.086426 -52.667408)
		(end 475.086426 -52.977542)
		(width 0.089408)
		(layer "In2.Cu")
		(net "FM_SLT_CFG1")
	)
	(segment
		(start 435.05247 -54.189884)
		(end 429.665638 -54.189884)
		(width 0.089408)
		(layer "In2.Cu")
		(net "FM_SLT_CFG1")
	)
	(segment
		(start 411.443424 -68.827142)
		(end 411.443424 -69.679312)
		(width 0.089408)
		(layer "In2.Cu")
		(net "FM_SLT_CFG1")
	)
	(segment
		(start 413.917384 -63.04407)
		(end 412.64586 -64.315594)
		(width 0.089408)
		(layer "In2.Cu")
		(net "FM_SLT_CFG1")
	)
	(segment
		(start 487.79176 -54.590188)
		(end 483.391464 -54.590188)
		(width 0.089408)
		(layer "In2.Cu")
		(net "FM_SLT_CFG1")
	)
	(segment
		(start 479.047048 -10.018014)
		(end 477.933258 -8.904224)
		(width 0.089408)
		(layer "In9.Cu")
		(net "FM_SLT_CFG1")
	)
	(segment
		(start 490.925358 -52.912264)
		(end 493.198912 -50.63871)
		(width 0.089408)
		(layer "In9.Cu")
		(net "FM_SLT_CFG1")
	)
	(segment
		(start 468.554054 -5.850636)
		(end 468.554054 -4.811522)
		(width 0.089408)
		(layer "In9.Cu")
		(net "FM_SLT_CFG1")
	)
	(segment
		(start 493.198912 -46.566836)
		(end 493.142778 -46.510702)
		(width 0.089408)
		(layer "In9.Cu")
		(net "FM_SLT_CFG1")
	)
	(segment
		(start 468.554308 -6.008878)
		(end 468.554308 -5.85089)
		(width 0.089408)
		(layer "In9.Cu")
		(net "FM_SLT_CFG1")
	)
	(segment
		(start 483.1842 -17.4244)
		(end 482.685852 -16.926052)
		(width 0.089408)
		(layer "In9.Cu")
		(net "FM_SLT_CFG1")
	)
	(segment
		(start 494.48466 -41.901618)
		(end 494.660936 -41.725342)
		(width 0.089408)
		(layer "In9.Cu")
		(net "FM_SLT_CFG1")
	)
	(segment
		(start 488.525312 -23.019512)
		(end 488.525312 -20.14347)
		(width 0.089408)
		(layer "In9.Cu")
		(net "FM_SLT_CFG1")
	)
	(segment
		(start 475.418658 -8.891016)
		(end 474.279722 -7.75208)
		(width 0.089408)
		(layer "In9.Cu")
		(net "FM_SLT_CFG1")
	)
	(segment
		(start 489.744766 -24.238966)
		(end 488.525312 -23.019512)
		(width 0.089408)
		(layer "In9.Cu")
		(net "FM_SLT_CFG1")
	)
	(segment
		(start 494.48466 -43.22826)
		(end 494.48466 -41.901618)
		(width 0.089408)
		(layer "In9.Cu")
		(net "FM_SLT_CFG1")
	)
	(segment
		(start 474.12148 -7.752334)
		(end 469.670892 -7.752334)
		(width 0.089408)
		(layer "In9.Cu")
		(net "FM_SLT_CFG1")
	)
	(segment
		(start 474.279722 -7.75208)
		(end 474.121734 -7.75208)
		(width 0.089408)
		(layer "In9.Cu")
		(net "FM_SLT_CFG1")
	)
	(segment
		(start 468.5538 -6.009386)
		(end 468.554308 -6.008878)
		(width 0.089408)
		(layer "In9.Cu")
		(net "FM_SLT_CFG1")
	)
	(segment
		(start 493.142778 -44.570142)
		(end 494.48466 -43.22826)
		(width 0.089408)
		(layer "In9.Cu")
		(net "FM_SLT_CFG1")
	)
	(segment
		(start 494.660936 -41.725342)
		(end 494.660936 -39.863014)
		(width 0.089408)
		(layer "In9.Cu")
		(net "FM_SLT_CFG1")
	)
	(segment
		(start 468.5538 -6.635242)
		(end 468.5538 -6.009386)
		(width 0.089408)
		(layer "In9.Cu")
		(net "FM_SLT_CFG1")
	)
	(segment
		(start 492.036608 -35.785552)
		(end 492.036608 -29.333952)
		(width 0.089408)
		(layer "In9.Cu")
		(net "FM_SLT_CFG1")
	)
	(segment
		(start 467.837266 -4.094734)
		(end 467.837266 -2.839466)
		(width 0.089408)
		(layer "In9.Cu")
		(net "FM_SLT_CFG1")
	)
	(segment
		(start 492.036608 -29.333952)
		(end 489.744766 -27.04211)
		(width 0.089408)
		(layer "In9.Cu")
		(net "FM_SLT_CFG1")
	)
	(segment
		(start 485.806242 -17.4244)
		(end 483.1842 -17.4244)
		(width 0.089408)
		(layer "In9.Cu")
		(net "FM_SLT_CFG1")
	)
	(segment
		(start 493.198912 -50.63871)
		(end 493.198912 -46.566836)
		(width 0.089408)
		(layer "In9.Cu")
		(net "FM_SLT_CFG1")
	)
	(segment
		(start 479.11004 -11.046206)
		(end 479.047048 -10.983214)
		(width 0.089408)
		(layer "In9.Cu")
		(net "FM_SLT_CFG1")
	)
	(segment
		(start 490.638592 -52.912264)
		(end 490.925358 -52.912264)
		(width 0.089408)
		(layer "In9.Cu")
		(net "FM_SLT_CFG1")
	)
	(segment
		(start 488.525312 -20.14347)
		(end 485.806242 -17.4244)
		(width 0.089408)
		(layer "In9.Cu")
		(net "FM_SLT_CFG1")
	)
	(segment
		(start 493.142778 -46.510702)
		(end 493.142778 -44.570142)
		(width 0.089408)
		(layer "In9.Cu")
		(net "FM_SLT_CFG1")
	)
	(segment
		(start 468.554054 -4.811522)
		(end 467.837266 -4.094734)
		(width 0.089408)
		(layer "In9.Cu")
		(net "FM_SLT_CFG1")
	)
	(segment
		(start 476.95485 -8.891016)
		(end 475.418658 -8.891016)
		(width 0.089408)
		(layer "In9.Cu")
		(net "FM_SLT_CFG1")
	)
	(segment
		(start 492.977932 -36.726876)
		(end 492.036608 -35.785552)
		(width 0.089408)
		(layer "In9.Cu")
		(net "FM_SLT_CFG1")
	)
	(segment
		(start 468.554308 -5.85089)
		(end 468.554054 -5.850636)
		(width 0.089408)
		(layer "In9.Cu")
		(net "FM_SLT_CFG1")
	)
	(segment
		(start 492.977932 -38.18001)
		(end 492.977932 -36.726876)
		(width 0.089408)
		(layer "In9.Cu")
		(net "FM_SLT_CFG1")
	)
	(segment
		(start 482.685852 -16.926052)
		(end 480.166934 -16.926052)
		(width 0.089408)
		(layer "In9.Cu")
		(net "FM_SLT_CFG1")
	)
	(segment
		(start 489.744766 -27.04211)
		(end 489.744766 -24.238966)
		(width 0.089408)
		(layer "In9.Cu")
		(net "FM_SLT_CFG1")
	)
	(segment
		(start 476.968058 -8.904224)
		(end 476.95485 -8.891016)
		(width 0.089408)
		(layer "In9.Cu")
		(net "FM_SLT_CFG1")
	)
	(segment
		(start 490.347 -53.203856)
		(end 490.638592 -52.912264)
		(width 0.089408)
		(layer "In9.Cu")
		(net "FM_SLT_CFG1")
	)
	(segment
		(start 469.670892 -7.752334)
		(end 468.5538 -6.635242)
		(width 0.089408)
		(layer "In9.Cu")
		(net "FM_SLT_CFG1")
	)
	(segment
		(start 480.166934 -16.926052)
		(end 479.11004 -15.869158)
		(width 0.089408)
		(layer "In9.Cu")
		(net "FM_SLT_CFG1")
	)
	(segment
		(start 479.11004 -15.869158)
		(end 479.11004 -11.046206)
		(width 0.089408)
		(layer "In9.Cu")
		(net "FM_SLT_CFG1")
	)
	(segment
		(start 467.837266 -2.839466)
		(end 467.4616 -2.4638)
		(width 0.089408)
		(layer "In9.Cu")
		(net "FM_SLT_CFG1")
	)
	(segment
		(start 479.047048 -10.983214)
		(end 479.047048 -10.018014)
		(width 0.089408)
		(layer "In9.Cu")
		(net "FM_SLT_CFG1")
	)
	(segment
		(start 477.933258 -8.904224)
		(end 476.968058 -8.904224)
		(width 0.089408)
		(layer "In9.Cu")
		(net "FM_SLT_CFG1")
	)
	(segment
		(start 494.660936 -39.863014)
		(end 492.977932 -38.18001)
		(width 0.089408)
		(layer "In9.Cu")
		(net "FM_SLT_CFG1")
	)
	(segment
		(start 474.121734 -7.75208)
		(end 474.12148 -7.752334)
		(width 0.089408)
		(layer "In9.Cu")
		(net "FM_SLT_CFG1")
	)
	(segment
		(start 410.291788 -33.733232)
		(end 410.291788 -32.335978)
		(width 0.089408)
		(layer "In11.Cu")
		(net "FM_SLT_CFG1")
	)
	(segment
		(start 416.743642 -22.655022)
		(end 419.038278 -22.655022)
		(width 0.089408)
		(layer "In11.Cu")
		(net "FM_SLT_CFG1")
	)
	(segment
		(start 439.680858 -18.454624)
		(end 445.500506 -18.454624)
		(width 0.089408)
		(layer "In11.Cu")
		(net "FM_SLT_CFG1")
	)
	(segment
		(start 412.12643 -31.368492)
		(end 412.134812 -31.36011)
		(width 0.089408)
		(layer "In11.Cu")
		(net "FM_SLT_CFG1")
	)
	(segment
		(start 413.526986 -30.301438)
		(end 413.515556 -30.290008)
		(width 0.089408)
		(layer "In11.Cu")
		(net "FM_SLT_CFG1")
	)
	(segment
		(start 421.4241 -20.2692)
		(end 427.733968 -20.2692)
		(width 0.089408)
		(layer "In11.Cu")
		(net "FM_SLT_CFG1")
	)
	(segment
		(start 410.46781 -32.159956)
		(end 410.794454 -32.159956)
		(width 0.089408)
		(layer "In11.Cu")
		(net "FM_SLT_CFG1")
	)
	(segment
		(start 413.602932 -30.555946)
		(end 413.526986 -30.48)
		(width 0.089408)
		(layer "In11.Cu")
		(net "FM_SLT_CFG1")
	)
	(segment
		(start 445.500506 -18.454624)
		(end 446.084706 -17.870424)
		(width 0.089408)
		(layer "In11.Cu")
		(net "FM_SLT_CFG1")
	)
	(segment
		(start 432.686206 -18.593816)
		(end 434.409342 -18.593816)
		(width 0.089408)
		(layer "In11.Cu")
		(net "FM_SLT_CFG1")
	)
	(segment
		(start 432.193192 -19.08683)
		(end 432.686206 -18.593816)
		(width 0.089408)
		(layer "In11.Cu")
		(net "FM_SLT_CFG1")
	)
	(segment
		(start 429.614838 -19.276568)
		(end 429.804576 -19.08683)
		(width 0.089408)
		(layer "In11.Cu")
		(net "FM_SLT_CFG1")
	)
	(segment
		(start 413.475678 -26.811478)
		(end 415.311336 -24.97582)
		(width 0.089408)
		(layer "In11.Cu")
		(net "FM_SLT_CFG1")
	)
	(segment
		(start 412.926276 -31.368492)
		(end 412.934658 -31.36011)
		(width 0.089408)
		(layer "In11.Cu")
		(net "FM_SLT_CFG1")
	)
	(segment
		(start 448.648582 -16.800576)
		(end 448.648582 -15.015464)
		(width 0.089408)
		(layer "In11.Cu")
		(net "FM_SLT_CFG1")
	)
	(segment
		(start 413.526986 -30.48)
		(end 413.526986 -30.301438)
		(width 0.089408)
		(layer "In11.Cu")
		(net "FM_SLT_CFG1")
	)
	(segment
		(start 413.526986 -29.967682)
		(end 413.526986 -29.668724)
		(width 0.089408)
		(layer "In11.Cu")
		(net "FM_SLT_CFG1")
	)
	(segment
		(start 429.804576 -19.08683)
		(end 432.193192 -19.08683)
		(width 0.089408)
		(layer "In11.Cu")
		(net "FM_SLT_CFG1")
	)
	(segment
		(start 413.526986 -29.668724)
		(end 413.475678 -29.617416)
		(width 0.089408)
		(layer "In11.Cu")
		(net "FM_SLT_CFG1")
	)
	(segment
		(start 434.409342 -18.593816)
		(end 435.157118 -19.341592)
		(width 0.089408)
		(layer "In11.Cu")
		(net "FM_SLT_CFG1")
	)
	(segment
		(start 413.475678 -29.617416)
		(end 413.475678 -26.811478)
		(width 0.089408)
		(layer "In11.Cu")
		(net "FM_SLT_CFG1")
	)
	(segment
		(start 412.445708 -31.36011)
		(end 412.45409 -31.368492)
		(width 0.089408)
		(layer "In11.Cu")
		(net "FM_SLT_CFG1")
	)
	(segment
		(start 438.79389 -19.341592)
		(end 439.680858 -18.454624)
		(width 0.089408)
		(layer "In11.Cu")
		(net "FM_SLT_CFG1")
	)
	(segment
		(start 409.890214 -34.134806)
		(end 410.291788 -33.733232)
		(width 0.089408)
		(layer "In11.Cu")
		(net "FM_SLT_CFG1")
	)
	(segment
		(start 411.586426 -31.368492)
		(end 412.12643 -31.368492)
		(width 0.089408)
		(layer "In11.Cu")
		(net "FM_SLT_CFG1")
	)
	(segment
		(start 410.845762 -32.109156)
		(end 411.586426 -31.368492)
		(width 0.089408)
		(layer "In11.Cu")
		(net "FM_SLT_CFG1")
	)
	(segment
		(start 410.845254 -32.109156)
		(end 410.845762 -32.109156)
		(width 0.089408)
		(layer "In11.Cu")
		(net "FM_SLT_CFG1")
	)
	(segment
		(start 447.578734 -17.870424)
		(end 448.648582 -16.800576)
		(width 0.089408)
		(layer "In11.Cu")
		(net "FM_SLT_CFG1")
	)
	(segment
		(start 428.7266 -19.276568)
		(end 429.614838 -19.276568)
		(width 0.089408)
		(layer "In11.Cu")
		(net "FM_SLT_CFG1")
	)
	(segment
		(start 410.291788 -32.335978)
		(end 410.46781 -32.159956)
		(width 0.089408)
		(layer "In11.Cu")
		(net "FM_SLT_CFG1")
	)
	(segment
		(start 435.157118 -19.341592)
		(end 438.79389 -19.341592)
		(width 0.089408)
		(layer "In11.Cu")
		(net "FM_SLT_CFG1")
	)
	(segment
		(start 419.038278 -22.655022)
		(end 421.4241 -20.2692)
		(width 0.089408)
		(layer "In11.Cu")
		(net "FM_SLT_CFG1")
	)
	(segment
		(start 427.733968 -20.2692)
		(end 428.7266 -19.276568)
		(width 0.089408)
		(layer "In11.Cu")
		(net "FM_SLT_CFG1")
	)
	(segment
		(start 412.45409 -31.368492)
		(end 412.926276 -31.368492)
		(width 0.089408)
		(layer "In11.Cu")
		(net "FM_SLT_CFG1")
	)
	(segment
		(start 413.602932 -31.140654)
		(end 413.602932 -30.555946)
		(width 0.089408)
		(layer "In11.Cu")
		(net "FM_SLT_CFG1")
	)
	(segment
		(start 415.311336 -24.087328)
		(end 416.743642 -22.655022)
		(width 0.089408)
		(layer "In11.Cu")
		(net "FM_SLT_CFG1")
	)
	(segment
		(start 446.084706 -17.870424)
		(end 447.578734 -17.870424)
		(width 0.089408)
		(layer "In11.Cu")
		(net "FM_SLT_CFG1")
	)
	(segment
		(start 413.515556 -30.290008)
		(end 413.515556 -29.979112)
		(width 0.089408)
		(layer "In11.Cu")
		(net "FM_SLT_CFG1")
	)
	(segment
		(start 413.375094 -31.368492)
		(end 413.602932 -31.140654)
		(width 0.089408)
		(layer "In11.Cu")
		(net "FM_SLT_CFG1")
	)
	(segment
		(start 413.245554 -31.36011)
		(end 413.253936 -31.368492)
		(width 0.089408)
		(layer "In11.Cu")
		(net "FM_SLT_CFG1")
	)
	(segment
		(start 412.934658 -31.36011)
		(end 413.245554 -31.36011)
		(width 0.089408)
		(layer "In11.Cu")
		(net "FM_SLT_CFG1")
	)
	(segment
		(start 415.311336 -24.97582)
		(end 415.311336 -24.087328)
		(width 0.089408)
		(layer "In11.Cu")
		(net "FM_SLT_CFG1")
	)
	(segment
		(start 413.515556 -29.979112)
		(end 413.526986 -29.967682)
		(width 0.089408)
		(layer "In11.Cu")
		(net "FM_SLT_CFG1")
	)
	(segment
		(start 410.794454 -32.159956)
		(end 410.845254 -32.109156)
		(width 0.089408)
		(layer "In11.Cu")
		(net "FM_SLT_CFG1")
	)
	(segment
		(start 413.253936 -31.368492)
		(end 413.375094 -31.368492)
		(width 0.089408)
		(layer "In11.Cu")
		(net "FM_SLT_CFG1")
	)
	(segment
		(start 412.134812 -31.36011)
		(end 412.445708 -31.36011)
		(width 0.089408)
		(layer "In11.Cu")
		(net "FM_SLT_CFG1")
	)
	(segment
		(start 402.0566 -107.76585)
		(end 402.378926 -108.088176)
		(width 0.0889)
		(layer "F.Cu")
		(net "FM_SLT_CFG0")
	)
	(segment
		(start 404.02891 -108.403644)
		(end 405.47544 -108.403644)
		(width 0.10795)
		(layer "F.Cu")
		(net "FM_SLT_CFG0")
	)
	(segment
		(start 409.43149 -109.09681)
		(end 409.13431 -109.39399)
		(width 0.10795)
		(layer "F.Cu")
		(net "FM_SLT_CFG0")
	)
	(segment
		(start 405.47544 -108.403644)
		(end 406.195276 -109.12348)
		(width 0.10795)
		(layer "F.Cu")
		(net "FM_SLT_CFG0")
	)
	(segment
		(start 403.249638 -108.519722)
		(end 403.912832 -108.519722)
		(width 0.0889)
		(layer "F.Cu")
		(net "FM_SLT_CFG0")
	)
	(segment
		(start 466.725 -9.0678)
		(end 466.725 -8.93318)
		(width 0.10795)
		(layer "F.Cu")
		(net "FM_SLT_CFG0")
	)
	(segment
		(start 402.378926 -108.088176)
		(end 402.818092 -108.088176)
		(width 0.0889)
		(layer "F.Cu")
		(net "FM_SLT_CFG0")
	)
	(segment
		(start 403.912832 -108.519722)
		(end 404.02891 -108.403644)
		(width 0.10795)
		(layer "F.Cu")
		(net "FM_SLT_CFG0")
	)
	(segment
		(start 410.1465 -109.81182)
		(end 410.1465 -109.855)
		(width 0.10795)
		(layer "F.Cu")
		(net "FM_SLT_CFG0")
	)
	(segment
		(start 409.13431 -109.39399)
		(end 406.465786 -109.39399)
		(width 0.10795)
		(layer "F.Cu")
		(net "FM_SLT_CFG0")
	)
	(segment
		(start 401.295108 -107.855004)
		(end 401.384262 -107.76585)
		(width 0.0889)
		(layer "F.Cu")
		(net "FM_SLT_CFG0")
	)
	(segment
		(start 466.879178 -8.779002)
		(end 466.879178 -7.789672)
		(width 0.10795)
		(layer "F.Cu")
		(net "FM_SLT_CFG0")
	)
	(segment
		(start 402.818092 -108.088176)
		(end 403.249638 -108.519722)
		(width 0.0889)
		(layer "F.Cu")
		(net "FM_SLT_CFG0")
	)
	(segment
		(start 401.384262 -107.76585)
		(end 402.0566 -107.76585)
		(width 0.0889)
		(layer "F.Cu")
		(net "FM_SLT_CFG0")
	)
	(segment
		(start 466.725 -8.93318)
		(end 466.879178 -8.779002)
		(width 0.10795)
		(layer "F.Cu")
		(net "FM_SLT_CFG0")
	)
	(segment
		(start 406.465786 -109.39399)
		(end 406.195276 -109.12348)
		(width 0.10795)
		(layer "F.Cu")
		(net "FM_SLT_CFG0")
	)
	(segment
		(start 409.87726 -31.74746)
		(end 409.490164 -32.134556)
		(width 0.10795)
		(layer "F.Cu")
		(net "FM_SLT_CFG0")
	)
	(segment
		(start 409.43149 -109.09681)
		(end 410.1465 -109.81182)
		(width 0.10795)
		(layer "F.Cu")
		(net "FM_SLT_CFG0")
	)
	(via
		(at 471.911426 -39.655242)
		(size 0.508)
		(drill 0.254)
		(layers "F.Cu" "B.Cu")
		(net "FM_SLT_CFG0")
	)
	(via
		(at 409.87726 -31.74746)
		(size 0.4572)
		(drill 0.2032)
		(layers "F.Cu" "B.Cu")
		(net "FM_SLT_CFG0")
	)
	(via
		(at 409.43149 -109.09681)
		(size 0.508)
		(drill 0.254)
		(layers "F.Cu" "B.Cu")
		(net "FM_SLT_CFG0")
	)
	(via
		(at 406.195276 -109.12348)
		(size 0.508)
		(drill 0.254)
		(layers "F.Cu" "B.Cu")
		(net "FM_SLT_CFG0")
	)
	(via
		(at 394.0175 -81.356962)
		(size 0.508)
		(drill 0.254)
		(layers "F.Cu" "B.Cu")
		(net "FM_SLT_CFG0")
	)
	(via
		(at 466.725 -9.0678)
		(size 0.508)
		(drill 0.254)
		(layers "F.Cu" "B.Cu")
		(net "FM_SLT_CFG0")
	)
	(via
		(at 403.913848 -80.11795)
		(size 0.508)
		(drill 0.254)
		(layers "F.Cu" "B.Cu")
		(net "FM_SLT_CFG0")
	)
	(segment
		(start 409.741624 -97.5106)
		(end 409.741624 -93.927422)
		(width 0.089408)
		(layer "In2.Cu")
		(net "FM_SLT_CFG0")
	)
	(segment
		(start 410.057854 -100.431854)
		(end 409.416504 -99.790504)
		(width 0.089408)
		(layer "In2.Cu")
		(net "FM_SLT_CFG0")
	)
	(segment
		(start 406.04948 -90.235278)
		(end 406.04948 -82.492596)
		(width 0.089408)
		(layer "In2.Cu")
		(net "FM_SLT_CFG0")
	)
	(segment
		(start 410.057854 -108.470446)
		(end 410.057854 -100.431854)
		(width 0.089408)
		(layer "In2.Cu")
		(net "FM_SLT_CFG0")
	)
	(segment
		(start 409.416504 -99.790504)
		(end 409.416504 -97.83572)
		(width 0.089408)
		(layer "In2.Cu")
		(net "FM_SLT_CFG0")
	)
	(segment
		(start 406.04948 -82.492596)
		(end 403.913848 -80.356964)
		(width 0.089408)
		(layer "In2.Cu")
		(net "FM_SLT_CFG0")
	)
	(segment
		(start 403.913848 -80.356964)
		(end 403.913848 -80.11795)
		(width 0.089408)
		(layer "In2.Cu")
		(net "FM_SLT_CFG0")
	)
	(segment
		(start 409.43149 -109.09681)
		(end 410.057854 -108.470446)
		(width 0.089408)
		(layer "In2.Cu")
		(net "FM_SLT_CFG0")
	)
	(segment
		(start 409.416504 -97.83572)
		(end 409.741624 -97.5106)
		(width 0.089408)
		(layer "In2.Cu")
		(net "FM_SLT_CFG0")
	)
	(segment
		(start 409.741624 -93.927422)
		(end 406.04948 -90.235278)
		(width 0.089408)
		(layer "In2.Cu")
		(net "FM_SLT_CFG0")
	)
	(segment
		(start 444.655956 -29.304742)
		(end 444.655956 -24.778208)
		(width 0.089408)
		(layer "In4.Cu")
		(net "FM_SLT_CFG0")
	)
	(segment
		(start 402.570442 -79.978758)
		(end 403.774656 -79.978758)
		(width 0.089408)
		(layer "In4.Cu")
		(net "FM_SLT_CFG0")
	)
	(segment
		(start 425.630848 -29.175964)
		(end 425.046902 -29.75991)
		(width 0.089408)
		(layer "In4.Cu")
		(net "FM_SLT_CFG0")
	)
	(segment
		(start 443.571122 -23.693374)
		(end 442.252862 -23.693374)
		(width 0.089408)
		(layer "In4.Cu")
		(net "FM_SLT_CFG0")
	)
	(segment
		(start 463.031332 -35.562286)
		(end 462.577942 -35.108896)
		(width 0.089408)
		(layer "In4.Cu")
		(net "FM_SLT_CFG0")
	)
	(segment
		(start 403.774656 -79.978758)
		(end 403.913848 -80.11795)
		(width 0.089408)
		(layer "In4.Cu")
		(net "FM_SLT_CFG0")
	)
	(segment
		(start 419.22827 -30.369256)
		(end 418.662104 -30.935422)
		(width 0.089408)
		(layer "In4.Cu")
		(net "FM_SLT_CFG0")
	)
	(segment
		(start 400.0246 -80.153002)
		(end 402.396198 -80.153002)
		(width 0.089408)
		(layer "In4.Cu")
		(net "FM_SLT_CFG0")
	)
	(segment
		(start 449.045838 -31.075884)
		(end 446.427098 -31.075884)
		(width 0.089408)
		(layer "In4.Cu")
		(net "FM_SLT_CFG0")
	)
	(segment
		(start 436.116984 -24.237442)
		(end 435.313836 -25.04059)
		(width 0.089408)
		(layer "In4.Cu")
		(net "FM_SLT_CFG0")
	)
	(segment
		(start 458.74432 -34.61004)
		(end 452.579994 -34.61004)
		(width 0.089408)
		(layer "In4.Cu")
		(net "FM_SLT_CFG0")
	)
	(segment
		(start 414.802828 -30.935422)
		(end 413.62884 -32.10941)
		(width 0.089408)
		(layer "In4.Cu")
		(net "FM_SLT_CFG0")
	)
	(segment
		(start 421.486584 -30.330648)
		(end 421.308022 -30.50921)
		(width 0.089408)
		(layer "In4.Cu")
		(net "FM_SLT_CFG0")
	)
	(segment
		(start 468.61095 -40.33647)
		(end 468.61095 -38.548564)
		(width 0.089408)
		(layer "In4.Cu")
		(net "FM_SLT_CFG0")
	)
	(segment
		(start 394.0175 -81.356962)
		(end 394.114274 -81.260188)
		(width 0.089408)
		(layer "In4.Cu")
		(net "FM_SLT_CFG0")
	)
	(segment
		(start 419.985952 -30.50921)
		(end 419.845998 -30.369256)
		(width 0.089408)
		(layer "In4.Cu")
		(net "FM_SLT_CFG0")
	)
	(segment
		(start 471.911426 -39.655242)
		(end 471.911426 -40.263572)
		(width 0.089408)
		(layer "In4.Cu")
		(net "FM_SLT_CFG0")
	)
	(segment
		(start 422.31564 -29.179266)
		(end 422.31564 -29.509974)
		(width 0.089408)
		(layer "In4.Cu")
		(net "FM_SLT_CFG0")
	)
	(segment
		(start 441.466732 -24.479504)
		(end 437.833262 -24.479504)
		(width 0.089408)
		(layer "In4.Cu")
		(net "FM_SLT_CFG0")
	)
	(segment
		(start 461.45831 -35.108642)
		(end 461.258158 -35.108642)
		(width 0.089408)
		(layer "In4.Cu")
		(net "FM_SLT_CFG0")
	)
	(segment
		(start 442.252862 -23.693374)
		(end 441.466732 -24.479504)
		(width 0.089408)
		(layer "In4.Cu")
		(net "FM_SLT_CFG0")
	)
	(segment
		(start 422.065704 -29.75991)
		(end 421.722804 -29.75991)
		(width 0.089408)
		(layer "In4.Cu")
		(net "FM_SLT_CFG0")
	)
	(segment
		(start 444.655956 -24.778208)
		(end 443.571122 -23.693374)
		(width 0.089408)
		(layer "In4.Cu")
		(net "FM_SLT_CFG0")
	)
	(segment
		(start 398.917414 -81.260188)
		(end 400.0246 -80.153002)
		(width 0.089408)
		(layer "In4.Cu")
		(net "FM_SLT_CFG0")
	)
	(segment
		(start 425.046902 -29.75991)
		(end 424.134534 -29.75991)
		(width 0.089408)
		(layer "In4.Cu")
		(net "FM_SLT_CFG0")
	)
	(segment
		(start 424.134534 -29.75991)
		(end 423.864786 -29.490162)
		(width 0.089408)
		(layer "In4.Cu")
		(net "FM_SLT_CFG0")
	)
	(segment
		(start 469.034622 -40.760142)
		(end 468.61095 -40.33647)
		(width 0.089408)
		(layer "In4.Cu")
		(net "FM_SLT_CFG0")
	)
	(segment
		(start 418.662104 -30.935422)
		(end 414.802828 -30.935422)
		(width 0.089408)
		(layer "In4.Cu")
		(net "FM_SLT_CFG0")
	)
	(segment
		(start 421.722804 -29.75991)
		(end 421.486584 -29.99613)
		(width 0.089408)
		(layer "In4.Cu")
		(net "FM_SLT_CFG0")
	)
	(segment
		(start 471.911426 -40.263572)
		(end 471.414856 -40.760142)
		(width 0.089408)
		(layer "In4.Cu")
		(net "FM_SLT_CFG0")
	)
	(segment
		(start 429.935132 -29.175964)
		(end 425.630848 -29.175964)
		(width 0.089408)
		(layer "In4.Cu")
		(net "FM_SLT_CFG0")
	)
	(segment
		(start 452.579994 -34.61004)
		(end 449.045838 -31.075884)
		(width 0.089408)
		(layer "In4.Cu")
		(net "FM_SLT_CFG0")
	)
	(segment
		(start 459.243176 -35.108896)
		(end 458.74432 -34.61004)
		(width 0.089408)
		(layer "In4.Cu")
		(net "FM_SLT_CFG0")
	)
	(segment
		(start 437.833262 -24.479504)
		(end 437.5912 -24.237442)
		(width 0.089408)
		(layer "In4.Cu")
		(net "FM_SLT_CFG0")
	)
	(segment
		(start 433.168298 -27.268424)
		(end 431.842672 -27.268424)
		(width 0.089408)
		(layer "In4.Cu")
		(net "FM_SLT_CFG0")
	)
	(segment
		(start 437.5912 -24.237442)
		(end 436.116984 -24.237442)
		(width 0.089408)
		(layer "In4.Cu")
		(net "FM_SLT_CFG0")
	)
	(segment
		(start 423.864786 -29.179266)
		(end 423.645584 -28.960064)
		(width 0.089408)
		(layer "In4.Cu")
		(net "FM_SLT_CFG0")
	)
	(segment
		(start 435.313836 -25.04059)
		(end 435.313836 -25.122886)
		(width 0.089408)
		(layer "In4.Cu")
		(net "FM_SLT_CFG0")
	)
	(segment
		(start 461.458564 -35.108896)
		(end 461.45831 -35.108642)
		(width 0.089408)
		(layer "In4.Cu")
		(net "FM_SLT_CFG0")
	)
	(segment
		(start 421.308022 -30.50921)
		(end 419.985952 -30.50921)
		(width 0.089408)
		(layer "In4.Cu")
		(net "FM_SLT_CFG0")
	)
	(segment
		(start 446.427098 -31.075884)
		(end 444.655956 -29.304742)
		(width 0.089408)
		(layer "In4.Cu")
		(net "FM_SLT_CFG0")
	)
	(segment
		(start 461.257904 -35.108896)
		(end 459.243176 -35.108896)
		(width 0.089408)
		(layer "In4.Cu")
		(net "FM_SLT_CFG0")
	)
	(segment
		(start 462.577942 -35.108896)
		(end 461.458564 -35.108896)
		(width 0.089408)
		(layer "In4.Cu")
		(net "FM_SLT_CFG0")
	)
	(segment
		(start 435.313836 -25.122886)
		(end 433.168298 -27.268424)
		(width 0.089408)
		(layer "In4.Cu")
		(net "FM_SLT_CFG0")
	)
	(segment
		(start 465.189062 -35.562286)
		(end 463.031332 -35.562286)
		(width 0.089408)
		(layer "In4.Cu")
		(net "FM_SLT_CFG0")
	)
	(segment
		(start 402.396198 -80.153002)
		(end 402.570442 -79.978758)
		(width 0.089408)
		(layer "In4.Cu")
		(net "FM_SLT_CFG0")
	)
	(segment
		(start 413.62884 -32.10941)
		(end 410.23921 -32.10941)
		(width 0.089408)
		(layer "In4.Cu")
		(net "FM_SLT_CFG0")
	)
	(segment
		(start 467.249764 -37.187378)
		(end 466.814154 -37.187378)
		(width 0.089408)
		(layer "In4.Cu")
		(net "FM_SLT_CFG0")
	)
	(segment
		(start 468.61095 -38.548564)
		(end 467.249764 -37.187378)
		(width 0.089408)
		(layer "In4.Cu")
		(net "FM_SLT_CFG0")
	)
	(segment
		(start 466.814154 -37.187378)
		(end 465.189062 -35.562286)
		(width 0.089408)
		(layer "In4.Cu")
		(net "FM_SLT_CFG0")
	)
	(segment
		(start 410.23921 -32.10941)
		(end 409.87726 -31.74746)
		(width 0.089408)
		(layer "In4.Cu")
		(net "FM_SLT_CFG0")
	)
	(segment
		(start 419.845998 -30.369256)
		(end 419.22827 -30.369256)
		(width 0.089408)
		(layer "In4.Cu")
		(net "FM_SLT_CFG0")
	)
	(segment
		(start 421.486584 -29.99613)
		(end 421.486584 -30.330648)
		(width 0.089408)
		(layer "In4.Cu")
		(net "FM_SLT_CFG0")
	)
	(segment
		(start 423.645584 -28.960064)
		(end 422.534842 -28.960064)
		(width 0.089408)
		(layer "In4.Cu")
		(net "FM_SLT_CFG0")
	)
	(segment
		(start 422.534842 -28.960064)
		(end 422.31564 -29.179266)
		(width 0.089408)
		(layer "In4.Cu")
		(net "FM_SLT_CFG0")
	)
	(segment
		(start 471.414856 -40.760142)
		(end 469.034622 -40.760142)
		(width 0.089408)
		(layer "In4.Cu")
		(net "FM_SLT_CFG0")
	)
	(segment
		(start 394.114274 -81.260188)
		(end 398.917414 -81.260188)
		(width 0.089408)
		(layer "In4.Cu")
		(net "FM_SLT_CFG0")
	)
	(segment
		(start 461.258158 -35.108642)
		(end 461.257904 -35.108896)
		(width 0.089408)
		(layer "In4.Cu")
		(net "FM_SLT_CFG0")
	)
	(segment
		(start 431.842672 -27.268424)
		(end 429.935132 -29.175964)
		(width 0.089408)
		(layer "In4.Cu")
		(net "FM_SLT_CFG0")
	)
	(segment
		(start 423.864786 -29.490162)
		(end 423.864786 -29.179266)
		(width 0.089408)
		(layer "In4.Cu")
		(net "FM_SLT_CFG0")
	)
	(segment
		(start 422.31564 -29.509974)
		(end 422.065704 -29.75991)
		(width 0.089408)
		(layer "In4.Cu")
		(net "FM_SLT_CFG0")
	)
	(segment
		(start 468.912448 -13.524992)
		(end 468.050372 -12.662916)
		(width 0.089408)
		(layer "In9.Cu")
		(net "FM_SLT_CFG0")
	)
	(segment
		(start 396.957296 -64.680592)
		(end 396.994634 -64.680592)
		(width 0.089408)
		(layer "In9.Cu")
		(net "FM_SLT_CFG0")
	)
	(segment
		(start 394.512546 -75.745594)
		(end 394.512546 -73.62952)
		(width 0.089408)
		(layer "In9.Cu")
		(net "FM_SLT_CFG0")
	)
	(segment
		(start 396.423134 -69.5579)
		(end 396.423134 -65.214754)
		(width 0.089408)
		(layer "In9.Cu")
		(net "FM_SLT_CFG0")
	)
	(segment
		(start 403.93874 -31.734506)
		(end 407.66365 -31.734506)
		(width 0.089408)
		(layer "In9.Cu")
		(net "FM_SLT_CFG0")
	)
	(segment
		(start 393.456922 -76.801218)
		(end 394.512546 -75.745594)
		(width 0.089408)
		(layer "In9.Cu")
		(net "FM_SLT_CFG0")
	)
	(segment
		(start 467.2076 -8.5852)
		(end 466.725 -9.0678)
		(width 0.089408)
		(layer "In9.Cu")
		(net "FM_SLT_CFG0")
	)
	(segment
		(start 398.066768 -61.759084)
		(end 398.066768 -61.688218)
		(width 0.089408)
		(layer "In9.Cu")
		(net "FM_SLT_CFG0")
	)
	(segment
		(start 393.457176 -78.062328)
		(end 393.457176 -77.288136)
		(width 0.089408)
		(layer "In9.Cu")
		(net "FM_SLT_CFG0")
	)
	(segment
		(start 475.35465 -18.138394)
		(end 470.741248 -13.524992)
		(width 0.089408)
		(layer "In9.Cu")
		(net "FM_SLT_CFG0")
	)
	(segment
		(start 393.456922 -77.287882)
		(end 393.456922 -76.801218)
		(width 0.089408)
		(layer "In9.Cu")
		(net "FM_SLT_CFG0")
	)
	(segment
		(start 475.35465 -25.092406)
		(end 475.35465 -18.138394)
		(width 0.089408)
		(layer "In9.Cu")
		(net "FM_SLT_CFG0")
	)
	(segment
		(start 394.512546 -73.62952)
		(end 394.788898 -73.353168)
		(width 0.089408)
		(layer "In9.Cu")
		(net "FM_SLT_CFG0")
	)
	(segment
		(start 397.753078 -46.957234)
		(end 397.48714 -46.691296)
		(width 0.089408)
		(layer "In9.Cu")
		(net "FM_SLT_CFG0")
	)
	(segment
		(start 393.457176 -77.288136)
		(end 393.456922 -77.287882)
		(width 0.089408)
		(layer "In9.Cu")
		(net "FM_SLT_CFG0")
	)
	(segment
		(start 400.277838 -43.481498)
		(end 400.277838 -37.749988)
		(width 0.089408)
		(layer "In9.Cu")
		(net "FM_SLT_CFG0")
	)
	(segment
		(start 471.915998 -39.655242)
		(end 471.915998 -39.44239)
		(width 0.089408)
		(layer "In9.Cu")
		(net "FM_SLT_CFG0")
	)
	(segment
		(start 398.066768 -61.688218)
		(end 398.067022 -61.687964)
		(width 0.089408)
		(layer "In9.Cu")
		(net "FM_SLT_CFG0")
	)
	(segment
		(start 470.41054 -35.325812)
		(end 470.41054 -32.11322)
		(width 0.089408)
		(layer "In9.Cu")
		(net "FM_SLT_CFG0")
	)
	(segment
		(start 397.154654 -64.67856)
		(end 397.156686 -64.680592)
		(width 0.089408)
		(layer "In9.Cu")
		(net "FM_SLT_CFG0")
	)
	(segment
		(start 467.753954 -8.5852)
		(end 467.2076 -8.5852)
		(width 0.089408)
		(layer "In9.Cu")
		(net "FM_SLT_CFG0")
	)
	(segment
		(start 393.274296 -78.245208)
		(end 393.457176 -78.062328)
		(width 0.089408)
		(layer "In9.Cu")
		(net "FM_SLT_CFG0")
	)
	(segment
		(start 407.66365 -31.734506)
		(end 408.0383 -32.109156)
		(width 0.089408)
		(layer "In9.Cu")
		(net "FM_SLT_CFG0")
	)
	(segment
		(start 395.0462 -71.813166)
		(end 395.0462 -70.934834)
		(width 0.089408)
		(layer "In9.Cu")
		(net "FM_SLT_CFG0")
	)
	(segment
		(start 471.911426 -39.655242)
		(end 471.915998 -39.655242)
		(width 0.089408)
		(layer "In9.Cu")
		(net "FM_SLT_CFG0")
	)
	(segment
		(start 396.996666 -64.67856)
		(end 397.154654 -64.67856)
		(width 0.089408)
		(layer "In9.Cu")
		(net "FM_SLT_CFG0")
	)
	(segment
		(start 393.8524 -79.548228)
		(end 393.274296 -78.970124)
		(width 0.089408)
		(layer "In9.Cu")
		(net "FM_SLT_CFG0")
	)
	(segment
		(start 397.156686 -64.680592)
		(end 397.320516 -64.680592)
		(width 0.089408)
		(layer "In9.Cu")
		(net "FM_SLT_CFG0")
	)
	(segment
		(start 409.515564 -32.109156)
		(end 409.87726 -31.74746)
		(width 0.089408)
		(layer "In9.Cu")
		(net "FM_SLT_CFG0")
	)
	(segment
		(start 397.868902 -45.494956)
		(end 398.26438 -45.494956)
		(width 0.089408)
		(layer "In9.Cu")
		(net "FM_SLT_CFG0")
	)
	(segment
		(start 397.70812 -64.292988)
		(end 397.70812 -62.117732)
		(width 0.089408)
		(layer "In9.Cu")
		(net "FM_SLT_CFG0")
	)
	(segment
		(start 468.050372 -8.881618)
		(end 467.753954 -8.5852)
		(width 0.089408)
		(layer "In9.Cu")
		(net "FM_SLT_CFG0")
	)
	(segment
		(start 395.0462 -70.934834)
		(end 396.423134 -69.5579)
		(width 0.089408)
		(layer "In9.Cu")
		(net "FM_SLT_CFG0")
	)
	(segment
		(start 470.41054 -32.11322)
		(end 472.814904 -29.708856)
		(width 0.089408)
		(layer "In9.Cu")
		(net "FM_SLT_CFG0")
	)
	(segment
		(start 398.26438 -45.494956)
		(end 400.277838 -43.481498)
		(width 0.089408)
		(layer "In9.Cu")
		(net "FM_SLT_CFG0")
	)
	(segment
		(start 394.788898 -73.353168)
		(end 394.788898 -72.070468)
		(width 0.089408)
		(layer "In9.Cu")
		(net "FM_SLT_CFG0")
	)
	(segment
		(start 393.8524 -81.191862)
		(end 393.8524 -79.548228)
		(width 0.089408)
		(layer "In9.Cu")
		(net "FM_SLT_CFG0")
	)
	(segment
		(start 472.814904 -29.708856)
		(end 472.814904 -27.632152)
		(width 0.089408)
		(layer "In9.Cu")
		(net "FM_SLT_CFG0")
	)
	(segment
		(start 468.050372 -12.662916)
		(end 468.050372 -8.881618)
		(width 0.089408)
		(layer "In9.Cu")
		(net "FM_SLT_CFG0")
	)
	(segment
		(start 401.80387 -36.223956)
		(end 401.80387 -33.869376)
		(width 0.089408)
		(layer "In9.Cu")
		(net "FM_SLT_CFG0")
	)
	(segment
		(start 400.277838 -37.749988)
		(end 401.80387 -36.223956)
		(width 0.089408)
		(layer "In9.Cu")
		(net "FM_SLT_CFG0")
	)
	(segment
		(start 398.067022 -61.687964)
		(end 398.067022 -60.737496)
		(width 0.089408)
		(layer "In9.Cu")
		(net "FM_SLT_CFG0")
	)
	(segment
		(start 408.0383 -32.109156)
		(end 409.515564 -32.109156)
		(width 0.089408)
		(layer "In9.Cu")
		(net "FM_SLT_CFG0")
	)
	(segment
		(start 470.56548 -38.091872)
		(end 470.56548 -35.480752)
		(width 0.089408)
		(layer "In9.Cu")
		(net "FM_SLT_CFG0")
	)
	(segment
		(start 397.320516 -64.680592)
		(end 397.70812 -64.292988)
		(width 0.089408)
		(layer "In9.Cu")
		(net "FM_SLT_CFG0")
	)
	(segment
		(start 396.423134 -65.214754)
		(end 396.957296 -64.680592)
		(width 0.089408)
		(layer "In9.Cu")
		(net "FM_SLT_CFG0")
	)
	(segment
		(start 470.56548 -35.480752)
		(end 470.41054 -35.325812)
		(width 0.089408)
		(layer "In9.Cu")
		(net "FM_SLT_CFG0")
	)
	(segment
		(start 401.80387 -33.869376)
		(end 403.93874 -31.734506)
		(width 0.089408)
		(layer "In9.Cu")
		(net "FM_SLT_CFG0")
	)
	(segment
		(start 397.753078 -58.457338)
		(end 397.753078 -46.957234)
		(width 0.089408)
		(layer "In9.Cu")
		(net "FM_SLT_CFG0")
	)
	(segment
		(start 472.814904 -27.632152)
		(end 475.35465 -25.092406)
		(width 0.089408)
		(layer "In9.Cu")
		(net "FM_SLT_CFG0")
	)
	(segment
		(start 397.48714 -45.876718)
		(end 397.868902 -45.494956)
		(width 0.089408)
		(layer "In9.Cu")
		(net "FM_SLT_CFG0")
	)
	(segment
		(start 396.994634 -64.680592)
		(end 396.996666 -64.67856)
		(width 0.089408)
		(layer "In9.Cu")
		(net "FM_SLT_CFG0")
	)
	(segment
		(start 397.48714 -46.691296)
		(end 397.48714 -45.876718)
		(width 0.089408)
		(layer "In9.Cu")
		(net "FM_SLT_CFG0")
	)
	(segment
		(start 394.0175 -81.356962)
		(end 393.8524 -81.191862)
		(width 0.089408)
		(layer "In9.Cu")
		(net "FM_SLT_CFG0")
	)
	(segment
		(start 393.274296 -78.970124)
		(end 393.274296 -78.245208)
		(width 0.089408)
		(layer "In9.Cu")
		(net "FM_SLT_CFG0")
	)
	(segment
		(start 394.788898 -72.070468)
		(end 395.0462 -71.813166)
		(width 0.089408)
		(layer "In9.Cu")
		(net "FM_SLT_CFG0")
	)
	(segment
		(start 398.067022 -60.737496)
		(end 398.066768 -60.737242)
		(width 0.089408)
		(layer "In9.Cu")
		(net "FM_SLT_CFG0")
	)
	(segment
		(start 398.066768 -60.737242)
		(end 398.066768 -58.771028)
		(width 0.089408)
		(layer "In9.Cu")
		(net "FM_SLT_CFG0")
	)
	(segment
		(start 398.066768 -58.771028)
		(end 397.753078 -58.457338)
		(width 0.089408)
		(layer "In9.Cu")
		(net "FM_SLT_CFG0")
	)
	(segment
		(start 470.741248 -13.524992)
		(end 468.912448 -13.524992)
		(width 0.089408)
		(layer "In9.Cu")
		(net "FM_SLT_CFG0")
	)
	(segment
		(start 471.915998 -39.44239)
		(end 470.56548 -38.091872)
		(width 0.089408)
		(layer "In9.Cu")
		(net "FM_SLT_CFG0")
	)
	(segment
		(start 397.70812 -62.117732)
		(end 398.066768 -61.759084)
		(width 0.089408)
		(layer "In9.Cu")
		(net "FM_SLT_CFG0")
	)
	(segment
		(start 387.579616 -7.789672)
		(end 387.135116 -7.345172)
		(width 0.10795)
		(layer "F.Cu")
		(net "FM_PRSNT_2_6_N")
	)
	(segment
		(start 383.77495 -100.41128)
		(end 384.27025 -100.181156)
		(width 0.10795)
		(layer "F.Cu")
		(net "FM_PRSNT_2_6_N")
	)
	(segment
		(start 391.670286 -7.789672)
		(end 387.579616 -7.789672)
		(width 0.10795)
		(layer "F.Cu")
		(net "FM_PRSNT_2_6_N")
	)
	(via
		(at 386.522214 -16.548354)
		(size 0.6604)
		(drill 0.3302)
		(layers "F.Cu" "B.Cu")
		(net "FM_PRSNT_2_6_N")
	)
	(via
		(at 384.27025 -100.181156)
		(size 0.508)
		(drill 0.254)
		(layers "F.Cu" "B.Cu")
		(net "FM_PRSNT_2_6_N")
	)
	(via
		(at 392.4935 -22.44344)
		(size 0.508)
		(drill 0.254)
		(layers "F.Cu" "B.Cu")
		(net "FM_PRSNT_2_6_N")
	)
	(via
		(at 387.135116 -7.345172)
		(size 0.508)
		(drill 0.254)
		(layers "F.Cu" "B.Cu")
		(net "FM_PRSNT_2_6_N")
	)
	(segment
		(start 387.132576 -7.345172)
		(end 387.132576 -9.235186)
		(width 0.10795)
		(layer "B.Cu")
		(net "FM_PRSNT_2_6_N")
	)
	(segment
		(start 373.3165 -94.2213)
		(end 373.741696 -94.646496)
		(width 0.10795)
		(layer "B.Cu")
		(net "FM_PRSNT_2_6_N")
	)
	(segment
		(start 373.3165 -93.853)
		(end 373.3165 -94.2213)
		(width 0.10795)
		(layer "B.Cu")
		(net "FM_PRSNT_2_6_N")
	)
	(segment
		(start 376.944382 -96.972628)
		(end 377.674886 -96.972628)
		(width 0.0889)
		(layer "B.Cu")
		(net "FM_PRSNT_2_6_N")
	)
	(segment
		(start 385.649216 -10.718546)
		(end 385.649216 -15.675356)
		(width 0.10795)
		(layer "B.Cu")
		(net "FM_PRSNT_2_6_N")
	)
	(segment
		(start 385.649216 -15.675356)
		(end 386.522214 -16.548354)
		(width 0.10795)
		(layer "B.Cu")
		(net "FM_PRSNT_2_6_N")
	)
	(segment
		(start 373.741696 -95.865696)
		(end 373.878856 -96.002856)
		(width 0.10795)
		(layer "B.Cu")
		(net "FM_PRSNT_2_6_N")
	)
	(segment
		(start 386.819648 -16.845788)
		(end 386.522214 -16.548354)
		(width 0.10795)
		(layer "B.Cu")
		(net "FM_PRSNT_2_6_N")
	)
	(segment
		(start 389.347964 -20.98929)
		(end 388.557262 -21.779992)
		(width 0.10795)
		(layer "B.Cu")
		(net "FM_PRSNT_2_6_N")
	)
	(segment
		(start 373.741696 -94.646496)
		(end 373.741696 -95.865696)
		(width 0.10795)
		(layer "B.Cu")
		(net "FM_PRSNT_2_6_N")
	)
	(segment
		(start 380.4031 -99.301046)
		(end 380.4031 -99.333812)
		(width 0.0889)
		(layer "B.Cu")
		(net "FM_PRSNT_2_6_N")
	)
	(segment
		(start 378.4219 -97.584006)
		(end 378.4219 -97.616772)
		(width 0.0889)
		(layer "B.Cu")
		(net "FM_PRSNT_2_6_N")
	)
	(segment
		(start 392.4935 -22.44344)
		(end 392.4935 -22.079966)
		(width 0.10795)
		(layer "B.Cu")
		(net "FM_PRSNT_2_6_N")
	)
	(segment
		(start 387.49351 -21.779992)
		(end 386.819648 -21.10613)
		(width 0.10795)
		(layer "B.Cu")
		(net "FM_PRSNT_2_6_N")
	)
	(segment
		(start 375.97461 -96.002856)
		(end 376.822208 -96.850454)
		(width 0.10795)
		(layer "B.Cu")
		(net "FM_PRSNT_2_6_N")
	)
	(segment
		(start 376.822208 -96.850454)
		(end 376.944382 -96.972628)
		(width 0.0889)
		(layer "B.Cu")
		(net "FM_PRSNT_2_6_N")
	)
	(segment
		(start 378.9172 -98.442526)
		(end 378.9172 -98.475292)
		(width 0.0889)
		(layer "B.Cu")
		(net "FM_PRSNT_2_6_N")
	)
	(segment
		(start 387.132576 -9.235186)
		(end 385.649216 -10.718546)
		(width 0.10795)
		(layer "B.Cu")
		(net "FM_PRSNT_2_6_N")
	)
	(segment
		(start 373.878856 -96.002856)
		(end 375.97461 -96.002856)
		(width 0.10795)
		(layer "B.Cu")
		(net "FM_PRSNT_2_6_N")
	)
	(segment
		(start 381.889 -100.159566)
		(end 381.889 -100.192332)
		(width 0.0889)
		(layer "B.Cu")
		(net "FM_PRSNT_2_6_N")
	)
	(segment
		(start 387.135116 -7.345172)
		(end 387.132576 -7.345172)
		(width 0.10795)
		(layer "B.Cu")
		(net "FM_PRSNT_2_6_N")
	)
	(segment
		(start 388.557262 -21.779992)
		(end 387.49351 -21.779992)
		(width 0.10795)
		(layer "B.Cu")
		(net "FM_PRSNT_2_6_N")
	)
	(segment
		(start 391.402824 -20.98929)
		(end 389.347964 -20.98929)
		(width 0.10795)
		(layer "B.Cu")
		(net "FM_PRSNT_2_6_N")
	)
	(segment
		(start 392.4935 -22.079966)
		(end 391.402824 -20.98929)
		(width 0.10795)
		(layer "B.Cu")
		(net "FM_PRSNT_2_6_N")
	)
	(segment
		(start 386.819648 -21.10613)
		(end 386.819648 -16.845788)
		(width 0.10795)
		(layer "B.Cu")
		(net "FM_PRSNT_2_6_N")
	)
	(arc
		(start 379.517148 -98.810826)
		(mid 379.81255 -98.731695)
		(end 380.107952 -98.810826)
		(width 0.0889)
		(layer "B.Cu")
		(net "FM_PRSNT_2_6_N")
	)
	(arc
		(start 383.479548 -100.527866)
		(mid 383.865375 -100.33279)
		(end 384.27025 -100.181156)
		(width 0.0889)
		(layer "B.Cu")
		(net "FM_PRSNT_2_6_N")
	)
	(arc
		(start 380.4031 -99.333812)
		(mid 380.45945 -99.527662)
		(end 380.603252 -99.669346)
		(width 0.0889)
		(layer "B.Cu")
		(net "FM_PRSNT_2_6_N")
	)
	(arc
		(start 380.603252 -99.669346)
		(mid 380.80315 -99.722845)
		(end 381.003048 -99.669346)
		(width 0.0889)
		(layer "B.Cu")
		(net "FM_PRSNT_2_6_N")
	)
	(arc
		(start 381.593852 -99.669346)
		(mid 381.804716 -99.87635)
		(end 381.889 -100.159566)
		(width 0.0889)
		(layer "B.Cu")
		(net "FM_PRSNT_2_6_N")
	)
	(arc
		(start 378.9172 -98.475292)
		(mid 378.97355 -98.669142)
		(end 379.117352 -98.810826)
		(width 0.0889)
		(layer "B.Cu")
		(net "FM_PRSNT_2_6_N")
	)
	(arc
		(start 382.089152 -100.527866)
		(mid 382.28905 -100.581365)
		(end 382.488948 -100.527866)
		(width 0.0889)
		(layer "B.Cu")
		(net "FM_PRSNT_2_6_N")
	)
	(arc
		(start 382.488948 -100.527866)
		(mid 382.78435 -100.448735)
		(end 383.079752 -100.527866)
		(width 0.0889)
		(layer "B.Cu")
		(net "FM_PRSNT_2_6_N")
	)
	(arc
		(start 379.117352 -98.810826)
		(mid 379.31725 -98.864325)
		(end 379.517148 -98.810826)
		(width 0.0889)
		(layer "B.Cu")
		(net "FM_PRSNT_2_6_N")
	)
	(arc
		(start 378.126752 -97.093786)
		(mid 378.337616 -97.30079)
		(end 378.4219 -97.584006)
		(width 0.0889)
		(layer "B.Cu")
		(net "FM_PRSNT_2_6_N")
	)
	(arc
		(start 381.003048 -99.669346)
		(mid 381.29845 -99.590215)
		(end 381.593852 -99.669346)
		(width 0.0889)
		(layer "B.Cu")
		(net "FM_PRSNT_2_6_N")
	)
	(arc
		(start 377.674886 -96.972628)
		(mid 377.908804 -97.003435)
		(end 378.126752 -97.093786)
		(width 0.0889)
		(layer "B.Cu")
		(net "FM_PRSNT_2_6_N")
	)
	(arc
		(start 378.622052 -97.952306)
		(mid 378.832916 -98.15931)
		(end 378.9172 -98.442526)
		(width 0.0889)
		(layer "B.Cu")
		(net "FM_PRSNT_2_6_N")
	)
	(arc
		(start 380.107952 -98.810826)
		(mid 380.318816 -99.01783)
		(end 380.4031 -99.301046)
		(width 0.0889)
		(layer "B.Cu")
		(net "FM_PRSNT_2_6_N")
	)
	(arc
		(start 378.4219 -97.616772)
		(mid 378.47825 -97.810622)
		(end 378.622052 -97.952306)
		(width 0.0889)
		(layer "B.Cu")
		(net "FM_PRSNT_2_6_N")
	)
	(arc
		(start 383.079752 -100.527866)
		(mid 383.27965 -100.581365)
		(end 383.479548 -100.527866)
		(width 0.0889)
		(layer "B.Cu")
		(net "FM_PRSNT_2_6_N")
	)
	(arc
		(start 381.889 -100.192332)
		(mid 381.94535 -100.386182)
		(end 382.089152 -100.527866)
		(width 0.0889)
		(layer "B.Cu")
		(net "FM_PRSNT_2_6_N")
	)
	(segment
		(start 393.319762 -40.651684)
		(end 393.319762 -41.58615)
		(width 0.089408)
		(layer "In9.Cu")
		(net "FM_PRSNT_2_6_N")
	)
	(segment
		(start 392.726926 -61.325252)
		(end 392.328146 -61.724032)
		(width 0.089408)
		(layer "In9.Cu")
		(net "FM_PRSNT_2_6_N")
	)
	(segment
		(start 393.248896 -60.192666)
		(end 392.726926 -60.714636)
		(width 0.089408)
		(layer "In9.Cu")
		(net "FM_PRSNT_2_6_N")
	)
	(segment
		(start 390.673336 -71.47814)
		(end 390.220708 -71.930768)
		(width 0.089408)
		(layer "In9.Cu")
		(net "FM_PRSNT_2_6_N")
	)
	(segment
		(start 391.547096 -46.934374)
		(end 391.791952 -47.17923)
		(width 0.089408)
		(layer "In9.Cu")
		(net "FM_PRSNT_2_6_N")
	)
	(segment
		(start 390.220454 -72.43445)
		(end 390.220708 -72.434704)
		(width 0.089408)
		(layer "In9.Cu")
		(net "FM_PRSNT_2_6_N")
	)
	(segment
		(start 388.58571 -84.077302)
		(end 387.436614 -85.226398)
		(width 0.089408)
		(layer "In9.Cu")
		(net "FM_PRSNT_2_6_N")
	)
	(segment
		(start 390.220708 -72.117712)
		(end 390.2202 -72.11822)
		(width 0.089408)
		(layer "In9.Cu")
		(net "FM_PRSNT_2_6_N")
	)
	(segment
		(start 392.067034 -26.822146)
		(end 392.112246 -26.867358)
		(width 0.089408)
		(layer "In9.Cu")
		(net "FM_PRSNT_2_6_N")
	)
	(segment
		(start 392.4935 -22.44344)
		(end 392.4935 -22.52853)
		(width 0.089408)
		(layer "In9.Cu")
		(net "FM_PRSNT_2_6_N")
	)
	(segment
		(start 392.932412 -37.190172)
		(end 392.932412 -40.264334)
		(width 0.089408)
		(layer "In9.Cu")
		(net "FM_PRSNT_2_6_N")
	)
	(segment
		(start 391.31621 -32.873188)
		(end 391.31621 -33.94329)
		(width 0.089408)
		(layer "In9.Cu")
		(net "FM_PRSNT_2_6_N")
	)
	(segment
		(start 381.536448 -91.478608)
		(end 381.536448 -91.589352)
		(width 0.0889)
		(layer "In9.Cu")
		(net "FM_PRSNT_2_6_N")
	)
	(segment
		(start 383.84226 -100.000562)
		(end 384.022854 -100.181156)
		(width 0.089408)
		(layer "In9.Cu")
		(net "FM_PRSNT_2_6_N")
	)
	(segment
		(start 393.319762 -41.58615)
		(end 392.089386 -42.817288)
		(width 0.089408)
		(layer "In9.Cu")
		(net "FM_PRSNT_2_6_N")
	)
	(segment
		(start 390.2202 -72.276208)
		(end 390.220454 -72.276462)
		(width 0.089408)
		(layer "In9.Cu")
		(net "FM_PRSNT_2_6_N")
	)
	(segment
		(start 388.58571 -83.587082)
		(end 388.58571 -84.077302)
		(width 0.089408)
		(layer "In9.Cu")
		(net "FM_PRSNT_2_6_N")
	)
	(segment
		(start 393.248896 -54.006496)
		(end 393.248896 -60.192666)
		(width 0.089408)
		(layer "In9.Cu")
		(net "FM_PRSNT_2_6_N")
	)
	(segment
		(start 390.220454 -72.276462)
		(end 390.220454 -72.43445)
		(width 0.089408)
		(layer "In9.Cu")
		(net "FM_PRSNT_2_6_N")
	)
	(segment
		(start 382.8796 -98.442526)
		(end 382.8796 -98.475292)
		(width 0.0889)
		(layer "In9.Cu")
		(net "FM_PRSNT_2_6_N")
	)
	(segment
		(start 386.930646 -79.4512)
		(end 387.86181 -80.382364)
		(width 0.089408)
		(layer "In9.Cu")
		(net "FM_PRSNT_2_6_N")
	)
	(segment
		(start 390.220708 -73.54189)
		(end 389.146288 -74.61631)
		(width 0.089408)
		(layer "In9.Cu")
		(net "FM_PRSNT_2_6_N")
	)
	(segment
		(start 391.791952 -51.67503)
		(end 392.486642 -52.36972)
		(width 0.089408)
		(layer "In9.Cu")
		(net "FM_PRSNT_2_6_N")
	)
	(segment
		(start 392.655298 -23.779734)
		(end 392.059414 -24.375618)
		(width 0.089408)
		(layer "In9.Cu")
		(net "FM_PRSNT_2_6_N")
	)
	(segment
		(start 392.932412 -40.264334)
		(end 393.319762 -40.651684)
		(width 0.089408)
		(layer "In9.Cu")
		(net "FM_PRSNT_2_6_N")
	)
	(segment
		(start 387.86181 -82.863182)
		(end 388.58571 -83.587082)
		(width 0.089408)
		(layer "In9.Cu")
		(net "FM_PRSNT_2_6_N")
	)
	(segment
		(start 389.885682 -68.307204)
		(end 390.673336 -69.094858)
		(width 0.089408)
		(layer "In9.Cu")
		(net "FM_PRSNT_2_6_N")
	)
	(segment
		(start 386.25272 -85.226398)
		(end 385.301236 -86.177882)
		(width 0.089408)
		(layer "In9.Cu")
		(net "FM_PRSNT_2_6_N")
	)
	(segment
		(start 391.547096 -46.402244)
		(end 391.547096 -46.934374)
		(width 0.089408)
		(layer "In9.Cu")
		(net "FM_PRSNT_2_6_N")
	)
	(segment
		(start 392.328146 -64.56172)
		(end 389.885682 -67.004184)
		(width 0.089408)
		(layer "In9.Cu")
		(net "FM_PRSNT_2_6_N")
	)
	(segment
		(start 387.86181 -80.382364)
		(end 387.86181 -82.863182)
		(width 0.089408)
		(layer "In9.Cu")
		(net "FM_PRSNT_2_6_N")
	)
	(segment
		(start 389.146288 -74.61631)
		(end 389.146288 -75.840844)
		(width 0.089408)
		(layer "In9.Cu")
		(net "FM_PRSNT_2_6_N")
	)
	(segment
		(start 381.3937 -95.614236)
		(end 381.3937 -95.899732)
		(width 0.0889)
		(layer "In9.Cu")
		(net "FM_PRSNT_2_6_N")
	)
	(segment
		(start 392.328146 -61.724032)
		(end 392.328146 -64.56172)
		(width 0.089408)
		(layer "In9.Cu")
		(net "FM_PRSNT_2_6_N")
	)
	(segment
		(start 392.486642 -52.36972)
		(end 392.486642 -53.244242)
		(width 0.089408)
		(layer "In9.Cu")
		(net "FM_PRSNT_2_6_N")
	)
	(segment
		(start 392.059414 -24.375618)
		(end 392.059414 -26.264108)
		(width 0.089408)
		(layer "In9.Cu")
		(net "FM_PRSNT_2_6_N")
	)
	(segment
		(start 381.536448 -90.175842)
		(end 381.536448 -91.478608)
		(width 0.089408)
		(layer "In9.Cu")
		(net "FM_PRSNT_2_6_N")
	)
	(segment
		(start 381.889 -96.725486)
		(end 381.889 -96.758252)
		(width 0.0889)
		(layer "In9.Cu")
		(net "FM_PRSNT_2_6_N")
	)
	(segment
		(start 392.486642 -53.244242)
		(end 393.248896 -54.006496)
		(width 0.089408)
		(layer "In9.Cu")
		(net "FM_PRSNT_2_6_N")
	)
	(segment
		(start 390.2202 -72.11822)
		(end 390.2202 -72.276208)
		(width 0.089408)
		(layer "In9.Cu")
		(net "FM_PRSNT_2_6_N")
	)
	(segment
		(start 392.112246 -27.357578)
		(end 391.028682 -28.441142)
		(width 0.089408)
		(layer "In9.Cu")
		(net "FM_PRSNT_2_6_N")
	)
	(segment
		(start 390.673336 -69.094858)
		(end 390.673336 -71.47814)
		(width 0.089408)
		(layer "In9.Cu")
		(net "FM_PRSNT_2_6_N")
	)
	(segment
		(start 386.930646 -78.056486)
		(end 386.930646 -79.4512)
		(width 0.089408)
		(layer "In9.Cu")
		(net "FM_PRSNT_2_6_N")
	)
	(segment
		(start 392.089386 -42.817288)
		(end 392.089386 -45.859954)
		(width 0.089408)
		(layer "In9.Cu")
		(net "FM_PRSNT_2_6_N")
	)
	(segment
		(start 381.4572 -93.84411)
		(end 381.4572 -95.550736)
		(width 0.089408)
		(layer "In9.Cu")
		(net "FM_PRSNT_2_6_N")
	)
	(segment
		(start 381.4572 -95.550736)
		(end 381.3937 -95.614236)
		(width 0.0889)
		(layer "In9.Cu")
		(net "FM_PRSNT_2_6_N")
	)
	(segment
		(start 391.791952 -47.17923)
		(end 391.791952 -51.67503)
		(width 0.089408)
		(layer "In9.Cu")
		(net "FM_PRSNT_2_6_N")
	)
	(segment
		(start 391.31621 -33.94329)
		(end 391.67308 -34.30016)
		(width 0.089408)
		(layer "In9.Cu")
		(net "FM_PRSNT_2_6_N")
	)
	(segment
		(start 392.089386 -45.859954)
		(end 391.547096 -46.402244)
		(width 0.089408)
		(layer "In9.Cu")
		(net "FM_PRSNT_2_6_N")
	)
	(segment
		(start 390.220708 -71.930768)
		(end 390.220708 -72.117712)
		(width 0.089408)
		(layer "In9.Cu")
		(net "FM_PRSNT_2_6_N")
	)
	(segment
		(start 391.028682 -32.58566)
		(end 391.31621 -32.873188)
		(width 0.089408)
		(layer "In9.Cu")
		(net "FM_PRSNT_2_6_N")
	)
	(segment
		(start 391.928858 -36.186618)
		(end 392.932412 -37.190172)
		(width 0.089408)
		(layer "In9.Cu")
		(net "FM_PRSNT_2_6_N")
	)
	(segment
		(start 392.067034 -26.271728)
		(end 392.067034 -26.822146)
		(width 0.089408)
		(layer "In9.Cu")
		(net "FM_PRSNT_2_6_N")
	)
	(segment
		(start 392.112246 -26.867358)
		(end 392.112246 -27.357578)
		(width 0.089408)
		(layer "In9.Cu")
		(net "FM_PRSNT_2_6_N")
	)
	(segment
		(start 385.301236 -86.177882)
		(end 385.301236 -86.411054)
		(width 0.089408)
		(layer "In9.Cu")
		(net "FM_PRSNT_2_6_N")
	)
	(segment
		(start 385.301236 -86.411054)
		(end 381.536448 -90.175842)
		(width 0.089408)
		(layer "In9.Cu")
		(net "FM_PRSNT_2_6_N")
	)
	(segment
		(start 381.4572 -91.6686)
		(end 381.4572 -93.84411)
		(width 0.0889)
		(layer "In9.Cu")
		(net "FM_PRSNT_2_6_N")
	)
	(segment
		(start 384.022854 -100.181156)
		(end 384.27025 -100.181156)
		(width 0.089408)
		(layer "In9.Cu")
		(net "FM_PRSNT_2_6_N")
	)
	(segment
		(start 391.028682 -28.441142)
		(end 391.028682 -32.58566)
		(width 0.089408)
		(layer "In9.Cu")
		(net "FM_PRSNT_2_6_N")
	)
	(segment
		(start 391.67308 -34.30016)
		(end 391.7696 -34.30016)
		(width 0.089408)
		(layer "In9.Cu")
		(net "FM_PRSNT_2_6_N")
	)
	(segment
		(start 381.536448 -91.589352)
		(end 381.4572 -91.6686)
		(width 0.0889)
		(layer "In9.Cu")
		(net "FM_PRSNT_2_6_N")
	)
	(segment
		(start 387.436614 -85.226398)
		(end 386.25272 -85.226398)
		(width 0.089408)
		(layer "In9.Cu")
		(net "FM_PRSNT_2_6_N")
	)
	(segment
		(start 391.7696 -34.30016)
		(end 391.928858 -34.459418)
		(width 0.089408)
		(layer "In9.Cu")
		(net "FM_PRSNT_2_6_N")
	)
	(segment
		(start 391.928858 -34.459418)
		(end 391.928858 -36.186618)
		(width 0.089408)
		(layer "In9.Cu")
		(net "FM_PRSNT_2_6_N")
	)
	(segment
		(start 389.885682 -67.004184)
		(end 389.885682 -68.307204)
		(width 0.089408)
		(layer "In9.Cu")
		(net "FM_PRSNT_2_6_N")
	)
	(segment
		(start 392.726926 -60.714636)
		(end 392.726926 -61.325252)
		(width 0.089408)
		(layer "In9.Cu")
		(net "FM_PRSNT_2_6_N")
	)
	(segment
		(start 392.059414 -26.264108)
		(end 392.067034 -26.271728)
		(width 0.089408)
		(layer "In9.Cu")
		(net "FM_PRSNT_2_6_N")
	)
	(segment
		(start 390.220708 -72.434704)
		(end 390.220708 -73.54189)
		(width 0.089408)
		(layer "In9.Cu")
		(net "FM_PRSNT_2_6_N")
	)
	(segment
		(start 392.655298 -22.690328)
		(end 392.655298 -23.779734)
		(width 0.089408)
		(layer "In9.Cu")
		(net "FM_PRSNT_2_6_N")
	)
	(segment
		(start 389.146288 -75.840844)
		(end 386.930646 -78.056486)
		(width 0.089408)
		(layer "In9.Cu")
		(net "FM_PRSNT_2_6_N")
	)
	(segment
		(start 392.4935 -22.52853)
		(end 392.655298 -22.690328)
		(width 0.089408)
		(layer "In9.Cu")
		(net "FM_PRSNT_2_6_N")
	)
	(segment
		(start 382.3843 -97.584006)
		(end 382.3843 -97.616772)
		(width 0.0889)
		(layer "In9.Cu")
		(net "FM_PRSNT_2_6_N")
	)
	(segment
		(start 383.3749 -99.301046)
		(end 383.3749 -99.333812)
		(width 0.0889)
		(layer "In9.Cu")
		(net "FM_PRSNT_2_6_N")
	)
	(arc
		(start 383.575052 -99.669346)
		(mid 383.739533 -99.810051)
		(end 383.84226 -100.000562)
		(width 0.0889)
		(layer "In9.Cu")
		(net "FM_PRSNT_2_6_N")
	)
	(arc
		(start 382.584452 -97.952306)
		(mid 382.795316 -98.15931)
		(end 382.8796 -98.442526)
		(width 0.0889)
		(layer "In9.Cu")
		(net "FM_PRSNT_2_6_N")
	)
	(arc
		(start 381.593852 -96.235266)
		(mid 381.804716 -96.44227)
		(end 381.889 -96.725486)
		(width 0.0889)
		(layer "In9.Cu")
		(net "FM_PRSNT_2_6_N")
	)
	(arc
		(start 381.3937 -95.899732)
		(mid 381.45005 -96.093582)
		(end 381.593852 -96.235266)
		(width 0.0889)
		(layer "In9.Cu")
		(net "FM_PRSNT_2_6_N")
	)
	(arc
		(start 382.3843 -97.616772)
		(mid 382.44065 -97.810622)
		(end 382.584452 -97.952306)
		(width 0.0889)
		(layer "In9.Cu")
		(net "FM_PRSNT_2_6_N")
	)
	(arc
		(start 382.8796 -98.475292)
		(mid 382.93595 -98.669142)
		(end 383.079752 -98.810826)
		(width 0.0889)
		(layer "In9.Cu")
		(net "FM_PRSNT_2_6_N")
	)
	(arc
		(start 383.079752 -98.810826)
		(mid 383.290616 -99.01783)
		(end 383.3749 -99.301046)
		(width 0.0889)
		(layer "In9.Cu")
		(net "FM_PRSNT_2_6_N")
	)
	(arc
		(start 382.089152 -97.093786)
		(mid 382.300016 -97.30079)
		(end 382.3843 -97.584006)
		(width 0.0889)
		(layer "In9.Cu")
		(net "FM_PRSNT_2_6_N")
	)
	(arc
		(start 383.3749 -99.333812)
		(mid 383.43125 -99.527662)
		(end 383.575052 -99.669346)
		(width 0.0889)
		(layer "In9.Cu")
		(net "FM_PRSNT_2_6_N")
	)
	(arc
		(start 381.889 -96.758252)
		(mid 381.94535 -96.952102)
		(end 382.089152 -97.093786)
		(width 0.0889)
		(layer "In9.Cu")
		(net "FM_PRSNT_2_6_N")
	)
	(segment
		(start 383.77495 -102.12832)
		(end 384.27025 -101.898196)
		(width 0.10795)
		(layer "F.Cu")
		(net "FM_PRSNT_2_5_N")
	)
	(via
		(at 376.808238 -95.482918)
		(size 0.6604)
		(drill 0.3302)
		(layers "F.Cu" "B.Cu")
		(net "FM_PRSNT_2_5_N")
	)
	(via
		(at 384.27025 -101.898196)
		(size 0.508)
		(drill 0.254)
		(layers "F.Cu" "B.Cu")
		(net "FM_PRSNT_2_5_N")
	)
	(segment
		(start 376.808238 -95.482918)
		(end 376.808238 -95.631)
		(width 0.10795)
		(layer "B.Cu")
		(net "FM_PRSNT_2_5_N")
	)
	(segment
		(start 379.222 -97.59442)
		(end 379.222 -97.627186)
		(width 0.0889)
		(layer "B.Cu")
		(net "FM_PRSNT_2_5_N")
	)
	(segment
		(start 376.457972 -94.780862)
		(end 376.808238 -95.131128)
		(width 0.10795)
		(layer "B.Cu")
		(net "FM_PRSNT_2_5_N")
	)
	(segment
		(start 376.808238 -95.631)
		(end 376.808238 -95.701358)
		(width 0.0889)
		(layer "B.Cu")
		(net "FM_PRSNT_2_5_N")
	)
	(segment
		(start 376.808238 -95.131128)
		(end 376.808238 -95.482918)
		(width 0.10795)
		(layer "B.Cu")
		(net "FM_PRSNT_2_5_N")
	)
	(segment
		(start 382.1938 -99.31146)
		(end 382.1938 -99.344226)
		(width 0.0889)
		(layer "B.Cu")
		(net "FM_PRSNT_2_5_N")
	)
	(segment
		(start 384.175 -101.018086)
		(end 384.175 -101.061266)
		(width 0.0889)
		(layer "B.Cu")
		(net "FM_PRSNT_2_5_N")
	)
	(segment
		(start 384.6703 -100.16998)
		(end 384.6703 -100.181156)
		(width 0.0889)
		(layer "B.Cu")
		(net "FM_PRSNT_2_5_N")
	)
	(segment
		(start 373.3165 -93.091)
		(end 375.006362 -94.780862)
		(width 0.10795)
		(layer "B.Cu")
		(net "FM_PRSNT_2_5_N")
	)
	(segment
		(start 376.808238 -95.701358)
		(end 377.41352 -96.30664)
		(width 0.0889)
		(layer "B.Cu")
		(net "FM_PRSNT_2_5_N")
	)
	(segment
		(start 378.7267 -96.7359)
		(end 378.7267 -96.768666)
		(width 0.0889)
		(layer "B.Cu")
		(net "FM_PRSNT_2_5_N")
	)
	(segment
		(start 380.7079 -98.45294)
		(end 380.7079 -98.485706)
		(width 0.0889)
		(layer "B.Cu")
		(net "FM_PRSNT_2_5_N")
	)
	(segment
		(start 375.006362 -94.780862)
		(end 376.457972 -94.780862)
		(width 0.10795)
		(layer "B.Cu")
		(net "FM_PRSNT_2_5_N")
	)
	(arc
		(start 384.470148 -100.527866)
		(mid 384.259284 -100.73487)
		(end 384.175 -101.018086)
		(width 0.0889)
		(layer "B.Cu")
		(net "FM_PRSNT_2_5_N")
	)
	(arc
		(start 380.507748 -98.117406)
		(mid 380.651552 -98.259089)
		(end 380.7079 -98.45294)
		(width 0.0889)
		(layer "B.Cu")
		(net "FM_PRSNT_2_5_N")
	)
	(arc
		(start 384.175 -101.061266)
		(mid 384.198888 -101.482433)
		(end 384.27025 -101.898196)
		(width 0.0889)
		(layer "B.Cu")
		(net "FM_PRSNT_2_5_N")
	)
	(arc
		(start 383.079752 -99.834446)
		(mid 383.27965 -99.780947)
		(end 383.479548 -99.834446)
		(width 0.0889)
		(layer "B.Cu")
		(net "FM_PRSNT_2_5_N")
	)
	(arc
		(start 384.6703 -100.181156)
		(mid 384.616665 -100.381316)
		(end 384.470148 -100.527866)
		(width 0.0889)
		(layer "B.Cu")
		(net "FM_PRSNT_2_5_N")
	)
	(arc
		(start 381.003048 -98.975926)
		(mid 381.29845 -99.055057)
		(end 381.593852 -98.975926)
		(width 0.0889)
		(layer "B.Cu")
		(net "FM_PRSNT_2_5_N")
	)
	(arc
		(start 384.070352 -99.834446)
		(mid 384.27025 -99.780947)
		(end 384.470148 -99.834446)
		(width 0.0889)
		(layer "B.Cu")
		(net "FM_PRSNT_2_5_N")
	)
	(arc
		(start 378.7267 -96.768666)
		(mid 378.810981 -97.051883)
		(end 379.021848 -97.258886)
		(width 0.0889)
		(layer "B.Cu")
		(net "FM_PRSNT_2_5_N")
	)
	(arc
		(start 384.470148 -99.834446)
		(mid 384.613952 -99.976129)
		(end 384.6703 -100.16998)
		(width 0.0889)
		(layer "B.Cu")
		(net "FM_PRSNT_2_5_N")
	)
	(arc
		(start 377.41352 -96.30664)
		(mid 377.433534 -96.325659)
		(end 377.454414 -96.343724)
		(width 0.0889)
		(layer "B.Cu")
		(net "FM_PRSNT_2_5_N")
	)
	(arc
		(start 382.1938 -99.344226)
		(mid 382.278081 -99.627443)
		(end 382.488948 -99.834446)
		(width 0.0889)
		(layer "B.Cu")
		(net "FM_PRSNT_2_5_N")
	)
	(arc
		(start 381.993648 -98.975926)
		(mid 382.137452 -99.117609)
		(end 382.1938 -99.31146)
		(width 0.0889)
		(layer "B.Cu")
		(net "FM_PRSNT_2_5_N")
	)
	(arc
		(start 379.222 -97.627186)
		(mid 379.306281 -97.910403)
		(end 379.517148 -98.117406)
		(width 0.0889)
		(layer "B.Cu")
		(net "FM_PRSNT_2_5_N")
	)
	(arc
		(start 381.593852 -98.975926)
		(mid 381.79375 -98.922427)
		(end 381.993648 -98.975926)
		(width 0.0889)
		(layer "B.Cu")
		(net "FM_PRSNT_2_5_N")
	)
	(arc
		(start 383.479548 -99.834446)
		(mid 383.77495 -99.913577)
		(end 384.070352 -99.834446)
		(width 0.0889)
		(layer "B.Cu")
		(net "FM_PRSNT_2_5_N")
	)
	(arc
		(start 380.107952 -98.117406)
		(mid 380.30785 -98.063907)
		(end 380.507748 -98.117406)
		(width 0.0889)
		(layer "B.Cu")
		(net "FM_PRSNT_2_5_N")
	)
	(arc
		(start 377.454414 -96.343724)
		(mid 377.781709 -96.477449)
		(end 378.126752 -96.400366)
		(width 0.0889)
		(layer "B.Cu")
		(net "FM_PRSNT_2_5_N")
	)
	(arc
		(start 379.517148 -98.117406)
		(mid 379.81255 -98.196537)
		(end 380.107952 -98.117406)
		(width 0.0889)
		(layer "B.Cu")
		(net "FM_PRSNT_2_5_N")
	)
	(arc
		(start 382.488948 -99.834446)
		(mid 382.78435 -99.913577)
		(end 383.079752 -99.834446)
		(width 0.0889)
		(layer "B.Cu")
		(net "FM_PRSNT_2_5_N")
	)
	(arc
		(start 378.126752 -96.400366)
		(mid 378.521999 -96.397783)
		(end 378.7267 -96.7359)
		(width 0.0889)
		(layer "B.Cu")
		(net "FM_PRSNT_2_5_N")
	)
	(arc
		(start 379.021848 -97.258886)
		(mid 379.165652 -97.400569)
		(end 379.222 -97.59442)
		(width 0.0889)
		(layer "B.Cu")
		(net "FM_PRSNT_2_5_N")
	)
	(arc
		(start 380.7079 -98.485706)
		(mid 380.792181 -98.768923)
		(end 381.003048 -98.975926)
		(width 0.0889)
		(layer "B.Cu")
		(net "FM_PRSNT_2_5_N")
	)
	(segment
		(start 383.77495 -101.039676)
		(end 383.27965 -101.2698)
		(width 0.10795)
		(layer "F.Cu")
		(net "FM_PRSNT_2_4_N")
	)
	(via
		(at 383.77495 -101.039676)
		(size 0.508)
		(drill 0.254)
		(layers "F.Cu" "B.Cu")
		(net "FM_PRSNT_2_4_N")
	)
	(via
		(at 369.522756 -96.32823)
		(size 0.6604)
		(drill 0.3302)
		(layers "F.Cu" "B.Cu")
		(net "FM_PRSNT_2_4_N")
	)
	(segment
		(start 373.5324 -94.838012)
		(end 373.5324 -96.012)
		(width 0.10795)
		(layer "B.Cu")
		(net "FM_PRSNT_2_4_N")
	)
	(segment
		(start 373.126 -94.431612)
		(end 373.5324 -94.838012)
		(width 0.10795)
		(layer "B.Cu")
		(net "FM_PRSNT_2_4_N")
	)
	(segment
		(start 378.2314 -97.59442)
		(end 378.2314 -97.627186)
		(width 0.0889)
		(layer "B.Cu")
		(net "FM_PRSNT_2_4_N")
	)
	(segment
		(start 376.86361 -97.204784)
		(end 377.831096 -97.204784)
		(width 0.0889)
		(layer "B.Cu")
		(net "FM_PRSNT_2_4_N")
	)
	(segment
		(start 371.425724 -94.841822)
		(end 371.835934 -94.431612)
		(width 0.10795)
		(layer "B.Cu")
		(net "FM_PRSNT_2_4_N")
	)
	(segment
		(start 373.5324 -96.012)
		(end 373.732552 -96.212152)
		(width 0.10795)
		(layer "B.Cu")
		(net "FM_PRSNT_2_4_N")
	)
	(segment
		(start 375.870978 -96.212152)
		(end 376.614436 -96.95561)
		(width 0.10795)
		(layer "B.Cu")
		(net "FM_PRSNT_2_4_N")
	)
	(segment
		(start 371.060472 -94.841822)
		(end 371.060472 -95.209868)
		(width 0.10795)
		(layer "B.Cu")
		(net "FM_PRSNT_2_4_N")
	)
	(segment
		(start 371.835934 -94.431612)
		(end 373.126 -94.431612)
		(width 0.10795)
		(layer "B.Cu")
		(net "FM_PRSNT_2_4_N")
	)
	(segment
		(start 373.732552 -96.212152)
		(end 375.870978 -96.212152)
		(width 0.10795)
		(layer "B.Cu")
		(net "FM_PRSNT_2_4_N")
	)
	(segment
		(start 371.060472 -95.209868)
		(end 370.285772 -95.984568)
		(width 0.10795)
		(layer "B.Cu")
		(net "FM_PRSNT_2_4_N")
	)
	(segment
		(start 378.7267 -98.45294)
		(end 378.7267 -98.485706)
		(width 0.0889)
		(layer "B.Cu")
		(net "FM_PRSNT_2_4_N")
	)
	(segment
		(start 370.285772 -95.984568)
		(end 369.866418 -95.984568)
		(width 0.10795)
		(layer "B.Cu")
		(net "FM_PRSNT_2_4_N")
	)
	(segment
		(start 369.866418 -95.984568)
		(end 369.522756 -96.32823)
		(width 0.10795)
		(layer "B.Cu")
		(net "FM_PRSNT_2_4_N")
	)
	(segment
		(start 380.2126 -99.31146)
		(end 380.2126 -99.344226)
		(width 0.0889)
		(layer "B.Cu")
		(net "FM_PRSNT_2_4_N")
	)
	(segment
		(start 371.060472 -94.841822)
		(end 371.425724 -94.841822)
		(width 0.10795)
		(layer "B.Cu")
		(net "FM_PRSNT_2_4_N")
	)
	(segment
		(start 376.614436 -96.95561)
		(end 376.86361 -97.204784)
		(width 0.0889)
		(layer "B.Cu")
		(net "FM_PRSNT_2_4_N")
	)
	(segment
		(start 381.6985 -100.16998)
		(end 381.6985 -100.202746)
		(width 0.0889)
		(layer "B.Cu")
		(net "FM_PRSNT_2_4_N")
	)
	(arc
		(start 379.021848 -98.975926)
		(mid 379.31725 -99.055057)
		(end 379.612652 -98.975926)
		(width 0.0889)
		(layer "B.Cu")
		(net "FM_PRSNT_2_4_N")
	)
	(arc
		(start 381.098552 -99.834446)
		(mid 381.29845 -99.780947)
		(end 381.498348 -99.834446)
		(width 0.0889)
		(layer "B.Cu")
		(net "FM_PRSNT_2_4_N")
	)
	(arc
		(start 381.6985 -100.202746)
		(mid 381.782781 -100.485963)
		(end 381.993648 -100.692966)
		(width 0.0889)
		(layer "B.Cu")
		(net "FM_PRSNT_2_4_N")
	)
	(arc
		(start 380.2126 -99.344226)
		(mid 380.296881 -99.627443)
		(end 380.507748 -99.834446)
		(width 0.0889)
		(layer "B.Cu")
		(net "FM_PRSNT_2_4_N")
	)
	(arc
		(start 381.498348 -99.834446)
		(mid 381.642152 -99.976129)
		(end 381.6985 -100.16998)
		(width 0.0889)
		(layer "B.Cu")
		(net "FM_PRSNT_2_4_N")
	)
	(arc
		(start 378.031248 -97.258886)
		(mid 378.175052 -97.400569)
		(end 378.2314 -97.59442)
		(width 0.0889)
		(layer "B.Cu")
		(net "FM_PRSNT_2_4_N")
	)
	(arc
		(start 382.984248 -100.692966)
		(mid 383.370075 -100.888042)
		(end 383.77495 -101.039676)
		(width 0.0889)
		(layer "B.Cu")
		(net "FM_PRSNT_2_4_N")
	)
	(arc
		(start 380.012448 -98.975926)
		(mid 380.156252 -99.117609)
		(end 380.2126 -99.31146)
		(width 0.0889)
		(layer "B.Cu")
		(net "FM_PRSNT_2_4_N")
	)
	(arc
		(start 378.2314 -97.627186)
		(mid 378.315681 -97.910403)
		(end 378.526548 -98.117406)
		(width 0.0889)
		(layer "B.Cu")
		(net "FM_PRSNT_2_4_N")
	)
	(arc
		(start 379.612652 -98.975926)
		(mid 379.81255 -98.922427)
		(end 380.012448 -98.975926)
		(width 0.0889)
		(layer "B.Cu")
		(net "FM_PRSNT_2_4_N")
	)
	(arc
		(start 377.831096 -97.204784)
		(mid 377.934745 -97.218631)
		(end 378.031248 -97.258886)
		(width 0.0889)
		(layer "B.Cu")
		(net "FM_PRSNT_2_4_N")
	)
	(arc
		(start 381.993648 -100.692966)
		(mid 382.28905 -100.772097)
		(end 382.584452 -100.692966)
		(width 0.0889)
		(layer "B.Cu")
		(net "FM_PRSNT_2_4_N")
	)
	(arc
		(start 378.526548 -98.117406)
		(mid 378.670352 -98.259089)
		(end 378.7267 -98.45294)
		(width 0.0889)
		(layer "B.Cu")
		(net "FM_PRSNT_2_4_N")
	)
	(arc
		(start 380.507748 -99.834446)
		(mid 380.80315 -99.913577)
		(end 381.098552 -99.834446)
		(width 0.0889)
		(layer "B.Cu")
		(net "FM_PRSNT_2_4_N")
	)
	(arc
		(start 382.584452 -100.692966)
		(mid 382.78435 -100.639467)
		(end 382.984248 -100.692966)
		(width 0.0889)
		(layer "B.Cu")
		(net "FM_PRSNT_2_4_N")
	)
	(arc
		(start 378.7267 -98.485706)
		(mid 378.810981 -98.768923)
		(end 379.021848 -98.975926)
		(width 0.0889)
		(layer "B.Cu")
		(net "FM_PRSNT_2_4_N")
	)
	(segment
		(start 385.26085 -97.83572)
		(end 385.75615 -97.605596)
		(width 0.10795)
		(layer "F.Cu")
		(net "FM_PRSNT_2_3_N")
	)
	(via
		(at 385.75615 -97.605596)
		(size 0.508)
		(drill 0.254)
		(layers "F.Cu" "B.Cu")
		(net "FM_PRSNT_2_3_N")
	)
	(segment
		(start 385.00304 -86.67496)
		(end 385.519676 -86.67496)
		(width 0.10795)
		(layer "B.Cu")
		(net "FM_PRSNT_2_3_N")
	)
	(segment
		(start 385.8514 -96.768666)
		(end 385.8514 -96.725486)
		(width 0.0889)
		(layer "B.Cu")
		(net "FM_PRSNT_2_3_N")
	)
	(segment
		(start 384.19532 -89.87536)
		(end 384.858006 -89.212674)
		(width 0.10795)
		(layer "B.Cu")
		(net "FM_PRSNT_2_3_N")
	)
	(segment
		(start 384.858006 -89.212674)
		(end 384.858006 -86.819994)
		(width 0.10795)
		(layer "B.Cu")
		(net "FM_PRSNT_2_3_N")
	)
	(segment
		(start 385.3561 -95.899732)
		(end 385.3561 -93.738954)
		(width 0.0889)
		(layer "B.Cu")
		(net "FM_PRSNT_2_3_N")
	)
	(segment
		(start 384.19532 -92.578174)
		(end 384.19532 -89.87536)
		(width 0.10795)
		(layer "B.Cu")
		(net "FM_PRSNT_2_3_N")
	)
	(segment
		(start 385.75615 -97.605596)
		(end 385.58724 -97.31248)
		(width 0.0889)
		(layer "B.Cu")
		(net "FM_PRSNT_2_3_N")
	)
	(segment
		(start 385.58724 -97.31248)
		(end 385.61137 -97.223072)
		(width 0.0889)
		(layer "B.Cu")
		(net "FM_PRSNT_2_3_N")
	)
	(segment
		(start 384.858006 -86.819994)
		(end 385.00304 -86.67496)
		(width 0.10795)
		(layer "B.Cu")
		(net "FM_PRSNT_2_3_N")
	)
	(segment
		(start 385.519676 -86.67496)
		(end 386.575808 -85.618828)
		(width 0.10795)
		(layer "B.Cu")
		(net "FM_PRSNT_2_3_N")
	)
	(segment
		(start 385.3561 -93.738954)
		(end 384.19532 -92.578174)
		(width 0.10795)
		(layer "B.Cu")
		(net "FM_PRSNT_2_3_N")
	)
	(arc
		(start 385.556252 -96.235266)
		(mid 385.412448 -96.093583)
		(end 385.3561 -95.899732)
		(width 0.0889)
		(layer "B.Cu")
		(net "FM_PRSNT_2_3_N")
	)
	(arc
		(start 385.8514 -96.725486)
		(mid 385.767119 -96.442269)
		(end 385.556252 -96.235266)
		(width 0.0889)
		(layer "B.Cu")
		(net "FM_PRSNT_2_3_N")
	)
	(arc
		(start 385.61137 -97.223072)
		(mid 385.783364 -97.023327)
		(end 385.8514 -96.768666)
		(width 0.0889)
		(layer "B.Cu")
		(net "FM_PRSNT_2_3_N")
	)
	(segment
		(start 385.26085 -99.55276)
		(end 385.75615 -99.322636)
		(width 0.10795)
		(layer "F.Cu")
		(net "FM_PRSNT_2_2_N")
	)
	(via
		(at 384.048 -87.9094)
		(size 0.6604)
		(drill 0.3302)
		(layers "F.Cu" "B.Cu")
		(net "FM_PRSNT_2_2_N")
	)
	(via
		(at 385.75615 -99.322636)
		(size 0.508)
		(drill 0.254)
		(layers "F.Cu" "B.Cu")
		(net "FM_PRSNT_2_2_N")
	)
	(segment
		(start 384.048 -87.1982)
		(end 384.40106 -86.84514)
		(width 0.10795)
		(layer "B.Cu")
		(net "FM_PRSNT_2_2_N")
	)
	(segment
		(start 384.3655 -93.876368)
		(end 384.3655 -95.197676)
		(width 0.10795)
		(layer "B.Cu")
		(net "FM_PRSNT_2_2_N")
	)
	(segment
		(start 385.729988 -99.367848)
		(end 385.75615 -99.322636)
		(width 0.0889)
		(layer "B.Cu")
		(net "FM_PRSNT_2_2_N")
	)
	(segment
		(start 384.263138 -89.202514)
		(end 383.76098 -89.704672)
		(width 0.10795)
		(layer "B.Cu")
		(net "FM_PRSNT_2_2_N")
	)
	(segment
		(start 384.3655 -95.197676)
		(end 384.3655 -95.910146)
		(width 0.0889)
		(layer "B.Cu")
		(net "FM_PRSNT_2_2_N")
	)
	(segment
		(start 385.5085 -99.636834)
		(end 385.58724 -99.615752)
		(width 0.0889)
		(layer "B.Cu")
		(net "FM_PRSNT_2_2_N")
	)
	(segment
		(start 384.048 -87.9094)
		(end 384.048 -87.1982)
		(width 0.10795)
		(layer "B.Cu")
		(net "FM_PRSNT_2_2_N")
	)
	(segment
		(start 385.58724 -99.615752)
		(end 385.729988 -99.367848)
		(width 0.0889)
		(layer "B.Cu")
		(net "FM_PRSNT_2_2_N")
	)
	(segment
		(start 384.8608 -98.442526)
		(end 384.8608 -98.475292)
		(width 0.0889)
		(layer "B.Cu")
		(net "FM_PRSNT_2_2_N")
	)
	(segment
		(start 384.3655 -97.584006)
		(end 384.3655 -97.616772)
		(width 0.0889)
		(layer "B.Cu")
		(net "FM_PRSNT_2_2_N")
	)
	(segment
		(start 384.40106 -86.449916)
		(end 385.051808 -85.799168)
		(width 0.10795)
		(layer "B.Cu")
		(net "FM_PRSNT_2_2_N")
	)
	(segment
		(start 384.048 -88.5444)
		(end 384.263138 -88.759538)
		(width 0.10795)
		(layer "B.Cu")
		(net "FM_PRSNT_2_2_N")
	)
	(segment
		(start 384.048 -87.9094)
		(end 384.048 -88.5444)
		(width 0.10795)
		(layer "B.Cu")
		(net "FM_PRSNT_2_2_N")
	)
	(segment
		(start 383.76098 -89.704672)
		(end 383.76098 -93.271848)
		(width 0.10795)
		(layer "B.Cu")
		(net "FM_PRSNT_2_2_N")
	)
	(segment
		(start 384.40106 -86.84514)
		(end 384.40106 -86.449916)
		(width 0.10795)
		(layer "B.Cu")
		(net "FM_PRSNT_2_2_N")
	)
	(segment
		(start 385.051808 -85.799168)
		(end 385.051808 -85.618828)
		(width 0.10795)
		(layer "B.Cu")
		(net "FM_PRSNT_2_2_N")
	)
	(segment
		(start 384.263138 -88.759538)
		(end 384.263138 -89.202514)
		(width 0.10795)
		(layer "B.Cu")
		(net "FM_PRSNT_2_2_N")
	)
	(segment
		(start 385.3561 -99.301046)
		(end 385.3561 -99.333812)
		(width 0.0889)
		(layer "B.Cu")
		(net "FM_PRSNT_2_2_N")
	)
	(segment
		(start 383.76098 -93.271848)
		(end 384.3655 -93.876368)
		(width 0.10795)
		(layer "B.Cu")
		(net "FM_PRSNT_2_2_N")
	)
	(segment
		(start 383.8702 -96.7359)
		(end 383.8702 -96.758252)
		(width 0.0889)
		(layer "B.Cu")
		(net "FM_PRSNT_2_2_N")
	)
	(arc
		(start 384.8608 -98.475292)
		(mid 384.91715 -98.669142)
		(end 385.060952 -98.810826)
		(width 0.0889)
		(layer "B.Cu")
		(net "FM_PRSNT_2_2_N")
	)
	(arc
		(start 384.070352 -97.093786)
		(mid 384.281216 -97.30079)
		(end 384.3655 -97.584006)
		(width 0.0889)
		(layer "B.Cu")
		(net "FM_PRSNT_2_2_N")
	)
	(arc
		(start 385.060952 -98.810826)
		(mid 385.271816 -99.01783)
		(end 385.3561 -99.301046)
		(width 0.0889)
		(layer "B.Cu")
		(net "FM_PRSNT_2_2_N")
	)
	(arc
		(start 384.3655 -95.910146)
		(mid 384.281219 -96.193363)
		(end 384.070352 -96.400366)
		(width 0.0889)
		(layer "B.Cu")
		(net "FM_PRSNT_2_2_N")
	)
	(arc
		(start 384.565652 -97.952306)
		(mid 384.776516 -98.15931)
		(end 384.8608 -98.442526)
		(width 0.0889)
		(layer "B.Cu")
		(net "FM_PRSNT_2_2_N")
	)
	(arc
		(start 384.070352 -96.400366)
		(mid 383.926548 -96.542049)
		(end 383.8702 -96.7359)
		(width 0.0889)
		(layer "B.Cu")
		(net "FM_PRSNT_2_2_N")
	)
	(arc
		(start 383.8702 -96.758252)
		(mid 383.92655 -96.952102)
		(end 384.070352 -97.093786)
		(width 0.0889)
		(layer "B.Cu")
		(net "FM_PRSNT_2_2_N")
	)
	(arc
		(start 384.3655 -97.616772)
		(mid 384.42185 -97.810622)
		(end 384.565652 -97.952306)
		(width 0.0889)
		(layer "B.Cu")
		(net "FM_PRSNT_2_2_N")
	)
	(arc
		(start 385.3561 -99.333812)
		(mid 385.398633 -99.502249)
		(end 385.5085 -99.636834)
		(width 0.0889)
		(layer "B.Cu")
		(net "FM_PRSNT_2_2_N")
	)
	(segment
		(start 385.75615 -101.039676)
		(end 385.26085 -101.2698)
		(width 0.10795)
		(layer "F.Cu")
		(net "FM_PRSNT_2_1_N")
	)
	(via
		(at 385.75615 -101.039676)
		(size 0.508)
		(drill 0.254)
		(layers "F.Cu" "B.Cu")
		(net "FM_PRSNT_2_1_N")
	)
	(via
		(at 375.3612 -94.1832)
		(size 0.6604)
		(drill 0.3302)
		(layers "F.Cu" "B.Cu")
		(net "FM_PRSNT_2_1_N")
	)
	(segment
		(start 369.267994 -93.807788)
		(end 370.088668 -92.987114)
		(width 0.10795)
		(layer "B.Cu")
		(net "FM_PRSNT_2_1_N")
	)
	(segment
		(start 373.738902 -92.767404)
		(end 373.738902 -93.153738)
		(width 0.10795)
		(layer "B.Cu")
		(net "FM_PRSNT_2_1_N")
	)
	(segment
		(start 378.9172 -96.725486)
		(end 378.9172 -96.758252)
		(width 0.0889)
		(layer "B.Cu")
		(net "FM_PRSNT_2_1_N")
	)
	(segment
		(start 379.4125 -97.584006)
		(end 379.4125 -97.616772)
		(width 0.0889)
		(layer "B.Cu")
		(net "FM_PRSNT_2_1_N")
	)
	(segment
		(start 384.8608 -100.159566)
		(end 384.8608 -100.181156)
		(width 0.0889)
		(layer "B.Cu")
		(net "FM_PRSNT_2_1_N")
	)
	(segment
		(start 380.8984 -98.442526)
		(end 380.8984 -98.475292)
		(width 0.0889)
		(layer "B.Cu")
		(net "FM_PRSNT_2_1_N")
	)
	(segment
		(start 382.3843 -99.301046)
		(end 382.3843 -99.333812)
		(width 0.0889)
		(layer "B.Cu")
		(net "FM_PRSNT_2_1_N")
	)
	(segment
		(start 373.738902 -93.153738)
		(end 374.768364 -94.1832)
		(width 0.10795)
		(layer "B.Cu")
		(net "FM_PRSNT_2_1_N")
	)
	(segment
		(start 371.489224 -92.987114)
		(end 371.939058 -92.53728)
		(width 0.10795)
		(layer "B.Cu")
		(net "FM_PRSNT_2_1_N")
	)
	(segment
		(start 372.594632 -92.624402)
		(end 373.5959 -92.624402)
		(width 0.10795)
		(layer "B.Cu")
		(net "FM_PRSNT_2_1_N")
	)
	(segment
		(start 373.5959 -92.624402)
		(end 373.738902 -92.767404)
		(width 0.10795)
		(layer "B.Cu")
		(net "FM_PRSNT_2_1_N")
	)
	(segment
		(start 377.390406 -95.153226)
		(end 377.390406 -95.450914)
		(width 0.10795)
		(layer "B.Cu")
		(net "FM_PRSNT_2_1_N")
	)
	(segment
		(start 375.909586 -94.1832)
		(end 376.20575 -94.479364)
		(width 0.10795)
		(layer "B.Cu")
		(net "FM_PRSNT_2_1_N")
	)
	(segment
		(start 372.50751 -92.53728)
		(end 372.594632 -92.624402)
		(width 0.10795)
		(layer "B.Cu")
		(net "FM_PRSNT_2_1_N")
	)
	(segment
		(start 374.768364 -94.1832)
		(end 375.3612 -94.1832)
		(width 0.10795)
		(layer "B.Cu")
		(net "FM_PRSNT_2_1_N")
	)
	(segment
		(start 377.390406 -95.450914)
		(end 377.390406 -96.014032)
		(width 0.0889)
		(layer "B.Cu")
		(net "FM_PRSNT_2_1_N")
	)
	(segment
		(start 376.20575 -94.479364)
		(end 376.716544 -94.479364)
		(width 0.10795)
		(layer "B.Cu")
		(net "FM_PRSNT_2_1_N")
	)
	(segment
		(start 370.088668 -92.987114)
		(end 371.489224 -92.987114)
		(width 0.10795)
		(layer "B.Cu")
		(net "FM_PRSNT_2_1_N")
	)
	(segment
		(start 377.390406 -96.014032)
		(end 377.54814 -96.171766)
		(width 0.0889)
		(layer "B.Cu")
		(net "FM_PRSNT_2_1_N")
	)
	(segment
		(start 375.3612 -94.1832)
		(end 375.909586 -94.1832)
		(width 0.10795)
		(layer "B.Cu")
		(net "FM_PRSNT_2_1_N")
	)
	(segment
		(start 376.716544 -94.479364)
		(end 377.390406 -95.153226)
		(width 0.10795)
		(layer "B.Cu")
		(net "FM_PRSNT_2_1_N")
	)
	(segment
		(start 369.267994 -93.915992)
		(end 369.267994 -93.807788)
		(width 0.10795)
		(layer "B.Cu")
		(net "FM_PRSNT_2_1_N")
	)
	(segment
		(start 371.939058 -92.53728)
		(end 372.50751 -92.53728)
		(width 0.10795)
		(layer "B.Cu")
		(net "FM_PRSNT_2_1_N")
	)
	(arc
		(start 380.8984 -98.475292)
		(mid 380.95475 -98.669142)
		(end 381.098552 -98.810826)
		(width 0.0889)
		(layer "B.Cu")
		(net "FM_PRSNT_2_1_N")
	)
	(arc
		(start 377.54814 -96.171766)
		(mid 377.587716 -96.206244)
		(end 377.631452 -96.235266)
		(width 0.0889)
		(layer "B.Cu")
		(net "FM_PRSNT_2_1_N")
	)
	(arc
		(start 379.117352 -97.093786)
		(mid 379.328216 -97.30079)
		(end 379.4125 -97.584006)
		(width 0.0889)
		(layer "B.Cu")
		(net "FM_PRSNT_2_1_N")
	)
	(arc
		(start 382.089152 -98.810826)
		(mid 382.300016 -99.01783)
		(end 382.3843 -99.301046)
		(width 0.0889)
		(layer "B.Cu")
		(net "FM_PRSNT_2_1_N")
	)
	(arc
		(start 381.498348 -98.810826)
		(mid 381.79375 -98.731695)
		(end 382.089152 -98.810826)
		(width 0.0889)
		(layer "B.Cu")
		(net "FM_PRSNT_2_1_N")
	)
	(arc
		(start 377.631452 -96.235266)
		(mid 377.83135 -96.288765)
		(end 378.031248 -96.235266)
		(width 0.0889)
		(layer "B.Cu")
		(net "FM_PRSNT_2_1_N")
	)
	(arc
		(start 381.098552 -98.810826)
		(mid 381.29845 -98.864325)
		(end 381.498348 -98.810826)
		(width 0.0889)
		(layer "B.Cu")
		(net "FM_PRSNT_2_1_N")
	)
	(arc
		(start 382.3843 -99.333812)
		(mid 382.44065 -99.527662)
		(end 382.584452 -99.669346)
		(width 0.0889)
		(layer "B.Cu")
		(net "FM_PRSNT_2_1_N")
	)
	(arc
		(start 380.603252 -97.952306)
		(mid 380.814116 -98.15931)
		(end 380.8984 -98.442526)
		(width 0.0889)
		(layer "B.Cu")
		(net "FM_PRSNT_2_1_N")
	)
	(arc
		(start 378.9172 -96.758252)
		(mid 378.97355 -96.952102)
		(end 379.117352 -97.093786)
		(width 0.0889)
		(layer "B.Cu")
		(net "FM_PRSNT_2_1_N")
	)
	(arc
		(start 382.984248 -99.669346)
		(mid 383.27965 -99.590215)
		(end 383.575052 -99.669346)
		(width 0.0889)
		(layer "B.Cu")
		(net "FM_PRSNT_2_1_N")
	)
	(arc
		(start 384.8608 -100.181156)
		(mid 384.914435 -100.381316)
		(end 385.060952 -100.527866)
		(width 0.0889)
		(layer "B.Cu")
		(net "FM_PRSNT_2_1_N")
	)
	(arc
		(start 379.4125 -97.616772)
		(mid 379.46885 -97.810622)
		(end 379.612652 -97.952306)
		(width 0.0889)
		(layer "B.Cu")
		(net "FM_PRSNT_2_1_N")
	)
	(arc
		(start 378.031248 -96.235266)
		(mid 378.32665 -96.156135)
		(end 378.622052 -96.235266)
		(width 0.0889)
		(layer "B.Cu")
		(net "FM_PRSNT_2_1_N")
	)
	(arc
		(start 378.622052 -96.235266)
		(mid 378.832916 -96.44227)
		(end 378.9172 -96.725486)
		(width 0.0889)
		(layer "B.Cu")
		(net "FM_PRSNT_2_1_N")
	)
	(arc
		(start 383.575052 -99.669346)
		(mid 383.77495 -99.722845)
		(end 383.974848 -99.669346)
		(width 0.0889)
		(layer "B.Cu")
		(net "FM_PRSNT_2_1_N")
	)
	(arc
		(start 385.060952 -100.527866)
		(mid 385.422774 -100.764451)
		(end 385.75615 -101.039676)
		(width 0.0889)
		(layer "B.Cu")
		(net "FM_PRSNT_2_1_N")
	)
	(arc
		(start 382.584452 -99.669346)
		(mid 382.78435 -99.722845)
		(end 382.984248 -99.669346)
		(width 0.0889)
		(layer "B.Cu")
		(net "FM_PRSNT_2_1_N")
	)
	(arc
		(start 383.974848 -99.669346)
		(mid 384.27025 -99.590215)
		(end 384.565652 -99.669346)
		(width 0.0889)
		(layer "B.Cu")
		(net "FM_PRSNT_2_1_N")
	)
	(arc
		(start 380.012448 -97.952306)
		(mid 380.30785 -97.873175)
		(end 380.603252 -97.952306)
		(width 0.0889)
		(layer "B.Cu")
		(net "FM_PRSNT_2_1_N")
	)
	(arc
		(start 384.565652 -99.669346)
		(mid 384.776516 -99.87635)
		(end 384.8608 -100.159566)
		(width 0.0889)
		(layer "B.Cu")
		(net "FM_PRSNT_2_1_N")
	)
	(arc
		(start 379.612652 -97.952306)
		(mid 379.81255 -98.005805)
		(end 380.012448 -97.952306)
		(width 0.0889)
		(layer "B.Cu")
		(net "FM_PRSNT_2_1_N")
	)
	(segment
		(start 102.089204 -62.52464)
		(end 101.517704 -62.52464)
		(width 0.10795)
		(layer "F.Cu")
		(net "PD_CPU1_RSVD_TEST_2")
	)
	(via
		(at 101.517704 -62.52464)
		(size 0.508)
		(drill 0.254)
		(layers "F.Cu" "B.Cu")
		(net "PD_CPU1_RSVD_TEST_2")
	)
	(via
		(at 81.233264 -65.488566)
		(size 0.6604)
		(drill 0.3302)
		(layers "F.Cu" "B.Cu")
		(net "PD_CPU1_RSVD_TEST_2")
	)
	(segment
		(start 91.427808 -63.022226)
		(end 90.972386 -63.022226)
		(width 0.1651)
		(layer "B.Cu")
		(net "PD_CPU1_RSVD_TEST_2")
	)
	(segment
		(start 93.114368 -62.96279)
		(end 92.726256 -62.96279)
		(width 0.1651)
		(layer "B.Cu")
		(net "PD_CPU1_RSVD_TEST_2")
	)
	(segment
		(start 84.076286 -64.04102)
		(end 83.63077 -64.486536)
		(width 0.1651)
		(layer "B.Cu")
		(net "PD_CPU1_RSVD_TEST_2")
	)
	(segment
		(start 80.391 -65.151)
		(end 80.895698 -65.151)
		(width 0.1651)
		(layer "B.Cu")
		(net "PD_CPU1_RSVD_TEST_2")
	)
	(segment
		(start 86.627716 -63.572136)
		(end 86.246462 -63.95339)
		(width 0.1651)
		(layer "B.Cu")
		(net "PD_CPU1_RSVD_TEST_2")
	)
	(segment
		(start 88.821514 -63.456312)
		(end 88.46058 -63.456312)
		(width 0.1651)
		(layer "B.Cu")
		(net "PD_CPU1_RSVD_TEST_2")
	)
	(segment
		(start 83.190842 -64.563498)
		(end 82.811874 -64.942466)
		(width 0.1651)
		(layer "B.Cu")
		(net "PD_CPU1_RSVD_TEST_2")
	)
	(segment
		(start 86.246462 -63.95339)
		(end 85.94725 -63.95339)
		(width 0.1651)
		(layer "B.Cu")
		(net "PD_CPU1_RSVD_TEST_2")
	)
	(segment
		(start 87.963502 -63.95339)
		(end 87.486236 -63.95339)
		(width 0.1651)
		(layer "B.Cu")
		(net "PD_CPU1_RSVD_TEST_2")
	)
	(segment
		(start 99.982528 -62.08649)
		(end 99.504754 -62.08649)
		(width 0.1651)
		(layer "B.Cu")
		(net "PD_CPU1_RSVD_TEST_2")
	)
	(segment
		(start 83.63077 -64.486536)
		(end 83.268058 -64.486536)
		(width 0.1651)
		(layer "B.Cu")
		(net "PD_CPU1_RSVD_TEST_2")
	)
	(segment
		(start 95.317056 -62.477142)
		(end 94.82709 -62.967108)
		(width 0.1651)
		(layer "B.Cu")
		(net "PD_CPU1_RSVD_TEST_2")
	)
	(segment
		(start 90.05951 -63.456312)
		(end 89.680288 -63.07709)
		(width 0.1651)
		(layer "B.Cu")
		(net "PD_CPU1_RSVD_TEST_2")
	)
	(segment
		(start 87.104982 -63.572136)
		(end 86.627716 -63.572136)
		(width 0.1651)
		(layer "B.Cu")
		(net "PD_CPU1_RSVD_TEST_2")
	)
	(segment
		(start 88.46058 -63.456312)
		(end 87.963502 -63.95339)
		(width 0.1651)
		(layer "B.Cu")
		(net "PD_CPU1_RSVD_TEST_2")
	)
	(segment
		(start 91.956636 -62.493398)
		(end 91.427808 -63.022226)
		(width 0.1651)
		(layer "B.Cu")
		(net "PD_CPU1_RSVD_TEST_2")
	)
	(segment
		(start 83.268058 -64.486536)
		(end 83.190842 -64.563498)
		(width 0.1651)
		(layer "B.Cu")
		(net "PD_CPU1_RSVD_TEST_2")
	)
	(segment
		(start 80.895698 -65.151)
		(end 81.233264 -65.488566)
		(width 0.1651)
		(layer "B.Cu")
		(net "PD_CPU1_RSVD_TEST_2")
	)
	(segment
		(start 92.256864 -62.493398)
		(end 91.956636 -62.493398)
		(width 0.1651)
		(layer "B.Cu")
		(net "PD_CPU1_RSVD_TEST_2")
	)
	(segment
		(start 96.929194 -62.467236)
		(end 96.548448 -62.08649)
		(width 0.1651)
		(layer "B.Cu")
		(net "PD_CPU1_RSVD_TEST_2")
	)
	(segment
		(start 89.680288 -63.07709)
		(end 89.200736 -63.07709)
		(width 0.1651)
		(layer "B.Cu")
		(net "PD_CPU1_RSVD_TEST_2")
	)
	(segment
		(start 93.575886 -62.501272)
		(end 93.114368 -62.96279)
		(width 0.1651)
		(layer "B.Cu")
		(net "PD_CPU1_RSVD_TEST_2")
	)
	(segment
		(start 81.9023 -65.488566)
		(end 81.233264 -65.488566)
		(width 0.1651)
		(layer "B.Cu")
		(net "PD_CPU1_RSVD_TEST_2")
	)
	(segment
		(start 87.486236 -63.95339)
		(end 87.104982 -63.572136)
		(width 0.1651)
		(layer "B.Cu")
		(net "PD_CPU1_RSVD_TEST_2")
	)
	(segment
		(start 97.787714 -62.08649)
		(end 97.406968 -62.467236)
		(width 0.1651)
		(layer "B.Cu")
		(net "PD_CPU1_RSVD_TEST_2")
	)
	(segment
		(start 94.35846 -62.967108)
		(end 93.892624 -62.501272)
		(width 0.1651)
		(layer "B.Cu")
		(net "PD_CPU1_RSVD_TEST_2")
	)
	(segment
		(start 95.680022 -62.477142)
		(end 95.317056 -62.477142)
		(width 0.1651)
		(layer "B.Cu")
		(net "PD_CPU1_RSVD_TEST_2")
	)
	(segment
		(start 85.453728 -64.446912)
		(end 84.906612 -64.446912)
		(width 0.1651)
		(layer "B.Cu")
		(net "PD_CPU1_RSVD_TEST_2")
	)
	(segment
		(start 98.703638 -62.52464)
		(end 98.265488 -62.08649)
		(width 0.1651)
		(layer "B.Cu")
		(net "PD_CPU1_RSVD_TEST_2")
	)
	(segment
		(start 101.517704 -62.52464)
		(end 100.420678 -62.52464)
		(width 0.1651)
		(layer "B.Cu")
		(net "PD_CPU1_RSVD_TEST_2")
	)
	(segment
		(start 98.265488 -62.08649)
		(end 97.787714 -62.08649)
		(width 0.1651)
		(layer "B.Cu")
		(net "PD_CPU1_RSVD_TEST_2")
	)
	(segment
		(start 84.50072 -64.04102)
		(end 84.076286 -64.04102)
		(width 0.1651)
		(layer "B.Cu")
		(net "PD_CPU1_RSVD_TEST_2")
	)
	(segment
		(start 84.906612 -64.446912)
		(end 84.50072 -64.04102)
		(width 0.1651)
		(layer "B.Cu")
		(net "PD_CPU1_RSVD_TEST_2")
	)
	(segment
		(start 82.811874 -64.942466)
		(end 82.4484 -64.942466)
		(width 0.1651)
		(layer "B.Cu")
		(net "PD_CPU1_RSVD_TEST_2")
	)
	(segment
		(start 92.726256 -62.96279)
		(end 92.256864 -62.493398)
		(width 0.1651)
		(layer "B.Cu")
		(net "PD_CPU1_RSVD_TEST_2")
	)
	(segment
		(start 93.892624 -62.501272)
		(end 93.575886 -62.501272)
		(width 0.1651)
		(layer "B.Cu")
		(net "PD_CPU1_RSVD_TEST_2")
	)
	(segment
		(start 85.94725 -63.95339)
		(end 85.453728 -64.446912)
		(width 0.1651)
		(layer "B.Cu")
		(net "PD_CPU1_RSVD_TEST_2")
	)
	(segment
		(start 99.504754 -62.08649)
		(end 99.066604 -62.52464)
		(width 0.1651)
		(layer "B.Cu")
		(net "PD_CPU1_RSVD_TEST_2")
	)
	(segment
		(start 96.548448 -62.08649)
		(end 96.070674 -62.08649)
		(width 0.1651)
		(layer "B.Cu")
		(net "PD_CPU1_RSVD_TEST_2")
	)
	(segment
		(start 90.5383 -63.456312)
		(end 90.05951 -63.456312)
		(width 0.1651)
		(layer "B.Cu")
		(net "PD_CPU1_RSVD_TEST_2")
	)
	(segment
		(start 82.4484 -64.942466)
		(end 81.9023 -65.488566)
		(width 0.1651)
		(layer "B.Cu")
		(net "PD_CPU1_RSVD_TEST_2")
	)
	(segment
		(start 89.200736 -63.07709)
		(end 88.821514 -63.456312)
		(width 0.1651)
		(layer "B.Cu")
		(net "PD_CPU1_RSVD_TEST_2")
	)
	(segment
		(start 94.82709 -62.967108)
		(end 94.35846 -62.967108)
		(width 0.1651)
		(layer "B.Cu")
		(net "PD_CPU1_RSVD_TEST_2")
	)
	(segment
		(start 100.420678 -62.52464)
		(end 99.982528 -62.08649)
		(width 0.1651)
		(layer "B.Cu")
		(net "PD_CPU1_RSVD_TEST_2")
	)
	(segment
		(start 90.972386 -63.022226)
		(end 90.5383 -63.456312)
		(width 0.1651)
		(layer "B.Cu")
		(net "PD_CPU1_RSVD_TEST_2")
	)
	(segment
		(start 97.406968 -62.467236)
		(end 96.929194 -62.467236)
		(width 0.1651)
		(layer "B.Cu")
		(net "PD_CPU1_RSVD_TEST_2")
	)
	(segment
		(start 99.066604 -62.52464)
		(end 98.703638 -62.52464)
		(width 0.1651)
		(layer "B.Cu")
		(net "PD_CPU1_RSVD_TEST_2")
	)
	(segment
		(start 96.070674 -62.08649)
		(end 95.680022 -62.477142)
		(width 0.1651)
		(layer "B.Cu")
		(net "PD_CPU1_RSVD_TEST_2")
	)
	(segment
		(start 102.947724 -62.029086)
		(end 103.557324 -62.029086)
		(width 0.10795)
		(layer "F.Cu")
		(net "PD_CPU1_RSVD_TEST_1")
	)
	(via
		(at 103.557324 -62.029086)
		(size 0.508)
		(drill 0.254)
		(layers "F.Cu" "B.Cu")
		(net "PD_CPU1_RSVD_TEST_1")
	)
	(segment
		(start 87.104982 -62.581536)
		(end 87.484712 -62.961266)
		(width 0.1651)
		(layer "B.Cu")
		(net "PD_CPU1_RSVD_TEST_1")
	)
	(segment
		(start 88.821514 -62.465712)
		(end 89.236296 -62.05093)
		(width 0.1651)
		(layer "B.Cu")
		(net "PD_CPU1_RSVD_TEST_1")
	)
	(segment
		(start 84.990686 -63.504064)
		(end 85.346032 -63.504064)
		(width 0.1651)
		(layer "B.Cu")
		(net "PD_CPU1_RSVD_TEST_1")
	)
	(segment
		(start 81.242154 -64.262)
		(end 81.42859 -64.448436)
		(width 0.1651)
		(layer "B.Cu")
		(net "PD_CPU1_RSVD_TEST_1")
	)
	(segment
		(start 82.37728 -64.025272)
		(end 82.738468 -64.025272)
		(width 0.1651)
		(layer "B.Cu")
		(net "PD_CPU1_RSVD_TEST_1")
	)
	(segment
		(start 85.346032 -63.504064)
		(end 85.828378 -63.021718)
		(width 0.1651)
		(layer "B.Cu")
		(net "PD_CPU1_RSVD_TEST_1")
	)
	(segment
		(start 99.982274 -61.09589)
		(end 100.47732 -61.590936)
		(width 0.1651)
		(layer "B.Cu")
		(net "PD_CPU1_RSVD_TEST_1")
	)
	(segment
		(start 90.5383 -62.465712)
		(end 91.031822 -61.97219)
		(width 0.1651)
		(layer "B.Cu")
		(net "PD_CPU1_RSVD_TEST_1")
	)
	(segment
		(start 91.397328 -61.97219)
		(end 91.777058 -61.59246)
		(width 0.1651)
		(layer "B.Cu")
		(net "PD_CPU1_RSVD_TEST_1")
	)
	(segment
		(start 93.964506 -61.584586)
		(end 94.35211 -61.97219)
		(width 0.1651)
		(layer "B.Cu")
		(net "PD_CPU1_RSVD_TEST_1")
	)
	(segment
		(start 91.031822 -61.97219)
		(end 91.397328 -61.97219)
		(width 0.1651)
		(layer "B.Cu")
		(net "PD_CPU1_RSVD_TEST_1")
	)
	(segment
		(start 91.777058 -61.59246)
		(end 92.371418 -61.59246)
		(width 0.1651)
		(layer "B.Cu")
		(net "PD_CPU1_RSVD_TEST_1")
	)
	(segment
		(start 99.037902 -61.562742)
		(end 99.504754 -61.09589)
		(width 0.1651)
		(layer "B.Cu")
		(net "PD_CPU1_RSVD_TEST_1")
	)
	(segment
		(start 98.73234 -61.562742)
		(end 99.037902 -61.562742)
		(width 0.1651)
		(layer "B.Cu")
		(net "PD_CPU1_RSVD_TEST_1")
	)
	(segment
		(start 101.39299 -62.029086)
		(end 103.557324 -62.029086)
		(width 0.1651)
		(layer "B.Cu")
		(net "PD_CPU1_RSVD_TEST_1")
	)
	(segment
		(start 85.828378 -63.021718)
		(end 86.30158 -63.021718)
		(width 0.1651)
		(layer "B.Cu")
		(net "PD_CPU1_RSVD_TEST_1")
	)
	(segment
		(start 87.484712 -62.961266)
		(end 87.962994 -62.961266)
		(width 0.1651)
		(layer "B.Cu")
		(net "PD_CPU1_RSVD_TEST_1")
	)
	(segment
		(start 92.371418 -61.59246)
		(end 92.751148 -61.97219)
		(width 0.1651)
		(layer "B.Cu")
		(net "PD_CPU1_RSVD_TEST_1")
	)
	(segment
		(start 87.962994 -62.961266)
		(end 88.458548 -62.465712)
		(width 0.1651)
		(layer "B.Cu")
		(net "PD_CPU1_RSVD_TEST_1")
	)
	(segment
		(start 83.553046 -63.57366)
		(end 84.048092 -63.078614)
		(width 0.1651)
		(layer "B.Cu")
		(net "PD_CPU1_RSVD_TEST_1")
	)
	(segment
		(start 95.282258 -61.52134)
		(end 95.643192 -61.52134)
		(width 0.1651)
		(layer "B.Cu")
		(net "PD_CPU1_RSVD_TEST_1")
	)
	(segment
		(start 100.47732 -61.590936)
		(end 100.95484 -61.590936)
		(width 0.1651)
		(layer "B.Cu")
		(net "PD_CPU1_RSVD_TEST_1")
	)
	(segment
		(start 88.458548 -62.465712)
		(end 88.821514 -62.465712)
		(width 0.1651)
		(layer "B.Cu")
		(net "PD_CPU1_RSVD_TEST_1")
	)
	(segment
		(start 94.35211 -61.97219)
		(end 94.831408 -61.97219)
		(width 0.1651)
		(layer "B.Cu")
		(net "PD_CPU1_RSVD_TEST_1")
	)
	(segment
		(start 83.19008 -63.57366)
		(end 83.553046 -63.57366)
		(width 0.1651)
		(layer "B.Cu")
		(net "PD_CPU1_RSVD_TEST_1")
	)
	(segment
		(start 93.114368 -61.97219)
		(end 93.501972 -61.584586)
		(width 0.1651)
		(layer "B.Cu")
		(net "PD_CPU1_RSVD_TEST_1")
	)
	(segment
		(start 90.057478 -62.465712)
		(end 90.5383 -62.465712)
		(width 0.1651)
		(layer "B.Cu")
		(net "PD_CPU1_RSVD_TEST_1")
	)
	(segment
		(start 86.30158 -63.021718)
		(end 86.741762 -62.581536)
		(width 0.1651)
		(layer "B.Cu")
		(net "PD_CPU1_RSVD_TEST_1")
	)
	(segment
		(start 92.751148 -61.97219)
		(end 93.114368 -61.97219)
		(width 0.1651)
		(layer "B.Cu")
		(net "PD_CPU1_RSVD_TEST_1")
	)
	(segment
		(start 89.642696 -62.05093)
		(end 90.057478 -62.465712)
		(width 0.1651)
		(layer "B.Cu")
		(net "PD_CPU1_RSVD_TEST_1")
	)
	(segment
		(start 82.738468 -64.025272)
		(end 83.19008 -63.57366)
		(width 0.1651)
		(layer "B.Cu")
		(net "PD_CPU1_RSVD_TEST_1")
	)
	(segment
		(start 95.643192 -61.52134)
		(end 96.156526 -61.008006)
		(width 0.1651)
		(layer "B.Cu")
		(net "PD_CPU1_RSVD_TEST_1")
	)
	(segment
		(start 89.236296 -62.05093)
		(end 89.642696 -62.05093)
		(width 0.1651)
		(layer "B.Cu")
		(net "PD_CPU1_RSVD_TEST_1")
	)
	(segment
		(start 96.460564 -61.008006)
		(end 96.966024 -61.513466)
		(width 0.1651)
		(layer "B.Cu")
		(net "PD_CPU1_RSVD_TEST_1")
	)
	(segment
		(start 84.565236 -63.078614)
		(end 84.990686 -63.504064)
		(width 0.1651)
		(layer "B.Cu")
		(net "PD_CPU1_RSVD_TEST_1")
	)
	(segment
		(start 81.954116 -64.448436)
		(end 82.37728 -64.025272)
		(width 0.1651)
		(layer "B.Cu")
		(net "PD_CPU1_RSVD_TEST_1")
	)
	(segment
		(start 100.95484 -61.590936)
		(end 101.39299 -62.029086)
		(width 0.1651)
		(layer "B.Cu")
		(net "PD_CPU1_RSVD_TEST_1")
	)
	(segment
		(start 84.048092 -63.078614)
		(end 84.565236 -63.078614)
		(width 0.1651)
		(layer "B.Cu")
		(net "PD_CPU1_RSVD_TEST_1")
	)
	(segment
		(start 97.787714 -61.09589)
		(end 98.265488 -61.09589)
		(width 0.1651)
		(layer "B.Cu")
		(net "PD_CPU1_RSVD_TEST_1")
	)
	(segment
		(start 80.391 -64.262)
		(end 81.242154 -64.262)
		(width 0.1651)
		(layer "B.Cu")
		(net "PD_CPU1_RSVD_TEST_1")
	)
	(segment
		(start 81.42859 -64.448436)
		(end 81.954116 -64.448436)
		(width 0.1651)
		(layer "B.Cu")
		(net "PD_CPU1_RSVD_TEST_1")
	)
	(segment
		(start 98.265488 -61.09589)
		(end 98.73234 -61.562742)
		(width 0.1651)
		(layer "B.Cu")
		(net "PD_CPU1_RSVD_TEST_1")
	)
	(segment
		(start 97.370138 -61.513466)
		(end 97.787714 -61.09589)
		(width 0.1651)
		(layer "B.Cu")
		(net "PD_CPU1_RSVD_TEST_1")
	)
	(segment
		(start 96.156526 -61.008006)
		(end 96.460564 -61.008006)
		(width 0.1651)
		(layer "B.Cu")
		(net "PD_CPU1_RSVD_TEST_1")
	)
	(segment
		(start 93.501972 -61.584586)
		(end 93.964506 -61.584586)
		(width 0.1651)
		(layer "B.Cu")
		(net "PD_CPU1_RSVD_TEST_1")
	)
	(segment
		(start 99.504754 -61.09589)
		(end 99.982274 -61.09589)
		(width 0.1651)
		(layer "B.Cu")
		(net "PD_CPU1_RSVD_TEST_1")
	)
	(segment
		(start 86.741762 -62.581536)
		(end 87.104982 -62.581536)
		(width 0.1651)
		(layer "B.Cu")
		(net "PD_CPU1_RSVD_TEST_1")
	)
	(segment
		(start 96.966024 -61.513466)
		(end 97.370138 -61.513466)
		(width 0.1651)
		(layer "B.Cu")
		(net "PD_CPU1_RSVD_TEST_1")
	)
	(segment
		(start 94.831408 -61.97219)
		(end 95.282258 -61.52134)
		(width 0.1651)
		(layer "B.Cu")
		(net "PD_CPU1_RSVD_TEST_1")
	)
	(segment
		(start 267.089636 -62.52464)
		(end 266.518136 -62.52464)
		(width 0.10795)
		(layer "F.Cu")
		(net "PD_CPU0_RSVD_TEST_2")
	)
	(via
		(at 266.518136 -62.52464)
		(size 0.508)
		(drill 0.254)
		(layers "F.Cu" "B.Cu")
		(net "PD_CPU0_RSVD_TEST_2")
	)
	(via
		(at 245.767606 -66.063622)
		(size 0.6604)
		(drill 0.3302)
		(layers "F.Cu" "B.Cu")
		(net "PD_CPU0_RSVD_TEST_2")
	)
	(segment
		(start 257.253232 -61.480192)
		(end 256.896108 -61.480192)
		(width 0.15875)
		(layer "B.Cu")
		(net "PD_CPU0_RSVD_TEST_2")
	)
	(segment
		(start 255.525524 -61.494162)
		(end 255.195578 -61.494162)
		(width 0.15875)
		(layer "B.Cu")
		(net "PD_CPU0_RSVD_TEST_2")
	)
	(segment
		(start 266.436348 -60.0964)
		(end 265.861546 -59.521598)
		(width 0.15875)
		(layer "B.Cu")
		(net "PD_CPU0_RSVD_TEST_2")
	)
	(segment
		(start 245.018306 -65.634616)
		(end 245.018306 -65.1764)
		(width 0.1651)
		(layer "B.Cu")
		(net "PD_CPU0_RSVD_TEST_2")
	)
	(segment
		(start 256.896108 -61.480192)
		(end 256.406142 -60.990226)
		(width 0.15875)
		(layer "B.Cu")
		(net "PD_CPU0_RSVD_TEST_2")
	)
	(segment
		(start 264.96391 -60.009278)
		(end 264.638282 -60.009278)
		(width 0.15875)
		(layer "B.Cu")
		(net "PD_CPU0_RSVD_TEST_2")
	)
	(segment
		(start 258.143248 -61.00826)
		(end 257.725164 -61.00826)
		(width 0.15875)
		(layer "B.Cu")
		(net "PD_CPU0_RSVD_TEST_2")
	)
	(segment
		(start 251.247148 -63.078614)
		(end 250.884182 -63.078614)
		(width 0.15875)
		(layer "B.Cu")
		(net "PD_CPU0_RSVD_TEST_2")
	)
	(segment
		(start 252.106176 -62.58306)
		(end 251.742702 -62.58306)
		(width 0.15875)
		(layer "B.Cu")
		(net "PD_CPU0_RSVD_TEST_2")
	)
	(segment
		(start 255.195578 -61.494162)
		(end 254.7493 -61.047884)
		(width 0.15875)
		(layer "B.Cu")
		(net "PD_CPU0_RSVD_TEST_2")
	)
	(segment
		(start 259.879846 -61.000132)
		(end 259.454142 -61.000132)
		(width 0.15875)
		(layer "B.Cu")
		(net "PD_CPU0_RSVD_TEST_2")
	)
	(segment
		(start 245.767606 -66.063622)
		(end 245.447312 -66.063622)
		(width 0.1651)
		(layer "B.Cu")
		(net "PD_CPU0_RSVD_TEST_2")
	)
	(segment
		(start 257.725164 -61.00826)
		(end 257.253232 -61.480192)
		(width 0.15875)
		(layer "B.Cu")
		(net "PD_CPU0_RSVD_TEST_2")
	)
	(segment
		(start 248.308622 -64.56426)
		(end 247.890792 -64.98209)
		(width 0.15875)
		(layer "B.Cu")
		(net "PD_CPU0_RSVD_TEST_2")
	)
	(segment
		(start 258.624832 -61.489844)
		(end 258.143248 -61.00826)
		(width 0.15875)
		(layer "B.Cu")
		(net "PD_CPU0_RSVD_TEST_2")
	)
	(segment
		(start 249.164602 -63.962026)
		(end 248.562368 -64.56426)
		(width 0.15875)
		(layer "B.Cu")
		(net "PD_CPU0_RSVD_TEST_2")
	)
	(segment
		(start 256.02946 -60.990226)
		(end 255.525524 -61.494162)
		(width 0.15875)
		(layer "B.Cu")
		(net "PD_CPU0_RSVD_TEST_2")
	)
	(segment
		(start 262.416798 -59.509406)
		(end 262.03402 -59.509406)
		(width 0.15875)
		(layer "B.Cu")
		(net "PD_CPU0_RSVD_TEST_2")
	)
	(segment
		(start 248.562368 -64.56426)
		(end 248.308622 -64.56426)
		(width 0.15875)
		(layer "B.Cu")
		(net "PD_CPU0_RSVD_TEST_2")
	)
	(segment
		(start 260.712712 -60.57392)
		(end 260.306058 -60.57392)
		(width 0.15875)
		(layer "B.Cu")
		(net "PD_CPU0_RSVD_TEST_2")
	)
	(segment
		(start 262.03402 -59.509406)
		(end 261.522464 -60.020962)
		(width 0.15875)
		(layer "B.Cu")
		(net "PD_CPU0_RSVD_TEST_2")
	)
	(segment
		(start 250.884182 -63.078614)
		(end 250.389136 -63.57366)
		(width 0.15875)
		(layer "B.Cu")
		(net "PD_CPU0_RSVD_TEST_2")
	)
	(segment
		(start 263.280144 -59.993276)
		(end 262.900668 -59.993276)
		(width 0.15875)
		(layer "B.Cu")
		(net "PD_CPU0_RSVD_TEST_2")
	)
	(segment
		(start 260.306058 -60.57392)
		(end 259.879846 -61.000132)
		(width 0.15875)
		(layer "B.Cu")
		(net "PD_CPU0_RSVD_TEST_2")
	)
	(segment
		(start 253.713234 -61.59246)
		(end 253.459742 -61.59246)
		(width 0.15875)
		(layer "B.Cu")
		(net "PD_CPU0_RSVD_TEST_2")
	)
	(segment
		(start 247.418098 -64.98209)
		(end 246.961152 -65.439036)
		(width 0.15875)
		(layer "B.Cu")
		(net "PD_CPU0_RSVD_TEST_2")
	)
	(segment
		(start 253.459742 -61.59246)
		(end 252.964188 -62.088014)
		(width 0.15875)
		(layer "B.Cu")
		(net "PD_CPU0_RSVD_TEST_2")
	)
	(segment
		(start 266.728194 -60.0964)
		(end 266.436348 -60.0964)
		(width 0.15875)
		(layer "B.Cu")
		(net "PD_CPU0_RSVD_TEST_2")
	)
	(segment
		(start 261.26567 -60.020962)
		(end 260.712712 -60.57392)
		(width 0.15875)
		(layer "B.Cu")
		(net "PD_CPU0_RSVD_TEST_2")
	)
	(segment
		(start 250.389136 -63.57366)
		(end 250.025662 -63.57366)
		(width 0.15875)
		(layer "B.Cu")
		(net "PD_CPU0_RSVD_TEST_2")
	)
	(segment
		(start 245.447312 -66.063622)
		(end 245.018306 -65.634616)
		(width 0.1651)
		(layer "B.Cu")
		(net "PD_CPU0_RSVD_TEST_2")
	)
	(segment
		(start 247.890792 -64.98209)
		(end 247.418098 -64.98209)
		(width 0.15875)
		(layer "B.Cu")
		(net "PD_CPU0_RSVD_TEST_2")
	)
	(segment
		(start 246.08282 -66.063622)
		(end 245.767606 -66.063622)
		(width 0.15875)
		(layer "B.Cu")
		(net "PD_CPU0_RSVD_TEST_2")
	)
	(segment
		(start 263.755886 -59.517534)
		(end 263.280144 -59.993276)
		(width 0.15875)
		(layer "B.Cu")
		(net "PD_CPU0_RSVD_TEST_2")
	)
	(segment
		(start 246.707406 -65.439036)
		(end 246.08282 -66.063622)
		(width 0.15875)
		(layer "B.Cu")
		(net "PD_CPU0_RSVD_TEST_2")
	)
	(segment
		(start 264.638282 -60.009278)
		(end 264.146538 -59.517534)
		(width 0.15875)
		(layer "B.Cu")
		(net "PD_CPU0_RSVD_TEST_2")
	)
	(segment
		(start 264.146538 -59.517534)
		(end 263.755886 -59.517534)
		(width 0.15875)
		(layer "B.Cu")
		(net "PD_CPU0_RSVD_TEST_2")
	)
	(segment
		(start 251.742702 -62.58306)
		(end 251.247148 -63.078614)
		(width 0.15875)
		(layer "B.Cu")
		(net "PD_CPU0_RSVD_TEST_2")
	)
	(segment
		(start 261.522464 -60.020962)
		(end 261.26567 -60.020962)
		(width 0.15875)
		(layer "B.Cu")
		(net "PD_CPU0_RSVD_TEST_2")
	)
	(segment
		(start 252.601222 -62.088014)
		(end 252.106176 -62.58306)
		(width 0.15875)
		(layer "B.Cu")
		(net "PD_CPU0_RSVD_TEST_2")
	)
	(segment
		(start 254.286004 -61.01969)
		(end 253.713234 -61.59246)
		(width 0.15875)
		(layer "B.Cu")
		(net "PD_CPU0_RSVD_TEST_2")
	)
	(segment
		(start 254.712216 -61.01969)
		(end 254.286004 -61.01969)
		(width 0.15875)
		(layer "B.Cu")
		(net "PD_CPU0_RSVD_TEST_2")
	)
	(segment
		(start 254.74041 -61.047884)
		(end 254.712216 -61.01969)
		(width 0.15875)
		(layer "B.Cu")
		(net "PD_CPU0_RSVD_TEST_2")
	)
	(segment
		(start 259.454142 -61.000132)
		(end 258.96443 -61.489844)
		(width 0.15875)
		(layer "B.Cu")
		(net "PD_CPU0_RSVD_TEST_2")
	)
	(segment
		(start 265.45159 -59.521598)
		(end 264.96391 -60.009278)
		(width 0.15875)
		(layer "B.Cu")
		(net "PD_CPU0_RSVD_TEST_2")
	)
	(segment
		(start 265.861546 -59.521598)
		(end 265.45159 -59.521598)
		(width 0.15875)
		(layer "B.Cu")
		(net "PD_CPU0_RSVD_TEST_2")
	)
	(segment
		(start 258.96443 -61.489844)
		(end 258.624832 -61.489844)
		(width 0.15875)
		(layer "B.Cu")
		(net "PD_CPU0_RSVD_TEST_2")
	)
	(segment
		(start 254.7493 -61.047884)
		(end 254.74041 -61.047884)
		(width 0.15875)
		(layer "B.Cu")
		(net "PD_CPU0_RSVD_TEST_2")
	)
	(segment
		(start 252.964188 -62.088014)
		(end 252.601222 -62.088014)
		(width 0.15875)
		(layer "B.Cu")
		(net "PD_CPU0_RSVD_TEST_2")
	)
	(segment
		(start 267.0556 -61.987176)
		(end 267.0556 -60.423806)
		(width 0.15875)
		(layer "B.Cu")
		(net "PD_CPU0_RSVD_TEST_2")
	)
	(segment
		(start 256.406142 -60.990226)
		(end 256.02946 -60.990226)
		(width 0.15875)
		(layer "B.Cu")
		(net "PD_CPU0_RSVD_TEST_2")
	)
	(segment
		(start 250.025662 -63.57366)
		(end 249.637296 -63.962026)
		(width 0.15875)
		(layer "B.Cu")
		(net "PD_CPU0_RSVD_TEST_2")
	)
	(segment
		(start 262.900668 -59.993276)
		(end 262.416798 -59.509406)
		(width 0.15875)
		(layer "B.Cu")
		(net "PD_CPU0_RSVD_TEST_2")
	)
	(segment
		(start 267.0556 -60.423806)
		(end 266.728194 -60.0964)
		(width 0.15875)
		(layer "B.Cu")
		(net "PD_CPU0_RSVD_TEST_2")
	)
	(segment
		(start 246.961152 -65.439036)
		(end 246.707406 -65.439036)
		(width 0.15875)
		(layer "B.Cu")
		(net "PD_CPU0_RSVD_TEST_2")
	)
	(segment
		(start 266.518136 -62.52464)
		(end 267.0556 -61.987176)
		(width 0.15875)
		(layer "B.Cu")
		(net "PD_CPU0_RSVD_TEST_2")
	)
	(segment
		(start 249.637296 -63.962026)
		(end 249.164602 -63.962026)
		(width 0.15875)
		(layer "B.Cu")
		(net "PD_CPU0_RSVD_TEST_2")
	)
	(segment
		(start 267.948156 -62.029086)
		(end 268.557756 -62.029086)
		(width 0.10795)
		(layer "F.Cu")
		(net "PD_CPU0_RSVD_TEST_1")
	)
	(via
		(at 245.927372 -64.666876)
		(size 0.6604)
		(drill 0.3302)
		(layers "F.Cu" "B.Cu")
		(net "PD_CPU0_RSVD_TEST_1")
	)
	(via
		(at 268.557756 -62.029086)
		(size 0.508)
		(drill 0.254)
		(layers "F.Cu" "B.Cu")
		(net "PD_CPU0_RSVD_TEST_1")
	)
	(segment
		(start 252.963426 -60.980066)
		(end 252.599952 -60.980066)
		(width 0.15875)
		(layer "B.Cu")
		(net "PD_CPU0_RSVD_TEST_1")
	)
	(segment
		(start 261.107428 -59.076336)
		(end 260.689852 -59.493912)
		(width 0.15875)
		(layer "B.Cu")
		(net "PD_CPU0_RSVD_TEST_1")
	)
	(segment
		(start 253.85395 -60.562236)
		(end 253.381256 -60.562236)
		(width 0.15875)
		(layer "B.Cu")
		(net "PD_CPU0_RSVD_TEST_1")
	)
	(segment
		(start 249.088148 -63.03899)
		(end 248.553478 -63.57366)
		(width 0.15875)
		(layer "B.Cu")
		(net "PD_CPU0_RSVD_TEST_1")
	)
	(segment
		(start 251.220478 -61.996574)
		(end 250.906026 -61.996574)
		(width 0.15875)
		(layer "B.Cu")
		(net "PD_CPU0_RSVD_TEST_1")
	)
	(segment
		(start 250.044204 -62.556136)
		(end 249.56135 -63.03899)
		(width 0.15875)
		(layer "B.Cu")
		(net "PD_CPU0_RSVD_TEST_1")
	)
	(segment
		(start 263.761728 -58.62066)
		(end 263.306052 -59.076336)
		(width 0.15875)
		(layer "B.Cu")
		(net "PD_CPU0_RSVD_TEST_1")
	)
	(segment
		(start 256.861564 -60.562236)
		(end 256.406142 -60.106814)
		(width 0.15875)
		(layer "B.Cu")
		(net "PD_CPU0_RSVD_TEST_1")
	)
	(segment
		(start 252.104906 -61.475112)
		(end 251.74194 -61.475112)
		(width 0.15875)
		(layer "B.Cu")
		(net "PD_CPU0_RSVD_TEST_1")
	)
	(segment
		(start 250.346464 -62.556136)
		(end 250.044204 -62.556136)
		(width 0.15875)
		(layer "B.Cu")
		(net "PD_CPU0_RSVD_TEST_1")
	)
	(segment
		(start 259.004816 -60.562236)
		(end 258.569714 -60.562236)
		(width 0.15875)
		(layer "B.Cu")
		(net "PD_CPU0_RSVD_TEST_1")
	)
	(segment
		(start 246.955056 -64.537336)
		(end 246.520462 -64.537336)
		(width 0.15875)
		(layer "B.Cu")
		(net "PD_CPU0_RSVD_TEST_1")
	)
	(segment
		(start 268.557756 -62.029086)
		(end 268.158468 -62.029086)
		(width 0.15875)
		(layer "B.Cu")
		(net "PD_CPU0_RSVD_TEST_1")
	)
	(segment
		(start 257.287776 -60.562236)
		(end 256.861564 -60.562236)
		(width 0.15875)
		(layer "B.Cu")
		(net "PD_CPU0_RSVD_TEST_1")
	)
	(segment
		(start 262.044688 -58.62066)
		(end 261.706106 -58.959242)
		(width 0.15875)
		(layer "B.Cu")
		(net "PD_CPU0_RSVD_TEST_1")
	)
	(segment
		(start 265.844274 -58.62066)
		(end 265.469878 -58.62066)
		(width 0.15875)
		(layer "B.Cu")
		(net "PD_CPU0_RSVD_TEST_1")
	)
	(segment
		(start 249.56135 -63.03899)
		(end 249.088148 -63.03899)
		(width 0.15875)
		(layer "B.Cu")
		(net "PD_CPU0_RSVD_TEST_1")
	)
	(segment
		(start 255.570736 -60.562236)
		(end 255.135634 -60.562236)
		(width 0.15875)
		(layer "B.Cu")
		(net "PD_CPU0_RSVD_TEST_1")
	)
	(segment
		(start 267.675106 -59.839352)
		(end 266.948412 -59.112658)
		(width 0.15875)
		(layer "B.Cu")
		(net "PD_CPU0_RSVD_TEST_1")
	)
	(segment
		(start 258.569714 -60.562236)
		(end 258.114292 -60.106814)
		(width 0.15875)
		(layer "B.Cu")
		(net "PD_CPU0_RSVD_TEST_1")
	)
	(segment
		(start 264.579608 -59.076336)
		(end 264.123932 -58.62066)
		(width 0.15875)
		(layer "B.Cu")
		(net "PD_CPU0_RSVD_TEST_1")
	)
	(segment
		(start 259.771388 -60.04941)
		(end 259.517642 -60.04941)
		(width 0.15875)
		(layer "B.Cu")
		(net "PD_CPU0_RSVD_TEST_1")
	)
	(segment
		(start 262.745474 -58.959242)
		(end 262.406892 -58.62066)
		(width 0.15875)
		(layer "B.Cu")
		(net "PD_CPU0_RSVD_TEST_1")
	)
	(segment
		(start 265.469878 -58.62066)
		(end 265.014202 -59.076336)
		(width 0.15875)
		(layer "B.Cu")
		(net "PD_CPU0_RSVD_TEST_1")
	)
	(segment
		(start 246.390922 -64.666876)
		(end 245.927372 -64.666876)
		(width 0.15875)
		(layer "B.Cu")
		(net "PD_CPU0_RSVD_TEST_1")
	)
	(segment
		(start 261.69747 -58.959242)
		(end 261.580376 -59.076336)
		(width 0.15875)
		(layer "B.Cu")
		(net "PD_CPU0_RSVD_TEST_1")
	)
	(segment
		(start 254.309372 -60.106814)
		(end 253.85395 -60.562236)
		(width 0.15875)
		(layer "B.Cu")
		(net "PD_CPU0_RSVD_TEST_1")
	)
	(segment
		(start 266.948412 -59.112658)
		(end 266.336272 -59.112658)
		(width 0.15875)
		(layer "B.Cu")
		(net "PD_CPU0_RSVD_TEST_1")
	)
	(segment
		(start 261.706106 -58.959242)
		(end 261.69747 -58.959242)
		(width 0.15875)
		(layer "B.Cu")
		(net "PD_CPU0_RSVD_TEST_1")
	)
	(segment
		(start 260.326886 -59.493912)
		(end 259.771388 -60.04941)
		(width 0.15875)
		(layer "B.Cu")
		(net "PD_CPU0_RSVD_TEST_1")
	)
	(segment
		(start 256.406142 -60.106814)
		(end 256.026158 -60.106814)
		(width 0.15875)
		(layer "B.Cu")
		(net "PD_CPU0_RSVD_TEST_1")
	)
	(segment
		(start 262.406892 -58.62066)
		(end 262.044688 -58.62066)
		(width 0.15875)
		(layer "B.Cu")
		(net "PD_CPU0_RSVD_TEST_1")
	)
	(segment
		(start 262.871204 -59.076336)
		(end 262.75411 -58.959242)
		(width 0.15875)
		(layer "B.Cu")
		(net "PD_CPU0_RSVD_TEST_1")
	)
	(segment
		(start 267.675106 -61.545724)
		(end 267.675106 -59.839352)
		(width 0.15875)
		(layer "B.Cu")
		(net "PD_CPU0_RSVD_TEST_1")
	)
	(segment
		(start 266.336272 -59.112658)
		(end 265.844274 -58.62066)
		(width 0.15875)
		(layer "B.Cu")
		(net "PD_CPU0_RSVD_TEST_1")
	)
	(segment
		(start 254.680212 -60.106814)
		(end 254.309372 -60.106814)
		(width 0.15875)
		(layer "B.Cu")
		(net "PD_CPU0_RSVD_TEST_1")
	)
	(segment
		(start 265.014202 -59.076336)
		(end 264.579608 -59.076336)
		(width 0.15875)
		(layer "B.Cu")
		(net "PD_CPU0_RSVD_TEST_1")
	)
	(segment
		(start 252.599952 -60.980066)
		(end 252.104906 -61.475112)
		(width 0.15875)
		(layer "B.Cu")
		(net "PD_CPU0_RSVD_TEST_1")
	)
	(segment
		(start 246.520462 -64.537336)
		(end 246.390922 -64.666876)
		(width 0.15875)
		(layer "B.Cu")
		(net "PD_CPU0_RSVD_TEST_1")
	)
	(segment
		(start 261.580376 -59.076336)
		(end 261.107428 -59.076336)
		(width 0.15875)
		(layer "B.Cu")
		(net "PD_CPU0_RSVD_TEST_1")
	)
	(segment
		(start 264.123932 -58.62066)
		(end 263.761728 -58.62066)
		(width 0.15875)
		(layer "B.Cu")
		(net "PD_CPU0_RSVD_TEST_1")
	)
	(segment
		(start 245.927372 -64.666876)
		(end 245.547896 -64.2874)
		(width 0.1651)
		(layer "B.Cu")
		(net "PD_CPU0_RSVD_TEST_1")
	)
	(segment
		(start 260.689852 -59.493912)
		(end 260.326886 -59.493912)
		(width 0.15875)
		(layer "B.Cu")
		(net "PD_CPU0_RSVD_TEST_1")
	)
	(segment
		(start 248.553478 -63.57366)
		(end 248.190512 -63.57366)
		(width 0.15875)
		(layer "B.Cu")
		(net "PD_CPU0_RSVD_TEST_1")
	)
	(segment
		(start 251.74194 -61.475112)
		(end 251.220478 -61.996574)
		(width 0.15875)
		(layer "B.Cu")
		(net "PD_CPU0_RSVD_TEST_1")
	)
	(segment
		(start 262.75411 -58.959242)
		(end 262.745474 -58.959242)
		(width 0.15875)
		(layer "B.Cu")
		(net "PD_CPU0_RSVD_TEST_1")
	)
	(segment
		(start 258.114292 -60.106814)
		(end 257.743198 -60.106814)
		(width 0.15875)
		(layer "B.Cu")
		(net "PD_CPU0_RSVD_TEST_1")
	)
	(segment
		(start 247.694958 -64.069214)
		(end 247.423178 -64.069214)
		(width 0.15875)
		(layer "B.Cu")
		(net "PD_CPU0_RSVD_TEST_1")
	)
	(segment
		(start 250.906026 -61.996574)
		(end 250.346464 -62.556136)
		(width 0.15875)
		(layer "B.Cu")
		(net "PD_CPU0_RSVD_TEST_1")
	)
	(segment
		(start 248.190512 -63.57366)
		(end 247.694958 -64.069214)
		(width 0.15875)
		(layer "B.Cu")
		(net "PD_CPU0_RSVD_TEST_1")
	)
	(segment
		(start 257.743198 -60.106814)
		(end 257.287776 -60.562236)
		(width 0.15875)
		(layer "B.Cu")
		(net "PD_CPU0_RSVD_TEST_1")
	)
	(segment
		(start 268.158468 -62.029086)
		(end 267.675106 -61.545724)
		(width 0.15875)
		(layer "B.Cu")
		(net "PD_CPU0_RSVD_TEST_1")
	)
	(segment
		(start 255.135634 -60.562236)
		(end 254.680212 -60.106814)
		(width 0.15875)
		(layer "B.Cu")
		(net "PD_CPU0_RSVD_TEST_1")
	)
	(segment
		(start 247.423178 -64.069214)
		(end 246.955056 -64.537336)
		(width 0.15875)
		(layer "B.Cu")
		(net "PD_CPU0_RSVD_TEST_1")
	)
	(segment
		(start 245.547896 -64.2874)
		(end 245.018306 -64.2874)
		(width 0.1651)
		(layer "B.Cu")
		(net "PD_CPU0_RSVD_TEST_1")
	)
	(segment
		(start 253.381256 -60.562236)
		(end 252.963426 -60.980066)
		(width 0.15875)
		(layer "B.Cu")
		(net "PD_CPU0_RSVD_TEST_1")
	)
	(segment
		(start 263.306052 -59.076336)
		(end 262.871204 -59.076336)
		(width 0.15875)
		(layer "B.Cu")
		(net "PD_CPU0_RSVD_TEST_1")
	)
	(segment
		(start 259.517642 -60.04941)
		(end 259.004816 -60.562236)
		(width 0.15875)
		(layer "B.Cu")
		(net "PD_CPU0_RSVD_TEST_1")
	)
	(segment
		(start 256.026158 -60.106814)
		(end 255.570736 -60.562236)
		(width 0.15875)
		(layer "B.Cu")
		(net "PD_CPU0_RSVD_TEST_1")
	)
	(segment
		(start 415.7345 -109.728)
		(end 415.7345 -108.4961)
		(width 0.10795)
		(layer "F.Cu")
		(net "IRQ_BMC_PCH_NMI_STBY_R_N")
	)
	(segment
		(start 416.3568 -108.4834)
		(end 415.7218 -108.4834)
		(width 0.10795)
		(layer "F.Cu")
		(net "IRQ_BMC_PCH_NMI_STBY_R_N")
	)
	(segment
		(start 415.7345 -108.4961)
		(end 415.7218 -108.4834)
		(width 0.10795)
		(layer "F.Cu")
		(net "IRQ_BMC_PCH_NMI_STBY_R_N")
	)
	(segment
		(start 416.644328 -109.008418)
		(end 416.644328 -108.770928)
		(width 0.10795)
		(layer "F.Cu")
		(net "IRQ_BMC_PCH_NMI_STBY_R_N")
	)
	(segment
		(start 416.71875 -109.08284)
		(end 416.644328 -109.008418)
		(width 0.10795)
		(layer "F.Cu")
		(net "IRQ_BMC_PCH_NMI_STBY_R_N")
	)
	(segment
		(start 398.63395 -112.43056)
		(end 399.12925 -112.660684)
		(width 0.10795)
		(layer "F.Cu")
		(net "IRQ_BMC_PCH_NMI_STBY_R_N")
	)
	(segment
		(start 416.644328 -108.770928)
		(end 416.3568 -108.4834)
		(width 0.10795)
		(layer "F.Cu")
		(net "IRQ_BMC_PCH_NMI_STBY_R_N")
	)
	(via
		(at 399.12925 -112.660684)
		(size 0.508)
		(drill 0.254)
		(layers "F.Cu" "B.Cu")
		(net "IRQ_BMC_PCH_NMI_STBY_R_N")
	)
	(via
		(at 415.7218 -108.4834)
		(size 0.762)
		(drill 0.381)
		(layers "F.Cu" "B.Cu")
		(net "IRQ_BMC_PCH_NMI_STBY_R_N")
	)
	(via
		(at 416.71875 -109.08284)
		(size 0.508)
		(drill 0.254)
		(layers "F.Cu" "B.Cu")
		(net "IRQ_BMC_PCH_NMI_STBY_R_N")
	)
	(segment
		(start 405.535892 -110.995968)
		(end 402.727414 -110.995968)
		(width 0.089408)
		(layer "In9.Cu")
		(net "IRQ_BMC_PCH_NMI_STBY_R_N")
	)
	(segment
		(start 411.52572 -109.1946)
		(end 409.703016 -111.017304)
		(width 0.089408)
		(layer "In9.Cu")
		(net "IRQ_BMC_PCH_NMI_STBY_R_N")
	)
	(segment
		(start 401.71243 -111.49838)
		(end 400.550126 -112.660684)
		(width 0.089408)
		(layer "In9.Cu")
		(net "IRQ_BMC_PCH_NMI_STBY_R_N")
	)
	(segment
		(start 402.727414 -110.995968)
		(end 402.225002 -111.49838)
		(width 0.089408)
		(layer "In9.Cu")
		(net "IRQ_BMC_PCH_NMI_STBY_R_N")
	)
	(segment
		(start 409.703016 -111.017304)
		(end 405.557228 -111.017304)
		(width 0.089408)
		(layer "In9.Cu")
		(net "IRQ_BMC_PCH_NMI_STBY_R_N")
	)
	(segment
		(start 416.71875 -109.08284)
		(end 416.60699 -109.1946)
		(width 0.089408)
		(layer "In9.Cu")
		(net "IRQ_BMC_PCH_NMI_STBY_R_N")
	)
	(segment
		(start 402.225002 -111.49838)
		(end 401.71243 -111.49838)
		(width 0.089408)
		(layer "In9.Cu")
		(net "IRQ_BMC_PCH_NMI_STBY_R_N")
	)
	(segment
		(start 416.60699 -109.1946)
		(end 411.52572 -109.1946)
		(width 0.089408)
		(layer "In9.Cu")
		(net "IRQ_BMC_PCH_NMI_STBY_R_N")
	)
	(segment
		(start 400.550126 -112.660684)
		(end 399.12925 -112.660684)
		(width 0.089408)
		(layer "In9.Cu")
		(net "IRQ_BMC_PCH_NMI_STBY_R_N")
	)
	(segment
		(start 405.557228 -111.017304)
		(end 405.535892 -110.995968)
		(width 0.089408)
		(layer "In9.Cu")
		(net "IRQ_BMC_PCH_NMI_STBY_R_N")
	)
	(via
		(at 373.507 -41.5798)
		(size 0.508)
		(drill 0.254)
		(layers "F.Cu" "B.Cu")
		(net "H_CPU_ERR1_GTL_R_N")
	)
	(segment
		(start 373.884952 -42.335958)
		(end 374.646952 -42.335958)
		(width 0.10795)
		(layer "B.Cu")
		(net "H_CPU_ERR1_GTL_R_N")
	)
	(segment
		(start 372.691152 -40.9448)
		(end 372.411752 -41.2242)
		(width 0.10795)
		(layer "B.Cu")
		(net "H_CPU_ERR1_GTL_R_N")
	)
	(segment
		(start 373.507 -41.1226)
		(end 373.3292 -40.9448)
		(width 0.10795)
		(layer "B.Cu")
		(net "H_CPU_ERR1_GTL_R_N")
	)
	(segment
		(start 372.411752 -41.2242)
		(end 372.411752 -42.615358)
		(width 0.10795)
		(layer "B.Cu")
		(net "H_CPU_ERR1_GTL_R_N")
	)
	(segment
		(start 374.646952 -42.335958)
		(end 375.408952 -42.335958)
		(width 0.10795)
		(layer "B.Cu")
		(net "H_CPU_ERR1_GTL_R_N")
	)
	(segment
		(start 376.170952 -42.335958)
		(end 375.408952 -42.335958)
		(width 0.10795)
		(layer "B.Cu")
		(net "H_CPU_ERR1_GTL_R_N")
	)
	(segment
		(start 373.507 -41.5798)
		(end 373.507 -41.958006)
		(width 0.10795)
		(layer "B.Cu")
		(net "H_CPU_ERR1_GTL_R_N")
	)
	(segment
		(start 373.507 -41.5798)
		(end 373.507 -41.1226)
		(width 0.10795)
		(layer "B.Cu")
		(net "H_CPU_ERR1_GTL_R_N")
	)
	(segment
		(start 373.507 -41.958006)
		(end 373.884952 -42.335958)
		(width 0.10795)
		(layer "B.Cu")
		(net "H_CPU_ERR1_GTL_R_N")
	)
	(segment
		(start 373.3292 -40.9448)
		(end 372.691152 -40.9448)
		(width 0.10795)
		(layer "B.Cu")
		(net "H_CPU_ERR1_GTL_R_N")
	)
	(via
		(at 372.5672 -39.8272)
		(size 0.508)
		(drill 0.254)
		(layers "F.Cu" "B.Cu")
		(net "H_CPU_ERR0_GTL_R_N")
	)
	(segment
		(start 372.2116 -39.8272)
		(end 371.875558 -40.163242)
		(width 0.10795)
		(layer "B.Cu")
		(net "H_CPU_ERR0_GTL_R_N")
	)
	(segment
		(start 374.173242 -41.424352)
		(end 374.173242 -40.662352)
		(width 0.10795)
		(layer "B.Cu")
		(net "H_CPU_ERR0_GTL_R_N")
	)
	(segment
		(start 373.436642 -39.874952)
		(end 373.38889 -39.8272)
		(width 0.10795)
		(layer "B.Cu")
		(net "H_CPU_ERR0_GTL_R_N")
	)
	(segment
		(start 371.875558 -40.163242)
		(end 371.875558 -40.617648)
		(width 0.10795)
		(layer "B.Cu")
		(net "H_CPU_ERR0_GTL_R_N")
	)
	(segment
		(start 373.436642 -39.874952)
		(end 373.436642 -40.112696)
		(width 0.10795)
		(layer "B.Cu")
		(net "H_CPU_ERR0_GTL_R_N")
	)
	(segment
		(start 372.5672 -39.8272)
		(end 372.2116 -39.8272)
		(width 0.10795)
		(layer "B.Cu")
		(net "H_CPU_ERR0_GTL_R_N")
	)
	(segment
		(start 371.875558 -41.506648)
		(end 371.875558 -40.617648)
		(width 0.10795)
		(layer "B.Cu")
		(net "H_CPU_ERR0_GTL_R_N")
	)
	(segment
		(start 373.38889 -39.8272)
		(end 372.5672 -39.8272)
		(width 0.10795)
		(layer "B.Cu")
		(net "H_CPU_ERR0_GTL_R_N")
	)
	(segment
		(start 373.986298 -40.662352)
		(end 374.173242 -40.662352)
		(width 0.10795)
		(layer "B.Cu")
		(net "H_CPU_ERR0_GTL_R_N")
	)
	(segment
		(start 373.436642 -40.112696)
		(end 373.986298 -40.662352)
		(width 0.10795)
		(layer "B.Cu")
		(net "H_CPU_ERR0_GTL_R_N")
	)
	(segment
		(start 414.528 -12.065)
		(end 414.528 -11.01344)
		(width 0.10795)
		(layer "F.Cu")
		(net "FP_NMI_BTN_OUT_R_N")
	)
	(segment
		(start 414.528 -11.01344)
		(end 414.118044 -10.603484)
		(width 0.10795)
		(layer "F.Cu")
		(net "FP_NMI_BTN_OUT_R_N")
	)
	(segment
		(start 414.118044 -10.603484)
		(end 414.118044 -10.527792)
		(width 0.10795)
		(layer "F.Cu")
		(net "FP_NMI_BTN_OUT_R_N")
	)
	(via
		(at 413.34182 -11.3792)
		(size 0.6604)
		(drill 0.3302)
		(layers "F.Cu" "B.Cu")
		(net "FP_NMI_BTN_OUT_R_N")
	)
	(via
		(at 414.118044 -10.527792)
		(size 0.508)
		(drill 0.254)
		(layers "F.Cu" "B.Cu")
		(net "FP_NMI_BTN_OUT_R_N")
	)
	(segment
		(start 412.1785 -11.000994)
		(end 412.57474 -11.000994)
		(width 0.10795)
		(layer "B.Cu")
		(net "FP_NMI_BTN_OUT_R_N")
	)
	(segment
		(start 414.118044 -11.027156)
		(end 414.118044 -10.527792)
		(width 0.10795)
		(layer "B.Cu")
		(net "FP_NMI_BTN_OUT_R_N")
	)
	(segment
		(start 412.1785 -11.000994)
		(end 412.1785 -11.7475)
		(width 0.10795)
		(layer "B.Cu")
		(net "FP_NMI_BTN_OUT_R_N")
	)
	(segment
		(start 412.1785 -11.7475)
		(end 412.048198 -11.877802)
		(width 0.10795)
		(layer "B.Cu")
		(net "FP_NMI_BTN_OUT_R_N")
	)
	(segment
		(start 413.34182 -11.3792)
		(end 413.766 -11.3792)
		(width 0.10795)
		(layer "B.Cu")
		(net "FP_NMI_BTN_OUT_R_N")
	)
	(segment
		(start 413.766 -11.3792)
		(end 414.118044 -11.027156)
		(width 0.10795)
		(layer "B.Cu")
		(net "FP_NMI_BTN_OUT_R_N")
	)
	(segment
		(start 412.952946 -11.3792)
		(end 413.34182 -11.3792)
		(width 0.10795)
		(layer "B.Cu")
		(net "FP_NMI_BTN_OUT_R_N")
	)
	(segment
		(start 412.048198 -11.877802)
		(end 411.791658 -11.877802)
		(width 0.10795)
		(layer "B.Cu")
		(net "FP_NMI_BTN_OUT_R_N")
	)
	(segment
		(start 412.57474 -11.000994)
		(end 412.952946 -11.3792)
		(width 0.10795)
		(layer "B.Cu")
		(net "FP_NMI_BTN_OUT_R_N")
	)
	(via
		(at 412.623 -12.92606)
		(size 0.6604)
		(drill 0.3302)
		(layers "F.Cu" "B.Cu")
		(net "FP_NMI_BTN_OUT_N")
	)
	(segment
		(start 410.902658 -11.877802)
		(end 410.902658 -12.33805)
		(width 0.10795)
		(layer "B.Cu")
		(net "FP_NMI_BTN_OUT_N")
	)
	(segment
		(start 412.623 -12.573)
		(end 412.623 -12.92606)
		(width 0.10795)
		(layer "B.Cu")
		(net "FP_NMI_BTN_OUT_N")
	)
	(segment
		(start 410.118052 -11.877802)
		(end 410.097986 -11.857736)
		(width 0.10795)
		(layer "B.Cu")
		(net "FP_NMI_BTN_OUT_N")
	)
	(segment
		(start 412.496 -12.446)
		(end 412.623 -12.573)
		(width 0.10795)
		(layer "B.Cu")
		(net "FP_NMI_BTN_OUT_N")
	)
	(segment
		(start 412.623 -12.92606)
		(end 412.623 -13.2842)
		(width 0.10795)
		(layer "B.Cu")
		(net "FP_NMI_BTN_OUT_N")
	)
	(segment
		(start 412.623 -13.2842)
		(end 412.46044 -13.44676)
		(width 0.10795)
		(layer "B.Cu")
		(net "FP_NMI_BTN_OUT_N")
	)
	(segment
		(start 412.46044 -13.44676)
		(end 411.3022 -13.44676)
		(width 0.10795)
		(layer "B.Cu")
		(net "FP_NMI_BTN_OUT_N")
	)
	(segment
		(start 410.902658 -11.877802)
		(end 410.118052 -11.877802)
		(width 0.10795)
		(layer "B.Cu")
		(net "FP_NMI_BTN_OUT_N")
	)
	(segment
		(start 411.010608 -12.446)
		(end 412.496 -12.446)
		(width 0.10795)
		(layer "B.Cu")
		(net "FP_NMI_BTN_OUT_N")
	)
	(segment
		(start 410.902658 -12.33805)
		(end 411.010608 -12.446)
		(width 0.10795)
		(layer "B.Cu")
		(net "FP_NMI_BTN_OUT_N")
	)
	(via
		(at 411.4165 -16.1671)
		(size 0.6604)
		(drill 0.3302)
		(layers "F.Cu" "B.Cu")
		(net "FP_NMI_BTN")
	)
	(segment
		(start 411.3022 -15.1638)
		(end 411.5943 -15.4559)
		(width 0.10795)
		(layer "B.Cu")
		(net "FP_NMI_BTN")
	)
	(segment
		(start 411.188154 -16.1671)
		(end 410.172408 -15.151354)
		(width 0.10795)
		(layer "B.Cu")
		(net "FP_NMI_BTN")
	)
	(segment
		(start 410.172408 -15.151354)
		(end 410.172408 -13.608304)
		(width 0.10795)
		(layer "B.Cu")
		(net "FP_NMI_BTN")
	)
	(segment
		(start 410.010864 -13.44676)
		(end 409.4226 -13.44676)
		(width 0.10795)
		(layer "B.Cu")
		(net "FP_NMI_BTN")
	)
	(segment
		(start 411.5943 -15.4559)
		(end 411.5943 -15.9893)
		(width 0.10795)
		(layer "B.Cu")
		(net "FP_NMI_BTN")
	)
	(segment
		(start 410.172408 -13.608304)
		(end 410.010864 -13.44676)
		(width 0.10795)
		(layer "B.Cu")
		(net "FP_NMI_BTN")
	)
	(segment
		(start 411.4165 -16.1671)
		(end 411.188154 -16.1671)
		(width 0.10795)
		(layer "B.Cu")
		(net "FP_NMI_BTN")
	)
	(segment
		(start 411.5943 -15.9893)
		(end 411.4165 -16.1671)
		(width 0.10795)
		(layer "B.Cu")
		(net "FP_NMI_BTN")
	)
	(segment
		(start 411.3022 -14.74724)
		(end 411.3022 -15.1638)
		(width 0.10795)
		(layer "B.Cu")
		(net "FP_NMI_BTN")
	)
	(segment
		(start 499.0084 -155.321)
		(end 499.872 -155.321)
		(width 0.10795)
		(layer "F.Cu")
		(net "FP_ID_LED_P5V_STBY_N")
	)
	(segment
		(start 498.6782 -155.6512)
		(end 499.0084 -155.321)
		(width 0.10795)
		(layer "F.Cu")
		(net "FP_ID_LED_P5V_STBY_N")
	)
	(via
		(at 498.6782 -155.6512)
		(size 0.508)
		(drill 0.254)
		(layers "F.Cu" "B.Cu")
		(net "FP_ID_LED_P5V_STBY_N")
	)
	(segment
		(start 497.6368 -155.6512)
		(end 498.6782 -155.6512)
		(width 0.10795)
		(layer "B.Cu")
		(net "FP_ID_LED_P5V_STBY_N")
	)
	(segment
		(start 491.121192 -152.146)
		(end 491.197392 -152.2222)
		(width 0.10795)
		(layer "B.Cu")
		(net "FP_ID_LED_P5V_STBY_N")
	)
	(segment
		(start 493.0648 -152.8318)
		(end 496.4938 -152.8318)
		(width 0.10795)
		(layer "B.Cu")
		(net "FP_ID_LED_P5V_STBY_N")
	)
	(segment
		(start 496.9002 -153.2382)
		(end 496.9002 -154.9146)
		(width 0.10795)
		(layer "B.Cu")
		(net "FP_ID_LED_P5V_STBY_N")
	)
	(segment
		(start 496.4938 -152.8318)
		(end 496.9002 -153.2382)
		(width 0.10795)
		(layer "B.Cu")
		(net "FP_ID_LED_P5V_STBY_N")
	)
	(segment
		(start 492.4552 -152.2222)
		(end 493.0648 -152.8318)
		(width 0.10795)
		(layer "B.Cu")
		(net "FP_ID_LED_P5V_STBY_N")
	)
	(segment
		(start 496.9002 -154.9146)
		(end 497.6368 -155.6512)
		(width 0.10795)
		(layer "B.Cu")
		(net "FP_ID_LED_P5V_STBY_N")
	)
	(segment
		(start 490.488986 -152.146)
		(end 491.121192 -152.146)
		(width 0.10795)
		(layer "B.Cu")
		(net "FP_ID_LED_P5V_STBY_N")
	)
	(segment
		(start 491.197392 -152.2222)
		(end 492.4552 -152.2222)
		(width 0.10795)
		(layer "B.Cu")
		(net "FP_ID_LED_P5V_STBY_N")
	)
	(segment
		(start 414.526984 -53.707792)
		(end 414.059116 -53.707792)
		(width 0.10795)
		(layer "F.Cu")
		(net "FM_BIOS_TOP_SWAP_SPKR_R")
	)
	(segment
		(start 415.260028 -54.440836)
		(end 414.526984 -53.707792)
		(width 0.10795)
		(layer "F.Cu")
		(net "FM_BIOS_TOP_SWAP_SPKR_R")
	)
	(segment
		(start 415.260028 -55.118)
		(end 415.260028 -54.440836)
		(width 0.10795)
		(layer "F.Cu")
		(net "FM_BIOS_TOP_SWAP_SPKR_R")
	)
	(segment
		(start 414.059116 -53.707792)
		(end 414.059116 -52.869592)
		(width 0.10795)
		(layer "F.Cu")
		(net "FM_BIOS_TOP_SWAP_SPKR_R")
	)
	(via
		(at 414.059116 -52.869592)
		(size 0.762)
		(drill 0.381)
		(layers "F.Cu" "B.Cu")
		(net "FM_BIOS_TOP_SWAP_SPKR_R")
	)
	(segment
		(start 414.362138 -57.071514)
		(end 414.362138 -54.899814)
		(width 0.10795)
		(layer "F.Cu")
		(net "FM_BIOS_TOP_SWAP_SPKR")
	)
	(segment
		(start 414.362138 -54.899814)
		(end 414.059116 -54.596792)
		(width 0.10795)
		(layer "F.Cu")
		(net "FM_BIOS_TOP_SWAP_SPKR")
	)
	(segment
		(start 489.204 -138.00455)
		(end 489.204 -137.16)
		(width 0.10795)
		(layer "F.Cu")
		(net "FM_BIOS_TOP_SWAP_SPKR")
	)
	(segment
		(start 489.09605 -138.1125)
		(end 489.204 -138.00455)
		(width 0.10795)
		(layer "F.Cu")
		(net "FM_BIOS_TOP_SWAP_SPKR")
	)
	(segment
		(start 395.66215 -98.69424)
		(end 396.15745 -98.464116)
		(width 0.10795)
		(layer "F.Cu")
		(net "FM_BIOS_TOP_SWAP_SPKR")
	)
	(segment
		(start 488.188 -138.1125)
		(end 489.09605 -138.1125)
		(width 0.10795)
		(layer "F.Cu")
		(net "FM_BIOS_TOP_SWAP_SPKR")
	)
	(segment
		(start 414.560512 -57.269888)
		(end 414.362138 -57.071514)
		(width 0.10795)
		(layer "F.Cu")
		(net "FM_BIOS_TOP_SWAP_SPKR")
	)
	(via
		(at 401.9804 -98.8822)
		(size 0.508)
		(drill 0.254)
		(layers "F.Cu" "B.Cu")
		(net "FM_BIOS_TOP_SWAP_SPKR")
	)
	(via
		(at 488.188 -138.1125)
		(size 0.508)
		(drill 0.254)
		(layers "F.Cu" "B.Cu")
		(net "FM_BIOS_TOP_SWAP_SPKR")
	)
	(via
		(at 396.15745 -98.464116)
		(size 0.508)
		(drill 0.254)
		(layers "F.Cu" "B.Cu")
		(net "FM_BIOS_TOP_SWAP_SPKR")
	)
	(via
		(at 414.560512 -57.269888)
		(size 0.508)
		(drill 0.254)
		(layers "F.Cu" "B.Cu")
		(net "FM_BIOS_TOP_SWAP_SPKR")
	)
	(segment
		(start 408.328622 -119.76227)
		(end 408.328622 -120.987058)
		(width 0.089408)
		(layer "In2.Cu")
		(net "FM_BIOS_TOP_SWAP_SPKR")
	)
	(segment
		(start 401.9804 -98.8822)
		(end 401.53082 -99.33178)
		(width 0.089408)
		(layer "In2.Cu")
		(net "FM_BIOS_TOP_SWAP_SPKR")
	)
	(segment
		(start 403.601936 -105.9942)
		(end 405.340312 -107.732576)
		(width 0.089408)
		(layer "In2.Cu")
		(net "FM_BIOS_TOP_SWAP_SPKR")
	)
	(segment
		(start 427.932342 -121.29008)
		(end 428.201328 -121.021094)
		(width 0.089408)
		(layer "In2.Cu")
		(net "FM_BIOS_TOP_SWAP_SPKR")
	)
	(segment
		(start 475.4372 -121.4374)
		(end 476.8596 -122.8598)
		(width 0.089408)
		(layer "In2.Cu")
		(net "FM_BIOS_TOP_SWAP_SPKR")
	)
	(segment
		(start 411.869636 -122.104912)
		(end 416.881056 -122.104912)
		(width 0.089408)
		(layer "In2.Cu")
		(net "FM_BIOS_TOP_SWAP_SPKR")
	)
	(segment
		(start 486.611422 -139.689078)
		(end 488.188 -138.1125)
		(width 0.089408)
		(layer "In2.Cu")
		(net "FM_BIOS_TOP_SWAP_SPKR")
	)
	(segment
		(start 405.340312 -107.732576)
		(end 405.340312 -111.422688)
		(width 0.089408)
		(layer "In2.Cu")
		(net "FM_BIOS_TOP_SWAP_SPKR")
	)
	(segment
		(start 402.9456 -105.9942)
		(end 403.601936 -105.9942)
		(width 0.089408)
		(layer "In2.Cu")
		(net "FM_BIOS_TOP_SWAP_SPKR")
	)
	(segment
		(start 408.328622 -120.987058)
		(end 410.017468 -122.675904)
		(width 0.089408)
		(layer "In2.Cu")
		(net "FM_BIOS_TOP_SWAP_SPKR")
	)
	(segment
		(start 428.201328 -121.021094)
		(end 434.335936 -121.021094)
		(width 0.089408)
		(layer "In2.Cu")
		(net "FM_BIOS_TOP_SWAP_SPKR")
	)
	(segment
		(start 401.041108 -104.32542)
		(end 402.171916 -105.456228)
		(width 0.089408)
		(layer "In2.Cu")
		(net "FM_BIOS_TOP_SWAP_SPKR")
	)
	(segment
		(start 480.797362 -136.002776)
		(end 484.483664 -139.689078)
		(width 0.089408)
		(layer "In2.Cu")
		(net "FM_BIOS_TOP_SWAP_SPKR")
	)
	(segment
		(start 477.945958 -126.76505)
		(end 477.945958 -133.013704)
		(width 0.089408)
		(layer "In2.Cu")
		(net "FM_BIOS_TOP_SWAP_SPKR")
	)
	(segment
		(start 470.281 -119.5578)
		(end 472.1606 -121.4374)
		(width 0.089408)
		(layer "In2.Cu")
		(net "FM_BIOS_TOP_SWAP_SPKR")
	)
	(segment
		(start 401.53082 -99.33178)
		(end 401.53082 -99.694492)
		(width 0.089408)
		(layer "In2.Cu")
		(net "FM_BIOS_TOP_SWAP_SPKR")
	)
	(segment
		(start 404.4696 -112.2934)
		(end 404.0505 -112.2934)
		(width 0.089408)
		(layer "In2.Cu")
		(net "FM_BIOS_TOP_SWAP_SPKR")
	)
	(segment
		(start 405.340312 -111.422688)
		(end 404.4696 -112.2934)
		(width 0.089408)
		(layer "In2.Cu")
		(net "FM_BIOS_TOP_SWAP_SPKR")
	)
	(segment
		(start 465.776818 -119.5578)
		(end 470.281 -119.5578)
		(width 0.089408)
		(layer "In2.Cu")
		(net "FM_BIOS_TOP_SWAP_SPKR")
	)
	(segment
		(start 404.037038 -113.506504)
		(end 404.273512 -113.506504)
		(width 0.089408)
		(layer "In2.Cu")
		(net "FM_BIOS_TOP_SWAP_SPKR")
	)
	(segment
		(start 464.246976 -118.027958)
		(end 465.776818 -119.5578)
		(width 0.089408)
		(layer "In2.Cu")
		(net "FM_BIOS_TOP_SWAP_SPKR")
	)
	(segment
		(start 480.35464 -134.50951)
		(end 480.797362 -134.952232)
		(width 0.089408)
		(layer "In2.Cu")
		(net "FM_BIOS_TOP_SWAP_SPKR")
	)
	(segment
		(start 411.298644 -122.675904)
		(end 411.869636 -122.104912)
		(width 0.089408)
		(layer "In2.Cu")
		(net "FM_BIOS_TOP_SWAP_SPKR")
	)
	(segment
		(start 419.847522 -121.5136)
		(end 423.350944 -121.5136)
		(width 0.089408)
		(layer "In2.Cu")
		(net "FM_BIOS_TOP_SWAP_SPKR")
	)
	(segment
		(start 477.945958 -133.013704)
		(end 479.441764 -134.50951)
		(width 0.089408)
		(layer "In2.Cu")
		(net "FM_BIOS_TOP_SWAP_SPKR")
	)
	(segment
		(start 403.802596 -113.272062)
		(end 404.037038 -113.506504)
		(width 0.089408)
		(layer "In2.Cu")
		(net "FM_BIOS_TOP_SWAP_SPKR")
	)
	(segment
		(start 416.881056 -122.104912)
		(end 417.904168 -121.0818)
		(width 0.089408)
		(layer "In2.Cu")
		(net "FM_BIOS_TOP_SWAP_SPKR")
	)
	(segment
		(start 480.797362 -134.952232)
		(end 480.797362 -136.002776)
		(width 0.089408)
		(layer "In2.Cu")
		(net "FM_BIOS_TOP_SWAP_SPKR")
	)
	(segment
		(start 419.415722 -121.0818)
		(end 419.847522 -121.5136)
		(width 0.089408)
		(layer "In2.Cu")
		(net "FM_BIOS_TOP_SWAP_SPKR")
	)
	(segment
		(start 404.0505 -112.2934)
		(end 403.802596 -112.541304)
		(width 0.089408)
		(layer "In2.Cu")
		(net "FM_BIOS_TOP_SWAP_SPKR")
	)
	(segment
		(start 423.350944 -121.5136)
		(end 423.574464 -121.29008)
		(width 0.089408)
		(layer "In2.Cu")
		(net "FM_BIOS_TOP_SWAP_SPKR")
	)
	(segment
		(start 405.9174 -115.150392)
		(end 405.9174 -117.351048)
		(width 0.089408)
		(layer "In2.Cu")
		(net "FM_BIOS_TOP_SWAP_SPKR")
	)
	(segment
		(start 476.8596 -125.678692)
		(end 477.945958 -126.76505)
		(width 0.089408)
		(layer "In2.Cu")
		(net "FM_BIOS_TOP_SWAP_SPKR")
	)
	(segment
		(start 476.8596 -122.8598)
		(end 476.8596 -125.678692)
		(width 0.089408)
		(layer "In2.Cu")
		(net "FM_BIOS_TOP_SWAP_SPKR")
	)
	(segment
		(start 423.574464 -121.29008)
		(end 427.932342 -121.29008)
		(width 0.089408)
		(layer "In2.Cu")
		(net "FM_BIOS_TOP_SWAP_SPKR")
	)
	(segment
		(start 404.273512 -113.506504)
		(end 405.9174 -115.150392)
		(width 0.089408)
		(layer "In2.Cu")
		(net "FM_BIOS_TOP_SWAP_SPKR")
	)
	(segment
		(start 401.041108 -100.184204)
		(end 401.041108 -104.32542)
		(width 0.089408)
		(layer "In2.Cu")
		(net "FM_BIOS_TOP_SWAP_SPKR")
	)
	(segment
		(start 479.441764 -134.50951)
		(end 480.35464 -134.50951)
		(width 0.089408)
		(layer "In2.Cu")
		(net "FM_BIOS_TOP_SWAP_SPKR")
	)
	(segment
		(start 437.329072 -118.027958)
		(end 464.246976 -118.027958)
		(width 0.089408)
		(layer "In2.Cu")
		(net "FM_BIOS_TOP_SWAP_SPKR")
	)
	(segment
		(start 484.483664 -139.689078)
		(end 486.611422 -139.689078)
		(width 0.089408)
		(layer "In2.Cu")
		(net "FM_BIOS_TOP_SWAP_SPKR")
	)
	(segment
		(start 402.407628 -105.456228)
		(end 402.9456 -105.9942)
		(width 0.089408)
		(layer "In2.Cu")
		(net "FM_BIOS_TOP_SWAP_SPKR")
	)
	(segment
		(start 405.9174 -117.351048)
		(end 408.328622 -119.76227)
		(width 0.089408)
		(layer "In2.Cu")
		(net "FM_BIOS_TOP_SWAP_SPKR")
	)
	(segment
		(start 434.335936 -121.021094)
		(end 437.329072 -118.027958)
		(width 0.089408)
		(layer "In2.Cu")
		(net "FM_BIOS_TOP_SWAP_SPKR")
	)
	(segment
		(start 401.53082 -99.694492)
		(end 401.041108 -100.184204)
		(width 0.089408)
		(layer "In2.Cu")
		(net "FM_BIOS_TOP_SWAP_SPKR")
	)
	(segment
		(start 410.017468 -122.675904)
		(end 411.298644 -122.675904)
		(width 0.089408)
		(layer "In2.Cu")
		(net "FM_BIOS_TOP_SWAP_SPKR")
	)
	(segment
		(start 472.1606 -121.4374)
		(end 475.4372 -121.4374)
		(width 0.089408)
		(layer "In2.Cu")
		(net "FM_BIOS_TOP_SWAP_SPKR")
	)
	(segment
		(start 417.904168 -121.0818)
		(end 419.415722 -121.0818)
		(width 0.089408)
		(layer "In2.Cu")
		(net "FM_BIOS_TOP_SWAP_SPKR")
	)
	(segment
		(start 403.802596 -112.541304)
		(end 403.802596 -113.272062)
		(width 0.089408)
		(layer "In2.Cu")
		(net "FM_BIOS_TOP_SWAP_SPKR")
	)
	(segment
		(start 402.171916 -105.456228)
		(end 402.407628 -105.456228)
		(width 0.089408)
		(layer "In2.Cu")
		(net "FM_BIOS_TOP_SWAP_SPKR")
	)
	(segment
		(start 396.575534 -98.8822)
		(end 401.9804 -98.8822)
		(width 0.089408)
		(layer "In4.Cu")
		(net "FM_BIOS_TOP_SWAP_SPKR")
	)
	(segment
		(start 396.15745 -98.464116)
		(end 396.575534 -98.8822)
		(width 0.089408)
		(layer "In4.Cu")
		(net "FM_BIOS_TOP_SWAP_SPKR")
	)
	(segment
		(start 396.55623 -96.35617)
		(end 396.25397 -96.05391)
		(width 0.089408)
		(layer "In9.Cu")
		(net "FM_BIOS_TOP_SWAP_SPKR")
	)
	(segment
		(start 397.247618 -94.729554)
		(end 398.798034 -94.729554)
		(width 0.089408)
		(layer "In9.Cu")
		(net "FM_BIOS_TOP_SWAP_SPKR")
	)
	(segment
		(start 413.434784 -65.652904)
		(end 413.669226 -65.418462)
		(width 0.089408)
		(layer "In9.Cu")
		(net "FM_BIOS_TOP_SWAP_SPKR")
	)
	(segment
		(start 398.798034 -94.729554)
		(end 401.396962 -92.130626)
		(width 0.089408)
		(layer "In9.Cu")
		(net "FM_BIOS_TOP_SWAP_SPKR")
	)
	(segment
		(start 405.765508 -78.400148)
		(end 405.765508 -75.367388)
		(width 0.089408)
		(layer "In9.Cu")
		(net "FM_BIOS_TOP_SWAP_SPKR")
	)
	(segment
		(start 414.48228 -60.623196)
		(end 414.33496 -60.475876)
		(width 0.089408)
		(layer "In9.Cu")
		(net "FM_BIOS_TOP_SWAP_SPKR")
	)
	(segment
		(start 412.902908 -66.273934)
		(end 412.902654 -66.27368)
		(width 0.089408)
		(layer "In9.Cu")
		(net "FM_BIOS_TOP_SWAP_SPKR")
	)
	(segment
		(start 412.902654 -65.941956)
		(end 412.902908 -65.941702)
		(width 0.089408)
		(layer "In9.Cu")
		(net "FM_BIOS_TOP_SWAP_SPKR")
	)
	(segment
		(start 412.902654 -66.27368)
		(end 412.902654 -65.941956)
		(width 0.089408)
		(layer "In9.Cu")
		(net "FM_BIOS_TOP_SWAP_SPKR")
	)
	(segment
		(start 413.165798 -65.652904)
		(end 413.434784 -65.652904)
		(width 0.089408)
		(layer "In9.Cu")
		(net "FM_BIOS_TOP_SWAP_SPKR")
	)
	(segment
		(start 414.33496 -62.634114)
		(end 414.33496 -61.545216)
		(width 0.089408)
		(layer "In9.Cu")
		(net "FM_BIOS_TOP_SWAP_SPKR")
	)
	(segment
		(start 401.396962 -90.295984)
		(end 406.268428 -85.424518)
		(width 0.089408)
		(layer "In9.Cu")
		(net "FM_BIOS_TOP_SWAP_SPKR")
	)
	(segment
		(start 405.765508 -75.367388)
		(end 410.310838 -70.822058)
		(width 0.089408)
		(layer "In9.Cu")
		(net "FM_BIOS_TOP_SWAP_SPKR")
	)
	(segment
		(start 410.949902 -70.822058)
		(end 411.864556 -69.907404)
		(width 0.089408)
		(layer "In9.Cu")
		(net "FM_BIOS_TOP_SWAP_SPKR")
	)
	(segment
		(start 396.25397 -98.367596)
		(end 396.25397 -97.440242)
		(width 0.089408)
		(layer "In9.Cu")
		(net "FM_BIOS_TOP_SWAP_SPKR")
	)
	(segment
		(start 412.472886 -68.30314)
		(end 412.472886 -66.911728)
		(width 0.089408)
		(layer "In9.Cu")
		(net "FM_BIOS_TOP_SWAP_SPKR")
	)
	(segment
		(start 414.33496 -61.545216)
		(end 414.48228 -61.397896)
		(width 0.089408)
		(layer "In9.Cu")
		(net "FM_BIOS_TOP_SWAP_SPKR")
	)
	(segment
		(start 396.25397 -96.05391)
		(end 396.25397 -95.723202)
		(width 0.089408)
		(layer "In9.Cu")
		(net "FM_BIOS_TOP_SWAP_SPKR")
	)
	(segment
		(start 412.902654 -66.420746)
		(end 412.902908 -66.420492)
		(width 0.089408)
		(layer "In9.Cu")
		(net "FM_BIOS_TOP_SWAP_SPKR")
	)
	(segment
		(start 412.472886 -66.911728)
		(end 412.902654 -66.48196)
		(width 0.089408)
		(layer "In9.Cu")
		(net "FM_BIOS_TOP_SWAP_SPKR")
	)
	(segment
		(start 396.25397 -95.723202)
		(end 397.247618 -94.729554)
		(width 0.089408)
		(layer "In9.Cu")
		(net "FM_BIOS_TOP_SWAP_SPKR")
	)
	(segment
		(start 401.396962 -92.130626)
		(end 401.396962 -90.295984)
		(width 0.089408)
		(layer "In9.Cu")
		(net "FM_BIOS_TOP_SWAP_SPKR")
	)
	(segment
		(start 414.48228 -61.397896)
		(end 414.48228 -60.623196)
		(width 0.089408)
		(layer "In9.Cu")
		(net "FM_BIOS_TOP_SWAP_SPKR")
	)
	(segment
		(start 412.902654 -66.48196)
		(end 412.902654 -66.420746)
		(width 0.089408)
		(layer "In9.Cu")
		(net "FM_BIOS_TOP_SWAP_SPKR")
	)
	(segment
		(start 396.25397 -97.440242)
		(end 396.55623 -97.137982)
		(width 0.089408)
		(layer "In9.Cu")
		(net "FM_BIOS_TOP_SWAP_SPKR")
	)
	(segment
		(start 413.669226 -63.299848)
		(end 414.33496 -62.634114)
		(width 0.089408)
		(layer "In9.Cu")
		(net "FM_BIOS_TOP_SWAP_SPKR")
	)
	(segment
		(start 406.268428 -85.424518)
		(end 406.268428 -78.903068)
		(width 0.089408)
		(layer "In9.Cu")
		(net "FM_BIOS_TOP_SWAP_SPKR")
	)
	(segment
		(start 412.902908 -65.941702)
		(end 412.902908 -65.915794)
		(width 0.089408)
		(layer "In9.Cu")
		(net "FM_BIOS_TOP_SWAP_SPKR")
	)
	(segment
		(start 414.33496 -57.49544)
		(end 414.560512 -57.269888)
		(width 0.089408)
		(layer "In9.Cu")
		(net "FM_BIOS_TOP_SWAP_SPKR")
	)
	(segment
		(start 412.902908 -66.420492)
		(end 412.902908 -66.273934)
		(width 0.089408)
		(layer "In9.Cu")
		(net "FM_BIOS_TOP_SWAP_SPKR")
	)
	(segment
		(start 410.310838 -70.822058)
		(end 410.949902 -70.822058)
		(width 0.089408)
		(layer "In9.Cu")
		(net "FM_BIOS_TOP_SWAP_SPKR")
	)
	(segment
		(start 396.55623 -97.137982)
		(end 396.55623 -96.35617)
		(width 0.089408)
		(layer "In9.Cu")
		(net "FM_BIOS_TOP_SWAP_SPKR")
	)
	(segment
		(start 396.15745 -98.464116)
		(end 396.25397 -98.367596)
		(width 0.089408)
		(layer "In9.Cu")
		(net "FM_BIOS_TOP_SWAP_SPKR")
	)
	(segment
		(start 406.268428 -78.903068)
		(end 405.765508 -78.400148)
		(width 0.089408)
		(layer "In9.Cu")
		(net "FM_BIOS_TOP_SWAP_SPKR")
	)
	(segment
		(start 414.33496 -60.475876)
		(end 414.33496 -57.49544)
		(width 0.089408)
		(layer "In9.Cu")
		(net "FM_BIOS_TOP_SWAP_SPKR")
	)
	(segment
		(start 411.864556 -69.907404)
		(end 411.864556 -68.91147)
		(width 0.089408)
		(layer "In9.Cu")
		(net "FM_BIOS_TOP_SWAP_SPKR")
	)
	(segment
		(start 411.864556 -68.91147)
		(end 412.472886 -68.30314)
		(width 0.089408)
		(layer "In9.Cu")
		(net "FM_BIOS_TOP_SWAP_SPKR")
	)
	(segment
		(start 413.669226 -65.418462)
		(end 413.669226 -63.299848)
		(width 0.089408)
		(layer "In9.Cu")
		(net "FM_BIOS_TOP_SWAP_SPKR")
	)
	(segment
		(start 412.902908 -65.915794)
		(end 413.165798 -65.652904)
		(width 0.089408)
		(layer "In9.Cu")
		(net "FM_BIOS_TOP_SWAP_SPKR")
	)
	(segment
		(start 420.323772 -26.90114)
		(end 420.323772 -25.343612)
		(width 0.10795)
		(layer "F.Cu")
		(net "FM_BIOS_TOP_SWAP")
	)
	(segment
		(start 422.5798 -22.3012)
		(end 422.871392 -22.3012)
		(width 0.10795)
		(layer "F.Cu")
		(net "FM_BIOS_TOP_SWAP")
	)
	(segment
		(start 417.7919 -58.62828)
		(end 417.7919 -58.801)
		(width 0.10795)
		(layer "F.Cu")
		(net "FM_BIOS_TOP_SWAP")
	)
	(segment
		(start 422.871392 -22.3012)
		(end 423.328592 -21.844)
		(width 0.10795)
		(layer "F.Cu")
		(net "FM_BIOS_TOP_SWAP")
	)
	(segment
		(start 422.5798 -23.601426)
		(end 422.5798 -22.3012)
		(width 0.10795)
		(layer "F.Cu")
		(net "FM_BIOS_TOP_SWAP")
	)
	(segment
		(start 419.890194 -27.334718)
		(end 420.323772 -26.90114)
		(width 0.10795)
		(layer "F.Cu")
		(net "FM_BIOS_TOP_SWAP")
	)
	(segment
		(start 389.22325 -99.55276)
		(end 389.71855 -99.322636)
		(width 0.10795)
		(layer "F.Cu")
		(net "FM_BIOS_TOP_SWAP")
	)
	(segment
		(start 416.94862 -57.785)
		(end 417.7919 -58.62828)
		(width 0.10795)
		(layer "F.Cu")
		(net "FM_BIOS_TOP_SWAP")
	)
	(segment
		(start 415.910014 -54.13756)
		(end 414.655 -52.882546)
		(width 0.10795)
		(layer "F.Cu")
		(net "FM_BIOS_TOP_SWAP")
	)
	(segment
		(start 421.057832 -24.609552)
		(end 421.571674 -24.609552)
		(width 0.10795)
		(layer "F.Cu")
		(net "FM_BIOS_TOP_SWAP")
	)
	(segment
		(start 414.655 -52.882546)
		(end 414.655 -50.812954)
		(width 0.10795)
		(layer "F.Cu")
		(net "FM_BIOS_TOP_SWAP")
	)
	(segment
		(start 416.052 -57.785)
		(end 416.94862 -57.785)
		(width 0.10795)
		(layer "F.Cu")
		(net "FM_BIOS_TOP_SWAP")
	)
	(segment
		(start 415.910014 -56.896)
		(end 415.910014 -57.643014)
		(width 0.10795)
		(layer "F.Cu")
		(net "FM_BIOS_TOP_SWAP")
	)
	(segment
		(start 415.910014 -57.643014)
		(end 416.052 -57.785)
		(width 0.10795)
		(layer "F.Cu")
		(net "FM_BIOS_TOP_SWAP")
	)
	(segment
		(start 420.323772 -25.343612)
		(end 421.057832 -24.609552)
		(width 0.10795)
		(layer "F.Cu")
		(net "FM_BIOS_TOP_SWAP")
	)
	(segment
		(start 421.571674 -24.609552)
		(end 422.5798 -23.601426)
		(width 0.10795)
		(layer "F.Cu")
		(net "FM_BIOS_TOP_SWAP")
	)
	(segment
		(start 424.1292 -21.5392)
		(end 424.942 -20.7264)
		(width 0.10795)
		(layer "F.Cu")
		(net "FM_BIOS_TOP_SWAP")
	)
	(segment
		(start 415.053526 -50.414428)
		(end 415.053526 -50.153316)
		(width 0.10795)
		(layer "F.Cu")
		(net "FM_BIOS_TOP_SWAP")
	)
	(segment
		(start 423.8244 -21.844)
		(end 424.1292 -21.5392)
		(width 0.10795)
		(layer "F.Cu")
		(net "FM_BIOS_TOP_SWAP")
	)
	(segment
		(start 423.328592 -21.844)
		(end 423.8244 -21.844)
		(width 0.10795)
		(layer "F.Cu")
		(net "FM_BIOS_TOP_SWAP")
	)
	(segment
		(start 415.910014 -56.896)
		(end 415.910014 -54.13756)
		(width 0.10795)
		(layer "F.Cu")
		(net "FM_BIOS_TOP_SWAP")
	)
	(segment
		(start 414.655 -50.812954)
		(end 415.053526 -50.414428)
		(width 0.10795)
		(layer "F.Cu")
		(net "FM_BIOS_TOP_SWAP")
	)
	(via
		(at 469.652858 -8.744204)
		(size 0.508)
		(drill 0.254)
		(layers "F.Cu" "B.Cu")
		(net "FM_BIOS_TOP_SWAP")
	)
	(via
		(at 424.1292 -21.5392)
		(size 0.762)
		(drill 0.381)
		(layers "F.Cu" "B.Cu")
		(net "FM_BIOS_TOP_SWAP")
	)
	(via
		(at 389.71855 -99.322636)
		(size 0.508)
		(drill 0.254)
		(layers "F.Cu" "B.Cu")
		(net "FM_BIOS_TOP_SWAP")
	)
	(via
		(at 415.053526 -50.153316)
		(size 0.508)
		(drill 0.254)
		(layers "F.Cu" "B.Cu")
		(net "FM_BIOS_TOP_SWAP")
	)
	(via
		(at 459.80223 -26.543)
		(size 0.508)
		(drill 0.254)
		(layers "F.Cu" "B.Cu")
		(net "FM_BIOS_TOP_SWAP")
	)
	(via
		(at 424.942 -20.7264)
		(size 0.508)
		(drill 0.254)
		(layers "F.Cu" "B.Cu")
		(net "FM_BIOS_TOP_SWAP")
	)
	(segment
		(start 404.9522 3.3782)
		(end 403.561296 4.769104)
		(width 0.089408)
		(layer "In2.Cu")
		(net "FM_BIOS_TOP_SWAP")
	)
	(segment
		(start 409.5242 3.3782)
		(end 404.9522 3.3782)
		(width 0.089408)
		(layer "In2.Cu")
		(net "FM_BIOS_TOP_SWAP")
	)
	(segment
		(start 464.832192 0.22987)
		(end 464.832192 1.01727)
		(width 0.089408)
		(layer "In2.Cu")
		(net "FM_BIOS_TOP_SWAP")
	)
	(segment
		(start 469.652858 -8.744204)
		(end 469.055196 -8.146542)
		(width 0.089408)
		(layer "In2.Cu")
		(net "FM_BIOS_TOP_SWAP")
	)
	(segment
		(start 410.658056 4.512056)
		(end 409.5242 3.3782)
		(width 0.089408)
		(layer "In2.Cu")
		(net "FM_BIOS_TOP_SWAP")
	)
	(segment
		(start 469.055196 -8.146542)
		(end 469.029542 -8.146542)
		(width 0.089408)
		(layer "In2.Cu")
		(net "FM_BIOS_TOP_SWAP")
	)
	(segment
		(start 399.104104 4.769104)
		(end 398.7546 4.4196)
		(width 0.089408)
		(layer "In2.Cu")
		(net "FM_BIOS_TOP_SWAP")
	)
	(segment
		(start 465.956904 -3.167126)
		(end 465.956904 -2.450338)
		(width 0.089408)
		(layer "In2.Cu")
		(net "FM_BIOS_TOP_SWAP")
	)
	(segment
		(start 468.187024 -5.397246)
		(end 465.956904 -3.167126)
		(width 0.089408)
		(layer "In2.Cu")
		(net "FM_BIOS_TOP_SWAP")
	)
	(segment
		(start 403.561296 4.769104)
		(end 399.104104 4.769104)
		(width 0.089408)
		(layer "In2.Cu")
		(net "FM_BIOS_TOP_SWAP")
	)
	(segment
		(start 425.780708 1.164336)
		(end 422.594532 1.164336)
		(width 0.089408)
		(layer "In2.Cu")
		(net "FM_BIOS_TOP_SWAP")
	)
	(segment
		(start 398.7546 1.8034)
		(end 397.960088 1.008888)
		(width 0.089408)
		(layer "In2.Cu")
		(net "FM_BIOS_TOP_SWAP")
	)
	(segment
		(start 419.246812 4.512056)
		(end 410.658056 4.512056)
		(width 0.089408)
		(layer "In2.Cu")
		(net "FM_BIOS_TOP_SWAP")
	)
	(segment
		(start 468.187024 -7.304024)
		(end 468.187024 -5.397246)
		(width 0.089408)
		(layer "In2.Cu")
		(net "FM_BIOS_TOP_SWAP")
	)
	(segment
		(start 397.960088 1.008888)
		(end 382.059688 1.008888)
		(width 0.089408)
		(layer "In2.Cu")
		(net "FM_BIOS_TOP_SWAP")
	)
	(segment
		(start 465.956904 -2.450338)
		(end 465.201 -1.694434)
		(width 0.089408)
		(layer "In2.Cu")
		(net "FM_BIOS_TOP_SWAP")
	)
	(segment
		(start 377.387104 0.310896)
		(end 376.428 1.27)
		(width 0.089408)
		(layer "In2.Cu")
		(net "FM_BIOS_TOP_SWAP")
	)
	(segment
		(start 427.156372 2.54)
		(end 425.780708 1.164336)
		(width 0.089408)
		(layer "In2.Cu")
		(net "FM_BIOS_TOP_SWAP")
	)
	(segment
		(start 469.029542 -8.146542)
		(end 468.187024 -7.304024)
		(width 0.089408)
		(layer "In2.Cu")
		(net "FM_BIOS_TOP_SWAP")
	)
	(segment
		(start 422.594532 1.164336)
		(end 419.246812 4.512056)
		(width 0.089408)
		(layer "In2.Cu")
		(net "FM_BIOS_TOP_SWAP")
	)
	(segment
		(start 465.201 -1.694434)
		(end 465.201 -0.138938)
		(width 0.089408)
		(layer "In2.Cu")
		(net "FM_BIOS_TOP_SWAP")
	)
	(segment
		(start 382.059688 1.008888)
		(end 381.361696 0.310896)
		(width 0.089408)
		(layer "In2.Cu")
		(net "FM_BIOS_TOP_SWAP")
	)
	(segment
		(start 465.201 -0.138938)
		(end 464.832192 0.22987)
		(width 0.089408)
		(layer "In2.Cu")
		(net "FM_BIOS_TOP_SWAP")
	)
	(segment
		(start 463.309462 2.54)
		(end 427.156372 2.54)
		(width 0.089408)
		(layer "In2.Cu")
		(net "FM_BIOS_TOP_SWAP")
	)
	(segment
		(start 464.832192 1.01727)
		(end 463.309462 2.54)
		(width 0.089408)
		(layer "In2.Cu")
		(net "FM_BIOS_TOP_SWAP")
	)
	(segment
		(start 381.361696 0.310896)
		(end 377.387104 0.310896)
		(width 0.089408)
		(layer "In2.Cu")
		(net "FM_BIOS_TOP_SWAP")
	)
	(segment
		(start 398.7546 4.4196)
		(end 398.7546 1.8034)
		(width 0.089408)
		(layer "In2.Cu")
		(net "FM_BIOS_TOP_SWAP")
	)
	(segment
		(start 427.85792 -22.286976)
		(end 426.753528 -21.182584)
		(width 0.089408)
		(layer "In4.Cu")
		(net "FM_BIOS_TOP_SWAP")
	)
	(segment
		(start 431.232818 -22.286976)
		(end 427.85792 -22.286976)
		(width 0.089408)
		(layer "In4.Cu")
		(net "FM_BIOS_TOP_SWAP")
	)
	(segment
		(start 448.2592 -19.836384)
		(end 446.450974 -19.836384)
		(width 0.089408)
		(layer "In4.Cu")
		(net "FM_BIOS_TOP_SWAP")
	)
	(segment
		(start 459.39583 -26.9494)
		(end 453.955912 -26.9494)
		(width 0.089408)
		(layer "In4.Cu")
		(net "FM_BIOS_TOP_SWAP")
	)
	(segment
		(start 446.450974 -19.836384)
		(end 445.559942 -18.945352)
		(width 0.089408)
		(layer "In4.Cu")
		(net "FM_BIOS_TOP_SWAP")
	)
	(segment
		(start 448.259454 -19.83613)
		(end 448.2592 -19.836384)
		(width 0.089408)
		(layer "In4.Cu")
		(net "FM_BIOS_TOP_SWAP")
	)
	(segment
		(start 433.39131 -20.128484)
		(end 431.232818 -22.286976)
		(width 0.089408)
		(layer "In4.Cu")
		(net "FM_BIOS_TOP_SWAP")
	)
	(segment
		(start 426.753528 -21.182584)
		(end 425.398184 -21.182584)
		(width 0.089408)
		(layer "In4.Cu")
		(net "FM_BIOS_TOP_SWAP")
	)
	(segment
		(start 449.4276 -20.846288)
		(end 448.417442 -19.83613)
		(width 0.089408)
		(layer "In4.Cu")
		(net "FM_BIOS_TOP_SWAP")
	)
	(segment
		(start 440.793886 -18.945352)
		(end 439.610754 -20.128484)
		(width 0.089408)
		(layer "In4.Cu")
		(net "FM_BIOS_TOP_SWAP")
	)
	(segment
		(start 439.610754 -20.128484)
		(end 433.39131 -20.128484)
		(width 0.089408)
		(layer "In4.Cu")
		(net "FM_BIOS_TOP_SWAP")
	)
	(segment
		(start 453.955912 -26.9494)
		(end 449.4276 -22.421088)
		(width 0.089408)
		(layer "In4.Cu")
		(net "FM_BIOS_TOP_SWAP")
	)
	(segment
		(start 448.417442 -19.83613)
		(end 448.259454 -19.83613)
		(width 0.089408)
		(layer "In4.Cu")
		(net "FM_BIOS_TOP_SWAP")
	)
	(segment
		(start 449.4276 -22.421088)
		(end 449.4276 -20.846288)
		(width 0.089408)
		(layer "In4.Cu")
		(net "FM_BIOS_TOP_SWAP")
	)
	(segment
		(start 459.80223 -26.543)
		(end 459.39583 -26.9494)
		(width 0.089408)
		(layer "In4.Cu")
		(net "FM_BIOS_TOP_SWAP")
	)
	(segment
		(start 445.559942 -18.945352)
		(end 440.793886 -18.945352)
		(width 0.089408)
		(layer "In4.Cu")
		(net "FM_BIOS_TOP_SWAP")
	)
	(segment
		(start 425.398184 -21.182584)
		(end 424.942 -20.7264)
		(width 0.089408)
		(layer "In4.Cu")
		(net "FM_BIOS_TOP_SWAP")
	)
	(segment
		(start 415.075116 -50.153316)
		(end 415.053526 -50.153316)
		(width 0.089408)
		(layer "In9.Cu")
		(net "FM_BIOS_TOP_SWAP")
	)
	(segment
		(start 409.787598 -55.254652)
		(end 409.787598 -54.064916)
		(width 0.089408)
		(layer "In9.Cu")
		(net "FM_BIOS_TOP_SWAP")
	)
	(segment
		(start 457.242672 -34.481008)
		(end 456.744324 -34.481008)
		(width 0.089408)
		(layer "In9.Cu")
		(net "FM_BIOS_TOP_SWAP")
	)
	(segment
		(start 409.415234 -66.103754)
		(end 409.415234 -61.312298)
		(width 0.089408)
		(layer "In9.Cu")
		(net "FM_BIOS_TOP_SWAP")
	)
	(segment
		(start 418.827204 -48.989488)
		(end 418.669216 -48.989488)
		(width 0.089408)
		(layer "In9.Cu")
		(net "FM_BIOS_TOP_SWAP")
	)
	(segment
		(start 409.787598 -54.064916)
		(end 413.24911 -50.603404)
		(width 0.089408)
		(layer "In9.Cu")
		(net "FM_BIOS_TOP_SWAP")
	)
	(segment
		(start 389.31977 -97.996502)
		(end 389.31977 -97.21469)
		(width 0.089408)
		(layer "In9.Cu")
		(net "FM_BIOS_TOP_SWAP")
	)
	(segment
		(start 432.035712 -44.760388)
		(end 428.0408 -44.760388)
		(width 0.089408)
		(layer "In9.Cu")
		(net "FM_BIOS_TOP_SWAP")
	)
	(segment
		(start 393.669774 -90.760804)
		(end 393.669774 -89.936574)
		(width 0.089408)
		(layer "In9.Cu")
		(net "FM_BIOS_TOP_SWAP")
	)
	(segment
		(start 396.410688 -86.412578)
		(end 396.410688 -86.36889)
		(width 0.089408)
		(layer "In9.Cu")
		(net "FM_BIOS_TOP_SWAP")
	)
	(segment
		(start 392.797792 -91.632786)
		(end 393.669774 -90.760804)
		(width 0.089408)
		(layer "In9.Cu")
		(net "FM_BIOS_TOP_SWAP")
	)
	(segment
		(start 392.797792 -92.856812)
		(end 392.797792 -91.632786)
		(width 0.089408)
		(layer "In9.Cu")
		(net "FM_BIOS_TOP_SWAP")
	)
	(segment
		(start 454.273666 -40.755062)
		(end 452.322946 -40.755062)
		(width 0.089408)
		(layer "In9.Cu")
		(net "FM_BIOS_TOP_SWAP")
	)
	(segment
		(start 416.134042 -50.635662)
		(end 415.557462 -50.635662)
		(width 0.089408)
		(layer "In9.Cu")
		(net "FM_BIOS_TOP_SWAP")
	)
	(segment
		(start 408.042618 -67.47637)
		(end 409.415234 -66.103754)
		(width 0.089408)
		(layer "In9.Cu")
		(net "FM_BIOS_TOP_SWAP")
	)
	(segment
		(start 418.669216 -48.989488)
		(end 418.387022 -49.271682)
		(width 0.089408)
		(layer "In9.Cu")
		(net "FM_BIOS_TOP_SWAP")
	)
	(segment
		(start 458.682598 -33.041082)
		(end 457.242672 -34.481008)
		(width 0.089408)
		(layer "In9.Cu")
		(net "FM_BIOS_TOP_SWAP")
	)
	(segment
		(start 396.410688 -86.36889)
		(end 397.814292 -84.965286)
		(width 0.089408)
		(layer "In9.Cu")
		(net "FM_BIOS_TOP_SWAP")
	)
	(segment
		(start 427.064424 -45.736764)
		(end 426.244258 -45.736764)
		(width 0.089408)
		(layer "In9.Cu")
		(net "FM_BIOS_TOP_SWAP")
	)
	(segment
		(start 456.913488 -30.102302)
		(end 458.682598 -31.871412)
		(width 0.089408)
		(layer "In9.Cu")
		(net "FM_BIOS_TOP_SWAP")
	)
	(segment
		(start 389.31977 -95.723202)
		(end 390.594088 -94.448884)
		(width 0.089408)
		(layer "In9.Cu")
		(net "FM_BIOS_TOP_SWAP")
	)
	(segment
		(start 401.42541 -77.983334)
		(end 401.42541 -76.261214)
		(width 0.089408)
		(layer "In9.Cu")
		(net "FM_BIOS_TOP_SWAP")
	)
	(segment
		(start 455.454512 -35.77082)
		(end 455.454512 -39.574216)
		(width 0.089408)
		(layer "In9.Cu")
		(net "FM_BIOS_TOP_SWAP")
	)
	(segment
		(start 397.814292 -82.268314)
		(end 400.66595 -79.416656)
		(width 0.089408)
		(layer "In9.Cu")
		(net "FM_BIOS_TOP_SWAP")
	)
	(segment
		(start 394.6144 -87.2998)
		(end 395.523466 -87.2998)
		(width 0.089408)
		(layer "In9.Cu")
		(net "FM_BIOS_TOP_SWAP")
	)
	(segment
		(start 409.415234 -61.312298)
		(end 409.210256 -61.10732)
		(width 0.089408)
		(layer "In9.Cu")
		(net "FM_BIOS_TOP_SWAP")
	)
	(segment
		(start 389.31977 -97.21469)
		(end 389.62203 -96.91243)
		(width 0.089408)
		(layer "In9.Cu")
		(net "FM_BIOS_TOP_SWAP")
	)
	(segment
		(start 393.1666 -89.4334)
		(end 393.1666 -88.7476)
		(width 0.089408)
		(layer "In9.Cu")
		(net "FM_BIOS_TOP_SWAP")
	)
	(segment
		(start 401.42541 -76.261214)
		(end 402.305774 -75.38085)
		(width 0.089408)
		(layer "In9.Cu")
		(net "FM_BIOS_TOP_SWAP")
	)
	(segment
		(start 416.5727 -50.197004)
		(end 416.134042 -50.635662)
		(width 0.089408)
		(layer "In9.Cu")
		(net "FM_BIOS_TOP_SWAP")
	)
	(segment
		(start 458.682598 -31.871412)
		(end 458.682598 -33.041082)
		(width 0.089408)
		(layer "In9.Cu")
		(net "FM_BIOS_TOP_SWAP")
	)
	(segment
		(start 436.64251 -42.382186)
		(end 435.606698 -43.417998)
		(width 0.089408)
		(layer "In9.Cu")
		(net "FM_BIOS_TOP_SWAP")
	)
	(segment
		(start 459.80223 -26.543)
		(end 459.401926 -26.142696)
		(width 0.089408)
		(layer "In9.Cu")
		(net "FM_BIOS_TOP_SWAP")
	)
	(segment
		(start 413.24911 -50.603404)
		(end 414.603438 -50.603404)
		(width 0.089408)
		(layer "In9.Cu")
		(net "FM_BIOS_TOP_SWAP")
	)
	(segment
		(start 390.594088 -94.448884)
		(end 391.20572 -94.448884)
		(width 0.089408)
		(layer "In9.Cu")
		(net "FM_BIOS_TOP_SWAP")
	)
	(segment
		(start 408.042618 -68.203572)
		(end 408.042618 -67.47637)
		(width 0.089408)
		(layer "In9.Cu")
		(net "FM_BIOS_TOP_SWAP")
	)
	(segment
		(start 418.827458 -48.989742)
		(end 418.827204 -48.989488)
		(width 0.089408)
		(layer "In9.Cu")
		(net "FM_BIOS_TOP_SWAP")
	)
	(segment
		(start 426.126402 -45.85462)
		(end 423.15638 -45.85462)
		(width 0.089408)
		(layer "In9.Cu")
		(net "FM_BIOS_TOP_SWAP")
	)
	(segment
		(start 393.1666 -88.7476)
		(end 394.6144 -87.2998)
		(width 0.089408)
		(layer "In9.Cu")
		(net "FM_BIOS_TOP_SWAP")
	)
	(segment
		(start 409.210256 -55.831994)
		(end 409.787598 -55.254652)
		(width 0.089408)
		(layer "In9.Cu")
		(net "FM_BIOS_TOP_SWAP")
	)
	(segment
		(start 400.66595 -79.416656)
		(end 400.66595 -78.742794)
		(width 0.089408)
		(layer "In9.Cu")
		(net "FM_BIOS_TOP_SWAP")
	)
	(segment
		(start 395.523466 -87.2998)
		(end 396.410688 -86.412578)
		(width 0.089408)
		(layer "In9.Cu")
		(net "FM_BIOS_TOP_SWAP")
	)
	(segment
		(start 389.71855 -99.322636)
		(end 389.71855 -98.395282)
		(width 0.089408)
		(layer "In9.Cu")
		(net "FM_BIOS_TOP_SWAP")
	)
	(segment
		(start 423.15638 -45.85462)
		(end 421.90924 -47.10176)
		(width 0.089408)
		(layer "In9.Cu")
		(net "FM_BIOS_TOP_SWAP")
	)
	(segment
		(start 389.31977 -96.279462)
		(end 389.31977 -95.723202)
		(width 0.089408)
		(layer "In9.Cu")
		(net "FM_BIOS_TOP_SWAP")
	)
	(segment
		(start 419.313614 -48.989742)
		(end 418.827458 -48.989742)
		(width 0.089408)
		(layer "In9.Cu")
		(net "FM_BIOS_TOP_SWAP")
	)
	(segment
		(start 393.669774 -89.936574)
		(end 393.1666 -89.4334)
		(width 0.089408)
		(layer "In9.Cu")
		(net "FM_BIOS_TOP_SWAP")
	)
	(segment
		(start 455.454512 -39.574216)
		(end 454.273666 -40.755062)
		(width 0.089408)
		(layer "In9.Cu")
		(net "FM_BIOS_TOP_SWAP")
	)
	(segment
		(start 389.62203 -96.581722)
		(end 389.31977 -96.279462)
		(width 0.089408)
		(layer "In9.Cu")
		(net "FM_BIOS_TOP_SWAP")
	)
	(segment
		(start 389.62203 -96.91243)
		(end 389.62203 -96.581722)
		(width 0.089408)
		(layer "In9.Cu")
		(net "FM_BIOS_TOP_SWAP")
	)
	(segment
		(start 416.572446 -49.85766)
		(end 416.572446 -50.188876)
		(width 0.089408)
		(layer "In9.Cu")
		(net "FM_BIOS_TOP_SWAP")
	)
	(segment
		(start 389.71855 -98.395282)
		(end 389.31977 -97.996502)
		(width 0.089408)
		(layer "In9.Cu")
		(net "FM_BIOS_TOP_SWAP")
	)
	(segment
		(start 416.5727 -50.18913)
		(end 416.5727 -50.197004)
		(width 0.089408)
		(layer "In9.Cu")
		(net "FM_BIOS_TOP_SWAP")
	)
	(segment
		(start 406.69718 -70.00875)
		(end 406.69718 -69.54901)
		(width 0.089408)
		(layer "In9.Cu")
		(net "FM_BIOS_TOP_SWAP")
	)
	(segment
		(start 402.305774 -74.400156)
		(end 406.69718 -70.00875)
		(width 0.089408)
		(layer "In9.Cu")
		(net "FM_BIOS_TOP_SWAP")
	)
	(segment
		(start 459.001368 -26.142696)
		(end 456.913488 -28.230576)
		(width 0.089408)
		(layer "In9.Cu")
		(net "FM_BIOS_TOP_SWAP")
	)
	(segment
		(start 417.158424 -49.271682)
		(end 416.572446 -49.85766)
		(width 0.089408)
		(layer "In9.Cu")
		(net "FM_BIOS_TOP_SWAP")
	)
	(segment
		(start 435.606698 -43.417998)
		(end 433.378102 -43.417998)
		(width 0.089408)
		(layer "In9.Cu")
		(net "FM_BIOS_TOP_SWAP")
	)
	(segment
		(start 402.305774 -75.38085)
		(end 402.305774 -74.400156)
		(width 0.089408)
		(layer "In9.Cu")
		(net "FM_BIOS_TOP_SWAP")
	)
	(segment
		(start 414.603438 -50.603404)
		(end 415.053526 -50.153316)
		(width 0.089408)
		(layer "In9.Cu")
		(net "FM_BIOS_TOP_SWAP")
	)
	(segment
		(start 409.210256 -61.10732)
		(end 409.210256 -55.831994)
		(width 0.089408)
		(layer "In9.Cu")
		(net "FM_BIOS_TOP_SWAP")
	)
	(segment
		(start 416.572446 -50.188876)
		(end 416.5727 -50.18913)
		(width 0.089408)
		(layer "In9.Cu")
		(net "FM_BIOS_TOP_SWAP")
	)
	(segment
		(start 459.401926 -26.142696)
		(end 459.001368 -26.142696)
		(width 0.089408)
		(layer "In9.Cu")
		(net "FM_BIOS_TOP_SWAP")
	)
	(segment
		(start 456.913488 -28.230576)
		(end 456.913488 -30.102302)
		(width 0.089408)
		(layer "In9.Cu")
		(net "FM_BIOS_TOP_SWAP")
	)
	(segment
		(start 418.387022 -49.271682)
		(end 417.158424 -49.271682)
		(width 0.089408)
		(layer "In9.Cu")
		(net "FM_BIOS_TOP_SWAP")
	)
	(segment
		(start 415.557462 -50.635662)
		(end 415.075116 -50.153316)
		(width 0.089408)
		(layer "In9.Cu")
		(net "FM_BIOS_TOP_SWAP")
	)
	(segment
		(start 450.695822 -42.382186)
		(end 436.64251 -42.382186)
		(width 0.089408)
		(layer "In9.Cu")
		(net "FM_BIOS_TOP_SWAP")
	)
	(segment
		(start 452.322946 -40.755062)
		(end 450.695822 -42.382186)
		(width 0.089408)
		(layer "In9.Cu")
		(net "FM_BIOS_TOP_SWAP")
	)
	(segment
		(start 397.814292 -84.965286)
		(end 397.814292 -82.268314)
		(width 0.089408)
		(layer "In9.Cu")
		(net "FM_BIOS_TOP_SWAP")
	)
	(segment
		(start 428.0408 -44.760388)
		(end 427.064424 -45.736764)
		(width 0.089408)
		(layer "In9.Cu")
		(net "FM_BIOS_TOP_SWAP")
	)
	(segment
		(start 391.20572 -94.448884)
		(end 392.797792 -92.856812)
		(width 0.089408)
		(layer "In9.Cu")
		(net "FM_BIOS_TOP_SWAP")
	)
	(segment
		(start 456.744324 -34.481008)
		(end 455.454512 -35.77082)
		(width 0.089408)
		(layer "In9.Cu")
		(net "FM_BIOS_TOP_SWAP")
	)
	(segment
		(start 433.378102 -43.417998)
		(end 432.035712 -44.760388)
		(width 0.089408)
		(layer "In9.Cu")
		(net "FM_BIOS_TOP_SWAP")
	)
	(segment
		(start 400.66595 -78.742794)
		(end 401.42541 -77.983334)
		(width 0.089408)
		(layer "In9.Cu")
		(net "FM_BIOS_TOP_SWAP")
	)
	(segment
		(start 426.244258 -45.736764)
		(end 426.126402 -45.85462)
		(width 0.089408)
		(layer "In9.Cu")
		(net "FM_BIOS_TOP_SWAP")
	)
	(segment
		(start 421.201596 -47.10176)
		(end 419.313614 -48.989742)
		(width 0.089408)
		(layer "In9.Cu")
		(net "FM_BIOS_TOP_SWAP")
	)
	(segment
		(start 421.90924 -47.10176)
		(end 421.201596 -47.10176)
		(width 0.089408)
		(layer "In9.Cu")
		(net "FM_BIOS_TOP_SWAP")
	)
	(segment
		(start 406.69718 -69.54901)
		(end 408.042618 -68.203572)
		(width 0.089408)
		(layer "In9.Cu")
		(net "FM_BIOS_TOP_SWAP")
	)
	(segment
		(start 440.001152 -19.060668)
		(end 445.698118 -19.060668)
		(width 0.089408)
		(layer "In11.Cu")
		(net "FM_BIOS_TOP_SWAP")
	)
	(segment
		(start 460.48803 -8.560816)
		(end 467.950042 -8.560816)
		(width 0.089408)
		(layer "In11.Cu")
		(net "FM_BIOS_TOP_SWAP")
	)
	(segment
		(start 431.356262 -20.586192)
		(end 432.16703 -19.775424)
		(width 0.089408)
		(layer "In11.Cu")
		(net "FM_BIOS_TOP_SWAP")
	)
	(segment
		(start 459.574392 -10.579354)
		(end 459.865222 -10.288524)
		(width 0.089408)
		(layer "In11.Cu")
		(net "FM_BIOS_TOP_SWAP")
	)
	(segment
		(start 468.53602 -9.146794)
		(end 469.250268 -9.146794)
		(width 0.089408)
		(layer "In11.Cu")
		(net "FM_BIOS_TOP_SWAP")
	)
	(segment
		(start 425.696888 -21.481288)
		(end 428.023528 -21.481288)
		(width 0.089408)
		(layer "In11.Cu")
		(net "FM_BIOS_TOP_SWAP")
	)
	(segment
		(start 424.942 -20.7264)
		(end 425.696888 -21.481288)
		(width 0.089408)
		(layer "In11.Cu")
		(net "FM_BIOS_TOP_SWAP")
	)
	(segment
		(start 428.023528 -21.481288)
		(end 428.918624 -20.586192)
		(width 0.089408)
		(layer "In11.Cu")
		(net "FM_BIOS_TOP_SWAP")
	)
	(segment
		(start 459.865222 -9.183624)
		(end 460.48803 -8.560816)
		(width 0.089408)
		(layer "In11.Cu")
		(net "FM_BIOS_TOP_SWAP")
	)
	(segment
		(start 450.285612 -18.260568)
		(end 450.285612 -16.965422)
		(width 0.089408)
		(layer "In11.Cu")
		(net "FM_BIOS_TOP_SWAP")
	)
	(segment
		(start 467.950042 -8.560816)
		(end 468.53602 -9.146794)
		(width 0.089408)
		(layer "In11.Cu")
		(net "FM_BIOS_TOP_SWAP")
	)
	(segment
		(start 469.250268 -9.146794)
		(end 469.652858 -8.744204)
		(width 0.089408)
		(layer "In11.Cu")
		(net "FM_BIOS_TOP_SWAP")
	)
	(segment
		(start 434.886862 -19.998182)
		(end 439.063638 -19.998182)
		(width 0.089408)
		(layer "In11.Cu")
		(net "FM_BIOS_TOP_SWAP")
	)
	(segment
		(start 449.920868 -18.625312)
		(end 450.285612 -18.260568)
		(width 0.089408)
		(layer "In11.Cu")
		(net "FM_BIOS_TOP_SWAP")
	)
	(segment
		(start 434.216048 -19.327368)
		(end 434.886862 -19.998182)
		(width 0.089408)
		(layer "In11.Cu")
		(net "FM_BIOS_TOP_SWAP")
	)
	(segment
		(start 433.170838 -19.327368)
		(end 434.216048 -19.327368)
		(width 0.089408)
		(layer "In11.Cu")
		(net "FM_BIOS_TOP_SWAP")
	)
	(segment
		(start 454.59777 -10.579354)
		(end 459.574392 -10.579354)
		(width 0.089408)
		(layer "In11.Cu")
		(net "FM_BIOS_TOP_SWAP")
	)
	(segment
		(start 447.38925 -19.13382)
		(end 447.897758 -18.625312)
		(width 0.089408)
		(layer "In11.Cu")
		(net "FM_BIOS_TOP_SWAP")
	)
	(segment
		(start 428.918624 -20.586192)
		(end 431.356262 -20.586192)
		(width 0.089408)
		(layer "In11.Cu")
		(net "FM_BIOS_TOP_SWAP")
	)
	(segment
		(start 439.063638 -19.998182)
		(end 440.001152 -19.060668)
		(width 0.089408)
		(layer "In11.Cu")
		(net "FM_BIOS_TOP_SWAP")
	)
	(segment
		(start 432.16703 -19.775424)
		(end 432.722782 -19.775424)
		(width 0.089408)
		(layer "In11.Cu")
		(net "FM_BIOS_TOP_SWAP")
	)
	(segment
		(start 445.77127 -19.13382)
		(end 447.38925 -19.13382)
		(width 0.089408)
		(layer "In11.Cu")
		(net "FM_BIOS_TOP_SWAP")
	)
	(segment
		(start 432.722782 -19.775424)
		(end 433.170838 -19.327368)
		(width 0.089408)
		(layer "In11.Cu")
		(net "FM_BIOS_TOP_SWAP")
	)
	(segment
		(start 447.897758 -18.625312)
		(end 449.920868 -18.625312)
		(width 0.089408)
		(layer "In11.Cu")
		(net "FM_BIOS_TOP_SWAP")
	)
	(segment
		(start 452.137526 -13.039598)
		(end 454.59777 -10.579354)
		(width 0.089408)
		(layer "In11.Cu")
		(net "FM_BIOS_TOP_SWAP")
	)
	(segment
		(start 450.285612 -16.965422)
		(end 452.137526 -15.113508)
		(width 0.089408)
		(layer "In11.Cu")
		(net "FM_BIOS_TOP_SWAP")
	)
	(segment
		(start 452.137526 -15.113508)
		(end 452.137526 -13.039598)
		(width 0.089408)
		(layer "In11.Cu")
		(net "FM_BIOS_TOP_SWAP")
	)
	(segment
		(start 459.865222 -10.288524)
		(end 459.865222 -9.183624)
		(width 0.089408)
		(layer "In11.Cu")
		(net "FM_BIOS_TOP_SWAP")
	)
	(segment
		(start 445.698118 -19.060668)
		(end 445.77127 -19.13382)
		(width 0.089408)
		(layer "In11.Cu")
		(net "FM_BIOS_TOP_SWAP")
	)
	(segment
		(start 12.022582 -108.808266)
		(end 12.023344 -108.809028)
		(width 0.254)
		(layer "F.Cu")
		(net "A_HSC_OCP_SEL")
	)
	(segment
		(start 11.418824 -108.087922)
		(end 12.022582 -108.69168)
		(width 0.254)
		(layer "F.Cu")
		(net "A_HSC_OCP_SEL")
	)
	(segment
		(start 9.834372 -88.285828)
		(end 9.834372 -105.896918)
		(width 0.254)
		(layer "F.Cu")
		(net "A_HSC_OCP_SEL")
	)
	(segment
		(start 14.986 -83.274408)
		(end 14.510004 -83.750404)
		(width 0.254)
		(layer "F.Cu")
		(net "A_HSC_OCP_SEL")
	)
	(segment
		(start 14.510004 -83.750404)
		(end 13.099796 -83.750404)
		(width 0.254)
		(layer "F.Cu")
		(net "A_HSC_OCP_SEL")
	)
	(segment
		(start 11.418824 -107.48137)
		(end 11.418824 -108.087922)
		(width 0.254)
		(layer "F.Cu")
		(net "A_HSC_OCP_SEL")
	)
	(segment
		(start 12.023344 -108.809028)
		(end 12.023344 -109.947964)
		(width 0.254)
		(layer "F.Cu")
		(net "A_HSC_OCP_SEL")
	)
	(segment
		(start 13.099796 -83.750404)
		(end 11.4935 -85.3567)
		(width 0.254)
		(layer "F.Cu")
		(net "A_HSC_OCP_SEL")
	)
	(segment
		(start 9.834372 -105.896918)
		(end 11.418824 -107.48137)
		(width 0.254)
		(layer "F.Cu")
		(net "A_HSC_OCP_SEL")
	)
	(segment
		(start 11.4935 -86.6267)
		(end 9.834372 -88.285828)
		(width 0.254)
		(layer "F.Cu")
		(net "A_HSC_OCP_SEL")
	)
	(segment
		(start 12.022582 -108.69168)
		(end 12.022582 -108.808266)
		(width 0.254)
		(layer "F.Cu")
		(net "A_HSC_OCP_SEL")
	)
	(segment
		(start 11.4935 -85.3567)
		(end 11.4935 -86.6267)
		(width 0.254)
		(layer "F.Cu")
		(net "A_HSC_OCP_SEL")
	)
	(segment
		(start 12.782804 -110.707424)
		(end 16.469106 -110.707424)
		(width 0.254)
		(layer "F.Cu")
		(net "A_HSC_OCP_SEL")
	)
	(segment
		(start 14.986 -83.058)
		(end 14.986 -83.274408)
		(width 0.254)
		(layer "F.Cu")
		(net "A_HSC_OCP_SEL")
	)
	(segment
		(start 12.023344 -109.947964)
		(end 12.782804 -110.707424)
		(width 0.254)
		(layer "F.Cu")
		(net "A_HSC_OCP_SEL")
	)
	(segment
		(start 406.824434 -114.096038)
		(end 406.7937 -114.126772)
		(width 0.10795)
		(layer "F.Cu")
		(net "SGPIO_PCH_SSATA_DOUT0")
	)
	(segment
		(start 405.675338 -113.93932)
		(end 405.86279 -114.126772)
		(width 0.10795)
		(layer "F.Cu")
		(net "SGPIO_PCH_SSATA_DOUT0")
	)
	(segment
		(start 401.140168 -112.559338)
		(end 402.055838 -112.559338)
		(width 0.0889)
		(layer "F.Cu")
		(net "SGPIO_PCH_SSATA_DOUT0")
	)
	(segment
		(start 409.447238 -114.096038)
		(end 406.824434 -114.096038)
		(width 0.10795)
		(layer "F.Cu")
		(net "SGPIO_PCH_SSATA_DOUT0")
	)
	(segment
		(start 404.630636 -113.546636)
		(end 405.02332 -113.93932)
		(width 0.0889)
		(layer "F.Cu")
		(net "SGPIO_PCH_SSATA_DOUT0")
	)
	(segment
		(start 405.02332 -113.93932)
		(end 405.675338 -113.93932)
		(width 0.10795)
		(layer "F.Cu")
		(net "SGPIO_PCH_SSATA_DOUT0")
	)
	(segment
		(start 403.043136 -113.546636)
		(end 404.630636 -113.546636)
		(width 0.0889)
		(layer "F.Cu")
		(net "SGPIO_PCH_SSATA_DOUT0")
	)
	(segment
		(start 400.844512 -112.854994)
		(end 401.140168 -112.559338)
		(width 0.0889)
		(layer "F.Cu")
		(net "SGPIO_PCH_SSATA_DOUT0")
	)
	(segment
		(start 402.055838 -112.559338)
		(end 403.043136 -113.546636)
		(width 0.0889)
		(layer "F.Cu")
		(net "SGPIO_PCH_SSATA_DOUT0")
	)
	(segment
		(start 400.465036 -112.854994)
		(end 400.844512 -112.854994)
		(width 0.0889)
		(layer "F.Cu")
		(net "SGPIO_PCH_SSATA_DOUT0")
	)
	(segment
		(start 406.7937 -114.126772)
		(end 405.86279 -114.126772)
		(width 0.10795)
		(layer "F.Cu")
		(net "SGPIO_PCH_SSATA_DOUT0")
	)
	(segment
		(start 409.6512 -114.3)
		(end 409.447238 -114.096038)
		(width 0.10795)
		(layer "F.Cu")
		(net "SGPIO_PCH_SSATA_DOUT0")
	)
	(via
		(at 405.86279 -114.126772)
		(size 0.762)
		(drill 0.381)
		(layers "F.Cu" "B.Cu")
		(net "SGPIO_PCH_SSATA_DOUT0")
	)
	(via
		(at 386.842 -50.5714)
		(size 0.6604)
		(drill 0.3302)
		(layers "F.Cu" "B.Cu")
		(net "PU_BIOS_SPI_WP1_N")
	)
	(segment
		(start 387.477 -47.22368)
		(end 388.657846 -47.22368)
		(width 0.10795)
		(layer "B.Cu")
		(net "PU_BIOS_SPI_WP1_N")
	)
	(segment
		(start 386.969 -48.9712)
		(end 387.1976 -49.1998)
		(width 0.10795)
		(layer "B.Cu")
		(net "PU_BIOS_SPI_WP1_N")
	)
	(segment
		(start 386.56895 -50.5714)
		(end 386.461 -50.46345)
		(width 0.10795)
		(layer "B.Cu")
		(net "PU_BIOS_SPI_WP1_N")
	)
	(segment
		(start 387.45668 -47.244)
		(end 387.477 -47.22368)
		(width 0.10795)
		(layer "B.Cu")
		(net "PU_BIOS_SPI_WP1_N")
	)
	(segment
		(start 387.08965 -50.5714)
		(end 386.842 -50.5714)
		(width 0.10795)
		(layer "B.Cu")
		(net "PU_BIOS_SPI_WP1_N")
	)
	(segment
		(start 386.842 -50.5714)
		(end 386.56895 -50.5714)
		(width 0.10795)
		(layer "B.Cu")
		(net "PU_BIOS_SPI_WP1_N")
	)
	(segment
		(start 386.969 -47.244)
		(end 387.45668 -47.244)
		(width 0.10795)
		(layer "B.Cu")
		(net "PU_BIOS_SPI_WP1_N")
	)
	(segment
		(start 386.461 -50.46345)
		(end 386.461 -49.403)
		(width 0.10795)
		(layer "B.Cu")
		(net "PU_BIOS_SPI_WP1_N")
	)
	(segment
		(start 387.1976 -50.46345)
		(end 387.08965 -50.5714)
		(width 0.10795)
		(layer "B.Cu")
		(net "PU_BIOS_SPI_WP1_N")
	)
	(segment
		(start 386.969 -47.244)
		(end 386.969 -48.006)
		(width 0.10795)
		(layer "B.Cu")
		(net "PU_BIOS_SPI_WP1_N")
	)
	(segment
		(start 386.969 -48.006)
		(end 386.969 -48.9712)
		(width 0.10795)
		(layer "B.Cu")
		(net "PU_BIOS_SPI_WP1_N")
	)
	(segment
		(start 387.1976 -49.1998)
		(end 387.1976 -50.46345)
		(width 0.10795)
		(layer "B.Cu")
		(net "PU_BIOS_SPI_WP1_N")
	)
	(segment
		(start 381.157988 -57.500012)
		(end 381.7112 -56.9468)
		(width 0.10795)
		(layer "F.Cu")
		(net "PU_BIOS_SPI_WP0_N")
	)
	(segment
		(start 382.651 -56.9468)
		(end 382.891284 -56.706516)
		(width 0.10795)
		(layer "F.Cu")
		(net "PU_BIOS_SPI_WP0_N")
	)
	(segment
		(start 385.572 -56.3245)
		(end 386.3975 -56.3245)
		(width 0.10795)
		(layer "F.Cu")
		(net "PU_BIOS_SPI_WP0_N")
	)
	(segment
		(start 386.60832 -56.11368)
		(end 388.543546 -56.11368)
		(width 0.10795)
		(layer "F.Cu")
		(net "PU_BIOS_SPI_WP0_N")
	)
	(segment
		(start 380.410212 -57.500012)
		(end 381.157988 -57.500012)
		(width 0.10795)
		(layer "F.Cu")
		(net "PU_BIOS_SPI_WP0_N")
	)
	(segment
		(start 382.896364 -56.3245)
		(end 382.891284 -56.32958)
		(width 0.10795)
		(layer "F.Cu")
		(net "PU_BIOS_SPI_WP0_N")
	)
	(segment
		(start 381.7112 -56.9468)
		(end 382.651 -56.9468)
		(width 0.10795)
		(layer "F.Cu")
		(net "PU_BIOS_SPI_WP0_N")
	)
	(segment
		(start 379.8062 -56.896)
		(end 380.410212 -57.500012)
		(width 0.10795)
		(layer "F.Cu")
		(net "PU_BIOS_SPI_WP0_N")
	)
	(segment
		(start 383.794 -56.3245)
		(end 382.896364 -56.3245)
		(width 0.10795)
		(layer "F.Cu")
		(net "PU_BIOS_SPI_WP0_N")
	)
	(segment
		(start 386.3975 -56.3245)
		(end 386.60832 -56.11368)
		(width 0.10795)
		(layer "F.Cu")
		(net "PU_BIOS_SPI_WP0_N")
	)
	(segment
		(start 385.572 -56.3245)
		(end 383.794 -56.3245)
		(width 0.10795)
		(layer "F.Cu")
		(net "PU_BIOS_SPI_WP0_N")
	)
	(segment
		(start 382.891284 -56.706516)
		(end 382.891284 -56.32958)
		(width 0.10795)
		(layer "F.Cu")
		(net "PU_BIOS_SPI_WP0_N")
	)
	(via
		(at 379.8062 -56.896)
		(size 0.762)
		(drill 0.381)
		(layers "F.Cu" "B.Cu")
		(net "PU_BIOS_SPI_WP0_N")
	)
	(via
		(at 401.2946 -56.769)
		(size 0.6604)
		(drill 0.3302)
		(layers "F.Cu" "B.Cu")
		(net "PU_BIOS_SPI_HOLD1_N")
	)
	(segment
		(start 401.2946 -56.769)
		(end 399.923 -56.769)
		(width 0.10795)
		(layer "B.Cu")
		(net "PU_BIOS_SPI_HOLD1_N")
	)
	(segment
		(start 398.093946 -56.11368)
		(end 399.30832 -56.11368)
		(width 0.10795)
		(layer "B.Cu")
		(net "PU_BIOS_SPI_HOLD1_N")
	)
	(segment
		(start 399.415 -56.007)
		(end 399.923 -56.007)
		(width 0.10795)
		(layer "B.Cu")
		(net "PU_BIOS_SPI_HOLD1_N")
	)
	(segment
		(start 399.923 -56.007)
		(end 399.923 -56.769)
		(width 0.10795)
		(layer "B.Cu")
		(net "PU_BIOS_SPI_HOLD1_N")
	)
	(segment
		(start 399.30832 -56.11368)
		(end 399.415 -56.007)
		(width 0.10795)
		(layer "B.Cu")
		(net "PU_BIOS_SPI_HOLD1_N")
	)
	(segment
		(start 400.89582 -47.22368)
		(end 401.066 -47.0535)
		(width 0.10795)
		(layer "F.Cu")
		(net "PU_BIOS_SPI_HOLD0_N")
	)
	(segment
		(start 398.093946 -47.22368)
		(end 400.89582 -47.22368)
		(width 0.10795)
		(layer "F.Cu")
		(net "PU_BIOS_SPI_HOLD0_N")
	)
	(segment
		(start 401.066 -47.0535)
		(end 401.066 -46.2915)
		(width 0.10795)
		(layer "F.Cu")
		(net "PU_BIOS_SPI_HOLD0_N")
	)
	(segment
		(start 381.38354 -91.635326)
		(end 380.554484 -90.80627)
		(width 0.0889)
		(layer "F.Cu")
		(net "FM_UART_PRES_N")
	)
	(segment
		(start 381.484886 -93.959934)
		(end 381.484886 -93.327982)
		(width 0.0889)
		(layer "F.Cu")
		(net "FM_UART_PRES_N")
	)
	(segment
		(start 381.484886 -93.327982)
		(end 381.38354 -93.226636)
		(width 0.0889)
		(layer "F.Cu")
		(net "FM_UART_PRES_N")
	)
	(segment
		(start 381.38354 -93.226636)
		(end 381.38354 -91.635326)
		(width 0.0889)
		(layer "F.Cu")
		(net "FM_UART_PRES_N")
	)
	(via
		(at 380.554484 -90.80627)
		(size 0.508)
		(drill 0.254)
		(layers "F.Cu" "B.Cu")
		(net "FM_UART_PRES_N")
	)
	(via
		(at 379.10516 -83.3755)
		(size 0.508)
		(drill 0.254)
		(layers "F.Cu" "B.Cu")
		(net "FM_UART_PRES_N")
	)
	(via
		(at 381 -89.66454)
		(size 0.508)
		(drill 0.254)
		(layers "F.Cu" "B.Cu")
		(net "FM_UART_PRES_N")
	)
	(via
		(at 479.067622 -51.354736)
		(size 0.508)
		(drill 0.254)
		(layers "F.Cu" "B.Cu")
		(net "FM_UART_PRES_N")
	)
	(segment
		(start 381 -90.360754)
		(end 380.554484 -90.80627)
		(width 0.10795)
		(layer "B.Cu")
		(net "FM_UART_PRES_N")
	)
	(segment
		(start 380.746 -88.2015)
		(end 381 -88.4555)
		(width 0.10795)
		(layer "B.Cu")
		(net "FM_UART_PRES_N")
	)
	(segment
		(start 381 -89.66454)
		(end 381 -90.360754)
		(width 0.10795)
		(layer "B.Cu")
		(net "FM_UART_PRES_N")
	)
	(segment
		(start 381 -88.4555)
		(end 381 -89.66454)
		(width 0.10795)
		(layer "B.Cu")
		(net "FM_UART_PRES_N")
	)
	(segment
		(start 478.089468 -51.907948)
		(end 476.229934 -53.767482)
		(width 0.089408)
		(layer "In4.Cu")
		(net "FM_UART_PRES_N")
	)
	(segment
		(start 388.736586 -81.781904)
		(end 388.122922 -82.395568)
		(width 0.089408)
		(layer "In4.Cu")
		(net "FM_UART_PRES_N")
	)
	(segment
		(start 392.0744 -80.830166)
		(end 391.129774 -81.774792)
		(width 0.089408)
		(layer "In4.Cu")
		(net "FM_UART_PRES_N")
	)
	(segment
		(start 423.277284 -63.777622)
		(end 422.6052 -64.449706)
		(width 0.089408)
		(layer "In4.Cu")
		(net "FM_UART_PRES_N")
	)
	(segment
		(start 475.013528 -56.035448)
		(end 474.993208 -56.055768)
		(width 0.089408)
		(layer "In4.Cu")
		(net "FM_UART_PRES_N")
	)
	(segment
		(start 389.496808 -81.774792)
		(end 389.489696 -81.781904)
		(width 0.089408)
		(layer "In4.Cu")
		(net "FM_UART_PRES_N")
	)
	(segment
		(start 407.672032 -80.75168)
		(end 405.793448 -78.873096)
		(width 0.089408)
		(layer "In4.Cu")
		(net "FM_UART_PRES_N")
	)
	(segment
		(start 474.993208 -56.183784)
		(end 474.312996 -56.863996)
		(width 0.089408)
		(layer "In4.Cu")
		(net "FM_UART_PRES_N")
	)
	(segment
		(start 392.0744 -80.2894)
		(end 392.0744 -80.830166)
		(width 0.089408)
		(layer "In4.Cu")
		(net "FM_UART_PRES_N")
	)
	(segment
		(start 418.014404 -67.15887)
		(end 418.014404 -68.70319)
		(width 0.089408)
		(layer "In4.Cu")
		(net "FM_UART_PRES_N")
	)
	(segment
		(start 415.913062 -72.74052)
		(end 415.581338 -72.74052)
		(width 0.089408)
		(layer "In4.Cu")
		(net "FM_UART_PRES_N")
	)
	(segment
		(start 469.779604 -56.863996)
		(end 468.912194 -55.996586)
		(width 0.089408)
		(layer "In4.Cu")
		(net "FM_UART_PRES_N")
	)
	(segment
		(start 475.211394 -53.767482)
		(end 475.015306 -53.96357)
		(width 0.089408)
		(layer "In4.Cu")
		(net "FM_UART_PRES_N")
	)
	(segment
		(start 474.312996 -56.863996)
		(end 469.779604 -56.863996)
		(width 0.089408)
		(layer "In4.Cu")
		(net "FM_UART_PRES_N")
	)
	(segment
		(start 418.014404 -68.70319)
		(end 416.710114 -70.00748)
		(width 0.089408)
		(layer "In4.Cu")
		(net "FM_UART_PRES_N")
	)
	(segment
		(start 413.928052 -74.284586)
		(end 413.928052 -78.416404)
		(width 0.089408)
		(layer "In4.Cu")
		(net "FM_UART_PRES_N")
	)
	(segment
		(start 420.723568 -64.449706)
		(end 418.014404 -67.15887)
		(width 0.089408)
		(layer "In4.Cu")
		(net "FM_UART_PRES_N")
	)
	(segment
		(start 380.46406 -82.551016)
		(end 379.639576 -83.3755)
		(width 0.089408)
		(layer "In4.Cu")
		(net "FM_UART_PRES_N")
	)
	(segment
		(start 393.768834 -79.4004)
		(end 393.476734 -79.1083)
		(width 0.089408)
		(layer "In4.Cu")
		(net "FM_UART_PRES_N")
	)
	(segment
		(start 468.912194 -55.996586)
		(end 467.407752 -55.996586)
		(width 0.089408)
		(layer "In4.Cu")
		(net "FM_UART_PRES_N")
	)
	(segment
		(start 465.241386 -61.163454)
		(end 463.860896 -62.543944)
		(width 0.089408)
		(layer "In4.Cu")
		(net "FM_UART_PRES_N")
	)
	(segment
		(start 393.044426 -79.1083)
		(end 392.809984 -79.342742)
		(width 0.089408)
		(layer "In4.Cu")
		(net "FM_UART_PRES_N")
	)
	(segment
		(start 388.122922 -82.395568)
		(end 386.545836 -82.395568)
		(width 0.089408)
		(layer "In4.Cu")
		(net "FM_UART_PRES_N")
	)
	(segment
		(start 478.51441 -51.907948)
		(end 478.089468 -51.907948)
		(width 0.089408)
		(layer "In4.Cu")
		(net "FM_UART_PRES_N")
	)
	(segment
		(start 466.103462 -54.692296)
		(end 465.771738 -54.692296)
		(width 0.089408)
		(layer "In4.Cu")
		(net "FM_UART_PRES_N")
	)
	(segment
		(start 405.793448 -78.873096)
		(end 400.223482 -78.873096)
		(width 0.089408)
		(layer "In4.Cu")
		(net "FM_UART_PRES_N")
	)
	(segment
		(start 391.129774 -81.774792)
		(end 389.496808 -81.774792)
		(width 0.089408)
		(layer "In4.Cu")
		(net "FM_UART_PRES_N")
	)
	(segment
		(start 467.407752 -55.996586)
		(end 466.103462 -54.692296)
		(width 0.089408)
		(layer "In4.Cu")
		(net "FM_UART_PRES_N")
	)
	(segment
		(start 392.809984 -79.342742)
		(end 392.809984 -79.553816)
		(width 0.089408)
		(layer "In4.Cu")
		(net "FM_UART_PRES_N")
	)
	(segment
		(start 452.2978 -62.927484)
		(end 450.784214 -64.44107)
		(width 0.089408)
		(layer "In4.Cu")
		(net "FM_UART_PRES_N")
	)
	(segment
		(start 425.32935 -63.777876)
		(end 423.435526 -63.777876)
		(width 0.089408)
		(layer "In4.Cu")
		(net "FM_UART_PRES_N")
	)
	(segment
		(start 416.710114 -72.396096)
		(end 416.36188 -72.74433)
		(width 0.089408)
		(layer "In4.Cu")
		(net "FM_UART_PRES_N")
	)
	(segment
		(start 475.013528 -54.048406)
		(end 475.013528 -56.035448)
		(width 0.089408)
		(layer "In4.Cu")
		(net "FM_UART_PRES_N")
	)
	(segment
		(start 423.435272 -63.777622)
		(end 423.277284 -63.777622)
		(width 0.089408)
		(layer "In4.Cu")
		(net "FM_UART_PRES_N")
	)
	(segment
		(start 400.223482 -78.873096)
		(end 398.632172 -80.464406)
		(width 0.089408)
		(layer "In4.Cu")
		(net "FM_UART_PRES_N")
	)
	(segment
		(start 465.771738 -54.692296)
		(end 465.241386 -55.222648)
		(width 0.089408)
		(layer "In4.Cu")
		(net "FM_UART_PRES_N")
	)
	(segment
		(start 379.639576 -83.3755)
		(end 379.10516 -83.3755)
		(width 0.089408)
		(layer "In4.Cu")
		(net "FM_UART_PRES_N")
	)
	(segment
		(start 392.809984 -79.553816)
		(end 392.0744 -80.2894)
		(width 0.089408)
		(layer "In4.Cu")
		(net "FM_UART_PRES_N")
	)
	(segment
		(start 422.6052 -64.449706)
		(end 420.723568 -64.449706)
		(width 0.089408)
		(layer "In4.Cu")
		(net "FM_UART_PRES_N")
	)
	(segment
		(start 423.435526 -63.777876)
		(end 423.435272 -63.777622)
		(width 0.089408)
		(layer "In4.Cu")
		(net "FM_UART_PRES_N")
	)
	(segment
		(start 416.710114 -70.00748)
		(end 416.710114 -72.396096)
		(width 0.089408)
		(layer "In4.Cu")
		(net "FM_UART_PRES_N")
	)
	(segment
		(start 474.993208 -56.055768)
		(end 474.993208 -56.183784)
		(width 0.089408)
		(layer "In4.Cu")
		(net "FM_UART_PRES_N")
	)
	(segment
		(start 415.577528 -72.74433)
		(end 415.468308 -72.74433)
		(width 0.089408)
		(layer "In4.Cu")
		(net "FM_UART_PRES_N")
	)
	(segment
		(start 457.722224 -62.927484)
		(end 452.2978 -62.927484)
		(width 0.089408)
		(layer "In4.Cu")
		(net "FM_UART_PRES_N")
	)
	(segment
		(start 398.632172 -80.464406)
		(end 396.81912 -80.464406)
		(width 0.089408)
		(layer "In4.Cu")
		(net "FM_UART_PRES_N")
	)
	(segment
		(start 476.229934 -53.767482)
		(end 475.211394 -53.767482)
		(width 0.089408)
		(layer "In4.Cu")
		(net "FM_UART_PRES_N")
	)
	(segment
		(start 475.015306 -54.046628)
		(end 475.013528 -54.048406)
		(width 0.089408)
		(layer "In4.Cu")
		(net "FM_UART_PRES_N")
	)
	(segment
		(start 450.784214 -64.44107)
		(end 425.992544 -64.44107)
		(width 0.089408)
		(layer "In4.Cu")
		(net "FM_UART_PRES_N")
	)
	(segment
		(start 458.105764 -62.543944)
		(end 457.722224 -62.927484)
		(width 0.089408)
		(layer "In4.Cu")
		(net "FM_UART_PRES_N")
	)
	(segment
		(start 389.489696 -81.781904)
		(end 388.736586 -81.781904)
		(width 0.089408)
		(layer "In4.Cu")
		(net "FM_UART_PRES_N")
	)
	(segment
		(start 415.468308 -72.74433)
		(end 413.928052 -74.284586)
		(width 0.089408)
		(layer "In4.Cu")
		(net "FM_UART_PRES_N")
	)
	(segment
		(start 386.545836 -82.395568)
		(end 386.390388 -82.551016)
		(width 0.089408)
		(layer "In4.Cu")
		(net "FM_UART_PRES_N")
	)
	(segment
		(start 425.992544 -64.44107)
		(end 425.32935 -63.777876)
		(width 0.089408)
		(layer "In4.Cu")
		(net "FM_UART_PRES_N")
	)
	(segment
		(start 395.755114 -79.4004)
		(end 393.768834 -79.4004)
		(width 0.089408)
		(layer "In4.Cu")
		(net "FM_UART_PRES_N")
	)
	(segment
		(start 475.015306 -53.96357)
		(end 475.015306 -54.046628)
		(width 0.089408)
		(layer "In4.Cu")
		(net "FM_UART_PRES_N")
	)
	(segment
		(start 393.476734 -79.1083)
		(end 393.044426 -79.1083)
		(width 0.089408)
		(layer "In4.Cu")
		(net "FM_UART_PRES_N")
	)
	(segment
		(start 415.916872 -72.74433)
		(end 415.913062 -72.74052)
		(width 0.089408)
		(layer "In4.Cu")
		(net "FM_UART_PRES_N")
	)
	(segment
		(start 411.592776 -80.75168)
		(end 407.672032 -80.75168)
		(width 0.089408)
		(layer "In4.Cu")
		(net "FM_UART_PRES_N")
	)
	(segment
		(start 396.81912 -80.464406)
		(end 395.755114 -79.4004)
		(width 0.089408)
		(layer "In4.Cu")
		(net "FM_UART_PRES_N")
	)
	(segment
		(start 479.067622 -51.354736)
		(end 478.51441 -51.907948)
		(width 0.089408)
		(layer "In4.Cu")
		(net "FM_UART_PRES_N")
	)
	(segment
		(start 416.36188 -72.74433)
		(end 415.916872 -72.74433)
		(width 0.089408)
		(layer "In4.Cu")
		(net "FM_UART_PRES_N")
	)
	(segment
		(start 463.860896 -62.543944)
		(end 458.105764 -62.543944)
		(width 0.089408)
		(layer "In4.Cu")
		(net "FM_UART_PRES_N")
	)
	(segment
		(start 386.390388 -82.551016)
		(end 380.46406 -82.551016)
		(width 0.089408)
		(layer "In4.Cu")
		(net "FM_UART_PRES_N")
	)
	(segment
		(start 413.928052 -78.416404)
		(end 411.592776 -80.75168)
		(width 0.089408)
		(layer "In4.Cu")
		(net "FM_UART_PRES_N")
	)
	(segment
		(start 465.241386 -55.222648)
		(end 465.241386 -61.163454)
		(width 0.089408)
		(layer "In4.Cu")
		(net "FM_UART_PRES_N")
	)
	(segment
		(start 415.581338 -72.74052)
		(end 415.577528 -72.74433)
		(width 0.089408)
		(layer "In4.Cu")
		(net "FM_UART_PRES_N")
	)
	(segment
		(start 479.067622 -51.354736)
		(end 479.067622 -50.403252)
		(width 0.089408)
		(layer "In11.Cu")
		(net "FM_UART_PRES_N")
	)
	(segment
		(start 472.054936 -2.257044)
		(end 470.372948 -2.257044)
		(width 0.089408)
		(layer "In11.Cu")
		(net "FM_UART_PRES_N")
	)
	(segment
		(start 475.826836 -44.441618)
		(end 478.447608 -41.820846)
		(width 0.089408)
		(layer "In11.Cu")
		(net "FM_UART_PRES_N")
	)
	(segment
		(start 477.965516 -33.99536)
		(end 477.019112 -33.048956)
		(width 0.089408)
		(layer "In11.Cu")
		(net "FM_UART_PRES_N")
	)
	(segment
		(start 381.806958 -85.439758)
		(end 381.806958 -86.98738)
		(width 0.089408)
		(layer "In11.Cu")
		(net "FM_UART_PRES_N")
	)
	(segment
		(start 464.085432 2.639822)
		(end 464.085432 3.846576)
		(width 0.089408)
		(layer "In11.Cu")
		(net "FM_UART_PRES_N")
	)
	(segment
		(start 469.55583 -2.027428)
		(end 467.727284 -0.198882)
		(width 0.089408)
		(layer "In11.Cu")
		(net "FM_UART_PRES_N")
	)
	(segment
		(start 474.880432 -12.70254)
		(end 476.11157 -11.471402)
		(width 0.089408)
		(layer "In11.Cu")
		(net "FM_UART_PRES_N")
	)
	(segment
		(start 476.11157 -11.471402)
		(end 476.11157 -10.584942)
		(width 0.089408)
		(layer "In11.Cu")
		(net "FM_UART_PRES_N")
	)
	(segment
		(start 476.111316 -8.462264)
		(end 476.57258 -8.001)
		(width 0.089408)
		(layer "In11.Cu")
		(net "FM_UART_PRES_N")
	)
	(segment
		(start 474.967808 -27.047952)
		(end 474.967808 -26.104596)
		(width 0.089408)
		(layer "In11.Cu")
		(net "FM_UART_PRES_N")
	)
	(segment
		(start 478.447608 -38.57752)
		(end 477.965516 -38.095428)
		(width 0.089408)
		(layer "In11.Cu")
		(net "FM_UART_PRES_N")
	)
	(segment
		(start 465.3407 1.384554)
		(end 464.085432 2.639822)
		(width 0.089408)
		(layer "In11.Cu")
		(net "FM_UART_PRES_N")
	)
	(segment
		(start 474.109796 -4.311904)
		(end 472.054936 -2.257044)
		(width 0.089408)
		(layer "In11.Cu")
		(net "FM_UART_PRES_N")
	)
	(segment
		(start 476.111316 -10.584688)
		(end 476.111316 -8.462264)
		(width 0.089408)
		(layer "In11.Cu")
		(net "FM_UART_PRES_N")
	)
	(segment
		(start 380.04496 -84.3153)
		(end 380.6825 -84.3153)
		(width 0.089408)
		(layer "In11.Cu")
		(net "FM_UART_PRES_N")
	)
	(segment
		(start 476.57258 -7.023354)
		(end 475.603824 -6.054598)
		(width 0.089408)
		(layer "In11.Cu")
		(net "FM_UART_PRES_N")
	)
	(segment
		(start 474.967808 -26.104596)
		(end 475.815406 -25.256998)
		(width 0.089408)
		(layer "In11.Cu")
		(net "FM_UART_PRES_N")
	)
	(segment
		(start 477.965516 -38.095428)
		(end 477.965516 -33.99536)
		(width 0.089408)
		(layer "In11.Cu")
		(net "FM_UART_PRES_N")
	)
	(segment
		(start 381.08382 -90.276934)
		(end 380.554484 -90.80627)
		(width 0.089408)
		(layer "In11.Cu")
		(net "FM_UART_PRES_N")
	)
	(segment
		(start 464.085432 3.846576)
		(end 462.891124 5.040884)
		(width 0.089408)
		(layer "In11.Cu")
		(net "FM_UART_PRES_N")
	)
	(segment
		(start 474.248734 -4.311904)
		(end 474.109796 -4.311904)
		(width 0.089408)
		(layer "In11.Cu")
		(net "FM_UART_PRES_N")
	)
	(segment
		(start 479.067622 -50.403252)
		(end 478.83953 -50.17516)
		(width 0.089408)
		(layer "In11.Cu")
		(net "FM_UART_PRES_N")
	)
	(segment
		(start 465.3407 0.6985)
		(end 465.3407 1.384554)
		(width 0.089408)
		(layer "In11.Cu")
		(net "FM_UART_PRES_N")
	)
	(segment
		(start 475.815406 -25.256998)
		(end 475.815406 -18.553938)
		(width 0.089408)
		(layer "In11.Cu")
		(net "FM_UART_PRES_N")
	)
	(segment
		(start 380.6825 -84.3153)
		(end 381.806958 -85.439758)
		(width 0.089408)
		(layer "In11.Cu")
		(net "FM_UART_PRES_N")
	)
	(segment
		(start 475.603824 -6.054598)
		(end 475.603824 -5.666994)
		(width 0.089408)
		(layer "In11.Cu")
		(net "FM_UART_PRES_N")
	)
	(segment
		(start 467.727284 -0.198882)
		(end 466.238082 -0.198882)
		(width 0.089408)
		(layer "In11.Cu")
		(net "FM_UART_PRES_N")
	)
	(segment
		(start 470.143332 -2.027428)
		(end 469.55583 -2.027428)
		(width 0.089408)
		(layer "In11.Cu")
		(net "FM_UART_PRES_N")
	)
	(segment
		(start 476.11157 -10.584942)
		(end 476.111316 -10.584688)
		(width 0.089408)
		(layer "In11.Cu")
		(net "FM_UART_PRES_N")
	)
	(segment
		(start 477.019112 -29.099256)
		(end 474.967808 -27.047952)
		(width 0.089408)
		(layer "In11.Cu")
		(net "FM_UART_PRES_N")
	)
	(segment
		(start 474.880432 -17.618964)
		(end 474.880432 -12.70254)
		(width 0.089408)
		(layer "In11.Cu")
		(net "FM_UART_PRES_N")
	)
	(segment
		(start 475.826836 -45.36567)
		(end 475.826836 -44.441618)
		(width 0.089408)
		(layer "In11.Cu")
		(net "FM_UART_PRES_N")
	)
	(segment
		(start 470.372948 -2.257044)
		(end 470.143332 -2.027428)
		(width 0.089408)
		(layer "In11.Cu")
		(net "FM_UART_PRES_N")
	)
	(segment
		(start 478.83953 -50.17516)
		(end 477.93529 -50.17516)
		(width 0.089408)
		(layer "In11.Cu")
		(net "FM_UART_PRES_N")
	)
	(segment
		(start 381.08382 -87.710518)
		(end 381.08382 -90.276934)
		(width 0.089408)
		(layer "In11.Cu")
		(net "FM_UART_PRES_N")
	)
	(segment
		(start 379.10516 -83.3755)
		(end 380.04496 -84.3153)
		(width 0.089408)
		(layer "In11.Cu")
		(net "FM_UART_PRES_N")
	)
	(segment
		(start 477.5454 -47.084234)
		(end 475.826836 -45.36567)
		(width 0.089408)
		(layer "In11.Cu")
		(net "FM_UART_PRES_N")
	)
	(segment
		(start 466.238082 -0.198882)
		(end 465.3407 0.6985)
		(width 0.089408)
		(layer "In11.Cu")
		(net "FM_UART_PRES_N")
	)
	(segment
		(start 475.815406 -18.553938)
		(end 474.880432 -17.618964)
		(width 0.089408)
		(layer "In11.Cu")
		(net "FM_UART_PRES_N")
	)
	(segment
		(start 460.8449 5.040884)
		(end 459.614016 3.81)
		(width 0.089408)
		(layer "In11.Cu")
		(net "FM_UART_PRES_N")
	)
	(segment
		(start 478.447608 -41.820846)
		(end 478.447608 -38.57752)
		(width 0.089408)
		(layer "In11.Cu")
		(net "FM_UART_PRES_N")
	)
	(segment
		(start 381.806958 -86.98738)
		(end 381.08382 -87.710518)
		(width 0.089408)
		(layer "In11.Cu")
		(net "FM_UART_PRES_N")
	)
	(segment
		(start 477.93529 -50.17516)
		(end 477.5454 -49.78527)
		(width 0.089408)
		(layer "In11.Cu")
		(net "FM_UART_PRES_N")
	)
	(segment
		(start 477.5454 -49.78527)
		(end 477.5454 -47.084234)
		(width 0.089408)
		(layer "In11.Cu")
		(net "FM_UART_PRES_N")
	)
	(segment
		(start 476.57258 -8.001)
		(end 476.57258 -7.023354)
		(width 0.089408)
		(layer "In11.Cu")
		(net "FM_UART_PRES_N")
	)
	(segment
		(start 462.891124 5.040884)
		(end 460.8449 5.040884)
		(width 0.089408)
		(layer "In11.Cu")
		(net "FM_UART_PRES_N")
	)
	(segment
		(start 475.603824 -5.666994)
		(end 474.248734 -4.311904)
		(width 0.089408)
		(layer "In11.Cu")
		(net "FM_UART_PRES_N")
	)
	(segment
		(start 477.019112 -33.048956)
		(end 477.019112 -29.099256)
		(width 0.089408)
		(layer "In11.Cu")
		(net "FM_UART_PRES_N")
	)
	(segment
		(start 416.3822 -110.617)
		(end 416.433 -110.6678)
		(width 0.10795)
		(layer "F.Cu")
		(net "FM_PCH_PLD_DATA_R")
	)
	(segment
		(start 398.13865 -112.660684)
		(end 397.64335 -112.43056)
		(width 0.10795)
		(layer "F.Cu")
		(net "FM_PCH_PLD_DATA_R")
	)
	(segment
		(start 415.7345 -110.617)
		(end 416.3822 -110.617)
		(width 0.10795)
		(layer "F.Cu")
		(net "FM_PCH_PLD_DATA_R")
	)
	(via
		(at 416.433 -110.6678)
		(size 0.508)
		(drill 0.254)
		(layers "F.Cu" "B.Cu")
		(net "FM_PCH_PLD_DATA_R")
	)
	(via
		(at 398.13865 -112.660684)
		(size 0.508)
		(drill 0.254)
		(layers "F.Cu" "B.Cu")
		(net "FM_PCH_PLD_DATA_R")
	)
	(segment
		(start 409.782264 -111.208312)
		(end 411.580076 -109.4105)
		(width 0.089408)
		(layer "In9.Cu")
		(net "FM_PCH_PLD_DATA_R")
	)
	(segment
		(start 416.2044 -110.6678)
		(end 416.433 -110.6678)
		(width 0.089408)
		(layer "In9.Cu")
		(net "FM_PCH_PLD_DATA_R")
	)
	(segment
		(start 401.566888 -112.570514)
		(end 402.848826 -111.288576)
		(width 0.089408)
		(layer "In9.Cu")
		(net "FM_PCH_PLD_DATA_R")
	)
	(segment
		(start 414.9471 -109.4105)
		(end 416.2044 -110.6678)
		(width 0.089408)
		(layer "In9.Cu")
		(net "FM_PCH_PLD_DATA_R")
	)
	(segment
		(start 409.524708 -111.208312)
		(end 409.782264 -111.208312)
		(width 0.089408)
		(layer "In9.Cu")
		(net "FM_PCH_PLD_DATA_R")
	)
	(segment
		(start 409.423108 -111.309912)
		(end 409.524708 -111.208312)
		(width 0.089408)
		(layer "In9.Cu")
		(net "FM_PCH_PLD_DATA_R")
	)
	(segment
		(start 402.848826 -111.288576)
		(end 405.41448 -111.288576)
		(width 0.089408)
		(layer "In9.Cu")
		(net "FM_PCH_PLD_DATA_R")
	)
	(segment
		(start 401.202398 -112.570514)
		(end 401.566888 -112.570514)
		(width 0.089408)
		(layer "In9.Cu")
		(net "FM_PCH_PLD_DATA_R")
	)
	(segment
		(start 400.844512 -112.9284)
		(end 401.202398 -112.570514)
		(width 0.0889)
		(layer "In9.Cu")
		(net "FM_PCH_PLD_DATA_R")
	)
	(segment
		(start 405.435816 -111.309912)
		(end 409.423108 -111.309912)
		(width 0.089408)
		(layer "In9.Cu")
		(net "FM_PCH_PLD_DATA_R")
	)
	(segment
		(start 405.41448 -111.288576)
		(end 405.435816 -111.309912)
		(width 0.089408)
		(layer "In9.Cu")
		(net "FM_PCH_PLD_DATA_R")
	)
	(segment
		(start 411.580076 -109.4105)
		(end 414.9471 -109.4105)
		(width 0.089408)
		(layer "In9.Cu")
		(net "FM_PCH_PLD_DATA_R")
	)
	(segment
		(start 399.62455 -112.9284)
		(end 400.844512 -112.9284)
		(width 0.0889)
		(layer "In9.Cu")
		(net "FM_PCH_PLD_DATA_R")
	)
	(arc
		(start 398.929352 -113.007394)
		(mid 399.12925 -113.060893)
		(end 399.329148 -113.007394)
		(width 0.0889)
		(layer "In9.Cu")
		(net "FM_PCH_PLD_DATA_R")
	)
	(arc
		(start 398.13865 -112.660684)
		(mid 398.543525 -112.812318)
		(end 398.929352 -113.007394)
		(width 0.0889)
		(layer "In9.Cu")
		(net "FM_PCH_PLD_DATA_R")
	)
	(arc
		(start 399.329148 -113.007394)
		(mid 399.471654 -112.948474)
		(end 399.62455 -112.9284)
		(width 0.0889)
		(layer "In9.Cu")
		(net "FM_PCH_PLD_DATA_R")
	)
	(segment
		(start 417.43122 -109.11332)
		(end 417.58616 -108.95838)
		(width 0.10795)
		(layer "F.Cu")
		(net "FM_CPU_CATERR_DLY_LVT3_N")
	)
	(segment
		(start 417.58616 -108.95838)
		(end 418.01288 -108.95838)
		(width 0.10795)
		(layer "F.Cu")
		(net "FM_CPU_CATERR_DLY_LVT3_N")
	)
	(segment
		(start 418.01288 -108.95838)
		(end 418.3888 -109.3343)
		(width 0.10795)
		(layer "F.Cu")
		(net "FM_CPU_CATERR_DLY_LVT3_N")
	)
	(segment
		(start 417.43122 -110.30712)
		(end 417.43122 -109.11332)
		(width 0.10795)
		(layer "F.Cu")
		(net "FM_CPU_CATERR_DLY_LVT3_N")
	)
	(segment
		(start 378.344684 -71.095108)
		(end 377.944888 -71.494904)
		(width 0.1016)
		(layer "F.Cu")
		(net "FM_CPU_CATERR_DLY_LVT3_N")
	)
	(via
		(at 417.58616 -108.95838)
		(size 0.762)
		(drill 0.381)
		(layers "F.Cu" "B.Cu")
		(net "FM_CPU_CATERR_DLY_LVT3_N")
	)
	(via
		(at 418.3888 -109.3343)
		(size 0.508)
		(drill 0.254)
		(layers "F.Cu" "B.Cu")
		(net "FM_CPU_CATERR_DLY_LVT3_N")
	)
	(via
		(at 423.247566 -62.265306)
		(size 0.508)
		(drill 0.254)
		(layers "F.Cu" "B.Cu")
		(net "FM_CPU_CATERR_DLY_LVT3_N")
	)
	(via
		(at 378.344684 -71.095108)
		(size 0.4572)
		(drill 0.2032)
		(layers "F.Cu" "B.Cu")
		(net "FM_CPU_CATERR_DLY_LVT3_N")
	)
	(segment
		(start 419.580314 -75.01128)
		(end 419.58006 -75.011026)
		(width 0.089408)
		(layer "In2.Cu")
		(net "FM_CPU_CATERR_DLY_LVT3_N")
	)
	(segment
		(start 419.579806 -76.467462)
		(end 419.579806 -76.331064)
		(width 0.089408)
		(layer "In2.Cu")
		(net "FM_CPU_CATERR_DLY_LVT3_N")
	)
	(segment
		(start 419.580314 -76.330556)
		(end 419.580314 -75.01128)
		(width 0.089408)
		(layer "In2.Cu")
		(net "FM_CPU_CATERR_DLY_LVT3_N")
	)
	(segment
		(start 422.833292 -62.265306)
		(end 423.247566 -62.265306)
		(width 0.089408)
		(layer "In2.Cu")
		(net "FM_CPU_CATERR_DLY_LVT3_N")
	)
	(segment
		(start 418.977318 -86.766146)
		(end 418.977064 -86.765892)
		(width 0.089408)
		(layer "In2.Cu")
		(net "FM_CPU_CATERR_DLY_LVT3_N")
	)
	(segment
		(start 418.532564 -107.208574)
		(end 418.532564 -95.24619)
		(width 0.089408)
		(layer "In2.Cu")
		(net "FM_CPU_CATERR_DLY_LVT3_N")
	)
	(segment
		(start 422.314116 -62.784482)
		(end 422.833292 -62.265306)
		(width 0.089408)
		(layer "In2.Cu")
		(net "FM_CPU_CATERR_DLY_LVT3_N")
	)
	(segment
		(start 420.570914 -88.758776)
		(end 418.977318 -87.16518)
		(width 0.089408)
		(layer "In2.Cu")
		(net "FM_CPU_CATERR_DLY_LVT3_N")
	)
	(segment
		(start 420.570914 -93.20784)
		(end 420.570914 -88.758776)
		(width 0.089408)
		(layer "In2.Cu")
		(net "FM_CPU_CATERR_DLY_LVT3_N")
	)
	(segment
		(start 418.532564 -95.24619)
		(end 420.570914 -93.20784)
		(width 0.089408)
		(layer "In2.Cu")
		(net "FM_CPU_CATERR_DLY_LVT3_N")
	)
	(segment
		(start 418.977318 -81.977738)
		(end 418.977064 -81.977484)
		(width 0.089408)
		(layer "In2.Cu")
		(net "FM_CPU_CATERR_DLY_LVT3_N")
	)
	(segment
		(start 422.312592 -62.784482)
		(end 422.314116 -62.784482)
		(width 0.089408)
		(layer "In2.Cu")
		(net "FM_CPU_CATERR_DLY_LVT3_N")
	)
	(segment
		(start 419.58006 -75.011026)
		(end 419.58006 -74.853038)
		(width 0.089408)
		(layer "In2.Cu")
		(net "FM_CPU_CATERR_DLY_LVT3_N")
	)
	(segment
		(start 419.811962 -65.527428)
		(end 419.811962 -64.549528)
		(width 0.089408)
		(layer "In2.Cu")
		(net "FM_CPU_CATERR_DLY_LVT3_N")
	)
	(segment
		(start 418.977064 -86.765892)
		(end 418.977064 -83.455764)
		(width 0.089408)
		(layer "In2.Cu")
		(net "FM_CPU_CATERR_DLY_LVT3_N")
	)
	(segment
		(start 418.977064 -77.070204)
		(end 419.579806 -76.467462)
		(width 0.089408)
		(layer "In2.Cu")
		(net "FM_CPU_CATERR_DLY_LVT3_N")
	)
	(segment
		(start 418.3888 -107.352338)
		(end 418.532564 -107.208574)
		(width 0.089408)
		(layer "In2.Cu")
		(net "FM_CPU_CATERR_DLY_LVT3_N")
	)
	(segment
		(start 421.45077 -62.91072)
		(end 422.186354 -62.91072)
		(width 0.089408)
		(layer "In2.Cu")
		(net "FM_CPU_CATERR_DLY_LVT3_N")
	)
	(segment
		(start 418.977318 -83.45551)
		(end 418.977318 -81.977738)
		(width 0.089408)
		(layer "In2.Cu")
		(net "FM_CPU_CATERR_DLY_LVT3_N")
	)
	(segment
		(start 422.186354 -62.91072)
		(end 422.312592 -62.784482)
		(width 0.089408)
		(layer "In2.Cu")
		(net "FM_CPU_CATERR_DLY_LVT3_N")
	)
	(segment
		(start 419.579806 -71.894192)
		(end 419.811708 -71.66229)
		(width 0.089408)
		(layer "In2.Cu")
		(net "FM_CPU_CATERR_DLY_LVT3_N")
	)
	(segment
		(start 419.811708 -65.527682)
		(end 419.811962 -65.527428)
		(width 0.089408)
		(layer "In2.Cu")
		(net "FM_CPU_CATERR_DLY_LVT3_N")
	)
	(segment
		(start 419.811962 -64.549528)
		(end 421.45077 -62.91072)
		(width 0.089408)
		(layer "In2.Cu")
		(net "FM_CPU_CATERR_DLY_LVT3_N")
	)
	(segment
		(start 418.3888 -109.3343)
		(end 418.3888 -107.352338)
		(width 0.089408)
		(layer "In2.Cu")
		(net "FM_CPU_CATERR_DLY_LVT3_N")
	)
	(segment
		(start 419.58006 -74.853038)
		(end 419.579806 -74.852784)
		(width 0.089408)
		(layer "In2.Cu")
		(net "FM_CPU_CATERR_DLY_LVT3_N")
	)
	(segment
		(start 419.579806 -76.331064)
		(end 419.580314 -76.330556)
		(width 0.089408)
		(layer "In2.Cu")
		(net "FM_CPU_CATERR_DLY_LVT3_N")
	)
	(segment
		(start 419.811708 -71.66229)
		(end 419.811708 -65.527682)
		(width 0.089408)
		(layer "In2.Cu")
		(net "FM_CPU_CATERR_DLY_LVT3_N")
	)
	(segment
		(start 419.579806 -74.852784)
		(end 419.579806 -71.894192)
		(width 0.089408)
		(layer "In2.Cu")
		(net "FM_CPU_CATERR_DLY_LVT3_N")
	)
	(segment
		(start 418.977064 -83.455764)
		(end 418.977318 -83.45551)
		(width 0.089408)
		(layer "In2.Cu")
		(net "FM_CPU_CATERR_DLY_LVT3_N")
	)
	(segment
		(start 418.977064 -81.977484)
		(end 418.977064 -77.070204)
		(width 0.089408)
		(layer "In2.Cu")
		(net "FM_CPU_CATERR_DLY_LVT3_N")
	)
	(segment
		(start 418.977318 -87.16518)
		(end 418.977318 -86.766146)
		(width 0.089408)
		(layer "In2.Cu")
		(net "FM_CPU_CATERR_DLY_LVT3_N")
	)
	(segment
		(start 393.664948 -71.720456)
		(end 394.458698 -72.514206)
		(width 0.089408)
		(layer "In4.Cu")
		(net "FM_CPU_CATERR_DLY_LVT3_N")
	)
	(segment
		(start 422.22928 -62.91072)
		(end 422.874694 -62.265306)
		(width 0.089408)
		(layer "In4.Cu")
		(net "FM_CPU_CATERR_DLY_LVT3_N")
	)
	(segment
		(start 395.669008 -72.514206)
		(end 395.788896 -72.394318)
		(width 0.089408)
		(layer "In4.Cu")
		(net "FM_CPU_CATERR_DLY_LVT3_N")
	)
	(segment
		(start 422.874694 -62.265306)
		(end 423.247566 -62.265306)
		(width 0.089408)
		(layer "In4.Cu")
		(net "FM_CPU_CATERR_DLY_LVT3_N")
	)
	(segment
		(start 414.296606 -69.44233)
		(end 415.587942 -68.150994)
		(width 0.089408)
		(layer "In4.Cu")
		(net "FM_CPU_CATERR_DLY_LVT3_N")
	)
	(segment
		(start 386.211318 -71.720456)
		(end 393.664948 -71.720456)
		(width 0.089408)
		(layer "In4.Cu")
		(net "FM_CPU_CATERR_DLY_LVT3_N")
	)
	(segment
		(start 415.765996 -68.150994)
		(end 416.664902 -67.252088)
		(width 0.089408)
		(layer "In4.Cu")
		(net "FM_CPU_CATERR_DLY_LVT3_N")
	)
	(segment
		(start 413.65424 -69.44233)
		(end 414.296606 -69.44233)
		(width 0.089408)
		(layer "In4.Cu")
		(net "FM_CPU_CATERR_DLY_LVT3_N")
	)
	(segment
		(start 380.793752 -71.893684)
		(end 381.799592 -70.887844)
		(width 0.089408)
		(layer "In4.Cu")
		(net "FM_CPU_CATERR_DLY_LVT3_N")
	)
	(segment
		(start 397.159226 -71.023988)
		(end 408.813762 -71.023988)
		(width 0.089408)
		(layer "In4.Cu")
		(net "FM_CPU_CATERR_DLY_LVT3_N")
	)
	(segment
		(start 381.799592 -70.887844)
		(end 385.378706 -70.887844)
		(width 0.089408)
		(layer "In4.Cu")
		(net "FM_CPU_CATERR_DLY_LVT3_N")
	)
	(segment
		(start 408.813762 -71.023988)
		(end 409.228036 -70.609714)
		(width 0.089408)
		(layer "In4.Cu")
		(net "FM_CPU_CATERR_DLY_LVT3_N")
	)
	(segment
		(start 395.788896 -72.394318)
		(end 395.788896 -72.300338)
		(width 0.089408)
		(layer "In4.Cu")
		(net "FM_CPU_CATERR_DLY_LVT3_N")
	)
	(segment
		(start 396.023338 -72.065896)
		(end 396.117318 -72.065896)
		(width 0.089408)
		(layer "In4.Cu")
		(net "FM_CPU_CATERR_DLY_LVT3_N")
	)
	(segment
		(start 409.228036 -70.609714)
		(end 411.347412 -70.609714)
		(width 0.089408)
		(layer "In4.Cu")
		(net "FM_CPU_CATERR_DLY_LVT3_N")
	)
	(segment
		(start 378.344684 -71.095108)
		(end 379.14326 -71.893684)
		(width 0.089408)
		(layer "In4.Cu")
		(net "FM_CPU_CATERR_DLY_LVT3_N")
	)
	(segment
		(start 416.664902 -67.036188)
		(end 420.79037 -62.91072)
		(width 0.089408)
		(layer "In4.Cu")
		(net "FM_CPU_CATERR_DLY_LVT3_N")
	)
	(segment
		(start 395.788896 -72.300338)
		(end 396.023338 -72.065896)
		(width 0.089408)
		(layer "In4.Cu")
		(net "FM_CPU_CATERR_DLY_LVT3_N")
	)
	(segment
		(start 416.664902 -67.252088)
		(end 416.664902 -67.036188)
		(width 0.089408)
		(layer "In4.Cu")
		(net "FM_CPU_CATERR_DLY_LVT3_N")
	)
	(segment
		(start 394.458698 -72.514206)
		(end 395.669008 -72.514206)
		(width 0.089408)
		(layer "In4.Cu")
		(net "FM_CPU_CATERR_DLY_LVT3_N")
	)
	(segment
		(start 411.347412 -70.609714)
		(end 411.828996 -70.128638)
		(width 0.089408)
		(layer "In4.Cu")
		(net "FM_CPU_CATERR_DLY_LVT3_N")
	)
	(segment
		(start 411.828996 -70.128638)
		(end 412.967932 -70.128638)
		(width 0.089408)
		(layer "In4.Cu")
		(net "FM_CPU_CATERR_DLY_LVT3_N")
	)
	(segment
		(start 385.378706 -70.887844)
		(end 386.211318 -71.720456)
		(width 0.089408)
		(layer "In4.Cu")
		(net "FM_CPU_CATERR_DLY_LVT3_N")
	)
	(segment
		(start 396.117318 -72.065896)
		(end 397.159226 -71.023988)
		(width 0.089408)
		(layer "In4.Cu")
		(net "FM_CPU_CATERR_DLY_LVT3_N")
	)
	(segment
		(start 412.967932 -70.128638)
		(end 413.65424 -69.44233)
		(width 0.089408)
		(layer "In4.Cu")
		(net "FM_CPU_CATERR_DLY_LVT3_N")
	)
	(segment
		(start 415.587942 -68.150994)
		(end 415.765996 -68.150994)
		(width 0.089408)
		(layer "In4.Cu")
		(net "FM_CPU_CATERR_DLY_LVT3_N")
	)
	(segment
		(start 420.79037 -62.91072)
		(end 422.22928 -62.91072)
		(width 0.089408)
		(layer "In4.Cu")
		(net "FM_CPU_CATERR_DLY_LVT3_N")
	)
	(segment
		(start 379.14326 -71.893684)
		(end 380.793752 -71.893684)
		(width 0.089408)
		(layer "In4.Cu")
		(net "FM_CPU_CATERR_DLY_LVT3_N")
	)
	(segment
		(start 414.8455 -115.316)
		(end 414.8455 -114.935)
		(width 0.10795)
		(layer "F.Cu")
		(net "FM_CPLD_ADR_TRIGGER_R_N")
	)
	(segment
		(start 416.492944 -115.075716)
		(end 416.339782 -115.075716)
		(width 0.10795)
		(layer "F.Cu")
		(net "FM_CPLD_ADR_TRIGGER_R_N")
	)
	(segment
		(start 415.972498 -115.443)
		(end 414.9725 -115.443)
		(width 0.10795)
		(layer "F.Cu")
		(net "FM_CPLD_ADR_TRIGGER_R_N")
	)
	(segment
		(start 414.9725 -115.443)
		(end 414.8455 -115.316)
		(width 0.10795)
		(layer "F.Cu")
		(net "FM_CPLD_ADR_TRIGGER_R_N")
	)
	(segment
		(start 416.514788 -115.09756)
		(end 416.492944 -115.075716)
		(width 0.10795)
		(layer "F.Cu")
		(net "FM_CPLD_ADR_TRIGGER_R_N")
	)
	(segment
		(start 394.17625 -116.72316)
		(end 394.67155 -116.953284)
		(width 0.10795)
		(layer "F.Cu")
		(net "FM_CPLD_ADR_TRIGGER_R_N")
	)
	(segment
		(start 416.339782 -115.075716)
		(end 415.972498 -115.443)
		(width 0.10795)
		(layer "F.Cu")
		(net "FM_CPLD_ADR_TRIGGER_R_N")
	)
	(via
		(at 394.67155 -116.953284)
		(size 0.508)
		(drill 0.254)
		(layers "F.Cu" "B.Cu")
		(net "FM_CPLD_ADR_TRIGGER_R_N")
	)
	(via
		(at 416.514788 -115.09756)
		(size 0.508)
		(drill 0.254)
		(layers "F.Cu" "B.Cu")
		(net "FM_CPLD_ADR_TRIGGER_R_N")
	)
	(segment
		(start 408.639518 -119.029226)
		(end 409.355544 -118.3132)
		(width 0.089408)
		(layer "In9.Cu")
		(net "FM_CPLD_ADR_TRIGGER_R_N")
	)
	(segment
		(start 399.1864 -116.893086)
		(end 401.32254 -119.029226)
		(width 0.089408)
		(layer "In9.Cu")
		(net "FM_CPLD_ADR_TRIGGER_R_N")
	)
	(segment
		(start 399.1864 -116.78539)
		(end 399.1864 -116.893086)
		(width 0.089408)
		(layer "In9.Cu")
		(net "FM_CPLD_ADR_TRIGGER_R_N")
	)
	(segment
		(start 394.67155 -116.953284)
		(end 395.009624 -116.953284)
		(width 0.0889)
		(layer "In9.Cu")
		(net "FM_CPLD_ADR_TRIGGER_R_N")
	)
	(segment
		(start 410.184854 -118.3132)
		(end 411.619954 -116.8781)
		(width 0.0889)
		(layer "In9.Cu")
		(net "FM_CPLD_ADR_TRIGGER_R_N")
	)
	(segment
		(start 415.077148 -116.5352)
		(end 416.514788 -115.09756)
		(width 0.089408)
		(layer "In9.Cu")
		(net "FM_CPLD_ADR_TRIGGER_R_N")
	)
	(segment
		(start 396.2527 -116.974874)
		(end 396.2527 -116.942108)
		(width 0.0889)
		(layer "In9.Cu")
		(net "FM_CPLD_ADR_TRIGGER_R_N")
	)
	(segment
		(start 409.355544 -118.3132)
		(end 410.184854 -118.3132)
		(width 0.0889)
		(layer "In9.Cu")
		(net "FM_CPLD_ADR_TRIGGER_R_N")
	)
	(segment
		(start 395.009624 -116.953284)
		(end 395.074648 -117.018308)
		(width 0.0889)
		(layer "In9.Cu")
		(net "FM_CPLD_ADR_TRIGGER_R_N")
	)
	(segment
		(start 413.0167 -116.5352)
		(end 415.077148 -116.5352)
		(width 0.089408)
		(layer "In9.Cu")
		(net "FM_CPLD_ADR_TRIGGER_R_N")
	)
	(segment
		(start 401.32254 -119.029226)
		(end 408.639518 -119.029226)
		(width 0.089408)
		(layer "In9.Cu")
		(net "FM_CPLD_ADR_TRIGGER_R_N")
	)
	(segment
		(start 412.6738 -116.8781)
		(end 413.0167 -116.5352)
		(width 0.089408)
		(layer "In9.Cu")
		(net "FM_CPLD_ADR_TRIGGER_R_N")
	)
	(segment
		(start 411.619954 -116.8781)
		(end 412.6738 -116.8781)
		(width 0.0889)
		(layer "In9.Cu")
		(net "FM_CPLD_ADR_TRIGGER_R_N")
	)
	(segment
		(start 399.085054 -116.684044)
		(end 399.1864 -116.78539)
		(width 0.0889)
		(layer "In9.Cu")
		(net "FM_CPLD_ADR_TRIGGER_R_N")
	)
	(arc
		(start 397.843248 -116.606574)
		(mid 398.13865 -116.685705)
		(end 398.434052 -116.606574)
		(width 0.0889)
		(layer "In9.Cu")
		(net "FM_CPLD_ADR_TRIGGER_R_N")
	)
	(arc
		(start 396.452852 -116.606574)
		(mid 396.65275 -116.553075)
		(end 396.852648 -116.606574)
		(width 0.0889)
		(layer "In9.Cu")
		(net "FM_CPLD_ADR_TRIGGER_R_N")
	)
	(arc
		(start 396.852648 -116.606574)
		(mid 397.14805 -116.685705)
		(end 397.443452 -116.606574)
		(width 0.0889)
		(layer "In9.Cu")
		(net "FM_CPLD_ADR_TRIGGER_R_N")
	)
	(arc
		(start 395.957552 -117.465094)
		(mid 396.168416 -117.25809)
		(end 396.2527 -116.974874)
		(width 0.0889)
		(layer "In9.Cu")
		(net "FM_CPLD_ADR_TRIGGER_R_N")
	)
	(arc
		(start 397.443452 -116.606574)
		(mid 397.64335 -116.553075)
		(end 397.843248 -116.606574)
		(width 0.0889)
		(layer "In9.Cu")
		(net "FM_CPLD_ADR_TRIGGER_R_N")
	)
	(arc
		(start 395.366748 -117.465094)
		(mid 395.66215 -117.544225)
		(end 395.957552 -117.465094)
		(width 0.0889)
		(layer "In9.Cu")
		(net "FM_CPLD_ADR_TRIGGER_R_N")
	)
	(arc
		(start 398.833848 -116.606574)
		(mid 398.955088 -116.659458)
		(end 399.085054 -116.684044)
		(width 0.0889)
		(layer "In9.Cu")
		(net "FM_CPLD_ADR_TRIGGER_R_N")
	)
	(arc
		(start 395.074648 -117.018308)
		(mid 395.167356 -117.276578)
		(end 395.366748 -117.465094)
		(width 0.0889)
		(layer "In9.Cu")
		(net "FM_CPLD_ADR_TRIGGER_R_N")
	)
	(arc
		(start 398.434052 -116.606574)
		(mid 398.63395 -116.553075)
		(end 398.833848 -116.606574)
		(width 0.0889)
		(layer "In9.Cu")
		(net "FM_CPLD_ADR_TRIGGER_R_N")
	)
	(arc
		(start 396.2527 -116.942108)
		(mid 396.30905 -116.748258)
		(end 396.452852 -116.606574)
		(width 0.0889)
		(layer "In9.Cu")
		(net "FM_CPLD_ADR_TRIGGER_R_N")
	)
	(segment
		(start 404.248112 -113.746788)
		(end 405.177498 -114.676174)
		(width 0.10795)
		(layer "F.Cu")
		(net "FM_ADR_MODE_SEL_R")
	)
	(segment
		(start 405.177498 -114.676174)
		(end 406.991566 -114.676174)
		(width 0.10795)
		(layer "F.Cu")
		(net "FM_ADR_MODE_SEL_R")
	)
	(segment
		(start 401.400518 -112.749584)
		(end 401.94103 -112.749584)
		(width 0.0889)
		(layer "F.Cu")
		(net "FM_ADR_MODE_SEL_R")
	)
	(segment
		(start 407.0223 -114.64544)
		(end 407.11374 -114.554)
		(width 0.10795)
		(layer "F.Cu")
		(net "FM_ADR_MODE_SEL_R")
	)
	(segment
		(start 402.41982 -113.228374)
		(end 402.938234 -113.746788)
		(width 0.10795)
		(layer "F.Cu")
		(net "FM_ADR_MODE_SEL_R")
	)
	(segment
		(start 407.11374 -114.554)
		(end 407.8605 -114.554)
		(width 0.10795)
		(layer "F.Cu")
		(net "FM_ADR_MODE_SEL_R")
	)
	(segment
		(start 401.295108 -112.854994)
		(end 401.400518 -112.749584)
		(width 0.0889)
		(layer "F.Cu")
		(net "FM_ADR_MODE_SEL_R")
	)
	(segment
		(start 406.991566 -114.676174)
		(end 407.0223 -114.64544)
		(width 0.10795)
		(layer "F.Cu")
		(net "FM_ADR_MODE_SEL_R")
	)
	(segment
		(start 401.94103 -112.749584)
		(end 402.41982 -113.228374)
		(width 0.0889)
		(layer "F.Cu")
		(net "FM_ADR_MODE_SEL_R")
	)
	(segment
		(start 402.938234 -113.746788)
		(end 404.248112 -113.746788)
		(width 0.10795)
		(layer "F.Cu")
		(net "FM_ADR_MODE_SEL_R")
	)
	(via
		(at 407.0223 -114.64544)
		(size 0.762)
		(drill 0.381)
		(layers "F.Cu" "B.Cu")
		(net "FM_ADR_MODE_SEL_R")
	)
	(segment
		(start 424.19397 -24.506682)
		(end 424.06697 -24.633682)
		(width 0.10795)
		(layer "F.Cu")
		(net "FAN_PWM_OUT_SYS1")
	)
	(segment
		(start 424.712892 -23.98776)
		(end 424.712892 -21.590508)
		(width 0.10795)
		(layer "F.Cu")
		(net "FAN_PWM_OUT_SYS1")
	)
	(segment
		(start 421.918638 -26.90622)
		(end 421.49014 -27.334718)
		(width 0.10795)
		(layer "F.Cu")
		(net "FAN_PWM_OUT_SYS1")
	)
	(segment
		(start 422.67505 -25.624282)
		(end 421.918638 -26.380694)
		(width 0.10795)
		(layer "F.Cu")
		(net "FAN_PWM_OUT_SYS1")
	)
	(segment
		(start 423.874438 -24.633682)
		(end 422.883838 -25.624282)
		(width 0.10795)
		(layer "F.Cu")
		(net "FAN_PWM_OUT_SYS1")
	)
	(segment
		(start 421.918638 -26.380694)
		(end 421.918638 -26.90622)
		(width 0.10795)
		(layer "F.Cu")
		(net "FAN_PWM_OUT_SYS1")
	)
	(segment
		(start 424.19397 -24.506682)
		(end 424.712892 -23.98776)
		(width 0.10795)
		(layer "F.Cu")
		(net "FAN_PWM_OUT_SYS1")
	)
	(segment
		(start 424.712892 -21.590508)
		(end 425.577 -20.7264)
		(width 0.10795)
		(layer "F.Cu")
		(net "FAN_PWM_OUT_SYS1")
	)
	(segment
		(start 422.883838 -25.624282)
		(end 422.67505 -25.624282)
		(width 0.10795)
		(layer "F.Cu")
		(net "FAN_PWM_OUT_SYS1")
	)
	(segment
		(start 424.06697 -24.633682)
		(end 423.874438 -24.633682)
		(width 0.10795)
		(layer "F.Cu")
		(net "FAN_PWM_OUT_SYS1")
	)
	(via
		(at 406.401016 4.405884)
		(size 0.508)
		(drill 0.254)
		(layers "F.Cu" "B.Cu")
		(net "FAN_PWM_OUT_SYS1")
	)
	(via
		(at 469.017858 -8.74649)
		(size 0.508)
		(drill 0.254)
		(layers "F.Cu" "B.Cu")
		(net "FAN_PWM_OUT_SYS1")
	)
	(via
		(at 424.19397 -24.506682)
		(size 0.762)
		(drill 0.381)
		(layers "F.Cu" "B.Cu")
		(net "FAN_PWM_OUT_SYS1")
	)
	(via
		(at 425.577 -20.7264)
		(size 0.508)
		(drill 0.254)
		(layers "F.Cu" "B.Cu")
		(net "FAN_PWM_OUT_SYS1")
	)
	(segment
		(start 406.0698 4.074668)
		(end 406.0698 3.1242)
		(width 0.10795)
		(layer "B.Cu")
		(net "FAN_PWM_OUT_SYS1")
	)
	(segment
		(start 406.0698 3.1242)
		(end 406.211786 2.982214)
		(width 0.10795)
		(layer "B.Cu")
		(net "FAN_PWM_OUT_SYS1")
	)
	(segment
		(start 406.211786 2.982214)
		(end 406.8064 2.982214)
		(width 0.10795)
		(layer "B.Cu")
		(net "FAN_PWM_OUT_SYS1")
	)
	(segment
		(start 406.401016 4.405884)
		(end 406.0698 4.074668)
		(width 0.10795)
		(layer "B.Cu")
		(net "FAN_PWM_OUT_SYS1")
	)
	(segment
		(start 407.176732 5.1816)
		(end 406.401016 4.405884)
		(width 0.089408)
		(layer "In4.Cu")
		(net "FAN_PWM_OUT_SYS1")
	)
	(segment
		(start 469.017858 -8.74649)
		(end 468.980774 -8.709406)
		(width 0.089408)
		(layer "In4.Cu")
		(net "FAN_PWM_OUT_SYS1")
	)
	(segment
		(start 468.3252 -4.0132)
		(end 468.3252 -3.226054)
		(width 0.089408)
		(layer "In4.Cu")
		(net "FAN_PWM_OUT_SYS1")
	)
	(segment
		(start 468.980774 -8.709406)
		(end 468.980774 -8.364474)
		(width 0.089408)
		(layer "In4.Cu")
		(net "FAN_PWM_OUT_SYS1")
	)
	(segment
		(start 465.606892 -0.261112)
		(end 464.984592 0.361188)
		(width 0.089408)
		(layer "In4.Cu")
		(net "FAN_PWM_OUT_SYS1")
	)
	(segment
		(start 468.3252 -3.226054)
		(end 468.570818 -2.980436)
		(width 0.089408)
		(layer "In4.Cu")
		(net "FAN_PWM_OUT_SYS1")
	)
	(segment
		(start 464.984592 1.461008)
		(end 463.6262 2.8194)
		(width 0.089408)
		(layer "In4.Cu")
		(net "FAN_PWM_OUT_SYS1")
	)
	(segment
		(start 468.980774 -8.364474)
		(end 468.436452 -7.820152)
		(width 0.089408)
		(layer "In4.Cu")
		(net "FAN_PWM_OUT_SYS1")
	)
	(segment
		(start 468.436452 -7.820152)
		(end 468.436452 -4.124452)
		(width 0.089408)
		(layer "In4.Cu")
		(net "FAN_PWM_OUT_SYS1")
	)
	(segment
		(start 468.436452 -4.124452)
		(end 468.3252 -4.0132)
		(width 0.089408)
		(layer "In4.Cu")
		(net "FAN_PWM_OUT_SYS1")
	)
	(segment
		(start 463.6262 2.8194)
		(end 463.6262 4.3688)
		(width 0.089408)
		(layer "In4.Cu")
		(net "FAN_PWM_OUT_SYS1")
	)
	(segment
		(start 468.570818 -2.980436)
		(end 468.722964 -2.980436)
		(width 0.089408)
		(layer "In4.Cu")
		(net "FAN_PWM_OUT_SYS1")
	)
	(segment
		(start 462.8134 5.1816)
		(end 407.176732 5.1816)
		(width 0.089408)
		(layer "In4.Cu")
		(net "FAN_PWM_OUT_SYS1")
	)
	(segment
		(start 468.8586 -1.8034)
		(end 467.316312 -0.261112)
		(width 0.089408)
		(layer "In4.Cu")
		(net "FAN_PWM_OUT_SYS1")
	)
	(segment
		(start 463.6262 4.3688)
		(end 462.8134 5.1816)
		(width 0.089408)
		(layer "In4.Cu")
		(net "FAN_PWM_OUT_SYS1")
	)
	(segment
		(start 464.984592 0.361188)
		(end 464.984592 1.461008)
		(width 0.089408)
		(layer "In4.Cu")
		(net "FAN_PWM_OUT_SYS1")
	)
	(segment
		(start 468.722964 -2.980436)
		(end 468.8586 -2.8448)
		(width 0.089408)
		(layer "In4.Cu")
		(net "FAN_PWM_OUT_SYS1")
	)
	(segment
		(start 467.316312 -0.261112)
		(end 465.606892 -0.261112)
		(width 0.089408)
		(layer "In4.Cu")
		(net "FAN_PWM_OUT_SYS1")
	)
	(segment
		(start 468.8586 -2.8448)
		(end 468.8586 -1.8034)
		(width 0.089408)
		(layer "In4.Cu")
		(net "FAN_PWM_OUT_SYS1")
	)
	(segment
		(start 448.21221 -18.283428)
		(end 446.137792 -18.283428)
		(width 0.089408)
		(layer "In11.Cu")
		(net "FAN_PWM_OUT_SYS1")
	)
	(segment
		(start 428.793402 -20.297394)
		(end 428.31512 -20.297394)
		(width 0.089408)
		(layer "In11.Cu")
		(net "FAN_PWM_OUT_SYS1")
	)
	(segment
		(start 432.045618 -19.482816)
		(end 431.23485 -20.293584)
		(width 0.089408)
		(layer "In11.Cu")
		(net "FAN_PWM_OUT_SYS1")
	)
	(segment
		(start 439.900568 -18.747232)
		(end 438.942226 -19.705574)
		(width 0.089408)
		(layer "In11.Cu")
		(net "FAN_PWM_OUT_SYS1")
	)
	(segment
		(start 438.942226 -19.705574)
		(end 435.015132 -19.705574)
		(width 0.089408)
		(layer "In11.Cu")
		(net "FAN_PWM_OUT_SYS1")
	)
	(segment
		(start 449.993004 -16.84401)
		(end 449.993004 -18.139156)
		(width 0.089408)
		(layer "In11.Cu")
		(net "FAN_PWM_OUT_SYS1")
	)
	(segment
		(start 433.109624 -18.974562)
		(end 432.60137 -19.482816)
		(width 0.089408)
		(layer "In11.Cu")
		(net "FAN_PWM_OUT_SYS1")
	)
	(segment
		(start 469.017858 -8.74649)
		(end 468.549736 -8.74649)
		(width 0.089408)
		(layer "In11.Cu")
		(net "FAN_PWM_OUT_SYS1")
	)
	(segment
		(start 434.28412 -18.974562)
		(end 433.109624 -18.974562)
		(width 0.089408)
		(layer "In11.Cu")
		(net "FAN_PWM_OUT_SYS1")
	)
	(segment
		(start 451.844918 -14.992096)
		(end 449.993004 -16.84401)
		(width 0.089408)
		(layer "In11.Cu")
		(net "FAN_PWM_OUT_SYS1")
	)
	(segment
		(start 426.00118 -21.15058)
		(end 425.577 -20.7264)
		(width 0.089408)
		(layer "In11.Cu")
		(net "FAN_PWM_OUT_SYS1")
	)
	(segment
		(start 468.071454 -8.268208)
		(end 458.987398 -8.268208)
		(width 0.089408)
		(layer "In11.Cu")
		(net "FAN_PWM_OUT_SYS1")
	)
	(segment
		(start 445.673988 -18.747232)
		(end 439.900568 -18.747232)
		(width 0.089408)
		(layer "In11.Cu")
		(net "FAN_PWM_OUT_SYS1")
	)
	(segment
		(start 449.993004 -18.139156)
		(end 449.799456 -18.332704)
		(width 0.089408)
		(layer "In11.Cu")
		(net "FAN_PWM_OUT_SYS1")
	)
	(segment
		(start 451.844918 -12.918186)
		(end 451.844918 -14.992096)
		(width 0.089408)
		(layer "In11.Cu")
		(net "FAN_PWM_OUT_SYS1")
	)
	(segment
		(start 454.587356 -10.175748)
		(end 451.844918 -12.918186)
		(width 0.089408)
		(layer "In11.Cu")
		(net "FAN_PWM_OUT_SYS1")
	)
	(segment
		(start 458.987398 -8.268208)
		(end 457.079858 -10.175748)
		(width 0.089408)
		(layer "In11.Cu")
		(net "FAN_PWM_OUT_SYS1")
	)
	(segment
		(start 448.261486 -18.332704)
		(end 448.21221 -18.283428)
		(width 0.089408)
		(layer "In11.Cu")
		(net "FAN_PWM_OUT_SYS1")
	)
	(segment
		(start 446.137792 -18.283428)
		(end 445.673988 -18.747232)
		(width 0.089408)
		(layer "In11.Cu")
		(net "FAN_PWM_OUT_SYS1")
	)
	(segment
		(start 457.079858 -10.175748)
		(end 454.587356 -10.175748)
		(width 0.089408)
		(layer "In11.Cu")
		(net "FAN_PWM_OUT_SYS1")
	)
	(segment
		(start 449.799456 -18.332704)
		(end 448.261486 -18.332704)
		(width 0.089408)
		(layer "In11.Cu")
		(net "FAN_PWM_OUT_SYS1")
	)
	(segment
		(start 427.461934 -21.15058)
		(end 426.00118 -21.15058)
		(width 0.089408)
		(layer "In11.Cu")
		(net "FAN_PWM_OUT_SYS1")
	)
	(segment
		(start 435.015132 -19.705574)
		(end 434.28412 -18.974562)
		(width 0.089408)
		(layer "In11.Cu")
		(net "FAN_PWM_OUT_SYS1")
	)
	(segment
		(start 431.23485 -20.293584)
		(end 428.797212 -20.293584)
		(width 0.089408)
		(layer "In11.Cu")
		(net "FAN_PWM_OUT_SYS1")
	)
	(segment
		(start 428.31512 -20.297394)
		(end 427.461934 -21.15058)
		(width 0.089408)
		(layer "In11.Cu")
		(net "FAN_PWM_OUT_SYS1")
	)
	(segment
		(start 468.549736 -8.74649)
		(end 468.071454 -8.268208)
		(width 0.089408)
		(layer "In11.Cu")
		(net "FAN_PWM_OUT_SYS1")
	)
	(segment
		(start 428.797212 -20.293584)
		(end 428.793402 -20.297394)
		(width 0.089408)
		(layer "In11.Cu")
		(net "FAN_PWM_OUT_SYS1")
	)
	(segment
		(start 432.60137 -19.482816)
		(end 432.045618 -19.482816)
		(width 0.089408)
		(layer "In11.Cu")
		(net "FAN_PWM_OUT_SYS1")
	)
	(segment
		(start 423.556938 -23.368)
		(end 423.140886 -23.784052)
		(width 0.10795)
		(layer "F.Cu")
		(net "FAN_PWM_OUT_SYS0")
	)
	(segment
		(start 423.140886 -23.784052)
		(end 422.151302 -24.773636)
		(width 0.10795)
		(layer "F.Cu")
		(net "FAN_PWM_OUT_SYS0")
	)
	(segment
		(start 422.151302 -25.340818)
		(end 421.048434 -26.443686)
		(width 0.10795)
		(layer "F.Cu")
		(net "FAN_PWM_OUT_SYS0")
	)
	(segment
		(start 421.048434 -26.443686)
		(end 421.048434 -26.976324)
		(width 0.10795)
		(layer "F.Cu")
		(net "FAN_PWM_OUT_SYS0")
	)
	(segment
		(start 421.048434 -26.976324)
		(end 420.69004 -27.334718)
		(width 0.10795)
		(layer "F.Cu")
		(net "FAN_PWM_OUT_SYS0")
	)
	(segment
		(start 423.926 -23.368)
		(end 423.556938 -23.368)
		(width 0.10795)
		(layer "F.Cu")
		(net "FAN_PWM_OUT_SYS0")
	)
	(segment
		(start 422.151302 -24.773636)
		(end 422.151302 -25.340818)
		(width 0.10795)
		(layer "F.Cu")
		(net "FAN_PWM_OUT_SYS0")
	)
	(via
		(at 412.4706 -1.1684)
		(size 0.508)
		(drill 0.254)
		(layers "F.Cu" "B.Cu")
		(net "FAN_PWM_OUT_SYS0")
	)
	(via
		(at 423.926 -23.368)
		(size 0.508)
		(drill 0.254)
		(layers "F.Cu" "B.Cu")
		(net "FAN_PWM_OUT_SYS0")
	)
	(via
		(at 423.140886 -23.784052)
		(size 0.762)
		(drill 0.381)
		(layers "F.Cu" "B.Cu")
		(net "FAN_PWM_OUT_SYS0")
	)
	(via
		(at 464.0326 -10.2616)
		(size 0.508)
		(drill 0.254)
		(layers "F.Cu" "B.Cu")
		(net "FAN_PWM_OUT_SYS0")
	)
	(segment
		(start 412.4706 0.7112)
		(end 412.252414 0.929386)
		(width 0.10795)
		(layer "B.Cu")
		(net "FAN_PWM_OUT_SYS0")
	)
	(segment
		(start 412.4706 -1.1684)
		(end 412.4706 0.7112)
		(width 0.10795)
		(layer "B.Cu")
		(net "FAN_PWM_OUT_SYS0")
	)
	(segment
		(start 412.252414 0.929386)
		(end 411.48 0.929386)
		(width 0.10795)
		(layer "B.Cu")
		(net "FAN_PWM_OUT_SYS0")
	)
	(segment
		(start 422.0718 -0.095504)
		(end 420.528496 1.4478)
		(width 0.089408)
		(layer "In2.Cu")
		(net "FAN_PWM_OUT_SYS0")
	)
	(segment
		(start 461.739234 -8.172196)
		(end 460.539592 -6.972554)
		(width 0.089408)
		(layer "In2.Cu")
		(net "FAN_PWM_OUT_SYS0")
	)
	(segment
		(start 450.581014 -3.417316)
		(end 442.043058 -3.417316)
		(width 0.089408)
		(layer "In2.Cu")
		(net "FAN_PWM_OUT_SYS0")
	)
	(segment
		(start 457.994766 -1.373124)
		(end 457.994258 -1.372616)
		(width 0.089408)
		(layer "In2.Cu")
		(net "FAN_PWM_OUT_SYS0")
	)
	(segment
		(start 441.349384 -2.317242)
		(end 440.92749 -1.895348)
		(width 0.089408)
		(layer "In2.Cu")
		(net "FAN_PWM_OUT_SYS0")
	)
	(segment
		(start 440.92749 -1.895348)
		(end 425.934378 -1.895348)
		(width 0.089408)
		(layer "In2.Cu")
		(net "FAN_PWM_OUT_SYS0")
	)
	(segment
		(start 458.437742 -1.372616)
		(end 458.437234 -1.373124)
		(width 0.089408)
		(layer "In2.Cu")
		(net "FAN_PWM_OUT_SYS0")
	)
	(segment
		(start 462.017872 -2.768854)
		(end 462.017872 -2.488438)
		(width 0.089408)
		(layer "In2.Cu")
		(net "FAN_PWM_OUT_SYS0")
	)
	(segment
		(start 457.994258 -1.372616)
		(end 456.118722 -1.372616)
		(width 0.089408)
		(layer "In2.Cu")
		(net "FAN_PWM_OUT_SYS0")
	)
	(segment
		(start 412.887414 1.4478)
		(end 412.4706 1.030986)
		(width 0.089408)
		(layer "In2.Cu")
		(net "FAN_PWM_OUT_SYS0")
	)
	(segment
		(start 462.611978 -8.172196)
		(end 461.739234 -8.172196)
		(width 0.089408)
		(layer "In2.Cu")
		(net "FAN_PWM_OUT_SYS0")
	)
	(segment
		(start 460.302102 -2.08407)
		(end 459.590648 -1.372616)
		(width 0.089408)
		(layer "In2.Cu")
		(net "FAN_PWM_OUT_SYS0")
	)
	(segment
		(start 464.0326 -10.2616)
		(end 464.0326 -10.004298)
		(width 0.089408)
		(layer "In2.Cu")
		(net "FAN_PWM_OUT_SYS0")
	)
	(segment
		(start 463.287364 -9.259062)
		(end 463.287364 -8.847582)
		(width 0.089408)
		(layer "In2.Cu")
		(net "FAN_PWM_OUT_SYS0")
	)
	(segment
		(start 462.284826 -3.73634)
		(end 462.284826 -3.035808)
		(width 0.089408)
		(layer "In2.Cu")
		(net "FAN_PWM_OUT_SYS0")
	)
	(segment
		(start 456.118722 -1.372616)
		(end 455.958702 -1.212596)
		(width 0.089408)
		(layer "In2.Cu")
		(net "FAN_PWM_OUT_SYS0")
	)
	(segment
		(start 424.134534 -0.095504)
		(end 422.0718 -0.095504)
		(width 0.089408)
		(layer "In2.Cu")
		(net "FAN_PWM_OUT_SYS0")
	)
	(segment
		(start 442.043058 -3.417316)
		(end 441.349384 -2.723642)
		(width 0.089408)
		(layer "In2.Cu")
		(net "FAN_PWM_OUT_SYS0")
	)
	(segment
		(start 458.437234 -1.373124)
		(end 457.994766 -1.373124)
		(width 0.089408)
		(layer "In2.Cu")
		(net "FAN_PWM_OUT_SYS0")
	)
	(segment
		(start 459.590648 -1.372616)
		(end 458.437742 -1.372616)
		(width 0.089408)
		(layer "In2.Cu")
		(net "FAN_PWM_OUT_SYS0")
	)
	(segment
		(start 463.287364 -8.847582)
		(end 462.611978 -8.172196)
		(width 0.089408)
		(layer "In2.Cu")
		(net "FAN_PWM_OUT_SYS0")
	)
	(segment
		(start 462.017872 -2.488438)
		(end 461.613504 -2.08407)
		(width 0.089408)
		(layer "In2.Cu")
		(net "FAN_PWM_OUT_SYS0")
	)
	(segment
		(start 412.4706 1.030986)
		(end 412.4706 -1.1684)
		(width 0.089408)
		(layer "In2.Cu")
		(net "FAN_PWM_OUT_SYS0")
	)
	(segment
		(start 462.284826 -3.035808)
		(end 462.017872 -2.768854)
		(width 0.089408)
		(layer "In2.Cu")
		(net "FAN_PWM_OUT_SYS0")
	)
	(segment
		(start 452.785734 -1.212596)
		(end 450.581014 -3.417316)
		(width 0.089408)
		(layer "In2.Cu")
		(net "FAN_PWM_OUT_SYS0")
	)
	(segment
		(start 464.0326 -10.004298)
		(end 463.287364 -9.259062)
		(width 0.089408)
		(layer "In2.Cu")
		(net "FAN_PWM_OUT_SYS0")
	)
	(segment
		(start 441.349384 -2.723642)
		(end 441.349384 -2.317242)
		(width 0.089408)
		(layer "In2.Cu")
		(net "FAN_PWM_OUT_SYS0")
	)
	(segment
		(start 460.539592 -5.481574)
		(end 462.284826 -3.73634)
		(width 0.089408)
		(layer "In2.Cu")
		(net "FAN_PWM_OUT_SYS0")
	)
	(segment
		(start 455.958702 -1.212596)
		(end 452.785734 -1.212596)
		(width 0.089408)
		(layer "In2.Cu")
		(net "FAN_PWM_OUT_SYS0")
	)
	(segment
		(start 425.934378 -1.895348)
		(end 424.134534 -0.095504)
		(width 0.089408)
		(layer "In2.Cu")
		(net "FAN_PWM_OUT_SYS0")
	)
	(segment
		(start 461.613504 -2.08407)
		(end 460.302102 -2.08407)
		(width 0.089408)
		(layer "In2.Cu")
		(net "FAN_PWM_OUT_SYS0")
	)
	(segment
		(start 420.528496 1.4478)
		(end 412.887414 1.4478)
		(width 0.089408)
		(layer "In2.Cu")
		(net "FAN_PWM_OUT_SYS0")
	)
	(segment
		(start 460.539592 -6.972554)
		(end 460.539592 -5.481574)
		(width 0.089408)
		(layer "In2.Cu")
		(net "FAN_PWM_OUT_SYS0")
	)
	(segment
		(start 452.621142 -15.314168)
		(end 450.769482 -17.165828)
		(width 0.089408)
		(layer "In11.Cu")
		(net "FAN_PWM_OUT_SYS0")
	)
	(segment
		(start 445.503808 -19.550634)
		(end 440.195462 -19.550634)
		(width 0.089408)
		(layer "In11.Cu")
		(net "FAN_PWM_OUT_SYS0")
	)
	(segment
		(start 433.455572 -20.482306)
		(end 432.597814 -21.340064)
		(width 0.089408)
		(layer "In11.Cu")
		(net "FAN_PWM_OUT_SYS0")
	)
	(segment
		(start 424.776646 -22.517354)
		(end 423.926 -23.368)
		(width 0.089408)
		(layer "In11.Cu")
		(net "FAN_PWM_OUT_SYS0")
	)
	(segment
		(start 452.621142 -13.240258)
		(end 452.621142 -15.314168)
		(width 0.089408)
		(layer "In11.Cu")
		(net "FAN_PWM_OUT_SYS0")
	)
	(segment
		(start 447.579496 -19.62785)
		(end 445.581024 -19.62785)
		(width 0.089408)
		(layer "In11.Cu")
		(net "FAN_PWM_OUT_SYS0")
	)
	(segment
		(start 440.195462 -19.550634)
		(end 439.26379 -20.482306)
		(width 0.089408)
		(layer "In11.Cu")
		(net "FAN_PWM_OUT_SYS0")
	)
	(segment
		(start 450.769482 -18.460974)
		(end 450.121528 -19.108928)
		(width 0.089408)
		(layer "In11.Cu")
		(net "FAN_PWM_OUT_SYS0")
	)
	(segment
		(start 450.769482 -17.165828)
		(end 450.769482 -18.460974)
		(width 0.089408)
		(layer "In11.Cu")
		(net "FAN_PWM_OUT_SYS0")
	)
	(segment
		(start 463.698082 -10.875264)
		(end 462.724246 -10.875264)
		(width 0.089408)
		(layer "In11.Cu")
		(net "FAN_PWM_OUT_SYS0")
	)
	(segment
		(start 458.8256 -11.0744)
		(end 458.240384 -11.659616)
		(width 0.089408)
		(layer "In11.Cu")
		(net "FAN_PWM_OUT_SYS0")
	)
	(segment
		(start 432.597814 -21.340064)
		(end 428.965868 -21.340064)
		(width 0.089408)
		(layer "In11.Cu")
		(net "FAN_PWM_OUT_SYS0")
	)
	(segment
		(start 450.121528 -19.108928)
		(end 448.098418 -19.108928)
		(width 0.089408)
		(layer "In11.Cu")
		(net "FAN_PWM_OUT_SYS0")
	)
	(segment
		(start 427.788578 -22.517354)
		(end 424.776646 -22.517354)
		(width 0.089408)
		(layer "In11.Cu")
		(net "FAN_PWM_OUT_SYS0")
	)
	(segment
		(start 462.724246 -10.875264)
		(end 462.52511 -11.0744)
		(width 0.089408)
		(layer "In11.Cu")
		(net "FAN_PWM_OUT_SYS0")
	)
	(segment
		(start 454.201784 -11.659616)
		(end 452.621142 -13.240258)
		(width 0.089408)
		(layer "In11.Cu")
		(net "FAN_PWM_OUT_SYS0")
	)
	(segment
		(start 448.098418 -19.108928)
		(end 447.579496 -19.62785)
		(width 0.089408)
		(layer "In11.Cu")
		(net "FAN_PWM_OUT_SYS0")
	)
	(segment
		(start 464.0326 -10.540746)
		(end 463.698082 -10.875264)
		(width 0.089408)
		(layer "In11.Cu")
		(net "FAN_PWM_OUT_SYS0")
	)
	(segment
		(start 439.26379 -20.482306)
		(end 433.455572 -20.482306)
		(width 0.089408)
		(layer "In11.Cu")
		(net "FAN_PWM_OUT_SYS0")
	)
	(segment
		(start 464.0326 -10.2616)
		(end 464.0326 -10.540746)
		(width 0.089408)
		(layer "In11.Cu")
		(net "FAN_PWM_OUT_SYS0")
	)
	(segment
		(start 445.581024 -19.62785)
		(end 445.503808 -19.550634)
		(width 0.089408)
		(layer "In11.Cu")
		(net "FAN_PWM_OUT_SYS0")
	)
	(segment
		(start 428.965868 -21.340064)
		(end 427.788578 -22.517354)
		(width 0.089408)
		(layer "In11.Cu")
		(net "FAN_PWM_OUT_SYS0")
	)
	(segment
		(start 458.240384 -11.659616)
		(end 454.201784 -11.659616)
		(width 0.089408)
		(layer "In11.Cu")
		(net "FAN_PWM_OUT_SYS0")
	)
	(segment
		(start 462.52511 -11.0744)
		(end 458.8256 -11.0744)
		(width 0.089408)
		(layer "In11.Cu")
		(net "FAN_PWM_OUT_SYS0")
	)
	(segment
		(start 172.95114 -147.828)
		(end 172.913294 -147.865846)
		(width 0.254)
		(layer "F.Cu")
		(net "VSENSE_PVDDQ_KLM_VTT")
	)
	(segment
		(start 172.046646 -147.865846)
		(end 171.983146 -147.929346)
		(width 0.254)
		(layer "F.Cu")
		(net "VSENSE_PVDDQ_KLM_VTT")
	)
	(segment
		(start 173.65726 -147.828)
		(end 172.95114 -147.828)
		(width 0.254)
		(layer "F.Cu")
		(net "VSENSE_PVDDQ_KLM_VTT")
	)
	(segment
		(start 172.913294 -147.865846)
		(end 172.046646 -147.865846)
		(width 0.254)
		(layer "F.Cu")
		(net "VSENSE_PVDDQ_KLM_VTT")
	)
	(segment
		(start 173.78172 -147.95246)
		(end 173.65726 -147.828)
		(width 0.254)
		(layer "F.Cu")
		(net "VSENSE_PVDDQ_KLM_VTT")
	)
	(via
		(at 173.31436 -148.58238)
		(size 0.6604)
		(drill 0.3302)
		(layers "F.Cu" "B.Cu")
		(net "VSENSE_PVDDQ_KLM_VTT")
	)
	(via
		(at 172.95114 -147.828)
		(size 0.508)
		(drill 0.254)
		(layers "F.Cu" "B.Cu")
		(net "VSENSE_PVDDQ_KLM_VTT")
	)
	(segment
		(start 172.451776 -148.58238)
		(end 172.0596 -148.190204)
		(width 0.254)
		(layer "B.Cu")
		(net "VSENSE_PVDDQ_KLM_VTT")
	)
	(segment
		(start 173.31436 -148.19122)
		(end 172.95114 -147.828)
		(width 0.254)
		(layer "B.Cu")
		(net "VSENSE_PVDDQ_KLM_VTT")
	)
	(segment
		(start 173.31436 -148.58238)
		(end 173.31436 -148.19122)
		(width 0.254)
		(layer "B.Cu")
		(net "VSENSE_PVDDQ_KLM_VTT")
	)
	(segment
		(start 172.0596 -148.190204)
		(end 172.0596 -147.8026)
		(width 0.254)
		(layer "B.Cu")
		(net "VSENSE_PVDDQ_KLM_VTT")
	)
	(segment
		(start 173.31436 -148.58238)
		(end 172.451776 -148.58238)
		(width 0.254)
		(layer "B.Cu")
		(net "VSENSE_PVDDQ_KLM_VTT")
	)
	(segment
		(start 171.8818 -4.675124)
		(end 172.703744 -4.675124)
		(width 0.254)
		(layer "F.Cu")
		(net "VSENSE_PVDDQ_GHJ_VTT")
	)
	(via
		(at 175.39081 -7.006844)
		(size 0.6604)
		(drill 0.3302)
		(layers "F.Cu" "B.Cu")
		(net "VSENSE_PVDDQ_GHJ_VTT")
	)
	(via
		(at 172.703744 -4.675124)
		(size 0.508)
		(drill 0.254)
		(layers "F.Cu" "B.Cu")
		(net "VSENSE_PVDDQ_GHJ_VTT")
	)
	(segment
		(start 173.920404 -4.57581)
		(end 172.803058 -4.57581)
		(width 0.254)
		(layer "B.Cu")
		(net "VSENSE_PVDDQ_GHJ_VTT")
	)
	(segment
		(start 173.920404 -4.810252)
		(end 174.1805 -5.070348)
		(width 0.254)
		(layer "B.Cu")
		(net "VSENSE_PVDDQ_GHJ_VTT")
	)
	(segment
		(start 174.554642 -5.471414)
		(end 174.554642 -5.674868)
		(width 0.254)
		(layer "B.Cu")
		(net "VSENSE_PVDDQ_GHJ_VTT")
	)
	(segment
		(start 173.725078 -5.551424)
		(end 173.4947 -5.551424)
		(width 0.254)
		(layer "B.Cu")
		(net "VSENSE_PVDDQ_GHJ_VTT")
	)
	(segment
		(start 174.254668 -6.644894)
		(end 174.254668 -6.081014)
		(width 0.254)
		(layer "B.Cu")
		(net "VSENSE_PVDDQ_GHJ_VTT")
	)
	(segment
		(start 173.920404 -4.57581)
		(end 173.920404 -4.810252)
		(width 0.254)
		(layer "B.Cu")
		(net "VSENSE_PVDDQ_GHJ_VTT")
	)
	(segment
		(start 172.803058 -4.57581)
		(end 172.703744 -4.675124)
		(width 0.254)
		(layer "B.Cu")
		(net "VSENSE_PVDDQ_GHJ_VTT")
	)
	(segment
		(start 174.1805 -5.070348)
		(end 174.1805 -5.097272)
		(width 0.254)
		(layer "B.Cu")
		(net "VSENSE_PVDDQ_GHJ_VTT")
	)
	(segment
		(start 175.39081 -7.006844)
		(end 174.616618 -7.006844)
		(width 0.254)
		(layer "B.Cu")
		(net "VSENSE_PVDDQ_GHJ_VTT")
	)
	(segment
		(start 174.616618 -7.006844)
		(end 174.254668 -6.644894)
		(width 0.254)
		(layer "B.Cu")
		(net "VSENSE_PVDDQ_GHJ_VTT")
	)
	(segment
		(start 175.39081 -6.511036)
		(end 175.39081 -7.006844)
		(width 0.254)
		(layer "B.Cu")
		(net "VSENSE_PVDDQ_GHJ_VTT")
	)
	(segment
		(start 174.254668 -6.081014)
		(end 173.725078 -5.551424)
		(width 0.254)
		(layer "B.Cu")
		(net "VSENSE_PVDDQ_GHJ_VTT")
	)
	(segment
		(start 174.554642 -5.674868)
		(end 175.39081 -6.511036)
		(width 0.254)
		(layer "B.Cu")
		(net "VSENSE_PVDDQ_GHJ_VTT")
	)
	(segment
		(start 174.1805 -5.097272)
		(end 174.554642 -5.471414)
		(width 0.254)
		(layer "B.Cu")
		(net "VSENSE_PVDDQ_GHJ_VTT")
	)
	(segment
		(start 183.391048 -147.774152)
		(end 183.515 -147.6502)
		(width 0.254)
		(layer "F.Cu")
		(net "VSENSE_PVDDQ_DEF_VTT")
	)
	(segment
		(start 183.515 -146.939)
		(end 183.515 -147.5486)
		(width 0.254)
		(layer "F.Cu")
		(net "VSENSE_PVDDQ_DEF_VTT")
	)
	(segment
		(start 182.6514 -146.685)
		(end 183.261 -146.685)
		(width 0.254)
		(layer "F.Cu")
		(net "VSENSE_PVDDQ_DEF_VTT")
	)
	(segment
		(start 183.261 -146.685)
		(end 183.515 -146.939)
		(width 0.254)
		(layer "F.Cu")
		(net "VSENSE_PVDDQ_DEF_VTT")
	)
	(segment
		(start 183.515 -147.6502)
		(end 183.515 -147.5486)
		(width 0.254)
		(layer "F.Cu")
		(net "VSENSE_PVDDQ_DEF_VTT")
	)
	(segment
		(start 183.391048 -148.3487)
		(end 183.391048 -147.774152)
		(width 0.254)
		(layer "F.Cu")
		(net "VSENSE_PVDDQ_DEF_VTT")
	)
	(via
		(at 183.515 -148.2852)
		(size 0.6604)
		(drill 0.3302)
		(layers "F.Cu" "B.Cu")
		(net "VSENSE_PVDDQ_DEF_VTT")
	)
	(via
		(at 183.515 -147.5486)
		(size 0.508)
		(drill 0.254)
		(layers "F.Cu" "B.Cu")
		(net "VSENSE_PVDDQ_DEF_VTT")
	)
	(segment
		(start 183.233314 -148.2852)
		(end 182.979314 -148.0312)
		(width 0.254)
		(layer "B.Cu")
		(net "VSENSE_PVDDQ_DEF_VTT")
	)
	(segment
		(start 183.515 -148.2852)
		(end 183.233314 -148.2852)
		(width 0.254)
		(layer "B.Cu")
		(net "VSENSE_PVDDQ_DEF_VTT")
	)
	(segment
		(start 182.979314 -147.220686)
		(end 183.515 -146.685)
		(width 0.254)
		(layer "B.Cu")
		(net "VSENSE_PVDDQ_DEF_VTT")
	)
	(segment
		(start 183.515 -148.2852)
		(end 183.515 -147.5486)
		(width 0.254)
		(layer "B.Cu")
		(net "VSENSE_PVDDQ_DEF_VTT")
	)
	(segment
		(start 182.979314 -148.0312)
		(end 182.979314 -147.220686)
		(width 0.254)
		(layer "B.Cu")
		(net "VSENSE_PVDDQ_DEF_VTT")
	)
	(segment
		(start 182.633874 -3.538474)
		(end 182.7276 -3.6322)
		(width 0.254)
		(layer "F.Cu")
		(net "VSENSE_PVDDQ_ABC_VTT")
	)
	(segment
		(start 182.633874 -2.705608)
		(end 182.633874 -3.538474)
		(width 0.254)
		(layer "F.Cu")
		(net "VSENSE_PVDDQ_ABC_VTT")
	)
	(via
		(at 180.34 -5.334)
		(size 0.6604)
		(drill 0.3302)
		(layers "F.Cu" "B.Cu")
		(net "VSENSE_PVDDQ_ABC_VTT")
	)
	(via
		(at 182.7276 -3.6322)
		(size 0.508)
		(drill 0.254)
		(layers "F.Cu" "B.Cu")
		(net "VSENSE_PVDDQ_ABC_VTT")
	)
	(segment
		(start 182.2196 -4.982718)
		(end 182.736998 -4.46532)
		(width 0.254)
		(layer "B.Cu")
		(net "VSENSE_PVDDQ_ABC_VTT")
	)
	(segment
		(start 180.34 -5.334)
		(end 180.34 -4.835144)
		(width 0.254)
		(layer "B.Cu")
		(net "VSENSE_PVDDQ_ABC_VTT")
	)
	(segment
		(start 182.2196 -5.002276)
		(end 182.2196 -4.982718)
		(width 0.254)
		(layer "B.Cu")
		(net "VSENSE_PVDDQ_ABC_VTT")
	)
	(segment
		(start 180.34 -4.835144)
		(end 180.717444 -4.4577)
		(width 0.254)
		(layer "B.Cu")
		(net "VSENSE_PVDDQ_ABC_VTT")
	)
	(segment
		(start 181.887876 -5.334)
		(end 182.2196 -5.002276)
		(width 0.254)
		(layer "B.Cu")
		(net "VSENSE_PVDDQ_ABC_VTT")
	)
	(segment
		(start 182.736998 -3.641598)
		(end 182.736998 -4.432808)
		(width 0.254)
		(layer "B.Cu")
		(net "VSENSE_PVDDQ_ABC_VTT")
	)
	(segment
		(start 180.717444 -4.4577)
		(end 181.5973 -4.4577)
		(width 0.254)
		(layer "B.Cu")
		(net "VSENSE_PVDDQ_ABC_VTT")
	)
	(segment
		(start 182.7276 -3.6322)
		(end 182.736998 -3.641598)
		(width 0.254)
		(layer "B.Cu")
		(net "VSENSE_PVDDQ_ABC_VTT")
	)
	(segment
		(start 182.736998 -4.46532)
		(end 182.736998 -4.432808)
		(width 0.254)
		(layer "B.Cu")
		(net "VSENSE_PVDDQ_ABC_VTT")
	)
	(segment
		(start 180.34 -5.334)
		(end 181.887876 -5.334)
		(width 0.254)
		(layer "B.Cu")
		(net "VSENSE_PVDDQ_ABC_VTT")
	)
	(segment
		(start 398.13865 -118.4402)
		(end 398.63395 -118.670324)
		(width 0.10795)
		(layer "F.Cu")
		(net "TP_USB3_P03_TXP")
	)
	(via
		(at 398.63395 -118.670324)
		(size 0.508)
		(drill 0.254)
		(layers "F.Cu" "B.Cu")
		(net "TP_USB3_P03_TXP")
	)
	(segment
		(start 398.13865 -117.811804)
		(end 397.64335 -117.58168)
		(width 0.10795)
		(layer "F.Cu")
		(net "TP_USB3_P03_TXN")
	)
	(via
		(at 398.13865 -117.811804)
		(size 0.508)
		(drill 0.254)
		(layers "F.Cu" "B.Cu")
		(net "TP_USB3_P03_TXN")
	)
	(segment
		(start 396.15745 -118.4402)
		(end 396.65275 -118.670324)
		(width 0.10795)
		(layer "F.Cu")
		(net "TP_USB3_P02_TXP")
	)
	(via
		(at 396.65275 -118.670324)
		(size 0.508)
		(drill 0.254)
		(layers "F.Cu" "B.Cu")
		(net "TP_USB3_P02_TXP")
	)
	(segment
		(start 397.470376 -118.59006)
		(end 397.558768 -118.630954)
		(width 0.10795)
		(layer "F.Cu")
		(net "TP_USB3_P02_TXN")
	)
	(segment
		(start 397.14805 -118.4402)
		(end 397.159988 -118.445788)
		(width 0.10795)
		(layer "F.Cu")
		(net "TP_USB3_P02_TXN")
	)
	(segment
		(start 397.558768 -118.630954)
		(end 397.64335 -118.670324)
		(width 0.10795)
		(layer "F.Cu")
		(net "TP_USB3_P02_TXN")
	)
	(segment
		(start 397.159988 -118.445788)
		(end 397.470376 -118.59006)
		(width 0.10795)
		(layer "F.Cu")
		(net "TP_USB3_P02_TXN")
	)
	(via
		(at 397.64335 -118.670324)
		(size 0.508)
		(drill 0.254)
		(layers "F.Cu" "B.Cu")
		(net "TP_USB3_P02_TXN")
	)
	(segment
		(start 39.542466 -93.836998)
		(end 40.045894 -94.34957)
		(width 0.508)
		(layer "F.Cu")
		(net "VR_PVSA_CPU1_PHASE_SW")
	)
	(segment
		(start 38.40734 -93.8276)
		(end 39.542466 -93.836998)
		(width 0.508)
		(layer "F.Cu")
		(net "VR_PVSA_CPU1_PHASE_SW")
	)
	(segment
		(start 40.036496 -95.484696)
		(end 40.036496 -97.671382)
		(width 0.508)
		(layer "F.Cu")
		(net "VR_PVSA_CPU1_PHASE_SW")
	)
	(segment
		(start 40.045894 -94.34957)
		(end 40.036496 -95.484696)
		(width 0.508)
		(layer "F.Cu")
		(net "VR_PVSA_CPU1_PHASE_SW")
	)
	(segment
		(start 204.978 -95.42907)
		(end 204.649832 -95.100902)
		(width 0.508)
		(layer "F.Cu")
		(net "VR_PVSA_CPU0_PHASE_SW")
	)
	(segment
		(start 204.978 -96.901)
		(end 204.978 -95.42907)
		(width 0.508)
		(layer "F.Cu")
		(net "VR_PVSA_CPU0_PHASE_SW")
	)
	(segment
		(start 204.649832 -95.100902)
		(end 204.649832 -93.36024)
		(width 0.508)
		(layer "F.Cu")
		(net "VR_PVSA_CPU0_PHASE_SW")
	)
	(segment
		(start 376.3772 -147.8788)
		(end 375.059448 -146.561048)
		(width 0.508)
		(layer "F.Cu")
		(net "VR_PVNN_PCH_PH1_PHASE_SW")
	)
	(segment
		(start 375.059448 -146.561048)
		(end 372.528338 -146.561048)
		(width 0.508)
		(layer "F.Cu")
		(net "VR_PVNN_PCH_PH1_PHASE_SW")
	)
	(segment
		(start 383.126488 -147.928076)
		(end 384.4798 -146.574764)
		(width 0.508)
		(layer "F.Cu")
		(net "VR_P1V05_PCH_STBY_PH1_PHASE_SW")
	)
	(segment
		(start 381.51562 -147.928076)
		(end 383.126488 -147.928076)
		(width 0.508)
		(layer "F.Cu")
		(net "VR_P1V05_PCH_STBY_PH1_PHASE_SW")
	)
	(segment
		(start 390.906 -86.5505)
		(end 390.906 -85.598)
		(width 0.10795)
		(layer "B.Cu")
		(net "SGPIO_PCH_SSATA_LOAD_R")
	)
	(segment
		(start 390.70915 -100.41128)
		(end 391.20445 -100.181156)
		(width 0.10795)
		(layer "F.Cu")
		(net "SGPIO_PCH_SSATA_LOAD")
	)
	(via
		(at 388.4676 -93.2688)
		(size 0.6604)
		(drill 0.3302)
		(layers "F.Cu" "B.Cu")
		(net "SGPIO_PCH_SSATA_LOAD")
	)
	(via
		(at 391.20445 -100.181156)
		(size 0.508)
		(drill 0.254)
		(layers "F.Cu" "B.Cu")
		(net "SGPIO_PCH_SSATA_LOAD")
	)
	(segment
		(start 389.8138 -98.475292)
		(end 389.8138 -98.442526)
		(width 0.0889)
		(layer "B.Cu")
		(net "SGPIO_PCH_SSATA_LOAD")
	)
	(segment
		(start 388.4676 -92.71)
		(end 388.154164 -92.396564)
		(width 0.10795)
		(layer "B.Cu")
		(net "SGPIO_PCH_SSATA_LOAD")
	)
	(segment
		(start 388.49046 -91.492324)
		(end 388.49046 -91.488768)
		(width 0.10795)
		(layer "B.Cu")
		(net "SGPIO_PCH_SSATA_LOAD")
	)
	(segment
		(start 389.3185 -97.616772)
		(end 389.3185 -97.584006)
		(width 0.0889)
		(layer "B.Cu")
		(net "SGPIO_PCH_SSATA_LOAD")
	)
	(segment
		(start 390.3091 -99.333812)
		(end 390.3091 -99.301046)
		(width 0.0889)
		(layer "B.Cu")
		(net "SGPIO_PCH_SSATA_LOAD")
	)
	(segment
		(start 388.154164 -92.396564)
		(end 388.154164 -91.82862)
		(width 0.10795)
		(layer "B.Cu")
		(net "SGPIO_PCH_SSATA_LOAD")
	)
	(segment
		(start 388.793482 -90.370406)
		(end 389.73125 -89.432638)
		(width 0.10795)
		(layer "B.Cu")
		(net "SGPIO_PCH_SSATA_LOAD")
	)
	(segment
		(start 389.73125 -89.432638)
		(end 389.73125 -88.61425)
		(width 0.10795)
		(layer "B.Cu")
		(net "SGPIO_PCH_SSATA_LOAD")
	)
	(segment
		(start 389.73125 -88.61425)
		(end 390.906 -87.4395)
		(width 0.10795)
		(layer "B.Cu")
		(net "SGPIO_PCH_SSATA_LOAD")
	)
	(segment
		(start 388.49046 -91.488768)
		(end 388.793482 -91.185746)
		(width 0.10795)
		(layer "B.Cu")
		(net "SGPIO_PCH_SSATA_LOAD")
	)
	(segment
		(start 388.154164 -91.82862)
		(end 388.49046 -91.492324)
		(width 0.10795)
		(layer "B.Cu")
		(net "SGPIO_PCH_SSATA_LOAD")
	)
	(segment
		(start 391.20445 -100.181156)
		(end 390.866376 -100.181156)
		(width 0.0889)
		(layer "B.Cu")
		(net "SGPIO_PCH_SSATA_LOAD")
	)
	(segment
		(start 389.3185 -94.8817)
		(end 389.198612 -94.761812)
		(width 0.0889)
		(layer "B.Cu")
		(net "SGPIO_PCH_SSATA_LOAD")
	)
	(segment
		(start 388.793482 -91.185746)
		(end 388.793482 -90.370406)
		(width 0.10795)
		(layer "B.Cu")
		(net "SGPIO_PCH_SSATA_LOAD")
	)
	(segment
		(start 390.866376 -100.181156)
		(end 390.801352 -100.116132)
		(width 0.0889)
		(layer "B.Cu")
		(net "SGPIO_PCH_SSATA_LOAD")
	)
	(segment
		(start 388.8232 -96.758252)
		(end 388.8232 -96.7359)
		(width 0.0889)
		(layer "B.Cu")
		(net "SGPIO_PCH_SSATA_LOAD")
	)
	(segment
		(start 388.4676 -94.0308)
		(end 388.4676 -93.2688)
		(width 0.10795)
		(layer "B.Cu")
		(net "SGPIO_PCH_SSATA_LOAD")
	)
	(segment
		(start 389.198612 -94.761812)
		(end 388.4676 -94.0308)
		(width 0.10795)
		(layer "B.Cu")
		(net "SGPIO_PCH_SSATA_LOAD")
	)
	(segment
		(start 389.3185 -95.910146)
		(end 389.3185 -94.8817)
		(width 0.0889)
		(layer "B.Cu")
		(net "SGPIO_PCH_SSATA_LOAD")
	)
	(segment
		(start 388.4676 -93.2688)
		(end 388.4676 -92.71)
		(width 0.10795)
		(layer "B.Cu")
		(net "SGPIO_PCH_SSATA_LOAD")
	)
	(arc
		(start 390.801352 -100.116132)
		(mid 390.708644 -99.857862)
		(end 390.509252 -99.669346)
		(width 0.0889)
		(layer "B.Cu")
		(net "SGPIO_PCH_SSATA_LOAD")
	)
	(arc
		(start 389.023352 -97.093786)
		(mid 388.879548 -96.952103)
		(end 388.8232 -96.758252)
		(width 0.0889)
		(layer "B.Cu")
		(net "SGPIO_PCH_SSATA_LOAD")
	)
	(arc
		(start 390.013952 -98.810826)
		(mid 389.870148 -98.669143)
		(end 389.8138 -98.475292)
		(width 0.0889)
		(layer "B.Cu")
		(net "SGPIO_PCH_SSATA_LOAD")
	)
	(arc
		(start 389.518652 -97.952306)
		(mid 389.374848 -97.810623)
		(end 389.3185 -97.616772)
		(width 0.0889)
		(layer "B.Cu")
		(net "SGPIO_PCH_SSATA_LOAD")
	)
	(arc
		(start 390.509252 -99.669346)
		(mid 390.365448 -99.527663)
		(end 390.3091 -99.333812)
		(width 0.0889)
		(layer "B.Cu")
		(net "SGPIO_PCH_SSATA_LOAD")
	)
	(arc
		(start 389.3185 -97.584006)
		(mid 389.234219 -97.300789)
		(end 389.023352 -97.093786)
		(width 0.0889)
		(layer "B.Cu")
		(net "SGPIO_PCH_SSATA_LOAD")
	)
	(arc
		(start 388.8232 -96.7359)
		(mid 388.87955 -96.54205)
		(end 389.023352 -96.400366)
		(width 0.0889)
		(layer "B.Cu")
		(net "SGPIO_PCH_SSATA_LOAD")
	)
	(arc
		(start 390.3091 -99.301046)
		(mid 390.224819 -99.017829)
		(end 390.013952 -98.810826)
		(width 0.0889)
		(layer "B.Cu")
		(net "SGPIO_PCH_SSATA_LOAD")
	)
	(arc
		(start 389.8138 -98.442526)
		(mid 389.729519 -98.159309)
		(end 389.518652 -97.952306)
		(width 0.0889)
		(layer "B.Cu")
		(net "SGPIO_PCH_SSATA_LOAD")
	)
	(arc
		(start 389.023352 -96.400366)
		(mid 389.234216 -96.193362)
		(end 389.3185 -95.910146)
		(width 0.0889)
		(layer "B.Cu")
		(net "SGPIO_PCH_SSATA_LOAD")
	)
	(segment
		(start 411.8737 -113.9698)
		(end 411.475936 -113.9698)
		(width 0.10795)
		(layer "F.Cu")
		(net "SGPIO_PCH_SSATA_DOUT0_R")
	)
	(segment
		(start 410.9466 -114.3)
		(end 410.5402 -114.3)
		(width 0.10795)
		(layer "F.Cu")
		(net "SGPIO_PCH_SSATA_DOUT0_R")
	)
	(segment
		(start 411.2768 -113.9698)
		(end 410.9466 -114.3)
		(width 0.10795)
		(layer "F.Cu")
		(net "SGPIO_PCH_SSATA_DOUT0_R")
	)
	(segment
		(start 412.4325 -113.411)
		(end 411.8737 -113.9698)
		(width 0.10795)
		(layer "F.Cu")
		(net "SGPIO_PCH_SSATA_DOUT0_R")
	)
	(segment
		(start 411.475936 -113.9698)
		(end 411.2768 -113.9698)
		(width 0.10795)
		(layer "F.Cu")
		(net "SGPIO_PCH_SSATA_DOUT0_R")
	)
	(via
		(at 411.475936 -113.9698)
		(size 0.762)
		(drill 0.381)
		(layers "F.Cu" "B.Cu")
		(net "SGPIO_PCH_SSATA_DOUT0_R")
	)
	(segment
		(start 390.144 -86.5505)
		(end 390.144 -85.611208)
		(width 0.10795)
		(layer "B.Cu")
		(net "SGPIO_PCH_SSATA_CLOCK_R")
	)
	(segment
		(start 390.144 -85.611208)
		(end 390.135364 -85.602572)
		(width 0.10795)
		(layer "B.Cu")
		(net "SGPIO_PCH_SSATA_CLOCK_R")
	)
	(segment
		(start 389.71855 -101.039676)
		(end 389.22325 -101.2698)
		(width 0.10795)
		(layer "F.Cu")
		(net "SGPIO_PCH_SSATA_CLOCK")
	)
	(via
		(at 389.71855 -101.039676)
		(size 0.508)
		(drill 0.254)
		(layers "F.Cu" "B.Cu")
		(net "SGPIO_PCH_SSATA_CLOCK")
	)
	(via
		(at 388.198106 -94.574106)
		(size 0.6604)
		(drill 0.3302)
		(layers "F.Cu" "B.Cu")
		(net "SGPIO_PCH_SSATA_CLOCK")
	)
	(segment
		(start 388.6327 -96.768666)
		(end 388.6327 -96.725486)
		(width 0.0889)
		(layer "B.Cu")
		(net "SGPIO_PCH_SSATA_CLOCK")
	)
	(segment
		(start 390.144 -87.757)
		(end 390.144 -87.4395)
		(width 0.10795)
		(layer "B.Cu")
		(net "SGPIO_PCH_SSATA_CLOCK")
	)
	(segment
		(start 389.128 -95.631)
		(end 388.950454 -95.453454)
		(width 0.0889)
		(layer "B.Cu")
		(net "SGPIO_PCH_SSATA_CLOCK")
	)
	(segment
		(start 388.498588 -91.076526)
		(end 388.498588 -90.261186)
		(width 0.10795)
		(layer "B.Cu")
		(net "SGPIO_PCH_SSATA_CLOCK")
	)
	(segment
		(start 389.352282 -89.407492)
		(end 389.352282 -88.548718)
		(width 0.10795)
		(layer "B.Cu")
		(net "SGPIO_PCH_SSATA_CLOCK")
	)
	(segment
		(start 389.352282 -88.548718)
		(end 390.144 -87.757)
		(width 0.10795)
		(layer "B.Cu")
		(net "SGPIO_PCH_SSATA_CLOCK")
	)
	(segment
		(start 387.848348 -91.726766)
		(end 388.498588 -91.076526)
		(width 0.10795)
		(layer "B.Cu")
		(net "SGPIO_PCH_SSATA_CLOCK")
	)
	(segment
		(start 388.198106 -94.574106)
		(end 387.848348 -94.224348)
		(width 0.10795)
		(layer "B.Cu")
		(net "SGPIO_PCH_SSATA_CLOCK")
	)
	(segment
		(start 388.950454 -95.453454)
		(end 388.950454 -95.326454)
		(width 0.0889)
		(layer "B.Cu")
		(net "SGPIO_PCH_SSATA_CLOCK")
	)
	(segment
		(start 389.128 -97.627186)
		(end 389.128 -97.59442)
		(width 0.0889)
		(layer "B.Cu")
		(net "SGPIO_PCH_SSATA_CLOCK")
	)
	(segment
		(start 389.128 -95.899732)
		(end 389.128 -95.631)
		(width 0.0889)
		(layer "B.Cu")
		(net "SGPIO_PCH_SSATA_CLOCK")
	)
	(segment
		(start 389.6233 -98.485706)
		(end 389.6233 -98.45294)
		(width 0.0889)
		(layer "B.Cu")
		(net "SGPIO_PCH_SSATA_CLOCK")
	)
	(segment
		(start 390.100566 -100.881434)
		(end 390.486392 -100.495608)
		(width 0.0889)
		(layer "B.Cu")
		(net "SGPIO_PCH_SSATA_CLOCK")
	)
	(segment
		(start 387.848348 -94.224348)
		(end 387.848348 -91.726766)
		(width 0.10795)
		(layer "B.Cu")
		(net "SGPIO_PCH_SSATA_CLOCK")
	)
	(segment
		(start 388.498588 -90.261186)
		(end 389.352282 -89.407492)
		(width 0.10795)
		(layer "B.Cu")
		(net "SGPIO_PCH_SSATA_CLOCK")
	)
	(segment
		(start 390.1186 -99.344226)
		(end 390.1186 -99.31146)
		(width 0.0889)
		(layer "B.Cu")
		(net "SGPIO_PCH_SSATA_CLOCK")
	)
	(segment
		(start 388.950454 -95.326454)
		(end 388.826756 -95.202756)
		(width 0.0889)
		(layer "B.Cu")
		(net "SGPIO_PCH_SSATA_CLOCK")
	)
	(segment
		(start 388.826756 -95.202756)
		(end 388.198106 -94.574106)
		(width 0.10795)
		(layer "B.Cu")
		(net "SGPIO_PCH_SSATA_CLOCK")
	)
	(arc
		(start 389.71855 -101.039676)
		(mid 389.925298 -100.998551)
		(end 390.100566 -100.881434)
		(width 0.0889)
		(layer "B.Cu")
		(net "SGPIO_PCH_SSATA_CLOCK")
	)
	(arc
		(start 389.918448 -98.975926)
		(mid 389.707584 -98.768922)
		(end 389.6233 -98.485706)
		(width 0.0889)
		(layer "B.Cu")
		(net "SGPIO_PCH_SSATA_CLOCK")
	)
	(arc
		(start 388.927848 -97.258886)
		(mid 388.716984 -97.051882)
		(end 388.6327 -96.768666)
		(width 0.0889)
		(layer "B.Cu")
		(net "SGPIO_PCH_SSATA_CLOCK")
	)
	(arc
		(start 389.128 -97.59442)
		(mid 389.07165 -97.40057)
		(end 388.927848 -97.258886)
		(width 0.0889)
		(layer "B.Cu")
		(net "SGPIO_PCH_SSATA_CLOCK")
	)
	(arc
		(start 390.1186 -99.31146)
		(mid 390.06225 -99.11761)
		(end 389.918448 -98.975926)
		(width 0.0889)
		(layer "B.Cu")
		(net "SGPIO_PCH_SSATA_CLOCK")
	)
	(arc
		(start 388.6327 -96.725486)
		(mid 388.716981 -96.442269)
		(end 388.927848 -96.235266)
		(width 0.0889)
		(layer "B.Cu")
		(net "SGPIO_PCH_SSATA_CLOCK")
	)
	(arc
		(start 388.927848 -96.235266)
		(mid 389.071652 -96.093583)
		(end 389.128 -95.899732)
		(width 0.0889)
		(layer "B.Cu")
		(net "SGPIO_PCH_SSATA_CLOCK")
	)
	(arc
		(start 390.486392 -100.495608)
		(mid 390.592226 -100.32405)
		(end 390.609836 -100.123244)
		(width 0.0889)
		(layer "B.Cu")
		(net "SGPIO_PCH_SSATA_CLOCK")
	)
	(arc
		(start 390.609836 -100.123244)
		(mid 390.544936 -99.956343)
		(end 390.413748 -99.834446)
		(width 0.0889)
		(layer "B.Cu")
		(net "SGPIO_PCH_SSATA_CLOCK")
	)
	(arc
		(start 389.423148 -98.117406)
		(mid 389.212284 -97.910402)
		(end 389.128 -97.627186)
		(width 0.0889)
		(layer "B.Cu")
		(net "SGPIO_PCH_SSATA_CLOCK")
	)
	(arc
		(start 390.413748 -99.834446)
		(mid 390.202884 -99.627442)
		(end 390.1186 -99.344226)
		(width 0.0889)
		(layer "B.Cu")
		(net "SGPIO_PCH_SSATA_CLOCK")
	)
	(arc
		(start 389.6233 -98.45294)
		(mid 389.56695 -98.25909)
		(end 389.423148 -98.117406)
		(width 0.0889)
		(layer "B.Cu")
		(net "SGPIO_PCH_SSATA_CLOCK")
	)
	(via
		(at 417.741354 -128.397)
		(size 0.508)
		(drill 0.254)
		(layers "F.Cu" "B.Cu")
		(net "SGPIO_PCH_SATA_LOAD_R")
	)
	(via
		(at 392.43 -85.5726)
		(size 0.6604)
		(drill 0.3302)
		(layers "F.Cu" "B.Cu")
		(net "SGPIO_PCH_SATA_LOAD_R")
	)
	(segment
		(start 413.233362 -86.335616)
		(end 413.233362 -85.91042)
		(width 0.10795)
		(layer "B.Cu")
		(net "SGPIO_PCH_SATA_LOAD_R")
	)
	(segment
		(start 393.648438 -83.389216)
		(end 392.966956 -83.389216)
		(width 0.10795)
		(layer "B.Cu")
		(net "SGPIO_PCH_SATA_LOAD_R")
	)
	(segment
		(start 398.747996 -81.851246)
		(end 395.186408 -81.851246)
		(width 0.10795)
		(layer "B.Cu")
		(net "SGPIO_PCH_SATA_LOAD_R")
	)
	(segment
		(start 415.309812 -89.857326)
		(end 415.309812 -88.88349)
		(width 0.10795)
		(layer "B.Cu")
		(net "SGPIO_PCH_SATA_LOAD_R")
	)
	(segment
		(start 418.23132 -119.763286)
		(end 418.230812 -119.762778)
		(width 0.10795)
		(layer "B.Cu")
		(net "SGPIO_PCH_SATA_LOAD_R")
	)
	(segment
		(start 392.43 -85.459824)
		(end 392.43 -85.5726)
		(width 0.10795)
		(layer "B.Cu")
		(net "SGPIO_PCH_SATA_LOAD_R")
	)
	(segment
		(start 402.665184 -82.98053)
		(end 399.87728 -82.98053)
		(width 0.10795)
		(layer "B.Cu")
		(net "SGPIO_PCH_SATA_LOAD_R")
	)
	(segment
		(start 417.941506 -103.855012)
		(end 416.100006 -102.013512)
		(width 0.10795)
		(layer "B.Cu")
		(net "SGPIO_PCH_SATA_LOAD_R")
	)
	(segment
		(start 417.305744 -117.75186)
		(end 417.305744 -108.817156)
		(width 0.10795)
		(layer "B.Cu")
		(net "SGPIO_PCH_SATA_LOAD_R")
	)
	(segment
		(start 392.23061 -84.41563)
		(end 391.983214 -84.663026)
		(width 0.10795)
		(layer "B.Cu")
		(net "SGPIO_PCH_SATA_LOAD_R")
	)
	(segment
		(start 415.78276 -94.5515)
		(end 415.78276 -90.330274)
		(width 0.10795)
		(layer "B.Cu")
		(net "SGPIO_PCH_SATA_LOAD_R")
	)
	(segment
		(start 413.233362 -85.91042)
		(end 412.203646 -84.880704)
		(width 0.10795)
		(layer "B.Cu")
		(net "SGPIO_PCH_SATA_LOAD_R")
	)
	(segment
		(start 420.018718 -121.80824)
		(end 418.23132 -120.020842)
		(width 0.10795)
		(layer "B.Cu")
		(net "SGPIO_PCH_SATA_LOAD_R")
	)
	(segment
		(start 418.23132 -120.020842)
		(end 418.23132 -119.763286)
		(width 0.10795)
		(layer "B.Cu")
		(net "SGPIO_PCH_SATA_LOAD_R")
	)
	(segment
		(start 417.305744 -108.817156)
		(end 417.941506 -108.181394)
		(width 0.10795)
		(layer "B.Cu")
		(net "SGPIO_PCH_SATA_LOAD_R")
	)
	(segment
		(start 430.95799 -152.539954)
		(end 429.525938 -152.539954)
		(width 0.10795)
		(layer "B.Cu")
		(net "SGPIO_PCH_SATA_LOAD_R")
	)
	(segment
		(start 418.230812 -119.762778)
		(end 418.230812 -118.676928)
		(width 0.10795)
		(layer "B.Cu")
		(net "SGPIO_PCH_SATA_LOAD_R")
	)
	(segment
		(start 407.28011 -83.728814)
		(end 403.413468 -83.728814)
		(width 0.10795)
		(layer "B.Cu")
		(net "SGPIO_PCH_SATA_LOAD_R")
	)
	(segment
		(start 395.186408 -81.851246)
		(end 393.648438 -83.389216)
		(width 0.10795)
		(layer "B.Cu")
		(net "SGPIO_PCH_SATA_LOAD_R")
	)
	(segment
		(start 392.43 -85.5726)
		(end 392.43 -86.5505)
		(width 0.10795)
		(layer "B.Cu")
		(net "SGPIO_PCH_SATA_LOAD_R")
	)
	(segment
		(start 432.689 -152.4)
		(end 431.097944 -152.4)
		(width 0.10795)
		(layer "B.Cu")
		(net "SGPIO_PCH_SATA_LOAD_R")
	)
	(segment
		(start 431.097944 -152.4)
		(end 430.95799 -152.539954)
		(width 0.10795)
		(layer "B.Cu")
		(net "SGPIO_PCH_SATA_LOAD_R")
	)
	(segment
		(start 391.983214 -85.013038)
		(end 392.43 -85.459824)
		(width 0.10795)
		(layer "B.Cu")
		(net "SGPIO_PCH_SATA_LOAD_R")
	)
	(segment
		(start 416.100006 -94.868746)
		(end 415.78276 -94.5515)
		(width 0.10795)
		(layer "B.Cu")
		(net "SGPIO_PCH_SATA_LOAD_R")
	)
	(segment
		(start 417.941506 -108.181394)
		(end 417.941506 -103.855012)
		(width 0.10795)
		(layer "B.Cu")
		(net "SGPIO_PCH_SATA_LOAD_R")
	)
	(segment
		(start 414.709356 -87.81161)
		(end 413.233362 -86.335616)
		(width 0.10795)
		(layer "B.Cu")
		(net "SGPIO_PCH_SATA_LOAD_R")
	)
	(segment
		(start 410.541216 -84.112862)
		(end 407.664158 -84.112862)
		(width 0.10795)
		(layer "B.Cu")
		(net "SGPIO_PCH_SATA_LOAD_R")
	)
	(segment
		(start 392.483848 -83.872324)
		(end 392.483848 -84.184744)
		(width 0.10795)
		(layer "B.Cu")
		(net "SGPIO_PCH_SATA_LOAD_R")
	)
	(segment
		(start 392.966956 -83.389216)
		(end 392.483848 -83.872324)
		(width 0.10795)
		(layer "B.Cu")
		(net "SGPIO_PCH_SATA_LOAD_R")
	)
	(segment
		(start 411.309058 -84.880704)
		(end 410.541216 -84.112862)
		(width 0.10795)
		(layer "B.Cu")
		(net "SGPIO_PCH_SATA_LOAD_R")
	)
	(segment
		(start 418.230812 -118.676928)
		(end 417.305744 -117.75186)
		(width 0.10795)
		(layer "B.Cu")
		(net "SGPIO_PCH_SATA_LOAD_R")
	)
	(segment
		(start 417.741354 -127.812292)
		(end 420.018718 -125.534928)
		(width 0.10795)
		(layer "B.Cu")
		(net "SGPIO_PCH_SATA_LOAD_R")
	)
	(segment
		(start 407.664158 -84.112862)
		(end 407.28011 -83.728814)
		(width 0.10795)
		(layer "B.Cu")
		(net "SGPIO_PCH_SATA_LOAD_R")
	)
	(segment
		(start 416.100006 -102.013512)
		(end 416.100006 -94.868746)
		(width 0.10795)
		(layer "B.Cu")
		(net "SGPIO_PCH_SATA_LOAD_R")
	)
	(segment
		(start 392.483848 -84.184744)
		(end 392.252962 -84.41563)
		(width 0.10795)
		(layer "B.Cu")
		(net "SGPIO_PCH_SATA_LOAD_R")
	)
	(segment
		(start 391.983214 -84.663026)
		(end 391.983214 -85.013038)
		(width 0.10795)
		(layer "B.Cu")
		(net "SGPIO_PCH_SATA_LOAD_R")
	)
	(segment
		(start 403.413468 -83.728814)
		(end 402.665184 -82.98053)
		(width 0.10795)
		(layer "B.Cu")
		(net "SGPIO_PCH_SATA_LOAD_R")
	)
	(segment
		(start 412.203646 -84.880704)
		(end 411.309058 -84.880704)
		(width 0.10795)
		(layer "B.Cu")
		(net "SGPIO_PCH_SATA_LOAD_R")
	)
	(segment
		(start 399.87728 -82.98053)
		(end 398.747996 -81.851246)
		(width 0.10795)
		(layer "B.Cu")
		(net "SGPIO_PCH_SATA_LOAD_R")
	)
	(segment
		(start 414.709356 -88.283034)
		(end 414.709356 -87.81161)
		(width 0.10795)
		(layer "B.Cu")
		(net "SGPIO_PCH_SATA_LOAD_R")
	)
	(segment
		(start 420.018718 -125.534928)
		(end 420.018718 -121.80824)
		(width 0.10795)
		(layer "B.Cu")
		(net "SGPIO_PCH_SATA_LOAD_R")
	)
	(segment
		(start 417.741354 -128.397)
		(end 417.741354 -127.812292)
		(width 0.10795)
		(layer "B.Cu")
		(net "SGPIO_PCH_SATA_LOAD_R")
	)
	(segment
		(start 392.252962 -84.41563)
		(end 392.23061 -84.41563)
		(width 0.10795)
		(layer "B.Cu")
		(net "SGPIO_PCH_SATA_LOAD_R")
	)
	(segment
		(start 415.309812 -88.88349)
		(end 414.709356 -88.283034)
		(width 0.10795)
		(layer "B.Cu")
		(net "SGPIO_PCH_SATA_LOAD_R")
	)
	(segment
		(start 415.78276 -90.330274)
		(end 415.309812 -89.857326)
		(width 0.10795)
		(layer "B.Cu")
		(net "SGPIO_PCH_SATA_LOAD_R")
	)
	(segment
		(start 429.525938 -152.539954)
		(end 429.525938 -151.090122)
		(width 0.089408)
		(layer "In9.Cu")
		(net "SGPIO_PCH_SATA_LOAD_R")
	)
	(segment
		(start 422.705276 -135.54583)
		(end 418.556186 -131.39674)
		(width 0.089408)
		(layer "In9.Cu")
		(net "SGPIO_PCH_SATA_LOAD_R")
	)
	(segment
		(start 418.556186 -130.526536)
		(end 417.741354 -129.711704)
		(width 0.089408)
		(layer "In9.Cu")
		(net "SGPIO_PCH_SATA_LOAD_R")
	)
	(segment
		(start 436.019448 -146.248628)
		(end 436.019448 -142.584932)
		(width 0.089408)
		(layer "In9.Cu")
		(net "SGPIO_PCH_SATA_LOAD_R")
	)
	(segment
		(start 429.525938 -151.090122)
		(end 430.34966 -150.2664)
		(width 0.089408)
		(layer "In9.Cu")
		(net "SGPIO_PCH_SATA_LOAD_R")
	)
	(segment
		(start 430.34966 -150.2664)
		(end 432.001676 -150.2664)
		(width 0.089408)
		(layer "In9.Cu")
		(net "SGPIO_PCH_SATA_LOAD_R")
	)
	(segment
		(start 433.535328 -140.100812)
		(end 431.674524 -140.100812)
		(width 0.089408)
		(layer "In9.Cu")
		(net "SGPIO_PCH_SATA_LOAD_R")
	)
	(segment
		(start 424.8658 -136.639046)
		(end 423.772584 -135.54583)
		(width 0.089408)
		(layer "In9.Cu")
		(net "SGPIO_PCH_SATA_LOAD_R")
	)
	(segment
		(start 431.18913 -140.101066)
		(end 429.09109 -138.003026)
		(width 0.089408)
		(layer "In9.Cu")
		(net "SGPIO_PCH_SATA_LOAD_R")
	)
	(segment
		(start 418.556186 -131.39674)
		(end 418.556186 -130.526536)
		(width 0.089408)
		(layer "In9.Cu")
		(net "SGPIO_PCH_SATA_LOAD_R")
	)
	(segment
		(start 432.001676 -150.2664)
		(end 436.019448 -146.248628)
		(width 0.089408)
		(layer "In9.Cu")
		(net "SGPIO_PCH_SATA_LOAD_R")
	)
	(segment
		(start 426.226478 -136.639046)
		(end 424.8658 -136.639046)
		(width 0.089408)
		(layer "In9.Cu")
		(net "SGPIO_PCH_SATA_LOAD_R")
	)
	(segment
		(start 431.674524 -140.100812)
		(end 431.67427 -140.101066)
		(width 0.089408)
		(layer "In9.Cu")
		(net "SGPIO_PCH_SATA_LOAD_R")
	)
	(segment
		(start 436.019448 -142.584932)
		(end 433.535328 -140.100812)
		(width 0.089408)
		(layer "In9.Cu")
		(net "SGPIO_PCH_SATA_LOAD_R")
	)
	(segment
		(start 431.67427 -140.101066)
		(end 431.18913 -140.101066)
		(width 0.089408)
		(layer "In9.Cu")
		(net "SGPIO_PCH_SATA_LOAD_R")
	)
	(segment
		(start 429.09109 -138.003026)
		(end 427.590458 -138.003026)
		(width 0.089408)
		(layer "In9.Cu")
		(net "SGPIO_PCH_SATA_LOAD_R")
	)
	(segment
		(start 417.741354 -129.711704)
		(end 417.741354 -128.397)
		(width 0.089408)
		(layer "In9.Cu")
		(net "SGPIO_PCH_SATA_LOAD_R")
	)
	(segment
		(start 427.590458 -138.003026)
		(end 426.226478 -136.639046)
		(width 0.089408)
		(layer "In9.Cu")
		(net "SGPIO_PCH_SATA_LOAD_R")
	)
	(segment
		(start 423.772584 -135.54583)
		(end 422.705276 -135.54583)
		(width 0.089408)
		(layer "In9.Cu")
		(net "SGPIO_PCH_SATA_LOAD_R")
	)
	(segment
		(start 389.7376 -96.96831)
		(end 390.21385 -96.747076)
		(width 0.10795)
		(layer "F.Cu")
		(net "SGPIO_PCH_SATA_LOAD")
	)
	(segment
		(start 389.71855 -96.9772)
		(end 389.7376 -96.96831)
		(width 0.10795)
		(layer "F.Cu")
		(net "SGPIO_PCH_SATA_LOAD")
	)
	(via
		(at 390.3472 -93.2942)
		(size 0.6604)
		(drill 0.3302)
		(layers "F.Cu" "B.Cu")
		(net "SGPIO_PCH_SATA_LOAD")
	)
	(via
		(at 390.21385 -96.747076)
		(size 0.508)
		(drill 0.254)
		(layers "F.Cu" "B.Cu")
		(net "SGPIO_PCH_SATA_LOAD")
	)
	(segment
		(start 390.3472 -94.095062)
		(end 390.3472 -93.2942)
		(width 0.10795)
		(layer "B.Cu")
		(net "SGPIO_PCH_SATA_LOAD")
	)
	(segment
		(start 390.470644 -95.431356)
		(end 390.652 -95.25)
		(width 0.10795)
		(layer "B.Cu")
		(net "SGPIO_PCH_SATA_LOAD")
	)
	(segment
		(start 391.284714 -88.5698)
		(end 390.639808 -88.5698)
		(width 0.10795)
		(layer "B.Cu")
		(net "SGPIO_PCH_SATA_LOAD")
	)
	(segment
		(start 390.35101 -88.858598)
		(end 390.35101 -90.606626)
		(width 0.10795)
		(layer "B.Cu")
		(net "SGPIO_PCH_SATA_LOAD")
	)
	(segment
		(start 390.025636 -90.932)
		(end 390.025636 -92.512642)
		(width 0.10795)
		(layer "B.Cu")
		(net "SGPIO_PCH_SATA_LOAD")
	)
	(segment
		(start 391.95375 -87.900764)
		(end 391.284714 -88.5698)
		(width 0.10795)
		(layer "B.Cu")
		(net "SGPIO_PCH_SATA_LOAD")
	)
	(segment
		(start 390.639808 -88.5698)
		(end 390.35101 -88.858598)
		(width 0.10795)
		(layer "B.Cu")
		(net "SGPIO_PCH_SATA_LOAD")
	)
	(segment
		(start 391.95375 -87.899748)
		(end 391.95375 -87.900764)
		(width 0.10795)
		(layer "B.Cu")
		(net "SGPIO_PCH_SATA_LOAD")
	)
	(segment
		(start 390.04494 -97.040192)
		(end 389.9662 -97.061274)
		(width 0.0889)
		(layer "B.Cu")
		(net "SGPIO_PCH_SATA_LOAD")
	)
	(segment
		(start 390.652 -95.25)
		(end 390.652 -94.399862)
		(width 0.10795)
		(layer "B.Cu")
		(net "SGPIO_PCH_SATA_LOAD")
	)
	(segment
		(start 390.35101 -90.606626)
		(end 390.025636 -90.932)
		(width 0.10795)
		(layer "B.Cu")
		(net "SGPIO_PCH_SATA_LOAD")
	)
	(segment
		(start 390.21385 -96.747076)
		(end 390.04494 -97.040192)
		(width 0.0889)
		(layer "B.Cu")
		(net "SGPIO_PCH_SATA_LOAD")
	)
	(segment
		(start 392.413998 -87.4395)
		(end 391.95375 -87.899748)
		(width 0.10795)
		(layer "B.Cu")
		(net "SGPIO_PCH_SATA_LOAD")
	)
	(segment
		(start 392.43 -87.4395)
		(end 392.413998 -87.4395)
		(width 0.10795)
		(layer "B.Cu")
		(net "SGPIO_PCH_SATA_LOAD")
	)
	(segment
		(start 390.025636 -92.512642)
		(end 390.3472 -92.834206)
		(width 0.10795)
		(layer "B.Cu")
		(net "SGPIO_PCH_SATA_LOAD")
	)
	(segment
		(start 389.8138 -96.758252)
		(end 389.8138 -96.7359)
		(width 0.0889)
		(layer "B.Cu")
		(net "SGPIO_PCH_SATA_LOAD")
	)
	(segment
		(start 390.3091 -95.910146)
		(end 390.3091 -95.5929)
		(width 0.0889)
		(layer "B.Cu")
		(net "SGPIO_PCH_SATA_LOAD")
	)
	(segment
		(start 390.3091 -95.5929)
		(end 390.470644 -95.431356)
		(width 0.0889)
		(layer "B.Cu")
		(net "SGPIO_PCH_SATA_LOAD")
	)
	(segment
		(start 390.652 -94.399862)
		(end 390.3472 -94.095062)
		(width 0.10795)
		(layer "B.Cu")
		(net "SGPIO_PCH_SATA_LOAD")
	)
	(segment
		(start 390.3472 -92.834206)
		(end 390.3472 -93.2942)
		(width 0.10795)
		(layer "B.Cu")
		(net "SGPIO_PCH_SATA_LOAD")
	)
	(arc
		(start 389.8138 -96.7359)
		(mid 389.87015 -96.54205)
		(end 390.013952 -96.400366)
		(width 0.0889)
		(layer "B.Cu")
		(net "SGPIO_PCH_SATA_LOAD")
	)
	(arc
		(start 389.9662 -97.061274)
		(mid 389.856288 -96.926712)
		(end 389.8138 -96.758252)
		(width 0.0889)
		(layer "B.Cu")
		(net "SGPIO_PCH_SATA_LOAD")
	)
	(arc
		(start 390.013952 -96.400366)
		(mid 390.224816 -96.193362)
		(end 390.3091 -95.910146)
		(width 0.0889)
		(layer "B.Cu")
		(net "SGPIO_PCH_SATA_LOAD")
	)
	(via
		(at 416.93338 -128.626362)
		(size 0.508)
		(drill 0.254)
		(layers "F.Cu" "B.Cu")
		(net "SGPIO_PCH_SATA_DOUT0_R")
	)
	(via
		(at 420.674038 -127.902208)
		(size 0.6604)
		(drill 0.3302)
		(layers "F.Cu" "B.Cu")
		(net "SGPIO_PCH_SATA_DOUT0_R")
	)
	(segment
		(start 411.678628 -83.293204)
		(end 407.8859 -83.293204)
		(width 0.10795)
		(layer "B.Cu")
		(net "SGPIO_PCH_SATA_DOUT0_R")
	)
	(segment
		(start 420.674038 -127.902208)
		(end 421.25773 -127.902208)
		(width 0.10795)
		(layer "B.Cu")
		(net "SGPIO_PCH_SATA_DOUT0_R")
	)
	(segment
		(start 417.808156 -93.79839)
		(end 417.808156 -90.611706)
		(width 0.10795)
		(layer "B.Cu")
		(net "SGPIO_PCH_SATA_DOUT0_R")
	)
	(segment
		(start 391.557002 -84.323428)
		(end 391.557002 -85.029802)
		(width 0.10795)
		(layer "B.Cu")
		(net "SGPIO_PCH_SATA_DOUT0_R")
	)
	(segment
		(start 422.805098 -121.62536)
		(end 419.096952 -117.917214)
		(width 0.10795)
		(layer "B.Cu")
		(net "SGPIO_PCH_SATA_DOUT0_R")
	)
	(segment
		(start 422.805098 -126.35484)
		(end 422.805098 -122.50801)
		(width 0.10795)
		(layer "B.Cu")
		(net "SGPIO_PCH_SATA_DOUT0_R")
	)
	(segment
		(start 430.276 -149.568916)
		(end 431.964084 -151.257)
		(width 0.10795)
		(layer "B.Cu")
		(net "SGPIO_PCH_SATA_DOUT0_R")
	)
	(segment
		(start 422.805352 -122.271536)
		(end 422.805098 -122.271282)
		(width 0.10795)
		(layer "B.Cu")
		(net "SGPIO_PCH_SATA_DOUT0_R")
	)
	(segment
		(start 421.25773 -127.902208)
		(end 422.805098 -126.35484)
		(width 0.10795)
		(layer "B.Cu")
		(net "SGPIO_PCH_SATA_DOUT0_R")
	)
	(segment
		(start 403.770084 -81.345532)
		(end 402.420836 -82.69478)
		(width 0.10795)
		(layer "B.Cu")
		(net "SGPIO_PCH_SATA_DOUT0_R")
	)
	(segment
		(start 416.457638 -90.196924)
		(end 415.881312 -89.620598)
		(width 0.10795)
		(layer "B.Cu")
		(net "SGPIO_PCH_SATA_DOUT0_R")
	)
	(segment
		(start 417.808156 -90.611706)
		(end 417.393374 -90.196924)
		(width 0.10795)
		(layer "B.Cu")
		(net "SGPIO_PCH_SATA_DOUT0_R")
	)
	(segment
		(start 422.805098 -122.271282)
		(end 422.805098 -121.62536)
		(width 0.10795)
		(layer "B.Cu")
		(net "SGPIO_PCH_SATA_DOUT0_R")
	)
	(segment
		(start 431.964084 -151.257)
		(end 432.689 -151.257)
		(width 0.10795)
		(layer "B.Cu")
		(net "SGPIO_PCH_SATA_DOUT0_R")
	)
	(segment
		(start 404.857458 -81.345532)
		(end 403.770084 -81.345532)
		(width 0.10795)
		(layer "B.Cu")
		(net "SGPIO_PCH_SATA_DOUT0_R")
	)
	(segment
		(start 391.557002 -85.029802)
		(end 391.668 -85.1408)
		(width 0.10795)
		(layer "B.Cu")
		(net "SGPIO_PCH_SATA_DOUT0_R")
	)
	(segment
		(start 402.420836 -82.69478)
		(end 399.995644 -82.69478)
		(width 0.10795)
		(layer "B.Cu")
		(net "SGPIO_PCH_SATA_DOUT0_R")
	)
	(segment
		(start 417.364926 -129.057908)
		(end 416.93338 -128.626362)
		(width 0.10795)
		(layer "B.Cu")
		(net "SGPIO_PCH_SATA_DOUT0_R")
	)
	(segment
		(start 417.306506 -94.30004)
		(end 417.808156 -93.79839)
		(width 0.10795)
		(layer "B.Cu")
		(net "SGPIO_PCH_SATA_DOUT0_R")
	)
	(segment
		(start 414.865312 -84.926424)
		(end 413.311848 -84.926424)
		(width 0.10795)
		(layer "B.Cu")
		(net "SGPIO_PCH_SATA_DOUT0_R")
	)
	(segment
		(start 407.353516 -82.76082)
		(end 406.272746 -82.76082)
		(width 0.10795)
		(layer "B.Cu")
		(net "SGPIO_PCH_SATA_DOUT0_R")
	)
	(segment
		(start 399.995644 -82.69478)
		(end 398.86636 -81.565496)
		(width 0.10795)
		(layer "B.Cu")
		(net "SGPIO_PCH_SATA_DOUT0_R")
	)
	(segment
		(start 415.881312 -85.942424)
		(end 414.865312 -84.926424)
		(width 0.10795)
		(layer "B.Cu")
		(net "SGPIO_PCH_SATA_DOUT0_R")
	)
	(segment
		(start 417.393374 -90.196924)
		(end 416.457638 -90.196924)
		(width 0.10795)
		(layer "B.Cu")
		(net "SGPIO_PCH_SATA_DOUT0_R")
	)
	(segment
		(start 391.668 -85.1408)
		(end 391.668 -86.5505)
		(width 0.10795)
		(layer "B.Cu")
		(net "SGPIO_PCH_SATA_DOUT0_R")
	)
	(segment
		(start 415.881312 -89.620598)
		(end 415.881312 -85.942424)
		(width 0.10795)
		(layer "B.Cu")
		(net "SGPIO_PCH_SATA_DOUT0_R")
	)
	(segment
		(start 398.86636 -81.565496)
		(end 395.068044 -81.565496)
		(width 0.10795)
		(layer "B.Cu")
		(net "SGPIO_PCH_SATA_DOUT0_R")
	)
	(segment
		(start 419.096952 -103.202994)
		(end 417.306506 -101.412548)
		(width 0.10795)
		(layer "B.Cu")
		(net "SGPIO_PCH_SATA_DOUT0_R")
	)
	(segment
		(start 417.306506 -101.412548)
		(end 417.306506 -94.30004)
		(width 0.10795)
		(layer "B.Cu")
		(net "SGPIO_PCH_SATA_DOUT0_R")
	)
	(segment
		(start 393.530074 -83.103466)
		(end 392.776964 -83.103466)
		(width 0.10795)
		(layer "B.Cu")
		(net "SGPIO_PCH_SATA_DOUT0_R")
	)
	(segment
		(start 407.8859 -83.293204)
		(end 407.353516 -82.76082)
		(width 0.10795)
		(layer "B.Cu")
		(net "SGPIO_PCH_SATA_DOUT0_R")
	)
	(segment
		(start 419.096952 -117.917214)
		(end 419.096952 -103.202994)
		(width 0.10795)
		(layer "B.Cu")
		(net "SGPIO_PCH_SATA_DOUT0_R")
	)
	(segment
		(start 392.776964 -83.103466)
		(end 391.557002 -84.323428)
		(width 0.10795)
		(layer "B.Cu")
		(net "SGPIO_PCH_SATA_DOUT0_R")
	)
	(segment
		(start 419.518338 -129.057908)
		(end 417.364926 -129.057908)
		(width 0.10795)
		(layer "B.Cu")
		(net "SGPIO_PCH_SATA_DOUT0_R")
	)
	(segment
		(start 422.805098 -122.50801)
		(end 422.805352 -122.507756)
		(width 0.10795)
		(layer "B.Cu")
		(net "SGPIO_PCH_SATA_DOUT0_R")
	)
	(segment
		(start 406.272746 -82.76082)
		(end 404.857458 -81.345532)
		(width 0.10795)
		(layer "B.Cu")
		(net "SGPIO_PCH_SATA_DOUT0_R")
	)
	(segment
		(start 420.674038 -127.902208)
		(end 419.518338 -129.057908)
		(width 0.10795)
		(layer "B.Cu")
		(net "SGPIO_PCH_SATA_DOUT0_R")
	)
	(segment
		(start 395.068044 -81.565496)
		(end 393.530074 -83.103466)
		(width 0.10795)
		(layer "B.Cu")
		(net "SGPIO_PCH_SATA_DOUT0_R")
	)
	(segment
		(start 413.311848 -84.926424)
		(end 411.678628 -83.293204)
		(width 0.10795)
		(layer "B.Cu")
		(net "SGPIO_PCH_SATA_DOUT0_R")
	)
	(segment
		(start 422.805352 -122.507756)
		(end 422.805352 -122.271536)
		(width 0.10795)
		(layer "B.Cu")
		(net "SGPIO_PCH_SATA_DOUT0_R")
	)
	(segment
		(start 430.276 -147.340066)
		(end 430.276 -149.568916)
		(width 0.10795)
		(layer "B.Cu")
		(net "SGPIO_PCH_SATA_DOUT0_R")
	)
	(segment
		(start 416.818064 -130.941064)
		(end 416.818064 -128.741678)
		(width 0.089408)
		(layer "In9.Cu")
		(net "SGPIO_PCH_SATA_DOUT0_R")
	)
	(segment
		(start 423.493438 -137.616438)
		(end 416.818064 -130.941064)
		(width 0.089408)
		(layer "In9.Cu")
		(net "SGPIO_PCH_SATA_DOUT0_R")
	)
	(segment
		(start 430.276 -147.340066)
		(end 430.58207 -147.646136)
		(width 0.089408)
		(layer "In9.Cu")
		(net "SGPIO_PCH_SATA_DOUT0_R")
	)
	(segment
		(start 432.441604 -147.646136)
		(end 435.091332 -144.996408)
		(width 0.089408)
		(layer "In9.Cu")
		(net "SGPIO_PCH_SATA_DOUT0_R")
	)
	(segment
		(start 416.818064 -128.741678)
		(end 416.93338 -128.626362)
		(width 0.089408)
		(layer "In9.Cu")
		(net "SGPIO_PCH_SATA_DOUT0_R")
	)
	(segment
		(start 430.58207 -147.646136)
		(end 432.441604 -147.646136)
		(width 0.089408)
		(layer "In9.Cu")
		(net "SGPIO_PCH_SATA_DOUT0_R")
	)
	(segment
		(start 435.091332 -143.483584)
		(end 432.655472 -141.047724)
		(width 0.089408)
		(layer "In9.Cu")
		(net "SGPIO_PCH_SATA_DOUT0_R")
	)
	(segment
		(start 423.493438 -139.891262)
		(end 423.493438 -137.616438)
		(width 0.089408)
		(layer "In9.Cu")
		(net "SGPIO_PCH_SATA_DOUT0_R")
	)
	(segment
		(start 424.6499 -141.047724)
		(end 423.493438 -139.891262)
		(width 0.089408)
		(layer "In9.Cu")
		(net "SGPIO_PCH_SATA_DOUT0_R")
	)
	(segment
		(start 432.655472 -141.047724)
		(end 424.6499 -141.047724)
		(width 0.089408)
		(layer "In9.Cu")
		(net "SGPIO_PCH_SATA_DOUT0_R")
	)
	(segment
		(start 435.091332 -144.996408)
		(end 435.091332 -143.483584)
		(width 0.089408)
		(layer "In9.Cu")
		(net "SGPIO_PCH_SATA_DOUT0_R")
	)
	(segment
		(start 389.71855 -97.605596)
		(end 389.22325 -97.83572)
		(width 0.10795)
		(layer "F.Cu")
		(net "SGPIO_PCH_SATA_DOUT0")
	)
	(via
		(at 389.636 -94.361)
		(size 0.6604)
		(drill 0.3302)
		(layers "F.Cu" "B.Cu")
		(net "SGPIO_PCH_SATA_DOUT0")
	)
	(via
		(at 389.71855 -97.605596)
		(size 0.508)
		(drill 0.254)
		(layers "F.Cu" "B.Cu")
		(net "SGPIO_PCH_SATA_DOUT0")
	)
	(segment
		(start 389.636 -95.180404)
		(end 389.636 -94.361)
		(width 0.10795)
		(layer "B.Cu")
		(net "SGPIO_PCH_SATA_DOUT0")
	)
	(segment
		(start 389.056626 -91.436698)
		(end 389.056626 -93.28912)
		(width 0.10795)
		(layer "B.Cu")
		(net "SGPIO_PCH_SATA_DOUT0")
	)
	(segment
		(start 389.636 -93.868494)
		(end 389.636 -94.361)
		(width 0.10795)
		(layer "B.Cu")
		(net "SGPIO_PCH_SATA_DOUT0")
	)
	(segment
		(start 391.668 -87.4395)
		(end 391.668 -87.7824)
		(width 0.10795)
		(layer "B.Cu")
		(net "SGPIO_PCH_SATA_DOUT0")
	)
	(segment
		(start 390.1186 -95.899732)
		(end 390.1186 -95.663004)
		(width 0.0889)
		(layer "B.Cu")
		(net "SGPIO_PCH_SATA_DOUT0")
	)
	(segment
		(start 391.668 -87.7824)
		(end 391.16635 -88.28405)
		(width 0.10795)
		(layer "B.Cu")
		(net "SGPIO_PCH_SATA_DOUT0")
	)
	(segment
		(start 389.6233 -96.768666)
		(end 389.6233 -96.725486)
		(width 0.0889)
		(layer "B.Cu")
		(net "SGPIO_PCH_SATA_DOUT0")
	)
	(segment
		(start 390.518396 -88.28405)
		(end 390.017 -88.785446)
		(width 0.10795)
		(layer "B.Cu")
		(net "SGPIO_PCH_SATA_DOUT0")
	)
	(segment
		(start 389.808466 -95.35287)
		(end 389.636 -95.180404)
		(width 0.10795)
		(layer "B.Cu")
		(net "SGPIO_PCH_SATA_DOUT0")
	)
	(segment
		(start 389.056626 -93.28912)
		(end 389.636 -93.868494)
		(width 0.10795)
		(layer "B.Cu")
		(net "SGPIO_PCH_SATA_DOUT0")
	)
	(segment
		(start 389.88746 -97.31248)
		(end 389.86333 -97.223072)
		(width 0.0889)
		(layer "B.Cu")
		(net "SGPIO_PCH_SATA_DOUT0")
	)
	(segment
		(start 389.71855 -97.605596)
		(end 389.88746 -97.31248)
		(width 0.0889)
		(layer "B.Cu")
		(net "SGPIO_PCH_SATA_DOUT0")
	)
	(segment
		(start 390.017 -88.785446)
		(end 390.017 -90.476324)
		(width 0.10795)
		(layer "B.Cu")
		(net "SGPIO_PCH_SATA_DOUT0")
	)
	(segment
		(start 390.017 -90.476324)
		(end 389.056626 -91.436698)
		(width 0.10795)
		(layer "B.Cu")
		(net "SGPIO_PCH_SATA_DOUT0")
	)
	(segment
		(start 390.1186 -95.663004)
		(end 389.808466 -95.35287)
		(width 0.0889)
		(layer "B.Cu")
		(net "SGPIO_PCH_SATA_DOUT0")
	)
	(segment
		(start 391.16635 -88.28405)
		(end 390.518396 -88.28405)
		(width 0.10795)
		(layer "B.Cu")
		(net "SGPIO_PCH_SATA_DOUT0")
	)
	(arc
		(start 389.918448 -96.235266)
		(mid 390.062252 -96.093583)
		(end 390.1186 -95.899732)
		(width 0.0889)
		(layer "B.Cu")
		(net "SGPIO_PCH_SATA_DOUT0")
	)
	(arc
		(start 389.86333 -97.223072)
		(mid 389.691336 -97.023327)
		(end 389.6233 -96.768666)
		(width 0.0889)
		(layer "B.Cu")
		(net "SGPIO_PCH_SATA_DOUT0")
	)
	(arc
		(start 389.6233 -96.725486)
		(mid 389.707581 -96.442269)
		(end 389.918448 -96.235266)
		(width 0.0889)
		(layer "B.Cu")
		(net "SGPIO_PCH_SATA_DOUT0")
	)
	(via
		(at 390.096502 -82.94116)
		(size 0.6604)
		(drill 0.3302)
		(layers "F.Cu" "B.Cu")
		(net "SGPIO_PCH_SATA_CLOCK_R")
	)
	(via
		(at 418.931344 -129.921508)
		(size 0.508)
		(drill 0.254)
		(layers "F.Cu" "B.Cu")
		(net "SGPIO_PCH_SATA_CLOCK_R")
	)
	(segment
		(start 418.86505 -87.86495)
		(end 415.4551 -84.455)
		(width 0.10795)
		(layer "B.Cu")
		(net "SGPIO_PCH_SATA_CLOCK_R")
	)
	(segment
		(start 404.975822 -81.059782)
		(end 403.65172 -81.059782)
		(width 0.10795)
		(layer "B.Cu")
		(net "SGPIO_PCH_SATA_CLOCK_R")
	)
	(segment
		(start 417.92525 -94.646496)
		(end 418.437568 -94.134178)
		(width 0.10795)
		(layer "B.Cu")
		(net "SGPIO_PCH_SATA_CLOCK_R")
	)
	(segment
		(start 419.382702 -117.757702)
		(end 419.382702 -103.025702)
		(width 0.10795)
		(layer "B.Cu")
		(net "SGPIO_PCH_SATA_CLOCK_R")
	)
	(segment
		(start 418.96157 -129.921508)
		(end 418.96157 -129.951988)
		(width 0.10795)
		(layer "B.Cu")
		(net "SGPIO_PCH_SATA_CLOCK_R")
	)
	(segment
		(start 402.873972 -81.83753)
		(end 401.369784 -81.83753)
		(width 0.10795)
		(layer "B.Cu")
		(net "SGPIO_PCH_SATA_CLOCK_R")
	)
	(segment
		(start 393.692126 -79.0956)
		(end 392.974322 -79.0956)
		(width 0.10795)
		(layer "B.Cu")
		(net "SGPIO_PCH_SATA_CLOCK_R")
	)
	(segment
		(start 392.974322 -79.0956)
		(end 391.729722 -80.3402)
		(width 0.10795)
		(layer "B.Cu")
		(net "SGPIO_PCH_SATA_CLOCK_R")
	)
	(segment
		(start 408.178 -82.969862)
		(end 407.589736 -82.381598)
		(width 0.10795)
		(layer "B.Cu")
		(net "SGPIO_PCH_SATA_CLOCK_R")
	)
	(segment
		(start 419.382702 -103.025702)
		(end 417.92525 -101.56825)
		(width 0.10795)
		(layer "B.Cu")
		(net "SGPIO_PCH_SATA_CLOCK_R")
	)
	(segment
		(start 423.545 -126.365)
		(end 423.545 -121.92)
		(width 0.10795)
		(layer "B.Cu")
		(net "SGPIO_PCH_SATA_CLOCK_R")
	)
	(segment
		(start 389.382 -83.655662)
		(end 390.096502 -82.94116)
		(width 0.10795)
		(layer "B.Cu")
		(net "SGPIO_PCH_SATA_CLOCK_R")
	)
	(segment
		(start 395.546326 -80.9498)
		(end 393.692126 -79.0956)
		(width 0.10795)
		(layer "B.Cu")
		(net "SGPIO_PCH_SATA_CLOCK_R")
	)
	(segment
		(start 406.297638 -82.381598)
		(end 404.975822 -81.059782)
		(width 0.10795)
		(layer "B.Cu")
		(net "SGPIO_PCH_SATA_CLOCK_R")
	)
	(segment
		(start 407.589736 -82.381598)
		(end 406.297638 -82.381598)
		(width 0.10795)
		(layer "B.Cu")
		(net "SGPIO_PCH_SATA_CLOCK_R")
	)
	(segment
		(start 418.96157 -129.951988)
		(end 419.396672 -130.38709)
		(width 0.10795)
		(layer "B.Cu")
		(net "SGPIO_PCH_SATA_CLOCK_R")
	)
	(segment
		(start 390.44626 -82.591402)
		(end 390.096502 -82.94116)
		(width 0.10795)
		(layer "B.Cu")
		(net "SGPIO_PCH_SATA_CLOCK_R")
	)
	(segment
		(start 423.662348 -127.038862)
		(end 423.662348 -126.482348)
		(width 0.10795)
		(layer "B.Cu")
		(net "SGPIO_PCH_SATA_CLOCK_R")
	)
	(segment
		(start 389.382 -86.5505)
		(end 389.382 -83.655662)
		(width 0.10795)
		(layer "B.Cu")
		(net "SGPIO_PCH_SATA_CLOCK_R")
	)
	(segment
		(start 418.437568 -94.134178)
		(end 418.437568 -90.320368)
		(width 0.10795)
		(layer "B.Cu")
		(net "SGPIO_PCH_SATA_CLOCK_R")
	)
	(segment
		(start 400.482054 -80.9498)
		(end 395.546326 -80.9498)
		(width 0.10795)
		(layer "B.Cu")
		(net "SGPIO_PCH_SATA_CLOCK_R")
	)
	(segment
		(start 429.525938 -154.215338)
		(end 429.525938 -156.340048)
		(width 0.10795)
		(layer "B.Cu")
		(net "SGPIO_PCH_SATA_CLOCK_R")
	)
	(segment
		(start 418.437568 -90.320368)
		(end 418.86505 -89.892886)
		(width 0.10795)
		(layer "B.Cu")
		(net "SGPIO_PCH_SATA_CLOCK_R")
	)
	(segment
		(start 403.65172 -81.059782)
		(end 402.873972 -81.83753)
		(width 0.10795)
		(layer "B.Cu")
		(net "SGPIO_PCH_SATA_CLOCK_R")
	)
	(segment
		(start 418.86505 -89.892886)
		(end 418.86505 -87.86495)
		(width 0.10795)
		(layer "B.Cu")
		(net "SGPIO_PCH_SATA_CLOCK_R")
	)
	(segment
		(start 420.31412 -130.38709)
		(end 423.662348 -127.038862)
		(width 0.10795)
		(layer "B.Cu")
		(net "SGPIO_PCH_SATA_CLOCK_R")
	)
	(segment
		(start 419.396672 -130.38709)
		(end 420.31412 -130.38709)
		(width 0.10795)
		(layer "B.Cu")
		(net "SGPIO_PCH_SATA_CLOCK_R")
	)
	(segment
		(start 413.409892 -84.455)
		(end 411.924754 -82.969862)
		(width 0.10795)
		(layer "B.Cu")
		(net "SGPIO_PCH_SATA_CLOCK_R")
	)
	(segment
		(start 417.92525 -101.56825)
		(end 417.92525 -94.646496)
		(width 0.10795)
		(layer "B.Cu")
		(net "SGPIO_PCH_SATA_CLOCK_R")
	)
	(segment
		(start 401.369784 -81.83753)
		(end 400.482054 -80.9498)
		(width 0.10795)
		(layer "B.Cu")
		(net "SGPIO_PCH_SATA_CLOCK_R")
	)
	(segment
		(start 423.662348 -126.482348)
		(end 423.545 -126.365)
		(width 0.10795)
		(layer "B.Cu")
		(net "SGPIO_PCH_SATA_CLOCK_R")
	)
	(segment
		(start 415.4551 -84.455)
		(end 413.409892 -84.455)
		(width 0.10795)
		(layer "B.Cu")
		(net "SGPIO_PCH_SATA_CLOCK_R")
	)
	(segment
		(start 418.931344 -129.921508)
		(end 418.96157 -129.921508)
		(width 0.10795)
		(layer "B.Cu")
		(net "SGPIO_PCH_SATA_CLOCK_R")
	)
	(segment
		(start 391.729722 -80.3402)
		(end 390.779 -80.3402)
		(width 0.10795)
		(layer "B.Cu")
		(net "SGPIO_PCH_SATA_CLOCK_R")
	)
	(segment
		(start 390.44626 -80.67294)
		(end 390.44626 -82.591402)
		(width 0.10795)
		(layer "B.Cu")
		(net "SGPIO_PCH_SATA_CLOCK_R")
	)
	(segment
		(start 432.689 -153.543)
		(end 430.198276 -153.543)
		(width 0.10795)
		(layer "B.Cu")
		(net "SGPIO_PCH_SATA_CLOCK_R")
	)
	(segment
		(start 390.779 -80.3402)
		(end 390.44626 -80.67294)
		(width 0.10795)
		(layer "B.Cu")
		(net "SGPIO_PCH_SATA_CLOCK_R")
	)
	(segment
		(start 411.924754 -82.969862)
		(end 408.178 -82.969862)
		(width 0.10795)
		(layer "B.Cu")
		(net "SGPIO_PCH_SATA_CLOCK_R")
	)
	(segment
		(start 430.198276 -153.543)
		(end 429.525938 -154.215338)
		(width 0.10795)
		(layer "B.Cu")
		(net "SGPIO_PCH_SATA_CLOCK_R")
	)
	(segment
		(start 423.545 -121.92)
		(end 419.382702 -117.757702)
		(width 0.10795)
		(layer "B.Cu")
		(net "SGPIO_PCH_SATA_CLOCK_R")
	)
	(segment
		(start 432.8033 -152.866852)
		(end 432.076352 -153.5938)
		(width 0.089408)
		(layer "In9.Cu")
		(net "SGPIO_PCH_SATA_CLOCK_R")
	)
	(segment
		(start 427.277784 -136.607804)
		(end 427.277784 -136.619234)
		(width 0.089408)
		(layer "In9.Cu")
		(net "SGPIO_PCH_SATA_CLOCK_R")
	)
	(segment
		(start 432.8033 -150.292816)
		(end 432.8033 -152.866852)
		(width 0.089408)
		(layer "In9.Cu")
		(net "SGPIO_PCH_SATA_CLOCK_R")
	)
	(segment
		(start 433.778152 -139.515596)
		(end 436.606442 -142.343886)
		(width 0.089408)
		(layer "In9.Cu")
		(net "SGPIO_PCH_SATA_CLOCK_R")
	)
	(segment
		(start 427.27753 -136.619488)
		(end 427.27753 -136.861804)
		(width 0.089408)
		(layer "In9.Cu")
		(net "SGPIO_PCH_SATA_CLOCK_R")
	)
	(segment
		(start 431.4317 -139.515596)
		(end 433.778152 -139.515596)
		(width 0.089408)
		(layer "In9.Cu")
		(net "SGPIO_PCH_SATA_CLOCK_R")
	)
	(segment
		(start 432.076352 -153.5938)
		(end 430.858422 -153.5938)
		(width 0.089408)
		(layer "In9.Cu")
		(net "SGPIO_PCH_SATA_CLOCK_R")
	)
	(segment
		(start 418.931344 -129.921508)
		(end 419.02761 -129.921508)
		(width 0.089408)
		(layer "In9.Cu")
		(net "SGPIO_PCH_SATA_CLOCK_R")
	)
	(segment
		(start 426.919644 -135.613902)
		(end 427.154086 -135.848344)
		(width 0.089408)
		(layer "In9.Cu")
		(net "SGPIO_PCH_SATA_CLOCK_R")
	)
	(segment
		(start 425.142914 -136.036812)
		(end 426.16501 -136.036812)
		(width 0.089408)
		(layer "In9.Cu")
		(net "SGPIO_PCH_SATA_CLOCK_R")
	)
	(segment
		(start 427.154086 -135.848344)
		(end 427.154086 -136.180068)
		(width 0.089408)
		(layer "In9.Cu")
		(net "SGPIO_PCH_SATA_CLOCK_R")
	)
	(segment
		(start 419.02761 -129.921508)
		(end 425.142914 -136.036812)
		(width 0.089408)
		(layer "In9.Cu")
		(net "SGPIO_PCH_SATA_CLOCK_R")
	)
	(segment
		(start 427.277784 -136.619234)
		(end 427.27753 -136.619488)
		(width 0.089408)
		(layer "In9.Cu")
		(net "SGPIO_PCH_SATA_CLOCK_R")
	)
	(segment
		(start 436.606442 -146.159982)
		(end 436.604664 -146.16176)
		(width 0.089408)
		(layer "In9.Cu")
		(net "SGPIO_PCH_SATA_CLOCK_R")
	)
	(segment
		(start 427.27753 -136.861804)
		(end 427.833536 -137.41781)
		(width 0.089408)
		(layer "In9.Cu")
		(net "SGPIO_PCH_SATA_CLOCK_R")
	)
	(segment
		(start 436.606442 -142.343886)
		(end 436.606442 -146.159982)
		(width 0.089408)
		(layer "In9.Cu")
		(net "SGPIO_PCH_SATA_CLOCK_R")
	)
	(segment
		(start 430.858422 -153.5938)
		(end 429.525938 -154.926284)
		(width 0.089408)
		(layer "In9.Cu")
		(net "SGPIO_PCH_SATA_CLOCK_R")
	)
	(segment
		(start 436.604664 -146.16176)
		(end 436.604664 -146.491452)
		(width 0.089408)
		(layer "In9.Cu")
		(net "SGPIO_PCH_SATA_CLOCK_R")
	)
	(segment
		(start 426.58792 -135.613902)
		(end 426.919644 -135.613902)
		(width 0.089408)
		(layer "In9.Cu")
		(net "SGPIO_PCH_SATA_CLOCK_R")
	)
	(segment
		(start 427.04639 -136.287764)
		(end 427.04639 -136.37641)
		(width 0.089408)
		(layer "In9.Cu")
		(net "SGPIO_PCH_SATA_CLOCK_R")
	)
	(segment
		(start 427.154086 -136.180068)
		(end 427.04639 -136.287764)
		(width 0.089408)
		(layer "In9.Cu")
		(net "SGPIO_PCH_SATA_CLOCK_R")
	)
	(segment
		(start 427.833536 -137.41781)
		(end 429.333914 -137.41781)
		(width 0.089408)
		(layer "In9.Cu")
		(net "SGPIO_PCH_SATA_CLOCK_R")
	)
	(segment
		(start 427.04639 -136.37641)
		(end 427.277784 -136.607804)
		(width 0.089408)
		(layer "In9.Cu")
		(net "SGPIO_PCH_SATA_CLOCK_R")
	)
	(segment
		(start 429.525938 -154.926284)
		(end 429.525938 -156.340048)
		(width 0.089408)
		(layer "In9.Cu")
		(net "SGPIO_PCH_SATA_CLOCK_R")
	)
	(segment
		(start 429.333914 -137.41781)
		(end 431.4317 -139.515596)
		(width 0.089408)
		(layer "In9.Cu")
		(net "SGPIO_PCH_SATA_CLOCK_R")
	)
	(segment
		(start 436.604664 -146.491452)
		(end 432.8033 -150.292816)
		(width 0.089408)
		(layer "In9.Cu")
		(net "SGPIO_PCH_SATA_CLOCK_R")
	)
	(segment
		(start 426.16501 -136.036812)
		(end 426.58792 -135.613902)
		(width 0.089408)
		(layer "In9.Cu")
		(net "SGPIO_PCH_SATA_CLOCK_R")
	)
	(segment
		(start 388.72795 -95.888556)
		(end 388.23265 -96.11868)
		(width 0.10795)
		(layer "F.Cu")
		(net "SGPIO_PCH_SATA_CLOCK")
	)
	(via
		(at 388.72795 -95.888556)
		(size 0.508)
		(drill 0.254)
		(layers "F.Cu" "B.Cu")
		(net "SGPIO_PCH_SATA_CLOCK")
	)
	(segment
		(start 389.382 -87.4395)
		(end 389.382 -88.011)
		(width 0.10795)
		(layer "B.Cu")
		(net "SGPIO_PCH_SATA_CLOCK")
	)
	(segment
		(start 388.079742 -91.091258)
		(end 387.548882 -91.622118)
		(width 0.10795)
		(layer "B.Cu")
		(net "SGPIO_PCH_SATA_CLOCK")
	)
	(segment
		(start 387.548882 -94.709488)
		(end 388.72795 -95.888556)
		(width 0.10795)
		(layer "B.Cu")
		(net "SGPIO_PCH_SATA_CLOCK")
	)
	(segment
		(start 388.079742 -90.275918)
		(end 388.079742 -91.091258)
		(width 0.10795)
		(layer "B.Cu")
		(net "SGPIO_PCH_SATA_CLOCK")
	)
	(segment
		(start 389.018018 -88.374982)
		(end 389.018018 -89.337642)
		(width 0.10795)
		(layer "B.Cu")
		(net "SGPIO_PCH_SATA_CLOCK")
	)
	(segment
		(start 389.382 -88.011)
		(end 389.018018 -88.374982)
		(width 0.10795)
		(layer "B.Cu")
		(net "SGPIO_PCH_SATA_CLOCK")
	)
	(segment
		(start 387.548882 -91.622118)
		(end 387.548882 -94.709488)
		(width 0.10795)
		(layer "B.Cu")
		(net "SGPIO_PCH_SATA_CLOCK")
	)
	(segment
		(start 389.018018 -89.337642)
		(end 388.079742 -90.275918)
		(width 0.10795)
		(layer "B.Cu")
		(net "SGPIO_PCH_SATA_CLOCK")
	)
	(segment
		(start 174.3583 -150.114)
		(end 174.3583 -149.3139)
		(width 0.10795)
		(layer "F.Cu")
		(net "PWRGD_PVTT_KLM_CPU1_R")
	)
	(segment
		(start 171.983146 -148.429218)
		(end 171.983146 -149.635464)
		(width 0.10795)
		(layer "F.Cu")
		(net "PWRGD_PVTT_KLM_CPU1_R")
	)
	(segment
		(start 173.39056 -150.114)
		(end 174.3583 -150.114)
		(width 0.10795)
		(layer "F.Cu")
		(net "PWRGD_PVTT_KLM_CPU1_R")
	)
	(segment
		(start 172.18152 -150.25624)
		(end 172.7581 -150.25624)
		(width 0.10795)
		(layer "F.Cu")
		(net "PWRGD_PVTT_KLM_CPU1_R")
	)
	(segment
		(start 174.3583 -149.3139)
		(end 174.371 -149.3012)
		(width 0.10795)
		(layer "F.Cu")
		(net "PWRGD_PVTT_KLM_CPU1_R")
	)
	(segment
		(start 172.90034 -150.114)
		(end 173.39056 -150.114)
		(width 0.10795)
		(layer "F.Cu")
		(net "PWRGD_PVTT_KLM_CPU1_R")
	)
	(segment
		(start 171.983146 -149.635464)
		(end 172.18152 -149.833838)
		(width 0.10795)
		(layer "F.Cu")
		(net "PWRGD_PVTT_KLM_CPU1_R")
	)
	(segment
		(start 172.7581 -150.25624)
		(end 172.90034 -150.114)
		(width 0.10795)
		(layer "F.Cu")
		(net "PWRGD_PVTT_KLM_CPU1_R")
	)
	(segment
		(start 172.18152 -149.833838)
		(end 172.18152 -150.25624)
		(width 0.10795)
		(layer "F.Cu")
		(net "PWRGD_PVTT_KLM_CPU1_R")
	)
	(via
		(at 173.39056 -150.114)
		(size 0.762)
		(drill 0.381)
		(layers "F.Cu" "B.Cu")
		(net "PWRGD_PVTT_KLM_CPU1_R")
	)
	(segment
		(start 173.7106 -5.461)
		(end 172.8978 -6.2738)
		(width 0.10795)
		(layer "F.Cu")
		(net "PWRGD_PVTT_GHJ_CPU1_R")
	)
	(segment
		(start 173.7106 -5.461)
		(end 173.5836 -5.334)
		(width 0.10795)
		(layer "F.Cu")
		(net "PWRGD_PVTT_GHJ_CPU1_R")
	)
	(segment
		(start 173.5836 -5.334)
		(end 173.5836 -4.5466)
		(width 0.10795)
		(layer "F.Cu")
		(net "PWRGD_PVTT_GHJ_CPU1_R")
	)
	(segment
		(start 171.8818 -5.74294)
		(end 172.0469 -5.90804)
		(width 0.10795)
		(layer "F.Cu")
		(net "PWRGD_PVTT_GHJ_CPU1_R")
	)
	(segment
		(start 172.0469 -6.9342)
		(end 172.2374 -6.9342)
		(width 0.10795)
		(layer "F.Cu")
		(net "PWRGD_PVTT_GHJ_CPU1_R")
	)
	(segment
		(start 172.2374 -6.9342)
		(end 172.8978 -6.2738)
		(width 0.10795)
		(layer "F.Cu")
		(net "PWRGD_PVTT_GHJ_CPU1_R")
	)
	(segment
		(start 172.0469 -5.90804)
		(end 172.0469 -6.9342)
		(width 0.10795)
		(layer "F.Cu")
		(net "PWRGD_PVTT_GHJ_CPU1_R")
	)
	(segment
		(start 171.8818 -5.174996)
		(end 171.8818 -5.74294)
		(width 0.10795)
		(layer "F.Cu")
		(net "PWRGD_PVTT_GHJ_CPU1_R")
	)
	(via
		(at 172.8978 -6.2738)
		(size 0.762)
		(drill 0.381)
		(layers "F.Cu" "B.Cu")
		(net "PWRGD_PVTT_GHJ_CPU1_R")
	)
	(segment
		(start 184.143396 -148.3487)
		(end 184.2516 -148.240496)
		(width 0.10795)
		(layer "F.Cu")
		(net "PWRGD_PVTT_DEF_CPU0_R")
	)
	(segment
		(start 184.531 -146.685)
		(end 185.4327 -146.685)
		(width 0.10795)
		(layer "F.Cu")
		(net "PWRGD_PVTT_DEF_CPU0_R")
	)
	(segment
		(start 184.531 -147.2692)
		(end 184.531 -146.685)
		(width 0.10795)
		(layer "F.Cu")
		(net "PWRGD_PVTT_DEF_CPU0_R")
	)
	(segment
		(start 183.89092 -148.3487)
		(end 184.143396 -148.3487)
		(width 0.10795)
		(layer "F.Cu")
		(net "PWRGD_PVTT_DEF_CPU0_R")
	)
	(segment
		(start 184.2516 -147.5486)
		(end 184.531 -147.2692)
		(width 0.10795)
		(layer "F.Cu")
		(net "PWRGD_PVTT_DEF_CPU0_R")
	)
	(segment
		(start 185.4327 -146.685)
		(end 185.4454 -146.6723)
		(width 0.10795)
		(layer "F.Cu")
		(net "PWRGD_PVTT_DEF_CPU0_R")
	)
	(segment
		(start 184.2516 -148.240496)
		(end 184.2516 -147.5486)
		(width 0.10795)
		(layer "F.Cu")
		(net "PWRGD_PVTT_DEF_CPU0_R")
	)
	(via
		(at 184.2516 -147.5486)
		(size 0.508)
		(drill 0.254)
		(layers "F.Cu" "B.Cu")
		(net "PWRGD_PVTT_DEF_CPU0_R")
	)
	(via
		(at 184.947814 -147.180554)
		(size 0.6604)
		(drill 0.3302)
		(layers "F.Cu" "B.Cu")
		(net "PWRGD_PVTT_DEF_CPU0_R")
	)
	(segment
		(start 184.531 -146.431)
		(end 184.947814 -146.847814)
		(width 0.10795)
		(layer "B.Cu")
		(net "PWRGD_PVTT_DEF_CPU0_R")
	)
	(segment
		(start 184.947814 -147.180554)
		(end 184.579768 -147.5486)
		(width 0.10795)
		(layer "B.Cu")
		(net "PWRGD_PVTT_DEF_CPU0_R")
	)
	(segment
		(start 184.579768 -147.5486)
		(end 184.2516 -147.5486)
		(width 0.10795)
		(layer "B.Cu")
		(net "PWRGD_PVTT_DEF_CPU0_R")
	)
	(segment
		(start 184.947814 -146.847814)
		(end 184.947814 -147.180554)
		(width 0.10795)
		(layer "B.Cu")
		(net "PWRGD_PVTT_DEF_CPU0_R")
	)
	(segment
		(start 184.531 -145.923)
		(end 184.531 -146.431)
		(width 0.10795)
		(layer "B.Cu")
		(net "PWRGD_PVTT_DEF_CPU0_R")
	)
	(segment
		(start 182.134002 -2.705608)
		(end 181.063392 -2.705608)
		(width 0.10795)
		(layer "F.Cu")
		(net "PWRGD_PVTT_ABC_CPU0_R")
	)
	(segment
		(start 180.6702 -3.0988)
		(end 180.0606 -3.7084)
		(width 0.10795)
		(layer "F.Cu")
		(net "PWRGD_PVTT_ABC_CPU0_R")
	)
	(segment
		(start 181.063392 -2.705608)
		(end 180.6702 -3.0988)
		(width 0.10795)
		(layer "F.Cu")
		(net "PWRGD_PVTT_ABC_CPU0_R")
	)
	(segment
		(start 181.34203 -4.445)
		(end 181.354222 -4.432808)
		(width 0.10795)
		(layer "F.Cu")
		(net "PWRGD_PVTT_ABC_CPU0_R")
	)
	(segment
		(start 180.0606 -3.7084)
		(end 180.0606 -4.445)
		(width 0.10795)
		(layer "F.Cu")
		(net "PWRGD_PVTT_ABC_CPU0_R")
	)
	(segment
		(start 180.975 -4.445)
		(end 180.0606 -4.445)
		(width 0.10795)
		(layer "F.Cu")
		(net "PWRGD_PVTT_ABC_CPU0_R")
	)
	(segment
		(start 180.975 -4.445)
		(end 181.34203 -4.445)
		(width 0.10795)
		(layer "F.Cu")
		(net "PWRGD_PVTT_ABC_CPU0_R")
	)
	(segment
		(start 181.354222 -4.432808)
		(end 181.847998 -4.432808)
		(width 0.10795)
		(layer "F.Cu")
		(net "PWRGD_PVTT_ABC_CPU0_R")
	)
	(via
		(at 180.6702 -3.0988)
		(size 0.762)
		(drill 0.381)
		(layers "F.Cu" "B.Cu")
		(net "PWRGD_PVTT_ABC_CPU0_R")
	)
	(segment
		(start 18.030952 -89.5604)
		(end 18.030952 -89.227152)
		(width 0.10795)
		(layer "F.Cu")
		(net "PWRGD_PVSA_CPU1_R")
	)
	(segment
		(start 16.002 -87.63)
		(end 16.764 -87.63)
		(width 0.10795)
		(layer "F.Cu")
		(net "PWRGD_PVSA_CPU1_R")
	)
	(segment
		(start 17.4498 -88.375998)
		(end 16.764 -87.690198)
		(width 0.10795)
		(layer "F.Cu")
		(net "PWRGD_PVSA_CPU1_R")
	)
	(segment
		(start 18.030952 -89.227152)
		(end 17.4498 -88.646)
		(width 0.10795)
		(layer "F.Cu")
		(net "PWRGD_PVSA_CPU1_R")
	)
	(segment
		(start 17.4498 -88.646)
		(end 17.4498 -88.375998)
		(width 0.10795)
		(layer "F.Cu")
		(net "PWRGD_PVSA_CPU1_R")
	)
	(segment
		(start 16.764 -87.690198)
		(end 16.764 -87.63)
		(width 0.10795)
		(layer "F.Cu")
		(net "PWRGD_PVSA_CPU1_R")
	)
	(segment
		(start 182.6768 -65.97904)
		(end 182.434484 -65.736724)
		(width 0.10795)
		(layer "F.Cu")
		(net "PWRGD_PVSA_CPU0_R")
	)
	(segment
		(start 182.118 -65.42024)
		(end 182.434484 -65.736724)
		(width 0.10795)
		(layer "F.Cu")
		(net "PWRGD_PVSA_CPU0_R")
	)
	(segment
		(start 182.876952 -66.9544)
		(end 182.876952 -66.417952)
		(width 0.10795)
		(layer "F.Cu")
		(net "PWRGD_PVSA_CPU0_R")
	)
	(segment
		(start 182.118 -65.024)
		(end 181.356 -65.024)
		(width 0.10795)
		(layer "F.Cu")
		(net "PWRGD_PVSA_CPU0_R")
	)
	(segment
		(start 182.6768 -66.2178)
		(end 182.6768 -65.97904)
		(width 0.10795)
		(layer "F.Cu")
		(net "PWRGD_PVSA_CPU0_R")
	)
	(segment
		(start 182.118 -65.024)
		(end 182.118 -65.42024)
		(width 0.10795)
		(layer "F.Cu")
		(net "PWRGD_PVSA_CPU0_R")
	)
	(segment
		(start 182.876952 -66.417952)
		(end 182.6768 -66.2178)
		(width 0.10795)
		(layer "F.Cu")
		(net "PWRGD_PVSA_CPU0_R")
	)
	(via
		(at 182.434484 -65.736724)
		(size 0.508)
		(drill 0.254)
		(layers "F.Cu" "B.Cu")
		(net "PWRGD_PVSA_CPU0_R")
	)
	(segment
		(start 13.5636 -76.9112)
		(end 13.8684 -77.216)
		(width 0.10795)
		(layer "F.Cu")
		(net "PWRGD_P12V_R")
	)
	(segment
		(start 15.8115 -76.94295)
		(end 15.513304 -76.94295)
		(width 0.10795)
		(layer "F.Cu")
		(net "PWRGD_P12V_R")
	)
	(segment
		(start 13.5255 -76.9112)
		(end 13.5636 -76.9112)
		(width 0.10795)
		(layer "F.Cu")
		(net "PWRGD_P12V_R")
	)
	(segment
		(start 14.478 -77.216)
		(end 14.224 -77.216)
		(width 0.10795)
		(layer "F.Cu")
		(net "PWRGD_P12V_R")
	)
	(segment
		(start 15.513304 -76.94295)
		(end 15.113254 -77.343)
		(width 0.10795)
		(layer "F.Cu")
		(net "PWRGD_P12V_R")
	)
	(segment
		(start 13.312648 -76.8858)
		(end 13.5001 -76.8858)
		(width 0.10795)
		(layer "F.Cu")
		(net "PWRGD_P12V_R")
	)
	(segment
		(start 12.9286 -75.8952)
		(end 12.9286 -76.501752)
		(width 0.10795)
		(layer "F.Cu")
		(net "PWRGD_P12V_R")
	)
	(segment
		(start 15.113254 -77.343)
		(end 14.605 -77.343)
		(width 0.10795)
		(layer "F.Cu")
		(net "PWRGD_P12V_R")
	)
	(segment
		(start 13.8684 -77.216)
		(end 14.224 -77.216)
		(width 0.10795)
		(layer "F.Cu")
		(net "PWRGD_P12V_R")
	)
	(segment
		(start 12.9286 -76.501752)
		(end 13.312648 -76.8858)
		(width 0.10795)
		(layer "F.Cu")
		(net "PWRGD_P12V_R")
	)
	(segment
		(start 14.605 -77.343)
		(end 14.478 -77.216)
		(width 0.10795)
		(layer "F.Cu")
		(net "PWRGD_P12V_R")
	)
	(segment
		(start 13.5001 -76.8858)
		(end 13.5255 -76.9112)
		(width 0.10795)
		(layer "F.Cu")
		(net "PWRGD_P12V_R")
	)
	(via
		(at 13.5255 -76.9112)
		(size 0.508)
		(drill 0.254)
		(layers "F.Cu" "B.Cu")
		(net "PWRGD_P12V_R")
	)
	(segment
		(start 13.5255 -76.8731)
		(end 12.3698 -75.7174)
		(width 0.10795)
		(layer "B.Cu")
		(net "PWRGD_P12V_R")
	)
	(segment
		(start 12.3698 -75.7174)
		(end 11.9126 -75.7174)
		(width 0.10795)
		(layer "B.Cu")
		(net "PWRGD_P12V_R")
	)
	(segment
		(start 13.5255 -76.9112)
		(end 13.5255 -76.8731)
		(width 0.10795)
		(layer "B.Cu")
		(net "PWRGD_P12V_R")
	)
	(segment
		(start 17.91081 -78.41361)
		(end 18.4404 -78.9432)
		(width 0.10795)
		(layer "F.Cu")
		(net "IRQ_SML1_PMBUS_ALERT_R_N")
	)
	(segment
		(start 17.9832 -79.4004)
		(end 18.4404 -78.9432)
		(width 0.10795)
		(layer "F.Cu")
		(net "IRQ_SML1_PMBUS_ALERT_R_N")
	)
	(segment
		(start 17.9832 -79.6417)
		(end 17.9832 -79.4004)
		(width 0.10795)
		(layer "F.Cu")
		(net "IRQ_SML1_PMBUS_ALERT_R_N")
	)
	(segment
		(start 17.91081 -78.0415)
		(end 17.91081 -78.41361)
		(width 0.10795)
		(layer "F.Cu")
		(net "IRQ_SML1_PMBUS_ALERT_R_N")
	)
	(via
		(at 18.4404 -78.9432)
		(size 0.508)
		(drill 0.254)
		(layers "F.Cu" "B.Cu")
		(net "IRQ_SML1_PMBUS_ALERT_R_N")
	)
	(segment
		(start 26.189432 -33.211516)
		(end 26.5684 -33.590484)
		(width 0.089408)
		(layer "In2.Cu")
		(net "IRQ_SML1_PMBUS_ALERT_R_N")
	)
	(segment
		(start 26.394918 -29.075888)
		(end 26.394918 -31.9024)
		(width 0.089408)
		(layer "In2.Cu")
		(net "IRQ_SML1_PMBUS_ALERT_R_N")
	)
	(segment
		(start 22.600666 -46.862492)
		(end 22.600666 -48.156368)
		(width 0.089408)
		(layer "In2.Cu")
		(net "IRQ_SML1_PMBUS_ALERT_R_N")
	)
	(segment
		(start 13.8684 -72.9488)
		(end 18.4404 -77.5208)
		(width 0.089408)
		(layer "In2.Cu")
		(net "IRQ_SML1_PMBUS_ALERT_R_N")
	)
	(segment
		(start 11.993372 -66.808858)
		(end 13.030962 -67.846448)
		(width 0.089408)
		(layer "In2.Cu")
		(net "IRQ_SML1_PMBUS_ALERT_R_N")
	)
	(segment
		(start 13.56995 -71.932292)
		(end 13.8684 -72.230742)
		(width 0.0889)
		(layer "In2.Cu")
		(net "IRQ_SML1_PMBUS_ALERT_R_N")
	)
	(segment
		(start 25.065228 -27.746198)
		(end 26.394918 -29.075888)
		(width 0.089408)
		(layer "In2.Cu")
		(net "IRQ_SML1_PMBUS_ALERT_R_N")
	)
	(segment
		(start 13.8684 -72.230742)
		(end 13.8684 -72.9488)
		(width 0.089408)
		(layer "In2.Cu")
		(net "IRQ_SML1_PMBUS_ALERT_R_N")
	)
	(segment
		(start 13.030962 -67.846448)
		(end 13.030962 -71.393304)
		(width 0.089408)
		(layer "In2.Cu")
		(net "IRQ_SML1_PMBUS_ALERT_R_N")
	)
	(segment
		(start 26.189432 -32.107886)
		(end 26.189432 -33.211516)
		(width 0.089408)
		(layer "In2.Cu")
		(net "IRQ_SML1_PMBUS_ALERT_R_N")
	)
	(segment
		(start 13.030962 -71.393304)
		(end 13.56995 -71.932292)
		(width 0.089408)
		(layer "In2.Cu")
		(net "IRQ_SML1_PMBUS_ALERT_R_N")
	)
	(segment
		(start 14.0716 -52.588922)
		(end 11.993372 -54.66715)
		(width 0.089408)
		(layer "In2.Cu")
		(net "IRQ_SML1_PMBUS_ALERT_R_N")
	)
	(segment
		(start 21.907246 -48.849788)
		(end 20.924012 -48.849788)
		(width 0.089408)
		(layer "In2.Cu")
		(net "IRQ_SML1_PMBUS_ALERT_R_N")
	)
	(segment
		(start 26.394918 -31.9024)
		(end 26.189432 -32.107886)
		(width 0.089408)
		(layer "In2.Cu")
		(net "IRQ_SML1_PMBUS_ALERT_R_N")
	)
	(segment
		(start 14.0716 -51.689)
		(end 14.0716 -52.588922)
		(width 0.089408)
		(layer "In2.Cu")
		(net "IRQ_SML1_PMBUS_ALERT_R_N")
	)
	(segment
		(start 20.924012 -48.849788)
		(end 19.5199 -50.2539)
		(width 0.089408)
		(layer "In2.Cu")
		(net "IRQ_SML1_PMBUS_ALERT_R_N")
	)
	(segment
		(start 26.5684 -42.894758)
		(end 22.600666 -46.862492)
		(width 0.089408)
		(layer "In2.Cu")
		(net "IRQ_SML1_PMBUS_ALERT_R_N")
	)
	(segment
		(start 15.5067 -50.2539)
		(end 14.0716 -51.689)
		(width 0.089408)
		(layer "In2.Cu")
		(net "IRQ_SML1_PMBUS_ALERT_R_N")
	)
	(segment
		(start 22.600666 -48.156368)
		(end 21.907246 -48.849788)
		(width 0.089408)
		(layer "In2.Cu")
		(net "IRQ_SML1_PMBUS_ALERT_R_N")
	)
	(segment
		(start 24.567388 -27.746198)
		(end 25.065228 -27.746198)
		(width 0.089408)
		(layer "In2.Cu")
		(net "IRQ_SML1_PMBUS_ALERT_R_N")
	)
	(segment
		(start 23.49119 -26.67)
		(end 24.567388 -27.746198)
		(width 0.089408)
		(layer "In2.Cu")
		(net "IRQ_SML1_PMBUS_ALERT_R_N")
	)
	(segment
		(start 19.5199 -50.2539)
		(end 15.5067 -50.2539)
		(width 0.089408)
		(layer "In2.Cu")
		(net "IRQ_SML1_PMBUS_ALERT_R_N")
	)
	(segment
		(start 11.993372 -54.66715)
		(end 11.993372 -66.808858)
		(width 0.089408)
		(layer "In2.Cu")
		(net "IRQ_SML1_PMBUS_ALERT_R_N")
	)
	(segment
		(start 18.4404 -77.5208)
		(end 18.4404 -78.9432)
		(width 0.089408)
		(layer "In2.Cu")
		(net "IRQ_SML1_PMBUS_ALERT_R_N")
	)
	(segment
		(start 26.5684 -33.590484)
		(end 26.5684 -42.894758)
		(width 0.089408)
		(layer "In2.Cu")
		(net "IRQ_SML1_PMBUS_ALERT_R_N")
	)
	(segment
		(start 21.06676 -25.9842)
		(end 19.806412 -24.723852)
		(width 0.089408)
		(layer "In4.Cu")
		(net "IRQ_SML1_PMBUS_ALERT_R_N")
	)
	(segment
		(start 10.3378 -23.9776)
		(end 10.3378 -29.464)
		(width 0.089408)
		(layer "In4.Cu")
		(net "IRQ_SML1_PMBUS_ALERT_R_N")
	)
	(segment
		(start 19.806412 -22.499828)
		(end 19.136106 -21.829522)
		(width 0.089408)
		(layer "In4.Cu")
		(net "IRQ_SML1_PMBUS_ALERT_R_N")
	)
	(segment
		(start 23.49119 -26.67)
		(end 22.80539 -25.9842)
		(width 0.089408)
		(layer "In4.Cu")
		(net "IRQ_SML1_PMBUS_ALERT_R_N")
	)
	(segment
		(start 10.3378 -29.464)
		(end 8.945372 -30.856428)
		(width 0.089408)
		(layer "In4.Cu")
		(net "IRQ_SML1_PMBUS_ALERT_R_N")
	)
	(segment
		(start 15.2146 -21.829522)
		(end 14.514322 -22.5298)
		(width 0.089408)
		(layer "In4.Cu")
		(net "IRQ_SML1_PMBUS_ALERT_R_N")
	)
	(segment
		(start -3.999992 -30.163008)
		(end -3.999992 -29.710126)
		(width 0.089408)
		(layer "In4.Cu")
		(net "IRQ_SML1_PMBUS_ALERT_R_N")
	)
	(segment
		(start 11.7856 -22.5298)
		(end 10.3378 -23.9776)
		(width 0.089408)
		(layer "In4.Cu")
		(net "IRQ_SML1_PMBUS_ALERT_R_N")
	)
	(segment
		(start 19.136106 -21.829522)
		(end 15.2146 -21.829522)
		(width 0.089408)
		(layer "In4.Cu")
		(net "IRQ_SML1_PMBUS_ALERT_R_N")
	)
	(segment
		(start 14.514322 -22.5298)
		(end 11.7856 -22.5298)
		(width 0.089408)
		(layer "In4.Cu")
		(net "IRQ_SML1_PMBUS_ALERT_R_N")
	)
	(segment
		(start 8.945372 -30.856428)
		(end -3.306572 -30.856428)
		(width 0.089408)
		(layer "In4.Cu")
		(net "IRQ_SML1_PMBUS_ALERT_R_N")
	)
	(segment
		(start 22.80539 -25.9842)
		(end 21.06676 -25.9842)
		(width 0.089408)
		(layer "In4.Cu")
		(net "IRQ_SML1_PMBUS_ALERT_R_N")
	)
	(segment
		(start 19.806412 -24.723852)
		(end 19.806412 -22.499828)
		(width 0.089408)
		(layer "In4.Cu")
		(net "IRQ_SML1_PMBUS_ALERT_R_N")
	)
	(segment
		(start -3.306572 -30.856428)
		(end -3.999992 -30.163008)
		(width 0.089408)
		(layer "In4.Cu")
		(net "IRQ_SML1_PMBUS_ALERT_R_N")
	)
	(segment
		(start -3.22326 -131.97586)
		(end -2.29616 -131.97586)
		(width 0.10795)
		(layer "F.Cu")
		(net "IRQ_PVDDQ_KLM_VRHOT_LVT3_R_N")
	)
	(segment
		(start -3.22326 -131.350004)
		(end -3.115056 -131.2418)
		(width 0.10795)
		(layer "F.Cu")
		(net "IRQ_PVDDQ_KLM_VRHOT_LVT3_R_N")
	)
	(segment
		(start -3.115056 -131.2418)
		(end -2.845308 -131.2418)
		(width 0.10795)
		(layer "F.Cu")
		(net "IRQ_PVDDQ_KLM_VRHOT_LVT3_R_N")
	)
	(segment
		(start -0.806196 -129.765298)
		(end -0.3937 -129.765298)
		(width 0.10795)
		(layer "F.Cu")
		(net "IRQ_PVDDQ_KLM_VRHOT_LVT3_R_N")
	)
	(segment
		(start -2.652776 -131.2418)
		(end -1.926082 -130.515106)
		(width 0.10795)
		(layer "F.Cu")
		(net "IRQ_PVDDQ_KLM_VRHOT_LVT3_R_N")
	)
	(segment
		(start -1.556004 -130.515106)
		(end -0.806196 -129.765298)
		(width 0.10795)
		(layer "F.Cu")
		(net "IRQ_PVDDQ_KLM_VRHOT_LVT3_R_N")
	)
	(segment
		(start -1.926082 -130.515106)
		(end -1.556004 -130.515106)
		(width 0.10795)
		(layer "F.Cu")
		(net "IRQ_PVDDQ_KLM_VRHOT_LVT3_R_N")
	)
	(segment
		(start -2.29616 -131.97586)
		(end -2.28346 -131.96316)
		(width 0.10795)
		(layer "F.Cu")
		(net "IRQ_PVDDQ_KLM_VRHOT_LVT3_R_N")
	)
	(segment
		(start -3.22326 -131.97586)
		(end -3.22326 -131.350004)
		(width 0.10795)
		(layer "F.Cu")
		(net "IRQ_PVDDQ_KLM_VRHOT_LVT3_R_N")
	)
	(segment
		(start -2.845308 -131.2418)
		(end -2.652776 -131.2418)
		(width 0.10795)
		(layer "F.Cu")
		(net "IRQ_PVDDQ_KLM_VRHOT_LVT3_R_N")
	)
	(via
		(at -2.845308 -131.2418)
		(size 0.508)
		(drill 0.254)
		(layers "F.Cu" "B.Cu")
		(net "IRQ_PVDDQ_KLM_VRHOT_LVT3_R_N")
	)
	(segment
		(start 13.44295 -3.54203)
		(end 14.209268 -3.54203)
		(width 0.10795)
		(layer "F.Cu")
		(net "IRQ_PVDDQ_GHJ_VRHOT_LVT3_R_N")
	)
	(segment
		(start 13.438124 -3.537204)
		(end 13.438124 -3.405378)
		(width 0.10795)
		(layer "F.Cu")
		(net "IRQ_PVDDQ_GHJ_VRHOT_LVT3_R_N")
	)
	(segment
		(start 12.62126 -2.89052)
		(end 11.93419 -2.20345)
		(width 0.10795)
		(layer "F.Cu")
		(net "IRQ_PVDDQ_GHJ_VRHOT_LVT3_R_N")
	)
	(segment
		(start 13.438124 -3.405378)
		(end 12.923266 -2.89052)
		(width 0.10795)
		(layer "F.Cu")
		(net "IRQ_PVDDQ_GHJ_VRHOT_LVT3_R_N")
	)
	(segment
		(start 13.438124 -3.537204)
		(end 13.44295 -3.54203)
		(width 0.10795)
		(layer "F.Cu")
		(net "IRQ_PVDDQ_GHJ_VRHOT_LVT3_R_N")
	)
	(segment
		(start 12.923266 -2.89052)
		(end 12.62126 -2.89052)
		(width 0.10795)
		(layer "F.Cu")
		(net "IRQ_PVDDQ_GHJ_VRHOT_LVT3_R_N")
	)
	(segment
		(start 11.93419 -2.20345)
		(end 11.833098 -2.20345)
		(width 0.10795)
		(layer "F.Cu")
		(net "IRQ_PVDDQ_GHJ_VRHOT_LVT3_R_N")
	)
	(segment
		(start 363.347 -133.985)
		(end 363.3597 -133.9977)
		(width 0.10795)
		(layer "F.Cu")
		(net "IRQ_PVDDQ_DEF_VRHOT_LVT3_R_N")
	)
	(segment
		(start 362.1024 -135.22198)
		(end 362.1024 -136.2202)
		(width 0.10795)
		(layer "F.Cu")
		(net "IRQ_PVDDQ_DEF_VRHOT_LVT3_R_N")
	)
	(segment
		(start 362.50118 -134.8232)
		(end 362.42498 -134.8232)
		(width 0.10795)
		(layer "F.Cu")
		(net "IRQ_PVDDQ_DEF_VRHOT_LVT3_R_N")
	)
	(segment
		(start 362.9152 -133.985)
		(end 362.9152 -134.40918)
		(width 0.10795)
		(layer "F.Cu")
		(net "IRQ_PVDDQ_DEF_VRHOT_LVT3_R_N")
	)
	(segment
		(start 362.9152 -133.985)
		(end 363.347 -133.985)
		(width 0.10795)
		(layer "F.Cu")
		(net "IRQ_PVDDQ_DEF_VRHOT_LVT3_R_N")
	)
	(segment
		(start 361.958128 -136.364472)
		(end 361.74934 -136.364472)
		(width 0.10795)
		(layer "F.Cu")
		(net "IRQ_PVDDQ_DEF_VRHOT_LVT3_R_N")
	)
	(segment
		(start 362.42498 -134.8232)
		(end 362.42498 -134.8994)
		(width 0.10795)
		(layer "F.Cu")
		(net "IRQ_PVDDQ_DEF_VRHOT_LVT3_R_N")
	)
	(segment
		(start 362.9152 -134.40918)
		(end 362.50118 -134.8232)
		(width 0.10795)
		(layer "F.Cu")
		(net "IRQ_PVDDQ_DEF_VRHOT_LVT3_R_N")
	)
	(segment
		(start 362.1024 -136.2202)
		(end 361.958128 -136.364472)
		(width 0.10795)
		(layer "F.Cu")
		(net "IRQ_PVDDQ_DEF_VRHOT_LVT3_R_N")
	)
	(segment
		(start 363.3597 -133.9977)
		(end 363.7788 -133.9977)
		(width 0.10795)
		(layer "F.Cu")
		(net "IRQ_PVDDQ_DEF_VRHOT_LVT3_R_N")
	)
	(segment
		(start 362.42498 -134.8994)
		(end 362.1024 -135.22198)
		(width 0.10795)
		(layer "F.Cu")
		(net "IRQ_PVDDQ_DEF_VRHOT_LVT3_R_N")
	)
	(via
		(at 362.42498 -134.8232)
		(size 0.508)
		(drill 0.254)
		(layers "F.Cu" "B.Cu")
		(net "IRQ_PVDDQ_DEF_VRHOT_LVT3_R_N")
	)
	(segment
		(start 339.797898 -19.840702)
		(end 340.487 -19.1516)
		(width 0.10795)
		(layer "F.Cu")
		(net "IRQ_PVDDQ_ABC_VRHOT_LVT3_R_N")
	)
	(segment
		(start 342.015826 -17.167098)
		(end 341.8332 -17.349724)
		(width 0.10795)
		(layer "F.Cu")
		(net "IRQ_PVDDQ_ABC_VRHOT_LVT3_R_N")
	)
	(segment
		(start 341.8332 -18.3134)
		(end 341.563198 -18.583402)
		(width 0.10795)
		(layer "F.Cu")
		(net "IRQ_PVDDQ_ABC_VRHOT_LVT3_R_N")
	)
	(segment
		(start 339.384894 -19.840702)
		(end 339.797898 -19.840702)
		(width 0.10795)
		(layer "F.Cu")
		(net "IRQ_PVDDQ_ABC_VRHOT_LVT3_R_N")
	)
	(segment
		(start 338.836 -19.7612)
		(end 338.836 -20.5232)
		(width 0.10795)
		(layer "F.Cu")
		(net "IRQ_PVDDQ_ABC_VRHOT_LVT3_R_N")
	)
	(segment
		(start 340.724998 -18.583402)
		(end 340.6648 -18.6436)
		(width 0.10795)
		(layer "F.Cu")
		(net "IRQ_PVDDQ_ABC_VRHOT_LVT3_R_N")
	)
	(segment
		(start 338.836 -19.7612)
		(end 339.305392 -19.7612)
		(width 0.10795)
		(layer "F.Cu")
		(net "IRQ_PVDDQ_ABC_VRHOT_LVT3_R_N")
	)
	(segment
		(start 342.2269 -17.167098)
		(end 342.015826 -17.167098)
		(width 0.10795)
		(layer "F.Cu")
		(net "IRQ_PVDDQ_ABC_VRHOT_LVT3_R_N")
	)
	(segment
		(start 339.305392 -19.7612)
		(end 339.384894 -19.840702)
		(width 0.10795)
		(layer "F.Cu")
		(net "IRQ_PVDDQ_ABC_VRHOT_LVT3_R_N")
	)
	(segment
		(start 341.8332 -17.349724)
		(end 341.8332 -18.3134)
		(width 0.10795)
		(layer "F.Cu")
		(net "IRQ_PVDDQ_ABC_VRHOT_LVT3_R_N")
	)
	(segment
		(start 340.487 -19.1516)
		(end 340.487 -18.8214)
		(width 0.10795)
		(layer "F.Cu")
		(net "IRQ_PVDDQ_ABC_VRHOT_LVT3_R_N")
	)
	(segment
		(start 341.563198 -18.583402)
		(end 340.724998 -18.583402)
		(width 0.10795)
		(layer "F.Cu")
		(net "IRQ_PVDDQ_ABC_VRHOT_LVT3_R_N")
	)
	(segment
		(start 340.487 -18.8214)
		(end 340.6648 -18.6436)
		(width 0.10795)
		(layer "F.Cu")
		(net "IRQ_PVDDQ_ABC_VRHOT_LVT3_R_N")
	)
	(via
		(at 340.6648 -18.6436)
		(size 0.762)
		(drill 0.381)
		(layers "F.Cu" "B.Cu")
		(net "IRQ_PVDDQ_ABC_VRHOT_LVT3_R_N")
	)
	(segment
		(start 17.231106 -89.5604)
		(end 17.231106 -89.3826)
		(width 0.10795)
		(layer "F.Cu")
		(net "IRQ_PVCCIN_CPU1_VRHOT_LVC3_R_N")
	)
	(segment
		(start 14.9098 -88.0618)
		(end 14.478 -87.63)
		(width 0.10795)
		(layer "F.Cu")
		(net "IRQ_PVCCIN_CPU1_VRHOT_LVC3_R_N")
	)
	(segment
		(start 17.104106 -89.2556)
		(end 16.256 -89.2556)
		(width 0.10795)
		(layer "F.Cu")
		(net "IRQ_PVCCIN_CPU1_VRHOT_LVC3_R_N")
	)
	(segment
		(start 17.231106 -89.3826)
		(end 17.104106 -89.2556)
		(width 0.10795)
		(layer "F.Cu")
		(net "IRQ_PVCCIN_CPU1_VRHOT_LVC3_R_N")
	)
	(segment
		(start 15.4686 -88.4682)
		(end 15.0622 -88.0618)
		(width 0.10795)
		(layer "F.Cu")
		(net "IRQ_PVCCIN_CPU1_VRHOT_LVC3_R_N")
	)
	(segment
		(start 15.0622 -88.0618)
		(end 14.9098 -88.0618)
		(width 0.10795)
		(layer "F.Cu")
		(net "IRQ_PVCCIN_CPU1_VRHOT_LVC3_R_N")
	)
	(segment
		(start 16.256 -89.2556)
		(end 15.4686 -88.4682)
		(width 0.10795)
		(layer "F.Cu")
		(net "IRQ_PVCCIN_CPU1_VRHOT_LVC3_R_N")
	)
	(via
		(at 15.4686 -88.4682)
		(size 0.508)
		(drill 0.254)
		(layers "F.Cu" "B.Cu")
		(net "IRQ_PVCCIN_CPU1_VRHOT_LVC3_R_N")
	)
	(segment
		(start 14.478 -87.8332)
		(end 15.113 -88.4682)
		(width 0.10795)
		(layer "B.Cu")
		(net "IRQ_PVCCIN_CPU1_VRHOT_LVC3_R_N")
	)
	(segment
		(start 15.113 -88.4682)
		(end 15.4686 -88.4682)
		(width 0.10795)
		(layer "B.Cu")
		(net "IRQ_PVCCIN_CPU1_VRHOT_LVC3_R_N")
	)
	(segment
		(start 14.478 -87.63)
		(end 14.478 -87.8332)
		(width 0.10795)
		(layer "B.Cu")
		(net "IRQ_PVCCIN_CPU1_VRHOT_LVC3_R_N")
	)
	(segment
		(start 180.8988 -66.0908)
		(end 180.5178 -66.0908)
		(width 0.10795)
		(layer "F.Cu")
		(net "IRQ_PVCCIN_CPU0_VRHOT_LVC3_R_N")
	)
	(segment
		(start 179.832 -65.024)
		(end 180.467 -65.659)
		(width 0.10795)
		(layer "F.Cu")
		(net "IRQ_PVCCIN_CPU0_VRHOT_LVC3_R_N")
	)
	(segment
		(start 180.467 -66.04)
		(end 180.5178 -66.0908)
		(width 0.10795)
		(layer "F.Cu")
		(net "IRQ_PVCCIN_CPU0_VRHOT_LVC3_R_N")
	)
	(segment
		(start 181.797706 -66.675)
		(end 181.483 -66.675)
		(width 0.10795)
		(layer "F.Cu")
		(net "IRQ_PVCCIN_CPU0_VRHOT_LVC3_R_N")
	)
	(segment
		(start 181.483 -66.675)
		(end 180.8988 -66.0908)
		(width 0.10795)
		(layer "F.Cu")
		(net "IRQ_PVCCIN_CPU0_VRHOT_LVC3_R_N")
	)
	(segment
		(start 179.705 -65.024)
		(end 179.832 -65.024)
		(width 0.10795)
		(layer "F.Cu")
		(net "IRQ_PVCCIN_CPU0_VRHOT_LVC3_R_N")
	)
	(segment
		(start 180.467 -65.659)
		(end 180.467 -66.04)
		(width 0.10795)
		(layer "F.Cu")
		(net "IRQ_PVCCIN_CPU0_VRHOT_LVC3_R_N")
	)
	(segment
		(start 182.077106 -66.9544)
		(end 181.797706 -66.675)
		(width 0.10795)
		(layer "F.Cu")
		(net "IRQ_PVCCIN_CPU0_VRHOT_LVC3_R_N")
	)
	(via
		(at 180.5178 -66.0908)
		(size 0.508)
		(drill 0.254)
		(layers "F.Cu" "B.Cu")
		(net "IRQ_PVCCIN_CPU0_VRHOT_LVC3_R_N")
	)
	(segment
		(start 180.5178 -66.0908)
		(end 180.467 -66.04)
		(width 0.10795)
		(layer "B.Cu")
		(net "IRQ_PVCCIN_CPU0_VRHOT_LVC3_R_N")
	)
	(segment
		(start 180.467 -66.04)
		(end 180.467 -65.024)
		(width 0.10795)
		(layer "B.Cu")
		(net "IRQ_PVCCIN_CPU0_VRHOT_LVC3_R_N")
	)
	(segment
		(start 21.197824 -76.44257)
		(end 20.5105 -76.44257)
		(width 0.10795)
		(layer "F.Cu")
		(net "IRQ_HSC_FAULT_R_N")
	)
	(segment
		(start 21.971 -77.215746)
		(end 21.708618 -76.953364)
		(width 0.10795)
		(layer "F.Cu")
		(net "IRQ_HSC_FAULT_R_N")
	)
	(segment
		(start 22.015196 -77.215746)
		(end 21.971 -77.215746)
		(width 0.10795)
		(layer "F.Cu")
		(net "IRQ_HSC_FAULT_R_N")
	)
	(segment
		(start 22.225 -77.724)
		(end 22.225 -77.42555)
		(width 0.10795)
		(layer "F.Cu")
		(net "IRQ_HSC_FAULT_R_N")
	)
	(segment
		(start 22.225 -77.42555)
		(end 22.015196 -77.215746)
		(width 0.10795)
		(layer "F.Cu")
		(net "IRQ_HSC_FAULT_R_N")
	)
	(segment
		(start 21.708618 -76.953364)
		(end 21.197824 -76.44257)
		(width 0.10795)
		(layer "F.Cu")
		(net "IRQ_HSC_FAULT_R_N")
	)
	(via
		(at 21.708618 -76.953364)
		(size 0.508)
		(drill 0.254)
		(layers "F.Cu" "B.Cu")
		(net "IRQ_HSC_FAULT_R_N")
	)
	(segment
		(start 171.242736 -54.10073)
		(end 169.420032 -55.923434)
		(width 0.508)
		(layer "F.Cu")
		(net "VR_PVCCIO_CPU1_PH1_SW")
	)
	(segment
		(start 169.420032 -55.923434)
		(end 169.420032 -57.349644)
		(width 0.508)
		(layer "F.Cu")
		(net "VR_PVCCIO_CPU1_PH1_SW")
	)
	(segment
		(start 169.420032 -57.349644)
		(end 169.883074 -57.812686)
		(width 0.508)
		(layer "F.Cu")
		(net "VR_PVCCIO_CPU1_PH1_SW")
	)
	(segment
		(start 169.883074 -57.812686)
		(end 170.234102 -57.812686)
		(width 0.508)
		(layer "F.Cu")
		(net "VR_PVCCIO_CPU1_PH1_SW")
	)
	(segment
		(start 342.2142 -94.107)
		(end 342.2142 -95.504)
		(width 0.508)
		(layer "F.Cu")
		(net "VR_PVCCIO_CPU0_PH1_SW")
	)
	(segment
		(start 174.8409 -11.58494)
		(end 174.406306 -11.58494)
		(width 0.254)
		(layer "F.Cu")
		(net "VR_FET_SW_P12V_STBY_PVPP_GHJ")
	)
	(segment
		(start 174.0154 -11.194034)
		(end 174.0154 -10.922)
		(width 0.254)
		(layer "F.Cu")
		(net "VR_FET_SW_P12V_STBY_PVPP_GHJ")
	)
	(segment
		(start 174.406306 -11.58494)
		(end 174.0154 -11.194034)
		(width 0.254)
		(layer "F.Cu")
		(net "VR_FET_SW_P12V_STBY_PVPP_GHJ")
	)
	(via
		(at 181.908704 -11.892788)
		(size 0.508)
		(drill 0.254)
		(layers "F.Cu" "B.Cu")
		(net "VR_FET_SW_P12V_STBY_PVPP_GHJ")
	)
	(via
		(at 182.8419 -12.43838)
		(size 0.508)
		(drill 0.254)
		(layers "F.Cu" "B.Cu")
		(net "VR_FET_SW_P12V_STBY_PVPP_GHJ")
	)
	(via
		(at 182.0926 -9.779)
		(size 0.508)
		(drill 0.254)
		(layers "F.Cu" "B.Cu")
		(net "VR_FET_SW_P12V_STBY_PVPP_GHJ")
	)
	(via
		(at 181.273196 -11.892788)
		(size 0.508)
		(drill 0.254)
		(layers "F.Cu" "B.Cu")
		(net "VR_FET_SW_P12V_STBY_PVPP_GHJ")
	)
	(via
		(at 181.356 -11.1506)
		(size 0.508)
		(drill 0.254)
		(layers "F.Cu" "B.Cu")
		(net "VR_FET_SW_P12V_STBY_PVPP_GHJ")
	)
	(via
		(at 180.6194 -9.8298)
		(size 0.508)
		(drill 0.254)
		(layers "F.Cu" "B.Cu")
		(net "VR_FET_SW_P12V_STBY_PVPP_GHJ")
	)
	(via
		(at 174.0154 -10.922)
		(size 0.508)
		(drill 0.254)
		(layers "F.Cu" "B.Cu")
		(net "VR_FET_SW_P12V_STBY_PVPP_GHJ")
	)
	(via
		(at 181.361842 -10.427462)
		(size 0.508)
		(drill 0.254)
		(layers "F.Cu" "B.Cu")
		(net "VR_FET_SW_P12V_STBY_PVPP_GHJ")
	)
	(via
		(at 181.361842 -9.817862)
		(size 0.508)
		(drill 0.254)
		(layers "F.Cu" "B.Cu")
		(net "VR_FET_SW_P12V_STBY_PVPP_GHJ")
	)
	(via
		(at 183.795162 -11.919966)
		(size 0.508)
		(drill 0.254)
		(layers "F.Cu" "B.Cu")
		(net "VR_FET_SW_P12V_STBY_PVPP_GHJ")
	)
	(via
		(at 182.0418 -11.1252)
		(size 0.508)
		(drill 0.254)
		(layers "F.Cu" "B.Cu")
		(net "VR_FET_SW_P12V_STBY_PVPP_GHJ")
	)
	(via
		(at 180.5178 -12.2936)
		(size 0.6604)
		(drill 0.3302)
		(layers "F.Cu" "B.Cu")
		(net "VR_FET_SW_P12V_STBY_PVPP_GHJ")
	)
	(via
		(at 182.052468 -10.429748)
		(size 0.508)
		(drill 0.254)
		(layers "F.Cu" "B.Cu")
		(net "VR_FET_SW_P12V_STBY_PVPP_GHJ")
	)
	(via
		(at 180.6194 -10.4394)
		(size 0.508)
		(drill 0.254)
		(layers "F.Cu" "B.Cu")
		(net "VR_FET_SW_P12V_STBY_PVPP_GHJ")
	)
	(via
		(at 183.467248 -12.445746)
		(size 0.508)
		(drill 0.254)
		(layers "F.Cu" "B.Cu")
		(net "VR_FET_SW_P12V_STBY_PVPP_GHJ")
	)
	(via
		(at 183.169814 -11.9126)
		(size 0.508)
		(drill 0.254)
		(layers "F.Cu" "B.Cu")
		(net "VR_FET_SW_P12V_STBY_PVPP_GHJ")
	)
	(via
		(at 182.5244 -11.917934)
		(size 0.508)
		(drill 0.254)
		(layers "F.Cu" "B.Cu")
		(net "VR_FET_SW_P12V_STBY_PVPP_GHJ")
	)
	(segment
		(start 174.0154 -10.922)
		(end 174.498 -10.922)
		(width 0.508)
		(layer "In2.Cu")
		(net "VR_FET_SW_P12V_STBY_PVPP_GHJ")
	)
	(segment
		(start 174.851314 -10.568686)
		(end 178.074066 -10.568686)
		(width 0.508)
		(layer "In2.Cu")
		(net "VR_FET_SW_P12V_STBY_PVPP_GHJ")
	)
	(segment
		(start 178.074066 -10.568686)
		(end 178.65598 -11.1506)
		(width 0.508)
		(layer "In2.Cu")
		(net "VR_FET_SW_P12V_STBY_PVPP_GHJ")
	)
	(segment
		(start 178.65598 -11.1506)
		(end 181.356 -11.1506)
		(width 0.508)
		(layer "In2.Cu")
		(net "VR_FET_SW_P12V_STBY_PVPP_GHJ")
	)
	(segment
		(start 174.498 -10.922)
		(end 174.851314 -10.568686)
		(width 0.508)
		(layer "In2.Cu")
		(net "VR_FET_SW_P12V_STBY_PVPP_GHJ")
	)
	(segment
		(start 482.6381 -127.323088)
		(end 482.6381 -132.171186)
		(width 0.1143)
		(layer "B.Cu")
		(net "USB2_P01_ESD_DP")
	)
	(segment
		(start 482.971094 -132.504434)
		(end 483.611174 -132.769356)
		(width 0.1143)
		(layer "B.Cu")
		(net "USB2_P01_ESD_DP")
	)
	(segment
		(start 476.9104 -124.627386)
		(end 477.0247 -124.741686)
		(width 0.1143)
		(layer "B.Cu")
		(net "USB2_P01_ESD_DP")
	)
	(segment
		(start 476.310198 -124.756926)
		(end 476.537274 -124.756926)
		(width 0.1143)
		(layer "B.Cu")
		(net "USB2_P01_ESD_DP")
	)
	(segment
		(start 484.870252 -132.121148)
		(end 484.870252 -131.769866)
		(width 0.1143)
		(layer "B.Cu")
		(net "USB2_P01_ESD_DP")
	)
	(segment
		(start 485.750108 -131.655058)
		(end 485.751124 -131.655312)
		(width 0.1143)
		(layer "B.Cu")
		(net "USB2_P01_ESD_DP")
	)
	(segment
		(start 477.0247 -125.830076)
		(end 477.889824 -126.6952)
		(width 0.1143)
		(layer "B.Cu")
		(net "USB2_P01_ESD_DP")
	)
	(segment
		(start 476.537274 -124.756926)
		(end 476.666814 -124.627386)
		(width 0.1143)
		(layer "B.Cu")
		(net "USB2_P01_ESD_DP")
	)
	(segment
		(start 483.611174 -132.769356)
		(end 484.222044 -132.769356)
		(width 0.1143)
		(layer "B.Cu")
		(net "USB2_P01_ESD_DP")
	)
	(segment
		(start 484.222044 -132.769356)
		(end 484.870252 -132.121148)
		(width 0.1143)
		(layer "B.Cu")
		(net "USB2_P01_ESD_DP")
	)
	(segment
		(start 475.726252 -124.756926)
		(end 476.310198 -124.756926)
		(width 0.1143)
		(layer "B.Cu")
		(net "USB2_P01_ESD_DP")
	)
	(segment
		(start 475.376748 -124.756926)
		(end 475.247208 -124.627386)
		(width 0.1143)
		(layer "B.Cu")
		(net "USB2_P01_ESD_DP")
	)
	(segment
		(start 477.0247 -124.741686)
		(end 477.0247 -125.830076)
		(width 0.1143)
		(layer "B.Cu")
		(net "USB2_P01_ESD_DP")
	)
	(segment
		(start 475.726252 -124.756926)
		(end 475.376748 -124.756926)
		(width 0.1143)
		(layer "B.Cu")
		(net "USB2_P01_ESD_DP")
	)
	(segment
		(start 482.6381 -132.171186)
		(end 482.971094 -132.504434)
		(width 0.1143)
		(layer "B.Cu")
		(net "USB2_P01_ESD_DP")
	)
	(segment
		(start 484.98506 -131.655058)
		(end 485.750108 -131.655058)
		(width 0.1143)
		(layer "B.Cu")
		(net "USB2_P01_ESD_DP")
	)
	(segment
		(start 477.889824 -126.6952)
		(end 482.010212 -126.6952)
		(width 0.1143)
		(layer "B.Cu")
		(net "USB2_P01_ESD_DP")
	)
	(segment
		(start 474.431614 -124.627386)
		(end 474.1799 -124.8791)
		(width 0.1143)
		(layer "B.Cu")
		(net "USB2_P01_ESD_DP")
	)
	(segment
		(start 484.870252 -131.769866)
		(end 484.98506 -131.655058)
		(width 0.1143)
		(layer "B.Cu")
		(net "USB2_P01_ESD_DP")
	)
	(segment
		(start 474.1799 -124.8791)
		(end 473.6973 -124.8791)
		(width 0.1143)
		(layer "B.Cu")
		(net "USB2_P01_ESD_DP")
	)
	(segment
		(start 475.247208 -124.627386)
		(end 474.431614 -124.627386)
		(width 0.1143)
		(layer "B.Cu")
		(net "USB2_P01_ESD_DP")
	)
	(segment
		(start 476.666814 -124.627386)
		(end 476.9104 -124.627386)
		(width 0.1143)
		(layer "B.Cu")
		(net "USB2_P01_ESD_DP")
	)
	(segment
		(start 482.010212 -126.6952)
		(end 482.6381 -127.323088)
		(width 0.1143)
		(layer "B.Cu")
		(net "USB2_P01_ESD_DP")
	)
	(segment
		(start 482.8794 -128.480312)
		(end 482.9937 -128.594612)
		(width 0.1143)
		(layer "B.Cu")
		(net "USB2_P01_ESD_DN")
	)
	(segment
		(start 482.9937 -128.937512)
		(end 482.8794 -129.051812)
		(width 0.1143)
		(layer "B.Cu")
		(net "USB2_P01_ESD_DN")
	)
	(segment
		(start 474.1672 -124.079)
		(end 474.474286 -124.386086)
		(width 0.1143)
		(layer "B.Cu")
		(net "USB2_P01_ESD_DN")
	)
	(segment
		(start 482.9937 -128.594612)
		(end 482.9937 -128.937512)
		(width 0.1143)
		(layer "B.Cu")
		(net "USB2_P01_ESD_DN")
	)
	(segment
		(start 482.8794 -129.051812)
		(end 482.8794 -129.394712)
		(width 0.1143)
		(layer "B.Cu")
		(net "USB2_P01_ESD_DN")
	)
	(segment
		(start 482.9937 -130.766312)
		(end 482.8794 -130.880612)
		(width 0.1143)
		(layer "B.Cu")
		(net "USB2_P01_ESD_DN")
	)
	(segment
		(start 475.247462 -124.386086)
		(end 475.376748 -124.2568)
		(width 0.1143)
		(layer "B.Cu")
		(net "USB2_P01_ESD_DN")
	)
	(segment
		(start 476.684086 -124.386086)
		(end 477.010476 -124.386086)
		(width 0.1143)
		(layer "B.Cu")
		(net "USB2_P01_ESD_DN")
	)
	(segment
		(start 482.110288 -126.4539)
		(end 482.8794 -127.223012)
		(width 0.1143)
		(layer "B.Cu")
		(net "USB2_P01_ESD_DN")
	)
	(segment
		(start 482.8794 -128.137412)
		(end 482.8794 -128.480312)
		(width 0.1143)
		(layer "B.Cu")
		(net "USB2_P01_ESD_DN")
	)
	(segment
		(start 477.266 -124.64161)
		(end 477.266 -125.73)
		(width 0.1143)
		(layer "B.Cu")
		(net "USB2_P01_ESD_DN")
	)
	(segment
		(start 484.514906 -131.654804)
		(end 484.514398 -131.655312)
		(width 0.1143)
		(layer "B.Cu")
		(net "USB2_P01_ESD_DN")
	)
	(segment
		(start 482.8794 -132.07111)
		(end 483.108 -132.29971)
		(width 0.1143)
		(layer "B.Cu")
		(net "USB2_P01_ESD_DN")
	)
	(segment
		(start 474.474286 -124.386086)
		(end 475.247462 -124.386086)
		(width 0.1143)
		(layer "B.Cu")
		(net "USB2_P01_ESD_DN")
	)
	(segment
		(start 483.108 -132.29971)
		(end 483.65918 -132.528056)
		(width 0.1143)
		(layer "B.Cu")
		(net "USB2_P01_ESD_DN")
	)
	(segment
		(start 482.8794 -127.223012)
		(end 482.8794 -127.565912)
		(width 0.1143)
		(layer "B.Cu")
		(net "USB2_P01_ESD_DN")
	)
	(segment
		(start 482.9937 -127.680212)
		(end 482.9937 -128.023112)
		(width 0.1143)
		(layer "B.Cu")
		(net "USB2_P01_ESD_DN")
	)
	(segment
		(start 477.010476 -124.386086)
		(end 477.266 -124.64161)
		(width 0.1143)
		(layer "B.Cu")
		(net "USB2_P01_ESD_DN")
	)
	(segment
		(start 484.628952 -131.76885)
		(end 484.514906 -131.654804)
		(width 0.1143)
		(layer "B.Cu")
		(net "USB2_P01_ESD_DN")
	)
	(segment
		(start 483.65918 -132.528056)
		(end 484.121968 -132.528056)
		(width 0.1143)
		(layer "B.Cu")
		(net "USB2_P01_ESD_DN")
	)
	(segment
		(start 482.8794 -129.966212)
		(end 482.8794 -130.309112)
		(width 0.1143)
		(layer "B.Cu")
		(net "USB2_P01_ESD_DN")
	)
	(segment
		(start 475.726252 -124.2568)
		(end 476.310198 -124.2568)
		(width 0.1143)
		(layer "B.Cu")
		(net "USB2_P01_ESD_DN")
	)
	(segment
		(start 482.9937 -129.509012)
		(end 482.9937 -129.851912)
		(width 0.1143)
		(layer "B.Cu")
		(net "USB2_P01_ESD_DN")
	)
	(segment
		(start 477.9899 -126.4539)
		(end 482.110288 -126.4539)
		(width 0.1143)
		(layer "B.Cu")
		(net "USB2_P01_ESD_DN")
	)
	(segment
		(start 484.628952 -132.021072)
		(end 484.628952 -131.76885)
		(width 0.1143)
		(layer "B.Cu")
		(net "USB2_P01_ESD_DN")
	)
	(segment
		(start 482.9937 -130.423412)
		(end 482.9937 -130.766312)
		(width 0.1143)
		(layer "B.Cu")
		(net "USB2_P01_ESD_DN")
	)
	(segment
		(start 473.6973 -124.079)
		(end 474.1672 -124.079)
		(width 0.1143)
		(layer "B.Cu")
		(net "USB2_P01_ESD_DN")
	)
	(segment
		(start 482.8794 -130.309112)
		(end 482.9937 -130.423412)
		(width 0.1143)
		(layer "B.Cu")
		(net "USB2_P01_ESD_DN")
	)
	(segment
		(start 482.9937 -128.023112)
		(end 482.8794 -128.137412)
		(width 0.1143)
		(layer "B.Cu")
		(net "USB2_P01_ESD_DN")
	)
	(segment
		(start 482.8794 -129.394712)
		(end 482.9937 -129.509012)
		(width 0.1143)
		(layer "B.Cu")
		(net "USB2_P01_ESD_DN")
	)
	(segment
		(start 484.121968 -132.528056)
		(end 484.628952 -132.021072)
		(width 0.1143)
		(layer "B.Cu")
		(net "USB2_P01_ESD_DN")
	)
	(segment
		(start 477.266 -125.73)
		(end 477.9899 -126.4539)
		(width 0.1143)
		(layer "B.Cu")
		(net "USB2_P01_ESD_DN")
	)
	(segment
		(start 476.5548 -124.2568)
		(end 476.684086 -124.386086)
		(width 0.1143)
		(layer "B.Cu")
		(net "USB2_P01_ESD_DN")
	)
	(segment
		(start 482.9937 -129.851912)
		(end 482.8794 -129.966212)
		(width 0.1143)
		(layer "B.Cu")
		(net "USB2_P01_ESD_DN")
	)
	(segment
		(start 475.376748 -124.2568)
		(end 475.726252 -124.2568)
		(width 0.1143)
		(layer "B.Cu")
		(net "USB2_P01_ESD_DN")
	)
	(segment
		(start 476.310198 -124.2568)
		(end 476.5548 -124.2568)
		(width 0.1143)
		(layer "B.Cu")
		(net "USB2_P01_ESD_DN")
	)
	(segment
		(start 484.514398 -131.655312)
		(end 483.751128 -131.655312)
		(width 0.1143)
		(layer "B.Cu")
		(net "USB2_P01_ESD_DN")
	)
	(segment
		(start 482.8794 -130.880612)
		(end 482.8794 -132.07111)
		(width 0.1143)
		(layer "B.Cu")
		(net "USB2_P01_ESD_DN")
	)
	(segment
		(start 482.8794 -127.565912)
		(end 482.9937 -127.680212)
		(width 0.1143)
		(layer "B.Cu")
		(net "USB2_P01_ESD_DN")
	)
	(segment
		(start 436.74919 -128.727454)
		(end 436.74919 -128.7272)
		(width 0.10795)
		(layer "F.Cu")
		(net "TP_SLG55021_P5V_8")
	)
	(segment
		(start 435.49062 -129.2479)
		(end 436.228744 -129.2479)
		(width 0.10795)
		(layer "F.Cu")
		(net "TP_SLG55021_P5V_8")
	)
	(segment
		(start 436.74919 -128.7272)
		(end 436.749444 -128.7272)
		(width 0.10795)
		(layer "F.Cu")
		(net "TP_SLG55021_P5V_8")
	)
	(segment
		(start 436.228744 -129.2479)
		(end 436.74919 -128.727454)
		(width 0.10795)
		(layer "F.Cu")
		(net "TP_SLG55021_P5V_8")
	)
	(via
		(at 436.749444 -128.7272)
		(size 0.762)
		(drill 0.381)
		(layers "F.Cu" "B.Cu")
		(net "TP_SLG55021_P5V_8")
	)
	(via
		(at 473.9894 -13.1064)
		(size 0.6604)
		(drill 0.3302)
		(layers "F.Cu" "B.Cu")
		(net "TP_SLG55021_P3V3_8")
	)
	(segment
		(start 475.0943 -12.0015)
		(end 473.9894 -13.1064)
		(width 0.10795)
		(layer "B.Cu")
		(net "TP_SLG55021_P3V3_8")
	)
	(segment
		(start 475.484952 -12.0015)
		(end 475.0943 -12.0015)
		(width 0.10795)
		(layer "B.Cu")
		(net "TP_SLG55021_P3V3_8")
	)
	(segment
		(start 167.1193 -75.2729)
		(end 167.1193 -75.3999)
		(width 0.10795)
		(layer "F.Cu")
		(net "FM_100M_N")
	)
	(segment
		(start 167.172386 -75.856338)
		(end 167.1193 -75.803252)
		(width 0.10795)
		(layer "F.Cu")
		(net "FM_100M_N")
	)
	(segment
		(start 166.497 -74.549)
		(end 166.497 -74.6506)
		(width 0.10795)
		(layer "F.Cu")
		(net "FM_100M_N")
	)
	(segment
		(start 167.1193 -75.803252)
		(end 167.1193 -75.3999)
		(width 0.10795)
		(layer "F.Cu")
		(net "FM_100M_N")
	)
	(segment
		(start 167.172386 -76.593192)
		(end 167.172386 -75.856338)
		(width 0.10795)
		(layer "F.Cu")
		(net "FM_100M_N")
	)
	(segment
		(start 166.497 -74.6506)
		(end 167.1193 -75.2729)
		(width 0.10795)
		(layer "F.Cu")
		(net "FM_100M_N")
	)
	(via
		(at 167.1193 -75.3999)
		(size 0.508)
		(drill 0.254)
		(layers "F.Cu" "B.Cu")
		(net "FM_100M_N")
	)
	(segment
		(start 166.497 -74.7776)
		(end 166.497 -74.549)
		(width 0.10795)
		(layer "B.Cu")
		(net "FM_100M_N")
	)
	(segment
		(start 167.1193 -75.3999)
		(end 166.497 -74.7776)
		(width 0.10795)
		(layer "B.Cu")
		(net "FM_100M_N")
	)
	(segment
		(start 21.258784 -85.573616)
		(end 21.146516 -85.573616)
		(width 0.254)
		(layer "F.Cu")
		(net "A_HSC_LOW_GATE")
	)
	(segment
		(start 20.9423 -84.455)
		(end 20.9423 -85.217)
		(width 0.254)
		(layer "F.Cu")
		(net "A_HSC_LOW_GATE")
	)
	(segment
		(start 21.146516 -85.573616)
		(end 20.8661 -85.2932)
		(width 0.254)
		(layer "F.Cu")
		(net "A_HSC_LOW_GATE")
	)
	(segment
		(start 21.5011 -86.0298)
		(end 21.5011 -85.815932)
		(width 0.254)
		(layer "F.Cu")
		(net "A_HSC_LOW_GATE")
	)
	(segment
		(start 20.9423 -85.217)
		(end 20.8661 -85.2932)
		(width 0.254)
		(layer "F.Cu")
		(net "A_HSC_LOW_GATE")
	)
	(segment
		(start 21.5011 -85.815932)
		(end 21.258784 -85.573616)
		(width 0.254)
		(layer "F.Cu")
		(net "A_HSC_LOW_GATE")
	)
	(via
		(at 13.4874 -80.01)
		(size 0.508)
		(drill 0.254)
		(layers "F.Cu" "B.Cu")
		(net "A_HSC_LOW_GATE")
	)
	(via
		(at 20.450302 -85.956648)
		(size 0.6604)
		(drill 0.3302)
		(layers "F.Cu" "B.Cu")
		(net "A_HSC_LOW_GATE")
	)
	(via
		(at 15.100808 -86.0552)
		(size 0.508)
		(drill 0.254)
		(layers "F.Cu" "B.Cu")
		(net "A_HSC_LOW_GATE")
	)
	(via
		(at 20.8661 -85.2932)
		(size 0.508)
		(drill 0.254)
		(layers "F.Cu" "B.Cu")
		(net "A_HSC_LOW_GATE")
	)
	(segment
		(start 16.3576 -85.217)
		(end 16.728186 -84.846414)
		(width 0.254)
		(layer "B.Cu")
		(net "A_HSC_LOW_GATE")
	)
	(segment
		(start 13.4874 -80.01)
		(end 13.3096 -79.8322)
		(width 0.254)
		(layer "B.Cu")
		(net "A_HSC_LOW_GATE")
	)
	(segment
		(start 20.8661 -85.54085)
		(end 20.8661 -85.2932)
		(width 0.254)
		(layer "B.Cu")
		(net "A_HSC_LOW_GATE")
	)
	(segment
		(start 16.728186 -84.846414)
		(end 16.728186 -84.455)
		(width 0.254)
		(layer "B.Cu")
		(net "A_HSC_LOW_GATE")
	)
	(segment
		(start 20.450302 -85.956648)
		(end 20.8661 -85.54085)
		(width 0.254)
		(layer "B.Cu")
		(net "A_HSC_LOW_GATE")
	)
	(segment
		(start 13.3096 -79.8322)
		(end 12.286488 -79.8322)
		(width 0.254)
		(layer "B.Cu")
		(net "A_HSC_LOW_GATE")
	)
	(segment
		(start 15.106904 -86.049104)
		(end 15.106904 -85.624416)
		(width 0.254)
		(layer "B.Cu")
		(net "A_HSC_LOW_GATE")
	)
	(segment
		(start 15.51432 -85.217)
		(end 16.3576 -85.217)
		(width 0.254)
		(layer "B.Cu")
		(net "A_HSC_LOW_GATE")
	)
	(segment
		(start 15.100808 -86.0552)
		(end 15.106904 -86.049104)
		(width 0.254)
		(layer "B.Cu")
		(net "A_HSC_LOW_GATE")
	)
	(segment
		(start 15.106904 -85.624416)
		(end 15.51432 -85.217)
		(width 0.254)
		(layer "B.Cu")
		(net "A_HSC_LOW_GATE")
	)
	(segment
		(start 15.100808 -86.0552)
		(end 16.256508 -84.8995)
		(width 0.254)
		(layer "In2.Cu")
		(net "A_HSC_LOW_GATE")
	)
	(segment
		(start 19.294348 -84.8995)
		(end 20.018248 -85.6234)
		(width 0.254)
		(layer "In2.Cu")
		(net "A_HSC_LOW_GATE")
	)
	(segment
		(start 16.256508 -84.8995)
		(end 19.294348 -84.8995)
		(width 0.254)
		(layer "In2.Cu")
		(net "A_HSC_LOW_GATE")
	)
	(segment
		(start 20.018248 -85.6234)
		(end 20.5359 -85.6234)
		(width 0.254)
		(layer "In2.Cu")
		(net "A_HSC_LOW_GATE")
	)
	(segment
		(start 20.5359 -85.6234)
		(end 20.8661 -85.2932)
		(width 0.254)
		(layer "In2.Cu")
		(net "A_HSC_LOW_GATE")
	)
	(segment
		(start 13.4874 -80.01)
		(end 15.0876 -81.6102)
		(width 0.254)
		(layer "In4.Cu")
		(net "A_HSC_LOW_GATE")
	)
	(segment
		(start 15.100808 -85.5726)
		(end 15.100808 -86.0552)
		(width 0.254)
		(layer "In4.Cu")
		(net "A_HSC_LOW_GATE")
	)
	(segment
		(start 15.0876 -85.559392)
		(end 15.100808 -85.5726)
		(width 0.254)
		(layer "In4.Cu")
		(net "A_HSC_LOW_GATE")
	)
	(segment
		(start 15.0876 -81.6102)
		(end 15.0876 -85.559392)
		(width 0.254)
		(layer "In4.Cu")
		(net "A_HSC_LOW_GATE")
	)
	(via
		(at 18.0086 -80.6196)
		(size 0.6604)
		(drill 0.3302)
		(layers "F.Cu" "B.Cu")
		(net "A_HSC_LOW_DRAIN")
	)
	(segment
		(start 18.0086 -80.6196)
		(end 16.6624 -80.6196)
		(width 0.10795)
		(layer "B.Cu")
		(net "A_HSC_LOW_DRAIN")
	)
	(segment
		(start 16.6624 -80.6196)
		(end 16.256 -81.026)
		(width 0.10795)
		(layer "B.Cu")
		(net "A_HSC_LOW_DRAIN")
	)
	(segment
		(start 16.0782 -82.677)
		(end 16.0782 -81.84642)
		(width 0.10795)
		(layer "B.Cu")
		(net "A_HSC_LOW_DRAIN")
	)
	(segment
		(start 16.0782 -81.84642)
		(end 16.256 -81.66862)
		(width 0.10795)
		(layer "B.Cu")
		(net "A_HSC_LOW_DRAIN")
	)
	(segment
		(start 16.256 -81.026)
		(end 16.256 -81.153)
		(width 0.10795)
		(layer "B.Cu")
		(net "A_HSC_LOW_DRAIN")
	)
	(segment
		(start 16.256 -81.66862)
		(end 16.256 -81.153)
		(width 0.10795)
		(layer "B.Cu")
		(net "A_HSC_LOW_DRAIN")
	)
	(segment
		(start 22.66188 -84.13242)
		(end 23.45182 -84.13242)
		(width 0.254)
		(layer "F.Cu")
		(net "A_HSC_LOW")
	)
	(segment
		(start 23.16099 -85.0646)
		(end 23.46198 -84.76361)
		(width 0.254)
		(layer "F.Cu")
		(net "A_HSC_LOW")
	)
	(segment
		(start 23.45182 -84.13242)
		(end 23.46198 -84.14258)
		(width 0.254)
		(layer "F.Cu")
		(net "A_HSC_LOW")
	)
	(segment
		(start 21.942298 -84.455)
		(end 22.3393 -84.455)
		(width 0.254)
		(layer "F.Cu")
		(net "A_HSC_LOW")
	)
	(segment
		(start 23.46198 -84.76361)
		(end 23.46198 -84.14258)
		(width 0.254)
		(layer "F.Cu")
		(net "A_HSC_LOW")
	)
	(segment
		(start 22.3393 -84.455)
		(end 22.66188 -84.13242)
		(width 0.254)
		(layer "F.Cu")
		(net "A_HSC_LOW")
	)
	(via
		(at 23.16099 -85.0646)
		(size 0.762)
		(drill 0.381)
		(layers "F.Cu" "B.Cu")
		(net "A_HSC_LOW")
	)
	(segment
		(start 22.225 -81.788)
		(end 21.942298 -82.070702)
		(width 0.2032)
		(layer "F.Cu")
		(net "A_HSC_HIGH")
	)
	(segment
		(start 22.72157 -81.030318)
		(end 23.030688 -80.7212)
		(width 0.254)
		(layer "F.Cu")
		(net "A_HSC_HIGH")
	)
	(segment
		(start 23.030688 -80.7212)
		(end 23.241 -80.7212)
		(width 0.254)
		(layer "F.Cu")
		(net "A_HSC_HIGH")
	)
	(segment
		(start 23.8506 -80.7212)
		(end 23.241 -80.7212)
		(width 0.254)
		(layer "F.Cu")
		(net "A_HSC_HIGH")
	)
	(segment
		(start 21.942298 -82.070702)
		(end 21.942298 -83.2866)
		(width 0.2032)
		(layer "F.Cu")
		(net "A_HSC_HIGH")
	)
	(segment
		(start 22.4282 -81.788)
		(end 22.72157 -81.49463)
		(width 0.254)
		(layer "F.Cu")
		(net "A_HSC_HIGH")
	)
	(segment
		(start 22.72157 -81.49463)
		(end 22.72157 -81.030318)
		(width 0.254)
		(layer "F.Cu")
		(net "A_HSC_HIGH")
	)
	(segment
		(start 24.08174 -80.95234)
		(end 23.8506 -80.7212)
		(width 0.254)
		(layer "F.Cu")
		(net "A_HSC_HIGH")
	)
	(segment
		(start 22.225 -81.788)
		(end 22.4282 -81.788)
		(width 0.254)
		(layer "F.Cu")
		(net "A_HSC_HIGH")
	)
	(via
		(at 24.08174 -80.95234)
		(size 0.762)
		(drill 0.381)
		(layers "F.Cu" "B.Cu")
		(net "A_HSC_HIGH")
	)
	(segment
		(start 178.3842 -129.54)
		(end 178.3334 -129.4892)
		(width 0.10795)
		(layer "F.Cu")
		(net "PWRGD_PVPP_KLM_R")
	)
	(segment
		(start 178.3842 -131.597146)
		(end 178.3842 -129.54)
		(width 0.10795)
		(layer "F.Cu")
		(net "PWRGD_PVPP_KLM_R")
	)
	(segment
		(start 178.943 -133.0706)
		(end 178.423062 -133.590538)
		(width 0.10795)
		(layer "F.Cu")
		(net "PWRGD_PVPP_KLM_R")
	)
	(segment
		(start 178.423062 -133.590538)
		(end 178.423062 -134.0104)
		(width 0.10795)
		(layer "F.Cu")
		(net "PWRGD_PVPP_KLM_R")
	)
	(segment
		(start 178.943 -131.7625)
		(end 178.943 -133.0706)
		(width 0.10795)
		(layer "F.Cu")
		(net "PWRGD_PVPP_KLM_R")
	)
	(segment
		(start 178.943 -131.7625)
		(end 179.959 -131.7625)
		(width 0.10795)
		(layer "F.Cu")
		(net "PWRGD_PVPP_KLM_R")
	)
	(segment
		(start 178.549554 -131.7625)
		(end 178.3842 -131.597146)
		(width 0.10795)
		(layer "F.Cu")
		(net "PWRGD_PVPP_KLM_R")
	)
	(segment
		(start 179.959 -131.7625)
		(end 180.8734 -131.7625)
		(width 0.10795)
		(layer "F.Cu")
		(net "PWRGD_PVPP_KLM_R")
	)
	(segment
		(start 178.943 -131.7625)
		(end 178.549554 -131.7625)
		(width 0.10795)
		(layer "F.Cu")
		(net "PWRGD_PVPP_KLM_R")
	)
	(via
		(at 178.3334 -129.4892)
		(size 0.762)
		(drill 0.381)
		(layers "F.Cu" "B.Cu")
		(net "PWRGD_PVPP_KLM_R")
	)
	(segment
		(start 180.848 -8.255)
		(end 179.959 -8.255)
		(width 0.10795)
		(layer "F.Cu")
		(net "PWRGD_PVPP_GHJ_R")
	)
	(segment
		(start 178.4096 -8.070596)
		(end 178.517804 -8.1788)
		(width 0.10795)
		(layer "F.Cu")
		(net "PWRGD_PVPP_GHJ_R")
	)
	(segment
		(start 179.365402 -8.1788)
		(end 178.943 -8.1788)
		(width 0.10795)
		(layer "F.Cu")
		(net "PWRGD_PVPP_GHJ_R")
	)
	(segment
		(start 178.4096 -6.0198)
		(end 178.4096 -8.070596)
		(width 0.10795)
		(layer "F.Cu")
		(net "PWRGD_PVPP_GHJ_R")
	)
	(segment
		(start 179.441602 -8.255)
		(end 179.365402 -8.1788)
		(width 0.10795)
		(layer "F.Cu")
		(net "PWRGD_PVPP_GHJ_R")
	)
	(segment
		(start 178.943 -8.1788)
		(end 178.943 -9.4742)
		(width 0.10795)
		(layer "F.Cu")
		(net "PWRGD_PVPP_GHJ_R")
	)
	(segment
		(start 179.959 -8.255)
		(end 179.441602 -8.255)
		(width 0.10795)
		(layer "F.Cu")
		(net "PWRGD_PVPP_GHJ_R")
	)
	(segment
		(start 178.423062 -9.994138)
		(end 178.423062 -10.5029)
		(width 0.10795)
		(layer "F.Cu")
		(net "PWRGD_PVPP_GHJ_R")
	)
	(segment
		(start 178.517804 -8.1788)
		(end 178.943 -8.1788)
		(width 0.10795)
		(layer "F.Cu")
		(net "PWRGD_PVPP_GHJ_R")
	)
	(segment
		(start 178.943 -9.4742)
		(end 178.423062 -9.994138)
		(width 0.10795)
		(layer "F.Cu")
		(net "PWRGD_PVPP_GHJ_R")
	)
	(via
		(at 178.4096 -6.0198)
		(size 0.762)
		(drill 0.381)
		(layers "F.Cu" "B.Cu")
		(net "PWRGD_PVPP_GHJ_R")
	)
	(segment
		(start 346.202 -127.609092)
		(end 346.60205 -128.009142)
		(width 0.10795)
		(layer "F.Cu")
		(net "PWRGD_PVPP_DEF_R")
	)
	(segment
		(start 346.202 -127.127)
		(end 345.821 -127.127)
		(width 0.10795)
		(layer "F.Cu")
		(net "PWRGD_PVPP_DEF_R")
	)
	(segment
		(start 345.567 -128.8034)
		(end 344.793062 -129.577338)
		(width 0.10795)
		(layer "F.Cu")
		(net "PWRGD_PVPP_DEF_R")
	)
	(segment
		(start 350.19107 -128.493266)
		(end 353.810062 -128.493266)
		(width 0.10795)
		(layer "F.Cu")
		(net "PWRGD_PVPP_DEF_R")
	)
	(segment
		(start 354.785168 -128.493266)
		(end 354.805234 -128.4732)
		(width 0.10795)
		(layer "F.Cu")
		(net "PWRGD_PVPP_DEF_R")
	)
	(segment
		(start 344.793062 -129.577338)
		(end 344.793062 -130.0226)
		(width 0.10795)
		(layer "F.Cu")
		(net "PWRGD_PVPP_DEF_R")
	)
	(segment
		(start 349.706946 -128.009142)
		(end 350.19107 -128.493266)
		(width 0.10795)
		(layer "F.Cu")
		(net "PWRGD_PVPP_DEF_R")
	)
	(segment
		(start 348.6404 -128.009142)
		(end 349.706946 -128.009142)
		(width 0.10795)
		(layer "F.Cu")
		(net "PWRGD_PVPP_DEF_R")
	)
	(segment
		(start 345.821 -127.127)
		(end 345.567 -127.381)
		(width 0.10795)
		(layer "F.Cu")
		(net "PWRGD_PVPP_DEF_R")
	)
	(segment
		(start 346.202 -127.127)
		(end 346.202 -127.609092)
		(width 0.10795)
		(layer "F.Cu")
		(net "PWRGD_PVPP_DEF_R")
	)
	(segment
		(start 353.810062 -128.493266)
		(end 354.785168 -128.493266)
		(width 0.10795)
		(layer "F.Cu")
		(net "PWRGD_PVPP_DEF_R")
	)
	(segment
		(start 346.60205 -128.009142)
		(end 348.6404 -128.009142)
		(width 0.10795)
		(layer "F.Cu")
		(net "PWRGD_PVPP_DEF_R")
	)
	(segment
		(start 345.567 -127.381)
		(end 345.567 -128.8034)
		(width 0.10795)
		(layer "F.Cu")
		(net "PWRGD_PVPP_DEF_R")
	)
	(via
		(at 348.6404 -128.009142)
		(size 0.762)
		(drill 0.381)
		(layers "F.Cu" "B.Cu")
		(net "PWRGD_PVPP_DEF_R")
	)
	(segment
		(start 346.6338 -23.4823)
		(end 347.622114 -23.4823)
		(width 0.10795)
		(layer "F.Cu")
		(net "PWRGD_PVPP_ABC_R")
	)
	(segment
		(start 348.379796 -23.4823)
		(end 348.384114 -23.486618)
		(width 0.10795)
		(layer "F.Cu")
		(net "PWRGD_PVPP_ABC_R")
	)
	(segment
		(start 346.6338 -24.7523)
		(end 346.6338 -24.49576)
		(width 0.10795)
		(layer "F.Cu")
		(net "PWRGD_PVPP_ABC_R")
	)
	(segment
		(start 346.113862 -25.7302)
		(end 346.113862 -25.272238)
		(width 0.10795)
		(layer "F.Cu")
		(net "PWRGD_PVPP_ABC_R")
	)
	(segment
		(start 347.622114 -23.4823)
		(end 348.379796 -23.4823)
		(width 0.10795)
		(layer "F.Cu")
		(net "PWRGD_PVPP_ABC_R")
	)
	(segment
		(start 346.113862 -25.272238)
		(end 346.6338 -24.7523)
		(width 0.10795)
		(layer "F.Cu")
		(net "PWRGD_PVPP_ABC_R")
	)
	(segment
		(start 346.6338 -23.4823)
		(end 346.6338 -24.49576)
		(width 0.10795)
		(layer "F.Cu")
		(net "PWRGD_PVPP_ABC_R")
	)
	(via
		(at 346.6338 -24.49576)
		(size 0.508)
		(drill 0.254)
		(layers "F.Cu" "B.Cu")
		(net "PWRGD_PVPP_ABC_R")
	)
	(segment
		(start 15.764002 -90.185494)
		(end 15.764002 -90.452702)
		(width 0.10795)
		(layer "F.Cu")
		(net "VR_VRRDY_PVCCIN_CPU1")
	)
	(segment
		(start 15.036292 -90.0684)
		(end 15.166594 -89.938098)
		(width 0.10795)
		(layer "F.Cu")
		(net "VR_VRRDY_PVCCIN_CPU1")
	)
	(segment
		(start 15.764002 -90.452702)
		(end 15.967202 -90.655902)
		(width 0.10795)
		(layer "F.Cu")
		(net "VR_VRRDY_PVCCIN_CPU1")
	)
	(segment
		(start 15.166594 -89.938098)
		(end 15.516606 -89.938098)
		(width 0.10795)
		(layer "F.Cu")
		(net "VR_VRRDY_PVCCIN_CPU1")
	)
	(segment
		(start 15.967202 -90.655902)
		(end 16.5354 -90.655902)
		(width 0.10795)
		(layer "F.Cu")
		(net "VR_VRRDY_PVCCIN_CPU1")
	)
	(segment
		(start 14.732 -88.4936)
		(end 14.732 -89.281)
		(width 0.10795)
		(layer "F.Cu")
		(net "VR_VRRDY_PVCCIN_CPU1")
	)
	(segment
		(start 14.732 -90.0684)
		(end 15.036292 -90.0684)
		(width 0.10795)
		(layer "F.Cu")
		(net "VR_VRRDY_PVCCIN_CPU1")
	)
	(segment
		(start 14.732 -90.0684)
		(end 14.732 -89.281)
		(width 0.10795)
		(layer "F.Cu")
		(net "VR_VRRDY_PVCCIN_CPU1")
	)
	(segment
		(start 15.516606 -89.938098)
		(end 15.764002 -90.185494)
		(width 0.10795)
		(layer "F.Cu")
		(net "VR_VRRDY_PVCCIN_CPU1")
	)
	(segment
		(start 180.4416 -67.437)
		(end 179.578 -67.437)
		(width 0.10795)
		(layer "F.Cu")
		(net "VR_VRRDY_PVCCIN_CPU0")
	)
	(segment
		(start 181.3814 -68.049902)
		(end 181.054502 -68.049902)
		(width 0.10795)
		(layer "F.Cu")
		(net "VR_VRRDY_PVCCIN_CPU0")
	)
	(segment
		(start 179.578 -66.2178)
		(end 179.6288 -66.167)
		(width 0.10795)
		(layer "F.Cu")
		(net "VR_VRRDY_PVCCIN_CPU0")
	)
	(segment
		(start 178.088036 -64.433958)
		(end 178.246278 -64.5922)
		(width 0.10795)
		(layer "F.Cu")
		(net "VR_VRRDY_PVCCIN_CPU0")
	)
	(segment
		(start 179.381404 -65.446402)
		(end 179.578508 -65.446402)
		(width 0.10795)
		(layer "F.Cu")
		(net "VR_VRRDY_PVCCIN_CPU0")
	)
	(segment
		(start 179.578 -67.437)
		(end 179.578 -66.548)
		(width 0.10795)
		(layer "F.Cu")
		(net "VR_VRRDY_PVCCIN_CPU0")
	)
	(segment
		(start 179.6288 -66.167)
		(end 179.6288 -65.7606)
		(width 0.10795)
		(layer "F.Cu")
		(net "VR_VRRDY_PVCCIN_CPU0")
	)
	(segment
		(start 179.282598 -64.89065)
		(end 179.282598 -65.347596)
		(width 0.10795)
		(layer "F.Cu")
		(net "VR_VRRDY_PVCCIN_CPU0")
	)
	(segment
		(start 178.984148 -64.5922)
		(end 179.282598 -64.89065)
		(width 0.10795)
		(layer "F.Cu")
		(net "VR_VRRDY_PVCCIN_CPU0")
	)
	(segment
		(start 179.578508 -65.446402)
		(end 179.6288 -65.496694)
		(width 0.10795)
		(layer "F.Cu")
		(net "VR_VRRDY_PVCCIN_CPU0")
	)
	(segment
		(start 179.578 -66.548)
		(end 179.578 -66.2178)
		(width 0.10795)
		(layer "F.Cu")
		(net "VR_VRRDY_PVCCIN_CPU0")
	)
	(segment
		(start 181.054502 -68.049902)
		(end 180.4416 -67.437)
		(width 0.10795)
		(layer "F.Cu")
		(net "VR_VRRDY_PVCCIN_CPU0")
	)
	(segment
		(start 179.282598 -65.347596)
		(end 179.381404 -65.446402)
		(width 0.10795)
		(layer "F.Cu")
		(net "VR_VRRDY_PVCCIN_CPU0")
	)
	(segment
		(start 178.246278 -64.5922)
		(end 178.984148 -64.5922)
		(width 0.10795)
		(layer "F.Cu")
		(net "VR_VRRDY_PVCCIN_CPU0")
	)
	(segment
		(start 179.6288 -65.496694)
		(end 179.6288 -65.7606)
		(width 0.10795)
		(layer "F.Cu")
		(net "VR_VRRDY_PVCCIN_CPU0")
	)
	(via
		(at 178.088036 -64.433958)
		(size 0.762)
		(drill 0.381)
		(layers "F.Cu" "B.Cu")
		(net "VR_VRRDY_PVCCIN_CPU0")
	)
	(segment
		(start 466.009736 -22.225)
		(end 466.435186 -22.65045)
		(width 0.10795)
		(layer "F.Cu")
		(net "PWRGD_P3V3_STBY_R")
	)
	(segment
		(start 465.582 -21.3233)
		(end 465.582 -22.225)
		(width 0.10795)
		(layer "F.Cu")
		(net "PWRGD_P3V3_STBY_R")
	)
	(segment
		(start 465.582 -21.3233)
		(end 464.7946 -21.3233)
		(width 0.10795)
		(layer "F.Cu")
		(net "PWRGD_P3V3_STBY_R")
	)
	(segment
		(start 465.582 -22.225)
		(end 466.009736 -22.225)
		(width 0.10795)
		(layer "F.Cu")
		(net "PWRGD_P3V3_STBY_R")
	)
	(segment
		(start 466.435186 -22.65045)
		(end 466.9536 -22.65045)
		(width 0.10795)
		(layer "F.Cu")
		(net "PWRGD_P3V3_STBY_R")
	)
	(segment
		(start 404.34514 -147.928584)
		(end 404.85314 -147.420584)
		(width 0.10795)
		(layer "F.Cu")
		(net "PWRGD_P1V8_PCH_STBY_R")
	)
	(segment
		(start 405.283416 -149.452584)
		(end 405.283416 -148.436584)
		(width 0.10795)
		(layer "F.Cu")
		(net "PWRGD_P1V8_PCH_STBY_R")
	)
	(segment
		(start 404.85314 -147.420584)
		(end 405.283416 -147.420584)
		(width 0.10795)
		(layer "F.Cu")
		(net "PWRGD_P1V8_PCH_STBY_R")
	)
	(segment
		(start 403.752812 -147.928584)
		(end 404.34514 -147.928584)
		(width 0.10795)
		(layer "F.Cu")
		(net "PWRGD_P1V8_PCH_STBY_R")
	)
	(segment
		(start 405.283416 -148.436584)
		(end 405.283416 -147.420584)
		(width 0.10795)
		(layer "F.Cu")
		(net "PWRGD_P1V8_PCH_STBY_R")
	)
	(segment
		(start 473.075 -37.337746)
		(end 472.930728 -37.193474)
		(width 0.10795)
		(layer "F.Cu")
		(net "PWRGD_P1V2_BMC_STBY_R")
	)
	(segment
		(start 472.930728 -37.193474)
		(end 472.422474 -37.701728)
		(width 0.10795)
		(layer "F.Cu")
		(net "PWRGD_P1V2_BMC_STBY_R")
	)
	(segment
		(start 472.422474 -37.701728)
		(end 472.422474 -38.037516)
		(width 0.10795)
		(layer "F.Cu")
		(net "PWRGD_P1V2_BMC_STBY_R")
	)
	(segment
		(start 472.422474 -38.037516)
		(end 472.271598 -38.188392)
		(width 0.10795)
		(layer "F.Cu")
		(net "PWRGD_P1V2_BMC_STBY_R")
	)
	(segment
		(start 473.075 -38.1)
		(end 473.075 -37.337746)
		(width 0.10795)
		(layer "F.Cu")
		(net "PWRGD_P1V2_BMC_STBY_R")
	)
	(segment
		(start 472.271598 -38.188392)
		(end 471.077798 -38.188392)
		(width 0.10795)
		(layer "F.Cu")
		(net "PWRGD_P1V2_BMC_STBY_R")
	)
	(via
		(at 472.930728 -37.193474)
		(size 0.508)
		(drill 0.254)
		(layers "F.Cu" "B.Cu")
		(net "PWRGD_P1V2_BMC_STBY_R")
	)
	(segment
		(start 472.354402 -37.7698)
		(end 472.354402 -38.340792)
		(width 0.10795)
		(layer "B.Cu")
		(net "PWRGD_P1V2_BMC_STBY_R")
	)
	(segment
		(start 472.930728 -37.193474)
		(end 472.354402 -37.7698)
		(width 0.10795)
		(layer "B.Cu")
		(net "PWRGD_P1V2_BMC_STBY_R")
	)
	(segment
		(start 473.329 -38.354)
		(end 473.329 -37.591746)
		(width 0.10795)
		(layer "B.Cu")
		(net "PWRGD_P1V2_BMC_STBY_R")
	)
	(segment
		(start 473.329 -37.591746)
		(end 472.930728 -37.193474)
		(width 0.10795)
		(layer "B.Cu")
		(net "PWRGD_P1V2_BMC_STBY_R")
	)
	(segment
		(start 462.114392 -37.956998)
		(end 461.098392 -37.956998)
		(width 0.10795)
		(layer "F.Cu")
		(net "PWRGD_P1V15_BMC_STBY_R")
	)
	(segment
		(start 461.098392 -37.956998)
		(end 460.082392 -37.956998)
		(width 0.10795)
		(layer "F.Cu")
		(net "PWRGD_P1V15_BMC_STBY_R")
	)
	(segment
		(start 460.082392 -37.956998)
		(end 460.082392 -39.132002)
		(width 0.10795)
		(layer "F.Cu")
		(net "PWRGD_P1V15_BMC_STBY_R")
	)
	(segment
		(start 459.844394 -37.956998)
		(end 459.613762 -37.726366)
		(width 0.10795)
		(layer "F.Cu")
		(net "PWRGD_P1V15_BMC_STBY_R")
	)
	(segment
		(start 459.613762 -37.726366)
		(end 459.613762 -37.27704)
		(width 0.10795)
		(layer "F.Cu")
		(net "PWRGD_P1V15_BMC_STBY_R")
	)
	(segment
		(start 460.082392 -39.132002)
		(end 460.463392 -39.513002)
		(width 0.10795)
		(layer "F.Cu")
		(net "PWRGD_P1V15_BMC_STBY_R")
	)
	(segment
		(start 460.082392 -37.956998)
		(end 459.844394 -37.956998)
		(width 0.10795)
		(layer "F.Cu")
		(net "PWRGD_P1V15_BMC_STBY_R")
	)
	(segment
		(start 459.613762 -37.27704)
		(end 458.8256 -36.488878)
		(width 0.10795)
		(layer "F.Cu")
		(net "PWRGD_P1V15_BMC_STBY_R")
	)
	(via
		(at 458.8256 -36.488878)
		(size 0.762)
		(drill 0.381)
		(layers "F.Cu" "B.Cu")
		(net "PWRGD_P1V15_BMC_STBY_R")
	)
	(segment
		(start 397.216376 -57.426352)
		(end 391.88644 -57.426352)
		(width 0.10795)
		(layer "F.Cu")
		(net "SMB_PEHPCPU1_STBY_LVC3_SDA")
	)
	(segment
		(start 359.283254 -69.561202)
		(end 358.582214 -69.561202)
		(width 0.10795)
		(layer "F.Cu")
		(net "SMB_PEHPCPU1_STBY_LVC3_SDA")
	)
	(segment
		(start 363.25175 -64.304164)
		(end 363.25175 -65.592706)
		(width 0.10795)
		(layer "F.Cu")
		(net "SMB_PEHPCPU1_STBY_LVC3_SDA")
	)
	(segment
		(start 387.505194 -60.010802)
		(end 386.943092 -59.4487)
		(width 0.10795)
		(layer "F.Cu")
		(net "SMB_PEHPCPU1_STBY_LVC3_SDA")
	)
	(segment
		(start 386.943092 -59.4487)
		(end 386.07746 -59.4487)
		(width 0.10795)
		(layer "F.Cu")
		(net "SMB_PEHPCPU1_STBY_LVC3_SDA")
	)
	(segment
		(start 376.313446 -61.57087)
		(end 374.922288 -61.57087)
		(width 0.10795)
		(layer "F.Cu")
		(net "SMB_PEHPCPU1_STBY_LVC3_SDA")
	)
	(segment
		(start 399.47342 -59.926474)
		(end 399.47342 -59.683396)
		(width 0.10795)
		(layer "F.Cu")
		(net "SMB_PEHPCPU1_STBY_LVC3_SDA")
	)
	(segment
		(start 364.729014 -61.1759)
		(end 363.62005 -62.284864)
		(width 0.10795)
		(layer "F.Cu")
		(net "SMB_PEHPCPU1_STBY_LVC3_SDA")
	)
	(segment
		(start 389.30199 -60.010802)
		(end 387.505194 -60.010802)
		(width 0.10795)
		(layer "F.Cu")
		(net "SMB_PEHPCPU1_STBY_LVC3_SDA")
	)
	(segment
		(start 410.290264 -35.334702)
		(end 409.890214 -35.734752)
		(width 0.089408)
		(layer "F.Cu")
		(net "SMB_PEHPCPU1_STBY_LVC3_SDA")
	)
	(segment
		(start 363.25175 -65.592706)
		(end 359.283254 -69.561202)
		(width 0.10795)
		(layer "F.Cu")
		(net "SMB_PEHPCPU1_STBY_LVC3_SDA")
	)
	(segment
		(start 357.70312 -68.682108)
		(end 350.179386 -68.682108)
		(width 0.10795)
		(layer "F.Cu")
		(net "SMB_PEHPCPU1_STBY_LVC3_SDA")
	)
	(segment
		(start 371.659404 -62.487302)
		(end 366.591596 -62.487302)
		(width 0.10795)
		(layer "F.Cu")
		(net "SMB_PEHPCPU1_STBY_LVC3_SDA")
	)
	(segment
		(start 338.407248 -72.03948)
		(end 339.02142 -71.425308)
		(width 0.10795)
		(layer "F.Cu")
		(net "SMB_PEHPCPU1_STBY_LVC3_SDA")
	)
	(segment
		(start 358.582214 -69.561202)
		(end 357.70312 -68.682108)
		(width 0.10795)
		(layer "F.Cu")
		(net "SMB_PEHPCPU1_STBY_LVC3_SDA")
	)
	(segment
		(start 374.608344 -61.256926)
		(end 372.88978 -61.256926)
		(width 0.10795)
		(layer "F.Cu")
		(net "SMB_PEHPCPU1_STBY_LVC3_SDA")
	)
	(segment
		(start 391.88644 -57.426352)
		(end 389.30199 -60.010802)
		(width 0.10795)
		(layer "F.Cu")
		(net "SMB_PEHPCPU1_STBY_LVC3_SDA")
	)
	(segment
		(start 340.427056 -69.650102)
		(end 339.02142 -71.055738)
		(width 0.10795)
		(layer "F.Cu")
		(net "SMB_PEHPCPU1_STBY_LVC3_SDA")
	)
	(segment
		(start 363.62005 -62.284864)
		(end 363.62005 -62.32525)
		(width 0.10795)
		(layer "F.Cu")
		(net "SMB_PEHPCPU1_STBY_LVC3_SDA")
	)
	(segment
		(start 363.6137 -63.942214)
		(end 363.25175 -64.304164)
		(width 0.10795)
		(layer "F.Cu")
		(net "SMB_PEHPCPU1_STBY_LVC3_SDA")
	)
	(segment
		(start 339.02142 -71.425308)
		(end 339.02142 -71.055738)
		(width 0.10795)
		(layer "F.Cu")
		(net "SMB_PEHPCPU1_STBY_LVC3_SDA")
	)
	(segment
		(start 350.179386 -68.682108)
		(end 349.799656 -68.302378)
		(width 0.10795)
		(layer "F.Cu")
		(net "SMB_PEHPCPU1_STBY_LVC3_SDA")
	)
	(segment
		(start 399.47342 -59.683396)
		(end 397.216376 -57.426352)
		(width 0.10795)
		(layer "F.Cu")
		(net "SMB_PEHPCPU1_STBY_LVC3_SDA")
	)
	(segment
		(start 365.280194 -61.1759)
		(end 364.729014 -61.1759)
		(width 0.10795)
		(layer "F.Cu")
		(net "SMB_PEHPCPU1_STBY_LVC3_SDA")
	)
	(segment
		(start 386.07746 -59.4487)
		(end 385.597146 -59.929014)
		(width 0.10795)
		(layer "F.Cu")
		(net "SMB_PEHPCPU1_STBY_LVC3_SDA")
	)
	(segment
		(start 372.88978 -61.256926)
		(end 371.659404 -62.487302)
		(width 0.10795)
		(layer "F.Cu")
		(net "SMB_PEHPCPU1_STBY_LVC3_SDA")
	)
	(segment
		(start 349.799656 -68.302378)
		(end 343.666064 -68.302378)
		(width 0.10795)
		(layer "F.Cu")
		(net "SMB_PEHPCPU1_STBY_LVC3_SDA")
	)
	(segment
		(start 342.31834 -69.650102)
		(end 340.427056 -69.650102)
		(width 0.10795)
		(layer "F.Cu")
		(net "SMB_PEHPCPU1_STBY_LVC3_SDA")
	)
	(segment
		(start 374.922288 -61.57087)
		(end 374.608344 -61.256926)
		(width 0.10795)
		(layer "F.Cu")
		(net "SMB_PEHPCPU1_STBY_LVC3_SDA")
	)
	(segment
		(start 343.666064 -68.302378)
		(end 342.31834 -69.650102)
		(width 0.10795)
		(layer "F.Cu")
		(net "SMB_PEHPCPU1_STBY_LVC3_SDA")
	)
	(segment
		(start 338.9376 -74.1807)
		(end 338.407248 -73.650348)
		(width 0.10795)
		(layer "F.Cu")
		(net "SMB_PEHPCPU1_STBY_LVC3_SDA")
	)
	(segment
		(start 366.591596 -62.487302)
		(end 365.280194 -61.1759)
		(width 0.10795)
		(layer "F.Cu")
		(net "SMB_PEHPCPU1_STBY_LVC3_SDA")
	)
	(segment
		(start 385.597146 -59.929014)
		(end 382.05029 -59.929014)
		(width 0.10795)
		(layer "F.Cu")
		(net "SMB_PEHPCPU1_STBY_LVC3_SDA")
	)
	(segment
		(start 382.05029 -59.929014)
		(end 381.739902 -60.239402)
		(width 0.10795)
		(layer "F.Cu")
		(net "SMB_PEHPCPU1_STBY_LVC3_SDA")
	)
	(segment
		(start 381.739902 -60.239402)
		(end 377.644914 -60.239402)
		(width 0.10795)
		(layer "F.Cu")
		(net "SMB_PEHPCPU1_STBY_LVC3_SDA")
	)
	(segment
		(start 338.407248 -73.650348)
		(end 338.407248 -72.03948)
		(width 0.10795)
		(layer "F.Cu")
		(net "SMB_PEHPCPU1_STBY_LVC3_SDA")
	)
	(segment
		(start 377.644914 -60.239402)
		(end 376.313446 -61.57087)
		(width 0.10795)
		(layer "F.Cu")
		(net "SMB_PEHPCPU1_STBY_LVC3_SDA")
	)
	(segment
		(start 363.62005 -62.32525)
		(end 363.6137 -62.3316)
		(width 0.10795)
		(layer "F.Cu")
		(net "SMB_PEHPCPU1_STBY_LVC3_SDA")
	)
	(segment
		(start 363.6137 -62.3316)
		(end 363.6137 -63.942214)
		(width 0.10795)
		(layer "F.Cu")
		(net "SMB_PEHPCPU1_STBY_LVC3_SDA")
	)
	(via
		(at 180.721 -156.533596)
		(size 0.508)
		(drill 0.254)
		(layers "F.Cu" "B.Cu")
		(net "SMB_PEHPCPU1_STBY_LVC3_SDA")
	)
	(via
		(at 339.02142 -71.055738)
		(size 0.762)
		(drill 0.381)
		(layers "F.Cu" "B.Cu")
		(net "SMB_PEHPCPU1_STBY_LVC3_SDA")
	)
	(via
		(at -5.024882 -122.246644)
		(size 0.508)
		(drill 0.254)
		(layers "F.Cu" "B.Cu")
		(net "SMB_PEHPCPU1_STBY_LVC3_SDA")
	)
	(via
		(at 399.47342 -59.926474)
		(size 0.508)
		(drill 0.254)
		(layers "F.Cu" "B.Cu")
		(net "SMB_PEHPCPU1_STBY_LVC3_SDA")
	)
	(via
		(at 116.05514 -158.32328)
		(size 0.508)
		(drill 0.254)
		(layers "F.Cu" "B.Cu")
		(net "SMB_PEHPCPU1_STBY_LVC3_SDA")
	)
	(via
		(at 338.9376 -74.1807)
		(size 0.508)
		(drill 0.254)
		(layers "F.Cu" "B.Cu")
		(net "SMB_PEHPCPU1_STBY_LVC3_SDA")
	)
	(via
		(at 409.890214 -35.734752)
		(size 0.4572)
		(drill 0.2032)
		(layers "F.Cu" "B.Cu")
		(net "SMB_PEHPCPU1_STBY_LVC3_SDA")
	)
	(via
		(at 17.139158 -121.39676)
		(size 0.508)
		(drill 0.254)
		(layers "F.Cu" "B.Cu")
		(net "SMB_PEHPCPU1_STBY_LVC3_SDA")
	)
	(segment
		(start -4.277614 -122.993912)
		(end -2.966212 -122.993912)
		(width 0.10795)
		(layer "B.Cu")
		(net "SMB_PEHPCPU1_STBY_LVC3_SDA")
	)
	(segment
		(start -5.024882 -122.246644)
		(end -4.277614 -122.993912)
		(width 0.10795)
		(layer "B.Cu")
		(net "SMB_PEHPCPU1_STBY_LVC3_SDA")
	)
	(segment
		(start -2.966212 -122.993912)
		(end -2.33426 -122.36196)
		(width 0.10795)
		(layer "B.Cu")
		(net "SMB_PEHPCPU1_STBY_LVC3_SDA")
	)
	(segment
		(start 180.630576 -156.533596)
		(end 180.721 -156.533596)
		(width 0.089408)
		(layer "In2.Cu")
		(net "SMB_PEHPCPU1_STBY_LVC3_SDA")
	)
	(segment
		(start 177.322988 -150.813008)
		(end 179.920392 -153.410412)
		(width 0.089408)
		(layer "In2.Cu")
		(net "SMB_PEHPCPU1_STBY_LVC3_SDA")
	)
	(segment
		(start 179.920392 -153.410412)
		(end 179.920392 -155.823412)
		(width 0.089408)
		(layer "In2.Cu")
		(net "SMB_PEHPCPU1_STBY_LVC3_SDA")
	)
	(segment
		(start 165.78326 -156.4513)
		(end 165.78326 -151.69134)
		(width 0.089408)
		(layer "In2.Cu")
		(net "SMB_PEHPCPU1_STBY_LVC3_SDA")
	)
	(segment
		(start 156.900626 -158.50108)
		(end 163.73348 -158.50108)
		(width 0.089408)
		(layer "In2.Cu")
		(net "SMB_PEHPCPU1_STBY_LVC3_SDA")
	)
	(segment
		(start 156.444442 -158.044896)
		(end 156.900626 -158.50108)
		(width 0.089408)
		(layer "In2.Cu")
		(net "SMB_PEHPCPU1_STBY_LVC3_SDA")
	)
	(segment
		(start 170.210988 -150.813008)
		(end 177.322988 -150.813008)
		(width 0.089408)
		(layer "In2.Cu")
		(net "SMB_PEHPCPU1_STBY_LVC3_SDA")
	)
	(segment
		(start 116.05514 -158.32328)
		(end 116.333524 -158.044896)
		(width 0.089408)
		(layer "In2.Cu")
		(net "SMB_PEHPCPU1_STBY_LVC3_SDA")
	)
	(segment
		(start 167.118792 -150.355808)
		(end 169.753788 -150.355808)
		(width 0.089408)
		(layer "In2.Cu")
		(net "SMB_PEHPCPU1_STBY_LVC3_SDA")
	)
	(segment
		(start 179.920392 -155.823412)
		(end 180.630576 -156.533596)
		(width 0.089408)
		(layer "In2.Cu")
		(net "SMB_PEHPCPU1_STBY_LVC3_SDA")
	)
	(segment
		(start 116.333524 -158.044896)
		(end 156.444442 -158.044896)
		(width 0.089408)
		(layer "In2.Cu")
		(net "SMB_PEHPCPU1_STBY_LVC3_SDA")
	)
	(segment
		(start 169.753788 -150.355808)
		(end 170.210988 -150.813008)
		(width 0.089408)
		(layer "In2.Cu")
		(net "SMB_PEHPCPU1_STBY_LVC3_SDA")
	)
	(segment
		(start 163.73348 -158.50108)
		(end 165.78326 -156.4513)
		(width 0.089408)
		(layer "In2.Cu")
		(net "SMB_PEHPCPU1_STBY_LVC3_SDA")
	)
	(segment
		(start 165.78326 -151.69134)
		(end 167.118792 -150.355808)
		(width 0.089408)
		(layer "In2.Cu")
		(net "SMB_PEHPCPU1_STBY_LVC3_SDA")
	)
	(segment
		(start 337.616546 -75.501754)
		(end 338.9376 -74.1807)
		(width 0.089408)
		(layer "In4.Cu")
		(net "SMB_PEHPCPU1_STBY_LVC3_SDA")
	)
	(segment
		(start 331.115162 -124.749814)
		(end 330.324968 -123.95962)
		(width 0.089408)
		(layer "In4.Cu")
		(net "SMB_PEHPCPU1_STBY_LVC3_SDA")
	)
	(segment
		(start 329.819 -157.251654)
		(end 329.819 -153.78938)
		(width 0.089408)
		(layer "In4.Cu")
		(net "SMB_PEHPCPU1_STBY_LVC3_SDA")
	)
	(segment
		(start 328.043794 -91.92006)
		(end 333.76743 -86.196424)
		(width 0.089408)
		(layer "In4.Cu")
		(net "SMB_PEHPCPU1_STBY_LVC3_SDA")
	)
	(segment
		(start 265.234928 -157.608778)
		(end 280.450798 -157.608778)
		(width 0.089408)
		(layer "In4.Cu")
		(net "SMB_PEHPCPU1_STBY_LVC3_SDA")
	)
	(segment
		(start 330.117704 -149.269704)
		(end 329.419458 -148.571458)
		(width 0.089408)
		(layer "In4.Cu")
		(net "SMB_PEHPCPU1_STBY_LVC3_SDA")
	)
	(segment
		(start 186.781186 -156.025596)
		(end 188.689996 -157.934406)
		(width 0.089408)
		(layer "In4.Cu")
		(net "SMB_PEHPCPU1_STBY_LVC3_SDA")
	)
	(segment
		(start 188.689996 -157.934406)
		(end 264.9093 -157.934406)
		(width 0.089408)
		(layer "In4.Cu")
		(net "SMB_PEHPCPU1_STBY_LVC3_SDA")
	)
	(segment
		(start 336.752692 -78.776576)
		(end 337.616546 -77.912722)
		(width 0.089408)
		(layer "In4.Cu")
		(net "SMB_PEHPCPU1_STBY_LVC3_SDA")
	)
	(segment
		(start 180.721 -156.533596)
		(end 181.229 -156.025596)
		(width 0.089408)
		(layer "In4.Cu")
		(net "SMB_PEHPCPU1_STBY_LVC3_SDA")
	)
	(segment
		(start 16.45666 -122.22988)
		(end 16.9672 -122.74042)
		(width 0.089408)
		(layer "In4.Cu")
		(net "SMB_PEHPCPU1_STBY_LVC3_SDA")
	)
	(segment
		(start 334.479392 -131.573016)
		(end 334.479392 -129.432812)
		(width 0.089408)
		(layer "In4.Cu")
		(net "SMB_PEHPCPU1_STBY_LVC3_SDA")
	)
	(segment
		(start 280.450798 -157.608778)
		(end 280.905458 -158.063438)
		(width 0.089408)
		(layer "In4.Cu")
		(net "SMB_PEHPCPU1_STBY_LVC3_SDA")
	)
	(segment
		(start 17.139158 -121.39676)
		(end 16.82242 -121.39676)
		(width 0.089408)
		(layer "In4.Cu")
		(net "SMB_PEHPCPU1_STBY_LVC3_SDA")
	)
	(segment
		(start 333.8068 -132.245608)
		(end 334.479392 -131.573016)
		(width 0.089408)
		(layer "In4.Cu")
		(net "SMB_PEHPCPU1_STBY_LVC3_SDA")
	)
	(segment
		(start 332.413356 -139.097258)
		(end 333.39278 -138.117834)
		(width 0.089408)
		(layer "In4.Cu")
		(net "SMB_PEHPCPU1_STBY_LVC3_SDA")
	)
	(segment
		(start 26.28392 -125.73508)
		(end 26.28392 -154.18562)
		(width 0.089408)
		(layer "In4.Cu")
		(net "SMB_PEHPCPU1_STBY_LVC3_SDA")
	)
	(segment
		(start 16.82242 -121.39676)
		(end 16.45666 -121.76252)
		(width 0.089408)
		(layer "In4.Cu")
		(net "SMB_PEHPCPU1_STBY_LVC3_SDA")
	)
	(segment
		(start 333.76743 -84.626958)
		(end 336.752692 -81.633314)
		(width 0.089408)
		(layer "In4.Cu")
		(net "SMB_PEHPCPU1_STBY_LVC3_SDA")
	)
	(segment
		(start 333.76743 -86.196424)
		(end 333.76743 -84.626958)
		(width 0.089408)
		(layer "In4.Cu")
		(net "SMB_PEHPCPU1_STBY_LVC3_SDA")
	)
	(segment
		(start 333.39278 -136.55802)
		(end 333.8068 -136.144)
		(width 0.089408)
		(layer "In4.Cu")
		(net "SMB_PEHPCPU1_STBY_LVC3_SDA")
	)
	(segment
		(start 26.28392 -154.18562)
		(end 29.30144 -157.20314)
		(width 0.089408)
		(layer "In4.Cu")
		(net "SMB_PEHPCPU1_STBY_LVC3_SDA")
	)
	(segment
		(start 333.8068 -136.144)
		(end 333.8068 -132.245608)
		(width 0.089408)
		(layer "In4.Cu")
		(net "SMB_PEHPCPU1_STBY_LVC3_SDA")
	)
	(segment
		(start 330.14285 -139.097258)
		(end 332.413356 -139.097258)
		(width 0.089408)
		(layer "In4.Cu")
		(net "SMB_PEHPCPU1_STBY_LVC3_SDA")
	)
	(segment
		(start 329.007216 -158.063438)
		(end 329.819 -157.251654)
		(width 0.089408)
		(layer "In4.Cu")
		(net "SMB_PEHPCPU1_STBY_LVC3_SDA")
	)
	(segment
		(start 330.324968 -123.95962)
		(end 329.894438 -123.95962)
		(width 0.089408)
		(layer "In4.Cu")
		(net "SMB_PEHPCPU1_STBY_LVC3_SDA")
	)
	(segment
		(start 329.894184 -123.959874)
		(end 329.736196 -123.959874)
		(width 0.089408)
		(layer "In4.Cu")
		(net "SMB_PEHPCPU1_STBY_LVC3_SDA")
	)
	(segment
		(start 329.419458 -139.82065)
		(end 330.14285 -139.097258)
		(width 0.089408)
		(layer "In4.Cu")
		(net "SMB_PEHPCPU1_STBY_LVC3_SDA")
	)
	(segment
		(start 336.752692 -81.633314)
		(end 336.752692 -78.776576)
		(width 0.089408)
		(layer "In4.Cu")
		(net "SMB_PEHPCPU1_STBY_LVC3_SDA")
	)
	(segment
		(start 330.117704 -153.490676)
		(end 330.117704 -149.269704)
		(width 0.089408)
		(layer "In4.Cu")
		(net "SMB_PEHPCPU1_STBY_LVC3_SDA")
	)
	(segment
		(start 23.28926 -122.74042)
		(end 26.28392 -125.73508)
		(width 0.089408)
		(layer "In4.Cu")
		(net "SMB_PEHPCPU1_STBY_LVC3_SDA")
	)
	(segment
		(start 331.115162 -126.068582)
		(end 331.115162 -124.749814)
		(width 0.089408)
		(layer "In4.Cu")
		(net "SMB_PEHPCPU1_STBY_LVC3_SDA")
	)
	(segment
		(start 181.229 -156.025596)
		(end 186.781186 -156.025596)
		(width 0.089408)
		(layer "In4.Cu")
		(net "SMB_PEHPCPU1_STBY_LVC3_SDA")
	)
	(segment
		(start 86.93912 -157.20314)
		(end 87.574882 -156.567378)
		(width 0.089408)
		(layer "In4.Cu")
		(net "SMB_PEHPCPU1_STBY_LVC3_SDA")
	)
	(segment
		(start 115.61572 -157.7086)
		(end 115.61572 -157.88386)
		(width 0.089408)
		(layer "In4.Cu")
		(net "SMB_PEHPCPU1_STBY_LVC3_SDA")
	)
	(segment
		(start 337.616546 -77.912722)
		(end 337.616546 -75.501754)
		(width 0.089408)
		(layer "In4.Cu")
		(net "SMB_PEHPCPU1_STBY_LVC3_SDA")
	)
	(segment
		(start 329.736196 -123.959874)
		(end 328.956924 -123.180602)
		(width 0.089408)
		(layer "In4.Cu")
		(net "SMB_PEHPCPU1_STBY_LVC3_SDA")
	)
	(segment
		(start 333.39278 -138.117834)
		(end 333.39278 -136.55802)
		(width 0.089408)
		(layer "In4.Cu")
		(net "SMB_PEHPCPU1_STBY_LVC3_SDA")
	)
	(segment
		(start 264.9093 -157.934406)
		(end 265.234928 -157.608778)
		(width 0.089408)
		(layer "In4.Cu")
		(net "SMB_PEHPCPU1_STBY_LVC3_SDA")
	)
	(segment
		(start 29.30144 -157.20314)
		(end 86.93912 -157.20314)
		(width 0.089408)
		(layer "In4.Cu")
		(net "SMB_PEHPCPU1_STBY_LVC3_SDA")
	)
	(segment
		(start 328.956924 -112.608106)
		(end 328.043794 -111.694976)
		(width 0.089408)
		(layer "In4.Cu")
		(net "SMB_PEHPCPU1_STBY_LVC3_SDA")
	)
	(segment
		(start 334.479392 -129.432812)
		(end 331.115162 -126.068582)
		(width 0.089408)
		(layer "In4.Cu")
		(net "SMB_PEHPCPU1_STBY_LVC3_SDA")
	)
	(segment
		(start 329.819 -153.78938)
		(end 330.117704 -153.490676)
		(width 0.089408)
		(layer "In4.Cu")
		(net "SMB_PEHPCPU1_STBY_LVC3_SDA")
	)
	(segment
		(start 114.474498 -156.567378)
		(end 115.61572 -157.7086)
		(width 0.089408)
		(layer "In4.Cu")
		(net "SMB_PEHPCPU1_STBY_LVC3_SDA")
	)
	(segment
		(start 87.574882 -156.567378)
		(end 114.474498 -156.567378)
		(width 0.089408)
		(layer "In4.Cu")
		(net "SMB_PEHPCPU1_STBY_LVC3_SDA")
	)
	(segment
		(start 328.043794 -111.694976)
		(end 328.043794 -91.92006)
		(width 0.089408)
		(layer "In4.Cu")
		(net "SMB_PEHPCPU1_STBY_LVC3_SDA")
	)
	(segment
		(start 329.419458 -148.571458)
		(end 329.419458 -139.82065)
		(width 0.089408)
		(layer "In4.Cu")
		(net "SMB_PEHPCPU1_STBY_LVC3_SDA")
	)
	(segment
		(start 16.45666 -121.76252)
		(end 16.45666 -122.22988)
		(width 0.089408)
		(layer "In4.Cu")
		(net "SMB_PEHPCPU1_STBY_LVC3_SDA")
	)
	(segment
		(start 280.905458 -158.063438)
		(end 329.007216 -158.063438)
		(width 0.089408)
		(layer "In4.Cu")
		(net "SMB_PEHPCPU1_STBY_LVC3_SDA")
	)
	(segment
		(start 329.894438 -123.95962)
		(end 329.894184 -123.959874)
		(width 0.089408)
		(layer "In4.Cu")
		(net "SMB_PEHPCPU1_STBY_LVC3_SDA")
	)
	(segment
		(start 16.9672 -122.74042)
		(end 23.28926 -122.74042)
		(width 0.089408)
		(layer "In4.Cu")
		(net "SMB_PEHPCPU1_STBY_LVC3_SDA")
	)
	(segment
		(start 328.956924 -123.180602)
		(end 328.956924 -112.608106)
		(width 0.089408)
		(layer "In4.Cu")
		(net "SMB_PEHPCPU1_STBY_LVC3_SDA")
	)
	(segment
		(start 115.61572 -157.88386)
		(end 116.05514 -158.32328)
		(width 0.089408)
		(layer "In4.Cu")
		(net "SMB_PEHPCPU1_STBY_LVC3_SDA")
	)
	(segment
		(start -5.471668 -96.177608)
		(end -5.471668 -120.919748)
		(width 0.089408)
		(layer "In9.Cu")
		(net "SMB_PEHPCPU1_STBY_LVC3_SDA")
	)
	(segment
		(start 401.6883 -39.675562)
		(end 401.6883 -43.113706)
		(width 0.089408)
		(layer "In9.Cu")
		(net "SMB_PEHPCPU1_STBY_LVC3_SDA")
	)
	(segment
		(start 17.139158 -121.39676)
		(end 17.10436 -121.431558)
		(width 0.089408)
		(layer "In9.Cu")
		(net "SMB_PEHPCPU1_STBY_LVC3_SDA")
	)
	(segment
		(start 5.63245 -121.159778)
		(end 5.17017 -121.622058)
		(width 0.089408)
		(layer "In9.Cu")
		(net "SMB_PEHPCPU1_STBY_LVC3_SDA")
	)
	(segment
		(start 409.245816 -36.109402)
		(end 409.245562 -36.109656)
		(width 0.089408)
		(layer "In9.Cu")
		(net "SMB_PEHPCPU1_STBY_LVC3_SDA")
	)
	(segment
		(start 408.934412 -36.109402)
		(end 408.72537 -36.109402)
		(width 0.089408)
		(layer "In9.Cu")
		(net "SMB_PEHPCPU1_STBY_LVC3_SDA")
	)
	(segment
		(start 399.47342 -58.395108)
		(end 399.47342 -59.926474)
		(width 0.089408)
		(layer "In9.Cu")
		(net "SMB_PEHPCPU1_STBY_LVC3_SDA")
	)
	(segment
		(start 5.17017 -121.622058)
		(end 2.112772 -121.622058)
		(width 0.089408)
		(layer "In9.Cu")
		(net "SMB_PEHPCPU1_STBY_LVC3_SDA")
	)
	(segment
		(start 14.918944 -121.159778)
		(end 5.63245 -121.159778)
		(width 0.089408)
		(layer "In9.Cu")
		(net "SMB_PEHPCPU1_STBY_LVC3_SDA")
	)
	(segment
		(start 2.112772 -121.622058)
		(end 0.954532 -120.463818)
		(width 0.089408)
		(layer "In9.Cu")
		(net "SMB_PEHPCPU1_STBY_LVC3_SDA")
	)
	(segment
		(start -2.599944 -94.76994)
		(end -2.599944 -94.770194)
		(width 0.089408)
		(layer "In9.Cu")
		(net "SMB_PEHPCPU1_STBY_LVC3_SDA")
	)
	(segment
		(start -5.471668 -120.919748)
		(end -5.430012 -120.961404)
		(width 0.089408)
		(layer "In9.Cu")
		(net "SMB_PEHPCPU1_STBY_LVC3_SDA")
	)
	(segment
		(start 408.340306 -35.724338)
		(end 405.639524 -35.724338)
		(width 0.089408)
		(layer "In9.Cu")
		(net "SMB_PEHPCPU1_STBY_LVC3_SDA")
	)
	(segment
		(start 0.954532 -120.463818)
		(end -1.931924 -120.463818)
		(width 0.089408)
		(layer "In9.Cu")
		(net "SMB_PEHPCPU1_STBY_LVC3_SDA")
	)
	(segment
		(start -3.085846 -121.61774)
		(end -3.79984 -121.61774)
		(width 0.089408)
		(layer "In9.Cu")
		(net "SMB_PEHPCPU1_STBY_LVC3_SDA")
	)
	(segment
		(start 401.6883 -43.113706)
		(end 400.956018 -43.845988)
		(width 0.089408)
		(layer "In9.Cu")
		(net "SMB_PEHPCPU1_STBY_LVC3_SDA")
	)
	(segment
		(start 400.956018 -43.845988)
		(end 400.956018 -44.925996)
		(width 0.089408)
		(layer "In9.Cu")
		(net "SMB_PEHPCPU1_STBY_LVC3_SDA")
	)
	(segment
		(start -4.909058 -122.13082)
		(end -5.024882 -122.246644)
		(width 0.089408)
		(layer "In9.Cu")
		(net "SMB_PEHPCPU1_STBY_LVC3_SDA")
	)
	(segment
		(start 398.586706 -47.295308)
		(end 398.586706 -57.508394)
		(width 0.089408)
		(layer "In9.Cu")
		(net "SMB_PEHPCPU1_STBY_LVC3_SDA")
	)
	(segment
		(start 405.639524 -35.724338)
		(end 401.6883 -39.675562)
		(width 0.089408)
		(layer "In9.Cu")
		(net "SMB_PEHPCPU1_STBY_LVC3_SDA")
	)
	(segment
		(start -4.64566 -95.3516)
		(end -5.471668 -96.177608)
		(width 0.089408)
		(layer "In9.Cu")
		(net "SMB_PEHPCPU1_STBY_LVC3_SDA")
	)
	(segment
		(start 408.72537 -36.109402)
		(end 408.340306 -35.724338)
		(width 0.089408)
		(layer "In9.Cu")
		(net "SMB_PEHPCPU1_STBY_LVC3_SDA")
	)
	(segment
		(start 398.586706 -57.508394)
		(end 399.47342 -58.395108)
		(width 0.089408)
		(layer "In9.Cu")
		(net "SMB_PEHPCPU1_STBY_LVC3_SDA")
	)
	(segment
		(start 409.890214 -35.734752)
		(end 409.515564 -36.109402)
		(width 0.089408)
		(layer "In9.Cu")
		(net "SMB_PEHPCPU1_STBY_LVC3_SDA")
	)
	(segment
		(start 408.934666 -36.109656)
		(end 408.934412 -36.109402)
		(width 0.089408)
		(layer "In9.Cu")
		(net "SMB_PEHPCPU1_STBY_LVC3_SDA")
	)
	(segment
		(start -4.31292 -122.13082)
		(end -4.909058 -122.13082)
		(width 0.089408)
		(layer "In9.Cu")
		(net "SMB_PEHPCPU1_STBY_LVC3_SDA")
	)
	(segment
		(start -5.430012 -121.841514)
		(end -5.024882 -122.246644)
		(width 0.089408)
		(layer "In9.Cu")
		(net "SMB_PEHPCPU1_STBY_LVC3_SDA")
	)
	(segment
		(start -5.430012 -120.961404)
		(end -5.430012 -121.841514)
		(width 0.089408)
		(layer "In9.Cu")
		(net "SMB_PEHPCPU1_STBY_LVC3_SDA")
	)
	(segment
		(start 409.245562 -36.109656)
		(end 408.934666 -36.109656)
		(width 0.089408)
		(layer "In9.Cu")
		(net "SMB_PEHPCPU1_STBY_LVC3_SDA")
	)
	(segment
		(start -2.599944 -94.770194)
		(end -3.18135 -95.3516)
		(width 0.089408)
		(layer "In9.Cu")
		(net "SMB_PEHPCPU1_STBY_LVC3_SDA")
	)
	(segment
		(start -1.931924 -120.463818)
		(end -3.085846 -121.61774)
		(width 0.089408)
		(layer "In9.Cu")
		(net "SMB_PEHPCPU1_STBY_LVC3_SDA")
	)
	(segment
		(start 15.190724 -121.431558)
		(end 14.918944 -121.159778)
		(width 0.089408)
		(layer "In9.Cu")
		(net "SMB_PEHPCPU1_STBY_LVC3_SDA")
	)
	(segment
		(start -3.79984 -121.61774)
		(end -4.31292 -122.13082)
		(width 0.089408)
		(layer "In9.Cu")
		(net "SMB_PEHPCPU1_STBY_LVC3_SDA")
	)
	(segment
		(start 17.10436 -121.431558)
		(end 15.190724 -121.431558)
		(width 0.089408)
		(layer "In9.Cu")
		(net "SMB_PEHPCPU1_STBY_LVC3_SDA")
	)
	(segment
		(start -3.18135 -95.3516)
		(end -4.64566 -95.3516)
		(width 0.089408)
		(layer "In9.Cu")
		(net "SMB_PEHPCPU1_STBY_LVC3_SDA")
	)
	(segment
		(start 400.956018 -44.925996)
		(end 398.586706 -47.295308)
		(width 0.089408)
		(layer "In9.Cu")
		(net "SMB_PEHPCPU1_STBY_LVC3_SDA")
	)
	(segment
		(start 409.515564 -36.109402)
		(end 409.245816 -36.109402)
		(width 0.089408)
		(layer "In9.Cu")
		(net "SMB_PEHPCPU1_STBY_LVC3_SDA")
	)
	(segment
		(start 338.769198 -72.189594)
		(end 339.542628 -71.416164)
		(width 0.10795)
		(layer "F.Cu")
		(net "SMB_PEHPCPU1_STBY_LVC3_SCL")
	)
	(segment
		(start 391.983976 -57.661302)
		(end 389.399526 -60.245752)
		(width 0.10795)
		(layer "F.Cu")
		(net "SMB_PEHPCPU1_STBY_LVC3_SCL")
	)
	(segment
		(start 365.167926 -61.4172)
		(end 364.8202 -61.4172)
		(width 0.10795)
		(layer "F.Cu")
		(net "SMB_PEHPCPU1_STBY_LVC3_SCL")
	)
	(segment
		(start 339.6488 -74.171048)
		(end 338.769198 -73.291446)
		(width 0.10795)
		(layer "F.Cu")
		(net "SMB_PEHPCPU1_STBY_LVC3_SCL")
	)
	(segment
		(start 366.7506 -62.999874)
		(end 365.167926 -61.4172)
		(width 0.10795)
		(layer "F.Cu")
		(net "SMB_PEHPCPU1_STBY_LVC3_SCL")
	)
	(segment
		(start 359.32618 -69.850762)
		(end 358.539288 -69.850762)
		(width 0.10795)
		(layer "F.Cu")
		(net "SMB_PEHPCPU1_STBY_LVC3_SCL")
	)
	(segment
		(start 363.4867 -65.690242)
		(end 359.32618 -69.850762)
		(width 0.10795)
		(layer "F.Cu")
		(net "SMB_PEHPCPU1_STBY_LVC3_SCL")
	)
	(segment
		(start 363.855 -62.3824)
		(end 363.855 -64.0334)
		(width 0.10795)
		(layer "F.Cu")
		(net "SMB_PEHPCPU1_STBY_LVC3_SCL")
	)
	(segment
		(start 341.687658 -69.885052)
		(end 340.616286 -70.956424)
		(width 0.10795)
		(layer "F.Cu")
		(net "SMB_PEHPCPU1_STBY_LVC3_SCL")
	)
	(segment
		(start 377.715272 -60.566046)
		(end 375.281444 -62.999874)
		(width 0.10795)
		(layer "F.Cu")
		(net "SMB_PEHPCPU1_STBY_LVC3_SCL")
	)
	(segment
		(start 396.848584 -57.661302)
		(end 391.983976 -57.661302)
		(width 0.10795)
		(layer "F.Cu")
		(net "SMB_PEHPCPU1_STBY_LVC3_SCL")
	)
	(segment
		(start 389.399526 -60.245752)
		(end 387.407658 -60.245752)
		(width 0.10795)
		(layer "F.Cu")
		(net "SMB_PEHPCPU1_STBY_LVC3_SCL")
	)
	(segment
		(start 387.407658 -60.245752)
		(end 386.859526 -59.69762)
		(width 0.10795)
		(layer "F.Cu")
		(net "SMB_PEHPCPU1_STBY_LVC3_SCL")
	)
	(segment
		(start 338.769198 -73.291446)
		(end 338.769198 -72.189594)
		(width 0.10795)
		(layer "F.Cu")
		(net "SMB_PEHPCPU1_STBY_LVC3_SCL")
	)
	(segment
		(start 358.539288 -69.850762)
		(end 357.605584 -68.917058)
		(width 0.10795)
		(layer "F.Cu")
		(net "SMB_PEHPCPU1_STBY_LVC3_SCL")
	)
	(segment
		(start 386.859526 -59.69762)
		(end 386.17906 -59.69762)
		(width 0.10795)
		(layer "F.Cu")
		(net "SMB_PEHPCPU1_STBY_LVC3_SCL")
	)
	(segment
		(start 363.855 -64.0334)
		(end 363.4867 -64.4017)
		(width 0.10795)
		(layer "F.Cu")
		(net "SMB_PEHPCPU1_STBY_LVC3_SCL")
	)
	(segment
		(start 363.4867 -64.4017)
		(end 363.4867 -65.690242)
		(width 0.10795)
		(layer "F.Cu")
		(net "SMB_PEHPCPU1_STBY_LVC3_SCL")
	)
	(segment
		(start 375.281444 -62.999874)
		(end 366.7506 -62.999874)
		(width 0.10795)
		(layer "F.Cu")
		(net "SMB_PEHPCPU1_STBY_LVC3_SCL")
	)
	(segment
		(start 382.207008 -60.163964)
		(end 381.804926 -60.566046)
		(width 0.10795)
		(layer "F.Cu")
		(net "SMB_PEHPCPU1_STBY_LVC3_SCL")
	)
	(segment
		(start 342.415876 -69.885052)
		(end 341.687658 -69.885052)
		(width 0.10795)
		(layer "F.Cu")
		(net "SMB_PEHPCPU1_STBY_LVC3_SCL")
	)
	(segment
		(start 409.490164 -33.734756)
		(end 409.090114 -34.134806)
		(width 0.10795)
		(layer "F.Cu")
		(net "SMB_PEHPCPU1_STBY_LVC3_SCL")
	)
	(segment
		(start 381.804926 -60.566046)
		(end 377.715272 -60.566046)
		(width 0.10795)
		(layer "F.Cu")
		(net "SMB_PEHPCPU1_STBY_LVC3_SCL")
	)
	(segment
		(start 339.542628 -71.416164)
		(end 340.156546 -71.416164)
		(width 0.10795)
		(layer "F.Cu")
		(net "SMB_PEHPCPU1_STBY_LVC3_SCL")
	)
	(segment
		(start 386.17906 -59.69762)
		(end 385.712716 -60.163964)
		(width 0.10795)
		(layer "F.Cu")
		(net "SMB_PEHPCPU1_STBY_LVC3_SCL")
	)
	(segment
		(start 350.055434 -68.917058)
		(end 349.675704 -68.537328)
		(width 0.10795)
		(layer "F.Cu")
		(net "SMB_PEHPCPU1_STBY_LVC3_SCL")
	)
	(segment
		(start 349.675704 -68.537328)
		(end 343.7636 -68.537328)
		(width 0.10795)
		(layer "F.Cu")
		(net "SMB_PEHPCPU1_STBY_LVC3_SCL")
	)
	(segment
		(start 340.156546 -71.416164)
		(end 340.616286 -70.956424)
		(width 0.10795)
		(layer "F.Cu")
		(net "SMB_PEHPCPU1_STBY_LVC3_SCL")
	)
	(segment
		(start 398.849088 -59.661806)
		(end 396.848584 -57.661302)
		(width 0.10795)
		(layer "F.Cu")
		(net "SMB_PEHPCPU1_STBY_LVC3_SCL")
	)
	(segment
		(start 357.605584 -68.917058)
		(end 350.055434 -68.917058)
		(width 0.10795)
		(layer "F.Cu")
		(net "SMB_PEHPCPU1_STBY_LVC3_SCL")
	)
	(segment
		(start 343.7636 -68.537328)
		(end 342.415876 -69.885052)
		(width 0.10795)
		(layer "F.Cu")
		(net "SMB_PEHPCPU1_STBY_LVC3_SCL")
	)
	(segment
		(start 364.8202 -61.4172)
		(end 363.855 -62.3824)
		(width 0.10795)
		(layer "F.Cu")
		(net "SMB_PEHPCPU1_STBY_LVC3_SCL")
	)
	(segment
		(start 385.712716 -60.163964)
		(end 382.207008 -60.163964)
		(width 0.10795)
		(layer "F.Cu")
		(net "SMB_PEHPCPU1_STBY_LVC3_SCL")
	)
	(via
		(at 409.090114 -34.134806)
		(size 0.4572)
		(drill 0.2032)
		(layers "F.Cu" "B.Cu")
		(net "SMB_PEHPCPU1_STBY_LVC3_SCL")
	)
	(via
		(at 181.229 -156.972)
		(size 0.508)
		(drill 0.254)
		(layers "F.Cu" "B.Cu")
		(net "SMB_PEHPCPU1_STBY_LVC3_SCL")
	)
	(via
		(at 16.6243 -120.80494)
		(size 0.508)
		(drill 0.254)
		(layers "F.Cu" "B.Cu")
		(net "SMB_PEHPCPU1_STBY_LVC3_SCL")
	)
	(via
		(at 340.616286 -70.956424)
		(size 0.762)
		(drill 0.381)
		(layers "F.Cu" "B.Cu")
		(net "SMB_PEHPCPU1_STBY_LVC3_SCL")
	)
	(via
		(at 398.849088 -59.661806)
		(size 0.508)
		(drill 0.254)
		(layers "F.Cu" "B.Cu")
		(net "SMB_PEHPCPU1_STBY_LVC3_SCL")
	)
	(via
		(at -5.029708 -121.091452)
		(size 0.508)
		(drill 0.254)
		(layers "F.Cu" "B.Cu")
		(net "SMB_PEHPCPU1_STBY_LVC3_SCL")
	)
	(via
		(at 115.1255 -158.32328)
		(size 0.508)
		(drill 0.254)
		(layers "F.Cu" "B.Cu")
		(net "SMB_PEHPCPU1_STBY_LVC3_SCL")
	)
	(via
		(at 339.6488 -74.171048)
		(size 0.508)
		(drill 0.254)
		(layers "F.Cu" "B.Cu")
		(net "SMB_PEHPCPU1_STBY_LVC3_SCL")
	)
	(segment
		(start -5.029708 -121.091452)
		(end -5.029708 -121.635012)
		(width 0.10795)
		(layer "B.Cu")
		(net "SMB_PEHPCPU1_STBY_LVC3_SCL")
	)
	(segment
		(start -5.029708 -121.635012)
		(end -4.30276 -122.36196)
		(width 0.10795)
		(layer "B.Cu")
		(net "SMB_PEHPCPU1_STBY_LVC3_SCL")
	)
	(segment
		(start -4.30276 -122.36196)
		(end -3.22326 -122.36196)
		(width 0.10795)
		(layer "B.Cu")
		(net "SMB_PEHPCPU1_STBY_LVC3_SCL")
	)
	(segment
		(start 166.99738 -150.0632)
		(end 169.8752 -150.0632)
		(width 0.089408)
		(layer "In2.Cu")
		(net "SMB_PEHPCPU1_STBY_LVC3_SCL")
	)
	(segment
		(start 180.213 -153.289)
		(end 180.213 -155.321)
		(width 0.089408)
		(layer "In2.Cu")
		(net "SMB_PEHPCPU1_STBY_LVC3_SCL")
	)
	(segment
		(start 177.4444 -150.5204)
		(end 180.213 -153.289)
		(width 0.089408)
		(layer "In2.Cu")
		(net "SMB_PEHPCPU1_STBY_LVC3_SCL")
	)
	(segment
		(start 165.424866 -156.395674)
		(end 165.424866 -151.635714)
		(width 0.089408)
		(layer "In2.Cu")
		(net "SMB_PEHPCPU1_STBY_LVC3_SCL")
	)
	(segment
		(start 115.16614 -158.32328)
		(end 115.635532 -157.853888)
		(width 0.089408)
		(layer "In2.Cu")
		(net "SMB_PEHPCPU1_STBY_LVC3_SCL")
	)
	(segment
		(start 169.8752 -150.0632)
		(end 170.3324 -150.5204)
		(width 0.089408)
		(layer "In2.Cu")
		(net "SMB_PEHPCPU1_STBY_LVC3_SCL")
	)
	(segment
		(start 156.54401 -157.853888)
		(end 156.898594 -158.208472)
		(width 0.089408)
		(layer "In2.Cu")
		(net "SMB_PEHPCPU1_STBY_LVC3_SCL")
	)
	(segment
		(start 180.213 -155.321)
		(end 181.229 -156.337)
		(width 0.089408)
		(layer "In2.Cu")
		(net "SMB_PEHPCPU1_STBY_LVC3_SCL")
	)
	(segment
		(start 156.898594 -158.208472)
		(end 163.612068 -158.208472)
		(width 0.089408)
		(layer "In2.Cu")
		(net "SMB_PEHPCPU1_STBY_LVC3_SCL")
	)
	(segment
		(start 170.3324 -150.5204)
		(end 177.4444 -150.5204)
		(width 0.089408)
		(layer "In2.Cu")
		(net "SMB_PEHPCPU1_STBY_LVC3_SCL")
	)
	(segment
		(start 115.1255 -158.32328)
		(end 115.16614 -158.32328)
		(width 0.089408)
		(layer "In2.Cu")
		(net "SMB_PEHPCPU1_STBY_LVC3_SCL")
	)
	(segment
		(start 115.635532 -157.853888)
		(end 156.54401 -157.853888)
		(width 0.089408)
		(layer "In2.Cu")
		(net "SMB_PEHPCPU1_STBY_LVC3_SCL")
	)
	(segment
		(start 181.229 -156.337)
		(end 181.229 -156.972)
		(width 0.089408)
		(layer "In2.Cu")
		(net "SMB_PEHPCPU1_STBY_LVC3_SCL")
	)
	(segment
		(start 163.612068 -158.208472)
		(end 165.424866 -156.395674)
		(width 0.089408)
		(layer "In2.Cu")
		(net "SMB_PEHPCPU1_STBY_LVC3_SCL")
	)
	(segment
		(start 165.424866 -151.635714)
		(end 166.99738 -150.0632)
		(width 0.089408)
		(layer "In2.Cu")
		(net "SMB_PEHPCPU1_STBY_LVC3_SCL")
	)
	(segment
		(start 330.265024 -139.389866)
		(end 329.712066 -139.942824)
		(width 0.089408)
		(layer "In4.Cu")
		(net "SMB_PEHPCPU1_STBY_LVC3_SCL")
	)
	(segment
		(start 188.610748 -158.125414)
		(end 188.572394 -158.08706)
		(width 0.089408)
		(layer "In4.Cu")
		(net "SMB_PEHPCPU1_STBY_LVC3_SCL")
	)
	(segment
		(start 337.807554 -77.99197)
		(end 337.163918 -78.635606)
		(width 0.089408)
		(layer "In4.Cu")
		(net "SMB_PEHPCPU1_STBY_LVC3_SCL")
	)
	(segment
		(start 115.39728 -158.0515)
		(end 115.39728 -157.86354)
		(width 0.089408)
		(layer "In4.Cu")
		(net "SMB_PEHPCPU1_STBY_LVC3_SCL")
	)
	(segment
		(start 339.1535 -74.6633)
		(end 338.855558 -74.6633)
		(width 0.089408)
		(layer "In4.Cu")
		(net "SMB_PEHPCPU1_STBY_LVC3_SCL")
	)
	(segment
		(start 330.404216 -123.768612)
		(end 331.30617 -124.670566)
		(width 0.089408)
		(layer "In4.Cu")
		(net "SMB_PEHPCPU1_STBY_LVC3_SCL")
	)
	(segment
		(start 330.111608 -157.454092)
		(end 329.145138 -158.420562)
		(width 0.089408)
		(layer "In4.Cu")
		(net "SMB_PEHPCPU1_STBY_LVC3_SCL")
	)
	(segment
		(start 334.02016 -132.496052)
		(end 334.02016 -136.3218)
		(width 0.089408)
		(layer "In4.Cu")
		(net "SMB_PEHPCPU1_STBY_LVC3_SCL")
	)
	(segment
		(start 328.234802 -109.322616)
		(end 328.235056 -109.32287)
		(width 0.089408)
		(layer "In4.Cu")
		(net "SMB_PEHPCPU1_STBY_LVC3_SCL")
	)
	(segment
		(start 181.882796 -156.318204)
		(end 181.229 -156.972)
		(width 0.089408)
		(layer "In4.Cu")
		(net "SMB_PEHPCPU1_STBY_LVC3_SCL")
	)
	(segment
		(start 329.712066 -139.942824)
		(end 329.712066 -148.450046)
		(width 0.089408)
		(layer "In4.Cu")
		(net "SMB_PEHPCPU1_STBY_LVC3_SCL")
	)
	(segment
		(start 334.060038 -84.765388)
		(end 334.060038 -86.538562)
		(width 0.089408)
		(layer "In4.Cu")
		(net "SMB_PEHPCPU1_STBY_LVC3_SCL")
	)
	(segment
		(start 337.163918 -81.653126)
		(end 334.060038 -84.765388)
		(width 0.089408)
		(layer "In4.Cu")
		(net "SMB_PEHPCPU1_STBY_LVC3_SCL")
	)
	(segment
		(start 329.147932 -112.528858)
		(end 329.147932 -123.101354)
		(width 0.089408)
		(layer "In4.Cu")
		(net "SMB_PEHPCPU1_STBY_LVC3_SCL")
	)
	(segment
		(start 328.234802 -111.615728)
		(end 329.147932 -112.528858)
		(width 0.089408)
		(layer "In4.Cu")
		(net "SMB_PEHPCPU1_STBY_LVC3_SCL")
	)
	(segment
		(start 331.30617 -125.989334)
		(end 334.772 -129.455164)
		(width 0.089408)
		(layer "In4.Cu")
		(net "SMB_PEHPCPU1_STBY_LVC3_SCL")
	)
	(segment
		(start 26.020014 -125.844554)
		(end 23.179786 -123.004326)
		(width 0.089408)
		(layer "In4.Cu")
		(net "SMB_PEHPCPU1_STBY_LVC3_SCL")
	)
	(segment
		(start 329.147932 -123.101354)
		(end 329.81519 -123.768612)
		(width 0.089408)
		(layer "In4.Cu")
		(net "SMB_PEHPCPU1_STBY_LVC3_SCL")
	)
	(segment
		(start 333.70139 -136.64057)
		(end 333.70139 -138.223244)
		(width 0.089408)
		(layer "In4.Cu")
		(net "SMB_PEHPCPU1_STBY_LVC3_SCL")
	)
	(segment
		(start 334.772 -131.744212)
		(end 334.02016 -132.496052)
		(width 0.089408)
		(layer "In4.Cu")
		(net "SMB_PEHPCPU1_STBY_LVC3_SCL")
	)
	(segment
		(start 328.235056 -110.025942)
		(end 328.234802 -110.026196)
		(width 0.089408)
		(layer "In4.Cu")
		(net "SMB_PEHPCPU1_STBY_LVC3_SCL")
	)
	(segment
		(start 331.30617 -124.670566)
		(end 331.30617 -125.989334)
		(width 0.089408)
		(layer "In4.Cu")
		(net "SMB_PEHPCPU1_STBY_LVC3_SCL")
	)
	(segment
		(start 16.6243 -121.2215)
		(end 16.6243 -120.80494)
		(width 0.089408)
		(layer "In4.Cu")
		(net "SMB_PEHPCPU1_STBY_LVC3_SCL")
	)
	(segment
		(start 26.020014 -154.295094)
		(end 26.020014 -125.844554)
		(width 0.089408)
		(layer "In4.Cu")
		(net "SMB_PEHPCPU1_STBY_LVC3_SCL")
	)
	(segment
		(start 337.163918 -78.635606)
		(end 337.163918 -81.653126)
		(width 0.089408)
		(layer "In4.Cu")
		(net "SMB_PEHPCPU1_STBY_LVC3_SCL")
	)
	(segment
		(start 334.02016 -136.3218)
		(end 333.70139 -136.64057)
		(width 0.089408)
		(layer "In4.Cu")
		(net "SMB_PEHPCPU1_STBY_LVC3_SCL")
	)
	(segment
		(start 265.240008 -158.08706)
		(end 265.026902 -158.08706)
		(width 0.089408)
		(layer "In4.Cu")
		(net "SMB_PEHPCPU1_STBY_LVC3_SCL")
	)
	(segment
		(start 87.65413 -156.758386)
		(end 86.94547 -157.467046)
		(width 0.089408)
		(layer "In4.Cu")
		(net "SMB_PEHPCPU1_STBY_LVC3_SCL")
	)
	(segment
		(start 329.712066 -148.450046)
		(end 330.5302 -149.26818)
		(width 0.089408)
		(layer "In4.Cu")
		(net "SMB_PEHPCPU1_STBY_LVC3_SCL")
	)
	(segment
		(start 280.848562 -158.420562)
		(end 280.329386 -157.901386)
		(width 0.089408)
		(layer "In4.Cu")
		(net "SMB_PEHPCPU1_STBY_LVC3_SCL")
	)
	(segment
		(start 188.312806 -158.08706)
		(end 186.54395 -156.318204)
		(width 0.089408)
		(layer "In4.Cu")
		(net "SMB_PEHPCPU1_STBY_LVC3_SCL")
	)
	(segment
		(start 114.292126 -156.758386)
		(end 87.65413 -156.758386)
		(width 0.089408)
		(layer "In4.Cu")
		(net "SMB_PEHPCPU1_STBY_LVC3_SCL")
	)
	(segment
		(start 16.192754 -122.339354)
		(end 16.192754 -121.653046)
		(width 0.089408)
		(layer "In4.Cu")
		(net "SMB_PEHPCPU1_STBY_LVC3_SCL")
	)
	(segment
		(start 328.235056 -109.32287)
		(end 328.235056 -110.025942)
		(width 0.089408)
		(layer "In4.Cu")
		(net "SMB_PEHPCPU1_STBY_LVC3_SCL")
	)
	(segment
		(start 330.5302 -153.4922)
		(end 330.111608 -153.910792)
		(width 0.089408)
		(layer "In4.Cu")
		(net "SMB_PEHPCPU1_STBY_LVC3_SCL")
	)
	(segment
		(start 188.572394 -158.08706)
		(end 188.312806 -158.08706)
		(width 0.089408)
		(layer "In4.Cu")
		(net "SMB_PEHPCPU1_STBY_LVC3_SCL")
	)
	(segment
		(start 330.111608 -153.910792)
		(end 330.111608 -157.454092)
		(width 0.089408)
		(layer "In4.Cu")
		(net "SMB_PEHPCPU1_STBY_LVC3_SCL")
	)
	(segment
		(start 16.192754 -121.653046)
		(end 16.6243 -121.2215)
		(width 0.089408)
		(layer "In4.Cu")
		(net "SMB_PEHPCPU1_STBY_LVC3_SCL")
	)
	(segment
		(start 16.857726 -123.004326)
		(end 16.192754 -122.339354)
		(width 0.089408)
		(layer "In4.Cu")
		(net "SMB_PEHPCPU1_STBY_LVC3_SCL")
	)
	(segment
		(start 339.6488 -74.171048)
		(end 339.6488 -74.168)
		(width 0.089408)
		(layer "In4.Cu")
		(net "SMB_PEHPCPU1_STBY_LVC3_SCL")
	)
	(segment
		(start 330.5302 -149.26818)
		(end 330.5302 -153.4922)
		(width 0.089408)
		(layer "In4.Cu")
		(net "SMB_PEHPCPU1_STBY_LVC3_SCL")
	)
	(segment
		(start 338.855558 -74.6633)
		(end 337.807554 -75.711304)
		(width 0.089408)
		(layer "In4.Cu")
		(net "SMB_PEHPCPU1_STBY_LVC3_SCL")
	)
	(segment
		(start 337.807554 -75.711304)
		(end 337.807554 -77.99197)
		(width 0.089408)
		(layer "In4.Cu")
		(net "SMB_PEHPCPU1_STBY_LVC3_SCL")
	)
	(segment
		(start 328.234802 -92.363798)
		(end 328.234802 -109.322616)
		(width 0.089408)
		(layer "In4.Cu")
		(net "SMB_PEHPCPU1_STBY_LVC3_SCL")
	)
	(segment
		(start 333.70139 -138.223244)
		(end 332.534768 -139.389866)
		(width 0.089408)
		(layer "In4.Cu")
		(net "SMB_PEHPCPU1_STBY_LVC3_SCL")
	)
	(segment
		(start 265.026902 -158.08706)
		(end 264.988548 -158.125414)
		(width 0.089408)
		(layer "In4.Cu")
		(net "SMB_PEHPCPU1_STBY_LVC3_SCL")
	)
	(segment
		(start 23.179786 -123.004326)
		(end 16.857726 -123.004326)
		(width 0.089408)
		(layer "In4.Cu")
		(net "SMB_PEHPCPU1_STBY_LVC3_SCL")
	)
	(segment
		(start 115.39728 -157.86354)
		(end 114.292126 -156.758386)
		(width 0.089408)
		(layer "In4.Cu")
		(net "SMB_PEHPCPU1_STBY_LVC3_SCL")
	)
	(segment
		(start 334.060038 -86.538562)
		(end 328.234802 -92.363798)
		(width 0.089408)
		(layer "In4.Cu")
		(net "SMB_PEHPCPU1_STBY_LVC3_SCL")
	)
	(segment
		(start 186.54395 -156.318204)
		(end 181.882796 -156.318204)
		(width 0.089408)
		(layer "In4.Cu")
		(net "SMB_PEHPCPU1_STBY_LVC3_SCL")
	)
	(segment
		(start 29.191966 -157.467046)
		(end 26.020014 -154.295094)
		(width 0.089408)
		(layer "In4.Cu")
		(net "SMB_PEHPCPU1_STBY_LVC3_SCL")
	)
	(segment
		(start 329.81519 -123.768612)
		(end 330.404216 -123.768612)
		(width 0.089408)
		(layer "In4.Cu")
		(net "SMB_PEHPCPU1_STBY_LVC3_SCL")
	)
	(segment
		(start 86.94547 -157.467046)
		(end 29.191966 -157.467046)
		(width 0.089408)
		(layer "In4.Cu")
		(net "SMB_PEHPCPU1_STBY_LVC3_SCL")
	)
	(segment
		(start 334.772 -129.455164)
		(end 334.772 -131.744212)
		(width 0.089408)
		(layer "In4.Cu")
		(net "SMB_PEHPCPU1_STBY_LVC3_SCL")
	)
	(segment
		(start 329.145138 -158.420562)
		(end 280.848562 -158.420562)
		(width 0.089408)
		(layer "In4.Cu")
		(net "SMB_PEHPCPU1_STBY_LVC3_SCL")
	)
	(segment
		(start 264.988548 -158.125414)
		(end 188.610748 -158.125414)
		(width 0.089408)
		(layer "In4.Cu")
		(net "SMB_PEHPCPU1_STBY_LVC3_SCL")
	)
	(segment
		(start 115.1255 -158.32328)
		(end 115.39728 -158.0515)
		(width 0.089408)
		(layer "In4.Cu")
		(net "SMB_PEHPCPU1_STBY_LVC3_SCL")
	)
	(segment
		(start 339.6488 -74.168)
		(end 339.1535 -74.6633)
		(width 0.089408)
		(layer "In4.Cu")
		(net "SMB_PEHPCPU1_STBY_LVC3_SCL")
	)
	(segment
		(start 332.534768 -139.389866)
		(end 330.265024 -139.389866)
		(width 0.089408)
		(layer "In4.Cu")
		(net "SMB_PEHPCPU1_STBY_LVC3_SCL")
	)
	(segment
		(start 280.329386 -157.901386)
		(end 265.425682 -157.901386)
		(width 0.089408)
		(layer "In4.Cu")
		(net "SMB_PEHPCPU1_STBY_LVC3_SCL")
	)
	(segment
		(start 328.234802 -110.026196)
		(end 328.234802 -111.615728)
		(width 0.089408)
		(layer "In4.Cu")
		(net "SMB_PEHPCPU1_STBY_LVC3_SCL")
	)
	(segment
		(start 265.425682 -157.901386)
		(end 265.240008 -158.08706)
		(width 0.089408)
		(layer "In4.Cu")
		(net "SMB_PEHPCPU1_STBY_LVC3_SCL")
	)
	(segment
		(start -5.28066 -96.407224)
		(end -5.28066 -120.8405)
		(width 0.089408)
		(layer "In9.Cu")
		(net "SMB_PEHPCPU1_STBY_LVC3_SCL")
	)
	(segment
		(start 399.663666 -44.711112)
		(end 401.120102 -43.254676)
		(width 0.089408)
		(layer "In9.Cu")
		(net "SMB_PEHPCPU1_STBY_LVC3_SCL")
	)
	(segment
		(start -1.20015 -94.76994)
		(end -1.47574 -94.76994)
		(width 0.089408)
		(layer "In9.Cu")
		(net "SMB_PEHPCPU1_STBY_LVC3_SCL")
	)
	(segment
		(start 5.48894 -120.92432)
		(end 15.01648 -120.92432)
		(width 0.089408)
		(layer "In9.Cu")
		(net "SMB_PEHPCPU1_STBY_LVC3_SCL")
	)
	(segment
		(start 398.849088 -59.661806)
		(end 398.849088 -58.598816)
		(width 0.089408)
		(layer "In9.Cu")
		(net "SMB_PEHPCPU1_STBY_LVC3_SCL")
	)
	(segment
		(start 399.663666 -45.948092)
		(end 399.663666 -44.711112)
		(width 0.089408)
		(layer "In9.Cu")
		(net "SMB_PEHPCPU1_STBY_LVC3_SCL")
	)
	(segment
		(start -4.560316 -95.68688)
		(end -5.28066 -96.407224)
		(width 0.089408)
		(layer "In9.Cu")
		(net "SMB_PEHPCPU1_STBY_LVC3_SCL")
	)
	(segment
		(start -2.02946 -120.22836)
		(end 1.104646 -120.22836)
		(width 0.089408)
		(layer "In9.Cu")
		(net "SMB_PEHPCPU1_STBY_LVC3_SCL")
	)
	(segment
		(start 16.48968 -121.1961)
		(end 16.6243 -121.06148)
		(width 0.089408)
		(layer "In9.Cu")
		(net "SMB_PEHPCPU1_STBY_LVC3_SCL")
	)
	(segment
		(start 401.120102 -39.760398)
		(end 407.140664 -33.739836)
		(width 0.089408)
		(layer "In9.Cu")
		(net "SMB_PEHPCPU1_STBY_LVC3_SCL")
	)
	(segment
		(start -2.39268 -95.68688)
		(end -4.560316 -95.68688)
		(width 0.089408)
		(layer "In9.Cu")
		(net "SMB_PEHPCPU1_STBY_LVC3_SCL")
	)
	(segment
		(start 407.140664 -33.739836)
		(end 408.695144 -33.739836)
		(width 0.089408)
		(layer "In9.Cu")
		(net "SMB_PEHPCPU1_STBY_LVC3_SCL")
	)
	(segment
		(start 15.01648 -120.92432)
		(end 15.28826 -121.1961)
		(width 0.089408)
		(layer "In9.Cu")
		(net "SMB_PEHPCPU1_STBY_LVC3_SCL")
	)
	(segment
		(start 5.083302 -121.329958)
		(end 5.48894 -120.92432)
		(width 0.089408)
		(layer "In9.Cu")
		(net "SMB_PEHPCPU1_STBY_LVC3_SCL")
	)
	(segment
		(start 398.849088 -58.598816)
		(end 398.326102 -58.07583)
		(width 0.089408)
		(layer "In9.Cu")
		(net "SMB_PEHPCPU1_STBY_LVC3_SCL")
	)
	(segment
		(start 408.695144 -33.739836)
		(end 409.090114 -34.134806)
		(width 0.089408)
		(layer "In9.Cu")
		(net "SMB_PEHPCPU1_STBY_LVC3_SCL")
	)
	(segment
		(start 398.326102 -47.285656)
		(end 399.663666 -45.948092)
		(width 0.089408)
		(layer "In9.Cu")
		(net "SMB_PEHPCPU1_STBY_LVC3_SCL")
	)
	(segment
		(start -4.74726 -121.3739)
		(end -3.175 -121.3739)
		(width 0.089408)
		(layer "In9.Cu")
		(net "SMB_PEHPCPU1_STBY_LVC3_SCL")
	)
	(segment
		(start -5.28066 -120.8405)
		(end -5.029708 -121.091452)
		(width 0.089408)
		(layer "In9.Cu")
		(net "SMB_PEHPCPU1_STBY_LVC3_SCL")
	)
	(segment
		(start 401.120102 -43.254676)
		(end 401.120102 -39.760398)
		(width 0.089408)
		(layer "In9.Cu")
		(net "SMB_PEHPCPU1_STBY_LVC3_SCL")
	)
	(segment
		(start 16.6243 -121.06148)
		(end 16.6243 -120.80494)
		(width 0.089408)
		(layer "In9.Cu")
		(net "SMB_PEHPCPU1_STBY_LVC3_SCL")
	)
	(segment
		(start 2.206244 -121.329958)
		(end 5.083302 -121.329958)
		(width 0.089408)
		(layer "In9.Cu")
		(net "SMB_PEHPCPU1_STBY_LVC3_SCL")
	)
	(segment
		(start 1.104646 -120.22836)
		(end 2.206244 -121.329958)
		(width 0.089408)
		(layer "In9.Cu")
		(net "SMB_PEHPCPU1_STBY_LVC3_SCL")
	)
	(segment
		(start 398.326102 -58.07583)
		(end 398.326102 -47.285656)
		(width 0.089408)
		(layer "In9.Cu")
		(net "SMB_PEHPCPU1_STBY_LVC3_SCL")
	)
	(segment
		(start -5.029708 -121.091452)
		(end -4.74726 -121.3739)
		(width 0.089408)
		(layer "In9.Cu")
		(net "SMB_PEHPCPU1_STBY_LVC3_SCL")
	)
	(segment
		(start 15.28826 -121.1961)
		(end 16.48968 -121.1961)
		(width 0.089408)
		(layer "In9.Cu")
		(net "SMB_PEHPCPU1_STBY_LVC3_SCL")
	)
	(segment
		(start -3.175 -121.3739)
		(end -2.02946 -120.22836)
		(width 0.089408)
		(layer "In9.Cu")
		(net "SMB_PEHPCPU1_STBY_LVC3_SCL")
	)
	(segment
		(start -1.47574 -94.76994)
		(end -2.39268 -95.68688)
		(width 0.089408)
		(layer "In9.Cu")
		(net "SMB_PEHPCPU1_STBY_LVC3_SCL")
	)
	(segment
		(start 127.655828 -66.305938)
		(end 128.227328 -66.305938)
		(width 0.1016)
		(layer "F.Cu")
		(net "SMB_CPU1_PE_HP_GTL_SDA")
	)
	(via
		(at 128.227328 -66.305938)
		(size 0.508)
		(drill 0.254)
		(layers "F.Cu" "B.Cu")
		(net "SMB_CPU1_PE_HP_GTL_SDA")
	)
	(via
		(at 176.73066 -89.2302)
		(size 0.762)
		(drill 0.3048)
		(layers "F.Cu" "B.Cu")
		(net "SMB_CPU1_PE_HP_GTL_SDA")
	)
	(segment
		(start 176.73066 -89.2302)
		(end 176.73066 -88.972644)
		(width 0.10795)
		(layer "B.Cu")
		(net "SMB_CPU1_PE_HP_GTL_SDA")
	)
	(segment
		(start 176.404016 -88.646)
		(end 176.022 -88.646)
		(width 0.10795)
		(layer "B.Cu")
		(net "SMB_CPU1_PE_HP_GTL_SDA")
	)
	(segment
		(start 176.73066 -88.972644)
		(end 176.404016 -88.646)
		(width 0.10795)
		(layer "B.Cu")
		(net "SMB_CPU1_PE_HP_GTL_SDA")
	)
	(segment
		(start 133.35 -67.887088)
		(end 132.671312 -67.2084)
		(width 0.089408)
		(layer "In4.Cu")
		(net "SMB_CPU1_PE_HP_GTL_SDA")
	)
	(segment
		(start 161.30016 -73.61936)
		(end 160.97885 -73.61936)
		(width 0.089408)
		(layer "In4.Cu")
		(net "SMB_CPU1_PE_HP_GTL_SDA")
	)
	(segment
		(start 154.983688 -69.065394)
		(end 145.896584 -69.065394)
		(width 0.089408)
		(layer "In4.Cu")
		(net "SMB_CPU1_PE_HP_GTL_SDA")
	)
	(segment
		(start 139.0904 -68.282312)
		(end 138.695176 -67.887088)
		(width 0.089408)
		(layer "In4.Cu")
		(net "SMB_CPU1_PE_HP_GTL_SDA")
	)
	(segment
		(start 134.8486 -67.818)
		(end 134.3914 -68.2752)
		(width 0.089408)
		(layer "In4.Cu")
		(net "SMB_CPU1_PE_HP_GTL_SDA")
	)
	(segment
		(start 145.89506 -69.06387)
		(end 143.40967 -69.06387)
		(width 0.089408)
		(layer "In4.Cu")
		(net "SMB_CPU1_PE_HP_GTL_SDA")
	)
	(segment
		(start 145.896584 -69.065394)
		(end 145.89506 -69.06387)
		(width 0.089408)
		(layer "In4.Cu")
		(net "SMB_CPU1_PE_HP_GTL_SDA")
	)
	(segment
		(start 161.8234 -74.1426)
		(end 161.30016 -73.61936)
		(width 0.089408)
		(layer "In4.Cu")
		(net "SMB_CPU1_PE_HP_GTL_SDA")
	)
	(segment
		(start 137.3632 -68.2498)
		(end 136.87425 -67.76085)
		(width 0.089408)
		(layer "In4.Cu")
		(net "SMB_CPU1_PE_HP_GTL_SDA")
	)
	(segment
		(start 134.3914 -68.2752)
		(end 134.154418 -68.2752)
		(width 0.089408)
		(layer "In4.Cu")
		(net "SMB_CPU1_PE_HP_GTL_SDA")
	)
	(segment
		(start 175.64354 -88.54059)
		(end 175.080168 -87.977218)
		(width 0.089408)
		(layer "In4.Cu")
		(net "SMB_CPU1_PE_HP_GTL_SDA")
	)
	(segment
		(start 142.0876 -67.7418)
		(end 141.7066 -67.7418)
		(width 0.089408)
		(layer "In4.Cu")
		(net "SMB_CPU1_PE_HP_GTL_SDA")
	)
	(segment
		(start 137.9474 -68.2498)
		(end 137.3632 -68.2498)
		(width 0.089408)
		(layer "In4.Cu")
		(net "SMB_CPU1_PE_HP_GTL_SDA")
	)
	(segment
		(start 176.73066 -89.2302)
		(end 176.04105 -88.54059)
		(width 0.089408)
		(layer "In4.Cu")
		(net "SMB_CPU1_PE_HP_GTL_SDA")
	)
	(segment
		(start 136.87425 -67.76085)
		(end 136.5504 -67.76085)
		(width 0.089408)
		(layer "In4.Cu")
		(net "SMB_CPU1_PE_HP_GTL_SDA")
	)
	(segment
		(start 138.310112 -67.887088)
		(end 137.9474 -68.2498)
		(width 0.089408)
		(layer "In4.Cu")
		(net "SMB_CPU1_PE_HP_GTL_SDA")
	)
	(segment
		(start 129.00279 -67.0814)
		(end 128.227328 -66.305938)
		(width 0.089408)
		(layer "In4.Cu")
		(net "SMB_CPU1_PE_HP_GTL_SDA")
	)
	(segment
		(start 166.784528 -85.743796)
		(end 165.011862 -83.97113)
		(width 0.089408)
		(layer "In4.Cu")
		(net "SMB_CPU1_PE_HP_GTL_SDA")
	)
	(segment
		(start 141.270736 -68.191634)
		(end 141.028166 -68.191634)
		(width 0.089408)
		(layer "In4.Cu")
		(net "SMB_CPU1_PE_HP_GTL_SDA")
	)
	(segment
		(start 135.3058 -67.818)
		(end 134.8486 -67.818)
		(width 0.089408)
		(layer "In4.Cu")
		(net "SMB_CPU1_PE_HP_GTL_SDA")
	)
	(segment
		(start 159.427926 -73.509632)
		(end 154.983688 -69.065394)
		(width 0.089408)
		(layer "In4.Cu")
		(net "SMB_CPU1_PE_HP_GTL_SDA")
	)
	(segment
		(start 141.028166 -68.191634)
		(end 140.462 -68.7578)
		(width 0.089408)
		(layer "In4.Cu")
		(net "SMB_CPU1_PE_HP_GTL_SDA")
	)
	(segment
		(start 138.695176 -67.887088)
		(end 138.310112 -67.887088)
		(width 0.089408)
		(layer "In4.Cu")
		(net "SMB_CPU1_PE_HP_GTL_SDA")
	)
	(segment
		(start 160.159446 -73.163938)
		(end 159.813752 -73.509632)
		(width 0.089408)
		(layer "In4.Cu")
		(net "SMB_CPU1_PE_HP_GTL_SDA")
	)
	(segment
		(start 165.011862 -75.058778)
		(end 164.638482 -74.685398)
		(width 0.089408)
		(layer "In4.Cu")
		(net "SMB_CPU1_PE_HP_GTL_SDA")
	)
	(segment
		(start 133.766306 -67.887088)
		(end 133.35 -67.887088)
		(width 0.089408)
		(layer "In4.Cu")
		(net "SMB_CPU1_PE_HP_GTL_SDA")
	)
	(segment
		(start 140.462 -68.7578)
		(end 140.0302 -68.7578)
		(width 0.089408)
		(layer "In4.Cu")
		(net "SMB_CPU1_PE_HP_GTL_SDA")
	)
	(segment
		(start 136.03605 -68.2752)
		(end 135.763 -68.2752)
		(width 0.089408)
		(layer "In4.Cu")
		(net "SMB_CPU1_PE_HP_GTL_SDA")
	)
	(segment
		(start 140.0302 -68.7578)
		(end 139.554712 -68.282312)
		(width 0.089408)
		(layer "In4.Cu")
		(net "SMB_CPU1_PE_HP_GTL_SDA")
	)
	(segment
		(start 132.671312 -67.2084)
		(end 132.2832 -67.2084)
		(width 0.089408)
		(layer "In4.Cu")
		(net "SMB_CPU1_PE_HP_GTL_SDA")
	)
	(segment
		(start 175.080168 -87.977218)
		(end 169.759884 -87.977218)
		(width 0.089408)
		(layer "In4.Cu")
		(net "SMB_CPU1_PE_HP_GTL_SDA")
	)
	(segment
		(start 135.763 -68.2752)
		(end 135.3058 -67.818)
		(width 0.089408)
		(layer "In4.Cu")
		(net "SMB_CPU1_PE_HP_GTL_SDA")
	)
	(segment
		(start 165.011862 -83.97113)
		(end 165.011862 -75.058778)
		(width 0.089408)
		(layer "In4.Cu")
		(net "SMB_CPU1_PE_HP_GTL_SDA")
	)
	(segment
		(start 134.154418 -68.2752)
		(end 133.766306 -67.887088)
		(width 0.089408)
		(layer "In4.Cu")
		(net "SMB_CPU1_PE_HP_GTL_SDA")
	)
	(segment
		(start 160.97885 -73.61936)
		(end 160.523428 -73.163938)
		(width 0.089408)
		(layer "In4.Cu")
		(net "SMB_CPU1_PE_HP_GTL_SDA")
	)
	(segment
		(start 141.7066 -67.75577)
		(end 141.270736 -68.191634)
		(width 0.089408)
		(layer "In4.Cu")
		(net "SMB_CPU1_PE_HP_GTL_SDA")
	)
	(segment
		(start 131.2418 -66.802)
		(end 130.9624 -67.0814)
		(width 0.089408)
		(layer "In4.Cu")
		(net "SMB_CPU1_PE_HP_GTL_SDA")
	)
	(segment
		(start 139.554712 -68.282312)
		(end 139.0904 -68.282312)
		(width 0.089408)
		(layer "In4.Cu")
		(net "SMB_CPU1_PE_HP_GTL_SDA")
	)
	(segment
		(start 141.7066 -67.7418)
		(end 141.7066 -67.75577)
		(width 0.089408)
		(layer "In4.Cu")
		(net "SMB_CPU1_PE_HP_GTL_SDA")
	)
	(segment
		(start 169.759884 -87.977218)
		(end 167.526462 -85.743796)
		(width 0.089408)
		(layer "In4.Cu")
		(net "SMB_CPU1_PE_HP_GTL_SDA")
	)
	(segment
		(start 167.526462 -85.743796)
		(end 166.784528 -85.743796)
		(width 0.089408)
		(layer "In4.Cu")
		(net "SMB_CPU1_PE_HP_GTL_SDA")
	)
	(segment
		(start 164.638482 -74.685398)
		(end 163.686998 -74.685398)
		(width 0.089408)
		(layer "In4.Cu")
		(net "SMB_CPU1_PE_HP_GTL_SDA")
	)
	(segment
		(start 130.9624 -67.0814)
		(end 129.00279 -67.0814)
		(width 0.089408)
		(layer "In4.Cu")
		(net "SMB_CPU1_PE_HP_GTL_SDA")
	)
	(segment
		(start 131.8768 -66.802)
		(end 131.2418 -66.802)
		(width 0.089408)
		(layer "In4.Cu")
		(net "SMB_CPU1_PE_HP_GTL_SDA")
	)
	(segment
		(start 143.40967 -69.06387)
		(end 142.0876 -67.7418)
		(width 0.089408)
		(layer "In4.Cu")
		(net "SMB_CPU1_PE_HP_GTL_SDA")
	)
	(segment
		(start 159.813752 -73.509632)
		(end 159.427926 -73.509632)
		(width 0.089408)
		(layer "In4.Cu")
		(net "SMB_CPU1_PE_HP_GTL_SDA")
	)
	(segment
		(start 163.1442 -74.1426)
		(end 161.8234 -74.1426)
		(width 0.089408)
		(layer "In4.Cu")
		(net "SMB_CPU1_PE_HP_GTL_SDA")
	)
	(segment
		(start 160.523428 -73.163938)
		(end 160.159446 -73.163938)
		(width 0.089408)
		(layer "In4.Cu")
		(net "SMB_CPU1_PE_HP_GTL_SDA")
	)
	(segment
		(start 132.2832 -67.2084)
		(end 131.8768 -66.802)
		(width 0.089408)
		(layer "In4.Cu")
		(net "SMB_CPU1_PE_HP_GTL_SDA")
	)
	(segment
		(start 136.5504 -67.76085)
		(end 136.03605 -68.2752)
		(width 0.089408)
		(layer "In4.Cu")
		(net "SMB_CPU1_PE_HP_GTL_SDA")
	)
	(segment
		(start 176.04105 -88.54059)
		(end 175.64354 -88.54059)
		(width 0.089408)
		(layer "In4.Cu")
		(net "SMB_CPU1_PE_HP_GTL_SDA")
	)
	(segment
		(start 163.686998 -74.685398)
		(end 163.1442 -74.1426)
		(width 0.089408)
		(layer "In4.Cu")
		(net "SMB_CPU1_PE_HP_GTL_SDA")
	)
	(segment
		(start 126.797308 -66.800984)
		(end 127.368808 -66.800984)
		(width 0.1016)
		(layer "F.Cu")
		(net "SMB_CPU1_PE_HP_GTL_SCL")
	)
	(via
		(at 176.7078 -87.9602)
		(size 0.508)
		(drill 0.254)
		(layers "F.Cu" "B.Cu")
		(net "SMB_CPU1_PE_HP_GTL_SCL")
	)
	(via
		(at 175.768 -87.7316)
		(size 0.6604)
		(drill 0.3302)
		(layers "F.Cu" "B.Cu")
		(net "SMB_CPU1_PE_HP_GTL_SCL")
	)
	(via
		(at 127.368808 -66.800984)
		(size 0.508)
		(drill 0.254)
		(layers "F.Cu" "B.Cu")
		(net "SMB_CPU1_PE_HP_GTL_SCL")
	)
	(segment
		(start 175.006 -88.4936)
		(end 175.768 -87.7316)
		(width 0.10795)
		(layer "B.Cu")
		(net "SMB_CPU1_PE_HP_GTL_SCL")
	)
	(segment
		(start 175.768 -87.7316)
		(end 176.4792 -87.7316)
		(width 0.10795)
		(layer "B.Cu")
		(net "SMB_CPU1_PE_HP_GTL_SCL")
	)
	(segment
		(start 176.4792 -87.7316)
		(end 176.7078 -87.9602)
		(width 0.10795)
		(layer "B.Cu")
		(net "SMB_CPU1_PE_HP_GTL_SCL")
	)
	(segment
		(start 175.006 -88.646)
		(end 175.006 -88.4936)
		(width 0.10795)
		(layer "B.Cu")
		(net "SMB_CPU1_PE_HP_GTL_SCL")
	)
	(segment
		(start 176.14138 -88.298782)
		(end 175.74387 -88.298782)
		(width 0.089408)
		(layer "In4.Cu")
		(net "SMB_CPU1_PE_HP_GTL_SCL")
	)
	(segment
		(start 162.492436 -71.966328)
		(end 159.533082 -71.966328)
		(width 0.089408)
		(layer "In4.Cu")
		(net "SMB_CPU1_PE_HP_GTL_SCL")
	)
	(segment
		(start 142.335504 -64.8208)
		(end 141.732 -64.8208)
		(width 0.0889)
		(layer "In4.Cu")
		(net "SMB_CPU1_PE_HP_GTL_SCL")
	)
	(segment
		(start 132.1308 -65.6082)
		(end 131.8768 -65.8622)
		(width 0.089408)
		(layer "In4.Cu")
		(net "SMB_CPU1_PE_HP_GTL_SCL")
	)
	(segment
		(start 145.816066 -65.12306)
		(end 143.334994 -65.12306)
		(width 0.089408)
		(layer "In4.Cu")
		(net "SMB_CPU1_PE_HP_GTL_SCL")
	)
	(segment
		(start 137.68578 -65.219834)
		(end 137.655808 -65.219834)
		(width 0.0889)
		(layer "In4.Cu")
		(net "SMB_CPU1_PE_HP_GTL_SCL")
	)
	(segment
		(start 138.550904 -64.724788)
		(end 138.507724 -64.724788)
		(width 0.0889)
		(layer "In4.Cu")
		(net "SMB_CPU1_PE_HP_GTL_SCL")
	)
	(segment
		(start 176.7078 -87.9602)
		(end 176.355248 -88.312752)
		(width 0.089408)
		(layer "In4.Cu")
		(net "SMB_CPU1_PE_HP_GTL_SCL")
	)
	(segment
		(start 142.733014 -65.21831)
		(end 142.335504 -64.8208)
		(width 0.0889)
		(layer "In4.Cu")
		(net "SMB_CPU1_PE_HP_GTL_SCL")
	)
	(segment
		(start 176.15535 -88.312752)
		(end 176.14138 -88.298782)
		(width 0.089408)
		(layer "In4.Cu")
		(net "SMB_CPU1_PE_HP_GTL_SCL")
	)
	(segment
		(start 169.860214 -87.73541)
		(end 167.626792 -85.501988)
		(width 0.089408)
		(layer "In4.Cu")
		(net "SMB_CPU1_PE_HP_GTL_SCL")
	)
	(segment
		(start 140.267944 -64.724788)
		(end 140.224764 -64.724788)
		(width 0.0889)
		(layer "In4.Cu")
		(net "SMB_CPU1_PE_HP_GTL_SCL")
	)
	(segment
		(start 159.533082 -71.966328)
		(end 155.473908 -67.907154)
		(width 0.089408)
		(layer "In4.Cu")
		(net "SMB_CPU1_PE_HP_GTL_SCL")
	)
	(segment
		(start 128.063752 -65.877948)
		(end 127.368808 -66.572892)
		(width 0.089408)
		(layer "In4.Cu")
		(net "SMB_CPU1_PE_HP_GTL_SCL")
	)
	(segment
		(start 175.74387 -88.298782)
		(end 175.180498 -87.73541)
		(width 0.089408)
		(layer "In4.Cu")
		(net "SMB_CPU1_PE_HP_GTL_SCL")
	)
	(segment
		(start 130.7846 -66.7258)
		(end 129.3368 -66.7258)
		(width 0.089408)
		(layer "In4.Cu")
		(net "SMB_CPU1_PE_HP_GTL_SCL")
	)
	(segment
		(start 133.399784 -64.724788)
		(end 133.356604 -64.724788)
		(width 0.0889)
		(layer "In4.Cu")
		(net "SMB_CPU1_PE_HP_GTL_SCL")
	)
	(segment
		(start 146.354038 -65.118996)
		(end 145.82013 -65.118996)
		(width 0.089408)
		(layer "In4.Cu")
		(net "SMB_CPU1_PE_HP_GTL_SCL")
	)
	(segment
		(start 165.25367 -74.727562)
		(end 162.492436 -71.966328)
		(width 0.089408)
		(layer "In4.Cu")
		(net "SMB_CPU1_PE_HP_GTL_SCL")
	)
	(segment
		(start 141.732 -64.8208)
		(end 141.332966 -65.219834)
		(width 0.0889)
		(layer "In4.Cu")
		(net "SMB_CPU1_PE_HP_GTL_SCL")
	)
	(segment
		(start 136.812528 -64.724534)
		(end 136.81202 -64.724534)
		(width 0.0889)
		(layer "In4.Cu")
		(net "SMB_CPU1_PE_HP_GTL_SCL")
	)
	(segment
		(start 135.116824 -64.724788)
		(end 135.073644 -64.724788)
		(width 0.0889)
		(layer "In4.Cu")
		(net "SMB_CPU1_PE_HP_GTL_SCL")
	)
	(segment
		(start 132.484622 -65.219834)
		(end 132.1308 -65.573656)
		(width 0.089408)
		(layer "In4.Cu")
		(net "SMB_CPU1_PE_HP_GTL_SCL")
	)
	(segment
		(start 132.1308 -65.573656)
		(end 132.1308 -65.6082)
		(width 0.089408)
		(layer "In4.Cu")
		(net "SMB_CPU1_PE_HP_GTL_SCL")
	)
	(segment
		(start 176.355248 -88.312752)
		(end 176.15535 -88.312752)
		(width 0.089408)
		(layer "In4.Cu")
		(net "SMB_CPU1_PE_HP_GTL_SCL")
	)
	(segment
		(start 145.82013 -65.118996)
		(end 145.816066 -65.12306)
		(width 0.089408)
		(layer "In4.Cu")
		(net "SMB_CPU1_PE_HP_GTL_SCL")
	)
	(segment
		(start 175.180498 -87.73541)
		(end 169.860214 -87.73541)
		(width 0.089408)
		(layer "In4.Cu")
		(net "SMB_CPU1_PE_HP_GTL_SCL")
	)
	(segment
		(start 134.2517 -65.219834)
		(end 134.221728 -65.219834)
		(width 0.0889)
		(layer "In4.Cu")
		(net "SMB_CPU1_PE_HP_GTL_SCL")
	)
	(segment
		(start 132.53466 -65.219834)
		(end 132.484622 -65.219834)
		(width 0.0889)
		(layer "In4.Cu")
		(net "SMB_CPU1_PE_HP_GTL_SCL")
	)
	(segment
		(start 165.25367 -83.8708)
		(end 165.25367 -74.727562)
		(width 0.089408)
		(layer "In4.Cu")
		(net "SMB_CPU1_PE_HP_GTL_SCL")
	)
	(segment
		(start 141.332966 -65.219834)
		(end 141.089888 -65.219834)
		(width 0.0889)
		(layer "In4.Cu")
		(net "SMB_CPU1_PE_HP_GTL_SCL")
	)
	(segment
		(start 129.3368 -66.7258)
		(end 128.488948 -65.877948)
		(width 0.089408)
		(layer "In4.Cu")
		(net "SMB_CPU1_PE_HP_GTL_SCL")
	)
	(segment
		(start 167.626792 -85.501988)
		(end 166.884858 -85.501988)
		(width 0.089408)
		(layer "In4.Cu")
		(net "SMB_CPU1_PE_HP_GTL_SCL")
	)
	(segment
		(start 127.368808 -66.572892)
		(end 127.368808 -66.800984)
		(width 0.089408)
		(layer "In4.Cu")
		(net "SMB_CPU1_PE_HP_GTL_SCL")
	)
	(segment
		(start 143.239744 -65.21831)
		(end 142.733014 -65.21831)
		(width 0.0889)
		(layer "In4.Cu")
		(net "SMB_CPU1_PE_HP_GTL_SCL")
	)
	(segment
		(start 149.142196 -67.907154)
		(end 146.354038 -65.118996)
		(width 0.089408)
		(layer "In4.Cu")
		(net "SMB_CPU1_PE_HP_GTL_SCL")
	)
	(segment
		(start 131.8768 -65.8622)
		(end 131.318 -65.8622)
		(width 0.089408)
		(layer "In4.Cu")
		(net "SMB_CPU1_PE_HP_GTL_SCL")
	)
	(segment
		(start 131.1148 -66.0654)
		(end 131.1148 -66.3956)
		(width 0.089408)
		(layer "In4.Cu")
		(net "SMB_CPU1_PE_HP_GTL_SCL")
	)
	(segment
		(start 131.318 -65.8622)
		(end 131.1148 -66.0654)
		(width 0.089408)
		(layer "In4.Cu")
		(net "SMB_CPU1_PE_HP_GTL_SCL")
	)
	(segment
		(start 166.884858 -85.501988)
		(end 165.25367 -83.8708)
		(width 0.089408)
		(layer "In4.Cu")
		(net "SMB_CPU1_PE_HP_GTL_SCL")
	)
	(segment
		(start 155.473908 -67.907154)
		(end 149.142196 -67.907154)
		(width 0.089408)
		(layer "In4.Cu")
		(net "SMB_CPU1_PE_HP_GTL_SCL")
	)
	(segment
		(start 143.334994 -65.12306)
		(end 143.239744 -65.21831)
		(width 0.089408)
		(layer "In4.Cu")
		(net "SMB_CPU1_PE_HP_GTL_SCL")
	)
	(segment
		(start 131.1148 -66.3956)
		(end 130.7846 -66.7258)
		(width 0.089408)
		(layer "In4.Cu")
		(net "SMB_CPU1_PE_HP_GTL_SCL")
	)
	(segment
		(start 139.40282 -65.219834)
		(end 139.372848 -65.219834)
		(width 0.0889)
		(layer "In4.Cu")
		(net "SMB_CPU1_PE_HP_GTL_SCL")
	)
	(segment
		(start 128.488948 -65.877948)
		(end 128.063752 -65.877948)
		(width 0.089408)
		(layer "In4.Cu")
		(net "SMB_CPU1_PE_HP_GTL_SCL")
	)
	(arc
		(start 134.221728 -65.219834)
		(mid 134.030086 -65.162668)
		(end 133.890004 -65.019936)
		(width 0.0889)
		(layer "In4.Cu")
		(net "SMB_CPU1_PE_HP_GTL_SCL")
	)
	(arc
		(start 134.583424 -65.019936)
		(mid 134.443345 -65.162672)
		(end 134.2517 -65.219834)
		(width 0.0889)
		(layer "In4.Cu")
		(net "SMB_CPU1_PE_HP_GTL_SCL")
	)
	(arc
		(start 137.324084 -65.019936)
		(mid 137.1079 -64.803657)
		(end 136.812528 -64.724534)
		(width 0.0889)
		(layer "In4.Cu")
		(net "SMB_CPU1_PE_HP_GTL_SCL")
	)
	(arc
		(start 136.300464 -65.019936)
		(mid 135.953754 -65.22012)
		(end 135.607044 -65.019936)
		(width 0.0889)
		(layer "In4.Cu")
		(net "SMB_CPU1_PE_HP_GTL_SCL")
	)
	(arc
		(start 136.81202 -64.724534)
		(mid 136.51667 -64.803696)
		(end 136.300464 -65.019936)
		(width 0.0889)
		(layer "In4.Cu")
		(net "SMB_CPU1_PE_HP_GTL_SCL")
	)
	(arc
		(start 140.758164 -65.019936)
		(mid 140.55116 -64.809072)
		(end 140.267944 -64.724788)
		(width 0.0889)
		(layer "In4.Cu")
		(net "SMB_CPU1_PE_HP_GTL_SCL")
	)
	(arc
		(start 139.041124 -65.019936)
		(mid 138.83412 -64.809072)
		(end 138.550904 -64.724788)
		(width 0.0889)
		(layer "In4.Cu")
		(net "SMB_CPU1_PE_HP_GTL_SCL")
	)
	(arc
		(start 135.073644 -64.724788)
		(mid 134.790427 -64.809069)
		(end 134.583424 -65.019936)
		(width 0.0889)
		(layer "In4.Cu")
		(net "SMB_CPU1_PE_HP_GTL_SCL")
	)
	(arc
		(start 141.089888 -65.219834)
		(mid 140.898246 -65.162668)
		(end 140.758164 -65.019936)
		(width 0.0889)
		(layer "In4.Cu")
		(net "SMB_CPU1_PE_HP_GTL_SCL")
	)
	(arc
		(start 138.507724 -64.724788)
		(mid 138.224507 -64.809069)
		(end 138.017504 -65.019936)
		(width 0.0889)
		(layer "In4.Cu")
		(net "SMB_CPU1_PE_HP_GTL_SCL")
	)
	(arc
		(start 139.734544 -65.019936)
		(mid 139.594465 -65.162672)
		(end 139.40282 -65.219834)
		(width 0.0889)
		(layer "In4.Cu")
		(net "SMB_CPU1_PE_HP_GTL_SCL")
	)
	(arc
		(start 133.890004 -65.019936)
		(mid 133.683 -64.809072)
		(end 133.399784 -64.724788)
		(width 0.0889)
		(layer "In4.Cu")
		(net "SMB_CPU1_PE_HP_GTL_SCL")
	)
	(arc
		(start 139.372848 -65.219834)
		(mid 139.181206 -65.162668)
		(end 139.041124 -65.019936)
		(width 0.0889)
		(layer "In4.Cu")
		(net "SMB_CPU1_PE_HP_GTL_SCL")
	)
	(arc
		(start 133.356604 -64.724788)
		(mid 133.073387 -64.809069)
		(end 132.866384 -65.019936)
		(width 0.0889)
		(layer "In4.Cu")
		(net "SMB_CPU1_PE_HP_GTL_SCL")
	)
	(arc
		(start 135.607044 -65.019936)
		(mid 135.40004 -64.809072)
		(end 135.116824 -64.724788)
		(width 0.0889)
		(layer "In4.Cu")
		(net "SMB_CPU1_PE_HP_GTL_SCL")
	)
	(arc
		(start 140.224764 -64.724788)
		(mid 139.941547 -64.809069)
		(end 139.734544 -65.019936)
		(width 0.0889)
		(layer "In4.Cu")
		(net "SMB_CPU1_PE_HP_GTL_SCL")
	)
	(arc
		(start 137.655808 -65.219834)
		(mid 137.464166 -65.162668)
		(end 137.324084 -65.019936)
		(width 0.0889)
		(layer "In4.Cu")
		(net "SMB_CPU1_PE_HP_GTL_SCL")
	)
	(arc
		(start 138.017504 -65.019936)
		(mid 137.877425 -65.162672)
		(end 137.68578 -65.219834)
		(width 0.0889)
		(layer "In4.Cu")
		(net "SMB_CPU1_PE_HP_GTL_SCL")
	)
	(arc
		(start 132.866384 -65.019936)
		(mid 132.726305 -65.162672)
		(end 132.53466 -65.219834)
		(width 0.0889)
		(layer "In4.Cu")
		(net "SMB_CPU1_PE_HP_GTL_SCL")
	)
	(segment
		(start -1.0033 -120.2817)
		(end -1.0033 -118.6561)
		(width 0.10795)
		(layer "F.Cu")
		(net "SMB_CPU1_PE_HP_GTL_R_SDA")
	)
	(segment
		(start -1.795526 -116.03482)
		(end -2.56413 -116.03482)
		(width 0.10795)
		(layer "F.Cu")
		(net "SMB_CPU1_PE_HP_GTL_R_SDA")
	)
	(segment
		(start 0.54864 -121.666)
		(end 0.381 -121.666)
		(width 0.10795)
		(layer "F.Cu")
		(net "SMB_CPU1_PE_HP_GTL_R_SDA")
	)
	(segment
		(start -1.1049 -118.5545)
		(end -1.1049 -116.725446)
		(width 0.10795)
		(layer "F.Cu")
		(net "SMB_CPU1_PE_HP_GTL_R_SDA")
	)
	(segment
		(start -2.855468 -116.326158)
		(end -2.855468 -117.38864)
		(width 0.10795)
		(layer "F.Cu")
		(net "SMB_CPU1_PE_HP_GTL_R_SDA")
	)
	(segment
		(start 0.381 -121.666)
		(end -1.0033 -120.2817)
		(width 0.10795)
		(layer "F.Cu")
		(net "SMB_CPU1_PE_HP_GTL_R_SDA")
	)
	(segment
		(start -2.56413 -116.03482)
		(end -2.855468 -116.326158)
		(width 0.10795)
		(layer "F.Cu")
		(net "SMB_CPU1_PE_HP_GTL_R_SDA")
	)
	(segment
		(start -1.1049 -116.725446)
		(end -1.795526 -116.03482)
		(width 0.10795)
		(layer "F.Cu")
		(net "SMB_CPU1_PE_HP_GTL_R_SDA")
	)
	(segment
		(start -1.0033 -118.6561)
		(end -1.1049 -118.5545)
		(width 0.10795)
		(layer "F.Cu")
		(net "SMB_CPU1_PE_HP_GTL_R_SDA")
	)
	(via
		(at -0.370332 -117.552216)
		(size 0.6604)
		(drill 0.3302)
		(layers "F.Cu" "B.Cu")
		(net "SMB_CPU1_PE_HP_GTL_R_SDA")
	)
	(via
		(at 0.54864 -121.666)
		(size 0.508)
		(drill 0.254)
		(layers "F.Cu" "B.Cu")
		(net "SMB_CPU1_PE_HP_GTL_R_SDA")
	)
	(via
		(at 176.693576 -90.079576)
		(size 0.508)
		(drill 0.254)
		(layers "F.Cu" "B.Cu")
		(net "SMB_CPU1_PE_HP_GTL_R_SDA")
	)
	(via
		(at 22.732238 -121.717054)
		(size 0.508)
		(drill 0.254)
		(layers "F.Cu" "B.Cu")
		(net "SMB_CPU1_PE_HP_GTL_R_SDA")
	)
	(via
		(at 174.803308 -126.424944)
		(size 0.508)
		(drill 0.254)
		(layers "F.Cu" "B.Cu")
		(net "SMB_CPU1_PE_HP_GTL_R_SDA")
	)
	(segment
		(start -0.163576 -117.758972)
		(end -0.370332 -117.552216)
		(width 0.10795)
		(layer "B.Cu")
		(net "SMB_CPU1_PE_HP_GTL_R_SDA")
	)
	(segment
		(start -2.09931 -116.60632)
		(end -1.2319 -116.60632)
		(width 0.10795)
		(layer "B.Cu")
		(net "SMB_CPU1_PE_HP_GTL_R_SDA")
	)
	(segment
		(start -1.2319 -116.60632)
		(end -0.370332 -117.467888)
		(width 0.10795)
		(layer "B.Cu")
		(net "SMB_CPU1_PE_HP_GTL_R_SDA")
	)
	(segment
		(start 176.566576 -90.079576)
		(end 176.693576 -90.079576)
		(width 0.10795)
		(layer "B.Cu")
		(net "SMB_CPU1_PE_HP_GTL_R_SDA")
	)
	(segment
		(start -0.163576 -120.404636)
		(end -0.163576 -117.758972)
		(width 0.10795)
		(layer "B.Cu")
		(net "SMB_CPU1_PE_HP_GTL_R_SDA")
	)
	(segment
		(start 0.54864 -121.116852)
		(end -0.163576 -120.404636)
		(width 0.10795)
		(layer "B.Cu")
		(net "SMB_CPU1_PE_HP_GTL_R_SDA")
	)
	(segment
		(start 0.54864 -121.666)
		(end 0.54864 -121.116852)
		(width 0.10795)
		(layer "B.Cu")
		(net "SMB_CPU1_PE_HP_GTL_R_SDA")
	)
	(segment
		(start 176.022 -89.535)
		(end 176.566576 -90.079576)
		(width 0.10795)
		(layer "B.Cu")
		(net "SMB_CPU1_PE_HP_GTL_R_SDA")
	)
	(segment
		(start -2.20726 -116.71427)
		(end -2.09931 -116.60632)
		(width 0.10795)
		(layer "B.Cu")
		(net "SMB_CPU1_PE_HP_GTL_R_SDA")
	)
	(segment
		(start -2.20726 -117.00256)
		(end -2.20726 -116.71427)
		(width 0.10795)
		(layer "B.Cu")
		(net "SMB_CPU1_PE_HP_GTL_R_SDA")
	)
	(segment
		(start -0.370332 -117.467888)
		(end -0.370332 -117.552216)
		(width 0.10795)
		(layer "B.Cu")
		(net "SMB_CPU1_PE_HP_GTL_R_SDA")
	)
	(segment
		(start 11.37666 -122.7836)
		(end 18.393918 -122.7836)
		(width 0.089408)
		(layer "In2.Cu")
		(net "SMB_CPU1_PE_HP_GTL_R_SDA")
	)
	(segment
		(start 0.54864 -121.666)
		(end 0.6985 -121.666)
		(width 0.089408)
		(layer "In2.Cu")
		(net "SMB_CPU1_PE_HP_GTL_R_SDA")
	)
	(segment
		(start 20.103338 -121.07418)
		(end 22.511512 -121.07418)
		(width 0.089408)
		(layer "In2.Cu")
		(net "SMB_CPU1_PE_HP_GTL_R_SDA")
	)
	(segment
		(start 0.999998 -121.967498)
		(end 1.730248 -121.967498)
		(width 0.089408)
		(layer "In2.Cu")
		(net "SMB_CPU1_PE_HP_GTL_R_SDA")
	)
	(segment
		(start 22.732238 -121.294906)
		(end 22.732238 -121.717054)
		(width 0.089408)
		(layer "In2.Cu")
		(net "SMB_CPU1_PE_HP_GTL_R_SDA")
	)
	(segment
		(start 2.253488 -122.490738)
		(end 4.761992 -122.490738)
		(width 0.089408)
		(layer "In2.Cu")
		(net "SMB_CPU1_PE_HP_GTL_R_SDA")
	)
	(segment
		(start 1.730248 -121.967498)
		(end 2.253488 -122.490738)
		(width 0.089408)
		(layer "In2.Cu")
		(net "SMB_CPU1_PE_HP_GTL_R_SDA")
	)
	(segment
		(start 5.965444 -121.287286)
		(end 9.880346 -121.287286)
		(width 0.089408)
		(layer "In2.Cu")
		(net "SMB_CPU1_PE_HP_GTL_R_SDA")
	)
	(segment
		(start 9.880346 -121.287286)
		(end 11.37666 -122.7836)
		(width 0.089408)
		(layer "In2.Cu")
		(net "SMB_CPU1_PE_HP_GTL_R_SDA")
	)
	(segment
		(start 22.511512 -121.07418)
		(end 22.732238 -121.294906)
		(width 0.089408)
		(layer "In2.Cu")
		(net "SMB_CPU1_PE_HP_GTL_R_SDA")
	)
	(segment
		(start 4.761992 -122.490738)
		(end 5.965444 -121.287286)
		(width 0.089408)
		(layer "In2.Cu")
		(net "SMB_CPU1_PE_HP_GTL_R_SDA")
	)
	(segment
		(start 18.393918 -122.7836)
		(end 20.103338 -121.07418)
		(width 0.089408)
		(layer "In2.Cu")
		(net "SMB_CPU1_PE_HP_GTL_R_SDA")
	)
	(segment
		(start 0.6985 -121.666)
		(end 0.999998 -121.967498)
		(width 0.089408)
		(layer "In2.Cu")
		(net "SMB_CPU1_PE_HP_GTL_R_SDA")
	)
	(segment
		(start 172.0342 -121.73458)
		(end 174.803308 -124.503688)
		(width 0.089408)
		(layer "In4.Cu")
		(net "SMB_CPU1_PE_HP_GTL_R_SDA")
	)
	(segment
		(start 173.913546 -98.450146)
		(end 172.0342 -100.329492)
		(width 0.089408)
		(layer "In4.Cu")
		(net "SMB_CPU1_PE_HP_GTL_R_SDA")
	)
	(segment
		(start 174.803308 -124.503688)
		(end 174.803308 -126.424944)
		(width 0.089408)
		(layer "In4.Cu")
		(net "SMB_CPU1_PE_HP_GTL_R_SDA")
	)
	(segment
		(start 175.514 -91.259152)
		(end 175.514 -92.69222)
		(width 0.089408)
		(layer "In4.Cu")
		(net "SMB_CPU1_PE_HP_GTL_R_SDA")
	)
	(segment
		(start 173.913546 -94.292674)
		(end 173.913546 -98.450146)
		(width 0.089408)
		(layer "In4.Cu")
		(net "SMB_CPU1_PE_HP_GTL_R_SDA")
	)
	(segment
		(start 176.693576 -90.079576)
		(end 175.514 -91.259152)
		(width 0.089408)
		(layer "In4.Cu")
		(net "SMB_CPU1_PE_HP_GTL_R_SDA")
	)
	(segment
		(start 172.0342 -100.329492)
		(end 172.0342 -121.73458)
		(width 0.089408)
		(layer "In4.Cu")
		(net "SMB_CPU1_PE_HP_GTL_R_SDA")
	)
	(segment
		(start 175.514 -92.69222)
		(end 173.913546 -94.292674)
		(width 0.089408)
		(layer "In4.Cu")
		(net "SMB_CPU1_PE_HP_GTL_R_SDA")
	)
	(segment
		(start 26.179526 -123.068588)
		(end 24.548338 -121.4374)
		(width 0.089408)
		(layer "In9.Cu")
		(net "SMB_CPU1_PE_HP_GTL_R_SDA")
	)
	(segment
		(start 24.548338 -121.4374)
		(end 23.011892 -121.4374)
		(width 0.089408)
		(layer "In9.Cu")
		(net "SMB_CPU1_PE_HP_GTL_R_SDA")
	)
	(segment
		(start 174.879 -127.7112)
		(end 174.10938 -128.48082)
		(width 0.089408)
		(layer "In9.Cu")
		(net "SMB_CPU1_PE_HP_GTL_R_SDA")
	)
	(segment
		(start 152.412192 -127.89408)
		(end 147.5867 -123.068588)
		(width 0.089408)
		(layer "In9.Cu")
		(net "SMB_CPU1_PE_HP_GTL_R_SDA")
	)
	(segment
		(start 163.240212 -126.201424)
		(end 161.547556 -127.89408)
		(width 0.089408)
		(layer "In9.Cu")
		(net "SMB_CPU1_PE_HP_GTL_R_SDA")
	)
	(segment
		(start 174.10938 -128.48082)
		(end 169.399204 -128.48082)
		(width 0.089408)
		(layer "In9.Cu")
		(net "SMB_CPU1_PE_HP_GTL_R_SDA")
	)
	(segment
		(start 23.011892 -121.4374)
		(end 22.732238 -121.717054)
		(width 0.089408)
		(layer "In9.Cu")
		(net "SMB_CPU1_PE_HP_GTL_R_SDA")
	)
	(segment
		(start 165.636702 -126.987808)
		(end 164.850318 -126.201424)
		(width 0.089408)
		(layer "In9.Cu")
		(net "SMB_CPU1_PE_HP_GTL_R_SDA")
	)
	(segment
		(start 174.803308 -126.424944)
		(end 174.879 -126.500636)
		(width 0.089408)
		(layer "In9.Cu")
		(net "SMB_CPU1_PE_HP_GTL_R_SDA")
	)
	(segment
		(start 174.879 -126.500636)
		(end 174.879 -127.7112)
		(width 0.089408)
		(layer "In9.Cu")
		(net "SMB_CPU1_PE_HP_GTL_R_SDA")
	)
	(segment
		(start 164.850318 -126.201424)
		(end 163.240212 -126.201424)
		(width 0.089408)
		(layer "In9.Cu")
		(net "SMB_CPU1_PE_HP_GTL_R_SDA")
	)
	(segment
		(start 147.5867 -123.068588)
		(end 26.179526 -123.068588)
		(width 0.089408)
		(layer "In9.Cu")
		(net "SMB_CPU1_PE_HP_GTL_R_SDA")
	)
	(segment
		(start 167.906192 -126.987808)
		(end 165.636702 -126.987808)
		(width 0.089408)
		(layer "In9.Cu")
		(net "SMB_CPU1_PE_HP_GTL_R_SDA")
	)
	(segment
		(start 161.547556 -127.89408)
		(end 152.412192 -127.89408)
		(width 0.089408)
		(layer "In9.Cu")
		(net "SMB_CPU1_PE_HP_GTL_R_SDA")
	)
	(segment
		(start 169.399204 -128.48082)
		(end 167.906192 -126.987808)
		(width 0.089408)
		(layer "In9.Cu")
		(net "SMB_CPU1_PE_HP_GTL_R_SDA")
	)
	(segment
		(start -0.762 -120.142)
		(end -0.762 -118.5545)
		(width 0.10795)
		(layer "F.Cu")
		(net "SMB_CPU1_PE_HP_GTL_R_SCL")
	)
	(segment
		(start -1.85674 -115.64366)
		(end -2.95148 -115.64366)
		(width 0.10795)
		(layer "F.Cu")
		(net "SMB_CPU1_PE_HP_GTL_R_SCL")
	)
	(segment
		(start -2.95148 -115.64366)
		(end -3.505708 -116.197888)
		(width 0.10795)
		(layer "F.Cu")
		(net "SMB_CPU1_PE_HP_GTL_R_SCL")
	)
	(segment
		(start 1.2954 -121.49582)
		(end 1.15062 -121.49582)
		(width 0.10795)
		(layer "F.Cu")
		(net "SMB_CPU1_PE_HP_GTL_R_SCL")
	)
	(segment
		(start -3.505708 -116.197888)
		(end -3.505708 -117.38864)
		(width 0.10795)
		(layer "F.Cu")
		(net "SMB_CPU1_PE_HP_GTL_R_SCL")
	)
	(segment
		(start -0.8636 -118.4529)
		(end -0.8636 -116.6241)
		(width 0.10795)
		(layer "F.Cu")
		(net "SMB_CPU1_PE_HP_GTL_R_SCL")
	)
	(segment
		(start -0.762 -118.5545)
		(end -0.8636 -118.4529)
		(width 0.10795)
		(layer "F.Cu")
		(net "SMB_CPU1_PE_HP_GTL_R_SCL")
	)
	(segment
		(start -0.8636 -116.6241)
		(end -1.6891 -115.7986)
		(width 0.10795)
		(layer "F.Cu")
		(net "SMB_CPU1_PE_HP_GTL_R_SCL")
	)
	(segment
		(start 0.8128 -121.158)
		(end 0.254 -121.158)
		(width 0.10795)
		(layer "F.Cu")
		(net "SMB_CPU1_PE_HP_GTL_R_SCL")
	)
	(segment
		(start 0.254 -121.158)
		(end -0.762 -120.142)
		(width 0.10795)
		(layer "F.Cu")
		(net "SMB_CPU1_PE_HP_GTL_R_SCL")
	)
	(segment
		(start -1.6891 -115.7986)
		(end -1.7018 -115.7986)
		(width 0.10795)
		(layer "F.Cu")
		(net "SMB_CPU1_PE_HP_GTL_R_SCL")
	)
	(segment
		(start 1.15062 -121.49582)
		(end 0.8128 -121.158)
		(width 0.10795)
		(layer "F.Cu")
		(net "SMB_CPU1_PE_HP_GTL_R_SCL")
	)
	(segment
		(start -1.7018 -115.7986)
		(end -1.85674 -115.64366)
		(width 0.10795)
		(layer "F.Cu")
		(net "SMB_CPU1_PE_HP_GTL_R_SCL")
	)
	(via
		(at 176.7078 -90.7542)
		(size 0.508)
		(drill 0.254)
		(layers "F.Cu" "B.Cu")
		(net "SMB_CPU1_PE_HP_GTL_R_SCL")
	)
	(via
		(at 175.514 -126.5428)
		(size 0.508)
		(drill 0.254)
		(layers "F.Cu" "B.Cu")
		(net "SMB_CPU1_PE_HP_GTL_R_SCL")
	)
	(via
		(at 23.450804 -122.021092)
		(size 0.508)
		(drill 0.254)
		(layers "F.Cu" "B.Cu")
		(net "SMB_CPU1_PE_HP_GTL_R_SCL")
	)
	(via
		(at 1.2954 -121.49582)
		(size 0.508)
		(drill 0.254)
		(layers "F.Cu" "B.Cu")
		(net "SMB_CPU1_PE_HP_GTL_R_SCL")
	)
	(segment
		(start 176.2252 -90.7542)
		(end 175.006 -89.535)
		(width 0.10795)
		(layer "B.Cu")
		(net "SMB_CPU1_PE_HP_GTL_R_SCL")
	)
	(segment
		(start 176.7078 -90.7542)
		(end 176.2252 -90.7542)
		(width 0.10795)
		(layer "B.Cu")
		(net "SMB_CPU1_PE_HP_GTL_R_SCL")
	)
	(segment
		(start -3.47726 -116.41455)
		(end -3.47726 -117.00256)
		(width 0.10795)
		(layer "B.Cu")
		(net "SMB_CPU1_PE_HP_GTL_R_SCL")
	)
	(segment
		(start -0.76454 -116.3066)
		(end -3.36931 -116.3066)
		(width 0.10795)
		(layer "B.Cu")
		(net "SMB_CPU1_PE_HP_GTL_R_SCL")
	)
	(segment
		(start 1.2954 -121.49582)
		(end 0.132842 -120.333262)
		(width 0.10795)
		(layer "B.Cu")
		(net "SMB_CPU1_PE_HP_GTL_R_SCL")
	)
	(segment
		(start -3.36931 -116.3066)
		(end -3.47726 -116.41455)
		(width 0.10795)
		(layer "B.Cu")
		(net "SMB_CPU1_PE_HP_GTL_R_SCL")
	)
	(segment
		(start 0.132842 -120.333262)
		(end 0.132842 -117.203982)
		(width 0.10795)
		(layer "B.Cu")
		(net "SMB_CPU1_PE_HP_GTL_R_SCL")
	)
	(segment
		(start 0.132842 -117.203982)
		(end -0.76454 -116.3066)
		(width 0.10795)
		(layer "B.Cu")
		(net "SMB_CPU1_PE_HP_GTL_R_SCL")
	)
	(segment
		(start 23.132542 -121.70283)
		(end 23.450804 -122.021092)
		(width 0.089408)
		(layer "In2.Cu")
		(net "SMB_CPU1_PE_HP_GTL_R_SCL")
	)
	(segment
		(start 2.448814 -122.24893)
		(end 4.661662 -122.24893)
		(width 0.089408)
		(layer "In2.Cu")
		(net "SMB_CPU1_PE_HP_GTL_R_SCL")
	)
	(segment
		(start 11.490198 -122.555)
		(end 18.28038 -122.555)
		(width 0.089408)
		(layer "In2.Cu")
		(net "SMB_CPU1_PE_HP_GTL_R_SCL")
	)
	(segment
		(start 20.003008 -120.832372)
		(end 22.611842 -120.832372)
		(width 0.089408)
		(layer "In2.Cu")
		(net "SMB_CPU1_PE_HP_GTL_R_SCL")
	)
	(segment
		(start 18.28038 -122.555)
		(end 20.003008 -120.832372)
		(width 0.089408)
		(layer "In2.Cu")
		(net "SMB_CPU1_PE_HP_GTL_R_SCL")
	)
	(segment
		(start 9.980676 -121.045478)
		(end 11.490198 -122.555)
		(width 0.089408)
		(layer "In2.Cu")
		(net "SMB_CPU1_PE_HP_GTL_R_SCL")
	)
	(segment
		(start 4.661662 -122.24893)
		(end 5.865114 -121.045478)
		(width 0.089408)
		(layer "In2.Cu")
		(net "SMB_CPU1_PE_HP_GTL_R_SCL")
	)
	(segment
		(start 23.132542 -121.353072)
		(end 23.132542 -121.70283)
		(width 0.089408)
		(layer "In2.Cu")
		(net "SMB_CPU1_PE_HP_GTL_R_SCL")
	)
	(segment
		(start 1.695704 -121.49582)
		(end 2.448814 -122.24893)
		(width 0.089408)
		(layer "In2.Cu")
		(net "SMB_CPU1_PE_HP_GTL_R_SCL")
	)
	(segment
		(start 1.2954 -121.49582)
		(end 1.695704 -121.49582)
		(width 0.089408)
		(layer "In2.Cu")
		(net "SMB_CPU1_PE_HP_GTL_R_SCL")
	)
	(segment
		(start 22.611842 -120.832372)
		(end 23.132542 -121.353072)
		(width 0.089408)
		(layer "In2.Cu")
		(net "SMB_CPU1_PE_HP_GTL_R_SCL")
	)
	(segment
		(start 5.865114 -121.045478)
		(end 9.980676 -121.045478)
		(width 0.089408)
		(layer "In2.Cu")
		(net "SMB_CPU1_PE_HP_GTL_R_SCL")
	)
	(segment
		(start 175.670464 -104.923336)
		(end 175.012096 -105.581704)
		(width 0.089408)
		(layer "In4.Cu")
		(net "SMB_CPU1_PE_HP_GTL_R_SCL")
	)
	(segment
		(start 174.206154 -98.867722)
		(end 175.670464 -100.332032)
		(width 0.089408)
		(layer "In4.Cu")
		(net "SMB_CPU1_PE_HP_GTL_R_SCL")
	)
	(segment
		(start 175.8696 -91.5924)
		(end 175.8696 -92.75064)
		(width 0.089408)
		(layer "In4.Cu")
		(net "SMB_CPU1_PE_HP_GTL_R_SCL")
	)
	(segment
		(start 176.7078 -90.7542)
		(end 175.8696 -91.5924)
		(width 0.089408)
		(layer "In4.Cu")
		(net "SMB_CPU1_PE_HP_GTL_R_SCL")
	)
	(segment
		(start 175.8696 -92.75064)
		(end 174.206154 -94.414086)
		(width 0.089408)
		(layer "In4.Cu")
		(net "SMB_CPU1_PE_HP_GTL_R_SCL")
	)
	(segment
		(start 175.615854 -123.952254)
		(end 175.615854 -126.440946)
		(width 0.089408)
		(layer "In4.Cu")
		(net "SMB_CPU1_PE_HP_GTL_R_SCL")
	)
	(segment
		(start 175.012096 -123.348496)
		(end 175.615854 -123.952254)
		(width 0.089408)
		(layer "In4.Cu")
		(net "SMB_CPU1_PE_HP_GTL_R_SCL")
	)
	(segment
		(start 174.206154 -94.414086)
		(end 174.206154 -98.867722)
		(width 0.089408)
		(layer "In4.Cu")
		(net "SMB_CPU1_PE_HP_GTL_R_SCL")
	)
	(segment
		(start 175.012096 -105.581704)
		(end 175.012096 -123.348496)
		(width 0.089408)
		(layer "In4.Cu")
		(net "SMB_CPU1_PE_HP_GTL_R_SCL")
	)
	(segment
		(start 175.670464 -100.332032)
		(end 175.670464 -104.923336)
		(width 0.089408)
		(layer "In4.Cu")
		(net "SMB_CPU1_PE_HP_GTL_R_SCL")
	)
	(segment
		(start 175.615854 -126.440946)
		(end 175.514 -126.5428)
		(width 0.089408)
		(layer "In4.Cu")
		(net "SMB_CPU1_PE_HP_GTL_R_SCL")
	)
	(segment
		(start 161.626804 -128.085088)
		(end 163.21786 -126.494032)
		(width 0.089408)
		(layer "In9.Cu")
		(net "SMB_CPU1_PE_HP_GTL_R_SCL")
	)
	(segment
		(start 147.558252 -123.310396)
		(end 152.332944 -128.085088)
		(width 0.089408)
		(layer "In9.Cu")
		(net "SMB_CPU1_PE_HP_GTL_R_SCL")
	)
	(segment
		(start 152.332944 -128.085088)
		(end 161.626804 -128.085088)
		(width 0.089408)
		(layer "In9.Cu")
		(net "SMB_CPU1_PE_HP_GTL_R_SCL")
	)
	(segment
		(start 165.51529 -127.280416)
		(end 167.78478 -127.280416)
		(width 0.089408)
		(layer "In9.Cu")
		(net "SMB_CPU1_PE_HP_GTL_R_SCL")
	)
	(segment
		(start 169.277792 -128.773428)
		(end 174.197772 -128.773428)
		(width 0.089408)
		(layer "In9.Cu")
		(net "SMB_CPU1_PE_HP_GTL_R_SCL")
	)
	(segment
		(start 163.21786 -126.494032)
		(end 164.728906 -126.494032)
		(width 0.089408)
		(layer "In9.Cu")
		(net "SMB_CPU1_PE_HP_GTL_R_SCL")
	)
	(segment
		(start 23.450804 -122.021092)
		(end 23.792688 -121.679208)
		(width 0.089408)
		(layer "In9.Cu")
		(net "SMB_CPU1_PE_HP_GTL_R_SCL")
	)
	(segment
		(start 174.197772 -128.773428)
		(end 175.1584 -127.8128)
		(width 0.089408)
		(layer "In9.Cu")
		(net "SMB_CPU1_PE_HP_GTL_R_SCL")
	)
	(segment
		(start 175.1584 -127.8128)
		(end 175.1584 -126.8984)
		(width 0.089408)
		(layer "In9.Cu")
		(net "SMB_CPU1_PE_HP_GTL_R_SCL")
	)
	(segment
		(start 23.792688 -121.679208)
		(end 24.448008 -121.679208)
		(width 0.089408)
		(layer "In9.Cu")
		(net "SMB_CPU1_PE_HP_GTL_R_SCL")
	)
	(segment
		(start 175.1584 -126.8984)
		(end 175.514 -126.5428)
		(width 0.089408)
		(layer "In9.Cu")
		(net "SMB_CPU1_PE_HP_GTL_R_SCL")
	)
	(segment
		(start 26.079196 -123.310396)
		(end 147.558252 -123.310396)
		(width 0.089408)
		(layer "In9.Cu")
		(net "SMB_CPU1_PE_HP_GTL_R_SCL")
	)
	(segment
		(start 167.78478 -127.280416)
		(end 169.277792 -128.773428)
		(width 0.089408)
		(layer "In9.Cu")
		(net "SMB_CPU1_PE_HP_GTL_R_SCL")
	)
	(segment
		(start 24.448008 -121.679208)
		(end 26.079196 -123.310396)
		(width 0.089408)
		(layer "In9.Cu")
		(net "SMB_CPU1_PE_HP_GTL_R_SCL")
	)
	(segment
		(start 164.728906 -126.494032)
		(end 165.51529 -127.280416)
		(width 0.089408)
		(layer "In9.Cu")
		(net "SMB_CPU1_PE_HP_GTL_R_SCL")
	)
	(segment
		(start 428.474886 -3.69824)
		(end 428.754286 -3.41884)
		(width 0.1143)
		(layer "F.Cu")
		(net "P3E_CPU0_PE1_SS_R_RXP<7>")
	)
	(segment
		(start 428.474886 -4.386072)
		(end 428.474886 -3.69824)
		(width 0.1143)
		(layer "F.Cu")
		(net "P3E_CPU0_PE1_SS_R_RXP<7>")
	)
	(segment
		(start 428.631604 -2.72415)
		(end 428.230792 -2.72415)
		(width 0.1143)
		(layer "F.Cu")
		(net "P3E_CPU0_PE1_SS_R_RXP<7>")
	)
	(segment
		(start 428.754286 -3.41884)
		(end 428.754286 -2.846832)
		(width 0.1143)
		(layer "F.Cu")
		(net "P3E_CPU0_PE1_SS_R_RXP<7>")
	)
	(segment
		(start 428.754286 -2.846832)
		(end 428.631604 -2.72415)
		(width 0.1143)
		(layer "F.Cu")
		(net "P3E_CPU0_PE1_SS_R_RXP<7>")
	)
	(via
		(at 353.5426 -58.957972)
		(size 0.508)
		(drill 0.254)
		(layers "F.Cu" "B.Cu")
		(net "P3E_CPU0_PE1_SS_R_RXP<7>")
	)
	(via
		(at 428.230792 -2.72415)
		(size 0.508)
		(drill 0.254)
		(layers "F.Cu" "B.Cu")
		(net "P3E_CPU0_PE1_SS_R_RXP<7>")
	)
	(segment
		(start 352.904806 -59.479434)
		(end 353.021138 -59.479434)
		(width 0.1143)
		(layer "B.Cu")
		(net "P3E_CPU0_PE1_SS_R_RXP<7>")
	)
	(segment
		(start 353.021138 -59.479434)
		(end 353.5426 -58.957972)
		(width 0.1143)
		(layer "B.Cu")
		(net "P3E_CPU0_PE1_SS_R_RXP<7>")
	)
	(segment
		(start 394.806424 -8.592566)
		(end 393.135612 -8.947912)
		(width 0.1143)
		(layer "In2.Cu")
		(net "P3E_CPU0_PE1_SS_R_RXP<7>")
	)
	(segment
		(start 428.575724 -2.72415)
		(end 428.719996 -2.868422)
		(width 0.1143)
		(layer "In2.Cu")
		(net "P3E_CPU0_PE1_SS_R_RXP<7>")
	)
	(segment
		(start 358.79786 -42.997628)
		(end 355.082094 -48.57369)
		(width 0.1143)
		(layer "In2.Cu")
		(net "P3E_CPU0_PE1_SS_R_RXP<7>")
	)
	(segment
		(start 353.375468 -57.656476)
		(end 354.09505 -58.681874)
		(width 0.1143)
		(layer "In2.Cu")
		(net "P3E_CPU0_PE1_SS_R_RXP<7>")
	)
	(segment
		(start 355.082094 -48.57369)
		(end 352.895662 -55.315104)
		(width 0.1143)
		(layer "In2.Cu")
		(net "P3E_CPU0_PE1_SS_R_RXP<7>")
	)
	(segment
		(start 406.781 -8.614156)
		(end 405.550624 -8.875522)
		(width 0.1143)
		(layer "In2.Cu")
		(net "P3E_CPU0_PE1_SS_R_RXP<7>")
	)
	(segment
		(start 427.845982 -5.96773)
		(end 426.719492 -6.71957)
		(width 0.1143)
		(layer "In2.Cu")
		(net "P3E_CPU0_PE1_SS_R_RXP<7>")
	)
	(segment
		(start 428.230792 -2.72415)
		(end 428.575724 -2.72415)
		(width 0.1143)
		(layer "In2.Cu")
		(net "P3E_CPU0_PE1_SS_R_RXP<7>")
	)
	(segment
		(start 393.135612 -8.947912)
		(end 392.185906 -8.746744)
		(width 0.1143)
		(layer "In2.Cu")
		(net "P3E_CPU0_PE1_SS_R_RXP<7>")
	)
	(segment
		(start 401.79879 -8.58647)
		(end 400.678904 -8.824214)
		(width 0.1143)
		(layer "In2.Cu")
		(net "P3E_CPU0_PE1_SS_R_RXP<7>")
	)
	(segment
		(start 354.09505 -58.843672)
		(end 353.98075 -58.957972)
		(width 0.1143)
		(layer "In2.Cu")
		(net "P3E_CPU0_PE1_SS_R_RXP<7>")
	)
	(segment
		(start 428.719996 -4.437126)
		(end 427.845982 -5.96773)
		(width 0.1143)
		(layer "In2.Cu")
		(net "P3E_CPU0_PE1_SS_R_RXP<7>")
	)
	(segment
		(start 398.1958 -8.82396)
		(end 396.953486 -8.560054)
		(width 0.1143)
		(layer "In2.Cu")
		(net "P3E_CPU0_PE1_SS_R_RXP<7>")
	)
	(segment
		(start 415.840926 -9.029954)
		(end 411.504384 -8.107934)
		(width 0.1143)
		(layer "In2.Cu")
		(net "P3E_CPU0_PE1_SS_R_RXP<7>")
	)
	(segment
		(start 360.927396 -34.799778)
		(end 360.225848 -35.852354)
		(width 0.1143)
		(layer "In2.Cu")
		(net "P3E_CPU0_PE1_SS_R_RXP<7>")
	)
	(segment
		(start 396.953486 -8.560054)
		(end 395.80312 -8.804402)
		(width 0.1143)
		(layer "In2.Cu")
		(net "P3E_CPU0_PE1_SS_R_RXP<7>")
	)
	(segment
		(start 395.80312 -8.804402)
		(end 394.806424 -8.592566)
		(width 0.1143)
		(layer "In2.Cu")
		(net "P3E_CPU0_PE1_SS_R_RXP<7>")
	)
	(segment
		(start 405.550624 -8.875522)
		(end 404.604728 -8.674608)
		(width 0.1143)
		(layer "In2.Cu")
		(net "P3E_CPU0_PE1_SS_R_RXP<7>")
	)
	(segment
		(start 403.40915 -8.928608)
		(end 401.79879 -8.58647)
		(width 0.1143)
		(layer "In2.Cu")
		(net "P3E_CPU0_PE1_SS_R_RXP<7>")
	)
	(segment
		(start 404.604728 -8.674608)
		(end 403.40915 -8.928608)
		(width 0.1143)
		(layer "In2.Cu")
		(net "P3E_CPU0_PE1_SS_R_RXP<7>")
	)
	(segment
		(start 353.98075 -58.957972)
		(end 353.5426 -58.957972)
		(width 0.1143)
		(layer "In2.Cu")
		(net "P3E_CPU0_PE1_SS_R_RXP<7>")
	)
	(segment
		(start 426.719492 -6.71957)
		(end 415.840926 -9.029954)
		(width 0.1143)
		(layer "In2.Cu")
		(net "P3E_CPU0_PE1_SS_R_RXP<7>")
	)
	(segment
		(start 392.185906 -8.746744)
		(end 378.986542 -11.552428)
		(width 0.1143)
		(layer "In2.Cu")
		(net "P3E_CPU0_PE1_SS_R_RXP<7>")
	)
	(segment
		(start 360.225848 -35.852354)
		(end 360.167682 -36.143438)
		(width 0.1143)
		(layer "In2.Cu")
		(net "P3E_CPU0_PE1_SS_R_RXP<7>")
	)
	(segment
		(start 399.43659 -8.560308)
		(end 398.1958 -8.82396)
		(width 0.1143)
		(layer "In2.Cu")
		(net "P3E_CPU0_PE1_SS_R_RXP<7>")
	)
	(segment
		(start 364.644432 -17.292066)
		(end 360.927396 -34.799778)
		(width 0.1143)
		(layer "In2.Cu")
		(net "P3E_CPU0_PE1_SS_R_RXP<7>")
	)
	(segment
		(start 360.167682 -36.143438)
		(end 358.79786 -42.997628)
		(width 0.1143)
		(layer "In2.Cu")
		(net "P3E_CPU0_PE1_SS_R_RXP<7>")
	)
	(segment
		(start 378.986542 -11.552428)
		(end 376.814334 -11.091672)
		(width 0.1143)
		(layer "In2.Cu")
		(net "P3E_CPU0_PE1_SS_R_RXP<7>")
	)
	(segment
		(start 400.678904 -8.824214)
		(end 399.43659 -8.560308)
		(width 0.1143)
		(layer "In2.Cu")
		(net "P3E_CPU0_PE1_SS_R_RXP<7>")
	)
	(segment
		(start 407.951178 -8.862822)
		(end 406.781 -8.614156)
		(width 0.1143)
		(layer "In2.Cu")
		(net "P3E_CPU0_PE1_SS_R_RXP<7>")
	)
	(segment
		(start 428.719996 -2.868422)
		(end 428.719996 -4.437126)
		(width 0.1143)
		(layer "In2.Cu")
		(net "P3E_CPU0_PE1_SS_R_RXP<7>")
	)
	(segment
		(start 352.895662 -55.315104)
		(end 353.375468 -57.656476)
		(width 0.1143)
		(layer "In2.Cu")
		(net "P3E_CPU0_PE1_SS_R_RXP<7>")
	)
	(segment
		(start 376.814334 -11.091672)
		(end 369.9002 -13.530072)
		(width 0.1143)
		(layer "In2.Cu")
		(net "P3E_CPU0_PE1_SS_R_RXP<7>")
	)
	(segment
		(start 369.9002 -13.530072)
		(end 364.644432 -17.292066)
		(width 0.1143)
		(layer "In2.Cu")
		(net "P3E_CPU0_PE1_SS_R_RXP<7>")
	)
	(segment
		(start 411.504384 -8.107934)
		(end 407.951178 -8.862822)
		(width 0.1143)
		(layer "In2.Cu")
		(net "P3E_CPU0_PE1_SS_R_RXP<7>")
	)
	(segment
		(start 354.09505 -58.681874)
		(end 354.09505 -58.843672)
		(width 0.1143)
		(layer "In2.Cu")
		(net "P3E_CPU0_PE1_SS_R_RXP<7>")
	)
	(segment
		(start 426.212762 -2.890774)
		(end 425.812712 -2.890774)
		(width 0.1143)
		(layer "F.Cu")
		(net "P3E_CPU0_PE1_SS_R_RXP<6>")
	)
	(segment
		(start 426.074586 -4.386072)
		(end 426.074586 -3.69824)
		(width 0.1143)
		(layer "F.Cu")
		(net "P3E_CPU0_PE1_SS_R_RXP<6>")
	)
	(segment
		(start 426.327062 -3.005074)
		(end 426.212762 -2.890774)
		(width 0.1143)
		(layer "F.Cu")
		(net "P3E_CPU0_PE1_SS_R_RXP<6>")
	)
	(segment
		(start 426.074586 -3.69824)
		(end 426.327062 -3.445764)
		(width 0.1143)
		(layer "F.Cu")
		(net "P3E_CPU0_PE1_SS_R_RXP<6>")
	)
	(segment
		(start 426.327062 -3.445764)
		(end 426.327062 -3.005074)
		(width 0.1143)
		(layer "F.Cu")
		(net "P3E_CPU0_PE1_SS_R_RXP<6>")
	)
	(via
		(at 425.812712 -2.890774)
		(size 0.508)
		(drill 0.254)
		(layers "F.Cu" "B.Cu")
		(net "P3E_CPU0_PE1_SS_R_RXP<6>")
	)
	(via
		(at 350.7486 -58.957972)
		(size 0.508)
		(drill 0.254)
		(layers "F.Cu" "B.Cu")
		(net "P3E_CPU0_PE1_SS_R_RXP<6>")
	)
	(segment
		(start 350.227138 -59.479434)
		(end 350.7486 -58.957972)
		(width 0.1143)
		(layer "B.Cu")
		(net "P3E_CPU0_PE1_SS_R_RXP<6>")
	)
	(segment
		(start 350.110806 -59.479434)
		(end 350.227138 -59.479434)
		(width 0.1143)
		(layer "B.Cu")
		(net "P3E_CPU0_PE1_SS_R_RXP<6>")
	)
	(segment
		(start 369.602512 -12.95908)
		(end 376.804936 -10.418572)
		(width 0.1143)
		(layer "In2.Cu")
		(net "P3E_CPU0_PE1_SS_R_RXP<6>")
	)
	(segment
		(start 358.200198 -42.664634)
		(end 359.613962 -35.60064)
		(width 0.1143)
		(layer "In2.Cu")
		(net "P3E_CPU0_PE1_SS_R_RXP<6>")
	)
	(segment
		(start 351.623122 -58.13044)
		(end 353.243388 -50.032158)
		(width 0.1143)
		(layer "In2.Cu")
		(net "P3E_CPU0_PE1_SS_R_RXP<6>")
	)
	(segment
		(start 396.953486 -7.90829)
		(end 398.1958 -8.172196)
		(width 0.1143)
		(layer "In2.Cu")
		(net "P3E_CPU0_PE1_SS_R_RXP<6>")
	)
	(segment
		(start 426.33265 -3.048)
		(end 426.175424 -2.890774)
		(width 0.1143)
		(layer "In2.Cu")
		(net "P3E_CPU0_PE1_SS_R_RXP<6>")
	)
	(segment
		(start 424.40733 -6.452616)
		(end 424.807126 -6.185662)
		(width 0.1143)
		(layer "In2.Cu")
		(net "P3E_CPU0_PE1_SS_R_RXP<6>")
	)
	(segment
		(start 407.951178 -8.211058)
		(end 411.503876 -7.456424)
		(width 0.1143)
		(layer "In2.Cu")
		(net "P3E_CPU0_PE1_SS_R_RXP<6>")
	)
	(segment
		(start 353.243388 -50.032158)
		(end 358.200198 -42.664634)
		(width 0.1143)
		(layer "In2.Cu")
		(net "P3E_CPU0_PE1_SS_R_RXP<6>")
	)
	(segment
		(start 376.804936 -10.418572)
		(end 379.00229 -10.884662)
		(width 0.1143)
		(layer "In2.Cu")
		(net "P3E_CPU0_PE1_SS_R_RXP<6>")
	)
	(segment
		(start 351.30105 -58.589418)
		(end 351.623122 -58.13044)
		(width 0.1143)
		(layer "In2.Cu")
		(net "P3E_CPU0_PE1_SS_R_RXP<6>")
	)
	(segment
		(start 350.7486 -58.957972)
		(end 351.18675 -58.957972)
		(width 0.1143)
		(layer "In2.Cu")
		(net "P3E_CPU0_PE1_SS_R_RXP<6>")
	)
	(segment
		(start 399.436336 -7.908544)
		(end 400.678904 -8.17245)
		(width 0.1143)
		(layer "In2.Cu")
		(net "P3E_CPU0_PE1_SS_R_RXP<6>")
	)
	(segment
		(start 351.30105 -58.843672)
		(end 351.30105 -58.589418)
		(width 0.1143)
		(layer "In2.Cu")
		(net "P3E_CPU0_PE1_SS_R_RXP<6>")
	)
	(segment
		(start 360.334052 -34.520124)
		(end 364.073948 -16.9164)
		(width 0.1143)
		(layer "In2.Cu")
		(net "P3E_CPU0_PE1_SS_R_RXP<6>")
	)
	(segment
		(start 406.76957 -7.959852)
		(end 407.951178 -8.211058)
		(width 0.1143)
		(layer "In2.Cu")
		(net "P3E_CPU0_PE1_SS_R_RXP<6>")
	)
	(segment
		(start 394.757656 -7.930642)
		(end 395.80312 -8.152638)
		(width 0.1143)
		(layer "In2.Cu")
		(net "P3E_CPU0_PE1_SS_R_RXP<6>")
	)
	(segment
		(start 411.503876 -7.456424)
		(end 415.592514 -8.325104)
		(width 0.1143)
		(layer "In2.Cu")
		(net "P3E_CPU0_PE1_SS_R_RXP<6>")
	)
	(segment
		(start 404.547832 -8.010652)
		(end 405.53894 -8.221218)
		(width 0.1143)
		(layer "In2.Cu")
		(net "P3E_CPU0_PE1_SS_R_RXP<6>")
	)
	(segment
		(start 400.678904 -8.17245)
		(end 401.79879 -7.934706)
		(width 0.1143)
		(layer "In2.Cu")
		(net "P3E_CPU0_PE1_SS_R_RXP<6>")
	)
	(segment
		(start 359.613962 -35.60064)
		(end 360.334052 -34.520124)
		(width 0.1143)
		(layer "In2.Cu")
		(net "P3E_CPU0_PE1_SS_R_RXP<6>")
	)
	(segment
		(start 403.352254 -8.264652)
		(end 404.547832 -8.010652)
		(width 0.1143)
		(layer "In2.Cu")
		(net "P3E_CPU0_PE1_SS_R_RXP<6>")
	)
	(segment
		(start 393.086082 -8.285734)
		(end 394.757656 -7.930642)
		(width 0.1143)
		(layer "In2.Cu")
		(net "P3E_CPU0_PE1_SS_R_RXP<6>")
	)
	(segment
		(start 392.15822 -8.08863)
		(end 393.086082 -8.285734)
		(width 0.1143)
		(layer "In2.Cu")
		(net "P3E_CPU0_PE1_SS_R_RXP<6>")
	)
	(segment
		(start 426.33265 -3.85953)
		(end 426.33265 -3.048)
		(width 0.1143)
		(layer "In2.Cu")
		(net "P3E_CPU0_PE1_SS_R_RXP<6>")
	)
	(segment
		(start 401.79879 -7.934706)
		(end 403.352254 -8.264652)
		(width 0.1143)
		(layer "In2.Cu")
		(net "P3E_CPU0_PE1_SS_R_RXP<6>")
	)
	(segment
		(start 379.00229 -10.884662)
		(end 392.15822 -8.08863)
		(width 0.1143)
		(layer "In2.Cu")
		(net "P3E_CPU0_PE1_SS_R_RXP<6>")
	)
	(segment
		(start 398.1958 -8.172196)
		(end 399.436336 -7.908544)
		(width 0.1143)
		(layer "In2.Cu")
		(net "P3E_CPU0_PE1_SS_R_RXP<6>")
	)
	(segment
		(start 424.807126 -6.185662)
		(end 426.33265 -3.85953)
		(width 0.1143)
		(layer "In2.Cu")
		(net "P3E_CPU0_PE1_SS_R_RXP<6>")
	)
	(segment
		(start 364.073948 -16.9164)
		(end 369.602512 -12.95908)
		(width 0.1143)
		(layer "In2.Cu")
		(net "P3E_CPU0_PE1_SS_R_RXP<6>")
	)
	(segment
		(start 415.592514 -8.325104)
		(end 424.40733 -6.452616)
		(width 0.1143)
		(layer "In2.Cu")
		(net "P3E_CPU0_PE1_SS_R_RXP<6>")
	)
	(segment
		(start 395.80312 -8.152638)
		(end 396.953486 -7.90829)
		(width 0.1143)
		(layer "In2.Cu")
		(net "P3E_CPU0_PE1_SS_R_RXP<6>")
	)
	(segment
		(start 351.18675 -58.957972)
		(end 351.30105 -58.843672)
		(width 0.1143)
		(layer "In2.Cu")
		(net "P3E_CPU0_PE1_SS_R_RXP<6>")
	)
	(segment
		(start 405.53894 -8.221218)
		(end 406.76957 -7.959852)
		(width 0.1143)
		(layer "In2.Cu")
		(net "P3E_CPU0_PE1_SS_R_RXP<6>")
	)
	(segment
		(start 426.175424 -2.890774)
		(end 425.812712 -2.890774)
		(width 0.1143)
		(layer "In2.Cu")
		(net "P3E_CPU0_PE1_SS_R_RXP<6>")
	)
	(segment
		(start 423.927016 -1.698244)
		(end 423.927016 -3.505454)
		(width 0.1143)
		(layer "F.Cu")
		(net "P3E_CPU0_PE1_SS_R_RXP<5>")
	)
	(segment
		(start 423.812716 -1.583944)
		(end 423.927016 -1.698244)
		(width 0.1143)
		(layer "F.Cu")
		(net "P3E_CPU0_PE1_SS_R_RXP<5>")
	)
	(segment
		(start 423.927016 -3.505454)
		(end 423.674286 -3.758184)
		(width 0.1143)
		(layer "F.Cu")
		(net "P3E_CPU0_PE1_SS_R_RXP<5>")
	)
	(segment
		(start 423.412666 -1.583944)
		(end 423.812716 -1.583944)
		(width 0.1143)
		(layer "F.Cu")
		(net "P3E_CPU0_PE1_SS_R_RXP<5>")
	)
	(segment
		(start 423.674286 -3.758184)
		(end 423.674286 -4.386072)
		(width 0.1143)
		(layer "F.Cu")
		(net "P3E_CPU0_PE1_SS_R_RXP<5>")
	)
	(via
		(at 423.412666 -1.583944)
		(size 0.508)
		(drill 0.254)
		(layers "F.Cu" "B.Cu")
		(net "P3E_CPU0_PE1_SS_R_RXP<5>")
	)
	(via
		(at 347.9546 -58.957972)
		(size 0.508)
		(drill 0.254)
		(layers "F.Cu" "B.Cu")
		(net "P3E_CPU0_PE1_SS_R_RXP<5>")
	)
	(segment
		(start 347.316806 -59.479434)
		(end 347.433138 -59.479434)
		(width 0.1143)
		(layer "B.Cu")
		(net "P3E_CPU0_PE1_SS_R_RXP<5>")
	)
	(segment
		(start 347.433138 -59.479434)
		(end 347.9546 -58.957972)
		(width 0.1143)
		(layer "B.Cu")
		(net "P3E_CPU0_PE1_SS_R_RXP<5>")
	)
	(segment
		(start 423.66946 -5.643626)
		(end 423.9514 -4.982972)
		(width 0.1143)
		(layer "In2.Cu")
		(net "P3E_CPU0_PE1_SS_R_RXP<5>")
	)
	(segment
		(start 405.52116 -7.565898)
		(end 406.751536 -7.304532)
		(width 0.1143)
		(layer "In2.Cu")
		(net "P3E_CPU0_PE1_SS_R_RXP<5>")
	)
	(segment
		(start 363.502448 -16.54175)
		(end 369.304824 -12.387834)
		(width 0.1143)
		(layer "In2.Cu")
		(net "P3E_CPU0_PE1_SS_R_RXP<5>")
	)
	(segment
		(start 394.691362 -7.264654)
		(end 395.80312 -7.500874)
		(width 0.1143)
		(layer "In2.Cu")
		(net "P3E_CPU0_PE1_SS_R_RXP<5>")
	)
	(segment
		(start 398.1958 -7.520432)
		(end 399.436336 -7.25678)
		(width 0.1143)
		(layer "In2.Cu")
		(net "P3E_CPU0_PE1_SS_R_RXP<5>")
	)
	(segment
		(start 359.024682 -35.292284)
		(end 359.75036 -34.203132)
		(width 0.1143)
		(layer "In2.Cu")
		(net "P3E_CPU0_PE1_SS_R_RXP<5>")
	)
	(segment
		(start 369.304824 -12.387834)
		(end 376.809254 -9.741154)
		(width 0.1143)
		(layer "In2.Cu")
		(net "P3E_CPU0_PE1_SS_R_RXP<5>")
	)
	(segment
		(start 393.02309 -7.619238)
		(end 394.691362 -7.264654)
		(width 0.1143)
		(layer "In2.Cu")
		(net "P3E_CPU0_PE1_SS_R_RXP<5>")
	)
	(segment
		(start 401.79879 -7.282942)
		(end 403.320504 -7.606284)
		(width 0.1143)
		(layer "In2.Cu")
		(net "P3E_CPU0_PE1_SS_R_RXP<5>")
	)
	(segment
		(start 348.50705 -58.230516)
		(end 350.539304 -55.325772)
		(width 0.1143)
		(layer "In2.Cu")
		(net "P3E_CPU0_PE1_SS_R_RXP<5>")
	)
	(segment
		(start 395.80312 -7.500874)
		(end 396.953486 -7.256526)
		(width 0.1143)
		(layer "In2.Cu")
		(net "P3E_CPU0_PE1_SS_R_RXP<5>")
	)
	(segment
		(start 399.436336 -7.25678)
		(end 400.678904 -7.520686)
		(width 0.1143)
		(layer "In2.Cu")
		(net "P3E_CPU0_PE1_SS_R_RXP<5>")
	)
	(segment
		(start 423.9514 -1.7272)
		(end 423.808144 -1.583944)
		(width 0.1143)
		(layer "In2.Cu")
		(net "P3E_CPU0_PE1_SS_R_RXP<5>")
	)
	(segment
		(start 357.650288 -42.162476)
		(end 359.024682 -35.292284)
		(width 0.1143)
		(layer "In2.Cu")
		(net "P3E_CPU0_PE1_SS_R_RXP<5>")
	)
	(segment
		(start 411.50413 -6.80466)
		(end 415.546794 -7.663688)
		(width 0.1143)
		(layer "In2.Cu")
		(net "P3E_CPU0_PE1_SS_R_RXP<5>")
	)
	(segment
		(start 350.539304 -55.325772)
		(end 351.249488 -51.773582)
		(width 0.1143)
		(layer "In2.Cu")
		(net "P3E_CPU0_PE1_SS_R_RXP<5>")
	)
	(segment
		(start 403.320504 -7.606284)
		(end 404.515828 -7.352284)
		(width 0.1143)
		(layer "In2.Cu")
		(net "P3E_CPU0_PE1_SS_R_RXP<5>")
	)
	(segment
		(start 407.951178 -7.559294)
		(end 411.50413 -6.80466)
		(width 0.1143)
		(layer "In2.Cu")
		(net "P3E_CPU0_PE1_SS_R_RXP<5>")
	)
	(segment
		(start 423.9514 -4.982972)
		(end 423.9514 -1.7272)
		(width 0.1143)
		(layer "In2.Cu")
		(net "P3E_CPU0_PE1_SS_R_RXP<5>")
	)
	(segment
		(start 415.546794 -7.663688)
		(end 423.021506 -6.076188)
		(width 0.1143)
		(layer "In2.Cu")
		(net "P3E_CPU0_PE1_SS_R_RXP<5>")
	)
	(segment
		(start 348.39275 -58.957972)
		(end 348.50705 -58.843672)
		(width 0.1143)
		(layer "In2.Cu")
		(net "P3E_CPU0_PE1_SS_R_RXP<5>")
	)
	(segment
		(start 347.9546 -58.957972)
		(end 348.39275 -58.957972)
		(width 0.1143)
		(layer "In2.Cu")
		(net "P3E_CPU0_PE1_SS_R_RXP<5>")
	)
	(segment
		(start 423.808144 -1.583944)
		(end 423.412666 -1.583944)
		(width 0.1143)
		(layer "In2.Cu")
		(net "P3E_CPU0_PE1_SS_R_RXP<5>")
	)
	(segment
		(start 400.678904 -7.520686)
		(end 401.79879 -7.282942)
		(width 0.1143)
		(layer "In2.Cu")
		(net "P3E_CPU0_PE1_SS_R_RXP<5>")
	)
	(segment
		(start 406.751536 -7.304532)
		(end 407.951178 -7.559294)
		(width 0.1143)
		(layer "In2.Cu")
		(net "P3E_CPU0_PE1_SS_R_RXP<5>")
	)
	(segment
		(start 404.515828 -7.352284)
		(end 405.52116 -7.565898)
		(width 0.1143)
		(layer "In2.Cu")
		(net "P3E_CPU0_PE1_SS_R_RXP<5>")
	)
	(segment
		(start 348.50705 -58.843672)
		(end 348.50705 -58.230516)
		(width 0.1143)
		(layer "In2.Cu")
		(net "P3E_CPU0_PE1_SS_R_RXP<5>")
	)
	(segment
		(start 392.138408 -7.431786)
		(end 393.02309 -7.619238)
		(width 0.1143)
		(layer "In2.Cu")
		(net "P3E_CPU0_PE1_SS_R_RXP<5>")
	)
	(segment
		(start 359.75036 -34.203132)
		(end 363.502448 -16.54175)
		(width 0.1143)
		(layer "In2.Cu")
		(net "P3E_CPU0_PE1_SS_R_RXP<5>")
	)
	(segment
		(start 351.249488 -51.773582)
		(end 357.650288 -42.162476)
		(width 0.1143)
		(layer "In2.Cu")
		(net "P3E_CPU0_PE1_SS_R_RXP<5>")
	)
	(segment
		(start 396.953486 -7.256526)
		(end 398.1958 -7.520432)
		(width 0.1143)
		(layer "In2.Cu")
		(net "P3E_CPU0_PE1_SS_R_RXP<5>")
	)
	(segment
		(start 423.021506 -6.076188)
		(end 423.66946 -5.643626)
		(width 0.1143)
		(layer "In2.Cu")
		(net "P3E_CPU0_PE1_SS_R_RXP<5>")
	)
	(segment
		(start 379.039628 -10.214356)
		(end 392.138408 -7.431786)
		(width 0.1143)
		(layer "In2.Cu")
		(net "P3E_CPU0_PE1_SS_R_RXP<5>")
	)
	(segment
		(start 376.809254 -9.741154)
		(end 379.039628 -10.214356)
		(width 0.1143)
		(layer "In2.Cu")
		(net "P3E_CPU0_PE1_SS_R_RXP<5>")
	)
	(segment
		(start 421.513 -3.459226)
		(end 421.273986 -3.69824)
		(width 0.1143)
		(layer "F.Cu")
		(net "P3E_CPU0_PE1_SS_R_RXP<4>")
	)
	(segment
		(start 421.513 -2.793746)
		(end 421.513 -3.459226)
		(width 0.1143)
		(layer "F.Cu")
		(net "P3E_CPU0_PE1_SS_R_RXP<4>")
	)
	(segment
		(start 421.324786 -2.605532)
		(end 421.513 -2.793746)
		(width 0.1143)
		(layer "F.Cu")
		(net "P3E_CPU0_PE1_SS_R_RXP<4>")
	)
	(segment
		(start 420.971726 -2.605532)
		(end 421.324786 -2.605532)
		(width 0.1143)
		(layer "F.Cu")
		(net "P3E_CPU0_PE1_SS_R_RXP<4>")
	)
	(segment
		(start 421.273986 -3.69824)
		(end 421.273986 -4.386072)
		(width 0.1143)
		(layer "F.Cu")
		(net "P3E_CPU0_PE1_SS_R_RXP<4>")
	)
	(via
		(at 420.971726 -2.605532)
		(size 0.508)
		(drill 0.254)
		(layers "F.Cu" "B.Cu")
		(net "P3E_CPU0_PE1_SS_R_RXP<4>")
	)
	(via
		(at 345.1606 -58.957972)
		(size 0.508)
		(drill 0.254)
		(layers "F.Cu" "B.Cu")
		(net "P3E_CPU0_PE1_SS_R_RXP<4>")
	)
	(segment
		(start 344.639138 -59.479434)
		(end 345.1606 -58.957972)
		(width 0.1143)
		(layer "B.Cu")
		(net "P3E_CPU0_PE1_SS_R_RXP<4>")
	)
	(segment
		(start 344.522806 -59.479434)
		(end 344.639138 -59.479434)
		(width 0.1143)
		(layer "B.Cu")
		(net "P3E_CPU0_PE1_SS_R_RXP<4>")
	)
	(segment
		(start 404.856442 -6.630416)
		(end 405.844248 -6.840474)
		(width 0.1143)
		(layer "In2.Cu")
		(net "P3E_CPU0_PE1_SS_R_RXP<4>")
	)
	(segment
		(start 345.1606 -58.957972)
		(end 345.567254 -58.957972)
		(width 0.1143)
		(layer "In2.Cu")
		(net "P3E_CPU0_PE1_SS_R_RXP<4>")
	)
	(segment
		(start 400.679158 -6.868922)
		(end 401.821396 -6.626352)
		(width 0.1143)
		(layer "In2.Cu")
		(net "P3E_CPU0_PE1_SS_R_RXP<4>")
	)
	(segment
		(start 395.80312 -6.84911)
		(end 396.953486 -6.604762)
		(width 0.1143)
		(layer "In2.Cu")
		(net "P3E_CPU0_PE1_SS_R_RXP<4>")
	)
	(segment
		(start 350.624902 -51.482498)
		(end 357.051102 -41.847262)
		(width 0.1143)
		(layer "In2.Cu")
		(net "P3E_CPU0_PE1_SS_R_RXP<4>")
	)
	(segment
		(start 406.757124 -6.646672)
		(end 407.96845 -6.90372)
		(width 0.1143)
		(layer "In2.Cu")
		(net "P3E_CPU0_PE1_SS_R_RXP<4>")
	)
	(segment
		(start 415.534856 -7.009384)
		(end 417.947094 -6.497066)
		(width 0.1143)
		(layer "In2.Cu")
		(net "P3E_CPU0_PE1_SS_R_RXP<4>")
	)
	(segment
		(start 394.679932 -6.610604)
		(end 395.80312 -6.84911)
		(width 0.1143)
		(layer "In2.Cu")
		(net "P3E_CPU0_PE1_SS_R_RXP<4>")
	)
	(segment
		(start 345.567254 -58.957972)
		(end 345.681554 -58.843672)
		(width 0.1143)
		(layer "In2.Cu")
		(net "P3E_CPU0_PE1_SS_R_RXP<4>")
	)
	(segment
		(start 421.518842 -2.749296)
		(end 421.375078 -2.605532)
		(width 0.1143)
		(layer "In2.Cu")
		(net "P3E_CPU0_PE1_SS_R_RXP<4>")
	)
	(segment
		(start 396.953486 -6.604762)
		(end 398.1958 -6.868668)
		(width 0.1143)
		(layer "In2.Cu")
		(net "P3E_CPU0_PE1_SS_R_RXP<4>")
	)
	(segment
		(start 399.43659 -6.605016)
		(end 400.679158 -6.868922)
		(width 0.1143)
		(layer "In2.Cu")
		(net "P3E_CPU0_PE1_SS_R_RXP<4>")
	)
	(segment
		(start 393.028932 -6.961378)
		(end 394.679932 -6.610604)
		(width 0.1143)
		(layer "In2.Cu")
		(net "P3E_CPU0_PE1_SS_R_RXP<4>")
	)
	(segment
		(start 411.503622 -6.152896)
		(end 415.534856 -7.009384)
		(width 0.1143)
		(layer "In2.Cu")
		(net "P3E_CPU0_PE1_SS_R_RXP<4>")
	)
	(segment
		(start 345.831414 -58.384948)
		(end 347.217238 -56.999124)
		(width 0.1143)
		(layer "In2.Cu")
		(net "P3E_CPU0_PE1_SS_R_RXP<4>")
	)
	(segment
		(start 376.768614 -9.078976)
		(end 379.004068 -9.553194)
		(width 0.1143)
		(layer "In2.Cu")
		(net "P3E_CPU0_PE1_SS_R_RXP<4>")
	)
	(segment
		(start 350.009968 -54.55666)
		(end 350.624902 -51.482498)
		(width 0.1143)
		(layer "In2.Cu")
		(net "P3E_CPU0_PE1_SS_R_RXP<4>")
	)
	(segment
		(start 359.187496 -33.784286)
		(end 362.930694 -16.1671)
		(width 0.1143)
		(layer "In2.Cu")
		(net "P3E_CPU0_PE1_SS_R_RXP<4>")
	)
	(segment
		(start 358.441244 -34.904172)
		(end 359.187496 -33.784286)
		(width 0.1143)
		(layer "In2.Cu")
		(net "P3E_CPU0_PE1_SS_R_RXP<4>")
	)
	(segment
		(start 421.375078 -2.605532)
		(end 420.971726 -2.605532)
		(width 0.1143)
		(layer "In2.Cu")
		(net "P3E_CPU0_PE1_SS_R_RXP<4>")
	)
	(segment
		(start 348.560644 -56.730646)
		(end 350.009968 -54.55666)
		(width 0.1143)
		(layer "In2.Cu")
		(net "P3E_CPU0_PE1_SS_R_RXP<4>")
	)
	(segment
		(start 403.348952 -6.950964)
		(end 404.856442 -6.630416)
		(width 0.1143)
		(layer "In2.Cu")
		(net "P3E_CPU0_PE1_SS_R_RXP<4>")
	)
	(segment
		(start 379.004068 -9.553194)
		(end 392.112246 -6.767068)
		(width 0.1143)
		(layer "In2.Cu")
		(net "P3E_CPU0_PE1_SS_R_RXP<4>")
	)
	(segment
		(start 407.96845 -6.90372)
		(end 411.503622 -6.152896)
		(width 0.1143)
		(layer "In2.Cu")
		(net "P3E_CPU0_PE1_SS_R_RXP<4>")
	)
	(segment
		(start 417.947094 -6.497066)
		(end 421.353996 -4.608068)
		(width 0.1143)
		(layer "In2.Cu")
		(net "P3E_CPU0_PE1_SS_R_RXP<4>")
	)
	(segment
		(start 357.051102 -41.847262)
		(end 358.441244 -34.904172)
		(width 0.1143)
		(layer "In2.Cu")
		(net "P3E_CPU0_PE1_SS_R_RXP<4>")
	)
	(segment
		(start 392.112246 -6.767068)
		(end 393.028932 -6.961378)
		(width 0.1143)
		(layer "In2.Cu")
		(net "P3E_CPU0_PE1_SS_R_RXP<4>")
	)
	(segment
		(start 362.930694 -16.1671)
		(end 369.008406 -11.81608)
		(width 0.1143)
		(layer "In2.Cu")
		(net "P3E_CPU0_PE1_SS_R_RXP<4>")
	)
	(segment
		(start 345.681554 -58.843672)
		(end 345.681554 -58.60161)
		(width 0.1143)
		(layer "In2.Cu")
		(net "P3E_CPU0_PE1_SS_R_RXP<4>")
	)
	(segment
		(start 369.008406 -11.81608)
		(end 376.768614 -9.078976)
		(width 0.1143)
		(layer "In2.Cu")
		(net "P3E_CPU0_PE1_SS_R_RXP<4>")
	)
	(segment
		(start 405.844248 -6.840474)
		(end 406.757124 -6.646672)
		(width 0.1143)
		(layer "In2.Cu")
		(net "P3E_CPU0_PE1_SS_R_RXP<4>")
	)
	(segment
		(start 421.518842 -4.261612)
		(end 421.518842 -2.749296)
		(width 0.1143)
		(layer "In2.Cu")
		(net "P3E_CPU0_PE1_SS_R_RXP<4>")
	)
	(segment
		(start 398.1958 -6.868668)
		(end 399.43659 -6.605016)
		(width 0.1143)
		(layer "In2.Cu")
		(net "P3E_CPU0_PE1_SS_R_RXP<4>")
	)
	(segment
		(start 345.681554 -58.60161)
		(end 345.831414 -58.384948)
		(width 0.1143)
		(layer "In2.Cu")
		(net "P3E_CPU0_PE1_SS_R_RXP<4>")
	)
	(segment
		(start 421.353996 -4.608068)
		(end 421.518842 -4.261612)
		(width 0.1143)
		(layer "In2.Cu")
		(net "P3E_CPU0_PE1_SS_R_RXP<4>")
	)
	(segment
		(start 347.217238 -56.999124)
		(end 348.560644 -56.730646)
		(width 0.1143)
		(layer "In2.Cu")
		(net "P3E_CPU0_PE1_SS_R_RXP<4>")
	)
	(segment
		(start 401.821396 -6.626352)
		(end 403.348952 -6.950964)
		(width 0.1143)
		(layer "In2.Cu")
		(net "P3E_CPU0_PE1_SS_R_RXP<4>")
	)
	(segment
		(start 418.873686 -3.758184)
		(end 418.873686 -4.386072)
		(width 0.1143)
		(layer "F.Cu")
		(net "P3E_CPU0_PE1_SS_R_RXP<3>")
	)
	(segment
		(start 419.153086 -3.478784)
		(end 418.873686 -3.758184)
		(width 0.1143)
		(layer "F.Cu")
		(net "P3E_CPU0_PE1_SS_R_RXP<3>")
	)
	(segment
		(start 419.298628 -1.723136)
		(end 419.298628 -2.351024)
		(width 0.1143)
		(layer "F.Cu")
		(net "P3E_CPU0_PE1_SS_R_RXP<3>")
	)
	(segment
		(start 418.781992 -1.60655)
		(end 419.182042 -1.60655)
		(width 0.1143)
		(layer "F.Cu")
		(net "P3E_CPU0_PE1_SS_R_RXP<3>")
	)
	(segment
		(start 419.298628 -2.351024)
		(end 419.153086 -2.496566)
		(width 0.1143)
		(layer "F.Cu")
		(net "P3E_CPU0_PE1_SS_R_RXP<3>")
	)
	(segment
		(start 419.153086 -2.496566)
		(end 419.153086 -3.478784)
		(width 0.1143)
		(layer "F.Cu")
		(net "P3E_CPU0_PE1_SS_R_RXP<3>")
	)
	(segment
		(start 419.182042 -1.60655)
		(end 419.298628 -1.723136)
		(width 0.1143)
		(layer "F.Cu")
		(net "P3E_CPU0_PE1_SS_R_RXP<3>")
	)
	(via
		(at 418.781992 -1.60655)
		(size 0.508)
		(drill 0.254)
		(layers "F.Cu" "B.Cu")
		(net "P3E_CPU0_PE1_SS_R_RXP<3>")
	)
	(via
		(at 342.3666 -58.957972)
		(size 0.508)
		(drill 0.254)
		(layers "F.Cu" "B.Cu")
		(net "P3E_CPU0_PE1_SS_R_RXP<3>")
	)
	(segment
		(start 341.728806 -59.479434)
		(end 341.845138 -59.479434)
		(width 0.1143)
		(layer "B.Cu")
		(net "P3E_CPU0_PE1_SS_R_RXP<3>")
	)
	(segment
		(start 341.845138 -59.479434)
		(end 342.3666 -58.957972)
		(width 0.1143)
		(layer "B.Cu")
		(net "P3E_CPU0_PE1_SS_R_RXP<3>")
	)
	(segment
		(start 418.749734 -5.014722)
		(end 419.118542 -4.147566)
		(width 0.1143)
		(layer "In2.Cu")
		(net "P3E_CPU0_PE1_SS_R_RXP<3>")
	)
	(segment
		(start 410.428948 -5.729478)
		(end 411.503368 -5.501132)
		(width 0.1143)
		(layer "In2.Cu")
		(net "P3E_CPU0_PE1_SS_R_RXP<3>")
	)
	(segment
		(start 371.60581 -10.187686)
		(end 373.054372 -8.145018)
		(width 0.1143)
		(layer "In2.Cu")
		(net "P3E_CPU0_PE1_SS_R_RXP<3>")
	)
	(segment
		(start 366.959134 -11.827002)
		(end 371.60581 -10.187686)
		(width 0.1143)
		(layer "In2.Cu")
		(net "P3E_CPU0_PE1_SS_R_RXP<3>")
	)
	(segment
		(start 400.75739 -5.857494)
		(end 400.760184 -5.856986)
		(width 0.1143)
		(layer "In2.Cu")
		(net "P3E_CPU0_PE1_SS_R_RXP<3>")
	)
	(segment
		(start 354.3935 -44.6024)
		(end 354.3935 -38.291008)
		(width 0.1143)
		(layer "In2.Cu")
		(net "P3E_CPU0_PE1_SS_R_RXP<3>")
	)
	(segment
		(start 394.016738 -5.299202)
		(end 394.68171 -5.16636)
		(width 0.1143)
		(layer "In2.Cu")
		(net "P3E_CPU0_PE1_SS_R_RXP<3>")
	)
	(segment
		(start 355.239066 -37.022024)
		(end 355.331522 -36.93414)
		(width 0.1143)
		(layer "In2.Cu")
		(net "P3E_CPU0_PE1_SS_R_RXP<3>")
	)
	(segment
		(start 342.91905 -58.843672)
		(end 342.91905 -58.570622)
		(width 0.1143)
		(layer "In2.Cu")
		(net "P3E_CPU0_PE1_SS_R_RXP<3>")
	)
	(segment
		(start 393.01547 -5.08635)
		(end 394.016738 -5.299202)
		(width 0.1143)
		(layer "In2.Cu")
		(net "P3E_CPU0_PE1_SS_R_RXP<3>")
	)
	(segment
		(start 392.426698 -5.211826)
		(end 393.01547 -5.08635)
		(width 0.1143)
		(layer "In2.Cu")
		(net "P3E_CPU0_PE1_SS_R_RXP<3>")
	)
	(segment
		(start 419.118542 -2.20345)
		(end 419.321742 -2.00025)
		(width 0.1143)
		(layer "In2.Cu")
		(net "P3E_CPU0_PE1_SS_R_RXP<3>")
	)
	(segment
		(start 377.37796 -6.909308)
		(end 382.50241 -5.784342)
		(width 0.1143)
		(layer "In2.Cu")
		(net "P3E_CPU0_PE1_SS_R_RXP<3>")
	)
	(segment
		(start 419.321742 -2.00025)
		(end 419.321742 -1.72085)
		(width 0.1143)
		(layer "In2.Cu")
		(net "P3E_CPU0_PE1_SS_R_RXP<3>")
	)
	(segment
		(start 405.89708 -4.766564)
		(end 410.428948 -5.729478)
		(width 0.1143)
		(layer "In2.Cu")
		(net "P3E_CPU0_PE1_SS_R_RXP<3>")
	)
	(segment
		(start 343.119202 -58.143394)
		(end 345.399614 -56.623204)
		(width 0.1143)
		(layer "In2.Cu")
		(net "P3E_CPU0_PE1_SS_R_RXP<3>")
	)
	(segment
		(start 354.3935 -38.291008)
		(end 355.239066 -37.022024)
		(width 0.1143)
		(layer "In2.Cu")
		(net "P3E_CPU0_PE1_SS_R_RXP<3>")
	)
	(segment
		(start 350.018096 -51.16703)
		(end 354.3935 -44.6024)
		(width 0.1143)
		(layer "In2.Cu")
		(net "P3E_CPU0_PE1_SS_R_RXP<3>")
	)
	(segment
		(start 419.118542 -4.147566)
		(end 419.118542 -2.20345)
		(width 0.1143)
		(layer "In2.Cu")
		(net "P3E_CPU0_PE1_SS_R_RXP<3>")
	)
	(segment
		(start 348.191328 -56.059832)
		(end 349.402654 -54.243478)
		(width 0.1143)
		(layer "In2.Cu")
		(net "P3E_CPU0_PE1_SS_R_RXP<3>")
	)
	(segment
		(start 356.859078 -36.01339)
		(end 358.598724 -33.403032)
		(width 0.1143)
		(layer "In2.Cu")
		(net "P3E_CPU0_PE1_SS_R_RXP<3>")
	)
	(segment
		(start 411.503368 -5.501132)
		(end 415.491168 -6.348222)
		(width 0.1143)
		(layer "In2.Cu")
		(net "P3E_CPU0_PE1_SS_R_RXP<3>")
	)
	(segment
		(start 342.91905 -58.570622)
		(end 343.119202 -58.143394)
		(width 0.1143)
		(layer "In2.Cu")
		(net "P3E_CPU0_PE1_SS_R_RXP<3>")
	)
	(segment
		(start 382.50241 -5.784342)
		(end 384.335782 -4.878832)
		(width 0.1143)
		(layer "In2.Cu")
		(net "P3E_CPU0_PE1_SS_R_RXP<3>")
	)
	(segment
		(start 416.91687 -6.045454)
		(end 418.749734 -5.014722)
		(width 0.1143)
		(layer "In2.Cu")
		(net "P3E_CPU0_PE1_SS_R_RXP<3>")
	)
	(segment
		(start 373.054372 -8.145018)
		(end 377.37796 -6.909308)
		(width 0.1143)
		(layer "In2.Cu")
		(net "P3E_CPU0_PE1_SS_R_RXP<3>")
	)
	(segment
		(start 355.331522 -36.93414)
		(end 356.859078 -36.01339)
		(width 0.1143)
		(layer "In2.Cu")
		(net "P3E_CPU0_PE1_SS_R_RXP<3>")
	)
	(segment
		(start 384.966464 -5.00507)
		(end 387.730492 -4.215384)
		(width 0.1143)
		(layer "In2.Cu")
		(net "P3E_CPU0_PE1_SS_R_RXP<3>")
	)
	(segment
		(start 358.598724 -33.403032)
		(end 362.504228 -15.015464)
		(width 0.1143)
		(layer "In2.Cu")
		(net "P3E_CPU0_PE1_SS_R_RXP<3>")
	)
	(segment
		(start 400.761454 -5.856478)
		(end 405.89708 -4.766564)
		(width 0.1143)
		(layer "In2.Cu")
		(net "P3E_CPU0_PE1_SS_R_RXP<3>")
	)
	(segment
		(start 342.80475 -58.957972)
		(end 342.91905 -58.843672)
		(width 0.1143)
		(layer "In2.Cu")
		(net "P3E_CPU0_PE1_SS_R_RXP<3>")
	)
	(segment
		(start 397.741648 -5.257038)
		(end 400.75104 -5.858764)
		(width 0.1143)
		(layer "In2.Cu")
		(net "P3E_CPU0_PE1_SS_R_RXP<3>")
	)
	(segment
		(start 345.399614 -56.623204)
		(end 348.191328 -56.059832)
		(width 0.1143)
		(layer "In2.Cu")
		(net "P3E_CPU0_PE1_SS_R_RXP<3>")
	)
	(segment
		(start 419.207442 -1.60655)
		(end 418.781992 -1.60655)
		(width 0.1143)
		(layer "In2.Cu")
		(net "P3E_CPU0_PE1_SS_R_RXP<3>")
	)
	(segment
		(start 400.75104 -5.858764)
		(end 400.75739 -5.857494)
		(width 0.1143)
		(layer "In2.Cu")
		(net "P3E_CPU0_PE1_SS_R_RXP<3>")
	)
	(segment
		(start 362.504228 -15.015464)
		(end 366.959134 -11.827002)
		(width 0.1143)
		(layer "In2.Cu")
		(net "P3E_CPU0_PE1_SS_R_RXP<3>")
	)
	(segment
		(start 349.402654 -54.243478)
		(end 350.018096 -51.16703)
		(width 0.1143)
		(layer "In2.Cu")
		(net "P3E_CPU0_PE1_SS_R_RXP<3>")
	)
	(segment
		(start 419.321742 -1.72085)
		(end 419.207442 -1.60655)
		(width 0.1143)
		(layer "In2.Cu")
		(net "P3E_CPU0_PE1_SS_R_RXP<3>")
	)
	(segment
		(start 400.761454 -5.856732)
		(end 400.761454 -5.856478)
		(width 0.1143)
		(layer "In2.Cu")
		(net "P3E_CPU0_PE1_SS_R_RXP<3>")
	)
	(segment
		(start 342.3666 -58.957972)
		(end 342.80475 -58.957972)
		(width 0.1143)
		(layer "In2.Cu")
		(net "P3E_CPU0_PE1_SS_R_RXP<3>")
	)
	(segment
		(start 400.760184 -5.856986)
		(end 400.761454 -5.856732)
		(width 0.1143)
		(layer "In2.Cu")
		(net "P3E_CPU0_PE1_SS_R_RXP<3>")
	)
	(segment
		(start 387.730492 -4.215384)
		(end 392.426698 -5.211826)
		(width 0.1143)
		(layer "In2.Cu")
		(net "P3E_CPU0_PE1_SS_R_RXP<3>")
	)
	(segment
		(start 415.491168 -6.348222)
		(end 416.91687 -6.045454)
		(width 0.1143)
		(layer "In2.Cu")
		(net "P3E_CPU0_PE1_SS_R_RXP<3>")
	)
	(segment
		(start 394.68171 -5.16636)
		(end 396.43812 -5.517642)
		(width 0.1143)
		(layer "In2.Cu")
		(net "P3E_CPU0_PE1_SS_R_RXP<3>")
	)
	(segment
		(start 384.335782 -4.878832)
		(end 384.966464 -5.00507)
		(width 0.1143)
		(layer "In2.Cu")
		(net "P3E_CPU0_PE1_SS_R_RXP<3>")
	)
	(segment
		(start 396.43812 -5.517642)
		(end 397.741648 -5.257038)
		(width 0.1143)
		(layer "In2.Cu")
		(net "P3E_CPU0_PE1_SS_R_RXP<3>")
	)
	(segment
		(start 416.473386 -3.683)
		(end 416.473386 -4.386072)
		(width 0.1143)
		(layer "F.Cu")
		(net "P3E_CPU0_PE1_SS_R_RXP<2>")
	)
	(segment
		(start 416.617658 -2.82067)
		(end 416.783012 -2.986024)
		(width 0.1143)
		(layer "F.Cu")
		(net "P3E_CPU0_PE1_SS_R_RXP<2>")
	)
	(segment
		(start 416.27171 -2.82067)
		(end 416.617658 -2.82067)
		(width 0.1143)
		(layer "F.Cu")
		(net "P3E_CPU0_PE1_SS_R_RXP<2>")
	)
	(segment
		(start 416.783012 -3.373374)
		(end 416.473386 -3.683)
		(width 0.1143)
		(layer "F.Cu")
		(net "P3E_CPU0_PE1_SS_R_RXP<2>")
	)
	(segment
		(start 416.783012 -2.986024)
		(end 416.783012 -3.373374)
		(width 0.1143)
		(layer "F.Cu")
		(net "P3E_CPU0_PE1_SS_R_RXP<2>")
	)
	(via
		(at 416.27171 -2.82067)
		(size 0.508)
		(drill 0.254)
		(layers "F.Cu" "B.Cu")
		(net "P3E_CPU0_PE1_SS_R_RXP<2>")
	)
	(via
		(at 339.5726 -58.957972)
		(size 0.508)
		(drill 0.254)
		(layers "F.Cu" "B.Cu")
		(net "P3E_CPU0_PE1_SS_R_RXP<2>")
	)
	(segment
		(start 338.934806 -59.479434)
		(end 339.051138 -59.479434)
		(width 0.1143)
		(layer "B.Cu")
		(net "P3E_CPU0_PE1_SS_R_RXP<2>")
	)
	(segment
		(start 339.051138 -59.479434)
		(end 339.5726 -58.957972)
		(width 0.1143)
		(layer "B.Cu")
		(net "P3E_CPU0_PE1_SS_R_RXP<2>")
	)
	(segment
		(start 347.562678 -55.408068)
		(end 348.786704 -53.57114)
		(width 0.1143)
		(layer "In2.Cu")
		(net "P3E_CPU0_PE1_SS_R_RXP<2>")
	)
	(segment
		(start 405.905208 -4.102862)
		(end 410.391864 -5.05587)
		(width 0.1143)
		(layer "In2.Cu")
		(net "P3E_CPU0_PE1_SS_R_RXP<2>")
	)
	(segment
		(start 396.479776 -4.831842)
		(end 397.558768 -4.615942)
		(width 0.1143)
		(layer "In2.Cu")
		(net "P3E_CPU0_PE1_SS_R_RXP<2>")
	)
	(segment
		(start 397.558768 -4.615942)
		(end 397.708882 -4.58597)
		(width 0.1143)
		(layer "In2.Cu")
		(net "P3E_CPU0_PE1_SS_R_RXP<2>")
	)
	(segment
		(start 372.49735 -7.605268)
		(end 379.95098 -5.475732)
		(width 0.1143)
		(layer "In2.Cu")
		(net "P3E_CPU0_PE1_SS_R_RXP<2>")
	)
	(segment
		(start 340.104222 -58.843418)
		(end 340.104222 -58.13044)
		(width 0.1143)
		(layer "In2.Cu")
		(net "P3E_CPU0_PE1_SS_R_RXP<2>")
	)
	(segment
		(start 394.013944 -4.634484)
		(end 394.753338 -4.486656)
		(width 0.1143)
		(layer "In2.Cu")
		(net "P3E_CPU0_PE1_SS_R_RXP<2>")
	)
	(segment
		(start 412.8516 -4.5339)
		(end 414.67151 -4.5339)
		(width 0.1143)
		(layer "In2.Cu")
		(net "P3E_CPU0_PE1_SS_R_RXP<2>")
	)
	(segment
		(start 392.879072 -4.393438)
		(end 394.013944 -4.634484)
		(width 0.1143)
		(layer "In2.Cu")
		(net "P3E_CPU0_PE1_SS_R_RXP<2>")
	)
	(segment
		(start 339.989668 -58.957972)
		(end 340.104222 -58.843418)
		(width 0.1143)
		(layer "In2.Cu")
		(net "P3E_CPU0_PE1_SS_R_RXP<2>")
	)
	(segment
		(start 414.83661 -4.3688)
		(end 415.17951 -4.3688)
		(width 0.1143)
		(layer "In2.Cu")
		(net "P3E_CPU0_PE1_SS_R_RXP<2>")
	)
	(segment
		(start 379.95098 -5.475732)
		(end 380.436882 -4.746752)
		(width 0.1143)
		(layer "In2.Cu")
		(net "P3E_CPU0_PE1_SS_R_RXP<2>")
	)
	(segment
		(start 410.391864 -5.05587)
		(end 412.8516 -4.5339)
		(width 0.1143)
		(layer "In2.Cu")
		(net "P3E_CPU0_PE1_SS_R_RXP<2>")
	)
	(segment
		(start 349.322898 -51.001676)
		(end 349.323152 -51.001676)
		(width 0.1143)
		(layer "In2.Cu")
		(net "P3E_CPU0_PE1_SS_R_RXP<2>")
	)
	(segment
		(start 349.323152 -51.001676)
		(end 353.7585 -44.3484)
		(width 0.1143)
		(layer "In2.Cu")
		(net "P3E_CPU0_PE1_SS_R_RXP<2>")
	)
	(segment
		(start 416.547808 -4.140708)
		(end 416.729672 -3.958844)
		(width 0.1143)
		(layer "In2.Cu")
		(net "P3E_CPU0_PE1_SS_R_RXP<2>")
	)
	(segment
		(start 340.585298 -57.165494)
		(end 341.36076 -56.617362)
		(width 0.1143)
		(layer "In2.Cu")
		(net "P3E_CPU0_PE1_SS_R_RXP<2>")
	)
	(segment
		(start 415.17951 -4.3688)
		(end 415.34461 -4.5339)
		(width 0.1143)
		(layer "In2.Cu")
		(net "P3E_CPU0_PE1_SS_R_RXP<2>")
	)
	(segment
		(start 382.59639 -3.791458)
		(end 385.123944 -4.296918)
		(width 0.1143)
		(layer "In2.Cu")
		(net "P3E_CPU0_PE1_SS_R_RXP<2>")
	)
	(segment
		(start 397.708882 -4.58597)
		(end 397.70939 -4.58597)
		(width 0.1143)
		(layer "In2.Cu")
		(net "P3E_CPU0_PE1_SS_R_RXP<2>")
	)
	(segment
		(start 371.240812 -9.488424)
		(end 372.49735 -7.605268)
		(width 0.1143)
		(layer "In2.Cu")
		(net "P3E_CPU0_PE1_SS_R_RXP<2>")
	)
	(segment
		(start 349.291148 -51.049682)
		(end 349.322898 -51.001676)
		(width 0.1143)
		(layer "In2.Cu")
		(net "P3E_CPU0_PE1_SS_R_RXP<2>")
	)
	(segment
		(start 394.753338 -4.486656)
		(end 396.479776 -4.831842)
		(width 0.1143)
		(layer "In2.Cu")
		(net "P3E_CPU0_PE1_SS_R_RXP<2>")
	)
	(segment
		(start 381.558038 -3.99923)
		(end 382.59639 -3.791458)
		(width 0.1143)
		(layer "In2.Cu")
		(net "P3E_CPU0_PE1_SS_R_RXP<2>")
	)
	(segment
		(start 353.7585 -44.3484)
		(end 353.7585 -38.074854)
		(width 0.1143)
		(layer "In2.Cu")
		(net "P3E_CPU0_PE1_SS_R_RXP<2>")
	)
	(segment
		(start 415.34461 -4.5339)
		(end 415.68751 -4.5339)
		(width 0.1143)
		(layer "In2.Cu")
		(net "P3E_CPU0_PE1_SS_R_RXP<2>")
	)
	(segment
		(start 392.464036 -4.51485)
		(end 392.879072 -4.393438)
		(width 0.1143)
		(layer "In2.Cu")
		(net "P3E_CPU0_PE1_SS_R_RXP<2>")
	)
	(segment
		(start 339.5726 -58.957972)
		(end 339.989668 -58.957972)
		(width 0.1143)
		(layer "In2.Cu")
		(net "P3E_CPU0_PE1_SS_R_RXP<2>")
	)
	(segment
		(start 400.757644 -5.195824)
		(end 405.905208 -4.102862)
		(width 0.1143)
		(layer "In2.Cu")
		(net "P3E_CPU0_PE1_SS_R_RXP<2>")
	)
	(segment
		(start 414.67151 -4.5339)
		(end 414.83661 -4.3688)
		(width 0.1143)
		(layer "In2.Cu")
		(net "P3E_CPU0_PE1_SS_R_RXP<2>")
	)
	(segment
		(start 361.933236 -14.64056)
		(end 367.306352 -10.794238)
		(width 0.1143)
		(layer "In2.Cu")
		(net "P3E_CPU0_PE1_SS_R_RXP<2>")
	)
	(segment
		(start 416.729672 -2.93497)
		(end 416.615372 -2.82067)
		(width 0.1143)
		(layer "In2.Cu")
		(net "P3E_CPU0_PE1_SS_R_RXP<2>")
	)
	(segment
		(start 416.615372 -2.82067)
		(end 416.27171 -2.82067)
		(width 0.1143)
		(layer "In2.Cu")
		(net "P3E_CPU0_PE1_SS_R_RXP<2>")
	)
	(segment
		(start 340.104222 -58.13044)
		(end 340.585298 -57.165494)
		(width 0.1143)
		(layer "In2.Cu")
		(net "P3E_CPU0_PE1_SS_R_RXP<2>")
	)
	(segment
		(start 341.36076 -56.617362)
		(end 347.562678 -55.408068)
		(width 0.1143)
		(layer "In2.Cu")
		(net "P3E_CPU0_PE1_SS_R_RXP<2>")
	)
	(segment
		(start 385.123944 -4.296918)
		(end 387.814312 -3.52806)
		(width 0.1143)
		(layer "In2.Cu")
		(net "P3E_CPU0_PE1_SS_R_RXP<2>")
	)
	(segment
		(start 387.814312 -3.52806)
		(end 392.464036 -4.51485)
		(width 0.1143)
		(layer "In2.Cu")
		(net "P3E_CPU0_PE1_SS_R_RXP<2>")
	)
	(segment
		(start 397.70939 -4.58597)
		(end 400.757644 -5.195824)
		(width 0.1143)
		(layer "In2.Cu")
		(net "P3E_CPU0_PE1_SS_R_RXP<2>")
	)
	(segment
		(start 358.00665 -33.122108)
		(end 361.933236 -14.64056)
		(width 0.1143)
		(layer "In2.Cu")
		(net "P3E_CPU0_PE1_SS_R_RXP<2>")
	)
	(segment
		(start 415.68751 -4.5339)
		(end 416.547808 -4.140708)
		(width 0.1143)
		(layer "In2.Cu")
		(net "P3E_CPU0_PE1_SS_R_RXP<2>")
	)
	(segment
		(start 354.834952 -36.459414)
		(end 356.416864 -35.506406)
		(width 0.1143)
		(layer "In2.Cu")
		(net "P3E_CPU0_PE1_SS_R_RXP<2>")
	)
	(segment
		(start 367.306352 -10.794238)
		(end 371.240812 -9.488424)
		(width 0.1143)
		(layer "In2.Cu")
		(net "P3E_CPU0_PE1_SS_R_RXP<2>")
	)
	(segment
		(start 356.416864 -35.506406)
		(end 358.00665 -33.122108)
		(width 0.1143)
		(layer "In2.Cu")
		(net "P3E_CPU0_PE1_SS_R_RXP<2>")
	)
	(segment
		(start 348.786704 -53.57114)
		(end 349.291148 -51.049682)
		(width 0.1143)
		(layer "In2.Cu")
		(net "P3E_CPU0_PE1_SS_R_RXP<2>")
	)
	(segment
		(start 416.729672 -3.958844)
		(end 416.729672 -2.93497)
		(width 0.1143)
		(layer "In2.Cu")
		(net "P3E_CPU0_PE1_SS_R_RXP<2>")
	)
	(segment
		(start 380.436882 -4.746752)
		(end 381.558038 -3.99923)
		(width 0.1143)
		(layer "In2.Cu")
		(net "P3E_CPU0_PE1_SS_R_RXP<2>")
	)
	(segment
		(start 353.7585 -38.074854)
		(end 354.834952 -36.459414)
		(width 0.1143)
		(layer "In2.Cu")
		(net "P3E_CPU0_PE1_SS_R_RXP<2>")
	)
	(segment
		(start 414.328356 -3.42265)
		(end 414.328356 -1.858264)
		(width 0.1143)
		(layer "F.Cu")
		(net "P3E_CPU0_PE1_SS_R_RXP<1>")
	)
	(segment
		(start 414.328356 -1.858264)
		(end 414.203642 -1.73355)
		(width 0.1143)
		(layer "F.Cu")
		(net "P3E_CPU0_PE1_SS_R_RXP<1>")
	)
	(segment
		(start 414.203642 -1.73355)
		(end 413.803592 -1.73355)
		(width 0.1143)
		(layer "F.Cu")
		(net "P3E_CPU0_PE1_SS_R_RXP<1>")
	)
	(segment
		(start 414.073086 -4.386072)
		(end 414.073086 -3.67792)
		(width 0.1143)
		(layer "F.Cu")
		(net "P3E_CPU0_PE1_SS_R_RXP<1>")
	)
	(segment
		(start 414.073086 -3.67792)
		(end 414.328356 -3.42265)
		(width 0.1143)
		(layer "F.Cu")
		(net "P3E_CPU0_PE1_SS_R_RXP<1>")
	)
	(via
		(at 336.7786 -58.957972)
		(size 0.508)
		(drill 0.254)
		(layers "F.Cu" "B.Cu")
		(net "P3E_CPU0_PE1_SS_R_RXP<1>")
	)
	(via
		(at 413.803592 -1.73355)
		(size 0.508)
		(drill 0.254)
		(layers "F.Cu" "B.Cu")
		(net "P3E_CPU0_PE1_SS_R_RXP<1>")
	)
	(segment
		(start 336.257138 -59.479434)
		(end 336.7786 -58.957972)
		(width 0.1143)
		(layer "B.Cu")
		(net "P3E_CPU0_PE1_SS_R_RXP<1>")
	)
	(segment
		(start 336.140806 -59.479434)
		(end 336.257138 -59.479434)
		(width 0.1143)
		(layer "B.Cu")
		(net "P3E_CPU0_PE1_SS_R_RXP<1>")
	)
	(segment
		(start 410.399992 -4.404614)
		(end 413.966152 -3.647948)
		(width 0.1143)
		(layer "In2.Cu")
		(net "P3E_CPU0_PE1_SS_R_RXP<1>")
	)
	(segment
		(start 340.294468 -56.110886)
		(end 347.12656 -54.776624)
		(width 0.1143)
		(layer "In2.Cu")
		(net "P3E_CPU0_PE1_SS_R_RXP<1>")
	)
	(segment
		(start 352.2853 -45.294296)
		(end 352.2853 -38.979602)
		(width 0.1143)
		(layer "In2.Cu")
		(net "P3E_CPU0_PE1_SS_R_RXP<1>")
	)
	(segment
		(start 348.580456 -50.851816)
		(end 352.2853 -45.294296)
		(width 0.1143)
		(layer "In2.Cu")
		(net "P3E_CPU0_PE1_SS_R_RXP<1>")
	)
	(segment
		(start 397.558768 -3.924046)
		(end 397.63954 -3.908044)
		(width 0.1143)
		(layer "In2.Cu")
		(net "P3E_CPU0_PE1_SS_R_RXP<1>")
	)
	(segment
		(start 385.51866 -3.519678)
		(end 387.804406 -2.866644)
		(width 0.1143)
		(layer "In2.Cu")
		(net "P3E_CPU0_PE1_SS_R_RXP<1>")
	)
	(segment
		(start 369.353084 -9.349486)
		(end 370.860828 -7.379716)
		(width 0.1143)
		(layer "In2.Cu")
		(net "P3E_CPU0_PE1_SS_R_RXP<1>")
	)
	(segment
		(start 396.504922 -4.134104)
		(end 397.558768 -3.924046)
		(width 0.1143)
		(layer "In2.Cu")
		(net "P3E_CPU0_PE1_SS_R_RXP<1>")
	)
	(segment
		(start 400.75612 -4.525518)
		(end 405.895302 -3.44678)
		(width 0.1143)
		(layer "In2.Cu")
		(net "P3E_CPU0_PE1_SS_R_RXP<1>")
	)
	(segment
		(start 397.63954 -3.908044)
		(end 400.735546 -4.52755)
		(width 0.1143)
		(layer "In2.Cu")
		(net "P3E_CPU0_PE1_SS_R_RXP<1>")
	)
	(segment
		(start 394.86713 -3.806698)
		(end 396.504922 -4.134104)
		(width 0.1143)
		(layer "In2.Cu")
		(net "P3E_CPU0_PE1_SS_R_RXP<1>")
	)
	(segment
		(start 405.895302 -3.44678)
		(end 410.399992 -4.404614)
		(width 0.1143)
		(layer "In2.Cu")
		(net "P3E_CPU0_PE1_SS_R_RXP<1>")
	)
	(segment
		(start 400.735546 -4.52755)
		(end 400.75612 -4.525518)
		(width 0.1143)
		(layer "In2.Cu")
		(net "P3E_CPU0_PE1_SS_R_RXP<1>")
	)
	(segment
		(start 347.12656 -54.776624)
		(end 348.083632 -53.34254)
		(width 0.1143)
		(layer "In2.Cu")
		(net "P3E_CPU0_PE1_SS_R_RXP<1>")
	)
	(segment
		(start 394.010642 -3.978148)
		(end 394.86713 -3.806698)
		(width 0.1143)
		(layer "In2.Cu")
		(net "P3E_CPU0_PE1_SS_R_RXP<1>")
	)
	(segment
		(start 337.33105 -58.843672)
		(end 337.33105 -58.477404)
		(width 0.1143)
		(layer "In2.Cu")
		(net "P3E_CPU0_PE1_SS_R_RXP<1>")
	)
	(segment
		(start 379.85446 -4.248658)
		(end 381.381 -3.23088)
		(width 0.1143)
		(layer "In2.Cu")
		(net "P3E_CPU0_PE1_SS_R_RXP<1>")
	)
	(segment
		(start 414.127442 -1.73355)
		(end 413.803592 -1.73355)
		(width 0.1143)
		(layer "In2.Cu")
		(net "P3E_CPU0_PE1_SS_R_RXP<1>")
	)
	(segment
		(start 392.441176 -3.85191)
		(end 392.850116 -3.731514)
		(width 0.1143)
		(layer "In2.Cu")
		(net "P3E_CPU0_PE1_SS_R_RXP<1>")
	)
	(segment
		(start 337.33105 -58.477404)
		(end 337.602322 -58.050684)
		(width 0.1143)
		(layer "In2.Cu")
		(net "P3E_CPU0_PE1_SS_R_RXP<1>")
	)
	(segment
		(start 361.361482 -14.265656)
		(end 367.2586 -10.04443)
		(width 0.1143)
		(layer "In2.Cu")
		(net "P3E_CPU0_PE1_SS_R_RXP<1>")
	)
	(segment
		(start 413.966152 -3.647948)
		(end 414.241742 -3.307842)
		(width 0.1143)
		(layer "In2.Cu")
		(net "P3E_CPU0_PE1_SS_R_RXP<1>")
	)
	(segment
		(start 338.455508 -57.23255)
		(end 338.733638 -57.03189)
		(width 0.1143)
		(layer "In2.Cu")
		(net "P3E_CPU0_PE1_SS_R_RXP<1>")
	)
	(segment
		(start 352.2853 -38.979602)
		(end 354.32746 -35.9156)
		(width 0.1143)
		(layer "In2.Cu")
		(net "P3E_CPU0_PE1_SS_R_RXP<1>")
	)
	(segment
		(start 381.381 -3.23088)
		(end 382.727708 -2.961386)
		(width 0.1143)
		(layer "In2.Cu")
		(net "P3E_CPU0_PE1_SS_R_RXP<1>")
	)
	(segment
		(start 354.32746 -35.9156)
		(end 356.036626 -34.885376)
		(width 0.1143)
		(layer "In2.Cu")
		(net "P3E_CPU0_PE1_SS_R_RXP<1>")
	)
	(segment
		(start 336.7786 -58.957972)
		(end 337.21675 -58.957972)
		(width 0.1143)
		(layer "In2.Cu")
		(net "P3E_CPU0_PE1_SS_R_RXP<1>")
	)
	(segment
		(start 379.392688 -4.941316)
		(end 379.85446 -4.248658)
		(width 0.1143)
		(layer "In2.Cu")
		(net "P3E_CPU0_PE1_SS_R_RXP<1>")
	)
	(segment
		(start 357.42118 -32.807148)
		(end 361.361482 -14.265656)
		(width 0.1143)
		(layer "In2.Cu")
		(net "P3E_CPU0_PE1_SS_R_RXP<1>")
	)
	(segment
		(start 338.733638 -57.03189)
		(end 338.96427 -57.069482)
		(width 0.1143)
		(layer "In2.Cu")
		(net "P3E_CPU0_PE1_SS_R_RXP<1>")
	)
	(segment
		(start 367.2586 -10.04443)
		(end 369.353084 -9.349486)
		(width 0.1143)
		(layer "In2.Cu")
		(net "P3E_CPU0_PE1_SS_R_RXP<1>")
	)
	(segment
		(start 337.602322 -58.050684)
		(end 338.417916 -57.462928)
		(width 0.1143)
		(layer "In2.Cu")
		(net "P3E_CPU0_PE1_SS_R_RXP<1>")
	)
	(segment
		(start 392.850116 -3.731514)
		(end 394.010642 -3.978148)
		(width 0.1143)
		(layer "In2.Cu")
		(net "P3E_CPU0_PE1_SS_R_RXP<1>")
	)
	(segment
		(start 356.036626 -34.885376)
		(end 357.42118 -32.807148)
		(width 0.1143)
		(layer "In2.Cu")
		(net "P3E_CPU0_PE1_SS_R_RXP<1>")
	)
	(segment
		(start 387.804406 -2.866644)
		(end 392.441176 -3.85191)
		(width 0.1143)
		(layer "In2.Cu")
		(net "P3E_CPU0_PE1_SS_R_RXP<1>")
	)
	(segment
		(start 382.727708 -2.961386)
		(end 385.51866 -3.519678)
		(width 0.1143)
		(layer "In2.Cu")
		(net "P3E_CPU0_PE1_SS_R_RXP<1>")
	)
	(segment
		(start 414.241742 -3.307842)
		(end 414.241742 -1.84785)
		(width 0.1143)
		(layer "In2.Cu")
		(net "P3E_CPU0_PE1_SS_R_RXP<1>")
	)
	(segment
		(start 338.417916 -57.462928)
		(end 338.455508 -57.23255)
		(width 0.1143)
		(layer "In2.Cu")
		(net "P3E_CPU0_PE1_SS_R_RXP<1>")
	)
	(segment
		(start 338.96427 -57.069482)
		(end 340.294468 -56.110886)
		(width 0.1143)
		(layer "In2.Cu")
		(net "P3E_CPU0_PE1_SS_R_RXP<1>")
	)
	(segment
		(start 337.21675 -58.957972)
		(end 337.33105 -58.843672)
		(width 0.1143)
		(layer "In2.Cu")
		(net "P3E_CPU0_PE1_SS_R_RXP<1>")
	)
	(segment
		(start 348.083632 -53.34254)
		(end 348.580456 -50.851816)
		(width 0.1143)
		(layer "In2.Cu")
		(net "P3E_CPU0_PE1_SS_R_RXP<1>")
	)
	(segment
		(start 414.241742 -1.84785)
		(end 414.127442 -1.73355)
		(width 0.1143)
		(layer "In2.Cu")
		(net "P3E_CPU0_PE1_SS_R_RXP<1>")
	)
	(segment
		(start 370.860828 -7.379716)
		(end 379.392688 -4.941316)
		(width 0.1143)
		(layer "In2.Cu")
		(net "P3E_CPU0_PE1_SS_R_RXP<1>")
	)
	(segment
		(start 411.952186 -2.9972)
		(end 411.686756 -2.73177)
		(width 0.1143)
		(layer "F.Cu")
		(net "P3E_CPU0_PE1_SS_R_RXP<0>")
	)
	(segment
		(start 411.952186 -3.41884)
		(end 411.952186 -2.9972)
		(width 0.1143)
		(layer "F.Cu")
		(net "P3E_CPU0_PE1_SS_R_RXP<0>")
	)
	(segment
		(start 411.672786 -4.386072)
		(end 411.672786 -3.69824)
		(width 0.1143)
		(layer "F.Cu")
		(net "P3E_CPU0_PE1_SS_R_RXP<0>")
	)
	(segment
		(start 411.686756 -2.73177)
		(end 411.428692 -2.73177)
		(width 0.1143)
		(layer "F.Cu")
		(net "P3E_CPU0_PE1_SS_R_RXP<0>")
	)
	(segment
		(start 411.672786 -3.69824)
		(end 411.952186 -3.41884)
		(width 0.1143)
		(layer "F.Cu")
		(net "P3E_CPU0_PE1_SS_R_RXP<0>")
	)
	(via
		(at 333.9846 -58.957972)
		(size 0.508)
		(drill 0.254)
		(layers "F.Cu" "B.Cu")
		(net "P3E_CPU0_PE1_SS_R_RXP<0>")
	)
	(via
		(at 411.428692 -2.73177)
		(size 0.508)
		(drill 0.254)
		(layers "F.Cu" "B.Cu")
		(net "P3E_CPU0_PE1_SS_R_RXP<0>")
	)
	(segment
		(start 333.463138 -59.479434)
		(end 333.9846 -58.957972)
		(width 0.1143)
		(layer "B.Cu")
		(net "P3E_CPU0_PE1_SS_R_RXP<0>")
	)
	(segment
		(start 333.346806 -59.479434)
		(end 333.463138 -59.479434)
		(width 0.1143)
		(layer "B.Cu")
		(net "P3E_CPU0_PE1_SS_R_RXP<0>")
	)
	(segment
		(start 336.027776 -57.266078)
		(end 336.07375 -57.037224)
		(width 0.1143)
		(layer "In2.Cu")
		(net "P3E_CPU0_PE1_SS_R_RXP<0>")
	)
	(segment
		(start 411.866842 -2.84607)
		(end 411.752542 -2.73177)
		(width 0.1143)
		(layer "In2.Cu")
		(net "P3E_CPU0_PE1_SS_R_RXP<0>")
	)
	(segment
		(start 400.094958 -2.183638)
		(end 404.69058 -1.208532)
		(width 0.1143)
		(layer "In2.Cu")
		(net "P3E_CPU0_PE1_SS_R_RXP<0>")
	)
	(segment
		(start 336.07375 -57.037224)
		(end 336.358992 -56.846978)
		(width 0.1143)
		(layer "In2.Cu")
		(net "P3E_CPU0_PE1_SS_R_RXP<0>")
	)
	(segment
		(start 411.866842 -3.041904)
		(end 411.866842 -2.84607)
		(width 0.1143)
		(layer "In2.Cu")
		(net "P3E_CPU0_PE1_SS_R_RXP<0>")
	)
	(segment
		(start 351.0407 -45.643292)
		(end 351.0407 -36.617656)
		(width 0.1143)
		(layer "In2.Cu")
		(net "P3E_CPU0_PE1_SS_R_RXP<0>")
	)
	(segment
		(start 379.101096 -3.076702)
		(end 379.10135 -3.076956)
		(width 0.1143)
		(layer "In2.Cu")
		(net "P3E_CPU0_PE1_SS_R_RXP<0>")
	)
	(segment
		(start 337.718908 -56.138826)
		(end 337.719924 -56.138318)
		(width 0.1143)
		(layer "In2.Cu")
		(net "P3E_CPU0_PE1_SS_R_RXP<0>")
	)
	(segment
		(start 391.36828 -1.570736)
		(end 392.531854 -1.818132)
		(width 0.1143)
		(layer "In2.Cu")
		(net "P3E_CPU0_PE1_SS_R_RXP<0>")
	)
	(segment
		(start 334.42275 -58.957972)
		(end 334.53705 -58.843672)
		(width 0.1143)
		(layer "In2.Cu")
		(net "P3E_CPU0_PE1_SS_R_RXP<0>")
	)
	(segment
		(start 336.587846 -56.892698)
		(end 337.718908 -56.138826)
		(width 0.1143)
		(layer "In2.Cu")
		(net "P3E_CPU0_PE1_SS_R_RXP<0>")
	)
	(segment
		(start 385.596638 -2.516124)
		(end 387.48208 -2.139696)
		(width 0.1143)
		(layer "In2.Cu")
		(net "P3E_CPU0_PE1_SS_R_RXP<0>")
	)
	(segment
		(start 404.69058 -1.208532)
		(end 408.372818 -1.990852)
		(width 0.1143)
		(layer "In2.Cu")
		(net "P3E_CPU0_PE1_SS_R_RXP<0>")
	)
	(segment
		(start 333.9846 -58.957972)
		(end 334.42275 -58.957972)
		(width 0.1143)
		(layer "In2.Cu")
		(net "P3E_CPU0_PE1_SS_R_RXP<0>")
	)
	(segment
		(start 411.530292 -3.378454)
		(end 411.866842 -3.041904)
		(width 0.1143)
		(layer "In2.Cu")
		(net "P3E_CPU0_PE1_SS_R_RXP<0>")
	)
	(segment
		(start 346.280486 -53.965348)
		(end 346.618052 -52.279804)
		(width 0.1143)
		(layer "In2.Cu")
		(net "P3E_CPU0_PE1_SS_R_RXP<0>")
	)
	(segment
		(start 360.788204 -13.892022)
		(end 366.780064 -9.60247)
		(width 0.1143)
		(layer "In2.Cu")
		(net "P3E_CPU0_PE1_SS_R_RXP<0>")
	)
	(segment
		(start 396.948914 -2.023364)
		(end 398.144492 -1.769364)
		(width 0.1143)
		(layer "In2.Cu")
		(net "P3E_CPU0_PE1_SS_R_RXP<0>")
	)
	(segment
		(start 356.904798 -32.172402)
		(end 360.788204 -13.892022)
		(width 0.1143)
		(layer "In2.Cu")
		(net "P3E_CPU0_PE1_SS_R_RXP<0>")
	)
	(segment
		(start 366.780064 -9.60247)
		(end 367.328196 -8.77951)
		(width 0.1143)
		(layer "In2.Cu")
		(net "P3E_CPU0_PE1_SS_R_RXP<0>")
	)
	(segment
		(start 334.78978 -58.091324)
		(end 336.027776 -57.266078)
		(width 0.1143)
		(layer "In2.Cu")
		(net "P3E_CPU0_PE1_SS_R_RXP<0>")
	)
	(segment
		(start 380.681992 -1.809242)
		(end 381.371856 -1.671066)
		(width 0.1143)
		(layer "In2.Cu")
		(net "P3E_CPU0_PE1_SS_R_RXP<0>")
	)
	(segment
		(start 346.650056 -52.231798)
		(end 351.0407 -45.643292)
		(width 0.1143)
		(layer "In2.Cu")
		(net "P3E_CPU0_PE1_SS_R_RXP<0>")
	)
	(segment
		(start 351.415096 -35.983672)
		(end 354.235766 -34.887916)
		(width 0.1143)
		(layer "In2.Cu")
		(net "P3E_CPU0_PE1_SS_R_RXP<0>")
	)
	(segment
		(start 339.748622 -55.53583)
		(end 346.054426 -54.304692)
		(width 0.1143)
		(layer "In2.Cu")
		(net "P3E_CPU0_PE1_SS_R_RXP<0>")
	)
	(segment
		(start 339.2678 -55.8292)
		(end 339.691218 -55.547006)
		(width 0.1143)
		(layer "In2.Cu")
		(net "P3E_CPU0_PE1_SS_R_RXP<0>")
	)
	(segment
		(start 408.372818 -1.990852)
		(end 410.013912 -3.6322)
		(width 0.1143)
		(layer "In2.Cu")
		(net "P3E_CPU0_PE1_SS_R_RXP<0>")
	)
	(segment
		(start 398.144492 -1.769364)
		(end 400.094958 -2.183638)
		(width 0.1143)
		(layer "In2.Cu")
		(net "P3E_CPU0_PE1_SS_R_RXP<0>")
	)
	(segment
		(start 387.48208 -2.139696)
		(end 388.103872 -2.264156)
		(width 0.1143)
		(layer "In2.Cu")
		(net "P3E_CPU0_PE1_SS_R_RXP<0>")
	)
	(segment
		(start 355.672136 -34.02203)
		(end 356.904798 -32.172402)
		(width 0.1143)
		(layer "In2.Cu")
		(net "P3E_CPU0_PE1_SS_R_RXP<0>")
	)
	(segment
		(start 392.531854 -1.818132)
		(end 394.257022 -1.45161)
		(width 0.1143)
		(layer "In2.Cu")
		(net "P3E_CPU0_PE1_SS_R_RXP<0>")
	)
	(segment
		(start 379.357382 -2.692654)
		(end 380.681992 -1.809242)
		(width 0.1143)
		(layer "In2.Cu")
		(net "P3E_CPU0_PE1_SS_R_RXP<0>")
	)
	(segment
		(start 410.769562 -3.6322)
		(end 411.530292 -3.378454)
		(width 0.1143)
		(layer "In2.Cu")
		(net "P3E_CPU0_PE1_SS_R_RXP<0>")
	)
	(segment
		(start 379.069092 -3.124962)
		(end 379.101096 -3.076702)
		(width 0.1143)
		(layer "In2.Cu")
		(net "P3E_CPU0_PE1_SS_R_RXP<0>")
	)
	(segment
		(start 378.404628 -4.536948)
		(end 378.950728 -3.717544)
		(width 0.1143)
		(layer "In2.Cu")
		(net "P3E_CPU0_PE1_SS_R_RXP<0>")
	)
	(segment
		(start 339.691218 -55.547006)
		(end 339.748368 -55.53583)
		(width 0.1143)
		(layer "In2.Cu")
		(net "P3E_CPU0_PE1_SS_R_RXP<0>")
	)
	(segment
		(start 339.748368 -55.53583)
		(end 339.748622 -55.53583)
		(width 0.1143)
		(layer "In2.Cu")
		(net "P3E_CPU0_PE1_SS_R_RXP<0>")
	)
	(segment
		(start 336.358992 -56.846978)
		(end 336.587846 -56.892698)
		(width 0.1143)
		(layer "In2.Cu")
		(net "P3E_CPU0_PE1_SS_R_RXP<0>")
	)
	(segment
		(start 354.235766 -34.887916)
		(end 355.672136 -34.02203)
		(width 0.1143)
		(layer "In2.Cu")
		(net "P3E_CPU0_PE1_SS_R_RXP<0>")
	)
	(segment
		(start 337.719924 -56.138318)
		(end 339.2678 -55.8292)
		(width 0.1143)
		(layer "In2.Cu")
		(net "P3E_CPU0_PE1_SS_R_RXP<0>")
	)
	(segment
		(start 381.371856 -1.671066)
		(end 385.596638 -2.516124)
		(width 0.1143)
		(layer "In2.Cu")
		(net "P3E_CPU0_PE1_SS_R_RXP<0>")
	)
	(segment
		(start 379.10135 -3.076956)
		(end 379.357382 -2.692654)
		(width 0.1143)
		(layer "In2.Cu")
		(net "P3E_CPU0_PE1_SS_R_RXP<0>")
	)
	(segment
		(start 378.950728 -3.717544)
		(end 379.069092 -3.124962)
		(width 0.1143)
		(layer "In2.Cu")
		(net "P3E_CPU0_PE1_SS_R_RXP<0>")
	)
	(segment
		(start 334.53705 -58.843672)
		(end 334.53705 -58.540142)
		(width 0.1143)
		(layer "In2.Cu")
		(net "P3E_CPU0_PE1_SS_R_RXP<0>")
	)
	(segment
		(start 334.53705 -58.540142)
		(end 334.78978 -58.091324)
		(width 0.1143)
		(layer "In2.Cu")
		(net "P3E_CPU0_PE1_SS_R_RXP<0>")
	)
	(segment
		(start 370.159026 -6.893052)
		(end 378.404628 -4.536948)
		(width 0.1143)
		(layer "In2.Cu")
		(net "P3E_CPU0_PE1_SS_R_RXP<0>")
	)
	(segment
		(start 346.054426 -54.304692)
		(end 346.280486 -53.965348)
		(width 0.1143)
		(layer "In2.Cu")
		(net "P3E_CPU0_PE1_SS_R_RXP<0>")
	)
	(segment
		(start 351.0407 -36.617656)
		(end 351.415096 -35.983672)
		(width 0.1143)
		(layer "In2.Cu")
		(net "P3E_CPU0_PE1_SS_R_RXP<0>")
	)
	(segment
		(start 367.328196 -8.77951)
		(end 370.159026 -6.893052)
		(width 0.1143)
		(layer "In2.Cu")
		(net "P3E_CPU0_PE1_SS_R_RXP<0>")
	)
	(segment
		(start 410.013912 -3.6322)
		(end 410.769562 -3.6322)
		(width 0.1143)
		(layer "In2.Cu")
		(net "P3E_CPU0_PE1_SS_R_RXP<0>")
	)
	(segment
		(start 346.649802 -52.231798)
		(end 346.650056 -52.231798)
		(width 0.1143)
		(layer "In2.Cu")
		(net "P3E_CPU0_PE1_SS_R_RXP<0>")
	)
	(segment
		(start 394.257022 -1.45161)
		(end 396.948914 -2.023364)
		(width 0.1143)
		(layer "In2.Cu")
		(net "P3E_CPU0_PE1_SS_R_RXP<0>")
	)
	(segment
		(start 346.618052 -52.279804)
		(end 346.649802 -52.231798)
		(width 0.1143)
		(layer "In2.Cu")
		(net "P3E_CPU0_PE1_SS_R_RXP<0>")
	)
	(segment
		(start 411.752542 -2.73177)
		(end 411.428692 -2.73177)
		(width 0.1143)
		(layer "In2.Cu")
		(net "P3E_CPU0_PE1_SS_R_RXP<0>")
	)
	(segment
		(start 388.103872 -2.264156)
		(end 391.36828 -1.570736)
		(width 0.1143)
		(layer "In2.Cu")
		(net "P3E_CPU0_PE1_SS_R_RXP<0>")
	)
	(segment
		(start 429.126396 -2.72415)
		(end 429.500792 -2.72415)
		(width 0.1143)
		(layer "F.Cu")
		(net "P3E_CPU0_PE1_SS_R_RXN<7>")
	)
	(segment
		(start 429.274986 -4.386072)
		(end 429.274986 -3.69824)
		(width 0.1143)
		(layer "F.Cu")
		(net "P3E_CPU0_PE1_SS_R_RXN<7>")
	)
	(segment
		(start 429.274986 -3.69824)
		(end 428.995586 -3.41884)
		(width 0.1143)
		(layer "F.Cu")
		(net "P3E_CPU0_PE1_SS_R_RXN<7>")
	)
	(segment
		(start 428.995586 -2.85496)
		(end 429.126396 -2.72415)
		(width 0.1143)
		(layer "F.Cu")
		(net "P3E_CPU0_PE1_SS_R_RXN<7>")
	)
	(segment
		(start 428.995586 -3.41884)
		(end 428.995586 -2.85496)
		(width 0.1143)
		(layer "F.Cu")
		(net "P3E_CPU0_PE1_SS_R_RXN<7>")
	)
	(via
		(at 429.500792 -2.72415)
		(size 0.508)
		(drill 0.254)
		(layers "F.Cu" "B.Cu")
		(net "P3E_CPU0_PE1_SS_R_RXN<7>")
	)
	(via
		(at 354.9396 -58.957972)
		(size 0.508)
		(drill 0.254)
		(layers "F.Cu" "B.Cu")
		(net "P3E_CPU0_PE1_SS_R_RXN<7>")
	)
	(segment
		(start 354.301806 -59.479434)
		(end 354.418138 -59.479434)
		(width 0.1143)
		(layer "B.Cu")
		(net "P3E_CPU0_PE1_SS_R_RXN<7>")
	)
	(segment
		(start 354.418138 -59.479434)
		(end 354.9396 -58.957972)
		(width 0.1143)
		(layer "B.Cu")
		(net "P3E_CPU0_PE1_SS_R_RXN<7>")
	)
	(segment
		(start 393.135612 -9.246616)
		(end 392.185906 -9.045448)
		(width 0.1143)
		(layer "In2.Cu")
		(net "P3E_CPU0_PE1_SS_R_RXN<7>")
	)
	(segment
		(start 360.501184 -35.9664)
		(end 359.073196 -43.111674)
		(width 0.1143)
		(layer "In2.Cu")
		(net "P3E_CPU0_PE1_SS_R_RXN<7>")
	)
	(segment
		(start 428.065692 -6.172454)
		(end 426.835062 -6.99389)
		(width 0.1143)
		(layer "In2.Cu")
		(net "P3E_CPU0_PE1_SS_R_RXN<7>")
	)
	(segment
		(start 354.50145 -58.957972)
		(end 354.9396 -58.957972)
		(width 0.1143)
		(layer "In2.Cu")
		(net "P3E_CPU0_PE1_SS_R_RXN<7>")
	)
	(segment
		(start 378.986542 -11.851132)
		(end 376.834146 -11.394694)
		(width 0.1143)
		(layer "In2.Cu")
		(net "P3E_CPU0_PE1_SS_R_RXN<7>")
	)
	(segment
		(start 404.604728 -8.973312)
		(end 403.40915 -9.227312)
		(width 0.1143)
		(layer "In2.Cu")
		(net "P3E_CPU0_PE1_SS_R_RXN<7>")
	)
	(segment
		(start 354.38715 -58.589418)
		(end 354.38715 -58.843672)
		(width 0.1143)
		(layer "In2.Cu")
		(net "P3E_CPU0_PE1_SS_R_RXN<7>")
	)
	(segment
		(start 395.80312 -9.103106)
		(end 394.806424 -8.89127)
		(width 0.1143)
		(layer "In2.Cu")
		(net "P3E_CPU0_PE1_SS_R_RXN<7>")
	)
	(segment
		(start 359.073196 -43.111674)
		(end 355.347524 -48.702214)
		(width 0.1143)
		(layer "In2.Cu")
		(net "P3E_CPU0_PE1_SS_R_RXN<7>")
	)
	(segment
		(start 406.781 -8.91286)
		(end 405.550624 -9.174226)
		(width 0.1143)
		(layer "In2.Cu")
		(net "P3E_CPU0_PE1_SS_R_RXN<7>")
	)
	(segment
		(start 426.835062 -6.99389)
		(end 415.840926 -9.328658)
		(width 0.1143)
		(layer "In2.Cu")
		(net "P3E_CPU0_PE1_SS_R_RXN<7>")
	)
	(segment
		(start 411.504384 -8.406638)
		(end 407.951178 -9.161526)
		(width 0.1143)
		(layer "In2.Cu")
		(net "P3E_CPU0_PE1_SS_R_RXN<7>")
	)
	(segment
		(start 355.347524 -48.702214)
		(end 353.197414 -55.331868)
		(width 0.1143)
		(layer "In2.Cu")
		(net "P3E_CPU0_PE1_SS_R_RXN<7>")
	)
	(segment
		(start 400.678904 -9.122918)
		(end 399.43659 -8.859012)
		(width 0.1143)
		(layer "In2.Cu")
		(net "P3E_CPU0_PE1_SS_R_RXN<7>")
	)
	(segment
		(start 403.40915 -9.227312)
		(end 401.79879 -8.885174)
		(width 0.1143)
		(layer "In2.Cu")
		(net "P3E_CPU0_PE1_SS_R_RXN<7>")
	)
	(segment
		(start 407.951178 -9.161526)
		(end 406.781 -8.91286)
		(width 0.1143)
		(layer "In2.Cu")
		(net "P3E_CPU0_PE1_SS_R_RXN<7>")
	)
	(segment
		(start 399.43659 -8.859012)
		(end 398.1958 -9.122664)
		(width 0.1143)
		(layer "In2.Cu")
		(net "P3E_CPU0_PE1_SS_R_RXN<7>")
	)
	(segment
		(start 361.201716 -34.915348)
		(end 360.501184 -35.9664)
		(width 0.1143)
		(layer "In2.Cu")
		(net "P3E_CPU0_PE1_SS_R_RXN<7>")
	)
	(segment
		(start 364.906814 -17.46377)
		(end 361.201716 -34.915348)
		(width 0.1143)
		(layer "In2.Cu")
		(net "P3E_CPU0_PE1_SS_R_RXN<7>")
	)
	(segment
		(start 370.036598 -13.791946)
		(end 364.906814 -17.46377)
		(width 0.1143)
		(layer "In2.Cu")
		(net "P3E_CPU0_PE1_SS_R_RXN<7>")
	)
	(segment
		(start 429.500792 -2.72415)
		(end 429.145192 -2.72415)
		(width 0.1143)
		(layer "In2.Cu")
		(net "P3E_CPU0_PE1_SS_R_RXN<7>")
	)
	(segment
		(start 401.79879 -8.885174)
		(end 400.678904 -9.122918)
		(width 0.1143)
		(layer "In2.Cu")
		(net "P3E_CPU0_PE1_SS_R_RXN<7>")
	)
	(segment
		(start 429.012096 -4.51485)
		(end 428.065692 -6.172454)
		(width 0.1143)
		(layer "In2.Cu")
		(net "P3E_CPU0_PE1_SS_R_RXN<7>")
	)
	(segment
		(start 394.806424 -8.89127)
		(end 393.135612 -9.246616)
		(width 0.1143)
		(layer "In2.Cu")
		(net "P3E_CPU0_PE1_SS_R_RXN<7>")
	)
	(segment
		(start 392.185906 -9.045448)
		(end 378.986542 -11.851132)
		(width 0.1143)
		(layer "In2.Cu")
		(net "P3E_CPU0_PE1_SS_R_RXN<7>")
	)
	(segment
		(start 429.145192 -2.72415)
		(end 429.012096 -2.857246)
		(width 0.1143)
		(layer "In2.Cu")
		(net "P3E_CPU0_PE1_SS_R_RXN<7>")
	)
	(segment
		(start 376.834146 -11.394694)
		(end 370.036598 -13.791946)
		(width 0.1143)
		(layer "In2.Cu")
		(net "P3E_CPU0_PE1_SS_R_RXN<7>")
	)
	(segment
		(start 405.550624 -9.174226)
		(end 404.604728 -8.973312)
		(width 0.1143)
		(layer "In2.Cu")
		(net "P3E_CPU0_PE1_SS_R_RXN<7>")
	)
	(segment
		(start 353.649534 -57.538366)
		(end 354.38715 -58.589418)
		(width 0.1143)
		(layer "In2.Cu")
		(net "P3E_CPU0_PE1_SS_R_RXN<7>")
	)
	(segment
		(start 354.38715 -58.843672)
		(end 354.50145 -58.957972)
		(width 0.1143)
		(layer "In2.Cu")
		(net "P3E_CPU0_PE1_SS_R_RXN<7>")
	)
	(segment
		(start 353.197414 -55.331868)
		(end 353.649534 -57.538366)
		(width 0.1143)
		(layer "In2.Cu")
		(net "P3E_CPU0_PE1_SS_R_RXN<7>")
	)
	(segment
		(start 396.953486 -8.858758)
		(end 395.80312 -9.103106)
		(width 0.1143)
		(layer "In2.Cu")
		(net "P3E_CPU0_PE1_SS_R_RXN<7>")
	)
	(segment
		(start 429.012096 -2.857246)
		(end 429.012096 -4.51485)
		(width 0.1143)
		(layer "In2.Cu")
		(net "P3E_CPU0_PE1_SS_R_RXN<7>")
	)
	(segment
		(start 398.1958 -9.122664)
		(end 396.953486 -8.858758)
		(width 0.1143)
		(layer "In2.Cu")
		(net "P3E_CPU0_PE1_SS_R_RXN<7>")
	)
	(segment
		(start 415.840926 -9.328658)
		(end 411.504384 -8.406638)
		(width 0.1143)
		(layer "In2.Cu")
		(net "P3E_CPU0_PE1_SS_R_RXN<7>")
	)
	(segment
		(start 426.874686 -3.69824)
		(end 426.568362 -3.391916)
		(width 0.1143)
		(layer "F.Cu")
		(net "P3E_CPU0_PE1_SS_R_RXN<6>")
	)
	(segment
		(start 426.682662 -2.890774)
		(end 427.082712 -2.890774)
		(width 0.1143)
		(layer "F.Cu")
		(net "P3E_CPU0_PE1_SS_R_RXN<6>")
	)
	(segment
		(start 426.874686 -4.386072)
		(end 426.874686 -3.69824)
		(width 0.1143)
		(layer "F.Cu")
		(net "P3E_CPU0_PE1_SS_R_RXN<6>")
	)
	(segment
		(start 426.568362 -3.391916)
		(end 426.568362 -3.005074)
		(width 0.1143)
		(layer "F.Cu")
		(net "P3E_CPU0_PE1_SS_R_RXN<6>")
	)
	(segment
		(start 426.568362 -3.005074)
		(end 426.682662 -2.890774)
		(width 0.1143)
		(layer "F.Cu")
		(net "P3E_CPU0_PE1_SS_R_RXN<6>")
	)
	(via
		(at 427.082712 -2.890774)
		(size 0.508)
		(drill 0.254)
		(layers "F.Cu" "B.Cu")
		(net "P3E_CPU0_PE1_SS_R_RXN<6>")
	)
	(via
		(at 352.1456 -58.957972)
		(size 0.508)
		(drill 0.254)
		(layers "F.Cu" "B.Cu")
		(net "P3E_CPU0_PE1_SS_R_RXN<6>")
	)
	(segment
		(start 351.624138 -59.479434)
		(end 352.1456 -58.957972)
		(width 0.1143)
		(layer "B.Cu")
		(net "P3E_CPU0_PE1_SS_R_RXN<6>")
	)
	(segment
		(start 351.507806 -59.479434)
		(end 351.624138 -59.479434)
		(width 0.1143)
		(layer "B.Cu")
		(net "P3E_CPU0_PE1_SS_R_RXN<6>")
	)
	(segment
		(start 411.503876 -7.755128)
		(end 415.592514 -8.623808)
		(width 0.1143)
		(layer "In2.Cu")
		(net "P3E_CPU0_PE1_SS_R_RXN<6>")
	)
	(segment
		(start 425.018962 -6.39572)
		(end 426.62475 -3.946906)
		(width 0.1143)
		(layer "In2.Cu")
		(net "P3E_CPU0_PE1_SS_R_RXN<6>")
	)
	(segment
		(start 394.757656 -8.229346)
		(end 395.80312 -8.451342)
		(width 0.1143)
		(layer "In2.Cu")
		(net "P3E_CPU0_PE1_SS_R_RXN<6>")
	)
	(segment
		(start 398.1958 -8.4709)
		(end 399.43659 -8.207248)
		(width 0.1143)
		(layer "In2.Cu")
		(net "P3E_CPU0_PE1_SS_R_RXN<6>")
	)
	(segment
		(start 360.608372 -34.635694)
		(end 364.33633 -17.088104)
		(width 0.1143)
		(layer "In2.Cu")
		(net "P3E_CPU0_PE1_SS_R_RXN<6>")
	)
	(segment
		(start 358.47528 -42.779188)
		(end 359.889044 -35.714686)
		(width 0.1143)
		(layer "In2.Cu")
		(net "P3E_CPU0_PE1_SS_R_RXN<6>")
	)
	(segment
		(start 415.592514 -8.623808)
		(end 424.5229 -6.726936)
		(width 0.1143)
		(layer "In2.Cu")
		(net "P3E_CPU0_PE1_SS_R_RXN<6>")
	)
	(segment
		(start 353.51847 -50.146712)
		(end 358.47528 -42.779188)
		(width 0.1143)
		(layer "In2.Cu")
		(net "P3E_CPU0_PE1_SS_R_RXN<6>")
	)
	(segment
		(start 351.70745 -58.957972)
		(end 351.59315 -58.843672)
		(width 0.1143)
		(layer "In2.Cu")
		(net "P3E_CPU0_PE1_SS_R_RXN<6>")
	)
	(segment
		(start 360.167682 -35.296856)
		(end 360.608372 -34.635694)
		(width 0.1143)
		(layer "In2.Cu")
		(net "P3E_CPU0_PE1_SS_R_RXN<6>")
	)
	(segment
		(start 376.824748 -10.721594)
		(end 379.00229 -11.183366)
		(width 0.1143)
		(layer "In2.Cu")
		(net "P3E_CPU0_PE1_SS_R_RXN<6>")
	)
	(segment
		(start 400.678904 -8.471154)
		(end 401.79879 -8.23341)
		(width 0.1143)
		(layer "In2.Cu")
		(net "P3E_CPU0_PE1_SS_R_RXN<6>")
	)
	(segment
		(start 424.5229 -6.726936)
		(end 425.018962 -6.39572)
		(width 0.1143)
		(layer "In2.Cu")
		(net "P3E_CPU0_PE1_SS_R_RXN<6>")
	)
	(segment
		(start 364.33633 -17.088104)
		(end 369.73891 -13.220954)
		(width 0.1143)
		(layer "In2.Cu")
		(net "P3E_CPU0_PE1_SS_R_RXN<6>")
	)
	(segment
		(start 426.62475 -3.946906)
		(end 426.62475 -3.005074)
		(width 0.1143)
		(layer "In2.Cu")
		(net "P3E_CPU0_PE1_SS_R_RXN<6>")
	)
	(segment
		(start 401.79879 -8.23341)
		(end 403.352254 -8.563356)
		(width 0.1143)
		(layer "In2.Cu")
		(net "P3E_CPU0_PE1_SS_R_RXN<6>")
	)
	(segment
		(start 426.62475 -3.005074)
		(end 426.73905 -2.890774)
		(width 0.1143)
		(layer "In2.Cu")
		(net "P3E_CPU0_PE1_SS_R_RXN<6>")
	)
	(segment
		(start 352.1456 -58.957972)
		(end 351.70745 -58.957972)
		(width 0.1143)
		(layer "In2.Cu")
		(net "P3E_CPU0_PE1_SS_R_RXN<6>")
	)
	(segment
		(start 359.889044 -35.714686)
		(end 360.167682 -35.296856)
		(width 0.1143)
		(layer "In2.Cu")
		(net "P3E_CPU0_PE1_SS_R_RXN<6>")
	)
	(segment
		(start 405.53894 -8.519922)
		(end 406.76957 -8.258556)
		(width 0.1143)
		(layer "In2.Cu")
		(net "P3E_CPU0_PE1_SS_R_RXN<6>")
	)
	(segment
		(start 369.73891 -13.220954)
		(end 376.824748 -10.721594)
		(width 0.1143)
		(layer "In2.Cu")
		(net "P3E_CPU0_PE1_SS_R_RXN<6>")
	)
	(segment
		(start 379.00229 -11.183366)
		(end 392.15822 -8.387334)
		(width 0.1143)
		(layer "In2.Cu")
		(net "P3E_CPU0_PE1_SS_R_RXN<6>")
	)
	(segment
		(start 395.80312 -8.451342)
		(end 396.953486 -8.206994)
		(width 0.1143)
		(layer "In2.Cu")
		(net "P3E_CPU0_PE1_SS_R_RXN<6>")
	)
	(segment
		(start 399.43659 -8.207248)
		(end 400.678904 -8.471154)
		(width 0.1143)
		(layer "In2.Cu")
		(net "P3E_CPU0_PE1_SS_R_RXN<6>")
	)
	(segment
		(start 403.352254 -8.563356)
		(end 404.547832 -8.309356)
		(width 0.1143)
		(layer "In2.Cu")
		(net "P3E_CPU0_PE1_SS_R_RXN<6>")
	)
	(segment
		(start 404.547832 -8.309356)
		(end 405.53894 -8.519922)
		(width 0.1143)
		(layer "In2.Cu")
		(net "P3E_CPU0_PE1_SS_R_RXN<6>")
	)
	(segment
		(start 393.086082 -8.584438)
		(end 394.757656 -8.229346)
		(width 0.1143)
		(layer "In2.Cu")
		(net "P3E_CPU0_PE1_SS_R_RXN<6>")
	)
	(segment
		(start 351.59315 -58.843672)
		(end 351.59315 -58.681874)
		(width 0.1143)
		(layer "In2.Cu")
		(net "P3E_CPU0_PE1_SS_R_RXN<6>")
	)
	(segment
		(start 351.897696 -58.248042)
		(end 353.51847 -50.146712)
		(width 0.1143)
		(layer "In2.Cu")
		(net "P3E_CPU0_PE1_SS_R_RXN<6>")
	)
	(segment
		(start 392.15822 -8.387334)
		(end 393.086082 -8.584438)
		(width 0.1143)
		(layer "In2.Cu")
		(net "P3E_CPU0_PE1_SS_R_RXN<6>")
	)
	(segment
		(start 407.951178 -8.509762)
		(end 411.503876 -7.755128)
		(width 0.1143)
		(layer "In2.Cu")
		(net "P3E_CPU0_PE1_SS_R_RXN<6>")
	)
	(segment
		(start 406.76957 -8.258556)
		(end 407.951178 -8.509762)
		(width 0.1143)
		(layer "In2.Cu")
		(net "P3E_CPU0_PE1_SS_R_RXN<6>")
	)
	(segment
		(start 426.73905 -2.890774)
		(end 427.082712 -2.890774)
		(width 0.1143)
		(layer "In2.Cu")
		(net "P3E_CPU0_PE1_SS_R_RXN<6>")
	)
	(segment
		(start 351.59315 -58.681874)
		(end 351.897696 -58.248042)
		(width 0.1143)
		(layer "In2.Cu")
		(net "P3E_CPU0_PE1_SS_R_RXN<6>")
	)
	(segment
		(start 396.953486 -8.206994)
		(end 398.1958 -8.4709)
		(width 0.1143)
		(layer "In2.Cu")
		(net "P3E_CPU0_PE1_SS_R_RXN<6>")
	)
	(segment
		(start 424.282616 -1.583944)
		(end 424.168316 -1.698244)
		(width 0.1143)
		(layer "F.Cu")
		(net "P3E_CPU0_PE1_SS_R_RXN<5>")
	)
	(segment
		(start 424.168316 -1.698244)
		(end 424.168316 -3.452114)
		(width 0.1143)
		(layer "F.Cu")
		(net "P3E_CPU0_PE1_SS_R_RXN<5>")
	)
	(segment
		(start 424.168316 -3.452114)
		(end 424.474386 -3.758184)
		(width 0.1143)
		(layer "F.Cu")
		(net "P3E_CPU0_PE1_SS_R_RXN<5>")
	)
	(segment
		(start 424.474386 -3.758184)
		(end 424.474386 -4.386072)
		(width 0.1143)
		(layer "F.Cu")
		(net "P3E_CPU0_PE1_SS_R_RXN<5>")
	)
	(segment
		(start 424.682666 -1.583944)
		(end 424.282616 -1.583944)
		(width 0.1143)
		(layer "F.Cu")
		(net "P3E_CPU0_PE1_SS_R_RXN<5>")
	)
	(via
		(at 424.682666 -1.583944)
		(size 0.508)
		(drill 0.254)
		(layers "F.Cu" "B.Cu")
		(net "P3E_CPU0_PE1_SS_R_RXN<5>")
	)
	(via
		(at 349.3516 -58.957972)
		(size 0.508)
		(drill 0.254)
		(layers "F.Cu" "B.Cu")
		(net "P3E_CPU0_PE1_SS_R_RXN<5>")
	)
	(segment
		(start 348.713806 -59.479434)
		(end 349.235268 -58.957972)
		(width 0.1143)
		(layer "B.Cu")
		(net "P3E_CPU0_PE1_SS_R_RXN<5>")
	)
	(segment
		(start 349.235268 -58.957972)
		(end 349.3516 -58.957972)
		(width 0.1143)
		(layer "B.Cu")
		(net "P3E_CPU0_PE1_SS_R_RXN<5>")
	)
	(segment
		(start 394.691362 -7.563358)
		(end 395.80312 -7.799578)
		(width 0.1143)
		(layer "In2.Cu")
		(net "P3E_CPU0_PE1_SS_R_RXN<5>")
	)
	(segment
		(start 348.79915 -58.843672)
		(end 348.79915 -58.322718)
		(width 0.1143)
		(layer "In2.Cu")
		(net "P3E_CPU0_PE1_SS_R_RXN<5>")
	)
	(segment
		(start 393.02309 -7.917942)
		(end 394.691362 -7.563358)
		(width 0.1143)
		(layer "In2.Cu")
		(net "P3E_CPU0_PE1_SS_R_RXN<5>")
	)
	(segment
		(start 359.300018 -35.40633)
		(end 360.02468 -34.318702)
		(width 0.1143)
		(layer "In2.Cu")
		(net "P3E_CPU0_PE1_SS_R_RXN<5>")
	)
	(segment
		(start 403.320504 -7.904988)
		(end 404.515828 -7.650988)
		(width 0.1143)
		(layer "In2.Cu")
		(net "P3E_CPU0_PE1_SS_R_RXN<5>")
	)
	(segment
		(start 360.02468 -34.318702)
		(end 363.76483 -16.713454)
		(width 0.1143)
		(layer "In2.Cu")
		(net "P3E_CPU0_PE1_SS_R_RXN<5>")
	)
	(segment
		(start 351.524824 -51.887628)
		(end 357.925624 -42.276522)
		(width 0.1143)
		(layer "In2.Cu")
		(net "P3E_CPU0_PE1_SS_R_RXN<5>")
	)
	(segment
		(start 415.546794 -7.962392)
		(end 423.137076 -6.350508)
		(width 0.1143)
		(layer "In2.Cu")
		(net "P3E_CPU0_PE1_SS_R_RXN<5>")
	)
	(segment
		(start 376.829066 -10.044176)
		(end 379.039628 -10.51306)
		(width 0.1143)
		(layer "In2.Cu")
		(net "P3E_CPU0_PE1_SS_R_RXN<5>")
	)
	(segment
		(start 399.43659 -7.555484)
		(end 400.678904 -7.81939)
		(width 0.1143)
		(layer "In2.Cu")
		(net "P3E_CPU0_PE1_SS_R_RXN<5>")
	)
	(segment
		(start 398.1958 -7.819136)
		(end 399.43659 -7.555484)
		(width 0.1143)
		(layer "In2.Cu")
		(net "P3E_CPU0_PE1_SS_R_RXN<5>")
	)
	(segment
		(start 407.951178 -7.857998)
		(end 411.50413 -7.103364)
		(width 0.1143)
		(layer "In2.Cu")
		(net "P3E_CPU0_PE1_SS_R_RXN<5>")
	)
	(segment
		(start 424.2435 -1.7399)
		(end 424.399456 -1.583944)
		(width 0.1143)
		(layer "In2.Cu")
		(net "P3E_CPU0_PE1_SS_R_RXN<5>")
	)
	(segment
		(start 401.79879 -7.581646)
		(end 403.320504 -7.904988)
		(width 0.1143)
		(layer "In2.Cu")
		(net "P3E_CPU0_PE1_SS_R_RXN<5>")
	)
	(segment
		(start 411.50413 -7.103364)
		(end 415.546794 -7.962392)
		(width 0.1143)
		(layer "In2.Cu")
		(net "P3E_CPU0_PE1_SS_R_RXN<5>")
	)
	(segment
		(start 349.3516 -58.957972)
		(end 348.91345 -58.957972)
		(width 0.1143)
		(layer "In2.Cu")
		(net "P3E_CPU0_PE1_SS_R_RXN<5>")
	)
	(segment
		(start 369.441222 -12.649708)
		(end 376.829066 -10.044176)
		(width 0.1143)
		(layer "In2.Cu")
		(net "P3E_CPU0_PE1_SS_R_RXN<5>")
	)
	(segment
		(start 396.953486 -7.55523)
		(end 398.1958 -7.819136)
		(width 0.1143)
		(layer "In2.Cu")
		(net "P3E_CPU0_PE1_SS_R_RXN<5>")
	)
	(segment
		(start 404.515828 -7.650988)
		(end 405.52116 -7.864602)
		(width 0.1143)
		(layer "In2.Cu")
		(net "P3E_CPU0_PE1_SS_R_RXN<5>")
	)
	(segment
		(start 424.2435 -5.042916)
		(end 424.2435 -1.7399)
		(width 0.1143)
		(layer "In2.Cu")
		(net "P3E_CPU0_PE1_SS_R_RXN<5>")
	)
	(segment
		(start 395.80312 -7.799578)
		(end 396.953486 -7.55523)
		(width 0.1143)
		(layer "In2.Cu")
		(net "P3E_CPU0_PE1_SS_R_RXN<5>")
	)
	(segment
		(start 423.137076 -6.350508)
		(end 423.904156 -5.838444)
		(width 0.1143)
		(layer "In2.Cu")
		(net "P3E_CPU0_PE1_SS_R_RXN<5>")
	)
	(segment
		(start 406.751536 -7.603236)
		(end 407.951178 -7.857998)
		(width 0.1143)
		(layer "In2.Cu")
		(net "P3E_CPU0_PE1_SS_R_RXN<5>")
	)
	(segment
		(start 350.813878 -55.44312)
		(end 351.524824 -51.887628)
		(width 0.1143)
		(layer "In2.Cu")
		(net "P3E_CPU0_PE1_SS_R_RXN<5>")
	)
	(segment
		(start 405.52116 -7.864602)
		(end 406.751536 -7.603236)
		(width 0.1143)
		(layer "In2.Cu")
		(net "P3E_CPU0_PE1_SS_R_RXN<5>")
	)
	(segment
		(start 363.76483 -16.713454)
		(end 369.441222 -12.649708)
		(width 0.1143)
		(layer "In2.Cu")
		(net "P3E_CPU0_PE1_SS_R_RXN<5>")
	)
	(segment
		(start 424.399456 -1.583944)
		(end 424.682666 -1.583944)
		(width 0.1143)
		(layer "In2.Cu")
		(net "P3E_CPU0_PE1_SS_R_RXN<5>")
	)
	(segment
		(start 423.904156 -5.838444)
		(end 424.2435 -5.042916)
		(width 0.1143)
		(layer "In2.Cu")
		(net "P3E_CPU0_PE1_SS_R_RXN<5>")
	)
	(segment
		(start 348.91345 -58.957972)
		(end 348.79915 -58.843672)
		(width 0.1143)
		(layer "In2.Cu")
		(net "P3E_CPU0_PE1_SS_R_RXN<5>")
	)
	(segment
		(start 400.678904 -7.81939)
		(end 401.79879 -7.581646)
		(width 0.1143)
		(layer "In2.Cu")
		(net "P3E_CPU0_PE1_SS_R_RXN<5>")
	)
	(segment
		(start 348.79915 -58.322718)
		(end 350.813878 -55.44312)
		(width 0.1143)
		(layer "In2.Cu")
		(net "P3E_CPU0_PE1_SS_R_RXN<5>")
	)
	(segment
		(start 392.138408 -7.73049)
		(end 393.02309 -7.917942)
		(width 0.1143)
		(layer "In2.Cu")
		(net "P3E_CPU0_PE1_SS_R_RXN<5>")
	)
	(segment
		(start 357.925624 -42.276522)
		(end 359.300018 -35.40633)
		(width 0.1143)
		(layer "In2.Cu")
		(net "P3E_CPU0_PE1_SS_R_RXN<5>")
	)
	(segment
		(start 379.039628 -10.51306)
		(end 392.138408 -7.73049)
		(width 0.1143)
		(layer "In2.Cu")
		(net "P3E_CPU0_PE1_SS_R_RXN<5>")
	)
	(segment
		(start 421.7543 -3.378454)
		(end 422.074086 -3.69824)
		(width 0.1143)
		(layer "F.Cu")
		(net "P3E_CPU0_PE1_SS_R_RXN<4>")
	)
	(segment
		(start 421.7543 -2.7559)
		(end 421.7543 -3.378454)
		(width 0.1143)
		(layer "F.Cu")
		(net "P3E_CPU0_PE1_SS_R_RXN<4>")
	)
	(segment
		(start 421.931084 -2.579116)
		(end 421.7543 -2.7559)
		(width 0.1143)
		(layer "F.Cu")
		(net "P3E_CPU0_PE1_SS_R_RXN<4>")
	)
	(segment
		(start 422.074086 -3.69824)
		(end 422.074086 -4.386072)
		(width 0.1143)
		(layer "F.Cu")
		(net "P3E_CPU0_PE1_SS_R_RXN<4>")
	)
	(segment
		(start 422.242742 -2.579116)
		(end 421.931084 -2.579116)
		(width 0.1143)
		(layer "F.Cu")
		(net "P3E_CPU0_PE1_SS_R_RXN<4>")
	)
	(via
		(at 422.242742 -2.579116)
		(size 0.508)
		(drill 0.254)
		(layers "F.Cu" "B.Cu")
		(net "P3E_CPU0_PE1_SS_R_RXN<4>")
	)
	(via
		(at 346.5576 -58.957972)
		(size 0.508)
		(drill 0.254)
		(layers "F.Cu" "B.Cu")
		(net "P3E_CPU0_PE1_SS_R_RXN<4>")
	)
	(segment
		(start 346.036138 -59.479434)
		(end 346.5576 -58.957972)
		(width 0.1143)
		(layer "B.Cu")
		(net "P3E_CPU0_PE1_SS_R_RXN<4>")
	)
	(segment
		(start 345.919806 -59.479434)
		(end 346.036138 -59.479434)
		(width 0.1143)
		(layer "B.Cu")
		(net "P3E_CPU0_PE1_SS_R_RXN<4>")
	)
	(segment
		(start 393.028932 -7.260082)
		(end 394.679932 -6.909308)
		(width 0.1143)
		(layer "In2.Cu")
		(net "P3E_CPU0_PE1_SS_R_RXN<4>")
	)
	(segment
		(start 401.821396 -6.925056)
		(end 403.348952 -7.249668)
		(width 0.1143)
		(layer "In2.Cu")
		(net "P3E_CPU0_PE1_SS_R_RXN<4>")
	)
	(segment
		(start 400.678904 -7.167626)
		(end 401.821396 -6.925056)
		(width 0.1143)
		(layer "In2.Cu")
		(net "P3E_CPU0_PE1_SS_R_RXN<4>")
	)
	(segment
		(start 404.856442 -6.92912)
		(end 405.844248 -7.139178)
		(width 0.1143)
		(layer "In2.Cu")
		(net "P3E_CPU0_PE1_SS_R_RXN<4>")
	)
	(segment
		(start 407.96845 -7.202424)
		(end 411.503622 -6.4516)
		(width 0.1143)
		(layer "In2.Cu")
		(net "P3E_CPU0_PE1_SS_R_RXN<4>")
	)
	(segment
		(start 358.716326 -35.018218)
		(end 359.461816 -33.899856)
		(width 0.1143)
		(layer "In2.Cu")
		(net "P3E_CPU0_PE1_SS_R_RXN<4>")
	)
	(segment
		(start 359.461816 -33.899856)
		(end 363.193076 -16.338804)
		(width 0.1143)
		(layer "In2.Cu")
		(net "P3E_CPU0_PE1_SS_R_RXN<4>")
	)
	(segment
		(start 346.5576 -58.957972)
		(end 346.065348 -58.957972)
		(width 0.1143)
		(layer "In2.Cu")
		(net "P3E_CPU0_PE1_SS_R_RXN<4>")
	)
	(segment
		(start 399.43659 -6.90372)
		(end 400.678904 -7.167626)
		(width 0.1143)
		(layer "In2.Cu")
		(net "P3E_CPU0_PE1_SS_R_RXN<4>")
	)
	(segment
		(start 347.361256 -57.268364)
		(end 348.736666 -56.993536)
		(width 0.1143)
		(layer "In2.Cu")
		(net "P3E_CPU0_PE1_SS_R_RXN<4>")
	)
	(segment
		(start 345.973654 -58.69305)
		(end 346.056712 -58.572908)
		(width 0.1143)
		(layer "In2.Cu")
		(net "P3E_CPU0_PE1_SS_R_RXN<4>")
	)
	(segment
		(start 394.679932 -6.909308)
		(end 395.80312 -7.147814)
		(width 0.1143)
		(layer "In2.Cu")
		(net "P3E_CPU0_PE1_SS_R_RXN<4>")
	)
	(segment
		(start 421.95623 -2.579116)
		(end 422.242742 -2.579116)
		(width 0.1143)
		(layer "In2.Cu")
		(net "P3E_CPU0_PE1_SS_R_RXN<4>")
	)
	(segment
		(start 350.28505 -54.670706)
		(end 350.899984 -51.596544)
		(width 0.1143)
		(layer "In2.Cu")
		(net "P3E_CPU0_PE1_SS_R_RXN<4>")
	)
	(segment
		(start 348.736666 -56.993536)
		(end 350.28505 -54.670706)
		(width 0.1143)
		(layer "In2.Cu")
		(net "P3E_CPU0_PE1_SS_R_RXN<4>")
	)
	(segment
		(start 398.1958 -7.167372)
		(end 399.43659 -6.90372)
		(width 0.1143)
		(layer "In2.Cu")
		(net "P3E_CPU0_PE1_SS_R_RXN<4>")
	)
	(segment
		(start 392.112246 -7.065772)
		(end 393.028932 -7.260082)
		(width 0.1143)
		(layer "In2.Cu")
		(net "P3E_CPU0_PE1_SS_R_RXN<4>")
	)
	(segment
		(start 376.788426 -9.381998)
		(end 379.004576 -9.851898)
		(width 0.1143)
		(layer "In2.Cu")
		(net "P3E_CPU0_PE1_SS_R_RXN<4>")
	)
	(segment
		(start 415.534856 -7.308088)
		(end 418.050472 -6.773926)
		(width 0.1143)
		(layer "In2.Cu")
		(net "P3E_CPU0_PE1_SS_R_RXN<4>")
	)
	(segment
		(start 379.004576 -9.851898)
		(end 392.112246 -7.065772)
		(width 0.1143)
		(layer "In2.Cu")
		(net "P3E_CPU0_PE1_SS_R_RXN<4>")
	)
	(segment
		(start 411.503622 -6.4516)
		(end 415.534856 -7.308088)
		(width 0.1143)
		(layer "In2.Cu")
		(net "P3E_CPU0_PE1_SS_R_RXN<4>")
	)
	(segment
		(start 363.193076 -16.338804)
		(end 369.144804 -12.077954)
		(width 0.1143)
		(layer "In2.Cu")
		(net "P3E_CPU0_PE1_SS_R_RXN<4>")
	)
	(segment
		(start 346.056712 -58.572908)
		(end 347.361256 -57.268364)
		(width 0.1143)
		(layer "In2.Cu")
		(net "P3E_CPU0_PE1_SS_R_RXN<4>")
	)
	(segment
		(start 421.810942 -2.724404)
		(end 421.95623 -2.579116)
		(width 0.1143)
		(layer "In2.Cu")
		(net "P3E_CPU0_PE1_SS_R_RXN<4>")
	)
	(segment
		(start 405.844248 -7.139178)
		(end 406.757124 -6.945376)
		(width 0.1143)
		(layer "In2.Cu")
		(net "P3E_CPU0_PE1_SS_R_RXN<4>")
	)
	(segment
		(start 345.973654 -58.866278)
		(end 345.973654 -58.69305)
		(width 0.1143)
		(layer "In2.Cu")
		(net "P3E_CPU0_PE1_SS_R_RXN<4>")
	)
	(segment
		(start 395.80312 -7.147814)
		(end 396.953486 -6.903466)
		(width 0.1143)
		(layer "In2.Cu")
		(net "P3E_CPU0_PE1_SS_R_RXN<4>")
	)
	(segment
		(start 406.757124 -6.945376)
		(end 407.96845 -7.202424)
		(width 0.1143)
		(layer "In2.Cu")
		(net "P3E_CPU0_PE1_SS_R_RXN<4>")
	)
	(segment
		(start 403.348952 -7.249668)
		(end 404.856442 -6.92912)
		(width 0.1143)
		(layer "In2.Cu")
		(net "P3E_CPU0_PE1_SS_R_RXN<4>")
	)
	(segment
		(start 357.326184 -41.961308)
		(end 358.716326 -35.018218)
		(width 0.1143)
		(layer "In2.Cu")
		(net "P3E_CPU0_PE1_SS_R_RXN<4>")
	)
	(segment
		(start 346.065348 -58.957972)
		(end 345.973654 -58.866278)
		(width 0.1143)
		(layer "In2.Cu")
		(net "P3E_CPU0_PE1_SS_R_RXN<4>")
	)
	(segment
		(start 396.953486 -6.903466)
		(end 398.1958 -7.167372)
		(width 0.1143)
		(layer "In2.Cu")
		(net "P3E_CPU0_PE1_SS_R_RXN<4>")
	)
	(segment
		(start 421.810942 -4.327652)
		(end 421.810942 -2.724404)
		(width 0.1143)
		(layer "In2.Cu")
		(net "P3E_CPU0_PE1_SS_R_RXN<4>")
	)
	(segment
		(start 421.57777 -4.81838)
		(end 421.810942 -4.327652)
		(width 0.1143)
		(layer "In2.Cu")
		(net "P3E_CPU0_PE1_SS_R_RXN<4>")
	)
	(segment
		(start 350.899984 -51.596544)
		(end 357.326184 -41.961308)
		(width 0.1143)
		(layer "In2.Cu")
		(net "P3E_CPU0_PE1_SS_R_RXN<4>")
	)
	(segment
		(start 418.050472 -6.773926)
		(end 421.57777 -4.81838)
		(width 0.1143)
		(layer "In2.Cu")
		(net "P3E_CPU0_PE1_SS_R_RXN<4>")
	)
	(segment
		(start 369.144804 -12.077954)
		(end 376.788426 -9.381998)
		(width 0.1143)
		(layer "In2.Cu")
		(net "P3E_CPU0_PE1_SS_R_RXN<4>")
	)
	(segment
		(start 419.673786 -3.758184)
		(end 419.673786 -4.386072)
		(width 0.1143)
		(layer "F.Cu")
		(net "P3E_CPU0_PE1_SS_R_RXN<3>")
	)
	(segment
		(start 419.654228 -1.60655)
		(end 419.539928 -1.72085)
		(width 0.1143)
		(layer "F.Cu")
		(net "P3E_CPU0_PE1_SS_R_RXN<3>")
	)
	(segment
		(start 419.394386 -3.478784)
		(end 419.673786 -3.758184)
		(width 0.1143)
		(layer "F.Cu")
		(net "P3E_CPU0_PE1_SS_R_RXN<3>")
	)
	(segment
		(start 419.539928 -1.72085)
		(end 419.539928 -2.4511)
		(width 0.1143)
		(layer "F.Cu")
		(net "P3E_CPU0_PE1_SS_R_RXN<3>")
	)
	(segment
		(start 419.394386 -2.596642)
		(end 419.394386 -3.478784)
		(width 0.1143)
		(layer "F.Cu")
		(net "P3E_CPU0_PE1_SS_R_RXN<3>")
	)
	(segment
		(start 420.051992 -1.60655)
		(end 419.654228 -1.60655)
		(width 0.1143)
		(layer "F.Cu")
		(net "P3E_CPU0_PE1_SS_R_RXN<3>")
	)
	(segment
		(start 419.539928 -2.4511)
		(end 419.394386 -2.596642)
		(width 0.1143)
		(layer "F.Cu")
		(net "P3E_CPU0_PE1_SS_R_RXN<3>")
	)
	(via
		(at 420.051992 -1.60655)
		(size 0.508)
		(drill 0.254)
		(layers "F.Cu" "B.Cu")
		(net "P3E_CPU0_PE1_SS_R_RXN<3>")
	)
	(via
		(at 343.7636 -58.957972)
		(size 0.508)
		(drill 0.254)
		(layers "F.Cu" "B.Cu")
		(net "P3E_CPU0_PE1_SS_R_RXN<3>")
	)
	(segment
		(start 343.7636 -58.957972)
		(end 343.242138 -59.479434)
		(width 0.1143)
		(layer "B.Cu")
		(net "P3E_CPU0_PE1_SS_R_RXN<3>")
	)
	(segment
		(start 343.242138 -59.479434)
		(end 343.125806 -59.479434)
		(width 0.1143)
		(layer "B.Cu")
		(net "P3E_CPU0_PE1_SS_R_RXN<3>")
	)
	(segment
		(start 354.6856 -38.379654)
		(end 355.482398 -37.18433)
		(width 0.1143)
		(layer "In2.Cu")
		(net "P3E_CPU0_PE1_SS_R_RXN<3>")
	)
	(segment
		(start 400.82216 -6.142736)
		(end 405.89708 -5.065268)
		(width 0.1143)
		(layer "In2.Cu")
		(net "P3E_CPU0_PE1_SS_R_RXN<3>")
	)
	(segment
		(start 400.750278 -6.156706)
		(end 400.755358 -6.156706)
		(width 0.1143)
		(layer "In2.Cu")
		(net "P3E_CPU0_PE1_SS_R_RXN<3>")
	)
	(segment
		(start 419.613842 -2.121408)
		(end 419.613842 -1.72085)
		(width 0.1143)
		(layer "In2.Cu")
		(net "P3E_CPU0_PE1_SS_R_RXN<3>")
	)
	(segment
		(start 400.812 -6.144768)
		(end 400.813524 -6.144514)
		(width 0.1143)
		(layer "In2.Cu")
		(net "P3E_CPU0_PE1_SS_R_RXN<3>")
	)
	(segment
		(start 343.7636 -58.957972)
		(end 343.32545 -58.957972)
		(width 0.1143)
		(layer "In2.Cu")
		(net "P3E_CPU0_PE1_SS_R_RXN<3>")
	)
	(segment
		(start 396.43812 -5.815584)
		(end 397.741648 -5.55498)
		(width 0.1143)
		(layer "In2.Cu")
		(net "P3E_CPU0_PE1_SS_R_RXN<3>")
	)
	(segment
		(start 400.811238 -6.145022)
		(end 400.812 -6.144768)
		(width 0.1143)
		(layer "In2.Cu")
		(net "P3E_CPU0_PE1_SS_R_RXN<3>")
	)
	(segment
		(start 387.740906 -4.516374)
		(end 392.426952 -5.51053)
		(width 0.1143)
		(layer "In2.Cu")
		(net "P3E_CPU0_PE1_SS_R_RXN<3>")
	)
	(segment
		(start 400.813524 -6.144514)
		(end 400.816064 -6.144006)
		(width 0.1143)
		(layer "In2.Cu")
		(net "P3E_CPU0_PE1_SS_R_RXN<3>")
	)
	(segment
		(start 358.87279 -33.51911)
		(end 362.76661 -15.187168)
		(width 0.1143)
		(layer "In2.Cu")
		(net "P3E_CPU0_PE1_SS_R_RXN<3>")
	)
	(segment
		(start 384.375914 -5.185156)
		(end 384.978656 -5.305552)
		(width 0.1143)
		(layer "In2.Cu")
		(net "P3E_CPU0_PE1_SS_R_RXN<3>")
	)
	(segment
		(start 371.790468 -10.432288)
		(end 373.233442 -8.398002)
		(width 0.1143)
		(layer "In2.Cu")
		(net "P3E_CPU0_PE1_SS_R_RXN<3>")
	)
	(segment
		(start 392.426952 -5.51053)
		(end 393.01547 -5.385054)
		(width 0.1143)
		(layer "In2.Cu")
		(net "P3E_CPU0_PE1_SS_R_RXN<3>")
	)
	(segment
		(start 357.066342 -36.229798)
		(end 358.87279 -33.51911)
		(width 0.1143)
		(layer "In2.Cu")
		(net "P3E_CPU0_PE1_SS_R_RXN<3>")
	)
	(segment
		(start 345.513914 -56.898286)
		(end 348.367604 -56.322468)
		(width 0.1143)
		(layer "In2.Cu")
		(net "P3E_CPU0_PE1_SS_R_RXN<3>")
	)
	(segment
		(start 348.367604 -56.322468)
		(end 349.677736 -54.357524)
		(width 0.1143)
		(layer "In2.Cu")
		(net "P3E_CPU0_PE1_SS_R_RXN<3>")
	)
	(segment
		(start 373.233442 -8.398002)
		(end 377.449588 -7.192772)
		(width 0.1143)
		(layer "In2.Cu")
		(net "P3E_CPU0_PE1_SS_R_RXN<3>")
	)
	(segment
		(start 355.482398 -37.18433)
		(end 357.066342 -36.229798)
		(width 0.1143)
		(layer "In2.Cu")
		(net "P3E_CPU0_PE1_SS_R_RXN<3>")
	)
	(segment
		(start 418.979858 -5.220716)
		(end 419.410642 -4.207256)
		(width 0.1143)
		(layer "In2.Cu")
		(net "P3E_CPU0_PE1_SS_R_RXN<3>")
	)
	(segment
		(start 417.021264 -6.32206)
		(end 418.979858 -5.220716)
		(width 0.1143)
		(layer "In2.Cu")
		(net "P3E_CPU0_PE1_SS_R_RXN<3>")
	)
	(segment
		(start 377.449588 -7.192772)
		(end 382.600454 -6.062218)
		(width 0.1143)
		(layer "In2.Cu")
		(net "P3E_CPU0_PE1_SS_R_RXN<3>")
	)
	(segment
		(start 354.6856 -44.691046)
		(end 354.6856 -38.379654)
		(width 0.1143)
		(layer "In2.Cu")
		(net "P3E_CPU0_PE1_SS_R_RXN<3>")
	)
	(segment
		(start 362.76661 -15.187168)
		(end 367.095532 -12.088876)
		(width 0.1143)
		(layer "In2.Cu")
		(net "P3E_CPU0_PE1_SS_R_RXN<3>")
	)
	(segment
		(start 393.01547 -5.385054)
		(end 394.01496 -5.597652)
		(width 0.1143)
		(layer "In2.Cu")
		(net "P3E_CPU0_PE1_SS_R_RXN<3>")
	)
	(segment
		(start 367.095532 -12.088876)
		(end 371.790468 -10.432288)
		(width 0.1143)
		(layer "In2.Cu")
		(net "P3E_CPU0_PE1_SS_R_RXN<3>")
	)
	(segment
		(start 394.01496 -5.597652)
		(end 394.68171 -5.464302)
		(width 0.1143)
		(layer "In2.Cu")
		(net "P3E_CPU0_PE1_SS_R_RXN<3>")
	)
	(segment
		(start 400.818858 -6.143498)
		(end 400.82216 -6.142736)
		(width 0.1143)
		(layer "In2.Cu")
		(net "P3E_CPU0_PE1_SS_R_RXN<3>")
	)
	(segment
		(start 350.293178 -51.281076)
		(end 354.6856 -44.691046)
		(width 0.1143)
		(layer "In2.Cu")
		(net "P3E_CPU0_PE1_SS_R_RXN<3>")
	)
	(segment
		(start 343.34958 -58.341006)
		(end 345.513914 -56.898286)
		(width 0.1143)
		(layer "In2.Cu")
		(net "P3E_CPU0_PE1_SS_R_RXN<3>")
	)
	(segment
		(start 415.491168 -6.646926)
		(end 417.021264 -6.32206)
		(width 0.1143)
		(layer "In2.Cu")
		(net "P3E_CPU0_PE1_SS_R_RXN<3>")
	)
	(segment
		(start 397.741648 -5.55498)
		(end 400.750278 -6.156706)
		(width 0.1143)
		(layer "In2.Cu")
		(net "P3E_CPU0_PE1_SS_R_RXN<3>")
	)
	(segment
		(start 411.503368 -5.799836)
		(end 415.491168 -6.646926)
		(width 0.1143)
		(layer "In2.Cu")
		(net "P3E_CPU0_PE1_SS_R_RXN<3>")
	)
	(segment
		(start 382.600454 -6.062218)
		(end 384.375914 -5.185156)
		(width 0.1143)
		(layer "In2.Cu")
		(net "P3E_CPU0_PE1_SS_R_RXN<3>")
	)
	(segment
		(start 384.978656 -5.305552)
		(end 387.740906 -4.516374)
		(width 0.1143)
		(layer "In2.Cu")
		(net "P3E_CPU0_PE1_SS_R_RXN<3>")
	)
	(segment
		(start 405.89708 -5.065268)
		(end 410.428948 -6.028182)
		(width 0.1143)
		(layer "In2.Cu")
		(net "P3E_CPU0_PE1_SS_R_RXN<3>")
	)
	(segment
		(start 410.428948 -6.028182)
		(end 411.503368 -5.799836)
		(width 0.1143)
		(layer "In2.Cu")
		(net "P3E_CPU0_PE1_SS_R_RXN<3>")
	)
	(segment
		(start 419.410642 -2.324608)
		(end 419.613842 -2.121408)
		(width 0.1143)
		(layer "In2.Cu")
		(net "P3E_CPU0_PE1_SS_R_RXN<3>")
	)
	(segment
		(start 343.32545 -58.957972)
		(end 343.21115 -58.843672)
		(width 0.1143)
		(layer "In2.Cu")
		(net "P3E_CPU0_PE1_SS_R_RXN<3>")
	)
	(segment
		(start 419.410642 -4.207256)
		(end 419.410642 -2.324608)
		(width 0.1143)
		(layer "In2.Cu")
		(net "P3E_CPU0_PE1_SS_R_RXN<3>")
	)
	(segment
		(start 343.21115 -58.6359)
		(end 343.34958 -58.341006)
		(width 0.1143)
		(layer "In2.Cu")
		(net "P3E_CPU0_PE1_SS_R_RXN<3>")
	)
	(segment
		(start 400.755358 -6.156706)
		(end 400.811238 -6.145022)
		(width 0.1143)
		(layer "In2.Cu")
		(net "P3E_CPU0_PE1_SS_R_RXN<3>")
	)
	(segment
		(start 343.21115 -58.843672)
		(end 343.21115 -58.6359)
		(width 0.1143)
		(layer "In2.Cu")
		(net "P3E_CPU0_PE1_SS_R_RXN<3>")
	)
	(segment
		(start 349.677736 -54.357524)
		(end 350.293178 -51.281076)
		(width 0.1143)
		(layer "In2.Cu")
		(net "P3E_CPU0_PE1_SS_R_RXN<3>")
	)
	(segment
		(start 400.816064 -6.144006)
		(end 400.818858 -6.143498)
		(width 0.1143)
		(layer "In2.Cu")
		(net "P3E_CPU0_PE1_SS_R_RXN<3>")
	)
	(segment
		(start 419.613842 -1.72085)
		(end 419.728142 -1.60655)
		(width 0.1143)
		(layer "In2.Cu")
		(net "P3E_CPU0_PE1_SS_R_RXN<3>")
	)
	(segment
		(start 394.68171 -5.464302)
		(end 396.43812 -5.815584)
		(width 0.1143)
		(layer "In2.Cu")
		(net "P3E_CPU0_PE1_SS_R_RXN<3>")
	)
	(segment
		(start 419.728142 -1.60655)
		(end 420.051992 -1.60655)
		(width 0.1143)
		(layer "In2.Cu")
		(net "P3E_CPU0_PE1_SS_R_RXN<3>")
	)
	(segment
		(start 417.54171 -2.82067)
		(end 417.164266 -2.82067)
		(width 0.1143)
		(layer "F.Cu")
		(net "P3E_CPU0_PE1_SS_R_RXN<2>")
	)
	(segment
		(start 417.024312 -3.357626)
		(end 417.273486 -3.6068)
		(width 0.1143)
		(layer "F.Cu")
		(net "P3E_CPU0_PE1_SS_R_RXN<2>")
	)
	(segment
		(start 417.164266 -2.82067)
		(end 417.024312 -2.960624)
		(width 0.1143)
		(layer "F.Cu")
		(net "P3E_CPU0_PE1_SS_R_RXN<2>")
	)
	(segment
		(start 417.024312 -2.960624)
		(end 417.024312 -3.357626)
		(width 0.1143)
		(layer "F.Cu")
		(net "P3E_CPU0_PE1_SS_R_RXN<2>")
	)
	(segment
		(start 417.273486 -3.6068)
		(end 417.273486 -4.386072)
		(width 0.1143)
		(layer "F.Cu")
		(net "P3E_CPU0_PE1_SS_R_RXN<2>")
	)
	(via
		(at 417.54171 -2.82067)
		(size 0.508)
		(drill 0.254)
		(layers "F.Cu" "B.Cu")
		(net "P3E_CPU0_PE1_SS_R_RXN<2>")
	)
	(via
		(at 340.9696 -58.957972)
		(size 0.508)
		(drill 0.254)
		(layers "F.Cu" "B.Cu")
		(net "P3E_CPU0_PE1_SS_R_RXN<2>")
	)
	(segment
		(start 340.448138 -59.479434)
		(end 340.9696 -58.957972)
		(width 0.1143)
		(layer "B.Cu")
		(net "P3E_CPU0_PE1_SS_R_RXN<2>")
	)
	(segment
		(start 340.331806 -59.479434)
		(end 340.448138 -59.479434)
		(width 0.1143)
		(layer "B.Cu")
		(net "P3E_CPU0_PE1_SS_R_RXN<2>")
	)
	(segment
		(start 417.021772 -2.971038)
		(end 417.17214 -2.82067)
		(width 0.1143)
		(layer "In2.Cu")
		(net "P3E_CPU0_PE1_SS_R_RXN<2>")
	)
	(segment
		(start 415.751264 -4.826)
		(end 416.717226 -4.384548)
		(width 0.1143)
		(layer "In2.Cu")
		(net "P3E_CPU0_PE1_SS_R_RXN<2>")
	)
	(segment
		(start 410.391864 -5.354574)
		(end 412.882334 -4.826)
		(width 0.1143)
		(layer "In2.Cu")
		(net "P3E_CPU0_PE1_SS_R_RXN<2>")
	)
	(segment
		(start 392.890502 -4.694682)
		(end 394.012166 -4.932934)
		(width 0.1143)
		(layer "In2.Cu")
		(net "P3E_CPU0_PE1_SS_R_RXN<2>")
	)
	(segment
		(start 358.280716 -33.237678)
		(end 362.195618 -14.812264)
		(width 0.1143)
		(layer "In2.Cu")
		(net "P3E_CPU0_PE1_SS_R_RXN<2>")
	)
	(segment
		(start 396.479776 -5.129784)
		(end 397.558768 -4.913884)
		(width 0.1143)
		(layer "In2.Cu")
		(net "P3E_CPU0_PE1_SS_R_RXN<2>")
	)
	(segment
		(start 340.396322 -58.199274)
		(end 340.814152 -57.361836)
		(width 0.1143)
		(layer "In2.Cu")
		(net "P3E_CPU0_PE1_SS_R_RXN<2>")
	)
	(segment
		(start 371.428264 -9.734296)
		(end 372.680738 -7.856728)
		(width 0.1143)
		(layer "In2.Cu")
		(net "P3E_CPU0_PE1_SS_R_RXN<2>")
	)
	(segment
		(start 372.680738 -7.856728)
		(end 380.134622 -5.727192)
		(width 0.1143)
		(layer "In2.Cu")
		(net "P3E_CPU0_PE1_SS_R_RXN<2>")
	)
	(segment
		(start 349.06204 -53.685186)
		(end 349.56623 -51.163728)
		(width 0.1143)
		(layer "In2.Cu")
		(net "P3E_CPU0_PE1_SS_R_RXN<2>")
	)
	(segment
		(start 354.0506 -44.437046)
		(end 354.0506 -38.1635)
		(width 0.1143)
		(layer "In2.Cu")
		(net "P3E_CPU0_PE1_SS_R_RXN<2>")
	)
	(segment
		(start 400.759422 -5.494274)
		(end 405.905208 -4.401566)
		(width 0.1143)
		(layer "In2.Cu")
		(net "P3E_CPU0_PE1_SS_R_RXN<2>")
	)
	(segment
		(start 412.882334 -4.826)
		(end 415.751264 -4.826)
		(width 0.1143)
		(layer "In2.Cu")
		(net "P3E_CPU0_PE1_SS_R_RXN<2>")
	)
	(segment
		(start 417.17214 -2.82067)
		(end 417.54171 -2.82067)
		(width 0.1143)
		(layer "In2.Cu")
		(net "P3E_CPU0_PE1_SS_R_RXN<2>")
	)
	(segment
		(start 367.440464 -11.057636)
		(end 371.428264 -9.734296)
		(width 0.1143)
		(layer "In2.Cu")
		(net "P3E_CPU0_PE1_SS_R_RXN<2>")
	)
	(segment
		(start 392.475466 -4.816094)
		(end 392.890502 -4.694682)
		(width 0.1143)
		(layer "In2.Cu")
		(net "P3E_CPU0_PE1_SS_R_RXN<2>")
	)
	(segment
		(start 380.134622 -5.727192)
		(end 380.647702 -4.957572)
		(width 0.1143)
		(layer "In2.Cu")
		(net "P3E_CPU0_PE1_SS_R_RXN<2>")
	)
	(segment
		(start 394.012166 -4.932934)
		(end 394.753338 -4.784598)
		(width 0.1143)
		(layer "In2.Cu")
		(net "P3E_CPU0_PE1_SS_R_RXN<2>")
	)
	(segment
		(start 397.558768 -4.913884)
		(end 397.708882 -4.883912)
		(width 0.1143)
		(layer "In2.Cu")
		(net "P3E_CPU0_PE1_SS_R_RXN<2>")
	)
	(segment
		(start 356.623874 -35.723068)
		(end 358.280716 -33.237678)
		(width 0.1143)
		(layer "In2.Cu")
		(net "P3E_CPU0_PE1_SS_R_RXN<2>")
	)
	(segment
		(start 355.041962 -36.676076)
		(end 356.623874 -35.723068)
		(width 0.1143)
		(layer "In2.Cu")
		(net "P3E_CPU0_PE1_SS_R_RXN<2>")
	)
	(segment
		(start 416.717226 -4.384548)
		(end 417.021772 -4.080002)
		(width 0.1143)
		(layer "In2.Cu")
		(net "P3E_CPU0_PE1_SS_R_RXN<2>")
	)
	(segment
		(start 417.021772 -4.080002)
		(end 417.021772 -2.971038)
		(width 0.1143)
		(layer "In2.Cu")
		(net "P3E_CPU0_PE1_SS_R_RXN<2>")
	)
	(segment
		(start 340.396322 -58.843672)
		(end 340.396322 -58.199274)
		(width 0.1143)
		(layer "In2.Cu")
		(net "P3E_CPU0_PE1_SS_R_RXN<2>")
	)
	(segment
		(start 340.510622 -58.957972)
		(end 340.396322 -58.843672)
		(width 0.1143)
		(layer "In2.Cu")
		(net "P3E_CPU0_PE1_SS_R_RXN<2>")
	)
	(segment
		(start 387.824726 -3.82905)
		(end 392.475466 -4.816094)
		(width 0.1143)
		(layer "In2.Cu")
		(net "P3E_CPU0_PE1_SS_R_RXN<2>")
	)
	(segment
		(start 347.738192 -55.671466)
		(end 349.06204 -53.685186)
		(width 0.1143)
		(layer "In2.Cu")
		(net "P3E_CPU0_PE1_SS_R_RXN<2>")
	)
	(segment
		(start 354.0506 -38.1635)
		(end 355.041962 -36.676076)
		(width 0.1143)
		(layer "In2.Cu")
		(net "P3E_CPU0_PE1_SS_R_RXN<2>")
	)
	(segment
		(start 382.59639 -4.0894)
		(end 385.136136 -4.5974)
		(width 0.1143)
		(layer "In2.Cu")
		(net "P3E_CPU0_PE1_SS_R_RXN<2>")
	)
	(segment
		(start 385.136136 -4.5974)
		(end 387.824726 -3.82905)
		(width 0.1143)
		(layer "In2.Cu")
		(net "P3E_CPU0_PE1_SS_R_RXN<2>")
	)
	(segment
		(start 349.56623 -51.163728)
		(end 354.0506 -44.437046)
		(width 0.1143)
		(layer "In2.Cu")
		(net "P3E_CPU0_PE1_SS_R_RXN<2>")
	)
	(segment
		(start 394.753338 -4.784598)
		(end 396.479776 -5.129784)
		(width 0.1143)
		(layer "In2.Cu")
		(net "P3E_CPU0_PE1_SS_R_RXN<2>")
	)
	(segment
		(start 380.647702 -4.957572)
		(end 381.672084 -4.274312)
		(width 0.1143)
		(layer "In2.Cu")
		(net "P3E_CPU0_PE1_SS_R_RXN<2>")
	)
	(segment
		(start 340.9696 -58.957972)
		(end 340.510622 -58.957972)
		(width 0.1143)
		(layer "In2.Cu")
		(net "P3E_CPU0_PE1_SS_R_RXN<2>")
	)
	(segment
		(start 340.814152 -57.361836)
		(end 341.478108 -56.89219)
		(width 0.1143)
		(layer "In2.Cu")
		(net "P3E_CPU0_PE1_SS_R_RXN<2>")
	)
	(segment
		(start 397.708882 -4.883912)
		(end 400.759422 -5.494274)
		(width 0.1143)
		(layer "In2.Cu")
		(net "P3E_CPU0_PE1_SS_R_RXN<2>")
	)
	(segment
		(start 405.905208 -4.401566)
		(end 410.391864 -5.354574)
		(width 0.1143)
		(layer "In2.Cu")
		(net "P3E_CPU0_PE1_SS_R_RXN<2>")
	)
	(segment
		(start 341.478108 -56.89219)
		(end 347.738192 -55.671466)
		(width 0.1143)
		(layer "In2.Cu")
		(net "P3E_CPU0_PE1_SS_R_RXN<2>")
	)
	(segment
		(start 362.195618 -14.812264)
		(end 367.440464 -11.057636)
		(width 0.1143)
		(layer "In2.Cu")
		(net "P3E_CPU0_PE1_SS_R_RXN<2>")
	)
	(segment
		(start 381.672084 -4.274312)
		(end 382.59639 -4.0894)
		(width 0.1143)
		(layer "In2.Cu")
		(net "P3E_CPU0_PE1_SS_R_RXN<2>")
	)
	(segment
		(start 414.569656 -1.914398)
		(end 414.569656 -3.414014)
		(width 0.1143)
		(layer "F.Cu")
		(net "P3E_CPU0_PE1_SS_R_RXN<1>")
	)
	(segment
		(start 414.750504 -1.73355)
		(end 414.569656 -1.914398)
		(width 0.1143)
		(layer "F.Cu")
		(net "P3E_CPU0_PE1_SS_R_RXN<1>")
	)
	(segment
		(start 415.073592 -1.73355)
		(end 414.750504 -1.73355)
		(width 0.1143)
		(layer "F.Cu")
		(net "P3E_CPU0_PE1_SS_R_RXN<1>")
	)
	(segment
		(start 414.569656 -3.414014)
		(end 414.873186 -3.717544)
		(width 0.1143)
		(layer "F.Cu")
		(net "P3E_CPU0_PE1_SS_R_RXN<1>")
	)
	(segment
		(start 414.873186 -3.717544)
		(end 414.873186 -4.386072)
		(width 0.1143)
		(layer "F.Cu")
		(net "P3E_CPU0_PE1_SS_R_RXN<1>")
	)
	(via
		(at 338.1756 -58.957972)
		(size 0.508)
		(drill 0.254)
		(layers "F.Cu" "B.Cu")
		(net "P3E_CPU0_PE1_SS_R_RXN<1>")
	)
	(via
		(at 415.073592 -1.73355)
		(size 0.508)
		(drill 0.254)
		(layers "F.Cu" "B.Cu")
		(net "P3E_CPU0_PE1_SS_R_RXN<1>")
	)
	(segment
		(start 337.654138 -59.479434)
		(end 338.1756 -58.957972)
		(width 0.1143)
		(layer "B.Cu")
		(net "P3E_CPU0_PE1_SS_R_RXN<1>")
	)
	(segment
		(start 337.537806 -59.479434)
		(end 337.654138 -59.479434)
		(width 0.1143)
		(layer "B.Cu")
		(net "P3E_CPU0_PE1_SS_R_RXN<1>")
	)
	(segment
		(start 400.741134 -4.820666)
		(end 400.801078 -4.81457)
		(width 0.1143)
		(layer "In2.Cu")
		(net "P3E_CPU0_PE1_SS_R_RXN<1>")
	)
	(segment
		(start 340.41334 -56.38546)
		(end 347.302074 -55.040022)
		(width 0.1143)
		(layer "In2.Cu")
		(net "P3E_CPU0_PE1_SS_R_RXN<1>")
	)
	(segment
		(start 414.648142 -1.73355)
		(end 415.073592 -1.73355)
		(width 0.1143)
		(layer "In2.Cu")
		(net "P3E_CPU0_PE1_SS_R_RXN<1>")
	)
	(segment
		(start 352.5774 -45.382942)
		(end 352.5774 -39.068248)
		(width 0.1143)
		(layer "In2.Cu")
		(net "P3E_CPU0_PE1_SS_R_RXN<1>")
	)
	(segment
		(start 381.495046 -3.505962)
		(end 382.727708 -3.259328)
		(width 0.1143)
		(layer "In2.Cu")
		(net "P3E_CPU0_PE1_SS_R_RXN<1>")
	)
	(segment
		(start 371.033802 -7.634478)
		(end 379.576076 -5.192776)
		(width 0.1143)
		(layer "In2.Cu")
		(net "P3E_CPU0_PE1_SS_R_RXN<1>")
	)
	(segment
		(start 405.894794 -3.745484)
		(end 405.895302 -3.745738)
		(width 0.1143)
		(layer "In2.Cu")
		(net "P3E_CPU0_PE1_SS_R_RXN<1>")
	)
	(segment
		(start 397.63954 -4.205986)
		(end 400.74088 -4.826508)
		(width 0.1143)
		(layer "In2.Cu")
		(net "P3E_CPU0_PE1_SS_R_RXN<1>")
	)
	(segment
		(start 369.53063 -9.59866)
		(end 371.033802 -7.634478)
		(width 0.1143)
		(layer "In2.Cu")
		(net "P3E_CPU0_PE1_SS_R_RXN<1>")
	)
	(segment
		(start 414.533842 -3.411474)
		(end 414.533842 -1.84785)
		(width 0.1143)
		(layer "In2.Cu")
		(net "P3E_CPU0_PE1_SS_R_RXN<1>")
	)
	(segment
		(start 400.801078 -4.81457)
		(end 405.894794 -3.745484)
		(width 0.1143)
		(layer "In2.Cu")
		(net "P3E_CPU0_PE1_SS_R_RXN<1>")
	)
	(segment
		(start 352.5774 -39.068248)
		(end 354.53447 -36.132262)
		(width 0.1143)
		(layer "In2.Cu")
		(net "P3E_CPU0_PE1_SS_R_RXN<1>")
	)
	(segment
		(start 392.8618 -4.032758)
		(end 394.008864 -4.276598)
		(width 0.1143)
		(layer "In2.Cu")
		(net "P3E_CPU0_PE1_SS_R_RXN<1>")
	)
	(segment
		(start 396.504922 -4.432046)
		(end 397.558768 -4.221988)
		(width 0.1143)
		(layer "In2.Cu")
		(net "P3E_CPU0_PE1_SS_R_RXN<1>")
	)
	(segment
		(start 394.86713 -4.10464)
		(end 396.504922 -4.432046)
		(width 0.1143)
		(layer "In2.Cu")
		(net "P3E_CPU0_PE1_SS_R_RXN<1>")
	)
	(segment
		(start 400.74088 -4.826508)
		(end 400.74088 -4.820666)
		(width 0.1143)
		(layer "In2.Cu")
		(net "P3E_CPU0_PE1_SS_R_RXN<1>")
	)
	(segment
		(start 357.6955 -32.922718)
		(end 361.623864 -14.43736)
		(width 0.1143)
		(layer "In2.Cu")
		(net "P3E_CPU0_PE1_SS_R_RXN<1>")
	)
	(segment
		(start 337.62315 -58.843672)
		(end 337.62315 -58.562494)
		(width 0.1143)
		(layer "In2.Cu")
		(net "P3E_CPU0_PE1_SS_R_RXN<1>")
	)
	(segment
		(start 354.53447 -36.132262)
		(end 356.243636 -35.102038)
		(width 0.1143)
		(layer "In2.Cu")
		(net "P3E_CPU0_PE1_SS_R_RXN<1>")
	)
	(segment
		(start 410.399992 -4.703318)
		(end 414.128204 -3.912362)
		(width 0.1143)
		(layer "In2.Cu")
		(net "P3E_CPU0_PE1_SS_R_RXN<1>")
	)
	(segment
		(start 356.243636 -35.102038)
		(end 357.6955 -32.922718)
		(width 0.1143)
		(layer "In2.Cu")
		(net "P3E_CPU0_PE1_SS_R_RXN<1>")
	)
	(segment
		(start 400.74088 -4.820666)
		(end 400.741134 -4.820666)
		(width 0.1143)
		(layer "In2.Cu")
		(net "P3E_CPU0_PE1_SS_R_RXN<1>")
	)
	(segment
		(start 387.81482 -3.167634)
		(end 392.45286 -4.153154)
		(width 0.1143)
		(layer "In2.Cu")
		(net "P3E_CPU0_PE1_SS_R_RXN<1>")
	)
	(segment
		(start 338.1756 -58.957972)
		(end 337.73745 -58.957972)
		(width 0.1143)
		(layer "In2.Cu")
		(net "P3E_CPU0_PE1_SS_R_RXN<1>")
	)
	(segment
		(start 392.45286 -4.153154)
		(end 392.8618 -4.032758)
		(width 0.1143)
		(layer "In2.Cu")
		(net "P3E_CPU0_PE1_SS_R_RXN<1>")
	)
	(segment
		(start 414.533842 -1.84785)
		(end 414.648142 -1.73355)
		(width 0.1143)
		(layer "In2.Cu")
		(net "P3E_CPU0_PE1_SS_R_RXN<1>")
	)
	(segment
		(start 348.358968 -53.456586)
		(end 348.855792 -50.965862)
		(width 0.1143)
		(layer "In2.Cu")
		(net "P3E_CPU0_PE1_SS_R_RXN<1>")
	)
	(segment
		(start 347.302074 -55.040022)
		(end 348.358968 -53.456586)
		(width 0.1143)
		(layer "In2.Cu")
		(net "P3E_CPU0_PE1_SS_R_RXN<1>")
	)
	(segment
		(start 337.62315 -58.562494)
		(end 337.81873 -58.2549)
		(width 0.1143)
		(layer "In2.Cu")
		(net "P3E_CPU0_PE1_SS_R_RXN<1>")
	)
	(segment
		(start 397.558768 -4.221988)
		(end 397.63954 -4.205986)
		(width 0.1143)
		(layer "In2.Cu")
		(net "P3E_CPU0_PE1_SS_R_RXN<1>")
	)
	(segment
		(start 385.530852 -3.82016)
		(end 387.81482 -3.167634)
		(width 0.1143)
		(layer "In2.Cu")
		(net "P3E_CPU0_PE1_SS_R_RXN<1>")
	)
	(segment
		(start 405.895302 -3.745484)
		(end 410.399992 -4.703318)
		(width 0.1143)
		(layer "In2.Cu")
		(net "P3E_CPU0_PE1_SS_R_RXN<1>")
	)
	(segment
		(start 394.008864 -4.276598)
		(end 394.86713 -4.10464)
		(width 0.1143)
		(layer "In2.Cu")
		(net "P3E_CPU0_PE1_SS_R_RXN<1>")
	)
	(segment
		(start 337.81873 -58.2549)
		(end 340.41334 -56.38546)
		(width 0.1143)
		(layer "In2.Cu")
		(net "P3E_CPU0_PE1_SS_R_RXN<1>")
	)
	(segment
		(start 367.392712 -10.307828)
		(end 369.53063 -9.59866)
		(width 0.1143)
		(layer "In2.Cu")
		(net "P3E_CPU0_PE1_SS_R_RXN<1>")
	)
	(segment
		(start 361.623864 -14.43736)
		(end 367.392712 -10.307828)
		(width 0.1143)
		(layer "In2.Cu")
		(net "P3E_CPU0_PE1_SS_R_RXN<1>")
	)
	(segment
		(start 379.576076 -5.192776)
		(end 380.06528 -4.459478)
		(width 0.1143)
		(layer "In2.Cu")
		(net "P3E_CPU0_PE1_SS_R_RXN<1>")
	)
	(segment
		(start 382.727708 -3.259328)
		(end 385.530852 -3.82016)
		(width 0.1143)
		(layer "In2.Cu")
		(net "P3E_CPU0_PE1_SS_R_RXN<1>")
	)
	(segment
		(start 337.73745 -58.957972)
		(end 337.62315 -58.843672)
		(width 0.1143)
		(layer "In2.Cu")
		(net "P3E_CPU0_PE1_SS_R_RXN<1>")
	)
	(segment
		(start 414.128204 -3.912362)
		(end 414.533842 -3.411474)
		(width 0.1143)
		(layer "In2.Cu")
		(net "P3E_CPU0_PE1_SS_R_RXN<1>")
	)
	(segment
		(start 348.855792 -50.965862)
		(end 352.5774 -45.382942)
		(width 0.1143)
		(layer "In2.Cu")
		(net "P3E_CPU0_PE1_SS_R_RXN<1>")
	)
	(segment
		(start 405.895302 -3.745738)
		(end 405.895302 -3.745484)
		(width 0.1143)
		(layer "In2.Cu")
		(net "P3E_CPU0_PE1_SS_R_RXN<1>")
	)
	(segment
		(start 380.06528 -4.459478)
		(end 381.495046 -3.505962)
		(width 0.1143)
		(layer "In2.Cu")
		(net "P3E_CPU0_PE1_SS_R_RXN<1>")
	)
	(segment
		(start 412.458916 -2.73177)
		(end 412.698692 -2.73177)
		(width 0.1143)
		(layer "F.Cu")
		(net "P3E_CPU0_PE1_SS_R_RXN<0>")
	)
	(segment
		(start 412.193486 -3.41884)
		(end 412.193486 -2.9972)
		(width 0.1143)
		(layer "F.Cu")
		(net "P3E_CPU0_PE1_SS_R_RXN<0>")
	)
	(segment
		(start 412.193486 -2.9972)
		(end 412.458916 -2.73177)
		(width 0.1143)
		(layer "F.Cu")
		(net "P3E_CPU0_PE1_SS_R_RXN<0>")
	)
	(segment
		(start 412.472886 -3.69824)
		(end 412.193486 -3.41884)
		(width 0.1143)
		(layer "F.Cu")
		(net "P3E_CPU0_PE1_SS_R_RXN<0>")
	)
	(segment
		(start 412.472886 -4.386072)
		(end 412.472886 -3.69824)
		(width 0.1143)
		(layer "F.Cu")
		(net "P3E_CPU0_PE1_SS_R_RXN<0>")
	)
	(via
		(at 335.3816 -58.957972)
		(size 0.508)
		(drill 0.254)
		(layers "F.Cu" "B.Cu")
		(net "P3E_CPU0_PE1_SS_R_RXN<0>")
	)
	(via
		(at 412.698692 -2.73177)
		(size 0.508)
		(drill 0.254)
		(layers "F.Cu" "B.Cu")
		(net "P3E_CPU0_PE1_SS_R_RXN<0>")
	)
	(segment
		(start 334.743806 -59.479434)
		(end 334.860138 -59.479434)
		(width 0.1143)
		(layer "B.Cu")
		(net "P3E_CPU0_PE1_SS_R_RXN<0>")
	)
	(segment
		(start 334.860138 -59.479434)
		(end 335.3816 -58.957972)
		(width 0.1143)
		(layer "B.Cu")
		(net "P3E_CPU0_PE1_SS_R_RXN<0>")
	)
	(segment
		(start 380.796038 -2.084324)
		(end 381.371856 -1.969008)
		(width 0.1143)
		(layer "In2.Cu")
		(net "P3E_CPU0_PE1_SS_R_RXN<0>")
	)
	(segment
		(start 394.257022 -1.750314)
		(end 396.948914 -2.322068)
		(width 0.1143)
		(layer "In2.Cu")
		(net "P3E_CPU0_PE1_SS_R_RXN<0>")
	)
	(segment
		(start 387.48208 -2.437638)
		(end 388.10565 -2.562606)
		(width 0.1143)
		(layer "In2.Cu")
		(net "P3E_CPU0_PE1_SS_R_RXN<0>")
	)
	(segment
		(start 370.283232 -7.16153)
		(end 378.58827 -4.788408)
		(width 0.1143)
		(layer "In2.Cu")
		(net "P3E_CPU0_PE1_SS_R_RXN<0>")
	)
	(segment
		(start 334.94345 -58.957972)
		(end 334.82915 -58.843672)
		(width 0.1143)
		(layer "In2.Cu")
		(net "P3E_CPU0_PE1_SS_R_RXN<0>")
	)
	(segment
		(start 346.555822 -54.079648)
		(end 346.893134 -52.39385)
		(width 0.1143)
		(layer "In2.Cu")
		(net "P3E_CPU0_PE1_SS_R_RXN<0>")
	)
	(segment
		(start 410.81706 -3.9243)
		(end 411.68828 -3.633978)
		(width 0.1143)
		(layer "In2.Cu")
		(net "P3E_CPU0_PE1_SS_R_RXN<0>")
	)
	(segment
		(start 351.615248 -36.219384)
		(end 354.365052 -35.15106)
		(width 0.1143)
		(layer "In2.Cu")
		(net "P3E_CPU0_PE1_SS_R_RXN<0>")
	)
	(segment
		(start 354.365052 -35.15106)
		(end 355.879146 -34.238692)
		(width 0.1143)
		(layer "In2.Cu")
		(net "P3E_CPU0_PE1_SS_R_RXN<0>")
	)
	(segment
		(start 379.226064 -3.83159)
		(end 379.344428 -3.239008)
		(width 0.1143)
		(layer "In2.Cu")
		(net "P3E_CPU0_PE1_SS_R_RXN<0>")
	)
	(segment
		(start 412.158942 -2.84607)
		(end 412.273242 -2.73177)
		(width 0.1143)
		(layer "In2.Cu")
		(net "P3E_CPU0_PE1_SS_R_RXN<0>")
	)
	(segment
		(start 392.531854 -2.116836)
		(end 394.257022 -1.750314)
		(width 0.1143)
		(layer "In2.Cu")
		(net "P3E_CPU0_PE1_SS_R_RXN<0>")
	)
	(segment
		(start 412.158942 -3.163062)
		(end 412.158942 -2.84607)
		(width 0.1143)
		(layer "In2.Cu")
		(net "P3E_CPU0_PE1_SS_R_RXN<0>")
	)
	(segment
		(start 381.371856 -1.969008)
		(end 385.596638 -2.814066)
		(width 0.1143)
		(layer "In2.Cu")
		(net "P3E_CPU0_PE1_SS_R_RXN<0>")
	)
	(segment
		(start 400.094958 -2.482342)
		(end 404.69058 -1.507236)
		(width 0.1143)
		(layer "In2.Cu")
		(net "P3E_CPU0_PE1_SS_R_RXN<0>")
	)
	(segment
		(start 339.804502 -55.822596)
		(end 346.22994 -54.56809)
		(width 0.1143)
		(layer "In2.Cu")
		(net "P3E_CPU0_PE1_SS_R_RXN<0>")
	)
	(segment
		(start 396.948914 -2.322068)
		(end 398.144492 -2.068068)
		(width 0.1143)
		(layer "In2.Cu")
		(net "P3E_CPU0_PE1_SS_R_RXN<0>")
	)
	(segment
		(start 334.82915 -58.61685)
		(end 335.009998 -58.295794)
		(width 0.1143)
		(layer "In2.Cu")
		(net "P3E_CPU0_PE1_SS_R_RXN<0>")
	)
	(segment
		(start 409.892754 -3.9243)
		(end 410.81706 -3.9243)
		(width 0.1143)
		(layer "In2.Cu")
		(net "P3E_CPU0_PE1_SS_R_RXN<0>")
	)
	(segment
		(start 335.3816 -58.957972)
		(end 334.94345 -58.957972)
		(width 0.1143)
		(layer "In2.Cu")
		(net "P3E_CPU0_PE1_SS_R_RXN<0>")
	)
	(segment
		(start 339.381846 -56.104536)
		(end 339.804502 -55.822596)
		(width 0.1143)
		(layer "In2.Cu")
		(net "P3E_CPU0_PE1_SS_R_RXN<0>")
	)
	(segment
		(start 335.009998 -58.295794)
		(end 335.010252 -58.295794)
		(width 0.1143)
		(layer "In2.Cu")
		(net "P3E_CPU0_PE1_SS_R_RXN<0>")
	)
	(segment
		(start 411.68828 -3.633978)
		(end 412.158942 -3.163062)
		(width 0.1143)
		(layer "In2.Cu")
		(net "P3E_CPU0_PE1_SS_R_RXN<0>")
	)
	(segment
		(start 398.144492 -2.068068)
		(end 400.094958 -2.482342)
		(width 0.1143)
		(layer "In2.Cu")
		(net "P3E_CPU0_PE1_SS_R_RXN<0>")
	)
	(segment
		(start 351.3328 -45.731938)
		(end 351.3328 -36.697666)
		(width 0.1143)
		(layer "In2.Cu")
		(net "P3E_CPU0_PE1_SS_R_RXN<0>")
	)
	(segment
		(start 357.179118 -32.287972)
		(end 361.050586 -14.063726)
		(width 0.1143)
		(layer "In2.Cu")
		(net "P3E_CPU0_PE1_SS_R_RXN<0>")
	)
	(segment
		(start 391.36828 -1.86944)
		(end 392.531854 -2.116836)
		(width 0.1143)
		(layer "In2.Cu")
		(net "P3E_CPU0_PE1_SS_R_RXN<0>")
	)
	(segment
		(start 337.83397 -56.413654)
		(end 339.381846 -56.104536)
		(width 0.1143)
		(layer "In2.Cu")
		(net "P3E_CPU0_PE1_SS_R_RXN<0>")
	)
	(segment
		(start 334.82915 -58.843672)
		(end 334.82915 -58.61685)
		(width 0.1143)
		(layer "In2.Cu")
		(net "P3E_CPU0_PE1_SS_R_RXN<0>")
	)
	(segment
		(start 379.568202 -2.90322)
		(end 380.796038 -2.084324)
		(width 0.1143)
		(layer "In2.Cu")
		(net "P3E_CPU0_PE1_SS_R_RXN<0>")
	)
	(segment
		(start 346.893134 -52.39385)
		(end 351.3328 -45.731938)
		(width 0.1143)
		(layer "In2.Cu")
		(net "P3E_CPU0_PE1_SS_R_RXN<0>")
	)
	(segment
		(start 367.539016 -8.99033)
		(end 370.283232 -7.16153)
		(width 0.1143)
		(layer "In2.Cu")
		(net "P3E_CPU0_PE1_SS_R_RXN<0>")
	)
	(segment
		(start 355.879146 -34.238692)
		(end 357.179118 -32.287972)
		(width 0.1143)
		(layer "In2.Cu")
		(net "P3E_CPU0_PE1_SS_R_RXN<0>")
	)
	(segment
		(start 366.993678 -9.808972)
		(end 367.539016 -8.99033)
		(width 0.1143)
		(layer "In2.Cu")
		(net "P3E_CPU0_PE1_SS_R_RXN<0>")
	)
	(segment
		(start 379.344428 -3.239008)
		(end 379.568202 -2.90322)
		(width 0.1143)
		(layer "In2.Cu")
		(net "P3E_CPU0_PE1_SS_R_RXN<0>")
	)
	(segment
		(start 346.22994 -54.56809)
		(end 346.555822 -54.079648)
		(width 0.1143)
		(layer "In2.Cu")
		(net "P3E_CPU0_PE1_SS_R_RXN<0>")
	)
	(segment
		(start 388.10565 -2.562606)
		(end 391.36828 -1.86944)
		(width 0.1143)
		(layer "In2.Cu")
		(net "P3E_CPU0_PE1_SS_R_RXN<0>")
	)
	(segment
		(start 408.227276 -2.258822)
		(end 409.892754 -3.9243)
		(width 0.1143)
		(layer "In2.Cu")
		(net "P3E_CPU0_PE1_SS_R_RXN<0>")
	)
	(segment
		(start 404.69058 -1.507236)
		(end 408.227276 -2.258822)
		(width 0.1143)
		(layer "In2.Cu")
		(net "P3E_CPU0_PE1_SS_R_RXN<0>")
	)
	(segment
		(start 412.273242 -2.73177)
		(end 412.698692 -2.73177)
		(width 0.1143)
		(layer "In2.Cu")
		(net "P3E_CPU0_PE1_SS_R_RXN<0>")
	)
	(segment
		(start 385.596638 -2.814066)
		(end 387.48208 -2.437638)
		(width 0.1143)
		(layer "In2.Cu")
		(net "P3E_CPU0_PE1_SS_R_RXN<0>")
	)
	(segment
		(start 335.010252 -58.295794)
		(end 337.83397 -56.413654)
		(width 0.1143)
		(layer "In2.Cu")
		(net "P3E_CPU0_PE1_SS_R_RXN<0>")
	)
	(segment
		(start 361.050586 -14.063726)
		(end 366.993678 -9.808972)
		(width 0.1143)
		(layer "In2.Cu")
		(net "P3E_CPU0_PE1_SS_R_RXN<0>")
	)
	(segment
		(start 378.58827 -4.788408)
		(end 379.226064 -3.83159)
		(width 0.1143)
		(layer "In2.Cu")
		(net "P3E_CPU0_PE1_SS_R_RXN<0>")
	)
	(segment
		(start 351.3328 -36.697666)
		(end 351.615248 -36.219384)
		(width 0.1143)
		(layer "In2.Cu")
		(net "P3E_CPU0_PE1_SS_R_RXN<0>")
	)
	(segment
		(start 430.075086 -8.657336)
		(end 430.075086 -7.789672)
		(width 0.1143)
		(layer "F.Cu")
		(net "P3E_CPU0_PE1_SS_C_TXP<7>")
	)
	(segment
		(start 429.795686 -8.936736)
		(end 430.075086 -8.657336)
		(width 0.1143)
		(layer "F.Cu")
		(net "P3E_CPU0_PE1_SS_C_TXP<7>")
	)
	(segment
		(start 430.300892 -10.023348)
		(end 429.936148 -10.023348)
		(width 0.1143)
		(layer "F.Cu")
		(net "P3E_CPU0_PE1_SS_C_TXP<7>")
	)
	(segment
		(start 429.795686 -9.882886)
		(end 429.795686 -8.936736)
		(width 0.1143)
		(layer "F.Cu")
		(net "P3E_CPU0_PE1_SS_C_TXP<7>")
	)
	(segment
		(start 429.936148 -10.023348)
		(end 429.795686 -9.882886)
		(width 0.1143)
		(layer "F.Cu")
		(net "P3E_CPU0_PE1_SS_C_TXP<7>")
	)
	(via
		(at 430.300892 -10.023348)
		(size 0.508)
		(drill 0.254)
		(layers "F.Cu" "B.Cu")
		(net "P3E_CPU0_PE1_SS_C_TXP<7>")
	)
	(via
		(at 360.48188 -76.703682)
		(size 0.508)
		(drill 0.254)
		(layers "F.Cu" "B.Cu")
		(net "P3E_CPU0_PE1_SS_C_TXP<7>")
	)
	(segment
		(start 360.151426 -77.034136)
		(end 359.84688 -77.034136)
		(width 0.1143)
		(layer "B.Cu")
		(net "P3E_CPU0_PE1_SS_C_TXP<7>")
	)
	(segment
		(start 360.48188 -76.703682)
		(end 360.151426 -77.034136)
		(width 0.1143)
		(layer "B.Cu")
		(net "P3E_CPU0_PE1_SS_C_TXP<7>")
	)
	(segment
		(start 360.822494 -64.299592)
		(end 358.856026 -65.733168)
		(width 0.1143)
		(layer "In2.Cu")
		(net "P3E_CPU0_PE1_SS_C_TXP<7>")
	)
	(segment
		(start 359.92816 -76.555854)
		(end 359.928414 -76.557124)
		(width 0.1143)
		(layer "In2.Cu")
		(net "P3E_CPU0_PE1_SS_C_TXP<7>")
	)
	(segment
		(start 391.4902 -15.707106)
		(end 388.903972 -15.157704)
		(width 0.1143)
		(layer "In2.Cu")
		(net "P3E_CPU0_PE1_SS_C_TXP<7>")
	)
	(segment
		(start 422.051988 -13.786358)
		(end 412.453836 -15.823438)
		(width 0.1143)
		(layer "In2.Cu")
		(net "P3E_CPU0_PE1_SS_C_TXP<7>")
	)
	(segment
		(start 361.775502 -59.806078)
		(end 360.822494 -64.299592)
		(width 0.1143)
		(layer "In2.Cu")
		(net "P3E_CPU0_PE1_SS_C_TXP<7>")
	)
	(segment
		(start 407.643838 -14.80185)
		(end 405.096726 -15.343378)
		(width 0.1143)
		(layer "In2.Cu")
		(net "P3E_CPU0_PE1_SS_C_TXP<7>")
	)
	(segment
		(start 403.37105 -14.976094)
		(end 402.177504 -15.230348)
		(width 0.1143)
		(layer "In2.Cu")
		(net "P3E_CPU0_PE1_SS_C_TXP<7>")
	)
	(segment
		(start 429.617886 -10.795254)
		(end 427.560994 -11.782806)
		(width 0.1143)
		(layer "In2.Cu")
		(net "P3E_CPU0_PE1_SS_C_TXP<7>")
	)
	(segment
		(start 358.856026 -65.733168)
		(end 357.846884 -68.558918)
		(width 0.1143)
		(layer "In2.Cu")
		(net "P3E_CPU0_PE1_SS_C_TXP<7>")
	)
	(segment
		(start 357.846884 -68.558918)
		(end 359.211372 -72.74306)
		(width 0.1143)
		(layer "In2.Cu")
		(net "P3E_CPU0_PE1_SS_C_TXP<7>")
	)
	(segment
		(start 366.526826 -37.809932)
		(end 366.070896 -40.321992)
		(width 0.1143)
		(layer "In2.Cu")
		(net "P3E_CPU0_PE1_SS_C_TXP<7>")
	)
	(segment
		(start 378.643388 -17.337786)
		(end 377.013978 -16.991838)
		(width 0.1143)
		(layer "In2.Cu")
		(net "P3E_CPU0_PE1_SS_C_TXP<7>")
	)
	(segment
		(start 359.928414 -76.557124)
		(end 359.929684 -76.591668)
		(width 0.1143)
		(layer "In2.Cu")
		(net "P3E_CPU0_PE1_SS_C_TXP<7>")
	)
	(segment
		(start 398.67586 -15.651734)
		(end 395.212824 -14.91615)
		(width 0.1143)
		(layer "In2.Cu")
		(net "P3E_CPU0_PE1_SS_C_TXP<7>")
	)
	(segment
		(start 366.070896 -40.321992)
		(end 364.889288 -42.095928)
		(width 0.1143)
		(layer "In2.Cu")
		(net "P3E_CPU0_PE1_SS_C_TXP<7>")
	)
	(segment
		(start 401.41906 -15.069058)
		(end 398.67586 -15.651734)
		(width 0.1143)
		(layer "In2.Cu")
		(net "P3E_CPU0_PE1_SS_C_TXP<7>")
	)
	(segment
		(start 366.27181 -36.831016)
		(end 366.526826 -37.809932)
		(width 0.1143)
		(layer "In2.Cu")
		(net "P3E_CPU0_PE1_SS_C_TXP<7>")
	)
	(segment
		(start 388.903972 -15.157704)
		(end 378.643388 -17.337786)
		(width 0.1143)
		(layer "In2.Cu")
		(net "P3E_CPU0_PE1_SS_C_TXP<7>")
	)
	(segment
		(start 364.103666 -46.040548)
		(end 364.62208 -47.736506)
		(width 0.1143)
		(layer "In2.Cu")
		(net "P3E_CPU0_PE1_SS_C_TXP<7>")
	)
	(segment
		(start 427.560994 -11.782806)
		(end 425.815506 -11.782806)
		(width 0.1143)
		(layer "In2.Cu")
		(net "P3E_CPU0_PE1_SS_C_TXP<7>")
	)
	(segment
		(start 360.04373 -76.703682)
		(end 360.48188 -76.703682)
		(width 0.1143)
		(layer "In2.Cu")
		(net "P3E_CPU0_PE1_SS_C_TXP<7>")
	)
	(segment
		(start 372.18747 -23.226268)
		(end 370.872258 -24.985726)
		(width 0.1143)
		(layer "In2.Cu")
		(net "P3E_CPU0_PE1_SS_C_TXP<7>")
	)
	(segment
		(start 363.723428 -52.228242)
		(end 364.532926 -54.33568)
		(width 0.1143)
		(layer "In2.Cu")
		(net "P3E_CPU0_PE1_SS_C_TXP<7>")
	)
	(segment
		(start 430.300892 -10.023348)
		(end 429.904906 -10.023348)
		(width 0.1143)
		(layer "In2.Cu")
		(net "P3E_CPU0_PE1_SS_C_TXP<7>")
	)
	(segment
		(start 368.775488 -25.716484)
		(end 368.572542 -26.013156)
		(width 0.1143)
		(layer "In2.Cu")
		(net "P3E_CPU0_PE1_SS_C_TXP<7>")
	)
	(segment
		(start 363.24413 -57.51449)
		(end 361.775502 -59.806078)
		(width 0.1143)
		(layer "In2.Cu")
		(net "P3E_CPU0_PE1_SS_C_TXP<7>")
	)
	(segment
		(start 412.453836 -15.823438)
		(end 407.643838 -14.80185)
		(width 0.1143)
		(layer "In2.Cu")
		(net "P3E_CPU0_PE1_SS_C_TXP<7>")
	)
	(segment
		(start 405.096726 -15.343378)
		(end 403.37105 -14.976094)
		(width 0.1143)
		(layer "In2.Cu")
		(net "P3E_CPU0_PE1_SS_C_TXP<7>")
	)
	(segment
		(start 395.212824 -14.91615)
		(end 391.4902 -15.707106)
		(width 0.1143)
		(layer "In2.Cu")
		(net "P3E_CPU0_PE1_SS_C_TXP<7>")
	)
	(segment
		(start 373.045482 -19.188684)
		(end 372.18747 -23.226268)
		(width 0.1143)
		(layer "In2.Cu")
		(net "P3E_CPU0_PE1_SS_C_TXP<7>")
	)
	(segment
		(start 364.532926 -54.33568)
		(end 363.24413 -57.51449)
		(width 0.1143)
		(layer "In2.Cu")
		(net "P3E_CPU0_PE1_SS_C_TXP<7>")
	)
	(segment
		(start 364.889288 -42.095928)
		(end 364.103666 -46.040548)
		(width 0.1143)
		(layer "In2.Cu")
		(net "P3E_CPU0_PE1_SS_C_TXP<7>")
	)
	(segment
		(start 370.872258 -24.985726)
		(end 368.775488 -25.716484)
		(width 0.1143)
		(layer "In2.Cu")
		(net "P3E_CPU0_PE1_SS_C_TXP<7>")
	)
	(segment
		(start 429.8315 -10.096754)
		(end 429.8315 -10.58164)
		(width 0.1143)
		(layer "In2.Cu")
		(net "P3E_CPU0_PE1_SS_C_TXP<7>")
	)
	(segment
		(start 402.177504 -15.230348)
		(end 401.41906 -15.069058)
		(width 0.1143)
		(layer "In2.Cu")
		(net "P3E_CPU0_PE1_SS_C_TXP<7>")
	)
	(segment
		(start 359.211372 -72.74306)
		(end 359.92816 -76.555854)
		(width 0.1143)
		(layer "In2.Cu")
		(net "P3E_CPU0_PE1_SS_C_TXP<7>")
	)
	(segment
		(start 375.237248 -17.61871)
		(end 373.045482 -19.188684)
		(width 0.1143)
		(layer "In2.Cu")
		(net "P3E_CPU0_PE1_SS_C_TXP<7>")
	)
	(segment
		(start 377.013978 -16.991838)
		(end 375.237248 -17.61871)
		(width 0.1143)
		(layer "In2.Cu")
		(net "P3E_CPU0_PE1_SS_C_TXP<7>")
	)
	(segment
		(start 429.904906 -10.023348)
		(end 429.8315 -10.096754)
		(width 0.1143)
		(layer "In2.Cu")
		(net "P3E_CPU0_PE1_SS_C_TXP<7>")
	)
	(segment
		(start 368.572542 -26.013156)
		(end 366.27181 -36.831016)
		(width 0.1143)
		(layer "In2.Cu")
		(net "P3E_CPU0_PE1_SS_C_TXP<7>")
	)
	(segment
		(start 364.62208 -47.736506)
		(end 363.723428 -52.228242)
		(width 0.1143)
		(layer "In2.Cu")
		(net "P3E_CPU0_PE1_SS_C_TXP<7>")
	)
	(segment
		(start 425.815506 -11.782806)
		(end 425.444412 -12.1539)
		(width 0.1143)
		(layer "In2.Cu")
		(net "P3E_CPU0_PE1_SS_C_TXP<7>")
	)
	(segment
		(start 429.8315 -10.58164)
		(end 429.617886 -10.795254)
		(width 0.1143)
		(layer "In2.Cu")
		(net "P3E_CPU0_PE1_SS_C_TXP<7>")
	)
	(segment
		(start 425.444412 -12.1539)
		(end 423.684446 -12.1539)
		(width 0.1143)
		(layer "In2.Cu")
		(net "P3E_CPU0_PE1_SS_C_TXP<7>")
	)
	(segment
		(start 423.684446 -12.1539)
		(end 422.051988 -13.786358)
		(width 0.1143)
		(layer "In2.Cu")
		(net "P3E_CPU0_PE1_SS_C_TXP<7>")
	)
	(arc
		(start 359.929684 -76.591668)
		(mid 359.963796 -76.671007)
		(end 360.04373 -76.703682)
		(width 0.1143)
		(layer "In2.Cu")
		(net "P3E_CPU0_PE1_SS_C_TXP<7>")
	)
	(segment
		(start 426.874686 -8.657336)
		(end 426.874686 -7.789672)
		(width 0.1143)
		(layer "F.Cu")
		(net "P3E_CPU0_PE1_SS_C_TXP<6>")
	)
	(segment
		(start 427.154086 -9.878314)
		(end 427.154086 -8.936736)
		(width 0.1143)
		(layer "F.Cu")
		(net "P3E_CPU0_PE1_SS_C_TXP<6>")
	)
	(segment
		(start 427.154086 -8.936736)
		(end 426.874686 -8.657336)
		(width 0.1143)
		(layer "F.Cu")
		(net "P3E_CPU0_PE1_SS_C_TXP<6>")
	)
	(segment
		(start 426.630592 -10.023348)
		(end 427.009052 -10.023348)
		(width 0.1143)
		(layer "F.Cu")
		(net "P3E_CPU0_PE1_SS_C_TXP<6>")
	)
	(segment
		(start 427.009052 -10.023348)
		(end 427.154086 -9.878314)
		(width 0.1143)
		(layer "F.Cu")
		(net "P3E_CPU0_PE1_SS_C_TXP<6>")
	)
	(via
		(at 426.630592 -10.023348)
		(size 0.508)
		(drill 0.254)
		(layers "F.Cu" "B.Cu")
		(net "P3E_CPU0_PE1_SS_C_TXP<6>")
	)
	(via
		(at 356.371398 -76.719684)
		(size 0.508)
		(drill 0.254)
		(layers "F.Cu" "B.Cu")
		(net "P3E_CPU0_PE1_SS_C_TXP<6>")
	)
	(segment
		(start 356.064566 -77.026516)
		(end 356.371398 -76.719684)
		(width 0.1143)
		(layer "B.Cu")
		(net "P3E_CPU0_PE1_SS_C_TXP<6>")
	)
	(segment
		(start 355.736398 -77.026516)
		(end 356.064566 -77.026516)
		(width 0.1143)
		(layer "B.Cu")
		(net "P3E_CPU0_PE1_SS_C_TXP<6>")
	)
	(segment
		(start 412.437072 -14.860016)
		(end 421.59428 -12.916408)
		(width 0.1143)
		(layer "In2.Cu")
		(net "P3E_CPU0_PE1_SS_C_TXP<6>")
	)
	(segment
		(start 356.923848 -76.605384)
		(end 356.923848 -75.058016)
		(width 0.1143)
		(layer "In2.Cu")
		(net "P3E_CPU0_PE1_SS_C_TXP<6>")
	)
	(segment
		(start 427.1264 -10.483342)
		(end 427.1264 -10.1346)
		(width 0.1143)
		(layer "In2.Cu")
		(net "P3E_CPU0_PE1_SS_C_TXP<6>")
	)
	(segment
		(start 426.890688 -10.719054)
		(end 427.1264 -10.483342)
		(width 0.1143)
		(layer "In2.Cu")
		(net "P3E_CPU0_PE1_SS_C_TXP<6>")
	)
	(segment
		(start 370.139214 -24.245824)
		(end 371.35181 -22.623526)
		(width 0.1143)
		(layer "In2.Cu")
		(net "P3E_CPU0_PE1_SS_C_TXP<6>")
	)
	(segment
		(start 363.459014 -54.215538)
		(end 362.108242 -50.705258)
		(width 0.1143)
		(layer "In2.Cu")
		(net "P3E_CPU0_PE1_SS_C_TXP<6>")
	)
	(segment
		(start 371.35181 -22.623526)
		(end 372.204488 -18.610326)
		(width 0.1143)
		(layer "In2.Cu")
		(net "P3E_CPU0_PE1_SS_C_TXP<6>")
	)
	(segment
		(start 364.718092 -37.583872)
		(end 364.718092 -37.583618)
		(width 0.1143)
		(layer "In2.Cu")
		(net "P3E_CPU0_PE1_SS_C_TXP<6>")
	)
	(segment
		(start 423.283888 -11.2268)
		(end 424.985942 -11.2268)
		(width 0.1143)
		(layer "In2.Cu")
		(net "P3E_CPU0_PE1_SS_C_TXP<6>")
	)
	(segment
		(start 401.401788 -14.111986)
		(end 402.16455 -14.274038)
		(width 0.1143)
		(layer "In2.Cu")
		(net "P3E_CPU0_PE1_SS_C_TXP<6>")
	)
	(segment
		(start 362.10113 -57.562496)
		(end 363.459014 -54.215538)
		(width 0.1143)
		(layer "In2.Cu")
		(net "P3E_CPU0_PE1_SS_C_TXP<6>")
	)
	(segment
		(start 378.67971 -16.380714)
		(end 388.910322 -14.208252)
		(width 0.1143)
		(layer "In2.Cu")
		(net "P3E_CPU0_PE1_SS_C_TXP<6>")
	)
	(segment
		(start 360.167682 -62.89802)
		(end 360.90225 -59.432444)
		(width 0.1143)
		(layer "In2.Cu")
		(net "P3E_CPU0_PE1_SS_C_TXP<6>")
	)
	(segment
		(start 388.910322 -14.208252)
		(end 391.488168 -14.757146)
		(width 0.1143)
		(layer "In2.Cu")
		(net "P3E_CPU0_PE1_SS_C_TXP<6>")
	)
	(segment
		(start 364.718092 -37.583618)
		(end 365.353854 -36.630102)
		(width 0.1143)
		(layer "In2.Cu")
		(net "P3E_CPU0_PE1_SS_C_TXP<6>")
	)
	(segment
		(start 403.37613 -14.016482)
		(end 405.09698 -14.382496)
		(width 0.1143)
		(layer "In2.Cu")
		(net "P3E_CPU0_PE1_SS_C_TXP<6>")
	)
	(segment
		(start 358.068372 -65.144396)
		(end 359.988104 -63.74511)
		(width 0.1143)
		(layer "In2.Cu")
		(net "P3E_CPU0_PE1_SS_C_TXP<6>")
	)
	(segment
		(start 374.703848 -16.82115)
		(end 376.977402 -16.01978)
		(width 0.1143)
		(layer "In2.Cu")
		(net "P3E_CPU0_PE1_SS_C_TXP<6>")
	)
	(segment
		(start 365.353854 -36.630102)
		(end 367.691416 -25.636474)
		(width 0.1143)
		(layer "In2.Cu")
		(net "P3E_CPU0_PE1_SS_C_TXP<6>")
	)
	(segment
		(start 398.675352 -14.690598)
		(end 401.401788 -14.111986)
		(width 0.1143)
		(layer "In2.Cu")
		(net "P3E_CPU0_PE1_SS_C_TXP<6>")
	)
	(segment
		(start 372.204488 -18.610326)
		(end 374.703848 -16.82115)
		(width 0.1143)
		(layer "In2.Cu")
		(net "P3E_CPU0_PE1_SS_C_TXP<6>")
	)
	(segment
		(start 424.985942 -11.2268)
		(end 425.493688 -10.719054)
		(width 0.1143)
		(layer "In2.Cu")
		(net "P3E_CPU0_PE1_SS_C_TXP<6>")
	)
	(segment
		(start 376.977402 -16.01978)
		(end 378.67971 -16.380714)
		(width 0.1143)
		(layer "In2.Cu")
		(net "P3E_CPU0_PE1_SS_C_TXP<6>")
	)
	(segment
		(start 425.493688 -10.719054)
		(end 426.890688 -10.719054)
		(width 0.1143)
		(layer "In2.Cu")
		(net "P3E_CPU0_PE1_SS_C_TXP<6>")
	)
	(segment
		(start 402.16455 -14.273784)
		(end 402.164804 -14.274038)
		(width 0.1143)
		(layer "In2.Cu")
		(net "P3E_CPU0_PE1_SS_C_TXP<6>")
	)
	(segment
		(start 405.09698 -14.382496)
		(end 407.641044 -13.84173)
		(width 0.1143)
		(layer "In2.Cu")
		(net "P3E_CPU0_PE1_SS_C_TXP<6>")
	)
	(segment
		(start 356.371398 -76.719684)
		(end 356.809548 -76.719684)
		(width 0.1143)
		(layer "In2.Cu")
		(net "P3E_CPU0_PE1_SS_C_TXP<6>")
	)
	(segment
		(start 395.237716 -13.960602)
		(end 398.675352 -14.690598)
		(width 0.1143)
		(layer "In2.Cu")
		(net "P3E_CPU0_PE1_SS_C_TXP<6>")
	)
	(segment
		(start 427.1264 -10.1346)
		(end 427.015148 -10.023348)
		(width 0.1143)
		(layer "In2.Cu")
		(net "P3E_CPU0_PE1_SS_C_TXP<6>")
	)
	(segment
		(start 368.17427 -24.9301)
		(end 370.139214 -24.245824)
		(width 0.1143)
		(layer "In2.Cu")
		(net "P3E_CPU0_PE1_SS_C_TXP<6>")
	)
	(segment
		(start 391.488168 -14.757146)
		(end 395.237716 -13.960602)
		(width 0.1143)
		(layer "In2.Cu")
		(net "P3E_CPU0_PE1_SS_C_TXP<6>")
	)
	(segment
		(start 359.988104 -63.74511)
		(end 360.167682 -62.89802)
		(width 0.1143)
		(layer "In2.Cu")
		(net "P3E_CPU0_PE1_SS_C_TXP<6>")
	)
	(segment
		(start 362.108242 -50.705258)
		(end 364.718092 -37.583872)
		(width 0.1143)
		(layer "In2.Cu")
		(net "P3E_CPU0_PE1_SS_C_TXP<6>")
	)
	(segment
		(start 357.69296 -72.498712)
		(end 356.66934 -69.061584)
		(width 0.1143)
		(layer "In2.Cu")
		(net "P3E_CPU0_PE1_SS_C_TXP<6>")
	)
	(segment
		(start 402.16455 -14.274038)
		(end 402.16455 -14.273784)
		(width 0.1143)
		(layer "In2.Cu")
		(net "P3E_CPU0_PE1_SS_C_TXP<6>")
	)
	(segment
		(start 360.90225 -59.432444)
		(end 362.10113 -57.562496)
		(width 0.1143)
		(layer "In2.Cu")
		(net "P3E_CPU0_PE1_SS_C_TXP<6>")
	)
	(segment
		(start 407.641044 -13.84173)
		(end 412.437072 -14.860016)
		(width 0.1143)
		(layer "In2.Cu")
		(net "P3E_CPU0_PE1_SS_C_TXP<6>")
	)
	(segment
		(start 367.691416 -25.636474)
		(end 368.17427 -24.9301)
		(width 0.1143)
		(layer "In2.Cu")
		(net "P3E_CPU0_PE1_SS_C_TXP<6>")
	)
	(segment
		(start 427.015148 -10.023348)
		(end 426.630592 -10.023348)
		(width 0.1143)
		(layer "In2.Cu")
		(net "P3E_CPU0_PE1_SS_C_TXP<6>")
	)
	(segment
		(start 421.59428 -12.916408)
		(end 423.283888 -11.2268)
		(width 0.1143)
		(layer "In2.Cu")
		(net "P3E_CPU0_PE1_SS_C_TXP<6>")
	)
	(segment
		(start 356.923848 -75.058016)
		(end 357.69296 -72.498712)
		(width 0.1143)
		(layer "In2.Cu")
		(net "P3E_CPU0_PE1_SS_C_TXP<6>")
	)
	(segment
		(start 402.164804 -14.274038)
		(end 403.37613 -14.016482)
		(width 0.1143)
		(layer "In2.Cu")
		(net "P3E_CPU0_PE1_SS_C_TXP<6>")
	)
	(segment
		(start 356.66934 -69.061584)
		(end 358.068372 -65.144396)
		(width 0.1143)
		(layer "In2.Cu")
		(net "P3E_CPU0_PE1_SS_C_TXP<6>")
	)
	(arc
		(start 356.809548 -76.719684)
		(mid 356.89037 -76.686206)
		(end 356.923848 -76.605384)
		(width 0.1143)
		(layer "In2.Cu")
		(net "P3E_CPU0_PE1_SS_C_TXP<6>")
	)
	(segment
		(start 424.474386 -8.657336)
		(end 424.753786 -8.936736)
		(width 0.1143)
		(layer "F.Cu")
		(net "P3E_CPU0_PE1_SS_C_TXP<5>")
	)
	(segment
		(start 424.545252 -10.023348)
		(end 424.230292 -10.023348)
		(width 0.1143)
		(layer "F.Cu")
		(net "P3E_CPU0_PE1_SS_C_TXP<5>")
	)
	(segment
		(start 424.753786 -8.936736)
		(end 424.753786 -9.814814)
		(width 0.1143)
		(layer "F.Cu")
		(net "P3E_CPU0_PE1_SS_C_TXP<5>")
	)
	(segment
		(start 424.753786 -9.814814)
		(end 424.545252 -10.023348)
		(width 0.1143)
		(layer "F.Cu")
		(net "P3E_CPU0_PE1_SS_C_TXP<5>")
	)
	(segment
		(start 424.474386 -7.789672)
		(end 424.474386 -8.657336)
		(width 0.1143)
		(layer "F.Cu")
		(net "P3E_CPU0_PE1_SS_C_TXP<5>")
	)
	(via
		(at 424.230292 -10.023348)
		(size 0.508)
		(drill 0.254)
		(layers "F.Cu" "B.Cu")
		(net "P3E_CPU0_PE1_SS_C_TXP<5>")
	)
	(via
		(at 353.60229 -76.720954)
		(size 0.508)
		(drill 0.254)
		(layers "F.Cu" "B.Cu")
		(net "P3E_CPU0_PE1_SS_C_TXP<5>")
	)
	(segment
		(start 353.60229 -76.720954)
		(end 353.296728 -77.026516)
		(width 0.1143)
		(layer "B.Cu")
		(net "P3E_CPU0_PE1_SS_C_TXP<5>")
	)
	(segment
		(start 353.296728 -77.026516)
		(end 352.96729 -77.026516)
		(width 0.1143)
		(layer "B.Cu")
		(net "P3E_CPU0_PE1_SS_C_TXP<5>")
	)
	(segment
		(start 405.078946 -13.724128)
		(end 407.659332 -13.175488)
		(width 0.1143)
		(layer "In2.Cu")
		(net "P3E_CPU0_PE1_SS_C_TXP<5>")
	)
	(segment
		(start 353.60229 -76.720954)
		(end 354.04044 -76.720954)
		(width 0.1143)
		(layer "In2.Cu")
		(net "P3E_CPU0_PE1_SS_C_TXP<5>")
	)
	(segment
		(start 354.15474 -73.624948)
		(end 353.853496 -71.943468)
		(width 0.1143)
		(layer "In2.Cu")
		(net "P3E_CPU0_PE1_SS_C_TXP<5>")
	)
	(segment
		(start 423.004996 -10.591546)
		(end 424.630596 -10.591546)
		(width 0.1143)
		(layer "In2.Cu")
		(net "P3E_CPU0_PE1_SS_C_TXP<5>")
	)
	(segment
		(start 370.360448 -22.125686)
		(end 370.70538 -21.895816)
		(width 0.1143)
		(layer "In2.Cu")
		(net "P3E_CPU0_PE1_SS_C_TXP<5>")
	)
	(segment
		(start 395.2621 -13.303504)
		(end 398.67586 -14.028674)
		(width 0.1143)
		(layer "In2.Cu")
		(net "P3E_CPU0_PE1_SS_C_TXP<5>")
	)
	(segment
		(start 364.041436 -37.430964)
		(end 364.746286 -36.373308)
		(width 0.1143)
		(layer "In2.Cu")
		(net "P3E_CPU0_PE1_SS_C_TXP<5>")
	)
	(segment
		(start 424.630596 -10.591546)
		(end 424.7515 -10.470642)
		(width 0.1143)
		(layer "In2.Cu")
		(net "P3E_CPU0_PE1_SS_C_TXP<5>")
	)
	(segment
		(start 424.7515 -10.470642)
		(end 424.7515 -10.120884)
		(width 0.1143)
		(layer "In2.Cu")
		(net "P3E_CPU0_PE1_SS_C_TXP<5>")
	)
	(segment
		(start 421.272462 -12.323826)
		(end 423.004996 -10.591546)
		(width 0.1143)
		(layer "In2.Cu")
		(net "P3E_CPU0_PE1_SS_C_TXP<5>")
	)
	(segment
		(start 362.715048 -54.081426)
		(end 361.396788 -50.653188)
		(width 0.1143)
		(layer "In2.Cu")
		(net "P3E_CPU0_PE1_SS_C_TXP<5>")
	)
	(segment
		(start 424.7515 -10.120884)
		(end 424.653964 -10.023348)
		(width 0.1143)
		(layer "In2.Cu")
		(net "P3E_CPU0_PE1_SS_C_TXP<5>")
	)
	(segment
		(start 353.853496 -71.943468)
		(end 356.383336 -67.936364)
		(width 0.1143)
		(layer "In2.Cu")
		(net "P3E_CPU0_PE1_SS_C_TXP<5>")
	)
	(segment
		(start 370.70538 -21.895816)
		(end 370.924328 -21.566632)
		(width 0.1143)
		(layer "In2.Cu")
		(net "P3E_CPU0_PE1_SS_C_TXP<5>")
	)
	(segment
		(start 359.417874 -63.358522)
		(end 360.167682 -59.82208)
		(width 0.1143)
		(layer "In2.Cu")
		(net "P3E_CPU0_PE1_SS_C_TXP<5>")
	)
	(segment
		(start 403.386544 -13.36421)
		(end 405.078946 -13.724128)
		(width 0.1143)
		(layer "In2.Cu")
		(net "P3E_CPU0_PE1_SS_C_TXP<5>")
	)
	(segment
		(start 360.167682 -59.82208)
		(end 360.32313 -59.089036)
		(width 0.1143)
		(layer "In2.Cu")
		(net "P3E_CPU0_PE1_SS_C_TXP<5>")
	)
	(segment
		(start 371.637814 -18.210022)
		(end 374.346216 -16.270986)
		(width 0.1143)
		(layer "In2.Cu")
		(net "P3E_CPU0_PE1_SS_C_TXP<5>")
	)
	(segment
		(start 378.737114 -15.714726)
		(end 388.900162 -13.554456)
		(width 0.1143)
		(layer "In2.Cu")
		(net "P3E_CPU0_PE1_SS_C_TXP<5>")
	)
	(segment
		(start 398.67586 -14.028674)
		(end 401.407376 -13.448538)
		(width 0.1143)
		(layer "In2.Cu")
		(net "P3E_CPU0_PE1_SS_C_TXP<5>")
	)
	(segment
		(start 364.746286 -36.373308)
		(end 367.26749 -24.517858)
		(width 0.1143)
		(layer "In2.Cu")
		(net "P3E_CPU0_PE1_SS_C_TXP<5>")
	)
	(segment
		(start 424.653964 -10.023348)
		(end 424.230292 -10.023348)
		(width 0.1143)
		(layer "In2.Cu")
		(net "P3E_CPU0_PE1_SS_C_TXP<5>")
	)
	(segment
		(start 357.525066 -64.73825)
		(end 359.417874 -63.358522)
		(width 0.1143)
		(layer "In2.Cu")
		(net "P3E_CPU0_PE1_SS_C_TXP<5>")
	)
	(segment
		(start 370.924328 -21.566632)
		(end 371.637814 -18.210022)
		(width 0.1143)
		(layer "In2.Cu")
		(net "P3E_CPU0_PE1_SS_C_TXP<5>")
	)
	(segment
		(start 368.275616 -23.004272)
		(end 369.265708 -22.344634)
		(width 0.1143)
		(layer "In2.Cu")
		(net "P3E_CPU0_PE1_SS_C_TXP<5>")
	)
	(segment
		(start 360.32313 -59.089036)
		(end 361.307888 -57.552844)
		(width 0.1143)
		(layer "In2.Cu")
		(net "P3E_CPU0_PE1_SS_C_TXP<5>")
	)
	(segment
		(start 369.265708 -22.344634)
		(end 370.360448 -22.125686)
		(width 0.1143)
		(layer "In2.Cu")
		(net "P3E_CPU0_PE1_SS_C_TXP<5>")
	)
	(segment
		(start 391.489692 -14.105128)
		(end 395.2621 -13.303504)
		(width 0.1143)
		(layer "In2.Cu")
		(net "P3E_CPU0_PE1_SS_C_TXP<5>")
	)
	(segment
		(start 376.982228 -15.342108)
		(end 378.737114 -15.714726)
		(width 0.1143)
		(layer "In2.Cu")
		(net "P3E_CPU0_PE1_SS_C_TXP<5>")
	)
	(segment
		(start 401.407376 -13.448538)
		(end 402.19884 -13.616686)
		(width 0.1143)
		(layer "In2.Cu")
		(net "P3E_CPU0_PE1_SS_C_TXP<5>")
	)
	(segment
		(start 388.900162 -13.554456)
		(end 391.489692 -14.105128)
		(width 0.1143)
		(layer "In2.Cu")
		(net "P3E_CPU0_PE1_SS_C_TXP<5>")
	)
	(segment
		(start 356.383336 -67.936364)
		(end 357.525066 -64.73825)
		(width 0.1143)
		(layer "In2.Cu")
		(net "P3E_CPU0_PE1_SS_C_TXP<5>")
	)
	(segment
		(start 374.346216 -16.270986)
		(end 376.982228 -15.342108)
		(width 0.1143)
		(layer "In2.Cu")
		(net "P3E_CPU0_PE1_SS_C_TXP<5>")
	)
	(segment
		(start 354.15474 -76.606654)
		(end 354.15474 -73.624948)
		(width 0.1143)
		(layer "In2.Cu")
		(net "P3E_CPU0_PE1_SS_C_TXP<5>")
	)
	(segment
		(start 412.459424 -14.195298)
		(end 421.272462 -12.323826)
		(width 0.1143)
		(layer "In2.Cu")
		(net "P3E_CPU0_PE1_SS_C_TXP<5>")
	)
	(segment
		(start 367.26749 -24.517858)
		(end 368.275616 -23.004272)
		(width 0.1143)
		(layer "In2.Cu")
		(net "P3E_CPU0_PE1_SS_C_TXP<5>")
	)
	(segment
		(start 361.396788 -50.653188)
		(end 364.041436 -37.430964)
		(width 0.1143)
		(layer "In2.Cu")
		(net "P3E_CPU0_PE1_SS_C_TXP<5>")
	)
	(segment
		(start 407.659332 -13.175488)
		(end 412.459424 -14.195298)
		(width 0.1143)
		(layer "In2.Cu")
		(net "P3E_CPU0_PE1_SS_C_TXP<5>")
	)
	(segment
		(start 402.19884 -13.616686)
		(end 403.386544 -13.36421)
		(width 0.1143)
		(layer "In2.Cu")
		(net "P3E_CPU0_PE1_SS_C_TXP<5>")
	)
	(segment
		(start 361.307888 -57.552844)
		(end 362.715048 -54.081426)
		(width 0.1143)
		(layer "In2.Cu")
		(net "P3E_CPU0_PE1_SS_C_TXP<5>")
	)
	(arc
		(start 354.04044 -76.720954)
		(mid 354.121262 -76.687476)
		(end 354.15474 -76.606654)
		(width 0.1143)
		(layer "In2.Cu")
		(net "P3E_CPU0_PE1_SS_C_TXP<5>")
	)
	(segment
		(start 422.344342 -8.927592)
		(end 422.344342 -9.909048)
		(width 0.1143)
		(layer "F.Cu")
		(net "P3E_CPU0_PE1_SS_C_TXP<4>")
	)
	(segment
		(start 422.074086 -8.657336)
		(end 422.344342 -8.927592)
		(width 0.1143)
		(layer "F.Cu")
		(net "P3E_CPU0_PE1_SS_C_TXP<4>")
	)
	(segment
		(start 422.230042 -10.023348)
		(end 421.829992 -10.023348)
		(width 0.1143)
		(layer "F.Cu")
		(net "P3E_CPU0_PE1_SS_C_TXP<4>")
	)
	(segment
		(start 422.074086 -7.789672)
		(end 422.074086 -8.657336)
		(width 0.1143)
		(layer "F.Cu")
		(net "P3E_CPU0_PE1_SS_C_TXP<4>")
	)
	(segment
		(start 422.344342 -9.909048)
		(end 422.230042 -10.023348)
		(width 0.1143)
		(layer "F.Cu")
		(net "P3E_CPU0_PE1_SS_C_TXP<4>")
	)
	(via
		(at 350.672654 -76.57211)
		(size 0.508)
		(drill 0.254)
		(layers "F.Cu" "B.Cu")
		(net "P3E_CPU0_PE1_SS_C_TXP<4>")
	)
	(via
		(at 421.829992 -10.023348)
		(size 0.508)
		(drill 0.254)
		(layers "F.Cu" "B.Cu")
		(net "P3E_CPU0_PE1_SS_C_TXP<4>")
	)
	(segment
		(start 350.672654 -76.57211)
		(end 350.299528 -76.945236)
		(width 0.1143)
		(layer "B.Cu")
		(net "P3E_CPU0_PE1_SS_C_TXP<4>")
	)
	(segment
		(start 350.299528 -76.945236)
		(end 350.024192 -76.945236)
		(width 0.1143)
		(layer "B.Cu")
		(net "P3E_CPU0_PE1_SS_C_TXP<4>")
	)
	(segment
		(start 352.67392 -72.87514)
		(end 353.307904 -71.593456)
		(width 0.1143)
		(layer "In2.Cu")
		(net "P3E_CPU0_PE1_SS_C_TXP<4>")
	)
	(segment
		(start 405.078946 -13.06195)
		(end 407.652982 -12.51458)
		(width 0.1143)
		(layer "In2.Cu")
		(net "P3E_CPU0_PE1_SS_C_TXP<4>")
	)
	(segment
		(start 402.172424 -12.957556)
		(end 403.379432 -12.700508)
		(width 0.1143)
		(layer "In2.Cu")
		(net "P3E_CPU0_PE1_SS_C_TXP<4>")
	)
	(segment
		(start 352.804222 -73.256902)
		(end 352.67392 -72.87514)
		(width 0.1143)
		(layer "In2.Cu")
		(net "P3E_CPU0_PE1_SS_C_TXP<4>")
	)
	(segment
		(start 350.672654 -76.57211)
		(end 351.094802 -76.57211)
		(width 0.1143)
		(layer "In2.Cu")
		(net "P3E_CPU0_PE1_SS_C_TXP<4>")
	)
	(segment
		(start 370.67617 -19.047968)
		(end 371.084348 -17.803368)
		(width 0.1143)
		(layer "In2.Cu")
		(net "P3E_CPU0_PE1_SS_C_TXP<4>")
	)
	(segment
		(start 403.379432 -12.700508)
		(end 405.078946 -13.06195)
		(width 0.1143)
		(layer "In2.Cu")
		(net "P3E_CPU0_PE1_SS_C_TXP<4>")
	)
	(segment
		(start 363.414818 -37.197538)
		(end 364.140242 -36.109656)
		(width 0.1143)
		(layer "In2.Cu")
		(net "P3E_CPU0_PE1_SS_C_TXP<4>")
	)
	(segment
		(start 412.458916 -13.535152)
		(end 419.184328 -12.107672)
		(width 0.1143)
		(layer "In2.Cu")
		(net "P3E_CPU0_PE1_SS_C_TXP<4>")
	)
	(segment
		(start 352.602292 -73.667366)
		(end 352.964242 -73.845166)
		(width 0.1143)
		(layer "In2.Cu")
		(net "P3E_CPU0_PE1_SS_C_TXP<4>")
	)
	(segment
		(start 366.945926 -22.916642)
		(end 368.33683 -20.830032)
		(width 0.1143)
		(layer "In2.Cu")
		(net "P3E_CPU0_PE1_SS_C_TXP<4>")
	)
	(segment
		(start 352.012504 -74.22134)
		(end 352.220784 -73.797414)
		(width 0.1143)
		(layer "In2.Cu")
		(net "P3E_CPU0_PE1_SS_C_TXP<4>")
	)
	(segment
		(start 395.28623 -12.64666)
		(end 398.676114 -13.366242)
		(width 0.1143)
		(layer "In2.Cu")
		(net "P3E_CPU0_PE1_SS_C_TXP<4>")
	)
	(segment
		(start 352.142552 -74.602848)
		(end 352.012504 -74.22134)
		(width 0.1143)
		(layer "In2.Cu")
		(net "P3E_CPU0_PE1_SS_C_TXP<4>")
	)
	(segment
		(start 352.302826 -75.191112)
		(end 352.45548 -75.139042)
		(width 0.1143)
		(layer "In2.Cu")
		(net "P3E_CPU0_PE1_SS_C_TXP<4>")
	)
	(segment
		(start 352.556572 -74.933302)
		(end 352.504502 -74.780648)
		(width 0.1143)
		(layer "In2.Cu")
		(net "P3E_CPU0_PE1_SS_C_TXP<4>")
	)
	(segment
		(start 352.964242 -73.845166)
		(end 353.116896 -73.793096)
		(width 0.1143)
		(layer "In2.Cu")
		(net "P3E_CPU0_PE1_SS_C_TXP<4>")
	)
	(segment
		(start 422.347644 -10.2997)
		(end 422.347644 -10.137648)
		(width 0.1143)
		(layer "In2.Cu")
		(net "P3E_CPU0_PE1_SS_C_TXP<4>")
	)
	(segment
		(start 351.940876 -75.013312)
		(end 352.302826 -75.191112)
		(width 0.1143)
		(layer "In2.Cu")
		(net "P3E_CPU0_PE1_SS_C_TXP<4>")
	)
	(segment
		(start 351.20834 -76.471018)
		(end 351.209102 -76.45781)
		(width 0.1143)
		(layer "In2.Cu")
		(net "P3E_CPU0_PE1_SS_C_TXP<4>")
	)
	(segment
		(start 361.044998 -52.209446)
		(end 360.725974 -50.614072)
		(width 0.1143)
		(layer "In2.Cu")
		(net "P3E_CPU0_PE1_SS_C_TXP<4>")
	)
	(segment
		(start 360.396282 -56.976264)
		(end 360.241342 -56.220614)
		(width 0.1143)
		(layer "In2.Cu")
		(net "P3E_CPU0_PE1_SS_C_TXP<4>")
	)
	(segment
		(start 364.140242 -36.109656)
		(end 366.945926 -22.916642)
		(width 0.1143)
		(layer "In2.Cu")
		(net "P3E_CPU0_PE1_SS_C_TXP<4>")
	)
	(segment
		(start 422.106344 -10.541)
		(end 422.347644 -10.2997)
		(width 0.1143)
		(layer "In2.Cu")
		(net "P3E_CPU0_PE1_SS_C_TXP<4>")
	)
	(segment
		(start 420.751 -10.541)
		(end 422.106344 -10.541)
		(width 0.1143)
		(layer "In2.Cu")
		(net "P3E_CPU0_PE1_SS_C_TXP<4>")
	)
	(segment
		(start 353.116896 -73.793096)
		(end 353.217988 -73.587356)
		(width 0.1143)
		(layer "In2.Cu")
		(net "P3E_CPU0_PE1_SS_C_TXP<4>")
	)
	(segment
		(start 353.217988 -73.587356)
		(end 353.165918 -73.434702)
		(width 0.1143)
		(layer "In2.Cu")
		(net "P3E_CPU0_PE1_SS_C_TXP<4>")
	)
	(segment
		(start 407.652982 -12.51458)
		(end 412.458916 -13.535152)
		(width 0.1143)
		(layer "In2.Cu")
		(net "P3E_CPU0_PE1_SS_C_TXP<4>")
	)
	(segment
		(start 352.220784 -73.797414)
		(end 352.602292 -73.667366)
		(width 0.1143)
		(layer "In2.Cu")
		(net "P3E_CPU0_PE1_SS_C_TXP<4>")
	)
	(segment
		(start 422.233344 -10.023348)
		(end 421.829992 -10.023348)
		(width 0.1143)
		(layer "In2.Cu")
		(net "P3E_CPU0_PE1_SS_C_TXP<4>")
	)
	(segment
		(start 360.241342 -56.220614)
		(end 361.044998 -52.209446)
		(width 0.1143)
		(layer "In2.Cu")
		(net "P3E_CPU0_PE1_SS_C_TXP<4>")
	)
	(segment
		(start 359.656634 -59.029092)
		(end 360.396282 -56.976264)
		(width 0.1143)
		(layer "In2.Cu")
		(net "P3E_CPU0_PE1_SS_C_TXP<4>")
	)
	(segment
		(start 373.996712 -15.718536)
		(end 376.997722 -14.660118)
		(width 0.1143)
		(layer "In2.Cu")
		(net "P3E_CPU0_PE1_SS_C_TXP<4>")
	)
	(segment
		(start 368.33683 -20.830032)
		(end 368.369342 -20.781264)
		(width 0.1143)
		(layer "In2.Cu")
		(net "P3E_CPU0_PE1_SS_C_TXP<4>")
	)
	(segment
		(start 351.209102 -75.856338)
		(end 351.559368 -75.14336)
		(width 0.1143)
		(layer "In2.Cu")
		(net "P3E_CPU0_PE1_SS_C_TXP<4>")
	)
	(segment
		(start 371.084348 -17.803368)
		(end 373.996712 -15.718536)
		(width 0.1143)
		(layer "In2.Cu")
		(net "P3E_CPU0_PE1_SS_C_TXP<4>")
	)
	(segment
		(start 351.559368 -75.14336)
		(end 351.940876 -75.013312)
		(width 0.1143)
		(layer "In2.Cu")
		(net "P3E_CPU0_PE1_SS_C_TXP<4>")
	)
	(segment
		(start 368.369342 -20.781264)
		(end 370.441474 -19.400012)
		(width 0.1143)
		(layer "In2.Cu")
		(net "P3E_CPU0_PE1_SS_C_TXP<4>")
	)
	(segment
		(start 353.307904 -71.593456)
		(end 353.308158 -71.593202)
		(width 0.1143)
		(layer "In2.Cu")
		(net "P3E_CPU0_PE1_SS_C_TXP<4>")
	)
	(segment
		(start 378.806456 -15.043658)
		(end 388.894066 -12.901422)
		(width 0.1143)
		(layer "In2.Cu")
		(net "P3E_CPU0_PE1_SS_C_TXP<4>")
	)
	(segment
		(start 422.347644 -10.137648)
		(end 422.233344 -10.023348)
		(width 0.1143)
		(layer "In2.Cu")
		(net "P3E_CPU0_PE1_SS_C_TXP<4>")
	)
	(segment
		(start 353.165918 -73.434702)
		(end 352.804222 -73.256902)
		(width 0.1143)
		(layer "In2.Cu")
		(net "P3E_CPU0_PE1_SS_C_TXP<4>")
	)
	(segment
		(start 356.982522 -64.332358)
		(end 358.815894 -62.99581)
		(width 0.1143)
		(layer "In2.Cu")
		(net "P3E_CPU0_PE1_SS_C_TXP<4>")
	)
	(segment
		(start 358.815894 -62.99581)
		(end 359.656634 -59.029092)
		(width 0.1143)
		(layer "In2.Cu")
		(net "P3E_CPU0_PE1_SS_C_TXP<4>")
	)
	(segment
		(start 352.45548 -75.139042)
		(end 352.556572 -74.933302)
		(width 0.1143)
		(layer "In2.Cu")
		(net "P3E_CPU0_PE1_SS_C_TXP<4>")
	)
	(segment
		(start 376.997722 -14.660118)
		(end 378.806456 -15.043658)
		(width 0.1143)
		(layer "In2.Cu")
		(net "P3E_CPU0_PE1_SS_C_TXP<4>")
	)
	(segment
		(start 391.489692 -13.453364)
		(end 395.28623 -12.64666)
		(width 0.1143)
		(layer "In2.Cu")
		(net "P3E_CPU0_PE1_SS_C_TXP<4>")
	)
	(segment
		(start 352.504502 -74.780648)
		(end 352.142552 -74.602848)
		(width 0.1143)
		(layer "In2.Cu")
		(net "P3E_CPU0_PE1_SS_C_TXP<4>")
	)
	(segment
		(start 355.797612 -67.650614)
		(end 356.982522 -64.332358)
		(width 0.1143)
		(layer "In2.Cu")
		(net "P3E_CPU0_PE1_SS_C_TXP<4>")
	)
	(segment
		(start 353.308158 -71.593202)
		(end 355.797612 -67.650614)
		(width 0.1143)
		(layer "In2.Cu")
		(net "P3E_CPU0_PE1_SS_C_TXP<4>")
	)
	(segment
		(start 351.209102 -76.45781)
		(end 351.209102 -75.856338)
		(width 0.1143)
		(layer "In2.Cu")
		(net "P3E_CPU0_PE1_SS_C_TXP<4>")
	)
	(segment
		(start 419.184328 -12.107672)
		(end 420.751 -10.541)
		(width 0.1143)
		(layer "In2.Cu")
		(net "P3E_CPU0_PE1_SS_C_TXP<4>")
	)
	(segment
		(start 388.894066 -12.901422)
		(end 391.489692 -13.453364)
		(width 0.1143)
		(layer "In2.Cu")
		(net "P3E_CPU0_PE1_SS_C_TXP<4>")
	)
	(segment
		(start 401.387564 -12.790678)
		(end 402.172424 -12.957556)
		(width 0.1143)
		(layer "In2.Cu")
		(net "P3E_CPU0_PE1_SS_C_TXP<4>")
	)
	(segment
		(start 398.676114 -13.366242)
		(end 401.387564 -12.790678)
		(width 0.1143)
		(layer "In2.Cu")
		(net "P3E_CPU0_PE1_SS_C_TXP<4>")
	)
	(segment
		(start 360.725974 -50.614072)
		(end 363.414818 -37.197538)
		(width 0.1143)
		(layer "In2.Cu")
		(net "P3E_CPU0_PE1_SS_C_TXP<4>")
	)
	(segment
		(start 370.441474 -19.400012)
		(end 370.67617 -19.047968)
		(width 0.1143)
		(layer "In2.Cu")
		(net "P3E_CPU0_PE1_SS_C_TXP<4>")
	)
	(arc
		(start 351.094802 -76.57211)
		(mid 351.170811 -76.543174)
		(end 351.20834 -76.471018)
		(width 0.1143)
		(layer "In2.Cu")
		(net "P3E_CPU0_PE1_SS_C_TXP<4>")
	)
	(segment
		(start 419.944042 -9.909048)
		(end 419.829742 -10.023348)
		(width 0.1143)
		(layer "F.Cu")
		(net "P3E_CPU0_PE1_SS_C_TXP<3>")
	)
	(segment
		(start 419.673786 -7.789672)
		(end 419.673786 -8.657336)
		(width 0.1143)
		(layer "F.Cu")
		(net "P3E_CPU0_PE1_SS_C_TXP<3>")
	)
	(segment
		(start 419.829742 -10.023348)
		(end 419.429692 -10.023348)
		(width 0.1143)
		(layer "F.Cu")
		(net "P3E_CPU0_PE1_SS_C_TXP<3>")
	)
	(segment
		(start 419.944042 -8.927592)
		(end 419.944042 -9.909048)
		(width 0.1143)
		(layer "F.Cu")
		(net "P3E_CPU0_PE1_SS_C_TXP<3>")
	)
	(segment
		(start 419.673786 -8.657336)
		(end 419.944042 -8.927592)
		(width 0.1143)
		(layer "F.Cu")
		(net "P3E_CPU0_PE1_SS_C_TXP<3>")
	)
	(via
		(at 347.80728 -76.509626)
		(size 0.508)
		(drill 0.254)
		(layers "F.Cu" "B.Cu")
		(net "P3E_CPU0_PE1_SS_C_TXP<3>")
	)
	(via
		(at 419.429692 -10.023348)
		(size 0.508)
		(drill 0.254)
		(layers "F.Cu" "B.Cu")
		(net "P3E_CPU0_PE1_SS_C_TXP<3>")
	)
	(segment
		(start 347.80728 -76.596748)
		(end 347.504512 -76.899516)
		(width 0.1143)
		(layer "B.Cu")
		(net "P3E_CPU0_PE1_SS_C_TXP<3>")
	)
	(segment
		(start 347.504512 -76.899516)
		(end 347.17736 -76.899516)
		(width 0.1143)
		(layer "B.Cu")
		(net "P3E_CPU0_PE1_SS_C_TXP<3>")
	)
	(segment
		(start 347.80728 -76.509626)
		(end 347.80728 -76.596748)
		(width 0.1143)
		(layer "B.Cu")
		(net "P3E_CPU0_PE1_SS_C_TXP<3>")
	)
	(segment
		(start 419.9382 -10.1346)
		(end 419.826948 -10.023348)
		(width 0.1143)
		(layer "In2.Cu")
		(net "P3E_CPU0_PE1_SS_C_TXP<3>")
	)
	(segment
		(start 360.167682 -46.986952)
		(end 361.074462 -45.639482)
		(width 0.1143)
		(layer "In2.Cu")
		(net "P3E_CPU0_PE1_SS_C_TXP<3>")
	)
	(segment
		(start 348.36481 -76.395326)
		(end 348.36481 -75.900534)
		(width 0.1143)
		(layer "In2.Cu")
		(net "P3E_CPU0_PE1_SS_C_TXP<3>")
	)
	(segment
		(start 348.36481 -75.900534)
		(end 351.324418 -74.094848)
		(width 0.1143)
		(layer "In2.Cu")
		(net "P3E_CPU0_PE1_SS_C_TXP<3>")
	)
	(segment
		(start 418.875718 -11.49477)
		(end 419.9382 -10.432542)
		(width 0.1143)
		(layer "In2.Cu")
		(net "P3E_CPU0_PE1_SS_C_TXP<3>")
	)
	(segment
		(start 355.222556 -67.333114)
		(end 356.439724 -63.926466)
		(width 0.1143)
		(layer "In2.Cu")
		(net "P3E_CPU0_PE1_SS_C_TXP<3>")
	)
	(segment
		(start 356.439724 -63.926466)
		(end 358.245156 -62.611)
		(width 0.1143)
		(layer "In2.Cu")
		(net "P3E_CPU0_PE1_SS_C_TXP<3>")
	)
	(segment
		(start 376.988324 -13.986764)
		(end 378.854208 -14.383004)
		(width 0.1143)
		(layer "In2.Cu")
		(net "P3E_CPU0_PE1_SS_C_TXP<3>")
	)
	(segment
		(start 358.896158 -53.098192)
		(end 360.097832 -47.090838)
		(width 0.1143)
		(layer "In2.Cu")
		(net "P3E_CPU0_PE1_SS_C_TXP<3>")
	)
	(segment
		(start 407.753058 -11.83132)
		(end 412.519876 -12.844018)
		(width 0.1143)
		(layer "In2.Cu")
		(net "P3E_CPU0_PE1_SS_C_TXP<3>")
	)
	(segment
		(start 403.363684 -12.035028)
		(end 405.0792 -12.399772)
		(width 0.1143)
		(layer "In2.Cu")
		(net "P3E_CPU0_PE1_SS_C_TXP<3>")
	)
	(segment
		(start 378.854208 -14.383004)
		(end 388.893812 -12.249658)
		(width 0.1143)
		(layer "In2.Cu")
		(net "P3E_CPU0_PE1_SS_C_TXP<3>")
	)
	(segment
		(start 371.201188 -16.028162)
		(end 376.988324 -13.986764)
		(width 0.1143)
		(layer "In2.Cu")
		(net "P3E_CPU0_PE1_SS_C_TXP<3>")
	)
	(segment
		(start 351.324418 -74.094848)
		(end 351.324418 -74.094594)
		(width 0.1143)
		(layer "In2.Cu")
		(net "P3E_CPU0_PE1_SS_C_TXP<3>")
	)
	(segment
		(start 352.591116 -71.516494)
		(end 355.222556 -67.333114)
		(width 0.1143)
		(layer "In2.Cu")
		(net "P3E_CPU0_PE1_SS_C_TXP<3>")
	)
	(segment
		(start 362.827316 -36.882578)
		(end 363.541818 -35.810698)
		(width 0.1143)
		(layer "In2.Cu")
		(net "P3E_CPU0_PE1_SS_C_TXP<3>")
	)
	(segment
		(start 395.31036 -11.989562)
		(end 398.676876 -12.704318)
		(width 0.1143)
		(layer "In2.Cu")
		(net "P3E_CPU0_PE1_SS_C_TXP<3>")
	)
	(segment
		(start 402.22043 -12.278106)
		(end 402.22043 -12.277852)
		(width 0.1143)
		(layer "In2.Cu")
		(net "P3E_CPU0_PE1_SS_C_TXP<3>")
	)
	(segment
		(start 388.893812 -12.249658)
		(end 391.490454 -12.8016)
		(width 0.1143)
		(layer "In2.Cu")
		(net "P3E_CPU0_PE1_SS_C_TXP<3>")
	)
	(segment
		(start 361.074462 -45.639482)
		(end 362.827316 -36.882578)
		(width 0.1143)
		(layer "In2.Cu")
		(net "P3E_CPU0_PE1_SS_C_TXP<3>")
	)
	(segment
		(start 419.9382 -10.432542)
		(end 419.9382 -10.1346)
		(width 0.1143)
		(layer "In2.Cu")
		(net "P3E_CPU0_PE1_SS_C_TXP<3>")
	)
	(segment
		(start 363.541818 -35.810698)
		(end 367.128806 -18.943574)
		(width 0.1143)
		(layer "In2.Cu")
		(net "P3E_CPU0_PE1_SS_C_TXP<3>")
	)
	(segment
		(start 360.097832 -47.090838)
		(end 360.167682 -46.986952)
		(width 0.1143)
		(layer "In2.Cu")
		(net "P3E_CPU0_PE1_SS_C_TXP<3>")
	)
	(segment
		(start 347.80728 -76.509626)
		(end 348.25051 -76.509626)
		(width 0.1143)
		(layer "In2.Cu")
		(net "P3E_CPU0_PE1_SS_C_TXP<3>")
	)
	(segment
		(start 419.826948 -10.023348)
		(end 419.429692 -10.023348)
		(width 0.1143)
		(layer "In2.Cu")
		(net "P3E_CPU0_PE1_SS_C_TXP<3>")
	)
	(segment
		(start 402.22043 -12.277852)
		(end 403.363684 -12.035028)
		(width 0.1143)
		(layer "In2.Cu")
		(net "P3E_CPU0_PE1_SS_C_TXP<3>")
	)
	(segment
		(start 391.490454 -12.8016)
		(end 395.31036 -11.989562)
		(width 0.1143)
		(layer "In2.Cu")
		(net "P3E_CPU0_PE1_SS_C_TXP<3>")
	)
	(segment
		(start 367.128806 -18.943574)
		(end 371.201188 -16.028162)
		(width 0.1143)
		(layer "In2.Cu")
		(net "P3E_CPU0_PE1_SS_C_TXP<3>")
	)
	(segment
		(start 359.030524 -58.891932)
		(end 359.7021 -57.029096)
		(width 0.1143)
		(layer "In2.Cu")
		(net "P3E_CPU0_PE1_SS_C_TXP<3>")
	)
	(segment
		(start 412.519876 -12.844018)
		(end 418.875718 -11.49477)
		(width 0.1143)
		(layer "In2.Cu")
		(net "P3E_CPU0_PE1_SS_C_TXP<3>")
	)
	(segment
		(start 359.7021 -57.029096)
		(end 358.896158 -53.098192)
		(width 0.1143)
		(layer "In2.Cu")
		(net "P3E_CPU0_PE1_SS_C_TXP<3>")
	)
	(segment
		(start 401.451572 -12.115038)
		(end 402.22043 -12.278106)
		(width 0.1143)
		(layer "In2.Cu")
		(net "P3E_CPU0_PE1_SS_C_TXP<3>")
	)
	(segment
		(start 351.324418 -74.094594)
		(end 352.591116 -71.516494)
		(width 0.1143)
		(layer "In2.Cu")
		(net "P3E_CPU0_PE1_SS_C_TXP<3>")
	)
	(segment
		(start 398.676876 -12.704318)
		(end 401.451572 -12.115038)
		(width 0.1143)
		(layer "In2.Cu")
		(net "P3E_CPU0_PE1_SS_C_TXP<3>")
	)
	(segment
		(start 405.0792 -12.399772)
		(end 407.753058 -11.83132)
		(width 0.1143)
		(layer "In2.Cu")
		(net "P3E_CPU0_PE1_SS_C_TXP<3>")
	)
	(segment
		(start 358.245156 -62.611)
		(end 359.030524 -58.891932)
		(width 0.1143)
		(layer "In2.Cu")
		(net "P3E_CPU0_PE1_SS_C_TXP<3>")
	)
	(arc
		(start 348.25051 -76.509626)
		(mid 348.331332 -76.476148)
		(end 348.36481 -76.395326)
		(width 0.1143)
		(layer "In2.Cu")
		(net "P3E_CPU0_PE1_SS_C_TXP<3>")
	)
	(segment
		(start 417.552886 -8.936736)
		(end 417.552886 -9.827514)
		(width 0.1143)
		(layer "F.Cu")
		(net "P3E_CPU0_PE1_SS_C_TXP<2>")
	)
	(segment
		(start 417.552886 -9.827514)
		(end 417.357052 -10.023348)
		(width 0.1143)
		(layer "F.Cu")
		(net "P3E_CPU0_PE1_SS_C_TXP<2>")
	)
	(segment
		(start 417.273486 -8.657336)
		(end 417.552886 -8.936736)
		(width 0.1143)
		(layer "F.Cu")
		(net "P3E_CPU0_PE1_SS_C_TXP<2>")
	)
	(segment
		(start 417.357052 -10.023348)
		(end 417.029392 -10.023348)
		(width 0.1143)
		(layer "F.Cu")
		(net "P3E_CPU0_PE1_SS_C_TXP<2>")
	)
	(segment
		(start 417.273486 -7.789672)
		(end 417.273486 -8.657336)
		(width 0.1143)
		(layer "F.Cu")
		(net "P3E_CPU0_PE1_SS_C_TXP<2>")
	)
	(via
		(at 417.029392 -10.023348)
		(size 0.508)
		(drill 0.254)
		(layers "F.Cu" "B.Cu")
		(net "P3E_CPU0_PE1_SS_C_TXP<2>")
	)
	(via
		(at 345.062556 -76.40701)
		(size 0.508)
		(drill 0.254)
		(layers "F.Cu" "B.Cu")
		(net "P3E_CPU0_PE1_SS_C_TXP<2>")
	)
	(segment
		(start 345.062556 -76.551536)
		(end 344.808556 -76.805536)
		(width 0.1143)
		(layer "B.Cu")
		(net "P3E_CPU0_PE1_SS_C_TXP<2>")
	)
	(segment
		(start 345.062556 -76.40701)
		(end 345.062556 -76.551536)
		(width 0.1143)
		(layer "B.Cu")
		(net "P3E_CPU0_PE1_SS_C_TXP<2>")
	)
	(segment
		(start 344.808556 -76.805536)
		(end 344.435176 -76.805536)
		(width 0.1143)
		(layer "B.Cu")
		(net "P3E_CPU0_PE1_SS_C_TXP<2>")
	)
	(segment
		(start 378.872242 -13.719048)
		(end 388.873238 -11.593576)
		(width 0.1143)
		(layer "In2.Cu")
		(net "P3E_CPU0_PE1_SS_C_TXP<2>")
	)
	(segment
		(start 360.167682 -45.825918)
		(end 360.468164 -45.380402)
		(width 0.1143)
		(layer "In2.Cu")
		(net "P3E_CPU0_PE1_SS_C_TXP<2>")
	)
	(segment
		(start 417.281868 -11.166348)
		(end 417.529772 -10.918444)
		(width 0.1143)
		(layer "In2.Cu")
		(net "P3E_CPU0_PE1_SS_C_TXP<2>")
	)
	(segment
		(start 402.287232 -11.604498)
		(end 403.448012 -11.357864)
		(width 0.1143)
		(layer "In2.Cu")
		(net "P3E_CPU0_PE1_SS_C_TXP<2>")
	)
	(segment
		(start 345.622626 -75.827636)
		(end 348.15399 -74.248264)
		(width 0.1143)
		(layer "In2.Cu")
		(net "P3E_CPU0_PE1_SS_C_TXP<2>")
	)
	(segment
		(start 362.94822 -35.53587)
		(end 366.553242 -18.571464)
		(width 0.1143)
		(layer "In2.Cu")
		(net "P3E_CPU0_PE1_SS_C_TXP<2>")
	)
	(segment
		(start 356.940104 -61.74613)
		(end 358.166416 -59.8932)
		(width 0.1143)
		(layer "In2.Cu")
		(net "P3E_CPU0_PE1_SS_C_TXP<2>")
	)
	(segment
		(start 391.490454 -12.149836)
		(end 395.335252 -11.332718)
		(width 0.1143)
		(layer "In2.Cu")
		(net "P3E_CPU0_PE1_SS_C_TXP<2>")
	)
	(segment
		(start 395.335252 -11.332718)
		(end 398.676622 -12.04214)
		(width 0.1143)
		(layer "In2.Cu")
		(net "P3E_CPU0_PE1_SS_C_TXP<2>")
	)
	(segment
		(start 358.166416 -59.8932)
		(end 358.165908 -59.8932)
		(width 0.1143)
		(layer "In2.Cu")
		(net "P3E_CPU0_PE1_SS_C_TXP<2>")
	)
	(segment
		(start 348.153736 -74.248264)
		(end 350.139 -71.4248)
		(width 0.1143)
		(layer "In2.Cu")
		(net "P3E_CPU0_PE1_SS_C_TXP<2>")
	)
	(segment
		(start 345.622626 -76.1746)
		(end 345.622626 -75.827636)
		(width 0.1143)
		(layer "In2.Cu")
		(net "P3E_CPU0_PE1_SS_C_TXP<2>")
	)
	(segment
		(start 352.03003 -70.301612)
		(end 353.284028 -67.847972)
		(width 0.1143)
		(layer "In2.Cu")
		(net "P3E_CPU0_PE1_SS_C_TXP<2>")
	)
	(segment
		(start 358.180132 -52.818284)
		(end 359.329736 -47.067978)
		(width 0.1143)
		(layer "In2.Cu")
		(net "P3E_CPU0_PE1_SS_C_TXP<2>")
	)
	(segment
		(start 345.062556 -76.40701)
		(end 345.390216 -76.40701)
		(width 0.1143)
		(layer "In2.Cu")
		(net "P3E_CPU0_PE1_SS_C_TXP<2>")
	)
	(segment
		(start 359.028746 -56.961278)
		(end 358.180132 -52.818284)
		(width 0.1143)
		(layer "In2.Cu")
		(net "P3E_CPU0_PE1_SS_C_TXP<2>")
	)
	(segment
		(start 370.904008 -15.457424)
		(end 376.9741 -13.316204)
		(width 0.1143)
		(layer "In2.Cu")
		(net "P3E_CPU0_PE1_SS_C_TXP<2>")
	)
	(segment
		(start 388.873238 -11.593576)
		(end 391.490454 -12.149836)
		(width 0.1143)
		(layer "In2.Cu")
		(net "P3E_CPU0_PE1_SS_C_TXP<2>")
	)
	(segment
		(start 360.468164 -45.380402)
		(end 362.21543 -36.635944)
		(width 0.1143)
		(layer "In2.Cu")
		(net "P3E_CPU0_PE1_SS_C_TXP<2>")
	)
	(segment
		(start 412.531052 -12.174982)
		(end 417.281868 -11.166348)
		(width 0.1143)
		(layer "In2.Cu")
		(net "P3E_CPU0_PE1_SS_C_TXP<2>")
	)
	(segment
		(start 359.329736 -47.067978)
		(end 360.167682 -45.825918)
		(width 0.1143)
		(layer "In2.Cu")
		(net "P3E_CPU0_PE1_SS_C_TXP<2>")
	)
	(segment
		(start 362.21543 -36.635944)
		(end 362.94822 -35.53587)
		(width 0.1143)
		(layer "In2.Cu")
		(net "P3E_CPU0_PE1_SS_C_TXP<2>")
	)
	(segment
		(start 348.15399 -74.248264)
		(end 348.153736 -74.248264)
		(width 0.1143)
		(layer "In2.Cu")
		(net "P3E_CPU0_PE1_SS_C_TXP<2>")
	)
	(segment
		(start 350.193356 -71.39305)
		(end 352.03003 -70.301612)
		(width 0.1143)
		(layer "In2.Cu")
		(net "P3E_CPU0_PE1_SS_C_TXP<2>")
	)
	(segment
		(start 353.284028 -67.847972)
		(end 355.16312 -63.040768)
		(width 0.1143)
		(layer "In2.Cu")
		(net "P3E_CPU0_PE1_SS_C_TXP<2>")
	)
	(segment
		(start 350.192848 -71.392796)
		(end 350.193356 -71.39305)
		(width 0.1143)
		(layer "In2.Cu")
		(net "P3E_CPU0_PE1_SS_C_TXP<2>")
	)
	(segment
		(start 398.676622 -12.04214)
		(end 401.511516 -11.44016)
		(width 0.1143)
		(layer "In2.Cu")
		(net "P3E_CPU0_PE1_SS_C_TXP<2>")
	)
	(segment
		(start 403.448012 -11.357864)
		(end 405.15667 -11.721084)
		(width 0.1143)
		(layer "In2.Cu")
		(net "P3E_CPU0_PE1_SS_C_TXP<2>")
	)
	(segment
		(start 417.529772 -10.918444)
		(end 417.529772 -10.137648)
		(width 0.1143)
		(layer "In2.Cu")
		(net "P3E_CPU0_PE1_SS_C_TXP<2>")
	)
	(segment
		(start 401.511516 -11.44016)
		(end 402.287232 -11.604752)
		(width 0.1143)
		(layer "In2.Cu")
		(net "P3E_CPU0_PE1_SS_C_TXP<2>")
	)
	(segment
		(start 376.9741 -13.316204)
		(end 378.872242 -13.719048)
		(width 0.1143)
		(layer "In2.Cu")
		(net "P3E_CPU0_PE1_SS_C_TXP<2>")
	)
	(segment
		(start 402.287232 -11.604752)
		(end 402.287232 -11.604498)
		(width 0.1143)
		(layer "In2.Cu")
		(net "P3E_CPU0_PE1_SS_C_TXP<2>")
	)
	(segment
		(start 358.194102 -59.746896)
		(end 358.435148 -58.60796)
		(width 0.1143)
		(layer "In2.Cu")
		(net "P3E_CPU0_PE1_SS_C_TXP<2>")
	)
	(segment
		(start 417.415472 -10.023348)
		(end 417.029392 -10.023348)
		(width 0.1143)
		(layer "In2.Cu")
		(net "P3E_CPU0_PE1_SS_C_TXP<2>")
	)
	(segment
		(start 405.15667 -11.721084)
		(end 407.77414 -11.16457)
		(width 0.1143)
		(layer "In2.Cu")
		(net "P3E_CPU0_PE1_SS_C_TXP<2>")
	)
	(segment
		(start 355.16312 -63.040768)
		(end 356.940104 -61.74613)
		(width 0.1143)
		(layer "In2.Cu")
		(net "P3E_CPU0_PE1_SS_C_TXP<2>")
	)
	(segment
		(start 350.139 -71.4248)
		(end 350.192848 -71.392796)
		(width 0.1143)
		(layer "In2.Cu")
		(net "P3E_CPU0_PE1_SS_C_TXP<2>")
	)
	(segment
		(start 358.165908 -59.8932)
		(end 358.194102 -59.746896)
		(width 0.1143)
		(layer "In2.Cu")
		(net "P3E_CPU0_PE1_SS_C_TXP<2>")
	)
	(segment
		(start 417.529772 -10.137648)
		(end 417.415472 -10.023348)
		(width 0.1143)
		(layer "In2.Cu")
		(net "P3E_CPU0_PE1_SS_C_TXP<2>")
	)
	(segment
		(start 407.77414 -11.16457)
		(end 412.531052 -12.174982)
		(width 0.1143)
		(layer "In2.Cu")
		(net "P3E_CPU0_PE1_SS_C_TXP<2>")
	)
	(segment
		(start 366.553242 -18.571464)
		(end 370.904008 -15.457424)
		(width 0.1143)
		(layer "In2.Cu")
		(net "P3E_CPU0_PE1_SS_C_TXP<2>")
	)
	(segment
		(start 358.435148 -58.60796)
		(end 359.028746 -56.961278)
		(width 0.1143)
		(layer "In2.Cu")
		(net "P3E_CPU0_PE1_SS_C_TXP<2>")
	)
	(arc
		(start 345.390216 -76.40701)
		(mid 345.554555 -76.338939)
		(end 345.622626 -76.1746)
		(width 0.1143)
		(layer "In2.Cu")
		(net "P3E_CPU0_PE1_SS_C_TXP<2>")
	)
	(segment
		(start 414.629092 -10.124948)
		(end 415.029142 -10.124948)
		(width 0.1143)
		(layer "F.Cu")
		(net "P3E_CPU0_PE1_SS_C_TXP<1>")
	)
	(segment
		(start 415.1249 -8.90905)
		(end 414.873186 -8.657336)
		(width 0.1143)
		(layer "F.Cu")
		(net "P3E_CPU0_PE1_SS_C_TXP<1>")
	)
	(segment
		(start 415.1249 -10.02919)
		(end 415.1249 -8.90905)
		(width 0.1143)
		(layer "F.Cu")
		(net "P3E_CPU0_PE1_SS_C_TXP<1>")
	)
	(segment
		(start 415.029142 -10.124948)
		(end 415.1249 -10.02919)
		(width 0.1143)
		(layer "F.Cu")
		(net "P3E_CPU0_PE1_SS_C_TXP<1>")
	)
	(segment
		(start 414.873186 -8.657336)
		(end 414.873186 -7.789672)
		(width 0.1143)
		(layer "F.Cu")
		(net "P3E_CPU0_PE1_SS_C_TXP<1>")
	)
	(via
		(at 342.364568 -76.134214)
		(size 0.508)
		(drill 0.254)
		(layers "F.Cu" "B.Cu")
		(net "P3E_CPU0_PE1_SS_C_TXP<1>")
	)
	(via
		(at 414.629092 -10.124948)
		(size 0.508)
		(drill 0.254)
		(layers "F.Cu" "B.Cu")
		(net "P3E_CPU0_PE1_SS_C_TXP<1>")
	)
	(segment
		(start 341.996014 -76.805536)
		(end 341.666068 -76.805536)
		(width 0.1143)
		(layer "B.Cu")
		(net "P3E_CPU0_PE1_SS_C_TXP<1>")
	)
	(segment
		(start 342.364568 -76.134214)
		(end 342.364568 -76.436982)
		(width 0.1143)
		(layer "B.Cu")
		(net "P3E_CPU0_PE1_SS_C_TXP<1>")
	)
	(segment
		(start 342.364568 -76.436982)
		(end 341.996014 -76.805536)
		(width 0.1143)
		(layer "B.Cu")
		(net "P3E_CPU0_PE1_SS_C_TXP<1>")
	)
	(segment
		(start 343.545668 -74.936858)
		(end 343.625424 -74.894694)
		(width 0.1143)
		(layer "In2.Cu")
		(net "P3E_CPU0_PE1_SS_C_TXP<1>")
	)
	(segment
		(start 398.676876 -11.379708)
		(end 398.676876 -11.379962)
		(width 0.1143)
		(layer "In2.Cu")
		(net "P3E_CPU0_PE1_SS_C_TXP<1>")
	)
	(segment
		(start 395.359128 -10.67562)
		(end 395.359128 -10.675874)
		(width 0.1143)
		(layer "In2.Cu")
		(net "P3E_CPU0_PE1_SS_C_TXP<1>")
	)
	(segment
		(start 342.995758 -75.562206)
		(end 343.545668 -74.936858)
		(width 0.1143)
		(layer "In2.Cu")
		(net "P3E_CPU0_PE1_SS_C_TXP<1>")
	)
	(segment
		(start 356.364794 -61.273182)
		(end 357.338376 -59.730132)
		(width 0.1143)
		(layer "In2.Cu")
		(net "P3E_CPU0_PE1_SS_C_TXP<1>")
	)
	(segment
		(start 352.509328 -67.940936)
		(end 354.618036 -62.548008)
		(width 0.1143)
		(layer "In2.Cu")
		(net "P3E_CPU0_PE1_SS_C_TXP<1>")
	)
	(segment
		(start 403.375622 -10.680192)
		(end 405.15667 -11.058906)
		(width 0.1143)
		(layer "In2.Cu")
		(net "P3E_CPU0_PE1_SS_C_TXP<1>")
	)
	(segment
		(start 415.099246 -10.763504)
		(end 415.099246 -10.239248)
		(width 0.1143)
		(layer "In2.Cu")
		(net "P3E_CPU0_PE1_SS_C_TXP<1>")
	)
	(segment
		(start 355.800406 -51.17719)
		(end 359.881678 -45.052742)
		(width 0.1143)
		(layer "In2.Cu")
		(net "P3E_CPU0_PE1_SS_C_TXP<1>")
	)
	(segment
		(start 342.364568 -76.134214)
		(end 342.36533 -76.133452)
		(width 0.1143)
		(layer "In2.Cu")
		(net "P3E_CPU0_PE1_SS_C_TXP<1>")
	)
	(segment
		(start 357.982266 -55.030116)
		(end 355.683566 -53.50002)
		(width 0.1143)
		(layer "In2.Cu")
		(net "P3E_CPU0_PE1_SS_C_TXP<1>")
	)
	(segment
		(start 365.929926 -18.233898)
		(end 370.606574 -14.886178)
		(width 0.1143)
		(layer "In2.Cu")
		(net "P3E_CPU0_PE1_SS_C_TXP<1>")
	)
	(segment
		(start 415.099246 -10.239248)
		(end 414.984946 -10.124948)
		(width 0.1143)
		(layer "In2.Cu")
		(net "P3E_CPU0_PE1_SS_C_TXP<1>")
	)
	(segment
		(start 351.676716 -69.570092)
		(end 352.509328 -67.940936)
		(width 0.1143)
		(layer "In2.Cu")
		(net "P3E_CPU0_PE1_SS_C_TXP<1>")
	)
	(segment
		(start 355.683566 -53.50002)
		(end 355.510084 -52.631086)
		(width 0.1143)
		(layer "In2.Cu")
		(net "P3E_CPU0_PE1_SS_C_TXP<1>")
	)
	(segment
		(start 388.878826 -10.943082)
		(end 391.489692 -11.498072)
		(width 0.1143)
		(layer "In2.Cu")
		(net "P3E_CPU0_PE1_SS_C_TXP<1>")
	)
	(segment
		(start 376.933714 -12.654788)
		(end 378.879862 -13.067792)
		(width 0.1143)
		(layer "In2.Cu")
		(net "P3E_CPU0_PE1_SS_C_TXP<1>")
	)
	(segment
		(start 358.35717 -56.905144)
		(end 357.982266 -55.030116)
		(width 0.1143)
		(layer "In2.Cu")
		(net "P3E_CPU0_PE1_SS_C_TXP<1>")
	)
	(segment
		(start 391.489692 -11.498072)
		(end 395.359128 -10.67562)
		(width 0.1143)
		(layer "In2.Cu")
		(net "P3E_CPU0_PE1_SS_C_TXP<1>")
	)
	(segment
		(start 343.625424 -74.894694)
		(end 348.253812 -72.452484)
		(width 0.1143)
		(layer "In2.Cu")
		(net "P3E_CPU0_PE1_SS_C_TXP<1>")
	)
	(segment
		(start 414.825434 -11.037062)
		(end 415.099246 -10.763504)
		(width 0.1143)
		(layer "In2.Cu")
		(net "P3E_CPU0_PE1_SS_C_TXP<1>")
	)
	(segment
		(start 348.253812 -72.452484)
		(end 349.18904 -70.80631)
		(width 0.1143)
		(layer "In2.Cu")
		(net "P3E_CPU0_PE1_SS_C_TXP<1>")
	)
	(segment
		(start 359.881678 -45.052742)
		(end 361.6198 -36.355528)
		(width 0.1143)
		(layer "In2.Cu")
		(net "P3E_CPU0_PE1_SS_C_TXP<1>")
	)
	(segment
		(start 402.199856 -10.930128)
		(end 403.375622 -10.680192)
		(width 0.1143)
		(layer "In2.Cu")
		(net "P3E_CPU0_PE1_SS_C_TXP<1>")
	)
	(segment
		(start 407.810716 -10.495026)
		(end 412.592012 -11.511534)
		(width 0.1143)
		(layer "In2.Cu")
		(net "P3E_CPU0_PE1_SS_C_TXP<1>")
	)
	(segment
		(start 370.606574 -14.886178)
		(end 376.933714 -12.654788)
		(width 0.1143)
		(layer "In2.Cu")
		(net "P3E_CPU0_PE1_SS_C_TXP<1>")
	)
	(segment
		(start 378.879862 -13.067792)
		(end 388.878826 -10.943082)
		(width 0.1143)
		(layer "In2.Cu")
		(net "P3E_CPU0_PE1_SS_C_TXP<1>")
	)
	(segment
		(start 395.359382 -10.67562)
		(end 398.676622 -11.379962)
		(width 0.1143)
		(layer "In2.Cu")
		(net "P3E_CPU0_PE1_SS_C_TXP<1>")
	)
	(segment
		(start 405.15667 -11.058906)
		(end 407.810716 -10.495026)
		(width 0.1143)
		(layer "In2.Cu")
		(net "P3E_CPU0_PE1_SS_C_TXP<1>")
	)
	(segment
		(start 342.995758 -75.86726)
		(end 342.995758 -75.562206)
		(width 0.1143)
		(layer "In2.Cu")
		(net "P3E_CPU0_PE1_SS_C_TXP<1>")
	)
	(segment
		(start 342.36533 -76.133452)
		(end 342.729566 -76.133452)
		(width 0.1143)
		(layer "In2.Cu")
		(net "P3E_CPU0_PE1_SS_C_TXP<1>")
	)
	(segment
		(start 362.292392 -35.347402)
		(end 365.929926 -18.233898)
		(width 0.1143)
		(layer "In2.Cu")
		(net "P3E_CPU0_PE1_SS_C_TXP<1>")
	)
	(segment
		(start 414.984946 -10.124948)
		(end 414.629092 -10.124948)
		(width 0.1143)
		(layer "In2.Cu")
		(net "P3E_CPU0_PE1_SS_C_TXP<1>")
	)
	(segment
		(start 412.592012 -11.511534)
		(end 414.825434 -11.037062)
		(width 0.1143)
		(layer "In2.Cu")
		(net "P3E_CPU0_PE1_SS_C_TXP<1>")
	)
	(segment
		(start 357.338376 -59.730132)
		(end 358.35717 -56.905144)
		(width 0.1143)
		(layer "In2.Cu")
		(net "P3E_CPU0_PE1_SS_C_TXP<1>")
	)
	(segment
		(start 395.359128 -10.675874)
		(end 395.359382 -10.67562)
		(width 0.1143)
		(layer "In2.Cu")
		(net "P3E_CPU0_PE1_SS_C_TXP<1>")
	)
	(segment
		(start 349.18904 -70.80631)
		(end 351.676716 -69.570092)
		(width 0.1143)
		(layer "In2.Cu")
		(net "P3E_CPU0_PE1_SS_C_TXP<1>")
	)
	(segment
		(start 401.497292 -10.78103)
		(end 402.199856 -10.930128)
		(width 0.1143)
		(layer "In2.Cu")
		(net "P3E_CPU0_PE1_SS_C_TXP<1>")
	)
	(segment
		(start 398.676622 -11.379962)
		(end 398.676876 -11.379708)
		(width 0.1143)
		(layer "In2.Cu")
		(net "P3E_CPU0_PE1_SS_C_TXP<1>")
	)
	(segment
		(start 354.618036 -62.548008)
		(end 356.364794 -61.273182)
		(width 0.1143)
		(layer "In2.Cu")
		(net "P3E_CPU0_PE1_SS_C_TXP<1>")
	)
	(segment
		(start 398.676876 -11.379962)
		(end 401.497292 -10.78103)
		(width 0.1143)
		(layer "In2.Cu")
		(net "P3E_CPU0_PE1_SS_C_TXP<1>")
	)
	(segment
		(start 361.6198 -36.355528)
		(end 362.292392 -35.347402)
		(width 0.1143)
		(layer "In2.Cu")
		(net "P3E_CPU0_PE1_SS_C_TXP<1>")
	)
	(segment
		(start 355.510084 -52.631086)
		(end 355.800406 -51.17719)
		(width 0.1143)
		(layer "In2.Cu")
		(net "P3E_CPU0_PE1_SS_C_TXP<1>")
	)
	(arc
		(start 342.729566 -76.133452)
		(mid 342.917792 -76.055486)
		(end 342.995758 -75.86726)
		(width 0.1143)
		(layer "In2.Cu")
		(net "P3E_CPU0_PE1_SS_C_TXP<1>")
	)
	(segment
		(start 412.472886 -8.511032)
		(end 412.472886 -7.789672)
		(width 0.1143)
		(layer "F.Cu")
		(net "P3E_CPU0_PE1_SS_C_TXP<0>")
	)
	(segment
		(start 412.14929 -10.1346)
		(end 412.571946 -10.1346)
		(width 0.1143)
		(layer "F.Cu")
		(net "P3E_CPU0_PE1_SS_C_TXP<0>")
	)
	(segment
		(start 412.66618 -8.704326)
		(end 412.472886 -8.511032)
		(width 0.1143)
		(layer "F.Cu")
		(net "P3E_CPU0_PE1_SS_C_TXP<0>")
	)
	(segment
		(start 412.571946 -10.1346)
		(end 412.66618 -10.040366)
		(width 0.1143)
		(layer "F.Cu")
		(net "P3E_CPU0_PE1_SS_C_TXP<0>")
	)
	(segment
		(start 412.66618 -10.040366)
		(end 412.66618 -8.704326)
		(width 0.1143)
		(layer "F.Cu")
		(net "P3E_CPU0_PE1_SS_C_TXP<0>")
	)
	(via
		(at 339.40496 -76.515722)
		(size 0.508)
		(drill 0.254)
		(layers "F.Cu" "B.Cu")
		(net "P3E_CPU0_PE1_SS_C_TXP<0>")
	)
	(via
		(at 412.14929 -10.1346)
		(size 0.508)
		(drill 0.254)
		(layers "F.Cu" "B.Cu")
		(net "P3E_CPU0_PE1_SS_C_TXP<0>")
	)
	(segment
		(start 338.76996 -76.805536)
		(end 339.115146 -76.805536)
		(width 0.1143)
		(layer "B.Cu")
		(net "P3E_CPU0_PE1_SS_C_TXP<0>")
	)
	(segment
		(start 339.115146 -76.805536)
		(end 339.40496 -76.515722)
		(width 0.1143)
		(layer "B.Cu")
		(net "P3E_CPU0_PE1_SS_C_TXP<0>")
	)
	(segment
		(start 412.4706 -10.7696)
		(end 412.64586 -10.59434)
		(width 0.1143)
		(layer "In2.Cu")
		(net "P3E_CPU0_PE1_SS_C_TXP<0>")
	)
	(segment
		(start 355.108002 -53.997098)
		(end 354.829618 -52.6034)
		(width 0.1143)
		(layer "In2.Cu")
		(net "P3E_CPU0_PE1_SS_C_TXP<0>")
	)
	(segment
		(start 355.84257 -60.77077)
		(end 356.850188 -59.207146)
		(width 0.1143)
		(layer "In2.Cu")
		(net "P3E_CPU0_PE1_SS_C_TXP<0>")
	)
	(segment
		(start 395.38402 -10.018776)
		(end 398.676876 -10.717784)
		(width 0.1143)
		(layer "In2.Cu")
		(net "P3E_CPU0_PE1_SS_C_TXP<0>")
	)
	(segment
		(start 398.676876 -10.717784)
		(end 401.507198 -10.11682)
		(width 0.1143)
		(layer "In2.Cu")
		(net "P3E_CPU0_PE1_SS_C_TXP<0>")
	)
	(segment
		(start 351.341944 -68.801488)
		(end 351.79254 -67.920108)
		(width 0.1143)
		(layer "In2.Cu")
		(net "P3E_CPU0_PE1_SS_C_TXP<0>")
	)
	(segment
		(start 405.15667 -10.396728)
		(end 407.78557 -9.837928)
		(width 0.1143)
		(layer "In2.Cu")
		(net "P3E_CPU0_PE1_SS_C_TXP<0>")
	)
	(segment
		(start 354.085906 -62.052962)
		(end 355.84257 -60.77077)
		(width 0.1143)
		(layer "In2.Cu")
		(net "P3E_CPU0_PE1_SS_C_TXP<0>")
	)
	(segment
		(start 340.299802 -75.087734)
		(end 345.587828 -72.89292)
		(width 0.1143)
		(layer "In2.Cu")
		(net "P3E_CPU0_PE1_SS_C_TXP<0>")
	)
	(segment
		(start 407.78557 -9.837928)
		(end 412.171134 -10.7696)
		(width 0.1143)
		(layer "In2.Cu")
		(net "P3E_CPU0_PE1_SS_C_TXP<0>")
	)
	(segment
		(start 339.40496 -76.515722)
		(end 339.878924 -76.515722)
		(width 0.1143)
		(layer "In2.Cu")
		(net "P3E_CPU0_PE1_SS_C_TXP<0>")
	)
	(segment
		(start 412.647384 -10.252456)
		(end 412.534354 -10.137394)
		(width 0.1143)
		(layer "In2.Cu")
		(net "P3E_CPU0_PE1_SS_C_TXP<0>")
	)
	(segment
		(start 401.507198 -10.11682)
		(end 402.1963 -10.263124)
		(width 0.1143)
		(layer "In2.Cu")
		(net "P3E_CPU0_PE1_SS_C_TXP<0>")
	)
	(segment
		(start 345.747086 -72.20712)
		(end 349.800418 -69.345302)
		(width 0.1143)
		(layer "In2.Cu")
		(net "P3E_CPU0_PE1_SS_C_TXP<0>")
	)
	(segment
		(start 378.863098 -12.400026)
		(end 388.832598 -10.281412)
		(width 0.1143)
		(layer "In2.Cu")
		(net "P3E_CPU0_PE1_SS_C_TXP<0>")
	)
	(segment
		(start 340.00694 -76.387706)
		(end 340.00694 -75.732132)
		(width 0.1143)
		(layer "In2.Cu")
		(net "P3E_CPU0_PE1_SS_C_TXP<0>")
	)
	(segment
		(start 412.64586 -10.59434)
		(end 412.647384 -10.252456)
		(width 0.1143)
		(layer "In2.Cu")
		(net "P3E_CPU0_PE1_SS_C_TXP<0>")
	)
	(segment
		(start 412.534354 -10.137394)
		(end 412.14929 -10.1346)
		(width 0.1143)
		(layer "In2.Cu")
		(net "P3E_CPU0_PE1_SS_C_TXP<0>")
	)
	(segment
		(start 388.832598 -10.281412)
		(end 391.489692 -10.846308)
		(width 0.1143)
		(layer "In2.Cu")
		(net "P3E_CPU0_PE1_SS_C_TXP<0>")
	)
	(segment
		(start 339.878924 -76.515722)
		(end 339.89264 -76.502006)
		(width 0.1143)
		(layer "In2.Cu")
		(net "P3E_CPU0_PE1_SS_C_TXP<0>")
	)
	(segment
		(start 355.16566 -50.922936)
		(end 359.28554 -44.775374)
		(width 0.1143)
		(layer "In2.Cu")
		(net "P3E_CPU0_PE1_SS_C_TXP<0>")
	)
	(segment
		(start 359.28554 -44.775374)
		(end 361.019344 -36.099242)
		(width 0.1143)
		(layer "In2.Cu")
		(net "P3E_CPU0_PE1_SS_C_TXP<0>")
	)
	(segment
		(start 376.912378 -11.985752)
		(end 378.863098 -12.400026)
		(width 0.1143)
		(layer "In2.Cu")
		(net "P3E_CPU0_PE1_SS_C_TXP<0>")
	)
	(segment
		(start 412.171134 -10.7696)
		(end 412.4706 -10.7696)
		(width 0.1143)
		(layer "In2.Cu")
		(net "P3E_CPU0_PE1_SS_C_TXP<0>")
	)
	(segment
		(start 356.850188 -59.207146)
		(end 357.68915 -56.88076)
		(width 0.1143)
		(layer "In2.Cu")
		(net "P3E_CPU0_PE1_SS_C_TXP<0>")
	)
	(segment
		(start 370.308886 -14.314932)
		(end 376.912378 -11.985752)
		(width 0.1143)
		(layer "In2.Cu")
		(net "P3E_CPU0_PE1_SS_C_TXP<0>")
	)
	(segment
		(start 351.79254 -67.920108)
		(end 354.085906 -62.052962)
		(width 0.1143)
		(layer "In2.Cu")
		(net "P3E_CPU0_PE1_SS_C_TXP<0>")
	)
	(segment
		(start 361.696 -35.084766)
		(end 365.357664 -17.859502)
		(width 0.1143)
		(layer "In2.Cu")
		(net "P3E_CPU0_PE1_SS_C_TXP<0>")
	)
	(segment
		(start 349.800418 -69.345302)
		(end 351.341944 -68.801488)
		(width 0.1143)
		(layer "In2.Cu")
		(net "P3E_CPU0_PE1_SS_C_TXP<0>")
	)
	(segment
		(start 402.1963 -10.263124)
		(end 403.362414 -10.01522)
		(width 0.1143)
		(layer "In2.Cu")
		(net "P3E_CPU0_PE1_SS_C_TXP<0>")
	)
	(segment
		(start 361.019344 -36.099242)
		(end 361.696 -35.084766)
		(width 0.1143)
		(layer "In2.Cu")
		(net "P3E_CPU0_PE1_SS_C_TXP<0>")
	)
	(segment
		(start 345.587828 -72.89292)
		(end 345.747086 -72.20712)
		(width 0.1143)
		(layer "In2.Cu")
		(net "P3E_CPU0_PE1_SS_C_TXP<0>")
	)
	(segment
		(start 391.489692 -10.846308)
		(end 395.38402 -10.018776)
		(width 0.1143)
		(layer "In2.Cu")
		(net "P3E_CPU0_PE1_SS_C_TXP<0>")
	)
	(segment
		(start 357.68915 -56.88076)
		(end 357.420926 -55.536846)
		(width 0.1143)
		(layer "In2.Cu")
		(net "P3E_CPU0_PE1_SS_C_TXP<0>")
	)
	(segment
		(start 403.362414 -10.01522)
		(end 405.15667 -10.396728)
		(width 0.1143)
		(layer "In2.Cu")
		(net "P3E_CPU0_PE1_SS_C_TXP<0>")
	)
	(segment
		(start 340.00694 -75.732132)
		(end 340.299802 -75.087734)
		(width 0.1143)
		(layer "In2.Cu")
		(net "P3E_CPU0_PE1_SS_C_TXP<0>")
	)
	(segment
		(start 357.420926 -55.536846)
		(end 355.108002 -53.997098)
		(width 0.1143)
		(layer "In2.Cu")
		(net "P3E_CPU0_PE1_SS_C_TXP<0>")
	)
	(segment
		(start 354.829618 -52.6034)
		(end 355.16566 -50.922936)
		(width 0.1143)
		(layer "In2.Cu")
		(net "P3E_CPU0_PE1_SS_C_TXP<0>")
	)
	(segment
		(start 365.357664 -17.859502)
		(end 370.308886 -14.314932)
		(width 0.1143)
		(layer "In2.Cu")
		(net "P3E_CPU0_PE1_SS_C_TXP<0>")
	)
	(arc
		(start 339.89264 -76.502006)
		(mid 339.973462 -76.468528)
		(end 340.00694 -76.387706)
		(width 0.1143)
		(layer "In2.Cu")
		(net "P3E_CPU0_PE1_SS_C_TXP<0>")
	)
	(segment
		(start 429.554386 -8.936736)
		(end 429.274986 -8.657336)
		(width 0.1143)
		(layer "F.Cu")
		(net "P3E_CPU0_PE1_SS_C_TXN<7>")
	)
	(segment
		(start 429.554386 -9.840214)
		(end 429.554386 -8.936736)
		(width 0.1143)
		(layer "F.Cu")
		(net "P3E_CPU0_PE1_SS_C_TXN<7>")
	)
	(segment
		(start 429.371252 -10.023348)
		(end 429.554386 -9.840214)
		(width 0.1143)
		(layer "F.Cu")
		(net "P3E_CPU0_PE1_SS_C_TXN<7>")
	)
	(segment
		(start 429.274986 -8.657336)
		(end 429.274986 -7.789672)
		(width 0.1143)
		(layer "F.Cu")
		(net "P3E_CPU0_PE1_SS_C_TXN<7>")
	)
	(segment
		(start 429.030892 -10.023348)
		(end 429.371252 -10.023348)
		(width 0.1143)
		(layer "F.Cu")
		(net "P3E_CPU0_PE1_SS_C_TXN<7>")
	)
	(via
		(at 359.08488 -76.703682)
		(size 0.508)
		(drill 0.254)
		(layers "F.Cu" "B.Cu")
		(net "P3E_CPU0_PE1_SS_C_TXN<7>")
	)
	(via
		(at 429.030892 -10.023348)
		(size 0.508)
		(drill 0.254)
		(layers "F.Cu" "B.Cu")
		(net "P3E_CPU0_PE1_SS_C_TXN<7>")
	)
	(segment
		(start 358.754426 -77.034136)
		(end 359.08488 -76.703682)
		(width 0.1143)
		(layer "B.Cu")
		(net "P3E_CPU0_PE1_SS_C_TXN<7>")
	)
	(segment
		(start 358.44988 -77.034136)
		(end 358.754426 -77.034136)
		(width 0.1143)
		(layer "B.Cu")
		(net "P3E_CPU0_PE1_SS_C_TXN<7>")
	)
	(segment
		(start 376.994166 -16.688816)
		(end 378.643388 -17.039082)
		(width 0.1143)
		(layer "In2.Cu")
		(net "P3E_CPU0_PE1_SS_C_TXN<7>")
	)
	(segment
		(start 361.500674 -59.693302)
		(end 362.983526 -57.379616)
		(width 0.1143)
		(layer "In2.Cu")
		(net "P3E_CPU0_PE1_SS_C_TXN<7>")
	)
	(segment
		(start 388.903972 -14.859)
		(end 391.4902 -15.408402)
		(width 0.1143)
		(layer "In2.Cu")
		(net "P3E_CPU0_PE1_SS_C_TXN<7>")
	)
	(segment
		(start 368.29873 -25.895808)
		(end 368.588544 -25.471882)
		(width 0.1143)
		(layer "In2.Cu")
		(net "P3E_CPU0_PE1_SS_C_TXN<7>")
	)
	(segment
		(start 429.428148 -10.023348)
		(end 429.030892 -10.023348)
		(width 0.1143)
		(layer "In2.Cu")
		(net "P3E_CPU0_PE1_SS_C_TXN<7>")
	)
	(segment
		(start 358.927908 -72.817228)
		(end 357.53802 -68.5546)
		(width 0.1143)
		(layer "In2.Cu")
		(net "P3E_CPU0_PE1_SS_C_TXN<7>")
	)
	(segment
		(start 401.41906 -14.770354)
		(end 402.177758 -14.931644)
		(width 0.1143)
		(layer "In2.Cu")
		(net "P3E_CPU0_PE1_SS_C_TXN<7>")
	)
	(segment
		(start 429.5394 -10.460482)
		(end 429.5394 -10.1346)
		(width 0.1143)
		(layer "In2.Cu")
		(net "P3E_CPU0_PE1_SS_C_TXN<7>")
	)
	(segment
		(start 370.691664 -24.739092)
		(end 371.914928 -23.10257)
		(width 0.1143)
		(layer "In2.Cu")
		(net "P3E_CPU0_PE1_SS_C_TXN<7>")
	)
	(segment
		(start 403.37105 -14.67739)
		(end 405.096726 -15.044674)
		(width 0.1143)
		(layer "In2.Cu")
		(net "P3E_CPU0_PE1_SS_C_TXN<7>")
	)
	(segment
		(start 429.446436 -10.553446)
		(end 429.5394 -10.460482)
		(width 0.1143)
		(layer "In2.Cu")
		(net "P3E_CPU0_PE1_SS_C_TXN<7>")
	)
	(segment
		(start 368.588544 -25.471882)
		(end 370.691664 -24.739092)
		(width 0.1143)
		(layer "In2.Cu")
		(net "P3E_CPU0_PE1_SS_C_TXN<7>")
	)
	(segment
		(start 407.643838 -14.503146)
		(end 412.453836 -15.524734)
		(width 0.1143)
		(layer "In2.Cu")
		(net "P3E_CPU0_PE1_SS_C_TXN<7>")
	)
	(segment
		(start 359.08488 -76.703682)
		(end 359.52303 -76.703682)
		(width 0.1143)
		(layer "In2.Cu")
		(net "P3E_CPU0_PE1_SS_C_TXN<7>")
	)
	(segment
		(start 425.323254 -11.8618)
		(end 425.694348 -11.490706)
		(width 0.1143)
		(layer "In2.Cu")
		(net "P3E_CPU0_PE1_SS_C_TXN<7>")
	)
	(segment
		(start 360.559858 -64.129412)
		(end 361.500674 -59.693302)
		(width 0.1143)
		(layer "In2.Cu")
		(net "P3E_CPU0_PE1_SS_C_TXN<7>")
	)
	(segment
		(start 364.218728 -54.332886)
		(end 363.420152 -52.253896)
		(width 0.1143)
		(layer "In2.Cu")
		(net "P3E_CPU0_PE1_SS_C_TXN<7>")
	)
	(segment
		(start 372.7831 -19.01698)
		(end 375.10085 -17.356836)
		(width 0.1143)
		(layer "In2.Cu")
		(net "P3E_CPU0_PE1_SS_C_TXN<7>")
	)
	(segment
		(start 429.5394 -10.1346)
		(end 429.428148 -10.023348)
		(width 0.1143)
		(layer "In2.Cu")
		(net "P3E_CPU0_PE1_SS_C_TXN<7>")
	)
	(segment
		(start 423.563288 -11.8618)
		(end 425.323254 -11.8618)
		(width 0.1143)
		(layer "In2.Cu")
		(net "P3E_CPU0_PE1_SS_C_TXN<7>")
	)
	(segment
		(start 402.177758 -14.93139)
		(end 403.37105 -14.67739)
		(width 0.1143)
		(layer "In2.Cu")
		(net "P3E_CPU0_PE1_SS_C_TXN<7>")
	)
	(segment
		(start 357.53802 -68.5546)
		(end 358.61117 -65.550034)
		(width 0.1143)
		(layer "In2.Cu")
		(net "P3E_CPU0_PE1_SS_C_TXN<7>")
	)
	(segment
		(start 359.636822 -76.58989)
		(end 359.636822 -76.588112)
		(width 0.1143)
		(layer "In2.Cu")
		(net "P3E_CPU0_PE1_SS_C_TXN<7>")
	)
	(segment
		(start 378.643388 -17.039082)
		(end 388.903972 -14.859)
		(width 0.1143)
		(layer "In2.Cu")
		(net "P3E_CPU0_PE1_SS_C_TXN<7>")
	)
	(segment
		(start 359.52303 -76.703682)
		(end 359.636822 -76.58989)
		(width 0.1143)
		(layer "In2.Cu")
		(net "P3E_CPU0_PE1_SS_C_TXN<7>")
	)
	(segment
		(start 362.983526 -57.379616)
		(end 364.218728 -54.332886)
		(width 0.1143)
		(layer "In2.Cu")
		(net "P3E_CPU0_PE1_SS_C_TXN<7>")
	)
	(segment
		(start 402.177758 -14.931644)
		(end 402.177758 -14.93139)
		(width 0.1143)
		(layer "In2.Cu")
		(net "P3E_CPU0_PE1_SS_C_TXN<7>")
	)
	(segment
		(start 405.096726 -15.044674)
		(end 407.643838 -14.503146)
		(width 0.1143)
		(layer "In2.Cu")
		(net "P3E_CPU0_PE1_SS_C_TXN<7>")
	)
	(segment
		(start 371.914928 -23.10257)
		(end 372.7831 -19.01698)
		(width 0.1143)
		(layer "In2.Cu")
		(net "P3E_CPU0_PE1_SS_C_TXN<7>")
	)
	(segment
		(start 363.420152 -52.253896)
		(end 364.32109 -47.751492)
		(width 0.1143)
		(layer "In2.Cu")
		(net "P3E_CPU0_PE1_SS_C_TXN<7>")
	)
	(segment
		(start 375.102882 -17.356074)
		(end 375.102882 -17.356328)
		(width 0.1143)
		(layer "In2.Cu")
		(net "P3E_CPU0_PE1_SS_C_TXN<7>")
	)
	(segment
		(start 412.453836 -15.524734)
		(end 421.906446 -13.518388)
		(width 0.1143)
		(layer "In2.Cu")
		(net "P3E_CPU0_PE1_SS_C_TXN<7>")
	)
	(segment
		(start 365.971582 -36.837874)
		(end 368.29873 -25.895808)
		(width 0.1143)
		(layer "In2.Cu")
		(net "P3E_CPU0_PE1_SS_C_TXN<7>")
	)
	(segment
		(start 391.4902 -15.408402)
		(end 395.212824 -14.617446)
		(width 0.1143)
		(layer "In2.Cu")
		(net "P3E_CPU0_PE1_SS_C_TXN<7>")
	)
	(segment
		(start 364.613952 -41.982136)
		(end 365.79429 -40.210232)
		(width 0.1143)
		(layer "In2.Cu")
		(net "P3E_CPU0_PE1_SS_C_TXN<7>")
	)
	(segment
		(start 425.694348 -11.490706)
		(end 427.494446 -11.490706)
		(width 0.1143)
		(layer "In2.Cu")
		(net "P3E_CPU0_PE1_SS_C_TXN<7>")
	)
	(segment
		(start 427.494446 -11.490706)
		(end 429.446436 -10.553446)
		(width 0.1143)
		(layer "In2.Cu")
		(net "P3E_CPU0_PE1_SS_C_TXN<7>")
	)
	(segment
		(start 375.10085 -17.356836)
		(end 375.102882 -17.356074)
		(width 0.1143)
		(layer "In2.Cu")
		(net "P3E_CPU0_PE1_SS_C_TXN<7>")
	)
	(segment
		(start 398.67586 -15.352776)
		(end 401.41906 -14.770354)
		(width 0.1143)
		(layer "In2.Cu")
		(net "P3E_CPU0_PE1_SS_C_TXN<7>")
	)
	(segment
		(start 421.906446 -13.518388)
		(end 423.563288 -11.8618)
		(width 0.1143)
		(layer "In2.Cu")
		(net "P3E_CPU0_PE1_SS_C_TXN<7>")
	)
	(segment
		(start 365.79429 -40.210232)
		(end 366.227868 -37.821108)
		(width 0.1143)
		(layer "In2.Cu")
		(net "P3E_CPU0_PE1_SS_C_TXN<7>")
	)
	(segment
		(start 375.102882 -17.356328)
		(end 376.994166 -16.688816)
		(width 0.1143)
		(layer "In2.Cu")
		(net "P3E_CPU0_PE1_SS_C_TXN<7>")
	)
	(segment
		(start 363.802676 -46.055534)
		(end 364.613952 -41.982136)
		(width 0.1143)
		(layer "In2.Cu")
		(net "P3E_CPU0_PE1_SS_C_TXN<7>")
	)
	(segment
		(start 359.636822 -76.588112)
		(end 358.927908 -72.817228)
		(width 0.1143)
		(layer "In2.Cu")
		(net "P3E_CPU0_PE1_SS_C_TXN<7>")
	)
	(segment
		(start 358.61117 -65.550034)
		(end 360.559858 -64.129412)
		(width 0.1143)
		(layer "In2.Cu")
		(net "P3E_CPU0_PE1_SS_C_TXN<7>")
	)
	(segment
		(start 364.32109 -47.751492)
		(end 363.802676 -46.055534)
		(width 0.1143)
		(layer "In2.Cu")
		(net "P3E_CPU0_PE1_SS_C_TXN<7>")
	)
	(segment
		(start 366.227868 -37.821108)
		(end 365.971582 -36.837874)
		(width 0.1143)
		(layer "In2.Cu")
		(net "P3E_CPU0_PE1_SS_C_TXN<7>")
	)
	(segment
		(start 395.212824 -14.617446)
		(end 398.67586 -15.352776)
		(width 0.1143)
		(layer "In2.Cu")
		(net "P3E_CPU0_PE1_SS_C_TXN<7>")
	)
	(segment
		(start 427.674786 -7.789672)
		(end 427.674786 -8.657336)
		(width 0.1143)
		(layer "F.Cu")
		(net "P3E_CPU0_PE1_SS_C_TXN<6>")
	)
	(segment
		(start 427.548548 -10.023348)
		(end 427.900592 -10.023348)
		(width 0.1143)
		(layer "F.Cu")
		(net "P3E_CPU0_PE1_SS_C_TXN<6>")
	)
	(segment
		(start 427.395386 -8.936736)
		(end 427.395386 -9.870186)
		(width 0.1143)
		(layer "F.Cu")
		(net "P3E_CPU0_PE1_SS_C_TXN<6>")
	)
	(segment
		(start 427.395386 -9.870186)
		(end 427.548548 -10.023348)
		(width 0.1143)
		(layer "F.Cu")
		(net "P3E_CPU0_PE1_SS_C_TXN<6>")
	)
	(segment
		(start 427.674786 -8.657336)
		(end 427.395386 -8.936736)
		(width 0.1143)
		(layer "F.Cu")
		(net "P3E_CPU0_PE1_SS_C_TXN<6>")
	)
	(via
		(at 357.768398 -76.719684)
		(size 0.508)
		(drill 0.254)
		(layers "F.Cu" "B.Cu")
		(net "P3E_CPU0_PE1_SS_C_TXN<6>")
	)
	(via
		(at 427.900592 -10.023348)
		(size 0.508)
		(drill 0.254)
		(layers "F.Cu" "B.Cu")
		(net "P3E_CPU0_PE1_SS_C_TXN<6>")
	)
	(segment
		(start 357.461566 -77.026516)
		(end 357.768398 -76.719684)
		(width 0.1143)
		(layer "B.Cu")
		(net "P3E_CPU0_PE1_SS_C_TXN<6>")
	)
	(segment
		(start 357.133398 -77.026516)
		(end 357.461566 -77.026516)
		(width 0.1143)
		(layer "B.Cu")
		(net "P3E_CPU0_PE1_SS_C_TXN<6>")
	)
	(segment
		(start 391.488168 -15.05585)
		(end 388.910322 -14.506956)
		(width 0.1143)
		(layer "In2.Cu")
		(net "P3E_CPU0_PE1_SS_C_TXN<6>")
	)
	(segment
		(start 395.237716 -14.259306)
		(end 391.488168 -15.05585)
		(width 0.1143)
		(layer "In2.Cu")
		(net "P3E_CPU0_PE1_SS_C_TXN<6>")
	)
	(segment
		(start 360.25074 -63.91529)
		(end 360.167682 -63.975742)
		(width 0.1143)
		(layer "In2.Cu")
		(net "P3E_CPU0_PE1_SS_C_TXN<6>")
	)
	(segment
		(start 427.011846 -11.011154)
		(end 425.614846 -11.011154)
		(width 0.1143)
		(layer "In2.Cu")
		(net "P3E_CPU0_PE1_SS_C_TXN<6>")
	)
	(segment
		(start 365.62792 -36.745672)
		(end 364.993428 -37.69741)
		(width 0.1143)
		(layer "In2.Cu")
		(net "P3E_CPU0_PE1_SS_C_TXN<6>")
	)
	(segment
		(start 427.4185 -10.6045)
		(end 427.011846 -11.011154)
		(width 0.1143)
		(layer "In2.Cu")
		(net "P3E_CPU0_PE1_SS_C_TXN<6>")
	)
	(segment
		(start 363.773212 -54.218332)
		(end 362.361734 -57.69737)
		(width 0.1143)
		(layer "In2.Cu")
		(net "P3E_CPU0_PE1_SS_C_TXN<6>")
	)
	(segment
		(start 412.437072 -15.15872)
		(end 407.641044 -14.140434)
		(width 0.1143)
		(layer "In2.Cu")
		(net "P3E_CPU0_PE1_SS_C_TXN<6>")
	)
	(segment
		(start 357.215948 -75.101196)
		(end 357.215948 -76.605384)
		(width 0.1143)
		(layer "In2.Cu")
		(net "P3E_CPU0_PE1_SS_C_TXN<6>")
	)
	(segment
		(start 357.330248 -76.719684)
		(end 357.768398 -76.719684)
		(width 0.1143)
		(layer "In2.Cu")
		(net "P3E_CPU0_PE1_SS_C_TXN<6>")
	)
	(segment
		(start 427.4185 -10.1219)
		(end 427.4185 -10.6045)
		(width 0.1143)
		(layer "In2.Cu")
		(net "P3E_CPU0_PE1_SS_C_TXN<6>")
	)
	(segment
		(start 427.900592 -10.023348)
		(end 427.517052 -10.023348)
		(width 0.1143)
		(layer "In2.Cu")
		(net "P3E_CPU0_PE1_SS_C_TXN<6>")
	)
	(segment
		(start 402.164804 -14.572742)
		(end 401.401788 -14.41069)
		(width 0.1143)
		(layer "In2.Cu")
		(net "P3E_CPU0_PE1_SS_C_TXN<6>")
	)
	(segment
		(start 371.624352 -22.747224)
		(end 370.319808 -24.492458)
		(width 0.1143)
		(layer "In2.Cu")
		(net "P3E_CPU0_PE1_SS_C_TXN<6>")
	)
	(segment
		(start 374.840246 -17.083024)
		(end 372.46687 -18.78203)
		(width 0.1143)
		(layer "In2.Cu")
		(net "P3E_CPU0_PE1_SS_C_TXN<6>")
	)
	(segment
		(start 405.09698 -14.6812)
		(end 403.37613 -14.315186)
		(width 0.1143)
		(layer "In2.Cu")
		(net "P3E_CPU0_PE1_SS_C_TXN<6>")
	)
	(segment
		(start 367.965228 -25.753568)
		(end 365.62792 -36.745672)
		(width 0.1143)
		(layer "In2.Cu")
		(net "P3E_CPU0_PE1_SS_C_TXN<6>")
	)
	(segment
		(start 362.361734 -57.69737)
		(end 361.177078 -59.54522)
		(width 0.1143)
		(layer "In2.Cu")
		(net "P3E_CPU0_PE1_SS_C_TXN<6>")
	)
	(segment
		(start 356.97668 -69.069712)
		(end 357.998014 -72.498966)
		(width 0.1143)
		(layer "In2.Cu")
		(net "P3E_CPU0_PE1_SS_C_TXN<6>")
	)
	(segment
		(start 407.641044 -14.140434)
		(end 405.09698 -14.6812)
		(width 0.1143)
		(layer "In2.Cu")
		(net "P3E_CPU0_PE1_SS_C_TXN<6>")
	)
	(segment
		(start 388.910322 -14.506956)
		(end 378.67971 -16.679418)
		(width 0.1143)
		(layer "In2.Cu")
		(net "P3E_CPU0_PE1_SS_C_TXN<6>")
	)
	(segment
		(start 364.993428 -37.69741)
		(end 362.411264 -50.67935)
		(width 0.1143)
		(layer "In2.Cu")
		(net "P3E_CPU0_PE1_SS_C_TXN<6>")
	)
	(segment
		(start 370.319808 -24.492458)
		(end 368.361214 -25.174448)
		(width 0.1143)
		(layer "In2.Cu")
		(net "P3E_CPU0_PE1_SS_C_TXN<6>")
	)
	(segment
		(start 358.313228 -65.32753)
		(end 356.97668 -69.069712)
		(width 0.1143)
		(layer "In2.Cu")
		(net "P3E_CPU0_PE1_SS_C_TXN<6>")
	)
	(segment
		(start 376.997214 -16.322802)
		(end 374.840246 -17.083024)
		(width 0.1143)
		(layer "In2.Cu")
		(net "P3E_CPU0_PE1_SS_C_TXN<6>")
	)
	(segment
		(start 423.405046 -11.5189)
		(end 421.739822 -13.184378)
		(width 0.1143)
		(layer "In2.Cu")
		(net "P3E_CPU0_PE1_SS_C_TXN<6>")
	)
	(segment
		(start 360.167682 -63.975742)
		(end 358.313228 -65.32753)
		(width 0.1143)
		(layer "In2.Cu")
		(net "P3E_CPU0_PE1_SS_C_TXN<6>")
	)
	(segment
		(start 357.998014 -72.498966)
		(end 357.215948 -75.101196)
		(width 0.1143)
		(layer "In2.Cu")
		(net "P3E_CPU0_PE1_SS_C_TXN<6>")
	)
	(segment
		(start 425.1071 -11.5189)
		(end 423.405046 -11.5189)
		(width 0.1143)
		(layer "In2.Cu")
		(net "P3E_CPU0_PE1_SS_C_TXN<6>")
	)
	(segment
		(start 378.67971 -16.679418)
		(end 376.997214 -16.322802)
		(width 0.1143)
		(layer "In2.Cu")
		(net "P3E_CPU0_PE1_SS_C_TXN<6>")
	)
	(segment
		(start 403.37613 -14.315186)
		(end 402.164804 -14.572742)
		(width 0.1143)
		(layer "In2.Cu")
		(net "P3E_CPU0_PE1_SS_C_TXN<6>")
	)
	(segment
		(start 398.675352 -14.989302)
		(end 395.237716 -14.259306)
		(width 0.1143)
		(layer "In2.Cu")
		(net "P3E_CPU0_PE1_SS_C_TXN<6>")
	)
	(segment
		(start 372.46687 -18.78203)
		(end 371.624352 -22.747224)
		(width 0.1143)
		(layer "In2.Cu")
		(net "P3E_CPU0_PE1_SS_C_TXN<6>")
	)
	(segment
		(start 361.177078 -59.54522)
		(end 360.25074 -63.91529)
		(width 0.1143)
		(layer "In2.Cu")
		(net "P3E_CPU0_PE1_SS_C_TXN<6>")
	)
	(segment
		(start 368.361214 -25.174448)
		(end 367.965228 -25.753568)
		(width 0.1143)
		(layer "In2.Cu")
		(net "P3E_CPU0_PE1_SS_C_TXN<6>")
	)
	(segment
		(start 401.401788 -14.41069)
		(end 398.675352 -14.989302)
		(width 0.1143)
		(layer "In2.Cu")
		(net "P3E_CPU0_PE1_SS_C_TXN<6>")
	)
	(segment
		(start 427.517052 -10.023348)
		(end 427.4185 -10.1219)
		(width 0.1143)
		(layer "In2.Cu")
		(net "P3E_CPU0_PE1_SS_C_TXN<6>")
	)
	(segment
		(start 421.739822 -13.184378)
		(end 412.437072 -15.15872)
		(width 0.1143)
		(layer "In2.Cu")
		(net "P3E_CPU0_PE1_SS_C_TXN<6>")
	)
	(segment
		(start 362.411264 -50.67935)
		(end 363.773212 -54.218332)
		(width 0.1143)
		(layer "In2.Cu")
		(net "P3E_CPU0_PE1_SS_C_TXN<6>")
	)
	(segment
		(start 425.614846 -11.011154)
		(end 425.1071 -11.5189)
		(width 0.1143)
		(layer "In2.Cu")
		(net "P3E_CPU0_PE1_SS_C_TXN<6>")
	)
	(arc
		(start 357.215948 -76.605384)
		(mid 357.249426 -76.686206)
		(end 357.330248 -76.719684)
		(width 0.1143)
		(layer "In2.Cu")
		(net "P3E_CPU0_PE1_SS_C_TXN<6>")
	)
	(segment
		(start 424.995086 -9.832086)
		(end 425.186348 -10.023348)
		(width 0.1143)
		(layer "F.Cu")
		(net "P3E_CPU0_PE1_SS_C_TXN<5>")
	)
	(segment
		(start 425.274486 -8.657336)
		(end 424.995086 -8.936736)
		(width 0.1143)
		(layer "F.Cu")
		(net "P3E_CPU0_PE1_SS_C_TXN<5>")
	)
	(segment
		(start 425.186348 -10.023348)
		(end 425.500292 -10.023348)
		(width 0.1143)
		(layer "F.Cu")
		(net "P3E_CPU0_PE1_SS_C_TXN<5>")
	)
	(segment
		(start 425.274486 -7.789672)
		(end 425.274486 -8.657336)
		(width 0.1143)
		(layer "F.Cu")
		(net "P3E_CPU0_PE1_SS_C_TXN<5>")
	)
	(segment
		(start 424.995086 -8.936736)
		(end 424.995086 -9.832086)
		(width 0.1143)
		(layer "F.Cu")
		(net "P3E_CPU0_PE1_SS_C_TXN<5>")
	)
	(via
		(at 425.500292 -10.023348)
		(size 0.508)
		(drill 0.254)
		(layers "F.Cu" "B.Cu")
		(net "P3E_CPU0_PE1_SS_C_TXN<5>")
	)
	(via
		(at 354.99929 -76.720954)
		(size 0.508)
		(drill 0.254)
		(layers "F.Cu" "B.Cu")
		(net "P3E_CPU0_PE1_SS_C_TXN<5>")
	)
	(segment
		(start 354.36429 -77.026516)
		(end 354.693728 -77.026516)
		(width 0.1143)
		(layer "B.Cu")
		(net "P3E_CPU0_PE1_SS_C_TXN<5>")
	)
	(segment
		(start 354.693728 -77.026516)
		(end 354.99929 -76.720954)
		(width 0.1143)
		(layer "B.Cu")
		(net "P3E_CPU0_PE1_SS_C_TXN<5>")
	)
	(segment
		(start 391.489692 -14.403832)
		(end 388.900162 -13.85316)
		(width 0.1143)
		(layer "In2.Cu")
		(net "P3E_CPU0_PE1_SS_C_TXN<5>")
	)
	(segment
		(start 388.900162 -13.85316)
		(end 378.737114 -16.01343)
		(width 0.1143)
		(layer "In2.Cu")
		(net "P3E_CPU0_PE1_SS_C_TXN<5>")
	)
	(segment
		(start 425.129706 -10.023348)
		(end 425.0436 -10.109454)
		(width 0.1143)
		(layer "In2.Cu")
		(net "P3E_CPU0_PE1_SS_C_TXN<5>")
	)
	(segment
		(start 423.126154 -10.883646)
		(end 421.418004 -12.591796)
		(width 0.1143)
		(layer "In2.Cu")
		(net "P3E_CPU0_PE1_SS_C_TXN<5>")
	)
	(segment
		(start 370.9162 -22.106382)
		(end 370.474494 -22.400768)
		(width 0.1143)
		(layer "In2.Cu")
		(net "P3E_CPU0_PE1_SS_C_TXN<5>")
	)
	(segment
		(start 371.900196 -18.381726)
		(end 371.198648 -21.682202)
		(width 0.1143)
		(layer "In2.Cu")
		(net "P3E_CPU0_PE1_SS_C_TXN<5>")
	)
	(segment
		(start 371.198648 -21.682202)
		(end 370.9162 -22.106382)
		(width 0.1143)
		(layer "In2.Cu")
		(net "P3E_CPU0_PE1_SS_C_TXN<5>")
	)
	(segment
		(start 412.459424 -14.494002)
		(end 407.659332 -13.474192)
		(width 0.1143)
		(layer "In2.Cu")
		(net "P3E_CPU0_PE1_SS_C_TXN<5>")
	)
	(segment
		(start 421.418004 -12.591796)
		(end 412.459424 -14.494002)
		(width 0.1143)
		(layer "In2.Cu")
		(net "P3E_CPU0_PE1_SS_C_TXN<5>")
	)
	(segment
		(start 377.001786 -15.64513)
		(end 374.482614 -16.53286)
		(width 0.1143)
		(layer "In2.Cu")
		(net "P3E_CPU0_PE1_SS_C_TXN<5>")
	)
	(segment
		(start 367.541556 -24.633936)
		(end 365.020352 -36.489132)
		(width 0.1143)
		(layer "In2.Cu")
		(net "P3E_CPU0_PE1_SS_C_TXN<5>")
	)
	(segment
		(start 361.700064 -50.62728)
		(end 363.029246 -54.08422)
		(width 0.1143)
		(layer "In2.Cu")
		(net "P3E_CPU0_PE1_SS_C_TXN<5>")
	)
	(segment
		(start 378.737114 -16.01343)
		(end 377.001786 -15.64513)
		(width 0.1143)
		(layer "In2.Cu")
		(net "P3E_CPU0_PE1_SS_C_TXN<5>")
	)
	(segment
		(start 356.64775 -68.065142)
		(end 354.16109 -72.003666)
		(width 0.1143)
		(layer "In2.Cu")
		(net "P3E_CPU0_PE1_SS_C_TXN<5>")
	)
	(segment
		(start 369.379754 -22.619716)
		(end 368.486436 -23.215092)
		(width 0.1143)
		(layer "In2.Cu")
		(net "P3E_CPU0_PE1_SS_C_TXN<5>")
	)
	(segment
		(start 398.67586 -14.327378)
		(end 395.2621 -13.602208)
		(width 0.1143)
		(layer "In2.Cu")
		(net "P3E_CPU0_PE1_SS_C_TXN<5>")
	)
	(segment
		(start 365.020352 -36.489132)
		(end 364.316518 -37.54501)
		(width 0.1143)
		(layer "In2.Cu")
		(net "P3E_CPU0_PE1_SS_C_TXN<5>")
	)
	(segment
		(start 424.751754 -10.883646)
		(end 423.126154 -10.883646)
		(width 0.1143)
		(layer "In2.Cu")
		(net "P3E_CPU0_PE1_SS_C_TXN<5>")
	)
	(segment
		(start 364.316518 -37.54501)
		(end 361.700064 -50.62728)
		(width 0.1143)
		(layer "In2.Cu")
		(net "P3E_CPU0_PE1_SS_C_TXN<5>")
	)
	(segment
		(start 360.597958 -59.201812)
		(end 359.68051 -63.528702)
		(width 0.1143)
		(layer "In2.Cu")
		(net "P3E_CPU0_PE1_SS_C_TXN<5>")
	)
	(segment
		(start 374.482614 -16.53286)
		(end 371.900196 -18.381726)
		(width 0.1143)
		(layer "In2.Cu")
		(net "P3E_CPU0_PE1_SS_C_TXN<5>")
	)
	(segment
		(start 405.078946 -14.022832)
		(end 403.386544 -13.662914)
		(width 0.1143)
		(layer "In2.Cu")
		(net "P3E_CPU0_PE1_SS_C_TXN<5>")
	)
	(segment
		(start 395.2621 -13.602208)
		(end 391.489692 -14.403832)
		(width 0.1143)
		(layer "In2.Cu")
		(net "P3E_CPU0_PE1_SS_C_TXN<5>")
	)
	(segment
		(start 354.44684 -73.598786)
		(end 354.44684 -76.606654)
		(width 0.1143)
		(layer "In2.Cu")
		(net "P3E_CPU0_PE1_SS_C_TXN<5>")
	)
	(segment
		(start 359.68051 -63.528702)
		(end 357.770176 -64.921384)
		(width 0.1143)
		(layer "In2.Cu")
		(net "P3E_CPU0_PE1_SS_C_TXN<5>")
	)
	(segment
		(start 354.56114 -76.720954)
		(end 354.99929 -76.720954)
		(width 0.1143)
		(layer "In2.Cu")
		(net "P3E_CPU0_PE1_SS_C_TXN<5>")
	)
	(segment
		(start 361.569508 -57.686448)
		(end 360.597958 -59.201812)
		(width 0.1143)
		(layer "In2.Cu")
		(net "P3E_CPU0_PE1_SS_C_TXN<5>")
	)
	(segment
		(start 368.486436 -23.215092)
		(end 367.541556 -24.633936)
		(width 0.1143)
		(layer "In2.Cu")
		(net "P3E_CPU0_PE1_SS_C_TXN<5>")
	)
	(segment
		(start 402.19884 -13.91539)
		(end 401.407376 -13.747242)
		(width 0.1143)
		(layer "In2.Cu")
		(net "P3E_CPU0_PE1_SS_C_TXN<5>")
	)
	(segment
		(start 407.659332 -13.474192)
		(end 405.078946 -14.022832)
		(width 0.1143)
		(layer "In2.Cu")
		(net "P3E_CPU0_PE1_SS_C_TXN<5>")
	)
	(segment
		(start 425.0436 -10.109454)
		(end 425.0436 -10.5918)
		(width 0.1143)
		(layer "In2.Cu")
		(net "P3E_CPU0_PE1_SS_C_TXN<5>")
	)
	(segment
		(start 401.407376 -13.747242)
		(end 398.67586 -14.327378)
		(width 0.1143)
		(layer "In2.Cu")
		(net "P3E_CPU0_PE1_SS_C_TXN<5>")
	)
	(segment
		(start 354.16109 -72.003666)
		(end 354.44684 -73.598786)
		(width 0.1143)
		(layer "In2.Cu")
		(net "P3E_CPU0_PE1_SS_C_TXN<5>")
	)
	(segment
		(start 357.770176 -64.921384)
		(end 356.64775 -68.065142)
		(width 0.1143)
		(layer "In2.Cu")
		(net "P3E_CPU0_PE1_SS_C_TXN<5>")
	)
	(segment
		(start 370.474494 -22.400768)
		(end 369.379754 -22.619716)
		(width 0.1143)
		(layer "In2.Cu")
		(net "P3E_CPU0_PE1_SS_C_TXN<5>")
	)
	(segment
		(start 425.0436 -10.5918)
		(end 424.751754 -10.883646)
		(width 0.1143)
		(layer "In2.Cu")
		(net "P3E_CPU0_PE1_SS_C_TXN<5>")
	)
	(segment
		(start 363.029246 -54.08422)
		(end 361.569508 -57.686448)
		(width 0.1143)
		(layer "In2.Cu")
		(net "P3E_CPU0_PE1_SS_C_TXN<5>")
	)
	(segment
		(start 425.500292 -10.023348)
		(end 425.129706 -10.023348)
		(width 0.1143)
		(layer "In2.Cu")
		(net "P3E_CPU0_PE1_SS_C_TXN<5>")
	)
	(segment
		(start 403.386544 -13.662914)
		(end 402.19884 -13.91539)
		(width 0.1143)
		(layer "In2.Cu")
		(net "P3E_CPU0_PE1_SS_C_TXN<5>")
	)
	(arc
		(start 354.44684 -76.606654)
		(mid 354.480318 -76.687476)
		(end 354.56114 -76.720954)
		(width 0.1143)
		(layer "In2.Cu")
		(net "P3E_CPU0_PE1_SS_C_TXN<5>")
	)
	(segment
		(start 422.585642 -9.909048)
		(end 422.699942 -10.023348)
		(width 0.1143)
		(layer "F.Cu")
		(net "P3E_CPU0_PE1_SS_C_TXN<4>")
	)
	(segment
		(start 422.699942 -10.023348)
		(end 423.099992 -10.023348)
		(width 0.1143)
		(layer "F.Cu")
		(net "P3E_CPU0_PE1_SS_C_TXN<4>")
	)
	(segment
		(start 422.585642 -8.94588)
		(end 422.585642 -9.909048)
		(width 0.1143)
		(layer "F.Cu")
		(net "P3E_CPU0_PE1_SS_C_TXN<4>")
	)
	(segment
		(start 422.874186 -8.657336)
		(end 422.585642 -8.94588)
		(width 0.1143)
		(layer "F.Cu")
		(net "P3E_CPU0_PE1_SS_C_TXN<4>")
	)
	(segment
		(start 422.874186 -7.789672)
		(end 422.874186 -8.657336)
		(width 0.1143)
		(layer "F.Cu")
		(net "P3E_CPU0_PE1_SS_C_TXN<4>")
	)
	(via
		(at 423.099992 -10.023348)
		(size 0.508)
		(drill 0.254)
		(layers "F.Cu" "B.Cu")
		(net "P3E_CPU0_PE1_SS_C_TXN<4>")
	)
	(via
		(at 352.069654 -76.57211)
		(size 0.508)
		(drill 0.254)
		(layers "F.Cu" "B.Cu")
		(net "P3E_CPU0_PE1_SS_C_TXN<4>")
	)
	(segment
		(start 351.696528 -76.945236)
		(end 352.069654 -76.57211)
		(width 0.1143)
		(layer "B.Cu")
		(net "P3E_CPU0_PE1_SS_C_TXN<4>")
	)
	(segment
		(start 351.421192 -76.945236)
		(end 351.696528 -76.945236)
		(width 0.1143)
		(layer "B.Cu")
		(net "P3E_CPU0_PE1_SS_C_TXN<4>")
	)
	(segment
		(start 351.501202 -75.92441)
		(end 351.768156 -75.38085)
		(width 0.1143)
		(layer "In2.Cu")
		(net "P3E_CPU0_PE1_SS_C_TXN<4>")
	)
	(segment
		(start 356.062026 -67.779392)
		(end 357.227378 -64.515492)
		(width 0.1143)
		(layer "In2.Cu")
		(net "P3E_CPU0_PE1_SS_C_TXN<4>")
	)
	(segment
		(start 353.55657 -71.750428)
		(end 353.555046 -71.749412)
		(width 0.1143)
		(layer "In2.Cu")
		(net "P3E_CPU0_PE1_SS_C_TXN<4>")
	)
	(segment
		(start 405.139652 -13.347954)
		(end 405.139652 -13.3477)
		(width 0.1143)
		(layer "In2.Cu")
		(net "P3E_CPU0_PE1_SS_C_TXN<4>")
	)
	(segment
		(start 353.403408 -73.225914)
		(end 353.041712 -73.048114)
		(width 0.1143)
		(layer "In2.Cu")
		(net "P3E_CPU0_PE1_SS_C_TXN<4>")
	)
	(segment
		(start 409.995116 -13.310616)
		(end 412.458916 -13.833856)
		(width 0.1143)
		(layer "In2.Cu")
		(net "P3E_CPU0_PE1_SS_C_TXN<4>")
	)
	(segment
		(start 377.017534 -14.96314)
		(end 378.806456 -15.342362)
		(width 0.1143)
		(layer "In2.Cu")
		(net "P3E_CPU0_PE1_SS_C_TXN<4>")
	)
	(segment
		(start 395.28623 -12.945364)
		(end 398.676114 -13.664946)
		(width 0.1143)
		(layer "In2.Cu")
		(net "P3E_CPU0_PE1_SS_C_TXN<4>")
	)
	(segment
		(start 420.872158 -10.8331)
		(end 422.227502 -10.8331)
		(width 0.1143)
		(layer "In2.Cu")
		(net "P3E_CPU0_PE1_SS_C_TXN<4>")
	)
	(segment
		(start 352.664268 -75.376532)
		(end 352.872294 -74.953622)
		(width 0.1143)
		(layer "In2.Cu")
		(net "P3E_CPU0_PE1_SS_C_TXN<4>")
	)
	(segment
		(start 378.806456 -15.342362)
		(end 388.894066 -13.200126)
		(width 0.1143)
		(layer "In2.Cu")
		(net "P3E_CPU0_PE1_SS_C_TXN<4>")
	)
	(segment
		(start 352.741992 -74.57186)
		(end 352.380042 -74.39406)
		(width 0.1143)
		(layer "In2.Cu")
		(net "P3E_CPU0_PE1_SS_C_TXN<4>")
	)
	(segment
		(start 352.943922 -74.160888)
		(end 353.325684 -74.030586)
		(width 0.1143)
		(layer "In2.Cu")
		(net "P3E_CPU0_PE1_SS_C_TXN<4>")
	)
	(segment
		(start 352.328226 -74.24166)
		(end 352.429572 -74.034904)
		(width 0.1143)
		(layer "In2.Cu")
		(net "P3E_CPU0_PE1_SS_C_TXN<4>")
	)
	(segment
		(start 351.502472 -76.47432)
		(end 351.501202 -76.465684)
		(width 0.1143)
		(layer "In2.Cu")
		(net "P3E_CPU0_PE1_SS_C_TXN<4>")
	)
	(segment
		(start 361.023916 -50.614072)
		(end 363.6899 -37.311584)
		(width 0.1143)
		(layer "In2.Cu")
		(net "P3E_CPU0_PE1_SS_C_TXN<4>")
	)
	(segment
		(start 398.676114 -13.664946)
		(end 401.387564 -13.089382)
		(width 0.1143)
		(layer "In2.Cu")
		(net "P3E_CPU0_PE1_SS_C_TXN<4>")
	)
	(segment
		(start 388.894066 -13.200126)
		(end 391.489692 -13.752068)
		(width 0.1143)
		(layer "In2.Cu")
		(net "P3E_CPU0_PE1_SS_C_TXN<4>")
	)
	(segment
		(start 352.282506 -75.506834)
		(end 352.664268 -75.376532)
		(width 0.1143)
		(layer "In2.Cu")
		(net "P3E_CPU0_PE1_SS_C_TXN<4>")
	)
	(segment
		(start 352.429572 -74.034904)
		(end 352.581972 -73.983088)
		(width 0.1143)
		(layer "In2.Cu")
		(net "P3E_CPU0_PE1_SS_C_TXN<4>")
	)
	(segment
		(start 357.227378 -64.515492)
		(end 359.07853 -63.16599)
		(width 0.1143)
		(layer "In2.Cu")
		(net "P3E_CPU0_PE1_SS_C_TXN<4>")
	)
	(segment
		(start 361.34294 -52.209446)
		(end 361.023916 -50.614072)
		(width 0.1143)
		(layer "In2.Cu")
		(net "P3E_CPU0_PE1_SS_C_TXN<4>")
	)
	(segment
		(start 353.041712 -73.048114)
		(end 352.989642 -72.895714)
		(width 0.1143)
		(layer "In2.Cu")
		(net "P3E_CPU0_PE1_SS_C_TXN<4>")
	)
	(segment
		(start 352.380042 -74.39406)
		(end 352.328226 -74.24166)
		(width 0.1143)
		(layer "In2.Cu")
		(net "P3E_CPU0_PE1_SS_C_TXN<4>")
	)
	(segment
		(start 352.069654 -76.57211)
		(end 351.615502 -76.57211)
		(width 0.1143)
		(layer "In2.Cu")
		(net "P3E_CPU0_PE1_SS_C_TXN<4>")
	)
	(segment
		(start 351.920556 -75.329034)
		(end 352.282506 -75.506834)
		(width 0.1143)
		(layer "In2.Cu")
		(net "P3E_CPU0_PE1_SS_C_TXN<4>")
	)
	(segment
		(start 353.325684 -74.030586)
		(end 353.53371 -73.607676)
		(width 0.1143)
		(layer "In2.Cu")
		(net "P3E_CPU0_PE1_SS_C_TXN<4>")
	)
	(segment
		(start 407.652982 -12.813284)
		(end 409.995116 -13.310616)
		(width 0.1143)
		(layer "In2.Cu")
		(net "P3E_CPU0_PE1_SS_C_TXN<4>")
	)
	(segment
		(start 352.581972 -73.983088)
		(end 352.943922 -74.160888)
		(width 0.1143)
		(layer "In2.Cu")
		(net "P3E_CPU0_PE1_SS_C_TXN<4>")
	)
	(segment
		(start 360.539538 -56.219852)
		(end 361.34294 -52.209446)
		(width 0.1143)
		(layer "In2.Cu")
		(net "P3E_CPU0_PE1_SS_C_TXN<4>")
	)
	(segment
		(start 353.556316 -71.750428)
		(end 353.55657 -71.750428)
		(width 0.1143)
		(layer "In2.Cu")
		(net "P3E_CPU0_PE1_SS_C_TXN<4>")
	)
	(segment
		(start 363.6899 -37.311584)
		(end 364.414308 -36.225226)
		(width 0.1143)
		(layer "In2.Cu")
		(net "P3E_CPU0_PE1_SS_C_TXN<4>")
	)
	(segment
		(start 370.9416 -19.177254)
		(end 371.332506 -17.985232)
		(width 0.1143)
		(layer "In2.Cu")
		(net "P3E_CPU0_PE1_SS_C_TXN<4>")
	)
	(segment
		(start 405.078946 -13.360654)
		(end 405.139652 -13.347954)
		(width 0.1143)
		(layer "In2.Cu")
		(net "P3E_CPU0_PE1_SS_C_TXN<4>")
	)
	(segment
		(start 368.580162 -20.992084)
		(end 370.652294 -19.610832)
		(width 0.1143)
		(layer "In2.Cu")
		(net "P3E_CPU0_PE1_SS_C_TXN<4>")
	)
	(segment
		(start 403.379432 -12.999212)
		(end 405.078946 -13.360654)
		(width 0.1143)
		(layer "In2.Cu")
		(net "P3E_CPU0_PE1_SS_C_TXN<4>")
	)
	(segment
		(start 422.227502 -10.8331)
		(end 422.639744 -10.420858)
		(width 0.1143)
		(layer "In2.Cu")
		(net "P3E_CPU0_PE1_SS_C_TXN<4>")
	)
	(segment
		(start 401.387564 -13.089382)
		(end 402.172424 -13.25626)
		(width 0.1143)
		(layer "In2.Cu")
		(net "P3E_CPU0_PE1_SS_C_TXN<4>")
	)
	(segment
		(start 370.652294 -19.610832)
		(end 370.9416 -19.177254)
		(width 0.1143)
		(layer "In2.Cu")
		(net "P3E_CPU0_PE1_SS_C_TXN<4>")
	)
	(segment
		(start 352.989642 -72.895714)
		(end 353.556316 -71.750428)
		(width 0.1143)
		(layer "In2.Cu")
		(net "P3E_CPU0_PE1_SS_C_TXN<4>")
	)
	(segment
		(start 351.501202 -76.465684)
		(end 351.501202 -75.92441)
		(width 0.1143)
		(layer "In2.Cu")
		(net "P3E_CPU0_PE1_SS_C_TXN<4>")
	)
	(segment
		(start 367.219992 -23.032212)
		(end 368.580162 -20.992084)
		(width 0.1143)
		(layer "In2.Cu")
		(net "P3E_CPU0_PE1_SS_C_TXN<4>")
	)
	(segment
		(start 391.489692 -13.752068)
		(end 395.28623 -12.945364)
		(width 0.1143)
		(layer "In2.Cu")
		(net "P3E_CPU0_PE1_SS_C_TXN<4>")
	)
	(segment
		(start 405.139652 -13.3477)
		(end 407.652982 -12.813284)
		(width 0.1143)
		(layer "In2.Cu")
		(net "P3E_CPU0_PE1_SS_C_TXN<4>")
	)
	(segment
		(start 364.414308 -36.225226)
		(end 367.219992 -23.032212)
		(width 0.1143)
		(layer "In2.Cu")
		(net "P3E_CPU0_PE1_SS_C_TXN<4>")
	)
	(segment
		(start 402.172424 -13.25626)
		(end 403.379432 -12.999212)
		(width 0.1143)
		(layer "In2.Cu")
		(net "P3E_CPU0_PE1_SS_C_TXN<4>")
	)
	(segment
		(start 360.69905 -56.998108)
		(end 360.539538 -56.219852)
		(width 0.1143)
		(layer "In2.Cu")
		(net "P3E_CPU0_PE1_SS_C_TXN<4>")
	)
	(segment
		(start 359.07853 -63.16599)
		(end 359.93832 -59.109356)
		(width 0.1143)
		(layer "In2.Cu")
		(net "P3E_CPU0_PE1_SS_C_TXN<4>")
	)
	(segment
		(start 353.5553 -71.749412)
		(end 356.062026 -67.779392)
		(width 0.1143)
		(layer "In2.Cu")
		(net "P3E_CPU0_PE1_SS_C_TXN<4>")
	)
	(segment
		(start 422.792398 -10.023348)
		(end 423.099992 -10.023348)
		(width 0.1143)
		(layer "In2.Cu")
		(net "P3E_CPU0_PE1_SS_C_TXN<4>")
	)
	(segment
		(start 371.332506 -17.985232)
		(end 374.13311 -15.98041)
		(width 0.1143)
		(layer "In2.Cu")
		(net "P3E_CPU0_PE1_SS_C_TXN<4>")
	)
	(segment
		(start 351.768156 -75.38085)
		(end 351.920556 -75.329034)
		(width 0.1143)
		(layer "In2.Cu")
		(net "P3E_CPU0_PE1_SS_C_TXN<4>")
	)
	(segment
		(start 353.53371 -73.607676)
		(end 353.403408 -73.225914)
		(width 0.1143)
		(layer "In2.Cu")
		(net "P3E_CPU0_PE1_SS_C_TXN<4>")
	)
	(segment
		(start 422.639744 -10.176002)
		(end 422.792398 -10.023348)
		(width 0.1143)
		(layer "In2.Cu")
		(net "P3E_CPU0_PE1_SS_C_TXN<4>")
	)
	(segment
		(start 419.32987 -12.375642)
		(end 420.872158 -10.8331)
		(width 0.1143)
		(layer "In2.Cu")
		(net "P3E_CPU0_PE1_SS_C_TXN<4>")
	)
	(segment
		(start 422.639744 -10.420858)
		(end 422.639744 -10.176002)
		(width 0.1143)
		(layer "In2.Cu")
		(net "P3E_CPU0_PE1_SS_C_TXN<4>")
	)
	(segment
		(start 359.93832 -59.109356)
		(end 360.69905 -56.998108)
		(width 0.1143)
		(layer "In2.Cu")
		(net "P3E_CPU0_PE1_SS_C_TXN<4>")
	)
	(segment
		(start 374.13311 -15.98041)
		(end 377.017534 -14.96314)
		(width 0.1143)
		(layer "In2.Cu")
		(net "P3E_CPU0_PE1_SS_C_TXN<4>")
	)
	(segment
		(start 353.555046 -71.749412)
		(end 353.5553 -71.749412)
		(width 0.1143)
		(layer "In2.Cu")
		(net "P3E_CPU0_PE1_SS_C_TXN<4>")
	)
	(segment
		(start 412.458916 -13.833856)
		(end 419.32987 -12.375642)
		(width 0.1143)
		(layer "In2.Cu")
		(net "P3E_CPU0_PE1_SS_C_TXN<4>")
	)
	(segment
		(start 352.872294 -74.953622)
		(end 352.741992 -74.57186)
		(width 0.1143)
		(layer "In2.Cu")
		(net "P3E_CPU0_PE1_SS_C_TXN<4>")
	)
	(arc
		(start 351.615502 -76.57211)
		(mid 351.540748 -76.544276)
		(end 351.502472 -76.47432)
		(width 0.1143)
		(layer "In2.Cu")
		(net "P3E_CPU0_PE1_SS_C_TXN<4>")
	)
	(segment
		(start 420.299642 -10.023348)
		(end 420.699692 -10.023348)
		(width 0.1143)
		(layer "F.Cu")
		(net "P3E_CPU0_PE1_SS_C_TXN<3>")
	)
	(segment
		(start 420.185342 -8.94588)
		(end 420.185342 -9.909048)
		(width 0.1143)
		(layer "F.Cu")
		(net "P3E_CPU0_PE1_SS_C_TXN<3>")
	)
	(segment
		(start 420.473886 -8.657336)
		(end 420.185342 -8.94588)
		(width 0.1143)
		(layer "F.Cu")
		(net "P3E_CPU0_PE1_SS_C_TXN<3>")
	)
	(segment
		(start 420.473886 -7.789672)
		(end 420.473886 -8.657336)
		(width 0.1143)
		(layer "F.Cu")
		(net "P3E_CPU0_PE1_SS_C_TXN<3>")
	)
	(segment
		(start 420.185342 -9.909048)
		(end 420.299642 -10.023348)
		(width 0.1143)
		(layer "F.Cu")
		(net "P3E_CPU0_PE1_SS_C_TXN<3>")
	)
	(via
		(at 420.699692 -10.023348)
		(size 0.508)
		(drill 0.254)
		(layers "F.Cu" "B.Cu")
		(net "P3E_CPU0_PE1_SS_C_TXN<3>")
	)
	(via
		(at 349.20428 -76.509626)
		(size 0.508)
		(drill 0.254)
		(layers "F.Cu" "B.Cu")
		(net "P3E_CPU0_PE1_SS_C_TXN<3>")
	)
	(segment
		(start 348.946724 -76.899516)
		(end 349.20428 -76.64196)
		(width 0.1143)
		(layer "B.Cu")
		(net "P3E_CPU0_PE1_SS_C_TXN<3>")
	)
	(segment
		(start 348.57436 -76.899516)
		(end 348.946724 -76.899516)
		(width 0.1143)
		(layer "B.Cu")
		(net "P3E_CPU0_PE1_SS_C_TXN<3>")
	)
	(segment
		(start 349.20428 -76.64196)
		(end 349.20428 -76.509626)
		(width 0.1143)
		(layer "B.Cu")
		(net "P3E_CPU0_PE1_SS_C_TXN<3>")
	)
	(segment
		(start 402.219922 -12.57681)
		(end 401.451572 -12.413742)
		(width 0.1143)
		(layer "In2.Cu")
		(net "P3E_CPU0_PE1_SS_C_TXN<3>")
	)
	(segment
		(start 407.753058 -12.130024)
		(end 405.0792 -12.698476)
		(width 0.1143)
		(layer "In2.Cu")
		(net "P3E_CPU0_PE1_SS_C_TXN<3>")
	)
	(segment
		(start 388.893812 -12.548362)
		(end 378.854208 -14.681708)
		(width 0.1143)
		(layer "In2.Cu")
		(net "P3E_CPU0_PE1_SS_C_TXN<3>")
	)
	(segment
		(start 352.84664 -71.658988)
		(end 351.549208 -74.30008)
		(width 0.1143)
		(layer "In2.Cu")
		(net "P3E_CPU0_PE1_SS_C_TXN<3>")
	)
	(segment
		(start 358.507792 -62.78118)
		(end 356.68458 -64.1096)
		(width 0.1143)
		(layer "In2.Cu")
		(net "P3E_CPU0_PE1_SS_C_TXN<3>")
	)
	(segment
		(start 401.451572 -12.413742)
		(end 398.676622 -13.003022)
		(width 0.1143)
		(layer "In2.Cu")
		(net "P3E_CPU0_PE1_SS_C_TXN<3>")
	)
	(segment
		(start 419.02126 -11.76274)
		(end 412.519876 -13.142722)
		(width 0.1143)
		(layer "In2.Cu")
		(net "P3E_CPU0_PE1_SS_C_TXN<3>")
	)
	(segment
		(start 405.0792 -12.698476)
		(end 403.363684 -12.333732)
		(width 0.1143)
		(layer "In2.Cu")
		(net "P3E_CPU0_PE1_SS_C_TXN<3>")
	)
	(segment
		(start 398.676622 -13.003022)
		(end 395.31036 -12.288266)
		(width 0.1143)
		(layer "In2.Cu")
		(net "P3E_CPU0_PE1_SS_C_TXN<3>")
	)
	(segment
		(start 391.490454 -13.100304)
		(end 388.893812 -12.548362)
		(width 0.1143)
		(layer "In2.Cu")
		(net "P3E_CPU0_PE1_SS_C_TXN<3>")
	)
	(segment
		(start 359.194354 -53.09743)
		(end 360.004868 -57.05094)
		(width 0.1143)
		(layer "In2.Cu")
		(net "P3E_CPU0_PE1_SS_C_TXN<3>")
	)
	(segment
		(start 363.815884 -35.926268)
		(end 363.102398 -36.996624)
		(width 0.1143)
		(layer "In2.Cu")
		(net "P3E_CPU0_PE1_SS_C_TXN<3>")
	)
	(segment
		(start 360.004868 -57.05094)
		(end 359.31221 -58.971942)
		(width 0.1143)
		(layer "In2.Cu")
		(net "P3E_CPU0_PE1_SS_C_TXN<3>")
	)
	(segment
		(start 412.519876 -13.142722)
		(end 407.753058 -12.130024)
		(width 0.1143)
		(layer "In2.Cu")
		(net "P3E_CPU0_PE1_SS_C_TXN<3>")
	)
	(segment
		(start 361.349544 -45.754036)
		(end 360.372914 -47.205392)
		(width 0.1143)
		(layer "In2.Cu")
		(net "P3E_CPU0_PE1_SS_C_TXN<3>")
	)
	(segment
		(start 360.372914 -47.205392)
		(end 360.167682 -48.231298)
		(width 0.1143)
		(layer "In2.Cu")
		(net "P3E_CPU0_PE1_SS_C_TXN<3>")
	)
	(segment
		(start 420.2303 -10.147554)
		(end 420.2303 -10.5537)
		(width 0.1143)
		(layer "In2.Cu")
		(net "P3E_CPU0_PE1_SS_C_TXN<3>")
	)
	(segment
		(start 420.354506 -10.023348)
		(end 420.2303 -10.147554)
		(width 0.1143)
		(layer "In2.Cu")
		(net "P3E_CPU0_PE1_SS_C_TXN<3>")
	)
	(segment
		(start 363.102398 -36.996624)
		(end 361.349544 -45.754036)
		(width 0.1143)
		(layer "In2.Cu")
		(net "P3E_CPU0_PE1_SS_C_TXN<3>")
	)
	(segment
		(start 378.854208 -14.681708)
		(end 377.008136 -14.289786)
		(width 0.1143)
		(layer "In2.Cu")
		(net "P3E_CPU0_PE1_SS_C_TXN<3>")
	)
	(segment
		(start 377.008136 -14.289786)
		(end 371.337586 -16.290036)
		(width 0.1143)
		(layer "In2.Cu")
		(net "P3E_CPU0_PE1_SS_C_TXN<3>")
	)
	(segment
		(start 356.68458 -64.1096)
		(end 355.487224 -67.46113)
		(width 0.1143)
		(layer "In2.Cu")
		(net "P3E_CPU0_PE1_SS_C_TXN<3>")
	)
	(segment
		(start 360.167682 -48.231298)
		(end 359.194354 -53.09743)
		(width 0.1143)
		(layer "In2.Cu")
		(net "P3E_CPU0_PE1_SS_C_TXN<3>")
	)
	(segment
		(start 359.31221 -58.971942)
		(end 358.507792 -62.78118)
		(width 0.1143)
		(layer "In2.Cu")
		(net "P3E_CPU0_PE1_SS_C_TXN<3>")
	)
	(segment
		(start 355.48697 -67.461638)
		(end 352.84664 -71.659242)
		(width 0.1143)
		(layer "In2.Cu")
		(net "P3E_CPU0_PE1_SS_C_TXN<3>")
	)
	(segment
		(start 395.31036 -12.288266)
		(end 391.490454 -13.100304)
		(width 0.1143)
		(layer "In2.Cu")
		(net "P3E_CPU0_PE1_SS_C_TXN<3>")
	)
	(segment
		(start 348.65691 -76.064618)
		(end 348.65691 -76.395326)
		(width 0.1143)
		(layer "In2.Cu")
		(net "P3E_CPU0_PE1_SS_C_TXN<3>")
	)
	(segment
		(start 367.390934 -19.115278)
		(end 363.815884 -35.926268)
		(width 0.1143)
		(layer "In2.Cu")
		(net "P3E_CPU0_PE1_SS_C_TXN<3>")
	)
	(segment
		(start 420.2303 -10.5537)
		(end 419.02126 -11.76274)
		(width 0.1143)
		(layer "In2.Cu")
		(net "P3E_CPU0_PE1_SS_C_TXN<3>")
	)
	(segment
		(start 355.487224 -67.461384)
		(end 355.48697 -67.461638)
		(width 0.1143)
		(layer "In2.Cu")
		(net "P3E_CPU0_PE1_SS_C_TXN<3>")
	)
	(segment
		(start 403.363684 -12.333732)
		(end 402.219922 -12.57681)
		(width 0.1143)
		(layer "In2.Cu")
		(net "P3E_CPU0_PE1_SS_C_TXN<3>")
	)
	(segment
		(start 348.77121 -76.509626)
		(end 349.20428 -76.509626)
		(width 0.1143)
		(layer "In2.Cu")
		(net "P3E_CPU0_PE1_SS_C_TXN<3>")
	)
	(segment
		(start 352.84664 -71.659242)
		(end 352.84664 -71.658988)
		(width 0.1143)
		(layer "In2.Cu")
		(net "P3E_CPU0_PE1_SS_C_TXN<3>")
	)
	(segment
		(start 371.337586 -16.290036)
		(end 367.390934 -19.115278)
		(width 0.1143)
		(layer "In2.Cu")
		(net "P3E_CPU0_PE1_SS_C_TXN<3>")
	)
	(segment
		(start 420.699692 -10.023348)
		(end 420.354506 -10.023348)
		(width 0.1143)
		(layer "In2.Cu")
		(net "P3E_CPU0_PE1_SS_C_TXN<3>")
	)
	(segment
		(start 355.487224 -67.46113)
		(end 355.487224 -67.461384)
		(width 0.1143)
		(layer "In2.Cu")
		(net "P3E_CPU0_PE1_SS_C_TXN<3>")
	)
	(segment
		(start 351.549208 -74.30008)
		(end 348.65691 -76.064618)
		(width 0.1143)
		(layer "In2.Cu")
		(net "P3E_CPU0_PE1_SS_C_TXN<3>")
	)
	(arc
		(start 348.65691 -76.395326)
		(mid 348.690388 -76.476148)
		(end 348.77121 -76.509626)
		(width 0.1143)
		(layer "In2.Cu")
		(net "P3E_CPU0_PE1_SS_C_TXN<3>")
	)
	(segment
		(start 417.794186 -8.936736)
		(end 417.794186 -9.819386)
		(width 0.1143)
		(layer "F.Cu")
		(net "P3E_CPU0_PE1_SS_C_TXN<2>")
	)
	(segment
		(start 418.073586 -7.789672)
		(end 418.073586 -8.657336)
		(width 0.1143)
		(layer "F.Cu")
		(net "P3E_CPU0_PE1_SS_C_TXN<2>")
	)
	(segment
		(start 417.998148 -10.023348)
		(end 418.299392 -10.023348)
		(width 0.1143)
		(layer "F.Cu")
		(net "P3E_CPU0_PE1_SS_C_TXN<2>")
	)
	(segment
		(start 417.794186 -9.819386)
		(end 417.998148 -10.023348)
		(width 0.1143)
		(layer "F.Cu")
		(net "P3E_CPU0_PE1_SS_C_TXN<2>")
	)
	(segment
		(start 418.073586 -8.657336)
		(end 417.794186 -8.936736)
		(width 0.1143)
		(layer "F.Cu")
		(net "P3E_CPU0_PE1_SS_C_TXN<2>")
	)
	(via
		(at 418.299392 -10.023348)
		(size 0.508)
		(drill 0.254)
		(layers "F.Cu" "B.Cu")
		(net "P3E_CPU0_PE1_SS_C_TXN<2>")
	)
	(via
		(at 346.459556 -76.40701)
		(size 0.508)
		(drill 0.254)
		(layers "F.Cu" "B.Cu")
		(net "P3E_CPU0_PE1_SS_C_TXN<2>")
	)
	(segment
		(start 346.144088 -76.805536)
		(end 346.459556 -76.490068)
		(width 0.1143)
		(layer "B.Cu")
		(net "P3E_CPU0_PE1_SS_C_TXN<2>")
	)
	(segment
		(start 346.459556 -76.490068)
		(end 346.459556 -76.40701)
		(width 0.1143)
		(layer "B.Cu")
		(net "P3E_CPU0_PE1_SS_C_TXN<2>")
	)
	(segment
		(start 345.832176 -76.805536)
		(end 346.144088 -76.805536)
		(width 0.1143)
		(layer "B.Cu")
		(net "P3E_CPU0_PE1_SS_C_TXN<2>")
	)
	(segment
		(start 346.739718 -75.669648)
		(end 346.448888 -75.851258)
		(width 0.1143)
		(layer "In2.Cu")
		(net "P3E_CPU0_PE1_SS_C_TXN<2>")
	)
	(segment
		(start 362.490766 -36.74999)
		(end 360.743246 -45.49521)
		(width 0.1143)
		(layer "In2.Cu")
		(net "P3E_CPU0_PE1_SS_C_TXN<2>")
	)
	(segment
		(start 346.221304 -75.79868)
		(end 345.914726 -75.989942)
		(width 0.1143)
		(layer "In2.Cu")
		(net "P3E_CPU0_PE1_SS_C_TXN<2>")
	)
	(segment
		(start 353.550982 -67.968114)
		(end 352.252026 -70.509892)
		(width 0.1143)
		(layer "In2.Cu")
		(net "P3E_CPU0_PE1_SS_C_TXN<2>")
	)
	(segment
		(start 412.531052 -12.473686)
		(end 407.77414 -11.463274)
		(width 0.1143)
		(layer "In2.Cu")
		(net "P3E_CPU0_PE1_SS_C_TXN<2>")
	)
	(segment
		(start 417.821872 -10.137648)
		(end 417.821872 -11.039602)
		(width 0.1143)
		(layer "In2.Cu")
		(net "P3E_CPU0_PE1_SS_C_TXN<2>")
	)
	(segment
		(start 350.342454 -71.644256)
		(end 348.358968 -74.464672)
		(width 0.1143)
		(layer "In2.Cu")
		(net "P3E_CPU0_PE1_SS_C_TXN<2>")
	)
	(segment
		(start 358.716834 -58.688224)
		(end 358.480614 -59.804808)
		(width 0.1143)
		(layer "In2.Cu")
		(net "P3E_CPU0_PE1_SS_C_TXN<2>")
	)
	(segment
		(start 395.335252 -11.631422)
		(end 391.490454 -12.44854)
		(width 0.1143)
		(layer "In2.Cu")
		(net "P3E_CPU0_PE1_SS_C_TXN<2>")
	)
	(segment
		(start 378.872242 -14.017752)
		(end 376.993912 -13.619226)
		(width 0.1143)
		(layer "In2.Cu")
		(net "P3E_CPU0_PE1_SS_C_TXN<2>")
	)
	(segment
		(start 403.448012 -11.656568)
		(end 402.28647 -11.903456)
		(width 0.1143)
		(layer "In2.Cu")
		(net "P3E_CPU0_PE1_SS_C_TXN<2>")
	)
	(segment
		(start 418.299392 -10.023348)
		(end 417.936172 -10.023348)
		(width 0.1143)
		(layer "In2.Cu")
		(net "P3E_CPU0_PE1_SS_C_TXN<2>")
	)
	(segment
		(start 359.331514 -56.983122)
		(end 358.716834 -58.688224)
		(width 0.1143)
		(layer "In2.Cu")
		(net "P3E_CPU0_PE1_SS_C_TXN<2>")
	)
	(segment
		(start 345.914726 -75.989942)
		(end 345.914726 -76.1746)
		(width 0.1143)
		(layer "In2.Cu")
		(net "P3E_CPU0_PE1_SS_C_TXN<2>")
	)
	(segment
		(start 355.404166 -63.226696)
		(end 353.550982 -67.968114)
		(width 0.1143)
		(layer "In2.Cu")
		(net "P3E_CPU0_PE1_SS_C_TXN<2>")
	)
	(segment
		(start 398.676114 -12.341098)
		(end 395.335252 -11.631422)
		(width 0.1143)
		(layer "In2.Cu")
		(net "P3E_CPU0_PE1_SS_C_TXN<2>")
	)
	(segment
		(start 352.252026 -70.509892)
		(end 350.342454 -71.644256)
		(width 0.1143)
		(layer "In2.Cu")
		(net "P3E_CPU0_PE1_SS_C_TXN<2>")
	)
	(segment
		(start 402.28647 -11.903456)
		(end 401.511516 -11.738864)
		(width 0.1143)
		(layer "In2.Cu")
		(net "P3E_CPU0_PE1_SS_C_TXN<2>")
	)
	(segment
		(start 359.604818 -47.182786)
		(end 358.478582 -52.819046)
		(width 0.1143)
		(layer "In2.Cu")
		(net "P3E_CPU0_PE1_SS_C_TXN<2>")
	)
	(segment
		(start 417.936172 -10.023348)
		(end 417.821872 -10.137648)
		(width 0.1143)
		(layer "In2.Cu")
		(net "P3E_CPU0_PE1_SS_C_TXN<2>")
	)
	(segment
		(start 417.821872 -11.039602)
		(end 417.426902 -11.434826)
		(width 0.1143)
		(layer "In2.Cu")
		(net "P3E_CPU0_PE1_SS_C_TXN<2>")
	)
	(segment
		(start 346.448888 -75.851258)
		(end 346.221304 -75.79868)
		(width 0.1143)
		(layer "In2.Cu")
		(net "P3E_CPU0_PE1_SS_C_TXN<2>")
	)
	(segment
		(start 407.77414 -11.463274)
		(end 405.15667 -12.019788)
		(width 0.1143)
		(layer "In2.Cu")
		(net "P3E_CPU0_PE1_SS_C_TXN<2>")
	)
	(segment
		(start 358.480614 -59.804808)
		(end 358.441498 -60.007246)
		(width 0.1143)
		(layer "In2.Cu")
		(net "P3E_CPU0_PE1_SS_C_TXN<2>")
	)
	(segment
		(start 388.873238 -11.89228)
		(end 378.872242 -14.017752)
		(width 0.1143)
		(layer "In2.Cu")
		(net "P3E_CPU0_PE1_SS_C_TXN<2>")
	)
	(segment
		(start 348.358968 -74.464672)
		(end 346.79255 -75.442318)
		(width 0.1143)
		(layer "In2.Cu")
		(net "P3E_CPU0_PE1_SS_C_TXN<2>")
	)
	(segment
		(start 346.79255 -75.442318)
		(end 346.739718 -75.669648)
		(width 0.1143)
		(layer "In2.Cu")
		(net "P3E_CPU0_PE1_SS_C_TXN<2>")
	)
	(segment
		(start 358.478582 -52.819046)
		(end 359.331514 -56.983122)
		(width 0.1143)
		(layer "In2.Cu")
		(net "P3E_CPU0_PE1_SS_C_TXN<2>")
	)
	(segment
		(start 376.993912 -13.619226)
		(end 371.040406 -15.719298)
		(width 0.1143)
		(layer "In2.Cu")
		(net "P3E_CPU0_PE1_SS_C_TXN<2>")
	)
	(segment
		(start 366.815624 -18.743168)
		(end 363.22254 -35.65144)
		(width 0.1143)
		(layer "In2.Cu")
		(net "P3E_CPU0_PE1_SS_C_TXN<2>")
	)
	(segment
		(start 346.147136 -76.40701)
		(end 346.459556 -76.40701)
		(width 0.1143)
		(layer "In2.Cu")
		(net "P3E_CPU0_PE1_SS_C_TXN<2>")
	)
	(segment
		(start 391.490454 -12.44854)
		(end 388.873238 -11.89228)
		(width 0.1143)
		(layer "In2.Cu")
		(net "P3E_CPU0_PE1_SS_C_TXN<2>")
	)
	(segment
		(start 363.22254 -35.65144)
		(end 362.490766 -36.74999)
		(width 0.1143)
		(layer "In2.Cu")
		(net "P3E_CPU0_PE1_SS_C_TXN<2>")
	)
	(segment
		(start 405.15667 -12.019788)
		(end 403.448012 -11.656568)
		(width 0.1143)
		(layer "In2.Cu")
		(net "P3E_CPU0_PE1_SS_C_TXN<2>")
	)
	(segment
		(start 357.154734 -61.951362)
		(end 355.404166 -63.226696)
		(width 0.1143)
		(layer "In2.Cu")
		(net "P3E_CPU0_PE1_SS_C_TXN<2>")
	)
	(segment
		(start 360.743246 -45.49521)
		(end 359.604818 -47.182786)
		(width 0.1143)
		(layer "In2.Cu")
		(net "P3E_CPU0_PE1_SS_C_TXN<2>")
	)
	(segment
		(start 417.426902 -11.434826)
		(end 412.531052 -12.473686)
		(width 0.1143)
		(layer "In2.Cu")
		(net "P3E_CPU0_PE1_SS_C_TXN<2>")
	)
	(segment
		(start 401.511516 -11.738864)
		(end 398.676114 -12.341098)
		(width 0.1143)
		(layer "In2.Cu")
		(net "P3E_CPU0_PE1_SS_C_TXN<2>")
	)
	(segment
		(start 371.040406 -15.719298)
		(end 366.815624 -18.743168)
		(width 0.1143)
		(layer "In2.Cu")
		(net "P3E_CPU0_PE1_SS_C_TXN<2>")
	)
	(segment
		(start 358.441498 -60.007246)
		(end 357.154734 -61.951362)
		(width 0.1143)
		(layer "In2.Cu")
		(net "P3E_CPU0_PE1_SS_C_TXN<2>")
	)
	(arc
		(start 345.914726 -76.1746)
		(mid 345.982797 -76.338939)
		(end 346.147136 -76.40701)
		(width 0.1143)
		(layer "In2.Cu")
		(net "P3E_CPU0_PE1_SS_C_TXN<2>")
	)
	(segment
		(start 415.499042 -10.124948)
		(end 415.3662 -9.992106)
		(width 0.1143)
		(layer "F.Cu")
		(net "P3E_CPU0_PE1_SS_C_TXN<1>")
	)
	(segment
		(start 415.673286 -8.608568)
		(end 415.673286 -7.789672)
		(width 0.1143)
		(layer "F.Cu")
		(net "P3E_CPU0_PE1_SS_C_TXN<1>")
	)
	(segment
		(start 415.3662 -9.992106)
		(end 415.3662 -8.915654)
		(width 0.1143)
		(layer "F.Cu")
		(net "P3E_CPU0_PE1_SS_C_TXN<1>")
	)
	(segment
		(start 415.3662 -8.915654)
		(end 415.673286 -8.608568)
		(width 0.1143)
		(layer "F.Cu")
		(net "P3E_CPU0_PE1_SS_C_TXN<1>")
	)
	(segment
		(start 415.899092 -10.124948)
		(end 415.499042 -10.124948)
		(width 0.1143)
		(layer "F.Cu")
		(net "P3E_CPU0_PE1_SS_C_TXN<1>")
	)
	(via
		(at 343.832688 -76.09967)
		(size 0.508)
		(drill 0.254)
		(layers "F.Cu" "B.Cu")
		(net "P3E_CPU0_PE1_SS_C_TXN<1>")
	)
	(via
		(at 415.899092 -10.124948)
		(size 0.508)
		(drill 0.254)
		(layers "F.Cu" "B.Cu")
		(net "P3E_CPU0_PE1_SS_C_TXN<1>")
	)
	(segment
		(start 343.832688 -76.365862)
		(end 343.393014 -76.805536)
		(width 0.1143)
		(layer "B.Cu")
		(net "P3E_CPU0_PE1_SS_C_TXN<1>")
	)
	(segment
		(start 343.832688 -76.09967)
		(end 343.832688 -76.365862)
		(width 0.1143)
		(layer "B.Cu")
		(net "P3E_CPU0_PE1_SS_C_TXN<1>")
	)
	(segment
		(start 343.393014 -76.805536)
		(end 343.063068 -76.805536)
		(width 0.1143)
		(layer "B.Cu")
		(net "P3E_CPU0_PE1_SS_C_TXN<1>")
	)
	(segment
		(start 401.497292 -11.079734)
		(end 398.676622 -11.678666)
		(width 0.1143)
		(layer "In2.Cu")
		(net "P3E_CPU0_PE1_SS_C_TXN<1>")
	)
	(segment
		(start 343.520268 -76.09967)
		(end 343.832688 -76.09967)
		(width 0.1143)
		(layer "In2.Cu")
		(net "P3E_CPU0_PE1_SS_C_TXN<1>")
	)
	(segment
		(start 415.505646 -10.124948)
		(end 415.391346 -10.239248)
		(width 0.1143)
		(layer "In2.Cu")
		(net "P3E_CPU0_PE1_SS_C_TXN<1>")
	)
	(segment
		(start 395.359382 -10.974324)
		(end 391.489692 -11.796776)
		(width 0.1143)
		(layer "In2.Cu")
		(net "P3E_CPU0_PE1_SS_C_TXN<1>")
	)
	(segment
		(start 366.192308 -18.405602)
		(end 362.566458 -35.462972)
		(width 0.1143)
		(layer "In2.Cu")
		(net "P3E_CPU0_PE1_SS_C_TXN<1>")
	)
	(segment
		(start 362.566458 -35.462972)
		(end 361.895136 -36.46932)
		(width 0.1143)
		(layer "In2.Cu")
		(net "P3E_CPU0_PE1_SS_C_TXN<1>")
	)
	(segment
		(start 358.659684 -56.92775)
		(end 357.602536 -59.859164)
		(width 0.1143)
		(layer "In2.Cu")
		(net "P3E_CPU0_PE1_SS_C_TXN<1>")
	)
	(segment
		(start 356.582218 -61.476382)
		(end 354.859336 -62.733936)
		(width 0.1143)
		(layer "In2.Cu")
		(net "P3E_CPU0_PE1_SS_C_TXN<1>")
	)
	(segment
		(start 355.946456 -53.323744)
		(end 358.245156 -54.85384)
		(width 0.1143)
		(layer "In2.Cu")
		(net "P3E_CPU0_PE1_SS_C_TXN<1>")
	)
	(segment
		(start 370.742972 -15.148052)
		(end 366.192308 -18.405602)
		(width 0.1143)
		(layer "In2.Cu")
		(net "P3E_CPU0_PE1_SS_C_TXN<1>")
	)
	(segment
		(start 415.391346 -10.239248)
		(end 415.391346 -10.884662)
		(width 0.1143)
		(layer "In2.Cu")
		(net "P3E_CPU0_PE1_SS_C_TXN<1>")
	)
	(segment
		(start 355.808026 -52.631086)
		(end 355.946456 -53.323744)
		(width 0.1143)
		(layer "In2.Cu")
		(net "P3E_CPU0_PE1_SS_C_TXN<1>")
	)
	(segment
		(start 343.729564 -75.170284)
		(end 343.287858 -75.672442)
		(width 0.1143)
		(layer "In2.Cu")
		(net "P3E_CPU0_PE1_SS_C_TXN<1>")
	)
	(segment
		(start 407.810716 -10.79373)
		(end 405.15667 -11.35761)
		(width 0.1143)
		(layer "In2.Cu")
		(net "P3E_CPU0_PE1_SS_C_TXN<1>")
	)
	(segment
		(start 358.245156 -54.85384)
		(end 358.659684 -56.92775)
		(width 0.1143)
		(layer "In2.Cu")
		(net "P3E_CPU0_PE1_SS_C_TXN<1>")
	)
	(segment
		(start 357.602536 -59.859164)
		(end 356.582218 -61.476382)
		(width 0.1143)
		(layer "In2.Cu")
		(net "P3E_CPU0_PE1_SS_C_TXN<1>")
	)
	(segment
		(start 348.465902 -72.671178)
		(end 343.729564 -75.170284)
		(width 0.1143)
		(layer "In2.Cu")
		(net "P3E_CPU0_PE1_SS_C_TXN<1>")
	)
	(segment
		(start 343.287858 -75.672442)
		(end 343.287858 -75.86726)
		(width 0.1143)
		(layer "In2.Cu")
		(net "P3E_CPU0_PE1_SS_C_TXN<1>")
	)
	(segment
		(start 391.489692 -11.796776)
		(end 388.878826 -11.241786)
		(width 0.1143)
		(layer "In2.Cu")
		(net "P3E_CPU0_PE1_SS_C_TXN<1>")
	)
	(segment
		(start 402.199856 -11.228832)
		(end 401.497292 -11.079734)
		(width 0.1143)
		(layer "In2.Cu")
		(net "P3E_CPU0_PE1_SS_C_TXN<1>")
	)
	(segment
		(start 361.895136 -36.46932)
		(end 360.167682 -45.113448)
		(width 0.1143)
		(layer "In2.Cu")
		(net "P3E_CPU0_PE1_SS_C_TXN<1>")
	)
	(segment
		(start 403.375622 -10.978896)
		(end 402.199856 -11.228832)
		(width 0.1143)
		(layer "In2.Cu")
		(net "P3E_CPU0_PE1_SS_C_TXN<1>")
	)
	(segment
		(start 378.879862 -13.366496)
		(end 376.953526 -12.95781)
		(width 0.1143)
		(layer "In2.Cu")
		(net "P3E_CPU0_PE1_SS_C_TXN<1>")
	)
	(segment
		(start 415.899092 -10.124948)
		(end 415.505646 -10.124948)
		(width 0.1143)
		(layer "In2.Cu")
		(net "P3E_CPU0_PE1_SS_C_TXN<1>")
	)
	(segment
		(start 414.970976 -11.305032)
		(end 412.592012 -11.810238)
		(width 0.1143)
		(layer "In2.Cu")
		(net "P3E_CPU0_PE1_SS_C_TXN<1>")
	)
	(segment
		(start 356.075742 -51.291236)
		(end 355.808026 -52.631086)
		(width 0.1143)
		(layer "In2.Cu")
		(net "P3E_CPU0_PE1_SS_C_TXN<1>")
	)
	(segment
		(start 412.592012 -11.810238)
		(end 407.810716 -10.79373)
		(width 0.1143)
		(layer "In2.Cu")
		(net "P3E_CPU0_PE1_SS_C_TXN<1>")
	)
	(segment
		(start 354.859336 -62.733936)
		(end 352.776282 -68.061078)
		(width 0.1143)
		(layer "In2.Cu")
		(net "P3E_CPU0_PE1_SS_C_TXN<1>")
	)
	(segment
		(start 398.676622 -11.678666)
		(end 395.359382 -10.974324)
		(width 0.1143)
		(layer "In2.Cu")
		(net "P3E_CPU0_PE1_SS_C_TXN<1>")
	)
	(segment
		(start 352.776282 -68.061078)
		(end 351.893124 -69.78904)
		(width 0.1143)
		(layer "In2.Cu")
		(net "P3E_CPU0_PE1_SS_C_TXN<1>")
	)
	(segment
		(start 360.157014 -45.166788)
		(end 356.075742 -51.291236)
		(width 0.1143)
		(layer "In2.Cu")
		(net "P3E_CPU0_PE1_SS_C_TXN<1>")
	)
	(segment
		(start 349.399098 -71.028306)
		(end 348.465902 -72.671178)
		(width 0.1143)
		(layer "In2.Cu")
		(net "P3E_CPU0_PE1_SS_C_TXN<1>")
	)
	(segment
		(start 405.15667 -11.35761)
		(end 403.375622 -10.978896)
		(width 0.1143)
		(layer "In2.Cu")
		(net "P3E_CPU0_PE1_SS_C_TXN<1>")
	)
	(segment
		(start 388.878826 -11.241786)
		(end 378.879862 -13.366496)
		(width 0.1143)
		(layer "In2.Cu")
		(net "P3E_CPU0_PE1_SS_C_TXN<1>")
	)
	(segment
		(start 360.167682 -45.113448)
		(end 360.157014 -45.166788)
		(width 0.1143)
		(layer "In2.Cu")
		(net "P3E_CPU0_PE1_SS_C_TXN<1>")
	)
	(segment
		(start 376.953526 -12.95781)
		(end 370.742972 -15.148052)
		(width 0.1143)
		(layer "In2.Cu")
		(net "P3E_CPU0_PE1_SS_C_TXN<1>")
	)
	(segment
		(start 351.893124 -69.78904)
		(end 349.399098 -71.028306)
		(width 0.1143)
		(layer "In2.Cu")
		(net "P3E_CPU0_PE1_SS_C_TXN<1>")
	)
	(segment
		(start 415.391346 -10.884662)
		(end 414.970976 -11.305032)
		(width 0.1143)
		(layer "In2.Cu")
		(net "P3E_CPU0_PE1_SS_C_TXN<1>")
	)
	(arc
		(start 343.287858 -75.86726)
		(mid 343.355929 -76.031599)
		(end 343.520268 -76.09967)
		(width 0.1143)
		(layer "In2.Cu")
		(net "P3E_CPU0_PE1_SS_C_TXN<1>")
	)
	(segment
		(start 412.90748 -10.047986)
		(end 412.90748 -8.884666)
		(width 0.1143)
		(layer "F.Cu")
		(net "P3E_CPU0_PE1_SS_C_TXN<0>")
	)
	(segment
		(start 412.90748 -8.884666)
		(end 413.272986 -8.51916)
		(width 0.1143)
		(layer "F.Cu")
		(net "P3E_CPU0_PE1_SS_C_TXN<0>")
	)
	(segment
		(start 413.272986 -8.51916)
		(end 413.272986 -7.789672)
		(width 0.1143)
		(layer "F.Cu")
		(net "P3E_CPU0_PE1_SS_C_TXN<0>")
	)
	(segment
		(start 413.00273 -10.143236)
		(end 412.90748 -10.047986)
		(width 0.1143)
		(layer "F.Cu")
		(net "P3E_CPU0_PE1_SS_C_TXN<0>")
	)
	(segment
		(start 413.43961 -10.143236)
		(end 413.00273 -10.143236)
		(width 0.1143)
		(layer "F.Cu")
		(net "P3E_CPU0_PE1_SS_C_TXN<0>")
	)
	(via
		(at 340.80196 -76.515722)
		(size 0.508)
		(drill 0.254)
		(layers "F.Cu" "B.Cu")
		(net "P3E_CPU0_PE1_SS_C_TXN<0>")
	)
	(via
		(at 413.43961 -10.143236)
		(size 0.508)
		(drill 0.254)
		(layers "F.Cu" "B.Cu")
		(net "P3E_CPU0_PE1_SS_C_TXN<0>")
	)
	(segment
		(start 340.512146 -76.805536)
		(end 340.80196 -76.515722)
		(width 0.1143)
		(layer "B.Cu")
		(net "P3E_CPU0_PE1_SS_C_TXN<0>")
	)
	(segment
		(start 340.16696 -76.805536)
		(end 340.512146 -76.805536)
		(width 0.1143)
		(layer "B.Cu")
		(net "P3E_CPU0_PE1_SS_C_TXN<0>")
	)
	(segment
		(start 361.970066 -35.200336)
		(end 361.29468 -36.213288)
		(width 0.1143)
		(layer "In2.Cu")
		(net "P3E_CPU0_PE1_SS_C_TXN<0>")
	)
	(segment
		(start 402.1963 -10.561828)
		(end 401.507198 -10.415524)
		(width 0.1143)
		(layer "In2.Cu")
		(net "P3E_CPU0_PE1_SS_C_TXN<0>")
	)
	(segment
		(start 357.683816 -55.360824)
		(end 357.991664 -56.903366)
		(width 0.1143)
		(layer "In2.Cu")
		(net "P3E_CPU0_PE1_SS_C_TXN<0>")
	)
	(segment
		(start 359.560622 -44.889674)
		(end 355.440742 -51.037236)
		(width 0.1143)
		(layer "In2.Cu")
		(net "P3E_CPU0_PE1_SS_C_TXN<0>")
	)
	(segment
		(start 357.991664 -56.903366)
		(end 357.11384 -59.337702)
		(width 0.1143)
		(layer "In2.Cu")
		(net "P3E_CPU0_PE1_SS_C_TXN<0>")
	)
	(segment
		(start 395.38402 -10.31748)
		(end 391.489692 -11.145012)
		(width 0.1143)
		(layer "In2.Cu")
		(net "P3E_CPU0_PE1_SS_C_TXN<0>")
	)
	(segment
		(start 401.507198 -10.415524)
		(end 398.676876 -11.016488)
		(width 0.1143)
		(layer "In2.Cu")
		(net "P3E_CPU0_PE1_SS_C_TXN<0>")
	)
	(segment
		(start 345.838526 -73.105264)
		(end 340.518242 -75.31354)
		(width 0.1143)
		(layer "In2.Cu")
		(net "P3E_CPU0_PE1_SS_C_TXN<0>")
	)
	(segment
		(start 355.12756 -52.6034)
		(end 355.370892 -53.820822)
		(width 0.1143)
		(layer "In2.Cu")
		(net "P3E_CPU0_PE1_SS_C_TXN<0>")
	)
	(segment
		(start 378.863098 -12.69873)
		(end 376.93219 -12.288774)
		(width 0.1143)
		(layer "In2.Cu")
		(net "P3E_CPU0_PE1_SS_C_TXN<0>")
	)
	(segment
		(start 346.006674 -72.381618)
		(end 345.838526 -73.105264)
		(width 0.1143)
		(layer "In2.Cu")
		(net "P3E_CPU0_PE1_SS_C_TXN<0>")
	)
	(segment
		(start 355.440742 -51.037236)
		(end 355.12756 -52.6034)
		(width 0.1143)
		(layer "In2.Cu")
		(net "P3E_CPU0_PE1_SS_C_TXN<0>")
	)
	(segment
		(start 340.431374 -76.515722)
		(end 340.80196 -76.515722)
		(width 0.1143)
		(layer "In2.Cu")
		(net "P3E_CPU0_PE1_SS_C_TXN<0>")
	)
	(segment
		(start 349.9358 -69.60743)
		(end 346.006674 -72.381618)
		(width 0.1143)
		(layer "In2.Cu")
		(net "P3E_CPU0_PE1_SS_C_TXN<0>")
	)
	(segment
		(start 412.591758 -11.0617)
		(end 412.1404 -11.0617)
		(width 0.1143)
		(layer "In2.Cu")
		(net "P3E_CPU0_PE1_SS_C_TXN<0>")
	)
	(segment
		(start 405.15667 -10.695432)
		(end 403.362414 -10.313924)
		(width 0.1143)
		(layer "In2.Cu")
		(net "P3E_CPU0_PE1_SS_C_TXN<0>")
	)
	(segment
		(start 340.518242 -75.31354)
		(end 340.29904 -75.795632)
		(width 0.1143)
		(layer "In2.Cu")
		(net "P3E_CPU0_PE1_SS_C_TXN<0>")
	)
	(segment
		(start 376.93219 -12.288774)
		(end 370.445284 -14.576806)
		(width 0.1143)
		(layer "In2.Cu")
		(net "P3E_CPU0_PE1_SS_C_TXN<0>")
	)
	(segment
		(start 413.43961 -10.143236)
		(end 413.054546 -10.140442)
		(width 0.1143)
		(layer "In2.Cu")
		(net "P3E_CPU0_PE1_SS_C_TXN<0>")
	)
	(segment
		(start 412.937706 -10.716006)
		(end 412.591758 -11.0617)
		(width 0.1143)
		(layer "In2.Cu")
		(net "P3E_CPU0_PE1_SS_C_TXN<0>")
	)
	(segment
		(start 388.832598 -10.580116)
		(end 378.863098 -12.69873)
		(width 0.1143)
		(layer "In2.Cu")
		(net "P3E_CPU0_PE1_SS_C_TXN<0>")
	)
	(segment
		(start 391.489692 -11.145012)
		(end 388.832598 -10.580116)
		(width 0.1143)
		(layer "In2.Cu")
		(net "P3E_CPU0_PE1_SS_C_TXN<0>")
	)
	(segment
		(start 355.370892 -53.820822)
		(end 357.683816 -55.360824)
		(width 0.1143)
		(layer "In2.Cu")
		(net "P3E_CPU0_PE1_SS_C_TXN<0>")
	)
	(segment
		(start 340.29904 -75.795632)
		(end 340.29904 -76.387706)
		(width 0.1143)
		(layer "In2.Cu")
		(net "P3E_CPU0_PE1_SS_C_TXN<0>")
	)
	(segment
		(start 407.78557 -10.136632)
		(end 405.15667 -10.695432)
		(width 0.1143)
		(layer "In2.Cu")
		(net "P3E_CPU0_PE1_SS_C_TXN<0>")
	)
	(segment
		(start 412.1404 -11.0617)
		(end 407.78557 -10.136632)
		(width 0.1143)
		(layer "In2.Cu")
		(net "P3E_CPU0_PE1_SS_C_TXN<0>")
	)
	(segment
		(start 361.29468 -36.213288)
		(end 359.560622 -44.889674)
		(width 0.1143)
		(layer "In2.Cu")
		(net "P3E_CPU0_PE1_SS_C_TXN<0>")
	)
	(segment
		(start 365.620046 -18.031206)
		(end 361.970066 -35.200336)
		(width 0.1143)
		(layer "In2.Cu")
		(net "P3E_CPU0_PE1_SS_C_TXN<0>")
	)
	(segment
		(start 356.058724 -60.974732)
		(end 354.327206 -62.23889)
		(width 0.1143)
		(layer "In2.Cu")
		(net "P3E_CPU0_PE1_SS_C_TXN<0>")
	)
	(segment
		(start 357.11384 -59.337702)
		(end 356.058724 -60.974732)
		(width 0.1143)
		(layer "In2.Cu")
		(net "P3E_CPU0_PE1_SS_C_TXN<0>")
	)
	(segment
		(start 403.362414 -10.313924)
		(end 402.1963 -10.561828)
		(width 0.1143)
		(layer "In2.Cu")
		(net "P3E_CPU0_PE1_SS_C_TXN<0>")
	)
	(segment
		(start 413.054546 -10.140442)
		(end 412.939484 -10.25398)
		(width 0.1143)
		(layer "In2.Cu")
		(net "P3E_CPU0_PE1_SS_C_TXN<0>")
	)
	(segment
		(start 370.445284 -14.576806)
		(end 365.620046 -18.031206)
		(width 0.1143)
		(layer "In2.Cu")
		(net "P3E_CPU0_PE1_SS_C_TXN<0>")
	)
	(segment
		(start 398.676876 -11.016488)
		(end 395.38402 -10.31748)
		(width 0.1143)
		(layer "In2.Cu")
		(net "P3E_CPU0_PE1_SS_C_TXN<0>")
	)
	(segment
		(start 354.327206 -62.23889)
		(end 352.059494 -68.04025)
		(width 0.1143)
		(layer "In2.Cu")
		(net "P3E_CPU0_PE1_SS_C_TXN<0>")
	)
	(segment
		(start 412.939484 -10.25398)
		(end 412.937706 -10.716006)
		(width 0.1143)
		(layer "In2.Cu")
		(net "P3E_CPU0_PE1_SS_C_TXN<0>")
	)
	(segment
		(start 351.549208 -69.03847)
		(end 349.9358 -69.60743)
		(width 0.1143)
		(layer "In2.Cu")
		(net "P3E_CPU0_PE1_SS_C_TXN<0>")
	)
	(segment
		(start 352.059494 -68.04025)
		(end 351.549208 -69.03847)
		(width 0.1143)
		(layer "In2.Cu")
		(net "P3E_CPU0_PE1_SS_C_TXN<0>")
	)
	(arc
		(start 340.29904 -76.387706)
		(mid 340.311829 -76.44018)
		(end 340.3473 -76.480924)
		(width 0.1143)
		(layer "In2.Cu")
		(net "P3E_CPU0_PE1_SS_C_TXN<0>")
	)
	(arc
		(start 340.3473 -76.480924)
		(mid 340.385873 -76.506698)
		(end 340.431374 -76.515722)
		(width 0.1143)
		(layer "In2.Cu")
		(net "P3E_CPU0_PE1_SS_C_TXN<0>")
	)
	(segment
		(start 235.325158 -68.963286)
		(end 234.753658 -68.963286)
		(width 0.10795)
		(layer "F.Cu")
		(net "TP_CPU0_RSVD_255")
	)
	(via
		(at 234.753658 -68.963286)
		(size 0.508)
		(drill 0.254)
		(layers "F.Cu" "B.Cu")
		(net "TP_CPU0_RSVD_255")
	)
	(segment
		(start 378.257816 -93.746828)
		(end 378.257816 -93.199966)
		(width 0.0889)
		(layer "F.Cu")
		(net "SPI_PCH_TPM_CS_N")
	)
	(segment
		(start 405.5364 -62.408054)
		(end 406.324054 -61.6204)
		(width 0.10795)
		(layer "F.Cu")
		(net "SPI_PCH_TPM_CS_N")
	)
	(segment
		(start 406.324054 -61.6204)
		(end 406.6286 -61.6204)
		(width 0.10795)
		(layer "F.Cu")
		(net "SPI_PCH_TPM_CS_N")
	)
	(segment
		(start 378.484892 -94.400116)
		(end 378.173742 -94.088966)
		(width 0.0889)
		(layer "F.Cu")
		(net "SPI_PCH_TPM_CS_N")
	)
	(segment
		(start 405.5364 -62.5729)
		(end 405.5364 -62.408054)
		(width 0.10795)
		(layer "F.Cu")
		(net "SPI_PCH_TPM_CS_N")
	)
	(segment
		(start 378.484892 -94.790006)
		(end 378.484892 -94.400116)
		(width 0.0889)
		(layer "F.Cu")
		(net "SPI_PCH_TPM_CS_N")
	)
	(segment
		(start 378.173742 -94.088966)
		(end 378.173742 -93.830902)
		(width 0.0889)
		(layer "F.Cu")
		(net "SPI_PCH_TPM_CS_N")
	)
	(segment
		(start 378.173742 -93.830902)
		(end 378.257816 -93.746828)
		(width 0.0889)
		(layer "F.Cu")
		(net "SPI_PCH_TPM_CS_N")
	)
	(segment
		(start 378.257816 -93.199966)
		(end 378.360686 -93.097096)
		(width 0.0889)
		(layer "F.Cu")
		(net "SPI_PCH_TPM_CS_N")
	)
	(segment
		(start 378.360686 -93.097096)
		(end 378.460254 -92.997528)
		(width 0.10795)
		(layer "F.Cu")
		(net "SPI_PCH_TPM_CS_N")
	)
	(segment
		(start 378.460254 -92.580206)
		(end 378.073666 -92.193618)
		(width 0.10795)
		(layer "F.Cu")
		(net "SPI_PCH_TPM_CS_N")
	)
	(segment
		(start 378.460254 -92.997528)
		(end 378.460254 -92.580206)
		(width 0.10795)
		(layer "F.Cu")
		(net "SPI_PCH_TPM_CS_N")
	)
	(via
		(at 404.6855 -62.370462)
		(size 0.6604)
		(drill 0.3302)
		(layers "F.Cu" "B.Cu")
		(net "SPI_PCH_TPM_CS_N")
	)
	(via
		(at 405.5364 -62.5729)
		(size 0.508)
		(drill 0.254)
		(layers "F.Cu" "B.Cu")
		(net "SPI_PCH_TPM_CS_N")
	)
	(via
		(at 386.184902 -60.832492)
		(size 0.508)
		(drill 0.254)
		(layers "F.Cu" "B.Cu")
		(net "SPI_PCH_TPM_CS_N")
	)
	(via
		(at 378.073666 -92.193618)
		(size 0.508)
		(drill 0.254)
		(layers "F.Cu" "B.Cu")
		(net "SPI_PCH_TPM_CS_N")
	)
	(segment
		(start 405.333962 -62.370462)
		(end 405.5364 -62.5729)
		(width 0.10795)
		(layer "B.Cu")
		(net "SPI_PCH_TPM_CS_N")
	)
	(segment
		(start 404.6855 -62.370462)
		(end 405.333962 -62.370462)
		(width 0.10795)
		(layer "B.Cu")
		(net "SPI_PCH_TPM_CS_N")
	)
	(segment
		(start 378.766578 -90.545412)
		(end 377.961144 -89.739978)
		(width 0.089408)
		(layer "In2.Cu")
		(net "SPI_PCH_TPM_CS_N")
	)
	(segment
		(start 384.472688 -75.702668)
		(end 383.607056 -74.837036)
		(width 0.089408)
		(layer "In2.Cu")
		(net "SPI_PCH_TPM_CS_N")
	)
	(segment
		(start 378.766578 -91.500706)
		(end 378.766578 -90.545412)
		(width 0.089408)
		(layer "In2.Cu")
		(net "SPI_PCH_TPM_CS_N")
	)
	(segment
		(start 383.549906 -78.408784)
		(end 384.472688 -77.486002)
		(width 0.089408)
		(layer "In2.Cu")
		(net "SPI_PCH_TPM_CS_N")
	)
	(segment
		(start 385.863592 -62.884558)
		(end 386.302504 -62.445646)
		(width 0.089408)
		(layer "In2.Cu")
		(net "SPI_PCH_TPM_CS_N")
	)
	(segment
		(start 378.610368 -88.00592)
		(end 381.766826 -88.00592)
		(width 0.089408)
		(layer "In2.Cu")
		(net "SPI_PCH_TPM_CS_N")
	)
	(segment
		(start 377.961144 -89.739978)
		(end 377.961144 -88.655144)
		(width 0.089408)
		(layer "In2.Cu")
		(net "SPI_PCH_TPM_CS_N")
	)
	(segment
		(start 383.085848 -80.140302)
		(end 383.549906 -79.676244)
		(width 0.089408)
		(layer "In2.Cu")
		(net "SPI_PCH_TPM_CS_N")
	)
	(segment
		(start 382.83388 -84.89442)
		(end 382.83388 -82.730848)
		(width 0.089408)
		(layer "In2.Cu")
		(net "SPI_PCH_TPM_CS_N")
	)
	(segment
		(start 382.68656 -87.086186)
		(end 382.68656 -86.43366)
		(width 0.089408)
		(layer "In2.Cu")
		(net "SPI_PCH_TPM_CS_N")
	)
	(segment
		(start 384.472688 -77.486002)
		(end 384.472688 -75.702668)
		(width 0.089408)
		(layer "In2.Cu")
		(net "SPI_PCH_TPM_CS_N")
	)
	(segment
		(start 377.961144 -88.655144)
		(end 378.610368 -88.00592)
		(width 0.089408)
		(layer "In2.Cu")
		(net "SPI_PCH_TPM_CS_N")
	)
	(segment
		(start 382.68656 -86.43366)
		(end 382.31318 -86.06028)
		(width 0.089408)
		(layer "In2.Cu")
		(net "SPI_PCH_TPM_CS_N")
	)
	(segment
		(start 385.369816 -64.271144)
		(end 385.863592 -63.777368)
		(width 0.089408)
		(layer "In2.Cu")
		(net "SPI_PCH_TPM_CS_N")
	)
	(segment
		(start 382.31318 -86.06028)
		(end 382.31318 -85.41512)
		(width 0.089408)
		(layer "In2.Cu")
		(net "SPI_PCH_TPM_CS_N")
	)
	(segment
		(start 386.302504 -62.445646)
		(end 386.302504 -61.900816)
		(width 0.089408)
		(layer "In2.Cu")
		(net "SPI_PCH_TPM_CS_N")
	)
	(segment
		(start 383.607056 -72.45731)
		(end 383.399792 -72.250046)
		(width 0.089408)
		(layer "In2.Cu")
		(net "SPI_PCH_TPM_CS_N")
	)
	(segment
		(start 383.607056 -74.837036)
		(end 383.607056 -72.45731)
		(width 0.089408)
		(layer "In2.Cu")
		(net "SPI_PCH_TPM_CS_N")
	)
	(segment
		(start 385.369816 -68.862194)
		(end 385.369816 -64.271144)
		(width 0.089408)
		(layer "In2.Cu")
		(net "SPI_PCH_TPM_CS_N")
	)
	(segment
		(start 386.184902 -61.783214)
		(end 386.184902 -60.832492)
		(width 0.089408)
		(layer "In2.Cu")
		(net "SPI_PCH_TPM_CS_N")
	)
	(segment
		(start 378.073666 -92.193618)
		(end 378.766578 -91.500706)
		(width 0.089408)
		(layer "In2.Cu")
		(net "SPI_PCH_TPM_CS_N")
	)
	(segment
		(start 383.549906 -79.676244)
		(end 383.549906 -78.408784)
		(width 0.089408)
		(layer "In2.Cu")
		(net "SPI_PCH_TPM_CS_N")
	)
	(segment
		(start 381.766826 -88.00592)
		(end 382.68656 -87.086186)
		(width 0.089408)
		(layer "In2.Cu")
		(net "SPI_PCH_TPM_CS_N")
	)
	(segment
		(start 383.399792 -70.832218)
		(end 385.369816 -68.862194)
		(width 0.089408)
		(layer "In2.Cu")
		(net "SPI_PCH_TPM_CS_N")
	)
	(segment
		(start 382.31318 -85.41512)
		(end 382.83388 -84.89442)
		(width 0.089408)
		(layer "In2.Cu")
		(net "SPI_PCH_TPM_CS_N")
	)
	(segment
		(start 382.83388 -82.730848)
		(end 383.085848 -82.47888)
		(width 0.089408)
		(layer "In2.Cu")
		(net "SPI_PCH_TPM_CS_N")
	)
	(segment
		(start 386.302504 -61.900816)
		(end 386.184902 -61.783214)
		(width 0.089408)
		(layer "In2.Cu")
		(net "SPI_PCH_TPM_CS_N")
	)
	(segment
		(start 385.863592 -63.777368)
		(end 385.863592 -62.884558)
		(width 0.089408)
		(layer "In2.Cu")
		(net "SPI_PCH_TPM_CS_N")
	)
	(segment
		(start 383.399792 -72.250046)
		(end 383.399792 -70.832218)
		(width 0.089408)
		(layer "In2.Cu")
		(net "SPI_PCH_TPM_CS_N")
	)
	(segment
		(start 383.085848 -82.47888)
		(end 383.085848 -80.140302)
		(width 0.089408)
		(layer "In2.Cu")
		(net "SPI_PCH_TPM_CS_N")
	)
	(segment
		(start 398.63903 -61.263784)
		(end 394.333984 -61.263784)
		(width 0.089408)
		(layer "In4.Cu")
		(net "SPI_PCH_TPM_CS_N")
	)
	(segment
		(start 391.39749 -61.50102)
		(end 391.06983 -61.17336)
		(width 0.089408)
		(layer "In4.Cu")
		(net "SPI_PCH_TPM_CS_N")
	)
	(segment
		(start 394.333984 -61.263784)
		(end 393.897104 -60.826904)
		(width 0.089408)
		(layer "In4.Cu")
		(net "SPI_PCH_TPM_CS_N")
	)
	(segment
		(start 386.52577 -61.17336)
		(end 386.184902 -60.832492)
		(width 0.089408)
		(layer "In4.Cu")
		(net "SPI_PCH_TPM_CS_N")
	)
	(segment
		(start 392.73734 -60.80506)
		(end 392.04138 -61.50102)
		(width 0.089408)
		(layer "In4.Cu")
		(net "SPI_PCH_TPM_CS_N")
	)
	(segment
		(start 405.38146 -62.41796)
		(end 399.793206 -62.41796)
		(width 0.089408)
		(layer "In4.Cu")
		(net "SPI_PCH_TPM_CS_N")
	)
	(segment
		(start 393.897104 -60.826904)
		(end 393.86764 -60.826904)
		(width 0.089408)
		(layer "In4.Cu")
		(net "SPI_PCH_TPM_CS_N")
	)
	(segment
		(start 393.845796 -60.80506)
		(end 392.73734 -60.80506)
		(width 0.089408)
		(layer "In4.Cu")
		(net "SPI_PCH_TPM_CS_N")
	)
	(segment
		(start 405.5364 -62.5729)
		(end 405.38146 -62.41796)
		(width 0.089408)
		(layer "In4.Cu")
		(net "SPI_PCH_TPM_CS_N")
	)
	(segment
		(start 393.86764 -60.826904)
		(end 393.845796 -60.80506)
		(width 0.089408)
		(layer "In4.Cu")
		(net "SPI_PCH_TPM_CS_N")
	)
	(segment
		(start 392.04138 -61.50102)
		(end 391.39749 -61.50102)
		(width 0.089408)
		(layer "In4.Cu")
		(net "SPI_PCH_TPM_CS_N")
	)
	(segment
		(start 399.793206 -62.41796)
		(end 398.63903 -61.263784)
		(width 0.089408)
		(layer "In4.Cu")
		(net "SPI_PCH_TPM_CS_N")
	)
	(segment
		(start 391.06983 -61.17336)
		(end 386.52577 -61.17336)
		(width 0.089408)
		(layer "In4.Cu")
		(net "SPI_PCH_TPM_CS_N")
	)
	(segment
		(start 489.712 -122.45086)
		(end 489.86948 -122.60834)
		(width 0.10795)
		(layer "F.Cu")
		(net "PU_TMP421_1_A1")
	)
	(segment
		(start 488.6706 -122.45086)
		(end 489.712 -122.45086)
		(width 0.10795)
		(layer "F.Cu")
		(net "PU_TMP421_1_A1")
	)
	(via
		(at 489.493052 -121.938034)
		(size 0.6604)
		(drill 0.3302)
		(layers "F.Cu" "B.Cu")
		(net "PU_TMP421_1_A1")
	)
	(via
		(at 489.86948 -122.60834)
		(size 0.508)
		(drill 0.254)
		(layers "F.Cu" "B.Cu")
		(net "PU_TMP421_1_A1")
	)
	(segment
		(start 489.86948 -122.60834)
		(end 490.18444 -122.9233)
		(width 0.10795)
		(layer "B.Cu")
		(net "PU_TMP421_1_A1")
	)
	(segment
		(start 489.86948 -122.314462)
		(end 489.493052 -121.938034)
		(width 0.10795)
		(layer "B.Cu")
		(net "PU_TMP421_1_A1")
	)
	(segment
		(start 489.86948 -122.60834)
		(end 489.86948 -122.314462)
		(width 0.10795)
		(layer "B.Cu")
		(net "PU_TMP421_1_A1")
	)
	(segment
		(start 490.18444 -122.9233)
		(end 490.18444 -123.56592)
		(width 0.10795)
		(layer "B.Cu")
		(net "PU_TMP421_1_A1")
	)
	(segment
		(start 410.0195 -50.038)
		(end 410.0195 -53.213)
		(width 0.10795)
		(layer "F.Cu")
		(net "PU_AT24C64_A2")
	)
	(segment
		(start 410.6545 -53.848)
		(end 411.6832 -53.848)
		(width 0.10795)
		(layer "F.Cu")
		(net "PU_AT24C64_A2")
	)
	(segment
		(start 410.0195 -53.213)
		(end 410.6545 -53.848)
		(width 0.10795)
		(layer "F.Cu")
		(net "PU_AT24C64_A2")
	)
	(segment
		(start 419.506146 -26.128472)
		(end 419.506146 -26.918666)
		(width 0.10795)
		(layer "F.Cu")
		(net "IRQ_UV_DETECT_N")
	)
	(segment
		(start 421.8686 -21.269706)
		(end 422.081452 -21.482558)
		(width 0.10795)
		(layer "F.Cu")
		(net "IRQ_UV_DETECT_N")
	)
	(segment
		(start 422.081452 -22.893274)
		(end 421.226234 -23.748492)
		(width 0.10795)
		(layer "F.Cu")
		(net "IRQ_UV_DETECT_N")
	)
	(segment
		(start 421.8686 -19.155156)
		(end 421.8686 -21.269706)
		(width 0.10795)
		(layer "F.Cu")
		(net "IRQ_UV_DETECT_N")
	)
	(segment
		(start 390.774682 -119.3292)
		(end 391.20445 -119.528844)
		(width 0.10795)
		(layer "F.Cu")
		(net "IRQ_UV_DETECT_N")
	)
	(segment
		(start 420.98595 -24.329644)
		(end 419.505892 -25.809702)
		(width 0.10795)
		(layer "F.Cu")
		(net "IRQ_UV_DETECT_N")
	)
	(segment
		(start 419.505892 -25.809702)
		(end 419.505892 -26.128218)
		(width 0.10795)
		(layer "F.Cu")
		(net "IRQ_UV_DETECT_N")
	)
	(segment
		(start 390.70915 -119.29872)
		(end 390.774682 -119.3292)
		(width 0.10795)
		(layer "F.Cu")
		(net "IRQ_UV_DETECT_N")
	)
	(segment
		(start 420.98595 -23.988522)
		(end 420.98595 -24.329644)
		(width 0.10795)
		(layer "F.Cu")
		(net "IRQ_UV_DETECT_N")
	)
	(segment
		(start 422.081452 -21.482558)
		(end 422.081452 -22.893274)
		(width 0.10795)
		(layer "F.Cu")
		(net "IRQ_UV_DETECT_N")
	)
	(segment
		(start 421.4114 -18.697956)
		(end 421.8686 -19.155156)
		(width 0.10795)
		(layer "F.Cu")
		(net "IRQ_UV_DETECT_N")
	)
	(segment
		(start 414.655762 -90.474038)
		(end 414.655762 -88.823292)
		(width 0.10795)
		(layer "F.Cu")
		(net "IRQ_UV_DETECT_N")
	)
	(segment
		(start 419.505892 -26.128218)
		(end 419.506146 -26.128472)
		(width 0.10795)
		(layer "F.Cu")
		(net "IRQ_UV_DETECT_N")
	)
	(segment
		(start 419.506146 -26.918666)
		(end 419.090094 -27.334718)
		(width 0.10795)
		(layer "F.Cu")
		(net "IRQ_UV_DETECT_N")
	)
	(segment
		(start 414.123632 -90.831162)
		(end 414.298638 -90.831162)
		(width 0.10795)
		(layer "F.Cu")
		(net "IRQ_UV_DETECT_N")
	)
	(segment
		(start 414.298638 -90.831162)
		(end 414.655762 -90.474038)
		(width 0.10795)
		(layer "F.Cu")
		(net "IRQ_UV_DETECT_N")
	)
	(segment
		(start 421.22598 -23.748492)
		(end 420.98595 -23.988522)
		(width 0.10795)
		(layer "F.Cu")
		(net "IRQ_UV_DETECT_N")
	)
	(segment
		(start 421.226234 -23.748492)
		(end 421.22598 -23.748492)
		(width 0.10795)
		(layer "F.Cu")
		(net "IRQ_UV_DETECT_N")
	)
	(via
		(at 391.20445 -119.528844)
		(size 0.508)
		(drill 0.254)
		(layers "F.Cu" "B.Cu")
		(net "IRQ_UV_DETECT_N")
	)
	(via
		(at 414.123632 -90.831162)
		(size 0.508)
		(drill 0.254)
		(layers "F.Cu" "B.Cu")
		(net "IRQ_UV_DETECT_N")
	)
	(via
		(at 373.543322 -125.805946)
		(size 0.508)
		(drill 0.254)
		(layers "F.Cu" "B.Cu")
		(net "IRQ_UV_DETECT_N")
	)
	(via
		(at 421.4114 -18.697956)
		(size 0.508)
		(drill 0.254)
		(layers "F.Cu" "B.Cu")
		(net "IRQ_UV_DETECT_N")
	)
	(via
		(at 376.671332 -123.473972)
		(size 0.508)
		(drill 0.254)
		(layers "F.Cu" "B.Cu")
		(net "IRQ_UV_DETECT_N")
	)
	(via
		(at 346.09024 -117.723412)
		(size 0.508)
		(drill 0.254)
		(layers "F.Cu" "B.Cu")
		(net "IRQ_UV_DETECT_N")
	)
	(via
		(at 17.378172 -85.3821)
		(size 0.508)
		(drill 0.254)
		(layers "F.Cu" "B.Cu")
		(net "IRQ_UV_DETECT_N")
	)
	(via
		(at 477.212406 -54.270402)
		(size 0.508)
		(drill 0.254)
		(layers "F.Cu" "B.Cu")
		(net "IRQ_UV_DETECT_N")
	)
	(via
		(at 21.717 -86.614)
		(size 0.6604)
		(drill 0.3302)
		(layers "F.Cu" "B.Cu")
		(net "IRQ_UV_DETECT_N")
	)
	(segment
		(start 21.192998 -87.138002)
		(end 20.712176 -87.138002)
		(width 0.10795)
		(layer "B.Cu")
		(net "IRQ_UV_DETECT_N")
	)
	(segment
		(start 22.93112 -87.24138)
		(end 23.87854 -87.24138)
		(width 0.10795)
		(layer "B.Cu")
		(net "IRQ_UV_DETECT_N")
	)
	(segment
		(start 21.717 -86.614)
		(end 22.30374 -86.614)
		(width 0.10795)
		(layer "B.Cu")
		(net "IRQ_UV_DETECT_N")
	)
	(segment
		(start 15.5448 -85.8266)
		(end 15.5448 -86.1314)
		(width 0.10795)
		(layer "B.Cu")
		(net "IRQ_UV_DETECT_N")
	)
	(segment
		(start 21.717 -86.614)
		(end 21.192998 -87.138002)
		(width 0.10795)
		(layer "B.Cu")
		(net "IRQ_UV_DETECT_N")
	)
	(segment
		(start 16.6497 -85.5599)
		(end 15.8115 -85.5599)
		(width 0.10795)
		(layer "B.Cu")
		(net "IRQ_UV_DETECT_N")
	)
	(segment
		(start 15.8115 -85.5599)
		(end 15.5448 -85.8266)
		(width 0.10795)
		(layer "B.Cu")
		(net "IRQ_UV_DETECT_N")
	)
	(segment
		(start 22.30374 -86.614)
		(end 22.93112 -87.24138)
		(width 0.10795)
		(layer "B.Cu")
		(net "IRQ_UV_DETECT_N")
	)
	(segment
		(start 18.956274 -85.3821)
		(end 17.378172 -85.3821)
		(width 0.10795)
		(layer "B.Cu")
		(net "IRQ_UV_DETECT_N")
	)
	(segment
		(start 15.5194 -86.1568)
		(end 15.5194 -87.1601)
		(width 0.10795)
		(layer "B.Cu")
		(net "IRQ_UV_DETECT_N")
	)
	(segment
		(start 17.378172 -85.3821)
		(end 16.8275 -85.3821)
		(width 0.10795)
		(layer "B.Cu")
		(net "IRQ_UV_DETECT_N")
	)
	(segment
		(start 16.8275 -85.3821)
		(end 16.6497 -85.5599)
		(width 0.10795)
		(layer "B.Cu")
		(net "IRQ_UV_DETECT_N")
	)
	(segment
		(start 20.712176 -87.138002)
		(end 18.956274 -85.3821)
		(width 0.10795)
		(layer "B.Cu")
		(net "IRQ_UV_DETECT_N")
	)
	(segment
		(start 15.5448 -86.1314)
		(end 15.5194 -86.1568)
		(width 0.10795)
		(layer "B.Cu")
		(net "IRQ_UV_DETECT_N")
	)
	(segment
		(start 17.378172 -84.455)
		(end 17.378172 -85.3821)
		(width 0.10795)
		(layer "B.Cu")
		(net "IRQ_UV_DETECT_N")
	)
	(segment
		(start 418.029898 -64.788288)
		(end 418.029898 -63.677038)
		(width 0.089408)
		(layer "In2.Cu")
		(net "IRQ_UV_DETECT_N")
	)
	(segment
		(start 418.029644 -70.92315)
		(end 418.029644 -64.788542)
		(width 0.089408)
		(layer "In2.Cu")
		(net "IRQ_UV_DETECT_N")
	)
	(segment
		(start 467.118954 -57.6072)
		(end 467.119208 -57.607454)
		(width 0.089408)
		(layer "In2.Cu")
		(net "IRQ_UV_DETECT_N")
	)
	(segment
		(start 467.119208 -57.607454)
		(end 468.59952 -57.607454)
		(width 0.089408)
		(layer "In2.Cu")
		(net "IRQ_UV_DETECT_N")
	)
	(segment
		(start 466.802216 -57.607454)
		(end 466.802724 -57.606946)
		(width 0.089408)
		(layer "In2.Cu")
		(net "IRQ_UV_DETECT_N")
	)
	(segment
		(start 436.060596 -59.544712)
		(end 436.809388 -59.544712)
		(width 0.089408)
		(layer "In2.Cu")
		(net "IRQ_UV_DETECT_N")
	)
	(segment
		(start 414.123632 -90.831162)
		(end 414.55594 -90.398854)
		(width 0.089408)
		(layer "In2.Cu")
		(net "IRQ_UV_DETECT_N")
	)
	(segment
		(start 468.59952 -57.607454)
		(end 468.986108 -57.220866)
		(width 0.089408)
		(layer "In2.Cu")
		(net "IRQ_UV_DETECT_N")
	)
	(segment
		(start 472.837002 -55.092346)
		(end 474.242638 -55.092346)
		(width 0.089408)
		(layer "In2.Cu")
		(net "IRQ_UV_DETECT_N")
	)
	(segment
		(start 414.55594 -90.398854)
		(end 414.55594 -87.74684)
		(width 0.089408)
		(layer "In2.Cu")
		(net "IRQ_UV_DETECT_N")
	)
	(segment
		(start 428.44847 -58.472832)
		(end 428.783242 -58.807604)
		(width 0.089408)
		(layer "In2.Cu")
		(net "IRQ_UV_DETECT_N")
	)
	(segment
		(start 418.029644 -64.788542)
		(end 418.029898 -64.788288)
		(width 0.089408)
		(layer "In2.Cu")
		(net "IRQ_UV_DETECT_N")
	)
	(segment
		(start 417.797742 -75.728322)
		(end 417.797742 -71.155052)
		(width 0.089408)
		(layer "In2.Cu")
		(net "IRQ_UV_DETECT_N")
	)
	(segment
		(start 437.090566 -60.437014)
		(end 437.521096 -60.867544)
		(width 0.089408)
		(layer "In2.Cu")
		(net "IRQ_UV_DETECT_N")
	)
	(segment
		(start 466.802724 -57.606946)
		(end 466.960712 -57.606946)
		(width 0.089408)
		(layer "In2.Cu")
		(net "IRQ_UV_DETECT_N")
	)
	(segment
		(start 466.960966 -57.6072)
		(end 467.118954 -57.6072)
		(width 0.089408)
		(layer "In2.Cu")
		(net "IRQ_UV_DETECT_N")
	)
	(segment
		(start 436.809388 -59.544712)
		(end 437.090566 -59.82589)
		(width 0.089408)
		(layer "In2.Cu")
		(net "IRQ_UV_DETECT_N")
	)
	(segment
		(start 414.255458 -86.87181)
		(end 414.55721 -86.570058)
		(width 0.089408)
		(layer "In2.Cu")
		(net "IRQ_UV_DETECT_N")
	)
	(segment
		(start 464.71586 -59.693556)
		(end 464.71586 -58.922412)
		(width 0.089408)
		(layer "In2.Cu")
		(net "IRQ_UV_DETECT_N")
	)
	(segment
		(start 437.521096 -60.867544)
		(end 463.541872 -60.867544)
		(width 0.089408)
		(layer "In2.Cu")
		(net "IRQ_UV_DETECT_N")
	)
	(segment
		(start 417.195 -76.331064)
		(end 417.797742 -75.728322)
		(width 0.089408)
		(layer "In2.Cu")
		(net "IRQ_UV_DETECT_N")
	)
	(segment
		(start 475.007178 -54.454298)
		(end 475.46006 -54.90718)
		(width 0.089408)
		(layer "In2.Cu")
		(net "IRQ_UV_DETECT_N")
	)
	(segment
		(start 414.55721 -85.354414)
		(end 417.195 -82.716624)
		(width 0.089408)
		(layer "In2.Cu")
		(net "IRQ_UV_DETECT_N")
	)
	(segment
		(start 376.671332 -123.473972)
		(end 375.637806 -124.507498)
		(width 0.089408)
		(layer "In2.Cu")
		(net "IRQ_UV_DETECT_N")
	)
	(segment
		(start 463.541872 -60.867544)
		(end 464.71586 -59.693556)
		(width 0.089408)
		(layer "In2.Cu")
		(net "IRQ_UV_DETECT_N")
	)
	(segment
		(start 423.234104 -58.472832)
		(end 428.44847 -58.472832)
		(width 0.089408)
		(layer "In2.Cu")
		(net "IRQ_UV_DETECT_N")
	)
	(segment
		(start 414.255458 -87.446358)
		(end 414.255458 -86.87181)
		(width 0.089408)
		(layer "In2.Cu")
		(net "IRQ_UV_DETECT_N")
	)
	(segment
		(start 469.759284 -54.90718)
		(end 472.651836 -54.90718)
		(width 0.089408)
		(layer "In2.Cu")
		(net "IRQ_UV_DETECT_N")
	)
	(segment
		(start 437.090566 -59.82589)
		(end 437.090566 -60.437014)
		(width 0.089408)
		(layer "In2.Cu")
		(net "IRQ_UV_DETECT_N")
	)
	(segment
		(start 476.656908 -54.270402)
		(end 477.212406 -54.270402)
		(width 0.089408)
		(layer "In2.Cu")
		(net "IRQ_UV_DETECT_N")
	)
	(segment
		(start 418.029898 -63.677038)
		(end 423.234104 -58.472832)
		(width 0.089408)
		(layer "In2.Cu")
		(net "IRQ_UV_DETECT_N")
	)
	(segment
		(start 374.84177 -124.507498)
		(end 373.543322 -125.805946)
		(width 0.089408)
		(layer "In2.Cu")
		(net "IRQ_UV_DETECT_N")
	)
	(segment
		(start 476.02013 -54.90718)
		(end 476.656908 -54.270402)
		(width 0.089408)
		(layer "In2.Cu")
		(net "IRQ_UV_DETECT_N")
	)
	(segment
		(start 475.46006 -54.90718)
		(end 476.02013 -54.90718)
		(width 0.089408)
		(layer "In2.Cu")
		(net "IRQ_UV_DETECT_N")
	)
	(segment
		(start 464.715606 -58.76417)
		(end 465.872322 -57.607454)
		(width 0.089408)
		(layer "In2.Cu")
		(net "IRQ_UV_DETECT_N")
	)
	(segment
		(start 468.986108 -55.680356)
		(end 469.759284 -54.90718)
		(width 0.089408)
		(layer "In2.Cu")
		(net "IRQ_UV_DETECT_N")
	)
	(segment
		(start 465.872322 -57.607454)
		(end 466.802216 -57.607454)
		(width 0.089408)
		(layer "In2.Cu")
		(net "IRQ_UV_DETECT_N")
	)
	(segment
		(start 414.55721 -86.570058)
		(end 414.55721 -85.354414)
		(width 0.089408)
		(layer "In2.Cu")
		(net "IRQ_UV_DETECT_N")
	)
	(segment
		(start 464.71586 -58.922412)
		(end 464.715606 -58.922158)
		(width 0.089408)
		(layer "In2.Cu")
		(net "IRQ_UV_DETECT_N")
	)
	(segment
		(start 428.782988 -61.10224)
		(end 430.59096 -62.910212)
		(width 0.089408)
		(layer "In2.Cu")
		(net "IRQ_UV_DETECT_N")
	)
	(segment
		(start 466.960712 -57.606946)
		(end 466.960966 -57.6072)
		(width 0.089408)
		(layer "In2.Cu")
		(net "IRQ_UV_DETECT_N")
	)
	(segment
		(start 414.55594 -87.74684)
		(end 414.255458 -87.446358)
		(width 0.089408)
		(layer "In2.Cu")
		(net "IRQ_UV_DETECT_N")
	)
	(segment
		(start 432.695096 -62.910212)
		(end 436.060596 -59.544712)
		(width 0.089408)
		(layer "In2.Cu")
		(net "IRQ_UV_DETECT_N")
	)
	(segment
		(start 430.59096 -62.910212)
		(end 432.695096 -62.910212)
		(width 0.089408)
		(layer "In2.Cu")
		(net "IRQ_UV_DETECT_N")
	)
	(segment
		(start 428.782988 -60.944252)
		(end 428.782988 -61.10224)
		(width 0.089408)
		(layer "In2.Cu")
		(net "IRQ_UV_DETECT_N")
	)
	(segment
		(start 464.715606 -58.922158)
		(end 464.715606 -58.76417)
		(width 0.089408)
		(layer "In2.Cu")
		(net "IRQ_UV_DETECT_N")
	)
	(segment
		(start 472.651836 -54.90718)
		(end 472.837002 -55.092346)
		(width 0.089408)
		(layer "In2.Cu")
		(net "IRQ_UV_DETECT_N")
	)
	(segment
		(start 474.242638 -55.092346)
		(end 474.880686 -54.454298)
		(width 0.089408)
		(layer "In2.Cu")
		(net "IRQ_UV_DETECT_N")
	)
	(segment
		(start 428.783242 -58.807604)
		(end 428.783242 -60.943998)
		(width 0.089408)
		(layer "In2.Cu")
		(net "IRQ_UV_DETECT_N")
	)
	(segment
		(start 468.986108 -57.220866)
		(end 468.986108 -55.680356)
		(width 0.089408)
		(layer "In2.Cu")
		(net "IRQ_UV_DETECT_N")
	)
	(segment
		(start 417.797742 -71.155052)
		(end 418.029644 -70.92315)
		(width 0.089408)
		(layer "In2.Cu")
		(net "IRQ_UV_DETECT_N")
	)
	(segment
		(start 417.195 -82.716624)
		(end 417.195 -76.331064)
		(width 0.089408)
		(layer "In2.Cu")
		(net "IRQ_UV_DETECT_N")
	)
	(segment
		(start 375.637806 -124.507498)
		(end 374.84177 -124.507498)
		(width 0.089408)
		(layer "In2.Cu")
		(net "IRQ_UV_DETECT_N")
	)
	(segment
		(start 428.783242 -60.943998)
		(end 428.782988 -60.944252)
		(width 0.089408)
		(layer "In2.Cu")
		(net "IRQ_UV_DETECT_N")
	)
	(segment
		(start 474.880686 -54.454298)
		(end 475.007178 -54.454298)
		(width 0.089408)
		(layer "In2.Cu")
		(net "IRQ_UV_DETECT_N")
	)
	(segment
		(start 381.979424 -99.782376)
		(end 381.133096 -99.782376)
		(width 0.089408)
		(layer "In4.Cu")
		(net "IRQ_UV_DETECT_N")
	)
	(segment
		(start 375.777252 -112.613948)
		(end 375.483882 -112.907318)
		(width 0.089408)
		(layer "In4.Cu")
		(net "IRQ_UV_DETECT_N")
	)
	(segment
		(start 391.765536 -87.567008)
		(end 390.198356 -87.567008)
		(width 0.089408)
		(layer "In4.Cu")
		(net "IRQ_UV_DETECT_N")
	)
	(segment
		(start 391.76579 -87.566754)
		(end 391.765536 -87.567008)
		(width 0.089408)
		(layer "In4.Cu")
		(net "IRQ_UV_DETECT_N")
	)
	(segment
		(start 377.288552 -105.80624)
		(end 377.288552 -106.931714)
		(width 0.089408)
		(layer "In4.Cu")
		(net "IRQ_UV_DETECT_N")
	)
	(segment
		(start 380.708916 -101.509576)
		(end 380.708916 -102.061264)
		(width 0.089408)
		(layer "In4.Cu")
		(net "IRQ_UV_DETECT_N")
	)
	(segment
		(start 390.719818 -121.427748)
		(end 390.719818 -120.94083)
		(width 0.089408)
		(layer "In4.Cu")
		(net "IRQ_UV_DETECT_N")
	)
	(segment
		(start 391.20445 -120.456198)
		(end 391.20445 -119.528844)
		(width 0.089408)
		(layer "In4.Cu")
		(net "IRQ_UV_DETECT_N")
	)
	(segment
		(start 414.55594 -89.978738)
		(end 414.321498 -89.744296)
		(width 0.089408)
		(layer "In4.Cu")
		(net "IRQ_UV_DETECT_N")
	)
	(segment
		(start 405.806402 -89.647776)
		(end 404.320502 -88.161876)
		(width 0.089408)
		(layer "In4.Cu")
		(net "IRQ_UV_DETECT_N")
	)
	(segment
		(start 379.71603 -103.78059)
		(end 379.22073 -104.27589)
		(width 0.089408)
		(layer "In4.Cu")
		(net "IRQ_UV_DETECT_N")
	)
	(segment
		(start 379.71603 -103.05415)
		(end 379.71603 -103.78059)
		(width 0.089408)
		(layer "In4.Cu")
		(net "IRQ_UV_DETECT_N")
	)
	(segment
		(start 392.39952 -87.567008)
		(end 392.399266 -87.566754)
		(width 0.089408)
		(layer "In4.Cu")
		(net "IRQ_UV_DETECT_N")
	)
	(segment
		(start 376.292364 -121.868946)
		(end 377.193556 -121.868946)
		(width 0.089408)
		(layer "In4.Cu")
		(net "IRQ_UV_DETECT_N")
	)
	(segment
		(start 414.321498 -89.744296)
		(end 413.00019 -89.744296)
		(width 0.089408)
		(layer "In4.Cu")
		(net "IRQ_UV_DETECT_N")
	)
	(segment
		(start 413.00019 -89.744296)
		(end 411.969712 -90.774774)
		(width 0.089408)
		(layer "In4.Cu")
		(net "IRQ_UV_DETECT_N")
	)
	(segment
		(start 409.822904 -89.647776)
		(end 405.806402 -89.647776)
		(width 0.089408)
		(layer "In4.Cu")
		(net "IRQ_UV_DETECT_N")
	)
	(segment
		(start 383.384044 -98.923856)
		(end 382.618996 -98.923856)
		(width 0.089408)
		(layer "In4.Cu")
		(net "IRQ_UV_DETECT_N")
	)
	(segment
		(start 387.7056 -95.356172)
		(end 387.33857 -95.723202)
		(width 0.089408)
		(layer "In4.Cu")
		(net "IRQ_UV_DETECT_N")
	)
	(segment
		(start 410.949902 -90.774774)
		(end 409.822904 -89.647776)
		(width 0.089408)
		(layer "In4.Cu")
		(net "IRQ_UV_DETECT_N")
	)
	(segment
		(start 402.682456 -88.161622)
		(end 402.302218 -88.54186)
		(width 0.089408)
		(layer "In4.Cu")
		(net "IRQ_UV_DETECT_N")
	)
	(segment
		(start 377.35891 -121.703592)
		(end 390.443974 -121.703592)
		(width 0.089408)
		(layer "In4.Cu")
		(net "IRQ_UV_DETECT_N")
	)
	(segment
		(start 385.095496 -96.348296)
		(end 384.86207 -96.581722)
		(width 0.089408)
		(layer "In4.Cu")
		(net "IRQ_UV_DETECT_N")
	)
	(segment
		(start 376.82678 -107.393486)
		(end 376.82678 -108.520484)
		(width 0.089408)
		(layer "In4.Cu")
		(net "IRQ_UV_DETECT_N")
	)
	(segment
		(start 382.38557 -99.37623)
		(end 381.979424 -99.782376)
		(width 0.089408)
		(layer "In4.Cu")
		(net "IRQ_UV_DETECT_N")
	)
	(segment
		(start 380.40437 -100.84181)
		(end 380.40437 -101.20503)
		(width 0.089408)
		(layer "In4.Cu")
		(net "IRQ_UV_DETECT_N")
	)
	(segment
		(start 375.483882 -112.907318)
		(end 375.483882 -121.060464)
		(width 0.089408)
		(layer "In4.Cu")
		(net "IRQ_UV_DETECT_N")
	)
	(segment
		(start 384.36677 -97.803462)
		(end 383.87147 -98.298762)
		(width 0.089408)
		(layer "In4.Cu")
		(net "IRQ_UV_DETECT_N")
	)
	(segment
		(start 377.288552 -106.931714)
		(end 376.82678 -107.393486)
		(width 0.089408)
		(layer "In4.Cu")
		(net "IRQ_UV_DETECT_N")
	)
	(segment
		(start 382.38557 -99.157282)
		(end 382.38557 -99.37623)
		(width 0.089408)
		(layer "In4.Cu")
		(net "IRQ_UV_DETECT_N")
	)
	(segment
		(start 390.719818 -120.94083)
		(end 391.20445 -120.456198)
		(width 0.089408)
		(layer "In4.Cu")
		(net "IRQ_UV_DETECT_N")
	)
	(segment
		(start 380.89967 -100.34651)
		(end 380.40437 -100.84181)
		(width 0.089408)
		(layer "In4.Cu")
		(net "IRQ_UV_DETECT_N")
	)
	(segment
		(start 384.36677 -97.440242)
		(end 384.36677 -97.803462)
		(width 0.089408)
		(layer "In4.Cu")
		(net "IRQ_UV_DETECT_N")
	)
	(segment
		(start 390.198356 -87.567008)
		(end 387.7056 -90.059764)
		(width 0.089408)
		(layer "In4.Cu")
		(net "IRQ_UV_DETECT_N")
	)
	(segment
		(start 399.46199 -88.54186)
		(end 399.03908 -88.11895)
		(width 0.089408)
		(layer "In4.Cu")
		(net "IRQ_UV_DETECT_N")
	)
	(segment
		(start 377.193556 -121.868946)
		(end 377.35891 -121.703592)
		(width 0.089408)
		(layer "In4.Cu")
		(net "IRQ_UV_DETECT_N")
	)
	(segment
		(start 379.22073 -104.63911)
		(end 378.987304 -104.872536)
		(width 0.089408)
		(layer "In4.Cu")
		(net "IRQ_UV_DETECT_N")
	)
	(segment
		(start 411.969712 -90.774774)
		(end 410.949902 -90.774774)
		(width 0.089408)
		(layer "In4.Cu")
		(net "IRQ_UV_DETECT_N")
	)
	(segment
		(start 380.708916 -102.061264)
		(end 379.71603 -103.05415)
		(width 0.089408)
		(layer "In4.Cu")
		(net "IRQ_UV_DETECT_N")
	)
	(segment
		(start 380.40437 -101.20503)
		(end 380.708916 -101.509576)
		(width 0.089408)
		(layer "In4.Cu")
		(net "IRQ_UV_DETECT_N")
	)
	(segment
		(start 387.7056 -90.059764)
		(end 387.7056 -95.356172)
		(width 0.089408)
		(layer "In4.Cu")
		(net "IRQ_UV_DETECT_N")
	)
	(segment
		(start 402.302218 -88.54186)
		(end 399.46199 -88.54186)
		(width 0.089408)
		(layer "In4.Cu")
		(net "IRQ_UV_DETECT_N")
	)
	(segment
		(start 386.851144 -96.348296)
		(end 385.095496 -96.348296)
		(width 0.089408)
		(layer "In4.Cu")
		(net "IRQ_UV_DETECT_N")
	)
	(segment
		(start 378.222256 -104.872536)
		(end 377.288552 -105.80624)
		(width 0.089408)
		(layer "In4.Cu")
		(net "IRQ_UV_DETECT_N")
	)
	(segment
		(start 395.391894 -88.11895)
		(end 394.839952 -87.567008)
		(width 0.089408)
		(layer "In4.Cu")
		(net "IRQ_UV_DETECT_N")
	)
	(segment
		(start 414.55594 -90.398854)
		(end 414.55594 -89.978738)
		(width 0.089408)
		(layer "In4.Cu")
		(net "IRQ_UV_DETECT_N")
	)
	(segment
		(start 404.227284 -88.161876)
		(end 404.22703 -88.161622)
		(width 0.089408)
		(layer "In4.Cu")
		(net "IRQ_UV_DETECT_N")
	)
	(segment
		(start 375.483882 -121.060464)
		(end 376.292364 -121.868946)
		(width 0.089408)
		(layer "In4.Cu")
		(net "IRQ_UV_DETECT_N")
	)
	(segment
		(start 387.33857 -95.723202)
		(end 387.33857 -95.86087)
		(width 0.089408)
		(layer "In4.Cu")
		(net "IRQ_UV_DETECT_N")
	)
	(segment
		(start 384.86207 -96.944942)
		(end 384.36677 -97.440242)
		(width 0.089408)
		(layer "In4.Cu")
		(net "IRQ_UV_DETECT_N")
	)
	(segment
		(start 404.22703 -88.161622)
		(end 402.682456 -88.161622)
		(width 0.089408)
		(layer "In4.Cu")
		(net "IRQ_UV_DETECT_N")
	)
	(segment
		(start 399.03908 -88.11895)
		(end 395.391894 -88.11895)
		(width 0.089408)
		(layer "In4.Cu")
		(net "IRQ_UV_DETECT_N")
	)
	(segment
		(start 382.618996 -98.923856)
		(end 382.38557 -99.157282)
		(width 0.089408)
		(layer "In4.Cu")
		(net "IRQ_UV_DETECT_N")
	)
	(segment
		(start 383.87147 -98.298762)
		(end 383.87147 -98.43643)
		(width 0.089408)
		(layer "In4.Cu")
		(net "IRQ_UV_DETECT_N")
	)
	(segment
		(start 379.22073 -104.27589)
		(end 379.22073 -104.63911)
		(width 0.089408)
		(layer "In4.Cu")
		(net "IRQ_UV_DETECT_N")
	)
	(segment
		(start 394.839952 -87.567008)
		(end 392.39952 -87.567008)
		(width 0.089408)
		(layer "In4.Cu")
		(net "IRQ_UV_DETECT_N")
	)
	(segment
		(start 414.123632 -90.831162)
		(end 414.55594 -90.398854)
		(width 0.089408)
		(layer "In4.Cu")
		(net "IRQ_UV_DETECT_N")
	)
	(segment
		(start 381.133096 -99.782376)
		(end 380.89967 -100.015802)
		(width 0.089408)
		(layer "In4.Cu")
		(net "IRQ_UV_DETECT_N")
	)
	(segment
		(start 375.777252 -111.88573)
		(end 375.777252 -112.613948)
		(width 0.089408)
		(layer "In4.Cu")
		(net "IRQ_UV_DETECT_N")
	)
	(segment
		(start 376.128026 -111.534956)
		(end 375.777252 -111.88573)
		(width 0.089408)
		(layer "In4.Cu")
		(net "IRQ_UV_DETECT_N")
	)
	(segment
		(start 387.33857 -95.86087)
		(end 386.851144 -96.348296)
		(width 0.089408)
		(layer "In4.Cu")
		(net "IRQ_UV_DETECT_N")
	)
	(segment
		(start 380.89967 -100.015802)
		(end 380.89967 -100.34651)
		(width 0.089408)
		(layer "In4.Cu")
		(net "IRQ_UV_DETECT_N")
	)
	(segment
		(start 390.443974 -121.703592)
		(end 390.719818 -121.427748)
		(width 0.089408)
		(layer "In4.Cu")
		(net "IRQ_UV_DETECT_N")
	)
	(segment
		(start 376.128026 -109.219238)
		(end 376.128026 -111.534956)
		(width 0.089408)
		(layer "In4.Cu")
		(net "IRQ_UV_DETECT_N")
	)
	(segment
		(start 404.320502 -88.161876)
		(end 404.227284 -88.161876)
		(width 0.089408)
		(layer "In4.Cu")
		(net "IRQ_UV_DETECT_N")
	)
	(segment
		(start 378.987304 -104.872536)
		(end 378.222256 -104.872536)
		(width 0.089408)
		(layer "In4.Cu")
		(net "IRQ_UV_DETECT_N")
	)
	(segment
		(start 392.399266 -87.566754)
		(end 391.76579 -87.566754)
		(width 0.089408)
		(layer "In4.Cu")
		(net "IRQ_UV_DETECT_N")
	)
	(segment
		(start 383.87147 -98.43643)
		(end 383.384044 -98.923856)
		(width 0.089408)
		(layer "In4.Cu")
		(net "IRQ_UV_DETECT_N")
	)
	(segment
		(start 376.82678 -108.520484)
		(end 376.128026 -109.219238)
		(width 0.089408)
		(layer "In4.Cu")
		(net "IRQ_UV_DETECT_N")
	)
	(segment
		(start 384.86207 -96.581722)
		(end 384.86207 -96.944942)
		(width 0.089408)
		(layer "In4.Cu")
		(net "IRQ_UV_DETECT_N")
	)
	(segment
		(start 13.458952 -91.999054)
		(end 13.458952 -96.227138)
		(width 0.089408)
		(layer "In9.Cu")
		(net "IRQ_UV_DETECT_N")
	)
	(segment
		(start 310.366664 -126.315724)
		(end 319.940686 -126.315724)
		(width 0.089408)
		(layer "In9.Cu")
		(net "IRQ_UV_DETECT_N")
	)
	(segment
		(start 26.230072 -114.36096)
		(end 34.009076 -122.139964)
		(width 0.089408)
		(layer "In9.Cu")
		(net "IRQ_UV_DETECT_N")
	)
	(segment
		(start 328.917554 -122.558048)
		(end 337.076542 -122.558048)
		(width 0.089408)
		(layer "In9.Cu")
		(net "IRQ_UV_DETECT_N")
	)
	(segment
		(start 223.858836 -122.865388)
		(end 243.969032 -122.865388)
		(width 0.089408)
		(layer "In9.Cu")
		(net "IRQ_UV_DETECT_N")
	)
	(segment
		(start 244.68455 -123.580906)
		(end 263.501378 -123.580906)
		(width 0.089408)
		(layer "In9.Cu")
		(net "IRQ_UV_DETECT_N")
	)
	(segment
		(start 17.378172 -85.3821)
		(end 17.1196 -85.640672)
		(width 0.089408)
		(layer "In9.Cu")
		(net "IRQ_UV_DETECT_N")
	)
	(segment
		(start 16.241014 -86.7156)
		(end 14.191742 -88.764872)
		(width 0.089408)
		(layer "In9.Cu")
		(net "IRQ_UV_DETECT_N")
	)
	(segment
		(start 166.34333 -125.434344)
		(end 167.01897 -126.109984)
		(width 0.089408)
		(layer "In9.Cu")
		(net "IRQ_UV_DETECT_N")
	)
	(segment
		(start 166.180008 -125.434344)
		(end 166.34333 -125.434344)
		(width 0.089408)
		(layer "In9.Cu")
		(net "IRQ_UV_DETECT_N")
	)
	(segment
		(start 325.026782 -123.215908)
		(end 328.259694 -123.215908)
		(width 0.089408)
		(layer "In9.Cu")
		(net "IRQ_UV_DETECT_N")
	)
	(segment
		(start 263.501378 -123.580906)
		(end 264.425684 -122.6566)
		(width 0.089408)
		(layer "In9.Cu")
		(net "IRQ_UV_DETECT_N")
	)
	(segment
		(start 186.3471 -125.332744)
		(end 187.357004 -124.32284)
		(width 0.089408)
		(layer "In9.Cu")
		(net "IRQ_UV_DETECT_N")
	)
	(segment
		(start 18.615152 -100.004626)
		(end 18.615152 -108.575348)
		(width 0.089408)
		(layer "In9.Cu")
		(net "IRQ_UV_DETECT_N")
	)
	(segment
		(start 167.01897 -126.109984)
		(end 172.402246 -126.109984)
		(width 0.089408)
		(layer "In9.Cu")
		(net "IRQ_UV_DETECT_N")
	)
	(segment
		(start 18.615152 -108.575348)
		(end 24.400764 -114.36096)
		(width 0.089408)
		(layer "In9.Cu")
		(net "IRQ_UV_DETECT_N")
	)
	(segment
		(start 328.259694 -123.215908)
		(end 328.917554 -122.558048)
		(width 0.089408)
		(layer "In9.Cu")
		(net "IRQ_UV_DETECT_N")
	)
	(segment
		(start 174.682404 -123.829826)
		(end 180.017928 -123.829826)
		(width 0.089408)
		(layer "In9.Cu")
		(net "IRQ_UV_DETECT_N")
	)
	(segment
		(start 163.961572 -124.669296)
		(end 165.41496 -124.669296)
		(width 0.089408)
		(layer "In9.Cu")
		(net "IRQ_UV_DETECT_N")
	)
	(segment
		(start 337.076542 -122.558048)
		(end 340.67877 -118.95582)
		(width 0.089408)
		(layer "In9.Cu")
		(net "IRQ_UV_DETECT_N")
	)
	(segment
		(start 17.1196 -86.240366)
		(end 16.644366 -86.7156)
		(width 0.089408)
		(layer "In9.Cu")
		(net "IRQ_UV_DETECT_N")
	)
	(segment
		(start 319.940686 -126.315724)
		(end 321.445636 -124.810774)
		(width 0.089408)
		(layer "In9.Cu")
		(net "IRQ_UV_DETECT_N")
	)
	(segment
		(start 17.1196 -85.640672)
		(end 17.1196 -86.240366)
		(width 0.089408)
		(layer "In9.Cu")
		(net "IRQ_UV_DETECT_N")
	)
	(segment
		(start 180.017928 -123.829826)
		(end 181.520846 -125.332744)
		(width 0.089408)
		(layer "In9.Cu")
		(net "IRQ_UV_DETECT_N")
	)
	(segment
		(start 165.41496 -124.669296)
		(end 166.180008 -125.434344)
		(width 0.089408)
		(layer "In9.Cu")
		(net "IRQ_UV_DETECT_N")
	)
	(segment
		(start 306.70754 -122.6566)
		(end 310.366664 -126.315724)
		(width 0.089408)
		(layer "In9.Cu")
		(net "IRQ_UV_DETECT_N")
	)
	(segment
		(start 323.431916 -124.810774)
		(end 325.026782 -123.215908)
		(width 0.089408)
		(layer "In9.Cu")
		(net "IRQ_UV_DETECT_N")
	)
	(segment
		(start 152.649936 -127.321056)
		(end 161.309812 -127.321056)
		(width 0.089408)
		(layer "In9.Cu")
		(net "IRQ_UV_DETECT_N")
	)
	(segment
		(start 264.425684 -122.6566)
		(end 306.70754 -122.6566)
		(width 0.089408)
		(layer "In9.Cu")
		(net "IRQ_UV_DETECT_N")
	)
	(segment
		(start 340.67877 -118.95582)
		(end 344.857832 -118.95582)
		(width 0.089408)
		(layer "In9.Cu")
		(net "IRQ_UV_DETECT_N")
	)
	(segment
		(start 321.445636 -124.810774)
		(end 323.431916 -124.810774)
		(width 0.089408)
		(layer "In9.Cu")
		(net "IRQ_UV_DETECT_N")
	)
	(segment
		(start 181.520846 -125.332744)
		(end 186.3471 -125.332744)
		(width 0.089408)
		(layer "In9.Cu")
		(net "IRQ_UV_DETECT_N")
	)
	(segment
		(start 24.400764 -114.36096)
		(end 26.230072 -114.36096)
		(width 0.089408)
		(layer "In9.Cu")
		(net "IRQ_UV_DETECT_N")
	)
	(segment
		(start 187.357004 -124.32284)
		(end 222.401384 -124.32284)
		(width 0.089408)
		(layer "In9.Cu")
		(net "IRQ_UV_DETECT_N")
	)
	(segment
		(start 222.401384 -124.32284)
		(end 223.858836 -122.865388)
		(width 0.089408)
		(layer "In9.Cu")
		(net "IRQ_UV_DETECT_N")
	)
	(segment
		(start 15.635224 -98.40341)
		(end 17.013936 -98.40341)
		(width 0.089408)
		(layer "In9.Cu")
		(net "IRQ_UV_DETECT_N")
	)
	(segment
		(start 17.013936 -98.40341)
		(end 18.615152 -100.004626)
		(width 0.089408)
		(layer "In9.Cu")
		(net "IRQ_UV_DETECT_N")
	)
	(segment
		(start 34.009076 -122.139964)
		(end 147.468844 -122.139964)
		(width 0.089408)
		(layer "In9.Cu")
		(net "IRQ_UV_DETECT_N")
	)
	(segment
		(start 172.402246 -126.109984)
		(end 174.682404 -123.829826)
		(width 0.089408)
		(layer "In9.Cu")
		(net "IRQ_UV_DETECT_N")
	)
	(segment
		(start 14.191742 -91.266264)
		(end 13.458952 -91.999054)
		(width 0.089408)
		(layer "In9.Cu")
		(net "IRQ_UV_DETECT_N")
	)
	(segment
		(start 16.644366 -86.7156)
		(end 16.241014 -86.7156)
		(width 0.089408)
		(layer "In9.Cu")
		(net "IRQ_UV_DETECT_N")
	)
	(segment
		(start 243.969032 -122.865388)
		(end 244.68455 -123.580906)
		(width 0.089408)
		(layer "In9.Cu")
		(net "IRQ_UV_DETECT_N")
	)
	(segment
		(start 13.458952 -96.227138)
		(end 15.635224 -98.40341)
		(width 0.089408)
		(layer "In9.Cu")
		(net "IRQ_UV_DETECT_N")
	)
	(segment
		(start 161.309812 -127.321056)
		(end 163.961572 -124.669296)
		(width 0.089408)
		(layer "In9.Cu")
		(net "IRQ_UV_DETECT_N")
	)
	(segment
		(start 147.468844 -122.139964)
		(end 152.649936 -127.321056)
		(width 0.089408)
		(layer "In9.Cu")
		(net "IRQ_UV_DETECT_N")
	)
	(segment
		(start 14.191742 -88.764872)
		(end 14.191742 -91.266264)
		(width 0.089408)
		(layer "In9.Cu")
		(net "IRQ_UV_DETECT_N")
	)
	(segment
		(start 344.857832 -118.95582)
		(end 346.09024 -117.723412)
		(width 0.089408)
		(layer "In9.Cu")
		(net "IRQ_UV_DETECT_N")
	)
	(segment
		(start 473.563696 -44.835318)
		(end 472.280488 -43.55211)
		(width 0.089408)
		(layer "In11.Cu")
		(net "IRQ_UV_DETECT_N")
	)
	(segment
		(start 439.011314 -16.886936)
		(end 438.933082 -16.965168)
		(width 0.089408)
		(layer "In11.Cu")
		(net "IRQ_UV_DETECT_N")
	)
	(segment
		(start 465.831936 -14.846808)
		(end 468.05977 -14.846808)
		(width 0.089408)
		(layer "In11.Cu")
		(net "IRQ_UV_DETECT_N")
	)
	(segment
		(start 474.689424 -33.519872)
		(end 475.121478 -33.087818)
		(width 0.089408)
		(layer "In11.Cu")
		(net "IRQ_UV_DETECT_N")
	)
	(segment
		(start 475.121732 -32.929576)
		(end 475.121732 -32.444436)
		(width 0.089408)
		(layer "In11.Cu")
		(net "IRQ_UV_DETECT_N")
	)
	(segment
		(start 476.211392 -48.57115)
		(end 473.563696 -45.923454)
		(width 0.089408)
		(layer "In11.Cu")
		(net "IRQ_UV_DETECT_N")
	)
	(segment
		(start 465.228686 -23.38705)
		(end 465.228686 -19.528536)
		(width 0.089408)
		(layer "In11.Cu")
		(net "IRQ_UV_DETECT_N")
	)
	(segment
		(start 465.228686 -19.528536)
		(end 464.574128 -18.873978)
		(width 0.089408)
		(layer "In11.Cu")
		(net "IRQ_UV_DETECT_N")
	)
	(segment
		(start 472.280488 -43.55211)
		(end 472.280488 -42.995088)
		(width 0.089408)
		(layer "In11.Cu")
		(net "IRQ_UV_DETECT_N")
	)
	(segment
		(start 373.024146 -121.15165)
		(end 373.024146 -125.28677)
		(width 0.089408)
		(layer "In11.Cu")
		(net "IRQ_UV_DETECT_N")
	)
	(segment
		(start 390.398 -121.85142)
		(end 390.398 -121.6914)
		(width 0.089408)
		(layer "In11.Cu")
		(net "IRQ_UV_DETECT_N")
	)
	(segment
		(start 464.574128 -18.873978)
		(end 464.574128 -16.104616)
		(width 0.089408)
		(layer "In11.Cu")
		(net "IRQ_UV_DETECT_N")
	)
	(segment
		(start 473.735908 -9.263888)
		(end 472.54668 -8.07466)
		(width 0.089408)
		(layer "In11.Cu")
		(net "IRQ_UV_DETECT_N")
	)
	(segment
		(start 373.76862 -120.407176)
		(end 373.024146 -121.15165)
		(width 0.089408)
		(layer "In11.Cu")
		(net "IRQ_UV_DETECT_N")
	)
	(segment
		(start 456.976734 -8.461756)
		(end 456.974194 -8.464296)
		(width 0.089408)
		(layer "In11.Cu")
		(net "IRQ_UV_DETECT_N")
	)
	(segment
		(start 473.563696 -45.923454)
		(end 473.563696 -44.835318)
		(width 0.089408)
		(layer "In11.Cu")
		(net "IRQ_UV_DETECT_N")
	)
	(segment
		(start 458.253338 -8.464296)
		(end 457.310998 -8.464296)
		(width 0.089408)
		(layer "In11.Cu")
		(net "IRQ_UV_DETECT_N")
	)
	(segment
		(start 477.212406 -54.270402)
		(end 477.079564 -54.13756)
		(width 0.089408)
		(layer "In11.Cu")
		(net "IRQ_UV_DETECT_N")
	)
	(segment
		(start 443.606682 -16.886936)
		(end 439.011314 -16.886936)
		(width 0.089408)
		(layer "In11.Cu")
		(net "IRQ_UV_DETECT_N")
	)
	(segment
		(start 390.779 -121.031)
		(end 391.20445 -120.60555)
		(width 0.089408)
		(layer "In11.Cu")
		(net "IRQ_UV_DETECT_N")
	)
	(segment
		(start 468.531702 -8.25246)
		(end 468.101934 -7.822692)
		(width 0.089408)
		(layer "In11.Cu")
		(net "IRQ_UV_DETECT_N")
	)
	(segment
		(start 467.952836 -26.1112)
		(end 465.228686 -23.38705)
		(width 0.089408)
		(layer "In11.Cu")
		(net "IRQ_UV_DETECT_N")
	)
	(segment
		(start 459.300834 -7.4168)
		(end 458.253338 -8.464296)
		(width 0.089408)
		(layer "In11.Cu")
		(net "IRQ_UV_DETECT_N")
	)
	(segment
		(start 471.283792 -26.1112)
		(end 467.952836 -26.1112)
		(width 0.089408)
		(layer "In11.Cu")
		(net "IRQ_UV_DETECT_N")
	)
	(segment
		(start 376.671332 -123.473972)
		(end 377.615704 -122.5296)
		(width 0.089408)
		(layer "In11.Cu")
		(net "IRQ_UV_DETECT_N")
	)
	(segment
		(start 451.992238 -11.2776)
		(end 450.114416 -11.2776)
		(width 0.089408)
		(layer "In11.Cu")
		(net "IRQ_UV_DETECT_N")
	)
	(segment
		(start 445.493648 -15.898368)
		(end 444.674244 -15.898368)
		(width 0.089408)
		(layer "In11.Cu")
		(net "IRQ_UV_DETECT_N")
	)
	(segment
		(start 470.32672 -8.25246)
		(end 468.531702 -8.25246)
		(width 0.089408)
		(layer "In11.Cu")
		(net "IRQ_UV_DETECT_N")
	)
	(segment
		(start 423.614596 -17.554956)
		(end 423.614596 -18.323814)
		(width 0.089408)
		(layer "In11.Cu")
		(net "IRQ_UV_DETECT_N")
	)
	(segment
		(start 373.76862 -118.11)
		(end 373.76862 -120.407176)
		(width 0.089408)
		(layer "In11.Cu")
		(net "IRQ_UV_DETECT_N")
	)
	(segment
		(start 389.9662 -122.5296)
		(end 390.31037 -122.18543)
		(width 0.089408)
		(layer "In11.Cu")
		(net "IRQ_UV_DETECT_N")
	)
	(segment
		(start 423.132758 -18.805652)
		(end 421.519096 -18.805652)
		(width 0.089408)
		(layer "In11.Cu")
		(net "IRQ_UV_DETECT_N")
	)
	(segment
		(start 454.671938 -8.464296)
		(end 453.424036 -9.712198)
		(width 0.089408)
		(layer "In11.Cu")
		(net "IRQ_UV_DETECT_N")
	)
	(segment
		(start 390.31037 -122.18543)
		(end 390.31037 -121.93905)
		(width 0.089408)
		(layer "In11.Cu")
		(net "IRQ_UV_DETECT_N")
	)
	(segment
		(start 457.310998 -8.464296)
		(end 457.308458 -8.461756)
		(width 0.089408)
		(layer "In11.Cu")
		(net "IRQ_UV_DETECT_N")
	)
	(segment
		(start 474.689424 -36.841176)
		(end 474.689424 -33.519872)
		(width 0.089408)
		(layer "In11.Cu")
		(net "IRQ_UV_DETECT_N")
	)
	(segment
		(start 390.779 -121.3104)
		(end 390.779 -121.031)
		(width 0.089408)
		(layer "In11.Cu")
		(net "IRQ_UV_DETECT_N")
	)
	(segment
		(start 473.762832 -37.767768)
		(end 474.689424 -36.841176)
		(width 0.089408)
		(layer "In11.Cu")
		(net "IRQ_UV_DETECT_N")
	)
	(segment
		(start 472.280488 -39.81069)
		(end 473.762832 -38.328346)
		(width 0.089408)
		(layer "In11.Cu")
		(net "IRQ_UV_DETECT_N")
	)
	(segment
		(start 456.974194 -8.464296)
		(end 454.671938 -8.464296)
		(width 0.089408)
		(layer "In11.Cu")
		(net "IRQ_UV_DETECT_N")
	)
	(segment
		(start 421.519096 -18.805652)
		(end 421.4114 -18.697956)
		(width 0.089408)
		(layer "In11.Cu")
		(net "IRQ_UV_DETECT_N")
	)
	(segment
		(start 475.121478 -33.087818)
		(end 475.121478 -32.92983)
		(width 0.089408)
		(layer "In11.Cu")
		(net "IRQ_UV_DETECT_N")
	)
	(segment
		(start 475.121732 -32.444436)
		(end 475.121224 -32.443928)
		(width 0.089408)
		(layer "In11.Cu")
		(net "IRQ_UV_DETECT_N")
	)
	(segment
		(start 443.703202 -16.790416)
		(end 443.606682 -16.886936)
		(width 0.089408)
		(layer "In11.Cu")
		(net "IRQ_UV_DETECT_N")
	)
	(segment
		(start 424.002962 -17.16659)
		(end 423.614596 -17.554956)
		(width 0.089408)
		(layer "In11.Cu")
		(net "IRQ_UV_DETECT_N")
	)
	(segment
		(start 346.329254 -117.484398)
		(end 373.143018 -117.484398)
		(width 0.089408)
		(layer "In11.Cu")
		(net "IRQ_UV_DETECT_N")
	)
	(segment
		(start 468.101934 -7.822692)
		(end 460.671672 -7.822692)
		(width 0.089408)
		(layer "In11.Cu")
		(net "IRQ_UV_DETECT_N")
	)
	(segment
		(start 373.024146 -125.28677)
		(end 373.543322 -125.805946)
		(width 0.089408)
		(layer "In11.Cu")
		(net "IRQ_UV_DETECT_N")
	)
	(segment
		(start 464.574128 -16.104616)
		(end 465.831936 -14.846808)
		(width 0.089408)
		(layer "In11.Cu")
		(net "IRQ_UV_DETECT_N")
	)
	(segment
		(start 450.114416 -11.2776)
		(end 445.493648 -15.898368)
		(width 0.089408)
		(layer "In11.Cu")
		(net "IRQ_UV_DETECT_N")
	)
	(segment
		(start 475.121224 -29.948632)
		(end 471.283792 -26.1112)
		(width 0.089408)
		(layer "In11.Cu")
		(net "IRQ_UV_DETECT_N")
	)
	(segment
		(start 473.735908 -11.132312)
		(end 473.735908 -9.263888)
		(width 0.089408)
		(layer "In11.Cu")
		(net "IRQ_UV_DETECT_N")
	)
	(segment
		(start 444.674244 -15.898368)
		(end 443.782196 -16.790416)
		(width 0.089408)
		(layer "In11.Cu")
		(net "IRQ_UV_DETECT_N")
	)
	(segment
		(start 460.26578 -7.4168)
		(end 459.300834 -7.4168)
		(width 0.089408)
		(layer "In11.Cu")
		(net "IRQ_UV_DETECT_N")
	)
	(segment
		(start 346.09024 -117.723412)
		(end 346.329254 -117.484398)
		(width 0.089408)
		(layer "In11.Cu")
		(net "IRQ_UV_DETECT_N")
	)
	(segment
		(start 475.121478 -32.92983)
		(end 475.121732 -32.929576)
		(width 0.089408)
		(layer "In11.Cu")
		(net "IRQ_UV_DETECT_N")
	)
	(segment
		(start 432.971956 -16.965168)
		(end 432.770534 -17.16659)
		(width 0.089408)
		(layer "In11.Cu")
		(net "IRQ_UV_DETECT_N")
	)
	(segment
		(start 443.782196 -16.790416)
		(end 443.703202 -16.790416)
		(width 0.089408)
		(layer "In11.Cu")
		(net "IRQ_UV_DETECT_N")
	)
	(segment
		(start 390.398 -121.6914)
		(end 390.779 -121.3104)
		(width 0.089408)
		(layer "In11.Cu")
		(net "IRQ_UV_DETECT_N")
	)
	(segment
		(start 472.280488 -42.995088)
		(end 471.5002 -42.2148)
		(width 0.089408)
		(layer "In11.Cu")
		(net "IRQ_UV_DETECT_N")
	)
	(segment
		(start 472.280488 -40.197532)
		(end 472.280488 -39.81069)
		(width 0.089408)
		(layer "In11.Cu")
		(net "IRQ_UV_DETECT_N")
	)
	(segment
		(start 471.108532 -13.759688)
		(end 473.735908 -11.132312)
		(width 0.089408)
		(layer "In11.Cu")
		(net "IRQ_UV_DETECT_N")
	)
	(segment
		(start 477.079564 -53.715412)
		(end 476.211392 -52.84724)
		(width 0.089408)
		(layer "In11.Cu")
		(net "IRQ_UV_DETECT_N")
	)
	(segment
		(start 377.615704 -122.5296)
		(end 389.9662 -122.5296)
		(width 0.089408)
		(layer "In11.Cu")
		(net "IRQ_UV_DETECT_N")
	)
	(segment
		(start 390.31037 -121.93905)
		(end 390.398 -121.85142)
		(width 0.089408)
		(layer "In11.Cu")
		(net "IRQ_UV_DETECT_N")
	)
	(segment
		(start 432.770534 -17.16659)
		(end 424.002962 -17.16659)
		(width 0.089408)
		(layer "In11.Cu")
		(net "IRQ_UV_DETECT_N")
	)
	(segment
		(start 472.54668 -8.07466)
		(end 470.50452 -8.07466)
		(width 0.089408)
		(layer "In11.Cu")
		(net "IRQ_UV_DETECT_N")
	)
	(segment
		(start 469.14689 -13.759688)
		(end 471.108532 -13.759688)
		(width 0.089408)
		(layer "In11.Cu")
		(net "IRQ_UV_DETECT_N")
	)
	(segment
		(start 470.50452 -8.07466)
		(end 470.32672 -8.25246)
		(width 0.089408)
		(layer "In11.Cu")
		(net "IRQ_UV_DETECT_N")
	)
	(segment
		(start 475.121224 -32.443928)
		(end 475.121224 -29.948632)
		(width 0.089408)
		(layer "In11.Cu")
		(net "IRQ_UV_DETECT_N")
	)
	(segment
		(start 453.424036 -9.845802)
		(end 451.992238 -11.2776)
		(width 0.089408)
		(layer "In11.Cu")
		(net "IRQ_UV_DETECT_N")
	)
	(segment
		(start 391.20445 -120.60555)
		(end 391.20445 -119.528844)
		(width 0.089408)
		(layer "In11.Cu")
		(net "IRQ_UV_DETECT_N")
	)
	(segment
		(start 473.762832 -38.328346)
		(end 473.762832 -37.767768)
		(width 0.089408)
		(layer "In11.Cu")
		(net "IRQ_UV_DETECT_N")
	)
	(segment
		(start 471.5002 -42.2148)
		(end 471.5002 -40.97782)
		(width 0.089408)
		(layer "In11.Cu")
		(net "IRQ_UV_DETECT_N")
	)
	(segment
		(start 471.5002 -40.97782)
		(end 472.280488 -40.197532)
		(width 0.089408)
		(layer "In11.Cu")
		(net "IRQ_UV_DETECT_N")
	)
	(segment
		(start 438.933082 -16.965168)
		(end 432.971956 -16.965168)
		(width 0.089408)
		(layer "In11.Cu")
		(net "IRQ_UV_DETECT_N")
	)
	(segment
		(start 460.671672 -7.822692)
		(end 460.26578 -7.4168)
		(width 0.089408)
		(layer "In11.Cu")
		(net "IRQ_UV_DETECT_N")
	)
	(segment
		(start 373.143018 -117.484398)
		(end 373.76862 -118.11)
		(width 0.089408)
		(layer "In11.Cu")
		(net "IRQ_UV_DETECT_N")
	)
	(segment
		(start 423.614596 -18.323814)
		(end 423.132758 -18.805652)
		(width 0.089408)
		(layer "In11.Cu")
		(net "IRQ_UV_DETECT_N")
	)
	(segment
		(start 457.308458 -8.461756)
		(end 456.976734 -8.461756)
		(width 0.089408)
		(layer "In11.Cu")
		(net "IRQ_UV_DETECT_N")
	)
	(segment
		(start 477.079564 -54.13756)
		(end 477.079564 -53.715412)
		(width 0.089408)
		(layer "In11.Cu")
		(net "IRQ_UV_DETECT_N")
	)
	(segment
		(start 468.05977 -14.846808)
		(end 469.14689 -13.759688)
		(width 0.089408)
		(layer "In11.Cu")
		(net "IRQ_UV_DETECT_N")
	)
	(segment
		(start 453.424036 -9.712198)
		(end 453.424036 -9.845802)
		(width 0.089408)
		(layer "In11.Cu")
		(net "IRQ_UV_DETECT_N")
	)
	(segment
		(start 476.211392 -52.84724)
		(end 476.211392 -48.57115)
		(width 0.089408)
		(layer "In11.Cu")
		(net "IRQ_UV_DETECT_N")
	)
	(segment
		(start 24.7015 -83.805014)
		(end 24.24684 -83.805014)
		(width 0.10795)
		(layer "F.Cu")
		(net "IRQ_OC_DETECT_N")
	)
	(segment
		(start 20.0914 -80.3656)
		(end 19.7104 -80.7466)
		(width 0.10795)
		(layer "F.Cu")
		(net "IRQ_OC_DETECT_N")
	)
	(segment
		(start 419.090094 -25.929082)
		(end 419.090094 -26.534618)
		(width 0.10795)
		(layer "F.Cu")
		(net "IRQ_OC_DETECT_N")
	)
	(segment
		(start 20.501102 -79.809086)
		(end 20.0914 -80.218788)
		(width 0.10795)
		(layer "F.Cu")
		(net "IRQ_OC_DETECT_N")
	)
	(segment
		(start 20.9423 -82.74558)
		(end 20.447 -82.25028)
		(width 0.10795)
		(layer "F.Cu")
		(net "IRQ_OC_DETECT_N")
	)
	(segment
		(start 20.0914 -80.218788)
		(end 20.0914 -80.3656)
		(width 0.10795)
		(layer "F.Cu")
		(net "IRQ_OC_DETECT_N")
	)
	(segment
		(start 421.846502 -22.795738)
		(end 420.755826 -23.886414)
		(width 0.10795)
		(layer "F.Cu")
		(net "IRQ_OC_DETECT_N")
	)
	(segment
		(start 20.02028 -81.79308)
		(end 20.447 -81.79308)
		(width 0.10795)
		(layer "F.Cu")
		(net "IRQ_OC_DETECT_N")
	)
	(segment
		(start 19.7104 -80.7466)
		(end 19.7104 -81.4832)
		(width 0.10795)
		(layer "F.Cu")
		(net "IRQ_OC_DETECT_N")
	)
	(segment
		(start 386.74675 -95.888556)
		(end 386.25145 -96.11868)
		(width 0.10795)
		(layer "F.Cu")
		(net "IRQ_OC_DETECT_N")
	)
	(segment
		(start 420.7764 -18.96364)
		(end 421.591486 -19.778726)
		(width 0.10795)
		(layer "F.Cu")
		(net "IRQ_OC_DETECT_N")
	)
	(segment
		(start 24.290528 -80.066388)
		(end 21.900388 -80.066388)
		(width 0.10795)
		(layer "F.Cu")
		(net "IRQ_OC_DETECT_N")
	)
	(segment
		(start 21.900388 -80.066388)
		(end 21.643086 -79.809086)
		(width 0.10795)
		(layer "F.Cu")
		(net "IRQ_OC_DETECT_N")
	)
	(segment
		(start 24.71928 -80.49514)
		(end 24.290528 -80.066388)
		(width 0.10795)
		(layer "F.Cu")
		(net "IRQ_OC_DETECT_N")
	)
	(segment
		(start 421.591486 -19.778726)
		(end 421.591486 -21.325078)
		(width 0.10795)
		(layer "F.Cu")
		(net "IRQ_OC_DETECT_N")
	)
	(segment
		(start 24.02078 -82.886296)
		(end 24.71928 -82.187796)
		(width 0.10795)
		(layer "F.Cu")
		(net "IRQ_OC_DETECT_N")
	)
	(segment
		(start 21.643086 -79.809086)
		(end 20.501102 -79.809086)
		(width 0.10795)
		(layer "F.Cu")
		(net "IRQ_OC_DETECT_N")
	)
	(segment
		(start 420.755826 -24.26335)
		(end 419.090094 -25.929082)
		(width 0.10795)
		(layer "F.Cu")
		(net "IRQ_OC_DETECT_N")
	)
	(segment
		(start 421.846502 -21.580094)
		(end 421.846502 -22.795738)
		(width 0.10795)
		(layer "F.Cu")
		(net "IRQ_OC_DETECT_N")
	)
	(segment
		(start 19.7104 -81.4832)
		(end 20.02028 -81.79308)
		(width 0.10795)
		(layer "F.Cu")
		(net "IRQ_OC_DETECT_N")
	)
	(segment
		(start 24.24684 -83.805014)
		(end 24.02078 -83.578954)
		(width 0.10795)
		(layer "F.Cu")
		(net "IRQ_OC_DETECT_N")
	)
	(segment
		(start 420.7764 -18.697956)
		(end 420.7764 -18.96364)
		(width 0.10795)
		(layer "F.Cu")
		(net "IRQ_OC_DETECT_N")
	)
	(segment
		(start 24.71928 -82.187796)
		(end 24.71928 -80.49514)
		(width 0.10795)
		(layer "F.Cu")
		(net "IRQ_OC_DETECT_N")
	)
	(segment
		(start 420.755826 -23.886414)
		(end 420.755826 -24.26335)
		(width 0.10795)
		(layer "F.Cu")
		(net "IRQ_OC_DETECT_N")
	)
	(segment
		(start 24.02078 -83.578954)
		(end 24.02078 -82.886296)
		(width 0.10795)
		(layer "F.Cu")
		(net "IRQ_OC_DETECT_N")
	)
	(segment
		(start 20.447 -82.25028)
		(end 20.447 -81.79308)
		(width 0.10795)
		(layer "F.Cu")
		(net "IRQ_OC_DETECT_N")
	)
	(segment
		(start 421.591486 -21.325078)
		(end 421.846502 -21.580094)
		(width 0.10795)
		(layer "F.Cu")
		(net "IRQ_OC_DETECT_N")
	)
	(segment
		(start 20.9423 -83.312)
		(end 20.9423 -82.74558)
		(width 0.10795)
		(layer "F.Cu")
		(net "IRQ_OC_DETECT_N")
	)
	(via
		(at 19.7104 -81.4832)
		(size 0.508)
		(drill 0.254)
		(layers "F.Cu" "B.Cu")
		(net "IRQ_OC_DETECT_N")
	)
	(via
		(at 423.418 -14.224)
		(size 0.6604)
		(drill 0.3302)
		(layers "F.Cu" "B.Cu")
		(net "IRQ_OC_DETECT_N")
	)
	(via
		(at 337.300824 -138.59637)
		(size 0.508)
		(drill 0.254)
		(layers "F.Cu" "B.Cu")
		(net "IRQ_OC_DETECT_N")
	)
	(via
		(at 420.7764 -18.697956)
		(size 0.508)
		(drill 0.254)
		(layers "F.Cu" "B.Cu")
		(net "IRQ_OC_DETECT_N")
	)
	(via
		(at 424.053 -13.081)
		(size 0.508)
		(drill 0.254)
		(layers "F.Cu" "B.Cu")
		(net "IRQ_OC_DETECT_N")
	)
	(via
		(at 186.055 -155.194)
		(size 0.508)
		(drill 0.254)
		(layers "F.Cu" "B.Cu")
		(net "IRQ_OC_DETECT_N")
	)
	(via
		(at 357.602536 -130.238754)
		(size 0.508)
		(drill 0.254)
		(layers "F.Cu" "B.Cu")
		(net "IRQ_OC_DETECT_N")
	)
	(via
		(at 386.74675 -95.888556)
		(size 0.508)
		(drill 0.254)
		(layers "F.Cu" "B.Cu")
		(net "IRQ_OC_DETECT_N")
	)
	(via
		(at 369.976908 -123.409456)
		(size 0.508)
		(drill 0.254)
		(layers "F.Cu" "B.Cu")
		(net "IRQ_OC_DETECT_N")
	)
	(segment
		(start 420.7764 -17.743424)
		(end 422.402 -16.117824)
		(width 0.10795)
		(layer "B.Cu")
		(net "IRQ_OC_DETECT_N")
	)
	(segment
		(start 423.081958 -14.560042)
		(end 423.418 -14.224)
		(width 0.10795)
		(layer "B.Cu")
		(net "IRQ_OC_DETECT_N")
	)
	(segment
		(start 422.402 -16.117824)
		(end 422.402 -15.748)
		(width 0.10795)
		(layer "B.Cu")
		(net "IRQ_OC_DETECT_N")
	)
	(segment
		(start 422.402 -15.748)
		(end 423.081958 -15.068042)
		(width 0.10795)
		(layer "B.Cu")
		(net "IRQ_OC_DETECT_N")
	)
	(segment
		(start 420.7764 -18.697956)
		(end 420.7764 -17.743424)
		(width 0.10795)
		(layer "B.Cu")
		(net "IRQ_OC_DETECT_N")
	)
	(segment
		(start 423.081958 -15.068042)
		(end 423.081958 -14.560042)
		(width 0.10795)
		(layer "B.Cu")
		(net "IRQ_OC_DETECT_N")
	)
	(segment
		(start 423.418 -14.224)
		(end 424.053 -13.589)
		(width 0.10795)
		(layer "B.Cu")
		(net "IRQ_OC_DETECT_N")
	)
	(segment
		(start 19.7104 -81.4832)
		(end 19.3802 -81.153)
		(width 0.10795)
		(layer "B.Cu")
		(net "IRQ_OC_DETECT_N")
	)
	(segment
		(start 424.053 -13.589)
		(end 424.053 -13.081)
		(width 0.10795)
		(layer "B.Cu")
		(net "IRQ_OC_DETECT_N")
	)
	(segment
		(start 19.3802 -81.153)
		(end 17.145 -81.153)
		(width 0.10795)
		(layer "B.Cu")
		(net "IRQ_OC_DETECT_N")
	)
	(segment
		(start 347.7006 -135.32866)
		(end 348.1959 -134.83336)
		(width 0.089408)
		(layer "In2.Cu")
		(net "IRQ_OC_DETECT_N")
	)
	(segment
		(start 342.865456 -135.32866)
		(end 347.7006 -135.32866)
		(width 0.089408)
		(layer "In2.Cu")
		(net "IRQ_OC_DETECT_N")
	)
	(segment
		(start 338.19846 -137.698734)
		(end 340.495382 -137.698734)
		(width 0.089408)
		(layer "In2.Cu")
		(net "IRQ_OC_DETECT_N")
	)
	(segment
		(start 357.602536 -131.752848)
		(end 357.602536 -130.238754)
		(width 0.089408)
		(layer "In2.Cu")
		(net "IRQ_OC_DETECT_N")
	)
	(segment
		(start 354.522024 -134.83336)
		(end 357.602536 -131.752848)
		(width 0.089408)
		(layer "In2.Cu")
		(net "IRQ_OC_DETECT_N")
	)
	(segment
		(start 340.495382 -137.698734)
		(end 342.865456 -135.32866)
		(width 0.089408)
		(layer "In2.Cu")
		(net "IRQ_OC_DETECT_N")
	)
	(segment
		(start 337.300824 -138.59637)
		(end 338.19846 -137.698734)
		(width 0.089408)
		(layer "In2.Cu")
		(net "IRQ_OC_DETECT_N")
	)
	(segment
		(start 348.1959 -134.83336)
		(end 354.522024 -134.83336)
		(width 0.089408)
		(layer "In2.Cu")
		(net "IRQ_OC_DETECT_N")
	)
	(segment
		(start 383.67843 -96.774762)
		(end 384.36677 -96.086422)
		(width 0.089408)
		(layer "In4.Cu")
		(net "IRQ_OC_DETECT_N")
	)
	(segment
		(start 375.937272 -107.281726)
		(end 376.411998 -106.807)
		(width 0.089408)
		(layer "In4.Cu")
		(net "IRQ_OC_DETECT_N")
	)
	(segment
		(start 376.540014 -106.807)
		(end 376.8725 -106.474514)
		(width 0.089408)
		(layer "In4.Cu")
		(net "IRQ_OC_DETECT_N")
	)
	(segment
		(start 384.36677 -95.723202)
		(end 384.600196 -95.489776)
		(width 0.089408)
		(layer "In4.Cu")
		(net "IRQ_OC_DETECT_N")
	)
	(segment
		(start 375.50725 -112.53597)
		(end 375.50725 -111.88573)
		(width 0.089408)
		(layer "In4.Cu")
		(net "IRQ_OC_DETECT_N")
	)
	(segment
		(start 375.937272 -111.455708)
		(end 375.937272 -107.281726)
		(width 0.089408)
		(layer "In4.Cu")
		(net "IRQ_OC_DETECT_N")
	)
	(segment
		(start 384.600196 -95.489776)
		(end 386.34797 -95.489776)
		(width 0.089408)
		(layer "In4.Cu")
		(net "IRQ_OC_DETECT_N")
	)
	(segment
		(start 376.8725 -106.474514)
		(end 376.8725 -105.852976)
		(width 0.089408)
		(layer "In4.Cu")
		(net "IRQ_OC_DETECT_N")
	)
	(segment
		(start 377.3678 -104.373172)
		(end 377.726956 -104.014016)
		(width 0.089408)
		(layer "In4.Cu")
		(net "IRQ_OC_DETECT_N")
	)
	(segment
		(start 369.976908 -123.409456)
		(end 370.218716 -123.651264)
		(width 0.089408)
		(layer "In4.Cu")
		(net "IRQ_OC_DETECT_N")
	)
	(segment
		(start 379.71603 -101.732842)
		(end 379.41377 -101.430582)
		(width 0.089408)
		(layer "In4.Cu")
		(net "IRQ_OC_DETECT_N")
	)
	(segment
		(start 383.67843 -96.91243)
		(end 383.67843 -96.774762)
		(width 0.089408)
		(layer "In4.Cu")
		(net "IRQ_OC_DETECT_N")
	)
	(segment
		(start 384.36677 -96.086422)
		(end 384.36677 -95.723202)
		(width 0.089408)
		(layer "In4.Cu")
		(net "IRQ_OC_DETECT_N")
	)
	(segment
		(start 378.841 -103.66502)
		(end 378.841 -103.3018)
		(width 0.089408)
		(layer "In4.Cu")
		(net "IRQ_OC_DETECT_N")
	)
	(segment
		(start 379.71603 -102.42677)
		(end 379.71603 -101.732842)
		(width 0.089408)
		(layer "In4.Cu")
		(net "IRQ_OC_DETECT_N")
	)
	(segment
		(start 380.21133 -98.93173)
		(end 379.90907 -98.62947)
		(width 0.089408)
		(layer "In4.Cu")
		(net "IRQ_OC_DETECT_N")
	)
	(segment
		(start 377.3678 -105.357676)
		(end 377.3678 -104.373172)
		(width 0.089408)
		(layer "In4.Cu")
		(net "IRQ_OC_DETECT_N")
	)
	(segment
		(start 370.218716 -123.651264)
		(end 371.08511 -123.651264)
		(width 0.089408)
		(layer "In4.Cu")
		(net "IRQ_OC_DETECT_N")
	)
	(segment
		(start 380.21133 -97.77095)
		(end 380.21133 -97.633282)
		(width 0.089408)
		(layer "In4.Cu")
		(net "IRQ_OC_DETECT_N")
	)
	(segment
		(start 379.90907 -98.62947)
		(end 379.90907 -98.07321)
		(width 0.089408)
		(layer "In4.Cu")
		(net "IRQ_OC_DETECT_N")
	)
	(segment
		(start 379.71603 -100.34651)
		(end 379.71603 -99.98329)
		(width 0.089408)
		(layer "In4.Cu")
		(net "IRQ_OC_DETECT_N")
	)
	(segment
		(start 383.445004 -97.145856)
		(end 383.67843 -96.91243)
		(width 0.089408)
		(layer "In4.Cu")
		(net "IRQ_OC_DETECT_N")
	)
	(segment
		(start 374.937528 -119.798846)
		(end 374.937528 -113.105692)
		(width 0.089408)
		(layer "In4.Cu")
		(net "IRQ_OC_DETECT_N")
	)
	(segment
		(start 386.34797 -95.489776)
		(end 386.74675 -95.888556)
		(width 0.089408)
		(layer "In4.Cu")
		(net "IRQ_OC_DETECT_N")
	)
	(segment
		(start 371.08511 -123.651264)
		(end 374.937528 -119.798846)
		(width 0.089408)
		(layer "In4.Cu")
		(net "IRQ_OC_DETECT_N")
	)
	(segment
		(start 378.492004 -104.014016)
		(end 378.841 -103.66502)
		(width 0.089408)
		(layer "In4.Cu")
		(net "IRQ_OC_DETECT_N")
	)
	(segment
		(start 380.21133 -97.633282)
		(end 380.698756 -97.145856)
		(width 0.089408)
		(layer "In4.Cu")
		(net "IRQ_OC_DETECT_N")
	)
	(segment
		(start 379.41377 -100.64877)
		(end 379.71603 -100.34651)
		(width 0.089408)
		(layer "In4.Cu")
		(net "IRQ_OC_DETECT_N")
	)
	(segment
		(start 377.726956 -104.014016)
		(end 378.492004 -104.014016)
		(width 0.089408)
		(layer "In4.Cu")
		(net "IRQ_OC_DETECT_N")
	)
	(segment
		(start 376.8725 -105.852976)
		(end 377.3678 -105.357676)
		(width 0.089408)
		(layer "In4.Cu")
		(net "IRQ_OC_DETECT_N")
	)
	(segment
		(start 378.841 -103.3018)
		(end 379.71603 -102.42677)
		(width 0.089408)
		(layer "In4.Cu")
		(net "IRQ_OC_DETECT_N")
	)
	(segment
		(start 380.21133 -99.48799)
		(end 380.21133 -98.93173)
		(width 0.089408)
		(layer "In4.Cu")
		(net "IRQ_OC_DETECT_N")
	)
	(segment
		(start 374.937528 -113.105692)
		(end 375.50725 -112.53597)
		(width 0.089408)
		(layer "In4.Cu")
		(net "IRQ_OC_DETECT_N")
	)
	(segment
		(start 379.41377 -101.430582)
		(end 379.41377 -100.64877)
		(width 0.089408)
		(layer "In4.Cu")
		(net "IRQ_OC_DETECT_N")
	)
	(segment
		(start 380.698756 -97.145856)
		(end 383.445004 -97.145856)
		(width 0.089408)
		(layer "In4.Cu")
		(net "IRQ_OC_DETECT_N")
	)
	(segment
		(start 379.71603 -99.98329)
		(end 380.21133 -99.48799)
		(width 0.089408)
		(layer "In4.Cu")
		(net "IRQ_OC_DETECT_N")
	)
	(segment
		(start 379.90907 -98.07321)
		(end 380.21133 -97.77095)
		(width 0.089408)
		(layer "In4.Cu")
		(net "IRQ_OC_DETECT_N")
	)
	(segment
		(start 375.50725 -111.88573)
		(end 375.937272 -111.455708)
		(width 0.089408)
		(layer "In4.Cu")
		(net "IRQ_OC_DETECT_N")
	)
	(segment
		(start 376.411998 -106.807)
		(end 376.540014 -106.807)
		(width 0.089408)
		(layer "In4.Cu")
		(net "IRQ_OC_DETECT_N")
	)
	(segment
		(start 280.401268 -156.688028)
		(end 280.139902 -156.426662)
		(width 0.089408)
		(layer "In9.Cu")
		(net "IRQ_OC_DETECT_N")
	)
	(segment
		(start 328.066146 -156.688028)
		(end 280.401268 -156.688028)
		(width 0.089408)
		(layer "In9.Cu")
		(net "IRQ_OC_DETECT_N")
	)
	(segment
		(start 264.324338 -156.426662)
		(end 264.0203 -156.7307)
		(width 0.089408)
		(layer "In9.Cu")
		(net "IRQ_OC_DETECT_N")
	)
	(segment
		(start 329.004422 -155.749752)
		(end 328.066146 -156.688028)
		(width 0.089408)
		(layer "In9.Cu")
		(net "IRQ_OC_DETECT_N")
	)
	(segment
		(start 337.300824 -138.59637)
		(end 337.128612 -138.768582)
		(width 0.089408)
		(layer "In9.Cu")
		(net "IRQ_OC_DETECT_N")
	)
	(segment
		(start 370.374164 -123.806712)
		(end 370.374164 -124.506736)
		(width 0.089408)
		(layer "In9.Cu")
		(net "IRQ_OC_DETECT_N")
	)
	(segment
		(start 264.0203 -156.7307)
		(end 188.236352 -156.7307)
		(width 0.089408)
		(layer "In9.Cu")
		(net "IRQ_OC_DETECT_N")
	)
	(segment
		(start 369.217702 -125.913896)
		(end 366.480598 -128.651)
		(width 0.089408)
		(layer "In9.Cu")
		(net "IRQ_OC_DETECT_N")
	)
	(segment
		(start 280.139902 -156.426662)
		(end 264.324338 -156.426662)
		(width 0.089408)
		(layer "In9.Cu")
		(net "IRQ_OC_DETECT_N")
	)
	(segment
		(start 366.480598 -128.651)
		(end 359.3846 -128.651)
		(width 0.089408)
		(layer "In9.Cu")
		(net "IRQ_OC_DETECT_N")
	)
	(segment
		(start 370.374164 -124.506736)
		(end 369.217702 -125.663198)
		(width 0.089408)
		(layer "In9.Cu")
		(net "IRQ_OC_DETECT_N")
	)
	(segment
		(start 359.3846 -128.651)
		(end 357.796846 -130.238754)
		(width 0.089408)
		(layer "In9.Cu")
		(net "IRQ_OC_DETECT_N")
	)
	(segment
		(start 188.236352 -156.7307)
		(end 186.699652 -155.194)
		(width 0.089408)
		(layer "In9.Cu")
		(net "IRQ_OC_DETECT_N")
	)
	(segment
		(start 369.217702 -125.663198)
		(end 369.217702 -125.913896)
		(width 0.089408)
		(layer "In9.Cu")
		(net "IRQ_OC_DETECT_N")
	)
	(segment
		(start 186.699652 -155.194)
		(end 186.055 -155.194)
		(width 0.089408)
		(layer "In9.Cu")
		(net "IRQ_OC_DETECT_N")
	)
	(segment
		(start 336.542634 -155.749752)
		(end 329.004422 -155.749752)
		(width 0.089408)
		(layer "In9.Cu")
		(net "IRQ_OC_DETECT_N")
	)
	(segment
		(start 337.128612 -155.163774)
		(end 336.542634 -155.749752)
		(width 0.089408)
		(layer "In9.Cu")
		(net "IRQ_OC_DETECT_N")
	)
	(segment
		(start 369.976908 -123.409456)
		(end 370.374164 -123.806712)
		(width 0.089408)
		(layer "In9.Cu")
		(net "IRQ_OC_DETECT_N")
	)
	(segment
		(start 337.128612 -138.768582)
		(end 337.128612 -155.163774)
		(width 0.089408)
		(layer "In9.Cu")
		(net "IRQ_OC_DETECT_N")
	)
	(segment
		(start 357.796846 -130.238754)
		(end 357.602536 -130.238754)
		(width 0.089408)
		(layer "In9.Cu")
		(net "IRQ_OC_DETECT_N")
	)
	(segment
		(start 371.42547 -44.765214)
		(end 373.18569 -46.525434)
		(width 0.089408)
		(layer "In11.Cu")
		(net "IRQ_OC_DETECT_N")
	)
	(segment
		(start 183.72455 -148.900896)
		(end 167.971216 -148.900896)
		(width 0.089408)
		(layer "In11.Cu")
		(net "IRQ_OC_DETECT_N")
	)
	(segment
		(start 385.586224 -92.43568)
		(end 385.586224 -93.556074)
		(width 0.089408)
		(layer "In11.Cu")
		(net "IRQ_OC_DETECT_N")
	)
	(segment
		(start 424.053 -13.081)
		(end 423.586402 -13.547598)
		(width 0.089408)
		(layer "In11.Cu")
		(net "IRQ_OC_DETECT_N")
	)
	(segment
		(start 385.313174 -72.270112)
		(end 385.780534 -72.270112)
		(width 0.089408)
		(layer "In11.Cu")
		(net "IRQ_OC_DETECT_N")
	)
	(segment
		(start 186.055 -155.194)
		(end 186.055 -154.051)
		(width 0.089408)
		(layer "In11.Cu")
		(net "IRQ_OC_DETECT_N")
	)
	(segment
		(start 19.7104 -85.28558)
		(end 19.7104 -81.4832)
		(width 0.089408)
		(layer "In11.Cu")
		(net "IRQ_OC_DETECT_N")
	)
	(segment
		(start 27.90444 -132.02539)
		(end 28.01874 -131.91109)
		(width 0.089408)
		(layer "In11.Cu")
		(net "IRQ_OC_DETECT_N")
	)
	(segment
		(start 30.42031 -157.211014)
		(end 27.90444 -154.695144)
		(width 0.089408)
		(layer "In11.Cu")
		(net "IRQ_OC_DETECT_N")
	)
	(segment
		(start 156.677868 -157.203902)
		(end 112.788192 -157.203902)
		(width 0.089408)
		(layer "In11.Cu")
		(net "IRQ_OC_DETECT_N")
	)
	(segment
		(start 28.01874 -130.51536)
		(end 28.106624 -130.427476)
		(width 0.089408)
		(layer "In11.Cu")
		(net "IRQ_OC_DETECT_N")
	)
	(segment
		(start 373.185436 -46.892464)
		(end 377.61418 -51.321208)
		(width 0.089408)
		(layer "In11.Cu")
		(net "IRQ_OC_DETECT_N")
	)
	(segment
		(start 184.302654 -149.479)
		(end 183.72455 -148.900896)
		(width 0.089408)
		(layer "In11.Cu")
		(net "IRQ_OC_DETECT_N")
	)
	(segment
		(start 372.917974 -21.720302)
		(end 372.917974 -26.998676)
		(width 0.089408)
		(layer "In11.Cu")
		(net "IRQ_OC_DETECT_N")
	)
	(segment
		(start 185.789824 -153.785824)
		(end 185.789824 -153.046176)
		(width 0.089408)
		(layer "In11.Cu")
		(net "IRQ_OC_DETECT_N")
	)
	(segment
		(start 373.18569 -46.649894)
		(end 373.185436 -46.650148)
		(width 0.089408)
		(layer "In11.Cu")
		(net "IRQ_OC_DETECT_N")
	)
	(segment
		(start 20.121118 -85.696298)
		(end 19.7104 -85.28558)
		(width 0.089408)
		(layer "In11.Cu")
		(net "IRQ_OC_DETECT_N")
	)
	(segment
		(start 27.90444 -154.695144)
		(end 27.90444 -132.02539)
		(width 0.089408)
		(layer "In11.Cu")
		(net "IRQ_OC_DETECT_N")
	)
	(segment
		(start 420.704772 -13.547598)
		(end 418.52215 -11.364976)
		(width 0.089408)
		(layer "In11.Cu")
		(net "IRQ_OC_DETECT_N")
	)
	(segment
		(start 379.489208 -51.321208)
		(end 384.010154 -55.842154)
		(width 0.089408)
		(layer "In11.Cu")
		(net "IRQ_OC_DETECT_N")
	)
	(segment
		(start 27.724608 -127.191008)
		(end 27.724608 -125.813566)
		(width 0.089408)
		(layer "In11.Cu")
		(net "IRQ_OC_DETECT_N")
	)
	(segment
		(start 385.586224 -93.556074)
		(end 386.74675 -94.7166)
		(width 0.089408)
		(layer "In11.Cu")
		(net "IRQ_OC_DETECT_N")
	)
	(segment
		(start 381.56896 -13.069316)
		(end 372.917974 -21.720302)
		(width 0.089408)
		(layer "In11.Cu")
		(net "IRQ_OC_DETECT_N")
	)
	(segment
		(start 22.053296 -98.97618)
		(end 22.7076 -98.321876)
		(width 0.089408)
		(layer "In11.Cu")
		(net "IRQ_OC_DETECT_N")
	)
	(segment
		(start 399.93316 -13.069316)
		(end 381.56896 -13.069316)
		(width 0.089408)
		(layer "In11.Cu")
		(net "IRQ_OC_DETECT_N")
	)
	(segment
		(start 22.7076 -89.287858)
		(end 20.121118 -86.701376)
		(width 0.089408)
		(layer "In11.Cu")
		(net "IRQ_OC_DETECT_N")
	)
	(segment
		(start 28.106624 -127.573024)
		(end 27.724608 -127.191008)
		(width 0.089408)
		(layer "In11.Cu")
		(net "IRQ_OC_DETECT_N")
	)
	(segment
		(start 386.592572 -91.429332)
		(end 385.586224 -92.43568)
		(width 0.089408)
		(layer "In11.Cu")
		(net "IRQ_OC_DETECT_N")
	)
	(segment
		(start 385.780534 -72.270112)
		(end 386.103622 -72.5932)
		(width 0.089408)
		(layer "In11.Cu")
		(net "IRQ_OC_DETECT_N")
	)
	(segment
		(start 377.61418 -51.321208)
		(end 379.489208 -51.321208)
		(width 0.089408)
		(layer "In11.Cu")
		(net "IRQ_OC_DETECT_N")
	)
	(segment
		(start 386.78231 -85.41893)
		(end 386.78231 -89.28354)
		(width 0.089408)
		(layer "In11.Cu")
		(net "IRQ_OC_DETECT_N")
	)
	(segment
		(start 185.993786 -150.251668)
		(end 185.221118 -149.479)
		(width 0.089408)
		(layer "In11.Cu")
		(net "IRQ_OC_DETECT_N")
	)
	(segment
		(start 164.441632 -152.43048)
		(end 161.103564 -152.43048)
		(width 0.089408)
		(layer "In11.Cu")
		(net "IRQ_OC_DETECT_N")
	)
	(segment
		(start 383.91084 -64.95796)
		(end 384.532124 -65.579244)
		(width 0.089408)
		(layer "In11.Cu")
		(net "IRQ_OC_DETECT_N")
	)
	(segment
		(start 112.788192 -157.203902)
		(end 112.78108 -157.211014)
		(width 0.089408)
		(layer "In11.Cu")
		(net "IRQ_OC_DETECT_N")
	)
	(segment
		(start 22.053296 -99.485958)
		(end 22.053296 -98.97618)
		(width 0.089408)
		(layer "In11.Cu")
		(net "IRQ_OC_DETECT_N")
	)
	(segment
		(start 384.010154 -59.989466)
		(end 383.540762 -60.458858)
		(width 0.089408)
		(layer "In11.Cu")
		(net "IRQ_OC_DETECT_N")
	)
	(segment
		(start 383.91084 -61.79566)
		(end 383.91084 -64.95796)
		(width 0.089408)
		(layer "In11.Cu")
		(net "IRQ_OC_DETECT_N")
	)
	(segment
		(start 161.103564 -152.43048)
		(end 158.156148 -155.377896)
		(width 0.089408)
		(layer "In11.Cu")
		(net "IRQ_OC_DETECT_N")
	)
	(segment
		(start 371.42547 -34.16681)
		(end 371.42547 -44.765214)
		(width 0.089408)
		(layer "In11.Cu")
		(net "IRQ_OC_DETECT_N")
	)
	(segment
		(start 28.01874 -131.91109)
		(end 28.01874 -130.51536)
		(width 0.089408)
		(layer "In11.Cu")
		(net "IRQ_OC_DETECT_N")
	)
	(segment
		(start 423.586402 -13.547598)
		(end 420.704772 -13.547598)
		(width 0.089408)
		(layer "In11.Cu")
		(net "IRQ_OC_DETECT_N")
	)
	(segment
		(start 185.221118 -149.479)
		(end 184.302654 -149.479)
		(width 0.089408)
		(layer "In11.Cu")
		(net "IRQ_OC_DETECT_N")
	)
	(segment
		(start 28.106624 -130.427476)
		(end 28.106624 -127.573024)
		(width 0.089408)
		(layer "In11.Cu")
		(net "IRQ_OC_DETECT_N")
	)
	(segment
		(start 23.402036 -100.834698)
		(end 22.053296 -99.485958)
		(width 0.089408)
		(layer "In11.Cu")
		(net "IRQ_OC_DETECT_N")
	)
	(segment
		(start 20.121118 -86.701376)
		(end 20.121118 -85.696298)
		(width 0.089408)
		(layer "In11.Cu")
		(net "IRQ_OC_DETECT_N")
	)
	(segment
		(start 22.7076 -98.321876)
		(end 22.7076 -89.287858)
		(width 0.089408)
		(layer "In11.Cu")
		(net "IRQ_OC_DETECT_N")
	)
	(segment
		(start 167.971216 -148.900896)
		(end 164.441632 -152.43048)
		(width 0.089408)
		(layer "In11.Cu")
		(net "IRQ_OC_DETECT_N")
	)
	(segment
		(start 185.789824 -153.046176)
		(end 185.993786 -152.842214)
		(width 0.089408)
		(layer "In11.Cu")
		(net "IRQ_OC_DETECT_N")
	)
	(segment
		(start 373.185436 -46.650148)
		(end 373.185436 -46.892464)
		(width 0.089408)
		(layer "In11.Cu")
		(net "IRQ_OC_DETECT_N")
	)
	(segment
		(start 401.6375 -11.364976)
		(end 399.93316 -13.069316)
		(width 0.089408)
		(layer "In11.Cu")
		(net "IRQ_OC_DETECT_N")
	)
	(segment
		(start 373.18569 -46.525434)
		(end 373.18569 -46.649894)
		(width 0.089408)
		(layer "In11.Cu")
		(net "IRQ_OC_DETECT_N")
	)
	(segment
		(start 158.156148 -155.377896)
		(end 158.156148 -155.725622)
		(width 0.089408)
		(layer "In11.Cu")
		(net "IRQ_OC_DETECT_N")
	)
	(segment
		(start 28.322778 -112.556036)
		(end 23.402036 -107.635294)
		(width 0.089408)
		(layer "In11.Cu")
		(net "IRQ_OC_DETECT_N")
	)
	(segment
		(start 386.131816 -84.768436)
		(end 386.78231 -85.41893)
		(width 0.089408)
		(layer "In11.Cu")
		(net "IRQ_OC_DETECT_N")
	)
	(segment
		(start 384.010154 -55.842154)
		(end 384.010154 -59.989466)
		(width 0.089408)
		(layer "In11.Cu")
		(net "IRQ_OC_DETECT_N")
	)
	(segment
		(start 384.532124 -65.579244)
		(end 384.532124 -71.489062)
		(width 0.089408)
		(layer "In11.Cu")
		(net "IRQ_OC_DETECT_N")
	)
	(segment
		(start 383.540762 -61.425582)
		(end 383.91084 -61.79566)
		(width 0.089408)
		(layer "In11.Cu")
		(net "IRQ_OC_DETECT_N")
	)
	(segment
		(start 386.74675 -94.7166)
		(end 386.74675 -95.888556)
		(width 0.089408)
		(layer "In11.Cu")
		(net "IRQ_OC_DETECT_N")
	)
	(segment
		(start 112.78108 -157.211014)
		(end 30.42031 -157.211014)
		(width 0.089408)
		(layer "In11.Cu")
		(net "IRQ_OC_DETECT_N")
	)
	(segment
		(start 383.540762 -60.458858)
		(end 383.540762 -61.425582)
		(width 0.089408)
		(layer "In11.Cu")
		(net "IRQ_OC_DETECT_N")
	)
	(segment
		(start 418.52215 -11.364976)
		(end 401.6375 -11.364976)
		(width 0.089408)
		(layer "In11.Cu")
		(net "IRQ_OC_DETECT_N")
	)
	(segment
		(start 386.131816 -82.531204)
		(end 386.131816 -84.768436)
		(width 0.089408)
		(layer "In11.Cu")
		(net "IRQ_OC_DETECT_N")
	)
	(segment
		(start 27.724608 -125.813566)
		(end 28.322778 -125.215396)
		(width 0.089408)
		(layer "In11.Cu")
		(net "IRQ_OC_DETECT_N")
	)
	(segment
		(start 372.917974 -26.998676)
		(end 371.135656 -28.780994)
		(width 0.089408)
		(layer "In11.Cu")
		(net "IRQ_OC_DETECT_N")
	)
	(segment
		(start 371.135656 -33.876996)
		(end 371.42547 -34.16681)
		(width 0.089408)
		(layer "In11.Cu")
		(net "IRQ_OC_DETECT_N")
	)
	(segment
		(start 185.993786 -152.842214)
		(end 185.993786 -150.251668)
		(width 0.089408)
		(layer "In11.Cu")
		(net "IRQ_OC_DETECT_N")
	)
	(segment
		(start 28.322778 -125.215396)
		(end 28.322778 -112.556036)
		(width 0.089408)
		(layer "In11.Cu")
		(net "IRQ_OC_DETECT_N")
	)
	(segment
		(start 23.402036 -107.635294)
		(end 23.402036 -100.834698)
		(width 0.089408)
		(layer "In11.Cu")
		(net "IRQ_OC_DETECT_N")
	)
	(segment
		(start 386.103622 -72.5932)
		(end 386.103622 -82.50301)
		(width 0.089408)
		(layer "In11.Cu")
		(net "IRQ_OC_DETECT_N")
	)
	(segment
		(start 186.055 -154.051)
		(end 185.789824 -153.785824)
		(width 0.089408)
		(layer "In11.Cu")
		(net "IRQ_OC_DETECT_N")
	)
	(segment
		(start 384.532124 -71.489062)
		(end 385.313174 -72.270112)
		(width 0.089408)
		(layer "In11.Cu")
		(net "IRQ_OC_DETECT_N")
	)
	(segment
		(start 386.103622 -82.50301)
		(end 386.131816 -82.531204)
		(width 0.089408)
		(layer "In11.Cu")
		(net "IRQ_OC_DETECT_N")
	)
	(segment
		(start 371.135656 -28.780994)
		(end 371.135656 -33.876996)
		(width 0.089408)
		(layer "In11.Cu")
		(net "IRQ_OC_DETECT_N")
	)
	(segment
		(start 158.156148 -155.725622)
		(end 156.677868 -157.203902)
		(width 0.089408)
		(layer "In11.Cu")
		(net "IRQ_OC_DETECT_N")
	)
	(segment
		(start 386.78231 -89.28354)
		(end 386.592572 -89.473278)
		(width 0.089408)
		(layer "In11.Cu")
		(net "IRQ_OC_DETECT_N")
	)
	(segment
		(start 386.592572 -89.473278)
		(end 386.592572 -91.429332)
		(width 0.089408)
		(layer "In11.Cu")
		(net "IRQ_OC_DETECT_N")
	)
	(segment
		(start 455.422 -37.846)
		(end 456.16368 -37.846)
		(width 0.10795)
		(layer "F.Cu")
		(net "FM_HEARTBEAT_LED")
	)
	(segment
		(start 455.40549 -36.522406)
		(end 455.40549 -37.317426)
		(width 0.10795)
		(layer "F.Cu")
		(net "FM_HEARTBEAT_LED")
	)
	(segment
		(start 455.94778 -35.814)
		(end 455.506074 -35.814)
		(width 0.10795)
		(layer "F.Cu")
		(net "FM_HEARTBEAT_LED")
	)
	(segment
		(start 455.40549 -37.317426)
		(end 455.422 -37.333936)
		(width 0.10795)
		(layer "F.Cu")
		(net "FM_HEARTBEAT_LED")
	)
	(segment
		(start 455.506074 -35.814)
		(end 455.40549 -35.914584)
		(width 0.10795)
		(layer "F.Cu")
		(net "FM_HEARTBEAT_LED")
	)
	(segment
		(start 455.40549 -35.914584)
		(end 455.40549 -36.522406)
		(width 0.10795)
		(layer "F.Cu")
		(net "FM_HEARTBEAT_LED")
	)
	(segment
		(start 456.05573 -35.92195)
		(end 455.94778 -35.814)
		(width 0.10795)
		(layer "F.Cu")
		(net "FM_HEARTBEAT_LED")
	)
	(segment
		(start 455.422 -37.333936)
		(end 455.422 -37.846)
		(width 0.10795)
		(layer "F.Cu")
		(net "FM_HEARTBEAT_LED")
	)
	(segment
		(start 456.05573 -36.522406)
		(end 456.05573 -35.92195)
		(width 0.10795)
		(layer "F.Cu")
		(net "FM_HEARTBEAT_LED")
	)
	(segment
		(start 456.16368 -37.846)
		(end 456.62088 -38.3032)
		(width 0.10795)
		(layer "F.Cu")
		(net "FM_HEARTBEAT_LED")
	)
	(via
		(at 456.62088 -38.3032)
		(size 0.762)
		(drill 0.381)
		(layers "F.Cu" "B.Cu")
		(net "FM_HEARTBEAT_LED")
	)
	(segment
		(start 407.247598 -39.002716)
		(end 407.233374 -38.988492)
		(width 0.10795)
		(layer "F.Cu")
		(net "FM_FORCE_ADR_N")
	)
	(segment
		(start 406.932638 -39.002716)
		(end 404.711662 -39.002716)
		(width 0.10795)
		(layer "F.Cu")
		(net "FM_FORCE_ADR_N")
	)
	(segment
		(start 374.344692 -70.295262)
		(end 373.944896 -70.695058)
		(width 0.10795)
		(layer "F.Cu")
		(net "FM_FORCE_ADR_N")
	)
	(segment
		(start 404.711662 -39.002716)
		(end 404.434802 -38.725856)
		(width 0.10795)
		(layer "F.Cu")
		(net "FM_FORCE_ADR_N")
	)
	(segment
		(start 389.71855 -98.69424)
		(end 389.7376 -98.68535)
		(width 0.10795)
		(layer "F.Cu")
		(net "FM_FORCE_ADR_N")
	)
	(segment
		(start 407.890218 -38.534594)
		(end 407.422096 -39.002716)
		(width 0.10795)
		(layer "F.Cu")
		(net "FM_FORCE_ADR_N")
	)
	(segment
		(start 389.7376 -98.68535)
		(end 390.21385 -98.464116)
		(width 0.10795)
		(layer "F.Cu")
		(net "FM_FORCE_ADR_N")
	)
	(segment
		(start 407.233374 -38.988492)
		(end 406.946862 -38.988492)
		(width 0.10795)
		(layer "F.Cu")
		(net "FM_FORCE_ADR_N")
	)
	(segment
		(start 404.434802 -38.725856)
		(end 404.004526 -38.725856)
		(width 0.10795)
		(layer "F.Cu")
		(net "FM_FORCE_ADR_N")
	)
	(segment
		(start 406.946862 -38.988492)
		(end 406.932638 -39.002716)
		(width 0.10795)
		(layer "F.Cu")
		(net "FM_FORCE_ADR_N")
	)
	(segment
		(start 407.422096 -39.002716)
		(end 407.247598 -39.002716)
		(width 0.10795)
		(layer "F.Cu")
		(net "FM_FORCE_ADR_N")
	)
	(via
		(at 404.004526 -38.725856)
		(size 0.4572)
		(drill 0.2032)
		(layers "F.Cu" "B.Cu")
		(net "FM_FORCE_ADR_N")
	)
	(via
		(at 404.5458 -39.2684)
		(size 0.6604)
		(drill 0.3302)
		(layers "F.Cu" "B.Cu")
		(net "FM_FORCE_ADR_N")
	)
	(via
		(at 374.344692 -70.295262)
		(size 0.4572)
		(drill 0.2032)
		(layers "F.Cu" "B.Cu")
		(net "FM_FORCE_ADR_N")
	)
	(via
		(at 390.21385 -98.464116)
		(size 0.508)
		(drill 0.254)
		(layers "F.Cu" "B.Cu")
		(net "FM_FORCE_ADR_N")
	)
	(via
		(at 379.945392 -38.2524)
		(size 0.508)
		(drill 0.254)
		(layers "F.Cu" "B.Cu")
		(net "FM_FORCE_ADR_N")
	)
	(segment
		(start 404.5458 -39.26713)
		(end 404.004526 -38.725856)
		(width 0.089408)
		(layer "B.Cu")
		(net "FM_FORCE_ADR_N")
	)
	(segment
		(start 374.7389 -68.0847)
		(end 375.412 -67.4116)
		(width 0.10795)
		(layer "B.Cu")
		(net "FM_FORCE_ADR_N")
	)
	(segment
		(start 404.5458 -39.2684)
		(end 404.5458 -39.26713)
		(width 0.089408)
		(layer "B.Cu")
		(net "FM_FORCE_ADR_N")
	)
	(segment
		(start 374.7389 -69.901054)
		(end 374.7389 -68.0847)
		(width 0.10795)
		(layer "B.Cu")
		(net "FM_FORCE_ADR_N")
	)
	(segment
		(start 374.344692 -70.295262)
		(end 374.7389 -69.901054)
		(width 0.10795)
		(layer "B.Cu")
		(net "FM_FORCE_ADR_N")
	)
	(segment
		(start 375.412 -67.4116)
		(end 375.412 -66.929)
		(width 0.10795)
		(layer "B.Cu")
		(net "FM_FORCE_ADR_N")
	)
	(segment
		(start 373.41048 -70.701408)
		(end 373.938546 -70.701408)
		(width 0.089408)
		(layer "In2.Cu")
		(net "FM_FORCE_ADR_N")
	)
	(segment
		(start 389.31977 -97.77095)
		(end 389.31977 -97.633282)
		(width 0.089408)
		(layer "In2.Cu")
		(net "FM_FORCE_ADR_N")
	)
	(segment
		(start 376.962162 -95.809562)
		(end 374.640348 -93.487748)
		(width 0.089408)
		(layer "In2.Cu")
		(net "FM_FORCE_ADR_N")
	)
	(segment
		(start 370.718588 -79.739998)
		(end 370.446808 -79.468218)
		(width 0.089408)
		(layer "In2.Cu")
		(net "FM_FORCE_ADR_N")
	)
	(segment
		(start 369.971828 -78.020672)
		(end 370.071142 -77.921358)
		(width 0.089408)
		(layer "In2.Cu")
		(net "FM_FORCE_ADR_N")
	)
	(segment
		(start 373.062754 -73.390252)
		(end 373.062754 -73.175876)
		(width 0.089408)
		(layer "In2.Cu")
		(net "FM_FORCE_ADR_N")
	)
	(segment
		(start 373.876824 -82.17027)
		(end 373.279416 -82.17027)
		(width 0.089408)
		(layer "In2.Cu")
		(net "FM_FORCE_ADR_N")
	)
	(segment
		(start 371.541802 -76.117958)
		(end 371.541802 -74.70267)
		(width 0.089408)
		(layer "In2.Cu")
		(net "FM_FORCE_ADR_N")
	)
	(segment
		(start 370.071142 -77.921358)
		(end 370.562886 -77.921358)
		(width 0.089408)
		(layer "In2.Cu")
		(net "FM_FORCE_ADR_N")
	)
	(segment
		(start 378.030994 -97.155)
		(end 376.962162 -96.086168)
		(width 0.089408)
		(layer "In2.Cu")
		(net "FM_FORCE_ADR_N")
	)
	(segment
		(start 372.838472 -82.131916)
		(end 372.2116 -81.505044)
		(width 0.089408)
		(layer "In2.Cu")
		(net "FM_FORCE_ADR_N")
	)
	(segment
		(start 370.990622 -80.268064)
		(end 370.718588 -79.99603)
		(width 0.089408)
		(layer "In2.Cu")
		(net "FM_FORCE_ADR_N")
	)
	(segment
		(start 373.139208 -82.131916)
		(end 372.838472 -82.131916)
		(width 0.089408)
		(layer "In2.Cu")
		(net "FM_FORCE_ADR_N")
	)
	(segment
		(start 370.718588 -79.99603)
		(end 370.718588 -79.739998)
		(width 0.089408)
		(layer "In2.Cu")
		(net "FM_FORCE_ADR_N")
	)
	(segment
		(start 372.017036 -74.43597)
		(end 373.062754 -73.390252)
		(width 0.089408)
		(layer "In2.Cu")
		(net "FM_FORCE_ADR_N")
	)
	(segment
		(start 389.75411 -98.004376)
		(end 389.553196 -98.004376)
		(width 0.089408)
		(layer "In2.Cu")
		(net "FM_FORCE_ADR_N")
	)
	(segment
		(start 371.541802 -74.70267)
		(end 371.808502 -74.43597)
		(width 0.089408)
		(layer "In2.Cu")
		(net "FM_FORCE_ADR_N")
	)
	(segment
		(start 372.2116 -80.96123)
		(end 371.518434 -80.268064)
		(width 0.089408)
		(layer "In2.Cu")
		(net "FM_FORCE_ADR_N")
	)
	(segment
		(start 370.446808 -79.468218)
		(end 370.190522 -79.468218)
		(width 0.089408)
		(layer "In2.Cu")
		(net "FM_FORCE_ADR_N")
	)
	(segment
		(start 373.252492 -82.143346)
		(end 373.150638 -82.143346)
		(width 0.089408)
		(layer "In2.Cu")
		(net "FM_FORCE_ADR_N")
	)
	(segment
		(start 371.37848 -76.28128)
		(end 371.541802 -76.117958)
		(width 0.089408)
		(layer "In2.Cu")
		(net "FM_FORCE_ADR_N")
	)
	(segment
		(start 370.562886 -77.921358)
		(end 370.754656 -77.729588)
		(width 0.089408)
		(layer "In2.Cu")
		(net "FM_FORCE_ADR_N")
	)
	(segment
		(start 389.31977 -97.633282)
		(end 388.841488 -97.155)
		(width 0.089408)
		(layer "In2.Cu")
		(net "FM_FORCE_ADR_N")
	)
	(segment
		(start 373.920512 -93.196156)
		(end 373.920512 -89.496392)
		(width 0.089408)
		(layer "In2.Cu")
		(net "FM_FORCE_ADR_N")
	)
	(segment
		(start 369.971828 -79.249524)
		(end 369.971828 -78.020672)
		(width 0.089408)
		(layer "In2.Cu")
		(net "FM_FORCE_ADR_N")
	)
	(segment
		(start 389.553196 -98.004376)
		(end 389.31977 -97.77095)
		(width 0.089408)
		(layer "In2.Cu")
		(net "FM_FORCE_ADR_N")
	)
	(segment
		(start 371.518434 -80.268064)
		(end 370.990622 -80.268064)
		(width 0.089408)
		(layer "In2.Cu")
		(net "FM_FORCE_ADR_N")
	)
	(segment
		(start 373.279416 -82.17027)
		(end 373.252492 -82.143346)
		(width 0.089408)
		(layer "In2.Cu")
		(net "FM_FORCE_ADR_N")
	)
	(segment
		(start 373.150638 -82.143346)
		(end 373.139208 -82.131916)
		(width 0.089408)
		(layer "In2.Cu")
		(net "FM_FORCE_ADR_N")
	)
	(segment
		(start 390.21385 -98.464116)
		(end 389.75411 -98.004376)
		(width 0.089408)
		(layer "In2.Cu")
		(net "FM_FORCE_ADR_N")
	)
	(segment
		(start 375.533666 -83.827112)
		(end 373.876824 -82.17027)
		(width 0.089408)
		(layer "In2.Cu")
		(net "FM_FORCE_ADR_N")
	)
	(segment
		(start 373.062754 -73.175876)
		(end 373.063008 -73.175622)
		(width 0.089408)
		(layer "In2.Cu")
		(net "FM_FORCE_ADR_N")
	)
	(segment
		(start 374.640348 -93.487748)
		(end 374.212104 -93.487748)
		(width 0.089408)
		(layer "In2.Cu")
		(net "FM_FORCE_ADR_N")
	)
	(segment
		(start 373.938546 -70.701408)
		(end 374.344692 -70.295262)
		(width 0.089408)
		(layer "In2.Cu")
		(net "FM_FORCE_ADR_N")
	)
	(segment
		(start 375.533666 -87.883238)
		(end 375.533666 -83.827112)
		(width 0.089408)
		(layer "In2.Cu")
		(net "FM_FORCE_ADR_N")
	)
	(segment
		(start 370.190522 -79.468218)
		(end 369.971828 -79.249524)
		(width 0.089408)
		(layer "In2.Cu")
		(net "FM_FORCE_ADR_N")
	)
	(segment
		(start 388.841488 -97.155)
		(end 378.030994 -97.155)
		(width 0.089408)
		(layer "In2.Cu")
		(net "FM_FORCE_ADR_N")
	)
	(segment
		(start 371.808502 -74.43597)
		(end 372.017036 -74.43597)
		(width 0.089408)
		(layer "In2.Cu")
		(net "FM_FORCE_ADR_N")
	)
	(segment
		(start 373.063008 -71.04888)
		(end 373.41048 -70.701408)
		(width 0.089408)
		(layer "In2.Cu")
		(net "FM_FORCE_ADR_N")
	)
	(segment
		(start 373.920512 -89.496392)
		(end 375.533666 -87.883238)
		(width 0.089408)
		(layer "In2.Cu")
		(net "FM_FORCE_ADR_N")
	)
	(segment
		(start 370.754656 -77.729588)
		(end 370.754656 -76.496926)
		(width 0.089408)
		(layer "In2.Cu")
		(net "FM_FORCE_ADR_N")
	)
	(segment
		(start 374.212104 -93.487748)
		(end 373.920512 -93.196156)
		(width 0.089408)
		(layer "In2.Cu")
		(net "FM_FORCE_ADR_N")
	)
	(segment
		(start 372.2116 -81.505044)
		(end 372.2116 -80.96123)
		(width 0.089408)
		(layer "In2.Cu")
		(net "FM_FORCE_ADR_N")
	)
	(segment
		(start 370.970302 -76.28128)
		(end 371.37848 -76.28128)
		(width 0.089408)
		(layer "In2.Cu")
		(net "FM_FORCE_ADR_N")
	)
	(segment
		(start 373.063008 -73.175622)
		(end 373.063008 -71.04888)
		(width 0.089408)
		(layer "In2.Cu")
		(net "FM_FORCE_ADR_N")
	)
	(segment
		(start 376.962162 -96.086168)
		(end 376.962162 -95.809562)
		(width 0.089408)
		(layer "In2.Cu")
		(net "FM_FORCE_ADR_N")
	)
	(segment
		(start 370.754656 -76.496926)
		(end 370.970302 -76.28128)
		(width 0.089408)
		(layer "In2.Cu")
		(net "FM_FORCE_ADR_N")
	)
	(segment
		(start 393.033504 -36.385246)
		(end 393.03198 -36.383722)
		(width 0.089408)
		(layer "In4.Cu")
		(net "FM_FORCE_ADR_N")
	)
	(segment
		(start 404.004526 -38.725856)
		(end 402.660358 -37.381688)
		(width 0.089408)
		(layer "In4.Cu")
		(net "FM_FORCE_ADR_N")
	)
	(segment
		(start 393.03198 -36.383722)
		(end 390.314688 -36.383722)
		(width 0.089408)
		(layer "In4.Cu")
		(net "FM_FORCE_ADR_N")
	)
	(segment
		(start 379.957076 -38.2524)
		(end 379.945392 -38.2524)
		(width 0.089408)
		(layer "In4.Cu")
		(net "FM_FORCE_ADR_N")
	)
	(segment
		(start 380.422404 -37.585142)
		(end 380.422404 -37.787072)
		(width 0.089408)
		(layer "In4.Cu")
		(net "FM_FORCE_ADR_N")
	)
	(segment
		(start 398.996408 -37.793422)
		(end 394.44168 -37.793422)
		(width 0.089408)
		(layer "In4.Cu")
		(net "FM_FORCE_ADR_N")
	)
	(segment
		(start 385.022344 -36.392358)
		(end 383.9845 -36.392358)
		(width 0.089408)
		(layer "In4.Cu")
		(net "FM_FORCE_ADR_N")
	)
	(segment
		(start 380.422404 -37.787072)
		(end 379.957076 -38.2524)
		(width 0.089408)
		(layer "In4.Cu")
		(net "FM_FORCE_ADR_N")
	)
	(segment
		(start 388.053834 -35.921188)
		(end 387.848602 -35.715956)
		(width 0.089408)
		(layer "In4.Cu")
		(net "FM_FORCE_ADR_N")
	)
	(segment
		(start 389.852154 -35.921188)
		(end 388.053834 -35.921188)
		(width 0.089408)
		(layer "In4.Cu")
		(net "FM_FORCE_ADR_N")
	)
	(segment
		(start 383.752598 -36.62426)
		(end 382.504696 -36.62426)
		(width 0.089408)
		(layer "In4.Cu")
		(net "FM_FORCE_ADR_N")
	)
	(segment
		(start 399.408142 -37.381688)
		(end 398.996408 -37.793422)
		(width 0.089408)
		(layer "In4.Cu")
		(net "FM_FORCE_ADR_N")
	)
	(segment
		(start 385.524502 -35.8902)
		(end 385.022344 -36.392358)
		(width 0.089408)
		(layer "In4.Cu")
		(net "FM_FORCE_ADR_N")
	)
	(segment
		(start 390.314688 -36.383722)
		(end 389.852154 -35.921188)
		(width 0.089408)
		(layer "In4.Cu")
		(net "FM_FORCE_ADR_N")
	)
	(segment
		(start 394.44168 -37.793422)
		(end 393.241022 -36.592764)
		(width 0.089408)
		(layer "In4.Cu")
		(net "FM_FORCE_ADR_N")
	)
	(segment
		(start 387.848602 -35.715956)
		(end 387.516878 -35.715956)
		(width 0.089408)
		(layer "In4.Cu")
		(net "FM_FORCE_ADR_N")
	)
	(segment
		(start 393.241022 -36.592764)
		(end 393.241022 -36.59251)
		(width 0.089408)
		(layer "In4.Cu")
		(net "FM_FORCE_ADR_N")
	)
	(segment
		(start 383.9845 -36.392358)
		(end 383.752598 -36.62426)
		(width 0.089408)
		(layer "In4.Cu")
		(net "FM_FORCE_ADR_N")
	)
	(segment
		(start 387.342634 -35.8902)
		(end 385.524502 -35.8902)
		(width 0.089408)
		(layer "In4.Cu")
		(net "FM_FORCE_ADR_N")
	)
	(segment
		(start 382.3462 -36.782756)
		(end 381.22479 -36.782756)
		(width 0.089408)
		(layer "In4.Cu")
		(net "FM_FORCE_ADR_N")
	)
	(segment
		(start 382.504696 -36.62426)
		(end 382.3462 -36.782756)
		(width 0.089408)
		(layer "In4.Cu")
		(net "FM_FORCE_ADR_N")
	)
	(segment
		(start 393.033758 -36.385246)
		(end 393.033504 -36.385246)
		(width 0.089408)
		(layer "In4.Cu")
		(net "FM_FORCE_ADR_N")
	)
	(segment
		(start 387.516878 -35.715956)
		(end 387.342634 -35.8902)
		(width 0.089408)
		(layer "In4.Cu")
		(net "FM_FORCE_ADR_N")
	)
	(segment
		(start 393.241022 -36.59251)
		(end 393.033758 -36.385246)
		(width 0.089408)
		(layer "In4.Cu")
		(net "FM_FORCE_ADR_N")
	)
	(segment
		(start 381.22479 -36.782756)
		(end 380.422404 -37.585142)
		(width 0.089408)
		(layer "In4.Cu")
		(net "FM_FORCE_ADR_N")
	)
	(segment
		(start 402.660358 -37.381688)
		(end 399.408142 -37.381688)
		(width 0.089408)
		(layer "In4.Cu")
		(net "FM_FORCE_ADR_N")
	)
	(segment
		(start 380.986284 -44.30395)
		(end 380.986284 -44.145962)
		(width 0.089408)
		(layer "In9.Cu")
		(net "FM_FORCE_ADR_N")
	)
	(segment
		(start 378.520198 -38.972998)
		(end 379.240796 -38.2524)
		(width 0.089408)
		(layer "In9.Cu")
		(net "FM_FORCE_ADR_N")
	)
	(segment
		(start 380.98603 -44.462192)
		(end 380.98603 -44.304204)
		(width 0.089408)
		(layer "In9.Cu")
		(net "FM_FORCE_ADR_N")
	)
	(segment
		(start 377.325382 -62.503304)
		(end 378.016516 -62.503304)
		(width 0.089408)
		(layer "In9.Cu")
		(net "FM_FORCE_ADR_N")
	)
	(segment
		(start 374.718072 -68.850002)
		(end 374.718072 -67.715638)
		(width 0.089408)
		(layer "In9.Cu")
		(net "FM_FORCE_ADR_N")
	)
	(segment
		(start 379.784864 -51.107086)
		(end 379.784864 -46.613318)
		(width 0.089408)
		(layer "In9.Cu")
		(net "FM_FORCE_ADR_N")
	)
	(segment
		(start 378.490226 -41.649904)
		(end 378.490226 -41.491916)
		(width 0.089408)
		(layer "In9.Cu")
		(net "FM_FORCE_ADR_N")
	)
	(segment
		(start 376.130058 -66.303652)
		(end 376.130058 -63.957708)
		(width 0.089408)
		(layer "In9.Cu")
		(net "FM_FORCE_ADR_N")
	)
	(segment
		(start 373.971312 -69.921882)
		(end 373.971312 -69.340476)
		(width 0.089408)
		(layer "In9.Cu")
		(net "FM_FORCE_ADR_N")
	)
	(segment
		(start 379.784864 -46.613318)
		(end 380.985776 -45.412406)
		(width 0.089408)
		(layer "In9.Cu")
		(net "FM_FORCE_ADR_N")
	)
	(segment
		(start 380.985776 -44.126658)
		(end 378.973588 -42.11447)
		(width 0.089408)
		(layer "In9.Cu")
		(net "FM_FORCE_ADR_N")
	)
	(segment
		(start 378.490226 -41.491916)
		(end 378.49048 -41.491662)
		(width 0.089408)
		(layer "In9.Cu")
		(net "FM_FORCE_ADR_N")
	)
	(segment
		(start 380.985776 -44.462446)
		(end 380.98603 -44.462192)
		(width 0.089408)
		(layer "In9.Cu")
		(net "FM_FORCE_ADR_N")
	)
	(segment
		(start 376.929904 -62.898782)
		(end 377.325382 -62.503304)
		(width 0.089408)
		(layer "In9.Cu")
		(net "FM_FORCE_ADR_N")
	)
	(segment
		(start 378.520198 -39.856918)
		(end 378.520198 -38.972998)
		(width 0.089408)
		(layer "In9.Cu")
		(net "FM_FORCE_ADR_N")
	)
	(segment
		(start 379.754638 -57.98439)
		(end 379.754638 -55.482236)
		(width 0.089408)
		(layer "In9.Cu")
		(net "FM_FORCE_ADR_N")
	)
	(segment
		(start 376.130058 -63.957708)
		(end 376.929904 -63.157862)
		(width 0.089408)
		(layer "In9.Cu")
		(net "FM_FORCE_ADR_N")
	)
	(segment
		(start 380.986284 -44.145962)
		(end 380.985776 -44.145454)
		(width 0.089408)
		(layer "In9.Cu")
		(net "FM_FORCE_ADR_N")
	)
	(segment
		(start 378.973588 -42.11447)
		(end 378.954792 -42.11447)
		(width 0.089408)
		(layer "In9.Cu")
		(net "FM_FORCE_ADR_N")
	)
	(segment
		(start 380.98603 -44.304204)
		(end 380.986284 -44.30395)
		(width 0.089408)
		(layer "In9.Cu")
		(net "FM_FORCE_ADR_N")
	)
	(segment
		(start 380.985776 -45.412406)
		(end 380.985776 -44.462446)
		(width 0.089408)
		(layer "In9.Cu")
		(net "FM_FORCE_ADR_N")
	)
	(segment
		(start 378.49048 -40.934132)
		(end 378.673868 -40.750744)
		(width 0.089408)
		(layer "In9.Cu")
		(net "FM_FORCE_ADR_N")
	)
	(segment
		(start 379.656086 -55.383684)
		(end 379.656086 -51.235864)
		(width 0.089408)
		(layer "In9.Cu")
		(net "FM_FORCE_ADR_N")
	)
	(segment
		(start 380.985776 -44.145454)
		(end 380.985776 -44.126658)
		(width 0.089408)
		(layer "In9.Cu")
		(net "FM_FORCE_ADR_N")
	)
	(segment
		(start 374.344692 -70.295262)
		(end 373.971312 -69.921882)
		(width 0.089408)
		(layer "In9.Cu")
		(net "FM_FORCE_ADR_N")
	)
	(segment
		(start 374.480074 -69.088)
		(end 374.718072 -68.850002)
		(width 0.089408)
		(layer "In9.Cu")
		(net "FM_FORCE_ADR_N")
	)
	(segment
		(start 378.284994 -62.234826)
		(end 378.284994 -59.454034)
		(width 0.089408)
		(layer "In9.Cu")
		(net "FM_FORCE_ADR_N")
	)
	(segment
		(start 374.223788 -69.088)
		(end 374.480074 -69.088)
		(width 0.089408)
		(layer "In9.Cu")
		(net "FM_FORCE_ADR_N")
	)
	(segment
		(start 378.284994 -59.454034)
		(end 379.754638 -57.98439)
		(width 0.089408)
		(layer "In9.Cu")
		(net "FM_FORCE_ADR_N")
	)
	(segment
		(start 373.971312 -69.340476)
		(end 374.223788 -69.088)
		(width 0.089408)
		(layer "In9.Cu")
		(net "FM_FORCE_ADR_N")
	)
	(segment
		(start 379.656086 -51.235864)
		(end 379.784864 -51.107086)
		(width 0.089408)
		(layer "In9.Cu")
		(net "FM_FORCE_ADR_N")
	)
	(segment
		(start 379.240796 -38.2524)
		(end 379.945392 -38.2524)
		(width 0.089408)
		(layer "In9.Cu")
		(net "FM_FORCE_ADR_N")
	)
	(segment
		(start 376.929904 -63.157862)
		(end 376.929904 -62.898782)
		(width 0.089408)
		(layer "In9.Cu")
		(net "FM_FORCE_ADR_N")
	)
	(segment
		(start 378.954792 -42.11447)
		(end 378.490226 -41.649904)
		(width 0.089408)
		(layer "In9.Cu")
		(net "FM_FORCE_ADR_N")
	)
	(segment
		(start 378.49048 -41.491662)
		(end 378.49048 -40.934132)
		(width 0.089408)
		(layer "In9.Cu")
		(net "FM_FORCE_ADR_N")
	)
	(segment
		(start 378.016516 -62.503304)
		(end 378.284994 -62.234826)
		(width 0.089408)
		(layer "In9.Cu")
		(net "FM_FORCE_ADR_N")
	)
	(segment
		(start 379.754638 -55.482236)
		(end 379.656086 -55.383684)
		(width 0.089408)
		(layer "In9.Cu")
		(net "FM_FORCE_ADR_N")
	)
	(segment
		(start 374.718072 -67.715638)
		(end 376.130058 -66.303652)
		(width 0.089408)
		(layer "In9.Cu")
		(net "FM_FORCE_ADR_N")
	)
	(segment
		(start 378.673868 -40.750744)
		(end 378.673868 -40.010588)
		(width 0.089408)
		(layer "In9.Cu")
		(net "FM_FORCE_ADR_N")
	)
	(segment
		(start 378.673868 -40.010588)
		(end 378.520198 -39.856918)
		(width 0.089408)
		(layer "In9.Cu")
		(net "FM_FORCE_ADR_N")
	)
	(segment
		(start 14.9352 -76.8604)
		(end 14.9098 -76.8858)
		(width 0.254)
		(layer "F.Cu")
		(net "A_HSC_CSOUT")
	)
	(segment
		(start 22.56536 -82.48396)
		(end 22.66188 -82.58048)
		(width 0.254)
		(layer "F.Cu")
		(net "A_HSC_CSOUT")
	)
	(segment
		(start 22.830028 -82.219292)
		(end 22.56536 -82.48396)
		(width 0.254)
		(layer "F.Cu")
		(net "A_HSC_CSOUT")
	)
	(segment
		(start 15.8115 -76.44257)
		(end 15.37843 -76.44257)
		(width 0.254)
		(layer "F.Cu")
		(net "A_HSC_CSOUT")
	)
	(segment
		(start 23.241 -81.6102)
		(end 22.830028 -82.021172)
		(width 0.254)
		(layer "F.Cu")
		(net "A_HSC_CSOUT")
	)
	(segment
		(start 22.830028 -82.021172)
		(end 22.830028 -82.219292)
		(width 0.254)
		(layer "F.Cu")
		(net "A_HSC_CSOUT")
	)
	(segment
		(start 14.9098 -76.8858)
		(end 14.8844 -76.8858)
		(width 0.254)
		(layer "F.Cu")
		(net "A_HSC_CSOUT")
	)
	(segment
		(start 15.37843 -76.44257)
		(end 14.9606 -76.8604)
		(width 0.254)
		(layer "F.Cu")
		(net "A_HSC_CSOUT")
	)
	(segment
		(start 22.66188 -82.58048)
		(end 22.66188 -83.24342)
		(width 0.254)
		(layer "F.Cu")
		(net "A_HSC_CSOUT")
	)
	(segment
		(start 14.9606 -76.8604)
		(end 14.9352 -76.8604)
		(width 0.254)
		(layer "F.Cu")
		(net "A_HSC_CSOUT")
	)
	(via
		(at 22.56536 -82.48396)
		(size 0.508)
		(drill 0.254)
		(layers "F.Cu" "B.Cu")
		(net "A_HSC_CSOUT")
	)
	(via
		(at 14.8844 -76.8858)
		(size 0.508)
		(drill 0.254)
		(layers "F.Cu" "B.Cu")
		(net "A_HSC_CSOUT")
	)
	(segment
		(start 15.516352 -76.8858)
		(end 14.8844 -76.8858)
		(width 0.254)
		(layer "In2.Cu")
		(net "A_HSC_CSOUT")
	)
	(segment
		(start 22.56536 -82.48396)
		(end 22.56536 -82.628232)
		(width 0.254)
		(layer "In2.Cu")
		(net "A_HSC_CSOUT")
	)
	(segment
		(start 17.526 -79.549752)
		(end 17.07515 -79.098902)
		(width 0.254)
		(layer "In2.Cu")
		(net "A_HSC_CSOUT")
	)
	(segment
		(start 19.685 -82.415888)
		(end 20.193 -81.907888)
		(width 0.254)
		(layer "In2.Cu")
		(net "A_HSC_CSOUT")
	)
	(segment
		(start 18.250408 -80.866742)
		(end 17.526 -80.142334)
		(width 0.254)
		(layer "In2.Cu")
		(net "A_HSC_CSOUT")
	)
	(segment
		(start 17.07515 -78.444598)
		(end 15.516352 -76.8858)
		(width 0.254)
		(layer "In2.Cu")
		(net "A_HSC_CSOUT")
	)
	(segment
		(start 17.07515 -79.098902)
		(end 17.07515 -78.444598)
		(width 0.254)
		(layer "In2.Cu")
		(net "A_HSC_CSOUT")
	)
	(segment
		(start 19.967448 -83.1342)
		(end 19.685 -82.851752)
		(width 0.254)
		(layer "In2.Cu")
		(net "A_HSC_CSOUT")
	)
	(segment
		(start 22.059392 -83.1342)
		(end 19.967448 -83.1342)
		(width 0.254)
		(layer "In2.Cu")
		(net "A_HSC_CSOUT")
	)
	(segment
		(start 17.526 -80.142334)
		(end 17.526 -79.549752)
		(width 0.254)
		(layer "In2.Cu")
		(net "A_HSC_CSOUT")
	)
	(segment
		(start 20.193 -81.283048)
		(end 19.776694 -80.866742)
		(width 0.254)
		(layer "In2.Cu")
		(net "A_HSC_CSOUT")
	)
	(segment
		(start 19.685 -82.851752)
		(end 19.685 -82.415888)
		(width 0.254)
		(layer "In2.Cu")
		(net "A_HSC_CSOUT")
	)
	(segment
		(start 20.193 -81.907888)
		(end 20.193 -81.283048)
		(width 0.254)
		(layer "In2.Cu")
		(net "A_HSC_CSOUT")
	)
	(segment
		(start 19.776694 -80.866742)
		(end 18.250408 -80.866742)
		(width 0.254)
		(layer "In2.Cu")
		(net "A_HSC_CSOUT")
	)
	(segment
		(start 22.56536 -82.628232)
		(end 22.059392 -83.1342)
		(width 0.254)
		(layer "In2.Cu")
		(net "A_HSC_CSOUT")
	)
	(segment
		(start 26.2255 -66.46672)
		(end 26.2255 -65.65138)
		(width 0.508)
		(layer "F.Cu")
		(net "A_HSC_C")
	)
	(segment
		(start 26.416 -65.3796)
		(end 26.416 -64.516)
		(width 0.508)
		(layer "F.Cu")
		(net "A_HSC_C")
	)
	(segment
		(start 26.2255 -65.65138)
		(end 26.18486 -65.61074)
		(width 0.508)
		(layer "F.Cu")
		(net "A_HSC_C")
	)
	(segment
		(start 26.18486 -65.6082)
		(end 26.18486 -65.61074)
		(width 0.508)
		(layer "F.Cu")
		(net "A_HSC_C")
	)
	(segment
		(start 26.18486 -65.61074)
		(end 26.416 -65.3796)
		(width 0.508)
		(layer "F.Cu")
		(net "A_HSC_C")
	)
	(via
		(at 26.18486 -65.6082)
		(size 0.762)
		(drill 0.381)
		(layers "F.Cu" "B.Cu")
		(net "A_HSC_C")
	)
	(via
		(at 372.872 -4.3434)
		(size 0.6604)
		(drill 0.3302)
		(layers "F.Cu" "B.Cu")
		(net "PU_BIOS_USB_RECOVERY")
	)
	(segment
		(start 373.345456 -3.19151)
		(end 373.345456 -3.742944)
		(width 0.10795)
		(layer "B.Cu")
		(net "PU_BIOS_USB_RECOVERY")
	)
	(segment
		(start 371.348 1.27)
		(end 372.257574 0.360426)
		(width 0.10795)
		(layer "B.Cu")
		(net "PU_BIOS_USB_RECOVERY")
	)
	(segment
		(start 373.345456 -3.742944)
		(end 372.872 -4.2164)
		(width 0.10795)
		(layer "B.Cu")
		(net "PU_BIOS_USB_RECOVERY")
	)
	(segment
		(start 372.257574 -2.103628)
		(end 373.345456 -3.19151)
		(width 0.10795)
		(layer "B.Cu")
		(net "PU_BIOS_USB_RECOVERY")
	)
	(segment
		(start 372.257574 0.360426)
		(end 372.257574 -2.103628)
		(width 0.10795)
		(layer "B.Cu")
		(net "PU_BIOS_USB_RECOVERY")
	)
	(segment
		(start 372.872 -4.3434)
		(end 372.872 -5.2705)
		(width 0.10795)
		(layer "B.Cu")
		(net "PU_BIOS_USB_RECOVERY")
	)
	(segment
		(start 372.872 -4.2164)
		(end 372.872 -4.3434)
		(width 0.10795)
		(layer "B.Cu")
		(net "PU_BIOS_USB_RECOVERY")
	)
	(via
		(at 379.1458 -3.1242)
		(size 0.6604)
		(drill 0.3302)
		(layers "F.Cu" "B.Cu")
		(net "P3V3_STBY_PLD_D")
	)
	(segment
		(start 382.27 2.159)
		(end 380.0348 -0.0762)
		(width 0.381)
		(layer "B.Cu")
		(net "P3V3_STBY_PLD_D")
	)
	(segment
		(start 380.0348 -2.2352)
		(end 379.1458 -3.1242)
		(width 0.381)
		(layer "B.Cu")
		(net "P3V3_STBY_PLD_D")
	)
	(segment
		(start 380.0348 -0.0762)
		(end 380.0348 -2.2352)
		(width 0.381)
		(layer "B.Cu")
		(net "P3V3_STBY_PLD_D")
	)
	(segment
		(start 378.5362 -5.08)
		(end 378.5362 -5.7658)
		(width 0.381)
		(layer "B.Cu")
		(net "P3V3_STBY_PLD_D")
	)
	(segment
		(start 379.1458 -3.1242)
		(end 378.892054 -3.377946)
		(width 0.381)
		(layer "B.Cu")
		(net "P3V3_STBY_PLD_D")
	)
	(segment
		(start 378.892054 -4.724146)
		(end 378.5362 -5.08)
		(width 0.381)
		(layer "B.Cu")
		(net "P3V3_STBY_PLD_D")
	)
	(segment
		(start 378.892054 -3.377946)
		(end 378.892054 -4.724146)
		(width 0.381)
		(layer "B.Cu")
		(net "P3V3_STBY_PLD_D")
	)
	(segment
		(start 382.27 3.81)
		(end 382.27 2.159)
		(width 0.381)
		(layer "B.Cu")
		(net "P3V3_STBY_PLD_D")
	)
	(segment
		(start 373.544846 -71.095108)
		(end 373.14505 -71.494904)
		(width 0.10795)
		(layer "F.Cu")
		(net "TP_CPLD1_PT16B")
	)
	(via
		(at 373.544846 -71.095108)
		(size 0.4572)
		(drill 0.2032)
		(layers "F.Cu" "B.Cu")
		(net "TP_CPLD1_PT16B")
	)
	(segment
		(start 368.745262 -68.695316)
		(end 369.145058 -69.095112)
		(width 0.10795)
		(layer "F.Cu")
		(net "TP_CPLD1_PT22C")
	)
	(via
		(at 368.745262 -68.695316)
		(size 0.4572)
		(drill 0.2032)
		(layers "F.Cu" "B.Cu")
		(net "TP_CPLD1_PT22C")
	)
	(segment
		(start 371.145308 -70.295262)
		(end 371.545104 -70.695058)
		(width 0.10795)
		(layer "F.Cu")
		(net "TP_CPLD1_PT20A")
	)
	(via
		(at 371.145308 -70.295262)
		(size 0.4572)
		(drill 0.2032)
		(layers "F.Cu" "B.Cu")
		(net "TP_CPLD1_PT20A")
	)
	(via
		(at 409.956 -16.129)
		(size 0.6604)
		(drill 0.3302)
		(layers "F.Cu" "B.Cu")
		(net "FP_NMI_BTN_R_N")
	)
	(segment
		(start 409.4226 -15.5956)
		(end 409.956 -16.129)
		(width 0.10795)
		(layer "B.Cu")
		(net "FP_NMI_BTN_R_N")
	)
	(segment
		(start 408.686 -14.74724)
		(end 409.4226 -14.74724)
		(width 0.10795)
		(layer "B.Cu")
		(net "FP_NMI_BTN_R_N")
	)
	(segment
		(start 408.1907 -14.7828)
		(end 408.65044 -14.7828)
		(width 0.10795)
		(layer "B.Cu")
		(net "FP_NMI_BTN_R_N")
	)
	(segment
		(start 408.65044 -14.7828)
		(end 408.686 -14.74724)
		(width 0.10795)
		(layer "B.Cu")
		(net "FP_NMI_BTN_R_N")
	)
	(segment
		(start 409.4226 -14.74724)
		(end 409.4226 -15.5956)
		(width 0.10795)
		(layer "B.Cu")
		(net "FP_NMI_BTN_R_N")
	)
	(via
		(at 384.499866 -46.247812)
		(size 0.6604)
		(drill 0.3302)
		(layers "F.Cu" "B.Cu")
		(net "FM_THROTTLE_R_N")
	)
	(segment
		(start 385.055872 -45.691806)
		(end 384.499866 -46.247812)
		(width 0.10795)
		(layer "B.Cu")
		(net "FM_THROTTLE_R_N")
	)
	(segment
		(start 385.774692 -44.215812)
		(end 385.774692 -44.816014)
		(width 0.10795)
		(layer "B.Cu")
		(net "FM_THROTTLE_R_N")
	)
	(segment
		(start 385.820666 -45.691806)
		(end 385.055872 -45.691806)
		(width 0.10795)
		(layer "B.Cu")
		(net "FM_THROTTLE_R_N")
	)
	(segment
		(start 385.820666 -44.861988)
		(end 385.820666 -45.691806)
		(width 0.10795)
		(layer "B.Cu")
		(net "FM_THROTTLE_R_N")
	)
	(segment
		(start 385.774692 -44.816014)
		(end 385.820666 -44.861988)
		(width 0.10795)
		(layer "B.Cu")
		(net "FM_THROTTLE_R_N")
	)
	(segment
		(start 421.956992 -76.673456)
		(end 421.956992 -77.523594)
		(width 0.10795)
		(layer "B.Cu")
		(net "FM_THROTTLE_R1_N")
	)
	(segment
		(start 422.281604 -76.348844)
		(end 421.956992 -76.673456)
		(width 0.10795)
		(layer "B.Cu")
		(net "FM_THROTTLE_R1_N")
	)
	(segment
		(start 385.19735 -4.342892)
		(end 383.729738 -4.342892)
		(width 0.10795)
		(layer "F.Cu")
		(net "FM_BIOS_USB_RECOVERY")
	)
	(segment
		(start 383.729738 -4.342892)
		(end 379.717046 -0.3302)
		(width 0.10795)
		(layer "F.Cu")
		(net "FM_BIOS_USB_RECOVERY")
	)
	(segment
		(start 375.981722 -0.3302)
		(end 375.727722 -0.0762)
		(width 0.10795)
		(layer "F.Cu")
		(net "FM_BIOS_USB_RECOVERY")
	)
	(segment
		(start 379.717046 -0.3302)
		(end 375.981722 -0.3302)
		(width 0.10795)
		(layer "F.Cu")
		(net "FM_BIOS_USB_RECOVERY")
	)
	(segment
		(start 386.357368 -5.50291)
		(end 385.19735 -4.342892)
		(width 0.10795)
		(layer "F.Cu")
		(net "FM_BIOS_USB_RECOVERY")
	)
	(segment
		(start 370.1542 -0.0762)
		(end 368.808 1.27)
		(width 0.10795)
		(layer "F.Cu")
		(net "FM_BIOS_USB_RECOVERY")
	)
	(segment
		(start 375.727722 -0.0762)
		(end 370.1542 -0.0762)
		(width 0.10795)
		(layer "F.Cu")
		(net "FM_BIOS_USB_RECOVERY")
	)
	(segment
		(start 386.74675 -100.41128)
		(end 386.25145 -100.181156)
		(width 0.10795)
		(layer "F.Cu")
		(net "FM_BIOS_USB_RECOVERY")
	)
	(via
		(at 399.436844 -24.292306)
		(size 0.508)
		(drill 0.254)
		(layers "F.Cu" "B.Cu")
		(net "FM_BIOS_USB_RECOVERY")
	)
	(via
		(at 386.25145 -100.181156)
		(size 0.508)
		(drill 0.254)
		(layers "F.Cu" "B.Cu")
		(net "FM_BIOS_USB_RECOVERY")
	)
	(via
		(at 398.666462 -8.170672)
		(size 0.6604)
		(drill 0.3302)
		(layers "F.Cu" "B.Cu")
		(net "FM_BIOS_USB_RECOVERY")
	)
	(via
		(at 386.357368 -5.50291)
		(size 0.508)
		(drill 0.254)
		(layers "F.Cu" "B.Cu")
		(net "FM_BIOS_USB_RECOVERY")
	)
	(segment
		(start 389.00608 -6.345428)
		(end 389.00608 -5.37718)
		(width 0.10795)
		(layer "B.Cu")
		(net "FM_BIOS_USB_RECOVERY")
	)
	(segment
		(start 369.5192 -2.72669)
		(end 369.5192 -4.5339)
		(width 0.10795)
		(layer "B.Cu")
		(net "FM_BIOS_USB_RECOVERY")
	)
	(segment
		(start 397.983202 -20.09013)
		(end 397.983202 -17.67332)
		(width 0.10795)
		(layer "B.Cu")
		(net "FM_BIOS_USB_RECOVERY")
	)
	(segment
		(start 390.610852 -7.9502)
		(end 389.00608 -6.345428)
		(width 0.10795)
		(layer "B.Cu")
		(net "FM_BIOS_USB_RECOVERY")
	)
	(segment
		(start 389.00608 -5.37718)
		(end 388.35838 -4.72948)
		(width 0.10795)
		(layer "B.Cu")
		(net "FM_BIOS_USB_RECOVERY")
	)
	(segment
		(start 397.983202 -17.67332)
		(end 398.431004 -17.225518)
		(width 0.10795)
		(layer "B.Cu")
		(net "FM_BIOS_USB_RECOVERY")
	)
	(segment
		(start 398.666462 -8.170672)
		(end 398.44599 -7.9502)
		(width 0.10795)
		(layer "B.Cu")
		(net "FM_BIOS_USB_RECOVERY")
	)
	(segment
		(start 369.5192 -4.5339)
		(end 368.7064 -5.3467)
		(width 0.10795)
		(layer "B.Cu")
		(net "FM_BIOS_USB_RECOVERY")
	)
	(segment
		(start 388.35838 -4.72948)
		(end 387.130798 -4.72948)
		(width 0.10795)
		(layer "B.Cu")
		(net "FM_BIOS_USB_RECOVERY")
	)
	(segment
		(start 370.30406 -1.94183)
		(end 369.5192 -2.72669)
		(width 0.10795)
		(layer "B.Cu")
		(net "FM_BIOS_USB_RECOVERY")
	)
	(segment
		(start 398.498314 -23.353776)
		(end 398.498314 -20.605242)
		(width 0.10795)
		(layer "B.Cu")
		(net "FM_BIOS_USB_RECOVERY")
	)
	(segment
		(start 398.431004 -14.954758)
		(end 398.973802 -14.41196)
		(width 0.10795)
		(layer "B.Cu")
		(net "FM_BIOS_USB_RECOVERY")
	)
	(segment
		(start 398.973802 -14.41196)
		(end 398.973802 -8.478012)
		(width 0.10795)
		(layer "B.Cu")
		(net "FM_BIOS_USB_RECOVERY")
	)
	(segment
		(start 370.30406 -0.22606)
		(end 370.30406 -1.94183)
		(width 0.10795)
		(layer "B.Cu")
		(net "FM_BIOS_USB_RECOVERY")
	)
	(segment
		(start 368.808 1.27)
		(end 370.30406 -0.22606)
		(width 0.10795)
		(layer "B.Cu")
		(net "FM_BIOS_USB_RECOVERY")
	)
	(segment
		(start 398.431004 -17.225518)
		(end 398.431004 -14.954758)
		(width 0.10795)
		(layer "B.Cu")
		(net "FM_BIOS_USB_RECOVERY")
	)
	(segment
		(start 398.44599 -7.9502)
		(end 390.610852 -7.9502)
		(width 0.10795)
		(layer "B.Cu")
		(net "FM_BIOS_USB_RECOVERY")
	)
	(segment
		(start 387.130798 -4.72948)
		(end 386.357368 -5.50291)
		(width 0.10795)
		(layer "B.Cu")
		(net "FM_BIOS_USB_RECOVERY")
	)
	(segment
		(start 399.436844 -24.292306)
		(end 398.498314 -23.353776)
		(width 0.10795)
		(layer "B.Cu")
		(net "FM_BIOS_USB_RECOVERY")
	)
	(segment
		(start 398.498314 -20.605242)
		(end 397.983202 -20.09013)
		(width 0.10795)
		(layer "B.Cu")
		(net "FM_BIOS_USB_RECOVERY")
	)
	(segment
		(start 398.973802 -8.478012)
		(end 398.666462 -8.170672)
		(width 0.10795)
		(layer "B.Cu")
		(net "FM_BIOS_USB_RECOVERY")
	)
	(segment
		(start 391.318496 -82.12836)
		(end 392.065256 -81.3816)
		(width 0.089408)
		(layer "In9.Cu")
		(net "FM_BIOS_USB_RECOVERY")
	)
	(segment
		(start 392.883898 -76.558394)
		(end 393.305792 -76.1365)
		(width 0.089408)
		(layer "In9.Cu")
		(net "FM_BIOS_USB_RECOVERY")
	)
	(segment
		(start 393.845288 -71.81469)
		(end 393.845288 -71.30669)
		(width 0.089408)
		(layer "In9.Cu")
		(net "FM_BIOS_USB_RECOVERY")
	)
	(segment
		(start 391.537444 -82.83321)
		(end 391.318496 -82.614262)
		(width 0.089408)
		(layer "In9.Cu")
		(net "FM_BIOS_USB_RECOVERY")
	)
	(segment
		(start 397.493998 -60.97524)
		(end 397.493744 -60.974986)
		(width 0.089408)
		(layer "In9.Cu")
		(net "FM_BIOS_USB_RECOVERY")
	)
	(segment
		(start 391.432288 -84.289392)
		(end 391.537444 -84.184236)
		(width 0.089408)
		(layer "In9.Cu")
		(net "FM_BIOS_USB_RECOVERY")
	)
	(segment
		(start 387.14553 -92.258134)
		(end 387.685788 -91.717876)
		(width 0.089408)
		(layer "In9.Cu")
		(net "FM_BIOS_USB_RECOVERY")
	)
	(segment
		(start 391.739628 -79.274924)
		(end 391.739628 -78.927198)
		(width 0.089408)
		(layer "In9.Cu")
		(net "FM_BIOS_USB_RECOVERY")
	)
	(segment
		(start 394.215874 -73.115424)
		(end 394.215874 -72.185276)
		(width 0.089408)
		(layer "In9.Cu")
		(net "FM_BIOS_USB_RECOVERY")
	)
	(segment
		(start 398.55521 -28.476956)
		(end 398.55521 -26.508456)
		(width 0.089408)
		(layer "In9.Cu")
		(net "FM_BIOS_USB_RECOVERY")
	)
	(segment
		(start 395.85011 -64.82969)
		(end 396.496286 -64.183514)
		(width 0.089408)
		(layer "In9.Cu")
		(net "FM_BIOS_USB_RECOVERY")
	)
	(segment
		(start 398.634712 -28.556458)
		(end 398.55521 -28.476956)
		(width 0.089408)
		(layer "In9.Cu")
		(net "FM_BIOS_USB_RECOVERY")
	)
	(segment
		(start 386.25145 -100.181156)
		(end 386.677916 -100.181156)
		(width 0.089408)
		(layer "In9.Cu")
		(net "FM_BIOS_USB_RECOVERY")
	)
	(segment
		(start 398.72285 -43.213528)
		(end 399.25498 -42.681398)
		(width 0.089408)
		(layer "In9.Cu")
		(net "FM_BIOS_USB_RECOVERY")
	)
	(segment
		(start 398.358868 -43.213528)
		(end 398.72285 -43.213528)
		(width 0.089408)
		(layer "In9.Cu")
		(net "FM_BIOS_USB_RECOVERY")
	)
	(segment
		(start 391.739628 -78.927198)
		(end 392.883898 -77.782928)
		(width 0.089408)
		(layer "In9.Cu")
		(net "FM_BIOS_USB_RECOVERY")
	)
	(segment
		(start 399.25498 -41.693338)
		(end 399.01368 -41.452038)
		(width 0.089408)
		(layer "In9.Cu")
		(net "FM_BIOS_USB_RECOVERY")
	)
	(segment
		(start 393.845288 -71.30669)
		(end 395.85011 -69.301868)
		(width 0.089408)
		(layer "In9.Cu")
		(net "FM_BIOS_USB_RECOVERY")
	)
	(segment
		(start 396.574264 -48.146716)
		(end 396.574264 -45.46981)
		(width 0.089408)
		(layer "In9.Cu")
		(net "FM_BIOS_USB_RECOVERY")
	)
	(segment
		(start 391.432288 -85.67801)
		(end 391.432288 -84.289392)
		(width 0.089408)
		(layer "In9.Cu")
		(net "FM_BIOS_USB_RECOVERY")
	)
	(segment
		(start 392.883898 -77.782928)
		(end 392.883898 -76.558394)
		(width 0.089408)
		(layer "In9.Cu")
		(net "FM_BIOS_USB_RECOVERY")
	)
	(segment
		(start 393.305792 -74.025506)
		(end 394.215874 -73.115424)
		(width 0.089408)
		(layer "In9.Cu")
		(net "FM_BIOS_USB_RECOVERY")
	)
	(segment
		(start 387.14553 -96.05391)
		(end 387.14553 -92.258134)
		(width 0.089408)
		(layer "In9.Cu")
		(net "FM_BIOS_USB_RECOVERY")
	)
	(segment
		(start 397.493744 -59.015376)
		(end 397.129254 -58.650886)
		(width 0.089408)
		(layer "In9.Cu")
		(net "FM_BIOS_USB_RECOVERY")
	)
	(segment
		(start 397.290544 -44.75353)
		(end 397.290544 -44.281852)
		(width 0.089408)
		(layer "In9.Cu")
		(net "FM_BIOS_USB_RECOVERY")
	)
	(segment
		(start 391.537444 -84.184236)
		(end 391.537444 -82.83321)
		(width 0.089408)
		(layer "In9.Cu")
		(net "FM_BIOS_USB_RECOVERY")
	)
	(segment
		(start 397.290544 -44.281852)
		(end 398.358868 -43.213528)
		(width 0.089408)
		(layer "In9.Cu")
		(net "FM_BIOS_USB_RECOVERY")
	)
	(segment
		(start 387.24205 -99.132644)
		(end 386.84327 -98.733864)
		(width 0.089408)
		(layer "In9.Cu")
		(net "FM_BIOS_USB_RECOVERY")
	)
	(segment
		(start 387.685788 -90.228674)
		(end 388.667752 -89.24671)
		(width 0.089408)
		(layer "In9.Cu")
		(net "FM_BIOS_USB_RECOVERY")
	)
	(segment
		(start 396.496286 -62.447932)
		(end 397.493998 -61.45022)
		(width 0.089408)
		(layer "In9.Cu")
		(net "FM_BIOS_USB_RECOVERY")
	)
	(segment
		(start 396.574264 -45.46981)
		(end 397.290544 -44.75353)
		(width 0.089408)
		(layer "In9.Cu")
		(net "FM_BIOS_USB_RECOVERY")
	)
	(segment
		(start 388.667752 -88.442546)
		(end 391.432288 -85.67801)
		(width 0.089408)
		(layer "In9.Cu")
		(net "FM_BIOS_USB_RECOVERY")
	)
	(segment
		(start 392.065256 -81.3816)
		(end 392.065256 -79.600552)
		(width 0.089408)
		(layer "In9.Cu")
		(net "FM_BIOS_USB_RECOVERY")
	)
	(segment
		(start 394.215874 -72.185276)
		(end 393.845288 -71.81469)
		(width 0.089408)
		(layer "In9.Cu")
		(net "FM_BIOS_USB_RECOVERY")
	)
	(segment
		(start 396.496286 -64.183514)
		(end 396.496286 -62.447932)
		(width 0.089408)
		(layer "In9.Cu")
		(net "FM_BIOS_USB_RECOVERY")
	)
	(segment
		(start 386.84327 -96.35617)
		(end 387.14553 -96.05391)
		(width 0.089408)
		(layer "In9.Cu")
		(net "FM_BIOS_USB_RECOVERY")
	)
	(segment
		(start 397.129254 -48.701706)
		(end 396.574264 -48.146716)
		(width 0.089408)
		(layer "In9.Cu")
		(net "FM_BIOS_USB_RECOVERY")
	)
	(segment
		(start 386.84327 -97.004378)
		(end 386.84327 -96.35617)
		(width 0.089408)
		(layer "In9.Cu")
		(net "FM_BIOS_USB_RECOVERY")
	)
	(segment
		(start 387.24205 -99.617022)
		(end 387.24205 -99.132644)
		(width 0.089408)
		(layer "In9.Cu")
		(net "FM_BIOS_USB_RECOVERY")
	)
	(segment
		(start 397.493998 -61.45022)
		(end 397.493998 -60.97524)
		(width 0.089408)
		(layer "In9.Cu")
		(net "FM_BIOS_USB_RECOVERY")
	)
	(segment
		(start 387.14553 -97.306638)
		(end 386.84327 -97.004378)
		(width 0.089408)
		(layer "In9.Cu")
		(net "FM_BIOS_USB_RECOVERY")
	)
	(segment
		(start 398.55521 -26.508456)
		(end 398.678146 -26.38552)
		(width 0.089408)
		(layer "In9.Cu")
		(net "FM_BIOS_USB_RECOVERY")
	)
	(segment
		(start 399.25498 -42.681398)
		(end 399.25498 -41.693338)
		(width 0.089408)
		(layer "In9.Cu")
		(net "FM_BIOS_USB_RECOVERY")
	)
	(segment
		(start 386.84327 -98.733864)
		(end 386.84327 -98.122994)
		(width 0.089408)
		(layer "In9.Cu")
		(net "FM_BIOS_USB_RECOVERY")
	)
	(segment
		(start 395.85011 -69.301868)
		(end 395.85011 -64.82969)
		(width 0.089408)
		(layer "In9.Cu")
		(net "FM_BIOS_USB_RECOVERY")
	)
	(segment
		(start 399.184876 -31.165292)
		(end 398.634712 -30.615128)
		(width 0.089408)
		(layer "In9.Cu")
		(net "FM_BIOS_USB_RECOVERY")
	)
	(segment
		(start 387.685788 -91.717876)
		(end 387.685788 -90.228674)
		(width 0.089408)
		(layer "In9.Cu")
		(net "FM_BIOS_USB_RECOVERY")
	)
	(segment
		(start 397.129254 -58.650886)
		(end 397.129254 -48.701706)
		(width 0.089408)
		(layer "In9.Cu")
		(net "FM_BIOS_USB_RECOVERY")
	)
	(segment
		(start 398.678146 -26.371042)
		(end 399.893536 -25.155652)
		(width 0.089408)
		(layer "In9.Cu")
		(net "FM_BIOS_USB_RECOVERY")
	)
	(segment
		(start 391.318496 -82.614262)
		(end 391.318496 -82.12836)
		(width 0.089408)
		(layer "In9.Cu")
		(net "FM_BIOS_USB_RECOVERY")
	)
	(segment
		(start 399.893536 -25.155652)
		(end 399.893536 -24.748998)
		(width 0.089408)
		(layer "In9.Cu")
		(net "FM_BIOS_USB_RECOVERY")
	)
	(segment
		(start 399.01368 -37.121592)
		(end 399.184876 -36.950396)
		(width 0.089408)
		(layer "In9.Cu")
		(net "FM_BIOS_USB_RECOVERY")
	)
	(segment
		(start 393.305792 -76.1365)
		(end 393.305792 -74.025506)
		(width 0.089408)
		(layer "In9.Cu")
		(net "FM_BIOS_USB_RECOVERY")
	)
	(segment
		(start 399.01368 -41.452038)
		(end 399.01368 -37.121592)
		(width 0.089408)
		(layer "In9.Cu")
		(net "FM_BIOS_USB_RECOVERY")
	)
	(segment
		(start 399.893536 -24.748998)
		(end 399.436844 -24.292306)
		(width 0.089408)
		(layer "In9.Cu")
		(net "FM_BIOS_USB_RECOVERY")
	)
	(segment
		(start 392.065256 -79.600552)
		(end 391.739628 -79.274924)
		(width 0.089408)
		(layer "In9.Cu")
		(net "FM_BIOS_USB_RECOVERY")
	)
	(segment
		(start 398.678146 -26.38552)
		(end 398.678146 -26.371042)
		(width 0.089408)
		(layer "In9.Cu")
		(net "FM_BIOS_USB_RECOVERY")
	)
	(segment
		(start 398.634712 -30.615128)
		(end 398.634712 -28.556458)
		(width 0.089408)
		(layer "In9.Cu")
		(net "FM_BIOS_USB_RECOVERY")
	)
	(segment
		(start 386.84327 -98.122994)
		(end 387.14553 -97.820734)
		(width 0.089408)
		(layer "In9.Cu")
		(net "FM_BIOS_USB_RECOVERY")
	)
	(segment
		(start 397.493744 -60.974986)
		(end 397.493744 -59.015376)
		(width 0.089408)
		(layer "In9.Cu")
		(net "FM_BIOS_USB_RECOVERY")
	)
	(segment
		(start 386.677916 -100.181156)
		(end 387.24205 -99.617022)
		(width 0.089408)
		(layer "In9.Cu")
		(net "FM_BIOS_USB_RECOVERY")
	)
	(segment
		(start 387.14553 -97.820734)
		(end 387.14553 -97.306638)
		(width 0.089408)
		(layer "In9.Cu")
		(net "FM_BIOS_USB_RECOVERY")
	)
	(segment
		(start 388.667752 -89.24671)
		(end 388.667752 -88.442546)
		(width 0.089408)
		(layer "In9.Cu")
		(net "FM_BIOS_USB_RECOVERY")
	)
	(segment
		(start 399.184876 -36.950396)
		(end 399.184876 -31.165292)
		(width 0.089408)
		(layer "In9.Cu")
		(net "FM_BIOS_USB_RECOVERY")
	)
	(segment
		(start 174.098966 -135.592566)
		(end 174.8409 -135.592566)
		(width 0.254)
		(layer "F.Cu")
		(net "VR_VB_PVPP_KLM")
	)
	(segment
		(start 173.863 -135.3566)
		(end 174.098966 -135.592566)
		(width 0.254)
		(layer "F.Cu")
		(net "VR_VB_PVPP_KLM")
	)
	(via
		(at 173.863 -135.3566)
		(size 0.508)
		(drill 0.254)
		(layers "F.Cu" "B.Cu")
		(net "VR_VB_PVPP_KLM")
	)
	(via
		(at 174.8282 -135.3566)
		(size 0.6604)
		(drill 0.3302)
		(layers "F.Cu" "B.Cu")
		(net "VR_VB_PVPP_KLM")
	)
	(segment
		(start 174.058834 -135.6106)
		(end 173.863 -135.414766)
		(width 0.4064)
		(layer "B.Cu")
		(net "VR_VB_PVPP_KLM")
	)
	(segment
		(start 173.863 -135.3566)
		(end 173.5836 -135.636)
		(width 0.508)
		(layer "B.Cu")
		(net "VR_VB_PVPP_KLM")
	)
	(segment
		(start 174.8282 -135.3566)
		(end 174.5742 -135.6106)
		(width 0.4064)
		(layer "B.Cu")
		(net "VR_VB_PVPP_KLM")
	)
	(segment
		(start 173.5836 -135.636)
		(end 172.6692 -135.636)
		(width 0.508)
		(layer "B.Cu")
		(net "VR_VB_PVPP_KLM")
	)
	(segment
		(start 174.5742 -135.6106)
		(end 174.058834 -135.6106)
		(width 0.4064)
		(layer "B.Cu")
		(net "VR_VB_PVPP_KLM")
	)
	(segment
		(start 173.863 -135.414766)
		(end 173.863 -135.3566)
		(width 0.4064)
		(layer "B.Cu")
		(net "VR_VB_PVPP_KLM")
	)
	(segment
		(start 174.225966 -12.085066)
		(end 173.99 -11.8491)
		(width 0.254)
		(layer "F.Cu")
		(net "VR_VB_PVPP_GHJ")
	)
	(segment
		(start 174.8409 -12.085066)
		(end 174.225966 -12.085066)
		(width 0.254)
		(layer "F.Cu")
		(net "VR_VB_PVPP_GHJ")
	)
	(via
		(at 173.99 -11.8491)
		(size 0.508)
		(drill 0.254)
		(layers "F.Cu" "B.Cu")
		(net "VR_VB_PVPP_GHJ")
	)
	(via
		(at 172.6692 -13.6144)
		(size 0.6604)
		(drill 0.3302)
		(layers "F.Cu" "B.Cu")
		(net "VR_VB_PVPP_GHJ")
	)
	(segment
		(start 172.8724 -12.1412)
		(end 172.8724 -13.4112)
		(width 0.254)
		(layer "B.Cu")
		(net "VR_VB_PVPP_GHJ")
	)
	(segment
		(start 173.6979 -12.1412)
		(end 172.8724 -12.1412)
		(width 0.254)
		(layer "B.Cu")
		(net "VR_VB_PVPP_GHJ")
	)
	(segment
		(start 173.99 -11.8491)
		(end 173.6979 -12.1412)
		(width 0.254)
		(layer "B.Cu")
		(net "VR_VB_PVPP_GHJ")
	)
	(segment
		(start 172.8724 -13.4112)
		(end 172.6692 -13.6144)
		(width 0.254)
		(layer "B.Cu")
		(net "VR_VB_PVPP_GHJ")
	)
	(segment
		(start 340.530434 -131.604766)
		(end 340.3346 -131.8006)
		(width 0.254)
		(layer "F.Cu")
		(net "VR_VB_PVPP_DEF")
	)
	(segment
		(start 341.2109 -131.604766)
		(end 340.530434 -131.604766)
		(width 0.254)
		(layer "F.Cu")
		(net "VR_VB_PVPP_DEF")
	)
	(via
		(at 340.3346 -131.8006)
		(size 0.508)
		(drill 0.254)
		(layers "F.Cu" "B.Cu")
		(net "VR_VB_PVPP_DEF")
	)
	(segment
		(start 339.471 -131.8006)
		(end 340.3346 -131.8006)
		(width 0.508)
		(layer "B.Cu")
		(net "VR_VB_PVPP_DEF")
	)
	(segment
		(start 339.3186 -131.6482)
		(end 339.471 -131.8006)
		(width 0.508)
		(layer "B.Cu")
		(net "VR_VB_PVPP_DEF")
	)
	(segment
		(start 175.423068 -134.0104)
		(end 174.838868 -133.4262)
		(width 0.254)
		(layer "F.Cu")
		(net "VR_PVPP_KLM_SS")
	)
	(segment
		(start 174.838868 -132.979668)
		(end 173.8884 -132.0292)
		(width 0.254)
		(layer "F.Cu")
		(net "VR_PVPP_KLM_SS")
	)
	(segment
		(start 173.8757 -132.0292)
		(end 173.355 -131.5085)
		(width 0.254)
		(layer "F.Cu")
		(net "VR_PVPP_KLM_SS")
	)
	(segment
		(start 173.8884 -132.0292)
		(end 173.8757 -132.0292)
		(width 0.254)
		(layer "F.Cu")
		(net "VR_PVPP_KLM_SS")
	)
	(segment
		(start 174.838868 -133.4262)
		(end 174.838868 -132.979668)
		(width 0.254)
		(layer "F.Cu")
		(net "VR_PVPP_KLM_SS")
	)
	(segment
		(start 176.922938 -134.0104)
		(end 176.922938 -133.428994)
		(width 0.254)
		(layer "F.Cu")
		(net "VR_PVPP_KLM_ISET")
	)
	(segment
		(start 177.4825 -129.154936)
		(end 177.4825 -131.6101)
		(width 0.1524)
		(layer "F.Cu")
		(net "VR_PVPP_KLM_ISET")
	)
	(segment
		(start 177.568352 -132.298948)
		(end 177.927 -131.9403)
		(width 0.254)
		(layer "F.Cu")
		(net "VR_PVPP_KLM_ISET")
	)
	(segment
		(start 177.061876 -128.734312)
		(end 177.4825 -129.154936)
		(width 0.1524)
		(layer "F.Cu")
		(net "VR_PVPP_KLM_ISET")
	)
	(segment
		(start 177.927 -131.9403)
		(end 177.927 -131.7625)
		(width 0.254)
		(layer "F.Cu")
		(net "VR_PVPP_KLM_ISET")
	)
	(segment
		(start 177.4825 -131.6101)
		(end 177.6349 -131.7625)
		(width 0.1524)
		(layer "F.Cu")
		(net "VR_PVPP_KLM_ISET")
	)
	(segment
		(start 176.922938 -133.428994)
		(end 177.568352 -132.78358)
		(width 0.254)
		(layer "F.Cu")
		(net "VR_PVPP_KLM_ISET")
	)
	(segment
		(start 177.6349 -131.7625)
		(end 177.927 -131.7625)
		(width 0.1524)
		(layer "F.Cu")
		(net "VR_PVPP_KLM_ISET")
	)
	(segment
		(start 177.568352 -132.78358)
		(end 177.568352 -132.298948)
		(width 0.254)
		(layer "F.Cu")
		(net "VR_PVPP_KLM_ISET")
	)
	(via
		(at 177.061876 -128.734312)
		(size 0.762)
		(drill 0.381)
		(layers "F.Cu" "B.Cu")
		(net "VR_PVPP_KLM_ISET")
	)
	(segment
		(start 174.331884 -9.402826)
		(end 173.70933 -9.402826)
		(width 0.254)
		(layer "F.Cu")
		(net "VR_PVPP_GHJ_SS")
	)
	(segment
		(start 174.625 -9.695942)
		(end 174.331884 -9.402826)
		(width 0.254)
		(layer "F.Cu")
		(net "VR_PVPP_GHJ_SS")
	)
	(segment
		(start 174.625 -9.837166)
		(end 174.625 -9.695942)
		(width 0.254)
		(layer "F.Cu")
		(net "VR_PVPP_GHJ_SS")
	)
	(segment
		(start 173.70933 -9.402826)
		(end 173.355 -9.048496)
		(width 0.254)
		(layer "F.Cu")
		(net "VR_PVPP_GHJ_SS")
	)
	(segment
		(start 175.290734 -10.5029)
		(end 174.625 -9.837166)
		(width 0.254)
		(layer "F.Cu")
		(net "VR_PVPP_GHJ_SS")
	)
	(segment
		(start 173.355 -9.048496)
		(end 173.355 -8.6995)
		(width 0.254)
		(layer "F.Cu")
		(net "VR_PVPP_GHJ_SS")
	)
	(segment
		(start 175.423068 -10.5029)
		(end 175.290734 -10.5029)
		(width 0.254)
		(layer "F.Cu")
		(net "VR_PVPP_GHJ_SS")
	)
	(segment
		(start 176.922938 -10.075164)
		(end 176.922938 -10.5029)
		(width 0.2032)
		(layer "F.Cu")
		(net "VR_PVPP_GHJ_ISET")
	)
	(segment
		(start 177.6222 -8.7376)
		(end 177.927 -8.4328)
		(width 0.254)
		(layer "F.Cu")
		(net "VR_PVPP_GHJ_ISET")
	)
	(segment
		(start 177.6222 -9.147048)
		(end 177.6222 -8.7376)
		(width 0.254)
		(layer "F.Cu")
		(net "VR_PVPP_GHJ_ISET")
	)
	(segment
		(start 177.6222 -9.375902)
		(end 177.162968 -9.835134)
		(width 0.254)
		(layer "F.Cu")
		(net "VR_PVPP_GHJ_ISET")
	)
	(segment
		(start 177.927 -8.4328)
		(end 177.927 -8.255)
		(width 0.254)
		(layer "F.Cu")
		(net "VR_PVPP_GHJ_ISET")
	)
	(segment
		(start 177.162968 -9.835134)
		(end 176.922938 -10.075164)
		(width 0.2032)
		(layer "F.Cu")
		(net "VR_PVPP_GHJ_ISET")
	)
	(segment
		(start 177.6222 -9.147048)
		(end 177.6222 -9.375902)
		(width 0.254)
		(layer "F.Cu")
		(net "VR_PVPP_GHJ_ISET")
	)
	(via
		(at 177.6222 -9.147048)
		(size 0.508)
		(drill 0.254)
		(layers "F.Cu" "B.Cu")
		(net "VR_PVPP_GHJ_ISET")
	)
	(segment
		(start 341.54618 -130.0226)
		(end 340.273894 -128.750314)
		(width 0.254)
		(layer "F.Cu")
		(net "VR_PVPP_DEF_SS")
	)
	(segment
		(start 340.273894 -128.750314)
		(end 340.273894 -128.67513)
		(width 0.254)
		(layer "F.Cu")
		(net "VR_PVPP_DEF_SS")
	)
	(segment
		(start 340.125304 -128.52654)
		(end 340.12124 -128.52654)
		(width 0.254)
		(layer "F.Cu")
		(net "VR_PVPP_DEF_SS")
	)
	(segment
		(start 340.273894 -128.67513)
		(end 340.125304 -128.52654)
		(width 0.254)
		(layer "F.Cu")
		(net "VR_PVPP_DEF_SS")
	)
	(segment
		(start 340.12124 -128.52654)
		(end 339.9282 -128.3335)
		(width 0.254)
		(layer "F.Cu")
		(net "VR_PVPP_DEF_SS")
	)
	(segment
		(start 341.793068 -130.0226)
		(end 341.54618 -130.0226)
		(width 0.254)
		(layer "F.Cu")
		(net "VR_PVPP_DEF_SS")
	)
	(segment
		(start 343.980516 -128.295908)
		(end 343.980516 -127.875284)
		(width 0.254)
		(layer "F.Cu")
		(net "VR_PVPP_DEF_ISET")
	)
	(segment
		(start 343.980516 -127.875284)
		(end 344.043 -127.8128)
		(width 0.254)
		(layer "F.Cu")
		(net "VR_PVPP_DEF_ISET")
	)
	(segment
		(start 344.043 -127.8128)
		(end 344.043 -127.4572)
		(width 0.254)
		(layer "F.Cu")
		(net "VR_PVPP_DEF_ISET")
	)
	(segment
		(start 343.292938 -129.628646)
		(end 343.8398 -129.081784)
		(width 0.254)
		(layer "F.Cu")
		(net "VR_PVPP_DEF_ISET")
	)
	(segment
		(start 343.8398 -129.081784)
		(end 343.8398 -128.6764)
		(width 0.254)
		(layer "F.Cu")
		(net "VR_PVPP_DEF_ISET")
	)
	(segment
		(start 343.292938 -130.0226)
		(end 343.292938 -129.628646)
		(width 0.254)
		(layer "F.Cu")
		(net "VR_PVPP_DEF_ISET")
	)
	(segment
		(start 343.980516 -128.535684)
		(end 343.980516 -128.323848)
		(width 0.254)
		(layer "F.Cu")
		(net "VR_PVPP_DEF_ISET")
	)
	(segment
		(start 343.980516 -128.323848)
		(end 343.994486 -128.309878)
		(width 0.254)
		(layer "F.Cu")
		(net "VR_PVPP_DEF_ISET")
	)
	(segment
		(start 343.8398 -128.6764)
		(end 343.980516 -128.535684)
		(width 0.254)
		(layer "F.Cu")
		(net "VR_PVPP_DEF_ISET")
	)
	(segment
		(start 343.994486 -128.309878)
		(end 343.980516 -128.295908)
		(width 0.254)
		(layer "F.Cu")
		(net "VR_PVPP_DEF_ISET")
	)
	(via
		(at 343.994486 -128.309878)
		(size 0.508)
		(drill 0.254)
		(layers "F.Cu" "B.Cu")
		(net "VR_PVPP_DEF_ISET")
	)
	(segment
		(start 170.7896 -131.8895)
		(end 171.577 -131.8895)
		(width 0.254)
		(layer "F.Cu")
		(net "VR_FB_PVPP_KLM")
	)
	(segment
		(start 175.92294 -134.0104)
		(end 175.92294 -133.45414)
		(width 0.254)
		(layer "F.Cu")
		(net "VR_FB_PVPP_KLM")
	)
	(segment
		(start 176.0855 -132.334)
		(end 175.5013 -132.9182)
		(width 0.254)
		(layer "F.Cu")
		(net "VR_FB_PVPP_KLM")
	)
	(segment
		(start 174.244 -131.5085)
		(end 174.244 -131.6228)
		(width 0.254)
		(layer "F.Cu")
		(net "VR_FB_PVPP_KLM")
	)
	(segment
		(start 176.022 -132.2705)
		(end 176.0855 -132.334)
		(width 0.254)
		(layer "F.Cu")
		(net "VR_FB_PVPP_KLM")
	)
	(segment
		(start 175.92294 -133.45414)
		(end 175.387 -132.9182)
		(width 0.254)
		(layer "F.Cu")
		(net "VR_FB_PVPP_KLM")
	)
	(segment
		(start 174.244 -131.6228)
		(end 174.8917 -132.2705)
		(width 0.254)
		(layer "F.Cu")
		(net "VR_FB_PVPP_KLM")
	)
	(segment
		(start 174.8917 -132.2705)
		(end 175.133 -132.2705)
		(width 0.254)
		(layer "F.Cu")
		(net "VR_FB_PVPP_KLM")
	)
	(segment
		(start 171.577 -131.8895)
		(end 171.577 -132.5626)
		(width 0.254)
		(layer "F.Cu")
		(net "VR_FB_PVPP_KLM")
	)
	(segment
		(start 175.5013 -132.9182)
		(end 175.387 -132.9182)
		(width 0.254)
		(layer "F.Cu")
		(net "VR_FB_PVPP_KLM")
	)
	(segment
		(start 175.133 -132.2705)
		(end 176.022 -132.2705)
		(width 0.254)
		(layer "F.Cu")
		(net "VR_FB_PVPP_KLM")
	)
	(via
		(at 171.577 -132.5626)
		(size 0.508)
		(drill 0.254)
		(layers "F.Cu" "B.Cu")
		(net "VR_FB_PVPP_KLM")
	)
	(via
		(at 175.387 -132.9182)
		(size 0.508)
		(drill 0.254)
		(layers "F.Cu" "B.Cu")
		(net "VR_FB_PVPP_KLM")
	)
	(via
		(at 173.249082 -132.280406)
		(size 0.6604)
		(drill 0.3302)
		(layers "F.Cu" "B.Cu")
		(net "VR_FB_PVPP_KLM")
	)
	(segment
		(start 174.749206 -132.280406)
		(end 173.249082 -132.280406)
		(width 0.254)
		(layer "B.Cu")
		(net "VR_FB_PVPP_KLM")
	)
	(segment
		(start 172.966888 -132.5626)
		(end 171.577 -132.5626)
		(width 0.254)
		(layer "B.Cu")
		(net "VR_FB_PVPP_KLM")
	)
	(segment
		(start 175.387 -132.9182)
		(end 174.749206 -132.280406)
		(width 0.254)
		(layer "B.Cu")
		(net "VR_FB_PVPP_KLM")
	)
	(segment
		(start 173.249082 -132.280406)
		(end 172.966888 -132.5626)
		(width 0.254)
		(layer "B.Cu")
		(net "VR_FB_PVPP_KLM")
	)
	(segment
		(start 175.92294 -9.45896)
		(end 176.0855 -9.2964)
		(width 0.254)
		(layer "F.Cu")
		(net "VR_FB_PVPP_GHJ")
	)
	(segment
		(start 169.6212 -8.0137)
		(end 169.5831 -8.0518)
		(width 0.127)
		(layer "F.Cu")
		(net "VR_FB_PVPP_GHJ")
	)
	(segment
		(start 169.5831 -8.0518)
		(end 169.5831 -8.763)
		(width 0.127)
		(layer "F.Cu")
		(net "VR_FB_PVPP_GHJ")
	)
	(segment
		(start 170.166538 -9.346438)
		(end 169.5831 -8.763)
		(width 0.127)
		(layer "F.Cu")
		(net "VR_FB_PVPP_GHJ")
	)
	(segment
		(start 175.92294 -10.5029)
		(end 175.92294 -9.45896)
		(width 0.254)
		(layer "F.Cu")
		(net "VR_FB_PVPP_GHJ")
	)
	(segment
		(start 175.133 -8.6995)
		(end 174.244 -8.6995)
		(width 0.254)
		(layer "F.Cu")
		(net "VR_FB_PVPP_GHJ")
	)
	(segment
		(start 175.133 -8.6995)
		(end 175.133 -9.6266)
		(width 0.254)
		(layer "F.Cu")
		(net "VR_FB_PVPP_GHJ")
	)
	(segment
		(start 171.50969 -9.346438)
		(end 170.166538 -9.346438)
		(width 0.127)
		(layer "F.Cu")
		(net "VR_FB_PVPP_GHJ")
	)
	(segment
		(start 176.0855 -9.2964)
		(end 176.0855 -8.763)
		(width 0.254)
		(layer "F.Cu")
		(net "VR_FB_PVPP_GHJ")
	)
	(segment
		(start 176.0855 -8.763)
		(end 175.685196 -8.763)
		(width 0.254)
		(layer "F.Cu")
		(net "VR_FB_PVPP_GHJ")
	)
	(segment
		(start 175.685196 -8.763)
		(end 175.621696 -8.6995)
		(width 0.254)
		(layer "F.Cu")
		(net "VR_FB_PVPP_GHJ")
	)
	(segment
		(start 175.621696 -8.6995)
		(end 175.133 -8.6995)
		(width 0.254)
		(layer "F.Cu")
		(net "VR_FB_PVPP_GHJ")
	)
	(via
		(at 171.50969 -9.346438)
		(size 0.508)
		(drill 0.254)
		(layers "F.Cu" "B.Cu")
		(net "VR_FB_PVPP_GHJ")
	)
	(via
		(at 175.133 -9.6266)
		(size 0.508)
		(drill 0.254)
		(layers "F.Cu" "B.Cu")
		(net "VR_FB_PVPP_GHJ")
	)
	(via
		(at 173.4058 -8.7376)
		(size 0.6604)
		(drill 0.3302)
		(layers "F.Cu" "B.Cu")
		(net "VR_FB_PVPP_GHJ")
	)
	(segment
		(start 174.244 -8.7376)
		(end 173.4058 -8.7376)
		(width 0.254)
		(layer "B.Cu")
		(net "VR_FB_PVPP_GHJ")
	)
	(segment
		(start 175.133 -9.6266)
		(end 174.244 -8.7376)
		(width 0.254)
		(layer "B.Cu")
		(net "VR_FB_PVPP_GHJ")
	)
	(segment
		(start 172.118528 -8.7376)
		(end 171.50969 -9.346438)
		(width 0.254)
		(layer "B.Cu")
		(net "VR_FB_PVPP_GHJ")
	)
	(segment
		(start 173.4058 -8.7376)
		(end 172.118528 -8.7376)
		(width 0.254)
		(layer "B.Cu")
		(net "VR_FB_PVPP_GHJ")
	)
	(segment
		(start 342.29294 -129.578354)
		(end 342.29294 -130.0226)
		(width 0.254)
		(layer "F.Cu")
		(net "VR_FB_PVPP_DEF")
	)
	(segment
		(start 342.4428 -127.7366)
		(end 341.8459 -128.3335)
		(width 0.254)
		(layer "F.Cu")
		(net "VR_FB_PVPP_DEF")
	)
	(segment
		(start 342.194134 -129.479548)
		(end 342.29294 -129.578354)
		(width 0.254)
		(layer "F.Cu")
		(net "VR_FB_PVPP_DEF")
	)
	(segment
		(start 341.8459 -128.3335)
		(end 341.6046 -128.3335)
		(width 0.254)
		(layer "F.Cu")
		(net "VR_FB_PVPP_DEF")
	)
	(segment
		(start 340.7664 -128.3335)
		(end 341.6046 -128.3335)
		(width 0.254)
		(layer "F.Cu")
		(net "VR_FB_PVPP_DEF")
	)
	(segment
		(start 342.158574 -128.887474)
		(end 342.158574 -129.011426)
		(width 0.254)
		(layer "F.Cu")
		(net "VR_FB_PVPP_DEF")
	)
	(segment
		(start 342.4428 -127.5588)
		(end 342.4428 -127.7366)
		(width 0.254)
		(layer "F.Cu")
		(net "VR_FB_PVPP_DEF")
	)
	(segment
		(start 341.6046 -128.3335)
		(end 342.158574 -128.887474)
		(width 0.254)
		(layer "F.Cu")
		(net "VR_FB_PVPP_DEF")
	)
	(segment
		(start 338.455 -129.3114)
		(end 338.2391 -129.0955)
		(width 0.254)
		(layer "F.Cu")
		(net "VR_FB_PVPP_DEF")
	)
	(segment
		(start 337.82 -129.0955)
		(end 337.0326 -129.0955)
		(width 0.254)
		(layer "F.Cu")
		(net "VR_FB_PVPP_DEF")
	)
	(segment
		(start 338.2391 -129.0955)
		(end 337.82 -129.0955)
		(width 0.254)
		(layer "F.Cu")
		(net "VR_FB_PVPP_DEF")
	)
	(segment
		(start 342.158574 -129.011426)
		(end 342.194134 -129.046986)
		(width 0.254)
		(layer "F.Cu")
		(net "VR_FB_PVPP_DEF")
	)
	(segment
		(start 342.194134 -129.046986)
		(end 342.194134 -129.479548)
		(width 0.254)
		(layer "F.Cu")
		(net "VR_FB_PVPP_DEF")
	)
	(via
		(at 342.158574 -129.011426)
		(size 0.508)
		(drill 0.254)
		(layers "F.Cu" "B.Cu")
		(net "VR_FB_PVPP_DEF")
	)
	(via
		(at 338.455 -129.3114)
		(size 0.508)
		(drill 0.254)
		(layers "F.Cu" "B.Cu")
		(net "VR_FB_PVPP_DEF")
	)
	(segment
		(start 338.7598 -129.3114)
		(end 338.455 -129.3114)
		(width 0.254)
		(layer "B.Cu")
		(net "VR_FB_PVPP_DEF")
	)
	(segment
		(start 341.721948 -128.5748)
		(end 340.36 -128.5748)
		(width 0.254)
		(layer "B.Cu")
		(net "VR_FB_PVPP_DEF")
	)
	(segment
		(start 340.36 -128.5748)
		(end 339.4837 -129.4511)
		(width 0.254)
		(layer "B.Cu")
		(net "VR_FB_PVPP_DEF")
	)
	(segment
		(start 342.158574 -129.011426)
		(end 341.721948 -128.5748)
		(width 0.254)
		(layer "B.Cu")
		(net "VR_FB_PVPP_DEF")
	)
	(segment
		(start 338.8995 -129.4511)
		(end 338.7598 -129.3114)
		(width 0.254)
		(layer "B.Cu")
		(net "VR_FB_PVPP_DEF")
	)
	(segment
		(start 339.4837 -129.4511)
		(end 338.8995 -129.4511)
		(width 0.254)
		(layer "B.Cu")
		(net "VR_FB_PVPP_DEF")
	)
	(segment
		(start 175.133 -131.3815)
		(end 175.133 -130.4036)
		(width 0.254)
		(layer "F.Cu")
		(net "VR_COMP_RC_PVPP_KLM")
	)
	(segment
		(start 175.6156 -130.1242)
		(end 176.0855 -130.5941)
		(width 0.254)
		(layer "F.Cu")
		(net "VR_COMP_RC_PVPP_KLM")
	)
	(segment
		(start 175.514 -130.1242)
		(end 175.6156 -130.1242)
		(width 0.254)
		(layer "F.Cu")
		(net "VR_COMP_RC_PVPP_KLM")
	)
	(segment
		(start 175.4124 -130.1242)
		(end 175.514 -130.1242)
		(width 0.254)
		(layer "F.Cu")
		(net "VR_COMP_RC_PVPP_KLM")
	)
	(segment
		(start 175.133 -130.4036)
		(end 175.4124 -130.1242)
		(width 0.254)
		(layer "F.Cu")
		(net "VR_COMP_RC_PVPP_KLM")
	)
	(segment
		(start 176.0855 -130.5941)
		(end 176.0855 -131.318)
		(width 0.254)
		(layer "F.Cu")
		(net "VR_COMP_RC_PVPP_KLM")
	)
	(via
		(at 175.514 -130.1242)
		(size 0.762)
		(drill 0.381)
		(layers "F.Cu" "B.Cu")
		(net "VR_COMP_RC_PVPP_KLM")
	)
	(segment
		(start 175.6156 -6.5532)
		(end 175.6156 -6.858)
		(width 0.254)
		(layer "F.Cu")
		(net "VR_COMP_RC_PVPP_GHJ")
	)
	(segment
		(start 175.133 -7.3406)
		(end 175.133 -7.8105)
		(width 0.254)
		(layer "F.Cu")
		(net "VR_COMP_RC_PVPP_GHJ")
	)
	(segment
		(start 176.0855 -7.874)
		(end 176.022 -7.8105)
		(width 0.254)
		(layer "F.Cu")
		(net "VR_COMP_RC_PVPP_GHJ")
	)
	(segment
		(start 175.6156 -6.858)
		(end 175.133 -7.3406)
		(width 0.254)
		(layer "F.Cu")
		(net "VR_COMP_RC_PVPP_GHJ")
	)
	(segment
		(start 176.022 -7.8105)
		(end 175.133 -7.8105)
		(width 0.254)
		(layer "F.Cu")
		(net "VR_COMP_RC_PVPP_GHJ")
	)
	(via
		(at 175.6156 -6.5532)
		(size 0.762)
		(drill 0.381)
		(layers "F.Cu" "B.Cu")
		(net "VR_COMP_RC_PVPP_GHJ")
	)
	(segment
		(start 341.6046 -127.4064)
		(end 341.9475 -127.0635)
		(width 0.254)
		(layer "F.Cu")
		(net "VR_COMP_RC_PVPP_DEF")
	)
	(segment
		(start 341.6046 -127.4445)
		(end 341.6046 -127.4064)
		(width 0.254)
		(layer "F.Cu")
		(net "VR_COMP_RC_PVPP_DEF")
	)
	(segment
		(start 341.9475 -127.0635)
		(end 342.1253 -127.0635)
		(width 0.254)
		(layer "F.Cu")
		(net "VR_COMP_RC_PVPP_DEF")
	)
	(segment
		(start 342.1253 -127.0635)
		(end 342.4428 -126.746)
		(width 0.254)
		(layer "F.Cu")
		(net "VR_COMP_RC_PVPP_DEF")
	)
	(segment
		(start 171.577 -130.2385)
		(end 171.5135 -130.175)
		(width 0.254)
		(layer "F.Cu")
		(net "VR_COMP_PVPP_KLM")
	)
	(segment
		(start 171.5135 -129.185162)
		(end 171.5135 -130.175)
		(width 0.254)
		(layer "F.Cu")
		(net "VR_COMP_PVPP_KLM")
	)
	(segment
		(start 170.802808 -128.47447)
		(end 171.5135 -129.185162)
		(width 0.254)
		(layer "F.Cu")
		(net "VR_COMP_PVPP_KLM")
	)
	(segment
		(start 171.577 -131.0005)
		(end 171.577 -130.2385)
		(width 0.254)
		(layer "F.Cu")
		(net "VR_COMP_PVPP_KLM")
	)
	(via
		(at 170.802808 -128.47447)
		(size 0.762)
		(drill 0.381)
		(layers "F.Cu" "B.Cu")
		(net "VR_COMP_PVPP_KLM")
	)
	(segment
		(start 168.7322 -7.1247)
		(end 169.6212 -7.1247)
		(width 0.254)
		(layer "F.Cu")
		(net "VR_COMP_PVPP_GHJ")
	)
	(segment
		(start 338.4804 -128.6002)
		(end 338.4804 -128.4605)
		(width 0.254)
		(layer "F.Cu")
		(net "VR_COMP_PVPP_DEF")
	)
	(segment
		(start 337.82 -128.2065)
		(end 337.82 -127.95504)
		(width 0.254)
		(layer "F.Cu")
		(net "VR_COMP_PVPP_DEF")
	)
	(segment
		(start 338.0105 -127.76454)
		(end 338.0105 -127.254)
		(width 0.254)
		(layer "F.Cu")
		(net "VR_COMP_PVPP_DEF")
	)
	(segment
		(start 338.4804 -128.4605)
		(end 338.2264 -128.2065)
		(width 0.254)
		(layer "F.Cu")
		(net "VR_COMP_PVPP_DEF")
	)
	(segment
		(start 337.82 -127.95504)
		(end 338.0105 -127.76454)
		(width 0.254)
		(layer "F.Cu")
		(net "VR_COMP_PVPP_DEF")
	)
	(segment
		(start 338.2264 -128.2065)
		(end 337.82 -128.2065)
		(width 0.254)
		(layer "F.Cu")
		(net "VR_COMP_PVPP_DEF")
	)
	(via
		(at 338.4804 -128.6002)
		(size 0.508)
		(drill 0.254)
		(layers "F.Cu" "B.Cu")
		(net "VR_COMP_PVPP_DEF")
	)
	(segment
		(start 473.456 -47.371)
		(end 474.345 -48.26)
		(width 0.10795)
		(layer "F.Cu")
		(net "IRQ_LOM_ALERT_N")
	)
	(segment
		(start 474.345 -50.9651)
		(end 475.996 -52.6161)
		(width 0.10795)
		(layer "F.Cu")
		(net "IRQ_LOM_ALERT_N")
	)
	(segment
		(start 403.163278 -114.497104)
		(end 402.754084 -114.497104)
		(width 0.0889)
		(layer "F.Cu")
		(net "IRQ_LOM_ALERT_N")
	)
	(segment
		(start 403.512528 -114.846354)
		(end 403.163278 -114.497104)
		(width 0.0889)
		(layer "F.Cu")
		(net "IRQ_LOM_ALERT_N")
	)
	(segment
		(start 473.456 -46.9646)
		(end 473.8116 -46.9646)
		(width 0.10795)
		(layer "F.Cu")
		(net "IRQ_LOM_ALERT_N")
	)
	(segment
		(start 478.057464 -53.785008)
		(end 478.4852 -54.212744)
		(width 0.10795)
		(layer "F.Cu")
		(net "IRQ_LOM_ALERT_N")
	)
	(segment
		(start 401.530566 -114.331242)
		(end 401.5232 -114.338608)
		(width 0.0889)
		(layer "F.Cu")
		(net "IRQ_LOM_ALERT_N")
	)
	(segment
		(start 416.690048 -40.13454)
		(end 417.090098 -40.53459)
		(width 0.10795)
		(layer "F.Cu")
		(net "IRQ_LOM_ALERT_N")
	)
	(segment
		(start 479.8822 -46.717458)
		(end 479.341942 -46.717458)
		(width 0.10795)
		(layer "F.Cu")
		(net "IRQ_LOM_ALERT_N")
	)
	(segment
		(start 401.53082 -114.331242)
		(end 401.530566 -114.331242)
		(width 0.0889)
		(layer "F.Cu")
		(net "IRQ_LOM_ALERT_N")
	)
	(segment
		(start 477.139 -48.0949)
		(end 477.8756 -48.0949)
		(width 0.10795)
		(layer "F.Cu")
		(net "IRQ_LOM_ALERT_N")
	)
	(segment
		(start 402.512784 -114.255804)
		(end 401.606258 -114.255804)
		(width 0.0889)
		(layer "F.Cu")
		(net "IRQ_LOM_ALERT_N")
	)
	(segment
		(start 479.341942 -46.717458)
		(end 478.777554 -47.281846)
		(width 0.10795)
		(layer "F.Cu")
		(net "IRQ_LOM_ALERT_N")
	)
	(segment
		(start 401.5232 -114.338608)
		(end 400.896582 -114.338608)
		(width 0.0889)
		(layer "F.Cu")
		(net "IRQ_LOM_ALERT_N")
	)
	(segment
		(start 475.996 -53.015896)
		(end 476.765112 -53.785008)
		(width 0.10795)
		(layer "F.Cu")
		(net "IRQ_LOM_ALERT_N")
	)
	(segment
		(start 475.996 -52.6161)
		(end 475.996 -53.015896)
		(width 0.10795)
		(layer "F.Cu")
		(net "IRQ_LOM_ALERT_N")
	)
	(segment
		(start 474.345 -48.26)
		(end 474.345 -50.9651)
		(width 0.10795)
		(layer "F.Cu")
		(net "IRQ_LOM_ALERT_N")
	)
	(segment
		(start 476.7326 -47.6885)
		(end 477.139 -48.0949)
		(width 0.10795)
		(layer "F.Cu")
		(net "IRQ_LOM_ALERT_N")
	)
	(segment
		(start 478.777554 -47.281846)
		(end 478.3709 -47.281846)
		(width 0.10795)
		(layer "F.Cu")
		(net "IRQ_LOM_ALERT_N")
	)
	(segment
		(start 473.456 -46.9646)
		(end 473.456 -47.371)
		(width 0.10795)
		(layer "F.Cu")
		(net "IRQ_LOM_ALERT_N")
	)
	(segment
		(start 473.8116 -46.9646)
		(end 474.5355 -47.6885)
		(width 0.10795)
		(layer "F.Cu")
		(net "IRQ_LOM_ALERT_N")
	)
	(segment
		(start 477.8756 -47.777146)
		(end 477.8756 -48.0949)
		(width 0.10795)
		(layer "F.Cu")
		(net "IRQ_LOM_ALERT_N")
	)
	(segment
		(start 478.3709 -47.281846)
		(end 477.8756 -47.777146)
		(width 0.10795)
		(layer "F.Cu")
		(net "IRQ_LOM_ALERT_N")
	)
	(segment
		(start 474.5355 -47.6885)
		(end 476.7326 -47.6885)
		(width 0.10795)
		(layer "F.Cu")
		(net "IRQ_LOM_ALERT_N")
	)
	(segment
		(start 400.896582 -114.338608)
		(end 400.880072 -114.355118)
		(width 0.0889)
		(layer "F.Cu")
		(net "IRQ_LOM_ALERT_N")
	)
	(segment
		(start 402.754084 -114.497104)
		(end 402.512784 -114.255804)
		(width 0.0889)
		(layer "F.Cu")
		(net "IRQ_LOM_ALERT_N")
	)
	(segment
		(start 401.606258 -114.255804)
		(end 401.53082 -114.331242)
		(width 0.0889)
		(layer "F.Cu")
		(net "IRQ_LOM_ALERT_N")
	)
	(segment
		(start 476.765112 -53.785008)
		(end 478.057464 -53.785008)
		(width 0.10795)
		(layer "F.Cu")
		(net "IRQ_LOM_ALERT_N")
	)
	(via
		(at 435.629812 -63.558674)
		(size 0.508)
		(drill 0.254)
		(layers "F.Cu" "B.Cu")
		(net "IRQ_LOM_ALERT_N")
	)
	(via
		(at 417.090098 -40.53459)
		(size 0.4572)
		(drill 0.2032)
		(layers "F.Cu" "B.Cu")
		(net "IRQ_LOM_ALERT_N")
	)
	(via
		(at 403.512528 -114.846354)
		(size 0.508)
		(drill 0.254)
		(layers "F.Cu" "B.Cu")
		(net "IRQ_LOM_ALERT_N")
	)
	(via
		(at 462.366614 -64.672464)
		(size 0.6604)
		(drill 0.3302)
		(layers "F.Cu" "B.Cu")
		(net "IRQ_LOM_ALERT_N")
	)
	(via
		(at 473.456 -46.9646)
		(size 0.508)
		(drill 0.254)
		(layers "F.Cu" "B.Cu")
		(net "IRQ_LOM_ALERT_N")
	)
	(via
		(at 478.4852 -54.212744)
		(size 0.508)
		(drill 0.254)
		(layers "F.Cu" "B.Cu")
		(net "IRQ_LOM_ALERT_N")
	)
	(via
		(at 471.010996 -63.19266)
		(size 0.508)
		(drill 0.254)
		(layers "F.Cu" "B.Cu")
		(net "IRQ_LOM_ALERT_N")
	)
	(segment
		(start 437.074564 -67.36715)
		(end 457.297028 -67.36715)
		(width 0.10795)
		(layer "B.Cu")
		(net "IRQ_LOM_ALERT_N")
	)
	(segment
		(start 457.297028 -67.36715)
		(end 459.991714 -64.672464)
		(width 0.10795)
		(layer "B.Cu")
		(net "IRQ_LOM_ALERT_N")
	)
	(segment
		(start 463.172302 -65.478152)
		(end 462.366614 -64.672464)
		(width 0.10795)
		(layer "B.Cu")
		(net "IRQ_LOM_ALERT_N")
	)
	(segment
		(start 435.629812 -65.922398)
		(end 437.074564 -67.36715)
		(width 0.10795)
		(layer "B.Cu")
		(net "IRQ_LOM_ALERT_N")
	)
	(segment
		(start 465.570824 -65.478152)
		(end 463.172302 -65.478152)
		(width 0.10795)
		(layer "B.Cu")
		(net "IRQ_LOM_ALERT_N")
	)
	(segment
		(start 470.729056 -63.4746)
		(end 467.574376 -63.4746)
		(width 0.10795)
		(layer "B.Cu")
		(net "IRQ_LOM_ALERT_N")
	)
	(segment
		(start 435.629812 -63.558674)
		(end 435.629812 -65.922398)
		(width 0.10795)
		(layer "B.Cu")
		(net "IRQ_LOM_ALERT_N")
	)
	(segment
		(start 467.574376 -63.4746)
		(end 465.570824 -65.478152)
		(width 0.10795)
		(layer "B.Cu")
		(net "IRQ_LOM_ALERT_N")
	)
	(segment
		(start 459.991714 -64.672464)
		(end 462.366614 -64.672464)
		(width 0.10795)
		(layer "B.Cu")
		(net "IRQ_LOM_ALERT_N")
	)
	(segment
		(start 471.010996 -63.19266)
		(end 470.729056 -63.4746)
		(width 0.10795)
		(layer "B.Cu")
		(net "IRQ_LOM_ALERT_N")
	)
	(segment
		(start 465.01558 -40.68318)
		(end 462.853278 -38.520878)
		(width 0.089408)
		(layer "In4.Cu")
		(net "IRQ_LOM_ALERT_N")
	)
	(segment
		(start 434.370734 -39.328598)
		(end 433.023264 -37.981128)
		(width 0.089408)
		(layer "In4.Cu")
		(net "IRQ_LOM_ALERT_N")
	)
	(segment
		(start 468.417656 -42.844212)
		(end 468.417656 -42.26687)
		(width 0.089408)
		(layer "In4.Cu")
		(net "IRQ_LOM_ALERT_N")
	)
	(segment
		(start 446.051178 -39.328598)
		(end 434.370734 -39.328598)
		(width 0.089408)
		(layer "In4.Cu")
		(net "IRQ_LOM_ALERT_N")
	)
	(segment
		(start 457.63561 -36.943792)
		(end 448.435984 -36.943792)
		(width 0.089408)
		(layer "In4.Cu")
		(net "IRQ_LOM_ALERT_N")
	)
	(segment
		(start 421.46474 -42.315638)
		(end 421.212772 -42.567606)
		(width 0.089408)
		(layer "In4.Cu")
		(net "IRQ_LOM_ALERT_N")
	)
	(segment
		(start 473.456 -46.9646)
		(end 473.456 -46.163992)
		(width 0.089408)
		(layer "In4.Cu")
		(net "IRQ_LOM_ALERT_N")
	)
	(segment
		(start 459.212696 -38.520878)
		(end 457.63561 -36.943792)
		(width 0.089408)
		(layer "In4.Cu")
		(net "IRQ_LOM_ALERT_N")
	)
	(segment
		(start 473.456 -46.163992)
		(end 472.2114 -44.919392)
		(width 0.089408)
		(layer "In4.Cu")
		(net "IRQ_LOM_ALERT_N")
	)
	(segment
		(start 462.853278 -38.520878)
		(end 459.212696 -38.520878)
		(width 0.089408)
		(layer "In4.Cu")
		(net "IRQ_LOM_ALERT_N")
	)
	(segment
		(start 421.212772 -42.567606)
		(end 419.32733 -42.567606)
		(width 0.089408)
		(layer "In4.Cu")
		(net "IRQ_LOM_ALERT_N")
	)
	(segment
		(start 418.535104 -41.70934)
		(end 418.243258 -41.417494)
		(width 0.089408)
		(layer "In4.Cu")
		(net "IRQ_LOM_ALERT_N")
	)
	(segment
		(start 422.17213 -41.70934)
		(end 421.65016 -41.70934)
		(width 0.089408)
		(layer "In4.Cu")
		(net "IRQ_LOM_ALERT_N")
	)
	(segment
		(start 418.243258 -41.417494)
		(end 418.243258 -41.157906)
		(width 0.089408)
		(layer "In4.Cu")
		(net "IRQ_LOM_ALERT_N")
	)
	(segment
		(start 468.75954 -43.186096)
		(end 468.417656 -42.844212)
		(width 0.089408)
		(layer "In4.Cu")
		(net "IRQ_LOM_ALERT_N")
	)
	(segment
		(start 423.3799 -40.50157)
		(end 422.17213 -41.70934)
		(width 0.089408)
		(layer "In4.Cu")
		(net "IRQ_LOM_ALERT_N")
	)
	(segment
		(start 472.2114 -44.919392)
		(end 472.2114 -44.446698)
		(width 0.089408)
		(layer "In4.Cu")
		(net "IRQ_LOM_ALERT_N")
	)
	(segment
		(start 470.950798 -43.186096)
		(end 468.75954 -43.186096)
		(width 0.089408)
		(layer "In4.Cu")
		(net "IRQ_LOM_ALERT_N")
	)
	(segment
		(start 427.977046 -37.981128)
		(end 425.456604 -40.50157)
		(width 0.089408)
		(layer "In4.Cu")
		(net "IRQ_LOM_ALERT_N")
	)
	(segment
		(start 419.32733 -42.567606)
		(end 419.099238 -42.339514)
		(width 0.089408)
		(layer "In4.Cu")
		(net "IRQ_LOM_ALERT_N")
	)
	(segment
		(start 433.023264 -37.981128)
		(end 427.977046 -37.981128)
		(width 0.089408)
		(layer "In4.Cu")
		(net "IRQ_LOM_ALERT_N")
	)
	(segment
		(start 468.417656 -42.26687)
		(end 466.833966 -40.68318)
		(width 0.089408)
		(layer "In4.Cu")
		(net "IRQ_LOM_ALERT_N")
	)
	(segment
		(start 472.2114 -44.446698)
		(end 470.950798 -43.186096)
		(width 0.089408)
		(layer "In4.Cu")
		(net "IRQ_LOM_ALERT_N")
	)
	(segment
		(start 419.099238 -41.928034)
		(end 418.880544 -41.70934)
		(width 0.089408)
		(layer "In4.Cu")
		(net "IRQ_LOM_ALERT_N")
	)
	(segment
		(start 466.833966 -40.68318)
		(end 465.01558 -40.68318)
		(width 0.089408)
		(layer "In4.Cu")
		(net "IRQ_LOM_ALERT_N")
	)
	(segment
		(start 418.243258 -41.157906)
		(end 418.023548 -40.938196)
		(width 0.089408)
		(layer "In4.Cu")
		(net "IRQ_LOM_ALERT_N")
	)
	(segment
		(start 417.493704 -40.938196)
		(end 417.090098 -40.53459)
		(width 0.089408)
		(layer "In4.Cu")
		(net "IRQ_LOM_ALERT_N")
	)
	(segment
		(start 419.099238 -42.339514)
		(end 419.099238 -41.928034)
		(width 0.089408)
		(layer "In4.Cu")
		(net "IRQ_LOM_ALERT_N")
	)
	(segment
		(start 425.456604 -40.50157)
		(end 423.3799 -40.50157)
		(width 0.089408)
		(layer "In4.Cu")
		(net "IRQ_LOM_ALERT_N")
	)
	(segment
		(start 418.880544 -41.70934)
		(end 418.535104 -41.70934)
		(width 0.089408)
		(layer "In4.Cu")
		(net "IRQ_LOM_ALERT_N")
	)
	(segment
		(start 418.023548 -40.938196)
		(end 417.493704 -40.938196)
		(width 0.089408)
		(layer "In4.Cu")
		(net "IRQ_LOM_ALERT_N")
	)
	(segment
		(start 421.65016 -41.70934)
		(end 421.46474 -41.89476)
		(width 0.089408)
		(layer "In4.Cu")
		(net "IRQ_LOM_ALERT_N")
	)
	(segment
		(start 448.435984 -36.943792)
		(end 446.051178 -39.328598)
		(width 0.089408)
		(layer "In4.Cu")
		(net "IRQ_LOM_ALERT_N")
	)
	(segment
		(start 421.46474 -41.89476)
		(end 421.46474 -42.315638)
		(width 0.089408)
		(layer "In4.Cu")
		(net "IRQ_LOM_ALERT_N")
	)
	(segment
		(start 420.969694 -93.396308)
		(end 418.482018 -95.883984)
		(width 0.089408)
		(layer "In9.Cu")
		(net "IRQ_LOM_ALERT_N")
	)
	(segment
		(start 421.832278 -77.394054)
		(end 420.969694 -78.256638)
		(width 0.089408)
		(layer "In9.Cu")
		(net "IRQ_LOM_ALERT_N")
	)
	(segment
		(start 418.482018 -95.883984)
		(end 417.954206 -95.883984)
		(width 0.089408)
		(layer "In9.Cu")
		(net "IRQ_LOM_ALERT_N")
	)
	(segment
		(start 403.55266 -114.846354)
		(end 403.512528 -114.846354)
		(width 0.089408)
		(layer "In9.Cu")
		(net "IRQ_LOM_ALERT_N")
	)
	(segment
		(start 417.336478 -113.184178)
		(end 416.777932 -113.742724)
		(width 0.089408)
		(layer "In9.Cu")
		(net "IRQ_LOM_ALERT_N")
	)
	(segment
		(start 430.083214 -62.709552)
		(end 428.112174 -62.709552)
		(width 0.089408)
		(layer "In9.Cu")
		(net "IRQ_LOM_ALERT_N")
	)
	(segment
		(start 409.69946 -114.257328)
		(end 409.541472 -114.257328)
		(width 0.089408)
		(layer "In9.Cu")
		(net "IRQ_LOM_ALERT_N")
	)
	(segment
		(start 417.35248 -108.232702)
		(end 417.35248 -111.049816)
		(width 0.089408)
		(layer "In9.Cu")
		(net "IRQ_LOM_ALERT_N")
	)
	(segment
		(start 410.800804 -112.2934)
		(end 410.276802 -112.817402)
		(width 0.089408)
		(layer "In9.Cu")
		(net "IRQ_LOM_ALERT_N")
	)
	(segment
		(start 417.35248 -111.049816)
		(end 417.336478 -111.065818)
		(width 0.089408)
		(layer "In9.Cu")
		(net "IRQ_LOM_ALERT_N")
	)
	(segment
		(start 417.954206 -95.883984)
		(end 415.997644 -97.840546)
		(width 0.089408)
		(layer "In9.Cu")
		(net "IRQ_LOM_ALERT_N")
	)
	(segment
		(start 415.981642 -113.742724)
		(end 414.532318 -112.2934)
		(width 0.089408)
		(layer "In9.Cu")
		(net "IRQ_LOM_ALERT_N")
	)
	(segment
		(start 414.532318 -112.2934)
		(end 410.800804 -112.2934)
		(width 0.089408)
		(layer "In9.Cu")
		(net "IRQ_LOM_ALERT_N")
	)
	(segment
		(start 415.997644 -97.840546)
		(end 415.997644 -106.877866)
		(width 0.089408)
		(layer "In9.Cu")
		(net "IRQ_LOM_ALERT_N")
	)
	(segment
		(start 410.276802 -113.679986)
		(end 409.69946 -114.257328)
		(width 0.089408)
		(layer "In9.Cu")
		(net "IRQ_LOM_ALERT_N")
	)
	(segment
		(start 416.777932 -113.742724)
		(end 415.981642 -113.742724)
		(width 0.089408)
		(layer "In9.Cu")
		(net "IRQ_LOM_ALERT_N")
	)
	(segment
		(start 409.541472 -114.257328)
		(end 409.541218 -114.257074)
		(width 0.089408)
		(layer "In9.Cu")
		(net "IRQ_LOM_ALERT_N")
	)
	(segment
		(start 423.744898 -62.790578)
		(end 421.832278 -64.703198)
		(width 0.089408)
		(layer "In9.Cu")
		(net "IRQ_LOM_ALERT_N")
	)
	(segment
		(start 404.581106 -115.24234)
		(end 403.948646 -115.24234)
		(width 0.089408)
		(layer "In9.Cu")
		(net "IRQ_LOM_ALERT_N")
	)
	(segment
		(start 421.832278 -64.703198)
		(end 421.832278 -77.394054)
		(width 0.089408)
		(layer "In9.Cu")
		(net "IRQ_LOM_ALERT_N")
	)
	(segment
		(start 410.276802 -112.817402)
		(end 410.276802 -113.679986)
		(width 0.089408)
		(layer "In9.Cu")
		(net "IRQ_LOM_ALERT_N")
	)
	(segment
		(start 417.336478 -111.065818)
		(end 417.336478 -113.184178)
		(width 0.089408)
		(layer "In9.Cu")
		(net "IRQ_LOM_ALERT_N")
	)
	(segment
		(start 435.629812 -63.558674)
		(end 430.932336 -63.558674)
		(width 0.089408)
		(layer "In9.Cu")
		(net "IRQ_LOM_ALERT_N")
	)
	(segment
		(start 415.997644 -106.877866)
		(end 417.35248 -108.232702)
		(width 0.089408)
		(layer "In9.Cu")
		(net "IRQ_LOM_ALERT_N")
	)
	(segment
		(start 409.541218 -114.257074)
		(end 405.566372 -114.257074)
		(width 0.089408)
		(layer "In9.Cu")
		(net "IRQ_LOM_ALERT_N")
	)
	(segment
		(start 405.566372 -114.257074)
		(end 404.581106 -115.24234)
		(width 0.089408)
		(layer "In9.Cu")
		(net "IRQ_LOM_ALERT_N")
	)
	(segment
		(start 420.969694 -78.256638)
		(end 420.969694 -93.396308)
		(width 0.089408)
		(layer "In9.Cu")
		(net "IRQ_LOM_ALERT_N")
	)
	(segment
		(start 403.948646 -115.24234)
		(end 403.55266 -114.846354)
		(width 0.089408)
		(layer "In9.Cu")
		(net "IRQ_LOM_ALERT_N")
	)
	(segment
		(start 430.932336 -63.558674)
		(end 430.083214 -62.709552)
		(width 0.089408)
		(layer "In9.Cu")
		(net "IRQ_LOM_ALERT_N")
	)
	(segment
		(start 428.112174 -62.709552)
		(end 428.031148 -62.790578)
		(width 0.089408)
		(layer "In9.Cu")
		(net "IRQ_LOM_ALERT_N")
	)
	(segment
		(start 428.031148 -62.790578)
		(end 423.744898 -62.790578)
		(width 0.089408)
		(layer "In9.Cu")
		(net "IRQ_LOM_ALERT_N")
	)
	(segment
		(start 477.494854 -60.498482)
		(end 476.893636 -59.897264)
		(width 0.089408)
		(layer "In11.Cu")
		(net "IRQ_LOM_ALERT_N")
	)
	(segment
		(start 476.893636 -59.897264)
		(end 476.893636 -57.994042)
		(width 0.089408)
		(layer "In11.Cu")
		(net "IRQ_LOM_ALERT_N")
	)
	(segment
		(start 481.479606 -55.587138)
		(end 483.950772 -55.587138)
		(width 0.089408)
		(layer "In11.Cu")
		(net "IRQ_LOM_ALERT_N")
	)
	(segment
		(start 479.229928 -54.957472)
		(end 480.84994 -54.957472)
		(width 0.089408)
		(layer "In11.Cu")
		(net "IRQ_LOM_ALERT_N")
	)
	(segment
		(start 483.351586 -60.498482)
		(end 477.494854 -60.498482)
		(width 0.089408)
		(layer "In11.Cu")
		(net "IRQ_LOM_ALERT_N")
	)
	(segment
		(start 471.010996 -58.571638)
		(end 471.010996 -63.19266)
		(width 0.089408)
		(layer "In11.Cu")
		(net "IRQ_LOM_ALERT_N")
	)
	(segment
		(start 484.507794 -59.342274)
		(end 483.351586 -60.498482)
		(width 0.089408)
		(layer "In11.Cu")
		(net "IRQ_LOM_ALERT_N")
	)
	(segment
		(start 478.4852 -54.212744)
		(end 479.229928 -54.957472)
		(width 0.089408)
		(layer "In11.Cu")
		(net "IRQ_LOM_ALERT_N")
	)
	(segment
		(start 473.025978 -56.556656)
		(end 471.010996 -58.571638)
		(width 0.089408)
		(layer "In11.Cu")
		(net "IRQ_LOM_ALERT_N")
	)
	(segment
		(start 480.84994 -54.957472)
		(end 481.479606 -55.587138)
		(width 0.089408)
		(layer "In11.Cu")
		(net "IRQ_LOM_ALERT_N")
	)
	(segment
		(start 483.950772 -55.587138)
		(end 484.507794 -56.14416)
		(width 0.089408)
		(layer "In11.Cu")
		(net "IRQ_LOM_ALERT_N")
	)
	(segment
		(start 476.893636 -57.994042)
		(end 475.45625 -56.556656)
		(width 0.089408)
		(layer "In11.Cu")
		(net "IRQ_LOM_ALERT_N")
	)
	(segment
		(start 484.507794 -56.14416)
		(end 484.507794 -59.342274)
		(width 0.089408)
		(layer "In11.Cu")
		(net "IRQ_LOM_ALERT_N")
	)
	(segment
		(start 475.45625 -56.556656)
		(end 473.025978 -56.556656)
		(width 0.089408)
		(layer "In11.Cu")
		(net "IRQ_LOM_ALERT_N")
	)
	(segment
		(start 380.699264 -93.38818)
		(end 380.705614 -93.38183)
		(width 0.0889)
		(layer "F.Cu")
		(net "CLK_24M_BMC_LPC_R")
	)
	(segment
		(start 380.985014 -94.37497)
		(end 380.929896 -94.319852)
		(width 0.0889)
		(layer "F.Cu")
		(net "CLK_24M_BMC_LPC_R")
	)
	(segment
		(start 380.705614 -93.38183)
		(end 380.705614 -92.980002)
		(width 0.0889)
		(layer "F.Cu")
		(net "CLK_24M_BMC_LPC_R")
	)
	(segment
		(start 380.929896 -94.319852)
		(end 380.929896 -93.96476)
		(width 0.0889)
		(layer "F.Cu")
		(net "CLK_24M_BMC_LPC_R")
	)
	(segment
		(start 380.705614 -93.740478)
		(end 380.705614 -93.707966)
		(width 0.0889)
		(layer "F.Cu")
		(net "CLK_24M_BMC_LPC_R")
	)
	(segment
		(start 380.705614 -92.980002)
		(end 380.538482 -92.81287)
		(width 0.0889)
		(layer "F.Cu")
		(net "CLK_24M_BMC_LPC_R")
	)
	(segment
		(start 380.699264 -93.701616)
		(end 380.699264 -93.38818)
		(width 0.0889)
		(layer "F.Cu")
		(net "CLK_24M_BMC_LPC_R")
	)
	(segment
		(start 380.929896 -93.96476)
		(end 380.705614 -93.740478)
		(width 0.0889)
		(layer "F.Cu")
		(net "CLK_24M_BMC_LPC_R")
	)
	(segment
		(start 380.705614 -93.707966)
		(end 380.699264 -93.701616)
		(width 0.0889)
		(layer "F.Cu")
		(net "CLK_24M_BMC_LPC_R")
	)
	(via
		(at 380.538482 -92.81287)
		(size 0.508)
		(drill 0.254)
		(layers "F.Cu" "B.Cu")
		(net "CLK_24M_BMC_LPC_R")
	)
	(segment
		(start 379.481842 -92.301822)
		(end 379.99289 -92.81287)
		(width 0.10795)
		(layer "B.Cu")
		(net "CLK_24M_BMC_LPC_R")
	)
	(segment
		(start 379.99289 -92.81287)
		(end 380.538482 -92.81287)
		(width 0.10795)
		(layer "B.Cu")
		(net "CLK_24M_BMC_LPC_R")
	)
	(segment
		(start 379.481842 -91.910662)
		(end 379.481842 -92.301822)
		(width 0.10795)
		(layer "B.Cu")
		(net "CLK_24M_BMC_LPC_R")
	)
	(segment
		(start 342.54821 -24.385524)
		(end 342.54821 -24.444706)
		(width 0.254)
		(layer "F.Cu")
		(net "VR_PVPP_ABC_SS")
	)
	(segment
		(start 343.113868 -25.7302)
		(end 343.113868 -25.265888)
		(width 0.254)
		(layer "F.Cu")
		(net "VR_PVPP_ABC_SS")
	)
	(segment
		(start 343.113868 -25.265888)
		(end 342.54821 -24.70023)
		(width 0.254)
		(layer "F.Cu")
		(net "VR_PVPP_ABC_SS")
	)
	(segment
		(start 342.54821 -24.70023)
		(end 342.54821 -24.444706)
		(width 0.254)
		(layer "F.Cu")
		(net "VR_PVPP_ABC_SS")
	)
	(segment
		(start 342.138 -23.749)
		(end 342.138 -23.975314)
		(width 0.254)
		(layer "F.Cu")
		(net "VR_PVPP_ABC_SS")
	)
	(segment
		(start 342.138 -23.975314)
		(end 342.54821 -24.385524)
		(width 0.254)
		(layer "F.Cu")
		(net "VR_PVPP_ABC_SS")
	)
	(via
		(at 342.54821 -24.444706)
		(size 0.508)
		(drill 0.254)
		(layers "F.Cu" "B.Cu")
		(net "VR_PVPP_ABC_SS")
	)
	(segment
		(start 344.613738 -25.7302)
		(end 344.613738 -25.280366)
		(width 0.254)
		(layer "F.Cu")
		(net "VR_PVPP_ABC_ISET")
	)
	(segment
		(start 345.352878 -24.408384)
		(end 345.352878 -23.747222)
		(width 0.254)
		(layer "F.Cu")
		(net "VR_PVPP_ABC_ISET")
	)
	(segment
		(start 344.613738 -25.280366)
		(end 345.352878 -24.541226)
		(width 0.254)
		(layer "F.Cu")
		(net "VR_PVPP_ABC_ISET")
	)
	(segment
		(start 345.352878 -23.747222)
		(end 345.6178 -23.4823)
		(width 0.254)
		(layer "F.Cu")
		(net "VR_PVPP_ABC_ISET")
	)
	(segment
		(start 345.352878 -24.541226)
		(end 345.352878 -24.408384)
		(width 0.254)
		(layer "F.Cu")
		(net "VR_PVPP_ABC_ISET")
	)
	(via
		(at 345.352878 -24.408384)
		(size 0.508)
		(drill 0.254)
		(layers "F.Cu" "B.Cu")
		(net "VR_PVPP_ABC_ISET")
	)
	(segment
		(start 343.789 -24.627586)
		(end 343.789 -23.45436)
		(width 0.254)
		(layer "F.Cu")
		(net "VR_FB_PVPP_ABC")
	)
	(segment
		(start 337.439 -24.1554)
		(end 337.439 -23.495)
		(width 0.254)
		(layer "F.Cu")
		(net "VR_FB_PVPP_ABC")
	)
	(segment
		(start 336.7024 -24.1554)
		(end 336.677 -24.13)
		(width 0.254)
		(layer "F.Cu")
		(net "VR_FB_PVPP_ABC")
	)
	(segment
		(start 343.61374 -24.802846)
		(end 343.789 -24.627586)
		(width 0.254)
		(layer "F.Cu")
		(net "VR_FB_PVPP_ABC")
	)
	(segment
		(start 343.37244 -23.53056)
		(end 343.027 -23.53056)
		(width 0.254)
		(layer "F.Cu")
		(net "VR_FB_PVPP_ABC")
	)
	(segment
		(start 343.789 -23.45436)
		(end 343.44864 -23.45436)
		(width 0.254)
		(layer "F.Cu")
		(net "VR_FB_PVPP_ABC")
	)
	(segment
		(start 343.61374 -25.7302)
		(end 343.61374 -24.802846)
		(width 0.254)
		(layer "F.Cu")
		(net "VR_FB_PVPP_ABC")
	)
	(segment
		(start 337.439 -24.1554)
		(end 336.7024 -24.1554)
		(width 0.254)
		(layer "F.Cu")
		(net "VR_FB_PVPP_ABC")
	)
	(segment
		(start 336.677 -23.241)
		(end 336.677 -24.13)
		(width 0.254)
		(layer "F.Cu")
		(net "VR_FB_PVPP_ABC")
	)
	(segment
		(start 343.44864 -23.45436)
		(end 343.37244 -23.53056)
		(width 0.254)
		(layer "F.Cu")
		(net "VR_FB_PVPP_ABC")
	)
	(via
		(at 337.439 -23.495)
		(size 0.508)
		(drill 0.254)
		(layers "F.Cu" "B.Cu")
		(net "VR_FB_PVPP_ABC")
	)
	(via
		(at 343.789 -24.627586)
		(size 0.508)
		(drill 0.254)
		(layers "F.Cu" "B.Cu")
		(net "VR_FB_PVPP_ABC")
	)
	(segment
		(start 343.268046 -23.368)
		(end 337.566 -23.368)
		(width 0.254)
		(layer "B.Cu")
		(net "VR_FB_PVPP_ABC")
	)
	(segment
		(start 337.566 -23.368)
		(end 337.439 -23.495)
		(width 0.254)
		(layer "B.Cu")
		(net "VR_FB_PVPP_ABC")
	)
	(segment
		(start 343.789 -24.627586)
		(end 343.789 -23.888954)
		(width 0.254)
		(layer "B.Cu")
		(net "VR_FB_PVPP_ABC")
	)
	(segment
		(start 343.789 -23.888954)
		(end 343.268046 -23.368)
		(width 0.254)
		(layer "B.Cu")
		(net "VR_FB_PVPP_ABC")
	)
	(segment
		(start 342.5317 -27.312366)
		(end 341.757 -27.312366)
		(width 0.254)
		(layer "F.Cu")
		(net "VR_VB_PVPP_ABC")
	)
	(via
		(at 341.757 -27.312366)
		(size 0.508)
		(drill 0.254)
		(layers "F.Cu" "B.Cu")
		(net "VR_VB_PVPP_ABC")
	)
	(segment
		(start 340.113366 -27.312366)
		(end 341.757 -27.312366)
		(width 0.508)
		(layer "B.Cu")
		(net "VR_VB_PVPP_ABC")
	)
	(segment
		(start 339.979 -27.178)
		(end 340.113366 -27.312366)
		(width 0.508)
		(layer "B.Cu")
		(net "VR_VB_PVPP_ABC")
	)
	(segment
		(start 343.789 -22.64156)
		(end 343.027 -22.64156)
		(width 0.254)
		(layer "F.Cu")
		(net "VR_COMP_RC_PVPP_ABC")
	)
	(segment
		(start 336.042 -21.63318)
		(end 335.788 -21.88718)
		(width 0.254)
		(layer "F.Cu")
		(net "VR_COMP_PVPP_ABC")
	)
	(segment
		(start 335.788 -21.88718)
		(end 335.788 -22.352)
		(width 0.254)
		(layer "F.Cu")
		(net "VR_COMP_PVPP_ABC")
	)
	(segment
		(start 335.788 -22.352)
		(end 336.677 -22.352)
		(width 0.254)
		(layer "F.Cu")
		(net "VR_COMP_PVPP_ABC")
	)
	(segment
		(start 336.042 -21.082)
		(end 336.042 -21.63318)
		(width 0.254)
		(layer "F.Cu")
		(net "VR_COMP_PVPP_ABC")
	)
	(via
		(at 336.042 -21.082)
		(size 0.508)
		(drill 0.254)
		(layers "F.Cu" "B.Cu")
		(net "VR_COMP_PVPP_ABC")
	)
	(segment
		(start 410.205936 -119.8499)
		(end 410.7815 -119.8499)
		(width 0.1143)
		(layer "F.Cu")
		(net "USB2_P02_DP")
	)
	(segment
		(start 408.106372 -120.263412)
		(end 408.348942 -120.020842)
		(width 0.1143)
		(layer "F.Cu")
		(net "USB2_P02_DP")
	)
	(segment
		(start 357.777542 -8.680196)
		(end 357.777542 -10.827258)
		(width 0.1143)
		(layer "F.Cu")
		(net "USB2_P02_DP")
	)
	(segment
		(start 407.745946 -120.6119)
		(end 407.919428 -120.6119)
		(width 0.1143)
		(layer "F.Cu")
		(net "USB2_P02_DP")
	)
	(segment
		(start 410.091636 -119.7356)
		(end 410.205936 -119.8499)
		(width 0.1143)
		(layer "F.Cu")
		(net "USB2_P02_DP")
	)
	(segment
		(start 357.485188 -8.387842)
		(end 357.777542 -8.680196)
		(width 0.1143)
		(layer "F.Cu")
		(net "USB2_P02_DP")
	)
	(segment
		(start 408.510486 -120.020842)
		(end 408.681428 -119.8499)
		(width 0.1143)
		(layer "F.Cu")
		(net "USB2_P02_DP")
	)
	(segment
		(start 357.485188 -7.789926)
		(end 357.485188 -8.387842)
		(width 0.1143)
		(layer "F.Cu")
		(net "USB2_P02_DP")
	)
	(segment
		(start 408.348942 -120.020842)
		(end 408.510486 -120.020842)
		(width 0.1143)
		(layer "F.Cu")
		(net "USB2_P02_DP")
	)
	(segment
		(start 407.919428 -120.6119)
		(end 408.106372 -120.424956)
		(width 0.1143)
		(layer "F.Cu")
		(net "USB2_P02_DP")
	)
	(segment
		(start 357.653336 -10.951464)
		(end 357.262684 -10.951464)
		(width 0.1143)
		(layer "F.Cu")
		(net "USB2_P02_DP")
	)
	(segment
		(start 410.7815 -119.8499)
		(end 410.8958 -119.7356)
		(width 0.1143)
		(layer "F.Cu")
		(net "USB2_P02_DP")
	)
	(segment
		(start 409.634436 -119.8499)
		(end 409.748736 -119.7356)
		(width 0.1143)
		(layer "F.Cu")
		(net "USB2_P02_DP")
	)
	(segment
		(start 410.781246 -119.36603)
		(end 410.618178 -119.36603)
		(width 0.1143)
		(layer "F.Cu")
		(net "USB2_P02_DP")
	)
	(segment
		(start 409.748736 -119.7356)
		(end 410.091636 -119.7356)
		(width 0.1143)
		(layer "F.Cu")
		(net "USB2_P02_DP")
	)
	(segment
		(start 408.681428 -119.8499)
		(end 409.634436 -119.8499)
		(width 0.1143)
		(layer "F.Cu")
		(net "USB2_P02_DP")
	)
	(segment
		(start 410.8958 -119.7356)
		(end 410.8958 -119.480584)
		(width 0.1143)
		(layer "F.Cu")
		(net "USB2_P02_DP")
	)
	(segment
		(start 408.106372 -120.424956)
		(end 408.106372 -120.263412)
		(width 0.1143)
		(layer "F.Cu")
		(net "USB2_P02_DP")
	)
	(segment
		(start 357.777542 -10.827258)
		(end 357.653336 -10.951464)
		(width 0.1143)
		(layer "F.Cu")
		(net "USB2_P02_DP")
	)
	(segment
		(start 410.8958 -119.480584)
		(end 410.781246 -119.36603)
		(width 0.1143)
		(layer "F.Cu")
		(net "USB2_P02_DP")
	)
	(segment
		(start 407.405078 -120.271032)
		(end 407.745946 -120.6119)
		(width 0.1143)
		(layer "F.Cu")
		(net "USB2_P02_DP")
	)
	(via
		(at 357.262684 -10.951464)
		(size 0.508)
		(drill 0.254)
		(layers "F.Cu" "B.Cu")
		(net "USB2_P02_DP")
	)
	(via
		(at 395.7574 -33.915604)
		(size 0.508)
		(drill 0.254)
		(layers "F.Cu" "B.Cu")
		(net "USB2_P02_DP")
	)
	(via
		(at 373.301006 -12.446)
		(size 0.508)
		(drill 0.254)
		(layers "F.Cu" "B.Cu")
		(net "USB2_P02_DP")
	)
	(via
		(at 410.618178 -119.36603)
		(size 0.508)
		(drill 0.254)
		(layers "F.Cu" "B.Cu")
		(net "USB2_P02_DP")
	)
	(segment
		(start 357.662734 -10.951464)
		(end 357.262684 -10.951464)
		(width 0.1143)
		(layer "B.Cu")
		(net "USB2_P02_DP")
	)
	(segment
		(start 366.0648 -12.446)
		(end 363.3978 -9.779)
		(width 0.1143)
		(layer "B.Cu")
		(net "USB2_P02_DP")
	)
	(segment
		(start 395.7574 -34.0106)
		(end 395.4145 -34.3535)
		(width 0.1143)
		(layer "B.Cu")
		(net "USB2_P02_DP")
	)
	(segment
		(start 357.777034 -10.837164)
		(end 357.662734 -10.951464)
		(width 0.1143)
		(layer "B.Cu")
		(net "USB2_P02_DP")
	)
	(segment
		(start 395.4145 -34.3535)
		(end 393.9159 -34.3535)
		(width 0.1143)
		(layer "B.Cu")
		(net "USB2_P02_DP")
	)
	(segment
		(start 374.9802 -12.446)
		(end 373.301006 -12.446)
		(width 0.1143)
		(layer "B.Cu")
		(net "USB2_P02_DP")
	)
	(segment
		(start 383.273554 -31.305754)
		(end 382.2192 -30.2514)
		(width 0.1143)
		(layer "B.Cu")
		(net "USB2_P02_DP")
	)
	(segment
		(start 393.9159 -34.3535)
		(end 392.448034 -32.885634)
		(width 0.1143)
		(layer "B.Cu")
		(net "USB2_P02_DP")
	)
	(segment
		(start 357.777034 -8.211566)
		(end 357.777034 -10.837164)
		(width 0.1143)
		(layer "B.Cu")
		(net "USB2_P02_DP")
	)
	(segment
		(start 359.0925 -6.8961)
		(end 357.777034 -8.211566)
		(width 0.1143)
		(layer "B.Cu")
		(net "USB2_P02_DP")
	)
	(segment
		(start 373.301006 -12.446)
		(end 366.0648 -12.446)
		(width 0.1143)
		(layer "B.Cu")
		(net "USB2_P02_DP")
	)
	(segment
		(start 382.2192 -30.2514)
		(end 382.2192 -19.685)
		(width 0.1143)
		(layer "B.Cu")
		(net "USB2_P02_DP")
	)
	(segment
		(start 382.2192 -19.685)
		(end 374.9802 -12.446)
		(width 0.1143)
		(layer "B.Cu")
		(net "USB2_P02_DP")
	)
	(segment
		(start 386.842 -32.004)
		(end 386.143754 -31.305754)
		(width 0.1143)
		(layer "B.Cu")
		(net "USB2_P02_DP")
	)
	(segment
		(start 363.3978 -8.3058)
		(end 361.9881 -6.8961)
		(width 0.1143)
		(layer "B.Cu")
		(net "USB2_P02_DP")
	)
	(segment
		(start 391.482834 -32.885634)
		(end 390.6012 -32.004)
		(width 0.1143)
		(layer "B.Cu")
		(net "USB2_P02_DP")
	)
	(segment
		(start 395.7574 -33.915604)
		(end 395.7574 -34.0106)
		(width 0.1143)
		(layer "B.Cu")
		(net "USB2_P02_DP")
	)
	(segment
		(start 392.448034 -32.885634)
		(end 391.482834 -32.885634)
		(width 0.1143)
		(layer "B.Cu")
		(net "USB2_P02_DP")
	)
	(segment
		(start 390.6012 -32.004)
		(end 386.842 -32.004)
		(width 0.1143)
		(layer "B.Cu")
		(net "USB2_P02_DP")
	)
	(segment
		(start 363.3978 -9.779)
		(end 363.3978 -8.3058)
		(width 0.1143)
		(layer "B.Cu")
		(net "USB2_P02_DP")
	)
	(segment
		(start 361.9881 -6.8961)
		(end 359.0925 -6.8961)
		(width 0.1143)
		(layer "B.Cu")
		(net "USB2_P02_DP")
	)
	(segment
		(start 386.143754 -31.305754)
		(end 383.273554 -31.305754)
		(width 0.1143)
		(layer "B.Cu")
		(net "USB2_P02_DP")
	)
	(segment
		(start 406.552908 -53.420518)
		(end 405.38146 -52.24907)
		(width 0.1143)
		(layer "In11.Cu")
		(net "USB2_P02_DP")
	)
	(segment
		(start 415.1122 -62.668658)
		(end 415.1122 -59.71921)
		(width 0.1143)
		(layer "In11.Cu")
		(net "USB2_P02_DP")
	)
	(segment
		(start 415.1122 -59.71921)
		(end 413.81299 -58.42)
		(width 0.1143)
		(layer "In11.Cu")
		(net "USB2_P02_DP")
	)
	(segment
		(start 393.616434 -35.820604)
		(end 393.616434 -35.082988)
		(width 0.1143)
		(layer "In11.Cu")
		(net "USB2_P02_DP")
	)
	(segment
		(start 394.742924 -36.967414)
		(end 394.686282 -36.910772)
		(width 0.1143)
		(layer "In11.Cu")
		(net "USB2_P02_DP")
	)
	(segment
		(start 415.6456 -89.82837)
		(end 415.548064 -89.730834)
		(width 0.1143)
		(layer "In11.Cu")
		(net "USB2_P02_DP")
	)
	(segment
		(start 405.3586 -52.247546)
		(end 403.019768 -52.247546)
		(width 0.1143)
		(layer "In11.Cu")
		(net "USB2_P02_DP")
	)
	(segment
		(start 393.616434 -35.082988)
		(end 394.189712 -34.50971)
		(width 0.1143)
		(layer "In11.Cu")
		(net "USB2_P02_DP")
	)
	(segment
		(start 415.548064 -88.478614)
		(end 416.124898 -87.90178)
		(width 0.1143)
		(layer "In11.Cu")
		(net "USB2_P02_DP")
	)
	(segment
		(start 416.124898 -87.90178)
		(end 416.124898 -83.931252)
		(width 0.1143)
		(layer "In11.Cu")
		(net "USB2_P02_DP")
	)
	(segment
		(start 413.81299 -58.42)
		(end 411.606746 -58.42)
		(width 0.1143)
		(layer "In11.Cu")
		(net "USB2_P02_DP")
	)
	(segment
		(start 416.124898 -83.931252)
		(end 416.537394 -83.518756)
		(width 0.1143)
		(layer "In11.Cu")
		(net "USB2_P02_DP")
	)
	(segment
		(start 413.131 -115.410488)
		(end 413.131 -110.744)
		(width 0.1143)
		(layer "In11.Cu")
		(net "USB2_P02_DP")
	)
	(segment
		(start 395.097508 -34.328354)
		(end 395.6431 -34.328354)
		(width 0.1143)
		(layer "In11.Cu")
		(net "USB2_P02_DP")
	)
	(segment
		(start 410.831792 -117.23497)
		(end 411.518862 -116.5479)
		(width 0.1143)
		(layer "In11.Cu")
		(net "USB2_P02_DP")
	)
	(segment
		(start 395.6431 -34.328354)
		(end 395.7574 -34.214054)
		(width 0.1143)
		(layer "In11.Cu")
		(net "USB2_P02_DP")
	)
	(segment
		(start 405.360124 -52.24907)
		(end 405.3586 -52.247546)
		(width 0.1143)
		(layer "In11.Cu")
		(net "USB2_P02_DP")
	)
	(segment
		(start 415.548064 -89.730834)
		(end 415.548064 -88.478614)
		(width 0.1143)
		(layer "In11.Cu")
		(net "USB2_P02_DP")
	)
	(segment
		(start 395.156944 -40.070786)
		(end 395.426946 -39.800784)
		(width 0.1143)
		(layer "In11.Cu")
		(net "USB2_P02_DP")
	)
	(segment
		(start 395.156944 -41.009824)
		(end 395.156944 -40.070786)
		(width 0.1143)
		(layer "In11.Cu")
		(net "USB2_P02_DP")
	)
	(segment
		(start 410.831792 -119.152416)
		(end 410.831792 -117.23497)
		(width 0.1143)
		(layer "In11.Cu")
		(net "USB2_P02_DP")
	)
	(segment
		(start 394.189712 -34.50971)
		(end 394.916152 -34.50971)
		(width 0.1143)
		(layer "In11.Cu")
		(net "USB2_P02_DP")
	)
	(segment
		(start 411.606746 -58.42)
		(end 408.4701 -55.283354)
		(width 0.1143)
		(layer "In11.Cu")
		(net "USB2_P02_DP")
	)
	(segment
		(start 416.3822 -70.872858)
		(end 416.3822 -63.938658)
		(width 0.1143)
		(layer "In11.Cu")
		(net "USB2_P02_DP")
	)
	(segment
		(start 416.537394 -81.003648)
		(end 417.054538 -80.486504)
		(width 0.1143)
		(layer "In11.Cu")
		(net "USB2_P02_DP")
	)
	(segment
		(start 417.054538 -80.486504)
		(end 417.054538 -71.545196)
		(width 0.1143)
		(layer "In11.Cu")
		(net "USB2_P02_DP")
	)
	(segment
		(start 394.686282 -36.890452)
		(end 393.616434 -35.820604)
		(width 0.1143)
		(layer "In11.Cu")
		(net "USB2_P02_DP")
	)
	(segment
		(start 411.993588 -116.5479)
		(end 413.131 -115.410488)
		(width 0.1143)
		(layer "In11.Cu")
		(net "USB2_P02_DP")
	)
	(segment
		(start 414.61055 -108.825792)
		(end 415.6456 -107.790742)
		(width 0.1143)
		(layer "In11.Cu")
		(net "USB2_P02_DP")
	)
	(segment
		(start 394.742924 -37.492686)
		(end 394.742924 -36.967414)
		(width 0.1143)
		(layer "In11.Cu")
		(net "USB2_P02_DP")
	)
	(segment
		(start 394.686282 -36.910772)
		(end 394.686282 -36.890452)
		(width 0.1143)
		(layer "In11.Cu")
		(net "USB2_P02_DP")
	)
	(segment
		(start 411.518862 -116.5479)
		(end 411.993588 -116.5479)
		(width 0.1143)
		(layer "In11.Cu")
		(net "USB2_P02_DP")
	)
	(segment
		(start 415.6456 -107.790742)
		(end 415.6456 -89.82837)
		(width 0.1143)
		(layer "In11.Cu")
		(net "USB2_P02_DP")
	)
	(segment
		(start 395.426946 -39.800784)
		(end 395.426946 -38.176708)
		(width 0.1143)
		(layer "In11.Cu")
		(net "USB2_P02_DP")
	)
	(segment
		(start 416.3822 -63.938658)
		(end 415.1122 -62.668658)
		(width 0.1143)
		(layer "In11.Cu")
		(net "USB2_P02_DP")
	)
	(segment
		(start 408.4701 -54.280054)
		(end 407.610564 -53.420518)
		(width 0.1143)
		(layer "In11.Cu")
		(net "USB2_P02_DP")
	)
	(segment
		(start 417.054538 -71.545196)
		(end 416.3822 -70.872858)
		(width 0.1143)
		(layer "In11.Cu")
		(net "USB2_P02_DP")
	)
	(segment
		(start 408.4701 -55.283354)
		(end 408.4701 -54.280054)
		(width 0.1143)
		(layer "In11.Cu")
		(net "USB2_P02_DP")
	)
	(segment
		(start 400.2278 -49.455578)
		(end 400.2278 -46.08068)
		(width 0.1143)
		(layer "In11.Cu")
		(net "USB2_P02_DP")
	)
	(segment
		(start 405.38146 -52.24907)
		(end 405.360124 -52.24907)
		(width 0.1143)
		(layer "In11.Cu")
		(net "USB2_P02_DP")
	)
	(segment
		(start 395.426946 -38.176708)
		(end 394.742924 -37.492686)
		(width 0.1143)
		(layer "In11.Cu")
		(net "USB2_P02_DP")
	)
	(segment
		(start 400.2278 -46.08068)
		(end 395.156944 -41.009824)
		(width 0.1143)
		(layer "In11.Cu")
		(net "USB2_P02_DP")
	)
	(segment
		(start 413.131 -110.744)
		(end 414.61055 -109.26445)
		(width 0.1143)
		(layer "In11.Cu")
		(net "USB2_P02_DP")
	)
	(segment
		(start 416.537394 -83.518756)
		(end 416.537394 -81.003648)
		(width 0.1143)
		(layer "In11.Cu")
		(net "USB2_P02_DP")
	)
	(segment
		(start 407.610564 -53.420518)
		(end 406.552908 -53.420518)
		(width 0.1143)
		(layer "In11.Cu")
		(net "USB2_P02_DP")
	)
	(segment
		(start 395.7574 -34.214054)
		(end 395.7574 -33.915604)
		(width 0.1143)
		(layer "In11.Cu")
		(net "USB2_P02_DP")
	)
	(segment
		(start 403.019768 -52.247546)
		(end 400.2278 -49.455578)
		(width 0.1143)
		(layer "In11.Cu")
		(net "USB2_P02_DP")
	)
	(segment
		(start 410.618178 -119.36603)
		(end 410.831792 -119.152416)
		(width 0.1143)
		(layer "In11.Cu")
		(net "USB2_P02_DP")
	)
	(segment
		(start 414.61055 -109.26445)
		(end 414.61055 -108.825792)
		(width 0.1143)
		(layer "In11.Cu")
		(net "USB2_P02_DP")
	)
	(segment
		(start 394.916152 -34.50971)
		(end 395.097508 -34.328354)
		(width 0.1143)
		(layer "In11.Cu")
		(net "USB2_P02_DP")
	)
	(segment
		(start 411.1371 -119.609108)
		(end 411.380178 -119.36603)
		(width 0.1143)
		(layer "F.Cu")
		(net "USB2_P02_DN")
	)
	(segment
		(start 408.781504 -120.0912)
		(end 410.881576 -120.0912)
		(width 0.1143)
		(layer "F.Cu")
		(net "USB2_P02_DN")
	)
	(segment
		(start 407.405078 -121.083832)
		(end 407.63571 -120.8532)
		(width 0.1143)
		(layer "F.Cu")
		(net "USB2_P02_DN")
	)
	(segment
		(start 410.881576 -120.0912)
		(end 411.1371 -119.835676)
		(width 0.1143)
		(layer "F.Cu")
		(net "USB2_P02_DN")
	)
	(segment
		(start 411.1371 -119.835676)
		(end 411.1371 -119.609108)
		(width 0.1143)
		(layer "F.Cu")
		(net "USB2_P02_DN")
	)
	(segment
		(start 358.285034 -8.41502)
		(end 358.018842 -8.681212)
		(width 0.1143)
		(layer "F.Cu")
		(net "USB2_P02_DN")
	)
	(segment
		(start 407.63571 -120.8532)
		(end 408.019504 -120.8532)
		(width 0.1143)
		(layer "F.Cu")
		(net "USB2_P02_DN")
	)
	(segment
		(start 358.018842 -10.817606)
		(end 358.1527 -10.951464)
		(width 0.1143)
		(layer "F.Cu")
		(net "USB2_P02_DN")
	)
	(segment
		(start 408.019504 -120.8532)
		(end 408.781504 -120.0912)
		(width 0.1143)
		(layer "F.Cu")
		(net "USB2_P02_DN")
	)
	(segment
		(start 358.1527 -10.951464)
		(end 358.532684 -10.951464)
		(width 0.1143)
		(layer "F.Cu")
		(net "USB2_P02_DN")
	)
	(segment
		(start 358.018842 -8.681212)
		(end 358.018842 -10.817606)
		(width 0.1143)
		(layer "F.Cu")
		(net "USB2_P02_DN")
	)
	(segment
		(start 358.285034 -7.789926)
		(end 358.285034 -8.41502)
		(width 0.1143)
		(layer "F.Cu")
		(net "USB2_P02_DN")
	)
	(via
		(at 368.282982 -12.6873)
		(size 0.508)
		(drill 0.254)
		(layers "F.Cu" "B.Cu")
		(net "USB2_P02_DN")
	)
	(via
		(at 395.7574 -35.05835)
		(size 0.508)
		(drill 0.254)
		(layers "F.Cu" "B.Cu")
		(net "USB2_P02_DN")
	)
	(via
		(at 411.380178 -119.36603)
		(size 0.508)
		(drill 0.254)
		(layers "F.Cu" "B.Cu")
		(net "USB2_P02_DN")
	)
	(via
		(at 358.532684 -10.951464)
		(size 0.508)
		(drill 0.254)
		(layers "F.Cu" "B.Cu")
		(net "USB2_P02_DN")
	)
	(segment
		(start 392.726418 -33.505394)
		(end 392.347958 -33.126934)
		(width 0.1143)
		(layer "B.Cu")
		(net "USB2_P02_DN")
	)
	(segment
		(start 374.880124 -12.6873)
		(end 368.282982 -12.6873)
		(width 0.1143)
		(layer "B.Cu")
		(net "USB2_P02_DN")
	)
	(segment
		(start 381.9779 -19.785076)
		(end 374.880124 -12.6873)
		(width 0.1143)
		(layer "B.Cu")
		(net "USB2_P02_DN")
	)
	(segment
		(start 386.043678 -31.547054)
		(end 383.173478 -31.547054)
		(width 0.1143)
		(layer "B.Cu")
		(net "USB2_P02_DN")
	)
	(segment
		(start 361.888024 -7.1374)
		(end 359.192576 -7.1374)
		(width 0.1143)
		(layer "B.Cu")
		(net "USB2_P02_DN")
	)
	(segment
		(start 383.173478 -31.547054)
		(end 381.9779 -30.351476)
		(width 0.1143)
		(layer "B.Cu")
		(net "USB2_P02_DN")
	)
	(segment
		(start 368.282982 -12.6873)
		(end 365.964724 -12.6873)
		(width 0.1143)
		(layer "B.Cu")
		(net "USB2_P02_DN")
	)
	(segment
		(start 388.987538 -32.2453)
		(end 388.644638 -32.2453)
		(width 0.1143)
		(layer "B.Cu")
		(net "USB2_P02_DN")
	)
	(segment
		(start 395.29385 -34.5948)
		(end 393.815824 -34.5948)
		(width 0.1143)
		(layer "B.Cu")
		(net "USB2_P02_DN")
	)
	(segment
		(start 389.559038 -32.2453)
		(end 389.444738 -32.3596)
		(width 0.1143)
		(layer "B.Cu")
		(net "USB2_P02_DN")
	)
	(segment
		(start 390.501124 -32.2453)
		(end 389.559038 -32.2453)
		(width 0.1143)
		(layer "B.Cu")
		(net "USB2_P02_DN")
	)
	(segment
		(start 363.1565 -8.405876)
		(end 361.888024 -7.1374)
		(width 0.1143)
		(layer "B.Cu")
		(net "USB2_P02_DN")
	)
	(segment
		(start 365.964724 -12.6873)
		(end 363.1565 -9.879076)
		(width 0.1143)
		(layer "B.Cu")
		(net "USB2_P02_DN")
	)
	(segment
		(start 381.8636 -24.665686)
		(end 381.8636 -24.322786)
		(width 0.1143)
		(layer "B.Cu")
		(net "USB2_P02_DN")
	)
	(segment
		(start 391.382758 -33.126934)
		(end 390.501124 -32.2453)
		(width 0.1143)
		(layer "B.Cu")
		(net "USB2_P02_DN")
	)
	(segment
		(start 386.741924 -32.2453)
		(end 386.043678 -31.547054)
		(width 0.1143)
		(layer "B.Cu")
		(net "USB2_P02_DN")
	)
	(segment
		(start 381.9779 -23.294086)
		(end 381.9779 -19.785076)
		(width 0.1143)
		(layer "B.Cu")
		(net "USB2_P02_DN")
	)
	(segment
		(start 381.8636 -23.408386)
		(end 381.9779 -23.294086)
		(width 0.1143)
		(layer "B.Cu")
		(net "USB2_P02_DN")
	)
	(segment
		(start 381.9779 -24.208486)
		(end 381.9779 -23.865586)
		(width 0.1143)
		(layer "B.Cu")
		(net "USB2_P02_DN")
	)
	(segment
		(start 381.8636 -23.751286)
		(end 381.8636 -23.408386)
		(width 0.1143)
		(layer "B.Cu")
		(net "USB2_P02_DN")
	)
	(segment
		(start 359.192576 -7.1374)
		(end 358.018334 -8.311642)
		(width 0.1143)
		(layer "B.Cu")
		(net "USB2_P02_DN")
	)
	(segment
		(start 358.018334 -8.311642)
		(end 358.018334 -10.837164)
		(width 0.1143)
		(layer "B.Cu")
		(net "USB2_P02_DN")
	)
	(segment
		(start 358.132634 -10.951464)
		(end 358.532684 -10.951464)
		(width 0.1143)
		(layer "B.Cu")
		(net "USB2_P02_DN")
	)
	(segment
		(start 388.187438 -32.3596)
		(end 388.073138 -32.2453)
		(width 0.1143)
		(layer "B.Cu")
		(net "USB2_P02_DN")
	)
	(segment
		(start 381.9779 -24.779986)
		(end 381.8636 -24.665686)
		(width 0.1143)
		(layer "B.Cu")
		(net "USB2_P02_DN")
	)
	(segment
		(start 388.530338 -32.3596)
		(end 388.187438 -32.3596)
		(width 0.1143)
		(layer "B.Cu")
		(net "USB2_P02_DN")
	)
	(segment
		(start 395.7574 -35.05835)
		(end 395.29385 -34.5948)
		(width 0.1143)
		(layer "B.Cu")
		(net "USB2_P02_DN")
	)
	(segment
		(start 393.130532 -33.909508)
		(end 392.968988 -33.909508)
		(width 0.1143)
		(layer "B.Cu")
		(net "USB2_P02_DN")
	)
	(segment
		(start 392.968988 -33.909508)
		(end 392.726418 -33.666938)
		(width 0.1143)
		(layer "B.Cu")
		(net "USB2_P02_DN")
	)
	(segment
		(start 392.726418 -33.666938)
		(end 392.726418 -33.505394)
		(width 0.1143)
		(layer "B.Cu")
		(net "USB2_P02_DN")
	)
	(segment
		(start 393.815824 -34.5948)
		(end 393.130532 -33.909508)
		(width 0.1143)
		(layer "B.Cu")
		(net "USB2_P02_DN")
	)
	(segment
		(start 381.9779 -30.351476)
		(end 381.9779 -24.779986)
		(width 0.1143)
		(layer "B.Cu")
		(net "USB2_P02_DN")
	)
	(segment
		(start 381.8636 -24.322786)
		(end 381.9779 -24.208486)
		(width 0.1143)
		(layer "B.Cu")
		(net "USB2_P02_DN")
	)
	(segment
		(start 388.073138 -32.2453)
		(end 386.741924 -32.2453)
		(width 0.1143)
		(layer "B.Cu")
		(net "USB2_P02_DN")
	)
	(segment
		(start 388.644638 -32.2453)
		(end 388.530338 -32.3596)
		(width 0.1143)
		(layer "B.Cu")
		(net "USB2_P02_DN")
	)
	(segment
		(start 358.018334 -10.837164)
		(end 358.132634 -10.951464)
		(width 0.1143)
		(layer "B.Cu")
		(net "USB2_P02_DN")
	)
	(segment
		(start 389.444738 -32.3596)
		(end 389.101838 -32.3596)
		(width 0.1143)
		(layer "B.Cu")
		(net "USB2_P02_DN")
	)
	(segment
		(start 392.347958 -33.126934)
		(end 391.382758 -33.126934)
		(width 0.1143)
		(layer "B.Cu")
		(net "USB2_P02_DN")
	)
	(segment
		(start 389.101838 -32.3596)
		(end 388.987538 -32.2453)
		(width 0.1143)
		(layer "B.Cu")
		(net "USB2_P02_DN")
	)
	(segment
		(start 363.1565 -9.879076)
		(end 363.1565 -8.405876)
		(width 0.1143)
		(layer "B.Cu")
		(net "USB2_P02_DN")
	)
	(segment
		(start 381.9779 -23.865586)
		(end 381.8636 -23.751286)
		(width 0.1143)
		(layer "B.Cu")
		(net "USB2_P02_DN")
	)
	(segment
		(start 408.7622 -55.162196)
		(end 408.7622 -54.158896)
		(width 0.1143)
		(layer "In11.Cu")
		(net "USB2_P02_DN")
	)
	(segment
		(start 415.840164 -88.599772)
		(end 416.416998 -88.022938)
		(width 0.1143)
		(layer "In11.Cu")
		(net "USB2_P02_DN")
	)
	(segment
		(start 395.719046 -38.05555)
		(end 395.035024 -37.371528)
		(width 0.1143)
		(layer "In11.Cu")
		(net "USB2_P02_DN")
	)
	(segment
		(start 416.1028 -103.676958)
		(end 415.9377 -103.511858)
		(width 0.1143)
		(layer "In11.Cu")
		(net "USB2_P02_DN")
	)
	(segment
		(start 411.123892 -119.109744)
		(end 411.123892 -117.356128)
		(width 0.1143)
		(layer "In11.Cu")
		(net "USB2_P02_DN")
	)
	(segment
		(start 417.346638 -80.607662)
		(end 417.346638 -71.424038)
		(width 0.1143)
		(layer "In11.Cu")
		(net "USB2_P02_DN")
	)
	(segment
		(start 395.449044 -40.191944)
		(end 395.719046 -39.921942)
		(width 0.1143)
		(layer "In11.Cu")
		(net "USB2_P02_DN")
	)
	(segment
		(start 407.731722 -53.128418)
		(end 406.674066 -53.128418)
		(width 0.1143)
		(layer "In11.Cu")
		(net "USB2_P02_DN")
	)
	(segment
		(start 416.416998 -84.05241)
		(end 416.829494 -83.639914)
		(width 0.1143)
		(layer "In11.Cu")
		(net "USB2_P02_DN")
	)
	(segment
		(start 413.4231 -110.865158)
		(end 414.90265 -109.385608)
		(width 0.1143)
		(layer "In11.Cu")
		(net "USB2_P02_DN")
	)
	(segment
		(start 394.978382 -36.789614)
		(end 394.978382 -36.769294)
		(width 0.1143)
		(layer "In11.Cu")
		(net "USB2_P02_DN")
	)
	(segment
		(start 415.840164 -89.609676)
		(end 415.840164 -88.599772)
		(width 0.1143)
		(layer "In11.Cu")
		(net "USB2_P02_DN")
	)
	(segment
		(start 405.481282 -51.95697)
		(end 405.479758 -51.955446)
		(width 0.1143)
		(layer "In11.Cu")
		(net "USB2_P02_DN")
	)
	(segment
		(start 416.6743 -70.7517)
		(end 416.6743 -63.8175)
		(width 0.1143)
		(layer "In11.Cu")
		(net "USB2_P02_DN")
	)
	(segment
		(start 415.9377 -107.9119)
		(end 415.9377 -106.216958)
		(width 0.1143)
		(layer "In11.Cu")
		(net "USB2_P02_DN")
	)
	(segment
		(start 415.9377 -89.707212)
		(end 415.840164 -89.609676)
		(width 0.1143)
		(layer "In11.Cu")
		(net "USB2_P02_DN")
	)
	(segment
		(start 415.9377 -104.527858)
		(end 415.9377 -104.184958)
		(width 0.1143)
		(layer "In11.Cu")
		(net "USB2_P02_DN")
	)
	(segment
		(start 411.64002 -116.84)
		(end 412.114746 -116.84)
		(width 0.1143)
		(layer "In11.Cu")
		(net "USB2_P02_DN")
	)
	(segment
		(start 395.7574 -34.76371)
		(end 395.7574 -35.05835)
		(width 0.1143)
		(layer "In11.Cu")
		(net "USB2_P02_DN")
	)
	(segment
		(start 395.449044 -40.888666)
		(end 395.449044 -40.191944)
		(width 0.1143)
		(layer "In11.Cu")
		(net "USB2_P02_DN")
	)
	(segment
		(start 417.346638 -71.424038)
		(end 416.6743 -70.7517)
		(width 0.1143)
		(layer "In11.Cu")
		(net "USB2_P02_DN")
	)
	(segment
		(start 416.1028 -105.035858)
		(end 416.1028 -104.692958)
		(width 0.1143)
		(layer "In11.Cu")
		(net "USB2_P02_DN")
	)
	(segment
		(start 416.416998 -88.022938)
		(end 416.416998 -84.05241)
		(width 0.1143)
		(layer "In11.Cu")
		(net "USB2_P02_DN")
	)
	(segment
		(start 415.4043 -59.598052)
		(end 413.934148 -58.1279)
		(width 0.1143)
		(layer "In11.Cu")
		(net "USB2_P02_DN")
	)
	(segment
		(start 405.479758 -51.955446)
		(end 403.140926 -51.955446)
		(width 0.1143)
		(layer "In11.Cu")
		(net "USB2_P02_DN")
	)
	(segment
		(start 395.218666 -34.620454)
		(end 395.614144 -34.620454)
		(width 0.1143)
		(layer "In11.Cu")
		(net "USB2_P02_DN")
	)
	(segment
		(start 406.674066 -53.128418)
		(end 405.502618 -51.95697)
		(width 0.1143)
		(layer "In11.Cu")
		(net "USB2_P02_DN")
	)
	(segment
		(start 415.9377 -104.184958)
		(end 416.1028 -104.019858)
		(width 0.1143)
		(layer "In11.Cu")
		(net "USB2_P02_DN")
	)
	(segment
		(start 408.7622 -54.158896)
		(end 407.731722 -53.128418)
		(width 0.1143)
		(layer "In11.Cu")
		(net "USB2_P02_DN")
	)
	(segment
		(start 393.908534 -35.204146)
		(end 394.31087 -34.80181)
		(width 0.1143)
		(layer "In11.Cu")
		(net "USB2_P02_DN")
	)
	(segment
		(start 411.123892 -117.356128)
		(end 411.64002 -116.84)
		(width 0.1143)
		(layer "In11.Cu")
		(net "USB2_P02_DN")
	)
	(segment
		(start 400.5199 -49.33442)
		(end 400.5199 -45.959522)
		(width 0.1143)
		(layer "In11.Cu")
		(net "USB2_P02_DN")
	)
	(segment
		(start 416.6743 -63.8175)
		(end 415.4043 -62.5475)
		(width 0.1143)
		(layer "In11.Cu")
		(net "USB2_P02_DN")
	)
	(segment
		(start 395.03731 -34.80181)
		(end 395.218666 -34.620454)
		(width 0.1143)
		(layer "In11.Cu")
		(net "USB2_P02_DN")
	)
	(segment
		(start 395.035024 -37.371528)
		(end 395.035024 -36.846256)
		(width 0.1143)
		(layer "In11.Cu")
		(net "USB2_P02_DN")
	)
	(segment
		(start 416.1028 -105.708958)
		(end 415.9377 -105.543858)
		(width 0.1143)
		(layer "In11.Cu")
		(net "USB2_P02_DN")
	)
	(segment
		(start 415.9377 -103.511858)
		(end 415.9377 -89.707212)
		(width 0.1143)
		(layer "In11.Cu")
		(net "USB2_P02_DN")
	)
	(segment
		(start 416.1028 -104.019858)
		(end 416.1028 -103.676958)
		(width 0.1143)
		(layer "In11.Cu")
		(net "USB2_P02_DN")
	)
	(segment
		(start 413.4231 -115.531646)
		(end 413.4231 -110.865158)
		(width 0.1143)
		(layer "In11.Cu")
		(net "USB2_P02_DN")
	)
	(segment
		(start 414.90265 -108.94695)
		(end 415.9377 -107.9119)
		(width 0.1143)
		(layer "In11.Cu")
		(net "USB2_P02_DN")
	)
	(segment
		(start 400.5199 -45.959522)
		(end 395.449044 -40.888666)
		(width 0.1143)
		(layer "In11.Cu")
		(net "USB2_P02_DN")
	)
	(segment
		(start 414.90265 -109.385608)
		(end 414.90265 -108.94695)
		(width 0.1143)
		(layer "In11.Cu")
		(net "USB2_P02_DN")
	)
	(segment
		(start 395.719046 -39.921942)
		(end 395.719046 -38.05555)
		(width 0.1143)
		(layer "In11.Cu")
		(net "USB2_P02_DN")
	)
	(segment
		(start 393.908534 -35.699446)
		(end 393.908534 -35.204146)
		(width 0.1143)
		(layer "In11.Cu")
		(net "USB2_P02_DN")
	)
	(segment
		(start 416.829494 -83.639914)
		(end 416.829494 -81.124806)
		(width 0.1143)
		(layer "In11.Cu")
		(net "USB2_P02_DN")
	)
	(segment
		(start 411.380178 -119.36603)
		(end 411.123892 -119.109744)
		(width 0.1143)
		(layer "In11.Cu")
		(net "USB2_P02_DN")
	)
	(segment
		(start 411.727904 -58.1279)
		(end 408.7622 -55.162196)
		(width 0.1143)
		(layer "In11.Cu")
		(net "USB2_P02_DN")
	)
	(segment
		(start 395.614144 -34.620454)
		(end 395.7574 -34.76371)
		(width 0.1143)
		(layer "In11.Cu")
		(net "USB2_P02_DN")
	)
	(segment
		(start 416.1028 -104.692958)
		(end 415.9377 -104.527858)
		(width 0.1143)
		(layer "In11.Cu")
		(net "USB2_P02_DN")
	)
	(segment
		(start 415.9377 -106.216958)
		(end 416.1028 -106.051858)
		(width 0.1143)
		(layer "In11.Cu")
		(net "USB2_P02_DN")
	)
	(segment
		(start 394.31087 -34.80181)
		(end 395.03731 -34.80181)
		(width 0.1143)
		(layer "In11.Cu")
		(net "USB2_P02_DN")
	)
	(segment
		(start 413.934148 -58.1279)
		(end 411.727904 -58.1279)
		(width 0.1143)
		(layer "In11.Cu")
		(net "USB2_P02_DN")
	)
	(segment
		(start 403.140926 -51.955446)
		(end 400.5199 -49.33442)
		(width 0.1143)
		(layer "In11.Cu")
		(net "USB2_P02_DN")
	)
	(segment
		(start 415.9377 -105.543858)
		(end 415.9377 -105.200958)
		(width 0.1143)
		(layer "In11.Cu")
		(net "USB2_P02_DN")
	)
	(segment
		(start 394.978382 -36.769294)
		(end 393.908534 -35.699446)
		(width 0.1143)
		(layer "In11.Cu")
		(net "USB2_P02_DN")
	)
	(segment
		(start 412.114746 -116.84)
		(end 413.4231 -115.531646)
		(width 0.1143)
		(layer "In11.Cu")
		(net "USB2_P02_DN")
	)
	(segment
		(start 395.035024 -36.846256)
		(end 394.978382 -36.789614)
		(width 0.1143)
		(layer "In11.Cu")
		(net "USB2_P02_DN")
	)
	(segment
		(start 415.4043 -62.5475)
		(end 415.4043 -59.598052)
		(width 0.1143)
		(layer "In11.Cu")
		(net "USB2_P02_DN")
	)
	(segment
		(start 415.9377 -105.200958)
		(end 416.1028 -105.035858)
		(width 0.1143)
		(layer "In11.Cu")
		(net "USB2_P02_DN")
	)
	(segment
		(start 405.502618 -51.95697)
		(end 405.481282 -51.95697)
		(width 0.1143)
		(layer "In11.Cu")
		(net "USB2_P02_DN")
	)
	(segment
		(start 416.1028 -106.051858)
		(end 416.1028 -105.708958)
		(width 0.1143)
		(layer "In11.Cu")
		(net "USB2_P02_DN")
	)
	(segment
		(start 416.829494 -81.124806)
		(end 417.346638 -80.607662)
		(width 0.1143)
		(layer "In11.Cu")
		(net "USB2_P02_DN")
	)
	(segment
		(start 382.78435 -95.888556)
		(end 382.28905 -96.11868)
		(width 0.10795)
		(layer "F.Cu")
		(net "TP_PM_SYNC_GTL")
	)
	(via
		(at 382.78435 -95.888556)
		(size 0.508)
		(drill 0.254)
		(layers "F.Cu" "B.Cu")
		(net "TP_PM_SYNC_GTL")
	)
	(segment
		(start 133.665214 -89.584784)
		(end 134.236714 -89.584784)
		(width 0.10795)
		(layer "F.Cu")
		(net "TP_CPU1_DMI_RX_DP3")
	)
	(via
		(at 134.236714 -89.584784)
		(size 0.4826)
		(drill 0.254)
		(layers "F.Cu" "B.Cu")
		(net "TP_CPU1_DMI_RX_DP3")
	)
	(segment
		(start 133.665214 -87.603584)
		(end 134.236714 -87.603584)
		(width 0.10795)
		(layer "F.Cu")
		(net "TP_CPU1_DMI_RX_DP2")
	)
	(via
		(at 134.236714 -87.603584)
		(size 0.4826)
		(drill 0.254)
		(layers "F.Cu" "B.Cu")
		(net "TP_CPU1_DMI_RX_DP2")
	)
	(segment
		(start 134.523734 -87.108538)
		(end 135.095234 -87.108538)
		(width 0.10795)
		(layer "F.Cu")
		(net "TP_CPU1_DMI_RX_DP1")
	)
	(via
		(at 135.095234 -87.108538)
		(size 0.4826)
		(drill 0.254)
		(layers "F.Cu" "B.Cu")
		(net "TP_CPU1_DMI_RX_DP1")
	)
	(segment
		(start 134.523734 -86.117938)
		(end 135.095234 -86.117938)
		(width 0.10795)
		(layer "F.Cu")
		(net "TP_CPU1_DMI_RX_DP0")
	)
	(via
		(at 135.095234 -86.117938)
		(size 0.4826)
		(drill 0.254)
		(layers "F.Cu" "B.Cu")
		(net "TP_CPU1_DMI_RX_DP0")
	)
	(segment
		(start 133.665214 -88.594184)
		(end 134.236714 -88.594184)
		(width 0.10795)
		(layer "F.Cu")
		(net "TP_CPU1_DMI_RX_DN3")
	)
	(via
		(at 134.236714 -88.594184)
		(size 0.4826)
		(drill 0.254)
		(layers "F.Cu" "B.Cu")
		(net "TP_CPU1_DMI_RX_DN3")
	)
	(segment
		(start 132.806694 -88.099138)
		(end 133.378194 -88.099138)
		(width 0.10795)
		(layer "F.Cu")
		(net "TP_CPU1_DMI_RX_DN2")
	)
	(via
		(at 133.378194 -88.099138)
		(size 0.4826)
		(drill 0.254)
		(layers "F.Cu" "B.Cu")
		(net "TP_CPU1_DMI_RX_DN2")
	)
	(segment
		(start 133.665214 -86.612984)
		(end 134.236714 -86.612984)
		(width 0.10795)
		(layer "F.Cu")
		(net "TP_CPU1_DMI_RX_DN1")
	)
	(via
		(at 134.236714 -86.612984)
		(size 0.4826)
		(drill 0.254)
		(layers "F.Cu" "B.Cu")
		(net "TP_CPU1_DMI_RX_DN1")
	)
	(segment
		(start 135.382254 -85.622384)
		(end 135.953754 -85.622384)
		(width 0.10795)
		(layer "F.Cu")
		(net "TP_CPU1_DMI_RX_DN0")
	)
	(via
		(at 135.953754 -85.622384)
		(size 0.4826)
		(drill 0.254)
		(layers "F.Cu" "B.Cu")
		(net "TP_CPU1_DMI_RX_DN0")
	)
	(segment
		(start 402.140928 -116.273326)
		(end 402.450554 -115.9637)
		(width 0.0889)
		(layer "F.Cu")
		(net "TP_CLK_24M_PMSYNC2")
	)
	(segment
		(start 400.05 -116.355114)
		(end 400.43989 -116.355114)
		(width 0.0889)
		(layer "F.Cu")
		(net "TP_CLK_24M_PMSYNC2")
	)
	(segment
		(start 400.43989 -116.355114)
		(end 400.75104 -116.043964)
		(width 0.0889)
		(layer "F.Cu")
		(net "TP_CLK_24M_PMSYNC2")
	)
	(segment
		(start 401.238466 -116.273326)
		(end 402.140928 -116.273326)
		(width 0.0889)
		(layer "F.Cu")
		(net "TP_CLK_24M_PMSYNC2")
	)
	(segment
		(start 401.009104 -116.043964)
		(end 401.238466 -116.273326)
		(width 0.0889)
		(layer "F.Cu")
		(net "TP_CLK_24M_PMSYNC2")
	)
	(segment
		(start 400.75104 -116.043964)
		(end 401.009104 -116.043964)
		(width 0.0889)
		(layer "F.Cu")
		(net "TP_CLK_24M_PMSYNC2")
	)
	(segment
		(start 402.450554 -115.9637)
		(end 403.2377 -115.9637)
		(width 0.0889)
		(layer "F.Cu")
		(net "TP_CLK_24M_PMSYNC2")
	)
	(via
		(at 403.2377 -115.9637)
		(size 0.508)
		(drill 0.254)
		(layers "F.Cu" "B.Cu")
		(net "TP_CLK_24M_PMSYNC2")
	)
	(segment
		(start 472.329002 -46.746922)
		(end 472.524328 -46.942248)
		(width 0.10795)
		(layer "F.Cu")
		(net "RMII_PCH_SPRNGVLLE_ARB_OUT")
	)
	(segment
		(start 478.615502 -43.409362)
		(end 476.025464 -45.9994)
		(width 0.10795)
		(layer "F.Cu")
		(net "RMII_PCH_SPRNGVLLE_ARB_OUT")
	)
	(segment
		(start 472.329002 -46.354238)
		(end 472.329002 -46.746922)
		(width 0.10795)
		(layer "F.Cu")
		(net "RMII_PCH_SPRNGVLLE_ARB_OUT")
	)
	(segment
		(start 472.524328 -46.942248)
		(end 472.524328 -50.360072)
		(width 0.10795)
		(layer "F.Cu")
		(net "RMII_PCH_SPRNGVLLE_ARB_OUT")
	)
	(segment
		(start 472.33332 -46.332394)
		(end 472.33332 -46.34992)
		(width 0.10795)
		(layer "F.Cu")
		(net "RMII_PCH_SPRNGVLLE_ARB_OUT")
	)
	(segment
		(start 478.615502 -43.100752)
		(end 478.615502 -43.409362)
		(width 0.10795)
		(layer "F.Cu")
		(net "RMII_PCH_SPRNGVLLE_ARB_OUT")
	)
	(segment
		(start 472.68384 -45.9994)
		(end 472.598242 -46.084998)
		(width 0.10795)
		(layer "F.Cu")
		(net "RMII_PCH_SPRNGVLLE_ARB_OUT")
	)
	(segment
		(start 472.33332 -46.34992)
		(end 472.329002 -46.354238)
		(width 0.10795)
		(layer "F.Cu")
		(net "RMII_PCH_SPRNGVLLE_ARB_OUT")
	)
	(segment
		(start 476.025464 -45.9994)
		(end 472.68384 -45.9994)
		(width 0.10795)
		(layer "F.Cu")
		(net "RMII_PCH_SPRNGVLLE_ARB_OUT")
	)
	(segment
		(start 479.8822 -42.717466)
		(end 478.998788 -42.717466)
		(width 0.10795)
		(layer "F.Cu")
		(net "RMII_PCH_SPRNGVLLE_ARB_OUT")
	)
	(segment
		(start 478.998788 -42.717466)
		(end 478.615502 -43.100752)
		(width 0.10795)
		(layer "F.Cu")
		(net "RMII_PCH_SPRNGVLLE_ARB_OUT")
	)
	(segment
		(start 472.524328 -50.360072)
		(end 472.059 -50.8254)
		(width 0.10795)
		(layer "F.Cu")
		(net "RMII_PCH_SPRNGVLLE_ARB_OUT")
	)
	(segment
		(start 472.598242 -46.084998)
		(end 472.580716 -46.084998)
		(width 0.10795)
		(layer "F.Cu")
		(net "RMII_PCH_SPRNGVLLE_ARB_OUT")
	)
	(segment
		(start 472.580716 -46.084998)
		(end 472.33332 -46.332394)
		(width 0.10795)
		(layer "F.Cu")
		(net "RMII_PCH_SPRNGVLLE_ARB_OUT")
	)
	(via
		(at 392.839448 -73.104248)
		(size 0.508)
		(drill 0.254)
		(layers "F.Cu" "B.Cu")
		(net "RMII_PCH_SPRNGVLLE_ARB_OUT")
	)
	(via
		(at 468.40394 -52.4764)
		(size 0.6604)
		(drill 0.3302)
		(layers "F.Cu" "B.Cu")
		(net "RMII_PCH_SPRNGVLLE_ARB_OUT")
	)
	(via
		(at 472.059 -50.8254)
		(size 0.508)
		(drill 0.254)
		(layers "F.Cu" "B.Cu")
		(net "RMII_PCH_SPRNGVLLE_ARB_OUT")
	)
	(via
		(at 392.141456 -79.095346)
		(size 0.508)
		(drill 0.254)
		(layers "F.Cu" "B.Cu")
		(net "RMII_PCH_SPRNGVLLE_ARB_OUT")
	)
	(segment
		(start 417.247324 -57.337198)
		(end 415.49066 -59.093862)
		(width 0.10795)
		(layer "B.Cu")
		(net "RMII_PCH_SPRNGVLLE_ARB_OUT")
	)
	(segment
		(start 388.112 -86.31428)
		(end 388.112 -86.7156)
		(width 0.10795)
		(layer "B.Cu")
		(net "RMII_PCH_SPRNGVLLE_ARB_OUT")
	)
	(segment
		(start 390.02716 -81.25968)
		(end 389.01751 -82.26933)
		(width 0.10795)
		(layer "B.Cu")
		(net "RMII_PCH_SPRNGVLLE_ARB_OUT")
	)
	(segment
		(start 423.333418 -53.703982)
		(end 423.057066 -53.980334)
		(width 0.10795)
		(layer "B.Cu")
		(net "RMII_PCH_SPRNGVLLE_ARB_OUT")
	)
	(segment
		(start 395.220444 -69.574156)
		(end 392.780266 -72.014334)
		(width 0.10795)
		(layer "B.Cu")
		(net "RMII_PCH_SPRNGVLLE_ARB_OUT")
	)
	(segment
		(start 423.731944 -53.752496)
		(end 423.68343 -53.703982)
		(width 0.10795)
		(layer "B.Cu")
		(net "RMII_PCH_SPRNGVLLE_ARB_OUT")
	)
	(segment
		(start 429.73498 -53.95595)
		(end 429.734726 -53.956204)
		(width 0.10795)
		(layer "B.Cu")
		(net "RMII_PCH_SPRNGVLLE_ARB_OUT")
	)
	(segment
		(start 412.8643 -59.093862)
		(end 411.562042 -60.39612)
		(width 0.10795)
		(layer "B.Cu")
		(net "RMII_PCH_SPRNGVLLE_ARB_OUT")
	)
	(segment
		(start 396.585186 -69.570346)
		(end 396.120366 -69.570346)
		(width 0.10795)
		(layer "B.Cu")
		(net "RMII_PCH_SPRNGVLLE_ARB_OUT")
	)
	(segment
		(start 401.566888 -63.12408)
		(end 401.566888 -64.307466)
		(width 0.10795)
		(layer "B.Cu")
		(net "RMII_PCH_SPRNGVLLE_ARB_OUT")
	)
	(segment
		(start 388.64794 -85.77834)
		(end 388.112 -86.31428)
		(width 0.10795)
		(layer "B.Cu")
		(net "RMII_PCH_SPRNGVLLE_ARB_OUT")
	)
	(segment
		(start 400.983704 -65.171828)
		(end 400.983958 -65.172082)
		(width 0.10795)
		(layer "B.Cu")
		(net "RMII_PCH_SPRNGVLLE_ARB_OUT")
	)
	(segment
		(start 400.983704 -64.89065)
		(end 400.983704 -65.171828)
		(width 0.10795)
		(layer "B.Cu")
		(net "RMII_PCH_SPRNGVLLE_ARB_OUT")
	)
	(segment
		(start 389.01751 -82.26933)
		(end 389.01751 -83.67649)
		(width 0.10795)
		(layer "B.Cu")
		(net "RMII_PCH_SPRNGVLLE_ARB_OUT")
	)
	(segment
		(start 420.232332 -57.337198)
		(end 417.247324 -57.337198)
		(width 0.10795)
		(layer "B.Cu")
		(net "RMII_PCH_SPRNGVLLE_ARB_OUT")
	)
	(segment
		(start 435.822598 -55.534052)
		(end 434.244496 -53.95595)
		(width 0.10795)
		(layer "B.Cu")
		(net "RMII_PCH_SPRNGVLLE_ARB_OUT")
	)
	(segment
		(start 392.141456 -79.095346)
		(end 390.774174 -79.095346)
		(width 0.10795)
		(layer "B.Cu")
		(net "RMII_PCH_SPRNGVLLE_ARB_OUT")
	)
	(segment
		(start 423.68343 -53.703982)
		(end 423.333418 -53.703982)
		(width 0.10795)
		(layer "B.Cu")
		(net "RMII_PCH_SPRNGVLLE_ARB_OUT")
	)
	(segment
		(start 464.844892 -55.534052)
		(end 435.822598 -55.534052)
		(width 0.10795)
		(layer "B.Cu")
		(net "RMII_PCH_SPRNGVLLE_ARB_OUT")
	)
	(segment
		(start 401.566888 -64.307466)
		(end 400.983704 -64.89065)
		(width 0.10795)
		(layer "B.Cu")
		(net "RMII_PCH_SPRNGVLLE_ARB_OUT")
	)
	(segment
		(start 397.218916 -69.105018)
		(end 396.753334 -69.5706)
		(width 0.10795)
		(layer "B.Cu")
		(net "RMII_PCH_SPRNGVLLE_ARB_OUT")
	)
	(segment
		(start 429.571658 -53.956204)
		(end 428.812706 -54.715156)
		(width 0.10795)
		(layer "B.Cu")
		(net "RMII_PCH_SPRNGVLLE_ARB_OUT")
	)
	(segment
		(start 428.812706 -54.715156)
		(end 424.715686 -54.715156)
		(width 0.10795)
		(layer "B.Cu")
		(net "RMII_PCH_SPRNGVLLE_ARB_OUT")
	)
	(segment
		(start 395.62532 -69.570092)
		(end 395.624812 -69.5706)
		(width 0.10795)
		(layer "B.Cu")
		(net "RMII_PCH_SPRNGVLLE_ARB_OUT")
	)
	(segment
		(start 434.244496 -53.95595)
		(end 429.73498 -53.95595)
		(width 0.10795)
		(layer "B.Cu")
		(net "RMII_PCH_SPRNGVLLE_ARB_OUT")
	)
	(segment
		(start 396.58544 -69.5706)
		(end 396.585186 -69.570346)
		(width 0.10795)
		(layer "B.Cu")
		(net "RMII_PCH_SPRNGVLLE_ARB_OUT")
	)
	(segment
		(start 390.774174 -79.095346)
		(end 390.02716 -79.84236)
		(width 0.10795)
		(layer "B.Cu")
		(net "RMII_PCH_SPRNGVLLE_ARB_OUT")
	)
	(segment
		(start 395.624812 -69.5706)
		(end 395.276578 -69.5706)
		(width 0.10795)
		(layer "B.Cu")
		(net "RMII_PCH_SPRNGVLLE_ARB_OUT")
	)
	(segment
		(start 388.64794 -84.04606)
		(end 388.64794 -84.75472)
		(width 0.10795)
		(layer "B.Cu")
		(net "RMII_PCH_SPRNGVLLE_ARB_OUT")
	)
	(segment
		(start 405.042116 -61.50991)
		(end 403.181058 -61.50991)
		(width 0.10795)
		(layer "B.Cu")
		(net "RMII_PCH_SPRNGVLLE_ARB_OUT")
	)
	(segment
		(start 392.8237 -73.0885)
		(end 392.8237 -73.104248)
		(width 0.10795)
		(layer "B.Cu")
		(net "RMII_PCH_SPRNGVLLE_ARB_OUT")
	)
	(segment
		(start 471.652854 -50.8254)
		(end 472.059 -50.8254)
		(width 0.10795)
		(layer "B.Cu")
		(net "RMII_PCH_SPRNGVLLE_ARB_OUT")
	)
	(segment
		(start 388.64794 -85.51672)
		(end 388.64794 -85.77834)
		(width 0.10795)
		(layer "B.Cu")
		(net "RMII_PCH_SPRNGVLLE_ARB_OUT")
	)
	(segment
		(start 468.40394 -52.4764)
		(end 467.902544 -52.4764)
		(width 0.10795)
		(layer "B.Cu")
		(net "RMII_PCH_SPRNGVLLE_ARB_OUT")
	)
	(segment
		(start 395.273276 -69.574156)
		(end 395.220444 -69.574156)
		(width 0.10795)
		(layer "B.Cu")
		(net "RMII_PCH_SPRNGVLLE_ARB_OUT")
	)
	(segment
		(start 396.120366 -69.570346)
		(end 396.120112 -69.570092)
		(width 0.10795)
		(layer "B.Cu")
		(net "RMII_PCH_SPRNGVLLE_ARB_OUT")
	)
	(segment
		(start 390.02716 -79.84236)
		(end 390.02716 -81.25968)
		(width 0.10795)
		(layer "B.Cu")
		(net "RMII_PCH_SPRNGVLLE_ARB_OUT")
	)
	(segment
		(start 403.181058 -61.50991)
		(end 401.566888 -63.12408)
		(width 0.10795)
		(layer "B.Cu")
		(net "RMII_PCH_SPRNGVLLE_ARB_OUT")
	)
	(segment
		(start 423.753026 -53.752496)
		(end 423.731944 -53.752496)
		(width 0.10795)
		(layer "B.Cu")
		(net "RMII_PCH_SPRNGVLLE_ARB_OUT")
	)
	(segment
		(start 395.276578 -69.5706)
		(end 395.273276 -69.574156)
		(width 0.10795)
		(layer "B.Cu")
		(net "RMII_PCH_SPRNGVLLE_ARB_OUT")
	)
	(segment
		(start 415.49066 -59.093862)
		(end 412.8643 -59.093862)
		(width 0.10795)
		(layer "B.Cu")
		(net "RMII_PCH_SPRNGVLLE_ARB_OUT")
	)
	(segment
		(start 470.001854 -52.4764)
		(end 471.652854 -50.8254)
		(width 0.10795)
		(layer "B.Cu")
		(net "RMII_PCH_SPRNGVLLE_ARB_OUT")
	)
	(segment
		(start 400.983958 -65.666874)
		(end 400.567652 -66.08318)
		(width 0.10795)
		(layer "B.Cu")
		(net "RMII_PCH_SPRNGVLLE_ARB_OUT")
	)
	(segment
		(start 392.780266 -72.014334)
		(end 392.780266 -73.045066)
		(width 0.10795)
		(layer "B.Cu")
		(net "RMII_PCH_SPRNGVLLE_ARB_OUT")
	)
	(segment
		(start 429.734726 -53.956204)
		(end 429.571658 -53.956204)
		(width 0.10795)
		(layer "B.Cu")
		(net "RMII_PCH_SPRNGVLLE_ARB_OUT")
	)
	(segment
		(start 468.40394 -52.4764)
		(end 470.001854 -52.4764)
		(width 0.10795)
		(layer "B.Cu")
		(net "RMII_PCH_SPRNGVLLE_ARB_OUT")
	)
	(segment
		(start 406.749504 -61.519054)
		(end 405.05126 -61.519054)
		(width 0.10795)
		(layer "B.Cu")
		(net "RMII_PCH_SPRNGVLLE_ARB_OUT")
	)
	(segment
		(start 396.120112 -69.570092)
		(end 395.62532 -69.570092)
		(width 0.10795)
		(layer "B.Cu")
		(net "RMII_PCH_SPRNGVLLE_ARB_OUT")
	)
	(segment
		(start 423.057066 -53.980334)
		(end 423.057066 -54.512464)
		(width 0.10795)
		(layer "B.Cu")
		(net "RMII_PCH_SPRNGVLLE_ARB_OUT")
	)
	(segment
		(start 400.567652 -66.273934)
		(end 400.567906 -66.274188)
		(width 0.10795)
		(layer "B.Cu")
		(net "RMII_PCH_SPRNGVLLE_ARB_OUT")
	)
	(segment
		(start 400.567652 -66.08318)
		(end 400.567652 -66.273934)
		(width 0.10795)
		(layer "B.Cu")
		(net "RMII_PCH_SPRNGVLLE_ARB_OUT")
	)
	(segment
		(start 396.753334 -69.5706)
		(end 396.58544 -69.5706)
		(width 0.10795)
		(layer "B.Cu")
		(net "RMII_PCH_SPRNGVLLE_ARB_OUT")
	)
	(segment
		(start 388.112 -86.7156)
		(end 388.366 -86.9696)
		(width 0.10795)
		(layer "B.Cu")
		(net "RMII_PCH_SPRNGVLLE_ARB_OUT")
	)
	(segment
		(start 388.366 -86.9696)
		(end 388.366 -87.3125)
		(width 0.10795)
		(layer "B.Cu")
		(net "RMII_PCH_SPRNGVLLE_ARB_OUT")
	)
	(segment
		(start 405.05126 -61.519054)
		(end 405.042116 -61.50991)
		(width 0.10795)
		(layer "B.Cu")
		(net "RMII_PCH_SPRNGVLLE_ARB_OUT")
	)
	(segment
		(start 392.780266 -73.045066)
		(end 392.8237 -73.0885)
		(width 0.10795)
		(layer "B.Cu")
		(net "RMII_PCH_SPRNGVLLE_ARB_OUT")
	)
	(segment
		(start 400.567906 -66.274188)
		(end 400.567906 -66.573908)
		(width 0.10795)
		(layer "B.Cu")
		(net "RMII_PCH_SPRNGVLLE_ARB_OUT")
	)
	(segment
		(start 407.872438 -60.39612)
		(end 406.749504 -61.519054)
		(width 0.10795)
		(layer "B.Cu")
		(net "RMII_PCH_SPRNGVLLE_ARB_OUT")
	)
	(segment
		(start 424.715686 -54.715156)
		(end 423.753026 -53.752496)
		(width 0.10795)
		(layer "B.Cu")
		(net "RMII_PCH_SPRNGVLLE_ARB_OUT")
	)
	(segment
		(start 392.8237 -73.104248)
		(end 392.839448 -73.104248)
		(width 0.10795)
		(layer "B.Cu")
		(net "RMII_PCH_SPRNGVLLE_ARB_OUT")
	)
	(segment
		(start 411.562042 -60.39612)
		(end 407.872438 -60.39612)
		(width 0.10795)
		(layer "B.Cu")
		(net "RMII_PCH_SPRNGVLLE_ARB_OUT")
	)
	(segment
		(start 400.567906 -66.573908)
		(end 398.036796 -69.105018)
		(width 0.10795)
		(layer "B.Cu")
		(net "RMII_PCH_SPRNGVLLE_ARB_OUT")
	)
	(segment
		(start 467.902544 -52.4764)
		(end 464.844892 -55.534052)
		(width 0.10795)
		(layer "B.Cu")
		(net "RMII_PCH_SPRNGVLLE_ARB_OUT")
	)
	(segment
		(start 389.01751 -83.67649)
		(end 388.64794 -84.04606)
		(width 0.10795)
		(layer "B.Cu")
		(net "RMII_PCH_SPRNGVLLE_ARB_OUT")
	)
	(segment
		(start 400.983958 -65.172082)
		(end 400.983958 -65.666874)
		(width 0.10795)
		(layer "B.Cu")
		(net "RMII_PCH_SPRNGVLLE_ARB_OUT")
	)
	(segment
		(start 423.057066 -54.512464)
		(end 420.232332 -57.337198)
		(width 0.10795)
		(layer "B.Cu")
		(net "RMII_PCH_SPRNGVLLE_ARB_OUT")
	)
	(segment
		(start 398.036796 -69.105018)
		(end 397.218916 -69.105018)
		(width 0.10795)
		(layer "B.Cu")
		(net "RMII_PCH_SPRNGVLLE_ARB_OUT")
	)
	(segment
		(start 388.64794 -85.51672)
		(end 388.64794 -84.75472)
		(width 0.10795)
		(layer "B.Cu")
		(net "RMII_PCH_SPRNGVLLE_ARB_OUT")
	)
	(segment
		(start 392.1506 -73.792842)
		(end 392.1506 -79.086202)
		(width 0.089408)
		(layer "In11.Cu")
		(net "RMII_PCH_SPRNGVLLE_ARB_OUT")
	)
	(segment
		(start 392.1506 -79.086202)
		(end 392.141456 -79.095346)
		(width 0.089408)
		(layer "In11.Cu")
		(net "RMII_PCH_SPRNGVLLE_ARB_OUT")
	)
	(segment
		(start 392.8237 -73.104248)
		(end 392.8237 -73.119742)
		(width 0.089408)
		(layer "In11.Cu")
		(net "RMII_PCH_SPRNGVLLE_ARB_OUT")
	)
	(segment
		(start 392.839448 -73.104248)
		(end 392.8237 -73.104248)
		(width 0.089408)
		(layer "In11.Cu")
		(net "RMII_PCH_SPRNGVLLE_ARB_OUT")
	)
	(segment
		(start 392.8237 -73.119742)
		(end 392.1506 -73.792842)
		(width 0.089408)
		(layer "In11.Cu")
		(net "RMII_PCH_SPRNGVLLE_ARB_OUT")
	)
	(segment
		(start 386.783834 -92.517722)
		(end 386.708904 -92.442792)
		(width 0.0889)
		(layer "F.Cu")
		(net "RMII_PCH_SPRNGVLLE_ARB_IN")
	)
	(segment
		(start 475.8944 -45.6184)
		(end 472.303602 -45.6184)
		(width 0.10795)
		(layer "F.Cu")
		(net "RMII_PCH_SPRNGVLLE_ARB_IN")
	)
	(segment
		(start 472.303602 -45.6184)
		(end 472.106244 -45.815758)
		(width 0.10795)
		(layer "F.Cu")
		(net "RMII_PCH_SPRNGVLLE_ARB_IN")
	)
	(segment
		(start 477.48952 -43.63212)
		(end 477.48952 -44.02328)
		(width 0.10795)
		(layer "F.Cu")
		(net "RMII_PCH_SPRNGVLLE_ARB_IN")
	)
	(segment
		(start 386.783834 -93.262704)
		(end 386.783834 -92.517722)
		(width 0.0889)
		(layer "F.Cu")
		(net "RMII_PCH_SPRNGVLLE_ARB_IN")
	)
	(segment
		(start 386.708904 -92.442792)
		(end 386.708904 -91.924378)
		(width 0.0889)
		(layer "F.Cu")
		(net "RMII_PCH_SPRNGVLLE_ARB_IN")
	)
	(segment
		(start 386.867908 -93.902784)
		(end 386.689346 -93.724222)
		(width 0.0889)
		(layer "F.Cu")
		(net "RMII_PCH_SPRNGVLLE_ARB_IN")
	)
	(segment
		(start 477.3041 -43.4467)
		(end 477.48952 -43.63212)
		(width 0.10795)
		(layer "F.Cu")
		(net "RMII_PCH_SPRNGVLLE_ARB_IN")
	)
	(segment
		(start 386.867908 -94.257876)
		(end 386.867908 -93.902784)
		(width 0.0889)
		(layer "F.Cu")
		(net "RMII_PCH_SPRNGVLLE_ARB_IN")
	)
	(segment
		(start 477.3041 -42.9514)
		(end 477.3041 -43.4467)
		(width 0.10795)
		(layer "F.Cu")
		(net "RMII_PCH_SPRNGVLLE_ARB_IN")
	)
	(segment
		(start 477.48952 -44.02328)
		(end 475.8944 -45.6184)
		(width 0.10795)
		(layer "F.Cu")
		(net "RMII_PCH_SPRNGVLLE_ARB_IN")
	)
	(segment
		(start 386.689346 -93.357192)
		(end 386.783834 -93.262704)
		(width 0.0889)
		(layer "F.Cu")
		(net "RMII_PCH_SPRNGVLLE_ARB_IN")
	)
	(segment
		(start 386.689346 -93.724222)
		(end 386.689346 -93.357192)
		(width 0.0889)
		(layer "F.Cu")
		(net "RMII_PCH_SPRNGVLLE_ARB_IN")
	)
	(segment
		(start 386.985002 -94.37497)
		(end 386.867908 -94.257876)
		(width 0.0889)
		(layer "F.Cu")
		(net "RMII_PCH_SPRNGVLLE_ARB_IN")
	)
	(via
		(at 386.708904 -91.924378)
		(size 0.508)
		(drill 0.254)
		(layers "F.Cu" "B.Cu")
		(net "RMII_PCH_SPRNGVLLE_ARB_IN")
	)
	(via
		(at 472.106244 -45.815758)
		(size 0.508)
		(drill 0.254)
		(layers "F.Cu" "B.Cu")
		(net "RMII_PCH_SPRNGVLLE_ARB_IN")
	)
	(segment
		(start 389.319516 -83.02625)
		(end 389.319516 -84.754974)
		(width 0.089408)
		(layer "In2.Cu")
		(net "RMII_PCH_SPRNGVLLE_ARB_IN")
	)
	(segment
		(start 411.344618 -45.55617)
		(end 411.344364 -45.55617)
		(width 0.089408)
		(layer "In2.Cu")
		(net "RMII_PCH_SPRNGVLLE_ARB_IN")
	)
	(segment
		(start 389.340344 -79.056738)
		(end 389.34009 -79.056992)
		(width 0.089408)
		(layer "In2.Cu")
		(net "RMII_PCH_SPRNGVLLE_ARB_IN")
	)
	(segment
		(start 412.86684 -45.448474)
		(end 412.544768 -45.770546)
		(width 0.089408)
		(layer "In2.Cu")
		(net "RMII_PCH_SPRNGVLLE_ARB_IN")
	)
	(segment
		(start 424.879008 -47.706788)
		(end 420.384478 -47.706788)
		(width 0.089408)
		(layer "In2.Cu")
		(net "RMII_PCH_SPRNGVLLE_ARB_IN")
	)
	(segment
		(start 431.787046 -51.198526)
		(end 431.786792 -51.19878)
		(width 0.089408)
		(layer "In2.Cu")
		(net "RMII_PCH_SPRNGVLLE_ARB_IN")
	)
	(segment
		(start 389.34009 -79.21498)
		(end 389.339836 -79.215234)
		(width 0.089408)
		(layer "In2.Cu")
		(net "RMII_PCH_SPRNGVLLE_ARB_IN")
	)
	(segment
		(start 412.544768 -45.770546)
		(end 411.558994 -45.770546)
		(width 0.089408)
		(layer "In2.Cu")
		(net "RMII_PCH_SPRNGVLLE_ARB_IN")
	)
	(segment
		(start 387.166612 -87.225886)
		(end 386.389372 -88.003126)
		(width 0.089408)
		(layer "In2.Cu")
		(net "RMII_PCH_SPRNGVLLE_ARB_IN")
	)
	(segment
		(start 390.9314 -69.191124)
		(end 390.9314 -75.049634)
		(width 0.089408)
		(layer "In2.Cu")
		(net "RMII_PCH_SPRNGVLLE_ARB_IN")
	)
	(segment
		(start 387.166612 -86.485222)
		(end 387.166612 -87.225886)
		(width 0.089408)
		(layer "In2.Cu")
		(net "RMII_PCH_SPRNGVLLE_ARB_IN")
	)
	(segment
		(start 411.344364 -45.55617)
		(end 411.34411 -45.555916)
		(width 0.089408)
		(layer "In2.Cu")
		(net "RMII_PCH_SPRNGVLLE_ARB_IN")
	)
	(segment
		(start 438.99709 -48.298608)
		(end 436.097172 -51.198526)
		(width 0.089408)
		(layer "In2.Cu")
		(net "RMII_PCH_SPRNGVLLE_ARB_IN")
	)
	(segment
		(start 410.85389 -45.555916)
		(end 410.467048 -45.942758)
		(width 0.089408)
		(layer "In2.Cu")
		(net "RMII_PCH_SPRNGVLLE_ARB_IN")
	)
	(segment
		(start 389.744204 -76.23683)
		(end 389.744204 -77.789786)
		(width 0.089408)
		(layer "In2.Cu")
		(net "RMII_PCH_SPRNGVLLE_ARB_IN")
	)
	(segment
		(start 394.042646 -62.787276)
		(end 392.318748 -64.511174)
		(width 0.089408)
		(layer "In2.Cu")
		(net "RMII_PCH_SPRNGVLLE_ARB_IN")
	)
	(segment
		(start 468.301832 -48.298608)
		(end 438.99709 -48.298608)
		(width 0.089408)
		(layer "In2.Cu")
		(net "RMII_PCH_SPRNGVLLE_ARB_IN")
	)
	(segment
		(start 436.097172 -51.198526)
		(end 431.787046 -51.198526)
		(width 0.089408)
		(layer "In2.Cu")
		(net "RMII_PCH_SPRNGVLLE_ARB_IN")
	)
	(segment
		(start 430.906174 -51.19878)
		(end 430.90592 -51.198526)
		(width 0.089408)
		(layer "In2.Cu")
		(net "RMII_PCH_SPRNGVLLE_ARB_IN")
	)
	(segment
		(start 386.389372 -89.555574)
		(end 386.58927 -89.755472)
		(width 0.089408)
		(layer "In2.Cu")
		(net "RMII_PCH_SPRNGVLLE_ARB_IN")
	)
	(segment
		(start 389.319516 -84.754974)
		(end 388.012432 -86.062058)
		(width 0.089408)
		(layer "In2.Cu")
		(net "RMII_PCH_SPRNGVLLE_ARB_IN")
	)
	(segment
		(start 389.001 -82.265012)
		(end 389.001 -82.677254)
		(width 0.089408)
		(layer "In2.Cu")
		(net "RMII_PCH_SPRNGVLLE_ARB_IN")
	)
	(segment
		(start 411.34411 -45.555916)
		(end 410.85389 -45.555916)
		(width 0.089408)
		(layer "In2.Cu")
		(net "RMII_PCH_SPRNGVLLE_ARB_IN")
	)
	(segment
		(start 431.786792 -51.19878)
		(end 430.906174 -51.19878)
		(width 0.089408)
		(layer "In2.Cu")
		(net "RMII_PCH_SPRNGVLLE_ARB_IN")
	)
	(segment
		(start 387.951726 -86.062312)
		(end 387.589522 -86.062312)
		(width 0.089408)
		(layer "In2.Cu")
		(net "RMII_PCH_SPRNGVLLE_ARB_IN")
	)
	(segment
		(start 411.558994 -45.770546)
		(end 411.344618 -45.55617)
		(width 0.089408)
		(layer "In2.Cu")
		(net "RMII_PCH_SPRNGVLLE_ARB_IN")
	)
	(segment
		(start 389.744204 -77.789786)
		(end 389.339836 -78.194154)
		(width 0.089408)
		(layer "In2.Cu")
		(net "RMII_PCH_SPRNGVLLE_ARB_IN")
	)
	(segment
		(start 386.58927 -91.804744)
		(end 386.708904 -91.924378)
		(width 0.089408)
		(layer "In2.Cu")
		(net "RMII_PCH_SPRNGVLLE_ARB_IN")
	)
	(segment
		(start 392.318748 -64.511174)
		(end 392.318748 -64.933576)
		(width 0.089408)
		(layer "In2.Cu")
		(net "RMII_PCH_SPRNGVLLE_ARB_IN")
	)
	(segment
		(start 427.477936 -51.19878)
		(end 426.657008 -50.377852)
		(width 0.089408)
		(layer "In2.Cu")
		(net "RMII_PCH_SPRNGVLLE_ARB_IN")
	)
	(segment
		(start 428.425102 -51.19878)
		(end 427.477936 -51.19878)
		(width 0.089408)
		(layer "In2.Cu")
		(net "RMII_PCH_SPRNGVLLE_ARB_IN")
	)
	(segment
		(start 388.012432 -86.062058)
		(end 387.95198 -86.062058)
		(width 0.089408)
		(layer "In2.Cu")
		(net "RMII_PCH_SPRNGVLLE_ARB_IN")
	)
	(segment
		(start 419.365176 -46.687486)
		(end 419.365176 -46.416722)
		(width 0.089408)
		(layer "In2.Cu")
		(net "RMII_PCH_SPRNGVLLE_ARB_IN")
	)
	(segment
		(start 389.339836 -78.739746)
		(end 389.340344 -78.740254)
		(width 0.089408)
		(layer "In2.Cu")
		(net "RMII_PCH_SPRNGVLLE_ARB_IN")
	)
	(segment
		(start 470.860374 -45.740066)
		(end 468.301832 -48.298608)
		(width 0.089408)
		(layer "In2.Cu")
		(net "RMII_PCH_SPRNGVLLE_ARB_IN")
	)
	(segment
		(start 418.396928 -45.448474)
		(end 412.86684 -45.448474)
		(width 0.089408)
		(layer "In2.Cu")
		(net "RMII_PCH_SPRNGVLLE_ARB_IN")
	)
	(segment
		(start 386.58927 -89.755472)
		(end 386.58927 -91.804744)
		(width 0.089408)
		(layer "In2.Cu")
		(net "RMII_PCH_SPRNGVLLE_ARB_IN")
	)
	(segment
		(start 389.001 -82.677254)
		(end 389.319262 -82.995516)
		(width 0.089408)
		(layer "In2.Cu")
		(net "RMII_PCH_SPRNGVLLE_ARB_IN")
	)
	(segment
		(start 392.2522 -50.977038)
		(end 394.042646 -52.767484)
		(width 0.089408)
		(layer "In2.Cu")
		(net "RMII_PCH_SPRNGVLLE_ARB_IN")
	)
	(segment
		(start 389.319262 -83.025996)
		(end 389.319516 -83.02625)
		(width 0.089408)
		(layer "In2.Cu")
		(net "RMII_PCH_SPRNGVLLE_ARB_IN")
	)
	(segment
		(start 472.106244 -45.815758)
		(end 472.030552 -45.740066)
		(width 0.089408)
		(layer "In2.Cu")
		(net "RMII_PCH_SPRNGVLLE_ARB_IN")
	)
	(segment
		(start 472.030552 -45.740066)
		(end 470.860374 -45.740066)
		(width 0.089408)
		(layer "In2.Cu")
		(net "RMII_PCH_SPRNGVLLE_ARB_IN")
	)
	(segment
		(start 389.339836 -79.215234)
		(end 389.339836 -81.926176)
		(width 0.089408)
		(layer "In2.Cu")
		(net "RMII_PCH_SPRNGVLLE_ARB_IN")
	)
	(segment
		(start 387.95198 -86.062058)
		(end 387.951726 -86.062312)
		(width 0.089408)
		(layer "In2.Cu")
		(net "RMII_PCH_SPRNGVLLE_ARB_IN")
	)
	(segment
		(start 393.661646 -47.31639)
		(end 392.2522 -48.725836)
		(width 0.089408)
		(layer "In2.Cu")
		(net "RMII_PCH_SPRNGVLLE_ARB_IN")
	)
	(segment
		(start 387.589522 -86.062312)
		(end 387.166612 -86.485222)
		(width 0.089408)
		(layer "In2.Cu")
		(net "RMII_PCH_SPRNGVLLE_ARB_IN")
	)
	(segment
		(start 426.657008 -49.484788)
		(end 424.879008 -47.706788)
		(width 0.089408)
		(layer "In2.Cu")
		(net "RMII_PCH_SPRNGVLLE_ARB_IN")
	)
	(segment
		(start 390.009888 -67.242436)
		(end 390.009888 -68.269612)
		(width 0.089408)
		(layer "In2.Cu")
		(net "RMII_PCH_SPRNGVLLE_ARB_IN")
	)
	(segment
		(start 392.2522 -48.725836)
		(end 392.2522 -50.977038)
		(width 0.089408)
		(layer "In2.Cu")
		(net "RMII_PCH_SPRNGVLLE_ARB_IN")
	)
	(segment
		(start 420.384478 -47.706788)
		(end 419.365176 -46.687486)
		(width 0.089408)
		(layer "In2.Cu")
		(net "RMII_PCH_SPRNGVLLE_ARB_IN")
	)
	(segment
		(start 389.339836 -81.926176)
		(end 389.001 -82.265012)
		(width 0.089408)
		(layer "In2.Cu")
		(net "RMII_PCH_SPRNGVLLE_ARB_IN")
	)
	(segment
		(start 389.339836 -78.194154)
		(end 389.339836 -78.739746)
		(width 0.089408)
		(layer "In2.Cu")
		(net "RMII_PCH_SPRNGVLLE_ARB_IN")
	)
	(segment
		(start 404.960328 -45.362622)
		(end 403.00656 -47.31639)
		(width 0.089408)
		(layer "In2.Cu")
		(net "RMII_PCH_SPRNGVLLE_ARB_IN")
	)
	(segment
		(start 410.467048 -45.942758)
		(end 409.511246 -45.942758)
		(width 0.089408)
		(layer "In2.Cu")
		(net "RMII_PCH_SPRNGVLLE_ARB_IN")
	)
	(segment
		(start 419.365176 -46.416722)
		(end 418.396928 -45.448474)
		(width 0.089408)
		(layer "In2.Cu")
		(net "RMII_PCH_SPRNGVLLE_ARB_IN")
	)
	(segment
		(start 389.340344 -78.740254)
		(end 389.340344 -79.056738)
		(width 0.089408)
		(layer "In2.Cu")
		(net "RMII_PCH_SPRNGVLLE_ARB_IN")
	)
	(segment
		(start 428.425356 -51.198526)
		(end 428.425102 -51.19878)
		(width 0.089408)
		(layer "In2.Cu")
		(net "RMII_PCH_SPRNGVLLE_ARB_IN")
	)
	(segment
		(start 389.34009 -79.056992)
		(end 389.34009 -79.21498)
		(width 0.089408)
		(layer "In2.Cu")
		(net "RMII_PCH_SPRNGVLLE_ARB_IN")
	)
	(segment
		(start 409.511246 -45.942758)
		(end 408.93111 -45.362622)
		(width 0.089408)
		(layer "In2.Cu")
		(net "RMII_PCH_SPRNGVLLE_ARB_IN")
	)
	(segment
		(start 408.93111 -45.362622)
		(end 404.960328 -45.362622)
		(width 0.089408)
		(layer "In2.Cu")
		(net "RMII_PCH_SPRNGVLLE_ARB_IN")
	)
	(segment
		(start 386.389372 -88.003126)
		(end 386.389372 -89.555574)
		(width 0.089408)
		(layer "In2.Cu")
		(net "RMII_PCH_SPRNGVLLE_ARB_IN")
	)
	(segment
		(start 390.9314 -75.049634)
		(end 389.744204 -76.23683)
		(width 0.089408)
		(layer "In2.Cu")
		(net "RMII_PCH_SPRNGVLLE_ARB_IN")
	)
	(segment
		(start 392.318748 -64.933576)
		(end 390.009888 -67.242436)
		(width 0.089408)
		(layer "In2.Cu")
		(net "RMII_PCH_SPRNGVLLE_ARB_IN")
	)
	(segment
		(start 403.00656 -47.31639)
		(end 393.661646 -47.31639)
		(width 0.089408)
		(layer "In2.Cu")
		(net "RMII_PCH_SPRNGVLLE_ARB_IN")
	)
	(segment
		(start 426.657008 -50.377852)
		(end 426.657008 -49.484788)
		(width 0.089408)
		(layer "In2.Cu")
		(net "RMII_PCH_SPRNGVLLE_ARB_IN")
	)
	(segment
		(start 394.042646 -52.767484)
		(end 394.042646 -62.787276)
		(width 0.089408)
		(layer "In2.Cu")
		(net "RMII_PCH_SPRNGVLLE_ARB_IN")
	)
	(segment
		(start 390.009888 -68.269612)
		(end 390.9314 -69.191124)
		(width 0.089408)
		(layer "In2.Cu")
		(net "RMII_PCH_SPRNGVLLE_ARB_IN")
	)
	(segment
		(start 430.90592 -51.198526)
		(end 428.425356 -51.198526)
		(width 0.089408)
		(layer "In2.Cu")
		(net "RMII_PCH_SPRNGVLLE_ARB_IN")
	)
	(segment
		(start 389.319262 -82.995516)
		(end 389.319262 -83.025996)
		(width 0.089408)
		(layer "In2.Cu")
		(net "RMII_PCH_SPRNGVLLE_ARB_IN")
	)
	(segment
		(start 365.6838 -94.0562)
		(end 365.6838 -91.9099)
		(width 0.10795)
		(layer "F.Cu")
		(net "H_PM_SYNC_GTL")
	)
	(segment
		(start 369.23853 -91.5924)
		(end 369.875054 -90.955876)
		(width 0.10795)
		(layer "F.Cu")
		(net "H_PM_SYNC_GTL")
	)
	(segment
		(start 369.875054 -90.955876)
		(end 370.812568 -90.955876)
		(width 0.10795)
		(layer "F.Cu")
		(net "H_PM_SYNC_GTL")
	)
	(segment
		(start 371.3988 -89.84107)
		(end 371.3988 -89.5858)
		(width 0.10795)
		(layer "F.Cu")
		(net "H_PM_SYNC_GTL")
	)
	(segment
		(start 373.2149 -86.323424)
		(end 373.813324 -85.725)
		(width 0.10795)
		(layer "F.Cu")
		(net "H_PM_SYNC_GTL")
	)
	(segment
		(start 366.014 -94.3864)
		(end 366.8776 -94.3864)
		(width 0.10795)
		(layer "F.Cu")
		(net "H_PM_SYNC_GTL")
	)
	(segment
		(start 371.3988 -89.5858)
		(end 372.6688 -88.3158)
		(width 0.10795)
		(layer "F.Cu")
		(net "H_PM_SYNC_GTL")
	)
	(segment
		(start 365.6838 -91.9099)
		(end 366.0013 -91.5924)
		(width 0.10795)
		(layer "F.Cu")
		(net "H_PM_SYNC_GTL")
	)
	(segment
		(start 365.6838 -94.0562)
		(end 366.014 -94.3864)
		(width 0.10795)
		(layer "F.Cu")
		(net "H_PM_SYNC_GTL")
	)
	(segment
		(start 371.051328 -90.717116)
		(end 371.051328 -90.188542)
		(width 0.10795)
		(layer "F.Cu")
		(net "H_PM_SYNC_GTL")
	)
	(segment
		(start 370.812568 -90.955876)
		(end 371.051328 -90.717116)
		(width 0.10795)
		(layer "F.Cu")
		(net "H_PM_SYNC_GTL")
	)
	(segment
		(start 373.813324 -85.725)
		(end 374.0023 -85.725)
		(width 0.10795)
		(layer "F.Cu")
		(net "H_PM_SYNC_GTL")
	)
	(segment
		(start 373.2149 -87.159592)
		(end 373.2149 -86.323424)
		(width 0.10795)
		(layer "F.Cu")
		(net "H_PM_SYNC_GTL")
	)
	(segment
		(start 371.051328 -90.188542)
		(end 371.3988 -89.84107)
		(width 0.10795)
		(layer "F.Cu")
		(net "H_PM_SYNC_GTL")
	)
	(segment
		(start 372.6688 -88.3158)
		(end 372.6688 -87.705692)
		(width 0.10795)
		(layer "F.Cu")
		(net "H_PM_SYNC_GTL")
	)
	(segment
		(start 372.6688 -87.705692)
		(end 373.2149 -87.159592)
		(width 0.10795)
		(layer "F.Cu")
		(net "H_PM_SYNC_GTL")
	)
	(segment
		(start 366.0013 -91.5924)
		(end 369.23853 -91.5924)
		(width 0.10795)
		(layer "F.Cu")
		(net "H_PM_SYNC_GTL")
	)
	(via
		(at 374.0023 -85.725)
		(size 0.508)
		(drill 0.254)
		(layers "F.Cu" "B.Cu")
		(net "H_PM_SYNC_GTL")
	)
	(via
		(at 365.6838 -94.0562)
		(size 0.762)
		(drill 0.381)
		(layers "F.Cu" "B.Cu")
		(net "H_PM_SYNC_GTL")
	)
	(via
		(at 193.981324 -130.6195)
		(size 0.508)
		(drill 0.254)
		(layers "F.Cu" "B.Cu")
		(net "H_PM_SYNC_GTL")
	)
	(via
		(at 130.519678 -66.263774)
		(size 0.508)
		(drill 0.254)
		(layers "F.Cu" "B.Cu")
		(net "H_PM_SYNC_GTL")
	)
	(via
		(at 296.66184 -67.296538)
		(size 0.508)
		(drill 0.254)
		(layers "F.Cu" "B.Cu")
		(net "H_PM_SYNC_GTL")
	)
	(via
		(at 366.8776 -94.3864)
		(size 0.508)
		(drill 0.254)
		(layers "F.Cu" "B.Cu")
		(net "H_PM_SYNC_GTL")
	)
	(segment
		(start 130.61188 -66.875914)
		(end 130.61188 -66.355976)
		(width 0.10795)
		(layer "B.Cu")
		(net "H_PM_SYNC_GTL")
	)
	(segment
		(start 130.61188 -66.355976)
		(end 130.519678 -66.263774)
		(width 0.10795)
		(layer "B.Cu")
		(net "H_PM_SYNC_GTL")
	)
	(segment
		(start 375.285 -87.72144)
		(end 374.453658 -86.890098)
		(width 0.10795)
		(layer "B.Cu")
		(net "H_PM_SYNC_GTL")
	)
	(segment
		(start 374.760998 -88.236806)
		(end 374.408446 -88.236806)
		(width 0.10795)
		(layer "B.Cu")
		(net "H_PM_SYNC_GTL")
	)
	(segment
		(start 375.106692 -88.5825)
		(end 374.760998 -88.236806)
		(width 0.10795)
		(layer "B.Cu")
		(net "H_PM_SYNC_GTL")
	)
	(segment
		(start 375.285 -88.5825)
		(end 375.285 -87.72144)
		(width 0.10795)
		(layer "B.Cu")
		(net "H_PM_SYNC_GTL")
	)
	(segment
		(start 295.8846 -67.265804)
		(end 296.631106 -67.265804)
		(width 0.10795)
		(layer "B.Cu")
		(net "H_PM_SYNC_GTL")
	)
	(segment
		(start 374.453658 -86.176358)
		(end 374.0023 -85.725)
		(width 0.10795)
		(layer "B.Cu")
		(net "H_PM_SYNC_GTL")
	)
	(segment
		(start 374.453658 -86.890098)
		(end 374.453658 -86.176358)
		(width 0.10795)
		(layer "B.Cu")
		(net "H_PM_SYNC_GTL")
	)
	(segment
		(start 296.631106 -67.265804)
		(end 296.66184 -67.296538)
		(width 0.10795)
		(layer "B.Cu")
		(net "H_PM_SYNC_GTL")
	)
	(segment
		(start 375.285 -88.5825)
		(end 375.106692 -88.5825)
		(width 0.10795)
		(layer "B.Cu")
		(net "H_PM_SYNC_GTL")
	)
	(segment
		(start 283.784294 -87.013034)
		(end 283.766514 -87.01278)
		(width 0.0889)
		(layer "In4.Cu")
		(net "H_PM_SYNC_GTL")
	)
	(segment
		(start 292.7096 -81.449418)
		(end 292.71595 -81.460086)
		(width 0.0889)
		(layer "In4.Cu")
		(net "H_PM_SYNC_GTL")
	)
	(segment
		(start 215.401144 -97.593658)
		(end 213.298278 -97.593658)
		(width 0.089408)
		(layer "In4.Cu")
		(net "H_PM_SYNC_GTL")
	)
	(segment
		(start 281.208734 -88.499188)
		(end 281.187144 -88.499188)
		(width 0.0889)
		(layer "In4.Cu")
		(net "H_PM_SYNC_GTL")
	)
	(segment
		(start 295.29151 -76.411836)
		(end 295.28516 -76.422504)
		(width 0.0889)
		(layer "In4.Cu")
		(net "H_PM_SYNC_GTL")
	)
	(segment
		(start 236.488478 -80.259936)
		(end 236.452918 -80.259936)
		(width 0.0889)
		(layer "In4.Cu")
		(net "H_PM_SYNC_GTL")
	)
	(segment
		(start 272.634964 -90.480388)
		(end 270.02105 -90.480388)
		(width 0.0889)
		(layer "In4.Cu")
		(net "H_PM_SYNC_GTL")
	)
	(segment
		(start 296.15003 -73.535286)
		(end 296.154856 -73.543922)
		(width 0.0889)
		(layer "In4.Cu")
		(net "H_PM_SYNC_GTL")
	)
	(segment
		(start 251.941584 -87.194136)
		(end 251.908818 -87.194136)
		(width 0.0889)
		(layer "In4.Cu")
		(net "H_PM_SYNC_GTL")
	)
	(segment
		(start 296.14368 -69.562218)
		(end 296.15003 -69.572886)
		(width 0.0889)
		(layer "In4.Cu")
		(net "H_PM_SYNC_GTL")
	)
	(segment
		(start 233.737404 -80.70342)
		(end 233.653584 -80.70342)
		(width 0.089408)
		(layer "In4.Cu")
		(net "H_PM_SYNC_GTL")
	)
	(segment
		(start 194.4878 -130.113024)
		(end 193.981324 -130.6195)
		(width 0.089408)
		(layer "In4.Cu")
		(net "H_PM_SYNC_GTL")
	)
	(segment
		(start 259.67182 -89.67089)
		(end 259.639054 -89.67089)
		(width 0.0889)
		(layer "In4.Cu")
		(net "H_PM_SYNC_GTL")
	)
	(segment
		(start 290.667186 -83.050634)
		(end 290.63442 -83.050634)
		(width 0.0889)
		(layer "In4.Cu")
		(net "H_PM_SYNC_GTL")
	)
	(segment
		(start 291.521896 -82.555334)
		(end 291.497766 -82.555334)
		(width 0.0889)
		(layer "In4.Cu")
		(net "H_PM_SYNC_GTL")
	)
	(segment
		(start 245.07063 -81.250536)
		(end 245.037864 -81.250536)
		(width 0.0889)
		(layer "In4.Cu")
		(net "H_PM_SYNC_GTL")
	)
	(segment
		(start 276.06879 -90.480388)
		(end 276.057614 -90.480388)
		(width 0.0889)
		(layer "In4.Cu")
		(net "H_PM_SYNC_GTL")
	)
	(segment
		(start 276.933914 -89.984834)
		(end 276.898354 -89.984834)
		(width 0.0889)
		(layer "In4.Cu")
		(net "H_PM_SYNC_GTL")
	)
	(segment
		(start 296.15003 -75.516486)
		(end 296.154856 -75.525122)
		(width 0.0889)
		(layer "In4.Cu")
		(net "H_PM_SYNC_GTL")
	)
	(segment
		(start 213.298278 -97.593658)
		(end 195.777612 -115.114324)
		(width 0.089408)
		(layer "In4.Cu")
		(net "H_PM_SYNC_GTL")
	)
	(segment
		(start 296.15003 -72.544686)
		(end 296.154856 -72.553322)
		(width 0.0889)
		(layer "In4.Cu")
		(net "H_PM_SYNC_GTL")
	)
	(segment
		(start 283.27223 -87.308436)
		(end 283.268928 -87.314278)
		(width 0.0889)
		(layer "In4.Cu")
		(net "H_PM_SYNC_GTL")
	)
	(segment
		(start 278.64816 -89.984834)
		(end 278.615394 -89.984834)
		(width 0.0889)
		(layer "In4.Cu")
		(net "H_PM_SYNC_GTL")
	)
	(segment
		(start 274.352004 -90.480388)
		(end 274.329652 -90.480388)
		(width 0.0889)
		(layer "In4.Cu")
		(net "H_PM_SYNC_GTL")
	)
	(segment
		(start 270.02105 -90.480388)
		(end 269.829026 -90.672412)
		(width 0.0889)
		(layer "In4.Cu")
		(net "H_PM_SYNC_GTL")
	)
	(segment
		(start 240.784888 -80.75549)
		(end 240.741708 -80.75549)
		(width 0.0889)
		(layer "In4.Cu")
		(net "H_PM_SYNC_GTL")
	)
	(segment
		(start 238.205518 -80.259936)
		(end 238.169958 -80.259936)
		(width 0.0889)
		(layer "In4.Cu")
		(net "H_PM_SYNC_GTL")
	)
	(segment
		(start 285.501334 -86.022434)
		(end 285.483554 -86.022434)
		(width 0.0889)
		(layer "In4.Cu")
		(net "H_PM_SYNC_GTL")
	)
	(segment
		(start 275.71446 -90.286078)
		(end 275.711158 -90.280236)
		(width 0.0889)
		(layer "In4.Cu")
		(net "H_PM_SYNC_GTL")
	)
	(segment
		(start 261.38886 -90.66149)
		(end 261.356094 -90.66149)
		(width 0.0889)
		(layer "In4.Cu")
		(net "H_PM_SYNC_GTL")
	)
	(segment
		(start 296.14368 -75.505818)
		(end 296.15003 -75.516486)
		(width 0.0889)
		(layer "In4.Cu")
		(net "H_PM_SYNC_GTL")
	)
	(segment
		(start 294.42664 -79.468218)
		(end 294.43299 -79.478886)
		(width 0.0889)
		(layer "In4.Cu")
		(net "H_PM_SYNC_GTL")
	)
	(segment
		(start 242.99545 -81.056226)
		(end 242.992148 -81.050384)
		(width 0.0889)
		(layer "In4.Cu")
		(net "H_PM_SYNC_GTL")
	)
	(segment
		(start 281.55519 -88.299036)
		(end 281.551888 -88.304878)
		(width 0.0889)
		(layer "In4.Cu")
		(net "H_PM_SYNC_GTL")
	)
	(segment
		(start 260.52653 -90.165936)
		(end 260.493764 -90.165936)
		(width 0.0889)
		(layer "In4.Cu")
		(net "H_PM_SYNC_GTL")
	)
	(segment
		(start 243.356384 -81.250536)
		(end 243.338604 -81.250536)
		(width 0.0889)
		(layer "In4.Cu")
		(net "H_PM_SYNC_GTL")
	)
	(segment
		(start 277.78583 -90.480388)
		(end 277.763478 -90.480388)
		(width 0.0889)
		(layer "In4.Cu")
		(net "H_PM_SYNC_GTL")
	)
	(segment
		(start 234.771438 -80.259936)
		(end 234.446064 -80.259936)
		(width 0.0889)
		(layer "In4.Cu")
		(net "H_PM_SYNC_GTL")
	)
	(segment
		(start 296.14368 -73.524618)
		(end 296.15003 -73.535286)
		(width 0.0889)
		(layer "In4.Cu")
		(net "H_PM_SYNC_GTL")
	)
	(segment
		(start 195.777612 -115.114324)
		(end 195.777612 -115.236244)
		(width 0.089408)
		(layer "In4.Cu")
		(net "H_PM_SYNC_GTL")
	)
	(segment
		(start 287.233106 -85.031834)
		(end 287.20034 -85.031834)
		(width 0.0889)
		(layer "In4.Cu")
		(net "H_PM_SYNC_GTL")
	)
	(segment
		(start 249.369834 -82.73669)
		(end 249.337068 -82.73669)
		(width 0.0889)
		(layer "In4.Cu")
		(net "H_PM_SYNC_GTL")
	)
	(segment
		(start 245.935754 -80.75549)
		(end 245.892574 -80.75549)
		(width 0.0889)
		(layer "In4.Cu")
		(net "H_PM_SYNC_GTL")
	)
	(segment
		(start 227.96373 -80.141064)
		(end 216.801446 -91.303348)
		(width 0.089408)
		(layer "In4.Cu")
		(net "H_PM_SYNC_GTL")
	)
	(segment
		(start 267.795502 -91.156282)
		(end 267.375894 -91.156282)
		(width 0.0889)
		(layer "In4.Cu")
		(net "H_PM_SYNC_GTL")
	)
	(segment
		(start 256.227326 -89.67089)
		(end 256.204974 -89.67089)
		(width 0.0889)
		(layer "In4.Cu")
		(net "H_PM_SYNC_GTL")
	)
	(segment
		(start 295.818306 -76.116434)
		(end 295.78554 -76.116434)
		(width 0.0889)
		(layer "In4.Cu")
		(net "H_PM_SYNC_GTL")
	)
	(segment
		(start 251.086874 -86.69909)
		(end 251.054108 -86.69909)
		(width 0.0889)
		(layer "In4.Cu")
		(net "H_PM_SYNC_GTL")
	)
	(segment
		(start 282.925774 -87.508588)
		(end 282.904184 -87.508588)
		(width 0.0889)
		(layer "In4.Cu")
		(net "H_PM_SYNC_GTL")
	)
	(segment
		(start 282.067254 -88.003634)
		(end 282.049474 -88.00338)
		(width 0.0889)
		(layer "In4.Cu")
		(net "H_PM_SYNC_GTL")
	)
	(segment
		(start 294.43299 -79.478886)
		(end 294.437816 -79.487522)
		(width 0.0889)
		(layer "In4.Cu")
		(net "H_PM_SYNC_GTL")
	)
	(segment
		(start 296.14368 -74.515218)
		(end 296.15003 -74.525886)
		(width 0.0889)
		(layer "In4.Cu")
		(net "H_PM_SYNC_GTL")
	)
	(segment
		(start 296.14368 -72.534018)
		(end 296.15003 -72.544686)
		(width 0.0889)
		(layer "In4.Cu")
		(net "H_PM_SYNC_GTL")
	)
	(segment
		(start 296.15003 -70.563486)
		(end 296.154856 -70.572122)
		(width 0.0889)
		(layer "In4.Cu")
		(net "H_PM_SYNC_GTL")
	)
	(segment
		(start 288.087816 -84.536788)
		(end 288.05505 -84.536788)
		(width 0.0889)
		(layer "In4.Cu")
		(net "H_PM_SYNC_GTL")
	)
	(segment
		(start 233.091228 -80.141064)
		(end 227.96373 -80.141064)
		(width 0.089408)
		(layer "In4.Cu")
		(net "H_PM_SYNC_GTL")
	)
	(segment
		(start 284.65399 -86.517988)
		(end 284.621224 -86.517988)
		(width 0.0889)
		(layer "In4.Cu")
		(net "H_PM_SYNC_GTL")
	)
	(segment
		(start 248.502678 -82.241136)
		(end 248.474738 -82.241136)
		(width 0.0889)
		(layer "In4.Cu")
		(net "H_PM_SYNC_GTL")
	)
	(segment
		(start 216.624662 -96.369886)
		(end 215.401144 -97.593658)
		(width 0.089408)
		(layer "In4.Cu")
		(net "H_PM_SYNC_GTL")
	)
	(segment
		(start 283.79928 -87.013034)
		(end 283.784294 -87.013034)
		(width 0.0889)
		(layer "In4.Cu")
		(net "H_PM_SYNC_GTL")
	)
	(segment
		(start 195.777612 -115.236244)
		(end 194.4878 -116.526056)
		(width 0.089408)
		(layer "In4.Cu")
		(net "H_PM_SYNC_GTL")
	)
	(segment
		(start 296.15003 -74.525886)
		(end 296.154856 -74.534522)
		(width 0.0889)
		(layer "In4.Cu")
		(net "H_PM_SYNC_GTL")
	)
	(segment
		(start 285.84779 -85.822282)
		(end 285.844488 -85.828124)
		(width 0.0889)
		(layer "In4.Cu")
		(net "H_PM_SYNC_GTL")
	)
	(segment
		(start 292.380416 -82.060034)
		(end 292.34765 -82.060034)
		(width 0.0889)
		(layer "In4.Cu")
		(net "H_PM_SYNC_GTL")
	)
	(segment
		(start 247.652794 -81.74609)
		(end 247.620028 -81.74609)
		(width 0.0889)
		(layer "In4.Cu")
		(net "H_PM_SYNC_GTL")
	)
	(segment
		(start 250.718574 -85.508338)
		(end 250.713748 -85.499702)
		(width 0.0889)
		(layer "In4.Cu")
		(net "H_PM_SYNC_GTL")
	)
	(segment
		(start 250.724924 -84.528406)
		(end 250.718574 -84.517738)
		(width 0.0889)
		(layer "In4.Cu")
		(net "H_PM_SYNC_GTL")
	)
	(segment
		(start 264.822686 -90.66149)
		(end 264.776204 -90.66149)
		(width 0.0889)
		(layer "In4.Cu")
		(net "H_PM_SYNC_GTL")
	)
	(segment
		(start 250.724924 -83.537806)
		(end 250.718574 -83.527138)
		(width 0.0889)
		(layer "In4.Cu")
		(net "H_PM_SYNC_GTL")
	)
	(segment
		(start 194.4878 -116.526056)
		(end 194.4878 -130.113024)
		(width 0.089408)
		(layer "In4.Cu")
		(net "H_PM_SYNC_GTL")
	)
	(segment
		(start 275.217128 -89.984834)
		(end 275.181568 -89.984834)
		(width 0.0889)
		(layer "In4.Cu")
		(net "H_PM_SYNC_GTL")
	)
	(segment
		(start 216.801446 -91.303348)
		(end 216.801446 -95.928942)
		(width 0.089408)
		(layer "In4.Cu")
		(net "H_PM_SYNC_GTL")
	)
	(segment
		(start 262.240776 -91.156536)
		(end 262.210804 -91.156536)
		(width 0.0889)
		(layer "In4.Cu")
		(net "H_PM_SYNC_GTL")
	)
	(segment
		(start 269.829026 -90.672412)
		(end 268.279372 -90.672412)
		(width 0.0889)
		(layer "In4.Cu")
		(net "H_PM_SYNC_GTL")
	)
	(segment
		(start 242.50523 -80.75549)
		(end 242.458748 -80.75549)
		(width 0.0889)
		(layer "In4.Cu")
		(net "H_PM_SYNC_GTL")
	)
	(segment
		(start 293.238936 -80.574388)
		(end 293.20617 -80.574388)
		(width 0.0889)
		(layer "In4.Cu")
		(net "H_PM_SYNC_GTL")
	)
	(segment
		(start 296.14368 -71.543418)
		(end 296.15003 -71.554086)
		(width 0.0889)
		(layer "In4.Cu")
		(net "H_PM_SYNC_GTL")
	)
	(segment
		(start 268.279372 -90.672412)
		(end 267.795502 -91.156282)
		(width 0.0889)
		(layer "In4.Cu")
		(net "H_PM_SYNC_GTL")
	)
	(segment
		(start 265.674602 -91.156536)
		(end 265.64463 -91.156536)
		(width 0.0889)
		(layer "In4.Cu")
		(net "H_PM_SYNC_GTL")
	)
	(segment
		(start 239.919764 -81.250536)
		(end 239.889792 -81.250536)
		(width 0.0889)
		(layer "In4.Cu")
		(net "H_PM_SYNC_GTL")
	)
	(segment
		(start 296.66184 -68.687188)
		(end 296.64025 -68.687188)
		(width 0.0889)
		(layer "In4.Cu")
		(net "H_PM_SYNC_GTL")
	)
	(segment
		(start 250.724924 -85.519006)
		(end 250.718574 -85.508338)
		(width 0.0889)
		(layer "In4.Cu")
		(net "H_PM_SYNC_GTL")
	)
	(segment
		(start 250.718574 -84.517738)
		(end 250.713748 -84.509102)
		(width 0.0889)
		(layer "In4.Cu")
		(net "H_PM_SYNC_GTL")
	)
	(segment
		(start 257.95478 -88.68029)
		(end 257.9116 -88.68029)
		(width 0.0889)
		(layer "In4.Cu")
		(net "H_PM_SYNC_GTL")
	)
	(segment
		(start 297.008296 -68.487036)
		(end 297.004994 -68.492878)
		(width 0.0889)
		(layer "In4.Cu")
		(net "H_PM_SYNC_GTL")
	)
	(segment
		(start 286.370776 -85.527388)
		(end 286.334708 -85.527388)
		(width 0.0889)
		(layer "In4.Cu")
		(net "H_PM_SYNC_GTL")
	)
	(segment
		(start 253.658624 -88.184736)
		(end 253.625858 -88.184736)
		(width 0.0889)
		(layer "In4.Cu")
		(net "H_PM_SYNC_GTL")
	)
	(segment
		(start 296.954702 -67.465448)
		(end 296.978578 -67.554348)
		(width 0.0889)
		(layer "In4.Cu")
		(net "H_PM_SYNC_GTL")
	)
	(segment
		(start 264.289286 -90.956384)
		(end 264.285984 -90.962226)
		(width 0.0889)
		(layer "In4.Cu")
		(net "H_PM_SYNC_GTL")
	)
	(segment
		(start 254.155956 -88.48598)
		(end 254.152654 -88.480138)
		(width 0.0889)
		(layer "In4.Cu")
		(net "H_PM_SYNC_GTL")
	)
	(segment
		(start 280.3652 -88.994234)
		(end 280.332434 -88.994234)
		(width 0.0889)
		(layer "In4.Cu")
		(net "H_PM_SYNC_GTL")
	)
	(segment
		(start 296.66184 -67.296538)
		(end 296.954702 -67.465448)
		(width 0.0889)
		(layer "In4.Cu")
		(net "H_PM_SYNC_GTL")
	)
	(segment
		(start 252.803914 -87.68969)
		(end 252.771148 -87.68969)
		(width 0.0889)
		(layer "In4.Cu")
		(net "H_PM_SYNC_GTL")
	)
	(segment
		(start 239.067848 -80.75549)
		(end 239.035082 -80.75549)
		(width 0.0889)
		(layer "In4.Cu")
		(net "H_PM_SYNC_GTL")
	)
	(segment
		(start 295.296336 -77.3938)
		(end 295.29151 -77.402436)
		(width 0.0889)
		(layer "In4.Cu")
		(net "H_PM_SYNC_GTL")
	)
	(segment
		(start 263.94283 -91.156536)
		(end 263.927844 -91.156536)
		(width 0.0889)
		(layer "In4.Cu")
		(net "H_PM_SYNC_GTL")
	)
	(segment
		(start 233.653584 -80.70342)
		(end 233.091228 -80.141064)
		(width 0.089408)
		(layer "In4.Cu")
		(net "H_PM_SYNC_GTL")
	)
	(segment
		(start 289.804856 -83.546188)
		(end 289.77209 -83.546188)
		(width 0.0889)
		(layer "In4.Cu")
		(net "H_PM_SYNC_GTL")
	)
	(segment
		(start 246.790464 -81.250536)
		(end 246.757698 -81.250536)
		(width 0.0889)
		(layer "In4.Cu")
		(net "H_PM_SYNC_GTL")
	)
	(segment
		(start 266.539726 -90.66149)
		(end 266.496546 -90.66149)
		(width 0.0889)
		(layer "In4.Cu")
		(net "H_PM_SYNC_GTL")
	)
	(segment
		(start 234.446064 -80.259936)
		(end 234.00258 -80.70342)
		(width 0.0889)
		(layer "In4.Cu")
		(net "H_PM_SYNC_GTL")
	)
	(segment
		(start 273.500088 -89.984834)
		(end 273.464528 -89.984834)
		(width 0.0889)
		(layer "In4.Cu")
		(net "H_PM_SYNC_GTL")
	)
	(segment
		(start 216.801446 -95.928942)
		(end 216.7509 -96.05518)
		(width 0.089408)
		(layer "In4.Cu")
		(net "H_PM_SYNC_GTL")
	)
	(segment
		(start 234.00258 -80.70342)
		(end 233.737404 -80.70342)
		(width 0.0889)
		(layer "In4.Cu")
		(net "H_PM_SYNC_GTL")
	)
	(segment
		(start 216.7509 -96.05518)
		(end 216.624662 -96.369886)
		(width 0.089408)
		(layer "In4.Cu")
		(net "H_PM_SYNC_GTL")
	)
	(segment
		(start 241.636804 -81.250536)
		(end 241.606832 -81.250536)
		(width 0.0889)
		(layer "In4.Cu")
		(net "H_PM_SYNC_GTL")
	)
	(segment
		(start 282.08224 -88.003634)
		(end 282.067254 -88.003634)
		(width 0.0889)
		(layer "In4.Cu")
		(net "H_PM_SYNC_GTL")
	)
	(segment
		(start 258.80949 -89.175336)
		(end 258.776724 -89.175336)
		(width 0.0889)
		(layer "In4.Cu")
		(net "H_PM_SYNC_GTL")
	)
	(segment
		(start 255.37541 -89.175336)
		(end 255.342644 -89.175336)
		(width 0.0889)
		(layer "In4.Cu")
		(net "H_PM_SYNC_GTL")
	)
	(segment
		(start 254.5207 -88.68029)
		(end 254.49911 -88.68029)
		(width 0.0889)
		(layer "In4.Cu")
		(net "H_PM_SYNC_GTL")
	)
	(segment
		(start 250.224544 -83.231736)
		(end 250.18873 -83.231736)
		(width 0.0889)
		(layer "In4.Cu")
		(net "H_PM_SYNC_GTL")
	)
	(segment
		(start 296.15003 -71.554086)
		(end 296.154856 -71.562722)
		(width 0.0889)
		(layer "In4.Cu")
		(net "H_PM_SYNC_GTL")
	)
	(segment
		(start 294.101266 -80.078834)
		(end 294.0685 -80.078834)
		(width 0.0889)
		(layer "In4.Cu")
		(net "H_PM_SYNC_GTL")
	)
	(segment
		(start 288.950146 -84.041234)
		(end 288.91738 -84.041234)
		(width 0.0889)
		(layer "In4.Cu")
		(net "H_PM_SYNC_GTL")
	)
	(segment
		(start 279.50287 -89.489788)
		(end 279.470104 -89.489788)
		(width 0.0889)
		(layer "In4.Cu")
		(net "H_PM_SYNC_GTL")
	)
	(segment
		(start 294.955976 -77.602588)
		(end 294.92321 -77.602588)
		(width 0.0889)
		(layer "In4.Cu")
		(net "H_PM_SYNC_GTL")
	)
	(segment
		(start 257.089656 -89.175336)
		(end 257.05689 -89.175336)
		(width 0.0889)
		(layer "In4.Cu")
		(net "H_PM_SYNC_GTL")
	)
	(segment
		(start 250.718574 -86.498938)
		(end 250.713748 -86.490302)
		(width 0.0889)
		(layer "In4.Cu")
		(net "H_PM_SYNC_GTL")
	)
	(arc
		(start 274.687538 -90.280236)
		(mid 274.545855 -90.42404)
		(end 274.352004 -90.480388)
		(width 0.0889)
		(layer "In4.Cu")
		(net "H_PM_SYNC_GTL")
	)
	(arc
		(start 250.718574 -85.108288)
		(mid 250.797796 -84.81917)
		(end 250.724924 -84.528406)
		(width 0.0889)
		(layer "In4.Cu")
		(net "H_PM_SYNC_GTL")
	)
	(arc
		(start 245.402354 -81.050638)
		(mid 245.262275 -81.193374)
		(end 245.07063 -81.250536)
		(width 0.0889)
		(layer "In4.Cu")
		(net "H_PM_SYNC_GTL")
	)
	(arc
		(start 261.02056 -90.461338)
		(mid 260.811952 -90.249406)
		(end 260.52653 -90.165936)
		(width 0.0889)
		(layer "In4.Cu")
		(net "H_PM_SYNC_GTL")
	)
	(arc
		(start 296.15003 -73.935336)
		(mid 296.070808 -74.224454)
		(end 296.14368 -74.515218)
		(width 0.0889)
		(layer "In4.Cu")
		(net "H_PM_SYNC_GTL")
	)
	(arc
		(start 239.558068 -81.050638)
		(mid 239.351064 -80.839774)
		(end 239.067848 -80.75549)
		(width 0.0889)
		(layer "In4.Cu")
		(net "H_PM_SYNC_GTL")
	)
	(arc
		(start 288.05505 -84.536788)
		(mid 287.771833 -84.621069)
		(end 287.56483 -84.831936)
		(width 0.0889)
		(layer "In4.Cu")
		(net "H_PM_SYNC_GTL")
	)
	(arc
		(start 296.154856 -72.553322)
		(mid 296.203611 -72.749674)
		(end 296.15003 -72.944736)
		(width 0.0889)
		(layer "In4.Cu")
		(net "H_PM_SYNC_GTL")
	)
	(arc
		(start 276.404324 -90.280236)
		(mid 276.262641 -90.42404)
		(end 276.06879 -90.480388)
		(width 0.0889)
		(layer "In4.Cu")
		(net "H_PM_SYNC_GTL")
	)
	(arc
		(start 266.496546 -90.66149)
		(mid 266.213329 -90.745771)
		(end 266.006326 -90.956638)
		(width 0.0889)
		(layer "In4.Cu")
		(net "H_PM_SYNC_GTL")
	)
	(arc
		(start 265.64463 -91.156536)
		(mid 265.452988 -91.09937)
		(end 265.312906 -90.956638)
		(width 0.0889)
		(layer "In4.Cu")
		(net "H_PM_SYNC_GTL")
	)
	(arc
		(start 296.15003 -74.925936)
		(mid 296.070808 -75.215054)
		(end 296.14368 -75.505818)
		(width 0.0889)
		(layer "In4.Cu")
		(net "H_PM_SYNC_GTL")
	)
	(arc
		(start 256.56286 -89.470738)
		(mid 256.421177 -89.614542)
		(end 256.227326 -89.67089)
		(width 0.0889)
		(layer "In4.Cu")
		(net "H_PM_SYNC_GTL")
	)
	(arc
		(start 264.285984 -90.962226)
		(mid 264.140018 -91.104625)
		(end 263.94283 -91.156536)
		(width 0.0889)
		(layer "In4.Cu")
		(net "H_PM_SYNC_GTL")
	)
	(arc
		(start 249.001534 -82.536538)
		(mid 248.790821 -82.323459)
		(end 248.502678 -82.241136)
		(width 0.0889)
		(layer "In4.Cu")
		(net "H_PM_SYNC_GTL")
	)
	(arc
		(start 290.99891 -82.850736)
		(mid 290.858831 -82.993472)
		(end 290.667186 -83.050634)
		(width 0.0889)
		(layer "In4.Cu")
		(net "H_PM_SYNC_GTL")
	)
	(arc
		(start 259.639054 -89.67089)
		(mid 259.445204 -89.61454)
		(end 259.30352 -89.470738)
		(width 0.0889)
		(layer "In4.Cu")
		(net "H_PM_SYNC_GTL")
	)
	(arc
		(start 247.620028 -81.74609)
		(mid 247.426178 -81.68974)
		(end 247.284494 -81.545938)
		(width 0.0889)
		(layer "In4.Cu")
		(net "H_PM_SYNC_GTL")
	)
	(arc
		(start 295.28516 -76.422504)
		(mid 295.212362 -76.713267)
		(end 295.29151 -77.002386)
		(width 0.0889)
		(layer "In4.Cu")
		(net "H_PM_SYNC_GTL")
	)
	(arc
		(start 295.78554 -76.116434)
		(mid 295.500116 -76.199901)
		(end 295.29151 -76.411836)
		(width 0.0889)
		(layer "In4.Cu")
		(net "H_PM_SYNC_GTL")
	)
	(arc
		(start 294.43299 -78.48854)
		(mid 294.486489 -78.688438)
		(end 294.43299 -78.888336)
		(width 0.0889)
		(layer "In4.Cu")
		(net "H_PM_SYNC_GTL")
	)
	(arc
		(start 254.152654 -88.480138)
		(mid 253.944046 -88.268206)
		(end 253.658624 -88.184736)
		(width 0.0889)
		(layer "In4.Cu")
		(net "H_PM_SYNC_GTL")
	)
	(arc
		(start 297.008296 -68.08724)
		(mid 297.061829 -68.287138)
		(end 297.008296 -68.487036)
		(width 0.0889)
		(layer "In4.Cu")
		(net "H_PM_SYNC_GTL")
	)
	(arc
		(start 260.493764 -90.165936)
		(mid 260.302122 -90.10877)
		(end 260.16204 -89.966038)
		(width 0.0889)
		(layer "In4.Cu")
		(net "H_PM_SYNC_GTL")
	)
	(arc
		(start 254.49911 -88.68029)
		(mid 254.301949 -88.628331)
		(end 254.155956 -88.48598)
		(width 0.0889)
		(layer "In4.Cu")
		(net "H_PM_SYNC_GTL")
	)
	(arc
		(start 292.71595 -81.859882)
		(mid 292.574267 -82.003686)
		(end 292.380416 -82.060034)
		(width 0.0889)
		(layer "In4.Cu")
		(net "H_PM_SYNC_GTL")
	)
	(arc
		(start 286.70631 -85.327236)
		(mid 286.564627 -85.47104)
		(end 286.370776 -85.527388)
		(width 0.0889)
		(layer "In4.Cu")
		(net "H_PM_SYNC_GTL")
	)
	(arc
		(start 287.56483 -84.831936)
		(mid 287.424751 -84.974672)
		(end 287.233106 -85.031834)
		(width 0.0889)
		(layer "In4.Cu")
		(net "H_PM_SYNC_GTL")
	)
	(arc
		(start 296.15003 -69.572886)
		(mid 296.203529 -69.772784)
		(end 296.15003 -69.972682)
		(width 0.0889)
		(layer "In4.Cu")
		(net "H_PM_SYNC_GTL")
	)
	(arc
		(start 249.337068 -82.73669)
		(mid 249.143218 -82.68034)
		(end 249.001534 -82.536538)
		(width 0.0889)
		(layer "In4.Cu")
		(net "H_PM_SYNC_GTL")
	)
	(arc
		(start 294.92321 -77.602588)
		(mid 294.639993 -77.686869)
		(end 294.43299 -77.897736)
		(width 0.0889)
		(layer "In4.Cu")
		(net "H_PM_SYNC_GTL")
	)
	(arc
		(start 294.43299 -79.878936)
		(mid 294.292911 -80.021672)
		(end 294.101266 -80.078834)
		(width 0.0889)
		(layer "In4.Cu")
		(net "H_PM_SYNC_GTL")
	)
	(arc
		(start 295.29151 -77.002386)
		(mid 295.34498 -77.197449)
		(end 295.296336 -77.3938)
		(width 0.0889)
		(layer "In4.Cu")
		(net "H_PM_SYNC_GTL")
	)
	(arc
		(start 285.483554 -86.022434)
		(mid 285.19813 -86.105901)
		(end 284.989524 -86.317836)
		(width 0.0889)
		(layer "In4.Cu")
		(net "H_PM_SYNC_GTL")
	)
	(arc
		(start 296.15003 -71.954136)
		(mid 296.070808 -72.243254)
		(end 296.14368 -72.534018)
		(width 0.0889)
		(layer "In4.Cu")
		(net "H_PM_SYNC_GTL")
	)
	(arc
		(start 296.15003 -75.916536)
		(mid 296.009951 -76.059272)
		(end 295.818306 -76.116434)
		(width 0.0889)
		(layer "In4.Cu")
		(net "H_PM_SYNC_GTL")
	)
	(arc
		(start 250.713748 -85.499702)
		(mid 250.664993 -85.30335)
		(end 250.718574 -85.108288)
		(width 0.0889)
		(layer "In4.Cu")
		(net "H_PM_SYNC_GTL")
	)
	(arc
		(start 264.776204 -90.66149)
		(mid 264.494904 -90.746456)
		(end 264.289286 -90.956384)
		(width 0.0889)
		(layer "In4.Cu")
		(net "H_PM_SYNC_GTL")
	)
	(arc
		(start 248.143014 -82.041238)
		(mid 247.93601 -81.830374)
		(end 247.652794 -81.74609)
		(width 0.0889)
		(layer "In4.Cu")
		(net "H_PM_SYNC_GTL")
	)
	(arc
		(start 243.850414 -81.545938)
		(mid 243.641806 -81.334006)
		(end 243.356384 -81.250536)
		(width 0.0889)
		(layer "In4.Cu")
		(net "H_PM_SYNC_GTL")
	)
	(arc
		(start 283.766514 -87.01278)
		(mid 283.480942 -87.096336)
		(end 283.27223 -87.308436)
		(width 0.0889)
		(layer "In4.Cu")
		(net "H_PM_SYNC_GTL")
	)
	(arc
		(start 255.342644 -89.175336)
		(mid 255.151002 -89.11817)
		(end 255.01092 -88.975438)
		(width 0.0889)
		(layer "In4.Cu")
		(net "H_PM_SYNC_GTL")
	)
	(arc
		(start 246.425974 -81.050638)
		(mid 246.21897 -80.839774)
		(end 245.935754 -80.75549)
		(width 0.0889)
		(layer "In4.Cu")
		(net "H_PM_SYNC_GTL")
	)
	(arc
		(start 296.154856 -70.572122)
		(mid 296.203611 -70.768474)
		(end 296.15003 -70.963536)
		(width 0.0889)
		(layer "In4.Cu")
		(net "H_PM_SYNC_GTL")
	)
	(arc
		(start 259.30352 -89.470738)
		(mid 259.094912 -89.258806)
		(end 258.80949 -89.175336)
		(width 0.0889)
		(layer "In4.Cu")
		(net "H_PM_SYNC_GTL")
	)
	(arc
		(start 296.64025 -68.687188)
		(mid 296.357033 -68.771469)
		(end 296.15003 -68.982336)
		(width 0.0889)
		(layer "In4.Cu")
		(net "H_PM_SYNC_GTL")
	)
	(arc
		(start 296.15003 -70.963536)
		(mid 296.070808 -71.252654)
		(end 296.14368 -71.543418)
		(width 0.0889)
		(layer "In4.Cu")
		(net "H_PM_SYNC_GTL")
	)
	(arc
		(start 263.927844 -91.156536)
		(mid 263.736202 -91.09937)
		(end 263.59612 -90.956638)
		(width 0.0889)
		(layer "In4.Cu")
		(net "H_PM_SYNC_GTL")
	)
	(arc
		(start 296.154856 -73.543922)
		(mid 296.203611 -73.740274)
		(end 296.15003 -73.935336)
		(width 0.0889)
		(layer "In4.Cu")
		(net "H_PM_SYNC_GTL")
	)
	(arc
		(start 258.445 -88.975438)
		(mid 258.237996 -88.764574)
		(end 257.95478 -88.68029)
		(width 0.0889)
		(layer "In4.Cu")
		(net "H_PM_SYNC_GTL")
	)
	(arc
		(start 276.057614 -90.480388)
		(mid 275.860453 -90.428429)
		(end 275.71446 -90.286078)
		(width 0.0889)
		(layer "In4.Cu")
		(net "H_PM_SYNC_GTL")
	)
	(arc
		(start 284.621224 -86.517988)
		(mid 284.338007 -86.602269)
		(end 284.131004 -86.813136)
		(width 0.0889)
		(layer "In4.Cu")
		(net "H_PM_SYNC_GTL")
	)
	(arc
		(start 239.889792 -81.250536)
		(mid 239.69815 -81.19337)
		(end 239.558068 -81.050638)
		(width 0.0889)
		(layer "In4.Cu")
		(net "H_PM_SYNC_GTL")
	)
	(arc
		(start 284.989524 -86.317836)
		(mid 284.847841 -86.46164)
		(end 284.65399 -86.517988)
		(width 0.0889)
		(layer "In4.Cu")
		(net "H_PM_SYNC_GTL")
	)
	(arc
		(start 282.904184 -87.508588)
		(mid 282.620967 -87.592869)
		(end 282.413964 -87.803736)
		(width 0.0889)
		(layer "In4.Cu")
		(net "H_PM_SYNC_GTL")
	)
	(arc
		(start 294.43299 -77.897736)
		(mid 294.353859 -78.193138)
		(end 294.43299 -78.48854)
		(width 0.0889)
		(layer "In4.Cu")
		(net "H_PM_SYNC_GTL")
	)
	(arc
		(start 257.9116 -88.68029)
		(mid 257.628383 -88.764571)
		(end 257.42138 -88.975438)
		(width 0.0889)
		(layer "In4.Cu")
		(net "H_PM_SYNC_GTL")
	)
	(arc
		(start 253.625858 -88.184736)
		(mid 253.434216 -88.12757)
		(end 253.294134 -87.984838)
		(width 0.0889)
		(layer "In4.Cu")
		(net "H_PM_SYNC_GTL")
	)
	(arc
		(start 251.577094 -86.994238)
		(mid 251.37009 -86.783374)
		(end 251.086874 -86.69909)
		(width 0.0889)
		(layer "In4.Cu")
		(net "H_PM_SYNC_GTL")
	)
	(arc
		(start 242.458748 -80.75549)
		(mid 242.175531 -80.839771)
		(end 241.968528 -81.050638)
		(width 0.0889)
		(layer "In4.Cu")
		(net "H_PM_SYNC_GTL")
	)
	(arc
		(start 280.332434 -88.994234)
		(mid 280.04701 -89.077701)
		(end 279.838404 -89.289636)
		(width 0.0889)
		(layer "In4.Cu")
		(net "H_PM_SYNC_GTL")
	)
	(arc
		(start 277.427944 -90.280236)
		(mid 277.219336 -90.068304)
		(end 276.933914 -89.984834)
		(width 0.0889)
		(layer "In4.Cu")
		(net "H_PM_SYNC_GTL")
	)
	(arc
		(start 255.86944 -89.470738)
		(mid 255.660832 -89.258806)
		(end 255.37541 -89.175336)
		(width 0.0889)
		(layer "In4.Cu")
		(net "H_PM_SYNC_GTL")
	)
	(arc
		(start 294.43299 -78.888336)
		(mid 294.353768 -79.177454)
		(end 294.42664 -79.468218)
		(width 0.0889)
		(layer "In4.Cu")
		(net "H_PM_SYNC_GTL")
	)
	(arc
		(start 235.958888 -80.555338)
		(mid 235.612178 -80.755649)
		(end 235.265468 -80.555338)
		(width 0.0889)
		(layer "In4.Cu")
		(net "H_PM_SYNC_GTL")
	)
	(arc
		(start 295.29151 -77.402436)
		(mid 295.149827 -77.54624)
		(end 294.955976 -77.602588)
		(width 0.0889)
		(layer "In4.Cu")
		(net "H_PM_SYNC_GTL")
	)
	(arc
		(start 296.15003 -69.972682)
		(mid 296.070899 -70.268084)
		(end 296.15003 -70.563486)
		(width 0.0889)
		(layer "In4.Cu")
		(net "H_PM_SYNC_GTL")
	)
	(arc
		(start 290.63442 -83.050634)
		(mid 290.348996 -83.134101)
		(end 290.14039 -83.346036)
		(width 0.0889)
		(layer "In4.Cu")
		(net "H_PM_SYNC_GTL")
	)
	(arc
		(start 285.844488 -85.828124)
		(mid 285.698522 -85.970523)
		(end 285.501334 -86.022434)
		(width 0.0889)
		(layer "In4.Cu")
		(net "H_PM_SYNC_GTL")
	)
	(arc
		(start 296.978578 -67.554348)
		(mid 296.929916 -67.824326)
		(end 297.008296 -68.08724)
		(width 0.0889)
		(layer "In4.Cu")
		(net "H_PM_SYNC_GTL")
	)
	(arc
		(start 250.718574 -86.098888)
		(mid 250.797796 -85.80977)
		(end 250.724924 -85.519006)
		(width 0.0889)
		(layer "In4.Cu")
		(net "H_PM_SYNC_GTL")
	)
	(arc
		(start 276.898354 -89.984834)
		(mid 276.61293 -90.068301)
		(end 276.404324 -90.280236)
		(width 0.0889)
		(layer "In4.Cu")
		(net "H_PM_SYNC_GTL")
	)
	(arc
		(start 296.15003 -68.982336)
		(mid 296.070808 -69.271454)
		(end 296.14368 -69.562218)
		(width 0.0889)
		(layer "In4.Cu")
		(net "H_PM_SYNC_GTL")
	)
	(arc
		(start 266.006326 -90.956638)
		(mid 265.866247 -91.099374)
		(end 265.674602 -91.156536)
		(width 0.0889)
		(layer "In4.Cu")
		(net "H_PM_SYNC_GTL")
	)
	(arc
		(start 286.334708 -85.527388)
		(mid 286.053408 -85.612354)
		(end 285.84779 -85.822282)
		(width 0.0889)
		(layer "In4.Cu")
		(net "H_PM_SYNC_GTL")
	)
	(arc
		(start 245.892574 -80.75549)
		(mid 245.609357 -80.839771)
		(end 245.402354 -81.050638)
		(width 0.0889)
		(layer "In4.Cu")
		(net "H_PM_SYNC_GTL")
	)
	(arc
		(start 275.181568 -89.984834)
		(mid 274.896144 -90.068301)
		(end 274.687538 -90.280236)
		(width 0.0889)
		(layer "In4.Cu")
		(net "H_PM_SYNC_GTL")
	)
	(arc
		(start 247.284494 -81.545938)
		(mid 247.075886 -81.334006)
		(end 246.790464 -81.250536)
		(width 0.0889)
		(layer "In4.Cu")
		(net "H_PM_SYNC_GTL")
	)
	(arc
		(start 250.713748 -86.490302)
		(mid 250.664993 -86.29395)
		(end 250.718574 -86.098888)
		(width 0.0889)
		(layer "In4.Cu")
		(net "H_PM_SYNC_GTL")
	)
	(arc
		(start 256.204974 -89.67089)
		(mid 256.011124 -89.61454)
		(end 255.86944 -89.470738)
		(width 0.0889)
		(layer "In4.Cu")
		(net "H_PM_SYNC_GTL")
	)
	(arc
		(start 267.029946 -90.956638)
		(mid 266.822942 -90.745774)
		(end 266.539726 -90.66149)
		(width 0.0889)
		(layer "In4.Cu")
		(net "H_PM_SYNC_GTL")
	)
	(arc
		(start 237.675928 -80.555338)
		(mid 237.329218 -80.755649)
		(end 236.982508 -80.555338)
		(width 0.0889)
		(layer "In4.Cu")
		(net "H_PM_SYNC_GTL")
	)
	(arc
		(start 250.718574 -83.527138)
		(mid 250.509966 -83.315206)
		(end 250.224544 -83.231736)
		(width 0.0889)
		(layer "In4.Cu")
		(net "H_PM_SYNC_GTL")
	)
	(arc
		(start 241.968528 -81.050638)
		(mid 241.828449 -81.193374)
		(end 241.636804 -81.250536)
		(width 0.0889)
		(layer "In4.Cu")
		(net "H_PM_SYNC_GTL")
	)
	(arc
		(start 294.437816 -79.487522)
		(mid 294.486571 -79.683874)
		(end 294.43299 -79.878936)
		(width 0.0889)
		(layer "In4.Cu")
		(net "H_PM_SYNC_GTL")
	)
	(arc
		(start 291.85743 -82.355182)
		(mid 291.715747 -82.498986)
		(end 291.521896 -82.555334)
		(width 0.0889)
		(layer "In4.Cu")
		(net "H_PM_SYNC_GTL")
	)
	(arc
		(start 260.16204 -89.966038)
		(mid 259.955036 -89.755174)
		(end 259.67182 -89.67089)
		(width 0.0889)
		(layer "In4.Cu")
		(net "H_PM_SYNC_GTL")
	)
	(arc
		(start 246.757698 -81.250536)
		(mid 246.566056 -81.19337)
		(end 246.425974 -81.050638)
		(width 0.0889)
		(layer "In4.Cu")
		(net "H_PM_SYNC_GTL")
	)
	(arc
		(start 289.28187 -83.841336)
		(mid 289.141791 -83.984072)
		(end 288.950146 -84.041234)
		(width 0.0889)
		(layer "In4.Cu")
		(net "H_PM_SYNC_GTL")
	)
	(arc
		(start 267.375894 -91.156282)
		(mid 267.176185 -91.102789)
		(end 267.029946 -90.956638)
		(width 0.0889)
		(layer "In4.Cu")
		(net "H_PM_SYNC_GTL")
	)
	(arc
		(start 252.771148 -87.68969)
		(mid 252.577298 -87.63334)
		(end 252.435614 -87.489538)
		(width 0.0889)
		(layer "In4.Cu")
		(net "H_PM_SYNC_GTL")
	)
	(arc
		(start 244.543834 -81.545938)
		(mid 244.197124 -81.746249)
		(end 243.850414 -81.545938)
		(width 0.0889)
		(layer "In4.Cu")
		(net "H_PM_SYNC_GTL")
	)
	(arc
		(start 261.87908 -90.956638)
		(mid 261.672076 -90.745774)
		(end 261.38886 -90.66149)
		(width 0.0889)
		(layer "In4.Cu")
		(net "H_PM_SYNC_GTL")
	)
	(arc
		(start 251.054108 -86.69909)
		(mid 250.860258 -86.64274)
		(end 250.718574 -86.498938)
		(width 0.0889)
		(layer "In4.Cu")
		(net "H_PM_SYNC_GTL")
	)
	(arc
		(start 296.154856 -75.525122)
		(mid 296.203611 -75.721474)
		(end 296.15003 -75.916536)
		(width 0.0889)
		(layer "In4.Cu")
		(net "H_PM_SYNC_GTL")
	)
	(arc
		(start 283.268928 -87.314278)
		(mid 283.122962 -87.456677)
		(end 282.925774 -87.508588)
		(width 0.0889)
		(layer "In4.Cu")
		(net "H_PM_SYNC_GTL")
	)
	(arc
		(start 287.20034 -85.031834)
		(mid 286.914916 -85.115301)
		(end 286.70631 -85.327236)
		(width 0.0889)
		(layer "In4.Cu")
		(net "H_PM_SYNC_GTL")
	)
	(arc
		(start 235.265468 -80.555338)
		(mid 235.05686 -80.343406)
		(end 234.771438 -80.259936)
		(width 0.0889)
		(layer "In4.Cu")
		(net "H_PM_SYNC_GTL")
	)
	(arc
		(start 292.34765 -82.060034)
		(mid 292.064433 -82.144315)
		(end 291.85743 -82.355182)
		(width 0.0889)
		(layer "In4.Cu")
		(net "H_PM_SYNC_GTL")
	)
	(arc
		(start 292.71595 -81.460086)
		(mid 292.769449 -81.659984)
		(end 292.71595 -81.859882)
		(width 0.0889)
		(layer "In4.Cu")
		(net "H_PM_SYNC_GTL")
	)
	(arc
		(start 282.413964 -87.803736)
		(mid 282.273885 -87.946472)
		(end 282.08224 -88.003634)
		(width 0.0889)
		(layer "In4.Cu")
		(net "H_PM_SYNC_GTL")
	)
	(arc
		(start 236.982508 -80.555338)
		(mid 236.7739 -80.343406)
		(end 236.488478 -80.259936)
		(width 0.0889)
		(layer "In4.Cu")
		(net "H_PM_SYNC_GTL")
	)
	(arc
		(start 277.763478 -90.480388)
		(mid 277.569628 -90.424038)
		(end 277.427944 -90.280236)
		(width 0.0889)
		(layer "In4.Cu")
		(net "H_PM_SYNC_GTL")
	)
	(arc
		(start 262.210804 -91.156536)
		(mid 262.019162 -91.09937)
		(end 261.87908 -90.956638)
		(width 0.0889)
		(layer "In4.Cu")
		(net "H_PM_SYNC_GTL")
	)
	(arc
		(start 278.121364 -90.280236)
		(mid 277.979681 -90.42404)
		(end 277.78583 -90.480388)
		(width 0.0889)
		(layer "In4.Cu")
		(net "H_PM_SYNC_GTL")
	)
	(arc
		(start 240.251488 -81.050638)
		(mid 240.111409 -81.193374)
		(end 239.919764 -81.250536)
		(width 0.0889)
		(layer "In4.Cu")
		(net "H_PM_SYNC_GTL")
	)
	(arc
		(start 250.713748 -84.509102)
		(mid 250.664993 -84.31275)
		(end 250.718574 -84.117688)
		(width 0.0889)
		(layer "In4.Cu")
		(net "H_PM_SYNC_GTL")
	)
	(arc
		(start 257.42138 -88.975438)
		(mid 257.281301 -89.118174)
		(end 257.089656 -89.175336)
		(width 0.0889)
		(layer "In4.Cu")
		(net "H_PM_SYNC_GTL")
	)
	(arc
		(start 275.711158 -90.280236)
		(mid 275.50255 -90.068304)
		(end 275.217128 -89.984834)
		(width 0.0889)
		(layer "In4.Cu")
		(net "H_PM_SYNC_GTL")
	)
	(arc
		(start 252.435614 -87.489538)
		(mid 252.227006 -87.277606)
		(end 251.941584 -87.194136)
		(width 0.0889)
		(layer "In4.Cu")
		(net "H_PM_SYNC_GTL")
	)
	(arc
		(start 242.992148 -81.050384)
		(mid 242.786527 -80.840461)
		(end 242.50523 -80.75549)
		(width 0.0889)
		(layer "In4.Cu")
		(net "H_PM_SYNC_GTL")
	)
	(arc
		(start 279.470104 -89.489788)
		(mid 279.186887 -89.574069)
		(end 278.979884 -89.784936)
		(width 0.0889)
		(layer "In4.Cu")
		(net "H_PM_SYNC_GTL")
	)
	(arc
		(start 263.59612 -90.956638)
		(mid 263.08431 -90.661099)
		(end 262.5725 -90.956638)
		(width 0.0889)
		(layer "In4.Cu")
		(net "H_PM_SYNC_GTL")
	)
	(arc
		(start 273.464528 -89.984834)
		(mid 273.179104 -90.068301)
		(end 272.970498 -90.280236)
		(width 0.0889)
		(layer "In4.Cu")
		(net "H_PM_SYNC_GTL")
	)
	(arc
		(start 262.5725 -90.956638)
		(mid 262.432421 -91.099374)
		(end 262.240776 -91.156536)
		(width 0.0889)
		(layer "In4.Cu")
		(net "H_PM_SYNC_GTL")
	)
	(arc
		(start 257.05689 -89.175336)
		(mid 256.771466 -89.258803)
		(end 256.56286 -89.470738)
		(width 0.0889)
		(layer "In4.Cu")
		(net "H_PM_SYNC_GTL")
	)
	(arc
		(start 284.131004 -86.813136)
		(mid 283.990925 -86.955872)
		(end 283.79928 -87.013034)
		(width 0.0889)
		(layer "In4.Cu")
		(net "H_PM_SYNC_GTL")
	)
	(arc
		(start 296.15003 -72.944736)
		(mid 296.070808 -73.233854)
		(end 296.14368 -73.524618)
		(width 0.0889)
		(layer "In4.Cu")
		(net "H_PM_SYNC_GTL")
	)
	(arc
		(start 241.275108 -81.050638)
		(mid 241.068104 -80.839774)
		(end 240.784888 -80.75549)
		(width 0.0889)
		(layer "In4.Cu")
		(net "H_PM_SYNC_GTL")
	)
	(arc
		(start 293.57447 -80.374236)
		(mid 293.432787 -80.51804)
		(end 293.238936 -80.574388)
		(width 0.0889)
		(layer "In4.Cu")
		(net "H_PM_SYNC_GTL")
	)
	(arc
		(start 250.718574 -84.117688)
		(mid 250.797796 -83.82857)
		(end 250.724924 -83.537806)
		(width 0.0889)
		(layer "In4.Cu")
		(net "H_PM_SYNC_GTL")
	)
	(arc
		(start 279.838404 -89.289636)
		(mid 279.696721 -89.43344)
		(end 279.50287 -89.489788)
		(width 0.0889)
		(layer "In4.Cu")
		(net "H_PM_SYNC_GTL")
	)
	(arc
		(start 290.14039 -83.346036)
		(mid 289.998707 -83.48984)
		(end 289.804856 -83.546188)
		(width 0.0889)
		(layer "In4.Cu")
		(net "H_PM_SYNC_GTL")
	)
	(arc
		(start 288.42335 -84.336636)
		(mid 288.281667 -84.48044)
		(end 288.087816 -84.536788)
		(width 0.0889)
		(layer "In4.Cu")
		(net "H_PM_SYNC_GTL")
	)
	(arc
		(start 248.474738 -82.241136)
		(mid 248.283096 -82.18397)
		(end 248.143014 -82.041238)
		(width 0.0889)
		(layer "In4.Cu")
		(net "H_PM_SYNC_GTL")
	)
	(arc
		(start 296.154856 -71.562722)
		(mid 296.203611 -71.759074)
		(end 296.15003 -71.954136)
		(width 0.0889)
		(layer "In4.Cu")
		(net "H_PM_SYNC_GTL")
	)
	(arc
		(start 255.01092 -88.975438)
		(mid 254.803916 -88.764574)
		(end 254.5207 -88.68029)
		(width 0.0889)
		(layer "In4.Cu")
		(net "H_PM_SYNC_GTL")
	)
	(arc
		(start 238.699548 -80.555338)
		(mid 238.49094 -80.343406)
		(end 238.205518 -80.259936)
		(width 0.0889)
		(layer "In4.Cu")
		(net "H_PM_SYNC_GTL")
	)
	(arc
		(start 273.994118 -90.280236)
		(mid 273.78551 -90.068304)
		(end 273.500088 -89.984834)
		(width 0.0889)
		(layer "In4.Cu")
		(net "H_PM_SYNC_GTL")
	)
	(arc
		(start 243.338604 -81.250536)
		(mid 243.141443 -81.198577)
		(end 242.99545 -81.056226)
		(width 0.0889)
		(layer "In4.Cu")
		(net "H_PM_SYNC_GTL")
	)
	(arc
		(start 297.004994 -68.492878)
		(mid 296.859028 -68.635277)
		(end 296.66184 -68.687188)
		(width 0.0889)
		(layer "In4.Cu")
		(net "H_PM_SYNC_GTL")
	)
	(arc
		(start 278.979884 -89.784936)
		(mid 278.839805 -89.927672)
		(end 278.64816 -89.984834)
		(width 0.0889)
		(layer "In4.Cu")
		(net "H_PM_SYNC_GTL")
	)
	(arc
		(start 251.908818 -87.194136)
		(mid 251.717176 -87.13697)
		(end 251.577094 -86.994238)
		(width 0.0889)
		(layer "In4.Cu")
		(net "H_PM_SYNC_GTL")
	)
	(arc
		(start 274.329652 -90.480388)
		(mid 274.135802 -90.424038)
		(end 273.994118 -90.280236)
		(width 0.0889)
		(layer "In4.Cu")
		(net "H_PM_SYNC_GTL")
	)
	(arc
		(start 296.154856 -74.534522)
		(mid 296.203611 -74.730874)
		(end 296.15003 -74.925936)
		(width 0.0889)
		(layer "In4.Cu")
		(net "H_PM_SYNC_GTL")
	)
	(arc
		(start 281.187144 -88.499188)
		(mid 280.903927 -88.583469)
		(end 280.696924 -88.794336)
		(width 0.0889)
		(layer "In4.Cu")
		(net "H_PM_SYNC_GTL")
	)
	(arc
		(start 239.035082 -80.75549)
		(mid 238.841232 -80.69914)
		(end 238.699548 -80.555338)
		(width 0.0889)
		(layer "In4.Cu")
		(net "H_PM_SYNC_GTL")
	)
	(arc
		(start 240.741708 -80.75549)
		(mid 240.458491 -80.839771)
		(end 240.251488 -81.050638)
		(width 0.0889)
		(layer "In4.Cu")
		(net "H_PM_SYNC_GTL")
	)
	(arc
		(start 281.551888 -88.304878)
		(mid 281.405922 -88.447277)
		(end 281.208734 -88.499188)
		(width 0.0889)
		(layer "In4.Cu")
		(net "H_PM_SYNC_GTL")
	)
	(arc
		(start 291.497766 -82.555334)
		(mid 291.209621 -82.637653)
		(end 290.99891 -82.850736)
		(width 0.0889)
		(layer "In4.Cu")
		(net "H_PM_SYNC_GTL")
	)
	(arc
		(start 249.860054 -83.031838)
		(mid 249.65305 -82.820974)
		(end 249.369834 -82.73669)
		(width 0.0889)
		(layer "In4.Cu")
		(net "H_PM_SYNC_GTL")
	)
	(arc
		(start 282.049474 -88.00338)
		(mid 281.763902 -88.086936)
		(end 281.55519 -88.299036)
		(width 0.0889)
		(layer "In4.Cu")
		(net "H_PM_SYNC_GTL")
	)
	(arc
		(start 253.294134 -87.984838)
		(mid 253.08713 -87.773974)
		(end 252.803914 -87.68969)
		(width 0.0889)
		(layer "In4.Cu")
		(net "H_PM_SYNC_GTL")
	)
	(arc
		(start 292.71595 -80.869536)
		(mid 292.636728 -81.158654)
		(end 292.7096 -81.449418)
		(width 0.0889)
		(layer "In4.Cu")
		(net "H_PM_SYNC_GTL")
	)
	(arc
		(start 261.356094 -90.66149)
		(mid 261.162244 -90.60514)
		(end 261.02056 -90.461338)
		(width 0.0889)
		(layer "In4.Cu")
		(net "H_PM_SYNC_GTL")
	)
	(arc
		(start 265.312906 -90.956638)
		(mid 265.105902 -90.745774)
		(end 264.822686 -90.66149)
		(width 0.0889)
		(layer "In4.Cu")
		(net "H_PM_SYNC_GTL")
	)
	(arc
		(start 278.615394 -89.984834)
		(mid 278.32997 -90.068301)
		(end 278.121364 -90.280236)
		(width 0.0889)
		(layer "In4.Cu")
		(net "H_PM_SYNC_GTL")
	)
	(arc
		(start 245.037864 -81.250536)
		(mid 244.75244 -81.334003)
		(end 244.543834 -81.545938)
		(width 0.0889)
		(layer "In4.Cu")
		(net "H_PM_SYNC_GTL")
	)
	(arc
		(start 250.18873 -83.231736)
		(mid 249.998801 -83.173866)
		(end 249.860054 -83.031838)
		(width 0.0889)
		(layer "In4.Cu")
		(net "H_PM_SYNC_GTL")
	)
	(arc
		(start 293.20617 -80.574388)
		(mid 292.922953 -80.658669)
		(end 292.71595 -80.869536)
		(width 0.0889)
		(layer "In4.Cu")
		(net "H_PM_SYNC_GTL")
	)
	(arc
		(start 258.776724 -89.175336)
		(mid 258.585082 -89.11817)
		(end 258.445 -88.975438)
		(width 0.0889)
		(layer "In4.Cu")
		(net "H_PM_SYNC_GTL")
	)
	(arc
		(start 272.970498 -90.280236)
		(mid 272.828815 -90.42404)
		(end 272.634964 -90.480388)
		(width 0.0889)
		(layer "In4.Cu")
		(net "H_PM_SYNC_GTL")
	)
	(arc
		(start 288.91738 -84.041234)
		(mid 288.631956 -84.124701)
		(end 288.42335 -84.336636)
		(width 0.0889)
		(layer "In4.Cu")
		(net "H_PM_SYNC_GTL")
	)
	(arc
		(start 280.696924 -88.794336)
		(mid 280.556845 -88.937072)
		(end 280.3652 -88.994234)
		(width 0.0889)
		(layer "In4.Cu")
		(net "H_PM_SYNC_GTL")
	)
	(arc
		(start 238.169958 -80.259936)
		(mid 237.884534 -80.343403)
		(end 237.675928 -80.555338)
		(width 0.0889)
		(layer "In4.Cu")
		(net "H_PM_SYNC_GTL")
	)
	(arc
		(start 241.606832 -81.250536)
		(mid 241.41519 -81.19337)
		(end 241.275108 -81.050638)
		(width 0.0889)
		(layer "In4.Cu")
		(net "H_PM_SYNC_GTL")
	)
	(arc
		(start 236.452918 -80.259936)
		(mid 236.167494 -80.343403)
		(end 235.958888 -80.555338)
		(width 0.0889)
		(layer "In4.Cu")
		(net "H_PM_SYNC_GTL")
	)
	(arc
		(start 289.77209 -83.546188)
		(mid 289.488873 -83.630469)
		(end 289.28187 -83.841336)
		(width 0.0889)
		(layer "In4.Cu")
		(net "H_PM_SYNC_GTL")
	)
	(arc
		(start 294.0685 -80.078834)
		(mid 293.783076 -80.162301)
		(end 293.57447 -80.374236)
		(width 0.0889)
		(layer "In4.Cu")
		(net "H_PM_SYNC_GTL")
	)
	(segment
		(start 320.34734 -67.657218)
		(end 320.257932 -67.56781)
		(width 0.089408)
		(layer "In11.Cu")
		(net "H_PM_SYNC_GTL")
	)
	(segment
		(start 328.904092 -68.363592)
		(end 328.814684 -68.274184)
		(width 0.089408)
		(layer "In11.Cu")
		(net "H_PM_SYNC_GTL")
	)
	(segment
		(start 326.373236 -68.363592)
		(end 326.081644 -68.363592)
		(width 0.089408)
		(layer "In11.Cu")
		(net "H_PM_SYNC_GTL")
	)
	(segment
		(start 355.752146 -63.6524)
		(end 355.289866 -63.6524)
		(width 0.089408)
		(layer "In11.Cu")
		(net "H_PM_SYNC_GTL")
	)
	(segment
		(start 314.232036 -68.274184)
		(end 314.142628 -68.363592)
		(width 0.089408)
		(layer "In11.Cu")
		(net "H_PM_SYNC_GTL")
	)
	(segment
		(start 325.05142 -68.274184)
		(end 325.05142 -67.657218)
		(width 0.089408)
		(layer "In11.Cu")
		(net "H_PM_SYNC_GTL")
	)
	(segment
		(start 324.962012 -67.56781)
		(end 324.67042 -67.56781)
		(width 0.089408)
		(layer "In11.Cu")
		(net "H_PM_SYNC_GTL")
	)
	(segment
		(start 316.113668 -68.274184)
		(end 316.02426 -68.363592)
		(width 0.089408)
		(layer "In11.Cu")
		(net "H_PM_SYNC_GTL")
	)
	(segment
		(start 316.584076 -67.657218)
		(end 316.494668 -67.56781)
		(width 0.089408)
		(layer "In11.Cu")
		(net "H_PM_SYNC_GTL")
	)
	(segment
		(start 363.1946 -68.1736)
		(end 363.1946 -67.564)
		(width 0.089408)
		(layer "In11.Cu")
		(net "H_PM_SYNC_GTL")
	)
	(segment
		(start 326.462644 -67.657218)
		(end 326.462644 -68.274184)
		(width 0.089408)
		(layer "In11.Cu")
		(net "H_PM_SYNC_GTL")
	)
	(segment
		(start 316.113668 -67.657218)
		(end 316.113668 -68.274184)
		(width 0.089408)
		(layer "In11.Cu")
		(net "H_PM_SYNC_GTL")
	)
	(segment
		(start 357.500174 -65.477136)
		(end 357.208582 -65.477136)
		(width 0.089408)
		(layer "In11.Cu")
		(net "H_PM_SYNC_GTL")
	)
	(segment
		(start 358.619806 -66.399918)
		(end 358.530398 -66.31051)
		(width 0.089408)
		(layer "In11.Cu")
		(net "H_PM_SYNC_GTL")
	)
	(segment
		(start 313.29122 -68.274184)
		(end 313.201812 -68.363592)
		(width 0.089408)
		(layer "In11.Cu")
		(net "H_PM_SYNC_GTL")
	)
	(segment
		(start 177.08245 -115.645946)
		(end 177.673 -115.645946)
		(width 0.089408)
		(layer "In11.Cu")
		(net "H_PM_SYNC_GTL")
	)
	(segment
		(start 364.889796 -91.121738)
		(end 364.584742 -90.816684)
		(width 0.089408)
		(layer "In11.Cu")
		(net "H_PM_SYNC_GTL")
	)
	(segment
		(start 332.260448 -67.56781)
		(end 331.36967 -67.56781)
		(width 0.089408)
		(layer "In11.Cu")
		(net "H_PM_SYNC_GTL")
	)
	(segment
		(start 173.076108 -92.243148)
		(end 173.076108 -100.709984)
		(width 0.089408)
		(layer "In11.Cu")
		(net "H_PM_SYNC_GTL")
	)
	(segment
		(start 364.584742 -90.816684)
		(end 364.584742 -84.641182)
		(width 0.089408)
		(layer "In11.Cu")
		(net "H_PM_SYNC_GTL")
	)
	(segment
		(start 322.69938 -68.274184)
		(end 322.609972 -68.363592)
		(width 0.089408)
		(layer "In11.Cu")
		(net "H_PM_SYNC_GTL")
	)
	(segment
		(start 357.119174 -66.31051)
		(end 357.029766 -66.399918)
		(width 0.089408)
		(layer "In11.Cu")
		(net "H_PM_SYNC_GTL")
	)
	(segment
		(start 323.169788 -68.274184)
		(end 323.169788 -67.657218)
		(width 0.089408)
		(layer "In11.Cu")
		(net "H_PM_SYNC_GTL")
	)
	(segment
		(start 360.501438 -66.399918)
		(end 360.41203 -66.31051)
		(width 0.089408)
		(layer "In11.Cu")
		(net "H_PM_SYNC_GTL")
	)
	(segment
		(start 176.993042 -113.674906)
		(end 177.08245 -113.764314)
		(width 0.089408)
		(layer "In11.Cu")
		(net "H_PM_SYNC_GTL")
	)
	(segment
		(start 328.344276 -68.274184)
		(end 328.254868 -68.363592)
		(width 0.089408)
		(layer "In11.Cu")
		(net "H_PM_SYNC_GTL")
	)
	(segment
		(start 360.03103 -65.477136)
		(end 359.941622 -65.566544)
		(width 0.089408)
		(layer "In11.Cu")
		(net "H_PM_SYNC_GTL")
	)
	(segment
		(start 328.433684 -67.56781)
		(end 328.344276 -67.657218)
		(width 0.089408)
		(layer "In11.Cu")
		(net "H_PM_SYNC_GTL")
	)
	(segment
		(start 317.524892 -67.657218)
		(end 317.435484 -67.56781)
		(width 0.089408)
		(layer "In11.Cu")
		(net "H_PM_SYNC_GTL")
	)
	(segment
		(start 313.761628 -68.274184)
		(end 313.761628 -67.657218)
		(width 0.089408)
		(layer "In11.Cu")
		(net "H_PM_SYNC_GTL")
	)
	(segment
		(start 366.220756 -92.452698)
		(end 366.014508 -92.24645)
		(width 0.089408)
		(layer "In11.Cu")
		(net "H_PM_SYNC_GTL")
	)
	(segment
		(start 177.762408 -108.500418)
		(end 177.673 -108.589826)
		(width 0.089408)
		(layer "In11.Cu")
		(net "H_PM_SYNC_GTL")
	)
	(segment
		(start 135.084058 -66.705988)
		(end 135.116824 -66.705988)
		(width 0.0889)
		(layer "In11.Cu")
		(net "H_PM_SYNC_GTL")
	)
	(segment
		(start 177.762408 -110.38205)
		(end 177.673 -110.471458)
		(width 0.089408)
		(layer "In11.Cu")
		(net "H_PM_SYNC_GTL")
	)
	(segment
		(start 316.203076 -67.56781)
		(end 316.113668 -67.657218)
		(width 0.089408)
		(layer "In11.Cu")
		(net "H_PM_SYNC_GTL")
	)
	(segment
		(start 312.820812 -67.657218)
		(end 312.731404 -67.56781)
		(width 0.089408)
		(layer "In11.Cu")
		(net "H_PM_SYNC_GTL")
	)
	(segment
		(start 317.9953 -68.274184)
		(end 317.905892 -68.363592)
		(width 0.089408)
		(layer "In11.Cu")
		(net "H_PM_SYNC_GTL")
	)
	(segment
		(start 177.762408 -107.084876)
		(end 177.762408 -107.559602)
		(width 0.089408)
		(layer "In11.Cu")
		(net "H_PM_SYNC_GTL")
	)
	(segment
		(start 177.673 -114.234722)
		(end 177.08245 -114.234722)
		(width 0.089408)
		(layer "In11.Cu")
		(net "H_PM_SYNC_GTL")
	)
	(segment
		(start 326.843644 -67.56781)
		(end 326.552052 -67.56781)
		(width 0.089408)
		(layer "In11.Cu")
		(net "H_PM_SYNC_GTL")
	)
	(segment
		(start 176.993042 -110.560866)
		(end 176.993042 -110.852458)
		(width 0.089408)
		(layer "In11.Cu")
		(net "H_PM_SYNC_GTL")
	)
	(segment
		(start 327.873868 -67.657218)
		(end 327.78446 -67.56781)
		(width 0.089408)
		(layer "In11.Cu")
		(net "H_PM_SYNC_GTL")
	)
	(segment
		(start 177.08245 -110.471458)
		(end 176.993042 -110.560866)
		(width 0.089408)
		(layer "In11.Cu")
		(net "H_PM_SYNC_GTL")
	)
	(segment
		(start 365.367316 -92.10167)
		(end 365.555276 -91.91371)
		(width 0.089408)
		(layer "In11.Cu")
		(net "H_PM_SYNC_GTL")
	)
	(segment
		(start 177.08245 -118.468394)
		(end 177.673 -118.468394)
		(width 0.089408)
		(layer "In11.Cu")
		(net "H_PM_SYNC_GTL")
	)
	(segment
		(start 327.02246 -68.363592)
		(end 326.933052 -68.274184)
		(width 0.089408)
		(layer "In11.Cu")
		(net "H_PM_SYNC_GTL")
	)
	(segment
		(start 326.081644 -68.363592)
		(end 325.992236 -68.274184)
		(width 0.089408)
		(layer "In11.Cu")
		(net "H_PM_SYNC_GTL")
	)
	(segment
		(start 177.762408 -113.853722)
		(end 177.762408 -114.145314)
		(width 0.089408)
		(layer "In11.Cu")
		(net "H_PM_SYNC_GTL")
	)
	(segment
		(start 363.82071 -83.87715)
		(end 363.82071 -80.16367)
		(width 0.089408)
		(layer "In11.Cu")
		(net "H_PM_SYNC_GTL")
	)
	(segment
		(start 310.334914 -67.89801)
		(end 308.835044 -66.39814)
		(width 0.089408)
		(layer "In11.Cu")
		(net "H_PM_SYNC_GTL")
	)
	(segment
		(start 177.673 -116.116354)
		(end 177.08245 -116.116354)
		(width 0.089408)
		(layer "In11.Cu")
		(net "H_PM_SYNC_GTL")
	)
	(segment
		(start 321.288156 -68.274184)
		(end 321.288156 -67.657218)
		(width 0.089408)
		(layer "In11.Cu")
		(net "H_PM_SYNC_GTL")
	)
	(segment
		(start 316.494668 -67.56781)
		(end 316.203076 -67.56781)
		(width 0.089408)
		(layer "In11.Cu")
		(net "H_PM_SYNC_GTL")
	)
	(segment
		(start 177.673 -113.293906)
		(end 177.08245 -113.293906)
		(width 0.089408)
		(layer "In11.Cu")
		(net "H_PM_SYNC_GTL")
	)
	(segment
		(start 177.762408 -112.912906)
		(end 177.762408 -113.204498)
		(width 0.089408)
		(layer "In11.Cu")
		(net "H_PM_SYNC_GTL")
	)
	(segment
		(start 314.702444 -67.657218)
		(end 314.613036 -67.56781)
		(width 0.089408)
		(layer "In11.Cu")
		(net "H_PM_SYNC_GTL")
	)
	(segment
		(start 359.941622 -65.566544)
		(end 359.941622 -66.31051)
		(width 0.089408)
		(layer "In11.Cu")
		(net "H_PM_SYNC_GTL")
	)
	(segment
		(start 176.993042 -108.970826)
		(end 177.08245 -109.060234)
		(width 0.089408)
		(layer "In11.Cu")
		(net "H_PM_SYNC_GTL")
	)
	(segment
		(start 178.8668 -129.7432)
		(end 182.212234 -129.7432)
		(width 0.089408)
		(layer "In11.Cu")
		(net "H_PM_SYNC_GTL")
	)
	(segment
		(start 136.801098 -67.696588)
		(end 136.833864 -67.696588)
		(width 0.0889)
		(layer "In11.Cu")
		(net "H_PM_SYNC_GTL")
	)
	(segment
		(start 357.119174 -65.566544)
		(end 357.119174 -66.31051)
		(width 0.089408)
		(layer "In11.Cu")
		(net "H_PM_SYNC_GTL")
	)
	(segment
		(start 296.757598 -67.20078)
		(end 296.66184 -67.296538)
		(width 0.089408)
		(layer "In11.Cu")
		(net "H_PM_SYNC_GTL")
	)
	(segment
		(start 321.288156 -67.657218)
		(end 321.198748 -67.56781)
		(width 0.089408)
		(layer "In11.Cu")
		(net "H_PM_SYNC_GTL")
	)
	(segment
		(start 177.08245 -114.234722)
		(end 176.993042 -114.32413)
		(width 0.089408)
		(layer "In11.Cu")
		(net "H_PM_SYNC_GTL")
	)
	(segment
		(start 137.655808 -68.191634)
		(end 137.688574 -68.191634)
		(width 0.0889)
		(layer "In11.Cu")
		(net "H_PM_SYNC_GTL")
	)
	(segment
		(start 364.584742 -84.641182)
		(end 363.82071 -83.87715)
		(width 0.089408)
		(layer "In11.Cu")
		(net "H_PM_SYNC_GTL")
	)
	(segment
		(start 325.611236 -67.56781)
		(end 325.521828 -67.657218)
		(width 0.089408)
		(layer "In11.Cu")
		(net "H_PM_SYNC_GTL")
	)
	(segment
		(start 317.054484 -68.274184)
		(end 316.965076 -68.363592)
		(width 0.089408)
		(layer "In11.Cu")
		(net "H_PM_SYNC_GTL")
	)
	(segment
		(start 364.370366 -77.412088)
		(end 364.370366 -74.190352)
		(width 0.089408)
		(layer "In11.Cu")
		(net "H_PM_SYNC_GTL")
	)
	(segment
		(start 359.471214 -66.31051)
		(end 359.471214 -65.566544)
		(width 0.089408)
		(layer "In11.Cu")
		(net "H_PM_SYNC_GTL")
	)
	(segment
		(start 177.762408 -117.616986)
		(end 177.762408 -117.908578)
		(width 0.089408)
		(layer "In11.Cu")
		(net "H_PM_SYNC_GTL")
	)
	(segment
		(start 315.083444 -68.363592)
		(end 314.791852 -68.363592)
		(width 0.089408)
		(layer "In11.Cu")
		(net "H_PM_SYNC_GTL")
	)
	(segment
		(start 177.08245 -111.412274)
		(end 176.993042 -111.501682)
		(width 0.089408)
		(layer "In11.Cu")
		(net "H_PM_SYNC_GTL")
	)
	(segment
		(start 176.993042 -109.62005)
		(end 176.993042 -109.911642)
		(width 0.089408)
		(layer "In11.Cu")
		(net "H_PM_SYNC_GTL")
	)
	(segment
		(start 315.553852 -67.56781)
		(end 315.26226 -67.56781)
		(width 0.089408)
		(layer "In11.Cu")
		(net "H_PM_SYNC_GTL")
	)
	(segment
		(start 323.169788 -67.657218)
		(end 323.08038 -67.56781)
		(width 0.089408)
		(layer "In11.Cu")
		(net "H_PM_SYNC_GTL")
	)
	(segment
		(start 184.513474 -129.07518)
		(end 187.657994 -125.93066)
		(width 0.089408)
		(layer "In11.Cu")
		(net "H_PM_SYNC_GTL")
	)
	(segment
		(start 359.000806 -66.31051)
		(end 358.911398 -66.399918)
		(width 0.089408)
		(layer "In11.Cu")
		(net "H_PM_SYNC_GTL")
	)
	(segment
		(start 314.321444 -67.56781)
		(end 314.232036 -67.657218)
		(width 0.089408)
		(layer "In11.Cu")
		(net "H_PM_SYNC_GTL")
	)
	(segment
		(start 177.08245 -110.00105)
		(end 177.673 -110.00105)
		(width 0.089408)
		(layer "In11.Cu")
		(net "H_PM_SYNC_GTL")
	)
	(segment
		(start 324.110604 -67.657218)
		(end 324.021196 -67.56781)
		(width 0.089408)
		(layer "In11.Cu")
		(net "H_PM_SYNC_GTL")
	)
	(segment
		(start 317.6143 -68.363592)
		(end 317.524892 -68.274184)
		(width 0.089408)
		(layer "In11.Cu")
		(net "H_PM_SYNC_GTL")
	)
	(segment
		(start 359.803192 -64.53632)
		(end 356.077266 -64.53632)
		(width 0.089408)
		(layer "In11.Cu")
		(net "H_PM_SYNC_GTL")
	)
	(segment
		(start 325.902828 -67.56781)
		(end 325.611236 -67.56781)
		(width 0.089408)
		(layer "In11.Cu")
		(net "H_PM_SYNC_GTL")
	)
	(segment
		(start 302.683418 -67.20078)
		(end 302.650652 -67.20078)
		(width 0.089408)
		(layer "In11.Cu")
		(net "H_PM_SYNC_GTL")
	)
	(segment
		(start 358.530398 -65.566544)
		(end 358.44099 -65.477136)
		(width 0.089408)
		(layer "In11.Cu")
		(net "H_PM_SYNC_GTL")
	)
	(segment
		(start 359.8926 -64.91732)
		(end 359.8926 -64.625728)
		(width 0.089408)
		(layer "In11.Cu")
		(net "H_PM_SYNC_GTL")
	)
	(segment
		(start 317.143892 -67.56781)
		(end 317.054484 -67.657218)
		(width 0.089408)
		(layer "In11.Cu")
		(net "H_PM_SYNC_GTL")
	)
	(segment
		(start 366.365536 -93.09989)
		(end 366.239044 -93.09989)
		(width 0.089408)
		(layer "In11.Cu")
		(net "H_PM_SYNC_GTL")
	)
	(segment
		(start 365.573564 -92.43441)
		(end 365.367316 -92.228162)
		(width 0.089408)
		(layer "In11.Cu")
		(net "H_PM_SYNC_GTL")
	)
	(segment
		(start 364.370366 -74.190352)
		(end 361.970828 -71.790814)
		(width 0.089408)
		(layer "In11.Cu")
		(net "H_PM_SYNC_GTL")
	)
	(segment
		(start 359.560622 -66.399918)
		(end 359.471214 -66.31051)
		(width 0.089408)
		(layer "In11.Cu")
		(net "H_PM_SYNC_GTL")
	)
	(segment
		(start 327.314052 -68.363592)
		(end 327.02246 -68.363592)
		(width 0.089408)
		(layer "In11.Cu")
		(net "H_PM_SYNC_GTL")
	)
	(segment
		(start 323.640196 -67.657218)
		(end 323.640196 -68.274184)
		(width 0.089408)
		(layer "In11.Cu")
		(net "H_PM_SYNC_GTL")
	)
	(segment
		(start 176.993042 -116.205762)
		(end 176.993042 -116.497354)
		(width 0.089408)
		(layer "In11.Cu")
		(net "H_PM_SYNC_GTL")
	)
	(segment
		(start 177.673 -116.586762)
		(end 177.762408 -116.67617)
		(width 0.089408)
		(layer "In11.Cu")
		(net "H_PM_SYNC_GTL")
	)
	(segment
		(start 360.79303 -66.399918)
		(end 360.501438 -66.399918)
		(width 0.089408)
		(layer "In11.Cu")
		(net "H_PM_SYNC_GTL")
	)
	(segment
		(start 177.673 -118.468394)
		(end 177.762408 -118.557802)
		(width 0.089408)
		(layer "In11.Cu")
		(net "H_PM_SYNC_GTL")
	)
	(segment
		(start 303.553876 -66.705734)
		(end 303.505616 -66.705734)
		(width 0.089408)
		(layer "In11.Cu")
		(net "H_PM_SYNC_GTL")
	)
	(segment
		(start 365.700056 -92.43441)
		(end 365.573564 -92.43441)
		(width 0.089408)
		(layer "In11.Cu")
		(net "H_PM_SYNC_GTL")
	)
	(segment
		(start 177.673 -109.530642)
		(end 177.08245 -109.530642)
		(width 0.089408)
		(layer "In11.Cu")
		(net "H_PM_SYNC_GTL")
	)
	(segment
		(start 366.220756 -92.57919)
		(end 366.220756 -92.452698)
		(width 0.089408)
		(layer "In11.Cu")
		(net "H_PM_SYNC_GTL")
	)
	(segment
		(start 140.22832 -69.677534)
		(end 140.267944 -69.677534)
		(width 0.0889)
		(layer "In11.Cu")
		(net "H_PM_SYNC_GTL")
	)
	(segment
		(start 327.963276 -68.363592)
		(end 327.873868 -68.274184)
		(width 0.089408)
		(layer "In11.Cu")
		(net "H_PM_SYNC_GTL")
	)
	(segment
		(start 177.762408 -118.557802)
		(end 177.762408 -128.638808)
		(width 0.089408)
		(layer "In11.Cu")
		(net "H_PM_SYNC_GTL")
	)
	(segment
		(start 319.406524 -68.274184)
		(end 319.406524 -67.657218)
		(width 0.089408)
		(layer "In11.Cu")
		(net "H_PM_SYNC_GTL")
	)
	(segment
		(start 176.993042 -112.73409)
		(end 177.08245 -112.823498)
		(width 0.089408)
		(layer "In11.Cu")
		(net "H_PM_SYNC_GTL")
	)
	(segment
		(start 328.814684 -67.657218)
		(end 328.725276 -67.56781)
		(width 0.089408)
		(layer "In11.Cu")
		(net "H_PM_SYNC_GTL")
	)
	(segment
		(start 331.280262 -68.268088)
		(end 331.190854 -68.357496)
		(width 0.089408)
		(layer "In11.Cu")
		(net "H_PM_SYNC_GTL")
	)
	(segment
		(start 177.762408 -108.208826)
		(end 177.762408 -108.500418)
		(width 0.089408)
		(layer "In11.Cu")
		(net "H_PM_SYNC_GTL")
	)
	(segment
		(start 317.905892 -68.363592)
		(end 317.6143 -68.363592)
		(width 0.089408)
		(layer "In11.Cu")
		(net "H_PM_SYNC_GTL")
	)
	(segment
		(start 324.581012 -68.274184)
		(end 324.491604 -68.363592)
		(width 0.089408)
		(layer "In11.Cu")
		(net "H_PM_SYNC_GTL")
	)
	(segment
		(start 172.283882 -91.450922)
		(end 173.076108 -92.243148)
		(width 0.089408)
		(layer "In11.Cu")
		(net "H_PM_SYNC_GTL")
	)
	(segment
		(start 141.093698 -70.172834)
		(end 142.494254 -70.172834)
		(width 0.0889)
		(layer "In11.Cu")
		(net "H_PM_SYNC_GTL")
	)
	(segment
		(start 326.552052 -67.56781)
		(end 326.462644 -67.657218)
		(width 0.089408)
		(layer "In11.Cu")
		(net "H_PM_SYNC_GTL")
	)
	(segment
		(start 329.3745 -67.56781)
		(end 329.285092 -67.657218)
		(width 0.089408)
		(layer "In11.Cu")
		(net "H_PM_SYNC_GTL")
	)
	(segment
		(start 163.772342 -91.450922)
		(end 172.283882 -91.450922)
		(width 0.089408)
		(layer "In11.Cu")
		(net "H_PM_SYNC_GTL")
	)
	(segment
		(start 312.492644 -67.56781)
		(end 312.162444 -67.89801)
		(width 0.089408)
		(layer "In11.Cu")
		(net "H_PM_SYNC_GTL")
	)
	(segment
		(start 363.82071 -80.16367)
		(end 364.370366 -77.412088)
		(width 0.089408)
		(layer "In11.Cu")
		(net "H_PM_SYNC_GTL")
	)
	(segment
		(start 177.08245 -113.293906)
		(end 176.993042 -113.383314)
		(width 0.089408)
		(layer "In11.Cu")
		(net "H_PM_SYNC_GTL")
	)
	(segment
		(start 176.993042 -115.556538)
		(end 177.08245 -115.645946)
		(width 0.089408)
		(layer "In11.Cu")
		(net "H_PM_SYNC_GTL")
	)
	(segment
		(start 356.077266 -64.53632)
		(end 355.987858 -64.446912)
		(width 0.089408)
		(layer "In11.Cu")
		(net "H_PM_SYNC_GTL")
	)
	(segment
		(start 176.993042 -110.852458)
		(end 177.08245 -110.941866)
		(width 0.089408)
		(layer "In11.Cu")
		(net "H_PM_SYNC_GTL")
	)
	(segment
		(start 315.172852 -68.274184)
		(end 315.083444 -68.363592)
		(width 0.089408)
		(layer "In11.Cu")
		(net "H_PM_SYNC_GTL")
	)
	(segment
		(start 316.673484 -68.363592)
		(end 316.584076 -68.274184)
		(width 0.089408)
		(layer "In11.Cu")
		(net "H_PM_SYNC_GTL")
	)
	(segment
		(start 328.344276 -67.657218)
		(end 328.344276 -68.274184)
		(width 0.089408)
		(layer "In11.Cu")
		(net "H_PM_SYNC_GTL")
	)
	(segment
		(start 366.553496 -92.91193)
		(end 366.365536 -93.09989)
		(width 0.089408)
		(layer "In11.Cu")
		(net "H_PM_SYNC_GTL")
	)
	(segment
		(start 359.8926 -64.625728)
		(end 359.803192 -64.53632)
		(width 0.089408)
		(layer "In11.Cu")
		(net "H_PM_SYNC_GTL")
	)
	(segment
		(start 361.970828 -69.397372)
		(end 363.1946 -68.1736)
		(width 0.089408)
		(layer "In11.Cu")
		(net "H_PM_SYNC_GTL")
	)
	(segment
		(start 331.280262 -67.657218)
		(end 331.280262 -68.268088)
		(width 0.089408)
		(layer "In11.Cu")
		(net "H_PM_SYNC_GTL")
	)
	(segment
		(start 321.847972 -67.56781)
		(end 321.758564 -67.657218)
		(width 0.089408)
		(layer "In11.Cu")
		(net "H_PM_SYNC_GTL")
	)
	(segment
		(start 365.555276 -91.91371)
		(end 365.555276 -91.787218)
		(width 0.089408)
		(layer "In11.Cu")
		(net "H_PM_SYNC_GTL")
	)
	(segment
		(start 177.08245 -117.997986)
		(end 176.993042 -118.087394)
		(width 0.089408)
		(layer "In11.Cu")
		(net "H_PM_SYNC_GTL")
	)
	(segment
		(start 322.788788 -67.56781)
		(end 322.69938 -67.657218)
		(width 0.089408)
		(layer "In11.Cu")
		(net "H_PM_SYNC_GTL")
	)
	(segment
		(start 315.732668 -68.363592)
		(end 315.64326 -68.274184)
		(width 0.089408)
		(layer "In11.Cu")
		(net "H_PM_SYNC_GTL")
	)
	(segment
		(start 325.521828 -68.274184)
		(end 325.43242 -68.363592)
		(width 0.089408)
		(layer "In11.Cu")
		(net "H_PM_SYNC_GTL")
	)
	(segment
		(start 313.29122 -67.657218)
		(end 313.29122 -68.274184)
		(width 0.089408)
		(layer "In11.Cu")
		(net "H_PM_SYNC_GTL")
	)
	(segment
		(start 365.367316 -92.228162)
		(end 365.367316 -92.10167)
		(width 0.089408)
		(layer "In11.Cu")
		(net "H_PM_SYNC_GTL")
	)
	(segment
		(start 177.08245 -113.764314)
		(end 177.673 -113.764314)
		(width 0.089408)
		(layer "In11.Cu")
		(net "H_PM_SYNC_GTL")
	)
	(segment
		(start 177.08245 -109.530642)
		(end 176.993042 -109.62005)
		(width 0.089408)
		(layer "In11.Cu")
		(net "H_PM_SYNC_GTL")
	)
	(segment
		(start 331.36967 -67.56781)
		(end 331.280262 -67.657218)
		(width 0.089408)
		(layer "In11.Cu")
		(net "H_PM_SYNC_GTL")
	)
	(segment
		(start 176.993042 -111.793274)
		(end 177.08245 -111.882682)
		(width 0.089408)
		(layer "In11.Cu")
		(net "H_PM_SYNC_GTL")
	)
	(segment
		(start 360.41203 -65.566544)
		(end 360.322622 -65.477136)
		(width 0.089408)
		(layer "In11.Cu")
		(net "H_PM_SYNC_GTL")
	)
	(segment
		(start 177.762408 -114.145314)
		(end 177.673 -114.234722)
		(width 0.089408)
		(layer "In11.Cu")
		(net "H_PM_SYNC_GTL")
	)
	(segment
		(start 176.993042 -114.32413)
		(end 176.993042 -114.615722)
		(width 0.089408)
		(layer "In11.Cu")
		(net "H_PM_SYNC_GTL")
	)
	(segment
		(start 176.993042 -112.442498)
		(end 176.993042 -112.73409)
		(width 0.089408)
		(layer "In11.Cu")
		(net "H_PM_SYNC_GTL")
	)
	(segment
		(start 320.34734 -68.274184)
		(end 320.34734 -67.657218)
		(width 0.089408)
		(layer "In11.Cu")
		(net "H_PM_SYNC_GTL")
	)
	(segment
		(start 316.02426 -68.363592)
		(end 315.732668 -68.363592)
		(width 0.089408)
		(layer "In11.Cu")
		(net "H_PM_SYNC_GTL")
	)
	(segment
		(start 177.673 -108.589826)
		(end 177.08245 -108.589826)
		(width 0.089408)
		(layer "In11.Cu")
		(net "H_PM_SYNC_GTL")
	)
	(segment
		(start 304.222404 -67.201034)
		(end 304.10531 -67.08394)
		(width 0.089408)
		(layer "In11.Cu")
		(net "H_PM_SYNC_GTL")
	)
	(segment
		(start 177.673 -111.882682)
		(end 177.762408 -111.97209)
		(width 0.089408)
		(layer "In11.Cu")
		(net "H_PM_SYNC_GTL")
	)
	(segment
		(start 193.31686 -129.955036)
		(end 193.981324 -130.6195)
		(width 0.089408)
		(layer "In11.Cu")
		(net "H_PM_SYNC_GTL")
	)
	(segment
		(start 298.436284 -67.692016)
		(end 298.406566 -67.696334)
		(width 0.089408)
		(layer "In11.Cu")
		(net "H_PM_SYNC_GTL")
	)
	(segment
		(start 327.40346 -67.657218)
		(end 327.40346 -68.274184)
		(width 0.089408)
		(layer "In11.Cu")
		(net "H_PM_SYNC_GTL")
	)
	(segment
		(start 327.78446 -67.56781)
		(end 327.492868 -67.56781)
		(width 0.089408)
		(layer "In11.Cu")
		(net "H_PM_SYNC_GTL")
	)
	(segment
		(start 329.285092 -68.274184)
		(end 329.195684 -68.363592)
		(width 0.089408)
		(layer "In11.Cu")
		(net "H_PM_SYNC_GTL")
	)
	(segment
		(start 326.933052 -68.274184)
		(end 326.933052 -67.657218)
		(width 0.089408)
		(layer "In11.Cu")
		(net "H_PM_SYNC_GTL")
	)
	(segment
		(start 312.162444 -67.89801)
		(end 310.334914 -67.89801)
		(width 0.089408)
		(layer "In11.Cu")
		(net "H_PM_SYNC_GTL")
	)
	(segment
		(start 177.673 -113.764314)
		(end 177.762408 -113.853722)
		(width 0.089408)
		(layer "In11.Cu")
		(net "H_PM_SYNC_GTL")
	)
	(segment
		(start 192.162176 -125.93066)
		(end 193.31686 -127.085344)
		(width 0.089408)
		(layer "In11.Cu")
		(net "H_PM_SYNC_GTL")
	)
	(segment
		(start 176.993042 -108.03001)
		(end 177.08245 -108.119418)
		(width 0.089408)
		(layer "In11.Cu")
		(net "H_PM_SYNC_GTL")
	)
	(segment
		(start 359.803192 -65.006728)
		(end 359.8926 -64.91732)
		(width 0.089408)
		(layer "In11.Cu")
		(net "H_PM_SYNC_GTL")
	)
	(segment
		(start 176.993042 -114.615722)
		(end 177.08245 -114.70513)
		(width 0.089408)
		(layer "In11.Cu")
		(net "H_PM_SYNC_GTL")
	)
	(segment
		(start 173.076108 -100.709984)
		(end 177.15611 -104.789986)
		(width 0.089408)
		(layer "In11.Cu")
		(net "H_PM_SYNC_GTL")
	)
	(segment
		(start 324.110604 -68.274184)
		(end 324.110604 -67.657218)
		(width 0.089408)
		(layer "In11.Cu")
		(net "H_PM_SYNC_GTL")
	)
	(segment
		(start 359.000806 -65.566544)
		(end 359.000806 -66.31051)
		(width 0.089408)
		(layer "In11.Cu")
		(net "H_PM_SYNC_GTL")
	)
	(segment
		(start 317.524892 -68.274184)
		(end 317.524892 -67.657218)
		(width 0.089408)
		(layer "In11.Cu")
		(net "H_PM_SYNC_GTL")
	)
	(segment
		(start 364.908084 -91.76893)
		(end 364.701836 -91.562682)
		(width 0.089408)
		(layer "In11.Cu")
		(net "H_PM_SYNC_GTL")
	)
	(segment
		(start 313.67222 -67.56781)
		(end 313.380628 -67.56781)
		(width 0.089408)
		(layer "In11.Cu")
		(net "H_PM_SYNC_GTL")
	)
	(segment
		(start 357.67899 -66.399918)
		(end 357.589582 -66.31051)
		(width 0.089408)
		(layer "In11.Cu")
		(net "H_PM_SYNC_GTL")
	)
	(segment
		(start 139.372848 -69.182234)
		(end 139.405614 -69.182234)
		(width 0.0889)
		(layer "In11.Cu")
		(net "H_PM_SYNC_GTL")
	)
	(segment
		(start 176.993042 -107.738418)
		(end 176.993042 -108.03001)
		(width 0.089408)
		(layer "In11.Cu")
		(net "H_PM_SYNC_GTL")
	)
	(segment
		(start 355.093016 -65.477136)
		(end 355.003608 -65.387728)
		(width 0.089408)
		(layer "In11.Cu")
		(net "H_PM_SYNC_GTL")
	)
	(segment
		(start 134.221728 -66.210434)
		(end 134.254494 -66.210434)
		(width 0.0889)
		(layer "In11.Cu")
		(net "H_PM_SYNC_GTL")
	)
	(segment
		(start 300.970696 -67.201034)
		(end 300.937676 -67.201034)
		(width 0.089408)
		(layer "In11.Cu")
		(net "H_PM_SYNC_GTL")
	)
	(segment
		(start 177.673 -107.64901)
		(end 177.08245 -107.64901)
		(width 0.089408)
		(layer "In11.Cu")
		(net "H_PM_SYNC_GTL")
	)
	(segment
		(start 176.993042 -117.43817)
		(end 177.08245 -117.527578)
		(width 0.089408)
		(layer "In11.Cu")
		(net "H_PM_SYNC_GTL")
	)
	(segment
		(start 355.289866 -63.6524)
		(end 354.808536 -64.13373)
		(width 0.089408)
		(layer "In11.Cu")
		(net "H_PM_SYNC_GTL")
	)
	(segment
		(start 177.08245 -116.586762)
		(end 177.673 -116.586762)
		(width 0.089408)
		(layer "In11.Cu")
		(net "H_PM_SYNC_GTL")
	)
	(segment
		(start 314.142628 -68.363592)
		(end 313.851036 -68.363592)
		(width 0.089408)
		(layer "In11.Cu")
		(net "H_PM_SYNC_GTL")
	)
	(segment
		(start 177.08245 -116.116354)
		(end 176.993042 -116.205762)
		(width 0.089408)
		(layer "In11.Cu")
		(net "H_PM_SYNC_GTL")
	)
	(segment
		(start 177.08245 -117.527578)
		(end 177.673 -117.527578)
		(width 0.089408)
		(layer "In11.Cu")
		(net "H_PM_SYNC_GTL")
	)
	(segment
		(start 177.673 -112.823498)
		(end 177.762408 -112.912906)
		(width 0.089408)
		(layer "In11.Cu")
		(net "H_PM_SYNC_GTL")
	)
	(segment
		(start 298.406566 -67.696334)
		(end 298.371514 -67.696334)
		(width 0.089408)
		(layer "In11.Cu")
		(net "H_PM_SYNC_GTL")
	)
	(segment
		(start 358.911398 -66.399918)
		(end 358.619806 -66.399918)
		(width 0.089408)
		(layer "In11.Cu")
		(net "H_PM_SYNC_GTL")
	)
	(segment
		(start 317.435484 -67.56781)
		(end 317.143892 -67.56781)
		(width 0.089408)
		(layer "In11.Cu")
		(net "H_PM_SYNC_GTL")
	)
	(segment
		(start 319.025524 -67.56781)
		(end 318.936116 -67.657218)
		(width 0.089408)
		(layer "In11.Cu")
		(net "H_PM_SYNC_GTL")
	)
	(segment
		(start 177.08245 -110.941866)
		(end 177.673 -110.941866)
		(width 0.089408)
		(layer "In11.Cu")
		(net "H_PM_SYNC_GTL")
	)
	(segment
		(start 357.029766 -66.399918)
		(end 356.738174 -66.399918)
		(width 0.089408)
		(layer "In11.Cu")
		(net "H_PM_SYNC_GTL")
	)
	(segment
		(start 177.762408 -116.026946)
		(end 177.673 -116.116354)
		(width 0.089408)
		(layer "In11.Cu")
		(net "H_PM_SYNC_GTL")
	)
	(segment
		(start 319.96634 -67.56781)
		(end 319.876932 -67.657218)
		(width 0.089408)
		(layer "In11.Cu")
		(net "H_PM_SYNC_GTL")
	)
	(segment
		(start 359.852214 -66.399918)
		(end 359.560622 -66.399918)
		(width 0.089408)
		(layer "In11.Cu")
		(net "H_PM_SYNC_GTL")
	)
	(segment
		(start 177.08245 -107.64901)
		(end 176.993042 -107.738418)
		(width 0.089408)
		(layer "In11.Cu")
		(net "H_PM_SYNC_GTL")
	)
	(segment
		(start 177.762408 -113.204498)
		(end 177.673 -113.293906)
		(width 0.089408)
		(layer "In11.Cu")
		(net "H_PM_SYNC_GTL")
	)
	(segment
		(start 177.762408 -107.559602)
		(end 177.673 -107.64901)
		(width 0.089408)
		(layer "In11.Cu")
		(net "H_PM_SYNC_GTL")
	)
	(segment
		(start 321.377564 -68.363592)
		(end 321.288156 -68.274184)
		(width 0.089408)
		(layer "In11.Cu")
		(net "H_PM_SYNC_GTL")
	)
	(segment
		(start 356.648766 -66.31051)
		(end 356.648766 -65.566544)
		(width 0.089408)
		(layer "In11.Cu")
		(net "H_PM_SYNC_GTL")
	)
	(segment
		(start 177.673 -117.527578)
		(end 177.762408 -117.616986)
		(width 0.089408)
		(layer "In11.Cu")
		(net "H_PM_SYNC_GTL")
	)
	(segment
		(start 319.876932 -67.657218)
		(end 319.876932 -68.274184)
		(width 0.089408)
		(layer "In11.Cu")
		(net "H_PM_SYNC_GTL")
	)
	(segment
		(start 364.889796 -91.24823)
		(end 364.889796 -91.121738)
		(width 0.089408)
		(layer "In11.Cu")
		(net "H_PM_SYNC_GTL")
	)
	(segment
		(start 355.987858 -64.446912)
		(end 355.987858 -63.888112)
		(width 0.089408)
		(layer "In11.Cu")
		(net "H_PM_SYNC_GTL")
	)
	(segment
		(start 176.993042 -118.378986)
		(end 177.08245 -118.468394)
		(width 0.089408)
		(layer "In11.Cu")
		(net "H_PM_SYNC_GTL")
	)
	(segment
		(start 318.846708 -68.363592)
		(end 318.555116 -68.363592)
		(width 0.089408)
		(layer "In11.Cu")
		(net "H_PM_SYNC_GTL")
	)
	(segment
		(start 367.0935 -94.1705)
		(end 367.0935 -93.325442)
		(width 0.089408)
		(layer "In11.Cu")
		(net "H_PM_SYNC_GTL")
	)
	(segment
		(start 322.228972 -67.657218)
		(end 322.139564 -67.56781)
		(width 0.089408)
		(layer "In11.Cu")
		(net "H_PM_SYNC_GTL")
	)
	(segment
		(start 327.40346 -68.274184)
		(end 327.314052 -68.363592)
		(width 0.089408)
		(layer "In11.Cu")
		(net "H_PM_SYNC_GTL")
	)
	(segment
		(start 330.809854 -67.657218)
		(end 330.720446 -67.56781)
		(width 0.089408)
		(layer "In11.Cu")
		(net "H_PM_SYNC_GTL")
	)
	(segment
		(start 320.72834 -68.363592)
		(end 320.436748 -68.363592)
		(width 0.089408)
		(layer "In11.Cu")
		(net "H_PM_SYNC_GTL")
	)
	(segment
		(start 313.201812 -68.363592)
		(end 312.91022 -68.363592)
		(width 0.089408)
		(layer "In11.Cu")
		(net "H_PM_SYNC_GTL")
	)
	(segment
		(start 315.64326 -67.657218)
		(end 315.553852 -67.56781)
		(width 0.089408)
		(layer "In11.Cu")
		(net "H_PM_SYNC_GTL")
	)
	(segment
		(start 325.992236 -67.657218)
		(end 325.902828 -67.56781)
		(width 0.089408)
		(layer "In11.Cu")
		(net "H_PM_SYNC_GTL")
	)
	(segment
		(start 177.673 -110.00105)
		(end 177.762408 -110.090458)
		(width 0.089408)
		(layer "In11.Cu")
		(net "H_PM_SYNC_GTL")
	)
	(segment
		(start 312.91022 -68.363592)
		(end 312.820812 -68.274184)
		(width 0.089408)
		(layer "In11.Cu")
		(net "H_PM_SYNC_GTL")
	)
	(segment
		(start 316.965076 -68.363592)
		(end 316.673484 -68.363592)
		(width 0.089408)
		(layer "In11.Cu")
		(net "H_PM_SYNC_GTL")
	)
	(segment
		(start 355.003608 -65.387728)
		(end 355.003608 -65.11163)
		(width 0.089408)
		(layer "In11.Cu")
		(net "H_PM_SYNC_GTL")
	)
	(segment
		(start 356.648766 -65.566544)
		(end 356.559358 -65.477136)
		(width 0.089408)
		(layer "In11.Cu")
		(net "H_PM_SYNC_GTL")
	)
	(segment
		(start 326.462644 -68.274184)
		(end 326.373236 -68.363592)
		(width 0.089408)
		(layer "In11.Cu")
		(net "H_PM_SYNC_GTL")
	)
	(segment
		(start 313.761628 -67.657218)
		(end 313.67222 -67.56781)
		(width 0.089408)
		(layer "In11.Cu")
		(net "H_PM_SYNC_GTL")
	)
	(segment
		(start 324.581012 -67.657218)
		(end 324.581012 -68.274184)
		(width 0.089408)
		(layer "In11.Cu")
		(net "H_PM_SYNC_GTL")
	)
	(segment
		(start 135.938768 -67.201034)
		(end 135.971534 -67.201034)
		(width 0.0889)
		(layer "In11.Cu")
		(net "H_PM_SYNC_GTL")
	)
	(segment
		(start 329.195684 -68.363592)
		(end 328.904092 -68.363592)
		(width 0.089408)
		(layer "In11.Cu")
		(net "H_PM_SYNC_GTL")
	)
	(segment
		(start 361.970828 -71.790814)
		(end 361.970828 -69.397372)
		(width 0.089408)
		(layer "In11.Cu")
		(net "H_PM_SYNC_GTL")
	)
	(segment
		(start 318.936116 -67.657218)
		(end 318.936116 -68.274184)
		(width 0.089408)
		(layer "In11.Cu")
		(net "H_PM_SYNC_GTL")
	)
	(segment
		(start 363.1946 -67.564)
		(end 361.107736 -65.477136)
		(width 0.089408)
		(layer "In11.Cu")
		(net "H_PM_SYNC_GTL")
	)
	(segment
		(start 355.003608 -65.11163)
		(end 355.10851 -65.006728)
		(width 0.089408)
		(layer "In11.Cu")
		(net "H_PM_SYNC_GTL")
	)
	(segment
		(start 177.673 -108.119418)
		(end 177.762408 -108.208826)
		(width 0.089408)
		(layer "In11.Cu")
		(net "H_PM_SYNC_GTL")
	)
	(segment
		(start 360.882438 -65.566544)
		(end 360.882438 -66.31051)
		(width 0.089408)
		(layer "In11.Cu")
		(net "H_PM_SYNC_GTL")
	)
	(segment
		(start 177.673 -111.412274)
		(end 177.08245 -111.412274)
		(width 0.089408)
		(layer "In11.Cu")
		(net "H_PM_SYNC_GTL")
	)
	(segment
		(start 177.08245 -108.119418)
		(end 177.673 -108.119418)
		(width 0.089408)
		(layer "In11.Cu")
		(net "H_PM_SYNC_GTL")
	)
	(segment
		(start 187.657994 -125.93066)
		(end 192.162176 -125.93066)
		(width 0.089408)
		(layer "In11.Cu")
		(net "H_PM_SYNC_GTL")
	)
	(segment
		(start 357.589582 -66.31051)
		(end 357.589582 -65.566544)
		(width 0.089408)
		(layer "In11.Cu")
		(net "H_PM_SYNC_GTL")
	)
	(segment
		(start 317.9953 -67.657218)
		(end 317.9953 -68.274184)
		(width 0.089408)
		(layer "In11.Cu")
		(net "H_PM_SYNC_GTL")
	)
	(segment
		(start 176.993042 -115.264946)
		(end 176.993042 -115.556538)
		(width 0.089408)
		(layer "In11.Cu")
		(net "H_PM_SYNC_GTL")
	)
	(segment
		(start 322.228972 -68.274184)
		(end 322.228972 -67.657218)
		(width 0.089408)
		(layer "In11.Cu")
		(net "H_PM_SYNC_GTL")
	)
	(segment
		(start 177.762408 -109.149642)
		(end 177.762408 -109.441234)
		(width 0.089408)
		(layer "In11.Cu")
		(net "H_PM_SYNC_GTL")
	)
	(segment
		(start 315.26226 -67.56781)
		(end 315.172852 -67.657218)
		(width 0.089408)
		(layer "In11.Cu")
		(net "H_PM_SYNC_GTL")
	)
	(segment
		(start 365.888016 -92.24645)
		(end 365.700056 -92.43441)
		(width 0.089408)
		(layer "In11.Cu")
		(net "H_PM_SYNC_GTL")
	)
	(segment
		(start 323.08038 -67.56781)
		(end 322.788788 -67.56781)
		(width 0.089408)
		(layer "In11.Cu")
		(net "H_PM_SYNC_GTL")
	)
	(segment
		(start 133.356604 -65.715388)
		(end 133.399784 -65.715388)
		(width 0.0889)
		(layer "In11.Cu")
		(net "H_PM_SYNC_GTL")
	)
	(segment
		(start 322.31838 -68.363592)
		(end 322.228972 -68.274184)
		(width 0.089408)
		(layer "In11.Cu")
		(net "H_PM_SYNC_GTL")
	)
	(segment
		(start 320.907156 -67.56781)
		(end 320.817748 -67.657218)
		(width 0.089408)
		(layer "In11.Cu")
		(net "H_PM_SYNC_GTL")
	)
	(segment
		(start 364.701836 -91.43619)
		(end 364.889796 -91.24823)
		(width 0.089408)
		(layer "In11.Cu")
		(net "H_PM_SYNC_GTL")
	)
	(segment
		(start 366.014508 -92.24645)
		(end 365.888016 -92.24645)
		(width 0.089408)
		(layer "In11.Cu")
		(net "H_PM_SYNC_GTL")
	)
	(segment
		(start 177.673 -115.175538)
		(end 177.08245 -115.175538)
		(width 0.089408)
		(layer "In11.Cu")
		(net "H_PM_SYNC_GTL")
	)
	(segment
		(start 327.873868 -68.274184)
		(end 327.873868 -67.657218)
		(width 0.089408)
		(layer "In11.Cu")
		(net "H_PM_SYNC_GTL")
	)
	(segment
		(start 177.673 -114.70513)
		(end 177.762408 -114.794538)
		(width 0.089408)
		(layer "In11.Cu")
		(net "H_PM_SYNC_GTL")
	)
	(segment
		(start 314.613036 -67.56781)
		(end 314.321444 -67.56781)
		(width 0.089408)
		(layer "In11.Cu")
		(net "H_PM_SYNC_GTL")
	)
	(segment
		(start 360.322622 -65.477136)
		(end 360.03103 -65.477136)
		(width 0.089408)
		(layer "In11.Cu")
		(net "H_PM_SYNC_GTL")
	)
	(segment
		(start 304.734722 -67.000882)
		(end 304.73142 -67.006724)
		(width 0.089408)
		(layer "In11.Cu")
		(net "H_PM_SYNC_GTL")
	)
	(segment
		(start 328.814684 -68.274184)
		(end 328.814684 -67.657218)
		(width 0.089408)
		(layer "In11.Cu")
		(net "H_PM_SYNC_GTL")
	)
	(segment
		(start 355.10851 -65.006728)
		(end 359.803192 -65.006728)
		(width 0.089408)
		(layer "In11.Cu")
		(net "H_PM_SYNC_GTL")
	)
	(segment
		(start 366.032796 -92.76715)
		(end 366.220756 -92.57919)
		(width 0.089408)
		(layer "In11.Cu")
		(net "H_PM_SYNC_GTL")
	)
	(segment
		(start 131.348988 -66.705988)
		(end 131.661408 -66.705988)
		(width 0.0889)
		(layer "In11.Cu")
		(net "H_PM_SYNC_GTL")
	)
	(segment
		(start 325.05142 -67.657218)
		(end 324.962012 -67.56781)
		(width 0.089408)
		(layer "In11.Cu")
		(net "H_PM_SYNC_GTL")
	)
	(segment
		(start 320.817748 -67.657218)
		(end 320.817748 -68.274184)
		(width 0.089408)
		(layer "In11.Cu")
		(net "H_PM_SYNC_GTL")
	)
	(segment
		(start 357.208582 -65.477136)
		(end 357.119174 -65.566544)
		(width 0.089408)
		(layer "In11.Cu")
		(net "H_PM_SYNC_GTL")
	)
	(segment
		(start 318.084708 -67.56781)
		(end 317.9953 -67.657218)
		(width 0.089408)
		(layer "In11.Cu")
		(net "H_PM_SYNC_GTL")
	)
	(segment
		(start 177.08245 -117.05717)
		(end 176.993042 -117.146578)
		(width 0.089408)
		(layer "In11.Cu")
		(net "H_PM_SYNC_GTL")
	)
	(segment
		(start 359.941622 -66.31051)
		(end 359.852214 -66.399918)
		(width 0.089408)
		(layer "In11.Cu")
		(net "H_PM_SYNC_GTL")
	)
	(segment
		(start 142.494254 -70.172834)
		(end 163.772342 -91.450922)
		(width 0.089408)
		(layer "In11.Cu")
		(net "H_PM_SYNC_GTL")
	)
	(segment
		(start 361.107736 -65.477136)
		(end 360.971846 -65.477136)
		(width 0.089408)
		(layer "In11.Cu")
		(net "H_PM_SYNC_GTL")
	)
	(segment
		(start 183.073294 -128.88214)
		(end 183.405018 -128.88214)
		(width 0.089408)
		(layer "In11.Cu")
		(net "H_PM_SYNC_GTL")
	)
	(segment
		(start 315.64326 -68.274184)
		(end 315.64326 -67.657218)
		(width 0.089408)
		(layer "In11.Cu")
		(net "H_PM_SYNC_GTL")
	)
	(segment
		(start 177.762408 -112.263682)
		(end 177.673 -112.35309)
		(width 0.089408)
		(layer "In11.Cu")
		(net "H_PM_SYNC_GTL")
	)
	(segment
		(start 177.762408 -110.090458)
		(end 177.762408 -110.38205)
		(width 0.089408)
		(layer "In11.Cu")
		(net "H_PM_SYNC_GTL")
	)
	(segment
		(start 177.673 -117.997986)
		(end 177.08245 -117.997986)
		(width 0.089408)
		(layer "In11.Cu")
		(net "H_PM_SYNC_GTL")
	)
	(segment
		(start 330.720446 -67.56781)
		(end 329.3745 -67.56781)
		(width 0.089408)
		(layer "In11.Cu")
		(net "H_PM_SYNC_GTL")
	)
	(segment
		(start 176.993042 -111.501682)
		(end 176.993042 -111.793274)
		(width 0.089408)
		(layer "In11.Cu")
		(net "H_PM_SYNC_GTL")
	)
	(segment
		(start 176.993042 -109.911642)
		(end 177.08245 -110.00105)
		(width 0.089408)
		(layer "In11.Cu")
		(net "H_PM_SYNC_GTL")
	)
	(segment
		(start 356.559358 -65.477136)
		(end 355.093016 -65.477136)
		(width 0.089408)
		(layer "In11.Cu")
		(net "H_PM_SYNC_GTL")
	)
	(segment
		(start 321.669156 -68.363592)
		(end 321.377564 -68.363592)
		(width 0.089408)
		(layer "In11.Cu")
		(net "H_PM_SYNC_GTL")
	)
	(segment
		(start 297.520868 -67.20078)
		(end 296.757598 -67.20078)
		(width 0.089408)
		(layer "In11.Cu")
		(net "H_PM_SYNC_GTL")
	)
	(segment
		(start 365.349028 -91.58097)
		(end 365.222536 -91.58097)
		(width 0.089408)
		(layer "In11.Cu")
		(net "H_PM_SYNC_GTL")
	)
	(segment
		(start 326.933052 -67.657218)
		(end 326.843644 -67.56781)
		(width 0.089408)
		(layer "In11.Cu")
		(net "H_PM_SYNC_GTL")
	)
	(segment
		(start 325.521828 -67.657218)
		(end 325.521828 -68.274184)
		(width 0.089408)
		(layer "In11.Cu")
		(net "H_PM_SYNC_GTL")
	)
	(segment
		(start 358.05999 -66.31051)
		(end 357.970582 -66.399918)
		(width 0.089408)
		(layer "In11.Cu")
		(net "H_PM_SYNC_GTL")
	)
	(segment
		(start 177.762408 -128.638808)
		(end 178.8668 -129.7432)
		(width 0.089408)
		(layer "In11.Cu")
		(net "H_PM_SYNC_GTL")
	)
	(segment
		(start 323.640196 -68.274184)
		(end 323.550788 -68.363592)
		(width 0.089408)
		(layer "In11.Cu")
		(net "H_PM_SYNC_GTL")
	)
	(segment
		(start 177.673 -112.35309)
		(end 177.08245 -112.35309)
		(width 0.089408)
		(layer "In11.Cu")
		(net "H_PM_SYNC_GTL")
	)
	(segment
		(start 183.598058 -129.07518)
		(end 184.513474 -129.07518)
		(width 0.089408)
		(layer "In11.Cu")
		(net "H_PM_SYNC_GTL")
	)
	(segment
		(start 177.762408 -116.967762)
		(end 177.673 -117.05717)
		(width 0.089408)
		(layer "In11.Cu")
		(net "H_PM_SYNC_GTL")
	)
	(segment
		(start 329.285092 -67.657218)
		(end 329.285092 -68.274184)
		(width 0.089408)
		(layer "In11.Cu")
		(net "H_PM_SYNC_GTL")
	)
	(segment
		(start 177.08245 -112.823498)
		(end 177.673 -112.823498)
		(width 0.089408)
		(layer "In11.Cu")
		(net "H_PM_SYNC_GTL")
	)
	(segment
		(start 130.519678 -66.263774)
		(end 130.906774 -66.263774)
		(width 0.0889)
		(layer "In11.Cu")
		(net "H_PM_SYNC_GTL")
	)
	(segment
		(start 177.762408 -115.735354)
		(end 177.762408 -116.026946)
		(width 0.089408)
		(layer "In11.Cu")
		(net "H_PM_SYNC_GTL")
	)
	(segment
		(start 177.08245 -112.35309)
		(end 176.993042 -112.442498)
		(width 0.089408)
		(layer "In11.Cu")
		(net "H_PM_SYNC_GTL")
	)
	(segment
		(start 177.762408 -116.67617)
		(end 177.762408 -116.967762)
		(width 0.089408)
		(layer "In11.Cu")
		(net "H_PM_SYNC_GTL")
	)
	(segment
		(start 322.69938 -67.657218)
		(end 322.69938 -68.274184)
		(width 0.089408)
		(layer "In11.Cu")
		(net "H_PM_SYNC_GTL")
	)
	(segment
		(start 319.317116 -67.56781)
		(end 319.025524 -67.56781)
		(width 0.089408)
		(layer "In11.Cu")
		(net "H_PM_SYNC_GTL")
	)
	(segment
		(start 358.149398 -65.477136)
		(end 358.05999 -65.566544)
		(width 0.089408)
		(layer "In11.Cu")
		(net "H_PM_SYNC_GTL")
	)
	(segment
		(start 177.08245 -115.175538)
		(end 176.993042 -115.264946)
		(width 0.089408)
		(layer "In11.Cu")
		(net "H_PM_SYNC_GTL")
	)
	(segment
		(start 325.992236 -68.274184)
		(end 325.992236 -67.657218)
		(width 0.089408)
		(layer "In11.Cu")
		(net "H_PM_SYNC_GTL")
	)
	(segment
		(start 177.673 -115.645946)
		(end 177.762408 -115.735354)
		(width 0.089408)
		(layer "In11.Cu")
		(net "H_PM_SYNC_GTL")
	)
	(segment
		(start 367.0935 -93.325442)
		(end 366.679988 -92.91193)
		(width 0.089408)
		(layer "In11.Cu")
		(net "H_PM_SYNC_GTL")
	)
	(segment
		(start 366.032796 -92.893642)
		(end 366.032796 -92.76715)
		(width 0.089408)
		(layer "In11.Cu")
		(net "H_PM_SYNC_GTL")
	)
	(segment
		(start 177.762408 -111.97209)
		(end 177.762408 -112.263682)
		(width 0.089408)
		(layer "In11.Cu")
		(net "H_PM_SYNC_GTL")
	)
	(segment
		(start 176.993042 -108.679234)
		(end 176.993042 -108.970826)
		(width 0.089408)
		(layer "In11.Cu")
		(net "H_PM_SYNC_GTL")
	)
	(segment
		(start 325.43242 -68.363592)
		(end 325.140828 -68.363592)
		(width 0.089408)
		(layer "In11.Cu")
		(net "H_PM_SYNC_GTL")
	)
	(segment
		(start 176.993042 -116.497354)
		(end 177.08245 -116.586762)
		(width 0.089408)
		(layer "In11.Cu")
		(net "H_PM_SYNC_GTL")
	)
	(segment
		(start 321.758564 -68.274184)
		(end 321.669156 -68.363592)
		(width 0.089408)
		(layer "In11.Cu")
		(net "H_PM_SYNC_GTL")
	)
	(segment
		(start 176.993042 -118.087394)
		(end 176.993042 -118.378986)
		(width 0.089408)
		(layer "In11.Cu")
		(net "H_PM_SYNC_GTL")
	)
	(segment
		(start 320.257932 -67.56781)
		(end 319.96634 -67.56781)
		(width 0.089408)
		(layer "In11.Cu")
		(net "H_PM_SYNC_GTL")
	)
	(segment
		(start 319.787524 -68.363592)
		(end 319.495932 -68.363592)
		(width 0.089408)
		(layer "In11.Cu")
		(net "H_PM_SYNC_GTL")
	)
	(segment
		(start 177.762408 -111.322866)
		(end 177.673 -111.412274)
		(width 0.089408)
		(layer "In11.Cu")
		(net "H_PM_SYNC_GTL")
	)
	(segment
		(start 177.762408 -117.908578)
		(end 177.673 -117.997986)
		(width 0.089408)
		(layer "In11.Cu")
		(net "H_PM_SYNC_GTL")
	)
	(segment
		(start 315.172852 -67.657218)
		(end 315.172852 -68.274184)
		(width 0.089408)
		(layer "In11.Cu")
		(net "H_PM_SYNC_GTL")
	)
	(segment
		(start 321.198748 -67.56781)
		(end 320.907156 -67.56781)
		(width 0.089408)
		(layer "In11.Cu")
		(net "H_PM_SYNC_GTL")
	)
	(segment
		(start 355.987858 -63.888112)
		(end 355.752146 -63.6524)
		(width 0.089408)
		(layer "In11.Cu")
		(net "H_PM_SYNC_GTL")
	)
	(segment
		(start 358.44099 -65.477136)
		(end 358.149398 -65.477136)
		(width 0.089408)
		(layer "In11.Cu")
		(net "H_PM_SYNC_GTL")
	)
	(segment
		(start 319.406524 -67.657218)
		(end 319.317116 -67.56781)
		(width 0.089408)
		(layer "In11.Cu")
		(net "H_PM_SYNC_GTL")
	)
	(segment
		(start 177.762408 -115.08613)
		(end 177.673 -115.175538)
		(width 0.089408)
		(layer "In11.Cu")
		(net "H_PM_SYNC_GTL")
	)
	(segment
		(start 366.239044 -93.09989)
		(end 366.032796 -92.893642)
		(width 0.089408)
		(layer "In11.Cu")
		(net "H_PM_SYNC_GTL")
	)
	(segment
		(start 366.679988 -92.91193)
		(end 366.553496 -92.91193)
		(width 0.089408)
		(layer "In11.Cu")
		(net "H_PM_SYNC_GTL")
	)
	(segment
		(start 316.584076 -68.274184)
		(end 316.584076 -67.657218)
		(width 0.089408)
		(layer "In11.Cu")
		(net "H_PM_SYNC_GTL")
	)
	(segment
		(start 323.729604 -67.56781)
		(end 323.640196 -67.657218)
		(width 0.089408)
		(layer "In11.Cu")
		(net "H_PM_SYNC_GTL")
	)
	(segment
		(start 324.67042 -67.56781)
		(end 324.581012 -67.657218)
		(width 0.089408)
		(layer "In11.Cu")
		(net "H_PM_SYNC_GTL")
	)
	(segment
		(start 335.694528 -64.13373)
		(end 332.260448 -67.56781)
		(width 0.089408)
		(layer "In11.Cu")
		(net "H_PM_SYNC_GTL")
	)
	(segment
		(start 324.021196 -67.56781)
		(end 323.729604 -67.56781)
		(width 0.089408)
		(layer "In11.Cu")
		(net "H_PM_SYNC_GTL")
	)
	(segment
		(start 327.492868 -67.56781)
		(end 327.40346 -67.657218)
		(width 0.089408)
		(layer "In11.Cu")
		(net "H_PM_SYNC_GTL")
	)
	(segment
		(start 331.190854 -68.357496)
		(end 330.899262 -68.357496)
		(width 0.089408)
		(layer "In11.Cu")
		(net "H_PM_SYNC_GTL")
	)
	(segment
		(start 183.405018 -128.88214)
		(end 183.598058 -129.07518)
		(width 0.089408)
		(layer "In11.Cu")
		(net "H_PM_SYNC_GTL")
	)
	(segment
		(start 357.589582 -65.566544)
		(end 357.500174 -65.477136)
		(width 0.089408)
		(layer "In11.Cu")
		(net "H_PM_SYNC_GTL")
	)
	(segment
		(start 320.436748 -68.363592)
		(end 320.34734 -68.274184)
		(width 0.089408)
		(layer "In11.Cu")
		(net "H_PM_SYNC_GTL")
	)
	(segment
		(start 318.465708 -67.657218)
		(end 318.3763 -67.56781)
		(width 0.089408)
		(layer "In11.Cu")
		(net "H_PM_SYNC_GTL")
	)
	(segment
		(start 177.15611 -104.789986)
		(end 177.15611 -106.478578)
		(width 0.089408)
		(layer "In11.Cu")
		(net "H_PM_SYNC_GTL")
	)
	(segment
		(start 313.380628 -67.56781)
		(end 313.29122 -67.657218)
		(width 0.089408)
		(layer "In11.Cu")
		(net "H_PM_SYNC_GTL")
	)
	(segment
		(start 328.254868 -68.363592)
		(end 327.963276 -68.363592)
		(width 0.089408)
		(layer "In11.Cu")
		(net "H_PM_SYNC_GTL")
	)
	(segment
		(start 177.762408 -114.794538)
		(end 177.762408 -115.08613)
		(width 0.089408)
		(layer "In11.Cu")
		(net "H_PM_SYNC_GTL")
	)
	(segment
		(start 177.15611 -106.478578)
		(end 177.762408 -107.084876)
		(width 0.089408)
		(layer "In11.Cu")
		(net "H_PM_SYNC_GTL")
	)
	(segment
		(start 324.200012 -68.363592)
		(end 324.110604 -68.274184)
		(width 0.089408)
		(layer "In11.Cu")
		(net "H_PM_SYNC_GTL")
	)
	(segment
		(start 365.222536 -91.58097)
		(end 365.034576 -91.76893)
		(width 0.089408)
		(layer "In11.Cu")
		(net "H_PM_SYNC_GTL")
	)
	(segment
		(start 360.41203 -66.31051)
		(end 360.41203 -65.566544)
		(width 0.089408)
		(layer "In11.Cu")
		(net "H_PM_SYNC_GTL")
	)
	(segment
		(start 322.139564 -67.56781)
		(end 321.847972 -67.56781)
		(width 0.089408)
		(layer "In11.Cu")
		(net "H_PM_SYNC_GTL")
	)
	(segment
		(start 176.993042 -117.146578)
		(end 176.993042 -117.43817)
		(width 0.089408)
		(layer "In11.Cu")
		(net "H_PM_SYNC_GTL")
	)
	(segment
		(start 318.555116 -68.363592)
		(end 318.465708 -68.274184)
		(width 0.089408)
		(layer "In11.Cu")
		(net "H_PM_SYNC_GTL")
	)
	(segment
		(start 359.471214 -65.566544)
		(end 359.381806 -65.477136)
		(width 0.089408)
		(layer "In11.Cu")
		(net "H_PM_SYNC_GTL")
	)
	(segment
		(start 177.673 -109.060234)
		(end 177.762408 -109.149642)
		(width 0.089408)
		(layer "In11.Cu")
		(net "H_PM_SYNC_GTL")
	)
	(segment
		(start 357.970582 -66.399918)
		(end 357.67899 -66.399918)
		(width 0.089408)
		(layer "In11.Cu")
		(net "H_PM_SYNC_GTL")
	)
	(segment
		(start 319.876932 -68.274184)
		(end 319.787524 -68.363592)
		(width 0.089408)
		(layer "In11.Cu")
		(net "H_PM_SYNC_GTL")
	)
	(segment
		(start 314.232036 -67.657218)
		(end 314.232036 -68.274184)
		(width 0.089408)
		(layer "In11.Cu")
		(net "H_PM_SYNC_GTL")
	)
	(segment
		(start 321.758564 -67.657218)
		(end 321.758564 -68.274184)
		(width 0.089408)
		(layer "In11.Cu")
		(net "H_PM_SYNC_GTL")
	)
	(segment
		(start 365.034576 -91.76893)
		(end 364.908084 -91.76893)
		(width 0.089408)
		(layer "In11.Cu")
		(net "H_PM_SYNC_GTL")
	)
	(segment
		(start 360.882438 -66.31051)
		(end 360.79303 -66.399918)
		(width 0.089408)
		(layer "In11.Cu")
		(net "H_PM_SYNC_GTL")
	)
	(segment
		(start 312.731404 -67.56781)
		(end 312.492644 -67.56781)
		(width 0.089408)
		(layer "In11.Cu")
		(net "H_PM_SYNC_GTL")
	)
	(segment
		(start 182.212234 -129.7432)
		(end 183.073294 -128.88214)
		(width 0.089408)
		(layer "In11.Cu")
		(net "H_PM_SYNC_GTL")
	)
	(segment
		(start 305.253898 -66.705734)
		(end 305.222656 -66.705734)
		(width 0.089408)
		(layer "In11.Cu")
		(net "H_PM_SYNC_GTL")
	)
	(segment
		(start 364.701836 -91.562682)
		(end 364.701836 -91.43619)
		(width 0.089408)
		(layer "In11.Cu")
		(net "H_PM_SYNC_GTL")
	)
	(segment
		(start 138.518138 -68.687188)
		(end 138.550904 -68.687188)
		(width 0.0889)
		(layer "In11.Cu")
		(net "H_PM_SYNC_GTL")
	)
	(segment
		(start 314.791852 -68.363592)
		(end 314.702444 -68.274184)
		(width 0.089408)
		(layer "In11.Cu")
		(net "H_PM_SYNC_GTL")
	)
	(segment
		(start 177.08245 -109.060234)
		(end 177.673 -109.060234)
		(width 0.089408)
		(layer "In11.Cu")
		(net "H_PM_SYNC_GTL")
	)
	(segment
		(start 356.738174 -66.399918)
		(end 356.648766 -66.31051)
		(width 0.089408)
		(layer "In11.Cu")
		(net "H_PM_SYNC_GTL")
	)
	(segment
		(start 177.762408 -109.441234)
		(end 177.673 -109.530642)
		(width 0.089408)
		(layer "In11.Cu")
		(net "H_PM_SYNC_GTL")
	)
	(segment
		(start 193.31686 -127.085344)
		(end 193.31686 -129.955036)
		(width 0.089408)
		(layer "In11.Cu")
		(net "H_PM_SYNC_GTL")
	)
	(segment
		(start 330.899262 -68.357496)
		(end 330.809854 -68.268088)
		(width 0.089408)
		(layer "In11.Cu")
		(net "H_PM_SYNC_GTL")
	)
	(segment
		(start 358.530398 -66.31051)
		(end 358.530398 -65.566544)
		(width 0.089408)
		(layer "In11.Cu")
		(net "H_PM_SYNC_GTL")
	)
	(segment
		(start 177.08245 -108.589826)
		(end 176.993042 -108.679234)
		(width 0.089408)
		(layer "In11.Cu")
		(net "H_PM_SYNC_GTL")
	)
	(segment
		(start 319.495932 -68.363592)
		(end 319.406524 -68.274184)
		(width 0.089408)
		(layer "In11.Cu")
		(net "H_PM_SYNC_GTL")
	)
	(segment
		(start 359.381806 -65.477136)
		(end 359.090214 -65.477136)
		(width 0.089408)
		(layer "In11.Cu")
		(net "H_PM_SYNC_GTL")
	)
	(segment
		(start 322.609972 -68.363592)
		(end 322.31838 -68.363592)
		(width 0.089408)
		(layer "In11.Cu")
		(net "H_PM_SYNC_GTL")
	)
	(segment
		(start 304.388266 -67.201034)
		(end 304.222404 -67.201034)
		(width 0.089408)
		(layer "In11.Cu")
		(net "H_PM_SYNC_GTL")
	)
	(segment
		(start 306.647088 -66.39814)
		(end 306.459128 -66.21018)
		(width 0.089408)
		(layer "In11.Cu")
		(net "H_PM_SYNC_GTL")
	)
	(segment
		(start 323.259196 -68.363592)
		(end 323.169788 -68.274184)
		(width 0.089408)
		(layer "In11.Cu")
		(net "H_PM_SYNC_GTL")
	)
	(segment
		(start 132.004562 -66.511678)
		(end 132.007864 -66.505836)
		(width 0.0889)
		(layer "In11.Cu")
		(net "H_PM_SYNC_GTL")
	)
	(segment
		(start 317.054484 -67.657218)
		(end 317.054484 -68.274184)
		(width 0.089408)
		(layer "In11.Cu")
		(net "H_PM_SYNC_GTL")
	)
	(segment
		(start 325.140828 -68.363592)
		(end 325.05142 -68.274184)
		(width 0.089408)
		(layer "In11.Cu")
		(net "H_PM_SYNC_GTL")
	)
	(segment
		(start 313.851036 -68.363592)
		(end 313.761628 -68.274184)
		(width 0.089408)
		(layer "In11.Cu")
		(net "H_PM_SYNC_GTL")
	)
	(segment
		(start 318.936116 -68.274184)
		(end 318.846708 -68.363592)
		(width 0.089408)
		(layer "In11.Cu")
		(net "H_PM_SYNC_GTL")
	)
	(segment
		(start 318.465708 -68.274184)
		(end 318.465708 -67.657218)
		(width 0.089408)
		(layer "In11.Cu")
		(net "H_PM_SYNC_GTL")
	)
	(segment
		(start 365.555276 -91.787218)
		(end 365.349028 -91.58097)
		(width 0.089408)
		(layer "In11.Cu")
		(net "H_PM_SYNC_GTL")
	)
	(segment
		(start 330.809854 -68.268088)
		(end 330.809854 -67.657218)
		(width 0.089408)
		(layer "In11.Cu")
		(net "H_PM_SYNC_GTL")
	)
	(segment
		(start 314.702444 -68.274184)
		(end 314.702444 -67.657218)
		(width 0.089408)
		(layer "In11.Cu")
		(net "H_PM_SYNC_GTL")
	)
	(segment
		(start 312.820812 -68.274184)
		(end 312.820812 -67.657218)
		(width 0.089408)
		(layer "In11.Cu")
		(net "H_PM_SYNC_GTL")
	)
	(segment
		(start 177.762408 -111.031274)
		(end 177.762408 -111.322866)
		(width 0.089408)
		(layer "In11.Cu")
		(net "H_PM_SYNC_GTL")
	)
	(segment
		(start 320.817748 -68.274184)
		(end 320.72834 -68.363592)
		(width 0.089408)
		(layer "In11.Cu")
		(net "H_PM_SYNC_GTL")
	)
	(segment
		(start 366.8776 -94.3864)
		(end 367.0935 -94.1705)
		(width 0.089408)
		(layer "In11.Cu")
		(net "H_PM_SYNC_GTL")
	)
	(segment
		(start 308.835044 -66.39814)
		(end 306.647088 -66.39814)
		(width 0.089408)
		(layer "In11.Cu")
		(net "H_PM_SYNC_GTL")
	)
	(segment
		(start 324.491604 -68.363592)
		(end 324.200012 -68.363592)
		(width 0.089408)
		(layer "In11.Cu")
		(net "H_PM_SYNC_GTL")
	)
	(segment
		(start 360.971846 -65.477136)
		(end 360.882438 -65.566544)
		(width 0.089408)
		(layer "In11.Cu")
		(net "H_PM_SYNC_GTL")
	)
	(segment
		(start 358.05999 -65.566544)
		(end 358.05999 -66.31051)
		(width 0.089408)
		(layer "In11.Cu")
		(net "H_PM_SYNC_GTL")
	)
	(segment
		(start 130.906774 -66.263774)
		(end 131.348988 -66.705988)
		(width 0.0889)
		(layer "In11.Cu")
		(net "H_PM_SYNC_GTL")
	)
	(segment
		(start 359.090214 -65.477136)
		(end 359.000806 -65.566544)
		(width 0.089408)
		(layer "In11.Cu")
		(net "H_PM_SYNC_GTL")
	)
	(segment
		(start 177.08245 -111.882682)
		(end 177.673 -111.882682)
		(width 0.089408)
		(layer "In11.Cu")
		(net "H_PM_SYNC_GTL")
	)
	(segment
		(start 177.08245 -114.70513)
		(end 177.673 -114.70513)
		(width 0.089408)
		(layer "In11.Cu")
		(net "H_PM_SYNC_GTL")
	)
	(segment
		(start 323.550788 -68.363592)
		(end 323.259196 -68.363592)
		(width 0.089408)
		(layer "In11.Cu")
		(net "H_PM_SYNC_GTL")
	)
	(segment
		(start 176.993042 -113.383314)
		(end 176.993042 -113.674906)
		(width 0.089408)
		(layer "In11.Cu")
		(net "H_PM_SYNC_GTL")
	)
	(segment
		(start 177.673 -117.05717)
		(end 177.08245 -117.05717)
		(width 0.089408)
		(layer "In11.Cu")
		(net "H_PM_SYNC_GTL")
	)
	(segment
		(start 354.808536 -64.13373)
		(end 335.694528 -64.13373)
		(width 0.089408)
		(layer "In11.Cu")
		(net "H_PM_SYNC_GTL")
	)
	(segment
		(start 132.501894 -66.210434)
		(end 132.53466 -66.210434)
		(width 0.0889)
		(layer "In11.Cu")
		(net "H_PM_SYNC_GTL")
	)
	(segment
		(start 177.673 -110.941866)
		(end 177.762408 -111.031274)
		(width 0.089408)
		(layer "In11.Cu")
		(net "H_PM_SYNC_GTL")
	)
	(segment
		(start 177.673 -110.471458)
		(end 177.08245 -110.471458)
		(width 0.089408)
		(layer "In11.Cu")
		(net "H_PM_SYNC_GTL")
	)
	(segment
		(start 328.725276 -67.56781)
		(end 328.433684 -67.56781)
		(width 0.089408)
		(layer "In11.Cu")
		(net "H_PM_SYNC_GTL")
	)
	(segment
		(start 318.3763 -67.56781)
		(end 318.084708 -67.56781)
		(width 0.089408)
		(layer "In11.Cu")
		(net "H_PM_SYNC_GTL")
	)
	(segment
		(start 306.459128 -66.21018)
		(end 306.084732 -66.21018)
		(width 0.089408)
		(layer "In11.Cu")
		(net "H_PM_SYNC_GTL")
	)
	(arc
		(start 137.688574 -68.191634)
		(mid 137.973998 -68.275101)
		(end 138.182604 -68.487036)
		(width 0.0889)
		(layer "In11.Cu")
		(net "H_PM_SYNC_GTL")
	)
	(arc
		(start 304.73142 -67.006724)
		(mid 304.585454 -67.149123)
		(end 304.388266 -67.201034)
		(width 0.089408)
		(layer "In11.Cu")
		(net "H_PM_SYNC_GTL")
	)
	(arc
		(start 303.505616 -66.705734)
		(mid 303.223714 -66.790597)
		(end 303.017682 -67.000882)
		(width 0.089408)
		(layer "In11.Cu")
		(net "H_PM_SYNC_GTL")
	)
	(arc
		(start 131.661408 -66.705988)
		(mid 131.858569 -66.654029)
		(end 132.004562 -66.511678)
		(width 0.0889)
		(layer "In11.Cu")
		(net "H_PM_SYNC_GTL")
	)
	(arc
		(start 136.465564 -67.496436)
		(mid 136.607247 -67.64024)
		(end 136.801098 -67.696588)
		(width 0.0889)
		(layer "In11.Cu")
		(net "H_PM_SYNC_GTL")
	)
	(arc
		(start 305.222656 -66.705734)
		(mid 304.940754 -66.790597)
		(end 304.734722 -67.000882)
		(width 0.089408)
		(layer "In11.Cu")
		(net "H_PM_SYNC_GTL")
	)
	(arc
		(start 140.267944 -69.677534)
		(mid 140.551161 -69.761815)
		(end 140.758164 -69.972682)
		(width 0.0889)
		(layer "In11.Cu")
		(net "H_PM_SYNC_GTL")
	)
	(arc
		(start 138.182604 -68.487036)
		(mid 138.324287 -68.63084)
		(end 138.518138 -68.687188)
		(width 0.0889)
		(layer "In11.Cu")
		(net "H_PM_SYNC_GTL")
	)
	(arc
		(start 132.53466 -66.210434)
		(mid 132.726302 -66.153268)
		(end 132.866384 -66.010536)
		(width 0.0889)
		(layer "In11.Cu")
		(net "H_PM_SYNC_GTL")
	)
	(arc
		(start 135.607044 -67.001136)
		(mid 135.747123 -67.143872)
		(end 135.938768 -67.201034)
		(width 0.0889)
		(layer "In11.Cu")
		(net "H_PM_SYNC_GTL")
	)
	(arc
		(start 302.159162 -67.496182)
		(mid 301.812816 -67.6964)
		(end 301.46625 -67.496436)
		(width 0.089408)
		(layer "In11.Cu")
		(net "H_PM_SYNC_GTL")
	)
	(arc
		(start 298.371514 -67.696334)
		(mid 298.175482 -67.64095)
		(end 298.03217 -67.496182)
		(width 0.089408)
		(layer "In11.Cu")
		(net "H_PM_SYNC_GTL")
	)
	(arc
		(start 302.650652 -67.20078)
		(mid 302.366691 -67.284898)
		(end 302.159162 -67.496182)
		(width 0.089408)
		(layer "In11.Cu")
		(net "H_PM_SYNC_GTL")
	)
	(arc
		(start 300.442122 -67.496436)
		(mid 300.095556 -67.696527)
		(end 299.74921 -67.496182)
		(width 0.089408)
		(layer "In11.Cu")
		(net "H_PM_SYNC_GTL")
	)
	(arc
		(start 132.007864 -66.505836)
		(mid 132.216472 -66.293904)
		(end 132.501894 -66.210434)
		(width 0.0889)
		(layer "In11.Cu")
		(net "H_PM_SYNC_GTL")
	)
	(arc
		(start 133.399784 -65.715388)
		(mid 133.683001 -65.799669)
		(end 133.890004 -66.010536)
		(width 0.0889)
		(layer "In11.Cu")
		(net "H_PM_SYNC_GTL")
	)
	(arc
		(start 140.758164 -69.972682)
		(mid 140.899847 -70.116486)
		(end 141.093698 -70.172834)
		(width 0.0889)
		(layer "In11.Cu")
		(net "H_PM_SYNC_GTL")
	)
	(arc
		(start 134.254494 -66.210434)
		(mid 134.539918 -66.293901)
		(end 134.748524 -66.505836)
		(width 0.0889)
		(layer "In11.Cu")
		(net "H_PM_SYNC_GTL")
	)
	(arc
		(start 134.748524 -66.505836)
		(mid 134.890207 -66.64964)
		(end 135.084058 -66.705988)
		(width 0.0889)
		(layer "In11.Cu")
		(net "H_PM_SYNC_GTL")
	)
	(arc
		(start 304.04181 -67.000882)
		(mid 303.835773 -66.790604)
		(end 303.553876 -66.705734)
		(width 0.089408)
		(layer "In11.Cu")
		(net "H_PM_SYNC_GTL")
	)
	(arc
		(start 135.971534 -67.201034)
		(mid 136.256958 -67.284501)
		(end 136.465564 -67.496436)
		(width 0.0889)
		(layer "In11.Cu")
		(net "H_PM_SYNC_GTL")
	)
	(arc
		(start 139.899644 -69.477636)
		(mid 140.038388 -69.619669)
		(end 140.22832 -69.677534)
		(width 0.0889)
		(layer "In11.Cu")
		(net "H_PM_SYNC_GTL")
	)
	(arc
		(start 139.041124 -68.982336)
		(mid 139.181203 -69.125072)
		(end 139.372848 -69.182234)
		(width 0.0889)
		(layer "In11.Cu")
		(net "H_PM_SYNC_GTL")
	)
	(arc
		(start 298.03217 -67.496182)
		(mid 297.816107 -67.279973)
		(end 297.520868 -67.20078)
		(width 0.089408)
		(layer "In11.Cu")
		(net "H_PM_SYNC_GTL")
	)
	(arc
		(start 300.937676 -67.201034)
		(mid 300.651427 -67.284195)
		(end 300.442122 -67.496436)
		(width 0.089408)
		(layer "In11.Cu")
		(net "H_PM_SYNC_GTL")
	)
	(arc
		(start 301.46625 -67.496436)
		(mid 301.256945 -67.284196)
		(end 300.970696 -67.201034)
		(width 0.089408)
		(layer "In11.Cu")
		(net "H_PM_SYNC_GTL")
	)
	(arc
		(start 306.084732 -66.21018)
		(mid 305.800771 -66.294298)
		(end 305.593242 -66.505582)
		(width 0.089408)
		(layer "In11.Cu")
		(net "H_PM_SYNC_GTL")
	)
	(arc
		(start 136.833864 -67.696588)
		(mid 137.117081 -67.780869)
		(end 137.324084 -67.991736)
		(width 0.0889)
		(layer "In11.Cu")
		(net "H_PM_SYNC_GTL")
	)
	(arc
		(start 139.405614 -69.182234)
		(mid 139.691038 -69.265701)
		(end 139.899644 -69.477636)
		(width 0.0889)
		(layer "In11.Cu")
		(net "H_PM_SYNC_GTL")
	)
	(arc
		(start 138.550904 -68.687188)
		(mid 138.834121 -68.771469)
		(end 139.041124 -68.982336)
		(width 0.0889)
		(layer "In11.Cu")
		(net "H_PM_SYNC_GTL")
	)
	(arc
		(start 132.866384 -66.010536)
		(mid 133.073388 -65.799672)
		(end 133.356604 -65.715388)
		(width 0.0889)
		(layer "In11.Cu")
		(net "H_PM_SYNC_GTL")
	)
	(arc
		(start 135.116824 -66.705988)
		(mid 135.400041 -66.790269)
		(end 135.607044 -67.001136)
		(width 0.0889)
		(layer "In11.Cu")
		(net "H_PM_SYNC_GTL")
	)
	(arc
		(start 133.890004 -66.010536)
		(mid 134.030083 -66.153272)
		(end 134.221728 -66.210434)
		(width 0.0889)
		(layer "In11.Cu")
		(net "H_PM_SYNC_GTL")
	)
	(arc
		(start 137.324084 -67.991736)
		(mid 137.464163 -68.134472)
		(end 137.655808 -68.191634)
		(width 0.0889)
		(layer "In11.Cu")
		(net "H_PM_SYNC_GTL")
	)
	(arc
		(start 299.74921 -67.496182)
		(mid 299.237146 -67.200423)
		(end 298.725082 -67.496182)
		(width 0.089408)
		(layer "In11.Cu")
		(net "H_PM_SYNC_GTL")
	)
	(arc
		(start 298.725082 -67.496182)
		(mid 298.603154 -67.627216)
		(end 298.436284 -67.692016)
		(width 0.089408)
		(layer "In11.Cu")
		(net "H_PM_SYNC_GTL")
	)
	(arc
		(start 305.593242 -66.505582)
		(mid 305.449931 -66.650353)
		(end 305.253898 -66.705734)
		(width 0.089408)
		(layer "In11.Cu")
		(net "H_PM_SYNC_GTL")
	)
	(arc
		(start 304.10531 -67.08394)
		(mid 304.070824 -67.044502)
		(end 304.04181 -67.000882)
		(width 0.089408)
		(layer "In11.Cu")
		(net "H_PM_SYNC_GTL")
	)
	(arc
		(start 303.017682 -67.000882)
		(mid 302.876525 -67.144267)
		(end 302.683418 -67.20078)
		(width 0.089408)
		(layer "In11.Cu")
		(net "H_PM_SYNC_GTL")
	)
	(segment
		(start 412.9024 -117.3226)
		(end 412.1658 -117.3226)
		(width 0.10795)
		(layer "F.Cu")
		(net "H_PMSYNC_CLK_24M")
	)
	(segment
		(start 413.4612 -117.8814)
		(end 412.9024 -117.3226)
		(width 0.10795)
		(layer "F.Cu")
		(net "H_PMSYNC_CLK_24M")
	)
	(segment
		(start 411.988 -117.1448)
		(end 412.1658 -117.3226)
		(width 0.10795)
		(layer "F.Cu")
		(net "H_PMSYNC_CLK_24M")
	)
	(segment
		(start 410.8196 -117.1448)
		(end 411.988 -117.1448)
		(width 0.10795)
		(layer "F.Cu")
		(net "H_PMSYNC_CLK_24M")
	)
	(segment
		(start 410.2862 -116.6114)
		(end 410.8196 -117.1448)
		(width 0.10795)
		(layer "F.Cu")
		(net "H_PMSYNC_CLK_24M")
	)
	(via
		(at 373.9515 -123.2154)
		(size 0.508)
		(drill 0.254)
		(layers "F.Cu" "B.Cu")
		(net "H_PMSYNC_CLK_24M")
	)
	(via
		(at 159.01416 -24.963374)
		(size 0.508)
		(drill 0.254)
		(layers "F.Cu" "B.Cu")
		(net "H_PMSYNC_CLK_24M")
	)
	(via
		(at 170.307762 -29.434536)
		(size 0.508)
		(drill 0.254)
		(layers "F.Cu" "B.Cu")
		(net "H_PMSYNC_CLK_24M")
	)
	(via
		(at 129.641854 -66.169794)
		(size 0.508)
		(drill 0.254)
		(layers "F.Cu" "B.Cu")
		(net "H_PMSYNC_CLK_24M")
	)
	(via
		(at 294.48506 -66.66484)
		(size 0.508)
		(drill 0.254)
		(layers "F.Cu" "B.Cu")
		(net "H_PMSYNC_CLK_24M")
	)
	(via
		(at 412.1658 -117.3226)
		(size 0.508)
		(drill 0.254)
		(layers "F.Cu" "B.Cu")
		(net "H_PMSYNC_CLK_24M")
	)
	(via
		(at 412.3182 -116.56314)
		(size 0.6604)
		(drill 0.3302)
		(layers "F.Cu" "B.Cu")
		(net "H_PMSYNC_CLK_24M")
	)
	(via
		(at 313.411108 -44.027598)
		(size 0.508)
		(drill 0.254)
		(layers "F.Cu" "B.Cu")
		(net "H_PMSYNC_CLK_24M")
	)
	(segment
		(start 412.1658 -116.71554)
		(end 412.3182 -116.56314)
		(width 0.10795)
		(layer "B.Cu")
		(net "H_PMSYNC_CLK_24M")
	)
	(segment
		(start 294.0939 -66.27368)
		(end 293.87292 -66.27368)
		(width 0.10795)
		(layer "B.Cu")
		(net "H_PMSYNC_CLK_24M")
	)
	(segment
		(start 129.777998 -66.305938)
		(end 129.641854 -66.169794)
		(width 0.10795)
		(layer "B.Cu")
		(net "H_PMSYNC_CLK_24M")
	)
	(segment
		(start 129.777998 -66.788538)
		(end 129.777998 -66.305938)
		(width 0.10795)
		(layer "B.Cu")
		(net "H_PMSYNC_CLK_24M")
	)
	(segment
		(start 412.1658 -117.3226)
		(end 412.1658 -116.71554)
		(width 0.10795)
		(layer "B.Cu")
		(net "H_PMSYNC_CLK_24M")
	)
	(segment
		(start 294.48506 -66.66484)
		(end 294.0939 -66.27368)
		(width 0.10795)
		(layer "B.Cu")
		(net "H_PMSYNC_CLK_24M")
	)
	(segment
		(start 303.531524 -68.687696)
		(end 303.281334 -68.687696)
		(width 0.0889)
		(layer "In2.Cu")
		(net "H_PMSYNC_CLK_24M")
	)
	(segment
		(start 300.292008 -68.74637)
		(end 299.948092 -68.74637)
		(width 0.0889)
		(layer "In2.Cu")
		(net "H_PMSYNC_CLK_24M")
	)
	(segment
		(start 298.876466 -68.397374)
		(end 298.844462 -68.397374)
		(width 0.0889)
		(layer "In2.Cu")
		(net "H_PMSYNC_CLK_24M")
	)
	(segment
		(start 311.322974 -44.602146)
		(end 310.6674 -45.25772)
		(width 0.0889)
		(layer "In2.Cu")
		(net "H_PMSYNC_CLK_24M")
	)
	(segment
		(start 306.120292 -68.191634)
		(end 306.087526 -68.191634)
		(width 0.0889)
		(layer "In2.Cu")
		(net "H_PMSYNC_CLK_24M")
	)
	(segment
		(start 301.191168 -68.300092)
		(end 300.683422 -68.300092)
		(width 0.0889)
		(layer "In2.Cu")
		(net "H_PMSYNC_CLK_24M")
	)
	(segment
		(start 302.363378 -68.358766)
		(end 301.997364 -68.72478)
		(width 0.0889)
		(layer "In2.Cu")
		(net "H_PMSYNC_CLK_24M")
	)
	(segment
		(start 310.6674 -45.25772)
		(end 310.6674 -56.683402)
		(width 0.089408)
		(layer "In2.Cu")
		(net "H_PMSYNC_CLK_24M")
	)
	(segment
		(start 297.618912 -68.211446)
		(end 297.223434 -68.211446)
		(width 0.0889)
		(layer "In2.Cu")
		(net "H_PMSYNC_CLK_24M")
	)
	(segment
		(start 300.426374 -68.612004)
		(end 300.292008 -68.74637)
		(width 0.0889)
		(layer "In2.Cu")
		(net "H_PMSYNC_CLK_24M")
	)
	(segment
		(start 295.802812 -67.147186)
		(end 295.508426 -66.8528)
		(width 0.0889)
		(layer "In2.Cu")
		(net "H_PMSYNC_CLK_24M")
	)
	(segment
		(start 295.802812 -67.254374)
		(end 295.802812 -67.147186)
		(width 0.0889)
		(layer "In2.Cu")
		(net "H_PMSYNC_CLK_24M")
	)
	(segment
		(start 303.281334 -68.687696)
		(end 302.952404 -68.358766)
		(width 0.0889)
		(layer "In2.Cu")
		(net "H_PMSYNC_CLK_24M")
	)
	(segment
		(start 296.29608 -67.747642)
		(end 295.802812 -67.254374)
		(width 0.0889)
		(layer "In2.Cu")
		(net "H_PMSYNC_CLK_24M")
	)
	(segment
		(start 300.426374 -68.55714)
		(end 300.426374 -68.612004)
		(width 0.0889)
		(layer "In2.Cu")
		(net "H_PMSYNC_CLK_24M")
	)
	(segment
		(start 298.478702 -68.763134)
		(end 298.1706 -68.763134)
		(width 0.0889)
		(layer "In2.Cu")
		(net "H_PMSYNC_CLK_24M")
	)
	(segment
		(start 299.948092 -68.74637)
		(end 299.479462 -68.27774)
		(width 0.0889)
		(layer "In2.Cu")
		(net "H_PMSYNC_CLK_24M")
	)
	(segment
		(start 298.844462 -68.397374)
		(end 298.478702 -68.763134)
		(width 0.0889)
		(layer "In2.Cu")
		(net "H_PMSYNC_CLK_24M")
	)
	(segment
		(start 294.67302 -66.8528)
		(end 294.48506 -66.66484)
		(width 0.0889)
		(layer "In2.Cu")
		(net "H_PMSYNC_CLK_24M")
	)
	(segment
		(start 313.411108 -44.027598)
		(end 312.83656 -44.602146)
		(width 0.0889)
		(layer "In2.Cu")
		(net "H_PMSYNC_CLK_24M")
	)
	(segment
		(start 297.223434 -68.211446)
		(end 296.75963 -67.747642)
		(width 0.0889)
		(layer "In2.Cu")
		(net "H_PMSYNC_CLK_24M")
	)
	(segment
		(start 307.162962 -67.696588)
		(end 306.942236 -67.696588)
		(width 0.0889)
		(layer "In2.Cu")
		(net "H_PMSYNC_CLK_24M")
	)
	(segment
		(start 310.6674 -56.683402)
		(end 311.4294 -57.445402)
		(width 0.089408)
		(layer "In2.Cu")
		(net "H_PMSYNC_CLK_24M")
	)
	(segment
		(start 301.997364 -68.72478)
		(end 301.615856 -68.72478)
		(width 0.0889)
		(layer "In2.Cu")
		(net "H_PMSYNC_CLK_24M")
	)
	(segment
		(start 296.75963 -67.747642)
		(end 296.29608 -67.747642)
		(width 0.0889)
		(layer "In2.Cu")
		(net "H_PMSYNC_CLK_24M")
	)
	(segment
		(start 312.83656 -44.602146)
		(end 311.322974 -44.602146)
		(width 0.0889)
		(layer "In2.Cu")
		(net "H_PMSYNC_CLK_24M")
	)
	(segment
		(start 295.508426 -66.8528)
		(end 294.67302 -66.8528)
		(width 0.0889)
		(layer "In2.Cu")
		(net "H_PMSYNC_CLK_24M")
	)
	(segment
		(start 307.567838 -67.291712)
		(end 307.162962 -67.696588)
		(width 0.0889)
		(layer "In2.Cu")
		(net "H_PMSYNC_CLK_24M")
	)
	(segment
		(start 298.9961 -68.27774)
		(end 298.876466 -68.397374)
		(width 0.0889)
		(layer "In2.Cu")
		(net "H_PMSYNC_CLK_24M")
	)
	(segment
		(start 304.403252 -69.182234)
		(end 304.37328 -69.182234)
		(width 0.0889)
		(layer "In2.Cu")
		(net "H_PMSYNC_CLK_24M")
	)
	(segment
		(start 299.479462 -68.27774)
		(end 298.9961 -68.27774)
		(width 0.0889)
		(layer "In2.Cu")
		(net "H_PMSYNC_CLK_24M")
	)
	(segment
		(start 311.4294 -57.445402)
		(end 311.4294 -62.909958)
		(width 0.089408)
		(layer "In2.Cu")
		(net "H_PMSYNC_CLK_24M")
	)
	(segment
		(start 301.615856 -68.72478)
		(end 301.191168 -68.300092)
		(width 0.0889)
		(layer "In2.Cu")
		(net "H_PMSYNC_CLK_24M")
	)
	(segment
		(start 300.683422 -68.300092)
		(end 300.426374 -68.55714)
		(width 0.0889)
		(layer "In2.Cu")
		(net "H_PMSYNC_CLK_24M")
	)
	(segment
		(start 311.4294 -62.909958)
		(end 307.567838 -66.77152)
		(width 0.089408)
		(layer "In2.Cu")
		(net "H_PMSYNC_CLK_24M")
	)
	(segment
		(start 305.257962 -68.687188)
		(end 305.225196 -68.687188)
		(width 0.0889)
		(layer "In2.Cu")
		(net "H_PMSYNC_CLK_24M")
	)
	(segment
		(start 302.952404 -68.358766)
		(end 302.363378 -68.358766)
		(width 0.0889)
		(layer "In2.Cu")
		(net "H_PMSYNC_CLK_24M")
	)
	(segment
		(start 307.567838 -66.77152)
		(end 307.567838 -67.291712)
		(width 0.0889)
		(layer "In2.Cu")
		(net "H_PMSYNC_CLK_24M")
	)
	(segment
		(start 298.1706 -68.763134)
		(end 297.618912 -68.211446)
		(width 0.0889)
		(layer "In2.Cu")
		(net "H_PMSYNC_CLK_24M")
	)
	(arc
		(start 306.087526 -68.191634)
		(mid 305.802102 -68.275101)
		(end 305.593496 -68.487036)
		(width 0.0889)
		(layer "In2.Cu")
		(net "H_PMSYNC_CLK_24M")
	)
	(arc
		(start 304.734976 -68.982336)
		(mid 304.594897 -69.125072)
		(end 304.403252 -69.182234)
		(width 0.0889)
		(layer "In2.Cu")
		(net "H_PMSYNC_CLK_24M")
	)
	(arc
		(start 305.225196 -68.687188)
		(mid 304.941979 -68.771469)
		(end 304.734976 -68.982336)
		(width 0.0889)
		(layer "In2.Cu")
		(net "H_PMSYNC_CLK_24M")
	)
	(arc
		(start 304.041556 -68.982336)
		(mid 303.826033 -68.766654)
		(end 303.531524 -68.687696)
		(width 0.0889)
		(layer "In2.Cu")
		(net "H_PMSYNC_CLK_24M")
	)
	(arc
		(start 305.593496 -68.487036)
		(mid 305.451813 -68.63084)
		(end 305.257962 -68.687188)
		(width 0.0889)
		(layer "In2.Cu")
		(net "H_PMSYNC_CLK_24M")
	)
	(arc
		(start 304.37328 -69.182234)
		(mid 304.181638 -69.125068)
		(end 304.041556 -68.982336)
		(width 0.0889)
		(layer "In2.Cu")
		(net "H_PMSYNC_CLK_24M")
	)
	(arc
		(start 306.942236 -67.696588)
		(mid 306.659019 -67.780869)
		(end 306.452016 -67.991736)
		(width 0.0889)
		(layer "In2.Cu")
		(net "H_PMSYNC_CLK_24M")
	)
	(arc
		(start 306.452016 -67.991736)
		(mid 306.311937 -68.134472)
		(end 306.120292 -68.191634)
		(width 0.0889)
		(layer "In2.Cu")
		(net "H_PMSYNC_CLK_24M")
	)
	(segment
		(start 161.104834 -24.77643)
		(end 160.91789 -24.963374)
		(width 0.089408)
		(layer "In4.Cu")
		(net "H_PMSYNC_CLK_24M")
	)
	(segment
		(start 398.825466 -123.114054)
		(end 403.252686 -123.114054)
		(width 0.089408)
		(layer "In4.Cu")
		(net "H_PMSYNC_CLK_24M")
	)
	(segment
		(start 411.708854 -116.865654)
		(end 412.1658 -117.3226)
		(width 0.089408)
		(layer "In4.Cu")
		(net "H_PMSYNC_CLK_24M")
	)
	(segment
		(start 375.98096 -123.880372)
		(end 377.052586 -123.880372)
		(width 0.089408)
		(layer "In4.Cu")
		(net "H_PMSYNC_CLK_24M")
	)
	(segment
		(start 408.62377 -117.36451)
		(end 409.122626 -116.865654)
		(width 0.089408)
		(layer "In4.Cu")
		(net "H_PMSYNC_CLK_24M")
	)
	(segment
		(start 408.62377 -117.74297)
		(end 408.62377 -117.36451)
		(width 0.089408)
		(layer "In4.Cu")
		(net "H_PMSYNC_CLK_24M")
	)
	(segment
		(start 377.052586 -123.880372)
		(end 377.510294 -123.422664)
		(width 0.089408)
		(layer "In4.Cu")
		(net "H_PMSYNC_CLK_24M")
	)
	(segment
		(start 403.252686 -123.114054)
		(end 408.62377 -117.74297)
		(width 0.089408)
		(layer "In4.Cu")
		(net "H_PMSYNC_CLK_24M")
	)
	(segment
		(start 409.122626 -116.865654)
		(end 411.708854 -116.865654)
		(width 0.089408)
		(layer "In4.Cu")
		(net "H_PMSYNC_CLK_24M")
	)
	(segment
		(start 373.9515 -123.2154)
		(end 375.315988 -123.2154)
		(width 0.089408)
		(layer "In4.Cu")
		(net "H_PMSYNC_CLK_24M")
	)
	(segment
		(start 160.91789 -24.963374)
		(end 159.01416 -24.963374)
		(width 0.089408)
		(layer "In4.Cu")
		(net "H_PMSYNC_CLK_24M")
	)
	(segment
		(start 170.307762 -29.186632)
		(end 165.89756 -24.77643)
		(width 0.089408)
		(layer "In4.Cu")
		(net "H_PMSYNC_CLK_24M")
	)
	(segment
		(start 170.307762 -29.434536)
		(end 170.307762 -29.186632)
		(width 0.089408)
		(layer "In4.Cu")
		(net "H_PMSYNC_CLK_24M")
	)
	(segment
		(start 398.516856 -123.422664)
		(end 398.825466 -123.114054)
		(width 0.089408)
		(layer "In4.Cu")
		(net "H_PMSYNC_CLK_24M")
	)
	(segment
		(start 375.315988 -123.2154)
		(end 375.98096 -123.880372)
		(width 0.089408)
		(layer "In4.Cu")
		(net "H_PMSYNC_CLK_24M")
	)
	(segment
		(start 165.89756 -24.77643)
		(end 161.104834 -24.77643)
		(width 0.089408)
		(layer "In4.Cu")
		(net "H_PMSYNC_CLK_24M")
	)
	(segment
		(start 377.510294 -123.422664)
		(end 398.516856 -123.422664)
		(width 0.089408)
		(layer "In4.Cu")
		(net "H_PMSYNC_CLK_24M")
	)
	(segment
		(start 260.692646 -31.23311)
		(end 259.381752 -29.922216)
		(width 0.089408)
		(layer "In9.Cu")
		(net "H_PMSYNC_CLK_24M")
	)
	(segment
		(start 148.04136 -34.093912)
		(end 129.035048 -34.093912)
		(width 0.089408)
		(layer "In9.Cu")
		(net "H_PMSYNC_CLK_24M")
	)
	(segment
		(start 242.179856 -30.728158)
		(end 223.362266 -30.728158)
		(width 0.089408)
		(layer "In9.Cu")
		(net "H_PMSYNC_CLK_24M")
	)
	(segment
		(start 129.641854 -65.473072)
		(end 129.641854 -66.169794)
		(width 0.089408)
		(layer "In9.Cu")
		(net "H_PMSYNC_CLK_24M")
	)
	(segment
		(start 126.623572 -62.742318)
		(end 127.190754 -63.3095)
		(width 0.089408)
		(layer "In9.Cu")
		(net "H_PMSYNC_CLK_24M")
	)
	(segment
		(start 129.035048 -34.093912)
		(end 123.22429 -39.90467)
		(width 0.089408)
		(layer "In9.Cu")
		(net "H_PMSYNC_CLK_24M")
	)
	(segment
		(start 221.686628 -29.05252)
		(end 187.987686 -29.05252)
		(width 0.089408)
		(layer "In9.Cu")
		(net "H_PMSYNC_CLK_24M")
	)
	(segment
		(start 263.891268 -32.859218)
		(end 262.26516 -31.23311)
		(width 0.089408)
		(layer "In9.Cu")
		(net "H_PMSYNC_CLK_24M")
	)
	(segment
		(start 128.687068 -64.518286)
		(end 129.641854 -65.473072)
		(width 0.089408)
		(layer "In9.Cu")
		(net "H_PMSYNC_CLK_24M")
	)
	(segment
		(start 123.007374 -61.356748)
		(end 123.402344 -61.751718)
		(width 0.089408)
		(layer "In9.Cu")
		(net "H_PMSYNC_CLK_24M")
	)
	(segment
		(start 153.052272 -29.083)
		(end 148.04136 -34.093912)
		(width 0.089408)
		(layer "In9.Cu")
		(net "H_PMSYNC_CLK_24M")
	)
	(segment
		(start 155.128214 -28.178252)
		(end 154.223466 -29.083)
		(width 0.089408)
		(layer "In9.Cu")
		(net "H_PMSYNC_CLK_24M")
	)
	(segment
		(start 223.362266 -30.728158)
		(end 221.686628 -29.05252)
		(width 0.089408)
		(layer "In9.Cu")
		(net "H_PMSYNC_CLK_24M")
	)
	(segment
		(start 187.987686 -29.05252)
		(end 187.978542 -29.043376)
		(width 0.089408)
		(layer "In9.Cu")
		(net "H_PMSYNC_CLK_24M")
	)
	(segment
		(start 156.39923 -28.178252)
		(end 155.128214 -28.178252)
		(width 0.089408)
		(layer "In9.Cu")
		(net "H_PMSYNC_CLK_24M")
	)
	(segment
		(start 259.381752 -29.922216)
		(end 242.985798 -29.922216)
		(width 0.089408)
		(layer "In9.Cu")
		(net "H_PMSYNC_CLK_24M")
	)
	(segment
		(start 128.162558 -63.925958)
		(end 128.59766 -63.925958)
		(width 0.089408)
		(layer "In9.Cu")
		(net "H_PMSYNC_CLK_24M")
	)
	(segment
		(start 125.869192 -62.32906)
		(end 126.28245 -62.742318)
		(width 0.089408)
		(layer "In9.Cu")
		(net "H_PMSYNC_CLK_24M")
	)
	(segment
		(start 121.336562 -60.405518)
		(end 121.776998 -60.845954)
		(width 0.089408)
		(layer "In9.Cu")
		(net "H_PMSYNC_CLK_24M")
	)
	(segment
		(start 124.654818 -62.32906)
		(end 125.869192 -62.32906)
		(width 0.089408)
		(layer "In9.Cu")
		(net "H_PMSYNC_CLK_24M")
	)
	(segment
		(start 128.59766 -63.925958)
		(end 128.687068 -64.015366)
		(width 0.089408)
		(layer "In9.Cu")
		(net "H_PMSYNC_CLK_24M")
	)
	(segment
		(start 127.190754 -63.3095)
		(end 127.5461 -63.3095)
		(width 0.089408)
		(layer "In9.Cu")
		(net "H_PMSYNC_CLK_24M")
	)
	(segment
		(start 121.067322 -60.405518)
		(end 121.336562 -60.405518)
		(width 0.089408)
		(layer "In9.Cu")
		(net "H_PMSYNC_CLK_24M")
	)
	(segment
		(start 126.28245 -62.742318)
		(end 126.623572 -62.742318)
		(width 0.089408)
		(layer "In9.Cu")
		(net "H_PMSYNC_CLK_24M")
	)
	(segment
		(start 127.5461 -63.3095)
		(end 128.162558 -63.925958)
		(width 0.089408)
		(layer "In9.Cu")
		(net "H_PMSYNC_CLK_24M")
	)
	(segment
		(start 262.26516 -31.23311)
		(end 260.692646 -31.23311)
		(width 0.089408)
		(layer "In9.Cu")
		(net "H_PMSYNC_CLK_24M")
	)
	(segment
		(start 120.675908 -52.646072)
		(end 120.675908 -60.014104)
		(width 0.089408)
		(layer "In9.Cu")
		(net "H_PMSYNC_CLK_24M")
	)
	(segment
		(start 122.630438 -61.356748)
		(end 123.007374 -61.356748)
		(width 0.089408)
		(layer "In9.Cu")
		(net "H_PMSYNC_CLK_24M")
	)
	(segment
		(start 154.223466 -29.083)
		(end 153.052272 -29.083)
		(width 0.089408)
		(layer "In9.Cu")
		(net "H_PMSYNC_CLK_24M")
	)
	(segment
		(start 170.51655 -29.434536)
		(end 170.307762 -29.434536)
		(width 0.089408)
		(layer "In9.Cu")
		(net "H_PMSYNC_CLK_24M")
	)
	(segment
		(start 302.894746 -32.859218)
		(end 263.891268 -32.859218)
		(width 0.089408)
		(layer "In9.Cu")
		(net "H_PMSYNC_CLK_24M")
	)
	(segment
		(start 242.985798 -29.922216)
		(end 242.179856 -30.728158)
		(width 0.089408)
		(layer "In9.Cu")
		(net "H_PMSYNC_CLK_24M")
	)
	(segment
		(start 313.411108 -43.37558)
		(end 302.894746 -32.859218)
		(width 0.089408)
		(layer "In9.Cu")
		(net "H_PMSYNC_CLK_24M")
	)
	(segment
		(start 313.411108 -44.027598)
		(end 313.411108 -43.37558)
		(width 0.089408)
		(layer "In9.Cu")
		(net "H_PMSYNC_CLK_24M")
	)
	(segment
		(start 170.90771 -29.043376)
		(end 170.51655 -29.434536)
		(width 0.089408)
		(layer "In9.Cu")
		(net "H_PMSYNC_CLK_24M")
	)
	(segment
		(start 123.402344 -61.751718)
		(end 124.077476 -61.751718)
		(width 0.089408)
		(layer "In9.Cu")
		(net "H_PMSYNC_CLK_24M")
	)
	(segment
		(start 121.776998 -60.845954)
		(end 122.119644 -60.845954)
		(width 0.089408)
		(layer "In9.Cu")
		(net "H_PMSYNC_CLK_24M")
	)
	(segment
		(start 159.01416 -25.563322)
		(end 156.39923 -28.178252)
		(width 0.089408)
		(layer "In9.Cu")
		(net "H_PMSYNC_CLK_24M")
	)
	(segment
		(start 159.01416 -24.963374)
		(end 159.01416 -25.563322)
		(width 0.089408)
		(layer "In9.Cu")
		(net "H_PMSYNC_CLK_24M")
	)
	(segment
		(start 120.675908 -60.014104)
		(end 121.067322 -60.405518)
		(width 0.089408)
		(layer "In9.Cu")
		(net "H_PMSYNC_CLK_24M")
	)
	(segment
		(start 187.978542 -29.043376)
		(end 170.90771 -29.043376)
		(width 0.089408)
		(layer "In9.Cu")
		(net "H_PMSYNC_CLK_24M")
	)
	(segment
		(start 123.22429 -50.09769)
		(end 120.675908 -52.646072)
		(width 0.089408)
		(layer "In9.Cu")
		(net "H_PMSYNC_CLK_24M")
	)
	(segment
		(start 128.687068 -64.015366)
		(end 128.687068 -64.518286)
		(width 0.089408)
		(layer "In9.Cu")
		(net "H_PMSYNC_CLK_24M")
	)
	(segment
		(start 122.119644 -60.845954)
		(end 122.630438 -61.356748)
		(width 0.089408)
		(layer "In9.Cu")
		(net "H_PMSYNC_CLK_24M")
	)
	(segment
		(start 123.22429 -39.90467)
		(end 123.22429 -50.09769)
		(width 0.089408)
		(layer "In9.Cu")
		(net "H_PMSYNC_CLK_24M")
	)
	(segment
		(start 124.077476 -61.751718)
		(end 124.654818 -62.32906)
		(width 0.089408)
		(layer "In9.Cu")
		(net "H_PMSYNC_CLK_24M")
	)
	(segment
		(start 303.505616 -67.696334)
		(end 305.319684 -67.696334)
		(width 0.089408)
		(layer "In11.Cu")
		(net "H_PMSYNC_CLK_24M")
	)
	(segment
		(start 331.635354 -69.1134)
		(end 336.004408 -64.744346)
		(width 0.089408)
		(layer "In11.Cu")
		(net "H_PMSYNC_CLK_24M")
	)
	(segment
		(start 372.233444 -107.08386)
		(end 373.130826 -107.981242)
		(width 0.089408)
		(layer "In11.Cu")
		(net "H_PMSYNC_CLK_24M")
	)
	(segment
		(start 297.519598 -68.286884)
		(end 297.532298 -68.286884)
		(width 0.089408)
		(layer "In11.Cu")
		(net "H_PMSYNC_CLK_24M")
	)
	(segment
		(start 296.66184 -67.791838)
		(end 296.67835 -67.791838)
		(width 0.089408)
		(layer "In11.Cu")
		(net "H_PMSYNC_CLK_24M")
	)
	(segment
		(start 371.823488 -107.08386)
		(end 372.233444 -107.08386)
		(width 0.089408)
		(layer "In11.Cu")
		(net "H_PMSYNC_CLK_24M")
	)
	(segment
		(start 373.868188 -107.981242)
		(end 374.673622 -108.786676)
		(width 0.089408)
		(layer "In11.Cu")
		(net "H_PMSYNC_CLK_24M")
	)
	(segment
		(start 295.495472 -66.8528)
		(end 296.325798 -67.683126)
		(width 0.089408)
		(layer "In11.Cu")
		(net "H_PMSYNC_CLK_24M")
	)
	(segment
		(start 364.257082 -84.813394)
		(end 364.257082 -99.517454)
		(width 0.089408)
		(layer "In11.Cu")
		(net "H_PMSYNC_CLK_24M")
	)
	(segment
		(start 374.673622 -108.786676)
		(end 374.673622 -109.24413)
		(width 0.089408)
		(layer "In11.Cu")
		(net "H_PMSYNC_CLK_24M")
	)
	(segment
		(start 302.650652 -68.19138)
		(end 302.683418 -68.19138)
		(width 0.089408)
		(layer "In11.Cu")
		(net "H_PMSYNC_CLK_24M")
	)
	(segment
		(start 361.89158 -66.717926)
		(end 362.8644 -67.690746)
		(width 0.089408)
		(layer "In11.Cu")
		(net "H_PMSYNC_CLK_24M")
	)
	(segment
		(start 362.8644 -67.690746)
		(end 362.8644 -68.053966)
		(width 0.089408)
		(layer "In11.Cu")
		(net "H_PMSYNC_CLK_24M")
	)
	(segment
		(start 363.502702 -84.059014)
		(end 364.257082 -84.813394)
		(width 0.089408)
		(layer "In11.Cu")
		(net "H_PMSYNC_CLK_24M")
	)
	(segment
		(start 362.8644 -68.053966)
		(end 361.6452 -69.273166)
		(width 0.089408)
		(layer "In11.Cu")
		(net "H_PMSYNC_CLK_24M")
	)
	(segment
		(start 361.6452 -69.273166)
		(end 361.6452 -71.99757)
		(width 0.089408)
		(layer "In11.Cu")
		(net "H_PMSYNC_CLK_24M")
	)
	(segment
		(start 300.927262 -68.191634)
		(end 300.98111 -68.191634)
		(width 0.089408)
		(layer "In11.Cu")
		(net "H_PMSYNC_CLK_24M")
	)
	(segment
		(start 308.949344 -69.1134)
		(end 331.635354 -69.1134)
		(width 0.089408)
		(layer "In11.Cu")
		(net "H_PMSYNC_CLK_24M")
	)
	(segment
		(start 294.67302 -66.8528)
		(end 295.495472 -66.8528)
		(width 0.089408)
		(layer "In11.Cu")
		(net "H_PMSYNC_CLK_24M")
	)
	(segment
		(start 363.502702 -80.131666)
		(end 363.502702 -84.059014)
		(width 0.089408)
		(layer "In11.Cu")
		(net "H_PMSYNC_CLK_24M")
	)
	(segment
		(start 306.956714 -67.696334)
		(end 307.532278 -67.696334)
		(width 0.089408)
		(layer "In11.Cu")
		(net "H_PMSYNC_CLK_24M")
	)
	(segment
		(start 364.257082 -99.517454)
		(end 371.823488 -107.08386)
		(width 0.089408)
		(layer "In11.Cu")
		(net "H_PMSYNC_CLK_24M")
	)
	(segment
		(start 364.036102 -77.45984)
		(end 363.502702 -80.131666)
		(width 0.089408)
		(layer "In11.Cu")
		(net "H_PMSYNC_CLK_24M")
	)
	(segment
		(start 306.084732 -67.20078)
		(end 306.12588 -67.20078)
		(width 0.089408)
		(layer "In11.Cu")
		(net "H_PMSYNC_CLK_24M")
	)
	(segment
		(start 374.815862 -122.351038)
		(end 373.9515 -123.2154)
		(width 0.089408)
		(layer "In11.Cu")
		(net "H_PMSYNC_CLK_24M")
	)
	(segment
		(start 364.036102 -74.388472)
		(end 364.036102 -77.45984)
		(width 0.089408)
		(layer "In11.Cu")
		(net "H_PMSYNC_CLK_24M")
	)
	(segment
		(start 361.6452 -71.99757)
		(end 364.036102 -74.388472)
		(width 0.089408)
		(layer "In11.Cu")
		(net "H_PMSYNC_CLK_24M")
	)
	(segment
		(start 296.325798 -67.683126)
		(end 296.66184 -67.791838)
		(width 0.089408)
		(layer "In11.Cu")
		(net "H_PMSYNC_CLK_24M")
	)
	(segment
		(start 307.532278 -67.696334)
		(end 308.949344 -69.1134)
		(width 0.089408)
		(layer "In11.Cu")
		(net "H_PMSYNC_CLK_24M")
	)
	(segment
		(start 353.422204 -64.744346)
		(end 356.1588 -66.717926)
		(width 0.089408)
		(layer "In11.Cu")
		(net "H_PMSYNC_CLK_24M")
	)
	(segment
		(start 373.130826 -107.981242)
		(end 373.868188 -107.981242)
		(width 0.089408)
		(layer "In11.Cu")
		(net "H_PMSYNC_CLK_24M")
	)
	(segment
		(start 336.004408 -64.744346)
		(end 353.422204 -64.744346)
		(width 0.089408)
		(layer "In11.Cu")
		(net "H_PMSYNC_CLK_24M")
	)
	(segment
		(start 374.673622 -109.24413)
		(end 374.815862 -109.38637)
		(width 0.089408)
		(layer "In11.Cu")
		(net "H_PMSYNC_CLK_24M")
	)
	(segment
		(start 294.48506 -66.66484)
		(end 294.67302 -66.8528)
		(width 0.089408)
		(layer "In11.Cu")
		(net "H_PMSYNC_CLK_24M")
	)
	(segment
		(start 374.815862 -109.38637)
		(end 374.815862 -122.351038)
		(width 0.089408)
		(layer "In11.Cu")
		(net "H_PMSYNC_CLK_24M")
	)
	(segment
		(start 356.1588 -66.717926)
		(end 361.89158 -66.717926)
		(width 0.089408)
		(layer "In11.Cu")
		(net "H_PMSYNC_CLK_24M")
	)
	(arc
		(start 300.442122 -68.486782)
		(mid 300.646932 -68.277142)
		(end 300.927262 -68.191634)
		(width 0.089408)
		(layer "In11.Cu")
		(net "H_PMSYNC_CLK_24M")
	)
	(arc
		(start 301.46625 -68.486782)
		(mid 301.812706 -68.687)
		(end 302.159162 -68.486782)
		(width 0.089408)
		(layer "In11.Cu")
		(net "H_PMSYNC_CLK_24M")
	)
	(arc
		(start 298.436284 -68.682616)
		(mid 298.603213 -68.617903)
		(end 298.725082 -68.486782)
		(width 0.089408)
		(layer "In11.Cu")
		(net "H_PMSYNC_CLK_24M")
	)
	(arc
		(start 302.159162 -68.486782)
		(mid 302.366691 -68.275498)
		(end 302.650652 -68.19138)
		(width 0.089408)
		(layer "In11.Cu")
		(net "H_PMSYNC_CLK_24M")
	)
	(arc
		(start 305.593242 -67.496182)
		(mid 305.800771 -67.284898)
		(end 306.084732 -67.20078)
		(width 0.089408)
		(layer "In11.Cu")
		(net "H_PMSYNC_CLK_24M")
	)
	(arc
		(start 306.12588 -67.20078)
		(mid 306.409841 -67.284898)
		(end 306.61737 -67.496182)
		(width 0.089408)
		(layer "In11.Cu")
		(net "H_PMSYNC_CLK_24M")
	)
	(arc
		(start 303.017682 -67.991482)
		(mid 303.223719 -67.781204)
		(end 303.505616 -67.696334)
		(width 0.089408)
		(layer "In11.Cu")
		(net "H_PMSYNC_CLK_24M")
	)
	(arc
		(start 300.98111 -68.191634)
		(mid 301.261441 -68.277141)
		(end 301.46625 -68.486782)
		(width 0.089408)
		(layer "In11.Cu")
		(net "H_PMSYNC_CLK_24M")
	)
	(arc
		(start 306.61737 -67.496182)
		(mid 306.760681 -67.640953)
		(end 306.956714 -67.696334)
		(width 0.089408)
		(layer "In11.Cu")
		(net "H_PMSYNC_CLK_24M")
	)
	(arc
		(start 297.949366 -68.534788)
		(mid 298.176337 -68.663053)
		(end 298.436284 -68.682616)
		(width 0.089408)
		(layer "In11.Cu")
		(net "H_PMSYNC_CLK_24M")
	)
	(arc
		(start 298.725082 -68.486782)
		(mid 299.237146 -68.191023)
		(end 299.74921 -68.486782)
		(width 0.089408)
		(layer "In11.Cu")
		(net "H_PMSYNC_CLK_24M")
	)
	(arc
		(start 302.683418 -68.19138)
		(mid 302.876521 -68.134861)
		(end 303.017682 -67.991482)
		(width 0.089408)
		(layer "In11.Cu")
		(net "H_PMSYNC_CLK_24M")
	)
	(arc
		(start 299.74921 -68.486782)
		(mid 300.095666 -68.687)
		(end 300.442122 -68.486782)
		(width 0.089408)
		(layer "In11.Cu")
		(net "H_PMSYNC_CLK_24M")
	)
	(arc
		(start 297.0911 -68.039488)
		(mid 297.272205 -68.220592)
		(end 297.519598 -68.286884)
		(width 0.089408)
		(layer "In11.Cu")
		(net "H_PMSYNC_CLK_24M")
	)
	(arc
		(start 297.532298 -68.286884)
		(mid 297.773255 -68.356289)
		(end 297.949366 -68.534788)
		(width 0.089408)
		(layer "In11.Cu")
		(net "H_PMSYNC_CLK_24M")
	)
	(arc
		(start 305.319684 -67.696334)
		(mid 305.47754 -67.625084)
		(end 305.593242 -67.496182)
		(width 0.089408)
		(layer "In11.Cu")
		(net "H_PMSYNC_CLK_24M")
	)
	(arc
		(start 296.67835 -67.791838)
		(mid 296.916811 -67.862186)
		(end 297.0911 -68.039488)
		(width 0.089408)
		(layer "In11.Cu")
		(net "H_PMSYNC_CLK_24M")
	)
	(segment
		(start 453.609964 -50.792634)
		(end 453.609964 -50.111914)
		(width 0.1143)
		(layer "F.Cu")
		(net "P3E_OCP_CPU0_PE3_C_TXP<3>")
	)
	(segment
		(start 453.340978 -51.875944)
		(end 453.340978 -51.06162)
		(width 0.1143)
		(layer "F.Cu")
		(net "P3E_OCP_CPU0_PE3_C_TXP<3>")
	)
	(segment
		(start 453.609964 -50.111914)
		(end 453.495664 -49.997614)
		(width 0.1143)
		(layer "F.Cu")
		(net "P3E_OCP_CPU0_PE3_C_TXP<3>")
	)
	(segment
		(start 453.340978 -51.06162)
		(end 453.609964 -50.792634)
		(width 0.1143)
		(layer "F.Cu")
		(net "P3E_OCP_CPU0_PE3_C_TXP<3>")
	)
	(segment
		(start 453.495664 -49.997614)
		(end 453.095614 -49.997614)
		(width 0.1143)
		(layer "F.Cu")
		(net "P3E_OCP_CPU0_PE3_C_TXP<3>")
	)
	(via
		(at 453.095614 -49.997614)
		(size 0.508)
		(drill 0.254)
		(layers "F.Cu" "B.Cu")
		(net "P3E_OCP_CPU0_PE3_C_TXP<3>")
	)
	(segment
		(start 453.48525 -50.922682)
		(end 453.609964 -50.797968)
		(width 0.1143)
		(layer "B.Cu")
		(net "P3E_OCP_CPU0_PE3_C_TXP<3>")
	)
	(segment
		(start 453.609964 -50.111914)
		(end 453.495664 -49.997614)
		(width 0.1143)
		(layer "B.Cu")
		(net "P3E_OCP_CPU0_PE3_C_TXP<3>")
	)
	(segment
		(start 453.495664 -49.997614)
		(end 453.095614 -49.997614)
		(width 0.1143)
		(layer "B.Cu")
		(net "P3E_OCP_CPU0_PE3_C_TXP<3>")
	)
	(segment
		(start 453.2122 -51.441858)
		(end 453.2122 -51.036982)
		(width 0.1143)
		(layer "B.Cu")
		(net "P3E_OCP_CPU0_PE3_C_TXP<3>")
	)
	(segment
		(start 453.609964 -50.797968)
		(end 453.609964 -50.111914)
		(width 0.1143)
		(layer "B.Cu")
		(net "P3E_OCP_CPU0_PE3_C_TXP<3>")
	)
	(segment
		(start 453.3265 -50.922682)
		(end 453.48525 -50.922682)
		(width 0.1143)
		(layer "B.Cu")
		(net "P3E_OCP_CPU0_PE3_C_TXP<3>")
	)
	(segment
		(start 453.2122 -51.036982)
		(end 453.3265 -50.922682)
		(width 0.1143)
		(layer "B.Cu")
		(net "P3E_OCP_CPU0_PE3_C_TXP<3>")
	)
	(segment
		(start 456.541124 -50.714402)
		(end 456.810364 -50.445162)
		(width 0.1143)
		(layer "F.Cu")
		(net "P3E_OCP_CPU0_PE3_C_TXP<2>")
	)
	(segment
		(start 456.541124 -51.875944)
		(end 456.541124 -50.714402)
		(width 0.1143)
		(layer "F.Cu")
		(net "P3E_OCP_CPU0_PE3_C_TXP<2>")
	)
	(segment
		(start 456.810364 -50.445162)
		(end 456.810364 -50.111914)
		(width 0.1143)
		(layer "F.Cu")
		(net "P3E_OCP_CPU0_PE3_C_TXP<2>")
	)
	(segment
		(start 456.810364 -50.111914)
		(end 456.696064 -49.997614)
		(width 0.1143)
		(layer "F.Cu")
		(net "P3E_OCP_CPU0_PE3_C_TXP<2>")
	)
	(segment
		(start 456.696064 -49.997614)
		(end 456.296014 -49.997614)
		(width 0.1143)
		(layer "F.Cu")
		(net "P3E_OCP_CPU0_PE3_C_TXP<2>")
	)
	(via
		(at 456.296014 -49.997614)
		(size 0.508)
		(drill 0.254)
		(layers "F.Cu" "B.Cu")
		(net "P3E_OCP_CPU0_PE3_C_TXP<2>")
	)
	(segment
		(start 456.74788 -51.075082)
		(end 456.86218 -50.960782)
		(width 0.1143)
		(layer "B.Cu")
		(net "P3E_OCP_CPU0_PE3_C_TXP<2>")
	)
	(segment
		(start 456.86218 -50.16373)
		(end 456.696064 -49.997614)
		(width 0.1143)
		(layer "B.Cu")
		(net "P3E_OCP_CPU0_PE3_C_TXP<2>")
	)
	(segment
		(start 456.696064 -49.997614)
		(end 456.296014 -49.997614)
		(width 0.1143)
		(layer "B.Cu")
		(net "P3E_OCP_CPU0_PE3_C_TXP<2>")
	)
	(segment
		(start 456.6031 -51.075082)
		(end 456.74788 -51.075082)
		(width 0.1143)
		(layer "B.Cu")
		(net "P3E_OCP_CPU0_PE3_C_TXP<2>")
	)
	(segment
		(start 456.4888 -51.189382)
		(end 456.6031 -51.075082)
		(width 0.1143)
		(layer "B.Cu")
		(net "P3E_OCP_CPU0_PE3_C_TXP<2>")
	)
	(segment
		(start 456.86218 -50.960782)
		(end 456.86218 -50.16373)
		(width 0.1143)
		(layer "B.Cu")
		(net "P3E_OCP_CPU0_PE3_C_TXP<2>")
	)
	(segment
		(start 456.4888 -51.594258)
		(end 456.4888 -51.189382)
		(width 0.1143)
		(layer "B.Cu")
		(net "P3E_OCP_CPU0_PE3_C_TXP<2>")
	)
	(segment
		(start 459.741016 -51.875944)
		(end 459.741016 -50.71491)
		(width 0.1143)
		(layer "F.Cu")
		(net "P3E_OCP_CPU0_PE3_C_TXP<1>")
	)
	(segment
		(start 459.741016 -50.71491)
		(end 460.010764 -50.445162)
		(width 0.1143)
		(layer "F.Cu")
		(net "P3E_OCP_CPU0_PE3_C_TXP<1>")
	)
	(segment
		(start 460.010764 -50.111914)
		(end 459.896464 -49.997614)
		(width 0.1143)
		(layer "F.Cu")
		(net "P3E_OCP_CPU0_PE3_C_TXP<1>")
	)
	(segment
		(start 459.896464 -49.997614)
		(end 459.496414 -49.997614)
		(width 0.1143)
		(layer "F.Cu")
		(net "P3E_OCP_CPU0_PE3_C_TXP<1>")
	)
	(segment
		(start 460.010764 -50.445162)
		(end 460.010764 -50.111914)
		(width 0.1143)
		(layer "F.Cu")
		(net "P3E_OCP_CPU0_PE3_C_TXP<1>")
	)
	(via
		(at 459.496414 -49.997614)
		(size 0.508)
		(drill 0.254)
		(layers "F.Cu" "B.Cu")
		(net "P3E_OCP_CPU0_PE3_C_TXP<1>")
	)
	(segment
		(start 459.6384 -51.568858)
		(end 459.6384 -51.163982)
		(width 0.1143)
		(layer "B.Cu")
		(net "P3E_OCP_CPU0_PE3_C_TXP<1>")
	)
	(segment
		(start 459.896464 -49.997614)
		(end 459.496414 -49.997614)
		(width 0.1143)
		(layer "B.Cu")
		(net "P3E_OCP_CPU0_PE3_C_TXP<1>")
	)
	(segment
		(start 459.6384 -51.163982)
		(end 459.7527 -51.049682)
		(width 0.1143)
		(layer "B.Cu")
		(net "P3E_OCP_CPU0_PE3_C_TXP<1>")
	)
	(segment
		(start 459.896464 -51.049682)
		(end 460.010764 -50.935382)
		(width 0.1143)
		(layer "B.Cu")
		(net "P3E_OCP_CPU0_PE3_C_TXP<1>")
	)
	(segment
		(start 460.010764 -50.111914)
		(end 459.896464 -49.997614)
		(width 0.1143)
		(layer "B.Cu")
		(net "P3E_OCP_CPU0_PE3_C_TXP<1>")
	)
	(segment
		(start 460.010764 -50.935382)
		(end 460.010764 -50.111914)
		(width 0.1143)
		(layer "B.Cu")
		(net "P3E_OCP_CPU0_PE3_C_TXP<1>")
	)
	(segment
		(start 459.7527 -51.049682)
		(end 459.896464 -51.049682)
		(width 0.1143)
		(layer "B.Cu")
		(net "P3E_OCP_CPU0_PE3_C_TXP<1>")
	)
	(segment
		(start 462.940908 -50.987198)
		(end 463.221578 -50.706528)
		(width 0.1143)
		(layer "F.Cu")
		(net "P3E_OCP_CPU0_PE3_C_TXP<0>")
	)
	(segment
		(start 463.107278 -49.997614)
		(end 462.707228 -49.997614)
		(width 0.1143)
		(layer "F.Cu")
		(net "P3E_OCP_CPU0_PE3_C_TXP<0>")
	)
	(segment
		(start 463.221578 -50.706528)
		(end 463.221578 -50.111914)
		(width 0.1143)
		(layer "F.Cu")
		(net "P3E_OCP_CPU0_PE3_C_TXP<0>")
	)
	(segment
		(start 462.940908 -51.875944)
		(end 462.940908 -50.987198)
		(width 0.1143)
		(layer "F.Cu")
		(net "P3E_OCP_CPU0_PE3_C_TXP<0>")
	)
	(segment
		(start 463.221578 -50.111914)
		(end 463.107278 -49.997614)
		(width 0.1143)
		(layer "F.Cu")
		(net "P3E_OCP_CPU0_PE3_C_TXP<0>")
	)
	(via
		(at 462.707228 -49.997614)
		(size 0.508)
		(drill 0.254)
		(layers "F.Cu" "B.Cu")
		(net "P3E_OCP_CPU0_PE3_C_TXP<0>")
	)
	(segment
		(start 462.8134 -51.138582)
		(end 462.9277 -51.024282)
		(width 0.1143)
		(layer "B.Cu")
		(net "P3E_OCP_CPU0_PE3_C_TXP<0>")
	)
	(segment
		(start 462.9277 -51.024282)
		(end 463.08645 -51.024282)
		(width 0.1143)
		(layer "B.Cu")
		(net "P3E_OCP_CPU0_PE3_C_TXP<0>")
	)
	(segment
		(start 463.08645 -51.024282)
		(end 463.221578 -50.889154)
		(width 0.1143)
		(layer "B.Cu")
		(net "P3E_OCP_CPU0_PE3_C_TXP<0>")
	)
	(segment
		(start 463.221578 -50.889154)
		(end 463.221578 -50.111914)
		(width 0.1143)
		(layer "B.Cu")
		(net "P3E_OCP_CPU0_PE3_C_TXP<0>")
	)
	(segment
		(start 462.8134 -51.543458)
		(end 462.8134 -51.138582)
		(width 0.1143)
		(layer "B.Cu")
		(net "P3E_OCP_CPU0_PE3_C_TXP<0>")
	)
	(segment
		(start 463.221578 -50.111914)
		(end 463.107278 -49.997614)
		(width 0.1143)
		(layer "B.Cu")
		(net "P3E_OCP_CPU0_PE3_C_TXP<0>")
	)
	(segment
		(start 463.107278 -49.997614)
		(end 462.707228 -49.997614)
		(width 0.1143)
		(layer "B.Cu")
		(net "P3E_OCP_CPU0_PE3_C_TXP<0>")
	)
	(segment
		(start 453.851264 -50.111914)
		(end 453.965564 -49.997614)
		(width 0.1143)
		(layer "F.Cu")
		(net "P3E_OCP_CPU0_PE3_C_TXN<3>")
	)
	(segment
		(start 454.141078 -51.070002)
		(end 453.851264 -50.780188)
		(width 0.1143)
		(layer "F.Cu")
		(net "P3E_OCP_CPU0_PE3_C_TXN<3>")
	)
	(segment
		(start 453.965564 -49.997614)
		(end 454.365614 -49.997614)
		(width 0.1143)
		(layer "F.Cu")
		(net "P3E_OCP_CPU0_PE3_C_TXN<3>")
	)
	(segment
		(start 454.141078 -51.875944)
		(end 454.141078 -51.070002)
		(width 0.1143)
		(layer "F.Cu")
		(net "P3E_OCP_CPU0_PE3_C_TXN<3>")
	)
	(segment
		(start 453.851264 -50.780188)
		(end 453.851264 -50.111914)
		(width 0.1143)
		(layer "F.Cu")
		(net "P3E_OCP_CPU0_PE3_C_TXN<3>")
	)
	(via
		(at 454.365614 -49.997614)
		(size 0.508)
		(drill 0.254)
		(layers "F.Cu" "B.Cu")
		(net "P3E_OCP_CPU0_PE3_C_TXN<3>")
	)
	(segment
		(start 454.1139 -50.922682)
		(end 453.965564 -50.922682)
		(width 0.1143)
		(layer "B.Cu")
		(net "P3E_OCP_CPU0_PE3_C_TXN<3>")
	)
	(segment
		(start 453.965564 -49.997614)
		(end 454.365614 -49.997614)
		(width 0.1143)
		(layer "B.Cu")
		(net "P3E_OCP_CPU0_PE3_C_TXN<3>")
	)
	(segment
		(start 453.965564 -50.922682)
		(end 453.851264 -50.808382)
		(width 0.1143)
		(layer "B.Cu")
		(net "P3E_OCP_CPU0_PE3_C_TXN<3>")
	)
	(segment
		(start 453.851264 -50.808382)
		(end 453.851264 -50.111914)
		(width 0.1143)
		(layer "B.Cu")
		(net "P3E_OCP_CPU0_PE3_C_TXN<3>")
	)
	(segment
		(start 453.851264 -50.111914)
		(end 453.965564 -49.997614)
		(width 0.1143)
		(layer "B.Cu")
		(net "P3E_OCP_CPU0_PE3_C_TXN<3>")
	)
	(segment
		(start 454.2282 -51.036982)
		(end 454.1139 -50.922682)
		(width 0.1143)
		(layer "B.Cu")
		(net "P3E_OCP_CPU0_PE3_C_TXN<3>")
	)
	(segment
		(start 454.2282 -51.441858)
		(end 454.2282 -51.036982)
		(width 0.1143)
		(layer "B.Cu")
		(net "P3E_OCP_CPU0_PE3_C_TXN<3>")
	)
	(segment
		(start 457.051664 -50.445162)
		(end 457.051664 -50.111914)
		(width 0.1143)
		(layer "F.Cu")
		(net "P3E_OCP_CPU0_PE3_C_TXN<2>")
	)
	(segment
		(start 457.34097 -51.875944)
		(end 457.34097 -50.734468)
		(width 0.1143)
		(layer "F.Cu")
		(net "P3E_OCP_CPU0_PE3_C_TXN<2>")
	)
	(segment
		(start 457.051664 -50.111914)
		(end 457.165964 -49.997614)
		(width 0.1143)
		(layer "F.Cu")
		(net "P3E_OCP_CPU0_PE3_C_TXN<2>")
	)
	(segment
		(start 457.165964 -49.997614)
		(end 457.566014 -49.997614)
		(width 0.1143)
		(layer "F.Cu")
		(net "P3E_OCP_CPU0_PE3_C_TXN<2>")
	)
	(segment
		(start 457.34097 -50.734468)
		(end 457.051664 -50.445162)
		(width 0.1143)
		(layer "F.Cu")
		(net "P3E_OCP_CPU0_PE3_C_TXN<2>")
	)
	(via
		(at 457.566014 -49.997614)
		(size 0.508)
		(drill 0.254)
		(layers "F.Cu" "B.Cu")
		(net "P3E_OCP_CPU0_PE3_C_TXN<2>")
	)
	(segment
		(start 457.5048 -51.189382)
		(end 457.3905 -51.075082)
		(width 0.1143)
		(layer "B.Cu")
		(net "P3E_OCP_CPU0_PE3_C_TXN<2>")
	)
	(segment
		(start 457.5048 -51.594258)
		(end 457.5048 -51.189382)
		(width 0.1143)
		(layer "B.Cu")
		(net "P3E_OCP_CPU0_PE3_C_TXN<2>")
	)
	(segment
		(start 457.3905 -51.075082)
		(end 457.23175 -51.075082)
		(width 0.1143)
		(layer "B.Cu")
		(net "P3E_OCP_CPU0_PE3_C_TXN<2>")
	)
	(segment
		(start 457.23175 -51.075082)
		(end 457.10348 -50.946812)
		(width 0.1143)
		(layer "B.Cu")
		(net "P3E_OCP_CPU0_PE3_C_TXN<2>")
	)
	(segment
		(start 457.10348 -50.946812)
		(end 457.10348 -50.111914)
		(width 0.1143)
		(layer "B.Cu")
		(net "P3E_OCP_CPU0_PE3_C_TXN<2>")
	)
	(segment
		(start 457.21778 -49.997614)
		(end 457.566014 -49.997614)
		(width 0.1143)
		(layer "B.Cu")
		(net "P3E_OCP_CPU0_PE3_C_TXN<2>")
	)
	(segment
		(start 457.10348 -50.111914)
		(end 457.21778 -49.997614)
		(width 0.1143)
		(layer "B.Cu")
		(net "P3E_OCP_CPU0_PE3_C_TXN<2>")
	)
	(segment
		(start 460.252064 -50.445162)
		(end 460.252064 -50.111914)
		(width 0.1143)
		(layer "F.Cu")
		(net "P3E_OCP_CPU0_PE3_C_TXN<1>")
	)
	(segment
		(start 460.366364 -49.997614)
		(end 460.766414 -49.997614)
		(width 0.1143)
		(layer "F.Cu")
		(net "P3E_OCP_CPU0_PE3_C_TXN<1>")
	)
	(segment
		(start 460.252064 -50.111914)
		(end 460.366364 -49.997614)
		(width 0.1143)
		(layer "F.Cu")
		(net "P3E_OCP_CPU0_PE3_C_TXN<1>")
	)
	(segment
		(start 460.541116 -51.875944)
		(end 460.541116 -50.734214)
		(width 0.1143)
		(layer "F.Cu")
		(net "P3E_OCP_CPU0_PE3_C_TXN<1>")
	)
	(segment
		(start 460.541116 -50.734214)
		(end 460.252064 -50.445162)
		(width 0.1143)
		(layer "F.Cu")
		(net "P3E_OCP_CPU0_PE3_C_TXN<1>")
	)
	(via
		(at 460.766414 -49.997614)
		(size 0.508)
		(drill 0.254)
		(layers "F.Cu" "B.Cu")
		(net "P3E_OCP_CPU0_PE3_C_TXN<1>")
	)
	(segment
		(start 460.38135 -51.049682)
		(end 460.252064 -50.920396)
		(width 0.1143)
		(layer "B.Cu")
		(net "P3E_OCP_CPU0_PE3_C_TXN<1>")
	)
	(segment
		(start 460.5401 -51.049682)
		(end 460.38135 -51.049682)
		(width 0.1143)
		(layer "B.Cu")
		(net "P3E_OCP_CPU0_PE3_C_TXN<1>")
	)
	(segment
		(start 460.252064 -50.111914)
		(end 460.366364 -49.997614)
		(width 0.1143)
		(layer "B.Cu")
		(net "P3E_OCP_CPU0_PE3_C_TXN<1>")
	)
	(segment
		(start 460.366364 -49.997614)
		(end 460.766414 -49.997614)
		(width 0.1143)
		(layer "B.Cu")
		(net "P3E_OCP_CPU0_PE3_C_TXN<1>")
	)
	(segment
		(start 460.6544 -51.568858)
		(end 460.6544 -51.163982)
		(width 0.1143)
		(layer "B.Cu")
		(net "P3E_OCP_CPU0_PE3_C_TXN<1>")
	)
	(segment
		(start 460.252064 -50.920396)
		(end 460.252064 -50.111914)
		(width 0.1143)
		(layer "B.Cu")
		(net "P3E_OCP_CPU0_PE3_C_TXN<1>")
	)
	(segment
		(start 460.6544 -51.163982)
		(end 460.5401 -51.049682)
		(width 0.1143)
		(layer "B.Cu")
		(net "P3E_OCP_CPU0_PE3_C_TXN<1>")
	)
	(segment
		(start 463.462878 -50.714656)
		(end 463.462878 -50.111914)
		(width 0.1143)
		(layer "F.Cu")
		(net "P3E_OCP_CPU0_PE3_C_TXN<0>")
	)
	(segment
		(start 463.462878 -50.111914)
		(end 463.577178 -49.997614)
		(width 0.1143)
		(layer "F.Cu")
		(net "P3E_OCP_CPU0_PE3_C_TXN<0>")
	)
	(segment
		(start 463.741008 -51.875944)
		(end 463.741008 -50.992786)
		(width 0.1143)
		(layer "F.Cu")
		(net "P3E_OCP_CPU0_PE3_C_TXN<0>")
	)
	(segment
		(start 463.577178 -49.997614)
		(end 463.977228 -49.997614)
		(width 0.1143)
		(layer "F.Cu")
		(net "P3E_OCP_CPU0_PE3_C_TXN<0>")
	)
	(segment
		(start 463.741008 -50.992786)
		(end 463.462878 -50.714656)
		(width 0.1143)
		(layer "F.Cu")
		(net "P3E_OCP_CPU0_PE3_C_TXN<0>")
	)
	(via
		(at 463.977228 -49.997614)
		(size 0.508)
		(drill 0.254)
		(layers "F.Cu" "B.Cu")
		(net "P3E_OCP_CPU0_PE3_C_TXN<0>")
	)
	(segment
		(start 463.8294 -51.543458)
		(end 463.8294 -51.138582)
		(width 0.1143)
		(layer "B.Cu")
		(net "P3E_OCP_CPU0_PE3_C_TXN<0>")
	)
	(segment
		(start 463.7151 -51.024282)
		(end 463.577178 -51.024282)
		(width 0.1143)
		(layer "B.Cu")
		(net "P3E_OCP_CPU0_PE3_C_TXN<0>")
	)
	(segment
		(start 463.577178 -51.024282)
		(end 463.462878 -50.909982)
		(width 0.1143)
		(layer "B.Cu")
		(net "P3E_OCP_CPU0_PE3_C_TXN<0>")
	)
	(segment
		(start 463.462878 -50.909982)
		(end 463.462878 -50.111914)
		(width 0.1143)
		(layer "B.Cu")
		(net "P3E_OCP_CPU0_PE3_C_TXN<0>")
	)
	(segment
		(start 463.462878 -50.111914)
		(end 463.577178 -49.997614)
		(width 0.1143)
		(layer "B.Cu")
		(net "P3E_OCP_CPU0_PE3_C_TXN<0>")
	)
	(segment
		(start 463.577178 -49.997614)
		(end 463.977228 -49.997614)
		(width 0.1143)
		(layer "B.Cu")
		(net "P3E_OCP_CPU0_PE3_C_TXN<0>")
	)
	(segment
		(start 463.8294 -51.138582)
		(end 463.7151 -51.024282)
		(width 0.1143)
		(layer "B.Cu")
		(net "P3E_OCP_CPU0_PE3_C_TXN<0>")
	)
	(segment
		(start 422.1734 -80.993996)
		(end 421.443404 -80.264)
		(width 0.10795)
		(layer "F.Cu")
		(net "IRQ_SML1_PMBUS_ALERT_BUF_N")
	)
	(segment
		(start 422.148 -83.5025)
		(end 422.148 -82.9564)
		(width 0.10795)
		(layer "F.Cu")
		(net "IRQ_SML1_PMBUS_ALERT_BUF_N")
	)
	(segment
		(start 422.6052 -82.0928)
		(end 422.6052 -81.407)
		(width 0.10795)
		(layer "F.Cu")
		(net "IRQ_SML1_PMBUS_ALERT_BUF_N")
	)
	(segment
		(start 422.6052 -81.407)
		(end 422.192196 -80.993996)
		(width 0.10795)
		(layer "F.Cu")
		(net "IRQ_SML1_PMBUS_ALERT_BUF_N")
	)
	(segment
		(start 421.9321 -82.7405)
		(end 420.9161 -82.7405)
		(width 0.10795)
		(layer "F.Cu")
		(net "IRQ_SML1_PMBUS_ALERT_BUF_N")
	)
	(segment
		(start 420.751 -82.5754)
		(end 420.751 -82.281014)
		(width 0.10795)
		(layer "F.Cu")
		(net "IRQ_SML1_PMBUS_ALERT_BUF_N")
	)
	(segment
		(start 422.192196 -80.993996)
		(end 422.1734 -80.993996)
		(width 0.10795)
		(layer "F.Cu")
		(net "IRQ_SML1_PMBUS_ALERT_BUF_N")
	)
	(segment
		(start 420.751 -82.281014)
		(end 422.416986 -82.281014)
		(width 0.10795)
		(layer "F.Cu")
		(net "IRQ_SML1_PMBUS_ALERT_BUF_N")
	)
	(segment
		(start 420.9161 -82.7405)
		(end 420.751 -82.5754)
		(width 0.10795)
		(layer "F.Cu")
		(net "IRQ_SML1_PMBUS_ALERT_BUF_N")
	)
	(segment
		(start 422.148 -82.9564)
		(end 421.9321 -82.7405)
		(width 0.10795)
		(layer "F.Cu")
		(net "IRQ_SML1_PMBUS_ALERT_BUF_N")
	)
	(segment
		(start 422.416986 -82.281014)
		(end 422.6052 -82.0928)
		(width 0.10795)
		(layer "F.Cu")
		(net "IRQ_SML1_PMBUS_ALERT_BUF_N")
	)
	(segment
		(start 421.443404 -80.264)
		(end 420.751 -80.264)
		(width 0.10795)
		(layer "F.Cu")
		(net "IRQ_SML1_PMBUS_ALERT_BUF_N")
	)
	(via
		(at 422.6052 -81.407)
		(size 0.762)
		(drill 0.381)
		(layers "F.Cu" "B.Cu")
		(net "IRQ_SML1_PMBUS_ALERT_BUF_N")
	)
	(segment
		(start 419.3794 -74.1807)
		(end 419.481 -74.0791)
		(width 0.10795)
		(layer "B.Cu")
		(net "FM_FAST_PROCHOT_THROTTLE_DLY_BU")
	)
	(segment
		(start 420.010336 -75.698858)
		(end 420.503604 -75.698858)
		(width 0.10795)
		(layer "B.Cu")
		(net "FM_FAST_PROCHOT_THROTTLE_DLY_BU")
	)
	(segment
		(start 419.3794 -76.4286)
		(end 419.3794 -74.1807)
		(width 0.10795)
		(layer "B.Cu")
		(net "FM_FAST_PROCHOT_THROTTLE_DLY_BU")
	)
	(segment
		(start 419.212014 -76.595986)
		(end 419.3794 -76.4286)
		(width 0.10795)
		(layer "B.Cu")
		(net "FM_FAST_PROCHOT_THROTTLE_DLY_BU")
	)
	(segment
		(start 419.7858 -75.474322)
		(end 420.010336 -75.698858)
		(width 0.10795)
		(layer "B.Cu")
		(net "FM_FAST_PROCHOT_THROTTLE_DLY_BU")
	)
	(segment
		(start 418.667184 -76.595986)
		(end 419.212014 -76.595986)
		(width 0.10795)
		(layer "B.Cu")
		(net "FM_FAST_PROCHOT_THROTTLE_DLY_BU")
	)
	(segment
		(start 419.7858 -74.2442)
		(end 419.7858 -75.474322)
		(width 0.10795)
		(layer "B.Cu")
		(net "FM_FAST_PROCHOT_THROTTLE_DLY_BU")
	)
	(segment
		(start 419.6207 -74.0791)
		(end 419.7858 -74.2442)
		(width 0.10795)
		(layer "B.Cu")
		(net "FM_FAST_PROCHOT_THROTTLE_DLY_BU")
	)
	(segment
		(start 419.481 -74.0791)
		(end 419.6207 -74.0791)
		(width 0.10795)
		(layer "B.Cu")
		(net "FM_FAST_PROCHOT_THROTTLE_DLY_BU")
	)
	(segment
		(start 499.872 -144.399)
		(end 499.0719 -144.399)
		(width 0.10795)
		(layer "F.Cu")
		(net "FM_SPEAKER_PCH_N")
	)
	(segment
		(start 499.0719 -144.399)
		(end 498.5893 -143.9164)
		(width 0.10795)
		(layer "F.Cu")
		(net "FM_SPEAKER_PCH_N")
	)
	(segment
		(start 490.1565 -139.319)
		(end 490.1565 -141.4907)
		(width 0.10795)
		(layer "F.Cu")
		(net "FM_SPEAKER_PCH_N")
	)
	(segment
		(start 490.1565 -141.4907)
		(end 491.3884 -142.7226)
		(width 0.10795)
		(layer "F.Cu")
		(net "FM_SPEAKER_PCH_N")
	)
	(via
		(at 491.3884 -142.7226)
		(size 0.508)
		(drill 0.254)
		(layers "F.Cu" "B.Cu")
		(net "FM_SPEAKER_PCH_N")
	)
	(via
		(at 498.5893 -143.9164)
		(size 0.508)
		(drill 0.254)
		(layers "F.Cu" "B.Cu")
		(net "FM_SPEAKER_PCH_N")
	)
	(via
		(at 490.37875 -143.81099)
		(size 0.6604)
		(drill 0.3302)
		(layers "F.Cu" "B.Cu")
		(net "FM_SPEAKER_PCH_N")
	)
	(segment
		(start 491.3884 -143.538194)
		(end 491.3884 -142.7226)
		(width 0.10795)
		(layer "B.Cu")
		(net "FM_SPEAKER_PCH_N")
	)
	(segment
		(start 490.37875 -143.81099)
		(end 491.115604 -143.81099)
		(width 0.10795)
		(layer "B.Cu")
		(net "FM_SPEAKER_PCH_N")
	)
	(segment
		(start 491.115604 -143.81099)
		(end 491.3884 -143.538194)
		(width 0.10795)
		(layer "B.Cu")
		(net "FM_SPEAKER_PCH_N")
	)
	(segment
		(start 497.3955 -142.7226)
		(end 498.5893 -143.9164)
		(width 0.089408)
		(layer "In4.Cu")
		(net "FM_SPEAKER_PCH_N")
	)
	(segment
		(start 491.3884 -142.7226)
		(end 497.3955 -142.7226)
		(width 0.089408)
		(layer "In4.Cu")
		(net "FM_SPEAKER_PCH_N")
	)
	(segment
		(start 497.794534 -38.029896)
		(end 497.794534 -37.942266)
		(width 0.10795)
		(layer "B.Cu")
		(net "UART_MUX_OUT_R")
	)
	(segment
		(start 499.0338 -36.703)
		(end 499.0338 -36.264596)
		(width 0.10795)
		(layer "B.Cu")
		(net "UART_MUX_OUT_R")
	)
	(segment
		(start 497.794534 -37.942266)
		(end 499.0338 -36.703)
		(width 0.10795)
		(layer "B.Cu")
		(net "UART_MUX_OUT_R")
	)
	(segment
		(start 499.340378 -35.958018)
		(end 499.967504 -35.958018)
		(width 0.10795)
		(layer "B.Cu")
		(net "UART_MUX_OUT_R")
	)
	(segment
		(start 499.0338 -36.264596)
		(end 499.340378 -35.958018)
		(width 0.10795)
		(layer "B.Cu")
		(net "UART_MUX_OUT_R")
	)
	(segment
		(start 494.13541 -35.557206)
		(end 494.538 -35.959796)
		(width 0.10795)
		(layer "F.Cu")
		(net "UART_MUX_IN_R")
	)
	(segment
		(start 490.6772 -30.911292)
		(end 490.6772 -32.639)
		(width 0.10795)
		(layer "F.Cu")
		(net "UART_MUX_IN_R")
	)
	(segment
		(start 489.173774 -29.31668)
		(end 488.974638 -29.31668)
		(width 0.10795)
		(layer "F.Cu")
		(net "UART_MUX_IN_R")
	)
	(segment
		(start 491.639606 -33.601406)
		(end 493.180624 -34.2392)
		(width 0.10795)
		(layer "F.Cu")
		(net "UART_MUX_IN_R")
	)
	(segment
		(start 493.180624 -34.2392)
		(end 493.7506 -34.2392)
		(width 0.10795)
		(layer "F.Cu")
		(net "UART_MUX_IN_R")
	)
	(segment
		(start 493.7506 -34.2392)
		(end 494.13541 -34.62401)
		(width 0.10795)
		(layer "F.Cu")
		(net "UART_MUX_IN_R")
	)
	(segment
		(start 490.061758 -30.204664)
		(end 489.173774 -29.31668)
		(width 0.10795)
		(layer "F.Cu")
		(net "UART_MUX_IN_R")
	)
	(segment
		(start 494.13541 -34.62401)
		(end 494.13541 -35.557206)
		(width 0.10795)
		(layer "F.Cu")
		(net "UART_MUX_IN_R")
	)
	(segment
		(start 490.6772 -32.639)
		(end 491.639606 -33.601406)
		(width 0.10795)
		(layer "F.Cu")
		(net "UART_MUX_IN_R")
	)
	(segment
		(start 490.061758 -30.29585)
		(end 490.6772 -30.911292)
		(width 0.10795)
		(layer "F.Cu")
		(net "UART_MUX_IN_R")
	)
	(segment
		(start 494.538 -35.959796)
		(end 494.538 -36.2204)
		(width 0.10795)
		(layer "F.Cu")
		(net "UART_MUX_IN_R")
	)
	(segment
		(start 490.061758 -30.204664)
		(end 490.061758 -30.29585)
		(width 0.10795)
		(layer "F.Cu")
		(net "UART_MUX_IN_R")
	)
	(via
		(at 494.538 -36.2204)
		(size 0.508)
		(drill 0.254)
		(layers "F.Cu" "B.Cu")
		(net "UART_MUX_IN_R")
	)
	(via
		(at 490.061758 -30.204664)
		(size 0.762)
		(drill 0.381)
		(layers "F.Cu" "B.Cu")
		(net "UART_MUX_IN_R")
	)
	(segment
		(start 494.262664 -35.945064)
		(end 494.538 -36.2204)
		(width 0.10795)
		(layer "B.Cu")
		(net "UART_MUX_IN_R")
	)
	(segment
		(start 493.251998 -35.945064)
		(end 494.262664 -35.945064)
		(width 0.10795)
		(layer "B.Cu")
		(net "UART_MUX_IN_R")
	)
	(segment
		(start 488.96016 -26.10104)
		(end 489.0262 -26.035)
		(width 0.10795)
		(layer "F.Cu")
		(net "SPA_MID_DBG_TX")
	)
	(segment
		(start 485.983026 -25.82291)
		(end 487.58983 -25.82291)
		(width 0.10795)
		(layer "F.Cu")
		(net "SPA_MID_DBG_TX")
	)
	(segment
		(start 425.9834 -75.311)
		(end 426.4914 -74.803)
		(width 0.10795)
		(layer "F.Cu")
		(net "SPA_MID_DBG_TX")
	)
	(segment
		(start 439.672984 -112.472216)
		(end 437.690006 -110.489238)
		(width 0.10795)
		(layer "F.Cu")
		(net "SPA_MID_DBG_TX")
	)
	(segment
		(start 487.58983 -25.82291)
		(end 487.86796 -26.10104)
		(width 0.10795)
		(layer "F.Cu")
		(net "SPA_MID_DBG_TX")
	)
	(segment
		(start 489.0262 -26.035)
		(end 489.0262 -25.767284)
		(width 0.10795)
		(layer "F.Cu")
		(net "SPA_MID_DBG_TX")
	)
	(segment
		(start 426.698664 -109.562646)
		(end 426.698664 -78.56601)
		(width 0.10795)
		(layer "F.Cu")
		(net "SPA_MID_DBG_TX")
	)
	(segment
		(start 426.698664 -78.56601)
		(end 425.9834 -77.850746)
		(width 0.10795)
		(layer "F.Cu")
		(net "SPA_MID_DBG_TX")
	)
	(segment
		(start 485.875076 -25.93086)
		(end 485.983026 -25.82291)
		(width 0.10795)
		(layer "F.Cu")
		(net "SPA_MID_DBG_TX")
	)
	(segment
		(start 427.625256 -110.489238)
		(end 426.698664 -109.562646)
		(width 0.10795)
		(layer "F.Cu")
		(net "SPA_MID_DBG_TX")
	)
	(segment
		(start 437.690006 -110.489238)
		(end 427.625256 -110.489238)
		(width 0.10795)
		(layer "F.Cu")
		(net "SPA_MID_DBG_TX")
	)
	(segment
		(start 487.86796 -26.10104)
		(end 488.96016 -26.10104)
		(width 0.10795)
		(layer "F.Cu")
		(net "SPA_MID_DBG_TX")
	)
	(segment
		(start 425.9834 -77.850746)
		(end 425.9834 -75.311)
		(width 0.10795)
		(layer "F.Cu")
		(net "SPA_MID_DBG_TX")
	)
	(segment
		(start 489.0262 -25.767284)
		(end 488.525566 -25.26665)
		(width 0.10795)
		(layer "F.Cu")
		(net "SPA_MID_DBG_TX")
	)
	(segment
		(start 485.875076 -26.326084)
		(end 485.875076 -25.93086)
		(width 0.10795)
		(layer "F.Cu")
		(net "SPA_MID_DBG_TX")
	)
	(via
		(at 501.0912 -143.5608)
		(size 0.508)
		(drill 0.254)
		(layers "F.Cu" "B.Cu")
		(net "SPA_MID_DBG_TX")
	)
	(via
		(at 439.672984 -112.472216)
		(size 0.508)
		(drill 0.254)
		(layers "F.Cu" "B.Cu")
		(net "SPA_MID_DBG_TX")
	)
	(via
		(at 489.0262 -26.035)
		(size 0.762)
		(drill 0.381)
		(layers "F.Cu" "B.Cu")
		(net "SPA_MID_DBG_TX")
	)
	(via
		(at 498.5512 -37.9222)
		(size 0.508)
		(drill 0.254)
		(layers "F.Cu" "B.Cu")
		(net "SPA_MID_DBG_TX")
	)
	(via
		(at 488.525566 -25.26665)
		(size 0.508)
		(drill 0.254)
		(layers "F.Cu" "B.Cu")
		(net "SPA_MID_DBG_TX")
	)
	(via
		(at 426.4914 -74.803)
		(size 0.508)
		(drill 0.254)
		(layers "F.Cu" "B.Cu")
		(net "SPA_MID_DBG_TX")
	)
	(via
		(at 493.649 -53.213)
		(size 0.508)
		(drill 0.254)
		(layers "F.Cu" "B.Cu")
		(net "SPA_MID_DBG_TX")
	)
	(segment
		(start 499.603014 -148.1582)
		(end 499.603014 -147.436586)
		(width 0.10795)
		(layer "B.Cu")
		(net "SPA_MID_DBG_TX")
	)
	(segment
		(start 496.905534 -38.308534)
		(end 497.2812 -38.6842)
		(width 0.10795)
		(layer "B.Cu")
		(net "SPA_MID_DBG_TX")
	)
	(segment
		(start 499.745 -143.9418)
		(end 500.7102 -143.9418)
		(width 0.10795)
		(layer "B.Cu")
		(net "SPA_MID_DBG_TX")
	)
	(segment
		(start 498.5512 -38.0746)
		(end 498.5512 -37.9222)
		(width 0.10795)
		(layer "B.Cu")
		(net "SPA_MID_DBG_TX")
	)
	(segment
		(start 499.745 -147.2946)
		(end 499.745 -143.9418)
		(width 0.10795)
		(layer "B.Cu")
		(net "SPA_MID_DBG_TX")
	)
	(segment
		(start 496.905534 -38.029896)
		(end 496.905534 -38.308534)
		(width 0.10795)
		(layer "B.Cu")
		(net "SPA_MID_DBG_TX")
	)
	(segment
		(start 500.7102 -143.9418)
		(end 501.0912 -143.5608)
		(width 0.10795)
		(layer "B.Cu")
		(net "SPA_MID_DBG_TX")
	)
	(segment
		(start 497.9416 -38.6842)
		(end 498.5512 -38.0746)
		(width 0.10795)
		(layer "B.Cu")
		(net "SPA_MID_DBG_TX")
	)
	(segment
		(start 499.603014 -147.436586)
		(end 499.745 -147.2946)
		(width 0.10795)
		(layer "B.Cu")
		(net "SPA_MID_DBG_TX")
	)
	(segment
		(start 497.2812 -38.6842)
		(end 497.9416 -38.6842)
		(width 0.10795)
		(layer "B.Cu")
		(net "SPA_MID_DBG_TX")
	)
	(segment
		(start 499.745 -143.016986)
		(end 499.730014 -143.002)
		(width 0.10795)
		(layer "B.Cu")
		(net "SPA_MID_DBG_TX")
	)
	(segment
		(start 499.745 -143.9418)
		(end 499.745 -143.016986)
		(width 0.10795)
		(layer "B.Cu")
		(net "SPA_MID_DBG_TX")
	)
	(segment
		(start 425.63161 -73.93813)
		(end 425.63161 -68.584064)
		(width 0.089408)
		(layer "In2.Cu")
		(net "SPA_MID_DBG_TX")
	)
	(segment
		(start 426.322998 -74.634598)
		(end 426.322998 -74.629518)
		(width 0.089408)
		(layer "In2.Cu")
		(net "SPA_MID_DBG_TX")
	)
	(segment
		(start 479.631756 -61.591444)
		(end 484.711502 -61.591444)
		(width 0.089408)
		(layer "In2.Cu")
		(net "SPA_MID_DBG_TX")
	)
	(segment
		(start 465.407756 -66.92392)
		(end 474.29928 -66.92392)
		(width 0.089408)
		(layer "In2.Cu")
		(net "SPA_MID_DBG_TX")
	)
	(segment
		(start 463.527902 -66.924174)
		(end 465.407502 -66.924174)
		(width 0.089408)
		(layer "In2.Cu")
		(net "SPA_MID_DBG_TX")
	)
	(segment
		(start 463.527648 -66.92392)
		(end 463.527902 -66.924174)
		(width 0.089408)
		(layer "In2.Cu")
		(net "SPA_MID_DBG_TX")
	)
	(segment
		(start 484.711502 -61.591444)
		(end 489.825538 -56.477408)
		(width 0.089408)
		(layer "In2.Cu")
		(net "SPA_MID_DBG_TX")
	)
	(segment
		(start 426.4914 -74.803)
		(end 426.322998 -74.634598)
		(width 0.089408)
		(layer "In2.Cu")
		(net "SPA_MID_DBG_TX")
	)
	(segment
		(start 465.407502 -66.924174)
		(end 465.407756 -66.92392)
		(width 0.089408)
		(layer "In2.Cu")
		(net "SPA_MID_DBG_TX")
	)
	(segment
		(start 489.825538 -56.477408)
		(end 490.896402 -56.477408)
		(width 0.089408)
		(layer "In2.Cu")
		(net "SPA_MID_DBG_TX")
	)
	(segment
		(start 427.291754 -66.92392)
		(end 463.527648 -66.92392)
		(width 0.089408)
		(layer "In2.Cu")
		(net "SPA_MID_DBG_TX")
	)
	(segment
		(start 425.63161 -68.584064)
		(end 427.291754 -66.92392)
		(width 0.089408)
		(layer "In2.Cu")
		(net "SPA_MID_DBG_TX")
	)
	(segment
		(start 474.29928 -66.92392)
		(end 479.631756 -61.591444)
		(width 0.089408)
		(layer "In2.Cu")
		(net "SPA_MID_DBG_TX")
	)
	(segment
		(start 426.322998 -74.629518)
		(end 425.63161 -73.93813)
		(width 0.089408)
		(layer "In2.Cu")
		(net "SPA_MID_DBG_TX")
	)
	(segment
		(start 493.649 -53.72481)
		(end 493.649 -53.213)
		(width 0.089408)
		(layer "In2.Cu")
		(net "SPA_MID_DBG_TX")
	)
	(segment
		(start 490.896402 -56.477408)
		(end 493.649 -53.72481)
		(width 0.089408)
		(layer "In2.Cu")
		(net "SPA_MID_DBG_TX")
	)
	(segment
		(start 495.755168 -125.062488)
		(end 499.54942 -128.85674)
		(width 0.089408)
		(layer "In4.Cu")
		(net "SPA_MID_DBG_TX")
	)
	(segment
		(start 493.824768 -115.542568)
		(end 493.824768 -118.537736)
		(width 0.089408)
		(layer "In4.Cu")
		(net "SPA_MID_DBG_TX")
	)
	(segment
		(start 500.209566 -130.487166)
		(end 500.209566 -142.679166)
		(width 0.089408)
		(layer "In4.Cu")
		(net "SPA_MID_DBG_TX")
	)
	(segment
		(start 497.85651 -35.74669)
		(end 499.6815 -33.9217)
		(width 0.089408)
		(layer "In4.Cu")
		(net "SPA_MID_DBG_TX")
	)
	(segment
		(start 499.54942 -129.82702)
		(end 500.209566 -130.487166)
		(width 0.089408)
		(layer "In4.Cu")
		(net "SPA_MID_DBG_TX")
	)
	(segment
		(start 495.755168 -120.468136)
		(end 495.755168 -125.062488)
		(width 0.089408)
		(layer "In4.Cu")
		(net "SPA_MID_DBG_TX")
	)
	(segment
		(start 498.1448 -28.13812)
		(end 491.802166 -28.13812)
		(width 0.089408)
		(layer "In4.Cu")
		(net "SPA_MID_DBG_TX")
	)
	(segment
		(start 489.759752 -112.8014)
		(end 489.779056 -112.782096)
		(width 0.089408)
		(layer "In4.Cu")
		(net "SPA_MID_DBG_TX")
	)
	(segment
		(start 500.209566 -142.679166)
		(end 501.0912 -143.5608)
		(width 0.089408)
		(layer "In4.Cu")
		(net "SPA_MID_DBG_TX")
	)
	(segment
		(start 493.824768 -118.537736)
		(end 495.755168 -120.468136)
		(width 0.089408)
		(layer "In4.Cu")
		(net "SPA_MID_DBG_TX")
	)
	(segment
		(start 499.54942 -128.85674)
		(end 499.54942 -129.82702)
		(width 0.089408)
		(layer "In4.Cu")
		(net "SPA_MID_DBG_TX")
	)
	(segment
		(start 499.6815 -29.67482)
		(end 498.1448 -28.13812)
		(width 0.089408)
		(layer "In4.Cu")
		(net "SPA_MID_DBG_TX")
	)
	(segment
		(start 491.802166 -28.13812)
		(end 488.930696 -25.26665)
		(width 0.089408)
		(layer "In4.Cu")
		(net "SPA_MID_DBG_TX")
	)
	(segment
		(start 498.5512 -37.9222)
		(end 497.85651 -37.22751)
		(width 0.089408)
		(layer "In4.Cu")
		(net "SPA_MID_DBG_TX")
	)
	(segment
		(start 469.138508 -111.850932)
		(end 470.088976 -112.8014)
		(width 0.089408)
		(layer "In4.Cu")
		(net "SPA_MID_DBG_TX")
	)
	(segment
		(start 499.6815 -33.9217)
		(end 499.6815 -29.67482)
		(width 0.089408)
		(layer "In4.Cu")
		(net "SPA_MID_DBG_TX")
	)
	(segment
		(start 439.672984 -112.472216)
		(end 440.294268 -111.850932)
		(width 0.089408)
		(layer "In4.Cu")
		(net "SPA_MID_DBG_TX")
	)
	(segment
		(start 491.064296 -112.782096)
		(end 493.824768 -115.542568)
		(width 0.089408)
		(layer "In4.Cu")
		(net "SPA_MID_DBG_TX")
	)
	(segment
		(start 440.294268 -111.850932)
		(end 469.138508 -111.850932)
		(width 0.089408)
		(layer "In4.Cu")
		(net "SPA_MID_DBG_TX")
	)
	(segment
		(start 470.088976 -112.8014)
		(end 489.759752 -112.8014)
		(width 0.089408)
		(layer "In4.Cu")
		(net "SPA_MID_DBG_TX")
	)
	(segment
		(start 488.930696 -25.26665)
		(end 488.525566 -25.26665)
		(width 0.089408)
		(layer "In4.Cu")
		(net "SPA_MID_DBG_TX")
	)
	(segment
		(start 497.85651 -37.22751)
		(end 497.85651 -35.74669)
		(width 0.089408)
		(layer "In4.Cu")
		(net "SPA_MID_DBG_TX")
	)
	(segment
		(start 489.779056 -112.782096)
		(end 491.064296 -112.782096)
		(width 0.089408)
		(layer "In4.Cu")
		(net "SPA_MID_DBG_TX")
	)
	(segment
		(start 493.649 -53.0606)
		(end 493.649 -53.213)
		(width 0.089408)
		(layer "In9.Cu")
		(net "SPA_MID_DBG_TX")
	)
	(segment
		(start 497.753894 -38.719506)
		(end 497.753894 -47.2694)
		(width 0.089408)
		(layer "In9.Cu")
		(net "SPA_MID_DBG_TX")
	)
	(segment
		(start 495.506502 -51.203098)
		(end 493.649 -53.0606)
		(width 0.089408)
		(layer "In9.Cu")
		(net "SPA_MID_DBG_TX")
	)
	(segment
		(start 497.753894 -47.2694)
		(end 495.506502 -49.516792)
		(width 0.089408)
		(layer "In9.Cu")
		(net "SPA_MID_DBG_TX")
	)
	(segment
		(start 495.506502 -49.516792)
		(end 495.506502 -51.203098)
		(width 0.089408)
		(layer "In9.Cu")
		(net "SPA_MID_DBG_TX")
	)
	(segment
		(start 498.5512 -37.9222)
		(end 497.753894 -38.719506)
		(width 0.089408)
		(layer "In9.Cu")
		(net "SPA_MID_DBG_TX")
	)
	(segment
		(start 487.969306 -28.407106)
		(end 487.970576 -28.408376)
		(width 0.10795)
		(layer "F.Cu")
		(net "SPA_MID_DBG_RX")
	)
	(segment
		(start 487.969306 -27.666696)
		(end 487.969306 -28.407106)
		(width 0.10795)
		(layer "F.Cu")
		(net "SPA_MID_DBG_RX")
	)
	(segment
		(start 488.955334 -28.408376)
		(end 488.974638 -28.42768)
		(width 0.10795)
		(layer "F.Cu")
		(net "SPA_MID_DBG_RX")
	)
	(segment
		(start 490.5375 -29.89326)
		(end 490.981492 -30.337252)
		(width 0.10795)
		(layer "F.Cu")
		(net "SPA_MID_DBG_RX")
	)
	(segment
		(start 486.151428 -138.120628)
		(end 485.394 -138.120628)
		(width 0.10795)
		(layer "F.Cu")
		(net "SPA_MID_DBG_RX")
	)
	(segment
		(start 487.970576 -28.408376)
		(end 488.955334 -28.408376)
		(width 0.10795)
		(layer "F.Cu")
		(net "SPA_MID_DBG_RX")
	)
	(segment
		(start 489.94822 -28.42768)
		(end 490.5375 -29.01696)
		(width 0.10795)
		(layer "F.Cu")
		(net "SPA_MID_DBG_RX")
	)
	(segment
		(start 486.3465 -138.3157)
		(end 486.151428 -138.120628)
		(width 0.10795)
		(layer "F.Cu")
		(net "SPA_MID_DBG_RX")
	)
	(segment
		(start 486.3465 -138.395202)
		(end 486.3465 -138.3157)
		(width 0.10795)
		(layer "F.Cu")
		(net "SPA_MID_DBG_RX")
	)
	(segment
		(start 488.974638 -28.42768)
		(end 489.94822 -28.42768)
		(width 0.10795)
		(layer "F.Cu")
		(net "SPA_MID_DBG_RX")
	)
	(segment
		(start 490.5375 -29.01696)
		(end 490.5375 -29.89326)
		(width 0.10795)
		(layer "F.Cu")
		(net "SPA_MID_DBG_RX")
	)
	(via
		(at 490.981492 -30.337252)
		(size 0.508)
		(drill 0.254)
		(layers "F.Cu" "B.Cu")
		(net "SPA_MID_DBG_RX")
	)
	(via
		(at 420.57066 -121.054622)
		(size 0.508)
		(drill 0.254)
		(layers "F.Cu" "B.Cu")
		(net "SPA_MID_DBG_RX")
	)
	(via
		(at 486.3465 -138.395202)
		(size 0.508)
		(drill 0.254)
		(layers "F.Cu" "B.Cu")
		(net "SPA_MID_DBG_RX")
	)
	(via
		(at 490.5375 -29.01696)
		(size 0.762)
		(drill 0.381)
		(layers "F.Cu" "B.Cu")
		(net "SPA_MID_DBG_RX")
	)
	(via
		(at 426.4914 -68.9102)
		(size 0.508)
		(drill 0.254)
		(layers "F.Cu" "B.Cu")
		(net "SPA_MID_DBG_RX")
	)
	(segment
		(start 486.3465 -138.395202)
		(end 486.3465 -138.2141)
		(width 0.089408)
		(layer "In2.Cu")
		(net "SPA_MID_DBG_RX")
	)
	(segment
		(start 437.180736 -117.670326)
		(end 434.071776 -120.779286)
		(width 0.089408)
		(layer "In2.Cu")
		(net "SPA_MID_DBG_RX")
	)
	(segment
		(start 434.071776 -120.779286)
		(end 428.100998 -120.779286)
		(width 0.089408)
		(layer "In2.Cu")
		(net "SPA_MID_DBG_RX")
	)
	(segment
		(start 477.139 -122.7582)
		(end 473.560394 -119.179594)
		(width 0.089408)
		(layer "In2.Cu")
		(net "SPA_MID_DBG_RX")
	)
	(segment
		(start 465.118704 -117.670326)
		(end 437.180736 -117.670326)
		(width 0.089408)
		(layer "In2.Cu")
		(net "SPA_MID_DBG_RX")
	)
	(segment
		(start 486.3465 -138.2141)
		(end 487.1974 -137.3632)
		(width 0.089408)
		(layer "In2.Cu")
		(net "SPA_MID_DBG_RX")
	)
	(segment
		(start 469.054434 -118.01729)
		(end 465.465668 -118.01729)
		(width 0.089408)
		(layer "In2.Cu")
		(net "SPA_MID_DBG_RX")
	)
	(segment
		(start 491.49 -133.705854)
		(end 490.499146 -132.715)
		(width 0.089408)
		(layer "In2.Cu")
		(net "SPA_MID_DBG_RX")
	)
	(segment
		(start 486.537 -132.08)
		(end 486.537 -131.064)
		(width 0.089408)
		(layer "In2.Cu")
		(net "SPA_MID_DBG_RX")
	)
	(segment
		(start 486.537 -131.064)
		(end 485.7242 -130.2512)
		(width 0.089408)
		(layer "In2.Cu")
		(net "SPA_MID_DBG_RX")
	)
	(segment
		(start 465.465668 -118.01729)
		(end 465.118704 -117.670326)
		(width 0.089408)
		(layer "In2.Cu")
		(net "SPA_MID_DBG_RX")
	)
	(segment
		(start 428.100998 -120.779286)
		(end 427.863508 -121.016776)
		(width 0.089408)
		(layer "In2.Cu")
		(net "SPA_MID_DBG_RX")
	)
	(segment
		(start 427.863508 -121.016776)
		(end 420.608506 -121.016776)
		(width 0.089408)
		(layer "In2.Cu")
		(net "SPA_MID_DBG_RX")
	)
	(segment
		(start 485.7242 -130.2512)
		(end 481.836222 -130.2512)
		(width 0.089408)
		(layer "In2.Cu")
		(net "SPA_MID_DBG_RX")
	)
	(segment
		(start 477.139 -125.553978)
		(end 477.139 -122.7582)
		(width 0.089408)
		(layer "In2.Cu")
		(net "SPA_MID_DBG_RX")
	)
	(segment
		(start 473.560394 -119.179594)
		(end 470.216738 -119.179594)
		(width 0.089408)
		(layer "In2.Cu")
		(net "SPA_MID_DBG_RX")
	)
	(segment
		(start 487.172 -132.715)
		(end 486.537 -132.08)
		(width 0.089408)
		(layer "In2.Cu")
		(net "SPA_MID_DBG_RX")
	)
	(segment
		(start 420.608506 -121.016776)
		(end 420.57066 -121.054622)
		(width 0.089408)
		(layer "In2.Cu")
		(net "SPA_MID_DBG_RX")
	)
	(segment
		(start 470.216738 -119.179594)
		(end 469.054434 -118.01729)
		(width 0.089408)
		(layer "In2.Cu")
		(net "SPA_MID_DBG_RX")
	)
	(segment
		(start 481.836222 -130.2512)
		(end 477.139 -125.553978)
		(width 0.089408)
		(layer "In2.Cu")
		(net "SPA_MID_DBG_RX")
	)
	(segment
		(start 491.49 -136.245346)
		(end 491.49 -133.705854)
		(width 0.089408)
		(layer "In2.Cu")
		(net "SPA_MID_DBG_RX")
	)
	(segment
		(start 490.499146 -132.715)
		(end 487.172 -132.715)
		(width 0.089408)
		(layer "In2.Cu")
		(net "SPA_MID_DBG_RX")
	)
	(segment
		(start 490.372146 -137.3632)
		(end 491.49 -136.245346)
		(width 0.089408)
		(layer "In2.Cu")
		(net "SPA_MID_DBG_RX")
	)
	(segment
		(start 487.1974 -137.3632)
		(end 490.372146 -137.3632)
		(width 0.089408)
		(layer "In2.Cu")
		(net "SPA_MID_DBG_RX")
	)
	(segment
		(start 423.947336 -105.299002)
		(end 423.44975 -105.299002)
		(width 0.089408)
		(layer "In4.Cu")
		(net "SPA_MID_DBG_RX")
	)
	(segment
		(start 423.44975 -105.299002)
		(end 420.070026 -108.678726)
		(width 0.089408)
		(layer "In4.Cu")
		(net "SPA_MID_DBG_RX")
	)
	(segment
		(start 426.4914 -68.9102)
		(end 426.08881 -68.9102)
		(width 0.089408)
		(layer "In4.Cu")
		(net "SPA_MID_DBG_RX")
	)
	(segment
		(start 420.070026 -108.678726)
		(end 420.070026 -120.553988)
		(width 0.089408)
		(layer "In4.Cu")
		(net "SPA_MID_DBG_RX")
	)
	(segment
		(start 420.070026 -120.553988)
		(end 420.57066 -121.054622)
		(width 0.089408)
		(layer "In4.Cu")
		(net "SPA_MID_DBG_RX")
	)
	(segment
		(start 424.421808 -70.577202)
		(end 424.421808 -104.82453)
		(width 0.089408)
		(layer "In4.Cu")
		(net "SPA_MID_DBG_RX")
	)
	(segment
		(start 424.421808 -104.82453)
		(end 423.947336 -105.299002)
		(width 0.089408)
		(layer "In4.Cu")
		(net "SPA_MID_DBG_RX")
	)
	(segment
		(start 426.08881 -68.9102)
		(end 424.421808 -70.577202)
		(width 0.089408)
		(layer "In4.Cu")
		(net "SPA_MID_DBG_RX")
	)
	(segment
		(start 485.073706 -59.657996)
		(end 484.648764 -59.657996)
		(width 0.089408)
		(layer "In11.Cu")
		(net "SPA_MID_DBG_RX")
	)
	(segment
		(start 476.651828 -58.094372)
		(end 475.35592 -56.798464)
		(width 0.089408)
		(layer "In11.Cu")
		(net "SPA_MID_DBG_RX")
	)
	(segment
		(start 470.650062 -63.607696)
		(end 470.318338 -63.607696)
		(width 0.089408)
		(layer "In11.Cu")
		(net "SPA_MID_DBG_RX")
	)
	(segment
		(start 426.4914 -68.459096)
		(end 426.4914 -68.9102)
		(width 0.089408)
		(layer "In11.Cu")
		(net "SPA_MID_DBG_RX")
	)
	(segment
		(start 494.382298 -51.601624)
		(end 492.071152 -53.91277)
		(width 0.089408)
		(layer "In11.Cu")
		(net "SPA_MID_DBG_RX")
	)
	(segment
		(start 491.208822 -33.605978)
		(end 491.208822 -35.271456)
		(width 0.089408)
		(layer "In11.Cu")
		(net "SPA_MID_DBG_RX")
	)
	(segment
		(start 492.771938 -40.481504)
		(end 492.925608 -40.481504)
		(width 0.089408)
		(layer "In11.Cu")
		(net "SPA_MID_DBG_RX")
	)
	(segment
		(start 470.652094 -63.609728)
		(end 470.650062 -63.607696)
		(width 0.089408)
		(layer "In11.Cu")
		(net "SPA_MID_DBG_RX")
	)
	(segment
		(start 491.8202 -31.821882)
		(end 491.8202 -32.9946)
		(width 0.089408)
		(layer "In11.Cu")
		(net "SPA_MID_DBG_RX")
	)
	(segment
		(start 492.071152 -53.91277)
		(end 490.818932 -53.91277)
		(width 0.089408)
		(layer "In11.Cu")
		(net "SPA_MID_DBG_RX")
	)
	(segment
		(start 492.925608 -40.481504)
		(end 494.382298 -41.938194)
		(width 0.089408)
		(layer "In11.Cu")
		(net "SPA_MID_DBG_RX")
	)
	(segment
		(start 476.651828 -59.997594)
		(end 476.651828 -58.094372)
		(width 0.089408)
		(layer "In11.Cu")
		(net "SPA_MID_DBG_RX")
	)
	(segment
		(start 477.394524 -60.74029)
		(end 476.651828 -59.997594)
		(width 0.089408)
		(layer "In11.Cu")
		(net "SPA_MID_DBG_RX")
	)
	(segment
		(start 490.4486 -36.031678)
		(end 490.4486 -38.158166)
		(width 0.089408)
		(layer "In11.Cu")
		(net "SPA_MID_DBG_RX")
	)
	(segment
		(start 490.981492 -30.983174)
		(end 491.8202 -31.821882)
		(width 0.089408)
		(layer "In11.Cu")
		(net "SPA_MID_DBG_RX")
	)
	(segment
		(start 471.567256 -63.347854)
		(end 471.305382 -63.609728)
		(width 0.089408)
		(layer "In11.Cu")
		(net "SPA_MID_DBG_RX")
	)
	(segment
		(start 471.567256 -58.398664)
		(end 471.567256 -63.347854)
		(width 0.089408)
		(layer "In11.Cu")
		(net "SPA_MID_DBG_RX")
	)
	(segment
		(start 494.382298 -41.938194)
		(end 494.382298 -51.601624)
		(width 0.089408)
		(layer "In11.Cu")
		(net "SPA_MID_DBG_RX")
	)
	(segment
		(start 427.939962 -67.010534)
		(end 426.4914 -68.459096)
		(width 0.089408)
		(layer "In11.Cu")
		(net "SPA_MID_DBG_RX")
	)
	(segment
		(start 475.35592 -56.798464)
		(end 473.167456 -56.798464)
		(width 0.089408)
		(layer "In11.Cu")
		(net "SPA_MID_DBG_RX")
	)
	(segment
		(start 473.167456 -56.798464)
		(end 471.567256 -58.398664)
		(width 0.089408)
		(layer "In11.Cu")
		(net "SPA_MID_DBG_RX")
	)
	(segment
		(start 470.318338 -63.607696)
		(end 470.316306 -63.609728)
		(width 0.089408)
		(layer "In11.Cu")
		(net "SPA_MID_DBG_RX")
	)
	(segment
		(start 483.56647 -60.74029)
		(end 477.394524 -60.74029)
		(width 0.089408)
		(layer "In11.Cu")
		(net "SPA_MID_DBG_RX")
	)
	(segment
		(start 490.4486 -38.158166)
		(end 492.771938 -40.481504)
		(width 0.089408)
		(layer "In11.Cu")
		(net "SPA_MID_DBG_RX")
	)
	(segment
		(start 491.208822 -35.271456)
		(end 490.4486 -36.031678)
		(width 0.089408)
		(layer "In11.Cu")
		(net "SPA_MID_DBG_RX")
	)
	(segment
		(start 491.8202 -32.9946)
		(end 491.208822 -33.605978)
		(width 0.089408)
		(layer "In11.Cu")
		(net "SPA_MID_DBG_RX")
	)
	(segment
		(start 465.008722 -67.010534)
		(end 427.939962 -67.010534)
		(width 0.089408)
		(layer "In11.Cu")
		(net "SPA_MID_DBG_RX")
	)
	(segment
		(start 470.316306 -63.609728)
		(end 468.409528 -63.609728)
		(width 0.089408)
		(layer "In11.Cu")
		(net "SPA_MID_DBG_RX")
	)
	(segment
		(start 471.305382 -63.609728)
		(end 470.652094 -63.609728)
		(width 0.089408)
		(layer "In11.Cu")
		(net "SPA_MID_DBG_RX")
	)
	(segment
		(start 490.818932 -53.91277)
		(end 485.073706 -59.657996)
		(width 0.089408)
		(layer "In11.Cu")
		(net "SPA_MID_DBG_RX")
	)
	(segment
		(start 490.981492 -30.337252)
		(end 490.981492 -30.983174)
		(width 0.089408)
		(layer "In11.Cu")
		(net "SPA_MID_DBG_RX")
	)
	(segment
		(start 468.409528 -63.609728)
		(end 465.008722 -67.010534)
		(width 0.089408)
		(layer "In11.Cu")
		(net "SPA_MID_DBG_RX")
	)
	(segment
		(start 484.648764 -59.657996)
		(end 483.56647 -60.74029)
		(width 0.089408)
		(layer "In11.Cu")
		(net "SPA_MID_DBG_RX")
	)
	(segment
		(start 440.714892 -49.981104)
		(end 440.325002 -49.981104)
		(width 0.1143)
		(layer "F.Cu")
		(net "P3E_OCP_CPU0_PE3_C_TXP<7>")
	)
	(segment
		(start 440.540902 -51.009804)
		(end 440.829192 -50.721514)
		(width 0.1143)
		(layer "F.Cu")
		(net "P3E_OCP_CPU0_PE3_C_TXP<7>")
	)
	(segment
		(start 440.829192 -50.721514)
		(end 440.829192 -50.095404)
		(width 0.1143)
		(layer "F.Cu")
		(net "P3E_OCP_CPU0_PE3_C_TXP<7>")
	)
	(segment
		(start 440.829192 -50.095404)
		(end 440.714892 -49.981104)
		(width 0.1143)
		(layer "F.Cu")
		(net "P3E_OCP_CPU0_PE3_C_TXP<7>")
	)
	(segment
		(start 440.540902 -51.875944)
		(end 440.540902 -51.009804)
		(width 0.1143)
		(layer "F.Cu")
		(net "P3E_OCP_CPU0_PE3_C_TXP<7>")
	)
	(via
		(at 440.325002 -49.981104)
		(size 0.508)
		(drill 0.254)
		(layers "F.Cu" "B.Cu")
		(net "P3E_OCP_CPU0_PE3_C_TXP<7>")
	)
	(segment
		(start 440.814206 -50.710338)
		(end 440.814206 -50.00625)
		(width 0.1143)
		(layer "B.Cu")
		(net "P3E_OCP_CPU0_PE3_C_TXP<7>")
	)
	(segment
		(start 440.814206 -50.00625)
		(end 440.67095 -49.862994)
		(width 0.1143)
		(layer "B.Cu")
		(net "P3E_OCP_CPU0_PE3_C_TXP<7>")
	)
	(segment
		(start 440.443112 -49.862994)
		(end 440.325002 -49.981104)
		(width 0.1143)
		(layer "B.Cu")
		(net "P3E_OCP_CPU0_PE3_C_TXP<7>")
	)
	(segment
		(start 440.67095 -49.862994)
		(end 440.443112 -49.862994)
		(width 0.1143)
		(layer "B.Cu")
		(net "P3E_OCP_CPU0_PE3_C_TXP<7>")
	)
	(segment
		(start 440.4614 -51.4096)
		(end 440.4614 -51.063144)
		(width 0.1143)
		(layer "B.Cu")
		(net "P3E_OCP_CPU0_PE3_C_TXP<7>")
	)
	(segment
		(start 440.4614 -51.063144)
		(end 440.814206 -50.710338)
		(width 0.1143)
		(layer "B.Cu")
		(net "P3E_OCP_CPU0_PE3_C_TXP<7>")
	)
	(segment
		(start 443.742064 -50.765202)
		(end 444.019178 -50.488088)
		(width 0.1143)
		(layer "F.Cu")
		(net "P3E_OCP_CPU0_PE3_C_TXP<6>")
	)
	(segment
		(start 443.904878 -49.998122)
		(end 443.504828 -49.998122)
		(width 0.1143)
		(layer "F.Cu")
		(net "P3E_OCP_CPU0_PE3_C_TXP<6>")
	)
	(segment
		(start 444.019178 -50.112422)
		(end 443.904878 -49.998122)
		(width 0.1143)
		(layer "F.Cu")
		(net "P3E_OCP_CPU0_PE3_C_TXP<6>")
	)
	(segment
		(start 444.019178 -50.488088)
		(end 444.019178 -50.112422)
		(width 0.1143)
		(layer "F.Cu")
		(net "P3E_OCP_CPU0_PE3_C_TXP<6>")
	)
	(segment
		(start 443.742064 -51.875944)
		(end 443.742064 -50.765202)
		(width 0.1143)
		(layer "F.Cu")
		(net "P3E_OCP_CPU0_PE3_C_TXP<6>")
	)
	(segment
		(start 443.741048 -51.875944)
		(end 443.742064 -51.875944)
		(width 0.1143)
		(layer "F.Cu")
		(net "P3E_OCP_CPU0_PE3_C_TXP<6>")
	)
	(via
		(at 443.504828 -49.998122)
		(size 0.508)
		(drill 0.254)
		(layers "F.Cu" "B.Cu")
		(net "P3E_OCP_CPU0_PE3_C_TXP<6>")
	)
	(segment
		(start 443.633606 -51.048158)
		(end 443.747906 -50.933858)
		(width 0.1143)
		(layer "B.Cu")
		(net "P3E_OCP_CPU0_PE3_C_TXP<6>")
	)
	(segment
		(start 443.987174 -50.112422)
		(end 443.872874 -49.998122)
		(width 0.1143)
		(layer "B.Cu")
		(net "P3E_OCP_CPU0_PE3_C_TXP<6>")
	)
	(segment
		(start 443.872874 -49.998122)
		(end 443.504828 -49.998122)
		(width 0.1143)
		(layer "B.Cu")
		(net "P3E_OCP_CPU0_PE3_C_TXP<6>")
	)
	(segment
		(start 443.633606 -51.453034)
		(end 443.633606 -51.048158)
		(width 0.1143)
		(layer "B.Cu")
		(net "P3E_OCP_CPU0_PE3_C_TXP<6>")
	)
	(segment
		(start 443.987174 -50.819558)
		(end 443.987174 -50.112422)
		(width 0.1143)
		(layer "B.Cu")
		(net "P3E_OCP_CPU0_PE3_C_TXP<6>")
	)
	(segment
		(start 443.747906 -50.933858)
		(end 443.872874 -50.933858)
		(width 0.1143)
		(layer "B.Cu")
		(net "P3E_OCP_CPU0_PE3_C_TXP<6>")
	)
	(segment
		(start 443.872874 -50.933858)
		(end 443.987174 -50.819558)
		(width 0.1143)
		(layer "B.Cu")
		(net "P3E_OCP_CPU0_PE3_C_TXP<6>")
	)
	(segment
		(start 447.20891 -50.498502)
		(end 447.20891 -50.112422)
		(width 0.1143)
		(layer "F.Cu")
		(net "P3E_OCP_CPU0_PE3_C_TXP<5>")
	)
	(segment
		(start 447.20891 -50.112422)
		(end 447.09461 -49.998122)
		(width 0.1143)
		(layer "F.Cu")
		(net "P3E_OCP_CPU0_PE3_C_TXP<5>")
	)
	(segment
		(start 447.09461 -49.998122)
		(end 446.701672 -49.998122)
		(width 0.1143)
		(layer "F.Cu")
		(net "P3E_OCP_CPU0_PE3_C_TXP<5>")
	)
	(segment
		(start 446.94094 -51.875944)
		(end 446.94094 -50.766472)
		(width 0.1143)
		(layer "F.Cu")
		(net "P3E_OCP_CPU0_PE3_C_TXP<5>")
	)
	(segment
		(start 446.94094 -50.766472)
		(end 447.20891 -50.498502)
		(width 0.1143)
		(layer "F.Cu")
		(net "P3E_OCP_CPU0_PE3_C_TXP<5>")
	)
	(via
		(at 446.701672 -49.998122)
		(size 0.508)
		(drill 0.254)
		(layers "F.Cu" "B.Cu")
		(net "P3E_OCP_CPU0_PE3_C_TXP<5>")
	)
	(segment
		(start 447.20891 -50.112422)
		(end 447.20891 -50.511964)
		(width 0.1143)
		(layer "B.Cu")
		(net "P3E_OCP_CPU0_PE3_C_TXP<5>")
	)
	(segment
		(start 447.026538 -50.998882)
		(end 446.912238 -51.113182)
		(width 0.1143)
		(layer "B.Cu")
		(net "P3E_OCP_CPU0_PE3_C_TXP<5>")
	)
	(segment
		(start 446.701672 -49.998122)
		(end 447.09461 -49.998122)
		(width 0.1143)
		(layer "B.Cu")
		(net "P3E_OCP_CPU0_PE3_C_TXP<5>")
	)
	(segment
		(start 447.09461 -49.998122)
		(end 447.20891 -50.112422)
		(width 0.1143)
		(layer "B.Cu")
		(net "P3E_OCP_CPU0_PE3_C_TXP<5>")
	)
	(segment
		(start 447.20891 -50.511964)
		(end 447.284348 -50.587402)
		(width 0.1143)
		(layer "B.Cu")
		(net "P3E_OCP_CPU0_PE3_C_TXP<5>")
	)
	(segment
		(start 447.185288 -50.998882)
		(end 447.026538 -50.998882)
		(width 0.1143)
		(layer "B.Cu")
		(net "P3E_OCP_CPU0_PE3_C_TXP<5>")
	)
	(segment
		(start 447.284348 -50.899822)
		(end 447.185288 -50.998882)
		(width 0.1143)
		(layer "B.Cu")
		(net "P3E_OCP_CPU0_PE3_C_TXP<5>")
	)
	(segment
		(start 446.912238 -51.113182)
		(end 446.912238 -51.518058)
		(width 0.1143)
		(layer "B.Cu")
		(net "P3E_OCP_CPU0_PE3_C_TXP<5>")
	)
	(segment
		(start 447.284348 -50.587402)
		(end 447.284348 -50.899822)
		(width 0.1143)
		(layer "B.Cu")
		(net "P3E_OCP_CPU0_PE3_C_TXP<5>")
	)
	(segment
		(start 450.409564 -50.792888)
		(end 450.409564 -50.111914)
		(width 0.1143)
		(layer "F.Cu")
		(net "P3E_OCP_CPU0_PE3_C_TXP<4>")
	)
	(segment
		(start 450.409564 -50.111914)
		(end 450.295264 -49.997614)
		(width 0.1143)
		(layer "F.Cu")
		(net "P3E_OCP_CPU0_PE3_C_TXP<4>")
	)
	(segment
		(start 450.141086 -51.875944)
		(end 450.141086 -51.061366)
		(width 0.1143)
		(layer "F.Cu")
		(net "P3E_OCP_CPU0_PE3_C_TXP<4>")
	)
	(segment
		(start 450.141086 -51.061366)
		(end 450.409564 -50.792888)
		(width 0.1143)
		(layer "F.Cu")
		(net "P3E_OCP_CPU0_PE3_C_TXP<4>")
	)
	(segment
		(start 450.295264 -49.997614)
		(end 449.895214 -49.997614)
		(width 0.1143)
		(layer "F.Cu")
		(net "P3E_OCP_CPU0_PE3_C_TXP<4>")
	)
	(via
		(at 449.895214 -49.997614)
		(size 0.508)
		(drill 0.254)
		(layers "F.Cu" "B.Cu")
		(net "P3E_OCP_CPU0_PE3_C_TXP<4>")
	)
	(segment
		(start 450.42074 -50.12309)
		(end 450.295264 -49.997614)
		(width 0.1143)
		(layer "B.Cu")
		(net "P3E_OCP_CPU0_PE3_C_TXP<4>")
	)
	(segment
		(start 450.295264 -49.997614)
		(end 449.895214 -49.997614)
		(width 0.1143)
		(layer "B.Cu")
		(net "P3E_OCP_CPU0_PE3_C_TXP<4>")
	)
	(segment
		(start 450.2404 -50.998882)
		(end 450.42074 -50.818542)
		(width 0.1143)
		(layer "B.Cu")
		(net "P3E_OCP_CPU0_PE3_C_TXP<4>")
	)
	(segment
		(start 449.96735 -51.113182)
		(end 450.08165 -50.998882)
		(width 0.1143)
		(layer "B.Cu")
		(net "P3E_OCP_CPU0_PE3_C_TXP<4>")
	)
	(segment
		(start 449.96735 -51.518058)
		(end 449.96735 -51.113182)
		(width 0.1143)
		(layer "B.Cu")
		(net "P3E_OCP_CPU0_PE3_C_TXP<4>")
	)
	(segment
		(start 450.08165 -50.998882)
		(end 450.2404 -50.998882)
		(width 0.1143)
		(layer "B.Cu")
		(net "P3E_OCP_CPU0_PE3_C_TXP<4>")
	)
	(segment
		(start 450.42074 -50.818542)
		(end 450.42074 -50.12309)
		(width 0.1143)
		(layer "B.Cu")
		(net "P3E_OCP_CPU0_PE3_C_TXP<4>")
	)
	(segment
		(start 441.070492 -50.105564)
		(end 441.194952 -49.981104)
		(width 0.1143)
		(layer "F.Cu")
		(net "P3E_OCP_CPU0_PE3_C_TXN<7>")
	)
	(segment
		(start 441.194952 -49.981104)
		(end 441.595002 -49.981104)
		(width 0.1143)
		(layer "F.Cu")
		(net "P3E_OCP_CPU0_PE3_C_TXN<7>")
	)
	(segment
		(start 441.341002 -51.875944)
		(end 441.341002 -51.02098)
		(width 0.1143)
		(layer "F.Cu")
		(net "P3E_OCP_CPU0_PE3_C_TXN<7>")
	)
	(segment
		(start 441.341002 -51.02098)
		(end 441.070492 -50.75047)
		(width 0.1143)
		(layer "F.Cu")
		(net "P3E_OCP_CPU0_PE3_C_TXN<7>")
	)
	(segment
		(start 441.070492 -50.75047)
		(end 441.070492 -50.105564)
		(width 0.1143)
		(layer "F.Cu")
		(net "P3E_OCP_CPU0_PE3_C_TXN<7>")
	)
	(via
		(at 441.595002 -49.981104)
		(size 0.508)
		(drill 0.254)
		(layers "F.Cu" "B.Cu")
		(net "P3E_OCP_CPU0_PE3_C_TXN<7>")
	)
	(segment
		(start 441.476892 -49.862994)
		(end 441.595002 -49.981104)
		(width 0.1143)
		(layer "B.Cu")
		(net "P3E_OCP_CPU0_PE3_C_TXN<7>")
	)
	(segment
		(start 441.055506 -50.70983)
		(end 441.055506 -49.981612)
		(width 0.1143)
		(layer "B.Cu")
		(net "P3E_OCP_CPU0_PE3_C_TXN<7>")
	)
	(segment
		(start 441.3504 -51.004724)
		(end 441.055506 -50.70983)
		(width 0.1143)
		(layer "B.Cu")
		(net "P3E_OCP_CPU0_PE3_C_TXN<7>")
	)
	(segment
		(start 441.3504 -51.4096)
		(end 441.3504 -51.004724)
		(width 0.1143)
		(layer "B.Cu")
		(net "P3E_OCP_CPU0_PE3_C_TXN<7>")
	)
	(segment
		(start 441.055506 -49.981612)
		(end 441.174124 -49.862994)
		(width 0.1143)
		(layer "B.Cu")
		(net "P3E_OCP_CPU0_PE3_C_TXN<7>")
	)
	(segment
		(start 441.174124 -49.862994)
		(end 441.476892 -49.862994)
		(width 0.1143)
		(layer "B.Cu")
		(net "P3E_OCP_CPU0_PE3_C_TXN<7>")
	)
	(segment
		(start 444.540894 -50.791872)
		(end 444.260478 -50.511456)
		(width 0.1143)
		(layer "F.Cu")
		(net "P3E_OCP_CPU0_PE3_C_TXN<6>")
	)
	(segment
		(start 444.260478 -50.511456)
		(end 444.260478 -50.112422)
		(width 0.1143)
		(layer "F.Cu")
		(net "P3E_OCP_CPU0_PE3_C_TXN<6>")
	)
	(segment
		(start 444.260478 -50.112422)
		(end 444.374778 -49.998122)
		(width 0.1143)
		(layer "F.Cu")
		(net "P3E_OCP_CPU0_PE3_C_TXN<6>")
	)
	(segment
		(start 444.540894 -51.875944)
		(end 444.540894 -50.791872)
		(width 0.1143)
		(layer "F.Cu")
		(net "P3E_OCP_CPU0_PE3_C_TXN<6>")
	)
	(segment
		(start 444.374778 -49.998122)
		(end 444.774828 -49.998122)
		(width 0.1143)
		(layer "F.Cu")
		(net "P3E_OCP_CPU0_PE3_C_TXN<6>")
	)
	(via
		(at 444.774828 -49.998122)
		(size 0.508)
		(drill 0.254)
		(layers "F.Cu" "B.Cu")
		(net "P3E_OCP_CPU0_PE3_C_TXN<6>")
	)
	(segment
		(start 444.649606 -51.048158)
		(end 444.535306 -50.933858)
		(width 0.1143)
		(layer "B.Cu")
		(net "P3E_OCP_CPU0_PE3_C_TXN<6>")
	)
	(segment
		(start 444.364364 -49.998122)
		(end 444.774828 -49.998122)
		(width 0.1143)
		(layer "B.Cu")
		(net "P3E_OCP_CPU0_PE3_C_TXN<6>")
	)
	(segment
		(start 444.228474 -50.134012)
		(end 444.364364 -49.998122)
		(width 0.1143)
		(layer "B.Cu")
		(net "P3E_OCP_CPU0_PE3_C_TXN<6>")
	)
	(segment
		(start 444.228474 -50.785776)
		(end 444.228474 -50.134012)
		(width 0.1143)
		(layer "B.Cu")
		(net "P3E_OCP_CPU0_PE3_C_TXN<6>")
	)
	(segment
		(start 444.376556 -50.933858)
		(end 444.228474 -50.785776)
		(width 0.1143)
		(layer "B.Cu")
		(net "P3E_OCP_CPU0_PE3_C_TXN<6>")
	)
	(segment
		(start 444.649606 -51.453034)
		(end 444.649606 -51.048158)
		(width 0.1143)
		(layer "B.Cu")
		(net "P3E_OCP_CPU0_PE3_C_TXN<6>")
	)
	(segment
		(start 444.535306 -50.933858)
		(end 444.376556 -50.933858)
		(width 0.1143)
		(layer "B.Cu")
		(net "P3E_OCP_CPU0_PE3_C_TXN<6>")
	)
	(segment
		(start 447.74231 -50.793142)
		(end 447.45021 -50.501042)
		(width 0.1143)
		(layer "F.Cu")
		(net "P3E_OCP_CPU0_PE3_C_TXN<5>")
	)
	(segment
		(start 447.74104 -50.794412)
		(end 447.74231 -50.793142)
		(width 0.1143)
		(layer "F.Cu")
		(net "P3E_OCP_CPU0_PE3_C_TXN<5>")
	)
	(segment
		(start 447.571622 -49.998122)
		(end 447.971672 -49.998122)
		(width 0.1143)
		(layer "F.Cu")
		(net "P3E_OCP_CPU0_PE3_C_TXN<5>")
	)
	(segment
		(start 447.45021 -50.501042)
		(end 447.45021 -50.119534)
		(width 0.1143)
		(layer "F.Cu")
		(net "P3E_OCP_CPU0_PE3_C_TXN<5>")
	)
	(segment
		(start 447.45021 -50.119534)
		(end 447.571622 -49.998122)
		(width 0.1143)
		(layer "F.Cu")
		(net "P3E_OCP_CPU0_PE3_C_TXN<5>")
	)
	(segment
		(start 447.74104 -51.875944)
		(end 447.74104 -50.794412)
		(width 0.1143)
		(layer "F.Cu")
		(net "P3E_OCP_CPU0_PE3_C_TXN<5>")
	)
	(via
		(at 447.971672 -49.998122)
		(size 0.508)
		(drill 0.254)
		(layers "F.Cu" "B.Cu")
		(net "P3E_OCP_CPU0_PE3_C_TXN<5>")
	)
	(segment
		(start 447.45021 -50.137822)
		(end 447.45021 -50.411888)
		(width 0.1143)
		(layer "B.Cu")
		(net "P3E_OCP_CPU0_PE3_C_TXN<5>")
	)
	(segment
		(start 447.58991 -49.998122)
		(end 447.45021 -50.137822)
		(width 0.1143)
		(layer "B.Cu")
		(net "P3E_OCP_CPU0_PE3_C_TXN<5>")
	)
	(segment
		(start 447.971672 -49.998122)
		(end 447.58991 -49.998122)
		(width 0.1143)
		(layer "B.Cu")
		(net "P3E_OCP_CPU0_PE3_C_TXN<5>")
	)
	(segment
		(start 447.928238 -51.113182)
		(end 447.928238 -51.518058)
		(width 0.1143)
		(layer "B.Cu")
		(net "P3E_OCP_CPU0_PE3_C_TXN<5>")
	)
	(segment
		(start 447.813938 -50.998882)
		(end 447.928238 -51.113182)
		(width 0.1143)
		(layer "B.Cu")
		(net "P3E_OCP_CPU0_PE3_C_TXN<5>")
	)
	(segment
		(start 447.525648 -50.869342)
		(end 447.655188 -50.998882)
		(width 0.1143)
		(layer "B.Cu")
		(net "P3E_OCP_CPU0_PE3_C_TXN<5>")
	)
	(segment
		(start 447.655188 -50.998882)
		(end 447.813938 -50.998882)
		(width 0.1143)
		(layer "B.Cu")
		(net "P3E_OCP_CPU0_PE3_C_TXN<5>")
	)
	(segment
		(start 447.45021 -50.411888)
		(end 447.525648 -50.487326)
		(width 0.1143)
		(layer "B.Cu")
		(net "P3E_OCP_CPU0_PE3_C_TXN<5>")
	)
	(segment
		(start 447.525648 -50.487326)
		(end 447.525648 -50.869342)
		(width 0.1143)
		(layer "B.Cu")
		(net "P3E_OCP_CPU0_PE3_C_TXN<5>")
	)
	(segment
		(start 450.940932 -51.875944)
		(end 450.940932 -51.070256)
		(width 0.1143)
		(layer "F.Cu")
		(net "P3E_OCP_CPU0_PE3_C_TXN<4>")
	)
	(segment
		(start 450.650864 -50.111914)
		(end 450.765164 -49.997614)
		(width 0.1143)
		(layer "F.Cu")
		(net "P3E_OCP_CPU0_PE3_C_TXN<4>")
	)
	(segment
		(start 450.650864 -50.780188)
		(end 450.650864 -50.111914)
		(width 0.1143)
		(layer "F.Cu")
		(net "P3E_OCP_CPU0_PE3_C_TXN<4>")
	)
	(segment
		(start 450.940932 -51.070256)
		(end 450.650864 -50.780188)
		(width 0.1143)
		(layer "F.Cu")
		(net "P3E_OCP_CPU0_PE3_C_TXN<4>")
	)
	(segment
		(start 450.765164 -49.997614)
		(end 451.165214 -49.997614)
		(width 0.1143)
		(layer "F.Cu")
		(net "P3E_OCP_CPU0_PE3_C_TXN<4>")
	)
	(via
		(at 451.165214 -49.997614)
		(size 0.508)
		(drill 0.254)
		(layers "F.Cu" "B.Cu")
		(net "P3E_OCP_CPU0_PE3_C_TXN<4>")
	)
	(segment
		(start 450.86905 -50.998882)
		(end 450.77634 -50.998882)
		(width 0.1143)
		(layer "B.Cu")
		(net "P3E_OCP_CPU0_PE3_C_TXN<4>")
	)
	(segment
		(start 450.66204 -50.884582)
		(end 450.66204 -50.111914)
		(width 0.1143)
		(layer "B.Cu")
		(net "P3E_OCP_CPU0_PE3_C_TXN<4>")
	)
	(segment
		(start 450.77634 -49.997614)
		(end 451.165214 -49.997614)
		(width 0.1143)
		(layer "B.Cu")
		(net "P3E_OCP_CPU0_PE3_C_TXN<4>")
	)
	(segment
		(start 450.77634 -50.998882)
		(end 450.66204 -50.884582)
		(width 0.1143)
		(layer "B.Cu")
		(net "P3E_OCP_CPU0_PE3_C_TXN<4>")
	)
	(segment
		(start 450.66204 -50.111914)
		(end 450.77634 -49.997614)
		(width 0.1143)
		(layer "B.Cu")
		(net "P3E_OCP_CPU0_PE3_C_TXN<4>")
	)
	(segment
		(start 450.98335 -51.113182)
		(end 450.86905 -50.998882)
		(width 0.1143)
		(layer "B.Cu")
		(net "P3E_OCP_CPU0_PE3_C_TXN<4>")
	)
	(segment
		(start 450.98335 -51.518058)
		(end 450.98335 -51.113182)
		(width 0.1143)
		(layer "B.Cu")
		(net "P3E_OCP_CPU0_PE3_C_TXN<4>")
	)
	(segment
		(start 26.4795 -83.155028)
		(end 26.4795 -83.60156)
		(width 0.10795)
		(layer "F.Cu")
		(net "FM_OC_DETECT_N")
	)
	(segment
		(start 26.289 -81.915)
		(end 26.289 -82.964528)
		(width 0.10795)
		(layer "F.Cu")
		(net "FM_OC_DETECT_N")
	)
	(segment
		(start 26.4795 -83.60156)
		(end 26.2128 -83.86826)
		(width 0.10795)
		(layer "F.Cu")
		(net "FM_OC_DETECT_N")
	)
	(segment
		(start 26.289 -82.964528)
		(end 26.4795 -83.155028)
		(width 0.10795)
		(layer "F.Cu")
		(net "FM_OC_DETECT_N")
	)
	(segment
		(start 416.303714 -89.342722)
		(end 415.784284 -88.823292)
		(width 0.10795)
		(layer "F.Cu")
		(net "FM_OC_DETECT_N")
	)
	(segment
		(start 416.303714 -89.417398)
		(end 416.303714 -89.342722)
		(width 0.10795)
		(layer "F.Cu")
		(net "FM_OC_DETECT_N")
	)
	(segment
		(start 415.784284 -88.823292)
		(end 415.65576 -88.823292)
		(width 0.10795)
		(layer "F.Cu")
		(net "FM_OC_DETECT_N")
	)
	(via
		(at 27.2542 -83.2104)
		(size 0.6604)
		(drill 0.3302)
		(layers "F.Cu" "B.Cu")
		(net "FM_OC_DETECT_N")
	)
	(via
		(at 355.2444 -29.591)
		(size 0.508)
		(drill 0.254)
		(layers "F.Cu" "B.Cu")
		(net "FM_OC_DETECT_N")
	)
	(via
		(at 479.285808 -54.13375)
		(size 0.508)
		(drill 0.254)
		(layers "F.Cu" "B.Cu")
		(net "FM_OC_DETECT_N")
	)
	(via
		(at 186.501024 -4.569714)
		(size 0.508)
		(drill 0.254)
		(layers "F.Cu" "B.Cu")
		(net "FM_OC_DETECT_N")
	)
	(via
		(at 26.2128 -83.86826)
		(size 0.508)
		(drill 0.254)
		(layers "F.Cu" "B.Cu")
		(net "FM_OC_DETECT_N")
	)
	(via
		(at 416.303714 -89.417398)
		(size 0.508)
		(drill 0.254)
		(layers "F.Cu" "B.Cu")
		(net "FM_OC_DETECT_N")
	)
	(via
		(at 31.58236 -50.2285)
		(size 0.508)
		(drill 0.254)
		(layers "F.Cu" "B.Cu")
		(net "FM_OC_DETECT_N")
	)
	(segment
		(start 26.2128 -83.86826)
		(end 26.59634 -83.86826)
		(width 0.10795)
		(layer "B.Cu")
		(net "FM_OC_DETECT_N")
	)
	(segment
		(start 26.59634 -83.86826)
		(end 27.2542 -83.2104)
		(width 0.10795)
		(layer "B.Cu")
		(net "FM_OC_DETECT_N")
	)
	(segment
		(start 422.762172 -60.071)
		(end 427.193964 -60.071)
		(width 0.089408)
		(layer "In2.Cu")
		(net "FM_OC_DETECT_N")
	)
	(segment
		(start 417.959032 -83.033616)
		(end 417.959286 -83.033362)
		(width 0.089408)
		(layer "In2.Cu")
		(net "FM_OC_DETECT_N")
	)
	(segment
		(start 478.542858 -54.8767)
		(end 479.285808 -54.13375)
		(width 0.089408)
		(layer "In2.Cu")
		(net "FM_OC_DETECT_N")
	)
	(segment
		(start 418.561774 -76.045314)
		(end 418.561774 -75.908916)
		(width 0.089408)
		(layer "In2.Cu")
		(net "FM_OC_DETECT_N")
	)
	(segment
		(start 418.562282 -75.433428)
		(end 418.562028 -75.433174)
		(width 0.089408)
		(layer "In2.Cu")
		(net "FM_OC_DETECT_N")
	)
	(segment
		(start 417.959032 -76.648056)
		(end 418.561774 -76.045314)
		(width 0.089408)
		(layer "In2.Cu")
		(net "FM_OC_DETECT_N")
	)
	(segment
		(start 418.561774 -71.472044)
		(end 418.793676 -71.240142)
		(width 0.089408)
		(layer "In2.Cu")
		(net "FM_OC_DETECT_N")
	)
	(segment
		(start 472.402408 -55.289196)
		(end 472.587574 -55.474362)
		(width 0.089408)
		(layer "In2.Cu")
		(net "FM_OC_DETECT_N")
	)
	(segment
		(start 468.75827 -57.98947)
		(end 469.368124 -57.379616)
		(width 0.089408)
		(layer "In2.Cu")
		(net "FM_OC_DETECT_N")
	)
	(segment
		(start 416.303714 -89.417398)
		(end 416.273234 -89.386918)
		(width 0.089408)
		(layer "In2.Cu")
		(net "FM_OC_DETECT_N")
	)
	(segment
		(start 418.562028 -75.433174)
		(end 418.562028 -75.275186)
		(width 0.089408)
		(layer "In2.Cu")
		(net "FM_OC_DETECT_N")
	)
	(segment
		(start 416.273234 -86.915752)
		(end 417.959032 -85.229954)
		(width 0.089408)
		(layer "In2.Cu")
		(net "FM_OC_DETECT_N")
	)
	(segment
		(start 416.273234 -89.386918)
		(end 416.273234 -86.915752)
		(width 0.089408)
		(layer "In2.Cu")
		(net "FM_OC_DETECT_N")
	)
	(segment
		(start 418.793676 -71.240142)
		(end 418.793676 -65.105534)
		(width 0.089408)
		(layer "In2.Cu")
		(net "FM_OC_DETECT_N")
	)
	(segment
		(start 469.91778 -55.289196)
		(end 472.402408 -55.289196)
		(width 0.089408)
		(layer "In2.Cu")
		(net "FM_OC_DETECT_N")
	)
	(segment
		(start 465.098384 -59.851798)
		(end 465.098384 -58.921904)
		(width 0.089408)
		(layer "In2.Cu")
		(net "FM_OC_DETECT_N")
	)
	(segment
		(start 418.561774 -75.908916)
		(end 418.562282 -75.908408)
		(width 0.089408)
		(layer "In2.Cu")
		(net "FM_OC_DETECT_N")
	)
	(segment
		(start 476.01124 -55.474362)
		(end 476.608902 -54.8767)
		(width 0.089408)
		(layer "In2.Cu")
		(net "FM_OC_DETECT_N")
	)
	(segment
		(start 466.030818 -57.98947)
		(end 468.75827 -57.98947)
		(width 0.089408)
		(layer "In2.Cu")
		(net "FM_OC_DETECT_N")
	)
	(segment
		(start 430.415192 -63.292228)
		(end 432.853592 -63.292228)
		(width 0.089408)
		(layer "In2.Cu")
		(net "FM_OC_DETECT_N")
	)
	(segment
		(start 465.098384 -58.921904)
		(end 466.030818 -57.98947)
		(width 0.089408)
		(layer "In2.Cu")
		(net "FM_OC_DETECT_N")
	)
	(segment
		(start 469.368124 -55.838852)
		(end 469.91778 -55.289196)
		(width 0.089408)
		(layer "In2.Cu")
		(net "FM_OC_DETECT_N")
	)
	(segment
		(start 469.368124 -57.379616)
		(end 469.368124 -55.838852)
		(width 0.089408)
		(layer "In2.Cu")
		(net "FM_OC_DETECT_N")
	)
	(segment
		(start 418.793676 -65.105534)
		(end 418.79393 -65.10528)
		(width 0.089408)
		(layer "In2.Cu")
		(net "FM_OC_DETECT_N")
	)
	(segment
		(start 417.959032 -85.229954)
		(end 417.959032 -83.033616)
		(width 0.089408)
		(layer "In2.Cu")
		(net "FM_OC_DETECT_N")
	)
	(segment
		(start 418.562028 -75.275186)
		(end 418.561774 -75.274932)
		(width 0.089408)
		(layer "In2.Cu")
		(net "FM_OC_DETECT_N")
	)
	(segment
		(start 417.959032 -82.399632)
		(end 417.959032 -76.648056)
		(width 0.089408)
		(layer "In2.Cu")
		(net "FM_OC_DETECT_N")
	)
	(segment
		(start 418.561774 -75.274932)
		(end 418.561774 -71.472044)
		(width 0.089408)
		(layer "In2.Cu")
		(net "FM_OC_DETECT_N")
	)
	(segment
		(start 463.51825 -61.431932)
		(end 465.098384 -59.851798)
		(width 0.089408)
		(layer "In2.Cu")
		(net "FM_OC_DETECT_N")
	)
	(segment
		(start 432.853592 -63.292228)
		(end 434.713888 -61.431932)
		(width 0.089408)
		(layer "In2.Cu")
		(net "FM_OC_DETECT_N")
	)
	(segment
		(start 476.608902 -54.8767)
		(end 478.542858 -54.8767)
		(width 0.089408)
		(layer "In2.Cu")
		(net "FM_OC_DETECT_N")
	)
	(segment
		(start 417.959286 -83.033362)
		(end 417.959286 -82.399886)
		(width 0.089408)
		(layer "In2.Cu")
		(net "FM_OC_DETECT_N")
	)
	(segment
		(start 418.79393 -65.10528)
		(end 418.79393 -64.039242)
		(width 0.089408)
		(layer "In2.Cu")
		(net "FM_OC_DETECT_N")
	)
	(segment
		(start 418.79393 -64.039242)
		(end 422.762172 -60.071)
		(width 0.089408)
		(layer "In2.Cu")
		(net "FM_OC_DETECT_N")
	)
	(segment
		(start 427.193964 -60.071)
		(end 430.415192 -63.292228)
		(width 0.089408)
		(layer "In2.Cu")
		(net "FM_OC_DETECT_N")
	)
	(segment
		(start 417.959286 -82.399886)
		(end 417.959032 -82.399632)
		(width 0.089408)
		(layer "In2.Cu")
		(net "FM_OC_DETECT_N")
	)
	(segment
		(start 434.713888 -61.431932)
		(end 463.51825 -61.431932)
		(width 0.089408)
		(layer "In2.Cu")
		(net "FM_OC_DETECT_N")
	)
	(segment
		(start 418.562282 -75.908408)
		(end 418.562282 -75.433428)
		(width 0.089408)
		(layer "In2.Cu")
		(net "FM_OC_DETECT_N")
	)
	(segment
		(start 472.587574 -55.474362)
		(end 476.01124 -55.474362)
		(width 0.089408)
		(layer "In2.Cu")
		(net "FM_OC_DETECT_N")
	)
	(segment
		(start 28.83154 -62.2554)
		(end 28.83154 -66.69532)
		(width 0.089408)
		(layer "In9.Cu")
		(net "FM_OC_DETECT_N")
	)
	(segment
		(start 325.821294 -6.36778)
		(end 327.670414 -6.36778)
		(width 0.089408)
		(layer "In9.Cu")
		(net "FM_OC_DETECT_N")
	)
	(segment
		(start 330.900024 -9.59739)
		(end 331.560424 -9.59739)
		(width 0.089408)
		(layer "In9.Cu")
		(net "FM_OC_DETECT_N")
	)
	(segment
		(start 323.798184 -2.342388)
		(end 323.798184 -4.34467)
		(width 0.089408)
		(layer "In9.Cu")
		(net "FM_OC_DETECT_N")
	)
	(segment
		(start 332.125066 -10.1219)
		(end 332.12532 -10.122154)
		(width 0.089408)
		(layer "In9.Cu")
		(net "FM_OC_DETECT_N")
	)
	(segment
		(start 338.665058 -21.071078)
		(end 338.665058 -24.101044)
		(width 0.089408)
		(layer "In9.Cu")
		(net "FM_OC_DETECT_N")
	)
	(segment
		(start 194.608196 -0.808736)
		(end 259.072126 -0.808736)
		(width 0.089408)
		(layer "In9.Cu")
		(net "FM_OC_DETECT_N")
	)
	(segment
		(start 339.506814 -24.9428)
		(end 343.135458 -24.9428)
		(width 0.089408)
		(layer "In9.Cu")
		(net "FM_OC_DETECT_N")
	)
	(segment
		(start 27.561794 -73.847198)
		(end 27.188922 -74.22007)
		(width 0.089408)
		(layer "In9.Cu")
		(net "FM_OC_DETECT_N")
	)
	(segment
		(start 355.3714 -29.464)
		(end 355.2444 -29.591)
		(width 0.089408)
		(layer "In9.Cu")
		(net "FM_OC_DETECT_N")
	)
	(segment
		(start 27.561794 -67.965066)
		(end 27.561794 -73.847198)
		(width 0.089408)
		(layer "In9.Cu")
		(net "FM_OC_DETECT_N")
	)
	(segment
		(start 343.135458 -24.9428)
		(end 343.581228 -25.38857)
		(width 0.089408)
		(layer "In9.Cu")
		(net "FM_OC_DETECT_N")
	)
	(segment
		(start 27.188922 -74.22007)
		(end 27.188922 -82.892138)
		(width 0.089408)
		(layer "In9.Cu")
		(net "FM_OC_DETECT_N")
	)
	(segment
		(start 262.878062 -1.506982)
		(end 322.962778 -1.506982)
		(width 0.089408)
		(layer "In9.Cu")
		(net "FM_OC_DETECT_N")
	)
	(segment
		(start 331.560424 -9.59739)
		(end 332.084934 -10.1219)
		(width 0.089408)
		(layer "In9.Cu")
		(net "FM_OC_DETECT_N")
	)
	(segment
		(start 260.596126 -2.332736)
		(end 262.052308 -2.332736)
		(width 0.089408)
		(layer "In9.Cu")
		(net "FM_OC_DETECT_N")
	)
	(segment
		(start 186.501024 -4.569714)
		(end 186.035696 -4.104386)
		(width 0.089408)
		(layer "In9.Cu")
		(net "FM_OC_DETECT_N")
	)
	(segment
		(start 347.52788 -24.642318)
		(end 354.582476 -24.642318)
		(width 0.089408)
		(layer "In9.Cu")
		(net "FM_OC_DETECT_N")
	)
	(segment
		(start 343.581228 -25.38857)
		(end 346.781628 -25.38857)
		(width 0.089408)
		(layer "In9.Cu")
		(net "FM_OC_DETECT_N")
	)
	(segment
		(start 336.974688 -10.122154)
		(end 338.05622 -11.203686)
		(width 0.089408)
		(layer "In9.Cu")
		(net "FM_OC_DETECT_N")
	)
	(segment
		(start 323.798184 -4.34467)
		(end 325.821294 -6.36778)
		(width 0.089408)
		(layer "In9.Cu")
		(net "FM_OC_DETECT_N")
	)
	(segment
		(start 355.3714 -29.3624)
		(end 355.3714 -29.464)
		(width 0.089408)
		(layer "In9.Cu")
		(net "FM_OC_DETECT_N")
	)
	(segment
		(start 27.188922 -82.892138)
		(end 26.2128 -83.86826)
		(width 0.089408)
		(layer "In9.Cu")
		(net "FM_OC_DETECT_N")
	)
	(segment
		(start 186.035696 -4.104386)
		(end 186.035696 -3.544062)
		(width 0.089408)
		(layer "In9.Cu")
		(net "FM_OC_DETECT_N")
	)
	(segment
		(start 346.781628 -25.38857)
		(end 347.52788 -24.642318)
		(width 0.089408)
		(layer "In9.Cu")
		(net "FM_OC_DETECT_N")
	)
	(segment
		(start 338.05622 -20.46224)
		(end 338.665058 -21.071078)
		(width 0.089408)
		(layer "In9.Cu")
		(net "FM_OC_DETECT_N")
	)
	(segment
		(start 28.26512 -59.71286)
		(end 28.26512 -61.68898)
		(width 0.089408)
		(layer "In9.Cu")
		(net "FM_OC_DETECT_N")
	)
	(segment
		(start 332.12532 -10.122154)
		(end 336.974688 -10.122154)
		(width 0.089408)
		(layer "In9.Cu")
		(net "FM_OC_DETECT_N")
	)
	(segment
		(start 28.83154 -66.69532)
		(end 27.561794 -67.965066)
		(width 0.089408)
		(layer "In9.Cu")
		(net "FM_OC_DETECT_N")
	)
	(segment
		(start 28.53182 -55.75046)
		(end 28.53182 -59.44616)
		(width 0.089408)
		(layer "In9.Cu")
		(net "FM_OC_DETECT_N")
	)
	(segment
		(start 338.665058 -24.101044)
		(end 339.506814 -24.9428)
		(width 0.089408)
		(layer "In9.Cu")
		(net "FM_OC_DETECT_N")
	)
	(segment
		(start 188.051694 -1.528064)
		(end 193.888868 -1.528064)
		(width 0.089408)
		(layer "In9.Cu")
		(net "FM_OC_DETECT_N")
	)
	(segment
		(start 28.12796 -54.00548)
		(end 28.12796 -55.3466)
		(width 0.089408)
		(layer "In9.Cu")
		(net "FM_OC_DETECT_N")
	)
	(segment
		(start 31.58236 -50.2285)
		(end 31.58236 -50.55108)
		(width 0.089408)
		(layer "In9.Cu")
		(net "FM_OC_DETECT_N")
	)
	(segment
		(start 262.052308 -2.332736)
		(end 262.878062 -1.506982)
		(width 0.089408)
		(layer "In9.Cu")
		(net "FM_OC_DETECT_N")
	)
	(segment
		(start 356.529386 -28.204414)
		(end 355.3714 -29.3624)
		(width 0.089408)
		(layer "In9.Cu")
		(net "FM_OC_DETECT_N")
	)
	(segment
		(start 356.529386 -26.589228)
		(end 356.529386 -28.204414)
		(width 0.089408)
		(layer "In9.Cu")
		(net "FM_OC_DETECT_N")
	)
	(segment
		(start 193.888868 -1.528064)
		(end 194.608196 -0.808736)
		(width 0.089408)
		(layer "In9.Cu")
		(net "FM_OC_DETECT_N")
	)
	(segment
		(start 354.582476 -24.642318)
		(end 356.529386 -26.589228)
		(width 0.089408)
		(layer "In9.Cu")
		(net "FM_OC_DETECT_N")
	)
	(segment
		(start 259.072126 -0.808736)
		(end 260.596126 -2.332736)
		(width 0.089408)
		(layer "In9.Cu")
		(net "FM_OC_DETECT_N")
	)
	(segment
		(start 327.670414 -6.36778)
		(end 330.900024 -9.59739)
		(width 0.089408)
		(layer "In9.Cu")
		(net "FM_OC_DETECT_N")
	)
	(segment
		(start 28.53182 -59.44616)
		(end 28.26512 -59.71286)
		(width 0.089408)
		(layer "In9.Cu")
		(net "FM_OC_DETECT_N")
	)
	(segment
		(start 28.26512 -61.68898)
		(end 28.83154 -62.2554)
		(width 0.089408)
		(layer "In9.Cu")
		(net "FM_OC_DETECT_N")
	)
	(segment
		(start 186.035696 -3.544062)
		(end 188.051694 -1.528064)
		(width 0.089408)
		(layer "In9.Cu")
		(net "FM_OC_DETECT_N")
	)
	(segment
		(start 332.084934 -10.1219)
		(end 332.125066 -10.1219)
		(width 0.089408)
		(layer "In9.Cu")
		(net "FM_OC_DETECT_N")
	)
	(segment
		(start 322.962778 -1.506982)
		(end 323.798184 -2.342388)
		(width 0.089408)
		(layer "In9.Cu")
		(net "FM_OC_DETECT_N")
	)
	(segment
		(start 31.58236 -50.55108)
		(end 28.12796 -54.00548)
		(width 0.089408)
		(layer "In9.Cu")
		(net "FM_OC_DETECT_N")
	)
	(segment
		(start 28.12796 -55.3466)
		(end 28.53182 -55.75046)
		(width 0.089408)
		(layer "In9.Cu")
		(net "FM_OC_DETECT_N")
	)
	(segment
		(start 338.05622 -11.203686)
		(end 338.05622 -20.46224)
		(width 0.089408)
		(layer "In9.Cu")
		(net "FM_OC_DETECT_N")
	)
	(segment
		(start 426.137324 -0.941324)
		(end 426.137324 -1.119124)
		(width 0.089408)
		(layer "In11.Cu")
		(net "FM_OC_DETECT_N")
	)
	(segment
		(start 167.54729 -4.25704)
		(end 166.44112 -3.15087)
		(width 0.089408)
		(layer "In11.Cu")
		(net "FM_OC_DETECT_N")
	)
	(segment
		(start 474.169486 -4.502912)
		(end 474.83522 -5.168646)
		(width 0.089408)
		(layer "In11.Cu")
		(net "FM_OC_DETECT_N")
	)
	(segment
		(start 477.354392 -47.163482)
		(end 477.354392 -50.997866)
		(width 0.089408)
		(layer "In11.Cu")
		(net "FM_OC_DETECT_N")
	)
	(segment
		(start 30.5562 -49.20234)
		(end 31.58236 -50.2285)
		(width 0.089408)
		(layer "In11.Cu")
		(net "FM_OC_DETECT_N")
	)
	(segment
		(start 448.99326 2.521712)
		(end 463.24647 2.521712)
		(width 0.089408)
		(layer "In11.Cu")
		(net "FM_OC_DETECT_N")
	)
	(segment
		(start 368.989864 -4.418584)
		(end 380.561596 -4.418584)
		(width 0.089408)
		(layer "In11.Cu")
		(net "FM_OC_DETECT_N")
	)
	(segment
		(start 166.44112 -2.44094)
		(end 164.4904 -0.49022)
		(width 0.089408)
		(layer "In11.Cu")
		(net "FM_OC_DETECT_N")
	)
	(segment
		(start 478.2566 -41.741598)
		(end 475.635828 -44.36237)
		(width 0.089408)
		(layer "In11.Cu")
		(net "FM_OC_DETECT_N")
	)
	(segment
		(start 399.874232 -1.750568)
		(end 401.2184 -0.4064)
		(width 0.089408)
		(layer "In11.Cu")
		(net "FM_OC_DETECT_N")
	)
	(segment
		(start 171.66844 -5.77342)
		(end 170.15206 -4.25704)
		(width 0.089408)
		(layer "In11.Cu")
		(net "FM_OC_DETECT_N")
	)
	(segment
		(start 118.88724 3.441192)
		(end 118.460012 3.013964)
		(width 0.089408)
		(layer "In11.Cu")
		(net "FM_OC_DETECT_N")
	)
	(segment
		(start 474.83522 -5.168646)
		(end 474.83522 -6.007354)
		(width 0.089408)
		(layer "In11.Cu")
		(net "FM_OC_DETECT_N")
	)
	(segment
		(start 160.063942 -0.49022)
		(end 156.13253 3.441192)
		(width 0.089408)
		(layer "In11.Cu")
		(net "FM_OC_DETECT_N")
	)
	(segment
		(start 29.39542 -32.159448)
		(end 29.39542 -43.361356)
		(width 0.089408)
		(layer "In11.Cu")
		(net "FM_OC_DETECT_N")
	)
	(segment
		(start 475.635828 -45.444918)
		(end 477.354392 -47.163482)
		(width 0.089408)
		(layer "In11.Cu")
		(net "FM_OC_DETECT_N")
	)
	(segment
		(start 470.2937 -2.448052)
		(end 471.975688 -2.448052)
		(width 0.089408)
		(layer "In11.Cu")
		(net "FM_OC_DETECT_N")
	)
	(segment
		(start 173.0502 -8.5344)
		(end 171.66844 -7.15264)
		(width 0.089408)
		(layer "In11.Cu")
		(net "FM_OC_DETECT_N")
	)
	(segment
		(start 475.920308 -9.350248)
		(end 475.920308 -10.663936)
		(width 0.089408)
		(layer "In11.Cu")
		(net "FM_OC_DETECT_N")
	)
	(segment
		(start 475.472506 -18.481294)
		(end 475.472506 -25.329642)
		(width 0.089408)
		(layer "In11.Cu")
		(net "FM_OC_DETECT_N")
	)
	(segment
		(start 476.828104 -29.178504)
		(end 476.828104 -33.660588)
		(width 0.089408)
		(layer "In11.Cu")
		(net "FM_OC_DETECT_N")
	)
	(segment
		(start 477.354392 -50.997866)
		(end 479.698304 -53.341778)
		(width 0.089408)
		(layer "In11.Cu")
		(net "FM_OC_DETECT_N")
	)
	(segment
		(start 184.997852 -7.661402)
		(end 176.946052 -7.661402)
		(width 0.089408)
		(layer "In11.Cu")
		(net "FM_OC_DETECT_N")
	)
	(segment
		(start 118.460012 3.013964)
		(end 103.090218 3.013964)
		(width 0.089408)
		(layer "In11.Cu")
		(net "FM_OC_DETECT_N")
	)
	(segment
		(start 426.545756 -1.527556)
		(end 446.161414 -1.527556)
		(width 0.089408)
		(layer "In11.Cu")
		(net "FM_OC_DETECT_N")
	)
	(segment
		(start 28.327096 1.755902)
		(end 28.327096 -20.4978)
		(width 0.089408)
		(layer "In11.Cu")
		(net "FM_OC_DETECT_N")
	)
	(segment
		(start 479.698304 -54.044342)
		(end 479.608896 -54.13375)
		(width 0.089408)
		(layer "In11.Cu")
		(net "FM_OC_DETECT_N")
	)
	(segment
		(start 446.161414 -1.527556)
		(end 448.2338 0.54483)
		(width 0.089408)
		(layer "In11.Cu")
		(net "FM_OC_DETECT_N")
	)
	(segment
		(start 186.501024 -6.15823)
		(end 184.997852 -7.661402)
		(width 0.089408)
		(layer "In11.Cu")
		(net "FM_OC_DETECT_N")
	)
	(segment
		(start 388.885176 -3.123184)
		(end 390.257792 -1.750568)
		(width 0.089408)
		(layer "In11.Cu")
		(net "FM_OC_DETECT_N")
	)
	(segment
		(start 390.257792 -1.750568)
		(end 399.874232 -1.750568)
		(width 0.089408)
		(layer "In11.Cu")
		(net "FM_OC_DETECT_N")
	)
	(segment
		(start 465.615528 -0.11684)
		(end 465.615528 -0.998728)
		(width 0.089408)
		(layer "In11.Cu")
		(net "FM_OC_DETECT_N")
	)
	(segment
		(start 176.946052 -7.661402)
		(end 176.073054 -8.5344)
		(width 0.089408)
		(layer "In11.Cu")
		(net "FM_OC_DETECT_N")
	)
	(segment
		(start 474.689424 -12.623292)
		(end 474.689424 -17.698212)
		(width 0.089408)
		(layer "In11.Cu")
		(net "FM_OC_DETECT_N")
	)
	(segment
		(start 474.577918 -8.007858)
		(end 475.920308 -9.350248)
		(width 0.089408)
		(layer "In11.Cu")
		(net "FM_OC_DETECT_N")
	)
	(segment
		(start 468.655146 -1.397)
		(end 469.476582 -2.218436)
		(width 0.089408)
		(layer "In11.Cu")
		(net "FM_OC_DETECT_N")
	)
	(segment
		(start 474.577918 -6.264656)
		(end 474.577918 -8.007858)
		(width 0.089408)
		(layer "In11.Cu")
		(net "FM_OC_DETECT_N")
	)
	(segment
		(start 381.856996 -3.123184)
		(end 388.885176 -3.123184)
		(width 0.089408)
		(layer "In11.Cu")
		(net "FM_OC_DETECT_N")
	)
	(segment
		(start 355.2444 -29.591)
		(end 359.8418 -24.9936)
		(width 0.089408)
		(layer "In11.Cu")
		(net "FM_OC_DETECT_N")
	)
	(segment
		(start 164.4904 -0.49022)
		(end 160.063942 -0.49022)
		(width 0.089408)
		(layer "In11.Cu")
		(net "FM_OC_DETECT_N")
	)
	(segment
		(start 423.531792 1.664208)
		(end 426.137324 -0.941324)
		(width 0.089408)
		(layer "In11.Cu")
		(net "FM_OC_DETECT_N")
	)
	(segment
		(start 415.784792 -0.1524)
		(end 417.6014 1.664208)
		(width 0.089408)
		(layer "In11.Cu")
		(net "FM_OC_DETECT_N")
	)
	(segment
		(start 464.958684 1.052322)
		(end 464.958684 0.540004)
		(width 0.089408)
		(layer "In11.Cu")
		(net "FM_OC_DETECT_N")
	)
	(segment
		(start 475.635828 -44.36237)
		(end 475.635828 -45.444918)
		(width 0.089408)
		(layer "In11.Cu")
		(net "FM_OC_DETECT_N")
	)
	(segment
		(start 103.090218 3.013964)
		(end 102.47884 3.625342)
		(width 0.089408)
		(layer "In11.Cu")
		(net "FM_OC_DETECT_N")
	)
	(segment
		(start 479.698304 -53.341778)
		(end 479.698304 -54.044342)
		(width 0.089408)
		(layer "In11.Cu")
		(net "FM_OC_DETECT_N")
	)
	(segment
		(start 30.196536 3.625342)
		(end 28.327096 1.755902)
		(width 0.089408)
		(layer "In11.Cu")
		(net "FM_OC_DETECT_N")
	)
	(segment
		(start 463.24647 2.521712)
		(end 463.246724 2.521966)
		(width 0.089408)
		(layer "In11.Cu")
		(net "FM_OC_DETECT_N")
	)
	(segment
		(start 417.6014 1.664208)
		(end 423.531792 1.664208)
		(width 0.089408)
		(layer "In11.Cu")
		(net "FM_OC_DETECT_N")
	)
	(segment
		(start 477.69907 -35.878008)
		(end 477.20758 -36.369498)
		(width 0.089408)
		(layer "In11.Cu")
		(net "FM_OC_DETECT_N")
	)
	(segment
		(start 474.7768 -27.1272)
		(end 476.828104 -29.178504)
		(width 0.089408)
		(layer "In11.Cu")
		(net "FM_OC_DETECT_N")
	)
	(segment
		(start 474.83522 -6.007354)
		(end 474.577918 -6.264656)
		(width 0.089408)
		(layer "In11.Cu")
		(net "FM_OC_DETECT_N")
	)
	(segment
		(start 470.064084 -2.218436)
		(end 470.2937 -2.448052)
		(width 0.089408)
		(layer "In11.Cu")
		(net "FM_OC_DETECT_N")
	)
	(segment
		(start 463.246724 2.521966)
		(end 463.48904 2.521966)
		(width 0.089408)
		(layer "In11.Cu")
		(net "FM_OC_DETECT_N")
	)
	(segment
		(start 380.561596 -4.418584)
		(end 381.856996 -3.123184)
		(width 0.089408)
		(layer "In11.Cu")
		(net "FM_OC_DETECT_N")
	)
	(segment
		(start 479.608896 -54.13375)
		(end 479.285808 -54.13375)
		(width 0.089408)
		(layer "In11.Cu")
		(net "FM_OC_DETECT_N")
	)
	(segment
		(start 474.7768 -26.025348)
		(end 474.7768 -27.1272)
		(width 0.089408)
		(layer "In11.Cu")
		(net "FM_OC_DETECT_N")
	)
	(segment
		(start 465.615528 -0.998728)
		(end 466.0138 -1.397)
		(width 0.089408)
		(layer "In11.Cu")
		(net "FM_OC_DETECT_N")
	)
	(segment
		(start 30.5562 -44.522136)
		(end 30.5562 -49.20234)
		(width 0.089408)
		(layer "In11.Cu")
		(net "FM_OC_DETECT_N")
	)
	(segment
		(start 474.030548 -4.502912)
		(end 474.169486 -4.502912)
		(width 0.089408)
		(layer "In11.Cu")
		(net "FM_OC_DETECT_N")
	)
	(segment
		(start 466.0138 -1.397)
		(end 468.655146 -1.397)
		(width 0.089408)
		(layer "In11.Cu")
		(net "FM_OC_DETECT_N")
	)
	(segment
		(start 477.69907 -34.531554)
		(end 477.69907 -35.878008)
		(width 0.089408)
		(layer "In11.Cu")
		(net "FM_OC_DETECT_N")
	)
	(segment
		(start 407.2382 -0.1524)
		(end 415.784792 -0.1524)
		(width 0.089408)
		(layer "In11.Cu")
		(net "FM_OC_DETECT_N")
	)
	(segment
		(start 475.472506 -25.329642)
		(end 474.7768 -26.025348)
		(width 0.089408)
		(layer "In11.Cu")
		(net "FM_OC_DETECT_N")
	)
	(segment
		(start 29.39542 -43.361356)
		(end 30.5562 -44.522136)
		(width 0.089408)
		(layer "In11.Cu")
		(net "FM_OC_DETECT_N")
	)
	(segment
		(start 176.073054 -8.5344)
		(end 173.0502 -8.5344)
		(width 0.089408)
		(layer "In11.Cu")
		(net "FM_OC_DETECT_N")
	)
	(segment
		(start 478.2566 -38.656768)
		(end 478.2566 -41.741598)
		(width 0.089408)
		(layer "In11.Cu")
		(net "FM_OC_DETECT_N")
	)
	(segment
		(start 475.920562 -11.392154)
		(end 474.689424 -12.623292)
		(width 0.089408)
		(layer "In11.Cu")
		(net "FM_OC_DETECT_N")
	)
	(segment
		(start 156.13253 3.441192)
		(end 118.88724 3.441192)
		(width 0.089408)
		(layer "In11.Cu")
		(net "FM_OC_DETECT_N")
	)
	(segment
		(start 29.776928 -21.947632)
		(end 29.776928 -31.77794)
		(width 0.089408)
		(layer "In11.Cu")
		(net "FM_OC_DETECT_N")
	)
	(segment
		(start 359.8418 -13.566648)
		(end 368.989864 -4.418584)
		(width 0.089408)
		(layer "In11.Cu")
		(net "FM_OC_DETECT_N")
	)
	(segment
		(start 471.975688 -2.448052)
		(end 474.030548 -4.502912)
		(width 0.089408)
		(layer "In11.Cu")
		(net "FM_OC_DETECT_N")
	)
	(segment
		(start 186.501024 -4.569714)
		(end 186.501024 -6.15823)
		(width 0.089408)
		(layer "In11.Cu")
		(net "FM_OC_DETECT_N")
	)
	(segment
		(start 170.15206 -4.25704)
		(end 167.54729 -4.25704)
		(width 0.089408)
		(layer "In11.Cu")
		(net "FM_OC_DETECT_N")
	)
	(segment
		(start 28.327096 -20.4978)
		(end 29.776928 -21.947632)
		(width 0.089408)
		(layer "In11.Cu")
		(net "FM_OC_DETECT_N")
	)
	(segment
		(start 463.48904 2.521966)
		(end 464.958684 1.052322)
		(width 0.089408)
		(layer "In11.Cu")
		(net "FM_OC_DETECT_N")
	)
	(segment
		(start 406.9842 -0.4064)
		(end 407.2382 -0.1524)
		(width 0.089408)
		(layer "In11.Cu")
		(net "FM_OC_DETECT_N")
	)
	(segment
		(start 401.2184 -0.4064)
		(end 406.9842 -0.4064)
		(width 0.089408)
		(layer "In11.Cu")
		(net "FM_OC_DETECT_N")
	)
	(segment
		(start 475.920308 -10.663936)
		(end 475.920562 -10.66419)
		(width 0.089408)
		(layer "In11.Cu")
		(net "FM_OC_DETECT_N")
	)
	(segment
		(start 171.66844 -7.15264)
		(end 171.66844 -5.77342)
		(width 0.089408)
		(layer "In11.Cu")
		(net "FM_OC_DETECT_N")
	)
	(segment
		(start 29.776928 -31.77794)
		(end 29.39542 -32.159448)
		(width 0.089408)
		(layer "In11.Cu")
		(net "FM_OC_DETECT_N")
	)
	(segment
		(start 474.689424 -17.698212)
		(end 475.472506 -18.481294)
		(width 0.089408)
		(layer "In11.Cu")
		(net "FM_OC_DETECT_N")
	)
	(segment
		(start 448.2338 0.54483)
		(end 448.2338 1.762252)
		(width 0.089408)
		(layer "In11.Cu")
		(net "FM_OC_DETECT_N")
	)
	(segment
		(start 476.828104 -33.660588)
		(end 477.69907 -34.531554)
		(width 0.089408)
		(layer "In11.Cu")
		(net "FM_OC_DETECT_N")
	)
	(segment
		(start 477.20758 -37.607748)
		(end 478.2566 -38.656768)
		(width 0.089408)
		(layer "In11.Cu")
		(net "FM_OC_DETECT_N")
	)
	(segment
		(start 359.8418 -24.9936)
		(end 359.8418 -13.566648)
		(width 0.089408)
		(layer "In11.Cu")
		(net "FM_OC_DETECT_N")
	)
	(segment
		(start 477.20758 -36.369498)
		(end 477.20758 -37.607748)
		(width 0.089408)
		(layer "In11.Cu")
		(net "FM_OC_DETECT_N")
	)
	(segment
		(start 102.47884 3.625342)
		(end 30.196536 3.625342)
		(width 0.089408)
		(layer "In11.Cu")
		(net "FM_OC_DETECT_N")
	)
	(segment
		(start 426.137324 -1.119124)
		(end 426.545756 -1.527556)
		(width 0.089408)
		(layer "In11.Cu")
		(net "FM_OC_DETECT_N")
	)
	(segment
		(start 166.44112 -3.15087)
		(end 166.44112 -2.44094)
		(width 0.089408)
		(layer "In11.Cu")
		(net "FM_OC_DETECT_N")
	)
	(segment
		(start 469.476582 -2.218436)
		(end 470.064084 -2.218436)
		(width 0.089408)
		(layer "In11.Cu")
		(net "FM_OC_DETECT_N")
	)
	(segment
		(start 448.2338 1.762252)
		(end 448.99326 2.521712)
		(width 0.089408)
		(layer "In11.Cu")
		(net "FM_OC_DETECT_N")
	)
	(segment
		(start 475.920562 -10.66419)
		(end 475.920562 -11.392154)
		(width 0.089408)
		(layer "In11.Cu")
		(net "FM_OC_DETECT_N")
	)
	(segment
		(start 464.958684 0.540004)
		(end 465.615528 -0.11684)
		(width 0.089408)
		(layer "In11.Cu")
		(net "FM_OC_DETECT_N")
	)
	(segment
		(start 415.38017 -82.353912)
		(end 415.0868 -82.647282)
		(width 0.10795)
		(layer "F.Cu")
		(net "FM_FAST_PROCHOT_THROTTLE_IN_N")
	)
	(segment
		(start 414.655762 -84.923884)
		(end 414.655762 -85.494876)
		(width 0.10795)
		(layer "F.Cu")
		(net "FM_FAST_PROCHOT_THROTTLE_IN_N")
	)
	(segment
		(start 366.345216 -73.4949)
		(end 366.745012 -73.095104)
		(width 0.10795)
		(layer "F.Cu")
		(net "FM_FAST_PROCHOT_THROTTLE_IN_N")
	)
	(segment
		(start 415.0868 -84.492846)
		(end 414.655762 -84.923884)
		(width 0.10795)
		(layer "F.Cu")
		(net "FM_FAST_PROCHOT_THROTTLE_IN_N")
	)
	(segment
		(start 415.0868 -82.647282)
		(end 415.0868 -84.492846)
		(width 0.10795)
		(layer "F.Cu")
		(net "FM_FAST_PROCHOT_THROTTLE_IN_N")
	)
	(via
		(at 415.38017 -82.353912)
		(size 0.508)
		(drill 0.254)
		(layers "F.Cu" "B.Cu")
		(net "FM_FAST_PROCHOT_THROTTLE_IN_N")
	)
	(via
		(at 399.108422 -72.32777)
		(size 0.508)
		(drill 0.254)
		(layers "F.Cu" "B.Cu")
		(net "FM_FAST_PROCHOT_THROTTLE_IN_N")
	)
	(via
		(at 414.380426 -81.105502)
		(size 0.6604)
		(drill 0.3302)
		(layers "F.Cu" "B.Cu")
		(net "FM_FAST_PROCHOT_THROTTLE_IN_N")
	)
	(via
		(at 366.345216 -73.4949)
		(size 0.4572)
		(drill 0.2032)
		(layers "F.Cu" "B.Cu")
		(net "FM_FAST_PROCHOT_THROTTLE_IN_N")
	)
	(segment
		(start 399.585434 -71.850758)
		(end 400.675094 -71.850758)
		(width 0.10795)
		(layer "B.Cu")
		(net "FM_FAST_PROCHOT_THROTTLE_IN_N")
	)
	(segment
		(start 399.108422 -72.32777)
		(end 399.585434 -71.850758)
		(width 0.10795)
		(layer "B.Cu")
		(net "FM_FAST_PROCHOT_THROTTLE_IN_N")
	)
	(segment
		(start 401.931378 -71.848218)
		(end 402.660104 -72.576944)
		(width 0.10795)
		(layer "B.Cu")
		(net "FM_FAST_PROCHOT_THROTTLE_IN_N")
	)
	(segment
		(start 411.611826 -72.576944)
		(end 414.00222 -74.967338)
		(width 0.10795)
		(layer "B.Cu")
		(net "FM_FAST_PROCHOT_THROTTLE_IN_N")
	)
	(segment
		(start 414.00222 -80.727296)
		(end 414.380426 -81.105502)
		(width 0.10795)
		(layer "B.Cu")
		(net "FM_FAST_PROCHOT_THROTTLE_IN_N")
	)
	(segment
		(start 402.660104 -72.576944)
		(end 411.611826 -72.576944)
		(width 0.10795)
		(layer "B.Cu")
		(net "FM_FAST_PROCHOT_THROTTLE_IN_N")
	)
	(segment
		(start 415.38017 -82.105246)
		(end 415.38017 -82.353912)
		(width 0.10795)
		(layer "B.Cu")
		(net "FM_FAST_PROCHOT_THROTTLE_IN_N")
	)
	(segment
		(start 414.380426 -81.105502)
		(end 415.38017 -82.105246)
		(width 0.10795)
		(layer "B.Cu")
		(net "FM_FAST_PROCHOT_THROTTLE_IN_N")
	)
	(segment
		(start 400.675094 -71.850758)
		(end 400.677634 -71.848218)
		(width 0.10795)
		(layer "B.Cu")
		(net "FM_FAST_PROCHOT_THROTTLE_IN_N")
	)
	(segment
		(start 414.00222 -74.967338)
		(end 414.00222 -80.727296)
		(width 0.10795)
		(layer "B.Cu")
		(net "FM_FAST_PROCHOT_THROTTLE_IN_N")
	)
	(segment
		(start 400.677634 -71.848218)
		(end 401.931378 -71.848218)
		(width 0.10795)
		(layer "B.Cu")
		(net "FM_FAST_PROCHOT_THROTTLE_IN_N")
	)
	(segment
		(start 381.738378 -73.5076)
		(end 381.560578 -73.6854)
		(width 0.089408)
		(layer "In4.Cu")
		(net "FM_FAST_PROCHOT_THROTTLE_IN_N")
	)
	(segment
		(start 374.990106 -73.121774)
		(end 374.7262 -73.38568)
		(width 0.089408)
		(layer "In4.Cu")
		(net "FM_FAST_PROCHOT_THROTTLE_IN_N")
	)
	(segment
		(start 385.768088 -73.5076)
		(end 381.738378 -73.5076)
		(width 0.089408)
		(layer "In4.Cu")
		(net "FM_FAST_PROCHOT_THROTTLE_IN_N")
	)
	(segment
		(start 396.278862 -73.335896)
		(end 395.823186 -73.335896)
		(width 0.089408)
		(layer "In4.Cu")
		(net "FM_FAST_PROCHOT_THROTTLE_IN_N")
	)
	(segment
		(start 393.047982 -73.688448)
		(end 392.586464 -73.688448)
		(width 0.089408)
		(layer "In4.Cu")
		(net "FM_FAST_PROCHOT_THROTTLE_IN_N")
	)
	(segment
		(start 388.742428 -73.731628)
		(end 388.137146 -73.126346)
		(width 0.089408)
		(layer "In4.Cu")
		(net "FM_FAST_PROCHOT_THROTTLE_IN_N")
	)
	(segment
		(start 374.7262 -73.641712)
		(end 374.499378 -73.868534)
		(width 0.089408)
		(layer "In4.Cu")
		(net "FM_FAST_PROCHOT_THROTTLE_IN_N")
	)
	(segment
		(start 395.823186 -73.335896)
		(end 395.632178 -73.144888)
		(width 0.089408)
		(layer "In4.Cu")
		(net "FM_FAST_PROCHOT_THROTTLE_IN_N")
	)
	(segment
		(start 375.5644 -73.642728)
		(end 375.5644 -73.386696)
		(width 0.089408)
		(layer "In4.Cu")
		(net "FM_FAST_PROCHOT_THROTTLE_IN_N")
	)
	(segment
		(start 378.0536 -73.6854)
		(end 377.870466 -73.868534)
		(width 0.089408)
		(layer "In4.Cu")
		(net "FM_FAST_PROCHOT_THROTTLE_IN_N")
	)
	(segment
		(start 399.095468 -72.32777)
		(end 399.019776 -72.252078)
		(width 0.089408)
		(layer "In4.Cu")
		(net "FM_FAST_PROCHOT_THROTTLE_IN_N")
	)
	(segment
		(start 396.536672 -73.368408)
		(end 396.311374 -73.368408)
		(width 0.089408)
		(layer "In4.Cu")
		(net "FM_FAST_PROCHOT_THROTTLE_IN_N")
	)
	(segment
		(start 369.171728 -73.596754)
		(end 368.899948 -73.868534)
		(width 0.089408)
		(layer "In4.Cu")
		(net "FM_FAST_PROCHOT_THROTTLE_IN_N")
	)
	(segment
		(start 369.971828 -73.393808)
		(end 369.699794 -73.121774)
		(width 0.089408)
		(layer "In4.Cu")
		(net "FM_FAST_PROCHOT_THROTTLE_IN_N")
	)
	(segment
		(start 381.560578 -73.6854)
		(end 378.0536 -73.6854)
		(width 0.089408)
		(layer "In4.Cu")
		(net "FM_FAST_PROCHOT_THROTTLE_IN_N")
	)
	(segment
		(start 392.543284 -73.731628)
		(end 388.742428 -73.731628)
		(width 0.089408)
		(layer "In4.Cu")
		(net "FM_FAST_PROCHOT_THROTTLE_IN_N")
	)
	(segment
		(start 366.71885 -73.868534)
		(end 366.345216 -73.4949)
		(width 0.089408)
		(layer "In4.Cu")
		(net "FM_FAST_PROCHOT_THROTTLE_IN_N")
	)
	(segment
		(start 395.632178 -73.144888)
		(end 393.591542 -73.144888)
		(width 0.089408)
		(layer "In4.Cu")
		(net "FM_FAST_PROCHOT_THROTTLE_IN_N")
	)
	(segment
		(start 386.149342 -73.126346)
		(end 385.768088 -73.5076)
		(width 0.089408)
		(layer "In4.Cu")
		(net "FM_FAST_PROCHOT_THROTTLE_IN_N")
	)
	(segment
		(start 374.7262 -73.38568)
		(end 374.7262 -73.641712)
		(width 0.089408)
		(layer "In4.Cu")
		(net "FM_FAST_PROCHOT_THROTTLE_IN_N")
	)
	(segment
		(start 370.190522 -73.868534)
		(end 369.971828 -73.64984)
		(width 0.089408)
		(layer "In4.Cu")
		(net "FM_FAST_PROCHOT_THROTTLE_IN_N")
	)
	(segment
		(start 396.740888 -73.164192)
		(end 396.536672 -73.368408)
		(width 0.089408)
		(layer "In4.Cu")
		(net "FM_FAST_PROCHOT_THROTTLE_IN_N")
	)
	(segment
		(start 399.108422 -72.32777)
		(end 399.095468 -72.32777)
		(width 0.089408)
		(layer "In4.Cu")
		(net "FM_FAST_PROCHOT_THROTTLE_IN_N")
	)
	(segment
		(start 392.586464 -73.688448)
		(end 392.543284 -73.731628)
		(width 0.089408)
		(layer "In4.Cu")
		(net "FM_FAST_PROCHOT_THROTTLE_IN_N")
	)
	(segment
		(start 375.5644 -73.386696)
		(end 375.299478 -73.121774)
		(width 0.089408)
		(layer "In4.Cu")
		(net "FM_FAST_PROCHOT_THROTTLE_IN_N")
	)
	(segment
		(start 377.870466 -73.868534)
		(end 375.790206 -73.868534)
		(width 0.089408)
		(layer "In4.Cu")
		(net "FM_FAST_PROCHOT_THROTTLE_IN_N")
	)
	(segment
		(start 369.971828 -73.64984)
		(end 369.971828 -73.393808)
		(width 0.089408)
		(layer "In4.Cu")
		(net "FM_FAST_PROCHOT_THROTTLE_IN_N")
	)
	(segment
		(start 393.591542 -73.144888)
		(end 393.047982 -73.688448)
		(width 0.089408)
		(layer "In4.Cu")
		(net "FM_FAST_PROCHOT_THROTTLE_IN_N")
	)
	(segment
		(start 369.171728 -73.340468)
		(end 369.171728 -73.596754)
		(width 0.089408)
		(layer "In4.Cu")
		(net "FM_FAST_PROCHOT_THROTTLE_IN_N")
	)
	(segment
		(start 375.790206 -73.868534)
		(end 375.5644 -73.642728)
		(width 0.089408)
		(layer "In4.Cu")
		(net "FM_FAST_PROCHOT_THROTTLE_IN_N")
	)
	(segment
		(start 368.899948 -73.868534)
		(end 366.71885 -73.868534)
		(width 0.089408)
		(layer "In4.Cu")
		(net "FM_FAST_PROCHOT_THROTTLE_IN_N")
	)
	(segment
		(start 388.137146 -73.126346)
		(end 386.149342 -73.126346)
		(width 0.089408)
		(layer "In4.Cu")
		(net "FM_FAST_PROCHOT_THROTTLE_IN_N")
	)
	(segment
		(start 396.311374 -73.368408)
		(end 396.278862 -73.335896)
		(width 0.089408)
		(layer "In4.Cu")
		(net "FM_FAST_PROCHOT_THROTTLE_IN_N")
	)
	(segment
		(start 398.204944 -72.252078)
		(end 397.29283 -73.164192)
		(width 0.089408)
		(layer "In4.Cu")
		(net "FM_FAST_PROCHOT_THROTTLE_IN_N")
	)
	(segment
		(start 374.499378 -73.868534)
		(end 370.190522 -73.868534)
		(width 0.089408)
		(layer "In4.Cu")
		(net "FM_FAST_PROCHOT_THROTTLE_IN_N")
	)
	(segment
		(start 369.699794 -73.121774)
		(end 369.390422 -73.121774)
		(width 0.089408)
		(layer "In4.Cu")
		(net "FM_FAST_PROCHOT_THROTTLE_IN_N")
	)
	(segment
		(start 369.390422 -73.121774)
		(end 369.171728 -73.340468)
		(width 0.089408)
		(layer "In4.Cu")
		(net "FM_FAST_PROCHOT_THROTTLE_IN_N")
	)
	(segment
		(start 397.29283 -73.164192)
		(end 396.740888 -73.164192)
		(width 0.089408)
		(layer "In4.Cu")
		(net "FM_FAST_PROCHOT_THROTTLE_IN_N")
	)
	(segment
		(start 399.019776 -72.252078)
		(end 398.204944 -72.252078)
		(width 0.089408)
		(layer "In4.Cu")
		(net "FM_FAST_PROCHOT_THROTTLE_IN_N")
	)
	(segment
		(start 375.299478 -73.121774)
		(end 374.990106 -73.121774)
		(width 0.089408)
		(layer "In4.Cu")
		(net "FM_FAST_PROCHOT_THROTTLE_IN_N")
	)
	(segment
		(start 369.944904 -74.69505)
		(end 369.545108 -75.094846)
		(width 0.1016)
		(layer "F.Cu")
		(net "FM_FAST_PROCHOT_THROTTLE_DLY_N")
	)
	(via
		(at 369.545108 -75.094846)
		(size 0.4572)
		(drill 0.2032)
		(layers "F.Cu" "B.Cu")
		(net "FM_FAST_PROCHOT_THROTTLE_DLY_N")
	)
	(via
		(at 397.51 -73.787)
		(size 0.508)
		(drill 0.254)
		(layers "F.Cu" "B.Cu")
		(net "FM_FAST_PROCHOT_THROTTLE_DLY_N")
	)
	(via
		(at 405.003 -70.485)
		(size 0.6604)
		(drill 0.3302)
		(layers "F.Cu" "B.Cu")
		(net "FM_FAST_PROCHOT_THROTTLE_DLY_N")
	)
	(segment
		(start 416.640518 -72.09282)
		(end 416.640518 -68.460112)
		(width 0.10795)
		(layer "B.Cu")
		(net "FM_FAST_PROCHOT_THROTTLE_DLY_N")
	)
	(segment
		(start 412.437326 -68.96862)
		(end 412.417006 -68.98894)
		(width 0.10795)
		(layer "B.Cu")
		(net "FM_FAST_PROCHOT_THROTTLE_DLY_N")
	)
	(segment
		(start 416.889184 -75.946)
		(end 416.320732 -75.946)
		(width 0.10795)
		(layer "B.Cu")
		(net "FM_FAST_PROCHOT_THROTTLE_DLY_N")
	)
	(segment
		(start 416.212782 -75.83805)
		(end 416.212782 -74.261472)
		(width 0.10795)
		(layer "B.Cu")
		(net "FM_FAST_PROCHOT_THROTTLE_DLY_N")
	)
	(segment
		(start 405.003 -70.485)
		(end 400.28622 -70.485)
		(width 0.10795)
		(layer "B.Cu")
		(net "FM_FAST_PROCHOT_THROTTLE_DLY_N")
	)
	(segment
		(start 399.100802 -71.670418)
		(end 398.282922 -71.670418)
		(width 0.10795)
		(layer "B.Cu")
		(net "FM_FAST_PROCHOT_THROTTLE_DLY_N")
	)
	(segment
		(start 416.212782 -74.261472)
		(end 416.640772 -73.833482)
		(width 0.10795)
		(layer "B.Cu")
		(net "FM_FAST_PROCHOT_THROTTLE_DLY_N")
	)
	(segment
		(start 412.180532 -68.98894)
		(end 411.933136 -69.236336)
		(width 0.10795)
		(layer "B.Cu")
		(net "FM_FAST_PROCHOT_THROTTLE_DLY_N")
	)
	(segment
		(start 400.28622 -70.485)
		(end 399.100802 -71.670418)
		(width 0.10795)
		(layer "B.Cu")
		(net "FM_FAST_PROCHOT_THROTTLE_DLY_N")
	)
	(segment
		(start 415.408364 -68.035678)
		(end 414.475422 -68.96862)
		(width 0.10795)
		(layer "B.Cu")
		(net "FM_FAST_PROCHOT_THROTTLE_DLY_N")
	)
	(segment
		(start 416.640772 -72.093074)
		(end 416.640518 -72.09282)
		(width 0.10795)
		(layer "B.Cu")
		(net "FM_FAST_PROCHOT_THROTTLE_DLY_N")
	)
	(segment
		(start 397.51 -73.72604)
		(end 397.51 -73.787)
		(width 0.10795)
		(layer "B.Cu")
		(net "FM_FAST_PROCHOT_THROTTLE_DLY_N")
	)
	(segment
		(start 416.320732 -75.946)
		(end 416.212782 -75.83805)
		(width 0.10795)
		(layer "B.Cu")
		(net "FM_FAST_PROCHOT_THROTTLE_DLY_N")
	)
	(segment
		(start 416.21583 -68.035424)
		(end 415.98469 -68.035424)
		(width 0.10795)
		(layer "B.Cu")
		(net "FM_FAST_PROCHOT_THROTTLE_DLY_N")
	)
	(segment
		(start 416.640518 -68.460112)
		(end 416.21583 -68.035424)
		(width 0.10795)
		(layer "B.Cu")
		(net "FM_FAST_PROCHOT_THROTTLE_DLY_N")
	)
	(segment
		(start 416.640772 -73.833482)
		(end 416.640772 -72.093074)
		(width 0.10795)
		(layer "B.Cu")
		(net "FM_FAST_PROCHOT_THROTTLE_DLY_N")
	)
	(segment
		(start 415.98469 -68.035424)
		(end 415.984436 -68.035678)
		(width 0.10795)
		(layer "B.Cu")
		(net "FM_FAST_PROCHOT_THROTTLE_DLY_N")
	)
	(segment
		(start 411.933136 -69.236336)
		(end 411.933136 -69.28104)
		(width 0.10795)
		(layer "B.Cu")
		(net "FM_FAST_PROCHOT_THROTTLE_DLY_N")
	)
	(segment
		(start 411.866588 -69.28104)
		(end 410.662628 -70.485)
		(width 0.10795)
		(layer "B.Cu")
		(net "FM_FAST_PROCHOT_THROTTLE_DLY_N")
	)
	(segment
		(start 397.41602 -73.63206)
		(end 397.51 -73.72604)
		(width 0.10795)
		(layer "B.Cu")
		(net "FM_FAST_PROCHOT_THROTTLE_DLY_N")
	)
	(segment
		(start 410.662628 -70.485)
		(end 405.003 -70.485)
		(width 0.10795)
		(layer "B.Cu")
		(net "FM_FAST_PROCHOT_THROTTLE_DLY_N")
	)
	(segment
		(start 398.282922 -71.670418)
		(end 397.41602 -72.53732)
		(width 0.10795)
		(layer "B.Cu")
		(net "FM_FAST_PROCHOT_THROTTLE_DLY_N")
	)
	(segment
		(start 397.41602 -72.53732)
		(end 397.41602 -73.63206)
		(width 0.10795)
		(layer "B.Cu")
		(net "FM_FAST_PROCHOT_THROTTLE_DLY_N")
	)
	(segment
		(start 412.417006 -68.98894)
		(end 412.180532 -68.98894)
		(width 0.10795)
		(layer "B.Cu")
		(net "FM_FAST_PROCHOT_THROTTLE_DLY_N")
	)
	(segment
		(start 414.475422 -68.96862)
		(end 412.437326 -68.96862)
		(width 0.10795)
		(layer "B.Cu")
		(net "FM_FAST_PROCHOT_THROTTLE_DLY_N")
	)
	(segment
		(start 411.933136 -69.28104)
		(end 411.866588 -69.28104)
		(width 0.10795)
		(layer "B.Cu")
		(net "FM_FAST_PROCHOT_THROTTLE_DLY_N")
	)
	(segment
		(start 415.984436 -68.035678)
		(end 415.408364 -68.035678)
		(width 0.10795)
		(layer "B.Cu")
		(net "FM_FAST_PROCHOT_THROTTLE_DLY_N")
	)
	(segment
		(start 392.74496 -74.070464)
		(end 391.682224 -75.1332)
		(width 0.089408)
		(layer "In4.Cu")
		(net "FM_FAST_PROCHOT_THROTTLE_DLY_N")
	)
	(segment
		(start 390.055862 -74.791062)
		(end 389.325612 -74.791062)
		(width 0.089408)
		(layer "In4.Cu")
		(net "FM_FAST_PROCHOT_THROTTLE_DLY_N")
	)
	(segment
		(start 386.966206 -73.796652)
		(end 385.702556 -75.060302)
		(width 0.089408)
		(layer "In4.Cu")
		(net "FM_FAST_PROCHOT_THROTTLE_DLY_N")
	)
	(segment
		(start 389.325358 -74.791316)
		(end 389.16737 -74.791316)
		(width 0.089408)
		(layer "In4.Cu")
		(net "FM_FAST_PROCHOT_THROTTLE_DLY_N")
	)
	(segment
		(start 378.294646 -74.530712)
		(end 370.109242 -74.530712)
		(width 0.089408)
		(layer "In4.Cu")
		(net "FM_FAST_PROCHOT_THROTTLE_DLY_N")
	)
	(segment
		(start 370.109242 -74.530712)
		(end 369.545108 -75.094846)
		(width 0.089408)
		(layer "In4.Cu")
		(net "FM_FAST_PROCHOT_THROTTLE_DLY_N")
	)
	(segment
		(start 391.682224 -75.1332)
		(end 390.398 -75.1332)
		(width 0.089408)
		(layer "In4.Cu")
		(net "FM_FAST_PROCHOT_THROTTLE_DLY_N")
	)
	(segment
		(start 390.398 -75.1332)
		(end 390.055862 -74.791062)
		(width 0.089408)
		(layer "In4.Cu")
		(net "FM_FAST_PROCHOT_THROTTLE_DLY_N")
	)
	(segment
		(start 397.51 -73.85304)
		(end 397.226536 -74.136504)
		(width 0.089408)
		(layer "In4.Cu")
		(net "FM_FAST_PROCHOT_THROTTLE_DLY_N")
	)
	(segment
		(start 385.702556 -75.060302)
		(end 378.824236 -75.060302)
		(width 0.089408)
		(layer "In4.Cu")
		(net "FM_FAST_PROCHOT_THROTTLE_DLY_N")
	)
	(segment
		(start 389.16737 -74.791316)
		(end 389.167116 -74.791062)
		(width 0.089408)
		(layer "In4.Cu")
		(net "FM_FAST_PROCHOT_THROTTLE_DLY_N")
	)
	(segment
		(start 394.390118 -74.070464)
		(end 392.74496 -74.070464)
		(width 0.089408)
		(layer "In4.Cu")
		(net "FM_FAST_PROCHOT_THROTTLE_DLY_N")
	)
	(segment
		(start 395.161262 -74.136504)
		(end 395.085062 -74.212704)
		(width 0.089408)
		(layer "In4.Cu")
		(net "FM_FAST_PROCHOT_THROTTLE_DLY_N")
	)
	(segment
		(start 388.991094 -74.791062)
		(end 387.996684 -73.796652)
		(width 0.089408)
		(layer "In4.Cu")
		(net "FM_FAST_PROCHOT_THROTTLE_DLY_N")
	)
	(segment
		(start 389.325612 -74.791062)
		(end 389.325358 -74.791316)
		(width 0.089408)
		(layer "In4.Cu")
		(net "FM_FAST_PROCHOT_THROTTLE_DLY_N")
	)
	(segment
		(start 378.824236 -75.060302)
		(end 378.294646 -74.530712)
		(width 0.089408)
		(layer "In4.Cu")
		(net "FM_FAST_PROCHOT_THROTTLE_DLY_N")
	)
	(segment
		(start 394.532358 -74.212704)
		(end 394.390118 -74.070464)
		(width 0.089408)
		(layer "In4.Cu")
		(net "FM_FAST_PROCHOT_THROTTLE_DLY_N")
	)
	(segment
		(start 389.167116 -74.791062)
		(end 388.991094 -74.791062)
		(width 0.089408)
		(layer "In4.Cu")
		(net "FM_FAST_PROCHOT_THROTTLE_DLY_N")
	)
	(segment
		(start 387.996684 -73.796652)
		(end 386.966206 -73.796652)
		(width 0.089408)
		(layer "In4.Cu")
		(net "FM_FAST_PROCHOT_THROTTLE_DLY_N")
	)
	(segment
		(start 395.085062 -74.212704)
		(end 394.532358 -74.212704)
		(width 0.089408)
		(layer "In4.Cu")
		(net "FM_FAST_PROCHOT_THROTTLE_DLY_N")
	)
	(segment
		(start 397.51 -73.787)
		(end 397.51 -73.85304)
		(width 0.089408)
		(layer "In4.Cu")
		(net "FM_FAST_PROCHOT_THROTTLE_DLY_N")
	)
	(segment
		(start 397.226536 -74.136504)
		(end 395.161262 -74.136504)
		(width 0.089408)
		(layer "In4.Cu")
		(net "FM_FAST_PROCHOT_THROTTLE_DLY_N")
	)
	(segment
		(start 423.580052 -80.984598)
		(end 423.580052 -87.311738)
		(width 0.10795)
		(layer "F.Cu")
		(net "FM_FAST_PROCHOT_AND_OUT_0_N")
	)
	(segment
		(start 415.3408 -82.926428)
		(end 415.490914 -82.776314)
		(width 0.10795)
		(layer "F.Cu")
		(net "FM_FAST_PROCHOT_AND_OUT_0_N")
	)
	(segment
		(start 419.4937 -88.6333)
		(end 418.0586 -90.0684)
		(width 0.10795)
		(layer "F.Cu")
		(net "FM_FAST_PROCHOT_AND_OUT_0_N")
	)
	(segment
		(start 423.580052 -87.311738)
		(end 422.25849 -88.6333)
		(width 0.10795)
		(layer "F.Cu")
		(net "FM_FAST_PROCHOT_AND_OUT_0_N")
	)
	(segment
		(start 415.155888 -85.494876)
		(end 415.155888 -84.720176)
		(width 0.10795)
		(layer "F.Cu")
		(net "FM_FAST_PROCHOT_AND_OUT_0_N")
	)
	(segment
		(start 422.25849 -88.6333)
		(end 419.4937 -88.6333)
		(width 0.10795)
		(layer "F.Cu")
		(net "FM_FAST_PROCHOT_AND_OUT_0_N")
	)
	(segment
		(start 415.3408 -84.535264)
		(end 415.3408 -82.926428)
		(width 0.10795)
		(layer "F.Cu")
		(net "FM_FAST_PROCHOT_AND_OUT_0_N")
	)
	(segment
		(start 415.594292 -90.282268)
		(end 415.376868 -90.282268)
		(width 0.10795)
		(layer "F.Cu")
		(net "FM_FAST_PROCHOT_AND_OUT_0_N")
	)
	(segment
		(start 415.155888 -90.061288)
		(end 415.376868 -90.282268)
		(width 0.10795)
		(layer "F.Cu")
		(net "FM_FAST_PROCHOT_AND_OUT_0_N")
	)
	(segment
		(start 415.490914 -82.776314)
		(end 415.555176 -82.776314)
		(width 0.10795)
		(layer "F.Cu")
		(net "FM_FAST_PROCHOT_AND_OUT_0_N")
	)
	(segment
		(start 415.802572 -82.528918)
		(end 415.901632 -82.528918)
		(width 0.10795)
		(layer "F.Cu")
		(net "FM_FAST_PROCHOT_AND_OUT_0_N")
	)
	(segment
		(start 415.80816 -90.0684)
		(end 415.594292 -90.282268)
		(width 0.10795)
		(layer "F.Cu")
		(net "FM_FAST_PROCHOT_AND_OUT_0_N")
	)
	(segment
		(start 419.599364 -79.020162)
		(end 419.775386 -78.84414)
		(width 0.10795)
		(layer "F.Cu")
		(net "FM_FAST_PROCHOT_AND_OUT_0_N")
	)
	(segment
		(start 417.245038 -80.183228)
		(end 418.408104 -79.020162)
		(width 0.10795)
		(layer "F.Cu")
		(net "FM_FAST_PROCHOT_AND_OUT_0_N")
	)
	(segment
		(start 418.408104 -79.020162)
		(end 419.599364 -79.020162)
		(width 0.10795)
		(layer "F.Cu")
		(net "FM_FAST_PROCHOT_AND_OUT_0_N")
	)
	(segment
		(start 419.775386 -78.84414)
		(end 421.439594 -78.84414)
		(width 0.10795)
		(layer "F.Cu")
		(net "FM_FAST_PROCHOT_AND_OUT_0_N")
	)
	(segment
		(start 415.155888 -88.823292)
		(end 415.155888 -90.061288)
		(width 0.10795)
		(layer "F.Cu")
		(net "FM_FAST_PROCHOT_AND_OUT_0_N")
	)
	(segment
		(start 417.245038 -81.185512)
		(end 417.245038 -80.183228)
		(width 0.10795)
		(layer "F.Cu")
		(net "FM_FAST_PROCHOT_AND_OUT_0_N")
	)
	(segment
		(start 415.155888 -84.720176)
		(end 415.3408 -84.535264)
		(width 0.10795)
		(layer "F.Cu")
		(net "FM_FAST_PROCHOT_AND_OUT_0_N")
	)
	(segment
		(start 415.555176 -82.776314)
		(end 415.802572 -82.528918)
		(width 0.10795)
		(layer "F.Cu")
		(net "FM_FAST_PROCHOT_AND_OUT_0_N")
	)
	(segment
		(start 415.901632 -82.528918)
		(end 417.245038 -81.185512)
		(width 0.10795)
		(layer "F.Cu")
		(net "FM_FAST_PROCHOT_AND_OUT_0_N")
	)
	(segment
		(start 418.0586 -90.0684)
		(end 415.80816 -90.0684)
		(width 0.10795)
		(layer "F.Cu")
		(net "FM_FAST_PROCHOT_AND_OUT_0_N")
	)
	(segment
		(start 421.439594 -78.84414)
		(end 423.580052 -80.984598)
		(width 0.10795)
		(layer "F.Cu")
		(net "FM_FAST_PROCHOT_AND_OUT_0_N")
	)
	(via
		(at 415.376868 -90.282268)
		(size 0.762)
		(drill 0.381)
		(layers "F.Cu" "B.Cu")
		(net "FM_FAST_PROCHOT_AND_OUT_0_N")
	)
	(segment
		(start 382.387348 -110.39602)
		(end 382.28905 -109.855)
		(width 0.127)
		(layer "F.Cu")
		(net "VSENSE_PVNN_PCH_STBY_QAT")
	)
	(segment
		(start 369.544346 -135.297418)
		(end 369.6716 -135.424672)
		(width 0.127)
		(layer "F.Cu")
		(net "VSENSE_PVNN_PCH_STBY_QAT")
	)
	(segment
		(start 369.8494 -136.1821)
		(end 369.57 -136.4615)
		(width 0.127)
		(layer "F.Cu")
		(net "VSENSE_PVNN_PCH_STBY_QAT")
	)
	(segment
		(start 369.6716 -135.6614)
		(end 369.8494 -135.8392)
		(width 0.127)
		(layer "F.Cu")
		(net "VSENSE_PVNN_PCH_STBY_QAT")
	)
	(segment
		(start 369.197382 -135.297418)
		(end 369.544346 -135.297418)
		(width 0.127)
		(layer "F.Cu")
		(net "VSENSE_PVNN_PCH_STBY_QAT")
	)
	(segment
		(start 369.6716 -135.424672)
		(end 369.6716 -135.6614)
		(width 0.127)
		(layer "F.Cu")
		(net "VSENSE_PVNN_PCH_STBY_QAT")
	)
	(segment
		(start 369.8494 -135.8392)
		(end 369.8494 -136.1821)
		(width 0.127)
		(layer "F.Cu")
		(net "VSENSE_PVNN_PCH_STBY_QAT")
	)
	(via
		(at 382.387348 -110.39602)
		(size 0.508)
		(drill 0.254)
		(layers "F.Cu" "B.Cu")
		(net "VSENSE_PVNN_PCH_STBY_QAT")
	)
	(via
		(at 369.197382 -135.297418)
		(size 0.508)
		(drill 0.254)
		(layers "F.Cu" "B.Cu")
		(net "VSENSE_PVNN_PCH_STBY_QAT")
	)
	(segment
		(start 382.27 -110.39602)
		(end 382.387348 -110.39602)
		(width 0.0889)
		(layer "In2.Cu")
		(net "VSENSE_PVNN_PCH_STBY_QAT")
	)
	(segment
		(start 381.84963 -111.024162)
		(end 381.84963 -110.81639)
		(width 0.0889)
		(layer "In2.Cu")
		(net "VSENSE_PVNN_PCH_STBY_QAT")
	)
	(segment
		(start 368.748564 -134.8486)
		(end 367.613946 -134.8486)
		(width 0.127)
		(layer "In2.Cu")
		(net "VSENSE_PVNN_PCH_STBY_QAT")
	)
	(segment
		(start 367.283746 -134.308088)
		(end 367.284 -134.307834)
		(width 0.127)
		(layer "In2.Cu")
		(net "VSENSE_PVNN_PCH_STBY_QAT")
	)
	(segment
		(start 373.460264 -126.377954)
		(end 374.499632 -126.377954)
		(width 0.127)
		(layer "In2.Cu")
		(net "VSENSE_PVNN_PCH_STBY_QAT")
	)
	(segment
		(start 367.284 -134.307834)
		(end 367.284 -128.037336)
		(width 0.127)
		(layer "In2.Cu")
		(net "VSENSE_PVNN_PCH_STBY_QAT")
	)
	(segment
		(start 382.1938 -122.11558)
		(end 382.1938 -122.082814)
		(width 0.0889)
		(layer "In2.Cu")
		(net "VSENSE_PVNN_PCH_STBY_QAT")
	)
	(segment
		(start 381.6985 -117.833394)
		(end 381.6985 -117.790214)
		(width 0.0889)
		(layer "In2.Cu")
		(net "VSENSE_PVNN_PCH_STBY_QAT")
	)
	(segment
		(start 373.31777 -126.23546)
		(end 373.460264 -126.377954)
		(width 0.127)
		(layer "In2.Cu")
		(net "VSENSE_PVNN_PCH_STBY_QAT")
	)
	(segment
		(start 380.684278 -125.095)
		(end 381.66675 -124.112528)
		(width 0.127)
		(layer "In2.Cu")
		(net "VSENSE_PVNN_PCH_STBY_QAT")
	)
	(segment
		(start 381.29845 -111.818674)
		(end 381.29845 -111.785654)
		(width 0.0889)
		(layer "In2.Cu")
		(net "VSENSE_PVNN_PCH_STBY_QAT")
	)
	(segment
		(start 367.283746 -134.5184)
		(end 367.283746 -134.308088)
		(width 0.127)
		(layer "In2.Cu")
		(net "VSENSE_PVNN_PCH_STBY_QAT")
	)
	(segment
		(start 369.197382 -135.297418)
		(end 368.748564 -134.8486)
		(width 0.127)
		(layer "In2.Cu")
		(net "VSENSE_PVNN_PCH_STBY_QAT")
	)
	(segment
		(start 381.6985 -119.550434)
		(end 381.6985 -119.507254)
		(width 0.0889)
		(layer "In2.Cu")
		(net "VSENSE_PVNN_PCH_STBY_QAT")
	)
	(segment
		(start 368.943382 -126.377954)
		(end 370.538756 -126.377954)
		(width 0.127)
		(layer "In2.Cu")
		(net "VSENSE_PVNN_PCH_STBY_QAT")
	)
	(segment
		(start 367.284 -128.037336)
		(end 368.943382 -126.377954)
		(width 0.127)
		(layer "In2.Cu")
		(net "VSENSE_PVNN_PCH_STBY_QAT")
	)
	(segment
		(start 381.66675 -123.761246)
		(end 381.66675 -123.739148)
		(width 0.0889)
		(layer "In2.Cu")
		(net "VSENSE_PVNN_PCH_STBY_QAT")
	)
	(segment
		(start 370.68125 -126.23546)
		(end 373.31777 -126.23546)
		(width 0.127)
		(layer "In2.Cu")
		(net "VSENSE_PVNN_PCH_STBY_QAT")
	)
	(segment
		(start 381.29845 -113.707164)
		(end 381.29845 -113.502694)
		(width 0.0889)
		(layer "In2.Cu")
		(net "VSENSE_PVNN_PCH_STBY_QAT")
	)
	(segment
		(start 381.297942 -115.259612)
		(end 381.29845 -115.248944)
		(width 0.0889)
		(layer "In2.Cu")
		(net "VSENSE_PVNN_PCH_STBY_QAT")
	)
	(segment
		(start 381.66675 -123.739148)
		(end 381.6985 -123.707398)
		(width 0.0889)
		(layer "In2.Cu")
		(net "VSENSE_PVNN_PCH_STBY_QAT")
	)
	(segment
		(start 382.1938 -120.408954)
		(end 382.1938 -120.376188)
		(width 0.0889)
		(layer "In2.Cu")
		(net "VSENSE_PVNN_PCH_STBY_QAT")
	)
	(segment
		(start 374.499632 -126.377954)
		(end 375.782586 -125.095)
		(width 0.127)
		(layer "In2.Cu")
		(net "VSENSE_PVNN_PCH_STBY_QAT")
	)
	(segment
		(start 380.806452 -114.415062)
		(end 380.81966 -114.239548)
		(width 0.0889)
		(layer "In2.Cu")
		(net "VSENSE_PVNN_PCH_STBY_QAT")
	)
	(segment
		(start 381.5461 -111.372904)
		(end 381.84963 -111.024162)
		(width 0.0889)
		(layer "In2.Cu")
		(net "VSENSE_PVNN_PCH_STBY_QAT")
	)
	(segment
		(start 380.80315 -112.677194)
		(end 380.80315 -112.644174)
		(width 0.0889)
		(layer "In2.Cu")
		(net "VSENSE_PVNN_PCH_STBY_QAT")
	)
	(segment
		(start 367.613946 -134.8486)
		(end 367.283746 -134.5184)
		(width 0.127)
		(layer "In2.Cu")
		(net "VSENSE_PVNN_PCH_STBY_QAT")
	)
	(segment
		(start 381.197612 -114.93627)
		(end 381.005588 -114.813334)
		(width 0.0889)
		(layer "In2.Cu")
		(net "VSENSE_PVNN_PCH_STBY_QAT")
	)
	(segment
		(start 381.66675 -124.112528)
		(end 381.66675 -123.761246)
		(width 0.127)
		(layer "In2.Cu")
		(net "VSENSE_PVNN_PCH_STBY_QAT")
	)
	(segment
		(start 381.84963 -110.81639)
		(end 382.27 -110.39602)
		(width 0.0889)
		(layer "In2.Cu")
		(net "VSENSE_PVNN_PCH_STBY_QAT")
	)
	(segment
		(start 380.80315 -116.111274)
		(end 380.80315 -116.078254)
		(width 0.0889)
		(layer "In2.Cu")
		(net "VSENSE_PVNN_PCH_STBY_QAT")
	)
	(segment
		(start 370.538756 -126.377954)
		(end 370.68125 -126.23546)
		(width 0.127)
		(layer "In2.Cu")
		(net "VSENSE_PVNN_PCH_STBY_QAT")
	)
	(segment
		(start 381.6985 -123.707398)
		(end 381.6985 -122.941334)
		(width 0.0889)
		(layer "In2.Cu")
		(net "VSENSE_PVNN_PCH_STBY_QAT")
	)
	(segment
		(start 375.782586 -125.095)
		(end 380.684278 -125.095)
		(width 0.127)
		(layer "In2.Cu")
		(net "VSENSE_PVNN_PCH_STBY_QAT")
	)
	(arc
		(start 380.80315 -112.644174)
		(mid 380.873498 -112.405713)
		(end 381.0508 -112.231424)
		(width 0.0889)
		(layer "In2.Cu")
		(net "VSENSE_PVNN_PCH_STBY_QAT")
	)
	(arc
		(start 381.6985 -117.790214)
		(mid 381.664346 -117.61126)
		(end 381.566674 -117.457474)
		(width 0.0889)
		(layer "In2.Cu")
		(net "VSENSE_PVNN_PCH_STBY_QAT")
	)
	(arc
		(start 381.993648 -120.040654)
		(mid 381.782784 -119.83365)
		(end 381.6985 -119.550434)
		(width 0.0889)
		(layer "In2.Cu")
		(net "VSENSE_PVNN_PCH_STBY_QAT")
	)
	(arc
		(start 381.29845 -115.248944)
		(mid 381.274729 -115.083992)
		(end 381.197612 -114.93627)
		(width 0.0889)
		(layer "In2.Cu")
		(net "VSENSE_PVNN_PCH_STBY_QAT")
	)
	(arc
		(start 382.488948 -121.592594)
		(mid 382.631838 -121.452435)
		(end 382.6891 -121.260616)
		(width 0.0889)
		(layer "In2.Cu")
		(net "VSENSE_PVNN_PCH_STBY_QAT")
	)
	(arc
		(start 381.0508 -112.231424)
		(mid 381.228102 -112.057135)
		(end 381.29845 -111.818674)
		(width 0.0889)
		(layer "In2.Cu")
		(net "VSENSE_PVNN_PCH_STBY_QAT")
	)
	(arc
		(start 381.993648 -118.323614)
		(mid 381.782784 -118.11661)
		(end 381.6985 -117.833394)
		(width 0.0889)
		(layer "In2.Cu")
		(net "VSENSE_PVNN_PCH_STBY_QAT")
	)
	(arc
		(start 381.0508 -113.089944)
		(mid 380.873498 -112.915655)
		(end 380.80315 -112.677194)
		(width 0.0889)
		(layer "In2.Cu")
		(net "VSENSE_PVNN_PCH_STBY_QAT")
	)
	(arc
		(start 381.566674 -117.457474)
		(mid 381.396054 -117.215932)
		(end 381.29845 -116.936774)
		(width 0.0889)
		(layer "In2.Cu")
		(net "VSENSE_PVNN_PCH_STBY_QAT")
	)
	(arc
		(start 381.6985 -119.507254)
		(mid 381.782781 -119.224037)
		(end 381.993648 -119.017034)
		(width 0.0889)
		(layer "In2.Cu")
		(net "VSENSE_PVNN_PCH_STBY_QAT")
	)
	(arc
		(start 381.6985 -122.941334)
		(mid 381.782781 -122.658117)
		(end 381.993648 -122.451114)
		(width 0.0889)
		(layer "In2.Cu")
		(net "VSENSE_PVNN_PCH_STBY_QAT")
	)
	(arc
		(start 381.29845 -116.936774)
		(mid 381.228102 -116.698313)
		(end 381.0508 -116.524024)
		(width 0.0889)
		(layer "In2.Cu")
		(net "VSENSE_PVNN_PCH_STBY_QAT")
	)
	(arc
		(start 382.1938 -118.655846)
		(mid 382.136692 -118.463829)
		(end 381.993648 -118.323614)
		(width 0.0889)
		(layer "In2.Cu")
		(net "VSENSE_PVNN_PCH_STBY_QAT")
	)
	(arc
		(start 381.993648 -119.017034)
		(mid 382.136538 -118.876875)
		(end 382.1938 -118.685056)
		(width 0.0889)
		(layer "In2.Cu")
		(net "VSENSE_PVNN_PCH_STBY_QAT")
	)
	(arc
		(start 382.488948 -120.899174)
		(mid 382.278084 -120.69217)
		(end 382.1938 -120.408954)
		(width 0.0889)
		(layer "In2.Cu")
		(net "VSENSE_PVNN_PCH_STBY_QAT")
	)
	(arc
		(start 381.0508 -116.524024)
		(mid 380.873498 -116.349735)
		(end 380.80315 -116.111274)
		(width 0.0889)
		(layer "In2.Cu")
		(net "VSENSE_PVNN_PCH_STBY_QAT")
	)
	(arc
		(start 381.993648 -122.451114)
		(mid 382.137452 -122.309431)
		(end 382.1938 -122.11558)
		(width 0.0889)
		(layer "In2.Cu")
		(net "VSENSE_PVNN_PCH_STBY_QAT")
	)
	(arc
		(start 382.6891 -121.231406)
		(mid 382.631992 -121.039389)
		(end 382.488948 -120.899174)
		(width 0.0889)
		(layer "In2.Cu")
		(net "VSENSE_PVNN_PCH_STBY_QAT")
	)
	(arc
		(start 381.29845 -113.502694)
		(mid 381.228102 -113.264233)
		(end 381.0508 -113.089944)
		(width 0.0889)
		(layer "In2.Cu")
		(net "VSENSE_PVNN_PCH_STBY_QAT")
	)
	(arc
		(start 382.1938 -120.376188)
		(mid 382.13745 -120.182338)
		(end 381.993648 -120.040654)
		(width 0.0889)
		(layer "In2.Cu")
		(net "VSENSE_PVNN_PCH_STBY_QAT")
	)
	(arc
		(start 382.6891 -121.260616)
		(mid 382.689362 -121.246011)
		(end 382.6891 -121.231406)
		(width 0.0889)
		(layer "In2.Cu")
		(net "VSENSE_PVNN_PCH_STBY_QAT")
	)
	(arc
		(start 381.053848 -113.985802)
		(mid 381.201287 -113.868561)
		(end 381.29845 -113.707164)
		(width 0.0889)
		(layer "In2.Cu")
		(net "VSENSE_PVNN_PCH_STBY_QAT")
	)
	(arc
		(start 380.81966 -114.239548)
		(mid 380.915508 -114.093069)
		(end 381.053848 -113.985802)
		(width 0.0889)
		(layer "In2.Cu")
		(net "VSENSE_PVNN_PCH_STBY_QAT")
	)
	(arc
		(start 382.1938 -118.685056)
		(mid 382.194062 -118.670451)
		(end 382.1938 -118.655846)
		(width 0.0889)
		(layer "In2.Cu")
		(net "VSENSE_PVNN_PCH_STBY_QAT")
	)
	(arc
		(start 380.80315 -116.078254)
		(mid 380.873498 -115.839793)
		(end 381.0508 -115.665504)
		(width 0.0889)
		(layer "In2.Cu")
		(net "VSENSE_PVNN_PCH_STBY_QAT")
	)
	(arc
		(start 382.1938 -122.082814)
		(mid 382.278081 -121.799597)
		(end 382.488948 -121.592594)
		(width 0.0889)
		(layer "In2.Cu")
		(net "VSENSE_PVNN_PCH_STBY_QAT")
	)
	(arc
		(start 381.29845 -111.785654)
		(mid 381.368798 -111.547193)
		(end 381.5461 -111.372904)
		(width 0.0889)
		(layer "In2.Cu")
		(net "VSENSE_PVNN_PCH_STBY_QAT")
	)
	(arc
		(start 381.0508 -115.665504)
		(mid 381.226149 -115.494101)
		(end 381.297942 -115.259612)
		(width 0.0889)
		(layer "In2.Cu")
		(net "VSENSE_PVNN_PCH_STBY_QAT")
	)
	(arc
		(start 381.005588 -114.813334)
		(mid 380.851039 -114.641671)
		(end 380.806452 -114.415062)
		(width 0.0889)
		(layer "In2.Cu")
		(net "VSENSE_PVNN_PCH_STBY_QAT")
	)
	(segment
		(start 368.689382 -134.078218)
		(end 368.812572 -134.078218)
		(width 0.127)
		(layer "F.Cu")
		(net "VSENSE_PVNN_PCH_STBY_FPK")
	)
	(segment
		(start 369.9256 -135.191246)
		(end 369.9256 -135.55599)
		(width 0.127)
		(layer "F.Cu")
		(net "VSENSE_PVNN_PCH_STBY_FPK")
	)
	(segment
		(start 370.1034 -135.73379)
		(end 370.1034 -136.2329)
		(width 0.127)
		(layer "F.Cu")
		(net "VSENSE_PVNN_PCH_STBY_FPK")
	)
	(segment
		(start 368.812572 -134.078218)
		(end 369.9256 -135.191246)
		(width 0.127)
		(layer "F.Cu")
		(net "VSENSE_PVNN_PCH_STBY_FPK")
	)
	(segment
		(start 369.9256 -135.55599)
		(end 370.1034 -135.73379)
		(width 0.127)
		(layer "F.Cu")
		(net "VSENSE_PVNN_PCH_STBY_FPK")
	)
	(segment
		(start 370.1034 -136.2329)
		(end 370.332 -136.4615)
		(width 0.127)
		(layer "F.Cu")
		(net "VSENSE_PVNN_PCH_STBY_FPK")
	)
	(segment
		(start 387.73735 -109.45495)
		(end 387.3373 -109.0549)
		(width 0.127)
		(layer "F.Cu")
		(net "VSENSE_PVNN_PCH_STBY_FPK")
	)
	(via
		(at 387.3373 -109.0549)
		(size 0.508)
		(drill 0.254)
		(layers "F.Cu" "B.Cu")
		(net "VSENSE_PVNN_PCH_STBY_FPK")
	)
	(via
		(at 368.689382 -134.078218)
		(size 0.508)
		(drill 0.254)
		(layers "F.Cu" "B.Cu")
		(net "VSENSE_PVNN_PCH_STBY_FPK")
	)
	(segment
		(start 367.538 -128.142746)
		(end 369.048792 -126.631954)
		(width 0.127)
		(layer "In2.Cu")
		(net "VSENSE_PVNN_PCH_STBY_FPK")
	)
	(segment
		(start 373.21236 -126.48946)
		(end 373.354854 -126.631954)
		(width 0.127)
		(layer "In2.Cu")
		(net "VSENSE_PVNN_PCH_STBY_FPK")
	)
	(segment
		(start 369.048792 -126.631954)
		(end 370.644166 -126.631954)
		(width 0.127)
		(layer "In2.Cu")
		(net "VSENSE_PVNN_PCH_STBY_FPK")
	)
	(segment
		(start 382.3843 -120.39854)
		(end 382.3843 -120.365774)
		(width 0.0889)
		(layer "In2.Cu")
		(net "VSENSE_PVNN_PCH_STBY_FPK")
	)
	(segment
		(start 380.789688 -125.349)
		(end 381.92075 -124.217938)
		(width 0.127)
		(layer "In2.Cu")
		(net "VSENSE_PVNN_PCH_STBY_FPK")
	)
	(segment
		(start 381.889 -123.707398)
		(end 381.889 -122.951748)
		(width 0.0889)
		(layer "In2.Cu")
		(net "VSENSE_PVNN_PCH_STBY_FPK")
	)
	(segment
		(start 383.735326 -113.315496)
		(end 383.735326 -110.395258)
		(width 0.0889)
		(layer "In2.Cu")
		(net "VSENSE_PVNN_PCH_STBY_FPK")
	)
	(segment
		(start 367.719356 -134.5946)
		(end 367.538 -134.413244)
		(width 0.127)
		(layer "In2.Cu")
		(net "VSENSE_PVNN_PCH_STBY_FPK")
	)
	(segment
		(start 386.849874 -109.880654)
		(end 387.3373 -109.393228)
		(width 0.0889)
		(layer "In2.Cu")
		(net "VSENSE_PVNN_PCH_STBY_FPK")
	)
	(segment
		(start 382.3843 -116.96446)
		(end 382.3843 -116.942108)
		(width 0.0889)
		(layer "In2.Cu")
		(net "VSENSE_PVNN_PCH_STBY_FPK")
	)
	(segment
		(start 368.689382 -134.078218)
		(end 368.173 -134.5946)
		(width 0.127)
		(layer "In2.Cu")
		(net "VSENSE_PVNN_PCH_STBY_FPK")
	)
	(segment
		(start 384.24993 -109.880654)
		(end 386.849874 -109.880654)
		(width 0.0889)
		(layer "In2.Cu")
		(net "VSENSE_PVNN_PCH_STBY_FPK")
	)
	(segment
		(start 370.78666 -126.48946)
		(end 373.21236 -126.48946)
		(width 0.127)
		(layer "In2.Cu")
		(net "VSENSE_PVNN_PCH_STBY_FPK")
	)
	(segment
		(start 381.92075 -123.739148)
		(end 381.889 -123.707398)
		(width 0.0889)
		(layer "In2.Cu")
		(net "VSENSE_PVNN_PCH_STBY_FPK")
	)
	(segment
		(start 381.92075 -124.217938)
		(end 381.92075 -123.761246)
		(width 0.127)
		(layer "In2.Cu")
		(net "VSENSE_PVNN_PCH_STBY_FPK")
	)
	(segment
		(start 382.3843 -122.125994)
		(end 382.3843 -122.093228)
		(width 0.0889)
		(layer "In2.Cu")
		(net "VSENSE_PVNN_PCH_STBY_FPK")
	)
	(segment
		(start 382.8288 -115.154456)
		(end 383.097278 -114.885978)
		(width 0.0889)
		(layer "In2.Cu")
		(net "VSENSE_PVNN_PCH_STBY_FPK")
	)
	(segment
		(start 374.605042 -126.631954)
		(end 375.887996 -125.349)
		(width 0.127)
		(layer "In2.Cu")
		(net "VSENSE_PVNN_PCH_STBY_FPK")
	)
	(segment
		(start 373.354854 -126.631954)
		(end 374.605042 -126.631954)
		(width 0.127)
		(layer "In2.Cu")
		(net "VSENSE_PVNN_PCH_STBY_FPK")
	)
	(segment
		(start 367.538 -134.413244)
		(end 367.538 -128.142746)
		(width 0.127)
		(layer "In2.Cu")
		(net "VSENSE_PVNN_PCH_STBY_FPK")
	)
	(segment
		(start 382.3843 -118.691914)
		(end 382.3843 -118.648734)
		(width 0.0889)
		(layer "In2.Cu")
		(net "VSENSE_PVNN_PCH_STBY_FPK")
	)
	(segment
		(start 383.097278 -114.885978)
		(end 383.097278 -113.953544)
		(width 0.0889)
		(layer "In2.Cu")
		(net "VSENSE_PVNN_PCH_STBY_FPK")
	)
	(segment
		(start 382.8796 -121.267474)
		(end 382.8796 -121.224294)
		(width 0.0889)
		(layer "In2.Cu")
		(net "VSENSE_PVNN_PCH_STBY_FPK")
	)
	(segment
		(start 381.889 -117.82298)
		(end 381.889 -117.800628)
		(width 0.0889)
		(layer "In2.Cu")
		(net "VSENSE_PVNN_PCH_STBY_FPK")
	)
	(segment
		(start 375.887996 -125.349)
		(end 380.789688 -125.349)
		(width 0.127)
		(layer "In2.Cu")
		(net "VSENSE_PVNN_PCH_STBY_FPK")
	)
	(segment
		(start 368.173 -134.5946)
		(end 367.719356 -134.5946)
		(width 0.127)
		(layer "In2.Cu")
		(net "VSENSE_PVNN_PCH_STBY_FPK")
	)
	(segment
		(start 381.92075 -123.761246)
		(end 381.92075 -123.739148)
		(width 0.0889)
		(layer "In2.Cu")
		(net "VSENSE_PVNN_PCH_STBY_FPK")
	)
	(segment
		(start 370.644166 -126.631954)
		(end 370.78666 -126.48946)
		(width 0.127)
		(layer "In2.Cu")
		(net "VSENSE_PVNN_PCH_STBY_FPK")
	)
	(segment
		(start 383.097278 -113.953544)
		(end 383.735326 -113.315496)
		(width 0.0889)
		(layer "In2.Cu")
		(net "VSENSE_PVNN_PCH_STBY_FPK")
	)
	(segment
		(start 382.8288 -116.18341)
		(end 382.8288 -115.154456)
		(width 0.0889)
		(layer "In2.Cu")
		(net "VSENSE_PVNN_PCH_STBY_FPK")
	)
	(segment
		(start 387.3373 -109.393228)
		(end 387.3373 -109.0549)
		(width 0.0889)
		(layer "In2.Cu")
		(net "VSENSE_PVNN_PCH_STBY_FPK")
	)
	(segment
		(start 383.735326 -110.395258)
		(end 384.24993 -109.880654)
		(width 0.0889)
		(layer "In2.Cu")
		(net "VSENSE_PVNN_PCH_STBY_FPK")
	)
	(arc
		(start 382.584452 -120.734074)
		(mid 382.440648 -120.592391)
		(end 382.3843 -120.39854)
		(width 0.0889)
		(layer "In2.Cu")
		(net "VSENSE_PVNN_PCH_STBY_FPK")
	)
	(arc
		(start 381.889 -119.543576)
		(mid 381.888738 -119.528971)
		(end 381.889 -119.514366)
		(width 0.0889)
		(layer "In2.Cu")
		(net "VSENSE_PVNN_PCH_STBY_FPK")
	)
	(arc
		(start 382.089152 -119.182134)
		(mid 382.300016 -118.97513)
		(end 382.3843 -118.691914)
		(width 0.0889)
		(layer "In2.Cu")
		(net "VSENSE_PVNN_PCH_STBY_FPK")
	)
	(arc
		(start 381.889 -122.951748)
		(mid 381.94535 -122.757898)
		(end 382.089152 -122.616214)
		(width 0.0889)
		(layer "In2.Cu")
		(net "VSENSE_PVNN_PCH_STBY_FPK")
	)
	(arc
		(start 381.889 -117.800628)
		(mid 381.944157 -117.593615)
		(end 382.094994 -117.441472)
		(width 0.0889)
		(layer "In2.Cu")
		(net "VSENSE_PVNN_PCH_STBY_FPK")
	)
	(arc
		(start 382.3843 -116.942108)
		(mid 382.44065 -116.748258)
		(end 382.584452 -116.606574)
		(width 0.0889)
		(layer "In2.Cu")
		(net "VSENSE_PVNN_PCH_STBY_FPK")
	)
	(arc
		(start 382.3843 -122.093228)
		(mid 382.44065 -121.899378)
		(end 382.584452 -121.757694)
		(width 0.0889)
		(layer "In2.Cu")
		(net "VSENSE_PVNN_PCH_STBY_FPK")
	)
	(arc
		(start 382.089152 -118.158514)
		(mid 381.945348 -118.016831)
		(end 381.889 -117.82298)
		(width 0.0889)
		(layer "In2.Cu")
		(net "VSENSE_PVNN_PCH_STBY_FPK")
	)
	(arc
		(start 382.089152 -119.875554)
		(mid 381.946262 -119.735395)
		(end 381.889 -119.543576)
		(width 0.0889)
		(layer "In2.Cu")
		(net "VSENSE_PVNN_PCH_STBY_FPK")
	)
	(arc
		(start 382.3843 -120.365774)
		(mid 382.300019 -120.082557)
		(end 382.089152 -119.875554)
		(width 0.0889)
		(layer "In2.Cu")
		(net "VSENSE_PVNN_PCH_STBY_FPK")
	)
	(arc
		(start 382.089152 -122.616214)
		(mid 382.300016 -122.40921)
		(end 382.3843 -122.125994)
		(width 0.0889)
		(layer "In2.Cu")
		(net "VSENSE_PVNN_PCH_STBY_FPK")
	)
	(arc
		(start 382.584452 -121.757694)
		(mid 382.795316 -121.55069)
		(end 382.8796 -121.267474)
		(width 0.0889)
		(layer "In2.Cu")
		(net "VSENSE_PVNN_PCH_STBY_FPK")
	)
	(arc
		(start 382.584452 -116.606574)
		(mid 382.76329 -116.42772)
		(end 382.8288 -116.18341)
		(width 0.0889)
		(layer "In2.Cu")
		(net "VSENSE_PVNN_PCH_STBY_FPK")
	)
	(arc
		(start 381.889 -119.514366)
		(mid 381.946108 -119.322349)
		(end 382.089152 -119.182134)
		(width 0.0889)
		(layer "In2.Cu")
		(net "VSENSE_PVNN_PCH_STBY_FPK")
	)
	(arc
		(start 382.8796 -121.224294)
		(mid 382.795319 -120.941077)
		(end 382.584452 -120.734074)
		(width 0.0889)
		(layer "In2.Cu")
		(net "VSENSE_PVNN_PCH_STBY_FPK")
	)
	(arc
		(start 382.094994 -117.441472)
		(mid 382.300063 -117.239619)
		(end 382.3843 -116.96446)
		(width 0.0889)
		(layer "In2.Cu")
		(net "VSENSE_PVNN_PCH_STBY_FPK")
	)
	(arc
		(start 382.3843 -118.648734)
		(mid 382.300019 -118.365517)
		(end 382.089152 -118.158514)
		(width 0.0889)
		(layer "In2.Cu")
		(net "VSENSE_PVNN_PCH_STBY_FPK")
	)
	(segment
		(start 400.558 -156.718)
		(end 400.558 -157.353)
		(width 0.127)
		(layer "F.Cu")
		(net "VSENSE_PVNN_PCH_STBY_AVSP")
	)
	(segment
		(start 368.808 -137.3124)
		(end 369.5319 -137.3124)
		(width 0.127)
		(layer "F.Cu")
		(net "VSENSE_PVNN_PCH_STBY_AVSP")
	)
	(segment
		(start 368.280188 -138.061954)
		(end 368.808 -137.534142)
		(width 0.127)
		(layer "F.Cu")
		(net "VSENSE_PVNN_PCH_STBY_AVSP")
	)
	(segment
		(start 368.280188 -138.852656)
		(end 368.280188 -138.061954)
		(width 0.127)
		(layer "F.Cu")
		(net "VSENSE_PVNN_PCH_STBY_AVSP")
	)
	(segment
		(start 369.5319 -137.3124)
		(end 369.57 -137.3505)
		(width 0.127)
		(layer "F.Cu")
		(net "VSENSE_PVNN_PCH_STBY_AVSP")
	)
	(segment
		(start 368.808 -137.534142)
		(end 368.808 -137.3124)
		(width 0.127)
		(layer "F.Cu")
		(net "VSENSE_PVNN_PCH_STBY_AVSP")
	)
	(segment
		(start 369.57 -137.3505)
		(end 370.332 -137.3505)
		(width 0.127)
		(layer "F.Cu")
		(net "VSENSE_PVNN_PCH_STBY_AVSP")
	)
	(via
		(at 400.558 -157.353)
		(size 0.508)
		(drill 0.254)
		(layers "F.Cu" "B.Cu")
		(net "VSENSE_PVNN_PCH_STBY_AVSP")
	)
	(via
		(at 368.280188 -138.852656)
		(size 0.508)
		(drill 0.254)
		(layers "F.Cu" "B.Cu")
		(net "VSENSE_PVNN_PCH_STBY_AVSP")
	)
	(segment
		(start 369.534948 -150.099776)
		(end 372.565168 -153.129996)
		(width 0.127)
		(layer "In2.Cu")
		(net "VSENSE_PVNN_PCH_STBY_AVSP")
	)
	(segment
		(start 369.534948 -147.50923)
		(end 369.534948 -150.099776)
		(width 0.127)
		(layer "In2.Cu")
		(net "VSENSE_PVNN_PCH_STBY_AVSP")
	)
	(segment
		(start 368.033554 -139.654534)
		(end 371.074442 -142.695422)
		(width 0.127)
		(layer "In2.Cu")
		(net "VSENSE_PVNN_PCH_STBY_AVSP")
	)
	(segment
		(start 400.30654 -156.62529)
		(end 400.30654 -157.10154)
		(width 0.127)
		(layer "In2.Cu")
		(net "VSENSE_PVNN_PCH_STBY_AVSP")
	)
	(segment
		(start 372.565168 -153.129996)
		(end 382.481582 -153.129996)
		(width 0.127)
		(layer "In2.Cu")
		(net "VSENSE_PVNN_PCH_STBY_AVSP")
	)
	(segment
		(start 382.856232 -153.504646)
		(end 387.860032 -153.504646)
		(width 0.127)
		(layer "In2.Cu")
		(net "VSENSE_PVNN_PCH_STBY_AVSP")
	)
	(segment
		(start 397.678656 -150.880572)
		(end 398.450562 -151.652478)
		(width 0.127)
		(layer "In2.Cu")
		(net "VSENSE_PVNN_PCH_STBY_AVSP")
	)
	(segment
		(start 398.450562 -151.652478)
		(end 398.450562 -154.769312)
		(width 0.127)
		(layer "In2.Cu")
		(net "VSENSE_PVNN_PCH_STBY_AVSP")
	)
	(segment
		(start 368.033554 -139.210542)
		(end 368.033554 -139.654534)
		(width 0.127)
		(layer "In2.Cu")
		(net "VSENSE_PVNN_PCH_STBY_AVSP")
	)
	(segment
		(start 389.030464 -152.334214)
		(end 389.030464 -151.338534)
		(width 0.127)
		(layer "In2.Cu")
		(net "VSENSE_PVNN_PCH_STBY_AVSP")
	)
	(segment
		(start 389.488426 -150.880572)
		(end 397.678656 -150.880572)
		(width 0.127)
		(layer "In2.Cu")
		(net "VSENSE_PVNN_PCH_STBY_AVSP")
	)
	(segment
		(start 382.481582 -153.129996)
		(end 382.856232 -153.504646)
		(width 0.127)
		(layer "In2.Cu")
		(net "VSENSE_PVNN_PCH_STBY_AVSP")
	)
	(segment
		(start 398.450562 -154.769312)
		(end 400.30654 -156.62529)
		(width 0.127)
		(layer "In2.Cu")
		(net "VSENSE_PVNN_PCH_STBY_AVSP")
	)
	(segment
		(start 387.860032 -153.504646)
		(end 389.030464 -152.334214)
		(width 0.127)
		(layer "In2.Cu")
		(net "VSENSE_PVNN_PCH_STBY_AVSP")
	)
	(segment
		(start 368.280188 -138.963908)
		(end 368.033554 -139.210542)
		(width 0.127)
		(layer "In2.Cu")
		(net "VSENSE_PVNN_PCH_STBY_AVSP")
	)
	(segment
		(start 371.074442 -142.695422)
		(end 371.074442 -145.969736)
		(width 0.127)
		(layer "In2.Cu")
		(net "VSENSE_PVNN_PCH_STBY_AVSP")
	)
	(segment
		(start 400.30654 -157.10154)
		(end 400.558 -157.353)
		(width 0.127)
		(layer "In2.Cu")
		(net "VSENSE_PVNN_PCH_STBY_AVSP")
	)
	(segment
		(start 389.030464 -151.338534)
		(end 389.488426 -150.880572)
		(width 0.127)
		(layer "In2.Cu")
		(net "VSENSE_PVNN_PCH_STBY_AVSP")
	)
	(segment
		(start 368.280188 -138.852656)
		(end 368.280188 -138.963908)
		(width 0.127)
		(layer "In2.Cu")
		(net "VSENSE_PVNN_PCH_STBY_AVSP")
	)
	(segment
		(start 371.074442 -145.969736)
		(end 369.534948 -147.50923)
		(width 0.127)
		(layer "In2.Cu")
		(net "VSENSE_PVNN_PCH_STBY_AVSP")
	)
	(segment
		(start 398.364202 -155.597098)
		(end 399.485104 -156.718)
		(width 0.127)
		(layer "F.Cu")
		(net "VSENSE_PVNN_PCH_STBY_AVSN")
	)
	(segment
		(start 367.560606 -137.3124)
		(end 368.0206 -137.3124)
		(width 0.127)
		(layer "F.Cu")
		(net "VSENSE_PVNN_PCH_STBY_AVSN")
	)
	(segment
		(start 367.32972 -137.543286)
		(end 367.560606 -137.3124)
		(width 0.127)
		(layer "F.Cu")
		(net "VSENSE_PVNN_PCH_STBY_AVSN")
	)
	(segment
		(start 367.543588 -138.830812)
		(end 367.32972 -138.616944)
		(width 0.127)
		(layer "F.Cu")
		(net "VSENSE_PVNN_PCH_STBY_AVSN")
	)
	(segment
		(start 367.32972 -138.616944)
		(end 367.32972 -138.0998)
		(width 0.127)
		(layer "F.Cu")
		(net "VSENSE_PVNN_PCH_STBY_AVSN")
	)
	(segment
		(start 399.669 -157.353)
		(end 399.669 -156.718)
		(width 0.127)
		(layer "F.Cu")
		(net "VSENSE_PVNN_PCH_STBY_AVSN")
	)
	(segment
		(start 399.485104 -156.718)
		(end 399.669 -156.718)
		(width 0.127)
		(layer "F.Cu")
		(net "VSENSE_PVNN_PCH_STBY_AVSN")
	)
	(segment
		(start 367.32972 -138.0998)
		(end 367.32972 -137.543286)
		(width 0.127)
		(layer "F.Cu")
		(net "VSENSE_PVNN_PCH_STBY_AVSN")
	)
	(segment
		(start 367.32718 -138.0998)
		(end 367.32972 -138.0998)
		(width 0.127)
		(layer "F.Cu")
		(net "VSENSE_PVNN_PCH_STBY_AVSN")
	)
	(segment
		(start 398.2339 -155.597098)
		(end 398.364202 -155.597098)
		(width 0.127)
		(layer "F.Cu")
		(net "VSENSE_PVNN_PCH_STBY_AVSN")
	)
	(via
		(at 367.543588 -138.830812)
		(size 0.508)
		(drill 0.254)
		(layers "F.Cu" "B.Cu")
		(net "VSENSE_PVNN_PCH_STBY_AVSN")
	)
	(via
		(at 367.32718 -138.0998)
		(size 0.762)
		(drill 0.381)
		(layers "F.Cu" "B.Cu")
		(net "VSENSE_PVNN_PCH_STBY_AVSN")
	)
	(via
		(at 399.669 -157.353)
		(size 0.508)
		(drill 0.254)
		(layers "F.Cu" "B.Cu")
		(net "VSENSE_PVNN_PCH_STBY_AVSN")
	)
	(segment
		(start 367.543588 -138.830812)
		(end 367.543588 -138.956796)
		(width 0.127)
		(layer "In2.Cu")
		(net "VSENSE_PVNN_PCH_STBY_AVSN")
	)
	(segment
		(start 389.593836 -151.134572)
		(end 397.573246 -151.134572)
		(width 0.127)
		(layer "In2.Cu")
		(net "VSENSE_PVNN_PCH_STBY_AVSN")
	)
	(segment
		(start 370.820442 -142.800832)
		(end 370.820442 -145.864326)
		(width 0.127)
		(layer "In2.Cu")
		(net "VSENSE_PVNN_PCH_STBY_AVSN")
	)
	(segment
		(start 369.280948 -147.40382)
		(end 369.280948 -150.205186)
		(width 0.127)
		(layer "In2.Cu")
		(net "VSENSE_PVNN_PCH_STBY_AVSN")
	)
	(segment
		(start 387.965442 -153.758646)
		(end 389.284464 -152.439624)
		(width 0.127)
		(layer "In2.Cu")
		(net "VSENSE_PVNN_PCH_STBY_AVSN")
	)
	(segment
		(start 372.459758 -153.383996)
		(end 382.376172 -153.383996)
		(width 0.127)
		(layer "In2.Cu")
		(net "VSENSE_PVNN_PCH_STBY_AVSN")
	)
	(segment
		(start 398.196562 -151.757888)
		(end 398.196562 -154.874722)
		(width 0.127)
		(layer "In2.Cu")
		(net "VSENSE_PVNN_PCH_STBY_AVSN")
	)
	(segment
		(start 367.543588 -138.956796)
		(end 367.779554 -139.192762)
		(width 0.127)
		(layer "In2.Cu")
		(net "VSENSE_PVNN_PCH_STBY_AVSN")
	)
	(segment
		(start 367.779554 -139.192762)
		(end 367.779554 -139.759944)
		(width 0.127)
		(layer "In2.Cu")
		(net "VSENSE_PVNN_PCH_STBY_AVSN")
	)
	(segment
		(start 398.196562 -154.874722)
		(end 400.05254 -156.7307)
		(width 0.127)
		(layer "In2.Cu")
		(net "VSENSE_PVNN_PCH_STBY_AVSN")
	)
	(segment
		(start 382.750822 -153.758646)
		(end 387.965442 -153.758646)
		(width 0.127)
		(layer "In2.Cu")
		(net "VSENSE_PVNN_PCH_STBY_AVSN")
	)
	(segment
		(start 397.573246 -151.134572)
		(end 398.196562 -151.757888)
		(width 0.127)
		(layer "In2.Cu")
		(net "VSENSE_PVNN_PCH_STBY_AVSN")
	)
	(segment
		(start 389.284464 -151.443944)
		(end 389.593836 -151.134572)
		(width 0.127)
		(layer "In2.Cu")
		(net "VSENSE_PVNN_PCH_STBY_AVSN")
	)
	(segment
		(start 400.05254 -156.96946)
		(end 399.669 -157.353)
		(width 0.127)
		(layer "In2.Cu")
		(net "VSENSE_PVNN_PCH_STBY_AVSN")
	)
	(segment
		(start 369.280948 -150.205186)
		(end 372.459758 -153.383996)
		(width 0.127)
		(layer "In2.Cu")
		(net "VSENSE_PVNN_PCH_STBY_AVSN")
	)
	(segment
		(start 382.376172 -153.383996)
		(end 382.750822 -153.758646)
		(width 0.127)
		(layer "In2.Cu")
		(net "VSENSE_PVNN_PCH_STBY_AVSN")
	)
	(segment
		(start 389.284464 -152.439624)
		(end 389.284464 -151.443944)
		(width 0.127)
		(layer "In2.Cu")
		(net "VSENSE_PVNN_PCH_STBY_AVSN")
	)
	(segment
		(start 400.05254 -156.7307)
		(end 400.05254 -156.96946)
		(width 0.127)
		(layer "In2.Cu")
		(net "VSENSE_PVNN_PCH_STBY_AVSN")
	)
	(segment
		(start 370.820442 -145.864326)
		(end 369.280948 -147.40382)
		(width 0.127)
		(layer "In2.Cu")
		(net "VSENSE_PVNN_PCH_STBY_AVSN")
	)
	(segment
		(start 367.779554 -139.759944)
		(end 370.820442 -142.800832)
		(width 0.127)
		(layer "In2.Cu")
		(net "VSENSE_PVNN_PCH_STBY_AVSN")
	)
	(segment
		(start 397.608806 -148.434806)
		(end 397.608806 -148.773134)
		(width 0.10795)
		(layer "F.Cu")
		(net "PWRGD_PVNN_P1V05_PCH")
	)
	(segment
		(start 373.544846 -79.094838)
		(end 373.14505 -78.695042)
		(width 0.10795)
		(layer "F.Cu")
		(net "PWRGD_PVNN_P1V05_PCH")
	)
	(segment
		(start 396.875 -148.1582)
		(end 397.3322 -148.1582)
		(width 0.10795)
		(layer "F.Cu")
		(net "PWRGD_PVNN_P1V05_PCH")
	)
	(segment
		(start 397.3322 -148.1582)
		(end 397.608806 -148.434806)
		(width 0.10795)
		(layer "F.Cu")
		(net "PWRGD_PVNN_P1V05_PCH")
	)
	(via
		(at 373.544846 -79.094838)
		(size 0.4572)
		(drill 0.2032)
		(layers "F.Cu" "B.Cu")
		(net "PWRGD_PVNN_P1V05_PCH")
	)
	(via
		(at 397.608806 -148.773134)
		(size 0.508)
		(drill 0.254)
		(layers "F.Cu" "B.Cu")
		(net "PWRGD_PVNN_P1V05_PCH")
	)
	(via
		(at 390.03351 -150.281132)
		(size 0.508)
		(drill 0.254)
		(layers "F.Cu" "B.Cu")
		(net "PWRGD_PVNN_P1V05_PCH")
	)
	(via
		(at 352.528378 -138.248644)
		(size 0.508)
		(drill 0.254)
		(layers "F.Cu" "B.Cu")
		(net "PWRGD_PVNN_P1V05_PCH")
	)
	(via
		(at 361.328462 -82.851752)
		(size 0.6604)
		(drill 0.3302)
		(layers "F.Cu" "B.Cu")
		(net "PWRGD_PVNN_P1V05_PCH")
	)
	(segment
		(start 349.447358 -115.824)
		(end 349.9612 -115.310158)
		(width 0.10795)
		(layer "B.Cu")
		(net "PWRGD_PVNN_P1V05_PCH")
	)
	(segment
		(start 362.591604 -81.58861)
		(end 361.328462 -82.851752)
		(width 0.10795)
		(layer "B.Cu")
		(net "PWRGD_PVNN_P1V05_PCH")
	)
	(segment
		(start 345.867736 -128.926336)
		(end 343.5731 -126.6317)
		(width 0.10795)
		(layer "B.Cu")
		(net "PWRGD_PVNN_P1V05_PCH")
	)
	(segment
		(start 350.785684 -113.132616)
		(end 351.29724 -112.62106)
		(width 0.10795)
		(layer "B.Cu")
		(net "PWRGD_PVNN_P1V05_PCH")
	)
	(segment
		(start 351.29724 -112.62106)
		(end 351.29724 -112.09528)
		(width 0.10795)
		(layer "B.Cu")
		(net "PWRGD_PVNN_P1V05_PCH")
	)
	(segment
		(start 373.544846 -79.094838)
		(end 373.48287 -79.094838)
		(width 0.10795)
		(layer "B.Cu")
		(net "PWRGD_PVNN_P1V05_PCH")
	)
	(segment
		(start 358.71404 -97.67316)
		(end 358.71404 -92.3544)
		(width 0.10795)
		(layer "B.Cu")
		(net "PWRGD_PVNN_P1V05_PCH")
	)
	(segment
		(start 353.6823 -129.2987)
		(end 353.309936 -128.926336)
		(width 0.10795)
		(layer "B.Cu")
		(net "PWRGD_PVNN_P1V05_PCH")
	)
	(segment
		(start 353.8601 -108.452158)
		(end 354.387658 -107.9246)
		(width 0.10795)
		(layer "B.Cu")
		(net "PWRGD_PVNN_P1V05_PCH")
	)
	(segment
		(start 360.134154 -90.0049)
		(end 360.134154 -88.610186)
		(width 0.10795)
		(layer "B.Cu")
		(net "PWRGD_PVNN_P1V05_PCH")
	)
	(segment
		(start 363.551216 -81.58861)
		(end 362.591604 -81.58861)
		(width 0.10795)
		(layer "B.Cu")
		(net "PWRGD_PVNN_P1V05_PCH")
	)
	(segment
		(start 363.758226 -81.79562)
		(end 363.551216 -81.58861)
		(width 0.10795)
		(layer "B.Cu")
		(net "PWRGD_PVNN_P1V05_PCH")
	)
	(segment
		(start 343.5731 -126.6317)
		(end 343.5731 -121.545858)
		(width 0.10795)
		(layer "B.Cu")
		(net "PWRGD_PVNN_P1V05_PCH")
	)
	(segment
		(start 358.43464 -91.704414)
		(end 360.134154 -90.0049)
		(width 0.10795)
		(layer "B.Cu")
		(net "PWRGD_PVNN_P1V05_PCH")
	)
	(segment
		(start 343.5731 -121.545858)
		(end 347.253052 -117.865906)
		(width 0.10795)
		(layer "B.Cu")
		(net "PWRGD_PVNN_P1V05_PCH")
	)
	(segment
		(start 372.466108 -80.1116)
		(end 372.466108 -80.415892)
		(width 0.10795)
		(layer "B.Cu")
		(net "PWRGD_PVNN_P1V05_PCH")
	)
	(segment
		(start 371.224048 -82.014568)
		(end 371.0051 -81.79562)
		(width 0.10795)
		(layer "B.Cu")
		(net "PWRGD_PVNN_P1V05_PCH")
	)
	(segment
		(start 372.1862 -80.6958)
		(end 372.1862 -81.749646)
		(width 0.10795)
		(layer "B.Cu")
		(net "PWRGD_PVNN_P1V05_PCH")
	)
	(segment
		(start 349.9612 -115.310158)
		(end 349.9612 -113.651792)
		(width 0.10795)
		(layer "B.Cu")
		(net "PWRGD_PVNN_P1V05_PCH")
	)
	(segment
		(start 371.0051 -81.79562)
		(end 363.758226 -81.79562)
		(width 0.10795)
		(layer "B.Cu")
		(net "PWRGD_PVNN_P1V05_PCH")
	)
	(segment
		(start 352.528378 -138.248644)
		(end 352.679 -138.098022)
		(width 0.10795)
		(layer "B.Cu")
		(net "PWRGD_PVNN_P1V05_PCH")
	)
	(segment
		(start 357.46563 -107.9246)
		(end 358.056434 -107.333796)
		(width 0.10795)
		(layer "B.Cu")
		(net "PWRGD_PVNN_P1V05_PCH")
	)
	(segment
		(start 373.48287 -79.094838)
		(end 372.466108 -80.1116)
		(width 0.10795)
		(layer "B.Cu")
		(net "PWRGD_PVNN_P1V05_PCH")
	)
	(segment
		(start 359.022904 -87.498936)
		(end 359.022904 -84.384896)
		(width 0.10795)
		(layer "B.Cu")
		(net "PWRGD_PVNN_P1V05_PCH")
	)
	(segment
		(start 358.056434 -98.330766)
		(end 358.71404 -97.67316)
		(width 0.10795)
		(layer "B.Cu")
		(net "PWRGD_PVNN_P1V05_PCH")
	)
	(segment
		(start 372.1862 -81.749646)
		(end 371.921278 -82.014568)
		(width 0.10795)
		(layer "B.Cu")
		(net "PWRGD_PVNN_P1V05_PCH")
	)
	(segment
		(start 354.387658 -107.9246)
		(end 357.46563 -107.9246)
		(width 0.10795)
		(layer "B.Cu")
		(net "PWRGD_PVNN_P1V05_PCH")
	)
	(segment
		(start 353.8601 -110.875064)
		(end 353.8601 -108.452158)
		(width 0.10795)
		(layer "B.Cu")
		(net "PWRGD_PVNN_P1V05_PCH")
	)
	(segment
		(start 350.480376 -113.132616)
		(end 350.785684 -113.132616)
		(width 0.10795)
		(layer "B.Cu")
		(net "PWRGD_PVNN_P1V05_PCH")
	)
	(segment
		(start 372.466108 -80.415892)
		(end 372.1862 -80.6958)
		(width 0.10795)
		(layer "B.Cu")
		(net "PWRGD_PVNN_P1V05_PCH")
	)
	(segment
		(start 358.43464 -92.075)
		(end 358.43464 -91.704414)
		(width 0.10795)
		(layer "B.Cu")
		(net "PWRGD_PVNN_P1V05_PCH")
	)
	(segment
		(start 352.679 -134.681468)
		(end 353.6823 -133.678168)
		(width 0.10795)
		(layer "B.Cu")
		(net "PWRGD_PVNN_P1V05_PCH")
	)
	(segment
		(start 349.9612 -113.651792)
		(end 350.480376 -113.132616)
		(width 0.10795)
		(layer "B.Cu")
		(net "PWRGD_PVNN_P1V05_PCH")
	)
	(segment
		(start 347.253052 -116.169948)
		(end 347.599 -115.824)
		(width 0.10795)
		(layer "B.Cu")
		(net "PWRGD_PVNN_P1V05_PCH")
	)
	(segment
		(start 371.921278 -82.014568)
		(end 371.224048 -82.014568)
		(width 0.10795)
		(layer "B.Cu")
		(net "PWRGD_PVNN_P1V05_PCH")
	)
	(segment
		(start 353.6823 -133.678168)
		(end 353.6823 -129.2987)
		(width 0.10795)
		(layer "B.Cu")
		(net "PWRGD_PVNN_P1V05_PCH")
	)
	(segment
		(start 347.599 -115.824)
		(end 349.447358 -115.824)
		(width 0.10795)
		(layer "B.Cu")
		(net "PWRGD_PVNN_P1V05_PCH")
	)
	(segment
		(start 352.679 -138.098022)
		(end 352.679 -134.681468)
		(width 0.10795)
		(layer "B.Cu")
		(net "PWRGD_PVNN_P1V05_PCH")
	)
	(segment
		(start 359.376472 -84.031328)
		(end 360.148886 -84.031328)
		(width 0.10795)
		(layer "B.Cu")
		(net "PWRGD_PVNN_P1V05_PCH")
	)
	(segment
		(start 351.29724 -112.09528)
		(end 351.58934 -111.80318)
		(width 0.10795)
		(layer "B.Cu")
		(net "PWRGD_PVNN_P1V05_PCH")
	)
	(segment
		(start 358.056434 -107.333796)
		(end 358.056434 -98.330766)
		(width 0.10795)
		(layer "B.Cu")
		(net "PWRGD_PVNN_P1V05_PCH")
	)
	(segment
		(start 358.71404 -92.3544)
		(end 358.43464 -92.075)
		(width 0.10795)
		(layer "B.Cu")
		(net "PWRGD_PVNN_P1V05_PCH")
	)
	(segment
		(start 347.253052 -117.865906)
		(end 347.253052 -116.169948)
		(width 0.10795)
		(layer "B.Cu")
		(net "PWRGD_PVNN_P1V05_PCH")
	)
	(segment
		(start 360.148886 -84.031328)
		(end 361.328462 -82.851752)
		(width 0.10795)
		(layer "B.Cu")
		(net "PWRGD_PVNN_P1V05_PCH")
	)
	(segment
		(start 351.58934 -111.80318)
		(end 352.931984 -111.80318)
		(width 0.10795)
		(layer "B.Cu")
		(net "PWRGD_PVNN_P1V05_PCH")
	)
	(segment
		(start 359.022904 -84.384896)
		(end 359.376472 -84.031328)
		(width 0.10795)
		(layer "B.Cu")
		(net "PWRGD_PVNN_P1V05_PCH")
	)
	(segment
		(start 352.931984 -111.80318)
		(end 353.8601 -110.875064)
		(width 0.10795)
		(layer "B.Cu")
		(net "PWRGD_PVNN_P1V05_PCH")
	)
	(segment
		(start 360.134154 -88.610186)
		(end 359.022904 -87.498936)
		(width 0.10795)
		(layer "B.Cu")
		(net "PWRGD_PVNN_P1V05_PCH")
	)
	(segment
		(start 353.309936 -128.926336)
		(end 345.867736 -128.926336)
		(width 0.10795)
		(layer "B.Cu")
		(net "PWRGD_PVNN_P1V05_PCH")
	)
	(segment
		(start 393.56665 -148.52015)
		(end 397.355822 -148.52015)
		(width 0.089408)
		(layer "In2.Cu")
		(net "PWRGD_PVNN_P1V05_PCH")
	)
	(segment
		(start 390.03351 -150.281132)
		(end 390.03351 -149.91588)
		(width 0.089408)
		(layer "In2.Cu")
		(net "PWRGD_PVNN_P1V05_PCH")
	)
	(segment
		(start 390.03351 -149.91588)
		(end 390.45515 -149.49424)
		(width 0.089408)
		(layer "In2.Cu")
		(net "PWRGD_PVNN_P1V05_PCH")
	)
	(segment
		(start 392.59256 -149.49424)
		(end 393.56665 -148.52015)
		(width 0.089408)
		(layer "In2.Cu")
		(net "PWRGD_PVNN_P1V05_PCH")
	)
	(segment
		(start 397.355822 -148.52015)
		(end 397.608806 -148.773134)
		(width 0.089408)
		(layer "In2.Cu")
		(net "PWRGD_PVNN_P1V05_PCH")
	)
	(segment
		(start 390.45515 -149.49424)
		(end 392.59256 -149.49424)
		(width 0.089408)
		(layer "In2.Cu")
		(net "PWRGD_PVNN_P1V05_PCH")
	)
	(segment
		(start 372.30177 -146.64055)
		(end 371.17782 -145.5166)
		(width 0.089408)
		(layer "In11.Cu")
		(net "PWRGD_PVNN_P1V05_PCH")
	)
	(segment
		(start 368.85626 -146.89074)
		(end 367.10874 -146.89074)
		(width 0.089408)
		(layer "In11.Cu")
		(net "PWRGD_PVNN_P1V05_PCH")
	)
	(segment
		(start 371.17782 -145.5166)
		(end 370.2304 -145.5166)
		(width 0.089408)
		(layer "In11.Cu")
		(net "PWRGD_PVNN_P1V05_PCH")
	)
	(segment
		(start 361.442 -140.4112)
		(end 360.4006 -140.4112)
		(width 0.089408)
		(layer "In11.Cu")
		(net "PWRGD_PVNN_P1V05_PCH")
	)
	(segment
		(start 353.453954 -138.823446)
		(end 353.10318 -138.823446)
		(width 0.089408)
		(layer "In11.Cu")
		(net "PWRGD_PVNN_P1V05_PCH")
	)
	(segment
		(start 387.080252 -149.094444)
		(end 385.394708 -147.4089)
		(width 0.089408)
		(layer "In11.Cu")
		(net "PWRGD_PVNN_P1V05_PCH")
	)
	(segment
		(start 357.468678 -137.479278)
		(end 354.798122 -137.479278)
		(width 0.089408)
		(layer "In11.Cu")
		(net "PWRGD_PVNN_P1V05_PCH")
	)
	(segment
		(start 363.2454 -143.0274)
		(end 363.2454 -142.2146)
		(width 0.089408)
		(layer "In11.Cu")
		(net "PWRGD_PVNN_P1V05_PCH")
	)
	(segment
		(start 360.4006 -140.4112)
		(end 357.468678 -137.479278)
		(width 0.089408)
		(layer "In11.Cu")
		(net "PWRGD_PVNN_P1V05_PCH")
	)
	(segment
		(start 388.846822 -149.094444)
		(end 387.080252 -149.094444)
		(width 0.089408)
		(layer "In11.Cu")
		(net "PWRGD_PVNN_P1V05_PCH")
	)
	(segment
		(start 367.10874 -146.89074)
		(end 363.2454 -143.0274)
		(width 0.089408)
		(layer "In11.Cu")
		(net "PWRGD_PVNN_P1V05_PCH")
	)
	(segment
		(start 390.03351 -150.281132)
		(end 388.846822 -149.094444)
		(width 0.089408)
		(layer "In11.Cu")
		(net "PWRGD_PVNN_P1V05_PCH")
	)
	(segment
		(start 363.2454 -142.2146)
		(end 361.442 -140.4112)
		(width 0.089408)
		(layer "In11.Cu")
		(net "PWRGD_PVNN_P1V05_PCH")
	)
	(segment
		(start 385.394708 -147.4089)
		(end 379.15342 -147.4089)
		(width 0.089408)
		(layer "In11.Cu")
		(net "PWRGD_PVNN_P1V05_PCH")
	)
	(segment
		(start 370.2304 -145.5166)
		(end 368.85626 -146.89074)
		(width 0.089408)
		(layer "In11.Cu")
		(net "PWRGD_PVNN_P1V05_PCH")
	)
	(segment
		(start 353.10318 -138.823446)
		(end 352.528378 -138.248644)
		(width 0.089408)
		(layer "In11.Cu")
		(net "PWRGD_PVNN_P1V05_PCH")
	)
	(segment
		(start 354.798122 -137.479278)
		(end 353.453954 -138.823446)
		(width 0.089408)
		(layer "In11.Cu")
		(net "PWRGD_PVNN_P1V05_PCH")
	)
	(segment
		(start 378.38507 -146.64055)
		(end 372.30177 -146.64055)
		(width 0.089408)
		(layer "In11.Cu")
		(net "PWRGD_PVNN_P1V05_PCH")
	)
	(segment
		(start 379.15342 -147.4089)
		(end 378.38507 -146.64055)
		(width 0.089408)
		(layer "In11.Cu")
		(net "PWRGD_PVNN_P1V05_PCH")
	)
	(segment
		(start 393.2936 -0.508)
		(end 393.6492 -0.8636)
		(width 0.10795)
		(layer "F.Cu")
		(net "JTAG_PCH_PLD_TMS")
	)
	(segment
		(start 393.2936 -0.2286)
		(end 393.2936 -0.508)
		(width 0.10795)
		(layer "F.Cu")
		(net "JTAG_PCH_PLD_TMS")
	)
	(segment
		(start 386.74675 -96.9772)
		(end 387.24205 -96.747076)
		(width 0.10795)
		(layer "F.Cu")
		(net "JTAG_PCH_PLD_TMS")
	)
	(via
		(at 387.24205 -96.747076)
		(size 0.508)
		(drill 0.254)
		(layers "F.Cu" "B.Cu")
		(net "JTAG_PCH_PLD_TMS")
	)
	(via
		(at 393.6492 -0.8636)
		(size 0.508)
		(drill 0.254)
		(layers "F.Cu" "B.Cu")
		(net "JTAG_PCH_PLD_TMS")
	)
	(via
		(at 456.6158 -5.338572)
		(size 0.508)
		(drill 0.254)
		(layers "F.Cu" "B.Cu")
		(net "JTAG_PCH_PLD_TMS")
	)
	(segment
		(start 412.627064 1.482598)
		(end 412.627318 1.482852)
		(width 0.089408)
		(layer "In4.Cu")
		(net "JTAG_PCH_PLD_TMS")
	)
	(segment
		(start 414.370774 1.482852)
		(end 415.673032 2.78511)
		(width 0.089408)
		(layer "In4.Cu")
		(net "JTAG_PCH_PLD_TMS")
	)
	(segment
		(start 400.549872 1.278128)
		(end 401.887944 1.278128)
		(width 0.089408)
		(layer "In4.Cu")
		(net "JTAG_PCH_PLD_TMS")
	)
	(segment
		(start 402.105876 1.060196)
		(end 404.035006 1.060196)
		(width 0.089408)
		(layer "In4.Cu")
		(net "JTAG_PCH_PLD_TMS")
	)
	(segment
		(start 396.019528 1.506728)
		(end 400.321272 1.506728)
		(width 0.089408)
		(layer "In4.Cu")
		(net "JTAG_PCH_PLD_TMS")
	)
	(segment
		(start 430.178972 1.27)
		(end 431.889408 -0.440436)
		(width 0.089408)
		(layer "In4.Cu")
		(net "JTAG_PCH_PLD_TMS")
	)
	(segment
		(start 404.235412 1.059942)
		(end 405.231854 2.056384)
		(width 0.089408)
		(layer "In4.Cu")
		(net "JTAG_PCH_PLD_TMS")
	)
	(segment
		(start 400.321272 1.506728)
		(end 400.549872 1.278128)
		(width 0.089408)
		(layer "In4.Cu")
		(net "JTAG_PCH_PLD_TMS")
	)
	(segment
		(start 412.426912 1.482598)
		(end 412.627064 1.482598)
		(width 0.089408)
		(layer "In4.Cu")
		(net "JTAG_PCH_PLD_TMS")
	)
	(segment
		(start 411.853126 2.056384)
		(end 412.426912 1.482598)
		(width 0.089408)
		(layer "In4.Cu")
		(net "JTAG_PCH_PLD_TMS")
	)
	(segment
		(start 420.993062 2.78511)
		(end 422.508172 1.27)
		(width 0.089408)
		(layer "In4.Cu")
		(net "JTAG_PCH_PLD_TMS")
	)
	(segment
		(start 431.889408 -0.440436)
		(end 450.694552 -0.440436)
		(width 0.089408)
		(layer "In4.Cu")
		(net "JTAG_PCH_PLD_TMS")
	)
	(segment
		(start 415.673032 2.78511)
		(end 420.993062 2.78511)
		(width 0.089408)
		(layer "In4.Cu")
		(net "JTAG_PCH_PLD_TMS")
	)
	(segment
		(start 405.231854 2.056384)
		(end 411.853126 2.056384)
		(width 0.089408)
		(layer "In4.Cu")
		(net "JTAG_PCH_PLD_TMS")
	)
	(segment
		(start 404.03526 1.059942)
		(end 404.235412 1.059942)
		(width 0.089408)
		(layer "In4.Cu")
		(net "JTAG_PCH_PLD_TMS")
	)
	(segment
		(start 455.592688 -5.338572)
		(end 456.6158 -5.338572)
		(width 0.089408)
		(layer "In4.Cu")
		(net "JTAG_PCH_PLD_TMS")
	)
	(segment
		(start 412.627318 1.482852)
		(end 414.370774 1.482852)
		(width 0.089408)
		(layer "In4.Cu")
		(net "JTAG_PCH_PLD_TMS")
	)
	(segment
		(start 401.887944 1.278128)
		(end 402.105876 1.060196)
		(width 0.089408)
		(layer "In4.Cu")
		(net "JTAG_PCH_PLD_TMS")
	)
	(segment
		(start 404.035006 1.060196)
		(end 404.03526 1.059942)
		(width 0.089408)
		(layer "In4.Cu")
		(net "JTAG_PCH_PLD_TMS")
	)
	(segment
		(start 393.6492 -0.8636)
		(end 396.019528 1.506728)
		(width 0.089408)
		(layer "In4.Cu")
		(net "JTAG_PCH_PLD_TMS")
	)
	(segment
		(start 422.508172 1.27)
		(end 430.178972 1.27)
		(width 0.089408)
		(layer "In4.Cu")
		(net "JTAG_PCH_PLD_TMS")
	)
	(segment
		(start 450.694552 -0.440436)
		(end 455.592688 -5.338572)
		(width 0.089408)
		(layer "In4.Cu")
		(net "JTAG_PCH_PLD_TMS")
	)
	(segment
		(start 371.45976 -28.87091)
		(end 373.210582 -27.120088)
		(width 0.089408)
		(layer "In11.Cu")
		(net "JTAG_PCH_PLD_TMS")
	)
	(segment
		(start 384.302762 -55.939182)
		(end 384.302762 -55.720742)
		(width 0.089408)
		(layer "In11.Cu")
		(net "JTAG_PCH_PLD_TMS")
	)
	(segment
		(start 455.780394 -4.727194)
		(end 455.780648 -4.727448)
		(width 0.089408)
		(layer "In11.Cu")
		(net "JTAG_PCH_PLD_TMS")
	)
	(segment
		(start 381.690372 -13.361924)
		(end 400.076924 -13.361924)
		(width 0.089408)
		(layer "In11.Cu")
		(net "JTAG_PCH_PLD_TMS")
	)
	(segment
		(start 371.45976 -33.78708)
		(end 371.45976 -28.87091)
		(width 0.089408)
		(layer "In11.Cu")
		(net "JTAG_PCH_PLD_TMS")
	)
	(segment
		(start 371.718078 -34.045398)
		(end 371.45976 -33.78708)
		(width 0.089408)
		(layer "In11.Cu")
		(net "JTAG_PCH_PLD_TMS")
	)
	(segment
		(start 387.074918 -85.540342)
		(end 387.075172 -85.540088)
		(width 0.089408)
		(layer "In11.Cu")
		(net "JTAG_PCH_PLD_TMS")
	)
	(segment
		(start 387.074918 -89.496646)
		(end 387.074918 -85.540342)
		(width 0.089408)
		(layer "In11.Cu")
		(net "JTAG_PCH_PLD_TMS")
	)
	(segment
		(start 387.075172 -85.297772)
		(end 387.074918 -85.297518)
		(width 0.089408)
		(layer "In11.Cu")
		(net "JTAG_PCH_PLD_TMS")
	)
	(segment
		(start 386.39623 -72.187562)
		(end 385.45262 -71.243952)
		(width 0.089408)
		(layer "In11.Cu")
		(net "JTAG_PCH_PLD_TMS")
	)
	(segment
		(start 386.88518 -91.534488)
		(end 386.88518 -89.686384)
		(width 0.089408)
		(layer "In11.Cu")
		(net "JTAG_PCH_PLD_TMS")
	)
	(segment
		(start 373.478298 -46.771306)
		(end 373.478298 -46.404022)
		(width 0.089408)
		(layer "In11.Cu")
		(net "JTAG_PCH_PLD_TMS")
	)
	(segment
		(start 401.781264 -11.657584)
		(end 418.400738 -11.657584)
		(width 0.089408)
		(layer "In11.Cu")
		(net "JTAG_PCH_PLD_TMS")
	)
	(segment
		(start 373.210582 -21.841714)
		(end 381.690372 -13.361924)
		(width 0.089408)
		(layer "In11.Cu")
		(net "JTAG_PCH_PLD_TMS")
	)
	(segment
		(start 371.718078 -44.643802)
		(end 371.718078 -34.045398)
		(width 0.089408)
		(layer "In11.Cu")
		(net "JTAG_PCH_PLD_TMS")
	)
	(segment
		(start 386.424424 -83.374738)
		(end 386.424424 -82.409792)
		(width 0.089408)
		(layer "In11.Cu")
		(net "JTAG_PCH_PLD_TMS")
	)
	(segment
		(start 385.45262 -66.082926)
		(end 384.203448 -64.833754)
		(width 0.089408)
		(layer "In11.Cu")
		(net "JTAG_PCH_PLD_TMS")
	)
	(segment
		(start 383.83337 -61.30417)
		(end 383.83337 -60.58027)
		(width 0.089408)
		(layer "In11.Cu")
		(net "JTAG_PCH_PLD_TMS")
	)
	(segment
		(start 454.648824 -4.727194)
		(end 455.780394 -4.727194)
		(width 0.089408)
		(layer "In11.Cu")
		(net "JTAG_PCH_PLD_TMS")
	)
	(segment
		(start 455.780648 -4.727448)
		(end 456.348592 -4.727448)
		(width 0.089408)
		(layer "In11.Cu")
		(net "JTAG_PCH_PLD_TMS")
	)
	(segment
		(start 377.735592 -51.0286)
		(end 373.478298 -46.771306)
		(width 0.089408)
		(layer "In11.Cu")
		(net "JTAG_PCH_PLD_TMS")
	)
	(segment
		(start 387.14553 -96.05391)
		(end 387.14553 -91.794838)
		(width 0.089408)
		(layer "In11.Cu")
		(net "JTAG_PCH_PLD_TMS")
	)
	(segment
		(start 384.203448 -61.674248)
		(end 383.83337 -61.30417)
		(width 0.089408)
		(layer "In11.Cu")
		(net "JTAG_PCH_PLD_TMS")
	)
	(segment
		(start 379.61062 -51.0286)
		(end 377.735592 -51.0286)
		(width 0.089408)
		(layer "In11.Cu")
		(net "JTAG_PCH_PLD_TMS")
	)
	(segment
		(start 384.203448 -64.833754)
		(end 384.203448 -61.674248)
		(width 0.089408)
		(layer "In11.Cu")
		(net "JTAG_PCH_PLD_TMS")
	)
	(segment
		(start 387.14553 -91.794838)
		(end 386.88518 -91.534488)
		(width 0.089408)
		(layer "In11.Cu")
		(net "JTAG_PCH_PLD_TMS")
	)
	(segment
		(start 386.424424 -82.409792)
		(end 386.39623 -82.381598)
		(width 0.089408)
		(layer "In11.Cu")
		(net "JTAG_PCH_PLD_TMS")
	)
	(segment
		(start 373.478298 -46.404022)
		(end 371.718078 -44.643802)
		(width 0.089408)
		(layer "In11.Cu")
		(net "JTAG_PCH_PLD_TMS")
	)
	(segment
		(start 456.348592 -4.727448)
		(end 456.6158 -4.994656)
		(width 0.089408)
		(layer "In11.Cu")
		(net "JTAG_PCH_PLD_TMS")
	)
	(segment
		(start 384.506724 -59.906916)
		(end 384.506724 -56.143144)
		(width 0.089408)
		(layer "In11.Cu")
		(net "JTAG_PCH_PLD_TMS")
	)
	(segment
		(start 383.83337 -60.58027)
		(end 384.506724 -59.906916)
		(width 0.089408)
		(layer "In11.Cu")
		(net "JTAG_PCH_PLD_TMS")
	)
	(segment
		(start 386.88518 -89.686384)
		(end 387.074918 -89.496646)
		(width 0.089408)
		(layer "In11.Cu")
		(net "JTAG_PCH_PLD_TMS")
	)
	(segment
		(start 454.64857 -4.727448)
		(end 454.648824 -4.727194)
		(width 0.089408)
		(layer "In11.Cu")
		(net "JTAG_PCH_PLD_TMS")
	)
	(segment
		(start 386.95884 -96.463866)
		(end 386.95884 -96.2406)
		(width 0.089408)
		(layer "In11.Cu")
		(net "JTAG_PCH_PLD_TMS")
	)
	(segment
		(start 384.506724 -56.143144)
		(end 384.302762 -55.939182)
		(width 0.089408)
		(layer "In11.Cu")
		(net "JTAG_PCH_PLD_TMS")
	)
	(segment
		(start 385.45262 -71.243952)
		(end 385.45262 -66.082926)
		(width 0.089408)
		(layer "In11.Cu")
		(net "JTAG_PCH_PLD_TMS")
	)
	(segment
		(start 420.632382 -13.889228)
		(end 425.423838 -13.889228)
		(width 0.089408)
		(layer "In11.Cu")
		(net "JTAG_PCH_PLD_TMS")
	)
	(segment
		(start 428.4218 -10.891266)
		(end 446.652142 -10.891266)
		(width 0.089408)
		(layer "In11.Cu")
		(net "JTAG_PCH_PLD_TMS")
	)
	(segment
		(start 425.423838 -13.889228)
		(end 428.4218 -10.891266)
		(width 0.089408)
		(layer "In11.Cu")
		(net "JTAG_PCH_PLD_TMS")
	)
	(segment
		(start 452.81596 -4.727448)
		(end 454.64857 -4.727448)
		(width 0.089408)
		(layer "In11.Cu")
		(net "JTAG_PCH_PLD_TMS")
	)
	(segment
		(start 386.39623 -82.381598)
		(end 386.39623 -72.187562)
		(width 0.089408)
		(layer "In11.Cu")
		(net "JTAG_PCH_PLD_TMS")
	)
	(segment
		(start 387.074918 -85.297518)
		(end 387.074918 -84.025232)
		(width 0.089408)
		(layer "In11.Cu")
		(net "JTAG_PCH_PLD_TMS")
	)
	(segment
		(start 373.210582 -27.120088)
		(end 373.210582 -21.841714)
		(width 0.089408)
		(layer "In11.Cu")
		(net "JTAG_PCH_PLD_TMS")
	)
	(segment
		(start 418.400738 -11.657584)
		(end 420.632382 -13.889228)
		(width 0.089408)
		(layer "In11.Cu")
		(net "JTAG_PCH_PLD_TMS")
	)
	(segment
		(start 456.6158 -4.994656)
		(end 456.6158 -5.338572)
		(width 0.089408)
		(layer "In11.Cu")
		(net "JTAG_PCH_PLD_TMS")
	)
	(segment
		(start 387.075172 -85.540088)
		(end 387.075172 -85.297772)
		(width 0.089408)
		(layer "In11.Cu")
		(net "JTAG_PCH_PLD_TMS")
	)
	(segment
		(start 446.652142 -10.891266)
		(end 452.81596 -4.727448)
		(width 0.089408)
		(layer "In11.Cu")
		(net "JTAG_PCH_PLD_TMS")
	)
	(segment
		(start 387.24205 -96.747076)
		(end 386.95884 -96.463866)
		(width 0.089408)
		(layer "In11.Cu")
		(net "JTAG_PCH_PLD_TMS")
	)
	(segment
		(start 386.95884 -96.2406)
		(end 387.14553 -96.05391)
		(width 0.089408)
		(layer "In11.Cu")
		(net "JTAG_PCH_PLD_TMS")
	)
	(segment
		(start 387.074918 -84.025232)
		(end 386.424424 -83.374738)
		(width 0.089408)
		(layer "In11.Cu")
		(net "JTAG_PCH_PLD_TMS")
	)
	(segment
		(start 384.302762 -55.720742)
		(end 379.61062 -51.0286)
		(width 0.089408)
		(layer "In11.Cu")
		(net "JTAG_PCH_PLD_TMS")
	)
	(segment
		(start 400.076924 -13.361924)
		(end 401.781264 -11.657584)
		(width 0.089408)
		(layer "In11.Cu")
		(net "JTAG_PCH_PLD_TMS")
	)
	(segment
		(start 382.6002 1.6764)
		(end 382.6002 0.6858)
		(width 0.10795)
		(layer "F.Cu")
		(net "JTAG_PCH_PLD_TDO")
	)
	(segment
		(start 382.6002 0.6858)
		(end 383.54 -0.254)
		(width 0.10795)
		(layer "F.Cu")
		(net "JTAG_PCH_PLD_TDO")
	)
	(segment
		(start 383.54 -0.254)
		(end 384.4798 -0.254)
		(width 0.10795)
		(layer "F.Cu")
		(net "JTAG_PCH_PLD_TDO")
	)
	(segment
		(start 389.71855 -102.12832)
		(end 389.7376 -102.11943)
		(width 0.10795)
		(layer "F.Cu")
		(net "JTAG_PCH_PLD_TDO")
	)
	(segment
		(start 389.7376 -102.11943)
		(end 390.21385 -101.898196)
		(width 0.10795)
		(layer "F.Cu")
		(net "JTAG_PCH_PLD_TDO")
	)
	(via
		(at 382.6002 1.6764)
		(size 0.508)
		(drill 0.254)
		(layers "F.Cu" "B.Cu")
		(net "JTAG_PCH_PLD_TDO")
	)
	(via
		(at 390.21385 -101.898196)
		(size 0.508)
		(drill 0.254)
		(layers "F.Cu" "B.Cu")
		(net "JTAG_PCH_PLD_TDO")
	)
	(via
		(at 468.230204 -2.420112)
		(size 0.508)
		(drill 0.254)
		(layers "F.Cu" "B.Cu")
		(net "JTAG_PCH_PLD_TDO")
	)
	(segment
		(start 425.680378 1.406144)
		(end 422.694862 1.406144)
		(width 0.089408)
		(layer "In2.Cu")
		(net "JTAG_PCH_PLD_TDO")
	)
	(segment
		(start 465.473034 -1.401572)
		(end 465.47278 -1.401318)
		(width 0.089408)
		(layer "In2.Cu")
		(net "JTAG_PCH_PLD_TDO")
	)
	(segment
		(start 410.557726 4.753864)
		(end 409.42387 3.620008)
		(width 0.089408)
		(layer "In2.Cu")
		(net "JTAG_PCH_PLD_TDO")
	)
	(segment
		(start 422.694862 1.406144)
		(end 419.347142 4.753864)
		(width 0.089408)
		(layer "In2.Cu")
		(net "JTAG_PCH_PLD_TDO")
	)
	(segment
		(start 419.347142 4.753864)
		(end 419.185598 4.753864)
		(width 0.089408)
		(layer "In2.Cu")
		(net "JTAG_PCH_PLD_TDO")
	)
	(segment
		(start 418.984938 4.753864)
		(end 410.557726 4.753864)
		(width 0.089408)
		(layer "In2.Cu")
		(net "JTAG_PCH_PLD_TDO")
	)
	(segment
		(start 403.661626 5.010912)
		(end 399.003774 5.010912)
		(width 0.089408)
		(layer "In2.Cu")
		(net "JTAG_PCH_PLD_TDO")
	)
	(segment
		(start 465.47278 -1.201166)
		(end 465.473034 -1.200912)
		(width 0.089408)
		(layer "In2.Cu")
		(net "JTAG_PCH_PLD_TDO")
	)
	(segment
		(start 465.47278 -1.401318)
		(end 465.47278 -1.201166)
		(width 0.089408)
		(layer "In2.Cu")
		(net "JTAG_PCH_PLD_TDO")
	)
	(segment
		(start 405.05253 3.620008)
		(end 403.661626 5.010912)
		(width 0.089408)
		(layer "In2.Cu")
		(net "JTAG_PCH_PLD_TDO")
	)
	(segment
		(start 468.230204 -2.420112)
		(end 467.6775 -1.892808)
		(width 0.089408)
		(layer "In2.Cu")
		(net "JTAG_PCH_PLD_TDO")
	)
	(segment
		(start 397.859758 1.250696)
		(end 383.025904 1.250696)
		(width 0.089408)
		(layer "In2.Cu")
		(net "JTAG_PCH_PLD_TDO")
	)
	(segment
		(start 398.512792 1.90373)
		(end 397.859758 1.250696)
		(width 0.089408)
		(layer "In2.Cu")
		(net "JTAG_PCH_PLD_TDO")
	)
	(segment
		(start 419.185598 4.753864)
		(end 419.185344 4.754118)
		(width 0.089408)
		(layer "In2.Cu")
		(net "JTAG_PCH_PLD_TDO")
	)
	(segment
		(start 418.985192 4.754118)
		(end 418.984938 4.753864)
		(width 0.089408)
		(layer "In2.Cu")
		(net "JTAG_PCH_PLD_TDO")
	)
	(segment
		(start 465.473034 -0.068834)
		(end 465.074 0.3302)
		(width 0.089408)
		(layer "In2.Cu")
		(net "JTAG_PCH_PLD_TDO")
	)
	(segment
		(start 427.056042 2.781808)
		(end 425.680378 1.406144)
		(width 0.089408)
		(layer "In2.Cu")
		(net "JTAG_PCH_PLD_TDO")
	)
	(segment
		(start 467.6775 -1.892808)
		(end 465.956904 -1.892808)
		(width 0.089408)
		(layer "In2.Cu")
		(net "JTAG_PCH_PLD_TDO")
	)
	(segment
		(start 399.003774 5.010912)
		(end 398.512792 4.51993)
		(width 0.089408)
		(layer "In2.Cu")
		(net "JTAG_PCH_PLD_TDO")
	)
	(segment
		(start 465.074 1.1176)
		(end 463.409792 2.781808)
		(width 0.089408)
		(layer "In2.Cu")
		(net "JTAG_PCH_PLD_TDO")
	)
	(segment
		(start 465.074 0.3302)
		(end 465.074 1.1176)
		(width 0.089408)
		(layer "In2.Cu")
		(net "JTAG_PCH_PLD_TDO")
	)
	(segment
		(start 465.473034 -1.408938)
		(end 465.473034 -1.401572)
		(width 0.089408)
		(layer "In2.Cu")
		(net "JTAG_PCH_PLD_TDO")
	)
	(segment
		(start 383.025904 1.250696)
		(end 382.6002 1.6764)
		(width 0.089408)
		(layer "In2.Cu")
		(net "JTAG_PCH_PLD_TDO")
	)
	(segment
		(start 463.409792 2.781808)
		(end 427.056042 2.781808)
		(width 0.089408)
		(layer "In2.Cu")
		(net "JTAG_PCH_PLD_TDO")
	)
	(segment
		(start 398.512792 4.51993)
		(end 398.512792 1.90373)
		(width 0.089408)
		(layer "In2.Cu")
		(net "JTAG_PCH_PLD_TDO")
	)
	(segment
		(start 419.185344 4.754118)
		(end 418.985192 4.754118)
		(width 0.089408)
		(layer "In2.Cu")
		(net "JTAG_PCH_PLD_TDO")
	)
	(segment
		(start 465.956904 -1.892808)
		(end 465.473034 -1.408938)
		(width 0.089408)
		(layer "In2.Cu")
		(net "JTAG_PCH_PLD_TDO")
	)
	(segment
		(start 465.473034 -1.200912)
		(end 465.473034 -0.068834)
		(width 0.089408)
		(layer "In2.Cu")
		(net "JTAG_PCH_PLD_TDO")
	)
	(segment
		(start 409.42387 3.620008)
		(end 405.05253 3.620008)
		(width 0.089408)
		(layer "In2.Cu")
		(net "JTAG_PCH_PLD_TDO")
	)
	(segment
		(start 437.172862 -13.720064)
		(end 436.841138 -13.720064)
		(width 0.089408)
		(layer "In11.Cu")
		(net "JTAG_PCH_PLD_TDO")
	)
	(segment
		(start 464.087464 -5.912104)
		(end 462.072736 -5.912104)
		(width 0.089408)
		(layer "In11.Cu")
		(net "JTAG_PCH_PLD_TDO")
	)
	(segment
		(start 372.185184 -33.48609)
		(end 372.443502 -33.744408)
		(width 0.089408)
		(layer "In11.Cu")
		(net "JTAG_PCH_PLD_TDO")
	)
	(segment
		(start 420.491412 -14.774672)
		(end 418.099748 -12.383008)
		(width 0.089408)
		(layer "In11.Cu")
		(net "JTAG_PCH_PLD_TDO")
	)
	(segment
		(start 389.62203 -100.01377)
		(end 389.62203 -100.34651)
		(width 0.089408)
		(layer "In11.Cu")
		(net "JTAG_PCH_PLD_TDO")
	)
	(segment
		(start 380.386336 -49.492408)
		(end 383.5654 -52.671472)
		(width 0.089408)
		(layer "In11.Cu")
		(net "JTAG_PCH_PLD_TDO")
	)
	(segment
		(start 436.841138 -13.720064)
		(end 436.82412 -13.703046)
		(width 0.089408)
		(layer "In11.Cu")
		(net "JTAG_PCH_PLD_TDO")
	)
	(segment
		(start 390.61263 -98.28403)
		(end 390.61263 -98.64217)
		(width 0.089408)
		(layer "In11.Cu")
		(net "JTAG_PCH_PLD_TDO")
	)
	(segment
		(start 464.281774 -5.0673)
		(end 464.281774 -5.717794)
		(width 0.089408)
		(layer "In11.Cu")
		(net "JTAG_PCH_PLD_TDO")
	)
	(segment
		(start 388.261098 -76.348844)
		(end 388.261098 -78.66126)
		(width 0.089408)
		(layer "In11.Cu")
		(net "JTAG_PCH_PLD_TDO")
	)
	(segment
		(start 389.636 -96.5708)
		(end 389.636 -96.9518)
		(width 0.089408)
		(layer "In11.Cu")
		(net "JTAG_PCH_PLD_TDO")
	)
	(segment
		(start 400.377914 -14.087348)
		(end 381.991362 -14.087348)
		(width 0.089408)
		(layer "In11.Cu")
		(net "JTAG_PCH_PLD_TDO")
	)
	(segment
		(start 388.525004 -63.62954)
		(end 387.527546 -64.626998)
		(width 0.089408)
		(layer "In11.Cu")
		(net "JTAG_PCH_PLD_TDO")
	)
	(segment
		(start 384.581654 -52.984908)
		(end 386.31749 -54.720744)
		(width 0.089408)
		(layer "In11.Cu")
		(net "JTAG_PCH_PLD_TDO")
	)
	(segment
		(start 373.93626 -22.14245)
		(end 373.93626 -27.220164)
		(width 0.089408)
		(layer "In11.Cu")
		(net "JTAG_PCH_PLD_TDO")
	)
	(segment
		(start 387.527546 -64.626998)
		(end 387.527546 -68.081144)
		(width 0.089408)
		(layer "In11.Cu")
		(net "JTAG_PCH_PLD_TDO")
	)
	(segment
		(start 389.62203 -100.34651)
		(end 390.21385 -100.93833)
		(width 0.089408)
		(layer "In11.Cu")
		(net "JTAG_PCH_PLD_TDO")
	)
	(segment
		(start 387.121654 -71.886572)
		(end 387.121654 -75.2094)
		(width 0.089408)
		(layer "In11.Cu")
		(net "JTAG_PCH_PLD_TDO")
	)
	(segment
		(start 390.1186 -97.79)
		(end 390.61263 -98.28403)
		(width 0.089408)
		(layer "In11.Cu")
		(net "JTAG_PCH_PLD_TDO")
	)
	(segment
		(start 388.793482 -90.365834)
		(end 388.793482 -91.115388)
		(width 0.089408)
		(layer "In11.Cu")
		(net "JTAG_PCH_PLD_TDO")
	)
	(segment
		(start 418.099748 -12.383008)
		(end 402.082254 -12.383008)
		(width 0.089408)
		(layer "In11.Cu")
		(net "JTAG_PCH_PLD_TDO")
	)
	(segment
		(start 374.203722 -46.470316)
		(end 377.225814 -49.492408)
		(width 0.089408)
		(layer "In11.Cu")
		(net "JTAG_PCH_PLD_TDO")
	)
	(segment
		(start 454.045574 -6.11124)
		(end 452.458582 -6.11124)
		(width 0.089408)
		(layer "In11.Cu")
		(net "JTAG_PCH_PLD_TDO")
	)
	(segment
		(start 373.936514 -27.42057)
		(end 372.185184 -29.1719)
		(width 0.089408)
		(layer "In11.Cu")
		(net "JTAG_PCH_PLD_TDO")
	)
	(segment
		(start 437.18988 -13.703046)
		(end 437.172862 -13.720064)
		(width 0.089408)
		(layer "In11.Cu")
		(net "JTAG_PCH_PLD_TDO")
	)
	(segment
		(start 426.871638 -14.774672)
		(end 420.491412 -14.774672)
		(width 0.089408)
		(layer "In11.Cu")
		(net "JTAG_PCH_PLD_TDO")
	)
	(segment
		(start 389.35406 -89.805256)
		(end 388.793482 -90.365834)
		(width 0.089408)
		(layer "In11.Cu")
		(net "JTAG_PCH_PLD_TDO")
	)
	(segment
		(start 390.1186 -99.5172)
		(end 389.62203 -100.01377)
		(width 0.089408)
		(layer "In11.Cu")
		(net "JTAG_PCH_PLD_TDO")
	)
	(segment
		(start 388.793482 -91.115388)
		(end 388.176262 -91.732608)
		(width 0.089408)
		(layer "In11.Cu")
		(net "JTAG_PCH_PLD_TDO")
	)
	(segment
		(start 458.251052 -4.360672)
		(end 457.258166 -5.353558)
		(width 0.089408)
		(layer "In11.Cu")
		(net "JTAG_PCH_PLD_TDO")
	)
	(segment
		(start 436.82412 -13.703046)
		(end 427.943264 -13.703046)
		(width 0.089408)
		(layer "In11.Cu")
		(net "JTAG_PCH_PLD_TDO")
	)
	(segment
		(start 389.636 -96.9518)
		(end 390.1186 -97.4344)
		(width 0.089408)
		(layer "In11.Cu")
		(net "JTAG_PCH_PLD_TDO")
	)
	(segment
		(start 386.31749 -54.720744)
		(end 386.31749 -56.89854)
		(width 0.089408)
		(layer "In11.Cu")
		(net "JTAG_PCH_PLD_TDO")
	)
	(segment
		(start 460.521304 -4.360672)
		(end 458.251052 -4.360672)
		(width 0.089408)
		(layer "In11.Cu")
		(net "JTAG_PCH_PLD_TDO")
	)
	(segment
		(start 446.002918 -12.566904)
		(end 440.01944 -12.566904)
		(width 0.089408)
		(layer "In11.Cu")
		(net "JTAG_PCH_PLD_TDO")
	)
	(segment
		(start 388.176262 -93.346524)
		(end 389.317484 -94.487746)
		(width 0.089408)
		(layer "In11.Cu")
		(net "JTAG_PCH_PLD_TDO")
	)
	(segment
		(start 372.443502 -44.342812)
		(end 374.203722 -46.103032)
		(width 0.089408)
		(layer "In11.Cu")
		(net "JTAG_PCH_PLD_TDO")
	)
	(segment
		(start 402.082254 -12.383008)
		(end 400.377914 -14.087348)
		(width 0.089408)
		(layer "In11.Cu")
		(net "JTAG_PCH_PLD_TDO")
	)
	(segment
		(start 373.93626 -27.220164)
		(end 373.936514 -27.220418)
		(width 0.089408)
		(layer "In11.Cu")
		(net "JTAG_PCH_PLD_TDO")
	)
	(segment
		(start 388.982712 -62.517528)
		(end 388.525004 -62.975236)
		(width 0.089408)
		(layer "In11.Cu")
		(net "JTAG_PCH_PLD_TDO")
	)
	(segment
		(start 372.185184 -29.1719)
		(end 372.185184 -33.48609)
		(width 0.089408)
		(layer "In11.Cu")
		(net "JTAG_PCH_PLD_TDO")
	)
	(segment
		(start 388.420102 -61.246004)
		(end 388.982712 -61.808614)
		(width 0.089408)
		(layer "In11.Cu")
		(net "JTAG_PCH_PLD_TDO")
	)
	(segment
		(start 388.708392 -82.088228)
		(end 388.708392 -83.052412)
		(width 0.089408)
		(layer "In11.Cu")
		(net "JTAG_PCH_PLD_TDO")
	)
	(segment
		(start 389.35406 -83.69808)
		(end 389.35406 -89.805256)
		(width 0.089408)
		(layer "In11.Cu")
		(net "JTAG_PCH_PLD_TDO")
	)
	(segment
		(start 390.61263 -98.64217)
		(end 390.1186 -99.1362)
		(width 0.089408)
		(layer "In11.Cu")
		(net "JTAG_PCH_PLD_TDO")
	)
	(segment
		(start 456.881992 -5.980684)
		(end 456.349608 -5.980684)
		(width 0.089408)
		(layer "In11.Cu")
		(net "JTAG_PCH_PLD_TDO")
	)
	(segment
		(start 388.420102 -59.001152)
		(end 388.420102 -61.246004)
		(width 0.089408)
		(layer "In11.Cu")
		(net "JTAG_PCH_PLD_TDO")
	)
	(segment
		(start 388.261098 -78.66126)
		(end 389.160512 -79.560674)
		(width 0.089408)
		(layer "In11.Cu")
		(net "JTAG_PCH_PLD_TDO")
	)
	(segment
		(start 377.225814 -49.492408)
		(end 380.386336 -49.492408)
		(width 0.089408)
		(layer "In11.Cu")
		(net "JTAG_PCH_PLD_TDO")
	)
	(segment
		(start 454.545954 -5.61086)
		(end 454.045574 -6.11124)
		(width 0.089408)
		(layer "In11.Cu")
		(net "JTAG_PCH_PLD_TDO")
	)
	(segment
		(start 388.525004 -62.975236)
		(end 388.525004 -63.62954)
		(width 0.089408)
		(layer "In11.Cu")
		(net "JTAG_PCH_PLD_TDO")
	)
	(segment
		(start 389.317484 -94.487746)
		(end 389.317484 -96.252284)
		(width 0.089408)
		(layer "In11.Cu")
		(net "JTAG_PCH_PLD_TDO")
	)
	(segment
		(start 427.943264 -13.703046)
		(end 426.871638 -14.774672)
		(width 0.089408)
		(layer "In11.Cu")
		(net "JTAG_PCH_PLD_TDO")
	)
	(segment
		(start 464.281774 -5.717794)
		(end 464.087464 -5.912104)
		(width 0.089408)
		(layer "In11.Cu")
		(net "JTAG_PCH_PLD_TDO")
	)
	(segment
		(start 388.982712 -61.808614)
		(end 388.982712 -62.517528)
		(width 0.089408)
		(layer "In11.Cu")
		(net "JTAG_PCH_PLD_TDO")
	)
	(segment
		(start 438.883298 -13.703046)
		(end 437.18988 -13.703046)
		(width 0.089408)
		(layer "In11.Cu")
		(net "JTAG_PCH_PLD_TDO")
	)
	(segment
		(start 457.258166 -5.353558)
		(end 457.258166 -5.60451)
		(width 0.089408)
		(layer "In11.Cu")
		(net "JTAG_PCH_PLD_TDO")
	)
	(segment
		(start 383.5654 -52.671472)
		(end 384.347212 -52.671472)
		(width 0.089408)
		(layer "In11.Cu")
		(net "JTAG_PCH_PLD_TDO")
	)
	(segment
		(start 372.443502 -33.744408)
		(end 372.443502 -44.342812)
		(width 0.089408)
		(layer "In11.Cu")
		(net "JTAG_PCH_PLD_TDO")
	)
	(segment
		(start 386.178044 -69.430646)
		(end 386.178044 -70.942962)
		(width 0.089408)
		(layer "In11.Cu")
		(net "JTAG_PCH_PLD_TDO")
	)
	(segment
		(start 387.121654 -75.2094)
		(end 388.261098 -76.348844)
		(width 0.089408)
		(layer "In11.Cu")
		(net "JTAG_PCH_PLD_TDO")
	)
	(segment
		(start 386.31749 -56.89854)
		(end 388.420102 -59.001152)
		(width 0.089408)
		(layer "In11.Cu")
		(net "JTAG_PCH_PLD_TDO")
	)
	(segment
		(start 455.979784 -5.61086)
		(end 454.545954 -5.61086)
		(width 0.089408)
		(layer "In11.Cu")
		(net "JTAG_PCH_PLD_TDO")
	)
	(segment
		(start 387.527546 -68.081144)
		(end 386.178044 -69.430646)
		(width 0.089408)
		(layer "In11.Cu")
		(net "JTAG_PCH_PLD_TDO")
	)
	(segment
		(start 464.955128 -4.393946)
		(end 464.281774 -5.0673)
		(width 0.089408)
		(layer "In11.Cu")
		(net "JTAG_PCH_PLD_TDO")
	)
	(segment
		(start 384.581654 -52.905914)
		(end 384.581654 -52.984908)
		(width 0.089408)
		(layer "In11.Cu")
		(net "JTAG_PCH_PLD_TDO")
	)
	(segment
		(start 468.230204 -2.965196)
		(end 466.801454 -4.393946)
		(width 0.089408)
		(layer "In11.Cu")
		(net "JTAG_PCH_PLD_TDO")
	)
	(segment
		(start 390.21385 -100.93833)
		(end 390.21385 -101.898196)
		(width 0.089408)
		(layer "In11.Cu")
		(net "JTAG_PCH_PLD_TDO")
	)
	(segment
		(start 390.1186 -97.4344)
		(end 390.1186 -97.79)
		(width 0.089408)
		(layer "In11.Cu")
		(net "JTAG_PCH_PLD_TDO")
	)
	(segment
		(start 456.349608 -5.980684)
		(end 455.979784 -5.61086)
		(width 0.089408)
		(layer "In11.Cu")
		(net "JTAG_PCH_PLD_TDO")
	)
	(segment
		(start 389.317484 -96.252284)
		(end 389.636 -96.5708)
		(width 0.089408)
		(layer "In11.Cu")
		(net "JTAG_PCH_PLD_TDO")
	)
	(segment
		(start 468.230204 -2.420112)
		(end 468.230204 -2.965196)
		(width 0.089408)
		(layer "In11.Cu")
		(net "JTAG_PCH_PLD_TDO")
	)
	(segment
		(start 389.160512 -79.560674)
		(end 389.160512 -81.636108)
		(width 0.089408)
		(layer "In11.Cu")
		(net "JTAG_PCH_PLD_TDO")
	)
	(segment
		(start 373.936514 -27.220418)
		(end 373.936514 -27.42057)
		(width 0.089408)
		(layer "In11.Cu")
		(net "JTAG_PCH_PLD_TDO")
	)
	(segment
		(start 390.1186 -99.1362)
		(end 390.1186 -99.5172)
		(width 0.089408)
		(layer "In11.Cu")
		(net "JTAG_PCH_PLD_TDO")
	)
	(segment
		(start 384.347212 -52.671472)
		(end 384.581654 -52.905914)
		(width 0.089408)
		(layer "In11.Cu")
		(net "JTAG_PCH_PLD_TDO")
	)
	(segment
		(start 440.01944 -12.566904)
		(end 438.883298 -13.703046)
		(width 0.089408)
		(layer "In11.Cu")
		(net "JTAG_PCH_PLD_TDO")
	)
	(segment
		(start 386.178044 -70.942962)
		(end 387.121654 -71.886572)
		(width 0.089408)
		(layer "In11.Cu")
		(net "JTAG_PCH_PLD_TDO")
	)
	(segment
		(start 374.203722 -46.103032)
		(end 374.203722 -46.470316)
		(width 0.089408)
		(layer "In11.Cu")
		(net "JTAG_PCH_PLD_TDO")
	)
	(segment
		(start 462.072736 -5.912104)
		(end 460.521304 -4.360672)
		(width 0.089408)
		(layer "In11.Cu")
		(net "JTAG_PCH_PLD_TDO")
	)
	(segment
		(start 389.160512 -81.636108)
		(end 388.708392 -82.088228)
		(width 0.089408)
		(layer "In11.Cu")
		(net "JTAG_PCH_PLD_TDO")
	)
	(segment
		(start 457.258166 -5.60451)
		(end 456.881992 -5.980684)
		(width 0.089408)
		(layer "In11.Cu")
		(net "JTAG_PCH_PLD_TDO")
	)
	(segment
		(start 466.801454 -4.393946)
		(end 464.955128 -4.393946)
		(width 0.089408)
		(layer "In11.Cu")
		(net "JTAG_PCH_PLD_TDO")
	)
	(segment
		(start 388.176262 -91.732608)
		(end 388.176262 -93.346524)
		(width 0.089408)
		(layer "In11.Cu")
		(net "JTAG_PCH_PLD_TDO")
	)
	(segment
		(start 452.458582 -6.11124)
		(end 446.002918 -12.566904)
		(width 0.089408)
		(layer "In11.Cu")
		(net "JTAG_PCH_PLD_TDO")
	)
	(segment
		(start 381.991362 -14.087348)
		(end 373.93626 -22.14245)
		(width 0.089408)
		(layer "In11.Cu")
		(net "JTAG_PCH_PLD_TDO")
	)
	(segment
		(start 388.708392 -83.052412)
		(end 389.35406 -83.69808)
		(width 0.089408)
		(layer "In11.Cu")
		(net "JTAG_PCH_PLD_TDO")
	)
	(segment
		(start 387.73735 -100.41128)
		(end 387.985 -100.296472)
		(width 0.10795)
		(layer "F.Cu")
		(net "JTAG_PCH_PLD_TDI")
	)
	(segment
		(start 388.23265 -100.18141)
		(end 388.23265 -100.181156)
		(width 0.10795)
		(layer "F.Cu")
		(net "JTAG_PCH_PLD_TDI")
	)
	(segment
		(start 387.985 -100.296472)
		(end 388.23265 -100.18141)
		(width 0.10795)
		(layer "F.Cu")
		(net "JTAG_PCH_PLD_TDI")
	)
	(segment
		(start 389.636 -0.254)
		(end 389.636 -0.889)
		(width 0.10795)
		(layer "F.Cu")
		(net "JTAG_PCH_PLD_TDI")
	)
	(via
		(at 389.636 -0.889)
		(size 0.508)
		(drill 0.254)
		(layers "F.Cu" "B.Cu")
		(net "JTAG_PCH_PLD_TDI")
	)
	(via
		(at 388.23265 -100.181156)
		(size 0.508)
		(drill 0.254)
		(layers "F.Cu" "B.Cu")
		(net "JTAG_PCH_PLD_TDI")
	)
	(via
		(at 463.1944 -2.2352)
		(size 0.508)
		(drill 0.254)
		(layers "F.Cu" "B.Cu")
		(net "JTAG_PCH_PLD_TDI")
	)
	(segment
		(start 431.01514 2.284984)
		(end 462.53146 2.284984)
		(width 0.089408)
		(layer "In4.Cu")
		(net "JTAG_PCH_PLD_TDI")
	)
	(segment
		(start 423.011346 2.33553)
		(end 423.0116 2.335276)
		(width 0.089408)
		(layer "In4.Cu")
		(net "JTAG_PCH_PLD_TDI")
	)
	(segment
		(start 423.21226 2.335784)
		(end 426.49394 2.335784)
		(width 0.089408)
		(layer "In4.Cu")
		(net "JTAG_PCH_PLD_TDI")
	)
	(segment
		(start 462.915 -1.9558)
		(end 463.1944 -2.2352)
		(width 0.089408)
		(layer "In4.Cu")
		(net "JTAG_PCH_PLD_TDI")
	)
	(segment
		(start 463.3214 1.495044)
		(end 463.3214 0.1016)
		(width 0.089408)
		(layer "In4.Cu")
		(net "JTAG_PCH_PLD_TDI")
	)
	(segment
		(start 462.53146 2.284984)
		(end 463.3214 1.495044)
		(width 0.089408)
		(layer "In4.Cu")
		(net "JTAG_PCH_PLD_TDI")
	)
	(segment
		(start 421.301164 3.84556)
		(end 422.811194 2.33553)
		(width 0.089408)
		(layer "In4.Cu")
		(net "JTAG_PCH_PLD_TDI")
	)
	(segment
		(start 427.02226 2.335784)
		(end 427.028356 2.34188)
		(width 0.089408)
		(layer "In4.Cu")
		(net "JTAG_PCH_PLD_TDI")
	)
	(segment
		(start 418.4523 3.84556)
		(end 421.301164 3.84556)
		(width 0.089408)
		(layer "In4.Cu")
		(net "JTAG_PCH_PLD_TDI")
	)
	(segment
		(start 416.646614 3.845814)
		(end 418.452046 3.845814)
		(width 0.089408)
		(layer "In4.Cu")
		(net "JTAG_PCH_PLD_TDI")
	)
	(segment
		(start 423.211752 2.335276)
		(end 423.21226 2.335784)
		(width 0.089408)
		(layer "In4.Cu")
		(net "JTAG_PCH_PLD_TDI")
	)
	(segment
		(start 394.780262 2.47396)
		(end 400.251168 2.47396)
		(width 0.089408)
		(layer "In4.Cu")
		(net "JTAG_PCH_PLD_TDI")
	)
	(segment
		(start 416.64636 3.84556)
		(end 416.646614 3.845814)
		(width 0.089408)
		(layer "In4.Cu")
		(net "JTAG_PCH_PLD_TDI")
	)
	(segment
		(start 422.811194 2.33553)
		(end 423.011346 2.33553)
		(width 0.089408)
		(layer "In4.Cu")
		(net "JTAG_PCH_PLD_TDI")
	)
	(segment
		(start 426.494194 2.33553)
		(end 426.895006 2.33553)
		(width 0.089408)
		(layer "In4.Cu")
		(net "JTAG_PCH_PLD_TDI")
	)
	(segment
		(start 426.895006 2.33553)
		(end 426.89526 2.335784)
		(width 0.089408)
		(layer "In4.Cu")
		(net "JTAG_PCH_PLD_TDI")
	)
	(segment
		(start 462.915 -0.3048)
		(end 462.915 -1.9558)
		(width 0.089408)
		(layer "In4.Cu")
		(net "JTAG_PCH_PLD_TDI")
	)
	(segment
		(start 392.084814 -0.221488)
		(end 394.780262 2.47396)
		(width 0.089408)
		(layer "In4.Cu")
		(net "JTAG_PCH_PLD_TDI")
	)
	(segment
		(start 413.969962 2.450592)
		(end 415.36493 3.84556)
		(width 0.089408)
		(layer "In4.Cu")
		(net "JTAG_PCH_PLD_TDI")
	)
	(segment
		(start 390.303512 -0.221488)
		(end 392.084814 -0.221488)
		(width 0.089408)
		(layer "In4.Cu")
		(net "JTAG_PCH_PLD_TDI")
	)
	(segment
		(start 463.3214 0.1016)
		(end 462.915 -0.3048)
		(width 0.089408)
		(layer "In4.Cu")
		(net "JTAG_PCH_PLD_TDI")
	)
	(segment
		(start 426.89526 2.335784)
		(end 427.02226 2.335784)
		(width 0.089408)
		(layer "In4.Cu")
		(net "JTAG_PCH_PLD_TDI")
	)
	(segment
		(start 400.901408 3.1242)
		(end 412.230062 3.1242)
		(width 0.089408)
		(layer "In4.Cu")
		(net "JTAG_PCH_PLD_TDI")
	)
	(segment
		(start 415.36493 3.84556)
		(end 416.64636 3.84556)
		(width 0.089408)
		(layer "In4.Cu")
		(net "JTAG_PCH_PLD_TDI")
	)
	(segment
		(start 418.452046 3.845814)
		(end 418.4523 3.84556)
		(width 0.089408)
		(layer "In4.Cu")
		(net "JTAG_PCH_PLD_TDI")
	)
	(segment
		(start 426.49394 2.335784)
		(end 426.494194 2.33553)
		(width 0.089408)
		(layer "In4.Cu")
		(net "JTAG_PCH_PLD_TDI")
	)
	(segment
		(start 412.230062 3.1242)
		(end 412.90367 2.450592)
		(width 0.089408)
		(layer "In4.Cu")
		(net "JTAG_PCH_PLD_TDI")
	)
	(segment
		(start 389.636 -0.889)
		(end 390.303512 -0.221488)
		(width 0.089408)
		(layer "In4.Cu")
		(net "JTAG_PCH_PLD_TDI")
	)
	(segment
		(start 400.251168 2.47396)
		(end 400.901408 3.1242)
		(width 0.089408)
		(layer "In4.Cu")
		(net "JTAG_PCH_PLD_TDI")
	)
	(segment
		(start 427.028356 2.34188)
		(end 430.958244 2.34188)
		(width 0.089408)
		(layer "In4.Cu")
		(net "JTAG_PCH_PLD_TDI")
	)
	(segment
		(start 423.0116 2.335276)
		(end 423.211752 2.335276)
		(width 0.089408)
		(layer "In4.Cu")
		(net "JTAG_PCH_PLD_TDI")
	)
	(segment
		(start 430.958244 2.34188)
		(end 431.01514 2.284984)
		(width 0.089408)
		(layer "In4.Cu")
		(net "JTAG_PCH_PLD_TDI")
	)
	(segment
		(start 412.90367 2.450592)
		(end 413.969962 2.450592)
		(width 0.089408)
		(layer "In4.Cu")
		(net "JTAG_PCH_PLD_TDI")
	)
	(segment
		(start 388.63143 -98.64217)
		(end 388.63143 -98.28403)
		(width 0.089408)
		(layer "In11.Cu")
		(net "JTAG_PCH_PLD_TDI")
	)
	(segment
		(start 457.871322 -4.118864)
		(end 460.621634 -4.118864)
		(width 0.089408)
		(layer "In11.Cu")
		(net "JTAG_PCH_PLD_TDI")
	)
	(segment
		(start 385.78282 -55.103014)
		(end 384.869182 -54.189376)
		(width 0.089408)
		(layer "In11.Cu")
		(net "JTAG_PCH_PLD_TDI")
	)
	(segment
		(start 388.16534 -85.336888)
		(end 388.47522 -85.027008)
		(width 0.089408)
		(layer "In11.Cu")
		(net "JTAG_PCH_PLD_TDI")
	)
	(segment
		(start 388.326376 -100.08743)
		(end 388.326376 -98.947224)
		(width 0.089408)
		(layer "In11.Cu")
		(net "JTAG_PCH_PLD_TDI")
	)
	(segment
		(start 388.16534 -87.741506)
		(end 388.16534 -85.336888)
		(width 0.089408)
		(layer "In11.Cu")
		(net "JTAG_PCH_PLD_TDI")
	)
	(segment
		(start 381.324866 -51.41722)
		(end 380.82728 -51.41722)
		(width 0.089408)
		(layer "In11.Cu")
		(net "JTAG_PCH_PLD_TDI")
	)
	(segment
		(start 388.326884 -97.216976)
		(end 388.63143 -96.91243)
		(width 0.089408)
		(layer "In11.Cu")
		(net "JTAG_PCH_PLD_TDI")
	)
	(segment
		(start 388.326376 -98.947224)
		(end 388.63143 -98.64217)
		(width 0.089408)
		(layer "In11.Cu")
		(net "JTAG_PCH_PLD_TDI")
	)
	(segment
		(start 388.13613 -96.06407)
		(end 388.13613 -95.19031)
		(width 0.089408)
		(layer "In11.Cu")
		(net "JTAG_PCH_PLD_TDI")
	)
	(segment
		(start 385.694428 -69.016372)
		(end 386.587746 -68.123054)
		(width 0.089408)
		(layer "In11.Cu")
		(net "JTAG_PCH_PLD_TDI")
	)
	(segment
		(start 460.621634 -4.118864)
		(end 460.834232 -4.331462)
		(width 0.089408)
		(layer "In11.Cu")
		(net "JTAG_PCH_PLD_TDI")
	)
	(segment
		(start 460.834232 -4.331462)
		(end 461.973676 -4.331462)
		(width 0.089408)
		(layer "In11.Cu")
		(net "JTAG_PCH_PLD_TDI")
	)
	(segment
		(start 428.541434 -11.133074)
		(end 446.752472 -11.133074)
		(width 0.089408)
		(layer "In11.Cu")
		(net "JTAG_PCH_PLD_TDI")
	)
	(segment
		(start 386.587746 -63.236348)
		(end 387.487414 -62.33668)
		(width 0.089408)
		(layer "In11.Cu")
		(net "JTAG_PCH_PLD_TDI")
	)
	(segment
		(start 456.781662 -5.738876)
		(end 457.016104 -5.504434)
		(width 0.089408)
		(layer "In11.Cu")
		(net "JTAG_PCH_PLD_TDI")
	)
	(segment
		(start 455.680064 -4.969002)
		(end 456.449938 -5.738876)
		(width 0.089408)
		(layer "In11.Cu")
		(net "JTAG_PCH_PLD_TDI")
	)
	(segment
		(start 371.959886 -44.543472)
		(end 371.959886 -33.945068)
		(width 0.089408)
		(layer "In11.Cu")
		(net "JTAG_PCH_PLD_TDI")
	)
	(segment
		(start 388.704582 -89.770458)
		(end 388.704582 -88.280748)
		(width 0.089408)
		(layer "In11.Cu")
		(net "JTAG_PCH_PLD_TDI")
	)
	(segment
		(start 373.45239 -27.220418)
		(end 373.45239 -21.942044)
		(width 0.089408)
		(layer "In11.Cu")
		(net "JTAG_PCH_PLD_TDI")
	)
	(segment
		(start 457.016104 -4.974082)
		(end 457.871322 -4.118864)
		(width 0.089408)
		(layer "In11.Cu")
		(net "JTAG_PCH_PLD_TDI")
	)
	(segment
		(start 379.386338 -49.976278)
		(end 377.025408 -49.976278)
		(width 0.089408)
		(layer "In11.Cu")
		(net "JTAG_PCH_PLD_TDI")
	)
	(segment
		(start 387.86054 -80.849724)
		(end 386.638038 -79.627222)
		(width 0.089408)
		(layer "In11.Cu")
		(net "JTAG_PCH_PLD_TDI")
	)
	(segment
		(start 388.704582 -88.280748)
		(end 388.16534 -87.741506)
		(width 0.089408)
		(layer "In11.Cu")
		(net "JTAG_PCH_PLD_TDI")
	)
	(segment
		(start 388.47522 -85.027008)
		(end 388.47522 -83.62188)
		(width 0.089408)
		(layer "In11.Cu")
		(net "JTAG_PCH_PLD_TDI")
	)
	(segment
		(start 456.449938 -5.738876)
		(end 456.781662 -5.738876)
		(width 0.089408)
		(layer "In11.Cu")
		(net "JTAG_PCH_PLD_TDI")
	)
	(segment
		(start 371.701568 -33.68675)
		(end 371.701568 -28.97124)
		(width 0.089408)
		(layer "In11.Cu")
		(net "JTAG_PCH_PLD_TDI")
	)
	(segment
		(start 386.587746 -68.123054)
		(end 386.587746 -63.236348)
		(width 0.089408)
		(layer "In11.Cu")
		(net "JTAG_PCH_PLD_TDI")
	)
	(segment
		(start 388.13613 -95.19031)
		(end 387.661404 -94.715584)
		(width 0.089408)
		(layer "In11.Cu")
		(net "JTAG_PCH_PLD_TDI")
	)
	(segment
		(start 461.973676 -4.331462)
		(end 463.1944 -3.110738)
		(width 0.089408)
		(layer "In11.Cu")
		(net "JTAG_PCH_PLD_TDI")
	)
	(segment
		(start 377.025408 -49.976278)
		(end 373.720106 -46.670976)
		(width 0.089408)
		(layer "In11.Cu")
		(net "JTAG_PCH_PLD_TDI")
	)
	(segment
		(start 387.487414 -59.959494)
		(end 386.587746 -59.059826)
		(width 0.089408)
		(layer "In11.Cu")
		(net "JTAG_PCH_PLD_TDI")
	)
	(segment
		(start 388.63143 -96.55937)
		(end 388.13613 -96.06407)
		(width 0.089408)
		(layer "In11.Cu")
		(net "JTAG_PCH_PLD_TDI")
	)
	(segment
		(start 425.505626 -14.168882)
		(end 428.541434 -11.133074)
		(width 0.089408)
		(layer "In11.Cu")
		(net "JTAG_PCH_PLD_TDI")
	)
	(segment
		(start 418.300408 -11.899392)
		(end 420.569898 -14.168882)
		(width 0.089408)
		(layer "In11.Cu")
		(net "JTAG_PCH_PLD_TDI")
	)
	(segment
		(start 385.78282 -57.120028)
		(end 385.78282 -55.103014)
		(width 0.089408)
		(layer "In11.Cu")
		(net "JTAG_PCH_PLD_TDI")
	)
	(segment
		(start 446.752472 -11.133074)
		(end 452.91629 -4.969256)
		(width 0.089408)
		(layer "In11.Cu")
		(net "JTAG_PCH_PLD_TDI")
	)
	(segment
		(start 371.959886 -33.945068)
		(end 371.701568 -33.68675)
		(width 0.089408)
		(layer "In11.Cu")
		(net "JTAG_PCH_PLD_TDI")
	)
	(segment
		(start 401.881594 -11.899392)
		(end 418.300408 -11.899392)
		(width 0.089408)
		(layer "In11.Cu")
		(net "JTAG_PCH_PLD_TDI")
	)
	(segment
		(start 420.569898 -14.168882)
		(end 425.505626 -14.168882)
		(width 0.089408)
		(layer "In11.Cu")
		(net "JTAG_PCH_PLD_TDI")
	)
	(segment
		(start 386.587746 -59.059826)
		(end 386.587746 -57.924954)
		(width 0.089408)
		(layer "In11.Cu")
		(net "JTAG_PCH_PLD_TDI")
	)
	(segment
		(start 384.097022 -54.189376)
		(end 381.324866 -51.41722)
		(width 0.089408)
		(layer "In11.Cu")
		(net "JTAG_PCH_PLD_TDI")
	)
	(segment
		(start 388.63143 -96.91243)
		(end 388.63143 -96.55937)
		(width 0.089408)
		(layer "In11.Cu")
		(net "JTAG_PCH_PLD_TDI")
	)
	(segment
		(start 373.720106 -46.670976)
		(end 373.720106 -46.303692)
		(width 0.089408)
		(layer "In11.Cu")
		(net "JTAG_PCH_PLD_TDI")
	)
	(segment
		(start 371.701568 -28.97124)
		(end 373.45239 -27.220418)
		(width 0.089408)
		(layer "In11.Cu")
		(net "JTAG_PCH_PLD_TDI")
	)
	(segment
		(start 388.309866 -90.857832)
		(end 388.309866 -90.165174)
		(width 0.089408)
		(layer "In11.Cu")
		(net "JTAG_PCH_PLD_TDI")
	)
	(segment
		(start 381.790702 -13.603732)
		(end 400.177254 -13.603732)
		(width 0.089408)
		(layer "In11.Cu")
		(net "JTAG_PCH_PLD_TDI")
	)
	(segment
		(start 387.661404 -94.715584)
		(end 387.661404 -91.506294)
		(width 0.089408)
		(layer "In11.Cu")
		(net "JTAG_PCH_PLD_TDI")
	)
	(segment
		(start 373.45239 -21.942044)
		(end 381.790702 -13.603732)
		(width 0.089408)
		(layer "In11.Cu")
		(net "JTAG_PCH_PLD_TDI")
	)
	(segment
		(start 386.638038 -72.087232)
		(end 385.694428 -71.143622)
		(width 0.089408)
		(layer "In11.Cu")
		(net "JTAG_PCH_PLD_TDI")
	)
	(segment
		(start 384.869182 -54.189376)
		(end 384.097022 -54.189376)
		(width 0.089408)
		(layer "In11.Cu")
		(net "JTAG_PCH_PLD_TDI")
	)
	(segment
		(start 388.309866 -90.165174)
		(end 388.704582 -89.770458)
		(width 0.089408)
		(layer "In11.Cu")
		(net "JTAG_PCH_PLD_TDI")
	)
	(segment
		(start 400.177254 -13.603732)
		(end 401.881594 -11.899392)
		(width 0.089408)
		(layer "In11.Cu")
		(net "JTAG_PCH_PLD_TDI")
	)
	(segment
		(start 388.47522 -83.62188)
		(end 387.86054 -83.0072)
		(width 0.089408)
		(layer "In11.Cu")
		(net "JTAG_PCH_PLD_TDI")
	)
	(segment
		(start 387.661404 -91.506294)
		(end 388.309866 -90.857832)
		(width 0.089408)
		(layer "In11.Cu")
		(net "JTAG_PCH_PLD_TDI")
	)
	(segment
		(start 386.587746 -57.924954)
		(end 385.78282 -57.120028)
		(width 0.089408)
		(layer "In11.Cu")
		(net "JTAG_PCH_PLD_TDI")
	)
	(segment
		(start 387.86054 -83.0072)
		(end 387.86054 -80.849724)
		(width 0.089408)
		(layer "In11.Cu")
		(net "JTAG_PCH_PLD_TDI")
	)
	(segment
		(start 454.749154 -4.969002)
		(end 455.680064 -4.969002)
		(width 0.089408)
		(layer "In11.Cu")
		(net "JTAG_PCH_PLD_TDI")
	)
	(segment
		(start 380.82728 -51.41722)
		(end 379.386338 -49.976278)
		(width 0.089408)
		(layer "In11.Cu")
		(net "JTAG_PCH_PLD_TDI")
	)
	(segment
		(start 387.487414 -62.33668)
		(end 387.487414 -59.959494)
		(width 0.089408)
		(layer "In11.Cu")
		(net "JTAG_PCH_PLD_TDI")
	)
	(segment
		(start 388.326884 -97.979484)
		(end 388.326884 -97.216976)
		(width 0.089408)
		(layer "In11.Cu")
		(net "JTAG_PCH_PLD_TDI")
	)
	(segment
		(start 463.1944 -3.110738)
		(end 463.1944 -2.2352)
		(width 0.089408)
		(layer "In11.Cu")
		(net "JTAG_PCH_PLD_TDI")
	)
	(segment
		(start 385.694428 -71.143622)
		(end 385.694428 -69.016372)
		(width 0.089408)
		(layer "In11.Cu")
		(net "JTAG_PCH_PLD_TDI")
	)
	(segment
		(start 388.63143 -98.28403)
		(end 388.326884 -97.979484)
		(width 0.089408)
		(layer "In11.Cu")
		(net "JTAG_PCH_PLD_TDI")
	)
	(segment
		(start 388.23265 -100.181156)
		(end 388.326376 -100.08743)
		(width 0.089408)
		(layer "In11.Cu")
		(net "JTAG_PCH_PLD_TDI")
	)
	(segment
		(start 452.91629 -4.969256)
		(end 454.7489 -4.969256)
		(width 0.089408)
		(layer "In11.Cu")
		(net "JTAG_PCH_PLD_TDI")
	)
	(segment
		(start 386.638038 -79.627222)
		(end 386.638038 -72.087232)
		(width 0.089408)
		(layer "In11.Cu")
		(net "JTAG_PCH_PLD_TDI")
	)
	(segment
		(start 457.016104 -5.504434)
		(end 457.016104 -4.974082)
		(width 0.089408)
		(layer "In11.Cu")
		(net "JTAG_PCH_PLD_TDI")
	)
	(segment
		(start 373.720106 -46.303692)
		(end 371.959886 -44.543472)
		(width 0.089408)
		(layer "In11.Cu")
		(net "JTAG_PCH_PLD_TDI")
	)
	(segment
		(start 454.7489 -4.969256)
		(end 454.749154 -4.969002)
		(width 0.089408)
		(layer "In11.Cu")
		(net "JTAG_PCH_PLD_TDI")
	)
	(segment
		(start 388.23265 -101.2698)
		(end 387.92785 -100.965)
		(width 0.10795)
		(layer "F.Cu")
		(net "JTAG_PCH_PLD_TCK")
	)
	(segment
		(start 396.5448 -0.6858)
		(end 396.367 -0.8636)
		(width 0.10795)
		(layer "F.Cu")
		(net "JTAG_PCH_PLD_TCK")
	)
	(segment
		(start 396.5448 -0.2286)
		(end 396.5448 -0.6858)
		(width 0.10795)
		(layer "F.Cu")
		(net "JTAG_PCH_PLD_TCK")
	)
	(segment
		(start 387.92785 -100.965)
		(end 387.771386 -100.965)
		(width 0.10795)
		(layer "F.Cu")
		(net "JTAG_PCH_PLD_TCK")
	)
	(via
		(at 387.771386 -100.965)
		(size 0.508)
		(drill 0.254)
		(layers "F.Cu" "B.Cu")
		(net "JTAG_PCH_PLD_TCK")
	)
	(via
		(at 453.86371 -5.68325)
		(size 0.508)
		(drill 0.254)
		(layers "F.Cu" "B.Cu")
		(net "JTAG_PCH_PLD_TCK")
	)
	(via
		(at 396.367 -0.8636)
		(size 0.508)
		(drill 0.254)
		(layers "F.Cu" "B.Cu")
		(net "JTAG_PCH_PLD_TCK")
	)
	(segment
		(start 396.367 -0.8636)
		(end 397.009112 -0.221488)
		(width 0.089408)
		(layer "In4.Cu")
		(net "JTAG_PCH_PLD_TCK")
	)
	(segment
		(start 403.068028 -0.489712)
		(end 404.494492 -0.489712)
		(width 0.089408)
		(layer "In4.Cu")
		(net "JTAG_PCH_PLD_TCK")
	)
	(segment
		(start 449.588128 -1.407668)
		(end 453.86371 -5.68325)
		(width 0.089408)
		(layer "In4.Cu")
		(net "JTAG_PCH_PLD_TCK")
	)
	(segment
		(start 407.85415 0.272288)
		(end 415.631122 0.272288)
		(width 0.089408)
		(layer "In4.Cu")
		(net "JTAG_PCH_PLD_TCK")
	)
	(segment
		(start 404.494492 -0.489712)
		(end 405.778716 0.794512)
		(width 0.089408)
		(layer "In4.Cu")
		(net "JTAG_PCH_PLD_TCK")
	)
	(segment
		(start 420.591742 1.817878)
		(end 422.15562 0.254)
		(width 0.089408)
		(layer "In4.Cu")
		(net "JTAG_PCH_PLD_TCK")
	)
	(segment
		(start 422.15562 0.254)
		(end 429.82642 0.254)
		(width 0.089408)
		(layer "In4.Cu")
		(net "JTAG_PCH_PLD_TCK")
	)
	(segment
		(start 402.8567 -0.278384)
		(end 403.068028 -0.489712)
		(width 0.089408)
		(layer "In4.Cu")
		(net "JTAG_PCH_PLD_TCK")
	)
	(segment
		(start 417.176712 1.817878)
		(end 420.591742 1.817878)
		(width 0.089408)
		(layer "In4.Cu")
		(net "JTAG_PCH_PLD_TCK")
	)
	(segment
		(start 415.631122 0.272288)
		(end 417.176712 1.817878)
		(width 0.089408)
		(layer "In4.Cu")
		(net "JTAG_PCH_PLD_TCK")
	)
	(segment
		(start 399.31975 -0.221488)
		(end 399.376646 -0.278384)
		(width 0.089408)
		(layer "In4.Cu")
		(net "JTAG_PCH_PLD_TCK")
	)
	(segment
		(start 407.331926 0.794512)
		(end 407.85415 0.272288)
		(width 0.089408)
		(layer "In4.Cu")
		(net "JTAG_PCH_PLD_TCK")
	)
	(segment
		(start 431.488088 -1.407668)
		(end 449.588128 -1.407668)
		(width 0.089408)
		(layer "In4.Cu")
		(net "JTAG_PCH_PLD_TCK")
	)
	(segment
		(start 397.009112 -0.221488)
		(end 399.31975 -0.221488)
		(width 0.089408)
		(layer "In4.Cu")
		(net "JTAG_PCH_PLD_TCK")
	)
	(segment
		(start 399.376646 -0.278384)
		(end 402.8567 -0.278384)
		(width 0.089408)
		(layer "In4.Cu")
		(net "JTAG_PCH_PLD_TCK")
	)
	(segment
		(start 429.82642 0.254)
		(end 431.488088 -1.407668)
		(width 0.089408)
		(layer "In4.Cu")
		(net "JTAG_PCH_PLD_TCK")
	)
	(segment
		(start 405.778716 0.794512)
		(end 407.331926 0.794512)
		(width 0.089408)
		(layer "In4.Cu")
		(net "JTAG_PCH_PLD_TCK")
	)
	(segment
		(start 388.14248 -80.789526)
		(end 388.14248 -82.828638)
		(width 0.089408)
		(layer "In11.Cu")
		(net "JTAG_PCH_PLD_TCK")
	)
	(segment
		(start 387.908546 -91.62415)
		(end 387.908546 -93.595444)
		(width 0.089408)
		(layer "In11.Cu")
		(net "JTAG_PCH_PLD_TCK")
	)
	(segment
		(start 389.112252 -83.79841)
		(end 389.112252 -89.704926)
		(width 0.089408)
		(layer "In11.Cu")
		(net "JTAG_PCH_PLD_TCK")
	)
	(segment
		(start 388.178294 -59.101482)
		(end 388.178294 -60.42152)
		(width 0.089408)
		(layer "In11.Cu")
		(net "JTAG_PCH_PLD_TCK")
	)
	(segment
		(start 389.128 -97.409)
		(end 389.128 -97.79)
		(width 0.089408)
		(layer "In11.Cu")
		(net "JTAG_PCH_PLD_TCK")
	)
	(segment
		(start 380.885446 -51.124612)
		(end 381.628142 -51.124612)
		(width 0.089408)
		(layer "In11.Cu")
		(net "JTAG_PCH_PLD_TCK")
	)
	(segment
		(start 389.12673 -96.05391)
		(end 388.822184 -96.358456)
		(width 0.089408)
		(layer "In11.Cu")
		(net "JTAG_PCH_PLD_TCK")
	)
	(segment
		(start 388.079996 -62.719712)
		(end 388.079996 -63.67907)
		(width 0.089408)
		(layer "In11.Cu")
		(net "JTAG_PCH_PLD_TCK")
	)
	(segment
		(start 373.961914 -46.570646)
		(end 377.125738 -49.73447)
		(width 0.089408)
		(layer "In11.Cu")
		(net "JTAG_PCH_PLD_TCK")
	)
	(segment
		(start 386.879846 -71.986902)
		(end 386.879846 -79.526892)
		(width 0.089408)
		(layer "In11.Cu")
		(net "JTAG_PCH_PLD_TCK")
	)
	(segment
		(start 388.63143 -100.34651)
		(end 388.01294 -100.965)
		(width 0.089408)
		(layer "In11.Cu")
		(net "JTAG_PCH_PLD_TCK")
	)
	(segment
		(start 389.128 -97.79)
		(end 389.62203 -98.28403)
		(width 0.089408)
		(layer "In11.Cu")
		(net "JTAG_PCH_PLD_TCK")
	)
	(segment
		(start 388.822184 -97.103184)
		(end 389.128 -97.409)
		(width 0.089408)
		(layer "In11.Cu")
		(net "JTAG_PCH_PLD_TCK")
	)
	(segment
		(start 389.62203 -98.28403)
		(end 389.62203 -98.64217)
		(width 0.089408)
		(layer "In11.Cu")
		(net "JTAG_PCH_PLD_TCK")
	)
	(segment
		(start 388.551674 -90.265504)
		(end 388.551674 -90.981022)
		(width 0.089408)
		(layer "In11.Cu")
		(net "JTAG_PCH_PLD_TCK")
	)
	(segment
		(start 373.694452 -27.320494)
		(end 371.943376 -29.07157)
		(width 0.089408)
		(layer "In11.Cu")
		(net "JTAG_PCH_PLD_TCK")
	)
	(segment
		(start 400.277584 -13.84554)
		(end 381.891032 -13.84554)
		(width 0.089408)
		(layer "In11.Cu")
		(net "JTAG_PCH_PLD_TCK")
	)
	(segment
		(start 371.943376 -29.07157)
		(end 371.943376 -33.58642)
		(width 0.089408)
		(layer "In11.Cu")
		(net "JTAG_PCH_PLD_TCK")
	)
	(segment
		(start 385.936236 -71.043292)
		(end 386.879846 -71.986902)
		(width 0.089408)
		(layer "In11.Cu")
		(net "JTAG_PCH_PLD_TCK")
	)
	(segment
		(start 373.694198 -22.042374)
		(end 373.694198 -27.120088)
		(width 0.089408)
		(layer "In11.Cu")
		(net "JTAG_PCH_PLD_TCK")
	)
	(segment
		(start 389.62203 -98.64217)
		(end 389.128 -99.1362)
		(width 0.089408)
		(layer "In11.Cu")
		(net "JTAG_PCH_PLD_TCK")
	)
	(segment
		(start 426.573442 -14.448282)
		(end 420.50716 -14.448282)
		(width 0.089408)
		(layer "In11.Cu")
		(net "JTAG_PCH_PLD_TCK")
	)
	(segment
		(start 384.918712 -53.896768)
		(end 386.075682 -55.053738)
		(width 0.089408)
		(layer "In11.Cu")
		(net "JTAG_PCH_PLD_TCK")
	)
	(segment
		(start 373.694198 -27.120088)
		(end 373.694452 -27.120342)
		(width 0.089408)
		(layer "In11.Cu")
		(net "JTAG_PCH_PLD_TCK")
	)
	(segment
		(start 388.01294 -100.965)
		(end 387.771386 -100.965)
		(width 0.089408)
		(layer "In11.Cu")
		(net "JTAG_PCH_PLD_TCK")
	)
	(segment
		(start 377.32589 -49.73447)
		(end 377.326144 -49.734216)
		(width 0.089408)
		(layer "In11.Cu")
		(net "JTAG_PCH_PLD_TCK")
	)
	(segment
		(start 439.12409 -12.91971)
		(end 439.123836 -12.919456)
		(width 0.089408)
		(layer "In11.Cu")
		(net "JTAG_PCH_PLD_TCK")
	)
	(segment
		(start 388.178294 -60.42152)
		(end 387.754114 -60.8457)
		(width 0.089408)
		(layer "In11.Cu")
		(net "JTAG_PCH_PLD_TCK")
	)
	(segment
		(start 452.544434 -5.68325)
		(end 446.77584 -11.451844)
		(width 0.089408)
		(layer "In11.Cu")
		(net "JTAG_PCH_PLD_TCK")
	)
	(segment
		(start 388.63143 -100.06457)
		(end 388.63143 -100.34651)
		(width 0.089408)
		(layer "In11.Cu")
		(net "JTAG_PCH_PLD_TCK")
	)
	(segment
		(start 388.14248 -82.828638)
		(end 389.112252 -83.79841)
		(width 0.089408)
		(layer "In11.Cu")
		(net "JTAG_PCH_PLD_TCK")
	)
	(segment
		(start 420.50716 -14.448282)
		(end 418.200078 -12.1412)
		(width 0.089408)
		(layer "In11.Cu")
		(net "JTAG_PCH_PLD_TCK")
	)
	(segment
		(start 446.77584 -11.451844)
		(end 440.792108 -11.451844)
		(width 0.089408)
		(layer "In11.Cu")
		(net "JTAG_PCH_PLD_TCK")
	)
	(segment
		(start 418.200078 -12.1412)
		(end 401.981924 -12.1412)
		(width 0.089408)
		(layer "In11.Cu")
		(net "JTAG_PCH_PLD_TCK")
	)
	(segment
		(start 389.128 -99.568)
		(end 388.63143 -100.06457)
		(width 0.089408)
		(layer "In11.Cu")
		(net "JTAG_PCH_PLD_TCK")
	)
	(segment
		(start 389.112252 -89.704926)
		(end 388.551674 -90.265504)
		(width 0.089408)
		(layer "In11.Cu")
		(net "JTAG_PCH_PLD_TCK")
	)
	(segment
		(start 373.694452 -27.120342)
		(end 373.694452 -27.320494)
		(width 0.089408)
		(layer "In11.Cu")
		(net "JTAG_PCH_PLD_TCK")
	)
	(segment
		(start 377.125738 -49.73447)
		(end 377.32589 -49.73447)
		(width 0.089408)
		(layer "In11.Cu")
		(net "JTAG_PCH_PLD_TCK")
	)
	(segment
		(start 389.128 -99.1362)
		(end 389.128 -99.568)
		(width 0.089408)
		(layer "In11.Cu")
		(net "JTAG_PCH_PLD_TCK")
	)
	(segment
		(start 377.326144 -49.734216)
		(end 379.49505 -49.734216)
		(width 0.089408)
		(layer "In11.Cu")
		(net "JTAG_PCH_PLD_TCK")
	)
	(segment
		(start 428.102268 -12.919456)
		(end 426.573442 -14.448282)
		(width 0.089408)
		(layer "In11.Cu")
		(net "JTAG_PCH_PLD_TCK")
	)
	(segment
		(start 389.12673 -94.813628)
		(end 389.12673 -96.05391)
		(width 0.089408)
		(layer "In11.Cu")
		(net "JTAG_PCH_PLD_TCK")
	)
	(segment
		(start 387.754114 -60.8457)
		(end 387.754114 -62.39383)
		(width 0.089408)
		(layer "In11.Cu")
		(net "JTAG_PCH_PLD_TCK")
	)
	(segment
		(start 381.891032 -13.84554)
		(end 373.694198 -22.042374)
		(width 0.089408)
		(layer "In11.Cu")
		(net "JTAG_PCH_PLD_TCK")
	)
	(segment
		(start 387.285738 -64.473328)
		(end 387.285738 -67.928744)
		(width 0.089408)
		(layer "In11.Cu")
		(net "JTAG_PCH_PLD_TCK")
	)
	(segment
		(start 381.628142 -51.124612)
		(end 384.400298 -53.896768)
		(width 0.089408)
		(layer "In11.Cu")
		(net "JTAG_PCH_PLD_TCK")
	)
	(segment
		(start 401.981924 -12.1412)
		(end 400.277584 -13.84554)
		(width 0.089408)
		(layer "In11.Cu")
		(net "JTAG_PCH_PLD_TCK")
	)
	(segment
		(start 453.86371 -5.68325)
		(end 452.544434 -5.68325)
		(width 0.089408)
		(layer "In11.Cu")
		(net "JTAG_PCH_PLD_TCK")
	)
	(segment
		(start 371.943376 -33.58642)
		(end 372.201694 -33.844738)
		(width 0.089408)
		(layer "In11.Cu")
		(net "JTAG_PCH_PLD_TCK")
	)
	(segment
		(start 440.792108 -11.451844)
		(end 439.324242 -12.91971)
		(width 0.089408)
		(layer "In11.Cu")
		(net "JTAG_PCH_PLD_TCK")
	)
	(segment
		(start 387.754114 -62.39383)
		(end 388.079996 -62.719712)
		(width 0.089408)
		(layer "In11.Cu")
		(net "JTAG_PCH_PLD_TCK")
	)
	(segment
		(start 373.961914 -46.203362)
		(end 373.961914 -46.570646)
		(width 0.089408)
		(layer "In11.Cu")
		(net "JTAG_PCH_PLD_TCK")
	)
	(segment
		(start 379.49505 -49.734216)
		(end 380.885446 -51.124612)
		(width 0.089408)
		(layer "In11.Cu")
		(net "JTAG_PCH_PLD_TCK")
	)
	(segment
		(start 387.285738 -67.928744)
		(end 385.936236 -69.278246)
		(width 0.089408)
		(layer "In11.Cu")
		(net "JTAG_PCH_PLD_TCK")
	)
	(segment
		(start 385.936236 -69.278246)
		(end 385.936236 -71.043292)
		(width 0.089408)
		(layer "In11.Cu")
		(net "JTAG_PCH_PLD_TCK")
	)
	(segment
		(start 388.822184 -96.358456)
		(end 388.822184 -97.103184)
		(width 0.089408)
		(layer "In11.Cu")
		(net "JTAG_PCH_PLD_TCK")
	)
	(segment
		(start 439.324242 -12.91971)
		(end 439.12409 -12.91971)
		(width 0.089408)
		(layer "In11.Cu")
		(net "JTAG_PCH_PLD_TCK")
	)
	(segment
		(start 388.551674 -90.981022)
		(end 387.908546 -91.62415)
		(width 0.089408)
		(layer "In11.Cu")
		(net "JTAG_PCH_PLD_TCK")
	)
	(segment
		(start 372.201694 -33.844738)
		(end 372.201694 -44.443142)
		(width 0.089408)
		(layer "In11.Cu")
		(net "JTAG_PCH_PLD_TCK")
	)
	(segment
		(start 386.879846 -79.526892)
		(end 388.14248 -80.789526)
		(width 0.089408)
		(layer "In11.Cu")
		(net "JTAG_PCH_PLD_TCK")
	)
	(segment
		(start 387.908546 -93.595444)
		(end 389.12673 -94.813628)
		(width 0.089408)
		(layer "In11.Cu")
		(net "JTAG_PCH_PLD_TCK")
	)
	(segment
		(start 372.201694 -44.443142)
		(end 373.961914 -46.203362)
		(width 0.089408)
		(layer "In11.Cu")
		(net "JTAG_PCH_PLD_TCK")
	)
	(segment
		(start 386.075682 -56.99887)
		(end 388.178294 -59.101482)
		(width 0.089408)
		(layer "In11.Cu")
		(net "JTAG_PCH_PLD_TCK")
	)
	(segment
		(start 386.075682 -55.053738)
		(end 386.075682 -56.99887)
		(width 0.089408)
		(layer "In11.Cu")
		(net "JTAG_PCH_PLD_TCK")
	)
	(segment
		(start 384.400298 -53.896768)
		(end 384.918712 -53.896768)
		(width 0.089408)
		(layer "In11.Cu")
		(net "JTAG_PCH_PLD_TCK")
	)
	(segment
		(start 439.123836 -12.919456)
		(end 428.102268 -12.919456)
		(width 0.089408)
		(layer "In11.Cu")
		(net "JTAG_PCH_PLD_TCK")
	)
	(segment
		(start 388.079996 -63.67907)
		(end 387.285738 -64.473328)
		(width 0.089408)
		(layer "In11.Cu")
		(net "JTAG_PCH_PLD_TCK")
	)
	(segment
		(start 409.48991 -42.534586)
		(end 409.090114 -42.13479)
		(width 0.089408)
		(layer "F.Cu")
		(net "IRQ_DIMM_SAVE_LVT3_N")
	)
	(segment
		(start 409.490164 -42.534586)
		(end 409.48991 -42.534586)
		(width 0.089408)
		(layer "F.Cu")
		(net "IRQ_DIMM_SAVE_LVT3_N")
	)
	(segment
		(start 410.7688 -99.274884)
		(end 409.816808 -98.322892)
		(width 0.10795)
		(layer "F.Cu")
		(net "IRQ_DIMM_SAVE_LVT3_N")
	)
	(segment
		(start 410.69006 -100.60432)
		(end 410.69006 -99.90074)
		(width 0.10795)
		(layer "F.Cu")
		(net "IRQ_DIMM_SAVE_LVT3_N")
	)
	(segment
		(start 410.7688 -99.3394)
		(end 410.7688 -99.274884)
		(width 0.10795)
		(layer "F.Cu")
		(net "IRQ_DIMM_SAVE_LVT3_N")
	)
	(segment
		(start 410.7688 -99.822)
		(end 410.7688 -99.3394)
		(width 0.10795)
		(layer "F.Cu")
		(net "IRQ_DIMM_SAVE_LVT3_N")
	)
	(segment
		(start 410.69006 -99.90074)
		(end 410.7688 -99.822)
		(width 0.10795)
		(layer "F.Cu")
		(net "IRQ_DIMM_SAVE_LVT3_N")
	)
	(via
		(at 382.133094 -69.704204)
		(size 0.508)
		(drill 0.254)
		(layers "F.Cu" "B.Cu")
		(net "IRQ_DIMM_SAVE_LVT3_N")
	)
	(via
		(at 409.816808 -98.322892)
		(size 0.508)
		(drill 0.254)
		(layers "F.Cu" "B.Cu")
		(net "IRQ_DIMM_SAVE_LVT3_N")
	)
	(via
		(at 409.090114 -42.13479)
		(size 0.4572)
		(drill 0.2032)
		(layers "F.Cu" "B.Cu")
		(net "IRQ_DIMM_SAVE_LVT3_N")
	)
	(via
		(at 410.844492 -69.451982)
		(size 0.508)
		(drill 0.254)
		(layers "F.Cu" "B.Cu")
		(net "IRQ_DIMM_SAVE_LVT3_N")
	)
	(via
		(at 397.99514 -80.039718)
		(size 0.508)
		(drill 0.254)
		(layers "F.Cu" "B.Cu")
		(net "IRQ_DIMM_SAVE_LVT3_N")
	)
	(via
		(at 372.62816 -66.130678)
		(size 0.508)
		(drill 0.254)
		(layers "F.Cu" "B.Cu")
		(net "IRQ_DIMM_SAVE_LVT3_N")
	)
	(via
		(at 315.962792 -39.348664)
		(size 0.508)
		(drill 0.254)
		(layers "F.Cu" "B.Cu")
		(net "IRQ_DIMM_SAVE_LVT3_N")
	)
	(via
		(at 399.1483 -91.3511)
		(size 0.508)
		(drill 0.254)
		(layers "F.Cu" "B.Cu")
		(net "IRQ_DIMM_SAVE_LVT3_N")
	)
	(via
		(at 313.73191 -32.94634)
		(size 0.6604)
		(drill 0.3302)
		(layers "F.Cu" "B.Cu")
		(net "IRQ_DIMM_SAVE_LVT3_N")
	)
	(segment
		(start 313.73191 -33.20669)
		(end 313.424062 -33.514538)
		(width 0.10795)
		(layer "B.Cu")
		(net "IRQ_DIMM_SAVE_LVT3_N")
	)
	(segment
		(start 313.424062 -29.505148)
		(end 313.424062 -32.271462)
		(width 0.10795)
		(layer "B.Cu")
		(net "IRQ_DIMM_SAVE_LVT3_N")
	)
	(segment
		(start 310.029606 -26.520648)
		(end 313.22137 -26.520648)
		(width 0.10795)
		(layer "B.Cu")
		(net "IRQ_DIMM_SAVE_LVT3_N")
	)
	(segment
		(start 372.62816 -65.355216)
		(end 372.62816 -66.130678)
		(width 0.10795)
		(layer "B.Cu")
		(net "IRQ_DIMM_SAVE_LVT3_N")
	)
	(segment
		(start 315.174122 -38.559994)
		(end 315.962792 -39.348664)
		(width 0.10795)
		(layer "B.Cu")
		(net "IRQ_DIMM_SAVE_LVT3_N")
	)
	(segment
		(start 309.7022 -26.848054)
		(end 310.029606 -26.520648)
		(width 0.10795)
		(layer "B.Cu")
		(net "IRQ_DIMM_SAVE_LVT3_N")
	)
	(segment
		(start 380.985776 -64.07277)
		(end 380.553214 -64.07277)
		(width 0.10795)
		(layer "B.Cu")
		(net "IRQ_DIMM_SAVE_LVT3_N")
	)
	(segment
		(start 375.108216 -63.064898)
		(end 374.958864 -63.21425)
		(width 0.10795)
		(layer "B.Cu")
		(net "IRQ_DIMM_SAVE_LVT3_N")
	)
	(segment
		(start 381.5588 -69.12991)
		(end 381.5588 -64.645794)
		(width 0.10795)
		(layer "B.Cu")
		(net "IRQ_DIMM_SAVE_LVT3_N")
	)
	(segment
		(start 313.807348 -27.106626)
		(end 314.488576 -27.106626)
		(width 0.10795)
		(layer "B.Cu")
		(net "IRQ_DIMM_SAVE_LVT3_N")
	)
	(segment
		(start 376.724672 -63.416434)
		(end 376.281442 -63.416434)
		(width 0.10795)
		(layer "B.Cu")
		(net "IRQ_DIMM_SAVE_LVT3_N")
	)
	(segment
		(start 376.841258 -63.299848)
		(end 376.724672 -63.416434)
		(width 0.10795)
		(layer "B.Cu")
		(net "IRQ_DIMM_SAVE_LVT3_N")
	)
	(segment
		(start 374.958864 -63.21425)
		(end 374.095264 -63.21425)
		(width 0.10795)
		(layer "B.Cu")
		(net "IRQ_DIMM_SAVE_LVT3_N")
	)
	(segment
		(start 313.424062 -32.271462)
		(end 313.73191 -32.57931)
		(width 0.10795)
		(layer "B.Cu")
		(net "IRQ_DIMM_SAVE_LVT3_N")
	)
	(segment
		(start 314.488576 -27.106626)
		(end 314.760102 -27.378152)
		(width 0.10795)
		(layer "B.Cu")
		(net "IRQ_DIMM_SAVE_LVT3_N")
	)
	(segment
		(start 372.563898 -64.475106)
		(end 372.7196 -64.630808)
		(width 0.10795)
		(layer "B.Cu")
		(net "IRQ_DIMM_SAVE_LVT3_N")
	)
	(segment
		(start 309.7022 -27.450796)
		(end 309.7022 -26.848054)
		(width 0.10795)
		(layer "B.Cu")
		(net "IRQ_DIMM_SAVE_LVT3_N")
	)
	(segment
		(start 313.73191 -32.94634)
		(end 313.73191 -33.20669)
		(width 0.10795)
		(layer "B.Cu")
		(net "IRQ_DIMM_SAVE_LVT3_N")
	)
	(segment
		(start 313.424062 -29.069792)
		(end 314.760102 -27.733752)
		(width 0.10795)
		(layer "B.Cu")
		(net "IRQ_DIMM_SAVE_LVT3_N")
	)
	(segment
		(start 313.424062 -36.047172)
		(end 315.174122 -37.797232)
		(width 0.10795)
		(layer "B.Cu")
		(net "IRQ_DIMM_SAVE_LVT3_N")
	)
	(segment
		(start 313.424062 -29.505148)
		(end 313.424062 -29.069792)
		(width 0.10795)
		(layer "B.Cu")
		(net "IRQ_DIMM_SAVE_LVT3_N")
	)
	(segment
		(start 375.929906 -63.064898)
		(end 375.108216 -63.064898)
		(width 0.10795)
		(layer "B.Cu")
		(net "IRQ_DIMM_SAVE_LVT3_N")
	)
	(segment
		(start 382.133094 -69.704204)
		(end 381.5588 -69.12991)
		(width 0.10795)
		(layer "B.Cu")
		(net "IRQ_DIMM_SAVE_LVT3_N")
	)
	(segment
		(start 376.281442 -63.416434)
		(end 375.929906 -63.064898)
		(width 0.10795)
		(layer "B.Cu")
		(net "IRQ_DIMM_SAVE_LVT3_N")
	)
	(segment
		(start 377.563888 -63.4238)
		(end 377.439936 -63.299848)
		(width 0.10795)
		(layer "B.Cu")
		(net "IRQ_DIMM_SAVE_LVT3_N")
	)
	(segment
		(start 379.904244 -63.4238)
		(end 377.563888 -63.4238)
		(width 0.10795)
		(layer "B.Cu")
		(net "IRQ_DIMM_SAVE_LVT3_N")
	)
	(segment
		(start 313.22137 -26.520648)
		(end 313.807348 -27.106626)
		(width 0.10795)
		(layer "B.Cu")
		(net "IRQ_DIMM_SAVE_LVT3_N")
	)
	(segment
		(start 372.983252 -63.742062)
		(end 372.620032 -63.742062)
		(width 0.10795)
		(layer "B.Cu")
		(net "IRQ_DIMM_SAVE_LVT3_N")
	)
	(segment
		(start 373.003318 -63.762128)
		(end 372.983252 -63.742062)
		(width 0.10795)
		(layer "B.Cu")
		(net "IRQ_DIMM_SAVE_LVT3_N")
	)
	(segment
		(start 372.7196 -65.263776)
		(end 372.62816 -65.355216)
		(width 0.10795)
		(layer "B.Cu")
		(net "IRQ_DIMM_SAVE_LVT3_N")
	)
	(segment
		(start 372.563898 -63.798196)
		(end 372.563898 -64.475106)
		(width 0.10795)
		(layer "B.Cu")
		(net "IRQ_DIMM_SAVE_LVT3_N")
	)
	(segment
		(start 373.547386 -63.762128)
		(end 373.003318 -63.762128)
		(width 0.10795)
		(layer "B.Cu")
		(net "IRQ_DIMM_SAVE_LVT3_N")
	)
	(segment
		(start 377.439936 -63.299848)
		(end 376.841258 -63.299848)
		(width 0.10795)
		(layer "B.Cu")
		(net "IRQ_DIMM_SAVE_LVT3_N")
	)
	(segment
		(start 372.620032 -63.742062)
		(end 372.563898 -63.798196)
		(width 0.10795)
		(layer "B.Cu")
		(net "IRQ_DIMM_SAVE_LVT3_N")
	)
	(segment
		(start 313.424062 -33.514538)
		(end 313.424062 -36.047172)
		(width 0.10795)
		(layer "B.Cu")
		(net "IRQ_DIMM_SAVE_LVT3_N")
	)
	(segment
		(start 372.7196 -64.630808)
		(end 372.7196 -65.263776)
		(width 0.10795)
		(layer "B.Cu")
		(net "IRQ_DIMM_SAVE_LVT3_N")
	)
	(segment
		(start 380.553214 -64.07277)
		(end 379.904244 -63.4238)
		(width 0.10795)
		(layer "B.Cu")
		(net "IRQ_DIMM_SAVE_LVT3_N")
	)
	(segment
		(start 315.174122 -37.797232)
		(end 315.174122 -38.559994)
		(width 0.10795)
		(layer "B.Cu")
		(net "IRQ_DIMM_SAVE_LVT3_N")
	)
	(segment
		(start 381.5588 -64.645794)
		(end 380.985776 -64.07277)
		(width 0.10795)
		(layer "B.Cu")
		(net "IRQ_DIMM_SAVE_LVT3_N")
	)
	(segment
		(start 314.760102 -27.378152)
		(end 314.760102 -27.733752)
		(width 0.10795)
		(layer "B.Cu")
		(net "IRQ_DIMM_SAVE_LVT3_N")
	)
	(segment
		(start 310.307228 -28.055824)
		(end 309.7022 -27.450796)
		(width 0.10795)
		(layer "B.Cu")
		(net "IRQ_DIMM_SAVE_LVT3_N")
	)
	(segment
		(start 374.095264 -63.21425)
		(end 373.547386 -63.762128)
		(width 0.10795)
		(layer "B.Cu")
		(net "IRQ_DIMM_SAVE_LVT3_N")
	)
	(segment
		(start 313.73191 -32.57931)
		(end 313.73191 -32.94634)
		(width 0.10795)
		(layer "B.Cu")
		(net "IRQ_DIMM_SAVE_LVT3_N")
	)
	(segment
		(start 399.19148 -85.31352)
		(end 399.19148 -83.57616)
		(width 0.089408)
		(layer "In2.Cu")
		(net "IRQ_DIMM_SAVE_LVT3_N")
	)
	(segment
		(start 397.9291 -80.8482)
		(end 397.99514 -80.78216)
		(width 0.089408)
		(layer "In2.Cu")
		(net "IRQ_DIMM_SAVE_LVT3_N")
	)
	(segment
		(start 398.41043 -90.61323)
		(end 398.41043 -86.09457)
		(width 0.089408)
		(layer "In2.Cu")
		(net "IRQ_DIMM_SAVE_LVT3_N")
	)
	(segment
		(start 399.19148 -83.57616)
		(end 397.9291 -82.31378)
		(width 0.089408)
		(layer "In2.Cu")
		(net "IRQ_DIMM_SAVE_LVT3_N")
	)
	(segment
		(start 409.932632 -88.670892)
		(end 409.065222 -87.803482)
		(width 0.089408)
		(layer "In2.Cu")
		(net "IRQ_DIMM_SAVE_LVT3_N")
	)
	(segment
		(start 398.41043 -86.09457)
		(end 399.19148 -85.31352)
		(width 0.089408)
		(layer "In2.Cu")
		(net "IRQ_DIMM_SAVE_LVT3_N")
	)
	(segment
		(start 405.55926 -74.737214)
		(end 410.844492 -69.451982)
		(width 0.089408)
		(layer "In2.Cu")
		(net "IRQ_DIMM_SAVE_LVT3_N")
	)
	(segment
		(start 409.932632 -98.207068)
		(end 409.932632 -88.670892)
		(width 0.089408)
		(layer "In2.Cu")
		(net "IRQ_DIMM_SAVE_LVT3_N")
	)
	(segment
		(start 405.445976 -78.891384)
		(end 404.96744 -78.412848)
		(width 0.089408)
		(layer "In2.Cu")
		(net "IRQ_DIMM_SAVE_LVT3_N")
	)
	(segment
		(start 405.445722 -79.648558)
		(end 405.445976 -79.648304)
		(width 0.089408)
		(layer "In2.Cu")
		(net "IRQ_DIMM_SAVE_LVT3_N")
	)
	(segment
		(start 409.816808 -98.322892)
		(end 409.932632 -98.207068)
		(width 0.089408)
		(layer "In2.Cu")
		(net "IRQ_DIMM_SAVE_LVT3_N")
	)
	(segment
		(start 409.065222 -87.803482)
		(end 408.508454 -87.803482)
		(width 0.089408)
		(layer "In2.Cu")
		(net "IRQ_DIMM_SAVE_LVT3_N")
	)
	(segment
		(start 399.1483 -91.3511)
		(end 398.41043 -90.61323)
		(width 0.089408)
		(layer "In2.Cu")
		(net "IRQ_DIMM_SAVE_LVT3_N")
	)
	(segment
		(start 405.445976 -79.648304)
		(end 405.445976 -78.891384)
		(width 0.089408)
		(layer "In2.Cu")
		(net "IRQ_DIMM_SAVE_LVT3_N")
	)
	(segment
		(start 408.508454 -87.803482)
		(end 407.988516 -87.283544)
		(width 0.089408)
		(layer "In2.Cu")
		(net "IRQ_DIMM_SAVE_LVT3_N")
	)
	(segment
		(start 404.96744 -78.412848)
		(end 404.96744 -75.354688)
		(width 0.089408)
		(layer "In2.Cu")
		(net "IRQ_DIMM_SAVE_LVT3_N")
	)
	(segment
		(start 397.9291 -82.31378)
		(end 397.9291 -80.8482)
		(width 0.089408)
		(layer "In2.Cu")
		(net "IRQ_DIMM_SAVE_LVT3_N")
	)
	(segment
		(start 397.99514 -80.78216)
		(end 397.99514 -80.039718)
		(width 0.089408)
		(layer "In2.Cu")
		(net "IRQ_DIMM_SAVE_LVT3_N")
	)
	(segment
		(start 405.55926 -74.762868)
		(end 405.55926 -74.737214)
		(width 0.089408)
		(layer "In2.Cu")
		(net "IRQ_DIMM_SAVE_LVT3_N")
	)
	(segment
		(start 404.96744 -75.354688)
		(end 405.55926 -74.762868)
		(width 0.089408)
		(layer "In2.Cu")
		(net "IRQ_DIMM_SAVE_LVT3_N")
	)
	(segment
		(start 407.988516 -87.283544)
		(end 407.988516 -82.666332)
		(width 0.089408)
		(layer "In2.Cu")
		(net "IRQ_DIMM_SAVE_LVT3_N")
	)
	(segment
		(start 407.988516 -82.666332)
		(end 405.445722 -80.123538)
		(width 0.089408)
		(layer "In2.Cu")
		(net "IRQ_DIMM_SAVE_LVT3_N")
	)
	(segment
		(start 405.445722 -80.123538)
		(end 405.445722 -79.648558)
		(width 0.089408)
		(layer "In2.Cu")
		(net "IRQ_DIMM_SAVE_LVT3_N")
	)
	(segment
		(start 414.4518 -99.0346)
		(end 413.7406 -99.0346)
		(width 0.089408)
		(layer "In4.Cu")
		(net "IRQ_DIMM_SAVE_LVT3_N")
	)
	(segment
		(start 412.4452 -97.7392)
		(end 412.4452 -96.40824)
		(width 0.089408)
		(layer "In4.Cu")
		(net "IRQ_DIMM_SAVE_LVT3_N")
	)
	(segment
		(start 404.12416 -93.4212)
		(end 400.94916 -93.4212)
		(width 0.089408)
		(layer "In4.Cu")
		(net "IRQ_DIMM_SAVE_LVT3_N")
	)
	(segment
		(start 413.7406 -99.0346)
		(end 412.4452 -97.7392)
		(width 0.089408)
		(layer "In4.Cu")
		(net "IRQ_DIMM_SAVE_LVT3_N")
	)
	(segment
		(start 382.529334 -70.100444)
		(end 407.676096 -70.100444)
		(width 0.089408)
		(layer "In4.Cu")
		(net "IRQ_DIMM_SAVE_LVT3_N")
	)
	(segment
		(start 399.51406 -91.71686)
		(end 399.1483 -91.3511)
		(width 0.089408)
		(layer "In4.Cu")
		(net "IRQ_DIMM_SAVE_LVT3_N")
	)
	(segment
		(start 400.94916 -93.4212)
		(end 399.51406 -91.9861)
		(width 0.089408)
		(layer "In4.Cu")
		(net "IRQ_DIMM_SAVE_LVT3_N")
	)
	(segment
		(start 414.68802 -99.27082)
		(end 414.4518 -99.0346)
		(width 0.089408)
		(layer "In4.Cu")
		(net "IRQ_DIMM_SAVE_LVT3_N")
	)
	(segment
		(start 406.13076 -92.2401)
		(end 405.30526 -92.2401)
		(width 0.089408)
		(layer "In4.Cu")
		(net "IRQ_DIMM_SAVE_LVT3_N")
	)
	(segment
		(start 412.4452 -96.40824)
		(end 409.885642 -93.848682)
		(width 0.089408)
		(layer "In4.Cu")
		(net "IRQ_DIMM_SAVE_LVT3_N")
	)
	(segment
		(start 405.30526 -92.2401)
		(end 404.12416 -93.4212)
		(width 0.089408)
		(layer "In4.Cu")
		(net "IRQ_DIMM_SAVE_LVT3_N")
	)
	(segment
		(start 409.885642 -93.848682)
		(end 407.739342 -93.848682)
		(width 0.089408)
		(layer "In4.Cu")
		(net "IRQ_DIMM_SAVE_LVT3_N")
	)
	(segment
		(start 407.676096 -70.100444)
		(end 408.324558 -69.451982)
		(width 0.089408)
		(layer "In4.Cu")
		(net "IRQ_DIMM_SAVE_LVT3_N")
	)
	(segment
		(start 382.133094 -69.704204)
		(end 382.529334 -70.100444)
		(width 0.089408)
		(layer "In4.Cu")
		(net "IRQ_DIMM_SAVE_LVT3_N")
	)
	(segment
		(start 414.68802 -99.71278)
		(end 414.68802 -99.27082)
		(width 0.089408)
		(layer "In4.Cu")
		(net "IRQ_DIMM_SAVE_LVT3_N")
	)
	(segment
		(start 407.739342 -93.848682)
		(end 406.13076 -92.2401)
		(width 0.089408)
		(layer "In4.Cu")
		(net "IRQ_DIMM_SAVE_LVT3_N")
	)
	(segment
		(start 409.816808 -98.322892)
		(end 411.123892 -98.322892)
		(width 0.089408)
		(layer "In4.Cu")
		(net "IRQ_DIMM_SAVE_LVT3_N")
	)
	(segment
		(start 412.7246 -99.9236)
		(end 414.4772 -99.9236)
		(width 0.089408)
		(layer "In4.Cu")
		(net "IRQ_DIMM_SAVE_LVT3_N")
	)
	(segment
		(start 414.4772 -99.9236)
		(end 414.68802 -99.71278)
		(width 0.089408)
		(layer "In4.Cu")
		(net "IRQ_DIMM_SAVE_LVT3_N")
	)
	(segment
		(start 408.324558 -69.451982)
		(end 410.844492 -69.451982)
		(width 0.089408)
		(layer "In4.Cu")
		(net "IRQ_DIMM_SAVE_LVT3_N")
	)
	(segment
		(start 411.123892 -98.322892)
		(end 412.7246 -99.9236)
		(width 0.089408)
		(layer "In4.Cu")
		(net "IRQ_DIMM_SAVE_LVT3_N")
	)
	(segment
		(start 399.51406 -91.9861)
		(end 399.51406 -91.71686)
		(width 0.089408)
		(layer "In4.Cu")
		(net "IRQ_DIMM_SAVE_LVT3_N")
	)
	(segment
		(start 397.97482 -80.019398)
		(end 397.97482 -78.396592)
		(width 0.089408)
		(layer "In9.Cu")
		(net "IRQ_DIMM_SAVE_LVT3_N")
	)
	(segment
		(start 401.834096 -52.869592)
		(end 401.834096 -50.285904)
		(width 0.089408)
		(layer "In9.Cu")
		(net "IRQ_DIMM_SAVE_LVT3_N")
	)
	(segment
		(start 404.695406 -65.840356)
		(end 404.695406 -65.60185)
		(width 0.089408)
		(layer "In9.Cu")
		(net "IRQ_DIMM_SAVE_LVT3_N")
	)
	(segment
		(start 399.04416 -76.85024)
		(end 399.81632 -76.07808)
		(width 0.089408)
		(layer "In9.Cu")
		(net "IRQ_DIMM_SAVE_LVT3_N")
	)
	(segment
		(start 404.699216 -66.197226)
		(end 404.699216 -65.844166)
		(width 0.089408)
		(layer "In9.Cu")
		(net "IRQ_DIMM_SAVE_LVT3_N")
	)
	(segment
		(start 404.699216 -65.597532)
		(end 404.699216 -65.058544)
		(width 0.089408)
		(layer "In9.Cu")
		(net "IRQ_DIMM_SAVE_LVT3_N")
	)
	(segment
		(start 404.699216 -65.058544)
		(end 404.69947 -65.05829)
		(width 0.089408)
		(layer "In9.Cu")
		(net "IRQ_DIMM_SAVE_LVT3_N")
	)
	(segment
		(start 403.50186 -57.571132)
		(end 401.903692 -55.972964)
		(width 0.089408)
		(layer "In9.Cu")
		(net "IRQ_DIMM_SAVE_LVT3_N")
	)
	(segment
		(start 399.04416 -77.343)
		(end 399.04416 -76.85024)
		(width 0.089408)
		(layer "In9.Cu")
		(net "IRQ_DIMM_SAVE_LVT3_N")
	)
	(segment
		(start 402.837142 -48.010064)
		(end 404.527766 -46.31944)
		(width 0.089408)
		(layer "In9.Cu")
		(net "IRQ_DIMM_SAVE_LVT3_N")
	)
	(segment
		(start 404.527766 -46.31944)
		(end 404.527766 -45.454062)
		(width 0.089408)
		(layer "In9.Cu")
		(net "IRQ_DIMM_SAVE_LVT3_N")
	)
	(segment
		(start 399.81632 -73.511918)
		(end 400.149822 -73.178416)
		(width 0.089408)
		(layer "In9.Cu")
		(net "IRQ_DIMM_SAVE_LVT3_N")
	)
	(segment
		(start 397.99514 -80.039718)
		(end 397.97482 -80.019398)
		(width 0.089408)
		(layer "In9.Cu")
		(net "IRQ_DIMM_SAVE_LVT3_N")
	)
	(segment
		(start 401.903692 -55.972964)
		(end 401.903692 -52.939188)
		(width 0.089408)
		(layer "In9.Cu")
		(net "IRQ_DIMM_SAVE_LVT3_N")
	)
	(segment
		(start 404.20544 -63.913766)
		(end 403.50186 -63.210186)
		(width 0.089408)
		(layer "In9.Cu")
		(net "IRQ_DIMM_SAVE_LVT3_N")
	)
	(segment
		(start 407.6954 -43.67276)
		(end 409.090114 -42.278046)
		(width 0.089408)
		(layer "In9.Cu")
		(net "IRQ_DIMM_SAVE_LVT3_N")
	)
	(segment
		(start 401.834096 -50.285904)
		(end 402.837142 -49.282858)
		(width 0.089408)
		(layer "In9.Cu")
		(net "IRQ_DIMM_SAVE_LVT3_N")
	)
	(segment
		(start 404.20544 -64.554608)
		(end 404.20544 -63.913766)
		(width 0.089408)
		(layer "In9.Cu")
		(net "IRQ_DIMM_SAVE_LVT3_N")
	)
	(segment
		(start 400.149822 -70.746874)
		(end 404.695406 -66.20129)
		(width 0.089408)
		(layer "In9.Cu")
		(net "IRQ_DIMM_SAVE_LVT3_N")
	)
	(segment
		(start 404.69947 -65.048638)
		(end 404.20544 -64.554608)
		(width 0.089408)
		(layer "In9.Cu")
		(net "IRQ_DIMM_SAVE_LVT3_N")
	)
	(segment
		(start 403.50186 -63.210186)
		(end 403.50186 -57.571132)
		(width 0.089408)
		(layer "In9.Cu")
		(net "IRQ_DIMM_SAVE_LVT3_N")
	)
	(segment
		(start 406.901904 -44.702984)
		(end 407.6954 -43.909488)
		(width 0.089408)
		(layer "In9.Cu")
		(net "IRQ_DIMM_SAVE_LVT3_N")
	)
	(segment
		(start 401.903692 -52.939188)
		(end 401.834096 -52.869592)
		(width 0.089408)
		(layer "In9.Cu")
		(net "IRQ_DIMM_SAVE_LVT3_N")
	)
	(segment
		(start 404.695406 -66.20129)
		(end 404.695406 -66.201036)
		(width 0.089408)
		(layer "In9.Cu")
		(net "IRQ_DIMM_SAVE_LVT3_N")
	)
	(segment
		(start 400.149822 -73.178416)
		(end 400.149822 -70.746874)
		(width 0.089408)
		(layer "In9.Cu")
		(net "IRQ_DIMM_SAVE_LVT3_N")
	)
	(segment
		(start 404.695406 -66.201036)
		(end 404.699216 -66.197226)
		(width 0.089408)
		(layer "In9.Cu")
		(net "IRQ_DIMM_SAVE_LVT3_N")
	)
	(segment
		(start 404.69947 -65.597786)
		(end 404.699216 -65.597532)
		(width 0.089408)
		(layer "In9.Cu")
		(net "IRQ_DIMM_SAVE_LVT3_N")
	)
	(segment
		(start 407.6954 -43.909488)
		(end 407.6954 -43.67276)
		(width 0.089408)
		(layer "In9.Cu")
		(net "IRQ_DIMM_SAVE_LVT3_N")
	)
	(segment
		(start 398.590008 -77.797152)
		(end 399.04416 -77.343)
		(width 0.089408)
		(layer "In9.Cu")
		(net "IRQ_DIMM_SAVE_LVT3_N")
	)
	(segment
		(start 409.090114 -42.278046)
		(end 409.090114 -42.13479)
		(width 0.089408)
		(layer "In9.Cu")
		(net "IRQ_DIMM_SAVE_LVT3_N")
	)
	(segment
		(start 404.527766 -45.454062)
		(end 405.278844 -44.702984)
		(width 0.089408)
		(layer "In9.Cu")
		(net "IRQ_DIMM_SAVE_LVT3_N")
	)
	(segment
		(start 405.278844 -44.702984)
		(end 406.901904 -44.702984)
		(width 0.089408)
		(layer "In9.Cu")
		(net "IRQ_DIMM_SAVE_LVT3_N")
	)
	(segment
		(start 402.837142 -49.282858)
		(end 402.837142 -48.010064)
		(width 0.089408)
		(layer "In9.Cu")
		(net "IRQ_DIMM_SAVE_LVT3_N")
	)
	(segment
		(start 404.69947 -65.05829)
		(end 404.69947 -65.048638)
		(width 0.089408)
		(layer "In9.Cu")
		(net "IRQ_DIMM_SAVE_LVT3_N")
	)
	(segment
		(start 398.57426 -77.797152)
		(end 398.590008 -77.797152)
		(width 0.089408)
		(layer "In9.Cu")
		(net "IRQ_DIMM_SAVE_LVT3_N")
	)
	(segment
		(start 399.81632 -76.07808)
		(end 399.81632 -73.511918)
		(width 0.089408)
		(layer "In9.Cu")
		(net "IRQ_DIMM_SAVE_LVT3_N")
	)
	(segment
		(start 404.699216 -65.844166)
		(end 404.695406 -65.840356)
		(width 0.089408)
		(layer "In9.Cu")
		(net "IRQ_DIMM_SAVE_LVT3_N")
	)
	(segment
		(start 397.97482 -78.396592)
		(end 398.57426 -77.797152)
		(width 0.089408)
		(layer "In9.Cu")
		(net "IRQ_DIMM_SAVE_LVT3_N")
	)
	(segment
		(start 404.695406 -65.60185)
		(end 404.69947 -65.597786)
		(width 0.089408)
		(layer "In9.Cu")
		(net "IRQ_DIMM_SAVE_LVT3_N")
	)
	(segment
		(start 315.851794 -42.540682)
		(end 314.91047 -43.482006)
		(width 0.089408)
		(layer "In11.Cu")
		(net "IRQ_DIMM_SAVE_LVT3_N")
	)
	(segment
		(start 326.154034 -52.54117)
		(end 339.10397 -52.54117)
		(width 0.089408)
		(layer "In11.Cu")
		(net "IRQ_DIMM_SAVE_LVT3_N")
	)
	(segment
		(start 349.979234 -53.008022)
		(end 355.029516 -53.008022)
		(width 0.089408)
		(layer "In11.Cu")
		(net "IRQ_DIMM_SAVE_LVT3_N")
	)
	(segment
		(start 315.851794 -39.459662)
		(end 315.851794 -42.540682)
		(width 0.089408)
		(layer "In11.Cu")
		(net "IRQ_DIMM_SAVE_LVT3_N")
	)
	(segment
		(start 361.048046 -55.804054)
		(end 361.944412 -55.804054)
		(width 0.089408)
		(layer "In11.Cu")
		(net "IRQ_DIMM_SAVE_LVT3_N")
	)
	(segment
		(start 370.122704 -63.994284)
		(end 370.122704 -64.893698)
		(width 0.089408)
		(layer "In11.Cu")
		(net "IRQ_DIMM_SAVE_LVT3_N")
	)
	(segment
		(start 369.441984 -61.68263)
		(end 369.441984 -63.313564)
		(width 0.089408)
		(layer "In11.Cu")
		(net "IRQ_DIMM_SAVE_LVT3_N")
	)
	(segment
		(start 355.905562 -53.884068)
		(end 359.12806 -53.884068)
		(width 0.089408)
		(layer "In11.Cu")
		(net "IRQ_DIMM_SAVE_LVT3_N")
	)
	(segment
		(start 363.62767 -57.487312)
		(end 365.246666 -57.487312)
		(width 0.089408)
		(layer "In11.Cu")
		(net "IRQ_DIMM_SAVE_LVT3_N")
	)
	(segment
		(start 355.029516 -53.008022)
		(end 355.905562 -53.884068)
		(width 0.089408)
		(layer "In11.Cu")
		(net "IRQ_DIMM_SAVE_LVT3_N")
	)
	(segment
		(start 359.12806 -53.884068)
		(end 361.048046 -55.804054)
		(width 0.089408)
		(layer "In11.Cu")
		(net "IRQ_DIMM_SAVE_LVT3_N")
	)
	(segment
		(start 369.441984 -63.313564)
		(end 370.122704 -63.994284)
		(width 0.089408)
		(layer "In11.Cu")
		(net "IRQ_DIMM_SAVE_LVT3_N")
	)
	(segment
		(start 339.424264 -53.618892)
		(end 340.492588 -54.687216)
		(width 0.089408)
		(layer "In11.Cu")
		(net "IRQ_DIMM_SAVE_LVT3_N")
	)
	(segment
		(start 317.428372 -47.238158)
		(end 320.851022 -47.238158)
		(width 0.089408)
		(layer "In11.Cu")
		(net "IRQ_DIMM_SAVE_LVT3_N")
	)
	(segment
		(start 314.91047 -44.720256)
		(end 317.428372 -47.238158)
		(width 0.089408)
		(layer "In11.Cu")
		(net "IRQ_DIMM_SAVE_LVT3_N")
	)
	(segment
		(start 340.492588 -54.687216)
		(end 348.30004 -54.687216)
		(width 0.089408)
		(layer "In11.Cu")
		(net "IRQ_DIMM_SAVE_LVT3_N")
	)
	(segment
		(start 365.246666 -57.487312)
		(end 369.441984 -61.68263)
		(width 0.089408)
		(layer "In11.Cu")
		(net "IRQ_DIMM_SAVE_LVT3_N")
	)
	(segment
		(start 361.944412 -55.804054)
		(end 363.62767 -57.487312)
		(width 0.089408)
		(layer "In11.Cu")
		(net "IRQ_DIMM_SAVE_LVT3_N")
	)
	(segment
		(start 339.10397 -52.54117)
		(end 339.424264 -52.861464)
		(width 0.089408)
		(layer "In11.Cu")
		(net "IRQ_DIMM_SAVE_LVT3_N")
	)
	(segment
		(start 315.962792 -39.348664)
		(end 315.851794 -39.459662)
		(width 0.089408)
		(layer "In11.Cu")
		(net "IRQ_DIMM_SAVE_LVT3_N")
	)
	(segment
		(start 320.851022 -47.238158)
		(end 326.154034 -52.54117)
		(width 0.089408)
		(layer "In11.Cu")
		(net "IRQ_DIMM_SAVE_LVT3_N")
	)
	(segment
		(start 348.30004 -54.687216)
		(end 349.979234 -53.008022)
		(width 0.089408)
		(layer "In11.Cu")
		(net "IRQ_DIMM_SAVE_LVT3_N")
	)
	(segment
		(start 370.122704 -64.893698)
		(end 371.359684 -66.130678)
		(width 0.089408)
		(layer "In11.Cu")
		(net "IRQ_DIMM_SAVE_LVT3_N")
	)
	(segment
		(start 371.359684 -66.130678)
		(end 372.62816 -66.130678)
		(width 0.089408)
		(layer "In11.Cu")
		(net "IRQ_DIMM_SAVE_LVT3_N")
	)
	(segment
		(start 339.424264 -52.861464)
		(end 339.424264 -53.618892)
		(width 0.089408)
		(layer "In11.Cu")
		(net "IRQ_DIMM_SAVE_LVT3_N")
	)
	(segment
		(start 314.91047 -43.482006)
		(end 314.91047 -44.720256)
		(width 0.089408)
		(layer "In11.Cu")
		(net "IRQ_DIMM_SAVE_LVT3_N")
	)
	(via
		(at 310.2102 -27.0764)
		(size 0.6604)
		(drill 0.3302)
		(layers "F.Cu" "B.Cu")
		(net "IRQ_DIMM_SAVE_LVT3")
	)
	(segment
		(start 311.45734 -27.727148)
		(end 311.130696 -28.053792)
		(width 0.10795)
		(layer "B.Cu")
		(net "IRQ_DIMM_SAVE_LVT3")
	)
	(segment
		(start 312.12409 -27.16911)
		(end 312.251344 -27.041856)
		(width 0.10795)
		(layer "B.Cu")
		(net "IRQ_DIMM_SAVE_LVT3")
	)
	(segment
		(start 312.12409 -27.727148)
		(end 311.45734 -27.727148)
		(width 0.10795)
		(layer "B.Cu")
		(net "IRQ_DIMM_SAVE_LVT3")
	)
	(segment
		(start 312.12409 -27.727148)
		(end 312.12409 -27.16911)
		(width 0.10795)
		(layer "B.Cu")
		(net "IRQ_DIMM_SAVE_LVT3")
	)
	(segment
		(start 312.774076 -27.15514)
		(end 312.774076 -27.727148)
		(width 0.10795)
		(layer "B.Cu")
		(net "IRQ_DIMM_SAVE_LVT3")
	)
	(segment
		(start 310.2102 -27.0764)
		(end 310.2102 -27.133296)
		(width 0.10795)
		(layer "B.Cu")
		(net "IRQ_DIMM_SAVE_LVT3")
	)
	(segment
		(start 312.251344 -27.041856)
		(end 312.660792 -27.041856)
		(width 0.10795)
		(layer "B.Cu")
		(net "IRQ_DIMM_SAVE_LVT3")
	)
	(segment
		(start 310.2102 -27.133296)
		(end 311.130696 -28.053792)
		(width 0.10795)
		(layer "B.Cu")
		(net "IRQ_DIMM_SAVE_LVT3")
	)
	(segment
		(start 312.660792 -27.041856)
		(end 312.774076 -27.15514)
		(width 0.10795)
		(layer "B.Cu")
		(net "IRQ_DIMM_SAVE_LVT3")
	)
	(segment
		(start 367.145316 -72.695308)
		(end 367.545112 -73.095104)
		(width 0.1016)
		(layer "F.Cu")
		(net "FM_UV_ADR_TRIGGER_N")
	)
	(segment
		(start 343.049352 -71.224648)
		(end 348.423484 -71.224648)
		(width 0.10795)
		(layer "F.Cu")
		(net "FM_UV_ADR_TRIGGER_N")
	)
	(segment
		(start 349.966534 -72.767698)
		(end 353.153472 -72.767698)
		(width 0.10795)
		(layer "F.Cu")
		(net "FM_UV_ADR_TRIGGER_N")
	)
	(segment
		(start 361.3658 -70.497446)
		(end 361.3658 -69.657976)
		(width 0.10795)
		(layer "F.Cu")
		(net "FM_UV_ADR_TRIGGER_N")
	)
	(segment
		(start 357.823008 -71.506588)
		(end 360.356658 -71.506588)
		(width 0.10795)
		(layer "F.Cu")
		(net "FM_UV_ADR_TRIGGER_N")
	)
	(segment
		(start 357.159814 -70.843394)
		(end 357.823008 -71.506588)
		(width 0.10795)
		(layer "F.Cu")
		(net "FM_UV_ADR_TRIGGER_N")
	)
	(segment
		(start 348.423484 -71.224648)
		(end 349.966534 -72.767698)
		(width 0.10795)
		(layer "F.Cu")
		(net "FM_UV_ADR_TRIGGER_N")
	)
	(segment
		(start 355.077776 -70.843394)
		(end 357.159814 -70.843394)
		(width 0.10795)
		(layer "F.Cu")
		(net "FM_UV_ADR_TRIGGER_N")
	)
	(segment
		(start 361.99572 -69.028056)
		(end 364.570264 -69.028056)
		(width 0.10795)
		(layer "F.Cu")
		(net "FM_UV_ADR_TRIGGER_N")
	)
	(segment
		(start 365.03864 -71.521574)
		(end 366.212374 -72.695308)
		(width 0.10795)
		(layer "F.Cu")
		(net "FM_UV_ADR_TRIGGER_N")
	)
	(segment
		(start 360.356658 -71.506588)
		(end 360.799634 -71.063612)
		(width 0.10795)
		(layer "F.Cu")
		(net "FM_UV_ADR_TRIGGER_N")
	)
	(segment
		(start 361.3658 -69.657976)
		(end 361.99572 -69.028056)
		(width 0.10795)
		(layer "F.Cu")
		(net "FM_UV_ADR_TRIGGER_N")
	)
	(segment
		(start 341.8078 -72.4662)
		(end 343.049352 -71.224648)
		(width 0.10795)
		(layer "F.Cu")
		(net "FM_UV_ADR_TRIGGER_N")
	)
	(segment
		(start 365.03864 -69.496432)
		(end 365.03864 -71.521574)
		(width 0.10795)
		(layer "F.Cu")
		(net "FM_UV_ADR_TRIGGER_N")
	)
	(segment
		(start 366.212374 -72.695308)
		(end 367.145316 -72.695308)
		(width 0.10795)
		(layer "F.Cu")
		(net "FM_UV_ADR_TRIGGER_N")
	)
	(segment
		(start 364.570264 -69.028056)
		(end 365.03864 -69.496432)
		(width 0.10795)
		(layer "F.Cu")
		(net "FM_UV_ADR_TRIGGER_N")
	)
	(segment
		(start 360.799634 -71.063612)
		(end 361.3658 -70.497446)
		(width 0.10795)
		(layer "F.Cu")
		(net "FM_UV_ADR_TRIGGER_N")
	)
	(segment
		(start 353.153472 -72.767698)
		(end 355.077776 -70.843394)
		(width 0.10795)
		(layer "F.Cu")
		(net "FM_UV_ADR_TRIGGER_N")
	)
	(via
		(at 341.8078 -72.4662)
		(size 0.508)
		(drill 0.254)
		(layers "F.Cu" "B.Cu")
		(net "FM_UV_ADR_TRIGGER_N")
	)
	(via
		(at 360.799634 -71.063612)
		(size 0.762)
		(drill 0.381)
		(layers "F.Cu" "B.Cu")
		(net "FM_UV_ADR_TRIGGER_N")
	)
	(via
		(at 22.1996 -85.6488)
		(size 0.508)
		(drill 0.254)
		(layers "F.Cu" "B.Cu")
		(net "FM_UV_ADR_TRIGGER_N")
	)
	(segment
		(start 22.96414 -83.977988)
		(end 22.487128 -84.455)
		(width 0.10795)
		(layer "B.Cu")
		(net "FM_UV_ADR_TRIGGER_N")
	)
	(segment
		(start 24.1046 -84.106258)
		(end 23.97633 -83.977988)
		(width 0.10795)
		(layer "B.Cu")
		(net "FM_UV_ADR_TRIGGER_N")
	)
	(segment
		(start 24.1046 -84.5312)
		(end 23.251414 -84.5312)
		(width 0.10795)
		(layer "B.Cu")
		(net "FM_UV_ADR_TRIGGER_N")
	)
	(segment
		(start 23.251414 -84.5312)
		(end 23.00478 -84.777834)
		(width 0.10795)
		(layer "B.Cu")
		(net "FM_UV_ADR_TRIGGER_N")
	)
	(segment
		(start 23.97633 -83.977988)
		(end 22.96414 -83.977988)
		(width 0.10795)
		(layer "B.Cu")
		(net "FM_UV_ADR_TRIGGER_N")
	)
	(segment
		(start 23.00478 -85.53958)
		(end 23.368 -85.9028)
		(width 0.10795)
		(layer "B.Cu")
		(net "FM_UV_ADR_TRIGGER_N")
	)
	(segment
		(start 22.487128 -84.455)
		(end 22.0345 -84.455)
		(width 0.10795)
		(layer "B.Cu")
		(net "FM_UV_ADR_TRIGGER_N")
	)
	(segment
		(start 24.1046 -84.5312)
		(end 24.1046 -84.106258)
		(width 0.10795)
		(layer "B.Cu")
		(net "FM_UV_ADR_TRIGGER_N")
	)
	(segment
		(start 23.00478 -84.777834)
		(end 23.00478 -85.53958)
		(width 0.10795)
		(layer "B.Cu")
		(net "FM_UV_ADR_TRIGGER_N")
	)
	(segment
		(start 23.368 -85.9028)
		(end 22.4536 -85.9028)
		(width 0.10795)
		(layer "B.Cu")
		(net "FM_UV_ADR_TRIGGER_N")
	)
	(segment
		(start 22.4536 -85.9028)
		(end 22.1996 -85.6488)
		(width 0.10795)
		(layer "B.Cu")
		(net "FM_UV_ADR_TRIGGER_N")
	)
	(segment
		(start 342.63076 -118.764812)
		(end 340.599522 -118.764812)
		(width 0.089408)
		(layer "In9.Cu")
		(net "FM_UV_ADR_TRIGGER_N")
	)
	(segment
		(start 328.838306 -122.36704)
		(end 328.180446 -123.0249)
		(width 0.089408)
		(layer "In9.Cu")
		(net "FM_UV_ADR_TRIGGER_N")
	)
	(segment
		(start 152.729184 -127.130048)
		(end 147.548092 -121.948956)
		(width 0.089408)
		(layer "In9.Cu")
		(net "FM_UV_ADR_TRIGGER_N")
	)
	(segment
		(start 306.916836 -122.451876)
		(end 264.216388 -122.451876)
		(width 0.089408)
		(layer "In9.Cu")
		(net "FM_UV_ADR_TRIGGER_N")
	)
	(segment
		(start 221.447868 -124.131832)
		(end 187.161424 -124.131832)
		(width 0.089408)
		(layer "In9.Cu")
		(net "FM_UV_ADR_TRIGGER_N")
	)
	(segment
		(start 181.746652 -125.141736)
		(end 180.243734 -123.638818)
		(width 0.089408)
		(layer "In9.Cu")
		(net "FM_UV_ADR_TRIGGER_N")
	)
	(segment
		(start 337.362292 -86.433914)
		(end 337.312 -86.484206)
		(width 0.089408)
		(layer "In9.Cu")
		(net "FM_UV_ADR_TRIGGER_N")
	)
	(segment
		(start 17.135348 -98.110802)
		(end 15.756636 -98.110802)
		(width 0.089408)
		(layer "In9.Cu")
		(net "FM_UV_ADR_TRIGGER_N")
	)
	(segment
		(start 19.563334 -87.286846)
		(end 20.920964 -85.929216)
		(width 0.089408)
		(layer "In9.Cu")
		(net "FM_UV_ADR_TRIGGER_N")
	)
	(segment
		(start 337.227672 -86.04758)
		(end 337.362292 -86.1822)
		(width 0.089408)
		(layer "In9.Cu")
		(net "FM_UV_ADR_TRIGGER_N")
	)
	(segment
		(start 163.882324 -124.478288)
		(end 161.230564 -127.130048)
		(width 0.089408)
		(layer "In9.Cu")
		(net "FM_UV_ADR_TRIGGER_N")
	)
	(segment
		(start 263.379966 -123.288298)
		(end 244.89918 -123.288298)
		(width 0.089408)
		(layer "In9.Cu")
		(net "FM_UV_ADR_TRIGGER_N")
	)
	(segment
		(start 340.399624 -93.728794)
		(end 340.95055 -94.27972)
		(width 0.089408)
		(layer "In9.Cu")
		(net "FM_UV_ADR_TRIGGER_N")
	)
	(segment
		(start 337.362292 -86.1822)
		(end 337.362292 -86.433914)
		(width 0.089408)
		(layer "In9.Cu")
		(net "FM_UV_ADR_TRIGGER_N")
	)
	(segment
		(start 244.285262 -122.67438)
		(end 222.90532 -122.67438)
		(width 0.089408)
		(layer "In9.Cu")
		(net "FM_UV_ADR_TRIGGER_N")
	)
	(segment
		(start 319.77203 -126.124716)
		(end 310.589676 -126.124716)
		(width 0.089408)
		(layer "In9.Cu")
		(net "FM_UV_ADR_TRIGGER_N")
	)
	(segment
		(start 14.500606 -88.870028)
		(end 16.083788 -87.286846)
		(width 0.089408)
		(layer "In9.Cu")
		(net "FM_UV_ADR_TRIGGER_N")
	)
	(segment
		(start 339.0646 -91.536012)
		(end 340.399624 -92.871036)
		(width 0.089408)
		(layer "In9.Cu")
		(net "FM_UV_ADR_TRIGGER_N")
	)
	(segment
		(start 26.351484 -114.068352)
		(end 24.522176 -114.068352)
		(width 0.089408)
		(layer "In9.Cu")
		(net "FM_UV_ADR_TRIGGER_N")
	)
	(segment
		(start 343.61628 -117.779292)
		(end 342.63076 -118.764812)
		(width 0.089408)
		(layer "In9.Cu")
		(net "FM_UV_ADR_TRIGGER_N")
	)
	(segment
		(start 264.216388 -122.451876)
		(end 263.379966 -123.288298)
		(width 0.089408)
		(layer "In9.Cu")
		(net "FM_UV_ADR_TRIGGER_N")
	)
	(segment
		(start 18.80616 -108.352336)
		(end 18.80616 -99.781614)
		(width 0.089408)
		(layer "In9.Cu")
		(net "FM_UV_ADR_TRIGGER_N")
	)
	(segment
		(start 338.6836 -88.4682)
		(end 339.0646 -88.8492)
		(width 0.089408)
		(layer "In9.Cu")
		(net "FM_UV_ADR_TRIGGER_N")
	)
	(segment
		(start 174.456598 -123.638818)
		(end 172.27804 -125.817376)
		(width 0.089408)
		(layer "In9.Cu")
		(net "FM_UV_ADR_TRIGGER_N")
	)
	(segment
		(start 337.016598 -76.380086)
		(end 337.016598 -85.707728)
		(width 0.089408)
		(layer "In9.Cu")
		(net "FM_UV_ADR_TRIGGER_N")
	)
	(segment
		(start 324.947534 -123.0249)
		(end 323.356478 -124.615956)
		(width 0.089408)
		(layer "In9.Cu")
		(net "FM_UV_ADR_TRIGGER_N")
	)
	(segment
		(start 187.161424 -124.131832)
		(end 186.15152 -125.141736)
		(width 0.089408)
		(layer "In9.Cu")
		(net "FM_UV_ADR_TRIGGER_N")
	)
	(segment
		(start 340.599522 -118.764812)
		(end 336.997294 -122.36704)
		(width 0.089408)
		(layer "In9.Cu")
		(net "FM_UV_ADR_TRIGGER_N")
	)
	(segment
		(start 167.140382 -125.817376)
		(end 166.464742 -125.141736)
		(width 0.089408)
		(layer "In9.Cu")
		(net "FM_UV_ADR_TRIGGER_N")
	)
	(segment
		(start 340.95055 -99.663504)
		(end 340.40699 -100.207064)
		(width 0.089408)
		(layer "In9.Cu")
		(net "FM_UV_ADR_TRIGGER_N")
	)
	(segment
		(start 18.80616 -99.781614)
		(end 17.135348 -98.110802)
		(width 0.089408)
		(layer "In9.Cu")
		(net "FM_UV_ADR_TRIGGER_N")
	)
	(segment
		(start 340.95055 -94.27972)
		(end 340.95055 -99.663504)
		(width 0.089408)
		(layer "In9.Cu")
		(net "FM_UV_ADR_TRIGGER_N")
	)
	(segment
		(start 24.522176 -114.068352)
		(end 18.80616 -108.352336)
		(width 0.089408)
		(layer "In9.Cu")
		(net "FM_UV_ADR_TRIGGER_N")
	)
	(segment
		(start 147.548092 -121.948956)
		(end 147.54098 -121.948956)
		(width 0.089408)
		(layer "In9.Cu")
		(net "FM_UV_ADR_TRIGGER_N")
	)
	(segment
		(start 13.6906 -96.044766)
		(end 13.6906 -92.181426)
		(width 0.089408)
		(layer "In9.Cu")
		(net "FM_UV_ADR_TRIGGER_N")
	)
	(segment
		(start 16.083788 -87.286846)
		(end 19.563334 -87.286846)
		(width 0.089408)
		(layer "In9.Cu")
		(net "FM_UV_ADR_TRIGGER_N")
	)
	(segment
		(start 336.997294 -122.36704)
		(end 328.838306 -122.36704)
		(width 0.089408)
		(layer "In9.Cu")
		(net "FM_UV_ADR_TRIGGER_N")
	)
	(segment
		(start 165.637972 -124.478288)
		(end 163.882324 -124.478288)
		(width 0.089408)
		(layer "In9.Cu")
		(net "FM_UV_ADR_TRIGGER_N")
	)
	(segment
		(start 340.40699 -104.442006)
		(end 343.61628 -107.651296)
		(width 0.089408)
		(layer "In9.Cu")
		(net "FM_UV_ADR_TRIGGER_N")
	)
	(segment
		(start 323.356478 -124.615956)
		(end 321.28079 -124.615956)
		(width 0.089408)
		(layer "In9.Cu")
		(net "FM_UV_ADR_TRIGGER_N")
	)
	(segment
		(start 340.40699 -100.207064)
		(end 340.40699 -104.442006)
		(width 0.089408)
		(layer "In9.Cu")
		(net "FM_UV_ADR_TRIGGER_N")
	)
	(segment
		(start 328.180446 -123.0249)
		(end 324.947534 -123.0249)
		(width 0.089408)
		(layer "In9.Cu")
		(net "FM_UV_ADR_TRIGGER_N")
	)
	(segment
		(start 180.243734 -123.638818)
		(end 174.456598 -123.638818)
		(width 0.089408)
		(layer "In9.Cu")
		(net "FM_UV_ADR_TRIGGER_N")
	)
	(segment
		(start 339.0646 -88.8492)
		(end 339.0646 -91.536012)
		(width 0.089408)
		(layer "In9.Cu")
		(net "FM_UV_ADR_TRIGGER_N")
	)
	(segment
		(start 186.15152 -125.141736)
		(end 181.746652 -125.141736)
		(width 0.089408)
		(layer "In9.Cu")
		(net "FM_UV_ADR_TRIGGER_N")
	)
	(segment
		(start 147.54098 -121.948956)
		(end 147.43938 -121.847356)
		(width 0.089408)
		(layer "In9.Cu")
		(net "FM_UV_ADR_TRIGGER_N")
	)
	(segment
		(start 338.760054 -74.63663)
		(end 337.016598 -76.380086)
		(width 0.089408)
		(layer "In9.Cu")
		(net "FM_UV_ADR_TRIGGER_N")
	)
	(segment
		(start 21.919184 -85.929216)
		(end 22.1996 -85.6488)
		(width 0.089408)
		(layer "In9.Cu")
		(net "FM_UV_ADR_TRIGGER_N")
	)
	(segment
		(start 321.28079 -124.615956)
		(end 319.77203 -126.124716)
		(width 0.089408)
		(layer "In9.Cu")
		(net "FM_UV_ADR_TRIGGER_N")
	)
	(segment
		(start 340.399624 -92.871036)
		(end 340.399624 -93.728794)
		(width 0.089408)
		(layer "In9.Cu")
		(net "FM_UV_ADR_TRIGGER_N")
	)
	(segment
		(start 337.312 -86.484206)
		(end 337.312 -88.138)
		(width 0.089408)
		(layer "In9.Cu")
		(net "FM_UV_ADR_TRIGGER_N")
	)
	(segment
		(start 337.6422 -88.4682)
		(end 338.6836 -88.4682)
		(width 0.089408)
		(layer "In9.Cu")
		(net "FM_UV_ADR_TRIGGER_N")
	)
	(segment
		(start 222.90532 -122.67438)
		(end 221.447868 -124.131832)
		(width 0.089408)
		(layer "In9.Cu")
		(net "FM_UV_ADR_TRIGGER_N")
	)
	(segment
		(start 244.89918 -123.288298)
		(end 244.285262 -122.67438)
		(width 0.089408)
		(layer "In9.Cu")
		(net "FM_UV_ADR_TRIGGER_N")
	)
	(segment
		(start 147.43938 -121.847356)
		(end 34.130488 -121.847356)
		(width 0.089408)
		(layer "In9.Cu")
		(net "FM_UV_ADR_TRIGGER_N")
	)
	(segment
		(start 34.130488 -121.847356)
		(end 26.351484 -114.068352)
		(width 0.089408)
		(layer "In9.Cu")
		(net "FM_UV_ADR_TRIGGER_N")
	)
	(segment
		(start 172.27804 -125.817376)
		(end 167.140382 -125.817376)
		(width 0.089408)
		(layer "In9.Cu")
		(net "FM_UV_ADR_TRIGGER_N")
	)
	(segment
		(start 20.920964 -85.929216)
		(end 21.919184 -85.929216)
		(width 0.089408)
		(layer "In9.Cu")
		(net "FM_UV_ADR_TRIGGER_N")
	)
	(segment
		(start 339.81517 -74.63663)
		(end 338.760054 -74.63663)
		(width 0.089408)
		(layer "In9.Cu")
		(net "FM_UV_ADR_TRIGGER_N")
	)
	(segment
		(start 337.016598 -85.707728)
		(end 337.227672 -85.918802)
		(width 0.089408)
		(layer "In9.Cu")
		(net "FM_UV_ADR_TRIGGER_N")
	)
	(segment
		(start 341.8078 -72.4662)
		(end 341.8078 -72.644)
		(width 0.089408)
		(layer "In9.Cu")
		(net "FM_UV_ADR_TRIGGER_N")
	)
	(segment
		(start 15.756636 -98.110802)
		(end 13.6906 -96.044766)
		(width 0.089408)
		(layer "In9.Cu")
		(net "FM_UV_ADR_TRIGGER_N")
	)
	(segment
		(start 13.6906 -92.181426)
		(end 14.500606 -91.37142)
		(width 0.089408)
		(layer "In9.Cu")
		(net "FM_UV_ADR_TRIGGER_N")
	)
	(segment
		(start 166.464742 -125.141736)
		(end 166.30142 -125.141736)
		(width 0.089408)
		(layer "In9.Cu")
		(net "FM_UV_ADR_TRIGGER_N")
	)
	(segment
		(start 14.500606 -91.37142)
		(end 14.500606 -88.870028)
		(width 0.089408)
		(layer "In9.Cu")
		(net "FM_UV_ADR_TRIGGER_N")
	)
	(segment
		(start 341.8078 -72.644)
		(end 339.81517 -74.63663)
		(width 0.089408)
		(layer "In9.Cu")
		(net "FM_UV_ADR_TRIGGER_N")
	)
	(segment
		(start 337.312 -88.138)
		(end 337.6422 -88.4682)
		(width 0.089408)
		(layer "In9.Cu")
		(net "FM_UV_ADR_TRIGGER_N")
	)
	(segment
		(start 337.227672 -85.918802)
		(end 337.227672 -86.04758)
		(width 0.089408)
		(layer "In9.Cu")
		(net "FM_UV_ADR_TRIGGER_N")
	)
	(segment
		(start 343.61628 -107.651296)
		(end 343.61628 -117.779292)
		(width 0.089408)
		(layer "In9.Cu")
		(net "FM_UV_ADR_TRIGGER_N")
	)
	(segment
		(start 161.230564 -127.130048)
		(end 152.729184 -127.130048)
		(width 0.089408)
		(layer "In9.Cu")
		(net "FM_UV_ADR_TRIGGER_N")
	)
	(segment
		(start 310.589676 -126.124716)
		(end 306.916836 -122.451876)
		(width 0.089408)
		(layer "In9.Cu")
		(net "FM_UV_ADR_TRIGGER_N")
	)
	(segment
		(start 166.30142 -125.141736)
		(end 165.637972 -124.478288)
		(width 0.089408)
		(layer "In9.Cu")
		(net "FM_UV_ADR_TRIGGER_N")
	)
	(segment
		(start 417.65982 -50.673)
		(end 418.975286 -50.673)
		(width 0.10795)
		(layer "F.Cu")
		(net "FM_UARTSW_MSB_N")
	)
	(segment
		(start 392.69035 -98.69424)
		(end 393.18565 -98.464116)
		(width 0.10795)
		(layer "F.Cu")
		(net "FM_UARTSW_MSB_N")
	)
	(segment
		(start 417.982146 -45.867828)
		(end 417.982146 -46.812454)
		(width 0.10795)
		(layer "F.Cu")
		(net "FM_UARTSW_MSB_N")
	)
	(segment
		(start 418.143944 -46.974252)
		(end 418.143944 -47.312326)
		(width 0.10795)
		(layer "F.Cu")
		(net "FM_UARTSW_MSB_N")
	)
	(segment
		(start 418.975286 -50.673)
		(end 419.843458 -51.541172)
		(width 0.10795)
		(layer "F.Cu")
		(net "FM_UARTSW_MSB_N")
	)
	(segment
		(start 417.148772 -50.161952)
		(end 417.65982 -50.673)
		(width 0.10795)
		(layer "F.Cu")
		(net "FM_UARTSW_MSB_N")
	)
	(segment
		(start 416.690048 -43.334686)
		(end 416.690048 -44.57573)
		(width 0.10795)
		(layer "F.Cu")
		(net "FM_UARTSW_MSB_N")
	)
	(segment
		(start 417.982146 -46.812454)
		(end 418.143944 -46.974252)
		(width 0.10795)
		(layer "F.Cu")
		(net "FM_UARTSW_MSB_N")
	)
	(segment
		(start 417.67633 -48.991774)
		(end 417.148772 -49.519332)
		(width 0.10795)
		(layer "F.Cu")
		(net "FM_UARTSW_MSB_N")
	)
	(segment
		(start 418.143944 -47.312326)
		(end 417.67633 -47.77994)
		(width 0.10795)
		(layer "F.Cu")
		(net "FM_UARTSW_MSB_N")
	)
	(segment
		(start 417.148772 -49.519332)
		(end 417.148772 -50.161952)
		(width 0.10795)
		(layer "F.Cu")
		(net "FM_UARTSW_MSB_N")
	)
	(segment
		(start 417.67633 -47.77994)
		(end 417.67633 -48.991774)
		(width 0.10795)
		(layer "F.Cu")
		(net "FM_UARTSW_MSB_N")
	)
	(segment
		(start 419.843458 -51.541172)
		(end 421.210994 -51.541172)
		(width 0.10795)
		(layer "F.Cu")
		(net "FM_UARTSW_MSB_N")
	)
	(segment
		(start 500.398034 -137.040366)
		(end 501.0912 -136.3472)
		(width 0.10795)
		(layer "F.Cu")
		(net "FM_UARTSW_MSB_N")
	)
	(segment
		(start 500.398034 -137.278618)
		(end 500.398034 -137.040366)
		(width 0.10795)
		(layer "F.Cu")
		(net "FM_UARTSW_MSB_N")
	)
	(segment
		(start 416.690048 -44.57573)
		(end 417.982146 -45.867828)
		(width 0.10795)
		(layer "F.Cu")
		(net "FM_UARTSW_MSB_N")
	)
	(segment
		(start 370.345208 -79.094838)
		(end 370.745004 -78.695042)
		(width 0.1016)
		(layer "F.Cu")
		(net "FM_UARTSW_MSB_N")
	)
	(segment
		(start 421.210994 -51.541172)
		(end 421.75176 -51.000406)
		(width 0.10795)
		(layer "F.Cu")
		(net "FM_UARTSW_MSB_N")
	)
	(via
		(at 393.18565 -98.464116)
		(size 0.508)
		(drill 0.254)
		(layers "F.Cu" "B.Cu")
		(net "FM_UARTSW_MSB_N")
	)
	(via
		(at 370.345208 -79.094838)
		(size 0.4572)
		(drill 0.2032)
		(layers "F.Cu" "B.Cu")
		(net "FM_UARTSW_MSB_N")
	)
	(via
		(at 501.0912 -136.3472)
		(size 0.508)
		(drill 0.254)
		(layers "F.Cu" "B.Cu")
		(net "FM_UARTSW_MSB_N")
	)
	(via
		(at 498.953028 -37.418772)
		(size 0.508)
		(drill 0.254)
		(layers "F.Cu" "B.Cu")
		(net "FM_UARTSW_MSB_N")
	)
	(via
		(at 473.9767 -114.5794)
		(size 0.508)
		(drill 0.254)
		(layers "F.Cu" "B.Cu")
		(net "FM_UARTSW_MSB_N")
	)
	(via
		(at 421.75176 -51.000406)
		(size 0.508)
		(drill 0.254)
		(layers "F.Cu" "B.Cu")
		(net "FM_UARTSW_MSB_N")
	)
	(via
		(at 493.9284 -38.5318)
		(size 0.508)
		(drill 0.254)
		(layers "F.Cu" "B.Cu")
		(net "FM_UARTSW_MSB_N")
	)
	(via
		(at 493.649 -119.634)
		(size 0.6604)
		(drill 0.3302)
		(layers "F.Cu" "B.Cu")
		(net "FM_UARTSW_MSB_N")
	)
	(segment
		(start 492.16056 -120.05056)
		(end 492.57712 -119.634)
		(width 0.10795)
		(layer "B.Cu")
		(net "FM_UARTSW_MSB_N")
	)
	(segment
		(start 473.7354 -114.8207)
		(end 473.7354 -115.194842)
		(width 0.10795)
		(layer "B.Cu")
		(net "FM_UARTSW_MSB_N")
	)
	(segment
		(start 490.87532 -119.55526)
		(end 491.37062 -120.05056)
		(width 0.10795)
		(layer "B.Cu")
		(net "FM_UARTSW_MSB_N")
	)
	(segment
		(start 487.51744 -119.55526)
		(end 490.87532 -119.55526)
		(width 0.10795)
		(layer "B.Cu")
		(net "FM_UARTSW_MSB_N")
	)
	(segment
		(start 493.649 -119.634)
		(end 494.8936 -119.634)
		(width 0.10795)
		(layer "B.Cu")
		(net "FM_UARTSW_MSB_N")
	)
	(segment
		(start 494.8936 -119.634)
		(end 495.122454 -119.862854)
		(width 0.10795)
		(layer "B.Cu")
		(net "FM_UARTSW_MSB_N")
	)
	(segment
		(start 476.598996 -121.0945)
		(end 477.145604 -121.0945)
		(width 0.10795)
		(layer "B.Cu")
		(net "FM_UARTSW_MSB_N")
	)
	(segment
		(start 484.90632 -122.80392)
		(end 486.358946 -122.80392)
		(width 0.10795)
		(layer "B.Cu")
		(net "FM_UARTSW_MSB_N")
	)
	(segment
		(start 473.6338 -120.9802)
		(end 474.007942 -121.354342)
		(width 0.10795)
		(layer "B.Cu")
		(net "FM_UARTSW_MSB_N")
	)
	(segment
		(start 501.458738 -122.897138)
		(end 501.458738 -133.113526)
		(width 0.10795)
		(layer "B.Cu")
		(net "FM_UARTSW_MSB_N")
	)
	(segment
		(start 482.473 -121.666)
		(end 483.444296 -122.637296)
		(width 0.10795)
		(layer "B.Cu")
		(net "FM_UARTSW_MSB_N")
	)
	(segment
		(start 491.37062 -120.05056)
		(end 492.16056 -120.05056)
		(width 0.10795)
		(layer "B.Cu")
		(net "FM_UARTSW_MSB_N")
	)
	(segment
		(start 499.23319 -36.957762)
		(end 499.967504 -36.957762)
		(width 0.10795)
		(layer "B.Cu")
		(net "FM_UARTSW_MSB_N")
	)
	(segment
		(start 477.145604 -121.0945)
		(end 477.717104 -121.666)
		(width 0.10795)
		(layer "B.Cu")
		(net "FM_UARTSW_MSB_N")
	)
	(segment
		(start 492.57712 -119.634)
		(end 493.649 -119.634)
		(width 0.10795)
		(layer "B.Cu")
		(net "FM_UARTSW_MSB_N")
	)
	(segment
		(start 477.717104 -121.666)
		(end 482.473 -121.666)
		(width 0.10795)
		(layer "B.Cu")
		(net "FM_UARTSW_MSB_N")
	)
	(segment
		(start 476.339154 -121.354342)
		(end 476.598996 -121.0945)
		(width 0.10795)
		(layer "B.Cu")
		(net "FM_UARTSW_MSB_N")
	)
	(segment
		(start 484.739696 -122.637296)
		(end 484.90632 -122.80392)
		(width 0.10795)
		(layer "B.Cu")
		(net "FM_UARTSW_MSB_N")
	)
	(segment
		(start 473.7354 -115.194842)
		(end 473.6338 -115.296442)
		(width 0.10795)
		(layer "B.Cu")
		(net "FM_UARTSW_MSB_N")
	)
	(segment
		(start 493.251998 -36.944808)
		(end 493.4966 -37.18941)
		(width 0.10795)
		(layer "B.Cu")
		(net "FM_UARTSW_MSB_N")
	)
	(segment
		(start 483.444296 -122.637296)
		(end 484.739696 -122.637296)
		(width 0.10795)
		(layer "B.Cu")
		(net "FM_UARTSW_MSB_N")
	)
	(segment
		(start 473.9767 -114.5794)
		(end 473.7354 -114.8207)
		(width 0.10795)
		(layer "B.Cu")
		(net "FM_UARTSW_MSB_N")
	)
	(segment
		(start 486.86466 -122.298206)
		(end 486.86466 -120.20804)
		(width 0.10795)
		(layer "B.Cu")
		(net "FM_UARTSW_MSB_N")
	)
	(segment
		(start 486.86466 -120.20804)
		(end 487.51744 -119.55526)
		(width 0.10795)
		(layer "B.Cu")
		(net "FM_UARTSW_MSB_N")
	)
	(segment
		(start 498.953028 -37.237924)
		(end 499.23319 -36.957762)
		(width 0.10795)
		(layer "B.Cu")
		(net "FM_UARTSW_MSB_N")
	)
	(segment
		(start 498.953028 -37.418772)
		(end 498.953028 -37.237924)
		(width 0.10795)
		(layer "B.Cu")
		(net "FM_UARTSW_MSB_N")
	)
	(segment
		(start 498.424454 -119.862854)
		(end 501.458738 -122.897138)
		(width 0.10795)
		(layer "B.Cu")
		(net "FM_UARTSW_MSB_N")
	)
	(segment
		(start 493.4966 -37.18941)
		(end 493.4966 -38.1)
		(width 0.10795)
		(layer "B.Cu")
		(net "FM_UARTSW_MSB_N")
	)
	(segment
		(start 486.358946 -122.80392)
		(end 486.86466 -122.298206)
		(width 0.10795)
		(layer "B.Cu")
		(net "FM_UARTSW_MSB_N")
	)
	(segment
		(start 501.458738 -133.113526)
		(end 501.0912 -133.481064)
		(width 0.10795)
		(layer "B.Cu")
		(net "FM_UARTSW_MSB_N")
	)
	(segment
		(start 501.0912 -133.481064)
		(end 501.0912 -136.3472)
		(width 0.10795)
		(layer "B.Cu")
		(net "FM_UARTSW_MSB_N")
	)
	(segment
		(start 493.4966 -38.1)
		(end 493.9284 -38.5318)
		(width 0.10795)
		(layer "B.Cu")
		(net "FM_UARTSW_MSB_N")
	)
	(segment
		(start 474.007942 -121.354342)
		(end 476.339154 -121.354342)
		(width 0.10795)
		(layer "B.Cu")
		(net "FM_UARTSW_MSB_N")
	)
	(segment
		(start 495.122454 -119.862854)
		(end 498.424454 -119.862854)
		(width 0.10795)
		(layer "B.Cu")
		(net "FM_UARTSW_MSB_N")
	)
	(segment
		(start 473.6338 -115.296442)
		(end 473.6338 -120.9802)
		(width 0.10795)
		(layer "B.Cu")
		(net "FM_UARTSW_MSB_N")
	)
	(segment
		(start 377.152916 -95.847916)
		(end 377.152916 -95.679006)
		(width 0.089408)
		(layer "In2.Cu")
		(net "FM_UARTSW_MSB_N")
	)
	(segment
		(start 389.388604 -96.348296)
		(end 377.653296 -96.348296)
		(width 0.089408)
		(layer "In2.Cu")
		(net "FM_UARTSW_MSB_N")
	)
	(segment
		(start 390.6774 -98.298)
		(end 390.31037 -97.93097)
		(width 0.089408)
		(layer "In2.Cu")
		(net "FM_UARTSW_MSB_N")
	)
	(segment
		(start 377.152916 -95.679006)
		(end 374.770904 -93.296994)
		(width 0.089408)
		(layer "In2.Cu")
		(net "FM_UARTSW_MSB_N")
	)
	(segment
		(start 374.291352 -93.296994)
		(end 374.11152 -93.117162)
		(width 0.089408)
		(layer "In2.Cu")
		(net "FM_UARTSW_MSB_N")
	)
	(segment
		(start 391.7696 -98.325432)
		(end 391.7696 -98.4631)
		(width 0.089408)
		(layer "In2.Cu")
		(net "FM_UARTSW_MSB_N")
	)
	(segment
		(start 478.237296 -46.707806)
		(end 476.32747 -48.617632)
		(width 0.089408)
		(layer "In2.Cu")
		(net "FM_UARTSW_MSB_N")
	)
	(segment
		(start 470.259918 -50.915316)
		(end 469.322912 -49.97831)
		(width 0.089408)
		(layer "In2.Cu")
		(net "FM_UARTSW_MSB_N")
	)
	(segment
		(start 480.915472 -46.286928)
		(end 480.88804 -46.259496)
		(width 0.089408)
		(layer "In2.Cu")
		(net "FM_UARTSW_MSB_N")
	)
	(segment
		(start 493.9284 -38.5318)
		(end 494.660936 -39.264336)
		(width 0.089408)
		(layer "In2.Cu")
		(net "FM_UARTSW_MSB_N")
	)
	(segment
		(start 390.31037 -97.62617)
		(end 389.7122 -97.028)
		(width 0.089408)
		(layer "In2.Cu")
		(net "FM_UARTSW_MSB_N")
	)
	(segment
		(start 436.624222 -52.470812)
		(end 426.950632 -52.470812)
		(width 0.089408)
		(layer "In2.Cu")
		(net "FM_UARTSW_MSB_N")
	)
	(segment
		(start 374.770904 -93.296994)
		(end 374.291352 -93.296994)
		(width 0.089408)
		(layer "In2.Cu")
		(net "FM_UARTSW_MSB_N")
	)
	(segment
		(start 469.322912 -49.97831)
		(end 468.33409 -49.97831)
		(width 0.089408)
		(layer "In2.Cu")
		(net "FM_UARTSW_MSB_N")
	)
	(segment
		(start 474.159834 -48.617632)
		(end 472.966288 -49.811178)
		(width 0.089408)
		(layer "In2.Cu")
		(net "FM_UARTSW_MSB_N")
	)
	(segment
		(start 389.7122 -97.028)
		(end 389.7122 -96.671892)
		(width 0.089408)
		(layer "In2.Cu")
		(net "FM_UARTSW_MSB_N")
	)
	(segment
		(start 392.029696 -98.065336)
		(end 391.7696 -98.325432)
		(width 0.089408)
		(layer "In2.Cu")
		(net "FM_UARTSW_MSB_N")
	)
	(segment
		(start 493.7633 -45.460412)
		(end 492.936784 -46.286928)
		(width 0.089408)
		(layer "In2.Cu")
		(net "FM_UARTSW_MSB_N")
	)
	(segment
		(start 470.584022 -51.225704)
		(end 470.273634 -50.915316)
		(width 0.089408)
		(layer "In2.Cu")
		(net "FM_UARTSW_MSB_N")
	)
	(segment
		(start 421.788082 -50.86223)
		(end 421.788082 -50.964084)
		(width 0.089408)
		(layer "In2.Cu")
		(net "FM_UARTSW_MSB_N")
	)
	(segment
		(start 478.237296 -46.493938)
		(end 478.237296 -46.707806)
		(width 0.089408)
		(layer "In2.Cu")
		(net "FM_UARTSW_MSB_N")
	)
	(segment
		(start 421.788082 -50.964084)
		(end 421.75176 -51.000406)
		(width 0.089408)
		(layer "In2.Cu")
		(net "FM_UARTSW_MSB_N")
	)
	(segment
		(start 472.966288 -49.811178)
		(end 472.966288 -50.484278)
		(width 0.089408)
		(layer "In2.Cu")
		(net "FM_UARTSW_MSB_N")
	)
	(segment
		(start 392.78687 -98.065336)
		(end 392.029696 -98.065336)
		(width 0.089408)
		(layer "In2.Cu")
		(net "FM_UARTSW_MSB_N")
	)
	(segment
		(start 494.660936 -39.264336)
		(end 494.660936 -44.981368)
		(width 0.089408)
		(layer "In2.Cu")
		(net "FM_UARTSW_MSB_N")
	)
	(segment
		(start 466.700362 -51.612038)
		(end 437.482996 -51.612038)
		(width 0.089408)
		(layer "In2.Cu")
		(net "FM_UARTSW_MSB_N")
	)
	(segment
		(start 494.181892 -45.460412)
		(end 493.7633 -45.460412)
		(width 0.089408)
		(layer "In2.Cu")
		(net "FM_UARTSW_MSB_N")
	)
	(segment
		(start 424.058588 -50.583592)
		(end 422.06672 -50.583592)
		(width 0.089408)
		(layer "In2.Cu")
		(net "FM_UARTSW_MSB_N")
	)
	(segment
		(start 393.18565 -98.464116)
		(end 392.78687 -98.065336)
		(width 0.089408)
		(layer "In2.Cu")
		(net "FM_UARTSW_MSB_N")
	)
	(segment
		(start 374.11152 -93.117162)
		(end 374.11152 -89.57564)
		(width 0.089408)
		(layer "In2.Cu")
		(net "FM_UARTSW_MSB_N")
	)
	(segment
		(start 391.7696 -98.4631)
		(end 391.369804 -98.862896)
		(width 0.089408)
		(layer "In2.Cu")
		(net "FM_UARTSW_MSB_N")
	)
	(segment
		(start 373.609362 -81.331816)
		(end 373.31396 -81.331816)
		(width 0.089408)
		(layer "In2.Cu")
		(net "FM_UARTSW_MSB_N")
	)
	(segment
		(start 426.950632 -52.470812)
		(end 426.035216 -51.555396)
		(width 0.089408)
		(layer "In2.Cu")
		(net "FM_UARTSW_MSB_N")
	)
	(segment
		(start 478.471738 -46.259496)
		(end 478.237296 -46.493938)
		(width 0.089408)
		(layer "In2.Cu")
		(net "FM_UARTSW_MSB_N")
	)
	(segment
		(start 470.273634 -50.915316)
		(end 470.259918 -50.915316)
		(width 0.089408)
		(layer "In2.Cu")
		(net "FM_UARTSW_MSB_N")
	)
	(segment
		(start 374.11152 -89.57564)
		(end 375.724674 -87.962486)
		(width 0.089408)
		(layer "In2.Cu")
		(net "FM_UARTSW_MSB_N")
	)
	(segment
		(start 373.843804 -81.731612)
		(end 373.843804 -81.566258)
		(width 0.089408)
		(layer "In2.Cu")
		(net "FM_UARTSW_MSB_N")
	)
	(segment
		(start 373.31396 -81.331816)
		(end 371.458744 -79.4766)
		(width 0.089408)
		(layer "In2.Cu")
		(net "FM_UARTSW_MSB_N")
	)
	(segment
		(start 425.030392 -51.555396)
		(end 424.058588 -50.583592)
		(width 0.089408)
		(layer "In2.Cu")
		(net "FM_UARTSW_MSB_N")
	)
	(segment
		(start 371.458744 -79.4766)
		(end 370.72697 -79.4766)
		(width 0.089408)
		(layer "In2.Cu")
		(net "FM_UARTSW_MSB_N")
	)
	(segment
		(start 437.482996 -51.612038)
		(end 436.624222 -52.470812)
		(width 0.089408)
		(layer "In2.Cu")
		(net "FM_UARTSW_MSB_N")
	)
	(segment
		(start 472.966288 -50.484278)
		(end 472.224862 -51.225704)
		(width 0.089408)
		(layer "In2.Cu")
		(net "FM_UARTSW_MSB_N")
	)
	(segment
		(start 480.88804 -46.259496)
		(end 478.471738 -46.259496)
		(width 0.089408)
		(layer "In2.Cu")
		(net "FM_UARTSW_MSB_N")
	)
	(segment
		(start 476.32747 -48.617632)
		(end 474.159834 -48.617632)
		(width 0.089408)
		(layer "In2.Cu")
		(net "FM_UARTSW_MSB_N")
	)
	(segment
		(start 389.7122 -96.671892)
		(end 389.388604 -96.348296)
		(width 0.089408)
		(layer "In2.Cu")
		(net "FM_UARTSW_MSB_N")
	)
	(segment
		(start 391.369804 -98.862896)
		(end 391.039096 -98.862896)
		(width 0.089408)
		(layer "In2.Cu")
		(net "FM_UARTSW_MSB_N")
	)
	(segment
		(start 370.72697 -79.4766)
		(end 370.345208 -79.094838)
		(width 0.089408)
		(layer "In2.Cu")
		(net "FM_UARTSW_MSB_N")
	)
	(segment
		(start 472.224862 -51.225704)
		(end 470.584022 -51.225704)
		(width 0.089408)
		(layer "In2.Cu")
		(net "FM_UARTSW_MSB_N")
	)
	(segment
		(start 391.039096 -98.862896)
		(end 390.6774 -98.5012)
		(width 0.089408)
		(layer "In2.Cu")
		(net "FM_UARTSW_MSB_N")
	)
	(segment
		(start 468.33409 -49.97831)
		(end 466.700362 -51.612038)
		(width 0.089408)
		(layer "In2.Cu")
		(net "FM_UARTSW_MSB_N")
	)
	(segment
		(start 377.653296 -96.348296)
		(end 377.152916 -95.847916)
		(width 0.089408)
		(layer "In2.Cu")
		(net "FM_UARTSW_MSB_N")
	)
	(segment
		(start 494.660936 -44.981368)
		(end 494.181892 -45.460412)
		(width 0.089408)
		(layer "In2.Cu")
		(net "FM_UARTSW_MSB_N")
	)
	(segment
		(start 375.724674 -83.612482)
		(end 373.843804 -81.731612)
		(width 0.089408)
		(layer "In2.Cu")
		(net "FM_UARTSW_MSB_N")
	)
	(segment
		(start 422.06672 -50.583592)
		(end 421.788082 -50.86223)
		(width 0.089408)
		(layer "In2.Cu")
		(net "FM_UARTSW_MSB_N")
	)
	(segment
		(start 375.724674 -87.962486)
		(end 375.724674 -83.612482)
		(width 0.089408)
		(layer "In2.Cu")
		(net "FM_UARTSW_MSB_N")
	)
	(segment
		(start 492.936784 -46.286928)
		(end 480.915472 -46.286928)
		(width 0.089408)
		(layer "In2.Cu")
		(net "FM_UARTSW_MSB_N")
	)
	(segment
		(start 426.035216 -51.555396)
		(end 425.030392 -51.555396)
		(width 0.089408)
		(layer "In2.Cu")
		(net "FM_UARTSW_MSB_N")
	)
	(segment
		(start 390.31037 -97.93097)
		(end 390.31037 -97.62617)
		(width 0.089408)
		(layer "In2.Cu")
		(net "FM_UARTSW_MSB_N")
	)
	(segment
		(start 373.843804 -81.566258)
		(end 373.609362 -81.331816)
		(width 0.089408)
		(layer "In2.Cu")
		(net "FM_UARTSW_MSB_N")
	)
	(segment
		(start 390.6774 -98.5012)
		(end 390.6774 -98.298)
		(width 0.089408)
		(layer "In2.Cu")
		(net "FM_UARTSW_MSB_N")
	)
	(segment
		(start 414.077658 -56.105552)
		(end 414.059624 -56.123586)
		(width 0.089408)
		(layer "In9.Cu")
		(net "FM_UARTSW_MSB_N")
	)
	(segment
		(start 402.166074 -87.088726)
		(end 401.432014 -87.088726)
		(width 0.089408)
		(layer "In9.Cu")
		(net "FM_UARTSW_MSB_N")
	)
	(segment
		(start 404.810468 -74.79919)
		(end 404.810468 -79.436468)
		(width 0.089408)
		(layer "In9.Cu")
		(net "FM_UARTSW_MSB_N")
	)
	(segment
		(start 411.467554 -60.400184)
		(end 411.467554 -62.719712)
		(width 0.089408)
		(layer "In9.Cu")
		(net "FM_UARTSW_MSB_N")
	)
	(segment
		(start 402.68398 -86.57082)
		(end 402.166074 -87.088726)
		(width 0.089408)
		(layer "In9.Cu")
		(net "FM_UARTSW_MSB_N")
	)
	(segment
		(start 421.361362 -51.390804)
		(end 419.94455 -51.390804)
		(width 0.089408)
		(layer "In9.Cu")
		(net "FM_UARTSW_MSB_N")
	)
	(segment
		(start 396.5575 -91.96324)
		(end 396.5575 -92.909136)
		(width 0.089408)
		(layer "In9.Cu")
		(net "FM_UARTSW_MSB_N")
	)
	(segment
		(start 409.826714 -69.782944)
		(end 404.810468 -74.79919)
		(width 0.089408)
		(layer "In9.Cu")
		(net "FM_UARTSW_MSB_N")
	)
	(segment
		(start 411.31744 -60.25007)
		(end 411.467554 -60.400184)
		(width 0.089408)
		(layer "In9.Cu")
		(net "FM_UARTSW_MSB_N")
	)
	(segment
		(start 393.18565 -97.40265)
		(end 393.18565 -98.464116)
		(width 0.089408)
		(layer "In9.Cu")
		(net "FM_UARTSW_MSB_N")
	)
	(segment
		(start 394.472414 -94.532958)
		(end 393.091416 -95.913956)
		(width 0.089408)
		(layer "In9.Cu")
		(net "FM_UARTSW_MSB_N")
	)
	(segment
		(start 411.947614 -66.024506)
		(end 411.467554 -66.504566)
		(width 0.089408)
		(layer "In9.Cu")
		(net "FM_UARTSW_MSB_N")
	)
	(segment
		(start 411.467554 -62.719712)
		(end 411.947614 -63.199772)
		(width 0.089408)
		(layer "In9.Cu")
		(net "FM_UARTSW_MSB_N")
	)
	(segment
		(start 392.78687 -97.00387)
		(end 393.18565 -97.40265)
		(width 0.089408)
		(layer "In9.Cu")
		(net "FM_UARTSW_MSB_N")
	)
	(segment
		(start 419.94455 -51.390804)
		(end 418.769038 -52.566316)
		(width 0.089408)
		(layer "In9.Cu")
		(net "FM_UARTSW_MSB_N")
	)
	(segment
		(start 415.758122 -53.951886)
		(end 415.758122 -54.868826)
		(width 0.089408)
		(layer "In9.Cu")
		(net "FM_UARTSW_MSB_N")
	)
	(segment
		(start 411.467554 -66.504566)
		(end 411.467554 -67.874896)
		(width 0.089408)
		(layer "In9.Cu")
		(net "FM_UARTSW_MSB_N")
	)
	(segment
		(start 402.68398 -84.475828)
		(end 402.68398 -86.57082)
		(width 0.089408)
		(layer "In9.Cu")
		(net "FM_UARTSW_MSB_N")
	)
	(segment
		(start 393.091416 -96.239584)
		(end 392.78687 -96.54413)
		(width 0.089408)
		(layer "In9.Cu")
		(net "FM_UARTSW_MSB_N")
	)
	(segment
		(start 418.769038 -52.566316)
		(end 417.143692 -52.566316)
		(width 0.089408)
		(layer "In9.Cu")
		(net "FM_UARTSW_MSB_N")
	)
	(segment
		(start 421.75176 -51.000406)
		(end 421.361362 -51.390804)
		(width 0.089408)
		(layer "In9.Cu")
		(net "FM_UARTSW_MSB_N")
	)
	(segment
		(start 396.5575 -92.909136)
		(end 394.933678 -94.532958)
		(width 0.089408)
		(layer "In9.Cu")
		(net "FM_UARTSW_MSB_N")
	)
	(segment
		(start 415.758122 -54.868826)
		(end 414.521396 -56.105552)
		(width 0.089408)
		(layer "In9.Cu")
		(net "FM_UARTSW_MSB_N")
	)
	(segment
		(start 411.947614 -63.199772)
		(end 411.947614 -66.024506)
		(width 0.089408)
		(layer "In9.Cu")
		(net "FM_UARTSW_MSB_N")
	)
	(segment
		(start 409.826714 -69.515736)
		(end 409.826714 -69.782944)
		(width 0.089408)
		(layer "In9.Cu")
		(net "FM_UARTSW_MSB_N")
	)
	(segment
		(start 411.31744 -56.628538)
		(end 411.31744 -60.25007)
		(width 0.089408)
		(layer "In9.Cu")
		(net "FM_UARTSW_MSB_N")
	)
	(segment
		(start 411.822392 -56.123586)
		(end 411.31744 -56.628538)
		(width 0.089408)
		(layer "In9.Cu")
		(net "FM_UARTSW_MSB_N")
	)
	(segment
		(start 414.059624 -56.123586)
		(end 411.822392 -56.123586)
		(width 0.089408)
		(layer "In9.Cu")
		(net "FM_UARTSW_MSB_N")
	)
	(segment
		(start 401.432014 -87.088726)
		(end 396.5575 -91.96324)
		(width 0.089408)
		(layer "In9.Cu")
		(net "FM_UARTSW_MSB_N")
	)
	(segment
		(start 405.050244 -79.676244)
		(end 405.050244 -82.109564)
		(width 0.089408)
		(layer "In9.Cu")
		(net "FM_UARTSW_MSB_N")
	)
	(segment
		(start 394.933678 -94.532958)
		(end 394.472414 -94.532958)
		(width 0.089408)
		(layer "In9.Cu")
		(net "FM_UARTSW_MSB_N")
	)
	(segment
		(start 414.521396 -56.105552)
		(end 414.077658 -56.105552)
		(width 0.089408)
		(layer "In9.Cu")
		(net "FM_UARTSW_MSB_N")
	)
	(segment
		(start 404.810468 -79.436468)
		(end 405.050244 -79.676244)
		(width 0.089408)
		(layer "In9.Cu")
		(net "FM_UARTSW_MSB_N")
	)
	(segment
		(start 393.091416 -95.913956)
		(end 393.091416 -96.239584)
		(width 0.089408)
		(layer "In9.Cu")
		(net "FM_UARTSW_MSB_N")
	)
	(segment
		(start 411.467554 -67.874896)
		(end 409.826714 -69.515736)
		(width 0.089408)
		(layer "In9.Cu")
		(net "FM_UARTSW_MSB_N")
	)
	(segment
		(start 417.143692 -52.566316)
		(end 415.758122 -53.951886)
		(width 0.089408)
		(layer "In9.Cu")
		(net "FM_UARTSW_MSB_N")
	)
	(segment
		(start 405.050244 -82.109564)
		(end 402.68398 -84.475828)
		(width 0.089408)
		(layer "In9.Cu")
		(net "FM_UARTSW_MSB_N")
	)
	(segment
		(start 392.78687 -96.54413)
		(end 392.78687 -97.00387)
		(width 0.089408)
		(layer "In9.Cu")
		(net "FM_UARTSW_MSB_N")
	)
	(segment
		(start 473.366338 -114.166904)
		(end 473.564204 -114.166904)
		(width 0.089408)
		(layer "In11.Cu")
		(net "FM_UARTSW_MSB_N")
	)
	(segment
		(start 426.202094 -66.090292)
		(end 424.590464 -67.701922)
		(width 0.089408)
		(layer "In11.Cu")
		(net "FM_UARTSW_MSB_N")
	)
	(segment
		(start 494.589562 -37.870638)
		(end 493.9284 -38.5318)
		(width 0.089408)
		(layer "In11.Cu")
		(net "FM_UARTSW_MSB_N")
	)
	(segment
		(start 425.254928 -62.884304)
		(end 426.202094 -63.83147)
		(width 0.089408)
		(layer "In11.Cu")
		(net "FM_UARTSW_MSB_N")
	)
	(segment
		(start 424.59021 -77.484224)
		(end 424.59021 -78.708504)
		(width 0.089408)
		(layer "In11.Cu")
		(net "FM_UARTSW_MSB_N")
	)
	(segment
		(start 471.261694 -112.06226)
		(end 473.366338 -114.166904)
		(width 0.089408)
		(layer "In11.Cu")
		(net "FM_UARTSW_MSB_N")
	)
	(segment
		(start 424.59021 -78.708504)
		(end 424.590464 -78.708758)
		(width 0.089408)
		(layer "In11.Cu")
		(net "FM_UARTSW_MSB_N")
	)
	(segment
		(start 434.732684 -113.538508)
		(end 439.267092 -113.538508)
		(width 0.089408)
		(layer "In11.Cu")
		(net "FM_UARTSW_MSB_N")
	)
	(segment
		(start 426.202094 -63.83147)
		(end 426.202094 -66.090292)
		(width 0.089408)
		(layer "In11.Cu")
		(net "FM_UARTSW_MSB_N")
	)
	(segment
		(start 496.666266 -37.418772)
		(end 496.2144 -37.870638)
		(width 0.089408)
		(layer "In11.Cu")
		(net "FM_UARTSW_MSB_N")
	)
	(segment
		(start 424.56735 -60.19927)
		(end 425.254928 -60.886848)
		(width 0.089408)
		(layer "In11.Cu")
		(net "FM_UARTSW_MSB_N")
	)
	(segment
		(start 425.254928 -60.886848)
		(end 425.254928 -62.884304)
		(width 0.089408)
		(layer "In11.Cu")
		(net "FM_UARTSW_MSB_N")
	)
	(segment
		(start 498.953028 -37.418772)
		(end 496.666266 -37.418772)
		(width 0.089408)
		(layer "In11.Cu")
		(net "FM_UARTSW_MSB_N")
	)
	(segment
		(start 424.590464 -67.701922)
		(end 424.590464 -77.48397)
		(width 0.089408)
		(layer "In11.Cu")
		(net "FM_UARTSW_MSB_N")
	)
	(segment
		(start 425.231814 -79.585312)
		(end 425.231814 -110.146846)
		(width 0.089408)
		(layer "In11.Cu")
		(net "FM_UARTSW_MSB_N")
	)
	(segment
		(start 473.564204 -114.166904)
		(end 473.9767 -114.5794)
		(width 0.089408)
		(layer "In11.Cu")
		(net "FM_UARTSW_MSB_N")
	)
	(segment
		(start 425.231814 -110.146846)
		(end 427.027086 -111.942118)
		(width 0.089408)
		(layer "In11.Cu")
		(net "FM_UARTSW_MSB_N")
	)
	(segment
		(start 424.56735 -54.117748)
		(end 424.56735 -60.19927)
		(width 0.089408)
		(layer "In11.Cu")
		(net "FM_UARTSW_MSB_N")
	)
	(segment
		(start 421.75176 -51.000406)
		(end 421.75176 -51.302158)
		(width 0.089408)
		(layer "In11.Cu")
		(net "FM_UARTSW_MSB_N")
	)
	(segment
		(start 433.136294 -111.942118)
		(end 434.732684 -113.538508)
		(width 0.089408)
		(layer "In11.Cu")
		(net "FM_UARTSW_MSB_N")
	)
	(segment
		(start 440.74334 -112.06226)
		(end 471.261694 -112.06226)
		(width 0.089408)
		(layer "In11.Cu")
		(net "FM_UARTSW_MSB_N")
	)
	(segment
		(start 424.590464 -77.48397)
		(end 424.59021 -77.484224)
		(width 0.089408)
		(layer "In11.Cu")
		(net "FM_UARTSW_MSB_N")
	)
	(segment
		(start 439.267092 -113.538508)
		(end 440.74334 -112.06226)
		(width 0.089408)
		(layer "In11.Cu")
		(net "FM_UARTSW_MSB_N")
	)
	(segment
		(start 496.2144 -37.870638)
		(end 494.589562 -37.870638)
		(width 0.089408)
		(layer "In11.Cu")
		(net "FM_UARTSW_MSB_N")
	)
	(segment
		(start 424.590464 -78.943962)
		(end 425.231814 -79.585312)
		(width 0.089408)
		(layer "In11.Cu")
		(net "FM_UARTSW_MSB_N")
	)
	(segment
		(start 424.590464 -78.708758)
		(end 424.590464 -78.943962)
		(width 0.089408)
		(layer "In11.Cu")
		(net "FM_UARTSW_MSB_N")
	)
	(segment
		(start 421.75176 -51.302158)
		(end 424.56735 -54.117748)
		(width 0.089408)
		(layer "In11.Cu")
		(net "FM_UARTSW_MSB_N")
	)
	(segment
		(start 427.027086 -111.942118)
		(end 433.136294 -111.942118)
		(width 0.089408)
		(layer "In11.Cu")
		(net "FM_UARTSW_MSB_N")
	)
	(segment
		(start 417.64966 -49.65573)
		(end 417.864544 -49.440846)
		(width 0.10795)
		(layer "F.Cu")
		(net "FM_UARTSW_LSB_N")
	)
	(segment
		(start 416.899344 -44.440856)
		(end 416.899344 -43.614848)
		(width 0.10795)
		(layer "F.Cu")
		(net "FM_UARTSW_LSB_N")
	)
	(segment
		(start 417.03625 -43.19143)
		(end 416.83686 -42.99204)
		(width 0.10795)
		(layer "F.Cu")
		(net "FM_UARTSW_LSB_N")
	)
	(segment
		(start 390.574022 -90.8304)
		(end 390.294622 -91.1098)
		(width 0.10795)
		(layer "F.Cu")
		(net "FM_UARTSW_LSB_N")
	)
	(segment
		(start 391.904728 -90.35796)
		(end 391.879836 -90.35796)
		(width 0.10795)
		(layer "F.Cu")
		(net "FM_UARTSW_LSB_N")
	)
	(segment
		(start 416.899344 -43.614848)
		(end 417.03625 -43.477942)
		(width 0.10795)
		(layer "F.Cu")
		(net "FM_UARTSW_LSB_N")
	)
	(segment
		(start 418.21862 -45.760132)
		(end 416.899344 -44.440856)
		(width 0.10795)
		(layer "F.Cu")
		(net "FM_UARTSW_LSB_N")
	)
	(segment
		(start 390.16432 -94.10065)
		(end 390.485122 -94.421452)
		(width 0.10795)
		(layer "F.Cu")
		(net "FM_UARTSW_LSB_N")
	)
	(segment
		(start 372.973346 -82.275426)
		(end 372.00205 -81.30413)
		(width 0.1016)
		(layer "F.Cu")
		(net "FM_UARTSW_LSB_N")
	)
	(segment
		(start 417.03625 -43.477942)
		(end 417.03625 -43.19143)
		(width 0.10795)
		(layer "F.Cu")
		(net "FM_UARTSW_LSB_N")
	)
	(segment
		(start 418.21862 -46.552358)
		(end 418.21862 -45.760132)
		(width 0.10795)
		(layer "F.Cu")
		(net "FM_UARTSW_LSB_N")
	)
	(segment
		(start 416.83686 -42.99204)
		(end 416.83686 -42.681398)
		(width 0.10795)
		(layer "F.Cu")
		(net "FM_UARTSW_LSB_N")
	)
	(segment
		(start 390.294622 -93.691202)
		(end 390.16432 -93.821504)
		(width 0.10795)
		(layer "F.Cu")
		(net "FM_UARTSW_LSB_N")
	)
	(segment
		(start 500.398034 -139.019534)
		(end 501.0658 -139.6873)
		(width 0.10795)
		(layer "F.Cu")
		(net "FM_UARTSW_LSB_N")
	)
	(segment
		(start 416.83686 -42.681398)
		(end 416.690048 -42.534586)
		(width 0.10795)
		(layer "F.Cu")
		(net "FM_UARTSW_LSB_N")
	)
	(segment
		(start 372.00205 -81.30413)
		(end 372.00205 -79.837788)
		(width 0.1016)
		(layer "F.Cu")
		(net "FM_UARTSW_LSB_N")
	)
	(segment
		(start 390.294622 -91.1098)
		(end 390.294622 -93.691202)
		(width 0.10795)
		(layer "F.Cu")
		(net "FM_UARTSW_LSB_N")
	)
	(segment
		(start 390.485122 -94.421452)
		(end 390.485122 -94.790006)
		(width 0.10795)
		(layer "F.Cu")
		(net "FM_UARTSW_LSB_N")
	)
	(segment
		(start 417.864544 -49.440846)
		(end 417.864544 -49.099978)
		(width 0.10795)
		(layer "F.Cu")
		(net "FM_UARTSW_LSB_N")
	)
	(segment
		(start 372.00205 -79.837788)
		(end 372.34495 -79.494888)
		(width 0.1016)
		(layer "F.Cu")
		(net "FM_UARTSW_LSB_N")
	)
	(segment
		(start 417.64966 -49.881282)
		(end 417.64966 -49.65573)
		(width 0.10795)
		(layer "F.Cu")
		(net "FM_UARTSW_LSB_N")
	)
	(segment
		(start 418.37102 -47.418752)
		(end 418.37102 -46.704758)
		(width 0.10795)
		(layer "F.Cu")
		(net "FM_UARTSW_LSB_N")
	)
	(segment
		(start 417.88588 -49.078642)
		(end 417.88588 -47.903892)
		(width 0.10795)
		(layer "F.Cu")
		(net "FM_UARTSW_LSB_N")
	)
	(segment
		(start 500.398034 -138.678666)
		(end 500.398034 -139.019534)
		(width 0.10795)
		(layer "F.Cu")
		(net "FM_UARTSW_LSB_N")
	)
	(segment
		(start 417.864544 -49.099978)
		(end 417.88588 -49.078642)
		(width 0.10795)
		(layer "F.Cu")
		(net "FM_UARTSW_LSB_N")
	)
	(segment
		(start 418.37102 -46.704758)
		(end 418.21862 -46.552358)
		(width 0.10795)
		(layer "F.Cu")
		(net "FM_UARTSW_LSB_N")
	)
	(segment
		(start 390.16432 -93.821504)
		(end 390.16432 -94.10065)
		(width 0.10795)
		(layer "F.Cu")
		(net "FM_UARTSW_LSB_N")
	)
	(segment
		(start 417.88588 -47.903892)
		(end 418.37102 -47.418752)
		(width 0.10795)
		(layer "F.Cu")
		(net "FM_UARTSW_LSB_N")
	)
	(segment
		(start 372.973346 -82.53222)
		(end 372.973346 -82.275426)
		(width 0.1016)
		(layer "F.Cu")
		(net "FM_UARTSW_LSB_N")
	)
	(segment
		(start 391.879836 -90.35796)
		(end 391.879836 -90.555064)
		(width 0.10795)
		(layer "F.Cu")
		(net "FM_UARTSW_LSB_N")
	)
	(segment
		(start 391.879836 -90.555064)
		(end 391.6045 -90.8304)
		(width 0.10795)
		(layer "F.Cu")
		(net "FM_UARTSW_LSB_N")
	)
	(segment
		(start 391.6045 -90.8304)
		(end 390.574022 -90.8304)
		(width 0.10795)
		(layer "F.Cu")
		(net "FM_UARTSW_LSB_N")
	)
	(via
		(at 391.904728 -90.35796)
		(size 0.508)
		(drill 0.254)
		(layers "F.Cu" "B.Cu")
		(net "FM_UARTSW_LSB_N")
	)
	(via
		(at 402.0312 -79.2734)
		(size 0.508)
		(drill 0.254)
		(layers "F.Cu" "B.Cu")
		(net "FM_UARTSW_LSB_N")
	)
	(via
		(at 417.64966 -49.881282)
		(size 0.508)
		(drill 0.254)
		(layers "F.Cu" "B.Cu")
		(net "FM_UARTSW_LSB_N")
	)
	(via
		(at 372.973346 -82.53222)
		(size 0.508)
		(drill 0.254)
		(layers "F.Cu" "B.Cu")
		(net "FM_UARTSW_LSB_N")
	)
	(via
		(at 501.143016 -36.35248)
		(size 0.508)
		(drill 0.254)
		(layers "F.Cu" "B.Cu")
		(net "FM_UARTSW_LSB_N")
	)
	(via
		(at 493.930686 -37.892736)
		(size 0.508)
		(drill 0.254)
		(layers "F.Cu" "B.Cu")
		(net "FM_UARTSW_LSB_N")
	)
	(via
		(at 501.0658 -139.6873)
		(size 0.508)
		(drill 0.254)
		(layers "F.Cu" "B.Cu")
		(net "FM_UARTSW_LSB_N")
	)
	(via
		(at 393.261342 -79.559658)
		(size 0.508)
		(drill 0.254)
		(layers "F.Cu" "B.Cu")
		(net "FM_UARTSW_LSB_N")
	)
	(segment
		(start 493.930686 -37.892736)
		(end 494.3602 -37.463222)
		(width 0.10795)
		(layer "B.Cu")
		(net "FM_UARTSW_LSB_N")
	)
	(segment
		(start 501.143016 -36.35248)
		(end 500.96547 -36.35248)
		(width 0.10795)
		(layer "B.Cu")
		(net "FM_UARTSW_LSB_N")
	)
	(segment
		(start 500.86006 -36.45789)
		(end 499.967504 -36.45789)
		(width 0.10795)
		(layer "B.Cu")
		(net "FM_UARTSW_LSB_N")
	)
	(segment
		(start 494.152936 -36.444936)
		(end 493.251998 -36.444936)
		(width 0.10795)
		(layer "B.Cu")
		(net "FM_UARTSW_LSB_N")
	)
	(segment
		(start 500.96547 -36.35248)
		(end 500.86006 -36.45789)
		(width 0.10795)
		(layer "B.Cu")
		(net "FM_UARTSW_LSB_N")
	)
	(segment
		(start 494.3602 -37.463222)
		(end 494.3602 -36.6522)
		(width 0.10795)
		(layer "B.Cu")
		(net "FM_UARTSW_LSB_N")
	)
	(segment
		(start 494.3602 -36.6522)
		(end 494.152936 -36.444936)
		(width 0.10795)
		(layer "B.Cu")
		(net "FM_UARTSW_LSB_N")
	)
	(segment
		(start 490.584236 -56.2356)
		(end 491.610396 -55.20944)
		(width 0.089408)
		(layer "In2.Cu")
		(net "FM_UARTSW_LSB_N")
	)
	(segment
		(start 424.825668 -50.353468)
		(end 425.732956 -50.353468)
		(width 0.089408)
		(layer "In2.Cu")
		(net "FM_UARTSW_LSB_N")
	)
	(segment
		(start 432.050698 -51.834542)
		(end 434.796438 -51.834542)
		(width 0.089408)
		(layer "In2.Cu")
		(net "FM_UARTSW_LSB_N")
	)
	(segment
		(start 463.628232 -66.682366)
		(end 465.307172 -66.682366)
		(width 0.089408)
		(layer "In2.Cu")
		(net "FM_UARTSW_LSB_N")
	)
	(segment
		(start 493.528096 -38.697662)
		(end 493.528096 -38.295326)
		(width 0.089408)
		(layer "In2.Cu")
		(net "FM_UARTSW_LSB_N")
	)
	(segment
		(start 428.689008 -51.834542)
		(end 430.642268 -51.834542)
		(width 0.089408)
		(layer "In2.Cu")
		(net "FM_UARTSW_LSB_N")
	)
	(segment
		(start 469.829388 -48.934624)
		(end 470.31529 -48.448722)
		(width 0.089408)
		(layer "In2.Cu")
		(net "FM_UARTSW_LSB_N")
	)
	(segment
		(start 490.728 -48.836834)
		(end 493.913414 -45.65142)
		(width 0.089408)
		(layer "In2.Cu")
		(net "FM_UARTSW_LSB_N")
	)
	(segment
		(start 494.693702 -38.927786)
		(end 494.693702 -38.655752)
		(width 0.089408)
		(layer "In2.Cu")
		(net "FM_UARTSW_LSB_N")
	)
	(segment
		(start 426.701458 -79.003398)
		(end 426.701458 -78.245716)
		(width 0.089408)
		(layer "In2.Cu")
		(net "FM_UARTSW_LSB_N")
	)
	(segment
		(start 434.796438 -51.834542)
		(end 434.796692 -51.834796)
		(width 0.089408)
		(layer "In2.Cu")
		(net "FM_UARTSW_LSB_N")
	)
	(segment
		(start 418.771578 -48.533812)
		(end 424.202606 -48.533812)
		(width 0.089408)
		(layer "In2.Cu")
		(net "FM_UARTSW_LSB_N")
	)
	(segment
		(start 484.491538 -111.195104)
		(end 483.846124 -110.54969)
		(width 0.089408)
		(layer "In2.Cu")
		(net "FM_UARTSW_LSB_N")
	)
	(segment
		(start 425.389802 -75.165966)
		(end 425.389802 -68.483734)
		(width 0.089408)
		(layer "In2.Cu")
		(net "FM_UARTSW_LSB_N")
	)
	(segment
		(start 426.08119 -75.857354)
		(end 425.389802 -75.165966)
		(width 0.089408)
		(layer "In2.Cu")
		(net "FM_UARTSW_LSB_N")
	)
	(segment
		(start 494.851944 -39.086028)
		(end 494.693702 -38.927786)
		(width 0.089408)
		(layer "In2.Cu")
		(net "FM_UARTSW_LSB_N")
	)
	(segment
		(start 426.701458 -109.49559)
		(end 426.701458 -80.841342)
		(width 0.089408)
		(layer "In2.Cu")
		(net "FM_UARTSW_LSB_N")
	)
	(segment
		(start 480.99472 -46.09592)
		(end 492.857536 -46.09592)
		(width 0.089408)
		(layer "In2.Cu")
		(net "FM_UARTSW_LSB_N")
	)
	(segment
		(start 479.51644 -61.318648)
		(end 484.603552 -61.318648)
		(width 0.089408)
		(layer "In2.Cu")
		(net "FM_UARTSW_LSB_N")
	)
	(segment
		(start 493.913414 -45.65142)
		(end 494.26114 -45.65142)
		(width 0.089408)
		(layer "In2.Cu")
		(net "FM_UARTSW_LSB_N")
	)
	(segment
		(start 426.701458 -78.245716)
		(end 426.08119 -77.625448)
		(width 0.089408)
		(layer "In2.Cu")
		(net "FM_UARTSW_LSB_N")
	)
	(segment
		(start 426.08119 -77.625448)
		(end 426.08119 -75.857354)
		(width 0.089408)
		(layer "In2.Cu")
		(net "FM_UARTSW_LSB_N")
	)
	(segment
		(start 500.6721 -132.073142)
		(end 501.08612 -131.659122)
		(width 0.089408)
		(layer "In2.Cu")
		(net "FM_UARTSW_LSB_N")
	)
	(segment
		(start 465.307426 -66.682112)
		(end 474.152976 -66.682112)
		(width 0.089408)
		(layer "In2.Cu")
		(net "FM_UARTSW_LSB_N")
	)
	(segment
		(start 424.7134 -50.2412)
		(end 424.825668 -50.353468)
		(width 0.089408)
		(layer "In2.Cu")
		(net "FM_UARTSW_LSB_N")
	)
	(segment
		(start 434.796692 -51.834796)
		(end 436.36057 -51.834796)
		(width 0.089408)
		(layer "In2.Cu")
		(net "FM_UARTSW_LSB_N")
	)
	(segment
		(start 427.755558 -110.54969)
		(end 426.701458 -109.49559)
		(width 0.089408)
		(layer "In2.Cu")
		(net "FM_UARTSW_LSB_N")
	)
	(segment
		(start 425.389802 -68.483734)
		(end 427.191424 -66.682112)
		(width 0.089408)
		(layer "In2.Cu")
		(net "FM_UARTSW_LSB_N")
	)
	(segment
		(start 427.191424 -66.682112)
		(end 463.627978 -66.682112)
		(width 0.089408)
		(layer "In2.Cu")
		(net "FM_UARTSW_LSB_N")
	)
	(segment
		(start 471.844878 -48.448722)
		(end 472.905836 -47.387764)
		(width 0.089408)
		(layer "In2.Cu")
		(net "FM_UARTSW_LSB_N")
	)
	(segment
		(start 463.627978 -66.682112)
		(end 463.628232 -66.682366)
		(width 0.089408)
		(layer "In2.Cu")
		(net "FM_UARTSW_LSB_N")
	)
	(segment
		(start 501.08612 -114.86388)
		(end 497.417344 -111.195104)
		(width 0.089408)
		(layer "In2.Cu")
		(net "FM_UARTSW_LSB_N")
	)
	(segment
		(start 428.688754 -51.834796)
		(end 428.689008 -51.834542)
		(width 0.089408)
		(layer "In2.Cu")
		(net "FM_UARTSW_LSB_N")
	)
	(segment
		(start 465.307172 -66.682366)
		(end 465.307426 -66.682112)
		(width 0.089408)
		(layer "In2.Cu")
		(net "FM_UARTSW_LSB_N")
	)
	(segment
		(start 470.31529 -48.448722)
		(end 471.844878 -48.448722)
		(width 0.089408)
		(layer "In2.Cu")
		(net "FM_UARTSW_LSB_N")
	)
	(segment
		(start 494.469928 -39.639494)
		(end 493.528096 -38.697662)
		(width 0.089408)
		(layer "In2.Cu")
		(net "FM_UARTSW_LSB_N")
	)
	(segment
		(start 427.214284 -51.834796)
		(end 428.688754 -51.834796)
		(width 0.089408)
		(layer "In2.Cu")
		(net "FM_UARTSW_LSB_N")
	)
	(segment
		(start 494.102644 -45.269404)
		(end 494.469928 -44.90212)
		(width 0.089408)
		(layer "In2.Cu")
		(net "FM_UARTSW_LSB_N")
	)
	(segment
		(start 477.4438 -46.489366)
		(end 477.4438 -45.247052)
		(width 0.089408)
		(layer "In2.Cu")
		(net "FM_UARTSW_LSB_N")
	)
	(segment
		(start 430.642522 -51.834796)
		(end 432.050444 -51.834796)
		(width 0.089408)
		(layer "In2.Cu")
		(net "FM_UARTSW_LSB_N")
	)
	(segment
		(start 490.728 -49.811178)
		(end 490.728 -48.836834)
		(width 0.089408)
		(layer "In2.Cu")
		(net "FM_UARTSW_LSB_N")
	)
	(segment
		(start 439.260742 -48.934624)
		(end 469.829388 -48.934624)
		(width 0.089408)
		(layer "In2.Cu")
		(net "FM_UARTSW_LSB_N")
	)
	(segment
		(start 490.196378 -50.3428)
		(end 490.728 -49.811178)
		(width 0.089408)
		(layer "In2.Cu")
		(net "FM_UARTSW_LSB_N")
	)
	(segment
		(start 426.701458 -80.841342)
		(end 426.701712 -80.841088)
		(width 0.089408)
		(layer "In2.Cu")
		(net "FM_UARTSW_LSB_N")
	)
	(segment
		(start 430.642268 -51.834542)
		(end 430.642522 -51.834796)
		(width 0.089408)
		(layer "In2.Cu")
		(net "FM_UARTSW_LSB_N")
	)
	(segment
		(start 497.417344 -111.195104)
		(end 484.491538 -111.195104)
		(width 0.089408)
		(layer "In2.Cu")
		(net "FM_UARTSW_LSB_N")
	)
	(segment
		(start 489.6866 -56.2356)
		(end 490.584236 -56.2356)
		(width 0.089408)
		(layer "In2.Cu")
		(net "FM_UARTSW_LSB_N")
	)
	(segment
		(start 494.693702 -38.655752)
		(end 493.930686 -37.892736)
		(width 0.089408)
		(layer "In2.Cu")
		(net "FM_UARTSW_LSB_N")
	)
	(segment
		(start 491.610396 -52.42814)
		(end 490.196378 -51.014122)
		(width 0.089408)
		(layer "In2.Cu")
		(net "FM_UARTSW_LSB_N")
	)
	(segment
		(start 424.7134 -49.044606)
		(end 424.7134 -50.2412)
		(width 0.089408)
		(layer "In2.Cu")
		(net "FM_UARTSW_LSB_N")
	)
	(segment
		(start 494.851944 -45.060616)
		(end 494.851944 -39.086028)
		(width 0.089408)
		(layer "In2.Cu")
		(net "FM_UARTSW_LSB_N")
	)
	(segment
		(start 483.846124 -110.54969)
		(end 427.755558 -110.54969)
		(width 0.089408)
		(layer "In2.Cu")
		(net "FM_UARTSW_LSB_N")
	)
	(segment
		(start 494.469928 -44.90212)
		(end 494.469928 -39.639494)
		(width 0.089408)
		(layer "In2.Cu")
		(net "FM_UARTSW_LSB_N")
	)
	(segment
		(start 493.528096 -38.295326)
		(end 493.930686 -37.892736)
		(width 0.089408)
		(layer "In2.Cu")
		(net "FM_UARTSW_LSB_N")
	)
	(segment
		(start 500.6721 -139.2936)
		(end 500.6721 -132.073142)
		(width 0.089408)
		(layer "In2.Cu")
		(net "FM_UARTSW_LSB_N")
	)
	(segment
		(start 484.603552 -61.318648)
		(end 489.6866 -56.2356)
		(width 0.089408)
		(layer "In2.Cu")
		(net "FM_UARTSW_LSB_N")
	)
	(segment
		(start 426.701966 -79.003906)
		(end 426.701458 -79.003398)
		(width 0.089408)
		(layer "In2.Cu")
		(net "FM_UARTSW_LSB_N")
	)
	(segment
		(start 417.64966 -49.881282)
		(end 417.64966 -49.65573)
		(width 0.089408)
		(layer "In2.Cu")
		(net "FM_UARTSW_LSB_N")
	)
	(segment
		(start 493.684052 -45.269404)
		(end 494.102644 -45.269404)
		(width 0.089408)
		(layer "In2.Cu")
		(net "FM_UARTSW_LSB_N")
	)
	(segment
		(start 477.4438 -45.247052)
		(end 478.352358 -44.338494)
		(width 0.089408)
		(layer "In2.Cu")
		(net "FM_UARTSW_LSB_N")
	)
	(segment
		(start 425.732956 -50.353468)
		(end 427.214284 -51.834796)
		(width 0.089408)
		(layer "In2.Cu")
		(net "FM_UARTSW_LSB_N")
	)
	(segment
		(start 426.701966 -80.682846)
		(end 426.701966 -79.003906)
		(width 0.089408)
		(layer "In2.Cu")
		(net "FM_UARTSW_LSB_N")
	)
	(segment
		(start 472.905836 -47.387764)
		(end 476.545402 -47.387764)
		(width 0.089408)
		(layer "In2.Cu")
		(net "FM_UARTSW_LSB_N")
	)
	(segment
		(start 424.202606 -48.533812)
		(end 424.7134 -49.044606)
		(width 0.089408)
		(layer "In2.Cu")
		(net "FM_UARTSW_LSB_N")
	)
	(segment
		(start 432.050444 -51.834796)
		(end 432.050698 -51.834542)
		(width 0.089408)
		(layer "In2.Cu")
		(net "FM_UARTSW_LSB_N")
	)
	(segment
		(start 426.701712 -80.841088)
		(end 426.701712 -80.6831)
		(width 0.089408)
		(layer "In2.Cu")
		(net "FM_UARTSW_LSB_N")
	)
	(segment
		(start 494.26114 -45.65142)
		(end 494.851944 -45.060616)
		(width 0.089408)
		(layer "In2.Cu")
		(net "FM_UARTSW_LSB_N")
	)
	(segment
		(start 501.08612 -131.659122)
		(end 501.08612 -114.86388)
		(width 0.089408)
		(layer "In2.Cu")
		(net "FM_UARTSW_LSB_N")
	)
	(segment
		(start 491.610396 -55.20944)
		(end 491.610396 -52.42814)
		(width 0.089408)
		(layer "In2.Cu")
		(net "FM_UARTSW_LSB_N")
	)
	(segment
		(start 478.352358 -44.338494)
		(end 479.237294 -44.338494)
		(width 0.089408)
		(layer "In2.Cu")
		(net "FM_UARTSW_LSB_N")
	)
	(segment
		(start 492.857536 -46.09592)
		(end 493.684052 -45.269404)
		(width 0.089408)
		(layer "In2.Cu")
		(net "FM_UARTSW_LSB_N")
	)
	(segment
		(start 476.545402 -47.387764)
		(end 477.4438 -46.489366)
		(width 0.089408)
		(layer "In2.Cu")
		(net "FM_UARTSW_LSB_N")
	)
	(segment
		(start 426.701712 -80.6831)
		(end 426.701966 -80.682846)
		(width 0.089408)
		(layer "In2.Cu")
		(net "FM_UARTSW_LSB_N")
	)
	(segment
		(start 474.152976 -66.682112)
		(end 479.51644 -61.318648)
		(width 0.089408)
		(layer "In2.Cu")
		(net "FM_UARTSW_LSB_N")
	)
	(segment
		(start 436.36057 -51.834796)
		(end 439.260742 -48.934624)
		(width 0.089408)
		(layer "In2.Cu")
		(net "FM_UARTSW_LSB_N")
	)
	(segment
		(start 417.64966 -49.65573)
		(end 418.771578 -48.533812)
		(width 0.089408)
		(layer "In2.Cu")
		(net "FM_UARTSW_LSB_N")
	)
	(segment
		(start 479.237294 -44.338494)
		(end 480.99472 -46.09592)
		(width 0.089408)
		(layer "In2.Cu")
		(net "FM_UARTSW_LSB_N")
	)
	(segment
		(start 501.0658 -139.6873)
		(end 500.6721 -139.2936)
		(width 0.089408)
		(layer "In2.Cu")
		(net "FM_UARTSW_LSB_N")
	)
	(segment
		(start 490.196378 -51.014122)
		(end 490.196378 -50.3428)
		(width 0.089408)
		(layer "In2.Cu")
		(net "FM_UARTSW_LSB_N")
	)
	(segment
		(start 393.261342 -79.559658)
		(end 393.34186 -79.640176)
		(width 0.089408)
		(layer "In4.Cu")
		(net "FM_UARTSW_LSB_N")
	)
	(segment
		(start 372.973346 -82.717894)
		(end 372.973346 -82.53222)
		(width 0.089408)
		(layer "In4.Cu")
		(net "FM_UARTSW_LSB_N")
	)
	(segment
		(start 396.739872 -80.655414)
		(end 398.71142 -80.655414)
		(width 0.089408)
		(layer "In4.Cu")
		(net "FM_UARTSW_LSB_N")
	)
	(segment
		(start 388.20217 -82.586576)
		(end 386.625084 -82.586576)
		(width 0.089408)
		(layer "In4.Cu")
		(net "FM_UARTSW_LSB_N")
	)
	(segment
		(start 400.093434 -79.2734)
		(end 402.0312 -79.2734)
		(width 0.089408)
		(layer "In4.Cu")
		(net "FM_UARTSW_LSB_N")
	)
	(segment
		(start 392.3284 -80.361028)
		(end 392.3284 -80.846422)
		(width 0.089408)
		(layer "In4.Cu")
		(net "FM_UARTSW_LSB_N")
	)
	(segment
		(start 373.531638 -83.276186)
		(end 372.973346 -82.717894)
		(width 0.089408)
		(layer "In4.Cu")
		(net "FM_UARTSW_LSB_N")
	)
	(segment
		(start 395.724634 -79.640176)
		(end 396.739872 -80.655414)
		(width 0.089408)
		(layer "In4.Cu")
		(net "FM_UARTSW_LSB_N")
	)
	(segment
		(start 378.47778 -83.8962)
		(end 377.857766 -83.276186)
		(width 0.089408)
		(layer "In4.Cu")
		(net "FM_UARTSW_LSB_N")
	)
	(segment
		(start 380.655576 -82.742024)
		(end 379.5014 -83.8962)
		(width 0.089408)
		(layer "In4.Cu")
		(net "FM_UARTSW_LSB_N")
	)
	(segment
		(start 393.34186 -79.640176)
		(end 395.724634 -79.640176)
		(width 0.089408)
		(layer "In4.Cu")
		(net "FM_UARTSW_LSB_N")
	)
	(segment
		(start 377.857766 -83.276186)
		(end 373.531638 -83.276186)
		(width 0.089408)
		(layer "In4.Cu")
		(net "FM_UARTSW_LSB_N")
	)
	(segment
		(start 393.13231 -79.557118)
		(end 392.3284 -80.361028)
		(width 0.089408)
		(layer "In4.Cu")
		(net "FM_UARTSW_LSB_N")
	)
	(segment
		(start 398.71142 -80.655414)
		(end 400.093434 -79.2734)
		(width 0.089408)
		(layer "In4.Cu")
		(net "FM_UARTSW_LSB_N")
	)
	(segment
		(start 392.3284 -80.846422)
		(end 391.20191 -81.972912)
		(width 0.089408)
		(layer "In4.Cu")
		(net "FM_UARTSW_LSB_N")
	)
	(segment
		(start 379.5014 -83.8962)
		(end 378.47778 -83.8962)
		(width 0.089408)
		(layer "In4.Cu")
		(net "FM_UARTSW_LSB_N")
	)
	(segment
		(start 393.261342 -79.559658)
		(end 393.258802 -79.557118)
		(width 0.089408)
		(layer "In4.Cu")
		(net "FM_UARTSW_LSB_N")
	)
	(segment
		(start 393.258802 -79.557118)
		(end 393.13231 -79.557118)
		(width 0.089408)
		(layer "In4.Cu")
		(net "FM_UARTSW_LSB_N")
	)
	(segment
		(start 386.469636 -82.742024)
		(end 380.655576 -82.742024)
		(width 0.089408)
		(layer "In4.Cu")
		(net "FM_UARTSW_LSB_N")
	)
	(segment
		(start 386.625084 -82.586576)
		(end 386.469636 -82.742024)
		(width 0.089408)
		(layer "In4.Cu")
		(net "FM_UARTSW_LSB_N")
	)
	(segment
		(start 388.815834 -81.972912)
		(end 388.20217 -82.586576)
		(width 0.089408)
		(layer "In4.Cu")
		(net "FM_UARTSW_LSB_N")
	)
	(segment
		(start 391.20191 -81.972912)
		(end 388.815834 -81.972912)
		(width 0.089408)
		(layer "In4.Cu")
		(net "FM_UARTSW_LSB_N")
	)
	(segment
		(start 417.64966 -49.881282)
		(end 417.64966 -50.28184)
		(width 0.089408)
		(layer "In9.Cu")
		(net "FM_UARTSW_LSB_N")
	)
	(segment
		(start 409.592272 -55.99049)
		(end 409.592272 -60.888118)
		(width 0.089408)
		(layer "In9.Cu")
		(net "FM_UARTSW_LSB_N")
	)
	(segment
		(start 416.84448 -51.08702)
		(end 414.495742 -51.08702)
		(width 0.089408)
		(layer "In9.Cu")
		(net "FM_UARTSW_LSB_N")
	)
	(segment
		(start 402.800312 -74.44613)
		(end 402.800312 -77.462888)
		(width 0.089408)
		(layer "In9.Cu")
		(net "FM_UARTSW_LSB_N")
	)
	(segment
		(start 407.079196 -69.900038)
		(end 407.079196 -70.167246)
		(width 0.089408)
		(layer "In9.Cu")
		(net "FM_UARTSW_LSB_N")
	)
	(segment
		(start 402.800312 -77.462888)
		(end 402.0312 -78.232)
		(width 0.089408)
		(layer "In9.Cu")
		(net "FM_UARTSW_LSB_N")
	)
	(segment
		(start 409.79725 -67.181984)
		(end 407.079196 -69.900038)
		(width 0.089408)
		(layer "In9.Cu")
		(net "FM_UARTSW_LSB_N")
	)
	(segment
		(start 402.0312 -78.232)
		(end 402.0312 -79.2734)
		(width 0.089408)
		(layer "In9.Cu")
		(net "FM_UARTSW_LSB_N")
	)
	(segment
		(start 407.079196 -70.167246)
		(end 402.800312 -74.44613)
		(width 0.089408)
		(layer "In9.Cu")
		(net "FM_UARTSW_LSB_N")
	)
	(segment
		(start 409.79725 -61.093096)
		(end 409.79725 -67.181984)
		(width 0.089408)
		(layer "In9.Cu")
		(net "FM_UARTSW_LSB_N")
	)
	(segment
		(start 414.495742 -51.08702)
		(end 409.592272 -55.99049)
		(width 0.089408)
		(layer "In9.Cu")
		(net "FM_UARTSW_LSB_N")
	)
	(segment
		(start 409.592272 -60.888118)
		(end 409.79725 -61.093096)
		(width 0.089408)
		(layer "In9.Cu")
		(net "FM_UARTSW_LSB_N")
	)
	(segment
		(start 417.64966 -50.28184)
		(end 416.84448 -51.08702)
		(width 0.089408)
		(layer "In9.Cu")
		(net "FM_UARTSW_LSB_N")
	)
	(segment
		(start 393.8778 -80.176116)
		(end 393.261342 -79.559658)
		(width 0.089408)
		(layer "In11.Cu")
		(net "FM_UARTSW_LSB_N")
	)
	(segment
		(start 391.879836 -90.35796)
		(end 391.879836 -90.22334)
		(width 0.089408)
		(layer "In11.Cu")
		(net "FM_UARTSW_LSB_N")
	)
	(segment
		(start 391.3886 -84.295488)
		(end 392.876532 -82.807556)
		(width 0.089408)
		(layer "In11.Cu")
		(net "FM_UARTSW_LSB_N")
	)
	(segment
		(start 493.930686 -37.892736)
		(end 494.917222 -36.9062)
		(width 0.089408)
		(layer "In11.Cu")
		(net "FM_UARTSW_LSB_N")
	)
	(segment
		(start 393.110974 -82.275934)
		(end 393.408154 -82.275934)
		(width 0.089408)
		(layer "In11.Cu")
		(net "FM_UARTSW_LSB_N")
	)
	(segment
		(start 391.3886 -89.732104)
		(end 391.3886 -84.295488)
		(width 0.089408)
		(layer "In11.Cu")
		(net "FM_UARTSW_LSB_N")
	)
	(segment
		(start 393.614656 -81.153)
		(end 393.8778 -80.889856)
		(width 0.089408)
		(layer "In11.Cu")
		(net "FM_UARTSW_LSB_N")
	)
	(segment
		(start 495.704622 -36.9062)
		(end 500.589296 -36.9062)
		(width 0.089408)
		(layer "In11.Cu")
		(net "FM_UARTSW_LSB_N")
	)
	(segment
		(start 393.408154 -82.275934)
		(end 393.614656 -82.069432)
		(width 0.089408)
		(layer "In11.Cu")
		(net "FM_UARTSW_LSB_N")
	)
	(segment
		(start 494.917222 -36.9062)
		(end 495.36985 -36.9062)
		(width 0.089408)
		(layer "In11.Cu")
		(net "FM_UARTSW_LSB_N")
	)
	(segment
		(start 500.589296 -36.9062)
		(end 501.143016 -36.35248)
		(width 0.089408)
		(layer "In11.Cu")
		(net "FM_UARTSW_LSB_N")
	)
	(segment
		(start 495.371374 -36.907724)
		(end 495.703098 -36.907724)
		(width 0.089408)
		(layer "In11.Cu")
		(net "FM_UARTSW_LSB_N")
	)
	(segment
		(start 495.36985 -36.9062)
		(end 495.371374 -36.907724)
		(width 0.089408)
		(layer "In11.Cu")
		(net "FM_UARTSW_LSB_N")
	)
	(segment
		(start 392.876532 -82.510376)
		(end 393.110974 -82.275934)
		(width 0.089408)
		(layer "In11.Cu")
		(net "FM_UARTSW_LSB_N")
	)
	(segment
		(start 391.904728 -90.35796)
		(end 391.879836 -90.35796)
		(width 0.089408)
		(layer "In11.Cu")
		(net "FM_UARTSW_LSB_N")
	)
	(segment
		(start 393.614656 -82.069432)
		(end 393.614656 -81.153)
		(width 0.089408)
		(layer "In11.Cu")
		(net "FM_UARTSW_LSB_N")
	)
	(segment
		(start 495.703098 -36.907724)
		(end 495.704622 -36.9062)
		(width 0.089408)
		(layer "In11.Cu")
		(net "FM_UARTSW_LSB_N")
	)
	(segment
		(start 393.8778 -80.889856)
		(end 393.8778 -80.176116)
		(width 0.089408)
		(layer "In11.Cu")
		(net "FM_UARTSW_LSB_N")
	)
	(segment
		(start 391.879836 -90.22334)
		(end 391.3886 -89.732104)
		(width 0.089408)
		(layer "In11.Cu")
		(net "FM_UARTSW_LSB_N")
	)
	(segment
		(start 392.876532 -82.807556)
		(end 392.876532 -82.510376)
		(width 0.089408)
		(layer "In11.Cu")
		(net "FM_UARTSW_LSB_N")
	)
	(segment
		(start 384.76555 -96.9772)
		(end 385.26085 -96.747076)
		(width 0.10795)
		(layer "F.Cu")
		(net "FM_OCP_MEZZB_PRES_1V05_PCH_N")
	)
	(segment
		(start 402.5138 -51.6636)
		(end 404.62708 -53.77688)
		(width 0.10795)
		(layer "F.Cu")
		(net "FM_OCP_MEZZB_PRES_1V05_PCH_N")
	)
	(segment
		(start 404.62708 -53.77688)
		(end 404.62708 -54.642766)
		(width 0.10795)
		(layer "F.Cu")
		(net "FM_OCP_MEZZB_PRES_1V05_PCH_N")
	)
	(segment
		(start 396.1638 -51.6636)
		(end 402.5138 -51.6636)
		(width 0.10795)
		(layer "F.Cu")
		(net "FM_OCP_MEZZB_PRES_1V05_PCH_N")
	)
	(segment
		(start 395.732 -52.0954)
		(end 396.1638 -51.6636)
		(width 0.10795)
		(layer "F.Cu")
		(net "FM_OCP_MEZZB_PRES_1V05_PCH_N")
	)
	(via
		(at 404.62708 -54.642766)
		(size 0.508)
		(drill 0.254)
		(layers "F.Cu" "B.Cu")
		(net "FM_OCP_MEZZB_PRES_1V05_PCH_N")
	)
	(via
		(at 395.732 -52.0954)
		(size 0.508)
		(drill 0.254)
		(layers "F.Cu" "B.Cu")
		(net "FM_OCP_MEZZB_PRES_1V05_PCH_N")
	)
	(via
		(at 384.856482 -94.5896)
		(size 0.6604)
		(drill 0.3302)
		(layers "F.Cu" "B.Cu")
		(net "FM_OCP_MEZZB_PRES_1V05_PCH_N")
	)
	(via
		(at 385.26085 -96.747076)
		(size 0.508)
		(drill 0.254)
		(layers "F.Cu" "B.Cu")
		(net "FM_OCP_MEZZB_PRES_1V05_PCH_N")
	)
	(segment
		(start 385.43738 -86.29904)
		(end 385.813808 -85.922612)
		(width 0.10795)
		(layer "B.Cu")
		(net "FM_OCP_MEZZB_PRES_1V05_PCH_N")
	)
	(segment
		(start 384.6449 -86.6648)
		(end 385.01066 -86.29904)
		(width 0.10795)
		(layer "B.Cu")
		(net "FM_OCP_MEZZB_PRES_1V05_PCH_N")
	)
	(segment
		(start 384.856482 -95.159322)
		(end 385.02844 -95.33128)
		(width 0.10795)
		(layer "B.Cu")
		(net "FM_OCP_MEZZB_PRES_1V05_PCH_N")
	)
	(segment
		(start 383.97942 -89.793318)
		(end 384.6449 -89.127838)
		(width 0.10795)
		(layer "B.Cu")
		(net "FM_OCP_MEZZB_PRES_1V05_PCH_N")
	)
	(segment
		(start 385.813808 -85.922612)
		(end 385.813808 -85.618828)
		(width 0.10795)
		(layer "B.Cu")
		(net "FM_OCP_MEZZB_PRES_1V05_PCH_N")
	)
	(segment
		(start 385.42976 -97.040192)
		(end 385.26085 -96.747076)
		(width 0.0889)
		(layer "B.Cu")
		(net "FM_OCP_MEZZB_PRES_1V05_PCH_N")
	)
	(segment
		(start 385.01066 -86.29904)
		(end 385.43738 -86.29904)
		(width 0.10795)
		(layer "B.Cu")
		(net "FM_OCP_MEZZB_PRES_1V05_PCH_N")
	)
	(segment
		(start 383.97942 -92.947998)
		(end 383.97942 -89.793318)
		(width 0.10795)
		(layer "B.Cu")
		(net "FM_OCP_MEZZB_PRES_1V05_PCH_N")
	)
	(segment
		(start 385.5085 -97.061274)
		(end 385.42976 -97.040192)
		(width 0.0889)
		(layer "B.Cu")
		(net "FM_OCP_MEZZB_PRES_1V05_PCH_N")
	)
	(segment
		(start 404.62708 -54.15407)
		(end 404.93315 -53.848)
		(width 0.10795)
		(layer "B.Cu")
		(net "FM_OCP_MEZZB_PRES_1V05_PCH_N")
	)
	(segment
		(start 384.856482 -94.5896)
		(end 384.856482 -93.82506)
		(width 0.10795)
		(layer "B.Cu")
		(net "FM_OCP_MEZZB_PRES_1V05_PCH_N")
	)
	(segment
		(start 404.93315 -53.848)
		(end 405.404828 -53.848)
		(width 0.10795)
		(layer "B.Cu")
		(net "FM_OCP_MEZZB_PRES_1V05_PCH_N")
	)
	(segment
		(start 385.02844 -95.33128)
		(end 385.1656 -95.46844)
		(width 0.0889)
		(layer "B.Cu")
		(net "FM_OCP_MEZZB_PRES_1V05_PCH_N")
	)
	(segment
		(start 384.856482 -94.5896)
		(end 384.856482 -95.159322)
		(width 0.10795)
		(layer "B.Cu")
		(net "FM_OCP_MEZZB_PRES_1V05_PCH_N")
	)
	(segment
		(start 384.856482 -93.82506)
		(end 383.97942 -92.947998)
		(width 0.10795)
		(layer "B.Cu")
		(net "FM_OCP_MEZZB_PRES_1V05_PCH_N")
	)
	(segment
		(start 384.6449 -89.127838)
		(end 384.6449 -86.6648)
		(width 0.10795)
		(layer "B.Cu")
		(net "FM_OCP_MEZZB_PRES_1V05_PCH_N")
	)
	(segment
		(start 404.62708 -54.642766)
		(end 404.62708 -54.15407)
		(width 0.10795)
		(layer "B.Cu")
		(net "FM_OCP_MEZZB_PRES_1V05_PCH_N")
	)
	(segment
		(start 385.1656 -95.46844)
		(end 385.1656 -95.910146)
		(width 0.0889)
		(layer "B.Cu")
		(net "FM_OCP_MEZZB_PRES_1V05_PCH_N")
	)
	(segment
		(start 385.6609 -96.7359)
		(end 385.6609 -96.758252)
		(width 0.0889)
		(layer "B.Cu")
		(net "FM_OCP_MEZZB_PRES_1V05_PCH_N")
	)
	(arc
		(start 385.1656 -95.910146)
		(mid 385.249881 -96.193363)
		(end 385.460748 -96.400366)
		(width 0.0889)
		(layer "B.Cu")
		(net "FM_OCP_MEZZB_PRES_1V05_PCH_N")
	)
	(arc
		(start 385.6609 -96.758252)
		(mid 385.618367 -96.926689)
		(end 385.5085 -97.061274)
		(width 0.0889)
		(layer "B.Cu")
		(net "FM_OCP_MEZZB_PRES_1V05_PCH_N")
	)
	(arc
		(start 385.460748 -96.400366)
		(mid 385.604552 -96.542049)
		(end 385.6609 -96.7359)
		(width 0.0889)
		(layer "B.Cu")
		(net "FM_OCP_MEZZB_PRES_1V05_PCH_N")
	)
	(segment
		(start 391.166604 -78.689454)
		(end 391.166604 -79.512668)
		(width 0.089408)
		(layer "In9.Cu")
		(net "FM_OCP_MEZZB_PRES_1V05_PCH_N")
	)
	(segment
		(start 394.974318 -65.165478)
		(end 394.974318 -69.366892)
		(width 0.089408)
		(layer "In9.Cu")
		(net "FM_OCP_MEZZB_PRES_1V05_PCH_N")
	)
	(segment
		(start 388.378192 -87.919814)
		(end 387.430264 -87.919814)
		(width 0.089408)
		(layer "In9.Cu")
		(net "FM_OCP_MEZZB_PRES_1V05_PCH_N")
	)
	(segment
		(start 393.272264 -71.88581)
		(end 393.272264 -72.052434)
		(width 0.089408)
		(layer "In9.Cu")
		(net "FM_OCP_MEZZB_PRES_1V05_PCH_N")
	)
	(segment
		(start 385.888484 -92.256864)
		(end 386.383784 -92.752164)
		(width 0.089408)
		(layer "In9.Cu")
		(net "FM_OCP_MEZZB_PRES_1V05_PCH_N")
	)
	(segment
		(start 395.732 -52.976272)
		(end 395.732508 -52.97678)
		(width 0.089408)
		(layer "In9.Cu")
		(net "FM_OCP_MEZZB_PRES_1V05_PCH_N")
	)
	(segment
		(start 394.97381 -65.16497)
		(end 394.974318 -65.165478)
		(width 0.089408)
		(layer "In9.Cu")
		(net "FM_OCP_MEZZB_PRES_1V05_PCH_N")
	)
	(segment
		(start 392.307064 -77.548994)
		(end 391.166604 -78.689454)
		(width 0.089408)
		(layer "In9.Cu")
		(net "FM_OCP_MEZZB_PRES_1V05_PCH_N")
	)
	(segment
		(start 395.732254 -54.878478)
		(end 395.732254 -63.06312)
		(width 0.089408)
		(layer "In9.Cu")
		(net "FM_OCP_MEZZB_PRES_1V05_PCH_N")
	)
	(segment
		(start 393.2428 -71.856346)
		(end 393.272264 -71.88581)
		(width 0.089408)
		(layer "In9.Cu")
		(net "FM_OCP_MEZZB_PRES_1V05_PCH_N")
	)
	(segment
		(start 392.732768 -75.887072)
		(end 392.307064 -76.312776)
		(width 0.089408)
		(layer "In9.Cu")
		(net "FM_OCP_MEZZB_PRES_1V05_PCH_N")
	)
	(segment
		(start 393.272264 -72.052434)
		(end 393.64285 -72.42302)
		(width 0.089408)
		(layer "In9.Cu")
		(net "FM_OCP_MEZZB_PRES_1V05_PCH_N")
	)
	(segment
		(start 394.974064 -64.690244)
		(end 394.974064 -65.006728)
		(width 0.089408)
		(layer "In9.Cu")
		(net "FM_OCP_MEZZB_PRES_1V05_PCH_N")
	)
	(segment
		(start 385.764024 -90.524838)
		(end 385.759198 -90.529664)
		(width 0.089408)
		(layer "In9.Cu")
		(net "FM_OCP_MEZZB_PRES_1V05_PCH_N")
	)
	(segment
		(start 395.732508 -54.878224)
		(end 395.732254 -54.878478)
		(width 0.089408)
		(layer "In9.Cu")
		(net "FM_OCP_MEZZB_PRES_1V05_PCH_N")
	)
	(segment
		(start 385.35737 -94.109286)
		(end 385.35737 -96.650556)
		(width 0.089408)
		(layer "In9.Cu")
		(net "FM_OCP_MEZZB_PRES_1V05_PCH_N")
	)
	(segment
		(start 390.35482 -85.943186)
		(end 388.378192 -87.919814)
		(width 0.089408)
		(layer "In9.Cu")
		(net "FM_OCP_MEZZB_PRES_1V05_PCH_N")
	)
	(segment
		(start 392.732768 -73.787762)
		(end 392.732768 -75.887072)
		(width 0.089408)
		(layer "In9.Cu")
		(net "FM_OCP_MEZZB_PRES_1V05_PCH_N")
	)
	(segment
		(start 394.97381 -65.006982)
		(end 394.97381 -65.16497)
		(width 0.089408)
		(layer "In9.Cu")
		(net "FM_OCP_MEZZB_PRES_1V05_PCH_N")
	)
	(segment
		(start 385.865116 -91.727782)
		(end 385.865116 -92.162122)
		(width 0.089408)
		(layer "In9.Cu")
		(net "FM_OCP_MEZZB_PRES_1V05_PCH_N")
	)
	(segment
		(start 386.289042 -89.259918)
		(end 386.289042 -89.267792)
		(width 0.089408)
		(layer "In9.Cu")
		(net "FM_OCP_MEZZB_PRES_1V05_PCH_N")
	)
	(segment
		(start 390.35482 -83.334606)
		(end 390.35482 -85.943186)
		(width 0.089408)
		(layer "In9.Cu")
		(net "FM_OCP_MEZZB_PRES_1V05_PCH_N")
	)
	(segment
		(start 390.739376 -81.69275)
		(end 390.739376 -82.009234)
		(width 0.089408)
		(layer "In9.Cu")
		(net "FM_OCP_MEZZB_PRES_1V05_PCH_N")
	)
	(segment
		(start 386.289042 -89.267792)
		(end 385.764024 -89.79281)
		(width 0.089408)
		(layer "In9.Cu")
		(net "FM_OCP_MEZZB_PRES_1V05_PCH_N")
	)
	(segment
		(start 390.739122 -82.950304)
		(end 390.35482 -83.334606)
		(width 0.089408)
		(layer "In9.Cu")
		(net "FM_OCP_MEZZB_PRES_1V05_PCH_N")
	)
	(segment
		(start 391.166604 -79.512668)
		(end 391.492232 -79.838296)
		(width 0.089408)
		(layer "In9.Cu")
		(net "FM_OCP_MEZZB_PRES_1V05_PCH_N")
	)
	(segment
		(start 386.383784 -93.082872)
		(end 385.35737 -94.109286)
		(width 0.089408)
		(layer "In9.Cu")
		(net "FM_OCP_MEZZB_PRES_1V05_PCH_N")
	)
	(segment
		(start 395.732508 -52.97678)
		(end 395.732508 -54.878224)
		(width 0.089408)
		(layer "In9.Cu")
		(net "FM_OCP_MEZZB_PRES_1V05_PCH_N")
	)
	(segment
		(start 385.888484 -92.185744)
		(end 385.888484 -92.256864)
		(width 0.089408)
		(layer "In9.Cu")
		(net "FM_OCP_MEZZB_PRES_1V05_PCH_N")
	)
	(segment
		(start 385.759198 -90.529664)
		(end 385.759198 -90.861388)
		(width 0.089408)
		(layer "In9.Cu")
		(net "FM_OCP_MEZZB_PRES_1V05_PCH_N")
	)
	(segment
		(start 385.8768 -92.17406)
		(end 385.888484 -92.185744)
		(width 0.089408)
		(layer "In9.Cu")
		(net "FM_OCP_MEZZB_PRES_1V05_PCH_N")
	)
	(segment
		(start 391.492232 -80.060038)
		(end 390.590786 -80.961484)
		(width 0.089408)
		(layer "In9.Cu")
		(net "FM_OCP_MEZZB_PRES_1V05_PCH_N")
	)
	(segment
		(start 385.764024 -90.866214)
		(end 385.764024 -91.62669)
		(width 0.089408)
		(layer "In9.Cu")
		(net "FM_OCP_MEZZB_PRES_1V05_PCH_N")
	)
	(segment
		(start 385.35737 -96.650556)
		(end 385.26085 -96.747076)
		(width 0.089408)
		(layer "In9.Cu")
		(net "FM_OCP_MEZZB_PRES_1V05_PCH_N")
	)
	(segment
		(start 394.974064 -65.006728)
		(end 394.97381 -65.006982)
		(width 0.089408)
		(layer "In9.Cu")
		(net "FM_OCP_MEZZB_PRES_1V05_PCH_N")
	)
	(segment
		(start 387.430264 -87.919814)
		(end 386.289296 -89.060782)
		(width 0.089408)
		(layer "In9.Cu")
		(net "FM_OCP_MEZZB_PRES_1V05_PCH_N")
	)
	(segment
		(start 385.759198 -90.861388)
		(end 385.764024 -90.866214)
		(width 0.089408)
		(layer "In9.Cu")
		(net "FM_OCP_MEZZB_PRES_1V05_PCH_N")
	)
	(segment
		(start 391.492232 -79.838296)
		(end 391.492232 -80.060038)
		(width 0.089408)
		(layer "In9.Cu")
		(net "FM_OCP_MEZZB_PRES_1V05_PCH_N")
	)
	(segment
		(start 385.764024 -89.79281)
		(end 385.764024 -90.524838)
		(width 0.089408)
		(layer "In9.Cu")
		(net "FM_OCP_MEZZB_PRES_1V05_PCH_N")
	)
	(segment
		(start 392.307064 -76.312776)
		(end 392.307064 -77.548994)
		(width 0.089408)
		(layer "In9.Cu")
		(net "FM_OCP_MEZZB_PRES_1V05_PCH_N")
	)
	(segment
		(start 394.974318 -64.68999)
		(end 394.974064 -64.690244)
		(width 0.089408)
		(layer "In9.Cu")
		(net "FM_OCP_MEZZB_PRES_1V05_PCH_N")
	)
	(segment
		(start 393.64285 -72.42302)
		(end 393.64285 -72.87768)
		(width 0.089408)
		(layer "In9.Cu")
		(net "FM_OCP_MEZZB_PRES_1V05_PCH_N")
	)
	(segment
		(start 386.289296 -89.259664)
		(end 386.289042 -89.259918)
		(width 0.089408)
		(layer "In9.Cu")
		(net "FM_OCP_MEZZB_PRES_1V05_PCH_N")
	)
	(segment
		(start 394.974318 -63.821056)
		(end 394.974318 -64.68999)
		(width 0.089408)
		(layer "In9.Cu")
		(net "FM_OCP_MEZZB_PRES_1V05_PCH_N")
	)
	(segment
		(start 385.865116 -92.162122)
		(end 385.8768 -92.173806)
		(width 0.089408)
		(layer "In9.Cu")
		(net "FM_OCP_MEZZB_PRES_1V05_PCH_N")
	)
	(segment
		(start 393.64285 -72.87768)
		(end 392.732768 -73.787762)
		(width 0.089408)
		(layer "In9.Cu")
		(net "FM_OCP_MEZZB_PRES_1V05_PCH_N")
	)
	(segment
		(start 394.974318 -69.366892)
		(end 393.2428 -71.09841)
		(width 0.089408)
		(layer "In9.Cu")
		(net "FM_OCP_MEZZB_PRES_1V05_PCH_N")
	)
	(segment
		(start 390.590786 -80.961484)
		(end 390.590786 -81.54416)
		(width 0.089408)
		(layer "In9.Cu")
		(net "FM_OCP_MEZZB_PRES_1V05_PCH_N")
	)
	(segment
		(start 386.289296 -89.060782)
		(end 386.289296 -89.259664)
		(width 0.089408)
		(layer "In9.Cu")
		(net "FM_OCP_MEZZB_PRES_1V05_PCH_N")
	)
	(segment
		(start 390.590786 -81.54416)
		(end 390.739376 -81.69275)
		(width 0.089408)
		(layer "In9.Cu")
		(net "FM_OCP_MEZZB_PRES_1V05_PCH_N")
	)
	(segment
		(start 385.764024 -91.62669)
		(end 385.865116 -91.727782)
		(width 0.089408)
		(layer "In9.Cu")
		(net "FM_OCP_MEZZB_PRES_1V05_PCH_N")
	)
	(segment
		(start 390.739376 -82.009234)
		(end 390.739122 -82.009488)
		(width 0.089408)
		(layer "In9.Cu")
		(net "FM_OCP_MEZZB_PRES_1V05_PCH_N")
	)
	(segment
		(start 393.2428 -71.09841)
		(end 393.2428 -71.856346)
		(width 0.089408)
		(layer "In9.Cu")
		(net "FM_OCP_MEZZB_PRES_1V05_PCH_N")
	)
	(segment
		(start 395.732 -52.0954)
		(end 395.732 -52.976272)
		(width 0.089408)
		(layer "In9.Cu")
		(net "FM_OCP_MEZZB_PRES_1V05_PCH_N")
	)
	(segment
		(start 385.8768 -92.173806)
		(end 385.8768 -92.17406)
		(width 0.089408)
		(layer "In9.Cu")
		(net "FM_OCP_MEZZB_PRES_1V05_PCH_N")
	)
	(segment
		(start 395.732254 -63.06312)
		(end 394.974318 -63.821056)
		(width 0.089408)
		(layer "In9.Cu")
		(net "FM_OCP_MEZZB_PRES_1V05_PCH_N")
	)
	(segment
		(start 386.383784 -92.752164)
		(end 386.383784 -93.082872)
		(width 0.089408)
		(layer "In9.Cu")
		(net "FM_OCP_MEZZB_PRES_1V05_PCH_N")
	)
	(segment
		(start 390.739122 -82.009488)
		(end 390.739122 -82.950304)
		(width 0.089408)
		(layer "In9.Cu")
		(net "FM_OCP_MEZZB_PRES_1V05_PCH_N")
	)
	(segment
		(start 417.068 -114.1476)
		(end 417.3982 -113.8174)
		(width 0.10795)
		(layer "F.Cu")
		(net "FM_MEM_THERM_EVENT_LVT3_N")
	)
	(segment
		(start 417.3982 -113.8174)
		(end 417.52774 -113.68786)
		(width 0.10795)
		(layer "F.Cu")
		(net "FM_MEM_THERM_EVENT_LVT3_N")
	)
	(segment
		(start 368.745262 -75.894692)
		(end 369.145058 -75.494896)
		(width 0.1016)
		(layer "F.Cu")
		(net "FM_MEM_THERM_EVENT_LVT3_N")
	)
	(segment
		(start 417.52774 -113.68786)
		(end 418.21735 -113.68786)
		(width 0.10795)
		(layer "F.Cu")
		(net "FM_MEM_THERM_EVENT_LVT3_N")
	)
	(segment
		(start 415.7599 -114.1476)
		(end 417.068 -114.1476)
		(width 0.10795)
		(layer "F.Cu")
		(net "FM_MEM_THERM_EVENT_LVT3_N")
	)
	(segment
		(start 415.7345 -114.173)
		(end 415.7599 -114.1476)
		(width 0.10795)
		(layer "F.Cu")
		(net "FM_MEM_THERM_EVENT_LVT3_N")
	)
	(via
		(at 375.8438 -57.099454)
		(size 0.508)
		(drill 0.254)
		(layers "F.Cu" "B.Cu")
		(net "FM_MEM_THERM_EVENT_LVT3_N")
	)
	(via
		(at 368.745262 -75.894692)
		(size 0.4572)
		(drill 0.2032)
		(layers "F.Cu" "B.Cu")
		(net "FM_MEM_THERM_EVENT_LVT3_N")
	)
	(via
		(at 422.148 -63.502032)
		(size 0.508)
		(drill 0.254)
		(layers "F.Cu" "B.Cu")
		(net "FM_MEM_THERM_EVENT_LVT3_N")
	)
	(via
		(at 417.3982 -113.8174)
		(size 0.762)
		(drill 0.381)
		(layers "F.Cu" "B.Cu")
		(net "FM_MEM_THERM_EVENT_LVT3_N")
	)
	(via
		(at 418.21735 -113.68786)
		(size 0.508)
		(drill 0.254)
		(layers "F.Cu" "B.Cu")
		(net "FM_MEM_THERM_EVENT_LVT3_N")
	)
	(via
		(at 329.42149 -13.03909)
		(size 0.508)
		(drill 0.254)
		(layers "F.Cu" "B.Cu")
		(net "FM_MEM_THERM_EVENT_LVT3_N")
	)
	(segment
		(start 330.904596 -12.401804)
		(end 330.904596 -11.081004)
		(width 0.10795)
		(layer "B.Cu")
		(net "FM_MEM_THERM_EVENT_LVT3_N")
	)
	(segment
		(start 330.904596 -11.081004)
		(end 331.1652 -10.8204)
		(width 0.10795)
		(layer "B.Cu")
		(net "FM_MEM_THERM_EVENT_LVT3_N")
	)
	(segment
		(start 329.42149 -13.03909)
		(end 330.26731 -13.03909)
		(width 0.10795)
		(layer "B.Cu")
		(net "FM_MEM_THERM_EVENT_LVT3_N")
	)
	(segment
		(start 331.80528 -10.35812)
		(end 331.343 -10.8204)
		(width 0.10795)
		(layer "B.Cu")
		(net "FM_MEM_THERM_EVENT_LVT3_N")
	)
	(segment
		(start 331.80528 -9.1186)
		(end 331.80528 -10.35812)
		(width 0.10795)
		(layer "B.Cu")
		(net "FM_MEM_THERM_EVENT_LVT3_N")
	)
	(segment
		(start 331.1652 -10.8204)
		(end 331.343 -10.8204)
		(width 0.10795)
		(layer "B.Cu")
		(net "FM_MEM_THERM_EVENT_LVT3_N")
	)
	(segment
		(start 330.26731 -13.03909)
		(end 330.904596 -12.401804)
		(width 0.10795)
		(layer "B.Cu")
		(net "FM_MEM_THERM_EVENT_LVT3_N")
	)
	(segment
		(start 369.014248 -65.291208)
		(end 369.749578 -65.291208)
		(width 0.089408)
		(layer "In2.Cu")
		(net "FM_MEM_THERM_EVENT_LVT3_N")
	)
	(segment
		(start 422.148 -63.502032)
		(end 421.258492 -63.502032)
		(width 0.089408)
		(layer "In2.Cu")
		(net "FM_MEM_THERM_EVENT_LVT3_N")
	)
	(segment
		(start 420.761922 -88.679528)
		(end 420.762176 -88.679782)
		(width 0.089408)
		(layer "In2.Cu")
		(net "FM_MEM_THERM_EVENT_LVT3_N")
	)
	(segment
		(start 369.749578 -65.291208)
		(end 370.134896 -64.90589)
		(width 0.089408)
		(layer "In2.Cu")
		(net "FM_MEM_THERM_EVENT_LVT3_N")
	)
	(segment
		(start 420.00297 -64.757554)
		(end 420.00297 -65.606676)
		(width 0.089408)
		(layer "In2.Cu")
		(net "FM_MEM_THERM_EVENT_LVT3_N")
	)
	(segment
		(start 418.789104 -95.259906)
		(end 418.789104 -113.116106)
		(width 0.089408)
		(layer "In2.Cu")
		(net "FM_MEM_THERM_EVENT_LVT3_N")
	)
	(segment
		(start 420.762176 -88.679782)
		(end 420.762176 -88.83777)
		(width 0.089408)
		(layer "In2.Cu")
		(net "FM_MEM_THERM_EVENT_LVT3_N")
	)
	(segment
		(start 419.771322 -74.932032)
		(end 419.771322 -76.409804)
		(width 0.089408)
		(layer "In2.Cu")
		(net "FM_MEM_THERM_EVENT_LVT3_N")
	)
	(segment
		(start 420.002716 -65.60693)
		(end 420.002716 -71.741538)
		(width 0.089408)
		(layer "In2.Cu")
		(net "FM_MEM_THERM_EVENT_LVT3_N")
	)
	(segment
		(start 419.168072 -77.149452)
		(end 419.168072 -81.898236)
		(width 0.089408)
		(layer "In2.Cu")
		(net "FM_MEM_THERM_EVENT_LVT3_N")
	)
	(segment
		(start 419.770814 -76.410312)
		(end 419.770814 -76.54671)
		(width 0.089408)
		(layer "In2.Cu")
		(net "FM_MEM_THERM_EVENT_LVT3_N")
	)
	(segment
		(start 419.771068 -74.931778)
		(end 419.771322 -74.932032)
		(width 0.089408)
		(layer "In2.Cu")
		(net "FM_MEM_THERM_EVENT_LVT3_N")
	)
	(segment
		(start 419.771322 -76.409804)
		(end 419.770814 -76.410312)
		(width 0.089408)
		(layer "In2.Cu")
		(net "FM_MEM_THERM_EVENT_LVT3_N")
	)
	(segment
		(start 420.762176 -88.83777)
		(end 420.761922 -88.838024)
		(width 0.089408)
		(layer "In2.Cu")
		(net "FM_MEM_THERM_EVENT_LVT3_N")
	)
	(segment
		(start 419.168326 -83.534758)
		(end 419.168072 -83.535012)
		(width 0.089408)
		(layer "In2.Cu")
		(net "FM_MEM_THERM_EVENT_LVT3_N")
	)
	(segment
		(start 419.771068 -74.77379)
		(end 419.771068 -74.931778)
		(width 0.089408)
		(layer "In2.Cu")
		(net "FM_MEM_THERM_EVENT_LVT3_N")
	)
	(segment
		(start 375.858786 -57.099454)
		(end 375.8438 -57.099454)
		(width 0.089408)
		(layer "In2.Cu")
		(net "FM_MEM_THERM_EVENT_LVT3_N")
	)
	(segment
		(start 418.789104 -113.116106)
		(end 418.21735 -113.68786)
		(width 0.089408)
		(layer "In2.Cu")
		(net "FM_MEM_THERM_EVENT_LVT3_N")
	)
	(segment
		(start 421.258492 -63.502032)
		(end 420.00297 -64.757554)
		(width 0.089408)
		(layer "In2.Cu")
		(net "FM_MEM_THERM_EVENT_LVT3_N")
	)
	(segment
		(start 368.3254 -67.196716)
		(end 368.153188 -67.024504)
		(width 0.089408)
		(layer "In2.Cu")
		(net "FM_MEM_THERM_EVENT_LVT3_N")
	)
	(segment
		(start 420.761922 -93.287088)
		(end 418.789104 -95.259906)
		(width 0.089408)
		(layer "In2.Cu")
		(net "FM_MEM_THERM_EVENT_LVT3_N")
	)
	(segment
		(start 420.002716 -71.741538)
		(end 419.770814 -71.97344)
		(width 0.089408)
		(layer "In2.Cu")
		(net "FM_MEM_THERM_EVENT_LVT3_N")
	)
	(segment
		(start 375.858786 -58.267854)
		(end 375.858786 -57.099454)
		(width 0.089408)
		(layer "In2.Cu")
		(net "FM_MEM_THERM_EVENT_LVT3_N")
	)
	(segment
		(start 368.153188 -66.152268)
		(end 369.014248 -65.291208)
		(width 0.089408)
		(layer "In2.Cu")
		(net "FM_MEM_THERM_EVENT_LVT3_N")
	)
	(segment
		(start 371.968776 -62.320424)
		(end 371.968776 -62.157864)
		(width 0.089408)
		(layer "In2.Cu")
		(net "FM_MEM_THERM_EVENT_LVT3_N")
	)
	(segment
		(start 420.761922 -88.838024)
		(end 420.761922 -93.287088)
		(width 0.089408)
		(layer "In2.Cu")
		(net "FM_MEM_THERM_EVENT_LVT3_N")
	)
	(segment
		(start 419.168072 -83.535012)
		(end 419.168072 -86.686644)
		(width 0.089408)
		(layer "In2.Cu")
		(net "FM_MEM_THERM_EVENT_LVT3_N")
	)
	(segment
		(start 368.745262 -75.894692)
		(end 368.3254 -75.47483)
		(width 0.089408)
		(layer "In2.Cu")
		(net "FM_MEM_THERM_EVENT_LVT3_N")
	)
	(segment
		(start 368.153188 -67.024504)
		(end 368.153188 -66.152268)
		(width 0.089408)
		(layer "In2.Cu")
		(net "FM_MEM_THERM_EVENT_LVT3_N")
	)
	(segment
		(start 419.168072 -81.898236)
		(end 419.168326 -81.89849)
		(width 0.089408)
		(layer "In2.Cu")
		(net "FM_MEM_THERM_EVENT_LVT3_N")
	)
	(segment
		(start 370.134896 -64.90589)
		(end 370.134896 -64.154304)
		(width 0.089408)
		(layer "In2.Cu")
		(net "FM_MEM_THERM_EVENT_LVT3_N")
	)
	(segment
		(start 420.00297 -65.606676)
		(end 420.002716 -65.60693)
		(width 0.089408)
		(layer "In2.Cu")
		(net "FM_MEM_THERM_EVENT_LVT3_N")
	)
	(segment
		(start 419.168072 -86.686644)
		(end 420.761922 -88.280494)
		(width 0.089408)
		(layer "In2.Cu")
		(net "FM_MEM_THERM_EVENT_LVT3_N")
	)
	(segment
		(start 419.770814 -74.773536)
		(end 419.771068 -74.77379)
		(width 0.089408)
		(layer "In2.Cu")
		(net "FM_MEM_THERM_EVENT_LVT3_N")
	)
	(segment
		(start 370.134896 -64.154304)
		(end 371.968776 -62.320424)
		(width 0.089408)
		(layer "In2.Cu")
		(net "FM_MEM_THERM_EVENT_LVT3_N")
	)
	(segment
		(start 419.770814 -71.97344)
		(end 419.770814 -74.773536)
		(width 0.089408)
		(layer "In2.Cu")
		(net "FM_MEM_THERM_EVENT_LVT3_N")
	)
	(segment
		(start 371.968776 -62.157864)
		(end 375.858786 -58.267854)
		(width 0.089408)
		(layer "In2.Cu")
		(net "FM_MEM_THERM_EVENT_LVT3_N")
	)
	(segment
		(start 419.168326 -81.89849)
		(end 419.168326 -83.534758)
		(width 0.089408)
		(layer "In2.Cu")
		(net "FM_MEM_THERM_EVENT_LVT3_N")
	)
	(segment
		(start 419.770814 -76.54671)
		(end 419.168072 -77.149452)
		(width 0.089408)
		(layer "In2.Cu")
		(net "FM_MEM_THERM_EVENT_LVT3_N")
	)
	(segment
		(start 368.3254 -75.47483)
		(end 368.3254 -67.196716)
		(width 0.089408)
		(layer "In2.Cu")
		(net "FM_MEM_THERM_EVENT_LVT3_N")
	)
	(segment
		(start 420.761922 -88.280494)
		(end 420.761922 -88.679528)
		(width 0.089408)
		(layer "In2.Cu")
		(net "FM_MEM_THERM_EVENT_LVT3_N")
	)
	(segment
		(start 406.103582 -72.531986)
		(end 402.42617 -72.531986)
		(width 0.089408)
		(layer "In4.Cu")
		(net "FM_MEM_THERM_EVENT_LVT3_N")
	)
	(segment
		(start 374.76176 -75.783694)
		(end 374.499378 -75.521312)
		(width 0.089408)
		(layer "In4.Cu")
		(net "FM_MEM_THERM_EVENT_LVT3_N")
	)
	(segment
		(start 370.771928 -75.996038)
		(end 370.499894 -76.268072)
		(width 0.089408)
		(layer "In4.Cu")
		(net "FM_MEM_THERM_EVENT_LVT3_N")
	)
	(segment
		(start 395.409928 -75.413616)
		(end 394.746988 -75.413616)
		(width 0.089408)
		(layer "In4.Cu")
		(net "FM_MEM_THERM_EVENT_LVT3_N")
	)
	(segment
		(start 413.89173 -70.015608)
		(end 412.152338 -71.755)
		(width 0.089408)
		(layer "In4.Cu")
		(net "FM_MEM_THERM_EVENT_LVT3_N")
	)
	(segment
		(start 412.152338 -71.755)
		(end 409.413964 -71.755)
		(width 0.089408)
		(layer "In4.Cu")
		(net "FM_MEM_THERM_EVENT_LVT3_N")
	)
	(segment
		(start 406.103836 -72.53224)
		(end 406.103582 -72.531986)
		(width 0.089408)
		(layer "In4.Cu")
		(net "FM_MEM_THERM_EVENT_LVT3_N")
	)
	(segment
		(start 406.752552 -72.041512)
		(end 406.261824 -72.53224)
		(width 0.089408)
		(layer "In4.Cu")
		(net "FM_MEM_THERM_EVENT_LVT3_N")
	)
	(segment
		(start 370.190522 -76.268072)
		(end 369.922298 -75.999848)
		(width 0.089408)
		(layer "In4.Cu")
		(net "FM_MEM_THERM_EVENT_LVT3_N")
	)
	(segment
		(start 401.987004 -72.971152)
		(end 400.48434 -72.971152)
		(width 0.089408)
		(layer "In4.Cu")
		(net "FM_MEM_THERM_EVENT_LVT3_N")
	)
	(segment
		(start 369.922298 -75.743816)
		(end 369.699794 -75.521312)
		(width 0.089408)
		(layer "In4.Cu")
		(net "FM_MEM_THERM_EVENT_LVT3_N")
	)
	(segment
		(start 375.790206 -77.068172)
		(end 375.539 -76.816966)
		(width 0.089408)
		(layer "In4.Cu")
		(net "FM_MEM_THERM_EVENT_LVT3_N")
	)
	(segment
		(start 375.279666 -76.3016)
		(end 375.023634 -76.3016)
		(width 0.089408)
		(layer "In4.Cu")
		(net "FM_MEM_THERM_EVENT_LVT3_N")
	)
	(segment
		(start 402.42617 -72.531986)
		(end 401.987004 -72.971152)
		(width 0.089408)
		(layer "In4.Cu")
		(net "FM_MEM_THERM_EVENT_LVT3_N")
	)
	(segment
		(start 409.127452 -72.041512)
		(end 406.752552 -72.041512)
		(width 0.089408)
		(layer "In4.Cu")
		(net "FM_MEM_THERM_EVENT_LVT3_N")
	)
	(segment
		(start 409.413964 -71.755)
		(end 409.127452 -72.041512)
		(width 0.089408)
		(layer "In4.Cu")
		(net "FM_MEM_THERM_EVENT_LVT3_N")
	)
	(segment
		(start 422.148 -63.502032)
		(end 420.73957 -63.502032)
		(width 0.089408)
		(layer "In4.Cu")
		(net "FM_MEM_THERM_EVENT_LVT3_N")
	)
	(segment
		(start 398.425924 -74.08164)
		(end 397.664686 -74.842878)
		(width 0.089408)
		(layer "In4.Cu")
		(net "FM_MEM_THERM_EVENT_LVT3_N")
	)
	(segment
		(start 420.73957 -63.502032)
		(end 417.046918 -67.194684)
		(width 0.089408)
		(layer "In4.Cu")
		(net "FM_MEM_THERM_EVENT_LVT3_N")
	)
	(segment
		(start 415.3408 -69.208904)
		(end 414.53435 -70.015354)
		(width 0.089408)
		(layer "In4.Cu")
		(net "FM_MEM_THERM_EVENT_LVT3_N")
	)
	(segment
		(start 414.128712 -70.015608)
		(end 413.89173 -70.015608)
		(width 0.089408)
		(layer "In4.Cu")
		(net "FM_MEM_THERM_EVENT_LVT3_N")
	)
	(segment
		(start 369.118642 -75.521312)
		(end 368.745262 -75.894692)
		(width 0.089408)
		(layer "In4.Cu")
		(net "FM_MEM_THERM_EVENT_LVT3_N")
	)
	(segment
		(start 414.128966 -70.015862)
		(end 414.128712 -70.015608)
		(width 0.089408)
		(layer "In4.Cu")
		(net "FM_MEM_THERM_EVENT_LVT3_N")
	)
	(segment
		(start 406.261824 -72.53224)
		(end 406.103836 -72.53224)
		(width 0.089408)
		(layer "In4.Cu")
		(net "FM_MEM_THERM_EVENT_LVT3_N")
	)
	(segment
		(start 414.486344 -70.015862)
		(end 414.128966 -70.015862)
		(width 0.089408)
		(layer "In4.Cu")
		(net "FM_MEM_THERM_EVENT_LVT3_N")
	)
	(segment
		(start 374.499378 -75.521312)
		(end 370.990622 -75.521312)
		(width 0.089408)
		(layer "In4.Cu")
		(net "FM_MEM_THERM_EVENT_LVT3_N")
	)
	(segment
		(start 392.982704 -74.643488)
		(end 391.652506 -75.973686)
		(width 0.089408)
		(layer "In4.Cu")
		(net "FM_MEM_THERM_EVENT_LVT3_N")
	)
	(segment
		(start 369.922298 -75.999848)
		(end 369.922298 -75.743816)
		(width 0.089408)
		(layer "In4.Cu")
		(net "FM_MEM_THERM_EVENT_LVT3_N")
	)
	(segment
		(start 383.83718 -75.82662)
		(end 380.595124 -75.82662)
		(width 0.089408)
		(layer "In4.Cu")
		(net "FM_MEM_THERM_EVENT_LVT3_N")
	)
	(segment
		(start 391.652506 -75.973686)
		(end 383.984246 -75.973686)
		(width 0.089408)
		(layer "In4.Cu")
		(net "FM_MEM_THERM_EVENT_LVT3_N")
	)
	(segment
		(start 380.595124 -75.82662)
		(end 379.477524 -76.94422)
		(width 0.089408)
		(layer "In4.Cu")
		(net "FM_MEM_THERM_EVENT_LVT3_N")
	)
	(segment
		(start 394.746988 -75.413616)
		(end 394.500862 -75.16749)
		(width 0.089408)
		(layer "In4.Cu")
		(net "FM_MEM_THERM_EVENT_LVT3_N")
	)
	(segment
		(start 394.14831 -74.643488)
		(end 392.982704 -74.643488)
		(width 0.089408)
		(layer "In4.Cu")
		(net "FM_MEM_THERM_EVENT_LVT3_N")
	)
	(segment
		(start 414.486852 -70.015354)
		(end 414.486344 -70.015862)
		(width 0.089408)
		(layer "In4.Cu")
		(net "FM_MEM_THERM_EVENT_LVT3_N")
	)
	(segment
		(start 397.664686 -74.842878)
		(end 395.980666 -74.842878)
		(width 0.089408)
		(layer "In4.Cu")
		(net "FM_MEM_THERM_EVENT_LVT3_N")
	)
	(segment
		(start 379.194314 -76.94422)
		(end 379.070362 -77.068172)
		(width 0.089408)
		(layer "In4.Cu")
		(net "FM_MEM_THERM_EVENT_LVT3_N")
	)
	(segment
		(start 383.984246 -75.973686)
		(end 383.83718 -75.82662)
		(width 0.089408)
		(layer "In4.Cu")
		(net "FM_MEM_THERM_EVENT_LVT3_N")
	)
	(segment
		(start 415.942018 -69.208904)
		(end 415.3408 -69.208904)
		(width 0.089408)
		(layer "In4.Cu")
		(net "FM_MEM_THERM_EVENT_LVT3_N")
	)
	(segment
		(start 379.070362 -77.068172)
		(end 375.790206 -77.068172)
		(width 0.089408)
		(layer "In4.Cu")
		(net "FM_MEM_THERM_EVENT_LVT3_N")
	)
	(segment
		(start 379.477524 -76.94422)
		(end 379.194314 -76.94422)
		(width 0.089408)
		(layer "In4.Cu")
		(net "FM_MEM_THERM_EVENT_LVT3_N")
	)
	(segment
		(start 375.023634 -76.3016)
		(end 374.76176 -76.039726)
		(width 0.089408)
		(layer "In4.Cu")
		(net "FM_MEM_THERM_EVENT_LVT3_N")
	)
	(segment
		(start 414.53435 -70.015354)
		(end 414.486852 -70.015354)
		(width 0.089408)
		(layer "In4.Cu")
		(net "FM_MEM_THERM_EVENT_LVT3_N")
	)
	(segment
		(start 395.980666 -74.842878)
		(end 395.409928 -75.413616)
		(width 0.089408)
		(layer "In4.Cu")
		(net "FM_MEM_THERM_EVENT_LVT3_N")
	)
	(segment
		(start 417.046918 -68.104004)
		(end 415.942018 -69.208904)
		(width 0.089408)
		(layer "In4.Cu")
		(net "FM_MEM_THERM_EVENT_LVT3_N")
	)
	(segment
		(start 370.771928 -75.740006)
		(end 370.771928 -75.996038)
		(width 0.089408)
		(layer "In4.Cu")
		(net "FM_MEM_THERM_EVENT_LVT3_N")
	)
	(segment
		(start 370.499894 -76.268072)
		(end 370.190522 -76.268072)
		(width 0.089408)
		(layer "In4.Cu")
		(net "FM_MEM_THERM_EVENT_LVT3_N")
	)
	(segment
		(start 375.539 -76.560934)
		(end 375.279666 -76.3016)
		(width 0.089408)
		(layer "In4.Cu")
		(net "FM_MEM_THERM_EVENT_LVT3_N")
	)
	(segment
		(start 394.500862 -74.99604)
		(end 394.14831 -74.643488)
		(width 0.089408)
		(layer "In4.Cu")
		(net "FM_MEM_THERM_EVENT_LVT3_N")
	)
	(segment
		(start 399.373852 -74.08164)
		(end 398.425924 -74.08164)
		(width 0.089408)
		(layer "In4.Cu")
		(net "FM_MEM_THERM_EVENT_LVT3_N")
	)
	(segment
		(start 374.76176 -76.039726)
		(end 374.76176 -75.783694)
		(width 0.089408)
		(layer "In4.Cu")
		(net "FM_MEM_THERM_EVENT_LVT3_N")
	)
	(segment
		(start 394.500862 -75.16749)
		(end 394.500862 -74.99604)
		(width 0.089408)
		(layer "In4.Cu")
		(net "FM_MEM_THERM_EVENT_LVT3_N")
	)
	(segment
		(start 370.990622 -75.521312)
		(end 370.771928 -75.740006)
		(width 0.089408)
		(layer "In4.Cu")
		(net "FM_MEM_THERM_EVENT_LVT3_N")
	)
	(segment
		(start 417.046918 -67.194684)
		(end 417.046918 -68.104004)
		(width 0.089408)
		(layer "In4.Cu")
		(net "FM_MEM_THERM_EVENT_LVT3_N")
	)
	(segment
		(start 400.48434 -72.971152)
		(end 399.373852 -74.08164)
		(width 0.089408)
		(layer "In4.Cu")
		(net "FM_MEM_THERM_EVENT_LVT3_N")
	)
	(segment
		(start 375.539 -76.816966)
		(end 375.539 -76.560934)
		(width 0.089408)
		(layer "In4.Cu")
		(net "FM_MEM_THERM_EVENT_LVT3_N")
	)
	(segment
		(start 369.699794 -75.521312)
		(end 369.118642 -75.521312)
		(width 0.089408)
		(layer "In4.Cu")
		(net "FM_MEM_THERM_EVENT_LVT3_N")
	)
	(segment
		(start 327.991978 -36.451032)
		(end 330.722224 -39.181278)
		(width 0.089408)
		(layer "In11.Cu")
		(net "FM_MEM_THERM_EVENT_LVT3_N")
	)
	(segment
		(start 370.463318 -53.289962)
		(end 373.688356 -56.515)
		(width 0.089408)
		(layer "In11.Cu")
		(net "FM_MEM_THERM_EVENT_LVT3_N")
	)
	(segment
		(start 359.343452 -42.615612)
		(end 365.668306 -48.940466)
		(width 0.089408)
		(layer "In11.Cu")
		(net "FM_MEM_THERM_EVENT_LVT3_N")
	)
	(segment
		(start 356.693978 -41.65219)
		(end 357.6574 -42.615612)
		(width 0.089408)
		(layer "In11.Cu")
		(net "FM_MEM_THERM_EVENT_LVT3_N")
	)
	(segment
		(start 365.668306 -48.940466)
		(end 367.034572 -48.940466)
		(width 0.089408)
		(layer "In11.Cu")
		(net "FM_MEM_THERM_EVENT_LVT3_N")
	)
	(segment
		(start 367.034572 -48.940466)
		(end 370.463318 -52.369212)
		(width 0.089408)
		(layer "In11.Cu")
		(net "FM_MEM_THERM_EVENT_LVT3_N")
	)
	(segment
		(start 324.197726 -24.713438)
		(end 327.1012 -27.616912)
		(width 0.089408)
		(layer "In11.Cu")
		(net "FM_MEM_THERM_EVENT_LVT3_N")
	)
	(segment
		(start 324.197726 -16.562578)
		(end 324.197726 -24.713438)
		(width 0.089408)
		(layer "In11.Cu")
		(net "FM_MEM_THERM_EVENT_LVT3_N")
	)
	(segment
		(start 336.08772 -41.585642)
		(end 336.08772 -42.096436)
		(width 0.089408)
		(layer "In11.Cu")
		(net "FM_MEM_THERM_EVENT_LVT3_N")
	)
	(segment
		(start 331.964538 -39.181278)
		(end 332.736444 -39.953184)
		(width 0.089408)
		(layer "In11.Cu")
		(net "FM_MEM_THERM_EVENT_LVT3_N")
	)
	(segment
		(start 330.722224 -39.181278)
		(end 331.964538 -39.181278)
		(width 0.089408)
		(layer "In11.Cu")
		(net "FM_MEM_THERM_EVENT_LVT3_N")
	)
	(segment
		(start 336.08772 -42.096436)
		(end 336.319876 -42.328592)
		(width 0.089408)
		(layer "In11.Cu")
		(net "FM_MEM_THERM_EVENT_LVT3_N")
	)
	(segment
		(start 325.999348 -14.760956)
		(end 324.197726 -16.562578)
		(width 0.089408)
		(layer "In11.Cu")
		(net "FM_MEM_THERM_EVENT_LVT3_N")
	)
	(segment
		(start 357.6574 -42.615612)
		(end 359.343452 -42.615612)
		(width 0.089408)
		(layer "In11.Cu")
		(net "FM_MEM_THERM_EVENT_LVT3_N")
	)
	(segment
		(start 327.1012 -31.75)
		(end 327.991978 -32.640778)
		(width 0.089408)
		(layer "In11.Cu")
		(net "FM_MEM_THERM_EVENT_LVT3_N")
	)
	(segment
		(start 332.736444 -39.953184)
		(end 334.455262 -39.953184)
		(width 0.089408)
		(layer "In11.Cu")
		(net "FM_MEM_THERM_EVENT_LVT3_N")
	)
	(segment
		(start 336.319876 -42.328592)
		(end 354.047552 -42.328592)
		(width 0.089408)
		(layer "In11.Cu")
		(net "FM_MEM_THERM_EVENT_LVT3_N")
	)
	(segment
		(start 329.42149 -13.03909)
		(end 329.42149 -13.83411)
		(width 0.089408)
		(layer "In11.Cu")
		(net "FM_MEM_THERM_EVENT_LVT3_N")
	)
	(segment
		(start 354.723954 -41.65219)
		(end 356.693978 -41.65219)
		(width 0.089408)
		(layer "In11.Cu")
		(net "FM_MEM_THERM_EVENT_LVT3_N")
	)
	(segment
		(start 375.274332 -56.515)
		(end 375.858786 -57.099454)
		(width 0.089408)
		(layer "In11.Cu")
		(net "FM_MEM_THERM_EVENT_LVT3_N")
	)
	(segment
		(start 375.858786 -57.099454)
		(end 375.8438 -57.099454)
		(width 0.089408)
		(layer "In11.Cu")
		(net "FM_MEM_THERM_EVENT_LVT3_N")
	)
	(segment
		(start 327.1012 -27.616912)
		(end 327.1012 -31.75)
		(width 0.089408)
		(layer "In11.Cu")
		(net "FM_MEM_THERM_EVENT_LVT3_N")
	)
	(segment
		(start 329.42149 -13.83411)
		(end 328.494644 -14.760956)
		(width 0.089408)
		(layer "In11.Cu")
		(net "FM_MEM_THERM_EVENT_LVT3_N")
	)
	(segment
		(start 328.494644 -14.760956)
		(end 325.999348 -14.760956)
		(width 0.089408)
		(layer "In11.Cu")
		(net "FM_MEM_THERM_EVENT_LVT3_N")
	)
	(segment
		(start 327.991978 -32.640778)
		(end 327.991978 -36.451032)
		(width 0.089408)
		(layer "In11.Cu")
		(net "FM_MEM_THERM_EVENT_LVT3_N")
	)
	(segment
		(start 373.688356 -56.515)
		(end 375.274332 -56.515)
		(width 0.089408)
		(layer "In11.Cu")
		(net "FM_MEM_THERM_EVENT_LVT3_N")
	)
	(segment
		(start 334.455262 -39.953184)
		(end 336.08772 -41.585642)
		(width 0.089408)
		(layer "In11.Cu")
		(net "FM_MEM_THERM_EVENT_LVT3_N")
	)
	(segment
		(start 354.047552 -42.328592)
		(end 354.723954 -41.65219)
		(width 0.089408)
		(layer "In11.Cu")
		(net "FM_MEM_THERM_EVENT_LVT3_N")
	)
	(segment
		(start 370.463318 -52.369212)
		(end 370.463318 -53.289962)
		(width 0.089408)
		(layer "In11.Cu")
		(net "FM_MEM_THERM_EVENT_LVT3_N")
	)
	(segment
		(start 100.249482 -142.677642)
		(end 100.249482 -142.6718)
		(width 0.1016)
		(layer "F.Cu")
		(net "FM_DIMM_EVENT_COD_N")
	)
	(segment
		(start 100.249228 -4.357878)
		(end 100.249228 -5.822188)
		(width 0.1016)
		(layer "F.Cu")
		(net "FM_DIMM_EVENT_COD_N")
	)
	(segment
		(start 100.249482 -154.251914)
		(end 100.249482 -152.273)
		(width 0.10795)
		(layer "F.Cu")
		(net "FM_DIMM_EVENT_COD_N")
	)
	(segment
		(start 100.712016 -3.349498)
		(end 100.249228 -3.812286)
		(width 0.1016)
		(layer "F.Cu")
		(net "FM_DIMM_EVENT_COD_N")
	)
	(segment
		(start 99.794568 -135.9408)
		(end 99.794568 -134.803134)
		(width 0.1016)
		(layer "F.Cu")
		(net "FM_DIMM_EVENT_COD_N")
	)
	(segment
		(start 99.794568 -140.4112)
		(end 99.794568 -136.0424)
		(width 0.1016)
		(layer "F.Cu")
		(net "FM_DIMM_EVENT_COD_N")
	)
	(segment
		(start 100.249228 -17.396968)
		(end 100.249228 -15.423896)
		(width 0.10795)
		(layer "F.Cu")
		(net "FM_DIMM_EVENT_COD_N")
	)
	(segment
		(start 100.556568 2.7432)
		(end 100.556568 2.1209)
		(width 0.1016)
		(layer "F.Cu")
		(net "FM_DIMM_EVENT_COD_N")
	)
	(segment
		(start 99.794568 -136.0424)
		(end 99.794568 -135.9408)
		(width 0.10795)
		(layer "F.Cu")
		(net "FM_DIMM_EVENT_COD_N")
	)
	(segment
		(start 265.536426 -3.900678)
		(end 264.795 -3.159252)
		(width 0.1016)
		(layer "F.Cu")
		(net "FM_DIMM_EVENT_COD_N")
	)
	(segment
		(start 100.249482 -144.650714)
		(end 100.249482 -142.677642)
		(width 0.10795)
		(layer "F.Cu")
		(net "FM_DIMM_EVENT_COD_N")
	)
	(segment
		(start 100.556568 2.1209)
		(end 99.794568 1.3589)
		(width 0.1016)
		(layer "F.Cu")
		(net "FM_DIMM_EVENT_COD_N")
	)
	(segment
		(start 100.249482 -134.34822)
		(end 100.249482 -133.0706)
		(width 0.10795)
		(layer "F.Cu")
		(net "FM_DIMM_EVENT_COD_N")
	)
	(segment
		(start 100.249482 3.050286)
		(end 100.556568 2.7432)
		(width 0.1016)
		(layer "F.Cu")
		(net "FM_DIMM_EVENT_COD_N")
	)
	(segment
		(start 265.249914 -8.333486)
		(end 264.795 -8.7884)
		(width 0.1016)
		(layer "F.Cu")
		(net "FM_DIMM_EVENT_COD_N")
	)
	(segment
		(start 100.683568 -12.347194)
		(end 100.683568 -14.020546)
		(width 0.1016)
		(layer "F.Cu")
		(net "FM_DIMM_EVENT_COD_N")
	)
	(segment
		(start 100.249482 -142.6718)
		(end 100.249482 -140.866114)
		(width 0.1016)
		(layer "F.Cu")
		(net "FM_DIMM_EVENT_COD_N")
	)
	(segment
		(start 99.82708 -8.97382)
		(end 99.82708 -11.490706)
		(width 0.1016)
		(layer "F.Cu")
		(net "FM_DIMM_EVENT_COD_N")
	)
	(segment
		(start 265.250422 -17.516094)
		(end 265.24966 -17.516856)
		(width 0.10795)
		(layer "F.Cu")
		(net "FM_DIMM_EVENT_COD_N")
	)
	(segment
		(start 265.684 -12.347194)
		(end 265.684 -13.156946)
		(width 0.1016)
		(layer "F.Cu")
		(net "FM_DIMM_EVENT_COD_N")
	)
	(segment
		(start 100.249228 -144.650968)
		(end 100.249482 -144.650714)
		(width 0.10795)
		(layer "F.Cu")
		(net "FM_DIMM_EVENT_COD_N")
	)
	(segment
		(start 99.769168 -145.8214)
		(end 100.249228 -145.34134)
		(width 0.10795)
		(layer "F.Cu")
		(net "FM_DIMM_EVENT_COD_N")
	)
	(segment
		(start 265.56335 -3.900678)
		(end 265.536426 -3.900678)
		(width 0.1016)
		(layer "F.Cu")
		(net "FM_DIMM_EVENT_COD_N")
	)
	(segment
		(start 265.24966 -145.34134)
		(end 264.764012 -145.826988)
		(width 0.10795)
		(layer "F.Cu")
		(net "FM_DIMM_EVENT_COD_N")
	)
	(segment
		(start 265.250422 -14.45514)
		(end 265.250422 -15.423642)
		(width 0.10795)
		(layer "F.Cu")
		(net "FM_DIMM_EVENT_COD_N")
	)
	(segment
		(start 265.250422 -5.822442)
		(end 265.249914 -5.822442)
		(width 0.1016)
		(layer "F.Cu")
		(net "FM_DIMM_EVENT_COD_N")
	)
	(segment
		(start 265.24966 -144.650968)
		(end 265.24966 -145.34134)
		(width 0.10795)
		(layer "F.Cu")
		(net "FM_DIMM_EVENT_COD_N")
	)
	(segment
		(start 100.683568 -14.020546)
		(end 100.249482 -14.454632)
		(width 0.1016)
		(layer "F.Cu")
		(net "FM_DIMM_EVENT_COD_N")
	)
	(segment
		(start 100.249482 -5.822442)
		(end 100.249482 -8.551418)
		(width 0.1016)
		(layer "F.Cu")
		(net "FM_DIMM_EVENT_COD_N")
	)
	(segment
		(start 264.763758 -140.727176)
		(end 265.249914 -141.213332)
		(width 0.10795)
		(layer "F.Cu")
		(net "FM_DIMM_EVENT_COD_N")
	)
	(segment
		(start 100.249228 -154.252168)
		(end 100.249482 -154.251914)
		(width 0.10795)
		(layer "F.Cu")
		(net "FM_DIMM_EVENT_COD_N")
	)
	(segment
		(start 265.250422 -142.6718)
		(end 265.249914 -142.6718)
		(width 0.10795)
		(layer "F.Cu")
		(net "FM_DIMM_EVENT_COD_N")
	)
	(segment
		(start 265.249914 3.778758)
		(end 265.250422 3.778758)
		(width 0.1016)
		(layer "F.Cu")
		(net "FM_DIMM_EVENT_COD_N")
	)
	(segment
		(start 100.249228 -145.34134)
		(end 100.249228 -144.650968)
		(width 0.10795)
		(layer "F.Cu")
		(net "FM_DIMM_EVENT_COD_N")
	)
	(segment
		(start 100.249482 -14.454632)
		(end 100.249482 -15.423642)
		(width 0.1016)
		(layer "F.Cu")
		(net "FM_DIMM_EVENT_COD_N")
	)
	(segment
		(start 265.22553 -134.372604)
		(end 264.763758 -134.834376)
		(width 0.10795)
		(layer "F.Cu")
		(net "FM_DIMM_EVENT_COD_N")
	)
	(segment
		(start 99.794568 -1.841754)
		(end 100.712016 -2.759202)
		(width 0.1016)
		(layer "F.Cu")
		(net "FM_DIMM_EVENT_COD_N")
	)
	(segment
		(start 100.249482 3.778758)
		(end 100.249482 3.050286)
		(width 0.1016)
		(layer "F.Cu")
		(net "FM_DIMM_EVENT_COD_N")
	)
	(segment
		(start 265.02995 -158.369)
		(end 264.668 -158.00705)
		(width 0.10795)
		(layer "F.Cu")
		(net "FM_DIMM_EVENT_COD_N")
	)
	(segment
		(start 264.795 -11.458194)
		(end 265.684 -12.347194)
		(width 0.1016)
		(layer "F.Cu")
		(net "FM_DIMM_EVENT_COD_N")
	)
	(segment
		(start 265.250422 -15.423642)
		(end 265.250422 -17.516094)
		(width 0.10795)
		(layer "F.Cu")
		(net "FM_DIMM_EVENT_COD_N")
	)
	(segment
		(start 265.22553 -134.372604)
		(end 265.250422 -134.347712)
		(width 0.10795)
		(layer "F.Cu")
		(net "FM_DIMM_EVENT_COD_N")
	)
	(segment
		(start 265.249914 -141.213332)
		(end 265.249914 -142.6718)
		(width 0.10795)
		(layer "F.Cu")
		(net "FM_DIMM_EVENT_COD_N")
	)
	(segment
		(start 265.249914 -5.822442)
		(end 265.249914 -8.333486)
		(width 0.1016)
		(layer "F.Cu")
		(net "FM_DIMM_EVENT_COD_N")
	)
	(segment
		(start 265.249914 -154.866086)
		(end 265.249914 -154.251914)
		(width 0.10795)
		(layer "F.Cu")
		(net "FM_DIMM_EVENT_COD_N")
	)
	(segment
		(start 100.249228 -5.822188)
		(end 100.249482 -5.822442)
		(width 0.1016)
		(layer "F.Cu")
		(net "FM_DIMM_EVENT_COD_N")
	)
	(segment
		(start 264.668 -155.448)
		(end 265.249914 -154.866086)
		(width 0.10795)
		(layer "F.Cu")
		(net "FM_DIMM_EVENT_COD_N")
	)
	(segment
		(start 100.249482 -8.551418)
		(end 99.82708 -8.97382)
		(width 0.1016)
		(layer "F.Cu")
		(net "FM_DIMM_EVENT_COD_N")
	)
	(segment
		(start 265.249914 3.050286)
		(end 265.249914 3.778758)
		(width 0.1016)
		(layer "F.Cu")
		(net "FM_DIMM_EVENT_COD_N")
	)
	(segment
		(start 265.6332 -14.071346)
		(end 265.249914 -14.454632)
		(width 0.1016)
		(layer "F.Cu")
		(net "FM_DIMM_EVENT_COD_N")
	)
	(segment
		(start 99.82708 -11.490706)
		(end 100.683568 -12.347194)
		(width 0.1016)
		(layer "F.Cu")
		(net "FM_DIMM_EVENT_COD_N")
	)
	(segment
		(start 100.712016 -2.759202)
		(end 100.712016 -3.349498)
		(width 0.1016)
		(layer "F.Cu")
		(net "FM_DIMM_EVENT_COD_N")
	)
	(segment
		(start 100.249228 -3.812286)
		(end 100.249228 -4.357878)
		(width 0.1016)
		(layer "F.Cu")
		(net "FM_DIMM_EVENT_COD_N")
	)
	(segment
		(start 265.250422 -150.264622)
		(end 265.250422 -152.273)
		(width 0.10795)
		(layer "F.Cu")
		(net "FM_DIMM_EVENT_COD_N")
	)
	(segment
		(start 100.249482 -150.264114)
		(end 99.769168 -149.7838)
		(width 0.10795)
		(layer "F.Cu")
		(net "FM_DIMM_EVENT_COD_N")
	)
	(segment
		(start 99.794568 -134.803134)
		(end 100.225098 -134.372604)
		(width 0.1016)
		(layer "F.Cu")
		(net "FM_DIMM_EVENT_COD_N")
	)
	(segment
		(start 264.795 -3.159252)
		(end 264.795 1.3589)
		(width 0.1016)
		(layer "F.Cu")
		(net "FM_DIMM_EVENT_COD_N")
	)
	(segment
		(start 264.668 -158.00705)
		(end 264.668 -155.448)
		(width 0.10795)
		(layer "F.Cu")
		(net "FM_DIMM_EVENT_COD_N")
	)
	(segment
		(start 100.249228 -15.423896)
		(end 100.249482 -15.423642)
		(width 0.10795)
		(layer "F.Cu")
		(net "FM_DIMM_EVENT_COD_N")
	)
	(segment
		(start 265.249914 -152.273)
		(end 265.249914 -154.251914)
		(width 0.10795)
		(layer "F.Cu")
		(net "FM_DIMM_EVENT_COD_N")
	)
	(segment
		(start 265.249914 -14.454632)
		(end 265.250422 -14.45514)
		(width 0.10795)
		(layer "F.Cu")
		(net "FM_DIMM_EVENT_COD_N")
	)
	(segment
		(start 265.557 2.1209)
		(end 265.557 2.7432)
		(width 0.1016)
		(layer "F.Cu")
		(net "FM_DIMM_EVENT_COD_N")
	)
	(segment
		(start 265.6332 -13.207746)
		(end 265.6332 -14.071346)
		(width 0.1016)
		(layer "F.Cu")
		(net "FM_DIMM_EVENT_COD_N")
	)
	(segment
		(start 265.56335 -3.900678)
		(end 265.56335 -4.159504)
		(width 0.1016)
		(layer "F.Cu")
		(net "FM_DIMM_EVENT_COD_N")
	)
	(segment
		(start 265.249914 -144.650714)
		(end 265.24966 -144.650968)
		(width 0.10795)
		(layer "F.Cu")
		(net "FM_DIMM_EVENT_COD_N")
	)
	(segment
		(start 265.684 -13.156946)
		(end 265.6332 -13.207746)
		(width 0.1016)
		(layer "F.Cu")
		(net "FM_DIMM_EVENT_COD_N")
	)
	(segment
		(start 265.250422 -152.273)
		(end 265.249914 -152.273)
		(width 0.10795)
		(layer "F.Cu")
		(net "FM_DIMM_EVENT_COD_N")
	)
	(segment
		(start 265.24966 -4.473194)
		(end 265.24966 -5.822188)
		(width 0.1016)
		(layer "F.Cu")
		(net "FM_DIMM_EVENT_COD_N")
	)
	(segment
		(start 100.249482 -152.273)
		(end 100.249482 -150.264114)
		(width 0.10795)
		(layer "F.Cu")
		(net "FM_DIMM_EVENT_COD_N")
	)
	(segment
		(start 264.795 -8.7884)
		(end 264.795 -11.458194)
		(width 0.1016)
		(layer "F.Cu")
		(net "FM_DIMM_EVENT_COD_N")
	)
	(segment
		(start 264.795 1.3589)
		(end 265.557 2.1209)
		(width 0.1016)
		(layer "F.Cu")
		(net "FM_DIMM_EVENT_COD_N")
	)
	(segment
		(start 100.249482 -140.866114)
		(end 99.794568 -140.4112)
		(width 0.1016)
		(layer "F.Cu")
		(net "FM_DIMM_EVENT_COD_N")
	)
	(segment
		(start 264.764012 -145.826988)
		(end 264.764012 -149.778212)
		(width 0.10795)
		(layer "F.Cu")
		(net "FM_DIMM_EVENT_COD_N")
	)
	(segment
		(start 264.764012 -149.778212)
		(end 265.250422 -150.264622)
		(width 0.10795)
		(layer "F.Cu")
		(net "FM_DIMM_EVENT_COD_N")
	)
	(segment
		(start 100.225098 -134.372604)
		(end 100.249482 -134.34822)
		(width 0.10795)
		(layer "F.Cu")
		(net "FM_DIMM_EVENT_COD_N")
	)
	(segment
		(start 265.56335 -4.159504)
		(end 265.24966 -4.473194)
		(width 0.1016)
		(layer "F.Cu")
		(net "FM_DIMM_EVENT_COD_N")
	)
	(segment
		(start 265.557 2.7432)
		(end 265.249914 3.050286)
		(width 0.1016)
		(layer "F.Cu")
		(net "FM_DIMM_EVENT_COD_N")
	)
	(segment
		(start 265.250422 -134.347712)
		(end 265.250422 -133.0706)
		(width 0.10795)
		(layer "F.Cu")
		(net "FM_DIMM_EVENT_COD_N")
	)
	(segment
		(start 265.24966 -5.822188)
		(end 265.249914 -5.822442)
		(width 0.1016)
		(layer "F.Cu")
		(net "FM_DIMM_EVENT_COD_N")
	)
	(segment
		(start 264.763758 -134.834376)
		(end 264.763758 -140.727176)
		(width 0.10795)
		(layer "F.Cu")
		(net "FM_DIMM_EVENT_COD_N")
	)
	(segment
		(start 99.794568 1.3589)
		(end 99.794568 -1.841754)
		(width 0.1016)
		(layer "F.Cu")
		(net "FM_DIMM_EVENT_COD_N")
	)
	(segment
		(start 99.769168 -149.7838)
		(end 99.769168 -145.8214)
		(width 0.10795)
		(layer "F.Cu")
		(net "FM_DIMM_EVENT_COD_N")
	)
	(segment
		(start 265.249914 -142.6718)
		(end 265.249914 -144.650714)
		(width 0.10795)
		(layer "F.Cu")
		(net "FM_DIMM_EVENT_COD_N")
	)
	(segment
		(start 265.249914 -154.251914)
		(end 265.24966 -154.252168)
		(width 0.10795)
		(layer "F.Cu")
		(net "FM_DIMM_EVENT_COD_N")
	)
	(segment
		(start 265.811 -158.369)
		(end 265.02995 -158.369)
		(width 0.10795)
		(layer "F.Cu")
		(net "FM_DIMM_EVENT_COD_N")
	)
	(via
		(at 265.56335 -3.900678)
		(size 0.508)
		(drill 0.254)
		(layers "F.Cu" "B.Cu")
		(net "FM_DIMM_EVENT_COD_N")
	)
	(via
		(at 100.249228 -144.650968)
		(size 0.508)
		(drill 0.254)
		(layers "F.Cu" "B.Cu")
		(net "FM_DIMM_EVENT_COD_N")
	)
	(via
		(at 329.414632 -9.3726)
		(size 0.508)
		(drill 0.254)
		(layers "F.Cu" "B.Cu")
		(net "FM_DIMM_EVENT_COD_N")
	)
	(via
		(at 160.462214 -156.402786)
		(size 0.508)
		(drill 0.254)
		(layers "F.Cu" "B.Cu")
		(net "FM_DIMM_EVENT_COD_N")
	)
	(via
		(at 185.654442 -19.13001)
		(size 0.508)
		(drill 0.254)
		(layers "F.Cu" "B.Cu")
		(net "FM_DIMM_EVENT_COD_N")
	)
	(via
		(at 331.343 -10.176764)
		(size 0.508)
		(drill 0.254)
		(layers "F.Cu" "B.Cu")
		(net "FM_DIMM_EVENT_COD_N")
	)
	(via
		(at 185.72734 3.844036)
		(size 0.508)
		(drill 0.254)
		(layers "F.Cu" "B.Cu")
		(net "FM_DIMM_EVENT_COD_N")
	)
	(via
		(at 184.61101 -19.13001)
		(size 0.6604)
		(drill 0.3302)
		(layers "F.Cu" "B.Cu")
		(net "FM_DIMM_EVENT_COD_N")
	)
	(via
		(at 265.24966 -144.650968)
		(size 0.508)
		(drill 0.254)
		(layers "F.Cu" "B.Cu")
		(net "FM_DIMM_EVENT_COD_N")
	)
	(via
		(at 100.225098 -134.372604)
		(size 0.508)
		(drill 0.254)
		(layers "F.Cu" "B.Cu")
		(net "FM_DIMM_EVENT_COD_N")
	)
	(via
		(at 100.249228 -4.357878)
		(size 0.508)
		(drill 0.254)
		(layers "F.Cu" "B.Cu")
		(net "FM_DIMM_EVENT_COD_N")
	)
	(via
		(at 265.24966 -154.252168)
		(size 0.508)
		(drill 0.254)
		(layers "F.Cu" "B.Cu")
		(net "FM_DIMM_EVENT_COD_N")
	)
	(via
		(at 100.249228 -17.396968)
		(size 0.508)
		(drill 0.254)
		(layers "F.Cu" "B.Cu")
		(net "FM_DIMM_EVENT_COD_N")
	)
	(via
		(at 265.22553 -134.372604)
		(size 0.508)
		(drill 0.254)
		(layers "F.Cu" "B.Cu")
		(net "FM_DIMM_EVENT_COD_N")
	)
	(via
		(at 100.249228 -154.252168)
		(size 0.508)
		(drill 0.254)
		(layers "F.Cu" "B.Cu")
		(net "FM_DIMM_EVENT_COD_N")
	)
	(via
		(at 265.24966 -17.516856)
		(size 0.508)
		(drill 0.254)
		(layers "F.Cu" "B.Cu")
		(net "FM_DIMM_EVENT_COD_N")
	)
	(via
		(at 265.811 -158.369)
		(size 0.508)
		(drill 0.254)
		(layers "F.Cu" "B.Cu")
		(net "FM_DIMM_EVENT_COD_N")
	)
	(segment
		(start 331.123036 -10.176764)
		(end 330.4794 -10.8204)
		(width 0.10795)
		(layer "B.Cu")
		(net "FM_DIMM_EVENT_COD_N")
	)
	(segment
		(start 185.654442 -19.13001)
		(end 184.61101 -19.13001)
		(width 0.10795)
		(layer "B.Cu")
		(net "FM_DIMM_EVENT_COD_N")
	)
	(segment
		(start 100.249482 -132.876036)
		(end 100.249482 -134.34822)
		(width 0.10795)
		(layer "B.Cu")
		(net "FM_DIMM_EVENT_COD_N")
	)
	(segment
		(start 331.15504 -9.71804)
		(end 331.343 -9.906)
		(width 0.10795)
		(layer "B.Cu")
		(net "FM_DIMM_EVENT_COD_N")
	)
	(segment
		(start 265.24966 -18.03654)
		(end 264.7188 -18.5674)
		(width 0.10795)
		(layer "B.Cu")
		(net "FM_DIMM_EVENT_COD_N")
	)
	(segment
		(start 99.718368 -19.323812)
		(end 100.249228 -18.792952)
		(width 0.10795)
		(layer "B.Cu")
		(net "FM_DIMM_EVENT_COD_N")
	)
	(segment
		(start 331.343 -10.176764)
		(end 331.123036 -10.176764)
		(width 0.10795)
		(layer "B.Cu")
		(net "FM_DIMM_EVENT_COD_N")
	)
	(segment
		(start 265.56335 -4.159504)
		(end 265.249914 -4.47294)
		(width 0.10795)
		(layer "B.Cu")
		(net "FM_DIMM_EVENT_COD_N")
	)
	(segment
		(start 100.249482 -134.34822)
		(end 100.225098 -134.372604)
		(width 0.10795)
		(layer "B.Cu")
		(net "FM_DIMM_EVENT_COD_N")
	)
	(segment
		(start 100.249228 -24.823928)
		(end 100.249228 -23.490428)
		(width 0.10795)
		(layer "B.Cu")
		(net "FM_DIMM_EVENT_COD_N")
	)
	(segment
		(start 331.15504 -9.1186)
		(end 331.15504 -9.71804)
		(width 0.10795)
		(layer "B.Cu")
		(net "FM_DIMM_EVENT_COD_N")
	)
	(segment
		(start 100.249228 -154.252168)
		(end 100.249228 -152.078436)
		(width 0.10795)
		(layer "B.Cu")
		(net "FM_DIMM_EVENT_COD_N")
	)
	(segment
		(start 264.7188 -23.0124)
		(end 265.250422 -23.544022)
		(width 0.10795)
		(layer "B.Cu")
		(net "FM_DIMM_EVENT_COD_N")
	)
	(segment
		(start 265.249914 -134.34822)
		(end 265.249914 -132.876036)
		(width 0.10795)
		(layer "B.Cu")
		(net "FM_DIMM_EVENT_COD_N")
	)
	(segment
		(start 100.249482 -17.396714)
		(end 100.249482 -15.222982)
		(width 0.1016)
		(layer "B.Cu")
		(net "FM_DIMM_EVENT_COD_N")
	)
	(segment
		(start 99.718368 -22.959568)
		(end 99.718368 -19.323812)
		(width 0.10795)
		(layer "B.Cu")
		(net "FM_DIMM_EVENT_COD_N")
	)
	(segment
		(start 100.249482 -24.824182)
		(end 100.249228 -24.823928)
		(width 0.10795)
		(layer "B.Cu")
		(net "FM_DIMM_EVENT_COD_N")
	)
	(segment
		(start 265.250422 -154.251406)
		(end 265.250422 -152.078436)
		(width 0.10795)
		(layer "B.Cu")
		(net "FM_DIMM_EVENT_COD_N")
	)
	(segment
		(start 100.249228 -23.490428)
		(end 99.718368 -22.959568)
		(width 0.10795)
		(layer "B.Cu")
		(net "FM_DIMM_EVENT_COD_N")
	)
	(segment
		(start 331.343 -9.906)
		(end 331.343 -10.176764)
		(width 0.10795)
		(layer "B.Cu")
		(net "FM_DIMM_EVENT_COD_N")
	)
	(segment
		(start 100.249482 -5.621782)
		(end 100.249482 -4.358132)
		(width 0.10795)
		(layer "B.Cu")
		(net "FM_DIMM_EVENT_COD_N")
	)
	(segment
		(start 100.249228 -152.078436)
		(end 100.249482 -152.078436)
		(width 0.10795)
		(layer "B.Cu")
		(net "FM_DIMM_EVENT_COD_N")
	)
	(segment
		(start 265.250422 -17.516094)
		(end 265.24966 -17.516856)
		(width 0.10795)
		(layer "B.Cu")
		(net "FM_DIMM_EVENT_COD_N")
	)
	(segment
		(start 100.249228 -142.477236)
		(end 100.249482 -142.477236)
		(width 0.10795)
		(layer "B.Cu")
		(net "FM_DIMM_EVENT_COD_N")
	)
	(segment
		(start 265.24966 -154.252168)
		(end 265.250422 -154.251406)
		(width 0.10795)
		(layer "B.Cu")
		(net "FM_DIMM_EVENT_COD_N")
	)
	(segment
		(start 100.249482 -4.358132)
		(end 100.249228 -4.357878)
		(width 0.10795)
		(layer "B.Cu")
		(net "FM_DIMM_EVENT_COD_N")
	)
	(segment
		(start 265.249914 -4.47294)
		(end 265.249914 -5.621782)
		(width 0.10795)
		(layer "B.Cu")
		(net "FM_DIMM_EVENT_COD_N")
	)
	(segment
		(start 100.249228 -17.396968)
		(end 100.249482 -17.396714)
		(width 0.1016)
		(layer "B.Cu")
		(net "FM_DIMM_EVENT_COD_N")
	)
	(segment
		(start 265.24966 -17.516856)
		(end 265.24966 -18.03654)
		(width 0.10795)
		(layer "B.Cu")
		(net "FM_DIMM_EVENT_COD_N")
	)
	(segment
		(start 265.250422 -23.544022)
		(end 265.250422 -24.824182)
		(width 0.10795)
		(layer "B.Cu")
		(net "FM_DIMM_EVENT_COD_N")
	)
	(segment
		(start 265.56335 -3.900678)
		(end 265.56335 -4.159504)
		(width 0.10795)
		(layer "B.Cu")
		(net "FM_DIMM_EVENT_COD_N")
	)
	(segment
		(start 265.250422 -15.222982)
		(end 265.250422 -17.516094)
		(width 0.10795)
		(layer "B.Cu")
		(net "FM_DIMM_EVENT_COD_N")
	)
	(segment
		(start 100.249228 -144.650968)
		(end 100.249228 -142.477236)
		(width 0.10795)
		(layer "B.Cu")
		(net "FM_DIMM_EVENT_COD_N")
	)
	(segment
		(start 265.249914 -132.876036)
		(end 265.250422 -132.876036)
		(width 0.10795)
		(layer "B.Cu")
		(net "FM_DIMM_EVENT_COD_N")
	)
	(segment
		(start 100.249228 -18.792952)
		(end 100.249228 -17.396968)
		(width 0.10795)
		(layer "B.Cu")
		(net "FM_DIMM_EVENT_COD_N")
	)
	(segment
		(start 265.249914 -5.621782)
		(end 265.250422 -5.621782)
		(width 0.10795)
		(layer "B.Cu")
		(net "FM_DIMM_EVENT_COD_N")
	)
	(segment
		(start 264.7188 -18.5674)
		(end 264.7188 -23.0124)
		(width 0.10795)
		(layer "B.Cu")
		(net "FM_DIMM_EVENT_COD_N")
	)
	(segment
		(start 265.22553 -134.372604)
		(end 265.249914 -134.34822)
		(width 0.10795)
		(layer "B.Cu")
		(net "FM_DIMM_EVENT_COD_N")
	)
	(segment
		(start 265.250422 -144.650206)
		(end 265.24966 -144.650968)
		(width 0.10795)
		(layer "B.Cu")
		(net "FM_DIMM_EVENT_COD_N")
	)
	(segment
		(start 265.250422 -142.477236)
		(end 265.250422 -144.650206)
		(width 0.10795)
		(layer "B.Cu")
		(net "FM_DIMM_EVENT_COD_N")
	)
	(segment
		(start 158.929832 -155.399232)
		(end 158.929832 -155.713684)
		(width 0.089408)
		(layer "In2.Cu")
		(net "FM_DIMM_EVENT_COD_N")
	)
	(segment
		(start 116.761514 2.981198)
		(end 116.603526 2.981198)
		(width 0.089408)
		(layer "In2.Cu")
		(net "FM_DIMM_EVENT_COD_N")
	)
	(segment
		(start 160.98647 -125.857)
		(end 160.693862 -125.564392)
		(width 0.089408)
		(layer "In2.Cu")
		(net "FM_DIMM_EVENT_COD_N")
	)
	(segment
		(start 100.731066 -0.946658)
		(end 100.641404 -1.03632)
		(width 0.089408)
		(layer "In2.Cu")
		(net "FM_DIMM_EVENT_COD_N")
	)
	(segment
		(start 111.866934 -155.30576)
		(end 111.98352 -155.189174)
		(width 0.089408)
		(layer "In2.Cu")
		(net "FM_DIMM_EVENT_COD_N")
	)
	(segment
		(start 108.3691 -155.15336)
		(end 109.281214 -155.15336)
		(width 0.089408)
		(layer "In2.Cu")
		(net "FM_DIMM_EVENT_COD_N")
	)
	(segment
		(start 185.349642 2.90068)
		(end 184.709308 2.260346)
		(width 0.089408)
		(layer "In2.Cu")
		(net "FM_DIMM_EVENT_COD_N")
	)
	(segment
		(start 164.079936 -5.365496)
		(end 164.079936 -0.885952)
		(width 0.089408)
		(layer "In2.Cu")
		(net "FM_DIMM_EVENT_COD_N")
	)
	(segment
		(start 175.13808 -78.589886)
		(end 175.13808 -90.9828)
		(width 0.089408)
		(layer "In2.Cu")
		(net "FM_DIMM_EVENT_COD_N")
	)
	(segment
		(start 161.881312 -62.332108)
		(end 162.503612 -62.954408)
		(width 0.089408)
		(layer "In2.Cu")
		(net "FM_DIMM_EVENT_COD_N")
	)
	(segment
		(start 109.433614 2.915158)
		(end 109.423962 2.905506)
		(width 0.089408)
		(layer "In2.Cu")
		(net "FM_DIMM_EVENT_COD_N")
	)
	(segment
		(start 174.18812 -93.88348)
		(end 171.23029 -96.84131)
		(width 0.089408)
		(layer "In2.Cu")
		(net "FM_DIMM_EVENT_COD_N")
	)
	(segment
		(start 167.89654 -6.60527)
		(end 165.31971 -6.60527)
		(width 0.089408)
		(layer "In2.Cu")
		(net "FM_DIMM_EVENT_COD_N")
	)
	(segment
		(start 265.619738 0.136398)
		(end 265.619738 0.362458)
		(width 0.089408)
		(layer "In2.Cu")
		(net "FM_DIMM_EVENT_COD_N")
	)
	(segment
		(start 111.98352 -155.189174)
		(end 112.644174 -155.189174)
		(width 0.089408)
		(layer "In2.Cu")
		(net "FM_DIMM_EVENT_COD_N")
	)
	(segment
		(start 265.650218 0.724662)
		(end 265.619484 0.755396)
		(width 0.089408)
		(layer "In2.Cu")
		(net "FM_DIMM_EVENT_COD_N")
	)
	(segment
		(start 165.2016 0.329692)
		(end 165.2016 3.1496)
		(width 0.089408)
		(layer "In2.Cu")
		(net "FM_DIMM_EVENT_COD_N")
	)
	(segment
		(start 265.619484 0.136144)
		(end 265.619738 0.136398)
		(width 0.089408)
		(layer "In2.Cu")
		(net "FM_DIMM_EVENT_COD_N")
	)
	(segment
		(start 185.72734 3.844036)
		(end 185.72734 3.269996)
		(width 0.089408)
		(layer "In2.Cu")
		(net "FM_DIMM_EVENT_COD_N")
	)
	(segment
		(start 265.701018 -2.550922)
		(end 265.619484 -2.469388)
		(width 0.089408)
		(layer "In2.Cu")
		(net "FM_DIMM_EVENT_COD_N")
	)
	(segment
		(start 116.603272 2.981452)
		(end 115.82527 2.981452)
		(width 0.089408)
		(layer "In2.Cu")
		(net "FM_DIMM_EVENT_COD_N")
	)
	(segment
		(start 109.765338 2.915158)
		(end 109.433614 2.915158)
		(width 0.089408)
		(layer "In2.Cu")
		(net "FM_DIMM_EVENT_COD_N")
	)
	(segment
		(start 265.619484 3.077464)
		(end 265.684 3.14198)
		(width 0.089408)
		(layer "In2.Cu")
		(net "FM_DIMM_EVENT_COD_N")
	)
	(segment
		(start 114.958368 2.11455)
		(end 114.213894 2.11455)
		(width 0.089408)
		(layer "In2.Cu")
		(net "FM_DIMM_EVENT_COD_N")
	)
	(segment
		(start 163.916868 -62.954408)
		(end 165.880796 -60.99048)
		(width 0.089408)
		(layer "In2.Cu")
		(net "FM_DIMM_EVENT_COD_N")
	)
	(segment
		(start 160.693862 -125.564392)
		(end 160.279588 -125.564392)
		(width 0.089408)
		(layer "In2.Cu")
		(net "FM_DIMM_EVENT_COD_N")
	)
	(segment
		(start 113.221516 2.905506)
		(end 109.77499 2.905506)
		(width 0.089408)
		(layer "In2.Cu")
		(net "FM_DIMM_EVENT_COD_N")
	)
	(segment
		(start 174.18812 -91.93276)
		(end 174.18812 -93.88348)
		(width 0.089408)
		(layer "In2.Cu")
		(net "FM_DIMM_EVENT_COD_N")
	)
	(segment
		(start 102.96525 2.915158)
		(end 102.633526 2.915158)
		(width 0.089408)
		(layer "In2.Cu")
		(net "FM_DIMM_EVENT_COD_N")
	)
	(segment
		(start 174.4726 -72.4027)
		(end 174.4726 -74.66838)
		(width 0.089408)
		(layer "In2.Cu")
		(net "FM_DIMM_EVENT_COD_N")
	)
	(segment
		(start 180.0352 -0.33909)
		(end 180.0352 -4.5212)
		(width 0.089408)
		(layer "In2.Cu")
		(net "FM_DIMM_EVENT_COD_N")
	)
	(segment
		(start 157.83052 -156.402786)
		(end 160.462214 -156.402786)
		(width 0.089408)
		(layer "In2.Cu")
		(net "FM_DIMM_EVENT_COD_N")
	)
	(segment
		(start 118.49227 4.146296)
		(end 117.34673 3.000756)
		(width 0.089408)
		(layer "In2.Cu")
		(net "FM_DIMM_EVENT_COD_N")
	)
	(segment
		(start 326.8472 3.517392)
		(end 326.57161 3.241802)
		(width 0.089408)
		(layer "In2.Cu")
		(net "FM_DIMM_EVENT_COD_N")
	)
	(segment
		(start 165.593776 -103.943404)
		(end 165.593776 -115.361466)
		(width 0.089408)
		(layer "In2.Cu")
		(net "FM_DIMM_EVENT_COD_N")
	)
	(segment
		(start 161.881312 -59.586876)
		(end 161.881312 -62.332108)
		(width 0.089408)
		(layer "In2.Cu")
		(net "FM_DIMM_EVENT_COD_N")
	)
	(segment
		(start 265.619484 -2.469388)
		(end 265.619484 0.136144)
		(width 0.089408)
		(layer "In2.Cu")
		(net "FM_DIMM_EVENT_COD_N")
	)
	(segment
		(start 265.701018 -3.76301)
		(end 265.701018 -2.550922)
		(width 0.089408)
		(layer "In2.Cu")
		(net "FM_DIMM_EVENT_COD_N")
	)
	(segment
		(start 175.13808 -90.9828)
		(end 174.18812 -91.93276)
		(width 0.089408)
		(layer "In2.Cu")
		(net "FM_DIMM_EVENT_COD_N")
	)
	(segment
		(start 159.324548 -156.1084)
		(end 160.167828 -156.1084)
		(width 0.089408)
		(layer "In2.Cu")
		(net "FM_DIMM_EVENT_COD_N")
	)
	(segment
		(start 323.8754 4.2418)
		(end 326.419718 4.2418)
		(width 0.089408)
		(layer "In2.Cu")
		(net "FM_DIMM_EVENT_COD_N")
	)
	(segment
		(start 109.423962 2.905506)
		(end 102.974902 2.905506)
		(width 0.089408)
		(layer "In2.Cu")
		(net "FM_DIMM_EVENT_COD_N")
	)
	(segment
		(start 102.974902 2.905506)
		(end 102.96525 2.915158)
		(width 0.089408)
		(layer "In2.Cu")
		(net "FM_DIMM_EVENT_COD_N")
	)
	(segment
		(start 165.880796 -60.99048)
		(end 173.0375 -60.99048)
		(width 0.089408)
		(layer "In2.Cu")
		(net "FM_DIMM_EVENT_COD_N")
	)
	(segment
		(start 157.669992 -128.173988)
		(end 156.882592 -128.961388)
		(width 0.089408)
		(layer "In2.Cu")
		(net "FM_DIMM_EVENT_COD_N")
	)
	(segment
		(start 171.802552 -67.165728)
		(end 174.81296 -70.176136)
		(width 0.089408)
		(layer "In2.Cu")
		(net "FM_DIMM_EVENT_COD_N")
	)
	(segment
		(start 109.479334 -155.35148)
		(end 110.146592 -155.35148)
		(width 0.089408)
		(layer "In2.Cu")
		(net "FM_DIMM_EVENT_COD_N")
	)
	(segment
		(start 99.822 -154.7622)
		(end 99.822 -155.889706)
		(width 0.089408)
		(layer "In2.Cu")
		(net "FM_DIMM_EVENT_COD_N")
	)
	(segment
		(start 156.882592 -135.839962)
		(end 157.613604 -136.570974)
		(width 0.089408)
		(layer "In2.Cu")
		(net "FM_DIMM_EVENT_COD_N")
	)
	(segment
		(start 173.0375 -60.99048)
		(end 174.19066 -62.14364)
		(width 0.089408)
		(layer "In2.Cu")
		(net "FM_DIMM_EVENT_COD_N")
	)
	(segment
		(start 184.83834 -43.943016)
		(end 181.308756 -47.4726)
		(width 0.089408)
		(layer "In2.Cu")
		(net "FM_DIMM_EVENT_COD_N")
	)
	(segment
		(start 100.923852 2.905506)
		(end 100.809044 2.905506)
		(width 0.089408)
		(layer "In2.Cu")
		(net "FM_DIMM_EVENT_COD_N")
	)
	(segment
		(start 165.7477 -47.4726)
		(end 161.14014 -52.08016)
		(width 0.089408)
		(layer "In2.Cu")
		(net "FM_DIMM_EVENT_COD_N")
	)
	(segment
		(start 265.619484 0.755396)
		(end 265.619484 3.077464)
		(width 0.089408)
		(layer "In2.Cu")
		(net "FM_DIMM_EVENT_COD_N")
	)
	(segment
		(start 113.885726 2.442718)
		(end 113.684304 2.442718)
		(width 0.089408)
		(layer "In2.Cu")
		(net "FM_DIMM_EVENT_COD_N")
	)
	(segment
		(start 174.19066 -63.458344)
		(end 171.802552 -65.846452)
		(width 0.089408)
		(layer "In2.Cu")
		(net "FM_DIMM_EVENT_COD_N")
	)
	(segment
		(start 100.809044 2.905506)
		(end 100.60686 2.703322)
		(width 0.089408)
		(layer "In2.Cu")
		(net "FM_DIMM_EVENT_COD_N")
	)
	(segment
		(start 159.034734 -126.808992)
		(end 157.669992 -128.173734)
		(width 0.089408)
		(layer "In2.Cu")
		(net "FM_DIMM_EVENT_COD_N")
	)
	(segment
		(start 163.068 -124.155454)
		(end 163.068 -124.714254)
		(width 0.089408)
		(layer "In2.Cu")
		(net "FM_DIMM_EVENT_COD_N")
	)
	(segment
		(start 102.633526 2.915158)
		(end 102.623874 2.905506)
		(width 0.089408)
		(layer "In2.Cu")
		(net "FM_DIMM_EVENT_COD_N")
	)
	(segment
		(start 158.929832 -155.713684)
		(end 159.324548 -156.1084)
		(width 0.089408)
		(layer "In2.Cu")
		(net "FM_DIMM_EVENT_COD_N")
	)
	(segment
		(start 181.308756 -47.4726)
		(end 165.7477 -47.4726)
		(width 0.089408)
		(layer "In2.Cu")
		(net "FM_DIMM_EVENT_COD_N")
	)
	(segment
		(start 157.669992 -128.173734)
		(end 157.669992 -128.173988)
		(width 0.089408)
		(layer "In2.Cu")
		(net "FM_DIMM_EVENT_COD_N")
	)
	(segment
		(start 162.503612 -62.954408)
		(end 163.916868 -62.954408)
		(width 0.089408)
		(layer "In2.Cu")
		(net "FM_DIMM_EVENT_COD_N")
	)
	(segment
		(start 322.841366 3.207766)
		(end 323.8754 4.2418)
		(width 0.089408)
		(layer "In2.Cu")
		(net "FM_DIMM_EVENT_COD_N")
	)
	(segment
		(start 175.177704 -78.550262)
		(end 175.13808 -78.589886)
		(width 0.089408)
		(layer "In2.Cu")
		(net "FM_DIMM_EVENT_COD_N")
	)
	(segment
		(start 163.068 -124.714254)
		(end 161.925254 -125.857)
		(width 0.089408)
		(layer "In2.Cu")
		(net "FM_DIMM_EVENT_COD_N")
	)
	(segment
		(start 161.14014 -58.845704)
		(end 161.881312 -59.586876)
		(width 0.089408)
		(layer "In2.Cu")
		(net "FM_DIMM_EVENT_COD_N")
	)
	(segment
		(start 156.882592 -128.961388)
		(end 156.882592 -135.839962)
		(width 0.089408)
		(layer "In2.Cu")
		(net "FM_DIMM_EVENT_COD_N")
	)
	(segment
		(start 159.034988 -126.808992)
		(end 159.034734 -126.808992)
		(width 0.089408)
		(layer "In2.Cu")
		(net "FM_DIMM_EVENT_COD_N")
	)
	(segment
		(start 326.419718 4.2418)
		(end 326.8472 3.814318)
		(width 0.089408)
		(layer "In2.Cu")
		(net "FM_DIMM_EVENT_COD_N")
	)
	(segment
		(start 160.279588 -125.564392)
		(end 159.034988 -126.808992)
		(width 0.089408)
		(layer "In2.Cu")
		(net "FM_DIMM_EVENT_COD_N")
	)
	(segment
		(start 186.61888 3.844036)
		(end 187.206636 4.431792)
		(width 0.089408)
		(layer "In2.Cu")
		(net "FM_DIMM_EVENT_COD_N")
	)
	(segment
		(start 265.56335 -3.900678)
		(end 265.701018 -3.76301)
		(width 0.089408)
		(layer "In2.Cu")
		(net "FM_DIMM_EVENT_COD_N")
	)
	(segment
		(start 163.693094 -123.53036)
		(end 163.068 -124.155454)
		(width 0.089408)
		(layer "In2.Cu")
		(net "FM_DIMM_EVENT_COD_N")
	)
	(segment
		(start 117.34673 3.000756)
		(end 116.781072 3.000756)
		(width 0.089408)
		(layer "In2.Cu")
		(net "FM_DIMM_EVENT_COD_N")
	)
	(segment
		(start 114.213894 2.11455)
		(end 113.885726 2.442718)
		(width 0.089408)
		(layer "In2.Cu")
		(net "FM_DIMM_EVENT_COD_N")
	)
	(segment
		(start 113.684304 2.442718)
		(end 113.221516 2.905506)
		(width 0.089408)
		(layer "In2.Cu")
		(net "FM_DIMM_EVENT_COD_N")
	)
	(segment
		(start 100.713794 -3.893312)
		(end 100.249228 -4.357878)
		(width 0.089408)
		(layer "In2.Cu")
		(net "FM_DIMM_EVENT_COD_N")
	)
	(segment
		(start 184.83834 -20.885404)
		(end 184.83834 -43.943016)
		(width 0.089408)
		(layer "In2.Cu")
		(net "FM_DIMM_EVENT_COD_N")
	)
	(segment
		(start 325.97852 -9.90092)
		(end 328.886312 -9.90092)
		(width 0.089408)
		(layer "In2.Cu")
		(net "FM_DIMM_EVENT_COD_N")
	)
	(segment
		(start 171.23029 -98.30689)
		(end 165.593776 -103.943404)
		(width 0.089408)
		(layer "In2.Cu")
		(net "FM_DIMM_EVENT_COD_N")
	)
	(segment
		(start 178.727608 -5.828792)
		(end 174.732188 -5.828792)
		(width 0.089408)
		(layer "In2.Cu")
		(net "FM_DIMM_EVENT_COD_N")
	)
	(segment
		(start 180.262784 0.729742)
		(end 180.262784 -0.111506)
		(width 0.089408)
		(layer "In2.Cu")
		(net "FM_DIMM_EVENT_COD_N")
	)
	(segment
		(start 165.2016 3.1496)
		(end 164.204904 4.146296)
		(width 0.089408)
		(layer "In2.Cu")
		(net "FM_DIMM_EVENT_COD_N")
	)
	(segment
		(start 265.749786 3.207766)
		(end 322.841366 3.207766)
		(width 0.089408)
		(layer "In2.Cu")
		(net "FM_DIMM_EVENT_COD_N")
	)
	(segment
		(start 164.12464 -0.841248)
		(end 164.12464 -0.747268)
		(width 0.089408)
		(layer "In2.Cu")
		(net "FM_DIMM_EVENT_COD_N")
	)
	(segment
		(start 100.641404 -2.618232)
		(end 100.713794 -2.690622)
		(width 0.089408)
		(layer "In2.Cu")
		(net "FM_DIMM_EVENT_COD_N")
	)
	(segment
		(start 172.920914 -5.51942)
		(end 170.604942 -7.835392)
		(width 0.089408)
		(layer "In2.Cu")
		(net "FM_DIMM_EVENT_COD_N")
	)
	(segment
		(start 324.866 1.87198)
		(end 324.866 -8.7884)
		(width 0.089408)
		(layer "In2.Cu")
		(net "FM_DIMM_EVENT_COD_N")
	)
	(segment
		(start 265.650218 0.392938)
		(end 265.650218 0.724662)
		(width 0.089408)
		(layer "In2.Cu")
		(net "FM_DIMM_EVENT_COD_N")
	)
	(segment
		(start 326.235822 3.241802)
		(end 324.866 1.87198)
		(width 0.089408)
		(layer "In2.Cu")
		(net "FM_DIMM_EVENT_COD_N")
	)
	(segment
		(start 112.784636 -155.30576)
		(end 113.49736 -156.018484)
		(width 0.089408)
		(layer "In2.Cu")
		(net "FM_DIMM_EVENT_COD_N")
	)
	(segment
		(start 100.249228 -154.334972)
		(end 99.822 -154.7622)
		(width 0.089408)
		(layer "In2.Cu")
		(net "FM_DIMM_EVENT_COD_N")
	)
	(segment
		(start 171.23029 -96.84131)
		(end 171.23029 -98.30689)
		(width 0.089408)
		(layer "In2.Cu")
		(net "FM_DIMM_EVENT_COD_N")
	)
	(segment
		(start 116.781072 3.000756)
		(end 116.761514 2.981198)
		(width 0.089408)
		(layer "In2.Cu")
		(net "FM_DIMM_EVENT_COD_N")
	)
	(segment
		(start 110.917736 -155.08986)
		(end 111.133636 -155.30576)
		(width 0.089408)
		(layer "In2.Cu")
		(net "FM_DIMM_EVENT_COD_N")
	)
	(segment
		(start 174.81296 -72.06234)
		(end 174.4726 -72.4027)
		(width 0.089408)
		(layer "In2.Cu")
		(net "FM_DIMM_EVENT_COD_N")
	)
	(segment
		(start 112.644174 -155.189174)
		(end 112.76076 -155.30576)
		(width 0.089408)
		(layer "In2.Cu")
		(net "FM_DIMM_EVENT_COD_N")
	)
	(segment
		(start 324.866 -8.7884)
		(end 325.97852 -9.90092)
		(width 0.089408)
		(layer "In2.Cu")
		(net "FM_DIMM_EVENT_COD_N")
	)
	(segment
		(start 161.14014 -52.08016)
		(end 161.14014 -58.845704)
		(width 0.089408)
		(layer "In2.Cu")
		(net "FM_DIMM_EVENT_COD_N")
	)
	(segment
		(start 164.079936 -0.885952)
		(end 164.12464 -0.841248)
		(width 0.089408)
		(layer "In2.Cu")
		(net "FM_DIMM_EVENT_COD_N")
	)
	(segment
		(start 161.925254 -125.857)
		(end 160.98647 -125.857)
		(width 0.089408)
		(layer "In2.Cu")
		(net "FM_DIMM_EVENT_COD_N")
	)
	(segment
		(start 112.76076 -155.30576)
		(end 112.784636 -155.30576)
		(width 0.089408)
		(layer "In2.Cu")
		(net "FM_DIMM_EVENT_COD_N")
	)
	(segment
		(start 107.503976 -156.018484)
		(end 108.3691 -155.15336)
		(width 0.089408)
		(layer "In2.Cu")
		(net "FM_DIMM_EVENT_COD_N")
	)
	(segment
		(start 101.27488 2.905506)
		(end 101.265228 2.915158)
		(width 0.089408)
		(layer "In2.Cu")
		(net "FM_DIMM_EVENT_COD_N")
	)
	(segment
		(start 326.57161 3.241802)
		(end 326.235822 3.241802)
		(width 0.089408)
		(layer "In2.Cu")
		(net "FM_DIMM_EVENT_COD_N")
	)
	(segment
		(start 185.72734 3.844036)
		(end 186.61888 3.844036)
		(width 0.089408)
		(layer "In2.Cu")
		(net "FM_DIMM_EVENT_COD_N")
	)
	(segment
		(start 175.177704 -78.218538)
		(end 175.177704 -78.550262)
		(width 0.089408)
		(layer "In2.Cu")
		(net "FM_DIMM_EVENT_COD_N")
	)
	(segment
		(start 185.654442 -19.13001)
		(end 185.654442 -20.069302)
		(width 0.089408)
		(layer "In2.Cu")
		(net "FM_DIMM_EVENT_COD_N")
	)
	(segment
		(start 163.693094 -117.262148)
		(end 163.693094 -123.53036)
		(width 0.089408)
		(layer "In2.Cu")
		(net "FM_DIMM_EVENT_COD_N")
	)
	(segment
		(start 157.613604 -136.570974)
		(end 157.613604 -154.083004)
		(width 0.089408)
		(layer "In2.Cu")
		(net "FM_DIMM_EVENT_COD_N")
	)
	(segment
		(start 174.732188 -5.828792)
		(end 174.422816 -5.51942)
		(width 0.089408)
		(layer "In2.Cu")
		(net "FM_DIMM_EVENT_COD_N")
	)
	(segment
		(start 169.126662 -7.835392)
		(end 167.89654 -6.60527)
		(width 0.089408)
		(layer "In2.Cu")
		(net "FM_DIMM_EVENT_COD_N")
	)
	(segment
		(start 265.684 3.14198)
		(end 265.749786 3.207766)
		(width 0.089408)
		(layer "In2.Cu")
		(net "FM_DIMM_EVENT_COD_N")
	)
	(segment
		(start 170.604942 -7.835392)
		(end 169.126662 -7.835392)
		(width 0.089408)
		(layer "In2.Cu")
		(net "FM_DIMM_EVENT_COD_N")
	)
	(segment
		(start 101.265228 2.915158)
		(end 100.933504 2.915158)
		(width 0.089408)
		(layer "In2.Cu")
		(net "FM_DIMM_EVENT_COD_N")
	)
	(segment
		(start 174.4726 -74.66838)
		(end 175.13808 -75.33386)
		(width 0.089408)
		(layer "In2.Cu")
		(net "FM_DIMM_EVENT_COD_N")
	)
	(segment
		(start 185.358024 2.90068)
		(end 185.349642 2.90068)
		(width 0.089408)
		(layer "In2.Cu")
		(net "FM_DIMM_EVENT_COD_N")
	)
	(segment
		(start 109.281214 -155.15336)
		(end 109.479334 -155.35148)
		(width 0.089408)
		(layer "In2.Cu")
		(net "FM_DIMM_EVENT_COD_N")
	)
	(segment
		(start 100.933504 2.915158)
		(end 100.923852 2.905506)
		(width 0.089408)
		(layer "In2.Cu")
		(net "FM_DIMM_EVENT_COD_N")
	)
	(segment
		(start 174.81296 -70.176136)
		(end 174.81296 -72.06234)
		(width 0.089408)
		(layer "In2.Cu")
		(net "FM_DIMM_EVENT_COD_N")
	)
	(segment
		(start 100.641404 -1.03632)
		(end 100.641404 -2.618232)
		(width 0.089408)
		(layer "In2.Cu")
		(net "FM_DIMM_EVENT_COD_N")
	)
	(segment
		(start 116.603526 2.981198)
		(end 116.603272 2.981452)
		(width 0.089408)
		(layer "In2.Cu")
		(net "FM_DIMM_EVENT_COD_N")
	)
	(segment
		(start 100.249228 -154.252168)
		(end 100.249228 -154.334972)
		(width 0.089408)
		(layer "In2.Cu")
		(net "FM_DIMM_EVENT_COD_N")
	)
	(segment
		(start 265.619738 0.362458)
		(end 265.650218 0.392938)
		(width 0.089408)
		(layer "In2.Cu")
		(net "FM_DIMM_EVENT_COD_N")
	)
	(segment
		(start 110.146592 -155.35148)
		(end 110.408212 -155.08986)
		(width 0.089408)
		(layer "In2.Cu")
		(net "FM_DIMM_EVENT_COD_N")
	)
	(segment
		(start 164.12464 -0.747268)
		(end 165.2016 0.329692)
		(width 0.089408)
		(layer "In2.Cu")
		(net "FM_DIMM_EVENT_COD_N")
	)
	(segment
		(start 165.593776 -115.361466)
		(end 163.693094 -117.262148)
		(width 0.089408)
		(layer "In2.Cu")
		(net "FM_DIMM_EVENT_COD_N")
	)
	(segment
		(start 171.802552 -65.846452)
		(end 171.802552 -67.165728)
		(width 0.089408)
		(layer "In2.Cu")
		(net "FM_DIMM_EVENT_COD_N")
	)
	(segment
		(start 164.204904 4.146296)
		(end 118.49227 4.146296)
		(width 0.089408)
		(layer "In2.Cu")
		(net "FM_DIMM_EVENT_COD_N")
	)
	(segment
		(start 157.613604 -154.083004)
		(end 158.929832 -155.399232)
		(width 0.089408)
		(layer "In2.Cu")
		(net "FM_DIMM_EVENT_COD_N")
	)
	(segment
		(start 111.133636 -155.30576)
		(end 111.866934 -155.30576)
		(width 0.089408)
		(layer "In2.Cu")
		(net "FM_DIMM_EVENT_COD_N")
	)
	(segment
		(start 326.8472 3.814318)
		(end 326.8472 3.517392)
		(width 0.089408)
		(layer "In2.Cu")
		(net "FM_DIMM_EVENT_COD_N")
	)
	(segment
		(start 100.713794 -2.690622)
		(end 100.713794 -3.893312)
		(width 0.089408)
		(layer "In2.Cu")
		(net "FM_DIMM_EVENT_COD_N")
	)
	(segment
		(start 174.422816 -5.51942)
		(end 172.920914 -5.51942)
		(width 0.089408)
		(layer "In2.Cu")
		(net "FM_DIMM_EVENT_COD_N")
	)
	(segment
		(start 264.394188 4.431792)
		(end 265.684 3.14198)
		(width 0.089408)
		(layer "In2.Cu")
		(net "FM_DIMM_EVENT_COD_N")
	)
	(segment
		(start 113.49736 -156.018484)
		(end 157.446218 -156.018484)
		(width 0.089408)
		(layer "In2.Cu")
		(net "FM_DIMM_EVENT_COD_N")
	)
	(segment
		(start 157.446218 -156.018484)
		(end 157.83052 -156.402786)
		(width 0.089408)
		(layer "In2.Cu")
		(net "FM_DIMM_EVENT_COD_N")
	)
	(segment
		(start 102.623874 2.905506)
		(end 101.27488 2.905506)
		(width 0.089408)
		(layer "In2.Cu")
		(net "FM_DIMM_EVENT_COD_N")
	)
	(segment
		(start 109.77499 2.905506)
		(end 109.765338 2.915158)
		(width 0.089408)
		(layer "In2.Cu")
		(net "FM_DIMM_EVENT_COD_N")
	)
	(segment
		(start 185.654442 -20.069302)
		(end 184.83834 -20.885404)
		(width 0.089408)
		(layer "In2.Cu")
		(net "FM_DIMM_EVENT_COD_N")
	)
	(segment
		(start 184.709308 2.260346)
		(end 181.793388 2.260346)
		(width 0.089408)
		(layer "In2.Cu")
		(net "FM_DIMM_EVENT_COD_N")
	)
	(segment
		(start 180.0352 -4.5212)
		(end 178.727608 -5.828792)
		(width 0.089408)
		(layer "In2.Cu")
		(net "FM_DIMM_EVENT_COD_N")
	)
	(segment
		(start 174.19066 -62.14364)
		(end 174.19066 -63.458344)
		(width 0.089408)
		(layer "In2.Cu")
		(net "FM_DIMM_EVENT_COD_N")
	)
	(segment
		(start 185.72734 3.269996)
		(end 185.358024 2.90068)
		(width 0.089408)
		(layer "In2.Cu")
		(net "FM_DIMM_EVENT_COD_N")
	)
	(segment
		(start 187.206636 4.431792)
		(end 264.394188 4.431792)
		(width 0.089408)
		(layer "In2.Cu")
		(net "FM_DIMM_EVENT_COD_N")
	)
	(segment
		(start 160.167828 -156.1084)
		(end 160.462214 -156.402786)
		(width 0.089408)
		(layer "In2.Cu")
		(net "FM_DIMM_EVENT_COD_N")
	)
	(segment
		(start 99.822 -155.889706)
		(end 99.950778 -156.018484)
		(width 0.089408)
		(layer "In2.Cu")
		(net "FM_DIMM_EVENT_COD_N")
	)
	(segment
		(start 100.60686 0.92964)
		(end 100.731066 0.805434)
		(width 0.089408)
		(layer "In2.Cu")
		(net "FM_DIMM_EVENT_COD_N")
	)
	(segment
		(start 100.60686 2.703322)
		(end 100.60686 0.92964)
		(width 0.089408)
		(layer "In2.Cu")
		(net "FM_DIMM_EVENT_COD_N")
	)
	(segment
		(start 165.31971 -6.60527)
		(end 164.079936 -5.365496)
		(width 0.089408)
		(layer "In2.Cu")
		(net "FM_DIMM_EVENT_COD_N")
	)
	(segment
		(start 100.731066 0.805434)
		(end 100.731066 -0.946658)
		(width 0.089408)
		(layer "In2.Cu")
		(net "FM_DIMM_EVENT_COD_N")
	)
	(segment
		(start 328.886312 -9.90092)
		(end 329.414632 -9.3726)
		(width 0.089408)
		(layer "In2.Cu")
		(net "FM_DIMM_EVENT_COD_N")
	)
	(segment
		(start 181.793388 2.260346)
		(end 180.262784 0.729742)
		(width 0.089408)
		(layer "In2.Cu")
		(net "FM_DIMM_EVENT_COD_N")
	)
	(segment
		(start 180.262784 -0.111506)
		(end 180.0352 -0.33909)
		(width 0.089408)
		(layer "In2.Cu")
		(net "FM_DIMM_EVENT_COD_N")
	)
	(segment
		(start 110.408212 -155.08986)
		(end 110.917736 -155.08986)
		(width 0.089408)
		(layer "In2.Cu")
		(net "FM_DIMM_EVENT_COD_N")
	)
	(segment
		(start 115.82527 2.981452)
		(end 114.958368 2.11455)
		(width 0.089408)
		(layer "In2.Cu")
		(net "FM_DIMM_EVENT_COD_N")
	)
	(segment
		(start 99.950778 -156.018484)
		(end 107.503976 -156.018484)
		(width 0.089408)
		(layer "In2.Cu")
		(net "FM_DIMM_EVENT_COD_N")
	)
	(segment
		(start 175.13808 -75.33386)
		(end 175.13808 -78.178914)
		(width 0.089408)
		(layer "In2.Cu")
		(net "FM_DIMM_EVENT_COD_N")
	)
	(segment
		(start 175.13808 -78.178914)
		(end 175.177704 -78.218538)
		(width 0.089408)
		(layer "In2.Cu")
		(net "FM_DIMM_EVENT_COD_N")
	)
	(segment
		(start 329.617832 -9.5758)
		(end 329.414632 -9.3726)
		(width 0.089408)
		(layer "In9.Cu")
		(net "FM_DIMM_EVENT_COD_N")
	)
	(segment
		(start 330.327 -9.5758)
		(end 329.617832 -9.5758)
		(width 0.089408)
		(layer "In9.Cu")
		(net "FM_DIMM_EVENT_COD_N")
	)
	(segment
		(start 330.927964 -10.176764)
		(end 330.327 -9.5758)
		(width 0.089408)
		(layer "In9.Cu")
		(net "FM_DIMM_EVENT_COD_N")
	)
	(segment
		(start 331.343 -10.176764)
		(end 330.927964 -10.176764)
		(width 0.089408)
		(layer "In9.Cu")
		(net "FM_DIMM_EVENT_COD_N")
	)
	(segment
		(start 170.9928 -151.5364)
		(end 168.5798 -153.9494)
		(width 0.089408)
		(layer "In11.Cu")
		(net "FM_DIMM_EVENT_COD_N")
	)
	(segment
		(start 189.612016 -15.26794)
		(end 185.510678 -15.26794)
		(width 0.089408)
		(layer "In11.Cu")
		(net "FM_DIMM_EVENT_COD_N")
	)
	(segment
		(start 190.161418 3.844036)
		(end 192.469008 1.536446)
		(width 0.089408)
		(layer "In11.Cu")
		(net "FM_DIMM_EVENT_COD_N")
	)
	(segment
		(start 192.60566 -7.72414)
		(end 191.599312 -8.730488)
		(width 0.089408)
		(layer "In11.Cu")
		(net "FM_DIMM_EVENT_COD_N")
	)
	(segment
		(start 191.599312 -10.701274)
		(end 191.496696 -10.80389)
		(width 0.089408)
		(layer "In11.Cu")
		(net "FM_DIMM_EVENT_COD_N")
	)
	(segment
		(start 191.599312 -8.730488)
		(end 191.599312 -10.701274)
		(width 0.089408)
		(layer "In11.Cu")
		(net "FM_DIMM_EVENT_COD_N")
	)
	(segment
		(start 168.5798 -153.9494)
		(end 166.4462 -153.9494)
		(width 0.089408)
		(layer "In11.Cu")
		(net "FM_DIMM_EVENT_COD_N")
	)
	(segment
		(start 184.93232 -15.846298)
		(end 184.93232 -18.407888)
		(width 0.089408)
		(layer "In11.Cu")
		(net "FM_DIMM_EVENT_COD_N")
	)
	(segment
		(start 265.627866 -158.185866)
		(end 265.624056 -158.189676)
		(width 0.089408)
		(layer "In11.Cu")
		(net "FM_DIMM_EVENT_COD_N")
	)
	(segment
		(start 163.5506 -156.845)
		(end 160.904428 -156.845)
		(width 0.089408)
		(layer "In11.Cu")
		(net "FM_DIMM_EVENT_COD_N")
	)
	(segment
		(start 180.174392 -153.631392)
		(end 176.9364 -150.3934)
		(width 0.089408)
		(layer "In11.Cu")
		(net "FM_DIMM_EVENT_COD_N")
	)
	(segment
		(start 191.496696 -10.80389)
		(end 191.496696 -13.38326)
		(width 0.089408)
		(layer "In11.Cu")
		(net "FM_DIMM_EVENT_COD_N")
	)
	(segment
		(start 184.93232 -18.407888)
		(end 185.654442 -19.13001)
		(width 0.089408)
		(layer "In11.Cu")
		(net "FM_DIMM_EVENT_COD_N")
	)
	(segment
		(start 181.42839 -155.893008)
		(end 180.174392 -154.63901)
		(width 0.089408)
		(layer "In11.Cu")
		(net "FM_DIMM_EVENT_COD_N")
	)
	(segment
		(start 172.9994 -151.5364)
		(end 170.9928 -151.5364)
		(width 0.089408)
		(layer "In11.Cu")
		(net "FM_DIMM_EVENT_COD_N")
	)
	(segment
		(start 185.484008 -155.893008)
		(end 181.42839 -155.893008)
		(width 0.089408)
		(layer "In11.Cu")
		(net "FM_DIMM_EVENT_COD_N")
	)
	(segment
		(start 187.780676 -158.189676)
		(end 185.484008 -155.893008)
		(width 0.089408)
		(layer "In11.Cu")
		(net "FM_DIMM_EVENT_COD_N")
	)
	(segment
		(start 185.72734 3.844036)
		(end 190.161418 3.844036)
		(width 0.089408)
		(layer "In11.Cu")
		(net "FM_DIMM_EVENT_COD_N")
	)
	(segment
		(start 185.510678 -15.26794)
		(end 184.93232 -15.846298)
		(width 0.089408)
		(layer "In11.Cu")
		(net "FM_DIMM_EVENT_COD_N")
	)
	(segment
		(start 265.624056 -158.189676)
		(end 187.780676 -158.189676)
		(width 0.089408)
		(layer "In11.Cu")
		(net "FM_DIMM_EVENT_COD_N")
	)
	(segment
		(start 192.469008 1.536446)
		(end 192.469008 -5.572506)
		(width 0.089408)
		(layer "In11.Cu")
		(net "FM_DIMM_EVENT_COD_N")
	)
	(segment
		(start 180.174392 -154.63901)
		(end 180.174392 -153.631392)
		(width 0.089408)
		(layer "In11.Cu")
		(net "FM_DIMM_EVENT_COD_N")
	)
	(segment
		(start 191.496696 -13.38326)
		(end 189.612016 -15.26794)
		(width 0.089408)
		(layer "In11.Cu")
		(net "FM_DIMM_EVENT_COD_N")
	)
	(segment
		(start 174.1424 -150.3934)
		(end 172.9994 -151.5364)
		(width 0.089408)
		(layer "In11.Cu")
		(net "FM_DIMM_EVENT_COD_N")
	)
	(segment
		(start 166.4462 -153.9494)
		(end 163.5506 -156.845)
		(width 0.089408)
		(layer "In11.Cu")
		(net "FM_DIMM_EVENT_COD_N")
	)
	(segment
		(start 265.811 -158.369)
		(end 265.627866 -158.185866)
		(width 0.089408)
		(layer "In11.Cu")
		(net "FM_DIMM_EVENT_COD_N")
	)
	(segment
		(start 192.469008 -5.572506)
		(end 192.60566 -5.709158)
		(width 0.089408)
		(layer "In11.Cu")
		(net "FM_DIMM_EVENT_COD_N")
	)
	(segment
		(start 160.904428 -156.845)
		(end 160.462214 -156.402786)
		(width 0.089408)
		(layer "In11.Cu")
		(net "FM_DIMM_EVENT_COD_N")
	)
	(segment
		(start 176.9364 -150.3934)
		(end 174.1424 -150.3934)
		(width 0.089408)
		(layer "In11.Cu")
		(net "FM_DIMM_EVENT_COD_N")
	)
	(segment
		(start 192.60566 -5.709158)
		(end 192.60566 -7.72414)
		(width 0.089408)
		(layer "In11.Cu")
		(net "FM_DIMM_EVENT_COD_N")
	)
	(segment
		(start 418.203126 -114.32286)
		(end 417.946586 -114.5794)
		(width 0.10795)
		(layer "F.Cu")
		(net "FM_CPLD_ADR_TRIGGER_N")
	)
	(segment
		(start 417.946586 -114.5794)
		(end 416.0901 -114.5794)
		(width 0.10795)
		(layer "F.Cu")
		(net "FM_CPLD_ADR_TRIGGER_N")
	)
	(segment
		(start 416.0901 -114.5794)
		(end 415.7345 -114.935)
		(width 0.10795)
		(layer "F.Cu")
		(net "FM_CPLD_ADR_TRIGGER_N")
	)
	(segment
		(start 367.945162 -71.095108)
		(end 368.344958 -71.494904)
		(width 0.1016)
		(layer "F.Cu")
		(net "FM_CPLD_ADR_TRIGGER_N")
	)
	(via
		(at 423.25163 -61.464698)
		(size 0.508)
		(drill 0.254)
		(layers "F.Cu" "B.Cu")
		(net "FM_CPLD_ADR_TRIGGER_N")
	)
	(via
		(at 424.014392 -61.178948)
		(size 0.6604)
		(drill 0.3302)
		(layers "F.Cu" "B.Cu")
		(net "FM_CPLD_ADR_TRIGGER_N")
	)
	(via
		(at 367.945162 -71.095108)
		(size 0.4572)
		(drill 0.2032)
		(layers "F.Cu" "B.Cu")
		(net "FM_CPLD_ADR_TRIGGER_N")
	)
	(via
		(at 418.203126 -114.32286)
		(size 0.508)
		(drill 0.254)
		(layers "F.Cu" "B.Cu")
		(net "FM_CPLD_ADR_TRIGGER_N")
	)
	(segment
		(start 423.728642 -61.464698)
		(end 424.014392 -61.178948)
		(width 0.10795)
		(layer "B.Cu")
		(net "FM_CPLD_ADR_TRIGGER_N")
	)
	(segment
		(start 423.25163 -61.464698)
		(end 423.728642 -61.464698)
		(width 0.10795)
		(layer "B.Cu")
		(net "FM_CPLD_ADR_TRIGGER_N")
	)
	(segment
		(start 419.961822 -76.625958)
		(end 419.35908 -77.2287)
		(width 0.089408)
		(layer "In2.Cu")
		(net "FM_CPLD_ADR_TRIGGER_N")
	)
	(segment
		(start 419.962076 -74.694542)
		(end 419.962076 -74.85253)
		(width 0.089408)
		(layer "In2.Cu")
		(net "FM_CPLD_ADR_TRIGGER_N")
	)
	(segment
		(start 422.394634 -63.902336)
		(end 421.128444 -63.902336)
		(width 0.089408)
		(layer "In2.Cu")
		(net "FM_CPLD_ADR_TRIGGER_N")
	)
	(segment
		(start 419.35908 -81.818988)
		(end 419.359334 -81.819242)
		(width 0.089408)
		(layer "In2.Cu")
		(net "FM_CPLD_ADR_TRIGGER_N")
	)
	(segment
		(start 420.95293 -88.917272)
		(end 420.95293 -93.366336)
		(width 0.089408)
		(layer "In2.Cu")
		(net "FM_CPLD_ADR_TRIGGER_N")
	)
	(segment
		(start 420.193978 -65.685924)
		(end 420.193724 -65.686178)
		(width 0.089408)
		(layer "In2.Cu")
		(net "FM_CPLD_ADR_TRIGGER_N")
	)
	(segment
		(start 423.25163 -61.464698)
		(end 423.64787 -61.860938)
		(width 0.089408)
		(layer "In2.Cu")
		(net "FM_CPLD_ADR_TRIGGER_N")
	)
	(segment
		(start 423.64787 -62.6491)
		(end 422.394634 -63.902336)
		(width 0.089408)
		(layer "In2.Cu")
		(net "FM_CPLD_ADR_TRIGGER_N")
	)
	(segment
		(start 419.961822 -74.694288)
		(end 419.962076 -74.694542)
		(width 0.089408)
		(layer "In2.Cu")
		(net "FM_CPLD_ADR_TRIGGER_N")
	)
	(segment
		(start 420.193978 -64.836802)
		(end 420.193978 -65.685924)
		(width 0.089408)
		(layer "In2.Cu")
		(net "FM_CPLD_ADR_TRIGGER_N")
	)
	(segment
		(start 418.980112 -95.339154)
		(end 418.980112 -113.545874)
		(width 0.089408)
		(layer "In2.Cu")
		(net "FM_CPLD_ADR_TRIGGER_N")
	)
	(segment
		(start 418.980112 -113.545874)
		(end 418.203126 -114.32286)
		(width 0.089408)
		(layer "In2.Cu")
		(net "FM_CPLD_ADR_TRIGGER_N")
	)
	(segment
		(start 419.962076 -74.85253)
		(end 419.96233 -74.852784)
		(width 0.089408)
		(layer "In2.Cu")
		(net "FM_CPLD_ADR_TRIGGER_N")
	)
	(segment
		(start 420.95293 -93.366336)
		(end 418.980112 -95.339154)
		(width 0.089408)
		(layer "In2.Cu")
		(net "FM_CPLD_ADR_TRIGGER_N")
	)
	(segment
		(start 419.961822 -72.052688)
		(end 419.961822 -74.694288)
		(width 0.089408)
		(layer "In2.Cu")
		(net "FM_CPLD_ADR_TRIGGER_N")
	)
	(segment
		(start 419.96233 -76.489052)
		(end 419.961822 -76.48956)
		(width 0.089408)
		(layer "In2.Cu")
		(net "FM_CPLD_ADR_TRIGGER_N")
	)
	(segment
		(start 423.64787 -61.860938)
		(end 423.64787 -62.6491)
		(width 0.089408)
		(layer "In2.Cu")
		(net "FM_CPLD_ADR_TRIGGER_N")
	)
	(segment
		(start 419.35908 -77.2287)
		(end 419.35908 -81.818988)
		(width 0.089408)
		(layer "In2.Cu")
		(net "FM_CPLD_ADR_TRIGGER_N")
	)
	(segment
		(start 419.359334 -83.614006)
		(end 419.35908 -83.61426)
		(width 0.089408)
		(layer "In2.Cu")
		(net "FM_CPLD_ADR_TRIGGER_N")
	)
	(segment
		(start 419.35908 -83.61426)
		(end 419.35908 -86.607396)
		(width 0.089408)
		(layer "In2.Cu")
		(net "FM_CPLD_ADR_TRIGGER_N")
	)
	(segment
		(start 420.193724 -65.686178)
		(end 420.193724 -71.820786)
		(width 0.089408)
		(layer "In2.Cu")
		(net "FM_CPLD_ADR_TRIGGER_N")
	)
	(segment
		(start 420.95293 -88.201246)
		(end 420.95293 -88.60028)
		(width 0.089408)
		(layer "In2.Cu")
		(net "FM_CPLD_ADR_TRIGGER_N")
	)
	(segment
		(start 419.359334 -81.819242)
		(end 419.359334 -83.614006)
		(width 0.089408)
		(layer "In2.Cu")
		(net "FM_CPLD_ADR_TRIGGER_N")
	)
	(segment
		(start 419.961822 -76.48956)
		(end 419.961822 -76.625958)
		(width 0.089408)
		(layer "In2.Cu")
		(net "FM_CPLD_ADR_TRIGGER_N")
	)
	(segment
		(start 420.95293 -88.60028)
		(end 420.953184 -88.600534)
		(width 0.089408)
		(layer "In2.Cu")
		(net "FM_CPLD_ADR_TRIGGER_N")
	)
	(segment
		(start 419.96233 -74.852784)
		(end 419.96233 -76.489052)
		(width 0.089408)
		(layer "In2.Cu")
		(net "FM_CPLD_ADR_TRIGGER_N")
	)
	(segment
		(start 421.128444 -63.902336)
		(end 420.193978 -64.836802)
		(width 0.089408)
		(layer "In2.Cu")
		(net "FM_CPLD_ADR_TRIGGER_N")
	)
	(segment
		(start 420.193724 -71.820786)
		(end 419.961822 -72.052688)
		(width 0.089408)
		(layer "In2.Cu")
		(net "FM_CPLD_ADR_TRIGGER_N")
	)
	(segment
		(start 420.953184 -88.917018)
		(end 420.95293 -88.917272)
		(width 0.089408)
		(layer "In2.Cu")
		(net "FM_CPLD_ADR_TRIGGER_N")
	)
	(segment
		(start 420.953184 -88.600534)
		(end 420.953184 -88.917018)
		(width 0.089408)
		(layer "In2.Cu")
		(net "FM_CPLD_ADR_TRIGGER_N")
	)
	(segment
		(start 419.35908 -86.607396)
		(end 420.95293 -88.201246)
		(width 0.089408)
		(layer "In2.Cu")
		(net "FM_CPLD_ADR_TRIGGER_N")
	)
	(segment
		(start 414.175702 -68.211954)
		(end 414.08731 -68.211954)
		(width 0.089408)
		(layer "In4.Cu")
		(net "FM_CPLD_ADR_TRIGGER_N")
	)
	(segment
		(start 406.282652 -68.751196)
		(end 397.320516 -68.751196)
		(width 0.089408)
		(layer "In4.Cu")
		(net "FM_CPLD_ADR_TRIGGER_N")
	)
	(segment
		(start 423.042334 -61.255402)
		(end 422.12387 -61.255402)
		(width 0.089408)
		(layer "In4.Cu")
		(net "FM_CPLD_ADR_TRIGGER_N")
	)
	(segment
		(start 397.320516 -68.751196)
		(end 394.716 -66.14668)
		(width 0.089408)
		(layer "In4.Cu")
		(net "FM_CPLD_ADR_TRIGGER_N")
	)
	(segment
		(start 374.45442 -70.7136)
		(end 368.32667 -70.7136)
		(width 0.089408)
		(layer "In4.Cu")
		(net "FM_CPLD_ADR_TRIGGER_N")
	)
	(segment
		(start 374.940322 -69.903848)
		(end 374.771412 -70.072758)
		(width 0.089408)
		(layer "In4.Cu")
		(net "FM_CPLD_ADR_TRIGGER_N")
	)
	(segment
		(start 391.248138 -66.14668)
		(end 391.247884 -66.146426)
		(width 0.089408)
		(layer "In4.Cu")
		(net "FM_CPLD_ADR_TRIGGER_N")
	)
	(segment
		(start 394.716 -66.14668)
		(end 391.248138 -66.14668)
		(width 0.089408)
		(layer "In4.Cu")
		(net "FM_CPLD_ADR_TRIGGER_N")
	)
	(segment
		(start 377.84786 -67.446398)
		(end 376.66549 -67.446398)
		(width 0.089408)
		(layer "In4.Cu")
		(net "FM_CPLD_ADR_TRIGGER_N")
	)
	(segment
		(start 376.33148 -68.947538)
		(end 376.179334 -69.099684)
		(width 0.089408)
		(layer "In4.Cu")
		(net "FM_CPLD_ADR_TRIGGER_N")
	)
	(segment
		(start 421.946832 -61.43244)
		(end 421.187626 -61.43244)
		(width 0.089408)
		(layer "In4.Cu")
		(net "FM_CPLD_ADR_TRIGGER_N")
	)
	(segment
		(start 375.756678 -69.099684)
		(end 375.541032 -69.31533)
		(width 0.089408)
		(layer "In4.Cu")
		(net "FM_CPLD_ADR_TRIGGER_N")
	)
	(segment
		(start 375.541032 -69.663564)
		(end 375.300748 -69.903848)
		(width 0.089408)
		(layer "In4.Cu")
		(net "FM_CPLD_ADR_TRIGGER_N")
	)
	(segment
		(start 376.33148 -67.780408)
		(end 376.33148 -68.947538)
		(width 0.089408)
		(layer "In4.Cu")
		(net "FM_CPLD_ADR_TRIGGER_N")
	)
	(segment
		(start 407.570686 -69.12483)
		(end 406.656286 -69.12483)
		(width 0.089408)
		(layer "In4.Cu")
		(net "FM_CPLD_ADR_TRIGGER_N")
	)
	(segment
		(start 414.086548 -68.212716)
		(end 408.4828 -68.212716)
		(width 0.089408)
		(layer "In4.Cu")
		(net "FM_CPLD_ADR_TRIGGER_N")
	)
	(segment
		(start 422.12387 -61.255402)
		(end 421.946832 -61.43244)
		(width 0.089408)
		(layer "In4.Cu")
		(net "FM_CPLD_ADR_TRIGGER_N")
	)
	(segment
		(start 379.046232 -68.36029)
		(end 378.746258 -68.060316)
		(width 0.089408)
		(layer "In4.Cu")
		(net "FM_CPLD_ADR_TRIGGER_N")
	)
	(segment
		(start 374.771412 -70.072758)
		(end 374.771412 -70.396608)
		(width 0.089408)
		(layer "In4.Cu")
		(net "FM_CPLD_ADR_TRIGGER_N")
	)
	(segment
		(start 421.187626 -61.43244)
		(end 417.011866 -65.6082)
		(width 0.089408)
		(layer "In4.Cu")
		(net "FM_CPLD_ADR_TRIGGER_N")
	)
	(segment
		(start 415.509456 -65.6082)
		(end 414.673288 -66.444368)
		(width 0.089408)
		(layer "In4.Cu")
		(net "FM_CPLD_ADR_TRIGGER_N")
	)
	(segment
		(start 374.771412 -70.396608)
		(end 374.45442 -70.7136)
		(width 0.089408)
		(layer "In4.Cu")
		(net "FM_CPLD_ADR_TRIGGER_N")
	)
	(segment
		(start 417.011866 -65.6082)
		(end 415.509456 -65.6082)
		(width 0.089408)
		(layer "In4.Cu")
		(net "FM_CPLD_ADR_TRIGGER_N")
	)
	(segment
		(start 406.656286 -69.12483)
		(end 406.282652 -68.751196)
		(width 0.089408)
		(layer "In4.Cu")
		(net "FM_CPLD_ADR_TRIGGER_N")
	)
	(segment
		(start 378.461778 -68.060316)
		(end 377.84786 -67.446398)
		(width 0.089408)
		(layer "In4.Cu")
		(net "FM_CPLD_ADR_TRIGGER_N")
	)
	(segment
		(start 414.08731 -68.211954)
		(end 414.086548 -68.212716)
		(width 0.089408)
		(layer "In4.Cu")
		(net "FM_CPLD_ADR_TRIGGER_N")
	)
	(segment
		(start 375.300748 -69.903848)
		(end 374.940322 -69.903848)
		(width 0.089408)
		(layer "In4.Cu")
		(net "FM_CPLD_ADR_TRIGGER_N")
	)
	(segment
		(start 388.876032 -68.36029)
		(end 379.046232 -68.36029)
		(width 0.089408)
		(layer "In4.Cu")
		(net "FM_CPLD_ADR_TRIGGER_N")
	)
	(segment
		(start 375.541032 -69.31533)
		(end 375.541032 -69.663564)
		(width 0.089408)
		(layer "In4.Cu")
		(net "FM_CPLD_ADR_TRIGGER_N")
	)
	(segment
		(start 391.247884 -66.146426)
		(end 391.089896 -66.146426)
		(width 0.089408)
		(layer "In4.Cu")
		(net "FM_CPLD_ADR_TRIGGER_N")
	)
	(segment
		(start 391.089896 -66.146426)
		(end 388.876032 -68.36029)
		(width 0.089408)
		(layer "In4.Cu")
		(net "FM_CPLD_ADR_TRIGGER_N")
	)
	(segment
		(start 376.179334 -69.099684)
		(end 375.756678 -69.099684)
		(width 0.089408)
		(layer "In4.Cu")
		(net "FM_CPLD_ADR_TRIGGER_N")
	)
	(segment
		(start 414.673288 -67.714368)
		(end 414.175702 -68.211954)
		(width 0.089408)
		(layer "In4.Cu")
		(net "FM_CPLD_ADR_TRIGGER_N")
	)
	(segment
		(start 376.66549 -67.446398)
		(end 376.33148 -67.780408)
		(width 0.089408)
		(layer "In4.Cu")
		(net "FM_CPLD_ADR_TRIGGER_N")
	)
	(segment
		(start 414.673288 -66.444368)
		(end 414.673288 -67.714368)
		(width 0.089408)
		(layer "In4.Cu")
		(net "FM_CPLD_ADR_TRIGGER_N")
	)
	(segment
		(start 378.746258 -68.060316)
		(end 378.461778 -68.060316)
		(width 0.089408)
		(layer "In4.Cu")
		(net "FM_CPLD_ADR_TRIGGER_N")
	)
	(segment
		(start 408.4828 -68.212716)
		(end 407.570686 -69.12483)
		(width 0.089408)
		(layer "In4.Cu")
		(net "FM_CPLD_ADR_TRIGGER_N")
	)
	(segment
		(start 368.32667 -70.7136)
		(end 367.945162 -71.095108)
		(width 0.089408)
		(layer "In4.Cu")
		(net "FM_CPLD_ADR_TRIGGER_N")
	)
	(segment
		(start 423.25163 -61.464698)
		(end 423.042334 -61.255402)
		(width 0.089408)
		(layer "In4.Cu")
		(net "FM_CPLD_ADR_TRIGGER_N")
	)
	(segment
		(start 466.478366 -25.776936)
		(end 466.476842 -25.77846)
		(width 0.127)
		(layer "F.Cu")
		(net "VSENSE_VOUT_P3V3_STBY")
	)
	(segment
		(start 467.257892 -25.776936)
		(end 467.53145 -25.503378)
		(width 0.127)
		(layer "F.Cu")
		(net "VSENSE_VOUT_P3V3_STBY")
	)
	(segment
		(start 467.53145 -25.503378)
		(end 467.53145 -24.0284)
		(width 0.127)
		(layer "F.Cu")
		(net "VSENSE_VOUT_P3V3_STBY")
	)
	(segment
		(start 467.257892 -25.776936)
		(end 466.478366 -25.776936)
		(width 0.127)
		(layer "F.Cu")
		(net "VSENSE_VOUT_P3V3_STBY")
	)
	(segment
		(start 465.952332 -24.8539)
		(end 465.5947 -24.8539)
		(width 0.127)
		(layer "F.Cu")
		(net "VSENSE_RGND_P3V3_STBY")
	)
	(segment
		(start 465.999576 -24.806656)
		(end 465.952332 -24.8539)
		(width 0.127)
		(layer "F.Cu")
		(net "VSENSE_RGND_P3V3_STBY")
	)
	(segment
		(start 466.9536 -24.637238)
		(end 466.784182 -24.806656)
		(width 0.127)
		(layer "F.Cu")
		(net "VSENSE_RGND_P3V3_STBY")
	)
	(segment
		(start 466.478874 -24.806656)
		(end 465.999576 -24.806656)
		(width 0.127)
		(layer "F.Cu")
		(net "VSENSE_RGND_P3V3_STBY")
	)
	(segment
		(start 466.784182 -24.806656)
		(end 466.478874 -24.806656)
		(width 0.127)
		(layer "F.Cu")
		(net "VSENSE_RGND_P3V3_STBY")
	)
	(segment
		(start 466.9536 -23.45055)
		(end 466.9536 -24.637238)
		(width 0.127)
		(layer "F.Cu")
		(net "VSENSE_RGND_P3V3_STBY")
	)
	(via
		(at 466.478874 -24.806656)
		(size 0.508)
		(drill 0.254)
		(layers "F.Cu" "B.Cu")
		(net "VSENSE_RGND_P3V3_STBY")
	)
	(segment
		(start 170.7896 -131.0005)
		(end 170.0403 -131.0005)
		(width 0.254)
		(layer "F.Cu")
		(net "VSENSE_PVPP_KLM")
	)
	(segment
		(start 169.635678 -129.068068)
		(end 169.635678 -129.728468)
		(width 0.254)
		(layer "F.Cu")
		(net "VSENSE_PVPP_KLM")
	)
	(segment
		(start 170.0403 -131.0005)
		(end 170.0276 -130.9878)
		(width 0.254)
		(layer "F.Cu")
		(net "VSENSE_PVPP_KLM")
	)
	(segment
		(start 170.311064 -129.068068)
		(end 169.635678 -129.068068)
		(width 0.254)
		(layer "F.Cu")
		(net "VSENSE_PVPP_KLM")
	)
	(segment
		(start 170.6245 -129.381504)
		(end 170.311064 -129.068068)
		(width 0.254)
		(layer "F.Cu")
		(net "VSENSE_PVPP_KLM")
	)
	(segment
		(start 169.635678 -129.728468)
		(end 170.0276 -130.12039)
		(width 0.254)
		(layer "F.Cu")
		(net "VSENSE_PVPP_KLM")
	)
	(segment
		(start 170.0276 -130.12039)
		(end 170.0276 -130.9878)
		(width 0.254)
		(layer "F.Cu")
		(net "VSENSE_PVPP_KLM")
	)
	(segment
		(start 170.6245 -130.175)
		(end 170.6245 -129.381504)
		(width 0.254)
		(layer "F.Cu")
		(net "VSENSE_PVPP_KLM")
	)
	(via
		(at 169.635678 -129.068068)
		(size 0.762)
		(drill 0.381)
		(layers "F.Cu" "B.Cu")
		(net "VSENSE_PVPP_KLM")
	)
	(segment
		(start 168.7322 -8.0137)
		(end 168.6941 -8.0518)
		(width 0.254)
		(layer "F.Cu")
		(net "VSENSE_PVPP_GHJ")
	)
	(segment
		(start 168.443148 -9.013952)
		(end 168.6941 -8.763)
		(width 0.254)
		(layer "F.Cu")
		(net "VSENSE_PVPP_GHJ")
	)
	(segment
		(start 167.866822 -9.013952)
		(end 168.443148 -9.013952)
		(width 0.254)
		(layer "F.Cu")
		(net "VSENSE_PVPP_GHJ")
	)
	(segment
		(start 168.6941 -8.0518)
		(end 168.6941 -8.763)
		(width 0.254)
		(layer "F.Cu")
		(net "VSENSE_PVPP_GHJ")
	)
	(segment
		(start 336.090768 -127.555244)
		(end 336.090768 -127.172212)
		(width 0.254)
		(layer "F.Cu")
		(net "VSENSE_PVPP_DEF")
	)
	(segment
		(start 336.30362 -127.254)
		(end 336.1563 -127.10668)
		(width 0.254)
		(layer "F.Cu")
		(net "VSENSE_PVPP_DEF")
	)
	(segment
		(start 337.0326 -128.2065)
		(end 336.2706 -128.2065)
		(width 0.254)
		(layer "F.Cu")
		(net "VSENSE_PVPP_DEF")
	)
	(segment
		(start 336.090768 -127.172212)
		(end 336.1563 -127.10668)
		(width 0.254)
		(layer "F.Cu")
		(net "VSENSE_PVPP_DEF")
	)
	(segment
		(start 336.2706 -127.735076)
		(end 336.090768 -127.555244)
		(width 0.254)
		(layer "F.Cu")
		(net "VSENSE_PVPP_DEF")
	)
	(segment
		(start 336.2706 -128.2065)
		(end 336.2706 -127.735076)
		(width 0.254)
		(layer "F.Cu")
		(net "VSENSE_PVPP_DEF")
	)
	(segment
		(start 337.1215 -127.254)
		(end 336.30362 -127.254)
		(width 0.254)
		(layer "F.Cu")
		(net "VSENSE_PVPP_DEF")
	)
	(via
		(at 336.1563 -127.10668)
		(size 0.762)
		(drill 0.381)
		(layers "F.Cu" "B.Cu")
		(net "VSENSE_PVPP_DEF")
	)
	(segment
		(start 335.788 -24.13)
		(end 335.788 -23.241)
		(width 0.254)
		(layer "F.Cu")
		(net "VSENSE_PVPP_ABC")
	)
	(segment
		(start 335.788 -24.13)
		(end 335.026 -24.13)
		(width 0.254)
		(layer "F.Cu")
		(net "VSENSE_PVPP_ABC")
	)
	(segment
		(start 467.257892 -26.665936)
		(end 466.890354 -26.665936)
		(width 0.127)
		(layer "F.Cu")
		(net "VSENSE_P3V3_STBY")
	)
	(segment
		(start 466.781642 -26.557224)
		(end 466.482938 -26.557224)
		(width 0.127)
		(layer "F.Cu")
		(net "VSENSE_P3V3_STBY")
	)
	(segment
		(start 466.890354 -26.665936)
		(end 466.781642 -26.557224)
		(width 0.127)
		(layer "F.Cu")
		(net "VSENSE_P3V3_STBY")
	)
	(segment
		(start 469.638888 -23.677626)
		(end 469.459564 -23.677626)
		(width 0.2032)
		(layer "F.Cu")
		(net "VR_P3V3_STBY_UGATE")
	)
	(segment
		(start 471.513916 -24.49322)
		(end 471.1573 -24.49322)
		(width 0.3302)
		(layer "F.Cu")
		(net "VR_P3V3_STBY_UGATE")
	)
	(segment
		(start 469.459564 -23.677626)
		(end 469.232488 -23.45055)
		(width 0.2032)
		(layer "F.Cu")
		(net "VR_P3V3_STBY_UGATE")
	)
	(segment
		(start 471.1573 -24.49322)
		(end 470.341706 -23.677626)
		(width 0.3302)
		(layer "F.Cu")
		(net "VR_P3V3_STBY_UGATE")
	)
	(segment
		(start 470.341706 -23.677626)
		(end 470.003378 -23.677626)
		(width 0.3302)
		(layer "F.Cu")
		(net "VR_P3V3_STBY_UGATE")
	)
	(segment
		(start 470.003378 -23.677626)
		(end 469.638888 -23.677626)
		(width 0.3302)
		(layer "F.Cu")
		(net "VR_P3V3_STBY_UGATE")
	)
	(segment
		(start 469.232488 -23.45055)
		(end 468.9094 -23.45055)
		(width 0.2032)
		(layer "F.Cu")
		(net "VR_P3V3_STBY_UGATE")
	)
	(via
		(at 470.003378 -23.677626)
		(size 0.508)
		(drill 0.254)
		(layers "F.Cu" "B.Cu")
		(net "VR_P3V3_STBY_UGATE")
	)
	(segment
		(start 468.9094 -22.65045)
		(end 469.372696 -22.65045)
		(width 0.2032)
		(layer "F.Cu")
		(net "VR_P3V3_STBY_LGATE")
	)
	(segment
		(start 469.372696 -22.65045)
		(end 469.530684 -22.492462)
		(width 0.2032)
		(layer "F.Cu")
		(net "VR_P3V3_STBY_LGATE")
	)
	(segment
		(start 470.026492 -22.251924)
		(end 470.832434 -21.445982)
		(width 0.3302)
		(layer "F.Cu")
		(net "VR_P3V3_STBY_LGATE")
	)
	(segment
		(start 469.785954 -22.492462)
		(end 470.026492 -22.251924)
		(width 0.3302)
		(layer "F.Cu")
		(net "VR_P3V3_STBY_LGATE")
	)
	(segment
		(start 470.832434 -21.445982)
		(end 471.513916 -21.445982)
		(width 0.3302)
		(layer "F.Cu")
		(net "VR_P3V3_STBY_LGATE")
	)
	(segment
		(start 469.530684 -22.492462)
		(end 469.785954 -22.492462)
		(width 0.2032)
		(layer "F.Cu")
		(net "VR_P3V3_STBY_LGATE")
	)
	(via
		(at 470.026492 -22.251924)
		(size 0.508)
		(drill 0.254)
		(layers "F.Cu" "B.Cu")
		(net "VR_P3V3_STBY_LGATE")
	)
	(segment
		(start 174.34814 -135.09244)
		(end 174.0408 -134.7851)
		(width 0.254)
		(layer "F.Cu")
		(net "VR_FET_SW_P12V_STBY_PVPP_KLM")
	)
	(segment
		(start 174.8409 -135.09244)
		(end 174.34814 -135.09244)
		(width 0.254)
		(layer "F.Cu")
		(net "VR_FET_SW_P12V_STBY_PVPP_KLM")
	)
	(segment
		(start 174.0408 -134.7851)
		(end 174.0408 -134.747)
		(width 0.254)
		(layer "F.Cu")
		(net "VR_FET_SW_P12V_STBY_PVPP_KLM")
	)
	(via
		(at 184.15 -135.5598)
		(size 0.508)
		(drill 0.254)
		(layers "F.Cu" "B.Cu")
		(net "VR_FET_SW_P12V_STBY_PVPP_KLM")
	)
	(via
		(at 181.2544 -135.3058)
		(size 0.508)
		(drill 0.254)
		(layers "F.Cu" "B.Cu")
		(net "VR_FET_SW_P12V_STBY_PVPP_KLM")
	)
	(via
		(at 184.912 -135.5725)
		(size 0.508)
		(drill 0.254)
		(layers "F.Cu" "B.Cu")
		(net "VR_FET_SW_P12V_STBY_PVPP_KLM")
	)
	(via
		(at 186.944 -136.5758)
		(size 0.508)
		(drill 0.254)
		(layers "F.Cu" "B.Cu")
		(net "VR_FET_SW_P12V_STBY_PVPP_KLM")
	)
	(via
		(at 181.2544 -134.0358)
		(size 0.508)
		(drill 0.254)
		(layers "F.Cu" "B.Cu")
		(net "VR_FET_SW_P12V_STBY_PVPP_KLM")
	)
	(via
		(at 181.8894 -135.3058)
		(size 0.508)
		(drill 0.254)
		(layers "F.Cu" "B.Cu")
		(net "VR_FET_SW_P12V_STBY_PVPP_KLM")
	)
	(via
		(at 180.772816 -133.472682)
		(size 0.508)
		(drill 0.254)
		(layers "F.Cu" "B.Cu")
		(net "VR_FET_SW_P12V_STBY_PVPP_KLM")
	)
	(via
		(at 181.8894 -134.6708)
		(size 0.508)
		(drill 0.254)
		(layers "F.Cu" "B.Cu")
		(net "VR_FET_SW_P12V_STBY_PVPP_KLM")
	)
	(via
		(at 174.0408 -134.747)
		(size 0.508)
		(drill 0.254)
		(layers "F.Cu" "B.Cu")
		(net "VR_FET_SW_P12V_STBY_PVPP_KLM")
	)
	(via
		(at 186.309 -135.9408)
		(size 0.508)
		(drill 0.254)
		(layers "F.Cu" "B.Cu")
		(net "VR_FET_SW_P12V_STBY_PVPP_KLM")
	)
	(via
		(at 186.944 -135.9408)
		(size 0.508)
		(drill 0.254)
		(layers "F.Cu" "B.Cu")
		(net "VR_FET_SW_P12V_STBY_PVPP_KLM")
	)
	(via
		(at 186.309 -136.5758)
		(size 0.508)
		(drill 0.254)
		(layers "F.Cu" "B.Cu")
		(net "VR_FET_SW_P12V_STBY_PVPP_KLM")
	)
	(via
		(at 181.2544 -134.6708)
		(size 0.508)
		(drill 0.254)
		(layers "F.Cu" "B.Cu")
		(net "VR_FET_SW_P12V_STBY_PVPP_KLM")
	)
	(via
		(at 181.8894 -133.4008)
		(size 0.508)
		(drill 0.254)
		(layers "F.Cu" "B.Cu")
		(net "VR_FET_SW_P12V_STBY_PVPP_KLM")
	)
	(via
		(at 181.8894 -134.0358)
		(size 0.508)
		(drill 0.254)
		(layers "F.Cu" "B.Cu")
		(net "VR_FET_SW_P12V_STBY_PVPP_KLM")
	)
	(segment
		(start 340.487 -131.0132)
		(end 340.2584 -131.0132)
		(width 0.254)
		(layer "F.Cu")
		(net "VR_FET_SW_P12V_STBY_PVPP_DEF")
	)
	(segment
		(start 341.2109 -131.10464)
		(end 340.57844 -131.10464)
		(width 0.254)
		(layer "F.Cu")
		(net "VR_FET_SW_P12V_STBY_PVPP_DEF")
	)
	(segment
		(start 340.57844 -131.10464)
		(end 340.487 -131.0132)
		(width 0.254)
		(layer "F.Cu")
		(net "VR_FET_SW_P12V_STBY_PVPP_DEF")
	)
	(via
		(at 352.135186 -132.062474)
		(size 0.508)
		(drill 0.254)
		(layers "F.Cu" "B.Cu")
		(net "VR_FET_SW_P12V_STBY_PVPP_DEF")
	)
	(via
		(at 349.531686 -132.062474)
		(size 0.508)
		(drill 0.254)
		(layers "F.Cu" "B.Cu")
		(net "VR_FET_SW_P12V_STBY_PVPP_DEF")
	)
	(via
		(at 340.2584 -131.0132)
		(size 0.508)
		(drill 0.254)
		(layers "F.Cu" "B.Cu")
		(net "VR_FET_SW_P12V_STBY_PVPP_DEF")
	)
	(via
		(at 350.79813 -132.06476)
		(size 0.508)
		(drill 0.254)
		(layers "F.Cu" "B.Cu")
		(net "VR_FET_SW_P12V_STBY_PVPP_DEF")
	)
	(via
		(at 350.166686 -132.062474)
		(size 0.508)
		(drill 0.254)
		(layers "F.Cu" "B.Cu")
		(net "VR_FET_SW_P12V_STBY_PVPP_DEF")
	)
	(via
		(at 348.82963 -132.06476)
		(size 0.508)
		(drill 0.254)
		(layers "F.Cu" "B.Cu")
		(net "VR_FET_SW_P12V_STBY_PVPP_DEF")
	)
	(via
		(at 348.850204 -131.225036)
		(size 0.6604)
		(drill 0.3302)
		(layers "F.Cu" "B.Cu")
		(net "VR_FET_SW_P12V_STBY_PVPP_DEF")
	)
	(via
		(at 351.500186 -132.062474)
		(size 0.508)
		(drill 0.254)
		(layers "F.Cu" "B.Cu")
		(net "VR_FET_SW_P12V_STBY_PVPP_DEF")
	)
	(segment
		(start 343.934542 -130.294888)
		(end 345.9353 -132.295646)
		(width 0.508)
		(layer "In2.Cu")
		(net "VR_FET_SW_P12V_STBY_PVPP_DEF")
	)
	(segment
		(start 348.598744 -132.295646)
		(end 348.82963 -132.06476)
		(width 0.508)
		(layer "In2.Cu")
		(net "VR_FET_SW_P12V_STBY_PVPP_DEF")
	)
	(segment
		(start 345.9353 -132.295646)
		(end 348.598744 -132.295646)
		(width 0.508)
		(layer "In2.Cu")
		(net "VR_FET_SW_P12V_STBY_PVPP_DEF")
	)
	(segment
		(start 340.2584 -131.0132)
		(end 340.806532 -131.0132)
		(width 0.508)
		(layer "In2.Cu")
		(net "VR_FET_SW_P12V_STBY_PVPP_DEF")
	)
	(segment
		(start 341.524844 -130.294888)
		(end 343.934542 -130.294888)
		(width 0.508)
		(layer "In2.Cu")
		(net "VR_FET_SW_P12V_STBY_PVPP_DEF")
	)
	(segment
		(start 340.806532 -131.0132)
		(end 341.524844 -130.294888)
		(width 0.508)
		(layer "In2.Cu")
		(net "VR_FET_SW_P12V_STBY_PVPP_DEF")
	)
	(segment
		(start 341.89924 -26.81224)
		(end 341.63 -26.543)
		(width 0.254)
		(layer "F.Cu")
		(net "VR_FET_SW_P12V_STBY_PVPP_ABC")
	)
	(segment
		(start 342.5317 -26.81224)
		(end 341.89924 -26.81224)
		(width 0.254)
		(layer "F.Cu")
		(net "VR_FET_SW_P12V_STBY_PVPP_ABC")
	)
	(via
		(at 349.201232 -25.238964)
		(size 0.508)
		(drill 0.254)
		(layers "F.Cu" "B.Cu")
		(net "VR_FET_SW_P12V_STBY_PVPP_ABC")
	)
	(via
		(at 349.836232 -27.143964)
		(size 0.508)
		(drill 0.254)
		(layers "F.Cu" "B.Cu")
		(net "VR_FET_SW_P12V_STBY_PVPP_ABC")
	)
	(via
		(at 354.151692 -27.571192)
		(size 0.508)
		(drill 0.254)
		(layers "F.Cu" "B.Cu")
		(net "VR_FET_SW_P12V_STBY_PVPP_ABC")
	)
	(via
		(at 354.15474 -28.322524)
		(size 0.508)
		(drill 0.254)
		(layers "F.Cu" "B.Cu")
		(net "VR_FET_SW_P12V_STBY_PVPP_ABC")
	)
	(via
		(at 349.201232 -26.508964)
		(size 0.508)
		(drill 0.254)
		(layers "F.Cu" "B.Cu")
		(net "VR_FET_SW_P12V_STBY_PVPP_ABC")
	)
	(via
		(at 349.201232 -25.873964)
		(size 0.508)
		(drill 0.254)
		(layers "F.Cu" "B.Cu")
		(net "VR_FET_SW_P12V_STBY_PVPP_ABC")
	)
	(via
		(at 349.836232 -25.873964)
		(size 0.508)
		(drill 0.254)
		(layers "F.Cu" "B.Cu")
		(net "VR_FET_SW_P12V_STBY_PVPP_ABC")
	)
	(via
		(at 347.853 -27.305)
		(size 0.6604)
		(drill 0.3302)
		(layers "F.Cu" "B.Cu")
		(net "VR_FET_SW_P12V_STBY_PVPP_ABC")
	)
	(via
		(at 341.63 -26.543)
		(size 0.508)
		(drill 0.254)
		(layers "F.Cu" "B.Cu")
		(net "VR_FET_SW_P12V_STBY_PVPP_ABC")
	)
	(via
		(at 349.201232 -27.143964)
		(size 0.508)
		(drill 0.254)
		(layers "F.Cu" "B.Cu")
		(net "VR_FET_SW_P12V_STBY_PVPP_ABC")
	)
	(via
		(at 351.6884 -27.559)
		(size 0.508)
		(drill 0.254)
		(layers "F.Cu" "B.Cu")
		(net "VR_FET_SW_P12V_STBY_PVPP_ABC")
	)
	(via
		(at 348.361 -25.654)
		(size 0.508)
		(drill 0.254)
		(layers "F.Cu" "B.Cu")
		(net "VR_FET_SW_P12V_STBY_PVPP_ABC")
	)
	(via
		(at 353.405186 -27.557984)
		(size 0.508)
		(drill 0.254)
		(layers "F.Cu" "B.Cu")
		(net "VR_FET_SW_P12V_STBY_PVPP_ABC")
	)
	(via
		(at 349.836232 -26.508964)
		(size 0.508)
		(drill 0.254)
		(layers "F.Cu" "B.Cu")
		(net "VR_FET_SW_P12V_STBY_PVPP_ABC")
	)
	(via
		(at 350.865186 -27.557984)
		(size 0.508)
		(drill 0.254)
		(layers "F.Cu" "B.Cu")
		(net "VR_FET_SW_P12V_STBY_PVPP_ABC")
	)
	(via
		(at 352.5774 -27.559)
		(size 0.508)
		(drill 0.254)
		(layers "F.Cu" "B.Cu")
		(net "VR_FET_SW_P12V_STBY_PVPP_ABC")
	)
	(segment
		(start 345.27744 -25.654)
		(end 343.563956 -25.654)
		(width 0.508)
		(layer "In2.Cu")
		(net "VR_FET_SW_P12V_STBY_PVPP_ABC")
	)
	(segment
		(start 343.563956 -25.654)
		(end 342.674956 -26.543)
		(width 0.508)
		(layer "In2.Cu")
		(net "VR_FET_SW_P12V_STBY_PVPP_ABC")
	)
	(segment
		(start 342.674956 -26.543)
		(end 341.63 -26.543)
		(width 0.508)
		(layer "In2.Cu")
		(net "VR_FET_SW_P12V_STBY_PVPP_ABC")
	)
	(segment
		(start 347.3704 -26.27376)
		(end 345.8972 -26.27376)
		(width 0.508)
		(layer "In2.Cu")
		(net "VR_FET_SW_P12V_STBY_PVPP_ABC")
	)
	(segment
		(start 345.8972 -26.27376)
		(end 345.27744 -25.654)
		(width 0.508)
		(layer "In2.Cu")
		(net "VR_FET_SW_P12V_STBY_PVPP_ABC")
	)
	(segment
		(start 347.99016 -25.654)
		(end 347.3704 -26.27376)
		(width 0.508)
		(layer "In2.Cu")
		(net "VR_FET_SW_P12V_STBY_PVPP_ABC")
	)
	(segment
		(start 348.361 -25.654)
		(end 347.99016 -25.654)
		(width 0.508)
		(layer "In2.Cu")
		(net "VR_FET_SW_P12V_STBY_PVPP_ABC")
	)
	(segment
		(start 471.696034 -26.1112)
		(end 471.507566 -26.299668)
		(width 0.508)
		(layer "F.Cu")
		(net "VR_FET_SW_P12V_STBY_P3V3_STBY")
	)
	(segment
		(start 472.86418 -26.1112)
		(end 471.696034 -26.1112)
		(width 0.508)
		(layer "F.Cu")
		(net "VR_FET_SW_P12V_STBY_P3V3_STBY")
	)
	(via
		(at 474.307154 -26.197814)
		(size 0.762)
		(drill 0.381)
		(layers "F.Cu" "B.Cu")
		(net "VR_FET_SW_P12V_STBY_P3V3_STBY")
	)
	(segment
		(start 413.893 -124.841)
		(end 414.046416 -124.841)
		(width 0.10795)
		(layer "F.Cu")
		(net "TP_HFI_IO_CONN0_RSVD_17")
	)
	(segment
		(start 414.046416 -124.841)
		(end 414.147 -124.740416)
		(width 0.10795)
		(layer "F.Cu")
		(net "TP_HFI_IO_CONN0_RSVD_17")
	)
	(segment
		(start 414.147 -124.740416)
		(end 415.191194 -124.740416)
		(width 0.10795)
		(layer "F.Cu")
		(net "TP_HFI_IO_CONN0_RSVD_17")
	)
	(via
		(at 413.893 -124.841)
		(size 0.508)
		(drill 0.254)
		(layers "F.Cu" "B.Cu")
		(net "TP_HFI_IO_CONN0_RSVD_17")
	)
	(segment
		(start 479.8822 -46.217332)
		(end 479.435922 -46.217332)
		(width 0.10795)
		(layer "F.Cu")
		(net "SMB_SPRINGVILLE_STBY_LVC3_SDA")
	)
	(segment
		(start 478.993454 -46.6598)
		(end 478.6376 -46.6598)
		(width 0.10795)
		(layer "F.Cu")
		(net "SMB_SPRINGVILLE_STBY_LVC3_SDA")
	)
	(segment
		(start 479.435922 -46.217332)
		(end 478.993454 -46.6598)
		(width 0.10795)
		(layer "F.Cu")
		(net "SMB_SPRINGVILLE_STBY_LVC3_SDA")
	)
	(via
		(at 494.8428 -120.4722)
		(size 0.508)
		(drill 0.254)
		(layers "F.Cu" "B.Cu")
		(net "SMB_SPRINGVILLE_STBY_LVC3_SDA")
	)
	(via
		(at 478.6376 -46.6598)
		(size 0.508)
		(drill 0.254)
		(layers "F.Cu" "B.Cu")
		(net "SMB_SPRINGVILLE_STBY_LVC3_SDA")
	)
	(via
		(at 485.0892 -129.7178)
		(size 0.508)
		(drill 0.254)
		(layers "F.Cu" "B.Cu")
		(net "SMB_SPRINGVILLE_STBY_LVC3_SDA")
	)
	(segment
		(start 493.2426 -120.8278)
		(end 494.4872 -120.8278)
		(width 0.10795)
		(layer "B.Cu")
		(net "SMB_SPRINGVILLE_STBY_LVC3_SDA")
	)
	(segment
		(start 485.0892 -129.0955)
		(end 485.0892 -129.7178)
		(width 0.10795)
		(layer "B.Cu")
		(net "SMB_SPRINGVILLE_STBY_LVC3_SDA")
	)
	(segment
		(start 494.4872 -120.8278)
		(end 494.8428 -120.4722)
		(width 0.10795)
		(layer "B.Cu")
		(net "SMB_SPRINGVILLE_STBY_LVC3_SDA")
	)
	(segment
		(start 491.59795 -121.18975)
		(end 491.76305 -121.18975)
		(width 0.10795)
		(layer "B.Cu")
		(net "SMB_SPRINGVILLE_STBY_LVC3_SDA")
	)
	(segment
		(start 491.2741 -121.5136)
		(end 491.59795 -121.18975)
		(width 0.10795)
		(layer "B.Cu")
		(net "SMB_SPRINGVILLE_STBY_LVC3_SDA")
	)
	(segment
		(start 493.0394 -120.6246)
		(end 493.2426 -120.8278)
		(width 0.10795)
		(layer "B.Cu")
		(net "SMB_SPRINGVILLE_STBY_LVC3_SDA")
	)
	(segment
		(start 491.76305 -121.18975)
		(end 492.3282 -120.6246)
		(width 0.10795)
		(layer "B.Cu")
		(net "SMB_SPRINGVILLE_STBY_LVC3_SDA")
	)
	(segment
		(start 492.3282 -120.6246)
		(end 493.0394 -120.6246)
		(width 0.10795)
		(layer "B.Cu")
		(net "SMB_SPRINGVILLE_STBY_LVC3_SDA")
	)
	(segment
		(start 426.319696 -80.682592)
		(end 426.319442 -80.682846)
		(width 0.089408)
		(layer "In2.Cu")
		(net "SMB_SPRINGVILLE_STBY_LVC3_SDA")
	)
	(segment
		(start 494.538 -118.87454)
		(end 494.538 -120.1674)
		(width 0.089408)
		(layer "In2.Cu")
		(net "SMB_SPRINGVILLE_STBY_LVC3_SDA")
	)
	(segment
		(start 484.623618 -112.155224)
		(end 490.627162 -112.155224)
		(width 0.089408)
		(layer "In2.Cu")
		(net "SMB_SPRINGVILLE_STBY_LVC3_SDA")
	)
	(segment
		(start 426.319442 -79.161894)
		(end 426.31995 -79.162402)
		(width 0.089408)
		(layer "In2.Cu")
		(net "SMB_SPRINGVILLE_STBY_LVC3_SDA")
	)
	(segment
		(start 426.319442 -78.5495)
		(end 426.319442 -79.161894)
		(width 0.089408)
		(layer "In2.Cu")
		(net "SMB_SPRINGVILLE_STBY_LVC3_SDA")
	)
	(segment
		(start 427.349666 -66.299842)
		(end 427.033182 -66.299842)
		(width 0.089408)
		(layer "In2.Cu")
		(net "SMB_SPRINGVILLE_STBY_LVC3_SDA")
	)
	(segment
		(start 465.148676 -66.30035)
		(end 463.786728 -66.30035)
		(width 0.089408)
		(layer "In2.Cu")
		(net "SMB_SPRINGVILLE_STBY_LVC3_SDA")
	)
	(segment
		(start 492.63554 -114.163602)
		(end 492.63554 -116.97208)
		(width 0.089408)
		(layer "In2.Cu")
		(net "SMB_SPRINGVILLE_STBY_LVC3_SDA")
	)
	(segment
		(start 425.69892 -77.291184)
		(end 425.69892 -77.928978)
		(width 0.089408)
		(layer "In2.Cu")
		(net "SMB_SPRINGVILLE_STBY_LVC3_SDA")
	)
	(segment
		(start 426.986446 -111.034576)
		(end 483.50297 -111.034576)
		(width 0.089408)
		(layer "In2.Cu")
		(net "SMB_SPRINGVILLE_STBY_LVC3_SDA")
	)
	(segment
		(start 490.045248 -51.62931)
		(end 491.171484 -52.755546)
		(width 0.089408)
		(layer "In2.Cu")
		(net "SMB_SPRINGVILLE_STBY_LVC3_SDA")
	)
	(segment
		(start 465.14893 -66.300096)
		(end 465.148676 -66.30035)
		(width 0.089408)
		(layer "In2.Cu")
		(net "SMB_SPRINGVILLE_STBY_LVC3_SDA")
	)
	(segment
		(start 483.50297 -111.034576)
		(end 484.623618 -112.155224)
		(width 0.089408)
		(layer "In2.Cu")
		(net "SMB_SPRINGVILLE_STBY_LVC3_SDA")
	)
	(segment
		(start 486.70591 -51.62931)
		(end 490.045248 -51.62931)
		(width 0.089408)
		(layer "In2.Cu")
		(net "SMB_SPRINGVILLE_STBY_LVC3_SDA")
	)
	(segment
		(start 482.17582 -47.078392)
		(end 486.389172 -51.291744)
		(width 0.089408)
		(layer "In2.Cu")
		(net "SMB_SPRINGVILLE_STBY_LVC3_SDA")
	)
	(segment
		(start 486.389172 -51.312572)
		(end 486.70591 -51.62931)
		(width 0.089408)
		(layer "In2.Cu")
		(net "SMB_SPRINGVILLE_STBY_LVC3_SDA")
	)
	(segment
		(start 478.6376 -46.6598)
		(end 479.056192 -47.078392)
		(width 0.089408)
		(layer "In2.Cu")
		(net "SMB_SPRINGVILLE_STBY_LVC3_SDA")
	)
	(segment
		(start 484.353616 -60.883546)
		(end 479.38563 -60.883546)
		(width 0.089408)
		(layer "In2.Cu")
		(net "SMB_SPRINGVILLE_STBY_LVC3_SDA")
	)
	(segment
		(start 463.786474 -66.300096)
		(end 427.34992 -66.300096)
		(width 0.089408)
		(layer "In2.Cu")
		(net "SMB_SPRINGVILLE_STBY_LVC3_SDA")
	)
	(segment
		(start 425.007786 -68.325238)
		(end 425.007786 -75.324462)
		(width 0.089408)
		(layer "In2.Cu")
		(net "SMB_SPRINGVILLE_STBY_LVC3_SDA")
	)
	(segment
		(start 492.63554 -116.97208)
		(end 494.538 -118.87454)
		(width 0.089408)
		(layer "In2.Cu")
		(net "SMB_SPRINGVILLE_STBY_LVC3_SDA")
	)
	(segment
		(start 463.786728 -66.30035)
		(end 463.786474 -66.300096)
		(width 0.089408)
		(layer "In2.Cu")
		(net "SMB_SPRINGVILLE_STBY_LVC3_SDA")
	)
	(segment
		(start 473.96908 -66.300096)
		(end 465.14893 -66.300096)
		(width 0.089408)
		(layer "In2.Cu")
		(net "SMB_SPRINGVILLE_STBY_LVC3_SDA")
	)
	(segment
		(start 426.31995 -80.52435)
		(end 426.319696 -80.524604)
		(width 0.089408)
		(layer "In2.Cu")
		(net "SMB_SPRINGVILLE_STBY_LVC3_SDA")
	)
	(segment
		(start 490.627162 -112.155224)
		(end 492.63554 -114.163602)
		(width 0.089408)
		(layer "In2.Cu")
		(net "SMB_SPRINGVILLE_STBY_LVC3_SDA")
	)
	(segment
		(start 486.389172 -51.291744)
		(end 486.389172 -51.312572)
		(width 0.089408)
		(layer "In2.Cu")
		(net "SMB_SPRINGVILLE_STBY_LVC3_SDA")
	)
	(segment
		(start 427.033182 -66.299842)
		(end 425.007786 -68.325238)
		(width 0.089408)
		(layer "In2.Cu")
		(net "SMB_SPRINGVILLE_STBY_LVC3_SDA")
	)
	(segment
		(start 426.319442 -110.367572)
		(end 426.986446 -111.034576)
		(width 0.089408)
		(layer "In2.Cu")
		(net "SMB_SPRINGVILLE_STBY_LVC3_SDA")
	)
	(segment
		(start 479.056192 -47.078392)
		(end 482.17582 -47.078392)
		(width 0.089408)
		(layer "In2.Cu")
		(net "SMB_SPRINGVILLE_STBY_LVC3_SDA")
	)
	(segment
		(start 494.538 -120.1674)
		(end 494.8428 -120.4722)
		(width 0.089408)
		(layer "In2.Cu")
		(net "SMB_SPRINGVILLE_STBY_LVC3_SDA")
	)
	(segment
		(start 427.34992 -66.300096)
		(end 427.349666 -66.299842)
		(width 0.089408)
		(layer "In2.Cu")
		(net "SMB_SPRINGVILLE_STBY_LVC3_SDA")
	)
	(segment
		(start 426.31995 -79.162402)
		(end 426.31995 -80.52435)
		(width 0.089408)
		(layer "In2.Cu")
		(net "SMB_SPRINGVILLE_STBY_LVC3_SDA")
	)
	(segment
		(start 425.007786 -75.324462)
		(end 425.699174 -76.01585)
		(width 0.089408)
		(layer "In2.Cu")
		(net "SMB_SPRINGVILLE_STBY_LVC3_SDA")
	)
	(segment
		(start 426.319442 -80.682846)
		(end 426.319442 -110.367572)
		(width 0.089408)
		(layer "In2.Cu")
		(net "SMB_SPRINGVILLE_STBY_LVC3_SDA")
	)
	(segment
		(start 426.319696 -80.524604)
		(end 426.319696 -80.682592)
		(width 0.089408)
		(layer "In2.Cu")
		(net "SMB_SPRINGVILLE_STBY_LVC3_SDA")
	)
	(segment
		(start 491.171484 -52.755546)
		(end 491.171484 -54.065678)
		(width 0.089408)
		(layer "In2.Cu")
		(net "SMB_SPRINGVILLE_STBY_LVC3_SDA")
	)
	(segment
		(start 425.699174 -77.29093)
		(end 425.69892 -77.291184)
		(width 0.089408)
		(layer "In2.Cu")
		(net "SMB_SPRINGVILLE_STBY_LVC3_SDA")
	)
	(segment
		(start 425.699174 -76.01585)
		(end 425.699174 -77.29093)
		(width 0.089408)
		(layer "In2.Cu")
		(net "SMB_SPRINGVILLE_STBY_LVC3_SDA")
	)
	(segment
		(start 425.69892 -77.928978)
		(end 426.319442 -78.5495)
		(width 0.089408)
		(layer "In2.Cu")
		(net "SMB_SPRINGVILLE_STBY_LVC3_SDA")
	)
	(segment
		(start 491.171484 -54.065678)
		(end 484.353616 -60.883546)
		(width 0.089408)
		(layer "In2.Cu")
		(net "SMB_SPRINGVILLE_STBY_LVC3_SDA")
	)
	(segment
		(start 479.38563 -60.883546)
		(end 473.96908 -66.300096)
		(width 0.089408)
		(layer "In2.Cu")
		(net "SMB_SPRINGVILLE_STBY_LVC3_SDA")
	)
	(segment
		(start 494.7158 -120.4722)
		(end 494.537746 -120.650254)
		(width 0.089408)
		(layer "In4.Cu")
		(net "SMB_SPRINGVILLE_STBY_LVC3_SDA")
	)
	(segment
		(start 486.717848 -130.416808)
		(end 485.695752 -130.416808)
		(width 0.089408)
		(layer "In4.Cu")
		(net "SMB_SPRINGVILLE_STBY_LVC3_SDA")
	)
	(segment
		(start 494.537746 -120.903746)
		(end 495.286792 -121.652792)
		(width 0.089408)
		(layer "In4.Cu")
		(net "SMB_SPRINGVILLE_STBY_LVC3_SDA")
	)
	(segment
		(start 487.744008 -129.390648)
		(end 486.717848 -130.416808)
		(width 0.089408)
		(layer "In4.Cu")
		(net "SMB_SPRINGVILLE_STBY_LVC3_SDA")
	)
	(segment
		(start 485.2416 -129.7178)
		(end 485.0892 -129.7178)
		(width 0.089408)
		(layer "In4.Cu")
		(net "SMB_SPRINGVILLE_STBY_LVC3_SDA")
	)
	(segment
		(start 494.537746 -120.650254)
		(end 494.537746 -120.903746)
		(width 0.089408)
		(layer "In4.Cu")
		(net "SMB_SPRINGVILLE_STBY_LVC3_SDA")
	)
	(segment
		(start 487.744008 -127.850392)
		(end 487.744008 -129.390648)
		(width 0.089408)
		(layer "In4.Cu")
		(net "SMB_SPRINGVILLE_STBY_LVC3_SDA")
	)
	(segment
		(start 485.695752 -130.416808)
		(end 485.398572 -130.119628)
		(width 0.089408)
		(layer "In4.Cu")
		(net "SMB_SPRINGVILLE_STBY_LVC3_SDA")
	)
	(segment
		(start 485.398572 -130.119628)
		(end 485.398572 -129.874772)
		(width 0.089408)
		(layer "In4.Cu")
		(net "SMB_SPRINGVILLE_STBY_LVC3_SDA")
	)
	(segment
		(start 488.428792 -127.165608)
		(end 487.744008 -127.850392)
		(width 0.089408)
		(layer "In4.Cu")
		(net "SMB_SPRINGVILLE_STBY_LVC3_SDA")
	)
	(segment
		(start 495.286792 -121.652792)
		(end 495.286792 -123.734068)
		(width 0.089408)
		(layer "In4.Cu")
		(net "SMB_SPRINGVILLE_STBY_LVC3_SDA")
	)
	(segment
		(start 485.398572 -129.874772)
		(end 485.2416 -129.7178)
		(width 0.089408)
		(layer "In4.Cu")
		(net "SMB_SPRINGVILLE_STBY_LVC3_SDA")
	)
	(segment
		(start 491.855252 -127.165608)
		(end 488.428792 -127.165608)
		(width 0.089408)
		(layer "In4.Cu")
		(net "SMB_SPRINGVILLE_STBY_LVC3_SDA")
	)
	(segment
		(start 494.8428 -120.4722)
		(end 494.7158 -120.4722)
		(width 0.089408)
		(layer "In4.Cu")
		(net "SMB_SPRINGVILLE_STBY_LVC3_SDA")
	)
	(segment
		(start 495.286792 -123.734068)
		(end 491.855252 -127.165608)
		(width 0.089408)
		(layer "In4.Cu")
		(net "SMB_SPRINGVILLE_STBY_LVC3_SDA")
	)
	(segment
		(start 479.35007 -47.21733)
		(end 478.79 -47.7774)
		(width 0.10795)
		(layer "F.Cu")
		(net "SMB_SPRINGVILLE_STBY_LVC3_SCL")
	)
	(segment
		(start 478.79 -47.7774)
		(end 478.536 -47.7774)
		(width 0.10795)
		(layer "F.Cu")
		(net "SMB_SPRINGVILLE_STBY_LVC3_SCL")
	)
	(segment
		(start 479.8822 -47.21733)
		(end 479.35007 -47.21733)
		(width 0.10795)
		(layer "F.Cu")
		(net "SMB_SPRINGVILLE_STBY_LVC3_SCL")
	)
	(via
		(at 485.8512 -129.7178)
		(size 0.508)
		(drill 0.254)
		(layers "F.Cu" "B.Cu")
		(net "SMB_SPRINGVILLE_STBY_LVC3_SCL")
	)
	(via
		(at 494.03 -120.396)
		(size 0.508)
		(drill 0.254)
		(layers "F.Cu" "B.Cu")
		(net "SMB_SPRINGVILLE_STBY_LVC3_SCL")
	)
	(via
		(at 478.536 -47.7774)
		(size 0.508)
		(drill 0.254)
		(layers "F.Cu" "B.Cu")
		(net "SMB_SPRINGVILLE_STBY_LVC3_SCL")
	)
	(segment
		(start 491.665514 -120.9548)
		(end 492.230664 -120.38965)
		(width 0.10795)
		(layer "B.Cu")
		(net "SMB_SPRINGVILLE_STBY_LVC3_SCL")
	)
	(segment
		(start 491.2741 -120.7516)
		(end 491.4773 -120.9548)
		(width 0.10795)
		(layer "B.Cu")
		(net "SMB_SPRINGVILLE_STBY_LVC3_SCL")
	)
	(segment
		(start 493.340136 -120.59285)
		(end 493.83315 -120.59285)
		(width 0.10795)
		(layer "B.Cu")
		(net "SMB_SPRINGVILLE_STBY_LVC3_SCL")
	)
	(segment
		(start 493.136936 -120.38965)
		(end 493.340136 -120.59285)
		(width 0.10795)
		(layer "B.Cu")
		(net "SMB_SPRINGVILLE_STBY_LVC3_SCL")
	)
	(segment
		(start 492.230664 -120.38965)
		(end 493.136936 -120.38965)
		(width 0.10795)
		(layer "B.Cu")
		(net "SMB_SPRINGVILLE_STBY_LVC3_SCL")
	)
	(segment
		(start 491.4773 -120.9548)
		(end 491.665514 -120.9548)
		(width 0.10795)
		(layer "B.Cu")
		(net "SMB_SPRINGVILLE_STBY_LVC3_SCL")
	)
	(segment
		(start 493.83315 -120.59285)
		(end 494.03 -120.396)
		(width 0.10795)
		(layer "B.Cu")
		(net "SMB_SPRINGVILLE_STBY_LVC3_SCL")
	)
	(segment
		(start 485.8512 -129.0955)
		(end 485.8512 -129.7178)
		(width 0.10795)
		(layer "B.Cu")
		(net "SMB_SPRINGVILLE_STBY_LVC3_SCL")
	)
	(segment
		(start 486.667302 -51.972718)
		(end 490.05998 -51.972718)
		(width 0.089408)
		(layer "In2.Cu")
		(net "SMB_SPRINGVILLE_STBY_LVC3_SCL")
	)
	(segment
		(start 482.147372 -47.3202)
		(end 486.198164 -51.370992)
		(width 0.089408)
		(layer "In2.Cu")
		(net "SMB_SPRINGVILLE_STBY_LVC3_SCL")
	)
	(segment
		(start 426.128942 -80.445102)
		(end 426.128688 -80.445356)
		(width 0.089408)
		(layer "In2.Cu")
		(net "SMB_SPRINGVILLE_STBY_LVC3_SCL")
	)
	(segment
		(start 427.429168 -66.109088)
		(end 427.428914 -66.108834)
		(width 0.089408)
		(layer "In2.Cu")
		(net "SMB_SPRINGVILLE_STBY_LVC3_SCL")
	)
	(segment
		(start 490.05998 -51.972718)
		(end 490.929676 -52.842414)
		(width 0.089408)
		(layer "In2.Cu")
		(net "SMB_SPRINGVILLE_STBY_LVC3_SCL")
	)
	(segment
		(start 424.816778 -75.40371)
		(end 425.508166 -76.095098)
		(width 0.089408)
		(layer "In2.Cu")
		(net "SMB_SPRINGVILLE_STBY_LVC3_SCL")
	)
	(segment
		(start 424.816778 -68.24599)
		(end 424.816778 -75.40371)
		(width 0.089408)
		(layer "In2.Cu")
		(net "SMB_SPRINGVILLE_STBY_LVC3_SCL")
	)
	(segment
		(start 494.284 -120.142)
		(end 494.03 -120.396)
		(width 0.089408)
		(layer "In2.Cu")
		(net "SMB_SPRINGVILLE_STBY_LVC3_SCL")
	)
	(segment
		(start 426.128688 -80.445356)
		(end 426.128688 -80.603344)
		(width 0.089408)
		(layer "In2.Cu")
		(net "SMB_SPRINGVILLE_STBY_LVC3_SCL")
	)
	(segment
		(start 427.428914 -66.108834)
		(end 426.953934 -66.108834)
		(width 0.089408)
		(layer "In2.Cu")
		(net "SMB_SPRINGVILLE_STBY_LVC3_SCL")
	)
	(segment
		(start 492.38154 -117.07749)
		(end 494.284 -118.97995)
		(width 0.089408)
		(layer "In2.Cu")
		(net "SMB_SPRINGVILLE_STBY_LVC3_SCL")
	)
	(segment
		(start 426.128434 -79.241142)
		(end 426.128942 -79.24165)
		(width 0.089408)
		(layer "In2.Cu")
		(net "SMB_SPRINGVILLE_STBY_LVC3_SCL")
	)
	(segment
		(start 426.953934 -66.108834)
		(end 424.816778 -68.24599)
		(width 0.089408)
		(layer "In2.Cu")
		(net "SMB_SPRINGVILLE_STBY_LVC3_SCL")
	)
	(segment
		(start 478.9932 -47.3202)
		(end 482.147372 -47.3202)
		(width 0.089408)
		(layer "In2.Cu")
		(net "SMB_SPRINGVILLE_STBY_LVC3_SCL")
	)
	(segment
		(start 478.536 -47.7774)
		(end 478.9932 -47.3202)
		(width 0.089408)
		(layer "In2.Cu")
		(net "SMB_SPRINGVILLE_STBY_LVC3_SCL")
	)
	(segment
		(start 425.507912 -78.008226)
		(end 426.128434 -78.628748)
		(width 0.089408)
		(layer "In2.Cu")
		(net "SMB_SPRINGVILLE_STBY_LVC3_SCL")
	)
	(segment
		(start 484.28148 -60.685426)
		(end 479.292412 -60.685426)
		(width 0.089408)
		(layer "In2.Cu")
		(net "SMB_SPRINGVILLE_STBY_LVC3_SCL")
	)
	(segment
		(start 465.069428 -66.109342)
		(end 463.865976 -66.109342)
		(width 0.089408)
		(layer "In2.Cu")
		(net "SMB_SPRINGVILLE_STBY_LVC3_SCL")
	)
	(segment
		(start 425.507912 -77.211936)
		(end 425.507912 -78.008226)
		(width 0.089408)
		(layer "In2.Cu")
		(net "SMB_SPRINGVILLE_STBY_LVC3_SCL")
	)
	(segment
		(start 473.86875 -66.109088)
		(end 465.069682 -66.109088)
		(width 0.089408)
		(layer "In2.Cu")
		(net "SMB_SPRINGVILLE_STBY_LVC3_SCL")
	)
	(segment
		(start 463.865976 -66.109342)
		(end 463.865722 -66.109088)
		(width 0.089408)
		(layer "In2.Cu")
		(net "SMB_SPRINGVILLE_STBY_LVC3_SCL")
	)
	(segment
		(start 425.508166 -76.095098)
		(end 425.508166 -77.211682)
		(width 0.089408)
		(layer "In2.Cu")
		(net "SMB_SPRINGVILLE_STBY_LVC3_SCL")
	)
	(segment
		(start 490.929676 -52.842414)
		(end 490.929676 -54.03723)
		(width 0.089408)
		(layer "In2.Cu")
		(net "SMB_SPRINGVILLE_STBY_LVC3_SCL")
	)
	(segment
		(start 426.128434 -110.44682)
		(end 426.907198 -111.225584)
		(width 0.089408)
		(layer "In2.Cu")
		(net "SMB_SPRINGVILLE_STBY_LVC3_SCL")
	)
	(segment
		(start 426.128434 -78.628748)
		(end 426.128434 -79.241142)
		(width 0.089408)
		(layer "In2.Cu")
		(net "SMB_SPRINGVILLE_STBY_LVC3_SCL")
	)
	(segment
		(start 426.128688 -80.603344)
		(end 426.128434 -80.603598)
		(width 0.089408)
		(layer "In2.Cu")
		(net "SMB_SPRINGVILLE_STBY_LVC3_SCL")
	)
	(segment
		(start 494.284 -118.97995)
		(end 494.284 -120.142)
		(width 0.089408)
		(layer "In2.Cu")
		(net "SMB_SPRINGVILLE_STBY_LVC3_SCL")
	)
	(segment
		(start 492.38154 -114.25174)
		(end 492.38154 -117.07749)
		(width 0.089408)
		(layer "In2.Cu")
		(net "SMB_SPRINGVILLE_STBY_LVC3_SCL")
	)
	(segment
		(start 486.198164 -51.370992)
		(end 486.198164 -51.50358)
		(width 0.089408)
		(layer "In2.Cu")
		(net "SMB_SPRINGVILLE_STBY_LVC3_SCL")
	)
	(segment
		(start 479.292412 -60.685426)
		(end 473.86875 -66.109088)
		(width 0.089408)
		(layer "In2.Cu")
		(net "SMB_SPRINGVILLE_STBY_LVC3_SCL")
	)
	(segment
		(start 484.523288 -112.397032)
		(end 490.526832 -112.397032)
		(width 0.089408)
		(layer "In2.Cu")
		(net "SMB_SPRINGVILLE_STBY_LVC3_SCL")
	)
	(segment
		(start 465.069682 -66.109088)
		(end 465.069428 -66.109342)
		(width 0.089408)
		(layer "In2.Cu")
		(net "SMB_SPRINGVILLE_STBY_LVC3_SCL")
	)
	(segment
		(start 483.35184 -111.225584)
		(end 484.523288 -112.397032)
		(width 0.089408)
		(layer "In2.Cu")
		(net "SMB_SPRINGVILLE_STBY_LVC3_SCL")
	)
	(segment
		(start 490.929676 -54.03723)
		(end 484.28148 -60.685426)
		(width 0.089408)
		(layer "In2.Cu")
		(net "SMB_SPRINGVILLE_STBY_LVC3_SCL")
	)
	(segment
		(start 426.128942 -79.24165)
		(end 426.128942 -80.445102)
		(width 0.089408)
		(layer "In2.Cu")
		(net "SMB_SPRINGVILLE_STBY_LVC3_SCL")
	)
	(segment
		(start 425.508166 -77.211682)
		(end 425.507912 -77.211936)
		(width 0.089408)
		(layer "In2.Cu")
		(net "SMB_SPRINGVILLE_STBY_LVC3_SCL")
	)
	(segment
		(start 490.526832 -112.397032)
		(end 492.38154 -114.25174)
		(width 0.089408)
		(layer "In2.Cu")
		(net "SMB_SPRINGVILLE_STBY_LVC3_SCL")
	)
	(segment
		(start 426.907198 -111.225584)
		(end 483.35184 -111.225584)
		(width 0.089408)
		(layer "In2.Cu")
		(net "SMB_SPRINGVILLE_STBY_LVC3_SCL")
	)
	(segment
		(start 463.865722 -66.109088)
		(end 427.429168 -66.109088)
		(width 0.089408)
		(layer "In2.Cu")
		(net "SMB_SPRINGVILLE_STBY_LVC3_SCL")
	)
	(segment
		(start 426.128434 -80.603598)
		(end 426.128434 -110.44682)
		(width 0.089408)
		(layer "In2.Cu")
		(net "SMB_SPRINGVILLE_STBY_LVC3_SCL")
	)
	(segment
		(start 486.198164 -51.50358)
		(end 486.667302 -51.972718)
		(width 0.089408)
		(layer "In2.Cu")
		(net "SMB_SPRINGVILLE_STBY_LVC3_SCL")
	)
	(segment
		(start 491.776004 -126.9746)
		(end 488.349544 -126.9746)
		(width 0.089408)
		(layer "In4.Cu")
		(net "SMB_SPRINGVILLE_STBY_LVC3_SCL")
	)
	(segment
		(start 487.553 -129.3114)
		(end 486.6386 -130.2258)
		(width 0.089408)
		(layer "In4.Cu")
		(net "SMB_SPRINGVILLE_STBY_LVC3_SCL")
	)
	(segment
		(start 487.553 -127.771144)
		(end 487.553 -129.3114)
		(width 0.089408)
		(layer "In4.Cu")
		(net "SMB_SPRINGVILLE_STBY_LVC3_SCL")
	)
	(segment
		(start 494.346738 -120.611138)
		(end 494.346738 -120.982994)
		(width 0.089408)
		(layer "In4.Cu")
		(net "SMB_SPRINGVILLE_STBY_LVC3_SCL")
	)
	(segment
		(start 485.775 -130.2258)
		(end 485.5972 -130.048)
		(width 0.089408)
		(layer "In4.Cu")
		(net "SMB_SPRINGVILLE_STBY_LVC3_SCL")
	)
	(segment
		(start 485.7242 -129.7178)
		(end 485.8512 -129.7178)
		(width 0.089408)
		(layer "In4.Cu")
		(net "SMB_SPRINGVILLE_STBY_LVC3_SCL")
	)
	(segment
		(start 494.346738 -120.982994)
		(end 495.095784 -121.73204)
		(width 0.089408)
		(layer "In4.Cu")
		(net "SMB_SPRINGVILLE_STBY_LVC3_SCL")
	)
	(segment
		(start 485.5972 -129.8448)
		(end 485.7242 -129.7178)
		(width 0.089408)
		(layer "In4.Cu")
		(net "SMB_SPRINGVILLE_STBY_LVC3_SCL")
	)
	(segment
		(start 494.03 -120.396)
		(end 494.1316 -120.396)
		(width 0.089408)
		(layer "In4.Cu")
		(net "SMB_SPRINGVILLE_STBY_LVC3_SCL")
	)
	(segment
		(start 486.6386 -130.2258)
		(end 485.775 -130.2258)
		(width 0.089408)
		(layer "In4.Cu")
		(net "SMB_SPRINGVILLE_STBY_LVC3_SCL")
	)
	(segment
		(start 495.095784 -121.73204)
		(end 495.095784 -123.65482)
		(width 0.089408)
		(layer "In4.Cu")
		(net "SMB_SPRINGVILLE_STBY_LVC3_SCL")
	)
	(segment
		(start 494.1316 -120.396)
		(end 494.346738 -120.611138)
		(width 0.089408)
		(layer "In4.Cu")
		(net "SMB_SPRINGVILLE_STBY_LVC3_SCL")
	)
	(segment
		(start 485.5972 -130.048)
		(end 485.5972 -129.8448)
		(width 0.089408)
		(layer "In4.Cu")
		(net "SMB_SPRINGVILLE_STBY_LVC3_SCL")
	)
	(segment
		(start 488.349544 -126.9746)
		(end 487.553 -127.771144)
		(width 0.089408)
		(layer "In4.Cu")
		(net "SMB_SPRINGVILLE_STBY_LVC3_SCL")
	)
	(segment
		(start 495.095784 -123.65482)
		(end 491.776004 -126.9746)
		(width 0.089408)
		(layer "In4.Cu")
		(net "SMB_SPRINGVILLE_STBY_LVC3_SCL")
	)
	(segment
		(start 471.508582 -8.767572)
		(end 471.508582 -8.855456)
		(width 0.10795)
		(layer "F.Cu")
		(net "SMB_SLOTX24_STBY_LVC3_SDA_R2")
	)
	(segment
		(start 471.508582 -8.855456)
		(end 470.666318 -9.69772)
		(width 0.10795)
		(layer "F.Cu")
		(net "SMB_SLOTX24_STBY_LVC3_SDA_R2")
	)
	(segment
		(start 470.666318 -9.69772)
		(end 468.818976 -9.69772)
		(width 0.10795)
		(layer "F.Cu")
		(net "SMB_SLOTX24_STBY_LVC3_SDA_R2")
	)
	(segment
		(start 468.479378 -9.358122)
		(end 468.479378 -7.789672)
		(width 0.10795)
		(layer "F.Cu")
		(net "SMB_SLOTX24_STBY_LVC3_SDA_R2")
	)
	(segment
		(start 468.818976 -9.69772)
		(end 468.479378 -9.358122)
		(width 0.10795)
		(layer "F.Cu")
		(net "SMB_SLOTX24_STBY_LVC3_SDA_R2")
	)
	(via
		(at 471.508582 -8.767572)
		(size 0.508)
		(drill 0.254)
		(layers "F.Cu" "B.Cu")
		(net "SMB_SLOTX24_STBY_LVC3_SDA_R2")
	)
	(segment
		(start 471.508582 -8.825484)
		(end 471.508582 -8.767572)
		(width 0.10795)
		(layer "B.Cu")
		(net "SMB_SLOTX24_STBY_LVC3_SDA_R2")
	)
	(segment
		(start 470.943686 -9.39038)
		(end 471.508582 -8.825484)
		(width 0.10795)
		(layer "B.Cu")
		(net "SMB_SLOTX24_STBY_LVC3_SDA_R2")
	)
	(segment
		(start 469.197944 -10.53592)
		(end 469.36152 -10.53592)
		(width 0.10795)
		(layer "B.Cu")
		(net "SMB_SLOTX24_STBY_LVC3_SDA_R2")
	)
	(segment
		(start 470.50706 -9.39038)
		(end 470.943686 -9.39038)
		(width 0.10795)
		(layer "B.Cu")
		(net "SMB_SLOTX24_STBY_LVC3_SDA_R2")
	)
	(segment
		(start 469.36152 -10.53592)
		(end 470.50706 -9.39038)
		(width 0.10795)
		(layer "B.Cu")
		(net "SMB_SLOTX24_STBY_LVC3_SDA_R2")
	)
	(segment
		(start 467.679278 -8.282686)
		(end 467.679278 -7.789672)
		(width 0.10795)
		(layer "F.Cu")
		(net "SMB_SLOTX24_STBY_LVC3_SCL_R2")
	)
	(segment
		(start 467.2076 -8.754364)
		(end 467.679278 -8.282686)
		(width 0.10795)
		(layer "F.Cu")
		(net "SMB_SLOTX24_STBY_LVC3_SCL_R2")
	)
	(segment
		(start 466.979 -10.2616)
		(end 467.2076 -10.033)
		(width 0.10795)
		(layer "F.Cu")
		(net "SMB_SLOTX24_STBY_LVC3_SCL_R2")
	)
	(segment
		(start 467.2076 -10.033)
		(end 467.2076 -8.754364)
		(width 0.10795)
		(layer "F.Cu")
		(net "SMB_SLOTX24_STBY_LVC3_SCL_R2")
	)
	(via
		(at 466.979 -10.2616)
		(size 0.508)
		(drill 0.254)
		(layers "F.Cu" "B.Cu")
		(net "SMB_SLOTX24_STBY_LVC3_SCL_R2")
	)
	(segment
		(start 467.25332 -10.53592)
		(end 468.181944 -10.53592)
		(width 0.10795)
		(layer "B.Cu")
		(net "SMB_SLOTX24_STBY_LVC3_SCL_R2")
	)
	(segment
		(start 466.979 -10.2616)
		(end 467.25332 -10.53592)
		(width 0.10795)
		(layer "B.Cu")
		(net "SMB_SLOTX24_STBY_LVC3_SCL_R2")
	)
	(via
		(at 427.604936 -48.490632)
		(size 0.508)
		(drill 0.254)
		(layers "F.Cu" "B.Cu")
		(net "SMB_SLOTX24_BMC_STBY_LVC3_SDA")
	)
	(via
		(at 472.948 -45.085)
		(size 0.508)
		(drill 0.254)
		(layers "F.Cu" "B.Cu")
		(net "SMB_SLOTX24_BMC_STBY_LVC3_SDA")
	)
	(via
		(at 471.982292 -10.441432)
		(size 0.508)
		(drill 0.254)
		(layers "F.Cu" "B.Cu")
		(net "SMB_SLOTX24_BMC_STBY_LVC3_SDA")
	)
	(via
		(at 426.099732 -48.245014)
		(size 0.6604)
		(drill 0.3302)
		(layers "F.Cu" "B.Cu")
		(net "SMB_SLOTX24_BMC_STBY_LVC3_SDA")
	)
	(segment
		(start 421.381682 -50.108104)
		(end 421.273986 -50.2158)
		(width 0.10795)
		(layer "B.Cu")
		(net "SMB_SLOTX24_BMC_STBY_LVC3_SDA")
	)
	(segment
		(start 421.273986 -50.2158)
		(end 420.183564 -50.2158)
		(width 0.10795)
		(layer "B.Cu")
		(net "SMB_SLOTX24_BMC_STBY_LVC3_SDA")
	)
	(segment
		(start 426.063918 -48.2092)
		(end 425.8056 -48.2092)
		(width 0.10795)
		(layer "B.Cu")
		(net "SMB_SLOTX24_BMC_STBY_LVC3_SDA")
	)
	(segment
		(start 427.604936 -48.490632)
		(end 426.34535 -48.490632)
		(width 0.10795)
		(layer "B.Cu")
		(net "SMB_SLOTX24_BMC_STBY_LVC3_SDA")
	)
	(segment
		(start 423.629328 -50.108104)
		(end 421.381682 -50.108104)
		(width 0.10795)
		(layer "B.Cu")
		(net "SMB_SLOTX24_BMC_STBY_LVC3_SDA")
	)
	(segment
		(start 471.28811 -11.42492)
		(end 469.197944 -11.42492)
		(width 0.10795)
		(layer "B.Cu")
		(net "SMB_SLOTX24_BMC_STBY_LVC3_SDA")
	)
	(segment
		(start 423.754296 -49.983136)
		(end 423.629328 -50.108104)
		(width 0.10795)
		(layer "B.Cu")
		(net "SMB_SLOTX24_BMC_STBY_LVC3_SDA")
	)
	(segment
		(start 420.183564 -50.2158)
		(end 419.887146 -49.919382)
		(width 0.10795)
		(layer "B.Cu")
		(net "SMB_SLOTX24_BMC_STBY_LVC3_SDA")
	)
	(segment
		(start 426.099732 -48.245014)
		(end 426.063918 -48.2092)
		(width 0.10795)
		(layer "B.Cu")
		(net "SMB_SLOTX24_BMC_STBY_LVC3_SDA")
	)
	(segment
		(start 471.982292 -10.730738)
		(end 471.28811 -11.42492)
		(width 0.10795)
		(layer "B.Cu")
		(net "SMB_SLOTX24_BMC_STBY_LVC3_SDA")
	)
	(segment
		(start 471.982292 -10.441432)
		(end 471.982292 -10.730738)
		(width 0.10795)
		(layer "B.Cu")
		(net "SMB_SLOTX24_BMC_STBY_LVC3_SDA")
	)
	(segment
		(start 424.031664 -49.983136)
		(end 423.754296 -49.983136)
		(width 0.10795)
		(layer "B.Cu")
		(net "SMB_SLOTX24_BMC_STBY_LVC3_SDA")
	)
	(segment
		(start 426.34535 -48.490632)
		(end 426.099732 -48.245014)
		(width 0.10795)
		(layer "B.Cu")
		(net "SMB_SLOTX24_BMC_STBY_LVC3_SDA")
	)
	(segment
		(start 419.887146 -49.919382)
		(end 419.887146 -48.922432)
		(width 0.10795)
		(layer "B.Cu")
		(net "SMB_SLOTX24_BMC_STBY_LVC3_SDA")
	)
	(segment
		(start 425.8056 -48.2092)
		(end 424.031664 -49.983136)
		(width 0.10795)
		(layer "B.Cu")
		(net "SMB_SLOTX24_BMC_STBY_LVC3_SDA")
	)
	(segment
		(start 431.027332 -50.905918)
		(end 431.027586 -50.906172)
		(width 0.089408)
		(layer "In2.Cu")
		(net "SMB_SLOTX24_BMC_STBY_LVC3_SDA")
	)
	(segment
		(start 472.736672 -45.296328)
		(end 472.948 -45.085)
		(width 0.089408)
		(layer "In2.Cu")
		(net "SMB_SLOTX24_BMC_STBY_LVC3_SDA")
	)
	(segment
		(start 468.299292 -47.887128)
		(end 470.890092 -45.296328)
		(width 0.089408)
		(layer "In2.Cu")
		(net "SMB_SLOTX24_BMC_STBY_LVC3_SDA")
	)
	(segment
		(start 470.890092 -45.296328)
		(end 472.736672 -45.296328)
		(width 0.089408)
		(layer "In2.Cu")
		(net "SMB_SLOTX24_BMC_STBY_LVC3_SDA")
	)
	(segment
		(start 427.890178 -50.080164)
		(end 428.715932 -50.905918)
		(width 0.089408)
		(layer "In2.Cu")
		(net "SMB_SLOTX24_BMC_STBY_LVC3_SDA")
	)
	(segment
		(start 435.885082 -50.905918)
		(end 438.903872 -47.887128)
		(width 0.089408)
		(layer "In2.Cu")
		(net "SMB_SLOTX24_BMC_STBY_LVC3_SDA")
	)
	(segment
		(start 427.604936 -48.490632)
		(end 427.890178 -48.775874)
		(width 0.089408)
		(layer "In2.Cu")
		(net "SMB_SLOTX24_BMC_STBY_LVC3_SDA")
	)
	(segment
		(start 428.715932 -50.905918)
		(end 431.027332 -50.905918)
		(width 0.089408)
		(layer "In2.Cu")
		(net "SMB_SLOTX24_BMC_STBY_LVC3_SDA")
	)
	(segment
		(start 427.890178 -48.775874)
		(end 427.890178 -50.080164)
		(width 0.089408)
		(layer "In2.Cu")
		(net "SMB_SLOTX24_BMC_STBY_LVC3_SDA")
	)
	(segment
		(start 431.665634 -50.905918)
		(end 435.885082 -50.905918)
		(width 0.089408)
		(layer "In2.Cu")
		(net "SMB_SLOTX24_BMC_STBY_LVC3_SDA")
	)
	(segment
		(start 431.027586 -50.906172)
		(end 431.66538 -50.906172)
		(width 0.089408)
		(layer "In2.Cu")
		(net "SMB_SLOTX24_BMC_STBY_LVC3_SDA")
	)
	(segment
		(start 431.66538 -50.906172)
		(end 431.665634 -50.905918)
		(width 0.089408)
		(layer "In2.Cu")
		(net "SMB_SLOTX24_BMC_STBY_LVC3_SDA")
	)
	(segment
		(start 438.903872 -47.887128)
		(end 468.299292 -47.887128)
		(width 0.089408)
		(layer "In2.Cu")
		(net "SMB_SLOTX24_BMC_STBY_LVC3_SDA")
	)
	(segment
		(start 470.1032 -40.546528)
		(end 470.953592 -39.696136)
		(width 0.089408)
		(layer "In11.Cu")
		(net "SMB_SLOTX24_BMC_STBY_LVC3_SDA")
	)
	(segment
		(start 472.948 -45.085)
		(end 472.948 -44.958)
		(width 0.089408)
		(layer "In11.Cu")
		(net "SMB_SLOTX24_BMC_STBY_LVC3_SDA")
	)
	(segment
		(start 465.24418 -14.1732)
		(end 467.225888 -14.1732)
		(width 0.089408)
		(layer "In11.Cu")
		(net "SMB_SLOTX24_BMC_STBY_LVC3_SDA")
	)
	(segment
		(start 470.1032 -42.42562)
		(end 470.1032 -40.546528)
		(width 0.089408)
		(layer "In11.Cu")
		(net "SMB_SLOTX24_BMC_STBY_LVC3_SDA")
	)
	(segment
		(start 474.536262 -32.844994)
		(end 474.536262 -32.687006)
		(width 0.089408)
		(layer "In11.Cu")
		(net "SMB_SLOTX24_BMC_STBY_LVC3_SDA")
	)
	(segment
		(start 468.224616 -13.174472)
		(end 470.847928 -13.174472)
		(width 0.089408)
		(layer "In11.Cu")
		(net "SMB_SLOTX24_BMC_STBY_LVC3_SDA")
	)
	(segment
		(start 474.037152 -30.365192)
		(end 471.936572 -30.365192)
		(width 0.089408)
		(layer "In11.Cu")
		(net "SMB_SLOTX24_BMC_STBY_LVC3_SDA")
	)
	(segment
		(start 474.536008 -30.705552)
		(end 474.195394 -30.364938)
		(width 0.089408)
		(layer "In11.Cu")
		(net "SMB_SLOTX24_BMC_STBY_LVC3_SDA")
	)
	(segment
		(start 473.86113 -33.520126)
		(end 474.536262 -32.844994)
		(width 0.089408)
		(layer "In11.Cu")
		(net "SMB_SLOTX24_BMC_STBY_LVC3_SDA")
	)
	(segment
		(start 473.1004 -10.287)
		(end 472.772232 -9.958832)
		(width 0.089408)
		(layer "In11.Cu")
		(net "SMB_SLOTX24_BMC_STBY_LVC3_SDA")
	)
	(segment
		(start 463.988912 -19.412712)
		(end 463.988912 -15.428468)
		(width 0.089408)
		(layer "In11.Cu")
		(net "SMB_SLOTX24_BMC_STBY_LVC3_SDA")
	)
	(segment
		(start 472.772232 -9.958832)
		(end 472.464892 -9.958832)
		(width 0.089408)
		(layer "In11.Cu")
		(net "SMB_SLOTX24_BMC_STBY_LVC3_SDA")
	)
	(segment
		(start 471.936572 -30.365192)
		(end 464.94319 -23.37181)
		(width 0.089408)
		(layer "In11.Cu")
		(net "SMB_SLOTX24_BMC_STBY_LVC3_SDA")
	)
	(segment
		(start 472.6686 -44.6786)
		(end 472.35618 -44.6786)
		(width 0.089408)
		(layer "In11.Cu")
		(net "SMB_SLOTX24_BMC_STBY_LVC3_SDA")
	)
	(segment
		(start 471.304366 -39.696136)
		(end 474.140784 -36.859718)
		(width 0.089408)
		(layer "In11.Cu")
		(net "SMB_SLOTX24_BMC_STBY_LVC3_SDA")
	)
	(segment
		(start 474.037406 -30.364938)
		(end 474.037152 -30.365192)
		(width 0.089408)
		(layer "In11.Cu")
		(net "SMB_SLOTX24_BMC_STBY_LVC3_SDA")
	)
	(segment
		(start 474.140784 -36.859718)
		(end 474.140784 -35.052)
		(width 0.089408)
		(layer "In11.Cu")
		(net "SMB_SLOTX24_BMC_STBY_LVC3_SDA")
	)
	(segment
		(start 473.86113 -34.772346)
		(end 473.86113 -33.520126)
		(width 0.089408)
		(layer "In11.Cu")
		(net "SMB_SLOTX24_BMC_STBY_LVC3_SDA")
	)
	(segment
		(start 467.225888 -14.1732)
		(end 468.224616 -13.174472)
		(width 0.089408)
		(layer "In11.Cu")
		(net "SMB_SLOTX24_BMC_STBY_LVC3_SDA")
	)
	(segment
		(start 472.948 -44.958)
		(end 472.6686 -44.6786)
		(width 0.089408)
		(layer "In11.Cu")
		(net "SMB_SLOTX24_BMC_STBY_LVC3_SDA")
	)
	(segment
		(start 474.140784 -35.052)
		(end 473.86113 -34.772346)
		(width 0.089408)
		(layer "In11.Cu")
		(net "SMB_SLOTX24_BMC_STBY_LVC3_SDA")
	)
	(segment
		(start 472.35618 -44.6786)
		(end 470.1032 -42.42562)
		(width 0.089408)
		(layer "In11.Cu")
		(net "SMB_SLOTX24_BMC_STBY_LVC3_SDA")
	)
	(segment
		(start 474.536008 -32.686752)
		(end 474.536008 -30.705552)
		(width 0.089408)
		(layer "In11.Cu")
		(net "SMB_SLOTX24_BMC_STBY_LVC3_SDA")
	)
	(segment
		(start 474.536262 -32.687006)
		(end 474.536008 -32.686752)
		(width 0.089408)
		(layer "In11.Cu")
		(net "SMB_SLOTX24_BMC_STBY_LVC3_SDA")
	)
	(segment
		(start 472.464892 -9.958832)
		(end 471.982292 -10.441432)
		(width 0.089408)
		(layer "In11.Cu")
		(net "SMB_SLOTX24_BMC_STBY_LVC3_SDA")
	)
	(segment
		(start 473.1004 -10.922)
		(end 473.1004 -10.287)
		(width 0.089408)
		(layer "In11.Cu")
		(net "SMB_SLOTX24_BMC_STBY_LVC3_SDA")
	)
	(segment
		(start 464.94319 -20.36699)
		(end 463.988912 -19.412712)
		(width 0.089408)
		(layer "In11.Cu")
		(net "SMB_SLOTX24_BMC_STBY_LVC3_SDA")
	)
	(segment
		(start 470.953592 -39.696136)
		(end 471.304366 -39.696136)
		(width 0.089408)
		(layer "In11.Cu")
		(net "SMB_SLOTX24_BMC_STBY_LVC3_SDA")
	)
	(segment
		(start 470.847928 -13.174472)
		(end 473.1004 -10.922)
		(width 0.089408)
		(layer "In11.Cu")
		(net "SMB_SLOTX24_BMC_STBY_LVC3_SDA")
	)
	(segment
		(start 464.94319 -23.37181)
		(end 464.94319 -20.36699)
		(width 0.089408)
		(layer "In11.Cu")
		(net "SMB_SLOTX24_BMC_STBY_LVC3_SDA")
	)
	(segment
		(start 474.195394 -30.364938)
		(end 474.037406 -30.364938)
		(width 0.089408)
		(layer "In11.Cu")
		(net "SMB_SLOTX24_BMC_STBY_LVC3_SDA")
	)
	(segment
		(start 463.988912 -15.428468)
		(end 465.24418 -14.1732)
		(width 0.089408)
		(layer "In11.Cu")
		(net "SMB_SLOTX24_BMC_STBY_LVC3_SDA")
	)
	(via
		(at 428.290482 -48.5775)
		(size 0.508)
		(drill 0.254)
		(layers "F.Cu" "B.Cu")
		(net "SMB_SLOTX24_BMC_STBY_LVC3_SCL")
	)
	(via
		(at 472.639644 -10.4648)
		(size 0.508)
		(drill 0.254)
		(layers "F.Cu" "B.Cu")
		(net "SMB_SLOTX24_BMC_STBY_LVC3_SCL")
	)
	(via
		(at 420.6748 -50.7238)
		(size 0.6604)
		(drill 0.3302)
		(layers "F.Cu" "B.Cu")
		(net "SMB_SLOTX24_BMC_STBY_LVC3_SCL")
	)
	(via
		(at 471.7796 -44.6786)
		(size 0.508)
		(drill 0.254)
		(layers "F.Cu" "B.Cu")
		(net "SMB_SLOTX24_BMC_STBY_LVC3_SCL")
	)
	(segment
		(start 419.63848 -50.19548)
		(end 420.1668 -50.7238)
		(width 0.10795)
		(layer "B.Cu")
		(net "SMB_SLOTX24_BMC_STBY_LVC3_SCL")
	)
	(segment
		(start 424.04665 -50.21834)
		(end 424.15079 -50.21834)
		(width 0.10795)
		(layer "B.Cu")
		(net "SMB_SLOTX24_BMC_STBY_LVC3_SCL")
	)
	(segment
		(start 472.639644 -10.793476)
		(end 471.5129 -11.92022)
		(width 0.10795)
		(layer "B.Cu")
		(net "SMB_SLOTX24_BMC_STBY_LVC3_SCL")
	)
	(segment
		(start 468.181944 -11.571224)
		(end 468.181944 -11.42492)
		(width 0.10795)
		(layer "B.Cu")
		(net "SMB_SLOTX24_BMC_STBY_LVC3_SCL")
	)
	(segment
		(start 420.1668 -50.7238)
		(end 420.6748 -50.7238)
		(width 0.10795)
		(layer "B.Cu")
		(net "SMB_SLOTX24_BMC_STBY_LVC3_SCL")
	)
	(segment
		(start 419.63848 -49.439576)
		(end 419.63848 -50.19548)
		(width 0.10795)
		(layer "B.Cu")
		(net "SMB_SLOTX24_BMC_STBY_LVC3_SCL")
	)
	(segment
		(start 425.09313 -49.276)
		(end 427.591982 -49.276)
		(width 0.10795)
		(layer "B.Cu")
		(net "SMB_SLOTX24_BMC_STBY_LVC3_SCL")
	)
	(segment
		(start 421.352472 -50.4698)
		(end 421.479218 -50.343054)
		(width 0.10795)
		(layer "B.Cu")
		(net "SMB_SLOTX24_BMC_STBY_LVC3_SCL")
	)
	(segment
		(start 421.479218 -50.343054)
		(end 423.726864 -50.343054)
		(width 0.10795)
		(layer "B.Cu")
		(net "SMB_SLOTX24_BMC_STBY_LVC3_SCL")
	)
	(segment
		(start 427.591982 -49.276)
		(end 428.290482 -48.5775)
		(width 0.10795)
		(layer "B.Cu")
		(net "SMB_SLOTX24_BMC_STBY_LVC3_SCL")
	)
	(segment
		(start 423.726864 -50.343054)
		(end 423.851832 -50.218086)
		(width 0.10795)
		(layer "B.Cu")
		(net "SMB_SLOTX24_BMC_STBY_LVC3_SCL")
	)
	(segment
		(start 421.024558 -50.4698)
		(end 421.352472 -50.4698)
		(width 0.10795)
		(layer "B.Cu")
		(net "SMB_SLOTX24_BMC_STBY_LVC3_SCL")
	)
	(segment
		(start 424.046396 -50.218086)
		(end 424.04665 -50.21834)
		(width 0.10795)
		(layer "B.Cu")
		(net "SMB_SLOTX24_BMC_STBY_LVC3_SCL")
	)
	(segment
		(start 418.7063 -48.9204)
		(end 419.119304 -48.9204)
		(width 0.10795)
		(layer "B.Cu")
		(net "SMB_SLOTX24_BMC_STBY_LVC3_SCL")
	)
	(segment
		(start 468.53094 -11.92022)
		(end 468.181944 -11.571224)
		(width 0.10795)
		(layer "B.Cu")
		(net "SMB_SLOTX24_BMC_STBY_LVC3_SCL")
	)
	(segment
		(start 419.119304 -48.9204)
		(end 419.63848 -49.439576)
		(width 0.10795)
		(layer "B.Cu")
		(net "SMB_SLOTX24_BMC_STBY_LVC3_SCL")
	)
	(segment
		(start 471.5129 -11.92022)
		(end 468.53094 -11.92022)
		(width 0.10795)
		(layer "B.Cu")
		(net "SMB_SLOTX24_BMC_STBY_LVC3_SCL")
	)
	(segment
		(start 423.851832 -50.218086)
		(end 424.046396 -50.218086)
		(width 0.10795)
		(layer "B.Cu")
		(net "SMB_SLOTX24_BMC_STBY_LVC3_SCL")
	)
	(segment
		(start 472.639644 -10.4648)
		(end 472.639644 -10.793476)
		(width 0.10795)
		(layer "B.Cu")
		(net "SMB_SLOTX24_BMC_STBY_LVC3_SCL")
	)
	(segment
		(start 424.15079 -50.21834)
		(end 425.09313 -49.276)
		(width 0.10795)
		(layer "B.Cu")
		(net "SMB_SLOTX24_BMC_STBY_LVC3_SCL")
	)
	(segment
		(start 420.6748 -50.7238)
		(end 420.770558 -50.7238)
		(width 0.10795)
		(layer "B.Cu")
		(net "SMB_SLOTX24_BMC_STBY_LVC3_SCL")
	)
	(segment
		(start 420.770558 -50.7238)
		(end 421.024558 -50.4698)
		(width 0.10795)
		(layer "B.Cu")
		(net "SMB_SLOTX24_BMC_STBY_LVC3_SCL")
	)
	(segment
		(start 431.586386 -50.71491)
		(end 433.39639 -50.71491)
		(width 0.089408)
		(layer "In2.Cu")
		(net "SMB_SLOTX24_BMC_STBY_LVC3_SCL")
	)
	(segment
		(start 434.165756 -48.069246)
		(end 434.982874 -48.069246)
		(width 0.089408)
		(layer "In2.Cu")
		(net "SMB_SLOTX24_BMC_STBY_LVC3_SCL")
	)
	(segment
		(start 431.586132 -50.715164)
		(end 431.586386 -50.71491)
		(width 0.089408)
		(layer "In2.Cu")
		(net "SMB_SLOTX24_BMC_STBY_LVC3_SCL")
	)
	(segment
		(start 428.79518 -50.71491)
		(end 431.10658 -50.71491)
		(width 0.089408)
		(layer "In2.Cu")
		(net "SMB_SLOTX24_BMC_STBY_LVC3_SCL")
	)
	(segment
		(start 468.140542 -47.69612)
		(end 470.731342 -45.10532)
		(width 0.089408)
		(layer "In2.Cu")
		(net "SMB_SLOTX24_BMC_STBY_LVC3_SCL")
	)
	(segment
		(start 435.356 -47.69612)
		(end 468.140542 -47.69612)
		(width 0.089408)
		(layer "In2.Cu")
		(net "SMB_SLOTX24_BMC_STBY_LVC3_SCL")
	)
	(segment
		(start 431.10658 -50.71491)
		(end 431.106834 -50.715164)
		(width 0.089408)
		(layer "In2.Cu")
		(net "SMB_SLOTX24_BMC_STBY_LVC3_SCL")
	)
	(segment
		(start 433.39639 -50.71491)
		(end 433.639468 -50.471832)
		(width 0.089408)
		(layer "In2.Cu")
		(net "SMB_SLOTX24_BMC_STBY_LVC3_SCL")
	)
	(segment
		(start 431.106834 -50.715164)
		(end 431.586132 -50.715164)
		(width 0.089408)
		(layer "In2.Cu")
		(net "SMB_SLOTX24_BMC_STBY_LVC3_SCL")
	)
	(segment
		(start 433.639468 -48.595534)
		(end 434.165756 -48.069246)
		(width 0.089408)
		(layer "In2.Cu")
		(net "SMB_SLOTX24_BMC_STBY_LVC3_SCL")
	)
	(segment
		(start 470.731342 -45.10532)
		(end 471.35288 -45.10532)
		(width 0.089408)
		(layer "In2.Cu")
		(net "SMB_SLOTX24_BMC_STBY_LVC3_SCL")
	)
	(segment
		(start 433.639468 -50.471832)
		(end 433.639468 -48.595534)
		(width 0.089408)
		(layer "In2.Cu")
		(net "SMB_SLOTX24_BMC_STBY_LVC3_SCL")
	)
	(segment
		(start 434.982874 -48.069246)
		(end 435.356 -47.69612)
		(width 0.089408)
		(layer "In2.Cu")
		(net "SMB_SLOTX24_BMC_STBY_LVC3_SCL")
	)
	(segment
		(start 471.35288 -45.10532)
		(end 471.7796 -44.6786)
		(width 0.089408)
		(layer "In2.Cu")
		(net "SMB_SLOTX24_BMC_STBY_LVC3_SCL")
	)
	(segment
		(start 428.290482 -48.5775)
		(end 428.0916 -48.776382)
		(width 0.089408)
		(layer "In2.Cu")
		(net "SMB_SLOTX24_BMC_STBY_LVC3_SCL")
	)
	(segment
		(start 428.0916 -50.01133)
		(end 428.79518 -50.71491)
		(width 0.089408)
		(layer "In2.Cu")
		(net "SMB_SLOTX24_BMC_STBY_LVC3_SCL")
	)
	(segment
		(start 428.0916 -48.776382)
		(end 428.0916 -50.01133)
		(width 0.089408)
		(layer "In2.Cu")
		(net "SMB_SLOTX24_BMC_STBY_LVC3_SCL")
	)
	(segment
		(start 463.797904 -19.551904)
		(end 463.797904 -15.34922)
		(width 0.089408)
		(layer "In11.Cu")
		(net "SMB_SLOTX24_BMC_STBY_LVC3_SCL")
	)
	(segment
		(start 469.912192 -42.504868)
		(end 469.912192 -40.46728)
		(width 0.089408)
		(layer "In11.Cu")
		(net "SMB_SLOTX24_BMC_STBY_LVC3_SCL")
	)
	(segment
		(start 463.797904 -15.34922)
		(end 465.329524 -13.8176)
		(width 0.089408)
		(layer "In11.Cu")
		(net "SMB_SLOTX24_BMC_STBY_LVC3_SCL")
	)
	(segment
		(start 471.225118 -39.505128)
		(end 473.939108 -36.791138)
		(width 0.089408)
		(layer "In11.Cu")
		(net "SMB_SLOTX24_BMC_STBY_LVC3_SCL")
	)
	(segment
		(start 473.550742 -33.560258)
		(end 474.345 -32.766)
		(width 0.089408)
		(layer "In11.Cu")
		(net "SMB_SLOTX24_BMC_STBY_LVC3_SCL")
	)
	(segment
		(start 467.311232 -13.8176)
		(end 468.17407 -12.954762)
		(width 0.089408)
		(layer "In11.Cu")
		(net "SMB_SLOTX24_BMC_STBY_LVC3_SCL")
	)
	(segment
		(start 468.17407 -12.954762)
		(end 470.73185 -12.954762)
		(width 0.089408)
		(layer "In11.Cu")
		(net "SMB_SLOTX24_BMC_STBY_LVC3_SCL")
	)
	(segment
		(start 464.752182 -23.451058)
		(end 464.752182 -20.506182)
		(width 0.089408)
		(layer "In11.Cu")
		(net "SMB_SLOTX24_BMC_STBY_LVC3_SCL")
	)
	(segment
		(start 470.73185 -12.954762)
		(end 472.639644 -11.046968)
		(width 0.089408)
		(layer "In11.Cu")
		(net "SMB_SLOTX24_BMC_STBY_LVC3_SCL")
	)
	(segment
		(start 473.550742 -34.91992)
		(end 473.550742 -33.560258)
		(width 0.089408)
		(layer "In11.Cu")
		(net "SMB_SLOTX24_BMC_STBY_LVC3_SCL")
	)
	(segment
		(start 472.639644 -11.046968)
		(end 472.639644 -10.4648)
		(width 0.089408)
		(layer "In11.Cu")
		(net "SMB_SLOTX24_BMC_STBY_LVC3_SCL")
	)
	(segment
		(start 473.939108 -36.791138)
		(end 473.939108 -35.308286)
		(width 0.089408)
		(layer "In11.Cu")
		(net "SMB_SLOTX24_BMC_STBY_LVC3_SCL")
	)
	(segment
		(start 474.1164 -30.5562)
		(end 471.857324 -30.5562)
		(width 0.089408)
		(layer "In11.Cu")
		(net "SMB_SLOTX24_BMC_STBY_LVC3_SCL")
	)
	(segment
		(start 470.874344 -39.505128)
		(end 471.225118 -39.505128)
		(width 0.089408)
		(layer "In11.Cu")
		(net "SMB_SLOTX24_BMC_STBY_LVC3_SCL")
	)
	(segment
		(start 474.345 -30.7848)
		(end 474.1164 -30.5562)
		(width 0.089408)
		(layer "In11.Cu")
		(net "SMB_SLOTX24_BMC_STBY_LVC3_SCL")
	)
	(segment
		(start 471.857324 -30.5562)
		(end 464.752182 -23.451058)
		(width 0.089408)
		(layer "In11.Cu")
		(net "SMB_SLOTX24_BMC_STBY_LVC3_SCL")
	)
	(segment
		(start 469.912192 -40.46728)
		(end 470.874344 -39.505128)
		(width 0.089408)
		(layer "In11.Cu")
		(net "SMB_SLOTX24_BMC_STBY_LVC3_SCL")
	)
	(segment
		(start 464.752182 -20.506182)
		(end 463.797904 -19.551904)
		(width 0.089408)
		(layer "In11.Cu")
		(net "SMB_SLOTX24_BMC_STBY_LVC3_SCL")
	)
	(segment
		(start 471.7796 -44.372276)
		(end 469.912192 -42.504868)
		(width 0.089408)
		(layer "In11.Cu")
		(net "SMB_SLOTX24_BMC_STBY_LVC3_SCL")
	)
	(segment
		(start 474.345 -32.766)
		(end 474.345 -30.7848)
		(width 0.089408)
		(layer "In11.Cu")
		(net "SMB_SLOTX24_BMC_STBY_LVC3_SCL")
	)
	(segment
		(start 473.939108 -35.308286)
		(end 473.550742 -34.91992)
		(width 0.089408)
		(layer "In11.Cu")
		(net "SMB_SLOTX24_BMC_STBY_LVC3_SCL")
	)
	(segment
		(start 465.329524 -13.8176)
		(end 467.311232 -13.8176)
		(width 0.089408)
		(layer "In11.Cu")
		(net "SMB_SLOTX24_BMC_STBY_LVC3_SCL")
	)
	(segment
		(start 471.7796 -44.6786)
		(end 471.7796 -44.372276)
		(width 0.089408)
		(layer "In11.Cu")
		(net "SMB_SLOTX24_BMC_STBY_LVC3_SCL")
	)
	(segment
		(start 404.083774 -157.172152)
		(end 404.232872 -157.32125)
		(width 0.10795)
		(layer "F.Cu")
		(net "SMB_SENSOR_STBY_LVC3_SDA")
	)
	(segment
		(start 422.275 -17.694148)
		(end 422.275 -17.935448)
		(width 0.10795)
		(layer "F.Cu")
		(net "SMB_SENSOR_STBY_LVC3_SDA")
	)
	(segment
		(start 495.36858 -124.54636)
		(end 495.07394 -124.25172)
		(width 0.10795)
		(layer "F.Cu")
		(net "SMB_SENSOR_STBY_LVC3_SDA")
	)
	(segment
		(start 451.364858 -158.489142)
		(end 451.7136 -158.1404)
		(width 0.10795)
		(layer "F.Cu")
		(net "SMB_SENSOR_STBY_LVC3_SDA")
	)
	(segment
		(start 422.275 -17.935448)
		(end 422.7449 -18.405348)
		(width 0.10795)
		(layer "F.Cu")
		(net "SMB_SENSOR_STBY_LVC3_SDA")
	)
	(segment
		(start 420.1414 -17.8562)
		(end 420.693088 -17.304512)
		(width 0.10795)
		(layer "F.Cu")
		(net "SMB_SENSOR_STBY_LVC3_SDA")
	)
	(segment
		(start 495.77244 -121.46788)
		(end 495.77244 -124.39142)
		(width 0.10795)
		(layer "F.Cu")
		(net "SMB_SENSOR_STBY_LVC3_SDA")
	)
	(segment
		(start 2.032 -75.946)
		(end 2.032 -76.492862)
		(width 0.10795)
		(layer "F.Cu")
		(net "SMB_SENSOR_STBY_LVC3_SDA")
	)
	(segment
		(start 421.885364 -17.304512)
		(end 422.275 -17.694148)
		(width 0.10795)
		(layer "F.Cu")
		(net "SMB_SENSOR_STBY_LVC3_SDA")
	)
	(segment
		(start 423.917872 -16.50492)
		(end 424.800776 -16.50492)
		(width 0.10795)
		(layer "F.Cu")
		(net "SMB_SENSOR_STBY_LVC3_SDA")
	)
	(segment
		(start 379.903228 -64.988694)
		(end 379.487684 -65.404238)
		(width 0.1016)
		(layer "F.Cu")
		(net "SMB_SENSOR_STBY_LVC3_SDA")
	)
	(segment
		(start 373.888 -66.548)
		(end 372.9736 -67.4624)
		(width 0.1016)
		(layer "F.Cu")
		(net "SMB_SENSOR_STBY_LVC3_SDA")
	)
	(segment
		(start 427.584616 -13.72108)
		(end 430.220628 -13.72108)
		(width 0.10795)
		(layer "F.Cu")
		(net "SMB_SENSOR_STBY_LVC3_SDA")
	)
	(segment
		(start 430.220628 -13.72108)
		(end 431.17008 -12.771628)
		(width 0.10795)
		(layer "F.Cu")
		(net "SMB_SENSOR_STBY_LVC3_SDA")
	)
	(segment
		(start 411.667706 -58.15965)
		(end 411.775656 -58.0517)
		(width 0.10795)
		(layer "F.Cu")
		(net "SMB_SENSOR_STBY_LVC3_SDA")
	)
	(segment
		(start 431.17008 -12.771628)
		(end 431.17008 -11.7856)
		(width 0.10795)
		(layer "F.Cu")
		(net "SMB_SENSOR_STBY_LVC3_SDA")
	)
	(segment
		(start 424.800776 -16.50492)
		(end 427.584616 -13.72108)
		(width 0.10795)
		(layer "F.Cu")
		(net "SMB_SENSOR_STBY_LVC3_SDA")
	)
	(segment
		(start 379.487684 -65.962276)
		(end 378.90196 -66.548)
		(width 0.1016)
		(layer "F.Cu")
		(net "SMB_SENSOR_STBY_LVC3_SDA")
	)
	(segment
		(start 495.77244 -124.39142)
		(end 495.6175 -124.54636)
		(width 0.10795)
		(layer "F.Cu")
		(net "SMB_SENSOR_STBY_LVC3_SDA")
	)
	(segment
		(start 2.032 -76.492862)
		(end 1.728724 -76.796138)
		(width 0.10795)
		(layer "F.Cu")
		(net "SMB_SENSOR_STBY_LVC3_SDA")
	)
	(segment
		(start 408.9908 -61.162946)
		(end 408.9908 -58.797952)
		(width 0.10795)
		(layer "F.Cu")
		(net "SMB_SENSOR_STBY_LVC3_SDA")
	)
	(segment
		(start 451.7136 -158.1404)
		(end 451.7136 -157.2006)
		(width 0.10795)
		(layer "F.Cu")
		(net "SMB_SENSOR_STBY_LVC3_SDA")
	)
	(segment
		(start 378.90196 -66.548)
		(end 373.888 -66.548)
		(width 0.1016)
		(layer "F.Cu")
		(net "SMB_SENSOR_STBY_LVC3_SDA")
	)
	(segment
		(start 372.7958 -67.843146)
		(end 372.7958 -69.444108)
		(width 0.1016)
		(layer "F.Cu")
		(net "SMB_SENSOR_STBY_LVC3_SDA")
	)
	(segment
		(start 496.18392 -121.0564)
		(end 495.77244 -121.46788)
		(width 0.10795)
		(layer "F.Cu")
		(net "SMB_SENSOR_STBY_LVC3_SDA")
	)
	(segment
		(start 496.628928 -121.0564)
		(end 496.18392 -121.0564)
		(width 0.10795)
		(layer "F.Cu")
		(net "SMB_SENSOR_STBY_LVC3_SDA")
	)
	(segment
		(start 404.813008 -158.489142)
		(end 451.364858 -158.489142)
		(width 0.10795)
		(layer "F.Cu")
		(net "SMB_SENSOR_STBY_LVC3_SDA")
	)
	(segment
		(start 409.35783 -61.529976)
		(end 408.9908 -61.162946)
		(width 0.10795)
		(layer "F.Cu")
		(net "SMB_SENSOR_STBY_LVC3_SDA")
	)
	(segment
		(start 410.340048 -61.529976)
		(end 409.35783 -61.529976)
		(width 0.10795)
		(layer "F.Cu")
		(net "SMB_SENSOR_STBY_LVC3_SDA")
	)
	(segment
		(start 411.775656 -57.38114)
		(end 411.661356 -57.26684)
		(width 0.10795)
		(layer "F.Cu")
		(net "SMB_SENSOR_STBY_LVC3_SDA")
	)
	(segment
		(start 409.629102 -58.15965)
		(end 411.667706 -58.15965)
		(width 0.10795)
		(layer "F.Cu")
		(net "SMB_SENSOR_STBY_LVC3_SDA")
	)
	(segment
		(start 372.9736 -67.665346)
		(end 372.7958 -67.843146)
		(width 0.1016)
		(layer "F.Cu")
		(net "SMB_SENSOR_STBY_LVC3_SDA")
	)
	(segment
		(start 423.353484 -17.069308)
		(end 423.917872 -16.50492)
		(width 0.10795)
		(layer "F.Cu")
		(net "SMB_SENSOR_STBY_LVC3_SDA")
	)
	(segment
		(start 423.353484 -17.796764)
		(end 423.353484 -17.069308)
		(width 0.10795)
		(layer "F.Cu")
		(net "SMB_SENSOR_STBY_LVC3_SDA")
	)
	(segment
		(start 411.775656 -58.0517)
		(end 411.775656 -57.38114)
		(width 0.10795)
		(layer "F.Cu")
		(net "SMB_SENSOR_STBY_LVC3_SDA")
	)
	(segment
		(start 495.6175 -124.54636)
		(end 495.36858 -124.54636)
		(width 0.10795)
		(layer "F.Cu")
		(net "SMB_SENSOR_STBY_LVC3_SDA")
	)
	(segment
		(start 422.7449 -18.405348)
		(end 423.353484 -17.796764)
		(width 0.10795)
		(layer "F.Cu")
		(net "SMB_SENSOR_STBY_LVC3_SDA")
	)
	(segment
		(start 404.232872 -157.909006)
		(end 404.813008 -158.489142)
		(width 0.10795)
		(layer "F.Cu")
		(net "SMB_SENSOR_STBY_LVC3_SDA")
	)
	(segment
		(start 411.661356 -57.26684)
		(end 411.115256 -57.26684)
		(width 0.10795)
		(layer "F.Cu")
		(net "SMB_SENSOR_STBY_LVC3_SDA")
	)
	(segment
		(start 372.7958 -69.444108)
		(end 372.34495 -69.894958)
		(width 0.1016)
		(layer "F.Cu")
		(net "SMB_SENSOR_STBY_LVC3_SDA")
	)
	(segment
		(start 372.9736 -67.4624)
		(end 372.9736 -67.665346)
		(width 0.1016)
		(layer "F.Cu")
		(net "SMB_SENSOR_STBY_LVC3_SDA")
	)
	(segment
		(start 420.693088 -17.304512)
		(end 421.885364 -17.304512)
		(width 0.10795)
		(layer "F.Cu")
		(net "SMB_SENSOR_STBY_LVC3_SDA")
	)
	(segment
		(start 497.094002 -120.591326)
		(end 496.628928 -121.0564)
		(width 0.10795)
		(layer "F.Cu")
		(net "SMB_SENSOR_STBY_LVC3_SDA")
	)
	(segment
		(start 379.487684 -65.404238)
		(end 379.487684 -65.962276)
		(width 0.1016)
		(layer "F.Cu")
		(net "SMB_SENSOR_STBY_LVC3_SDA")
	)
	(segment
		(start 404.232872 -157.32125)
		(end 404.232872 -157.909006)
		(width 0.10795)
		(layer "F.Cu")
		(net "SMB_SENSOR_STBY_LVC3_SDA")
	)
	(segment
		(start 408.9908 -58.797952)
		(end 409.629102 -58.15965)
		(width 0.10795)
		(layer "F.Cu")
		(net "SMB_SENSOR_STBY_LVC3_SDA")
	)
	(via
		(at 422.7449 -18.405348)
		(size 0.508)
		(drill 0.254)
		(layers "F.Cu" "B.Cu")
		(net "SMB_SENSOR_STBY_LVC3_SDA")
	)
	(via
		(at 497.094002 -120.591326)
		(size 0.508)
		(drill 0.254)
		(layers "F.Cu" "B.Cu")
		(net "SMB_SENSOR_STBY_LVC3_SDA")
	)
	(via
		(at 328.21626 -146.545808)
		(size 0.508)
		(drill 0.254)
		(layers "F.Cu" "B.Cu")
		(net "SMB_SENSOR_STBY_LVC3_SDA")
	)
	(via
		(at 411.775656 -57.38114)
		(size 0.508)
		(drill 0.254)
		(layers "F.Cu" "B.Cu")
		(net "SMB_SENSOR_STBY_LVC3_SDA")
	)
	(via
		(at 346.717112 -139.180316)
		(size 0.508)
		(drill 0.254)
		(layers "F.Cu" "B.Cu")
		(net "SMB_SENSOR_STBY_LVC3_SDA")
	)
	(via
		(at 468.63 -150.0632)
		(size 0.508)
		(drill 0.254)
		(layers "F.Cu" "B.Cu")
		(net "SMB_SENSOR_STBY_LVC3_SDA")
	)
	(via
		(at 476.727774 -5.633974)
		(size 0.508)
		(drill 0.254)
		(layers "F.Cu" "B.Cu")
		(net "SMB_SENSOR_STBY_LVC3_SDA")
	)
	(via
		(at 411.54096 -65.44564)
		(size 0.508)
		(drill 0.254)
		(layers "F.Cu" "B.Cu")
		(net "SMB_SENSOR_STBY_LVC3_SDA")
	)
	(via
		(at 451.7136 -157.2006)
		(size 0.508)
		(drill 0.254)
		(layers "F.Cu" "B.Cu")
		(net "SMB_SENSOR_STBY_LVC3_SDA")
	)
	(via
		(at 379.903228 -64.988694)
		(size 0.508)
		(drill 0.254)
		(layers "F.Cu" "B.Cu")
		(net "SMB_SENSOR_STBY_LVC3_SDA")
	)
	(via
		(at 426.4914 -72.794622)
		(size 0.508)
		(drill 0.254)
		(layers "F.Cu" "B.Cu")
		(net "SMB_SENSOR_STBY_LVC3_SDA")
	)
	(via
		(at 489.16209 -59.36869)
		(size 0.508)
		(drill 0.254)
		(layers "F.Cu" "B.Cu")
		(net "SMB_SENSOR_STBY_LVC3_SDA")
	)
	(via
		(at 459.694788 -6.75259)
		(size 0.508)
		(drill 0.254)
		(layers "F.Cu" "B.Cu")
		(net "SMB_SENSOR_STBY_LVC3_SDA")
	)
	(via
		(at 404.083774 -157.172152)
		(size 0.508)
		(drill 0.254)
		(layers "F.Cu" "B.Cu")
		(net "SMB_SENSOR_STBY_LVC3_SDA")
	)
	(via
		(at 1.728724 -76.796138)
		(size 0.508)
		(drill 0.254)
		(layers "F.Cu" "B.Cu")
		(net "SMB_SENSOR_STBY_LVC3_SDA")
	)
	(segment
		(start 466.172296 -1.51765)
		(end 466.016594 -1.361948)
		(width 0.10795)
		(layer "B.Cu")
		(net "SMB_SENSOR_STBY_LVC3_SDA")
	)
	(segment
		(start 473.067888 -3.884168)
		(end 472.23934 -3.05562)
		(width 0.10795)
		(layer "B.Cu")
		(net "SMB_SENSOR_STBY_LVC3_SDA")
	)
	(segment
		(start 416.109912 -61.179202)
		(end 420.940992 -61.179202)
		(width 0.10795)
		(layer "B.Cu")
		(net "SMB_SENSOR_STBY_LVC3_SDA")
	)
	(segment
		(start 476.849694 -4.236212)
		(end 476.597472 -4.236212)
		(width 0.10795)
		(layer "B.Cu")
		(net "SMB_SENSOR_STBY_LVC3_SDA")
	)
	(segment
		(start 410.972 -63.989712)
		(end 411.624272 -63.33744)
		(width 0.10795)
		(layer "B.Cu")
		(net "SMB_SENSOR_STBY_LVC3_SDA")
	)
	(segment
		(start 426.262292 -72.794622)
		(end 426.4914 -72.794622)
		(width 0.10795)
		(layer "B.Cu")
		(net "SMB_SENSOR_STBY_LVC3_SDA")
	)
	(segment
		(start 424.913298 -70.513956)
		(end 425.79925 -71.399908)
		(width 0.10795)
		(layer "B.Cu")
		(net "SMB_SENSOR_STBY_LVC3_SDA")
	)
	(segment
		(start 425.79925 -71.399908)
		(end 425.79925 -72.33158)
		(width 0.10795)
		(layer "B.Cu")
		(net "SMB_SENSOR_STBY_LVC3_SDA")
	)
	(segment
		(start 336.154014 -137.794492)
		(end 338.937092 -137.794492)
		(width 0.10795)
		(layer "B.Cu")
		(net "SMB_SENSOR_STBY_LVC3_SDA")
	)
	(segment
		(start 461.7466 -4.0132)
		(end 460.621126 -4.0132)
		(width 0.10795)
		(layer "B.Cu")
		(net "SMB_SENSOR_STBY_LVC3_SDA")
	)
	(segment
		(start 329.075796 -139.425426)
		(end 329.61199 -138.889232)
		(width 0.10795)
		(layer "B.Cu")
		(net "SMB_SENSOR_STBY_LVC3_SDA")
	)
	(segment
		(start 413.951674 -63.33744)
		(end 416.109912 -61.179202)
		(width 0.10795)
		(layer "B.Cu")
		(net "SMB_SENSOR_STBY_LVC3_SDA")
	)
	(segment
		(start 468.8078 -1.73355)
		(end 468.5919 -1.51765)
		(width 0.10795)
		(layer "B.Cu")
		(net "SMB_SENSOR_STBY_LVC3_SDA")
	)
	(segment
		(start 476.597472 -4.236212)
		(end 476.245428 -3.884168)
		(width 0.10795)
		(layer "B.Cu")
		(net "SMB_SENSOR_STBY_LVC3_SDA")
	)
	(segment
		(start 411.624272 -63.33744)
		(end 413.951674 -63.33744)
		(width 0.10795)
		(layer "B.Cu")
		(net "SMB_SENSOR_STBY_LVC3_SDA")
	)
	(segment
		(start 411.121098 -64.87922)
		(end 411.121098 -64.779652)
		(width 0.10795)
		(layer "B.Cu")
		(net "SMB_SENSOR_STBY_LVC3_SDA")
	)
	(segment
		(start 462.1784 -3.5814)
		(end 461.7466 -4.0132)
		(width 0.10795)
		(layer "B.Cu")
		(net "SMB_SENSOR_STBY_LVC3_SDA")
	)
	(segment
		(start 459.74 -6.478778)
		(end 459.694788 -6.52399)
		(width 0.10795)
		(layer "B.Cu")
		(net "SMB_SENSOR_STBY_LVC3_SDA")
	)
	(segment
		(start 424.391328 -59.999626)
		(end 425.050966 -60.659264)
		(width 0.10795)
		(layer "B.Cu")
		(net "SMB_SENSOR_STBY_LVC3_SDA")
	)
	(segment
		(start 346.535248 -138.58748)
		(end 346.535248 -138.998452)
		(width 0.10795)
		(layer "B.Cu")
		(net "SMB_SENSOR_STBY_LVC3_SDA")
	)
	(segment
		(start 460.621126 -4.0132)
		(end 459.74 -4.894326)
		(width 0.10795)
		(layer "B.Cu")
		(net "SMB_SENSOR_STBY_LVC3_SDA")
	)
	(segment
		(start 425.524676 -63.255652)
		(end 425.524676 -67.163442)
		(width 0.10795)
		(layer "B.Cu")
		(net "SMB_SENSOR_STBY_LVC3_SDA")
	)
	(segment
		(start 468.5919 -1.51765)
		(end 466.172296 -1.51765)
		(width 0.10795)
		(layer "B.Cu")
		(net "SMB_SENSOR_STBY_LVC3_SDA")
	)
	(segment
		(start 328.611484 -146.545808)
		(end 329.075796 -146.081496)
		(width 0.10795)
		(layer "B.Cu")
		(net "SMB_SENSOR_STBY_LVC3_SDA")
	)
	(segment
		(start 422.120568 -59.999626)
		(end 424.391328 -59.999626)
		(width 0.10795)
		(layer "B.Cu")
		(net "SMB_SENSOR_STBY_LVC3_SDA")
	)
	(segment
		(start 335.059274 -138.889232)
		(end 336.154014 -137.794492)
		(width 0.10795)
		(layer "B.Cu")
		(net "SMB_SENSOR_STBY_LVC3_SDA")
	)
	(segment
		(start 472.23934 -3.05562)
		(end 470.667842 -3.05562)
		(width 0.10795)
		(layer "B.Cu")
		(net "SMB_SENSOR_STBY_LVC3_SDA")
	)
	(segment
		(start 459.694788 -6.52399)
		(end 459.694788 -6.75259)
		(width 0.10795)
		(layer "B.Cu")
		(net "SMB_SENSOR_STBY_LVC3_SDA")
	)
	(segment
		(start 476.727774 -5.633974)
		(end 477.12757 -5.234178)
		(width 0.10795)
		(layer "B.Cu")
		(net "SMB_SENSOR_STBY_LVC3_SDA")
	)
	(segment
		(start 424.710606 -67.977512)
		(end 424.710606 -70.29831)
		(width 0.10795)
		(layer "B.Cu")
		(net "SMB_SENSOR_STBY_LVC3_SDA")
	)
	(segment
		(start 424.913298 -70.501002)
		(end 424.913298 -70.513956)
		(width 0.10795)
		(layer "B.Cu")
		(net "SMB_SENSOR_STBY_LVC3_SDA")
	)
	(segment
		(start 346.250768 -138.303)
		(end 346.535248 -138.58748)
		(width 0.10795)
		(layer "B.Cu")
		(net "SMB_SENSOR_STBY_LVC3_SDA")
	)
	(segment
		(start 476.651828 -5.70992)
		(end 475.827344 -5.70992)
		(width 0.10795)
		(layer "B.Cu")
		(net "SMB_SENSOR_STBY_LVC3_SDA")
	)
	(segment
		(start 425.050966 -62.781942)
		(end 425.524676 -63.255652)
		(width 0.10795)
		(layer "B.Cu")
		(net "SMB_SENSOR_STBY_LVC3_SDA")
	)
	(segment
		(start 476.245428 -3.884168)
		(end 473.067888 -3.884168)
		(width 0.10795)
		(layer "B.Cu")
		(net "SMB_SENSOR_STBY_LVC3_SDA")
	)
	(segment
		(start 425.79925 -72.33158)
		(end 426.262292 -72.794622)
		(width 0.10795)
		(layer "B.Cu")
		(net "SMB_SENSOR_STBY_LVC3_SDA")
	)
	(segment
		(start 329.61199 -138.889232)
		(end 335.059274 -138.889232)
		(width 0.10795)
		(layer "B.Cu")
		(net "SMB_SENSOR_STBY_LVC3_SDA")
	)
	(segment
		(start 477.12757 -5.234178)
		(end 477.12757 -4.514088)
		(width 0.10795)
		(layer "B.Cu")
		(net "SMB_SENSOR_STBY_LVC3_SDA")
	)
	(segment
		(start 459.74 -4.894326)
		(end 459.74 -6.478778)
		(width 0.10795)
		(layer "B.Cu")
		(net "SMB_SENSOR_STBY_LVC3_SDA")
	)
	(segment
		(start 477.12757 -4.514088)
		(end 476.849694 -4.236212)
		(width 0.10795)
		(layer "B.Cu")
		(net "SMB_SENSOR_STBY_LVC3_SDA")
	)
	(segment
		(start 470.667842 -3.05562)
		(end 469.345772 -1.73355)
		(width 0.10795)
		(layer "B.Cu")
		(net "SMB_SENSOR_STBY_LVC3_SDA")
	)
	(segment
		(start 424.710606 -70.29831)
		(end 424.913298 -70.501002)
		(width 0.10795)
		(layer "B.Cu")
		(net "SMB_SENSOR_STBY_LVC3_SDA")
	)
	(segment
		(start 346.535248 -138.998452)
		(end 346.717112 -139.180316)
		(width 0.10795)
		(layer "B.Cu")
		(net "SMB_SENSOR_STBY_LVC3_SDA")
	)
	(segment
		(start 410.972 -64.630554)
		(end 410.972 -63.989712)
		(width 0.10795)
		(layer "B.Cu")
		(net "SMB_SENSOR_STBY_LVC3_SDA")
	)
	(segment
		(start 411.54096 -65.44564)
		(end 411.54096 -65.299082)
		(width 0.10795)
		(layer "B.Cu")
		(net "SMB_SENSOR_STBY_LVC3_SDA")
	)
	(segment
		(start 425.050966 -60.659264)
		(end 425.050966 -62.781942)
		(width 0.10795)
		(layer "B.Cu")
		(net "SMB_SENSOR_STBY_LVC3_SDA")
	)
	(segment
		(start 329.075796 -146.081496)
		(end 329.075796 -139.425426)
		(width 0.10795)
		(layer "B.Cu")
		(net "SMB_SENSOR_STBY_LVC3_SDA")
	)
	(segment
		(start 411.54096 -65.299082)
		(end 411.121098 -64.87922)
		(width 0.10795)
		(layer "B.Cu")
		(net "SMB_SENSOR_STBY_LVC3_SDA")
	)
	(segment
		(start 469.345772 -1.73355)
		(end 468.8078 -1.73355)
		(width 0.10795)
		(layer "B.Cu")
		(net "SMB_SENSOR_STBY_LVC3_SDA")
	)
	(segment
		(start 466.016594 -1.361948)
		(end 462.823052 -1.361948)
		(width 0.10795)
		(layer "B.Cu")
		(net "SMB_SENSOR_STBY_LVC3_SDA")
	)
	(segment
		(start 425.524676 -67.163442)
		(end 424.710606 -67.977512)
		(width 0.10795)
		(layer "B.Cu")
		(net "SMB_SENSOR_STBY_LVC3_SDA")
	)
	(segment
		(start 476.727774 -5.633974)
		(end 476.651828 -5.70992)
		(width 0.10795)
		(layer "B.Cu")
		(net "SMB_SENSOR_STBY_LVC3_SDA")
	)
	(segment
		(start 411.121098 -64.779652)
		(end 410.972 -64.630554)
		(width 0.10795)
		(layer "B.Cu")
		(net "SMB_SENSOR_STBY_LVC3_SDA")
	)
	(segment
		(start 338.937092 -137.794492)
		(end 339.4456 -138.303)
		(width 0.10795)
		(layer "B.Cu")
		(net "SMB_SENSOR_STBY_LVC3_SDA")
	)
	(segment
		(start 328.21626 -146.545808)
		(end 328.611484 -146.545808)
		(width 0.10795)
		(layer "B.Cu")
		(net "SMB_SENSOR_STBY_LVC3_SDA")
	)
	(segment
		(start 420.940992 -61.179202)
		(end 422.120568 -59.999626)
		(width 0.10795)
		(layer "B.Cu")
		(net "SMB_SENSOR_STBY_LVC3_SDA")
	)
	(segment
		(start 462.823052 -1.361948)
		(end 462.1784 -2.0066)
		(width 0.10795)
		(layer "B.Cu")
		(net "SMB_SENSOR_STBY_LVC3_SDA")
	)
	(segment
		(start 339.4456 -138.303)
		(end 346.250768 -138.303)
		(width 0.10795)
		(layer "B.Cu")
		(net "SMB_SENSOR_STBY_LVC3_SDA")
	)
	(segment
		(start 462.1784 -2.0066)
		(end 462.1784 -3.5814)
		(width 0.10795)
		(layer "B.Cu")
		(net "SMB_SENSOR_STBY_LVC3_SDA")
	)
	(segment
		(start 426.4914 -72.794622)
		(end 426.207174 -72.794622)
		(width 0.089408)
		(layer "In2.Cu")
		(net "SMB_SENSOR_STBY_LVC3_SDA")
	)
	(segment
		(start 411.143196 -65.094104)
		(end 411.143196 -58.0136)
		(width 0.089408)
		(layer "In2.Cu")
		(net "SMB_SENSOR_STBY_LVC3_SDA")
	)
	(segment
		(start 479.814636 -62.095126)
		(end 484.96093 -62.095126)
		(width 0.089408)
		(layer "In2.Cu")
		(net "SMB_SENSOR_STBY_LVC3_SDA")
	)
	(segment
		(start 426.072808 -68.75526)
		(end 427.471332 -67.356736)
		(width 0.089408)
		(layer "In2.Cu")
		(net "SMB_SENSOR_STBY_LVC3_SDA")
	)
	(segment
		(start 463.34807 -67.356736)
		(end 463.348324 -67.35699)
		(width 0.089408)
		(layer "In2.Cu")
		(net "SMB_SENSOR_STBY_LVC3_SDA")
	)
	(segment
		(start 427.471332 -67.356736)
		(end 463.34807 -67.356736)
		(width 0.089408)
		(layer "In2.Cu")
		(net "SMB_SENSOR_STBY_LVC3_SDA")
	)
	(segment
		(start 426.072808 -72.660256)
		(end 426.072808 -68.75526)
		(width 0.089408)
		(layer "In2.Cu")
		(net "SMB_SENSOR_STBY_LVC3_SDA")
	)
	(segment
		(start 411.54096 -65.44564)
		(end 411.494732 -65.44564)
		(width 0.089408)
		(layer "In2.Cu")
		(net "SMB_SENSOR_STBY_LVC3_SDA")
	)
	(segment
		(start 463.348324 -67.35699)
		(end 465.58708 -67.35699)
		(width 0.089408)
		(layer "In2.Cu")
		(net "SMB_SENSOR_STBY_LVC3_SDA")
	)
	(segment
		(start 426.207174 -72.794622)
		(end 426.072808 -72.660256)
		(width 0.089408)
		(layer "In2.Cu")
		(net "SMB_SENSOR_STBY_LVC3_SDA")
	)
	(segment
		(start 465.58708 -67.35699)
		(end 465.587334 -67.356736)
		(width 0.089408)
		(layer "In2.Cu")
		(net "SMB_SENSOR_STBY_LVC3_SDA")
	)
	(segment
		(start 474.553026 -67.356736)
		(end 479.814636 -62.095126)
		(width 0.089408)
		(layer "In2.Cu")
		(net "SMB_SENSOR_STBY_LVC3_SDA")
	)
	(segment
		(start 465.587334 -67.356736)
		(end 474.553026 -67.356736)
		(width 0.089408)
		(layer "In2.Cu")
		(net "SMB_SENSOR_STBY_LVC3_SDA")
	)
	(segment
		(start 411.494732 -65.44564)
		(end 411.143196 -65.094104)
		(width 0.089408)
		(layer "In2.Cu")
		(net "SMB_SENSOR_STBY_LVC3_SDA")
	)
	(segment
		(start 411.143196 -58.0136)
		(end 411.775656 -57.38114)
		(width 0.089408)
		(layer "In2.Cu")
		(net "SMB_SENSOR_STBY_LVC3_SDA")
	)
	(segment
		(start 484.96093 -62.095126)
		(end 487.912918 -59.143138)
		(width 0.089408)
		(layer "In2.Cu")
		(net "SMB_SENSOR_STBY_LVC3_SDA")
	)
	(segment
		(start 487.912918 -59.143138)
		(end 488.936538 -59.143138)
		(width 0.089408)
		(layer "In2.Cu")
		(net "SMB_SENSOR_STBY_LVC3_SDA")
	)
	(segment
		(start 488.936538 -59.143138)
		(end 489.16209 -59.36869)
		(width 0.089408)
		(layer "In2.Cu")
		(net "SMB_SENSOR_STBY_LVC3_SDA")
	)
	(segment
		(start 497.094002 -120.763792)
		(end 497.378736 -121.048526)
		(width 0.089408)
		(layer "In4.Cu")
		(net "SMB_SENSOR_STBY_LVC3_SDA")
	)
	(segment
		(start 410.700728 -64.972438)
		(end 410.056838 -65.616328)
		(width 0.089408)
		(layer "In4.Cu")
		(net "SMB_SENSOR_STBY_LVC3_SDA")
	)
	(segment
		(start 452.284592 -157.771592)
		(end 456.486768 -157.771592)
		(width 0.089408)
		(layer "In4.Cu")
		(net "SMB_SENSOR_STBY_LVC3_SDA")
	)
	(segment
		(start 470.76487 -110.623604)
		(end 427.34103 -110.623604)
		(width 0.089408)
		(layer "In4.Cu")
		(net "SMB_SENSOR_STBY_LVC3_SDA")
	)
	(segment
		(start 426.504354 -78.243176)
		(end 425.900088 -77.63891)
		(width 0.089408)
		(layer "In4.Cu")
		(net "SMB_SENSOR_STBY_LVC3_SDA")
	)
	(segment
		(start 395.785848 -62.80404)
		(end 394.359384 -64.230504)
		(width 0.089408)
		(layer "In4.Cu")
		(net "SMB_SENSOR_STBY_LVC3_SDA")
	)
	(segment
		(start 461.11668 -153.14168)
		(end 465.95792 -153.14168)
		(width 0.089408)
		(layer "In4.Cu")
		(net "SMB_SENSOR_STBY_LVC3_SDA")
	)
	(segment
		(start 425.900088 -77.63891)
		(end 425.900088 -73.385934)
		(width 0.089408)
		(layer "In4.Cu")
		(net "SMB_SENSOR_STBY_LVC3_SDA")
	)
	(segment
		(start 499.815612 -113.684812)
		(end 497.567712 -111.436912)
		(width 0.089408)
		(layer "In4.Cu")
		(net "SMB_SENSOR_STBY_LVC3_SDA")
	)
	(segment
		(start 401.317714 -64.820038)
		(end 401.242276 -64.7446)
		(width 0.089408)
		(layer "In4.Cu")
		(net "SMB_SENSOR_STBY_LVC3_SDA")
	)
	(segment
		(start 389.509 -64.482472)
		(end 386.966206 -64.482472)
		(width 0.089408)
		(layer "In4.Cu")
		(net "SMB_SENSOR_STBY_LVC3_SDA")
	)
	(segment
		(start 491.64494 -111.436912)
		(end 491.240064 -111.841788)
		(width 0.089408)
		(layer "In4.Cu")
		(net "SMB_SENSOR_STBY_LVC3_SDA")
	)
	(segment
		(start 380.322074 -65.40754)
		(end 379.903228 -64.988694)
		(width 0.089408)
		(layer "In4.Cu")
		(net "SMB_SENSOR_STBY_LVC3_SDA")
	)
	(segment
		(start 497.567712 -111.436912)
		(end 491.64494 -111.436912)
		(width 0.089408)
		(layer "In4.Cu")
		(net "SMB_SENSOR_STBY_LVC3_SDA")
	)
	(segment
		(start 393.657582 -64.231012)
		(end 393.657328 -64.230758)
		(width 0.089408)
		(layer "In4.Cu")
		(net "SMB_SENSOR_STBY_LVC3_SDA")
	)
	(segment
		(start 386.966206 -64.482472)
		(end 385.154678 -66.294)
		(width 0.089408)
		(layer "In4.Cu")
		(net "SMB_SENSOR_STBY_LVC3_SDA")
	)
	(segment
		(start 393.657328 -64.230758)
		(end 393.49934 -64.230758)
		(width 0.089408)
		(layer "In4.Cu")
		(net "SMB_SENSOR_STBY_LVC3_SDA")
	)
	(segment
		(start 491.240064 -111.841788)
		(end 485.58831 -111.841788)
		(width 0.089408)
		(layer "In4.Cu")
		(net "SMB_SENSOR_STBY_LVC3_SDA")
	)
	(segment
		(start 393.49934 -64.230758)
		(end 393.499086 -64.230504)
		(width 0.089408)
		(layer "In4.Cu")
		(net "SMB_SENSOR_STBY_LVC3_SDA")
	)
	(segment
		(start 407.73985 -65.616328)
		(end 406.598882 -64.47536)
		(width 0.089408)
		(layer "In4.Cu")
		(net "SMB_SENSOR_STBY_LVC3_SDA")
	)
	(segment
		(start 468.63 -150.4696)
		(end 468.63 -150.0632)
		(width 0.089408)
		(layer "In4.Cu")
		(net "SMB_SENSOR_STBY_LVC3_SDA")
	)
	(segment
		(start 398.66062 -63.53048)
		(end 397.79702 -63.53048)
		(width 0.089408)
		(layer "In4.Cu")
		(net "SMB_SENSOR_STBY_LVC3_SDA")
	)
	(segment
		(start 411.54096 -65.44564)
		(end 411.511242 -65.44564)
		(width 0.089408)
		(layer "In4.Cu")
		(net "SMB_SENSOR_STBY_LVC3_SDA")
	)
	(segment
		(start 385.154678 -66.294)
		(end 381.341376 -66.294)
		(width 0.089408)
		(layer "In4.Cu")
		(net "SMB_SENSOR_STBY_LVC3_SDA")
	)
	(segment
		(start 397.07058 -62.80404)
		(end 395.785848 -62.80404)
		(width 0.089408)
		(layer "In4.Cu")
		(net "SMB_SENSOR_STBY_LVC3_SDA")
	)
	(segment
		(start 381.341376 -66.294)
		(end 380.454916 -65.40754)
		(width 0.089408)
		(layer "In4.Cu")
		(net "SMB_SENSOR_STBY_LVC3_SDA")
	)
	(segment
		(start 427.34103 -110.623604)
		(end 426.504354 -109.786928)
		(width 0.089408)
		(layer "In4.Cu")
		(net "SMB_SENSOR_STBY_LVC3_SDA")
	)
	(segment
		(start 394.132562 -64.231012)
		(end 393.657582 -64.231012)
		(width 0.089408)
		(layer "In4.Cu")
		(net "SMB_SENSOR_STBY_LVC3_SDA")
	)
	(segment
		(start 485.58831 -111.841788)
		(end 485.183434 -111.436912)
		(width 0.089408)
		(layer "In4.Cu")
		(net "SMB_SENSOR_STBY_LVC3_SDA")
	)
	(segment
		(start 426.504354 -109.786928)
		(end 426.504354 -78.243176)
		(width 0.089408)
		(layer "In4.Cu")
		(net "SMB_SENSOR_STBY_LVC3_SDA")
	)
	(segment
		(start 471.578178 -111.436912)
		(end 470.76487 -110.623604)
		(width 0.089408)
		(layer "In4.Cu")
		(net "SMB_SENSOR_STBY_LVC3_SDA")
	)
	(segment
		(start 405.877268 -64.47536)
		(end 405.53259 -64.820038)
		(width 0.089408)
		(layer "In4.Cu")
		(net "SMB_SENSOR_STBY_LVC3_SDA")
	)
	(segment
		(start 393.499086 -64.230504)
		(end 389.760968 -64.230504)
		(width 0.089408)
		(layer "In4.Cu")
		(net "SMB_SENSOR_STBY_LVC3_SDA")
	)
	(segment
		(start 425.900088 -73.385934)
		(end 426.4914 -72.794622)
		(width 0.089408)
		(layer "In4.Cu")
		(net "SMB_SENSOR_STBY_LVC3_SDA")
	)
	(segment
		(start 411.511242 -65.44564)
		(end 411.03804 -64.972438)
		(width 0.089408)
		(layer "In4.Cu")
		(net "SMB_SENSOR_STBY_LVC3_SDA")
	)
	(segment
		(start 394.359384 -64.230504)
		(end 394.13307 -64.230504)
		(width 0.089408)
		(layer "In4.Cu")
		(net "SMB_SENSOR_STBY_LVC3_SDA")
	)
	(segment
		(start 411.03804 -64.972438)
		(end 410.700728 -64.972438)
		(width 0.089408)
		(layer "In4.Cu")
		(net "SMB_SENSOR_STBY_LVC3_SDA")
	)
	(segment
		(start 497.58346 -121.048526)
		(end 497.88572 -120.746266)
		(width 0.089408)
		(layer "In4.Cu")
		(net "SMB_SENSOR_STBY_LVC3_SDA")
	)
	(segment
		(start 400.381978 -63.917068)
		(end 399.047208 -63.917068)
		(width 0.089408)
		(layer "In4.Cu")
		(net "SMB_SENSOR_STBY_LVC3_SDA")
	)
	(segment
		(start 497.378736 -121.048526)
		(end 497.58346 -121.048526)
		(width 0.089408)
		(layer "In4.Cu")
		(net "SMB_SENSOR_STBY_LVC3_SDA")
	)
	(segment
		(start 389.760968 -64.230504)
		(end 389.509 -64.482472)
		(width 0.089408)
		(layer "In4.Cu")
		(net "SMB_SENSOR_STBY_LVC3_SDA")
	)
	(segment
		(start 497.094002 -120.591326)
		(end 497.094002 -120.763792)
		(width 0.089408)
		(layer "In4.Cu")
		(net "SMB_SENSOR_STBY_LVC3_SDA")
	)
	(segment
		(start 465.95792 -153.14168)
		(end 468.63 -150.4696)
		(width 0.089408)
		(layer "In4.Cu")
		(net "SMB_SENSOR_STBY_LVC3_SDA")
	)
	(segment
		(start 410.056838 -65.616328)
		(end 407.73985 -65.616328)
		(width 0.089408)
		(layer "In4.Cu")
		(net "SMB_SENSOR_STBY_LVC3_SDA")
	)
	(segment
		(start 406.598882 -64.47536)
		(end 405.877268 -64.47536)
		(width 0.089408)
		(layer "In4.Cu")
		(net "SMB_SENSOR_STBY_LVC3_SDA")
	)
	(segment
		(start 380.454916 -65.40754)
		(end 380.322074 -65.40754)
		(width 0.089408)
		(layer "In4.Cu")
		(net "SMB_SENSOR_STBY_LVC3_SDA")
	)
	(segment
		(start 401.242276 -64.7446)
		(end 401.20951 -64.7446)
		(width 0.089408)
		(layer "In4.Cu")
		(net "SMB_SENSOR_STBY_LVC3_SDA")
	)
	(segment
		(start 394.13307 -64.230504)
		(end 394.132562 -64.231012)
		(width 0.089408)
		(layer "In4.Cu")
		(net "SMB_SENSOR_STBY_LVC3_SDA")
	)
	(segment
		(start 401.20951 -64.7446)
		(end 400.381978 -63.917068)
		(width 0.089408)
		(layer "In4.Cu")
		(net "SMB_SENSOR_STBY_LVC3_SDA")
	)
	(segment
		(start 485.183434 -111.436912)
		(end 471.578178 -111.436912)
		(width 0.089408)
		(layer "In4.Cu")
		(net "SMB_SENSOR_STBY_LVC3_SDA")
	)
	(segment
		(start 497.88572 -119.348758)
		(end 499.815612 -117.418866)
		(width 0.089408)
		(layer "In4.Cu")
		(net "SMB_SENSOR_STBY_LVC3_SDA")
	)
	(segment
		(start 397.79702 -63.53048)
		(end 397.07058 -62.80404)
		(width 0.089408)
		(layer "In4.Cu")
		(net "SMB_SENSOR_STBY_LVC3_SDA")
	)
	(segment
		(start 497.88572 -120.746266)
		(end 497.88572 -119.348758)
		(width 0.089408)
		(layer "In4.Cu")
		(net "SMB_SENSOR_STBY_LVC3_SDA")
	)
	(segment
		(start 399.047208 -63.917068)
		(end 398.66062 -63.53048)
		(width 0.089408)
		(layer "In4.Cu")
		(net "SMB_SENSOR_STBY_LVC3_SDA")
	)
	(segment
		(start 405.53259 -64.820038)
		(end 401.317714 -64.820038)
		(width 0.089408)
		(layer "In4.Cu")
		(net "SMB_SENSOR_STBY_LVC3_SDA")
	)
	(segment
		(start 451.7136 -157.2006)
		(end 452.284592 -157.771592)
		(width 0.089408)
		(layer "In4.Cu")
		(net "SMB_SENSOR_STBY_LVC3_SDA")
	)
	(segment
		(start 499.815612 -117.418866)
		(end 499.815612 -113.684812)
		(width 0.089408)
		(layer "In4.Cu")
		(net "SMB_SENSOR_STBY_LVC3_SDA")
	)
	(segment
		(start 456.486768 -157.771592)
		(end 461.11668 -153.14168)
		(width 0.089408)
		(layer "In4.Cu")
		(net "SMB_SENSOR_STBY_LVC3_SDA")
	)
	(segment
		(start 499.5291 -128.71196)
		(end 499.5291 -130.8989)
		(width 0.089408)
		(layer "In9.Cu")
		(net "SMB_SENSOR_STBY_LVC3_SDA")
	)
	(segment
		(start 480.427792 -14.354048)
		(end 483.193344 -17.1196)
		(width 0.089408)
		(layer "In9.Cu")
		(net "SMB_SENSOR_STBY_LVC3_SDA")
	)
	(segment
		(start 498.32514 -121.430542)
		(end 498.32514 -127.508)
		(width 0.089408)
		(layer "In9.Cu")
		(net "SMB_SENSOR_STBY_LVC3_SDA")
	)
	(segment
		(start 1.52273 -77.99324)
		(end 2.092452 -78.562962)
		(width 0.089408)
		(layer "In9.Cu")
		(net "SMB_SENSOR_STBY_LVC3_SDA")
	)
	(segment
		(start 2.092452 -78.562962)
		(end 2.092452 -86.41715)
		(width 0.089408)
		(layer "In9.Cu")
		(net "SMB_SENSOR_STBY_LVC3_SDA")
	)
	(segment
		(start 166.231062 -142.677896)
		(end 166.835582 -143.282416)
		(width 0.089408)
		(layer "In9.Cu")
		(net "SMB_SENSOR_STBY_LVC3_SDA")
	)
	(segment
		(start 477.078548 -5.2832)
		(end 477.4184 -5.2832)
		(width 0.089408)
		(layer "In9.Cu")
		(net "SMB_SENSOR_STBY_LVC3_SDA")
	)
	(segment
		(start 474.153484 -148.309584)
		(end 471.927682 -148.309584)
		(width 0.089408)
		(layer "In9.Cu")
		(net "SMB_SENSOR_STBY_LVC3_SDA")
	)
	(segment
		(start 2.092452 -86.41715)
		(end 3.575558 -87.900256)
		(width 0.089408)
		(layer "In9.Cu")
		(net "SMB_SENSOR_STBY_LVC3_SDA")
	)
	(segment
		(start 120.896634 -124.50699)
		(end 123.61926 -127.229616)
		(width 0.089408)
		(layer "In9.Cu")
		(net "SMB_SENSOR_STBY_LVC3_SDA")
	)
	(segment
		(start 494.953544 -39.498778)
		(end 494.953544 -41.846754)
		(width 0.089408)
		(layer "In9.Cu")
		(net "SMB_SENSOR_STBY_LVC3_SDA")
	)
	(segment
		(start 10.573004 -93.935804)
		(end 11.56462 -94.92742)
		(width 0.089408)
		(layer "In9.Cu")
		(net "SMB_SENSOR_STBY_LVC3_SDA")
	)
	(segment
		(start 476.727774 -5.633974)
		(end 477.078548 -5.2832)
		(width 0.089408)
		(layer "In9.Cu")
		(net "SMB_SENSOR_STBY_LVC3_SDA")
	)
	(segment
		(start 88.885014 -124.50699)
		(end 120.896634 -124.50699)
		(width 0.089408)
		(layer "In9.Cu")
		(net "SMB_SENSOR_STBY_LVC3_SDA")
	)
	(segment
		(start 492.2647 -28.8163)
		(end 492.2647 -35.6235)
		(width 0.089408)
		(layer "In9.Cu")
		(net "SMB_SENSOR_STBY_LVC3_SDA")
	)
	(segment
		(start 327.47458 -146.69643)
		(end 327.625202 -146.545808)
		(width 0.089408)
		(layer "In9.Cu")
		(net "SMB_SENSOR_STBY_LVC3_SDA")
	)
	(segment
		(start 1.52273 -77.002132)
		(end 1.52273 -77.99324)
		(width 0.089408)
		(layer "In9.Cu")
		(net "SMB_SENSOR_STBY_LVC3_SDA")
	)
	(segment
		(start 486.017062 -17.1196)
		(end 488.835192 -19.93773)
		(width 0.089408)
		(layer "In9.Cu")
		(net "SMB_SENSOR_STBY_LVC3_SDA")
	)
	(segment
		(start 491.062264 -53.593492)
		(end 488.1372 -56.518556)
		(width 0.089408)
		(layer "In9.Cu")
		(net "SMB_SENSOR_STBY_LVC3_SDA")
	)
	(segment
		(start 160.526476 -142.677896)
		(end 166.231062 -142.677896)
		(width 0.089408)
		(layer "In9.Cu")
		(net "SMB_SENSOR_STBY_LVC3_SDA")
	)
	(segment
		(start 477.745044 -4.956556)
		(end 479.304604 -4.956556)
		(width 0.089408)
		(layer "In9.Cu")
		(net "SMB_SENSOR_STBY_LVC3_SDA")
	)
	(segment
		(start 498.32514 -127.508)
		(end 499.5291 -128.71196)
		(width 0.089408)
		(layer "In9.Cu")
		(net "SMB_SENSOR_STBY_LVC3_SDA")
	)
	(segment
		(start 21.451062 -114.161062)
		(end 21.451062 -122.04065)
		(width 0.089408)
		(layer "In9.Cu")
		(net "SMB_SENSOR_STBY_LVC3_SDA")
	)
	(segment
		(start 259.072634 -147.258786)
		(end 260.357874 -145.973546)
		(width 0.089408)
		(layer "In9.Cu")
		(net "SMB_SENSOR_STBY_LVC3_SDA")
	)
	(segment
		(start 497.094002 -120.690386)
		(end 497.532406 -121.12879)
		(width 0.089408)
		(layer "In9.Cu")
		(net "SMB_SENSOR_STBY_LVC3_SDA")
	)
	(segment
		(start 469.017604 -150.450804)
		(end 468.63 -150.0632)
		(width 0.089408)
		(layer "In9.Cu")
		(net "SMB_SENSOR_STBY_LVC3_SDA")
	)
	(segment
		(start 261.833614 -145.973546)
		(end 263.046464 -147.186396)
		(width 0.089408)
		(layer "In9.Cu")
		(net "SMB_SENSOR_STBY_LVC3_SDA")
	)
	(segment
		(start 85.75167 -127.640334)
		(end 88.885014 -124.50699)
		(width 0.089408)
		(layer "In9.Cu")
		(net "SMB_SENSOR_STBY_LVC3_SDA")
	)
	(segment
		(start 263.046464 -147.186396)
		(end 321.6402 -147.186396)
		(width 0.089408)
		(layer "In9.Cu")
		(net "SMB_SENSOR_STBY_LVC3_SDA")
	)
	(segment
		(start 499.5291 -130.8989)
		(end 497.32438 -133.10362)
		(width 0.089408)
		(layer "In9.Cu")
		(net "SMB_SENSOR_STBY_LVC3_SDA")
	)
	(segment
		(start 149.954742 -127.229616)
		(end 151.582374 -128.857248)
		(width 0.089408)
		(layer "In9.Cu")
		(net "SMB_SENSOR_STBY_LVC3_SDA")
	)
	(segment
		(start 151.582374 -128.857248)
		(end 157.116272 -128.857248)
		(width 0.089408)
		(layer "In9.Cu")
		(net "SMB_SENSOR_STBY_LVC3_SDA")
	)
	(segment
		(start 488.1372 -56.518556)
		(end 488.1372 -58.674)
		(width 0.089408)
		(layer "In9.Cu")
		(net "SMB_SENSOR_STBY_LVC3_SDA")
	)
	(segment
		(start 497.532406 -121.12879)
		(end 498.023388 -121.12879)
		(width 0.089408)
		(layer "In9.Cu")
		(net "SMB_SENSOR_STBY_LVC3_SDA")
	)
	(segment
		(start 492.2647 -35.6235)
		(end 494.41735 -37.77615)
		(width 0.089408)
		(layer "In9.Cu")
		(net "SMB_SENSOR_STBY_LVC3_SDA")
	)
	(segment
		(start 11.56462 -102.63759)
		(end 14.02207 -105.09504)
		(width 0.089408)
		(layer "In9.Cu")
		(net "SMB_SENSOR_STBY_LVC3_SDA")
	)
	(segment
		(start 496.67922 -133.10362)
		(end 495.11204 -134.6708)
		(width 0.089408)
		(layer "In9.Cu")
		(net "SMB_SENSOR_STBY_LVC3_SDA")
	)
	(segment
		(start 488.8992 -59.1058)
		(end 489.16209 -59.36869)
		(width 0.089408)
		(layer "In9.Cu")
		(net "SMB_SENSOR_STBY_LVC3_SDA")
	)
	(segment
		(start 479.304604 -4.956556)
		(end 480.427792 -6.079744)
		(width 0.089408)
		(layer "In9.Cu")
		(net "SMB_SENSOR_STBY_LVC3_SDA")
	)
	(segment
		(start 184.559702 -143.282416)
		(end 188.241432 -146.964146)
		(width 0.089408)
		(layer "In9.Cu")
		(net "SMB_SENSOR_STBY_LVC3_SDA")
	)
	(segment
		(start 17.041368 -109.751368)
		(end 21.451062 -114.161062)
		(width 0.089408)
		(layer "In9.Cu")
		(net "SMB_SENSOR_STBY_LVC3_SDA")
	)
	(segment
		(start 487.520234 -142.940278)
		(end 482.691948 -142.940278)
		(width 0.089408)
		(layer "In9.Cu")
		(net "SMB_SENSOR_STBY_LVC3_SDA")
	)
	(segment
		(start 494.41735 -38.962584)
		(end 494.953544 -39.498778)
		(width 0.089408)
		(layer "In9.Cu")
		(net "SMB_SENSOR_STBY_LVC3_SDA")
	)
	(segment
		(start 494.41735 -37.77615)
		(end 494.41735 -38.962584)
		(width 0.089408)
		(layer "In9.Cu")
		(net "SMB_SENSOR_STBY_LVC3_SDA")
	)
	(segment
		(start 323.651118 -148.600668)
		(end 325.555356 -146.69643)
		(width 0.089408)
		(layer "In9.Cu")
		(net "SMB_SENSOR_STBY_LVC3_SDA")
	)
	(segment
		(start 321.6402 -147.186396)
		(end 323.054472 -148.600668)
		(width 0.089408)
		(layer "In9.Cu")
		(net "SMB_SENSOR_STBY_LVC3_SDA")
	)
	(segment
		(start 483.193344 -17.1196)
		(end 486.017062 -17.1196)
		(width 0.089408)
		(layer "In9.Cu")
		(net "SMB_SENSOR_STBY_LVC3_SDA")
	)
	(segment
		(start 488.835192 -22.98573)
		(end 490.035088 -24.185626)
		(width 0.089408)
		(layer "In9.Cu")
		(net "SMB_SENSOR_STBY_LVC3_SDA")
	)
	(segment
		(start 159.131 -130.871976)
		(end 159.131 -141.28242)
		(width 0.089408)
		(layer "In9.Cu")
		(net "SMB_SENSOR_STBY_LVC3_SDA")
	)
	(segment
		(start 497.32438 -133.10362)
		(end 496.67922 -133.10362)
		(width 0.089408)
		(layer "In9.Cu")
		(net "SMB_SENSOR_STBY_LVC3_SDA")
	)
	(segment
		(start 494.953544 -41.846754)
		(end 494.777268 -42.02303)
		(width 0.089408)
		(layer "In9.Cu")
		(net "SMB_SENSOR_STBY_LVC3_SDA")
	)
	(segment
		(start 494.777268 -42.02303)
		(end 494.777268 -50.822098)
		(width 0.089408)
		(layer "In9.Cu")
		(net "SMB_SENSOR_STBY_LVC3_SDA")
	)
	(segment
		(start 325.555356 -146.69643)
		(end 327.47458 -146.69643)
		(width 0.089408)
		(layer "In9.Cu")
		(net "SMB_SENSOR_STBY_LVC3_SDA")
	)
	(segment
		(start 488.569 -59.1058)
		(end 488.8992 -59.1058)
		(width 0.089408)
		(layer "In9.Cu")
		(net "SMB_SENSOR_STBY_LVC3_SDA")
	)
	(segment
		(start 492.005874 -53.593492)
		(end 491.062264 -53.593492)
		(width 0.089408)
		(layer "In9.Cu")
		(net "SMB_SENSOR_STBY_LVC3_SDA")
	)
	(segment
		(start 488.1372 -58.674)
		(end 488.569 -59.1058)
		(width 0.089408)
		(layer "In9.Cu")
		(net "SMB_SENSOR_STBY_LVC3_SDA")
	)
	(segment
		(start 24.861266 -124.379228)
		(end 28.122372 -127.640334)
		(width 0.089408)
		(layer "In9.Cu")
		(net "SMB_SENSOR_STBY_LVC3_SDA")
	)
	(segment
		(start 1.728724 -76.796138)
		(end 1.52273 -77.002132)
		(width 0.089408)
		(layer "In9.Cu")
		(net "SMB_SENSOR_STBY_LVC3_SDA")
	)
	(segment
		(start 14.69644 -105.09504)
		(end 17.041368 -107.439968)
		(width 0.089408)
		(layer "In9.Cu")
		(net "SMB_SENSOR_STBY_LVC3_SDA")
	)
	(segment
		(start 10.573004 -89.772744)
		(end 10.573004 -93.935804)
		(width 0.089408)
		(layer "In9.Cu")
		(net "SMB_SENSOR_STBY_LVC3_SDA")
	)
	(segment
		(start 159.131 -141.28242)
		(end 160.526476 -142.677896)
		(width 0.089408)
		(layer "In9.Cu")
		(net "SMB_SENSOR_STBY_LVC3_SDA")
	)
	(segment
		(start 479.392234 -146.239992)
		(end 476.223076 -146.239992)
		(width 0.089408)
		(layer "In9.Cu")
		(net "SMB_SENSOR_STBY_LVC3_SDA")
	)
	(segment
		(start 28.122372 -127.640334)
		(end 85.75167 -127.640334)
		(width 0.089408)
		(layer "In9.Cu")
		(net "SMB_SENSOR_STBY_LVC3_SDA")
	)
	(segment
		(start 21.451062 -122.04065)
		(end 23.78964 -124.379228)
		(width 0.089408)
		(layer "In9.Cu")
		(net "SMB_SENSOR_STBY_LVC3_SDA")
	)
	(segment
		(start 489.331 -141.129512)
		(end 487.520234 -142.940278)
		(width 0.089408)
		(layer "In9.Cu")
		(net "SMB_SENSOR_STBY_LVC3_SDA")
	)
	(segment
		(start 480.427792 -6.079744)
		(end 480.427792 -14.354048)
		(width 0.089408)
		(layer "In9.Cu")
		(net "SMB_SENSOR_STBY_LVC3_SDA")
	)
	(segment
		(start 123.61926 -127.229616)
		(end 149.954742 -127.229616)
		(width 0.089408)
		(layer "In9.Cu")
		(net "SMB_SENSOR_STBY_LVC3_SDA")
	)
	(segment
		(start 188.241432 -146.964146)
		(end 192.876424 -146.964146)
		(width 0.089408)
		(layer "In9.Cu")
		(net "SMB_SENSOR_STBY_LVC3_SDA")
	)
	(segment
		(start 260.357874 -145.973546)
		(end 261.833614 -145.973546)
		(width 0.089408)
		(layer "In9.Cu")
		(net "SMB_SENSOR_STBY_LVC3_SDA")
	)
	(segment
		(start 193.171064 -147.258786)
		(end 259.072634 -147.258786)
		(width 0.089408)
		(layer "In9.Cu")
		(net "SMB_SENSOR_STBY_LVC3_SDA")
	)
	(segment
		(start 157.116272 -128.857248)
		(end 159.131 -130.871976)
		(width 0.089408)
		(layer "In9.Cu")
		(net "SMB_SENSOR_STBY_LVC3_SDA")
	)
	(segment
		(start 11.56462 -94.92742)
		(end 11.56462 -102.63759)
		(width 0.089408)
		(layer "In9.Cu")
		(net "SMB_SENSOR_STBY_LVC3_SDA")
	)
	(segment
		(start 477.4184 -5.2832)
		(end 477.745044 -4.956556)
		(width 0.089408)
		(layer "In9.Cu")
		(net "SMB_SENSOR_STBY_LVC3_SDA")
	)
	(segment
		(start 476.223076 -146.239992)
		(end 474.153484 -148.309584)
		(width 0.089408)
		(layer "In9.Cu")
		(net "SMB_SENSOR_STBY_LVC3_SDA")
	)
	(segment
		(start 14.02207 -105.09504)
		(end 14.69644 -105.09504)
		(width 0.089408)
		(layer "In9.Cu")
		(net "SMB_SENSOR_STBY_LVC3_SDA")
	)
	(segment
		(start 490.035088 -24.185626)
		(end 490.035088 -26.586688)
		(width 0.089408)
		(layer "In9.Cu")
		(net "SMB_SENSOR_STBY_LVC3_SDA")
	)
	(segment
		(start 17.041368 -107.439968)
		(end 17.041368 -109.751368)
		(width 0.089408)
		(layer "In9.Cu")
		(net "SMB_SENSOR_STBY_LVC3_SDA")
	)
	(segment
		(start 3.575558 -87.900256)
		(end 8.700516 -87.900256)
		(width 0.089408)
		(layer "In9.Cu")
		(net "SMB_SENSOR_STBY_LVC3_SDA")
	)
	(segment
		(start 471.927682 -148.309584)
		(end 469.786462 -150.450804)
		(width 0.089408)
		(layer "In9.Cu")
		(net "SMB_SENSOR_STBY_LVC3_SDA")
	)
	(segment
		(start 8.700516 -87.900256)
		(end 10.573004 -89.772744)
		(width 0.089408)
		(layer "In9.Cu")
		(net "SMB_SENSOR_STBY_LVC3_SDA")
	)
	(segment
		(start 490.035088 -26.586688)
		(end 492.2647 -28.8163)
		(width 0.089408)
		(layer "In9.Cu")
		(net "SMB_SENSOR_STBY_LVC3_SDA")
	)
	(segment
		(start 488.835192 -19.93773)
		(end 488.835192 -22.98573)
		(width 0.089408)
		(layer "In9.Cu")
		(net "SMB_SENSOR_STBY_LVC3_SDA")
	)
	(segment
		(start 498.023388 -121.12879)
		(end 498.32514 -121.430542)
		(width 0.089408)
		(layer "In9.Cu")
		(net "SMB_SENSOR_STBY_LVC3_SDA")
	)
	(segment
		(start 495.11204 -134.6708)
		(end 492.689642 -134.6708)
		(width 0.089408)
		(layer "In9.Cu")
		(net "SMB_SENSOR_STBY_LVC3_SDA")
	)
	(segment
		(start 323.054472 -148.600668)
		(end 323.651118 -148.600668)
		(width 0.089408)
		(layer "In9.Cu")
		(net "SMB_SENSOR_STBY_LVC3_SDA")
	)
	(segment
		(start 469.786462 -150.450804)
		(end 469.017604 -150.450804)
		(width 0.089408)
		(layer "In9.Cu")
		(net "SMB_SENSOR_STBY_LVC3_SDA")
	)
	(segment
		(start 327.625202 -146.545808)
		(end 328.21626 -146.545808)
		(width 0.089408)
		(layer "In9.Cu")
		(net "SMB_SENSOR_STBY_LVC3_SDA")
	)
	(segment
		(start 482.691948 -142.940278)
		(end 479.392234 -146.239992)
		(width 0.089408)
		(layer "In9.Cu")
		(net "SMB_SENSOR_STBY_LVC3_SDA")
	)
	(segment
		(start 166.835582 -143.282416)
		(end 184.559702 -143.282416)
		(width 0.089408)
		(layer "In9.Cu")
		(net "SMB_SENSOR_STBY_LVC3_SDA")
	)
	(segment
		(start 192.876424 -146.964146)
		(end 193.171064 -147.258786)
		(width 0.089408)
		(layer "In9.Cu")
		(net "SMB_SENSOR_STBY_LVC3_SDA")
	)
	(segment
		(start 23.78964 -124.379228)
		(end 24.861266 -124.379228)
		(width 0.089408)
		(layer "In9.Cu")
		(net "SMB_SENSOR_STBY_LVC3_SDA")
	)
	(segment
		(start 497.094002 -120.591326)
		(end 497.094002 -120.690386)
		(width 0.089408)
		(layer "In9.Cu")
		(net "SMB_SENSOR_STBY_LVC3_SDA")
	)
	(segment
		(start 492.689642 -134.6708)
		(end 489.331 -138.029442)
		(width 0.089408)
		(layer "In9.Cu")
		(net "SMB_SENSOR_STBY_LVC3_SDA")
	)
	(segment
		(start 494.777268 -50.822098)
		(end 492.005874 -53.593492)
		(width 0.089408)
		(layer "In9.Cu")
		(net "SMB_SENSOR_STBY_LVC3_SDA")
	)
	(segment
		(start 489.331 -138.029442)
		(end 489.331 -141.129512)
		(width 0.089408)
		(layer "In9.Cu")
		(net "SMB_SENSOR_STBY_LVC3_SDA")
	)
	(segment
		(start 388.248652 -149.521672)
		(end 389.667496 -150.940516)
		(width 0.089408)
		(layer "In11.Cu")
		(net "SMB_SENSOR_STBY_LVC3_SDA")
	)
	(segment
		(start 458.17409 -8.273288)
		(end 459.694788 -6.75259)
		(width 0.089408)
		(layer "In11.Cu")
		(net "SMB_SENSOR_STBY_LVC3_SDA")
	)
	(segment
		(start 366.886998 -147.425156)
		(end 369.078002 -147.425156)
		(width 0.089408)
		(layer "In11.Cu")
		(net "SMB_SENSOR_STBY_LVC3_SDA")
	)
	(segment
		(start 399.04924 -153.439114)
		(end 400.220688 -154.610562)
		(width 0.089408)
		(layer "In11.Cu")
		(net "SMB_SENSOR_STBY_LVC3_SDA")
	)
	(segment
		(start 423.145204 -17.573244)
		(end 423.756074 -16.962374)
		(width 0.089408)
		(layer "In11.Cu")
		(net "SMB_SENSOR_STBY_LVC3_SDA")
	)
	(segment
		(start 386.675376 -149.521672)
		(end 388.248652 -149.521672)
		(width 0.089408)
		(layer "In11.Cu")
		(net "SMB_SENSOR_STBY_LVC3_SDA")
	)
	(segment
		(start 395.592808 -151.610314)
		(end 397.663162 -151.610314)
		(width 0.089408)
		(layer "In11.Cu")
		(net "SMB_SENSOR_STBY_LVC3_SDA")
	)
	(segment
		(start 457.390246 -8.273288)
		(end 458.17409 -8.273288)
		(width 0.089408)
		(layer "In11.Cu")
		(net "SMB_SENSOR_STBY_LVC3_SDA")
	)
	(segment
		(start 422.7449 -18.405348)
		(end 422.7449 -18.336514)
		(width 0.089408)
		(layer "In11.Cu")
		(net "SMB_SENSOR_STBY_LVC3_SDA")
	)
	(segment
		(start 432.590956 -16.77416)
		(end 438.853834 -16.77416)
		(width 0.089408)
		(layer "In11.Cu")
		(net "SMB_SENSOR_STBY_LVC3_SDA")
	)
	(segment
		(start 443.702948 -16.599408)
		(end 444.627 -15.675356)
		(width 0.089408)
		(layer "In11.Cu")
		(net "SMB_SENSOR_STBY_LVC3_SDA")
	)
	(segment
		(start 378.8791 -147.9677)
		(end 385.121404 -147.9677)
		(width 0.089408)
		(layer "In11.Cu")
		(net "SMB_SENSOR_STBY_LVC3_SDA")
	)
	(segment
		(start 438.853834 -16.77416)
		(end 439.028586 -16.599408)
		(width 0.089408)
		(layer "In11.Cu")
		(net "SMB_SENSOR_STBY_LVC3_SDA")
	)
	(segment
		(start 456.894946 -8.273288)
		(end 456.897486 -8.270748)
		(width 0.089408)
		(layer "In11.Cu")
		(net "SMB_SENSOR_STBY_LVC3_SDA")
	)
	(segment
		(start 400.220688 -154.610562)
		(end 402.527262 -154.610562)
		(width 0.089408)
		(layer "In11.Cu")
		(net "SMB_SENSOR_STBY_LVC3_SDA")
	)
	(segment
		(start 378.195332 -147.283932)
		(end 378.8791 -147.9677)
		(width 0.089408)
		(layer "In11.Cu")
		(net "SMB_SENSOR_STBY_LVC3_SDA")
	)
	(segment
		(start 389.667496 -150.940516)
		(end 394.92301 -150.940516)
		(width 0.089408)
		(layer "In11.Cu")
		(net "SMB_SENSOR_STBY_LVC3_SDA")
	)
	(segment
		(start 361.390184 -141.115542)
		(end 362.71073 -142.436088)
		(width 0.089408)
		(layer "In11.Cu")
		(net "SMB_SENSOR_STBY_LVC3_SDA")
	)
	(segment
		(start 453.233028 -9.766554)
		(end 453.233028 -9.63295)
		(width 0.089408)
		(layer "In11.Cu")
		(net "SMB_SENSOR_STBY_LVC3_SDA")
	)
	(segment
		(start 362.71073 -143.248888)
		(end 366.886998 -147.425156)
		(width 0.089408)
		(layer "In11.Cu")
		(net "SMB_SENSOR_STBY_LVC3_SDA")
	)
	(segment
		(start 397.663162 -151.610314)
		(end 398.221708 -152.16886)
		(width 0.089408)
		(layer "In11.Cu")
		(net "SMB_SENSOR_STBY_LVC3_SDA")
	)
	(segment
		(start 454.59269 -8.273288)
		(end 456.894946 -8.273288)
		(width 0.089408)
		(layer "In11.Cu")
		(net "SMB_SENSOR_STBY_LVC3_SDA")
	)
	(segment
		(start 456.897486 -8.270748)
		(end 457.387706 -8.270748)
		(width 0.089408)
		(layer "In11.Cu")
		(net "SMB_SENSOR_STBY_LVC3_SDA")
	)
	(segment
		(start 362.71073 -142.436088)
		(end 362.71073 -143.248888)
		(width 0.089408)
		(layer "In11.Cu")
		(net "SMB_SENSOR_STBY_LVC3_SDA")
	)
	(segment
		(start 369.078002 -147.425156)
		(end 370.452142 -146.051016)
		(width 0.089408)
		(layer "In11.Cu")
		(net "SMB_SENSOR_STBY_LVC3_SDA")
	)
	(segment
		(start 404.308818 -156.947108)
		(end 404.083774 -157.172152)
		(width 0.089408)
		(layer "In11.Cu")
		(net "SMB_SENSOR_STBY_LVC3_SDA")
	)
	(segment
		(start 457.387706 -8.270748)
		(end 457.390246 -8.273288)
		(width 0.089408)
		(layer "In11.Cu")
		(net "SMB_SENSOR_STBY_LVC3_SDA")
	)
	(segment
		(start 394.92301 -150.940516)
		(end 395.592808 -151.610314)
		(width 0.089408)
		(layer "In11.Cu")
		(net "SMB_SENSOR_STBY_LVC3_SDA")
	)
	(segment
		(start 370.900452 -146.051016)
		(end 372.133368 -147.283932)
		(width 0.089408)
		(layer "In11.Cu")
		(net "SMB_SENSOR_STBY_LVC3_SDA")
	)
	(segment
		(start 423.145204 -17.93621)
		(end 423.145204 -17.573244)
		(width 0.089408)
		(layer "In11.Cu")
		(net "SMB_SENSOR_STBY_LVC3_SDA")
	)
	(segment
		(start 450.065648 -11.0236)
		(end 451.975982 -11.0236)
		(width 0.089408)
		(layer "In11.Cu")
		(net "SMB_SENSOR_STBY_LVC3_SDA")
	)
	(segment
		(start 346.717112 -139.180316)
		(end 346.717112 -138.852656)
		(width 0.089408)
		(layer "In11.Cu")
		(net "SMB_SENSOR_STBY_LVC3_SDA")
	)
	(segment
		(start 359.27411 -140.351764)
		(end 360.037888 -141.115542)
		(width 0.089408)
		(layer "In11.Cu")
		(net "SMB_SENSOR_STBY_LVC3_SDA")
	)
	(segment
		(start 370.452142 -146.051016)
		(end 370.900452 -146.051016)
		(width 0.089408)
		(layer "In11.Cu")
		(net "SMB_SENSOR_STBY_LVC3_SDA")
	)
	(segment
		(start 398.681448 -153.439114)
		(end 399.04924 -153.439114)
		(width 0.089408)
		(layer "In11.Cu")
		(net "SMB_SENSOR_STBY_LVC3_SDA")
	)
	(segment
		(start 360.037888 -141.115542)
		(end 361.390184 -141.115542)
		(width 0.089408)
		(layer "In11.Cu")
		(net "SMB_SENSOR_STBY_LVC3_SDA")
	)
	(segment
		(start 404.308818 -156.392118)
		(end 404.308818 -156.947108)
		(width 0.089408)
		(layer "In11.Cu")
		(net "SMB_SENSOR_STBY_LVC3_SDA")
	)
	(segment
		(start 453.233028 -9.63295)
		(end 454.59269 -8.273288)
		(width 0.089408)
		(layer "In11.Cu")
		(net "SMB_SENSOR_STBY_LVC3_SDA")
	)
	(segment
		(start 422.7449 -18.336514)
		(end 423.145204 -17.93621)
		(width 0.089408)
		(layer "In11.Cu")
		(net "SMB_SENSOR_STBY_LVC3_SDA")
	)
	(segment
		(start 444.627 -15.675356)
		(end 445.413892 -15.675356)
		(width 0.089408)
		(layer "In11.Cu")
		(net "SMB_SENSOR_STBY_LVC3_SDA")
	)
	(segment
		(start 346.717112 -138.852656)
		(end 346.80652 -138.763248)
		(width 0.089408)
		(layer "In11.Cu")
		(net "SMB_SENSOR_STBY_LVC3_SDA")
	)
	(segment
		(start 439.028586 -16.599408)
		(end 443.702948 -16.599408)
		(width 0.089408)
		(layer "In11.Cu")
		(net "SMB_SENSOR_STBY_LVC3_SDA")
	)
	(segment
		(start 423.756074 -16.962374)
		(end 432.402742 -16.962374)
		(width 0.089408)
		(layer "In11.Cu")
		(net "SMB_SENSOR_STBY_LVC3_SDA")
	)
	(segment
		(start 352.799142 -140.351764)
		(end 359.27411 -140.351764)
		(width 0.089408)
		(layer "In11.Cu")
		(net "SMB_SENSOR_STBY_LVC3_SDA")
	)
	(segment
		(start 346.80652 -138.763248)
		(end 351.210626 -138.763248)
		(width 0.089408)
		(layer "In11.Cu")
		(net "SMB_SENSOR_STBY_LVC3_SDA")
	)
	(segment
		(start 402.527262 -154.610562)
		(end 404.308818 -156.392118)
		(width 0.089408)
		(layer "In11.Cu")
		(net "SMB_SENSOR_STBY_LVC3_SDA")
	)
	(segment
		(start 351.210626 -138.763248)
		(end 352.799142 -140.351764)
		(width 0.089408)
		(layer "In11.Cu")
		(net "SMB_SENSOR_STBY_LVC3_SDA")
	)
	(segment
		(start 432.402742 -16.962374)
		(end 432.590956 -16.77416)
		(width 0.089408)
		(layer "In11.Cu")
		(net "SMB_SENSOR_STBY_LVC3_SDA")
	)
	(segment
		(start 398.221708 -152.16886)
		(end 398.221708 -152.979374)
		(width 0.089408)
		(layer "In11.Cu")
		(net "SMB_SENSOR_STBY_LVC3_SDA")
	)
	(segment
		(start 385.121404 -147.9677)
		(end 386.675376 -149.521672)
		(width 0.089408)
		(layer "In11.Cu")
		(net "SMB_SENSOR_STBY_LVC3_SDA")
	)
	(segment
		(start 398.221708 -152.979374)
		(end 398.681448 -153.439114)
		(width 0.089408)
		(layer "In11.Cu")
		(net "SMB_SENSOR_STBY_LVC3_SDA")
	)
	(segment
		(start 445.413892 -15.675356)
		(end 450.065648 -11.0236)
		(width 0.089408)
		(layer "In11.Cu")
		(net "SMB_SENSOR_STBY_LVC3_SDA")
	)
	(segment
		(start 372.133368 -147.283932)
		(end 378.195332 -147.283932)
		(width 0.089408)
		(layer "In11.Cu")
		(net "SMB_SENSOR_STBY_LVC3_SDA")
	)
	(segment
		(start 451.975982 -11.0236)
		(end 453.233028 -9.766554)
		(width 0.089408)
		(layer "In11.Cu")
		(net "SMB_SENSOR_STBY_LVC3_SDA")
	)
	(segment
		(start 409.701492 -58.42)
		(end 409.25115 -58.870342)
		(width 0.10795)
		(layer "F.Cu")
		(net "SMB_SENSOR_STBY_LVC3_SCL")
	)
	(segment
		(start 411.861 -58.42)
		(end 409.701492 -58.42)
		(width 0.10795)
		(layer "F.Cu")
		(net "SMB_SENSOR_STBY_LVC3_SCL")
	)
	(segment
		(start 411.115256 -56.50484)
		(end 411.538928 -56.50484)
		(width 0.10795)
		(layer "F.Cu")
		(net "SMB_SENSOR_STBY_LVC3_SCL")
	)
	(segment
		(start 404.920958 -158.228792)
		(end 450.964808 -158.228792)
		(width 0.10795)
		(layer "F.Cu")
		(net "SMB_SENSOR_STBY_LVC3_SCL")
	)
	(segment
		(start 422.7449 -17.770348)
		(end 422.044114 -17.069562)
		(width 0.10795)
		(layer "F.Cu")
		(net "SMB_SENSOR_STBY_LVC3_SCL")
	)
	(segment
		(start 424.648376 -16.26997)
		(end 427.537372 -13.380974)
		(width 0.10795)
		(layer "F.Cu")
		(net "SMB_SENSOR_STBY_LVC3_SCL")
	)
	(segment
		(start 422.7449 -17.770348)
		(end 423.118534 -17.396714)
		(width 0.10795)
		(layer "F.Cu")
		(net "SMB_SENSOR_STBY_LVC3_SCL")
	)
	(segment
		(start 495.554 -125.03912)
		(end 495.0587 -125.03912)
		(width 0.10795)
		(layer "F.Cu")
		(net "SMB_SENSOR_STBY_LVC3_SCL")
	)
	(segment
		(start 372.7704 -67.564254)
		(end 372.34495 -67.989704)
		(width 0.1016)
		(layer "F.Cu")
		(net "SMB_SENSOR_STBY_LVC3_SCL")
	)
	(segment
		(start 430.154588 -13.380974)
		(end 430.51984 -13.015722)
		(width 0.10795)
		(layer "F.Cu")
		(net "SMB_SENSOR_STBY_LVC3_SCL")
	)
	(segment
		(start 411.1752 -60.96)
		(end 412.624016 -62.408816)
		(width 0.10795)
		(layer "F.Cu")
		(net "SMB_SENSOR_STBY_LVC3_SCL")
	)
	(segment
		(start 1.27 -76.492862)
		(end 0.966724 -76.796138)
		(width 0.10795)
		(layer "F.Cu")
		(net "SMB_SENSOR_STBY_LVC3_SCL")
	)
	(segment
		(start 413.656272 -63.0301)
		(end 414.556448 -63.0301)
		(width 0.10795)
		(layer "F.Cu")
		(net "SMB_SENSOR_STBY_LVC3_SCL")
	)
	(segment
		(start 423.118534 -17.396714)
		(end 423.118534 -16.971772)
		(width 0.10795)
		(layer "F.Cu")
		(net "SMB_SENSOR_STBY_LVC3_SCL")
	)
	(segment
		(start 430.51984 -13.015722)
		(end 430.51984 -11.7856)
		(width 0.10795)
		(layer "F.Cu")
		(net "SMB_SENSOR_STBY_LVC3_SCL")
	)
	(segment
		(start 451.231 -157.9626)
		(end 451.231 -157.7848)
		(width 0.10795)
		(layer "F.Cu")
		(net "SMB_SENSOR_STBY_LVC3_SCL")
	)
	(segment
		(start 409.3591 -60.96)
		(end 411.1752 -60.96)
		(width 0.10795)
		(layer "F.Cu")
		(net "SMB_SENSOR_STBY_LVC3_SCL")
	)
	(segment
		(start 409.25115 -58.870342)
		(end 409.25115 -60.85205)
		(width 0.10795)
		(layer "F.Cu")
		(net "SMB_SENSOR_STBY_LVC3_SCL")
	)
	(segment
		(start 379.236478 -64.934846)
		(end 379.236478 -65.835022)
		(width 0.1016)
		(layer "F.Cu")
		(net "SMB_SENSOR_STBY_LVC3_SCL")
	)
	(segment
		(start 412.2166 -57.182512)
		(end 412.2166 -58.0644)
		(width 0.10795)
		(layer "F.Cu")
		(net "SMB_SENSOR_STBY_LVC3_SCL")
	)
	(segment
		(start 427.537372 -13.380974)
		(end 430.154588 -13.380974)
		(width 0.10795)
		(layer "F.Cu")
		(net "SMB_SENSOR_STBY_LVC3_SCL")
	)
	(segment
		(start 412.2166 -58.0644)
		(end 411.861 -58.42)
		(width 0.10795)
		(layer "F.Cu")
		(net "SMB_SENSOR_STBY_LVC3_SCL")
	)
	(segment
		(start 411.538928 -56.50484)
		(end 411.775656 -56.741568)
		(width 0.10795)
		(layer "F.Cu")
		(net "SMB_SENSOR_STBY_LVC3_SCL")
	)
	(segment
		(start 497.131848 -121.798334)
		(end 496.631214 -121.2977)
		(width 0.10795)
		(layer "F.Cu")
		(net "SMB_SENSOR_STBY_LVC3_SCL")
	)
	(segment
		(start 496.631214 -121.2977)
		(end 496.28298 -121.2977)
		(width 0.10795)
		(layer "F.Cu")
		(net "SMB_SENSOR_STBY_LVC3_SCL")
	)
	(segment
		(start 404.753826 -157.158944)
		(end 404.493222 -157.419548)
		(width 0.10795)
		(layer "F.Cu")
		(net "SMB_SENSOR_STBY_LVC3_SCL")
	)
	(segment
		(start 423.820336 -16.26997)
		(end 424.648376 -16.26997)
		(width 0.10795)
		(layer "F.Cu")
		(net "SMB_SENSOR_STBY_LVC3_SCL")
	)
	(segment
		(start 378.7775 -66.294)
		(end 373.761 -66.294)
		(width 0.1016)
		(layer "F.Cu")
		(net "SMB_SENSOR_STBY_LVC3_SCL")
	)
	(segment
		(start 373.761 -66.294)
		(end 372.7704 -67.2846)
		(width 0.1016)
		(layer "F.Cu")
		(net "SMB_SENSOR_STBY_LVC3_SCL")
	)
	(segment
		(start 372.7704 -67.2846)
		(end 372.7704 -67.564254)
		(width 0.1016)
		(layer "F.Cu")
		(net "SMB_SENSOR_STBY_LVC3_SCL")
	)
	(segment
		(start 420.089838 -17.069562)
		(end 419.3032 -17.8562)
		(width 0.10795)
		(layer "F.Cu")
		(net "SMB_SENSOR_STBY_LVC3_SCL")
	)
	(segment
		(start 413.034988 -62.408816)
		(end 413.656272 -63.0301)
		(width 0.10795)
		(layer "F.Cu")
		(net "SMB_SENSOR_STBY_LVC3_SCL")
	)
	(segment
		(start 496.28298 -121.2977)
		(end 496.01628 -121.5644)
		(width 0.10795)
		(layer "F.Cu")
		(net "SMB_SENSOR_STBY_LVC3_SCL")
	)
	(segment
		(start 496.01628 -121.5644)
		(end 496.01628 -124.57684)
		(width 0.10795)
		(layer "F.Cu")
		(net "SMB_SENSOR_STBY_LVC3_SCL")
	)
	(segment
		(start 450.964808 -158.228792)
		(end 451.231 -157.9626)
		(width 0.10795)
		(layer "F.Cu")
		(net "SMB_SENSOR_STBY_LVC3_SCL")
	)
	(segment
		(start 404.493222 -157.419548)
		(end 404.493222 -157.801056)
		(width 0.10795)
		(layer "F.Cu")
		(net "SMB_SENSOR_STBY_LVC3_SCL")
	)
	(segment
		(start 372.34495 -67.989704)
		(end 372.34495 -68.295012)
		(width 0.1016)
		(layer "F.Cu")
		(net "SMB_SENSOR_STBY_LVC3_SCL")
	)
	(segment
		(start 379.236478 -65.835022)
		(end 378.7775 -66.294)
		(width 0.1016)
		(layer "F.Cu")
		(net "SMB_SENSOR_STBY_LVC3_SCL")
	)
	(segment
		(start 404.493222 -157.801056)
		(end 404.920958 -158.228792)
		(width 0.10795)
		(layer "F.Cu")
		(net "SMB_SENSOR_STBY_LVC3_SCL")
	)
	(segment
		(start 422.044114 -17.069562)
		(end 420.089838 -17.069562)
		(width 0.10795)
		(layer "F.Cu")
		(net "SMB_SENSOR_STBY_LVC3_SCL")
	)
	(segment
		(start 409.25115 -60.85205)
		(end 409.3591 -60.96)
		(width 0.10795)
		(layer "F.Cu")
		(net "SMB_SENSOR_STBY_LVC3_SCL")
	)
	(segment
		(start 1.27 -75.946)
		(end 1.27 -76.492862)
		(width 0.10795)
		(layer "F.Cu")
		(net "SMB_SENSOR_STBY_LVC3_SCL")
	)
	(segment
		(start 412.624016 -62.408816)
		(end 413.034988 -62.408816)
		(width 0.10795)
		(layer "F.Cu")
		(net "SMB_SENSOR_STBY_LVC3_SCL")
	)
	(segment
		(start 423.118534 -16.971772)
		(end 423.820336 -16.26997)
		(width 0.10795)
		(layer "F.Cu")
		(net "SMB_SENSOR_STBY_LVC3_SCL")
	)
	(segment
		(start 496.01628 -124.57684)
		(end 495.554 -125.03912)
		(width 0.10795)
		(layer "F.Cu")
		(net "SMB_SENSOR_STBY_LVC3_SCL")
	)
	(segment
		(start 379.272546 -64.898778)
		(end 379.236478 -64.934846)
		(width 0.1016)
		(layer "F.Cu")
		(net "SMB_SENSOR_STBY_LVC3_SCL")
	)
	(segment
		(start 411.775656 -56.741568)
		(end 412.2166 -57.182512)
		(width 0.10795)
		(layer "F.Cu")
		(net "SMB_SENSOR_STBY_LVC3_SCL")
	)
	(via
		(at 476.705168 -4.689094)
		(size 0.508)
		(drill 0.254)
		(layers "F.Cu" "B.Cu")
		(net "SMB_SENSOR_STBY_LVC3_SCL")
	)
	(via
		(at 469.6206 -150.0505)
		(size 0.508)
		(drill 0.254)
		(layers "F.Cu" "B.Cu")
		(net "SMB_SENSOR_STBY_LVC3_SCL")
	)
	(via
		(at 422.7449 -17.770348)
		(size 0.508)
		(drill 0.254)
		(layers "F.Cu" "B.Cu")
		(net "SMB_SENSOR_STBY_LVC3_SCL")
	)
	(via
		(at 327.734168 -147.056348)
		(size 0.508)
		(drill 0.254)
		(layers "F.Cu" "B.Cu")
		(net "SMB_SENSOR_STBY_LVC3_SCL")
	)
	(via
		(at 411.775656 -56.741568)
		(size 0.508)
		(drill 0.254)
		(layers "F.Cu" "B.Cu")
		(net "SMB_SENSOR_STBY_LVC3_SCL")
	)
	(via
		(at 0.966724 -76.796138)
		(size 0.508)
		(drill 0.254)
		(layers "F.Cu" "B.Cu")
		(net "SMB_SENSOR_STBY_LVC3_SCL")
	)
	(via
		(at 459.010258 -6.837172)
		(size 0.508)
		(drill 0.254)
		(layers "F.Cu" "B.Cu")
		(net "SMB_SENSOR_STBY_LVC3_SCL")
	)
	(via
		(at 489.2294 -58.7248)
		(size 0.508)
		(drill 0.254)
		(layers "F.Cu" "B.Cu")
		(net "SMB_SENSOR_STBY_LVC3_SCL")
	)
	(via
		(at 346.082112 -139.180316)
		(size 0.508)
		(drill 0.254)
		(layers "F.Cu" "B.Cu")
		(net "SMB_SENSOR_STBY_LVC3_SCL")
	)
	(via
		(at 426.4914 -73.533)
		(size 0.508)
		(drill 0.254)
		(layers "F.Cu" "B.Cu")
		(net "SMB_SENSOR_STBY_LVC3_SCL")
	)
	(via
		(at 379.272546 -64.898778)
		(size 0.508)
		(drill 0.254)
		(layers "F.Cu" "B.Cu")
		(net "SMB_SENSOR_STBY_LVC3_SCL")
	)
	(via
		(at 404.753826 -157.158944)
		(size 0.508)
		(drill 0.254)
		(layers "F.Cu" "B.Cu")
		(net "SMB_SENSOR_STBY_LVC3_SCL")
	)
	(via
		(at 451.231 -157.7848)
		(size 0.508)
		(drill 0.254)
		(layers "F.Cu" "B.Cu")
		(net "SMB_SENSOR_STBY_LVC3_SCL")
	)
	(via
		(at 497.131848 -121.798334)
		(size 0.508)
		(drill 0.254)
		(layers "F.Cu" "B.Cu")
		(net "SMB_SENSOR_STBY_LVC3_SCL")
	)
	(via
		(at 411.5435 -64.704214)
		(size 0.508)
		(drill 0.254)
		(layers "F.Cu" "B.Cu")
		(net "SMB_SENSOR_STBY_LVC3_SCL")
	)
	(segment
		(start 346.082112 -139.180316)
		(end 346.291408 -138.97102)
		(width 0.10795)
		(layer "B.Cu")
		(net "SMB_SENSOR_STBY_LVC3_SCL")
	)
	(segment
		(start 424.352974 -60.293758)
		(end 422.159684 -60.293758)
		(width 0.10795)
		(layer "B.Cu")
		(net "SMB_SENSOR_STBY_LVC3_SCL")
	)
	(segment
		(start 466.0646 -1.7526)
		(end 468.4776 -1.7526)
		(width 0.10795)
		(layer "B.Cu")
		(net "SMB_SENSOR_STBY_LVC3_SCL")
	)
	(segment
		(start 476.573342 -4.82092)
		(end 475.827344 -4.82092)
		(width 0.10795)
		(layer "B.Cu")
		(net "SMB_SENSOR_STBY_LVC3_SCL")
	)
	(segment
		(start 460.121 -7.0866)
		(end 460.121 -4.881626)
		(width 0.10795)
		(layer "B.Cu")
		(net "SMB_SENSOR_STBY_LVC3_SCL")
	)
	(segment
		(start 335.167224 -139.149582)
		(end 329.71994 -139.149582)
		(width 0.10795)
		(layer "B.Cu")
		(net "SMB_SENSOR_STBY_LVC3_SCL")
	)
	(segment
		(start 411.560772 -64.00419)
		(end 411.560772 -64.686942)
		(width 0.10795)
		(layer "B.Cu")
		(net "SMB_SENSOR_STBY_LVC3_SCL")
	)
	(segment
		(start 336.261964 -138.054842)
		(end 335.167224 -139.149582)
		(width 0.10795)
		(layer "B.Cu")
		(net "SMB_SENSOR_STBY_LVC3_SCL")
	)
	(segment
		(start 462.42605 -3.70205)
		(end 462.42605 -2.13995)
		(width 0.10795)
		(layer "B.Cu")
		(net "SMB_SENSOR_STBY_LVC3_SCL")
	)
	(segment
		(start 415.982912 -61.67755)
		(end 414.0581 -63.602362)
		(width 0.10795)
		(layer "B.Cu")
		(net "SMB_SENSOR_STBY_LVC3_SCL")
	)
	(segment
		(start 468.7062 -1.9812)
		(end 469.174068 -1.9812)
		(width 0.10795)
		(layer "B.Cu")
		(net "SMB_SENSOR_STBY_LVC3_SCL")
	)
	(segment
		(start 462.42605 -2.13995)
		(end 462.943702 -1.622298)
		(width 0.10795)
		(layer "B.Cu")
		(net "SMB_SENSOR_STBY_LVC3_SCL")
	)
	(segment
		(start 472.934538 -4.144518)
		(end 476.160592 -4.144518)
		(width 0.10795)
		(layer "B.Cu")
		(net "SMB_SENSOR_STBY_LVC3_SCL")
	)
	(segment
		(start 462.943702 -1.622298)
		(end 465.934298 -1.622298)
		(width 0.10795)
		(layer "B.Cu")
		(net "SMB_SENSOR_STBY_LVC3_SCL")
	)
	(segment
		(start 424.475656 -67.879976)
		(end 425.289726 -67.065906)
		(width 0.10795)
		(layer "B.Cu")
		(net "SMB_SENSOR_STBY_LVC3_SCL")
	)
	(segment
		(start 426.4914 -73.475342)
		(end 425.5643 -72.548242)
		(width 0.10795)
		(layer "B.Cu")
		(net "SMB_SENSOR_STBY_LVC3_SCL")
	)
	(segment
		(start 422.159684 -60.293758)
		(end 420.775892 -61.67755)
		(width 0.10795)
		(layer "B.Cu")
		(net "SMB_SENSOR_STBY_LVC3_SCL")
	)
	(segment
		(start 425.5643 -71.497444)
		(end 424.475656 -70.4088)
		(width 0.10795)
		(layer "B.Cu")
		(net "SMB_SENSOR_STBY_LVC3_SCL")
	)
	(segment
		(start 460.121 -4.881626)
		(end 460.729076 -4.27355)
		(width 0.10795)
		(layer "B.Cu")
		(net "SMB_SENSOR_STBY_LVC3_SCL")
	)
	(segment
		(start 469.174068 -1.9812)
		(end 470.532968 -3.3401)
		(width 0.10795)
		(layer "B.Cu")
		(net "SMB_SENSOR_STBY_LVC3_SCL")
	)
	(segment
		(start 424.816016 -60.7568)
		(end 424.352974 -60.293758)
		(width 0.10795)
		(layer "B.Cu")
		(net "SMB_SENSOR_STBY_LVC3_SCL")
	)
	(segment
		(start 346.291408 -138.700764)
		(end 346.153994 -138.56335)
		(width 0.10795)
		(layer "B.Cu")
		(net "SMB_SENSOR_STBY_LVC3_SCL")
	)
	(segment
		(start 420.775892 -61.67755)
		(end 415.982912 -61.67755)
		(width 0.10795)
		(layer "B.Cu")
		(net "SMB_SENSOR_STBY_LVC3_SCL")
	)
	(segment
		(start 476.160592 -4.144518)
		(end 476.705168 -4.689094)
		(width 0.10795)
		(layer "B.Cu")
		(net "SMB_SENSOR_STBY_LVC3_SCL")
	)
	(segment
		(start 472.13012 -3.3401)
		(end 472.934538 -4.144518)
		(width 0.10795)
		(layer "B.Cu")
		(net "SMB_SENSOR_STBY_LVC3_SCL")
	)
	(segment
		(start 338.816442 -138.054842)
		(end 336.261964 -138.054842)
		(width 0.10795)
		(layer "B.Cu")
		(net "SMB_SENSOR_STBY_LVC3_SCL")
	)
	(segment
		(start 459.010258 -6.837172)
		(end 459.462886 -7.2898)
		(width 0.10795)
		(layer "B.Cu")
		(net "SMB_SENSOR_STBY_LVC3_SCL")
	)
	(segment
		(start 329.71994 -139.149582)
		(end 329.336146 -139.533376)
		(width 0.10795)
		(layer "B.Cu")
		(net "SMB_SENSOR_STBY_LVC3_SCL")
	)
	(segment
		(start 460.729076 -4.27355)
		(end 461.85455 -4.27355)
		(width 0.10795)
		(layer "B.Cu")
		(net "SMB_SENSOR_STBY_LVC3_SCL")
	)
	(segment
		(start 426.4914 -73.533)
		(end 426.4914 -73.475342)
		(width 0.10795)
		(layer "B.Cu")
		(net "SMB_SENSOR_STBY_LVC3_SCL")
	)
	(segment
		(start 424.475656 -70.4088)
		(end 424.475656 -67.879976)
		(width 0.10795)
		(layer "B.Cu")
		(net "SMB_SENSOR_STBY_LVC3_SCL")
	)
	(segment
		(start 329.336146 -139.533376)
		(end 329.336146 -146.162014)
		(width 0.10795)
		(layer "B.Cu")
		(net "SMB_SENSOR_STBY_LVC3_SCL")
	)
	(segment
		(start 411.560772 -64.686942)
		(end 411.5435 -64.704214)
		(width 0.10795)
		(layer "B.Cu")
		(net "SMB_SENSOR_STBY_LVC3_SCL")
	)
	(segment
		(start 425.289726 -63.353188)
		(end 424.816016 -62.879478)
		(width 0.10795)
		(layer "B.Cu")
		(net "SMB_SENSOR_STBY_LVC3_SCL")
	)
	(segment
		(start 346.291408 -138.97102)
		(end 346.291408 -138.700764)
		(width 0.10795)
		(layer "B.Cu")
		(net "SMB_SENSOR_STBY_LVC3_SCL")
	)
	(segment
		(start 459.462886 -7.2898)
		(end 459.9178 -7.2898)
		(width 0.10795)
		(layer "B.Cu")
		(net "SMB_SENSOR_STBY_LVC3_SCL")
	)
	(segment
		(start 329.336146 -146.162014)
		(end 328.441812 -147.056348)
		(width 0.10795)
		(layer "B.Cu")
		(net "SMB_SENSOR_STBY_LVC3_SCL")
	)
	(segment
		(start 411.9626 -63.602362)
		(end 411.560772 -64.00419)
		(width 0.10795)
		(layer "B.Cu")
		(net "SMB_SENSOR_STBY_LVC3_SCL")
	)
	(segment
		(start 465.934298 -1.622298)
		(end 466.0646 -1.7526)
		(width 0.10795)
		(layer "B.Cu")
		(net "SMB_SENSOR_STBY_LVC3_SCL")
	)
	(segment
		(start 470.532968 -3.3401)
		(end 472.13012 -3.3401)
		(width 0.10795)
		(layer "B.Cu")
		(net "SMB_SENSOR_STBY_LVC3_SCL")
	)
	(segment
		(start 461.85455 -4.27355)
		(end 462.42605 -3.70205)
		(width 0.10795)
		(layer "B.Cu")
		(net "SMB_SENSOR_STBY_LVC3_SCL")
	)
	(segment
		(start 425.5643 -72.548242)
		(end 425.5643 -71.497444)
		(width 0.10795)
		(layer "B.Cu")
		(net "SMB_SENSOR_STBY_LVC3_SCL")
	)
	(segment
		(start 425.289726 -67.065906)
		(end 425.289726 -63.353188)
		(width 0.10795)
		(layer "B.Cu")
		(net "SMB_SENSOR_STBY_LVC3_SCL")
	)
	(segment
		(start 346.153994 -138.56335)
		(end 339.32495 -138.56335)
		(width 0.10795)
		(layer "B.Cu")
		(net "SMB_SENSOR_STBY_LVC3_SCL")
	)
	(segment
		(start 476.705168 -4.689094)
		(end 476.573342 -4.82092)
		(width 0.10795)
		(layer "B.Cu")
		(net "SMB_SENSOR_STBY_LVC3_SCL")
	)
	(segment
		(start 459.9178 -7.2898)
		(end 460.121 -7.0866)
		(width 0.10795)
		(layer "B.Cu")
		(net "SMB_SENSOR_STBY_LVC3_SCL")
	)
	(segment
		(start 424.816016 -62.879478)
		(end 424.816016 -60.7568)
		(width 0.10795)
		(layer "B.Cu")
		(net "SMB_SENSOR_STBY_LVC3_SCL")
	)
	(segment
		(start 414.0581 -63.602362)
		(end 411.9626 -63.602362)
		(width 0.10795)
		(layer "B.Cu")
		(net "SMB_SENSOR_STBY_LVC3_SCL")
	)
	(segment
		(start 328.441812 -147.056348)
		(end 327.734168 -147.056348)
		(width 0.10795)
		(layer "B.Cu")
		(net "SMB_SENSOR_STBY_LVC3_SCL")
	)
	(segment
		(start 468.4776 -1.7526)
		(end 468.7062 -1.9812)
		(width 0.10795)
		(layer "B.Cu")
		(net "SMB_SENSOR_STBY_LVC3_SCL")
	)
	(segment
		(start 339.32495 -138.56335)
		(end 338.816442 -138.054842)
		(width 0.10795)
		(layer "B.Cu")
		(net "SMB_SENSOR_STBY_LVC3_SCL")
	)
	(segment
		(start 463.427318 -67.165728)
		(end 427.392084 -67.165728)
		(width 0.089408)
		(layer "In2.Cu")
		(net "SMB_SENSOR_STBY_LVC3_SCL")
	)
	(segment
		(start 463.427572 -67.165982)
		(end 463.427318 -67.165728)
		(width 0.089408)
		(layer "In2.Cu")
		(net "SMB_SENSOR_STBY_LVC3_SCL")
	)
	(segment
		(start 425.8818 -68.676012)
		(end 425.8818 -72.811386)
		(width 0.089408)
		(layer "In2.Cu")
		(net "SMB_SENSOR_STBY_LVC3_SCL")
	)
	(segment
		(start 484.932482 -61.853318)
		(end 479.714306 -61.853318)
		(width 0.089408)
		(layer "In2.Cu")
		(net "SMB_SENSOR_STBY_LVC3_SCL")
	)
	(segment
		(start 489.2294 -58.7248)
		(end 489.00207 -58.95213)
		(width 0.089408)
		(layer "In2.Cu")
		(net "SMB_SENSOR_STBY_LVC3_SCL")
	)
	(segment
		(start 411.48 -58.292746)
		(end 412.17596 -57.596786)
		(width 0.089408)
		(layer "In2.Cu")
		(net "SMB_SENSOR_STBY_LVC3_SCL")
	)
	(segment
		(start 479.714306 -61.853318)
		(end 474.401896 -67.165728)
		(width 0.089408)
		(layer "In2.Cu")
		(net "SMB_SENSOR_STBY_LVC3_SCL")
	)
	(segment
		(start 411.5435 -64.704214)
		(end 411.5435 -64.550798)
		(width 0.089408)
		(layer "In2.Cu")
		(net "SMB_SENSOR_STBY_LVC3_SCL")
	)
	(segment
		(start 465.507832 -67.165982)
		(end 463.427572 -67.165982)
		(width 0.089408)
		(layer "In2.Cu")
		(net "SMB_SENSOR_STBY_LVC3_SCL")
	)
	(segment
		(start 465.508086 -67.165728)
		(end 465.507832 -67.165982)
		(width 0.089408)
		(layer "In2.Cu")
		(net "SMB_SENSOR_STBY_LVC3_SCL")
	)
	(segment
		(start 474.401896 -67.165728)
		(end 465.508086 -67.165728)
		(width 0.089408)
		(layer "In2.Cu")
		(net "SMB_SENSOR_STBY_LVC3_SCL")
	)
	(segment
		(start 411.48 -64.487298)
		(end 411.48 -58.292746)
		(width 0.089408)
		(layer "In2.Cu")
		(net "SMB_SENSOR_STBY_LVC3_SCL")
	)
	(segment
		(start 425.8818 -72.811386)
		(end 426.4914 -73.420986)
		(width 0.089408)
		(layer "In2.Cu")
		(net "SMB_SENSOR_STBY_LVC3_SCL")
	)
	(segment
		(start 411.5435 -64.550798)
		(end 411.48 -64.487298)
		(width 0.089408)
		(layer "In2.Cu")
		(net "SMB_SENSOR_STBY_LVC3_SCL")
	)
	(segment
		(start 412.17596 -57.141872)
		(end 411.775656 -56.741568)
		(width 0.089408)
		(layer "In2.Cu")
		(net "SMB_SENSOR_STBY_LVC3_SCL")
	)
	(segment
		(start 412.17596 -57.596786)
		(end 412.17596 -57.141872)
		(width 0.089408)
		(layer "In2.Cu")
		(net "SMB_SENSOR_STBY_LVC3_SCL")
	)
	(segment
		(start 489.00207 -58.95213)
		(end 487.83367 -58.95213)
		(width 0.089408)
		(layer "In2.Cu")
		(net "SMB_SENSOR_STBY_LVC3_SCL")
	)
	(segment
		(start 426.4914 -73.420986)
		(end 426.4914 -73.533)
		(width 0.089408)
		(layer "In2.Cu")
		(net "SMB_SENSOR_STBY_LVC3_SCL")
	)
	(segment
		(start 487.83367 -58.95213)
		(end 484.932482 -61.853318)
		(width 0.089408)
		(layer "In2.Cu")
		(net "SMB_SENSOR_STBY_LVC3_SCL")
	)
	(segment
		(start 427.392084 -67.165728)
		(end 425.8818 -68.676012)
		(width 0.089408)
		(layer "In2.Cu")
		(net "SMB_SENSOR_STBY_LVC3_SCL")
	)
	(segment
		(start 426.091096 -77.559662)
		(end 426.091096 -73.933304)
		(width 0.089408)
		(layer "In4.Cu")
		(net "SMB_SENSOR_STBY_LVC3_SCL")
	)
	(segment
		(start 407.819098 -65.42532)
		(end 406.623266 -64.229488)
		(width 0.089408)
		(layer "In4.Cu")
		(net "SMB_SENSOR_STBY_LVC3_SCL")
	)
	(segment
		(start 382.99263 -65.436496)
		(end 381.795528 -65.436496)
		(width 0.089408)
		(layer "In4.Cu")
		(net "SMB_SENSOR_STBY_LVC3_SCL")
	)
	(segment
		(start 471.678508 -111.195104)
		(end 470.8652 -110.381796)
		(width 0.089408)
		(layer "In4.Cu")
		(net "SMB_SENSOR_STBY_LVC3_SCL")
	)
	(segment
		(start 411.424628 -64.704214)
		(end 411.347412 -64.78143)
		(width 0.089408)
		(layer "In4.Cu")
		(net "SMB_SENSOR_STBY_LVC3_SCL")
	)
	(segment
		(start 398.73936 -63.3349)
		(end 397.87322 -63.3349)
		(width 0.089408)
		(layer "In4.Cu")
		(net "SMB_SENSOR_STBY_LVC3_SCL")
	)
	(segment
		(start 393.736576 -64.03975)
		(end 393.578588 -64.03975)
		(width 0.089408)
		(layer "In4.Cu")
		(net "SMB_SENSOR_STBY_LVC3_SCL")
	)
	(segment
		(start 381.795528 -65.436496)
		(end 380.946406 -64.587374)
		(width 0.089408)
		(layer "In4.Cu")
		(net "SMB_SENSOR_STBY_LVC3_SCL")
	)
	(segment
		(start 491.54461 -111.195104)
		(end 491.139734 -111.59998)
		(width 0.089408)
		(layer "In4.Cu")
		(net "SMB_SENSOR_STBY_LVC3_SCL")
	)
	(segment
		(start 461.151224 -153.383488)
		(end 466.05825 -153.383488)
		(width 0.089408)
		(layer "In4.Cu")
		(net "SMB_SENSOR_STBY_LVC3_SCL")
	)
	(segment
		(start 379.58395 -64.587374)
		(end 379.272546 -64.898778)
		(width 0.089408)
		(layer "In4.Cu")
		(net "SMB_SENSOR_STBY_LVC3_SCL")
	)
	(segment
		(start 401.396962 -64.62903)
		(end 400.493992 -63.72606)
		(width 0.089408)
		(layer "In4.Cu")
		(net "SMB_SENSOR_STBY_LVC3_SCL")
	)
	(segment
		(start 399.13052 -63.72606)
		(end 398.73936 -63.3349)
		(width 0.089408)
		(layer "In4.Cu")
		(net "SMB_SENSOR_STBY_LVC3_SCL")
	)
	(segment
		(start 451.231 -157.7848)
		(end 451.446392 -158.000192)
		(width 0.089408)
		(layer "In4.Cu")
		(net "SMB_SENSOR_STBY_LVC3_SCL")
	)
	(segment
		(start 385.16687 -66.011552)
		(end 383.567686 -66.011552)
		(width 0.089408)
		(layer "In4.Cu")
		(net "SMB_SENSOR_STBY_LVC3_SCL")
	)
	(segment
		(start 469.391238 -150.0505)
		(end 469.6206 -150.0505)
		(width 0.089408)
		(layer "In4.Cu")
		(net "SMB_SENSOR_STBY_LVC3_SCL")
	)
	(segment
		(start 470.8652 -110.381796)
		(end 427.463712 -110.381796)
		(width 0.089408)
		(layer "In4.Cu")
		(net "SMB_SENSOR_STBY_LVC3_SCL")
	)
	(segment
		(start 500.05742 -117.465348)
		(end 500.05742 -113.584482)
		(width 0.089408)
		(layer "In4.Cu")
		(net "SMB_SENSOR_STBY_LVC3_SCL")
	)
	(segment
		(start 397.87322 -63.3349)
		(end 397.151352 -62.613032)
		(width 0.089408)
		(layer "In4.Cu")
		(net "SMB_SENSOR_STBY_LVC3_SCL")
	)
	(segment
		(start 380.946406 -64.587374)
		(end 379.58395 -64.587374)
		(width 0.089408)
		(layer "In4.Cu")
		(net "SMB_SENSOR_STBY_LVC3_SCL")
	)
	(segment
		(start 405.453342 -64.62903)
		(end 401.396962 -64.62903)
		(width 0.089408)
		(layer "In4.Cu")
		(net "SMB_SENSOR_STBY_LVC3_SCL")
	)
	(segment
		(start 466.05825 -153.383488)
		(end 469.391238 -150.0505)
		(width 0.089408)
		(layer "In4.Cu")
		(net "SMB_SENSOR_STBY_LVC3_SCL")
	)
	(segment
		(start 451.446392 -158.000192)
		(end 456.53452 -158.000192)
		(width 0.089408)
		(layer "In4.Cu")
		(net "SMB_SENSOR_STBY_LVC3_SCL")
	)
	(segment
		(start 400.493992 -63.72606)
		(end 399.13052 -63.72606)
		(width 0.089408)
		(layer "In4.Cu")
		(net "SMB_SENSOR_STBY_LVC3_SCL")
	)
	(segment
		(start 426.091096 -73.933304)
		(end 426.4914 -73.533)
		(width 0.089408)
		(layer "In4.Cu")
		(net "SMB_SENSOR_STBY_LVC3_SCL")
	)
	(segment
		(start 426.695362 -78.163928)
		(end 426.091096 -77.559662)
		(width 0.089408)
		(layer "In4.Cu")
		(net "SMB_SENSOR_STBY_LVC3_SCL")
	)
	(segment
		(start 411.347412 -64.78143)
		(end 410.62148 -64.78143)
		(width 0.089408)
		(layer "In4.Cu")
		(net "SMB_SENSOR_STBY_LVC3_SCL")
	)
	(segment
		(start 393.578334 -64.039496)
		(end 389.68172 -64.039496)
		(width 0.089408)
		(layer "In4.Cu")
		(net "SMB_SENSOR_STBY_LVC3_SCL")
	)
	(segment
		(start 456.53452 -158.000192)
		(end 461.151224 -153.383488)
		(width 0.089408)
		(layer "In4.Cu")
		(net "SMB_SENSOR_STBY_LVC3_SCL")
	)
	(segment
		(start 497.131848 -121.798334)
		(end 497.131848 -121.447814)
		(width 0.089408)
		(layer "In4.Cu")
		(net "SMB_SENSOR_STBY_LVC3_SCL")
	)
	(segment
		(start 410.62148 -64.78143)
		(end 409.97759 -65.42532)
		(width 0.089408)
		(layer "In4.Cu")
		(net "SMB_SENSOR_STBY_LVC3_SCL")
	)
	(segment
		(start 485.68864 -111.59998)
		(end 485.283764 -111.195104)
		(width 0.089408)
		(layer "In4.Cu")
		(net "SMB_SENSOR_STBY_LVC3_SCL")
	)
	(segment
		(start 411.5435 -64.704214)
		(end 411.424628 -64.704214)
		(width 0.089408)
		(layer "In4.Cu")
		(net "SMB_SENSOR_STBY_LVC3_SCL")
	)
	(segment
		(start 497.668042 -111.195104)
		(end 491.54461 -111.195104)
		(width 0.089408)
		(layer "In4.Cu")
		(net "SMB_SENSOR_STBY_LVC3_SCL")
	)
	(segment
		(start 485.283764 -111.195104)
		(end 471.678508 -111.195104)
		(width 0.089408)
		(layer "In4.Cu")
		(net "SMB_SENSOR_STBY_LVC3_SCL")
	)
	(segment
		(start 397.151352 -62.613032)
		(end 395.7066 -62.613032)
		(width 0.089408)
		(layer "In4.Cu")
		(net "SMB_SENSOR_STBY_LVC3_SCL")
	)
	(segment
		(start 497.131848 -121.447814)
		(end 497.340128 -121.239534)
		(width 0.089408)
		(layer "In4.Cu")
		(net "SMB_SENSOR_STBY_LVC3_SCL")
	)
	(segment
		(start 491.139734 -111.59998)
		(end 485.68864 -111.59998)
		(width 0.089408)
		(layer "In4.Cu")
		(net "SMB_SENSOR_STBY_LVC3_SCL")
	)
	(segment
		(start 395.7066 -62.613032)
		(end 394.280136 -64.039496)
		(width 0.089408)
		(layer "In4.Cu")
		(net "SMB_SENSOR_STBY_LVC3_SCL")
	)
	(segment
		(start 383.567686 -66.011552)
		(end 382.99263 -65.436496)
		(width 0.089408)
		(layer "In4.Cu")
		(net "SMB_SENSOR_STBY_LVC3_SCL")
	)
	(segment
		(start 394.053822 -64.039496)
		(end 394.053314 -64.040004)
		(width 0.089408)
		(layer "In4.Cu")
		(net "SMB_SENSOR_STBY_LVC3_SCL")
	)
	(segment
		(start 386.895848 -64.282574)
		(end 385.16687 -66.011552)
		(width 0.089408)
		(layer "In4.Cu")
		(net "SMB_SENSOR_STBY_LVC3_SCL")
	)
	(segment
		(start 405.852884 -64.229488)
		(end 405.453342 -64.62903)
		(width 0.089408)
		(layer "In4.Cu")
		(net "SMB_SENSOR_STBY_LVC3_SCL")
	)
	(segment
		(start 393.578588 -64.03975)
		(end 393.578334 -64.039496)
		(width 0.089408)
		(layer "In4.Cu")
		(net "SMB_SENSOR_STBY_LVC3_SCL")
	)
	(segment
		(start 389.438642 -64.282574)
		(end 386.895848 -64.282574)
		(width 0.089408)
		(layer "In4.Cu")
		(net "SMB_SENSOR_STBY_LVC3_SCL")
	)
	(segment
		(start 498.076728 -119.44604)
		(end 500.05742 -117.465348)
		(width 0.089408)
		(layer "In4.Cu")
		(net "SMB_SENSOR_STBY_LVC3_SCL")
	)
	(segment
		(start 409.97759 -65.42532)
		(end 407.819098 -65.42532)
		(width 0.089408)
		(layer "In4.Cu")
		(net "SMB_SENSOR_STBY_LVC3_SCL")
	)
	(segment
		(start 406.623266 -64.229488)
		(end 405.852884 -64.229488)
		(width 0.089408)
		(layer "In4.Cu")
		(net "SMB_SENSOR_STBY_LVC3_SCL")
	)
	(segment
		(start 394.053314 -64.040004)
		(end 393.73683 -64.040004)
		(width 0.089408)
		(layer "In4.Cu")
		(net "SMB_SENSOR_STBY_LVC3_SCL")
	)
	(segment
		(start 426.695362 -109.613446)
		(end 426.695362 -78.163928)
		(width 0.089408)
		(layer "In4.Cu")
		(net "SMB_SENSOR_STBY_LVC3_SCL")
	)
	(segment
		(start 389.68172 -64.039496)
		(end 389.438642 -64.282574)
		(width 0.089408)
		(layer "In4.Cu")
		(net "SMB_SENSOR_STBY_LVC3_SCL")
	)
	(segment
		(start 394.280136 -64.039496)
		(end 394.053822 -64.039496)
		(width 0.089408)
		(layer "In4.Cu")
		(net "SMB_SENSOR_STBY_LVC3_SCL")
	)
	(segment
		(start 497.340128 -121.239534)
		(end 497.662708 -121.239534)
		(width 0.089408)
		(layer "In4.Cu")
		(net "SMB_SENSOR_STBY_LVC3_SCL")
	)
	(segment
		(start 497.662708 -121.239534)
		(end 498.076728 -120.825514)
		(width 0.089408)
		(layer "In4.Cu")
		(net "SMB_SENSOR_STBY_LVC3_SCL")
	)
	(segment
		(start 427.463712 -110.381796)
		(end 426.695362 -109.613446)
		(width 0.089408)
		(layer "In4.Cu")
		(net "SMB_SENSOR_STBY_LVC3_SCL")
	)
	(segment
		(start 500.05742 -113.584482)
		(end 497.668042 -111.195104)
		(width 0.089408)
		(layer "In4.Cu")
		(net "SMB_SENSOR_STBY_LVC3_SCL")
	)
	(segment
		(start 393.73683 -64.040004)
		(end 393.736576 -64.03975)
		(width 0.089408)
		(layer "In4.Cu")
		(net "SMB_SENSOR_STBY_LVC3_SCL")
	)
	(segment
		(start 498.076728 -120.825514)
		(end 498.076728 -119.44604)
		(width 0.089408)
		(layer "In4.Cu")
		(net "SMB_SENSOR_STBY_LVC3_SCL")
	)
	(segment
		(start 496.60302 -132.7658)
		(end 495.01552 -134.3533)
		(width 0.089408)
		(layer "In9.Cu")
		(net "SMB_SENSOR_STBY_LVC3_SCL")
	)
	(segment
		(start 323.695314 -148.91004)
		(end 325.549006 -147.056348)
		(width 0.089408)
		(layer "In9.Cu")
		(net "SMB_SENSOR_STBY_LVC3_SCL")
	)
	(segment
		(start 3.31089 -88.21166)
		(end 8.611616 -88.21166)
		(width 0.089408)
		(layer "In9.Cu")
		(net "SMB_SENSOR_STBY_LVC3_SCL")
	)
	(segment
		(start 479.234754 -145.9865)
		(end 476.062548 -145.9865)
		(width 0.089408)
		(layer "In9.Cu")
		(net "SMB_SENSOR_STBY_LVC3_SCL")
	)
	(segment
		(start 325.549006 -147.056348)
		(end 327.734168 -147.056348)
		(width 0.089408)
		(layer "In9.Cu")
		(net "SMB_SENSOR_STBY_LVC3_SCL")
	)
	(segment
		(start 158.8262 -141.39672)
		(end 160.43148 -143.002)
		(width 0.089408)
		(layer "In9.Cu")
		(net "SMB_SENSOR_STBY_LVC3_SCL")
	)
	(segment
		(start 498.12956 -121.505218)
		(end 498.12956 -127.605536)
		(width 0.089408)
		(layer "In9.Cu")
		(net "SMB_SENSOR_STBY_LVC3_SCL")
	)
	(segment
		(start 120.775222 -124.799598)
		(end 123.497848 -127.522224)
		(width 0.089408)
		(layer "In9.Cu")
		(net "SMB_SENSOR_STBY_LVC3_SCL")
	)
	(segment
		(start 156.99486 -129.149856)
		(end 158.8262 -130.981196)
		(width 0.089408)
		(layer "In9.Cu")
		(net "SMB_SENSOR_STBY_LVC3_SCL")
	)
	(segment
		(start 262.909304 -147.479004)
		(end 321.518788 -147.479004)
		(width 0.089408)
		(layer "In9.Cu")
		(net "SMB_SENSOR_STBY_LVC3_SCL")
	)
	(segment
		(start 123.497848 -127.522224)
		(end 149.83333 -127.522224)
		(width 0.089408)
		(layer "In9.Cu")
		(net "SMB_SENSOR_STBY_LVC3_SCL")
	)
	(segment
		(start 490.246924 -24.055324)
		(end 490.246924 -26.498804)
		(width 0.089408)
		(layer "In9.Cu")
		(net "SMB_SENSOR_STBY_LVC3_SCL")
	)
	(segment
		(start 489.0516 -58.9026)
		(end 489.2294 -58.7248)
		(width 0.089408)
		(layer "In9.Cu")
		(net "SMB_SENSOR_STBY_LVC3_SCL")
	)
	(segment
		(start 10.331196 -94.036134)
		(end 11.322812 -95.02775)
		(width 0.089408)
		(layer "In9.Cu")
		(net "SMB_SENSOR_STBY_LVC3_SCL")
	)
	(segment
		(start 477.644714 -4.714748)
		(end 479.404934 -4.714748)
		(width 0.089408)
		(layer "In9.Cu")
		(net "SMB_SENSOR_STBY_LVC3_SCL")
	)
	(segment
		(start 492.476536 -35.56508)
		(end 494.608358 -37.696902)
		(width 0.089408)
		(layer "In9.Cu")
		(net "SMB_SENSOR_STBY_LVC3_SCL")
	)
	(segment
		(start 488.328208 -56.669686)
		(end 488.328208 -58.585608)
		(width 0.089408)
		(layer "In9.Cu")
		(net "SMB_SENSOR_STBY_LVC3_SCL")
	)
	(segment
		(start 16.79956 -109.851698)
		(end 21.209254 -114.261392)
		(width 0.089408)
		(layer "In9.Cu")
		(net "SMB_SENSOR_STBY_LVC3_SCL")
	)
	(segment
		(start 499.3259 -128.801876)
		(end 499.3259 -130.6195)
		(width 0.089408)
		(layer "In9.Cu")
		(net "SMB_SENSOR_STBY_LVC3_SCL")
	)
	(segment
		(start 477.31807 -5.041392)
		(end 477.644714 -4.714748)
		(width 0.089408)
		(layer "In9.Cu")
		(net "SMB_SENSOR_STBY_LVC3_SCL")
	)
	(segment
		(start 494.608358 -38.811454)
		(end 495.195352 -39.398448)
		(width 0.089408)
		(layer "In9.Cu")
		(net "SMB_SENSOR_STBY_LVC3_SCL")
	)
	(segment
		(start 24.760936 -124.621036)
		(end 28.022042 -127.882142)
		(width 0.089408)
		(layer "In9.Cu")
		(net "SMB_SENSOR_STBY_LVC3_SCL")
	)
	(segment
		(start 149.83333 -127.522224)
		(end 151.460962 -129.149856)
		(width 0.089408)
		(layer "In9.Cu")
		(net "SMB_SENSOR_STBY_LVC3_SCL")
	)
	(segment
		(start 476.705168 -4.689094)
		(end 477.057466 -5.041392)
		(width 0.089408)
		(layer "In9.Cu")
		(net "SMB_SENSOR_STBY_LVC3_SCL")
	)
	(segment
		(start 163.641024 -143.575024)
		(end 184.43829 -143.575024)
		(width 0.089408)
		(layer "In9.Cu")
		(net "SMB_SENSOR_STBY_LVC3_SCL")
	)
	(segment
		(start 497.1796 -132.7658)
		(end 496.60302 -132.7658)
		(width 0.089408)
		(layer "In9.Cu")
		(net "SMB_SENSOR_STBY_LVC3_SCL")
	)
	(segment
		(start 0.966724 -76.796138)
		(end 1.293368 -77.122782)
		(width 0.089408)
		(layer "In9.Cu")
		(net "SMB_SENSOR_STBY_LVC3_SCL")
	)
	(segment
		(start 11.322812 -95.02775)
		(end 11.322812 -102.73792)
		(width 0.089408)
		(layer "In9.Cu")
		(net "SMB_SENSOR_STBY_LVC3_SCL")
	)
	(segment
		(start 495.019076 -42.12336)
		(end 495.019076 -50.922428)
		(width 0.089408)
		(layer "In9.Cu")
		(net "SMB_SENSOR_STBY_LVC3_SCL")
	)
	(segment
		(start 469.91651 -150.0505)
		(end 469.6206 -150.0505)
		(width 0.089408)
		(layer "In9.Cu")
		(net "SMB_SENSOR_STBY_LVC3_SCL")
	)
	(segment
		(start 14.59611 -105.336848)
		(end 16.79956 -107.540298)
		(width 0.089408)
		(layer "In9.Cu")
		(net "SMB_SENSOR_STBY_LVC3_SCL")
	)
	(segment
		(start 261.696708 -146.266408)
		(end 262.909304 -147.479004)
		(width 0.089408)
		(layer "In9.Cu")
		(net "SMB_SENSOR_STBY_LVC3_SCL")
	)
	(segment
		(start 492.106204 -53.8353)
		(end 491.162594 -53.8353)
		(width 0.089408)
		(layer "In9.Cu")
		(net "SMB_SENSOR_STBY_LVC3_SCL")
	)
	(segment
		(start 28.022042 -127.882142)
		(end 85.923882 -127.882142)
		(width 0.089408)
		(layer "In9.Cu")
		(net "SMB_SENSOR_STBY_LVC3_SCL")
	)
	(segment
		(start 489.077 -19.8374)
		(end 489.077 -22.8854)
		(width 0.089408)
		(layer "In9.Cu")
		(net "SMB_SENSOR_STBY_LVC3_SCL")
	)
	(segment
		(start 160.43148 -143.002)
		(end 163.068 -143.002)
		(width 0.089408)
		(layer "In9.Cu")
		(net "SMB_SENSOR_STBY_LVC3_SCL")
	)
	(segment
		(start 489.077 -140.97)
		(end 487.4006 -142.6464)
		(width 0.089408)
		(layer "In9.Cu")
		(net "SMB_SENSOR_STBY_LVC3_SCL")
	)
	(segment
		(start 492.593122 -134.3533)
		(end 489.077 -137.869422)
		(width 0.089408)
		(layer "In9.Cu")
		(net "SMB_SENSOR_STBY_LVC3_SCL")
	)
	(segment
		(start 473.930472 -148.118576)
		(end 471.848434 -148.118576)
		(width 0.089408)
		(layer "In9.Cu")
		(net "SMB_SENSOR_STBY_LVC3_SCL")
	)
	(segment
		(start 85.923882 -127.882142)
		(end 89.006426 -124.799598)
		(width 0.089408)
		(layer "In9.Cu")
		(net "SMB_SENSOR_STBY_LVC3_SCL")
	)
	(segment
		(start 489.077 -137.869422)
		(end 489.077 -140.97)
		(width 0.089408)
		(layer "In9.Cu")
		(net "SMB_SENSOR_STBY_LVC3_SCL")
	)
	(segment
		(start 480.6696 -14.3256)
		(end 483.221792 -16.877792)
		(width 0.089408)
		(layer "In9.Cu")
		(net "SMB_SENSOR_STBY_LVC3_SCL")
	)
	(segment
		(start 1.293368 -77.122782)
		(end 1.293368 -78.174342)
		(width 0.089408)
		(layer "In9.Cu")
		(net "SMB_SENSOR_STBY_LVC3_SCL")
	)
	(segment
		(start 192.755012 -147.256754)
		(end 193.049652 -147.551394)
		(width 0.089408)
		(layer "In9.Cu")
		(net "SMB_SENSOR_STBY_LVC3_SCL")
	)
	(segment
		(start 486.117392 -16.877792)
		(end 489.077 -19.8374)
		(width 0.089408)
		(layer "In9.Cu")
		(net "SMB_SENSOR_STBY_LVC3_SCL")
	)
	(segment
		(start 495.195352 -41.947084)
		(end 495.019076 -42.12336)
		(width 0.089408)
		(layer "In9.Cu")
		(net "SMB_SENSOR_STBY_LVC3_SCL")
	)
	(segment
		(start 23.68931 -124.621036)
		(end 24.760936 -124.621036)
		(width 0.089408)
		(layer "In9.Cu")
		(net "SMB_SENSOR_STBY_LVC3_SCL")
	)
	(segment
		(start 476.062548 -145.9865)
		(end 473.930472 -148.118576)
		(width 0.089408)
		(layer "In9.Cu")
		(net "SMB_SENSOR_STBY_LVC3_SCL")
	)
	(segment
		(start 260.48843 -146.266408)
		(end 261.696708 -146.266408)
		(width 0.089408)
		(layer "In9.Cu")
		(net "SMB_SENSOR_STBY_LVC3_SCL")
	)
	(segment
		(start 21.209254 -122.14098)
		(end 23.68931 -124.621036)
		(width 0.089408)
		(layer "In9.Cu")
		(net "SMB_SENSOR_STBY_LVC3_SCL")
	)
	(segment
		(start 479.404934 -4.714748)
		(end 480.6696 -5.979414)
		(width 0.089408)
		(layer "In9.Cu")
		(net "SMB_SENSOR_STBY_LVC3_SCL")
	)
	(segment
		(start 1.293368 -78.174342)
		(end 1.766316 -78.64729)
		(width 0.089408)
		(layer "In9.Cu")
		(net "SMB_SENSOR_STBY_LVC3_SCL")
	)
	(segment
		(start 498.12956 -127.605536)
		(end 499.3259 -128.801876)
		(width 0.089408)
		(layer "In9.Cu")
		(net "SMB_SENSOR_STBY_LVC3_SCL")
	)
	(segment
		(start 497.131848 -121.798334)
		(end 497.131848 -121.642886)
		(width 0.089408)
		(layer "In9.Cu")
		(net "SMB_SENSOR_STBY_LVC3_SCL")
	)
	(segment
		(start 495.01552 -134.3533)
		(end 492.593122 -134.3533)
		(width 0.089408)
		(layer "In9.Cu")
		(net "SMB_SENSOR_STBY_LVC3_SCL")
	)
	(segment
		(start 491.162594 -53.8353)
		(end 488.328208 -56.669686)
		(width 0.089408)
		(layer "In9.Cu")
		(net "SMB_SENSOR_STBY_LVC3_SCL")
	)
	(segment
		(start 322.949824 -148.91004)
		(end 323.695314 -148.91004)
		(width 0.089408)
		(layer "In9.Cu")
		(net "SMB_SENSOR_STBY_LVC3_SCL")
	)
	(segment
		(start 193.049652 -147.551394)
		(end 259.203444 -147.551394)
		(width 0.089408)
		(layer "In9.Cu")
		(net "SMB_SENSOR_STBY_LVC3_SCL")
	)
	(segment
		(start 16.79956 -107.540298)
		(end 16.79956 -109.851698)
		(width 0.089408)
		(layer "In9.Cu")
		(net "SMB_SENSOR_STBY_LVC3_SCL")
	)
	(segment
		(start 13.92174 -105.336848)
		(end 14.59611 -105.336848)
		(width 0.089408)
		(layer "In9.Cu")
		(net "SMB_SENSOR_STBY_LVC3_SCL")
	)
	(segment
		(start 490.246924 -26.498804)
		(end 492.476536 -28.728416)
		(width 0.089408)
		(layer "In9.Cu")
		(net "SMB_SENSOR_STBY_LVC3_SCL")
	)
	(segment
		(start 11.322812 -102.73792)
		(end 13.92174 -105.336848)
		(width 0.089408)
		(layer "In9.Cu")
		(net "SMB_SENSOR_STBY_LVC3_SCL")
	)
	(segment
		(start 8.611616 -88.21166)
		(end 10.331196 -89.93124)
		(width 0.089408)
		(layer "In9.Cu")
		(net "SMB_SENSOR_STBY_LVC3_SCL")
	)
	(segment
		(start 1.766316 -86.667086)
		(end 3.31089 -88.21166)
		(width 0.089408)
		(layer "In9.Cu")
		(net "SMB_SENSOR_STBY_LVC3_SCL")
	)
	(segment
		(start 10.331196 -89.93124)
		(end 10.331196 -94.036134)
		(width 0.089408)
		(layer "In9.Cu")
		(net "SMB_SENSOR_STBY_LVC3_SCL")
	)
	(segment
		(start 492.476536 -28.728416)
		(end 492.476536 -35.56508)
		(width 0.089408)
		(layer "In9.Cu")
		(net "SMB_SENSOR_STBY_LVC3_SCL")
	)
	(segment
		(start 495.019076 -50.922428)
		(end 492.106204 -53.8353)
		(width 0.089408)
		(layer "In9.Cu")
		(net "SMB_SENSOR_STBY_LVC3_SCL")
	)
	(segment
		(start 489.077 -22.8854)
		(end 490.246924 -24.055324)
		(width 0.089408)
		(layer "In9.Cu")
		(net "SMB_SENSOR_STBY_LVC3_SCL")
	)
	(segment
		(start 321.518788 -147.479004)
		(end 322.949824 -148.91004)
		(width 0.089408)
		(layer "In9.Cu")
		(net "SMB_SENSOR_STBY_LVC3_SCL")
	)
	(segment
		(start 487.4006 -142.6464)
		(end 482.574854 -142.6464)
		(width 0.089408)
		(layer "In9.Cu")
		(net "SMB_SENSOR_STBY_LVC3_SCL")
	)
	(segment
		(start 497.97462 -121.350278)
		(end 498.12956 -121.505218)
		(width 0.089408)
		(layer "In9.Cu")
		(net "SMB_SENSOR_STBY_LVC3_SCL")
	)
	(segment
		(start 488.6452 -58.9026)
		(end 489.0516 -58.9026)
		(width 0.089408)
		(layer "In9.Cu")
		(net "SMB_SENSOR_STBY_LVC3_SCL")
	)
	(segment
		(start 1.766316 -78.64729)
		(end 1.766316 -86.667086)
		(width 0.089408)
		(layer "In9.Cu")
		(net "SMB_SENSOR_STBY_LVC3_SCL")
	)
	(segment
		(start 497.424456 -121.350278)
		(end 497.97462 -121.350278)
		(width 0.089408)
		(layer "In9.Cu")
		(net "SMB_SENSOR_STBY_LVC3_SCL")
	)
	(segment
		(start 497.131848 -121.642886)
		(end 497.424456 -121.350278)
		(width 0.089408)
		(layer "In9.Cu")
		(net "SMB_SENSOR_STBY_LVC3_SCL")
	)
	(segment
		(start 259.203444 -147.551394)
		(end 260.48843 -146.266408)
		(width 0.089408)
		(layer "In9.Cu")
		(net "SMB_SENSOR_STBY_LVC3_SCL")
	)
	(segment
		(start 184.43829 -143.575024)
		(end 188.12002 -147.256754)
		(width 0.089408)
		(layer "In9.Cu")
		(net "SMB_SENSOR_STBY_LVC3_SCL")
	)
	(segment
		(start 21.209254 -114.261392)
		(end 21.209254 -122.14098)
		(width 0.089408)
		(layer "In9.Cu")
		(net "SMB_SENSOR_STBY_LVC3_SCL")
	)
	(segment
		(start 163.068 -143.002)
		(end 163.641024 -143.575024)
		(width 0.089408)
		(layer "In9.Cu")
		(net "SMB_SENSOR_STBY_LVC3_SCL")
	)
	(segment
		(start 151.460962 -129.149856)
		(end 156.99486 -129.149856)
		(width 0.089408)
		(layer "In9.Cu")
		(net "SMB_SENSOR_STBY_LVC3_SCL")
	)
	(segment
		(start 495.195352 -39.398448)
		(end 495.195352 -41.947084)
		(width 0.089408)
		(layer "In9.Cu")
		(net "SMB_SENSOR_STBY_LVC3_SCL")
	)
	(segment
		(start 89.006426 -124.799598)
		(end 120.775222 -124.799598)
		(width 0.089408)
		(layer "In9.Cu")
		(net "SMB_SENSOR_STBY_LVC3_SCL")
	)
	(segment
		(start 188.12002 -147.256754)
		(end 192.755012 -147.256754)
		(width 0.089408)
		(layer "In9.Cu")
		(net "SMB_SENSOR_STBY_LVC3_SCL")
	)
	(segment
		(start 483.221792 -16.877792)
		(end 486.117392 -16.877792)
		(width 0.089408)
		(layer "In9.Cu")
		(net "SMB_SENSOR_STBY_LVC3_SCL")
	)
	(segment
		(start 488.328208 -58.585608)
		(end 488.6452 -58.9026)
		(width 0.089408)
		(layer "In9.Cu")
		(net "SMB_SENSOR_STBY_LVC3_SCL")
	)
	(segment
		(start 494.608358 -37.696902)
		(end 494.608358 -38.811454)
		(width 0.089408)
		(layer "In9.Cu")
		(net "SMB_SENSOR_STBY_LVC3_SCL")
	)
	(segment
		(start 482.574854 -142.6464)
		(end 479.234754 -145.9865)
		(width 0.089408)
		(layer "In9.Cu")
		(net "SMB_SENSOR_STBY_LVC3_SCL")
	)
	(segment
		(start 471.848434 -148.118576)
		(end 469.91651 -150.0505)
		(width 0.089408)
		(layer "In9.Cu")
		(net "SMB_SENSOR_STBY_LVC3_SCL")
	)
	(segment
		(start 480.6696 -5.979414)
		(end 480.6696 -14.3256)
		(width 0.089408)
		(layer "In9.Cu")
		(net "SMB_SENSOR_STBY_LVC3_SCL")
	)
	(segment
		(start 477.057466 -5.041392)
		(end 477.31807 -5.041392)
		(width 0.089408)
		(layer "In9.Cu")
		(net "SMB_SENSOR_STBY_LVC3_SCL")
	)
	(segment
		(start 499.3259 -130.6195)
		(end 497.1796 -132.7658)
		(width 0.089408)
		(layer "In9.Cu")
		(net "SMB_SENSOR_STBY_LVC3_SCL")
	)
	(segment
		(start 158.8262 -130.981196)
		(end 158.8262 -141.39672)
		(width 0.089408)
		(layer "In9.Cu")
		(net "SMB_SENSOR_STBY_LVC3_SCL")
	)
	(segment
		(start 371.026182 -145.809208)
		(end 372.161054 -146.94408)
		(width 0.089408)
		(layer "In11.Cu")
		(net "SMB_SENSOR_STBY_LVC3_SCL")
	)
	(segment
		(start 451.976236 -10.75309)
		(end 449.9737 -10.75309)
		(width 0.089408)
		(layer "In11.Cu")
		(net "SMB_SENSOR_STBY_LVC3_SCL")
	)
	(segment
		(start 432.323494 -16.771366)
		(end 423.341546 -16.771366)
		(width 0.089408)
		(layer "In11.Cu")
		(net "SMB_SENSOR_STBY_LVC3_SCL")
	)
	(segment
		(start 359.37444 -140.109956)
		(end 360.138218 -140.873734)
		(width 0.089408)
		(layer "In11.Cu")
		(net "SMB_SENSOR_STBY_LVC3_SCL")
	)
	(segment
		(start 362.952538 -142.335758)
		(end 362.952538 -143.148558)
		(width 0.089408)
		(layer "In11.Cu")
		(net "SMB_SENSOR_STBY_LVC3_SCL")
	)
	(segment
		(start 351.322894 -138.548364)
		(end 352.884486 -140.109956)
		(width 0.089408)
		(layer "In11.Cu")
		(net "SMB_SENSOR_STBY_LVC3_SCL")
	)
	(segment
		(start 449.9737 -10.75309)
		(end 446.132458 -14.594332)
		(width 0.089408)
		(layer "In11.Cu")
		(net "SMB_SENSOR_STBY_LVC3_SCL")
	)
	(segment
		(start 444.5 -15.484348)
		(end 443.59449 -16.389858)
		(width 0.089408)
		(layer "In11.Cu")
		(net "SMB_SENSOR_STBY_LVC3_SCL")
	)
	(segment
		(start 398.760696 -153.248106)
		(end 399.20037 -153.248106)
		(width 0.089408)
		(layer "In11.Cu")
		(net "SMB_SENSOR_STBY_LVC3_SCL")
	)
	(segment
		(start 445.209168 -15.484348)
		(end 444.5 -15.484348)
		(width 0.089408)
		(layer "In11.Cu")
		(net "SMB_SENSOR_STBY_LVC3_SCL")
	)
	(segment
		(start 388.446772 -149.308312)
		(end 389.887968 -150.749508)
		(width 0.089408)
		(layer "In11.Cu")
		(net "SMB_SENSOR_STBY_LVC3_SCL")
	)
	(segment
		(start 366.987328 -147.183348)
		(end 368.977672 -147.183348)
		(width 0.089408)
		(layer "In11.Cu")
		(net "SMB_SENSOR_STBY_LVC3_SCL")
	)
	(segment
		(start 399.20037 -153.248106)
		(end 400.321018 -154.368754)
		(width 0.089408)
		(layer "In11.Cu")
		(net "SMB_SENSOR_STBY_LVC3_SCL")
	)
	(segment
		(start 438.96788 -16.389858)
		(end 438.774586 -16.583152)
		(width 0.089408)
		(layer "In11.Cu")
		(net "SMB_SENSOR_STBY_LVC3_SCL")
	)
	(segment
		(start 368.977672 -147.183348)
		(end 370.351812 -145.809208)
		(width 0.089408)
		(layer "In11.Cu")
		(net "SMB_SENSOR_STBY_LVC3_SCL")
	)
	(segment
		(start 346.714064 -138.548364)
		(end 351.322894 -138.548364)
		(width 0.089408)
		(layer "In11.Cu")
		(net "SMB_SENSOR_STBY_LVC3_SCL")
	)
	(segment
		(start 372.161054 -146.94408)
		(end 378.24664 -146.94408)
		(width 0.089408)
		(layer "In11.Cu")
		(net "SMB_SENSOR_STBY_LVC3_SCL")
	)
	(segment
		(start 402.59762 -154.368754)
		(end 404.550626 -156.32176)
		(width 0.089408)
		(layer "In11.Cu")
		(net "SMB_SENSOR_STBY_LVC3_SCL")
	)
	(segment
		(start 395.07414 -150.749508)
		(end 395.693138 -151.368506)
		(width 0.089408)
		(layer "In11.Cu")
		(net "SMB_SENSOR_STBY_LVC3_SCL")
	)
	(segment
		(start 400.321018 -154.368754)
		(end 402.59762 -154.368754)
		(width 0.089408)
		(layer "In11.Cu")
		(net "SMB_SENSOR_STBY_LVC3_SCL")
	)
	(segment
		(start 398.412716 -152.01773)
		(end 398.412716 -152.900126)
		(width 0.089408)
		(layer "In11.Cu")
		(net "SMB_SENSOR_STBY_LVC3_SCL")
	)
	(segment
		(start 432.511708 -16.583152)
		(end 432.323494 -16.771366)
		(width 0.089408)
		(layer "In11.Cu")
		(net "SMB_SENSOR_STBY_LVC3_SCL")
	)
	(segment
		(start 378.24664 -146.94408)
		(end 379.0188 -147.71624)
		(width 0.089408)
		(layer "In11.Cu")
		(net "SMB_SENSOR_STBY_LVC3_SCL")
	)
	(segment
		(start 404.550626 -156.32176)
		(end 404.550626 -156.955744)
		(width 0.089408)
		(layer "In11.Cu")
		(net "SMB_SENSOR_STBY_LVC3_SCL")
	)
	(segment
		(start 395.693138 -151.368506)
		(end 397.763492 -151.368506)
		(width 0.089408)
		(layer "In11.Cu")
		(net "SMB_SENSOR_STBY_LVC3_SCL")
	)
	(segment
		(start 446.099184 -14.594332)
		(end 445.209168 -15.484348)
		(width 0.089408)
		(layer "In11.Cu")
		(net "SMB_SENSOR_STBY_LVC3_SCL")
	)
	(segment
		(start 454.54189 -8.053832)
		(end 453.04202 -9.553702)
		(width 0.089408)
		(layer "In11.Cu")
		(net "SMB_SENSOR_STBY_LVC3_SCL")
	)
	(segment
		(start 443.59449 -16.389858)
		(end 438.96788 -16.389858)
		(width 0.089408)
		(layer "In11.Cu")
		(net "SMB_SENSOR_STBY_LVC3_SCL")
	)
	(segment
		(start 346.082112 -139.180316)
		(end 346.714064 -138.548364)
		(width 0.089408)
		(layer "In11.Cu")
		(net "SMB_SENSOR_STBY_LVC3_SCL")
	)
	(segment
		(start 352.884486 -140.109956)
		(end 359.37444 -140.109956)
		(width 0.089408)
		(layer "In11.Cu")
		(net "SMB_SENSOR_STBY_LVC3_SCL")
	)
	(segment
		(start 457.793598 -8.053832)
		(end 454.54189 -8.053832)
		(width 0.089408)
		(layer "In11.Cu")
		(net "SMB_SENSOR_STBY_LVC3_SCL")
	)
	(segment
		(start 361.490514 -140.873734)
		(end 362.952538 -142.335758)
		(width 0.089408)
		(layer "In11.Cu")
		(net "SMB_SENSOR_STBY_LVC3_SCL")
	)
	(segment
		(start 362.952538 -143.148558)
		(end 366.987328 -147.183348)
		(width 0.089408)
		(layer "In11.Cu")
		(net "SMB_SENSOR_STBY_LVC3_SCL")
	)
	(segment
		(start 446.132458 -14.594332)
		(end 446.099184 -14.594332)
		(width 0.089408)
		(layer "In11.Cu")
		(net "SMB_SENSOR_STBY_LVC3_SCL")
	)
	(segment
		(start 438.774586 -16.583152)
		(end 432.511708 -16.583152)
		(width 0.089408)
		(layer "In11.Cu")
		(net "SMB_SENSOR_STBY_LVC3_SCL")
	)
	(segment
		(start 404.550626 -156.955744)
		(end 404.753826 -157.158944)
		(width 0.089408)
		(layer "In11.Cu")
		(net "SMB_SENSOR_STBY_LVC3_SCL")
	)
	(segment
		(start 389.887968 -150.749508)
		(end 395.07414 -150.749508)
		(width 0.089408)
		(layer "In11.Cu")
		(net "SMB_SENSOR_STBY_LVC3_SCL")
	)
	(segment
		(start 370.351812 -145.809208)
		(end 371.026182 -145.809208)
		(width 0.089408)
		(layer "In11.Cu")
		(net "SMB_SENSOR_STBY_LVC3_SCL")
	)
	(segment
		(start 397.763492 -151.368506)
		(end 398.412716 -152.01773)
		(width 0.089408)
		(layer "In11.Cu")
		(net "SMB_SENSOR_STBY_LVC3_SCL")
	)
	(segment
		(start 385.30276 -147.71624)
		(end 386.894832 -149.308312)
		(width 0.089408)
		(layer "In11.Cu")
		(net "SMB_SENSOR_STBY_LVC3_SCL")
	)
	(segment
		(start 459.010258 -6.837172)
		(end 457.793598 -8.053832)
		(width 0.089408)
		(layer "In11.Cu")
		(net "SMB_SENSOR_STBY_LVC3_SCL")
	)
	(segment
		(start 453.04202 -9.687306)
		(end 451.976236 -10.75309)
		(width 0.089408)
		(layer "In11.Cu")
		(net "SMB_SENSOR_STBY_LVC3_SCL")
	)
	(segment
		(start 386.894832 -149.308312)
		(end 388.446772 -149.308312)
		(width 0.089408)
		(layer "In11.Cu")
		(net "SMB_SENSOR_STBY_LVC3_SCL")
	)
	(segment
		(start 423.341546 -16.771366)
		(end 422.7449 -17.368012)
		(width 0.089408)
		(layer "In11.Cu")
		(net "SMB_SENSOR_STBY_LVC3_SCL")
	)
	(segment
		(start 379.0188 -147.71624)
		(end 385.30276 -147.71624)
		(width 0.089408)
		(layer "In11.Cu")
		(net "SMB_SENSOR_STBY_LVC3_SCL")
	)
	(segment
		(start 398.412716 -152.900126)
		(end 398.760696 -153.248106)
		(width 0.089408)
		(layer "In11.Cu")
		(net "SMB_SENSOR_STBY_LVC3_SCL")
	)
	(segment
		(start 360.138218 -140.873734)
		(end 361.490514 -140.873734)
		(width 0.089408)
		(layer "In11.Cu")
		(net "SMB_SENSOR_STBY_LVC3_SCL")
	)
	(segment
		(start 453.04202 -9.553702)
		(end 453.04202 -9.687306)
		(width 0.089408)
		(layer "In11.Cu")
		(net "SMB_SENSOR_STBY_LVC3_SCL")
	)
	(segment
		(start 422.7449 -17.368012)
		(end 422.7449 -17.770348)
		(width 0.089408)
		(layer "In11.Cu")
		(net "SMB_SENSOR_STBY_LVC3_SCL")
	)
	(segment
		(start 417.785296 -24.940514)
		(end 417.785296 -23.903432)
		(width 0.10795)
		(layer "F.Cu")
		(net "SMB_SENSOR_BMC_STBY_LVC3_SDA")
	)
	(segment
		(start 418.589714 -19.937984)
		(end 418.589714 -19.75485)
		(width 0.10795)
		(layer "F.Cu")
		(net "SMB_SENSOR_BMC_STBY_LVC3_SDA")
	)
	(segment
		(start 417.490148 -26.534618)
		(end 417.490148 -25.235662)
		(width 0.10795)
		(layer "F.Cu")
		(net "SMB_SENSOR_BMC_STBY_LVC3_SDA")
	)
	(segment
		(start 420.1414 -18.7452)
		(end 420.1414 -19.329146)
		(width 0.10795)
		(layer "F.Cu")
		(net "SMB_SENSOR_BMC_STBY_LVC3_SDA")
	)
	(segment
		(start 420.1414 -19.329146)
		(end 420.587678 -19.775424)
		(width 0.10795)
		(layer "F.Cu")
		(net "SMB_SENSOR_BMC_STBY_LVC3_SDA")
	)
	(segment
		(start 419.354 -19.5326)
		(end 420.1414 -18.7452)
		(width 0.10795)
		(layer "F.Cu")
		(net "SMB_SENSOR_BMC_STBY_LVC3_SDA")
	)
	(segment
		(start 418.811964 -19.5326)
		(end 419.354 -19.5326)
		(width 0.10795)
		(layer "F.Cu")
		(net "SMB_SENSOR_BMC_STBY_LVC3_SDA")
	)
	(segment
		(start 417.95065 -23.735538)
		(end 418.084 -23.602188)
		(width 0.10795)
		(layer "F.Cu")
		(net "SMB_SENSOR_BMC_STBY_LVC3_SDA")
	)
	(segment
		(start 417.95065 -23.738078)
		(end 417.95065 -23.735538)
		(width 0.10795)
		(layer "F.Cu")
		(net "SMB_SENSOR_BMC_STBY_LVC3_SDA")
	)
	(segment
		(start 418.084 -23.602188)
		(end 418.084 -20.443698)
		(width 0.10795)
		(layer "F.Cu")
		(net "SMB_SENSOR_BMC_STBY_LVC3_SDA")
	)
	(segment
		(start 418.084 -20.443698)
		(end 418.589714 -19.937984)
		(width 0.10795)
		(layer "F.Cu")
		(net "SMB_SENSOR_BMC_STBY_LVC3_SDA")
	)
	(segment
		(start 418.589714 -19.75485)
		(end 418.811964 -19.5326)
		(width 0.10795)
		(layer "F.Cu")
		(net "SMB_SENSOR_BMC_STBY_LVC3_SDA")
	)
	(segment
		(start 420.587678 -19.775424)
		(end 420.811198 -19.775424)
		(width 0.10795)
		(layer "F.Cu")
		(net "SMB_SENSOR_BMC_STBY_LVC3_SDA")
	)
	(segment
		(start 417.490148 -25.235662)
		(end 417.785296 -24.940514)
		(width 0.10795)
		(layer "F.Cu")
		(net "SMB_SENSOR_BMC_STBY_LVC3_SDA")
	)
	(segment
		(start 417.785296 -23.903432)
		(end 417.95065 -23.738078)
		(width 0.10795)
		(layer "F.Cu")
		(net "SMB_SENSOR_BMC_STBY_LVC3_SDA")
	)
	(via
		(at 420.811198 -19.775424)
		(size 0.762)
		(drill 0.381)
		(layers "F.Cu" "B.Cu")
		(net "SMB_SENSOR_BMC_STBY_LVC3_SDA")
	)
	(segment
		(start 418.75075 -19.27225)
		(end 418.478208 -19.27225)
		(width 0.10795)
		(layer "F.Cu")
		(net "SMB_SENSOR_BMC_STBY_LVC3_SCL")
	)
	(segment
		(start 417.976812 -19.773646)
		(end 417.76523 -19.985228)
		(width 0.10795)
		(layer "F.Cu")
		(net "SMB_SENSOR_BMC_STBY_LVC3_SCL")
	)
	(segment
		(start 417.273232 -19.985228)
		(end 416.659314 -20.599146)
		(width 0.10795)
		(layer "F.Cu")
		(net "SMB_SENSOR_BMC_STBY_LVC3_SCL")
	)
	(segment
		(start 416.553142 -26.397712)
		(end 416.690048 -26.534618)
		(width 0.10795)
		(layer "F.Cu")
		(net "SMB_SENSOR_BMC_STBY_LVC3_SCL")
	)
	(segment
		(start 419.3032 -18.7452)
		(end 419.2778 -18.7452)
		(width 0.10795)
		(layer "F.Cu")
		(net "SMB_SENSOR_BMC_STBY_LVC3_SCL")
	)
	(segment
		(start 415.74339 -24.157178)
		(end 415.74339 -25.062434)
		(width 0.10795)
		(layer "F.Cu")
		(net "SMB_SENSOR_BMC_STBY_LVC3_SCL")
	)
	(segment
		(start 415.74339 -25.062434)
		(end 416.553142 -25.872186)
		(width 0.10795)
		(layer "F.Cu")
		(net "SMB_SENSOR_BMC_STBY_LVC3_SCL")
	)
	(segment
		(start 417.76523 -19.985228)
		(end 417.273232 -19.985228)
		(width 0.10795)
		(layer "F.Cu")
		(net "SMB_SENSOR_BMC_STBY_LVC3_SCL")
	)
	(segment
		(start 416.659314 -20.599146)
		(end 416.659314 -23.241254)
		(width 0.10795)
		(layer "F.Cu")
		(net "SMB_SENSOR_BMC_STBY_LVC3_SCL")
	)
	(segment
		(start 418.478208 -19.27225)
		(end 417.976812 -19.773646)
		(width 0.10795)
		(layer "F.Cu")
		(net "SMB_SENSOR_BMC_STBY_LVC3_SCL")
	)
	(segment
		(start 416.659314 -23.241254)
		(end 415.74339 -24.157178)
		(width 0.10795)
		(layer "F.Cu")
		(net "SMB_SENSOR_BMC_STBY_LVC3_SCL")
	)
	(segment
		(start 416.553142 -25.872186)
		(end 416.553142 -26.397712)
		(width 0.10795)
		(layer "F.Cu")
		(net "SMB_SENSOR_BMC_STBY_LVC3_SCL")
	)
	(segment
		(start 419.2778 -18.7452)
		(end 418.75075 -19.27225)
		(width 0.10795)
		(layer "F.Cu")
		(net "SMB_SENSOR_BMC_STBY_LVC3_SCL")
	)
	(via
		(at 417.976812 -19.773646)
		(size 0.762)
		(drill 0.381)
		(layers "F.Cu" "B.Cu")
		(net "SMB_SENSOR_BMC_STBY_LVC3_SCL")
	)
	(segment
		(start 390.70915 -102.12832)
		(end 391.20445 -101.898196)
		(width 0.10795)
		(layer "F.Cu")
		(net "SMB_LAN_STBY_LVC3_SDA_R2")
	)
	(via
		(at 391.20445 -101.898196)
		(size 0.508)
		(drill 0.254)
		(layers "F.Cu" "B.Cu")
		(net "SMB_LAN_STBY_LVC3_SDA_R2")
	)
	(via
		(at 391.2362 -94.4372)
		(size 0.6604)
		(drill 0.3302)
		(layers "F.Cu" "B.Cu")
		(net "SMB_LAN_STBY_LVC3_SDA_R2")
	)
	(segment
		(start 390.748266 -96.545146)
		(end 391.1092 -96.184212)
		(width 0.0889)
		(layer "B.Cu")
		(net "SMB_LAN_STBY_LVC3_SDA_R2")
	)
	(segment
		(start 394.800582 -89.211658)
		(end 394.800582 -88.552274)
		(width 0.10795)
		(layer "B.Cu")
		(net "SMB_LAN_STBY_LVC3_SDA_R2")
	)
	(segment
		(start 391.235946 -91.66225)
		(end 391.235946 -91.446858)
		(width 0.10795)
		(layer "B.Cu")
		(net "SMB_LAN_STBY_LVC3_SDA_R2")
	)
	(segment
		(start 391.20445 -101.898196)
		(end 391.20445 -100.92055)
		(width 0.0889)
		(layer "B.Cu")
		(net "SMB_LAN_STBY_LVC3_SDA_R2")
	)
	(segment
		(start 391.612628 -98.832416)
		(end 391.612628 -98.095816)
		(width 0.0889)
		(layer "B.Cu")
		(net "SMB_LAN_STBY_LVC3_SDA_R2")
	)
	(segment
		(start 391.291572 -99.153472)
		(end 391.612628 -98.832416)
		(width 0.0889)
		(layer "B.Cu")
		(net "SMB_LAN_STBY_LVC3_SDA_R2")
	)
	(segment
		(start 391.291572 -99.4918)
		(end 391.291572 -99.153472)
		(width 0.0889)
		(layer "B.Cu")
		(net "SMB_LAN_STBY_LVC3_SDA_R2")
	)
	(segment
		(start 394.589 -88.340692)
		(end 394.589 -88.2015)
		(width 0.10795)
		(layer "B.Cu")
		(net "SMB_LAN_STBY_LVC3_SDA_R2")
	)
	(segment
		(start 391.235946 -91.446858)
		(end 391.854182 -90.828622)
		(width 0.10795)
		(layer "B.Cu")
		(net "SMB_LAN_STBY_LVC3_SDA_R2")
	)
	(segment
		(start 391.1092 -96.184212)
		(end 391.1092 -95.49384)
		(width 0.0889)
		(layer "B.Cu")
		(net "SMB_LAN_STBY_LVC3_SDA_R2")
	)
	(segment
		(start 391.2362 -94.4372)
		(end 391.2362 -91.662504)
		(width 0.10795)
		(layer "B.Cu")
		(net "SMB_LAN_STBY_LVC3_SDA_R2")
	)
	(segment
		(start 391.668 -100.457)
		(end 391.668 -99.868228)
		(width 0.0889)
		(layer "B.Cu")
		(net "SMB_LAN_STBY_LVC3_SDA_R2")
	)
	(segment
		(start 391.668 -99.868228)
		(end 391.291572 -99.4918)
		(width 0.0889)
		(layer "B.Cu")
		(net "SMB_LAN_STBY_LVC3_SDA_R2")
	)
	(segment
		(start 391.287 -97.770188)
		(end 391.287 -97.536)
		(width 0.0889)
		(layer "B.Cu")
		(net "SMB_LAN_STBY_LVC3_SDA_R2")
	)
	(segment
		(start 391.1092 -94.996)
		(end 391.2362 -94.869)
		(width 0.10795)
		(layer "B.Cu")
		(net "SMB_LAN_STBY_LVC3_SDA_R2")
	)
	(segment
		(start 391.20445 -100.92055)
		(end 391.668 -100.457)
		(width 0.0889)
		(layer "B.Cu")
		(net "SMB_LAN_STBY_LVC3_SDA_R2")
	)
	(segment
		(start 392.793474 -90.828622)
		(end 393.460224 -90.161872)
		(width 0.10795)
		(layer "B.Cu")
		(net "SMB_LAN_STBY_LVC3_SDA_R2")
	)
	(segment
		(start 391.1092 -95.49384)
		(end 391.1092 -94.996)
		(width 0.10795)
		(layer "B.Cu")
		(net "SMB_LAN_STBY_LVC3_SDA_R2")
	)
	(segment
		(start 394.800582 -88.552274)
		(end 394.589 -88.340692)
		(width 0.10795)
		(layer "B.Cu")
		(net "SMB_LAN_STBY_LVC3_SDA_R2")
	)
	(segment
		(start 391.2362 -91.662504)
		(end 391.235946 -91.66225)
		(width 0.10795)
		(layer "B.Cu")
		(net "SMB_LAN_STBY_LVC3_SDA_R2")
	)
	(segment
		(start 393.850368 -90.161872)
		(end 394.800582 -89.211658)
		(width 0.10795)
		(layer "B.Cu")
		(net "SMB_LAN_STBY_LVC3_SDA_R2")
	)
	(segment
		(start 391.2362 -94.869)
		(end 391.2362 -94.4372)
		(width 0.10795)
		(layer "B.Cu")
		(net "SMB_LAN_STBY_LVC3_SDA_R2")
	)
	(segment
		(start 393.460224 -90.161872)
		(end 393.850368 -90.161872)
		(width 0.10795)
		(layer "B.Cu")
		(net "SMB_LAN_STBY_LVC3_SDA_R2")
	)
	(segment
		(start 391.854182 -90.828622)
		(end 392.793474 -90.828622)
		(width 0.10795)
		(layer "B.Cu")
		(net "SMB_LAN_STBY_LVC3_SDA_R2")
	)
	(segment
		(start 391.612628 -98.095816)
		(end 391.287 -97.770188)
		(width 0.0889)
		(layer "B.Cu")
		(net "SMB_LAN_STBY_LVC3_SDA_R2")
	)
	(arc
		(start 391.004552 -97.093786)
		(mid 390.897688 -97.004105)
		(end 390.828022 -96.88322)
		(width 0.0889)
		(layer "B.Cu")
		(net "SMB_LAN_STBY_LVC3_SDA_R2")
	)
	(arc
		(start 390.828022 -96.88322)
		(mid 390.762699 -96.720187)
		(end 390.748266 -96.545146)
		(width 0.0889)
		(layer "B.Cu")
		(net "SMB_LAN_STBY_LVC3_SDA_R2")
	)
	(arc
		(start 391.287 -97.536)
		(mid 391.199829 -97.280358)
		(end 391.004552 -97.093786)
		(width 0.0889)
		(layer "B.Cu")
		(net "SMB_LAN_STBY_LVC3_SDA_R2")
	)
	(segment
		(start 390.70915 -96.9772)
		(end 391.20445 -96.747076)
		(width 0.10795)
		(layer "F.Cu")
		(net "SMB_LAN_STBY_LVC3_SCL_R2")
	)
	(via
		(at 392.087354 -93.66377)
		(size 0.6604)
		(drill 0.3302)
		(layers "F.Cu" "B.Cu")
		(net "SMB_LAN_STBY_LVC3_SCL_R2")
	)
	(via
		(at 391.20445 -96.747076)
		(size 0.508)
		(drill 0.254)
		(layers "F.Cu" "B.Cu")
		(net "SMB_LAN_STBY_LVC3_SCL_R2")
	)
	(segment
		(start 391.571226 -96.3803)
		(end 391.766044 -96.3803)
		(width 0.0889)
		(layer "B.Cu")
		(net "SMB_LAN_STBY_LVC3_SCL_R2")
	)
	(segment
		(start 395.351 -88.993726)
		(end 395.351 -88.2015)
		(width 0.10795)
		(layer "B.Cu")
		(net "SMB_LAN_STBY_LVC3_SCL_R2")
	)
	(segment
		(start 391.49655 -91.554554)
		(end 391.973054 -91.07805)
		(width 0.10795)
		(layer "B.Cu")
		(net "SMB_LAN_STBY_LVC3_SCL_R2")
	)
	(segment
		(start 391.49655 -93.072966)
		(end 391.49655 -91.554554)
		(width 0.10795)
		(layer "B.Cu")
		(net "SMB_LAN_STBY_LVC3_SCL_R2")
	)
	(segment
		(start 392.087354 -94.946978)
		(end 392.087354 -93.66377)
		(width 0.10795)
		(layer "B.Cu")
		(net "SMB_LAN_STBY_LVC3_SCL_R2")
	)
	(segment
		(start 392.087354 -93.66377)
		(end 391.49655 -93.072966)
		(width 0.10795)
		(layer "B.Cu")
		(net "SMB_LAN_STBY_LVC3_SCL_R2")
	)
	(segment
		(start 392.1506 -95.995744)
		(end 392.1506 -95.264224)
		(width 0.0889)
		(layer "B.Cu")
		(net "SMB_LAN_STBY_LVC3_SCL_R2")
	)
	(segment
		(start 391.766044 -96.3803)
		(end 392.1506 -95.995744)
		(width 0.0889)
		(layer "B.Cu")
		(net "SMB_LAN_STBY_LVC3_SCL_R2")
	)
	(segment
		(start 392.887454 -91.07805)
		(end 393.500102 -90.465402)
		(width 0.10795)
		(layer "B.Cu")
		(net "SMB_LAN_STBY_LVC3_SCL_R2")
	)
	(segment
		(start 392.1506 -95.264224)
		(end 392.087354 -95.200978)
		(width 0.0889)
		(layer "B.Cu")
		(net "SMB_LAN_STBY_LVC3_SCL_R2")
	)
	(segment
		(start 392.087354 -95.200978)
		(end 392.087354 -94.946978)
		(width 0.0889)
		(layer "B.Cu")
		(net "SMB_LAN_STBY_LVC3_SCL_R2")
	)
	(segment
		(start 393.879324 -90.465402)
		(end 395.351 -88.993726)
		(width 0.10795)
		(layer "B.Cu")
		(net "SMB_LAN_STBY_LVC3_SCL_R2")
	)
	(segment
		(start 391.20445 -96.747076)
		(end 391.571226 -96.3803)
		(width 0.0889)
		(layer "B.Cu")
		(net "SMB_LAN_STBY_LVC3_SCL_R2")
	)
	(segment
		(start 391.973054 -91.07805)
		(end 392.887454 -91.07805)
		(width 0.10795)
		(layer "B.Cu")
		(net "SMB_LAN_STBY_LVC3_SCL_R2")
	)
	(segment
		(start 393.500102 -90.465402)
		(end 393.879324 -90.465402)
		(width 0.10795)
		(layer "B.Cu")
		(net "SMB_LAN_STBY_LVC3_SCL_R2")
	)
	(segment
		(start 423.18559 -127.74041)
		(end 420.779194 -127.74041)
		(width 0.10795)
		(layer "F.Cu")
		(net "SMB_HFI1_CPU0_LVC2_SDA")
	)
	(segment
		(start 424.920918 -125.6792)
		(end 424.728386 -125.486668)
		(width 0.10795)
		(layer "F.Cu")
		(net "SMB_HFI1_CPU0_LVC2_SDA")
	)
	(segment
		(start 288.36366 -74.725784)
		(end 288.93516 -74.725784)
		(width 0.1016)
		(layer "F.Cu")
		(net "SMB_HFI1_CPU0_LVC2_SDA")
	)
	(segment
		(start 425.6151 -125.6792)
		(end 424.920918 -125.6792)
		(width 0.10795)
		(layer "F.Cu")
		(net "SMB_HFI1_CPU0_LVC2_SDA")
	)
	(segment
		(start 424.00855 -126.91745)
		(end 423.18559 -127.74041)
		(width 0.10795)
		(layer "F.Cu")
		(net "SMB_HFI1_CPU0_LVC2_SDA")
	)
	(segment
		(start 424.00855 -126.206504)
		(end 424.00855 -126.91745)
		(width 0.10795)
		(layer "F.Cu")
		(net "SMB_HFI1_CPU0_LVC2_SDA")
	)
	(segment
		(start 424.728386 -125.486668)
		(end 424.00855 -126.206504)
		(width 0.10795)
		(layer "F.Cu")
		(net "SMB_HFI1_CPU0_LVC2_SDA")
	)
	(via
		(at 336.216752 -73.71207)
		(size 0.508)
		(drill 0.254)
		(layers "F.Cu" "B.Cu")
		(net "SMB_HFI1_CPU0_LVC2_SDA")
	)
	(via
		(at 410.8704 -157.4292)
		(size 0.508)
		(drill 0.254)
		(layers "F.Cu" "B.Cu")
		(net "SMB_HFI1_CPU0_LVC2_SDA")
	)
	(via
		(at 424.728386 -125.486668)
		(size 0.508)
		(drill 0.254)
		(layers "F.Cu" "B.Cu")
		(net "SMB_HFI1_CPU0_LVC2_SDA")
	)
	(via
		(at 288.93516 -74.725784)
		(size 0.508)
		(drill 0.254)
		(layers "F.Cu" "B.Cu")
		(net "SMB_HFI1_CPU0_LVC2_SDA")
	)
	(via
		(at 324.946772 -138.483848)
		(size 0.508)
		(drill 0.254)
		(layers "F.Cu" "B.Cu")
		(net "SMB_HFI1_CPU0_LVC2_SDA")
	)
	(via
		(at 328.95286 -147.15744)
		(size 0.508)
		(drill 0.254)
		(layers "F.Cu" "B.Cu")
		(net "SMB_HFI1_CPU0_LVC2_SDA")
	)
	(segment
		(start 325.355712 -139.007088)
		(end 326.2884 -138.0744)
		(width 0.089408)
		(layer "In2.Cu")
		(net "SMB_HFI1_CPU0_LVC2_SDA")
	)
	(segment
		(start 324.946772 -138.483848)
		(end 324.946772 -138.86688)
		(width 0.089408)
		(layer "In2.Cu")
		(net "SMB_HFI1_CPU0_LVC2_SDA")
	)
	(segment
		(start 326.2884 -138.0744)
		(end 327.9902 -138.0744)
		(width 0.089408)
		(layer "In2.Cu")
		(net "SMB_HFI1_CPU0_LVC2_SDA")
	)
	(segment
		(start 324.946772 -138.86688)
		(end 325.08698 -139.007088)
		(width 0.089408)
		(layer "In2.Cu")
		(net "SMB_HFI1_CPU0_LVC2_SDA")
	)
	(segment
		(start 325.08698 -139.007088)
		(end 325.355712 -139.007088)
		(width 0.089408)
		(layer "In2.Cu")
		(net "SMB_HFI1_CPU0_LVC2_SDA")
	)
	(segment
		(start 328.95286 -139.03706)
		(end 328.95286 -147.15744)
		(width 0.089408)
		(layer "In2.Cu")
		(net "SMB_HFI1_CPU0_LVC2_SDA")
	)
	(segment
		(start 327.9902 -138.0744)
		(end 328.95286 -139.03706)
		(width 0.089408)
		(layer "In2.Cu")
		(net "SMB_HFI1_CPU0_LVC2_SDA")
	)
	(segment
		(start 334.499204 -76.7715)
		(end 334.499204 -75.163934)
		(width 0.089408)
		(layer "In4.Cu")
		(net "SMB_HFI1_CPU0_LVC2_SDA")
	)
	(segment
		(start 324.990714 -92.165424)
		(end 332.042008 -85.11413)
		(width 0.089408)
		(layer "In4.Cu")
		(net "SMB_HFI1_CPU0_LVC2_SDA")
	)
	(segment
		(start 326.183498 -133.3754)
		(end 329.956922 -133.3754)
		(width 0.089408)
		(layer "In4.Cu")
		(net "SMB_HFI1_CPU0_LVC2_SDA")
	)
	(segment
		(start 326.216772 -122.726196)
		(end 326.216772 -118.292372)
		(width 0.089408)
		(layer "In4.Cu")
		(net "SMB_HFI1_CPU0_LVC2_SDA")
	)
	(segment
		(start 330.994512 -132.33781)
		(end 330.994512 -129.818892)
		(width 0.089408)
		(layer "In4.Cu")
		(net "SMB_HFI1_CPU0_LVC2_SDA")
	)
	(segment
		(start 324.990714 -115.180364)
		(end 324.990714 -92.165424)
		(width 0.089408)
		(layer "In4.Cu")
		(net "SMB_HFI1_CPU0_LVC2_SDA")
	)
	(segment
		(start 332.042008 -85.11413)
		(end 332.042008 -82.58937)
		(width 0.089408)
		(layer "In4.Cu")
		(net "SMB_HFI1_CPU0_LVC2_SDA")
	)
	(segment
		(start 334.499204 -75.163934)
		(end 335.951068 -73.71207)
		(width 0.089408)
		(layer "In4.Cu")
		(net "SMB_HFI1_CPU0_LVC2_SDA")
	)
	(segment
		(start 327.5076 -124.017024)
		(end 326.216772 -122.726196)
		(width 0.089408)
		(layer "In4.Cu")
		(net "SMB_HFI1_CPU0_LVC2_SDA")
	)
	(segment
		(start 330.994512 -129.818892)
		(end 327.5076 -126.33198)
		(width 0.089408)
		(layer "In4.Cu")
		(net "SMB_HFI1_CPU0_LVC2_SDA")
	)
	(segment
		(start 325.790052 -115.979702)
		(end 324.990714 -115.180364)
		(width 0.089408)
		(layer "In4.Cu")
		(net "SMB_HFI1_CPU0_LVC2_SDA")
	)
	(segment
		(start 335.078324 -79.553054)
		(end 335.078324 -77.35062)
		(width 0.089408)
		(layer "In4.Cu")
		(net "SMB_HFI1_CPU0_LVC2_SDA")
	)
	(segment
		(start 325.5264 -136.7028)
		(end 325.0184 -136.1948)
		(width 0.089408)
		(layer "In4.Cu")
		(net "SMB_HFI1_CPU0_LVC2_SDA")
	)
	(segment
		(start 326.216772 -118.292372)
		(end 325.790052 -117.865652)
		(width 0.089408)
		(layer "In4.Cu")
		(net "SMB_HFI1_CPU0_LVC2_SDA")
	)
	(segment
		(start 324.946772 -138.483848)
		(end 324.946772 -138.187938)
		(width 0.089408)
		(layer "In4.Cu")
		(net "SMB_HFI1_CPU0_LVC2_SDA")
	)
	(segment
		(start 335.951068 -73.71207)
		(end 336.216752 -73.71207)
		(width 0.089408)
		(layer "In4.Cu")
		(net "SMB_HFI1_CPU0_LVC2_SDA")
	)
	(segment
		(start 325.0184 -136.1948)
		(end 325.0184 -134.540498)
		(width 0.089408)
		(layer "In4.Cu")
		(net "SMB_HFI1_CPU0_LVC2_SDA")
	)
	(segment
		(start 335.078324 -77.35062)
		(end 334.499204 -76.7715)
		(width 0.089408)
		(layer "In4.Cu")
		(net "SMB_HFI1_CPU0_LVC2_SDA")
	)
	(segment
		(start 332.042008 -82.58937)
		(end 335.078324 -79.553054)
		(width 0.089408)
		(layer "In4.Cu")
		(net "SMB_HFI1_CPU0_LVC2_SDA")
	)
	(segment
		(start 324.946772 -138.187938)
		(end 325.5264 -137.60831)
		(width 0.089408)
		(layer "In4.Cu")
		(net "SMB_HFI1_CPU0_LVC2_SDA")
	)
	(segment
		(start 329.956922 -133.3754)
		(end 330.994512 -132.33781)
		(width 0.089408)
		(layer "In4.Cu")
		(net "SMB_HFI1_CPU0_LVC2_SDA")
	)
	(segment
		(start 325.5264 -137.60831)
		(end 325.5264 -136.7028)
		(width 0.089408)
		(layer "In4.Cu")
		(net "SMB_HFI1_CPU0_LVC2_SDA")
	)
	(segment
		(start 325.0184 -134.540498)
		(end 326.183498 -133.3754)
		(width 0.089408)
		(layer "In4.Cu")
		(net "SMB_HFI1_CPU0_LVC2_SDA")
	)
	(segment
		(start 325.790052 -117.865652)
		(end 325.790052 -115.979702)
		(width 0.089408)
		(layer "In4.Cu")
		(net "SMB_HFI1_CPU0_LVC2_SDA")
	)
	(segment
		(start 327.5076 -126.33198)
		(end 327.5076 -124.017024)
		(width 0.089408)
		(layer "In4.Cu")
		(net "SMB_HFI1_CPU0_LVC2_SDA")
	)
	(segment
		(start 432.303428 -154.369262)
		(end 434.779674 -154.369262)
		(width 0.089408)
		(layer "In9.Cu")
		(net "SMB_HFI1_CPU0_LVC2_SDA")
	)
	(segment
		(start 446.861184 -147.09648)
		(end 446.861184 -144.577816)
		(width 0.089408)
		(layer "In9.Cu")
		(net "SMB_HFI1_CPU0_LVC2_SDA")
	)
	(segment
		(start 437.51627 -128.130808)
		(end 436.174388 -128.130808)
		(width 0.089408)
		(layer "In9.Cu")
		(net "SMB_HFI1_CPU0_LVC2_SDA")
	)
	(segment
		(start 444.624714 -135.155686)
		(end 437.820816 -128.351788)
		(width 0.089408)
		(layer "In9.Cu")
		(net "SMB_HFI1_CPU0_LVC2_SDA")
	)
	(segment
		(start 435.764686 -155.354274)
		(end 446.064386 -155.354274)
		(width 0.089408)
		(layer "In9.Cu")
		(net "SMB_HFI1_CPU0_LVC2_SDA")
	)
	(segment
		(start 447.52133 -152.012904)
		(end 448.684904 -150.84933)
		(width 0.089408)
		(layer "In9.Cu")
		(net "SMB_HFI1_CPU0_LVC2_SDA")
	)
	(segment
		(start 437.736234 -128.350772)
		(end 437.51627 -128.130808)
		(width 0.089408)
		(layer "In9.Cu")
		(net "SMB_HFI1_CPU0_LVC2_SDA")
	)
	(segment
		(start 424.841416 -125.599698)
		(end 424.728386 -125.486668)
		(width 0.089408)
		(layer "In9.Cu")
		(net "SMB_HFI1_CPU0_LVC2_SDA")
	)
	(segment
		(start 448.551808 -140.158724)
		(end 448.551808 -136.413748)
		(width 0.089408)
		(layer "In9.Cu")
		(net "SMB_HFI1_CPU0_LVC2_SDA")
	)
	(segment
		(start 448.684904 -150.84933)
		(end 448.684904 -148.9202)
		(width 0.089408)
		(layer "In9.Cu")
		(net "SMB_HFI1_CPU0_LVC2_SDA")
	)
	(segment
		(start 410.8704 -157.4292)
		(end 411.696662 -157.4292)
		(width 0.089408)
		(layer "In9.Cu")
		(net "SMB_HFI1_CPU0_LVC2_SDA")
	)
	(segment
		(start 448.551808 -136.413748)
		(end 447.293746 -135.155686)
		(width 0.089408)
		(layer "In9.Cu")
		(net "SMB_HFI1_CPU0_LVC2_SDA")
	)
	(segment
		(start 447.864992 -143.574008)
		(end 447.864992 -140.84554)
		(width 0.089408)
		(layer "In9.Cu")
		(net "SMB_HFI1_CPU0_LVC2_SDA")
	)
	(segment
		(start 447.293746 -135.155686)
		(end 444.624714 -135.155686)
		(width 0.089408)
		(layer "In9.Cu")
		(net "SMB_HFI1_CPU0_LVC2_SDA")
	)
	(segment
		(start 447.52133 -153.89733)
		(end 447.52133 -152.012904)
		(width 0.089408)
		(layer "In9.Cu")
		(net "SMB_HFI1_CPU0_LVC2_SDA")
	)
	(segment
		(start 446.861184 -144.577816)
		(end 447.864992 -143.574008)
		(width 0.089408)
		(layer "In9.Cu")
		(net "SMB_HFI1_CPU0_LVC2_SDA")
	)
	(segment
		(start 448.684904 -148.9202)
		(end 446.861184 -147.09648)
		(width 0.089408)
		(layer "In9.Cu")
		(net "SMB_HFI1_CPU0_LVC2_SDA")
	)
	(segment
		(start 436.174388 -128.130808)
		(end 433.643278 -125.599698)
		(width 0.089408)
		(layer "In9.Cu")
		(net "SMB_HFI1_CPU0_LVC2_SDA")
	)
	(segment
		(start 411.696662 -157.4292)
		(end 411.868874 -157.601412)
		(width 0.089408)
		(layer "In9.Cu")
		(net "SMB_HFI1_CPU0_LVC2_SDA")
	)
	(segment
		(start 446.064386 -155.354274)
		(end 447.52133 -153.89733)
		(width 0.089408)
		(layer "In9.Cu")
		(net "SMB_HFI1_CPU0_LVC2_SDA")
	)
	(segment
		(start 437.820816 -128.351788)
		(end 437.741314 -128.351788)
		(width 0.089408)
		(layer "In9.Cu")
		(net "SMB_HFI1_CPU0_LVC2_SDA")
	)
	(segment
		(start 447.864992 -140.84554)
		(end 448.551808 -140.158724)
		(width 0.089408)
		(layer "In9.Cu")
		(net "SMB_HFI1_CPU0_LVC2_SDA")
	)
	(segment
		(start 429.298608 -157.601412)
		(end 430.467008 -156.433012)
		(width 0.089408)
		(layer "In9.Cu")
		(net "SMB_HFI1_CPU0_LVC2_SDA")
	)
	(segment
		(start 437.741314 -128.351788)
		(end 437.740298 -128.350772)
		(width 0.089408)
		(layer "In9.Cu")
		(net "SMB_HFI1_CPU0_LVC2_SDA")
	)
	(segment
		(start 433.643278 -125.599698)
		(end 424.841416 -125.599698)
		(width 0.089408)
		(layer "In9.Cu")
		(net "SMB_HFI1_CPU0_LVC2_SDA")
	)
	(segment
		(start 430.467008 -156.205682)
		(end 432.303428 -154.369262)
		(width 0.089408)
		(layer "In9.Cu")
		(net "SMB_HFI1_CPU0_LVC2_SDA")
	)
	(segment
		(start 430.467008 -156.433012)
		(end 430.467008 -156.205682)
		(width 0.089408)
		(layer "In9.Cu")
		(net "SMB_HFI1_CPU0_LVC2_SDA")
	)
	(segment
		(start 434.779674 -154.369262)
		(end 435.764686 -155.354274)
		(width 0.089408)
		(layer "In9.Cu")
		(net "SMB_HFI1_CPU0_LVC2_SDA")
	)
	(segment
		(start 411.868874 -157.601412)
		(end 429.298608 -157.601412)
		(width 0.089408)
		(layer "In9.Cu")
		(net "SMB_HFI1_CPU0_LVC2_SDA")
	)
	(segment
		(start 437.740298 -128.350772)
		(end 437.736234 -128.350772)
		(width 0.089408)
		(layer "In9.Cu")
		(net "SMB_HFI1_CPU0_LVC2_SDA")
	)
	(segment
		(start 328.95286 -147.15744)
		(end 329.248008 -147.452588)
		(width 0.089408)
		(layer "In11.Cu")
		(net "SMB_HFI1_CPU0_LVC2_SDA")
	)
	(segment
		(start 398.55013 -157.060392)
		(end 399.691606 -158.201868)
		(width 0.089408)
		(layer "In11.Cu")
		(net "SMB_HFI1_CPU0_LVC2_SDA")
	)
	(segment
		(start 336.216752 -73.71207)
		(end 335.783682 -73.279)
		(width 0.089408)
		(layer "In11.Cu")
		(net "SMB_HFI1_CPU0_LVC2_SDA")
	)
	(segment
		(start 329.248008 -155.730448)
		(end 328.816208 -156.162248)
		(width 0.089408)
		(layer "In11.Cu")
		(net "SMB_HFI1_CPU0_LVC2_SDA")
	)
	(segment
		(start 328.816208 -157.41396)
		(end 329.364848 -157.9626)
		(width 0.089408)
		(layer "In11.Cu")
		(net "SMB_HFI1_CPU0_LVC2_SDA")
	)
	(segment
		(start 304.406046 -73.144634)
		(end 304.370486 -73.144634)
		(width 0.0889)
		(layer "In11.Cu")
		(net "SMB_HFI1_CPU0_LVC2_SDA")
	)
	(segment
		(start 410.796994 -158.201868)
		(end 411.366208 -157.632654)
		(width 0.089408)
		(layer "In11.Cu")
		(net "SMB_HFI1_CPU0_LVC2_SDA")
	)
	(segment
		(start 302.689006 -73.144634)
		(end 302.653446 -73.144634)
		(width 0.0889)
		(layer "In11.Cu")
		(net "SMB_HFI1_CPU0_LVC2_SDA")
	)
	(segment
		(start 357.610156 -151.65832)
		(end 358.637332 -150.631144)
		(width 0.089408)
		(layer "In11.Cu")
		(net "SMB_HFI1_CPU0_LVC2_SDA")
	)
	(segment
		(start 371.231922 -157.287214)
		(end 372.170198 -158.22549)
		(width 0.089408)
		(layer "In11.Cu")
		(net "SMB_HFI1_CPU0_LVC2_SDA")
	)
	(segment
		(start 350.0374 -156.8196)
		(end 352.4758 -156.8196)
		(width 0.089408)
		(layer "In11.Cu")
		(net "SMB_HFI1_CPU0_LVC2_SDA")
	)
	(segment
		(start 290.667186 -74.135234)
		(end 290.63442 -74.135234)
		(width 0.0889)
		(layer "In11.Cu")
		(net "SMB_HFI1_CPU0_LVC2_SDA")
	)
	(segment
		(start 392.74369 -158.22549)
		(end 393.908788 -157.060392)
		(width 0.089408)
		(layer "In11.Cu")
		(net "SMB_HFI1_CPU0_LVC2_SDA")
	)
	(segment
		(start 308.364382 -73.597516)
		(end 307.877464 -74.084434)
		(width 0.0889)
		(layer "In11.Cu")
		(net "SMB_HFI1_CPU0_LVC2_SDA")
	)
	(segment
		(start 335.026 -73.279)
		(end 334.834738 -73.470262)
		(width 0.089408)
		(layer "In11.Cu")
		(net "SMB_HFI1_CPU0_LVC2_SDA")
	)
	(segment
		(start 399.691606 -158.201868)
		(end 410.796994 -158.201868)
		(width 0.089408)
		(layer "In11.Cu")
		(net "SMB_HFI1_CPU0_LVC2_SDA")
	)
	(segment
		(start 307.877464 -74.084434)
		(end 307.162962 -74.084434)
		(width 0.0889)
		(layer "In11.Cu")
		(net "SMB_HFI1_CPU0_LVC2_SDA")
	)
	(segment
		(start 411.284166 -157.393386)
		(end 410.8704 -157.4292)
		(width 0.089408)
		(layer "In11.Cu")
		(net "SMB_HFI1_CPU0_LVC2_SDA")
	)
	(segment
		(start 299.254926 -73.144634)
		(end 299.219366 -73.144634)
		(width 0.0889)
		(layer "In11.Cu")
		(net "SMB_HFI1_CPU0_LVC2_SDA")
	)
	(segment
		(start 293.238936 -72.649588)
		(end 293.20617 -72.649588)
		(width 0.0889)
		(layer "In11.Cu")
		(net "SMB_HFI1_CPU0_LVC2_SDA")
	)
	(segment
		(start 305.449986 -73.640188)
		(end 305.23561 -73.640188)
		(width 0.0889)
		(layer "In11.Cu")
		(net "SMB_HFI1_CPU0_LVC2_SDA")
	)
	(segment
		(start 300.106842 -73.640188)
		(end 300.08449 -73.640188)
		(width 0.0889)
		(layer "In11.Cu")
		(net "SMB_HFI1_CPU0_LVC2_SDA")
	)
	(segment
		(start 367.319052 -157.287214)
		(end 371.231922 -157.287214)
		(width 0.089408)
		(layer "In11.Cu")
		(net "SMB_HFI1_CPU0_LVC2_SDA")
	)
	(segment
		(start 289.804856 -74.630788)
		(end 289.77209 -74.630788)
		(width 0.0889)
		(layer "In11.Cu")
		(net "SMB_HFI1_CPU0_LVC2_SDA")
	)
	(segment
		(start 411.366208 -157.632654)
		(end 411.366208 -157.46222)
		(width 0.089408)
		(layer "In11.Cu")
		(net "SMB_HFI1_CPU0_LVC2_SDA")
	)
	(segment
		(start 294.955976 -72.649588)
		(end 294.933624 -72.649588)
		(width 0.0889)
		(layer "In11.Cu")
		(net "SMB_HFI1_CPU0_LVC2_SDA")
	)
	(segment
		(start 297.176952 -72.950324)
		(end 297.17365 -72.944482)
		(width 0.0889)
		(layer "In11.Cu")
		(net "SMB_HFI1_CPU0_LVC2_SDA")
	)
	(segment
		(start 307.162962 -74.084434)
		(end 307.112162 -74.135234)
		(width 0.0889)
		(layer "In11.Cu")
		(net "SMB_HFI1_CPU0_LVC2_SDA")
	)
	(segment
		(start 291.521896 -73.640188)
		(end 291.48913 -73.640188)
		(width 0.0889)
		(layer "In11.Cu")
		(net "SMB_HFI1_CPU0_LVC2_SDA")
	)
	(segment
		(start 308.860444 -73.101454)
		(end 308.364382 -73.597516)
		(width 0.089408)
		(layer "In11.Cu")
		(net "SMB_HFI1_CPU0_LVC2_SDA")
	)
	(segment
		(start 289.317684 -74.870818)
		(end 289.228276 -74.894948)
		(width 0.0889)
		(layer "In11.Cu")
		(net "SMB_HFI1_CPU0_LVC2_SDA")
	)
	(segment
		(start 329.248008 -147.452588)
		(end 329.248008 -155.730448)
		(width 0.089408)
		(layer "In11.Cu")
		(net "SMB_HFI1_CPU0_LVC2_SDA")
	)
	(segment
		(start 362.320332 -150.631144)
		(end 364.938564 -153.249376)
		(width 0.089408)
		(layer "In11.Cu")
		(net "SMB_HFI1_CPU0_LVC2_SDA")
	)
	(segment
		(start 333.19339 -73.101454)
		(end 308.860444 -73.101454)
		(width 0.089408)
		(layer "In11.Cu")
		(net "SMB_HFI1_CPU0_LVC2_SDA")
	)
	(segment
		(start 307.112162 -74.135234)
		(end 306.014628 -74.135234)
		(width 0.0889)
		(layer "In11.Cu")
		(net "SMB_HFI1_CPU0_LVC2_SDA")
	)
	(segment
		(start 335.783682 -73.279)
		(end 335.026 -73.279)
		(width 0.089408)
		(layer "In11.Cu")
		(net "SMB_HFI1_CPU0_LVC2_SDA")
	)
	(segment
		(start 355.30028 -151.65832)
		(end 357.610156 -151.65832)
		(width 0.089408)
		(layer "In11.Cu")
		(net "SMB_HFI1_CPU0_LVC2_SDA")
	)
	(segment
		(start 294.10406 -72.154034)
		(end 294.0685 -72.154034)
		(width 0.0889)
		(layer "In11.Cu")
		(net "SMB_HFI1_CPU0_LVC2_SDA")
	)
	(segment
		(start 372.170198 -158.22549)
		(end 392.74369 -158.22549)
		(width 0.089408)
		(layer "In11.Cu")
		(net "SMB_HFI1_CPU0_LVC2_SDA")
	)
	(segment
		(start 364.938564 -153.249376)
		(end 364.938564 -154.906726)
		(width 0.089408)
		(layer "In11.Cu")
		(net "SMB_HFI1_CPU0_LVC2_SDA")
	)
	(segment
		(start 298.389802 -73.640188)
		(end 298.36745 -73.640188)
		(width 0.0889)
		(layer "In11.Cu")
		(net "SMB_HFI1_CPU0_LVC2_SDA")
	)
	(segment
		(start 295.8211 -72.154034)
		(end 295.78554 -72.154034)
		(width 0.0889)
		(layer "In11.Cu")
		(net "SMB_HFI1_CPU0_LVC2_SDA")
	)
	(segment
		(start 296.686732 -72.649588)
		(end 296.650664 -72.649588)
		(width 0.0889)
		(layer "In11.Cu")
		(net "SMB_HFI1_CPU0_LVC2_SDA")
	)
	(segment
		(start 411.366208 -157.46222)
		(end 411.284166 -157.393386)
		(width 0.089408)
		(layer "In11.Cu")
		(net "SMB_HFI1_CPU0_LVC2_SDA")
	)
	(segment
		(start 292.384226 -73.144634)
		(end 292.35146 -73.144634)
		(width 0.0889)
		(layer "In11.Cu")
		(net "SMB_HFI1_CPU0_LVC2_SDA")
	)
	(segment
		(start 358.637332 -150.631144)
		(end 362.320332 -150.631144)
		(width 0.089408)
		(layer "In11.Cu")
		(net "SMB_HFI1_CPU0_LVC2_SDA")
	)
	(segment
		(start 352.4758 -156.8196)
		(end 353.2632 -156.0322)
		(width 0.089408)
		(layer "In11.Cu")
		(net "SMB_HFI1_CPU0_LVC2_SDA")
	)
	(segment
		(start 393.908788 -157.060392)
		(end 398.55013 -157.060392)
		(width 0.089408)
		(layer "In11.Cu")
		(net "SMB_HFI1_CPU0_LVC2_SDA")
	)
	(segment
		(start 353.2632 -156.0322)
		(end 353.2632 -153.6954)
		(width 0.089408)
		(layer "In11.Cu")
		(net "SMB_HFI1_CPU0_LVC2_SDA")
	)
	(segment
		(start 300.971966 -73.144634)
		(end 300.936406 -73.144634)
		(width 0.0889)
		(layer "In11.Cu")
		(net "SMB_HFI1_CPU0_LVC2_SDA")
	)
	(segment
		(start 353.2632 -153.6954)
		(end 355.30028 -151.65832)
		(width 0.089408)
		(layer "In11.Cu")
		(net "SMB_HFI1_CPU0_LVC2_SDA")
	)
	(segment
		(start 329.364848 -157.9626)
		(end 348.8944 -157.9626)
		(width 0.089408)
		(layer "In11.Cu")
		(net "SMB_HFI1_CPU0_LVC2_SDA")
	)
	(segment
		(start 364.938564 -154.906726)
		(end 367.319052 -157.287214)
		(width 0.089408)
		(layer "In11.Cu")
		(net "SMB_HFI1_CPU0_LVC2_SDA")
	)
	(segment
		(start 333.562198 -73.470262)
		(end 333.19339 -73.101454)
		(width 0.089408)
		(layer "In11.Cu")
		(net "SMB_HFI1_CPU0_LVC2_SDA")
	)
	(segment
		(start 334.834738 -73.470262)
		(end 333.562198 -73.470262)
		(width 0.089408)
		(layer "In11.Cu")
		(net "SMB_HFI1_CPU0_LVC2_SDA")
	)
	(segment
		(start 328.816208 -156.162248)
		(end 328.816208 -157.41396)
		(width 0.089408)
		(layer "In11.Cu")
		(net "SMB_HFI1_CPU0_LVC2_SDA")
	)
	(segment
		(start 303.540922 -73.640188)
		(end 303.51857 -73.640188)
		(width 0.0889)
		(layer "In11.Cu")
		(net "SMB_HFI1_CPU0_LVC2_SDA")
	)
	(segment
		(start 348.8944 -157.9626)
		(end 350.0374 -156.8196)
		(width 0.089408)
		(layer "In11.Cu")
		(net "SMB_HFI1_CPU0_LVC2_SDA")
	)
	(segment
		(start 297.537886 -73.144634)
		(end 297.520106 -73.144634)
		(width 0.0889)
		(layer "In11.Cu")
		(net "SMB_HFI1_CPU0_LVC2_SDA")
	)
	(segment
		(start 301.823882 -73.640188)
		(end 301.80153 -73.640188)
		(width 0.0889)
		(layer "In11.Cu")
		(net "SMB_HFI1_CPU0_LVC2_SDA")
	)
	(segment
		(start 289.228276 -74.894948)
		(end 288.93516 -74.725784)
		(width 0.0889)
		(layer "In11.Cu")
		(net "SMB_HFI1_CPU0_LVC2_SDA")
	)
	(arc
		(start 304.900076 -73.440036)
		(mid 304.691468 -73.228104)
		(end 304.406046 -73.144634)
		(width 0.0889)
		(layer "In11.Cu")
		(net "SMB_HFI1_CPU0_LVC2_SDA")
	)
	(arc
		(start 298.725336 -73.440036)
		(mid 298.583653 -73.58384)
		(end 298.389802 -73.640188)
		(width 0.0889)
		(layer "In11.Cu")
		(net "SMB_HFI1_CPU0_LVC2_SDA")
	)
	(arc
		(start 291.48913 -73.640188)
		(mid 291.205913 -73.724469)
		(end 290.99891 -73.935336)
		(width 0.0889)
		(layer "In11.Cu")
		(net "SMB_HFI1_CPU0_LVC2_SDA")
	)
	(arc
		(start 301.80153 -73.640188)
		(mid 301.60768 -73.583838)
		(end 301.465996 -73.440036)
		(width 0.0889)
		(layer "In11.Cu")
		(net "SMB_HFI1_CPU0_LVC2_SDA")
	)
	(arc
		(start 289.77209 -74.630788)
		(mid 289.517425 -74.698817)
		(end 289.317684 -74.870818)
		(width 0.0889)
		(layer "In11.Cu")
		(net "SMB_HFI1_CPU0_LVC2_SDA")
	)
	(arc
		(start 306.014628 -74.135234)
		(mid 305.889427 -74.055463)
		(end 305.798474 -73.93813)
		(width 0.0889)
		(layer "In11.Cu")
		(net "SMB_HFI1_CPU0_LVC2_SDA")
	)
	(arc
		(start 305.798474 -73.93813)
		(mid 305.652549 -73.756043)
		(end 305.449986 -73.640188)
		(width 0.0889)
		(layer "In11.Cu")
		(net "SMB_HFI1_CPU0_LVC2_SDA")
	)
	(arc
		(start 293.57447 -72.449436)
		(mid 293.432787 -72.59324)
		(end 293.238936 -72.649588)
		(width 0.0889)
		(layer "In11.Cu")
		(net "SMB_HFI1_CPU0_LVC2_SDA")
	)
	(arc
		(start 290.99891 -73.935336)
		(mid 290.858831 -74.078072)
		(end 290.667186 -74.135234)
		(width 0.0889)
		(layer "In11.Cu")
		(net "SMB_HFI1_CPU0_LVC2_SDA")
	)
	(arc
		(start 300.442376 -73.440036)
		(mid 300.300693 -73.58384)
		(end 300.106842 -73.640188)
		(width 0.0889)
		(layer "In11.Cu")
		(net "SMB_HFI1_CPU0_LVC2_SDA")
	)
	(arc
		(start 294.59809 -72.449436)
		(mid 294.389482 -72.237504)
		(end 294.10406 -72.154034)
		(width 0.0889)
		(layer "In11.Cu")
		(net "SMB_HFI1_CPU0_LVC2_SDA")
	)
	(arc
		(start 291.85743 -73.440036)
		(mid 291.715747 -73.58384)
		(end 291.521896 -73.640188)
		(width 0.0889)
		(layer "In11.Cu")
		(net "SMB_HFI1_CPU0_LVC2_SDA")
	)
	(arc
		(start 298.031916 -73.440036)
		(mid 297.823308 -73.228104)
		(end 297.537886 -73.144634)
		(width 0.0889)
		(layer "In11.Cu")
		(net "SMB_HFI1_CPU0_LVC2_SDA")
	)
	(arc
		(start 292.35146 -73.144634)
		(mid 292.066036 -73.228101)
		(end 291.85743 -73.440036)
		(width 0.0889)
		(layer "In11.Cu")
		(net "SMB_HFI1_CPU0_LVC2_SDA")
	)
	(arc
		(start 301.465996 -73.440036)
		(mid 301.257388 -73.228104)
		(end 300.971966 -73.144634)
		(width 0.0889)
		(layer "In11.Cu")
		(net "SMB_HFI1_CPU0_LVC2_SDA")
	)
	(arc
		(start 299.219366 -73.144634)
		(mid 298.933942 -73.228101)
		(end 298.725336 -73.440036)
		(width 0.0889)
		(layer "In11.Cu")
		(net "SMB_HFI1_CPU0_LVC2_SDA")
	)
	(arc
		(start 300.08449 -73.640188)
		(mid 299.89064 -73.583838)
		(end 299.748956 -73.440036)
		(width 0.0889)
		(layer "In11.Cu")
		(net "SMB_HFI1_CPU0_LVC2_SDA")
	)
	(arc
		(start 297.520106 -73.144634)
		(mid 297.322945 -73.092675)
		(end 297.176952 -72.950324)
		(width 0.0889)
		(layer "In11.Cu")
		(net "SMB_HFI1_CPU0_LVC2_SDA")
	)
	(arc
		(start 303.51857 -73.640188)
		(mid 303.32472 -73.583838)
		(end 303.183036 -73.440036)
		(width 0.0889)
		(layer "In11.Cu")
		(net "SMB_HFI1_CPU0_LVC2_SDA")
	)
	(arc
		(start 295.78554 -72.154034)
		(mid 295.500116 -72.237501)
		(end 295.29151 -72.449436)
		(width 0.0889)
		(layer "In11.Cu")
		(net "SMB_HFI1_CPU0_LVC2_SDA")
	)
	(arc
		(start 303.183036 -73.440036)
		(mid 302.974428 -73.228104)
		(end 302.689006 -73.144634)
		(width 0.0889)
		(layer "In11.Cu")
		(net "SMB_HFI1_CPU0_LVC2_SDA")
	)
	(arc
		(start 293.20617 -72.649588)
		(mid 292.922953 -72.733869)
		(end 292.71595 -72.944736)
		(width 0.0889)
		(layer "In11.Cu")
		(net "SMB_HFI1_CPU0_LVC2_SDA")
	)
	(arc
		(start 294.933624 -72.649588)
		(mid 294.739774 -72.593238)
		(end 294.59809 -72.449436)
		(width 0.0889)
		(layer "In11.Cu")
		(net "SMB_HFI1_CPU0_LVC2_SDA")
	)
	(arc
		(start 296.650664 -72.649588)
		(mid 296.456814 -72.593238)
		(end 296.31513 -72.449436)
		(width 0.0889)
		(layer "In11.Cu")
		(net "SMB_HFI1_CPU0_LVC2_SDA")
	)
	(arc
		(start 294.0685 -72.154034)
		(mid 293.783076 -72.237501)
		(end 293.57447 -72.449436)
		(width 0.0889)
		(layer "In11.Cu")
		(net "SMB_HFI1_CPU0_LVC2_SDA")
	)
	(arc
		(start 298.36745 -73.640188)
		(mid 298.1736 -73.583838)
		(end 298.031916 -73.440036)
		(width 0.0889)
		(layer "In11.Cu")
		(net "SMB_HFI1_CPU0_LVC2_SDA")
	)
	(arc
		(start 299.748956 -73.440036)
		(mid 299.540348 -73.228104)
		(end 299.254926 -73.144634)
		(width 0.0889)
		(layer "In11.Cu")
		(net "SMB_HFI1_CPU0_LVC2_SDA")
	)
	(arc
		(start 295.29151 -72.449436)
		(mid 295.149827 -72.59324)
		(end 294.955976 -72.649588)
		(width 0.0889)
		(layer "In11.Cu")
		(net "SMB_HFI1_CPU0_LVC2_SDA")
	)
	(arc
		(start 302.159416 -73.440036)
		(mid 302.017733 -73.58384)
		(end 301.823882 -73.640188)
		(width 0.0889)
		(layer "In11.Cu")
		(net "SMB_HFI1_CPU0_LVC2_SDA")
	)
	(arc
		(start 290.14039 -74.430636)
		(mid 289.998707 -74.57444)
		(end 289.804856 -74.630788)
		(width 0.0889)
		(layer "In11.Cu")
		(net "SMB_HFI1_CPU0_LVC2_SDA")
	)
	(arc
		(start 292.71595 -72.944736)
		(mid 292.575871 -73.087472)
		(end 292.384226 -73.144634)
		(width 0.0889)
		(layer "In11.Cu")
		(net "SMB_HFI1_CPU0_LVC2_SDA")
	)
	(arc
		(start 296.31513 -72.449436)
		(mid 296.106522 -72.237504)
		(end 295.8211 -72.154034)
		(width 0.0889)
		(layer "In11.Cu")
		(net "SMB_HFI1_CPU0_LVC2_SDA")
	)
	(arc
		(start 297.17365 -72.944482)
		(mid 296.968029 -72.734559)
		(end 296.686732 -72.649588)
		(width 0.0889)
		(layer "In11.Cu")
		(net "SMB_HFI1_CPU0_LVC2_SDA")
	)
	(arc
		(start 305.23561 -73.640188)
		(mid 305.04176 -73.583838)
		(end 304.900076 -73.440036)
		(width 0.0889)
		(layer "In11.Cu")
		(net "SMB_HFI1_CPU0_LVC2_SDA")
	)
	(arc
		(start 300.936406 -73.144634)
		(mid 300.650982 -73.228101)
		(end 300.442376 -73.440036)
		(width 0.0889)
		(layer "In11.Cu")
		(net "SMB_HFI1_CPU0_LVC2_SDA")
	)
	(arc
		(start 303.876456 -73.440036)
		(mid 303.734773 -73.58384)
		(end 303.540922 -73.640188)
		(width 0.0889)
		(layer "In11.Cu")
		(net "SMB_HFI1_CPU0_LVC2_SDA")
	)
	(arc
		(start 302.653446 -73.144634)
		(mid 302.368022 -73.228101)
		(end 302.159416 -73.440036)
		(width 0.0889)
		(layer "In11.Cu")
		(net "SMB_HFI1_CPU0_LVC2_SDA")
	)
	(arc
		(start 290.63442 -74.135234)
		(mid 290.348996 -74.218701)
		(end 290.14039 -74.430636)
		(width 0.0889)
		(layer "In11.Cu")
		(net "SMB_HFI1_CPU0_LVC2_SDA")
	)
	(arc
		(start 304.370486 -73.144634)
		(mid 304.085062 -73.228101)
		(end 303.876456 -73.440036)
		(width 0.0889)
		(layer "In11.Cu")
		(net "SMB_HFI1_CPU0_LVC2_SDA")
	)
	(segment
		(start 425.6405 -126.5047)
		(end 425.375324 -126.5047)
		(width 0.10795)
		(layer "F.Cu")
		(net "SMB_HFI1_CPU0_LVC2_SCL")
	)
	(segment
		(start 423.328592 -128.740408)
		(end 420.779194 -128.740408)
		(width 0.10795)
		(layer "F.Cu")
		(net "SMB_HFI1_CPU0_LVC2_SCL")
	)
	(segment
		(start 425.375324 -126.5047)
		(end 425.184824 -126.3142)
		(width 0.10795)
		(layer "F.Cu")
		(net "SMB_HFI1_CPU0_LVC2_SCL")
	)
	(segment
		(start 424.767502 -126.3142)
		(end 424.2816 -126.800102)
		(width 0.10795)
		(layer "F.Cu")
		(net "SMB_HFI1_CPU0_LVC2_SCL")
	)
	(segment
		(start 289.22218 -75.221338)
		(end 289.79368 -75.221338)
		(width 0.1016)
		(layer "F.Cu")
		(net "SMB_HFI1_CPU0_LVC2_SCL")
	)
	(segment
		(start 424.2816 -126.800102)
		(end 424.2816 -127.7874)
		(width 0.10795)
		(layer "F.Cu")
		(net "SMB_HFI1_CPU0_LVC2_SCL")
	)
	(segment
		(start 424.2816 -127.7874)
		(end 423.328592 -128.740408)
		(width 0.10795)
		(layer "F.Cu")
		(net "SMB_HFI1_CPU0_LVC2_SCL")
	)
	(segment
		(start 425.184824 -126.3142)
		(end 424.767502 -126.3142)
		(width 0.10795)
		(layer "F.Cu")
		(net "SMB_HFI1_CPU0_LVC2_SCL")
	)
	(via
		(at 335.251552 -73.71207)
		(size 0.508)
		(drill 0.254)
		(layers "F.Cu" "B.Cu")
		(net "SMB_HFI1_CPU0_LVC2_SCL")
	)
	(via
		(at 324.392798 -139.037822)
		(size 0.508)
		(drill 0.254)
		(layers "F.Cu" "B.Cu")
		(net "SMB_HFI1_CPU0_LVC2_SCL")
	)
	(via
		(at 289.79368 -75.221338)
		(size 0.508)
		(drill 0.254)
		(layers "F.Cu" "B.Cu")
		(net "SMB_HFI1_CPU0_LVC2_SCL")
	)
	(via
		(at 328.49566 -147.61464)
		(size 0.508)
		(drill 0.254)
		(layers "F.Cu" "B.Cu")
		(net "SMB_HFI1_CPU0_LVC2_SCL")
	)
	(via
		(at 424.767502 -126.3142)
		(size 0.508)
		(drill 0.254)
		(layers "F.Cu" "B.Cu")
		(net "SMB_HFI1_CPU0_LVC2_SCL")
	)
	(via
		(at 411.4038 -156.7942)
		(size 0.508)
		(drill 0.254)
		(layers "F.Cu" "B.Cu")
		(net "SMB_HFI1_CPU0_LVC2_SCL")
	)
	(segment
		(start 328.49566 -146.99234)
		(end 328.49566 -147.61464)
		(width 0.089408)
		(layer "In2.Cu")
		(net "SMB_HFI1_CPU0_LVC2_SCL")
	)
	(segment
		(start 328.713592 -146.774408)
		(end 328.49566 -146.99234)
		(width 0.089408)
		(layer "In2.Cu")
		(net "SMB_HFI1_CPU0_LVC2_SCL")
	)
	(segment
		(start 324.775322 -139.037822)
		(end 324.986396 -139.248896)
		(width 0.089408)
		(layer "In2.Cu")
		(net "SMB_HFI1_CPU0_LVC2_SCL")
	)
	(segment
		(start 328.713592 -139.13993)
		(end 328.713592 -146.774408)
		(width 0.089408)
		(layer "In2.Cu")
		(net "SMB_HFI1_CPU0_LVC2_SCL")
	)
	(segment
		(start 324.392798 -139.037822)
		(end 324.775322 -139.037822)
		(width 0.089408)
		(layer "In2.Cu")
		(net "SMB_HFI1_CPU0_LVC2_SCL")
	)
	(segment
		(start 324.986396 -139.248896)
		(end 325.39305 -139.248896)
		(width 0.089408)
		(layer "In2.Cu")
		(net "SMB_HFI1_CPU0_LVC2_SCL")
	)
	(segment
		(start 325.39305 -139.248896)
		(end 326.325738 -138.316208)
		(width 0.089408)
		(layer "In2.Cu")
		(net "SMB_HFI1_CPU0_LVC2_SCL")
	)
	(segment
		(start 327.88987 -138.316208)
		(end 328.713592 -139.13993)
		(width 0.089408)
		(layer "In2.Cu")
		(net "SMB_HFI1_CPU0_LVC2_SCL")
	)
	(segment
		(start 326.325738 -138.316208)
		(end 327.88987 -138.316208)
		(width 0.089408)
		(layer "In2.Cu")
		(net "SMB_HFI1_CPU0_LVC2_SCL")
	)
	(segment
		(start 327.304908 -124.300234)
		(end 325.974964 -122.97029)
		(width 0.089408)
		(layer "In4.Cu")
		(net "SMB_HFI1_CPU0_LVC2_SCL")
	)
	(segment
		(start 324.392798 -139.037822)
		(end 324.392798 -138.471656)
		(width 0.089408)
		(layer "In4.Cu")
		(net "SMB_HFI1_CPU0_LVC2_SCL")
	)
	(segment
		(start 324.748906 -92.065094)
		(end 331.8002 -85.0138)
		(width 0.089408)
		(layer "In4.Cu")
		(net "SMB_HFI1_CPU0_LVC2_SCL")
	)
	(segment
		(start 334.836516 -79.452724)
		(end 334.836516 -77.45095)
		(width 0.089408)
		(layer "In4.Cu")
		(net "SMB_HFI1_CPU0_LVC2_SCL")
	)
	(segment
		(start 331.8002 -85.0138)
		(end 331.8002 -82.48904)
		(width 0.089408)
		(layer "In4.Cu")
		(net "SMB_HFI1_CPU0_LVC2_SCL")
	)
	(segment
		(start 326.15505 -133.133592)
		(end 329.928474 -133.133592)
		(width 0.089408)
		(layer "In4.Cu")
		(net "SMB_HFI1_CPU0_LVC2_SCL")
	)
	(segment
		(start 325.335392 -137.529062)
		(end 325.335392 -136.782048)
		(width 0.089408)
		(layer "In4.Cu")
		(net "SMB_HFI1_CPU0_LVC2_SCL")
	)
	(segment
		(start 324.392798 -138.471656)
		(end 325.335392 -137.529062)
		(width 0.089408)
		(layer "In4.Cu")
		(net "SMB_HFI1_CPU0_LVC2_SCL")
	)
	(segment
		(start 325.599044 -116.05895)
		(end 324.748906 -115.208812)
		(width 0.089408)
		(layer "In4.Cu")
		(net "SMB_HFI1_CPU0_LVC2_SCL")
	)
	(segment
		(start 327.304908 -126.40437)
		(end 327.304908 -124.300234)
		(width 0.089408)
		(layer "In4.Cu")
		(net "SMB_HFI1_CPU0_LVC2_SCL")
	)
	(segment
		(start 325.599044 -117.97411)
		(end 325.599044 -116.05895)
		(width 0.089408)
		(layer "In4.Cu")
		(net "SMB_HFI1_CPU0_LVC2_SCL")
	)
	(segment
		(start 334.836516 -77.45095)
		(end 334.257396 -76.87183)
		(width 0.089408)
		(layer "In4.Cu")
		(net "SMB_HFI1_CPU0_LVC2_SCL")
	)
	(segment
		(start 325.335392 -136.782048)
		(end 324.827392 -136.274048)
		(width 0.089408)
		(layer "In4.Cu")
		(net "SMB_HFI1_CPU0_LVC2_SCL")
	)
	(segment
		(start 331.8002 -82.48904)
		(end 334.836516 -79.452724)
		(width 0.089408)
		(layer "In4.Cu")
		(net "SMB_HFI1_CPU0_LVC2_SCL")
	)
	(segment
		(start 334.257396 -75.063604)
		(end 335.251552 -74.069448)
		(width 0.089408)
		(layer "In4.Cu")
		(net "SMB_HFI1_CPU0_LVC2_SCL")
	)
	(segment
		(start 324.827392 -136.274048)
		(end 324.827392 -134.46125)
		(width 0.089408)
		(layer "In4.Cu")
		(net "SMB_HFI1_CPU0_LVC2_SCL")
	)
	(segment
		(start 324.748906 -115.208812)
		(end 324.748906 -92.065094)
		(width 0.089408)
		(layer "In4.Cu")
		(net "SMB_HFI1_CPU0_LVC2_SCL")
	)
	(segment
		(start 334.257396 -76.87183)
		(end 334.257396 -75.063604)
		(width 0.089408)
		(layer "In4.Cu")
		(net "SMB_HFI1_CPU0_LVC2_SCL")
	)
	(segment
		(start 330.803504 -132.258562)
		(end 330.803504 -129.902966)
		(width 0.089408)
		(layer "In4.Cu")
		(net "SMB_HFI1_CPU0_LVC2_SCL")
	)
	(segment
		(start 325.974964 -122.97029)
		(end 325.974964 -118.35003)
		(width 0.089408)
		(layer "In4.Cu")
		(net "SMB_HFI1_CPU0_LVC2_SCL")
	)
	(segment
		(start 325.974964 -118.35003)
		(end 325.599044 -117.97411)
		(width 0.089408)
		(layer "In4.Cu")
		(net "SMB_HFI1_CPU0_LVC2_SCL")
	)
	(segment
		(start 329.928474 -133.133592)
		(end 330.803504 -132.258562)
		(width 0.089408)
		(layer "In4.Cu")
		(net "SMB_HFI1_CPU0_LVC2_SCL")
	)
	(segment
		(start 335.251552 -74.069448)
		(end 335.251552 -73.71207)
		(width 0.089408)
		(layer "In4.Cu")
		(net "SMB_HFI1_CPU0_LVC2_SCL")
	)
	(segment
		(start 324.827392 -134.46125)
		(end 326.15505 -133.133592)
		(width 0.089408)
		(layer "In4.Cu")
		(net "SMB_HFI1_CPU0_LVC2_SCL")
	)
	(segment
		(start 330.803504 -129.902966)
		(end 327.304908 -126.40437)
		(width 0.089408)
		(layer "In4.Cu")
		(net "SMB_HFI1_CPU0_LVC2_SCL")
	)
	(segment
		(start 429.21936 -157.410404)
		(end 430.2252 -156.404564)
		(width 0.089408)
		(layer "In9.Cu")
		(net "SMB_HFI1_CPU0_LVC2_SCL")
	)
	(segment
		(start 447.310002 -151.953976)
		(end 448.437 -150.826978)
		(width 0.089408)
		(layer "In9.Cu")
		(net "SMB_HFI1_CPU0_LVC2_SCL")
	)
	(segment
		(start 448.437 -149.2504)
		(end 446.4939 -147.3073)
		(width 0.089408)
		(layer "In9.Cu")
		(net "SMB_HFI1_CPU0_LVC2_SCL")
	)
	(segment
		(start 447.310002 -153.838402)
		(end 447.310002 -151.953976)
		(width 0.089408)
		(layer "In9.Cu")
		(net "SMB_HFI1_CPU0_LVC2_SCL")
	)
	(segment
		(start 436.753254 -154.063192)
		(end 436.976266 -154.286204)
		(width 0.089408)
		(layer "In9.Cu")
		(net "SMB_HFI1_CPU0_LVC2_SCL")
	)
	(segment
		(start 430.2252 -156.404564)
		(end 430.2252 -155.914344)
		(width 0.089408)
		(layer "In9.Cu")
		(net "SMB_HFI1_CPU0_LVC2_SCL")
	)
	(segment
		(start 448.3608 -136.492996)
		(end 447.265298 -135.397494)
		(width 0.089408)
		(layer "In9.Cu")
		(net "SMB_HFI1_CPU0_LVC2_SCL")
	)
	(segment
		(start 433.588414 -125.81509)
		(end 426.434504 -125.81509)
		(width 0.089408)
		(layer "In9.Cu")
		(net "SMB_HFI1_CPU0_LVC2_SCL")
	)
	(segment
		(start 447.673984 -140.766292)
		(end 448.3608 -140.079476)
		(width 0.089408)
		(layer "In9.Cu")
		(net "SMB_HFI1_CPU0_LVC2_SCL")
	)
	(segment
		(start 446.4939 -144.5641)
		(end 447.673984 -143.384016)
		(width 0.089408)
		(layer "In9.Cu")
		(net "SMB_HFI1_CPU0_LVC2_SCL")
	)
	(segment
		(start 437.662066 -128.542796)
		(end 437.66105 -128.54178)
		(width 0.089408)
		(layer "In9.Cu")
		(net "SMB_HFI1_CPU0_LVC2_SCL")
	)
	(segment
		(start 447.673984 -143.384016)
		(end 447.673984 -140.766292)
		(width 0.089408)
		(layer "In9.Cu")
		(net "SMB_HFI1_CPU0_LVC2_SCL")
	)
	(segment
		(start 439.405776 -154.286204)
		(end 440.143138 -155.023566)
		(width 0.089408)
		(layer "In9.Cu")
		(net "SMB_HFI1_CPU0_LVC2_SCL")
	)
	(segment
		(start 436.976266 -154.286204)
		(end 439.405776 -154.286204)
		(width 0.089408)
		(layer "In9.Cu")
		(net "SMB_HFI1_CPU0_LVC2_SCL")
	)
	(segment
		(start 430.2252 -155.914344)
		(end 432.076352 -154.063192)
		(width 0.089408)
		(layer "In9.Cu")
		(net "SMB_HFI1_CPU0_LVC2_SCL")
	)
	(segment
		(start 446.124838 -155.023566)
		(end 447.310002 -153.838402)
		(width 0.089408)
		(layer "In9.Cu")
		(net "SMB_HFI1_CPU0_LVC2_SCL")
	)
	(segment
		(start 446.4939 -147.3073)
		(end 446.4939 -144.5641)
		(width 0.089408)
		(layer "In9.Cu")
		(net "SMB_HFI1_CPU0_LVC2_SCL")
	)
	(segment
		(start 426.434504 -125.81509)
		(end 425.935394 -126.3142)
		(width 0.089408)
		(layer "In9.Cu")
		(net "SMB_HFI1_CPU0_LVC2_SCL")
	)
	(segment
		(start 437.437022 -128.321816)
		(end 436.09514 -128.321816)
		(width 0.089408)
		(layer "In9.Cu")
		(net "SMB_HFI1_CPU0_LVC2_SCL")
	)
	(segment
		(start 437.656986 -128.54178)
		(end 437.437022 -128.321816)
		(width 0.089408)
		(layer "In9.Cu")
		(net "SMB_HFI1_CPU0_LVC2_SCL")
	)
	(segment
		(start 448.437 -150.826978)
		(end 448.437 -149.2504)
		(width 0.089408)
		(layer "In9.Cu")
		(net "SMB_HFI1_CPU0_LVC2_SCL")
	)
	(segment
		(start 411.4038 -156.7942)
		(end 412.020004 -157.410404)
		(width 0.089408)
		(layer "In9.Cu")
		(net "SMB_HFI1_CPU0_LVC2_SCL")
	)
	(segment
		(start 436.09514 -128.321816)
		(end 433.588414 -125.81509)
		(width 0.089408)
		(layer "In9.Cu")
		(net "SMB_HFI1_CPU0_LVC2_SCL")
	)
	(segment
		(start 432.076352 -154.063192)
		(end 436.753254 -154.063192)
		(width 0.089408)
		(layer "In9.Cu")
		(net "SMB_HFI1_CPU0_LVC2_SCL")
	)
	(segment
		(start 448.3608 -140.079476)
		(end 448.3608 -136.492996)
		(width 0.089408)
		(layer "In9.Cu")
		(net "SMB_HFI1_CPU0_LVC2_SCL")
	)
	(segment
		(start 440.143138 -155.023566)
		(end 446.124838 -155.023566)
		(width 0.089408)
		(layer "In9.Cu")
		(net "SMB_HFI1_CPU0_LVC2_SCL")
	)
	(segment
		(start 412.020004 -157.410404)
		(end 429.21936 -157.410404)
		(width 0.089408)
		(layer "In9.Cu")
		(net "SMB_HFI1_CPU0_LVC2_SCL")
	)
	(segment
		(start 444.596266 -135.397494)
		(end 437.741568 -128.542796)
		(width 0.089408)
		(layer "In9.Cu")
		(net "SMB_HFI1_CPU0_LVC2_SCL")
	)
	(segment
		(start 437.741568 -128.542796)
		(end 437.662066 -128.542796)
		(width 0.089408)
		(layer "In9.Cu")
		(net "SMB_HFI1_CPU0_LVC2_SCL")
	)
	(segment
		(start 437.66105 -128.54178)
		(end 437.656986 -128.54178)
		(width 0.089408)
		(layer "In9.Cu")
		(net "SMB_HFI1_CPU0_LVC2_SCL")
	)
	(segment
		(start 447.265298 -135.397494)
		(end 444.596266 -135.397494)
		(width 0.089408)
		(layer "In9.Cu")
		(net "SMB_HFI1_CPU0_LVC2_SCL")
	)
	(segment
		(start 425.935394 -126.3142)
		(end 424.767502 -126.3142)
		(width 0.089408)
		(layer "In9.Cu")
		(net "SMB_HFI1_CPU0_LVC2_SCL")
	)
	(segment
		(start 328.49566 -147.61464)
		(end 329.057 -148.17598)
		(width 0.089408)
		(layer "In11.Cu")
		(net "SMB_HFI1_CPU0_LVC2_SCL")
	)
	(segment
		(start 328.6252 -157.493208)
		(end 329.3364 -158.204408)
		(width 0.089408)
		(layer "In11.Cu")
		(net "SMB_HFI1_CPU0_LVC2_SCL")
	)
	(segment
		(start 394.0302 -157.3022)
		(end 398.4498 -157.3022)
		(width 0.089408)
		(layer "In11.Cu")
		(net "SMB_HFI1_CPU0_LVC2_SCL")
	)
	(segment
		(start 308.443376 -73.859898)
		(end 307.97754 -74.325734)
		(width 0.0889)
		(layer "In11.Cu")
		(net "SMB_HFI1_CPU0_LVC2_SCL")
	)
	(segment
		(start 297.008296 -73.04024)
		(end 297.004994 -73.034398)
		(width 0.0889)
		(layer "In11.Cu")
		(net "SMB_HFI1_CPU0_LVC2_SCL")
	)
	(segment
		(start 399.591276 -158.443676)
		(end 410.897324 -158.443676)
		(width 0.089408)
		(layer "In11.Cu")
		(net "SMB_HFI1_CPU0_LVC2_SCL")
	)
	(segment
		(start 392.905996 -158.426404)
		(end 394.0302 -157.3022)
		(width 0.089408)
		(layer "In11.Cu")
		(net "SMB_HFI1_CPU0_LVC2_SCL")
	)
	(segment
		(start 328.6252 -156.083)
		(end 328.6252 -157.493208)
		(width 0.089408)
		(layer "In11.Cu")
		(net "SMB_HFI1_CPU0_LVC2_SCL")
	)
	(segment
		(start 348.99473 -158.204408)
		(end 350.13773 -157.061408)
		(width 0.089408)
		(layer "In11.Cu")
		(net "SMB_HFI1_CPU0_LVC2_SCL")
	)
	(segment
		(start 294.96258 -72.840088)
		(end 294.92702 -72.840088)
		(width 0.0889)
		(layer "In11.Cu")
		(net "SMB_HFI1_CPU0_LVC2_SCL")
	)
	(segment
		(start 352.57613 -157.061408)
		(end 353.505008 -156.13253)
		(width 0.089408)
		(layer "In11.Cu")
		(net "SMB_HFI1_CPU0_LVC2_SCL")
	)
	(segment
		(start 350.13773 -157.061408)
		(end 352.57613 -157.061408)
		(width 0.089408)
		(layer "In11.Cu")
		(net "SMB_HFI1_CPU0_LVC2_SCL")
	)
	(segment
		(start 355.40061 -151.900128)
		(end 357.710486 -151.900128)
		(width 0.089408)
		(layer "In11.Cu")
		(net "SMB_HFI1_CPU0_LVC2_SCL")
	)
	(segment
		(start 294.097456 -72.344534)
		(end 294.075104 -72.344534)
		(width 0.0889)
		(layer "In11.Cu")
		(net "SMB_HFI1_CPU0_LVC2_SCL")
	)
	(segment
		(start 371.06733 -157.529022)
		(end 371.964712 -158.426404)
		(width 0.089408)
		(layer "In11.Cu")
		(net "SMB_HFI1_CPU0_LVC2_SCL")
	)
	(segment
		(start 304.399442 -73.335134)
		(end 304.37709 -73.335134)
		(width 0.0889)
		(layer "In11.Cu")
		(net "SMB_HFI1_CPU0_LVC2_SCL")
	)
	(segment
		(start 367.218722 -157.529022)
		(end 371.06733 -157.529022)
		(width 0.089408)
		(layer "In11.Cu")
		(net "SMB_HFI1_CPU0_LVC2_SCL")
	)
	(segment
		(start 292.39083 -73.335134)
		(end 292.358064 -73.335134)
		(width 0.0889)
		(layer "In11.Cu")
		(net "SMB_HFI1_CPU0_LVC2_SCL")
	)
	(segment
		(start 329.057 -155.6512)
		(end 328.6252 -156.083)
		(width 0.089408)
		(layer "In11.Cu")
		(net "SMB_HFI1_CPU0_LVC2_SCL")
	)
	(segment
		(start 411.439868 -157.20822)
		(end 411.4038 -156.7942)
		(width 0.089408)
		(layer "In11.Cu")
		(net "SMB_HFI1_CPU0_LVC2_SCL")
	)
	(segment
		(start 371.964712 -158.426404)
		(end 392.905996 -158.426404)
		(width 0.089408)
		(layer "In11.Cu")
		(net "SMB_HFI1_CPU0_LVC2_SCL")
	)
	(segment
		(start 362.220002 -150.872952)
		(end 364.696756 -153.349706)
		(width 0.089408)
		(layer "In11.Cu")
		(net "SMB_HFI1_CPU0_LVC2_SCL")
	)
	(segment
		(start 307.97754 -74.325734)
		(end 305.978306 -74.325734)
		(width 0.0889)
		(layer "In11.Cu")
		(net "SMB_HFI1_CPU0_LVC2_SCL")
	)
	(segment
		(start 289.500564 -75.052174)
		(end 289.79368 -75.221338)
		(width 0.0889)
		(layer "In11.Cu")
		(net "SMB_HFI1_CPU0_LVC2_SCL")
	)
	(segment
		(start 303.547526 -73.830688)
		(end 303.511966 -73.830688)
		(width 0.0889)
		(layer "In11.Cu")
		(net "SMB_HFI1_CPU0_LVC2_SCL")
	)
	(segment
		(start 353.505008 -153.79573)
		(end 355.40061 -151.900128)
		(width 0.089408)
		(layer "In11.Cu")
		(net "SMB_HFI1_CPU0_LVC2_SCL")
	)
	(segment
		(start 291.5285 -73.830688)
		(end 291.495734 -73.830688)
		(width 0.0889)
		(layer "In11.Cu")
		(net "SMB_HFI1_CPU0_LVC2_SCL")
	)
	(segment
		(start 411.536642 -157.2895)
		(end 411.439868 -157.20822)
		(width 0.089408)
		(layer "In11.Cu")
		(net "SMB_HFI1_CPU0_LVC2_SCL")
	)
	(segment
		(start 299.248322 -73.335134)
		(end 299.22597 -73.335134)
		(width 0.0889)
		(layer "In11.Cu")
		(net "SMB_HFI1_CPU0_LVC2_SCL")
	)
	(segment
		(start 298.396406 -73.830688)
		(end 298.360846 -73.830688)
		(width 0.0889)
		(layer "In11.Cu")
		(net "SMB_HFI1_CPU0_LVC2_SCL")
	)
	(segment
		(start 353.505008 -156.13253)
		(end 353.505008 -153.79573)
		(width 0.089408)
		(layer "In11.Cu")
		(net "SMB_HFI1_CPU0_LVC2_SCL")
	)
	(segment
		(start 305.413664 -73.830688)
		(end 305.229006 -73.830688)
		(width 0.0889)
		(layer "In11.Cu")
		(net "SMB_HFI1_CPU0_LVC2_SCL")
	)
	(segment
		(start 398.4498 -157.3022)
		(end 399.591276 -158.443676)
		(width 0.089408)
		(layer "In11.Cu")
		(net "SMB_HFI1_CPU0_LVC2_SCL")
	)
	(segment
		(start 335.251552 -73.71207)
		(end 333.461868 -73.71207)
		(width 0.089408)
		(layer "In11.Cu")
		(net "SMB_HFI1_CPU0_LVC2_SCL")
	)
	(segment
		(start 410.897324 -158.443676)
		(end 411.608016 -157.732984)
		(width 0.089408)
		(layer "In11.Cu")
		(net "SMB_HFI1_CPU0_LVC2_SCL")
	)
	(segment
		(start 296.66184 -72.840088)
		(end 296.64406 -72.840088)
		(width 0.0889)
		(layer "In11.Cu")
		(net "SMB_HFI1_CPU0_LVC2_SCL")
	)
	(segment
		(start 300.113446 -73.830688)
		(end 300.077886 -73.830688)
		(width 0.0889)
		(layer "In11.Cu")
		(net "SMB_HFI1_CPU0_LVC2_SCL")
	)
	(segment
		(start 411.608016 -157.360874)
		(end 411.536642 -157.2895)
		(width 0.089408)
		(layer "In11.Cu")
		(net "SMB_HFI1_CPU0_LVC2_SCL")
	)
	(segment
		(start 301.830486 -73.830688)
		(end 301.794926 -73.830688)
		(width 0.0889)
		(layer "In11.Cu")
		(net "SMB_HFI1_CPU0_LVC2_SCL")
	)
	(segment
		(start 295.814496 -72.344534)
		(end 295.792144 -72.344534)
		(width 0.0889)
		(layer "In11.Cu")
		(net "SMB_HFI1_CPU0_LVC2_SCL")
	)
	(segment
		(start 357.710486 -151.900128)
		(end 358.737662 -150.872952)
		(width 0.089408)
		(layer "In11.Cu")
		(net "SMB_HFI1_CPU0_LVC2_SCL")
	)
	(segment
		(start 289.81146 -74.821288)
		(end 289.778694 -74.821288)
		(width 0.0889)
		(layer "In11.Cu")
		(net "SMB_HFI1_CPU0_LVC2_SCL")
	)
	(segment
		(start 290.67379 -74.325734)
		(end 290.641024 -74.325734)
		(width 0.0889)
		(layer "In11.Cu")
		(net "SMB_HFI1_CPU0_LVC2_SCL")
	)
	(segment
		(start 300.965362 -73.335134)
		(end 300.94301 -73.335134)
		(width 0.0889)
		(layer "In11.Cu")
		(net "SMB_HFI1_CPU0_LVC2_SCL")
	)
	(segment
		(start 333.461868 -73.71207)
		(end 333.09306 -73.343262)
		(width 0.089408)
		(layer "In11.Cu")
		(net "SMB_HFI1_CPU0_LVC2_SCL")
	)
	(segment
		(start 297.531282 -73.335134)
		(end 297.495214 -73.335134)
		(width 0.0889)
		(layer "In11.Cu")
		(net "SMB_HFI1_CPU0_LVC2_SCL")
	)
	(segment
		(start 293.24554 -72.840088)
		(end 293.212774 -72.840088)
		(width 0.0889)
		(layer "In11.Cu")
		(net "SMB_HFI1_CPU0_LVC2_SCL")
	)
	(segment
		(start 364.696756 -155.007056)
		(end 367.218722 -157.529022)
		(width 0.089408)
		(layer "In11.Cu")
		(net "SMB_HFI1_CPU0_LVC2_SCL")
	)
	(segment
		(start 302.682402 -73.335134)
		(end 302.66005 -73.335134)
		(width 0.0889)
		(layer "In11.Cu")
		(net "SMB_HFI1_CPU0_LVC2_SCL")
	)
	(segment
		(start 308.960012 -73.343262)
		(end 308.443376 -73.859898)
		(width 0.089408)
		(layer "In11.Cu")
		(net "SMB_HFI1_CPU0_LVC2_SCL")
	)
	(segment
		(start 329.057 -148.17598)
		(end 329.057 -155.6512)
		(width 0.089408)
		(layer "In11.Cu")
		(net "SMB_HFI1_CPU0_LVC2_SCL")
	)
	(segment
		(start 329.3364 -158.204408)
		(end 348.99473 -158.204408)
		(width 0.089408)
		(layer "In11.Cu")
		(net "SMB_HFI1_CPU0_LVC2_SCL")
	)
	(segment
		(start 364.696756 -153.349706)
		(end 364.696756 -155.007056)
		(width 0.089408)
		(layer "In11.Cu")
		(net "SMB_HFI1_CPU0_LVC2_SCL")
	)
	(segment
		(start 289.479482 -74.973434)
		(end 289.500564 -75.052174)
		(width 0.0889)
		(layer "In11.Cu")
		(net "SMB_HFI1_CPU0_LVC2_SCL")
	)
	(segment
		(start 333.09306 -73.343262)
		(end 308.960012 -73.343262)
		(width 0.089408)
		(layer "In11.Cu")
		(net "SMB_HFI1_CPU0_LVC2_SCL")
	)
	(segment
		(start 411.608016 -157.732984)
		(end 411.608016 -157.360874)
		(width 0.089408)
		(layer "In11.Cu")
		(net "SMB_HFI1_CPU0_LVC2_SCL")
	)
	(segment
		(start 358.737662 -150.872952)
		(end 362.220002 -150.872952)
		(width 0.089408)
		(layer "In11.Cu")
		(net "SMB_HFI1_CPU0_LVC2_SCL")
	)
	(arc
		(start 292.02253 -73.535286)
		(mid 291.813922 -73.747218)
		(end 291.5285 -73.830688)
		(width 0.0889)
		(layer "In11.Cu")
		(net "SMB_HFI1_CPU0_LVC2_SCL")
	)
	(arc
		(start 304.37709 -73.335134)
		(mid 304.18324 -73.391484)
		(end 304.041556 -73.535286)
		(width 0.0889)
		(layer "In11.Cu")
		(net "SMB_HFI1_CPU0_LVC2_SCL")
	)
	(arc
		(start 297.866816 -73.535286)
		(mid 297.725133 -73.391482)
		(end 297.531282 -73.335134)
		(width 0.0889)
		(layer "In11.Cu")
		(net "SMB_HFI1_CPU0_LVC2_SCL")
	)
	(arc
		(start 303.017936 -73.535286)
		(mid 302.876253 -73.391482)
		(end 302.682402 -73.335134)
		(width 0.0889)
		(layer "In11.Cu")
		(net "SMB_HFI1_CPU0_LVC2_SCL")
	)
	(arc
		(start 305.978306 -74.325734)
		(mid 305.775712 -74.209916)
		(end 305.629818 -74.027792)
		(width 0.0889)
		(layer "In11.Cu")
		(net "SMB_HFI1_CPU0_LVC2_SCL")
	)
	(arc
		(start 305.629818 -74.027792)
		(mid 305.538874 -73.910449)
		(end 305.413664 -73.830688)
		(width 0.0889)
		(layer "In11.Cu")
		(net "SMB_HFI1_CPU0_LVC2_SCL")
	)
	(arc
		(start 291.495734 -73.830688)
		(mid 291.304092 -73.887854)
		(end 291.16401 -74.030586)
		(width 0.0889)
		(layer "In11.Cu")
		(net "SMB_HFI1_CPU0_LVC2_SCL")
	)
	(arc
		(start 299.583856 -73.535286)
		(mid 299.442173 -73.391482)
		(end 299.248322 -73.335134)
		(width 0.0889)
		(layer "In11.Cu")
		(net "SMB_HFI1_CPU0_LVC2_SCL")
	)
	(arc
		(start 302.66005 -73.335134)
		(mid 302.4662 -73.391484)
		(end 302.324516 -73.535286)
		(width 0.0889)
		(layer "In11.Cu")
		(net "SMB_HFI1_CPU0_LVC2_SCL")
	)
	(arc
		(start 298.360846 -73.830688)
		(mid 298.075422 -73.747221)
		(end 297.866816 -73.535286)
		(width 0.0889)
		(layer "In11.Cu")
		(net "SMB_HFI1_CPU0_LVC2_SCL")
	)
	(arc
		(start 290.641024 -74.325734)
		(mid 290.447174 -74.382084)
		(end 290.30549 -74.525886)
		(width 0.0889)
		(layer "In11.Cu")
		(net "SMB_HFI1_CPU0_LVC2_SCL")
	)
	(arc
		(start 294.43299 -72.544686)
		(mid 294.291307 -72.400882)
		(end 294.097456 -72.344534)
		(width 0.0889)
		(layer "In11.Cu")
		(net "SMB_HFI1_CPU0_LVC2_SCL")
	)
	(arc
		(start 298.890436 -73.535286)
		(mid 298.681828 -73.747218)
		(end 298.396406 -73.830688)
		(width 0.0889)
		(layer "In11.Cu")
		(net "SMB_HFI1_CPU0_LVC2_SCL")
	)
	(arc
		(start 302.324516 -73.535286)
		(mid 302.115908 -73.747218)
		(end 301.830486 -73.830688)
		(width 0.0889)
		(layer "In11.Cu")
		(net "SMB_HFI1_CPU0_LVC2_SCL")
	)
	(arc
		(start 299.22597 -73.335134)
		(mid 299.03212 -73.391484)
		(end 298.890436 -73.535286)
		(width 0.0889)
		(layer "In11.Cu")
		(net "SMB_HFI1_CPU0_LVC2_SCL")
	)
	(arc
		(start 301.794926 -73.830688)
		(mid 301.509502 -73.747221)
		(end 301.300896 -73.535286)
		(width 0.0889)
		(layer "In11.Cu")
		(net "SMB_HFI1_CPU0_LVC2_SCL")
	)
	(arc
		(start 297.004994 -73.034398)
		(mid 296.859028 -72.891999)
		(end 296.66184 -72.840088)
		(width 0.0889)
		(layer "In11.Cu")
		(net "SMB_HFI1_CPU0_LVC2_SCL")
	)
	(arc
		(start 304.734976 -73.535286)
		(mid 304.593293 -73.391482)
		(end 304.399442 -73.335134)
		(width 0.0889)
		(layer "In11.Cu")
		(net "SMB_HFI1_CPU0_LVC2_SCL")
	)
	(arc
		(start 300.607476 -73.535286)
		(mid 300.398868 -73.747218)
		(end 300.113446 -73.830688)
		(width 0.0889)
		(layer "In11.Cu")
		(net "SMB_HFI1_CPU0_LVC2_SCL")
	)
	(arc
		(start 295.45661 -72.544686)
		(mid 295.248002 -72.756618)
		(end 294.96258 -72.840088)
		(width 0.0889)
		(layer "In11.Cu")
		(net "SMB_HFI1_CPU0_LVC2_SCL")
	)
	(arc
		(start 305.229006 -73.830688)
		(mid 304.943582 -73.747221)
		(end 304.734976 -73.535286)
		(width 0.0889)
		(layer "In11.Cu")
		(net "SMB_HFI1_CPU0_LVC2_SCL")
	)
	(arc
		(start 301.300896 -73.535286)
		(mid 301.159213 -73.391482)
		(end 300.965362 -73.335134)
		(width 0.0889)
		(layer "In11.Cu")
		(net "SMB_HFI1_CPU0_LVC2_SCL")
	)
	(arc
		(start 294.92702 -72.840088)
		(mid 294.641596 -72.756621)
		(end 294.43299 -72.544686)
		(width 0.0889)
		(layer "In11.Cu")
		(net "SMB_HFI1_CPU0_LVC2_SCL")
	)
	(arc
		(start 293.212774 -72.840088)
		(mid 293.021132 -72.897254)
		(end 292.88105 -73.039986)
		(width 0.0889)
		(layer "In11.Cu")
		(net "SMB_HFI1_CPU0_LVC2_SCL")
	)
	(arc
		(start 297.495214 -73.335134)
		(mid 297.213914 -73.250168)
		(end 297.008296 -73.04024)
		(width 0.0889)
		(layer "In11.Cu")
		(net "SMB_HFI1_CPU0_LVC2_SCL")
	)
	(arc
		(start 296.15003 -72.544686)
		(mid 296.008347 -72.400882)
		(end 295.814496 -72.344534)
		(width 0.0889)
		(layer "In11.Cu")
		(net "SMB_HFI1_CPU0_LVC2_SCL")
	)
	(arc
		(start 303.511966 -73.830688)
		(mid 303.226542 -73.747221)
		(end 303.017936 -73.535286)
		(width 0.0889)
		(layer "In11.Cu")
		(net "SMB_HFI1_CPU0_LVC2_SCL")
	)
	(arc
		(start 300.94301 -73.335134)
		(mid 300.74916 -73.391484)
		(end 300.607476 -73.535286)
		(width 0.0889)
		(layer "In11.Cu")
		(net "SMB_HFI1_CPU0_LVC2_SCL")
	)
	(arc
		(start 290.30549 -74.525886)
		(mid 290.096882 -74.737818)
		(end 289.81146 -74.821288)
		(width 0.0889)
		(layer "In11.Cu")
		(net "SMB_HFI1_CPU0_LVC2_SCL")
	)
	(arc
		(start 296.64406 -72.840088)
		(mid 296.358636 -72.756621)
		(end 296.15003 -72.544686)
		(width 0.0889)
		(layer "In11.Cu")
		(net "SMB_HFI1_CPU0_LVC2_SCL")
	)
	(arc
		(start 304.041556 -73.535286)
		(mid 303.832948 -73.747218)
		(end 303.547526 -73.830688)
		(width 0.0889)
		(layer "In11.Cu")
		(net "SMB_HFI1_CPU0_LVC2_SCL")
	)
	(arc
		(start 289.778694 -74.821288)
		(mid 289.6124 -74.864522)
		(end 289.479482 -74.973434)
		(width 0.0889)
		(layer "In11.Cu")
		(net "SMB_HFI1_CPU0_LVC2_SCL")
	)
	(arc
		(start 292.88105 -73.039986)
		(mid 292.674046 -73.25085)
		(end 292.39083 -73.335134)
		(width 0.0889)
		(layer "In11.Cu")
		(net "SMB_HFI1_CPU0_LVC2_SCL")
	)
	(arc
		(start 293.73957 -72.544686)
		(mid 293.530962 -72.756618)
		(end 293.24554 -72.840088)
		(width 0.0889)
		(layer "In11.Cu")
		(net "SMB_HFI1_CPU0_LVC2_SCL")
	)
	(arc
		(start 294.075104 -72.344534)
		(mid 293.881254 -72.400884)
		(end 293.73957 -72.544686)
		(width 0.0889)
		(layer "In11.Cu")
		(net "SMB_HFI1_CPU0_LVC2_SCL")
	)
	(arc
		(start 292.358064 -73.335134)
		(mid 292.164214 -73.391484)
		(end 292.02253 -73.535286)
		(width 0.0889)
		(layer "In11.Cu")
		(net "SMB_HFI1_CPU0_LVC2_SCL")
	)
	(arc
		(start 300.077886 -73.830688)
		(mid 299.792462 -73.747221)
		(end 299.583856 -73.535286)
		(width 0.0889)
		(layer "In11.Cu")
		(net "SMB_HFI1_CPU0_LVC2_SCL")
	)
	(arc
		(start 291.16401 -74.030586)
		(mid 290.957006 -74.24145)
		(end 290.67379 -74.325734)
		(width 0.0889)
		(layer "In11.Cu")
		(net "SMB_HFI1_CPU0_LVC2_SCL")
	)
	(arc
		(start 295.792144 -72.344534)
		(mid 295.598294 -72.400884)
		(end 295.45661 -72.544686)
		(width 0.0889)
		(layer "In11.Cu")
		(net "SMB_HFI1_CPU0_LVC2_SCL")
	)
	(segment
		(start 421.743886 -131.740402)
		(end 421.851582 -131.848098)
		(width 0.10795)
		(layer "F.Cu")
		(net "SMB_HFI0_CPU0_LVC2_SDA")
	)
	(segment
		(start 421.959532 -132.109972)
		(end 422.776904 -132.109972)
		(width 0.10795)
		(layer "F.Cu")
		(net "SMB_HFI0_CPU0_LVC2_SDA")
	)
	(segment
		(start 425.6405 -128.95707)
		(end 425.89577 -128.7018)
		(width 0.10795)
		(layer "F.Cu")
		(net "SMB_HFI0_CPU0_LVC2_SDA")
	)
	(segment
		(start 424.796712 -130.090164)
		(end 425.344336 -130.090164)
		(width 0.10795)
		(layer "F.Cu")
		(net "SMB_HFI0_CPU0_LVC2_SDA")
	)
	(segment
		(start 420.779194 -131.740402)
		(end 421.743886 -131.740402)
		(width 0.10795)
		(layer "F.Cu")
		(net "SMB_HFI0_CPU0_LVC2_SDA")
	)
	(segment
		(start 425.89577 -128.7018)
		(end 427.5201 -128.7018)
		(width 0.10795)
		(layer "F.Cu")
		(net "SMB_HFI0_CPU0_LVC2_SDA")
	)
	(segment
		(start 425.6405 -129.794)
		(end 425.6405 -128.95707)
		(width 0.10795)
		(layer "F.Cu")
		(net "SMB_HFI0_CPU0_LVC2_SDA")
	)
	(segment
		(start 421.851582 -131.848098)
		(end 421.851582 -132.002022)
		(width 0.10795)
		(layer "F.Cu")
		(net "SMB_HFI0_CPU0_LVC2_SDA")
	)
	(segment
		(start 288.36366 -77.697584)
		(end 288.93516 -77.697584)
		(width 0.1016)
		(layer "F.Cu")
		(net "SMB_HFI0_CPU0_LVC2_SDA")
	)
	(segment
		(start 425.344336 -130.090164)
		(end 425.6405 -129.794)
		(width 0.10795)
		(layer "F.Cu")
		(net "SMB_HFI0_CPU0_LVC2_SDA")
	)
	(segment
		(start 421.851582 -132.002022)
		(end 421.959532 -132.109972)
		(width 0.10795)
		(layer "F.Cu")
		(net "SMB_HFI0_CPU0_LVC2_SDA")
	)
	(segment
		(start 422.776904 -132.109972)
		(end 424.796712 -130.090164)
		(width 0.10795)
		(layer "F.Cu")
		(net "SMB_HFI0_CPU0_LVC2_SDA")
	)
	(segment
		(start 427.5201 -128.7018)
		(end 427.9011 -128.3208)
		(width 0.10795)
		(layer "F.Cu")
		(net "SMB_HFI0_CPU0_LVC2_SDA")
	)
	(via
		(at 330.13269 -76.529692)
		(size 0.508)
		(drill 0.254)
		(layers "F.Cu" "B.Cu")
		(net "SMB_HFI0_CPU0_LVC2_SDA")
	)
	(via
		(at 326.585326 -111.775748)
		(size 0.508)
		(drill 0.254)
		(layers "F.Cu" "B.Cu")
		(net "SMB_HFI0_CPU0_LVC2_SDA")
	)
	(via
		(at 288.93516 -77.697584)
		(size 0.508)
		(drill 0.254)
		(layers "F.Cu" "B.Cu")
		(net "SMB_HFI0_CPU0_LVC2_SDA")
	)
	(via
		(at 427.9011 -128.3208)
		(size 0.508)
		(drill 0.254)
		(layers "F.Cu" "B.Cu")
		(net "SMB_HFI0_CPU0_LVC2_SDA")
	)
	(segment
		(start 331.174598 -89.010744)
		(end 331.174598 -79.66964)
		(width 0.089408)
		(layer "In9.Cu")
		(net "SMB_HFI0_CPU0_LVC2_SDA")
	)
	(segment
		(start 329.94092 -78.435962)
		(end 329.94092 -77.592936)
		(width 0.089408)
		(layer "In9.Cu")
		(net "SMB_HFI0_CPU0_LVC2_SDA")
	)
	(segment
		(start 332.075536 -89.911682)
		(end 331.174598 -89.010744)
		(width 0.089408)
		(layer "In9.Cu")
		(net "SMB_HFI0_CPU0_LVC2_SDA")
	)
	(segment
		(start 332.451964 -93.420692)
		(end 332.075536 -93.044264)
		(width 0.089408)
		(layer "In9.Cu")
		(net "SMB_HFI0_CPU0_LVC2_SDA")
	)
	(segment
		(start 330.590906 -76.94295)
		(end 330.590906 -76.404724)
		(width 0.089408)
		(layer "In9.Cu")
		(net "SMB_HFI0_CPU0_LVC2_SDA")
	)
	(segment
		(start 330.835 -107.069636)
		(end 330.835 -106.536236)
		(width 0.089408)
		(layer "In9.Cu")
		(net "SMB_HFI0_CPU0_LVC2_SDA")
	)
	(segment
		(start 331.174598 -79.66964)
		(end 329.94092 -78.435962)
		(width 0.089408)
		(layer "In9.Cu")
		(net "SMB_HFI0_CPU0_LVC2_SDA")
	)
	(segment
		(start 330.494386 -76.308712)
		(end 330.348082 -76.308712)
		(width 0.089408)
		(layer "In9.Cu")
		(net "SMB_HFI0_CPU0_LVC2_SDA")
	)
	(segment
		(start 329.94092 -77.592936)
		(end 330.590906 -76.94295)
		(width 0.089408)
		(layer "In9.Cu")
		(net "SMB_HFI0_CPU0_LVC2_SDA")
	)
	(segment
		(start 332.451964 -104.919272)
		(end 332.451964 -93.420692)
		(width 0.089408)
		(layer "In9.Cu")
		(net "SMB_HFI0_CPU0_LVC2_SDA")
	)
	(segment
		(start 327.36282 -110.998254)
		(end 327.36282 -110.541816)
		(width 0.089408)
		(layer "In9.Cu")
		(net "SMB_HFI0_CPU0_LVC2_SDA")
	)
	(segment
		(start 326.585326 -111.775748)
		(end 327.36282 -110.998254)
		(width 0.089408)
		(layer "In9.Cu")
		(net "SMB_HFI0_CPU0_LVC2_SDA")
	)
	(segment
		(start 332.075536 -93.044264)
		(end 332.075536 -89.911682)
		(width 0.089408)
		(layer "In9.Cu")
		(net "SMB_HFI0_CPU0_LVC2_SDA")
	)
	(segment
		(start 330.835 -106.536236)
		(end 332.451964 -104.919272)
		(width 0.089408)
		(layer "In9.Cu")
		(net "SMB_HFI0_CPU0_LVC2_SDA")
	)
	(segment
		(start 330.590906 -76.404724)
		(end 330.494386 -76.308712)
		(width 0.089408)
		(layer "In9.Cu")
		(net "SMB_HFI0_CPU0_LVC2_SDA")
	)
	(segment
		(start 330.348082 -76.308712)
		(end 330.13269 -76.529692)
		(width 0.089408)
		(layer "In9.Cu")
		(net "SMB_HFI0_CPU0_LVC2_SDA")
	)
	(segment
		(start 327.36282 -110.541816)
		(end 330.835 -107.069636)
		(width 0.089408)
		(layer "In9.Cu")
		(net "SMB_HFI0_CPU0_LVC2_SDA")
	)
	(segment
		(start 356.148894 -121.055638)
		(end 358.607106 -123.51385)
		(width 0.089408)
		(layer "In11.Cu")
		(net "SMB_HFI0_CPU0_LVC2_SDA")
	)
	(segment
		(start 304.694844 -76.84008)
		(end 304.205894 -76.84008)
		(width 0.0889)
		(layer "In11.Cu")
		(net "SMB_HFI0_CPU0_LVC2_SDA")
	)
	(segment
		(start 374.03024 -130.968496)
		(end 375.280936 -130.968496)
		(width 0.089408)
		(layer "In11.Cu")
		(net "SMB_HFI0_CPU0_LVC2_SDA")
	)
	(segment
		(start 296.66184 -75.811888)
		(end 296.64406 -75.811888)
		(width 0.0889)
		(layer "In11.Cu")
		(net "SMB_HFI0_CPU0_LVC2_SDA")
	)
	(segment
		(start 304.205894 -76.84008)
		(end 304.168556 -76.802742)
		(width 0.0889)
		(layer "In11.Cu")
		(net "SMB_HFI0_CPU0_LVC2_SDA")
	)
	(segment
		(start 331.73543 -115.804696)
		(end 332.054962 -116.124228)
		(width 0.089408)
		(layer "In11.Cu")
		(net "SMB_HFI0_CPU0_LVC2_SDA")
	)
	(segment
		(start 361.412536 -123.51385)
		(end 364.52429 -126.625604)
		(width 0.089408)
		(layer "In11.Cu")
		(net "SMB_HFI0_CPU0_LVC2_SDA")
	)
	(segment
		(start 334.84566 -122.127518)
		(end 343.770966 -122.127518)
		(width 0.089408)
		(layer "In11.Cu")
		(net "SMB_HFI0_CPU0_LVC2_SDA")
	)
	(segment
		(start 332.798674 -117.908324)
		(end 332.798674 -120.080532)
		(width 0.089408)
		(layer "In11.Cu")
		(net "SMB_HFI0_CPU0_LVC2_SDA")
	)
	(segment
		(start 375.280936 -130.968496)
		(end 376.12066 -131.80822)
		(width 0.089408)
		(layer "In11.Cu")
		(net "SMB_HFI0_CPU0_LVC2_SDA")
	)
	(segment
		(start 421.001698 -132.659628)
		(end 424.506644 -129.154682)
		(width 0.089408)
		(layer "In11.Cu")
		(net "SMB_HFI0_CPU0_LVC2_SDA")
	)
	(segment
		(start 418.144706 -136.311894)
		(end 421.001698 -133.454902)
		(width 0.089408)
		(layer "In11.Cu")
		(net "SMB_HFI0_CPU0_LVC2_SDA")
	)
	(segment
		(start 380.687072 -133.515608)
		(end 381.363982 -132.838698)
		(width 0.089408)
		(layer "In11.Cu")
		(net "SMB_HFI0_CPU0_LVC2_SDA")
	)
	(segment
		(start 414.537906 -136.534144)
		(end 417.447476 -136.534144)
		(width 0.089408)
		(layer "In11.Cu")
		(net "SMB_HFI0_CPU0_LVC2_SDA")
	)
	(segment
		(start 424.506644 -129.154682)
		(end 425.739814 -129.154682)
		(width 0.089408)
		(layer "In11.Cu")
		(net "SMB_HFI0_CPU0_LVC2_SDA")
	)
	(segment
		(start 358.607106 -123.51385)
		(end 361.412536 -123.51385)
		(width 0.089408)
		(layer "In11.Cu")
		(net "SMB_HFI0_CPU0_LVC2_SDA")
	)
	(segment
		(start 377.138184 -131.80822)
		(end 378.845572 -133.515608)
		(width 0.089408)
		(layer "In11.Cu")
		(net "SMB_HFI0_CPU0_LVC2_SDA")
	)
	(segment
		(start 382.023112 -132.838698)
		(end 383.032254 -133.84784)
		(width 0.089408)
		(layer "In11.Cu")
		(net "SMB_HFI0_CPU0_LVC2_SDA")
	)
	(segment
		(start 332.798674 -120.080532)
		(end 334.84566 -122.127518)
		(width 0.089408)
		(layer "In11.Cu")
		(net "SMB_HFI0_CPU0_LVC2_SDA")
	)
	(segment
		(start 407.016204 -137.180828)
		(end 409.52293 -136.098788)
		(width 0.089408)
		(layer "In11.Cu")
		(net "SMB_HFI0_CPU0_LVC2_SDA")
	)
	(segment
		(start 290.67379 -77.297534)
		(end 290.641024 -77.297534)
		(width 0.0889)
		(layer "In11.Cu")
		(net "SMB_HFI0_CPU0_LVC2_SDA")
	)
	(segment
		(start 289.317684 -77.552804)
		(end 289.228276 -77.528674)
		(width 0.0889)
		(layer "In11.Cu")
		(net "SMB_HFI0_CPU0_LVC2_SDA")
	)
	(segment
		(start 305.623468 -77.036676)
		(end 305.426872 -76.84008)
		(width 0.089408)
		(layer "In11.Cu")
		(net "SMB_HFI0_CPU0_LVC2_SDA")
	)
	(segment
		(start 291.5285 -76.802488)
		(end 291.495734 -76.802488)
		(width 0.0889)
		(layer "In11.Cu")
		(net "SMB_HFI0_CPU0_LVC2_SDA")
	)
	(segment
		(start 305.426872 -76.84008)
		(end 304.694844 -76.84008)
		(width 0.089408)
		(layer "In11.Cu")
		(net "SMB_HFI0_CPU0_LVC2_SDA")
	)
	(segment
		(start 369.599464 -129.167382)
		(end 370.579142 -129.167382)
		(width 0.089408)
		(layer "In11.Cu")
		(net "SMB_HFI0_CPU0_LVC2_SDA")
	)
	(segment
		(start 298.396406 -76.802488)
		(end 298.360846 -76.802488)
		(width 0.0889)
		(layer "In11.Cu")
		(net "SMB_HFI0_CPU0_LVC2_SDA")
	)
	(segment
		(start 383.032254 -133.84784)
		(end 384.683 -133.84784)
		(width 0.089408)
		(layer "In11.Cu")
		(net "SMB_HFI0_CPU0_LVC2_SDA")
	)
	(segment
		(start 326.45477 -111.906304)
		(end 326.45477 -113.08461)
		(width 0.089408)
		(layer "In11.Cu")
		(net "SMB_HFI0_CPU0_LVC2_SDA")
	)
	(segment
		(start 332.054962 -117.164612)
		(end 332.798674 -117.908324)
		(width 0.089408)
		(layer "In11.Cu")
		(net "SMB_HFI0_CPU0_LVC2_SDA")
	)
	(segment
		(start 295.814496 -75.316334)
		(end 295.792144 -75.316334)
		(width 0.0889)
		(layer "In11.Cu")
		(net "SMB_HFI0_CPU0_LVC2_SDA")
	)
	(segment
		(start 409.52293 -136.098788)
		(end 412.047436 -136.098788)
		(width 0.089408)
		(layer "In11.Cu")
		(net "SMB_HFI0_CPU0_LVC2_SDA")
	)
	(segment
		(start 378.845572 -133.515608)
		(end 380.687072 -133.515608)
		(width 0.089408)
		(layer "In11.Cu")
		(net "SMB_HFI0_CPU0_LVC2_SDA")
	)
	(segment
		(start 412.047436 -136.098788)
		(end 412.260542 -136.311894)
		(width 0.089408)
		(layer "In11.Cu")
		(net "SMB_HFI0_CPU0_LVC2_SDA")
	)
	(segment
		(start 376.12066 -131.80822)
		(end 377.138184 -131.80822)
		(width 0.089408)
		(layer "In11.Cu")
		(net "SMB_HFI0_CPU0_LVC2_SDA")
	)
	(segment
		(start 371.312948 -129.901188)
		(end 372.962932 -129.901188)
		(width 0.089408)
		(layer "In11.Cu")
		(net "SMB_HFI0_CPU0_LVC2_SDA")
	)
	(segment
		(start 417.669726 -136.311894)
		(end 418.144706 -136.311894)
		(width 0.089408)
		(layer "In11.Cu")
		(net "SMB_HFI0_CPU0_LVC2_SDA")
	)
	(segment
		(start 381.363982 -132.838698)
		(end 382.023112 -132.838698)
		(width 0.089408)
		(layer "In11.Cu")
		(net "SMB_HFI0_CPU0_LVC2_SDA")
	)
	(segment
		(start 329.174856 -115.804696)
		(end 331.73543 -115.804696)
		(width 0.089408)
		(layer "In11.Cu")
		(net "SMB_HFI0_CPU0_LVC2_SDA")
	)
	(segment
		(start 417.447476 -136.534144)
		(end 417.669726 -136.311894)
		(width 0.089408)
		(layer "In11.Cu")
		(net "SMB_HFI0_CPU0_LVC2_SDA")
	)
	(segment
		(start 329.939396 -76.336398)
		(end 308.92242 -76.336398)
		(width 0.089408)
		(layer "In11.Cu")
		(net "SMB_HFI0_CPU0_LVC2_SDA")
	)
	(segment
		(start 308.92242 -76.336398)
		(end 308.222142 -77.036676)
		(width 0.089408)
		(layer "In11.Cu")
		(net "SMB_HFI0_CPU0_LVC2_SDA")
	)
	(segment
		(start 404.070312 -137.180828)
		(end 407.016204 -137.180828)
		(width 0.089408)
		(layer "In11.Cu")
		(net "SMB_HFI0_CPU0_LVC2_SDA")
	)
	(segment
		(start 294.96258 -75.811888)
		(end 294.92702 -75.811888)
		(width 0.0889)
		(layer "In11.Cu")
		(net "SMB_HFI0_CPU0_LVC2_SDA")
	)
	(segment
		(start 297.008296 -76.01204)
		(end 297.004994 -76.006198)
		(width 0.0889)
		(layer "In11.Cu")
		(net "SMB_HFI0_CPU0_LVC2_SDA")
	)
	(segment
		(start 297.531282 -76.306934)
		(end 297.495214 -76.306934)
		(width 0.0889)
		(layer "In11.Cu")
		(net "SMB_HFI0_CPU0_LVC2_SDA")
	)
	(segment
		(start 343.770966 -122.127518)
		(end 344.842846 -121.055638)
		(width 0.089408)
		(layer "In11.Cu")
		(net "SMB_HFI0_CPU0_LVC2_SDA")
	)
	(segment
		(start 302.682402 -76.306934)
		(end 302.66005 -76.306934)
		(width 0.0889)
		(layer "In11.Cu")
		(net "SMB_HFI0_CPU0_LVC2_SDA")
	)
	(segment
		(start 294.097456 -75.316334)
		(end 294.075104 -75.316334)
		(width 0.0889)
		(layer "In11.Cu")
		(net "SMB_HFI0_CPU0_LVC2_SDA")
	)
	(segment
		(start 330.13269 -76.529692)
		(end 329.939396 -76.336398)
		(width 0.089408)
		(layer "In11.Cu")
		(net "SMB_HFI0_CPU0_LVC2_SDA")
	)
	(segment
		(start 403.658832 -137.592308)
		(end 404.070312 -137.180828)
		(width 0.089408)
		(layer "In11.Cu")
		(net "SMB_HFI0_CPU0_LVC2_SDA")
	)
	(segment
		(start 370.579142 -129.167382)
		(end 371.312948 -129.901188)
		(width 0.089408)
		(layer "In11.Cu")
		(net "SMB_HFI0_CPU0_LVC2_SDA")
	)
	(segment
		(start 421.001698 -133.454902)
		(end 421.001698 -132.659628)
		(width 0.089408)
		(layer "In11.Cu")
		(net "SMB_HFI0_CPU0_LVC2_SDA")
	)
	(segment
		(start 332.054962 -116.124228)
		(end 332.054962 -117.164612)
		(width 0.089408)
		(layer "In11.Cu")
		(net "SMB_HFI0_CPU0_LVC2_SDA")
	)
	(segment
		(start 300.965362 -76.306934)
		(end 300.94301 -76.306934)
		(width 0.0889)
		(layer "In11.Cu")
		(net "SMB_HFI0_CPU0_LVC2_SDA")
	)
	(segment
		(start 391.426192 -137.557256)
		(end 391.461244 -137.592308)
		(width 0.089408)
		(layer "In11.Cu")
		(net "SMB_HFI0_CPU0_LVC2_SDA")
	)
	(segment
		(start 292.39083 -76.306934)
		(end 292.358064 -76.306934)
		(width 0.0889)
		(layer "In11.Cu")
		(net "SMB_HFI0_CPU0_LVC2_SDA")
	)
	(segment
		(start 289.81146 -77.793088)
		(end 289.7759 -77.793088)
		(width 0.0889)
		(layer "In11.Cu")
		(net "SMB_HFI0_CPU0_LVC2_SDA")
	)
	(segment
		(start 372.962932 -129.901188)
		(end 374.03024 -130.968496)
		(width 0.089408)
		(layer "In11.Cu")
		(net "SMB_HFI0_CPU0_LVC2_SDA")
	)
	(segment
		(start 412.260542 -136.311894)
		(end 414.315656 -136.311894)
		(width 0.089408)
		(layer "In11.Cu")
		(net "SMB_HFI0_CPU0_LVC2_SDA")
	)
	(segment
		(start 425.739814 -129.154682)
		(end 426.732192 -128.162304)
		(width 0.089408)
		(layer "In11.Cu")
		(net "SMB_HFI0_CPU0_LVC2_SDA")
	)
	(segment
		(start 426.732192 -128.162304)
		(end 427.742604 -128.162304)
		(width 0.089408)
		(layer "In11.Cu")
		(net "SMB_HFI0_CPU0_LVC2_SDA")
	)
	(segment
		(start 344.842846 -121.055638)
		(end 356.148894 -121.055638)
		(width 0.089408)
		(layer "In11.Cu")
		(net "SMB_HFI0_CPU0_LVC2_SDA")
	)
	(segment
		(start 388.392416 -137.557256)
		(end 391.426192 -137.557256)
		(width 0.089408)
		(layer "In11.Cu")
		(net "SMB_HFI0_CPU0_LVC2_SDA")
	)
	(segment
		(start 427.742604 -128.162304)
		(end 427.9011 -128.3208)
		(width 0.089408)
		(layer "In11.Cu")
		(net "SMB_HFI0_CPU0_LVC2_SDA")
	)
	(segment
		(start 414.315656 -136.311894)
		(end 414.537906 -136.534144)
		(width 0.089408)
		(layer "In11.Cu")
		(net "SMB_HFI0_CPU0_LVC2_SDA")
	)
	(segment
		(start 301.830486 -76.802488)
		(end 301.794926 -76.802488)
		(width 0.0889)
		(layer "In11.Cu")
		(net "SMB_HFI0_CPU0_LVC2_SDA")
	)
	(segment
		(start 300.113446 -76.802488)
		(end 300.077886 -76.802488)
		(width 0.0889)
		(layer "In11.Cu")
		(net "SMB_HFI0_CPU0_LVC2_SDA")
	)
	(segment
		(start 326.585326 -111.775748)
		(end 326.45477 -111.906304)
		(width 0.089408)
		(layer "In11.Cu")
		(net "SMB_HFI0_CPU0_LVC2_SDA")
	)
	(segment
		(start 367.057686 -126.625604)
		(end 369.599464 -129.167382)
		(width 0.089408)
		(layer "In11.Cu")
		(net "SMB_HFI0_CPU0_LVC2_SDA")
	)
	(segment
		(start 299.248322 -76.306934)
		(end 299.22597 -76.306934)
		(width 0.0889)
		(layer "In11.Cu")
		(net "SMB_HFI0_CPU0_LVC2_SDA")
	)
	(segment
		(start 293.24554 -75.811888)
		(end 293.212774 -75.811888)
		(width 0.0889)
		(layer "In11.Cu")
		(net "SMB_HFI0_CPU0_LVC2_SDA")
	)
	(segment
		(start 289.228276 -77.528674)
		(end 288.93516 -77.697584)
		(width 0.0889)
		(layer "In11.Cu")
		(net "SMB_HFI0_CPU0_LVC2_SDA")
	)
	(segment
		(start 304.168556 -76.802742)
		(end 303.529746 -76.802742)
		(width 0.0889)
		(layer "In11.Cu")
		(net "SMB_HFI0_CPU0_LVC2_SDA")
	)
	(segment
		(start 308.222142 -77.036676)
		(end 305.623468 -77.036676)
		(width 0.089408)
		(layer "In11.Cu")
		(net "SMB_HFI0_CPU0_LVC2_SDA")
	)
	(segment
		(start 384.683 -133.84784)
		(end 388.392416 -137.557256)
		(width 0.089408)
		(layer "In11.Cu")
		(net "SMB_HFI0_CPU0_LVC2_SDA")
	)
	(segment
		(start 391.461244 -137.592308)
		(end 403.658832 -137.592308)
		(width 0.089408)
		(layer "In11.Cu")
		(net "SMB_HFI0_CPU0_LVC2_SDA")
	)
	(segment
		(start 364.52429 -126.625604)
		(end 367.057686 -126.625604)
		(width 0.089408)
		(layer "In11.Cu")
		(net "SMB_HFI0_CPU0_LVC2_SDA")
	)
	(segment
		(start 326.45477 -113.08461)
		(end 329.174856 -115.804696)
		(width 0.089408)
		(layer "In11.Cu")
		(net "SMB_HFI0_CPU0_LVC2_SDA")
	)
	(arc
		(start 291.16401 -77.002386)
		(mid 290.957006 -77.21325)
		(end 290.67379 -77.297534)
		(width 0.0889)
		(layer "In11.Cu")
		(net "SMB_HFI0_CPU0_LVC2_SDA")
	)
	(arc
		(start 298.360846 -76.802488)
		(mid 298.075422 -76.719021)
		(end 297.866816 -76.507086)
		(width 0.0889)
		(layer "In11.Cu")
		(net "SMB_HFI0_CPU0_LVC2_SDA")
	)
	(arc
		(start 292.358064 -76.306934)
		(mid 292.164214 -76.363284)
		(end 292.02253 -76.507086)
		(width 0.0889)
		(layer "In11.Cu")
		(net "SMB_HFI0_CPU0_LVC2_SDA")
	)
	(arc
		(start 297.866816 -76.507086)
		(mid 297.725133 -76.363282)
		(end 297.531282 -76.306934)
		(width 0.0889)
		(layer "In11.Cu")
		(net "SMB_HFI0_CPU0_LVC2_SDA")
	)
	(arc
		(start 290.30549 -77.497686)
		(mid 290.096882 -77.709618)
		(end 289.81146 -77.793088)
		(width 0.0889)
		(layer "In11.Cu")
		(net "SMB_HFI0_CPU0_LVC2_SDA")
	)
	(arc
		(start 293.73957 -75.516486)
		(mid 293.530962 -75.728418)
		(end 293.24554 -75.811888)
		(width 0.0889)
		(layer "In11.Cu")
		(net "SMB_HFI0_CPU0_LVC2_SDA")
	)
	(arc
		(start 300.077886 -76.802488)
		(mid 299.792462 -76.719021)
		(end 299.583856 -76.507086)
		(width 0.0889)
		(layer "In11.Cu")
		(net "SMB_HFI0_CPU0_LVC2_SDA")
	)
	(arc
		(start 292.88105 -76.011786)
		(mid 292.674046 -76.22265)
		(end 292.39083 -76.306934)
		(width 0.0889)
		(layer "In11.Cu")
		(net "SMB_HFI0_CPU0_LVC2_SDA")
	)
	(arc
		(start 303.529746 -76.802742)
		(mid 303.234214 -76.723514)
		(end 303.017936 -76.507086)
		(width 0.0889)
		(layer "In11.Cu")
		(net "SMB_HFI0_CPU0_LVC2_SDA")
	)
	(arc
		(start 296.15003 -75.516486)
		(mid 296.008347 -75.372682)
		(end 295.814496 -75.316334)
		(width 0.0889)
		(layer "In11.Cu")
		(net "SMB_HFI0_CPU0_LVC2_SDA")
	)
	(arc
		(start 295.792144 -75.316334)
		(mid 295.598294 -75.372684)
		(end 295.45661 -75.516486)
		(width 0.0889)
		(layer "In11.Cu")
		(net "SMB_HFI0_CPU0_LVC2_SDA")
	)
	(arc
		(start 298.890436 -76.507086)
		(mid 298.681828 -76.719018)
		(end 298.396406 -76.802488)
		(width 0.0889)
		(layer "In11.Cu")
		(net "SMB_HFI0_CPU0_LVC2_SDA")
	)
	(arc
		(start 302.324516 -76.507086)
		(mid 302.115908 -76.719018)
		(end 301.830486 -76.802488)
		(width 0.0889)
		(layer "In11.Cu")
		(net "SMB_HFI0_CPU0_LVC2_SDA")
	)
	(arc
		(start 300.607476 -76.507086)
		(mid 300.398868 -76.719018)
		(end 300.113446 -76.802488)
		(width 0.0889)
		(layer "In11.Cu")
		(net "SMB_HFI0_CPU0_LVC2_SDA")
	)
	(arc
		(start 294.43299 -75.516486)
		(mid 294.291307 -75.372682)
		(end 294.097456 -75.316334)
		(width 0.0889)
		(layer "In11.Cu")
		(net "SMB_HFI0_CPU0_LVC2_SDA")
	)
	(arc
		(start 301.794926 -76.802488)
		(mid 301.509502 -76.719021)
		(end 301.300896 -76.507086)
		(width 0.0889)
		(layer "In11.Cu")
		(net "SMB_HFI0_CPU0_LVC2_SDA")
	)
	(arc
		(start 301.300896 -76.507086)
		(mid 301.159213 -76.363282)
		(end 300.965362 -76.306934)
		(width 0.0889)
		(layer "In11.Cu")
		(net "SMB_HFI0_CPU0_LVC2_SDA")
	)
	(arc
		(start 294.075104 -75.316334)
		(mid 293.881254 -75.372684)
		(end 293.73957 -75.516486)
		(width 0.0889)
		(layer "In11.Cu")
		(net "SMB_HFI0_CPU0_LVC2_SDA")
	)
	(arc
		(start 295.45661 -75.516486)
		(mid 295.248002 -75.728418)
		(end 294.96258 -75.811888)
		(width 0.0889)
		(layer "In11.Cu")
		(net "SMB_HFI0_CPU0_LVC2_SDA")
	)
	(arc
		(start 289.7759 -77.793088)
		(mid 289.519078 -77.725787)
		(end 289.317684 -77.552804)
		(width 0.0889)
		(layer "In11.Cu")
		(net "SMB_HFI0_CPU0_LVC2_SDA")
	)
	(arc
		(start 303.017936 -76.507086)
		(mid 302.876253 -76.363282)
		(end 302.682402 -76.306934)
		(width 0.0889)
		(layer "In11.Cu")
		(net "SMB_HFI0_CPU0_LVC2_SDA")
	)
	(arc
		(start 296.64406 -75.811888)
		(mid 296.358636 -75.728421)
		(end 296.15003 -75.516486)
		(width 0.0889)
		(layer "In11.Cu")
		(net "SMB_HFI0_CPU0_LVC2_SDA")
	)
	(arc
		(start 299.22597 -76.306934)
		(mid 299.03212 -76.363284)
		(end 298.890436 -76.507086)
		(width 0.0889)
		(layer "In11.Cu")
		(net "SMB_HFI0_CPU0_LVC2_SDA")
	)
	(arc
		(start 300.94301 -76.306934)
		(mid 300.74916 -76.363284)
		(end 300.607476 -76.507086)
		(width 0.0889)
		(layer "In11.Cu")
		(net "SMB_HFI0_CPU0_LVC2_SDA")
	)
	(arc
		(start 290.641024 -77.297534)
		(mid 290.447174 -77.353884)
		(end 290.30549 -77.497686)
		(width 0.0889)
		(layer "In11.Cu")
		(net "SMB_HFI0_CPU0_LVC2_SDA")
	)
	(arc
		(start 291.495734 -76.802488)
		(mid 291.304092 -76.859654)
		(end 291.16401 -77.002386)
		(width 0.0889)
		(layer "In11.Cu")
		(net "SMB_HFI0_CPU0_LVC2_SDA")
	)
	(arc
		(start 293.212774 -75.811888)
		(mid 293.021132 -75.869054)
		(end 292.88105 -76.011786)
		(width 0.0889)
		(layer "In11.Cu")
		(net "SMB_HFI0_CPU0_LVC2_SDA")
	)
	(arc
		(start 297.495214 -76.306934)
		(mid 297.213914 -76.221968)
		(end 297.008296 -76.01204)
		(width 0.0889)
		(layer "In11.Cu")
		(net "SMB_HFI0_CPU0_LVC2_SDA")
	)
	(arc
		(start 302.66005 -76.306934)
		(mid 302.4662 -76.363284)
		(end 302.324516 -76.507086)
		(width 0.0889)
		(layer "In11.Cu")
		(net "SMB_HFI0_CPU0_LVC2_SDA")
	)
	(arc
		(start 292.02253 -76.507086)
		(mid 291.813922 -76.719018)
		(end 291.5285 -76.802488)
		(width 0.0889)
		(layer "In11.Cu")
		(net "SMB_HFI0_CPU0_LVC2_SDA")
	)
	(arc
		(start 294.92702 -75.811888)
		(mid 294.641596 -75.728421)
		(end 294.43299 -75.516486)
		(width 0.0889)
		(layer "In11.Cu")
		(net "SMB_HFI0_CPU0_LVC2_SDA")
	)
	(arc
		(start 299.583856 -76.507086)
		(mid 299.442173 -76.363282)
		(end 299.248322 -76.306934)
		(width 0.0889)
		(layer "In11.Cu")
		(net "SMB_HFI0_CPU0_LVC2_SDA")
	)
	(arc
		(start 297.004994 -76.006198)
		(mid 296.859028 -75.863799)
		(end 296.66184 -75.811888)
		(width 0.0889)
		(layer "In11.Cu")
		(net "SMB_HFI0_CPU0_LVC2_SDA")
	)
	(segment
		(start 428.625 -130.217164)
		(end 427.524164 -131.318)
		(width 0.10795)
		(layer "F.Cu")
		(net "SMB_HFI0_CPU0_LVC2_SCL")
	)
	(segment
		(start 428.625 -128.3208)
		(end 428.625 -130.217164)
		(width 0.10795)
		(layer "F.Cu")
		(net "SMB_HFI0_CPU0_LVC2_SCL")
	)
	(segment
		(start 421.851582 -132.632196)
		(end 421.851582 -132.478272)
		(width 0.10795)
		(layer "F.Cu")
		(net "SMB_HFI0_CPU0_LVC2_SCL")
	)
	(segment
		(start 424.904662 -130.350514)
		(end 425.435014 -130.350514)
		(width 0.10795)
		(layer "F.Cu")
		(net "SMB_HFI0_CPU0_LVC2_SCL")
	)
	(segment
		(start 420.779194 -132.7404)
		(end 421.743378 -132.7404)
		(width 0.10795)
		(layer "F.Cu")
		(net "SMB_HFI0_CPU0_LVC2_SCL")
	)
	(segment
		(start 421.959532 -132.370322)
		(end 422.884854 -132.370322)
		(width 0.10795)
		(layer "F.Cu")
		(net "SMB_HFI0_CPU0_LVC2_SCL")
	)
	(segment
		(start 425.831 -131.318)
		(end 425.6405 -131.1275)
		(width 0.10795)
		(layer "F.Cu")
		(net "SMB_HFI0_CPU0_LVC2_SCL")
	)
	(segment
		(start 427.524164 -131.318)
		(end 425.831 -131.318)
		(width 0.10795)
		(layer "F.Cu")
		(net "SMB_HFI0_CPU0_LVC2_SCL")
	)
	(segment
		(start 421.743378 -132.7404)
		(end 421.851582 -132.632196)
		(width 0.10795)
		(layer "F.Cu")
		(net "SMB_HFI0_CPU0_LVC2_SCL")
	)
	(segment
		(start 425.6405 -131.1275)
		(end 425.6405 -130.556)
		(width 0.10795)
		(layer "F.Cu")
		(net "SMB_HFI0_CPU0_LVC2_SCL")
	)
	(segment
		(start 425.435014 -130.350514)
		(end 425.6405 -130.556)
		(width 0.10795)
		(layer "F.Cu")
		(net "SMB_HFI0_CPU0_LVC2_SCL")
	)
	(segment
		(start 421.851582 -132.478272)
		(end 421.959532 -132.370322)
		(width 0.10795)
		(layer "F.Cu")
		(net "SMB_HFI0_CPU0_LVC2_SCL")
	)
	(segment
		(start 289.22218 -77.202538)
		(end 289.79368 -77.202538)
		(width 0.1016)
		(layer "F.Cu")
		(net "SMB_HFI0_CPU0_LVC2_SCL")
	)
	(segment
		(start 422.884854 -132.370322)
		(end 424.904662 -130.350514)
		(width 0.10795)
		(layer "F.Cu")
		(net "SMB_HFI0_CPU0_LVC2_SCL")
	)
	(via
		(at 330.1238 -75.833478)
		(size 0.508)
		(drill 0.254)
		(layers "F.Cu" "B.Cu")
		(net "SMB_HFI0_CPU0_LVC2_SCL")
	)
	(via
		(at 428.625 -128.3208)
		(size 0.508)
		(drill 0.254)
		(layers "F.Cu" "B.Cu")
		(net "SMB_HFI0_CPU0_LVC2_SCL")
	)
	(via
		(at 326.855074 -112.536732)
		(size 0.508)
		(drill 0.254)
		(layers "F.Cu" "B.Cu")
		(net "SMB_HFI0_CPU0_LVC2_SCL")
	)
	(via
		(at 289.79368 -77.202538)
		(size 0.508)
		(drill 0.254)
		(layers "F.Cu" "B.Cu")
		(net "SMB_HFI0_CPU0_LVC2_SCL")
	)
	(segment
		(start 332.317344 -92.949522)
		(end 332.317344 -89.79789)
		(width 0.089408)
		(layer "In9.Cu")
		(net "SMB_HFI0_CPU0_LVC2_SCL")
	)
	(segment
		(start 330.832714 -77.04328)
		(end 330.832714 -76.30414)
		(width 0.089408)
		(layer "In9.Cu")
		(net "SMB_HFI0_CPU0_LVC2_SCL")
	)
	(segment
		(start 327.65238 -111.739426)
		(end 327.65238 -110.611666)
		(width 0.089408)
		(layer "In9.Cu")
		(net "SMB_HFI0_CPU0_LVC2_SCL")
	)
	(segment
		(start 330.182728 -77.693266)
		(end 330.832714 -77.04328)
		(width 0.089408)
		(layer "In9.Cu")
		(net "SMB_HFI0_CPU0_LVC2_SCL")
	)
	(segment
		(start 330.182728 -78.335632)
		(end 330.182728 -77.693266)
		(width 0.089408)
		(layer "In9.Cu")
		(net "SMB_HFI0_CPU0_LVC2_SCL")
	)
	(segment
		(start 331.416406 -88.896952)
		(end 331.416406 -79.56931)
		(width 0.089408)
		(layer "In9.Cu")
		(net "SMB_HFI0_CPU0_LVC2_SCL")
	)
	(segment
		(start 330.365354 -76.066904)
		(end 330.353924 -76.055474)
		(width 0.089408)
		(layer "In9.Cu")
		(net "SMB_HFI0_CPU0_LVC2_SCL")
	)
	(segment
		(start 330.832714 -76.30414)
		(end 330.594208 -76.066904)
		(width 0.089408)
		(layer "In9.Cu")
		(net "SMB_HFI0_CPU0_LVC2_SCL")
	)
	(segment
		(start 330.24953 -75.955652)
		(end 330.1238 -75.833478)
		(width 0.089408)
		(layer "In9.Cu")
		(net "SMB_HFI0_CPU0_LVC2_SCL")
	)
	(segment
		(start 330.594208 -76.066904)
		(end 330.365354 -76.066904)
		(width 0.089408)
		(layer "In9.Cu")
		(net "SMB_HFI0_CPU0_LVC2_SCL")
	)
	(segment
		(start 330.352146 -76.055474)
		(end 330.24953 -75.955652)
		(width 0.089408)
		(layer "In9.Cu")
		(net "SMB_HFI0_CPU0_LVC2_SCL")
	)
	(segment
		(start 332.693772 -93.32595)
		(end 332.317344 -92.949522)
		(width 0.089408)
		(layer "In9.Cu")
		(net "SMB_HFI0_CPU0_LVC2_SCL")
	)
	(segment
		(start 331.416406 -79.56931)
		(end 330.182728 -78.335632)
		(width 0.089408)
		(layer "In9.Cu")
		(net "SMB_HFI0_CPU0_LVC2_SCL")
	)
	(segment
		(start 332.317344 -89.79789)
		(end 331.416406 -88.896952)
		(width 0.089408)
		(layer "In9.Cu")
		(net "SMB_HFI0_CPU0_LVC2_SCL")
	)
	(segment
		(start 330.353924 -76.055474)
		(end 330.352146 -76.055474)
		(width 0.089408)
		(layer "In9.Cu")
		(net "SMB_HFI0_CPU0_LVC2_SCL")
	)
	(segment
		(start 331.089 -107.175046)
		(end 331.089 -106.624628)
		(width 0.089408)
		(layer "In9.Cu")
		(net "SMB_HFI0_CPU0_LVC2_SCL")
	)
	(segment
		(start 332.693772 -105.019856)
		(end 332.693772 -93.32595)
		(width 0.089408)
		(layer "In9.Cu")
		(net "SMB_HFI0_CPU0_LVC2_SCL")
	)
	(segment
		(start 327.65238 -110.611666)
		(end 331.089 -107.175046)
		(width 0.089408)
		(layer "In9.Cu")
		(net "SMB_HFI0_CPU0_LVC2_SCL")
	)
	(segment
		(start 326.855074 -112.536732)
		(end 327.65238 -111.739426)
		(width 0.089408)
		(layer "In9.Cu")
		(net "SMB_HFI0_CPU0_LVC2_SCL")
	)
	(segment
		(start 331.089 -106.624628)
		(end 332.693772 -105.019856)
		(width 0.089408)
		(layer "In9.Cu")
		(net "SMB_HFI0_CPU0_LVC2_SCL")
	)
	(segment
		(start 304.714656 -76.57846)
		(end 304.692558 -76.57846)
		(width 0.0889)
		(layer "In11.Cu")
		(net "SMB_HFI0_CPU0_LVC2_SCL")
	)
	(segment
		(start 296.686732 -75.621388)
		(end 296.650664 -75.621388)
		(width 0.0889)
		(layer "In11.Cu")
		(net "SMB_HFI0_CPU0_LVC2_SCL")
	)
	(segment
		(start 334.864202 -121.875804)
		(end 334.917034 -121.875804)
		(width 0.089408)
		(layer "In11.Cu")
		(net "SMB_HFI0_CPU0_LVC2_SCL")
	)
	(segment
		(start 403.951186 -136.957816)
		(end 407.050494 -136.957816)
		(width 0.089408)
		(layer "In11.Cu")
		(net "SMB_HFI0_CPU0_LVC2_SCL")
	)
	(segment
		(start 409.6004 -135.85698)
		(end 412.147766 -135.85698)
		(width 0.089408)
		(layer "In11.Cu")
		(net "SMB_HFI0_CPU0_LVC2_SCL")
	)
	(segment
		(start 292.384226 -76.116434)
		(end 292.35146 -76.116434)
		(width 0.0889)
		(layer "In11.Cu")
		(net "SMB_HFI0_CPU0_LVC2_SCL")
	)
	(segment
		(start 300.971966 -76.116434)
		(end 300.936406 -76.116434)
		(width 0.0889)
		(layer "In11.Cu")
		(net "SMB_HFI0_CPU0_LVC2_SCL")
	)
	(segment
		(start 343.619836 -121.93651)
		(end 344.691716 -120.86463)
		(width 0.089408)
		(layer "In11.Cu")
		(net "SMB_HFI0_CPU0_LVC2_SCL")
	)
	(segment
		(start 384.757676 -133.580378)
		(end 388.492746 -137.315448)
		(width 0.089408)
		(layer "In11.Cu")
		(net "SMB_HFI0_CPU0_LVC2_SCL")
	)
	(segment
		(start 289.479482 -77.450188)
		(end 289.500564 -77.371448)
		(width 0.0889)
		(layer "In11.Cu")
		(net "SMB_HFI0_CPU0_LVC2_SCL")
	)
	(segment
		(start 297.176952 -75.922124)
		(end 297.17365 -75.916282)
		(width 0.0889)
		(layer "In11.Cu")
		(net "SMB_HFI0_CPU0_LVC2_SCL")
	)
	(segment
		(start 332.24597 -117.085364)
		(end 332.989682 -117.829076)
		(width 0.089408)
		(layer "In11.Cu")
		(net "SMB_HFI0_CPU0_LVC2_SCL")
	)
	(segment
		(start 425.639484 -128.912874)
		(end 426.631862 -127.920496)
		(width 0.089408)
		(layer "In11.Cu")
		(net "SMB_HFI0_CPU0_LVC2_SCL")
	)
	(segment
		(start 374.13057 -130.726688)
		(end 375.381266 -130.726688)
		(width 0.089408)
		(layer "In11.Cu")
		(net "SMB_HFI0_CPU0_LVC2_SCL")
	)
	(segment
		(start 294.10406 -75.125834)
		(end 294.0685 -75.125834)
		(width 0.0889)
		(layer "In11.Cu")
		(net "SMB_HFI0_CPU0_LVC2_SCL")
	)
	(segment
		(start 388.492746 -137.315448)
		(end 391.520426 -137.315448)
		(width 0.089408)
		(layer "In11.Cu")
		(net "SMB_HFI0_CPU0_LVC2_SCL")
	)
	(segment
		(start 375.381266 -130.726688)
		(end 376.22099 -131.566412)
		(width 0.089408)
		(layer "In11.Cu")
		(net "SMB_HFI0_CPU0_LVC2_SCL")
	)
	(segment
		(start 380.586742 -133.2738)
		(end 381.263652 -132.59689)
		(width 0.089408)
		(layer "In11.Cu")
		(net "SMB_HFI0_CPU0_LVC2_SCL")
	)
	(segment
		(start 378.945902 -133.2738)
		(end 380.586742 -133.2738)
		(width 0.089408)
		(layer "In11.Cu")
		(net "SMB_HFI0_CPU0_LVC2_SCL")
	)
	(segment
		(start 376.22099 -131.566412)
		(end 377.238514 -131.566412)
		(width 0.089408)
		(layer "In11.Cu")
		(net "SMB_HFI0_CPU0_LVC2_SCL")
	)
	(segment
		(start 367.158016 -126.383796)
		(end 369.699794 -128.925574)
		(width 0.089408)
		(layer "In11.Cu")
		(net "SMB_HFI0_CPU0_LVC2_SCL")
	)
	(segment
		(start 369.699794 -128.925574)
		(end 370.679472 -128.925574)
		(width 0.089408)
		(layer "In11.Cu")
		(net "SMB_HFI0_CPU0_LVC2_SCL")
	)
	(segment
		(start 304.13833 -76.578714)
		(end 304.105056 -76.611988)
		(width 0.089408)
		(layer "In11.Cu")
		(net "SMB_HFI0_CPU0_LVC2_SCL")
	)
	(segment
		(start 293.238936 -75.621388)
		(end 293.20617 -75.621388)
		(width 0.0889)
		(layer "In11.Cu")
		(net "SMB_HFI0_CPU0_LVC2_SCL")
	)
	(segment
		(start 382.08331 -132.59689)
		(end 383.066798 -133.580378)
		(width 0.089408)
		(layer "In11.Cu")
		(net "SMB_HFI0_CPU0_LVC2_SCL")
	)
	(segment
		(start 289.500564 -77.371448)
		(end 289.79368 -77.202538)
		(width 0.0889)
		(layer "In11.Cu")
		(net "SMB_HFI0_CPU0_LVC2_SCL")
	)
	(segment
		(start 301.823882 -76.611988)
		(end 301.80153 -76.611988)
		(width 0.0889)
		(layer "In11.Cu")
		(net "SMB_HFI0_CPU0_LVC2_SCL")
	)
	(segment
		(start 332.989682 -120.001284)
		(end 334.864202 -121.875804)
		(width 0.089408)
		(layer "In11.Cu")
		(net "SMB_HFI0_CPU0_LVC2_SCL")
	)
	(segment
		(start 364.62462 -126.383796)
		(end 367.158016 -126.383796)
		(width 0.089408)
		(layer "In11.Cu")
		(net "SMB_HFI0_CPU0_LVC2_SCL")
	)
	(segment
		(start 417.347146 -136.292336)
		(end 417.569396 -136.070086)
		(width 0.089408)
		(layer "In11.Cu")
		(net "SMB_HFI0_CPU0_LVC2_SCL")
	)
	(segment
		(start 305.723798 -76.794868)
		(end 305.50739 -76.57846)
		(width 0.089408)
		(layer "In11.Cu")
		(net "SMB_HFI0_CPU0_LVC2_SCL")
	)
	(segment
		(start 335.869534 -121.93651)
		(end 343.619836 -121.93651)
		(width 0.089408)
		(layer "In11.Cu")
		(net "SMB_HFI0_CPU0_LVC2_SCL")
	)
	(segment
		(start 308.79161 -76.09459)
		(end 308.091332 -76.794868)
		(width 0.089408)
		(layer "In11.Cu")
		(net "SMB_HFI0_CPU0_LVC2_SCL")
	)
	(segment
		(start 370.679472 -128.925574)
		(end 371.413278 -129.65938)
		(width 0.089408)
		(layer "In11.Cu")
		(net "SMB_HFI0_CPU0_LVC2_SCL")
	)
	(segment
		(start 308.091332 -76.794868)
		(end 305.723798 -76.794868)
		(width 0.089408)
		(layer "In11.Cu")
		(net "SMB_HFI0_CPU0_LVC2_SCL")
	)
	(segment
		(start 291.521896 -76.611988)
		(end 291.48913 -76.611988)
		(width 0.0889)
		(layer "In11.Cu")
		(net "SMB_HFI0_CPU0_LVC2_SCL")
	)
	(segment
		(start 371.413278 -129.65938)
		(end 373.063262 -129.65938)
		(width 0.089408)
		(layer "In11.Cu")
		(net "SMB_HFI0_CPU0_LVC2_SCL")
	)
	(segment
		(start 414.415986 -136.070086)
		(end 414.638236 -136.292336)
		(width 0.089408)
		(layer "In11.Cu")
		(net "SMB_HFI0_CPU0_LVC2_SCL")
	)
	(segment
		(start 428.224696 -127.920496)
		(end 428.625 -128.3208)
		(width 0.089408)
		(layer "In11.Cu")
		(net "SMB_HFI0_CPU0_LVC2_SCL")
	)
	(segment
		(start 304.105056 -76.611988)
		(end 303.51857 -76.611988)
		(width 0.0889)
		(layer "In11.Cu")
		(net "SMB_HFI0_CPU0_LVC2_SCL")
	)
	(segment
		(start 290.667186 -77.107034)
		(end 290.63442 -77.107034)
		(width 0.0889)
		(layer "In11.Cu")
		(net "SMB_HFI0_CPU0_LVC2_SCL")
	)
	(segment
		(start 426.631862 -127.920496)
		(end 428.224696 -127.920496)
		(width 0.089408)
		(layer "In11.Cu")
		(net "SMB_HFI0_CPU0_LVC2_SCL")
	)
	(segment
		(start 383.066798 -133.580378)
		(end 384.757676 -133.580378)
		(width 0.089408)
		(layer "In11.Cu")
		(net "SMB_HFI0_CPU0_LVC2_SCL")
	)
	(segment
		(start 377.238514 -131.566412)
		(end 378.945902 -133.2738)
		(width 0.089408)
		(layer "In11.Cu")
		(net "SMB_HFI0_CPU0_LVC2_SCL")
	)
	(segment
		(start 424.406314 -128.912874)
		(end 425.639484 -128.912874)
		(width 0.089408)
		(layer "In11.Cu")
		(net "SMB_HFI0_CPU0_LVC2_SCL")
	)
	(segment
		(start 418.044376 -136.070086)
		(end 420.75989 -133.354572)
		(width 0.089408)
		(layer "In11.Cu")
		(net "SMB_HFI0_CPU0_LVC2_SCL")
	)
	(segment
		(start 298.389802 -76.611988)
		(end 298.36745 -76.611988)
		(width 0.0889)
		(layer "In11.Cu")
		(net "SMB_HFI0_CPU0_LVC2_SCL")
	)
	(segment
		(start 326.855074 -113.214658)
		(end 329.254104 -115.613688)
		(width 0.089408)
		(layer "In11.Cu")
		(net "SMB_HFI0_CPU0_LVC2_SCL")
	)
	(segment
		(start 305.50739 -76.57846)
		(end 304.714656 -76.57846)
		(width 0.089408)
		(layer "In11.Cu")
		(net "SMB_HFI0_CPU0_LVC2_SCL")
	)
	(segment
		(start 381.263652 -132.59689)
		(end 382.08331 -132.59689)
		(width 0.089408)
		(layer "In11.Cu")
		(net "SMB_HFI0_CPU0_LVC2_SCL")
	)
	(segment
		(start 304.578512 -76.578714)
		(end 304.13833 -76.578714)
		(width 0.089408)
		(layer "In11.Cu")
		(net "SMB_HFI0_CPU0_LVC2_SCL")
	)
	(segment
		(start 332.24597 -116.04498)
		(end 332.24597 -117.085364)
		(width 0.089408)
		(layer "In11.Cu")
		(net "SMB_HFI0_CPU0_LVC2_SCL")
	)
	(segment
		(start 358.707436 -123.272042)
		(end 361.512866 -123.272042)
		(width 0.089408)
		(layer "In11.Cu")
		(net "SMB_HFI0_CPU0_LVC2_SCL")
	)
	(segment
		(start 414.638236 -136.292336)
		(end 417.347146 -136.292336)
		(width 0.089408)
		(layer "In11.Cu")
		(net "SMB_HFI0_CPU0_LVC2_SCL")
	)
	(segment
		(start 361.512866 -123.272042)
		(end 364.62462 -126.383796)
		(width 0.089408)
		(layer "In11.Cu")
		(net "SMB_HFI0_CPU0_LVC2_SCL")
	)
	(segment
		(start 420.75989 -132.559298)
		(end 424.406314 -128.912874)
		(width 0.089408)
		(layer "In11.Cu")
		(net "SMB_HFI0_CPU0_LVC2_SCL")
	)
	(segment
		(start 334.977486 -121.936256)
		(end 335.86928 -121.936256)
		(width 0.089408)
		(layer "In11.Cu")
		(net "SMB_HFI0_CPU0_LVC2_SCL")
	)
	(segment
		(start 300.106842 -76.611988)
		(end 300.08449 -76.611988)
		(width 0.0889)
		(layer "In11.Cu")
		(net "SMB_HFI0_CPU0_LVC2_SCL")
	)
	(segment
		(start 391.520426 -137.315448)
		(end 391.555478 -137.3505)
		(width 0.089408)
		(layer "In11.Cu")
		(net "SMB_HFI0_CPU0_LVC2_SCL")
	)
	(segment
		(start 289.804856 -77.602588)
		(end 289.782504 -77.602588)
		(width 0.0889)
		(layer "In11.Cu")
		(net "SMB_HFI0_CPU0_LVC2_SCL")
	)
	(segment
		(start 335.86928 -121.936256)
		(end 335.869534 -121.93651)
		(width 0.089408)
		(layer "In11.Cu")
		(net "SMB_HFI0_CPU0_LVC2_SCL")
	)
	(segment
		(start 407.050494 -136.957816)
		(end 409.6004 -135.85698)
		(width 0.089408)
		(layer "In11.Cu")
		(net "SMB_HFI0_CPU0_LVC2_SCL")
	)
	(segment
		(start 412.147766 -135.85698)
		(end 412.360872 -136.070086)
		(width 0.089408)
		(layer "In11.Cu")
		(net "SMB_HFI0_CPU0_LVC2_SCL")
	)
	(segment
		(start 373.063262 -129.65938)
		(end 374.13057 -130.726688)
		(width 0.089408)
		(layer "In11.Cu")
		(net "SMB_HFI0_CPU0_LVC2_SCL")
	)
	(segment
		(start 295.8211 -75.125834)
		(end 295.78554 -75.125834)
		(width 0.0889)
		(layer "In11.Cu")
		(net "SMB_HFI0_CPU0_LVC2_SCL")
	)
	(segment
		(start 391.555478 -137.3505)
		(end 403.558502 -137.3505)
		(width 0.089408)
		(layer "In11.Cu")
		(net "SMB_HFI0_CPU0_LVC2_SCL")
	)
	(segment
		(start 330.1238 -75.833478)
		(end 329.862688 -76.09459)
		(width 0.089408)
		(layer "In11.Cu")
		(net "SMB_HFI0_CPU0_LVC2_SCL")
	)
	(segment
		(start 297.537886 -76.116434)
		(end 297.520106 -76.116434)
		(width 0.0889)
		(layer "In11.Cu")
		(net "SMB_HFI0_CPU0_LVC2_SCL")
	)
	(segment
		(start 412.360872 -136.070086)
		(end 414.415986 -136.070086)
		(width 0.089408)
		(layer "In11.Cu")
		(net "SMB_HFI0_CPU0_LVC2_SCL")
	)
	(segment
		(start 344.691716 -120.86463)
		(end 356.300024 -120.86463)
		(width 0.089408)
		(layer "In11.Cu")
		(net "SMB_HFI0_CPU0_LVC2_SCL")
	)
	(segment
		(start 417.569396 -136.070086)
		(end 418.044376 -136.070086)
		(width 0.089408)
		(layer "In11.Cu")
		(net "SMB_HFI0_CPU0_LVC2_SCL")
	)
	(segment
		(start 356.300024 -120.86463)
		(end 358.707436 -123.272042)
		(width 0.089408)
		(layer "In11.Cu")
		(net "SMB_HFI0_CPU0_LVC2_SCL")
	)
	(segment
		(start 302.689006 -76.116434)
		(end 302.653446 -76.116434)
		(width 0.0889)
		(layer "In11.Cu")
		(net "SMB_HFI0_CPU0_LVC2_SCL")
	)
	(segment
		(start 331.814678 -115.613688)
		(end 332.24597 -116.04498)
		(width 0.089408)
		(layer "In11.Cu")
		(net "SMB_HFI0_CPU0_LVC2_SCL")
	)
	(segment
		(start 299.254926 -76.116434)
		(end 299.219366 -76.116434)
		(width 0.0889)
		(layer "In11.Cu")
		(net "SMB_HFI0_CPU0_LVC2_SCL")
	)
	(segment
		(start 304.692304 -76.578714)
		(end 304.578512 -76.578714)
		(width 0.0889)
		(layer "In11.Cu")
		(net "SMB_HFI0_CPU0_LVC2_SCL")
	)
	(segment
		(start 329.862688 -76.09459)
		(end 308.79161 -76.09459)
		(width 0.089408)
		(layer "In11.Cu")
		(net "SMB_HFI0_CPU0_LVC2_SCL")
	)
	(segment
		(start 334.917034 -121.875804)
		(end 334.977486 -121.936256)
		(width 0.089408)
		(layer "In11.Cu")
		(net "SMB_HFI0_CPU0_LVC2_SCL")
	)
	(segment
		(start 304.692558 -76.57846)
		(end 304.692304 -76.578714)
		(width 0.0889)
		(layer "In11.Cu")
		(net "SMB_HFI0_CPU0_LVC2_SCL")
	)
	(segment
		(start 332.989682 -117.829076)
		(end 332.989682 -120.001284)
		(width 0.089408)
		(layer "In11.Cu")
		(net "SMB_HFI0_CPU0_LVC2_SCL")
	)
	(segment
		(start 294.955976 -75.621388)
		(end 294.933624 -75.621388)
		(width 0.0889)
		(layer "In11.Cu")
		(net "SMB_HFI0_CPU0_LVC2_SCL")
	)
	(segment
		(start 329.254104 -115.613688)
		(end 331.814678 -115.613688)
		(width 0.089408)
		(layer "In11.Cu")
		(net "SMB_HFI0_CPU0_LVC2_SCL")
	)
	(segment
		(start 420.75989 -133.354572)
		(end 420.75989 -132.559298)
		(width 0.089408)
		(layer "In11.Cu")
		(net "SMB_HFI0_CPU0_LVC2_SCL")
	)
	(segment
		(start 403.558502 -137.3505)
		(end 403.951186 -136.957816)
		(width 0.089408)
		(layer "In11.Cu")
		(net "SMB_HFI0_CPU0_LVC2_SCL")
	)
	(segment
		(start 326.855074 -112.536732)
		(end 326.855074 -113.214658)
		(width 0.089408)
		(layer "In11.Cu")
		(net "SMB_HFI0_CPU0_LVC2_SCL")
	)
	(arc
		(start 290.63442 -77.107034)
		(mid 290.348996 -77.190501)
		(end 290.14039 -77.402436)
		(width 0.0889)
		(layer "In11.Cu")
		(net "SMB_HFI0_CPU0_LVC2_SCL")
	)
	(arc
		(start 291.85743 -76.411836)
		(mid 291.715747 -76.55564)
		(end 291.521896 -76.611988)
		(width 0.0889)
		(layer "In11.Cu")
		(net "SMB_HFI0_CPU0_LVC2_SCL")
	)
	(arc
		(start 294.59809 -75.421236)
		(mid 294.389482 -75.209304)
		(end 294.10406 -75.125834)
		(width 0.0889)
		(layer "In11.Cu")
		(net "SMB_HFI0_CPU0_LVC2_SCL")
	)
	(arc
		(start 296.31513 -75.421236)
		(mid 296.106522 -75.209304)
		(end 295.8211 -75.125834)
		(width 0.0889)
		(layer "In11.Cu")
		(net "SMB_HFI0_CPU0_LVC2_SCL")
	)
	(arc
		(start 291.48913 -76.611988)
		(mid 291.205913 -76.696269)
		(end 290.99891 -76.907136)
		(width 0.0889)
		(layer "In11.Cu")
		(net "SMB_HFI0_CPU0_LVC2_SCL")
	)
	(arc
		(start 292.71595 -75.916536)
		(mid 292.575871 -76.059272)
		(end 292.384226 -76.116434)
		(width 0.0889)
		(layer "In11.Cu")
		(net "SMB_HFI0_CPU0_LVC2_SCL")
	)
	(arc
		(start 298.031916 -76.411836)
		(mid 297.823308 -76.199904)
		(end 297.537886 -76.116434)
		(width 0.0889)
		(layer "In11.Cu")
		(net "SMB_HFI0_CPU0_LVC2_SCL")
	)
	(arc
		(start 301.465996 -76.411836)
		(mid 301.257388 -76.199904)
		(end 300.971966 -76.116434)
		(width 0.0889)
		(layer "In11.Cu")
		(net "SMB_HFI0_CPU0_LVC2_SCL")
	)
	(arc
		(start 300.08449 -76.611988)
		(mid 299.89064 -76.555638)
		(end 299.748956 -76.411836)
		(width 0.0889)
		(layer "In11.Cu")
		(net "SMB_HFI0_CPU0_LVC2_SCL")
	)
	(arc
		(start 299.748956 -76.411836)
		(mid 299.540348 -76.199904)
		(end 299.254926 -76.116434)
		(width 0.0889)
		(layer "In11.Cu")
		(net "SMB_HFI0_CPU0_LVC2_SCL")
	)
	(arc
		(start 302.653446 -76.116434)
		(mid 302.368022 -76.199901)
		(end 302.159416 -76.411836)
		(width 0.0889)
		(layer "In11.Cu")
		(net "SMB_HFI0_CPU0_LVC2_SCL")
	)
	(arc
		(start 303.183036 -76.411836)
		(mid 302.974428 -76.199904)
		(end 302.689006 -76.116434)
		(width 0.0889)
		(layer "In11.Cu")
		(net "SMB_HFI0_CPU0_LVC2_SCL")
	)
	(arc
		(start 297.520106 -76.116434)
		(mid 297.322945 -76.064475)
		(end 297.176952 -75.922124)
		(width 0.0889)
		(layer "In11.Cu")
		(net "SMB_HFI0_CPU0_LVC2_SCL")
	)
	(arc
		(start 298.725336 -76.411836)
		(mid 298.583653 -76.55564)
		(end 298.389802 -76.611988)
		(width 0.0889)
		(layer "In11.Cu")
		(net "SMB_HFI0_CPU0_LVC2_SCL")
	)
	(arc
		(start 290.99891 -76.907136)
		(mid 290.858831 -77.049872)
		(end 290.667186 -77.107034)
		(width 0.0889)
		(layer "In11.Cu")
		(net "SMB_HFI0_CPU0_LVC2_SCL")
	)
	(arc
		(start 290.14039 -77.402436)
		(mid 289.998707 -77.54624)
		(end 289.804856 -77.602588)
		(width 0.0889)
		(layer "In11.Cu")
		(net "SMB_HFI0_CPU0_LVC2_SCL")
	)
	(arc
		(start 293.57447 -75.421236)
		(mid 293.432787 -75.56504)
		(end 293.238936 -75.621388)
		(width 0.0889)
		(layer "In11.Cu")
		(net "SMB_HFI0_CPU0_LVC2_SCL")
	)
	(arc
		(start 301.80153 -76.611988)
		(mid 301.60768 -76.555638)
		(end 301.465996 -76.411836)
		(width 0.0889)
		(layer "In11.Cu")
		(net "SMB_HFI0_CPU0_LVC2_SCL")
	)
	(arc
		(start 289.782504 -77.602588)
		(mid 289.614067 -77.560055)
		(end 289.479482 -77.450188)
		(width 0.0889)
		(layer "In11.Cu")
		(net "SMB_HFI0_CPU0_LVC2_SCL")
	)
	(arc
		(start 295.29151 -75.421236)
		(mid 295.149827 -75.56504)
		(end 294.955976 -75.621388)
		(width 0.0889)
		(layer "In11.Cu")
		(net "SMB_HFI0_CPU0_LVC2_SCL")
	)
	(arc
		(start 298.36745 -76.611988)
		(mid 298.1736 -76.555638)
		(end 298.031916 -76.411836)
		(width 0.0889)
		(layer "In11.Cu")
		(net "SMB_HFI0_CPU0_LVC2_SCL")
	)
	(arc
		(start 294.0685 -75.125834)
		(mid 293.783076 -75.209301)
		(end 293.57447 -75.421236)
		(width 0.0889)
		(layer "In11.Cu")
		(net "SMB_HFI0_CPU0_LVC2_SCL")
	)
	(arc
		(start 303.51857 -76.611988)
		(mid 303.32472 -76.555638)
		(end 303.183036 -76.411836)
		(width 0.0889)
		(layer "In11.Cu")
		(net "SMB_HFI0_CPU0_LVC2_SCL")
	)
	(arc
		(start 292.35146 -76.116434)
		(mid 292.066036 -76.199901)
		(end 291.85743 -76.411836)
		(width 0.0889)
		(layer "In11.Cu")
		(net "SMB_HFI0_CPU0_LVC2_SCL")
	)
	(arc
		(start 300.936406 -76.116434)
		(mid 300.650982 -76.199901)
		(end 300.442376 -76.411836)
		(width 0.0889)
		(layer "In11.Cu")
		(net "SMB_HFI0_CPU0_LVC2_SCL")
	)
	(arc
		(start 300.442376 -76.411836)
		(mid 300.300693 -76.55564)
		(end 300.106842 -76.611988)
		(width 0.0889)
		(layer "In11.Cu")
		(net "SMB_HFI0_CPU0_LVC2_SCL")
	)
	(arc
		(start 293.20617 -75.621388)
		(mid 292.922953 -75.705669)
		(end 292.71595 -75.916536)
		(width 0.0889)
		(layer "In11.Cu")
		(net "SMB_HFI0_CPU0_LVC2_SCL")
	)
	(arc
		(start 296.650664 -75.621388)
		(mid 296.456814 -75.565038)
		(end 296.31513 -75.421236)
		(width 0.0889)
		(layer "In11.Cu")
		(net "SMB_HFI0_CPU0_LVC2_SCL")
	)
	(arc
		(start 294.933624 -75.621388)
		(mid 294.739774 -75.565038)
		(end 294.59809 -75.421236)
		(width 0.0889)
		(layer "In11.Cu")
		(net "SMB_HFI0_CPU0_LVC2_SCL")
	)
	(arc
		(start 297.17365 -75.916282)
		(mid 296.968029 -75.706359)
		(end 296.686732 -75.621388)
		(width 0.0889)
		(layer "In11.Cu")
		(net "SMB_HFI0_CPU0_LVC2_SCL")
	)
	(arc
		(start 302.159416 -76.411836)
		(mid 302.017733 -76.55564)
		(end 301.823882 -76.611988)
		(width 0.0889)
		(layer "In11.Cu")
		(net "SMB_HFI0_CPU0_LVC2_SCL")
	)
	(arc
		(start 299.219366 -76.116434)
		(mid 298.933942 -76.199901)
		(end 298.725336 -76.411836)
		(width 0.0889)
		(layer "In11.Cu")
		(net "SMB_HFI0_CPU0_LVC2_SCL")
	)
	(arc
		(start 295.78554 -75.125834)
		(mid 295.500116 -75.209301)
		(end 295.29151 -75.421236)
		(width 0.0889)
		(layer "In11.Cu")
		(net "SMB_HFI0_CPU0_LVC2_SCL")
	)
	(segment
		(start 377.335542 -1.165606)
		(end 377.931426 -0.569722)
		(width 0.10795)
		(layer "F.Cu")
		(net "RST_PCIE_MIDPLANE_N")
	)
	(segment
		(start 383.632202 -4.577842)
		(end 384.612642 -4.577842)
		(width 0.10795)
		(layer "F.Cu")
		(net "RST_PCIE_MIDPLANE_N")
	)
	(segment
		(start 371.945154 -70.295262)
		(end 372.34495 -70.695058)
		(width 0.10795)
		(layer "F.Cu")
		(net "RST_PCIE_MIDPLANE_N")
	)
	(segment
		(start 379.624082 -0.569722)
		(end 383.632202 -4.577842)
		(width 0.10795)
		(layer "F.Cu")
		(net "RST_PCIE_MIDPLANE_N")
	)
	(segment
		(start 377.931426 -0.569722)
		(end 379.624082 -0.569722)
		(width 0.10795)
		(layer "F.Cu")
		(net "RST_PCIE_MIDPLANE_N")
	)
	(segment
		(start 384.612642 -4.577842)
		(end 386.5626 -6.5278)
		(width 0.10795)
		(layer "F.Cu")
		(net "RST_PCIE_MIDPLANE_N")
	)
	(segment
		(start 386.5626 -6.5278)
		(end 386.5626 -6.985)
		(width 0.10795)
		(layer "F.Cu")
		(net "RST_PCIE_MIDPLANE_N")
	)
	(segment
		(start 377.251468 -1.165606)
		(end 377.335542 -1.165606)
		(width 0.10795)
		(layer "F.Cu")
		(net "RST_PCIE_MIDPLANE_N")
	)
	(via
		(at 386.5626 -6.985)
		(size 0.508)
		(drill 0.254)
		(layers "F.Cu" "B.Cu")
		(net "RST_PCIE_MIDPLANE_N")
	)
	(via
		(at 389.905494 -27.827986)
		(size 0.6604)
		(drill 0.3302)
		(layers "F.Cu" "B.Cu")
		(net "RST_PCIE_MIDPLANE_N")
	)
	(via
		(at 387.168136 -28.644342)
		(size 0.508)
		(drill 0.254)
		(layers "F.Cu" "B.Cu")
		(net "RST_PCIE_MIDPLANE_N")
	)
	(via
		(at 377.251468 -1.165606)
		(size 0.508)
		(drill 0.254)
		(layers "F.Cu" "B.Cu")
		(net "RST_PCIE_MIDPLANE_N")
	)
	(via
		(at 17.161256 5.26923)
		(size 0.508)
		(drill 0.254)
		(layers "F.Cu" "B.Cu")
		(net "RST_PCIE_MIDPLANE_N")
	)
	(via
		(at 371.945154 -70.295262)
		(size 0.4572)
		(drill 0.2032)
		(layers "F.Cu" "B.Cu")
		(net "RST_PCIE_MIDPLANE_N")
	)
	(segment
		(start 386.584698 -19.24685)
		(end 386.584698 -21.203666)
		(width 0.10795)
		(layer "B.Cu")
		(net "RST_PCIE_MIDPLANE_N")
	)
	(segment
		(start 392.31824 -22.86762)
		(end 392.47572 -22.86762)
		(width 0.10795)
		(layer "B.Cu")
		(net "RST_PCIE_MIDPLANE_N")
	)
	(segment
		(start 391.309098 -21.253958)
		(end 392.00836 -21.95322)
		(width 0.10795)
		(layer "B.Cu")
		(net "RST_PCIE_MIDPLANE_N")
	)
	(segment
		(start 392.00836 -22.55774)
		(end 392.31824 -22.86762)
		(width 0.10795)
		(layer "B.Cu")
		(net "RST_PCIE_MIDPLANE_N")
	)
	(segment
		(start 392.00836 -21.95322)
		(end 392.00836 -22.55774)
		(width 0.10795)
		(layer "B.Cu")
		(net "RST_PCIE_MIDPLANE_N")
	)
	(segment
		(start 386.5626 -6.985)
		(end 386.5626 -9.418828)
		(width 0.10795)
		(layer "B.Cu")
		(net "RST_PCIE_MIDPLANE_N")
	)
	(segment
		(start 386.5626 -9.418828)
		(end 385.414266 -10.567162)
		(width 0.10795)
		(layer "B.Cu")
		(net "RST_PCIE_MIDPLANE_N")
	)
	(segment
		(start 389.415782 -21.253958)
		(end 391.309098 -21.253958)
		(width 0.10795)
		(layer "B.Cu")
		(net "RST_PCIE_MIDPLANE_N")
	)
	(segment
		(start 385.414266 -18.076418)
		(end 386.584698 -19.24685)
		(width 0.10795)
		(layer "B.Cu")
		(net "RST_PCIE_MIDPLANE_N")
	)
	(segment
		(start 386.584698 -21.203666)
		(end 387.395974 -22.014942)
		(width 0.10795)
		(layer "B.Cu")
		(net "RST_PCIE_MIDPLANE_N")
	)
	(segment
		(start 389.905494 -27.82951)
		(end 389.905494 -27.827986)
		(width 0.10795)
		(layer "B.Cu")
		(net "RST_PCIE_MIDPLANE_N")
	)
	(segment
		(start 385.414266 -10.567162)
		(end 385.414266 -18.076418)
		(width 0.10795)
		(layer "B.Cu")
		(net "RST_PCIE_MIDPLANE_N")
	)
	(segment
		(start 389.090662 -28.644342)
		(end 389.905494 -27.82951)
		(width 0.10795)
		(layer "B.Cu")
		(net "RST_PCIE_MIDPLANE_N")
	)
	(segment
		(start 388.654798 -22.014942)
		(end 389.415782 -21.253958)
		(width 0.10795)
		(layer "B.Cu")
		(net "RST_PCIE_MIDPLANE_N")
	)
	(segment
		(start 387.168136 -28.644342)
		(end 389.090662 -28.644342)
		(width 0.10795)
		(layer "B.Cu")
		(net "RST_PCIE_MIDPLANE_N")
	)
	(segment
		(start 392.662918 -23.054818)
		(end 392.662918 -25.070562)
		(width 0.10795)
		(layer "B.Cu")
		(net "RST_PCIE_MIDPLANE_N")
	)
	(segment
		(start 392.47572 -22.86762)
		(end 392.662918 -23.054818)
		(width 0.10795)
		(layer "B.Cu")
		(net "RST_PCIE_MIDPLANE_N")
	)
	(segment
		(start 387.395974 -22.014942)
		(end 388.654798 -22.014942)
		(width 0.10795)
		(layer "B.Cu")
		(net "RST_PCIE_MIDPLANE_N")
	)
	(segment
		(start 392.662918 -25.070562)
		(end 389.905494 -27.827986)
		(width 0.10795)
		(layer "B.Cu")
		(net "RST_PCIE_MIDPLANE_N")
	)
	(segment
		(start 386.728208 -31.746952)
		(end 386.52196 -31.540704)
		(width 0.089408)
		(layer "In2.Cu")
		(net "RST_PCIE_MIDPLANE_N")
	)
	(segment
		(start 382.670304 -40.844978)
		(end 382.670304 -38.814756)
		(width 0.089408)
		(layer "In2.Cu")
		(net "RST_PCIE_MIDPLANE_N")
	)
	(segment
		(start 380.213108 -58.366914)
		(end 381.257302 -57.32272)
		(width 0.089408)
		(layer "In2.Cu")
		(net "RST_PCIE_MIDPLANE_N")
	)
	(segment
		(start 379.818646 -66.584576)
		(end 379.819154 -66.584068)
		(width 0.089408)
		(layer "In2.Cu")
		(net "RST_PCIE_MIDPLANE_N")
	)
	(segment
		(start 386.728462 -32.184594)
		(end 386.728462 -32.026606)
		(width 0.089408)
		(layer "In2.Cu")
		(net "RST_PCIE_MIDPLANE_N")
	)
	(segment
		(start 380.061724 -66.584322)
		(end 380.074678 -66.584322)
		(width 0.089408)
		(layer "In2.Cu")
		(net "RST_PCIE_MIDPLANE_N")
	)
	(segment
		(start 380.548896 -46.88586)
		(end 382.853946 -44.58081)
		(width 0.089408)
		(layer "In2.Cu")
		(net "RST_PCIE_MIDPLANE_N")
	)
	(segment
		(start 381.219202 -64.649858)
		(end 380.213108 -63.643764)
		(width 0.089408)
		(layer "In2.Cu")
		(net "RST_PCIE_MIDPLANE_N")
	)
	(segment
		(start 372.371366 -69.86905)
		(end 372.371366 -68.644516)
		(width 0.089408)
		(layer "In2.Cu")
		(net "RST_PCIE_MIDPLANE_N")
	)
	(segment
		(start 386.52196 -29.290518)
		(end 387.168136 -28.644342)
		(width 0.089408)
		(layer "In2.Cu")
		(net "RST_PCIE_MIDPLANE_N")
	)
	(segment
		(start 385.783836 -35.542728)
		(end 385.783836 -34.05251)
		(width 0.089408)
		(layer "In2.Cu")
		(net "RST_PCIE_MIDPLANE_N")
	)
	(segment
		(start 381.257302 -56.8325)
		(end 381.097536 -56.672734)
		(width 0.089408)
		(layer "In2.Cu")
		(net "RST_PCIE_MIDPLANE_N")
	)
	(segment
		(start 382.977644 -41.152318)
		(end 382.670304 -40.844978)
		(width 0.089408)
		(layer "In2.Cu")
		(net "RST_PCIE_MIDPLANE_N")
	)
	(segment
		(start 377.338336 -67.460368)
		(end 378.214128 -66.584576)
		(width 0.089408)
		(layer "In2.Cu")
		(net "RST_PCIE_MIDPLANE_N")
	)
	(segment
		(start 385.78409 -35.542982)
		(end 385.783836 -35.542728)
		(width 0.089408)
		(layer "In2.Cu")
		(net "RST_PCIE_MIDPLANE_N")
	)
	(segment
		(start 380.213108 -63.643764)
		(end 380.213108 -58.366914)
		(width 0.089408)
		(layer "In2.Cu")
		(net "RST_PCIE_MIDPLANE_N")
	)
	(segment
		(start 381.219202 -65.439798)
		(end 381.219202 -64.649858)
		(width 0.089408)
		(layer "In2.Cu")
		(net "RST_PCIE_MIDPLANE_N")
	)
	(segment
		(start 381.097536 -56.672734)
		(end 381.097536 -51.402488)
		(width 0.089408)
		(layer "In2.Cu")
		(net "RST_PCIE_MIDPLANE_N")
	)
	(segment
		(start 371.945154 -70.295262)
		(end 372.371366 -69.86905)
		(width 0.089408)
		(layer "In2.Cu")
		(net "RST_PCIE_MIDPLANE_N")
	)
	(segment
		(start 378.214128 -66.584576)
		(end 379.818646 -66.584576)
		(width 0.089408)
		(layer "In2.Cu")
		(net "RST_PCIE_MIDPLANE_N")
	)
	(segment
		(start 386.728208 -32.184848)
		(end 386.728462 -32.184594)
		(width 0.089408)
		(layer "In2.Cu")
		(net "RST_PCIE_MIDPLANE_N")
	)
	(segment
		(start 380.074678 -66.584322)
		(end 381.219202 -65.439798)
		(width 0.089408)
		(layer "In2.Cu")
		(net "RST_PCIE_MIDPLANE_N")
	)
	(segment
		(start 385.78409 -35.70097)
		(end 385.78409 -35.542982)
		(width 0.089408)
		(layer "In2.Cu")
		(net "RST_PCIE_MIDPLANE_N")
	)
	(segment
		(start 385.783836 -34.05251)
		(end 386.728208 -33.108138)
		(width 0.089408)
		(layer "In2.Cu")
		(net "RST_PCIE_MIDPLANE_N")
	)
	(segment
		(start 386.728208 -33.108138)
		(end 386.728208 -32.184848)
		(width 0.089408)
		(layer "In2.Cu")
		(net "RST_PCIE_MIDPLANE_N")
	)
	(segment
		(start 374.19915 -67.460368)
		(end 377.338336 -67.460368)
		(width 0.089408)
		(layer "In2.Cu")
		(net "RST_PCIE_MIDPLANE_N")
	)
	(segment
		(start 382.853946 -42.32529)
		(end 382.977644 -42.201592)
		(width 0.089408)
		(layer "In2.Cu")
		(net "RST_PCIE_MIDPLANE_N")
	)
	(segment
		(start 382.977644 -42.201592)
		(end 382.977644 -41.152318)
		(width 0.089408)
		(layer "In2.Cu")
		(net "RST_PCIE_MIDPLANE_N")
	)
	(segment
		(start 379.819154 -66.584068)
		(end 380.06147 -66.584068)
		(width 0.089408)
		(layer "In2.Cu")
		(net "RST_PCIE_MIDPLANE_N")
	)
	(segment
		(start 386.52196 -31.540704)
		(end 386.52196 -29.290518)
		(width 0.089408)
		(layer "In2.Cu")
		(net "RST_PCIE_MIDPLANE_N")
	)
	(segment
		(start 373.491252 -68.168266)
		(end 374.19915 -67.460368)
		(width 0.089408)
		(layer "In2.Cu")
		(net "RST_PCIE_MIDPLANE_N")
	)
	(segment
		(start 381.097536 -51.402488)
		(end 380.548896 -50.853848)
		(width 0.089408)
		(layer "In2.Cu")
		(net "RST_PCIE_MIDPLANE_N")
	)
	(segment
		(start 372.847616 -68.168266)
		(end 373.491252 -68.168266)
		(width 0.089408)
		(layer "In2.Cu")
		(net "RST_PCIE_MIDPLANE_N")
	)
	(segment
		(start 380.06147 -66.584068)
		(end 380.061724 -66.584322)
		(width 0.089408)
		(layer "In2.Cu")
		(net "RST_PCIE_MIDPLANE_N")
	)
	(segment
		(start 382.853946 -44.58081)
		(end 382.853946 -42.32529)
		(width 0.089408)
		(layer "In2.Cu")
		(net "RST_PCIE_MIDPLANE_N")
	)
	(segment
		(start 382.670304 -38.814756)
		(end 385.78409 -35.70097)
		(width 0.089408)
		(layer "In2.Cu")
		(net "RST_PCIE_MIDPLANE_N")
	)
	(segment
		(start 380.548896 -50.853848)
		(end 380.548896 -46.88586)
		(width 0.089408)
		(layer "In2.Cu")
		(net "RST_PCIE_MIDPLANE_N")
	)
	(segment
		(start 381.257302 -57.32272)
		(end 381.257302 -56.8325)
		(width 0.089408)
		(layer "In2.Cu")
		(net "RST_PCIE_MIDPLANE_N")
	)
	(segment
		(start 386.728462 -32.026606)
		(end 386.728208 -32.026352)
		(width 0.089408)
		(layer "In2.Cu")
		(net "RST_PCIE_MIDPLANE_N")
	)
	(segment
		(start 386.728208 -32.026352)
		(end 386.728208 -31.746952)
		(width 0.089408)
		(layer "In2.Cu")
		(net "RST_PCIE_MIDPLANE_N")
	)
	(segment
		(start 372.371366 -68.644516)
		(end 372.847616 -68.168266)
		(width 0.089408)
		(layer "In2.Cu")
		(net "RST_PCIE_MIDPLANE_N")
	)
	(segment
		(start 181.524656 -2.806446)
		(end 183.2102 -1.120902)
		(width 0.089408)
		(layer "In9.Cu")
		(net "RST_PCIE_MIDPLANE_N")
	)
	(segment
		(start 335.200244 -6.367272)
		(end 336.794856 -7.961884)
		(width 0.089408)
		(layer "In9.Cu")
		(net "RST_PCIE_MIDPLANE_N")
	)
	(segment
		(start 321.480942 4.059936)
		(end 322.570094 2.970784)
		(width 0.089408)
		(layer "In9.Cu")
		(net "RST_PCIE_MIDPLANE_N")
	)
	(segment
		(start 360.433366 -13.725398)
		(end 359.4608 -12.752832)
		(width 0.089408)
		(layer "In9.Cu")
		(net "RST_PCIE_MIDPLANE_N")
	)
	(segment
		(start 22.454616 5.207)
		(end 23.495508 4.166108)
		(width 0.089408)
		(layer "In9.Cu")
		(net "RST_PCIE_MIDPLANE_N")
	)
	(segment
		(start 329.29957 -4.453382)
		(end 331.21346 -6.367272)
		(width 0.089408)
		(layer "In9.Cu")
		(net "RST_PCIE_MIDPLANE_N")
	)
	(segment
		(start 356.128828 -21.849842)
		(end 358.578658 -21.849842)
		(width 0.089408)
		(layer "In9.Cu")
		(net "RST_PCIE_MIDPLANE_N")
	)
	(segment
		(start 178.64963 -2.4638)
		(end 178.992276 -2.806446)
		(width 0.089408)
		(layer "In9.Cu")
		(net "RST_PCIE_MIDPLANE_N")
	)
	(segment
		(start 103.914702 4.476496)
		(end 165.283642 4.476496)
		(width 0.089408)
		(layer "In9.Cu")
		(net "RST_PCIE_MIDPLANE_N")
	)
	(segment
		(start 362.940092 -9.168384)
		(end 362.939838 -9.16813)
		(width 0.089408)
		(layer "In9.Cu")
		(net "RST_PCIE_MIDPLANE_N")
	)
	(segment
		(start 103.184198 5.207)
		(end 103.914702 4.476496)
		(width 0.089408)
		(layer "In9.Cu")
		(net "RST_PCIE_MIDPLANE_N")
	)
	(segment
		(start 327.782428 -1.017524)
		(end 327.940416 -1.017524)
		(width 0.089408)
		(layer "In9.Cu")
		(net "RST_PCIE_MIDPLANE_N")
	)
	(segment
		(start 360.525568 -10.187432)
		(end 362.217208 -10.187432)
		(width 0.089408)
		(layer "In9.Cu")
		(net "RST_PCIE_MIDPLANE_N")
	)
	(segment
		(start 373.145558 -4.176522)
		(end 375.03862 -2.28346)
		(width 0.089408)
		(layer "In9.Cu")
		(net "RST_PCIE_MIDPLANE_N")
	)
	(segment
		(start 184.543446 1.745488)
		(end 186.857894 4.059936)
		(width 0.089408)
		(layer "In9.Cu")
		(net "RST_PCIE_MIDPLANE_N")
	)
	(segment
		(start 17.386808 5.494782)
		(end 20.292314 5.494782)
		(width 0.089408)
		(layer "In9.Cu")
		(net "RST_PCIE_MIDPLANE_N")
	)
	(segment
		(start 25.13076 5.207)
		(end 103.184198 5.207)
		(width 0.089408)
		(layer "In9.Cu")
		(net "RST_PCIE_MIDPLANE_N")
	)
	(segment
		(start 167.386 -0.558546)
		(end 168.425622 -1.598168)
		(width 0.089408)
		(layer "In9.Cu")
		(net "RST_PCIE_MIDPLANE_N")
	)
	(segment
		(start 23.495508 4.166108)
		(end 24.089868 4.166108)
		(width 0.089408)
		(layer "In9.Cu")
		(net "RST_PCIE_MIDPLANE_N")
	)
	(segment
		(start 375.03862 -2.28346)
		(end 376.133614 -2.28346)
		(width 0.089408)
		(layer "In9.Cu")
		(net "RST_PCIE_MIDPLANE_N")
	)
	(segment
		(start 364.917482 -5.437886)
		(end 364.988602 -5.437886)
		(width 0.089408)
		(layer "In9.Cu")
		(net "RST_PCIE_MIDPLANE_N")
	)
	(segment
		(start 348.96298 -20.376642)
		(end 350.087184 -21.500846)
		(width 0.089408)
		(layer "In9.Cu")
		(net "RST_PCIE_MIDPLANE_N")
	)
	(segment
		(start 183.2102 -1.120902)
		(end 183.2102 -0.746252)
		(width 0.089408)
		(layer "In9.Cu")
		(net "RST_PCIE_MIDPLANE_N")
	)
	(segment
		(start 183.2102 -0.746252)
		(end 184.442354 0.485902)
		(width 0.089408)
		(layer "In9.Cu")
		(net "RST_PCIE_MIDPLANE_N")
	)
	(segment
		(start 362.939838 -9.16813)
		(end 362.939838 -7.41553)
		(width 0.089408)
		(layer "In9.Cu")
		(net "RST_PCIE_MIDPLANE_N")
	)
	(segment
		(start 358.578658 -21.849842)
		(end 359.678986 -20.749514)
		(width 0.089408)
		(layer "In9.Cu")
		(net "RST_PCIE_MIDPLANE_N")
	)
	(segment
		(start 347.79204 -17.457674)
		(end 348.96298 -18.628614)
		(width 0.089408)
		(layer "In9.Cu")
		(net "RST_PCIE_MIDPLANE_N")
	)
	(segment
		(start 351.342706 -21.500846)
		(end 352.205798 -22.363938)
		(width 0.089408)
		(layer "In9.Cu")
		(net "RST_PCIE_MIDPLANE_N")
	)
	(segment
		(start 354.98659 -22.363938)
		(end 355.333808 -22.01672)
		(width 0.089408)
		(layer "In9.Cu")
		(net "RST_PCIE_MIDPLANE_N")
	)
	(segment
		(start 168.425622 -1.598168)
		(end 171.517818 -1.598168)
		(width 0.089408)
		(layer "In9.Cu")
		(net "RST_PCIE_MIDPLANE_N")
	)
	(segment
		(start 359.678986 -20.749514)
		(end 359.678986 -19.197574)
		(width 0.089408)
		(layer "In9.Cu")
		(net "RST_PCIE_MIDPLANE_N")
	)
	(segment
		(start 352.205798 -22.363938)
		(end 354.98659 -22.363938)
		(width 0.089408)
		(layer "In9.Cu")
		(net "RST_PCIE_MIDPLANE_N")
	)
	(segment
		(start 322.570094 2.970784)
		(end 322.570094 2.45745)
		(width 0.089408)
		(layer "In9.Cu")
		(net "RST_PCIE_MIDPLANE_N")
	)
	(segment
		(start 362.940092 -9.464548)
		(end 362.940092 -9.168384)
		(width 0.089408)
		(layer "In9.Cu")
		(net "RST_PCIE_MIDPLANE_N")
	)
	(segment
		(start 362.217208 -10.187432)
		(end 362.940092 -9.464548)
		(width 0.089408)
		(layer "In9.Cu")
		(net "RST_PCIE_MIDPLANE_N")
	)
	(segment
		(start 366.092486 -4.334002)
		(end 372.973346 -4.334002)
		(width 0.089408)
		(layer "In9.Cu")
		(net "RST_PCIE_MIDPLANE_N")
	)
	(segment
		(start 20.292314 5.494782)
		(end 20.580096 5.207)
		(width 0.089408)
		(layer "In9.Cu")
		(net "RST_PCIE_MIDPLANE_N")
	)
	(segment
		(start 329.29957 -2.376678)
		(end 329.29957 -4.453382)
		(width 0.089408)
		(layer "In9.Cu")
		(net "RST_PCIE_MIDPLANE_N")
	)
	(segment
		(start 184.543446 1.721866)
		(end 184.543446 1.745488)
		(width 0.089408)
		(layer "In9.Cu")
		(net "RST_PCIE_MIDPLANE_N")
	)
	(segment
		(start 184.442354 0.485902)
		(end 184.442354 1.620774)
		(width 0.089408)
		(layer "In9.Cu")
		(net "RST_PCIE_MIDPLANE_N")
	)
	(segment
		(start 373.130826 -4.176522)
		(end 373.145558 -4.176522)
		(width 0.089408)
		(layer "In9.Cu")
		(net "RST_PCIE_MIDPLANE_N")
	)
	(segment
		(start 338.075778 -7.961884)
		(end 343.189306 -13.075412)
		(width 0.089408)
		(layer "In9.Cu")
		(net "RST_PCIE_MIDPLANE_N")
	)
	(segment
		(start 343.189306 -13.075412)
		(end 346.486988 -13.075412)
		(width 0.089408)
		(layer "In9.Cu")
		(net "RST_PCIE_MIDPLANE_N")
	)
	(segment
		(start 172.38345 -2.4638)
		(end 178.64963 -2.4638)
		(width 0.089408)
		(layer "In9.Cu")
		(net "RST_PCIE_MIDPLANE_N")
	)
	(segment
		(start 17.161256 5.26923)
		(end 17.386808 5.494782)
		(width 0.089408)
		(layer "In9.Cu")
		(net "RST_PCIE_MIDPLANE_N")
	)
	(segment
		(start 359.4608 -11.2522)
		(end 360.525568 -10.187432)
		(width 0.089408)
		(layer "In9.Cu")
		(net "RST_PCIE_MIDPLANE_N")
	)
	(segment
		(start 327.940416 -1.017524)
		(end 329.29957 -2.376678)
		(width 0.089408)
		(layer "In9.Cu")
		(net "RST_PCIE_MIDPLANE_N")
	)
	(segment
		(start 331.21346 -6.367272)
		(end 335.200244 -6.367272)
		(width 0.089408)
		(layer "In9.Cu")
		(net "RST_PCIE_MIDPLANE_N")
	)
	(segment
		(start 20.580096 5.207)
		(end 22.454616 5.207)
		(width 0.089408)
		(layer "In9.Cu")
		(net "RST_PCIE_MIDPLANE_N")
	)
	(segment
		(start 178.992276 -2.806446)
		(end 181.524656 -2.806446)
		(width 0.089408)
		(layer "In9.Cu")
		(net "RST_PCIE_MIDPLANE_N")
	)
	(segment
		(start 360.433366 -18.443194)
		(end 360.433366 -13.725398)
		(width 0.089408)
		(layer "In9.Cu")
		(net "RST_PCIE_MIDPLANE_N")
	)
	(segment
		(start 362.939838 -7.41553)
		(end 364.917482 -5.437886)
		(width 0.089408)
		(layer "In9.Cu")
		(net "RST_PCIE_MIDPLANE_N")
	)
	(segment
		(start 326.045322 -1.017778)
		(end 327.782174 -1.017778)
		(width 0.089408)
		(layer "In9.Cu")
		(net "RST_PCIE_MIDPLANE_N")
	)
	(segment
		(start 184.442354 1.620774)
		(end 184.543446 1.721866)
		(width 0.089408)
		(layer "In9.Cu")
		(net "RST_PCIE_MIDPLANE_N")
	)
	(segment
		(start 24.089868 4.166108)
		(end 25.13076 5.207)
		(width 0.089408)
		(layer "In9.Cu")
		(net "RST_PCIE_MIDPLANE_N")
	)
	(segment
		(start 355.96195 -22.01672)
		(end 356.128828 -21.849842)
		(width 0.089408)
		(layer "In9.Cu")
		(net "RST_PCIE_MIDPLANE_N")
	)
	(segment
		(start 376.133614 -2.28346)
		(end 377.251468 -1.165606)
		(width 0.089408)
		(layer "In9.Cu")
		(net "RST_PCIE_MIDPLANE_N")
	)
	(segment
		(start 355.333808 -22.01672)
		(end 355.96195 -22.01672)
		(width 0.089408)
		(layer "In9.Cu")
		(net "RST_PCIE_MIDPLANE_N")
	)
	(segment
		(start 346.486988 -13.075412)
		(end 347.79204 -14.380464)
		(width 0.089408)
		(layer "In9.Cu")
		(net "RST_PCIE_MIDPLANE_N")
	)
	(segment
		(start 171.517818 -1.598168)
		(end 172.38345 -2.4638)
		(width 0.089408)
		(layer "In9.Cu")
		(net "RST_PCIE_MIDPLANE_N")
	)
	(segment
		(start 347.79204 -14.380464)
		(end 347.79204 -17.457674)
		(width 0.089408)
		(layer "In9.Cu")
		(net "RST_PCIE_MIDPLANE_N")
	)
	(segment
		(start 372.973346 -4.334002)
		(end 373.130826 -4.176522)
		(width 0.089408)
		(layer "In9.Cu")
		(net "RST_PCIE_MIDPLANE_N")
	)
	(segment
		(start 350.087184 -21.500846)
		(end 351.342706 -21.500846)
		(width 0.089408)
		(layer "In9.Cu")
		(net "RST_PCIE_MIDPLANE_N")
	)
	(segment
		(start 359.678986 -19.197574)
		(end 360.433366 -18.443194)
		(width 0.089408)
		(layer "In9.Cu")
		(net "RST_PCIE_MIDPLANE_N")
	)
	(segment
		(start 364.988602 -5.437886)
		(end 366.092486 -4.334002)
		(width 0.089408)
		(layer "In9.Cu")
		(net "RST_PCIE_MIDPLANE_N")
	)
	(segment
		(start 348.96298 -18.628614)
		(end 348.96298 -20.376642)
		(width 0.089408)
		(layer "In9.Cu")
		(net "RST_PCIE_MIDPLANE_N")
	)
	(segment
		(start 336.794856 -7.961884)
		(end 338.075778 -7.961884)
		(width 0.089408)
		(layer "In9.Cu")
		(net "RST_PCIE_MIDPLANE_N")
	)
	(segment
		(start 167.386 2.374138)
		(end 167.386 -0.558546)
		(width 0.089408)
		(layer "In9.Cu")
		(net "RST_PCIE_MIDPLANE_N")
	)
	(segment
		(start 186.857894 4.059936)
		(end 321.480942 4.059936)
		(width 0.089408)
		(layer "In9.Cu")
		(net "RST_PCIE_MIDPLANE_N")
	)
	(segment
		(start 322.570094 2.45745)
		(end 326.045322 -1.017778)
		(width 0.089408)
		(layer "In9.Cu")
		(net "RST_PCIE_MIDPLANE_N")
	)
	(segment
		(start 165.283642 4.476496)
		(end 167.386 2.374138)
		(width 0.089408)
		(layer "In9.Cu")
		(net "RST_PCIE_MIDPLANE_N")
	)
	(segment
		(start 327.782174 -1.017778)
		(end 327.782428 -1.017524)
		(width 0.089408)
		(layer "In9.Cu")
		(net "RST_PCIE_MIDPLANE_N")
	)
	(segment
		(start 359.4608 -12.752832)
		(end 359.4608 -11.2522)
		(width 0.089408)
		(layer "In9.Cu")
		(net "RST_PCIE_MIDPLANE_N")
	)
	(segment
		(start 8.510016 3.1242)
		(end 1.631696 -3.75412)
		(width 0.089408)
		(layer "In11.Cu")
		(net "RST_PCIE_MIDPLANE_N")
	)
	(segment
		(start 13.997432 3.1242)
		(end 8.510016 3.1242)
		(width 0.089408)
		(layer "In11.Cu")
		(net "RST_PCIE_MIDPLANE_N")
	)
	(segment
		(start -4.8006 -4.559554)
		(end -4.8006 -15.4813)
		(width 0.089408)
		(layer "In11.Cu")
		(net "RST_PCIE_MIDPLANE_N")
	)
	(segment
		(start -5.093208 -32.463994)
		(end -4.751832 -32.80537)
		(width 0.089408)
		(layer "In11.Cu")
		(net "RST_PCIE_MIDPLANE_N")
	)
	(segment
		(start -5.093208 -30.677104)
		(end -5.093208 -32.463994)
		(width 0.089408)
		(layer "In11.Cu")
		(net "RST_PCIE_MIDPLANE_N")
	)
	(segment
		(start -5.434584 -16.115284)
		(end -5.434584 -30.335728)
		(width 0.089408)
		(layer "In11.Cu")
		(net "RST_PCIE_MIDPLANE_N")
	)
	(segment
		(start -4.8006 -15.4813)
		(end -5.434584 -16.115284)
		(width 0.089408)
		(layer "In11.Cu")
		(net "RST_PCIE_MIDPLANE_N")
	)
	(segment
		(start 16.939006 5.49148)
		(end 15.901924 5.49148)
		(width 0.089408)
		(layer "In11.Cu")
		(net "RST_PCIE_MIDPLANE_N")
	)
	(segment
		(start 15.901924 5.49148)
		(end 15.39494 4.984496)
		(width 0.089408)
		(layer "In11.Cu")
		(net "RST_PCIE_MIDPLANE_N")
	)
	(segment
		(start 17.161256 5.26923)
		(end 16.939006 5.49148)
		(width 0.089408)
		(layer "In11.Cu")
		(net "RST_PCIE_MIDPLANE_N")
	)
	(segment
		(start -4.751832 -32.80537)
		(end 5.07492 -32.80537)
		(width 0.089408)
		(layer "In11.Cu")
		(net "RST_PCIE_MIDPLANE_N")
	)
	(segment
		(start -3.995166 -3.75412)
		(end -4.8006 -4.559554)
		(width 0.089408)
		(layer "In11.Cu")
		(net "RST_PCIE_MIDPLANE_N")
	)
	(segment
		(start 15.39494 4.984496)
		(end 15.39494 4.521708)
		(width 0.089408)
		(layer "In11.Cu")
		(net "RST_PCIE_MIDPLANE_N")
	)
	(segment
		(start 5.11429 -32.766)
		(end 6.244082 -32.766)
		(width 0.089408)
		(layer "In11.Cu")
		(net "RST_PCIE_MIDPLANE_N")
	)
	(segment
		(start 5.07492 -32.80537)
		(end 5.11429 -32.766)
		(width 0.089408)
		(layer "In11.Cu")
		(net "RST_PCIE_MIDPLANE_N")
	)
	(segment
		(start -5.434584 -30.335728)
		(end -5.093208 -30.677104)
		(width 0.089408)
		(layer "In11.Cu")
		(net "RST_PCIE_MIDPLANE_N")
	)
	(segment
		(start 15.39494 4.521708)
		(end 13.997432 3.1242)
		(width 0.089408)
		(layer "In11.Cu")
		(net "RST_PCIE_MIDPLANE_N")
	)
	(segment
		(start 1.631696 -3.75412)
		(end -3.995166 -3.75412)
		(width 0.089408)
		(layer "In11.Cu")
		(net "RST_PCIE_MIDPLANE_N")
	)
	(segment
		(start 6.244082 -32.766)
		(end 7.29996 -31.710122)
		(width 0.089408)
		(layer "In11.Cu")
		(net "RST_PCIE_MIDPLANE_N")
	)
	(segment
		(start 424.4467 -124.6759)
		(end 424.9547 -124.6759)
		(width 0.10795)
		(layer "F.Cu")
		(net "RST_HFI1_CPU0_LVT2_N")
	)
	(segment
		(start 288.36366 -75.716384)
		(end 288.93516 -75.716384)
		(width 0.1016)
		(layer "F.Cu")
		(net "RST_HFI1_CPU0_LVT2_N")
	)
	(segment
		(start 424.9547 -124.6759)
		(end 425.196 -124.9172)
		(width 0.10795)
		(layer "F.Cu")
		(net "RST_HFI1_CPU0_LVT2_N")
	)
	(segment
		(start 425.196 -124.9172)
		(end 425.5643 -124.9172)
		(width 0.10795)
		(layer "F.Cu")
		(net "RST_HFI1_CPU0_LVT2_N")
	)
	(segment
		(start 420.779194 -126.740412)
		(end 422.285668 -126.740412)
		(width 0.10795)
		(layer "F.Cu")
		(net "RST_HFI1_CPU0_LVT2_N")
	)
	(segment
		(start 422.285668 -126.740412)
		(end 424.35018 -124.6759)
		(width 0.10795)
		(layer "F.Cu")
		(net "RST_HFI1_CPU0_LVT2_N")
	)
	(segment
		(start 424.35018 -124.6759)
		(end 424.4467 -124.6759)
		(width 0.10795)
		(layer "F.Cu")
		(net "RST_HFI1_CPU0_LVT2_N")
	)
	(via
		(at 337.8454 -88.9254)
		(size 0.508)
		(drill 0.254)
		(layers "F.Cu" "B.Cu")
		(net "RST_HFI1_CPU0_LVT2_N")
	)
	(via
		(at 342.071706 -117.75821)
		(size 0.508)
		(drill 0.254)
		(layers "F.Cu" "B.Cu")
		(net "RST_HFI1_CPU0_LVT2_N")
	)
	(via
		(at 331.181964 -74.25563)
		(size 0.508)
		(drill 0.254)
		(layers "F.Cu" "B.Cu")
		(net "RST_HFI1_CPU0_LVT2_N")
	)
	(via
		(at 334.729836 -86.927436)
		(size 0.6604)
		(drill 0.3302)
		(layers "F.Cu" "B.Cu")
		(net "RST_HFI1_CPU0_LVT2_N")
	)
	(via
		(at 288.93516 -75.716384)
		(size 0.508)
		(drill 0.254)
		(layers "F.Cu" "B.Cu")
		(net "RST_HFI1_CPU0_LVT2_N")
	)
	(via
		(at 424.4467 -124.6759)
		(size 0.508)
		(drill 0.254)
		(layers "F.Cu" "B.Cu")
		(net "RST_HFI1_CPU0_LVT2_N")
	)
	(segment
		(start 333.054198 -75.49261)
		(end 333.054198 -78.169262)
		(width 0.10795)
		(layer "B.Cu")
		(net "RST_HFI1_CPU0_LVT2_N")
	)
	(segment
		(start 336.7278 -88.9254)
		(end 337.8454 -88.9254)
		(width 0.10795)
		(layer "B.Cu")
		(net "RST_HFI1_CPU0_LVT2_N")
	)
	(segment
		(start 331.181964 -74.25563)
		(end 331.817218 -74.25563)
		(width 0.10795)
		(layer "B.Cu")
		(net "RST_HFI1_CPU0_LVT2_N")
	)
	(segment
		(start 334.729836 -86.927436)
		(end 336.7278 -88.9254)
		(width 0.10795)
		(layer "B.Cu")
		(net "RST_HFI1_CPU0_LVT2_N")
	)
	(segment
		(start 331.817218 -74.25563)
		(end 333.054198 -75.49261)
		(width 0.10795)
		(layer "B.Cu")
		(net "RST_HFI1_CPU0_LVT2_N")
	)
	(segment
		(start 333.054198 -78.169262)
		(end 334.423512 -79.538576)
		(width 0.10795)
		(layer "B.Cu")
		(net "RST_HFI1_CPU0_LVT2_N")
	)
	(segment
		(start 334.423512 -79.538576)
		(end 334.423512 -86.621112)
		(width 0.10795)
		(layer "B.Cu")
		(net "RST_HFI1_CPU0_LVT2_N")
	)
	(segment
		(start 334.423512 -86.621112)
		(end 334.729836 -86.927436)
		(width 0.10795)
		(layer "B.Cu")
		(net "RST_HFI1_CPU0_LVT2_N")
	)
	(segment
		(start 339.365844 -118.432326)
		(end 337.873848 -116.94033)
		(width 0.089408)
		(layer "In4.Cu")
		(net "RST_HFI1_CPU0_LVT2_N")
	)
	(segment
		(start 331.836268 -95.328486)
		(end 331.836522 -95.328232)
		(width 0.089408)
		(layer "In4.Cu")
		(net "RST_HFI1_CPU0_LVT2_N")
	)
	(segment
		(start 335.800192 -114.863626)
		(end 334.201262 -113.264696)
		(width 0.089408)
		(layer "In4.Cu")
		(net "RST_HFI1_CPU0_LVT2_N")
	)
	(segment
		(start 334.435704 -112.560862)
		(end 334.435704 -111.548164)
		(width 0.089408)
		(layer "In4.Cu")
		(net "RST_HFI1_CPU0_LVT2_N")
	)
	(segment
		(start 334.435704 -111.548164)
		(end 333.530702 -110.643162)
		(width 0.089408)
		(layer "In4.Cu")
		(net "RST_HFI1_CPU0_LVT2_N")
	)
	(segment
		(start 331.836522 -96.901)
		(end 331.836268 -96.900746)
		(width 0.089408)
		(layer "In4.Cu")
		(net "RST_HFI1_CPU0_LVT2_N")
	)
	(segment
		(start 333.530702 -110.643162)
		(end 333.530702 -108.172504)
		(width 0.089408)
		(layer "In4.Cu")
		(net "RST_HFI1_CPU0_LVT2_N")
	)
	(segment
		(start 331.836522 -95.328232)
		(end 331.836522 -95.061532)
		(width 0.089408)
		(layer "In4.Cu")
		(net "RST_HFI1_CPU0_LVT2_N")
	)
	(segment
		(start 342.071706 -117.75821)
		(end 341.39759 -118.432326)
		(width 0.089408)
		(layer "In4.Cu")
		(net "RST_HFI1_CPU0_LVT2_N")
	)
	(segment
		(start 333.530702 -108.172504)
		(end 331.836522 -106.478324)
		(width 0.089408)
		(layer "In4.Cu")
		(net "RST_HFI1_CPU0_LVT2_N")
	)
	(segment
		(start 331.836268 -96.900746)
		(end 331.836268 -95.328486)
		(width 0.089408)
		(layer "In4.Cu")
		(net "RST_HFI1_CPU0_LVT2_N")
	)
	(segment
		(start 335.800192 -115.995958)
		(end 335.800192 -114.863626)
		(width 0.089408)
		(layer "In4.Cu")
		(net "RST_HFI1_CPU0_LVT2_N")
	)
	(segment
		(start 334.201262 -113.264696)
		(end 334.201262 -112.795304)
		(width 0.089408)
		(layer "In4.Cu")
		(net "RST_HFI1_CPU0_LVT2_N")
	)
	(segment
		(start 336.744564 -116.94033)
		(end 335.800192 -115.995958)
		(width 0.089408)
		(layer "In4.Cu")
		(net "RST_HFI1_CPU0_LVT2_N")
	)
	(segment
		(start 334.201262 -112.795304)
		(end 334.435704 -112.560862)
		(width 0.089408)
		(layer "In4.Cu")
		(net "RST_HFI1_CPU0_LVT2_N")
	)
	(segment
		(start 331.836522 -106.478324)
		(end 331.836522 -96.901)
		(width 0.089408)
		(layer "In4.Cu")
		(net "RST_HFI1_CPU0_LVT2_N")
	)
	(segment
		(start 337.8454 -89.052654)
		(end 337.8454 -88.9254)
		(width 0.089408)
		(layer "In4.Cu")
		(net "RST_HFI1_CPU0_LVT2_N")
	)
	(segment
		(start 331.836522 -95.061532)
		(end 337.8454 -89.052654)
		(width 0.089408)
		(layer "In4.Cu")
		(net "RST_HFI1_CPU0_LVT2_N")
	)
	(segment
		(start 337.873848 -116.94033)
		(end 336.744564 -116.94033)
		(width 0.089408)
		(layer "In4.Cu")
		(net "RST_HFI1_CPU0_LVT2_N")
	)
	(segment
		(start 341.39759 -118.432326)
		(end 339.365844 -118.432326)
		(width 0.089408)
		(layer "In4.Cu")
		(net "RST_HFI1_CPU0_LVT2_N")
	)
	(segment
		(start 399.4023 -133.449822)
		(end 400.885406 -133.449822)
		(width 0.089408)
		(layer "In11.Cu")
		(net "RST_HFI1_CPU0_LVT2_N")
	)
	(segment
		(start 297.17619 -73.938892)
		(end 297.173904 -73.935082)
		(width 0.089408)
		(layer "In11.Cu")
		(net "RST_HFI1_CPU0_LVT2_N")
	)
	(segment
		(start 308.779926 -74.25563)
		(end 307.909468 -75.126088)
		(width 0.089408)
		(layer "In11.Cu")
		(net "RST_HFI1_CPU0_LVT2_N")
	)
	(segment
		(start 404.385272 -129.950464)
		(end 409.015184 -129.950464)
		(width 0.089408)
		(layer "In11.Cu")
		(net "RST_HFI1_CPU0_LVT2_N")
	)
	(segment
		(start 373.144542 -125.971046)
		(end 373.144542 -125.9713)
		(width 0.089408)
		(layer "In11.Cu")
		(net "RST_HFI1_CPU0_LVT2_N")
	)
	(segment
		(start 372.784878 -125.611128)
		(end 373.114062 -125.940312)
		(width 0.089408)
		(layer "In11.Cu")
		(net "RST_HFI1_CPU0_LVT2_N")
	)
	(segment
		(start 291.517832 -74.630534)
		(end 291.48659 -74.630534)
		(width 0.089408)
		(layer "In11.Cu")
		(net "RST_HFI1_CPU0_LVT2_N")
	)
	(segment
		(start 371.260624 -120.884188)
		(end 372.784878 -122.408442)
		(width 0.089408)
		(layer "In11.Cu")
		(net "RST_HFI1_CPU0_LVT2_N")
	)
	(segment
		(start 385.279392 -128.278128)
		(end 385.591304 -128.59004)
		(width 0.089408)
		(layer "In11.Cu")
		(net "RST_HFI1_CPU0_LVT2_N")
	)
	(segment
		(start 385.591304 -129.168652)
		(end 390.614916 -134.192264)
		(width 0.089408)
		(layer "In11.Cu")
		(net "RST_HFI1_CPU0_LVT2_N")
	)
	(segment
		(start 400.885406 -133.449822)
		(end 404.385272 -129.950464)
		(width 0.089408)
		(layer "In11.Cu")
		(net "RST_HFI1_CPU0_LVT2_N")
	)
	(segment
		(start 345.924378 -118.123716)
		(end 367.793524 -118.123716)
		(width 0.089408)
		(layer "In11.Cu")
		(net "RST_HFI1_CPU0_LVT2_N")
	)
	(segment
		(start 373.114062 -125.940566)
		(end 373.144542 -125.971046)
		(width 0.089408)
		(layer "In11.Cu")
		(net "RST_HFI1_CPU0_LVT2_N")
	)
	(segment
		(start 398.659858 -134.192264)
		(end 399.4023 -133.449822)
		(width 0.089408)
		(layer "In11.Cu")
		(net "RST_HFI1_CPU0_LVT2_N")
	)
	(segment
		(start 420.26078 -128.86182)
		(end 424.4467 -124.6759)
		(width 0.089408)
		(layer "In11.Cu")
		(net "RST_HFI1_CPU0_LVT2_N")
	)
	(segment
		(start 290.664392 -75.12558)
		(end 290.631626 -75.12558)
		(width 0.089408)
		(layer "In11.Cu")
		(net "RST_HFI1_CPU0_LVT2_N")
	)
	(segment
		(start 292.381432 -74.13498)
		(end 292.348666 -74.13498)
		(width 0.089408)
		(layer "In11.Cu")
		(net "RST_HFI1_CPU0_LVT2_N")
	)
	(segment
		(start 373.505222 -126.33198)
		(end 374.510554 -126.33198)
		(width 0.089408)
		(layer "In11.Cu")
		(net "RST_HFI1_CPU0_LVT2_N")
	)
	(segment
		(start 370.553996 -120.884188)
		(end 371.260624 -120.884188)
		(width 0.089408)
		(layer "In11.Cu")
		(net "RST_HFI1_CPU0_LVT2_N")
	)
	(segment
		(start 380.742444 -126.130812)
		(end 380.971044 -125.902212)
		(width 0.089408)
		(layer "In11.Cu")
		(net "RST_HFI1_CPU0_LVT2_N")
	)
	(segment
		(start 331.181964 -74.25563)
		(end 308.779926 -74.25563)
		(width 0.089408)
		(layer "In11.Cu")
		(net "RST_HFI1_CPU0_LVT2_N")
	)
	(segment
		(start 415.20237 -129.48285)
		(end 416.88766 -129.48285)
		(width 0.089408)
		(layer "In11.Cu")
		(net "RST_HFI1_CPU0_LVT2_N")
	)
	(segment
		(start 413.822896 -130.862324)
		(end 415.20237 -129.48285)
		(width 0.089408)
		(layer "In11.Cu")
		(net "RST_HFI1_CPU0_LVT2_N")
	)
	(segment
		(start 367.793524 -118.123716)
		(end 370.553996 -120.884188)
		(width 0.089408)
		(layer "In11.Cu")
		(net "RST_HFI1_CPU0_LVT2_N")
	)
	(segment
		(start 416.88766 -129.48285)
		(end 417.50869 -128.86182)
		(width 0.089408)
		(layer "In11.Cu")
		(net "RST_HFI1_CPU0_LVT2_N")
	)
	(segment
		(start 345.558872 -117.75821)
		(end 345.924378 -118.123716)
		(width 0.089408)
		(layer "In11.Cu")
		(net "RST_HFI1_CPU0_LVT2_N")
	)
	(segment
		(start 417.50869 -128.86182)
		(end 420.26078 -128.86182)
		(width 0.089408)
		(layer "In11.Cu")
		(net "RST_HFI1_CPU0_LVT2_N")
	)
	(segment
		(start 374.711722 -126.130812)
		(end 380.742444 -126.130812)
		(width 0.089408)
		(layer "In11.Cu")
		(net "RST_HFI1_CPU0_LVT2_N")
	)
	(segment
		(start 374.510554 -126.33198)
		(end 374.711722 -126.130812)
		(width 0.089408)
		(layer "In11.Cu")
		(net "RST_HFI1_CPU0_LVT2_N")
	)
	(segment
		(start 380.971044 -125.902212)
		(end 384.301238 -125.902212)
		(width 0.089408)
		(layer "In11.Cu")
		(net "RST_HFI1_CPU0_LVT2_N")
	)
	(segment
		(start 409.015184 -129.950464)
		(end 409.927044 -130.862324)
		(width 0.089408)
		(layer "In11.Cu")
		(net "RST_HFI1_CPU0_LVT2_N")
	)
	(segment
		(start 390.614916 -134.192264)
		(end 398.659858 -134.192264)
		(width 0.089408)
		(layer "In11.Cu")
		(net "RST_HFI1_CPU0_LVT2_N")
	)
	(segment
		(start 385.591304 -128.59004)
		(end 385.591304 -129.168652)
		(width 0.089408)
		(layer "In11.Cu")
		(net "RST_HFI1_CPU0_LVT2_N")
	)
	(segment
		(start 342.071706 -117.75821)
		(end 345.558872 -117.75821)
		(width 0.089408)
		(layer "In11.Cu")
		(net "RST_HFI1_CPU0_LVT2_N")
	)
	(segment
		(start 293.234872 -73.639934)
		(end 293.20363 -73.639934)
		(width 0.089408)
		(layer "In11.Cu")
		(net "RST_HFI1_CPU0_LVT2_N")
	)
	(segment
		(start 409.927044 -130.862324)
		(end 413.822896 -130.862324)
		(width 0.089408)
		(layer "In11.Cu")
		(net "RST_HFI1_CPU0_LVT2_N")
	)
	(segment
		(start 384.301238 -125.902212)
		(end 385.279392 -126.880366)
		(width 0.089408)
		(layer "In11.Cu")
		(net "RST_HFI1_CPU0_LVT2_N")
	)
	(segment
		(start 289.79368 -75.716638)
		(end 288.93516 -75.716384)
		(width 0.089408)
		(layer "In11.Cu")
		(net "RST_HFI1_CPU0_LVT2_N")
	)
	(segment
		(start 296.68597 -73.639934)
		(end 296.654728 -73.639934)
		(width 0.089408)
		(layer "In11.Cu")
		(net "RST_HFI1_CPU0_LVT2_N")
	)
	(segment
		(start 385.279392 -126.880366)
		(end 385.279392 -128.278128)
		(width 0.089408)
		(layer "In11.Cu")
		(net "RST_HFI1_CPU0_LVT2_N")
	)
	(segment
		(start 307.909468 -75.126088)
		(end 306.098194 -75.126088)
		(width 0.089408)
		(layer "In11.Cu")
		(net "RST_HFI1_CPU0_LVT2_N")
	)
	(segment
		(start 297.54068 -74.13498)
		(end 297.520106 -74.13498)
		(width 0.089408)
		(layer "In11.Cu")
		(net "RST_HFI1_CPU0_LVT2_N")
	)
	(segment
		(start 372.784878 -122.408442)
		(end 372.784878 -125.611128)
		(width 0.089408)
		(layer "In11.Cu")
		(net "RST_HFI1_CPU0_LVT2_N")
	)
	(segment
		(start 373.114062 -125.940312)
		(end 373.114062 -125.940566)
		(width 0.089408)
		(layer "In11.Cu")
		(net "RST_HFI1_CPU0_LVT2_N")
	)
	(segment
		(start 373.144542 -125.9713)
		(end 373.505222 -126.33198)
		(width 0.089408)
		(layer "In11.Cu")
		(net "RST_HFI1_CPU0_LVT2_N")
	)
	(segment
		(start 305.26736 -74.630534)
		(end 305.239674 -74.630534)
		(width 0.089408)
		(layer "In11.Cu")
		(net "RST_HFI1_CPU0_LVT2_N")
	)
	(arc
		(start 304.90033 -74.430382)
		(mid 304.388266 -74.134623)
		(end 303.876202 -74.430382)
		(width 0.089408)
		(layer "In11.Cu")
		(net "RST_HFI1_CPU0_LVT2_N")
	)
	(arc
		(start 295.291256 -73.439782)
		(mid 294.9448 -73.64)
		(end 294.598344 -73.439782)
		(width 0.089408)
		(layer "In11.Cu")
		(net "RST_HFI1_CPU0_LVT2_N")
	)
	(arc
		(start 290.17595 -75.365864)
		(mid 290.127562 -75.442022)
		(end 290.090098 -75.524106)
		(width 0.089408)
		(layer "In11.Cu")
		(net "RST_HFI1_CPU0_LVT2_N")
	)
	(arc
		(start 294.598344 -73.439782)
		(mid 294.08628 -73.144023)
		(end 293.574216 -73.439782)
		(width 0.089408)
		(layer "In11.Cu")
		(net "RST_HFI1_CPU0_LVT2_N")
	)
	(arc
		(start 300.442122 -74.430382)
		(mid 300.095666 -74.6306)
		(end 299.74921 -74.430382)
		(width 0.089408)
		(layer "In11.Cu")
		(net "RST_HFI1_CPU0_LVT2_N")
	)
	(arc
		(start 290.998656 -74.925682)
		(mid 290.857499 -75.069067)
		(end 290.664392 -75.12558)
		(width 0.089408)
		(layer "In11.Cu")
		(net "RST_HFI1_CPU0_LVT2_N")
	)
	(arc
		(start 293.574216 -73.439782)
		(mid 293.430905 -73.584553)
		(end 293.234872 -73.639934)
		(width 0.089408)
		(layer "In11.Cu")
		(net "RST_HFI1_CPU0_LVT2_N")
	)
	(arc
		(start 305.75885 -74.925936)
		(mid 305.551321 -74.714652)
		(end 305.26736 -74.630534)
		(width 0.089408)
		(layer "In11.Cu")
		(net "RST_HFI1_CPU0_LVT2_N")
	)
	(arc
		(start 292.348666 -74.13498)
		(mid 292.064705 -74.219098)
		(end 291.857176 -74.430382)
		(width 0.089408)
		(layer "In11.Cu")
		(net "RST_HFI1_CPU0_LVT2_N")
	)
	(arc
		(start 296.315384 -73.439782)
		(mid 295.80332 -73.144023)
		(end 295.291256 -73.439782)
		(width 0.089408)
		(layer "In11.Cu")
		(net "RST_HFI1_CPU0_LVT2_N")
	)
	(arc
		(start 297.520106 -74.13498)
		(mid 297.322173 -74.082506)
		(end 297.17619 -73.938892)
		(width 0.089408)
		(layer "In11.Cu")
		(net "RST_HFI1_CPU0_LVT2_N")
	)
	(arc
		(start 290.631626 -75.12558)
		(mid 290.37623 -75.193466)
		(end 290.17595 -75.365864)
		(width 0.089408)
		(layer "In11.Cu")
		(net "RST_HFI1_CPU0_LVT2_N")
	)
	(arc
		(start 293.20363 -73.639934)
		(mid 292.921728 -73.724797)
		(end 292.715696 -73.935082)
		(width 0.089408)
		(layer "In11.Cu")
		(net "RST_HFI1_CPU0_LVT2_N")
	)
	(arc
		(start 292.715696 -73.935082)
		(mid 292.574539 -74.078467)
		(end 292.381432 -74.13498)
		(width 0.089408)
		(layer "In11.Cu")
		(net "RST_HFI1_CPU0_LVT2_N")
	)
	(arc
		(start 303.876202 -74.430382)
		(mid 303.529746 -74.6306)
		(end 303.18329 -74.430382)
		(width 0.089408)
		(layer "In11.Cu")
		(net "RST_HFI1_CPU0_LVT2_N")
	)
	(arc
		(start 298.725082 -74.430382)
		(mid 298.378626 -74.6306)
		(end 298.03217 -74.430382)
		(width 0.089408)
		(layer "In11.Cu")
		(net "RST_HFI1_CPU0_LVT2_N")
	)
	(arc
		(start 290.090098 -75.524106)
		(mid 289.973523 -75.669081)
		(end 289.79368 -75.716638)
		(width 0.089408)
		(layer "In11.Cu")
		(net "RST_HFI1_CPU0_LVT2_N")
	)
	(arc
		(start 305.239674 -74.630534)
		(mid 305.043642 -74.57515)
		(end 304.90033 -74.430382)
		(width 0.089408)
		(layer "In11.Cu")
		(net "RST_HFI1_CPU0_LVT2_N")
	)
	(arc
		(start 291.857176 -74.430382)
		(mid 291.713865 -74.575153)
		(end 291.517832 -74.630534)
		(width 0.089408)
		(layer "In11.Cu")
		(net "RST_HFI1_CPU0_LVT2_N")
	)
	(arc
		(start 301.46625 -74.430382)
		(mid 300.954186 -74.134623)
		(end 300.442122 -74.430382)
		(width 0.089408)
		(layer "In11.Cu")
		(net "RST_HFI1_CPU0_LVT2_N")
	)
	(arc
		(start 291.48659 -74.630534)
		(mid 291.204688 -74.715397)
		(end 290.998656 -74.925682)
		(width 0.089408)
		(layer "In11.Cu")
		(net "RST_HFI1_CPU0_LVT2_N")
	)
	(arc
		(start 297.173904 -73.935082)
		(mid 296.967867 -73.724804)
		(end 296.68597 -73.639934)
		(width 0.089408)
		(layer "In11.Cu")
		(net "RST_HFI1_CPU0_LVT2_N")
	)
	(arc
		(start 299.74921 -74.430382)
		(mid 299.237146 -74.134623)
		(end 298.725082 -74.430382)
		(width 0.089408)
		(layer "In11.Cu")
		(net "RST_HFI1_CPU0_LVT2_N")
	)
	(arc
		(start 298.03217 -74.430382)
		(mid 297.824641 -74.219098)
		(end 297.54068 -74.13498)
		(width 0.089408)
		(layer "In11.Cu")
		(net "RST_HFI1_CPU0_LVT2_N")
	)
	(arc
		(start 302.159162 -74.430382)
		(mid 301.812706 -74.6306)
		(end 301.46625 -74.430382)
		(width 0.089408)
		(layer "In11.Cu")
		(net "RST_HFI1_CPU0_LVT2_N")
	)
	(arc
		(start 306.098194 -75.126088)
		(mid 305.902162 -75.070704)
		(end 305.75885 -74.925936)
		(width 0.089408)
		(layer "In11.Cu")
		(net "RST_HFI1_CPU0_LVT2_N")
	)
	(arc
		(start 303.18329 -74.430382)
		(mid 302.671226 -74.134623)
		(end 302.159162 -74.430382)
		(width 0.089408)
		(layer "In11.Cu")
		(net "RST_HFI1_CPU0_LVT2_N")
	)
	(arc
		(start 296.654728 -73.639934)
		(mid 296.458696 -73.58455)
		(end 296.315384 -73.439782)
		(width 0.089408)
		(layer "In11.Cu")
		(net "RST_HFI1_CPU0_LVT2_N")
	)
	(segment
		(start 420.054024 -130.740404)
		(end 420.779194 -130.740404)
		(width 0.10795)
		(layer "F.Cu")
		(net "RST_HFI0_CPU0_LVT2_N")
	)
	(segment
		(start 419.866064 -130.927856)
		(end 420.05377 -130.74015)
		(width 0.10795)
		(layer "F.Cu")
		(net "RST_HFI0_CPU0_LVT2_N")
	)
	(segment
		(start 420.779194 -130.740404)
		(end 423.164 -130.740404)
		(width 0.10795)
		(layer "F.Cu")
		(net "RST_HFI0_CPU0_LVT2_N")
	)
	(segment
		(start 423.9387 -129.4765)
		(end 425.2595 -128.1557)
		(width 0.10795)
		(layer "F.Cu")
		(net "RST_HFI0_CPU0_LVT2_N")
	)
	(segment
		(start 419.691312 -130.927856)
		(end 419.866064 -130.927856)
		(width 0.10795)
		(layer "F.Cu")
		(net "RST_HFI0_CPU0_LVT2_N")
	)
	(segment
		(start 423.164 -130.74015)
		(end 423.60215 -130.74015)
		(width 0.10795)
		(layer "F.Cu")
		(net "RST_HFI0_CPU0_LVT2_N")
	)
	(segment
		(start 423.164 -130.740404)
		(end 423.164 -130.74015)
		(width 0.10795)
		(layer "F.Cu")
		(net "RST_HFI0_CPU0_LVT2_N")
	)
	(segment
		(start 420.05377 -130.74015)
		(end 420.054024 -130.740404)
		(width 0.10795)
		(layer "F.Cu")
		(net "RST_HFI0_CPU0_LVT2_N")
	)
	(segment
		(start 419.264846 -131.354322)
		(end 419.691312 -130.927856)
		(width 0.10795)
		(layer "F.Cu")
		(net "RST_HFI0_CPU0_LVT2_N")
	)
	(segment
		(start 423.9387 -130.4036)
		(end 423.9387 -129.4765)
		(width 0.10795)
		(layer "F.Cu")
		(net "RST_HFI0_CPU0_LVT2_N")
	)
	(segment
		(start 417.23818 -130.794506)
		(end 417.797996 -131.354322)
		(width 0.10795)
		(layer "F.Cu")
		(net "RST_HFI0_CPU0_LVT2_N")
	)
	(segment
		(start 287.50514 -77.202538)
		(end 288.07664 -77.202538)
		(width 0.1016)
		(layer "F.Cu")
		(net "RST_HFI0_CPU0_LVT2_N")
	)
	(segment
		(start 417.797996 -131.354322)
		(end 419.264846 -131.354322)
		(width 0.10795)
		(layer "F.Cu")
		(net "RST_HFI0_CPU0_LVT2_N")
	)
	(segment
		(start 425.2595 -128.1557)
		(end 425.6405 -128.1557)
		(width 0.10795)
		(layer "F.Cu")
		(net "RST_HFI0_CPU0_LVT2_N")
	)
	(segment
		(start 423.60215 -130.74015)
		(end 423.9387 -130.4036)
		(width 0.10795)
		(layer "F.Cu")
		(net "RST_HFI0_CPU0_LVT2_N")
	)
	(via
		(at 336.24901 -117.739922)
		(size 0.508)
		(drill 0.254)
		(layers "F.Cu" "B.Cu")
		(net "RST_HFI0_CPU0_LVT2_N")
	)
	(via
		(at 332.457298 -72.39381)
		(size 0.508)
		(drill 0.254)
		(layers "F.Cu" "B.Cu")
		(net "RST_HFI0_CPU0_LVT2_N")
	)
	(via
		(at 288.07664 -77.202538)
		(size 0.508)
		(drill 0.254)
		(layers "F.Cu" "B.Cu")
		(net "RST_HFI0_CPU0_LVT2_N")
	)
	(via
		(at 417.23818 -130.794506)
		(size 0.508)
		(drill 0.254)
		(layers "F.Cu" "B.Cu")
		(net "RST_HFI0_CPU0_LVT2_N")
	)
	(segment
		(start 335.788 -108.077)
		(end 336.1563 -108.4453)
		(width 0.089408)
		(layer "In9.Cu")
		(net "RST_HFI0_CPU0_LVT2_N")
	)
	(segment
		(start 333.732886 -92.1258)
		(end 333.944976 -92.33789)
		(width 0.089408)
		(layer "In9.Cu")
		(net "RST_HFI0_CPU0_LVT2_N")
	)
	(segment
		(start 332.457298 -72.522334)
		(end 334.399382 -74.464418)
		(width 0.089408)
		(layer "In9.Cu")
		(net "RST_HFI0_CPU0_LVT2_N")
	)
	(segment
		(start 332.457298 -72.39381)
		(end 332.457298 -72.522334)
		(width 0.089408)
		(layer "In9.Cu")
		(net "RST_HFI0_CPU0_LVT2_N")
	)
	(segment
		(start 334.816704 -77.033628)
		(end 334.816704 -78.01102)
		(width 0.089408)
		(layer "In9.Cu")
		(net "RST_HFI0_CPU0_LVT2_N")
	)
	(segment
		(start 334.816704 -78.01102)
		(end 332.812644 -80.01508)
		(width 0.089408)
		(layer "In9.Cu")
		(net "RST_HFI0_CPU0_LVT2_N")
	)
	(segment
		(start 333.732886 -89.25814)
		(end 333.732886 -92.1258)
		(width 0.089408)
		(layer "In9.Cu")
		(net "RST_HFI0_CPU0_LVT2_N")
	)
	(segment
		(start 333.757016 -107.416092)
		(end 334.417924 -108.077)
		(width 0.089408)
		(layer "In9.Cu")
		(net "RST_HFI0_CPU0_LVT2_N")
	)
	(segment
		(start 333.944976 -92.33789)
		(end 333.944976 -105.65765)
		(width 0.089408)
		(layer "In9.Cu")
		(net "RST_HFI0_CPU0_LVT2_N")
	)
	(segment
		(start 332.812644 -88.337898)
		(end 333.732886 -89.25814)
		(width 0.089408)
		(layer "In9.Cu")
		(net "RST_HFI0_CPU0_LVT2_N")
	)
	(segment
		(start 336.1563 -117.246908)
		(end 336.24901 -117.339618)
		(width 0.089408)
		(layer "In9.Cu")
		(net "RST_HFI0_CPU0_LVT2_N")
	)
	(segment
		(start 332.812644 -80.01508)
		(end 332.812644 -88.337898)
		(width 0.089408)
		(layer "In9.Cu")
		(net "RST_HFI0_CPU0_LVT2_N")
	)
	(segment
		(start 333.944976 -105.65765)
		(end 333.757016 -105.84561)
		(width 0.089408)
		(layer "In9.Cu")
		(net "RST_HFI0_CPU0_LVT2_N")
	)
	(segment
		(start 336.24901 -117.339618)
		(end 336.24901 -117.739922)
		(width 0.089408)
		(layer "In9.Cu")
		(net "RST_HFI0_CPU0_LVT2_N")
	)
	(segment
		(start 336.1563 -108.4453)
		(end 336.1563 -117.246908)
		(width 0.089408)
		(layer "In9.Cu")
		(net "RST_HFI0_CPU0_LVT2_N")
	)
	(segment
		(start 334.399382 -76.616306)
		(end 334.816704 -77.033628)
		(width 0.089408)
		(layer "In9.Cu")
		(net "RST_HFI0_CPU0_LVT2_N")
	)
	(segment
		(start 333.757016 -105.84561)
		(end 333.757016 -107.416092)
		(width 0.089408)
		(layer "In9.Cu")
		(net "RST_HFI0_CPU0_LVT2_N")
	)
	(segment
		(start 334.417924 -108.077)
		(end 335.788 -108.077)
		(width 0.089408)
		(layer "In9.Cu")
		(net "RST_HFI0_CPU0_LVT2_N")
	)
	(segment
		(start 334.399382 -74.464418)
		(end 334.399382 -76.616306)
		(width 0.089408)
		(layer "In9.Cu")
		(net "RST_HFI0_CPU0_LVT2_N")
	)
	(segment
		(start 338.201508 -117.34038)
		(end 339.608414 -118.747286)
		(width 0.089408)
		(layer "In11.Cu")
		(net "RST_HFI0_CPU0_LVT2_N")
	)
	(segment
		(start 399.719292 -134.213854)
		(end 401.202398 -134.213854)
		(width 0.089408)
		(layer "In11.Cu")
		(net "RST_HFI0_CPU0_LVT2_N")
	)
	(segment
		(start 374.672606 -127.516636)
		(end 379.072902 -127.516636)
		(width 0.089408)
		(layer "In11.Cu")
		(net "RST_HFI0_CPU0_LVT2_N")
	)
	(segment
		(start 293.812214 -71.462646)
		(end 293.690548 -71.5772)
		(width 0.089408)
		(layer "In11.Cu")
		(net "RST_HFI0_CPU0_LVT2_N")
	)
	(segment
		(start 384.827272 -128.918716)
		(end 384.827272 -129.485644)
		(width 0.089408)
		(layer "In11.Cu")
		(net "RST_HFI0_CPU0_LVT2_N")
	)
	(segment
		(start 336.24901 -117.739922)
		(end 336.648552 -117.34038)
		(width 0.089408)
		(layer "In11.Cu")
		(net "RST_HFI0_CPU0_LVT2_N")
	)
	(segment
		(start 332.372208 -72.4789)
		(end 308.694836 -72.4789)
		(width 0.089408)
		(layer "In11.Cu")
		(net "RST_HFI0_CPU0_LVT2_N")
	)
	(segment
		(start 292.389306 -72.249284)
		(end 292.357048 -72.249284)
		(width 0.089408)
		(layer "In11.Cu")
		(net "RST_HFI0_CPU0_LVT2_N")
	)
	(segment
		(start 370.94414 -121.648728)
		(end 371.998494 -122.703082)
		(width 0.089408)
		(layer "In11.Cu")
		(net "RST_HFI0_CPU0_LVT2_N")
	)
	(segment
		(start 379.072902 -127.516636)
		(end 379.24359 -127.345948)
		(width 0.089408)
		(layer "In11.Cu")
		(net "RST_HFI0_CPU0_LVT2_N")
	)
	(segment
		(start 300.112176 -72.744838)
		(end 300.095158 -72.744838)
		(width 0.089408)
		(layer "In11.Cu")
		(net "RST_HFI0_CPU0_LVT2_N")
	)
	(segment
		(start 293.24427 -71.754238)
		(end 293.21125 -71.754238)
		(width 0.089408)
		(layer "In11.Cu")
		(net "RST_HFI0_CPU0_LVT2_N")
	)
	(segment
		(start 297.532298 -72.249284)
		(end 297.519598 -72.249284)
		(width 0.089408)
		(layer "In11.Cu")
		(net "RST_HFI0_CPU0_LVT2_N")
	)
	(segment
		(start 289.81019 -73.735438)
		(end 289.77717 -73.735438)
		(width 0.089408)
		(layer "In11.Cu")
		(net "RST_HFI0_CPU0_LVT2_N")
	)
	(segment
		(start 410.464254 -132.480558)
		(end 412.857696 -132.480558)
		(width 0.089408)
		(layer "In11.Cu")
		(net "RST_HFI0_CPU0_LVT2_N")
	)
	(segment
		(start 413.011874 -132.634736)
		(end 414.26003 -132.634736)
		(width 0.089408)
		(layer "In11.Cu")
		(net "RST_HFI0_CPU0_LVT2_N")
	)
	(segment
		(start 370.17071 -121.648728)
		(end 370.94414 -121.648728)
		(width 0.089408)
		(layer "In11.Cu")
		(net "RST_HFI0_CPU0_LVT2_N")
	)
	(segment
		(start 339.608414 -118.747286)
		(end 345.466924 -118.747286)
		(width 0.089408)
		(layer "In11.Cu")
		(net "RST_HFI0_CPU0_LVT2_N")
	)
	(segment
		(start 371.998494 -125.905768)
		(end 373.247412 -127.154686)
		(width 0.089408)
		(layer "In11.Cu")
		(net "RST_HFI0_CPU0_LVT2_N")
	)
	(segment
		(start 408.698192 -130.714496)
		(end 410.464254 -132.480558)
		(width 0.089408)
		(layer "In11.Cu")
		(net "RST_HFI0_CPU0_LVT2_N")
	)
	(segment
		(start 296.67835 -71.754238)
		(end 296.495724 -71.754238)
		(width 0.089408)
		(layer "In11.Cu")
		(net "RST_HFI0_CPU0_LVT2_N")
	)
	(segment
		(start 294.617902 -71.665084)
		(end 294.470074 -71.517256)
		(width 0.089408)
		(layer "In11.Cu")
		(net "RST_HFI0_CPU0_LVT2_N")
	)
	(segment
		(start 291.52723 -72.744838)
		(end 291.49421 -72.744838)
		(width 0.089408)
		(layer "In11.Cu")
		(net "RST_HFI0_CPU0_LVT2_N")
	)
	(segment
		(start 305.263296 -71.754238)
		(end 305.230276 -71.754238)
		(width 0.089408)
		(layer "In11.Cu")
		(net "RST_HFI0_CPU0_LVT2_N")
	)
	(segment
		(start 415.449766 -131.445)
		(end 416.587686 -131.445)
		(width 0.089408)
		(layer "In11.Cu")
		(net "RST_HFI0_CPU0_LVT2_N")
	)
	(segment
		(start 414.26003 -132.634736)
		(end 415.449766 -131.445)
		(width 0.089408)
		(layer "In11.Cu")
		(net "RST_HFI0_CPU0_LVT2_N")
	)
	(segment
		(start 288.5059 -74.478388)
		(end 288.497772 -74.492358)
		(width 0.089408)
		(layer "In11.Cu")
		(net "RST_HFI0_CPU0_LVT2_N")
	)
	(segment
		(start 384.827272 -129.485644)
		(end 390.297924 -134.956296)
		(width 0.089408)
		(layer "In11.Cu")
		(net "RST_HFI0_CPU0_LVT2_N")
	)
	(segment
		(start 345.607386 -118.887748)
		(end 367.40973 -118.887748)
		(width 0.089408)
		(layer "In11.Cu")
		(net "RST_HFI0_CPU0_LVT2_N")
	)
	(segment
		(start 307.970174 -71.754238)
		(end 306.854352 -71.754238)
		(width 0.089408)
		(layer "In11.Cu")
		(net "RST_HFI0_CPU0_LVT2_N")
	)
	(segment
		(start 371.998494 -122.703082)
		(end 371.998494 -125.905768)
		(width 0.089408)
		(layer "In11.Cu")
		(net "RST_HFI0_CPU0_LVT2_N")
	)
	(segment
		(start 302.691292 -72.249284)
		(end 302.659034 -72.249284)
		(width 0.089408)
		(layer "In11.Cu")
		(net "RST_HFI0_CPU0_LVT2_N")
	)
	(segment
		(start 404.704042 -130.714496)
		(end 408.698192 -130.714496)
		(width 0.089408)
		(layer "In11.Cu")
		(net "RST_HFI0_CPU0_LVT2_N")
	)
	(segment
		(start 298.395136 -72.744838)
		(end 298.362116 -72.744838)
		(width 0.089408)
		(layer "In11.Cu")
		(net "RST_HFI0_CPU0_LVT2_N")
	)
	(segment
		(start 290.672266 -73.239884)
		(end 290.640008 -73.239884)
		(width 0.089408)
		(layer "In11.Cu")
		(net "RST_HFI0_CPU0_LVT2_N")
	)
	(segment
		(start 384.339592 -127.683006)
		(end 384.339592 -128.431036)
		(width 0.089408)
		(layer "In11.Cu")
		(net "RST_HFI0_CPU0_LVT2_N")
	)
	(segment
		(start 379.24359 -127.345948)
		(end 384.002534 -127.345948)
		(width 0.089408)
		(layer "In11.Cu")
		(net "RST_HFI0_CPU0_LVT2_N")
	)
	(segment
		(start 288.5059 -76.459588)
		(end 288.5059 -76.459334)
		(width 0.089408)
		(layer "In11.Cu")
		(net "RST_HFI0_CPU0_LVT2_N")
	)
	(segment
		(start 345.466924 -118.747286)
		(end 345.607386 -118.887748)
		(width 0.089408)
		(layer "In11.Cu")
		(net "RST_HFI0_CPU0_LVT2_N")
	)
	(segment
		(start 374.310656 -127.154686)
		(end 374.672606 -127.516636)
		(width 0.089408)
		(layer "In11.Cu")
		(net "RST_HFI0_CPU0_LVT2_N")
	)
	(segment
		(start 384.002534 -127.345948)
		(end 384.339592 -127.683006)
		(width 0.089408)
		(layer "In11.Cu")
		(net "RST_HFI0_CPU0_LVT2_N")
	)
	(segment
		(start 306.290726 -71.258684)
		(end 306.093114 -71.258684)
		(width 0.089408)
		(layer "In11.Cu")
		(net "RST_HFI0_CPU0_LVT2_N")
	)
	(segment
		(start 416.587686 -131.445)
		(end 417.23818 -130.794506)
		(width 0.089408)
		(layer "In11.Cu")
		(net "RST_HFI0_CPU0_LVT2_N")
	)
	(segment
		(start 373.247412 -127.154686)
		(end 374.310656 -127.154686)
		(width 0.089408)
		(layer "In11.Cu")
		(net "RST_HFI0_CPU0_LVT2_N")
	)
	(segment
		(start 384.339592 -128.431036)
		(end 384.827272 -128.918716)
		(width 0.089408)
		(layer "In11.Cu")
		(net "RST_HFI0_CPU0_LVT2_N")
	)
	(segment
		(start 332.457298 -72.39381)
		(end 332.372208 -72.4789)
		(width 0.089408)
		(layer "In11.Cu")
		(net "RST_HFI0_CPU0_LVT2_N")
	)
	(segment
		(start 301.829216 -72.744838)
		(end 301.796196 -72.744838)
		(width 0.089408)
		(layer "In11.Cu")
		(net "RST_HFI0_CPU0_LVT2_N")
	)
	(segment
		(start 288.5059 -75.468988)
		(end 288.497772 -75.482958)
		(width 0.089408)
		(layer "In11.Cu")
		(net "RST_HFI0_CPU0_LVT2_N")
	)
	(segment
		(start 303.546256 -71.754238)
		(end 303.513236 -71.754238)
		(width 0.089408)
		(layer "In11.Cu")
		(net "RST_HFI0_CPU0_LVT2_N")
	)
	(segment
		(start 398.97685 -134.956296)
		(end 399.719292 -134.213854)
		(width 0.089408)
		(layer "In11.Cu")
		(net "RST_HFI0_CPU0_LVT2_N")
	)
	(segment
		(start 288.5059 -76.459334)
		(end 288.07664 -77.202538)
		(width 0.089408)
		(layer "In11.Cu")
		(net "RST_HFI0_CPU0_LVT2_N")
	)
	(segment
		(start 401.202398 -134.213854)
		(end 404.704042 -130.714496)
		(width 0.089408)
		(layer "In11.Cu")
		(net "RST_HFI0_CPU0_LVT2_N")
	)
	(segment
		(start 308.694836 -72.4789)
		(end 307.970174 -71.754238)
		(width 0.089408)
		(layer "In11.Cu")
		(net "RST_HFI0_CPU0_LVT2_N")
	)
	(segment
		(start 336.648552 -117.34038)
		(end 338.201508 -117.34038)
		(width 0.089408)
		(layer "In11.Cu")
		(net "RST_HFI0_CPU0_LVT2_N")
	)
	(segment
		(start 288.955226 -74.230484)
		(end 288.934906 -74.230484)
		(width 0.089408)
		(layer "In11.Cu")
		(net "RST_HFI0_CPU0_LVT2_N")
	)
	(segment
		(start 367.40973 -118.887748)
		(end 370.17071 -121.648728)
		(width 0.089408)
		(layer "In11.Cu")
		(net "RST_HFI0_CPU0_LVT2_N")
	)
	(segment
		(start 390.297924 -134.956296)
		(end 398.97685 -134.956296)
		(width 0.089408)
		(layer "In11.Cu")
		(net "RST_HFI0_CPU0_LVT2_N")
	)
	(segment
		(start 412.857696 -132.480558)
		(end 413.011874 -132.634736)
		(width 0.089408)
		(layer "In11.Cu")
		(net "RST_HFI0_CPU0_LVT2_N")
	)
	(arc
		(start 293.21125 -71.754238)
		(mid 292.972789 -71.824586)
		(end 292.7985 -72.001888)
		(width 0.089408)
		(layer "In11.Cu")
		(net "RST_HFI0_CPU0_LVT2_N")
	)
	(arc
		(start 301.383446 -72.497188)
		(mid 300.954186 -72.249136)
		(end 300.524926 -72.497188)
		(width 0.089408)
		(layer "In11.Cu")
		(net "RST_HFI0_CPU0_LVT2_N")
	)
	(arc
		(start 296.149776 -71.55434)
		(mid 295.80332 -71.354122)
		(end 295.456864 -71.55434)
		(width 0.089408)
		(layer "In11.Cu")
		(net "RST_HFI0_CPU0_LVT2_N")
	)
	(arc
		(start 305.676046 -71.506588)
		(mid 305.501757 -71.68389)
		(end 305.263296 -71.754238)
		(width 0.089408)
		(layer "In11.Cu")
		(net "RST_HFI0_CPU0_LVT2_N")
	)
	(arc
		(start 289.36442 -73.983088)
		(mid 289.191625 -74.159385)
		(end 288.955226 -74.230484)
		(width 0.089408)
		(layer "In11.Cu")
		(net "RST_HFI0_CPU0_LVT2_N")
	)
	(arc
		(start 288.497772 -74.492358)
		(mid 288.439451 -74.734086)
		(end 288.5059 -74.973688)
		(width 0.089408)
		(layer "In11.Cu")
		(net "RST_HFI0_CPU0_LVT2_N")
	)
	(arc
		(start 291.08146 -72.992488)
		(mid 290.908665 -73.168785)
		(end 290.672266 -73.239884)
		(width 0.089408)
		(layer "In11.Cu")
		(net "RST_HFI0_CPU0_LVT2_N")
	)
	(arc
		(start 304.817526 -71.506588)
		(mid 304.388266 -71.258536)
		(end 303.959006 -71.506588)
		(width 0.089408)
		(layer "In11.Cu")
		(net "RST_HFI0_CPU0_LVT2_N")
	)
	(arc
		(start 292.357048 -72.249284)
		(mid 292.116091 -72.318689)
		(end 291.93998 -72.497188)
		(width 0.089408)
		(layer "In11.Cu")
		(net "RST_HFI0_CPU0_LVT2_N")
	)
	(arc
		(start 288.5059 -74.973688)
		(mid 288.572215 -75.221338)
		(end 288.5059 -75.468988)
		(width 0.089408)
		(layer "In11.Cu")
		(net "RST_HFI0_CPU0_LVT2_N")
	)
	(arc
		(start 290.640008 -73.239884)
		(mid 290.399051 -73.309289)
		(end 290.22294 -73.487788)
		(width 0.089408)
		(layer "In11.Cu")
		(net "RST_HFI0_CPU0_LVT2_N")
	)
	(arc
		(start 291.49421 -72.744838)
		(mid 291.255749 -72.815186)
		(end 291.08146 -72.992488)
		(width 0.089408)
		(layer "In11.Cu")
		(net "RST_HFI0_CPU0_LVT2_N")
	)
	(arc
		(start 296.495724 -71.754238)
		(mid 296.295951 -71.700669)
		(end 296.149776 -71.55434)
		(width 0.089408)
		(layer "In11.Cu")
		(net "RST_HFI0_CPU0_LVT2_N")
	)
	(arc
		(start 294.017954 -71.359776)
		(mid 293.907542 -71.396122)
		(end 293.812214 -71.462646)
		(width 0.089408)
		(layer "In11.Cu")
		(net "RST_HFI0_CPU0_LVT2_N")
	)
	(arc
		(start 297.949366 -72.497188)
		(mid 297.773254 -72.318691)
		(end 297.532298 -72.249284)
		(width 0.089408)
		(layer "In11.Cu")
		(net "RST_HFI0_CPU0_LVT2_N")
	)
	(arc
		(start 302.659034 -72.249284)
		(mid 302.418077 -72.318689)
		(end 302.241966 -72.497188)
		(width 0.089408)
		(layer "In11.Cu")
		(net "RST_HFI0_CPU0_LVT2_N")
	)
	(arc
		(start 306.854352 -71.754238)
		(mid 306.690806 -71.656231)
		(end 306.572666 -71.506588)
		(width 0.089408)
		(layer "In11.Cu")
		(net "RST_HFI0_CPU0_LVT2_N")
	)
	(arc
		(start 303.959006 -71.506588)
		(mid 303.784717 -71.68389)
		(end 303.546256 -71.754238)
		(width 0.089408)
		(layer "In11.Cu")
		(net "RST_HFI0_CPU0_LVT2_N")
	)
	(arc
		(start 305.230276 -71.754238)
		(mid 304.991815 -71.68389)
		(end 304.817526 -71.506588)
		(width 0.089408)
		(layer "In11.Cu")
		(net "RST_HFI0_CPU0_LVT2_N")
	)
	(arc
		(start 297.519598 -72.249284)
		(mid 297.272203 -72.182995)
		(end 297.0911 -72.001888)
		(width 0.089408)
		(layer "In11.Cu")
		(net "RST_HFI0_CPU0_LVT2_N")
	)
	(arc
		(start 303.513236 -71.754238)
		(mid 303.274775 -71.824586)
		(end 303.100486 -72.001888)
		(width 0.089408)
		(layer "In11.Cu")
		(net "RST_HFI0_CPU0_LVT2_N")
	)
	(arc
		(start 289.77717 -73.735438)
		(mid 289.538709 -73.805786)
		(end 289.36442 -73.983088)
		(width 0.089408)
		(layer "In11.Cu")
		(net "RST_HFI0_CPU0_LVT2_N")
	)
	(arc
		(start 293.690548 -71.5772)
		(mid 293.484326 -71.708363)
		(end 293.24427 -71.754238)
		(width 0.089408)
		(layer "In11.Cu")
		(net "RST_HFI0_CPU0_LVT2_N")
	)
	(arc
		(start 302.241966 -72.497188)
		(mid 302.067677 -72.67449)
		(end 301.829216 -72.744838)
		(width 0.089408)
		(layer "In11.Cu")
		(net "RST_HFI0_CPU0_LVT2_N")
	)
	(arc
		(start 288.934906 -74.230484)
		(mid 288.687179 -74.296926)
		(end 288.5059 -74.478388)
		(width 0.089408)
		(layer "In11.Cu")
		(net "RST_HFI0_CPU0_LVT2_N")
	)
	(arc
		(start 306.572666 -71.506588)
		(mid 306.454417 -71.356805)
		(end 306.290726 -71.258684)
		(width 0.089408)
		(layer "In11.Cu")
		(net "RST_HFI0_CPU0_LVT2_N")
	)
	(arc
		(start 298.362116 -72.744838)
		(mid 298.123655 -72.67449)
		(end 297.949366 -72.497188)
		(width 0.089408)
		(layer "In11.Cu")
		(net "RST_HFI0_CPU0_LVT2_N")
	)
	(arc
		(start 288.497772 -75.482958)
		(mid 288.439451 -75.724686)
		(end 288.5059 -75.964288)
		(width 0.089408)
		(layer "In11.Cu")
		(net "RST_HFI0_CPU0_LVT2_N")
	)
	(arc
		(start 295.456864 -71.55434)
		(mid 295.064677 -71.816777)
		(end 294.617902 -71.665084)
		(width 0.089408)
		(layer "In11.Cu")
		(net "RST_HFI0_CPU0_LVT2_N")
	)
	(arc
		(start 292.7985 -72.001888)
		(mid 292.625705 -72.178185)
		(end 292.389306 -72.249284)
		(width 0.089408)
		(layer "In11.Cu")
		(net "RST_HFI0_CPU0_LVT2_N")
	)
	(arc
		(start 288.5059 -75.964288)
		(mid 288.572215 -76.211938)
		(end 288.5059 -76.459588)
		(width 0.089408)
		(layer "In11.Cu")
		(net "RST_HFI0_CPU0_LVT2_N")
	)
	(arc
		(start 303.100486 -72.001888)
		(mid 302.927691 -72.178185)
		(end 302.691292 -72.249284)
		(width 0.089408)
		(layer "In11.Cu")
		(net "RST_HFI0_CPU0_LVT2_N")
	)
	(arc
		(start 306.093114 -71.258684)
		(mid 305.852157 -71.328089)
		(end 305.676046 -71.506588)
		(width 0.089408)
		(layer "In11.Cu")
		(net "RST_HFI0_CPU0_LVT2_N")
	)
	(arc
		(start 290.22294 -73.487788)
		(mid 290.048651 -73.66509)
		(end 289.81019 -73.735438)
		(width 0.089408)
		(layer "In11.Cu")
		(net "RST_HFI0_CPU0_LVT2_N")
	)
	(arc
		(start 300.524926 -72.497188)
		(mid 300.350637 -72.67449)
		(end 300.112176 -72.744838)
		(width 0.089408)
		(layer "In11.Cu")
		(net "RST_HFI0_CPU0_LVT2_N")
	)
	(arc
		(start 300.095158 -72.744838)
		(mid 299.847581 -72.678483)
		(end 299.666406 -72.497188)
		(width 0.089408)
		(layer "In11.Cu")
		(net "RST_HFI0_CPU0_LVT2_N")
	)
	(arc
		(start 291.93998 -72.497188)
		(mid 291.765691 -72.67449)
		(end 291.52723 -72.744838)
		(width 0.089408)
		(layer "In11.Cu")
		(net "RST_HFI0_CPU0_LVT2_N")
	)
	(arc
		(start 297.0911 -72.001888)
		(mid 296.916811 -71.824586)
		(end 296.67835 -71.754238)
		(width 0.089408)
		(layer "In11.Cu")
		(net "RST_HFI0_CPU0_LVT2_N")
	)
	(arc
		(start 301.796196 -72.744838)
		(mid 301.557735 -72.67449)
		(end 301.383446 -72.497188)
		(width 0.089408)
		(layer "In11.Cu")
		(net "RST_HFI0_CPU0_LVT2_N")
	)
	(arc
		(start 298.807886 -72.497188)
		(mid 298.633597 -72.67449)
		(end 298.395136 -72.744838)
		(width 0.089408)
		(layer "In11.Cu")
		(net "RST_HFI0_CPU0_LVT2_N")
	)
	(arc
		(start 294.470074 -71.517256)
		(mid 294.263135 -71.383659)
		(end 294.017954 -71.359776)
		(width 0.089408)
		(layer "In11.Cu")
		(net "RST_HFI0_CPU0_LVT2_N")
	)
	(arc
		(start 299.666406 -72.497188)
		(mid 299.237146 -72.249136)
		(end 298.807886 -72.497188)
		(width 0.089408)
		(layer "In11.Cu")
		(net "RST_HFI0_CPU0_LVT2_N")
	)
	(segment
		(start 348.644972 -114.28095)
		(end 349.2754 -113.665)
		(width 0.10795)
		(layer "F.Cu")
		(net "PWRGD_PVCCIOMCP_CPU0")
	)
	(segment
		(start 362.9152 -107.293664)
		(end 358.822244 -111.38662)
		(width 0.10795)
		(layer "F.Cu")
		(net "PWRGD_PVCCIOMCP_CPU0")
	)
	(segment
		(start 375.144792 -78.294738)
		(end 374.744996 -77.894942)
		(width 0.10795)
		(layer "F.Cu")
		(net "PWRGD_PVCCIOMCP_CPU0")
	)
	(segment
		(start 368.905536 -89.7509)
		(end 368.617246 -89.46261)
		(width 0.10795)
		(layer "F.Cu")
		(net "PWRGD_PVCCIOMCP_CPU0")
	)
	(segment
		(start 365.182912 -89.985088)
		(end 362.9152 -92.2528)
		(width 0.10795)
		(layer "F.Cu")
		(net "PWRGD_PVCCIOMCP_CPU0")
	)
	(segment
		(start 368.617246 -89.46261)
		(end 368.273838 -89.46261)
		(width 0.10795)
		(layer "F.Cu")
		(net "PWRGD_PVCCIOMCP_CPU0")
	)
	(segment
		(start 369.2906 -89.7509)
		(end 368.905536 -89.7509)
		(width 0.10795)
		(layer "F.Cu")
		(net "PWRGD_PVCCIOMCP_CPU0")
	)
	(segment
		(start 362.9152 -92.2528)
		(end 362.9152 -107.293664)
		(width 0.10795)
		(layer "F.Cu")
		(net "PWRGD_PVCCIOMCP_CPU0")
	)
	(segment
		(start 367.75136 -89.985088)
		(end 365.182912 -89.985088)
		(width 0.10795)
		(layer "F.Cu")
		(net "PWRGD_PVCCIOMCP_CPU0")
	)
	(segment
		(start 368.273838 -89.46261)
		(end 367.75136 -89.985088)
		(width 0.10795)
		(layer "F.Cu")
		(net "PWRGD_PVCCIOMCP_CPU0")
	)
	(segment
		(start 358.822244 -111.38662)
		(end 358.31653 -111.38662)
		(width 0.10795)
		(layer "F.Cu")
		(net "PWRGD_PVCCIOMCP_CPU0")
	)
	(segment
		(start 358.31653 -111.38662)
		(end 357.68915 -112.014)
		(width 0.10795)
		(layer "F.Cu")
		(net "PWRGD_PVCCIOMCP_CPU0")
	)
	(via
		(at 349.2754 -113.665)
		(size 0.508)
		(drill 0.254)
		(layers "F.Cu" "B.Cu")
		(net "PWRGD_PVCCIOMCP_CPU0")
	)
	(via
		(at 357.68915 -112.014)
		(size 0.508)
		(drill 0.254)
		(layers "F.Cu" "B.Cu")
		(net "PWRGD_PVCCIOMCP_CPU0")
	)
	(via
		(at 369.2906 -89.7509)
		(size 0.508)
		(drill 0.254)
		(layers "F.Cu" "B.Cu")
		(net "PWRGD_PVCCIOMCP_CPU0")
	)
	(via
		(at 375.144792 -78.294738)
		(size 0.4572)
		(drill 0.2032)
		(layers "F.Cu" "B.Cu")
		(net "PWRGD_PVCCIOMCP_CPU0")
	)
	(segment
		(start 348.742 -113.1316)
		(end 348.742 -112.103408)
		(width 0.089408)
		(layer "In9.Cu")
		(net "PWRGD_PVCCIOMCP_CPU0")
	)
	(segment
		(start 370.395754 -88.2904)
		(end 371.0432 -88.2904)
		(width 0.089408)
		(layer "In9.Cu")
		(net "PWRGD_PVCCIOMCP_CPU0")
	)
	(segment
		(start 369.2906 -89.7509)
		(end 369.2906 -89.395554)
		(width 0.089408)
		(layer "In9.Cu")
		(net "PWRGD_PVCCIOMCP_CPU0")
	)
	(segment
		(start 375.518172 -79.249524)
		(end 375.518172 -78.668118)
		(width 0.089408)
		(layer "In9.Cu")
		(net "PWRGD_PVCCIOMCP_CPU0")
	)
	(segment
		(start 369.2906 -89.395554)
		(end 370.395754 -88.2904)
		(width 0.089408)
		(layer "In9.Cu")
		(net "PWRGD_PVCCIOMCP_CPU0")
	)
	(segment
		(start 374.9929 -79.774796)
		(end 375.518172 -79.249524)
		(width 0.089408)
		(layer "In9.Cu")
		(net "PWRGD_PVCCIOMCP_CPU0")
	)
	(segment
		(start 373.774462 -87.4395)
		(end 374.571768 -86.642194)
		(width 0.089408)
		(layer "In9.Cu")
		(net "PWRGD_PVCCIOMCP_CPU0")
	)
	(segment
		(start 374.571768 -86.642194)
		(end 374.571768 -81.806796)
		(width 0.089408)
		(layer "In9.Cu")
		(net "PWRGD_PVCCIOMCP_CPU0")
	)
	(segment
		(start 356.864158 -111.189008)
		(end 357.68915 -112.014)
		(width 0.089408)
		(layer "In9.Cu")
		(net "PWRGD_PVCCIOMCP_CPU0")
	)
	(segment
		(start 371.0432 -88.2904)
		(end 371.8941 -87.4395)
		(width 0.089408)
		(layer "In9.Cu")
		(net "PWRGD_PVCCIOMCP_CPU0")
	)
	(segment
		(start 348.742 -112.103408)
		(end 348.958408 -111.887)
		(width 0.089408)
		(layer "In9.Cu")
		(net "PWRGD_PVCCIOMCP_CPU0")
	)
	(segment
		(start 352.806 -111.887)
		(end 353.503992 -111.189008)
		(width 0.089408)
		(layer "In9.Cu")
		(net "PWRGD_PVCCIOMCP_CPU0")
	)
	(segment
		(start 349.2754 -113.665)
		(end 348.742 -113.1316)
		(width 0.089408)
		(layer "In9.Cu")
		(net "PWRGD_PVCCIOMCP_CPU0")
	)
	(segment
		(start 374.9929 -81.385664)
		(end 374.9929 -79.774796)
		(width 0.089408)
		(layer "In9.Cu")
		(net "PWRGD_PVCCIOMCP_CPU0")
	)
	(segment
		(start 371.8941 -87.4395)
		(end 373.774462 -87.4395)
		(width 0.089408)
		(layer "In9.Cu")
		(net "PWRGD_PVCCIOMCP_CPU0")
	)
	(segment
		(start 375.518172 -78.668118)
		(end 375.144792 -78.294738)
		(width 0.089408)
		(layer "In9.Cu")
		(net "PWRGD_PVCCIOMCP_CPU0")
	)
	(segment
		(start 348.958408 -111.887)
		(end 352.806 -111.887)
		(width 0.089408)
		(layer "In9.Cu")
		(net "PWRGD_PVCCIOMCP_CPU0")
	)
	(segment
		(start 374.571768 -81.806796)
		(end 374.9929 -81.385664)
		(width 0.089408)
		(layer "In9.Cu")
		(net "PWRGD_PVCCIOMCP_CPU0")
	)
	(segment
		(start 353.503992 -111.189008)
		(end 356.864158 -111.189008)
		(width 0.089408)
		(layer "In9.Cu")
		(net "PWRGD_PVCCIOMCP_CPU0")
	)
	(segment
		(start 368.18316 -66.93916)
		(end 368.4016 -67.1576)
		(width 0.10795)
		(layer "F.Cu")
		(net "PU_THERMTRIP_FORCE_N")
	)
	(segment
		(start 368.005106 -64.81064)
		(end 368.343434 -64.81064)
		(width 0.10795)
		(layer "F.Cu")
		(net "PU_THERMTRIP_FORCE_N")
	)
	(segment
		(start 368.4016 -67.1576)
		(end 369.697 -67.1576)
		(width 0.10795)
		(layer "F.Cu")
		(net "PU_THERMTRIP_FORCE_N")
	)
	(segment
		(start 368.539268 -65.006474)
		(end 368.539268 -65.935606)
		(width 0.10795)
		(layer "F.Cu")
		(net "PU_THERMTRIP_FORCE_N")
	)
	(segment
		(start 368.539268 -65.935606)
		(end 368.18316 -66.291714)
		(width 0.10795)
		(layer "F.Cu")
		(net "PU_THERMTRIP_FORCE_N")
	)
	(segment
		(start 368.18316 -66.291714)
		(end 368.18316 -66.93916)
		(width 0.10795)
		(layer "F.Cu")
		(net "PU_THERMTRIP_FORCE_N")
	)
	(segment
		(start 368.343434 -64.81064)
		(end 368.539268 -65.006474)
		(width 0.10795)
		(layer "F.Cu")
		(net "PU_THERMTRIP_FORCE_N")
	)
	(segment
		(start 369.944904 -67.405504)
		(end 369.944904 -68.295012)
		(width 0.10795)
		(layer "F.Cu")
		(net "PU_THERMTRIP_FORCE_N")
	)
	(segment
		(start 369.697 -67.1576)
		(end 369.944904 -67.405504)
		(width 0.10795)
		(layer "F.Cu")
		(net "PU_THERMTRIP_FORCE_N")
	)
	(segment
		(start 371.145308 -71.095108)
		(end 371.545104 -71.494904)
		(width 0.10795)
		(layer "F.Cu")
		(net "TP_CPLD1_PT20B")
	)
	(via
		(at 371.145308 -71.095108)
		(size 0.4572)
		(drill 0.2032)
		(layers "F.Cu" "B.Cu")
		(net "TP_CPLD1_PT20B")
	)
	(segment
		(start 414.22955 -126.740412)
		(end 415.191194 -126.740412)
		(width 0.10795)
		(layer "F.Cu")
		(net "LED_HFI1_CPU0_N")
	)
	(segment
		(start 413.963612 -128.852676)
		(end 413.963612 -127.00635)
		(width 0.10795)
		(layer "F.Cu")
		(net "LED_HFI1_CPU0_N")
	)
	(segment
		(start 419.470078 -120.929146)
		(end 419.470078 -120.469406)
		(width 0.10795)
		(layer "F.Cu")
		(net "LED_HFI1_CPU0_N")
	)
	(segment
		(start 288.36366 -76.706984)
		(end 288.93516 -76.706984)
		(width 0.10795)
		(layer "F.Cu")
		(net "LED_HFI1_CPU0_N")
	)
	(segment
		(start 418.709602 -122.211846)
		(end 418.709602 -121.689622)
		(width 0.10795)
		(layer "F.Cu")
		(net "LED_HFI1_CPU0_N")
	)
	(segment
		(start 418.286692 -122.634756)
		(end 418.709602 -122.211846)
		(width 0.10795)
		(layer "F.Cu")
		(net "LED_HFI1_CPU0_N")
	)
	(segment
		(start 418.286692 -125.695964)
		(end 418.286692 -122.634756)
		(width 0.10795)
		(layer "F.Cu")
		(net "LED_HFI1_CPU0_N")
	)
	(segment
		(start 418.709602 -121.689622)
		(end 419.470078 -120.929146)
		(width 0.10795)
		(layer "F.Cu")
		(net "LED_HFI1_CPU0_N")
	)
	(segment
		(start 415.191194 -126.740412)
		(end 417.242244 -126.740412)
		(width 0.10795)
		(layer "F.Cu")
		(net "LED_HFI1_CPU0_N")
	)
	(segment
		(start 421.005 -118.934484)
		(end 421.005 -118.3767)
		(width 0.10795)
		(layer "F.Cu")
		(net "LED_HFI1_CPU0_N")
	)
	(segment
		(start 419.470078 -120.469406)
		(end 421.005 -118.934484)
		(width 0.10795)
		(layer "F.Cu")
		(net "LED_HFI1_CPU0_N")
	)
	(segment
		(start 417.242244 -126.740412)
		(end 418.286692 -125.695964)
		(width 0.10795)
		(layer "F.Cu")
		(net "LED_HFI1_CPU0_N")
	)
	(segment
		(start 413.963612 -127.00635)
		(end 414.22955 -126.740412)
		(width 0.10795)
		(layer "F.Cu")
		(net "LED_HFI1_CPU0_N")
	)
	(via
		(at 413.963612 -128.852676)
		(size 0.508)
		(drill 0.254)
		(layers "F.Cu" "B.Cu")
		(net "LED_HFI1_CPU0_N")
	)
	(via
		(at 288.93516 -76.706984)
		(size 0.508)
		(drill 0.254)
		(layers "F.Cu" "B.Cu")
		(net "LED_HFI1_CPU0_N")
	)
	(segment
		(start 356.962456 -72.8726)
		(end 361.315 -72.8726)
		(width 0.089408)
		(layer "In11.Cu")
		(net "LED_HFI1_CPU0_N")
	)
	(segment
		(start 373.220488 -121.22531)
		(end 373.220488 -125.018546)
		(width 0.089408)
		(layer "In11.Cu")
		(net "LED_HFI1_CPU0_N")
	)
	(segment
		(start 413.963612 -130.451352)
		(end 413.963612 -128.852676)
		(width 0.089408)
		(layer "In11.Cu")
		(net "LED_HFI1_CPU0_N")
	)
	(segment
		(start 385.782312 -129.089404)
		(end 390.694164 -134.001256)
		(width 0.089408)
		(layer "In11.Cu")
		(net "LED_HFI1_CPU0_N")
	)
	(segment
		(start 375.147332 -125.388624)
		(end 375.698512 -125.939804)
		(width 0.089408)
		(layer "In11.Cu")
		(net "LED_HFI1_CPU0_N")
	)
	(segment
		(start 384.330448 -125.581918)
		(end 385.533392 -126.784862)
		(width 0.089408)
		(layer "In11.Cu")
		(net "LED_HFI1_CPU0_N")
	)
	(segment
		(start 374.434354 -109.660436)
		(end 374.434354 -116.250466)
		(width 0.089408)
		(layer "In11.Cu")
		(net "LED_HFI1_CPU0_N")
	)
	(segment
		(start 361.315 -72.8726)
		(end 363.31144 -74.86904)
		(width 0.089408)
		(layer "In11.Cu")
		(net "LED_HFI1_CPU0_N")
	)
	(segment
		(start 363.31144 -74.86904)
		(end 363.31144 -77.738732)
		(width 0.089408)
		(layer "In11.Cu")
		(net "LED_HFI1_CPU0_N")
	)
	(segment
		(start 352.141536 -72.639936)
		(end 355.424994 -72.639936)
		(width 0.089408)
		(layer "In11.Cu")
		(net "LED_HFI1_CPU0_N")
	)
	(segment
		(start 363.038898 -79.102966)
		(end 363.00029 -79.295244)
		(width 0.089408)
		(layer "In11.Cu")
		(net "LED_HFI1_CPU0_N")
	)
	(segment
		(start 333.64932 -74.1934)
		(end 336.4992 -74.1934)
		(width 0.089408)
		(layer "In11.Cu")
		(net "LED_HFI1_CPU0_N")
	)
	(segment
		(start 363.232954 -78.132432)
		(end 363.039406 -79.102458)
		(width 0.089408)
		(layer "In11.Cu")
		(net "LED_HFI1_CPU0_N")
	)
	(segment
		(start 338.950808 -70.979792)
		(end 350.481392 -70.979792)
		(width 0.089408)
		(layer "In11.Cu")
		(net "LED_HFI1_CPU0_N")
	)
	(segment
		(start 297.520106 -75.12558)
		(end 297.54068 -75.12558)
		(width 0.089408)
		(layer "In11.Cu")
		(net "LED_HFI1_CPU0_N")
	)
	(segment
		(start 355.424994 -72.639936)
		(end 355.731064 -72.333866)
		(width 0.089408)
		(layer "In11.Cu")
		(net "LED_HFI1_CPU0_N")
	)
	(segment
		(start 398.58061 -134.001256)
		(end 399.323052 -133.258814)
		(width 0.089408)
		(layer "In11.Cu")
		(net "LED_HFI1_CPU0_N")
	)
	(segment
		(start 404.715726 -129.349754)
		(end 408.68473 -129.349754)
		(width 0.089408)
		(layer "In11.Cu")
		(net "LED_HFI1_CPU0_N")
	)
	(segment
		(start 362.84281 -84.622132)
		(end 363.55401 -85.333332)
		(width 0.089408)
		(layer "In11.Cu")
		(net "LED_HFI1_CPU0_N")
	)
	(segment
		(start 374.066562 -120.379236)
		(end 373.220488 -121.22531)
		(width 0.089408)
		(layer "In11.Cu")
		(net "LED_HFI1_CPU0_N")
	)
	(segment
		(start 371.653562 -109.363002)
		(end 374.13692 -109.363002)
		(width 0.089408)
		(layer "In11.Cu")
		(net "LED_HFI1_CPU0_N")
	)
	(segment
		(start 296.654728 -74.630534)
		(end 296.68597 -74.630534)
		(width 0.089408)
		(layer "In11.Cu")
		(net "LED_HFI1_CPU0_N")
	)
	(segment
		(start 363.31017 -77.745082)
		(end 363.292644 -77.832966)
		(width 0.089408)
		(layer "In11.Cu")
		(net "LED_HFI1_CPU0_N")
	)
	(segment
		(start 399.323052 -133.258814)
		(end 400.806158 -133.258814)
		(width 0.089408)
		(layer "In11.Cu")
		(net "LED_HFI1_CPU0_N")
	)
	(segment
		(start 373.220488 -125.018546)
		(end 373.590566 -125.388624)
		(width 0.089408)
		(layer "In11.Cu")
		(net "LED_HFI1_CPU0_N")
	)
	(segment
		(start 362.84281 -80.082136)
		(end 362.84281 -84.622132)
		(width 0.089408)
		(layer "In11.Cu")
		(net "LED_HFI1_CPU0_N")
	)
	(segment
		(start 390.694164 -134.001256)
		(end 398.58061 -134.001256)
		(width 0.089408)
		(layer "In11.Cu")
		(net "LED_HFI1_CPU0_N")
	)
	(segment
		(start 293.20363 -74.630534)
		(end 293.234872 -74.630534)
		(width 0.089408)
		(layer "In11.Cu")
		(net "LED_HFI1_CPU0_N")
	)
	(segment
		(start 369.2144 -105.262426)
		(end 369.2144 -106.92384)
		(width 0.089408)
		(layer "In11.Cu")
		(net "LED_HFI1_CPU0_N")
	)
	(segment
		(start 363.55401 -99.602036)
		(end 369.2144 -105.262426)
		(width 0.089408)
		(layer "In11.Cu")
		(net "LED_HFI1_CPU0_N")
	)
	(segment
		(start 363.292644 -77.832966)
		(end 363.287818 -77.856588)
		(width 0.089408)
		(layer "In11.Cu")
		(net "LED_HFI1_CPU0_N")
	)
	(segment
		(start 331.215238 -75.169268)
		(end 332.673452 -75.169268)
		(width 0.089408)
		(layer "In11.Cu")
		(net "LED_HFI1_CPU0_N")
	)
	(segment
		(start 331.068934 -75.022964)
		(end 331.215238 -75.169268)
		(width 0.089408)
		(layer "In11.Cu")
		(net "LED_HFI1_CPU0_N")
	)
	(segment
		(start 375.698512 -125.939804)
		(end 380.272544 -125.939804)
		(width 0.089408)
		(layer "In11.Cu")
		(net "LED_HFI1_CPU0_N")
	)
	(segment
		(start 307.87594 -76.202286)
		(end 309.055262 -75.022964)
		(width 0.089408)
		(layer "In11.Cu")
		(net "LED_HFI1_CPU0_N")
	)
	(segment
		(start 374.066562 -116.618258)
		(end 374.066562 -120.379236)
		(width 0.089408)
		(layer "In11.Cu")
		(net "LED_HFI1_CPU0_N")
	)
	(segment
		(start 305.413156 -75.621134)
		(end 305.994308 -76.202286)
		(width 0.089408)
		(layer "In11.Cu")
		(net "LED_HFI1_CPU0_N")
	)
	(segment
		(start 289.79368 -76.707238)
		(end 289.81019 -76.707238)
		(width 0.089408)
		(layer "In11.Cu")
		(net "LED_HFI1_CPU0_N")
	)
	(segment
		(start 291.48659 -75.621134)
		(end 291.517832 -75.621134)
		(width 0.089408)
		(layer "In11.Cu")
		(net "LED_HFI1_CPU0_N")
	)
	(segment
		(start 413.743648 -130.671316)
		(end 413.963612 -130.451352)
		(width 0.089408)
		(layer "In11.Cu")
		(net "LED_HFI1_CPU0_N")
	)
	(segment
		(start 355.965506 -71.741284)
		(end 356.304596 -71.741284)
		(width 0.089408)
		(layer "In11.Cu")
		(net "LED_HFI1_CPU0_N")
	)
	(segment
		(start 385.533392 -128.253744)
		(end 385.782312 -128.502664)
		(width 0.089408)
		(layer "In11.Cu")
		(net "LED_HFI1_CPU0_N")
	)
	(segment
		(start 303.522634 -75.621134)
		(end 305.413156 -75.621134)
		(width 0.089408)
		(layer "In11.Cu")
		(net "LED_HFI1_CPU0_N")
	)
	(segment
		(start 309.055262 -75.022964)
		(end 331.068934 -75.022964)
		(width 0.089408)
		(layer "In11.Cu")
		(net "LED_HFI1_CPU0_N")
	)
	(segment
		(start 408.68473 -129.349754)
		(end 410.006292 -130.671316)
		(width 0.089408)
		(layer "In11.Cu")
		(net "LED_HFI1_CPU0_N")
	)
	(segment
		(start 332.673452 -75.169268)
		(end 333.64932 -74.1934)
		(width 0.089408)
		(layer "In11.Cu")
		(net "LED_HFI1_CPU0_N")
	)
	(segment
		(start 350.481392 -70.979792)
		(end 352.141536 -72.639936)
		(width 0.089408)
		(layer "In11.Cu")
		(net "LED_HFI1_CPU0_N")
	)
	(segment
		(start 305.994308 -76.202286)
		(end 307.87594 -76.202286)
		(width 0.089408)
		(layer "In11.Cu")
		(net "LED_HFI1_CPU0_N")
	)
	(segment
		(start 363.287818 -77.856588)
		(end 363.232954 -78.132432)
		(width 0.089408)
		(layer "In11.Cu")
		(net "LED_HFI1_CPU0_N")
	)
	(segment
		(start 336.4992 -74.1934)
		(end 336.83067 -73.86193)
		(width 0.089408)
		(layer "In11.Cu")
		(net "LED_HFI1_CPU0_N")
	)
	(segment
		(start 356.569264 -72.005952)
		(end 356.569264 -72.479408)
		(width 0.089408)
		(layer "In11.Cu")
		(net "LED_HFI1_CPU0_N")
	)
	(segment
		(start 385.782312 -128.502664)
		(end 385.782312 -129.089404)
		(width 0.089408)
		(layer "In11.Cu")
		(net "LED_HFI1_CPU0_N")
	)
	(segment
		(start 355.731064 -72.333866)
		(end 355.731064 -71.975726)
		(width 0.089408)
		(layer "In11.Cu")
		(net "LED_HFI1_CPU0_N")
	)
	(segment
		(start 380.272544 -125.939804)
		(end 380.370842 -125.841506)
		(width 0.089408)
		(layer "In11.Cu")
		(net "LED_HFI1_CPU0_N")
	)
	(segment
		(start 374.13692 -109.363002)
		(end 374.434354 -109.660436)
		(width 0.089408)
		(layer "In11.Cu")
		(net "LED_HFI1_CPU0_N")
	)
	(segment
		(start 369.2144 -106.92384)
		(end 371.653562 -109.363002)
		(width 0.089408)
		(layer "In11.Cu")
		(net "LED_HFI1_CPU0_N")
	)
	(segment
		(start 374.434354 -116.250466)
		(end 374.066562 -116.618258)
		(width 0.089408)
		(layer "In11.Cu")
		(net "LED_HFI1_CPU0_N")
	)
	(segment
		(start 363.31144 -77.738732)
		(end 363.31017 -77.745082)
		(width 0.089408)
		(layer "In11.Cu")
		(net "LED_HFI1_CPU0_N")
	)
	(segment
		(start 297.173904 -74.925682)
		(end 297.17619 -74.929492)
		(width 0.089408)
		(layer "In11.Cu")
		(net "LED_HFI1_CPU0_N")
	)
	(segment
		(start 292.348666 -75.12558)
		(end 292.381432 -75.12558)
		(width 0.089408)
		(layer "In11.Cu")
		(net "LED_HFI1_CPU0_N")
	)
	(segment
		(start 380.371096 -125.841506)
		(end 380.630684 -125.581918)
		(width 0.089408)
		(layer "In11.Cu")
		(net "LED_HFI1_CPU0_N")
	)
	(segment
		(start 380.370842 -125.841506)
		(end 380.371096 -125.841506)
		(width 0.089408)
		(layer "In11.Cu")
		(net "LED_HFI1_CPU0_N")
	)
	(segment
		(start 336.83067 -73.86193)
		(end 336.83067 -73.09993)
		(width 0.089408)
		(layer "In11.Cu")
		(net "LED_HFI1_CPU0_N")
	)
	(segment
		(start 356.569264 -72.479408)
		(end 356.962456 -72.8726)
		(width 0.089408)
		(layer "In11.Cu")
		(net "LED_HFI1_CPU0_N")
	)
	(segment
		(start 356.304596 -71.741284)
		(end 356.569264 -72.005952)
		(width 0.089408)
		(layer "In11.Cu")
		(net "LED_HFI1_CPU0_N")
	)
	(segment
		(start 363.00029 -79.295244)
		(end 362.84281 -80.082136)
		(width 0.089408)
		(layer "In11.Cu")
		(net "LED_HFI1_CPU0_N")
	)
	(segment
		(start 336.83067 -73.09993)
		(end 338.950808 -70.979792)
		(width 0.089408)
		(layer "In11.Cu")
		(net "LED_HFI1_CPU0_N")
	)
	(segment
		(start 400.806158 -133.258814)
		(end 404.715726 -129.349754)
		(width 0.089408)
		(layer "In11.Cu")
		(net "LED_HFI1_CPU0_N")
	)
	(segment
		(start 363.039406 -79.102458)
		(end 363.038898 -79.102966)
		(width 0.089408)
		(layer "In11.Cu")
		(net "LED_HFI1_CPU0_N")
	)
	(segment
		(start 363.55401 -85.333332)
		(end 363.55401 -99.602036)
		(width 0.089408)
		(layer "In11.Cu")
		(net "LED_HFI1_CPU0_N")
	)
	(segment
		(start 410.006292 -130.671316)
		(end 413.743648 -130.671316)
		(width 0.089408)
		(layer "In11.Cu")
		(net "LED_HFI1_CPU0_N")
	)
	(segment
		(start 355.731064 -71.975726)
		(end 355.965506 -71.741284)
		(width 0.089408)
		(layer "In11.Cu")
		(net "LED_HFI1_CPU0_N")
	)
	(segment
		(start 380.630684 -125.581918)
		(end 384.330448 -125.581918)
		(width 0.089408)
		(layer "In11.Cu")
		(net "LED_HFI1_CPU0_N")
	)
	(segment
		(start 373.590566 -125.388624)
		(end 375.147332 -125.388624)
		(width 0.089408)
		(layer "In11.Cu")
		(net "LED_HFI1_CPU0_N")
	)
	(segment
		(start 385.533392 -126.784862)
		(end 385.533392 -128.253744)
		(width 0.089408)
		(layer "In11.Cu")
		(net "LED_HFI1_CPU0_N")
	)
	(arc
		(start 290.55822 -76.120498)
		(mid 290.634356 -76.119744)
		(end 290.710112 -76.112116)
		(width 0.089408)
		(layer "In11.Cu")
		(net "LED_HFI1_CPU0_N")
	)
	(arc
		(start 293.234872 -74.630534)
		(mid 293.430904 -74.57515)
		(end 293.574216 -74.430382)
		(width 0.089408)
		(layer "In11.Cu")
		(net "LED_HFI1_CPU0_N")
	)
	(arc
		(start 289.81019 -76.707238)
		(mid 290.075799 -76.609939)
		(end 290.233354 -76.375006)
		(width 0.089408)
		(layer "In11.Cu")
		(net "LED_HFI1_CPU0_N")
	)
	(arc
		(start 303.18329 -75.420982)
		(mid 303.326601 -75.565753)
		(end 303.522634 -75.621134)
		(width 0.089408)
		(layer "In11.Cu")
		(net "LED_HFI1_CPU0_N")
	)
	(arc
		(start 301.46625 -75.420982)
		(mid 301.812706 -75.6212)
		(end 302.159162 -75.420982)
		(width 0.089408)
		(layer "In11.Cu")
		(net "LED_HFI1_CPU0_N")
	)
	(arc
		(start 299.74921 -75.420982)
		(mid 300.095666 -75.6212)
		(end 300.442122 -75.420982)
		(width 0.089408)
		(layer "In11.Cu")
		(net "LED_HFI1_CPU0_N")
	)
	(arc
		(start 290.710112 -76.112116)
		(mid 290.876835 -76.047287)
		(end 290.998656 -75.916282)
		(width 0.089408)
		(layer "In11.Cu")
		(net "LED_HFI1_CPU0_N")
	)
	(arc
		(start 297.54068 -75.12558)
		(mid 297.824641 -75.209698)
		(end 298.03217 -75.420982)
		(width 0.089408)
		(layer "In11.Cu")
		(net "LED_HFI1_CPU0_N")
	)
	(arc
		(start 290.233354 -76.375006)
		(mid 290.349369 -76.188495)
		(end 290.55822 -76.120498)
		(width 0.089408)
		(layer "In11.Cu")
		(net "LED_HFI1_CPU0_N")
	)
	(arc
		(start 290.998656 -75.916282)
		(mid 291.204693 -75.706004)
		(end 291.48659 -75.621134)
		(width 0.089408)
		(layer "In11.Cu")
		(net "LED_HFI1_CPU0_N")
	)
	(arc
		(start 291.517832 -75.621134)
		(mid 291.713864 -75.56575)
		(end 291.857176 -75.420982)
		(width 0.089408)
		(layer "In11.Cu")
		(net "LED_HFI1_CPU0_N")
	)
	(arc
		(start 296.68597 -74.630534)
		(mid 296.967872 -74.715397)
		(end 297.173904 -74.925682)
		(width 0.089408)
		(layer "In11.Cu")
		(net "LED_HFI1_CPU0_N")
	)
	(arc
		(start 296.315384 -74.430382)
		(mid 296.458695 -74.575153)
		(end 296.654728 -74.630534)
		(width 0.089408)
		(layer "In11.Cu")
		(net "LED_HFI1_CPU0_N")
	)
	(arc
		(start 288.93516 -76.706984)
		(mid 289.36442 -76.707175)
		(end 289.79368 -76.707238)
		(width 0.089408)
		(layer "In11.Cu")
		(net "LED_HFI1_CPU0_N")
	)
	(arc
		(start 294.598344 -74.430382)
		(mid 294.9448 -74.6306)
		(end 295.291256 -74.430382)
		(width 0.089408)
		(layer "In11.Cu")
		(net "LED_HFI1_CPU0_N")
	)
	(arc
		(start 293.574216 -74.430382)
		(mid 294.08628 -74.134623)
		(end 294.598344 -74.430382)
		(width 0.089408)
		(layer "In11.Cu")
		(net "LED_HFI1_CPU0_N")
	)
	(arc
		(start 295.291256 -74.430382)
		(mid 295.80332 -74.134623)
		(end 296.315384 -74.430382)
		(width 0.089408)
		(layer "In11.Cu")
		(net "LED_HFI1_CPU0_N")
	)
	(arc
		(start 292.381432 -75.12558)
		(mid 292.574535 -75.069061)
		(end 292.715696 -74.925682)
		(width 0.089408)
		(layer "In11.Cu")
		(net "LED_HFI1_CPU0_N")
	)
	(arc
		(start 302.159162 -75.420982)
		(mid 302.671226 -75.125223)
		(end 303.18329 -75.420982)
		(width 0.089408)
		(layer "In11.Cu")
		(net "LED_HFI1_CPU0_N")
	)
	(arc
		(start 298.725082 -75.420982)
		(mid 299.237146 -75.125223)
		(end 299.74921 -75.420982)
		(width 0.089408)
		(layer "In11.Cu")
		(net "LED_HFI1_CPU0_N")
	)
	(arc
		(start 292.715696 -74.925682)
		(mid 292.921733 -74.715404)
		(end 293.20363 -74.630534)
		(width 0.089408)
		(layer "In11.Cu")
		(net "LED_HFI1_CPU0_N")
	)
	(arc
		(start 297.17619 -74.929492)
		(mid 297.322149 -75.073147)
		(end 297.520106 -75.12558)
		(width 0.089408)
		(layer "In11.Cu")
		(net "LED_HFI1_CPU0_N")
	)
	(arc
		(start 300.442122 -75.420982)
		(mid 300.954186 -75.125223)
		(end 301.46625 -75.420982)
		(width 0.089408)
		(layer "In11.Cu")
		(net "LED_HFI1_CPU0_N")
	)
	(arc
		(start 298.03217 -75.420982)
		(mid 298.378626 -75.6212)
		(end 298.725082 -75.420982)
		(width 0.089408)
		(layer "In11.Cu")
		(net "LED_HFI1_CPU0_N")
	)
	(arc
		(start 291.857176 -75.420982)
		(mid 292.064705 -75.209698)
		(end 292.348666 -75.12558)
		(width 0.089408)
		(layer "In11.Cu")
		(net "LED_HFI1_CPU0_N")
	)
	(segment
		(start 412.923482 -131.805172)
		(end 413.334454 -131.3942)
		(width 0.10795)
		(layer "F.Cu")
		(net "LED_HFI0_CPU0_N")
	)
	(segment
		(start 412.333694 -131.805172)
		(end 412.923482 -131.805172)
		(width 0.10795)
		(layer "F.Cu")
		(net "LED_HFI0_CPU0_N")
	)
	(segment
		(start 290.0807 -75.716384)
		(end 290.6522 -75.716384)
		(width 0.10795)
		(layer "F.Cu")
		(net "LED_HFI0_CPU0_N")
	)
	(segment
		(start 415.98342 -130.740404)
		(end 416.405314 -130.31851)
		(width 0.10795)
		(layer "F.Cu")
		(net "LED_HFI0_CPU0_N")
	)
	(segment
		(start 415.191194 -130.740404)
		(end 415.98342 -130.740404)
		(width 0.10795)
		(layer "F.Cu")
		(net "LED_HFI0_CPU0_N")
	)
	(segment
		(start 413.935672 -131.3942)
		(end 414.589468 -130.740404)
		(width 0.10795)
		(layer "F.Cu")
		(net "LED_HFI0_CPU0_N")
	)
	(segment
		(start 413.334454 -131.3942)
		(end 413.935672 -131.3942)
		(width 0.10795)
		(layer "F.Cu")
		(net "LED_HFI0_CPU0_N")
	)
	(segment
		(start 414.589468 -130.740404)
		(end 415.191194 -130.740404)
		(width 0.10795)
		(layer "F.Cu")
		(net "LED_HFI0_CPU0_N")
	)
	(via
		(at 341.39886 -117.76202)
		(size 0.508)
		(drill 0.254)
		(layers "F.Cu" "B.Cu")
		(net "LED_HFI0_CPU0_N")
	)
	(via
		(at 338.4804 -88.8746)
		(size 0.508)
		(drill 0.254)
		(layers "F.Cu" "B.Cu")
		(net "LED_HFI0_CPU0_N")
	)
	(via
		(at 335.551272 -88.705436)
		(size 0.6604)
		(drill 0.3302)
		(layers "F.Cu" "B.Cu")
		(net "LED_HFI0_CPU0_N")
	)
	(via
		(at 416.405314 -130.31851)
		(size 0.508)
		(drill 0.254)
		(layers "F.Cu" "B.Cu")
		(net "LED_HFI0_CPU0_N")
	)
	(via
		(at 290.6522 -75.716384)
		(size 0.508)
		(drill 0.254)
		(layers "F.Cu" "B.Cu")
		(net "LED_HFI0_CPU0_N")
	)
	(via
		(at 331.611732 -74.755502)
		(size 0.508)
		(drill 0.254)
		(layers "F.Cu" "B.Cu")
		(net "LED_HFI0_CPU0_N")
	)
	(segment
		(start 335.551272 -88.705436)
		(end 336.186272 -89.340436)
		(width 0.10795)
		(layer "B.Cu")
		(net "LED_HFI0_CPU0_N")
	)
	(segment
		(start 334.01889 -87.173054)
		(end 335.551272 -88.705436)
		(width 0.10795)
		(layer "B.Cu")
		(net "LED_HFI0_CPU0_N")
	)
	(segment
		(start 332.692248 -78.420468)
		(end 334.01889 -79.74711)
		(width 0.10795)
		(layer "B.Cu")
		(net "LED_HFI0_CPU0_N")
	)
	(segment
		(start 332.692248 -75.836018)
		(end 332.692248 -78.420468)
		(width 0.10795)
		(layer "B.Cu")
		(net "LED_HFI0_CPU0_N")
	)
	(segment
		(start 338.014564 -89.340436)
		(end 338.4804 -88.8746)
		(width 0.10795)
		(layer "B.Cu")
		(net "LED_HFI0_CPU0_N")
	)
	(segment
		(start 334.01889 -79.74711)
		(end 334.01889 -87.173054)
		(width 0.10795)
		(layer "B.Cu")
		(net "LED_HFI0_CPU0_N")
	)
	(segment
		(start 331.611732 -74.755502)
		(end 332.692248 -75.836018)
		(width 0.10795)
		(layer "B.Cu")
		(net "LED_HFI0_CPU0_N")
	)
	(segment
		(start 336.186272 -89.340436)
		(end 338.014564 -89.340436)
		(width 0.10795)
		(layer "B.Cu")
		(net "LED_HFI0_CPU0_N")
	)
	(segment
		(start 332.027276 -96.821498)
		(end 332.027276 -95.407734)
		(width 0.089408)
		(layer "In4.Cu")
		(net "LED_HFI0_CPU0_N")
	)
	(segment
		(start 334.626712 -112.282478)
		(end 334.626712 -108.513372)
		(width 0.089408)
		(layer "In4.Cu")
		(net "LED_HFI0_CPU0_N")
	)
	(segment
		(start 341.39886 -117.76202)
		(end 340.977728 -118.183152)
		(width 0.089408)
		(layer "In4.Cu")
		(net "LED_HFI0_CPU0_N")
	)
	(segment
		(start 340.977728 -118.183152)
		(end 340.527386 -118.183152)
		(width 0.089408)
		(layer "In4.Cu")
		(net "LED_HFI0_CPU0_N")
	)
	(segment
		(start 334.626712 -108.513372)
		(end 334.297782 -108.184442)
		(width 0.089408)
		(layer "In4.Cu")
		(net "LED_HFI0_CPU0_N")
	)
	(segment
		(start 332.02753 -96.821752)
		(end 332.027276 -96.821498)
		(width 0.089408)
		(layer "In4.Cu")
		(net "LED_HFI0_CPU0_N")
	)
	(segment
		(start 332.02753 -106.399076)
		(end 332.02753 -96.821752)
		(width 0.089408)
		(layer "In4.Cu")
		(net "LED_HFI0_CPU0_N")
	)
	(segment
		(start 340.527386 -118.183152)
		(end 334.626712 -112.282478)
		(width 0.089408)
		(layer "In4.Cu")
		(net "LED_HFI0_CPU0_N")
	)
	(segment
		(start 332.027276 -95.407734)
		(end 332.02753 -95.40748)
		(width 0.089408)
		(layer "In4.Cu")
		(net "LED_HFI0_CPU0_N")
	)
	(segment
		(start 333.812896 -108.184442)
		(end 332.02753 -106.399076)
		(width 0.089408)
		(layer "In4.Cu")
		(net "LED_HFI0_CPU0_N")
	)
	(segment
		(start 334.297782 -108.184442)
		(end 333.812896 -108.184442)
		(width 0.089408)
		(layer "In4.Cu")
		(net "LED_HFI0_CPU0_N")
	)
	(segment
		(start 332.02753 -95.40748)
		(end 332.02753 -95.32747)
		(width 0.089408)
		(layer "In4.Cu")
		(net "LED_HFI0_CPU0_N")
	)
	(segment
		(start 332.02753 -95.32747)
		(end 338.4804 -88.8746)
		(width 0.089408)
		(layer "In4.Cu")
		(net "LED_HFI0_CPU0_N")
	)
	(segment
		(start 290.66998 -75.316334)
		(end 290.637214 -75.316334)
		(width 0.0889)
		(layer "In11.Cu")
		(net "LED_HFI0_CPU0_N")
	)
	(segment
		(start 308.86146 -74.704956)
		(end 308.24932 -75.317096)
		(width 0.089408)
		(layer "In11.Cu")
		(net "LED_HFI0_CPU0_N")
	)
	(segment
		(start 297.527218 -74.325988)
		(end 297.495976 -74.325988)
		(width 0.089408)
		(layer "In11.Cu")
		(net "LED_HFI0_CPU0_N")
	)
	(segment
		(start 296.66184 -73.830942)
		(end 296.641266 -73.830942)
		(width 0.089408)
		(layer "In11.Cu")
		(net "LED_HFI0_CPU0_N")
	)
	(segment
		(start 293.248334 -73.830942)
		(end 293.215568 -73.830942)
		(width 0.089408)
		(layer "In11.Cu")
		(net "LED_HFI0_CPU0_N")
	)
	(segment
		(start 290.359084 -75.54722)
		(end 290.6522 -75.716384)
		(width 0.0889)
		(layer "In11.Cu")
		(net "LED_HFI0_CPU0_N")
	)
	(segment
		(start 345.84513 -118.314724)
		(end 367.647474 -118.314724)
		(width 0.089408)
		(layer "In11.Cu")
		(net "LED_HFI0_CPU0_N")
	)
	(segment
		(start 385.050792 -128.319784)
		(end 385.400296 -128.669288)
		(width 0.089408)
		(layer "In11.Cu")
		(net "LED_HFI0_CPU0_N")
	)
	(segment
		(start 373.58447 -126.522734)
		(end 374.590056 -126.522734)
		(width 0.089408)
		(layer "In11.Cu")
		(net "LED_HFI0_CPU0_N")
	)
	(segment
		(start 297.008042 -74.03084)
		(end 297.005756 -74.02703)
		(width 0.089408)
		(layer "In11.Cu")
		(net "LED_HFI0_CPU0_N")
	)
	(segment
		(start 290.338002 -75.46848)
		(end 290.359084 -75.54722)
		(width 0.0889)
		(layer "In11.Cu")
		(net "LED_HFI0_CPU0_N")
	)
	(segment
		(start 374.590056 -126.522734)
		(end 374.79097 -126.32182)
		(width 0.089408)
		(layer "In11.Cu")
		(net "LED_HFI0_CPU0_N")
	)
	(segment
		(start 341.39886 -117.76202)
		(end 341.811102 -118.174262)
		(width 0.089408)
		(layer "In11.Cu")
		(net "LED_HFI0_CPU0_N")
	)
	(segment
		(start 408.935936 -130.141472)
		(end 409.847796 -131.053332)
		(width 0.089408)
		(layer "In11.Cu")
		(net "LED_HFI0_CPU0_N")
	)
	(segment
		(start 372.571518 -125.668024)
		(end 372.953788 -126.050294)
		(width 0.089408)
		(layer "In11.Cu")
		(net "LED_HFI0_CPU0_N")
	)
	(segment
		(start 381.050546 -126.092966)
		(end 384.22199 -126.092966)
		(width 0.089408)
		(layer "In11.Cu")
		(net "LED_HFI0_CPU0_N")
	)
	(segment
		(start 399.481548 -133.64083)
		(end 400.964654 -133.64083)
		(width 0.089408)
		(layer "In11.Cu")
		(net "LED_HFI0_CPU0_N")
	)
	(segment
		(start 373.584216 -126.522988)
		(end 373.58447 -126.522734)
		(width 0.089408)
		(layer "In11.Cu")
		(net "LED_HFI0_CPU0_N")
	)
	(segment
		(start 398.739106 -134.383272)
		(end 399.481548 -133.64083)
		(width 0.089408)
		(layer "In11.Cu")
		(net "LED_HFI0_CPU0_N")
	)
	(segment
		(start 331.251306 -74.755502)
		(end 331.20076 -74.704956)
		(width 0.089408)
		(layer "In11.Cu")
		(net "LED_HFI0_CPU0_N")
	)
	(segment
		(start 331.20076 -74.704956)
		(end 308.86146 -74.704956)
		(width 0.089408)
		(layer "In11.Cu")
		(net "LED_HFI0_CPU0_N")
	)
	(segment
		(start 404.464774 -130.141472)
		(end 408.935936 -130.141472)
		(width 0.089408)
		(layer "In11.Cu")
		(net "LED_HFI0_CPU0_N")
	)
	(segment
		(start 415.670492 -131.053332)
		(end 416.405314 -130.31851)
		(width 0.089408)
		(layer "In11.Cu")
		(net "LED_HFI0_CPU0_N")
	)
	(segment
		(start 385.400296 -128.669288)
		(end 385.400296 -129.2479)
		(width 0.089408)
		(layer "In11.Cu")
		(net "LED_HFI0_CPU0_N")
	)
	(segment
		(start 370.407946 -121.075196)
		(end 371.181376 -121.075196)
		(width 0.089408)
		(layer "In11.Cu")
		(net "LED_HFI0_CPU0_N")
	)
	(segment
		(start 292.39337 -74.325988)
		(end 292.362128 -74.325988)
		(width 0.089408)
		(layer "In11.Cu")
		(net "LED_HFI0_CPU0_N")
	)
	(segment
		(start 380.821692 -126.32182)
		(end 381.050546 -126.092966)
		(width 0.089408)
		(layer "In11.Cu")
		(net "LED_HFI0_CPU0_N")
	)
	(segment
		(start 367.647474 -118.314724)
		(end 370.407946 -121.075196)
		(width 0.089408)
		(layer "In11.Cu")
		(net "LED_HFI0_CPU0_N")
	)
	(segment
		(start 385.050792 -126.921768)
		(end 385.050792 -128.319784)
		(width 0.089408)
		(layer "In11.Cu")
		(net "LED_HFI0_CPU0_N")
	)
	(segment
		(start 331.611732 -74.755502)
		(end 331.251306 -74.755502)
		(width 0.089408)
		(layer "In11.Cu")
		(net "LED_HFI0_CPU0_N")
	)
	(segment
		(start 305.253898 -74.821542)
		(end 305.226212 -74.821542)
		(width 0.089408)
		(layer "In11.Cu")
		(net "LED_HFI0_CPU0_N")
	)
	(segment
		(start 390.535668 -134.383272)
		(end 398.739106 -134.383272)
		(width 0.089408)
		(layer "In11.Cu")
		(net "LED_HFI0_CPU0_N")
	)
	(segment
		(start 372.953788 -126.050548)
		(end 373.426228 -126.522988)
		(width 0.089408)
		(layer "In11.Cu")
		(net "LED_HFI0_CPU0_N")
	)
	(segment
		(start 385.400296 -129.2479)
		(end 390.535668 -134.383272)
		(width 0.089408)
		(layer "In11.Cu")
		(net "LED_HFI0_CPU0_N")
	)
	(segment
		(start 409.847796 -131.053332)
		(end 415.670492 -131.053332)
		(width 0.089408)
		(layer "In11.Cu")
		(net "LED_HFI0_CPU0_N")
	)
	(segment
		(start 345.704668 -118.174262)
		(end 345.84513 -118.314724)
		(width 0.089408)
		(layer "In11.Cu")
		(net "LED_HFI0_CPU0_N")
	)
	(segment
		(start 291.531294 -74.821542)
		(end 291.498528 -74.821542)
		(width 0.089408)
		(layer "In11.Cu")
		(net "LED_HFI0_CPU0_N")
	)
	(segment
		(start 341.811102 -118.174262)
		(end 345.704668 -118.174262)
		(width 0.089408)
		(layer "In11.Cu")
		(net "LED_HFI0_CPU0_N")
	)
	(segment
		(start 372.953788 -126.050294)
		(end 372.953788 -126.050548)
		(width 0.089408)
		(layer "In11.Cu")
		(net "LED_HFI0_CPU0_N")
	)
	(segment
		(start 373.426228 -126.522988)
		(end 373.584216 -126.522988)
		(width 0.089408)
		(layer "In11.Cu")
		(net "LED_HFI0_CPU0_N")
	)
	(segment
		(start 371.181376 -121.075196)
		(end 372.571518 -122.465338)
		(width 0.089408)
		(layer "In11.Cu")
		(net "LED_HFI0_CPU0_N")
	)
	(segment
		(start 372.571518 -122.465338)
		(end 372.571518 -125.668024)
		(width 0.089408)
		(layer "In11.Cu")
		(net "LED_HFI0_CPU0_N")
	)
	(segment
		(start 374.79097 -126.32182)
		(end 380.821692 -126.32182)
		(width 0.089408)
		(layer "In11.Cu")
		(net "LED_HFI0_CPU0_N")
	)
	(segment
		(start 400.964654 -133.64083)
		(end 404.464774 -130.141472)
		(width 0.089408)
		(layer "In11.Cu")
		(net "LED_HFI0_CPU0_N")
	)
	(segment
		(start 384.22199 -126.092966)
		(end 385.050792 -126.921768)
		(width 0.089408)
		(layer "In11.Cu")
		(net "LED_HFI0_CPU0_N")
	)
	(segment
		(start 308.24932 -75.317096)
		(end 306.084732 -75.317096)
		(width 0.089408)
		(layer "In11.Cu")
		(net "LED_HFI0_CPU0_N")
	)
	(arc
		(start 291.16401 -75.020932)
		(mid 290.955402 -75.232864)
		(end 290.66998 -75.316334)
		(width 0.0889)
		(layer "In11.Cu")
		(net "LED_HFI0_CPU0_N")
	)
	(arc
		(start 297.005756 -74.02703)
		(mid 296.859797 -73.883375)
		(end 296.66184 -73.830942)
		(width 0.089408)
		(layer "In11.Cu")
		(net "LED_HFI0_CPU0_N")
	)
	(arc
		(start 295.456864 -73.53554)
		(mid 294.9448 -73.831299)
		(end 294.432736 -73.53554)
		(width 0.089408)
		(layer "In11.Cu")
		(net "LED_HFI0_CPU0_N")
	)
	(arc
		(start 304.04181 -74.52614)
		(mid 303.529746 -74.821899)
		(end 303.017682 -74.52614)
		(width 0.089408)
		(layer "In11.Cu")
		(net "LED_HFI0_CPU0_N")
	)
	(arc
		(start 291.498528 -74.821542)
		(mid 291.305288 -74.877635)
		(end 291.16401 -75.020932)
		(width 0.0889)
		(layer "In11.Cu")
		(net "LED_HFI0_CPU0_N")
	)
	(arc
		(start 301.300642 -74.52614)
		(mid 300.954186 -74.325922)
		(end 300.60773 -74.52614)
		(width 0.089408)
		(layer "In11.Cu")
		(net "LED_HFI0_CPU0_N")
	)
	(arc
		(start 293.739824 -73.53554)
		(mid 293.532295 -73.746824)
		(end 293.248334 -73.830942)
		(width 0.089408)
		(layer "In11.Cu")
		(net "LED_HFI0_CPU0_N")
	)
	(arc
		(start 297.866562 -74.52614)
		(mid 297.723251 -74.381369)
		(end 297.527218 -74.325988)
		(width 0.089408)
		(layer "In11.Cu")
		(net "LED_HFI0_CPU0_N")
	)
	(arc
		(start 294.432736 -73.53554)
		(mid 294.08628 -73.335322)
		(end 293.739824 -73.53554)
		(width 0.089408)
		(layer "In11.Cu")
		(net "LED_HFI0_CPU0_N")
	)
	(arc
		(start 296.149776 -73.53554)
		(mid 295.80332 -73.335322)
		(end 295.456864 -73.53554)
		(width 0.089408)
		(layer "In11.Cu")
		(net "LED_HFI0_CPU0_N")
	)
	(arc
		(start 292.881304 -74.03084)
		(mid 292.675267 -74.241118)
		(end 292.39337 -74.325988)
		(width 0.089408)
		(layer "In11.Cu")
		(net "LED_HFI0_CPU0_N")
	)
	(arc
		(start 305.593242 -75.021694)
		(mid 305.449931 -74.876923)
		(end 305.253898 -74.821542)
		(width 0.089408)
		(layer "In11.Cu")
		(net "LED_HFI0_CPU0_N")
	)
	(arc
		(start 299.583602 -74.52614)
		(mid 299.237146 -74.325922)
		(end 298.89069 -74.52614)
		(width 0.089408)
		(layer "In11.Cu")
		(net "LED_HFI0_CPU0_N")
	)
	(arc
		(start 306.084732 -75.317096)
		(mid 305.800771 -75.232978)
		(end 305.593242 -75.021694)
		(width 0.089408)
		(layer "In11.Cu")
		(net "LED_HFI0_CPU0_N")
	)
	(arc
		(start 297.495976 -74.325988)
		(mid 297.214074 -74.241125)
		(end 297.008042 -74.03084)
		(width 0.089408)
		(layer "In11.Cu")
		(net "LED_HFI0_CPU0_N")
	)
	(arc
		(start 303.017682 -74.52614)
		(mid 302.671226 -74.325922)
		(end 302.32477 -74.52614)
		(width 0.089408)
		(layer "In11.Cu")
		(net "LED_HFI0_CPU0_N")
	)
	(arc
		(start 304.734722 -74.52614)
		(mid 304.388266 -74.325922)
		(end 304.04181 -74.52614)
		(width 0.089408)
		(layer "In11.Cu")
		(net "LED_HFI0_CPU0_N")
	)
	(arc
		(start 290.637214 -75.316334)
		(mid 290.47092 -75.359568)
		(end 290.338002 -75.46848)
		(width 0.0889)
		(layer "In11.Cu")
		(net "LED_HFI0_CPU0_N")
	)
	(arc
		(start 300.60773 -74.52614)
		(mid 300.095666 -74.821899)
		(end 299.583602 -74.52614)
		(width 0.089408)
		(layer "In11.Cu")
		(net "LED_HFI0_CPU0_N")
	)
	(arc
		(start 293.215568 -73.830942)
		(mid 293.022465 -73.887461)
		(end 292.881304 -74.03084)
		(width 0.089408)
		(layer "In11.Cu")
		(net "LED_HFI0_CPU0_N")
	)
	(arc
		(start 298.89069 -74.52614)
		(mid 298.378626 -74.821899)
		(end 297.866562 -74.52614)
		(width 0.089408)
		(layer "In11.Cu")
		(net "LED_HFI0_CPU0_N")
	)
	(arc
		(start 292.362128 -74.325988)
		(mid 292.166096 -74.381372)
		(end 292.022784 -74.52614)
		(width 0.089408)
		(layer "In11.Cu")
		(net "LED_HFI0_CPU0_N")
	)
	(arc
		(start 302.32477 -74.52614)
		(mid 301.812706 -74.821899)
		(end 301.300642 -74.52614)
		(width 0.089408)
		(layer "In11.Cu")
		(net "LED_HFI0_CPU0_N")
	)
	(arc
		(start 292.022784 -74.52614)
		(mid 291.815255 -74.737424)
		(end 291.531294 -74.821542)
		(width 0.089408)
		(layer "In11.Cu")
		(net "LED_HFI0_CPU0_N")
	)
	(arc
		(start 296.641266 -73.830942)
		(mid 296.357305 -73.746824)
		(end 296.149776 -73.53554)
		(width 0.089408)
		(layer "In11.Cu")
		(net "LED_HFI0_CPU0_N")
	)
	(arc
		(start 305.226212 -74.821542)
		(mid 304.942251 -74.737424)
		(end 304.734722 -74.52614)
		(width 0.089408)
		(layer "In11.Cu")
		(net "LED_HFI0_CPU0_N")
	)
	(segment
		(start 424.8023 -124.0536)
		(end 424.4467 -123.698)
		(width 0.10795)
		(layer "F.Cu")
		(net "IRQ_HFI1_CPU0_LVT2_N")
	)
	(segment
		(start 290.0807 -76.706984)
		(end 290.6522 -76.706984)
		(width 0.1016)
		(layer "F.Cu")
		(net "IRQ_HFI1_CPU0_LVT2_N")
	)
	(segment
		(start 425.5389 -124.0536)
		(end 424.8023 -124.0536)
		(width 0.10795)
		(layer "F.Cu")
		(net "IRQ_HFI1_CPU0_LVT2_N")
	)
	(segment
		(start 422.404286 -125.740414)
		(end 420.779194 -125.740414)
		(width 0.10795)
		(layer "F.Cu")
		(net "IRQ_HFI1_CPU0_LVT2_N")
	)
	(segment
		(start 424.4467 -123.698)
		(end 422.404286 -125.740414)
		(width 0.10795)
		(layer "F.Cu")
		(net "IRQ_HFI1_CPU0_LVT2_N")
	)
	(via
		(at 290.6522 -76.706984)
		(size 0.508)
		(drill 0.254)
		(layers "F.Cu" "B.Cu")
		(net "IRQ_HFI1_CPU0_LVT2_N")
	)
	(via
		(at 334.135984 -89.9414)
		(size 0.6604)
		(drill 0.3302)
		(layers "F.Cu" "B.Cu")
		(net "IRQ_HFI1_CPU0_LVT2_N")
	)
	(via
		(at 340.748112 -117.736112)
		(size 0.508)
		(drill 0.254)
		(layers "F.Cu" "B.Cu")
		(net "IRQ_HFI1_CPU0_LVT2_N")
	)
	(via
		(at 424.4467 -123.698)
		(size 0.508)
		(drill 0.254)
		(layers "F.Cu" "B.Cu")
		(net "IRQ_HFI1_CPU0_LVT2_N")
	)
	(via
		(at 334.135984 -91.74226)
		(size 0.508)
		(drill 0.254)
		(layers "F.Cu" "B.Cu")
		(net "IRQ_HFI1_CPU0_LVT2_N")
	)
	(via
		(at 331.79766 -75.75677)
		(size 0.508)
		(drill 0.254)
		(layers "F.Cu" "B.Cu")
		(net "IRQ_HFI1_CPU0_LVT2_N")
	)
	(segment
		(start 332.241906 -78.593442)
		(end 333.614268 -79.965804)
		(width 0.10795)
		(layer "B.Cu")
		(net "IRQ_HFI1_CPU0_LVT2_N")
	)
	(segment
		(start 334.135984 -87.948008)
		(end 334.135984 -89.9414)
		(width 0.10795)
		(layer "B.Cu")
		(net "IRQ_HFI1_CPU0_LVT2_N")
	)
	(segment
		(start 333.614268 -79.965804)
		(end 333.614268 -87.426292)
		(width 0.10795)
		(layer "B.Cu")
		(net "IRQ_HFI1_CPU0_LVT2_N")
	)
	(segment
		(start 332.241906 -76.201016)
		(end 332.241906 -78.593442)
		(width 0.10795)
		(layer "B.Cu")
		(net "IRQ_HFI1_CPU0_LVT2_N")
	)
	(segment
		(start 333.614268 -87.426292)
		(end 334.135984 -87.948008)
		(width 0.10795)
		(layer "B.Cu")
		(net "IRQ_HFI1_CPU0_LVT2_N")
	)
	(segment
		(start 331.79766 -75.75677)
		(end 332.241906 -76.201016)
		(width 0.10795)
		(layer "B.Cu")
		(net "IRQ_HFI1_CPU0_LVT2_N")
	)
	(segment
		(start 334.135984 -89.9414)
		(end 334.135984 -91.74226)
		(width 0.10795)
		(layer "B.Cu")
		(net "IRQ_HFI1_CPU0_LVT2_N")
	)
	(segment
		(start 337.2612 -116.393214)
		(end 337.2612 -108.59516)
		(width 0.089408)
		(layer "In9.Cu")
		(net "IRQ_HFI1_CPU0_LVT2_N")
	)
	(segment
		(start 338.604098 -117.736112)
		(end 337.2612 -116.393214)
		(width 0.089408)
		(layer "In9.Cu")
		(net "IRQ_HFI1_CPU0_LVT2_N")
	)
	(segment
		(start 337.2612 -108.59516)
		(end 336.53222 -107.86618)
		(width 0.089408)
		(layer "In9.Cu")
		(net "IRQ_HFI1_CPU0_LVT2_N")
	)
	(segment
		(start 334.011016 -105.91673)
		(end 334.135984 -105.791762)
		(width 0.089408)
		(layer "In9.Cu")
		(net "IRQ_HFI1_CPU0_LVT2_N")
	)
	(segment
		(start 340.748112 -117.736112)
		(end 338.604098 -117.736112)
		(width 0.089408)
		(layer "In9.Cu")
		(net "IRQ_HFI1_CPU0_LVT2_N")
	)
	(segment
		(start 334.011016 -107.399836)
		(end 334.011016 -105.91673)
		(width 0.089408)
		(layer "In9.Cu")
		(net "IRQ_HFI1_CPU0_LVT2_N")
	)
	(segment
		(start 336.53222 -107.86618)
		(end 334.47736 -107.86618)
		(width 0.089408)
		(layer "In9.Cu")
		(net "IRQ_HFI1_CPU0_LVT2_N")
	)
	(segment
		(start 334.47736 -107.86618)
		(end 334.011016 -107.399836)
		(width 0.089408)
		(layer "In9.Cu")
		(net "IRQ_HFI1_CPU0_LVT2_N")
	)
	(segment
		(start 334.135984 -105.791762)
		(end 334.135984 -91.74226)
		(width 0.089408)
		(layer "In9.Cu")
		(net "IRQ_HFI1_CPU0_LVT2_N")
	)
	(segment
		(start 330.238354 -75.349354)
		(end 328.177906 -75.349354)
		(width 0.089408)
		(layer "In11.Cu")
		(net "IRQ_HFI1_CPU0_LVT2_N")
	)
	(segment
		(start 378.379228 -127.135128)
		(end 374.867678 -127.135128)
		(width 0.089408)
		(layer "In11.Cu")
		(net "IRQ_HFI1_CPU0_LVT2_N")
	)
	(segment
		(start 374.867678 -127.135128)
		(end 374.50522 -126.77267)
		(width 0.089408)
		(layer "In11.Cu")
		(net "IRQ_HFI1_CPU0_LVT2_N")
	)
	(segment
		(start 384.142742 -126.28372)
		(end 382.02108 -126.28372)
		(width 0.089408)
		(layer "In11.Cu")
		(net "IRQ_HFI1_CPU0_LVT2_N")
	)
	(segment
		(start 331.79766 -75.75677)
		(end 331.601826 -75.952604)
		(width 0.089408)
		(layer "In11.Cu")
		(net "IRQ_HFI1_CPU0_LVT2_N")
	)
	(segment
		(start 297.527218 -75.316588)
		(end 297.495976 -75.316588)
		(width 0.089408)
		(layer "In11.Cu")
		(net "IRQ_HFI1_CPU0_LVT2_N")
	)
	(segment
		(start 385.209288 -129.327148)
		(end 385.209288 -128.748536)
		(width 0.089408)
		(layer "In11.Cu")
		(net "IRQ_HFI1_CPU0_LVT2_N")
	)
	(segment
		(start 424.8912 -124.797566)
		(end 424.612562 -125.076204)
		(width 0.089408)
		(layer "In11.Cu")
		(net "IRQ_HFI1_CPU0_LVT2_N")
	)
	(segment
		(start 367.568226 -118.505732)
		(end 345.765882 -118.505732)
		(width 0.089408)
		(layer "In11.Cu")
		(net "IRQ_HFI1_CPU0_LVT2_N")
	)
	(segment
		(start 384.832606 -126.973584)
		(end 384.142742 -126.28372)
		(width 0.089408)
		(layer "In11.Cu")
		(net "IRQ_HFI1_CPU0_LVT2_N")
	)
	(segment
		(start 372.38051 -125.747272)
		(end 372.38051 -122.544586)
		(width 0.089408)
		(layer "In11.Cu")
		(net "IRQ_HFI1_CPU0_LVT2_N")
	)
	(segment
		(start 327.776586 -75.750674)
		(end 308.711854 -75.750674)
		(width 0.089408)
		(layer "In11.Cu")
		(net "IRQ_HFI1_CPU0_LVT2_N")
	)
	(segment
		(start 290.717224 -76.30414)
		(end 290.6522 -76.369164)
		(width 0.089408)
		(layer "In11.Cu")
		(net "IRQ_HFI1_CPU0_LVT2_N")
	)
	(segment
		(start 341.37727 -118.36527)
		(end 340.748112 -117.736112)
		(width 0.089408)
		(layer "In11.Cu")
		(net "IRQ_HFI1_CPU0_LVT2_N")
	)
	(segment
		(start 374.50522 -126.77267)
		(end 373.405908 -126.77267)
		(width 0.089408)
		(layer "In11.Cu")
		(net "IRQ_HFI1_CPU0_LVT2_N")
	)
	(segment
		(start 293.248334 -74.821542)
		(end 293.215568 -74.821542)
		(width 0.089408)
		(layer "In11.Cu")
		(net "IRQ_HFI1_CPU0_LVT2_N")
	)
	(segment
		(start 330.841604 -75.952604)
		(end 330.238354 -75.349354)
		(width 0.089408)
		(layer "In11.Cu")
		(net "IRQ_HFI1_CPU0_LVT2_N")
	)
	(segment
		(start 408.856688 -130.33248)
		(end 404.544276 -130.33248)
		(width 0.089408)
		(layer "In11.Cu")
		(net "IRQ_HFI1_CPU0_LVT2_N")
	)
	(segment
		(start 382.02108 -126.28372)
		(end 381.543052 -126.761748)
		(width 0.089408)
		(layer "In11.Cu")
		(net "IRQ_HFI1_CPU0_LVT2_N")
	)
	(segment
		(start 305.921156 -76.430124)
		(end 305.30419 -75.813158)
		(width 0.089408)
		(layer "In11.Cu")
		(net "IRQ_HFI1_CPU0_LVT2_N")
	)
	(segment
		(start 424.316652 -125.076204)
		(end 420.196518 -129.196338)
		(width 0.089408)
		(layer "In11.Cu")
		(net "IRQ_HFI1_CPU0_LVT2_N")
	)
	(segment
		(start 416.04565 -131.24434)
		(end 409.768548 -131.24434)
		(width 0.089408)
		(layer "In11.Cu")
		(net "IRQ_HFI1_CPU0_LVT2_N")
	)
	(segment
		(start 345.62542 -118.36527)
		(end 341.37727 -118.36527)
		(width 0.089408)
		(layer "In11.Cu")
		(net "IRQ_HFI1_CPU0_LVT2_N")
	)
	(segment
		(start 424.8912 -124.1425)
		(end 424.8912 -124.797566)
		(width 0.089408)
		(layer "In11.Cu")
		(net "IRQ_HFI1_CPU0_LVT2_N")
	)
	(segment
		(start 401.043902 -133.831838)
		(end 399.560796 -133.831838)
		(width 0.089408)
		(layer "In11.Cu")
		(net "IRQ_HFI1_CPU0_LVT2_N")
	)
	(segment
		(start 418.093652 -129.196338)
		(end 416.04565 -131.24434)
		(width 0.089408)
		(layer "In11.Cu")
		(net "IRQ_HFI1_CPU0_LVT2_N")
	)
	(segment
		(start 381.543052 -126.761748)
		(end 378.752608 -126.761748)
		(width 0.089408)
		(layer "In11.Cu")
		(net "IRQ_HFI1_CPU0_LVT2_N")
	)
	(segment
		(start 384.832606 -128.371854)
		(end 384.832606 -126.973584)
		(width 0.089408)
		(layer "In11.Cu")
		(net "IRQ_HFI1_CPU0_LVT2_N")
	)
	(segment
		(start 398.818354 -134.57428)
		(end 390.45642 -134.57428)
		(width 0.089408)
		(layer "In11.Cu")
		(net "IRQ_HFI1_CPU0_LVT2_N")
	)
	(segment
		(start 409.768548 -131.24434)
		(end 408.856688 -130.33248)
		(width 0.089408)
		(layer "In11.Cu")
		(net "IRQ_HFI1_CPU0_LVT2_N")
	)
	(segment
		(start 370.328698 -121.266204)
		(end 367.568226 -118.505732)
		(width 0.089408)
		(layer "In11.Cu")
		(net "IRQ_HFI1_CPU0_LVT2_N")
	)
	(segment
		(start 371.102128 -121.266204)
		(end 370.328698 -121.266204)
		(width 0.089408)
		(layer "In11.Cu")
		(net "IRQ_HFI1_CPU0_LVT2_N")
	)
	(segment
		(start 291.531294 -75.812142)
		(end 291.498528 -75.812142)
		(width 0.089408)
		(layer "In11.Cu")
		(net "IRQ_HFI1_CPU0_LVT2_N")
	)
	(segment
		(start 404.544276 -130.33248)
		(end 401.043902 -133.831838)
		(width 0.089408)
		(layer "In11.Cu")
		(net "IRQ_HFI1_CPU0_LVT2_N")
	)
	(segment
		(start 399.560796 -133.831838)
		(end 398.818354 -134.57428)
		(width 0.089408)
		(layer "In11.Cu")
		(net "IRQ_HFI1_CPU0_LVT2_N")
	)
	(segment
		(start 331.601826 -75.952604)
		(end 330.841604 -75.952604)
		(width 0.089408)
		(layer "In11.Cu")
		(net "IRQ_HFI1_CPU0_LVT2_N")
	)
	(segment
		(start 390.45642 -134.57428)
		(end 385.209288 -129.327148)
		(width 0.089408)
		(layer "In11.Cu")
		(net "IRQ_HFI1_CPU0_LVT2_N")
	)
	(segment
		(start 296.66184 -74.821542)
		(end 296.641266 -74.821542)
		(width 0.089408)
		(layer "In11.Cu")
		(net "IRQ_HFI1_CPU0_LVT2_N")
	)
	(segment
		(start 420.196518 -129.196338)
		(end 418.093652 -129.196338)
		(width 0.089408)
		(layer "In11.Cu")
		(net "IRQ_HFI1_CPU0_LVT2_N")
	)
	(segment
		(start 424.612562 -125.076204)
		(end 424.316652 -125.076204)
		(width 0.089408)
		(layer "In11.Cu")
		(net "IRQ_HFI1_CPU0_LVT2_N")
	)
	(segment
		(start 385.209288 -128.748536)
		(end 384.832606 -128.371854)
		(width 0.089408)
		(layer "In11.Cu")
		(net "IRQ_HFI1_CPU0_LVT2_N")
	)
	(segment
		(start 308.711854 -75.750674)
		(end 308.032404 -76.430124)
		(width 0.089408)
		(layer "In11.Cu")
		(net "IRQ_HFI1_CPU0_LVT2_N")
	)
	(segment
		(start 308.032404 -76.430124)
		(end 305.921156 -76.430124)
		(width 0.089408)
		(layer "In11.Cu")
		(net "IRQ_HFI1_CPU0_LVT2_N")
	)
	(segment
		(start 424.4467 -123.698)
		(end 424.8912 -124.1425)
		(width 0.089408)
		(layer "In11.Cu")
		(net "IRQ_HFI1_CPU0_LVT2_N")
	)
	(segment
		(start 305.30419 -75.813158)
		(end 303.530762 -75.813158)
		(width 0.089408)
		(layer "In11.Cu")
		(net "IRQ_HFI1_CPU0_LVT2_N")
	)
	(segment
		(start 292.39337 -75.316588)
		(end 292.362128 -75.316588)
		(width 0.089408)
		(layer "In11.Cu")
		(net "IRQ_HFI1_CPU0_LVT2_N")
	)
	(segment
		(start 328.177906 -75.349354)
		(end 327.776586 -75.750674)
		(width 0.089408)
		(layer "In11.Cu")
		(net "IRQ_HFI1_CPU0_LVT2_N")
	)
	(segment
		(start 372.38051 -122.544586)
		(end 371.102128 -121.266204)
		(width 0.089408)
		(layer "In11.Cu")
		(net "IRQ_HFI1_CPU0_LVT2_N")
	)
	(segment
		(start 297.008042 -75.02144)
		(end 297.005756 -75.01763)
		(width 0.089408)
		(layer "In11.Cu")
		(net "IRQ_HFI1_CPU0_LVT2_N")
	)
	(segment
		(start 373.405908 -126.77267)
		(end 372.38051 -125.747272)
		(width 0.089408)
		(layer "In11.Cu")
		(net "IRQ_HFI1_CPU0_LVT2_N")
	)
	(segment
		(start 378.752608 -126.761748)
		(end 378.379228 -127.135128)
		(width 0.089408)
		(layer "In11.Cu")
		(net "IRQ_HFI1_CPU0_LVT2_N")
	)
	(segment
		(start 345.765882 -118.505732)
		(end 345.62542 -118.36527)
		(width 0.089408)
		(layer "In11.Cu")
		(net "IRQ_HFI1_CPU0_LVT2_N")
	)
	(segment
		(start 290.6522 -76.369164)
		(end 290.6522 -76.706984)
		(width 0.089408)
		(layer "In11.Cu")
		(net "IRQ_HFI1_CPU0_LVT2_N")
	)
	(arc
		(start 293.215568 -74.821542)
		(mid 293.022465 -74.878061)
		(end 292.881304 -75.02144)
		(width 0.089408)
		(layer "In11.Cu")
		(net "IRQ_HFI1_CPU0_LVT2_N")
	)
	(arc
		(start 296.641266 -74.821542)
		(mid 296.357305 -74.737424)
		(end 296.149776 -74.52614)
		(width 0.089408)
		(layer "In11.Cu")
		(net "IRQ_HFI1_CPU0_LVT2_N")
	)
	(arc
		(start 301.300642 -75.51674)
		(mid 300.954186 -75.316522)
		(end 300.60773 -75.51674)
		(width 0.089408)
		(layer "In11.Cu")
		(net "IRQ_HFI1_CPU0_LVT2_N")
	)
	(arc
		(start 300.60773 -75.51674)
		(mid 300.095666 -75.812499)
		(end 299.583602 -75.51674)
		(width 0.089408)
		(layer "In11.Cu")
		(net "IRQ_HFI1_CPU0_LVT2_N")
	)
	(arc
		(start 291.164264 -76.01204)
		(mid 290.975586 -76.211402)
		(end 290.717224 -76.30414)
		(width 0.089408)
		(layer "In11.Cu")
		(net "IRQ_HFI1_CPU0_LVT2_N")
	)
	(arc
		(start 296.149776 -74.52614)
		(mid 295.80332 -74.325922)
		(end 295.456864 -74.52614)
		(width 0.089408)
		(layer "In11.Cu")
		(net "IRQ_HFI1_CPU0_LVT2_N")
	)
	(arc
		(start 303.530762 -75.813158)
		(mid 303.234447 -75.733753)
		(end 303.017682 -75.51674)
		(width 0.089408)
		(layer "In11.Cu")
		(net "IRQ_HFI1_CPU0_LVT2_N")
	)
	(arc
		(start 297.495976 -75.316588)
		(mid 297.214074 -75.231725)
		(end 297.008042 -75.02144)
		(width 0.089408)
		(layer "In11.Cu")
		(net "IRQ_HFI1_CPU0_LVT2_N")
	)
	(arc
		(start 297.866562 -75.51674)
		(mid 297.723251 -75.371969)
		(end 297.527218 -75.316588)
		(width 0.089408)
		(layer "In11.Cu")
		(net "IRQ_HFI1_CPU0_LVT2_N")
	)
	(arc
		(start 292.881304 -75.02144)
		(mid 292.675267 -75.231718)
		(end 292.39337 -75.316588)
		(width 0.089408)
		(layer "In11.Cu")
		(net "IRQ_HFI1_CPU0_LVT2_N")
	)
	(arc
		(start 292.362128 -75.316588)
		(mid 292.166096 -75.371972)
		(end 292.022784 -75.51674)
		(width 0.089408)
		(layer "In11.Cu")
		(net "IRQ_HFI1_CPU0_LVT2_N")
	)
	(arc
		(start 295.456864 -74.52614)
		(mid 294.9448 -74.821899)
		(end 294.432736 -74.52614)
		(width 0.089408)
		(layer "In11.Cu")
		(net "IRQ_HFI1_CPU0_LVT2_N")
	)
	(arc
		(start 299.583602 -75.51674)
		(mid 299.237146 -75.316522)
		(end 298.89069 -75.51674)
		(width 0.089408)
		(layer "In11.Cu")
		(net "IRQ_HFI1_CPU0_LVT2_N")
	)
	(arc
		(start 293.739824 -74.52614)
		(mid 293.532295 -74.737424)
		(end 293.248334 -74.821542)
		(width 0.089408)
		(layer "In11.Cu")
		(net "IRQ_HFI1_CPU0_LVT2_N")
	)
	(arc
		(start 291.498528 -75.812142)
		(mid 291.305425 -75.868661)
		(end 291.164264 -76.01204)
		(width 0.089408)
		(layer "In11.Cu")
		(net "IRQ_HFI1_CPU0_LVT2_N")
	)
	(arc
		(start 292.022784 -75.51674)
		(mid 291.815255 -75.728024)
		(end 291.531294 -75.812142)
		(width 0.089408)
		(layer "In11.Cu")
		(net "IRQ_HFI1_CPU0_LVT2_N")
	)
	(arc
		(start 298.89069 -75.51674)
		(mid 298.378626 -75.812499)
		(end 297.866562 -75.51674)
		(width 0.089408)
		(layer "In11.Cu")
		(net "IRQ_HFI1_CPU0_LVT2_N")
	)
	(arc
		(start 303.017682 -75.51674)
		(mid 302.671226 -75.316522)
		(end 302.32477 -75.51674)
		(width 0.089408)
		(layer "In11.Cu")
		(net "IRQ_HFI1_CPU0_LVT2_N")
	)
	(arc
		(start 294.432736 -74.52614)
		(mid 294.08628 -74.325922)
		(end 293.739824 -74.52614)
		(width 0.089408)
		(layer "In11.Cu")
		(net "IRQ_HFI1_CPU0_LVT2_N")
	)
	(arc
		(start 302.32477 -75.51674)
		(mid 301.812706 -75.812499)
		(end 301.300642 -75.51674)
		(width 0.089408)
		(layer "In11.Cu")
		(net "IRQ_HFI1_CPU0_LVT2_N")
	)
	(arc
		(start 297.005756 -75.01763)
		(mid 296.859797 -74.873975)
		(end 296.66184 -74.821542)
		(width 0.089408)
		(layer "In11.Cu")
		(net "IRQ_HFI1_CPU0_LVT2_N")
	)
	(segment
		(start 356.7176 -73.6346)
		(end 356.3366 -73.6346)
		(width 0.10795)
		(layer "F.Cu")
		(net "IRQ_HFI0_CPU0_LVT2_N")
	)
	(segment
		(start 349.0214 -73.6346)
		(end 347.5228 -72.136)
		(width 0.10795)
		(layer "F.Cu")
		(net "IRQ_HFI0_CPU0_LVT2_N")
	)
	(segment
		(start 425.205144 -127.3175)
		(end 425.6405 -127.3175)
		(width 0.10795)
		(layer "F.Cu")
		(net "IRQ_HFI0_CPU0_LVT2_N")
	)
	(segment
		(start 291.79774 -77.697584)
		(end 292.36924 -77.697584)
		(width 0.1016)
		(layer "F.Cu")
		(net "IRQ_HFI0_CPU0_LVT2_N")
	)
	(segment
		(start 364.777274 -83.2866)
		(end 362.641388 -81.150714)
		(width 0.10795)
		(layer "F.Cu")
		(net "IRQ_HFI0_CPU0_LVT2_N")
	)
	(segment
		(start 420.779194 -129.740406)
		(end 422.988994 -129.740406)
		(width 0.10795)
		(layer "F.Cu")
		(net "IRQ_HFI0_CPU0_LVT2_N")
	)
	(segment
		(start 424.841924 -126.95428)
		(end 425.205144 -127.3175)
		(width 0.10795)
		(layer "F.Cu")
		(net "IRQ_HFI0_CPU0_LVT2_N")
	)
	(segment
		(start 360.517694 -73.822052)
		(end 356.905052 -73.822052)
		(width 0.10795)
		(layer "F.Cu")
		(net "IRQ_HFI0_CPU0_LVT2_N")
	)
	(segment
		(start 424.75785 -127.97155)
		(end 424.75785 -127.038354)
		(width 0.10795)
		(layer "F.Cu")
		(net "IRQ_HFI0_CPU0_LVT2_N")
	)
	(segment
		(start 366.649 -83.2866)
		(end 364.777274 -83.2866)
		(width 0.10795)
		(layer "F.Cu")
		(net "IRQ_HFI0_CPU0_LVT2_N")
	)
	(segment
		(start 422.988994 -129.740406)
		(end 424.75785 -127.97155)
		(width 0.10795)
		(layer "F.Cu")
		(net "IRQ_HFI0_CPU0_LVT2_N")
	)
	(segment
		(start 356.905052 -73.822052)
		(end 356.7176 -73.6346)
		(width 0.10795)
		(layer "F.Cu")
		(net "IRQ_HFI0_CPU0_LVT2_N")
	)
	(segment
		(start 362.641388 -75.945746)
		(end 360.517694 -73.822052)
		(width 0.10795)
		(layer "F.Cu")
		(net "IRQ_HFI0_CPU0_LVT2_N")
	)
	(segment
		(start 424.75785 -127.038354)
		(end 424.841924 -126.95428)
		(width 0.10795)
		(layer "F.Cu")
		(net "IRQ_HFI0_CPU0_LVT2_N")
	)
	(segment
		(start 356.3366 -73.6346)
		(end 349.0214 -73.6346)
		(width 0.10795)
		(layer "F.Cu")
		(net "IRQ_HFI0_CPU0_LVT2_N")
	)
	(segment
		(start 362.641388 -81.150714)
		(end 362.641388 -75.945746)
		(width 0.10795)
		(layer "F.Cu")
		(net "IRQ_HFI0_CPU0_LVT2_N")
	)
	(via
		(at 383.688336 -83.98256)
		(size 0.508)
		(drill 0.254)
		(layers "F.Cu" "B.Cu")
		(net "IRQ_HFI0_CPU0_LVT2_N")
	)
	(via
		(at 356.3366 -73.6346)
		(size 0.762)
		(drill 0.381)
		(layers "F.Cu" "B.Cu")
		(net "IRQ_HFI0_CPU0_LVT2_N")
	)
	(via
		(at 347.5228 -72.136)
		(size 0.508)
		(drill 0.254)
		(layers "F.Cu" "B.Cu")
		(net "IRQ_HFI0_CPU0_LVT2_N")
	)
	(via
		(at 424.841924 -126.95428)
		(size 0.508)
		(drill 0.254)
		(layers "F.Cu" "B.Cu")
		(net "IRQ_HFI0_CPU0_LVT2_N")
	)
	(via
		(at 366.649 -83.2866)
		(size 0.508)
		(drill 0.254)
		(layers "F.Cu" "B.Cu")
		(net "IRQ_HFI0_CPU0_LVT2_N")
	)
	(via
		(at 292.36924 -77.697584)
		(size 0.508)
		(drill 0.254)
		(layers "F.Cu" "B.Cu")
		(net "IRQ_HFI0_CPU0_LVT2_N")
	)
	(segment
		(start 384.393694 -82.760058)
		(end 384.385312 -82.76844)
		(width 0.10795)
		(layer "B.Cu")
		(net "IRQ_HFI0_CPU0_LVT2_N")
	)
	(segment
		(start 424.024298 -126.168404)
		(end 424.024298 -121.764298)
		(width 0.10795)
		(layer "B.Cu")
		(net "IRQ_HFI0_CPU0_LVT2_N")
	)
	(segment
		(start 424.810174 -126.95428)
		(end 424.024298 -126.168404)
		(width 0.10795)
		(layer "B.Cu")
		(net "IRQ_HFI0_CPU0_LVT2_N")
	)
	(segment
		(start 408.328114 -82.607912)
		(end 407.73985 -82.019648)
		(width 0.10795)
		(layer "B.Cu")
		(net "IRQ_HFI0_CPU0_LVT2_N")
	)
	(segment
		(start 396.857982 -80.518)
		(end 394.499084 -78.159102)
		(width 0.10795)
		(layer "B.Cu")
		(net "IRQ_HFI0_CPU0_LVT2_N")
	)
	(segment
		(start 383.688336 -83.161124)
		(end 383.688336 -83.98256)
		(width 0.10795)
		(layer "B.Cu")
		(net "IRQ_HFI0_CPU0_LVT2_N")
	)
	(segment
		(start 418.465 -101.463856)
		(end 418.2872 -101.286056)
		(width 0.10795)
		(layer "B.Cu")
		(net "IRQ_HFI0_CPU0_LVT2_N")
	)
	(segment
		(start 414.353502 -84.074)
		(end 413.78505 -83.505548)
		(width 0.10795)
		(layer "B.Cu")
		(net "IRQ_HFI0_CPU0_LVT2_N")
	)
	(segment
		(start 418.2872 -101.286056)
		(end 418.2872 -94.79661)
		(width 0.10795)
		(layer "B.Cu")
		(net "IRQ_HFI0_CPU0_LVT2_N")
	)
	(segment
		(start 387.91642 -82.76844)
		(end 384.752088 -82.76844)
		(width 0.10795)
		(layer "B.Cu")
		(net "IRQ_HFI0_CPU0_LVT2_N")
	)
	(segment
		(start 413.78505 -83.505548)
		(end 413.78505 -82.943954)
		(width 0.10795)
		(layer "B.Cu")
		(net "IRQ_HFI0_CPU0_LVT2_N")
	)
	(segment
		(start 418.2872 -94.79661)
		(end 418.799518 -94.284292)
		(width 0.10795)
		(layer "B.Cu")
		(net "IRQ_HFI0_CPU0_LVT2_N")
	)
	(segment
		(start 406.447752 -82.019648)
		(end 405.125936 -80.697832)
		(width 0.10795)
		(layer "B.Cu")
		(net "IRQ_HFI0_CPU0_LVT2_N")
	)
	(segment
		(start 389.62584 -79.685642)
		(end 389.62584 -81.05902)
		(width 0.10795)
		(layer "B.Cu")
		(net "IRQ_HFI0_CPU0_LVT2_N")
	)
	(segment
		(start 424.024298 -121.764298)
		(end 419.744652 -117.484652)
		(width 0.10795)
		(layer "B.Cu")
		(net "IRQ_HFI0_CPU0_LVT2_N")
	)
	(segment
		(start 407.73985 -82.019648)
		(end 406.447752 -82.019648)
		(width 0.10795)
		(layer "B.Cu")
		(net "IRQ_HFI0_CPU0_LVT2_N")
	)
	(segment
		(start 418.465 -101.473)
		(end 418.465 -101.463856)
		(width 0.10795)
		(layer "B.Cu")
		(net "IRQ_HFI0_CPU0_LVT2_N")
	)
	(segment
		(start 418.799518 -94.284292)
		(end 418.799518 -90.470482)
		(width 0.10795)
		(layer "B.Cu")
		(net "IRQ_HFI0_CPU0_LVT2_N")
	)
	(segment
		(start 424.841924 -126.95428)
		(end 424.810174 -126.95428)
		(width 0.10795)
		(layer "B.Cu")
		(net "IRQ_HFI0_CPU0_LVT2_N")
	)
	(segment
		(start 384.385312 -82.76844)
		(end 384.08102 -82.76844)
		(width 0.10795)
		(layer "B.Cu")
		(net "IRQ_HFI0_CPU0_LVT2_N")
	)
	(segment
		(start 413.449008 -82.607912)
		(end 408.328114 -82.607912)
		(width 0.10795)
		(layer "B.Cu")
		(net "IRQ_HFI0_CPU0_LVT2_N")
	)
	(segment
		(start 389.62584 -81.05902)
		(end 387.91642 -82.76844)
		(width 0.10795)
		(layer "B.Cu")
		(net "IRQ_HFI0_CPU0_LVT2_N")
	)
	(segment
		(start 400.562318 -80.518)
		(end 396.857982 -80.518)
		(width 0.10795)
		(layer "B.Cu")
		(net "IRQ_HFI0_CPU0_LVT2_N")
	)
	(segment
		(start 405.125936 -80.697832)
		(end 403.501352 -80.697832)
		(width 0.10795)
		(layer "B.Cu")
		(net "IRQ_HFI0_CPU0_LVT2_N")
	)
	(segment
		(start 419.227 -87.714836)
		(end 415.586164 -84.074)
		(width 0.10795)
		(layer "B.Cu")
		(net "IRQ_HFI0_CPU0_LVT2_N")
	)
	(segment
		(start 391.15238 -78.159102)
		(end 389.62584 -79.685642)
		(width 0.10795)
		(layer "B.Cu")
		(net "IRQ_HFI0_CPU0_LVT2_N")
	)
	(segment
		(start 419.227 -90.043)
		(end 419.227 -87.714836)
		(width 0.10795)
		(layer "B.Cu")
		(net "IRQ_HFI0_CPU0_LVT2_N")
	)
	(segment
		(start 418.799518 -90.470482)
		(end 419.227 -90.043)
		(width 0.10795)
		(layer "B.Cu")
		(net "IRQ_HFI0_CPU0_LVT2_N")
	)
	(segment
		(start 403.501352 -80.697832)
		(end 402.854668 -81.344516)
		(width 0.10795)
		(layer "B.Cu")
		(net "IRQ_HFI0_CPU0_LVT2_N")
	)
	(segment
		(start 415.586164 -84.074)
		(end 414.353502 -84.074)
		(width 0.10795)
		(layer "B.Cu")
		(net "IRQ_HFI0_CPU0_LVT2_N")
	)
	(segment
		(start 401.388834 -81.344516)
		(end 400.562318 -80.518)
		(width 0.10795)
		(layer "B.Cu")
		(net "IRQ_HFI0_CPU0_LVT2_N")
	)
	(segment
		(start 402.854668 -81.344516)
		(end 401.388834 -81.344516)
		(width 0.10795)
		(layer "B.Cu")
		(net "IRQ_HFI0_CPU0_LVT2_N")
	)
	(segment
		(start 419.744652 -102.752652)
		(end 418.465 -101.473)
		(width 0.10795)
		(layer "B.Cu")
		(net "IRQ_HFI0_CPU0_LVT2_N")
	)
	(segment
		(start 384.08102 -82.76844)
		(end 383.688336 -83.161124)
		(width 0.10795)
		(layer "B.Cu")
		(net "IRQ_HFI0_CPU0_LVT2_N")
	)
	(segment
		(start 394.499084 -78.159102)
		(end 391.15238 -78.159102)
		(width 0.10795)
		(layer "B.Cu")
		(net "IRQ_HFI0_CPU0_LVT2_N")
	)
	(segment
		(start 413.78505 -82.943954)
		(end 413.449008 -82.607912)
		(width 0.10795)
		(layer "B.Cu")
		(net "IRQ_HFI0_CPU0_LVT2_N")
	)
	(segment
		(start 419.744652 -117.484652)
		(end 419.744652 -102.752652)
		(width 0.10795)
		(layer "B.Cu")
		(net "IRQ_HFI0_CPU0_LVT2_N")
	)
	(segment
		(start 384.743706 -82.760058)
		(end 384.393694 -82.760058)
		(width 0.10795)
		(layer "B.Cu")
		(net "IRQ_HFI0_CPU0_LVT2_N")
	)
	(segment
		(start 384.752088 -82.76844)
		(end 384.743706 -82.760058)
		(width 0.10795)
		(layer "B.Cu")
		(net "IRQ_HFI0_CPU0_LVT2_N")
	)
	(segment
		(start 379.5522 -84.582)
		(end 378.661168 -84.582)
		(width 0.089408)
		(layer "In4.Cu")
		(net "IRQ_HFI0_CPU0_LVT2_N")
	)
	(segment
		(start 383.688336 -83.98256)
		(end 383.272284 -83.566508)
		(width 0.089408)
		(layer "In4.Cu")
		(net "IRQ_HFI0_CPU0_LVT2_N")
	)
	(segment
		(start 369.945412 -83.2866)
		(end 366.649 -83.2866)
		(width 0.089408)
		(layer "In4.Cu")
		(net "IRQ_HFI0_CPU0_LVT2_N")
	)
	(segment
		(start 378.661168 -84.582)
		(end 378.076968 -85.1662)
		(width 0.089408)
		(layer "In4.Cu")
		(net "IRQ_HFI0_CPU0_LVT2_N")
	)
	(segment
		(start 380.567692 -83.566508)
		(end 379.5522 -84.582)
		(width 0.089408)
		(layer "In4.Cu")
		(net "IRQ_HFI0_CPU0_LVT2_N")
	)
	(segment
		(start 372.866412 -86.2076)
		(end 369.945412 -83.2866)
		(width 0.089408)
		(layer "In4.Cu")
		(net "IRQ_HFI0_CPU0_LVT2_N")
	)
	(segment
		(start 375.6406 -85.1662)
		(end 374.5992 -86.2076)
		(width 0.089408)
		(layer "In4.Cu")
		(net "IRQ_HFI0_CPU0_LVT2_N")
	)
	(segment
		(start 378.076968 -85.1662)
		(end 375.6406 -85.1662)
		(width 0.089408)
		(layer "In4.Cu")
		(net "IRQ_HFI0_CPU0_LVT2_N")
	)
	(segment
		(start 374.5992 -86.2076)
		(end 372.866412 -86.2076)
		(width 0.089408)
		(layer "In4.Cu")
		(net "IRQ_HFI0_CPU0_LVT2_N")
	)
	(segment
		(start 383.272284 -83.566508)
		(end 380.567692 -83.566508)
		(width 0.089408)
		(layer "In4.Cu")
		(net "IRQ_HFI0_CPU0_LVT2_N")
	)
	(segment
		(start 292.751764 -77.842618)
		(end 292.662356 -77.866748)
		(width 0.0889)
		(layer "In11.Cu")
		(net "IRQ_HFI0_CPU0_LVT2_N")
	)
	(segment
		(start 347.5228 -72.136)
		(end 346.5576 -71.1708)
		(width 0.089408)
		(layer "In11.Cu")
		(net "IRQ_HFI0_CPU0_LVT2_N")
	)
	(segment
		(start 332.05039 -76.20635)
		(end 331.053694 -76.20635)
		(width 0.089408)
		(layer "In11.Cu")
		(net "IRQ_HFI0_CPU0_LVT2_N")
	)
	(segment
		(start 304.613056 -77.602588)
		(end 303.51857 -77.602588)
		(width 0.0889)
		(layer "In11.Cu")
		(net "IRQ_HFI0_CPU0_LVT2_N")
	)
	(segment
		(start 293.238936 -77.602588)
		(end 293.20617 -77.602588)
		(width 0.0889)
		(layer "In11.Cu")
		(net "IRQ_HFI0_CPU0_LVT2_N")
	)
	(segment
		(start 339.030056 -71.1708)
		(end 337.021678 -73.179178)
		(width 0.089408)
		(layer "In11.Cu")
		(net "IRQ_HFI0_CPU0_LVT2_N")
	)
	(segment
		(start 337.021678 -73.179178)
		(end 337.021678 -73.943718)
		(width 0.089408)
		(layer "In11.Cu")
		(net "IRQ_HFI0_CPU0_LVT2_N")
	)
	(segment
		(start 331.053694 -76.20635)
		(end 330.233782 -77.026262)
		(width 0.089408)
		(layer "In11.Cu")
		(net "IRQ_HFI0_CPU0_LVT2_N")
	)
	(segment
		(start 346.5576 -71.1708)
		(end 339.030056 -71.1708)
		(width 0.089408)
		(layer "In11.Cu")
		(net "IRQ_HFI0_CPU0_LVT2_N")
	)
	(segment
		(start 304.952908 -77.262736)
		(end 304.613056 -77.602588)
		(width 0.0889)
		(layer "In11.Cu")
		(net "IRQ_HFI0_CPU0_LVT2_N")
	)
	(segment
		(start 333.872332 -74.384408)
		(end 332.05039 -76.20635)
		(width 0.089408)
		(layer "In11.Cu")
		(net "IRQ_HFI0_CPU0_LVT2_N")
	)
	(segment
		(start 337.021678 -73.943718)
		(end 336.580988 -74.384408)
		(width 0.089408)
		(layer "In11.Cu")
		(net "IRQ_HFI0_CPU0_LVT2_N")
	)
	(segment
		(start 336.580988 -74.384408)
		(end 333.872332 -74.384408)
		(width 0.089408)
		(layer "In11.Cu")
		(net "IRQ_HFI0_CPU0_LVT2_N")
	)
	(segment
		(start 308.315868 -77.262736)
		(end 304.952908 -77.262736)
		(width 0.089408)
		(layer "In11.Cu")
		(net "IRQ_HFI0_CPU0_LVT2_N")
	)
	(segment
		(start 308.552342 -77.026262)
		(end 308.315868 -77.262736)
		(width 0.089408)
		(layer "In11.Cu")
		(net "IRQ_HFI0_CPU0_LVT2_N")
	)
	(segment
		(start 297.008296 -77.402436)
		(end 297.001692 -77.413866)
		(width 0.0889)
		(layer "In11.Cu")
		(net "IRQ_HFI0_CPU0_LVT2_N")
	)
	(segment
		(start 292.662356 -77.866748)
		(end 292.36924 -77.697584)
		(width 0.0889)
		(layer "In11.Cu")
		(net "IRQ_HFI0_CPU0_LVT2_N")
	)
	(segment
		(start 330.233782 -77.026262)
		(end 308.552342 -77.026262)
		(width 0.089408)
		(layer "In11.Cu")
		(net "IRQ_HFI0_CPU0_LVT2_N")
	)
	(arc
		(start 302.159416 -77.402436)
		(mid 301.812706 -77.602747)
		(end 301.465996 -77.402436)
		(width 0.0889)
		(layer "In11.Cu")
		(net "IRQ_HFI0_CPU0_LVT2_N")
	)
	(arc
		(start 298.031916 -77.402436)
		(mid 297.520106 -77.106769)
		(end 297.008296 -77.402436)
		(width 0.0889)
		(layer "In11.Cu")
		(net "IRQ_HFI0_CPU0_LVT2_N")
	)
	(arc
		(start 295.29151 -77.402436)
		(mid 294.9448 -77.602747)
		(end 294.59809 -77.402436)
		(width 0.0889)
		(layer "In11.Cu")
		(net "IRQ_HFI0_CPU0_LVT2_N")
	)
	(arc
		(start 301.465996 -77.402436)
		(mid 300.954186 -77.106769)
		(end 300.442376 -77.402436)
		(width 0.0889)
		(layer "In11.Cu")
		(net "IRQ_HFI0_CPU0_LVT2_N")
	)
	(arc
		(start 299.748956 -77.402436)
		(mid 299.237146 -77.106769)
		(end 298.725336 -77.402436)
		(width 0.0889)
		(layer "In11.Cu")
		(net "IRQ_HFI0_CPU0_LVT2_N")
	)
	(arc
		(start 298.725336 -77.402436)
		(mid 298.378626 -77.602747)
		(end 298.031916 -77.402436)
		(width 0.0889)
		(layer "In11.Cu")
		(net "IRQ_HFI0_CPU0_LVT2_N")
	)
	(arc
		(start 303.51857 -77.602588)
		(mid 303.32472 -77.546238)
		(end 303.183036 -77.402436)
		(width 0.0889)
		(layer "In11.Cu")
		(net "IRQ_HFI0_CPU0_LVT2_N")
	)
	(arc
		(start 294.59809 -77.402436)
		(mid 294.08628 -77.106769)
		(end 293.57447 -77.402436)
		(width 0.0889)
		(layer "In11.Cu")
		(net "IRQ_HFI0_CPU0_LVT2_N")
	)
	(arc
		(start 293.57447 -77.402436)
		(mid 293.432787 -77.54624)
		(end 293.238936 -77.602588)
		(width 0.0889)
		(layer "In11.Cu")
		(net "IRQ_HFI0_CPU0_LVT2_N")
	)
	(arc
		(start 293.20617 -77.602588)
		(mid 292.951505 -77.670617)
		(end 292.751764 -77.842618)
		(width 0.0889)
		(layer "In11.Cu")
		(net "IRQ_HFI0_CPU0_LVT2_N")
	)
	(arc
		(start 300.442376 -77.402436)
		(mid 300.095666 -77.602747)
		(end 299.748956 -77.402436)
		(width 0.0889)
		(layer "In11.Cu")
		(net "IRQ_HFI0_CPU0_LVT2_N")
	)
	(arc
		(start 297.001692 -77.413866)
		(mid 296.655175 -77.602681)
		(end 296.31513 -77.402436)
		(width 0.0889)
		(layer "In11.Cu")
		(net "IRQ_HFI0_CPU0_LVT2_N")
	)
	(arc
		(start 296.31513 -77.402436)
		(mid 295.80332 -77.106769)
		(end 295.29151 -77.402436)
		(width 0.0889)
		(layer "In11.Cu")
		(net "IRQ_HFI0_CPU0_LVT2_N")
	)
	(arc
		(start 303.183036 -77.402436)
		(mid 302.671226 -77.106769)
		(end 302.159416 -77.402436)
		(width 0.0889)
		(layer "In11.Cu")
		(net "IRQ_HFI0_CPU0_LVT2_N")
	)
	(segment
		(start 428.381668 -126.365508)
		(end 429.153574 -127.137414)
		(width 0.10795)
		(layer "F.Cu")
		(net "FM_MODPRST_HFI1_CPU0_LVT2_N")
	)
	(segment
		(start 419.046152 -121.829068)
		(end 419.806882 -121.068338)
		(width 0.10795)
		(layer "F.Cu")
		(net "FM_MODPRST_HFI1_CPU0_LVT2_N")
	)
	(segment
		(start 418.623242 -122.774456)
		(end 419.046152 -122.351546)
		(width 0.10795)
		(layer "F.Cu")
		(net "FM_MODPRST_HFI1_CPU0_LVT2_N")
	)
	(segment
		(start 419.806882 -121.068338)
		(end 419.806882 -120.789954)
		(width 0.10795)
		(layer "F.Cu")
		(net "FM_MODPRST_HFI1_CPU0_LVT2_N")
	)
	(segment
		(start 421.464994 -119.07012)
		(end 421.894 -118.641114)
		(width 0.10795)
		(layer "F.Cu")
		(net "FM_MODPRST_HFI1_CPU0_LVT2_N")
	)
	(segment
		(start 415.191194 -127.74041)
		(end 416.718242 -127.74041)
		(width 0.10795)
		(layer "F.Cu")
		(net "FM_MODPRST_HFI1_CPU0_LVT2_N")
	)
	(segment
		(start 418.623242 -125.83541)
		(end 418.623242 -122.774456)
		(width 0.10795)
		(layer "F.Cu")
		(net "FM_MODPRST_HFI1_CPU0_LVT2_N")
	)
	(segment
		(start 427.918626 -120.654826)
		(end 427.918626 -125.513338)
		(width 0.10795)
		(layer "F.Cu")
		(net "FM_MODPRST_HFI1_CPU0_LVT2_N")
	)
	(segment
		(start 416.718242 -127.74041)
		(end 418.623242 -125.83541)
		(width 0.10795)
		(layer "F.Cu")
		(net "FM_MODPRST_HFI1_CPU0_LVT2_N")
	)
	(segment
		(start 421.948102 -118.3767)
		(end 422.837102 -119.2657)
		(width 0.10795)
		(layer "F.Cu")
		(net "FM_MODPRST_HFI1_CPU0_LVT2_N")
	)
	(segment
		(start 291.79774 -78.688438)
		(end 292.36924 -78.688438)
		(width 0.1016)
		(layer "F.Cu")
		(net "FM_MODPRST_HFI1_CPU0_LVT2_N")
	)
	(segment
		(start 419.806628 -120.7897)
		(end 419.806628 -120.608852)
		(width 0.10795)
		(layer "F.Cu")
		(net "FM_MODPRST_HFI1_CPU0_LVT2_N")
	)
	(segment
		(start 428.381668 -126.293118)
		(end 428.381668 -126.365508)
		(width 0.10795)
		(layer "F.Cu")
		(net "FM_MODPRST_HFI1_CPU0_LVT2_N")
	)
	(segment
		(start 422.837102 -119.2657)
		(end 426.5295 -119.2657)
		(width 0.10795)
		(layer "F.Cu")
		(net "FM_MODPRST_HFI1_CPU0_LVT2_N")
	)
	(segment
		(start 429.153574 -127.137414)
		(end 429.153574 -127.88519)
		(width 0.10795)
		(layer "F.Cu")
		(net "FM_MODPRST_HFI1_CPU0_LVT2_N")
	)
	(segment
		(start 429.153574 -127.88519)
		(end 429.283114 -128.01473)
		(width 0.10795)
		(layer "F.Cu")
		(net "FM_MODPRST_HFI1_CPU0_LVT2_N")
	)
	(segment
		(start 426.5295 -119.2657)
		(end 427.918626 -120.654826)
		(width 0.10795)
		(layer "F.Cu")
		(net "FM_MODPRST_HFI1_CPU0_LVT2_N")
	)
	(segment
		(start 419.806882 -120.789954)
		(end 419.806628 -120.7897)
		(width 0.10795)
		(layer "F.Cu")
		(net "FM_MODPRST_HFI1_CPU0_LVT2_N")
	)
	(segment
		(start 428.381668 -125.97638)
		(end 428.381668 -126.293118)
		(width 0.10795)
		(layer "F.Cu")
		(net "FM_MODPRST_HFI1_CPU0_LVT2_N")
	)
	(segment
		(start 421.34536 -119.07012)
		(end 421.464994 -119.07012)
		(width 0.10795)
		(layer "F.Cu")
		(net "FM_MODPRST_HFI1_CPU0_LVT2_N")
	)
	(segment
		(start 419.046152 -122.351546)
		(end 419.046152 -121.829068)
		(width 0.10795)
		(layer "F.Cu")
		(net "FM_MODPRST_HFI1_CPU0_LVT2_N")
	)
	(segment
		(start 421.894 -118.641114)
		(end 421.894 -118.3767)
		(width 0.10795)
		(layer "F.Cu")
		(net "FM_MODPRST_HFI1_CPU0_LVT2_N")
	)
	(segment
		(start 419.806628 -120.608852)
		(end 421.34536 -119.07012)
		(width 0.10795)
		(layer "F.Cu")
		(net "FM_MODPRST_HFI1_CPU0_LVT2_N")
	)
	(segment
		(start 427.918626 -125.513338)
		(end 428.381668 -125.97638)
		(width 0.10795)
		(layer "F.Cu")
		(net "FM_MODPRST_HFI1_CPU0_LVT2_N")
	)
	(segment
		(start 421.894 -118.3767)
		(end 421.948102 -118.3767)
		(width 0.10795)
		(layer "F.Cu")
		(net "FM_MODPRST_HFI1_CPU0_LVT2_N")
	)
	(via
		(at 331.05852 -78.598014)
		(size 0.508)
		(drill 0.254)
		(layers "F.Cu" "B.Cu")
		(net "FM_MODPRST_HFI1_CPU0_LVT2_N")
	)
	(via
		(at 292.36924 -78.688438)
		(size 0.508)
		(drill 0.254)
		(layers "F.Cu" "B.Cu")
		(net "FM_MODPRST_HFI1_CPU0_LVT2_N")
	)
	(via
		(at 428.381668 -126.293118)
		(size 0.762)
		(drill 0.381)
		(layers "F.Cu" "B.Cu")
		(net "FM_MODPRST_HFI1_CPU0_LVT2_N")
	)
	(via
		(at 429.283114 -128.01473)
		(size 0.508)
		(drill 0.254)
		(layers "F.Cu" "B.Cu")
		(net "FM_MODPRST_HFI1_CPU0_LVT2_N")
	)
	(via
		(at 327.322434 -113.115852)
		(size 0.508)
		(drill 0.254)
		(layers "F.Cu" "B.Cu")
		(net "FM_MODPRST_HFI1_CPU0_LVT2_N")
	)
	(segment
		(start 331.709014 -79.447898)
		(end 331.709014 -88.732614)
		(width 0.089408)
		(layer "In9.Cu")
		(net "FM_MODPRST_HFI1_CPU0_LVT2_N")
	)
	(segment
		(start 331.709014 -88.732614)
		(end 332.609952 -89.633552)
		(width 0.089408)
		(layer "In9.Cu")
		(net "FM_MODPRST_HFI1_CPU0_LVT2_N")
	)
	(segment
		(start 332.359 -105.768648)
		(end 332.359 -110.007654)
		(width 0.089408)
		(layer "In9.Cu")
		(net "FM_MODPRST_HFI1_CPU0_LVT2_N")
	)
	(segment
		(start 331.05852 -78.797404)
		(end 331.709014 -79.447898)
		(width 0.089408)
		(layer "In9.Cu")
		(net "FM_MODPRST_HFI1_CPU0_LVT2_N")
	)
	(segment
		(start 331.05852 -78.598014)
		(end 331.05852 -78.797404)
		(width 0.089408)
		(layer "In9.Cu")
		(net "FM_MODPRST_HFI1_CPU0_LVT2_N")
	)
	(segment
		(start 332.609952 -92.712794)
		(end 332.98638 -93.089222)
		(width 0.089408)
		(layer "In9.Cu")
		(net "FM_MODPRST_HFI1_CPU0_LVT2_N")
	)
	(segment
		(start 332.98638 -105.141268)
		(end 332.359 -105.768648)
		(width 0.089408)
		(layer "In9.Cu")
		(net "FM_MODPRST_HFI1_CPU0_LVT2_N")
	)
	(segment
		(start 332.609952 -89.633552)
		(end 332.609952 -92.712794)
		(width 0.089408)
		(layer "In9.Cu")
		(net "FM_MODPRST_HFI1_CPU0_LVT2_N")
	)
	(segment
		(start 332.359 -110.007654)
		(end 330.710794 -111.65586)
		(width 0.089408)
		(layer "In9.Cu")
		(net "FM_MODPRST_HFI1_CPU0_LVT2_N")
	)
	(segment
		(start 328.782426 -111.65586)
		(end 327.322434 -113.115852)
		(width 0.089408)
		(layer "In9.Cu")
		(net "FM_MODPRST_HFI1_CPU0_LVT2_N")
	)
	(segment
		(start 330.710794 -111.65586)
		(end 328.782426 -111.65586)
		(width 0.089408)
		(layer "In9.Cu")
		(net "FM_MODPRST_HFI1_CPU0_LVT2_N")
	)
	(segment
		(start 332.98638 -93.089222)
		(end 332.98638 -105.141268)
		(width 0.089408)
		(layer "In9.Cu")
		(net "FM_MODPRST_HFI1_CPU0_LVT2_N")
	)
	(segment
		(start 343.337134 -121.745248)
		(end 344.40876 -120.673622)
		(width 0.089408)
		(layer "In11.Cu")
		(net "FM_MODPRST_HFI1_CPU0_LVT2_N")
	)
	(segment
		(start 400.962622 -135.981694)
		(end 404.11146 -135.981694)
		(width 0.089408)
		(layer "In11.Cu")
		(net "FM_MODPRST_HFI1_CPU0_LVT2_N")
	)
	(segment
		(start 366.754918 -121.129298)
		(end 366.754918 -121.503186)
		(width 0.089408)
		(layer "In11.Cu")
		(net "FM_MODPRST_HFI1_CPU0_LVT2_N")
	)
	(segment
		(start 335.056734 -121.745248)
		(end 343.337134 -121.745248)
		(width 0.089408)
		(layer "In11.Cu")
		(net "FM_MODPRST_HFI1_CPU0_LVT2_N")
	)
	(segment
		(start 309.206138 -80.083152)
		(end 304.398426 -80.083152)
		(width 0.089408)
		(layer "In11.Cu")
		(net "FM_MODPRST_HFI1_CPU0_LVT2_N")
	)
	(segment
		(start 366.750346 -124.101098)
		(end 366.750346 -124.764546)
		(width 0.089408)
		(layer "In11.Cu")
		(net "FM_MODPRST_HFI1_CPU0_LVT2_N")
	)
	(segment
		(start 331.043788 -78.598014)
		(end 330.836524 -78.805278)
		(width 0.089408)
		(layer "In11.Cu")
		(net "FM_MODPRST_HFI1_CPU0_LVT2_N")
	)
	(segment
		(start 412.482284 -135.777478)
		(end 414.537398 -135.777478)
		(width 0.089408)
		(layer "In11.Cu")
		(net "FM_MODPRST_HFI1_CPU0_LVT2_N")
	)
	(segment
		(start 417.922964 -135.777478)
		(end 420.298372 -133.40207)
		(width 0.089408)
		(layer "In11.Cu")
		(net "FM_MODPRST_HFI1_CPU0_LVT2_N")
	)
	(segment
		(start 310.484012 -78.805278)
		(end 309.206138 -80.083152)
		(width 0.089408)
		(layer "In11.Cu")
		(net "FM_MODPRST_HFI1_CPU0_LVT2_N")
	)
	(segment
		(start 334.94345 -121.684796)
		(end 334.996282 -121.684796)
		(width 0.089408)
		(layer "In11.Cu")
		(net "FM_MODPRST_HFI1_CPU0_LVT2_N")
	)
	(segment
		(start 366.36579 -123.17984)
		(end 366.36579 -123.716542)
		(width 0.089408)
		(layer "In11.Cu")
		(net "FM_MODPRST_HFI1_CPU0_LVT2_N")
	)
	(segment
		(start 382.147064 -132.274564)
		(end 382.944624 -133.072124)
		(width 0.089408)
		(layer "In11.Cu")
		(net "FM_MODPRST_HFI1_CPU0_LVT2_N")
	)
	(segment
		(start 412.269178 -135.564372)
		(end 412.482284 -135.777478)
		(width 0.089408)
		(layer "In11.Cu")
		(net "FM_MODPRST_HFI1_CPU0_LVT2_N")
	)
	(segment
		(start 385.173982 -133.072124)
		(end 389.124698 -137.02284)
		(width 0.089408)
		(layer "In11.Cu")
		(net "FM_MODPRST_HFI1_CPU0_LVT2_N")
	)
	(segment
		(start 372.687342 -128.836166)
		(end 374.280176 -130.429)
		(width 0.089408)
		(layer "In11.Cu")
		(net "FM_MODPRST_HFI1_CPU0_LVT2_N")
	)
	(segment
		(start 332.838298 -115.380008)
		(end 333.18069 -115.7224)
		(width 0.089408)
		(layer "In11.Cu")
		(net "FM_MODPRST_HFI1_CPU0_LVT2_N")
	)
	(segment
		(start 366.750346 -122.795284)
		(end 366.36579 -123.17984)
		(width 0.089408)
		(layer "In11.Cu")
		(net "FM_MODPRST_HFI1_CPU0_LVT2_N")
	)
	(segment
		(start 426.451776 -127.6604)
		(end 428.928784 -127.6604)
		(width 0.089408)
		(layer "In11.Cu")
		(net "FM_MODPRST_HFI1_CPU0_LVT2_N")
	)
	(segment
		(start 330.836524 -78.805278)
		(end 310.484012 -78.805278)
		(width 0.089408)
		(layer "In11.Cu")
		(net "FM_MODPRST_HFI1_CPU0_LVT2_N")
	)
	(segment
		(start 333.18069 -119.922036)
		(end 334.94345 -121.684796)
		(width 0.089408)
		(layer "In11.Cu")
		(net "FM_MODPRST_HFI1_CPU0_LVT2_N")
	)
	(segment
		(start 374.280176 -130.429)
		(end 378.159772 -130.429)
		(width 0.089408)
		(layer "In11.Cu")
		(net "FM_MODPRST_HFI1_CPU0_LVT2_N")
	)
	(segment
		(start 366.465358 -123.811538)
		(end 366.729518 -124.075698)
		(width 0.089408)
		(layer "In11.Cu")
		(net "FM_MODPRST_HFI1_CPU0_LVT2_N")
	)
	(segment
		(start 302.683418 -80.07858)
		(end 302.650652 -80.07858)
		(width 0.089408)
		(layer "In11.Cu")
		(net "FM_MODPRST_HFI1_CPU0_LVT2_N")
	)
	(segment
		(start 414.759648 -135.999728)
		(end 416.700716 -135.999728)
		(width 0.089408)
		(layer "In11.Cu")
		(net "FM_MODPRST_HFI1_CPU0_LVT2_N")
	)
	(segment
		(start 416.700716 -135.999728)
		(end 416.922966 -135.777478)
		(width 0.089408)
		(layer "In11.Cu")
		(net "FM_MODPRST_HFI1_CPU0_LVT2_N")
	)
	(segment
		(start 382.944624 -133.072124)
		(end 385.173982 -133.072124)
		(width 0.089408)
		(layer "In11.Cu")
		(net "FM_MODPRST_HFI1_CPU0_LVT2_N")
	)
	(segment
		(start 293.25189 -79.583534)
		(end 293.220648 -79.583534)
		(width 0.089408)
		(layer "In11.Cu")
		(net "FM_MODPRST_HFI1_CPU0_LVT2_N")
	)
	(segment
		(start 378.159772 -130.429)
		(end 380.005336 -132.274564)
		(width 0.089408)
		(layer "In11.Cu")
		(net "FM_MODPRST_HFI1_CPU0_LVT2_N")
	)
	(segment
		(start 424.258486 -128.608328)
		(end 425.503848 -128.608328)
		(width 0.089408)
		(layer "In11.Cu")
		(net "FM_MODPRST_HFI1_CPU0_LVT2_N")
	)
	(segment
		(start 295.823894 -80.07858)
		(end 295.791128 -80.07858)
		(width 0.089408)
		(layer "In11.Cu")
		(net "FM_MODPRST_HFI1_CPU0_LVT2_N")
	)
	(segment
		(start 404.11146 -135.981694)
		(end 404.873968 -136.744202)
		(width 0.089408)
		(layer "In11.Cu")
		(net "FM_MODPRST_HFI1_CPU0_LVT2_N")
	)
	(segment
		(start 366.550702 -120.673622)
		(end 366.750346 -120.873266)
		(width 0.089408)
		(layer "In11.Cu")
		(net "FM_MODPRST_HFI1_CPU0_LVT2_N")
	)
	(segment
		(start 329.58659 -115.380008)
		(end 332.838298 -115.380008)
		(width 0.089408)
		(layer "In11.Cu")
		(net "FM_MODPRST_HFI1_CPU0_LVT2_N")
	)
	(segment
		(start 371.626384 -128.836166)
		(end 372.687342 -128.836166)
		(width 0.089408)
		(layer "In11.Cu")
		(net "FM_MODPRST_HFI1_CPU0_LVT2_N")
	)
	(segment
		(start 366.754918 -121.503186)
		(end 366.750346 -121.507758)
		(width 0.089408)
		(layer "In11.Cu")
		(net "FM_MODPRST_HFI1_CPU0_LVT2_N")
	)
	(segment
		(start 369.424458 -126.63424)
		(end 371.626384 -128.836166)
		(width 0.089408)
		(layer "In11.Cu")
		(net "FM_MODPRST_HFI1_CPU0_LVT2_N")
	)
	(segment
		(start 380.005336 -132.274564)
		(end 382.147064 -132.274564)
		(width 0.089408)
		(layer "In11.Cu")
		(net "FM_MODPRST_HFI1_CPU0_LVT2_N")
	)
	(segment
		(start 428.928784 -127.6604)
		(end 429.283114 -128.01473)
		(width 0.089408)
		(layer "In11.Cu")
		(net "FM_MODPRST_HFI1_CPU0_LVT2_N")
	)
	(segment
		(start 366.750346 -121.124726)
		(end 366.754918 -121.129298)
		(width 0.089408)
		(layer "In11.Cu")
		(net "FM_MODPRST_HFI1_CPU0_LVT2_N")
	)
	(segment
		(start 366.729518 -124.08027)
		(end 366.750346 -124.101098)
		(width 0.089408)
		(layer "In11.Cu")
		(net "FM_MODPRST_HFI1_CPU0_LVT2_N")
	)
	(segment
		(start 366.36579 -123.716542)
		(end 366.460786 -123.811538)
		(width 0.089408)
		(layer "In11.Cu")
		(net "FM_MODPRST_HFI1_CPU0_LVT2_N")
	)
	(segment
		(start 414.537398 -135.777478)
		(end 414.759648 -135.999728)
		(width 0.089408)
		(layer "In11.Cu")
		(net "FM_MODPRST_HFI1_CPU0_LVT2_N")
	)
	(segment
		(start 344.40876 -120.673622)
		(end 366.550702 -120.673622)
		(width 0.089408)
		(layer "In11.Cu")
		(net "FM_MODPRST_HFI1_CPU0_LVT2_N")
	)
	(segment
		(start 327.322434 -113.115852)
		(end 329.58659 -115.380008)
		(width 0.089408)
		(layer "In11.Cu")
		(net "FM_MODPRST_HFI1_CPU0_LVT2_N")
	)
	(segment
		(start 333.18069 -115.7224)
		(end 333.18069 -119.922036)
		(width 0.089408)
		(layer "In11.Cu")
		(net "FM_MODPRST_HFI1_CPU0_LVT2_N")
	)
	(segment
		(start 366.750346 -120.873266)
		(end 366.750346 -121.124726)
		(width 0.089408)
		(layer "In11.Cu")
		(net "FM_MODPRST_HFI1_CPU0_LVT2_N")
	)
	(segment
		(start 331.05852 -78.598014)
		(end 331.043788 -78.598014)
		(width 0.089408)
		(layer "In11.Cu")
		(net "FM_MODPRST_HFI1_CPU0_LVT2_N")
	)
	(segment
		(start 399.921476 -137.02284)
		(end 400.962622 -135.981694)
		(width 0.089408)
		(layer "In11.Cu")
		(net "FM_MODPRST_HFI1_CPU0_LVT2_N")
	)
	(segment
		(start 420.298372 -132.568442)
		(end 424.258486 -128.608328)
		(width 0.089408)
		(layer "In11.Cu")
		(net "FM_MODPRST_HFI1_CPU0_LVT2_N")
	)
	(segment
		(start 389.124698 -137.02284)
		(end 399.921476 -137.02284)
		(width 0.089408)
		(layer "In11.Cu")
		(net "FM_MODPRST_HFI1_CPU0_LVT2_N")
	)
	(segment
		(start 366.460786 -123.811538)
		(end 366.465358 -123.811538)
		(width 0.089408)
		(layer "In11.Cu")
		(net "FM_MODPRST_HFI1_CPU0_LVT2_N")
	)
	(segment
		(start 409.796234 -135.564372)
		(end 412.269178 -135.564372)
		(width 0.089408)
		(layer "In11.Cu")
		(net "FM_MODPRST_HFI1_CPU0_LVT2_N")
	)
	(segment
		(start 407.062432 -136.744202)
		(end 409.796234 -135.564372)
		(width 0.089408)
		(layer "In11.Cu")
		(net "FM_MODPRST_HFI1_CPU0_LVT2_N")
	)
	(segment
		(start 425.503848 -128.608328)
		(end 426.451776 -127.6604)
		(width 0.089408)
		(layer "In11.Cu")
		(net "FM_MODPRST_HFI1_CPU0_LVT2_N")
	)
	(segment
		(start 291.997638 -78.540864)
		(end 292.076378 -78.519528)
		(width 0.089408)
		(layer "In11.Cu")
		(net "FM_MODPRST_HFI1_CPU0_LVT2_N")
	)
	(segment
		(start 334.996282 -121.684796)
		(end 335.056734 -121.745248)
		(width 0.089408)
		(layer "In11.Cu")
		(net "FM_MODPRST_HFI1_CPU0_LVT2_N")
	)
	(segment
		(start 368.62004 -126.63424)
		(end 369.424458 -126.63424)
		(width 0.089408)
		(layer "In11.Cu")
		(net "FM_MODPRST_HFI1_CPU0_LVT2_N")
	)
	(segment
		(start 366.750346 -121.507758)
		(end 366.750346 -122.795284)
		(width 0.089408)
		(layer "In11.Cu")
		(net "FM_MODPRST_HFI1_CPU0_LVT2_N")
	)
	(segment
		(start 420.298372 -133.40207)
		(end 420.298372 -132.568442)
		(width 0.089408)
		(layer "In11.Cu")
		(net "FM_MODPRST_HFI1_CPU0_LVT2_N")
	)
	(segment
		(start 292.076378 -78.519528)
		(end 292.36924 -78.688438)
		(width 0.089408)
		(layer "In11.Cu")
		(net "FM_MODPRST_HFI1_CPU0_LVT2_N")
	)
	(segment
		(start 366.729518 -124.075698)
		(end 366.729518 -124.08027)
		(width 0.089408)
		(layer "In11.Cu")
		(net "FM_MODPRST_HFI1_CPU0_LVT2_N")
	)
	(segment
		(start 404.873968 -136.744202)
		(end 407.062432 -136.744202)
		(width 0.089408)
		(layer "In11.Cu")
		(net "FM_MODPRST_HFI1_CPU0_LVT2_N")
	)
	(segment
		(start 416.922966 -135.777478)
		(end 417.922964 -135.777478)
		(width 0.089408)
		(layer "In11.Cu")
		(net "FM_MODPRST_HFI1_CPU0_LVT2_N")
	)
	(segment
		(start 366.750346 -124.764546)
		(end 368.62004 -126.63424)
		(width 0.089408)
		(layer "In11.Cu")
		(net "FM_MODPRST_HFI1_CPU0_LVT2_N")
	)
	(segment
		(start 297.008042 -80.373982)
		(end 297.002708 -80.38338)
		(width 0.089408)
		(layer "In11.Cu")
		(net "FM_MODPRST_HFI1_CPU0_LVT2_N")
	)
	(arc
		(start 302.159162 -80.373982)
		(mid 301.812706 -80.5742)
		(end 301.46625 -80.373982)
		(width 0.089408)
		(layer "In11.Cu")
		(net "FM_MODPRST_HFI1_CPU0_LVT2_N")
	)
	(arc
		(start 295.456864 -79.878682)
		(mid 294.9448 -79.58305)
		(end 294.432736 -79.878682)
		(width 0.089408)
		(layer "In11.Cu")
		(net "FM_MODPRST_HFI1_CPU0_LVT2_N")
	)
	(arc
		(start 293.220648 -79.583534)
		(mid 293.024616 -79.52815)
		(end 292.881304 -79.383382)
		(width 0.089408)
		(layer "In11.Cu")
		(net "FM_MODPRST_HFI1_CPU0_LVT2_N")
	)
	(arc
		(start 301.46625 -80.373982)
		(mid 300.954186 -80.078223)
		(end 300.442122 -80.373982)
		(width 0.089408)
		(layer "In11.Cu")
		(net "FM_MODPRST_HFI1_CPU0_LVT2_N")
	)
	(arc
		(start 298.725082 -80.373982)
		(mid 298.378626 -80.5742)
		(end 298.03217 -80.373982)
		(width 0.089408)
		(layer "In11.Cu")
		(net "FM_MODPRST_HFI1_CPU0_LVT2_N")
	)
	(arc
		(start 296.315384 -80.373982)
		(mid 296.107855 -80.162698)
		(end 295.823894 -80.07858)
		(width 0.089408)
		(layer "In11.Cu")
		(net "FM_MODPRST_HFI1_CPU0_LVT2_N")
	)
	(arc
		(start 302.650652 -80.07858)
		(mid 302.366691 -80.162698)
		(end 302.159162 -80.373982)
		(width 0.089408)
		(layer "In11.Cu")
		(net "FM_MODPRST_HFI1_CPU0_LVT2_N")
	)
	(arc
		(start 297.002708 -80.38338)
		(mid 296.656373 -80.574163)
		(end 296.315384 -80.373982)
		(width 0.089408)
		(layer "In11.Cu")
		(net "FM_MODPRST_HFI1_CPU0_LVT2_N")
	)
	(arc
		(start 295.791128 -80.07858)
		(mid 295.598025 -80.022061)
		(end 295.456864 -79.878682)
		(width 0.089408)
		(layer "In11.Cu")
		(net "FM_MODPRST_HFI1_CPU0_LVT2_N")
	)
	(arc
		(start 304.398426 -80.083152)
		(mid 304.239793 -80.051598)
		(end 304.10531 -79.96174)
		(width 0.089408)
		(layer "In11.Cu")
		(net "FM_MODPRST_HFI1_CPU0_LVT2_N")
	)
	(arc
		(start 294.432736 -79.878682)
		(mid 294.08628 -80.078773)
		(end 293.739824 -79.878682)
		(width 0.089408)
		(layer "In11.Cu")
		(net "FM_MODPRST_HFI1_CPU0_LVT2_N")
	)
	(arc
		(start 300.442122 -80.373982)
		(mid 300.095666 -80.5742)
		(end 299.74921 -80.373982)
		(width 0.089408)
		(layer "In11.Cu")
		(net "FM_MODPRST_HFI1_CPU0_LVT2_N")
	)
	(arc
		(start 298.03217 -80.373982)
		(mid 297.520106 -80.078223)
		(end 297.008042 -80.373982)
		(width 0.089408)
		(layer "In11.Cu")
		(net "FM_MODPRST_HFI1_CPU0_LVT2_N")
	)
	(arc
		(start 292.881304 -79.383382)
		(mid 292.673817 -79.172016)
		(end 292.389814 -79.08798)
		(width 0.089408)
		(layer "In11.Cu")
		(net "FM_MODPRST_HFI1_CPU0_LVT2_N")
	)
	(arc
		(start 299.74921 -80.373982)
		(mid 299.237146 -80.078223)
		(end 298.725082 -80.373982)
		(width 0.089408)
		(layer "In11.Cu")
		(net "FM_MODPRST_HFI1_CPU0_LVT2_N")
	)
	(arc
		(start 292.389814 -79.08798)
		(mid 292.044121 -78.921579)
		(end 291.997638 -78.540864)
		(width 0.089408)
		(layer "In11.Cu")
		(net "FM_MODPRST_HFI1_CPU0_LVT2_N")
	)
	(arc
		(start 304.04181 -79.878682)
		(mid 303.529746 -79.58305)
		(end 303.017682 -79.878682)
		(width 0.089408)
		(layer "In11.Cu")
		(net "FM_MODPRST_HFI1_CPU0_LVT2_N")
	)
	(arc
		(start 304.10531 -79.96174)
		(mid 304.070824 -79.922302)
		(end 304.04181 -79.878682)
		(width 0.089408)
		(layer "In11.Cu")
		(net "FM_MODPRST_HFI1_CPU0_LVT2_N")
	)
	(arc
		(start 293.739824 -79.878682)
		(mid 293.533787 -79.668404)
		(end 293.25189 -79.583534)
		(width 0.089408)
		(layer "In11.Cu")
		(net "FM_MODPRST_HFI1_CPU0_LVT2_N")
	)
	(arc
		(start 303.017682 -79.878682)
		(mid 302.876525 -80.022067)
		(end 302.683418 -80.07858)
		(width 0.089408)
		(layer "In11.Cu")
		(net "FM_MODPRST_HFI1_CPU0_LVT2_N")
	)
	(segment
		(start 413.781748 -131.740402)
		(end 413.361378 -132.160772)
		(width 0.10795)
		(layer "F.Cu")
		(net "FM_MODPRST_HFI0_CPU0_LVT2_N")
	)
	(segment
		(start 290.93922 -78.193138)
		(end 291.51072 -78.193138)
		(width 0.1016)
		(layer "F.Cu")
		(net "FM_MODPRST_HFI0_CPU0_LVT2_N")
	)
	(segment
		(start 412.954978 -132.567172)
		(end 412.333694 -132.567172)
		(width 0.10795)
		(layer "F.Cu")
		(net "FM_MODPRST_HFI0_CPU0_LVT2_N")
	)
	(segment
		(start 415.191194 -131.740402)
		(end 413.781748 -131.740402)
		(width 0.10795)
		(layer "F.Cu")
		(net "FM_MODPRST_HFI0_CPU0_LVT2_N")
	)
	(segment
		(start 413.361378 -132.160772)
		(end 412.954978 -132.567172)
		(width 0.10795)
		(layer "F.Cu")
		(net "FM_MODPRST_HFI0_CPU0_LVT2_N")
	)
	(via
		(at 334.4164 -77.597)
		(size 0.508)
		(drill 0.254)
		(layers "F.Cu" "B.Cu")
		(net "FM_MODPRST_HFI0_CPU0_LVT2_N")
	)
	(via
		(at 413.361378 -132.160772)
		(size 0.508)
		(drill 0.254)
		(layers "F.Cu" "B.Cu")
		(net "FM_MODPRST_HFI0_CPU0_LVT2_N")
	)
	(via
		(at 335.577688 -117.976396)
		(size 0.508)
		(drill 0.254)
		(layers "F.Cu" "B.Cu")
		(net "FM_MODPRST_HFI0_CPU0_LVT2_N")
	)
	(via
		(at 291.51072 -78.193138)
		(size 0.508)
		(drill 0.254)
		(layers "F.Cu" "B.Cu")
		(net "FM_MODPRST_HFI0_CPU0_LVT2_N")
	)
	(segment
		(start 333.749904 -105.581958)
		(end 333.503016 -105.828846)
		(width 0.089408)
		(layer "In9.Cu")
		(net "FM_MODPRST_HFI0_CPU0_LVT2_N")
	)
	(segment
		(start 333.503016 -105.828846)
		(end 333.503016 -107.443016)
		(width 0.089408)
		(layer "In9.Cu")
		(net "FM_MODPRST_HFI0_CPU0_LVT2_N")
	)
	(segment
		(start 332.621636 -88.441022)
		(end 333.46136 -89.280746)
		(width 0.089408)
		(layer "In9.Cu")
		(net "FM_MODPRST_HFI0_CPU0_LVT2_N")
	)
	(segment
		(start 335.8896 -111.4806)
		(end 335.8896 -116.79428)
		(width 0.089408)
		(layer "In9.Cu")
		(net "FM_MODPRST_HFI0_CPU0_LVT2_N")
	)
	(segment
		(start 335.577688 -117.106192)
		(end 335.577688 -117.976396)
		(width 0.089408)
		(layer "In9.Cu")
		(net "FM_MODPRST_HFI0_CPU0_LVT2_N")
	)
	(segment
		(start 333.749904 -92.515944)
		(end 333.749904 -105.581958)
		(width 0.089408)
		(layer "In9.Cu")
		(net "FM_MODPRST_HFI0_CPU0_LVT2_N")
	)
	(segment
		(start 332.621636 -78.649576)
		(end 332.621636 -88.441022)
		(width 0.089408)
		(layer "In9.Cu")
		(net "FM_MODPRST_HFI0_CPU0_LVT2_N")
	)
	(segment
		(start 333.674212 -77.597)
		(end 332.621636 -78.649576)
		(width 0.089408)
		(layer "In9.Cu")
		(net "FM_MODPRST_HFI0_CPU0_LVT2_N")
	)
	(segment
		(start 334.772 -108.712)
		(end 334.772 -110.363)
		(width 0.089408)
		(layer "In9.Cu")
		(net "FM_MODPRST_HFI0_CPU0_LVT2_N")
	)
	(segment
		(start 334.4164 -77.597)
		(end 333.674212 -77.597)
		(width 0.089408)
		(layer "In9.Cu")
		(net "FM_MODPRST_HFI0_CPU0_LVT2_N")
	)
	(segment
		(start 334.772 -110.363)
		(end 335.8896 -111.4806)
		(width 0.089408)
		(layer "In9.Cu")
		(net "FM_MODPRST_HFI0_CPU0_LVT2_N")
	)
	(segment
		(start 333.503016 -107.443016)
		(end 334.772 -108.712)
		(width 0.089408)
		(layer "In9.Cu")
		(net "FM_MODPRST_HFI0_CPU0_LVT2_N")
	)
	(segment
		(start 335.8896 -116.79428)
		(end 335.577688 -117.106192)
		(width 0.089408)
		(layer "In9.Cu")
		(net "FM_MODPRST_HFI0_CPU0_LVT2_N")
	)
	(segment
		(start 333.46136 -92.2274)
		(end 333.749904 -92.515944)
		(width 0.089408)
		(layer "In9.Cu")
		(net "FM_MODPRST_HFI0_CPU0_LVT2_N")
	)
	(segment
		(start 333.46136 -89.280746)
		(end 333.46136 -92.2274)
		(width 0.089408)
		(layer "In9.Cu")
		(net "FM_MODPRST_HFI0_CPU0_LVT2_N")
	)
	(segment
		(start 309.49519 -80.276446)
		(end 310.587898 -79.183738)
		(width 0.089408)
		(layer "In11.Cu")
		(net "FM_MODPRST_HFI0_CPU0_LVT2_N")
	)
	(segment
		(start 412.961074 -132.160772)
		(end 413.361378 -132.160772)
		(width 0.089408)
		(layer "In11.Cu")
		(net "FM_MODPRST_HFI0_CPU0_LVT2_N")
	)
	(segment
		(start 335.876646 -116.855494)
		(end 338.34197 -116.855494)
		(width 0.089408)
		(layer "In11.Cu")
		(net "FM_MODPRST_HFI0_CPU0_LVT2_N")
	)
	(segment
		(start 398.897602 -134.765288)
		(end 399.640044 -134.022846)
		(width 0.089408)
		(layer "In11.Cu")
		(net "FM_MODPRST_HFI0_CPU0_LVT2_N")
	)
	(segment
		(start 335.577688 -117.154452)
		(end 335.876646 -116.855494)
		(width 0.089408)
		(layer "In11.Cu")
		(net "FM_MODPRST_HFI0_CPU0_LVT2_N")
	)
	(segment
		(start 374.389904 -126.963678)
		(end 374.752108 -127.325882)
		(width 0.089408)
		(layer "In11.Cu")
		(net "FM_MODPRST_HFI0_CPU0_LVT2_N")
	)
	(segment
		(start 302.664114 -80.269588)
		(end 302.695356 -80.269588)
		(width 0.089408)
		(layer "In11.Cu")
		(net "FM_MODPRST_HFI0_CPU0_LVT2_N")
	)
	(segment
		(start 371.023134 -121.457466)
		(end 372.189502 -122.623834)
		(width 0.089408)
		(layer "In11.Cu")
		(net "FM_MODPRST_HFI0_CPU0_LVT2_N")
	)
	(segment
		(start 384.542792 -127.616204)
		(end 384.542792 -128.36398)
		(width 0.089408)
		(layer "In11.Cu")
		(net "FM_MODPRST_HFI0_CPU0_LVT2_N")
	)
	(segment
		(start 378.77877 -127.155194)
		(end 384.081782 -127.155194)
		(width 0.089408)
		(layer "In11.Cu")
		(net "FM_MODPRST_HFI0_CPU0_LVT2_N")
	)
	(segment
		(start 310.587898 -79.183738)
		(end 331.695044 -79.183738)
		(width 0.089408)
		(layer "In11.Cu")
		(net "FM_MODPRST_HFI0_CPU0_LVT2_N")
	)
	(segment
		(start 385.01828 -129.406396)
		(end 390.377172 -134.765288)
		(width 0.089408)
		(layer "In11.Cu")
		(net "FM_MODPRST_HFI0_CPU0_LVT2_N")
	)
	(segment
		(start 404.624032 -130.523488)
		(end 408.77744 -130.523488)
		(width 0.089408)
		(layer "In11.Cu")
		(net "FM_MODPRST_HFI0_CPU0_LVT2_N")
	)
	(segment
		(start 333.281782 -77.597)
		(end 334.4164 -77.597)
		(width 0.089408)
		(layer "In11.Cu")
		(net "FM_MODPRST_HFI0_CPU0_LVT2_N")
	)
	(segment
		(start 410.480256 -132.226304)
		(end 412.895542 -132.226304)
		(width 0.089408)
		(layer "In11.Cu")
		(net "FM_MODPRST_HFI0_CPU0_LVT2_N")
	)
	(segment
		(start 390.377172 -134.765288)
		(end 398.897602 -134.765288)
		(width 0.089408)
		(layer "In11.Cu")
		(net "FM_MODPRST_HFI0_CPU0_LVT2_N")
	)
	(segment
		(start 291.803582 -78.362048)
		(end 291.827458 -78.451456)
		(width 0.089408)
		(layer "In11.Cu")
		(net "FM_MODPRST_HFI0_CPU0_LVT2_N")
	)
	(segment
		(start 374.752108 -127.325882)
		(end 378.608082 -127.325882)
		(width 0.089408)
		(layer "In11.Cu")
		(net "FM_MODPRST_HFI0_CPU0_LVT2_N")
	)
	(segment
		(start 384.542792 -128.36398)
		(end 385.01828 -128.839468)
		(width 0.089408)
		(layer "In11.Cu")
		(net "FM_MODPRST_HFI0_CPU0_LVT2_N")
	)
	(segment
		(start 338.34197 -116.855494)
		(end 340.042754 -118.556278)
		(width 0.089408)
		(layer "In11.Cu")
		(net "FM_MODPRST_HFI0_CPU0_LVT2_N")
	)
	(segment
		(start 401.12315 -134.022846)
		(end 404.624032 -130.523488)
		(width 0.089408)
		(layer "In11.Cu")
		(net "FM_MODPRST_HFI0_CPU0_LVT2_N")
	)
	(segment
		(start 412.895542 -132.226304)
		(end 412.961074 -132.160772)
		(width 0.089408)
		(layer "In11.Cu")
		(net "FM_MODPRST_HFI0_CPU0_LVT2_N")
	)
	(segment
		(start 399.640044 -134.022846)
		(end 401.12315 -134.022846)
		(width 0.089408)
		(layer "In11.Cu")
		(net "FM_MODPRST_HFI0_CPU0_LVT2_N")
	)
	(segment
		(start 304.404014 -80.276446)
		(end 309.49519 -80.276446)
		(width 0.089408)
		(layer "In11.Cu")
		(net "FM_MODPRST_HFI0_CPU0_LVT2_N")
	)
	(segment
		(start 331.695044 -79.183738)
		(end 333.281782 -77.597)
		(width 0.089408)
		(layer "In11.Cu")
		(net "FM_MODPRST_HFI0_CPU0_LVT2_N")
	)
	(segment
		(start 373.32666 -126.963678)
		(end 374.389904 -126.963678)
		(width 0.089408)
		(layer "In11.Cu")
		(net "FM_MODPRST_HFI0_CPU0_LVT2_N")
	)
	(segment
		(start 293.207186 -79.774542)
		(end 293.239952 -79.774542)
		(width 0.089408)
		(layer "In11.Cu")
		(net "FM_MODPRST_HFI0_CPU0_LVT2_N")
	)
	(segment
		(start 408.77744 -130.523488)
		(end 410.480256 -132.226304)
		(width 0.089408)
		(layer "In11.Cu")
		(net "FM_MODPRST_HFI0_CPU0_LVT2_N")
	)
	(segment
		(start 292.348666 -79.279242)
		(end 292.368732 -79.280004)
		(width 0.089408)
		(layer "In11.Cu")
		(net "FM_MODPRST_HFI0_CPU0_LVT2_N")
	)
	(segment
		(start 378.608082 -127.325882)
		(end 378.77877 -127.155194)
		(width 0.089408)
		(layer "In11.Cu")
		(net "FM_MODPRST_HFI0_CPU0_LVT2_N")
	)
	(segment
		(start 340.042754 -118.556278)
		(end 345.546172 -118.556278)
		(width 0.089408)
		(layer "In11.Cu")
		(net "FM_MODPRST_HFI0_CPU0_LVT2_N")
	)
	(segment
		(start 385.01828 -128.839468)
		(end 385.01828 -129.406396)
		(width 0.089408)
		(layer "In11.Cu")
		(net "FM_MODPRST_HFI0_CPU0_LVT2_N")
	)
	(segment
		(start 367.488978 -118.69674)
		(end 370.249704 -121.457466)
		(width 0.089408)
		(layer "In11.Cu")
		(net "FM_MODPRST_HFI0_CPU0_LVT2_N")
	)
	(segment
		(start 295.77919 -80.269588)
		(end 295.810432 -80.269588)
		(width 0.089408)
		(layer "In11.Cu")
		(net "FM_MODPRST_HFI0_CPU0_LVT2_N")
	)
	(segment
		(start 335.577688 -117.976396)
		(end 335.577688 -117.154452)
		(width 0.089408)
		(layer "In11.Cu")
		(net "FM_MODPRST_HFI0_CPU0_LVT2_N")
	)
	(segment
		(start 372.189502 -122.623834)
		(end 372.189502 -125.82652)
		(width 0.089408)
		(layer "In11.Cu")
		(net "FM_MODPRST_HFI0_CPU0_LVT2_N")
	)
	(segment
		(start 345.686634 -118.69674)
		(end 367.488978 -118.69674)
		(width 0.089408)
		(layer "In11.Cu")
		(net "FM_MODPRST_HFI0_CPU0_LVT2_N")
	)
	(segment
		(start 291.51072 -78.193138)
		(end 291.803582 -78.362048)
		(width 0.089408)
		(layer "In11.Cu")
		(net "FM_MODPRST_HFI0_CPU0_LVT2_N")
	)
	(segment
		(start 372.189502 -125.82652)
		(end 373.32666 -126.963678)
		(width 0.089408)
		(layer "In11.Cu")
		(net "FM_MODPRST_HFI0_CPU0_LVT2_N")
	)
	(segment
		(start 384.081782 -127.155194)
		(end 384.542792 -127.616204)
		(width 0.089408)
		(layer "In11.Cu")
		(net "FM_MODPRST_HFI0_CPU0_LVT2_N")
	)
	(segment
		(start 370.249704 -121.457466)
		(end 371.023134 -121.457466)
		(width 0.089408)
		(layer "In11.Cu")
		(net "FM_MODPRST_HFI0_CPU0_LVT2_N")
	)
	(segment
		(start 345.546172 -118.556278)
		(end 345.686634 -118.69674)
		(width 0.089408)
		(layer "In11.Cu")
		(net "FM_MODPRST_HFI0_CPU0_LVT2_N")
	)
	(arc
		(start 295.291256 -79.97444)
		(mid 295.497293 -80.184718)
		(end 295.77919 -80.269588)
		(width 0.089408)
		(layer "In11.Cu")
		(net "FM_MODPRST_HFI0_CPU0_LVT2_N")
	)
	(arc
		(start 300.60773 -80.46974)
		(mid 300.954186 -80.269522)
		(end 301.300642 -80.46974)
		(width 0.089408)
		(layer "In11.Cu")
		(net "FM_MODPRST_HFI0_CPU0_LVT2_N")
	)
	(arc
		(start 301.300642 -80.46974)
		(mid 301.812706 -80.765499)
		(end 302.32477 -80.46974)
		(width 0.089408)
		(layer "In11.Cu")
		(net "FM_MODPRST_HFI0_CPU0_LVT2_N")
	)
	(arc
		(start 303.18329 -79.97444)
		(mid 303.529746 -79.774349)
		(end 303.876202 -79.97444)
		(width 0.089408)
		(layer "In11.Cu")
		(net "FM_MODPRST_HFI0_CPU0_LVT2_N")
	)
	(arc
		(start 292.368732 -79.280004)
		(mid 292.569084 -79.332778)
		(end 292.715696 -79.47914)
		(width 0.089408)
		(layer "In11.Cu")
		(net "FM_MODPRST_HFI0_CPU0_LVT2_N")
	)
	(arc
		(start 296.149776 -80.46974)
		(mid 296.667243 -80.765475)
		(end 297.179238 -80.460342)
		(width 0.089408)
		(layer "In11.Cu")
		(net "FM_MODPRST_HFI0_CPU0_LVT2_N")
	)
	(arc
		(start 294.598344 -79.97444)
		(mid 294.9448 -79.774349)
		(end 295.291256 -79.97444)
		(width 0.089408)
		(layer "In11.Cu")
		(net "FM_MODPRST_HFI0_CPU0_LVT2_N")
	)
	(arc
		(start 291.827458 -78.451456)
		(mid 291.868795 -79.003466)
		(end 292.348666 -79.279242)
		(width 0.089408)
		(layer "In11.Cu")
		(net "FM_MODPRST_HFI0_CPU0_LVT2_N")
	)
	(arc
		(start 292.715696 -79.47914)
		(mid 292.923225 -79.690424)
		(end 293.207186 -79.774542)
		(width 0.089408)
		(layer "In11.Cu")
		(net "FM_MODPRST_HFI0_CPU0_LVT2_N")
	)
	(arc
		(start 295.810432 -80.269588)
		(mid 296.006464 -80.324972)
		(end 296.149776 -80.46974)
		(width 0.089408)
		(layer "In11.Cu")
		(net "FM_MODPRST_HFI0_CPU0_LVT2_N")
	)
	(arc
		(start 298.89069 -80.46974)
		(mid 299.237146 -80.269522)
		(end 299.583602 -80.46974)
		(width 0.089408)
		(layer "In11.Cu")
		(net "FM_MODPRST_HFI0_CPU0_LVT2_N")
	)
	(arc
		(start 302.32477 -80.46974)
		(mid 302.468081 -80.324969)
		(end 302.664114 -80.269588)
		(width 0.089408)
		(layer "In11.Cu")
		(net "FM_MODPRST_HFI0_CPU0_LVT2_N")
	)
	(arc
		(start 293.574216 -79.97444)
		(mid 294.08628 -80.270072)
		(end 294.598344 -79.97444)
		(width 0.089408)
		(layer "In11.Cu")
		(net "FM_MODPRST_HFI0_CPU0_LVT2_N")
	)
	(arc
		(start 302.695356 -80.269588)
		(mid 302.977258 -80.184725)
		(end 303.18329 -79.97444)
		(width 0.089408)
		(layer "In11.Cu")
		(net "FM_MODPRST_HFI0_CPU0_LVT2_N")
	)
	(arc
		(start 297.866562 -80.46974)
		(mid 298.378626 -80.765499)
		(end 298.89069 -80.46974)
		(width 0.089408)
		(layer "In11.Cu")
		(net "FM_MODPRST_HFI0_CPU0_LVT2_N")
	)
	(arc
		(start 299.583602 -80.46974)
		(mid 300.095666 -80.765499)
		(end 300.60773 -80.46974)
		(width 0.089408)
		(layer "In11.Cu")
		(net "FM_MODPRST_HFI0_CPU0_LVT2_N")
	)
	(arc
		(start 297.179238 -80.460342)
		(mid 297.525573 -80.269559)
		(end 297.866562 -80.46974)
		(width 0.089408)
		(layer "In11.Cu")
		(net "FM_MODPRST_HFI0_CPU0_LVT2_N")
	)
	(arc
		(start 303.970182 -80.096868)
		(mid 304.169226 -80.229865)
		(end 304.404014 -80.276446)
		(width 0.089408)
		(layer "In11.Cu")
		(net "FM_MODPRST_HFI0_CPU0_LVT2_N")
	)
	(arc
		(start 303.876202 -79.97444)
		(mid 303.919169 -80.038743)
		(end 303.970182 -80.096868)
		(width 0.089408)
		(layer "In11.Cu")
		(net "FM_MODPRST_HFI0_CPU0_LVT2_N")
	)
	(arc
		(start 293.239952 -79.774542)
		(mid 293.433055 -79.831061)
		(end 293.574216 -79.97444)
		(width 0.089408)
		(layer "In11.Cu")
		(net "FM_MODPRST_HFI0_CPU0_LVT2_N")
	)
	(segment
		(start 371.145308 -69.495162)
		(end 371.545104 -69.894958)
		(width 0.1016)
		(layer "F.Cu")
		(net "FM_JTAG_PLD_EN_DEBUG")
	)
	(via
		(at 414.2105 -102.8192)
		(size 0.508)
		(drill 0.254)
		(layers "F.Cu" "B.Cu")
		(net "FM_JTAG_PLD_EN_DEBUG")
	)
	(via
		(at 415.869374 -64.597788)
		(size 0.508)
		(drill 0.254)
		(layers "F.Cu" "B.Cu")
		(net "FM_JTAG_PLD_EN_DEBUG")
	)
	(via
		(at 371.5893 -68.049902)
		(size 0.6604)
		(drill 0.3302)
		(layers "F.Cu" "B.Cu")
		(net "FM_JTAG_PLD_EN_DEBUG")
	)
	(via
		(at 371.145308 -69.495162)
		(size 0.4572)
		(drill 0.2032)
		(layers "F.Cu" "B.Cu")
		(net "FM_JTAG_PLD_EN_DEBUG")
	)
	(segment
		(start 371.145308 -69.495162)
		(end 371.5893 -69.05117)
		(width 0.10795)
		(layer "B.Cu")
		(net "FM_JTAG_PLD_EN_DEBUG")
	)
	(segment
		(start 414.546542 -102.8192)
		(end 416.474402 -104.74706)
		(width 0.10795)
		(layer "B.Cu")
		(net "FM_JTAG_PLD_EN_DEBUG")
	)
	(segment
		(start 414.905444 -108.666534)
		(end 414.905444 -108.67517)
		(width 0.10795)
		(layer "B.Cu")
		(net "FM_JTAG_PLD_EN_DEBUG")
	)
	(segment
		(start 370.29009 -66.300604)
		(end 371.05209 -66.300604)
		(width 0.10795)
		(layer "B.Cu")
		(net "FM_JTAG_PLD_EN_DEBUG")
	)
	(segment
		(start 416.763708 -119.285258)
		(end 416.763708 -121.1326)
		(width 0.10795)
		(layer "B.Cu")
		(net "FM_JTAG_PLD_EN_DEBUG")
	)
	(segment
		(start 437.642 -132.461)
		(end 437.642 -141.097)
		(width 0.10795)
		(layer "B.Cu")
		(net "FM_JTAG_PLD_EN_DEBUG")
	)
	(segment
		(start 415.8234 -128.0668)
		(end 415.8234 -130.8608)
		(width 0.10795)
		(layer "B.Cu")
		(net "FM_JTAG_PLD_EN_DEBUG")
	)
	(segment
		(start 416.474402 -107.097576)
		(end 414.905444 -108.666534)
		(width 0.10795)
		(layer "B.Cu")
		(net "FM_JTAG_PLD_EN_DEBUG")
	)
	(segment
		(start 416.6235 -122.8471)
		(end 417.713922 -123.937522)
		(width 0.10795)
		(layer "B.Cu")
		(net "FM_JTAG_PLD_EN_DEBUG")
	)
	(segment
		(start 416.6235 -121.272808)
		(end 416.6235 -122.8471)
		(width 0.10795)
		(layer "B.Cu")
		(net "FM_JTAG_PLD_EN_DEBUG")
	)
	(segment
		(start 414.899602 -117.421152)
		(end 416.763708 -119.285258)
		(width 0.10795)
		(layer "B.Cu")
		(net "FM_JTAG_PLD_EN_DEBUG")
	)
	(segment
		(start 417.713922 -126.176278)
		(end 415.8234 -128.0668)
		(width 0.10795)
		(layer "B.Cu")
		(net "FM_JTAG_PLD_EN_DEBUG")
	)
	(segment
		(start 416.474402 -104.74706)
		(end 416.474402 -107.097576)
		(width 0.10795)
		(layer "B.Cu")
		(net "FM_JTAG_PLD_EN_DEBUG")
	)
	(segment
		(start 436.753 -131.572)
		(end 437.642 -132.461)
		(width 0.10795)
		(layer "B.Cu")
		(net "FM_JTAG_PLD_EN_DEBUG")
	)
	(segment
		(start 414.899602 -108.681012)
		(end 414.899602 -117.421152)
		(width 0.10795)
		(layer "B.Cu")
		(net "FM_JTAG_PLD_EN_DEBUG")
	)
	(segment
		(start 414.2105 -102.8192)
		(end 414.546542 -102.8192)
		(width 0.10795)
		(layer "B.Cu")
		(net "FM_JTAG_PLD_EN_DEBUG")
	)
	(segment
		(start 414.905444 -108.67517)
		(end 414.899602 -108.681012)
		(width 0.10795)
		(layer "B.Cu")
		(net "FM_JTAG_PLD_EN_DEBUG")
	)
	(segment
		(start 415.8234 -130.8608)
		(end 416.5346 -131.572)
		(width 0.10795)
		(layer "B.Cu")
		(net "FM_JTAG_PLD_EN_DEBUG")
	)
	(segment
		(start 417.713922 -123.937522)
		(end 417.713922 -126.176278)
		(width 0.10795)
		(layer "B.Cu")
		(net "FM_JTAG_PLD_EN_DEBUG")
	)
	(segment
		(start 371.5893 -68.049902)
		(end 371.5893 -67.074542)
		(width 0.10795)
		(layer "B.Cu")
		(net "FM_JTAG_PLD_EN_DEBUG")
	)
	(segment
		(start 371.5893 -67.074542)
		(end 371.05209 -66.537332)
		(width 0.10795)
		(layer "B.Cu")
		(net "FM_JTAG_PLD_EN_DEBUG")
	)
	(segment
		(start 416.5346 -131.572)
		(end 436.753 -131.572)
		(width 0.10795)
		(layer "B.Cu")
		(net "FM_JTAG_PLD_EN_DEBUG")
	)
	(segment
		(start 371.05209 -66.537332)
		(end 371.05209 -66.300604)
		(width 0.10795)
		(layer "B.Cu")
		(net "FM_JTAG_PLD_EN_DEBUG")
	)
	(segment
		(start 371.5893 -69.05117)
		(end 371.5893 -68.049902)
		(width 0.10795)
		(layer "B.Cu")
		(net "FM_JTAG_PLD_EN_DEBUG")
	)
	(segment
		(start 416.763708 -121.1326)
		(end 416.6235 -121.272808)
		(width 0.10795)
		(layer "B.Cu")
		(net "FM_JTAG_PLD_EN_DEBUG")
	)
	(segment
		(start 412.641034 -86.189566)
		(end 415.0614 -83.7692)
		(width 0.089408)
		(layer "In2.Cu")
		(net "FM_JTAG_PLD_EN_DEBUG")
	)
	(segment
		(start 414.2105 -102.8192)
		(end 414.610804 -102.418896)
		(width 0.089408)
		(layer "In2.Cu")
		(net "FM_JTAG_PLD_EN_DEBUG")
	)
	(segment
		(start 414.8582 -71.400162)
		(end 414.8582 -70.984364)
		(width 0.089408)
		(layer "In2.Cu")
		(net "FM_JTAG_PLD_EN_DEBUG")
	)
	(segment
		(start 414.8582 -74.828654)
		(end 414.356804 -74.327258)
		(width 0.089408)
		(layer "In2.Cu")
		(net "FM_JTAG_PLD_EN_DEBUG")
	)
	(segment
		(start 414.610804 -102.418896)
		(end 414.610804 -99.39655)
		(width 0.089408)
		(layer "In2.Cu")
		(net "FM_JTAG_PLD_EN_DEBUG")
	)
	(segment
		(start 415.0614 -83.7692)
		(end 415.0614 -82.9818)
		(width 0.089408)
		(layer "In2.Cu")
		(net "FM_JTAG_PLD_EN_DEBUG")
	)
	(segment
		(start 414.610804 -99.39655)
		(end 412.641034 -97.42678)
		(width 0.089408)
		(layer "In2.Cu")
		(net "FM_JTAG_PLD_EN_DEBUG")
	)
	(segment
		(start 414.356804 -74.327258)
		(end 414.356804 -71.901558)
		(width 0.089408)
		(layer "In2.Cu")
		(net "FM_JTAG_PLD_EN_DEBUG")
	)
	(segment
		(start 415.46018 -68.521834)
		(end 415.46018 -65.006982)
		(width 0.089408)
		(layer "In2.Cu")
		(net "FM_JTAG_PLD_EN_DEBUG")
	)
	(segment
		(start 414.8582 -70.825868)
		(end 414.8582 -70.757034)
		(width 0.089408)
		(layer "In2.Cu")
		(net "FM_JTAG_PLD_EN_DEBUG")
	)
	(segment
		(start 414.857946 -70.98411)
		(end 414.857946 -70.826122)
		(width 0.089408)
		(layer "In2.Cu")
		(net "FM_JTAG_PLD_EN_DEBUG")
	)
	(segment
		(start 414.4772 -80.645)
		(end 414.8582 -80.264)
		(width 0.089408)
		(layer "In2.Cu")
		(net "FM_JTAG_PLD_EN_DEBUG")
	)
	(segment
		(start 414.857946 -70.826122)
		(end 414.8582 -70.825868)
		(width 0.089408)
		(layer "In2.Cu")
		(net "FM_JTAG_PLD_EN_DEBUG")
	)
	(segment
		(start 415.0614 -82.9818)
		(end 414.4772 -82.3976)
		(width 0.089408)
		(layer "In2.Cu")
		(net "FM_JTAG_PLD_EN_DEBUG")
	)
	(segment
		(start 414.8582 -70.757034)
		(end 415.0614 -70.553834)
		(width 0.089408)
		(layer "In2.Cu")
		(net "FM_JTAG_PLD_EN_DEBUG")
	)
	(segment
		(start 414.4772 -82.3976)
		(end 414.4772 -80.645)
		(width 0.089408)
		(layer "In2.Cu")
		(net "FM_JTAG_PLD_EN_DEBUG")
	)
	(segment
		(start 414.8582 -70.984364)
		(end 414.857946 -70.98411)
		(width 0.089408)
		(layer "In2.Cu")
		(net "FM_JTAG_PLD_EN_DEBUG")
	)
	(segment
		(start 415.46018 -65.006982)
		(end 415.869374 -64.597788)
		(width 0.089408)
		(layer "In2.Cu")
		(net "FM_JTAG_PLD_EN_DEBUG")
	)
	(segment
		(start 414.8582 -80.264)
		(end 414.8582 -74.828654)
		(width 0.089408)
		(layer "In2.Cu")
		(net "FM_JTAG_PLD_EN_DEBUG")
	)
	(segment
		(start 415.0614 -68.920614)
		(end 415.46018 -68.521834)
		(width 0.089408)
		(layer "In2.Cu")
		(net "FM_JTAG_PLD_EN_DEBUG")
	)
	(segment
		(start 414.356804 -71.901558)
		(end 414.8582 -71.400162)
		(width 0.089408)
		(layer "In2.Cu")
		(net "FM_JTAG_PLD_EN_DEBUG")
	)
	(segment
		(start 412.641034 -97.42678)
		(end 412.641034 -86.189566)
		(width 0.089408)
		(layer "In2.Cu")
		(net "FM_JTAG_PLD_EN_DEBUG")
	)
	(segment
		(start 415.0614 -70.553834)
		(end 415.0614 -68.920614)
		(width 0.089408)
		(layer "In2.Cu")
		(net "FM_JTAG_PLD_EN_DEBUG")
	)
	(segment
		(start 398.35201 -65.514728)
		(end 400.642328 -67.805046)
		(width 0.089408)
		(layer "In4.Cu")
		(net "FM_JTAG_PLD_EN_DEBUG")
	)
	(segment
		(start 396.75816 -65.14084)
		(end 397.253714 -65.14084)
		(width 0.089408)
		(layer "In4.Cu")
		(net "FM_JTAG_PLD_EN_DEBUG")
	)
	(segment
		(start 380.9238 -67.5386)
		(end 385.611624 -67.5386)
		(width 0.089408)
		(layer "In4.Cu")
		(net "FM_JTAG_PLD_EN_DEBUG")
	)
	(segment
		(start 401.370546 -68.251578)
		(end 401.3708 -68.251324)
		(width 0.089408)
		(layer "In4.Cu")
		(net "FM_JTAG_PLD_EN_DEBUG")
	)
	(segment
		(start 398.089628 -65.514982)
		(end 398.089882 -65.514728)
		(width 0.089408)
		(layer "In4.Cu")
		(net "FM_JTAG_PLD_EN_DEBUG")
	)
	(segment
		(start 400.642328 -67.805046)
		(end 400.679412 -67.805046)
		(width 0.089408)
		(layer "In4.Cu")
		(net "FM_JTAG_PLD_EN_DEBUG")
	)
	(segment
		(start 397.253714 -65.14084)
		(end 397.62557 -65.512696)
		(width 0.089408)
		(layer "In4.Cu")
		(net "FM_JTAG_PLD_EN_DEBUG")
	)
	(segment
		(start 407.306272 -68.546472)
		(end 407.878788 -68.546472)
		(width 0.089408)
		(layer "In4.Cu")
		(net "FM_JTAG_PLD_EN_DEBUG")
	)
	(segment
		(start 393.023598 -65.376552)
		(end 393.023852 -65.376806)
		(width 0.089408)
		(layer "In4.Cu")
		(net "FM_JTAG_PLD_EN_DEBUG")
	)
	(segment
		(start 408.403552 -68.021708)
		(end 411.530292 -68.021708)
		(width 0.089408)
		(layer "In4.Cu")
		(net "FM_JTAG_PLD_EN_DEBUG")
	)
	(segment
		(start 397.93164 -65.514982)
		(end 398.089628 -65.514982)
		(width 0.089408)
		(layer "In4.Cu")
		(net "FM_JTAG_PLD_EN_DEBUG")
	)
	(segment
		(start 414.007808 -68.0212)
		(end 414.008062 -68.020946)
		(width 0.089408)
		(layer "In4.Cu")
		(net "FM_JTAG_PLD_EN_DEBUG")
	)
	(segment
		(start 380.175008 -66.789808)
		(end 380.9238 -67.5386)
		(width 0.089408)
		(layer "In4.Cu")
		(net "FM_JTAG_PLD_EN_DEBUG")
	)
	(segment
		(start 371.423438 -69.495162)
		(end 372.596664 -68.321936)
		(width 0.089408)
		(layer "In4.Cu")
		(net "FM_JTAG_PLD_EN_DEBUG")
	)
	(segment
		(start 401.3708 -68.251324)
		(end 407.011124 -68.251324)
		(width 0.089408)
		(layer "In4.Cu")
		(net "FM_JTAG_PLD_EN_DEBUG")
	)
	(segment
		(start 398.089882 -65.514728)
		(end 398.35201 -65.514728)
		(width 0.089408)
		(layer "In4.Cu")
		(net "FM_JTAG_PLD_EN_DEBUG")
	)
	(segment
		(start 390.756648 -65.376552)
		(end 393.023598 -65.376552)
		(width 0.089408)
		(layer "In4.Cu")
		(net "FM_JTAG_PLD_EN_DEBUG")
	)
	(segment
		(start 396.522448 -65.376552)
		(end 396.75816 -65.14084)
		(width 0.089408)
		(layer "In4.Cu")
		(net "FM_JTAG_PLD_EN_DEBUG")
	)
	(segment
		(start 401.12569 -68.251324)
		(end 401.212304 -68.251324)
		(width 0.089408)
		(layer "In4.Cu")
		(net "FM_JTAG_PLD_EN_DEBUG")
	)
	(segment
		(start 373.663464 -68.321936)
		(end 375.180606 -66.804794)
		(width 0.089408)
		(layer "In4.Cu")
		(net "FM_JTAG_PLD_EN_DEBUG")
	)
	(segment
		(start 376.171206 -66.804794)
		(end 376.3518 -66.6242)
		(width 0.089408)
		(layer "In4.Cu")
		(net "FM_JTAG_PLD_EN_DEBUG")
	)
	(segment
		(start 385.611624 -67.5386)
		(end 385.611878 -67.538854)
		(width 0.089408)
		(layer "In4.Cu")
		(net "FM_JTAG_PLD_EN_DEBUG")
	)
	(segment
		(start 414.096454 -68.020946)
		(end 414.48228 -67.63512)
		(width 0.089408)
		(layer "In4.Cu")
		(net "FM_JTAG_PLD_EN_DEBUG")
	)
	(segment
		(start 414.008062 -68.020946)
		(end 414.096454 -68.020946)
		(width 0.089408)
		(layer "In4.Cu")
		(net "FM_JTAG_PLD_EN_DEBUG")
	)
	(segment
		(start 414.48228 -67.63512)
		(end 414.48228 -65.984882)
		(width 0.089408)
		(layer "In4.Cu")
		(net "FM_JTAG_PLD_EN_DEBUG")
	)
	(segment
		(start 393.023852 -65.376806)
		(end 393.18184 -65.376806)
		(width 0.089408)
		(layer "In4.Cu")
		(net "FM_JTAG_PLD_EN_DEBUG")
	)
	(segment
		(start 401.212304 -68.251324)
		(end 401.212558 -68.251578)
		(width 0.089408)
		(layer "In4.Cu")
		(net "FM_JTAG_PLD_EN_DEBUG")
	)
	(segment
		(start 411.5308 -68.0212)
		(end 414.007808 -68.0212)
		(width 0.089408)
		(layer "In4.Cu")
		(net "FM_JTAG_PLD_EN_DEBUG")
	)
	(segment
		(start 407.011124 -68.251324)
		(end 407.306272 -68.546472)
		(width 0.089408)
		(layer "In4.Cu")
		(net "FM_JTAG_PLD_EN_DEBUG")
	)
	(segment
		(start 397.62557 -65.512696)
		(end 397.929354 -65.512696)
		(width 0.089408)
		(layer "In4.Cu")
		(net "FM_JTAG_PLD_EN_DEBUG")
	)
	(segment
		(start 397.929354 -65.512696)
		(end 397.93164 -65.514982)
		(width 0.089408)
		(layer "In4.Cu")
		(net "FM_JTAG_PLD_EN_DEBUG")
	)
	(segment
		(start 385.77012 -67.5386)
		(end 388.5946 -67.5386)
		(width 0.089408)
		(layer "In4.Cu")
		(net "FM_JTAG_PLD_EN_DEBUG")
	)
	(segment
		(start 407.878788 -68.546472)
		(end 408.403552 -68.021708)
		(width 0.089408)
		(layer "In4.Cu")
		(net "FM_JTAG_PLD_EN_DEBUG")
	)
	(segment
		(start 401.212558 -68.251578)
		(end 401.370546 -68.251578)
		(width 0.089408)
		(layer "In4.Cu")
		(net "FM_JTAG_PLD_EN_DEBUG")
	)
	(segment
		(start 414.48228 -65.984882)
		(end 415.869374 -64.597788)
		(width 0.089408)
		(layer "In4.Cu")
		(net "FM_JTAG_PLD_EN_DEBUG")
	)
	(segment
		(start 388.5946 -67.5386)
		(end 390.756648 -65.376552)
		(width 0.089408)
		(layer "In4.Cu")
		(net "FM_JTAG_PLD_EN_DEBUG")
	)
	(segment
		(start 371.145308 -69.495162)
		(end 371.423438 -69.495162)
		(width 0.089408)
		(layer "In4.Cu")
		(net "FM_JTAG_PLD_EN_DEBUG")
	)
	(segment
		(start 411.530292 -68.021708)
		(end 411.5308 -68.0212)
		(width 0.089408)
		(layer "In4.Cu")
		(net "FM_JTAG_PLD_EN_DEBUG")
	)
	(segment
		(start 378.106432 -66.6242)
		(end 378.27204 -66.789808)
		(width 0.089408)
		(layer "In4.Cu")
		(net "FM_JTAG_PLD_EN_DEBUG")
	)
	(segment
		(start 394.608558 -65.376552)
		(end 396.522448 -65.376552)
		(width 0.089408)
		(layer "In4.Cu")
		(net "FM_JTAG_PLD_EN_DEBUG")
	)
	(segment
		(start 385.611878 -67.538854)
		(end 385.769866 -67.538854)
		(width 0.089408)
		(layer "In4.Cu")
		(net "FM_JTAG_PLD_EN_DEBUG")
	)
	(segment
		(start 372.596664 -68.321936)
		(end 373.663464 -68.321936)
		(width 0.089408)
		(layer "In4.Cu")
		(net "FM_JTAG_PLD_EN_DEBUG")
	)
	(segment
		(start 378.27204 -66.789808)
		(end 380.175008 -66.789808)
		(width 0.089408)
		(layer "In4.Cu")
		(net "FM_JTAG_PLD_EN_DEBUG")
	)
	(segment
		(start 400.679412 -67.805046)
		(end 401.12569 -68.251324)
		(width 0.089408)
		(layer "In4.Cu")
		(net "FM_JTAG_PLD_EN_DEBUG")
	)
	(segment
		(start 375.180606 -66.804794)
		(end 376.171206 -66.804794)
		(width 0.089408)
		(layer "In4.Cu")
		(net "FM_JTAG_PLD_EN_DEBUG")
	)
	(segment
		(start 385.769866 -67.538854)
		(end 385.77012 -67.5386)
		(width 0.089408)
		(layer "In4.Cu")
		(net "FM_JTAG_PLD_EN_DEBUG")
	)
	(segment
		(start 393.18184 -65.376806)
		(end 393.182094 -65.37706)
		(width 0.089408)
		(layer "In4.Cu")
		(net "FM_JTAG_PLD_EN_DEBUG")
	)
	(segment
		(start 393.182094 -65.37706)
		(end 394.60805 -65.37706)
		(width 0.089408)
		(layer "In4.Cu")
		(net "FM_JTAG_PLD_EN_DEBUG")
	)
	(segment
		(start 394.60805 -65.37706)
		(end 394.608558 -65.376552)
		(width 0.089408)
		(layer "In4.Cu")
		(net "FM_JTAG_PLD_EN_DEBUG")
	)
	(segment
		(start 376.3518 -66.6242)
		(end 378.106432 -66.6242)
		(width 0.089408)
		(layer "In4.Cu")
		(net "FM_JTAG_PLD_EN_DEBUG")
	)
	(segment
		(start 435.229 1.27)
		(end 435.229 0.397764)
		(width 0.10795)
		(layer "F.Cu")
		(net "FM_IE_DISABLE_N")
	)
	(segment
		(start 390.70915 -98.69424)
		(end 391.20445 -98.464116)
		(width 0.10795)
		(layer "F.Cu")
		(net "FM_IE_DISABLE_N")
	)
	(segment
		(start 436.013352 -1.2573)
		(end 440.633866 -1.2573)
		(width 0.10795)
		(layer "F.Cu")
		(net "FM_IE_DISABLE_N")
	)
	(segment
		(start 435.229762 1.27)
		(end 435.229 1.27)
		(width 0.10795)
		(layer "F.Cu")
		(net "FM_IE_DISABLE_N")
	)
	(segment
		(start 371.945154 -76.694792)
		(end 372.34495 -76.294996)
		(width 0.1016)
		(layer "F.Cu")
		(net "FM_IE_DISABLE_N")
	)
	(segment
		(start 435.905402 -1.14935)
		(end 436.013352 -1.2573)
		(width 0.10795)
		(layer "F.Cu")
		(net "FM_IE_DISABLE_N")
	)
	(segment
		(start 442.111384 -2.734818)
		(end 442.781182 -2.734818)
		(width 0.10795)
		(layer "F.Cu")
		(net "FM_IE_DISABLE_N")
	)
	(segment
		(start 435.229 0.397764)
		(end 435.905402 -0.278638)
		(width 0.10795)
		(layer "F.Cu")
		(net "FM_IE_DISABLE_N")
	)
	(segment
		(start 440.633866 -1.2573)
		(end 442.111384 -2.734818)
		(width 0.10795)
		(layer "F.Cu")
		(net "FM_IE_DISABLE_N")
	)
	(segment
		(start 435.905402 -0.821182)
		(end 435.905402 -1.14935)
		(width 0.10795)
		(layer "F.Cu")
		(net "FM_IE_DISABLE_N")
	)
	(segment
		(start 442.781182 -2.734818)
		(end 443.2046 -2.3114)
		(width 0.10795)
		(layer "F.Cu")
		(net "FM_IE_DISABLE_N")
	)
	(segment
		(start 435.905402 -0.278638)
		(end 435.905402 -0.821182)
		(width 0.10795)
		(layer "F.Cu")
		(net "FM_IE_DISABLE_N")
	)
	(via
		(at 443.2046 -2.3114)
		(size 0.508)
		(drill 0.254)
		(layers "F.Cu" "B.Cu")
		(net "FM_IE_DISABLE_N")
	)
	(via
		(at 391.20445 -98.464116)
		(size 0.508)
		(drill 0.254)
		(layers "F.Cu" "B.Cu")
		(net "FM_IE_DISABLE_N")
	)
	(via
		(at 371.945154 -76.694792)
		(size 0.4572)
		(drill 0.2032)
		(layers "F.Cu" "B.Cu")
		(net "FM_IE_DISABLE_N")
	)
	(via
		(at 402.525992 -17.99336)
		(size 0.508)
		(drill 0.254)
		(layers "F.Cu" "B.Cu")
		(net "FM_IE_DISABLE_N")
	)
	(segment
		(start 391.154666 -95.576898)
		(end 391.058908 -95.48114)
		(width 0.089408)
		(layer "In2.Cu")
		(net "FM_IE_DISABLE_N")
	)
	(segment
		(start 375.915682 -82.24139)
		(end 374.573292 -80.899)
		(width 0.089408)
		(layer "In2.Cu")
		(net "FM_IE_DISABLE_N")
	)
	(segment
		(start 374.573292 -80.899)
		(end 373.45239 -80.899)
		(width 0.089408)
		(layer "In2.Cu")
		(net "FM_IE_DISABLE_N")
	)
	(segment
		(start 374.93194 -93.11894)
		(end 374.93194 -92.642944)
		(width 0.089408)
		(layer "In2.Cu")
		(net "FM_IE_DISABLE_N")
	)
	(segment
		(start 374.73382 -92.444824)
		(end 374.73382 -89.223596)
		(width 0.089408)
		(layer "In2.Cu")
		(net "FM_IE_DISABLE_N")
	)
	(segment
		(start 372.452646 -77.202284)
		(end 371.945154 -76.694792)
		(width 0.089408)
		(layer "In2.Cu")
		(net "FM_IE_DISABLE_N")
	)
	(segment
		(start 391.6934 -96.469454)
		(end 391.154666 -95.93072)
		(width 0.089408)
		(layer "In2.Cu")
		(net "FM_IE_DISABLE_N")
	)
	(segment
		(start 375.915682 -88.041734)
		(end 375.915682 -82.24139)
		(width 0.089408)
		(layer "In2.Cu")
		(net "FM_IE_DISABLE_N")
	)
	(segment
		(start 374.93194 -92.642944)
		(end 374.73382 -92.444824)
		(width 0.089408)
		(layer "In2.Cu")
		(net "FM_IE_DISABLE_N")
	)
	(segment
		(start 377.29414 -95.48114)
		(end 374.93194 -93.11894)
		(width 0.089408)
		(layer "In2.Cu")
		(net "FM_IE_DISABLE_N")
	)
	(segment
		(start 373.45239 -80.899)
		(end 372.452646 -79.899256)
		(width 0.089408)
		(layer "In2.Cu")
		(net "FM_IE_DISABLE_N")
	)
	(segment
		(start 391.154666 -95.93072)
		(end 391.154666 -95.576898)
		(width 0.089408)
		(layer "In2.Cu")
		(net "FM_IE_DISABLE_N")
	)
	(segment
		(start 391.20445 -98.464116)
		(end 391.20445 -97.44075)
		(width 0.089408)
		(layer "In2.Cu")
		(net "FM_IE_DISABLE_N")
	)
	(segment
		(start 391.058908 -95.48114)
		(end 377.29414 -95.48114)
		(width 0.089408)
		(layer "In2.Cu")
		(net "FM_IE_DISABLE_N")
	)
	(segment
		(start 374.73382 -89.223596)
		(end 375.915682 -88.041734)
		(width 0.089408)
		(layer "In2.Cu")
		(net "FM_IE_DISABLE_N")
	)
	(segment
		(start 391.20445 -97.44075)
		(end 391.6934 -96.9518)
		(width 0.089408)
		(layer "In2.Cu")
		(net "FM_IE_DISABLE_N")
	)
	(segment
		(start 372.452646 -79.899256)
		(end 372.452646 -77.202284)
		(width 0.089408)
		(layer "In2.Cu")
		(net "FM_IE_DISABLE_N")
	)
	(segment
		(start 391.6934 -96.9518)
		(end 391.6934 -96.469454)
		(width 0.089408)
		(layer "In2.Cu")
		(net "FM_IE_DISABLE_N")
	)
	(segment
		(start 420.520622 -2.817876)
		(end 420.520622 -3.046476)
		(width 0.089408)
		(layer "In4.Cu")
		(net "FM_IE_DISABLE_N")
	)
	(segment
		(start 420.019988 -2.317242)
		(end 420.520622 -2.817876)
		(width 0.089408)
		(layer "In4.Cu")
		(net "FM_IE_DISABLE_N")
	)
	(segment
		(start 430.27727 -3.977132)
		(end 430.608994 -3.977132)
		(width 0.089408)
		(layer "In4.Cu")
		(net "FM_IE_DISABLE_N")
	)
	(segment
		(start 430.731422 -3.854704)
		(end 441.661296 -3.854704)
		(width 0.089408)
		(layer "In4.Cu")
		(net "FM_IE_DISABLE_N")
	)
	(segment
		(start 430.154842 -3.854704)
		(end 430.27727 -3.977132)
		(width 0.089408)
		(layer "In4.Cu")
		(net "FM_IE_DISABLE_N")
	)
	(segment
		(start 402.6662 -13.560806)
		(end 406.616408 -9.610598)
		(width 0.089408)
		(layer "In4.Cu")
		(net "FM_IE_DISABLE_N")
	)
	(segment
		(start 406.616408 -9.610598)
		(end 406.616408 -7.017766)
		(width 0.089408)
		(layer "In4.Cu")
		(net "FM_IE_DISABLE_N")
	)
	(segment
		(start 421.32885 -3.854704)
		(end 430.154842 -3.854704)
		(width 0.089408)
		(layer "In4.Cu")
		(net "FM_IE_DISABLE_N")
	)
	(segment
		(start 402.525992 -17.99336)
		(end 402.6662 -17.853152)
		(width 0.089408)
		(layer "In4.Cu")
		(net "FM_IE_DISABLE_N")
	)
	(segment
		(start 416.046158 -2.317242)
		(end 420.019988 -2.317242)
		(width 0.089408)
		(layer "In4.Cu")
		(net "FM_IE_DISABLE_N")
	)
	(segment
		(start 415.452052 -5.76072)
		(end 415.452052 -2.911348)
		(width 0.089408)
		(layer "In4.Cu")
		(net "FM_IE_DISABLE_N")
	)
	(segment
		(start 406.616408 -7.017766)
		(end 407.172668 -6.461506)
		(width 0.089408)
		(layer "In4.Cu")
		(net "FM_IE_DISABLE_N")
	)
	(segment
		(start 441.661296 -3.854704)
		(end 443.2046 -2.3114)
		(width 0.089408)
		(layer "In4.Cu")
		(net "FM_IE_DISABLE_N")
	)
	(segment
		(start 407.172668 -6.461506)
		(end 414.751266 -6.461506)
		(width 0.089408)
		(layer "In4.Cu")
		(net "FM_IE_DISABLE_N")
	)
	(segment
		(start 430.608994 -3.977132)
		(end 430.731422 -3.854704)
		(width 0.089408)
		(layer "In4.Cu")
		(net "FM_IE_DISABLE_N")
	)
	(segment
		(start 402.6662 -17.853152)
		(end 402.6662 -13.560806)
		(width 0.089408)
		(layer "In4.Cu")
		(net "FM_IE_DISABLE_N")
	)
	(segment
		(start 415.452052 -2.911348)
		(end 416.046158 -2.317242)
		(width 0.089408)
		(layer "In4.Cu")
		(net "FM_IE_DISABLE_N")
	)
	(segment
		(start 414.751266 -6.461506)
		(end 415.452052 -5.76072)
		(width 0.089408)
		(layer "In4.Cu")
		(net "FM_IE_DISABLE_N")
	)
	(segment
		(start 420.520622 -3.046476)
		(end 421.32885 -3.854704)
		(width 0.089408)
		(layer "In4.Cu")
		(net "FM_IE_DISABLE_N")
	)
	(segment
		(start 372.337076 -69.036946)
		(end 372.024148 -68.724018)
		(width 0.089408)
		(layer "In9.Cu")
		(net "FM_IE_DISABLE_N")
	)
	(segment
		(start 396.591028 -17.949418)
		(end 398.279366 -17.949418)
		(width 0.089408)
		(layer "In9.Cu")
		(net "FM_IE_DISABLE_N")
	)
	(segment
		(start 379.402848 -49.98085)
		(end 379.402848 -46.454822)
		(width 0.089408)
		(layer "In9.Cu")
		(net "FM_IE_DISABLE_N")
	)
	(segment
		(start 387.53796 -21.362416)
		(end 387.683248 -21.362416)
		(width 0.089408)
		(layer "In9.Cu")
		(net "FM_IE_DISABLE_N")
	)
	(segment
		(start 380.977648 -33.010602)
		(end 381.4572 -33.010602)
		(width 0.089408)
		(layer "In9.Cu")
		(net "FM_IE_DISABLE_N")
	)
	(segment
		(start 377.394216 -41.458388)
		(end 377.394216 -39.828724)
		(width 0.089408)
		(layer "In9.Cu")
		(net "FM_IE_DISABLE_N")
	)
	(segment
		(start 384.137916 -25.463754)
		(end 385.28498 -24.31669)
		(width 0.089408)
		(layer "In9.Cu")
		(net "FM_IE_DISABLE_N")
	)
	(segment
		(start 379.088904 -38.134036)
		(end 379.088904 -35.506406)
		(width 0.089408)
		(layer "In9.Cu")
		(net "FM_IE_DISABLE_N")
	)
	(segment
		(start 400.015456 -17.458944)
		(end 400.419824 -17.054576)
		(width 0.089408)
		(layer "In9.Cu")
		(net "FM_IE_DISABLE_N")
	)
	(segment
		(start 371.040914 -67.60718)
		(end 370.82222 -67.388486)
		(width 0.089408)
		(layer "In9.Cu")
		(net "FM_IE_DISABLE_N")
	)
	(segment
		(start 379.402594 -49.981104)
		(end 379.402848 -49.98085)
		(width 0.089408)
		(layer "In9.Cu")
		(net "FM_IE_DISABLE_N")
	)
	(segment
		(start 371.597936 -67.60718)
		(end 371.040914 -67.60718)
		(width 0.089408)
		(layer "In9.Cu")
		(net "FM_IE_DISABLE_N")
	)
	(segment
		(start 373.254524 -64.661288)
		(end 373.787162 -64.661288)
		(width 0.089408)
		(layer "In9.Cu")
		(net "FM_IE_DISABLE_N")
	)
	(segment
		(start 379.372622 -57.825894)
		(end 379.372622 -55.640732)
		(width 0.089408)
		(layer "In9.Cu")
		(net "FM_IE_DISABLE_N")
	)
	(segment
		(start 381.998474 -32.469328)
		(end 381.998474 -26.984198)
		(width 0.089408)
		(layer "In9.Cu")
		(net "FM_IE_DISABLE_N")
	)
	(segment
		(start 370.82222 -67.079114)
		(end 372.115334 -65.786)
		(width 0.089408)
		(layer "In9.Cu")
		(net "FM_IE_DISABLE_N")
	)
	(segment
		(start 396.05458 -18.48612)
		(end 396.05458 -18.485866)
		(width 0.089408)
		(layer "In9.Cu")
		(net "FM_IE_DISABLE_N")
	)
	(segment
		(start 380.60376 -44.285154)
		(end 378.815346 -42.49674)
		(width 0.089408)
		(layer "In9.Cu")
		(net "FM_IE_DISABLE_N")
	)
	(segment
		(start 385.28498 -23.025862)
		(end 385.1021 -22.842982)
		(width 0.089408)
		(layer "In9.Cu")
		(net "FM_IE_DISABLE_N")
	)
	(segment
		(start 385.1021 -22.842982)
		(end 385.1021 -21.51253)
		(width 0.089408)
		(layer "In9.Cu")
		(net "FM_IE_DISABLE_N")
	)
	(segment
		(start 372.115334 -65.786)
		(end 372.336822 -65.786)
		(width 0.089408)
		(layer "In9.Cu")
		(net "FM_IE_DISABLE_N")
	)
	(segment
		(start 386.46227 -19.346672)
		(end 386.860542 -19.744944)
		(width 0.089408)
		(layer "In9.Cu")
		(net "FM_IE_DISABLE_N")
	)
	(segment
		(start 383.518918 -25.463754)
		(end 384.137916 -25.463754)
		(width 0.089408)
		(layer "In9.Cu")
		(net "FM_IE_DISABLE_N")
	)
	(segment
		(start 400.419824 -17.054576)
		(end 401.428458 -16.8402)
		(width 0.089408)
		(layer "In9.Cu")
		(net "FM_IE_DISABLE_N")
	)
	(segment
		(start 384.931158 -21.341588)
		(end 384.931158 -19.80184)
		(width 0.089408)
		(layer "In9.Cu")
		(net "FM_IE_DISABLE_N")
	)
	(segment
		(start 385.386326 -19.346672)
		(end 386.46227 -19.346672)
		(width 0.089408)
		(layer "In9.Cu")
		(net "FM_IE_DISABLE_N")
	)
	(segment
		(start 381.4572 -33.010602)
		(end 381.998474 -32.469328)
		(width 0.089408)
		(layer "In9.Cu")
		(net "FM_IE_DISABLE_N")
	)
	(segment
		(start 372.337076 -76.30287)
		(end 372.337076 -69.036946)
		(width 0.089408)
		(layer "In9.Cu")
		(net "FM_IE_DISABLE_N")
	)
	(segment
		(start 396.05458 -18.485866)
		(end 396.591028 -17.949418)
		(width 0.089408)
		(layer "In9.Cu")
		(net "FM_IE_DISABLE_N")
	)
	(segment
		(start 387.683248 -21.362416)
		(end 387.789928 -21.469096)
		(width 0.089408)
		(layer "In9.Cu")
		(net "FM_IE_DISABLE_N")
	)
	(segment
		(start 385.28498 -24.31669)
		(end 385.28498 -23.025862)
		(width 0.089408)
		(layer "In9.Cu")
		(net "FM_IE_DISABLE_N")
	)
	(segment
		(start 371.945154 -76.694792)
		(end 372.337076 -76.30287)
		(width 0.089408)
		(layer "In9.Cu")
		(net "FM_IE_DISABLE_N")
	)
	(segment
		(start 376.52325 -60.675266)
		(end 379.372622 -57.825894)
		(width 0.089408)
		(layer "In9.Cu")
		(net "FM_IE_DISABLE_N")
	)
	(segment
		(start 378.815346 -42.49674)
		(end 378.432568 -42.49674)
		(width 0.089408)
		(layer "In9.Cu")
		(net "FM_IE_DISABLE_N")
	)
	(segment
		(start 379.402594 -50.139092)
		(end 379.402594 -49.981104)
		(width 0.089408)
		(layer "In9.Cu")
		(net "FM_IE_DISABLE_N")
	)
	(segment
		(start 390.897618 -21.469096)
		(end 392.613134 -19.75358)
		(width 0.089408)
		(layer "In9.Cu")
		(net "FM_IE_DISABLE_N")
	)
	(segment
		(start 401.8534 -16.8402)
		(end 402.525992 -17.512792)
		(width 0.089408)
		(layer "In9.Cu")
		(net "FM_IE_DISABLE_N")
	)
	(segment
		(start 384.931158 -19.80184)
		(end 385.386326 -19.346672)
		(width 0.089408)
		(layer "In9.Cu")
		(net "FM_IE_DISABLE_N")
	)
	(segment
		(start 374.05056 -63.73114)
		(end 376.52325 -61.25845)
		(width 0.089408)
		(layer "In9.Cu")
		(net "FM_IE_DISABLE_N")
	)
	(segment
		(start 372.929912 -64.9859)
		(end 373.254524 -64.661288)
		(width 0.089408)
		(layer "In9.Cu")
		(net "FM_IE_DISABLE_N")
	)
	(segment
		(start 379.088904 -35.506406)
		(end 380.437644 -34.157666)
		(width 0.089408)
		(layer "In9.Cu")
		(net "FM_IE_DISABLE_N")
	)
	(segment
		(start 379.402848 -50.139346)
		(end 379.402594 -50.139092)
		(width 0.089408)
		(layer "In9.Cu")
		(net "FM_IE_DISABLE_N")
	)
	(segment
		(start 380.60376 -45.25391)
		(end 380.60376 -44.285154)
		(width 0.089408)
		(layer "In9.Cu")
		(net "FM_IE_DISABLE_N")
	)
	(segment
		(start 377.394216 -39.828724)
		(end 379.088904 -38.134036)
		(width 0.089408)
		(layer "In9.Cu")
		(net "FM_IE_DISABLE_N")
	)
	(segment
		(start 380.437644 -34.157666)
		(end 380.437644 -33.550606)
		(width 0.089408)
		(layer "In9.Cu")
		(net "FM_IE_DISABLE_N")
	)
	(segment
		(start 372.024148 -68.033392)
		(end 371.597936 -67.60718)
		(width 0.089408)
		(layer "In9.Cu")
		(net "FM_IE_DISABLE_N")
	)
	(segment
		(start 379.27407 -55.54218)
		(end 379.27407 -51.077368)
		(width 0.089408)
		(layer "In9.Cu")
		(net "FM_IE_DISABLE_N")
	)
	(segment
		(start 381.998474 -26.984198)
		(end 383.518918 -25.463754)
		(width 0.089408)
		(layer "In9.Cu")
		(net "FM_IE_DISABLE_N")
	)
	(segment
		(start 402.525992 -17.512792)
		(end 402.525992 -17.99336)
		(width 0.089408)
		(layer "In9.Cu")
		(net "FM_IE_DISABLE_N")
	)
	(segment
		(start 379.402848 -46.454822)
		(end 380.60376 -45.25391)
		(width 0.089408)
		(layer "In9.Cu")
		(net "FM_IE_DISABLE_N")
	)
	(segment
		(start 376.52325 -61.25845)
		(end 376.52325 -60.675266)
		(width 0.089408)
		(layer "In9.Cu")
		(net "FM_IE_DISABLE_N")
	)
	(segment
		(start 372.929912 -65.19291)
		(end 372.929912 -64.9859)
		(width 0.089408)
		(layer "In9.Cu")
		(net "FM_IE_DISABLE_N")
	)
	(segment
		(start 386.860542 -19.744944)
		(end 386.860542 -20.684998)
		(width 0.089408)
		(layer "In9.Cu")
		(net "FM_IE_DISABLE_N")
	)
	(segment
		(start 379.402848 -50.94859)
		(end 379.402848 -50.139346)
		(width 0.089408)
		(layer "In9.Cu")
		(net "FM_IE_DISABLE_N")
	)
	(segment
		(start 373.787162 -64.661288)
		(end 374.05056 -64.39789)
		(width 0.089408)
		(layer "In9.Cu")
		(net "FM_IE_DISABLE_N")
	)
	(segment
		(start 380.437644 -33.550606)
		(end 380.977648 -33.010602)
		(width 0.089408)
		(layer "In9.Cu")
		(net "FM_IE_DISABLE_N")
	)
	(segment
		(start 378.432568 -42.49674)
		(end 377.394216 -41.458388)
		(width 0.089408)
		(layer "In9.Cu")
		(net "FM_IE_DISABLE_N")
	)
	(segment
		(start 379.27407 -51.077368)
		(end 379.402848 -50.94859)
		(width 0.089408)
		(layer "In9.Cu")
		(net "FM_IE_DISABLE_N")
	)
	(segment
		(start 374.05056 -64.39789)
		(end 374.05056 -63.73114)
		(width 0.089408)
		(layer "In9.Cu")
		(net "FM_IE_DISABLE_N")
	)
	(segment
		(start 394.78712 -19.75358)
		(end 396.05458 -18.48612)
		(width 0.089408)
		(layer "In9.Cu")
		(net "FM_IE_DISABLE_N")
	)
	(segment
		(start 398.76984 -17.458944)
		(end 400.015456 -17.458944)
		(width 0.089408)
		(layer "In9.Cu")
		(net "FM_IE_DISABLE_N")
	)
	(segment
		(start 401.428458 -16.8402)
		(end 401.8534 -16.8402)
		(width 0.089408)
		(layer "In9.Cu")
		(net "FM_IE_DISABLE_N")
	)
	(segment
		(start 372.336822 -65.786)
		(end 372.929912 -65.19291)
		(width 0.089408)
		(layer "In9.Cu")
		(net "FM_IE_DISABLE_N")
	)
	(segment
		(start 385.1021 -21.51253)
		(end 384.931158 -21.341588)
		(width 0.089408)
		(layer "In9.Cu")
		(net "FM_IE_DISABLE_N")
	)
	(segment
		(start 392.613134 -19.75358)
		(end 394.78712 -19.75358)
		(width 0.089408)
		(layer "In9.Cu")
		(net "FM_IE_DISABLE_N")
	)
	(segment
		(start 387.789928 -21.469096)
		(end 390.897618 -21.469096)
		(width 0.089408)
		(layer "In9.Cu")
		(net "FM_IE_DISABLE_N")
	)
	(segment
		(start 372.024148 -68.724018)
		(end 372.024148 -68.033392)
		(width 0.089408)
		(layer "In9.Cu")
		(net "FM_IE_DISABLE_N")
	)
	(segment
		(start 379.372622 -55.640732)
		(end 379.27407 -55.54218)
		(width 0.089408)
		(layer "In9.Cu")
		(net "FM_IE_DISABLE_N")
	)
	(segment
		(start 386.860542 -20.684998)
		(end 387.53796 -21.362416)
		(width 0.089408)
		(layer "In9.Cu")
		(net "FM_IE_DISABLE_N")
	)
	(segment
		(start 398.279366 -17.949418)
		(end 398.76984 -17.458944)
		(width 0.089408)
		(layer "In9.Cu")
		(net "FM_IE_DISABLE_N")
	)
	(segment
		(start 370.82222 -67.388486)
		(end 370.82222 -67.079114)
		(width 0.089408)
		(layer "In9.Cu")
		(net "FM_IE_DISABLE_N")
	)
	(segment
		(start 417.561014 -115.5954)
		(end 418.198554 -114.95786)
		(width 0.10795)
		(layer "F.Cu")
		(net "FM_BMC_CPLD_GPO")
	)
	(segment
		(start 422.29024 -41.73474)
		(end 421.89019 -42.13479)
		(width 0.10795)
		(layer "F.Cu")
		(net "FM_BMC_CPLD_GPO")
	)
	(segment
		(start 411.3276 -116.5098)
		(end 413.732218 -116.5098)
		(width 0.10795)
		(layer "F.Cu")
		(net "FM_BMC_CPLD_GPO")
	)
	(segment
		(start 402.625814 -113.738914)
		(end 402.741892 -113.854992)
		(width 0.0889)
		(layer "F.Cu")
		(net "FM_BMC_CPLD_GPO")
	)
	(segment
		(start 405.010112 -114.935)
		(end 405.892 -114.935)
		(width 0.10795)
		(layer "F.Cu")
		(net "FM_BMC_CPLD_GPO")
	)
	(segment
		(start 379.545088 -79.494888)
		(end 378.744988 -79.494888)
		(width 0.10795)
		(layer "F.Cu")
		(net "FM_BMC_CPLD_GPO")
	)
	(segment
		(start 406.151842 -115.194842)
		(end 407.420572 -115.194842)
		(width 0.10795)
		(layer "F.Cu")
		(net "FM_BMC_CPLD_GPO")
	)
	(segment
		(start 379.907546 -79.894684)
		(end 379.944884 -79.894684)
		(width 0.10795)
		(layer "F.Cu")
		(net "FM_BMC_CPLD_GPO")
	)
	(segment
		(start 416.369246 -115.592098)
		(end 416.750754 -115.592098)
		(width 0.10795)
		(layer "F.Cu")
		(net "FM_BMC_CPLD_GPO")
	)
	(segment
		(start 401.295108 -113.854992)
		(end 401.411186 -113.738914)
		(width 0.0889)
		(layer "F.Cu")
		(net "FM_BMC_CPLD_GPO")
	)
	(segment
		(start 415.235136 -116.691664)
		(end 416.3314 -115.5954)
		(width 0.10795)
		(layer "F.Cu")
		(net "FM_BMC_CPLD_GPO")
	)
	(segment
		(start 407.420572 -115.194842)
		(end 407.52903 -115.086384)
		(width 0.10795)
		(layer "F.Cu")
		(net "FM_BMC_CPLD_GPO")
	)
	(segment
		(start 409.904184 -115.086384)
		(end 411.3276 -116.5098)
		(width 0.10795)
		(layer "F.Cu")
		(net "FM_BMC_CPLD_GPO")
	)
	(segment
		(start 407.52903 -115.086384)
		(end 409.904184 -115.086384)
		(width 0.10795)
		(layer "F.Cu")
		(net "FM_BMC_CPLD_GPO")
	)
	(segment
		(start 379.944884 -79.894684)
		(end 379.545088 -79.494888)
		(width 0.10795)
		(layer "F.Cu")
		(net "FM_BMC_CPLD_GPO")
	)
	(segment
		(start 413.732218 -116.5098)
		(end 413.914082 -116.691664)
		(width 0.10795)
		(layer "F.Cu")
		(net "FM_BMC_CPLD_GPO")
	)
	(segment
		(start 416.365944 -115.5954)
		(end 416.369246 -115.592098)
		(width 0.10795)
		(layer "F.Cu")
		(net "FM_BMC_CPLD_GPO")
	)
	(segment
		(start 413.914082 -116.691664)
		(end 415.235136 -116.691664)
		(width 0.10795)
		(layer "F.Cu")
		(net "FM_BMC_CPLD_GPO")
	)
	(segment
		(start 402.741892 -113.854992)
		(end 402.90877 -114.02187)
		(width 0.10795)
		(layer "F.Cu")
		(net "FM_BMC_CPLD_GPO")
	)
	(segment
		(start 418.272214 -114.8842)
		(end 418.198554 -114.95786)
		(width 0.10795)
		(layer "F.Cu")
		(net "FM_BMC_CPLD_GPO")
	)
	(segment
		(start 404.096982 -114.02187)
		(end 405.010112 -114.935)
		(width 0.10795)
		(layer "F.Cu")
		(net "FM_BMC_CPLD_GPO")
	)
	(segment
		(start 401.411186 -113.738914)
		(end 402.625814 -113.738914)
		(width 0.0889)
		(layer "F.Cu")
		(net "FM_BMC_CPLD_GPO")
	)
	(segment
		(start 417.3982 -115.5954)
		(end 417.561014 -115.5954)
		(width 0.10795)
		(layer "F.Cu")
		(net "FM_BMC_CPLD_GPO")
	)
	(segment
		(start 416.754056 -115.5954)
		(end 417.3982 -115.5954)
		(width 0.10795)
		(layer "F.Cu")
		(net "FM_BMC_CPLD_GPO")
	)
	(segment
		(start 416.750754 -115.592098)
		(end 416.754056 -115.5954)
		(width 0.10795)
		(layer "F.Cu")
		(net "FM_BMC_CPLD_GPO")
	)
	(segment
		(start 402.90877 -114.02187)
		(end 404.096982 -114.02187)
		(width 0.10795)
		(layer "F.Cu")
		(net "FM_BMC_CPLD_GPO")
	)
	(segment
		(start 405.892 -114.935)
		(end 406.151842 -115.194842)
		(width 0.10795)
		(layer "F.Cu")
		(net "FM_BMC_CPLD_GPO")
	)
	(segment
		(start 416.3314 -115.5954)
		(end 416.365944 -115.5954)
		(width 0.10795)
		(layer "F.Cu")
		(net "FM_BMC_CPLD_GPO")
	)
	(segment
		(start 419.0492 -114.8842)
		(end 418.272214 -114.8842)
		(width 0.10795)
		(layer "F.Cu")
		(net "FM_BMC_CPLD_GPO")
	)
	(via
		(at 401.81276 -75.13828)
		(size 0.508)
		(drill 0.254)
		(layers "F.Cu" "B.Cu")
		(net "FM_BMC_CPLD_GPO")
	)
	(via
		(at 418.198554 -114.95786)
		(size 0.508)
		(drill 0.254)
		(layers "F.Cu" "B.Cu")
		(net "FM_BMC_CPLD_GPO")
	)
	(via
		(at 379.907546 -79.894684)
		(size 0.4572)
		(drill 0.2032)
		(layers "F.Cu" "B.Cu")
		(net "FM_BMC_CPLD_GPO")
	)
	(via
		(at 421.89019 -42.13479)
		(size 0.4572)
		(drill 0.2032)
		(layers "F.Cu" "B.Cu")
		(net "FM_BMC_CPLD_GPO")
	)
	(via
		(at 417.3982 -115.5954)
		(size 0.762)
		(drill 0.381)
		(layers "F.Cu" "B.Cu")
		(net "FM_BMC_CPLD_GPO")
	)
	(via
		(at 435.822598 -62.529212)
		(size 0.508)
		(drill 0.254)
		(layers "F.Cu" "B.Cu")
		(net "FM_BMC_CPLD_GPO")
	)
	(segment
		(start 421.051736 -64.569848)
		(end 420.384986 -65.236598)
		(width 0.089408)
		(layer "In2.Cu")
		(net "FM_BMC_CPLD_GPO")
	)
	(segment
		(start 422.059608 -64.569848)
		(end 421.051736 -64.569848)
		(width 0.089408)
		(layer "In2.Cu")
		(net "FM_BMC_CPLD_GPO")
	)
	(segment
		(start 420.384986 -65.236598)
		(end 420.384986 -65.765172)
		(width 0.089408)
		(layer "In2.Cu")
		(net "FM_BMC_CPLD_GPO")
	)
	(segment
		(start 430.335944 -63.483236)
		(end 427.872398 -61.01969)
		(width 0.089408)
		(layer "In2.Cu")
		(net "FM_BMC_CPLD_GPO")
	)
	(segment
		(start 420.384732 -71.900034)
		(end 420.362126 -71.92264)
		(width 0.089408)
		(layer "In2.Cu")
		(net "FM_BMC_CPLD_GPO")
	)
	(segment
		(start 420.362126 -71.92264)
		(end 420.362126 -79.836264)
		(width 0.089408)
		(layer "In2.Cu")
		(net "FM_BMC_CPLD_GPO")
	)
	(segment
		(start 433.928266 -62.529212)
		(end 432.974242 -63.483236)
		(width 0.089408)
		(layer "In2.Cu")
		(net "FM_BMC_CPLD_GPO")
	)
	(segment
		(start 420.362126 -79.836264)
		(end 421.4368 -80.910938)
		(width 0.089408)
		(layer "In2.Cu")
		(net "FM_BMC_CPLD_GPO")
	)
	(segment
		(start 432.974242 -63.483236)
		(end 430.335944 -63.483236)
		(width 0.089408)
		(layer "In2.Cu")
		(net "FM_BMC_CPLD_GPO")
	)
	(segment
		(start 425.609766 -61.01969)
		(end 422.059608 -64.569848)
		(width 0.089408)
		(layer "In2.Cu")
		(net "FM_BMC_CPLD_GPO")
	)
	(segment
		(start 420.384986 -65.765172)
		(end 420.384732 -65.765426)
		(width 0.089408)
		(layer "In2.Cu")
		(net "FM_BMC_CPLD_GPO")
	)
	(segment
		(start 421.4368 -93.566742)
		(end 419.17112 -95.832422)
		(width 0.089408)
		(layer "In2.Cu")
		(net "FM_BMC_CPLD_GPO")
	)
	(segment
		(start 419.17112 -113.985294)
		(end 418.198554 -114.95786)
		(width 0.089408)
		(layer "In2.Cu")
		(net "FM_BMC_CPLD_GPO")
	)
	(segment
		(start 435.822598 -62.529212)
		(end 433.928266 -62.529212)
		(width 0.089408)
		(layer "In2.Cu")
		(net "FM_BMC_CPLD_GPO")
	)
	(segment
		(start 421.4368 -80.910938)
		(end 421.4368 -93.566742)
		(width 0.089408)
		(layer "In2.Cu")
		(net "FM_BMC_CPLD_GPO")
	)
	(segment
		(start 420.384732 -65.765426)
		(end 420.384732 -71.900034)
		(width 0.089408)
		(layer "In2.Cu")
		(net "FM_BMC_CPLD_GPO")
	)
	(segment
		(start 419.17112 -95.832422)
		(end 419.17112 -113.985294)
		(width 0.089408)
		(layer "In2.Cu")
		(net "FM_BMC_CPLD_GPO")
	)
	(segment
		(start 427.872398 -61.01969)
		(end 425.609766 -61.01969)
		(width 0.089408)
		(layer "In2.Cu")
		(net "FM_BMC_CPLD_GPO")
	)
	(segment
		(start 386.456174 -77.571092)
		(end 388.442454 -77.571092)
		(width 0.089408)
		(layer "In4.Cu")
		(net "FM_BMC_CPLD_GPO")
	)
	(segment
		(start 390.649206 -78.073504)
		(end 391.590784 -77.131926)
		(width 0.089408)
		(layer "In4.Cu")
		(net "FM_BMC_CPLD_GPO")
	)
	(segment
		(start 401.087082 -76.001118)
		(end 401.81276 -75.27544)
		(width 0.089408)
		(layer "In4.Cu")
		(net "FM_BMC_CPLD_GPO")
	)
	(segment
		(start 382.203452 -77.37221)
		(end 386.257292 -77.37221)
		(width 0.089408)
		(layer "In4.Cu")
		(net "FM_BMC_CPLD_GPO")
	)
	(segment
		(start 386.257292 -77.37221)
		(end 386.456174 -77.571092)
		(width 0.089408)
		(layer "In4.Cu")
		(net "FM_BMC_CPLD_GPO")
	)
	(segment
		(start 396.461234 -76.001118)
		(end 401.087082 -76.001118)
		(width 0.089408)
		(layer "In4.Cu")
		(net "FM_BMC_CPLD_GPO")
	)
	(segment
		(start 395.890496 -76.571856)
		(end 396.461234 -76.001118)
		(width 0.089408)
		(layer "In4.Cu")
		(net "FM_BMC_CPLD_GPO")
	)
	(segment
		(start 392.133074 -77.131926)
		(end 392.693144 -76.571856)
		(width 0.089408)
		(layer "In4.Cu")
		(net "FM_BMC_CPLD_GPO")
	)
	(segment
		(start 380.137162 -79.894684)
		(end 381.707644 -78.324202)
		(width 0.089408)
		(layer "In4.Cu")
		(net "FM_BMC_CPLD_GPO")
	)
	(segment
		(start 379.907546 -79.894684)
		(end 380.137162 -79.894684)
		(width 0.089408)
		(layer "In4.Cu")
		(net "FM_BMC_CPLD_GPO")
	)
	(segment
		(start 401.81276 -75.27544)
		(end 401.81276 -75.13828)
		(width 0.089408)
		(layer "In4.Cu")
		(net "FM_BMC_CPLD_GPO")
	)
	(segment
		(start 388.944866 -78.073504)
		(end 390.649206 -78.073504)
		(width 0.089408)
		(layer "In4.Cu")
		(net "FM_BMC_CPLD_GPO")
	)
	(segment
		(start 388.442454 -77.571092)
		(end 388.944866 -78.073504)
		(width 0.089408)
		(layer "In4.Cu")
		(net "FM_BMC_CPLD_GPO")
	)
	(segment
		(start 381.707644 -77.868018)
		(end 382.203452 -77.37221)
		(width 0.089408)
		(layer "In4.Cu")
		(net "FM_BMC_CPLD_GPO")
	)
	(segment
		(start 381.707644 -78.324202)
		(end 381.707644 -77.868018)
		(width 0.089408)
		(layer "In4.Cu")
		(net "FM_BMC_CPLD_GPO")
	)
	(segment
		(start 391.590784 -77.131926)
		(end 392.133074 -77.131926)
		(width 0.089408)
		(layer "In4.Cu")
		(net "FM_BMC_CPLD_GPO")
	)
	(segment
		(start 392.693144 -76.571856)
		(end 395.890496 -76.571856)
		(width 0.089408)
		(layer "In4.Cu")
		(net "FM_BMC_CPLD_GPO")
	)
	(segment
		(start 411.951932 -49.589944)
		(end 411.951932 -50.03292)
		(width 0.089408)
		(layer "In9.Cu")
		(net "FM_BMC_CPLD_GPO")
	)
	(segment
		(start 418.280596 -47.385478)
		(end 418.280596 -47.385732)
		(width 0.089408)
		(layer "In9.Cu")
		(net "FM_BMC_CPLD_GPO")
	)
	(segment
		(start 418.107876 -45.67047)
		(end 418.280596 -45.84319)
		(width 0.089408)
		(layer "In9.Cu")
		(net "FM_BMC_CPLD_GPO")
	)
	(segment
		(start 415.698432 -48.279812)
		(end 413.262064 -48.279812)
		(width 0.089408)
		(layer "In9.Cu")
		(net "FM_BMC_CPLD_GPO")
	)
	(segment
		(start 418.280596 -45.84319)
		(end 418.280596 -47.226982)
		(width 0.089408)
		(layer "In9.Cu")
		(net "FM_BMC_CPLD_GPO")
	)
	(segment
		(start 418.28085 -47.227236)
		(end 418.28085 -47.385224)
		(width 0.089408)
		(layer "In9.Cu")
		(net "FM_BMC_CPLD_GPO")
	)
	(segment
		(start 418.280596 -47.385732)
		(end 417.590224 -48.076104)
		(width 0.089408)
		(layer "In9.Cu")
		(net "FM_BMC_CPLD_GPO")
	)
	(segment
		(start 418.884862 -42.794682)
		(end 418.107876 -43.571668)
		(width 0.089408)
		(layer "In9.Cu")
		(net "FM_BMC_CPLD_GPO")
	)
	(segment
		(start 418.28085 -47.385224)
		(end 418.280596 -47.385478)
		(width 0.089408)
		(layer "In9.Cu")
		(net "FM_BMC_CPLD_GPO")
	)
	(segment
		(start 408.503374 -53.481478)
		(end 408.503374 -54.935628)
		(width 0.089408)
		(layer "In9.Cu")
		(net "FM_BMC_CPLD_GPO")
	)
	(segment
		(start 407.006044 -67.5894)
		(end 407.006044 -67.95008)
		(width 0.089408)
		(layer "In9.Cu")
		(net "FM_BMC_CPLD_GPO")
	)
	(segment
		(start 406.448768 -68.507356)
		(end 406.448768 -69.986906)
		(width 0.089408)
		(layer "In9.Cu")
		(net "FM_BMC_CPLD_GPO")
	)
	(segment
		(start 408.077416 -62.057026)
		(end 408.077416 -66.518028)
		(width 0.089408)
		(layer "In9.Cu")
		(net "FM_BMC_CPLD_GPO")
	)
	(segment
		(start 407.688542 -61.668152)
		(end 408.077416 -62.057026)
		(width 0.089408)
		(layer "In9.Cu")
		(net "FM_BMC_CPLD_GPO")
	)
	(segment
		(start 417.590224 -48.076104)
		(end 415.90214 -48.076104)
		(width 0.089408)
		(layer "In9.Cu")
		(net "FM_BMC_CPLD_GPO")
	)
	(segment
		(start 407.688542 -61.080396)
		(end 407.688542 -61.668152)
		(width 0.089408)
		(layer "In9.Cu")
		(net "FM_BMC_CPLD_GPO")
	)
	(segment
		(start 407.006044 -67.95008)
		(end 406.448768 -68.507356)
		(width 0.089408)
		(layer "In9.Cu")
		(net "FM_BMC_CPLD_GPO")
	)
	(segment
		(start 408.37993 -60.389008)
		(end 407.688542 -61.080396)
		(width 0.089408)
		(layer "In9.Cu")
		(net "FM_BMC_CPLD_GPO")
	)
	(segment
		(start 421.230298 -42.794682)
		(end 418.884862 -42.794682)
		(width 0.089408)
		(layer "In9.Cu")
		(net "FM_BMC_CPLD_GPO")
	)
	(segment
		(start 415.90214 -48.076104)
		(end 415.698432 -48.279812)
		(width 0.089408)
		(layer "In9.Cu")
		(net "FM_BMC_CPLD_GPO")
	)
	(segment
		(start 421.89019 -42.13479)
		(end 421.230298 -42.794682)
		(width 0.089408)
		(layer "In9.Cu")
		(net "FM_BMC_CPLD_GPO")
	)
	(segment
		(start 402.044916 -74.906124)
		(end 401.81276 -75.13828)
		(width 0.089408)
		(layer "In9.Cu")
		(net "FM_BMC_CPLD_GPO")
	)
	(segment
		(start 411.951932 -50.03292)
		(end 408.503374 -53.481478)
		(width 0.089408)
		(layer "In9.Cu")
		(net "FM_BMC_CPLD_GPO")
	)
	(segment
		(start 408.37993 -55.059072)
		(end 408.37993 -60.389008)
		(width 0.089408)
		(layer "In9.Cu")
		(net "FM_BMC_CPLD_GPO")
	)
	(segment
		(start 402.044916 -74.390758)
		(end 402.044916 -74.906124)
		(width 0.089408)
		(layer "In9.Cu")
		(net "FM_BMC_CPLD_GPO")
	)
	(segment
		(start 408.077416 -66.518028)
		(end 407.006044 -67.5894)
		(width 0.089408)
		(layer "In9.Cu")
		(net "FM_BMC_CPLD_GPO")
	)
	(segment
		(start 418.107876 -43.571668)
		(end 418.107876 -45.67047)
		(width 0.089408)
		(layer "In9.Cu")
		(net "FM_BMC_CPLD_GPO")
	)
	(segment
		(start 406.448768 -69.986906)
		(end 402.044916 -74.390758)
		(width 0.089408)
		(layer "In9.Cu")
		(net "FM_BMC_CPLD_GPO")
	)
	(segment
		(start 418.280596 -47.226982)
		(end 418.28085 -47.227236)
		(width 0.089408)
		(layer "In9.Cu")
		(net "FM_BMC_CPLD_GPO")
	)
	(segment
		(start 413.262064 -48.279812)
		(end 411.951932 -49.589944)
		(width 0.089408)
		(layer "In9.Cu")
		(net "FM_BMC_CPLD_GPO")
	)
	(segment
		(start 408.503374 -54.935628)
		(end 408.37993 -55.059072)
		(width 0.089408)
		(layer "In9.Cu")
		(net "FM_BMC_CPLD_GPO")
	)
	(segment
		(start 423.351452 -43.596052)
		(end 423.351452 -43.99788)
		(width 0.089408)
		(layer "In11.Cu")
		(net "FM_BMC_CPLD_GPO")
	)
	(segment
		(start 424.718988 -45.365416)
		(end 425.146978 -45.365416)
		(width 0.089408)
		(layer "In11.Cu")
		(net "FM_BMC_CPLD_GPO")
	)
	(segment
		(start 426.018452 -47.38497)
		(end 426.018198 -47.385224)
		(width 0.089408)
		(layer "In11.Cu")
		(net "FM_BMC_CPLD_GPO")
	)
	(segment
		(start 435.469538 -61.649864)
		(end 435.822598 -62.002924)
		(width 0.089408)
		(layer "In11.Cu")
		(net "FM_BMC_CPLD_GPO")
	)
	(segment
		(start 427.156118 -48.881538)
		(end 428.451772 -50.177192)
		(width 0.089408)
		(layer "In11.Cu")
		(net "FM_BMC_CPLD_GPO")
	)
	(segment
		(start 426.018452 -46.23689)
		(end 426.018452 -47.38497)
		(width 0.089408)
		(layer "In11.Cu")
		(net "FM_BMC_CPLD_GPO")
	)
	(segment
		(start 435.822598 -62.002924)
		(end 435.822598 -62.529212)
		(width 0.089408)
		(layer "In11.Cu")
		(net "FM_BMC_CPLD_GPO")
	)
	(segment
		(start 426.018198 -47.385224)
		(end 426.018198 -48.068484)
		(width 0.089408)
		(layer "In11.Cu")
		(net "FM_BMC_CPLD_GPO")
	)
	(segment
		(start 428.451772 -50.177192)
		(end 428.451772 -50.60315)
		(width 0.089408)
		(layer "In11.Cu")
		(net "FM_BMC_CPLD_GPO")
	)
	(segment
		(start 435.469538 -57.620916)
		(end 435.469538 -61.649864)
		(width 0.089408)
		(layer "In11.Cu")
		(net "FM_BMC_CPLD_GPO")
	)
	(segment
		(start 426.018198 -48.068484)
		(end 426.831252 -48.881538)
		(width 0.089408)
		(layer "In11.Cu")
		(net "FM_BMC_CPLD_GPO")
	)
	(segment
		(start 423.351452 -43.99788)
		(end 424.718988 -45.365416)
		(width 0.089408)
		(layer "In11.Cu")
		(net "FM_BMC_CPLD_GPO")
	)
	(segment
		(start 428.451772 -50.60315)
		(end 435.469538 -57.620916)
		(width 0.089408)
		(layer "In11.Cu")
		(net "FM_BMC_CPLD_GPO")
	)
	(segment
		(start 426.831252 -48.881538)
		(end 427.156118 -48.881538)
		(width 0.089408)
		(layer "In11.Cu")
		(net "FM_BMC_CPLD_GPO")
	)
	(segment
		(start 421.89019 -42.13479)
		(end 423.351452 -43.596052)
		(width 0.089408)
		(layer "In11.Cu")
		(net "FM_BMC_CPLD_GPO")
	)
	(segment
		(start 425.146978 -45.365416)
		(end 426.018452 -46.23689)
		(width 0.089408)
		(layer "In11.Cu")
		(net "FM_BMC_CPLD_GPO")
	)
	(segment
		(start 21.31187 -99.98837)
		(end 19.464782 -99.98837)
		(width 0.508)
		(layer "F.Cu")
		(net "VR_FET_SW_P12V_STBY_PVCCIN_CPU1")
	)
	(segment
		(start 21.92274 -100.59924)
		(end 21.31187 -99.98837)
		(width 0.508)
		(layer "F.Cu")
		(net "VR_FET_SW_P12V_STBY_PVCCIN_CPU1")
	)
	(segment
		(start 19.123152 -100.33)
		(end 18.288 -100.33)
		(width 0.508)
		(layer "F.Cu")
		(net "VR_FET_SW_P12V_STBY_PVCCIN_CPU1")
	)
	(segment
		(start 19.464782 -99.98837)
		(end 19.123152 -100.33)
		(width 0.508)
		(layer "F.Cu")
		(net "VR_FET_SW_P12V_STBY_PVCCIN_CPU1")
	)
	(segment
		(start 23.430484 -100.59924)
		(end 21.92274 -100.59924)
		(width 0.508)
		(layer "F.Cu")
		(net "VR_FET_SW_P12V_STBY_PVCCIN_CPU1")
	)
	(via
		(at 31.9024 -92.6846)
		(size 0.5588)
		(drill 0.3048)
		(layers "F.Cu" "B.Cu")
		(net "VR_FET_SW_P12V_STBY_PVCCIN_CPU1")
	)
	(via
		(at 31.918402 -58.601864)
		(size 0.508)
		(drill 0.254)
		(layers "F.Cu" "B.Cu")
		(net "VR_FET_SW_P12V_STBY_PVCCIN_CPU1")
	)
	(via
		(at 25.654 -100.8888)
		(size 0.5588)
		(drill 0.3048)
		(layers "F.Cu" "B.Cu")
		(net "VR_FET_SW_P12V_STBY_PVCCIN_CPU1")
	)
	(via
		(at 26.863294 -103.938832)
		(size 0.5588)
		(drill 0.3048)
		(layers "F.Cu" "B.Cu")
		(net "VR_FET_SW_P12V_STBY_PVCCIN_CPU1")
	)
	(via
		(at 31.893002 -98.327464)
		(size 0.508)
		(drill 0.254)
		(layers "F.Cu" "B.Cu")
		(net "VR_FET_SW_P12V_STBY_PVCCIN_CPU1")
	)
	(via
		(at 26.62428 -49.7078)
		(size 0.508)
		(drill 0.254)
		(layers "F.Cu" "B.Cu")
		(net "VR_FET_SW_P12V_STBY_PVCCIN_CPU1")
	)
	(via
		(at 31.918402 -99.241864)
		(size 0.508)
		(drill 0.254)
		(layers "F.Cu" "B.Cu")
		(net "VR_FET_SW_P12V_STBY_PVCCIN_CPU1")
	)
	(via
		(at 27.7114 -100.8888)
		(size 0.5588)
		(drill 0.3048)
		(layers "F.Cu" "B.Cu")
		(net "VR_FET_SW_P12V_STBY_PVCCIN_CPU1")
	)
	(via
		(at 27.0256 -101.5746)
		(size 0.5588)
		(drill 0.3048)
		(layers "F.Cu" "B.Cu")
		(net "VR_FET_SW_P12V_STBY_PVCCIN_CPU1")
	)
	(via
		(at 25.654 -101.5746)
		(size 0.5588)
		(drill 0.3048)
		(layers "F.Cu" "B.Cu")
		(net "VR_FET_SW_P12V_STBY_PVCCIN_CPU1")
	)
	(via
		(at 31.893002 -92.028264)
		(size 0.508)
		(drill 0.254)
		(layers "F.Cu" "B.Cu")
		(net "VR_FET_SW_P12V_STBY_PVCCIN_CPU1")
	)
	(via
		(at 31.893256 -60.405264)
		(size 0.5588)
		(drill 0.3048)
		(layers "F.Cu" "B.Cu")
		(net "VR_FET_SW_P12V_STBY_PVCCIN_CPU1")
	)
	(via
		(at 28.336494 -101.300026)
		(size 0.5588)
		(drill 0.3048)
		(layers "F.Cu" "B.Cu")
		(net "VR_FET_SW_P12V_STBY_PVCCIN_CPU1")
	)
	(via
		(at 31.893002 -57.687464)
		(size 0.508)
		(drill 0.254)
		(layers "F.Cu" "B.Cu")
		(net "VR_FET_SW_P12V_STBY_PVCCIN_CPU1")
	)
	(via
		(at 31.046674 -84.001864)
		(size 0.5588)
		(drill 0.3048)
		(layers "F.Cu" "B.Cu")
		(net "VR_FET_SW_P12V_STBY_PVCCIN_CPU1")
	)
	(via
		(at 24.8666 -49.403)
		(size 0.508)
		(drill 0.254)
		(layers "F.Cu" "B.Cu")
		(net "VR_FET_SW_P12V_STBY_PVCCIN_CPU1")
	)
	(via
		(at 30.988 -100.9904)
		(size 0.5588)
		(drill 0.3048)
		(layers "F.Cu" "B.Cu")
		(net "VR_FET_SW_P12V_STBY_PVCCIN_CPU1")
	)
	(via
		(at 31.122874 -68.533264)
		(size 0.5588)
		(drill 0.3048)
		(layers "F.Cu" "B.Cu")
		(net "VR_FET_SW_P12V_STBY_PVCCIN_CPU1")
	)
	(via
		(at 26.3398 -100.8888)
		(size 0.5588)
		(drill 0.3048)
		(layers "F.Cu" "B.Cu")
		(net "VR_FET_SW_P12V_STBY_PVCCIN_CPU1")
	)
	(via
		(at 31.877 -84.709)
		(size 0.5588)
		(drill 0.3048)
		(layers "F.Cu" "B.Cu")
		(net "VR_FET_SW_P12V_STBY_PVCCIN_CPU1")
	)
	(via
		(at 31.173674 -76.635864)
		(size 0.5588)
		(drill 0.3048)
		(layers "F.Cu" "B.Cu")
		(net "VR_FET_SW_P12V_STBY_PVCCIN_CPU1")
	)
	(via
		(at 31.867602 -68.533264)
		(size 0.5588)
		(drill 0.3048)
		(layers "F.Cu" "B.Cu")
		(net "VR_FET_SW_P12V_STBY_PVCCIN_CPU1")
	)
	(via
		(at 31.918402 -66.729864)
		(size 0.508)
		(drill 0.254)
		(layers "F.Cu" "B.Cu")
		(net "VR_FET_SW_P12V_STBY_PVCCIN_CPU1")
	)
	(via
		(at 31.072074 -92.129864)
		(size 0.5588)
		(drill 0.3048)
		(layers "F.Cu" "B.Cu")
		(net "VR_FET_SW_P12V_STBY_PVCCIN_CPU1")
	)
	(via
		(at 31.1404 -92.837)
		(size 0.5588)
		(drill 0.3048)
		(layers "F.Cu" "B.Cu")
		(net "VR_FET_SW_P12V_STBY_PVCCIN_CPU1")
	)
	(via
		(at 31.893002 -83.900264)
		(size 0.508)
		(drill 0.254)
		(layers "F.Cu" "B.Cu")
		(net "VR_FET_SW_P12V_STBY_PVCCIN_CPU1")
	)
	(via
		(at 31.893002 -90.199464)
		(size 0.508)
		(drill 0.254)
		(layers "F.Cu" "B.Cu")
		(net "VR_FET_SW_P12V_STBY_PVCCIN_CPU1")
	)
	(via
		(at 31.046674 -59.617864)
		(size 0.5588)
		(drill 0.3048)
		(layers "F.Cu" "B.Cu")
		(net "VR_FET_SW_P12V_STBY_PVCCIN_CPU1")
	)
	(via
		(at 26.62428 -51.3334)
		(size 0.508)
		(drill 0.254)
		(layers "F.Cu" "B.Cu")
		(net "VR_FET_SW_P12V_STBY_PVCCIN_CPU1")
	)
	(via
		(at 31.148528 -60.405264)
		(size 0.5588)
		(drill 0.3048)
		(layers "F.Cu" "B.Cu")
		(net "VR_FET_SW_P12V_STBY_PVCCIN_CPU1")
	)
	(via
		(at 31.046674 -75.873864)
		(size 0.5588)
		(drill 0.3048)
		(layers "F.Cu" "B.Cu")
		(net "VR_FET_SW_P12V_STBY_PVCCIN_CPU1")
	)
	(via
		(at 31.173674 -84.814664)
		(size 0.5588)
		(drill 0.3048)
		(layers "F.Cu" "B.Cu")
		(net "VR_FET_SW_P12V_STBY_PVCCIN_CPU1")
	)
	(via
		(at 24.8412 -51.0032)
		(size 0.508)
		(drill 0.254)
		(layers "F.Cu" "B.Cu")
		(net "VR_FET_SW_P12V_STBY_PVCCIN_CPU1")
	)
	(via
		(at 31.918402 -74.857864)
		(size 0.508)
		(drill 0.254)
		(layers "F.Cu" "B.Cu")
		(net "VR_FET_SW_P12V_STBY_PVCCIN_CPU1")
	)
	(via
		(at 31.893002 -82.071464)
		(size 0.508)
		(drill 0.254)
		(layers "F.Cu" "B.Cu")
		(net "VR_FET_SW_P12V_STBY_PVCCIN_CPU1")
	)
	(via
		(at 24.8412 -50.1904)
		(size 0.508)
		(drill 0.254)
		(layers "F.Cu" "B.Cu")
		(net "VR_FET_SW_P12V_STBY_PVCCIN_CPU1")
	)
	(via
		(at 31.918402 -82.985864)
		(size 0.508)
		(drill 0.254)
		(layers "F.Cu" "B.Cu")
		(net "VR_FET_SW_P12V_STBY_PVCCIN_CPU1")
	)
	(via
		(at 31.893002 -73.943464)
		(size 0.508)
		(drill 0.254)
		(layers "F.Cu" "B.Cu")
		(net "VR_FET_SW_P12V_STBY_PVCCIN_CPU1")
	)
	(via
		(at 31.893002 -59.516264)
		(size 0.508)
		(drill 0.254)
		(layers "F.Cu" "B.Cu")
		(net "VR_FET_SW_P12V_STBY_PVCCIN_CPU1")
	)
	(via
		(at 27.0256 -100.8888)
		(size 0.5588)
		(drill 0.3048)
		(layers "F.Cu" "B.Cu")
		(net "VR_FET_SW_P12V_STBY_PVCCIN_CPU1")
	)
	(via
		(at 31.893002 -75.772264)
		(size 0.508)
		(drill 0.254)
		(layers "F.Cu" "B.Cu")
		(net "VR_FET_SW_P12V_STBY_PVCCIN_CPU1")
	)
	(via
		(at 26.3398 -101.5746)
		(size 0.5588)
		(drill 0.3048)
		(layers "F.Cu" "B.Cu")
		(net "VR_FET_SW_P12V_STBY_PVCCIN_CPU1")
	)
	(via
		(at 31.046674 -67.745864)
		(size 0.5588)
		(drill 0.3048)
		(layers "F.Cu" "B.Cu")
		(net "VR_FET_SW_P12V_STBY_PVCCIN_CPU1")
	)
	(via
		(at 31.918402 -91.113864)
		(size 0.508)
		(drill 0.254)
		(layers "F.Cu" "B.Cu")
		(net "VR_FET_SW_P12V_STBY_PVCCIN_CPU1")
	)
	(via
		(at 31.893002 -67.644264)
		(size 0.508)
		(drill 0.254)
		(layers "F.Cu" "B.Cu")
		(net "VR_FET_SW_P12V_STBY_PVCCIN_CPU1")
	)
	(via
		(at 31.8262 -101.0158)
		(size 0.5588)
		(drill 0.3048)
		(layers "F.Cu" "B.Cu")
		(net "VR_FET_SW_P12V_STBY_PVCCIN_CPU1")
	)
	(via
		(at 31.893002 -65.815464)
		(size 0.508)
		(drill 0.254)
		(layers "F.Cu" "B.Cu")
		(net "VR_FET_SW_P12V_STBY_PVCCIN_CPU1")
	)
	(via
		(at 31.918402 -76.635864)
		(size 0.5588)
		(drill 0.3048)
		(layers "F.Cu" "B.Cu")
		(net "VR_FET_SW_P12V_STBY_PVCCIN_CPU1")
	)
	(via
		(at 26.62428 -50.4952)
		(size 0.508)
		(drill 0.254)
		(layers "F.Cu" "B.Cu")
		(net "VR_FET_SW_P12V_STBY_PVCCIN_CPU1")
	)
	(via
		(at 27.43454 -104.515666)
		(size 0.5588)
		(drill 0.3048)
		(layers "F.Cu" "B.Cu")
		(net "VR_FET_SW_P12V_STBY_PVCCIN_CPU1")
	)
	(via
		(at 31.046674 -100.257864)
		(size 0.5588)
		(drill 0.3048)
		(layers "F.Cu" "B.Cu")
		(net "VR_FET_SW_P12V_STBY_PVCCIN_CPU1")
	)
	(via
		(at 27.7114 -101.5746)
		(size 0.5588)
		(drill 0.3048)
		(layers "F.Cu" "B.Cu")
		(net "VR_FET_SW_P12V_STBY_PVCCIN_CPU1")
	)
	(via
		(at 26.547318 -103.194866)
		(size 0.5588)
		(drill 0.3048)
		(layers "F.Cu" "B.Cu")
		(net "VR_FET_SW_P12V_STBY_PVCCIN_CPU1")
	)
	(via
		(at 31.893002 -100.156264)
		(size 0.508)
		(drill 0.254)
		(layers "F.Cu" "B.Cu")
		(net "VR_FET_SW_P12V_STBY_PVCCIN_CPU1")
	)
	(segment
		(start 373.544846 -71.895208)
		(end 373.14505 -72.295004)
		(width 0.1016)
		(layer "F.Cu")
		(net "SGPIO_BMC_DIN_R")
	)
	(via
		(at 373.544846 -71.895208)
		(size 0.4572)
		(drill 0.2032)
		(layers "F.Cu" "B.Cu")
		(net "SGPIO_BMC_DIN_R")
	)
	(via
		(at 372.737126 -70.485)
		(size 0.6604)
		(drill 0.3302)
		(layers "F.Cu" "B.Cu")
		(net "SGPIO_BMC_DIN_R")
	)
	(segment
		(start 373.203978 -67.3862)
		(end 372.953788 -67.63639)
		(width 0.10795)
		(layer "B.Cu")
		(net "SGPIO_BMC_DIN_R")
	)
	(segment
		(start 372.737126 -70.026022)
		(end 372.737126 -70.485)
		(width 0.10795)
		(layer "B.Cu")
		(net "SGPIO_BMC_DIN_R")
	)
	(segment
		(start 372.737126 -71.087488)
		(end 372.737126 -70.485)
		(width 0.10795)
		(layer "B.Cu")
		(net "SGPIO_BMC_DIN_R")
	)
	(segment
		(start 373.016018 -68.015612)
		(end 373.016018 -69.74713)
		(width 0.10795)
		(layer "B.Cu")
		(net "SGPIO_BMC_DIN_R")
	)
	(segment
		(start 372.953788 -67.63639)
		(end 372.953788 -67.953382)
		(width 0.10795)
		(layer "B.Cu")
		(net "SGPIO_BMC_DIN_R")
	)
	(segment
		(start 373.6848 -67.3862)
		(end 373.203978 -67.3862)
		(width 0.10795)
		(layer "B.Cu")
		(net "SGPIO_BMC_DIN_R")
	)
	(segment
		(start 372.953788 -67.953382)
		(end 373.016018 -68.015612)
		(width 0.10795)
		(layer "B.Cu")
		(net "SGPIO_BMC_DIN_R")
	)
	(segment
		(start 373.016018 -69.74713)
		(end 372.737126 -70.026022)
		(width 0.10795)
		(layer "B.Cu")
		(net "SGPIO_BMC_DIN_R")
	)
	(segment
		(start 373.888 -66.929)
		(end 373.888 -67.183)
		(width 0.10795)
		(layer "B.Cu")
		(net "SGPIO_BMC_DIN_R")
	)
	(segment
		(start 373.544846 -71.895208)
		(end 372.737126 -71.087488)
		(width 0.10795)
		(layer "B.Cu")
		(net "SGPIO_BMC_DIN_R")
	)
	(segment
		(start 373.888 -67.183)
		(end 373.6848 -67.3862)
		(width 0.10795)
		(layer "B.Cu")
		(net "SGPIO_BMC_DIN_R")
	)
	(segment
		(start 384.76555 -121.01576)
		(end 385.26085 -121.245884)
		(width 0.1143)
		(layer "F.Cu")
		(net "SATA6G_PCH_PCIE_UP_SATA_RXP<7>")
	)
	(via
		(at 407.382726 -153.5303)
		(size 0.508)
		(drill 0.254)
		(layers "F.Cu" "B.Cu")
		(net "SATA6G_PCH_PCIE_UP_SATA_RXP<7>")
	)
	(via
		(at 385.26085 -121.245884)
		(size 0.508)
		(drill 0.254)
		(layers "F.Cu" "B.Cu")
		(net "SATA6G_PCH_PCIE_UP_SATA_RXP<7>")
	)
	(segment
		(start 407.382726 -153.80335)
		(end 407.382726 -153.5303)
		(width 0.1143)
		(layer "B.Cu")
		(net "SATA6G_PCH_PCIE_UP_SATA_RXP<7>")
	)
	(segment
		(start 407.617168 -153.91765)
		(end 407.497026 -153.91765)
		(width 0.1143)
		(layer "B.Cu")
		(net "SATA6G_PCH_PCIE_UP_SATA_RXP<7>")
	)
	(segment
		(start 408.1526 -153.5938)
		(end 407.97861 -153.76779)
		(width 0.1143)
		(layer "B.Cu")
		(net "SATA6G_PCH_PCIE_UP_SATA_RXP<7>")
	)
	(arc
		(start 407.497026 -153.91765)
		(mid 407.416204 -153.884172)
		(end 407.382726 -153.80335)
		(width 0.1143)
		(layer "B.Cu")
		(net "SATA6G_PCH_PCIE_UP_SATA_RXP<7>")
	)
	(arc
		(start 407.97861 -153.76779)
		(mid 407.812794 -153.878678)
		(end 407.617168 -153.91765)
		(width 0.1143)
		(layer "B.Cu")
		(net "SATA6G_PCH_PCIE_UP_SATA_RXP<7>")
	)
	(segment
		(start 402.844254 -142.907512)
		(end 402.844254 -142.564612)
		(width 0.1143)
		(layer "In9.Cu")
		(net "SATA6G_PCH_PCIE_UP_SATA_RXP<7>")
	)
	(segment
		(start 403.735286 -150.478998)
		(end 403.381972 -150.478998)
		(width 0.1143)
		(layer "In9.Cu")
		(net "SATA6G_PCH_PCIE_UP_SATA_RXP<7>")
	)
	(segment
		(start 402.679154 -149.77618)
		(end 402.679154 -149.43328)
		(width 0.1143)
		(layer "In9.Cu")
		(net "SATA6G_PCH_PCIE_UP_SATA_RXP<7>")
	)
	(segment
		(start 397.20901 -137.856722)
		(end 392.466322 -137.856722)
		(width 0.1143)
		(layer "In9.Cu")
		(net "SATA6G_PCH_PCIE_UP_SATA_RXP<7>")
	)
	(segment
		(start 402.844254 -149.10308)
		(end 402.844254 -148.76018)
		(width 0.1143)
		(layer "In9.Cu")
		(net "SATA6G_PCH_PCIE_UP_SATA_RXP<7>")
	)
	(segment
		(start 382.50114 -127.699262)
		(end 382.500886 -127.699516)
		(width 0.1143)
		(layer "In9.Cu")
		(net "SATA6G_PCH_PCIE_UP_SATA_RXP<7>")
	)
	(segment
		(start 389.15594 -136.197594)
		(end 385.186428 -132.228082)
		(width 0.1143)
		(layer "In9.Cu")
		(net "SATA6G_PCH_PCIE_UP_SATA_RXP<7>")
	)
	(segment
		(start 398.787874 -136.761728)
		(end 398.035018 -137.514584)
		(width 0.1143)
		(layer "In9.Cu")
		(net "SATA6G_PCH_PCIE_UP_SATA_RXP<7>")
	)
	(segment
		(start 402.679154 -146.028664)
		(end 402.679154 -143.237712)
		(width 0.1143)
		(layer "In9.Cu")
		(net "SATA6G_PCH_PCIE_UP_SATA_RXP<7>")
	)
	(segment
		(start 402.844254 -146.701764)
		(end 402.844254 -146.358864)
		(width 0.1143)
		(layer "In9.Cu")
		(net "SATA6G_PCH_PCIE_UP_SATA_RXP<7>")
	)
	(segment
		(start 404.783036 -152.09266)
		(end 404.783036 -151.526748)
		(width 0.1143)
		(layer "In9.Cu")
		(net "SATA6G_PCH_PCIE_UP_SATA_RXP<7>")
	)
	(segment
		(start 392.466322 -137.336022)
		(end 396.560802 -137.336022)
		(width 0.1143)
		(layer "In9.Cu")
		(net "SATA6G_PCH_PCIE_UP_SATA_RXP<7>")
	)
	(segment
		(start 382.692148 -128.101344)
		(end 382.64973 -128.058672)
		(width 0.1143)
		(layer "In9.Cu")
		(net "SATA6G_PCH_PCIE_UP_SATA_RXP<7>")
	)
	(segment
		(start 384.039364 -128.219454)
		(end 382.97739 -128.219454)
		(width 0.1143)
		(layer "In9.Cu")
		(net "SATA6G_PCH_PCIE_UP_SATA_RXP<7>")
	)
	(segment
		(start 406.973532 -153.89225)
		(end 406.582626 -153.89225)
		(width 0.1143)
		(layer "In9.Cu")
		(net "SATA6G_PCH_PCIE_UP_SATA_RXP<7>")
	)
	(segment
		(start 384.3655 -122.125994)
		(end 384.3655 -122.093228)
		(width 0.0889)
		(layer "In9.Cu")
		(net "SATA6G_PCH_PCIE_UP_SATA_RXP<7>")
	)
	(segment
		(start 384.924808 -130.970528)
		(end 384.701288 -130.747008)
		(width 0.1143)
		(layer "In9.Cu")
		(net "SATA6G_PCH_PCIE_UP_SATA_RXP<7>")
	)
	(segment
		(start 382.500886 -127.699516)
		(end 382.500886 -126.556008)
		(width 0.1143)
		(layer "In9.Cu")
		(net "SATA6G_PCH_PCIE_UP_SATA_RXP<7>")
	)
	(segment
		(start 406.142698 -153.26614)
		(end 405.900128 -153.02357)
		(width 0.1143)
		(layer "In9.Cu")
		(net "SATA6G_PCH_PCIE_UP_SATA_RXP<7>")
	)
	(segment
		(start 402.679154 -148.42998)
		(end 402.679154 -147.031964)
		(width 0.1143)
		(layer "In9.Cu")
		(net "SATA6G_PCH_PCIE_UP_SATA_RXP<7>")
	)
	(segment
		(start 403.743668 -137.379456)
		(end 403.743668 -136.671558)
		(width 0.1143)
		(layer "In9.Cu")
		(net "SATA6G_PCH_PCIE_UP_SATA_RXP<7>")
	)
	(segment
		(start 384.610864 -130.529584)
		(end 384.610864 -128.790954)
		(width 0.1143)
		(layer "In9.Cu")
		(net "SATA6G_PCH_PCIE_UP_SATA_RXP<7>")
	)
	(segment
		(start 404.66391 -151.23922)
		(end 404.02256 -150.59787)
		(width 0.1143)
		(layer "In9.Cu")
		(net "SATA6G_PCH_PCIE_UP_SATA_RXP<7>")
	)
	(segment
		(start 403.3012 -150.44547)
		(end 402.712682 -149.856952)
		(width 0.1143)
		(layer "In9.Cu")
		(net "SATA6G_PCH_PCIE_UP_SATA_RXP<7>")
	)
	(segment
		(start 402.94179 -138.63828)
		(end 403.420834 -138.158982)
		(width 0.1143)
		(layer "In9.Cu")
		(net "SATA6G_PCH_PCIE_UP_SATA_RXP<7>")
	)
	(segment
		(start 383.3749 -124.2568)
		(end 383.3749 -123.810268)
		(width 0.0889)
		(layer "In9.Cu")
		(net "SATA6G_PCH_PCIE_UP_SATA_RXP<7>")
	)
	(segment
		(start 406.501854 -153.858722)
		(end 406.259284 -153.616152)
		(width 0.1143)
		(layer "In9.Cu")
		(net "SATA6G_PCH_PCIE_UP_SATA_RXP<7>")
	)
	(segment
		(start 405.549862 -152.90673)
		(end 404.816564 -152.173432)
		(width 0.1143)
		(layer "In9.Cu")
		(net "SATA6G_PCH_PCIE_UP_SATA_RXP<7>")
	)
	(segment
		(start 396.560802 -136.231122)
		(end 389.236966 -136.231122)
		(width 0.1143)
		(layer "In9.Cu")
		(net "SATA6G_PCH_PCIE_UP_SATA_RXP<7>")
	)
	(segment
		(start 385.1529 -132.14731)
		(end 385.1529 -131.520946)
		(width 0.1143)
		(layer "In9.Cu")
		(net "SATA6G_PCH_PCIE_UP_SATA_RXP<7>")
	)
	(segment
		(start 384.857752 -121.310908)
		(end 384.863848 -121.304812)
		(width 0.0889)
		(layer "In9.Cu")
		(net "SATA6G_PCH_PCIE_UP_SATA_RXP<7>")
	)
	(segment
		(start 382.54813 -126.44247)
		(end 383.306574 -125.684026)
		(width 0.1143)
		(layer "In9.Cu")
		(net "SATA6G_PCH_PCIE_UP_SATA_RXP<7>")
	)
	(segment
		(start 407.382726 -153.5303)
		(end 407.054304 -153.858722)
		(width 0.1143)
		(layer "In9.Cu")
		(net "SATA6G_PCH_PCIE_UP_SATA_RXP<7>")
	)
	(segment
		(start 383.4257 -125.396498)
		(end 383.4257 -124.329698)
		(width 0.1143)
		(layer "In9.Cu")
		(net "SATA6G_PCH_PCIE_UP_SATA_RXP<7>")
	)
	(segment
		(start 383.4257 -124.329698)
		(end 383.4257 -124.3076)
		(width 0.0889)
		(layer "In9.Cu")
		(net "SATA6G_PCH_PCIE_UP_SATA_RXP<7>")
	)
	(segment
		(start 385.006088 -121.245884)
		(end 385.26085 -121.245884)
		(width 0.0889)
		(layer "In9.Cu")
		(net "SATA6G_PCH_PCIE_UP_SATA_RXP<7>")
	)
	(segment
		(start 383.8702 -122.984514)
		(end 383.8702 -122.951748)
		(width 0.0889)
		(layer "In9.Cu")
		(net "SATA6G_PCH_PCIE_UP_SATA_RXP<7>")
	)
	(segment
		(start 383.4257 -124.3076)
		(end 383.3749 -124.2568)
		(width 0.0889)
		(layer "In9.Cu")
		(net "SATA6G_PCH_PCIE_UP_SATA_RXP<7>")
	)
	(segment
		(start 402.679154 -142.234412)
		(end 402.679154 -139.272264)
		(width 0.1143)
		(layer "In9.Cu")
		(net "SATA6G_PCH_PCIE_UP_SATA_RXP<7>")
	)
	(segment
		(start 403.321012 -135.650478)
		(end 403.320758 -135.650224)
		(width 0.1143)
		(layer "In9.Cu")
		(net "SATA6G_PCH_PCIE_UP_SATA_RXP<7>")
	)
	(arc
		(start 402.761704 -146.866864)
		(mid 402.82153 -146.793583)
		(end 402.844254 -146.701764)
		(width 0.1143)
		(layer "In9.Cu")
		(net "SATA6G_PCH_PCIE_UP_SATA_RXP<7>")
	)
	(arc
		(start 382.64973 -128.058672)
		(mid 382.539685 -127.893744)
		(end 382.50114 -127.699262)
		(width 0.1143)
		(layer "In9.Cu")
		(net "SATA6G_PCH_PCIE_UP_SATA_RXP<7>")
	)
	(arc
		(start 406.259284 -153.616152)
		(mid 406.210575 -153.535171)
		(end 406.201118 -153.441146)
		(width 0.1143)
		(layer "In9.Cu")
		(net "SATA6G_PCH_PCIE_UP_SATA_RXP<7>")
	)
	(arc
		(start 383.8702 -122.951748)
		(mid 383.92655 -122.757898)
		(end 384.070352 -122.616214)
		(width 0.0889)
		(layer "In9.Cu")
		(net "SATA6G_PCH_PCIE_UP_SATA_RXP<7>")
	)
	(arc
		(start 385.186428 -132.228082)
		(mid 385.161666 -132.191023)
		(end 385.1529 -132.14731)
		(width 0.1143)
		(layer "In9.Cu")
		(net "SATA6G_PCH_PCIE_UP_SATA_RXP<7>")
	)
	(arc
		(start 384.701288 -130.747008)
		(mid 384.634497 -130.647282)
		(end 384.610864 -130.529584)
		(width 0.1143)
		(layer "In9.Cu")
		(net "SATA6G_PCH_PCIE_UP_SATA_RXP<7>")
	)
	(arc
		(start 405.725122 -152.96515)
		(mid 405.630929 -152.955629)
		(end 405.549862 -152.90673)
		(width 0.1143)
		(layer "In9.Cu")
		(net "SATA6G_PCH_PCIE_UP_SATA_RXP<7>")
	)
	(arc
		(start 403.381972 -150.478998)
		(mid 403.338231 -150.470297)
		(end 403.3012 -150.44547)
		(width 0.1143)
		(layer "In9.Cu")
		(net "SATA6G_PCH_PCIE_UP_SATA_RXP<7>")
	)
	(arc
		(start 382.97739 -128.219454)
		(mid 382.823034 -128.188751)
		(end 382.692148 -128.101344)
		(width 0.1143)
		(layer "In9.Cu")
		(net "SATA6G_PCH_PCIE_UP_SATA_RXP<7>")
	)
	(arc
		(start 404.02256 -150.59787)
		(mid 403.890729 -150.50991)
		(end 403.735286 -150.478998)
		(width 0.1143)
		(layer "In9.Cu")
		(net "SATA6G_PCH_PCIE_UP_SATA_RXP<7>")
	)
	(arc
		(start 402.761704 -143.072612)
		(mid 402.82153 -142.999331)
		(end 402.844254 -142.907512)
		(width 0.1143)
		(layer "In9.Cu")
		(net "SATA6G_PCH_PCIE_UP_SATA_RXP<7>")
	)
	(arc
		(start 389.236966 -136.231122)
		(mid 389.193128 -136.222402)
		(end 389.15594 -136.197594)
		(width 0.1143)
		(layer "In9.Cu")
		(net "SATA6G_PCH_PCIE_UP_SATA_RXP<7>")
	)
	(arc
		(start 384.610864 -128.790954)
		(mid 384.443476 -128.386842)
		(end 384.039364 -128.219454)
		(width 0.1143)
		(layer "In9.Cu")
		(net "SATA6G_PCH_PCIE_UP_SATA_RXP<7>")
	)
	(arc
		(start 402.679154 -139.272264)
		(mid 402.747405 -138.929142)
		(end 402.94179 -138.63828)
		(width 0.1143)
		(layer "In9.Cu")
		(net "SATA6G_PCH_PCIE_UP_SATA_RXP<7>")
	)
	(arc
		(start 392.466322 -137.856722)
		(mid 392.205972 -137.596372)
		(end 392.466322 -137.336022)
		(width 0.1143)
		(layer "In9.Cu")
		(net "SATA6G_PCH_PCIE_UP_SATA_RXP<7>")
	)
	(arc
		(start 402.761704 -148.59508)
		(mid 402.701878 -148.521799)
		(end 402.679154 -148.42998)
		(width 0.1143)
		(layer "In9.Cu")
		(net "SATA6G_PCH_PCIE_UP_SATA_RXP<7>")
	)
	(arc
		(start 406.582626 -153.89225)
		(mid 406.538885 -153.883549)
		(end 406.501854 -153.858722)
		(width 0.1143)
		(layer "In9.Cu")
		(net "SATA6G_PCH_PCIE_UP_SATA_RXP<7>")
	)
	(arc
		(start 402.712682 -149.856952)
		(mid 402.68792 -149.819893)
		(end 402.679154 -149.77618)
		(width 0.1143)
		(layer "In9.Cu")
		(net "SATA6G_PCH_PCIE_UP_SATA_RXP<7>")
	)
	(arc
		(start 382.500886 -126.556008)
		(mid 382.513223 -126.494547)
		(end 382.54813 -126.44247)
		(width 0.1143)
		(layer "In9.Cu")
		(net "SATA6G_PCH_PCIE_UP_SATA_RXP<7>")
	)
	(arc
		(start 400.153124 -135.918956)
		(mid 399.421348 -136.260719)
		(end 398.787874 -136.761728)
		(width 0.1143)
		(layer "In9.Cu")
		(net "SATA6G_PCH_PCIE_UP_SATA_RXP<7>")
	)
	(arc
		(start 385.1529 -131.520946)
		(mid 385.093572 -131.223063)
		(end 384.924808 -130.970528)
		(width 0.1143)
		(layer "In9.Cu")
		(net "SATA6G_PCH_PCIE_UP_SATA_RXP<7>")
	)
	(arc
		(start 403.743668 -136.671558)
		(mid 403.633853 -136.11901)
		(end 403.321012 -135.650478)
		(width 0.1143)
		(layer "In9.Cu")
		(net "SATA6G_PCH_PCIE_UP_SATA_RXP<7>")
	)
	(arc
		(start 405.900128 -153.02357)
		(mid 405.819181 -152.974711)
		(end 405.725122 -152.96515)
		(width 0.1143)
		(layer "In9.Cu")
		(net "SATA6G_PCH_PCIE_UP_SATA_RXP<7>")
	)
	(arc
		(start 402.761704 -149.26818)
		(mid 402.82153 -149.194899)
		(end 402.844254 -149.10308)
		(width 0.1143)
		(layer "In9.Cu")
		(net "SATA6G_PCH_PCIE_UP_SATA_RXP<7>")
	)
	(arc
		(start 398.035018 -137.514584)
		(mid 397.656042 -137.767807)
		(end 397.20901 -137.856722)
		(width 0.1143)
		(layer "In9.Cu")
		(net "SATA6G_PCH_PCIE_UP_SATA_RXP<7>")
	)
	(arc
		(start 402.844254 -146.358864)
		(mid 402.821486 -146.267067)
		(end 402.761704 -146.193764)
		(width 0.1143)
		(layer "In9.Cu")
		(net "SATA6G_PCH_PCIE_UP_SATA_RXP<7>")
	)
	(arc
		(start 402.761704 -146.193764)
		(mid 402.701878 -146.120483)
		(end 402.679154 -146.028664)
		(width 0.1143)
		(layer "In9.Cu")
		(net "SATA6G_PCH_PCIE_UP_SATA_RXP<7>")
	)
	(arc
		(start 384.565652 -121.757694)
		(mid 384.765025 -121.569166)
		(end 384.857752 -121.310908)
		(width 0.0889)
		(layer "In9.Cu")
		(net "SATA6G_PCH_PCIE_UP_SATA_RXP<7>")
	)
	(arc
		(start 383.3749 -123.810268)
		(mid 383.43125 -123.616418)
		(end 383.575052 -123.474734)
		(width 0.0889)
		(layer "In9.Cu")
		(net "SATA6G_PCH_PCIE_UP_SATA_RXP<7>")
	)
	(arc
		(start 403.420834 -138.158982)
		(mid 403.659754 -137.801318)
		(end 403.743668 -137.379456)
		(width 0.1143)
		(layer "In9.Cu")
		(net "SATA6G_PCH_PCIE_UP_SATA_RXP<7>")
	)
	(arc
		(start 384.3655 -122.093228)
		(mid 384.42185 -121.899378)
		(end 384.565652 -121.757694)
		(width 0.0889)
		(layer "In9.Cu")
		(net "SATA6G_PCH_PCIE_UP_SATA_RXP<7>")
	)
	(arc
		(start 383.306574 -125.684026)
		(mid 383.394719 -125.552107)
		(end 383.4257 -125.396498)
		(width 0.1143)
		(layer "In9.Cu")
		(net "SATA6G_PCH_PCIE_UP_SATA_RXP<7>")
	)
	(arc
		(start 406.201118 -153.441146)
		(mid 406.191528 -153.347097)
		(end 406.142698 -153.26614)
		(width 0.1143)
		(layer "In9.Cu")
		(net "SATA6G_PCH_PCIE_UP_SATA_RXP<7>")
	)
	(arc
		(start 404.816564 -152.173432)
		(mid 404.791802 -152.136373)
		(end 404.783036 -152.09266)
		(width 0.1143)
		(layer "In9.Cu")
		(net "SATA6G_PCH_PCIE_UP_SATA_RXP<7>")
	)
	(arc
		(start 402.212556 -135.1915)
		(mid 401.753238 -135.244909)
		(end 401.32127 -135.40994)
		(width 0.1143)
		(layer "In9.Cu")
		(net "SATA6G_PCH_PCIE_UP_SATA_RXP<7>")
	)
	(arc
		(start 383.575052 -123.474734)
		(mid 383.785916 -123.26773)
		(end 383.8702 -122.984514)
		(width 0.0889)
		(layer "In9.Cu")
		(net "SATA6G_PCH_PCIE_UP_SATA_RXP<7>")
	)
	(arc
		(start 402.679154 -143.237712)
		(mid 402.701922 -143.145915)
		(end 402.761704 -143.072612)
		(width 0.1143)
		(layer "In9.Cu")
		(net "SATA6G_PCH_PCIE_UP_SATA_RXP<7>")
	)
	(arc
		(start 402.844254 -148.76018)
		(mid 402.821486 -148.668383)
		(end 402.761704 -148.59508)
		(width 0.1143)
		(layer "In9.Cu")
		(net "SATA6G_PCH_PCIE_UP_SATA_RXP<7>")
	)
	(arc
		(start 402.679154 -147.031964)
		(mid 402.701922 -146.940167)
		(end 402.761704 -146.866864)
		(width 0.1143)
		(layer "In9.Cu")
		(net "SATA6G_PCH_PCIE_UP_SATA_RXP<7>")
	)
	(arc
		(start 403.320758 -135.650224)
		(mid 402.812281 -135.310627)
		(end 402.212556 -135.1915)
		(width 0.1143)
		(layer "In9.Cu")
		(net "SATA6G_PCH_PCIE_UP_SATA_RXP<7>")
	)
	(arc
		(start 402.761704 -142.399512)
		(mid 402.701878 -142.326231)
		(end 402.679154 -142.234412)
		(width 0.1143)
		(layer "In9.Cu")
		(net "SATA6G_PCH_PCIE_UP_SATA_RXP<7>")
	)
	(arc
		(start 402.844254 -142.564612)
		(mid 402.821486 -142.472815)
		(end 402.761704 -142.399512)
		(width 0.1143)
		(layer "In9.Cu")
		(net "SATA6G_PCH_PCIE_UP_SATA_RXP<7>")
	)
	(arc
		(start 384.070352 -122.616214)
		(mid 384.281216 -122.40921)
		(end 384.3655 -122.125994)
		(width 0.0889)
		(layer "In9.Cu")
		(net "SATA6G_PCH_PCIE_UP_SATA_RXP<7>")
	)
	(arc
		(start 384.863848 -121.304812)
		(mid 384.929108 -121.261206)
		(end 385.006088 -121.245884)
		(width 0.0889)
		(layer "In9.Cu")
		(net "SATA6G_PCH_PCIE_UP_SATA_RXP<7>")
	)
	(arc
		(start 407.054304 -153.858722)
		(mid 407.01726 -153.883538)
		(end 406.973532 -153.89225)
		(width 0.1143)
		(layer "In9.Cu")
		(net "SATA6G_PCH_PCIE_UP_SATA_RXP<7>")
	)
	(arc
		(start 401.32127 -135.40994)
		(mid 400.747219 -135.687448)
		(end 400.153124 -135.918956)
		(width 0.1143)
		(layer "In9.Cu")
		(net "SATA6G_PCH_PCIE_UP_SATA_RXP<7>")
	)
	(arc
		(start 402.679154 -149.43328)
		(mid 402.701922 -149.341483)
		(end 402.761704 -149.26818)
		(width 0.1143)
		(layer "In9.Cu")
		(net "SATA6G_PCH_PCIE_UP_SATA_RXP<7>")
	)
	(arc
		(start 396.560802 -137.336022)
		(mid 397.113252 -136.783572)
		(end 396.560802 -136.231122)
		(width 0.1143)
		(layer "In9.Cu")
		(net "SATA6G_PCH_PCIE_UP_SATA_RXP<7>")
	)
	(arc
		(start 404.783036 -151.526748)
		(mid 404.752066 -151.371142)
		(end 404.66391 -151.23922)
		(width 0.1143)
		(layer "In9.Cu")
		(net "SATA6G_PCH_PCIE_UP_SATA_RXP<7>")
	)
	(segment
		(start 388.72795 -121.01576)
		(end 389.22325 -121.245884)
		(width 0.10795)
		(layer "F.Cu")
		(net "SATA6G_PCH_PCIE_UP_SATA_RXP<6>")
	)
	(via
		(at 407.395426 -150.5585)
		(size 0.508)
		(drill 0.254)
		(layers "F.Cu" "B.Cu")
		(net "SATA6G_PCH_PCIE_UP_SATA_RXP<6>")
	)
	(via
		(at 389.22325 -121.245884)
		(size 0.508)
		(drill 0.254)
		(layers "F.Cu" "B.Cu")
		(net "SATA6G_PCH_PCIE_UP_SATA_RXP<6>")
	)
	(segment
		(start 408.305 -150.622)
		(end 408.014678 -150.912322)
		(width 0.1143)
		(layer "B.Cu")
		(net "SATA6G_PCH_PCIE_UP_SATA_RXP<6>")
	)
	(segment
		(start 407.395426 -150.83155)
		(end 407.395426 -150.5585)
		(width 0.1143)
		(layer "B.Cu")
		(net "SATA6G_PCH_PCIE_UP_SATA_RXP<6>")
	)
	(segment
		(start 407.933906 -150.94585)
		(end 407.509726 -150.94585)
		(width 0.1143)
		(layer "B.Cu")
		(net "SATA6G_PCH_PCIE_UP_SATA_RXP<6>")
	)
	(arc
		(start 408.014678 -150.912322)
		(mid 407.977619 -150.937084)
		(end 407.933906 -150.94585)
		(width 0.1143)
		(layer "B.Cu")
		(net "SATA6G_PCH_PCIE_UP_SATA_RXP<6>")
	)
	(arc
		(start 407.509726 -150.94585)
		(mid 407.428904 -150.912372)
		(end 407.395426 -150.83155)
		(width 0.1143)
		(layer "B.Cu")
		(net "SATA6G_PCH_PCIE_UP_SATA_RXP<6>")
	)
	(segment
		(start 404.353268 -141.900656)
		(end 405.886666 -140.367258)
		(width 0.1143)
		(layer "In9.Cu")
		(net "SATA6G_PCH_PCIE_UP_SATA_RXP<6>")
	)
	(segment
		(start 403.337014 -132.80644)
		(end 403.258274 -132.884926)
		(width 0.1143)
		(layer "In9.Cu")
		(net "SATA6G_PCH_PCIE_UP_SATA_RXP<6>")
	)
	(segment
		(start 389.263128 -121.256552)
		(end 389.22325 -121.245884)
		(width 0.0889)
		(layer "In9.Cu")
		(net "SATA6G_PCH_PCIE_UP_SATA_RXP<6>")
	)
	(segment
		(start 405.711152 -150.10384)
		(end 405.94915 -149.867112)
		(width 0.1143)
		(layer "In9.Cu")
		(net "SATA6G_PCH_PCIE_UP_SATA_RXP<6>")
	)
	(segment
		(start 403.337014 -132.806186)
		(end 403.337014 -132.80644)
		(width 0.1143)
		(layer "In9.Cu")
		(net "SATA6G_PCH_PCIE_UP_SATA_RXP<6>")
	)
	(segment
		(start 404.18893 -142.296896)
		(end 404.189184 -142.29715)
		(width 0.1143)
		(layer "In9.Cu")
		(net "SATA6G_PCH_PCIE_UP_SATA_RXP<6>")
	)
	(segment
		(start 385.9784 -131.591558)
		(end 385.9784 -130.626866)
		(width 0.1143)
		(layer "In9.Cu")
		(net "SATA6G_PCH_PCIE_UP_SATA_RXP<6>")
	)
	(segment
		(start 387.33349 -133.173978)
		(end 387.09092 -132.931408)
		(width 0.1143)
		(layer "In9.Cu")
		(net "SATA6G_PCH_PCIE_UP_SATA_RXP<6>")
	)
	(segment
		(start 405.167846 -149.085046)
		(end 404.867618 -149.38502)
		(width 0.1143)
		(layer "In9.Cu")
		(net "SATA6G_PCH_PCIE_UP_SATA_RXP<6>")
	)
	(segment
		(start 389.276082 -121.261378)
		(end 389.263128 -121.256552)
		(width 0.0889)
		(layer "In9.Cu")
		(net "SATA6G_PCH_PCIE_UP_SATA_RXP<6>")
	)
	(segment
		(start 404.886668 -139.787122)
		(end 403.935438 -140.737844)
		(width 0.1143)
		(layer "In9.Cu")
		(net "SATA6G_PCH_PCIE_UP_SATA_RXP<6>")
	)
	(segment
		(start 385.265422 -125.728476)
		(end 384.433318 -124.896118)
		(width 0.0889)
		(layer "In9.Cu")
		(net "SATA6G_PCH_PCIE_UP_SATA_RXP<6>")
	)
	(segment
		(start 386.381498 -132.221986)
		(end 386.138928 -131.979416)
		(width 0.1143)
		(layer "In9.Cu")
		(net "SATA6G_PCH_PCIE_UP_SATA_RXP<6>")
	)
	(segment
		(start 403.695154 -144.81175)
		(end 403.827742 -144.81175)
		(width 0.1143)
		(layer "In9.Cu")
		(net "SATA6G_PCH_PCIE_UP_SATA_RXP<6>")
	)
	(segment
		(start 387.926072 -133.533134)
		(end 387.683502 -133.290564)
		(width 0.1143)
		(layer "In9.Cu")
		(net "SATA6G_PCH_PCIE_UP_SATA_RXP<6>")
	)
	(segment
		(start 397.177768 -135.403844)
		(end 389.610092 -135.403844)
		(width 0.1143)
		(layer "In9.Cu")
		(net "SATA6G_PCH_PCIE_UP_SATA_RXP<6>")
	)
	(segment
		(start 405.083518 -136.364726)
		(end 405.083518 -139.312904)
		(width 0.1143)
		(layer "In9.Cu")
		(net "SATA6G_PCH_PCIE_UP_SATA_RXP<6>")
	)
	(segment
		(start 404.711916 -148.547074)
		(end 404.711916 -148.204174)
		(width 0.1143)
		(layer "In9.Cu")
		(net "SATA6G_PCH_PCIE_UP_SATA_RXP<6>")
	)
	(segment
		(start 385.398264 -126.72568)
		(end 385.398264 -126.703582)
		(width 0.0889)
		(layer "In9.Cu")
		(net "SATA6G_PCH_PCIE_UP_SATA_RXP<6>")
	)
	(segment
		(start 407.395426 -150.5585)
		(end 407.068274 -150.885652)
		(width 0.1143)
		(layer "In9.Cu")
		(net "SATA6G_PCH_PCIE_UP_SATA_RXP<6>")
	)
	(segment
		(start 404.259542 -134.634478)
		(end 404.259542 -134.634224)
		(width 0.1143)
		(layer "In9.Cu")
		(net "SATA6G_PCH_PCIE_UP_SATA_RXP<6>")
	)
	(segment
		(start 406.987502 -150.91918)
		(end 406.142952 -150.91918)
		(width 0.1143)
		(layer "In9.Cu")
		(net "SATA6G_PCH_PCIE_UP_SATA_RXP<6>")
	)
	(segment
		(start 385.739132 -130.048508)
		(end 385.496816 -129.806192)
		(width 0.1143)
		(layer "In9.Cu")
		(net "SATA6G_PCH_PCIE_UP_SATA_RXP<6>")
	)
	(segment
		(start 404.546816 -147.873974)
		(end 404.546816 -147.2946)
		(width 0.1143)
		(layer "In9.Cu")
		(net "SATA6G_PCH_PCIE_UP_SATA_RXP<6>")
	)
	(segment
		(start 388.878064 -134.485126)
		(end 388.635494 -134.242556)
		(width 0.1143)
		(layer "In9.Cu")
		(net "SATA6G_PCH_PCIE_UP_SATA_RXP<6>")
	)
	(segment
		(start 388.285482 -134.12597)
		(end 388.042912 -133.8834)
		(width 0.1143)
		(layer "In9.Cu")
		(net "SATA6G_PCH_PCIE_UP_SATA_RXP<6>")
	)
	(segment
		(start 389.320278 -120.857772)
		(end 389.412226 -120.881394)
		(width 0.0889)
		(layer "In9.Cu")
		(net "SATA6G_PCH_PCIE_UP_SATA_RXP<6>")
	)
	(segment
		(start 406.06218 -150.885652)
		(end 405.710898 -150.53437)
		(width 0.1143)
		(layer "In9.Cu")
		(net "SATA6G_PCH_PCIE_UP_SATA_RXP<6>")
	)
	(segment
		(start 406.188418 -139.638024)
		(end 406.188418 -136.364726)
		(width 0.1143)
		(layer "In9.Cu")
		(net "SATA6G_PCH_PCIE_UP_SATA_RXP<6>")
	)
	(segment
		(start 403.63521 -132.50799)
		(end 403.337014 -132.806186)
		(width 0.1143)
		(layer "In9.Cu")
		(net "SATA6G_PCH_PCIE_UP_SATA_RXP<6>")
	)
	(segment
		(start 386.97408 -132.581142)
		(end 386.73151 -132.338572)
		(width 0.1143)
		(layer "In9.Cu")
		(net "SATA6G_PCH_PCIE_UP_SATA_RXP<6>")
	)
	(segment
		(start 404.259542 -134.634224)
		(end 403.768814 -134.143496)
		(width 0.1143)
		(layer "In9.Cu")
		(net "SATA6G_PCH_PCIE_UP_SATA_RXP<6>")
	)
	(segment
		(start 384.3655 -124.732542)
		(end 384.3655 -123.810268)
		(width 0.0889)
		(layer "In9.Cu")
		(net "SATA6G_PCH_PCIE_UP_SATA_RXP<6>")
	)
	(segment
		(start 404.18893 -146.430746)
		(end 404.18893 -145.762726)
		(width 0.1143)
		(layer "In9.Cu")
		(net "SATA6G_PCH_PCIE_UP_SATA_RXP<6>")
	)
	(segment
		(start 404.546816 -149.220174)
		(end 404.546816 -148.877274)
		(width 0.1143)
		(layer "In9.Cu")
		(net "SATA6G_PCH_PCIE_UP_SATA_RXP<6>")
	)
	(segment
		(start 385.398264 -126.703582)
		(end 385.347464 -126.652782)
		(width 0.0889)
		(layer "In9.Cu")
		(net "SATA6G_PCH_PCIE_UP_SATA_RXP<6>")
	)
	(segment
		(start 385.8514 -121.267474)
		(end 385.8514 -121.234708)
		(width 0.0889)
		(layer "In9.Cu")
		(net "SATA6G_PCH_PCIE_UP_SATA_RXP<6>")
	)
	(segment
		(start 404.562818 -138.973052)
		(end 404.562818 -135.3947)
		(width 0.1143)
		(layer "In9.Cu")
		(net "SATA6G_PCH_PCIE_UP_SATA_RXP<6>")
	)
	(segment
		(start 403.695154 -143.31315)
		(end 403.75967 -143.31315)
		(width 0.1143)
		(layer "In9.Cu")
		(net "SATA6G_PCH_PCIE_UP_SATA_RXP<6>")
	)
	(segment
		(start 404.66391 -149.38502)
		(end 404.580598 -149.301708)
		(width 0.1143)
		(layer "In9.Cu")
		(net "SATA6G_PCH_PCIE_UP_SATA_RXP<6>")
	)
	(segment
		(start 403.768814 -133.93674)
		(end 404.41626 -133.289294)
		(width 0.1143)
		(layer "In9.Cu")
		(net "SATA6G_PCH_PCIE_UP_SATA_RXP<6>")
	)
	(segment
		(start 385.398264 -129.568448)
		(end 385.398264 -126.72568)
		(width 0.1143)
		(layer "In9.Cu")
		(net "SATA6G_PCH_PCIE_UP_SATA_RXP<6>")
	)
	(segment
		(start 404.887176 -139.787122)
		(end 404.886668 -139.787122)
		(width 0.1143)
		(layer "In9.Cu")
		(net "SATA6G_PCH_PCIE_UP_SATA_RXP<6>")
	)
	(segment
		(start 404.18893 -142.88389)
		(end 404.18893 -142.296896)
		(width 0.1143)
		(layer "In9.Cu")
		(net "SATA6G_PCH_PCIE_UP_SATA_RXP<6>")
	)
	(segment
		(start 385.3561 -122.125994)
		(end 385.3561 -122.093228)
		(width 0.0889)
		(layer "In9.Cu")
		(net "SATA6G_PCH_PCIE_UP_SATA_RXP<6>")
	)
	(segment
		(start 384.8608 -122.984514)
		(end 384.8608 -122.951748)
		(width 0.0889)
		(layer "In9.Cu")
		(net "SATA6G_PCH_PCIE_UP_SATA_RXP<6>")
	)
	(segment
		(start 389.529574 -135.370062)
		(end 388.994904 -134.835392)
		(width 0.1143)
		(layer "In9.Cu")
		(net "SATA6G_PCH_PCIE_UP_SATA_RXP<6>")
	)
	(segment
		(start 404.26132 -134.637272)
		(end 404.259542 -134.634478)
		(width 0.1143)
		(layer "In9.Cu")
		(net "SATA6G_PCH_PCIE_UP_SATA_RXP<6>")
	)
	(segment
		(start 385.347464 -126.652782)
		(end 385.347464 -125.926596)
		(width 0.0889)
		(layer "In9.Cu")
		(net "SATA6G_PCH_PCIE_UP_SATA_RXP<6>")
	)
	(segment
		(start 403.552406 -140.385546)
		(end 404.2791 -139.658852)
		(width 0.1143)
		(layer "In9.Cu")
		(net "SATA6G_PCH_PCIE_UP_SATA_RXP<6>")
	)
	(segment
		(start 404.18893 -144.450562)
		(end 404.18893 -144.264126)
		(width 0.1143)
		(layer "In9.Cu")
		(net "SATA6G_PCH_PCIE_UP_SATA_RXP<6>")
	)
	(arc
		(start 403.75967 -143.31315)
		(mid 404.063203 -143.187423)
		(end 404.18893 -142.88389)
		(width 0.1143)
		(layer "In9.Cu")
		(net "SATA6G_PCH_PCIE_UP_SATA_RXP<6>")
	)
	(arc
		(start 389.254746 -120.847104)
		(mid 389.287734 -120.851075)
		(end 389.320278 -120.857772)
		(width 0.0889)
		(layer "In9.Cu")
		(net "SATA6G_PCH_PCIE_UP_SATA_RXP<6>")
	)
	(arc
		(start 403.935438 -140.737844)
		(mid 403.743922 -140.817173)
		(end 403.552406 -140.737844)
		(width 0.1143)
		(layer "In9.Cu")
		(net "SATA6G_PCH_PCIE_UP_SATA_RXP<6>")
	)
	(arc
		(start 385.556252 -121.757694)
		(mid 385.767116 -121.55069)
		(end 385.8514 -121.267474)
		(width 0.0889)
		(layer "In9.Cu")
		(net "SATA6G_PCH_PCIE_UP_SATA_RXP<6>")
	)
	(arc
		(start 385.496816 -129.806192)
		(mid 385.423879 -129.697128)
		(end 385.398264 -129.568448)
		(width 0.1143)
		(layer "In9.Cu")
		(net "SATA6G_PCH_PCIE_UP_SATA_RXP<6>")
	)
	(arc
		(start 385.347464 -125.926596)
		(mid 385.326176 -125.819372)
		(end 385.265422 -125.728476)
		(width 0.0889)
		(layer "In9.Cu")
		(net "SATA6G_PCH_PCIE_UP_SATA_RXP<6>")
	)
	(arc
		(start 404.30323 -146.70659)
		(mid 404.218666 -146.580032)
		(end 404.18893 -146.430746)
		(width 0.1143)
		(layer "In9.Cu")
		(net "SATA6G_PCH_PCIE_UP_SATA_RXP<6>")
	)
	(arc
		(start 405.94915 -149.867112)
		(mid 405.949595 -149.085236)
		(end 405.167846 -149.085046)
		(width 0.1143)
		(layer "In9.Cu")
		(net "SATA6G_PCH_PCIE_UP_SATA_RXP<6>")
	)
	(arc
		(start 404.711916 -148.204174)
		(mid 404.689148 -148.112377)
		(end 404.629366 -148.039074)
		(width 0.1143)
		(layer "In9.Cu")
		(net "SATA6G_PCH_PCIE_UP_SATA_RXP<6>")
	)
	(arc
		(start 386.556504 -132.280152)
		(mid 386.462481 -132.270687)
		(end 386.381498 -132.221986)
		(width 0.1143)
		(layer "In9.Cu")
		(net "SATA6G_PCH_PCIE_UP_SATA_RXP<6>")
	)
	(arc
		(start 389.412226 -120.881394)
		(mid 389.419812 -120.88352)
		(end 389.427212 -120.88622)
		(width 0.0889)
		(layer "In9.Cu")
		(net "SATA6G_PCH_PCIE_UP_SATA_RXP<6>")
	)
	(arc
		(start 405.886666 -140.367258)
		(mid 406.110085 -140.032653)
		(end 406.188418 -139.638024)
		(width 0.1143)
		(layer "In9.Cu")
		(net "SATA6G_PCH_PCIE_UP_SATA_RXP<6>")
	)
	(arc
		(start 406.142952 -150.91918)
		(mid 406.099211 -150.910479)
		(end 406.06218 -150.885652)
		(width 0.1143)
		(layer "In9.Cu")
		(net "SATA6G_PCH_PCIE_UP_SATA_RXP<6>")
	)
	(arc
		(start 387.683502 -133.290564)
		(mid 387.602555 -133.241705)
		(end 387.508496 -133.232144)
		(width 0.1143)
		(layer "In9.Cu")
		(net "SATA6G_PCH_PCIE_UP_SATA_RXP<6>")
	)
	(arc
		(start 384.433318 -124.896118)
		(mid 384.383118 -124.821083)
		(end 384.3655 -124.732542)
		(width 0.0889)
		(layer "In9.Cu")
		(net "SATA6G_PCH_PCIE_UP_SATA_RXP<6>")
	)
	(arc
		(start 403.827742 -144.81175)
		(mid 404.08314 -144.70596)
		(end 404.18893 -144.450562)
		(width 0.1143)
		(layer "In9.Cu")
		(net "SATA6G_PCH_PCIE_UP_SATA_RXP<6>")
	)
	(arc
		(start 387.441948 -120.899174)
		(mid 387.73735 -120.978305)
		(end 388.032752 -120.899174)
		(width 0.0889)
		(layer "In9.Cu")
		(net "SATA6G_PCH_PCIE_UP_SATA_RXP<6>")
	)
	(arc
		(start 388.994904 -134.835392)
		(mid 388.946005 -134.754325)
		(end 388.936484 -134.660132)
		(width 0.1143)
		(layer "In9.Cu")
		(net "SATA6G_PCH_PCIE_UP_SATA_RXP<6>")
	)
	(arc
		(start 405.083518 -139.312904)
		(mid 405.03249 -139.56953)
		(end 404.887176 -139.787122)
		(width 0.1143)
		(layer "In9.Cu")
		(net "SATA6G_PCH_PCIE_UP_SATA_RXP<6>")
	)
	(arc
		(start 386.451348 -120.899174)
		(mid 386.74675 -120.978305)
		(end 387.042152 -120.899174)
		(width 0.0889)
		(layer "In9.Cu")
		(net "SATA6G_PCH_PCIE_UP_SATA_RXP<6>")
	)
	(arc
		(start 385.8514 -121.234708)
		(mid 386.056102 -120.896593)
		(end 386.451348 -120.899174)
		(width 0.0889)
		(layer "In9.Cu")
		(net "SATA6G_PCH_PCIE_UP_SATA_RXP<6>")
	)
	(arc
		(start 404.41626 -133.289294)
		(mid 404.416451 -132.50818)
		(end 403.63521 -132.50799)
		(width 0.1143)
		(layer "In9.Cu")
		(net "SATA6G_PCH_PCIE_UP_SATA_RXP<6>")
	)
	(arc
		(start 388.635494 -134.242556)
		(mid 388.554547 -134.193697)
		(end 388.460488 -134.184136)
		(width 0.1143)
		(layer "In9.Cu")
		(net "SATA6G_PCH_PCIE_UP_SATA_RXP<6>")
	)
	(arc
		(start 404.629366 -148.712174)
		(mid 404.689192 -148.638893)
		(end 404.711916 -148.547074)
		(width 0.1143)
		(layer "In9.Cu")
		(net "SATA6G_PCH_PCIE_UP_SATA_RXP<6>")
	)
	(arc
		(start 404.629366 -148.039074)
		(mid 404.56954 -147.965793)
		(end 404.546816 -147.873974)
		(width 0.1143)
		(layer "In9.Cu")
		(net "SATA6G_PCH_PCIE_UP_SATA_RXP<6>")
	)
	(arc
		(start 385.9784 -130.626866)
		(mid 385.91626 -130.313906)
		(end 385.739132 -130.048508)
		(width 0.1143)
		(layer "In9.Cu")
		(net "SATA6G_PCH_PCIE_UP_SATA_RXP<6>")
	)
	(arc
		(start 386.73151 -132.338572)
		(mid 386.650563 -132.289713)
		(end 386.556504 -132.280152)
		(width 0.1143)
		(layer "In9.Cu")
		(net "SATA6G_PCH_PCIE_UP_SATA_RXP<6>")
	)
	(arc
		(start 388.936484 -134.660132)
		(mid 388.926894 -134.566083)
		(end 388.878064 -134.485126)
		(width 0.1143)
		(layer "In9.Cu")
		(net "SATA6G_PCH_PCIE_UP_SATA_RXP<6>")
	)
	(arc
		(start 404.562818 -135.3947)
		(mid 404.484579 -134.987125)
		(end 404.26132 -134.637272)
		(width 0.1143)
		(layer "In9.Cu")
		(net "SATA6G_PCH_PCIE_UP_SATA_RXP<6>")
	)
	(arc
		(start 387.0325 -132.756148)
		(mid 387.02291 -132.662099)
		(end 386.97408 -132.581142)
		(width 0.1143)
		(layer "In9.Cu")
		(net "SATA6G_PCH_PCIE_UP_SATA_RXP<6>")
	)
	(arc
		(start 403.695154 -145.26895)
		(mid 403.466554 -145.04035)
		(end 403.695154 -144.81175)
		(width 0.1143)
		(layer "In9.Cu")
		(net "SATA6G_PCH_PCIE_UP_SATA_RXP<6>")
	)
	(arc
		(start 407.068274 -150.885652)
		(mid 407.031215 -150.910414)
		(end 406.987502 -150.91918)
		(width 0.1143)
		(layer "In9.Cu")
		(net "SATA6G_PCH_PCIE_UP_SATA_RXP<6>")
	)
	(arc
		(start 405.710898 -150.53437)
		(mid 405.621711 -150.319052)
		(end 405.711152 -150.10384)
		(width 0.1143)
		(layer "In9.Cu")
		(net "SATA6G_PCH_PCIE_UP_SATA_RXP<6>")
	)
	(arc
		(start 404.546816 -147.2946)
		(mid 404.483515 -146.976362)
		(end 404.30323 -146.70659)
		(width 0.1143)
		(layer "In9.Cu")
		(net "SATA6G_PCH_PCIE_UP_SATA_RXP<6>")
	)
	(arc
		(start 404.18893 -144.264126)
		(mid 404.044306 -143.914974)
		(end 403.695154 -143.77035)
		(width 0.1143)
		(layer "In9.Cu")
		(net "SATA6G_PCH_PCIE_UP_SATA_RXP<6>")
	)
	(arc
		(start 387.09092 -132.931408)
		(mid 387.042021 -132.850341)
		(end 387.0325 -132.756148)
		(width 0.1143)
		(layer "In9.Cu")
		(net "SATA6G_PCH_PCIE_UP_SATA_RXP<6>")
	)
	(arc
		(start 404.2791 -139.658852)
		(mid 404.489204 -139.344175)
		(end 404.562818 -138.973052)
		(width 0.1143)
		(layer "In9.Cu")
		(net "SATA6G_PCH_PCIE_UP_SATA_RXP<6>")
	)
	(arc
		(start 406.188418 -136.364726)
		(mid 405.635968 -135.812276)
		(end 405.083518 -136.364726)
		(width 0.1143)
		(layer "In9.Cu")
		(net "SATA6G_PCH_PCIE_UP_SATA_RXP<6>")
	)
	(arc
		(start 384.565652 -123.474734)
		(mid 384.776516 -123.26773)
		(end 384.8608 -122.984514)
		(width 0.0889)
		(layer "In9.Cu")
		(net "SATA6G_PCH_PCIE_UP_SATA_RXP<6>")
	)
	(arc
		(start 388.432548 -120.899174)
		(mid 388.72795 -120.978305)
		(end 389.023352 -120.899174)
		(width 0.0889)
		(layer "In9.Cu")
		(net "SATA6G_PCH_PCIE_UP_SATA_RXP<6>")
	)
	(arc
		(start 403.768814 -134.143496)
		(mid 403.725993 -134.040118)
		(end 403.768814 -133.93674)
		(width 0.1143)
		(layer "In9.Cu")
		(net "SATA6G_PCH_PCIE_UP_SATA_RXP<6>")
	)
	(arc
		(start 387.984492 -133.70814)
		(mid 387.974902 -133.614091)
		(end 387.926072 -133.533134)
		(width 0.1143)
		(layer "In9.Cu")
		(net "SATA6G_PCH_PCIE_UP_SATA_RXP<6>")
	)
	(arc
		(start 404.580598 -149.301708)
		(mid 404.555603 -149.2643)
		(end 404.546816 -149.220174)
		(width 0.1143)
		(layer "In9.Cu")
		(net "SATA6G_PCH_PCIE_UP_SATA_RXP<6>")
	)
	(arc
		(start 384.8608 -122.951748)
		(mid 384.91715 -122.757898)
		(end 385.060952 -122.616214)
		(width 0.0889)
		(layer "In9.Cu")
		(net "SATA6G_PCH_PCIE_UP_SATA_RXP<6>")
	)
	(arc
		(start 387.508496 -133.232144)
		(mid 387.414473 -133.222679)
		(end 387.33349 -133.173978)
		(width 0.1143)
		(layer "In9.Cu")
		(net "SATA6G_PCH_PCIE_UP_SATA_RXP<6>")
	)
	(arc
		(start 387.042152 -120.899174)
		(mid 387.24205 -120.845675)
		(end 387.441948 -120.899174)
		(width 0.0889)
		(layer "In9.Cu")
		(net "SATA6G_PCH_PCIE_UP_SATA_RXP<6>")
	)
	(arc
		(start 403.552406 -140.737844)
		(mid 403.47957 -140.561732)
		(end 403.552406 -140.385546)
		(width 0.1143)
		(layer "In9.Cu")
		(net "SATA6G_PCH_PCIE_UP_SATA_RXP<6>")
	)
	(arc
		(start 403.258274 -132.884926)
		(mid 400.468529 -134.749067)
		(end 397.177768 -135.403844)
		(width 0.1143)
		(layer "In9.Cu")
		(net "SATA6G_PCH_PCIE_UP_SATA_RXP<6>")
	)
	(arc
		(start 404.189184 -142.29715)
		(mid 404.23184 -142.082612)
		(end 404.353268 -141.900656)
		(width 0.1143)
		(layer "In9.Cu")
		(net "SATA6G_PCH_PCIE_UP_SATA_RXP<6>")
	)
	(arc
		(start 404.867618 -149.38502)
		(mid 404.765764 -149.427209)
		(end 404.66391 -149.38502)
		(width 0.1143)
		(layer "In9.Cu")
		(net "SATA6G_PCH_PCIE_UP_SATA_RXP<6>")
	)
	(arc
		(start 388.042912 -133.8834)
		(mid 387.994013 -133.802333)
		(end 387.984492 -133.70814)
		(width 0.1143)
		(layer "In9.Cu")
		(net "SATA6G_PCH_PCIE_UP_SATA_RXP<6>")
	)
	(arc
		(start 386.138928 -131.979416)
		(mid 386.020186 -131.801423)
		(end 385.9784 -131.591558)
		(width 0.1143)
		(layer "In9.Cu")
		(net "SATA6G_PCH_PCIE_UP_SATA_RXP<6>")
	)
	(arc
		(start 388.460488 -134.184136)
		(mid 388.366465 -134.174671)
		(end 388.285482 -134.12597)
		(width 0.1143)
		(layer "In9.Cu")
		(net "SATA6G_PCH_PCIE_UP_SATA_RXP<6>")
	)
	(arc
		(start 403.695154 -143.77035)
		(mid 403.466554 -143.54175)
		(end 403.695154 -143.31315)
		(width 0.1143)
		(layer "In9.Cu")
		(net "SATA6G_PCH_PCIE_UP_SATA_RXP<6>")
	)
	(arc
		(start 388.032752 -120.899174)
		(mid 388.23265 -120.845675)
		(end 388.432548 -120.899174)
		(width 0.0889)
		(layer "In9.Cu")
		(net "SATA6G_PCH_PCIE_UP_SATA_RXP<6>")
	)
	(arc
		(start 384.3655 -123.810268)
		(mid 384.42185 -123.616418)
		(end 384.565652 -123.474734)
		(width 0.0889)
		(layer "In9.Cu")
		(net "SATA6G_PCH_PCIE_UP_SATA_RXP<6>")
	)
	(arc
		(start 404.546816 -148.877274)
		(mid 404.569584 -148.785477)
		(end 404.629366 -148.712174)
		(width 0.1143)
		(layer "In9.Cu")
		(net "SATA6G_PCH_PCIE_UP_SATA_RXP<6>")
	)
	(arc
		(start 385.3561 -122.093228)
		(mid 385.41245 -121.899378)
		(end 385.556252 -121.757694)
		(width 0.0889)
		(layer "In9.Cu")
		(net "SATA6G_PCH_PCIE_UP_SATA_RXP<6>")
	)
	(arc
		(start 389.610092 -135.403844)
		(mid 389.566458 -135.394978)
		(end 389.529574 -135.370062)
		(width 0.1143)
		(layer "In9.Cu")
		(net "SATA6G_PCH_PCIE_UP_SATA_RXP<6>")
	)
	(arc
		(start 404.18893 -145.762726)
		(mid 404.044306 -145.413574)
		(end 403.695154 -145.26895)
		(width 0.1143)
		(layer "In9.Cu")
		(net "SATA6G_PCH_PCIE_UP_SATA_RXP<6>")
	)
	(arc
		(start 389.427212 -120.88622)
		(mid 389.539418 -121.149517)
		(end 389.276082 -121.261378)
		(width 0.0889)
		(layer "In9.Cu")
		(net "SATA6G_PCH_PCIE_UP_SATA_RXP<6>")
	)
	(arc
		(start 385.060952 -122.616214)
		(mid 385.271816 -122.40921)
		(end 385.3561 -122.125994)
		(width 0.0889)
		(layer "In9.Cu")
		(net "SATA6G_PCH_PCIE_UP_SATA_RXP<6>")
	)
	(arc
		(start 389.023352 -120.899174)
		(mid 389.135101 -120.855621)
		(end 389.254746 -120.847104)
		(width 0.0889)
		(layer "In9.Cu")
		(net "SATA6G_PCH_PCIE_UP_SATA_RXP<6>")
	)
	(segment
		(start 386.25145 -121.87428)
		(end 386.74675 -122.104404)
		(width 0.1143)
		(layer "F.Cu")
		(net "SATA6G_PCH_PCIE_UP_SATA_RXP<5>")
	)
	(via
		(at 409.790646 -152.2095)
		(size 0.508)
		(drill 0.254)
		(layers "F.Cu" "B.Cu")
		(net "SATA6G_PCH_PCIE_UP_SATA_RXP<5>")
	)
	(via
		(at 386.74675 -122.104404)
		(size 0.508)
		(drill 0.254)
		(layers "F.Cu" "B.Cu")
		(net "SATA6G_PCH_PCIE_UP_SATA_RXP<5>")
	)
	(segment
		(start 409.790646 -152.48255)
		(end 409.790646 -152.2095)
		(width 0.1143)
		(layer "B.Cu")
		(net "SATA6G_PCH_PCIE_UP_SATA_RXP<5>")
	)
	(segment
		(start 410.092652 -152.59685)
		(end 409.904946 -152.59685)
		(width 0.1143)
		(layer "B.Cu")
		(net "SATA6G_PCH_PCIE_UP_SATA_RXP<5>")
	)
	(segment
		(start 410.464 -152.273)
		(end 410.173678 -152.563322)
		(width 0.1143)
		(layer "B.Cu")
		(net "SATA6G_PCH_PCIE_UP_SATA_RXP<5>")
	)
	(segment
		(start 410.173678 -152.563322)
		(end 410.147516 -152.58288)
		(width 0.1143)
		(layer "B.Cu")
		(net "SATA6G_PCH_PCIE_UP_SATA_RXP<5>")
	)
	(arc
		(start 409.904946 -152.59685)
		(mid 409.824124 -152.563372)
		(end 409.790646 -152.48255)
		(width 0.1143)
		(layer "B.Cu")
		(net "SATA6G_PCH_PCIE_UP_SATA_RXP<5>")
	)
	(arc
		(start 410.09443 -152.59685)
		(mid 410.093541 -152.596849)
		(end 410.092652 -152.59685)
		(width 0.1143)
		(layer "B.Cu")
		(net "SATA6G_PCH_PCIE_UP_SATA_RXP<5>")
	)
	(arc
		(start 410.147516 -152.58288)
		(mid 410.121822 -152.593094)
		(end 410.09443 -152.59685)
		(width 0.1143)
		(layer "B.Cu")
		(net "SATA6G_PCH_PCIE_UP_SATA_RXP<5>")
	)
	(segment
		(start 407.263346 -140.130784)
		(end 407.064972 -140.329158)
		(width 0.1143)
		(layer "In9.Cu")
		(net "SATA6G_PCH_PCIE_UP_SATA_RXP<5>")
	)
	(segment
		(start 408.39263 -150.395686)
		(end 408.39263 -151.909018)
		(width 0.1143)
		(layer "In9.Cu")
		(net "SATA6G_PCH_PCIE_UP_SATA_RXP<5>")
	)
	(segment
		(start 409.462224 -152.537922)
		(end 409.790646 -152.2095)
		(width 0.1143)
		(layer "In9.Cu")
		(net "SATA6G_PCH_PCIE_UP_SATA_RXP<5>")
	)
	(segment
		(start 388.83082 -133.205474)
		(end 389.07339 -133.448044)
		(width 0.1143)
		(layer "In9.Cu")
		(net "SATA6G_PCH_PCIE_UP_SATA_RXP<5>")
	)
	(segment
		(start 386.74675 -122.104404)
		(end 386.77469 -122.115072)
		(width 0.0889)
		(layer "In9.Cu")
		(net "SATA6G_PCH_PCIE_UP_SATA_RXP<5>")
	)
	(segment
		(start 407.709624 -138.538712)
		(end 407.709624 -136.97712)
		(width 0.1143)
		(layer "In9.Cu")
		(net "SATA6G_PCH_PCIE_UP_SATA_RXP<5>")
	)
	(segment
		(start 387.519418 -131.660646)
		(end 387.761988 -131.903216)
		(width 0.1143)
		(layer "In9.Cu")
		(net "SATA6G_PCH_PCIE_UP_SATA_RXP<5>")
	)
	(segment
		(start 405.694388 -147.615656)
		(end 406.57526 -148.496528)
		(width 0.1143)
		(layer "In9.Cu")
		(net "SATA6G_PCH_PCIE_UP_SATA_RXP<5>")
	)
	(segment
		(start 385.382262 -124.109988)
		(end 386.060442 -124.788168)
		(width 0.0889)
		(layer "In9.Cu")
		(net "SATA6G_PCH_PCIE_UP_SATA_RXP<5>")
	)
	(segment
		(start 386.142484 -124.986034)
		(end 386.142484 -126.76251)
		(width 0.0889)
		(layer "In9.Cu")
		(net "SATA6G_PCH_PCIE_UP_SATA_RXP<5>")
	)
	(segment
		(start 408.208226 -135.87476)
		(end 407.90876 -135.87476)
		(width 0.1143)
		(layer "In9.Cu")
		(net "SATA6G_PCH_PCIE_UP_SATA_RXP<5>")
	)
	(segment
		(start 407.188924 -136.594596)
		(end 407.188924 -138.538712)
		(width 0.1143)
		(layer "In9.Cu")
		(net "SATA6G_PCH_PCIE_UP_SATA_RXP<5>")
	)
	(segment
		(start 390.201658 -134.4422)
		(end 397.100806 -134.4422)
		(width 0.1143)
		(layer "In9.Cu")
		(net "SATA6G_PCH_PCIE_UP_SATA_RXP<5>")
	)
	(segment
		(start 406.948132 -140.679424)
		(end 406.705562 -140.921994)
		(width 0.1143)
		(layer "In9.Cu")
		(net "SATA6G_PCH_PCIE_UP_SATA_RXP<5>")
	)
	(segment
		(start 386.926836 -131.30149)
		(end 387.169406 -131.54406)
		(width 0.1143)
		(layer "In9.Cu")
		(net "SATA6G_PCH_PCIE_UP_SATA_RXP<5>")
	)
	(segment
		(start 409.323032 -138.865864)
		(end 409.074874 -138.865864)
		(width 0.1143)
		(layer "In9.Cu")
		(net "SATA6G_PCH_PCIE_UP_SATA_RXP<5>")
	)
	(segment
		(start 386.193284 -126.81331)
		(end 386.193284 -126.835408)
		(width 0.0889)
		(layer "In9.Cu")
		(net "SATA6G_PCH_PCIE_UP_SATA_RXP<5>")
	)
	(segment
		(start 387.034024 -121.997978)
		(end 387.034024 -121.997724)
		(width 0.0889)
		(layer "In9.Cu")
		(net "SATA6G_PCH_PCIE_UP_SATA_RXP<5>")
	)
	(segment
		(start 387.878828 -132.253482)
		(end 388.121398 -132.496052)
		(width 0.1143)
		(layer "In9.Cu")
		(net "SATA6G_PCH_PCIE_UP_SATA_RXP<5>")
	)
	(segment
		(start 409.074874 -137.760964)
		(end 409.323032 -137.760964)
		(width 0.1143)
		(layer "In9.Cu")
		(net "SATA6G_PCH_PCIE_UP_SATA_RXP<5>")
	)
	(segment
		(start 388.47141 -132.612638)
		(end 388.71398 -132.855208)
		(width 0.1143)
		(layer "In9.Cu")
		(net "SATA6G_PCH_PCIE_UP_SATA_RXP<5>")
	)
	(segment
		(start 406.35555 -141.03858)
		(end 405.160988 -142.233142)
		(width 0.1143)
		(layer "In9.Cu")
		(net "SATA6G_PCH_PCIE_UP_SATA_RXP<5>")
	)
	(segment
		(start 386.346192 -129.527554)
		(end 386.346446 -129.527808)
		(width 0.1143)
		(layer "In9.Cu")
		(net "SATA6G_PCH_PCIE_UP_SATA_RXP<5>")
	)
	(segment
		(start 389.423402 -133.56463)
		(end 389.665972 -133.8072)
		(width 0.1143)
		(layer "In9.Cu")
		(net "SATA6G_PCH_PCIE_UP_SATA_RXP<5>")
	)
	(segment
		(start 405.651716 -146.378676)
		(end 405.651716 -147.512532)
		(width 0.1143)
		(layer "In9.Cu")
		(net "SATA6G_PCH_PCIE_UP_SATA_RXP<5>")
	)
	(segment
		(start 385.3561 -123.810268)
		(end 385.3561 -124.046996)
		(width 0.0889)
		(layer "In9.Cu")
		(net "SATA6G_PCH_PCIE_UP_SATA_RXP<5>")
	)
	(segment
		(start 408.814524 -133.585966)
		(end 408.814524 -135.268462)
		(width 0.1143)
		(layer "In9.Cu")
		(net "SATA6G_PCH_PCIE_UP_SATA_RXP<5>")
	)
	(segment
		(start 408.814524 -139.126214)
		(end 408.814524 -139.368784)
		(width 0.1143)
		(layer "In9.Cu")
		(net "SATA6G_PCH_PCIE_UP_SATA_RXP<5>")
	)
	(segment
		(start 386.142484 -126.76251)
		(end 386.193284 -126.81331)
		(width 0.0889)
		(layer "In9.Cu")
		(net "SATA6G_PCH_PCIE_UP_SATA_RXP<5>")
	)
	(segment
		(start 408.149044 -140.034264)
		(end 407.496264 -140.034264)
		(width 0.1143)
		(layer "In9.Cu")
		(net "SATA6G_PCH_PCIE_UP_SATA_RXP<5>")
	)
	(segment
		(start 386.777738 -130.568954)
		(end 386.777738 -130.941572)
		(width 0.1143)
		(layer "In9.Cu")
		(net "SATA6G_PCH_PCIE_UP_SATA_RXP<5>")
	)
	(segment
		(start 404.993348 -142.63751)
		(end 404.993348 -145.036794)
		(width 0.1143)
		(layer "In9.Cu")
		(net "SATA6G_PCH_PCIE_UP_SATA_RXP<5>")
	)
	(segment
		(start 407.851864 -149.686518)
		(end 408.273758 -150.108412)
		(width 0.1143)
		(layer "In9.Cu")
		(net "SATA6G_PCH_PCIE_UP_SATA_RXP<5>")
	)
	(segment
		(start 409.0162 -152.57145)
		(end 409.381452 -152.57145)
		(width 0.1143)
		(layer "In9.Cu")
		(net "SATA6G_PCH_PCIE_UP_SATA_RXP<5>")
	)
	(segment
		(start 385.8514 -122.951748)
		(end 385.8514 -122.984514)
		(width 0.0889)
		(layer "In9.Cu")
		(net "SATA6G_PCH_PCIE_UP_SATA_RXP<5>")
	)
	(segment
		(start 386.3467 -122.093228)
		(end 386.3467 -122.125994)
		(width 0.0889)
		(layer "In9.Cu")
		(net "SATA6G_PCH_PCIE_UP_SATA_RXP<5>")
	)
	(segment
		(start 386.193284 -129.159)
		(end 386.193538 -129.158746)
		(width 0.1143)
		(layer "In9.Cu")
		(net "SATA6G_PCH_PCIE_UP_SATA_RXP<5>")
	)
	(segment
		(start 403.038564 -131.982464)
		(end 403.333712 -131.687316)
		(width 0.1143)
		(layer "In9.Cu")
		(net "SATA6G_PCH_PCIE_UP_SATA_RXP<5>")
	)
	(segment
		(start 408.492198 -152.149302)
		(end 408.84221 -152.499314)
		(width 0.1143)
		(layer "In9.Cu")
		(net "SATA6G_PCH_PCIE_UP_SATA_RXP<5>")
	)
	(segment
		(start 408.814524 -136.97712)
		(end 408.814524 -137.500614)
		(width 0.1143)
		(layer "In9.Cu")
		(net "SATA6G_PCH_PCIE_UP_SATA_RXP<5>")
	)
	(segment
		(start 406.656286 -148.530056)
		(end 407.302208 -148.530056)
		(width 0.1143)
		(layer "In9.Cu")
		(net "SATA6G_PCH_PCIE_UP_SATA_RXP<5>")
	)
	(segment
		(start 389.782812 -134.157466)
		(end 389.972296 -134.347204)
		(width 0.1143)
		(layer "In9.Cu")
		(net "SATA6G_PCH_PCIE_UP_SATA_RXP<5>")
	)
	(segment
		(start 405.250904 -145.65884)
		(end 405.426164 -145.8341)
		(width 0.1143)
		(layer "In9.Cu")
		(net "SATA6G_PCH_PCIE_UP_SATA_RXP<5>")
	)
	(segment
		(start 407.818336 -149.046184)
		(end 407.818336 -149.605746)
		(width 0.1143)
		(layer "In9.Cu")
		(net "SATA6G_PCH_PCIE_UP_SATA_RXP<5>")
	)
	(segment
		(start 403.713188 -131.530344)
		(end 406.759156 -131.530344)
		(width 0.1143)
		(layer "In9.Cu")
		(net "SATA6G_PCH_PCIE_UP_SATA_RXP<5>")
	)
	(segment
		(start 386.193284 -126.835408)
		(end 386.193284 -129.159)
		(width 0.1143)
		(layer "In9.Cu")
		(net "SATA6G_PCH_PCIE_UP_SATA_RXP<5>")
	)
	(arc
		(start 408.814524 -135.268462)
		(mid 408.636943 -135.697179)
		(end 408.208226 -135.87476)
		(width 0.1143)
		(layer "In9.Cu")
		(net "SATA6G_PCH_PCIE_UP_SATA_RXP<5>")
	)
	(arc
		(start 389.665972 -133.8072)
		(mid 389.714831 -133.888147)
		(end 389.724392 -133.982206)
		(width 0.1143)
		(layer "In9.Cu")
		(net "SATA6G_PCH_PCIE_UP_SATA_RXP<5>")
	)
	(arc
		(start 407.188924 -138.538712)
		(mid 407.449274 -138.799062)
		(end 407.709624 -138.538712)
		(width 0.1143)
		(layer "In9.Cu")
		(net "SATA6G_PCH_PCIE_UP_SATA_RXP<5>")
	)
	(arc
		(start 389.724392 -133.982206)
		(mid 389.733913 -134.076399)
		(end 389.782812 -134.157466)
		(width 0.1143)
		(layer "In9.Cu")
		(net "SATA6G_PCH_PCIE_UP_SATA_RXP<5>")
	)
	(arc
		(start 408.39263 -151.909018)
		(mid 408.418515 -152.039059)
		(end 408.492198 -152.149302)
		(width 0.1143)
		(layer "In9.Cu")
		(net "SATA6G_PCH_PCIE_UP_SATA_RXP<5>")
	)
	(arc
		(start 407.709624 -136.97712)
		(mid 408.262074 -136.42467)
		(end 408.814524 -136.97712)
		(width 0.1143)
		(layer "In9.Cu")
		(net "SATA6G_PCH_PCIE_UP_SATA_RXP<5>")
	)
	(arc
		(start 385.3561 -124.046996)
		(mid 385.362902 -124.0811)
		(end 385.382262 -124.109988)
		(width 0.0889)
		(layer "In9.Cu")
		(net "SATA6G_PCH_PCIE_UP_SATA_RXP<5>")
	)
	(arc
		(start 387.761988 -131.903216)
		(mid 387.810847 -131.984163)
		(end 387.820408 -132.078222)
		(width 0.1143)
		(layer "In9.Cu")
		(net "SATA6G_PCH_PCIE_UP_SATA_RXP<5>")
	)
	(arc
		(start 388.71398 -132.855208)
		(mid 388.762839 -132.936155)
		(end 388.7724 -133.030214)
		(width 0.1143)
		(layer "In9.Cu")
		(net "SATA6G_PCH_PCIE_UP_SATA_RXP<5>")
	)
	(arc
		(start 404.993348 -145.036794)
		(mid 405.060289 -145.373417)
		(end 405.250904 -145.65884)
		(width 0.1143)
		(layer "In9.Cu")
		(net "SATA6G_PCH_PCIE_UP_SATA_RXP<5>")
	)
	(arc
		(start 386.820156 -121.711212)
		(mid 386.772587 -121.705288)
		(end 386.724652 -121.705116)
		(width 0.0889)
		(layer "In9.Cu")
		(net "SATA6G_PCH_PCIE_UP_SATA_RXP<5>")
	)
	(arc
		(start 386.3467 -122.125994)
		(mid 386.262419 -122.409211)
		(end 386.051552 -122.616214)
		(width 0.0889)
		(layer "In9.Cu")
		(net "SATA6G_PCH_PCIE_UP_SATA_RXP<5>")
	)
	(arc
		(start 406.759156 -131.530344)
		(mid 408.212536 -132.132512)
		(end 408.814524 -133.585966)
		(width 0.1143)
		(layer "In9.Cu")
		(net "SATA6G_PCH_PCIE_UP_SATA_RXP<5>")
	)
	(arc
		(start 387.344412 -131.602226)
		(mid 387.438461 -131.611816)
		(end 387.519418 -131.660646)
		(width 0.1143)
		(layer "In9.Cu")
		(net "SATA6G_PCH_PCIE_UP_SATA_RXP<5>")
	)
	(arc
		(start 385.556252 -123.474734)
		(mid 385.412448 -123.616417)
		(end 385.3561 -123.810268)
		(width 0.0889)
		(layer "In9.Cu")
		(net "SATA6G_PCH_PCIE_UP_SATA_RXP<5>")
	)
	(arc
		(start 386.051552 -122.616214)
		(mid 385.907748 -122.757897)
		(end 385.8514 -122.951748)
		(width 0.0889)
		(layer "In9.Cu")
		(net "SATA6G_PCH_PCIE_UP_SATA_RXP<5>")
	)
	(arc
		(start 386.060442 -124.788168)
		(mid 386.121154 -124.878935)
		(end 386.142484 -124.986034)
		(width 0.0889)
		(layer "In9.Cu")
		(net "SATA6G_PCH_PCIE_UP_SATA_RXP<5>")
	)
	(arc
		(start 408.814524 -137.500614)
		(mid 408.890779 -137.684709)
		(end 409.074874 -137.760964)
		(width 0.1143)
		(layer "In9.Cu")
		(net "SATA6G_PCH_PCIE_UP_SATA_RXP<5>")
	)
	(arc
		(start 406.705562 -140.921994)
		(mid 406.624615 -140.970853)
		(end 406.530556 -140.980414)
		(width 0.1143)
		(layer "In9.Cu")
		(net "SATA6G_PCH_PCIE_UP_SATA_RXP<5>")
	)
	(arc
		(start 386.77469 -122.115072)
		(mid 386.928608 -122.110235)
		(end 387.034024 -121.997978)
		(width 0.0889)
		(layer "In9.Cu")
		(net "SATA6G_PCH_PCIE_UP_SATA_RXP<5>")
	)
	(arc
		(start 409.381452 -152.57145)
		(mid 409.425193 -152.562749)
		(end 409.462224 -152.537922)
		(width 0.1143)
		(layer "In9.Cu")
		(net "SATA6G_PCH_PCIE_UP_SATA_RXP<5>")
	)
	(arc
		(start 407.90876 -135.87476)
		(mid 407.399759 -136.085595)
		(end 407.188924 -136.594596)
		(width 0.1143)
		(layer "In9.Cu")
		(net "SATA6G_PCH_PCIE_UP_SATA_RXP<5>")
	)
	(arc
		(start 389.248396 -133.50621)
		(mid 389.342445 -133.5158)
		(end 389.423402 -133.56463)
		(width 0.1143)
		(layer "In9.Cu")
		(net "SATA6G_PCH_PCIE_UP_SATA_RXP<5>")
	)
	(arc
		(start 407.006552 -140.504418)
		(mid 406.996962 -140.598467)
		(end 406.948132 -140.679424)
		(width 0.1143)
		(layer "In9.Cu")
		(net "SATA6G_PCH_PCIE_UP_SATA_RXP<5>")
	)
	(arc
		(start 403.333712 -131.687316)
		(mid 403.507846 -131.57109)
		(end 403.713188 -131.530344)
		(width 0.1143)
		(layer "In9.Cu")
		(net "SATA6G_PCH_PCIE_UP_SATA_RXP<5>")
	)
	(arc
		(start 389.972296 -134.347204)
		(mid 390.077542 -134.417464)
		(end 390.201658 -134.4422)
		(width 0.1143)
		(layer "In9.Cu")
		(net "SATA6G_PCH_PCIE_UP_SATA_RXP<5>")
	)
	(arc
		(start 407.818336 -149.605746)
		(mid 407.827037 -149.649487)
		(end 407.851864 -149.686518)
		(width 0.1143)
		(layer "In9.Cu")
		(net "SATA6G_PCH_PCIE_UP_SATA_RXP<5>")
	)
	(arc
		(start 405.160988 -142.233142)
		(mid 405.036941 -142.418653)
		(end 404.993348 -142.63751)
		(width 0.1143)
		(layer "In9.Cu")
		(net "SATA6G_PCH_PCIE_UP_SATA_RXP<5>")
	)
	(arc
		(start 386.91693 -121.73839)
		(mid 386.869139 -121.722676)
		(end 386.820156 -121.711212)
		(width 0.0889)
		(layer "In9.Cu")
		(net "SATA6G_PCH_PCIE_UP_SATA_RXP<5>")
	)
	(arc
		(start 407.064972 -140.329158)
		(mid 407.016073 -140.410225)
		(end 407.006552 -140.504418)
		(width 0.1143)
		(layer "In9.Cu")
		(net "SATA6G_PCH_PCIE_UP_SATA_RXP<5>")
	)
	(arc
		(start 388.296404 -132.554218)
		(mid 388.390453 -132.563808)
		(end 388.47141 -132.612638)
		(width 0.1143)
		(layer "In9.Cu")
		(net "SATA6G_PCH_PCIE_UP_SATA_RXP<5>")
	)
	(arc
		(start 405.426164 -145.8341)
		(mid 405.593111 -146.083954)
		(end 405.651716 -146.378676)
		(width 0.1143)
		(layer "In9.Cu")
		(net "SATA6G_PCH_PCIE_UP_SATA_RXP<5>")
	)
	(arc
		(start 397.100806 -134.4422)
		(mid 400.314334 -133.802896)
		(end 403.038564 -131.982464)
		(width 0.1143)
		(layer "In9.Cu")
		(net "SATA6G_PCH_PCIE_UP_SATA_RXP<5>")
	)
	(arc
		(start 386.724652 -121.705116)
		(mid 386.460049 -121.825508)
		(end 386.3467 -122.093228)
		(width 0.0889)
		(layer "In9.Cu")
		(net "SATA6G_PCH_PCIE_UP_SATA_RXP<5>")
	)
	(arc
		(start 405.651716 -147.512532)
		(mid 405.662799 -147.56834)
		(end 405.694388 -147.615656)
		(width 0.1143)
		(layer "In9.Cu")
		(net "SATA6G_PCH_PCIE_UP_SATA_RXP<5>")
	)
	(arc
		(start 408.814524 -139.368784)
		(mid 408.619609 -139.839349)
		(end 408.149044 -140.034264)
		(width 0.1143)
		(layer "In9.Cu")
		(net "SATA6G_PCH_PCIE_UP_SATA_RXP<5>")
	)
	(arc
		(start 407.302208 -148.530056)
		(mid 407.667166 -148.681226)
		(end 407.818336 -149.046184)
		(width 0.1143)
		(layer "In9.Cu")
		(net "SATA6G_PCH_PCIE_UP_SATA_RXP<5>")
	)
	(arc
		(start 386.193538 -129.158746)
		(mid 386.233202 -129.358329)
		(end 386.346192 -129.527554)
		(width 0.1143)
		(layer "In9.Cu")
		(net "SATA6G_PCH_PCIE_UP_SATA_RXP<5>")
	)
	(arc
		(start 408.84221 -152.499314)
		(mid 408.922023 -152.552707)
		(end 409.0162 -152.57145)
		(width 0.1143)
		(layer "In9.Cu")
		(net "SATA6G_PCH_PCIE_UP_SATA_RXP<5>")
	)
	(arc
		(start 406.530556 -140.980414)
		(mid 406.436533 -140.989879)
		(end 406.35555 -141.03858)
		(width 0.1143)
		(layer "In9.Cu")
		(net "SATA6G_PCH_PCIE_UP_SATA_RXP<5>")
	)
	(arc
		(start 408.273758 -150.108412)
		(mid 408.361718 -150.240243)
		(end 408.39263 -150.395686)
		(width 0.1143)
		(layer "In9.Cu")
		(net "SATA6G_PCH_PCIE_UP_SATA_RXP<5>")
	)
	(arc
		(start 409.323032 -137.760964)
		(mid 409.875482 -138.313414)
		(end 409.323032 -138.865864)
		(width 0.1143)
		(layer "In9.Cu")
		(net "SATA6G_PCH_PCIE_UP_SATA_RXP<5>")
	)
	(arc
		(start 386.777738 -130.941572)
		(mid 386.816485 -131.136364)
		(end 386.926836 -131.30149)
		(width 0.1143)
		(layer "In9.Cu")
		(net "SATA6G_PCH_PCIE_UP_SATA_RXP<5>")
	)
	(arc
		(start 387.820408 -132.078222)
		(mid 387.829929 -132.172415)
		(end 387.878828 -132.253482)
		(width 0.1143)
		(layer "In9.Cu")
		(net "SATA6G_PCH_PCIE_UP_SATA_RXP<5>")
	)
	(arc
		(start 406.57526 -148.496528)
		(mid 406.612435 -148.521368)
		(end 406.656286 -148.530056)
		(width 0.1143)
		(layer "In9.Cu")
		(net "SATA6G_PCH_PCIE_UP_SATA_RXP<5>")
	)
	(arc
		(start 407.496264 -140.034264)
		(mid 407.370208 -140.059356)
		(end 407.263346 -140.130784)
		(width 0.1143)
		(layer "In9.Cu")
		(net "SATA6G_PCH_PCIE_UP_SATA_RXP<5>")
	)
	(arc
		(start 387.034024 -121.997724)
		(mid 387.029187 -121.843806)
		(end 386.91693 -121.73839)
		(width 0.0889)
		(layer "In9.Cu")
		(net "SATA6G_PCH_PCIE_UP_SATA_RXP<5>")
	)
	(arc
		(start 385.8514 -122.984514)
		(mid 385.767119 -123.267731)
		(end 385.556252 -123.474734)
		(width 0.0889)
		(layer "In9.Cu")
		(net "SATA6G_PCH_PCIE_UP_SATA_RXP<5>")
	)
	(arc
		(start 388.7724 -133.030214)
		(mid 388.781921 -133.124407)
		(end 388.83082 -133.205474)
		(width 0.1143)
		(layer "In9.Cu")
		(net "SATA6G_PCH_PCIE_UP_SATA_RXP<5>")
	)
	(arc
		(start 386.346446 -129.527808)
		(mid 386.665623 -130.00549)
		(end 386.777738 -130.568954)
		(width 0.1143)
		(layer "In9.Cu")
		(net "SATA6G_PCH_PCIE_UP_SATA_RXP<5>")
	)
	(arc
		(start 389.07339 -133.448044)
		(mid 389.154371 -133.496753)
		(end 389.248396 -133.50621)
		(width 0.1143)
		(layer "In9.Cu")
		(net "SATA6G_PCH_PCIE_UP_SATA_RXP<5>")
	)
	(arc
		(start 387.169406 -131.54406)
		(mid 387.250387 -131.592769)
		(end 387.344412 -131.602226)
		(width 0.1143)
		(layer "In9.Cu")
		(net "SATA6G_PCH_PCIE_UP_SATA_RXP<5>")
	)
	(arc
		(start 388.121398 -132.496052)
		(mid 388.202379 -132.544761)
		(end 388.296404 -132.554218)
		(width 0.1143)
		(layer "In9.Cu")
		(net "SATA6G_PCH_PCIE_UP_SATA_RXP<5>")
	)
	(arc
		(start 409.074874 -138.865864)
		(mid 408.890779 -138.942119)
		(end 408.814524 -139.126214)
		(width 0.1143)
		(layer "In9.Cu")
		(net "SATA6G_PCH_PCIE_UP_SATA_RXP<5>")
	)
	(segment
		(start 386.74675 -122.7328)
		(end 387.24205 -122.962924)
		(width 0.1143)
		(layer "F.Cu")
		(net "SATA6G_PCH_PCIE_UP_SATA_RXP<4>")
	)
	(via
		(at 409.579826 -148.845016)
		(size 0.508)
		(drill 0.254)
		(layers "F.Cu" "B.Cu")
		(net "SATA6G_PCH_PCIE_UP_SATA_RXP<4>")
	)
	(via
		(at 387.24205 -122.962924)
		(size 0.508)
		(drill 0.254)
		(layers "F.Cu" "B.Cu")
		(net "SATA6G_PCH_PCIE_UP_SATA_RXP<4>")
	)
	(segment
		(start 409.579826 -149.15769)
		(end 409.579826 -148.845016)
		(width 0.1143)
		(layer "B.Cu")
		(net "SATA6G_PCH_PCIE_UP_SATA_RXP<4>")
	)
	(segment
		(start 410.464 -149.06752)
		(end 410.25953 -149.27199)
		(width 0.1143)
		(layer "B.Cu")
		(net "SATA6G_PCH_PCIE_UP_SATA_RXP<4>")
	)
	(segment
		(start 410.25953 -149.27199)
		(end 409.694126 -149.27199)
		(width 0.1143)
		(layer "B.Cu")
		(net "SATA6G_PCH_PCIE_UP_SATA_RXP<4>")
	)
	(arc
		(start 409.694126 -149.27199)
		(mid 409.613304 -149.238512)
		(end 409.579826 -149.15769)
		(width 0.1143)
		(layer "B.Cu")
		(net "SATA6G_PCH_PCIE_UP_SATA_RXP<4>")
	)
	(segment
		(start 408.854402 -146.355054)
		(end 408.854402 -146.360388)
		(width 0.1143)
		(layer "In9.Cu")
		(net "SATA6G_PCH_PCIE_UP_SATA_RXP<4>")
	)
	(segment
		(start 409.603194 -134.656068)
		(end 409.603194 -134.998968)
		(width 0.1143)
		(layer "In9.Cu")
		(net "SATA6G_PCH_PCIE_UP_SATA_RXP<4>")
	)
	(segment
		(start 387.710172 -130.729228)
		(end 387.952488 -130.971798)
		(width 0.1143)
		(layer "In9.Cu")
		(net "SATA6G_PCH_PCIE_UP_SATA_RXP<4>")
	)
	(segment
		(start 387.047994 -124.870718)
		(end 387.047994 -125.278388)
		(width 0.1143)
		(layer "In9.Cu")
		(net "SATA6G_PCH_PCIE_UP_SATA_RXP<4>")
	)
	(segment
		(start 407.6827 -141.590522)
		(end 407.6827 -144.729454)
		(width 0.1143)
		(layer "In9.Cu")
		(net "SATA6G_PCH_PCIE_UP_SATA_RXP<4>")
	)
	(segment
		(start 390.490964 -133.4643)
		(end 397.526002 -133.4643)
		(width 0.1143)
		(layer "In9.Cu")
		(net "SATA6G_PCH_PCIE_UP_SATA_RXP<4>")
	)
	(segment
		(start 408.854402 -148.229828)
		(end 408.854402 -148.910294)
		(width 0.1143)
		(layer "In9.Cu")
		(net "SATA6G_PCH_PCIE_UP_SATA_RXP<4>")
	)
	(segment
		(start 387.047994 -126.281688)
		(end 387.047994 -128.779778)
		(width 0.1143)
		(layer "In9.Cu")
		(net "SATA6G_PCH_PCIE_UP_SATA_RXP<4>")
	)
	(segment
		(start 387.232906 -129.225294)
		(end 387.249162 -129.241804)
		(width 0.1143)
		(layer "In9.Cu")
		(net "SATA6G_PCH_PCIE_UP_SATA_RXP<4>")
	)
	(segment
		(start 409.160472 -149.216364)
		(end 409.465526 -149.216364)
		(width 0.1143)
		(layer "In9.Cu")
		(net "SATA6G_PCH_PCIE_UP_SATA_RXP<4>")
	)
	(segment
		(start 409.579826 -149.102064)
		(end 409.579826 -148.845016)
		(width 0.1143)
		(layer "In9.Cu")
		(net "SATA6G_PCH_PCIE_UP_SATA_RXP<4>")
	)
	(segment
		(start 387.617462 -130.132074)
		(end 387.617462 -130.505962)
		(width 0.1143)
		(layer "In9.Cu")
		(net "SATA6G_PCH_PCIE_UP_SATA_RXP<4>")
	)
	(segment
		(start 386.997194 -124.410724)
		(end 386.997194 -124.808742)
		(width 0.0889)
		(layer "In9.Cu")
		(net "SATA6G_PCH_PCIE_UP_SATA_RXP<4>")
	)
	(segment
		(start 387.042152 -123.309634)
		(end 387.041898 -123.309634)
		(width 0.0889)
		(layer "In9.Cu")
		(net "SATA6G_PCH_PCIE_UP_SATA_RXP<4>")
	)
	(segment
		(start 387.24205 -122.962924)
		(end 386.977128 -122.962924)
		(width 0.0889)
		(layer "In9.Cu")
		(net "SATA6G_PCH_PCIE_UP_SATA_RXP<4>")
	)
	(segment
		(start 407.6827 -144.729454)
		(end 407.682954 -144.7292)
		(width 0.1143)
		(layer "In9.Cu")
		(net "SATA6G_PCH_PCIE_UP_SATA_RXP<4>")
	)
	(segment
		(start 386.85216 -123.01474)
		(end 386.846064 -123.020836)
		(width 0.0889)
		(layer "In9.Cu")
		(net "SATA6G_PCH_PCIE_UP_SATA_RXP<4>")
	)
	(segment
		(start 387.047994 -124.859542)
		(end 387.047994 -124.870718)
		(width 0.0889)
		(layer "In9.Cu")
		(net "SATA6G_PCH_PCIE_UP_SATA_RXP<4>")
	)
	(segment
		(start 403.607016 -130.684778)
		(end 406.714198 -130.684778)
		(width 0.1143)
		(layer "In9.Cu")
		(net "SATA6G_PCH_PCIE_UP_SATA_RXP<4>")
	)
	(segment
		(start 410.53385 -139.192508)
		(end 410.53385 -140.327888)
		(width 0.1143)
		(layer "In9.Cu")
		(net "SATA6G_PCH_PCIE_UP_SATA_RXP<4>")
	)
	(segment
		(start 409.982924 -147.866354)
		(end 409.217876 -147.866354)
		(width 0.1143)
		(layer "In9.Cu")
		(net "SATA6G_PCH_PCIE_UP_SATA_RXP<4>")
	)
	(segment
		(start 407.80081 -145.01368)
		(end 408.651456 -145.864326)
		(width 0.1143)
		(layer "In9.Cu")
		(net "SATA6G_PCH_PCIE_UP_SATA_RXP<4>")
	)
	(segment
		(start 389.613648 -132.633466)
		(end 390.410192 -133.430518)
		(width 0.1143)
		(layer "In9.Cu")
		(net "SATA6G_PCH_PCIE_UP_SATA_RXP<4>")
	)
	(segment
		(start 388.66191 -131.681474)
		(end 388.904226 -131.924044)
		(width 0.1143)
		(layer "In9.Cu")
		(net "SATA6G_PCH_PCIE_UP_SATA_RXP<4>")
	)
	(segment
		(start 409.863544 -135.259318)
		(end 411.61589 -135.259318)
		(width 0.1143)
		(layer "In9.Cu")
		(net "SATA6G_PCH_PCIE_UP_SATA_RXP<4>")
	)
	(segment
		(start 389.254492 -132.040884)
		(end 389.497062 -132.2832)
		(width 0.1143)
		(layer "In9.Cu")
		(net "SATA6G_PCH_PCIE_UP_SATA_RXP<4>")
	)
	(segment
		(start 387.047994 -128.779778)
		(end 387.048248 -128.779524)
		(width 0.1143)
		(layer "In9.Cu")
		(net "SATA6G_PCH_PCIE_UP_SATA_RXP<4>")
	)
	(segment
		(start 388.302754 -131.088638)
		(end 388.545324 -131.331208)
		(width 0.1143)
		(layer "In9.Cu")
		(net "SATA6G_PCH_PCIE_UP_SATA_RXP<4>")
	)
	(segment
		(start 410.960062 -138.163046)
		(end 410.959808 -138.1633)
		(width 0.1143)
		(layer "In9.Cu")
		(net "SATA6G_PCH_PCIE_UP_SATA_RXP<4>")
	)
	(segment
		(start 409.768294 -133.982968)
		(end 409.768294 -134.325868)
		(width 0.1143)
		(layer "In9.Cu")
		(net "SATA6G_PCH_PCIE_UP_SATA_RXP<4>")
	)
	(segment
		(start 409.98394 -140.877798)
		(end 408.395424 -140.877798)
		(width 0.1143)
		(layer "In9.Cu")
		(net "SATA6G_PCH_PCIE_UP_SATA_RXP<4>")
	)
	(segment
		(start 411.48889 -137.989818)
		(end 411.378654 -137.989818)
		(width 0.1143)
		(layer "In9.Cu")
		(net "SATA6G_PCH_PCIE_UP_SATA_RXP<4>")
	)
	(segment
		(start 402.45538 -131.422394)
		(end 402.900388 -130.977386)
		(width 0.1143)
		(layer "In9.Cu")
		(net "SATA6G_PCH_PCIE_UP_SATA_RXP<4>")
	)
	(segment
		(start 387.213094 -125.608588)
		(end 387.213094 -125.951488)
		(width 0.1143)
		(layer "In9.Cu")
		(net "SATA6G_PCH_PCIE_UP_SATA_RXP<4>")
	)
	(segment
		(start 409.863544 -136.884918)
		(end 411.48889 -136.884918)
		(width 0.1143)
		(layer "In9.Cu")
		(net "SATA6G_PCH_PCIE_UP_SATA_RXP<4>")
	)
	(segment
		(start 411.61589 -136.364218)
		(end 409.863544 -136.364218)
		(width 0.1143)
		(layer "In9.Cu")
		(net "SATA6G_PCH_PCIE_UP_SATA_RXP<4>")
	)
	(segment
		(start 386.997194 -124.808742)
		(end 387.047994 -124.859542)
		(width 0.0889)
		(layer "In9.Cu")
		(net "SATA6G_PCH_PCIE_UP_SATA_RXP<4>")
	)
	(segment
		(start 409.255468 -146.761454)
		(end 409.982924 -146.761454)
		(width 0.1143)
		(layer "In9.Cu")
		(net "SATA6G_PCH_PCIE_UP_SATA_RXP<4>")
	)
	(segment
		(start 409.603194 -133.574028)
		(end 409.603194 -133.652768)
		(width 0.1143)
		(layer "In9.Cu")
		(net "SATA6G_PCH_PCIE_UP_SATA_RXP<4>")
	)
	(arc
		(start 408.395424 -140.877798)
		(mid 407.891452 -141.08655)
		(end 407.6827 -141.590522)
		(width 0.1143)
		(layer "In9.Cu")
		(net "SATA6G_PCH_PCIE_UP_SATA_RXP<4>")
	)
	(arc
		(start 388.545324 -131.331208)
		(mid 388.594033 -131.412189)
		(end 388.60349 -131.506214)
		(width 0.1143)
		(layer "In9.Cu")
		(net "SATA6G_PCH_PCIE_UP_SATA_RXP<4>")
	)
	(arc
		(start 409.603194 -134.998968)
		(mid 409.679449 -135.183063)
		(end 409.863544 -135.259318)
		(width 0.1143)
		(layer "In9.Cu")
		(net "SATA6G_PCH_PCIE_UP_SATA_RXP<4>")
	)
	(arc
		(start 388.127748 -131.030218)
		(mid 388.221797 -131.039808)
		(end 388.302754 -131.088638)
		(width 0.1143)
		(layer "In9.Cu")
		(net "SATA6G_PCH_PCIE_UP_SATA_RXP<4>")
	)
	(arc
		(start 409.217876 -147.866354)
		(mid 408.960861 -147.972813)
		(end 408.854402 -148.229828)
		(width 0.1143)
		(layer "In9.Cu")
		(net "SATA6G_PCH_PCIE_UP_SATA_RXP<4>")
	)
	(arc
		(start 409.685744 -134.490968)
		(mid 409.625918 -134.564249)
		(end 409.603194 -134.656068)
		(width 0.1143)
		(layer "In9.Cu")
		(net "SATA6G_PCH_PCIE_UP_SATA_RXP<4>")
	)
	(arc
		(start 407.682954 -144.7292)
		(mid 407.713595 -144.883153)
		(end 407.80081 -145.01368)
		(width 0.1143)
		(layer "In9.Cu")
		(net "SATA6G_PCH_PCIE_UP_SATA_RXP<4>")
	)
	(arc
		(start 387.130544 -125.443488)
		(mid 387.19037 -125.516769)
		(end 387.213094 -125.608588)
		(width 0.1143)
		(layer "In9.Cu")
		(net "SATA6G_PCH_PCIE_UP_SATA_RXP<4>")
	)
	(arc
		(start 411.378654 -137.989818)
		(mid 411.152095 -138.034732)
		(end 410.960062 -138.163046)
		(width 0.1143)
		(layer "In9.Cu")
		(net "SATA6G_PCH_PCIE_UP_SATA_RXP<4>")
	)
	(arc
		(start 386.846064 -123.020836)
		(mid 386.910964 -123.187737)
		(end 387.042152 -123.309634)
		(width 0.0889)
		(layer "In9.Cu")
		(net "SATA6G_PCH_PCIE_UP_SATA_RXP<4>")
	)
	(arc
		(start 406.714198 -130.684778)
		(mid 408.757116 -131.531035)
		(end 409.603194 -133.574028)
		(width 0.1143)
		(layer "In9.Cu")
		(net "SATA6G_PCH_PCIE_UP_SATA_RXP<4>")
	)
	(arc
		(start 409.863544 -136.364218)
		(mid 409.603194 -136.624568)
		(end 409.863544 -136.884918)
		(width 0.1143)
		(layer "In9.Cu")
		(net "SATA6G_PCH_PCIE_UP_SATA_RXP<4>")
	)
	(arc
		(start 389.497062 -132.2832)
		(mid 389.545811 -132.364301)
		(end 389.555228 -132.45846)
		(width 0.1143)
		(layer "In9.Cu")
		(net "SATA6G_PCH_PCIE_UP_SATA_RXP<4>")
	)
	(arc
		(start 397.526002 -133.4643)
		(mid 400.193783 -132.933628)
		(end 402.45538 -131.422394)
		(width 0.1143)
		(layer "In9.Cu")
		(net "SATA6G_PCH_PCIE_UP_SATA_RXP<4>")
	)
	(arc
		(start 387.130544 -126.116588)
		(mid 387.070718 -126.189869)
		(end 387.047994 -126.281688)
		(width 0.1143)
		(layer "In9.Cu")
		(net "SATA6G_PCH_PCIE_UP_SATA_RXP<4>")
	)
	(arc
		(start 387.952488 -130.971798)
		(mid 388.033555 -131.020697)
		(end 388.127748 -131.030218)
		(width 0.1143)
		(layer "In9.Cu")
		(net "SATA6G_PCH_PCIE_UP_SATA_RXP<4>")
	)
	(arc
		(start 408.854402 -148.910294)
		(mid 408.944048 -149.126718)
		(end 409.160472 -149.216364)
		(width 0.1143)
		(layer "In9.Cu")
		(net "SATA6G_PCH_PCIE_UP_SATA_RXP<4>")
	)
	(arc
		(start 409.603194 -133.652768)
		(mid 409.625962 -133.744565)
		(end 409.685744 -133.817868)
		(width 0.1143)
		(layer "In9.Cu")
		(net "SATA6G_PCH_PCIE_UP_SATA_RXP<4>")
	)
	(arc
		(start 387.047994 -125.278388)
		(mid 387.070762 -125.370185)
		(end 387.130544 -125.443488)
		(width 0.1143)
		(layer "In9.Cu")
		(net "SATA6G_PCH_PCIE_UP_SATA_RXP<4>")
	)
	(arc
		(start 387.249162 -129.241804)
		(mid 387.521662 -129.65039)
		(end 387.617462 -130.132074)
		(width 0.1143)
		(layer "In9.Cu")
		(net "SATA6G_PCH_PCIE_UP_SATA_RXP<4>")
	)
	(arc
		(start 409.982924 -146.761454)
		(mid 410.535374 -147.313904)
		(end 409.982924 -147.866354)
		(width 0.1143)
		(layer "In9.Cu")
		(net "SATA6G_PCH_PCIE_UP_SATA_RXP<4>")
	)
	(arc
		(start 388.904226 -131.924044)
		(mid 388.985293 -131.972943)
		(end 389.079486 -131.982464)
		(width 0.1143)
		(layer "In9.Cu")
		(net "SATA6G_PCH_PCIE_UP_SATA_RXP<4>")
	)
	(arc
		(start 387.041898 -124.333254)
		(mid 387.009147 -124.365994)
		(end 386.997194 -124.410724)
		(width 0.0889)
		(layer "In9.Cu")
		(net "SATA6G_PCH_PCIE_UP_SATA_RXP<4>")
	)
	(arc
		(start 386.977128 -122.962924)
		(mid 386.90949 -122.976396)
		(end 386.85216 -123.01474)
		(width 0.0889)
		(layer "In9.Cu")
		(net "SATA6G_PCH_PCIE_UP_SATA_RXP<4>")
	)
	(arc
		(start 388.60349 -131.506214)
		(mid 388.613011 -131.600407)
		(end 388.66191 -131.681474)
		(width 0.1143)
		(layer "In9.Cu")
		(net "SATA6G_PCH_PCIE_UP_SATA_RXP<4>")
	)
	(arc
		(start 408.854402 -146.360388)
		(mid 408.971872 -146.643984)
		(end 409.255468 -146.761454)
		(width 0.1143)
		(layer "In9.Cu")
		(net "SATA6G_PCH_PCIE_UP_SATA_RXP<4>")
	)
	(arc
		(start 408.651456 -145.864326)
		(mid 408.801758 -146.089503)
		(end 408.854402 -146.355054)
		(width 0.1143)
		(layer "In9.Cu")
		(net "SATA6G_PCH_PCIE_UP_SATA_RXP<4>")
	)
	(arc
		(start 411.61589 -135.259318)
		(mid 412.16834 -135.811768)
		(end 411.61589 -136.364218)
		(width 0.1143)
		(layer "In9.Cu")
		(net "SATA6G_PCH_PCIE_UP_SATA_RXP<4>")
	)
	(arc
		(start 409.465526 -149.216364)
		(mid 409.546348 -149.182886)
		(end 409.579826 -149.102064)
		(width 0.1143)
		(layer "In9.Cu")
		(net "SATA6G_PCH_PCIE_UP_SATA_RXP<4>")
	)
	(arc
		(start 387.213094 -125.951488)
		(mid 387.190326 -126.043285)
		(end 387.130544 -126.116588)
		(width 0.1143)
		(layer "In9.Cu")
		(net "SATA6G_PCH_PCIE_UP_SATA_RXP<4>")
	)
	(arc
		(start 390.410192 -133.430518)
		(mid 390.447221 -133.455417)
		(end 390.490964 -133.4643)
		(width 0.1143)
		(layer "In9.Cu")
		(net "SATA6G_PCH_PCIE_UP_SATA_RXP<4>")
	)
	(arc
		(start 409.768294 -134.325868)
		(mid 409.745526 -134.417665)
		(end 409.685744 -134.490968)
		(width 0.1143)
		(layer "In9.Cu")
		(net "SATA6G_PCH_PCIE_UP_SATA_RXP<4>")
	)
	(arc
		(start 387.617462 -130.505962)
		(mid 387.641597 -130.626827)
		(end 387.710172 -130.729228)
		(width 0.1143)
		(layer "In9.Cu")
		(net "SATA6G_PCH_PCIE_UP_SATA_RXP<4>")
	)
	(arc
		(start 411.48889 -136.884918)
		(mid 412.04134 -137.437368)
		(end 411.48889 -137.989818)
		(width 0.1143)
		(layer "In9.Cu")
		(net "SATA6G_PCH_PCIE_UP_SATA_RXP<4>")
	)
	(arc
		(start 410.53385 -140.327888)
		(mid 410.372785 -140.716733)
		(end 409.98394 -140.877798)
		(width 0.1143)
		(layer "In9.Cu")
		(net "SATA6G_PCH_PCIE_UP_SATA_RXP<4>")
	)
	(arc
		(start 409.685744 -133.817868)
		(mid 409.74557 -133.891149)
		(end 409.768294 -133.982968)
		(width 0.1143)
		(layer "In9.Cu")
		(net "SATA6G_PCH_PCIE_UP_SATA_RXP<4>")
	)
	(arc
		(start 387.048248 -128.779524)
		(mid 387.096236 -129.020778)
		(end 387.232906 -129.225294)
		(width 0.1143)
		(layer "In9.Cu")
		(net "SATA6G_PCH_PCIE_UP_SATA_RXP<4>")
	)
	(arc
		(start 387.041898 -123.309634)
		(mid 387.337565 -123.821444)
		(end 387.041898 -124.333254)
		(width 0.0889)
		(layer "In9.Cu")
		(net "SATA6G_PCH_PCIE_UP_SATA_RXP<4>")
	)
	(arc
		(start 389.079486 -131.982464)
		(mid 389.173535 -131.992054)
		(end 389.254492 -132.040884)
		(width 0.1143)
		(layer "In9.Cu")
		(net "SATA6G_PCH_PCIE_UP_SATA_RXP<4>")
	)
	(arc
		(start 402.900388 -130.977386)
		(mid 403.224606 -130.760814)
		(end 403.607016 -130.684778)
		(width 0.1143)
		(layer "In9.Cu")
		(net "SATA6G_PCH_PCIE_UP_SATA_RXP<4>")
	)
	(arc
		(start 389.555228 -132.45846)
		(mid 389.564818 -132.552509)
		(end 389.613648 -132.633466)
		(width 0.1143)
		(layer "In9.Cu")
		(net "SATA6G_PCH_PCIE_UP_SATA_RXP<4>")
	)
	(arc
		(start 410.959808 -138.1633)
		(mid 410.644584 -138.635589)
		(end 410.53385 -139.192508)
		(width 0.1143)
		(layer "In9.Cu")
		(net "SATA6G_PCH_PCIE_UP_SATA_RXP<4>")
	)
	(segment
		(start 388.23265 -121.87428)
		(end 388.659116 -122.0724)
		(width 0.1143)
		(layer "F.Cu")
		(net "SATA6G_PCH_PCIE_UP_SATA_RXP<3>")
	)
	(segment
		(start 388.659116 -122.0724)
		(end 388.72795 -122.104404)
		(width 0.1143)
		(layer "F.Cu")
		(net "SATA6G_PCH_PCIE_UP_SATA_RXP<3>")
	)
	(via
		(at 388.72795 -122.104404)
		(size 0.508)
		(drill 0.254)
		(layers "F.Cu" "B.Cu")
		(net "SATA6G_PCH_PCIE_UP_SATA_RXP<3>")
	)
	(via
		(at 419.320726 -154.7368)
		(size 0.508)
		(drill 0.254)
		(layers "F.Cu" "B.Cu")
		(net "SATA6G_PCH_PCIE_UP_SATA_RXP<3>")
	)
	(segment
		(start 419.435026 -155.26385)
		(end 420.252906 -155.26385)
		(width 0.1143)
		(layer "B.Cu")
		(net "SATA6G_PCH_PCIE_UP_SATA_RXP<3>")
	)
	(segment
		(start 420.333678 -155.230322)
		(end 420.624 -154.94)
		(width 0.1143)
		(layer "B.Cu")
		(net "SATA6G_PCH_PCIE_UP_SATA_RXP<3>")
	)
	(segment
		(start 419.320726 -154.7368)
		(end 419.320726 -155.14955)
		(width 0.1143)
		(layer "B.Cu")
		(net "SATA6G_PCH_PCIE_UP_SATA_RXP<3>")
	)
	(arc
		(start 420.252906 -155.26385)
		(mid 420.296647 -155.255149)
		(end 420.333678 -155.230322)
		(width 0.1143)
		(layer "B.Cu")
		(net "SATA6G_PCH_PCIE_UP_SATA_RXP<3>")
	)
	(arc
		(start 419.320726 -155.14955)
		(mid 419.354204 -155.230372)
		(end 419.435026 -155.26385)
		(width 0.1143)
		(layer "B.Cu")
		(net "SATA6G_PCH_PCIE_UP_SATA_RXP<3>")
	)
	(segment
		(start 393.789408 -127.302768)
		(end 393.789408 -127.28067)
		(width 0.0889)
		(layer "In9.Cu")
		(net "SATA6G_PCH_PCIE_UP_SATA_RXP<3>")
	)
	(segment
		(start 414.5661 -132.131054)
		(end 414.003744 -131.568698)
		(width 0.1143)
		(layer "In9.Cu")
		(net "SATA6G_PCH_PCIE_UP_SATA_RXP<3>")
	)
	(segment
		(start 419.320726 -154.7368)
		(end 419.320726 -155.12415)
		(width 0.1143)
		(layer "In9.Cu")
		(net "SATA6G_PCH_PCIE_UP_SATA_RXP<3>")
	)
	(segment
		(start 417.09721 -139.089892)
		(end 416.85464 -138.847576)
		(width 0.1143)
		(layer "In9.Cu")
		(net "SATA6G_PCH_PCIE_UP_SATA_RXP<3>")
	)
	(segment
		(start 418.408358 -140.634466)
		(end 418.165788 -140.391896)
		(width 0.1143)
		(layer "In9.Cu")
		(net "SATA6G_PCH_PCIE_UP_SATA_RXP<3>")
	)
	(segment
		(start 415.0741 -134.467854)
		(end 415.0741 -133.357112)
		(width 0.1143)
		(layer "In9.Cu")
		(net "SATA6G_PCH_PCIE_UP_SATA_RXP<3>")
	)
	(segment
		(start 422.399714 -152.441148)
		(end 421.310816 -151.352504)
		(width 0.1143)
		(layer "In9.Cu")
		(net "SATA6G_PCH_PCIE_UP_SATA_RXP<3>")
	)
	(segment
		(start 417.456366 -139.682728)
		(end 417.213796 -139.440158)
		(width 0.1143)
		(layer "In9.Cu")
		(net "SATA6G_PCH_PCIE_UP_SATA_RXP<3>")
	)
	(segment
		(start 411.945074 -128.444498)
		(end 411.94482 -128.444498)
		(width 0.1143)
		(layer "In9.Cu")
		(net "SATA6G_PCH_PCIE_UP_SATA_RXP<3>")
	)
	(segment
		(start 393.840208 -127.22987)
		(end 393.840208 -126.67615)
		(width 0.0889)
		(layer "In9.Cu")
		(net "SATA6G_PCH_PCIE_UP_SATA_RXP<3>")
	)
	(segment
		(start 421.567102 -142.401798)
		(end 420.864538 -142.401798)
		(width 0.1143)
		(layer "In9.Cu")
		(net "SATA6G_PCH_PCIE_UP_SATA_RXP<3>")
	)
	(segment
		(start 415.552382 -137.779252)
		(end 415.309812 -137.536682)
		(width 0.1143)
		(layer "In9.Cu")
		(net "SATA6G_PCH_PCIE_UP_SATA_RXP<3>")
	)
	(segment
		(start 390.1186 -123.962668)
		(end 390.1186 -123.810268)
		(width 0.0889)
		(layer "In9.Cu")
		(net "SATA6G_PCH_PCIE_UP_SATA_RXP<3>")
	)
	(segment
		(start 419.435026 -155.23845)
		(end 421.590216 -155.23845)
		(width 0.1143)
		(layer "In9.Cu")
		(net "SATA6G_PCH_PCIE_UP_SATA_RXP<3>")
	)
	(segment
		(start 422.76649 -143.449802)
		(end 421.825928 -142.50924)
		(width 0.1143)
		(layer "In9.Cu")
		(net "SATA6G_PCH_PCIE_UP_SATA_RXP<3>")
	)
	(segment
		(start 393.789408 -127.28067)
		(end 393.840208 -127.22987)
		(width 0.0889)
		(layer "In9.Cu")
		(net "SATA6G_PCH_PCIE_UP_SATA_RXP<3>")
	)
	(segment
		(start 412.546292 -130.47472)
		(end 412.547562 -129.207768)
		(width 0.1143)
		(layer "In9.Cu")
		(net "SATA6G_PCH_PCIE_UP_SATA_RXP<3>")
	)
	(segment
		(start 414.831784 -136.656318)
		(end 414.831784 -135.10641)
		(width 0.1143)
		(layer "In9.Cu")
		(net "SATA6G_PCH_PCIE_UP_SATA_RXP<3>")
	)
	(segment
		(start 416.145218 -138.138154)
		(end 415.902648 -137.895838)
		(width 0.1143)
		(layer "In9.Cu")
		(net "SATA6G_PCH_PCIE_UP_SATA_RXP<3>")
	)
	(segment
		(start 389.131048 -122.169428)
		(end 389.066024 -122.104404)
		(width 0.0889)
		(layer "In9.Cu")
		(net "SATA6G_PCH_PCIE_UP_SATA_RXP<3>")
	)
	(segment
		(start 393.789408 -130.22326)
		(end 393.789408 -127.302768)
		(width 0.1143)
		(layer "In9.Cu")
		(net "SATA6G_PCH_PCIE_UP_SATA_RXP<3>")
	)
	(segment
		(start 392.234928 -126.19482)
		(end 390.200388 -124.16028)
		(width 0.0889)
		(layer "In9.Cu")
		(net "SATA6G_PCH_PCIE_UP_SATA_RXP<3>")
	)
	(segment
		(start 422.91 -145.085054)
		(end 422.91 -143.795496)
		(width 0.1143)
		(layer "In9.Cu")
		(net "SATA6G_PCH_PCIE_UP_SATA_RXP<3>")
	)
	(segment
		(start 420.088314 -142.080488)
		(end 418.758624 -140.751052)
		(width 0.1143)
		(layer "In9.Cu")
		(net "SATA6G_PCH_PCIE_UP_SATA_RXP<3>")
	)
	(segment
		(start 397.283686 -131.172966)
		(end 394.739114 -131.172966)
		(width 0.1143)
		(layer "In9.Cu")
		(net "SATA6G_PCH_PCIE_UP_SATA_RXP<3>")
	)
	(segment
		(start 393.840208 -126.67615)
		(end 393.839954 -126.676404)
		(width 0.0889)
		(layer "In9.Cu")
		(net "SATA6G_PCH_PCIE_UP_SATA_RXP<3>")
	)
	(segment
		(start 389.066024 -122.104404)
		(end 388.72795 -122.104404)
		(width 0.0889)
		(layer "In9.Cu")
		(net "SATA6G_PCH_PCIE_UP_SATA_RXP<3>")
	)
	(segment
		(start 389.6233 -122.984514)
		(end 389.6233 -122.951748)
		(width 0.0889)
		(layer "In9.Cu")
		(net "SATA6G_PCH_PCIE_UP_SATA_RXP<3>")
	)
	(segment
		(start 422.433242 -154.664156)
		(end 422.433242 -152.522174)
		(width 0.1143)
		(layer "In9.Cu")
		(net "SATA6G_PCH_PCIE_UP_SATA_RXP<3>")
	)
	(segment
		(start 412.431738 -128.92913)
		(end 411.945074 -128.444498)
		(width 0.1143)
		(layer "In9.Cu")
		(net "SATA6G_PCH_PCIE_UP_SATA_RXP<3>")
	)
	(segment
		(start 421.581326 -146.660616)
		(end 422.734994 -145.506948)
		(width 0.1143)
		(layer "In9.Cu")
		(net "SATA6G_PCH_PCIE_UP_SATA_RXP<3>")
	)
	(segment
		(start 416.504374 -138.73099)
		(end 416.261804 -138.48842)
		(width 0.1143)
		(layer "In9.Cu")
		(net "SATA6G_PCH_PCIE_UP_SATA_RXP<3>")
	)
	(segment
		(start 415.193226 -137.186416)
		(end 414.950656 -136.9441)
		(width 0.1143)
		(layer "In9.Cu")
		(net "SATA6G_PCH_PCIE_UP_SATA_RXP<3>")
	)
	(segment
		(start 422.194736 -154.987752)
		(end 422.373044 -154.809444)
		(width 0.1143)
		(layer "In9.Cu")
		(net "SATA6G_PCH_PCIE_UP_SATA_RXP<3>")
	)
	(segment
		(start 393.440666 -126.276608)
		(end 392.431778 -126.276608)
		(width 0.0889)
		(layer "In9.Cu")
		(net "SATA6G_PCH_PCIE_UP_SATA_RXP<3>")
	)
	(segment
		(start 411.738572 -128.3589)
		(end 402.37918 -128.3589)
		(width 0.1143)
		(layer "In9.Cu")
		(net "SATA6G_PCH_PCIE_UP_SATA_RXP<3>")
	)
	(segment
		(start 393.814046 -126.613666)
		(end 393.50315 -126.30277)
		(width 0.0889)
		(layer "In9.Cu")
		(net "SATA6G_PCH_PCIE_UP_SATA_RXP<3>")
	)
	(segment
		(start 394.451586 -131.05384)
		(end 393.908534 -130.510788)
		(width 0.1143)
		(layer "In9.Cu")
		(net "SATA6G_PCH_PCIE_UP_SATA_RXP<3>")
	)
	(segment
		(start 402.261578 -128.407668)
		(end 401.060666 -129.60858)
		(width 0.1143)
		(layer "In9.Cu")
		(net "SATA6G_PCH_PCIE_UP_SATA_RXP<3>")
	)
	(segment
		(start 418.049202 -140.04163)
		(end 417.806632 -139.799314)
		(width 0.1143)
		(layer "In9.Cu")
		(net "SATA6G_PCH_PCIE_UP_SATA_RXP<3>")
	)
	(segment
		(start 421.083232 -150.80234)
		(end 421.083232 -147.862544)
		(width 0.1143)
		(layer "In9.Cu")
		(net "SATA6G_PCH_PCIE_UP_SATA_RXP<3>")
	)
	(arc
		(start 421.083232 -147.862544)
		(mid 421.212669 -147.212002)
		(end 421.581326 -146.660616)
		(width 0.1143)
		(layer "In9.Cu")
		(net "SATA6G_PCH_PCIE_UP_SATA_RXP<3>")
	)
	(arc
		(start 394.739114 -131.172966)
		(mid 394.583508 -131.141996)
		(end 394.451586 -131.05384)
		(width 0.1143)
		(layer "In9.Cu")
		(net "SATA6G_PCH_PCIE_UP_SATA_RXP<3>")
	)
	(arc
		(start 422.433242 -152.522174)
		(mid 422.424537 -152.478322)
		(end 422.399714 -152.441148)
		(width 0.1143)
		(layer "In9.Cu")
		(net "SATA6G_PCH_PCIE_UP_SATA_RXP<3>")
	)
	(arc
		(start 414.003744 -131.568698)
		(mid 413.719046 -131.378469)
		(end 413.383222 -131.31165)
		(width 0.1143)
		(layer "In9.Cu")
		(net "SATA6G_PCH_PCIE_UP_SATA_RXP<3>")
	)
	(arc
		(start 419.320726 -155.12415)
		(mid 419.354204 -155.204972)
		(end 419.435026 -155.23845)
		(width 0.1143)
		(layer "In9.Cu")
		(net "SATA6G_PCH_PCIE_UP_SATA_RXP<3>")
	)
	(arc
		(start 415.727642 -137.837418)
		(mid 415.633475 -137.828022)
		(end 415.552382 -137.779252)
		(width 0.1143)
		(layer "In9.Cu")
		(net "SATA6G_PCH_PCIE_UP_SATA_RXP<3>")
	)
	(arc
		(start 417.15563 -139.265152)
		(mid 417.146109 -139.170959)
		(end 417.09721 -139.089892)
		(width 0.1143)
		(layer "In9.Cu")
		(net "SATA6G_PCH_PCIE_UP_SATA_RXP<3>")
	)
	(arc
		(start 414.950656 -136.9441)
		(mid 414.862569 -136.812035)
		(end 414.831784 -136.656318)
		(width 0.1143)
		(layer "In9.Cu")
		(net "SATA6G_PCH_PCIE_UP_SATA_RXP<3>")
	)
	(arc
		(start 411.94482 -128.444498)
		(mid 411.850208 -128.381187)
		(end 411.738572 -128.3589)
		(width 0.1143)
		(layer "In9.Cu")
		(net "SATA6G_PCH_PCIE_UP_SATA_RXP<3>")
	)
	(arc
		(start 417.213796 -139.440158)
		(mid 417.165087 -139.359177)
		(end 417.15563 -139.265152)
		(width 0.1143)
		(layer "In9.Cu")
		(net "SATA6G_PCH_PCIE_UP_SATA_RXP<3>")
	)
	(arc
		(start 389.423148 -122.616214)
		(mid 389.223775 -122.427686)
		(end 389.131048 -122.169428)
		(width 0.0889)
		(layer "In9.Cu")
		(net "SATA6G_PCH_PCIE_UP_SATA_RXP<3>")
	)
	(arc
		(start 402.37918 -128.3589)
		(mid 402.315538 -128.371617)
		(end 402.261578 -128.407668)
		(width 0.1143)
		(layer "In9.Cu")
		(net "SATA6G_PCH_PCIE_UP_SATA_RXP<3>")
	)
	(arc
		(start 422.91 -143.795496)
		(mid 422.872648 -143.608368)
		(end 422.76649 -143.449802)
		(width 0.1143)
		(layer "In9.Cu")
		(net "SATA6G_PCH_PCIE_UP_SATA_RXP<3>")
	)
	(arc
		(start 417.806632 -139.799314)
		(mid 417.725685 -139.750455)
		(end 417.631626 -139.740894)
		(width 0.1143)
		(layer "In9.Cu")
		(net "SATA6G_PCH_PCIE_UP_SATA_RXP<3>")
	)
	(arc
		(start 416.679634 -138.789156)
		(mid 416.585467 -138.77976)
		(end 416.504374 -138.73099)
		(width 0.1143)
		(layer "In9.Cu")
		(net "SATA6G_PCH_PCIE_UP_SATA_RXP<3>")
	)
	(arc
		(start 416.85464 -138.847576)
		(mid 416.773693 -138.798717)
		(end 416.679634 -138.789156)
		(width 0.1143)
		(layer "In9.Cu")
		(net "SATA6G_PCH_PCIE_UP_SATA_RXP<3>")
	)
	(arc
		(start 417.631626 -139.740894)
		(mid 417.537459 -139.731498)
		(end 417.456366 -139.682728)
		(width 0.1143)
		(layer "In9.Cu")
		(net "SATA6G_PCH_PCIE_UP_SATA_RXP<3>")
	)
	(arc
		(start 392.431778 -126.276608)
		(mid 392.325266 -126.255195)
		(end 392.234928 -126.19482)
		(width 0.0889)
		(layer "In9.Cu")
		(net "SATA6G_PCH_PCIE_UP_SATA_RXP<3>")
	)
	(arc
		(start 421.590216 -155.23845)
		(mid 421.917426 -155.173252)
		(end 422.194736 -154.987752)
		(width 0.1143)
		(layer "In9.Cu")
		(net "SATA6G_PCH_PCIE_UP_SATA_RXP<3>")
	)
	(arc
		(start 412.547562 -129.207768)
		(mid 412.517445 -129.0569)
		(end 412.431738 -128.92913)
		(width 0.1143)
		(layer "In9.Cu")
		(net "SATA6G_PCH_PCIE_UP_SATA_RXP<3>")
	)
	(arc
		(start 421.310816 -151.352504)
		(mid 421.142293 -151.100057)
		(end 421.083232 -150.80234)
		(width 0.1143)
		(layer "In9.Cu")
		(net "SATA6G_PCH_PCIE_UP_SATA_RXP<3>")
	)
	(arc
		(start 416.261804 -138.48842)
		(mid 416.213095 -138.407439)
		(end 416.203638 -138.313414)
		(width 0.1143)
		(layer "In9.Cu")
		(net "SATA6G_PCH_PCIE_UP_SATA_RXP<3>")
	)
	(arc
		(start 418.107622 -140.21689)
		(mid 418.098101 -140.122697)
		(end 418.049202 -140.04163)
		(width 0.1143)
		(layer "In9.Cu")
		(net "SATA6G_PCH_PCIE_UP_SATA_RXP<3>")
	)
	(arc
		(start 414.934146 -134.8359)
		(mid 415.037812 -134.664698)
		(end 415.0741 -134.467854)
		(width 0.1143)
		(layer "In9.Cu")
		(net "SATA6G_PCH_PCIE_UP_SATA_RXP<3>")
	)
	(arc
		(start 401.060666 -129.60858)
		(mid 399.327786 -130.766487)
		(end 397.283686 -131.172966)
		(width 0.1143)
		(layer "In9.Cu")
		(net "SATA6G_PCH_PCIE_UP_SATA_RXP<3>")
	)
	(arc
		(start 422.373044 -154.809444)
		(mid 422.417584 -154.742785)
		(end 422.433242 -154.664156)
		(width 0.1143)
		(layer "In9.Cu")
		(net "SATA6G_PCH_PCIE_UP_SATA_RXP<3>")
	)
	(arc
		(start 393.839954 -126.676404)
		(mid 393.833206 -126.642481)
		(end 393.814046 -126.613666)
		(width 0.0889)
		(layer "In9.Cu")
		(net "SATA6G_PCH_PCIE_UP_SATA_RXP<3>")
	)
	(arc
		(start 421.825928 -142.50924)
		(mid 421.707221 -142.429703)
		(end 421.567102 -142.401798)
		(width 0.1143)
		(layer "In9.Cu")
		(net "SATA6G_PCH_PCIE_UP_SATA_RXP<3>")
	)
	(arc
		(start 420.864538 -142.401798)
		(mid 420.444501 -142.318283)
		(end 420.088314 -142.080488)
		(width 0.1143)
		(layer "In9.Cu")
		(net "SATA6G_PCH_PCIE_UP_SATA_RXP<3>")
	)
	(arc
		(start 389.6233 -122.951748)
		(mid 389.56695 -122.757898)
		(end 389.423148 -122.616214)
		(width 0.0889)
		(layer "In9.Cu")
		(net "SATA6G_PCH_PCIE_UP_SATA_RXP<3>")
	)
	(arc
		(start 418.583618 -140.692886)
		(mid 418.489425 -140.683365)
		(end 418.408358 -140.634466)
		(width 0.1143)
		(layer "In9.Cu")
		(net "SATA6G_PCH_PCIE_UP_SATA_RXP<3>")
	)
	(arc
		(start 415.902648 -137.895838)
		(mid 415.821701 -137.846979)
		(end 415.727642 -137.837418)
		(width 0.1143)
		(layer "In9.Cu")
		(net "SATA6G_PCH_PCIE_UP_SATA_RXP<3>")
	)
	(arc
		(start 418.165788 -140.391896)
		(mid 418.117079 -140.310915)
		(end 418.107622 -140.21689)
		(width 0.1143)
		(layer "In9.Cu")
		(net "SATA6G_PCH_PCIE_UP_SATA_RXP<3>")
	)
	(arc
		(start 393.908534 -130.510788)
		(mid 393.820335 -130.378883)
		(end 393.789408 -130.22326)
		(width 0.1143)
		(layer "In9.Cu")
		(net "SATA6G_PCH_PCIE_UP_SATA_RXP<3>")
	)
	(arc
		(start 415.251646 -137.361676)
		(mid 415.242125 -137.267483)
		(end 415.193226 -137.186416)
		(width 0.1143)
		(layer "In9.Cu")
		(net "SATA6G_PCH_PCIE_UP_SATA_RXP<3>")
	)
	(arc
		(start 393.50315 -126.30277)
		(mid 393.474498 -126.283503)
		(end 393.440666 -126.276608)
		(width 0.0889)
		(layer "In9.Cu")
		(net "SATA6G_PCH_PCIE_UP_SATA_RXP<3>")
	)
	(arc
		(start 422.734994 -145.506948)
		(mid 422.864443 -145.313397)
		(end 422.91 -145.085054)
		(width 0.1143)
		(layer "In9.Cu")
		(net "SATA6G_PCH_PCIE_UP_SATA_RXP<3>")
	)
	(arc
		(start 415.0741 -133.357112)
		(mid 414.942035 -132.693556)
		(end 414.5661 -132.131054)
		(width 0.1143)
		(layer "In9.Cu")
		(net "SATA6G_PCH_PCIE_UP_SATA_RXP<3>")
	)
	(arc
		(start 414.831784 -135.10641)
		(mid 414.858162 -134.961779)
		(end 414.934146 -134.8359)
		(width 0.1143)
		(layer "In9.Cu")
		(net "SATA6G_PCH_PCIE_UP_SATA_RXP<3>")
	)
	(arc
		(start 413.383222 -131.31165)
		(mid 412.791423 -131.066519)
		(end 412.546292 -130.47472)
		(width 0.1143)
		(layer "In9.Cu")
		(net "SATA6G_PCH_PCIE_UP_SATA_RXP<3>")
	)
	(arc
		(start 418.758624 -140.751052)
		(mid 418.677643 -140.702343)
		(end 418.583618 -140.692886)
		(width 0.1143)
		(layer "In9.Cu")
		(net "SATA6G_PCH_PCIE_UP_SATA_RXP<3>")
	)
	(arc
		(start 389.918448 -123.474734)
		(mid 389.707584 -123.26773)
		(end 389.6233 -122.984514)
		(width 0.0889)
		(layer "In9.Cu")
		(net "SATA6G_PCH_PCIE_UP_SATA_RXP<3>")
	)
	(arc
		(start 390.200388 -124.16028)
		(mid 390.139807 -124.069615)
		(end 390.1186 -123.962668)
		(width 0.0889)
		(layer "In9.Cu")
		(net "SATA6G_PCH_PCIE_UP_SATA_RXP<3>")
	)
	(arc
		(start 390.1186 -123.810268)
		(mid 390.06225 -123.616418)
		(end 389.918448 -123.474734)
		(width 0.0889)
		(layer "In9.Cu")
		(net "SATA6G_PCH_PCIE_UP_SATA_RXP<3>")
	)
	(arc
		(start 415.309812 -137.536682)
		(mid 415.261103 -137.455701)
		(end 415.251646 -137.361676)
		(width 0.1143)
		(layer "In9.Cu")
		(net "SATA6G_PCH_PCIE_UP_SATA_RXP<3>")
	)
	(arc
		(start 416.203638 -138.313414)
		(mid 416.194117 -138.219221)
		(end 416.145218 -138.138154)
		(width 0.1143)
		(layer "In9.Cu")
		(net "SATA6G_PCH_PCIE_UP_SATA_RXP<3>")
	)
	(segment
		(start 387.24205 -121.87428)
		(end 387.308852 -121.905268)
		(width 0.1143)
		(layer "F.Cu")
		(net "SATA6G_PCH_PCIE_UP_SATA_RXP<2>")
	)
	(segment
		(start 387.308852 -121.905268)
		(end 387.668516 -122.0724)
		(width 0.1143)
		(layer "F.Cu")
		(net "SATA6G_PCH_PCIE_UP_SATA_RXP<2>")
	)
	(segment
		(start 387.668516 -122.0724)
		(end 387.73735 -122.104404)
		(width 0.1143)
		(layer "F.Cu")
		(net "SATA6G_PCH_PCIE_UP_SATA_RXP<2>")
	)
	(via
		(at 419.734746 -150.8633)
		(size 0.508)
		(drill 0.254)
		(layers "F.Cu" "B.Cu")
		(net "SATA6G_PCH_PCIE_UP_SATA_RXP<2>")
	)
	(via
		(at 387.73735 -122.104404)
		(size 0.508)
		(drill 0.254)
		(layers "F.Cu" "B.Cu")
		(net "SATA6G_PCH_PCIE_UP_SATA_RXP<2>")
	)
	(segment
		(start 420.624 -150.876)
		(end 420.317676 -151.182324)
		(width 0.1143)
		(layer "B.Cu")
		(net "SATA6G_PCH_PCIE_UP_SATA_RXP<2>")
	)
	(segment
		(start 420.23665 -151.215852)
		(end 419.849046 -151.215852)
		(width 0.1143)
		(layer "B.Cu")
		(net "SATA6G_PCH_PCIE_UP_SATA_RXP<2>")
	)
	(segment
		(start 419.734746 -151.101552)
		(end 419.734746 -150.8633)
		(width 0.1143)
		(layer "B.Cu")
		(net "SATA6G_PCH_PCIE_UP_SATA_RXP<2>")
	)
	(arc
		(start 420.317676 -151.182324)
		(mid 420.280501 -151.207164)
		(end 420.23665 -151.215852)
		(width 0.1143)
		(layer "B.Cu")
		(net "SATA6G_PCH_PCIE_UP_SATA_RXP<2>")
	)
	(arc
		(start 419.849046 -151.215852)
		(mid 419.768224 -151.182374)
		(end 419.734746 -151.101552)
		(width 0.1143)
		(layer "B.Cu")
		(net "SATA6G_PCH_PCIE_UP_SATA_RXP<2>")
	)
	(segment
		(start 391.158222 -132.491988)
		(end 397.51254 -132.491988)
		(width 0.1143)
		(layer "In9.Cu")
		(net "SATA6G_PCH_PCIE_UP_SATA_RXP<2>")
	)
	(segment
		(start 419.232842 -150.777194)
		(end 419.232842 -151.055832)
		(width 0.1143)
		(layer "In9.Cu")
		(net "SATA6G_PCH_PCIE_UP_SATA_RXP<2>")
	)
	(segment
		(start 411.640528 -142.559278)
		(end 411.640528 -142.902178)
		(width 0.1143)
		(layer "In9.Cu")
		(net "SATA6G_PCH_PCIE_UP_SATA_RXP<2>")
	)
	(segment
		(start 389.523478 -130.671316)
		(end 389.766048 -130.913886)
		(width 0.1143)
		(layer "In9.Cu")
		(net "SATA6G_PCH_PCIE_UP_SATA_RXP<2>")
	)
	(segment
		(start 413.27705 -149.9235)
		(end 418.378894 -149.9235)
		(width 0.1143)
		(layer "In9.Cu")
		(net "SATA6G_PCH_PCIE_UP_SATA_RXP<2>")
	)
	(segment
		(start 388.4676 -126.4158)
		(end 388.4676 -126.760224)
		(width 0.0889)
		(layer "In9.Cu")
		(net "SATA6G_PCH_PCIE_UP_SATA_RXP<2>")
	)
	(segment
		(start 411.475428 -139.181078)
		(end 411.475428 -140.882878)
		(width 0.1143)
		(layer "In9.Cu")
		(net "SATA6G_PCH_PCIE_UP_SATA_RXP<2>")
	)
	(segment
		(start 411.640528 -141.213078)
		(end 411.640528 -141.555978)
		(width 0.1143)
		(layer "In9.Cu")
		(net "SATA6G_PCH_PCIE_UP_SATA_RXP<2>")
	)
	(segment
		(start 401.853146 -130.693922)
		(end 402.646642 -129.900426)
		(width 0.1143)
		(layer "In9.Cu")
		(net "SATA6G_PCH_PCIE_UP_SATA_RXP<2>")
	)
	(segment
		(start 411.475428 -147.831556)
		(end 411.475682 -147.831302)
		(width 0.1143)
		(layer "In9.Cu")
		(net "SATA6G_PCH_PCIE_UP_SATA_RXP<2>")
	)
	(segment
		(start 413.122872 -135.32104)
		(end 413.122872 -138.140694)
		(width 0.1143)
		(layer "In9.Cu")
		(net "SATA6G_PCH_PCIE_UP_SATA_RXP<2>")
	)
	(segment
		(start 412.410656 -149.564344)
		(end 412.411164 -149.564852)
		(width 0.1143)
		(layer "In9.Cu")
		(net "SATA6G_PCH_PCIE_UP_SATA_RXP<2>")
	)
	(segment
		(start 412.010606 -139.882626)
		(end 412.010606 -139.181078)
		(width 0.1143)
		(layer "In9.Cu")
		(net "SATA6G_PCH_PCIE_UP_SATA_RXP<2>")
	)
	(segment
		(start 418.666422 -150.042626)
		(end 419.113716 -150.48992)
		(width 0.1143)
		(layer "In9.Cu")
		(net "SATA6G_PCH_PCIE_UP_SATA_RXP<2>")
	)
	(segment
		(start 412.039816 -149.19325)
		(end 412.410656 -149.56409)
		(width 0.1143)
		(layer "In9.Cu")
		(net "SATA6G_PCH_PCIE_UP_SATA_RXP<2>")
	)
	(segment
		(start 388.4676 -126.760224)
		(end 388.5184 -126.811024)
		(width 0.0889)
		(layer "In9.Cu")
		(net "SATA6G_PCH_PCIE_UP_SATA_RXP<2>")
	)
	(segment
		(start 388.74319 -130.124454)
		(end 389.173212 -130.554476)
		(width 0.1143)
		(layer "In9.Cu")
		(net "SATA6G_PCH_PCIE_UP_SATA_RXP<2>")
	)
	(segment
		(start 411.475428 -141.886178)
		(end 411.475428 -142.229078)
		(width 0.1143)
		(layer "In9.Cu")
		(net "SATA6G_PCH_PCIE_UP_SATA_RXP<2>")
	)
	(segment
		(start 419.40226 -151.22525)
		(end 419.620446 -151.22525)
		(width 0.1143)
		(layer "In9.Cu")
		(net "SATA6G_PCH_PCIE_UP_SATA_RXP<2>")
	)
	(segment
		(start 388.5184 -126.811024)
		(end 388.5184 -126.8222)
		(width 0.0889)
		(layer "In9.Cu")
		(net "SATA6G_PCH_PCIE_UP_SATA_RXP<2>")
	)
	(segment
		(start 413.383222 -138.401044)
		(end 413.651192 -138.401044)
		(width 0.1143)
		(layer "In9.Cu")
		(net "SATA6G_PCH_PCIE_UP_SATA_RXP<2>")
	)
	(segment
		(start 419.734746 -151.11095)
		(end 419.734746 -150.8633)
		(width 0.1143)
		(layer "In9.Cu")
		(net "SATA6G_PCH_PCIE_UP_SATA_RXP<2>")
	)
	(segment
		(start 388.5184 -126.8222)
		(end 388.5184 -129.581656)
		(width 0.1143)
		(layer "In9.Cu")
		(net "SATA6G_PCH_PCIE_UP_SATA_RXP<2>")
	)
	(segment
		(start 388.3279 -126.2761)
		(end 388.4676 -126.4158)
		(width 0.0889)
		(layer "In9.Cu")
		(net "SATA6G_PCH_PCIE_UP_SATA_RXP<2>")
	)
	(segment
		(start 390.834626 -132.21589)
		(end 391.077196 -132.45846)
		(width 0.1143)
		(layer "In9.Cu")
		(net "SATA6G_PCH_PCIE_UP_SATA_RXP<2>")
	)
	(segment
		(start 403.131782 -129.699512)
		(end 406.929844 -129.699512)
		(width 0.1143)
		(layer "In9.Cu")
		(net "SATA6G_PCH_PCIE_UP_SATA_RXP<2>")
	)
	(segment
		(start 413.651192 -139.505944)
		(end 413.31134 -139.505944)
		(width 0.1143)
		(layer "In9.Cu")
		(net "SATA6G_PCH_PCIE_UP_SATA_RXP<2>")
	)
	(segment
		(start 390.47547 -131.623308)
		(end 390.71804 -131.865878)
		(width 0.1143)
		(layer "In9.Cu")
		(net "SATA6G_PCH_PCIE_UP_SATA_RXP<2>")
	)
	(segment
		(start 413.122872 -139.694412)
		(end 413.122872 -139.882626)
		(width 0.1143)
		(layer "In9.Cu")
		(net "SATA6G_PCH_PCIE_UP_SATA_RXP<2>")
	)
	(segment
		(start 411.526482 -134.29615)
		(end 412.097982 -134.29615)
		(width 0.1143)
		(layer "In9.Cu")
		(net "SATA6G_PCH_PCIE_UP_SATA_RXP<2>")
	)
	(segment
		(start 388.3279 -123.803918)
		(end 388.3279 -126.2761)
		(width 0.0889)
		(layer "In9.Cu")
		(net "SATA6G_PCH_PCIE_UP_SATA_RXP<2>")
	)
	(segment
		(start 412.410656 -149.56409)
		(end 412.410656 -149.564344)
		(width 0.1143)
		(layer "In9.Cu")
		(net "SATA6G_PCH_PCIE_UP_SATA_RXP<2>")
	)
	(segment
		(start 389.882634 -131.263898)
		(end 390.125204 -131.506468)
		(width 0.1143)
		(layer "In9.Cu")
		(net "SATA6G_PCH_PCIE_UP_SATA_RXP<2>")
	)
	(segment
		(start 411.475428 -143.232378)
		(end 411.475428 -147.831556)
		(width 0.1143)
		(layer "In9.Cu")
		(net "SATA6G_PCH_PCIE_UP_SATA_RXP<2>")
	)
	(arc
		(start 411.640528 -141.555978)
		(mid 411.61776 -141.647775)
		(end 411.557978 -141.721078)
		(width 0.1143)
		(layer "In9.Cu")
		(net "SATA6G_PCH_PCIE_UP_SATA_RXP<2>")
	)
	(arc
		(start 410.642816 -133.412484)
		(mid 410.901636 -134.03733)
		(end 411.526482 -134.29615)
		(width 0.1143)
		(layer "In9.Cu")
		(net "SATA6G_PCH_PCIE_UP_SATA_RXP<2>")
	)
	(arc
		(start 419.620446 -151.22525)
		(mid 419.701268 -151.191772)
		(end 419.734746 -151.11095)
		(width 0.1143)
		(layer "In9.Cu")
		(net "SATA6G_PCH_PCIE_UP_SATA_RXP<2>")
	)
	(arc
		(start 419.113716 -150.48992)
		(mid 419.201867 -150.621707)
		(end 419.232842 -150.777194)
		(width 0.1143)
		(layer "In9.Cu")
		(net "SATA6G_PCH_PCIE_UP_SATA_RXP<2>")
	)
	(arc
		(start 391.077196 -132.45846)
		(mid 391.114371 -132.4833)
		(end 391.158222 -132.491988)
		(width 0.1143)
		(layer "In9.Cu")
		(net "SATA6G_PCH_PCIE_UP_SATA_RXP<2>")
	)
	(arc
		(start 411.475428 -142.229078)
		(mid 411.498196 -142.320875)
		(end 411.557978 -142.394178)
		(width 0.1143)
		(layer "In9.Cu")
		(net "SATA6G_PCH_PCIE_UP_SATA_RXP<2>")
	)
	(arc
		(start 390.71804 -131.865878)
		(mid 390.766899 -131.946825)
		(end 390.77646 -132.040884)
		(width 0.1143)
		(layer "In9.Cu")
		(net "SATA6G_PCH_PCIE_UP_SATA_RXP<2>")
	)
	(arc
		(start 390.77646 -132.040884)
		(mid 390.785925 -132.134907)
		(end 390.834626 -132.21589)
		(width 0.1143)
		(layer "In9.Cu")
		(net "SATA6G_PCH_PCIE_UP_SATA_RXP<2>")
	)
	(arc
		(start 418.378894 -149.9235)
		(mid 418.5345 -149.95447)
		(end 418.666422 -150.042626)
		(width 0.1143)
		(layer "In9.Cu")
		(net "SATA6G_PCH_PCIE_UP_SATA_RXP<2>")
	)
	(arc
		(start 411.475428 -140.882878)
		(mid 411.498196 -140.974675)
		(end 411.557978 -141.047978)
		(width 0.1143)
		(layer "In9.Cu")
		(net "SATA6G_PCH_PCIE_UP_SATA_RXP<2>")
	)
	(arc
		(start 411.557978 -142.394178)
		(mid 411.617804 -142.467459)
		(end 411.640528 -142.559278)
		(width 0.1143)
		(layer "In9.Cu")
		(net "SATA6G_PCH_PCIE_UP_SATA_RXP<2>")
	)
	(arc
		(start 388.527798 -123.474734)
		(mid 388.385718 -123.613727)
		(end 388.3279 -123.803918)
		(width 0.0889)
		(layer "In9.Cu")
		(net "SATA6G_PCH_PCIE_UP_SATA_RXP<2>")
	)
	(arc
		(start 389.766048 -130.913886)
		(mid 389.814907 -130.994833)
		(end 389.824468 -131.088892)
		(width 0.1143)
		(layer "In9.Cu")
		(net "SATA6G_PCH_PCIE_UP_SATA_RXP<2>")
	)
	(arc
		(start 387.73735 -122.104404)
		(mid 388.067759 -122.269241)
		(end 388.413244 -122.399552)
		(width 0.0889)
		(layer "In9.Cu")
		(net "SATA6G_PCH_PCIE_UP_SATA_RXP<2>")
	)
	(arc
		(start 412.010606 -139.181078)
		(mid 411.743144 -138.913616)
		(end 411.475428 -139.181078)
		(width 0.1143)
		(layer "In9.Cu")
		(net "SATA6G_PCH_PCIE_UP_SATA_RXP<2>")
	)
	(arc
		(start 413.651192 -138.401044)
		(mid 414.203642 -138.953494)
		(end 413.651192 -139.505944)
		(width 0.1143)
		(layer "In9.Cu")
		(net "SATA6G_PCH_PCIE_UP_SATA_RXP<2>")
	)
	(arc
		(start 388.5184 -129.581656)
		(mid 388.576814 -129.875413)
		(end 388.74319 -130.124454)
		(width 0.1143)
		(layer "In9.Cu")
		(net "SATA6G_PCH_PCIE_UP_SATA_RXP<2>")
	)
	(arc
		(start 413.122872 -139.882626)
		(mid 412.566866 -140.438632)
		(end 412.010606 -139.882626)
		(width 0.1143)
		(layer "In9.Cu")
		(net "SATA6G_PCH_PCIE_UP_SATA_RXP<2>")
	)
	(arc
		(start 411.557978 -141.721078)
		(mid 411.498152 -141.794359)
		(end 411.475428 -141.886178)
		(width 0.1143)
		(layer "In9.Cu")
		(net "SATA6G_PCH_PCIE_UP_SATA_RXP<2>")
	)
	(arc
		(start 411.640528 -142.902178)
		(mid 411.61776 -142.993975)
		(end 411.557978 -143.067278)
		(width 0.1143)
		(layer "In9.Cu")
		(net "SATA6G_PCH_PCIE_UP_SATA_RXP<2>")
	)
	(arc
		(start 411.475682 -147.831302)
		(mid 411.622311 -148.568367)
		(end 412.039816 -149.19325)
		(width 0.1143)
		(layer "In9.Cu")
		(net "SATA6G_PCH_PCIE_UP_SATA_RXP<2>")
	)
	(arc
		(start 411.557978 -143.067278)
		(mid 411.498152 -143.140559)
		(end 411.475428 -143.232378)
		(width 0.1143)
		(layer "In9.Cu")
		(net "SATA6G_PCH_PCIE_UP_SATA_RXP<2>")
	)
	(arc
		(start 413.122872 -138.140694)
		(mid 413.199127 -138.324789)
		(end 413.383222 -138.401044)
		(width 0.1143)
		(layer "In9.Cu")
		(net "SATA6G_PCH_PCIE_UP_SATA_RXP<2>")
	)
	(arc
		(start 419.232842 -151.055832)
		(mid 419.282463 -151.175629)
		(end 419.40226 -151.22525)
		(width 0.1143)
		(layer "In9.Cu")
		(net "SATA6G_PCH_PCIE_UP_SATA_RXP<2>")
	)
	(arc
		(start 397.51254 -132.491988)
		(mid 399.86168 -132.024679)
		(end 401.853146 -130.693922)
		(width 0.1143)
		(layer "In9.Cu")
		(net "SATA6G_PCH_PCIE_UP_SATA_RXP<2>")
	)
	(arc
		(start 389.824468 -131.088892)
		(mid 389.833933 -131.182915)
		(end 389.882634 -131.263898)
		(width 0.1143)
		(layer "In9.Cu")
		(net "SATA6G_PCH_PCIE_UP_SATA_RXP<2>")
	)
	(arc
		(start 411.557978 -141.047978)
		(mid 411.617804 -141.121259)
		(end 411.640528 -141.213078)
		(width 0.1143)
		(layer "In9.Cu")
		(net "SATA6G_PCH_PCIE_UP_SATA_RXP<2>")
	)
	(arc
		(start 389.348472 -130.612896)
		(mid 389.442521 -130.622486)
		(end 389.523478 -130.671316)
		(width 0.1143)
		(layer "In9.Cu")
		(net "SATA6G_PCH_PCIE_UP_SATA_RXP<2>")
	)
	(arc
		(start 389.173212 -130.554476)
		(mid 389.254279 -130.603375)
		(end 389.348472 -130.612896)
		(width 0.1143)
		(layer "In9.Cu")
		(net "SATA6G_PCH_PCIE_UP_SATA_RXP<2>")
	)
	(arc
		(start 402.646642 -129.900426)
		(mid 402.869255 -129.751807)
		(end 403.131782 -129.699512)
		(width 0.1143)
		(layer "In9.Cu")
		(net "SATA6G_PCH_PCIE_UP_SATA_RXP<2>")
	)
	(arc
		(start 388.413244 -122.399552)
		(mid 388.820804 -122.899813)
		(end 388.527798 -123.474734)
		(width 0.0889)
		(layer "In9.Cu")
		(net "SATA6G_PCH_PCIE_UP_SATA_RXP<2>")
	)
	(arc
		(start 390.300464 -131.564888)
		(mid 390.394513 -131.574478)
		(end 390.47547 -131.623308)
		(width 0.1143)
		(layer "In9.Cu")
		(net "SATA6G_PCH_PCIE_UP_SATA_RXP<2>")
	)
	(arc
		(start 413.31134 -139.505944)
		(mid 413.178073 -139.561145)
		(end 413.122872 -139.694412)
		(width 0.1143)
		(layer "In9.Cu")
		(net "SATA6G_PCH_PCIE_UP_SATA_RXP<2>")
	)
	(arc
		(start 390.125204 -131.506468)
		(mid 390.206271 -131.555367)
		(end 390.300464 -131.564888)
		(width 0.1143)
		(layer "In9.Cu")
		(net "SATA6G_PCH_PCIE_UP_SATA_RXP<2>")
	)
	(arc
		(start 406.929844 -129.699512)
		(mid 409.555312 -130.787016)
		(end 410.642816 -133.412484)
		(width 0.1143)
		(layer "In9.Cu")
		(net "SATA6G_PCH_PCIE_UP_SATA_RXP<2>")
	)
	(arc
		(start 412.097982 -134.29615)
		(mid 412.822689 -134.596333)
		(end 413.122872 -135.32104)
		(width 0.1143)
		(layer "In9.Cu")
		(net "SATA6G_PCH_PCIE_UP_SATA_RXP<2>")
	)
	(arc
		(start 412.411164 -149.564852)
		(mid 412.808436 -149.830301)
		(end 413.27705 -149.9235)
		(width 0.1143)
		(layer "In9.Cu")
		(net "SATA6G_PCH_PCIE_UP_SATA_RXP<2>")
	)
	(segment
		(start 388.72795 -122.7328)
		(end 389.22325 -122.962924)
		(width 0.1143)
		(layer "F.Cu")
		(net "SATA6G_PCH_PCIE_UP_SATA_RXP<1>")
	)
	(via
		(at 421.225726 -152.9715)
		(size 0.508)
		(drill 0.254)
		(layers "F.Cu" "B.Cu")
		(net "SATA6G_PCH_PCIE_UP_SATA_RXP<1>")
	)
	(via
		(at 389.22325 -122.962924)
		(size 0.508)
		(drill 0.254)
		(layers "F.Cu" "B.Cu")
		(net "SATA6G_PCH_PCIE_UP_SATA_RXP<1>")
	)
	(segment
		(start 422.284906 -153.35885)
		(end 421.340026 -153.35885)
		(width 0.1143)
		(layer "B.Cu")
		(net "SATA6G_PCH_PCIE_UP_SATA_RXP<1>")
	)
	(segment
		(start 422.656 -153.035)
		(end 422.365678 -153.325322)
		(width 0.1143)
		(layer "B.Cu")
		(net "SATA6G_PCH_PCIE_UP_SATA_RXP<1>")
	)
	(segment
		(start 421.225726 -153.24455)
		(end 421.225726 -152.9715)
		(width 0.1143)
		(layer "B.Cu")
		(net "SATA6G_PCH_PCIE_UP_SATA_RXP<1>")
	)
	(arc
		(start 422.365678 -153.325322)
		(mid 422.328619 -153.350084)
		(end 422.284906 -153.35885)
		(width 0.1143)
		(layer "B.Cu")
		(net "SATA6G_PCH_PCIE_UP_SATA_RXP<1>")
	)
	(arc
		(start 421.340026 -153.35885)
		(mid 421.259204 -153.325372)
		(end 421.225726 -153.24455)
		(width 0.1143)
		(layer "B.Cu")
		(net "SATA6G_PCH_PCIE_UP_SATA_RXP<1>")
	)
	(segment
		(start 412.863792 -132.396738)
		(end 412.451296 -131.984242)
		(width 0.1143)
		(layer "In9.Cu")
		(net "SATA6G_PCH_PCIE_UP_SATA_RXP<1>")
	)
	(segment
		(start 419.180264 -142.14094)
		(end 419.065456 -142.026132)
		(width 0.1143)
		(layer "In9.Cu")
		(net "SATA6G_PCH_PCIE_UP_SATA_RXP<1>")
	)
	(segment
		(start 420.035482 -149.310344)
		(end 419.649148 -149.310344)
		(width 0.1143)
		(layer "In9.Cu")
		(net "SATA6G_PCH_PCIE_UP_SATA_RXP<1>")
	)
	(segment
		(start 414.059624 -132.856478)
		(end 413.905192 -132.701792)
		(width 0.1143)
		(layer "In9.Cu")
		(net "SATA6G_PCH_PCIE_UP_SATA_RXP<1>")
	)
	(segment
		(start 414.041082 -133.827774)
		(end 414.040828 -133.827266)
		(width 0.1143)
		(layer "In9.Cu")
		(net "SATA6G_PCH_PCIE_UP_SATA_RXP<1>")
	)
	(segment
		(start 420.295832 -145.626836)
		(end 420.29126 -145.622264)
		(width 0.1143)
		(layer "In9.Cu")
		(net "SATA6G_PCH_PCIE_UP_SATA_RXP<1>")
	)
	(segment
		(start 420.29126 -145.622264)
		(end 420.286688 -145.617946)
		(width 0.1143)
		(layer "In9.Cu")
		(net "SATA6G_PCH_PCIE_UP_SATA_RXP<1>")
	)
	(segment
		(start 420.587932 -148.237194)
		(end 420.587932 -146.3294)
		(width 0.1143)
		(layer "In9.Cu")
		(net "SATA6G_PCH_PCIE_UP_SATA_RXP<1>")
	)
	(segment
		(start 413.97047 -137.142474)
		(end 413.97047 -136.704324)
		(width 0.1143)
		(layer "In9.Cu")
		(net "SATA6G_PCH_PCIE_UP_SATA_RXP<1>")
	)
	(segment
		(start 390.811258 -125.636528)
		(end 390.718548 -125.543818)
		(width 0.0889)
		(layer "In9.Cu")
		(net "SATA6G_PCH_PCIE_UP_SATA_RXP<1>")
	)
	(segment
		(start 411.25648 -129.266442)
		(end 411.004258 -129.01422)
		(width 0.1143)
		(layer "In9.Cu")
		(net "SATA6G_PCH_PCIE_UP_SATA_RXP<1>")
	)
	(segment
		(start 413.97047 -135.701024)
		(end 413.97047 -135.358124)
		(width 0.1143)
		(layer "In9.Cu")
		(net "SATA6G_PCH_PCIE_UP_SATA_RXP<1>")
	)
	(segment
		(start 413.97047 -134.354824)
		(end 413.97047 -134.011924)
		(width 0.1143)
		(layer "In9.Cu")
		(net "SATA6G_PCH_PCIE_UP_SATA_RXP<1>")
	)
	(segment
		(start 421.225726 -152.9715)
		(end 420.897304 -153.299922)
		(width 0.1143)
		(layer "In9.Cu")
		(net "SATA6G_PCH_PCIE_UP_SATA_RXP<1>")
	)
	(segment
		(start 410.617162 -128.8542)
		(end 402.739098 -128.8542)
		(width 0.1143)
		(layer "In9.Cu")
		(net "SATA6G_PCH_PCIE_UP_SATA_RXP<1>")
	)
	(segment
		(start 393.40536 -131.528312)
		(end 393.06246 -131.528312)
		(width 0.1143)
		(layer "In9.Cu")
		(net "SATA6G_PCH_PCIE_UP_SATA_RXP<1>")
	)
	(segment
		(start 390.9441 -127.9144)
		(end 390.9441 -127.892302)
		(width 0.0889)
		(layer "In9.Cu")
		(net "SATA6G_PCH_PCIE_UP_SATA_RXP<1>")
	)
	(segment
		(start 414.207452 -133.223)
		(end 414.207452 -133.213348)
		(width 0.1143)
		(layer "In9.Cu")
		(net "SATA6G_PCH_PCIE_UP_SATA_RXP<1>")
	)
	(segment
		(start 390.9441 -130.34391)
		(end 390.9441 -127.9144)
		(width 0.1143)
		(layer "In9.Cu")
		(net "SATA6G_PCH_PCIE_UP_SATA_RXP<1>")
	)
	(segment
		(start 419.457378 -144.508728)
		(end 419.457378 -142.810484)
		(width 0.1143)
		(layer "In9.Cu")
		(net "SATA6G_PCH_PCIE_UP_SATA_RXP<1>")
	)
	(segment
		(start 411.375352 -130.7338)
		(end 411.375352 -129.554224)
		(width 0.1143)
		(layer "In9.Cu")
		(net "SATA6G_PCH_PCIE_UP_SATA_RXP<1>")
	)
	(segment
		(start 390.718548 -125.543818)
		(end 390.718802 -125.543818)
		(width 0.0889)
		(layer "In9.Cu")
		(net "SATA6G_PCH_PCIE_UP_SATA_RXP<1>")
	)
	(segment
		(start 417.03879 -142.903194)
		(end 417.038028 -142.902432)
		(width 0.1143)
		(layer "In9.Cu")
		(net "SATA6G_PCH_PCIE_UP_SATA_RXP<1>")
	)
	(segment
		(start 389.05434 -123.25604)
		(end 389.22325 -122.962924)
		(width 0.0889)
		(layer "In9.Cu")
		(net "SATA6G_PCH_PCIE_UP_SATA_RXP<1>")
	)
	(segment
		(start 414.13557 -135.027924)
		(end 414.13557 -134.685024)
		(width 0.1143)
		(layer "In9.Cu")
		(net "SATA6G_PCH_PCIE_UP_SATA_RXP<1>")
	)
	(segment
		(start 411.741874 -131.27482)
		(end 411.499304 -131.03225)
		(width 0.1143)
		(layer "In9.Cu")
		(net "SATA6G_PCH_PCIE_UP_SATA_RXP<1>")
	)
	(segment
		(start 413.59963 -132.5753)
		(end 413.294576 -132.5753)
		(width 0.1143)
		(layer "In9.Cu")
		(net "SATA6G_PCH_PCIE_UP_SATA_RXP<1>")
	)
	(segment
		(start 420.816532 -153.33345)
		(end 420.702232 -153.33345)
		(width 0.1143)
		(layer "In9.Cu")
		(net "SATA6G_PCH_PCIE_UP_SATA_RXP<1>")
	)
	(segment
		(start 417.6522 -141.002004)
		(end 414.0962 -137.446004)
		(width 0.1143)
		(layer "In9.Cu")
		(net "SATA6G_PCH_PCIE_UP_SATA_RXP<1>")
	)
	(segment
		(start 392.73226 -131.693412)
		(end 392.38936 -131.693412)
		(width 0.1143)
		(layer "In9.Cu")
		(net "SATA6G_PCH_PCIE_UP_SATA_RXP<1>")
	)
	(segment
		(start 418.283644 -142.026132)
		(end 417.406582 -142.903194)
		(width 0.1143)
		(layer "In9.Cu")
		(net "SATA6G_PCH_PCIE_UP_SATA_RXP<1>")
	)
	(segment
		(start 414.040828 -133.827266)
		(end 414.076642 -133.787388)
		(width 0.1143)
		(layer "In9.Cu")
		(net "SATA6G_PCH_PCIE_UP_SATA_RXP<1>")
	)
	(segment
		(start 390.8933 -127.841502)
		(end 390.8933 -125.834394)
		(width 0.0889)
		(layer "In9.Cu")
		(net "SATA6G_PCH_PCIE_UP_SATA_RXP<1>")
	)
	(segment
		(start 389.318754 -124.10694)
		(end 389.3185 -124.107194)
		(width 0.0889)
		(layer "In9.Cu")
		(net "SATA6G_PCH_PCIE_UP_SATA_RXP<1>")
	)
	(segment
		(start 414.20796 -133.44144)
		(end 414.207452 -133.223)
		(width 0.1143)
		(layer "In9.Cu")
		(net "SATA6G_PCH_PCIE_UP_SATA_RXP<1>")
	)
	(segment
		(start 417.038028 -142.53464)
		(end 417.6522 -141.920468)
		(width 0.1143)
		(layer "In9.Cu")
		(net "SATA6G_PCH_PCIE_UP_SATA_RXP<1>")
	)
	(segment
		(start 420.587932 -153.21915)
		(end 420.587932 -149.862794)
		(width 0.1143)
		(layer "In9.Cu")
		(net "SATA6G_PCH_PCIE_UP_SATA_RXP<1>")
	)
	(segment
		(start 397.333724 -131.693412)
		(end 393.73556 -131.693412)
		(width 0.1143)
		(layer "In9.Cu")
		(net "SATA6G_PCH_PCIE_UP_SATA_RXP<1>")
	)
	(segment
		(start 389.07847 -123.345448)
		(end 389.05434 -123.25604)
		(width 0.0889)
		(layer "In9.Cu")
		(net "SATA6G_PCH_PCIE_UP_SATA_RXP<1>")
	)
	(segment
		(start 389.3185 -124.107194)
		(end 389.3185 -123.799854)
		(width 0.0889)
		(layer "In9.Cu")
		(net "SATA6G_PCH_PCIE_UP_SATA_RXP<1>")
	)
	(segment
		(start 390.9441 -127.892302)
		(end 390.8933 -127.841502)
		(width 0.0889)
		(layer "In9.Cu")
		(net "SATA6G_PCH_PCIE_UP_SATA_RXP<1>")
	)
	(segment
		(start 390.718802 -125.543818)
		(end 389.344662 -124.169678)
		(width 0.0889)
		(layer "In9.Cu")
		(net "SATA6G_PCH_PCIE_UP_SATA_RXP<1>")
	)
	(segment
		(start 419.649148 -148.789644)
		(end 420.035482 -148.789644)
		(width 0.1143)
		(layer "In9.Cu")
		(net "SATA6G_PCH_PCIE_UP_SATA_RXP<1>")
	)
	(segment
		(start 392.026902 -131.543044)
		(end 391.026904 -130.543046)
		(width 0.1143)
		(layer "In9.Cu")
		(net "SATA6G_PCH_PCIE_UP_SATA_RXP<1>")
	)
	(segment
		(start 402.451316 -128.973072)
		(end 401.426426 -129.997962)
		(width 0.1143)
		(layer "In9.Cu")
		(net "SATA6G_PCH_PCIE_UP_SATA_RXP<1>")
	)
	(segment
		(start 412.334456 -131.633976)
		(end 412.091886 -131.391406)
		(width 0.1143)
		(layer "In9.Cu")
		(net "SATA6G_PCH_PCIE_UP_SATA_RXP<1>")
	)
	(segment
		(start 420.286688 -145.617946)
		(end 419.655244 -144.986502)
		(width 0.1143)
		(layer "In9.Cu")
		(net "SATA6G_PCH_PCIE_UP_SATA_RXP<1>")
	)
	(segment
		(start 414.13557 -136.374124)
		(end 414.13557 -136.031224)
		(width 0.1143)
		(layer "In9.Cu")
		(net "SATA6G_PCH_PCIE_UP_SATA_RXP<1>")
	)
	(arc
		(start 419.649148 -149.310344)
		(mid 419.388798 -149.049994)
		(end 419.649148 -148.789644)
		(width 0.1143)
		(layer "In9.Cu")
		(net "SATA6G_PCH_PCIE_UP_SATA_RXP<1>")
	)
	(arc
		(start 419.065456 -142.026132)
		(mid 418.67455 -141.864213)
		(end 418.283644 -142.026132)
		(width 0.1143)
		(layer "In9.Cu")
		(net "SATA6G_PCH_PCIE_UP_SATA_RXP<1>")
	)
	(arc
		(start 391.026904 -130.543046)
		(mid 390.96572 -130.451711)
		(end 390.9441 -130.34391)
		(width 0.1143)
		(layer "In9.Cu")
		(net "SATA6G_PCH_PCIE_UP_SATA_RXP<1>")
	)
	(arc
		(start 420.897304 -153.299922)
		(mid 420.860245 -153.324684)
		(end 420.816532 -153.33345)
		(width 0.1143)
		(layer "In9.Cu")
		(net "SATA6G_PCH_PCIE_UP_SATA_RXP<1>")
	)
	(arc
		(start 414.05302 -135.193024)
		(mid 414.112846 -135.119743)
		(end 414.13557 -135.027924)
		(width 0.1143)
		(layer "In9.Cu")
		(net "SATA6G_PCH_PCIE_UP_SATA_RXP<1>")
	)
	(arc
		(start 414.207452 -133.213348)
		(mid 414.207508 -133.205982)
		(end 414.207452 -133.198616)
		(width 0.1143)
		(layer "In9.Cu")
		(net "SATA6G_PCH_PCIE_UP_SATA_RXP<1>")
	)
	(arc
		(start 414.13557 -136.031224)
		(mid 414.112802 -135.939427)
		(end 414.05302 -135.866124)
		(width 0.1143)
		(layer "In9.Cu")
		(net "SATA6G_PCH_PCIE_UP_SATA_RXP<1>")
	)
	(arc
		(start 392.89736 -131.610862)
		(mid 392.824079 -131.670688)
		(end 392.73226 -131.693412)
		(width 0.1143)
		(layer "In9.Cu")
		(net "SATA6G_PCH_PCIE_UP_SATA_RXP<1>")
	)
	(arc
		(start 411.004258 -129.01422)
		(mid 410.826628 -128.895687)
		(end 410.617162 -128.8542)
		(width 0.1143)
		(layer "In9.Cu")
		(net "SATA6G_PCH_PCIE_UP_SATA_RXP<1>")
	)
	(arc
		(start 413.294576 -132.5753)
		(mid 413.061443 -132.528833)
		(end 412.863792 -132.396738)
		(width 0.1143)
		(layer "In9.Cu")
		(net "SATA6G_PCH_PCIE_UP_SATA_RXP<1>")
	)
	(arc
		(start 420.587932 -149.862794)
		(mid 420.426123 -149.472153)
		(end 420.035482 -149.310344)
		(width 0.1143)
		(layer "In9.Cu")
		(net "SATA6G_PCH_PCIE_UP_SATA_RXP<1>")
	)
	(arc
		(start 412.451296 -131.984242)
		(mid 412.402397 -131.903175)
		(end 412.392876 -131.808982)
		(width 0.1143)
		(layer "In9.Cu")
		(net "SATA6G_PCH_PCIE_UP_SATA_RXP<1>")
	)
	(arc
		(start 412.392876 -131.808982)
		(mid 412.383286 -131.714933)
		(end 412.334456 -131.633976)
		(width 0.1143)
		(layer "In9.Cu")
		(net "SATA6G_PCH_PCIE_UP_SATA_RXP<1>")
	)
	(arc
		(start 419.655244 -144.986502)
		(mid 419.508776 -144.767297)
		(end 419.457378 -144.508728)
		(width 0.1143)
		(layer "In9.Cu")
		(net "SATA6G_PCH_PCIE_UP_SATA_RXP<1>")
	)
	(arc
		(start 411.91688 -131.332986)
		(mid 411.822857 -131.323521)
		(end 411.741874 -131.27482)
		(width 0.1143)
		(layer "In9.Cu")
		(net "SATA6G_PCH_PCIE_UP_SATA_RXP<1>")
	)
	(arc
		(start 413.97047 -136.704324)
		(mid 413.993238 -136.612527)
		(end 414.05302 -136.539224)
		(width 0.1143)
		(layer "In9.Cu")
		(net "SATA6G_PCH_PCIE_UP_SATA_RXP<1>")
	)
	(arc
		(start 413.905192 -132.701792)
		(mid 413.765012 -132.608123)
		(end 413.59963 -132.5753)
		(width 0.1143)
		(layer "In9.Cu")
		(net "SATA6G_PCH_PCIE_UP_SATA_RXP<1>")
	)
	(arc
		(start 414.13557 -134.685024)
		(mid 414.112802 -134.593227)
		(end 414.05302 -134.519924)
		(width 0.1143)
		(layer "In9.Cu")
		(net "SATA6G_PCH_PCIE_UP_SATA_RXP<1>")
	)
	(arc
		(start 414.05302 -136.539224)
		(mid 414.112846 -136.465943)
		(end 414.13557 -136.374124)
		(width 0.1143)
		(layer "In9.Cu")
		(net "SATA6G_PCH_PCIE_UP_SATA_RXP<1>")
	)
	(arc
		(start 393.06246 -131.528312)
		(mid 392.970663 -131.55108)
		(end 392.89736 -131.610862)
		(width 0.1143)
		(layer "In9.Cu")
		(net "SATA6G_PCH_PCIE_UP_SATA_RXP<1>")
	)
	(arc
		(start 411.375352 -129.554224)
		(mid 411.344495 -129.398536)
		(end 411.25648 -129.266442)
		(width 0.1143)
		(layer "In9.Cu")
		(net "SATA6G_PCH_PCIE_UP_SATA_RXP<1>")
	)
	(arc
		(start 420.587932 -146.3294)
		(mid 420.511991 -145.948972)
		(end 420.295832 -145.626836)
		(width 0.1143)
		(layer "In9.Cu")
		(net "SATA6G_PCH_PCIE_UP_SATA_RXP<1>")
	)
	(arc
		(start 419.457378 -142.810484)
		(mid 419.385363 -142.448171)
		(end 419.180264 -142.14094)
		(width 0.1143)
		(layer "In9.Cu")
		(net "SATA6G_PCH_PCIE_UP_SATA_RXP<1>")
	)
	(arc
		(start 389.344662 -124.169678)
		(mid 389.325429 -124.140894)
		(end 389.318754 -124.10694)
		(width 0.0889)
		(layer "In9.Cu")
		(net "SATA6G_PCH_PCIE_UP_SATA_RXP<1>")
	)
	(arc
		(start 401.426426 -129.997962)
		(mid 399.548721 -131.252794)
		(end 397.333724 -131.693412)
		(width 0.1143)
		(layer "In9.Cu")
		(net "SATA6G_PCH_PCIE_UP_SATA_RXP<1>")
	)
	(arc
		(start 414.0962 -137.446004)
		(mid 414.003149 -137.306743)
		(end 413.97047 -137.142474)
		(width 0.1143)
		(layer "In9.Cu")
		(net "SATA6G_PCH_PCIE_UP_SATA_RXP<1>")
	)
	(arc
		(start 413.97047 -134.011924)
		(mid 413.98872 -133.913305)
		(end 414.041082 -133.827774)
		(width 0.1143)
		(layer "In9.Cu")
		(net "SATA6G_PCH_PCIE_UP_SATA_RXP<1>")
	)
	(arc
		(start 402.739098 -128.8542)
		(mid 402.58341 -128.885057)
		(end 402.451316 -128.973072)
		(width 0.1143)
		(layer "In9.Cu")
		(net "SATA6G_PCH_PCIE_UP_SATA_RXP<1>")
	)
	(arc
		(start 411.499304 -131.03225)
		(mid 411.407674 -130.895349)
		(end 411.375352 -130.7338)
		(width 0.1143)
		(layer "In9.Cu")
		(net "SATA6G_PCH_PCIE_UP_SATA_RXP<1>")
	)
	(arc
		(start 392.38936 -131.693412)
		(mid 392.193178 -131.654277)
		(end 392.026902 -131.543044)
		(width 0.1143)
		(layer "In9.Cu")
		(net "SATA6G_PCH_PCIE_UP_SATA_RXP<1>")
	)
	(arc
		(start 417.038028 -142.902432)
		(mid 416.961856 -142.718536)
		(end 417.038028 -142.53464)
		(width 0.1143)
		(layer "In9.Cu")
		(net "SATA6G_PCH_PCIE_UP_SATA_RXP<1>")
	)
	(arc
		(start 412.091886 -131.391406)
		(mid 412.010939 -131.342547)
		(end 411.91688 -131.332986)
		(width 0.1143)
		(layer "In9.Cu")
		(net "SATA6G_PCH_PCIE_UP_SATA_RXP<1>")
	)
	(arc
		(start 414.05302 -135.866124)
		(mid 413.993194 -135.792843)
		(end 413.97047 -135.701024)
		(width 0.1143)
		(layer "In9.Cu")
		(net "SATA6G_PCH_PCIE_UP_SATA_RXP<1>")
	)
	(arc
		(start 389.3185 -123.799854)
		(mid 389.250471 -123.545189)
		(end 389.07847 -123.345448)
		(width 0.0889)
		(layer "In9.Cu")
		(net "SATA6G_PCH_PCIE_UP_SATA_RXP<1>")
	)
	(arc
		(start 390.8933 -125.834394)
		(mid 390.871978 -125.727292)
		(end 390.811258 -125.636528)
		(width 0.0889)
		(layer "In9.Cu")
		(net "SATA6G_PCH_PCIE_UP_SATA_RXP<1>")
	)
	(arc
		(start 417.406582 -142.903194)
		(mid 417.222686 -142.979366)
		(end 417.03879 -142.903194)
		(width 0.1143)
		(layer "In9.Cu")
		(net "SATA6G_PCH_PCIE_UP_SATA_RXP<1>")
	)
	(arc
		(start 420.702232 -153.33345)
		(mid 420.62141 -153.299972)
		(end 420.587932 -153.21915)
		(width 0.1143)
		(layer "In9.Cu")
		(net "SATA6G_PCH_PCIE_UP_SATA_RXP<1>")
	)
	(arc
		(start 393.73556 -131.693412)
		(mid 393.643763 -131.670644)
		(end 393.57046 -131.610862)
		(width 0.1143)
		(layer "In9.Cu")
		(net "SATA6G_PCH_PCIE_UP_SATA_RXP<1>")
	)
	(arc
		(start 414.207452 -133.198616)
		(mid 414.166162 -133.013446)
		(end 414.059624 -132.856478)
		(width 0.1143)
		(layer "In9.Cu")
		(net "SATA6G_PCH_PCIE_UP_SATA_RXP<1>")
	)
	(arc
		(start 414.05302 -134.519924)
		(mid 413.993194 -134.446643)
		(end 413.97047 -134.354824)
		(width 0.1143)
		(layer "In9.Cu")
		(net "SATA6G_PCH_PCIE_UP_SATA_RXP<1>")
	)
	(arc
		(start 413.97047 -135.358124)
		(mid 413.993238 -135.266327)
		(end 414.05302 -135.193024)
		(width 0.1143)
		(layer "In9.Cu")
		(net "SATA6G_PCH_PCIE_UP_SATA_RXP<1>")
	)
	(arc
		(start 417.6522 -141.920468)
		(mid 417.84242 -141.461236)
		(end 417.6522 -141.002004)
		(width 0.1143)
		(layer "In9.Cu")
		(net "SATA6G_PCH_PCIE_UP_SATA_RXP<1>")
	)
	(arc
		(start 420.035482 -148.789644)
		(mid 420.426123 -148.627835)
		(end 420.587932 -148.237194)
		(width 0.1143)
		(layer "In9.Cu")
		(net "SATA6G_PCH_PCIE_UP_SATA_RXP<1>")
	)
	(arc
		(start 414.076642 -133.787388)
		(mid 414.17443 -133.626615)
		(end 414.20796 -133.44144)
		(width 0.1143)
		(layer "In9.Cu")
		(net "SATA6G_PCH_PCIE_UP_SATA_RXP<1>")
	)
	(arc
		(start 393.57046 -131.610862)
		(mid 393.497179 -131.551036)
		(end 393.40536 -131.528312)
		(width 0.1143)
		(layer "In9.Cu")
		(net "SATA6G_PCH_PCIE_UP_SATA_RXP<1>")
	)
	(segment
		(start 390.21385 -121.87428)
		(end 390.640316 -122.0724)
		(width 0.1143)
		(layer "F.Cu")
		(net "SATA6G_PCH_PCIE_UP_SATA_RXP<0>")
	)
	(segment
		(start 390.640316 -122.0724)
		(end 390.70915 -122.104404)
		(width 0.1143)
		(layer "F.Cu")
		(net "SATA6G_PCH_PCIE_UP_SATA_RXP<0>")
	)
	(via
		(at 390.70915 -122.104404)
		(size 0.508)
		(drill 0.254)
		(layers "F.Cu" "B.Cu")
		(net "SATA6G_PCH_PCIE_UP_SATA_RXP<0>")
	)
	(via
		(at 421.81272 -149.0345)
		(size 0.508)
		(drill 0.254)
		(layers "F.Cu" "B.Cu")
		(net "SATA6G_PCH_PCIE_UP_SATA_RXP<0>")
	)
	(segment
		(start 421.81272 -149.0345)
		(end 421.81272 -149.307042)
		(width 0.1143)
		(layer "B.Cu")
		(net "SATA6G_PCH_PCIE_UP_SATA_RXP<0>")
	)
	(segment
		(start 422.411906 -149.387814)
		(end 422.70172 -149.098)
		(width 0.1143)
		(layer "B.Cu")
		(net "SATA6G_PCH_PCIE_UP_SATA_RXP<0>")
	)
	(segment
		(start 421.92702 -149.421342)
		(end 422.331134 -149.421342)
		(width 0.1143)
		(layer "B.Cu")
		(net "SATA6G_PCH_PCIE_UP_SATA_RXP<0>")
	)
	(arc
		(start 421.81272 -149.307042)
		(mid 421.846198 -149.387864)
		(end 421.92702 -149.421342)
		(width 0.1143)
		(layer "B.Cu")
		(net "SATA6G_PCH_PCIE_UP_SATA_RXP<0>")
	)
	(arc
		(start 422.331134 -149.421342)
		(mid 422.374875 -149.412641)
		(end 422.411906 -149.387814)
		(width 0.1143)
		(layer "B.Cu")
		(net "SATA6G_PCH_PCIE_UP_SATA_RXP<0>")
	)
	(segment
		(start 391.1092 -122.125994)
		(end 391.1092 -122.093228)
		(width 0.0889)
		(layer "In9.Cu")
		(net "SATA6G_PCH_PCIE_UP_SATA_RXP<0>")
	)
	(segment
		(start 395.507972 -126.268734)
		(end 395.423644 -126.184406)
		(width 0.1143)
		(layer "In9.Cu")
		(net "SATA6G_PCH_PCIE_UP_SATA_RXP<0>")
	)
	(segment
		(start 409.204414 -127.404368)
		(end 408.861514 -127.404368)
		(width 0.1143)
		(layer "In9.Cu")
		(net "SATA6G_PCH_PCIE_UP_SATA_RXP<0>")
	)
	(segment
		(start 393.865354 -124.590302)
		(end 393.566904 -124.590302)
		(width 0.0889)
		(layer "In9.Cu")
		(net "SATA6G_PCH_PCIE_UP_SATA_RXP<0>")
	)
	(segment
		(start 420.260018 -141.11859)
		(end 417.266628 -138.1252)
		(width 0.1143)
		(layer "In9.Cu")
		(net "SATA6G_PCH_PCIE_UP_SATA_RXP<0>")
	)
	(segment
		(start 421.657526 -141.504162)
		(end 421.191436 -141.504162)
		(width 0.1143)
		(layer "In9.Cu")
		(net "SATA6G_PCH_PCIE_UP_SATA_RXP<0>")
	)
	(segment
		(start 412.569914 -127.569468)
		(end 412.227014 -127.569468)
		(width 0.1143)
		(layer "In9.Cu")
		(net "SATA6G_PCH_PCIE_UP_SATA_RXP<0>")
	)
	(segment
		(start 410.550614 -127.404368)
		(end 410.207714 -127.404368)
		(width 0.1143)
		(layer "In9.Cu")
		(net "SATA6G_PCH_PCIE_UP_SATA_RXP<0>")
	)
	(segment
		(start 430.196498 -142.6972)
		(end 423.644314 -142.6972)
		(width 0.1143)
		(layer "In9.Cu")
		(net "SATA6G_PCH_PCIE_UP_SATA_RXP<0>")
	)
	(segment
		(start 397.903446 -130.1496)
		(end 397.800322 -130.1496)
		(width 0.1143)
		(layer "In9.Cu")
		(net "SATA6G_PCH_PCIE_UP_SATA_RXP<0>")
	)
	(segment
		(start 413.572452 -127.404368)
		(end 412.900114 -127.404368)
		(width 0.1143)
		(layer "In9.Cu")
		(net "SATA6G_PCH_PCIE_UP_SATA_RXP<0>")
	)
	(segment
		(start 391.6045 -122.984514)
		(end 391.6045 -122.951748)
		(width 0.0889)
		(layer "In9.Cu")
		(net "SATA6G_PCH_PCIE_UP_SATA_RXP<0>")
	)
	(segment
		(start 396.795498 -129.733802)
		(end 395.74978 -128.687576)
		(width 0.1143)
		(layer "In9.Cu")
		(net "SATA6G_PCH_PCIE_UP_SATA_RXP<0>")
	)
	(segment
		(start 411.223714 -127.569468)
		(end 410.880814 -127.569468)
		(width 0.1143)
		(layer "In9.Cu")
		(net "SATA6G_PCH_PCIE_UP_SATA_RXP<0>")
	)
	(segment
		(start 430.083468 -145.251932)
		(end 430.627282 -144.708118)
		(width 0.1143)
		(layer "In9.Cu")
		(net "SATA6G_PCH_PCIE_UP_SATA_RXP<0>")
	)
	(segment
		(start 390.571736 -121.770902)
		(end 390.55421 -121.835672)
		(width 0.0889)
		(layer "In9.Cu")
		(net "SATA6G_PCH_PCIE_UP_SATA_RXP<0>")
	)
	(segment
		(start 395.423644 -126.184406)
		(end 395.40815 -126.168912)
		(width 0.0889)
		(layer "In9.Cu")
		(net "SATA6G_PCH_PCIE_UP_SATA_RXP<0>")
	)
	(segment
		(start 390.695688 -121.7041)
		(end 390.654794 -121.70537)
		(width 0.0889)
		(layer "In9.Cu")
		(net "SATA6G_PCH_PCIE_UP_SATA_RXP<0>")
	)
	(segment
		(start 406.118822 -127.569468)
		(end 405.775922 -127.569468)
		(width 0.1143)
		(layer "In9.Cu")
		(net "SATA6G_PCH_PCIE_UP_SATA_RXP<0>")
	)
	(segment
		(start 422.6433 -149.198838)
		(end 422.6433 -147.799298)
		(width 0.1143)
		(layer "In9.Cu")
		(net "SATA6G_PCH_PCIE_UP_SATA_RXP<0>")
	)
	(segment
		(start 411.896814 -127.404368)
		(end 411.553914 -127.404368)
		(width 0.1143)
		(layer "In9.Cu")
		(net "SATA6G_PCH_PCIE_UP_SATA_RXP<0>")
	)
	(segment
		(start 416.524186 -132.971286)
		(end 415.025078 -131.472178)
		(width 0.1143)
		(layer "In9.Cu")
		(net "SATA6G_PCH_PCIE_UP_SATA_RXP<0>")
	)
	(segment
		(start 421.81272 -149.0345)
		(end 422.117774 -149.339554)
		(width 0.1143)
		(layer "In9.Cu")
		(net "SATA6G_PCH_PCIE_UP_SATA_RXP<0>")
	)
	(segment
		(start 392.944604 -124.590302)
		(end 392.677904 -124.590302)
		(width 0.0889)
		(layer "In9.Cu")
		(net "SATA6G_PCH_PCIE_UP_SATA_RXP<0>")
	)
	(segment
		(start 393.389104 -124.679202)
		(end 393.122404 -124.679202)
		(width 0.0889)
		(layer "In9.Cu")
		(net "SATA6G_PCH_PCIE_UP_SATA_RXP<0>")
	)
	(segment
		(start 422.198546 -149.373082)
		(end 422.469056 -149.373082)
		(width 0.1143)
		(layer "In9.Cu")
		(net "SATA6G_PCH_PCIE_UP_SATA_RXP<0>")
	)
	(segment
		(start 422.893998 -142.386558)
		(end 422.261538 -141.754352)
		(width 0.1143)
		(layer "In9.Cu")
		(net "SATA6G_PCH_PCIE_UP_SATA_RXP<0>")
	)
	(segment
		(start 416.796982 -136.990836)
		(end 416.796982 -133.6294)
		(width 0.1143)
		(layer "In9.Cu")
		(net "SATA6G_PCH_PCIE_UP_SATA_RXP<0>")
	)
	(segment
		(start 424.985942 -145.6182)
		(end 429.199802 -145.6182)
		(width 0.1143)
		(layer "In9.Cu")
		(net "SATA6G_PCH_PCIE_UP_SATA_RXP<0>")
	)
	(segment
		(start 394.36802 -125.182122)
		(end 394.179298 -124.993654)
		(width 0.0889)
		(layer "In9.Cu")
		(net "SATA6G_PCH_PCIE_UP_SATA_RXP<0>")
	)
	(segment
		(start 392.0998 -124.012452)
		(end 392.0998 -123.810268)
		(width 0.0889)
		(layer "In9.Cu")
		(net "SATA6G_PCH_PCIE_UP_SATA_RXP<0>")
	)
	(segment
		(start 405.445722 -127.404368)
		(end 405.102822 -127.404368)
		(width 0.1143)
		(layer "In9.Cu")
		(net "SATA6G_PCH_PCIE_UP_SATA_RXP<0>")
	)
	(segment
		(start 404.099522 -127.404368)
		(end 403.756622 -127.404368)
		(width 0.1143)
		(layer "In9.Cu")
		(net "SATA6G_PCH_PCIE_UP_SATA_RXP<0>")
	)
	(segment
		(start 395.40815 -126.096776)
		(end 395.185138 -125.873764)
		(width 0.0889)
		(layer "In9.Cu")
		(net "SATA6G_PCH_PCIE_UP_SATA_RXP<0>")
	)
	(segment
		(start 404.772622 -127.569468)
		(end 404.429722 -127.569468)
		(width 0.1143)
		(layer "In9.Cu")
		(net "SATA6G_PCH_PCIE_UP_SATA_RXP<0>")
	)
	(segment
		(start 403.426422 -127.569468)
		(end 403.083522 -127.569468)
		(width 0.1143)
		(layer "In9.Cu")
		(net "SATA6G_PCH_PCIE_UP_SATA_RXP<0>")
	)
	(segment
		(start 414.508696 -130.225292)
		(end 414.508696 -128.340612)
		(width 0.1143)
		(layer "In9.Cu")
		(net "SATA6G_PCH_PCIE_UP_SATA_RXP<0>")
	)
	(segment
		(start 394.11656 -124.804932)
		(end 393.927838 -124.616464)
		(width 0.0889)
		(layer "In9.Cu")
		(net "SATA6G_PCH_PCIE_UP_SATA_RXP<0>")
	)
	(segment
		(start 402.753322 -127.404368)
		(end 402.410168 -127.404368)
		(width 0.1143)
		(layer "In9.Cu")
		(net "SATA6G_PCH_PCIE_UP_SATA_RXP<0>")
	)
	(segment
		(start 394.744956 -125.433582)
		(end 394.556488 -125.245114)
		(width 0.0889)
		(layer "In9.Cu")
		(net "SATA6G_PCH_PCIE_UP_SATA_RXP<0>")
	)
	(segment
		(start 401.957286 -127.592074)
		(end 400.45767 -129.09169)
		(width 0.1143)
		(layer "In9.Cu")
		(net "SATA6G_PCH_PCIE_UP_SATA_RXP<0>")
	)
	(segment
		(start 408.531314 -127.569468)
		(end 408.188414 -127.569468)
		(width 0.1143)
		(layer "In9.Cu")
		(net "SATA6G_PCH_PCIE_UP_SATA_RXP<0>")
	)
	(segment
		(start 407.858214 -127.404368)
		(end 406.449022 -127.404368)
		(width 0.1143)
		(layer "In9.Cu")
		(net "SATA6G_PCH_PCIE_UP_SATA_RXP<0>")
	)
	(segment
		(start 409.877514 -127.569468)
		(end 409.534614 -127.569468)
		(width 0.1143)
		(layer "In9.Cu")
		(net "SATA6G_PCH_PCIE_UP_SATA_RXP<0>")
	)
	(segment
		(start 392.479784 -124.50826)
		(end 392.181842 -124.210318)
		(width 0.0889)
		(layer "In9.Cu")
		(net "SATA6G_PCH_PCIE_UP_SATA_RXP<0>")
	)
	(segment
		(start 390.55421 -121.835672)
		(end 390.70915 -122.104404)
		(width 0.0889)
		(layer "In9.Cu")
		(net "SATA6G_PCH_PCIE_UP_SATA_RXP<0>")
	)
	(segment
		(start 395.5415 -128.184148)
		(end 395.5415 -126.349506)
		(width 0.1143)
		(layer "In9.Cu")
		(net "SATA6G_PCH_PCIE_UP_SATA_RXP<0>")
	)
	(segment
		(start 395.40815 -126.168912)
		(end 395.40815 -126.096776)
		(width 0.0889)
		(layer "In9.Cu")
		(net "SATA6G_PCH_PCIE_UP_SATA_RXP<0>")
	)
	(segment
		(start 394.996416 -125.810772)
		(end 394.807948 -125.622304)
		(width 0.0889)
		(layer "In9.Cu")
		(net "SATA6G_PCH_PCIE_UP_SATA_RXP<0>")
	)
	(segment
		(start 422.995344 -146.948398)
		(end 423.858944 -146.084798)
		(width 0.1143)
		(layer "In9.Cu")
		(net "SATA6G_PCH_PCIE_UP_SATA_RXP<0>")
	)
	(segment
		(start 430.8602 -144.145762)
		(end 430.8602 -143.360902)
		(width 0.1143)
		(layer "In9.Cu")
		(net "SATA6G_PCH_PCIE_UP_SATA_RXP<0>")
	)
	(arc
		(start 390.654794 -121.70537)
		(mid 390.602478 -121.724456)
		(end 390.571736 -121.770902)
		(width 0.0889)
		(layer "In9.Cu")
		(net "SATA6G_PCH_PCIE_UP_SATA_RXP<0>")
	)
	(arc
		(start 393.122404 -124.679202)
		(mid 393.073878 -124.665137)
		(end 393.033504 -124.634752)
		(width 0.0889)
		(layer "In9.Cu")
		(net "SATA6G_PCH_PCIE_UP_SATA_RXP<0>")
	)
	(arc
		(start 394.147802 -124.89942)
		(mid 394.140913 -124.84928)
		(end 394.11656 -124.804932)
		(width 0.0889)
		(layer "In9.Cu")
		(net "SATA6G_PCH_PCIE_UP_SATA_RXP<0>")
	)
	(arc
		(start 394.807948 -125.622304)
		(mid 394.783596 -125.578073)
		(end 394.776452 -125.52807)
		(width 0.0889)
		(layer "In9.Cu")
		(net "SATA6G_PCH_PCIE_UP_SATA_RXP<0>")
	)
	(arc
		(start 404.937722 -127.486918)
		(mid 404.864441 -127.546744)
		(end 404.772622 -127.569468)
		(width 0.1143)
		(layer "In9.Cu")
		(net "SATA6G_PCH_PCIE_UP_SATA_RXP<0>")
	)
	(arc
		(start 408.188414 -127.569468)
		(mid 408.096617 -127.5467)
		(end 408.023314 -127.486918)
		(width 0.1143)
		(layer "In9.Cu")
		(net "SATA6G_PCH_PCIE_UP_SATA_RXP<0>")
	)
	(arc
		(start 394.179298 -124.993654)
		(mid 394.154865 -124.949433)
		(end 394.147802 -124.89942)
		(width 0.0889)
		(layer "In9.Cu")
		(net "SATA6G_PCH_PCIE_UP_SATA_RXP<0>")
	)
	(arc
		(start 410.042614 -127.486918)
		(mid 409.969333 -127.546744)
		(end 409.877514 -127.569468)
		(width 0.1143)
		(layer "In9.Cu")
		(net "SATA6G_PCH_PCIE_UP_SATA_RXP<0>")
	)
	(arc
		(start 395.090904 -125.842268)
		(mid 395.04074 -125.835262)
		(end 394.996416 -125.810772)
		(width 0.0889)
		(layer "In9.Cu")
		(net "SATA6G_PCH_PCIE_UP_SATA_RXP<0>")
	)
	(arc
		(start 391.1092 -122.093228)
		(mid 391.05285 -121.899378)
		(end 390.909048 -121.757694)
		(width 0.0889)
		(layer "In9.Cu")
		(net "SATA6G_PCH_PCIE_UP_SATA_RXP<0>")
	)
	(arc
		(start 402.410168 -127.404368)
		(mid 402.165079 -127.453213)
		(end 401.957286 -127.592074)
		(width 0.1143)
		(layer "In9.Cu")
		(net "SATA6G_PCH_PCIE_UP_SATA_RXP<0>")
	)
	(arc
		(start 412.227014 -127.569468)
		(mid 412.135217 -127.5467)
		(end 412.061914 -127.486918)
		(width 0.1143)
		(layer "In9.Cu")
		(net "SATA6G_PCH_PCIE_UP_SATA_RXP<0>")
	)
	(arc
		(start 400.45767 -129.09169)
		(mid 399.285796 -129.874745)
		(end 397.903446 -130.1496)
		(width 0.1143)
		(layer "In9.Cu")
		(net "SATA6G_PCH_PCIE_UP_SATA_RXP<0>")
	)
	(arc
		(start 405.102822 -127.404368)
		(mid 405.011025 -127.427136)
		(end 404.937722 -127.486918)
		(width 0.1143)
		(layer "In9.Cu")
		(net "SATA6G_PCH_PCIE_UP_SATA_RXP<0>")
	)
	(arc
		(start 393.033504 -124.634752)
		(mid 392.993148 -124.604331)
		(end 392.944604 -124.590302)
		(width 0.0889)
		(layer "In9.Cu")
		(net "SATA6G_PCH_PCIE_UP_SATA_RXP<0>")
	)
	(arc
		(start 395.5415 -126.349506)
		(mid 395.532799 -126.305765)
		(end 395.507972 -126.268734)
		(width 0.1143)
		(layer "In9.Cu")
		(net "SATA6G_PCH_PCIE_UP_SATA_RXP<0>")
	)
	(arc
		(start 430.8602 -143.360902)
		(mid 430.665806 -142.891594)
		(end 430.196498 -142.6972)
		(width 0.1143)
		(layer "In9.Cu")
		(net "SATA6G_PCH_PCIE_UP_SATA_RXP<0>")
	)
	(arc
		(start 408.696414 -127.486918)
		(mid 408.623133 -127.546744)
		(end 408.531314 -127.569468)
		(width 0.1143)
		(layer "In9.Cu")
		(net "SATA6G_PCH_PCIE_UP_SATA_RXP<0>")
	)
	(arc
		(start 429.199802 -145.6182)
		(mid 429.678063 -145.522956)
		(end 430.083468 -145.251932)
		(width 0.1143)
		(layer "In9.Cu")
		(net "SATA6G_PCH_PCIE_UP_SATA_RXP<0>")
	)
	(arc
		(start 416.796982 -133.6294)
		(mid 416.726038 -133.27321)
		(end 416.524186 -132.971286)
		(width 0.1143)
		(layer "In9.Cu")
		(net "SATA6G_PCH_PCIE_UP_SATA_RXP<0>")
	)
	(arc
		(start 409.369514 -127.486918)
		(mid 409.296233 -127.427092)
		(end 409.204414 -127.404368)
		(width 0.1143)
		(layer "In9.Cu")
		(net "SATA6G_PCH_PCIE_UP_SATA_RXP<0>")
	)
	(arc
		(start 404.264622 -127.486918)
		(mid 404.191341 -127.427092)
		(end 404.099522 -127.404368)
		(width 0.1143)
		(layer "In9.Cu")
		(net "SATA6G_PCH_PCIE_UP_SATA_RXP<0>")
	)
	(arc
		(start 406.449022 -127.404368)
		(mid 406.357225 -127.427136)
		(end 406.283922 -127.486918)
		(width 0.1143)
		(layer "In9.Cu")
		(net "SATA6G_PCH_PCIE_UP_SATA_RXP<0>")
	)
	(arc
		(start 392.0998 -123.810268)
		(mid 392.04345 -123.616418)
		(end 391.899648 -123.474734)
		(width 0.0889)
		(layer "In9.Cu")
		(net "SATA6G_PCH_PCIE_UP_SATA_RXP<0>")
	)
	(arc
		(start 393.566904 -124.590302)
		(mid 393.518378 -124.604367)
		(end 393.478004 -124.634752)
		(width 0.0889)
		(layer "In9.Cu")
		(net "SATA6G_PCH_PCIE_UP_SATA_RXP<0>")
	)
	(arc
		(start 393.927838 -124.616464)
		(mid 393.899186 -124.597197)
		(end 393.865354 -124.590302)
		(width 0.0889)
		(layer "In9.Cu")
		(net "SATA6G_PCH_PCIE_UP_SATA_RXP<0>")
	)
	(arc
		(start 410.880814 -127.569468)
		(mid 410.789017 -127.5467)
		(end 410.715714 -127.486918)
		(width 0.1143)
		(layer "In9.Cu")
		(net "SATA6G_PCH_PCIE_UP_SATA_RXP<0>")
	)
	(arc
		(start 421.191436 -141.504162)
		(mid 420.687392 -141.403995)
		(end 420.260018 -141.11859)
		(width 0.1143)
		(layer "In9.Cu")
		(net "SATA6G_PCH_PCIE_UP_SATA_RXP<0>")
	)
	(arc
		(start 411.388814 -127.486918)
		(mid 411.315533 -127.546744)
		(end 411.223714 -127.569468)
		(width 0.1143)
		(layer "In9.Cu")
		(net "SATA6G_PCH_PCIE_UP_SATA_RXP<0>")
	)
	(arc
		(start 394.776452 -125.52807)
		(mid 394.769446 -125.477906)
		(end 394.744956 -125.433582)
		(width 0.0889)
		(layer "In9.Cu")
		(net "SATA6G_PCH_PCIE_UP_SATA_RXP<0>")
	)
	(arc
		(start 403.591522 -127.486918)
		(mid 403.518241 -127.546744)
		(end 403.426422 -127.569468)
		(width 0.1143)
		(layer "In9.Cu")
		(net "SATA6G_PCH_PCIE_UP_SATA_RXP<0>")
	)
	(arc
		(start 406.283922 -127.486918)
		(mid 406.210641 -127.546744)
		(end 406.118822 -127.569468)
		(width 0.1143)
		(layer "In9.Cu")
		(net "SATA6G_PCH_PCIE_UP_SATA_RXP<0>")
	)
	(arc
		(start 395.185138 -125.873764)
		(mid 395.140907 -125.849412)
		(end 395.090904 -125.842268)
		(width 0.0889)
		(layer "In9.Cu")
		(net "SATA6G_PCH_PCIE_UP_SATA_RXP<0>")
	)
	(arc
		(start 422.261538 -141.754352)
		(mid 421.984402 -141.569209)
		(end 421.657526 -141.504162)
		(width 0.1143)
		(layer "In9.Cu")
		(net "SATA6G_PCH_PCIE_UP_SATA_RXP<0>")
	)
	(arc
		(start 412.735014 -127.486918)
		(mid 412.661733 -127.546744)
		(end 412.569914 -127.569468)
		(width 0.1143)
		(layer "In9.Cu")
		(net "SATA6G_PCH_PCIE_UP_SATA_RXP<0>")
	)
	(arc
		(start 397.800322 -130.1496)
		(mid 397.256566 -130.041628)
		(end 396.795498 -129.733802)
		(width 0.1143)
		(layer "In9.Cu")
		(net "SATA6G_PCH_PCIE_UP_SATA_RXP<0>")
	)
	(arc
		(start 391.899648 -123.474734)
		(mid 391.688784 -123.26773)
		(end 391.6045 -122.984514)
		(width 0.0889)
		(layer "In9.Cu")
		(net "SATA6G_PCH_PCIE_UP_SATA_RXP<0>")
	)
	(arc
		(start 395.74978 -128.687576)
		(mid 395.595609 -128.456559)
		(end 395.5415 -128.184148)
		(width 0.1143)
		(layer "In9.Cu")
		(net "SATA6G_PCH_PCIE_UP_SATA_RXP<0>")
	)
	(arc
		(start 394.462254 -125.213618)
		(mid 394.412227 -125.206562)
		(end 394.36802 -125.182122)
		(width 0.0889)
		(layer "In9.Cu")
		(net "SATA6G_PCH_PCIE_UP_SATA_RXP<0>")
	)
	(arc
		(start 408.023314 -127.486918)
		(mid 407.950033 -127.427092)
		(end 407.858214 -127.404368)
		(width 0.1143)
		(layer "In9.Cu")
		(net "SATA6G_PCH_PCIE_UP_SATA_RXP<0>")
	)
	(arc
		(start 423.644314 -142.6972)
		(mid 423.238224 -142.616575)
		(end 422.893998 -142.386558)
		(width 0.1143)
		(layer "In9.Cu")
		(net "SATA6G_PCH_PCIE_UP_SATA_RXP<0>")
	)
	(arc
		(start 412.061914 -127.486918)
		(mid 411.988633 -127.427092)
		(end 411.896814 -127.404368)
		(width 0.1143)
		(layer "In9.Cu")
		(net "SATA6G_PCH_PCIE_UP_SATA_RXP<0>")
	)
	(arc
		(start 403.083522 -127.569468)
		(mid 402.991725 -127.5467)
		(end 402.918422 -127.486918)
		(width 0.1143)
		(layer "In9.Cu")
		(net "SATA6G_PCH_PCIE_UP_SATA_RXP<0>")
	)
	(arc
		(start 392.677904 -124.590302)
		(mid 392.57068 -124.569014)
		(end 392.479784 -124.50826)
		(width 0.0889)
		(layer "In9.Cu")
		(net "SATA6G_PCH_PCIE_UP_SATA_RXP<0>")
	)
	(arc
		(start 403.756622 -127.404368)
		(mid 403.664825 -127.427136)
		(end 403.591522 -127.486918)
		(width 0.1143)
		(layer "In9.Cu")
		(net "SATA6G_PCH_PCIE_UP_SATA_RXP<0>")
	)
	(arc
		(start 422.469056 -149.373082)
		(mid 422.592265 -149.322047)
		(end 422.6433 -149.198838)
		(width 0.1143)
		(layer "In9.Cu")
		(net "SATA6G_PCH_PCIE_UP_SATA_RXP<0>")
	)
	(arc
		(start 417.266628 -138.1252)
		(mid 416.918957 -137.604734)
		(end 416.796982 -136.990836)
		(width 0.1143)
		(layer "In9.Cu")
		(net "SATA6G_PCH_PCIE_UP_SATA_RXP<0>")
	)
	(arc
		(start 410.715714 -127.486918)
		(mid 410.642433 -127.427092)
		(end 410.550614 -127.404368)
		(width 0.1143)
		(layer "In9.Cu")
		(net "SATA6G_PCH_PCIE_UP_SATA_RXP<0>")
	)
	(arc
		(start 430.627282 -144.708118)
		(mid 430.799626 -144.450093)
		(end 430.8602 -144.145762)
		(width 0.1143)
		(layer "In9.Cu")
		(net "SATA6G_PCH_PCIE_UP_SATA_RXP<0>")
	)
	(arc
		(start 422.6433 -147.799298)
		(mid 422.734635 -147.338804)
		(end 422.995344 -146.948398)
		(width 0.1143)
		(layer "In9.Cu")
		(net "SATA6G_PCH_PCIE_UP_SATA_RXP<0>")
	)
	(arc
		(start 412.900114 -127.404368)
		(mid 412.808317 -127.427136)
		(end 412.735014 -127.486918)
		(width 0.1143)
		(layer "In9.Cu")
		(net "SATA6G_PCH_PCIE_UP_SATA_RXP<0>")
	)
	(arc
		(start 393.478004 -124.634752)
		(mid 393.437648 -124.665173)
		(end 393.389104 -124.679202)
		(width 0.0889)
		(layer "In9.Cu")
		(net "SATA6G_PCH_PCIE_UP_SATA_RXP<0>")
	)
	(arc
		(start 405.775922 -127.569468)
		(mid 405.684125 -127.5467)
		(end 405.610822 -127.486918)
		(width 0.1143)
		(layer "In9.Cu")
		(net "SATA6G_PCH_PCIE_UP_SATA_RXP<0>")
	)
	(arc
		(start 414.508696 -128.340612)
		(mid 414.234476 -127.678588)
		(end 413.572452 -127.404368)
		(width 0.1143)
		(layer "In9.Cu")
		(net "SATA6G_PCH_PCIE_UP_SATA_RXP<0>")
	)
	(arc
		(start 411.553914 -127.404368)
		(mid 411.462117 -127.427136)
		(end 411.388814 -127.486918)
		(width 0.1143)
		(layer "In9.Cu")
		(net "SATA6G_PCH_PCIE_UP_SATA_RXP<0>")
	)
	(arc
		(start 391.6045 -122.951748)
		(mid 391.54815 -122.757898)
		(end 391.404348 -122.616214)
		(width 0.0889)
		(layer "In9.Cu")
		(net "SATA6G_PCH_PCIE_UP_SATA_RXP<0>")
	)
	(arc
		(start 391.404348 -122.616214)
		(mid 391.193484 -122.40921)
		(end 391.1092 -122.125994)
		(width 0.0889)
		(layer "In9.Cu")
		(net "SATA6G_PCH_PCIE_UP_SATA_RXP<0>")
	)
	(arc
		(start 404.429722 -127.569468)
		(mid 404.337925 -127.5467)
		(end 404.264622 -127.486918)
		(width 0.1143)
		(layer "In9.Cu")
		(net "SATA6G_PCH_PCIE_UP_SATA_RXP<0>")
	)
	(arc
		(start 394.556488 -125.245114)
		(mid 394.512266 -125.220718)
		(end 394.462254 -125.213618)
		(width 0.0889)
		(layer "In9.Cu")
		(net "SATA6G_PCH_PCIE_UP_SATA_RXP<0>")
	)
	(arc
		(start 392.181842 -124.210318)
		(mid 392.121076 -124.119565)
		(end 392.0998 -124.012452)
		(width 0.0889)
		(layer "In9.Cu")
		(net "SATA6G_PCH_PCIE_UP_SATA_RXP<0>")
	)
	(arc
		(start 402.918422 -127.486918)
		(mid 402.845141 -127.427092)
		(end 402.753322 -127.404368)
		(width 0.1143)
		(layer "In9.Cu")
		(net "SATA6G_PCH_PCIE_UP_SATA_RXP<0>")
	)
	(arc
		(start 415.025078 -131.472178)
		(mid 414.642804 -130.900115)
		(end 414.508696 -130.225292)
		(width 0.1143)
		(layer "In9.Cu")
		(net "SATA6G_PCH_PCIE_UP_SATA_RXP<0>")
	)
	(arc
		(start 390.909048 -121.757694)
		(mid 390.806121 -121.715959)
		(end 390.695688 -121.7041)
		(width 0.0889)
		(layer "In9.Cu")
		(net "SATA6G_PCH_PCIE_UP_SATA_RXP<0>")
	)
	(arc
		(start 409.534614 -127.569468)
		(mid 409.442817 -127.5467)
		(end 409.369514 -127.486918)
		(width 0.1143)
		(layer "In9.Cu")
		(net "SATA6G_PCH_PCIE_UP_SATA_RXP<0>")
	)
	(arc
		(start 423.858944 -146.084798)
		(mid 424.376044 -145.73941)
		(end 424.985942 -145.6182)
		(width 0.1143)
		(layer "In9.Cu")
		(net "SATA6G_PCH_PCIE_UP_SATA_RXP<0>")
	)
	(arc
		(start 422.117774 -149.339554)
		(mid 422.154833 -149.364316)
		(end 422.198546 -149.373082)
		(width 0.1143)
		(layer "In9.Cu")
		(net "SATA6G_PCH_PCIE_UP_SATA_RXP<0>")
	)
	(arc
		(start 410.207714 -127.404368)
		(mid 410.115917 -127.427136)
		(end 410.042614 -127.486918)
		(width 0.1143)
		(layer "In9.Cu")
		(net "SATA6G_PCH_PCIE_UP_SATA_RXP<0>")
	)
	(arc
		(start 405.610822 -127.486918)
		(mid 405.537541 -127.427092)
		(end 405.445722 -127.404368)
		(width 0.1143)
		(layer "In9.Cu")
		(net "SATA6G_PCH_PCIE_UP_SATA_RXP<0>")
	)
	(arc
		(start 408.861514 -127.404368)
		(mid 408.769717 -127.427136)
		(end 408.696414 -127.486918)
		(width 0.1143)
		(layer "In9.Cu")
		(net "SATA6G_PCH_PCIE_UP_SATA_RXP<0>")
	)
	(segment
		(start 412.606236 -147.175728)
		(end 413.244284 -147.813776)
		(width 0.1143)
		(layer "B.Cu")
		(net "SATA6G_P7_TX_C_DP")
	)
	(segment
		(start 411.548834 -147.292822)
		(end 411.645862 -147.195794)
		(width 0.1143)
		(layer "B.Cu")
		(net "SATA6G_P7_TX_C_DP")
	)
	(segment
		(start 409.6004 -146.939)
		(end 409.954222 -147.292822)
		(width 0.1143)
		(layer "B.Cu")
		(net "SATA6G_P7_TX_C_DP")
	)
	(segment
		(start 411.94609 -147.071334)
		(end 412.354522 -147.071334)
		(width 0.1143)
		(layer "B.Cu")
		(net "SATA6G_P7_TX_C_DP")
	)
	(segment
		(start 413.512254 -147.832826)
		(end 413.775906 -147.340066)
		(width 0.1143)
		(layer "B.Cu")
		(net "SATA6G_P7_TX_C_DP")
	)
	(segment
		(start 413.356298 -147.879054)
		(end 413.357314 -147.879562)
		(width 0.1143)
		(layer "B.Cu")
		(net "SATA6G_P7_TX_C_DP")
	)
	(segment
		(start 410.034994 -147.32635)
		(end 411.468062 -147.32635)
		(width 0.1143)
		(layer "B.Cu")
		(net "SATA6G_P7_TX_C_DP")
	)
	(segment
		(start 413.271208 -147.833842)
		(end 413.356298 -147.879054)
		(width 0.1143)
		(layer "B.Cu")
		(net "SATA6G_P7_TX_C_DP")
	)
	(arc
		(start 411.468062 -147.32635)
		(mid 411.511803 -147.317649)
		(end 411.548834 -147.292822)
		(width 0.1143)
		(layer "B.Cu")
		(net "SATA6G_P7_TX_C_DP")
	)
	(arc
		(start 413.357314 -147.879562)
		(mid 413.444448 -147.888308)
		(end 413.512254 -147.832826)
		(width 0.1143)
		(layer "B.Cu")
		(net "SATA6G_P7_TX_C_DP")
	)
	(arc
		(start 412.354522 -147.071334)
		(mid 412.490745 -147.098524)
		(end 412.606236 -147.175728)
		(width 0.1143)
		(layer "B.Cu")
		(net "SATA6G_P7_TX_C_DP")
	)
	(arc
		(start 409.954222 -147.292822)
		(mid 409.991281 -147.317584)
		(end 410.034994 -147.32635)
		(width 0.1143)
		(layer "B.Cu")
		(net "SATA6G_P7_TX_C_DP")
	)
	(arc
		(start 411.645862 -147.195794)
		(mid 411.783594 -147.103701)
		(end 411.94609 -147.071334)
		(width 0.1143)
		(layer "B.Cu")
		(net "SATA6G_P7_TX_C_DP")
	)
	(arc
		(start 413.244284 -147.813776)
		(mid 413.257013 -147.824791)
		(end 413.271208 -147.833842)
		(width 0.1143)
		(layer "B.Cu")
		(net "SATA6G_P7_TX_C_DP")
	)
	(segment
		(start 411.94609 -147.312634)
		(end 412.354268 -147.312634)
		(width 0.1143)
		(layer "B.Cu")
		(net "SATA6G_P7_TX_C_DN")
	)
	(segment
		(start 413.243014 -148.092414)
		(end 413.243268 -148.092414)
		(width 0.1143)
		(layer "B.Cu")
		(net "SATA6G_P7_TX_C_DN")
	)
	(segment
		(start 409.6004 -147.955)
		(end 409.954222 -147.601178)
		(width 0.1143)
		(layer "B.Cu")
		(net "SATA6G_P7_TX_C_DN")
	)
	(segment
		(start 410.034994 -147.56765)
		(end 410.377894 -147.56765)
		(width 0.1143)
		(layer "B.Cu")
		(net "SATA6G_P7_TX_C_DN")
	)
	(segment
		(start 411.177994 -147.56765)
		(end 411.468316 -147.56765)
		(width 0.1143)
		(layer "B.Cu")
		(net "SATA6G_P7_TX_C_DN")
	)
	(segment
		(start 411.719522 -147.46351)
		(end 411.81655 -147.366482)
		(width 0.1143)
		(layer "B.Cu")
		(net "SATA6G_P7_TX_C_DN")
	)
	(segment
		(start 413.290004 -148.2471)
		(end 413.026098 -148.740114)
		(width 0.1143)
		(layer "B.Cu")
		(net "SATA6G_P7_TX_C_DN")
	)
	(segment
		(start 412.435548 -147.346416)
		(end 413.073342 -147.984464)
		(width 0.1143)
		(layer "B.Cu")
		(net "SATA6G_P7_TX_C_DN")
	)
	(segment
		(start 410.606494 -147.68195)
		(end 410.949394 -147.68195)
		(width 0.1143)
		(layer "B.Cu")
		(net "SATA6G_P7_TX_C_DN")
	)
	(segment
		(start 413.157416 -148.046948)
		(end 413.243014 -148.092414)
		(width 0.1143)
		(layer "B.Cu")
		(net "SATA6G_P7_TX_C_DN")
	)
	(segment
		(start 411.81655 -147.366482)
		(end 411.816804 -147.366482)
		(width 0.1143)
		(layer "B.Cu")
		(net "SATA6G_P7_TX_C_DN")
	)
	(arc
		(start 410.377894 -147.56765)
		(mid 410.440808 -147.584707)
		(end 410.492194 -147.6248)
		(width 0.1143)
		(layer "B.Cu")
		(net "SATA6G_P7_TX_C_DN")
	)
	(arc
		(start 409.954222 -147.601178)
		(mid 409.991281 -147.576416)
		(end 410.034994 -147.56765)
		(width 0.1143)
		(layer "B.Cu")
		(net "SATA6G_P7_TX_C_DN")
	)
	(arc
		(start 411.468316 -147.56765)
		(mid 411.604262 -147.540533)
		(end 411.719522 -147.46351)
		(width 0.1143)
		(layer "B.Cu")
		(net "SATA6G_P7_TX_C_DN")
	)
	(arc
		(start 412.354268 -147.312634)
		(mid 412.398286 -147.321408)
		(end 412.435548 -147.346416)
		(width 0.1143)
		(layer "B.Cu")
		(net "SATA6G_P7_TX_C_DN")
	)
	(arc
		(start 413.073342 -147.984464)
		(mid 413.113066 -148.018818)
		(end 413.157416 -148.046948)
		(width 0.1143)
		(layer "B.Cu")
		(net "SATA6G_P7_TX_C_DN")
	)
	(arc
		(start 411.816804 -147.366482)
		(mid 411.876092 -147.326711)
		(end 411.94609 -147.312634)
		(width 0.1143)
		(layer "B.Cu")
		(net "SATA6G_P7_TX_C_DN")
	)
	(arc
		(start 411.063694 -147.6248)
		(mid 411.115099 -147.584746)
		(end 411.177994 -147.56765)
		(width 0.1143)
		(layer "B.Cu")
		(net "SATA6G_P7_TX_C_DN")
	)
	(arc
		(start 410.949394 -147.68195)
		(mid 411.012308 -147.664893)
		(end 411.063694 -147.6248)
		(width 0.1143)
		(layer "B.Cu")
		(net "SATA6G_P7_TX_C_DN")
	)
	(arc
		(start 413.243268 -148.092414)
		(mid 413.298693 -148.160097)
		(end 413.290004 -148.2471)
		(width 0.1143)
		(layer "B.Cu")
		(net "SATA6G_P7_TX_C_DN")
	)
	(arc
		(start 410.492194 -147.6248)
		(mid 410.543599 -147.664854)
		(end 410.606494 -147.68195)
		(width 0.1143)
		(layer "B.Cu")
		(net "SATA6G_P7_TX_C_DN")
	)
	(segment
		(start 409.31211 -153.86431)
		(end 409.0416 -153.5938)
		(width 0.1143)
		(layer "B.Cu")
		(net "SATA6G_P7_RX_C_DP")
	)
	(segment
		(start 412.242254 -154.559)
		(end 410.49829 -154.559)
		(width 0.1143)
		(layer "B.Cu")
		(net "SATA6G_P7_RX_C_DP")
	)
	(segment
		(start 409.643072 -153.897838)
		(end 409.392882 -153.897838)
		(width 0.1143)
		(layer "B.Cu")
		(net "SATA6G_P7_RX_C_DP")
	)
	(segment
		(start 413.357314 -155.479496)
		(end 413.356298 -155.478988)
		(width 0.1143)
		(layer "B.Cu")
		(net "SATA6G_P7_RX_C_DP")
	)
	(segment
		(start 413.356298 -155.478988)
		(end 413.271208 -155.433776)
		(width 0.1143)
		(layer "B.Cu")
		(net "SATA6G_P7_RX_C_DP")
	)
	(segment
		(start 413.775906 -154.94)
		(end 413.512254 -155.43276)
		(width 0.1143)
		(layer "B.Cu")
		(net "SATA6G_P7_RX_C_DP")
	)
	(segment
		(start 413.244284 -155.41371)
		(end 412.493714 -154.66314)
		(width 0.1143)
		(layer "B.Cu")
		(net "SATA6G_P7_RX_C_DP")
	)
	(segment
		(start 410.417772 -154.525472)
		(end 409.894278 -154.001978)
		(width 0.1143)
		(layer "B.Cu")
		(net "SATA6G_P7_RX_C_DP")
	)
	(arc
		(start 409.894278 -154.001978)
		(mid 409.779025 -153.924938)
		(end 409.643072 -153.897838)
		(width 0.1143)
		(layer "B.Cu")
		(net "SATA6G_P7_RX_C_DP")
	)
	(arc
		(start 412.493714 -154.66314)
		(mid 412.378343 -154.586052)
		(end 412.242254 -154.559)
		(width 0.1143)
		(layer "B.Cu")
		(net "SATA6G_P7_RX_C_DP")
	)
	(arc
		(start 410.49829 -154.559)
		(mid 410.454686 -154.550251)
		(end 410.417772 -154.525472)
		(width 0.1143)
		(layer "B.Cu")
		(net "SATA6G_P7_RX_C_DP")
	)
	(arc
		(start 413.512254 -155.43276)
		(mid 413.444478 -155.488341)
		(end 413.357314 -155.479496)
		(width 0.1143)
		(layer "B.Cu")
		(net "SATA6G_P7_RX_C_DP")
	)
	(arc
		(start 413.271208 -155.433776)
		(mid 413.256997 -155.424746)
		(end 413.244284 -155.41371)
		(width 0.1143)
		(layer "B.Cu")
		(net "SATA6G_P7_RX_C_DP")
	)
	(arc
		(start 409.392882 -153.897838)
		(mid 409.349141 -153.889137)
		(end 409.31211 -153.86431)
		(width 0.1143)
		(layer "B.Cu")
		(net "SATA6G_P7_RX_C_DP")
	)
	(segment
		(start 409.351734 -154.172666)
		(end 409.0416 -154.4828)
		(width 0.1143)
		(layer "B.Cu")
		(net "SATA6G_P7_RX_C_DN")
	)
	(segment
		(start 412.242508 -154.8003)
		(end 411.641544 -154.8003)
		(width 0.1143)
		(layer "B.Cu")
		(net "SATA6G_P7_RX_C_DN")
	)
	(segment
		(start 413.073342 -155.584398)
		(end 412.323026 -154.833828)
		(width 0.1143)
		(layer "B.Cu")
		(net "SATA6G_P7_RX_C_DN")
	)
	(segment
		(start 410.247084 -154.69616)
		(end 409.72359 -154.172666)
		(width 0.1143)
		(layer "B.Cu")
		(net "SATA6G_P7_RX_C_DN")
	)
	(segment
		(start 410.841444 -154.8003)
		(end 410.498544 -154.8003)
		(width 0.1143)
		(layer "B.Cu")
		(net "SATA6G_P7_RX_C_DN")
	)
	(segment
		(start 413.026098 -156.340048)
		(end 413.290004 -155.847034)
		(width 0.1143)
		(layer "B.Cu")
		(net "SATA6G_P7_RX_C_DN")
	)
	(segment
		(start 413.243014 -155.692348)
		(end 413.157416 -155.646882)
		(width 0.1143)
		(layer "B.Cu")
		(net "SATA6G_P7_RX_C_DN")
	)
	(segment
		(start 409.642818 -154.139138)
		(end 409.432506 -154.139138)
		(width 0.1143)
		(layer "B.Cu")
		(net "SATA6G_P7_RX_C_DN")
	)
	(segment
		(start 411.412944 -154.9146)
		(end 411.070044 -154.9146)
		(width 0.1143)
		(layer "B.Cu")
		(net "SATA6G_P7_RX_C_DN")
	)
	(segment
		(start 413.243268 -155.692348)
		(end 413.243014 -155.692348)
		(width 0.1143)
		(layer "B.Cu")
		(net "SATA6G_P7_RX_C_DN")
	)
	(arc
		(start 411.641544 -154.8003)
		(mid 411.57863 -154.817357)
		(end 411.527244 -154.85745)
		(width 0.1143)
		(layer "B.Cu")
		(net "SATA6G_P7_RX_C_DN")
	)
	(arc
		(start 409.432506 -154.139138)
		(mid 409.388765 -154.147839)
		(end 409.351734 -154.172666)
		(width 0.1143)
		(layer "B.Cu")
		(net "SATA6G_P7_RX_C_DN")
	)
	(arc
		(start 413.290004 -155.847034)
		(mid 413.298578 -155.760066)
		(end 413.243268 -155.692348)
		(width 0.1143)
		(layer "B.Cu")
		(net "SATA6G_P7_RX_C_DN")
	)
	(arc
		(start 410.498544 -154.8003)
		(mid 410.362462 -154.773232)
		(end 410.247084 -154.69616)
		(width 0.1143)
		(layer "B.Cu")
		(net "SATA6G_P7_RX_C_DN")
	)
	(arc
		(start 413.157416 -155.646882)
		(mid 413.113068 -155.61875)
		(end 413.073342 -155.584398)
		(width 0.1143)
		(layer "B.Cu")
		(net "SATA6G_P7_RX_C_DN")
	)
	(arc
		(start 409.72359 -154.172666)
		(mid 409.686531 -154.147904)
		(end 409.642818 -154.139138)
		(width 0.1143)
		(layer "B.Cu")
		(net "SATA6G_P7_RX_C_DN")
	)
	(arc
		(start 411.070044 -154.9146)
		(mid 411.00713 -154.897543)
		(end 410.955744 -154.85745)
		(width 0.1143)
		(layer "B.Cu")
		(net "SATA6G_P7_RX_C_DN")
	)
	(arc
		(start 411.527244 -154.85745)
		(mid 411.475839 -154.897504)
		(end 411.412944 -154.9146)
		(width 0.1143)
		(layer "B.Cu")
		(net "SATA6G_P7_RX_C_DN")
	)
	(arc
		(start 412.323026 -154.833828)
		(mid 412.286085 -154.809115)
		(end 412.242508 -154.8003)
		(width 0.1143)
		(layer "B.Cu")
		(net "SATA6G_P7_RX_C_DN")
	)
	(arc
		(start 410.955744 -154.85745)
		(mid 410.904339 -154.817396)
		(end 410.841444 -154.8003)
		(width 0.1143)
		(layer "B.Cu")
		(net "SATA6G_P7_RX_C_DN")
	)
	(segment
		(start 413.534098 -143.992092)
		(end 413.775906 -143.539972)
		(width 0.1143)
		(layer "B.Cu")
		(net "SATA6G_P6_TX_C_DP")
	)
	(segment
		(start 411.537912 -141.412468)
		(end 411.694884 -141.412468)
		(width 0.1143)
		(layer "B.Cu")
		(net "SATA6G_P6_TX_C_DP")
	)
	(segment
		(start 412.084012 -142.85341)
		(end 413.14243 -143.912336)
		(width 0.1143)
		(layer "B.Cu")
		(net "SATA6G_P6_TX_C_DP")
	)
	(segment
		(start 413.14243 -143.912336)
		(end 413.379158 -144.038828)
		(width 0.1143)
		(layer "B.Cu")
		(net "SATA6G_P6_TX_C_DP")
	)
	(segment
		(start 412.050484 -141.768068)
		(end 412.050484 -142.772638)
		(width 0.1143)
		(layer "B.Cu")
		(net "SATA6G_P6_TX_C_DP")
	)
	(segment
		(start 411.099 -141.0208)
		(end 411.45714 -141.37894)
		(width 0.1143)
		(layer "B.Cu")
		(net "SATA6G_P6_TX_C_DP")
	)
	(arc
		(start 412.050484 -142.772638)
		(mid 412.059185 -142.816379)
		(end 412.084012 -142.85341)
		(width 0.1143)
		(layer "B.Cu")
		(net "SATA6G_P6_TX_C_DP")
	)
	(arc
		(start 411.694884 -141.412468)
		(mid 411.946331 -141.516621)
		(end 412.050484 -141.768068)
		(width 0.1143)
		(layer "B.Cu")
		(net "SATA6G_P6_TX_C_DP")
	)
	(arc
		(start 411.45714 -141.37894)
		(mid 411.494199 -141.403702)
		(end 411.537912 -141.412468)
		(width 0.1143)
		(layer "B.Cu")
		(net "SATA6G_P6_TX_C_DP")
	)
	(arc
		(start 413.379158 -144.038828)
		(mid 413.466322 -144.047524)
		(end 413.534098 -143.992092)
		(width 0.1143)
		(layer "B.Cu")
		(net "SATA6G_P6_TX_C_DP")
	)
	(segment
		(start 411.809184 -142.772892)
		(end 411.809184 -141.768068)
		(width 0.1143)
		(layer "B.Cu")
		(net "SATA6G_P6_TX_C_DN")
	)
	(segment
		(start 413.026098 -144.94002)
		(end 413.3088 -144.411954)
		(width 0.1143)
		(layer "B.Cu")
		(net "SATA6G_P6_TX_C_DN")
	)
	(segment
		(start 412.996888 -144.10817)
		(end 411.913324 -143.024098)
		(width 0.1143)
		(layer "B.Cu")
		(net "SATA6G_P6_TX_C_DN")
	)
	(segment
		(start 411.694884 -141.653768)
		(end 411.529276 -141.653768)
		(width 0.1143)
		(layer "B.Cu")
		(net "SATA6G_P6_TX_C_DN")
	)
	(segment
		(start 413.25927 -144.248886)
		(end 412.996888 -144.10817)
		(width 0.1143)
		(layer "B.Cu")
		(net "SATA6G_P6_TX_C_DN")
	)
	(segment
		(start 411.448504 -141.687296)
		(end 411.099 -142.0368)
		(width 0.1143)
		(layer "B.Cu")
		(net "SATA6G_P6_TX_C_DN")
	)
	(arc
		(start 411.913324 -143.024098)
		(mid 411.836284 -142.908845)
		(end 411.809184 -142.772892)
		(width 0.1143)
		(layer "B.Cu")
		(net "SATA6G_P6_TX_C_DN")
	)
	(arc
		(start 413.3088 -144.411954)
		(mid 413.317902 -144.320107)
		(end 413.25927 -144.248886)
		(width 0.1143)
		(layer "B.Cu")
		(net "SATA6G_P6_TX_C_DN")
	)
	(arc
		(start 411.529276 -141.653768)
		(mid 411.485535 -141.662469)
		(end 411.448504 -141.687296)
		(width 0.1143)
		(layer "B.Cu")
		(net "SATA6G_P6_TX_C_DN")
	)
	(arc
		(start 411.809184 -141.768068)
		(mid 411.775706 -141.687246)
		(end 411.694884 -141.653768)
		(width 0.1143)
		(layer "B.Cu")
		(net "SATA6G_P6_TX_C_DN")
	)
	(segment
		(start 409.194 -150.622)
		(end 409.452572 -150.880572)
		(width 0.1143)
		(layer "B.Cu")
		(net "SATA6G_P6_RX_C_DP")
	)
	(segment
		(start 412.662116 -151.031194)
		(end 413.243522 -151.613108)
		(width 0.1143)
		(layer "B.Cu")
		(net "SATA6G_P6_RX_C_DP")
	)
	(segment
		(start 413.271208 -151.633682)
		(end 413.356552 -151.678894)
		(width 0.1143)
		(layer "B.Cu")
		(net "SATA6G_P6_RX_C_DP")
	)
	(segment
		(start 413.243522 -151.613108)
		(end 413.24403 -151.613362)
		(width 0.1143)
		(layer "B.Cu")
		(net "SATA6G_P6_RX_C_DP")
	)
	(segment
		(start 413.356552 -151.678894)
		(end 413.357314 -151.679402)
		(width 0.1143)
		(layer "B.Cu")
		(net "SATA6G_P6_RX_C_DP")
	)
	(segment
		(start 409.533598 -150.9141)
		(end 412.37916 -150.9141)
		(width 0.1143)
		(layer "B.Cu")
		(net "SATA6G_P6_RX_C_DP")
	)
	(segment
		(start 413.512254 -151.632666)
		(end 413.775906 -151.139906)
		(width 0.1143)
		(layer "B.Cu")
		(net "SATA6G_P6_RX_C_DP")
	)
	(arc
		(start 413.24403 -151.613362)
		(mid 413.256868 -151.624525)
		(end 413.271208 -151.633682)
		(width 0.1143)
		(layer "B.Cu")
		(net "SATA6G_P6_RX_C_DP")
	)
	(arc
		(start 409.452572 -150.880572)
		(mid 409.489747 -150.905412)
		(end 409.533598 -150.9141)
		(width 0.1143)
		(layer "B.Cu")
		(net "SATA6G_P6_RX_C_DP")
	)
	(arc
		(start 413.357314 -151.679402)
		(mid 413.444448 -151.688148)
		(end 413.512254 -151.632666)
		(width 0.1143)
		(layer "B.Cu")
		(net "SATA6G_P6_RX_C_DP")
	)
	(arc
		(start 412.37916 -150.9141)
		(mid 412.532278 -150.944499)
		(end 412.662116 -151.031194)
		(width 0.1143)
		(layer "B.Cu")
		(net "SATA6G_P6_RX_C_DP")
	)
	(segment
		(start 412.491174 -151.201882)
		(end 413.072834 -151.783796)
		(width 0.1143)
		(layer "B.Cu")
		(net "SATA6G_P6_RX_C_DN")
	)
	(segment
		(start 413.243014 -151.892254)
		(end 413.243268 -151.892254)
		(width 0.1143)
		(layer "B.Cu")
		(net "SATA6G_P6_RX_C_DN")
	)
	(segment
		(start 411.46476 -151.2697)
		(end 411.80766 -151.2697)
		(width 0.1143)
		(layer "B.Cu")
		(net "SATA6G_P6_RX_C_DN")
	)
	(segment
		(start 409.194 -151.511)
		(end 409.485592 -151.219408)
		(width 0.1143)
		(layer "B.Cu")
		(net "SATA6G_P6_RX_C_DN")
	)
	(segment
		(start 409.640024 -151.1554)
		(end 411.23616 -151.1554)
		(width 0.1143)
		(layer "B.Cu")
		(net "SATA6G_P6_RX_C_DN")
	)
	(segment
		(start 412.03626 -151.1554)
		(end 412.37916 -151.1554)
		(width 0.1143)
		(layer "B.Cu")
		(net "SATA6G_P6_RX_C_DN")
	)
	(segment
		(start 413.290004 -152.04694)
		(end 413.026098 -152.539954)
		(width 0.1143)
		(layer "B.Cu")
		(net "SATA6G_P6_RX_C_DN")
	)
	(segment
		(start 413.15767 -151.846788)
		(end 413.243014 -151.892254)
		(width 0.1143)
		(layer "B.Cu")
		(net "SATA6G_P6_RX_C_DN")
	)
	(arc
		(start 411.92196 -151.21255)
		(mid 411.973365 -151.172496)
		(end 412.03626 -151.1554)
		(width 0.1143)
		(layer "B.Cu")
		(net "SATA6G_P6_RX_C_DN")
	)
	(arc
		(start 411.23616 -151.1554)
		(mid 411.299074 -151.172457)
		(end 411.35046 -151.21255)
		(width 0.1143)
		(layer "B.Cu")
		(net "SATA6G_P6_RX_C_DN")
	)
	(arc
		(start 413.243268 -151.892254)
		(mid 413.298693 -151.959937)
		(end 413.290004 -152.04694)
		(width 0.1143)
		(layer "B.Cu")
		(net "SATA6G_P6_RX_C_DN")
	)
	(arc
		(start 409.485592 -151.219408)
		(mid 409.556432 -151.172011)
		(end 409.640024 -151.1554)
		(width 0.1143)
		(layer "B.Cu")
		(net "SATA6G_P6_RX_C_DN")
	)
	(arc
		(start 413.072834 -151.783796)
		(mid 413.112909 -151.818446)
		(end 413.15767 -151.846788)
		(width 0.1143)
		(layer "B.Cu")
		(net "SATA6G_P6_RX_C_DN")
	)
	(arc
		(start 412.37916 -151.1554)
		(mid 412.4398 -151.16748)
		(end 412.491174 -151.201882)
		(width 0.1143)
		(layer "B.Cu")
		(net "SATA6G_P6_RX_C_DN")
	)
	(arc
		(start 411.80766 -151.2697)
		(mid 411.870574 -151.252643)
		(end 411.92196 -151.21255)
		(width 0.1143)
		(layer "B.Cu")
		(net "SATA6G_P6_RX_C_DN")
	)
	(arc
		(start 411.35046 -151.21255)
		(mid 411.401865 -151.252604)
		(end 411.46476 -151.2697)
		(width 0.1143)
		(layer "B.Cu")
		(net "SATA6G_P6_RX_C_DN")
	)
	(segment
		(start 415.761678 -147.832826)
		(end 416.026092 -147.340066)
		(width 0.1143)
		(layer "B.Cu")
		(net "SATA6G_P5_TX_C_DP")
	)
	(segment
		(start 415.38906 -146.996404)
		(end 415.38906 -147.661376)
		(width 0.1143)
		(layer "B.Cu")
		(net "SATA6G_P5_TX_C_DP")
	)
	(segment
		(start 411.861 -145.415)
		(end 412.207456 -145.761456)
		(width 0.1143)
		(layer "B.Cu")
		(net "SATA6G_P5_TX_C_DP")
	)
	(segment
		(start 414.4391 -145.899124)
		(end 415.28492 -146.744944)
		(width 0.1143)
		(layer "B.Cu")
		(net "SATA6G_P5_TX_C_DP")
	)
	(segment
		(start 415.422588 -147.742148)
		(end 415.494216 -147.813776)
		(width 0.1143)
		(layer "B.Cu")
		(net "SATA6G_P5_TX_C_DP")
	)
	(segment
		(start 412.288228 -145.794984)
		(end 414.187386 -145.794984)
		(width 0.1143)
		(layer "B.Cu")
		(net "SATA6G_P5_TX_C_DP")
	)
	(segment
		(start 415.52114 -147.833588)
		(end 415.606738 -147.879562)
		(width 0.1143)
		(layer "B.Cu")
		(net "SATA6G_P5_TX_C_DP")
	)
	(arc
		(start 414.187386 -145.794984)
		(mid 414.323594 -145.822042)
		(end 414.4391 -145.899124)
		(width 0.1143)
		(layer "B.Cu")
		(net "SATA6G_P5_TX_C_DP")
	)
	(arc
		(start 415.494216 -147.813776)
		(mid 415.50694 -147.824687)
		(end 415.52114 -147.833588)
		(width 0.1143)
		(layer "B.Cu")
		(net "SATA6G_P5_TX_C_DP")
	)
	(arc
		(start 415.606738 -147.879562)
		(mid 415.693872 -147.888308)
		(end 415.761678 -147.832826)
		(width 0.1143)
		(layer "B.Cu")
		(net "SATA6G_P5_TX_C_DP")
	)
	(arc
		(start 415.38906 -147.661376)
		(mid 415.397761 -147.705117)
		(end 415.422588 -147.742148)
		(width 0.1143)
		(layer "B.Cu")
		(net "SATA6G_P5_TX_C_DP")
	)
	(arc
		(start 415.28492 -146.744944)
		(mid 415.362008 -146.860315)
		(end 415.38906 -146.996404)
		(width 0.1143)
		(layer "B.Cu")
		(net "SATA6G_P5_TX_C_DP")
	)
	(arc
		(start 412.207456 -145.761456)
		(mid 412.244515 -145.786218)
		(end 412.288228 -145.794984)
		(width 0.1143)
		(layer "B.Cu")
		(net "SATA6G_P5_TX_C_DP")
	)
	(segment
		(start 413.21736 -146.150584)
		(end 412.87446 -146.150584)
		(width 0.1143)
		(layer "B.Cu")
		(net "SATA6G_P5_TX_C_DN")
	)
	(segment
		(start 415.27603 -148.740114)
		(end 415.54019 -148.247862)
		(width 0.1143)
		(layer "B.Cu")
		(net "SATA6G_P5_TX_C_DN")
	)
	(segment
		(start 415.114232 -146.915632)
		(end 414.268412 -146.069812)
		(width 0.1143)
		(layer "B.Cu")
		(net "SATA6G_P5_TX_C_DN")
	)
	(segment
		(start 415.14776 -146.99615)
		(end 415.147506 -146.996404)
		(width 0.1143)
		(layer "B.Cu")
		(net "SATA6G_P5_TX_C_DN")
	)
	(segment
		(start 415.323782 -147.984718)
		(end 415.2519 -147.912836)
		(width 0.1143)
		(layer "B.Cu")
		(net "SATA6G_P5_TX_C_DN")
	)
	(segment
		(start 414.187386 -146.036284)
		(end 413.44596 -146.036284)
		(width 0.1143)
		(layer "B.Cu")
		(net "SATA6G_P5_TX_C_DN")
	)
	(segment
		(start 412.222188 -146.069812)
		(end 411.861 -146.431)
		(width 0.1143)
		(layer "B.Cu")
		(net "SATA6G_P5_TX_C_DN")
	)
	(segment
		(start 415.14776 -147.66163)
		(end 415.14776 -146.99615)
		(width 0.1143)
		(layer "B.Cu")
		(net "SATA6G_P5_TX_C_DN")
	)
	(segment
		(start 415.492438 -148.092414)
		(end 415.492438 -148.09216)
		(width 0.1143)
		(layer "B.Cu")
		(net "SATA6G_P5_TX_C_DN")
	)
	(segment
		(start 415.492438 -148.09216)
		(end 415.407348 -148.04644)
		(width 0.1143)
		(layer "B.Cu")
		(net "SATA6G_P5_TX_C_DN")
	)
	(segment
		(start 412.64586 -146.036284)
		(end 412.30296 -146.036284)
		(width 0.1143)
		(layer "B.Cu")
		(net "SATA6G_P5_TX_C_DN")
	)
	(segment
		(start 415.493454 -148.092922)
		(end 415.492438 -148.092414)
		(width 0.1143)
		(layer "B.Cu")
		(net "SATA6G_P5_TX_C_DN")
	)
	(arc
		(start 414.268412 -146.069812)
		(mid 414.231237 -146.044972)
		(end 414.187386 -146.036284)
		(width 0.1143)
		(layer "B.Cu")
		(net "SATA6G_P5_TX_C_DN")
	)
	(arc
		(start 415.407348 -148.04644)
		(mid 415.363299 -148.018647)
		(end 415.323782 -147.984718)
		(width 0.1143)
		(layer "B.Cu")
		(net "SATA6G_P5_TX_C_DN")
	)
	(arc
		(start 412.76016 -146.093434)
		(mid 412.708755 -146.05338)
		(end 412.64586 -146.036284)
		(width 0.1143)
		(layer "B.Cu")
		(net "SATA6G_P5_TX_C_DN")
	)
	(arc
		(start 413.44596 -146.036284)
		(mid 413.383046 -146.053341)
		(end 413.33166 -146.093434)
		(width 0.1143)
		(layer "B.Cu")
		(net "SATA6G_P5_TX_C_DN")
	)
	(arc
		(start 413.33166 -146.093434)
		(mid 413.280255 -146.133488)
		(end 413.21736 -146.150584)
		(width 0.1143)
		(layer "B.Cu")
		(net "SATA6G_P5_TX_C_DN")
	)
	(arc
		(start 415.2519 -147.912836)
		(mid 415.17486 -147.797583)
		(end 415.14776 -147.66163)
		(width 0.1143)
		(layer "B.Cu")
		(net "SATA6G_P5_TX_C_DN")
	)
	(arc
		(start 415.147506 -146.996404)
		(mid 415.138923 -146.952693)
		(end 415.114232 -146.915632)
		(width 0.1143)
		(layer "B.Cu")
		(net "SATA6G_P5_TX_C_DN")
	)
	(arc
		(start 415.54019 -148.247862)
		(mid 415.548936 -148.160728)
		(end 415.493454 -148.092922)
		(width 0.1143)
		(layer "B.Cu")
		(net "SATA6G_P5_TX_C_DN")
	)
	(arc
		(start 412.30296 -146.036284)
		(mid 412.259219 -146.044985)
		(end 412.222188 -146.069812)
		(width 0.1143)
		(layer "B.Cu")
		(net "SATA6G_P5_TX_C_DN")
	)
	(arc
		(start 412.87446 -146.150584)
		(mid 412.811546 -146.133527)
		(end 412.76016 -146.093434)
		(width 0.1143)
		(layer "B.Cu")
		(net "SATA6G_P5_TX_C_DN")
	)
	(segment
		(start 414.249362 -153.785824)
		(end 414.891474 -154.427936)
		(width 0.1143)
		(layer "B.Cu")
		(net "SATA6G_P5_RX_C_DP")
	)
	(segment
		(start 413.134556 -153.681684)
		(end 413.997902 -153.681684)
		(width 0.1143)
		(layer "B.Cu")
		(net "SATA6G_P5_RX_C_DP")
	)
	(segment
		(start 414.995614 -154.679396)
		(end 414.995614 -154.867864)
		(width 0.1143)
		(layer "B.Cu")
		(net "SATA6G_P5_RX_C_DP")
	)
	(segment
		(start 415.761678 -155.43276)
		(end 416.026092 -154.94)
		(width 0.1143)
		(layer "B.Cu")
		(net "SATA6G_P5_RX_C_DP")
	)
	(segment
		(start 415.029142 -154.948636)
		(end 415.494216 -155.41371)
		(width 0.1143)
		(layer "B.Cu")
		(net "SATA6G_P5_RX_C_DP")
	)
	(segment
		(start 415.52114 -155.433522)
		(end 415.606738 -155.479496)
		(width 0.1143)
		(layer "B.Cu")
		(net "SATA6G_P5_RX_C_DP")
	)
	(segment
		(start 411.724094 -152.59685)
		(end 411.855158 -152.59685)
		(width 0.1143)
		(layer "B.Cu")
		(net "SATA6G_P5_RX_C_DP")
	)
	(segment
		(start 411.353 -152.273)
		(end 411.643322 -152.563322)
		(width 0.1143)
		(layer "B.Cu")
		(net "SATA6G_P5_RX_C_DP")
	)
	(segment
		(start 412.106872 -152.701244)
		(end 413.053784 -153.648156)
		(width 0.1143)
		(layer "B.Cu")
		(net "SATA6G_P5_RX_C_DP")
	)
	(arc
		(start 413.053784 -153.648156)
		(mid 413.090843 -153.672918)
		(end 413.134556 -153.681684)
		(width 0.1143)
		(layer "B.Cu")
		(net "SATA6G_P5_RX_C_DP")
	)
	(arc
		(start 411.855158 -152.59685)
		(mid 411.991381 -152.62404)
		(end 412.106872 -152.701244)
		(width 0.1143)
		(layer "B.Cu")
		(net "SATA6G_P5_RX_C_DP")
	)
	(arc
		(start 415.606738 -155.479496)
		(mid 415.693872 -155.488242)
		(end 415.761678 -155.43276)
		(width 0.1143)
		(layer "B.Cu")
		(net "SATA6G_P5_RX_C_DP")
	)
	(arc
		(start 414.995614 -154.867864)
		(mid 415.004315 -154.911605)
		(end 415.029142 -154.948636)
		(width 0.1143)
		(layer "B.Cu")
		(net "SATA6G_P5_RX_C_DP")
	)
	(arc
		(start 413.997902 -153.681684)
		(mid 414.133984 -153.708752)
		(end 414.249362 -153.785824)
		(width 0.1143)
		(layer "B.Cu")
		(net "SATA6G_P5_RX_C_DP")
	)
	(arc
		(start 411.643322 -152.563322)
		(mid 411.680381 -152.588084)
		(end 411.724094 -152.59685)
		(width 0.1143)
		(layer "B.Cu")
		(net "SATA6G_P5_RX_C_DP")
	)
	(arc
		(start 414.891474 -154.427936)
		(mid 414.968562 -154.543307)
		(end 414.995614 -154.679396)
		(width 0.1143)
		(layer "B.Cu")
		(net "SATA6G_P5_RX_C_DP")
	)
	(arc
		(start 415.494216 -155.41371)
		(mid 415.50694 -155.424621)
		(end 415.52114 -155.433522)
		(width 0.1143)
		(layer "B.Cu")
		(net "SATA6G_P5_RX_C_DP")
	)
	(segment
		(start 415.492438 -155.692348)
		(end 415.493454 -155.692856)
		(width 0.1143)
		(layer "B.Cu")
		(net "SATA6G_P5_RX_C_DN")
	)
	(segment
		(start 415.492438 -155.692094)
		(end 415.492438 -155.692348)
		(width 0.1143)
		(layer "B.Cu")
		(net "SATA6G_P5_RX_C_DN")
	)
	(segment
		(start 414.858454 -155.119324)
		(end 415.323782 -155.584652)
		(width 0.1143)
		(layer "B.Cu")
		(net "SATA6G_P5_RX_C_DN")
	)
	(segment
		(start 415.407348 -155.646374)
		(end 415.492438 -155.692094)
		(width 0.1143)
		(layer "B.Cu")
		(net "SATA6G_P5_RX_C_DN")
	)
	(segment
		(start 414.75406 -154.679396)
		(end 414.754314 -154.679142)
		(width 0.1143)
		(layer "B.Cu")
		(net "SATA6G_P5_RX_C_DN")
	)
	(segment
		(start 414.754314 -154.679142)
		(end 414.754314 -154.868118)
		(width 0.1143)
		(layer "B.Cu")
		(net "SATA6G_P5_RX_C_DN")
	)
	(segment
		(start 415.54019 -155.847796)
		(end 415.27603 -156.340048)
		(width 0.1143)
		(layer "B.Cu")
		(net "SATA6G_P5_RX_C_DN")
	)
	(segment
		(start 414.078674 -153.956512)
		(end 414.720786 -154.598624)
		(width 0.1143)
		(layer "B.Cu")
		(net "SATA6G_P5_RX_C_DN")
	)
	(segment
		(start 411.724094 -152.83815)
		(end 411.854904 -152.83815)
		(width 0.1143)
		(layer "B.Cu")
		(net "SATA6G_P5_RX_C_DN")
	)
	(segment
		(start 413.134302 -153.922984)
		(end 413.998156 -153.922984)
		(width 0.1143)
		(layer "B.Cu")
		(net "SATA6G_P5_RX_C_DN")
	)
	(segment
		(start 411.353 -153.162)
		(end 411.643322 -152.871678)
		(width 0.1143)
		(layer "B.Cu")
		(net "SATA6G_P5_RX_C_DN")
	)
	(segment
		(start 411.936184 -152.871932)
		(end 412.883096 -153.818844)
		(width 0.1143)
		(layer "B.Cu")
		(net "SATA6G_P5_RX_C_DN")
	)
	(arc
		(start 415.323782 -155.584652)
		(mid 415.363297 -155.618584)
		(end 415.407348 -155.646374)
		(width 0.1143)
		(layer "B.Cu")
		(net "SATA6G_P5_RX_C_DN")
	)
	(arc
		(start 411.854904 -152.83815)
		(mid 411.898922 -152.846924)
		(end 411.936184 -152.871932)
		(width 0.1143)
		(layer "B.Cu")
		(net "SATA6G_P5_RX_C_DN")
	)
	(arc
		(start 413.998156 -153.922984)
		(mid 414.04176 -153.931733)
		(end 414.078674 -153.956512)
		(width 0.1143)
		(layer "B.Cu")
		(net "SATA6G_P5_RX_C_DN")
	)
	(arc
		(start 411.643322 -152.871678)
		(mid 411.680381 -152.846916)
		(end 411.724094 -152.83815)
		(width 0.1143)
		(layer "B.Cu")
		(net "SATA6G_P5_RX_C_DN")
	)
	(arc
		(start 414.754314 -154.868118)
		(mid 414.781431 -155.004064)
		(end 414.858454 -155.119324)
		(width 0.1143)
		(layer "B.Cu")
		(net "SATA6G_P5_RX_C_DN")
	)
	(arc
		(start 415.493454 -155.692856)
		(mid 415.549035 -155.760632)
		(end 415.54019 -155.847796)
		(width 0.1143)
		(layer "B.Cu")
		(net "SATA6G_P5_RX_C_DN")
	)
	(arc
		(start 414.720786 -154.598624)
		(mid 414.745411 -154.635712)
		(end 414.75406 -154.679396)
		(width 0.1143)
		(layer "B.Cu")
		(net "SATA6G_P5_RX_C_DN")
	)
	(arc
		(start 412.883096 -153.818844)
		(mid 412.998349 -153.895884)
		(end 413.134302 -153.922984)
		(width 0.1143)
		(layer "B.Cu")
		(net "SATA6G_P5_RX_C_DN")
	)
	(segment
		(start 415.778442 -144.00149)
		(end 416.026092 -143.539972)
		(width 0.1143)
		(layer "B.Cu")
		(net "SATA6G_P4_TX_C_DP")
	)
	(segment
		(start 415.380678 -142.83436)
		(end 415.30778 -142.907258)
		(width 0.1143)
		(layer "B.Cu")
		(net "SATA6G_P4_TX_C_DP")
	)
	(segment
		(start 414.987994 -141.40815)
		(end 415.09569 -141.40815)
		(width 0.1143)
		(layer "B.Cu")
		(net "SATA6G_P4_TX_C_DP")
	)
	(segment
		(start 415.274252 -142.98803)
		(end 415.274252 -143.754348)
		(width 0.1143)
		(layer "B.Cu")
		(net "SATA6G_P4_TX_C_DP")
	)
	(segment
		(start 415.348674 -143.879316)
		(end 415.388044 -143.900652)
		(width 0.1143)
		(layer "B.Cu")
		(net "SATA6G_P4_TX_C_DP")
	)
	(segment
		(start 414.5534 -141.0208)
		(end 414.907222 -141.374622)
		(width 0.1143)
		(layer "B.Cu")
		(net "SATA6G_P4_TX_C_DP")
	)
	(segment
		(start 415.484818 -141.797278)
		(end 415.484818 -142.5829)
		(width 0.1143)
		(layer "B.Cu")
		(net "SATA6G_P4_TX_C_DP")
	)
	(arc
		(start 415.484818 -142.5829)
		(mid 415.45775 -142.718982)
		(end 415.380678 -142.83436)
		(width 0.1143)
		(layer "B.Cu")
		(net "SATA6G_P4_TX_C_DP")
	)
	(arc
		(start 415.64687 -144.039336)
		(mid 415.720296 -144.047058)
		(end 415.778442 -144.00149)
		(width 0.1143)
		(layer "B.Cu")
		(net "SATA6G_P4_TX_C_DP")
	)
	(arc
		(start 415.388044 -143.900652)
		(mid 415.5174 -143.9701)
		(end 415.64687 -144.039336)
		(width 0.1143)
		(layer "B.Cu")
		(net "SATA6G_P4_TX_C_DP")
	)
	(arc
		(start 415.09569 -141.40815)
		(mid 415.370845 -141.522123)
		(end 415.484818 -141.797278)
		(width 0.1143)
		(layer "B.Cu")
		(net "SATA6G_P4_TX_C_DP")
	)
	(arc
		(start 415.30778 -142.907258)
		(mid 415.283018 -142.944317)
		(end 415.274252 -142.98803)
		(width 0.1143)
		(layer "B.Cu")
		(net "SATA6G_P4_TX_C_DP")
	)
	(arc
		(start 414.907222 -141.374622)
		(mid 414.944281 -141.399384)
		(end 414.987994 -141.40815)
		(width 0.1143)
		(layer "B.Cu")
		(net "SATA6G_P4_TX_C_DP")
	)
	(arc
		(start 415.274252 -143.754348)
		(mid 415.294258 -143.827087)
		(end 415.348674 -143.879316)
		(width 0.1143)
		(layer "B.Cu")
		(net "SATA6G_P4_TX_C_DP")
	)
	(segment
		(start 415.243264 -142.375636)
		(end 415.243518 -142.37589)
		(width 0.1143)
		(layer "B.Cu")
		(net "SATA6G_P4_TX_C_DN")
	)
	(segment
		(start 415.273236 -144.11325)
		(end 415.272474 -144.112742)
		(width 0.1143)
		(layer "B.Cu")
		(net "SATA6G_P4_TX_C_DN")
	)
	(segment
		(start 415.09569 -141.64945)
		(end 414.98774 -141.64945)
		(width 0.1143)
		(layer "B.Cu")
		(net "SATA6G_P4_TX_C_DN")
	)
	(segment
		(start 415.515806 -144.243298)
		(end 415.431224 -144.198086)
		(width 0.1143)
		(layer "B.Cu")
		(net "SATA6G_P4_TX_C_DN")
	)
	(segment
		(start 415.243518 -142.37589)
		(end 415.243518 -141.797278)
		(width 0.1143)
		(layer "B.Cu")
		(net "SATA6G_P4_TX_C_DN")
	)
	(segment
		(start 415.243264 -142.5829)
		(end 415.243264 -142.375636)
		(width 0.1143)
		(layer "B.Cu")
		(net "SATA6G_P4_TX_C_DN")
	)
	(segment
		(start 415.27603 -144.94002)
		(end 415.565336 -144.400778)
		(width 0.1143)
		(layer "B.Cu")
		(net "SATA6G_P4_TX_C_DN")
	)
	(segment
		(start 415.032952 -143.754348)
		(end 415.032952 -142.987776)
		(width 0.1143)
		(layer "B.Cu")
		(net "SATA6G_P4_TX_C_DN")
	)
	(segment
		(start 415.272474 -144.112742)
		(end 415.233612 -144.09166)
		(width 0.1143)
		(layer "B.Cu")
		(net "SATA6G_P4_TX_C_DN")
	)
	(segment
		(start 415.137092 -142.73657)
		(end 415.20999 -142.663672)
		(width 0.1143)
		(layer "B.Cu")
		(net "SATA6G_P4_TX_C_DN")
	)
	(segment
		(start 414.907222 -141.682978)
		(end 414.5534 -142.0368)
		(width 0.1143)
		(layer "B.Cu")
		(net "SATA6G_P4_TX_C_DN")
	)
	(arc
		(start 414.98774 -141.64945)
		(mid 414.944136 -141.658199)
		(end 414.907222 -141.682978)
		(width 0.1143)
		(layer "B.Cu")
		(net "SATA6G_P4_TX_C_DN")
	)
	(arc
		(start 415.20999 -142.663672)
		(mid 415.234615 -142.626584)
		(end 415.243264 -142.5829)
		(width 0.1143)
		(layer "B.Cu")
		(net "SATA6G_P4_TX_C_DN")
	)
	(arc
		(start 415.233612 -144.09166)
		(mid 415.086895 -143.950609)
		(end 415.032952 -143.754348)
		(width 0.1143)
		(layer "B.Cu")
		(net "SATA6G_P4_TX_C_DN")
	)
	(arc
		(start 415.243518 -141.797278)
		(mid 415.20022 -141.692748)
		(end 415.09569 -141.64945)
		(width 0.1143)
		(layer "B.Cu")
		(net "SATA6G_P4_TX_C_DN")
	)
	(arc
		(start 415.032952 -142.987776)
		(mid 415.060069 -142.85183)
		(end 415.137092 -142.73657)
		(width 0.1143)
		(layer "B.Cu")
		(net "SATA6G_P4_TX_C_DN")
	)
	(arc
		(start 415.431224 -144.198086)
		(mid 415.352209 -144.155707)
		(end 415.273236 -144.11325)
		(width 0.1143)
		(layer "B.Cu")
		(net "SATA6G_P4_TX_C_DN")
	)
	(arc
		(start 415.565336 -144.400778)
		(mid 415.573776 -144.311584)
		(end 415.515806 -144.243298)
		(width 0.1143)
		(layer "B.Cu")
		(net "SATA6G_P4_TX_C_DN")
	)
	(segment
		(start 415.399982 -151.160734)
		(end 415.399982 -151.472138)
		(width 0.1143)
		(layer "B.Cu")
		(net "SATA6G_P4_RX_C_DP")
	)
	(segment
		(start 414.05556 -149.668992)
		(end 415.296096 -150.909274)
		(width 0.1143)
		(layer "B.Cu")
		(net "SATA6G_P4_RX_C_DP")
	)
	(segment
		(start 411.353 -149.06752)
		(end 411.640782 -149.355302)
		(width 0.1143)
		(layer "B.Cu")
		(net "SATA6G_P4_RX_C_DP")
	)
	(segment
		(start 412.650178 -149.49551)
		(end 412.685738 -149.53107)
		(width 0.1143)
		(layer "B.Cu")
		(net "SATA6G_P4_RX_C_DP")
	)
	(segment
		(start 415.761678 -151.632666)
		(end 416.026092 -151.139906)
		(width 0.1143)
		(layer "B.Cu")
		(net "SATA6G_P4_RX_C_DP")
	)
	(segment
		(start 415.43351 -151.55291)
		(end 415.494216 -151.613616)
		(width 0.1143)
		(layer "B.Cu")
		(net "SATA6G_P4_RX_C_DP")
	)
	(segment
		(start 412.767018 -149.564852)
		(end 413.803846 -149.564852)
		(width 0.1143)
		(layer "B.Cu")
		(net "SATA6G_P4_RX_C_DP")
	)
	(segment
		(start 411.721554 -149.38883)
		(end 412.392622 -149.38883)
		(width 0.1143)
		(layer "B.Cu")
		(net "SATA6G_P4_RX_C_DP")
	)
	(segment
		(start 415.52114 -151.633428)
		(end 415.606738 -151.679402)
		(width 0.1143)
		(layer "B.Cu")
		(net "SATA6G_P4_RX_C_DP")
	)
	(arc
		(start 415.494216 -151.613616)
		(mid 415.50694 -151.624527)
		(end 415.52114 -151.633428)
		(width 0.1143)
		(layer "B.Cu")
		(net "SATA6G_P4_RX_C_DP")
	)
	(arc
		(start 413.803846 -149.564852)
		(mid 413.940054 -149.59191)
		(end 414.05556 -149.668992)
		(width 0.1143)
		(layer "B.Cu")
		(net "SATA6G_P4_RX_C_DP")
	)
	(arc
		(start 411.640782 -149.355302)
		(mid 411.677841 -149.380064)
		(end 411.721554 -149.38883)
		(width 0.1143)
		(layer "B.Cu")
		(net "SATA6G_P4_RX_C_DP")
	)
	(arc
		(start 415.399982 -151.472138)
		(mid 415.408683 -151.515879)
		(end 415.43351 -151.55291)
		(width 0.1143)
		(layer "B.Cu")
		(net "SATA6G_P4_RX_C_DP")
	)
	(arc
		(start 412.392622 -149.38883)
		(mid 412.532009 -149.416556)
		(end 412.650178 -149.49551)
		(width 0.1143)
		(layer "B.Cu")
		(net "SATA6G_P4_RX_C_DP")
	)
	(arc
		(start 415.296096 -150.909274)
		(mid 415.373048 -151.024674)
		(end 415.399982 -151.160734)
		(width 0.1143)
		(layer "B.Cu")
		(net "SATA6G_P4_RX_C_DP")
	)
	(arc
		(start 415.606738 -151.679402)
		(mid 415.693872 -151.688148)
		(end 415.761678 -151.632666)
		(width 0.1143)
		(layer "B.Cu")
		(net "SATA6G_P4_RX_C_DP")
	)
	(arc
		(start 412.685738 -149.53107)
		(mid 412.723015 -149.556041)
		(end 412.767018 -149.564852)
		(width 0.1143)
		(layer "B.Cu")
		(net "SATA6G_P4_RX_C_DP")
	)
	(segment
		(start 415.492438 -151.892)
		(end 415.492438 -151.892254)
		(width 0.1143)
		(layer "B.Cu")
		(net "SATA6G_P4_RX_C_DN")
	)
	(segment
		(start 415.262822 -151.723598)
		(end 415.323782 -151.784558)
		(width 0.1143)
		(layer "B.Cu")
		(net "SATA6G_P4_RX_C_DN")
	)
	(segment
		(start 415.492438 -151.892254)
		(end 415.493454 -151.892762)
		(width 0.1143)
		(layer "B.Cu")
		(net "SATA6G_P4_RX_C_DN")
	)
	(segment
		(start 411.353 -149.95652)
		(end 411.645862 -149.663658)
		(width 0.1143)
		(layer "B.Cu")
		(net "SATA6G_P4_RX_C_DN")
	)
	(segment
		(start 414.6931 -150.647908)
		(end 415.125154 -151.079962)
		(width 0.1143)
		(layer "B.Cu")
		(net "SATA6G_P4_RX_C_DN")
	)
	(segment
		(start 412.47949 -149.666198)
		(end 412.51505 -149.701758)
		(width 0.1143)
		(layer "B.Cu")
		(net "SATA6G_P4_RX_C_DN")
	)
	(segment
		(start 414.208214 -150.324566)
		(end 414.45053 -150.567136)
		(width 0.1143)
		(layer "B.Cu")
		(net "SATA6G_P4_RX_C_DN")
	)
	(segment
		(start 415.158428 -151.160734)
		(end 415.158682 -151.16048)
		(width 0.1143)
		(layer "B.Cu")
		(net "SATA6G_P4_RX_C_DN")
	)
	(segment
		(start 412.766764 -149.806152)
		(end 413.803846 -149.806152)
		(width 0.1143)
		(layer "B.Cu")
		(net "SATA6G_P4_RX_C_DN")
	)
	(segment
		(start 411.726634 -149.63013)
		(end 412.392368 -149.63013)
		(width 0.1143)
		(layer "B.Cu")
		(net "SATA6G_P4_RX_C_DN")
	)
	(segment
		(start 413.884872 -149.83968)
		(end 414.127442 -150.08225)
		(width 0.1143)
		(layer "B.Cu")
		(net "SATA6G_P4_RX_C_DN")
	)
	(segment
		(start 415.158682 -151.16048)
		(end 415.158682 -151.472392)
		(width 0.1143)
		(layer "B.Cu")
		(net "SATA6G_P4_RX_C_DN")
	)
	(segment
		(start 415.407348 -151.84628)
		(end 415.492438 -151.892)
		(width 0.1143)
		(layer "B.Cu")
		(net "SATA6G_P4_RX_C_DN")
	)
	(segment
		(start 415.54019 -152.047702)
		(end 415.27603 -152.539954)
		(width 0.1143)
		(layer "B.Cu")
		(net "SATA6G_P4_RX_C_DN")
	)
	(arc
		(start 412.51505 -149.701758)
		(mid 412.630522 -149.779007)
		(end 412.766764 -149.806152)
		(width 0.1143)
		(layer "B.Cu")
		(net "SATA6G_P4_RX_C_DN")
	)
	(arc
		(start 414.167828 -150.203408)
		(mid 414.175829 -150.268051)
		(end 414.208214 -150.324566)
		(width 0.1143)
		(layer "B.Cu")
		(net "SATA6G_P4_RX_C_DN")
	)
	(arc
		(start 412.392368 -149.63013)
		(mid 412.439496 -149.639522)
		(end 412.47949 -149.666198)
		(width 0.1143)
		(layer "B.Cu")
		(net "SATA6G_P4_RX_C_DN")
	)
	(arc
		(start 411.645862 -149.663658)
		(mid 411.682921 -149.638896)
		(end 411.726634 -149.63013)
		(width 0.1143)
		(layer "B.Cu")
		(net "SATA6G_P4_RX_C_DN")
	)
	(arc
		(start 414.127442 -150.08225)
		(mid 414.159827 -150.138765)
		(end 414.167828 -150.203408)
		(width 0.1143)
		(layer "B.Cu")
		(net "SATA6G_P4_RX_C_DN")
	)
	(arc
		(start 415.323782 -151.784558)
		(mid 415.363297 -151.81849)
		(end 415.407348 -151.84628)
		(width 0.1143)
		(layer "B.Cu")
		(net "SATA6G_P4_RX_C_DN")
	)
	(arc
		(start 414.571942 -150.607522)
		(mid 414.636585 -150.615523)
		(end 414.6931 -150.647908)
		(width 0.1143)
		(layer "B.Cu")
		(net "SATA6G_P4_RX_C_DN")
	)
	(arc
		(start 415.125154 -151.079962)
		(mid 415.149779 -151.11705)
		(end 415.158428 -151.160734)
		(width 0.1143)
		(layer "B.Cu")
		(net "SATA6G_P4_RX_C_DN")
	)
	(arc
		(start 413.803846 -149.806152)
		(mid 413.847684 -149.814872)
		(end 413.884872 -149.83968)
		(width 0.1143)
		(layer "B.Cu")
		(net "SATA6G_P4_RX_C_DN")
	)
	(arc
		(start 415.493454 -151.892762)
		(mid 415.549035 -151.960538)
		(end 415.54019 -152.047702)
		(width 0.1143)
		(layer "B.Cu")
		(net "SATA6G_P4_RX_C_DN")
	)
	(arc
		(start 415.158682 -151.472392)
		(mid 415.185799 -151.608338)
		(end 415.262822 -151.723598)
		(width 0.1143)
		(layer "B.Cu")
		(net "SATA6G_P4_RX_C_DN")
	)
	(arc
		(start 414.45053 -150.567136)
		(mid 414.507165 -150.599561)
		(end 414.571942 -150.607522)
		(width 0.1143)
		(layer "B.Cu")
		(net "SATA6G_P4_RX_C_DN")
	)
	(segment
		(start 423.95267 -147.033742)
		(end 424.31716 -147.033742)
		(width 0.1143)
		(layer "B.Cu")
		(net "SATA6G_P3_TX_C_DP")
	)
	(segment
		(start 425.191174 -147.753832)
		(end 425.372022 -147.849844)
		(width 0.1143)
		(layer "B.Cu")
		(net "SATA6G_P3_TX_C_DP")
	)
	(segment
		(start 423.610024 -147.229068)
		(end 423.700956 -147.138136)
		(width 0.1143)
		(layer "B.Cu")
		(net "SATA6G_P3_TX_C_DP")
	)
	(segment
		(start 421.513 -146.939)
		(end 421.803322 -147.229322)
		(width 0.1143)
		(layer "B.Cu")
		(net "SATA6G_P3_TX_C_DP")
	)
	(segment
		(start 424.568366 -147.137882)
		(end 425.163996 -147.733512)
		(width 0.1143)
		(layer "B.Cu")
		(net "SATA6G_P3_TX_C_DP")
	)
	(segment
		(start 425.527978 -147.803616)
		(end 425.775882 -147.340066)
		(width 0.1143)
		(layer "B.Cu")
		(net "SATA6G_P3_TX_C_DP")
	)
	(segment
		(start 421.88384 -147.26285)
		(end 423.528744 -147.26285)
		(width 0.1143)
		(layer "B.Cu")
		(net "SATA6G_P3_TX_C_DP")
	)
	(arc
		(start 425.372022 -147.849844)
		(mid 425.459417 -147.858552)
		(end 425.527978 -147.803616)
		(width 0.1143)
		(layer "B.Cu")
		(net "SATA6G_P3_TX_C_DP")
	)
	(arc
		(start 421.803322 -147.229322)
		(mid 421.840263 -147.254035)
		(end 421.88384 -147.26285)
		(width 0.1143)
		(layer "B.Cu")
		(net "SATA6G_P3_TX_C_DP")
	)
	(arc
		(start 423.528744 -147.26285)
		(mid 423.572762 -147.254076)
		(end 423.610024 -147.229068)
		(width 0.1143)
		(layer "B.Cu")
		(net "SATA6G_P3_TX_C_DP")
	)
	(arc
		(start 424.31716 -147.033742)
		(mid 424.453106 -147.060859)
		(end 424.568366 -147.137882)
		(width 0.1143)
		(layer "B.Cu")
		(net "SATA6G_P3_TX_C_DP")
	)
	(arc
		(start 423.700956 -147.138136)
		(mid 423.816428 -147.060887)
		(end 423.95267 -147.033742)
		(width 0.1143)
		(layer "B.Cu")
		(net "SATA6G_P3_TX_C_DP")
	)
	(arc
		(start 425.163996 -147.733512)
		(mid 425.176834 -147.744675)
		(end 425.191174 -147.753832)
		(width 0.1143)
		(layer "B.Cu")
		(net "SATA6G_P3_TX_C_DP")
	)
	(segment
		(start 423.952924 -147.275042)
		(end 424.316906 -147.275042)
		(width 0.1143)
		(layer "B.Cu")
		(net "SATA6G_P3_TX_C_DN")
	)
	(segment
		(start 425.077382 -147.966938)
		(end 425.258738 -148.063204)
		(width 0.1143)
		(layer "B.Cu")
		(net "SATA6G_P3_TX_C_DN")
	)
	(segment
		(start 421.513 -147.828)
		(end 421.803322 -147.537678)
		(width 0.1143)
		(layer "B.Cu")
		(net "SATA6G_P3_TX_C_DN")
	)
	(segment
		(start 425.305728 -148.21789)
		(end 425.026074 -148.740114)
		(width 0.1143)
		(layer "B.Cu")
		(net "SATA6G_P3_TX_C_DN")
	)
	(segment
		(start 422.455594 -147.61845)
		(end 422.798494 -147.61845)
		(width 0.1143)
		(layer "B.Cu")
		(net "SATA6G_P3_TX_C_DN")
	)
	(segment
		(start 424.397678 -147.30857)
		(end 424.564556 -147.475448)
		(width 0.1143)
		(layer "B.Cu")
		(net "SATA6G_P3_TX_C_DN")
	)
	(segment
		(start 423.027094 -147.50415)
		(end 423.528998 -147.50415)
		(width 0.1143)
		(layer "B.Cu")
		(net "SATA6G_P3_TX_C_DN")
	)
	(segment
		(start 424.564556 -147.475448)
		(end 424.9928 -147.903946)
		(width 0.1143)
		(layer "B.Cu")
		(net "SATA6G_P3_TX_C_DN")
	)
	(segment
		(start 421.884094 -147.50415)
		(end 422.226994 -147.50415)
		(width 0.1143)
		(layer "B.Cu")
		(net "SATA6G_P3_TX_C_DN")
	)
	(segment
		(start 423.780712 -147.399756)
		(end 423.871644 -147.308824)
		(width 0.1143)
		(layer "B.Cu")
		(net "SATA6G_P3_TX_C_DN")
	)
	(arc
		(start 424.9928 -147.903946)
		(mid 425.032743 -147.938596)
		(end 425.077382 -147.966938)
		(width 0.1143)
		(layer "B.Cu")
		(net "SATA6G_P3_TX_C_DN")
	)
	(arc
		(start 425.258738 -148.063204)
		(mid 425.314394 -148.1308)
		(end 425.305728 -148.21789)
		(width 0.1143)
		(layer "B.Cu")
		(net "SATA6G_P3_TX_C_DN")
	)
	(arc
		(start 421.803322 -147.537678)
		(mid 421.840381 -147.512916)
		(end 421.884094 -147.50415)
		(width 0.1143)
		(layer "B.Cu")
		(net "SATA6G_P3_TX_C_DN")
	)
	(arc
		(start 422.226994 -147.50415)
		(mid 422.289908 -147.521207)
		(end 422.341294 -147.5613)
		(width 0.1143)
		(layer "B.Cu")
		(net "SATA6G_P3_TX_C_DN")
	)
	(arc
		(start 422.341294 -147.5613)
		(mid 422.392699 -147.601354)
		(end 422.455594 -147.61845)
		(width 0.1143)
		(layer "B.Cu")
		(net "SATA6G_P3_TX_C_DN")
	)
	(arc
		(start 422.912794 -147.5613)
		(mid 422.964199 -147.521246)
		(end 423.027094 -147.50415)
		(width 0.1143)
		(layer "B.Cu")
		(net "SATA6G_P3_TX_C_DN")
	)
	(arc
		(start 422.798494 -147.61845)
		(mid 422.861408 -147.601393)
		(end 422.912794 -147.5613)
		(width 0.1143)
		(layer "B.Cu")
		(net "SATA6G_P3_TX_C_DN")
	)
	(arc
		(start 423.871644 -147.308824)
		(mid 423.908921 -147.283853)
		(end 423.952924 -147.275042)
		(width 0.1143)
		(layer "B.Cu")
		(net "SATA6G_P3_TX_C_DN")
	)
	(arc
		(start 424.316906 -147.275042)
		(mid 424.360647 -147.283743)
		(end 424.397678 -147.30857)
		(width 0.1143)
		(layer "B.Cu")
		(net "SATA6G_P3_TX_C_DN")
	)
	(arc
		(start 423.528998 -147.50415)
		(mid 423.665221 -147.47696)
		(end 423.780712 -147.399756)
		(width 0.1143)
		(layer "B.Cu")
		(net "SATA6G_P3_TX_C_DN")
	)
	(segment
		(start 421.884094 -155.26385)
		(end 423.280332 -155.26385)
		(width 0.1143)
		(layer "B.Cu")
		(net "SATA6G_P3_RX_C_DP")
	)
	(segment
		(start 424.660568 -154.815286)
		(end 425.275756 -155.430474)
		(width 0.1143)
		(layer "B.Cu")
		(net "SATA6G_P3_RX_C_DP")
	)
	(segment
		(start 425.297854 -155.447746)
		(end 425.35729 -155.479496)
		(width 0.1143)
		(layer "B.Cu")
		(net "SATA6G_P3_RX_C_DP")
	)
	(segment
		(start 423.36085 -155.230322)
		(end 423.775886 -154.815286)
		(width 0.1143)
		(layer "B.Cu")
		(net "SATA6G_P3_RX_C_DP")
	)
	(segment
		(start 425.275756 -155.430474)
		(end 425.27601 -155.430474)
		(width 0.1143)
		(layer "B.Cu")
		(net "SATA6G_P3_RX_C_DP")
	)
	(segment
		(start 421.513 -154.94)
		(end 421.803322 -155.230322)
		(width 0.1143)
		(layer "B.Cu")
		(net "SATA6G_P3_RX_C_DP")
	)
	(segment
		(start 425.51223 -155.43276)
		(end 425.775882 -154.94)
		(width 0.1143)
		(layer "B.Cu")
		(net "SATA6G_P3_RX_C_DP")
	)
	(segment
		(start 424.027092 -154.711146)
		(end 424.409362 -154.711146)
		(width 0.1143)
		(layer "B.Cu")
		(net "SATA6G_P3_RX_C_DP")
	)
	(arc
		(start 425.35729 -155.479496)
		(mid 425.444424 -155.488242)
		(end 425.51223 -155.43276)
		(width 0.1143)
		(layer "B.Cu")
		(net "SATA6G_P3_RX_C_DP")
	)
	(arc
		(start 423.280332 -155.26385)
		(mid 423.323936 -155.255101)
		(end 423.36085 -155.230322)
		(width 0.1143)
		(layer "B.Cu")
		(net "SATA6G_P3_RX_C_DP")
	)
	(arc
		(start 421.803322 -155.230322)
		(mid 421.840381 -155.255084)
		(end 421.884094 -155.26385)
		(width 0.1143)
		(layer "B.Cu")
		(net "SATA6G_P3_RX_C_DP")
	)
	(arc
		(start 424.409362 -154.711146)
		(mid 424.545308 -154.738263)
		(end 424.660568 -154.815286)
		(width 0.1143)
		(layer "B.Cu")
		(net "SATA6G_P3_RX_C_DP")
	)
	(arc
		(start 423.775886 -154.815286)
		(mid 423.891139 -154.738246)
		(end 424.027092 -154.711146)
		(width 0.1143)
		(layer "B.Cu")
		(net "SATA6G_P3_RX_C_DP")
	)
	(arc
		(start 425.27601 -155.430474)
		(mid 425.2864 -155.439783)
		(end 425.297854 -155.447746)
		(width 0.1143)
		(layer "B.Cu")
		(net "SATA6G_P3_RX_C_DP")
	)
	(segment
		(start 422.226994 -155.50515)
		(end 421.884094 -155.50515)
		(width 0.1143)
		(layer "B.Cu")
		(net "SATA6G_P3_RX_C_DN")
	)
	(segment
		(start 425.243244 -155.692348)
		(end 425.24299 -155.692348)
		(width 0.1143)
		(layer "B.Cu")
		(net "SATA6G_P3_RX_C_DN")
	)
	(segment
		(start 421.803322 -155.538678)
		(end 421.513 -155.829)
		(width 0.1143)
		(layer "B.Cu")
		(net "SATA6G_P3_RX_C_DN")
	)
	(segment
		(start 424.409108 -154.952446)
		(end 424.027346 -154.952446)
		(width 0.1143)
		(layer "B.Cu")
		(net "SATA6G_P3_RX_C_DN")
	)
	(segment
		(start 422.798494 -155.61945)
		(end 422.455594 -155.61945)
		(width 0.1143)
		(layer "B.Cu")
		(net "SATA6G_P3_RX_C_DN")
	)
	(segment
		(start 425.026074 -156.340048)
		(end 425.28998 -155.847034)
		(width 0.1143)
		(layer "B.Cu")
		(net "SATA6G_P3_RX_C_DN")
	)
	(segment
		(start 423.946574 -154.985974)
		(end 423.531538 -155.40101)
		(width 0.1143)
		(layer "B.Cu")
		(net "SATA6G_P3_RX_C_DN")
	)
	(segment
		(start 425.105068 -155.601162)
		(end 424.48988 -154.985974)
		(width 0.1143)
		(layer "B.Cu")
		(net "SATA6G_P3_RX_C_DN")
	)
	(segment
		(start 423.280078 -155.50515)
		(end 423.027094 -155.50515)
		(width 0.1143)
		(layer "B.Cu")
		(net "SATA6G_P3_RX_C_DN")
	)
	(segment
		(start 425.24299 -155.692348)
		(end 425.188888 -155.663392)
		(width 0.1143)
		(layer "B.Cu")
		(net "SATA6G_P3_RX_C_DN")
	)
	(arc
		(start 424.027346 -154.952446)
		(mid 423.983605 -154.961147)
		(end 423.946574 -154.985974)
		(width 0.1143)
		(layer "B.Cu")
		(net "SATA6G_P3_RX_C_DN")
	)
	(arc
		(start 425.28998 -155.847034)
		(mid 425.298554 -155.760066)
		(end 425.243244 -155.692348)
		(width 0.1143)
		(layer "B.Cu")
		(net "SATA6G_P3_RX_C_DN")
	)
	(arc
		(start 425.188888 -155.663392)
		(mid 425.144677 -155.635376)
		(end 425.105068 -155.601162)
		(width 0.1143)
		(layer "B.Cu")
		(net "SATA6G_P3_RX_C_DN")
	)
	(arc
		(start 423.531538 -155.40101)
		(mid 423.416167 -155.478098)
		(end 423.280078 -155.50515)
		(width 0.1143)
		(layer "B.Cu")
		(net "SATA6G_P3_RX_C_DN")
	)
	(arc
		(start 423.027094 -155.50515)
		(mid 422.96418 -155.522207)
		(end 422.912794 -155.5623)
		(width 0.1143)
		(layer "B.Cu")
		(net "SATA6G_P3_RX_C_DN")
	)
	(arc
		(start 422.455594 -155.61945)
		(mid 422.39268 -155.602393)
		(end 422.341294 -155.5623)
		(width 0.1143)
		(layer "B.Cu")
		(net "SATA6G_P3_RX_C_DN")
	)
	(arc
		(start 424.48988 -154.985974)
		(mid 424.452821 -154.961212)
		(end 424.409108 -154.952446)
		(width 0.1143)
		(layer "B.Cu")
		(net "SATA6G_P3_RX_C_DN")
	)
	(arc
		(start 421.884094 -155.50515)
		(mid 421.840353 -155.513851)
		(end 421.803322 -155.538678)
		(width 0.1143)
		(layer "B.Cu")
		(net "SATA6G_P3_RX_C_DN")
	)
	(arc
		(start 422.912794 -155.5623)
		(mid 422.861389 -155.602354)
		(end 422.798494 -155.61945)
		(width 0.1143)
		(layer "B.Cu")
		(net "SATA6G_P3_RX_C_DN")
	)
	(arc
		(start 422.341294 -155.5623)
		(mid 422.289889 -155.522246)
		(end 422.226994 -155.50515)
		(width 0.1143)
		(layer "B.Cu")
		(net "SATA6G_P3_RX_C_DN")
	)
	(segment
		(start 424.991022 -143.030448)
		(end 424.845734 -142.88516)
		(width 0.1143)
		(layer "B.Cu")
		(net "SATA6G_P2_TX_C_DP")
	)
	(segment
		(start 424.845734 -142.336266)
		(end 425.196 -141.986)
		(width 0.1143)
		(layer "B.Cu")
		(net "SATA6G_P2_TX_C_DP")
	)
	(segment
		(start 425.233084 -144.138396)
		(end 425.158916 -144.098264)
		(width 0.1143)
		(layer "B.Cu")
		(net "SATA6G_P2_TX_C_DP")
	)
	(segment
		(start 425.775882 -143.539972)
		(end 425.468288 -144.113758)
		(width 0.1143)
		(layer "B.Cu")
		(net "SATA6G_P2_TX_C_DP")
	)
	(segment
		(start 425.098718 -143.997426)
		(end 425.098718 -143.290544)
		(width 0.1143)
		(layer "B.Cu")
		(net "SATA6G_P2_TX_C_DP")
	)
	(segment
		(start 424.80865 -142.795498)
		(end 424.80865 -142.425928)
		(width 0.1143)
		(layer "B.Cu")
		(net "SATA6G_P2_TX_C_DP")
	)
	(segment
		(start 425.31411 -144.172178)
		(end 425.266358 -144.154398)
		(width 0.1143)
		(layer "B.Cu")
		(net "SATA6G_P2_TX_C_DP")
	)
	(arc
		(start 425.158916 -144.098264)
		(mid 425.114911 -144.056146)
		(end 425.098718 -143.997426)
		(width 0.1143)
		(layer "B.Cu")
		(net "SATA6G_P2_TX_C_DP")
	)
	(arc
		(start 425.098718 -143.290544)
		(mid 425.070669 -143.149821)
		(end 424.991022 -143.030448)
		(width 0.1143)
		(layer "B.Cu")
		(net "SATA6G_P2_TX_C_DP")
	)
	(arc
		(start 425.266358 -144.154398)
		(mid 425.254491 -144.149465)
		(end 425.24299 -144.14373)
		(width 0.1143)
		(layer "B.Cu")
		(net "SATA6G_P2_TX_C_DP")
	)
	(arc
		(start 425.468288 -144.113758)
		(mid 425.40215 -144.171809)
		(end 425.31411 -144.172178)
		(width 0.1143)
		(layer "B.Cu")
		(net "SATA6G_P2_TX_C_DP")
	)
	(arc
		(start 425.24299 -144.14373)
		(mid 425.238055 -144.14103)
		(end 425.233084 -144.138396)
		(width 0.1143)
		(layer "B.Cu")
		(net "SATA6G_P2_TX_C_DP")
	)
	(arc
		(start 424.845734 -142.88516)
		(mid 424.818301 -142.844009)
		(end 424.80865 -142.795498)
		(width 0.1143)
		(layer "B.Cu")
		(net "SATA6G_P2_TX_C_DP")
	)
	(arc
		(start 424.80865 -142.425928)
		(mid 424.818283 -142.37741)
		(end 424.845734 -142.336266)
		(width 0.1143)
		(layer "B.Cu")
		(net "SATA6G_P2_TX_C_DP")
	)
	(segment
		(start 425.026074 -144.94002)
		(end 425.183046 -144.646904)
		(width 0.1143)
		(layer "B.Cu")
		(net "SATA6G_P2_TX_C_DN")
	)
	(segment
		(start 424.56735 -142.795752)
		(end 424.56735 -142.425928)
		(width 0.1143)
		(layer "B.Cu")
		(net "SATA6G_P2_TX_C_DN")
	)
	(segment
		(start 424.820334 -143.201136)
		(end 424.674792 -143.055848)
		(width 0.1143)
		(layer "B.Cu")
		(net "SATA6G_P2_TX_C_DN")
	)
	(segment
		(start 424.530266 -142.336266)
		(end 424.18 -141.986)
		(width 0.1143)
		(layer "B.Cu")
		(net "SATA6G_P2_TX_C_DN")
	)
	(segment
		(start 425.08932 -144.335246)
		(end 425.044362 -144.310862)
		(width 0.1143)
		(layer "B.Cu")
		(net "SATA6G_P2_TX_C_DN")
	)
	(segment
		(start 424.857418 -143.997172)
		(end 424.857418 -143.290798)
		(width 0.1143)
		(layer "B.Cu")
		(net "SATA6G_P2_TX_C_DN")
	)
	(arc
		(start 425.183046 -144.646904)
		(mid 425.200705 -144.471649)
		(end 425.08932 -144.335246)
		(width 0.1143)
		(layer "B.Cu")
		(net "SATA6G_P2_TX_C_DN")
	)
	(arc
		(start 424.857418 -143.290798)
		(mid 424.847785 -143.24228)
		(end 424.820334 -143.201136)
		(width 0.1143)
		(layer "B.Cu")
		(net "SATA6G_P2_TX_C_DN")
	)
	(arc
		(start 425.044362 -144.310862)
		(mid 424.907596 -144.179822)
		(end 424.857418 -143.997172)
		(width 0.1143)
		(layer "B.Cu")
		(net "SATA6G_P2_TX_C_DN")
	)
	(arc
		(start 424.674792 -143.055848)
		(mid 424.595217 -142.936472)
		(end 424.56735 -142.795752)
		(width 0.1143)
		(layer "B.Cu")
		(net "SATA6G_P2_TX_C_DN")
	)
	(arc
		(start 424.56735 -142.425928)
		(mid 424.557717 -142.37741)
		(end 424.530266 -142.336266)
		(width 0.1143)
		(layer "B.Cu")
		(net "SATA6G_P2_TX_C_DN")
	)
	(segment
		(start 423.623486 -151.159972)
		(end 423.750994 -151.032464)
		(width 0.1143)
		(layer "B.Cu")
		(net "SATA6G_P2_RX_C_DP")
	)
	(segment
		(start 425.356274 -151.678894)
		(end 425.35729 -151.679402)
		(width 0.1143)
		(layer "B.Cu")
		(net "SATA6G_P2_RX_C_DP")
	)
	(segment
		(start 421.513 -150.876)
		(end 421.796972 -151.159972)
		(width 0.1143)
		(layer "B.Cu")
		(net "SATA6G_P2_RX_C_DP")
	)
	(segment
		(start 421.877744 -151.1935)
		(end 423.542714 -151.1935)
		(width 0.1143)
		(layer "B.Cu")
		(net "SATA6G_P2_RX_C_DP")
	)
	(segment
		(start 425.271184 -151.633682)
		(end 425.356274 -151.678894)
		(width 0.1143)
		(layer "B.Cu")
		(net "SATA6G_P2_RX_C_DP")
	)
	(segment
		(start 424.663108 -151.032464)
		(end 425.24426 -151.613616)
		(width 0.1143)
		(layer "B.Cu")
		(net "SATA6G_P2_RX_C_DP")
	)
	(segment
		(start 425.51223 -151.632666)
		(end 425.775882 -151.139906)
		(width 0.1143)
		(layer "B.Cu")
		(net "SATA6G_P2_RX_C_DP")
	)
	(segment
		(start 424.002454 -150.928324)
		(end 424.411648 -150.928324)
		(width 0.1143)
		(layer "B.Cu")
		(net "SATA6G_P2_RX_C_DP")
	)
	(arc
		(start 423.750994 -151.032464)
		(mid 423.866365 -150.955376)
		(end 424.002454 -150.928324)
		(width 0.1143)
		(layer "B.Cu")
		(net "SATA6G_P2_RX_C_DP")
	)
	(arc
		(start 421.796972 -151.159972)
		(mid 421.834031 -151.184734)
		(end 421.877744 -151.1935)
		(width 0.1143)
		(layer "B.Cu")
		(net "SATA6G_P2_RX_C_DP")
	)
	(arc
		(start 424.411648 -150.928324)
		(mid 424.54773 -150.955392)
		(end 424.663108 -151.032464)
		(width 0.1143)
		(layer "B.Cu")
		(net "SATA6G_P2_RX_C_DP")
	)
	(arc
		(start 423.542714 -151.1935)
		(mid 423.586455 -151.184799)
		(end 423.623486 -151.159972)
		(width 0.1143)
		(layer "B.Cu")
		(net "SATA6G_P2_RX_C_DP")
	)
	(arc
		(start 425.24426 -151.613616)
		(mid 425.256989 -151.624631)
		(end 425.271184 -151.633682)
		(width 0.1143)
		(layer "B.Cu")
		(net "SATA6G_P2_RX_C_DP")
	)
	(arc
		(start 425.35729 -151.679402)
		(mid 425.444424 -151.688148)
		(end 425.51223 -151.632666)
		(width 0.1143)
		(layer "B.Cu")
		(net "SATA6G_P2_RX_C_DP")
	)
	(segment
		(start 423.542968 -151.4348)
		(end 423.033444 -151.4348)
		(width 0.1143)
		(layer "B.Cu")
		(net "SATA6G_P2_RX_C_DN")
	)
	(segment
		(start 425.073318 -151.784304)
		(end 424.49242 -151.203152)
		(width 0.1143)
		(layer "B.Cu")
		(net "SATA6G_P2_RX_C_DN")
	)
	(segment
		(start 424.411902 -151.169624)
		(end 424.002454 -151.169624)
		(width 0.1143)
		(layer "B.Cu")
		(net "SATA6G_P2_RX_C_DN")
	)
	(segment
		(start 425.026074 -152.539954)
		(end 425.28998 -152.04694)
		(width 0.1143)
		(layer "B.Cu")
		(net "SATA6G_P2_RX_C_DN")
	)
	(segment
		(start 425.24299 -151.892254)
		(end 425.157392 -151.846788)
		(width 0.1143)
		(layer "B.Cu")
		(net "SATA6G_P2_RX_C_DN")
	)
	(segment
		(start 425.243244 -151.892254)
		(end 425.24299 -151.892254)
		(width 0.1143)
		(layer "B.Cu")
		(net "SATA6G_P2_RX_C_DN")
	)
	(segment
		(start 422.233344 -151.4348)
		(end 421.890444 -151.4348)
		(width 0.1143)
		(layer "B.Cu")
		(net "SATA6G_P2_RX_C_DN")
	)
	(segment
		(start 423.921682 -151.203152)
		(end 423.794174 -151.33066)
		(width 0.1143)
		(layer "B.Cu")
		(net "SATA6G_P2_RX_C_DN")
	)
	(segment
		(start 422.804844 -151.5491)
		(end 422.461944 -151.5491)
		(width 0.1143)
		(layer "B.Cu")
		(net "SATA6G_P2_RX_C_DN")
	)
	(segment
		(start 421.809672 -151.468328)
		(end 421.513 -151.765)
		(width 0.1143)
		(layer "B.Cu")
		(net "SATA6G_P2_RX_C_DN")
	)
	(arc
		(start 424.002454 -151.169624)
		(mid 423.958713 -151.178325)
		(end 423.921682 -151.203152)
		(width 0.1143)
		(layer "B.Cu")
		(net "SATA6G_P2_RX_C_DN")
	)
	(arc
		(start 422.347644 -151.49195)
		(mid 422.296239 -151.451896)
		(end 422.233344 -151.4348)
		(width 0.1143)
		(layer "B.Cu")
		(net "SATA6G_P2_RX_C_DN")
	)
	(arc
		(start 421.890444 -151.4348)
		(mid 421.846703 -151.443501)
		(end 421.809672 -151.468328)
		(width 0.1143)
		(layer "B.Cu")
		(net "SATA6G_P2_RX_C_DN")
	)
	(arc
		(start 424.49242 -151.203152)
		(mid 424.455479 -151.178439)
		(end 424.411902 -151.169624)
		(width 0.1143)
		(layer "B.Cu")
		(net "SATA6G_P2_RX_C_DN")
	)
	(arc
		(start 422.919144 -151.49195)
		(mid 422.867739 -151.532004)
		(end 422.804844 -151.5491)
		(width 0.1143)
		(layer "B.Cu")
		(net "SATA6G_P2_RX_C_DN")
	)
	(arc
		(start 422.461944 -151.5491)
		(mid 422.39903 -151.532043)
		(end 422.347644 -151.49195)
		(width 0.1143)
		(layer "B.Cu")
		(net "SATA6G_P2_RX_C_DN")
	)
	(arc
		(start 425.28998 -152.04694)
		(mid 425.298554 -151.959972)
		(end 425.243244 -151.892254)
		(width 0.1143)
		(layer "B.Cu")
		(net "SATA6G_P2_RX_C_DN")
	)
	(arc
		(start 423.794174 -151.33066)
		(mid 423.678921 -151.4077)
		(end 423.542968 -151.4348)
		(width 0.1143)
		(layer "B.Cu")
		(net "SATA6G_P2_RX_C_DN")
	)
	(arc
		(start 425.157392 -151.846788)
		(mid 425.113044 -151.818656)
		(end 425.073318 -151.784304)
		(width 0.1143)
		(layer "B.Cu")
		(net "SATA6G_P2_RX_C_DN")
	)
	(arc
		(start 423.033444 -151.4348)
		(mid 422.97053 -151.451857)
		(end 422.919144 -151.49195)
		(width 0.1143)
		(layer "B.Cu")
		(net "SATA6G_P2_RX_C_DN")
	)
	(segment
		(start 427.76775 -147.821904)
		(end 428.026068 -147.340066)
		(width 0.1143)
		(layer "B.Cu")
		(net "SATA6G_P1_TX_C_DP")
	)
	(segment
		(start 423.436542 -143.967708)
		(end 423.436542 -144.783302)
		(width 0.1143)
		(layer "B.Cu")
		(net "SATA6G_P1_TX_C_DP")
	)
	(segment
		(start 423.9387 -145.175986)
		(end 424.181016 -145.418556)
		(width 0.1143)
		(layer "B.Cu")
		(net "SATA6G_P1_TX_C_DP")
	)
	(segment
		(start 425.758864 -145.94078)
		(end 425.974256 -145.94078)
		(width 0.1143)
		(layer "B.Cu")
		(net "SATA6G_P1_TX_C_DP")
	)
	(segment
		(start 426.22597 -146.04492)
		(end 427.206918 -147.025868)
		(width 0.1143)
		(layer "B.Cu")
		(net "SATA6G_P1_TX_C_DP")
	)
	(segment
		(start 422.92016 -143.298672)
		(end 423.328592 -143.707104)
		(width 0.1143)
		(layer "B.Cu")
		(net "SATA6G_P1_TX_C_DP")
	)
	(segment
		(start 427.548548 -147.848574)
		(end 427.595538 -147.87372)
		(width 0.1143)
		(layer "B.Cu")
		(net "SATA6G_P1_TX_C_DP")
	)
	(segment
		(start 427.366938 -147.723352)
		(end 427.414944 -147.771358)
		(width 0.1143)
		(layer "B.Cu")
		(net "SATA6G_P1_TX_C_DP")
	)
	(segment
		(start 422.402 -141.9606)
		(end 422.115234 -142.247366)
		(width 0.1143)
		(layer "B.Cu")
		(net "SATA6G_P1_TX_C_DP")
	)
	(segment
		(start 423.47388 -144.872964)
		(end 423.69613 -145.095214)
		(width 0.1143)
		(layer "B.Cu")
		(net "SATA6G_P1_TX_C_DP")
	)
	(segment
		(start 424.59402 -145.94078)
		(end 424.958764 -145.94078)
		(width 0.1143)
		(layer "B.Cu")
		(net "SATA6G_P1_TX_C_DP")
	)
	(segment
		(start 427.442122 -147.791424)
		(end 427.547786 -147.848066)
		(width 0.1143)
		(layer "B.Cu")
		(net "SATA6G_P1_TX_C_DP")
	)
	(segment
		(start 424.261788 -145.660872)
		(end 424.504358 -145.903442)
		(width 0.1143)
		(layer "B.Cu")
		(net "SATA6G_P1_TX_C_DP")
	)
	(segment
		(start 427.311058 -147.277582)
		(end 427.311058 -147.588478)
		(width 0.1143)
		(layer "B.Cu")
		(net "SATA6G_P1_TX_C_DP")
	)
	(segment
		(start 427.547786 -147.848066)
		(end 427.548548 -147.848574)
		(width 0.1143)
		(layer "B.Cu")
		(net "SATA6G_P1_TX_C_DP")
	)
	(segment
		(start 422.596818 -142.813786)
		(end 422.839388 -143.056102)
		(width 0.1143)
		(layer "B.Cu")
		(net "SATA6G_P1_TX_C_DP")
	)
	(segment
		(start 422.07815 -142.337028)
		(end 422.07815 -142.409164)
		(width 0.1143)
		(layer "B.Cu")
		(net "SATA6G_P1_TX_C_DP")
	)
	(segment
		(start 425.187364 -145.82648)
		(end 425.530264 -145.82648)
		(width 0.1143)
		(layer "B.Cu")
		(net "SATA6G_P1_TX_C_DP")
	)
	(segment
		(start 422.111932 -142.490444)
		(end 422.354502 -142.733014)
		(width 0.1143)
		(layer "B.Cu")
		(net "SATA6G_P1_TX_C_DP")
	)
	(segment
		(start 423.436542 -144.783302)
		(end 423.436796 -144.783048)
		(width 0.1143)
		(layer "B.Cu")
		(net "SATA6G_P1_TX_C_DP")
	)
	(arc
		(start 425.974256 -145.94078)
		(mid 426.110464 -145.967838)
		(end 426.22597 -146.04492)
		(width 0.1143)
		(layer "B.Cu")
		(net "SATA6G_P1_TX_C_DP")
	)
	(arc
		(start 425.530264 -145.82648)
		(mid 425.593178 -145.843537)
		(end 425.644564 -145.88363)
		(width 0.1143)
		(layer "B.Cu")
		(net "SATA6G_P1_TX_C_DP")
	)
	(arc
		(start 422.47566 -142.7734)
		(mid 422.540303 -142.781401)
		(end 422.596818 -142.813786)
		(width 0.1143)
		(layer "B.Cu")
		(net "SATA6G_P1_TX_C_DP")
	)
	(arc
		(start 423.436796 -144.783048)
		(mid 423.44638 -144.831703)
		(end 423.47388 -144.872964)
		(width 0.1143)
		(layer "B.Cu")
		(net "SATA6G_P1_TX_C_DP")
	)
	(arc
		(start 427.311058 -147.588478)
		(mid 427.325578 -147.661476)
		(end 427.366938 -147.723352)
		(width 0.1143)
		(layer "B.Cu")
		(net "SATA6G_P1_TX_C_DP")
	)
	(arc
		(start 423.328592 -143.707104)
		(mid 423.408537 -143.826656)
		(end 423.436542 -143.967708)
		(width 0.1143)
		(layer "B.Cu")
		(net "SATA6G_P1_TX_C_DP")
	)
	(arc
		(start 423.69613 -145.095214)
		(mid 423.752645 -145.127599)
		(end 423.817288 -145.1356)
		(width 0.1143)
		(layer "B.Cu")
		(net "SATA6G_P1_TX_C_DP")
	)
	(arc
		(start 427.206918 -147.025868)
		(mid 427.283977 -147.141384)
		(end 427.311058 -147.277582)
		(width 0.1143)
		(layer "B.Cu")
		(net "SATA6G_P1_TX_C_DP")
	)
	(arc
		(start 424.181016 -145.418556)
		(mid 424.213401 -145.475071)
		(end 424.221402 -145.539714)
		(width 0.1143)
		(layer "B.Cu")
		(net "SATA6G_P1_TX_C_DP")
	)
	(arc
		(start 422.879774 -143.177514)
		(mid 422.887775 -143.242157)
		(end 422.92016 -143.298672)
		(width 0.1143)
		(layer "B.Cu")
		(net "SATA6G_P1_TX_C_DP")
	)
	(arc
		(start 425.073064 -145.88363)
		(mid 425.124469 -145.843576)
		(end 425.187364 -145.82648)
		(width 0.1143)
		(layer "B.Cu")
		(net "SATA6G_P1_TX_C_DP")
	)
	(arc
		(start 424.221402 -145.539714)
		(mid 424.229403 -145.604357)
		(end 424.261788 -145.660872)
		(width 0.1143)
		(layer "B.Cu")
		(net "SATA6G_P1_TX_C_DP")
	)
	(arc
		(start 424.504358 -145.903442)
		(mid 424.54548 -145.931012)
		(end 424.59402 -145.94078)
		(width 0.1143)
		(layer "B.Cu")
		(net "SATA6G_P1_TX_C_DP")
	)
	(arc
		(start 422.115234 -142.247366)
		(mid 422.087801 -142.288517)
		(end 422.07815 -142.337028)
		(width 0.1143)
		(layer "B.Cu")
		(net "SATA6G_P1_TX_C_DP")
	)
	(arc
		(start 427.414944 -147.771358)
		(mid 427.427788 -147.782402)
		(end 427.442122 -147.791424)
		(width 0.1143)
		(layer "B.Cu")
		(net "SATA6G_P1_TX_C_DP")
	)
	(arc
		(start 427.595538 -147.87372)
		(mid 427.69236 -147.883503)
		(end 427.76775 -147.821904)
		(width 0.1143)
		(layer "B.Cu")
		(net "SATA6G_P1_TX_C_DP")
	)
	(arc
		(start 425.644564 -145.88363)
		(mid 425.695969 -145.923684)
		(end 425.758864 -145.94078)
		(width 0.1143)
		(layer "B.Cu")
		(net "SATA6G_P1_TX_C_DP")
	)
	(arc
		(start 423.817288 -145.1356)
		(mid 423.882071 -145.143542)
		(end 423.9387 -145.175986)
		(width 0.1143)
		(layer "B.Cu")
		(net "SATA6G_P1_TX_C_DP")
	)
	(arc
		(start 424.958764 -145.94078)
		(mid 425.021678 -145.923723)
		(end 425.073064 -145.88363)
		(width 0.1143)
		(layer "B.Cu")
		(net "SATA6G_P1_TX_C_DP")
	)
	(arc
		(start 422.354502 -142.733014)
		(mid 422.411017 -142.765399)
		(end 422.47566 -142.7734)
		(width 0.1143)
		(layer "B.Cu")
		(net "SATA6G_P1_TX_C_DP")
	)
	(arc
		(start 422.07815 -142.409164)
		(mid 422.086924 -142.453182)
		(end 422.111932 -142.490444)
		(width 0.1143)
		(layer "B.Cu")
		(net "SATA6G_P1_TX_C_DP")
	)
	(arc
		(start 422.839388 -143.056102)
		(mid 422.871813 -143.112737)
		(end 422.879774 -143.177514)
		(width 0.1143)
		(layer "B.Cu")
		(net "SATA6G_P1_TX_C_DP")
	)
	(segment
		(start 427.482 -148.086826)
		(end 427.482254 -148.08708)
		(width 0.1143)
		(layer "B.Cu")
		(net "SATA6G_P1_TX_C_DN")
	)
	(segment
		(start 427.43501 -148.061934)
		(end 427.482 -148.086826)
		(width 0.1143)
		(layer "B.Cu")
		(net "SATA6G_P1_TX_C_DN")
	)
	(segment
		(start 427.434248 -148.061426)
		(end 427.43501 -148.061934)
		(width 0.1143)
		(layer "B.Cu")
		(net "SATA6G_P1_TX_C_DN")
	)
	(segment
		(start 421.941244 -142.661132)
		(end 422.664636 -143.384524)
		(width 0.1143)
		(layer "B.Cu")
		(net "SATA6G_P1_TX_C_DN")
	)
	(segment
		(start 423.303192 -145.043652)
		(end 424.33367 -146.07413)
		(width 0.1143)
		(layer "B.Cu")
		(net "SATA6G_P1_TX_C_DN")
	)
	(segment
		(start 422.664382 -143.384524)
		(end 423.157904 -143.877792)
		(width 0.1143)
		(layer "B.Cu")
		(net "SATA6G_P1_TX_C_DN")
	)
	(segment
		(start 422.664636 -143.384524)
		(end 422.664382 -143.384524)
		(width 0.1143)
		(layer "B.Cu")
		(net "SATA6G_P1_TX_C_DN")
	)
	(segment
		(start 427.53407 -148.258784)
		(end 427.276006 -148.740114)
		(width 0.1143)
		(layer "B.Cu")
		(net "SATA6G_P1_TX_C_DN")
	)
	(segment
		(start 426.055282 -146.215608)
		(end 427.03623 -147.196556)
		(width 0.1143)
		(layer "B.Cu")
		(net "SATA6G_P1_TX_C_DN")
	)
	(segment
		(start 423.195242 -143.967454)
		(end 423.195242 -144.783048)
		(width 0.1143)
		(layer "B.Cu")
		(net "SATA6G_P1_TX_C_DN")
	)
	(segment
		(start 423.194988 -143.967708)
		(end 423.195242 -143.967454)
		(width 0.1143)
		(layer "B.Cu")
		(net "SATA6G_P1_TX_C_DN")
	)
	(segment
		(start 421.83685 -142.337028)
		(end 421.83685 -142.409418)
		(width 0.1143)
		(layer "B.Cu")
		(net "SATA6G_P1_TX_C_DN")
	)
	(segment
		(start 421.513 -141.9606)
		(end 421.799766 -142.247366)
		(width 0.1143)
		(layer "B.Cu")
		(net "SATA6G_P1_TX_C_DN")
	)
	(segment
		(start 427.19625 -147.89404)
		(end 427.244256 -147.9423)
		(width 0.1143)
		(layer "B.Cu")
		(net "SATA6G_P1_TX_C_DN")
	)
	(segment
		(start 427.433486 -148.060664)
		(end 427.434248 -148.061426)
		(width 0.1143)
		(layer "B.Cu")
		(net "SATA6G_P1_TX_C_DN")
	)
	(segment
		(start 427.32833 -148.004276)
		(end 427.433486 -148.060664)
		(width 0.1143)
		(layer "B.Cu")
		(net "SATA6G_P1_TX_C_DN")
	)
	(segment
		(start 424.594274 -146.18208)
		(end 425.974256 -146.18208)
		(width 0.1143)
		(layer "B.Cu")
		(net "SATA6G_P1_TX_C_DN")
	)
	(segment
		(start 427.069758 -147.277582)
		(end 427.069758 -147.588732)
		(width 0.1143)
		(layer "B.Cu")
		(net "SATA6G_P1_TX_C_DN")
	)
	(arc
		(start 427.069758 -147.588732)
		(mid 427.102695 -147.753935)
		(end 427.19625 -147.89404)
		(width 0.1143)
		(layer "B.Cu")
		(net "SATA6G_P1_TX_C_DN")
	)
	(arc
		(start 425.974256 -146.18208)
		(mid 426.018094 -146.1908)
		(end 426.055282 -146.215608)
		(width 0.1143)
		(layer "B.Cu")
		(net "SATA6G_P1_TX_C_DN")
	)
	(arc
		(start 421.799766 -142.247366)
		(mid 421.827199 -142.288517)
		(end 421.83685 -142.337028)
		(width 0.1143)
		(layer "B.Cu")
		(net "SATA6G_P1_TX_C_DN")
	)
	(arc
		(start 427.03623 -147.196556)
		(mid 427.06107 -147.233731)
		(end 427.069758 -147.277582)
		(width 0.1143)
		(layer "B.Cu")
		(net "SATA6G_P1_TX_C_DN")
	)
	(arc
		(start 427.244256 -147.9423)
		(mid 427.284006 -147.976391)
		(end 427.32833 -148.004276)
		(width 0.1143)
		(layer "B.Cu")
		(net "SATA6G_P1_TX_C_DN")
	)
	(arc
		(start 423.195242 -144.783048)
		(mid 423.223312 -144.924073)
		(end 423.303192 -145.043652)
		(width 0.1143)
		(layer "B.Cu")
		(net "SATA6G_P1_TX_C_DN")
	)
	(arc
		(start 421.83685 -142.409418)
		(mid 421.86404 -142.545641)
		(end 421.941244 -142.661132)
		(width 0.1143)
		(layer "B.Cu")
		(net "SATA6G_P1_TX_C_DN")
	)
	(arc
		(start 424.33367 -146.07413)
		(mid 424.453222 -146.154075)
		(end 424.594274 -146.18208)
		(width 0.1143)
		(layer "B.Cu")
		(net "SATA6G_P1_TX_C_DN")
	)
	(arc
		(start 427.482254 -148.08708)
		(mid 427.543599 -148.162216)
		(end 427.53407 -148.258784)
		(width 0.1143)
		(layer "B.Cu")
		(net "SATA6G_P1_TX_C_DN")
	)
	(arc
		(start 423.157904 -143.877792)
		(mid 423.185386 -143.919061)
		(end 423.194988 -143.967708)
		(width 0.1143)
		(layer "B.Cu")
		(net "SATA6G_P1_TX_C_DN")
	)
	(segment
		(start 423.897044 -153.3398)
		(end 425.630848 -153.3398)
		(width 0.1143)
		(layer "B.Cu")
		(net "SATA6G_P1_RX_C_DP")
	)
	(segment
		(start 425.993306 -153.489914)
		(end 427.09592 -154.592528)
		(width 0.1143)
		(layer "B.Cu")
		(net "SATA6G_P1_RX_C_DP")
	)
	(segment
		(start 427.761908 -155.432506)
		(end 428.026068 -154.94)
		(width 0.1143)
		(layer "B.Cu")
		(net "SATA6G_P1_RX_C_DP")
	)
	(segment
		(start 427.24578 -155.164282)
		(end 427.4947 -155.413202)
		(width 0.1143)
		(layer "B.Cu")
		(net "SATA6G_P1_RX_C_DP")
	)
	(segment
		(start 427.212252 -154.873198)
		(end 427.212252 -155.08351)
		(width 0.1143)
		(layer "B.Cu")
		(net "SATA6G_P1_RX_C_DP")
	)
	(segment
		(start 427.52137 -155.433014)
		(end 427.606968 -155.478988)
		(width 0.1143)
		(layer "B.Cu")
		(net "SATA6G_P1_RX_C_DP")
	)
	(segment
		(start 423.545 -153.035)
		(end 423.816272 -153.306272)
		(width 0.1143)
		(layer "B.Cu")
		(net "SATA6G_P1_RX_C_DP")
	)
	(arc
		(start 427.4947 -155.413202)
		(mid 427.507306 -155.42409)
		(end 427.52137 -155.433014)
		(width 0.1143)
		(layer "B.Cu")
		(net "SATA6G_P1_RX_C_DP")
	)
	(arc
		(start 427.09592 -154.592528)
		(mid 427.182017 -154.721286)
		(end 427.212252 -154.873198)
		(width 0.1143)
		(layer "B.Cu")
		(net "SATA6G_P1_RX_C_DP")
	)
	(arc
		(start 427.212252 -155.08351)
		(mid 427.220953 -155.127251)
		(end 427.24578 -155.164282)
		(width 0.1143)
		(layer "B.Cu")
		(net "SATA6G_P1_RX_C_DP")
	)
	(arc
		(start 427.606968 -155.478988)
		(mid 427.694119 -155.487931)
		(end 427.761908 -155.432506)
		(width 0.1143)
		(layer "B.Cu")
		(net "SATA6G_P1_RX_C_DP")
	)
	(arc
		(start 423.816272 -153.306272)
		(mid 423.853331 -153.331034)
		(end 423.897044 -153.3398)
		(width 0.1143)
		(layer "B.Cu")
		(net "SATA6G_P1_RX_C_DP")
	)
	(arc
		(start 425.630848 -153.3398)
		(mid 425.827001 -153.378817)
		(end 425.993306 -153.489914)
		(width 0.1143)
		(layer "B.Cu")
		(net "SATA6G_P1_RX_C_DP")
	)
	(segment
		(start 427.406816 -155.645612)
		(end 427.406562 -155.645612)
		(width 0.1143)
		(layer "B.Cu")
		(net "SATA6G_P1_RX_C_DN")
	)
	(segment
		(start 424.278044 -153.5811)
		(end 423.935144 -153.5811)
		(width 0.1143)
		(layer "B.Cu")
		(net "SATA6G_P1_RX_C_DN")
	)
	(segment
		(start 423.854372 -153.614628)
		(end 423.545 -153.924)
		(width 0.1143)
		(layer "B.Cu")
		(net "SATA6G_P1_RX_C_DN")
	)
	(segment
		(start 426.925232 -154.763216)
		(end 425.822618 -153.660602)
		(width 0.1143)
		(layer "B.Cu")
		(net "SATA6G_P1_RX_C_DN")
	)
	(segment
		(start 427.324012 -155.58389)
		(end 427.075092 -155.33497)
		(width 0.1143)
		(layer "B.Cu")
		(net "SATA6G_P1_RX_C_DN")
	)
	(segment
		(start 427.276006 -156.340048)
		(end 427.54042 -155.847288)
		(width 0.1143)
		(layer "B.Cu")
		(net "SATA6G_P1_RX_C_DN")
	)
	(segment
		(start 424.849544 -153.6954)
		(end 424.506644 -153.6954)
		(width 0.1143)
		(layer "B.Cu")
		(net "SATA6G_P1_RX_C_DN")
	)
	(segment
		(start 425.630848 -153.5811)
		(end 425.078144 -153.5811)
		(width 0.1143)
		(layer "B.Cu")
		(net "SATA6G_P1_RX_C_DN")
	)
	(segment
		(start 426.970952 -155.083764)
		(end 426.970952 -154.873198)
		(width 0.1143)
		(layer "B.Cu")
		(net "SATA6G_P1_RX_C_DN")
	)
	(segment
		(start 427.493684 -155.692348)
		(end 427.492668 -155.69184)
		(width 0.1143)
		(layer "B.Cu")
		(net "SATA6G_P1_RX_C_DN")
	)
	(segment
		(start 427.492668 -155.69184)
		(end 427.406816 -155.645612)
		(width 0.1143)
		(layer "B.Cu")
		(net "SATA6G_P1_RX_C_DN")
	)
	(arc
		(start 427.406562 -155.645612)
		(mid 427.363038 -155.617759)
		(end 427.324012 -155.58389)
		(width 0.1143)
		(layer "B.Cu")
		(net "SATA6G_P1_RX_C_DN")
	)
	(arc
		(start 427.54042 -155.847288)
		(mid 427.549166 -155.760154)
		(end 427.493684 -155.692348)
		(width 0.1143)
		(layer "B.Cu")
		(net "SATA6G_P1_RX_C_DN")
	)
	(arc
		(start 427.075092 -155.33497)
		(mid 426.998052 -155.219717)
		(end 426.970952 -155.083764)
		(width 0.1143)
		(layer "B.Cu")
		(net "SATA6G_P1_RX_C_DN")
	)
	(arc
		(start 426.970952 -154.873198)
		(mid 426.95907 -154.813642)
		(end 426.925232 -154.763216)
		(width 0.1143)
		(layer "B.Cu")
		(net "SATA6G_P1_RX_C_DN")
	)
	(arc
		(start 424.963844 -153.63825)
		(mid 424.912439 -153.678304)
		(end 424.849544 -153.6954)
		(width 0.1143)
		(layer "B.Cu")
		(net "SATA6G_P1_RX_C_DN")
	)
	(arc
		(start 425.822618 -153.660602)
		(mid 425.734647 -153.601759)
		(end 425.630848 -153.5811)
		(width 0.1143)
		(layer "B.Cu")
		(net "SATA6G_P1_RX_C_DN")
	)
	(arc
		(start 424.392344 -153.63825)
		(mid 424.340939 -153.598196)
		(end 424.278044 -153.5811)
		(width 0.1143)
		(layer "B.Cu")
		(net "SATA6G_P1_RX_C_DN")
	)
	(arc
		(start 423.935144 -153.5811)
		(mid 423.891403 -153.589801)
		(end 423.854372 -153.614628)
		(width 0.1143)
		(layer "B.Cu")
		(net "SATA6G_P1_RX_C_DN")
	)
	(arc
		(start 424.506644 -153.6954)
		(mid 424.44373 -153.678343)
		(end 424.392344 -153.63825)
		(width 0.1143)
		(layer "B.Cu")
		(net "SATA6G_P1_RX_C_DN")
	)
	(arc
		(start 425.078144 -153.5811)
		(mid 425.01523 -153.598157)
		(end 424.963844 -153.63825)
		(width 0.1143)
		(layer "B.Cu")
		(net "SATA6G_P1_RX_C_DN")
	)
	(segment
		(start 427.34865 -143.99768)
		(end 427.348904 -143.997426)
		(width 0.1143)
		(layer "B.Cu")
		(net "SATA6G_P0_TX_C_DP")
	)
	(segment
		(start 427.736 -142.0876)
		(end 427.385734 -142.437866)
		(width 0.1143)
		(layer "B.Cu")
		(net "SATA6G_P0_TX_C_DP")
	)
	(segment
		(start 427.516544 -144.154398)
		(end 427.564296 -144.172178)
		(width 0.1143)
		(layer "B.Cu")
		(net "SATA6G_P0_TX_C_DP")
	)
	(segment
		(start 427.718474 -144.113758)
		(end 428.026068 -143.539972)
		(width 0.1143)
		(layer "B.Cu")
		(net "SATA6G_P0_TX_C_DP")
	)
	(segment
		(start 427.34865 -142.527528)
		(end 427.34865 -143.99768)
		(width 0.1143)
		(layer "B.Cu")
		(net "SATA6G_P0_TX_C_DP")
	)
	(segment
		(start 427.409102 -144.098264)
		(end 427.48327 -144.138396)
		(width 0.1143)
		(layer "B.Cu")
		(net "SATA6G_P0_TX_C_DP")
	)
	(arc
		(start 427.493176 -144.14373)
		(mid 427.50467 -144.149481)
		(end 427.516544 -144.154398)
		(width 0.1143)
		(layer "B.Cu")
		(net "SATA6G_P0_TX_C_DP")
	)
	(arc
		(start 427.348904 -143.997426)
		(mid 427.365098 -144.056146)
		(end 427.409102 -144.098264)
		(width 0.1143)
		(layer "B.Cu")
		(net "SATA6G_P0_TX_C_DP")
	)
	(arc
		(start 427.385734 -142.437866)
		(mid 427.358301 -142.479017)
		(end 427.34865 -142.527528)
		(width 0.1143)
		(layer "B.Cu")
		(net "SATA6G_P0_TX_C_DP")
	)
	(arc
		(start 427.48327 -144.138396)
		(mid 427.48824 -144.141032)
		(end 427.493176 -144.14373)
		(width 0.1143)
		(layer "B.Cu")
		(net "SATA6G_P0_TX_C_DP")
	)
	(arc
		(start 427.564296 -144.172178)
		(mid 427.652376 -144.171914)
		(end 427.718474 -144.113758)
		(width 0.1143)
		(layer "B.Cu")
		(net "SATA6G_P0_TX_C_DP")
	)
	(segment
		(start 427.339506 -144.335246)
		(end 427.294294 -144.310862)
		(width 0.1143)
		(layer "B.Cu")
		(net "SATA6G_P0_TX_C_DN")
	)
	(segment
		(start 427.10735 -143.997426)
		(end 427.10735 -142.527528)
		(width 0.1143)
		(layer "B.Cu")
		(net "SATA6G_P0_TX_C_DN")
	)
	(segment
		(start 427.276006 -144.94002)
		(end 427.433232 -144.646904)
		(width 0.1143)
		(layer "B.Cu")
		(net "SATA6G_P0_TX_C_DN")
	)
	(segment
		(start 427.070266 -142.437866)
		(end 426.72 -142.0876)
		(width 0.1143)
		(layer "B.Cu")
		(net "SATA6G_P0_TX_C_DN")
	)
	(arc
		(start 427.10735 -142.527528)
		(mid 427.097717 -142.47901)
		(end 427.070266 -142.437866)
		(width 0.1143)
		(layer "B.Cu")
		(net "SATA6G_P0_TX_C_DN")
	)
	(arc
		(start 427.294294 -144.310862)
		(mid 427.157593 -144.179931)
		(end 427.10735 -143.997426)
		(width 0.1143)
		(layer "B.Cu")
		(net "SATA6G_P0_TX_C_DN")
	)
	(arc
		(start 427.433232 -144.646904)
		(mid 427.450891 -144.471649)
		(end 427.339506 -144.335246)
		(width 0.1143)
		(layer "B.Cu")
		(net "SATA6G_P0_TX_C_DN")
	)
	(segment
		(start 423.881042 -149.388322)
		(end 423.59072 -149.098)
		(width 0.1143)
		(layer "B.Cu")
		(net "SATA6G_P0_RX_C_DP")
	)
	(segment
		(start 427.606714 -151.679402)
		(end 427.521116 -151.633428)
		(width 0.1143)
		(layer "B.Cu")
		(net "SATA6G_P0_RX_C_DP")
	)
	(segment
		(start 426.24629 -149.753066)
		(end 424.689524 -149.753066)
		(width 0.1143)
		(layer "B.Cu")
		(net "SATA6G_P0_RX_C_DP")
	)
	(segment
		(start 424.163744 -149.42185)
		(end 423.961814 -149.42185)
		(width 0.1143)
		(layer "B.Cu")
		(net "SATA6G_P0_RX_C_DP")
	)
	(segment
		(start 424.608752 -149.719538)
		(end 424.415204 -149.52599)
		(width 0.1143)
		(layer "B.Cu")
		(net "SATA6G_P0_RX_C_DP")
	)
	(segment
		(start 427.494192 -151.613616)
		(end 427.15561 -151.275034)
		(width 0.1143)
		(layer "B.Cu")
		(net "SATA6G_P0_RX_C_DP")
	)
	(segment
		(start 427.122082 -151.194262)
		(end 427.122082 -150.628858)
		(width 0.1143)
		(layer "B.Cu")
		(net "SATA6G_P0_RX_C_DP")
	)
	(segment
		(start 427.017942 -150.377398)
		(end 426.49775 -149.857206)
		(width 0.1143)
		(layer "B.Cu")
		(net "SATA6G_P0_RX_C_DP")
	)
	(segment
		(start 428.026068 -151.139906)
		(end 427.761654 -151.632666)
		(width 0.1143)
		(layer "B.Cu")
		(net "SATA6G_P0_RX_C_DP")
	)
	(arc
		(start 427.521116 -151.633428)
		(mid 427.506936 -151.624499)
		(end 427.494192 -151.613616)
		(width 0.1143)
		(layer "B.Cu")
		(net "SATA6G_P0_RX_C_DP")
	)
	(arc
		(start 427.761654 -151.632666)
		(mid 427.693878 -151.688247)
		(end 427.606714 -151.679402)
		(width 0.1143)
		(layer "B.Cu")
		(net "SATA6G_P0_RX_C_DP")
	)
	(arc
		(start 423.961814 -149.42185)
		(mid 423.918073 -149.413149)
		(end 423.881042 -149.388322)
		(width 0.1143)
		(layer "B.Cu")
		(net "SATA6G_P0_RX_C_DP")
	)
	(arc
		(start 426.49775 -149.857206)
		(mid 426.382379 -149.780118)
		(end 426.24629 -149.753066)
		(width 0.1143)
		(layer "B.Cu")
		(net "SATA6G_P0_RX_C_DP")
	)
	(arc
		(start 424.689524 -149.753066)
		(mid 424.645783 -149.744365)
		(end 424.608752 -149.719538)
		(width 0.1143)
		(layer "B.Cu")
		(net "SATA6G_P0_RX_C_DP")
	)
	(arc
		(start 427.122082 -150.628858)
		(mid 427.095014 -150.492776)
		(end 427.017942 -150.377398)
		(width 0.1143)
		(layer "B.Cu")
		(net "SATA6G_P0_RX_C_DP")
	)
	(arc
		(start 424.415204 -149.52599)
		(mid 424.299833 -149.448902)
		(end 424.163744 -149.42185)
		(width 0.1143)
		(layer "B.Cu")
		(net "SATA6G_P0_RX_C_DP")
	)
	(arc
		(start 427.15561 -151.275034)
		(mid 427.130848 -151.237975)
		(end 427.122082 -151.194262)
		(width 0.1143)
		(layer "B.Cu")
		(net "SATA6G_P0_RX_C_DP")
	)
	(segment
		(start 427.323758 -151.784558)
		(end 426.984922 -151.445722)
		(width 0.1143)
		(layer "B.Cu")
		(net "SATA6G_P0_RX_C_DN")
	)
	(segment
		(start 427.492414 -151.892254)
		(end 427.492414 -151.892)
		(width 0.1143)
		(layer "B.Cu")
		(net "SATA6G_P0_RX_C_DN")
	)
	(segment
		(start 426.246544 -149.994366)
		(end 425.83227 -149.994366)
		(width 0.1143)
		(layer "B.Cu")
		(net "SATA6G_P0_RX_C_DN")
	)
	(segment
		(start 427.49343 -151.892762)
		(end 427.492414 -151.892254)
		(width 0.1143)
		(layer "B.Cu")
		(net "SATA6G_P0_RX_C_DN")
	)
	(segment
		(start 426.880782 -151.194516)
		(end 426.880782 -150.628604)
		(width 0.1143)
		(layer "B.Cu")
		(net "SATA6G_P0_RX_C_DN")
	)
	(segment
		(start 427.492414 -151.892)
		(end 427.407324 -151.84628)
		(width 0.1143)
		(layer "B.Cu")
		(net "SATA6G_P0_RX_C_DN")
	)
	(segment
		(start 425.03217 -149.994366)
		(end 424.68927 -149.994366)
		(width 0.1143)
		(layer "B.Cu")
		(net "SATA6G_P0_RX_C_DN")
	)
	(segment
		(start 426.880782 -150.628604)
		(end 426.880528 -150.628858)
		(width 0.1143)
		(layer "B.Cu")
		(net "SATA6G_P0_RX_C_DN")
	)
	(segment
		(start 425.60367 -150.108666)
		(end 425.26077 -150.108666)
		(width 0.1143)
		(layer "B.Cu")
		(net "SATA6G_P0_RX_C_DN")
	)
	(segment
		(start 427.276006 -152.539954)
		(end 427.540166 -152.047702)
		(width 0.1143)
		(layer "B.Cu")
		(net "SATA6G_P0_RX_C_DN")
	)
	(segment
		(start 424.438064 -149.890226)
		(end 424.244516 -149.696678)
		(width 0.1143)
		(layer "B.Cu")
		(net "SATA6G_P0_RX_C_DN")
	)
	(segment
		(start 423.881042 -149.696678)
		(end 423.59072 -149.987)
		(width 0.1143)
		(layer "B.Cu")
		(net "SATA6G_P0_RX_C_DN")
	)
	(segment
		(start 424.163744 -149.66315)
		(end 423.961814 -149.66315)
		(width 0.1143)
		(layer "B.Cu")
		(net "SATA6G_P0_RX_C_DN")
	)
	(segment
		(start 426.847254 -150.548086)
		(end 426.327062 -150.027894)
		(width 0.1143)
		(layer "B.Cu")
		(net "SATA6G_P0_RX_C_DN")
	)
	(arc
		(start 427.407324 -151.84628)
		(mid 427.363275 -151.818487)
		(end 427.323758 -151.784558)
		(width 0.1143)
		(layer "B.Cu")
		(net "SATA6G_P0_RX_C_DN")
	)
	(arc
		(start 426.984922 -151.445722)
		(mid 426.907882 -151.330469)
		(end 426.880782 -151.194516)
		(width 0.1143)
		(layer "B.Cu")
		(net "SATA6G_P0_RX_C_DN")
	)
	(arc
		(start 425.26077 -150.108666)
		(mid 425.197856 -150.091609)
		(end 425.14647 -150.051516)
		(width 0.1143)
		(layer "B.Cu")
		(net "SATA6G_P0_RX_C_DN")
	)
	(arc
		(start 425.83227 -149.994366)
		(mid 425.769356 -150.011423)
		(end 425.71797 -150.051516)
		(width 0.1143)
		(layer "B.Cu")
		(net "SATA6G_P0_RX_C_DN")
	)
	(arc
		(start 424.244516 -149.696678)
		(mid 424.207457 -149.671916)
		(end 424.163744 -149.66315)
		(width 0.1143)
		(layer "B.Cu")
		(net "SATA6G_P0_RX_C_DN")
	)
	(arc
		(start 426.327062 -150.027894)
		(mid 426.290121 -150.003181)
		(end 426.246544 -149.994366)
		(width 0.1143)
		(layer "B.Cu")
		(net "SATA6G_P0_RX_C_DN")
	)
	(arc
		(start 426.880528 -150.628858)
		(mid 426.871945 -150.585147)
		(end 426.847254 -150.548086)
		(width 0.1143)
		(layer "B.Cu")
		(net "SATA6G_P0_RX_C_DN")
	)
	(arc
		(start 425.14647 -150.051516)
		(mid 425.095065 -150.011462)
		(end 425.03217 -149.994366)
		(width 0.1143)
		(layer "B.Cu")
		(net "SATA6G_P0_RX_C_DN")
	)
	(arc
		(start 427.540166 -152.047702)
		(mid 427.548912 -151.960568)
		(end 427.49343 -151.892762)
		(width 0.1143)
		(layer "B.Cu")
		(net "SATA6G_P0_RX_C_DN")
	)
	(arc
		(start 423.961814 -149.66315)
		(mid 423.918073 -149.671851)
		(end 423.881042 -149.696678)
		(width 0.1143)
		(layer "B.Cu")
		(net "SATA6G_P0_RX_C_DN")
	)
	(arc
		(start 425.71797 -150.051516)
		(mid 425.666565 -150.09157)
		(end 425.60367 -150.108666)
		(width 0.1143)
		(layer "B.Cu")
		(net "SATA6G_P0_RX_C_DN")
	)
	(arc
		(start 424.68927 -149.994366)
		(mid 424.553324 -149.967249)
		(end 424.438064 -149.890226)
		(width 0.1143)
		(layer "B.Cu")
		(net "SATA6G_P0_RX_C_DN")
	)
	(segment
		(start 375.3866 -81.383378)
		(end 375.0945 -81.091278)
		(width 0.10795)
		(layer "F.Cu")
		(net "RST_PCIE_M2_DEV_N")
	)
	(segment
		(start 380.287276 -81.383378)
		(end 375.3866 -81.383378)
		(width 0.10795)
		(layer "F.Cu")
		(net "RST_PCIE_M2_DEV_N")
	)
	(segment
		(start 382.490726 -80.941926)
		(end 382.490726 -80.365092)
		(width 0.10795)
		(layer "F.Cu")
		(net "RST_PCIE_M2_DEV_N")
	)
	(segment
		(start 381.515112 -80.155542)
		(end 380.287276 -81.383378)
		(width 0.10795)
		(layer "F.Cu")
		(net "RST_PCIE_M2_DEV_N")
	)
	(segment
		(start 382.490726 -80.365092)
		(end 382.281176 -80.155542)
		(width 0.10795)
		(layer "F.Cu")
		(net "RST_PCIE_M2_DEV_N")
	)
	(segment
		(start 375.0945 -79.844392)
		(end 374.744996 -79.494888)
		(width 0.10795)
		(layer "F.Cu")
		(net "RST_PCIE_M2_DEV_N")
	)
	(segment
		(start 382.281176 -80.155542)
		(end 381.515112 -80.155542)
		(width 0.10795)
		(layer "F.Cu")
		(net "RST_PCIE_M2_DEV_N")
	)
	(segment
		(start 375.0945 -81.091278)
		(end 375.0945 -79.844392)
		(width 0.10795)
		(layer "F.Cu")
		(net "RST_PCIE_M2_DEV_N")
	)
	(segment
		(start 387.985 -94.37497)
		(end 387.841236 -94.231206)
		(width 0.10795)
		(layer "F.Cu")
		(net "RMII_BMC_PCH_SPRNGVLLE_TXEN")
	)
	(segment
		(start 489.928662 -42.8498)
		(end 489.381546 -42.8498)
		(width 0.10795)
		(layer "F.Cu")
		(net "RMII_BMC_PCH_SPRNGVLLE_TXEN")
	)
	(segment
		(start 406.908 -22.1615)
		(end 406.908 -21.463)
		(width 0.10795)
		(layer "F.Cu")
		(net "RMII_BMC_PCH_SPRNGVLLE_TXEN")
	)
	(segment
		(start 489.014008 -43.217338)
		(end 488.6198 -43.217338)
		(width 0.10795)
		(layer "F.Cu")
		(net "RMII_BMC_PCH_SPRNGVLLE_TXEN")
	)
	(segment
		(start 387.89483 -91.529916)
		(end 387.89483 -90.580464)
		(width 0.10795)
		(layer "F.Cu")
		(net "RMII_BMC_PCH_SPRNGVLLE_TXEN")
	)
	(segment
		(start 387.689344 -93.357192)
		(end 387.770878 -93.275658)
		(width 0.10795)
		(layer "F.Cu")
		(net "RMII_BMC_PCH_SPRNGVLLE_TXEN")
	)
	(segment
		(start 490.2962 -43.217338)
		(end 489.928662 -42.8498)
		(width 0.10795)
		(layer "F.Cu")
		(net "RMII_BMC_PCH_SPRNGVLLE_TXEN")
	)
	(segment
		(start 387.89483 -90.580464)
		(end 387.285484 -89.971118)
		(width 0.10795)
		(layer "F.Cu")
		(net "RMII_BMC_PCH_SPRNGVLLE_TXEN")
	)
	(segment
		(start 490.619796 -43.540934)
		(end 490.2962 -43.217338)
		(width 0.10795)
		(layer "F.Cu")
		(net "RMII_BMC_PCH_SPRNGVLLE_TXEN")
	)
	(segment
		(start 387.841236 -93.862652)
		(end 387.689344 -93.71076)
		(width 0.10795)
		(layer "F.Cu")
		(net "RMII_BMC_PCH_SPRNGVLLE_TXEN")
	)
	(segment
		(start 387.770878 -93.275658)
		(end 387.770878 -91.653868)
		(width 0.10795)
		(layer "F.Cu")
		(net "RMII_BMC_PCH_SPRNGVLLE_TXEN")
	)
	(segment
		(start 490.895894 -43.540934)
		(end 490.619796 -43.540934)
		(width 0.10795)
		(layer "F.Cu")
		(net "RMII_BMC_PCH_SPRNGVLLE_TXEN")
	)
	(segment
		(start 489.381546 -42.8498)
		(end 489.014008 -43.217338)
		(width 0.10795)
		(layer "F.Cu")
		(net "RMII_BMC_PCH_SPRNGVLLE_TXEN")
	)
	(segment
		(start 491.0455 -44.0944)
		(end 491.0455 -43.69054)
		(width 0.10795)
		(layer "F.Cu")
		(net "RMII_BMC_PCH_SPRNGVLLE_TXEN")
	)
	(segment
		(start 387.689344 -93.71076)
		(end 387.689344 -93.357192)
		(width 0.10795)
		(layer "F.Cu")
		(net "RMII_BMC_PCH_SPRNGVLLE_TXEN")
	)
	(segment
		(start 387.841236 -94.231206)
		(end 387.841236 -93.862652)
		(width 0.10795)
		(layer "F.Cu")
		(net "RMII_BMC_PCH_SPRNGVLLE_TXEN")
	)
	(segment
		(start 387.770878 -91.653868)
		(end 387.89483 -91.529916)
		(width 0.10795)
		(layer "F.Cu")
		(net "RMII_BMC_PCH_SPRNGVLLE_TXEN")
	)
	(segment
		(start 491.0455 -43.69054)
		(end 490.895894 -43.540934)
		(width 0.10795)
		(layer "F.Cu")
		(net "RMII_BMC_PCH_SPRNGVLLE_TXEN")
	)
	(via
		(at 387.285484 -89.971118)
		(size 0.508)
		(drill 0.254)
		(layers "F.Cu" "B.Cu")
		(net "RMII_BMC_PCH_SPRNGVLLE_TXEN")
	)
	(via
		(at 392.684 -50.1396)
		(size 0.508)
		(drill 0.254)
		(layers "F.Cu" "B.Cu")
		(net "RMII_BMC_PCH_SPRNGVLLE_TXEN")
	)
	(via
		(at 491.2106 -42.5704)
		(size 0.6604)
		(drill 0.3302)
		(layers "F.Cu" "B.Cu")
		(net "RMII_BMC_PCH_SPRNGVLLE_TXEN")
	)
	(via
		(at 490.2962 -43.217338)
		(size 0.508)
		(drill 0.254)
		(layers "F.Cu" "B.Cu")
		(net "RMII_BMC_PCH_SPRNGVLLE_TXEN")
	)
	(via
		(at 406.908 -21.463)
		(size 0.508)
		(drill 0.254)
		(layers "F.Cu" "B.Cu")
		(net "RMII_BMC_PCH_SPRNGVLLE_TXEN")
	)
	(segment
		(start 406.908 -22.1615)
		(end 406.908 -21.463)
		(width 0.10795)
		(layer "B.Cu")
		(net "RMII_BMC_PCH_SPRNGVLLE_TXEN")
	)
	(segment
		(start 490.8296 -42.9514)
		(end 490.562138 -42.9514)
		(width 0.10795)
		(layer "B.Cu")
		(net "RMII_BMC_PCH_SPRNGVLLE_TXEN")
	)
	(segment
		(start 490.562138 -42.9514)
		(end 490.2962 -43.217338)
		(width 0.10795)
		(layer "B.Cu")
		(net "RMII_BMC_PCH_SPRNGVLLE_TXEN")
	)
	(segment
		(start 491.2106 -42.5704)
		(end 490.8296 -42.9514)
		(width 0.10795)
		(layer "B.Cu")
		(net "RMII_BMC_PCH_SPRNGVLLE_TXEN")
	)
	(segment
		(start 391.638028 -71.556372)
		(end 391.638028 -77.323188)
		(width 0.089408)
		(layer "In2.Cu")
		(net "RMII_BMC_PCH_SPRNGVLLE_TXEN")
	)
	(segment
		(start 386.886958 -88.386412)
		(end 386.886958 -89.271602)
		(width 0.089408)
		(layer "In2.Cu")
		(net "RMII_BMC_PCH_SPRNGVLLE_TXEN")
	)
	(segment
		(start 388.794244 -86.96325)
		(end 388.31012 -86.96325)
		(width 0.089408)
		(layer "In2.Cu")
		(net "RMII_BMC_PCH_SPRNGVLLE_TXEN")
	)
	(segment
		(start 387.285484 -89.670128)
		(end 387.285484 -89.971118)
		(width 0.089408)
		(layer "In2.Cu")
		(net "RMII_BMC_PCH_SPRNGVLLE_TXEN")
	)
	(segment
		(start 390.04748 -79.714598)
		(end 390.04748 -81.707736)
		(width 0.089408)
		(layer "In2.Cu")
		(net "RMII_BMC_PCH_SPRNGVLLE_TXEN")
	)
	(segment
		(start 394.613384 -62.942216)
		(end 393.338304 -64.217296)
		(width 0.089408)
		(layer "In2.Cu")
		(net "RMII_BMC_PCH_SPRNGVLLE_TXEN")
	)
	(segment
		(start 388.31012 -86.96325)
		(end 386.886958 -88.386412)
		(width 0.089408)
		(layer "In2.Cu")
		(net "RMII_BMC_PCH_SPRNGVLLE_TXEN")
	)
	(segment
		(start 393.823698 -51.002184)
		(end 393.823698 -51.481736)
		(width 0.089408)
		(layer "In2.Cu")
		(net "RMII_BMC_PCH_SPRNGVLLE_TXEN")
	)
	(segment
		(start 394.613384 -52.271422)
		(end 394.613384 -62.942216)
		(width 0.089408)
		(layer "In2.Cu")
		(net "RMII_BMC_PCH_SPRNGVLLE_TXEN")
	)
	(segment
		(start 392.961114 -50.1396)
		(end 393.823698 -51.002184)
		(width 0.089408)
		(layer "In2.Cu")
		(net "RMII_BMC_PCH_SPRNGVLLE_TXEN")
	)
	(segment
		(start 386.886958 -89.271602)
		(end 387.285484 -89.670128)
		(width 0.089408)
		(layer "In2.Cu")
		(net "RMII_BMC_PCH_SPRNGVLLE_TXEN")
	)
	(segment
		(start 390.612884 -78.348332)
		(end 390.612884 -79.149194)
		(width 0.089408)
		(layer "In2.Cu")
		(net "RMII_BMC_PCH_SPRNGVLLE_TXEN")
	)
	(segment
		(start 390.149842 -81.810098)
		(end 390.149842 -85.607652)
		(width 0.089408)
		(layer "In2.Cu")
		(net "RMII_BMC_PCH_SPRNGVLLE_TXEN")
	)
	(segment
		(start 393.338304 -69.856096)
		(end 391.638028 -71.556372)
		(width 0.089408)
		(layer "In2.Cu")
		(net "RMII_BMC_PCH_SPRNGVLLE_TXEN")
	)
	(segment
		(start 390.04748 -81.707736)
		(end 390.149842 -81.810098)
		(width 0.089408)
		(layer "In2.Cu")
		(net "RMII_BMC_PCH_SPRNGVLLE_TXEN")
	)
	(segment
		(start 392.684 -50.1396)
		(end 392.961114 -50.1396)
		(width 0.089408)
		(layer "In2.Cu")
		(net "RMII_BMC_PCH_SPRNGVLLE_TXEN")
	)
	(segment
		(start 391.638028 -77.323188)
		(end 390.612884 -78.348332)
		(width 0.089408)
		(layer "In2.Cu")
		(net "RMII_BMC_PCH_SPRNGVLLE_TXEN")
	)
	(segment
		(start 390.149842 -85.607652)
		(end 388.794244 -86.96325)
		(width 0.089408)
		(layer "In2.Cu")
		(net "RMII_BMC_PCH_SPRNGVLLE_TXEN")
	)
	(segment
		(start 390.612884 -79.149194)
		(end 390.04748 -79.714598)
		(width 0.089408)
		(layer "In2.Cu")
		(net "RMII_BMC_PCH_SPRNGVLLE_TXEN")
	)
	(segment
		(start 393.338304 -64.217296)
		(end 393.338304 -69.856096)
		(width 0.089408)
		(layer "In2.Cu")
		(net "RMII_BMC_PCH_SPRNGVLLE_TXEN")
	)
	(segment
		(start 393.823698 -51.481736)
		(end 394.613384 -52.271422)
		(width 0.089408)
		(layer "In2.Cu")
		(net "RMII_BMC_PCH_SPRNGVLLE_TXEN")
	)
	(segment
		(start 408.169618 -20.497292)
		(end 407.20391 -21.463)
		(width 0.089408)
		(layer "In4.Cu")
		(net "RMII_BMC_PCH_SPRNGVLLE_TXEN")
	)
	(segment
		(start 419.640258 -17.910302)
		(end 413.276542 -17.910302)
		(width 0.089408)
		(layer "In4.Cu")
		(net "RMII_BMC_PCH_SPRNGVLLE_TXEN")
	)
	(segment
		(start 483.025704 -38.857682)
		(end 483.025704 -38.80866)
		(width 0.089408)
		(layer "In4.Cu")
		(net "RMII_BMC_PCH_SPRNGVLLE_TXEN")
	)
	(segment
		(start 420.3827 -17.16786)
		(end 419.640258 -17.910302)
		(width 0.089408)
		(layer "In4.Cu")
		(net "RMII_BMC_PCH_SPRNGVLLE_TXEN")
	)
	(segment
		(start 490.2962 -43.217338)
		(end 489.960158 -42.881296)
		(width 0.089408)
		(layer "In4.Cu")
		(net "RMII_BMC_PCH_SPRNGVLLE_TXEN")
	)
	(segment
		(start 474.92666 -27.667204)
		(end 473.627704 -26.368248)
		(width 0.089408)
		(layer "In4.Cu")
		(net "RMII_BMC_PCH_SPRNGVLLE_TXEN")
	)
	(segment
		(start 445.070738 -15.634462)
		(end 444.260224 -16.444976)
		(width 0.089408)
		(layer "In4.Cu")
		(net "RMII_BMC_PCH_SPRNGVLLE_TXEN")
	)
	(segment
		(start 461.044544 -20.712176)
		(end 458.384656 -20.712176)
		(width 0.089408)
		(layer "In4.Cu")
		(net "RMII_BMC_PCH_SPRNGVLLE_TXEN")
	)
	(segment
		(start 448.816222 -15.634462)
		(end 445.070738 -15.634462)
		(width 0.089408)
		(layer "In4.Cu")
		(net "RMII_BMC_PCH_SPRNGVLLE_TXEN")
	)
	(segment
		(start 411.260798 -18.374614)
		(end 409.13812 -20.497292)
		(width 0.089408)
		(layer "In4.Cu")
		(net "RMII_BMC_PCH_SPRNGVLLE_TXEN")
	)
	(segment
		(start 455.012552 -20.362418)
		(end 452.934324 -20.362418)
		(width 0.089408)
		(layer "In4.Cu")
		(net "RMII_BMC_PCH_SPRNGVLLE_TXEN")
	)
	(segment
		(start 487.049318 -42.881296)
		(end 483.025704 -38.857682)
		(width 0.089408)
		(layer "In4.Cu")
		(net "RMII_BMC_PCH_SPRNGVLLE_TXEN")
	)
	(segment
		(start 483.017576 -37.925502)
		(end 483.258622 -37.684456)
		(width 0.089408)
		(layer "In4.Cu")
		(net "RMII_BMC_PCH_SPRNGVLLE_TXEN")
	)
	(segment
		(start 450.615304 -18.043398)
		(end 450.615304 -17.433544)
		(width 0.089408)
		(layer "In4.Cu")
		(net "RMII_BMC_PCH_SPRNGVLLE_TXEN")
	)
	(segment
		(start 464.69554 -22.954742)
		(end 463.28711 -22.954742)
		(width 0.089408)
		(layer "In4.Cu")
		(net "RMII_BMC_PCH_SPRNGVLLE_TXEN")
	)
	(segment
		(start 479.992182 -28.302458)
		(end 479.356928 -27.667204)
		(width 0.089408)
		(layer "In4.Cu")
		(net "RMII_BMC_PCH_SPRNGVLLE_TXEN")
	)
	(segment
		(start 479.356928 -27.667204)
		(end 474.92666 -27.667204)
		(width 0.089408)
		(layer "In4.Cu")
		(net "RMII_BMC_PCH_SPRNGVLLE_TXEN")
	)
	(segment
		(start 483.012496 -35.958526)
		(end 482.06279 -35.00882)
		(width 0.089408)
		(layer "In4.Cu")
		(net "RMII_BMC_PCH_SPRNGVLLE_TXEN")
	)
	(segment
		(start 489.960158 -42.881296)
		(end 487.049318 -42.881296)
		(width 0.089408)
		(layer "In4.Cu")
		(net "RMII_BMC_PCH_SPRNGVLLE_TXEN")
	)
	(segment
		(start 450.615304 -17.433544)
		(end 448.816222 -15.634462)
		(width 0.089408)
		(layer "In4.Cu")
		(net "RMII_BMC_PCH_SPRNGVLLE_TXEN")
	)
	(segment
		(start 456.179174 -21.52904)
		(end 455.012552 -20.362418)
		(width 0.089408)
		(layer "In4.Cu")
		(net "RMII_BMC_PCH_SPRNGVLLE_TXEN")
	)
	(segment
		(start 457.567792 -21.52904)
		(end 456.179174 -21.52904)
		(width 0.089408)
		(layer "In4.Cu")
		(net "RMII_BMC_PCH_SPRNGVLLE_TXEN")
	)
	(segment
		(start 452.934324 -20.362418)
		(end 450.615304 -18.043398)
		(width 0.089408)
		(layer "In4.Cu")
		(net "RMII_BMC_PCH_SPRNGVLLE_TXEN")
	)
	(segment
		(start 463.28711 -22.954742)
		(end 461.044544 -20.712176)
		(width 0.089408)
		(layer "In4.Cu")
		(net "RMII_BMC_PCH_SPRNGVLLE_TXEN")
	)
	(segment
		(start 482.06279 -34.063178)
		(end 479.992182 -31.99257)
		(width 0.089408)
		(layer "In4.Cu")
		(net "RMII_BMC_PCH_SPRNGVLLE_TXEN")
	)
	(segment
		(start 482.06279 -35.00882)
		(end 482.06279 -34.063178)
		(width 0.089408)
		(layer "In4.Cu")
		(net "RMII_BMC_PCH_SPRNGVLLE_TXEN")
	)
	(segment
		(start 407.20391 -21.463)
		(end 406.908 -21.463)
		(width 0.089408)
		(layer "In4.Cu")
		(net "RMII_BMC_PCH_SPRNGVLLE_TXEN")
	)
	(segment
		(start 483.012496 -36.53917)
		(end 483.012496 -35.958526)
		(width 0.089408)
		(layer "In4.Cu")
		(net "RMII_BMC_PCH_SPRNGVLLE_TXEN")
	)
	(segment
		(start 426.733208 -17.16786)
		(end 420.3827 -17.16786)
		(width 0.089408)
		(layer "In4.Cu")
		(net "RMII_BMC_PCH_SPRNGVLLE_TXEN")
	)
	(segment
		(start 413.276542 -17.910302)
		(end 412.81223 -18.374614)
		(width 0.089408)
		(layer "In4.Cu")
		(net "RMII_BMC_PCH_SPRNGVLLE_TXEN")
	)
	(segment
		(start 483.258622 -36.785296)
		(end 483.012496 -36.53917)
		(width 0.089408)
		(layer "In4.Cu")
		(net "RMII_BMC_PCH_SPRNGVLLE_TXEN")
	)
	(segment
		(start 444.260224 -16.444976)
		(end 427.456092 -16.444976)
		(width 0.089408)
		(layer "In4.Cu")
		(net "RMII_BMC_PCH_SPRNGVLLE_TXEN")
	)
	(segment
		(start 483.025704 -38.80866)
		(end 483.017576 -38.800532)
		(width 0.089408)
		(layer "In4.Cu")
		(net "RMII_BMC_PCH_SPRNGVLLE_TXEN")
	)
	(segment
		(start 479.992182 -31.99257)
		(end 479.992182 -28.302458)
		(width 0.089408)
		(layer "In4.Cu")
		(net "RMII_BMC_PCH_SPRNGVLLE_TXEN")
	)
	(segment
		(start 427.456092 -16.444976)
		(end 426.733208 -17.16786)
		(width 0.089408)
		(layer "In4.Cu")
		(net "RMII_BMC_PCH_SPRNGVLLE_TXEN")
	)
	(segment
		(start 412.81223 -18.374614)
		(end 411.260798 -18.374614)
		(width 0.089408)
		(layer "In4.Cu")
		(net "RMII_BMC_PCH_SPRNGVLLE_TXEN")
	)
	(segment
		(start 473.627704 -26.368248)
		(end 468.109046 -26.368248)
		(width 0.089408)
		(layer "In4.Cu")
		(net "RMII_BMC_PCH_SPRNGVLLE_TXEN")
	)
	(segment
		(start 458.384656 -20.712176)
		(end 457.567792 -21.52904)
		(width 0.089408)
		(layer "In4.Cu")
		(net "RMII_BMC_PCH_SPRNGVLLE_TXEN")
	)
	(segment
		(start 409.13812 -20.497292)
		(end 408.169618 -20.497292)
		(width 0.089408)
		(layer "In4.Cu")
		(net "RMII_BMC_PCH_SPRNGVLLE_TXEN")
	)
	(segment
		(start 468.109046 -26.368248)
		(end 464.69554 -22.954742)
		(width 0.089408)
		(layer "In4.Cu")
		(net "RMII_BMC_PCH_SPRNGVLLE_TXEN")
	)
	(segment
		(start 483.258622 -37.684456)
		(end 483.258622 -36.785296)
		(width 0.089408)
		(layer "In4.Cu")
		(net "RMII_BMC_PCH_SPRNGVLLE_TXEN")
	)
	(segment
		(start 483.017576 -38.800532)
		(end 483.017576 -37.925502)
		(width 0.089408)
		(layer "In4.Cu")
		(net "RMII_BMC_PCH_SPRNGVLLE_TXEN")
	)
	(segment
		(start 393.079478 -27.948636)
		(end 392.877294 -28.15082)
		(width 0.089408)
		(layer "In9.Cu")
		(net "RMII_BMC_PCH_SPRNGVLLE_TXEN")
	)
	(segment
		(start 403.699218 -20.762468)
		(end 402.740114 -19.803364)
		(width 0.089408)
		(layer "In9.Cu")
		(net "RMII_BMC_PCH_SPRNGVLLE_TXEN")
	)
	(segment
		(start 406.207468 -20.762468)
		(end 403.699218 -20.762468)
		(width 0.089408)
		(layer "In9.Cu")
		(net "RMII_BMC_PCH_SPRNGVLLE_TXEN")
	)
	(segment
		(start 406.908 -21.463)
		(end 406.207468 -20.762468)
		(width 0.089408)
		(layer "In9.Cu")
		(net "RMII_BMC_PCH_SPRNGVLLE_TXEN")
	)
	(segment
		(start 393.869926 -39.899336)
		(end 394.188696 -40.218106)
		(width 0.089408)
		(layer "In9.Cu")
		(net "RMII_BMC_PCH_SPRNGVLLE_TXEN")
	)
	(segment
		(start 393.034266 -24.772366)
		(end 393.034266 -26.420826)
		(width 0.089408)
		(layer "In9.Cu")
		(net "RMII_BMC_PCH_SPRNGVLLE_TXEN")
	)
	(segment
		(start 392.79449 -34.386266)
		(end 392.877294 -34.46907)
		(width 0.089408)
		(layer "In9.Cu")
		(net "RMII_BMC_PCH_SPRNGVLLE_TXEN")
	)
	(segment
		(start 392.877294 -32.994346)
		(end 392.79449 -33.07715)
		(width 0.089408)
		(layer "In9.Cu")
		(net "RMII_BMC_PCH_SPRNGVLLE_TXEN")
	)
	(segment
		(start 392.955018 -43.176444)
		(end 392.955018 -45.77969)
		(width 0.089408)
		(layer "In9.Cu")
		(net "RMII_BMC_PCH_SPRNGVLLE_TXEN")
	)
	(segment
		(start 394.188696 -41.942512)
		(end 393.869926 -42.261282)
		(width 0.089408)
		(layer "In9.Cu")
		(net "RMII_BMC_PCH_SPRNGVLLE_TXEN")
	)
	(segment
		(start 394.188696 -40.218106)
		(end 394.188696 -41.942512)
		(width 0.089408)
		(layer "In9.Cu")
		(net "RMII_BMC_PCH_SPRNGVLLE_TXEN")
	)
	(segment
		(start 392.877294 -28.15082)
		(end 392.877294 -32.994346)
		(width 0.089408)
		(layer "In9.Cu")
		(net "RMII_BMC_PCH_SPRNGVLLE_TXEN")
	)
	(segment
		(start 393.869926 -42.261282)
		(end 393.869926 -42.261536)
		(width 0.089408)
		(layer "In9.Cu")
		(net "RMII_BMC_PCH_SPRNGVLLE_TXEN")
	)
	(segment
		(start 392.79449 -33.07715)
		(end 392.79449 -34.386266)
		(width 0.089408)
		(layer "In9.Cu")
		(net "RMII_BMC_PCH_SPRNGVLLE_TXEN")
	)
	(segment
		(start 393.832334 -36.715446)
		(end 393.832334 -38.234112)
		(width 0.089408)
		(layer "In9.Cu")
		(net "RMII_BMC_PCH_SPRNGVLLE_TXEN")
	)
	(segment
		(start 393.034266 -26.420826)
		(end 393.079478 -26.466038)
		(width 0.089408)
		(layer "In9.Cu")
		(net "RMII_BMC_PCH_SPRNGVLLE_TXEN")
	)
	(segment
		(start 402.740114 -19.803364)
		(end 398.003268 -19.803364)
		(width 0.089408)
		(layer "In9.Cu")
		(net "RMII_BMC_PCH_SPRNGVLLE_TXEN")
	)
	(segment
		(start 392.684 -48.178466)
		(end 392.684 -50.1396)
		(width 0.089408)
		(layer "In9.Cu")
		(net "RMII_BMC_PCH_SPRNGVLLE_TXEN")
	)
	(segment
		(start 393.869926 -42.261536)
		(end 392.955018 -43.176444)
		(width 0.089408)
		(layer "In9.Cu")
		(net "RMII_BMC_PCH_SPRNGVLLE_TXEN")
	)
	(segment
		(start 393.265914 -46.090586)
		(end 393.265914 -47.596552)
		(width 0.089408)
		(layer "In9.Cu")
		(net "RMII_BMC_PCH_SPRNGVLLE_TXEN")
	)
	(segment
		(start 393.079478 -26.466038)
		(end 393.079478 -27.948636)
		(width 0.089408)
		(layer "In9.Cu")
		(net "RMII_BMC_PCH_SPRNGVLLE_TXEN")
	)
	(segment
		(start 398.003268 -19.803364)
		(end 393.034266 -24.772366)
		(width 0.089408)
		(layer "In9.Cu")
		(net "RMII_BMC_PCH_SPRNGVLLE_TXEN")
	)
	(segment
		(start 393.832334 -38.234112)
		(end 393.869926 -38.271704)
		(width 0.089408)
		(layer "In9.Cu")
		(net "RMII_BMC_PCH_SPRNGVLLE_TXEN")
	)
	(segment
		(start 393.869926 -38.271704)
		(end 393.869926 -39.899336)
		(width 0.089408)
		(layer "In9.Cu")
		(net "RMII_BMC_PCH_SPRNGVLLE_TXEN")
	)
	(segment
		(start 392.877294 -35.760406)
		(end 393.832334 -36.715446)
		(width 0.089408)
		(layer "In9.Cu")
		(net "RMII_BMC_PCH_SPRNGVLLE_TXEN")
	)
	(segment
		(start 392.955018 -45.77969)
		(end 393.265914 -46.090586)
		(width 0.089408)
		(layer "In9.Cu")
		(net "RMII_BMC_PCH_SPRNGVLLE_TXEN")
	)
	(segment
		(start 392.877294 -34.46907)
		(end 392.877294 -35.760406)
		(width 0.089408)
		(layer "In9.Cu")
		(net "RMII_BMC_PCH_SPRNGVLLE_TXEN")
	)
	(segment
		(start 393.265914 -47.596552)
		(end 392.684 -48.178466)
		(width 0.089408)
		(layer "In9.Cu")
		(net "RMII_BMC_PCH_SPRNGVLLE_TXEN")
	)
	(segment
		(start 402.971 -22.098)
		(end 402.971 -21.642578)
		(width 0.10795)
		(layer "F.Cu")
		(net "RMII_BMC_PCH_SPRNGVLLE_TXD1")
	)
	(segment
		(start 387.570726 -91.57081)
		(end 387.68401 -91.457526)
		(width 0.0889)
		(layer "F.Cu")
		(net "RMII_BMC_PCH_SPRNGVLLE_TXD1")
	)
	(segment
		(start 488.6198 -43.717464)
		(end 489.022136 -43.717464)
		(width 0.10795)
		(layer "F.Cu")
		(net "RMII_BMC_PCH_SPRNGVLLE_TXD1")
	)
	(segment
		(start 387.68401 -91.457526)
		(end 387.68401 -91.004644)
		(width 0.0889)
		(layer "F.Cu")
		(net "RMII_BMC_PCH_SPRNGVLLE_TXD1")
	)
	(segment
		(start 489.458 -43.2816)
		(end 489.585 -43.2816)
		(width 0.10795)
		(layer "F.Cu")
		(net "RMII_BMC_PCH_SPRNGVLLE_TXD1")
	)
	(segment
		(start 402.971 -21.642578)
		(end 403.189186 -21.424392)
		(width 0.10795)
		(layer "F.Cu")
		(net "RMII_BMC_PCH_SPRNGVLLE_TXD1")
	)
	(segment
		(start 489.022136 -43.717464)
		(end 489.458 -43.2816)
		(width 0.10795)
		(layer "F.Cu")
		(net "RMII_BMC_PCH_SPRNGVLLE_TXD1")
	)
	(segment
		(start 387.484874 -93.959934)
		(end 387.484874 -92.787978)
		(width 0.0889)
		(layer "F.Cu")
		(net "RMII_BMC_PCH_SPRNGVLLE_TXD1")
	)
	(segment
		(start 387.68401 -91.004644)
		(end 387.285484 -90.606118)
		(width 0.0889)
		(layer "F.Cu")
		(net "RMII_BMC_PCH_SPRNGVLLE_TXD1")
	)
	(segment
		(start 387.570726 -92.702126)
		(end 387.570726 -91.57081)
		(width 0.0889)
		(layer "F.Cu")
		(net "RMII_BMC_PCH_SPRNGVLLE_TXD1")
	)
	(segment
		(start 387.484874 -92.787978)
		(end 387.570726 -92.702126)
		(width 0.0889)
		(layer "F.Cu")
		(net "RMII_BMC_PCH_SPRNGVLLE_TXD1")
	)
	(via
		(at 489.585 -43.2816)
		(size 0.508)
		(drill 0.254)
		(layers "F.Cu" "B.Cu")
		(net "RMII_BMC_PCH_SPRNGVLLE_TXD1")
	)
	(via
		(at 392.66114 -50.794158)
		(size 0.508)
		(drill 0.254)
		(layers "F.Cu" "B.Cu")
		(net "RMII_BMC_PCH_SPRNGVLLE_TXD1")
	)
	(via
		(at 387.285484 -90.606118)
		(size 0.508)
		(drill 0.254)
		(layers "F.Cu" "B.Cu")
		(net "RMII_BMC_PCH_SPRNGVLLE_TXD1")
	)
	(via
		(at 403.189186 -21.424392)
		(size 0.508)
		(drill 0.254)
		(layers "F.Cu" "B.Cu")
		(net "RMII_BMC_PCH_SPRNGVLLE_TXD1")
	)
	(segment
		(start 389.958834 -84.595716)
		(end 389.958834 -81.93278)
		(width 0.089408)
		(layer "In2.Cu")
		(net "RMII_BMC_PCH_SPRNGVLLE_TXD1")
	)
	(segment
		(start 394.386308 -62.864492)
		(end 394.386308 -52.519326)
		(width 0.089408)
		(layer "In2.Cu")
		(net "RMII_BMC_PCH_SPRNGVLLE_TXD1")
	)
	(segment
		(start 390.39673 -78.29423)
		(end 391.2616 -77.42936)
		(width 0.089408)
		(layer "In2.Cu")
		(net "RMII_BMC_PCH_SPRNGVLLE_TXD1")
	)
	(segment
		(start 392.611356 -65.054988)
		(end 392.611356 -64.639444)
		(width 0.089408)
		(layer "In2.Cu")
		(net "RMII_BMC_PCH_SPRNGVLLE_TXD1")
	)
	(segment
		(start 386.881878 -89.600532)
		(end 386.68198 -89.400634)
		(width 0.089408)
		(layer "In2.Cu")
		(net "RMII_BMC_PCH_SPRNGVLLE_TXD1")
	)
	(segment
		(start 388.081266 -86.473284)
		(end 389.958834 -84.595716)
		(width 0.089408)
		(layer "In2.Cu")
		(net "RMII_BMC_PCH_SPRNGVLLE_TXD1")
	)
	(segment
		(start 388.081266 -86.778084)
		(end 388.081266 -86.473284)
		(width 0.089408)
		(layer "In2.Cu")
		(net "RMII_BMC_PCH_SPRNGVLLE_TXD1")
	)
	(segment
		(start 390.39673 -79.095092)
		(end 390.39673 -78.29423)
		(width 0.089408)
		(layer "In2.Cu")
		(net "RMII_BMC_PCH_SPRNGVLLE_TXD1")
	)
	(segment
		(start 386.881878 -90.202512)
		(end 386.881878 -89.600532)
		(width 0.089408)
		(layer "In2.Cu")
		(net "RMII_BMC_PCH_SPRNGVLLE_TXD1")
	)
	(segment
		(start 391.2616 -69.107304)
		(end 390.333738 -68.179442)
		(width 0.089408)
		(layer "In2.Cu")
		(net "RMII_BMC_PCH_SPRNGVLLE_TXD1")
	)
	(segment
		(start 386.68198 -88.17737)
		(end 388.081266 -86.778084)
		(width 0.089408)
		(layer "In2.Cu")
		(net "RMII_BMC_PCH_SPRNGVLLE_TXD1")
	)
	(segment
		(start 390.333738 -68.179442)
		(end 390.333738 -67.332606)
		(width 0.089408)
		(layer "In2.Cu")
		(net "RMII_BMC_PCH_SPRNGVLLE_TXD1")
	)
	(segment
		(start 389.958834 -81.93278)
		(end 389.856472 -81.830418)
		(width 0.089408)
		(layer "In2.Cu")
		(net "RMII_BMC_PCH_SPRNGVLLE_TXD1")
	)
	(segment
		(start 387.285484 -90.606118)
		(end 386.881878 -90.202512)
		(width 0.089408)
		(layer "In2.Cu")
		(net "RMII_BMC_PCH_SPRNGVLLE_TXD1")
	)
	(segment
		(start 390.333738 -67.332606)
		(end 392.611356 -65.054988)
		(width 0.089408)
		(layer "In2.Cu")
		(net "RMII_BMC_PCH_SPRNGVLLE_TXD1")
	)
	(segment
		(start 391.2616 -77.42936)
		(end 391.2616 -69.107304)
		(width 0.089408)
		(layer "In2.Cu")
		(net "RMII_BMC_PCH_SPRNGVLLE_TXD1")
	)
	(segment
		(start 389.856472 -79.63535)
		(end 390.39673 -79.095092)
		(width 0.089408)
		(layer "In2.Cu")
		(net "RMII_BMC_PCH_SPRNGVLLE_TXD1")
	)
	(segment
		(start 389.856472 -81.830418)
		(end 389.856472 -79.63535)
		(width 0.089408)
		(layer "In2.Cu")
		(net "RMII_BMC_PCH_SPRNGVLLE_TXD1")
	)
	(segment
		(start 392.611356 -64.639444)
		(end 394.386308 -62.864492)
		(width 0.089408)
		(layer "In2.Cu")
		(net "RMII_BMC_PCH_SPRNGVLLE_TXD1")
	)
	(segment
		(start 394.386308 -52.519326)
		(end 392.66114 -50.794158)
		(width 0.089408)
		(layer "In2.Cu")
		(net "RMII_BMC_PCH_SPRNGVLLE_TXD1")
	)
	(segment
		(start 386.68198 -89.400634)
		(end 386.68198 -88.17737)
		(width 0.089408)
		(layer "In2.Cu")
		(net "RMII_BMC_PCH_SPRNGVLLE_TXD1")
	)
	(segment
		(start 419.56101 -18.10131)
		(end 413.35579 -18.10131)
		(width 0.089408)
		(layer "In4.Cu")
		(net "RMII_BMC_PCH_SPRNGVLLE_TXD1")
	)
	(segment
		(start 407.051764 -21.885402)
		(end 403.650196 -21.885402)
		(width 0.089408)
		(layer "In4.Cu")
		(net "RMII_BMC_PCH_SPRNGVLLE_TXD1")
	)
	(segment
		(start 457.64704 -21.720048)
		(end 456.099926 -21.720048)
		(width 0.089408)
		(layer "In4.Cu")
		(net "RMII_BMC_PCH_SPRNGVLLE_TXD1")
	)
	(segment
		(start 482.821488 -37.690298)
		(end 482.108256 -36.977066)
		(width 0.089408)
		(layer "In4.Cu")
		(net "RMII_BMC_PCH_SPRNGVLLE_TXD1")
	)
	(segment
		(start 489.585 -43.2816)
		(end 487.179366 -43.2816)
		(width 0.089408)
		(layer "In4.Cu")
		(net "RMII_BMC_PCH_SPRNGVLLE_TXD1")
	)
	(segment
		(start 411.340046 -18.565622)
		(end 409.217368 -20.6883)
		(width 0.089408)
		(layer "In4.Cu")
		(net "RMII_BMC_PCH_SPRNGVLLE_TXD1")
	)
	(segment
		(start 427.53534 -16.635984)
		(end 426.812456 -17.358868)
		(width 0.089408)
		(layer "In4.Cu")
		(net "RMII_BMC_PCH_SPRNGVLLE_TXD1")
	)
	(segment
		(start 419.719252 -18.101564)
		(end 419.561264 -18.101564)
		(width 0.089408)
		(layer "In4.Cu")
		(net "RMII_BMC_PCH_SPRNGVLLE_TXD1")
	)
	(segment
		(start 479.27768 -27.858212)
		(end 474.847412 -27.858212)
		(width 0.089408)
		(layer "In4.Cu")
		(net "RMII_BMC_PCH_SPRNGVLLE_TXD1")
	)
	(segment
		(start 460.965296 -20.903184)
		(end 458.463904 -20.903184)
		(width 0.089408)
		(layer "In4.Cu")
		(net "RMII_BMC_PCH_SPRNGVLLE_TXD1")
	)
	(segment
		(start 420.461948 -17.358868)
		(end 419.719252 -18.101564)
		(width 0.089408)
		(layer "In4.Cu")
		(net "RMII_BMC_PCH_SPRNGVLLE_TXD1")
	)
	(segment
		(start 419.561264 -18.101564)
		(end 419.56101 -18.10131)
		(width 0.089408)
		(layer "In4.Cu")
		(net "RMII_BMC_PCH_SPRNGVLLE_TXD1")
	)
	(segment
		(start 413.35579 -18.10131)
		(end 412.891478 -18.565622)
		(width 0.089408)
		(layer "In4.Cu")
		(net "RMII_BMC_PCH_SPRNGVLLE_TXD1")
	)
	(segment
		(start 448.736974 -15.82547)
		(end 445.149986 -15.82547)
		(width 0.089408)
		(layer "In4.Cu")
		(net "RMII_BMC_PCH_SPRNGVLLE_TXD1")
	)
	(segment
		(start 487.179366 -43.2816)
		(end 482.821488 -38.923722)
		(width 0.089408)
		(layer "In4.Cu")
		(net "RMII_BMC_PCH_SPRNGVLLE_TXD1")
	)
	(segment
		(start 445.149986 -15.82547)
		(end 444.339472 -16.635984)
		(width 0.089408)
		(layer "In4.Cu")
		(net "RMII_BMC_PCH_SPRNGVLLE_TXD1")
	)
	(segment
		(start 479.801174 -32.236918)
		(end 479.801174 -28.381706)
		(width 0.089408)
		(layer "In4.Cu")
		(net "RMII_BMC_PCH_SPRNGVLLE_TXD1")
	)
	(segment
		(start 482.108256 -36.977066)
		(end 482.108256 -35.524186)
		(width 0.089408)
		(layer "In4.Cu")
		(net "RMII_BMC_PCH_SPRNGVLLE_TXD1")
	)
	(segment
		(start 450.424296 -17.512792)
		(end 448.736974 -15.82547)
		(width 0.089408)
		(layer "In4.Cu")
		(net "RMII_BMC_PCH_SPRNGVLLE_TXD1")
	)
	(segment
		(start 412.891478 -18.565622)
		(end 411.340046 -18.565622)
		(width 0.089408)
		(layer "In4.Cu")
		(net "RMII_BMC_PCH_SPRNGVLLE_TXD1")
	)
	(segment
		(start 479.801174 -28.381706)
		(end 479.27768 -27.858212)
		(width 0.089408)
		(layer "In4.Cu")
		(net "RMII_BMC_PCH_SPRNGVLLE_TXD1")
	)
	(segment
		(start 452.855076 -20.553426)
		(end 450.424296 -18.122646)
		(width 0.089408)
		(layer "In4.Cu")
		(net "RMII_BMC_PCH_SPRNGVLLE_TXD1")
	)
	(segment
		(start 454.933304 -20.553426)
		(end 452.855076 -20.553426)
		(width 0.089408)
		(layer "In4.Cu")
		(net "RMII_BMC_PCH_SPRNGVLLE_TXD1")
	)
	(segment
		(start 481.833174 -34.268918)
		(end 479.801174 -32.236918)
		(width 0.089408)
		(layer "In4.Cu")
		(net "RMII_BMC_PCH_SPRNGVLLE_TXD1")
	)
	(segment
		(start 409.217368 -20.6883)
		(end 409.201112 -20.6883)
		(width 0.089408)
		(layer "In4.Cu")
		(net "RMII_BMC_PCH_SPRNGVLLE_TXD1")
	)
	(segment
		(start 403.650196 -21.885402)
		(end 403.189186 -21.424392)
		(width 0.089408)
		(layer "In4.Cu")
		(net "RMII_BMC_PCH_SPRNGVLLE_TXD1")
	)
	(segment
		(start 473.548456 -26.559256)
		(end 468.02167 -26.559256)
		(width 0.089408)
		(layer "In4.Cu")
		(net "RMII_BMC_PCH_SPRNGVLLE_TXD1")
	)
	(segment
		(start 468.02167 -26.559256)
		(end 464.608164 -23.14575)
		(width 0.089408)
		(layer "In4.Cu")
		(net "RMII_BMC_PCH_SPRNGVLLE_TXD1")
	)
	(segment
		(start 482.108256 -35.524186)
		(end 481.833174 -35.249104)
		(width 0.089408)
		(layer "In4.Cu")
		(net "RMII_BMC_PCH_SPRNGVLLE_TXD1")
	)
	(segment
		(start 458.463904 -20.903184)
		(end 457.64704 -21.720048)
		(width 0.089408)
		(layer "In4.Cu")
		(net "RMII_BMC_PCH_SPRNGVLLE_TXD1")
	)
	(segment
		(start 444.339472 -16.635984)
		(end 427.53534 -16.635984)
		(width 0.089408)
		(layer "In4.Cu")
		(net "RMII_BMC_PCH_SPRNGVLLE_TXD1")
	)
	(segment
		(start 482.821488 -38.923722)
		(end 482.821488 -37.690298)
		(width 0.089408)
		(layer "In4.Cu")
		(net "RMII_BMC_PCH_SPRNGVLLE_TXD1")
	)
	(segment
		(start 426.812456 -17.358868)
		(end 420.461948 -17.358868)
		(width 0.089408)
		(layer "In4.Cu")
		(net "RMII_BMC_PCH_SPRNGVLLE_TXD1")
	)
	(segment
		(start 474.847412 -27.858212)
		(end 473.548456 -26.559256)
		(width 0.089408)
		(layer "In4.Cu")
		(net "RMII_BMC_PCH_SPRNGVLLE_TXD1")
	)
	(segment
		(start 409.201112 -20.6883)
		(end 409.200858 -20.688554)
		(width 0.089408)
		(layer "In4.Cu")
		(net "RMII_BMC_PCH_SPRNGVLLE_TXD1")
	)
	(segment
		(start 450.424296 -18.122646)
		(end 450.424296 -17.512792)
		(width 0.089408)
		(layer "In4.Cu")
		(net "RMII_BMC_PCH_SPRNGVLLE_TXD1")
	)
	(segment
		(start 456.099926 -21.720048)
		(end 454.933304 -20.553426)
		(width 0.089408)
		(layer "In4.Cu")
		(net "RMII_BMC_PCH_SPRNGVLLE_TXD1")
	)
	(segment
		(start 408.248612 -20.688554)
		(end 407.051764 -21.885402)
		(width 0.089408)
		(layer "In4.Cu")
		(net "RMII_BMC_PCH_SPRNGVLLE_TXD1")
	)
	(segment
		(start 409.200858 -20.688554)
		(end 408.248612 -20.688554)
		(width 0.089408)
		(layer "In4.Cu")
		(net "RMII_BMC_PCH_SPRNGVLLE_TXD1")
	)
	(segment
		(start 464.608164 -23.14575)
		(end 463.207862 -23.14575)
		(width 0.089408)
		(layer "In4.Cu")
		(net "RMII_BMC_PCH_SPRNGVLLE_TXD1")
	)
	(segment
		(start 481.833174 -35.249104)
		(end 481.833174 -34.268918)
		(width 0.089408)
		(layer "In4.Cu")
		(net "RMII_BMC_PCH_SPRNGVLLE_TXD1")
	)
	(segment
		(start 463.207862 -23.14575)
		(end 460.965296 -20.903184)
		(width 0.089408)
		(layer "In4.Cu")
		(net "RMII_BMC_PCH_SPRNGVLLE_TXD1")
	)
	(segment
		(start 393.854432 -42.817542)
		(end 394.636244 -42.817542)
		(width 0.089408)
		(layer "In9.Cu")
		(net "RMII_BMC_PCH_SPRNGVLLE_TXD1")
	)
	(segment
		(start 393.176506 -34.22777)
		(end 393.176506 -33.235646)
		(width 0.089408)
		(layer "In9.Cu")
		(net "RMII_BMC_PCH_SPRNGVLLE_TXD1")
	)
	(segment
		(start 394.294868 -38.598094)
		(end 394.294868 -38.156134)
		(width 0.089408)
		(layer "In9.Cu")
		(net "RMII_BMC_PCH_SPRNGVLLE_TXD1")
	)
	(segment
		(start 393.084304 -49.511204)
		(end 393.64793 -48.947578)
		(width 0.089408)
		(layer "In9.Cu")
		(net "RMII_BMC_PCH_SPRNGVLLE_TXD1")
	)
	(segment
		(start 398.141952 -20.231862)
		(end 402.6281 -20.231862)
		(width 0.089408)
		(layer "In9.Cu")
		(net "RMII_BMC_PCH_SPRNGVLLE_TXD1")
	)
	(segment
		(start 393.337034 -45.621194)
		(end 393.337034 -43.33494)
		(width 0.089408)
		(layer "In9.Cu")
		(net "RMII_BMC_PCH_SPRNGVLLE_TXD1")
	)
	(segment
		(start 394.21435 -36.216336)
		(end 394.00226 -36.004246)
		(width 0.089408)
		(layer "In9.Cu")
		(net "RMII_BMC_PCH_SPRNGVLLE_TXD1")
	)
	(segment
		(start 393.279884 -30.609286)
		(end 394.131546 -29.757624)
		(width 0.089408)
		(layer "In9.Cu")
		(net "RMII_BMC_PCH_SPRNGVLLE_TXD1")
	)
	(segment
		(start 395.242796 -41.399714)
		(end 395.242796 -39.546022)
		(width 0.089408)
		(layer "In9.Cu")
		(net "RMII_BMC_PCH_SPRNGVLLE_TXD1")
	)
	(segment
		(start 393.084304 -50.370994)
		(end 393.084304 -49.511204)
		(width 0.089408)
		(layer "In9.Cu")
		(net "RMII_BMC_PCH_SPRNGVLLE_TXD1")
	)
	(segment
		(start 393.64793 -48.947578)
		(end 393.64793 -45.93209)
		(width 0.089408)
		(layer "In9.Cu")
		(net "RMII_BMC_PCH_SPRNGVLLE_TXD1")
	)
	(segment
		(start 394.131546 -24.242268)
		(end 398.141952 -20.231862)
		(width 0.089408)
		(layer "In9.Cu")
		(net "RMII_BMC_PCH_SPRNGVLLE_TXD1")
	)
	(segment
		(start 403.189186 -20.792948)
		(end 403.189186 -21.424392)
		(width 0.089408)
		(layer "In9.Cu")
		(net "RMII_BMC_PCH_SPRNGVLLE_TXD1")
	)
	(segment
		(start 395.242796 -39.546022)
		(end 394.294868 -38.598094)
		(width 0.089408)
		(layer "In9.Cu")
		(net "RMII_BMC_PCH_SPRNGVLLE_TXD1")
	)
	(segment
		(start 395.24305 -42.210736)
		(end 395.24305 -41.399968)
		(width 0.089408)
		(layer "In9.Cu")
		(net "RMII_BMC_PCH_SPRNGVLLE_TXD1")
	)
	(segment
		(start 392.66114 -50.794158)
		(end 393.084304 -50.370994)
		(width 0.089408)
		(layer "In9.Cu")
		(net "RMII_BMC_PCH_SPRNGVLLE_TXD1")
	)
	(segment
		(start 393.279884 -35.258756)
		(end 393.279884 -34.331148)
		(width 0.089408)
		(layer "In9.Cu")
		(net "RMII_BMC_PCH_SPRNGVLLE_TXD1")
	)
	(segment
		(start 394.636244 -42.817542)
		(end 395.24305 -42.210736)
		(width 0.089408)
		(layer "In9.Cu")
		(net "RMII_BMC_PCH_SPRNGVLLE_TXD1")
	)
	(segment
		(start 393.64793 -45.93209)
		(end 393.337034 -45.621194)
		(width 0.089408)
		(layer "In9.Cu")
		(net "RMII_BMC_PCH_SPRNGVLLE_TXD1")
	)
	(segment
		(start 393.279884 -33.132268)
		(end 393.279884 -30.609286)
		(width 0.089408)
		(layer "In9.Cu")
		(net "RMII_BMC_PCH_SPRNGVLLE_TXD1")
	)
	(segment
		(start 394.294868 -38.156134)
		(end 394.21435 -38.075616)
		(width 0.089408)
		(layer "In9.Cu")
		(net "RMII_BMC_PCH_SPRNGVLLE_TXD1")
	)
	(segment
		(start 394.00226 -35.981132)
		(end 393.279884 -35.258756)
		(width 0.089408)
		(layer "In9.Cu")
		(net "RMII_BMC_PCH_SPRNGVLLE_TXD1")
	)
	(segment
		(start 394.21435 -38.075616)
		(end 394.21435 -36.216336)
		(width 0.089408)
		(layer "In9.Cu")
		(net "RMII_BMC_PCH_SPRNGVLLE_TXD1")
	)
	(segment
		(start 393.279884 -34.331148)
		(end 393.176506 -34.22777)
		(width 0.089408)
		(layer "In9.Cu")
		(net "RMII_BMC_PCH_SPRNGVLLE_TXD1")
	)
	(segment
		(start 393.337034 -43.33494)
		(end 393.854432 -42.817542)
		(width 0.089408)
		(layer "In9.Cu")
		(net "RMII_BMC_PCH_SPRNGVLLE_TXD1")
	)
	(segment
		(start 402.6281 -20.231862)
		(end 403.189186 -20.792948)
		(width 0.089408)
		(layer "In9.Cu")
		(net "RMII_BMC_PCH_SPRNGVLLE_TXD1")
	)
	(segment
		(start 395.24305 -41.399968)
		(end 395.242796 -41.399714)
		(width 0.089408)
		(layer "In9.Cu")
		(net "RMII_BMC_PCH_SPRNGVLLE_TXD1")
	)
	(segment
		(start 393.176506 -33.235646)
		(end 393.279884 -33.132268)
		(width 0.089408)
		(layer "In9.Cu")
		(net "RMII_BMC_PCH_SPRNGVLLE_TXD1")
	)
	(segment
		(start 394.00226 -36.004246)
		(end 394.00226 -35.981132)
		(width 0.089408)
		(layer "In9.Cu")
		(net "RMII_BMC_PCH_SPRNGVLLE_TXD1")
	)
	(segment
		(start 394.131546 -29.757624)
		(end 394.131546 -24.242268)
		(width 0.089408)
		(layer "In9.Cu")
		(net "RMII_BMC_PCH_SPRNGVLLE_TXD1")
	)
	(segment
		(start 405.257 -22.1615)
		(end 405.6126 -21.8059)
		(width 0.10795)
		(layer "F.Cu")
		(net "RMII_BMC_PCH_SPRNGVLLE_TXD0")
	)
	(segment
		(start 388.485126 -93.959934)
		(end 388.485126 -92.20581)
		(width 0.0889)
		(layer "F.Cu")
		(net "RMII_BMC_PCH_SPRNGVLLE_TXD0")
	)
	(segment
		(start 488.6198 -44.217336)
		(end 489.09478 -44.217336)
		(width 0.10795)
		(layer "F.Cu")
		(net "RMII_BMC_PCH_SPRNGVLLE_TXD0")
	)
	(segment
		(start 489.20019 -44.111926)
		(end 489.913676 -44.111926)
		(width 0.10795)
		(layer "F.Cu")
		(net "RMII_BMC_PCH_SPRNGVLLE_TXD0")
	)
	(segment
		(start 388.485126 -92.20581)
		(end 388.576566 -92.11437)
		(width 0.0889)
		(layer "F.Cu")
		(net "RMII_BMC_PCH_SPRNGVLLE_TXD0")
	)
	(segment
		(start 405.6126 -21.8059)
		(end 405.6126 -21.463)
		(width 0.10795)
		(layer "F.Cu")
		(net "RMII_BMC_PCH_SPRNGVLLE_TXD0")
	)
	(segment
		(start 489.913676 -44.111926)
		(end 490.38383 -44.58208)
		(width 0.10795)
		(layer "F.Cu")
		(net "RMII_BMC_PCH_SPRNGVLLE_TXD0")
	)
	(segment
		(start 490.38383 -44.58208)
		(end 490.49051 -44.58208)
		(width 0.10795)
		(layer "F.Cu")
		(net "RMII_BMC_PCH_SPRNGVLLE_TXD0")
	)
	(segment
		(start 489.09478 -44.217336)
		(end 489.20019 -44.111926)
		(width 0.10795)
		(layer "F.Cu")
		(net "RMII_BMC_PCH_SPRNGVLLE_TXD0")
	)
	(via
		(at 393.237212 -48.48352)
		(size 0.508)
		(drill 0.254)
		(layers "F.Cu" "B.Cu")
		(net "RMII_BMC_PCH_SPRNGVLLE_TXD0")
	)
	(via
		(at 490.49051 -44.58208)
		(size 0.508)
		(drill 0.254)
		(layers "F.Cu" "B.Cu")
		(net "RMII_BMC_PCH_SPRNGVLLE_TXD0")
	)
	(via
		(at 388.576566 -92.11437)
		(size 0.508)
		(drill 0.254)
		(layers "F.Cu" "B.Cu")
		(net "RMII_BMC_PCH_SPRNGVLLE_TXD0")
	)
	(via
		(at 405.6126 -21.463)
		(size 0.508)
		(drill 0.254)
		(layers "F.Cu" "B.Cu")
		(net "RMII_BMC_PCH_SPRNGVLLE_TXD0")
	)
	(segment
		(start 390.238488 -79.793846)
		(end 390.803892 -79.228442)
		(width 0.089408)
		(layer "In2.Cu")
		(net "RMII_BMC_PCH_SPRNGVLLE_TXD0")
	)
	(segment
		(start 393.599162 -50.507392)
		(end 393.1666 -50.07483)
		(width 0.089408)
		(layer "In2.Cu")
		(net "RMII_BMC_PCH_SPRNGVLLE_TXD0")
	)
	(segment
		(start 387.082284 -88.461342)
		(end 388.389368 -87.154258)
		(width 0.089408)
		(layer "In2.Cu")
		(net "RMII_BMC_PCH_SPRNGVLLE_TXD0")
	)
	(segment
		(start 390.238488 -81.628488)
		(end 390.238488 -79.793846)
		(width 0.089408)
		(layer "In2.Cu")
		(net "RMII_BMC_PCH_SPRNGVLLE_TXD0")
	)
	(segment
		(start 387.082284 -89.196672)
		(end 387.082284 -88.461342)
		(width 0.089408)
		(layer "In2.Cu")
		(net "RMII_BMC_PCH_SPRNGVLLE_TXD0")
	)
	(segment
		(start 390.803892 -79.228442)
		(end 390.803892 -78.42758)
		(width 0.089408)
		(layer "In2.Cu")
		(net "RMII_BMC_PCH_SPRNGVLLE_TXD0")
	)
	(segment
		(start 391.829036 -72.002396)
		(end 393.529312 -70.30212)
		(width 0.089408)
		(layer "In2.Cu")
		(net "RMII_BMC_PCH_SPRNGVLLE_TXD0")
	)
	(segment
		(start 390.34085 -85.6869)
		(end 390.34085 -81.73085)
		(width 0.089408)
		(layer "In2.Cu")
		(net "RMII_BMC_PCH_SPRNGVLLE_TXD0")
	)
	(segment
		(start 393.529312 -70.30212)
		(end 393.529312 -64.305688)
		(width 0.089408)
		(layer "In2.Cu")
		(net "RMII_BMC_PCH_SPRNGVLLE_TXD0")
	)
	(segment
		(start 394.8176 -63.0174)
		(end 394.8176 -51.294792)
		(width 0.089408)
		(layer "In2.Cu")
		(net "RMII_BMC_PCH_SPRNGVLLE_TXD0")
	)
	(segment
		(start 393.1666 -50.07483)
		(end 393.1666 -48.733202)
		(width 0.089408)
		(layer "In2.Cu")
		(net "RMII_BMC_PCH_SPRNGVLLE_TXD0")
	)
	(segment
		(start 388.389368 -87.154258)
		(end 388.873492 -87.154258)
		(width 0.089408)
		(layer "In2.Cu")
		(net "RMII_BMC_PCH_SPRNGVLLE_TXD0")
	)
	(segment
		(start 390.803892 -78.42758)
		(end 391.829036 -77.402436)
		(width 0.089408)
		(layer "In2.Cu")
		(net "RMII_BMC_PCH_SPRNGVLLE_TXD0")
	)
	(segment
		(start 393.237212 -48.66259)
		(end 393.237212 -48.48352)
		(width 0.089408)
		(layer "In2.Cu")
		(net "RMII_BMC_PCH_SPRNGVLLE_TXD0")
	)
	(segment
		(start 388.576566 -92.11437)
		(end 388.576566 -90.690954)
		(width 0.089408)
		(layer "In2.Cu")
		(net "RMII_BMC_PCH_SPRNGVLLE_TXD0")
	)
	(segment
		(start 388.873492 -87.154258)
		(end 390.34085 -85.6869)
		(width 0.089408)
		(layer "In2.Cu")
		(net "RMII_BMC_PCH_SPRNGVLLE_TXD0")
	)
	(segment
		(start 388.576566 -90.690954)
		(end 387.082284 -89.196672)
		(width 0.089408)
		(layer "In2.Cu")
		(net "RMII_BMC_PCH_SPRNGVLLE_TXD0")
	)
	(segment
		(start 393.1666 -48.733202)
		(end 393.237212 -48.66259)
		(width 0.089408)
		(layer "In2.Cu")
		(net "RMII_BMC_PCH_SPRNGVLLE_TXD0")
	)
	(segment
		(start 393.529312 -64.305688)
		(end 394.8176 -63.0174)
		(width 0.089408)
		(layer "In2.Cu")
		(net "RMII_BMC_PCH_SPRNGVLLE_TXD0")
	)
	(segment
		(start 391.829036 -77.402436)
		(end 391.829036 -72.002396)
		(width 0.089408)
		(layer "In2.Cu")
		(net "RMII_BMC_PCH_SPRNGVLLE_TXD0")
	)
	(segment
		(start 390.34085 -81.73085)
		(end 390.238488 -81.628488)
		(width 0.089408)
		(layer "In2.Cu")
		(net "RMII_BMC_PCH_SPRNGVLLE_TXD0")
	)
	(segment
		(start 394.8176 -51.294792)
		(end 394.0302 -50.507392)
		(width 0.089408)
		(layer "In2.Cu")
		(net "RMII_BMC_PCH_SPRNGVLLE_TXD0")
	)
	(segment
		(start 394.0302 -50.507392)
		(end 393.599162 -50.507392)
		(width 0.089408)
		(layer "In2.Cu")
		(net "RMII_BMC_PCH_SPRNGVLLE_TXD0")
	)
	(segment
		(start 408.09037 -20.306284)
		(end 407.333958 -21.062696)
		(width 0.089408)
		(layer "In4.Cu")
		(net "RMII_BMC_PCH_SPRNGVLLE_TXD0")
	)
	(segment
		(start 444.99149 -15.443454)
		(end 444.180976 -16.253968)
		(width 0.089408)
		(layer "In4.Cu")
		(net "RMII_BMC_PCH_SPRNGVLLE_TXD0")
	)
	(segment
		(start 483.208584 -38.00475)
		(end 483.44963 -37.763704)
		(width 0.089408)
		(layer "In4.Cu")
		(net "RMII_BMC_PCH_SPRNGVLLE_TXD0")
	)
	(segment
		(start 483.219506 -35.89528)
		(end 482.32949 -35.005264)
		(width 0.089408)
		(layer "In4.Cu")
		(net "RMII_BMC_PCH_SPRNGVLLE_TXD0")
	)
	(segment
		(start 490.328712 -41.90746)
		(end 486.39476 -41.90746)
		(width 0.089408)
		(layer "In4.Cu")
		(net "RMII_BMC_PCH_SPRNGVLLE_TXD0")
	)
	(segment
		(start 413.35579 -17.719294)
		(end 413.355536 -17.71904)
		(width 0.089408)
		(layer "In4.Cu")
		(net "RMII_BMC_PCH_SPRNGVLLE_TXD0")
	)
	(segment
		(start 420.303452 -16.976852)
		(end 419.56101 -17.719294)
		(width 0.089408)
		(layer "In4.Cu")
		(net "RMII_BMC_PCH_SPRNGVLLE_TXD0")
	)
	(segment
		(start 475.005908 -27.476196)
		(end 473.706952 -26.17724)
		(width 0.089408)
		(layer "In4.Cu")
		(net "RMII_BMC_PCH_SPRNGVLLE_TXD0")
	)
	(segment
		(start 407.333958 -21.062696)
		(end 406.012904 -21.062696)
		(width 0.089408)
		(layer "In4.Cu")
		(net "RMII_BMC_PCH_SPRNGVLLE_TXD0")
	)
	(segment
		(start 490.8296 -42.408348)
		(end 490.328712 -41.90746)
		(width 0.089408)
		(layer "In4.Cu")
		(net "RMII_BMC_PCH_SPRNGVLLE_TXD0")
	)
	(segment
		(start 444.180976 -16.253968)
		(end 427.53534 -16.253968)
		(width 0.089408)
		(layer "In4.Cu")
		(net "RMII_BMC_PCH_SPRNGVLLE_TXD0")
	)
	(segment
		(start 468.188294 -26.17724)
		(end 464.774534 -22.76348)
		(width 0.089408)
		(layer "In4.Cu")
		(net "RMII_BMC_PCH_SPRNGVLLE_TXD0")
	)
	(segment
		(start 480.18319 -31.804864)
		(end 480.18319 -28.22321)
		(width 0.089408)
		(layer "In4.Cu")
		(net "RMII_BMC_PCH_SPRNGVLLE_TXD0")
	)
	(segment
		(start 464.616292 -22.763734)
		(end 463.366358 -22.763734)
		(width 0.089408)
		(layer "In4.Cu")
		(net "RMII_BMC_PCH_SPRNGVLLE_TXD0")
	)
	(segment
		(start 427.535086 -16.253714)
		(end 427.377098 -16.253714)
		(width 0.089408)
		(layer "In4.Cu")
		(net "RMII_BMC_PCH_SPRNGVLLE_TXD0")
	)
	(segment
		(start 427.53534 -16.253968)
		(end 427.535086 -16.253714)
		(width 0.089408)
		(layer "In4.Cu")
		(net "RMII_BMC_PCH_SPRNGVLLE_TXD0")
	)
	(segment
		(start 412.732982 -18.183606)
		(end 411.18155 -18.183606)
		(width 0.089408)
		(layer "In4.Cu")
		(net "RMII_BMC_PCH_SPRNGVLLE_TXD0")
	)
	(segment
		(start 483.208584 -38.721284)
		(end 483.208584 -38.00475)
		(width 0.089408)
		(layer "In4.Cu")
		(net "RMII_BMC_PCH_SPRNGVLLE_TXD0")
	)
	(segment
		(start 450.806312 -17.264888)
		(end 448.984878 -15.443454)
		(width 0.089408)
		(layer "In4.Cu")
		(net "RMII_BMC_PCH_SPRNGVLLE_TXD0")
	)
	(segment
		(start 473.706952 -26.17724)
		(end 468.188294 -26.17724)
		(width 0.089408)
		(layer "In4.Cu")
		(net "RMII_BMC_PCH_SPRNGVLLE_TXD0")
	)
	(segment
		(start 411.18155 -18.183606)
		(end 409.058872 -20.306284)
		(width 0.089408)
		(layer "In4.Cu")
		(net "RMII_BMC_PCH_SPRNGVLLE_TXD0")
	)
	(segment
		(start 406.012904 -21.062696)
		(end 405.6126 -21.463)
		(width 0.089408)
		(layer "In4.Cu")
		(net "RMII_BMC_PCH_SPRNGVLLE_TXD0")
	)
	(segment
		(start 456.258422 -21.338032)
		(end 455.0918 -20.17141)
		(width 0.089408)
		(layer "In4.Cu")
		(net "RMII_BMC_PCH_SPRNGVLLE_TXD0")
	)
	(segment
		(start 482.32949 -35.005264)
		(end 482.32949 -33.951164)
		(width 0.089408)
		(layer "In4.Cu")
		(net "RMII_BMC_PCH_SPRNGVLLE_TXD0")
	)
	(segment
		(start 490.8296 -44.24299)
		(end 490.8296 -42.408348)
		(width 0.089408)
		(layer "In4.Cu")
		(net "RMII_BMC_PCH_SPRNGVLLE_TXD0")
	)
	(segment
		(start 455.0918 -20.17141)
		(end 453.013572 -20.17141)
		(width 0.089408)
		(layer "In4.Cu")
		(net "RMII_BMC_PCH_SPRNGVLLE_TXD0")
	)
	(segment
		(start 480.18319 -28.22321)
		(end 479.436176 -27.476196)
		(width 0.089408)
		(layer "In4.Cu")
		(net "RMII_BMC_PCH_SPRNGVLLE_TXD0")
	)
	(segment
		(start 413.197548 -17.71904)
		(end 412.732982 -18.183606)
		(width 0.089408)
		(layer "In4.Cu")
		(net "RMII_BMC_PCH_SPRNGVLLE_TXD0")
	)
	(segment
		(start 461.123792 -20.521168)
		(end 458.305408 -20.521168)
		(width 0.089408)
		(layer "In4.Cu")
		(net "RMII_BMC_PCH_SPRNGVLLE_TXD0")
	)
	(segment
		(start 483.44963 -36.691316)
		(end 483.219506 -36.461192)
		(width 0.089408)
		(layer "In4.Cu")
		(net "RMII_BMC_PCH_SPRNGVLLE_TXD0")
	)
	(segment
		(start 482.32949 -33.951164)
		(end 480.18319 -31.804864)
		(width 0.089408)
		(layer "In4.Cu")
		(net "RMII_BMC_PCH_SPRNGVLLE_TXD0")
	)
	(segment
		(start 483.219506 -36.461192)
		(end 483.219506 -35.89528)
		(width 0.089408)
		(layer "In4.Cu")
		(net "RMII_BMC_PCH_SPRNGVLLE_TXD0")
	)
	(segment
		(start 463.366358 -22.763734)
		(end 461.123792 -20.521168)
		(width 0.089408)
		(layer "In4.Cu")
		(net "RMII_BMC_PCH_SPRNGVLLE_TXD0")
	)
	(segment
		(start 413.355536 -17.71904)
		(end 413.197548 -17.71904)
		(width 0.089408)
		(layer "In4.Cu")
		(net "RMII_BMC_PCH_SPRNGVLLE_TXD0")
	)
	(segment
		(start 479.436176 -27.476196)
		(end 475.005908 -27.476196)
		(width 0.089408)
		(layer "In4.Cu")
		(net "RMII_BMC_PCH_SPRNGVLLE_TXD0")
	)
	(segment
		(start 464.616546 -22.76348)
		(end 464.616292 -22.763734)
		(width 0.089408)
		(layer "In4.Cu")
		(net "RMII_BMC_PCH_SPRNGVLLE_TXD0")
	)
	(segment
		(start 419.56101 -17.719294)
		(end 413.35579 -17.719294)
		(width 0.089408)
		(layer "In4.Cu")
		(net "RMII_BMC_PCH_SPRNGVLLE_TXD0")
	)
	(segment
		(start 483.44963 -37.763704)
		(end 483.44963 -36.691316)
		(width 0.089408)
		(layer "In4.Cu")
		(net "RMII_BMC_PCH_SPRNGVLLE_TXD0")
	)
	(segment
		(start 450.806312 -17.96415)
		(end 450.806312 -17.264888)
		(width 0.089408)
		(layer "In4.Cu")
		(net "RMII_BMC_PCH_SPRNGVLLE_TXD0")
	)
	(segment
		(start 426.65396 -16.976852)
		(end 420.303452 -16.976852)
		(width 0.089408)
		(layer "In4.Cu")
		(net "RMII_BMC_PCH_SPRNGVLLE_TXD0")
	)
	(segment
		(start 490.49051 -44.58208)
		(end 490.8296 -44.24299)
		(width 0.089408)
		(layer "In4.Cu")
		(net "RMII_BMC_PCH_SPRNGVLLE_TXD0")
	)
	(segment
		(start 453.013572 -20.17141)
		(end 450.806312 -17.96415)
		(width 0.089408)
		(layer "In4.Cu")
		(net "RMII_BMC_PCH_SPRNGVLLE_TXD0")
	)
	(segment
		(start 486.39476 -41.90746)
		(end 483.208584 -38.721284)
		(width 0.089408)
		(layer "In4.Cu")
		(net "RMII_BMC_PCH_SPRNGVLLE_TXD0")
	)
	(segment
		(start 427.377098 -16.253714)
		(end 426.65396 -16.976852)
		(width 0.089408)
		(layer "In4.Cu")
		(net "RMII_BMC_PCH_SPRNGVLLE_TXD0")
	)
	(segment
		(start 448.984878 -15.443454)
		(end 444.99149 -15.443454)
		(width 0.089408)
		(layer "In4.Cu")
		(net "RMII_BMC_PCH_SPRNGVLLE_TXD0")
	)
	(segment
		(start 458.305408 -20.521168)
		(end 457.488544 -21.338032)
		(width 0.089408)
		(layer "In4.Cu")
		(net "RMII_BMC_PCH_SPRNGVLLE_TXD0")
	)
	(segment
		(start 457.488544 -21.338032)
		(end 456.258422 -21.338032)
		(width 0.089408)
		(layer "In4.Cu")
		(net "RMII_BMC_PCH_SPRNGVLLE_TXD0")
	)
	(segment
		(start 464.774534 -22.76348)
		(end 464.616546 -22.76348)
		(width 0.089408)
		(layer "In4.Cu")
		(net "RMII_BMC_PCH_SPRNGVLLE_TXD0")
	)
	(segment
		(start 409.058872 -20.306284)
		(end 408.09037 -20.306284)
		(width 0.089408)
		(layer "In4.Cu")
		(net "RMII_BMC_PCH_SPRNGVLLE_TXD0")
	)
	(segment
		(start 393.070334 -34.391854)
		(end 393.070334 -35.319462)
		(width 0.089408)
		(layer "In9.Cu")
		(net "RMII_BMC_PCH_SPRNGVLLE_TXD0")
	)
	(segment
		(start 393.070334 -35.319462)
		(end 393.811252 -36.06038)
		(width 0.089408)
		(layer "In9.Cu")
		(net "RMII_BMC_PCH_SPRNGVLLE_TXD0")
	)
	(segment
		(start 394.060934 -38.192456)
		(end 394.060934 -38.65118)
		(width 0.089408)
		(layer "In9.Cu")
		(net "RMII_BMC_PCH_SPRNGVLLE_TXD0")
	)
	(segment
		(start 405.6126 -21.463)
		(end 405.113998 -20.964398)
		(width 0.089408)
		(layer "In9.Cu")
		(net "RMII_BMC_PCH_SPRNGVLLE_TXD0")
	)
	(segment
		(start 393.456922 -46.011338)
		(end 393.456922 -48.26381)
		(width 0.089408)
		(layer "In9.Cu")
		(net "RMII_BMC_PCH_SPRNGVLLE_TXD0")
	)
	(segment
		(start 393.070334 -33.071562)
		(end 392.985498 -33.156398)
		(width 0.089408)
		(layer "In9.Cu")
		(net "RMII_BMC_PCH_SPRNGVLLE_TXD0")
	)
	(segment
		(start 393.811252 -36.083494)
		(end 394.023342 -36.295584)
		(width 0.089408)
		(layer "In9.Cu")
		(net "RMII_BMC_PCH_SPRNGVLLE_TXD0")
	)
	(segment
		(start 394.023342 -36.295584)
		(end 394.023342 -38.154864)
		(width 0.089408)
		(layer "In9.Cu")
		(net "RMII_BMC_PCH_SPRNGVLLE_TXD0")
	)
	(segment
		(start 393.146026 -43.255692)
		(end 393.146026 -45.700442)
		(width 0.089408)
		(layer "In9.Cu")
		(net "RMII_BMC_PCH_SPRNGVLLE_TXD0")
	)
	(segment
		(start 394.023342 -38.154864)
		(end 394.060934 -38.192456)
		(width 0.089408)
		(layer "In9.Cu")
		(net "RMII_BMC_PCH_SPRNGVLLE_TXD0")
	)
	(segment
		(start 405.113998 -20.964398)
		(end 403.630892 -20.964398)
		(width 0.089408)
		(layer "In9.Cu")
		(net "RMII_BMC_PCH_SPRNGVLLE_TXD0")
	)
	(segment
		(start 394.060934 -38.65118)
		(end 395.051788 -39.642034)
		(width 0.089408)
		(layer "In9.Cu")
		(net "RMII_BMC_PCH_SPRNGVLLE_TXD0")
	)
	(segment
		(start 398.062704 -20.040854)
		(end 393.940538 -24.16302)
		(width 0.089408)
		(layer "In9.Cu")
		(net "RMII_BMC_PCH_SPRNGVLLE_TXD0")
	)
	(segment
		(start 393.940538 -24.16302)
		(end 393.940538 -29.678376)
		(width 0.089408)
		(layer "In9.Cu")
		(net "RMII_BMC_PCH_SPRNGVLLE_TXD0")
	)
	(segment
		(start 393.775184 -42.626534)
		(end 393.146026 -43.255692)
		(width 0.089408)
		(layer "In9.Cu")
		(net "RMII_BMC_PCH_SPRNGVLLE_TXD0")
	)
	(segment
		(start 395.052042 -41.479216)
		(end 395.052042 -42.131488)
		(width 0.089408)
		(layer "In9.Cu")
		(net "RMII_BMC_PCH_SPRNGVLLE_TXD0")
	)
	(segment
		(start 393.811252 -36.06038)
		(end 393.811252 -36.083494)
		(width 0.089408)
		(layer "In9.Cu")
		(net "RMII_BMC_PCH_SPRNGVLLE_TXD0")
	)
	(segment
		(start 395.052042 -42.131488)
		(end 394.556996 -42.626534)
		(width 0.089408)
		(layer "In9.Cu")
		(net "RMII_BMC_PCH_SPRNGVLLE_TXD0")
	)
	(segment
		(start 402.707348 -20.040854)
		(end 398.062704 -20.040854)
		(width 0.089408)
		(layer "In9.Cu")
		(net "RMII_BMC_PCH_SPRNGVLLE_TXD0")
	)
	(segment
		(start 395.051788 -39.642034)
		(end 395.051788 -41.478962)
		(width 0.089408)
		(layer "In9.Cu")
		(net "RMII_BMC_PCH_SPRNGVLLE_TXD0")
	)
	(segment
		(start 394.556996 -42.626534)
		(end 393.775184 -42.626534)
		(width 0.089408)
		(layer "In9.Cu")
		(net "RMII_BMC_PCH_SPRNGVLLE_TXD0")
	)
	(segment
		(start 403.630892 -20.964398)
		(end 402.707348 -20.040854)
		(width 0.089408)
		(layer "In9.Cu")
		(net "RMII_BMC_PCH_SPRNGVLLE_TXD0")
	)
	(segment
		(start 393.146026 -45.700442)
		(end 393.456922 -46.011338)
		(width 0.089408)
		(layer "In9.Cu")
		(net "RMII_BMC_PCH_SPRNGVLLE_TXD0")
	)
	(segment
		(start 392.985498 -34.307018)
		(end 393.070334 -34.391854)
		(width 0.089408)
		(layer "In9.Cu")
		(net "RMII_BMC_PCH_SPRNGVLLE_TXD0")
	)
	(segment
		(start 393.456922 -48.26381)
		(end 393.237212 -48.48352)
		(width 0.089408)
		(layer "In9.Cu")
		(net "RMII_BMC_PCH_SPRNGVLLE_TXD0")
	)
	(segment
		(start 393.940538 -29.678376)
		(end 393.070334 -30.54858)
		(width 0.089408)
		(layer "In9.Cu")
		(net "RMII_BMC_PCH_SPRNGVLLE_TXD0")
	)
	(segment
		(start 395.051788 -41.478962)
		(end 395.052042 -41.479216)
		(width 0.089408)
		(layer "In9.Cu")
		(net "RMII_BMC_PCH_SPRNGVLLE_TXD0")
	)
	(segment
		(start 393.070334 -30.54858)
		(end 393.070334 -33.071562)
		(width 0.089408)
		(layer "In9.Cu")
		(net "RMII_BMC_PCH_SPRNGVLLE_TXD0")
	)
	(segment
		(start 392.985498 -33.156398)
		(end 392.985498 -34.307018)
		(width 0.089408)
		(layer "In9.Cu")
		(net "RMII_BMC_PCH_SPRNGVLLE_TXD0")
	)
	(segment
		(start 390.1694 -86.6394)
		(end 390.1694 -86.106)
		(width 0.10795)
		(layer "F.Cu")
		(net "RMII_BMC_PCH_SPRNGVLLE_CRSDV")
	)
	(segment
		(start 491.9345 -40.0304)
		(end 492.887 -40.0304)
		(width 0.10795)
		(layer "F.Cu")
		(net "RMII_BMC_PCH_SPRNGVLLE_CRSDV")
	)
	(segment
		(start 408.19705 -24.638)
		(end 407.416 -23.85695)
		(width 0.10795)
		(layer "F.Cu")
		(net "RMII_BMC_PCH_SPRNGVLLE_CRSDV")
	)
	(segment
		(start 392.218926 -83.91525)
		(end 391.259568 -84.874608)
		(width 0.10795)
		(layer "F.Cu")
		(net "RMII_BMC_PCH_SPRNGVLLE_CRSDV")
	)
	(segment
		(start 393.276836 -82.676238)
		(end 393.276836 -83.176364)
		(width 0.10795)
		(layer "F.Cu")
		(net "RMII_BMC_PCH_SPRNGVLLE_CRSDV")
	)
	(segment
		(start 392.634724 -83.81619)
		(end 392.535664 -83.91525)
		(width 0.10795)
		(layer "F.Cu")
		(net "RMII_BMC_PCH_SPRNGVLLE_CRSDV")
	)
	(segment
		(start 390.871456 -84.874608)
		(end 390.1694 -85.576664)
		(width 0.10795)
		(layer "F.Cu")
		(net "RMII_BMC_PCH_SPRNGVLLE_CRSDV")
	)
	(segment
		(start 409.1305 -25.347168)
		(end 408.421332 -24.638)
		(width 0.10795)
		(layer "F.Cu")
		(net "RMII_BMC_PCH_SPRNGVLLE_CRSDV")
	)
	(segment
		(start 408.421332 -24.638)
		(end 408.19705 -24.638)
		(width 0.10795)
		(layer "F.Cu")
		(net "RMII_BMC_PCH_SPRNGVLLE_CRSDV")
	)
	(segment
		(start 389.89 -87.3125)
		(end 389.89 -86.9188)
		(width 0.10795)
		(layer "F.Cu")
		(net "RMII_BMC_PCH_SPRNGVLLE_CRSDV")
	)
	(segment
		(start 389.89 -86.9188)
		(end 390.1694 -86.6394)
		(width 0.10795)
		(layer "F.Cu")
		(net "RMII_BMC_PCH_SPRNGVLLE_CRSDV")
	)
	(segment
		(start 409.1305 -26.975054)
		(end 409.1305 -25.347168)
		(width 0.10795)
		(layer "F.Cu")
		(net "RMII_BMC_PCH_SPRNGVLLE_CRSDV")
	)
	(segment
		(start 392.63701 -83.81619)
		(end 392.634724 -83.81619)
		(width 0.10795)
		(layer "F.Cu")
		(net "RMII_BMC_PCH_SPRNGVLLE_CRSDV")
	)
	(segment
		(start 409.490164 -27.334718)
		(end 409.1305 -26.975054)
		(width 0.10795)
		(layer "F.Cu")
		(net "RMII_BMC_PCH_SPRNGVLLE_CRSDV")
	)
	(segment
		(start 391.259568 -84.874608)
		(end 390.871456 -84.874608)
		(width 0.10795)
		(layer "F.Cu")
		(net "RMII_BMC_PCH_SPRNGVLLE_CRSDV")
	)
	(segment
		(start 393.276836 -83.176364)
		(end 392.63701 -83.81619)
		(width 0.10795)
		(layer "F.Cu")
		(net "RMII_BMC_PCH_SPRNGVLLE_CRSDV")
	)
	(segment
		(start 390.1694 -85.576664)
		(end 390.1694 -86.106)
		(width 0.10795)
		(layer "F.Cu")
		(net "RMII_BMC_PCH_SPRNGVLLE_CRSDV")
	)
	(segment
		(start 392.535664 -83.91525)
		(end 392.218926 -83.91525)
		(width 0.10795)
		(layer "F.Cu")
		(net "RMII_BMC_PCH_SPRNGVLLE_CRSDV")
	)
	(via
		(at 407.416 -23.85695)
		(size 0.4572)
		(drill 0.2032)
		(layers "F.Cu" "B.Cu")
		(net "RMII_BMC_PCH_SPRNGVLLE_CRSDV")
	)
	(via
		(at 393.276836 -82.676238)
		(size 0.508)
		(drill 0.254)
		(layers "F.Cu" "B.Cu")
		(net "RMII_BMC_PCH_SPRNGVLLE_CRSDV")
	)
	(via
		(at 492.887 -40.0304)
		(size 0.508)
		(drill 0.254)
		(layers "F.Cu" "B.Cu")
		(net "RMII_BMC_PCH_SPRNGVLLE_CRSDV")
	)
	(via
		(at 404.622 -19.84756)
		(size 0.508)
		(drill 0.254)
		(layers "F.Cu" "B.Cu")
		(net "RMII_BMC_PCH_SPRNGVLLE_CRSDV")
	)
	(via
		(at 374.1674 -33.5026)
		(size 0.508)
		(drill 0.254)
		(layers "F.Cu" "B.Cu")
		(net "RMII_BMC_PCH_SPRNGVLLE_CRSDV")
	)
	(via
		(at 390.1694 -86.106)
		(size 0.762)
		(drill 0.381)
		(layers "F.Cu" "B.Cu")
		(net "RMII_BMC_PCH_SPRNGVLLE_CRSDV")
	)
	(segment
		(start 491.9345 -40.0304)
		(end 492.887 -40.0304)
		(width 0.10795)
		(layer "B.Cu")
		(net "RMII_BMC_PCH_SPRNGVLLE_CRSDV")
	)
	(segment
		(start 476.148908 -21.108416)
		(end 476.148908 -19.66468)
		(width 0.089408)
		(layer "In4.Cu")
		(net "RMII_BMC_PCH_SPRNGVLLE_CRSDV")
	)
	(segment
		(start 488.170474 -37.5666)
		(end 485.922574 -35.3187)
		(width 0.089408)
		(layer "In4.Cu")
		(net "RMII_BMC_PCH_SPRNGVLLE_CRSDV")
	)
	(segment
		(start 477.138492 -22.223984)
		(end 476.665544 -22.697186)
		(width 0.089408)
		(layer "In4.Cu")
		(net "RMII_BMC_PCH_SPRNGVLLE_CRSDV")
	)
	(segment
		(start 476.715836 -21.801328)
		(end 476.715836 -21.675344)
		(width 0.089408)
		(layer "In4.Cu")
		(net "RMII_BMC_PCH_SPRNGVLLE_CRSDV")
	)
	(segment
		(start 378.75464 -27.596338)
		(end 379.62332 -26.727658)
		(width 0.089408)
		(layer "In4.Cu")
		(net "RMII_BMC_PCH_SPRNGVLLE_CRSDV")
	)
	(segment
		(start 374.889522 -31.8516)
		(end 375.645172 -31.09595)
		(width 0.089408)
		(layer "In4.Cu")
		(net "RMII_BMC_PCH_SPRNGVLLE_CRSDV")
	)
	(segment
		(start 471.952574 -15.468346)
		(end 465.788248 -15.468346)
		(width 0.089408)
		(layer "In4.Cu")
		(net "RMII_BMC_PCH_SPRNGVLLE_CRSDV")
	)
	(segment
		(start 374.1674 -33.5026)
		(end 374.001792 -33.5026)
		(width 0.089408)
		(layer "In4.Cu")
		(net "RMII_BMC_PCH_SPRNGVLLE_CRSDV")
	)
	(segment
		(start 463.601054 -18.835624)
		(end 461.947006 -18.835624)
		(width 0.089408)
		(layer "In4.Cu")
		(net "RMII_BMC_PCH_SPRNGVLLE_CRSDV")
	)
	(segment
		(start 391.808462 -24.313896)
		(end 392.025886 -24.53132)
		(width 0.089408)
		(layer "In4.Cu")
		(net "RMII_BMC_PCH_SPRNGVLLE_CRSDV")
	)
	(segment
		(start 409.6766 -12.723876)
		(end 409.6766 -13.142722)
		(width 0.089408)
		(layer "In4.Cu")
		(net "RMII_BMC_PCH_SPRNGVLLE_CRSDV")
	)
	(segment
		(start 479.95332 -23.55342)
		(end 477.395794 -23.55342)
		(width 0.089408)
		(layer "In4.Cu")
		(net "RMII_BMC_PCH_SPRNGVLLE_CRSDV")
	)
	(segment
		(start 373.49684 -32.997648)
		(end 373.49684 -32.03956)
		(width 0.089408)
		(layer "In4.Cu")
		(net "RMII_BMC_PCH_SPRNGVLLE_CRSDV")
	)
	(segment
		(start 491.350046 -39.357554)
		(end 489.559092 -37.5666)
		(width 0.089408)
		(layer "In4.Cu")
		(net "RMII_BMC_PCH_SPRNGVLLE_CRSDV")
	)
	(segment
		(start 405.379174 -18.60296)
		(end 404.875238 -19.106896)
		(width 0.089408)
		(layer "In4.Cu")
		(net "RMII_BMC_PCH_SPRNGVLLE_CRSDV")
	)
	(segment
		(start 411.568392 -15.025116)
		(end 407.376884 -15.025116)
		(width 0.089408)
		(layer "In4.Cu")
		(net "RMII_BMC_PCH_SPRNGVLLE_CRSDV")
	)
	(segment
		(start 374.001792 -33.5026)
		(end 373.49684 -32.997648)
		(width 0.089408)
		(layer "In4.Cu")
		(net "RMII_BMC_PCH_SPRNGVLLE_CRSDV")
	)
	(segment
		(start 420.202868 -12.634468)
		(end 409.766008 -12.634468)
		(width 0.089408)
		(layer "In4.Cu")
		(net "RMII_BMC_PCH_SPRNGVLLE_CRSDV")
	)
	(segment
		(start 477.561148 -22.520656)
		(end 477.264476 -22.223984)
		(width 0.089408)
		(layer "In4.Cu")
		(net "RMII_BMC_PCH_SPRNGVLLE_CRSDV")
	)
	(segment
		(start 461.947006 -18.835624)
		(end 461.607154 -18.495772)
		(width 0.089408)
		(layer "In4.Cu")
		(net "RMII_BMC_PCH_SPRNGVLLE_CRSDV")
	)
	(segment
		(start 408.572208 -13.829792)
		(end 408.4828 -13.9192)
		(width 0.089408)
		(layer "In4.Cu")
		(net "RMII_BMC_PCH_SPRNGVLLE_CRSDV")
	)
	(segment
		(start 419.8366 -13.740384)
		(end 419.747192 -13.829792)
		(width 0.089408)
		(layer "In4.Cu")
		(net "RMII_BMC_PCH_SPRNGVLLE_CRSDV")
	)
	(segment
		(start 405.451818 -25.564592)
		(end 407.15946 -23.85695)
		(width 0.089408)
		(layer "In4.Cu")
		(net "RMII_BMC_PCH_SPRNGVLLE_CRSDV")
	)
	(segment
		(start 479.988372 -23.588472)
		(end 479.95332 -23.55342)
		(width 0.089408)
		(layer "In4.Cu")
		(net "RMII_BMC_PCH_SPRNGVLLE_CRSDV")
	)
	(segment
		(start 448.79768 -12.996672)
		(end 439.986674 -12.996672)
		(width 0.089408)
		(layer "In4.Cu")
		(net "RMII_BMC_PCH_SPRNGVLLE_CRSDV")
	)
	(segment
		(start 411.6578 -14.516862)
		(end 411.6578 -14.935708)
		(width 0.089408)
		(layer "In4.Cu")
		(net "RMII_BMC_PCH_SPRNGVLLE_CRSDV")
	)
	(segment
		(start 400.810476 -23.815802)
		(end 401.636738 -24.642064)
		(width 0.089408)
		(layer "In4.Cu")
		(net "RMII_BMC_PCH_SPRNGVLLE_CRSDV")
	)
	(segment
		(start 481.4443 -31.7246)
		(end 481.4443 -24.995378)
		(width 0.089408)
		(layer "In4.Cu")
		(net "RMII_BMC_PCH_SPRNGVLLE_CRSDV")
	)
	(segment
		(start 419.747192 -13.829792)
		(end 408.572208 -13.829792)
		(width 0.089408)
		(layer "In4.Cu")
		(net "RMII_BMC_PCH_SPRNGVLLE_CRSDV")
	)
	(segment
		(start 407.376884 -15.025116)
		(end 405.9428 -16.4592)
		(width 0.089408)
		(layer "In4.Cu")
		(net "RMII_BMC_PCH_SPRNGVLLE_CRSDV")
	)
	(segment
		(start 398.974818 -23.815802)
		(end 400.810476 -23.815802)
		(width 0.089408)
		(layer "In4.Cu")
		(net "RMII_BMC_PCH_SPRNGVLLE_CRSDV")
	)
	(segment
		(start 409.766008 -12.634468)
		(end 409.6766 -12.723876)
		(width 0.089408)
		(layer "In4.Cu")
		(net "RMII_BMC_PCH_SPRNGVLLE_CRSDV")
	)
	(segment
		(start 401.636738 -24.642064)
		(end 403.323044 -24.642064)
		(width 0.089408)
		(layer "In4.Cu")
		(net "RMII_BMC_PCH_SPRNGVLLE_CRSDV")
	)
	(segment
		(start 398.58696 -24.20366)
		(end 398.974818 -23.815802)
		(width 0.089408)
		(layer "In4.Cu")
		(net "RMII_BMC_PCH_SPRNGVLLE_CRSDV")
	)
	(segment
		(start 485.922574 -35.3187)
		(end 485.3432 -35.3187)
		(width 0.089408)
		(layer "In4.Cu")
		(net "RMII_BMC_PCH_SPRNGVLLE_CRSDV")
	)
	(segment
		(start 491.8583 -40.0304)
		(end 491.350046 -39.522146)
		(width 0.089408)
		(layer "In4.Cu")
		(net "RMII_BMC_PCH_SPRNGVLLE_CRSDV")
	)
	(segment
		(start 405.7904 -18.60296)
		(end 405.379174 -18.60296)
		(width 0.089408)
		(layer "In4.Cu")
		(net "RMII_BMC_PCH_SPRNGVLLE_CRSDV")
	)
	(segment
		(start 395.8336 -24.20366)
		(end 398.58696 -24.20366)
		(width 0.089408)
		(layer "In4.Cu")
		(net "RMII_BMC_PCH_SPRNGVLLE_CRSDV")
	)
	(segment
		(start 411.6578 -14.935708)
		(end 411.568392 -15.025116)
		(width 0.089408)
		(layer "In4.Cu")
		(net "RMII_BMC_PCH_SPRNGVLLE_CRSDV")
	)
	(segment
		(start 409.6766 -13.142722)
		(end 409.766008 -13.23213)
		(width 0.089408)
		(layer "In4.Cu")
		(net "RMII_BMC_PCH_SPRNGVLLE_CRSDV")
	)
	(segment
		(start 476.242888 -22.400514)
		(end 476.242888 -22.27453)
		(width 0.089408)
		(layer "In4.Cu")
		(net "RMII_BMC_PCH_SPRNGVLLE_CRSDV")
	)
	(segment
		(start 408.4828 -14.338046)
		(end 408.572208 -14.427454)
		(width 0.089408)
		(layer "In4.Cu")
		(net "RMII_BMC_PCH_SPRNGVLLE_CRSDV")
	)
	(segment
		(start 476.242888 -22.27453)
		(end 476.715836 -21.801328)
		(width 0.089408)
		(layer "In4.Cu")
		(net "RMII_BMC_PCH_SPRNGVLLE_CRSDV")
	)
	(segment
		(start 461.607154 -18.495772)
		(end 454.104248 -18.495772)
		(width 0.089408)
		(layer "In4.Cu")
		(net "RMII_BMC_PCH_SPRNGVLLE_CRSDV")
	)
	(segment
		(start 404.875238 -19.106896)
		(end 404.875238 -19.594322)
		(width 0.089408)
		(layer "In4.Cu")
		(net "RMII_BMC_PCH_SPRNGVLLE_CRSDV")
	)
	(segment
		(start 483.350316 -34.626804)
		(end 483.343712 -34.6202)
		(width 0.089408)
		(layer "In4.Cu")
		(net "RMII_BMC_PCH_SPRNGVLLE_CRSDV")
	)
	(segment
		(start 404.875238 -19.594322)
		(end 404.622 -19.84756)
		(width 0.089408)
		(layer "In4.Cu")
		(net "RMII_BMC_PCH_SPRNGVLLE_CRSDV")
	)
	(segment
		(start 465.788248 -15.468346)
		(end 463.960464 -17.29613)
		(width 0.089408)
		(layer "In4.Cu")
		(net "RMII_BMC_PCH_SPRNGVLLE_CRSDV")
	)
	(segment
		(start 419.747192 -13.23213)
		(end 419.8366 -13.321538)
		(width 0.089408)
		(layer "In4.Cu")
		(net "RMII_BMC_PCH_SPRNGVLLE_CRSDV")
	)
	(segment
		(start 395.50594 -24.53132)
		(end 395.8336 -24.20366)
		(width 0.089408)
		(layer "In4.Cu")
		(net "RMII_BMC_PCH_SPRNGVLLE_CRSDV")
	)
	(segment
		(start 477.395794 -23.55342)
		(end 477.0882 -23.245826)
		(width 0.089408)
		(layer "In4.Cu")
		(net "RMII_BMC_PCH_SPRNGVLLE_CRSDV")
	)
	(segment
		(start 422.75252 -15.18412)
		(end 420.202868 -12.634468)
		(width 0.089408)
		(layer "In4.Cu")
		(net "RMII_BMC_PCH_SPRNGVLLE_CRSDV")
	)
	(segment
		(start 476.53956 -22.697186)
		(end 476.242888 -22.400514)
		(width 0.089408)
		(layer "In4.Cu")
		(net "RMII_BMC_PCH_SPRNGVLLE_CRSDV")
	)
	(segment
		(start 408.572208 -14.427454)
		(end 411.568392 -14.427454)
		(width 0.089408)
		(layer "In4.Cu")
		(net "RMII_BMC_PCH_SPRNGVLLE_CRSDV")
	)
	(segment
		(start 404.245572 -25.564592)
		(end 405.451818 -25.564592)
		(width 0.089408)
		(layer "In4.Cu")
		(net "RMII_BMC_PCH_SPRNGVLLE_CRSDV")
	)
	(segment
		(start 454.104248 -18.495772)
		(end 452.3486 -16.740124)
		(width 0.089408)
		(layer "In4.Cu")
		(net "RMII_BMC_PCH_SPRNGVLLE_CRSDV")
	)
	(segment
		(start 375.645172 -29.25699)
		(end 377.305824 -27.596338)
		(width 0.089408)
		(layer "In4.Cu")
		(net "RMII_BMC_PCH_SPRNGVLLE_CRSDV")
	)
	(segment
		(start 409.766008 -13.23213)
		(end 419.747192 -13.23213)
		(width 0.089408)
		(layer "In4.Cu")
		(net "RMII_BMC_PCH_SPRNGVLLE_CRSDV")
	)
	(segment
		(start 405.9428 -18.45056)
		(end 405.7904 -18.60296)
		(width 0.089408)
		(layer "In4.Cu")
		(net "RMII_BMC_PCH_SPRNGVLLE_CRSDV")
	)
	(segment
		(start 483.343712 -34.6202)
		(end 483.320344 -34.6202)
		(width 0.089408)
		(layer "In4.Cu")
		(net "RMII_BMC_PCH_SPRNGVLLE_CRSDV")
	)
	(segment
		(start 392.025886 -24.53132)
		(end 395.50594 -24.53132)
		(width 0.089408)
		(layer "In4.Cu")
		(net "RMII_BMC_PCH_SPRNGVLLE_CRSDV")
	)
	(segment
		(start 484.651304 -34.626804)
		(end 483.350316 -34.626804)
		(width 0.089408)
		(layer "In4.Cu")
		(net "RMII_BMC_PCH_SPRNGVLLE_CRSDV")
	)
	(segment
		(start 483.17023 -33.45053)
		(end 481.4443 -31.7246)
		(width 0.089408)
		(layer "In4.Cu")
		(net "RMII_BMC_PCH_SPRNGVLLE_CRSDV")
	)
	(segment
		(start 483.320344 -34.6202)
		(end 483.17023 -34.470086)
		(width 0.089408)
		(layer "In4.Cu")
		(net "RMII_BMC_PCH_SPRNGVLLE_CRSDV")
	)
	(segment
		(start 375.645172 -31.09595)
		(end 375.645172 -29.25699)
		(width 0.089408)
		(layer "In4.Cu")
		(net "RMII_BMC_PCH_SPRNGVLLE_CRSDV")
	)
	(segment
		(start 419.8366 -13.321538)
		(end 419.8366 -13.740384)
		(width 0.089408)
		(layer "In4.Cu")
		(net "RMII_BMC_PCH_SPRNGVLLE_CRSDV")
	)
	(segment
		(start 476.715836 -21.675344)
		(end 476.148908 -21.108416)
		(width 0.089408)
		(layer "In4.Cu")
		(net "RMII_BMC_PCH_SPRNGVLLE_CRSDV")
	)
	(segment
		(start 476.665544 -22.697186)
		(end 476.53956 -22.697186)
		(width 0.089408)
		(layer "In4.Cu")
		(net "RMII_BMC_PCH_SPRNGVLLE_CRSDV")
	)
	(segment
		(start 492.887 -40.0304)
		(end 491.8583 -40.0304)
		(width 0.089408)
		(layer "In4.Cu")
		(net "RMII_BMC_PCH_SPRNGVLLE_CRSDV")
	)
	(segment
		(start 403.323044 -24.642064)
		(end 404.245572 -25.564592)
		(width 0.089408)
		(layer "In4.Cu")
		(net "RMII_BMC_PCH_SPRNGVLLE_CRSDV")
	)
	(segment
		(start 408.4828 -13.9192)
		(end 408.4828 -14.338046)
		(width 0.089408)
		(layer "In4.Cu")
		(net "RMII_BMC_PCH_SPRNGVLLE_CRSDV")
	)
	(segment
		(start 389.390382 -24.313896)
		(end 391.808462 -24.313896)
		(width 0.089408)
		(layer "In4.Cu")
		(net "RMII_BMC_PCH_SPRNGVLLE_CRSDV")
	)
	(segment
		(start 477.561148 -22.64664)
		(end 477.561148 -22.520656)
		(width 0.089408)
		(layer "In4.Cu")
		(net "RMII_BMC_PCH_SPRNGVLLE_CRSDV")
	)
	(segment
		(start 386.260086 -22.915372)
		(end 387.991858 -22.915372)
		(width 0.089408)
		(layer "In4.Cu")
		(net "RMII_BMC_PCH_SPRNGVLLE_CRSDV")
	)
	(segment
		(start 491.350046 -39.522146)
		(end 491.350046 -39.357554)
		(width 0.089408)
		(layer "In4.Cu")
		(net "RMII_BMC_PCH_SPRNGVLLE_CRSDV")
	)
	(segment
		(start 379.62332 -26.727658)
		(end 379.62332 -25.268682)
		(width 0.089408)
		(layer "In4.Cu")
		(net "RMII_BMC_PCH_SPRNGVLLE_CRSDV")
	)
	(segment
		(start 463.960464 -18.476214)
		(end 463.601054 -18.835624)
		(width 0.089408)
		(layer "In4.Cu")
		(net "RMII_BMC_PCH_SPRNGVLLE_CRSDV")
	)
	(segment
		(start 477.0882 -23.119842)
		(end 477.561148 -22.64664)
		(width 0.089408)
		(layer "In4.Cu")
		(net "RMII_BMC_PCH_SPRNGVLLE_CRSDV")
	)
	(segment
		(start 383.882392 -21.00961)
		(end 384.876802 -21.00961)
		(width 0.089408)
		(layer "In4.Cu")
		(net "RMII_BMC_PCH_SPRNGVLLE_CRSDV")
	)
	(segment
		(start 481.4443 -24.995378)
		(end 480.037394 -23.588472)
		(width 0.089408)
		(layer "In4.Cu")
		(net "RMII_BMC_PCH_SPRNGVLLE_CRSDV")
	)
	(segment
		(start 385.267454 -21.92274)
		(end 386.260086 -22.915372)
		(width 0.089408)
		(layer "In4.Cu")
		(net "RMII_BMC_PCH_SPRNGVLLE_CRSDV")
	)
	(segment
		(start 385.267454 -21.400262)
		(end 385.267454 -21.92274)
		(width 0.089408)
		(layer "In4.Cu")
		(net "RMII_BMC_PCH_SPRNGVLLE_CRSDV")
	)
	(segment
		(start 387.991858 -22.915372)
		(end 389.390382 -24.313896)
		(width 0.089408)
		(layer "In4.Cu")
		(net "RMII_BMC_PCH_SPRNGVLLE_CRSDV")
	)
	(segment
		(start 485.3432 -35.3187)
		(end 484.651304 -34.626804)
		(width 0.089408)
		(layer "In4.Cu")
		(net "RMII_BMC_PCH_SPRNGVLLE_CRSDV")
	)
	(segment
		(start 477.0882 -23.245826)
		(end 477.0882 -23.119842)
		(width 0.089408)
		(layer "In4.Cu")
		(net "RMII_BMC_PCH_SPRNGVLLE_CRSDV")
	)
	(segment
		(start 373.49684 -32.03956)
		(end 373.6848 -31.8516)
		(width 0.089408)
		(layer "In4.Cu")
		(net "RMII_BMC_PCH_SPRNGVLLE_CRSDV")
	)
	(segment
		(start 411.568392 -14.427454)
		(end 411.6578 -14.516862)
		(width 0.089408)
		(layer "In4.Cu")
		(net "RMII_BMC_PCH_SPRNGVLLE_CRSDV")
	)
	(segment
		(start 373.6848 -31.8516)
		(end 374.889522 -31.8516)
		(width 0.089408)
		(layer "In4.Cu")
		(net "RMII_BMC_PCH_SPRNGVLLE_CRSDV")
	)
	(segment
		(start 476.148908 -19.66468)
		(end 471.952574 -15.468346)
		(width 0.089408)
		(layer "In4.Cu")
		(net "RMII_BMC_PCH_SPRNGVLLE_CRSDV")
	)
	(segment
		(start 463.960464 -17.29613)
		(end 463.960464 -18.476214)
		(width 0.089408)
		(layer "In4.Cu")
		(net "RMII_BMC_PCH_SPRNGVLLE_CRSDV")
	)
	(segment
		(start 483.17023 -34.470086)
		(end 483.17023 -33.45053)
		(width 0.089408)
		(layer "In4.Cu")
		(net "RMII_BMC_PCH_SPRNGVLLE_CRSDV")
	)
	(segment
		(start 377.305824 -27.596338)
		(end 378.75464 -27.596338)
		(width 0.089408)
		(layer "In4.Cu")
		(net "RMII_BMC_PCH_SPRNGVLLE_CRSDV")
	)
	(segment
		(start 452.3486 -16.547592)
		(end 448.79768 -12.996672)
		(width 0.089408)
		(layer "In4.Cu")
		(net "RMII_BMC_PCH_SPRNGVLLE_CRSDV")
	)
	(segment
		(start 379.62332 -25.268682)
		(end 383.882392 -21.00961)
		(width 0.089408)
		(layer "In4.Cu")
		(net "RMII_BMC_PCH_SPRNGVLLE_CRSDV")
	)
	(segment
		(start 489.559092 -37.5666)
		(end 488.170474 -37.5666)
		(width 0.089408)
		(layer "In4.Cu")
		(net "RMII_BMC_PCH_SPRNGVLLE_CRSDV")
	)
	(segment
		(start 477.264476 -22.223984)
		(end 477.138492 -22.223984)
		(width 0.089408)
		(layer "In4.Cu")
		(net "RMII_BMC_PCH_SPRNGVLLE_CRSDV")
	)
	(segment
		(start 480.037394 -23.588472)
		(end 479.988372 -23.588472)
		(width 0.089408)
		(layer "In4.Cu")
		(net "RMII_BMC_PCH_SPRNGVLLE_CRSDV")
	)
	(segment
		(start 384.876802 -21.00961)
		(end 385.267454 -21.400262)
		(width 0.089408)
		(layer "In4.Cu")
		(net "RMII_BMC_PCH_SPRNGVLLE_CRSDV")
	)
	(segment
		(start 405.9428 -16.4592)
		(end 405.9428 -18.45056)
		(width 0.089408)
		(layer "In4.Cu")
		(net "RMII_BMC_PCH_SPRNGVLLE_CRSDV")
	)
	(segment
		(start 452.3486 -16.740124)
		(end 452.3486 -16.547592)
		(width 0.089408)
		(layer "In4.Cu")
		(net "RMII_BMC_PCH_SPRNGVLLE_CRSDV")
	)
	(segment
		(start 407.15946 -23.85695)
		(end 407.416 -23.85695)
		(width 0.089408)
		(layer "In4.Cu")
		(net "RMII_BMC_PCH_SPRNGVLLE_CRSDV")
	)
	(segment
		(start 439.986674 -12.996672)
		(end 437.799226 -15.18412)
		(width 0.089408)
		(layer "In4.Cu")
		(net "RMII_BMC_PCH_SPRNGVLLE_CRSDV")
	)
	(segment
		(start 437.799226 -15.18412)
		(end 422.75252 -15.18412)
		(width 0.089408)
		(layer "In4.Cu")
		(net "RMII_BMC_PCH_SPRNGVLLE_CRSDV")
	)
	(segment
		(start 376.795792 -45.082714)
		(end 377.317 -45.603922)
		(width 0.089408)
		(layer "In11.Cu")
		(net "RMII_BMC_PCH_SPRNGVLLE_CRSDV")
	)
	(segment
		(start 376.795792 -44.023788)
		(end 376.795538 -44.024042)
		(width 0.089408)
		(layer "In11.Cu")
		(net "RMII_BMC_PCH_SPRNGVLLE_CRSDV")
	)
	(segment
		(start 376.795792 -44.266612)
		(end 376.795792 -45.082714)
		(width 0.089408)
		(layer "In11.Cu")
		(net "RMII_BMC_PCH_SPRNGVLLE_CRSDV")
	)
	(segment
		(start 405.2062 -22.403054)
		(end 406.660096 -23.85695)
		(width 0.089408)
		(layer "In11.Cu")
		(net "RMII_BMC_PCH_SPRNGVLLE_CRSDV")
	)
	(segment
		(start 390.594088 -62.573916)
		(end 394.429742 -66.40957)
		(width 0.089408)
		(layer "In11.Cu")
		(net "RMII_BMC_PCH_SPRNGVLLE_CRSDV")
	)
	(segment
		(start 390.097518 -60.58154)
		(end 390.594088 -61.07811)
		(width 0.089408)
		(layer "In11.Cu")
		(net "RMII_BMC_PCH_SPRNGVLLE_CRSDV")
	)
	(segment
		(start 393.123166 -73.609708)
		(end 393.123166 -78.81239)
		(width 0.089408)
		(layer "In11.Cu")
		(net "RMII_BMC_PCH_SPRNGVLLE_CRSDV")
	)
	(segment
		(start 374.017032 -33.652968)
		(end 374.017032 -34.142426)
		(width 0.089408)
		(layer "In11.Cu")
		(net "RMII_BMC_PCH_SPRNGVLLE_CRSDV")
	)
	(segment
		(start 381.545592 -48.204628)
		(end 382.921764 -49.5808)
		(width 0.089408)
		(layer "In11.Cu")
		(net "RMII_BMC_PCH_SPRNGVLLE_CRSDV")
	)
	(segment
		(start 394.465556 -80.15478)
		(end 394.465556 -81.809844)
		(width 0.089408)
		(layer "In11.Cu")
		(net "RMII_BMC_PCH_SPRNGVLLE_CRSDV")
	)
	(segment
		(start 393.6619 -70.97014)
		(end 393.6619 -73.070974)
		(width 0.089408)
		(layer "In11.Cu")
		(net "RMII_BMC_PCH_SPRNGVLLE_CRSDV")
	)
	(segment
		(start 393.123166 -78.81239)
		(end 394.465556 -80.15478)
		(width 0.089408)
		(layer "In11.Cu")
		(net "RMII_BMC_PCH_SPRNGVLLE_CRSDV")
	)
	(segment
		(start 394.465556 -81.809844)
		(end 393.599162 -82.676238)
		(width 0.089408)
		(layer "In11.Cu")
		(net "RMII_BMC_PCH_SPRNGVLLE_CRSDV")
	)
	(segment
		(start 374.1674 -33.5026)
		(end 374.017032 -33.652968)
		(width 0.089408)
		(layer "In11.Cu")
		(net "RMII_BMC_PCH_SPRNGVLLE_CRSDV")
	)
	(segment
		(start 394.429742 -70.202298)
		(end 393.6619 -70.97014)
		(width 0.089408)
		(layer "In11.Cu")
		(net "RMII_BMC_PCH_SPRNGVLLE_CRSDV")
	)
	(segment
		(start 376.273822 -42.629836)
		(end 376.795792 -43.151806)
		(width 0.089408)
		(layer "In11.Cu")
		(net "RMII_BMC_PCH_SPRNGVLLE_CRSDV")
	)
	(segment
		(start 390.097518 -56.407304)
		(end 390.097518 -60.58154)
		(width 0.089408)
		(layer "In11.Cu")
		(net "RMII_BMC_PCH_SPRNGVLLE_CRSDV")
	)
	(segment
		(start 406.660096 -23.85695)
		(end 407.416 -23.85695)
		(width 0.089408)
		(layer "In11.Cu")
		(net "RMII_BMC_PCH_SPRNGVLLE_CRSDV")
	)
	(segment
		(start 385.053332 -49.5808)
		(end 386.551424 -51.078892)
		(width 0.089408)
		(layer "In11.Cu")
		(net "RMII_BMC_PCH_SPRNGVLLE_CRSDV")
	)
	(segment
		(start 390.594088 -61.07811)
		(end 390.594088 -62.573916)
		(width 0.089408)
		(layer "In11.Cu")
		(net "RMII_BMC_PCH_SPRNGVLLE_CRSDV")
	)
	(segment
		(start 376.795792 -43.151806)
		(end 376.795792 -44.023788)
		(width 0.089408)
		(layer "In11.Cu")
		(net "RMII_BMC_PCH_SPRNGVLLE_CRSDV")
	)
	(segment
		(start 379.319282 -48.204628)
		(end 381.545592 -48.204628)
		(width 0.089408)
		(layer "In11.Cu")
		(net "RMII_BMC_PCH_SPRNGVLLE_CRSDV")
	)
	(segment
		(start 377.317 -46.202346)
		(end 379.319282 -48.204628)
		(width 0.089408)
		(layer "In11.Cu")
		(net "RMII_BMC_PCH_SPRNGVLLE_CRSDV")
	)
	(segment
		(start 386.551424 -52.86121)
		(end 390.097518 -56.407304)
		(width 0.089408)
		(layer "In11.Cu")
		(net "RMII_BMC_PCH_SPRNGVLLE_CRSDV")
	)
	(segment
		(start 393.599162 -82.676238)
		(end 393.276836 -82.676238)
		(width 0.089408)
		(layer "In11.Cu")
		(net "RMII_BMC_PCH_SPRNGVLLE_CRSDV")
	)
	(segment
		(start 405.2062 -20.579842)
		(end 405.2062 -22.403054)
		(width 0.089408)
		(layer "In11.Cu")
		(net "RMII_BMC_PCH_SPRNGVLLE_CRSDV")
	)
	(segment
		(start 376.795538 -44.024042)
		(end 376.795538 -44.266358)
		(width 0.089408)
		(layer "In11.Cu")
		(net "RMII_BMC_PCH_SPRNGVLLE_CRSDV")
	)
	(segment
		(start 404.622 -19.995642)
		(end 405.2062 -20.579842)
		(width 0.089408)
		(layer "In11.Cu")
		(net "RMII_BMC_PCH_SPRNGVLLE_CRSDV")
	)
	(segment
		(start 394.429742 -66.40957)
		(end 394.429742 -70.202298)
		(width 0.089408)
		(layer "In11.Cu")
		(net "RMII_BMC_PCH_SPRNGVLLE_CRSDV")
	)
	(segment
		(start 374.017032 -34.142426)
		(end 376.273822 -36.399216)
		(width 0.089408)
		(layer "In11.Cu")
		(net "RMII_BMC_PCH_SPRNGVLLE_CRSDV")
	)
	(segment
		(start 404.622 -19.84756)
		(end 404.622 -19.995642)
		(width 0.089408)
		(layer "In11.Cu")
		(net "RMII_BMC_PCH_SPRNGVLLE_CRSDV")
	)
	(segment
		(start 393.6619 -73.070974)
		(end 393.123166 -73.609708)
		(width 0.089408)
		(layer "In11.Cu")
		(net "RMII_BMC_PCH_SPRNGVLLE_CRSDV")
	)
	(segment
		(start 382.921764 -49.5808)
		(end 385.053332 -49.5808)
		(width 0.089408)
		(layer "In11.Cu")
		(net "RMII_BMC_PCH_SPRNGVLLE_CRSDV")
	)
	(segment
		(start 377.317 -45.603922)
		(end 377.317 -46.202346)
		(width 0.089408)
		(layer "In11.Cu")
		(net "RMII_BMC_PCH_SPRNGVLLE_CRSDV")
	)
	(segment
		(start 386.551424 -51.078892)
		(end 386.551424 -52.86121)
		(width 0.089408)
		(layer "In11.Cu")
		(net "RMII_BMC_PCH_SPRNGVLLE_CRSDV")
	)
	(segment
		(start 376.273822 -36.399216)
		(end 376.273822 -42.629836)
		(width 0.089408)
		(layer "In11.Cu")
		(net "RMII_BMC_PCH_SPRNGVLLE_CRSDV")
	)
	(segment
		(start 376.795538 -44.266358)
		(end 376.795792 -44.266612)
		(width 0.089408)
		(layer "In11.Cu")
		(net "RMII_BMC_PCH_SPRNGVLLE_CRSDV")
	)
	(segment
		(start 387.73735 -98.69424)
		(end 388.23265 -98.464116)
		(width 0.10795)
		(layer "F.Cu")
		(net "FM_MP_PS_REDUNDANT_LOST_N")
	)
	(segment
		(start 419.090094 -40.93464)
		(end 419.490144 -41.33469)
		(width 0.10795)
		(layer "F.Cu")
		(net "FM_MP_PS_REDUNDANT_LOST_N")
	)
	(via
		(at 419.490144 -41.33469)
		(size 0.4572)
		(drill 0.2032)
		(layers "F.Cu" "B.Cu")
		(net "FM_MP_PS_REDUNDANT_LOST_N")
	)
	(via
		(at 388.23265 -98.464116)
		(size 0.508)
		(drill 0.254)
		(layers "F.Cu" "B.Cu")
		(net "FM_MP_PS_REDUNDANT_LOST_N")
	)
	(via
		(at 378.825252 -56.168798)
		(size 0.508)
		(drill 0.254)
		(layers "F.Cu" "B.Cu")
		(net "FM_MP_PS_REDUNDANT_LOST_N")
	)
	(via
		(at 177.41138 -4.995926)
		(size 0.508)
		(drill 0.254)
		(layers "F.Cu" "B.Cu")
		(net "FM_MP_PS_REDUNDANT_LOST_N")
	)
	(via
		(at 330.509626 -22.641814)
		(size 0.508)
		(drill 0.254)
		(layers "F.Cu" "B.Cu")
		(net "FM_MP_PS_REDUNDANT_LOST_N")
	)
	(via
		(at 405.203914 -42.271442)
		(size 0.508)
		(drill 0.254)
		(layers "F.Cu" "B.Cu")
		(net "FM_MP_PS_REDUNDANT_LOST_N")
	)
	(via
		(at 380.0221 -37.62121)
		(size 0.508)
		(drill 0.254)
		(layers "F.Cu" "B.Cu")
		(net "FM_MP_PS_REDUNDANT_LOST_N")
	)
	(via
		(at 387.0198 -93.0148)
		(size 0.6604)
		(drill 0.3302)
		(layers "F.Cu" "B.Cu")
		(net "FM_MP_PS_REDUNDANT_LOST_N")
	)
	(segment
		(start 387.731 -96.52)
		(end 387.223 -96.012)
		(width 0.10795)
		(layer "B.Cu")
		(net "FM_MP_PS_REDUNDANT_LOST_N")
	)
	(segment
		(start 387.223 -95.3262)
		(end 387.0198 -95.123)
		(width 0.10795)
		(layer "B.Cu")
		(net "FM_MP_PS_REDUNDANT_LOST_N")
	)
	(segment
		(start 387.068314 -88.737186)
		(end 387.068314 -89.529158)
		(width 0.10795)
		(layer "B.Cu")
		(net "FM_MP_PS_REDUNDANT_LOST_N")
	)
	(segment
		(start 386.820918 -91.41841)
		(end 387.1722 -91.769692)
		(width 0.10795)
		(layer "B.Cu")
		(net "FM_MP_PS_REDUNDANT_LOST_N")
	)
	(segment
		(start 387.223 -96.012)
		(end 387.223 -95.3262)
		(width 0.10795)
		(layer "B.Cu")
		(net "FM_MP_PS_REDUNDANT_LOST_N")
	)
	(segment
		(start 387.0198 -95.123)
		(end 387.0198 -93.0148)
		(width 0.10795)
		(layer "B.Cu")
		(net "FM_MP_PS_REDUNDANT_LOST_N")
	)
	(segment
		(start 387.604 -88.2015)
		(end 387.068314 -88.737186)
		(width 0.10795)
		(layer "B.Cu")
		(net "FM_MP_PS_REDUNDANT_LOST_N")
	)
	(segment
		(start 388.23265 -98.464116)
		(end 388.23265 -97.510854)
		(width 0.10795)
		(layer "B.Cu")
		(net "FM_MP_PS_REDUNDANT_LOST_N")
	)
	(segment
		(start 387.731 -97.009204)
		(end 387.731 -96.52)
		(width 0.10795)
		(layer "B.Cu")
		(net "FM_MP_PS_REDUNDANT_LOST_N")
	)
	(segment
		(start 388.23265 -97.510854)
		(end 387.731 -97.009204)
		(width 0.10795)
		(layer "B.Cu")
		(net "FM_MP_PS_REDUNDANT_LOST_N")
	)
	(segment
		(start 387.1722 -91.769692)
		(end 387.1722 -92.237814)
		(width 0.10795)
		(layer "B.Cu")
		(net "FM_MP_PS_REDUNDANT_LOST_N")
	)
	(segment
		(start 387.068314 -89.529158)
		(end 386.820918 -89.776554)
		(width 0.10795)
		(layer "B.Cu")
		(net "FM_MP_PS_REDUNDANT_LOST_N")
	)
	(segment
		(start 387.1722 -92.237814)
		(end 387.0198 -92.390214)
		(width 0.10795)
		(layer "B.Cu")
		(net "FM_MP_PS_REDUNDANT_LOST_N")
	)
	(segment
		(start 386.820918 -89.776554)
		(end 386.820918 -91.41841)
		(width 0.10795)
		(layer "B.Cu")
		(net "FM_MP_PS_REDUNDANT_LOST_N")
	)
	(segment
		(start 387.0198 -92.390214)
		(end 387.0198 -93.0148)
		(width 0.10795)
		(layer "B.Cu")
		(net "FM_MP_PS_REDUNDANT_LOST_N")
	)
	(segment
		(start 322.281804 3.60172)
		(end 323.59346 4.913376)
		(width 0.089408)
		(layer "In2.Cu")
		(net "FM_MP_PS_REDUNDANT_LOST_N")
	)
	(segment
		(start 329.181968 3.8862)
		(end 329.5904 3.477768)
		(width 0.089408)
		(layer "In2.Cu")
		(net "FM_MP_PS_REDUNDANT_LOST_N")
	)
	(segment
		(start 408.141424 -42.900092)
		(end 407.401268 -42.159936)
		(width 0.089408)
		(layer "In2.Cu")
		(net "FM_MP_PS_REDUNDANT_LOST_N")
	)
	(segment
		(start 416.96386 -40.938196)
		(end 416.7124 -41.189656)
		(width 0.089408)
		(layer "In2.Cu")
		(net "FM_MP_PS_REDUNDANT_LOST_N")
	)
	(segment
		(start 379.169676 -55.682642)
		(end 379.169676 -54.944772)
		(width 0.089408)
		(layer "In2.Cu")
		(net "FM_MP_PS_REDUNDANT_LOST_N")
	)
	(segment
		(start 380.774448 -45.038772)
		(end 380.774448 -41.500552)
		(width 0.089408)
		(layer "In2.Cu")
		(net "FM_MP_PS_REDUNDANT_LOST_N")
	)
	(segment
		(start 405.31542 -42.159936)
		(end 405.203914 -42.271442)
		(width 0.089408)
		(layer "In2.Cu")
		(net "FM_MP_PS_REDUNDANT_LOST_N")
	)
	(segment
		(start 181.4576 3.960114)
		(end 182.38597 4.888484)
		(width 0.089408)
		(layer "In2.Cu")
		(net "FM_MP_PS_REDUNDANT_LOST_N")
	)
	(segment
		(start 265.537442 4.888484)
		(end 266.824206 3.60172)
		(width 0.089408)
		(layer "In2.Cu")
		(net "FM_MP_PS_REDUNDANT_LOST_N")
	)
	(segment
		(start 329.181968 4.760976)
		(end 329.181968 3.8862)
		(width 0.089408)
		(layer "In2.Cu")
		(net "FM_MP_PS_REDUNDANT_LOST_N")
	)
	(segment
		(start 179.587144 -2.820162)
		(end 179.587144 -0.126238)
		(width 0.089408)
		(layer "In2.Cu")
		(net "FM_MP_PS_REDUNDANT_LOST_N")
	)
	(segment
		(start 415.864802 -42.030142)
		(end 415.864802 -42.289984)
		(width 0.089408)
		(layer "In2.Cu")
		(net "FM_MP_PS_REDUNDANT_LOST_N")
	)
	(segment
		(start 329.8317 -5.2197)
		(end 329.8317 -13.1953)
		(width 0.089408)
		(layer "In2.Cu")
		(net "FM_MP_PS_REDUNDANT_LOST_N")
	)
	(segment
		(start 415.864802 -42.289984)
		(end 414.922208 -43.232578)
		(width 0.089408)
		(layer "In2.Cu")
		(net "FM_MP_PS_REDUNDANT_LOST_N")
	)
	(segment
		(start 179.587144 -0.126238)
		(end 179.880768 0.167386)
		(width 0.089408)
		(layer "In2.Cu")
		(net "FM_MP_PS_REDUNDANT_LOST_N")
	)
	(segment
		(start 378.825252 -56.168798)
		(end 378.825252 -56.027066)
		(width 0.089408)
		(layer "In2.Cu")
		(net "FM_MP_PS_REDUNDANT_LOST_N")
	)
	(segment
		(start 380.919736 -41.355264)
		(end 380.919736 -41.124886)
		(width 0.089408)
		(layer "In2.Cu")
		(net "FM_MP_PS_REDUNDANT_LOST_N")
	)
	(segment
		(start 411.636972 -43.289474)
		(end 411.29204 -43.289474)
		(width 0.089408)
		(layer "In2.Cu")
		(net "FM_MP_PS_REDUNDANT_LOST_N")
	)
	(segment
		(start 380.381002 -38.552374)
		(end 380.381002 -37.980112)
		(width 0.089408)
		(layer "In2.Cu")
		(net "FM_MP_PS_REDUNDANT_LOST_N")
	)
	(segment
		(start 380.774448 -41.500552)
		(end 380.919736 -41.355264)
		(width 0.089408)
		(layer "In2.Cu")
		(net "FM_MP_PS_REDUNDANT_LOST_N")
	)
	(segment
		(start 330.3524 -18.4912)
		(end 330.3524 -22.484588)
		(width 0.089408)
		(layer "In2.Cu")
		(net "FM_MP_PS_REDUNDANT_LOST_N")
	)
	(segment
		(start 410.92882 -42.926254)
		(end 410.928566 -42.926254)
		(width 0.089408)
		(layer "In2.Cu")
		(net "FM_MP_PS_REDUNDANT_LOST_N")
	)
	(segment
		(start 419.001194 -40.938196)
		(end 416.96386 -40.938196)
		(width 0.089408)
		(layer "In2.Cu")
		(net "FM_MP_PS_REDUNDANT_LOST_N")
	)
	(segment
		(start 329.029568 4.913376)
		(end 329.181968 4.760976)
		(width 0.089408)
		(layer "In2.Cu")
		(net "FM_MP_PS_REDUNDANT_LOST_N")
	)
	(segment
		(start 182.38597 4.888484)
		(end 265.537442 4.888484)
		(width 0.089408)
		(layer "In2.Cu")
		(net "FM_MP_PS_REDUNDANT_LOST_N")
	)
	(segment
		(start 416.135058 -41.759886)
		(end 415.864802 -42.030142)
		(width 0.089408)
		(layer "In2.Cu")
		(net "FM_MP_PS_REDUNDANT_LOST_N")
	)
	(segment
		(start 378.587 -47.22622)
		(end 380.774448 -45.038772)
		(width 0.089408)
		(layer "In2.Cu")
		(net "FM_MP_PS_REDUNDANT_LOST_N")
	)
	(segment
		(start 330.3524 -22.484588)
		(end 330.509626 -22.641814)
		(width 0.089408)
		(layer "In2.Cu")
		(net "FM_MP_PS_REDUNDANT_LOST_N")
	)
	(segment
		(start 329.8317 -13.1953)
		(end 329.065636 -13.961364)
		(width 0.089408)
		(layer "In2.Cu")
		(net "FM_MP_PS_REDUNDANT_LOST_N")
	)
	(segment
		(start 419.490144 -41.33469)
		(end 419.397688 -41.33469)
		(width 0.089408)
		(layer "In2.Cu")
		(net "FM_MP_PS_REDUNDANT_LOST_N")
	)
	(segment
		(start 323.59346 4.913376)
		(end 329.029568 4.913376)
		(width 0.089408)
		(layer "In2.Cu")
		(net "FM_MP_PS_REDUNDANT_LOST_N")
	)
	(segment
		(start 179.880768 1.720088)
		(end 181.4576 3.29692)
		(width 0.089408)
		(layer "In2.Cu")
		(net "FM_MP_PS_REDUNDANT_LOST_N")
	)
	(segment
		(start 380.919736 -41.124886)
		(end 380.381002 -40.586152)
		(width 0.089408)
		(layer "In2.Cu")
		(net "FM_MP_PS_REDUNDANT_LOST_N")
	)
	(segment
		(start 179.880768 0.167386)
		(end 179.880768 1.720088)
		(width 0.089408)
		(layer "In2.Cu")
		(net "FM_MP_PS_REDUNDANT_LOST_N")
	)
	(segment
		(start 414.922208 -43.232578)
		(end 411.693868 -43.232578)
		(width 0.089408)
		(layer "In2.Cu")
		(net "FM_MP_PS_REDUNDANT_LOST_N")
	)
	(segment
		(start 181.4576 3.29692)
		(end 181.4576 3.960114)
		(width 0.089408)
		(layer "In2.Cu")
		(net "FM_MP_PS_REDUNDANT_LOST_N")
	)
	(segment
		(start 266.824206 3.60172)
		(end 322.281804 3.60172)
		(width 0.089408)
		(layer "In2.Cu")
		(net "FM_MP_PS_REDUNDANT_LOST_N")
	)
	(segment
		(start 177.41138 -4.995926)
		(end 179.587144 -2.820162)
		(width 0.089408)
		(layer "In2.Cu")
		(net "FM_MP_PS_REDUNDANT_LOST_N")
	)
	(segment
		(start 416.7124 -41.442386)
		(end 416.3949 -41.759886)
		(width 0.089408)
		(layer "In2.Cu")
		(net "FM_MP_PS_REDUNDANT_LOST_N")
	)
	(segment
		(start 410.902404 -42.900092)
		(end 408.141424 -42.900092)
		(width 0.089408)
		(layer "In2.Cu")
		(net "FM_MP_PS_REDUNDANT_LOST_N")
	)
	(segment
		(start 329.5904 3.477768)
		(end 329.5904 -4.9784)
		(width 0.089408)
		(layer "In2.Cu")
		(net "FM_MP_PS_REDUNDANT_LOST_N")
	)
	(segment
		(start 419.397688 -41.33469)
		(end 419.001194 -40.938196)
		(width 0.089408)
		(layer "In2.Cu")
		(net "FM_MP_PS_REDUNDANT_LOST_N")
	)
	(segment
		(start 378.587 -54.362096)
		(end 378.587 -47.22622)
		(width 0.089408)
		(layer "In2.Cu")
		(net "FM_MP_PS_REDUNDANT_LOST_N")
	)
	(segment
		(start 379.593348 -39.008304)
		(end 379.82779 -38.773862)
		(width 0.089408)
		(layer "In2.Cu")
		(net "FM_MP_PS_REDUNDANT_LOST_N")
	)
	(segment
		(start 379.593348 -39.45001)
		(end 379.593348 -39.008304)
		(width 0.089408)
		(layer "In2.Cu")
		(net "FM_MP_PS_REDUNDANT_LOST_N")
	)
	(segment
		(start 407.401268 -42.159936)
		(end 405.31542 -42.159936)
		(width 0.089408)
		(layer "In2.Cu")
		(net "FM_MP_PS_REDUNDANT_LOST_N")
	)
	(segment
		(start 329.065636 -13.961364)
		(end 329.065636 -17.204436)
		(width 0.089408)
		(layer "In2.Cu")
		(net "FM_MP_PS_REDUNDANT_LOST_N")
	)
	(segment
		(start 380.381002 -37.980112)
		(end 380.0221 -37.62121)
		(width 0.089408)
		(layer "In2.Cu")
		(net "FM_MP_PS_REDUNDANT_LOST_N")
	)
	(segment
		(start 378.825252 -56.027066)
		(end 379.169676 -55.682642)
		(width 0.089408)
		(layer "In2.Cu")
		(net "FM_MP_PS_REDUNDANT_LOST_N")
	)
	(segment
		(start 416.3949 -41.759886)
		(end 416.135058 -41.759886)
		(width 0.089408)
		(layer "In2.Cu")
		(net "FM_MP_PS_REDUNDANT_LOST_N")
	)
	(segment
		(start 416.7124 -41.189656)
		(end 416.7124 -41.442386)
		(width 0.089408)
		(layer "In2.Cu")
		(net "FM_MP_PS_REDUNDANT_LOST_N")
	)
	(segment
		(start 379.169676 -54.944772)
		(end 378.587 -54.362096)
		(width 0.089408)
		(layer "In2.Cu")
		(net "FM_MP_PS_REDUNDANT_LOST_N")
	)
	(segment
		(start 380.381002 -40.586152)
		(end 380.381002 -40.237664)
		(width 0.089408)
		(layer "In2.Cu")
		(net "FM_MP_PS_REDUNDANT_LOST_N")
	)
	(segment
		(start 379.82779 -38.773862)
		(end 380.159514 -38.773862)
		(width 0.089408)
		(layer "In2.Cu")
		(net "FM_MP_PS_REDUNDANT_LOST_N")
	)
	(segment
		(start 329.065636 -17.204436)
		(end 330.3524 -18.4912)
		(width 0.089408)
		(layer "In2.Cu")
		(net "FM_MP_PS_REDUNDANT_LOST_N")
	)
	(segment
		(start 380.159514 -38.773862)
		(end 380.381002 -38.552374)
		(width 0.089408)
		(layer "In2.Cu")
		(net "FM_MP_PS_REDUNDANT_LOST_N")
	)
	(segment
		(start 410.928566 -42.926254)
		(end 410.902404 -42.900092)
		(width 0.089408)
		(layer "In2.Cu")
		(net "FM_MP_PS_REDUNDANT_LOST_N")
	)
	(segment
		(start 329.5904 -4.9784)
		(end 329.8317 -5.2197)
		(width 0.089408)
		(layer "In2.Cu")
		(net "FM_MP_PS_REDUNDANT_LOST_N")
	)
	(segment
		(start 411.29204 -43.289474)
		(end 410.92882 -42.926254)
		(width 0.089408)
		(layer "In2.Cu")
		(net "FM_MP_PS_REDUNDANT_LOST_N")
	)
	(segment
		(start 411.693868 -43.232578)
		(end 411.636972 -43.289474)
		(width 0.089408)
		(layer "In2.Cu")
		(net "FM_MP_PS_REDUNDANT_LOST_N")
	)
	(segment
		(start 380.381002 -40.237664)
		(end 379.593348 -39.45001)
		(width 0.089408)
		(layer "In2.Cu")
		(net "FM_MP_PS_REDUNDANT_LOST_N")
	)
	(segment
		(start 390.06653 -35.492944)
		(end 388.171944 -35.492944)
		(width 0.089408)
		(layer "In4.Cu")
		(net "FM_MP_PS_REDUNDANT_LOST_N")
	)
	(segment
		(start 399.12036 -37.128958)
		(end 397.201898 -37.128958)
		(width 0.089408)
		(layer "In4.Cu")
		(net "FM_MP_PS_REDUNDANT_LOST_N")
	)
	(segment
		(start 418.130228 -40.110664)
		(end 407.31186 -40.110664)
		(width 0.089408)
		(layer "In4.Cu")
		(net "FM_MP_PS_REDUNDANT_LOST_N")
	)
	(segment
		(start 394.629132 -37.369242)
		(end 393.189206 -35.929316)
		(width 0.089408)
		(layer "In4.Cu")
		(net "FM_MP_PS_REDUNDANT_LOST_N")
	)
	(segment
		(start 382.895602 -35.823652)
		(end 382.425448 -36.293806)
		(width 0.089408)
		(layer "In4.Cu")
		(net "FM_MP_PS_REDUNDANT_LOST_N")
	)
	(segment
		(start 384.067558 -36.138612)
		(end 383.752598 -35.823652)
		(width 0.089408)
		(layer "In4.Cu")
		(net "FM_MP_PS_REDUNDANT_LOST_N")
	)
	(segment
		(start 385.005834 -36.138612)
		(end 384.067558 -36.138612)
		(width 0.089408)
		(layer "In4.Cu")
		(net "FM_MP_PS_REDUNDANT_LOST_N")
	)
	(segment
		(start 396.961614 -37.369242)
		(end 394.629132 -37.369242)
		(width 0.089408)
		(layer "In4.Cu")
		(net "FM_MP_PS_REDUNDANT_LOST_N")
	)
	(segment
		(start 382.425448 -36.293806)
		(end 382.425448 -36.433252)
		(width 0.089408)
		(layer "In4.Cu")
		(net "FM_MP_PS_REDUNDANT_LOST_N")
	)
	(segment
		(start 387.3246 -34.6456)
		(end 386.498846 -34.6456)
		(width 0.089408)
		(layer "In4.Cu")
		(net "FM_MP_PS_REDUNDANT_LOST_N")
	)
	(segment
		(start 382.266952 -36.591748)
		(end 381.051562 -36.591748)
		(width 0.089408)
		(layer "In4.Cu")
		(net "FM_MP_PS_REDUNDANT_LOST_N")
	)
	(segment
		(start 418.315394 -40.690038)
		(end 418.315394 -40.29583)
		(width 0.089408)
		(layer "In4.Cu")
		(net "FM_MP_PS_REDUNDANT_LOST_N")
	)
	(segment
		(start 381.051562 -36.591748)
		(end 380.0221 -37.62121)
		(width 0.089408)
		(layer "In4.Cu")
		(net "FM_MP_PS_REDUNDANT_LOST_N")
	)
	(segment
		(start 419.490144 -41.33469)
		(end 419.27526 -41.33469)
		(width 0.089408)
		(layer "In4.Cu")
		(net "FM_MP_PS_REDUNDANT_LOST_N")
	)
	(segment
		(start 418.875718 -40.935148)
		(end 418.561012 -40.935148)
		(width 0.089408)
		(layer "In4.Cu")
		(net "FM_MP_PS_REDUNDANT_LOST_N")
	)
	(segment
		(start 407.31186 -40.110664)
		(end 406.557988 -39.356792)
		(width 0.089408)
		(layer "In4.Cu")
		(net "FM_MP_PS_REDUNDANT_LOST_N")
	)
	(segment
		(start 390.502902 -35.929316)
		(end 390.06653 -35.492944)
		(width 0.089408)
		(layer "In4.Cu")
		(net "FM_MP_PS_REDUNDANT_LOST_N")
	)
	(segment
		(start 399.299938 -36.94938)
		(end 399.12036 -37.128958)
		(width 0.089408)
		(layer "In4.Cu")
		(net "FM_MP_PS_REDUNDANT_LOST_N")
	)
	(segment
		(start 388.171944 -35.492944)
		(end 387.3246 -34.6456)
		(width 0.089408)
		(layer "In4.Cu")
		(net "FM_MP_PS_REDUNDANT_LOST_N")
	)
	(segment
		(start 405.503888 -39.356792)
		(end 403.096476 -36.94938)
		(width 0.089408)
		(layer "In4.Cu")
		(net "FM_MP_PS_REDUNDANT_LOST_N")
	)
	(segment
		(start 406.557988 -39.356792)
		(end 405.503888 -39.356792)
		(width 0.089408)
		(layer "In4.Cu")
		(net "FM_MP_PS_REDUNDANT_LOST_N")
	)
	(segment
		(start 393.189206 -35.929316)
		(end 390.502902 -35.929316)
		(width 0.089408)
		(layer "In4.Cu")
		(net "FM_MP_PS_REDUNDANT_LOST_N")
	)
	(segment
		(start 403.096476 -36.94938)
		(end 399.299938 -36.94938)
		(width 0.089408)
		(layer "In4.Cu")
		(net "FM_MP_PS_REDUNDANT_LOST_N")
	)
	(segment
		(start 418.561012 -40.935148)
		(end 418.535358 -40.909494)
		(width 0.089408)
		(layer "In4.Cu")
		(net "FM_MP_PS_REDUNDANT_LOST_N")
	)
	(segment
		(start 383.752598 -35.823652)
		(end 382.895602 -35.823652)
		(width 0.089408)
		(layer "In4.Cu")
		(net "FM_MP_PS_REDUNDANT_LOST_N")
	)
	(segment
		(start 419.27526 -41.33469)
		(end 418.875718 -40.935148)
		(width 0.089408)
		(layer "In4.Cu")
		(net "FM_MP_PS_REDUNDANT_LOST_N")
	)
	(segment
		(start 418.315394 -40.29583)
		(end 418.130228 -40.110664)
		(width 0.089408)
		(layer "In4.Cu")
		(net "FM_MP_PS_REDUNDANT_LOST_N")
	)
	(segment
		(start 382.425448 -36.433252)
		(end 382.266952 -36.591748)
		(width 0.089408)
		(layer "In4.Cu")
		(net "FM_MP_PS_REDUNDANT_LOST_N")
	)
	(segment
		(start 386.498846 -34.6456)
		(end 385.005834 -36.138612)
		(width 0.089408)
		(layer "In4.Cu")
		(net "FM_MP_PS_REDUNDANT_LOST_N")
	)
	(segment
		(start 418.535358 -40.909494)
		(end 418.53485 -40.909494)
		(width 0.089408)
		(layer "In4.Cu")
		(net "FM_MP_PS_REDUNDANT_LOST_N")
	)
	(segment
		(start 418.53485 -40.909494)
		(end 418.315394 -40.690038)
		(width 0.089408)
		(layer "In4.Cu")
		(net "FM_MP_PS_REDUNDANT_LOST_N")
	)
	(segment
		(start 397.201898 -37.128958)
		(end 396.961614 -37.369242)
		(width 0.089408)
		(layer "In4.Cu")
		(net "FM_MP_PS_REDUNDANT_LOST_N")
	)
	(segment
		(start 388.32917 -97.376742)
		(end 388.32917 -98.367596)
		(width 0.089408)
		(layer "In9.Cu")
		(net "FM_MP_PS_REDUNDANT_LOST_N")
	)
	(segment
		(start 400.49704 -56.458104)
		(end 400.49704 -56.572404)
		(width 0.089408)
		(layer "In9.Cu")
		(net "FM_MP_PS_REDUNDANT_LOST_N")
	)
	(segment
		(start 398.37487 -73.440036)
		(end 398.37487 -74.38263)
		(width 0.089408)
		(layer "In9.Cu")
		(net "FM_MP_PS_REDUNDANT_LOST_N")
	)
	(segment
		(start 402.967698 -44.738036)
		(end 402.967698 -45.616876)
		(width 0.089408)
		(layer "In9.Cu")
		(net "FM_MP_PS_REDUNDANT_LOST_N")
	)
	(segment
		(start 398.37487 -74.38263)
		(end 397.171672 -75.585828)
		(width 0.089408)
		(layer "In9.Cu")
		(net "FM_MP_PS_REDUNDANT_LOST_N")
	)
	(segment
		(start 400.49704 -56.572404)
		(end 402.143976 -58.21934)
		(width 0.089408)
		(layer "In9.Cu")
		(net "FM_MP_PS_REDUNDANT_LOST_N")
	)
	(segment
		(start 400.802856 -63.408814)
		(end 400.802856 -66.252598)
		(width 0.089408)
		(layer "In9.Cu")
		(net "FM_MP_PS_REDUNDANT_LOST_N")
	)
	(segment
		(start 397.171672 -76.716128)
		(end 395.838934 -78.048866)
		(width 0.089408)
		(layer "In9.Cu")
		(net "FM_MP_PS_REDUNDANT_LOST_N")
	)
	(segment
		(start 400.49704 -48.087534)
		(end 400.49704 -55.507128)
		(width 0.089408)
		(layer "In9.Cu")
		(net "FM_MP_PS_REDUNDANT_LOST_N")
	)
	(segment
		(start 388.32917 -96.05391)
		(end 388.63143 -96.35617)
		(width 0.089408)
		(layer "In9.Cu")
		(net "FM_MP_PS_REDUNDANT_LOST_N")
	)
	(segment
		(start 403.866096 -43.60926)
		(end 403.866096 -43.839638)
		(width 0.089408)
		(layer "In9.Cu")
		(net "FM_MP_PS_REDUNDANT_LOST_N")
	)
	(segment
		(start 395.838934 -78.048866)
		(end 395.838934 -79.007462)
		(width 0.089408)
		(layer "In9.Cu")
		(net "FM_MP_PS_REDUNDANT_LOST_N")
	)
	(segment
		(start 388.32917 -98.367596)
		(end 388.23265 -98.464116)
		(width 0.089408)
		(layer "In9.Cu")
		(net "FM_MP_PS_REDUNDANT_LOST_N")
	)
	(segment
		(start 395.838934 -79.007462)
		(end 396.514828 -79.683356)
		(width 0.089408)
		(layer "In9.Cu")
		(net "FM_MP_PS_REDUNDANT_LOST_N")
	)
	(segment
		(start 388.63143 -97.074482)
		(end 388.32917 -97.376742)
		(width 0.089408)
		(layer "In9.Cu")
		(net "FM_MP_PS_REDUNDANT_LOST_N")
	)
	(segment
		(start 400.49704 -55.507128)
		(end 400.496786 -55.507382)
		(width 0.089408)
		(layer "In9.Cu")
		(net "FM_MP_PS_REDUNDANT_LOST_N")
	)
	(segment
		(start 400.496786 -55.507382)
		(end 400.496786 -56.45785)
		(width 0.089408)
		(layer "In9.Cu")
		(net "FM_MP_PS_REDUNDANT_LOST_N")
	)
	(segment
		(start 398.59458 -69.094858)
		(end 398.59458 -71.129906)
		(width 0.089408)
		(layer "In9.Cu")
		(net "FM_MP_PS_REDUNDANT_LOST_N")
	)
	(segment
		(start 396.514828 -79.683356)
		(end 396.514828 -82.089752)
		(width 0.089408)
		(layer "In9.Cu")
		(net "FM_MP_PS_REDUNDANT_LOST_N")
	)
	(segment
		(start 398.594326 -69.094604)
		(end 398.59458 -69.094858)
		(width 0.089408)
		(layer "In9.Cu")
		(net "FM_MP_PS_REDUNDANT_LOST_N")
	)
	(segment
		(start 396.514828 -82.089752)
		(end 395.64818 -82.9564)
		(width 0.089408)
		(layer "In9.Cu")
		(net "FM_MP_PS_REDUNDANT_LOST_N")
	)
	(segment
		(start 394.13688 -86.315042)
		(end 394.13688 -86.86292)
		(width 0.089408)
		(layer "In9.Cu")
		(net "FM_MP_PS_REDUNDANT_LOST_N")
	)
	(segment
		(start 391.3886 -88.773)
		(end 391.3886 -92.512134)
		(width 0.089408)
		(layer "In9.Cu")
		(net "FM_MP_PS_REDUNDANT_LOST_N")
	)
	(segment
		(start 394.13688 -86.86292)
		(end 392.687048 -88.312752)
		(width 0.089408)
		(layer "In9.Cu")
		(net "FM_MP_PS_REDUNDANT_LOST_N")
	)
	(segment
		(start 391.848848 -88.312752)
		(end 391.3886 -88.773)
		(width 0.089408)
		(layer "In9.Cu")
		(net "FM_MP_PS_REDUNDANT_LOST_N")
	)
	(segment
		(start 402.144484 -61.275214)
		(end 402.144484 -62.067186)
		(width 0.089408)
		(layer "In9.Cu")
		(net "FM_MP_PS_REDUNDANT_LOST_N")
	)
	(segment
		(start 405.203914 -42.271442)
		(end 403.866096 -43.60926)
		(width 0.089408)
		(layer "In9.Cu")
		(net "FM_MP_PS_REDUNDANT_LOST_N")
	)
	(segment
		(start 395.64818 -82.9564)
		(end 395.64818 -84.803742)
		(width 0.089408)
		(layer "In9.Cu")
		(net "FM_MP_PS_REDUNDANT_LOST_N")
	)
	(segment
		(start 402.14423 -61.27496)
		(end 402.144484 -61.275214)
		(width 0.089408)
		(layer "In9.Cu")
		(net "FM_MP_PS_REDUNDANT_LOST_N")
	)
	(segment
		(start 402.144484 -62.067186)
		(end 400.802856 -63.408814)
		(width 0.089408)
		(layer "In9.Cu")
		(net "FM_MP_PS_REDUNDANT_LOST_N")
	)
	(segment
		(start 397.171672 -75.585828)
		(end 397.171672 -76.716128)
		(width 0.089408)
		(layer "In9.Cu")
		(net "FM_MP_PS_REDUNDANT_LOST_N")
	)
	(segment
		(start 395.64818 -84.803742)
		(end 394.13688 -86.315042)
		(width 0.089408)
		(layer "In9.Cu")
		(net "FM_MP_PS_REDUNDANT_LOST_N")
	)
	(segment
		(start 388.63143 -96.35617)
		(end 388.63143 -97.074482)
		(width 0.089408)
		(layer "In9.Cu")
		(net "FM_MP_PS_REDUNDANT_LOST_N")
	)
	(segment
		(start 391.3886 -92.512134)
		(end 388.32917 -95.571564)
		(width 0.089408)
		(layer "In9.Cu")
		(net "FM_MP_PS_REDUNDANT_LOST_N")
	)
	(segment
		(start 402.143976 -60.799726)
		(end 402.14423 -60.79998)
		(width 0.089408)
		(layer "In9.Cu")
		(net "FM_MP_PS_REDUNDANT_LOST_N")
	)
	(segment
		(start 402.14423 -60.79998)
		(end 402.14423 -61.27496)
		(width 0.089408)
		(layer "In9.Cu")
		(net "FM_MP_PS_REDUNDANT_LOST_N")
	)
	(segment
		(start 388.32917 -95.571564)
		(end 388.32917 -96.05391)
		(width 0.089408)
		(layer "In9.Cu")
		(net "FM_MP_PS_REDUNDANT_LOST_N")
	)
	(segment
		(start 398.594326 -68.461128)
		(end 398.594326 -69.094604)
		(width 0.089408)
		(layer "In9.Cu")
		(net "FM_MP_PS_REDUNDANT_LOST_N")
	)
	(segment
		(start 400.496786 -56.45785)
		(end 400.49704 -56.458104)
		(width 0.089408)
		(layer "In9.Cu")
		(net "FM_MP_PS_REDUNDANT_LOST_N")
	)
	(segment
		(start 392.687048 -88.312752)
		(end 391.848848 -88.312752)
		(width 0.089408)
		(layer "In9.Cu")
		(net "FM_MP_PS_REDUNDANT_LOST_N")
	)
	(segment
		(start 402.143976 -58.21934)
		(end 402.143976 -60.799726)
		(width 0.089408)
		(layer "In9.Cu")
		(net "FM_MP_PS_REDUNDANT_LOST_N")
	)
	(segment
		(start 403.866096 -43.839638)
		(end 402.967698 -44.738036)
		(width 0.089408)
		(layer "In9.Cu")
		(net "FM_MP_PS_REDUNDANT_LOST_N")
	)
	(segment
		(start 398.59458 -71.129906)
		(end 397.944086 -71.7804)
		(width 0.089408)
		(layer "In9.Cu")
		(net "FM_MP_PS_REDUNDANT_LOST_N")
	)
	(segment
		(start 400.802856 -66.252598)
		(end 398.594326 -68.461128)
		(width 0.089408)
		(layer "In9.Cu")
		(net "FM_MP_PS_REDUNDANT_LOST_N")
	)
	(segment
		(start 397.944086 -73.009252)
		(end 398.37487 -73.440036)
		(width 0.089408)
		(layer "In9.Cu")
		(net "FM_MP_PS_REDUNDANT_LOST_N")
	)
	(segment
		(start 402.967698 -45.616876)
		(end 400.49704 -48.087534)
		(width 0.089408)
		(layer "In9.Cu")
		(net "FM_MP_PS_REDUNDANT_LOST_N")
	)
	(segment
		(start 397.944086 -71.7804)
		(end 397.944086 -73.009252)
		(width 0.089408)
		(layer "In9.Cu")
		(net "FM_MP_PS_REDUNDANT_LOST_N")
	)
	(segment
		(start 165.055296 -0.118618)
		(end 165.055296 3.192526)
		(width 0.089408)
		(layer "In11.Cu")
		(net "FM_MP_PS_REDUNDANT_LOST_N")
	)
	(segment
		(start 167.77335 -3.672332)
		(end 167.27678 -3.175762)
		(width 0.089408)
		(layer "In11.Cu")
		(net "FM_MP_PS_REDUNDANT_LOST_N")
	)
	(segment
		(start 333.356712 -36.58489)
		(end 333.356712 -37.044122)
		(width 0.089408)
		(layer "In11.Cu")
		(net "FM_MP_PS_REDUNDANT_LOST_N")
	)
	(segment
		(start 177.41138 -4.995926)
		(end 177.41138 -5.164074)
		(width 0.089408)
		(layer "In11.Cu")
		(net "FM_MP_PS_REDUNDANT_LOST_N")
	)
	(segment
		(start 331.087984 -26.373582)
		(end 330.066904 -27.394662)
		(width 0.089408)
		(layer "In11.Cu")
		(net "FM_MP_PS_REDUNDANT_LOST_N")
	)
	(segment
		(start 102.716584 4.198366)
		(end 28.988004 4.198366)
		(width 0.089408)
		(layer "In11.Cu")
		(net "FM_MP_PS_REDUNDANT_LOST_N")
	)
	(segment
		(start 25.887934 1.098296)
		(end 25.887934 -15.194788)
		(width 0.089408)
		(layer "In11.Cu")
		(net "FM_MP_PS_REDUNDANT_LOST_N")
	)
	(segment
		(start 336.348832 -38.778688)
		(end 353.038918 -38.778688)
		(width 0.089408)
		(layer "In11.Cu")
		(net "FM_MP_PS_REDUNDANT_LOST_N")
	)
	(segment
		(start 25.887934 -15.194788)
		(end 26.333704 -15.640558)
		(width 0.089408)
		(layer "In11.Cu")
		(net "FM_MP_PS_REDUNDANT_LOST_N")
	)
	(segment
		(start 333.356712 -37.044122)
		(end 334.627982 -38.315392)
		(width 0.089408)
		(layer "In11.Cu")
		(net "FM_MP_PS_REDUNDANT_LOST_N")
	)
	(segment
		(start 26.333704 -19.002756)
		(end 26.105866 -19.230594)
		(width 0.089408)
		(layer "In11.Cu")
		(net "FM_MP_PS_REDUNDANT_LOST_N")
	)
	(segment
		(start 373.160544 -52.620164)
		(end 374.682004 -54.141624)
		(width 0.089408)
		(layer "In11.Cu")
		(net "FM_MP_PS_REDUNDANT_LOST_N")
	)
	(segment
		(start 167.27678 -2.340102)
		(end 165.055296 -0.118618)
		(width 0.089408)
		(layer "In11.Cu")
		(net "FM_MP_PS_REDUNDANT_LOST_N")
	)
	(segment
		(start 331.087984 -25.369266)
		(end 331.087984 -26.373582)
		(width 0.089408)
		(layer "In11.Cu")
		(net "FM_MP_PS_REDUNDANT_LOST_N")
	)
	(segment
		(start 176.154842 -6.420612)
		(end 174.775368 -6.420612)
		(width 0.089408)
		(layer "In11.Cu")
		(net "FM_MP_PS_REDUNDANT_LOST_N")
	)
	(segment
		(start 353.038918 -38.778688)
		(end 354.60432 -37.213286)
		(width 0.089408)
		(layer "In11.Cu")
		(net "FM_MP_PS_REDUNDANT_LOST_N")
	)
	(segment
		(start 330.509626 -22.641814)
		(end 330.509626 -24.790908)
		(width 0.089408)
		(layer "In11.Cu")
		(net "FM_MP_PS_REDUNDANT_LOST_N")
	)
	(segment
		(start 332.468474 -33.392872)
		(end 332.468474 -35.696652)
		(width 0.089408)
		(layer "In11.Cu")
		(net "FM_MP_PS_REDUNDANT_LOST_N")
	)
	(segment
		(start 177.41138 -5.164074)
		(end 176.154842 -6.420612)
		(width 0.089408)
		(layer "In11.Cu")
		(net "FM_MP_PS_REDUNDANT_LOST_N")
	)
	(segment
		(start 332.138274 -33.062672)
		(end 332.468474 -33.392872)
		(width 0.089408)
		(layer "In11.Cu")
		(net "FM_MP_PS_REDUNDANT_LOST_N")
	)
	(segment
		(start 103.327962 3.586988)
		(end 102.716584 4.198366)
		(width 0.089408)
		(layer "In11.Cu")
		(net "FM_MP_PS_REDUNDANT_LOST_N")
	)
	(segment
		(start 332.468474 -35.696652)
		(end 333.356712 -36.58489)
		(width 0.089408)
		(layer "In11.Cu")
		(net "FM_MP_PS_REDUNDANT_LOST_N")
	)
	(segment
		(start 174.775368 -6.420612)
		(end 173.757082 -5.402326)
		(width 0.089408)
		(layer "In11.Cu")
		(net "FM_MP_PS_REDUNDANT_LOST_N")
	)
	(segment
		(start 172.45076 -5.402326)
		(end 170.720766 -3.672332)
		(width 0.089408)
		(layer "In11.Cu")
		(net "FM_MP_PS_REDUNDANT_LOST_N")
	)
	(segment
		(start 379.381512 -55.612538)
		(end 378.825252 -56.168798)
		(width 0.089408)
		(layer "In11.Cu")
		(net "FM_MP_PS_REDUNDANT_LOST_N")
	)
	(segment
		(start 330.066904 -27.394662)
		(end 330.066904 -31.836614)
		(width 0.089408)
		(layer "In11.Cu")
		(net "FM_MP_PS_REDUNDANT_LOST_N")
	)
	(segment
		(start 164.233352 4.01447)
		(end 118.64975 4.01447)
		(width 0.089408)
		(layer "In11.Cu")
		(net "FM_MP_PS_REDUNDANT_LOST_N")
	)
	(segment
		(start 379.381512 -55.016146)
		(end 379.381512 -55.612538)
		(width 0.089408)
		(layer "In11.Cu")
		(net "FM_MP_PS_REDUNDANT_LOST_N")
	)
	(segment
		(start 330.066904 -31.836614)
		(end 331.292962 -33.062672)
		(width 0.089408)
		(layer "In11.Cu")
		(net "FM_MP_PS_REDUNDANT_LOST_N")
	)
	(segment
		(start 25.357328 -24.384)
		(end 22.027134 -24.384)
		(width 0.089408)
		(layer "In11.Cu")
		(net "FM_MP_PS_REDUNDANT_LOST_N")
	)
	(segment
		(start 374.682004 -54.141624)
		(end 378.50699 -54.141624)
		(width 0.089408)
		(layer "In11.Cu")
		(net "FM_MP_PS_REDUNDANT_LOST_N")
	)
	(segment
		(start 330.509626 -24.790908)
		(end 331.087984 -25.369266)
		(width 0.089408)
		(layer "In11.Cu")
		(net "FM_MP_PS_REDUNDANT_LOST_N")
	)
	(segment
		(start 373.160544 -52.165758)
		(end 373.160544 -52.620164)
		(width 0.089408)
		(layer "In11.Cu")
		(net "FM_MP_PS_REDUNDANT_LOST_N")
	)
	(segment
		(start 165.055296 3.192526)
		(end 164.233352 4.01447)
		(width 0.089408)
		(layer "In11.Cu")
		(net "FM_MP_PS_REDUNDANT_LOST_N")
	)
	(segment
		(start 118.222268 3.586988)
		(end 103.327962 3.586988)
		(width 0.089408)
		(layer "In11.Cu")
		(net "FM_MP_PS_REDUNDANT_LOST_N")
	)
	(segment
		(start 173.757082 -5.402326)
		(end 172.45076 -5.402326)
		(width 0.089408)
		(layer "In11.Cu")
		(net "FM_MP_PS_REDUNDANT_LOST_N")
	)
	(segment
		(start 170.720766 -3.672332)
		(end 167.77335 -3.672332)
		(width 0.089408)
		(layer "In11.Cu")
		(net "FM_MP_PS_REDUNDANT_LOST_N")
	)
	(segment
		(start 378.50699 -54.141624)
		(end 379.381512 -55.016146)
		(width 0.089408)
		(layer "In11.Cu")
		(net "FM_MP_PS_REDUNDANT_LOST_N")
	)
	(segment
		(start 334.627982 -38.315392)
		(end 335.885536 -38.315392)
		(width 0.089408)
		(layer "In11.Cu")
		(net "FM_MP_PS_REDUNDANT_LOST_N")
	)
	(segment
		(start 118.64975 4.01447)
		(end 118.222268 3.586988)
		(width 0.089408)
		(layer "In11.Cu")
		(net "FM_MP_PS_REDUNDANT_LOST_N")
	)
	(segment
		(start 335.885536 -38.315392)
		(end 336.348832 -38.778688)
		(width 0.089408)
		(layer "In11.Cu")
		(net "FM_MP_PS_REDUNDANT_LOST_N")
	)
	(segment
		(start 26.105866 -23.635462)
		(end 25.357328 -24.384)
		(width 0.089408)
		(layer "In11.Cu")
		(net "FM_MP_PS_REDUNDANT_LOST_N")
	)
	(segment
		(start 167.27678 -3.175762)
		(end 167.27678 -2.340102)
		(width 0.089408)
		(layer "In11.Cu")
		(net "FM_MP_PS_REDUNDANT_LOST_N")
	)
	(segment
		(start 356.988872 -37.213286)
		(end 366.604804 -46.829218)
		(width 0.089408)
		(layer "In11.Cu")
		(net "FM_MP_PS_REDUNDANT_LOST_N")
	)
	(segment
		(start 331.292962 -33.062672)
		(end 332.138274 -33.062672)
		(width 0.089408)
		(layer "In11.Cu")
		(net "FM_MP_PS_REDUNDANT_LOST_N")
	)
	(segment
		(start 28.988004 4.198366)
		(end 25.887934 1.098296)
		(width 0.089408)
		(layer "In11.Cu")
		(net "FM_MP_PS_REDUNDANT_LOST_N")
	)
	(segment
		(start 367.824004 -46.829218)
		(end 373.160544 -52.165758)
		(width 0.089408)
		(layer "In11.Cu")
		(net "FM_MP_PS_REDUNDANT_LOST_N")
	)
	(segment
		(start 22.027134 -24.384)
		(end 19.741134 -26.67)
		(width 0.089408)
		(layer "In11.Cu")
		(net "FM_MP_PS_REDUNDANT_LOST_N")
	)
	(segment
		(start 354.60432 -37.213286)
		(end 356.988872 -37.213286)
		(width 0.089408)
		(layer "In11.Cu")
		(net "FM_MP_PS_REDUNDANT_LOST_N")
	)
	(segment
		(start 26.105866 -19.230594)
		(end 26.105866 -23.635462)
		(width 0.089408)
		(layer "In11.Cu")
		(net "FM_MP_PS_REDUNDANT_LOST_N")
	)
	(segment
		(start 26.333704 -15.640558)
		(end 26.333704 -19.002756)
		(width 0.089408)
		(layer "In11.Cu")
		(net "FM_MP_PS_REDUNDANT_LOST_N")
	)
	(segment
		(start 366.604804 -46.829218)
		(end 367.824004 -46.829218)
		(width 0.089408)
		(layer "In11.Cu")
		(net "FM_MP_PS_REDUNDANT_LOST_N")
	)
	(segment
		(start 387.73735 -102.12832)
		(end 388.23265 -101.898196)
		(width 0.10795)
		(layer "F.Cu")
		(net "FM_MP_PS_FAIL_N")
	)
	(segment
		(start 415.090102 -40.13454)
		(end 415.490152 -40.53459)
		(width 0.10795)
		(layer "F.Cu")
		(net "FM_MP_PS_FAIL_N")
	)
	(segment
		(start 376.744738 -73.495154)
		(end 376.344942 -73.89495)
		(width 0.1016)
		(layer "F.Cu")
		(net "FM_MP_PS_FAIL_N")
	)
	(via
		(at 386.3467 -94.4118)
		(size 0.6604)
		(drill 0.3302)
		(layers "F.Cu" "B.Cu")
		(net "FM_MP_PS_FAIL_N")
	)
	(via
		(at 382.8288 -91.1098)
		(size 0.508)
		(drill 0.254)
		(layers "F.Cu" "B.Cu")
		(net "FM_MP_PS_FAIL_N")
	)
	(via
		(at 178.08448 -4.983226)
		(size 0.508)
		(drill 0.254)
		(layers "F.Cu" "B.Cu")
		(net "FM_MP_PS_FAIL_N")
	)
	(via
		(at 376.744738 -73.495154)
		(size 0.4572)
		(drill 0.2032)
		(layers "F.Cu" "B.Cu")
		(net "FM_MP_PS_FAIL_N")
	)
	(via
		(at 328.343768 -0.256032)
		(size 0.508)
		(drill 0.254)
		(layers "F.Cu" "B.Cu")
		(net "FM_MP_PS_FAIL_N")
	)
	(via
		(at 388.747 -73.0758)
		(size 0.508)
		(drill 0.254)
		(layers "F.Cu" "B.Cu")
		(net "FM_MP_PS_FAIL_N")
	)
	(via
		(at 388.23265 -101.898196)
		(size 0.508)
		(drill 0.254)
		(layers "F.Cu" "B.Cu")
		(net "FM_MP_PS_FAIL_N")
	)
	(via
		(at 415.490152 -40.53459)
		(size 0.4572)
		(drill 0.2032)
		(layers "F.Cu" "B.Cu")
		(net "FM_MP_PS_FAIL_N")
	)
	(via
		(at 380.190248 -69.524372)
		(size 0.508)
		(drill 0.254)
		(layers "F.Cu" "B.Cu")
		(net "FM_MP_PS_FAIL_N")
	)
	(segment
		(start 386.611368 -89.624662)
		(end 386.842 -89.39403)
		(width 0.10795)
		(layer "B.Cu")
		(net "FM_MP_PS_FAIL_N")
	)
	(segment
		(start 386.3467 -95.899732)
		(end 386.3467 -95.123)
		(width 0.0889)
		(layer "B.Cu")
		(net "FM_MP_PS_FAIL_N")
	)
	(segment
		(start 386.842 -100.192332)
		(end 386.842 -100.159566)
		(width 0.0889)
		(layer "B.Cu")
		(net "FM_MP_PS_FAIL_N")
	)
	(segment
		(start 387.251194 -100.739194)
		(end 387.110224 -100.598224)
		(width 0.0889)
		(layer "B.Cu")
		(net "FM_MP_PS_FAIL_N")
	)
	(segment
		(start 386.3467 -97.616772)
		(end 386.3467 -97.59442)
		(width 0.0889)
		(layer "B.Cu")
		(net "FM_MP_PS_FAIL_N")
	)
	(segment
		(start 386.842 -89.39403)
		(end 386.842 -88.2015)
		(width 0.10795)
		(layer "B.Cu")
		(net "FM_MP_PS_FAIL_N")
	)
	(segment
		(start 386.211318 -92.173806)
		(end 386.211318 -91.735402)
		(width 0.10795)
		(layer "B.Cu")
		(net "FM_MP_PS_FAIL_N")
	)
	(segment
		(start 386.3467 -99.333812)
		(end 386.3467 -99.31146)
		(width 0.0889)
		(layer "B.Cu")
		(net "FM_MP_PS_FAIL_N")
	)
	(segment
		(start 386.211318 -91.735402)
		(end 386.611368 -91.335352)
		(width 0.10795)
		(layer "B.Cu")
		(net "FM_MP_PS_FAIL_N")
	)
	(segment
		(start 380.106428 -69.608192)
		(end 380.106428 -69.845682)
		(width 0.10795)
		(layer "B.Cu")
		(net "FM_MP_PS_FAIL_N")
	)
	(segment
		(start 377.70308 -73.495154)
		(end 376.744738 -73.495154)
		(width 0.10795)
		(layer "B.Cu")
		(net "FM_MP_PS_FAIL_N")
	)
	(segment
		(start 386.842 -98.485706)
		(end 386.842 -98.442526)
		(width 0.0889)
		(layer "B.Cu")
		(net "FM_MP_PS_FAIL_N")
	)
	(segment
		(start 380.106428 -69.845682)
		(end 378.727462 -71.224648)
		(width 0.10795)
		(layer "B.Cu")
		(net "FM_MP_PS_FAIL_N")
	)
	(segment
		(start 378.727462 -72.900032)
		(end 378.471176 -73.156318)
		(width 0.10795)
		(layer "B.Cu")
		(net "FM_MP_PS_FAIL_N")
	)
	(segment
		(start 386.842 -96.768666)
		(end 386.842 -96.725486)
		(width 0.0889)
		(layer "B.Cu")
		(net "FM_MP_PS_FAIL_N")
	)
	(segment
		(start 378.727462 -71.224648)
		(end 378.727462 -72.900032)
		(width 0.10795)
		(layer "B.Cu")
		(net "FM_MP_PS_FAIL_N")
	)
	(segment
		(start 386.461 -92.423488)
		(end 386.211318 -92.173806)
		(width 0.10795)
		(layer "B.Cu")
		(net "FM_MP_PS_FAIL_N")
	)
	(segment
		(start 380.190248 -69.524372)
		(end 380.106428 -69.608192)
		(width 0.10795)
		(layer "B.Cu")
		(net "FM_MP_PS_FAIL_N")
	)
	(segment
		(start 387.251194 -101.281484)
		(end 387.251194 -100.739194)
		(width 0.0889)
		(layer "B.Cu")
		(net "FM_MP_PS_FAIL_N")
	)
	(segment
		(start 386.3467 -94.4118)
		(end 386.3467 -93.43644)
		(width 0.10795)
		(layer "B.Cu")
		(net "FM_MP_PS_FAIL_N")
	)
	(segment
		(start 388.23265 -101.898196)
		(end 387.867906 -101.898196)
		(width 0.0889)
		(layer "B.Cu")
		(net "FM_MP_PS_FAIL_N")
	)
	(segment
		(start 386.3467 -93.43644)
		(end 386.461 -93.32214)
		(width 0.10795)
		(layer "B.Cu")
		(net "FM_MP_PS_FAIL_N")
	)
	(segment
		(start 378.471176 -73.156318)
		(end 378.041916 -73.156318)
		(width 0.10795)
		(layer "B.Cu")
		(net "FM_MP_PS_FAIL_N")
	)
	(segment
		(start 387.867906 -101.898196)
		(end 387.251194 -101.281484)
		(width 0.0889)
		(layer "B.Cu")
		(net "FM_MP_PS_FAIL_N")
	)
	(segment
		(start 378.041916 -73.156318)
		(end 377.70308 -73.495154)
		(width 0.10795)
		(layer "B.Cu")
		(net "FM_MP_PS_FAIL_N")
	)
	(segment
		(start 386.3467 -95.123)
		(end 386.3467 -94.4118)
		(width 0.10795)
		(layer "B.Cu")
		(net "FM_MP_PS_FAIL_N")
	)
	(segment
		(start 386.611368 -91.335352)
		(end 386.611368 -89.624662)
		(width 0.10795)
		(layer "B.Cu")
		(net "FM_MP_PS_FAIL_N")
	)
	(segment
		(start 386.461 -93.32214)
		(end 386.461 -92.423488)
		(width 0.10795)
		(layer "B.Cu")
		(net "FM_MP_PS_FAIL_N")
	)
	(arc
		(start 386.546852 -97.258886)
		(mid 386.757716 -97.051882)
		(end 386.842 -96.768666)
		(width 0.0889)
		(layer "B.Cu")
		(net "FM_MP_PS_FAIL_N")
	)
	(arc
		(start 387.110224 -100.598224)
		(mid 387.053828 -100.545082)
		(end 386.9944 -100.495354)
		(width 0.0889)
		(layer "B.Cu")
		(net "FM_MP_PS_FAIL_N")
	)
	(arc
		(start 386.3467 -99.31146)
		(mid 386.40305 -99.11761)
		(end 386.546852 -98.975926)
		(width 0.0889)
		(layer "B.Cu")
		(net "FM_MP_PS_FAIL_N")
	)
	(arc
		(start 386.842 -100.159566)
		(mid 386.757719 -99.876349)
		(end 386.546852 -99.669346)
		(width 0.0889)
		(layer "B.Cu")
		(net "FM_MP_PS_FAIL_N")
	)
	(arc
		(start 386.546852 -98.975926)
		(mid 386.757716 -98.768922)
		(end 386.842 -98.485706)
		(width 0.0889)
		(layer "B.Cu")
		(net "FM_MP_PS_FAIL_N")
	)
	(arc
		(start 386.546852 -97.952306)
		(mid 386.403048 -97.810623)
		(end 386.3467 -97.616772)
		(width 0.0889)
		(layer "B.Cu")
		(net "FM_MP_PS_FAIL_N")
	)
	(arc
		(start 386.546852 -99.669346)
		(mid 386.403048 -99.527663)
		(end 386.3467 -99.333812)
		(width 0.0889)
		(layer "B.Cu")
		(net "FM_MP_PS_FAIL_N")
	)
	(arc
		(start 386.842 -96.725486)
		(mid 386.757719 -96.442269)
		(end 386.546852 -96.235266)
		(width 0.0889)
		(layer "B.Cu")
		(net "FM_MP_PS_FAIL_N")
	)
	(arc
		(start 386.842 -98.442526)
		(mid 386.757719 -98.159309)
		(end 386.546852 -97.952306)
		(width 0.0889)
		(layer "B.Cu")
		(net "FM_MP_PS_FAIL_N")
	)
	(arc
		(start 386.3467 -97.59442)
		(mid 386.40305 -97.40057)
		(end 386.546852 -97.258886)
		(width 0.0889)
		(layer "B.Cu")
		(net "FM_MP_PS_FAIL_N")
	)
	(arc
		(start 386.9944 -100.495354)
		(mid 386.884488 -100.360792)
		(end 386.842 -100.192332)
		(width 0.0889)
		(layer "B.Cu")
		(net "FM_MP_PS_FAIL_N")
	)
	(arc
		(start 386.546852 -96.235266)
		(mid 386.403048 -96.093583)
		(end 386.3467 -95.899732)
		(width 0.0889)
		(layer "B.Cu")
		(net "FM_MP_PS_FAIL_N")
	)
	(segment
		(start 391.620756 -45.089064)
		(end 391.798302 -45.089064)
		(width 0.089408)
		(layer "In2.Cu")
		(net "FM_MP_PS_FAIL_N")
	)
	(segment
		(start 179.836826 -0.147828)
		(end 180.071776 0.087122)
		(width 0.089408)
		(layer "In2.Cu")
		(net "FM_MP_PS_FAIL_N")
	)
	(segment
		(start 411.9118 -40.3606)
		(end 411.9118 -40.767)
		(width 0.089408)
		(layer "In2.Cu")
		(net "FM_MP_PS_FAIL_N")
	)
	(segment
		(start 391.957052 -45.088302)
		(end 391.957306 -45.088556)
		(width 0.089408)
		(layer "In2.Cu")
		(net "FM_MP_PS_FAIL_N")
	)
	(segment
		(start 390.458198 -46.771306)
		(end 390.458198 -46.454822)
		(width 0.089408)
		(layer "In2.Cu")
		(net "FM_MP_PS_FAIL_N")
	)
	(segment
		(start 390.241536 -60.11164)
		(end 390.241536 -59.52744)
		(width 0.089408)
		(layer "In2.Cu")
		(net "FM_MP_PS_FAIL_N")
	)
	(segment
		(start 388.807198 -71.702422)
		(end 388.807198 -70.237096)
		(width 0.089408)
		(layer "In2.Cu")
		(net "FM_MP_PS_FAIL_N")
	)
	(segment
		(start 390.6774 -51.612546)
		(end 390.6774 -47.46498)
		(width 0.089408)
		(layer "In2.Cu")
		(net "FM_MP_PS_FAIL_N")
	)
	(segment
		(start 388.62254 -83.354418)
		(end 388.62254 -84.641182)
		(width 0.089408)
		(layer "In2.Cu")
		(net "FM_MP_PS_FAIL_N")
	)
	(segment
		(start 391.482326 -52.417472)
		(end 390.6774 -51.612546)
		(width 0.089408)
		(layer "In2.Cu")
		(net "FM_MP_PS_FAIL_N")
	)
	(segment
		(start 391.096246 -64.42837)
		(end 391.096246 -60.96635)
		(width 0.089408)
		(layer "In2.Cu")
		(net "FM_MP_PS_FAIL_N")
	)
	(segment
		(start 411.6832 -40.132)
		(end 411.9118 -40.3606)
		(width 0.089408)
		(layer "In2.Cu")
		(net "FM_MP_PS_FAIL_N")
	)
	(segment
		(start 412.953708 -41.7322)
		(end 414.292542 -41.7322)
		(width 0.089408)
		(layer "In2.Cu")
		(net "FM_MP_PS_FAIL_N")
	)
	(segment
		(start 385.56819 -91.251786)
		(end 384.924808 -91.895168)
		(width 0.089408)
		(layer "In2.Cu")
		(net "FM_MP_PS_FAIL_N")
	)
	(segment
		(start 323.949568 4.722368)
		(end 327.408032 4.722368)
		(width 0.089408)
		(layer "In2.Cu")
		(net "FM_MP_PS_FAIL_N")
	)
	(segment
		(start 388.047738 -78.675992)
		(end 387.217412 -78.675992)
		(width 0.089408)
		(layer "In2.Cu")
		(net "FM_MP_PS_FAIL_N")
	)
	(segment
		(start 388.807198 -70.237096)
		(end 388.511288 -69.941186)
		(width 0.089408)
		(layer "In2.Cu")
		(net "FM_MP_PS_FAIL_N")
	)
	(segment
		(start 390.6774 -47.46498)
		(end 390.458706 -47.246286)
		(width 0.089408)
		(layer "In2.Cu")
		(net "FM_MP_PS_FAIL_N")
	)
	(segment
		(start 388.747 -73.0758)
		(end 388.747 -71.76262)
		(width 0.089408)
		(layer "In2.Cu")
		(net "FM_MP_PS_FAIL_N")
	)
	(segment
		(start 182.619396 3.093466)
		(end 184.223406 4.697476)
		(width 0.089408)
		(layer "In2.Cu")
		(net "FM_MP_PS_FAIL_N")
	)
	(segment
		(start 388.242048 -78.481682)
		(end 388.047738 -78.675992)
		(width 0.089408)
		(layer "In2.Cu")
		(net "FM_MP_PS_FAIL_N")
	)
	(segment
		(start 392.273536 -45.08881)
		(end 392.27379 -45.089064)
		(width 0.089408)
		(layer "In2.Cu")
		(net "FM_MP_PS_FAIL_N")
	)
	(segment
		(start 412.694628 -41.143428)
		(end 412.694628 -41.47312)
		(width 0.089408)
		(layer "In2.Cu")
		(net "FM_MP_PS_FAIL_N")
	)
	(segment
		(start 414.292542 -41.7322)
		(end 415.490152 -40.53459)
		(width 0.089408)
		(layer "In2.Cu")
		(net "FM_MP_PS_FAIL_N")
	)
	(segment
		(start 390.458452 -47.088044)
		(end 390.458452 -46.77156)
		(width 0.089408)
		(layer "In2.Cu")
		(net "FM_MP_PS_FAIL_N")
	)
	(segment
		(start 391.799064 -45.088302)
		(end 391.957052 -45.088302)
		(width 0.089408)
		(layer "In2.Cu")
		(net "FM_MP_PS_FAIL_N")
	)
	(segment
		(start 390.458452 -46.454568)
		(end 390.458452 -46.251368)
		(width 0.089408)
		(layer "In2.Cu")
		(net "FM_MP_PS_FAIL_N")
	)
	(segment
		(start 391.798302 -45.089064)
		(end 391.799064 -45.088302)
		(width 0.089408)
		(layer "In2.Cu")
		(net "FM_MP_PS_FAIL_N")
	)
	(segment
		(start 386.993892 -78.899512)
		(end 386.993892 -79.80934)
		(width 0.089408)
		(layer "In2.Cu")
		(net "FM_MP_PS_FAIL_N")
	)
	(segment
		(start 181.54142 3.093466)
		(end 182.619396 3.093466)
		(width 0.089408)
		(layer "In2.Cu")
		(net "FM_MP_PS_FAIL_N")
	)
	(segment
		(start 390.458706 -47.246286)
		(end 390.458706 -47.088298)
		(width 0.089408)
		(layer "In2.Cu")
		(net "FM_MP_PS_FAIL_N")
	)
	(segment
		(start 327.7362 4.3942)
		(end 327.7362 3.548634)
		(width 0.089408)
		(layer "In2.Cu")
		(net "FM_MP_PS_FAIL_N")
	)
	(segment
		(start 391.957306 -45.088556)
		(end 392.115294 -45.088556)
		(width 0.089408)
		(layer "In2.Cu")
		(net "FM_MP_PS_FAIL_N")
	)
	(segment
		(start 398.864074 -43.340274)
		(end 399.161 -43.6372)
		(width 0.089408)
		(layer "In2.Cu")
		(net "FM_MP_PS_FAIL_N")
	)
	(segment
		(start 403.252178 -40.5892)
		(end 406.8064 -40.5892)
		(width 0.089408)
		(layer "In2.Cu")
		(net "FM_MP_PS_FAIL_N")
	)
	(segment
		(start 265.042396 4.697476)
		(end 266.32916 3.410712)
		(width 0.089408)
		(layer "In2.Cu")
		(net "FM_MP_PS_FAIL_N")
	)
	(segment
		(start 397.028162 -43.340274)
		(end 398.864074 -43.340274)
		(width 0.089408)
		(layer "In2.Cu")
		(net "FM_MP_PS_FAIL_N")
	)
	(segment
		(start 388.242048 -76.148946)
		(end 388.242048 -78.481682)
		(width 0.089408)
		(layer "In2.Cu")
		(net "FM_MP_PS_FAIL_N")
	)
	(segment
		(start 396.16634 -44.202096)
		(end 397.028162 -43.340274)
		(width 0.089408)
		(layer "In2.Cu")
		(net "FM_MP_PS_FAIL_N")
	)
	(segment
		(start 386.57403 -85.46465)
		(end 385.008628 -87.030052)
		(width 0.089408)
		(layer "In2.Cu")
		(net "FM_MP_PS_FAIL_N")
	)
	(segment
		(start 406.8064 -40.5892)
		(end 407.2636 -40.132)
		(width 0.089408)
		(layer "In2.Cu")
		(net "FM_MP_PS_FAIL_N")
	)
	(segment
		(start 180.071776 0.087122)
		(end 180.071776 1.623822)
		(width 0.089408)
		(layer "In2.Cu")
		(net "FM_MP_PS_FAIL_N")
	)
	(segment
		(start 400.204178 -43.6372)
		(end 403.252178 -40.5892)
		(width 0.089408)
		(layer "In2.Cu")
		(net "FM_MP_PS_FAIL_N")
	)
	(segment
		(start 399.161 -43.6372)
		(end 400.204178 -43.6372)
		(width 0.089408)
		(layer "In2.Cu")
		(net "FM_MP_PS_FAIL_N")
	)
	(segment
		(start 387.799072 -85.46465)
		(end 386.57403 -85.46465)
		(width 0.089408)
		(layer "In2.Cu")
		(net "FM_MP_PS_FAIL_N")
	)
	(segment
		(start 390.458706 -47.088298)
		(end 390.458452 -47.088044)
		(width 0.089408)
		(layer "In2.Cu")
		(net "FM_MP_PS_FAIL_N")
	)
	(segment
		(start 327.408032 4.722368)
		(end 327.7362 4.3942)
		(width 0.089408)
		(layer "In2.Cu")
		(net "FM_MP_PS_FAIL_N")
	)
	(segment
		(start 392.115548 -45.08881)
		(end 392.273536 -45.08881)
		(width 0.089408)
		(layer "In2.Cu")
		(net "FM_MP_PS_FAIL_N")
	)
	(segment
		(start 391.482326 -58.28665)
		(end 391.482326 -52.417472)
		(width 0.089408)
		(layer "In2.Cu")
		(net "FM_MP_PS_FAIL_N")
	)
	(segment
		(start 322.637912 3.410712)
		(end 323.949568 4.722368)
		(width 0.089408)
		(layer "In2.Cu")
		(net "FM_MP_PS_FAIL_N")
	)
	(segment
		(start 388.61492 -75.776074)
		(end 388.242048 -76.148946)
		(width 0.089408)
		(layer "In2.Cu")
		(net "FM_MP_PS_FAIL_N")
	)
	(segment
		(start 387.217412 -78.675992)
		(end 386.993892 -78.899512)
		(width 0.089408)
		(layer "In2.Cu")
		(net "FM_MP_PS_FAIL_N")
	)
	(segment
		(start 412.694628 -41.47312)
		(end 412.953708 -41.7322)
		(width 0.089408)
		(layer "In2.Cu")
		(net "FM_MP_PS_FAIL_N")
	)
	(segment
		(start 391.096246 -60.96635)
		(end 390.241536 -60.11164)
		(width 0.089408)
		(layer "In2.Cu")
		(net "FM_MP_PS_FAIL_N")
	)
	(segment
		(start 385.008628 -89.330022)
		(end 385.56819 -89.889584)
		(width 0.089408)
		(layer "In2.Cu")
		(net "FM_MP_PS_FAIL_N")
	)
	(segment
		(start 184.223406 4.697476)
		(end 265.042396 4.697476)
		(width 0.089408)
		(layer "In2.Cu")
		(net "FM_MP_PS_FAIL_N")
	)
	(segment
		(start 388.747 -73.0758)
		(end 388.61492 -73.20788)
		(width 0.089408)
		(layer "In2.Cu")
		(net "FM_MP_PS_FAIL_N")
	)
	(segment
		(start 390.458198 -46.454822)
		(end 390.458452 -46.454568)
		(width 0.089408)
		(layer "In2.Cu")
		(net "FM_MP_PS_FAIL_N")
	)
	(segment
		(start 395.402054 -44.202096)
		(end 396.16634 -44.202096)
		(width 0.089408)
		(layer "In2.Cu")
		(net "FM_MP_PS_FAIL_N")
	)
	(segment
		(start 178.08448 -4.983226)
		(end 179.836826 -3.23088)
		(width 0.089408)
		(layer "In2.Cu")
		(net "FM_MP_PS_FAIL_N")
	)
	(segment
		(start 384.924808 -91.895168)
		(end 383.614168 -91.895168)
		(width 0.089408)
		(layer "In2.Cu")
		(net "FM_MP_PS_FAIL_N")
	)
	(segment
		(start 327.7362 3.548634)
		(end 328.71664 2.568194)
		(width 0.089408)
		(layer "In2.Cu")
		(net "FM_MP_PS_FAIL_N")
	)
	(segment
		(start 392.115294 -45.088556)
		(end 392.115548 -45.08881)
		(width 0.089408)
		(layer "In2.Cu")
		(net "FM_MP_PS_FAIL_N")
	)
	(segment
		(start 407.2636 -40.132)
		(end 411.6832 -40.132)
		(width 0.089408)
		(layer "In2.Cu")
		(net "FM_MP_PS_FAIL_N")
	)
	(segment
		(start 394.515086 -45.089064)
		(end 395.402054 -44.202096)
		(width 0.089408)
		(layer "In2.Cu")
		(net "FM_MP_PS_FAIL_N")
	)
	(segment
		(start 266.32916 3.410712)
		(end 322.637912 3.410712)
		(width 0.089408)
		(layer "In2.Cu")
		(net "FM_MP_PS_FAIL_N")
	)
	(segment
		(start 386.993892 -79.80934)
		(end 387.520942 -80.33639)
		(width 0.089408)
		(layer "In2.Cu")
		(net "FM_MP_PS_FAIL_N")
	)
	(segment
		(start 388.511288 -69.941186)
		(end 388.511288 -67.013328)
		(width 0.089408)
		(layer "In2.Cu")
		(net "FM_MP_PS_FAIL_N")
	)
	(segment
		(start 390.458452 -46.251368)
		(end 391.620756 -45.089064)
		(width 0.089408)
		(layer "In2.Cu")
		(net "FM_MP_PS_FAIL_N")
	)
	(segment
		(start 388.747 -71.76262)
		(end 388.807198 -71.702422)
		(width 0.089408)
		(layer "In2.Cu")
		(net "FM_MP_PS_FAIL_N")
	)
	(segment
		(start 385.56819 -89.889584)
		(end 385.56819 -91.251786)
		(width 0.089408)
		(layer "In2.Cu")
		(net "FM_MP_PS_FAIL_N")
	)
	(segment
		(start 383.614168 -91.895168)
		(end 382.8288 -91.1098)
		(width 0.089408)
		(layer "In2.Cu")
		(net "FM_MP_PS_FAIL_N")
	)
	(segment
		(start 179.836826 -3.23088)
		(end 179.836826 -0.147828)
		(width 0.089408)
		(layer "In2.Cu")
		(net "FM_MP_PS_FAIL_N")
	)
	(segment
		(start 328.71664 0.11684)
		(end 328.343768 -0.256032)
		(width 0.089408)
		(layer "In2.Cu")
		(net "FM_MP_PS_FAIL_N")
	)
	(segment
		(start 388.511288 -67.013328)
		(end 391.096246 -64.42837)
		(width 0.089408)
		(layer "In2.Cu")
		(net "FM_MP_PS_FAIL_N")
	)
	(segment
		(start 411.9118 -40.767)
		(end 412.0642 -40.9194)
		(width 0.089408)
		(layer "In2.Cu")
		(net "FM_MP_PS_FAIL_N")
	)
	(segment
		(start 388.61492 -73.20788)
		(end 388.61492 -75.776074)
		(width 0.089408)
		(layer "In2.Cu")
		(net "FM_MP_PS_FAIL_N")
	)
	(segment
		(start 387.520942 -82.25282)
		(end 388.62254 -83.354418)
		(width 0.089408)
		(layer "In2.Cu")
		(net "FM_MP_PS_FAIL_N")
	)
	(segment
		(start 390.241536 -59.52744)
		(end 391.482326 -58.28665)
		(width 0.089408)
		(layer "In2.Cu")
		(net "FM_MP_PS_FAIL_N")
	)
	(segment
		(start 392.27379 -45.089064)
		(end 394.515086 -45.089064)
		(width 0.089408)
		(layer "In2.Cu")
		(net "FM_MP_PS_FAIL_N")
	)
	(segment
		(start 387.520942 -80.33639)
		(end 387.520942 -82.25282)
		(width 0.089408)
		(layer "In2.Cu")
		(net "FM_MP_PS_FAIL_N")
	)
	(segment
		(start 385.008628 -87.030052)
		(end 385.008628 -89.330022)
		(width 0.089408)
		(layer "In2.Cu")
		(net "FM_MP_PS_FAIL_N")
	)
	(segment
		(start 412.4706 -40.9194)
		(end 412.694628 -41.143428)
		(width 0.089408)
		(layer "In2.Cu")
		(net "FM_MP_PS_FAIL_N")
	)
	(segment
		(start 328.71664 2.568194)
		(end 328.71664 0.11684)
		(width 0.089408)
		(layer "In2.Cu")
		(net "FM_MP_PS_FAIL_N")
	)
	(segment
		(start 388.62254 -84.641182)
		(end 387.799072 -85.46465)
		(width 0.089408)
		(layer "In2.Cu")
		(net "FM_MP_PS_FAIL_N")
	)
	(segment
		(start 412.0642 -40.9194)
		(end 412.4706 -40.9194)
		(width 0.089408)
		(layer "In2.Cu")
		(net "FM_MP_PS_FAIL_N")
	)
	(segment
		(start 390.458452 -46.77156)
		(end 390.458198 -46.771306)
		(width 0.089408)
		(layer "In2.Cu")
		(net "FM_MP_PS_FAIL_N")
	)
	(segment
		(start 180.071776 1.623822)
		(end 181.54142 3.093466)
		(width 0.089408)
		(layer "In2.Cu")
		(net "FM_MP_PS_FAIL_N")
	)
	(segment
		(start 377.9774 -73.3044)
		(end 377.786646 -73.495154)
		(width 0.089408)
		(layer "In4.Cu")
		(net "FM_MP_PS_FAIL_N")
	)
	(segment
		(start 388.09803 -72.42683)
		(end 385.743196 -72.42683)
		(width 0.089408)
		(layer "In4.Cu")
		(net "FM_MP_PS_FAIL_N")
	)
	(segment
		(start 377.786646 -73.495154)
		(end 376.744738 -73.495154)
		(width 0.089408)
		(layer "In4.Cu")
		(net "FM_MP_PS_FAIL_N")
	)
	(segment
		(start 385.403852 -72.42683)
		(end 382.81737 -72.42683)
		(width 0.089408)
		(layer "In4.Cu")
		(net "FM_MP_PS_FAIL_N")
	)
	(segment
		(start 379.083062 -72.7456)
		(end 378.524262 -73.3044)
		(width 0.089408)
		(layer "In4.Cu")
		(net "FM_MP_PS_FAIL_N")
	)
	(segment
		(start 385.743196 -72.42683)
		(end 385.739386 -72.42302)
		(width 0.089408)
		(layer "In4.Cu")
		(net "FM_MP_PS_FAIL_N")
	)
	(segment
		(start 378.524262 -73.3044)
		(end 377.9774 -73.3044)
		(width 0.089408)
		(layer "In4.Cu")
		(net "FM_MP_PS_FAIL_N")
	)
	(segment
		(start 382.81737 -72.42683)
		(end 382.4986 -72.7456)
		(width 0.089408)
		(layer "In4.Cu")
		(net "FM_MP_PS_FAIL_N")
	)
	(segment
		(start 385.739386 -72.42302)
		(end 385.407662 -72.42302)
		(width 0.089408)
		(layer "In4.Cu")
		(net "FM_MP_PS_FAIL_N")
	)
	(segment
		(start 382.4986 -72.7456)
		(end 379.083062 -72.7456)
		(width 0.089408)
		(layer "In4.Cu")
		(net "FM_MP_PS_FAIL_N")
	)
	(segment
		(start 388.747 -73.0758)
		(end 388.09803 -72.42683)
		(width 0.089408)
		(layer "In4.Cu")
		(net "FM_MP_PS_FAIL_N")
	)
	(segment
		(start 385.407662 -72.42302)
		(end 385.403852 -72.42683)
		(width 0.089408)
		(layer "In4.Cu")
		(net "FM_MP_PS_FAIL_N")
	)
	(segment
		(start 335.145888 -39.0906)
		(end 334.322166 -39.0906)
		(width 0.089408)
		(layer "In11.Cu")
		(net "FM_MP_PS_FAIL_N")
	)
	(segment
		(start 380.190248 -69.524372)
		(end 380.190248 -69.224144)
		(width 0.089408)
		(layer "In11.Cu")
		(net "FM_MP_PS_FAIL_N")
	)
	(segment
		(start 376.776488 -55.631842)
		(end 373.886222 -55.631842)
		(width 0.089408)
		(layer "In11.Cu")
		(net "FM_MP_PS_FAIL_N")
	)
	(segment
		(start 26.721054 -15.757652)
		(end 26.721054 -20.846542)
		(width 0.089408)
		(layer "In11.Cu")
		(net "FM_MP_PS_FAIL_N")
	)
	(segment
		(start 386.086858 -98.931476)
		(end 386.233162 -99.07778)
		(width 0.0889)
		(layer "In11.Cu")
		(net "FM_MP_PS_FAIL_N")
	)
	(segment
		(start 26.721054 -20.846542)
		(end 26.473912 -21.093684)
		(width 0.089408)
		(layer "In11.Cu")
		(net "FM_MP_PS_FAIL_N")
	)
	(segment
		(start 379.292104 -62.5094)
		(end 379.292104 -61.051694)
		(width 0.089408)
		(layer "In11.Cu")
		(net "FM_MP_PS_FAIL_N")
	)
	(segment
		(start 174.708058 -6.663182)
		(end 173.67377 -5.628894)
		(width 0.089408)
		(layer "In11.Cu")
		(net "FM_MP_PS_FAIL_N")
	)
	(segment
		(start 385.852924 -102.063296)
		(end 386.08635 -102.296722)
		(width 0.0889)
		(layer "In11.Cu")
		(net "FM_MP_PS_FAIL_N")
	)
	(segment
		(start 330.449428 -11.254232)
		(end 330.034138 -10.838942)
		(width 0.089408)
		(layer "In11.Cu")
		(net "FM_MP_PS_FAIL_N")
	)
	(segment
		(start 22.820122 -24.8412)
		(end 20.991322 -26.67)
		(width 0.089408)
		(layer "In11.Cu")
		(net "FM_MP_PS_FAIL_N")
	)
	(segment
		(start 373.886222 -55.631842)
		(end 371.22735 -52.97297)
		(width 0.089408)
		(layer "In11.Cu")
		(net "FM_MP_PS_FAIL_N")
	)
	(segment
		(start 378.087128 -63.714376)
		(end 379.292104 -62.5094)
		(width 0.089408)
		(layer "In11.Cu")
		(net "FM_MP_PS_FAIL_N")
	)
	(segment
		(start 334.322166 -39.0906)
		(end 332.931262 -37.699696)
		(width 0.089408)
		(layer "In11.Cu")
		(net "FM_MP_PS_FAIL_N")
	)
	(segment
		(start 354.651056 -38.9382)
		(end 353.379786 -40.20947)
		(width 0.089408)
		(layer "In11.Cu")
		(net "FM_MP_PS_FAIL_N")
	)
	(segment
		(start 178.08448 -4.983226)
		(end 176.404524 -6.663182)
		(width 0.089408)
		(layer "In11.Cu")
		(net "FM_MP_PS_FAIL_N")
	)
	(segment
		(start 330.034138 -10.838942)
		(end 330.034138 -10.233152)
		(width 0.089408)
		(layer "In11.Cu")
		(net "FM_MP_PS_FAIL_N")
	)
	(segment
		(start 385.26085 -97.589086)
		(end 385.26085 -97.622106)
		(width 0.089408)
		(layer "In11.Cu")
		(net "FM_MP_PS_FAIL_N")
	)
	(segment
		(start 377.925076 -56.78043)
		(end 376.776488 -55.631842)
		(width 0.089408)
		(layer "In11.Cu")
		(net "FM_MP_PS_FAIL_N")
	)
	(segment
		(start 167.694102 -3.86334)
		(end 166.97706 -3.146298)
		(width 0.089408)
		(layer "In11.Cu")
		(net "FM_MP_PS_FAIL_N")
	)
	(segment
		(start 26.142696 0.635762)
		(end 26.142696 -15.179294)
		(width 0.089408)
		(layer "In11.Cu")
		(net "FM_MP_PS_FAIL_N")
	)
	(segment
		(start 329.182984 -31.9786)
		(end 329.182984 -28.18638)
		(width 0.089408)
		(layer "In11.Cu")
		(net "FM_MP_PS_FAIL_N")
	)
	(segment
		(start 176.404524 -6.663182)
		(end 174.708058 -6.663182)
		(width 0.089408)
		(layer "In11.Cu")
		(net "FM_MP_PS_FAIL_N")
	)
	(segment
		(start 382.8288 -91.1098)
		(end 381.580644 -92.357956)
		(width 0.089408)
		(layer "In11.Cu")
		(net "FM_MP_PS_FAIL_N")
	)
	(segment
		(start 166.97706 -3.146298)
		(end 166.97706 -2.310638)
		(width 0.089408)
		(layer "In11.Cu")
		(net "FM_MP_PS_FAIL_N")
	)
	(segment
		(start 172.3136 -5.628894)
		(end 170.548046 -3.86334)
		(width 0.089408)
		(layer "In11.Cu")
		(net "FM_MP_PS_FAIL_N")
	)
	(segment
		(start 173.67377 -5.628894)
		(end 172.3136 -5.628894)
		(width 0.089408)
		(layer "In11.Cu")
		(net "FM_MP_PS_FAIL_N")
	)
	(segment
		(start 25.439878 -24.8412)
		(end 22.820122 -24.8412)
		(width 0.089408)
		(layer "In11.Cu")
		(net "FM_MP_PS_FAIL_N")
	)
	(segment
		(start 26.473912 -21.093684)
		(end 26.473912 -23.807166)
		(width 0.089408)
		(layer "In11.Cu")
		(net "FM_MP_PS_FAIL_N")
	)
	(segment
		(start 118.301516 3.39598)
		(end 103.248714 3.39598)
		(width 0.089408)
		(layer "In11.Cu")
		(net "FM_MP_PS_FAIL_N")
	)
	(segment
		(start 325.266558 -17.006062)
		(end 326.39508 -15.87754)
		(width 0.089408)
		(layer "In11.Cu")
		(net "FM_MP_PS_FAIL_N")
	)
	(segment
		(start 164.864288 3.113278)
		(end 164.154358 3.823208)
		(width 0.089408)
		(layer "In11.Cu")
		(net "FM_MP_PS_FAIL_N")
	)
	(segment
		(start 380.556008 -68.858384)
		(end 380.556008 -67.752976)
		(width 0.089408)
		(layer "In11.Cu")
		(net "FM_MP_PS_FAIL_N")
	)
	(segment
		(start 380.190248 -69.224144)
		(end 380.556008 -68.858384)
		(width 0.089408)
		(layer "In11.Cu")
		(net "FM_MP_PS_FAIL_N")
	)
	(segment
		(start 26.142696 -15.179294)
		(end 26.721054 -15.757652)
		(width 0.089408)
		(layer "In11.Cu")
		(net "FM_MP_PS_FAIL_N")
	)
	(segment
		(start 378.855732 -66.993008)
		(end 378.087128 -66.224404)
		(width 0.089408)
		(layer "In11.Cu")
		(net "FM_MP_PS_FAIL_N")
	)
	(segment
		(start 330.80579 -33.601406)
		(end 329.182984 -31.9786)
		(width 0.089408)
		(layer "In11.Cu")
		(net "FM_MP_PS_FAIL_N")
	)
	(segment
		(start 385.659376 -100.468684)
		(end 385.357624 -100.770436)
		(width 0.0889)
		(layer "In11.Cu")
		(net "FM_MP_PS_FAIL_N")
	)
	(segment
		(start 332.931262 -37.699696)
		(end 332.00213 -37.699696)
		(width 0.089408)
		(layer "In11.Cu")
		(net "FM_MP_PS_FAIL_N")
	)
	(segment
		(start 366.15243 -48.176434)
		(end 356.914196 -38.9382)
		(width 0.089408)
		(layer "In11.Cu")
		(net "FM_MP_PS_FAIL_N")
	)
	(segment
		(start 371.22735 -52.05222)
		(end 367.351564 -48.176434)
		(width 0.089408)
		(layer "In11.Cu")
		(net "FM_MP_PS_FAIL_N")
	)
	(segment
		(start 381.580644 -92.357956)
		(end 381.580644 -93.199712)
		(width 0.089408)
		(layer "In11.Cu")
		(net "FM_MP_PS_FAIL_N")
	)
	(segment
		(start 353.379786 -40.20947)
		(end 336.264758 -40.20947)
		(width 0.089408)
		(layer "In11.Cu")
		(net "FM_MP_PS_FAIL_N")
	)
	(segment
		(start 385.357624 -100.770436)
		(end 385.357624 -101.204776)
		(width 0.0889)
		(layer "In11.Cu")
		(net "FM_MP_PS_FAIL_N")
	)
	(segment
		(start 326.291194 -10.11174)
		(end 325.240396 -9.06145)
		(width 0.089408)
		(layer "In11.Cu")
		(net "FM_MP_PS_FAIL_N")
	)
	(segment
		(start 378.66701 -60.4266)
		(end 378.66701 -59.39282)
		(width 0.089408)
		(layer "In11.Cu")
		(net "FM_MP_PS_FAIL_N")
	)
	(segment
		(start 328.2188 -0.381)
		(end 328.343768 -0.256032)
		(width 0.089408)
		(layer "In11.Cu")
		(net "FM_MP_PS_FAIL_N")
	)
	(segment
		(start 170.548046 -3.86334)
		(end 167.694102 -3.86334)
		(width 0.089408)
		(layer "In11.Cu")
		(net "FM_MP_PS_FAIL_N")
	)
	(segment
		(start 103.248714 3.39598)
		(end 102.637336 4.007358)
		(width 0.089408)
		(layer "In11.Cu")
		(net "FM_MP_PS_FAIL_N")
	)
	(segment
		(start 164.154358 3.823208)
		(end 118.728744 3.823208)
		(width 0.089408)
		(layer "In11.Cu")
		(net "FM_MP_PS_FAIL_N")
	)
	(segment
		(start 385.75615 -98.447606)
		(end 385.75615 -98.480626)
		(width 0.089408)
		(layer "In11.Cu")
		(net "FM_MP_PS_FAIL_N")
	)
	(segment
		(start 384.76555 -96.730566)
		(end 384.76555 -96.763586)
		(width 0.089408)
		(layer "In11.Cu")
		(net "FM_MP_PS_FAIL_N")
	)
	(segment
		(start 329.182984 -28.18638)
		(end 325.266558 -24.269954)
		(width 0.089408)
		(layer "In11.Cu")
		(net "FM_MP_PS_FAIL_N")
	)
	(segment
		(start 381.580644 -93.199712)
		(end 383.428748 -95.047816)
		(width 0.089408)
		(layer "In11.Cu")
		(net "FM_MP_PS_FAIL_N")
	)
	(segment
		(start 118.728744 3.823208)
		(end 118.301516 3.39598)
		(width 0.089408)
		(layer "In11.Cu")
		(net "FM_MP_PS_FAIL_N")
	)
	(segment
		(start 378.66701 -59.39282)
		(end 377.925076 -58.650886)
		(width 0.089408)
		(layer "In11.Cu")
		(net "FM_MP_PS_FAIL_N")
	)
	(segment
		(start 385.357624 -101.204776)
		(end 385.852924 -101.700076)
		(width 0.0889)
		(layer "In11.Cu")
		(net "FM_MP_PS_FAIL_N")
	)
	(segment
		(start 332.00213 -37.699696)
		(end 330.80579 -36.503356)
		(width 0.089408)
		(layer "In11.Cu")
		(net "FM_MP_PS_FAIL_N")
	)
	(segment
		(start 336.264758 -40.20947)
		(end 335.145888 -39.0906)
		(width 0.089408)
		(layer "In11.Cu")
		(net "FM_MP_PS_FAIL_N")
	)
	(segment
		(start 385.852924 -101.700076)
		(end 385.852924 -102.063296)
		(width 0.0889)
		(layer "In11.Cu")
		(net "FM_MP_PS_FAIL_N")
	)
	(segment
		(start 378.087128 -66.224404)
		(end 378.087128 -63.714376)
		(width 0.089408)
		(layer "In11.Cu")
		(net "FM_MP_PS_FAIL_N")
	)
	(segment
		(start 379.79604 -66.993008)
		(end 378.855732 -66.993008)
		(width 0.089408)
		(layer "In11.Cu")
		(net "FM_MP_PS_FAIL_N")
	)
	(segment
		(start 386.233162 -99.07778)
		(end 386.233162 -99.536504)
		(width 0.0889)
		(layer "In11.Cu")
		(net "FM_MP_PS_FAIL_N")
	)
	(segment
		(start 367.351564 -48.176434)
		(end 366.15243 -48.176434)
		(width 0.089408)
		(layer "In11.Cu")
		(net "FM_MP_PS_FAIL_N")
	)
	(segment
		(start 386.233162 -99.536504)
		(end 385.659376 -100.11029)
		(width 0.0889)
		(layer "In11.Cu")
		(net "FM_MP_PS_FAIL_N")
	)
	(segment
		(start 102.637336 4.007358)
		(end 29.514292 4.007358)
		(width 0.089408)
		(layer "In11.Cu")
		(net "FM_MP_PS_FAIL_N")
	)
	(segment
		(start 384.27025 -95.47225)
		(end 384.27025 -95.905066)
		(width 0.089408)
		(layer "In11.Cu")
		(net "FM_MP_PS_FAIL_N")
	)
	(segment
		(start 26.473912 -23.807166)
		(end 25.439878 -24.8412)
		(width 0.089408)
		(layer "In11.Cu")
		(net "FM_MP_PS_FAIL_N")
	)
	(segment
		(start 330.80579 -36.503356)
		(end 330.80579 -33.601406)
		(width 0.089408)
		(layer "In11.Cu")
		(net "FM_MP_PS_FAIL_N")
	)
	(segment
		(start 164.864288 -0.197866)
		(end 164.864288 3.113278)
		(width 0.089408)
		(layer "In11.Cu")
		(net "FM_MP_PS_FAIL_N")
	)
	(segment
		(start 329.912726 -10.11174)
		(end 326.291194 -10.11174)
		(width 0.089408)
		(layer "In11.Cu")
		(net "FM_MP_PS_FAIL_N")
	)
	(segment
		(start 379.292104 -61.051694)
		(end 378.66701 -60.4266)
		(width 0.089408)
		(layer "In11.Cu")
		(net "FM_MP_PS_FAIL_N")
	)
	(segment
		(start 330.034138 -10.233152)
		(end 329.912726 -10.11174)
		(width 0.089408)
		(layer "In11.Cu")
		(net "FM_MP_PS_FAIL_N")
	)
	(segment
		(start 383.845816 -95.047816)
		(end 384.27025 -95.47225)
		(width 0.089408)
		(layer "In11.Cu")
		(net "FM_MP_PS_FAIL_N")
	)
	(segment
		(start 356.914196 -38.9382)
		(end 354.651056 -38.9382)
		(width 0.089408)
		(layer "In11.Cu")
		(net "FM_MP_PS_FAIL_N")
	)
	(segment
		(start 325.240396 -9.06145)
		(end 325.240396 -2.121662)
		(width 0.089408)
		(layer "In11.Cu")
		(net "FM_MP_PS_FAIL_N")
	)
	(segment
		(start 328.64806 -15.87754)
		(end 330.449428 -14.076172)
		(width 0.089408)
		(layer "In11.Cu")
		(net "FM_MP_PS_FAIL_N")
	)
	(segment
		(start 325.266558 -24.269954)
		(end 325.266558 -17.006062)
		(width 0.089408)
		(layer "In11.Cu")
		(net "FM_MP_PS_FAIL_N")
	)
	(segment
		(start 380.556008 -67.752976)
		(end 379.79604 -66.993008)
		(width 0.089408)
		(layer "In11.Cu")
		(net "FM_MP_PS_FAIL_N")
	)
	(segment
		(start 326.39508 -15.87754)
		(end 328.64806 -15.87754)
		(width 0.089408)
		(layer "In11.Cu")
		(net "FM_MP_PS_FAIL_N")
	)
	(segment
		(start 29.514292 4.007358)
		(end 26.142696 0.635762)
		(width 0.089408)
		(layer "In11.Cu")
		(net "FM_MP_PS_FAIL_N")
	)
	(segment
		(start 383.428748 -95.047816)
		(end 383.845816 -95.047816)
		(width 0.089408)
		(layer "In11.Cu")
		(net "FM_MP_PS_FAIL_N")
	)
	(segment
		(start 325.240396 -2.121662)
		(end 326.981058 -0.381)
		(width 0.089408)
		(layer "In11.Cu")
		(net "FM_MP_PS_FAIL_N")
	)
	(segment
		(start 386.08635 -102.296722)
		(end 387.834124 -102.296722)
		(width 0.0889)
		(layer "In11.Cu")
		(net "FM_MP_PS_FAIL_N")
	)
	(segment
		(start 166.97706 -2.310638)
		(end 164.864288 -0.197866)
		(width 0.089408)
		(layer "In11.Cu")
		(net "FM_MP_PS_FAIL_N")
	)
	(segment
		(start 377.925076 -58.650886)
		(end 377.925076 -56.78043)
		(width 0.089408)
		(layer "In11.Cu")
		(net "FM_MP_PS_FAIL_N")
	)
	(segment
		(start 385.659376 -100.11029)
		(end 385.659376 -100.468684)
		(width 0.0889)
		(layer "In11.Cu")
		(net "FM_MP_PS_FAIL_N")
	)
	(segment
		(start 387.834124 -102.296722)
		(end 388.23265 -101.898196)
		(width 0.0889)
		(layer "In11.Cu")
		(net "FM_MP_PS_FAIL_N")
	)
	(segment
		(start 371.22735 -52.97297)
		(end 371.22735 -52.05222)
		(width 0.089408)
		(layer "In11.Cu")
		(net "FM_MP_PS_FAIL_N")
	)
	(segment
		(start 326.981058 -0.381)
		(end 328.2188 -0.381)
		(width 0.089408)
		(layer "In11.Cu")
		(net "FM_MP_PS_FAIL_N")
	)
	(segment
		(start 330.449428 -14.076172)
		(end 330.449428 -11.254232)
		(width 0.089408)
		(layer "In11.Cu")
		(net "FM_MP_PS_FAIL_N")
	)
	(arc
		(start 385.26085 -97.622106)
		(mid 385.331198 -97.860567)
		(end 385.5085 -98.034856)
		(width 0.089408)
		(layer "In11.Cu")
		(net "FM_MP_PS_FAIL_N")
	)
	(arc
		(start 385.5085 -98.034856)
		(mid 385.685802 -98.209145)
		(end 385.75615 -98.447606)
		(width 0.089408)
		(layer "In11.Cu")
		(net "FM_MP_PS_FAIL_N")
	)
	(arc
		(start 384.5179 -96.317816)
		(mid 384.695202 -96.492105)
		(end 384.76555 -96.730566)
		(width 0.089408)
		(layer "In11.Cu")
		(net "FM_MP_PS_FAIL_N")
	)
	(arc
		(start 384.27025 -95.905066)
		(mid 384.340598 -96.143527)
		(end 384.5179 -96.317816)
		(width 0.089408)
		(layer "In11.Cu")
		(net "FM_MP_PS_FAIL_N")
	)
	(arc
		(start 384.76555 -96.763586)
		(mid 384.835898 -97.002047)
		(end 385.0132 -97.176336)
		(width 0.089408)
		(layer "In11.Cu")
		(net "FM_MP_PS_FAIL_N")
	)
	(arc
		(start 385.0132 -97.176336)
		(mid 385.190502 -97.350625)
		(end 385.26085 -97.589086)
		(width 0.089408)
		(layer "In11.Cu")
		(net "FM_MP_PS_FAIL_N")
	)
	(arc
		(start 385.75615 -98.480626)
		(mid 385.851817 -98.757183)
		(end 386.086858 -98.931476)
		(width 0.089408)
		(layer "In11.Cu")
		(net "FM_MP_PS_FAIL_N")
	)
	(segment
		(start 367.145316 -69.495162)
		(end 367.545112 -69.894958)
		(width 0.1016)
		(layer "F.Cu")
		(net "FM_DB1200_PWRGD")
	)
	(segment
		(start 168.07942 -73.106026)
		(end 167.952928 -72.979534)
		(width 0.10795)
		(layer "F.Cu")
		(net "FM_DB1200_PWRGD")
	)
	(segment
		(start 168.07942 -73.662032)
		(end 168.07942 -73.106026)
		(width 0.10795)
		(layer "F.Cu")
		(net "FM_DB1200_PWRGD")
	)
	(via
		(at 167.952928 -72.979534)
		(size 0.508)
		(drill 0.254)
		(layers "F.Cu" "B.Cu")
		(net "FM_DB1200_PWRGD")
	)
	(via
		(at 320.692526 -37.389054)
		(size 0.508)
		(drill 0.254)
		(layers "F.Cu" "B.Cu")
		(net "FM_DB1200_PWRGD")
	)
	(via
		(at 168.347644 -70.633336)
		(size 0.508)
		(drill 0.254)
		(layers "F.Cu" "B.Cu")
		(net "FM_DB1200_PWRGD")
	)
	(via
		(at 373.787416 -62.556898)
		(size 0.508)
		(drill 0.254)
		(layers "F.Cu" "B.Cu")
		(net "FM_DB1200_PWRGD")
	)
	(via
		(at 367.145316 -69.495162)
		(size 0.4572)
		(drill 0.2032)
		(layers "F.Cu" "B.Cu")
		(net "FM_DB1200_PWRGD")
	)
	(via
		(at 194.773296 -21.829522)
		(size 0.508)
		(drill 0.254)
		(layers "F.Cu" "B.Cu")
		(net "FM_DB1200_PWRGD")
	)
	(segment
		(start 168.76141 -69.67728)
		(end 168.76141 -70.21957)
		(width 0.10795)
		(layer "B.Cu")
		(net "FM_DB1200_PWRGD")
	)
	(segment
		(start 173.279816 -68.650104)
		(end 172.615352 -68.650104)
		(width 0.10795)
		(layer "B.Cu")
		(net "FM_DB1200_PWRGD")
	)
	(segment
		(start 172.615352 -68.650104)
		(end 172.165264 -69.100192)
		(width 0.10795)
		(layer "B.Cu")
		(net "FM_DB1200_PWRGD")
	)
	(segment
		(start 169.338498 -69.100192)
		(end 168.76141 -69.67728)
		(width 0.10795)
		(layer "B.Cu")
		(net "FM_DB1200_PWRGD")
	)
	(segment
		(start 168.76141 -70.21957)
		(end 168.347644 -70.633336)
		(width 0.10795)
		(layer "B.Cu")
		(net "FM_DB1200_PWRGD")
	)
	(segment
		(start 172.165264 -69.100192)
		(end 169.338498 -69.100192)
		(width 0.10795)
		(layer "B.Cu")
		(net "FM_DB1200_PWRGD")
	)
	(segment
		(start 371.042438 -63.374016)
		(end 370.261134 -64.15532)
		(width 0.089408)
		(layer "In9.Cu")
		(net "FM_DB1200_PWRGD")
	)
	(segment
		(start 313.202066 -32.579818)
		(end 306.425092 -25.802844)
		(width 0.089408)
		(layer "In9.Cu")
		(net "FM_DB1200_PWRGD")
	)
	(segment
		(start 244.587776 -24.252936)
		(end 243.32184 -22.987)
		(width 0.089408)
		(layer "In9.Cu")
		(net "FM_DB1200_PWRGD")
	)
	(segment
		(start 373.787416 -62.556898)
		(end 372.971314 -63.373)
		(width 0.089408)
		(layer "In9.Cu")
		(net "FM_DB1200_PWRGD")
	)
	(segment
		(start 241.4905 -22.734778)
		(end 241.4905 -22.603968)
		(width 0.089408)
		(layer "In9.Cu")
		(net "FM_DB1200_PWRGD")
	)
	(segment
		(start 263.745218 -27.00782)
		(end 262.394954 -27.00782)
		(width 0.089408)
		(layer "In9.Cu")
		(net "FM_DB1200_PWRGD")
	)
	(segment
		(start 367.518696 -68.87083)
		(end 367.145316 -69.24421)
		(width 0.089408)
		(layer "In9.Cu")
		(net "FM_DB1200_PWRGD")
	)
	(segment
		(start 372.971314 -63.373)
		(end 372.191026 -63.373)
		(width 0.089408)
		(layer "In9.Cu")
		(net "FM_DB1200_PWRGD")
	)
	(segment
		(start 319.644776 -37.555424)
		(end 317.677038 -37.555424)
		(width 0.089408)
		(layer "In9.Cu")
		(net "FM_DB1200_PWRGD")
	)
	(segment
		(start 306.425092 -25.802844)
		(end 279.152604 -25.802844)
		(width 0.089408)
		(layer "In9.Cu")
		(net "FM_DB1200_PWRGD")
	)
	(segment
		(start 368.780314 -64.15532)
		(end 368.458496 -64.477138)
		(width 0.089408)
		(layer "In9.Cu")
		(net "FM_DB1200_PWRGD")
	)
	(segment
		(start 259.932932 -24.545798)
		(end 246.047514 -24.545798)
		(width 0.089408)
		(layer "In9.Cu")
		(net "FM_DB1200_PWRGD")
	)
	(segment
		(start 262.394954 -27.00782)
		(end 259.932932 -24.545798)
		(width 0.089408)
		(layer "In9.Cu")
		(net "FM_DB1200_PWRGD")
	)
	(segment
		(start 279.152604 -25.802844)
		(end 275.570696 -29.384752)
		(width 0.089408)
		(layer "In9.Cu")
		(net "FM_DB1200_PWRGD")
	)
	(segment
		(start 319.811146 -37.389054)
		(end 319.644776 -37.555424)
		(width 0.089408)
		(layer "In9.Cu")
		(net "FM_DB1200_PWRGD")
	)
	(segment
		(start 195.382134 -20.82038)
		(end 194.773296 -21.429218)
		(width 0.089408)
		(layer "In9.Cu")
		(net "FM_DB1200_PWRGD")
	)
	(segment
		(start 313.202066 -33.080452)
		(end 313.202066 -32.579818)
		(width 0.089408)
		(layer "In9.Cu")
		(net "FM_DB1200_PWRGD")
	)
	(segment
		(start 275.570696 -29.384752)
		(end 266.12215 -29.384752)
		(width 0.089408)
		(layer "In9.Cu")
		(net "FM_DB1200_PWRGD")
	)
	(segment
		(start 317.677038 -37.555424)
		(end 313.202066 -33.080452)
		(width 0.089408)
		(layer "In9.Cu")
		(net "FM_DB1200_PWRGD")
	)
	(segment
		(start 239.706912 -20.82038)
		(end 195.382134 -20.82038)
		(width 0.089408)
		(layer "In9.Cu")
		(net "FM_DB1200_PWRGD")
	)
	(segment
		(start 245.754652 -24.252936)
		(end 244.587776 -24.252936)
		(width 0.089408)
		(layer "In9.Cu")
		(net "FM_DB1200_PWRGD")
	)
	(segment
		(start 242.58524 -23.36546)
		(end 242.121182 -23.36546)
		(width 0.089408)
		(layer "In9.Cu")
		(net "FM_DB1200_PWRGD")
	)
	(segment
		(start 241.4905 -22.603968)
		(end 239.706912 -20.82038)
		(width 0.089408)
		(layer "In9.Cu")
		(net "FM_DB1200_PWRGD")
	)
	(segment
		(start 372.19001 -63.374016)
		(end 371.042438 -63.374016)
		(width 0.089408)
		(layer "In9.Cu")
		(net "FM_DB1200_PWRGD")
	)
	(segment
		(start 372.191026 -63.373)
		(end 372.19001 -63.374016)
		(width 0.089408)
		(layer "In9.Cu")
		(net "FM_DB1200_PWRGD")
	)
	(segment
		(start 242.121182 -23.36546)
		(end 241.4905 -22.734778)
		(width 0.089408)
		(layer "In9.Cu")
		(net "FM_DB1200_PWRGD")
	)
	(segment
		(start 266.12215 -29.384752)
		(end 263.745218 -27.00782)
		(width 0.089408)
		(layer "In9.Cu")
		(net "FM_DB1200_PWRGD")
	)
	(segment
		(start 367.145316 -69.24421)
		(end 367.145316 -69.495162)
		(width 0.089408)
		(layer "In9.Cu")
		(net "FM_DB1200_PWRGD")
	)
	(segment
		(start 320.692526 -37.389054)
		(end 319.811146 -37.389054)
		(width 0.089408)
		(layer "In9.Cu")
		(net "FM_DB1200_PWRGD")
	)
	(segment
		(start 370.261134 -64.15532)
		(end 368.780314 -64.15532)
		(width 0.089408)
		(layer "In9.Cu")
		(net "FM_DB1200_PWRGD")
	)
	(segment
		(start 194.773296 -21.429218)
		(end 194.773296 -21.829522)
		(width 0.089408)
		(layer "In9.Cu")
		(net "FM_DB1200_PWRGD")
	)
	(segment
		(start 242.9637 -22.987)
		(end 242.58524 -23.36546)
		(width 0.089408)
		(layer "In9.Cu")
		(net "FM_DB1200_PWRGD")
	)
	(segment
		(start 243.32184 -22.987)
		(end 242.9637 -22.987)
		(width 0.089408)
		(layer "In9.Cu")
		(net "FM_DB1200_PWRGD")
	)
	(segment
		(start 246.047514 -24.545798)
		(end 245.754652 -24.252936)
		(width 0.089408)
		(layer "In9.Cu")
		(net "FM_DB1200_PWRGD")
	)
	(segment
		(start 367.518696 -66.831464)
		(end 367.518696 -68.87083)
		(width 0.089408)
		(layer "In9.Cu")
		(net "FM_DB1200_PWRGD")
	)
	(segment
		(start 368.458496 -64.477138)
		(end 368.458496 -65.891664)
		(width 0.089408)
		(layer "In9.Cu")
		(net "FM_DB1200_PWRGD")
	)
	(segment
		(start 368.458496 -65.891664)
		(end 367.518696 -66.831464)
		(width 0.089408)
		(layer "In9.Cu")
		(net "FM_DB1200_PWRGD")
	)
	(segment
		(start 165.89248 -64.63792)
		(end 165.207696 -65.322704)
		(width 0.089408)
		(layer "In11.Cu")
		(net "FM_DB1200_PWRGD")
	)
	(segment
		(start 167.952928 -72.979534)
		(end 167.7416 -72.768206)
		(width 0.089408)
		(layer "In11.Cu")
		(net "FM_DB1200_PWRGD")
	)
	(segment
		(start 319.435988 -36.49599)
		(end 319.435988 -41.793922)
		(width 0.089408)
		(layer "In11.Cu")
		(net "FM_DB1200_PWRGD")
	)
	(segment
		(start 167.7416 -72.768206)
		(end 167.7416 -72.008492)
		(width 0.089408)
		(layer "In11.Cu")
		(net "FM_DB1200_PWRGD")
	)
	(segment
		(start 187.96 -30.5054)
		(end 168.016682 -50.448718)
		(width 0.089408)
		(layer "In11.Cu")
		(net "FM_DB1200_PWRGD")
	)
	(segment
		(start 194.773296 -21.829522)
		(end 191.406018 -25.1968)
		(width 0.089408)
		(layer "In11.Cu")
		(net "FM_DB1200_PWRGD")
	)
	(segment
		(start 191.406018 -25.1968)
		(end 188.4934 -25.1968)
		(width 0.089408)
		(layer "In11.Cu")
		(net "FM_DB1200_PWRGD")
	)
	(segment
		(start 372.700296 -61.913262)
		(end 372.934738 -62.147704)
		(width 0.089408)
		(layer "In11.Cu")
		(net "FM_DB1200_PWRGD")
	)
	(segment
		(start 373.378222 -62.147704)
		(end 373.787416 -62.556898)
		(width 0.089408)
		(layer "In11.Cu")
		(net "FM_DB1200_PWRGD")
	)
	(segment
		(start 168.531794 -70.817486)
		(end 168.347644 -70.633336)
		(width 0.089408)
		(layer "In11.Cu")
		(net "FM_DB1200_PWRGD")
	)
	(segment
		(start 320.237104 -42.595038)
		(end 320.237104 -43.190668)
		(width 0.089408)
		(layer "In11.Cu")
		(net "FM_DB1200_PWRGD")
	)
	(segment
		(start 166.204392 -70.529958)
		(end 168.244266 -70.529958)
		(width 0.089408)
		(layer "In11.Cu")
		(net "FM_DB1200_PWRGD")
	)
	(segment
		(start 359.455974 -51.646836)
		(end 360.83875 -51.646836)
		(width 0.089408)
		(layer "In11.Cu")
		(net "FM_DB1200_PWRGD")
	)
	(segment
		(start 366.447832 -55.519066)
		(end 372.700296 -61.771022)
		(width 0.089408)
		(layer "In11.Cu")
		(net "FM_DB1200_PWRGD")
	)
	(segment
		(start 321.023488 -43.977052)
		(end 323.386958 -43.977052)
		(width 0.089408)
		(layer "In11.Cu")
		(net "FM_DB1200_PWRGD")
	)
	(segment
		(start 322.580254 -36.265612)
		(end 322.580254 -35.933888)
		(width 0.089408)
		(layer "In11.Cu")
		(net "FM_DB1200_PWRGD")
	)
	(segment
		(start 322.580254 -35.933888)
		(end 321.942968 -35.296602)
		(width 0.089408)
		(layer "In11.Cu")
		(net "FM_DB1200_PWRGD")
	)
	(segment
		(start 323.386958 -43.977052)
		(end 328.796904 -49.386998)
		(width 0.089408)
		(layer "In11.Cu")
		(net "FM_DB1200_PWRGD")
	)
	(segment
		(start 165.89248 -64.14516)
		(end 165.89248 -64.63792)
		(width 0.089408)
		(layer "In11.Cu")
		(net "FM_DB1200_PWRGD")
	)
	(segment
		(start 319.435988 -41.793922)
		(end 320.237104 -42.595038)
		(width 0.089408)
		(layer "In11.Cu")
		(net "FM_DB1200_PWRGD")
	)
	(segment
		(start 187.96 -25.7302)
		(end 187.96 -30.5054)
		(width 0.089408)
		(layer "In11.Cu")
		(net "FM_DB1200_PWRGD")
	)
	(segment
		(start 168.016682 -60.811918)
		(end 166.085774 -62.742826)
		(width 0.089408)
		(layer "In11.Cu")
		(net "FM_DB1200_PWRGD")
	)
	(segment
		(start 188.4934 -25.1968)
		(end 187.96 -25.7302)
		(width 0.089408)
		(layer "In11.Cu")
		(net "FM_DB1200_PWRGD")
	)
	(segment
		(start 168.531794 -71.218298)
		(end 168.531794 -70.817486)
		(width 0.089408)
		(layer "In11.Cu")
		(net "FM_DB1200_PWRGD")
	)
	(segment
		(start 364.71098 -55.519066)
		(end 366.447832 -55.519066)
		(width 0.089408)
		(layer "In11.Cu")
		(net "FM_DB1200_PWRGD")
	)
	(segment
		(start 372.934738 -62.147704)
		(end 373.378222 -62.147704)
		(width 0.089408)
		(layer "In11.Cu")
		(net "FM_DB1200_PWRGD")
	)
	(segment
		(start 357.196136 -49.386998)
		(end 359.455974 -51.646836)
		(width 0.089408)
		(layer "In11.Cu")
		(net "FM_DB1200_PWRGD")
	)
	(segment
		(start 166.085774 -62.742826)
		(end 166.085774 -63.951866)
		(width 0.089408)
		(layer "In11.Cu")
		(net "FM_DB1200_PWRGD")
	)
	(segment
		(start 322.180966 -36.6649)
		(end 322.580254 -36.265612)
		(width 0.089408)
		(layer "In11.Cu")
		(net "FM_DB1200_PWRGD")
	)
	(segment
		(start 168.016682 -50.448718)
		(end 168.016682 -60.811918)
		(width 0.089408)
		(layer "In11.Cu")
		(net "FM_DB1200_PWRGD")
	)
	(segment
		(start 360.83875 -51.646836)
		(end 364.71098 -55.519066)
		(width 0.089408)
		(layer "In11.Cu")
		(net "FM_DB1200_PWRGD")
	)
	(segment
		(start 321.41668 -36.6649)
		(end 322.180966 -36.6649)
		(width 0.089408)
		(layer "In11.Cu")
		(net "FM_DB1200_PWRGD")
	)
	(segment
		(start 167.7416 -72.008492)
		(end 168.531794 -71.218298)
		(width 0.089408)
		(layer "In11.Cu")
		(net "FM_DB1200_PWRGD")
	)
	(segment
		(start 320.635376 -35.296602)
		(end 319.435988 -36.49599)
		(width 0.089408)
		(layer "In11.Cu")
		(net "FM_DB1200_PWRGD")
	)
	(segment
		(start 372.700296 -61.771022)
		(end 372.700296 -61.913262)
		(width 0.089408)
		(layer "In11.Cu")
		(net "FM_DB1200_PWRGD")
	)
	(segment
		(start 168.244266 -70.529958)
		(end 168.347644 -70.633336)
		(width 0.089408)
		(layer "In11.Cu")
		(net "FM_DB1200_PWRGD")
	)
	(segment
		(start 320.692526 -37.389054)
		(end 321.41668 -36.6649)
		(width 0.089408)
		(layer "In11.Cu")
		(net "FM_DB1200_PWRGD")
	)
	(segment
		(start 321.942968 -35.296602)
		(end 320.635376 -35.296602)
		(width 0.089408)
		(layer "In11.Cu")
		(net "FM_DB1200_PWRGD")
	)
	(segment
		(start 166.085774 -63.951866)
		(end 165.89248 -64.14516)
		(width 0.089408)
		(layer "In11.Cu")
		(net "FM_DB1200_PWRGD")
	)
	(segment
		(start 165.207696 -69.533262)
		(end 166.204392 -70.529958)
		(width 0.089408)
		(layer "In11.Cu")
		(net "FM_DB1200_PWRGD")
	)
	(segment
		(start 320.237104 -43.190668)
		(end 321.023488 -43.977052)
		(width 0.089408)
		(layer "In11.Cu")
		(net "FM_DB1200_PWRGD")
	)
	(segment
		(start 328.796904 -49.386998)
		(end 357.196136 -49.386998)
		(width 0.089408)
		(layer "In11.Cu")
		(net "FM_DB1200_PWRGD")
	)
	(segment
		(start 165.207696 -65.322704)
		(end 165.207696 -69.533262)
		(width 0.089408)
		(layer "In11.Cu")
		(net "FM_DB1200_PWRGD")
	)
	(segment
		(start 382.817116 -88.748616)
		(end 382.817116 -89.6874)
		(width 0.10795)
		(layer "F.Cu")
		(net "IRQ_PIRQA_SPI_TPM_N")
	)
	(segment
		(start 417.8935 -63.62954)
		(end 417.8935 -64.135)
		(width 0.10795)
		(layer "F.Cu")
		(net "IRQ_PIRQA_SPI_TPM_N")
	)
	(segment
		(start 382.27 -88.2015)
		(end 382.817116 -88.748616)
		(width 0.10795)
		(layer "F.Cu")
		(net "IRQ_PIRQA_SPI_TPM_N")
	)
	(segment
		(start 382.817116 -89.6874)
		(end 383.528824 -90.399108)
		(width 0.0889)
		(layer "F.Cu")
		(net "IRQ_PIRQA_SPI_TPM_N")
	)
	(segment
		(start 383.528824 -93.915992)
		(end 383.484882 -93.959934)
		(width 0.0889)
		(layer "F.Cu")
		(net "IRQ_PIRQA_SPI_TPM_N")
	)
	(segment
		(start 383.65049 -91.873578)
		(end 383.65049 -92.540328)
		(width 0.0889)
		(layer "F.Cu")
		(net "IRQ_PIRQA_SPI_TPM_N")
	)
	(segment
		(start 417.51885 -62.518798)
		(end 417.51885 -63.25489)
		(width 0.10795)
		(layer "F.Cu")
		(net "IRQ_PIRQA_SPI_TPM_N")
	)
	(segment
		(start 383.528824 -92.661994)
		(end 383.528824 -93.915992)
		(width 0.0889)
		(layer "F.Cu")
		(net "IRQ_PIRQA_SPI_TPM_N")
	)
	(segment
		(start 383.65049 -92.540328)
		(end 383.528824 -92.661994)
		(width 0.0889)
		(layer "F.Cu")
		(net "IRQ_PIRQA_SPI_TPM_N")
	)
	(segment
		(start 383.528824 -91.751912)
		(end 383.65049 -91.873578)
		(width 0.0889)
		(layer "F.Cu")
		(net "IRQ_PIRQA_SPI_TPM_N")
	)
	(segment
		(start 417.51885 -63.25489)
		(end 417.8935 -63.62954)
		(width 0.10795)
		(layer "F.Cu")
		(net "IRQ_PIRQA_SPI_TPM_N")
	)
	(segment
		(start 383.528824 -90.399108)
		(end 383.528824 -91.751912)
		(width 0.0889)
		(layer "F.Cu")
		(net "IRQ_PIRQA_SPI_TPM_N")
	)
	(via
		(at 417.51885 -62.518798)
		(size 0.508)
		(drill 0.254)
		(layers "F.Cu" "B.Cu")
		(net "IRQ_PIRQA_SPI_TPM_N")
	)
	(via
		(at 386.98932 -60.44184)
		(size 0.508)
		(drill 0.254)
		(layers "F.Cu" "B.Cu")
		(net "IRQ_PIRQA_SPI_TPM_N")
	)
	(via
		(at 382.817116 -89.6874)
		(size 0.508)
		(drill 0.254)
		(layers "F.Cu" "B.Cu")
		(net "IRQ_PIRQA_SPI_TPM_N")
	)
	(segment
		(start 387.428994 -62.46114)
		(end 387.915404 -62.94755)
		(width 0.089408)
		(layer "In2.Cu")
		(net "IRQ_PIRQA_SPI_TPM_N")
	)
	(segment
		(start 384.715512 -73.588626)
		(end 385.139692 -74.012806)
		(width 0.089408)
		(layer "In2.Cu")
		(net "IRQ_PIRQA_SPI_TPM_N")
	)
	(segment
		(start 383.320544 -88.740996)
		(end 382.817116 -89.244424)
		(width 0.089408)
		(layer "In2.Cu")
		(net "IRQ_PIRQA_SPI_TPM_N")
	)
	(segment
		(start 383.378456 -80.261714)
		(end 383.378456 -82.947002)
		(width 0.089408)
		(layer "In2.Cu")
		(net "IRQ_PIRQA_SPI_TPM_N")
	)
	(segment
		(start 382.817116 -89.244424)
		(end 382.817116 -89.6874)
		(width 0.089408)
		(layer "In2.Cu")
		(net "IRQ_PIRQA_SPI_TPM_N")
	)
	(segment
		(start 385.139692 -77.325474)
		(end 383.842514 -78.622652)
		(width 0.089408)
		(layer "In2.Cu")
		(net "IRQ_PIRQA_SPI_TPM_N")
	)
	(segment
		(start 383.842514 -79.797656)
		(end 383.378456 -80.261714)
		(width 0.089408)
		(layer "In2.Cu")
		(net "IRQ_PIRQA_SPI_TPM_N")
	)
	(segment
		(start 383.378456 -82.947002)
		(end 383.126488 -83.19897)
		(width 0.089408)
		(layer "In2.Cu")
		(net "IRQ_PIRQA_SPI_TPM_N")
	)
	(segment
		(start 385.979162 -69.137784)
		(end 384.532124 -70.584822)
		(width 0.089408)
		(layer "In2.Cu")
		(net "IRQ_PIRQA_SPI_TPM_N")
	)
	(segment
		(start 387.428994 -61.029342)
		(end 387.428994 -62.46114)
		(width 0.089408)
		(layer "In2.Cu")
		(net "IRQ_PIRQA_SPI_TPM_N")
	)
	(segment
		(start 386.98932 -60.44184)
		(end 386.98932 -60.589668)
		(width 0.089408)
		(layer "In2.Cu")
		(net "IRQ_PIRQA_SPI_TPM_N")
	)
	(segment
		(start 385.979162 -64.489838)
		(end 385.979162 -69.137784)
		(width 0.089408)
		(layer "In2.Cu")
		(net "IRQ_PIRQA_SPI_TPM_N")
	)
	(segment
		(start 383.320544 -85.167724)
		(end 383.320544 -88.740996)
		(width 0.089408)
		(layer "In2.Cu")
		(net "IRQ_PIRQA_SPI_TPM_N")
	)
	(segment
		(start 383.126488 -83.19897)
		(end 383.126488 -84.973668)
		(width 0.089408)
		(layer "In2.Cu")
		(net "IRQ_PIRQA_SPI_TPM_N")
	)
	(segment
		(start 385.139692 -74.012806)
		(end 385.139692 -77.325474)
		(width 0.089408)
		(layer "In2.Cu")
		(net "IRQ_PIRQA_SPI_TPM_N")
	)
	(segment
		(start 387.680962 -63.570104)
		(end 386.898896 -63.570104)
		(width 0.089408)
		(layer "In2.Cu")
		(net "IRQ_PIRQA_SPI_TPM_N")
	)
	(segment
		(start 384.532124 -70.584822)
		(end 384.532124 -72.554338)
		(width 0.089408)
		(layer "In2.Cu")
		(net "IRQ_PIRQA_SPI_TPM_N")
	)
	(segment
		(start 386.98932 -60.589668)
		(end 387.428994 -61.029342)
		(width 0.089408)
		(layer "In2.Cu")
		(net "IRQ_PIRQA_SPI_TPM_N")
	)
	(segment
		(start 383.842514 -78.622652)
		(end 383.842514 -79.797656)
		(width 0.089408)
		(layer "In2.Cu")
		(net "IRQ_PIRQA_SPI_TPM_N")
	)
	(segment
		(start 387.915404 -63.335662)
		(end 387.680962 -63.570104)
		(width 0.089408)
		(layer "In2.Cu")
		(net "IRQ_PIRQA_SPI_TPM_N")
	)
	(segment
		(start 383.126488 -84.973668)
		(end 383.320544 -85.167724)
		(width 0.089408)
		(layer "In2.Cu")
		(net "IRQ_PIRQA_SPI_TPM_N")
	)
	(segment
		(start 384.532124 -72.554338)
		(end 384.715512 -72.737726)
		(width 0.089408)
		(layer "In2.Cu")
		(net "IRQ_PIRQA_SPI_TPM_N")
	)
	(segment
		(start 387.915404 -62.94755)
		(end 387.915404 -63.335662)
		(width 0.089408)
		(layer "In2.Cu")
		(net "IRQ_PIRQA_SPI_TPM_N")
	)
	(segment
		(start 384.715512 -72.737726)
		(end 384.715512 -73.588626)
		(width 0.089408)
		(layer "In2.Cu")
		(net "IRQ_PIRQA_SPI_TPM_N")
	)
	(segment
		(start 386.898896 -63.570104)
		(end 385.979162 -64.489838)
		(width 0.089408)
		(layer "In2.Cu")
		(net "IRQ_PIRQA_SPI_TPM_N")
	)
	(segment
		(start 413.5628 -64.8208)
		(end 413.563816 -64.819784)
		(width 0.089408)
		(layer "In4.Cu")
		(net "IRQ_PIRQA_SPI_TPM_N")
	)
	(segment
		(start 406.545542 -61.931296)
		(end 407.73096 -63.116714)
		(width 0.089408)
		(layer "In4.Cu")
		(net "IRQ_PIRQA_SPI_TPM_N")
	)
	(segment
		(start 398.955514 -60.881768)
		(end 400.005042 -61.931296)
		(width 0.089408)
		(layer "In4.Cu")
		(net "IRQ_PIRQA_SPI_TPM_N")
	)
	(segment
		(start 407.73096 -64.473582)
		(end 408.24023 -64.982852)
		(width 0.089408)
		(layer "In4.Cu")
		(net "IRQ_PIRQA_SPI_TPM_N")
	)
	(segment
		(start 411.793436 -64.117728)
		(end 411.793944 -64.117728)
		(width 0.089408)
		(layer "In4.Cu")
		(net "IRQ_PIRQA_SPI_TPM_N")
	)
	(segment
		(start 414.27908 -64.819784)
		(end 415.33191 -63.766954)
		(width 0.089408)
		(layer "In4.Cu")
		(net "IRQ_PIRQA_SPI_TPM_N")
	)
	(segment
		(start 411.793944 -64.117728)
		(end 412.497016 -64.8208)
		(width 0.089408)
		(layer "In4.Cu")
		(net "IRQ_PIRQA_SPI_TPM_N")
	)
	(segment
		(start 387.38048 -60.44184)
		(end 387.48462 -60.54598)
		(width 0.089408)
		(layer "In4.Cu")
		(net "IRQ_PIRQA_SPI_TPM_N")
	)
	(segment
		(start 407.73096 -63.116714)
		(end 407.73096 -64.473582)
		(width 0.089408)
		(layer "In4.Cu")
		(net "IRQ_PIRQA_SPI_TPM_N")
	)
	(segment
		(start 409.516072 -64.982852)
		(end 410.386022 -64.112902)
		(width 0.089408)
		(layer "In4.Cu")
		(net "IRQ_PIRQA_SPI_TPM_N")
	)
	(segment
		(start 412.497016 -64.8208)
		(end 413.5628 -64.8208)
		(width 0.089408)
		(layer "In4.Cu")
		(net "IRQ_PIRQA_SPI_TPM_N")
	)
	(segment
		(start 391.1727 -60.36818)
		(end 392.350498 -60.36818)
		(width 0.089408)
		(layer "In4.Cu")
		(net "IRQ_PIRQA_SPI_TPM_N")
	)
	(segment
		(start 386.98932 -60.44184)
		(end 387.38048 -60.44184)
		(width 0.089408)
		(layer "In4.Cu")
		(net "IRQ_PIRQA_SPI_TPM_N")
	)
	(segment
		(start 415.33191 -63.766954)
		(end 416.599878 -63.766954)
		(width 0.089408)
		(layer "In4.Cu")
		(net "IRQ_PIRQA_SPI_TPM_N")
	)
	(segment
		(start 411.78861 -64.112902)
		(end 411.793436 -64.117728)
		(width 0.089408)
		(layer "In4.Cu")
		(net "IRQ_PIRQA_SPI_TPM_N")
	)
	(segment
		(start 394.013182 -60.115196)
		(end 394.779754 -60.881768)
		(width 0.089408)
		(layer "In4.Cu")
		(net "IRQ_PIRQA_SPI_TPM_N")
	)
	(segment
		(start 392.603482 -60.115196)
		(end 394.013182 -60.115196)
		(width 0.089408)
		(layer "In4.Cu")
		(net "IRQ_PIRQA_SPI_TPM_N")
	)
	(segment
		(start 413.563816 -64.819784)
		(end 414.27908 -64.819784)
		(width 0.089408)
		(layer "In4.Cu")
		(net "IRQ_PIRQA_SPI_TPM_N")
	)
	(segment
		(start 417.51885 -62.847982)
		(end 417.51885 -62.518798)
		(width 0.089408)
		(layer "In4.Cu")
		(net "IRQ_PIRQA_SPI_TPM_N")
	)
	(segment
		(start 394.779754 -60.881768)
		(end 398.955514 -60.881768)
		(width 0.089408)
		(layer "In4.Cu")
		(net "IRQ_PIRQA_SPI_TPM_N")
	)
	(segment
		(start 416.599878 -63.766954)
		(end 417.51885 -62.847982)
		(width 0.089408)
		(layer "In4.Cu")
		(net "IRQ_PIRQA_SPI_TPM_N")
	)
	(segment
		(start 400.005042 -61.931296)
		(end 406.545542 -61.931296)
		(width 0.089408)
		(layer "In4.Cu")
		(net "IRQ_PIRQA_SPI_TPM_N")
	)
	(segment
		(start 392.350498 -60.36818)
		(end 392.603482 -60.115196)
		(width 0.089408)
		(layer "In4.Cu")
		(net "IRQ_PIRQA_SPI_TPM_N")
	)
	(segment
		(start 410.386022 -64.112902)
		(end 411.78861 -64.112902)
		(width 0.089408)
		(layer "In4.Cu")
		(net "IRQ_PIRQA_SPI_TPM_N")
	)
	(segment
		(start 387.48462 -60.54598)
		(end 390.9949 -60.54598)
		(width 0.089408)
		(layer "In4.Cu")
		(net "IRQ_PIRQA_SPI_TPM_N")
	)
	(segment
		(start 390.9949 -60.54598)
		(end 391.1727 -60.36818)
		(width 0.089408)
		(layer "In4.Cu")
		(net "IRQ_PIRQA_SPI_TPM_N")
	)
	(segment
		(start 408.24023 -64.982852)
		(end 409.516072 -64.982852)
		(width 0.089408)
		(layer "In4.Cu")
		(net "IRQ_PIRQA_SPI_TPM_N")
	)
	(segment
		(start 473.94876 -52.30876)
		(end 475.01556 -52.30876)
		(width 0.10795)
		(layer "F.Cu")
		(net "H_CPU0_FAST_WAKE_LVT3_N")
	)
	(segment
		(start 400.75104 -114.666268)
		(end 401.041362 -114.666268)
		(width 0.0889)
		(layer "F.Cu")
		(net "H_CPU0_FAST_WAKE_LVT3_N")
	)
	(segment
		(start 472.755722 -46.650656)
		(end 472.886278 -46.781212)
		(width 0.10795)
		(layer "F.Cu")
		(net "H_CPU0_FAST_WAKE_LVT3_N")
	)
	(segment
		(start 472.886278 -51.246278)
		(end 473.94876 -52.30876)
		(width 0.10795)
		(layer "F.Cu")
		(net "H_CPU0_FAST_WAKE_LVT3_N")
	)
	(segment
		(start 472.886278 -46.781212)
		(end 472.886278 -51.246278)
		(width 0.10795)
		(layer "F.Cu")
		(net "H_CPU0_FAST_WAKE_LVT3_N")
	)
	(segment
		(start 401.041362 -114.666268)
		(end 401.13839 -114.56924)
		(width 0.0889)
		(layer "F.Cu")
		(net "H_CPU0_FAST_WAKE_LVT3_N")
	)
	(segment
		(start 401.804124 -114.56924)
		(end 401.92706 -114.446304)
		(width 0.0889)
		(layer "F.Cu")
		(net "H_CPU0_FAST_WAKE_LVT3_N")
	)
	(segment
		(start 400.05 -114.355118)
		(end 400.43989 -114.355118)
		(width 0.0889)
		(layer "F.Cu")
		(net "H_CPU0_FAST_WAKE_LVT3_N")
	)
	(segment
		(start 402.368512 -114.446304)
		(end 402.82368 -114.901472)
		(width 0.0889)
		(layer "F.Cu")
		(net "H_CPU0_FAST_WAKE_LVT3_N")
	)
	(segment
		(start 401.92706 -114.446304)
		(end 402.368512 -114.446304)
		(width 0.0889)
		(layer "F.Cu")
		(net "H_CPU0_FAST_WAKE_LVT3_N")
	)
	(segment
		(start 475.01556 -52.30876)
		(end 475.5134 -52.8066)
		(width 0.10795)
		(layer "F.Cu")
		(net "H_CPU0_FAST_WAKE_LVT3_N")
	)
	(segment
		(start 472.755722 -46.5074)
		(end 472.755722 -46.650656)
		(width 0.10795)
		(layer "F.Cu")
		(net "H_CPU0_FAST_WAKE_LVT3_N")
	)
	(segment
		(start 400.43989 -114.355118)
		(end 400.75104 -114.666268)
		(width 0.0889)
		(layer "F.Cu")
		(net "H_CPU0_FAST_WAKE_LVT3_N")
	)
	(segment
		(start 401.13839 -114.56924)
		(end 401.804124 -114.56924)
		(width 0.0889)
		(layer "F.Cu")
		(net "H_CPU0_FAST_WAKE_LVT3_N")
	)
	(segment
		(start 414.290256 -40.13454)
		(end 413.890206 -40.53459)
		(width 0.10795)
		(layer "F.Cu")
		(net "H_CPU0_FAST_WAKE_LVT3_N")
	)
	(via
		(at 471.037158 -53.94071)
		(size 0.6604)
		(drill 0.3302)
		(layers "F.Cu" "B.Cu")
		(net "H_CPU0_FAST_WAKE_LVT3_N")
	)
	(via
		(at 413.890206 -40.53459)
		(size 0.4572)
		(drill 0.2032)
		(layers "F.Cu" "B.Cu")
		(net "H_CPU0_FAST_WAKE_LVT3_N")
	)
	(via
		(at 424.307 -20.7264)
		(size 0.508)
		(drill 0.254)
		(layers "F.Cu" "B.Cu")
		(net "H_CPU0_FAST_WAKE_LVT3_N")
	)
	(via
		(at 472.755722 -46.5074)
		(size 0.508)
		(drill 0.254)
		(layers "F.Cu" "B.Cu")
		(net "H_CPU0_FAST_WAKE_LVT3_N")
	)
	(via
		(at 422.402 -19.4056)
		(size 0.6604)
		(drill 0.3302)
		(layers "F.Cu" "B.Cu")
		(net "H_CPU0_FAST_WAKE_LVT3_N")
	)
	(via
		(at 475.5134 -52.8066)
		(size 0.508)
		(drill 0.254)
		(layers "F.Cu" "B.Cu")
		(net "H_CPU0_FAST_WAKE_LVT3_N")
	)
	(via
		(at 402.82368 -114.901472)
		(size 0.508)
		(drill 0.254)
		(layers "F.Cu" "B.Cu")
		(net "H_CPU0_FAST_WAKE_LVT3_N")
	)
	(segment
		(start 471.73007 -53.247798)
		(end 473.192602 -53.247798)
		(width 0.10795)
		(layer "B.Cu")
		(net "H_CPU0_FAST_WAKE_LVT3_N")
	)
	(segment
		(start 422.275 -15.362936)
		(end 422.275 -14.9352)
		(width 0.10795)
		(layer "B.Cu")
		(net "H_CPU0_FAST_WAKE_LVT3_N")
	)
	(segment
		(start 474.030802 -53.0606)
		(end 474.218 -53.247798)
		(width 0.10795)
		(layer "B.Cu")
		(net "H_CPU0_FAST_WAKE_LVT3_N")
	)
	(segment
		(start 422.04005 -15.597886)
		(end 422.275 -15.362936)
		(width 0.10795)
		(layer "B.Cu")
		(net "H_CPU0_FAST_WAKE_LVT3_N")
	)
	(segment
		(start 420.8526 -16.248634)
		(end 421.759126 -16.248634)
		(width 0.10795)
		(layer "B.Cu")
		(net "H_CPU0_FAST_WAKE_LVT3_N")
	)
	(segment
		(start 473.192602 -53.247798)
		(end 473.3798 -53.0606)
		(width 0.10795)
		(layer "B.Cu")
		(net "H_CPU0_FAST_WAKE_LVT3_N")
	)
	(segment
		(start 422.402 -19.4056)
		(end 422.9862 -19.4056)
		(width 0.10795)
		(layer "B.Cu")
		(net "H_CPU0_FAST_WAKE_LVT3_N")
	)
	(segment
		(start 420.8526 -16.789146)
		(end 420.2938 -17.347946)
		(width 0.10795)
		(layer "B.Cu")
		(net "H_CPU0_FAST_WAKE_LVT3_N")
	)
	(segment
		(start 473.3798 -53.0606)
		(end 474.030802 -53.0606)
		(width 0.10795)
		(layer "B.Cu")
		(net "H_CPU0_FAST_WAKE_LVT3_N")
	)
	(segment
		(start 420.8526 -16.248634)
		(end 420.8526 -16.789146)
		(width 0.10795)
		(layer "B.Cu")
		(net "H_CPU0_FAST_WAKE_LVT3_N")
	)
	(segment
		(start 420.2938 -17.347946)
		(end 420.2938 -18.918936)
		(width 0.10795)
		(layer "B.Cu")
		(net "H_CPU0_FAST_WAKE_LVT3_N")
	)
	(segment
		(start 420.780464 -19.4056)
		(end 422.402 -19.4056)
		(width 0.10795)
		(layer "B.Cu")
		(net "H_CPU0_FAST_WAKE_LVT3_N")
	)
	(segment
		(start 422.04005 -15.96771)
		(end 422.04005 -15.597886)
		(width 0.10795)
		(layer "B.Cu")
		(net "H_CPU0_FAST_WAKE_LVT3_N")
	)
	(segment
		(start 422.9862 -19.4056)
		(end 424.307 -20.7264)
		(width 0.10795)
		(layer "B.Cu")
		(net "H_CPU0_FAST_WAKE_LVT3_N")
	)
	(segment
		(start 475.072202 -53.247798)
		(end 475.5134 -52.8066)
		(width 0.10795)
		(layer "B.Cu")
		(net "H_CPU0_FAST_WAKE_LVT3_N")
	)
	(segment
		(start 421.759126 -16.248634)
		(end 422.04005 -15.96771)
		(width 0.10795)
		(layer "B.Cu")
		(net "H_CPU0_FAST_WAKE_LVT3_N")
	)
	(segment
		(start 471.037158 -53.94071)
		(end 471.73007 -53.247798)
		(width 0.10795)
		(layer "B.Cu")
		(net "H_CPU0_FAST_WAKE_LVT3_N")
	)
	(segment
		(start 474.218 -53.247798)
		(end 475.072202 -53.247798)
		(width 0.10795)
		(layer "B.Cu")
		(net "H_CPU0_FAST_WAKE_LVT3_N")
	)
	(segment
		(start 420.2938 -18.918936)
		(end 420.780464 -19.4056)
		(width 0.10795)
		(layer "B.Cu")
		(net "H_CPU0_FAST_WAKE_LVT3_N")
	)
	(segment
		(start 421.699944 -42.85488)
		(end 419.320726 -42.85488)
		(width 0.089408)
		(layer "In4.Cu")
		(net "H_CPU0_FAST_WAKE_LVT3_N")
	)
	(segment
		(start 457.514198 -37.2364)
		(end 448.657472 -37.2364)
		(width 0.089408)
		(layer "In4.Cu")
		(net "H_CPU0_FAST_WAKE_LVT3_N")
	)
	(segment
		(start 466.691472 -40.975788)
		(end 464.894168 -40.975788)
		(width 0.089408)
		(layer "In4.Cu")
		(net "H_CPU0_FAST_WAKE_LVT3_N")
	)
	(segment
		(start 417.78555 -41.759886)
		(end 417.493704 -41.46804)
		(width 0.089408)
		(layer "In4.Cu")
		(net "H_CPU0_FAST_WAKE_LVT3_N")
	)
	(segment
		(start 413.89046 -40.53459)
		(end 413.890206 -40.53459)
		(width 0.089408)
		(layer "In4.Cu")
		(net "H_CPU0_FAST_WAKE_LVT3_N")
	)
	(segment
		(start 423.475658 -40.76954)
		(end 422.26484 -41.980358)
		(width 0.089408)
		(layer "In4.Cu")
		(net "H_CPU0_FAST_WAKE_LVT3_N")
	)
	(segment
		(start 417.493704 -41.208452)
		(end 417.245292 -40.96004)
		(width 0.089408)
		(layer "In4.Cu")
		(net "H_CPU0_FAST_WAKE_LVT3_N")
	)
	(segment
		(start 448.657472 -37.2364)
		(end 446.272412 -39.62146)
		(width 0.089408)
		(layer "In4.Cu")
		(net "H_CPU0_FAST_WAKE_LVT3_N")
	)
	(segment
		(start 414.31591 -40.96004)
		(end 413.89046 -40.53459)
		(width 0.089408)
		(layer "In4.Cu")
		(net "H_CPU0_FAST_WAKE_LVT3_N")
	)
	(segment
		(start 428.098458 -38.273736)
		(end 425.602654 -40.76954)
		(width 0.089408)
		(layer "In4.Cu")
		(net "H_CPU0_FAST_WAKE_LVT3_N")
	)
	(segment
		(start 425.602654 -40.76954)
		(end 423.475658 -40.76954)
		(width 0.089408)
		(layer "In4.Cu")
		(net "H_CPU0_FAST_WAKE_LVT3_N")
	)
	(segment
		(start 417.245292 -40.96004)
		(end 414.31591 -40.96004)
		(width 0.089408)
		(layer "In4.Cu")
		(net "H_CPU0_FAST_WAKE_LVT3_N")
	)
	(segment
		(start 435.290976 -39.62146)
		(end 435.290722 -39.621206)
		(width 0.089408)
		(layer "In4.Cu")
		(net "H_CPU0_FAST_WAKE_LVT3_N")
	)
	(segment
		(start 472.755722 -45.877734)
		(end 472.10345 -45.225462)
		(width 0.089408)
		(layer "In4.Cu")
		(net "H_CPU0_FAST_WAKE_LVT3_N")
	)
	(segment
		(start 422.26484 -42.289984)
		(end 421.699944 -42.85488)
		(width 0.089408)
		(layer "In4.Cu")
		(net "H_CPU0_FAST_WAKE_LVT3_N")
	)
	(segment
		(start 471.276172 -45.225462)
		(end 471.129614 -45.078904)
		(width 0.089408)
		(layer "In4.Cu")
		(net "H_CPU0_FAST_WAKE_LVT3_N")
	)
	(segment
		(start 417.493704 -41.46804)
		(end 417.493704 -41.208452)
		(width 0.089408)
		(layer "In4.Cu")
		(net "H_CPU0_FAST_WAKE_LVT3_N")
	)
	(segment
		(start 418.264848 -41.979342)
		(end 418.045392 -41.759886)
		(width 0.089408)
		(layer "In4.Cu")
		(net "H_CPU0_FAST_WAKE_LVT3_N")
	)
	(segment
		(start 470.744296 -44.844462)
		(end 470.744296 -44.693586)
		(width 0.089408)
		(layer "In4.Cu")
		(net "H_CPU0_FAST_WAKE_LVT3_N")
	)
	(segment
		(start 468.638128 -43.478704)
		(end 468.125048 -42.965624)
		(width 0.089408)
		(layer "In4.Cu")
		(net "H_CPU0_FAST_WAKE_LVT3_N")
	)
	(segment
		(start 446.272412 -39.62146)
		(end 435.290976 -39.62146)
		(width 0.089408)
		(layer "In4.Cu")
		(net "H_CPU0_FAST_WAKE_LVT3_N")
	)
	(segment
		(start 422.26484 -41.980358)
		(end 422.26484 -42.289984)
		(width 0.089408)
		(layer "In4.Cu")
		(net "H_CPU0_FAST_WAKE_LVT3_N")
	)
	(segment
		(start 418.585396 -42.559986)
		(end 418.264848 -42.239438)
		(width 0.089408)
		(layer "In4.Cu")
		(net "H_CPU0_FAST_WAKE_LVT3_N")
	)
	(segment
		(start 468.125048 -42.965624)
		(end 468.125048 -42.409364)
		(width 0.089408)
		(layer "In4.Cu")
		(net "H_CPU0_FAST_WAKE_LVT3_N")
	)
	(segment
		(start 434.249322 -39.621206)
		(end 432.901852 -38.273736)
		(width 0.089408)
		(layer "In4.Cu")
		(net "H_CPU0_FAST_WAKE_LVT3_N")
	)
	(segment
		(start 435.290722 -39.621206)
		(end 434.249322 -39.621206)
		(width 0.089408)
		(layer "In4.Cu")
		(net "H_CPU0_FAST_WAKE_LVT3_N")
	)
	(segment
		(start 432.901852 -38.273736)
		(end 428.098458 -38.273736)
		(width 0.089408)
		(layer "In4.Cu")
		(net "H_CPU0_FAST_WAKE_LVT3_N")
	)
	(segment
		(start 419.320726 -42.85488)
		(end 419.025832 -42.559986)
		(width 0.089408)
		(layer "In4.Cu")
		(net "H_CPU0_FAST_WAKE_LVT3_N")
	)
	(segment
		(start 472.755722 -46.5074)
		(end 472.755722 -45.877734)
		(width 0.089408)
		(layer "In4.Cu")
		(net "H_CPU0_FAST_WAKE_LVT3_N")
	)
	(segment
		(start 472.10345 -45.225462)
		(end 471.276172 -45.225462)
		(width 0.089408)
		(layer "In4.Cu")
		(net "H_CPU0_FAST_WAKE_LVT3_N")
	)
	(segment
		(start 418.045392 -41.759886)
		(end 417.78555 -41.759886)
		(width 0.089408)
		(layer "In4.Cu")
		(net "H_CPU0_FAST_WAKE_LVT3_N")
	)
	(segment
		(start 464.894168 -40.975788)
		(end 462.731866 -38.813486)
		(width 0.089408)
		(layer "In4.Cu")
		(net "H_CPU0_FAST_WAKE_LVT3_N")
	)
	(segment
		(start 470.744296 -44.693586)
		(end 469.529414 -43.478704)
		(width 0.089408)
		(layer "In4.Cu")
		(net "H_CPU0_FAST_WAKE_LVT3_N")
	)
	(segment
		(start 418.264848 -42.239438)
		(end 418.264848 -41.979342)
		(width 0.089408)
		(layer "In4.Cu")
		(net "H_CPU0_FAST_WAKE_LVT3_N")
	)
	(segment
		(start 470.978738 -45.078904)
		(end 470.744296 -44.844462)
		(width 0.089408)
		(layer "In4.Cu")
		(net "H_CPU0_FAST_WAKE_LVT3_N")
	)
	(segment
		(start 419.025832 -42.559986)
		(end 418.585396 -42.559986)
		(width 0.089408)
		(layer "In4.Cu")
		(net "H_CPU0_FAST_WAKE_LVT3_N")
	)
	(segment
		(start 471.129614 -45.078904)
		(end 470.978738 -45.078904)
		(width 0.089408)
		(layer "In4.Cu")
		(net "H_CPU0_FAST_WAKE_LVT3_N")
	)
	(segment
		(start 459.091284 -38.813486)
		(end 457.514198 -37.2364)
		(width 0.089408)
		(layer "In4.Cu")
		(net "H_CPU0_FAST_WAKE_LVT3_N")
	)
	(segment
		(start 468.125048 -42.409364)
		(end 466.691472 -40.975788)
		(width 0.089408)
		(layer "In4.Cu")
		(net "H_CPU0_FAST_WAKE_LVT3_N")
	)
	(segment
		(start 469.529414 -43.478704)
		(end 468.638128 -43.478704)
		(width 0.089408)
		(layer "In4.Cu")
		(net "H_CPU0_FAST_WAKE_LVT3_N")
	)
	(segment
		(start 462.731866 -38.813486)
		(end 459.091284 -38.813486)
		(width 0.089408)
		(layer "In4.Cu")
		(net "H_CPU0_FAST_WAKE_LVT3_N")
	)
	(segment
		(start 404.38959 -116.097304)
		(end 406.418288 -116.097304)
		(width 0.089408)
		(layer "In9.Cu")
		(net "H_CPU0_FAST_WAKE_LVT3_N")
	)
	(segment
		(start 415.915602 -31.416498)
		(end 414.264856 -33.067244)
		(width 0.089408)
		(layer "In9.Cu")
		(net "H_CPU0_FAST_WAKE_LVT3_N")
	)
	(segment
		(start 422.468294 -77.657706)
		(end 422.468294 -64.96685)
		(width 0.089408)
		(layer "In9.Cu")
		(net "H_CPU0_FAST_WAKE_LVT3_N")
	)
	(segment
		(start 422.468294 -64.96685)
		(end 423.209466 -64.225678)
		(width 0.089408)
		(layer "In9.Cu")
		(net "H_CPU0_FAST_WAKE_LVT3_N")
	)
	(segment
		(start 423.239692 -23.123652)
		(end 423.239692 -23.504144)
		(width 0.089408)
		(layer "In9.Cu")
		(net "H_CPU0_FAST_WAKE_LVT3_N")
	)
	(segment
		(start 471.299032 -53.461158)
		(end 470.897966 -53.060092)
		(width 0.089408)
		(layer "In9.Cu")
		(net "H_CPU0_FAST_WAKE_LVT3_N")
	)
	(segment
		(start 465.745576 -62.974982)
		(end 467.9442 -62.974982)
		(width 0.089408)
		(layer "In9.Cu")
		(net "H_CPU0_FAST_WAKE_LVT3_N")
	)
	(segment
		(start 471.299032 -54.67223)
		(end 471.299032 -53.461158)
		(width 0.089408)
		(layer "In9.Cu")
		(net "H_CPU0_FAST_WAKE_LVT3_N")
	)
	(segment
		(start 414.767014 -113.777014)
		(end 415.64433 -114.65433)
		(width 0.089408)
		(layer "In9.Cu")
		(net "H_CPU0_FAST_WAKE_LVT3_N")
	)
	(segment
		(start 418.364416 -115.358164)
		(end 418.67836 -115.04422)
		(width 0.089408)
		(layer "In9.Cu")
		(net "H_CPU0_FAST_WAKE_LVT3_N")
	)
	(segment
		(start 464.137502 -64.583056)
		(end 465.745576 -62.974982)
		(width 0.089408)
		(layer "In9.Cu")
		(net "H_CPU0_FAST_WAKE_LVT3_N")
	)
	(segment
		(start 421.60571 -93.76029)
		(end 421.60571 -78.52029)
		(width 0.089408)
		(layer "In9.Cu")
		(net "H_CPU0_FAST_WAKE_LVT3_N")
	)
	(segment
		(start 418.67836 -111.74222)
		(end 417.98875 -111.05261)
		(width 0.089408)
		(layer "In9.Cu")
		(net "H_CPU0_FAST_WAKE_LVT3_N")
	)
	(segment
		(start 421.515286 -27.884882)
		(end 421.291004 -28.109164)
		(width 0.089408)
		(layer "In9.Cu")
		(net "H_CPU0_FAST_WAKE_LVT3_N")
	)
	(segment
		(start 421.515286 -27.378914)
		(end 421.515286 -27.884882)
		(width 0.089408)
		(layer "In9.Cu")
		(net "H_CPU0_FAST_WAKE_LVT3_N")
	)
	(segment
		(start 414.264856 -40.15994)
		(end 413.890206 -40.53459)
		(width 0.089408)
		(layer "In9.Cu")
		(net "H_CPU0_FAST_WAKE_LVT3_N")
	)
	(segment
		(start 402.82368 -114.901472)
		(end 403.168866 -115.246658)
		(width 0.089408)
		(layer "In9.Cu")
		(net "H_CPU0_FAST_WAKE_LVT3_N")
	)
	(segment
		(start 420.713154 -28.341574)
		(end 420.713154 -28.765246)
		(width 0.089408)
		(layer "In9.Cu")
		(net "H_CPU0_FAST_WAKE_LVT3_N")
	)
	(segment
		(start 424.307 -20.7264)
		(end 423.83583 -21.19757)
		(width 0.089408)
		(layer "In9.Cu")
		(net "H_CPU0_FAST_WAKE_LVT3_N")
	)
	(segment
		(start 403.538944 -115.246658)
		(end 404.38959 -116.097304)
		(width 0.089408)
		(layer "In9.Cu")
		(net "H_CPU0_FAST_WAKE_LVT3_N")
	)
	(segment
		(start 425.161202 -64.225678)
		(end 425.51858 -64.583056)
		(width 0.089408)
		(layer "In9.Cu")
		(net "H_CPU0_FAST_WAKE_LVT3_N")
	)
	(segment
		(start 417.98875 -110.822232)
		(end 417.988496 -110.821978)
		(width 0.089408)
		(layer "In9.Cu")
		(net "H_CPU0_FAST_WAKE_LVT3_N")
	)
	(segment
		(start 417.98875 -111.05261)
		(end 417.98875 -110.822232)
		(width 0.089408)
		(layer "In9.Cu")
		(net "H_CPU0_FAST_WAKE_LVT3_N")
	)
	(segment
		(start 417.988496 -110.821978)
		(end 417.988496 -107.96905)
		(width 0.089408)
		(layer "In9.Cu")
		(net "H_CPU0_FAST_WAKE_LVT3_N")
	)
	(segment
		(start 411.139386 -113.777014)
		(end 414.767014 -113.777014)
		(width 0.089408)
		(layer "In9.Cu")
		(net "H_CPU0_FAST_WAKE_LVT3_N")
	)
	(segment
		(start 407.524712 -114.99088)
		(end 409.92552 -114.99088)
		(width 0.089408)
		(layer "In9.Cu")
		(net "H_CPU0_FAST_WAKE_LVT3_N")
	)
	(segment
		(start 416.723576 -114.65433)
		(end 417.42741 -115.358164)
		(width 0.089408)
		(layer "In9.Cu")
		(net "H_CPU0_FAST_WAKE_LVT3_N")
	)
	(segment
		(start 472.755722 -49.414176)
		(end 472.755722 -46.5074)
		(width 0.089408)
		(layer "In9.Cu")
		(net "H_CPU0_FAST_WAKE_LVT3_N")
	)
	(segment
		(start 417.988496 -107.96905)
		(end 416.63366 -106.614214)
		(width 0.089408)
		(layer "In9.Cu")
		(net "H_CPU0_FAST_WAKE_LVT3_N")
	)
	(segment
		(start 417.42741 -115.358164)
		(end 418.364416 -115.358164)
		(width 0.089408)
		(layer "In9.Cu")
		(net "H_CPU0_FAST_WAKE_LVT3_N")
	)
	(segment
		(start 423.209466 -64.225678)
		(end 425.161202 -64.225678)
		(width 0.089408)
		(layer "In9.Cu")
		(net "H_CPU0_FAST_WAKE_LVT3_N")
	)
	(segment
		(start 418.67836 -115.04422)
		(end 418.67836 -111.74222)
		(width 0.089408)
		(layer "In9.Cu")
		(net "H_CPU0_FAST_WAKE_LVT3_N")
	)
	(segment
		(start 420.94531 -28.109418)
		(end 420.713154 -28.341574)
		(width 0.089408)
		(layer "In9.Cu")
		(net "H_CPU0_FAST_WAKE_LVT3_N")
	)
	(segment
		(start 406.418288 -116.097304)
		(end 407.524712 -114.99088)
		(width 0.089408)
		(layer "In9.Cu")
		(net "H_CPU0_FAST_WAKE_LVT3_N")
	)
	(segment
		(start 416.416236 -28.960064)
		(end 415.915602 -29.460698)
		(width 0.089408)
		(layer "In9.Cu")
		(net "H_CPU0_FAST_WAKE_LVT3_N")
	)
	(segment
		(start 415.915602 -29.460698)
		(end 415.915602 -31.416498)
		(width 0.089408)
		(layer "In9.Cu")
		(net "H_CPU0_FAST_WAKE_LVT3_N")
	)
	(segment
		(start 425.51858 -64.583056)
		(end 464.137502 -64.583056)
		(width 0.089408)
		(layer "In9.Cu")
		(net "H_CPU0_FAST_WAKE_LVT3_N")
	)
	(segment
		(start 416.63366 -98.73234)
		(end 421.60571 -93.76029)
		(width 0.089408)
		(layer "In9.Cu")
		(net "H_CPU0_FAST_WAKE_LVT3_N")
	)
	(segment
		(start 423.2402 -23.504652)
		(end 423.2402 -25.654)
		(width 0.089408)
		(layer "In9.Cu")
		(net "H_CPU0_FAST_WAKE_LVT3_N")
	)
	(segment
		(start 470.897966 -51.271932)
		(end 472.755722 -49.414176)
		(width 0.089408)
		(layer "In9.Cu")
		(net "H_CPU0_FAST_WAKE_LVT3_N")
	)
	(segment
		(start 421.245792 -28.109164)
		(end 421.245538 -28.109418)
		(width 0.089408)
		(layer "In9.Cu")
		(net "H_CPU0_FAST_WAKE_LVT3_N")
	)
	(segment
		(start 420.713154 -28.765246)
		(end 420.518336 -28.960064)
		(width 0.089408)
		(layer "In9.Cu")
		(net "H_CPU0_FAST_WAKE_LVT3_N")
	)
	(segment
		(start 414.264856 -33.067244)
		(end 414.264856 -40.15994)
		(width 0.089408)
		(layer "In9.Cu")
		(net "H_CPU0_FAST_WAKE_LVT3_N")
	)
	(segment
		(start 423.83583 -21.19757)
		(end 423.83583 -22.527514)
		(width 0.089408)
		(layer "In9.Cu")
		(net "H_CPU0_FAST_WAKE_LVT3_N")
	)
	(segment
		(start 415.64433 -114.65433)
		(end 416.723576 -114.65433)
		(width 0.089408)
		(layer "In9.Cu")
		(net "H_CPU0_FAST_WAKE_LVT3_N")
	)
	(segment
		(start 470.897966 -53.060092)
		(end 470.897966 -51.271932)
		(width 0.089408)
		(layer "In9.Cu")
		(net "H_CPU0_FAST_WAKE_LVT3_N")
	)
	(segment
		(start 409.92552 -114.99088)
		(end 411.139386 -113.777014)
		(width 0.089408)
		(layer "In9.Cu")
		(net "H_CPU0_FAST_WAKE_LVT3_N")
	)
	(segment
		(start 421.60571 -78.52029)
		(end 422.468294 -77.657706)
		(width 0.089408)
		(layer "In9.Cu")
		(net "H_CPU0_FAST_WAKE_LVT3_N")
	)
	(segment
		(start 420.518336 -28.960064)
		(end 416.416236 -28.960064)
		(width 0.089408)
		(layer "In9.Cu")
		(net "H_CPU0_FAST_WAKE_LVT3_N")
	)
	(segment
		(start 421.291004 -28.109164)
		(end 421.245792 -28.109164)
		(width 0.089408)
		(layer "In9.Cu")
		(net "H_CPU0_FAST_WAKE_LVT3_N")
	)
	(segment
		(start 421.245538 -28.109418)
		(end 420.94531 -28.109418)
		(width 0.089408)
		(layer "In9.Cu")
		(net "H_CPU0_FAST_WAKE_LVT3_N")
	)
	(segment
		(start 416.63366 -106.614214)
		(end 416.63366 -98.73234)
		(width 0.089408)
		(layer "In9.Cu")
		(net "H_CPU0_FAST_WAKE_LVT3_N")
	)
	(segment
		(start 467.9442 -62.974982)
		(end 471.169746 -59.749436)
		(width 0.089408)
		(layer "In9.Cu")
		(net "H_CPU0_FAST_WAKE_LVT3_N")
	)
	(segment
		(start 403.168866 -115.246658)
		(end 403.538944 -115.246658)
		(width 0.089408)
		(layer "In9.Cu")
		(net "H_CPU0_FAST_WAKE_LVT3_N")
	)
	(segment
		(start 423.239692 -23.504144)
		(end 423.2402 -23.504652)
		(width 0.089408)
		(layer "In9.Cu")
		(net "H_CPU0_FAST_WAKE_LVT3_N")
	)
	(segment
		(start 423.2402 -25.654)
		(end 421.515286 -27.378914)
		(width 0.089408)
		(layer "In9.Cu")
		(net "H_CPU0_FAST_WAKE_LVT3_N")
	)
	(segment
		(start 471.169746 -54.801516)
		(end 471.299032 -54.67223)
		(width 0.089408)
		(layer "In9.Cu")
		(net "H_CPU0_FAST_WAKE_LVT3_N")
	)
	(segment
		(start 471.169746 -59.749436)
		(end 471.169746 -54.801516)
		(width 0.089408)
		(layer "In9.Cu")
		(net "H_CPU0_FAST_WAKE_LVT3_N")
	)
	(segment
		(start 423.83583 -22.527514)
		(end 423.239692 -23.123652)
		(width 0.089408)
		(layer "In9.Cu")
		(net "H_CPU0_FAST_WAKE_LVT3_N")
	)
	(via
		(at 423.544238 -11.989308)
		(size 0.6604)
		(drill 0.3302)
		(layers "F.Cu" "B.Cu")
		(net "H_CPU0_FAST_WAKE")
	)
	(segment
		(start 421.822626 -12.446)
		(end 421.728392 -12.540234)
		(width 0.10795)
		(layer "B.Cu")
		(net "H_CPU0_FAST_WAKE")
	)
	(segment
		(start 419.678866 -15.296134)
		(end 418.6936 -15.296134)
		(width 0.10795)
		(layer "B.Cu")
		(net "H_CPU0_FAST_WAKE")
	)
	(segment
		(start 423.087546 -12.446)
		(end 423.544238 -11.989308)
		(width 0.10795)
		(layer "B.Cu")
		(net "H_CPU0_FAST_WAKE")
	)
	(segment
		(start 422.3004 -12.446)
		(end 421.822626 -12.446)
		(width 0.10795)
		(layer "B.Cu")
		(net "H_CPU0_FAST_WAKE")
	)
	(segment
		(start 420.9796 -13.9954)
		(end 419.678866 -15.296134)
		(width 0.10795)
		(layer "B.Cu")
		(net "H_CPU0_FAST_WAKE")
	)
	(segment
		(start 420.9796 -12.540234)
		(end 420.9796 -13.9954)
		(width 0.10795)
		(layer "B.Cu")
		(net "H_CPU0_FAST_WAKE")
	)
	(segment
		(start 422.3004 -12.446)
		(end 423.087546 -12.446)
		(width 0.10795)
		(layer "B.Cu")
		(net "H_CPU0_FAST_WAKE")
	)
	(segment
		(start 421.728392 -12.540234)
		(end 420.9796 -12.540234)
		(width 0.10795)
		(layer "B.Cu")
		(net "H_CPU0_FAST_WAKE")
	)
	(segment
		(start 373.68988 -96.13138)
		(end 373.20982 -96.61144)
		(width 0.10795)
		(layer "F.Cu")
		(net "FM_WBG_PRSNT_N")
	)
	(segment
		(start 370.0018 -94.742)
		(end 369.443 -94.742)
		(width 0.10795)
		(layer "F.Cu")
		(net "FM_WBG_PRSNT_N")
	)
	(segment
		(start 370.34978 -94.8944)
		(end 370.1542 -94.8944)
		(width 0.10795)
		(layer "F.Cu")
		(net "FM_WBG_PRSNT_N")
	)
	(segment
		(start 374.21058 -96.13138)
		(end 373.68988 -96.13138)
		(width 0.10795)
		(layer "F.Cu")
		(net "FM_WBG_PRSNT_N")
	)
	(segment
		(start 370.345208 -72.695308)
		(end 370.745004 -73.095104)
		(width 0.1016)
		(layer "F.Cu")
		(net "FM_WBG_PRSNT_N")
	)
	(segment
		(start 373.20982 -96.61144)
		(end 372.06682 -96.61144)
		(width 0.10795)
		(layer "F.Cu")
		(net "FM_WBG_PRSNT_N")
	)
	(segment
		(start 372.06682 -96.61144)
		(end 370.34978 -94.8944)
		(width 0.10795)
		(layer "F.Cu")
		(net "FM_WBG_PRSNT_N")
	)
	(segment
		(start 374.4341 -96.3549)
		(end 374.21058 -96.13138)
		(width 0.10795)
		(layer "F.Cu")
		(net "FM_WBG_PRSNT_N")
	)
	(segment
		(start 375.92 -96.3549)
		(end 374.4341 -96.3549)
		(width 0.10795)
		(layer "F.Cu")
		(net "FM_WBG_PRSNT_N")
	)
	(segment
		(start 370.1542 -94.8944)
		(end 370.0018 -94.742)
		(width 0.10795)
		(layer "F.Cu")
		(net "FM_WBG_PRSNT_N")
	)
	(via
		(at 370.1542 -94.8944)
		(size 0.508)
		(drill 0.254)
		(layers "F.Cu" "B.Cu")
		(net "FM_WBG_PRSNT_N")
	)
	(via
		(at 370.345208 -72.695308)
		(size 0.4572)
		(drill 0.2032)
		(layers "F.Cu" "B.Cu")
		(net "FM_WBG_PRSNT_N")
	)
	(segment
		(start 369.8875 -89.5985)
		(end 369.8875 -91.0336)
		(width 0.089408)
		(layer "In11.Cu")
		(net "FM_WBG_PRSNT_N")
	)
	(segment
		(start 367.3856 -87.0966)
		(end 369.8875 -89.5985)
		(width 0.089408)
		(layer "In11.Cu")
		(net "FM_WBG_PRSNT_N")
	)
	(segment
		(start 368.099848 -79.468218)
		(end 368.096038 -79.468218)
		(width 0.089408)
		(layer "In11.Cu")
		(net "FM_WBG_PRSNT_N")
	)
	(segment
		(start 367.53038 -79.706216)
		(end 367.53038 -80.55229)
		(width 0.089408)
		(layer "In11.Cu")
		(net "FM_WBG_PRSNT_N")
	)
	(segment
		(start 367.53038 -80.55229)
		(end 367.537492 -80.559402)
		(width 0.089408)
		(layer "In11.Cu")
		(net "FM_WBG_PRSNT_N")
	)
	(segment
		(start 370.1542 -94.1451)
		(end 370.1542 -94.8944)
		(width 0.089408)
		(layer "In11.Cu")
		(net "FM_WBG_PRSNT_N")
	)
	(segment
		(start 369.390422 -72.321928)
		(end 369.133374 -72.578976)
		(width 0.089408)
		(layer "In11.Cu")
		(net "FM_WBG_PRSNT_N")
	)
	(segment
		(start 369.133374 -72.578976)
		(end 369.133374 -77.970634)
		(width 0.089408)
		(layer "In11.Cu")
		(net "FM_WBG_PRSNT_N")
	)
	(segment
		(start 367.537492 -80.559402)
		(end 367.537492 -80.868774)
		(width 0.089408)
		(layer "In11.Cu")
		(net "FM_WBG_PRSNT_N")
	)
	(segment
		(start 368.042952 -79.521304)
		(end 367.715292 -79.521304)
		(width 0.089408)
		(layer "In11.Cu")
		(net "FM_WBG_PRSNT_N")
	)
	(segment
		(start 370.2939 -94.0054)
		(end 370.1542 -94.1451)
		(width 0.089408)
		(layer "In11.Cu")
		(net "FM_WBG_PRSNT_N")
	)
	(segment
		(start 367.3856 -84.4296)
		(end 367.3856 -87.0966)
		(width 0.089408)
		(layer "In11.Cu")
		(net "FM_WBG_PRSNT_N")
	)
	(segment
		(start 367.53038 -80.922622)
		(end 367.597944 -80.990186)
		(width 0.089408)
		(layer "In11.Cu")
		(net "FM_WBG_PRSNT_N")
	)
	(segment
		(start 367.597944 -80.990186)
		(end 367.597944 -84.217256)
		(width 0.089408)
		(layer "In11.Cu")
		(net "FM_WBG_PRSNT_N")
	)
	(segment
		(start 368.318542 -79.249524)
		(end 368.099848 -79.468218)
		(width 0.089408)
		(layer "In11.Cu")
		(net "FM_WBG_PRSNT_N")
	)
	(segment
		(start 369.8875 -91.0336)
		(end 370.2939 -91.44)
		(width 0.089408)
		(layer "In11.Cu")
		(net "FM_WBG_PRSNT_N")
	)
	(segment
		(start 370.2939 -91.44)
		(end 370.2939 -94.0054)
		(width 0.089408)
		(layer "In11.Cu")
		(net "FM_WBG_PRSNT_N")
	)
	(segment
		(start 369.971828 -72.321928)
		(end 369.390422 -72.321928)
		(width 0.089408)
		(layer "In11.Cu")
		(net "FM_WBG_PRSNT_N")
	)
	(segment
		(start 367.715292 -79.521304)
		(end 367.53038 -79.706216)
		(width 0.089408)
		(layer "In11.Cu")
		(net "FM_WBG_PRSNT_N")
	)
	(segment
		(start 367.597944 -84.217256)
		(end 367.3856 -84.4296)
		(width 0.089408)
		(layer "In11.Cu")
		(net "FM_WBG_PRSNT_N")
	)
	(segment
		(start 368.318542 -78.785466)
		(end 368.318542 -79.249524)
		(width 0.089408)
		(layer "In11.Cu")
		(net "FM_WBG_PRSNT_N")
	)
	(segment
		(start 369.133374 -77.970634)
		(end 368.318542 -78.785466)
		(width 0.089408)
		(layer "In11.Cu")
		(net "FM_WBG_PRSNT_N")
	)
	(segment
		(start 367.537492 -80.868774)
		(end 367.53038 -80.875886)
		(width 0.089408)
		(layer "In11.Cu")
		(net "FM_WBG_PRSNT_N")
	)
	(segment
		(start 367.53038 -80.875886)
		(end 367.53038 -80.922622)
		(width 0.089408)
		(layer "In11.Cu")
		(net "FM_WBG_PRSNT_N")
	)
	(segment
		(start 370.345208 -72.695308)
		(end 369.971828 -72.321928)
		(width 0.089408)
		(layer "In11.Cu")
		(net "FM_WBG_PRSNT_N")
	)
	(segment
		(start 368.096038 -79.468218)
		(end 368.042952 -79.521304)
		(width 0.089408)
		(layer "In11.Cu")
		(net "FM_WBG_PRSNT_N")
	)
	(segment
		(start 482.29774 -36.098988)
		(end 482.56317 -36.098988)
		(width 0.10033)
		(layer "F.Cu")
		(net "NIC_SET_P_MDI_2_DP")
	)
	(segment
		(start 480.842574 4.65709)
		(end 480.842574 5.26669)
		(width 0.10033)
		(layer "F.Cu")
		(net "NIC_SET_P_MDI_2_DP")
	)
	(segment
		(start 482.197156 -36.199572)
		(end 482.29774 -36.098988)
		(width 0.10033)
		(layer "F.Cu")
		(net "NIC_SET_P_MDI_2_DP")
	)
	(segment
		(start 482.479604 -38.969442)
		(end 482.479604 -37.498528)
		(width 0.10033)
		(layer "F.Cu")
		(net "NIC_SET_P_MDI_2_DP")
	)
	(segment
		(start 482.197156 -37.21608)
		(end 482.197156 -36.199572)
		(width 0.10033)
		(layer "F.Cu")
		(net "NIC_SET_P_MDI_2_DP")
	)
	(segment
		(start 482.50094 -38.990778)
		(end 482.479604 -38.969442)
		(width 0.10033)
		(layer "F.Cu")
		(net "NIC_SET_P_MDI_2_DP")
	)
	(segment
		(start 482.479604 -37.498528)
		(end 482.197156 -37.21608)
		(width 0.10033)
		(layer "F.Cu")
		(net "NIC_SET_P_MDI_2_DP")
	)
	(segment
		(start 482.50094 -39.5986)
		(end 482.50094 -38.990778)
		(width 0.10033)
		(layer "F.Cu")
		(net "NIC_SET_P_MDI_2_DP")
	)
	(via
		(at 482.56317 -36.098988)
		(size 0.508)
		(drill 0.254)
		(layers "F.Cu" "B.Cu")
		(net "NIC_SET_P_MDI_2_DP")
	)
	(via
		(at 480.842574 5.26669)
		(size 0.508)
		(drill 0.254)
		(layers "F.Cu" "B.Cu")
		(net "NIC_SET_P_MDI_2_DP")
	)
	(segment
		(start 480.209606 0.640842)
		(end 480.648772 0.201676)
		(width 0.101346)
		(layer "In11.Cu")
		(net "NIC_SET_P_MDI_2_DP")
	)
	(segment
		(start 482.715824 -21.195538)
		(end 483.837742 -21.195538)
		(width 0.101346)
		(layer "In11.Cu")
		(net "NIC_SET_P_MDI_2_DP")
	)
	(segment
		(start 480.459034 -18.024856)
		(end 480.459034 -17.110964)
		(width 0.101346)
		(layer "In11.Cu")
		(net "NIC_SET_P_MDI_2_DP")
	)
	(segment
		(start 482.837236 -33.049718)
		(end 483.1842 -33.396682)
		(width 0.101346)
		(layer "In11.Cu")
		(net "NIC_SET_P_MDI_2_DP")
	)
	(segment
		(start 479.203258 -15.92961)
		(end 478.856294 -16.276574)
		(width 0.101346)
		(layer "In11.Cu")
		(net "NIC_SET_P_MDI_2_DP")
	)
	(segment
		(start 481.92055 -17.151604)
		(end 481.92055 -17.567656)
		(width 0.101346)
		(layer "In11.Cu")
		(net "NIC_SET_P_MDI_2_DP")
	)
	(segment
		(start 483.1842 -33.396682)
		(end 483.1842 -34.765488)
		(width 0.101346)
		(layer "In11.Cu")
		(net "NIC_SET_P_MDI_2_DP")
	)
	(segment
		(start 480.955858 4.80822)
		(end 481.734114 4.80822)
		(width 0.101346)
		(layer "In11.Cu")
		(net "NIC_SET_P_MDI_2_DP")
	)
	(segment
		(start 479.854514 -18.271744)
		(end 480.212146 -18.271744)
		(width 0.101346)
		(layer "In11.Cu")
		(net "NIC_SET_P_MDI_2_DP")
	)
	(segment
		(start 479.203258 -17.620488)
		(end 479.854514 -18.271744)
		(width 0.101346)
		(layer "In11.Cu")
		(net "NIC_SET_P_MDI_2_DP")
	)
	(segment
		(start 480.50069 -1.94564)
		(end 480.50069 -2.714244)
		(width 0.101346)
		(layer "In11.Cu")
		(net "NIC_SET_P_MDI_2_DP")
	)
	(segment
		(start 479.480118 -3.805936)
		(end 480.17938 -3.805936)
		(width 0.101346)
		(layer "In11.Cu")
		(net "NIC_SET_P_MDI_2_DP")
	)
	(segment
		(start 479.203258 -15.302484)
		(end 479.203258 -15.92961)
		(width 0.101346)
		(layer "In11.Cu")
		(net "NIC_SET_P_MDI_2_DP")
	)
	(segment
		(start 483.1842 -30.99943)
		(end 483.1842 -32.220154)
		(width 0.101346)
		(layer "In11.Cu")
		(net "NIC_SET_P_MDI_2_DP")
	)
	(segment
		(start 484.027988 -26.242772)
		(end 483.687882 -26.582878)
		(width 0.101346)
		(layer "In11.Cu")
		(net "NIC_SET_P_MDI_2_DP")
	)
	(segment
		(start 480.628198 -10.14349)
		(end 480.281234 -10.490454)
		(width 0.101346)
		(layer "In11.Cu")
		(net "NIC_SET_P_MDI_2_DP")
	)
	(segment
		(start 480.174046 -1.618996)
		(end 480.50069 -1.94564)
		(width 0.101346)
		(layer "In11.Cu")
		(net "NIC_SET_P_MDI_2_DP")
	)
	(segment
		(start 478.65919 -16.657574)
		(end 478.760536 -16.75892)
		(width 0.101346)
		(layer "In11.Cu")
		(net "NIC_SET_P_MDI_2_DP")
	)
	(segment
		(start 482.614986 -32.567372)
		(end 482.51364 -32.668718)
		(width 0.101346)
		(layer "In11.Cu")
		(net "NIC_SET_P_MDI_2_DP")
	)
	(segment
		(start 483.129336 -19.654012)
		(end 482.673152 -19.654012)
		(width 0.101346)
		(layer "In11.Cu")
		(net "NIC_SET_P_MDI_2_DP")
	)
	(segment
		(start 483.1842 -32.220154)
		(end 482.836982 -32.567372)
		(width 0.101346)
		(layer "In11.Cu")
		(net "NIC_SET_P_MDI_2_DP")
	)
	(segment
		(start 480.459034 -17.110964)
		(end 480.765612 -16.804386)
		(width 0.101346)
		(layer "In11.Cu")
		(net "NIC_SET_P_MDI_2_DP")
	)
	(segment
		(start 479.304604 -10.490454)
		(end 479.203258 -10.5918)
		(width 0.101346)
		(layer "In11.Cu")
		(net "NIC_SET_P_MDI_2_DP")
	)
	(segment
		(start 480.913948 1.250188)
		(end 480.566984 1.250188)
		(width 0.101346)
		(layer "In11.Cu")
		(net "NIC_SET_P_MDI_2_DP")
	)
	(segment
		(start 483.837742 -21.195538)
		(end 484.184706 -21.542502)
		(width 0.101346)
		(layer "In11.Cu")
		(net "NIC_SET_P_MDI_2_DP")
	)
	(segment
		(start 478.856294 -14.95552)
		(end 479.203258 -15.302484)
		(width 0.101346)
		(layer "In11.Cu")
		(net "NIC_SET_P_MDI_2_DP")
	)
	(segment
		(start 483.4763 -19.307048)
		(end 483.129336 -19.654012)
		(width 0.101346)
		(layer "In11.Cu")
		(net "NIC_SET_P_MDI_2_DP")
	)
	(segment
		(start 483.837488 -22.6568)
		(end 482.803962 -22.6568)
		(width 0.101346)
		(layer "In11.Cu")
		(net "NIC_SET_P_MDI_2_DP")
	)
	(segment
		(start 482.1428 4.399534)
		(end 482.1428 2.47904)
		(width 0.101346)
		(layer "In11.Cu")
		(net "NIC_SET_P_MDI_2_DP")
	)
	(segment
		(start 479.399346 -1.618996)
		(end 480.174046 -1.618996)
		(width 0.101346)
		(layer "In11.Cu")
		(net "NIC_SET_P_MDI_2_DP")
	)
	(segment
		(start 483.678992 -28.875482)
		(end 483.173786 -28.875482)
		(width 0.101346)
		(layer "In11.Cu")
		(net "NIC_SET_P_MDI_2_DP")
	)
	(segment
		(start 479.203258 -17.105884)
		(end 479.203258 -17.620488)
		(width 0.101346)
		(layer "In11.Cu")
		(net "NIC_SET_P_MDI_2_DP")
	)
	(segment
		(start 482.294946 -36.098988)
		(end 482.56317 -36.098988)
		(width 0.101346)
		(layer "In11.Cu")
		(net "NIC_SET_P_MDI_2_DP")
	)
	(segment
		(start 479.678492 -9.1694)
		(end 480.281234 -9.1694)
		(width 0.101346)
		(layer "In11.Cu")
		(net "NIC_SET_P_MDI_2_DP")
	)
	(segment
		(start 482.98354 -29.065728)
		(end 482.98354 -30.79877)
		(width 0.101346)
		(layer "In11.Cu")
		(net "NIC_SET_P_MDI_2_DP")
	)
	(segment
		(start 482.51364 -32.668718)
		(end 482.51364 -32.948372)
		(width 0.101346)
		(layer "In11.Cu")
		(net "NIC_SET_P_MDI_2_DP")
	)
	(segment
		(start 479.186748 -1.406398)
		(end 479.399346 -1.618996)
		(width 0.101346)
		(layer "In11.Cu")
		(net "NIC_SET_P_MDI_2_DP")
	)
	(segment
		(start 482.220778 -35.22091)
		(end 482.119432 -35.322256)
		(width 0.101346)
		(layer "In11.Cu")
		(net "NIC_SET_P_MDI_2_DP")
	)
	(segment
		(start 481.734114 4.80822)
		(end 482.1428 4.399534)
		(width 0.101346)
		(layer "In11.Cu")
		(net "NIC_SET_P_MDI_2_DP")
	)
	(segment
		(start 480.281234 -10.490454)
		(end 479.304604 -10.490454)
		(width 0.101346)
		(layer "In11.Cu")
		(net "NIC_SET_P_MDI_2_DP")
	)
	(segment
		(start 479.444558 -3.061208)
		(end 479.343212 -3.162554)
		(width 0.101346)
		(layer "In11.Cu")
		(net "NIC_SET_P_MDI_2_DP")
	)
	(segment
		(start 479.577146 -8.611616)
		(end 479.577146 -9.068054)
		(width 0.101346)
		(layer "In11.Cu")
		(net "NIC_SET_P_MDI_2_DP")
	)
	(segment
		(start 480.212146 -18.271744)
		(end 480.459034 -18.024856)
		(width 0.101346)
		(layer "In11.Cu")
		(net "NIC_SET_P_MDI_2_DP")
	)
	(segment
		(start 483.701344 -27.34691)
		(end 484.070406 -27.715972)
		(width 0.101346)
		(layer "In11.Cu")
		(net "NIC_SET_P_MDI_2_DP")
	)
	(segment
		(start 482.852476 -25.13457)
		(end 483.687882 -25.13457)
		(width 0.101346)
		(layer "In11.Cu")
		(net "NIC_SET_P_MDI_2_DP")
	)
	(segment
		(start 479.212656 1.250442)
		(end 479.110802 1.148588)
		(width 0.101346)
		(layer "In11.Cu")
		(net "NIC_SET_P_MDI_2_DP")
	)
	(segment
		(start 480.914456 1.250442)
		(end 480.914202 1.250442)
		(width 0.101346)
		(layer "In11.Cu")
		(net "NIC_SET_P_MDI_2_DP")
	)
	(segment
		(start 480.153726 -3.061208)
		(end 479.444558 -3.061208)
		(width 0.101346)
		(layer "In11.Cu")
		(net "NIC_SET_P_MDI_2_DP")
	)
	(segment
		(start 480.281234 -9.1694)
		(end 480.628198 -9.516364)
		(width 0.101346)
		(layer "In11.Cu")
		(net "NIC_SET_P_MDI_2_DP")
	)
	(segment
		(start 479.110802 0.727964)
		(end 479.197924 0.640842)
		(width 0.101346)
		(layer "In11.Cu")
		(net "NIC_SET_P_MDI_2_DP")
	)
	(segment
		(start 484.070406 -27.715972)
		(end 484.070406 -28.484068)
		(width 0.101346)
		(layer "In11.Cu")
		(net "NIC_SET_P_MDI_2_DP")
	)
	(segment
		(start 480.26066 -0.861568)
		(end 479.453956 -0.861568)
		(width 0.101346)
		(layer "In11.Cu")
		(net "NIC_SET_P_MDI_2_DP")
	)
	(segment
		(start 479.343212 -3.162554)
		(end 479.343212 -3.66903)
		(width 0.101346)
		(layer "In11.Cu")
		(net "NIC_SET_P_MDI_2_DP")
	)
	(segment
		(start 481.573332 -16.804386)
		(end 481.92055 -17.151604)
		(width 0.101346)
		(layer "In11.Cu")
		(net "NIC_SET_P_MDI_2_DP")
	)
	(segment
		(start 482.739192 -22.72157)
		(end 482.739192 -22.75713)
		(width 0.101346)
		(layer "In11.Cu")
		(net "NIC_SET_P_MDI_2_DP")
	)
	(segment
		(start 482.571552 -19.755612)
		(end 482.571552 -21.051266)
		(width 0.101346)
		(layer "In11.Cu")
		(net "NIC_SET_P_MDI_2_DP")
	)
	(segment
		(start 479.203258 -10.5918)
		(end 479.203258 -14.12621)
		(width 0.101346)
		(layer "In11.Cu")
		(net "NIC_SET_P_MDI_2_DP")
	)
	(segment
		(start 480.842574 4.921504)
		(end 480.955858 4.80822)
		(width 0.101346)
		(layer "In11.Cu")
		(net "NIC_SET_P_MDI_2_DP")
	)
	(segment
		(start 478.856294 -14.473174)
		(end 478.760536 -14.473174)
		(width 0.101346)
		(layer "In11.Cu")
		(net "NIC_SET_P_MDI_2_DP")
	)
	(segment
		(start 478.760536 -16.75892)
		(end 478.856294 -16.75892)
		(width 0.101346)
		(layer "In11.Cu")
		(net "NIC_SET_P_MDI_2_DP")
	)
	(segment
		(start 481.15982 1.49606)
		(end 481.15982 1.495806)
		(width 0.101346)
		(layer "In11.Cu")
		(net "NIC_SET_P_MDI_2_DP")
	)
	(segment
		(start 482.728778 -35.22091)
		(end 482.220778 -35.22091)
		(width 0.101346)
		(layer "In11.Cu")
		(net "NIC_SET_P_MDI_2_DP")
	)
	(segment
		(start 479.453956 -0.861568)
		(end 479.186748 -1.128776)
		(width 0.101346)
		(layer "In11.Cu")
		(net "NIC_SET_P_MDI_2_DP")
	)
	(segment
		(start 479.343212 -3.66903)
		(end 479.480118 -3.805936)
		(width 0.101346)
		(layer "In11.Cu")
		(net "NIC_SET_P_MDI_2_DP")
	)
	(segment
		(start 481.92055 -17.567656)
		(end 482.048312 -17.695418)
		(width 0.101346)
		(layer "In11.Cu")
		(net "NIC_SET_P_MDI_2_DP")
	)
	(segment
		(start 480.56673 1.250442)
		(end 479.212656 1.250442)
		(width 0.101346)
		(layer "In11.Cu")
		(net "NIC_SET_P_MDI_2_DP")
	)
	(segment
		(start 479.186748 -1.128776)
		(end 479.186748 -1.406398)
		(width 0.101346)
		(layer "In11.Cu")
		(net "NIC_SET_P_MDI_2_DP")
	)
	(segment
		(start 483.4763 -18.146522)
		(end 483.4763 -19.307048)
		(width 0.101346)
		(layer "In11.Cu")
		(net "NIC_SET_P_MDI_2_DP")
	)
	(segment
		(start 482.571552 -21.051266)
		(end 482.715824 -21.195538)
		(width 0.101346)
		(layer "In11.Cu")
		(net "NIC_SET_P_MDI_2_DP")
	)
	(segment
		(start 480.514406 -4.140962)
		(end 480.514406 -7.674356)
		(width 0.101346)
		(layer "In11.Cu")
		(net "NIC_SET_P_MDI_2_DP")
	)
	(segment
		(start 482.673152 -19.654012)
		(end 482.571552 -19.755612)
		(width 0.101346)
		(layer "In11.Cu")
		(net "NIC_SET_P_MDI_2_DP")
	)
	(segment
		(start 482.1428 2.47904)
		(end 481.15982 1.49606)
		(width 0.101346)
		(layer "In11.Cu")
		(net "NIC_SET_P_MDI_2_DP")
	)
	(segment
		(start 483.037642 -26.699464)
		(end 483.037642 -27.130756)
		(width 0.101346)
		(layer "In11.Cu")
		(net "NIC_SET_P_MDI_2_DP")
	)
	(segment
		(start 478.760536 -14.95552)
		(end 478.856294 -14.95552)
		(width 0.101346)
		(layer "In11.Cu")
		(net "NIC_SET_P_MDI_2_DP")
	)
	(segment
		(start 478.65919 -14.854174)
		(end 478.760536 -14.95552)
		(width 0.101346)
		(layer "In11.Cu")
		(net "NIC_SET_P_MDI_2_DP")
	)
	(segment
		(start 482.51364 -32.948372)
		(end 482.614986 -33.049718)
		(width 0.101346)
		(layer "In11.Cu")
		(net "NIC_SET_P_MDI_2_DP")
	)
	(segment
		(start 483.173786 -28.875482)
		(end 482.98354 -29.065728)
		(width 0.101346)
		(layer "In11.Cu")
		(net "NIC_SET_P_MDI_2_DP")
	)
	(segment
		(start 478.760536 -14.473174)
		(end 478.65919 -14.57452)
		(width 0.101346)
		(layer "In11.Cu")
		(net "NIC_SET_P_MDI_2_DP")
	)
	(segment
		(start 484.027988 -25.474676)
		(end 484.027988 -26.242772)
		(width 0.101346)
		(layer "In11.Cu")
		(net "NIC_SET_P_MDI_2_DP")
	)
	(segment
		(start 480.566984 1.250188)
		(end 480.56673 1.250442)
		(width 0.101346)
		(layer "In11.Cu")
		(net "NIC_SET_P_MDI_2_DP")
	)
	(segment
		(start 479.577146 -9.068054)
		(end 479.678492 -9.1694)
		(width 0.101346)
		(layer "In11.Cu")
		(net "NIC_SET_P_MDI_2_DP")
	)
	(segment
		(start 483.253796 -27.34691)
		(end 483.701344 -27.34691)
		(width 0.101346)
		(layer "In11.Cu")
		(net "NIC_SET_P_MDI_2_DP")
	)
	(segment
		(start 482.725476 -22.770846)
		(end 482.725476 -25.00757)
		(width 0.101346)
		(layer "In11.Cu")
		(net "NIC_SET_P_MDI_2_DP")
	)
	(segment
		(start 483.037642 -27.130756)
		(end 483.253796 -27.34691)
		(width 0.101346)
		(layer "In11.Cu")
		(net "NIC_SET_P_MDI_2_DP")
	)
	(segment
		(start 480.648772 -0.473456)
		(end 480.26066 -0.861568)
		(width 0.101346)
		(layer "In11.Cu")
		(net "NIC_SET_P_MDI_2_DP")
	)
	(segment
		(start 483.687882 -25.13457)
		(end 484.027988 -25.474676)
		(width 0.101346)
		(layer "In11.Cu")
		(net "NIC_SET_P_MDI_2_DP")
	)
	(segment
		(start 481.15982 1.495806)
		(end 480.914456 1.250442)
		(width 0.101346)
		(layer "In11.Cu")
		(net "NIC_SET_P_MDI_2_DP")
	)
	(segment
		(start 478.760536 -16.276574)
		(end 478.65919 -16.37792)
		(width 0.101346)
		(layer "In11.Cu")
		(net "NIC_SET_P_MDI_2_DP")
	)
	(segment
		(start 482.119432 -35.322256)
		(end 482.119432 -35.923474)
		(width 0.101346)
		(layer "In11.Cu")
		(net "NIC_SET_P_MDI_2_DP")
	)
	(segment
		(start 484.184706 -21.542502)
		(end 484.184706 -22.309582)
		(width 0.101346)
		(layer "In11.Cu")
		(net "NIC_SET_P_MDI_2_DP")
	)
	(segment
		(start 482.614986 -33.049718)
		(end 482.837236 -33.049718)
		(width 0.101346)
		(layer "In11.Cu")
		(net "NIC_SET_P_MDI_2_DP")
	)
	(segment
		(start 482.048312 -17.695418)
		(end 483.025196 -17.695418)
		(width 0.101346)
		(layer "In11.Cu")
		(net "NIC_SET_P_MDI_2_DP")
	)
	(segment
		(start 484.070406 -28.484068)
		(end 483.678992 -28.875482)
		(width 0.101346)
		(layer "In11.Cu")
		(net "NIC_SET_P_MDI_2_DP")
	)
	(segment
		(start 479.197924 0.640842)
		(end 480.209606 0.640842)
		(width 0.101346)
		(layer "In11.Cu")
		(net "NIC_SET_P_MDI_2_DP")
	)
	(segment
		(start 482.739192 -22.75713)
		(end 482.725476 -22.770846)
		(width 0.101346)
		(layer "In11.Cu")
		(net "NIC_SET_P_MDI_2_DP")
	)
	(segment
		(start 482.725476 -25.00757)
		(end 482.852476 -25.13457)
		(width 0.101346)
		(layer "In11.Cu")
		(net "NIC_SET_P_MDI_2_DP")
	)
	(segment
		(start 478.65919 -14.57452)
		(end 478.65919 -14.854174)
		(width 0.101346)
		(layer "In11.Cu")
		(net "NIC_SET_P_MDI_2_DP")
	)
	(segment
		(start 480.628198 -9.516364)
		(end 480.628198 -10.14349)
		(width 0.101346)
		(layer "In11.Cu")
		(net "NIC_SET_P_MDI_2_DP")
	)
	(segment
		(start 480.514406 -7.674356)
		(end 479.577146 -8.611616)
		(width 0.101346)
		(layer "In11.Cu")
		(net "NIC_SET_P_MDI_2_DP")
	)
	(segment
		(start 479.110802 1.148588)
		(end 479.110802 0.727964)
		(width 0.101346)
		(layer "In11.Cu")
		(net "NIC_SET_P_MDI_2_DP")
	)
	(segment
		(start 478.65919 -16.37792)
		(end 478.65919 -16.657574)
		(width 0.101346)
		(layer "In11.Cu")
		(net "NIC_SET_P_MDI_2_DP")
	)
	(segment
		(start 483.025196 -17.695418)
		(end 483.4763 -18.146522)
		(width 0.101346)
		(layer "In11.Cu")
		(net "NIC_SET_P_MDI_2_DP")
	)
	(segment
		(start 480.765612 -16.804386)
		(end 481.573332 -16.804386)
		(width 0.101346)
		(layer "In11.Cu")
		(net "NIC_SET_P_MDI_2_DP")
	)
	(segment
		(start 479.203258 -14.12621)
		(end 478.856294 -14.473174)
		(width 0.101346)
		(layer "In11.Cu")
		(net "NIC_SET_P_MDI_2_DP")
	)
	(segment
		(start 480.842574 5.26669)
		(end 480.842574 4.921504)
		(width 0.101346)
		(layer "In11.Cu")
		(net "NIC_SET_P_MDI_2_DP")
	)
	(segment
		(start 480.17938 -3.805936)
		(end 480.514406 -4.140962)
		(width 0.101346)
		(layer "In11.Cu")
		(net "NIC_SET_P_MDI_2_DP")
	)
	(segment
		(start 482.803962 -22.6568)
		(end 482.739192 -22.72157)
		(width 0.101346)
		(layer "In11.Cu")
		(net "NIC_SET_P_MDI_2_DP")
	)
	(segment
		(start 478.856294 -16.276574)
		(end 478.760536 -16.276574)
		(width 0.101346)
		(layer "In11.Cu")
		(net "NIC_SET_P_MDI_2_DP")
	)
	(segment
		(start 480.50069 -2.714244)
		(end 480.153726 -3.061208)
		(width 0.101346)
		(layer "In11.Cu")
		(net "NIC_SET_P_MDI_2_DP")
	)
	(segment
		(start 478.856294 -16.75892)
		(end 479.203258 -17.105884)
		(width 0.101346)
		(layer "In11.Cu")
		(net "NIC_SET_P_MDI_2_DP")
	)
	(segment
		(start 483.1842 -34.765488)
		(end 482.728778 -35.22091)
		(width 0.101346)
		(layer "In11.Cu")
		(net "NIC_SET_P_MDI_2_DP")
	)
	(segment
		(start 480.914202 1.250442)
		(end 480.913948 1.250188)
		(width 0.101346)
		(layer "In11.Cu")
		(net "NIC_SET_P_MDI_2_DP")
	)
	(segment
		(start 483.154228 -26.582878)
		(end 483.037642 -26.699464)
		(width 0.101346)
		(layer "In11.Cu")
		(net "NIC_SET_P_MDI_2_DP")
	)
	(segment
		(start 480.648772 0.201676)
		(end 480.648772 -0.473456)
		(width 0.101346)
		(layer "In11.Cu")
		(net "NIC_SET_P_MDI_2_DP")
	)
	(segment
		(start 483.687882 -26.582878)
		(end 483.154228 -26.582878)
		(width 0.101346)
		(layer "In11.Cu")
		(net "NIC_SET_P_MDI_2_DP")
	)
	(segment
		(start 482.119432 -35.923474)
		(end 482.294946 -36.098988)
		(width 0.101346)
		(layer "In11.Cu")
		(net "NIC_SET_P_MDI_2_DP")
	)
	(segment
		(start 482.836982 -32.567372)
		(end 482.614986 -32.567372)
		(width 0.101346)
		(layer "In11.Cu")
		(net "NIC_SET_P_MDI_2_DP")
	)
	(segment
		(start 484.184706 -22.309582)
		(end 483.837488 -22.6568)
		(width 0.101346)
		(layer "In11.Cu")
		(net "NIC_SET_P_MDI_2_DP")
	)
	(segment
		(start 482.98354 -30.79877)
		(end 483.1842 -30.99943)
		(width 0.101346)
		(layer "In11.Cu")
		(net "NIC_SET_P_MDI_2_DP")
	)
	(segment
		(start 482.022404 -37.688012)
		(end 481.739956 -37.405564)
		(width 0.10033)
		(layer "F.Cu")
		(net "NIC_SET_N_MDI_2_DN")
	)
	(segment
		(start 481.739956 -36.33851)
		(end 481.500434 -36.098988)
		(width 0.10033)
		(layer "F.Cu")
		(net "NIC_SET_N_MDI_2_DN")
	)
	(segment
		(start 482.022404 -38.969442)
		(end 482.022404 -37.688012)
		(width 0.10033)
		(layer "F.Cu")
		(net "NIC_SET_N_MDI_2_DN")
	)
	(segment
		(start 481.739956 -37.405564)
		(end 481.739956 -36.33851)
		(width 0.10033)
		(layer "F.Cu")
		(net "NIC_SET_N_MDI_2_DN")
	)
	(segment
		(start 480.845876 3.820668)
		(end 480.845876 3.211068)
		(width 0.10033)
		(layer "F.Cu")
		(net "NIC_SET_N_MDI_2_DN")
	)
	(segment
		(start 481.500434 -36.098988)
		(end 481.29317 -36.098988)
		(width 0.10033)
		(layer "F.Cu")
		(net "NIC_SET_N_MDI_2_DN")
	)
	(segment
		(start 482.001068 -38.990778)
		(end 482.022404 -38.969442)
		(width 0.10033)
		(layer "F.Cu")
		(net "NIC_SET_N_MDI_2_DN")
	)
	(segment
		(start 482.001068 -39.5986)
		(end 482.001068 -38.990778)
		(width 0.10033)
		(layer "F.Cu")
		(net "NIC_SET_N_MDI_2_DN")
	)
	(via
		(at 480.845876 3.211068)
		(size 0.508)
		(drill 0.254)
		(layers "F.Cu" "B.Cu")
		(net "NIC_SET_N_MDI_2_DN")
	)
	(via
		(at 481.29317 -36.098988)
		(size 0.508)
		(drill 0.254)
		(layers "F.Cu" "B.Cu")
		(net "NIC_SET_N_MDI_2_DN")
	)
	(segment
		(start 479.024188 0.221488)
		(end 480.03587 0.221488)
		(width 0.101346)
		(layer "In11.Cu")
		(net "NIC_SET_N_MDI_2_DN")
	)
	(segment
		(start 479.97999 -2.641854)
		(end 479.270822 -2.641854)
		(width 0.101346)
		(layer "In11.Cu")
		(net "NIC_SET_N_MDI_2_DN")
	)
	(segment
		(start 482.764846 -33.570418)
		(end 482.764846 -34.591752)
		(width 0.101346)
		(layer "In11.Cu")
		(net "NIC_SET_N_MDI_2_DN")
	)
	(segment
		(start 480.095052 -4.314698)
		(end 480.095052 -7.50062)
		(width 0.101346)
		(layer "In11.Cu")
		(net "NIC_SET_N_MDI_2_DN")
	)
	(segment
		(start 483.664006 -28.28671)
		(end 483.561898 -28.388818)
		(width 0.101346)
		(layer "In11.Cu")
		(net "NIC_SET_N_MDI_2_DN")
	)
	(segment
		(start 482.764846 -32.046418)
		(end 482.663246 -32.148018)
		(width 0.101346)
		(layer "In11.Cu")
		(net "NIC_SET_N_MDI_2_DN")
	)
	(segment
		(start 479.28022 -0.442214)
		(end 478.767394 -0.95504)
		(width 0.101346)
		(layer "In11.Cu")
		(net "NIC_SET_N_MDI_2_DN")
	)
	(segment
		(start 480.972876 4.388866)
		(end 481.560378 4.388866)
		(width 0.101346)
		(layer "In11.Cu")
		(net "NIC_SET_N_MDI_2_DN")
	)
	(segment
		(start 479.270822 -2.641854)
		(end 478.923858 -2.988818)
		(width 0.101346)
		(layer "In11.Cu")
		(net "NIC_SET_N_MDI_2_DN")
	)
	(segment
		(start 479.22561 -2.03835)
		(end 480.00031 -2.03835)
		(width 0.101346)
		(layer "In11.Cu")
		(net "NIC_SET_N_MDI_2_DN")
	)
	(segment
		(start 482.764846 -31.173166)
		(end 482.764846 -32.046418)
		(width 0.101346)
		(layer "In11.Cu")
		(net "NIC_SET_N_MDI_2_DN")
	)
	(segment
		(start 481.723446 4.225798)
		(end 481.723446 2.652776)
		(width 0.101346)
		(layer "In11.Cu")
		(net "NIC_SET_N_MDI_2_DN")
	)
	(segment
		(start 482.663246 -32.148018)
		(end 482.44125 -32.148018)
		(width 0.101346)
		(layer "In11.Cu")
		(net "NIC_SET_N_MDI_2_DN")
	)
	(segment
		(start 483.519734 -26.17724)
		(end 482.98608 -26.17724)
		(width 0.101346)
		(layer "In11.Cu")
		(net "NIC_SET_N_MDI_2_DN")
	)
	(segment
		(start 482.555042 -34.801556)
		(end 482.047042 -34.801556)
		(width 0.101346)
		(layer "In11.Cu")
		(net "NIC_SET_N_MDI_2_DN")
	)
	(segment
		(start 480.740466 1.669796)
		(end 479.03892 1.669796)
		(width 0.101346)
		(layer "In11.Cu")
		(net "NIC_SET_N_MDI_2_DN")
	)
	(segment
		(start 481.501196 -17.32534)
		(end 481.501196 -17.741392)
		(width 0.101346)
		(layer "In11.Cu")
		(net "NIC_SET_N_MDI_2_DN")
	)
	(segment
		(start 482.9556 -19.234658)
		(end 482.499416 -19.234658)
		(width 0.101346)
		(layer "In11.Cu")
		(net "NIC_SET_N_MDI_2_DN")
	)
	(segment
		(start 482.542088 -21.614892)
		(end 483.664006 -21.614892)
		(width 0.101346)
		(layer "In11.Cu")
		(net "NIC_SET_N_MDI_2_DN")
	)
	(segment
		(start 478.783904 -10.418064)
		(end 478.783904 -13.952474)
		(width 0.101346)
		(layer "In11.Cu")
		(net "NIC_SET_N_MDI_2_DN")
	)
	(segment
		(start 480.081336 -2.540508)
		(end 479.97999 -2.641854)
		(width 0.101346)
		(layer "In11.Cu")
		(net "NIC_SET_N_MDI_2_DN")
	)
	(segment
		(start 482.6635 -33.469072)
		(end 482.764846 -33.570418)
		(width 0.101346)
		(layer "In11.Cu")
		(net "NIC_SET_N_MDI_2_DN")
	)
	(segment
		(start 483.532942 -27.75331)
		(end 483.664006 -27.884374)
		(width 0.101346)
		(layer "In11.Cu")
		(net "NIC_SET_N_MDI_2_DN")
	)
	(segment
		(start 482.564186 -28.891992)
		(end 482.564186 -30.972506)
		(width 0.101346)
		(layer "In11.Cu")
		(net "NIC_SET_N_MDI_2_DN")
	)
	(segment
		(start 482.047042 -34.801556)
		(end 481.700078 -35.14852)
		(width 0.101346)
		(layer "In11.Cu")
		(net "NIC_SET_N_MDI_2_DN")
	)
	(segment
		(start 478.682558 -14.05382)
		(end 478.5868 -14.05382)
		(width 0.101346)
		(layer "In11.Cu")
		(net "NIC_SET_N_MDI_2_DN")
	)
	(segment
		(start 478.682558 -17.178274)
		(end 478.783904 -17.27962)
		(width 0.101346)
		(layer "In11.Cu")
		(net "NIC_SET_N_MDI_2_DN")
	)
	(segment
		(start 479.157792 -9.24179)
		(end 479.504756 -9.588754)
		(width 0.101346)
		(layer "In11.Cu")
		(net "NIC_SET_N_MDI_2_DN")
	)
	(segment
		(start 483.08641 -28.388818)
		(end 483.0191 -28.456128)
		(width 0.101346)
		(layer "In11.Cu")
		(net "NIC_SET_N_MDI_2_DN")
	)
	(segment
		(start 481.874576 -18.114772)
		(end 482.85146 -18.114772)
		(width 0.101346)
		(layer "In11.Cu")
		(net "NIC_SET_N_MDI_2_DN")
	)
	(segment
		(start 480.229418 0.02794)
		(end 480.229418 -0.29972)
		(width 0.101346)
		(layer "In11.Cu")
		(net "NIC_SET_N_MDI_2_DN")
	)
	(segment
		(start 483.056946 -19.133312)
		(end 482.9556 -19.234658)
		(width 0.101346)
		(layer "In11.Cu")
		(net "NIC_SET_N_MDI_2_DN")
	)
	(segment
		(start 481.700078 -35.14852)
		(end 481.700078 -35.971988)
		(width 0.101346)
		(layer "In11.Cu")
		(net "NIC_SET_N_MDI_2_DN")
	)
	(segment
		(start 482.44125 -33.469072)
		(end 482.6635 -33.469072)
		(width 0.101346)
		(layer "In11.Cu")
		(net "NIC_SET_N_MDI_2_DN")
	)
	(segment
		(start 479.504756 -9.588754)
		(end 480.107498 -9.588754)
		(width 0.101346)
		(layer "In11.Cu")
		(net "NIC_SET_N_MDI_2_DN")
	)
	(segment
		(start 483.765352 -21.716238)
		(end 483.765352 -22.135846)
		(width 0.101346)
		(layer "In11.Cu")
		(net "NIC_SET_N_MDI_2_DN")
	)
	(segment
		(start 478.239836 -15.02791)
		(end 478.5868 -15.374874)
		(width 0.101346)
		(layer "In11.Cu")
		(net "NIC_SET_N_MDI_2_DN")
	)
	(segment
		(start 478.783904 -17.794224)
		(end 479.680778 -18.691098)
		(width 0.101346)
		(layer "In11.Cu")
		(net "NIC_SET_N_MDI_2_DN")
	)
	(segment
		(start 478.767394 -1.580134)
		(end 479.22561 -2.03835)
		(width 0.101346)
		(layer "In11.Cu")
		(net "NIC_SET_N_MDI_2_DN")
	)
	(segment
		(start 483.00005 -28.456128)
		(end 482.564186 -28.891992)
		(width 0.101346)
		(layer "In11.Cu")
		(net "NIC_SET_N_MDI_2_DN")
	)
	(segment
		(start 478.5868 -17.178274)
		(end 478.682558 -17.178274)
		(width 0.101346)
		(layer "In11.Cu")
		(net "NIC_SET_N_MDI_2_DN")
	)
	(segment
		(start 478.767394 -0.95504)
		(end 478.767394 -1.580134)
		(width 0.101346)
		(layer "In11.Cu")
		(net "NIC_SET_N_MDI_2_DN")
	)
	(segment
		(start 480.208844 -9.6901)
		(end 480.208844 -9.969754)
		(width 0.101346)
		(layer "In11.Cu")
		(net "NIC_SET_N_MDI_2_DN")
	)
	(segment
		(start 482.564186 -30.972506)
		(end 482.764846 -31.173166)
		(width 0.101346)
		(layer "In11.Cu")
		(net "NIC_SET_N_MDI_2_DN")
	)
	(segment
		(start 478.239836 -16.83131)
		(end 478.5868 -17.178274)
		(width 0.101346)
		(layer "In11.Cu")
		(net "NIC_SET_N_MDI_2_DN")
	)
	(segment
		(start 479.03892 1.669796)
		(end 478.691448 1.322324)
		(width 0.101346)
		(layer "In11.Cu")
		(net "NIC_SET_N_MDI_2_DN")
	)
	(segment
		(start 480.03587 0.221488)
		(end 480.229418 0.02794)
		(width 0.101346)
		(layer "In11.Cu")
		(net "NIC_SET_N_MDI_2_DN")
	)
	(segment
		(start 480.845876 4.261866)
		(end 480.972876 4.388866)
		(width 0.101346)
		(layer "In11.Cu")
		(net "NIC_SET_N_MDI_2_DN")
	)
	(segment
		(start 481.573078 -36.098988)
		(end 481.29317 -36.098988)
		(width 0.101346)
		(layer "In11.Cu")
		(net "NIC_SET_N_MDI_2_DN")
	)
	(segment
		(start 483.62235 -26.074624)
		(end 483.519734 -26.17724)
		(width 0.101346)
		(layer "In11.Cu")
		(net "NIC_SET_N_MDI_2_DN")
	)
	(segment
		(start 482.98608 -26.17724)
		(end 482.632004 -26.531316)
		(width 0.101346)
		(layer "In11.Cu")
		(net "NIC_SET_N_MDI_2_DN")
	)
	(segment
		(start 482.85146 -18.114772)
		(end 483.056946 -18.320258)
		(width 0.101346)
		(layer "In11.Cu")
		(net "NIC_SET_N_MDI_2_DN")
	)
	(segment
		(start 482.152198 -19.581876)
		(end 482.152198 -21.225002)
		(width 0.101346)
		(layer "In11.Cu")
		(net "NIC_SET_N_MDI_2_DN")
	)
	(segment
		(start 480.107498 -9.588754)
		(end 480.208844 -9.6901)
		(width 0.101346)
		(layer "In11.Cu")
		(net "NIC_SET_N_MDI_2_DN")
	)
	(segment
		(start 481.700078 -35.971988)
		(end 481.573078 -36.098988)
		(width 0.101346)
		(layer "In11.Cu")
		(net "NIC_SET_N_MDI_2_DN")
	)
	(segment
		(start 482.499416 -19.234658)
		(end 482.152198 -19.581876)
		(width 0.101346)
		(layer "In11.Cu")
		(net "NIC_SET_N_MDI_2_DN")
	)
	(segment
		(start 480.086924 -0.442214)
		(end 479.28022 -0.442214)
		(width 0.101346)
		(layer "In11.Cu")
		(net "NIC_SET_N_MDI_2_DN")
	)
	(segment
		(start 482.094286 -32.494982)
		(end 482.094286 -33.122108)
		(width 0.101346)
		(layer "In11.Cu")
		(net "NIC_SET_N_MDI_2_DN")
	)
	(segment
		(start 478.5868 -15.85722)
		(end 478.239836 -16.204184)
		(width 0.101346)
		(layer "In11.Cu")
		(net "NIC_SET_N_MDI_2_DN")
	)
	(segment
		(start 480.878388 -18.198592)
		(end 480.878388 -17.2847)
		(width 0.101346)
		(layer "In11.Cu")
		(net "NIC_SET_N_MDI_2_DN")
	)
	(segment
		(start 482.632004 -27.29992)
		(end 483.085394 -27.75331)
		(width 0.101346)
		(layer "In11.Cu")
		(net "NIC_SET_N_MDI_2_DN")
	)
	(segment
		(start 479.130868 -10.0711)
		(end 478.783904 -10.418064)
		(width 0.101346)
		(layer "In11.Cu")
		(net "NIC_SET_N_MDI_2_DN")
	)
	(segment
		(start 481.399596 -17.22374)
		(end 481.501196 -17.32534)
		(width 0.101346)
		(layer "In11.Cu")
		(net "NIC_SET_N_MDI_2_DN")
	)
	(segment
		(start 478.239836 -16.204184)
		(end 478.239836 -16.83131)
		(width 0.101346)
		(layer "In11.Cu")
		(net "NIC_SET_N_MDI_2_DN")
	)
	(segment
		(start 482.094286 -33.122108)
		(end 482.44125 -33.469072)
		(width 0.101346)
		(layer "In11.Cu")
		(net "NIC_SET_N_MDI_2_DN")
	)
	(segment
		(start 478.783904 -13.952474)
		(end 478.682558 -14.05382)
		(width 0.101346)
		(layer "In11.Cu")
		(net "NIC_SET_N_MDI_2_DN")
	)
	(segment
		(start 478.783904 -15.755874)
		(end 478.682558 -15.85722)
		(width 0.101346)
		(layer "In11.Cu")
		(net "NIC_SET_N_MDI_2_DN")
	)
	(segment
		(start 478.783904 -17.27962)
		(end 478.783904 -17.794224)
		(width 0.101346)
		(layer "In11.Cu")
		(net "NIC_SET_N_MDI_2_DN")
	)
	(segment
		(start 482.44125 -32.148018)
		(end 482.094286 -32.494982)
		(width 0.101346)
		(layer "In11.Cu")
		(net "NIC_SET_N_MDI_2_DN")
	)
	(segment
		(start 479.306382 -4.22529)
		(end 480.005644 -4.22529)
		(width 0.101346)
		(layer "In11.Cu")
		(net "NIC_SET_N_MDI_2_DN")
	)
	(segment
		(start 479.680778 -18.691098)
		(end 480.385882 -18.691098)
		(width 0.101346)
		(layer "In11.Cu")
		(net "NIC_SET_N_MDI_2_DN")
	)
	(segment
		(start 482.152198 -21.225002)
		(end 482.542088 -21.614892)
		(width 0.101346)
		(layer "In11.Cu")
		(net "NIC_SET_N_MDI_2_DN")
	)
	(segment
		(start 481.501196 -17.741392)
		(end 481.874576 -18.114772)
		(width 0.101346)
		(layer "In11.Cu")
		(net "NIC_SET_N_MDI_2_DN")
	)
	(segment
		(start 482.319838 -22.547834)
		(end 482.319838 -25.224486)
		(width 0.101346)
		(layer "In11.Cu")
		(net "NIC_SET_N_MDI_2_DN")
	)
	(segment
		(start 483.663752 -22.237446)
		(end 482.630226 -22.237446)
		(width 0.101346)
		(layer "In11.Cu")
		(net "NIC_SET_N_MDI_2_DN")
	)
	(segment
		(start 480.081336 -2.119376)
		(end 480.081336 -2.540508)
		(width 0.101346)
		(layer "In11.Cu")
		(net "NIC_SET_N_MDI_2_DN")
	)
	(segment
		(start 483.561898 -28.388818)
		(end 483.08641 -28.388818)
		(width 0.101346)
		(layer "In11.Cu")
		(net "NIC_SET_N_MDI_2_DN")
	)
	(segment
		(start 480.878388 -17.2847)
		(end 480.939348 -17.22374)
		(width 0.101346)
		(layer "In11.Cu")
		(net "NIC_SET_N_MDI_2_DN")
	)
	(segment
		(start 478.923858 -2.988818)
		(end 478.923858 -3.842766)
		(width 0.101346)
		(layer "In11.Cu")
		(net "NIC_SET_N_MDI_2_DN")
	)
	(segment
		(start 481.723446 2.652776)
		(end 480.740466 1.669796)
		(width 0.101346)
		(layer "In11.Cu")
		(net "NIC_SET_N_MDI_2_DN")
	)
	(segment
		(start 482.319838 -25.224486)
		(end 482.63556 -25.540208)
		(width 0.101346)
		(layer "In11.Cu")
		(net "NIC_SET_N_MDI_2_DN")
	)
	(segment
		(start 483.519734 -25.540208)
		(end 483.62235 -25.642824)
		(width 0.101346)
		(layer "In11.Cu")
		(net "NIC_SET_N_MDI_2_DN")
	)
	(segment
		(start 483.664006 -21.614892)
		(end 483.765352 -21.716238)
		(width 0.101346)
		(layer "In11.Cu")
		(net "NIC_SET_N_MDI_2_DN")
	)
	(segment
		(start 478.691448 0.554228)
		(end 479.024188 0.221488)
		(width 0.101346)
		(layer "In11.Cu")
		(net "NIC_SET_N_MDI_2_DN")
	)
	(segment
		(start 482.630226 -22.237446)
		(end 482.319838 -22.547834)
		(width 0.101346)
		(layer "In11.Cu")
		(net "NIC_SET_N_MDI_2_DN")
	)
	(segment
		(start 480.00031 -2.03835)
		(end 480.081336 -2.119376)
		(width 0.101346)
		(layer "In11.Cu")
		(net "NIC_SET_N_MDI_2_DN")
	)
	(segment
		(start 478.682558 -15.374874)
		(end 478.783904 -15.47622)
		(width 0.101346)
		(layer "In11.Cu")
		(net "NIC_SET_N_MDI_2_DN")
	)
	(segment
		(start 483.765352 -22.135846)
		(end 483.663752 -22.237446)
		(width 0.101346)
		(layer "In11.Cu")
		(net "NIC_SET_N_MDI_2_DN")
	)
	(segment
		(start 480.229418 -0.29972)
		(end 480.086924 -0.442214)
		(width 0.101346)
		(layer "In11.Cu")
		(net "NIC_SET_N_MDI_2_DN")
	)
	(segment
		(start 478.691448 1.322324)
		(end 478.691448 0.554228)
		(width 0.101346)
		(layer "In11.Cu")
		(net "NIC_SET_N_MDI_2_DN")
	)
	(segment
		(start 478.239836 -14.400784)
		(end 478.239836 -15.02791)
		(width 0.101346)
		(layer "In11.Cu")
		(net "NIC_SET_N_MDI_2_DN")
	)
	(segment
		(start 480.939348 -17.22374)
		(end 481.399596 -17.22374)
		(width 0.101346)
		(layer "In11.Cu")
		(net "NIC_SET_N_MDI_2_DN")
	)
	(segment
		(start 483.664006 -27.884374)
		(end 483.664006 -28.28671)
		(width 0.101346)
		(layer "In11.Cu")
		(net "NIC_SET_N_MDI_2_DN")
	)
	(segment
		(start 483.085394 -27.75331)
		(end 483.532942 -27.75331)
		(width 0.101346)
		(layer "In11.Cu")
		(net "NIC_SET_N_MDI_2_DN")
	)
	(segment
		(start 481.560378 4.388866)
		(end 481.723446 4.225798)
		(width 0.101346)
		(layer "In11.Cu")
		(net "NIC_SET_N_MDI_2_DN")
	)
	(segment
		(start 480.208844 -9.969754)
		(end 480.107498 -10.0711)
		(width 0.101346)
		(layer "In11.Cu")
		(net "NIC_SET_N_MDI_2_DN")
	)
	(segment
		(start 480.107498 -10.0711)
		(end 479.130868 -10.0711)
		(width 0.101346)
		(layer "In11.Cu")
		(net "NIC_SET_N_MDI_2_DN")
	)
	(segment
		(start 483.0191 -28.456128)
		(end 483.00005 -28.456128)
		(width 0.101346)
		(layer "In11.Cu")
		(net "NIC_SET_N_MDI_2_DN")
	)
	(segment
		(start 478.783904 -15.47622)
		(end 478.783904 -15.755874)
		(width 0.101346)
		(layer "In11.Cu")
		(net "NIC_SET_N_MDI_2_DN")
	)
	(segment
		(start 478.5868 -14.05382)
		(end 478.239836 -14.400784)
		(width 0.101346)
		(layer "In11.Cu")
		(net "NIC_SET_N_MDI_2_DN")
	)
	(segment
		(start 483.056946 -18.320258)
		(end 483.056946 -19.133312)
		(width 0.101346)
		(layer "In11.Cu")
		(net "NIC_SET_N_MDI_2_DN")
	)
	(segment
		(start 480.385882 -18.691098)
		(end 480.878388 -18.198592)
		(width 0.101346)
		(layer "In11.Cu")
		(net "NIC_SET_N_MDI_2_DN")
	)
	(segment
		(start 478.682558 -15.85722)
		(end 478.5868 -15.85722)
		(width 0.101346)
		(layer "In11.Cu")
		(net "NIC_SET_N_MDI_2_DN")
	)
	(segment
		(start 480.005644 -4.22529)
		(end 480.095052 -4.314698)
		(width 0.101346)
		(layer "In11.Cu")
		(net "NIC_SET_N_MDI_2_DN")
	)
	(segment
		(start 480.095052 -7.50062)
		(end 479.157792 -8.43788)
		(width 0.101346)
		(layer "In11.Cu")
		(net "NIC_SET_N_MDI_2_DN")
	)
	(segment
		(start 482.632004 -26.531316)
		(end 482.632004 -27.29992)
		(width 0.101346)
		(layer "In11.Cu")
		(net "NIC_SET_N_MDI_2_DN")
	)
	(segment
		(start 482.764846 -34.591752)
		(end 482.555042 -34.801556)
		(width 0.101346)
		(layer "In11.Cu")
		(net "NIC_SET_N_MDI_2_DN")
	)
	(segment
		(start 478.5868 -15.374874)
		(end 478.682558 -15.374874)
		(width 0.101346)
		(layer "In11.Cu")
		(net "NIC_SET_N_MDI_2_DN")
	)
	(segment
		(start 480.845876 3.211068)
		(end 480.845876 4.261866)
		(width 0.101346)
		(layer "In11.Cu")
		(net "NIC_SET_N_MDI_2_DN")
	)
	(segment
		(start 478.923858 -3.842766)
		(end 479.306382 -4.22529)
		(width 0.101346)
		(layer "In11.Cu")
		(net "NIC_SET_N_MDI_2_DN")
	)
	(segment
		(start 483.62235 -25.642824)
		(end 483.62235 -26.074624)
		(width 0.101346)
		(layer "In11.Cu")
		(net "NIC_SET_N_MDI_2_DN")
	)
	(segment
		(start 482.63556 -25.540208)
		(end 483.519734 -25.540208)
		(width 0.101346)
		(layer "In11.Cu")
		(net "NIC_SET_N_MDI_2_DN")
	)
	(segment
		(start 479.157792 -8.43788)
		(end 479.157792 -9.24179)
		(width 0.101346)
		(layer "In11.Cu")
		(net "NIC_SET_N_MDI_2_DN")
	)
	(segment
		(start 480.577906 -37.474144)
		(end 480.703382 -37.348668)
		(width 0.10033)
		(layer "F.Cu")
		(net "NIC_SER_P_MDI_3_DP")
	)
	(segment
		(start 480.577906 -38.681406)
		(end 480.577906 -37.474144)
		(width 0.10033)
		(layer "F.Cu")
		(net "NIC_SER_P_MDI_3_DP")
	)
	(segment
		(start 481.00107 -39.5986)
		(end 481.00107 -39.10457)
		(width 0.10033)
		(layer "F.Cu")
		(net "NIC_SER_P_MDI_3_DP")
	)
	(segment
		(start 481.00107 -39.10457)
		(end 480.577906 -38.681406)
		(width 0.10033)
		(layer "F.Cu")
		(net "NIC_SER_P_MDI_3_DP")
	)
	(segment
		(start 480.703382 -37.348668)
		(end 480.98456 -37.348668)
		(width 0.10033)
		(layer "F.Cu")
		(net "NIC_SER_P_MDI_3_DP")
	)
	(via
		(at 480.98456 -37.348668)
		(size 0.508)
		(drill 0.254)
		(layers "F.Cu" "B.Cu")
		(net "NIC_SER_P_MDI_3_DP")
	)
	(via
		(at 478.292414 -4.016756)
		(size 0.508)
		(drill 0.254)
		(layers "F.Cu" "B.Cu")
		(net "NIC_SER_P_MDI_3_DP")
	)
	(segment
		(start 477.980502 -4.016756)
		(end 478.292414 -4.016756)
		(width 0.10033)
		(layer "B.Cu")
		(net "NIC_SER_P_MDI_3_DP")
	)
	(segment
		(start 477.645222 -3.3782)
		(end 477.645222 -3.681476)
		(width 0.10033)
		(layer "B.Cu")
		(net "NIC_SER_P_MDI_3_DP")
	)
	(segment
		(start 477.645222 -3.681476)
		(end 477.980502 -4.016756)
		(width 0.10033)
		(layer "B.Cu")
		(net "NIC_SER_P_MDI_3_DP")
	)
	(segment
		(start 479.16973 -34.30651)
		(end 479.16973 -34.738564)
		(width 0.101346)
		(layer "In11.Cu")
		(net "NIC_SER_P_MDI_3_DP")
	)
	(segment
		(start 479.392996 -5.55498)
		(end 479.392996 -7.16534)
		(width 0.101346)
		(layer "In11.Cu")
		(net "NIC_SER_P_MDI_3_DP")
	)
	(segment
		(start 477.687132 -17.466056)
		(end 479.477324 -19.256248)
		(width 0.101346)
		(layer "In11.Cu")
		(net "NIC_SER_P_MDI_3_DP")
	)
	(segment
		(start 478.292414 -2.929636)
		(end 478.201228 -2.83845)
		(width 0.101346)
		(layer "In11.Cu")
		(net "NIC_SER_P_MDI_3_DP")
	)
	(segment
		(start 478.519744 -21.82241)
		(end 478.538032 -21.82241)
		(width 0.101346)
		(layer "In11.Cu")
		(net "NIC_SER_P_MDI_3_DP")
	)
	(segment
		(start 481.268024 -21.28901)
		(end 478.621852 -21.28901)
		(width 0.101346)
		(layer "In11.Cu")
		(net "NIC_SER_P_MDI_3_DP")
	)
	(segment
		(start 479.21037 -27.792934)
		(end 479.09734 -27.905964)
		(width 0.101346)
		(layer "In11.Cu")
		(net "NIC_SER_P_MDI_3_DP")
	)
	(segment
		(start 481.655374 -23.025608)
		(end 481.308156 -23.372826)
		(width 0.101346)
		(layer "In11.Cu")
		(net "NIC_SER_P_MDI_3_DP")
	)
	(segment
		(start 478.201228 -2.83845)
		(end 477.387412 -2.83845)
		(width 0.101346)
		(layer "In11.Cu")
		(net "NIC_SER_P_MDI_3_DP")
	)
	(segment
		(start 477.135698 -23.906226)
		(end 477.224852 -23.99538)
		(width 0.101346)
		(layer "In11.Cu")
		(net "NIC_SER_P_MDI_3_DP")
	)
	(segment
		(start 480.748848 -25.569672)
		(end 480.748848 -25.990042)
		(width 0.101346)
		(layer "In11.Cu")
		(net "NIC_SER_P_MDI_3_DP")
	)
	(segment
		(start 481.437696 -28.799536)
		(end 481.437696 -29.55671)
		(width 0.101346)
		(layer "In11.Cu")
		(net "NIC_SER_P_MDI_3_DP")
	)
	(segment
		(start 481.327968 -21.930106)
		(end 481.655374 -22.257512)
		(width 0.101346)
		(layer "In11.Cu")
		(net "NIC_SER_P_MDI_3_DP")
	)
	(segment
		(start 481.655374 -22.257512)
		(end 481.655374 -23.025608)
		(width 0.101346)
		(layer "In11.Cu")
		(net "NIC_SER_P_MDI_3_DP")
	)
	(segment
		(start 480.23399 -30.561534)
		(end 481.039678 -30.561534)
		(width 0.101346)
		(layer "In11.Cu")
		(net "NIC_SER_P_MDI_3_DP")
	)
	(segment
		(start 480.349814 -32.059118)
		(end 480.236784 -32.172148)
		(width 0.101346)
		(layer "In11.Cu")
		(net "NIC_SER_P_MDI_3_DP")
	)
	(segment
		(start 481.308156 -23.372826)
		(end 477.237806 -23.372826)
		(width 0.101346)
		(layer "In11.Cu")
		(net "NIC_SER_P_MDI_3_DP")
	)
	(segment
		(start 478.60966 -4.771644)
		(end 479.392996 -5.55498)
		(width 0.101346)
		(layer "In11.Cu")
		(net "NIC_SER_P_MDI_3_DP")
	)
	(segment
		(start 481.06838 -29.926026)
		(end 480.252024 -29.926026)
		(width 0.101346)
		(layer "In11.Cu")
		(net "NIC_SER_P_MDI_3_DP")
	)
	(segment
		(start 481.23348 -23.99538)
		(end 481.568252 -24.330152)
		(width 0.101346)
		(layer "In11.Cu")
		(net "NIC_SER_P_MDI_3_DP")
	)
	(segment
		(start 480.559364 -35.171126)
		(end 480.559364 -36.923472)
		(width 0.101346)
		(layer "In11.Cu")
		(net "NIC_SER_P_MDI_3_DP")
	)
	(segment
		(start 479.09734 -27.905964)
		(end 479.09734 -28.318968)
		(width 0.101346)
		(layer "In11.Cu")
		(net "NIC_SER_P_MDI_3_DP")
	)
	(segment
		(start 481.422964 -30.94482)
		(end 481.422964 -31.68269)
		(width 0.101346)
		(layer "In11.Cu")
		(net "NIC_SER_P_MDI_3_DP")
	)
	(segment
		(start 480.236784 -32.592518)
		(end 480.338892 -32.694626)
		(width 0.101346)
		(layer "In11.Cu")
		(net "NIC_SER_P_MDI_3_DP")
	)
	(segment
		(start 480.850956 -26.09215)
		(end 481.217986 -26.09215)
		(width 0.101346)
		(layer "In11.Cu")
		(net "NIC_SER_P_MDI_3_DP")
	)
	(segment
		(start 477.23171 -14.33322)
		(end 477.687132 -14.788642)
		(width 0.101346)
		(layer "In11.Cu")
		(net "NIC_SER_P_MDI_3_DP")
	)
	(segment
		(start 481.538026 -33.077912)
		(end 481.538026 -33.804352)
		(width 0.101346)
		(layer "In11.Cu")
		(net "NIC_SER_P_MDI_3_DP")
	)
	(segment
		(start 481.198936 -25.456642)
		(end 480.861878 -25.456642)
		(width 0.101346)
		(layer "In11.Cu")
		(net "NIC_SER_P_MDI_3_DP")
	)
	(segment
		(start 479.477324 -19.256248)
		(end 480.779582 -19.256248)
		(width 0.101346)
		(layer "In11.Cu")
		(net "NIC_SER_P_MDI_3_DP")
	)
	(segment
		(start 478.1931 -8.365236)
		(end 478.1931 -12.476988)
		(width 0.101346)
		(layer "In11.Cu")
		(net "NIC_SER_P_MDI_3_DP")
	)
	(segment
		(start 481.046536 -32.059118)
		(end 480.349814 -32.059118)
		(width 0.101346)
		(layer "In11.Cu")
		(net "NIC_SER_P_MDI_3_DP")
	)
	(segment
		(start 481.039678 -30.561534)
		(end 481.422964 -30.94482)
		(width 0.101346)
		(layer "In11.Cu")
		(net "NIC_SER_P_MDI_3_DP")
	)
	(segment
		(start 480.338892 -32.694626)
		(end 481.15474 -32.694626)
		(width 0.101346)
		(layer "In11.Cu")
		(net "NIC_SER_P_MDI_3_DP")
	)
	(segment
		(start 480.20224 -34.814002)
		(end 480.559364 -35.171126)
		(width 0.101346)
		(layer "In11.Cu")
		(net "NIC_SER_P_MDI_3_DP")
	)
	(segment
		(start 481.608384 -27.423618)
		(end 481.239068 -27.792934)
		(width 0.101346)
		(layer "In11.Cu")
		(net "NIC_SER_P_MDI_3_DP")
	)
	(segment
		(start 479.245168 -34.814002)
		(end 480.20224 -34.814002)
		(width 0.101346)
		(layer "In11.Cu")
		(net "NIC_SER_P_MDI_3_DP")
	)
	(segment
		(start 480.779582 -19.256248)
		(end 481.607622 -20.084288)
		(width 0.101346)
		(layer "In11.Cu")
		(net "NIC_SER_P_MDI_3_DP")
	)
	(segment
		(start 477.26854 -2.957322)
		(end 477.26854 -3.98653)
		(width 0.101346)
		(layer "In11.Cu")
		(net "NIC_SER_P_MDI_3_DP")
	)
	(segment
		(start 479.09734 -28.318968)
		(end 479.19386 -28.415488)
		(width 0.101346)
		(layer "In11.Cu")
		(net "NIC_SER_P_MDI_3_DP")
	)
	(segment
		(start 481.320602 -21.911564)
		(end 481.327968 -21.91893)
		(width 0.101346)
		(layer "In11.Cu")
		(net "NIC_SER_P_MDI_3_DP")
	)
	(segment
		(start 479.271076 -34.205164)
		(end 479.16973 -34.30651)
		(width 0.101346)
		(layer "In11.Cu")
		(net "NIC_SER_P_MDI_3_DP")
	)
	(segment
		(start 480.559364 -36.923472)
		(end 480.98456 -37.348668)
		(width 0.101346)
		(layer "In11.Cu")
		(net "NIC_SER_P_MDI_3_DP")
	)
	(segment
		(start 477.387412 -2.83845)
		(end 477.26854 -2.957322)
		(width 0.101346)
		(layer "In11.Cu")
		(net "NIC_SER_P_MDI_3_DP")
	)
	(segment
		(start 481.607622 -20.084288)
		(end 481.607622 -20.949412)
		(width 0.101346)
		(layer "In11.Cu")
		(net "NIC_SER_P_MDI_3_DP")
	)
	(segment
		(start 479.392996 -7.16534)
		(end 478.1931 -8.365236)
		(width 0.101346)
		(layer "In11.Cu")
		(net "NIC_SER_P_MDI_3_DP")
	)
	(segment
		(start 478.053654 -4.771644)
		(end 478.60966 -4.771644)
		(width 0.101346)
		(layer "In11.Cu")
		(net "NIC_SER_P_MDI_3_DP")
	)
	(segment
		(start 478.1931 -12.476988)
		(end 477.23171 -13.438378)
		(width 0.101346)
		(layer "In11.Cu")
		(net "NIC_SER_P_MDI_3_DP")
	)
	(segment
		(start 481.217986 -26.09215)
		(end 481.608384 -26.482548)
		(width 0.101346)
		(layer "In11.Cu")
		(net "NIC_SER_P_MDI_3_DP")
	)
	(segment
		(start 480.236784 -32.172148)
		(end 480.236784 -32.592518)
		(width 0.101346)
		(layer "In11.Cu")
		(net "NIC_SER_P_MDI_3_DP")
	)
	(segment
		(start 481.437696 -29.55671)
		(end 481.06838 -29.926026)
		(width 0.101346)
		(layer "In11.Cu")
		(net "NIC_SER_P_MDI_3_DP")
	)
	(segment
		(start 481.568252 -24.330152)
		(end 481.568252 -25.087326)
		(width 0.101346)
		(layer "In11.Cu")
		(net "NIC_SER_P_MDI_3_DP")
	)
	(segment
		(start 478.292414 -4.016756)
		(end 478.292414 -2.929636)
		(width 0.101346)
		(layer "In11.Cu")
		(net "NIC_SER_P_MDI_3_DP")
	)
	(segment
		(start 478.519744 -21.391118)
		(end 478.519744 -21.82241)
		(width 0.101346)
		(layer "In11.Cu")
		(net "NIC_SER_P_MDI_3_DP")
	)
	(segment
		(start 481.538026 -33.804352)
		(end 481.137214 -34.205164)
		(width 0.101346)
		(layer "In11.Cu")
		(net "NIC_SER_P_MDI_3_DP")
	)
	(segment
		(start 480.131882 -30.046168)
		(end 480.131882 -30.459426)
		(width 0.101346)
		(layer "In11.Cu")
		(net "NIC_SER_P_MDI_3_DP")
	)
	(segment
		(start 477.23171 -13.438378)
		(end 477.23171 -14.33322)
		(width 0.101346)
		(layer "In11.Cu")
		(net "NIC_SER_P_MDI_3_DP")
	)
	(segment
		(start 481.137214 -34.205164)
		(end 479.271076 -34.205164)
		(width 0.101346)
		(layer "In11.Cu")
		(net "NIC_SER_P_MDI_3_DP")
	)
	(segment
		(start 481.15474 -32.694626)
		(end 481.538026 -33.077912)
		(width 0.101346)
		(layer "In11.Cu")
		(net "NIC_SER_P_MDI_3_DP")
	)
	(segment
		(start 477.687132 -14.788642)
		(end 477.687132 -17.466056)
		(width 0.101346)
		(layer "In11.Cu")
		(net "NIC_SER_P_MDI_3_DP")
	)
	(segment
		(start 480.252024 -29.926026)
		(end 480.131882 -30.046168)
		(width 0.101346)
		(layer "In11.Cu")
		(net "NIC_SER_P_MDI_3_DP")
	)
	(segment
		(start 478.621852 -21.28901)
		(end 478.519744 -21.391118)
		(width 0.101346)
		(layer "In11.Cu")
		(net "NIC_SER_P_MDI_3_DP")
	)
	(segment
		(start 479.16973 -34.738564)
		(end 479.245168 -34.814002)
		(width 0.101346)
		(layer "In11.Cu")
		(net "NIC_SER_P_MDI_3_DP")
	)
	(segment
		(start 477.26854 -3.98653)
		(end 478.053654 -4.771644)
		(width 0.101346)
		(layer "In11.Cu")
		(net "NIC_SER_P_MDI_3_DP")
	)
	(segment
		(start 480.748848 -25.990042)
		(end 480.850956 -26.09215)
		(width 0.101346)
		(layer "In11.Cu")
		(net "NIC_SER_P_MDI_3_DP")
	)
	(segment
		(start 478.538032 -21.82241)
		(end 478.627186 -21.911564)
		(width 0.101346)
		(layer "In11.Cu")
		(net "NIC_SER_P_MDI_3_DP")
	)
	(segment
		(start 478.627186 -21.911564)
		(end 481.320602 -21.911564)
		(width 0.101346)
		(layer "In11.Cu")
		(net "NIC_SER_P_MDI_3_DP")
	)
	(segment
		(start 481.608384 -26.482548)
		(end 481.608384 -27.423618)
		(width 0.101346)
		(layer "In11.Cu")
		(net "NIC_SER_P_MDI_3_DP")
	)
	(segment
		(start 477.135698 -23.474934)
		(end 477.135698 -23.906226)
		(width 0.101346)
		(layer "In11.Cu")
		(net "NIC_SER_P_MDI_3_DP")
	)
	(segment
		(start 477.237806 -23.372826)
		(end 477.135698 -23.474934)
		(width 0.101346)
		(layer "In11.Cu")
		(net "NIC_SER_P_MDI_3_DP")
	)
	(segment
		(start 477.224852 -23.99538)
		(end 481.23348 -23.99538)
		(width 0.101346)
		(layer "In11.Cu")
		(net "NIC_SER_P_MDI_3_DP")
	)
	(segment
		(start 481.239068 -27.792934)
		(end 479.21037 -27.792934)
		(width 0.101346)
		(layer "In11.Cu")
		(net "NIC_SER_P_MDI_3_DP")
	)
	(segment
		(start 481.422964 -31.68269)
		(end 481.046536 -32.059118)
		(width 0.101346)
		(layer "In11.Cu")
		(net "NIC_SER_P_MDI_3_DP")
	)
	(segment
		(start 481.327968 -21.91893)
		(end 481.327968 -21.930106)
		(width 0.101346)
		(layer "In11.Cu")
		(net "NIC_SER_P_MDI_3_DP")
	)
	(segment
		(start 481.053648 -28.415488)
		(end 481.437696 -28.799536)
		(width 0.101346)
		(layer "In11.Cu")
		(net "NIC_SER_P_MDI_3_DP")
	)
	(segment
		(start 480.131882 -30.459426)
		(end 480.23399 -30.561534)
		(width 0.101346)
		(layer "In11.Cu")
		(net "NIC_SER_P_MDI_3_DP")
	)
	(segment
		(start 481.568252 -25.087326)
		(end 481.198936 -25.456642)
		(width 0.101346)
		(layer "In11.Cu")
		(net "NIC_SER_P_MDI_3_DP")
	)
	(segment
		(start 480.861878 -25.456642)
		(end 480.748848 -25.569672)
		(width 0.101346)
		(layer "In11.Cu")
		(net "NIC_SER_P_MDI_3_DP")
	)
	(segment
		(start 479.19386 -28.415488)
		(end 481.053648 -28.415488)
		(width 0.101346)
		(layer "In11.Cu")
		(net "NIC_SER_P_MDI_3_DP")
	)
	(segment
		(start 481.607622 -20.949412)
		(end 481.268024 -21.28901)
		(width 0.101346)
		(layer "In11.Cu")
		(net "NIC_SER_P_MDI_3_DP")
	)
	(segment
		(start 480.020376 -37.348668)
		(end 479.714306 -37.348668)
		(width 0.10033)
		(layer "F.Cu")
		(net "NIC_SER_N_MDI_3_DN")
	)
	(segment
		(start 480.500944 -39.587424)
		(end 480.499928 -39.586408)
		(width 0.10033)
		(layer "F.Cu")
		(net "NIC_SER_N_MDI_3_DN")
	)
	(segment
		(start 480.499928 -39.238428)
		(end 480.120706 -38.859206)
		(width 0.10033)
		(layer "F.Cu")
		(net "NIC_SER_N_MDI_3_DN")
	)
	(segment
		(start 480.500944 -39.5986)
		(end 480.500944 -39.587424)
		(width 0.10033)
		(layer "F.Cu")
		(net "NIC_SER_N_MDI_3_DN")
	)
	(segment
		(start 480.120706 -38.859206)
		(end 480.120706 -37.448998)
		(width 0.10033)
		(layer "F.Cu")
		(net "NIC_SER_N_MDI_3_DN")
	)
	(segment
		(start 480.499928 -39.586408)
		(end 480.499928 -39.238428)
		(width 0.10033)
		(layer "F.Cu")
		(net "NIC_SER_N_MDI_3_DN")
	)
	(segment
		(start 480.120706 -37.448998)
		(end 480.020376 -37.348668)
		(width 0.10033)
		(layer "F.Cu")
		(net "NIC_SER_N_MDI_3_DN")
	)
	(via
		(at 478.281746 -1.875282)
		(size 0.508)
		(drill 0.254)
		(layers "F.Cu" "B.Cu")
		(net "NIC_SER_N_MDI_3_DN")
	)
	(via
		(at 479.714306 -37.348668)
		(size 0.508)
		(drill 0.254)
		(layers "F.Cu" "B.Cu")
		(net "NIC_SER_N_MDI_3_DN")
	)
	(segment
		(start 477.634554 -2.513838)
		(end 477.634554 -2.210562)
		(width 0.10033)
		(layer "B.Cu")
		(net "NIC_SER_N_MDI_3_DN")
	)
	(segment
		(start 477.634554 -2.210562)
		(end 477.969834 -1.875282)
		(width 0.10033)
		(layer "B.Cu")
		(net "NIC_SER_N_MDI_3_DN")
	)
	(segment
		(start 477.969834 -1.875282)
		(end 478.281746 -1.875282)
		(width 0.10033)
		(layer "B.Cu")
		(net "NIC_SER_N_MDI_3_DN")
	)
	(segment
		(start 477.213676 -2.419096)
		(end 476.849186 -2.783586)
		(width 0.101346)
		(layer "In11.Cu")
		(net "NIC_SER_N_MDI_3_DN")
	)
	(segment
		(start 481.059744 -24.414734)
		(end 481.161852 -24.516842)
		(width 0.101346)
		(layer "In11.Cu")
		(net "NIC_SER_N_MDI_3_DN")
	)
	(segment
		(start 480.028504 -35.233356)
		(end 480.153726 -35.358578)
		(width 0.101346)
		(layer "In11.Cu")
		(net "NIC_SER_N_MDI_3_DN")
	)
	(segment
		(start 481.031296 -28.986226)
		(end 481.031296 -29.388308)
		(width 0.101346)
		(layer "In11.Cu")
		(net "NIC_SER_N_MDI_3_DN")
	)
	(segment
		(start 479.830384 -32.771842)
		(end 480.159568 -33.101026)
		(width 0.101346)
		(layer "In11.Cu")
		(net "NIC_SER_N_MDI_3_DN")
	)
	(segment
		(start 478.364296 -22.241764)
		(end 478.45345 -22.330918)
		(width 0.101346)
		(layer "In11.Cu")
		(net "NIC_SER_N_MDI_3_DN")
	)
	(segment
		(start 480.899978 -29.519626)
		(end 480.083622 -29.519626)
		(width 0.101346)
		(layer "In11.Cu")
		(net "NIC_SER_N_MDI_3_DN")
	)
	(segment
		(start 481.132388 -33.636204)
		(end 480.982782 -33.78581)
		(width 0.101346)
		(layer "In11.Cu")
		(net "NIC_SER_N_MDI_3_DN")
	)
	(segment
		(start 478.345754 -22.241764)
		(end 478.364296 -22.241764)
		(width 0.101346)
		(layer "In11.Cu")
		(net "NIC_SER_N_MDI_3_DN")
	)
	(segment
		(start 481.030534 -25.050242)
		(end 480.693476 -25.050242)
		(width 0.101346)
		(layer "In11.Cu")
		(net "NIC_SER_N_MDI_3_DN")
	)
	(segment
		(start 481.188268 -20.258024)
		(end 481.188268 -20.775676)
		(width 0.101346)
		(layer "In11.Cu")
		(net "NIC_SER_N_MDI_3_DN")
	)
	(segment
		(start 480.342448 -25.40127)
		(end 480.342448 -26.169366)
		(width 0.101346)
		(layer "In11.Cu")
		(net "NIC_SER_N_MDI_3_DN")
	)
	(segment
		(start 478.69094 -27.737562)
		(end 478.69094 -28.505658)
		(width 0.101346)
		(layer "In11.Cu")
		(net "NIC_SER_N_MDI_3_DN")
	)
	(segment
		(start 481.248974 -22.857206)
		(end 481.139754 -22.966426)
		(width 0.101346)
		(layer "In11.Cu")
		(net "NIC_SER_N_MDI_3_DN")
	)
	(segment
		(start 478.45345 -22.330918)
		(end 481.146866 -22.330918)
		(width 0.101346)
		(layer "In11.Cu")
		(net "NIC_SER_N_MDI_3_DN")
	)
	(segment
		(start 477.267778 -14.962378)
		(end 477.267778 -17.639792)
		(width 0.101346)
		(layer "In11.Cu")
		(net "NIC_SER_N_MDI_3_DN")
	)
	(segment
		(start 480.159568 -33.101026)
		(end 480.987354 -33.101026)
		(width 0.101346)
		(layer "In11.Cu")
		(net "NIC_SER_N_MDI_3_DN")
	)
	(segment
		(start 481.094288 -20.869656)
		(end 478.448116 -20.869656)
		(width 0.101346)
		(layer "In11.Cu")
		(net "NIC_SER_N_MDI_3_DN")
	)
	(segment
		(start 479.725482 -30.645862)
		(end 480.047554 -30.967934)
		(width 0.101346)
		(layer "In11.Cu")
		(net "NIC_SER_N_MDI_3_DN")
	)
	(segment
		(start 479.303588 -19.675602)
		(end 480.605846 -19.675602)
		(width 0.101346)
		(layer "In11.Cu")
		(net "NIC_SER_N_MDI_3_DN")
	)
	(segment
		(start 479.725482 -29.877766)
		(end 479.725482 -30.645862)
		(width 0.101346)
		(layer "In11.Cu")
		(net "NIC_SER_N_MDI_3_DN")
	)
	(segment
		(start 479.09734 -33.78581)
		(end 478.750376 -34.132774)
		(width 0.101346)
		(layer "In11.Cu")
		(net "NIC_SER_N_MDI_3_DN")
	)
	(segment
		(start 481.132388 -33.24606)
		(end 481.132388 -33.636204)
		(width 0.101346)
		(layer "In11.Cu")
		(net "NIC_SER_N_MDI_3_DN")
	)
	(segment
		(start 481.0506 -26.49855)
		(end 481.201984 -26.649934)
		(width 0.101346)
		(layer "In11.Cu")
		(net "NIC_SER_N_MDI_3_DN")
	)
	(segment
		(start 481.146866 -22.330918)
		(end 481.248974 -22.433026)
		(width 0.101346)
		(layer "In11.Cu")
		(net "NIC_SER_N_MDI_3_DN")
	)
	(segment
		(start 479.020124 -28.834842)
		(end 480.879912 -28.834842)
		(width 0.101346)
		(layer "In11.Cu")
		(net "NIC_SER_N_MDI_3_DN")
	)
	(segment
		(start 480.871276 -30.967934)
		(end 481.016564 -31.113222)
		(width 0.101346)
		(layer "In11.Cu")
		(net "NIC_SER_N_MDI_3_DN")
	)
	(segment
		(start 480.153726 -36.909248)
		(end 479.714306 -37.348668)
		(width 0.101346)
		(layer "In11.Cu")
		(net "NIC_SER_N_MDI_3_DN")
	)
	(segment
		(start 478.10039 -21.217382)
		(end 478.10039 -21.9964)
		(width 0.101346)
		(layer "In11.Cu")
		(net "NIC_SER_N_MDI_3_DN")
	)
	(segment
		(start 478.69094 -28.505658)
		(end 479.020124 -28.834842)
		(width 0.101346)
		(layer "In11.Cu")
		(net "NIC_SER_N_MDI_3_DN")
	)
	(segment
		(start 477.879918 -5.190998)
		(end 478.435924 -5.190998)
		(width 0.101346)
		(layer "In11.Cu")
		(net "NIC_SER_N_MDI_3_DN")
	)
	(segment
		(start 480.083622 -29.519626)
		(end 479.725482 -29.877766)
		(width 0.101346)
		(layer "In11.Cu")
		(net "NIC_SER_N_MDI_3_DN")
	)
	(segment
		(start 481.031296 -29.388308)
		(end 480.899978 -29.519626)
		(width 0.101346)
		(layer "In11.Cu")
		(net "NIC_SER_N_MDI_3_DN")
	)
	(segment
		(start 478.973642 -6.991604)
		(end 477.773746 -8.1915)
		(width 0.101346)
		(layer "In11.Cu")
		(net "NIC_SER_N_MDI_3_DN")
	)
	(segment
		(start 481.201984 -26.649934)
		(end 481.201984 -27.255216)
		(width 0.101346)
		(layer "In11.Cu")
		(net "NIC_SER_N_MDI_3_DN")
	)
	(segment
		(start 481.188268 -20.775676)
		(end 481.094288 -20.869656)
		(width 0.101346)
		(layer "In11.Cu")
		(net "NIC_SER_N_MDI_3_DN")
	)
	(segment
		(start 480.879912 -28.834842)
		(end 481.031296 -28.986226)
		(width 0.101346)
		(layer "In11.Cu")
		(net "NIC_SER_N_MDI_3_DN")
	)
	(segment
		(start 477.773746 -8.1915)
		(end 477.773746 -12.303252)
		(width 0.101346)
		(layer "In11.Cu")
		(net "NIC_SER_N_MDI_3_DN")
	)
	(segment
		(start 477.069404 -24.414734)
		(end 481.059744 -24.414734)
		(width 0.101346)
		(layer "In11.Cu")
		(net "NIC_SER_N_MDI_3_DN")
	)
	(segment
		(start 478.435924 -5.190998)
		(end 478.973642 -5.728716)
		(width 0.101346)
		(layer "In11.Cu")
		(net "NIC_SER_N_MDI_3_DN")
	)
	(segment
		(start 477.773746 -12.303252)
		(end 476.812356 -13.264642)
		(width 0.101346)
		(layer "In11.Cu")
		(net "NIC_SER_N_MDI_3_DN")
	)
	(segment
		(start 481.161852 -24.918924)
		(end 481.030534 -25.050242)
		(width 0.101346)
		(layer "In11.Cu")
		(net "NIC_SER_N_MDI_3_DN")
	)
	(segment
		(start 480.342448 -26.169366)
		(end 480.671632 -26.49855)
		(width 0.101346)
		(layer "In11.Cu")
		(net "NIC_SER_N_MDI_3_DN")
	)
	(segment
		(start 478.973642 -5.728716)
		(end 478.973642 -6.991604)
		(width 0.101346)
		(layer "In11.Cu")
		(net "NIC_SER_N_MDI_3_DN")
	)
	(segment
		(start 480.181412 -31.652718)
		(end 479.830384 -32.003746)
		(width 0.101346)
		(layer "In11.Cu")
		(net "NIC_SER_N_MDI_3_DN")
	)
	(segment
		(start 479.830384 -32.003746)
		(end 479.830384 -32.771842)
		(width 0.101346)
		(layer "In11.Cu")
		(net "NIC_SER_N_MDI_3_DN")
	)
	(segment
		(start 478.448116 -20.869656)
		(end 478.10039 -21.217382)
		(width 0.101346)
		(layer "In11.Cu")
		(net "NIC_SER_N_MDI_3_DN")
	)
	(segment
		(start 481.201984 -27.255216)
		(end 481.070666 -27.386534)
		(width 0.101346)
		(layer "In11.Cu")
		(net "NIC_SER_N_MDI_3_DN")
	)
	(segment
		(start 480.671632 -26.49855)
		(end 481.0506 -26.49855)
		(width 0.101346)
		(layer "In11.Cu")
		(net "NIC_SER_N_MDI_3_DN")
	)
	(segment
		(start 481.016564 -31.514288)
		(end 480.878134 -31.652718)
		(width 0.101346)
		(layer "In11.Cu")
		(net "NIC_SER_N_MDI_3_DN")
	)
	(segment
		(start 478.750376 -34.9123)
		(end 479.071432 -35.233356)
		(width 0.101346)
		(layer "In11.Cu")
		(net "NIC_SER_N_MDI_3_DN")
	)
	(segment
		(start 478.281746 -1.875282)
		(end 478.281746 -2.28854)
		(width 0.101346)
		(layer "In11.Cu")
		(net "NIC_SER_N_MDI_3_DN")
	)
	(segment
		(start 481.248974 -22.433026)
		(end 481.248974 -22.857206)
		(width 0.101346)
		(layer "In11.Cu")
		(net "NIC_SER_N_MDI_3_DN")
	)
	(segment
		(start 480.878134 -31.652718)
		(end 480.181412 -31.652718)
		(width 0.101346)
		(layer "In11.Cu")
		(net "NIC_SER_N_MDI_3_DN")
	)
	(segment
		(start 480.693476 -25.050242)
		(end 480.342448 -25.40127)
		(width 0.101346)
		(layer "In11.Cu")
		(net "NIC_SER_N_MDI_3_DN")
	)
	(segment
		(start 480.982782 -33.78581)
		(end 479.09734 -33.78581)
		(width 0.101346)
		(layer "In11.Cu")
		(net "NIC_SER_N_MDI_3_DN")
	)
	(segment
		(start 476.812356 -13.264642)
		(end 476.812356 -14.506956)
		(width 0.101346)
		(layer "In11.Cu")
		(net "NIC_SER_N_MDI_3_DN")
	)
	(segment
		(start 476.849186 -2.783586)
		(end 476.849186 -4.160266)
		(width 0.101346)
		(layer "In11.Cu")
		(net "NIC_SER_N_MDI_3_DN")
	)
	(segment
		(start 481.016564 -31.113222)
		(end 481.016564 -31.514288)
		(width 0.101346)
		(layer "In11.Cu")
		(net "NIC_SER_N_MDI_3_DN")
	)
	(segment
		(start 480.605846 -19.675602)
		(end 481.188268 -20.258024)
		(width 0.101346)
		(layer "In11.Cu")
		(net "NIC_SER_N_MDI_3_DN")
	)
	(segment
		(start 477.069404 -22.966426)
		(end 476.729298 -23.306532)
		(width 0.101346)
		(layer "In11.Cu")
		(net "NIC_SER_N_MDI_3_DN")
	)
	(segment
		(start 476.729298 -24.074628)
		(end 477.069404 -24.414734)
		(width 0.101346)
		(layer "In11.Cu")
		(net "NIC_SER_N_MDI_3_DN")
	)
	(segment
		(start 479.071432 -35.233356)
		(end 480.028504 -35.233356)
		(width 0.101346)
		(layer "In11.Cu")
		(net "NIC_SER_N_MDI_3_DN")
	)
	(segment
		(start 480.987354 -33.101026)
		(end 481.132388 -33.24606)
		(width 0.101346)
		(layer "In11.Cu")
		(net "NIC_SER_N_MDI_3_DN")
	)
	(segment
		(start 481.070666 -27.386534)
		(end 479.041968 -27.386534)
		(width 0.101346)
		(layer "In11.Cu")
		(net "NIC_SER_N_MDI_3_DN")
	)
	(segment
		(start 476.812356 -14.506956)
		(end 477.267778 -14.962378)
		(width 0.101346)
		(layer "In11.Cu")
		(net "NIC_SER_N_MDI_3_DN")
	)
	(segment
		(start 480.153726 -35.358578)
		(end 480.153726 -36.909248)
		(width 0.101346)
		(layer "In11.Cu")
		(net "NIC_SER_N_MDI_3_DN")
	)
	(segment
		(start 478.15119 -2.419096)
		(end 477.213676 -2.419096)
		(width 0.101346)
		(layer "In11.Cu")
		(net "NIC_SER_N_MDI_3_DN")
	)
	(segment
		(start 480.047554 -30.967934)
		(end 480.871276 -30.967934)
		(width 0.101346)
		(layer "In11.Cu")
		(net "NIC_SER_N_MDI_3_DN")
	)
	(segment
		(start 481.161852 -24.516842)
		(end 481.161852 -24.918924)
		(width 0.101346)
		(layer "In11.Cu")
		(net "NIC_SER_N_MDI_3_DN")
	)
	(segment
		(start 478.750376 -34.132774)
		(end 478.750376 -34.9123)
		(width 0.101346)
		(layer "In11.Cu")
		(net "NIC_SER_N_MDI_3_DN")
	)
	(segment
		(start 479.041968 -27.386534)
		(end 478.69094 -27.737562)
		(width 0.101346)
		(layer "In11.Cu")
		(net "NIC_SER_N_MDI_3_DN")
	)
	(segment
		(start 478.10039 -21.9964)
		(end 478.345754 -22.241764)
		(width 0.101346)
		(layer "In11.Cu")
		(net "NIC_SER_N_MDI_3_DN")
	)
	(segment
		(start 478.281746 -2.28854)
		(end 478.15119 -2.419096)
		(width 0.101346)
		(layer "In11.Cu")
		(net "NIC_SER_N_MDI_3_DN")
	)
	(segment
		(start 476.849186 -4.160266)
		(end 477.879918 -5.190998)
		(width 0.101346)
		(layer "In11.Cu")
		(net "NIC_SER_N_MDI_3_DN")
	)
	(segment
		(start 481.139754 -22.966426)
		(end 477.069404 -22.966426)
		(width 0.101346)
		(layer "In11.Cu")
		(net "NIC_SER_N_MDI_3_DN")
	)
	(segment
		(start 476.729298 -23.306532)
		(end 476.729298 -24.074628)
		(width 0.101346)
		(layer "In11.Cu")
		(net "NIC_SER_N_MDI_3_DN")
	)
	(segment
		(start 477.267778 -17.639792)
		(end 479.303588 -19.675602)
		(width 0.101346)
		(layer "In11.Cu")
		(net "NIC_SER_N_MDI_3_DN")
	)
	(segment
		(start 383.840736 -91.794584)
		(end 383.840736 -93.112082)
		(width 0.0889)
		(layer "F.Cu")
		(net "PU_LPC_CLKRUN_N")
	)
	(segment
		(start 383.840736 -93.112082)
		(end 383.985008 -93.256354)
		(width 0.0889)
		(layer "F.Cu")
		(net "PU_LPC_CLKRUN_N")
	)
	(segment
		(start 383.744978 -91.698826)
		(end 383.840736 -91.794584)
		(width 0.0889)
		(layer "F.Cu")
		(net "PU_LPC_CLKRUN_N")
	)
	(segment
		(start 383.985008 -93.256354)
		(end 383.985008 -93.544898)
		(width 0.0889)
		(layer "F.Cu")
		(net "PU_LPC_CLKRUN_N")
	)
	(segment
		(start 383.3368 -88.5063)
		(end 383.3368 -89.306654)
		(width 0.10795)
		(layer "F.Cu")
		(net "PU_LPC_CLKRUN_N")
	)
	(segment
		(start 383.032 -88.2015)
		(end 383.3368 -88.5063)
		(width 0.10795)
		(layer "F.Cu")
		(net "PU_LPC_CLKRUN_N")
	)
	(segment
		(start 383.744978 -89.714832)
		(end 383.744978 -91.698826)
		(width 0.0889)
		(layer "F.Cu")
		(net "PU_LPC_CLKRUN_N")
	)
	(segment
		(start 383.3368 -89.306654)
		(end 383.744978 -89.714832)
		(width 0.10795)
		(layer "F.Cu")
		(net "PU_LPC_CLKRUN_N")
	)
	(segment
		(start 478.534222 -3.3782)
		(end 479.78314 -3.3782)
		(width 0.10033)
		(layer "B.Cu")
		(net "NIC_MDI_SPRV_RJ45_3_R_DP")
	)
	(segment
		(start 479.78314 -3.3782)
		(end 480.706176 -2.455164)
		(width 0.10033)
		(layer "B.Cu")
		(net "NIC_MDI_SPRV_RJ45_3_R_DP")
	)
	(segment
		(start 480.706176 -2.455164)
		(end 482.84003 -2.455164)
		(width 0.10033)
		(layer "B.Cu")
		(net "NIC_MDI_SPRV_RJ45_3_R_DP")
	)
	(segment
		(start 481.779326 -1.997964)
		(end 481.906834 -1.870456)
		(width 0.10033)
		(layer "B.Cu")
		(net "NIC_MDI_SPRV_RJ45_3_R_DN")
	)
	(segment
		(start 478.523554 -2.513838)
		(end 478.930716 -2.921)
		(width 0.10033)
		(layer "B.Cu")
		(net "NIC_MDI_SPRV_RJ45_3_R_DN")
	)
	(segment
		(start 479.593656 -2.921)
		(end 480.516692 -1.997964)
		(width 0.10033)
		(layer "B.Cu")
		(net "NIC_MDI_SPRV_RJ45_3_R_DN")
	)
	(segment
		(start 481.779834 -1.44018)
		(end 481.57003 -1.44018)
		(width 0.10033)
		(layer "B.Cu")
		(net "NIC_MDI_SPRV_RJ45_3_R_DN")
	)
	(segment
		(start 478.930716 -2.921)
		(end 479.593656 -2.921)
		(width 0.10033)
		(layer "B.Cu")
		(net "NIC_MDI_SPRV_RJ45_3_R_DN")
	)
	(segment
		(start 481.906834 -1.56718)
		(end 481.779834 -1.44018)
		(width 0.10033)
		(layer "B.Cu")
		(net "NIC_MDI_SPRV_RJ45_3_R_DN")
	)
	(segment
		(start 481.906834 -1.870456)
		(end 481.906834 -1.56718)
		(width 0.10033)
		(layer "B.Cu")
		(net "NIC_MDI_SPRV_RJ45_3_R_DN")
	)
	(segment
		(start 480.516692 -1.997964)
		(end 481.779326 -1.997964)
		(width 0.10033)
		(layer "B.Cu")
		(net "NIC_MDI_SPRV_RJ45_3_R_DN")
	)
	(segment
		(start 478.770442 3.473958)
		(end 478.770442 -2.46634)
		(width 0.10033)
		(layer "F.Cu")
		(net "NIC_MDI_SPRV_RJ45_2_R_DP")
	)
	(segment
		(start 478.770442 -2.46634)
		(end 480.789234 -4.485132)
		(width 0.10033)
		(layer "F.Cu")
		(net "NIC_MDI_SPRV_RJ45_2_R_DP")
	)
	(segment
		(start 479.953574 4.65709)
		(end 478.770442 3.473958)
		(width 0.10033)
		(layer "F.Cu")
		(net "NIC_MDI_SPRV_RJ45_2_R_DP")
	)
	(segment
		(start 480.789234 -4.485132)
		(end 482.84003 -4.485132)
		(width 0.10033)
		(layer "F.Cu")
		(net "NIC_MDI_SPRV_RJ45_2_R_DP")
	)
	(segment
		(start 480.972876 -4.041902)
		(end 481.92563 -4.041902)
		(width 0.10033)
		(layer "F.Cu")
		(net "NIC_MDI_SPRV_RJ45_2_R_DN")
	)
	(segment
		(start 480.156012 2.977134)
		(end 480.029012 2.850134)
		(width 0.10033)
		(layer "F.Cu")
		(net "NIC_MDI_SPRV_RJ45_2_R_DN")
	)
	(segment
		(start 480.271836 -2.87782)
		(end 480.271836 -3.340862)
		(width 0.10033)
		(layer "F.Cu")
		(net "NIC_MDI_SPRV_RJ45_2_R_DN")
	)
	(segment
		(start 479.213672 1.856232)
		(end 479.541332 1.528572)
		(width 0.10033)
		(layer "F.Cu")
		(net "NIC_MDI_SPRV_RJ45_2_R_DN")
	)
	(segment
		(start 479.213672 0.494792)
		(end 479.541332 0.167132)
		(width 0.10033)
		(layer "F.Cu")
		(net "NIC_MDI_SPRV_RJ45_2_R_DN")
	)
	(segment
		(start 479.541332 1.178052)
		(end 479.213672 0.850392)
		(width 0.10033)
		(layer "F.Cu")
		(net "NIC_MDI_SPRV_RJ45_2_R_DN")
	)
	(segment
		(start 479.56089 -2.629916)
		(end 480.023932 -2.629916)
		(width 0.10033)
		(layer "F.Cu")
		(net "NIC_MDI_SPRV_RJ45_2_R_DN")
	)
	(segment
		(start 479.213672 -0.511048)
		(end 479.213672 -0.866648)
		(width 0.10033)
		(layer "F.Cu")
		(net "NIC_MDI_SPRV_RJ45_2_R_DN")
	)
	(segment
		(start 479.213672 0.850392)
		(end 479.213672 0.494792)
		(width 0.10033)
		(layer "F.Cu")
		(net "NIC_MDI_SPRV_RJ45_2_R_DN")
	)
	(segment
		(start 479.213672 2.72288)
		(end 479.213672 1.856232)
		(width 0.10033)
		(layer "F.Cu")
		(net "NIC_MDI_SPRV_RJ45_2_R_DN")
	)
	(segment
		(start 479.541332 -1.544828)
		(end 479.213672 -1.872488)
		(width 0.10033)
		(layer "F.Cu")
		(net "NIC_MDI_SPRV_RJ45_2_R_DN")
	)
	(segment
		(start 479.213672 -1.872488)
		(end 479.213672 -2.282698)
		(width 0.10033)
		(layer "F.Cu")
		(net "NIC_MDI_SPRV_RJ45_2_R_DN")
	)
	(segment
		(start 482.06025 -3.907282)
		(end 482.06025 -3.597148)
		(width 0.10033)
		(layer "F.Cu")
		(net "NIC_MDI_SPRV_RJ45_2_R_DN")
	)
	(segment
		(start 479.340926 2.850134)
		(end 479.213672 2.72288)
		(width 0.10033)
		(layer "F.Cu")
		(net "NIC_MDI_SPRV_RJ45_2_R_DN")
	)
	(segment
		(start 479.541332 -1.194308)
		(end 479.541332 -1.544828)
		(width 0.10033)
		(layer "F.Cu")
		(net "NIC_MDI_SPRV_RJ45_2_R_DN")
	)
	(segment
		(start 480.029012 2.850134)
		(end 479.340926 2.850134)
		(width 0.10033)
		(layer "F.Cu")
		(net "NIC_MDI_SPRV_RJ45_2_R_DN")
	)
	(segment
		(start 479.213672 -0.866648)
		(end 479.541332 -1.194308)
		(width 0.10033)
		(layer "F.Cu")
		(net "NIC_MDI_SPRV_RJ45_2_R_DN")
	)
	(segment
		(start 480.023932 -2.629916)
		(end 480.271836 -2.87782)
		(width 0.10033)
		(layer "F.Cu")
		(net "NIC_MDI_SPRV_RJ45_2_R_DN")
	)
	(segment
		(start 482.06025 -3.597148)
		(end 481.93325 -3.470148)
		(width 0.10033)
		(layer "F.Cu")
		(net "NIC_MDI_SPRV_RJ45_2_R_DN")
	)
	(segment
		(start 479.956876 3.820668)
		(end 480.156012 3.621532)
		(width 0.10033)
		(layer "F.Cu")
		(net "NIC_MDI_SPRV_RJ45_2_R_DN")
	)
	(segment
		(start 479.213672 -2.282698)
		(end 479.56089 -2.629916)
		(width 0.10033)
		(layer "F.Cu")
		(net "NIC_MDI_SPRV_RJ45_2_R_DN")
	)
	(segment
		(start 481.92563 -4.041902)
		(end 482.06025 -3.907282)
		(width 0.10033)
		(layer "F.Cu")
		(net "NIC_MDI_SPRV_RJ45_2_R_DN")
	)
	(segment
		(start 480.271836 -3.340862)
		(end 480.972876 -4.041902)
		(width 0.10033)
		(layer "F.Cu")
		(net "NIC_MDI_SPRV_RJ45_2_R_DN")
	)
	(segment
		(start 479.541332 -0.183388)
		(end 479.213672 -0.511048)
		(width 0.10033)
		(layer "F.Cu")
		(net "NIC_MDI_SPRV_RJ45_2_R_DN")
	)
	(segment
		(start 479.541332 1.528572)
		(end 479.541332 1.178052)
		(width 0.10033)
		(layer "F.Cu")
		(net "NIC_MDI_SPRV_RJ45_2_R_DN")
	)
	(segment
		(start 479.541332 0.167132)
		(end 479.541332 -0.183388)
		(width 0.10033)
		(layer "F.Cu")
		(net "NIC_MDI_SPRV_RJ45_2_R_DN")
	)
	(segment
		(start 480.156012 3.621532)
		(end 480.156012 2.977134)
		(width 0.10033)
		(layer "F.Cu")
		(net "NIC_MDI_SPRV_RJ45_2_R_DN")
	)
	(segment
		(start 481.93325 -3.470148)
		(end 481.57003 -3.470148)
		(width 0.10033)
		(layer "F.Cu")
		(net "NIC_MDI_SPRV_RJ45_2_R_DN")
	)
	(segment
		(start 479.39325 -5.830316)
		(end 479.860102 -5.830316)
		(width 0.11684)
		(layer "F.Cu")
		(net "NIC_MDI_SPRV_RJ45_1_R_DP")
	)
	(segment
		(start 476.657162 -9.133586)
		(end 476.905066 -8.885682)
		(width 0.11684)
		(layer "F.Cu")
		(net "NIC_MDI_SPRV_RJ45_1_R_DP")
	)
	(segment
		(start 481.004626 -6.97484)
		(end 481.708714 -6.97484)
		(width 0.11684)
		(layer "F.Cu")
		(net "NIC_MDI_SPRV_RJ45_1_R_DP")
	)
	(segment
		(start 476.50273 -4.179316)
		(end 477.010984 -4.179316)
		(width 0.11684)
		(layer "F.Cu")
		(net "NIC_MDI_SPRV_RJ45_1_R_DP")
	)
	(segment
		(start 479.145346 -5.582412)
		(end 479.39325 -5.830316)
		(width 0.11684)
		(layer "F.Cu")
		(net "NIC_MDI_SPRV_RJ45_1_R_DP")
	)
	(segment
		(start 480.108006 -6.07822)
		(end 480.108006 -6.545072)
		(width 0.11684)
		(layer "F.Cu")
		(net "NIC_MDI_SPRV_RJ45_1_R_DP")
	)
	(segment
		(start 475.60992 -9.713976)
		(end 476.19031 -9.133586)
		(width 0.11684)
		(layer "F.Cu")
		(net "NIC_MDI_SPRV_RJ45_1_R_DP")
	)
	(segment
		(start 475.94012 -11.179048)
		(end 475.94012 -10.828528)
		(width 0.11684)
		(layer "F.Cu")
		(net "NIC_MDI_SPRV_RJ45_1_R_DP")
	)
	(segment
		(start 475.60992 -11.859768)
		(end 475.60992 -11.509248)
		(width 0.11684)
		(layer "F.Cu")
		(net "NIC_MDI_SPRV_RJ45_1_R_DP")
	)
	(segment
		(start 480.822762 -6.792976)
		(end 481.004626 -6.97484)
		(width 0.11684)
		(layer "F.Cu")
		(net "NIC_MDI_SPRV_RJ45_1_R_DP")
	)
	(segment
		(start 477.656144 -14.092936)
		(end 477.391222 -13.828014)
		(width 0.11684)
		(layer "F.Cu")
		(net "NIC_MDI_SPRV_RJ45_1_R_DP")
	)
	(segment
		(start 477.15297 -8.170926)
		(end 477.15297 -6.866382)
		(width 0.11684)
		(layer "F.Cu")
		(net "NIC_MDI_SPRV_RJ45_1_R_DP")
	)
	(segment
		(start 479.860102 -5.830316)
		(end 480.108006 -6.07822)
		(width 0.11684)
		(layer "F.Cu")
		(net "NIC_MDI_SPRV_RJ45_1_R_DP")
	)
	(segment
		(start 481.825554 -7.09168)
		(end 481.825554 -7.27456)
		(width 0.11684)
		(layer "F.Cu")
		(net "NIC_MDI_SPRV_RJ45_1_R_DP")
	)
	(segment
		(start 478.977706 -4.94792)
		(end 479.145346 -5.11556)
		(width 0.11684)
		(layer "F.Cu")
		(net "NIC_MDI_SPRV_RJ45_1_R_DP")
	)
	(segment
		(start 477.15297 -6.866382)
		(end 476.227648 -5.94106)
		(width 0.11684)
		(layer "F.Cu")
		(net "NIC_MDI_SPRV_RJ45_1_R_DP")
	)
	(segment
		(start 476.19031 -9.133586)
		(end 476.657162 -9.133586)
		(width 0.11684)
		(layer "F.Cu")
		(net "NIC_MDI_SPRV_RJ45_1_R_DP")
	)
	(segment
		(start 476.227648 -5.94106)
		(end 476.227648 -4.454398)
		(width 0.11684)
		(layer "F.Cu")
		(net "NIC_MDI_SPRV_RJ45_1_R_DP")
	)
	(segment
		(start 476.227648 -4.454398)
		(end 476.50273 -4.179316)
		(width 0.11684)
		(layer "F.Cu")
		(net "NIC_MDI_SPRV_RJ45_1_R_DP")
	)
	(segment
		(start 477.033336 -13.828014)
		(end 476.482664 -14.378686)
		(width 0.11684)
		(layer "F.Cu")
		(net "NIC_MDI_SPRV_RJ45_1_R_DP")
	)
	(segment
		(start 476.905066 -8.41883)
		(end 477.15297 -8.170926)
		(width 0.11684)
		(layer "F.Cu")
		(net "NIC_MDI_SPRV_RJ45_1_R_DP")
	)
	(segment
		(start 475.835726 -14.378686)
		(end 475.60992 -14.15288)
		(width 0.11684)
		(layer "F.Cu")
		(net "NIC_MDI_SPRV_RJ45_1_R_DP")
	)
	(segment
		(start 479.145346 -5.11556)
		(end 479.145346 -5.582412)
		(width 0.11684)
		(layer "F.Cu")
		(net "NIC_MDI_SPRV_RJ45_1_R_DP")
	)
	(segment
		(start 475.94012 -10.828528)
		(end 475.60992 -10.498328)
		(width 0.11684)
		(layer "F.Cu")
		(net "NIC_MDI_SPRV_RJ45_1_R_DP")
	)
	(segment
		(start 475.60992 -11.509248)
		(end 475.94012 -11.179048)
		(width 0.11684)
		(layer "F.Cu")
		(net "NIC_MDI_SPRV_RJ45_1_R_DP")
	)
	(segment
		(start 477.010984 -4.179316)
		(end 477.779588 -4.94792)
		(width 0.11684)
		(layer "F.Cu")
		(net "NIC_MDI_SPRV_RJ45_1_R_DP")
	)
	(segment
		(start 475.94012 -12.540488)
		(end 475.94012 -12.189968)
		(width 0.11684)
		(layer "F.Cu")
		(net "NIC_MDI_SPRV_RJ45_1_R_DP")
	)
	(segment
		(start 475.60992 -10.498328)
		(end 475.60992 -9.713976)
		(width 0.11684)
		(layer "F.Cu")
		(net "NIC_MDI_SPRV_RJ45_1_R_DP")
	)
	(segment
		(start 475.60992 -12.870688)
		(end 475.94012 -12.540488)
		(width 0.11684)
		(layer "F.Cu")
		(net "NIC_MDI_SPRV_RJ45_1_R_DP")
	)
	(segment
		(start 480.35591 -6.792976)
		(end 480.822762 -6.792976)
		(width 0.11684)
		(layer "F.Cu")
		(net "NIC_MDI_SPRV_RJ45_1_R_DP")
	)
	(segment
		(start 477.656144 -14.478508)
		(end 477.656144 -14.092936)
		(width 0.11684)
		(layer "F.Cu")
		(net "NIC_MDI_SPRV_RJ45_1_R_DP")
	)
	(segment
		(start 475.60992 -14.15288)
		(end 475.60992 -12.870688)
		(width 0.11684)
		(layer "F.Cu")
		(net "NIC_MDI_SPRV_RJ45_1_R_DP")
	)
	(segment
		(start 481.708714 -6.97484)
		(end 481.825554 -7.09168)
		(width 0.11684)
		(layer "F.Cu")
		(net "NIC_MDI_SPRV_RJ45_1_R_DP")
	)
	(segment
		(start 480.108006 -6.545072)
		(end 480.35591 -6.792976)
		(width 0.11684)
		(layer "F.Cu")
		(net "NIC_MDI_SPRV_RJ45_1_R_DP")
	)
	(segment
		(start 476.905066 -8.885682)
		(end 476.905066 -8.41883)
		(width 0.11684)
		(layer "F.Cu")
		(net "NIC_MDI_SPRV_RJ45_1_R_DP")
	)
	(segment
		(start 476.482664 -14.378686)
		(end 475.835726 -14.378686)
		(width 0.11684)
		(layer "F.Cu")
		(net "NIC_MDI_SPRV_RJ45_1_R_DP")
	)
	(segment
		(start 477.779588 -4.94792)
		(end 478.977706 -4.94792)
		(width 0.11684)
		(layer "F.Cu")
		(net "NIC_MDI_SPRV_RJ45_1_R_DP")
	)
	(segment
		(start 481.825554 -7.27456)
		(end 481.57003 -7.530084)
		(width 0.11684)
		(layer "F.Cu")
		(net "NIC_MDI_SPRV_RJ45_1_R_DP")
	)
	(segment
		(start 477.391222 -13.828014)
		(end 477.033336 -13.828014)
		(width 0.11684)
		(layer "F.Cu")
		(net "NIC_MDI_SPRV_RJ45_1_R_DP")
	)
	(segment
		(start 475.94012 -12.189968)
		(end 475.60992 -11.859768)
		(width 0.11684)
		(layer "F.Cu")
		(net "NIC_MDI_SPRV_RJ45_1_R_DP")
	)
	(segment
		(start 477.201484 -3.719576)
		(end 477.970088 -4.48818)
		(width 0.11684)
		(layer "F.Cu")
		(net "NIC_MDI_SPRV_RJ45_1_R_DN")
	)
	(segment
		(start 476.31223 -3.719576)
		(end 477.201484 -3.719576)
		(width 0.11684)
		(layer "F.Cu")
		(net "NIC_MDI_SPRV_RJ45_1_R_DN")
	)
	(segment
		(start 475.15018 -9.523476)
		(end 476.69323 -7.980426)
		(width 0.11684)
		(layer "F.Cu")
		(net "NIC_MDI_SPRV_RJ45_1_R_DN")
	)
	(segment
		(start 479.168206 -4.48818)
		(end 481.195126 -6.5151)
		(width 0.11684)
		(layer "F.Cu")
		(net "NIC_MDI_SPRV_RJ45_1_R_DN")
	)
	(segment
		(start 476.69323 -7.980426)
		(end 476.69323 -7.056882)
		(width 0.11684)
		(layer "F.Cu")
		(net "NIC_MDI_SPRV_RJ45_1_R_DN")
	)
	(segment
		(start 475.15018 -14.34338)
		(end 475.15018 -9.523476)
		(width 0.11684)
		(layer "F.Cu")
		(net "NIC_MDI_SPRV_RJ45_1_R_DN")
	)
	(segment
		(start 476.69323 -7.056882)
		(end 475.767908 -6.13156)
		(width 0.11684)
		(layer "F.Cu")
		(net "NIC_MDI_SPRV_RJ45_1_R_DN")
	)
	(segment
		(start 475.767908 -6.13156)
		(end 475.767908 -4.263898)
		(width 0.11684)
		(layer "F.Cu")
		(net "NIC_MDI_SPRV_RJ45_1_R_DN")
	)
	(segment
		(start 477.242632 -14.838426)
		(end 475.645226 -14.838426)
		(width 0.11684)
		(layer "F.Cu")
		(net "NIC_MDI_SPRV_RJ45_1_R_DN")
	)
	(segment
		(start 475.767908 -4.263898)
		(end 476.31223 -3.719576)
		(width 0.11684)
		(layer "F.Cu")
		(net "NIC_MDI_SPRV_RJ45_1_R_DN")
	)
	(segment
		(start 475.645226 -14.838426)
		(end 475.15018 -14.34338)
		(width 0.11684)
		(layer "F.Cu")
		(net "NIC_MDI_SPRV_RJ45_1_R_DN")
	)
	(segment
		(start 481.195126 -6.5151)
		(end 482.84003 -6.5151)
		(width 0.11684)
		(layer "F.Cu")
		(net "NIC_MDI_SPRV_RJ45_1_R_DN")
	)
	(segment
		(start 477.656144 -15.251938)
		(end 477.242632 -14.838426)
		(width 0.11684)
		(layer "F.Cu")
		(net "NIC_MDI_SPRV_RJ45_1_R_DN")
	)
	(segment
		(start 477.970088 -4.48818)
		(end 479.168206 -4.48818)
		(width 0.11684)
		(layer "F.Cu")
		(net "NIC_MDI_SPRV_RJ45_1_R_DN")
	)
	(segment
		(start 478.322132 -10.412476)
		(end 478.13976 -10.230104)
		(width 0.11684)
		(layer "F.Cu")
		(net "NIC_MDI_SPRV_RJ45_0_R_DP")
	)
	(segment
		(start 481.822252 -9.30783)
		(end 481.57003 -9.560052)
		(width 0.11684)
		(layer "F.Cu")
		(net "NIC_MDI_SPRV_RJ45_0_R_DP")
	)
	(segment
		(start 480.709732 -9.00811)
		(end 481.68814 -9.00811)
		(width 0.11684)
		(layer "F.Cu")
		(net "NIC_MDI_SPRV_RJ45_0_R_DP")
	)
	(segment
		(start 479.452178 -8.625078)
		(end 480.3267 -8.625078)
		(width 0.11684)
		(layer "F.Cu")
		(net "NIC_MDI_SPRV_RJ45_0_R_DP")
	)
	(segment
		(start 480.3267 -8.625078)
		(end 480.709732 -9.00811)
		(width 0.11684)
		(layer "F.Cu")
		(net "NIC_MDI_SPRV_RJ45_0_R_DP")
	)
	(segment
		(start 481.68814 -9.00811)
		(end 481.822252 -9.142222)
		(width 0.11684)
		(layer "F.Cu")
		(net "NIC_MDI_SPRV_RJ45_0_R_DP")
	)
	(segment
		(start 478.912682 -10.412476)
		(end 478.322132 -10.412476)
		(width 0.11684)
		(layer "F.Cu")
		(net "NIC_MDI_SPRV_RJ45_0_R_DP")
	)
	(segment
		(start 478.917254 -11.573256)
		(end 479.098356 -11.392154)
		(width 0.11684)
		(layer "F.Cu")
		(net "NIC_MDI_SPRV_RJ45_0_R_DP")
	)
	(segment
		(start 479.098356 -10.59815)
		(end 478.912682 -10.412476)
		(width 0.11684)
		(layer "F.Cu")
		(net "NIC_MDI_SPRV_RJ45_0_R_DP")
	)
	(segment
		(start 478.540572 -11.573256)
		(end 478.917254 -11.573256)
		(width 0.11684)
		(layer "F.Cu")
		(net "NIC_MDI_SPRV_RJ45_0_R_DP")
	)
	(segment
		(start 478.13976 -10.230104)
		(end 478.13976 -9.937496)
		(width 0.11684)
		(layer "F.Cu")
		(net "NIC_MDI_SPRV_RJ45_0_R_DP")
	)
	(segment
		(start 479.098356 -11.392154)
		(end 479.098356 -10.59815)
		(width 0.11684)
		(layer "F.Cu")
		(net "NIC_MDI_SPRV_RJ45_0_R_DP")
	)
	(segment
		(start 481.822252 -9.142222)
		(end 481.822252 -9.30783)
		(width 0.11684)
		(layer "F.Cu")
		(net "NIC_MDI_SPRV_RJ45_0_R_DP")
	)
	(segment
		(start 478.13976 -9.937496)
		(end 479.452178 -8.625078)
		(width 0.11684)
		(layer "F.Cu")
		(net "NIC_MDI_SPRV_RJ45_0_R_DP")
	)
	(segment
		(start 477.68002 -9.746996)
		(end 479.261678 -8.165338)
		(width 0.11684)
		(layer "F.Cu")
		(net "NIC_MDI_SPRV_RJ45_0_R_DN")
	)
	(segment
		(start 480.900232 -8.54837)
		(end 482.836728 -8.54837)
		(width 0.11684)
		(layer "F.Cu")
		(net "NIC_MDI_SPRV_RJ45_0_R_DN")
	)
	(segment
		(start 477.68002 -11.585194)
		(end 477.68002 -9.746996)
		(width 0.11684)
		(layer "F.Cu")
		(net "NIC_MDI_SPRV_RJ45_0_R_DN")
	)
	(segment
		(start 479.261678 -8.165338)
		(end 480.5172 -8.165338)
		(width 0.11684)
		(layer "F.Cu")
		(net "NIC_MDI_SPRV_RJ45_0_R_DN")
	)
	(segment
		(start 482.836728 -8.54837)
		(end 482.84003 -8.545068)
		(width 0.11684)
		(layer "F.Cu")
		(net "NIC_MDI_SPRV_RJ45_0_R_DN")
	)
	(segment
		(start 480.5172 -8.165338)
		(end 480.900232 -8.54837)
		(width 0.11684)
		(layer "F.Cu")
		(net "NIC_MDI_SPRV_RJ45_0_R_DN")
	)
	(segment
		(start 379.984 -47.625)
		(end 379.984 -47.1043)
		(width 0.10795)
		(layer "B.Cu")
		(net "IRQ_CPU1_PROCHOT_G_N")
	)
	(segment
		(start 380.34976 -46.73854)
		(end 380.746 -46.73854)
		(width 0.10795)
		(layer "B.Cu")
		(net "IRQ_CPU1_PROCHOT_G_N")
	)
	(segment
		(start 379.30201 -48.30699)
		(end 379.984 -47.625)
		(width 0.10795)
		(layer "B.Cu")
		(net "IRQ_CPU1_PROCHOT_G_N")
	)
	(segment
		(start 378.196348 -48.30699)
		(end 379.30201 -48.30699)
		(width 0.10795)
		(layer "B.Cu")
		(net "IRQ_CPU1_PROCHOT_G_N")
	)
	(segment
		(start 379.984 -47.1043)
		(end 380.34976 -46.73854)
		(width 0.10795)
		(layer "B.Cu")
		(net "IRQ_CPU1_PROCHOT_G_N")
	)
	(via
		(at 369.336066 -39.996872)
		(size 0.6604)
		(drill 0.3302)
		(layers "F.Cu" "B.Cu")
		(net "IRQ_CPU0_PROCHOT_G_N")
	)
	(segment
		(start 374.231916 -37.713666)
		(end 373.86895 -37.713666)
		(width 0.10795)
		(layer "B.Cu")
		(net "IRQ_CPU0_PROCHOT_G_N")
	)
	(segment
		(start 373.86895 -37.713666)
		(end 373.196104 -38.386512)
		(width 0.10795)
		(layer "B.Cu")
		(net "IRQ_CPU0_PROCHOT_G_N")
	)
	(segment
		(start 369.336066 -39.996872)
		(end 371.381528 -39.996872)
		(width 0.10795)
		(layer "B.Cu")
		(net "IRQ_CPU0_PROCHOT_G_N")
	)
	(segment
		(start 373.196104 -38.386512)
		(end 372.707916 -38.386512)
		(width 0.10795)
		(layer "B.Cu")
		(net "IRQ_CPU0_PROCHOT_G_N")
	)
	(segment
		(start 372.707916 -38.670484)
		(end 372.707916 -38.386512)
		(width 0.10795)
		(layer "B.Cu")
		(net "IRQ_CPU0_PROCHOT_G_N")
	)
	(segment
		(start 371.381528 -39.996872)
		(end 372.707916 -38.670484)
		(width 0.10795)
		(layer "B.Cu")
		(net "IRQ_CPU0_PROCHOT_G_N")
	)
	(via
		(at 451.53199 -3.25882)
		(size 0.6604)
		(drill 0.3302)
		(layers "F.Cu" "B.Cu")
		(net "PD_IE_DEBUG_MODE")
	)
	(segment
		(start 451.53199 -3.25882)
		(end 451.53199 -1.93421)
		(width 0.10795)
		(layer "B.Cu")
		(net "PD_IE_DEBUG_MODE")
	)
	(segment
		(start 452.010272 -4.614672)
		(end 452.35241 -4.614672)
		(width 0.10795)
		(layer "B.Cu")
		(net "PD_IE_DEBUG_MODE")
	)
	(segment
		(start 460.892144 2.548128)
		(end 462.154016 3.81)
		(width 0.10795)
		(layer "B.Cu")
		(net "PD_IE_DEBUG_MODE")
	)
	(segment
		(start 451.53199 -3.25882)
		(end 451.53199 -4.13639)
		(width 0.10795)
		(layer "B.Cu")
		(net "PD_IE_DEBUG_MODE")
	)
	(segment
		(start 451.53199 -1.93421)
		(end 453.493632 0.027432)
		(width 0.10795)
		(layer "B.Cu")
		(net "PD_IE_DEBUG_MODE")
	)
	(segment
		(start 451.53199 -4.13639)
		(end 452.010272 -4.614672)
		(width 0.10795)
		(layer "B.Cu")
		(net "PD_IE_DEBUG_MODE")
	)
	(segment
		(start 453.855328 2.548128)
		(end 460.892144 2.548128)
		(width 0.10795)
		(layer "B.Cu")
		(net "PD_IE_DEBUG_MODE")
	)
	(segment
		(start 453.493632 2.186432)
		(end 453.855328 2.548128)
		(width 0.10795)
		(layer "B.Cu")
		(net "PD_IE_DEBUG_MODE")
	)
	(segment
		(start 453.493632 0.027432)
		(end 453.493632 2.186432)
		(width 0.10795)
		(layer "B.Cu")
		(net "PD_IE_DEBUG_MODE")
	)
	(segment
		(start 377.145042 -80.295242)
		(end 377.544584 -80.694784)
		(width 0.10795)
		(layer "F.Cu")
		(net "FM_DIS_ADR_DLY")
	)
	(segment
		(start 442.849762 1.27)
		(end 442.849 1.27)
		(width 0.10795)
		(layer "F.Cu")
		(net "FM_DIS_ADR_DLY")
	)
	(segment
		(start 442.849 -0.6985)
		(end 443.2935 -1.143)
		(width 0.10795)
		(layer "F.Cu")
		(net "FM_DIS_ADR_DLY")
	)
	(segment
		(start 442.849 1.27)
		(end 442.849 -0.6985)
		(width 0.10795)
		(layer "F.Cu")
		(net "FM_DIS_ADR_DLY")
	)
	(segment
		(start 443.2935 -1.6002)
		(end 443.2935 -1.143)
		(width 0.10795)
		(layer "F.Cu")
		(net "FM_DIS_ADR_DLY")
	)
	(segment
		(start 377.145042 -80.294988)
		(end 377.145042 -80.295242)
		(width 0.10795)
		(layer "F.Cu")
		(net "FM_DIS_ADR_DLY")
	)
	(segment
		(start 444.024258 -2.330958)
		(end 443.2935 -1.6002)
		(width 0.10795)
		(layer "F.Cu")
		(net "FM_DIS_ADR_DLY")
	)
	(segment
		(start 444.26759 -2.330958)
		(end 444.024258 -2.330958)
		(width 0.10795)
		(layer "F.Cu")
		(net "FM_DIS_ADR_DLY")
	)
	(via
		(at 444.26759 -2.330958)
		(size 0.508)
		(drill 0.254)
		(layers "F.Cu" "B.Cu")
		(net "FM_DIS_ADR_DLY")
	)
	(via
		(at 463.1182 -5.5118)
		(size 0.508)
		(drill 0.254)
		(layers "F.Cu" "B.Cu")
		(net "FM_DIS_ADR_DLY")
	)
	(via
		(at 476.6818 -52.7304)
		(size 0.508)
		(drill 0.254)
		(layers "F.Cu" "B.Cu")
		(net "FM_DIS_ADR_DLY")
	)
	(via
		(at 377.544584 -80.694784)
		(size 0.4572)
		(drill 0.2032)
		(layers "F.Cu" "B.Cu")
		(net "FM_DIS_ADR_DLY")
	)
	(segment
		(start 462.60512 -1.707134)
		(end 462.014824 -1.116838)
		(width 0.089408)
		(layer "In2.Cu")
		(net "FM_DIS_ADR_DLY")
	)
	(segment
		(start 463.1182 -5.5118)
		(end 463.1182 -5.358892)
		(width 0.089408)
		(layer "In2.Cu")
		(net "FM_DIS_ADR_DLY")
	)
	(segment
		(start 463.614008 -4.863084)
		(end 463.614008 -2.045462)
		(width 0.089408)
		(layer "In2.Cu")
		(net "FM_DIS_ADR_DLY")
	)
	(segment
		(start 463.614008 -2.045462)
		(end 463.27568 -1.707134)
		(width 0.089408)
		(layer "In2.Cu")
		(net "FM_DIS_ADR_DLY")
	)
	(segment
		(start 460.703422 -1.116838)
		(end 459.991968 -0.405384)
		(width 0.089408)
		(layer "In2.Cu")
		(net "FM_DIS_ADR_DLY")
	)
	(segment
		(start 463.1182 -5.358892)
		(end 463.614008 -4.863084)
		(width 0.089408)
		(layer "In2.Cu")
		(net "FM_DIS_ADR_DLY")
	)
	(segment
		(start 456.291442 -0.176784)
		(end 451.724522 -0.176784)
		(width 0.089408)
		(layer "In2.Cu")
		(net "FM_DIS_ADR_DLY")
	)
	(segment
		(start 450.918834 -0.982472)
		(end 445.616076 -0.982472)
		(width 0.089408)
		(layer "In2.Cu")
		(net "FM_DIS_ADR_DLY")
	)
	(segment
		(start 451.724522 -0.176784)
		(end 450.918834 -0.982472)
		(width 0.089408)
		(layer "In2.Cu")
		(net "FM_DIS_ADR_DLY")
	)
	(segment
		(start 459.991968 -0.405384)
		(end 456.520042 -0.405384)
		(width 0.089408)
		(layer "In2.Cu")
		(net "FM_DIS_ADR_DLY")
	)
	(segment
		(start 445.616076 -0.982472)
		(end 444.26759 -2.330958)
		(width 0.089408)
		(layer "In2.Cu")
		(net "FM_DIS_ADR_DLY")
	)
	(segment
		(start 462.014824 -1.116838)
		(end 460.703422 -1.116838)
		(width 0.089408)
		(layer "In2.Cu")
		(net "FM_DIS_ADR_DLY")
	)
	(segment
		(start 463.27568 -1.707134)
		(end 462.60512 -1.707134)
		(width 0.089408)
		(layer "In2.Cu")
		(net "FM_DIS_ADR_DLY")
	)
	(segment
		(start 456.520042 -0.405384)
		(end 456.291442 -0.176784)
		(width 0.089408)
		(layer "In2.Cu")
		(net "FM_DIS_ADR_DLY")
	)
	(segment
		(start 417.823396 -68.425822)
		(end 417.823396 -67.079622)
		(width 0.089408)
		(layer "In4.Cu")
		(net "FM_DIS_ADR_DLY")
	)
	(segment
		(start 416.519106 -72.316848)
		(end 416.519106 -69.730112)
		(width 0.089408)
		(layer "In4.Cu")
		(net "FM_DIS_ADR_DLY")
	)
	(segment
		(start 416.519106 -69.730112)
		(end 417.823396 -68.425822)
		(width 0.089408)
		(layer "In4.Cu")
		(net "FM_DIS_ADR_DLY")
	)
	(segment
		(start 475.290388 -53.57622)
		(end 475.290642 -53.576474)
		(width 0.089408)
		(layer "In4.Cu")
		(net "FM_DIS_ADR_DLY")
	)
	(segment
		(start 381.000762 -79.912718)
		(end 383.313432 -79.912718)
		(width 0.089408)
		(layer "In4.Cu")
		(net "FM_DIS_ADR_DLY")
	)
	(segment
		(start 425.432982 -63.586868)
		(end 426.096176 -64.250062)
		(width 0.089408)
		(layer "In4.Cu")
		(net "FM_DIS_ADR_DLY")
	)
	(segment
		(start 417.823396 -67.079622)
		(end 420.64432 -64.258698)
		(width 0.089408)
		(layer "In4.Cu")
		(net "FM_DIS_ADR_DLY")
	)
	(segment
		(start 415.389314 -72.553068)
		(end 415.498534 -72.553068)
		(width 0.089408)
		(layer "In4.Cu")
		(net "FM_DIS_ADR_DLY")
	)
	(segment
		(start 475.290642 -53.576474)
		(end 475.835726 -53.576474)
		(width 0.089408)
		(layer "In4.Cu")
		(net "FM_DIS_ADR_DLY")
	)
	(segment
		(start 401.14855 -76.776072)
		(end 402.25345 -75.671172)
		(width 0.089408)
		(layer "In4.Cu")
		(net "FM_DIS_ADR_DLY")
	)
	(segment
		(start 416.282632 -72.553322)
		(end 416.519106 -72.316848)
		(width 0.089408)
		(layer "In4.Cu")
		(net "FM_DIS_ADR_DLY")
	)
	(segment
		(start 420.64432 -64.258698)
		(end 422.525952 -64.258698)
		(width 0.089408)
		(layer "In4.Cu")
		(net "FM_DIS_ADR_DLY")
	)
	(segment
		(start 405.73452 -77.153516)
		(end 405.73452 -78.543912)
		(width 0.089408)
		(layer "In4.Cu")
		(net "FM_DIS_ADR_DLY")
	)
	(segment
		(start 415.50209 -72.549512)
		(end 415.99231 -72.549512)
		(width 0.089408)
		(layer "In4.Cu")
		(net "FM_DIS_ADR_DLY")
	)
	(segment
		(start 404.252176 -75.671172)
		(end 405.73452 -77.153516)
		(width 0.089408)
		(layer "In4.Cu")
		(net "FM_DIS_ADR_DLY")
	)
	(segment
		(start 386.858256 -78.783434)
		(end 388.5057 -78.783434)
		(width 0.089408)
		(layer "In4.Cu")
		(net "FM_DIS_ADR_DLY")
	)
	(segment
		(start 397.7767 -77.888846)
		(end 398.889474 -76.776072)
		(width 0.089408)
		(layer "In4.Cu")
		(net "FM_DIS_ADR_DLY")
	)
	(segment
		(start 383.587498 -79.638652)
		(end 383.587498 -79.047594)
		(width 0.089408)
		(layer "In4.Cu")
		(net "FM_DIS_ADR_DLY")
	)
	(segment
		(start 452.218552 -62.736476)
		(end 457.642976 -62.736476)
		(width 0.089408)
		(layer "In4.Cu")
		(net "FM_DIS_ADR_DLY")
	)
	(segment
		(start 474.824298 -53.96738)
		(end 474.824298 -53.884068)
		(width 0.089408)
		(layer "In4.Cu")
		(net "FM_DIS_ADR_DLY")
	)
	(segment
		(start 379.845316 -81.068164)
		(end 381.000762 -79.912718)
		(width 0.089408)
		(layer "In4.Cu")
		(net "FM_DIS_ADR_DLY")
	)
	(segment
		(start 396.745206 -77.178154)
		(end 397.455898 -77.888846)
		(width 0.089408)
		(layer "In4.Cu")
		(net "FM_DIS_ADR_DLY")
	)
	(segment
		(start 383.587498 -79.047594)
		(end 384.690366 -77.944726)
		(width 0.089408)
		(layer "In4.Cu")
		(net "FM_DIS_ADR_DLY")
	)
	(segment
		(start 392.498326 -77.577442)
		(end 395.027404 -77.577442)
		(width 0.089408)
		(layer "In4.Cu")
		(net "FM_DIS_ADR_DLY")
	)
	(segment
		(start 389.177022 -79.454756)
		(end 389.92175 -79.454756)
		(width 0.089408)
		(layer "In4.Cu")
		(net "FM_DIS_ADR_DLY")
	)
	(segment
		(start 422.525952 -64.258698)
		(end 423.198036 -63.586614)
		(width 0.089408)
		(layer "In4.Cu")
		(net "FM_DIS_ADR_DLY")
	)
	(segment
		(start 465.050378 -55.1434)
		(end 465.69249 -54.501288)
		(width 0.089408)
		(layer "In4.Cu")
		(net "FM_DIS_ADR_DLY")
	)
	(segment
		(start 423.198036 -63.586614)
		(end 423.51452 -63.586614)
		(width 0.089408)
		(layer "In4.Cu")
		(net "FM_DIS_ADR_DLY")
	)
	(segment
		(start 466.18271 -54.501288)
		(end 467.487 -55.805578)
		(width 0.089408)
		(layer "In4.Cu")
		(net "FM_DIS_ADR_DLY")
	)
	(segment
		(start 426.096176 -64.250062)
		(end 450.704966 -64.250062)
		(width 0.089408)
		(layer "In4.Cu")
		(net "FM_DIS_ADR_DLY")
	)
	(segment
		(start 402.25345 -75.671172)
		(end 404.252176 -75.671172)
		(width 0.089408)
		(layer "In4.Cu")
		(net "FM_DIS_ADR_DLY")
	)
	(segment
		(start 407.75128 -80.560672)
		(end 411.513528 -80.560672)
		(width 0.089408)
		(layer "In4.Cu")
		(net "FM_DIS_ADR_DLY")
	)
	(segment
		(start 390.88695 -78.646528)
		(end 391.828528 -77.70495)
		(width 0.089408)
		(layer "In4.Cu")
		(net "FM_DIS_ADR_DLY")
	)
	(segment
		(start 458.037692 -62.34176)
		(end 463.792824 -62.34176)
		(width 0.089408)
		(layer "In4.Cu")
		(net "FM_DIS_ADR_DLY")
	)
	(segment
		(start 465.050378 -61.084206)
		(end 465.050378 -55.1434)
		(width 0.089408)
		(layer "In4.Cu")
		(net "FM_DIS_ADR_DLY")
	)
	(segment
		(start 398.889474 -76.776072)
		(end 401.14855 -76.776072)
		(width 0.089408)
		(layer "In4.Cu")
		(net "FM_DIS_ADR_DLY")
	)
	(segment
		(start 405.73452 -78.543912)
		(end 407.75128 -80.560672)
		(width 0.089408)
		(layer "In4.Cu")
		(net "FM_DIS_ADR_DLY")
	)
	(segment
		(start 413.737044 -78.337156)
		(end 413.737044 -74.205338)
		(width 0.089408)
		(layer "In4.Cu")
		(net "FM_DIS_ADR_DLY")
	)
	(segment
		(start 388.5057 -78.783434)
		(end 389.177022 -79.454756)
		(width 0.089408)
		(layer "In4.Cu")
		(net "FM_DIS_ADR_DLY")
	)
	(segment
		(start 423.51452 -63.586614)
		(end 423.514774 -63.586868)
		(width 0.089408)
		(layer "In4.Cu")
		(net "FM_DIS_ADR_DLY")
	)
	(segment
		(start 377.917964 -81.068164)
		(end 379.845316 -81.068164)
		(width 0.089408)
		(layer "In4.Cu")
		(net "FM_DIS_ADR_DLY")
	)
	(segment
		(start 450.704966 -64.250062)
		(end 452.218552 -62.736476)
		(width 0.089408)
		(layer "In4.Cu")
		(net "FM_DIS_ADR_DLY")
	)
	(segment
		(start 465.69249 -54.501288)
		(end 466.18271 -54.501288)
		(width 0.089408)
		(layer "In4.Cu")
		(net "FM_DIS_ADR_DLY")
	)
	(segment
		(start 391.828528 -77.70495)
		(end 392.370818 -77.70495)
		(width 0.089408)
		(layer "In4.Cu")
		(net "FM_DIS_ADR_DLY")
	)
	(segment
		(start 475.132146 -53.57622)
		(end 475.290388 -53.57622)
		(width 0.089408)
		(layer "In4.Cu")
		(net "FM_DIS_ADR_DLY")
	)
	(segment
		(start 384.690366 -77.944726)
		(end 386.019548 -77.944726)
		(width 0.089408)
		(layer "In4.Cu")
		(net "FM_DIS_ADR_DLY")
	)
	(segment
		(start 467.487 -55.805578)
		(end 469.067134 -55.805578)
		(width 0.089408)
		(layer "In4.Cu")
		(net "FM_DIS_ADR_DLY")
	)
	(segment
		(start 474.824298 -53.884068)
		(end 475.132146 -53.57622)
		(width 0.089408)
		(layer "In4.Cu")
		(net "FM_DIS_ADR_DLY")
	)
	(segment
		(start 395.027404 -77.577442)
		(end 395.426692 -77.178154)
		(width 0.089408)
		(layer "In4.Cu")
		(net "FM_DIS_ADR_DLY")
	)
	(segment
		(start 383.313432 -79.912718)
		(end 383.587498 -79.638652)
		(width 0.089408)
		(layer "In4.Cu")
		(net "FM_DIS_ADR_DLY")
	)
	(segment
		(start 474.82252 -55.9562)
		(end 474.82252 -53.969158)
		(width 0.089408)
		(layer "In4.Cu")
		(net "FM_DIS_ADR_DLY")
	)
	(segment
		(start 397.455898 -77.888846)
		(end 397.7767 -77.888846)
		(width 0.089408)
		(layer "In4.Cu")
		(net "FM_DIS_ADR_DLY")
	)
	(segment
		(start 415.498534 -72.553068)
		(end 415.50209 -72.549512)
		(width 0.089408)
		(layer "In4.Cu")
		(net "FM_DIS_ADR_DLY")
	)
	(segment
		(start 377.544584 -80.694784)
		(end 377.917964 -81.068164)
		(width 0.089408)
		(layer "In4.Cu")
		(net "FM_DIS_ADR_DLY")
	)
	(segment
		(start 389.92175 -79.454756)
		(end 390.729978 -78.646528)
		(width 0.089408)
		(layer "In4.Cu")
		(net "FM_DIS_ADR_DLY")
	)
	(segment
		(start 386.019548 -77.944726)
		(end 386.858256 -78.783434)
		(width 0.089408)
		(layer "In4.Cu")
		(net "FM_DIS_ADR_DLY")
	)
	(segment
		(start 469.067134 -55.805578)
		(end 469.934544 -56.672988)
		(width 0.089408)
		(layer "In4.Cu")
		(net "FM_DIS_ADR_DLY")
	)
	(segment
		(start 392.370818 -77.70495)
		(end 392.498326 -77.577442)
		(width 0.089408)
		(layer "In4.Cu")
		(net "FM_DIS_ADR_DLY")
	)
	(segment
		(start 457.642976 -62.736476)
		(end 458.037692 -62.34176)
		(width 0.089408)
		(layer "In4.Cu")
		(net "FM_DIS_ADR_DLY")
	)
	(segment
		(start 469.934544 -56.672988)
		(end 474.105732 -56.672988)
		(width 0.089408)
		(layer "In4.Cu")
		(net "FM_DIS_ADR_DLY")
	)
	(segment
		(start 474.82252 -53.969158)
		(end 474.824298 -53.96738)
		(width 0.089408)
		(layer "In4.Cu")
		(net "FM_DIS_ADR_DLY")
	)
	(segment
		(start 415.99231 -72.549512)
		(end 415.99612 -72.553322)
		(width 0.089408)
		(layer "In4.Cu")
		(net "FM_DIS_ADR_DLY")
	)
	(segment
		(start 413.737044 -74.205338)
		(end 415.389314 -72.553068)
		(width 0.089408)
		(layer "In4.Cu")
		(net "FM_DIS_ADR_DLY")
	)
	(segment
		(start 411.513528 -80.560672)
		(end 413.737044 -78.337156)
		(width 0.089408)
		(layer "In4.Cu")
		(net "FM_DIS_ADR_DLY")
	)
	(segment
		(start 395.426692 -77.178154)
		(end 396.745206 -77.178154)
		(width 0.089408)
		(layer "In4.Cu")
		(net "FM_DIS_ADR_DLY")
	)
	(segment
		(start 463.792824 -62.34176)
		(end 465.050378 -61.084206)
		(width 0.089408)
		(layer "In4.Cu")
		(net "FM_DIS_ADR_DLY")
	)
	(segment
		(start 390.729978 -78.646528)
		(end 390.88695 -78.646528)
		(width 0.089408)
		(layer "In4.Cu")
		(net "FM_DIS_ADR_DLY")
	)
	(segment
		(start 475.835726 -53.576474)
		(end 476.6818 -52.7304)
		(width 0.089408)
		(layer "In4.Cu")
		(net "FM_DIS_ADR_DLY")
	)
	(segment
		(start 423.514774 -63.586868)
		(end 425.432982 -63.586868)
		(width 0.089408)
		(layer "In4.Cu")
		(net "FM_DIS_ADR_DLY")
	)
	(segment
		(start 415.99612 -72.553322)
		(end 416.282632 -72.553322)
		(width 0.089408)
		(layer "In4.Cu")
		(net "FM_DIS_ADR_DLY")
	)
	(segment
		(start 474.105732 -56.672988)
		(end 474.82252 -55.9562)
		(width 0.089408)
		(layer "In4.Cu")
		(net "FM_DIS_ADR_DLY")
	)
	(segment
		(start 476.34144 -52.39004)
		(end 476.6818 -52.7304)
		(width 0.089408)
		(layer "In9.Cu")
		(net "FM_DIS_ADR_DLY")
	)
	(segment
		(start 464.561682 -7.177024)
		(end 464.64728 -7.177024)
		(width 0.089408)
		(layer "In9.Cu")
		(net "FM_DIS_ADR_DLY")
	)
	(segment
		(start 477.074992 -44.351448)
		(end 477.074992 -48.550068)
		(width 0.089408)
		(layer "In9.Cu")
		(net "FM_DIS_ADR_DLY")
	)
	(segment
		(start 478.2566 -38.50894)
		(end 478.2566 -39.781226)
		(width 0.089408)
		(layer "In9.Cu")
		(net "FM_DIS_ADR_DLY")
	)
	(segment
		(start 470.820496 -13.333984)
		(end 475.615 -18.128488)
		(width 0.089408)
		(layer "In9.Cu")
		(net "FM_DIS_ADR_DLY")
	)
	(segment
		(start 475.615 -18.128488)
		(end 475.615 -21.006308)
		(width 0.089408)
		(layer "In9.Cu")
		(net "FM_DIS_ADR_DLY")
	)
	(segment
		(start 468.991696 -13.333984)
		(end 470.820496 -13.333984)
		(width 0.089408)
		(layer "In9.Cu")
		(net "FM_DIS_ADR_DLY")
	)
	(segment
		(start 477.536256 -37.788596)
		(end 478.2566 -38.50894)
		(width 0.089408)
		(layer "In9.Cu")
		(net "FM_DIS_ADR_DLY")
	)
	(segment
		(start 468.241634 -10.657078)
		(end 468.24138 -10.657332)
		(width 0.089408)
		(layer "In9.Cu")
		(net "FM_DIS_ADR_DLY")
	)
	(segment
		(start 476.34144 -49.28362)
		(end 476.34144 -52.39004)
		(width 0.089408)
		(layer "In9.Cu")
		(net "FM_DIS_ADR_DLY")
	)
	(segment
		(start 468.24138 -12.583668)
		(end 468.991696 -13.333984)
		(width 0.089408)
		(layer "In9.Cu")
		(net "FM_DIS_ADR_DLY")
	)
	(segment
		(start 463.1182 -5.5118)
		(end 463.1182 -5.733542)
		(width 0.089408)
		(layer "In9.Cu")
		(net "FM_DIS_ADR_DLY")
	)
	(segment
		(start 477.189292 -22.5806)
		(end 477.6978 -22.5806)
		(width 0.089408)
		(layer "In9.Cu")
		(net "FM_DIS_ADR_DLY")
	)
	(segment
		(start 463.1182 -5.733542)
		(end 464.561682 -7.177024)
		(width 0.089408)
		(layer "In9.Cu")
		(net "FM_DIS_ADR_DLY")
	)
	(segment
		(start 480.017074 -33.418272)
		(end 477.536256 -35.89909)
		(width 0.089408)
		(layer "In9.Cu")
		(net "FM_DIS_ADR_DLY")
	)
	(segment
		(start 477.52127 -43.90517)
		(end 477.074992 -44.351448)
		(width 0.089408)
		(layer "In9.Cu")
		(net "FM_DIS_ADR_DLY")
	)
	(segment
		(start 480.838002 -27.84983)
		(end 480.017074 -28.670758)
		(width 0.089408)
		(layer "In9.Cu")
		(net "FM_DIS_ADR_DLY")
	)
	(segment
		(start 466.895434 -7.366)
		(end 468.24138 -8.711946)
		(width 0.089408)
		(layer "In9.Cu")
		(net "FM_DIS_ADR_DLY")
	)
	(segment
		(start 468.241634 -10.49909)
		(end 468.241634 -10.657078)
		(width 0.089408)
		(layer "In9.Cu")
		(net "FM_DIS_ADR_DLY")
	)
	(segment
		(start 478.2566 -39.781226)
		(end 477.52127 -40.516556)
		(width 0.089408)
		(layer "In9.Cu")
		(net "FM_DIS_ADR_DLY")
	)
	(segment
		(start 468.24138 -10.498836)
		(end 468.241634 -10.49909)
		(width 0.089408)
		(layer "In9.Cu")
		(net "FM_DIS_ADR_DLY")
	)
	(segment
		(start 464.64728 -7.177024)
		(end 464.836256 -7.366)
		(width 0.089408)
		(layer "In9.Cu")
		(net "FM_DIS_ADR_DLY")
	)
	(segment
		(start 464.836256 -7.366)
		(end 466.895434 -7.366)
		(width 0.089408)
		(layer "In9.Cu")
		(net "FM_DIS_ADR_DLY")
	)
	(segment
		(start 477.536256 -35.89909)
		(end 477.536256 -37.788596)
		(width 0.089408)
		(layer "In9.Cu")
		(net "FM_DIS_ADR_DLY")
	)
	(segment
		(start 477.52127 -40.516556)
		(end 477.52127 -43.90517)
		(width 0.089408)
		(layer "In9.Cu")
		(net "FM_DIS_ADR_DLY")
	)
	(segment
		(start 477.6978 -22.5806)
		(end 480.838002 -25.720802)
		(width 0.089408)
		(layer "In9.Cu")
		(net "FM_DIS_ADR_DLY")
	)
	(segment
		(start 480.017074 -28.670758)
		(end 480.017074 -33.418272)
		(width 0.089408)
		(layer "In9.Cu")
		(net "FM_DIS_ADR_DLY")
	)
	(segment
		(start 468.24138 -10.657332)
		(end 468.24138 -12.583668)
		(width 0.089408)
		(layer "In9.Cu")
		(net "FM_DIS_ADR_DLY")
	)
	(segment
		(start 477.074992 -48.550068)
		(end 476.34144 -49.28362)
		(width 0.089408)
		(layer "In9.Cu")
		(net "FM_DIS_ADR_DLY")
	)
	(segment
		(start 475.615 -21.006308)
		(end 477.189292 -22.5806)
		(width 0.089408)
		(layer "In9.Cu")
		(net "FM_DIS_ADR_DLY")
	)
	(segment
		(start 480.838002 -25.720802)
		(end 480.838002 -27.84983)
		(width 0.089408)
		(layer "In9.Cu")
		(net "FM_DIS_ADR_DLY")
	)
	(segment
		(start 468.24138 -8.711946)
		(end 468.24138 -10.498836)
		(width 0.089408)
		(layer "In9.Cu")
		(net "FM_DIS_ADR_DLY")
	)
	(segment
		(start 385.75615 -117.58168)
		(end 386.25145 -117.811804)
		(width 0.1016)
		(layer "F.Cu")
		(net "XDP_PCH_CPU_TCK0")
	)
	(via
		(at 386.1562 -125.476)
		(size 0.6604)
		(drill 0.3302)
		(layers "F.Cu" "B.Cu")
		(net "XDP_PCH_CPU_TCK0")
	)
	(via
		(at 386.25145 -117.811804)
		(size 0.508)
		(drill 0.254)
		(layers "F.Cu" "B.Cu")
		(net "XDP_PCH_CPU_TCK0")
	)
	(via
		(at 454.025 -152.527)
		(size 0.508)
		(drill 0.254)
		(layers "F.Cu" "B.Cu")
		(net "XDP_PCH_CPU_TCK0")
	)
	(segment
		(start 385.8514 -122.941334)
		(end 385.8514 -122.984514)
		(width 0.0889)
		(layer "B.Cu")
		(net "XDP_PCH_CPU_TCK0")
	)
	(segment
		(start 385.8514 -121.224294)
		(end 385.8514 -121.267474)
		(width 0.0889)
		(layer "B.Cu")
		(net "XDP_PCH_CPU_TCK0")
	)
	(segment
		(start 385.8514 -119.517668)
		(end 385.8514 -119.550434)
		(width 0.0889)
		(layer "B.Cu")
		(net "XDP_PCH_CPU_TCK0")
	)
	(segment
		(start 386.08254 -118.10492)
		(end 386.10667 -118.194328)
		(width 0.0889)
		(layer "B.Cu")
		(net "XDP_PCH_CPU_TCK0")
	)
	(segment
		(start 385.8514 -124.747274)
		(end 386.1562 -125.052074)
		(width 0.0889)
		(layer "B.Cu")
		(net "XDP_PCH_CPU_TCK0")
	)
	(segment
		(start 385.3561 -120.365774)
		(end 385.3561 -120.39854)
		(width 0.0889)
		(layer "B.Cu")
		(net "XDP_PCH_CPU_TCK0")
	)
	(segment
		(start 386.25145 -117.811804)
		(end 386.08254 -118.10492)
		(width 0.0889)
		(layer "B.Cu")
		(net "XDP_PCH_CPU_TCK0")
	)
	(segment
		(start 452.8058 -153.6446)
		(end 453.5678 -153.6446)
		(width 0.10795)
		(layer "B.Cu")
		(net "XDP_PCH_CPU_TCK0")
	)
	(segment
		(start 386.538724 -126.653544)
		(end 386.80898 -126.9238)
		(width 0.10795)
		(layer "B.Cu")
		(net "XDP_PCH_CPU_TCK0")
	)
	(segment
		(start 453.5678 -153.6446)
		(end 453.5678 -152.9842)
		(width 0.10795)
		(layer "B.Cu")
		(net "XDP_PCH_CPU_TCK0")
	)
	(segment
		(start 386.1562 -126.034546)
		(end 386.538724 -126.41707)
		(width 0.10795)
		(layer "B.Cu")
		(net "XDP_PCH_CPU_TCK0")
	)
	(segment
		(start 386.1562 -125.476)
		(end 386.1562 -126.034546)
		(width 0.10795)
		(layer "B.Cu")
		(net "XDP_PCH_CPU_TCK0")
	)
	(segment
		(start 386.3467 -118.648734)
		(end 386.3467 -118.691914)
		(width 0.0889)
		(layer "B.Cu")
		(net "XDP_PCH_CPU_TCK0")
	)
	(segment
		(start 385.8514 -124.658374)
		(end 385.8514 -124.747274)
		(width 0.0889)
		(layer "B.Cu")
		(net "XDP_PCH_CPU_TCK0")
	)
	(segment
		(start 386.538724 -126.41707)
		(end 386.538724 -126.653544)
		(width 0.10795)
		(layer "B.Cu")
		(net "XDP_PCH_CPU_TCK0")
	)
	(segment
		(start 386.1562 -125.052074)
		(end 386.1562 -125.476)
		(width 0.10795)
		(layer "B.Cu")
		(net "XDP_PCH_CPU_TCK0")
	)
	(segment
		(start 453.5678 -152.9842)
		(end 454.025 -152.527)
		(width 0.10795)
		(layer "B.Cu")
		(net "XDP_PCH_CPU_TCK0")
	)
	(arc
		(start 385.3561 -120.39854)
		(mid 385.41245 -120.59239)
		(end 385.556252 -120.734074)
		(width 0.0889)
		(layer "B.Cu")
		(net "XDP_PCH_CPU_TCK0")
	)
	(arc
		(start 385.556252 -121.757694)
		(mid 385.355941 -122.104404)
		(end 385.556252 -122.451114)
		(width 0.0889)
		(layer "B.Cu")
		(net "XDP_PCH_CPU_TCK0")
	)
	(arc
		(start 385.556252 -120.040654)
		(mid 385.410189 -120.174894)
		(end 385.3561 -120.365774)
		(width 0.0889)
		(layer "B.Cu")
		(net "XDP_PCH_CPU_TCK0")
	)
	(arc
		(start 386.051552 -119.182134)
		(mid 385.907748 -119.323817)
		(end 385.8514 -119.517668)
		(width 0.0889)
		(layer "B.Cu")
		(net "XDP_PCH_CPU_TCK0")
	)
	(arc
		(start 385.556252 -123.474734)
		(mid 385.355941 -123.821444)
		(end 385.556252 -124.168154)
		(width 0.0889)
		(layer "B.Cu")
		(net "XDP_PCH_CPU_TCK0")
	)
	(arc
		(start 386.3467 -118.691914)
		(mid 386.262419 -118.975131)
		(end 386.051552 -119.182134)
		(width 0.0889)
		(layer "B.Cu")
		(net "XDP_PCH_CPU_TCK0")
	)
	(arc
		(start 385.556252 -124.168154)
		(mid 385.767116 -124.375158)
		(end 385.8514 -124.658374)
		(width 0.0889)
		(layer "B.Cu")
		(net "XDP_PCH_CPU_TCK0")
	)
	(arc
		(start 385.556252 -120.734074)
		(mid 385.767116 -120.941078)
		(end 385.8514 -121.224294)
		(width 0.0889)
		(layer "B.Cu")
		(net "XDP_PCH_CPU_TCK0")
	)
	(arc
		(start 385.556252 -122.451114)
		(mid 385.767116 -122.658118)
		(end 385.8514 -122.941334)
		(width 0.0889)
		(layer "B.Cu")
		(net "XDP_PCH_CPU_TCK0")
	)
	(arc
		(start 385.8514 -119.550434)
		(mid 385.767119 -119.833651)
		(end 385.556252 -120.040654)
		(width 0.0889)
		(layer "B.Cu")
		(net "XDP_PCH_CPU_TCK0")
	)
	(arc
		(start 385.8514 -121.267474)
		(mid 385.767119 -121.550691)
		(end 385.556252 -121.757694)
		(width 0.0889)
		(layer "B.Cu")
		(net "XDP_PCH_CPU_TCK0")
	)
	(arc
		(start 385.8514 -122.984514)
		(mid 385.767119 -123.267731)
		(end 385.556252 -123.474734)
		(width 0.0889)
		(layer "B.Cu")
		(net "XDP_PCH_CPU_TCK0")
	)
	(arc
		(start 386.10667 -118.194328)
		(mid 386.278664 -118.394073)
		(end 386.3467 -118.648734)
		(width 0.0889)
		(layer "B.Cu")
		(net "XDP_PCH_CPU_TCK0")
	)
	(segment
		(start 401.475194 -131.88188)
		(end 402.508466 -130.848608)
		(width 0.089408)
		(layer "In2.Cu")
		(net "XDP_PCH_CPU_TCK0")
	)
	(segment
		(start 410.963618 -135.002778)
		(end 414.120838 -135.002778)
		(width 0.089408)
		(layer "In2.Cu")
		(net "XDP_PCH_CPU_TCK0")
	)
	(segment
		(start 430.512474 -133.48843)
		(end 436.129684 -133.48843)
		(width 0.089408)
		(layer "In2.Cu")
		(net "XDP_PCH_CPU_TCK0")
	)
	(segment
		(start 429.286924 -132.26288)
		(end 430.512474 -133.48843)
		(width 0.089408)
		(layer "In2.Cu")
		(net "XDP_PCH_CPU_TCK0")
	)
	(segment
		(start 447.95821 -136.662922)
		(end 447.491104 -137.130028)
		(width 0.089408)
		(layer "In2.Cu")
		(net "XDP_PCH_CPU_TCK0")
	)
	(segment
		(start 454.005696 -152.546304)
		(end 454.025 -152.527)
		(width 0.089408)
		(layer "In2.Cu")
		(net "XDP_PCH_CPU_TCK0")
	)
	(segment
		(start 387.1468 -118.659148)
		(end 387.1468 -118.691914)
		(width 0.0889)
		(layer "In2.Cu")
		(net "XDP_PCH_CPU_TCK0")
	)
	(segment
		(start 409.48356 -133.52272)
		(end 410.963618 -135.002778)
		(width 0.089408)
		(layer "In2.Cu")
		(net "XDP_PCH_CPU_TCK0")
	)
	(segment
		(start 437.782462 -135.141208)
		(end 447.044826 -135.141208)
		(width 0.089408)
		(layer "In2.Cu")
		(net "XDP_PCH_CPU_TCK0")
	)
	(segment
		(start 447.491104 -144.473168)
		(end 446.7098 -145.254472)
		(width 0.089408)
		(layer "In2.Cu")
		(net "XDP_PCH_CPU_TCK0")
	)
	(segment
		(start 447.95821 -136.054592)
		(end 447.95821 -136.662922)
		(width 0.089408)
		(layer "In2.Cu")
		(net "XDP_PCH_CPU_TCK0")
	)
	(segment
		(start 386.58927 -117.811804)
		(end 386.654294 -117.876828)
		(width 0.089408)
		(layer "In2.Cu")
		(net "XDP_PCH_CPU_TCK0")
	)
	(segment
		(start 390.4234 -125.361954)
		(end 390.4234 -130.41122)
		(width 0.089408)
		(layer "In2.Cu")
		(net "XDP_PCH_CPU_TCK0")
	)
	(segment
		(start 391.89406 -131.88188)
		(end 401.475194 -131.88188)
		(width 0.089408)
		(layer "In2.Cu")
		(net "XDP_PCH_CPU_TCK0")
	)
	(segment
		(start 388.1374 -120.376188)
		(end 388.1374 -120.408954)
		(width 0.0889)
		(layer "In2.Cu")
		(net "XDP_PCH_CPU_TCK0")
	)
	(segment
		(start 419.513512 -132.876036)
		(end 420.126668 -132.26288)
		(width 0.089408)
		(layer "In2.Cu")
		(net "XDP_PCH_CPU_TCK0")
	)
	(segment
		(start 409.48356 -132.559298)
		(end 409.48356 -133.52272)
		(width 0.089408)
		(layer "In2.Cu")
		(net "XDP_PCH_CPU_TCK0")
	)
	(segment
		(start 420.126668 -132.26288)
		(end 429.286924 -132.26288)
		(width 0.089408)
		(layer "In2.Cu")
		(net "XDP_PCH_CPU_TCK0")
	)
	(segment
		(start 390.4234 -130.41122)
		(end 391.89406 -131.88188)
		(width 0.089408)
		(layer "In2.Cu")
		(net "XDP_PCH_CPU_TCK0")
	)
	(segment
		(start 415.196782 -133.926834)
		(end 415.196782 -133.571234)
		(width 0.089408)
		(layer "In2.Cu")
		(net "XDP_PCH_CPU_TCK0")
	)
	(segment
		(start 447.491104 -137.130028)
		(end 447.491104 -144.473168)
		(width 0.089408)
		(layer "In2.Cu")
		(net "XDP_PCH_CPU_TCK0")
	)
	(segment
		(start 446.7098 -145.254472)
		(end 446.7098 -147.682966)
		(width 0.089408)
		(layer "In2.Cu")
		(net "XDP_PCH_CPU_TCK0")
	)
	(segment
		(start 386.25145 -117.811804)
		(end 386.58927 -117.811804)
		(width 0.089408)
		(layer "In2.Cu")
		(net "XDP_PCH_CPU_TCK0")
	)
	(segment
		(start 389.29945 -124.238004)
		(end 390.4234 -125.361954)
		(width 0.089408)
		(layer "In2.Cu")
		(net "XDP_PCH_CPU_TCK0")
	)
	(segment
		(start 389.128 -123.810268)
		(end 389.128 -123.843034)
		(width 0.0889)
		(layer "In2.Cu")
		(net "XDP_PCH_CPU_TCK0")
	)
	(segment
		(start 388.6327 -121.234708)
		(end 388.6327 -121.267474)
		(width 0.0889)
		(layer "In2.Cu")
		(net "XDP_PCH_CPU_TCK0")
	)
	(segment
		(start 447.044826 -135.141208)
		(end 447.95821 -136.054592)
		(width 0.089408)
		(layer "In2.Cu")
		(net "XDP_PCH_CPU_TCK0")
	)
	(segment
		(start 436.129684 -133.48843)
		(end 437.782462 -135.141208)
		(width 0.089408)
		(layer "In2.Cu")
		(net "XDP_PCH_CPU_TCK0")
	)
	(segment
		(start 387.6421 -119.517668)
		(end 387.6421 -119.550434)
		(width 0.0889)
		(layer "In2.Cu")
		(net "XDP_PCH_CPU_TCK0")
	)
	(segment
		(start 415.89198 -132.876036)
		(end 419.513512 -132.876036)
		(width 0.089408)
		(layer "In2.Cu")
		(net "XDP_PCH_CPU_TCK0")
	)
	(segment
		(start 402.508466 -130.848608)
		(end 407.77287 -130.848608)
		(width 0.089408)
		(layer "In2.Cu")
		(net "XDP_PCH_CPU_TCK0")
	)
	(segment
		(start 446.7098 -147.682966)
		(end 451.573138 -152.546304)
		(width 0.089408)
		(layer "In2.Cu")
		(net "XDP_PCH_CPU_TCK0")
	)
	(segment
		(start 415.196782 -133.571234)
		(end 415.89198 -132.876036)
		(width 0.089408)
		(layer "In2.Cu")
		(net "XDP_PCH_CPU_TCK0")
	)
	(segment
		(start 407.77287 -130.848608)
		(end 409.48356 -132.559298)
		(width 0.089408)
		(layer "In2.Cu")
		(net "XDP_PCH_CPU_TCK0")
	)
	(segment
		(start 414.120838 -135.002778)
		(end 415.196782 -133.926834)
		(width 0.089408)
		(layer "In2.Cu")
		(net "XDP_PCH_CPU_TCK0")
	)
	(segment
		(start 451.573138 -152.546304)
		(end 454.005696 -152.546304)
		(width 0.089408)
		(layer "In2.Cu")
		(net "XDP_PCH_CPU_TCK0")
	)
	(arc
		(start 386.946648 -118.323868)
		(mid 387.092918 -118.463923)
		(end 387.1468 -118.659148)
		(width 0.0889)
		(layer "In2.Cu")
		(net "XDP_PCH_CPU_TCK0")
	)
	(arc
		(start 388.66064 -122.781822)
		(mid 388.637811 -122.881947)
		(end 388.6327 -122.984514)
		(width 0.0889)
		(layer "In2.Cu")
		(net "XDP_PCH_CPU_TCK0")
	)
	(arc
		(start 387.441948 -119.182134)
		(mid 387.585752 -119.323817)
		(end 387.6421 -119.517668)
		(width 0.0889)
		(layer "In2.Cu")
		(net "XDP_PCH_CPU_TCK0")
	)
	(arc
		(start 388.432548 -120.899174)
		(mid 388.576352 -121.040857)
		(end 388.6327 -121.234708)
		(width 0.0889)
		(layer "In2.Cu")
		(net "XDP_PCH_CPU_TCK0")
	)
	(arc
		(start 388.927848 -122.451114)
		(mid 388.763519 -122.59163)
		(end 388.66064 -122.781822)
		(width 0.0889)
		(layer "In2.Cu")
		(net "XDP_PCH_CPU_TCK0")
	)
	(arc
		(start 386.654294 -117.876828)
		(mid 386.747072 -118.135277)
		(end 386.946648 -118.323868)
		(width 0.089408)
		(layer "In2.Cu")
		(net "XDP_PCH_CPU_TCK0")
	)
	(arc
		(start 388.927848 -121.757694)
		(mid 389.128159 -122.104404)
		(end 388.927848 -122.451114)
		(width 0.0889)
		(layer "In2.Cu")
		(net "XDP_PCH_CPU_TCK0")
	)
	(arc
		(start 388.1374 -120.408954)
		(mid 388.221681 -120.692171)
		(end 388.432548 -120.899174)
		(width 0.0889)
		(layer "In2.Cu")
		(net "XDP_PCH_CPU_TCK0")
	)
	(arc
		(start 388.6327 -121.267474)
		(mid 388.716981 -121.550691)
		(end 388.927848 -121.757694)
		(width 0.0889)
		(layer "In2.Cu")
		(net "XDP_PCH_CPU_TCK0")
	)
	(arc
		(start 387.6421 -119.550434)
		(mid 387.726381 -119.833651)
		(end 387.937248 -120.040654)
		(width 0.0889)
		(layer "In2.Cu")
		(net "XDP_PCH_CPU_TCK0")
	)
	(arc
		(start 387.937248 -120.040654)
		(mid 388.081052 -120.182337)
		(end 388.1374 -120.376188)
		(width 0.0889)
		(layer "In2.Cu")
		(net "XDP_PCH_CPU_TCK0")
	)
	(arc
		(start 387.1468 -118.691914)
		(mid 387.231081 -118.975131)
		(end 387.441948 -119.182134)
		(width 0.0889)
		(layer "In2.Cu")
		(net "XDP_PCH_CPU_TCK0")
	)
	(arc
		(start 388.927848 -123.474734)
		(mid 389.071652 -123.616417)
		(end 389.128 -123.810268)
		(width 0.0889)
		(layer "In2.Cu")
		(net "XDP_PCH_CPU_TCK0")
	)
	(arc
		(start 389.128 -123.843034)
		(mid 389.172705 -124.058328)
		(end 389.29945 -124.238004)
		(width 0.0889)
		(layer "In2.Cu")
		(net "XDP_PCH_CPU_TCK0")
	)
	(arc
		(start 388.6327 -122.984514)
		(mid 388.716981 -123.267731)
		(end 388.927848 -123.474734)
		(width 0.0889)
		(layer "In2.Cu")
		(net "XDP_PCH_CPU_TCK0")
	)
	(segment
		(start 454.22566 -155.449524)
		(end 453.658732 -155.449524)
		(width 0.10795)
		(layer "F.Cu")
		(net "XDP_CPU_GTL_TCK_R2")
	)
	(segment
		(start 453.771 -157.607)
		(end 454.279 -157.607)
		(width 0.10795)
		(layer "F.Cu")
		(net "XDP_CPU_GTL_TCK_R2")
	)
	(segment
		(start 453.658732 -155.449524)
		(end 453.136 -155.972256)
		(width 0.10795)
		(layer "F.Cu")
		(net "XDP_CPU_GTL_TCK_R2")
	)
	(segment
		(start 453.136 -155.972256)
		(end 453.136 -156.972)
		(width 0.10795)
		(layer "F.Cu")
		(net "XDP_CPU_GTL_TCK_R2")
	)
	(segment
		(start 453.136 -156.972)
		(end 453.771 -157.607)
		(width 0.10795)
		(layer "F.Cu")
		(net "XDP_CPU_GTL_TCK_R2")
	)
	(via
		(at 454.22566 -155.449524)
		(size 0.508)
		(drill 0.254)
		(layers "F.Cu" "B.Cu")
		(net "XDP_CPU_GTL_TCK_R2")
	)
	(segment
		(start 453.899016 -155.449524)
		(end 454.22566 -155.449524)
		(width 0.10795)
		(layer "B.Cu")
		(net "XDP_CPU_GTL_TCK_R2")
	)
	(segment
		(start 453.5678 -155.118308)
		(end 453.899016 -155.449524)
		(width 0.10795)
		(layer "B.Cu")
		(net "XDP_CPU_GTL_TCK_R2")
	)
	(segment
		(start 453.5678 -154.5336)
		(end 453.5678 -155.118308)
		(width 0.10795)
		(layer "B.Cu")
		(net "XDP_CPU_GTL_TCK_R2")
	)
	(segment
		(start 462.980532 -139.719812)
		(end 464.712812 -139.719812)
		(width 0.10795)
		(layer "F.Cu")
		(net "TP_XDP_OBSDATA_A3")
	)
	(segment
		(start 464.712812 -139.719812)
		(end 465.2772 -140.2842)
		(width 0.10795)
		(layer "F.Cu")
		(net "TP_XDP_OBSDATA_A3")
	)
	(via
		(at 465.2772 -140.2842)
		(size 0.508)
		(drill 0.254)
		(layers "F.Cu" "B.Cu")
		(net "TP_XDP_OBSDATA_A3")
	)
	(segment
		(start 462.993994 -139.233402)
		(end 462.980532 -139.21994)
		(width 0.10795)
		(layer "F.Cu")
		(net "TP_XDP_OBSDATA_A2")
	)
	(segment
		(start 465.201 -139.192)
		(end 465.159598 -139.233402)
		(width 0.10795)
		(layer "F.Cu")
		(net "TP_XDP_OBSDATA_A2")
	)
	(segment
		(start 465.159598 -139.233402)
		(end 462.993994 -139.233402)
		(width 0.10795)
		(layer "F.Cu")
		(net "TP_XDP_OBSDATA_A2")
	)
	(via
		(at 463.9564 -139.573)
		(size 0.6604)
		(drill 0.3302)
		(layers "F.Cu" "B.Cu")
		(net "TP_XDP_OBSDATA_A2")
	)
	(via
		(at 465.201 -139.192)
		(size 0.508)
		(drill 0.254)
		(layers "F.Cu" "B.Cu")
		(net "TP_XDP_OBSDATA_A2")
	)
	(segment
		(start 463.9564 -139.573)
		(end 464.82 -139.573)
		(width 0.10795)
		(layer "B.Cu")
		(net "TP_XDP_OBSDATA_A2")
	)
	(segment
		(start 464.82 -139.573)
		(end 465.201 -139.192)
		(width 0.10795)
		(layer "B.Cu")
		(net "TP_XDP_OBSDATA_A2")
	)
	(segment
		(start 465.117942 -138.219942)
		(end 465.201 -138.303)
		(width 0.10795)
		(layer "F.Cu")
		(net "TP_XDP_OBSDATA_A1")
	)
	(segment
		(start 462.980532 -138.219942)
		(end 465.117942 -138.219942)
		(width 0.10795)
		(layer "F.Cu")
		(net "TP_XDP_OBSDATA_A1")
	)
	(via
		(at 465.201 -138.303)
		(size 0.508)
		(drill 0.254)
		(layers "F.Cu" "B.Cu")
		(net "TP_XDP_OBSDATA_A1")
	)
	(via
		(at 389.261604 -57.7088)
		(size 0.6604)
		(drill 0.3302)
		(layers "F.Cu" "B.Cu")
		(net "SPI_CLK_R1")
	)
	(segment
		(start 389.590026 -56.11368)
		(end 388.657846 -56.11368)
		(width 0.10795)
		(layer "B.Cu")
		(net "SPI_CLK_R1")
	)
	(segment
		(start 389.7122 -57.455054)
		(end 389.7122 -56.235854)
		(width 0.10795)
		(layer "B.Cu")
		(net "SPI_CLK_R1")
	)
	(segment
		(start 389.7122 -56.235854)
		(end 389.590026 -56.11368)
		(width 0.10795)
		(layer "B.Cu")
		(net "SPI_CLK_R1")
	)
	(segment
		(start 389.261604 -57.7088)
		(end 388.98195 -57.7088)
		(width 0.10795)
		(layer "B.Cu")
		(net "SPI_CLK_R1")
	)
	(segment
		(start 388.98195 -57.7088)
		(end 388.874 -57.81675)
		(width 0.10795)
		(layer "B.Cu")
		(net "SPI_CLK_R1")
	)
	(segment
		(start 389.261604 -57.7088)
		(end 389.458454 -57.7088)
		(width 0.10795)
		(layer "B.Cu")
		(net "SPI_CLK_R1")
	)
	(segment
		(start 388.874 -57.81675)
		(end 388.346188 -57.81675)
		(width 0.10795)
		(layer "B.Cu")
		(net "SPI_CLK_R1")
	)
	(segment
		(start 389.458454 -57.7088)
		(end 389.7122 -57.455054)
		(width 0.10795)
		(layer "B.Cu")
		(net "SPI_CLK_R1")
	)
	(segment
		(start 386.460746 -50.8508)
		(end 386.1054 -50.8508)
		(width 0.10795)
		(layer "F.Cu")
		(net "SPI_CLK_R0")
	)
	(segment
		(start 388.543546 -47.22368)
		(end 388.543546 -47.6758)
		(width 0.10795)
		(layer "F.Cu")
		(net "SPI_CLK_R0")
	)
	(segment
		(start 388.416546 -47.8028)
		(end 387.146546 -47.8028)
		(width 0.10795)
		(layer "F.Cu")
		(net "SPI_CLK_R0")
	)
	(segment
		(start 388.543546 -47.6758)
		(end 388.416546 -47.8028)
		(width 0.10795)
		(layer "F.Cu")
		(net "SPI_CLK_R0")
	)
	(segment
		(start 386.99313 -50.318416)
		(end 386.460746 -50.8508)
		(width 0.10795)
		(layer "F.Cu")
		(net "SPI_CLK_R0")
	)
	(segment
		(start 386.99313 -47.956216)
		(end 386.99313 -50.318416)
		(width 0.10795)
		(layer "F.Cu")
		(net "SPI_CLK_R0")
	)
	(segment
		(start 387.146546 -47.8028)
		(end 386.99313 -47.956216)
		(width 0.10795)
		(layer "F.Cu")
		(net "SPI_CLK_R0")
	)
	(segment
		(start 459.576678 -39.480998)
		(end 458.875892 -39.480998)
		(width 0.254)
		(layer "F.Cu")
		(net "VR_P1V15_BMC_STBY_FB")
	)
	(segment
		(start 460.463392 -40.012874)
		(end 460.108554 -40.012874)
		(width 0.254)
		(layer "F.Cu")
		(net "VR_P1V15_BMC_STBY_FB")
	)
	(segment
		(start 458.875892 -39.480998)
		(end 459.066392 -39.290498)
		(width 0.254)
		(layer "F.Cu")
		(net "VR_P1V15_BMC_STBY_FB")
	)
	(segment
		(start 459.69174 -39.59606)
		(end 459.576678 -39.480998)
		(width 0.254)
		(layer "F.Cu")
		(net "VR_P1V15_BMC_STBY_FB")
	)
	(segment
		(start 460.108554 -40.012874)
		(end 459.69174 -39.59606)
		(width 0.254)
		(layer "F.Cu")
		(net "VR_P1V15_BMC_STBY_FB")
	)
	(segment
		(start 459.69174 -39.587932)
		(end 459.69174 -39.59606)
		(width 0.254)
		(layer "F.Cu")
		(net "VR_P1V15_BMC_STBY_FB")
	)
	(segment
		(start 459.066392 -39.290498)
		(end 459.066392 -38.591998)
		(width 0.254)
		(layer "F.Cu")
		(net "VR_P1V15_BMC_STBY_FB")
	)
	(via
		(at 459.69174 -39.587932)
		(size 0.508)
		(drill 0.254)
		(layers "F.Cu" "B.Cu")
		(net "VR_P1V15_BMC_STBY_FB")
	)
	(segment
		(start 396.748 -76.962)
		(end 396.748 -77.343)
		(width 0.10795)
		(layer "F.Cu")
		(net "PWRGD_P12V_HSC_DLY_R")
	)
	(segment
		(start 397.750538 -73.367138)
		(end 397.750538 -73.145396)
		(width 0.10795)
		(layer "F.Cu")
		(net "PWRGD_P12V_HSC_DLY_R")
	)
	(segment
		(start 397.1925 -77.7875)
		(end 398.145 -77.7875)
		(width 0.10795)
		(layer "F.Cu")
		(net "PWRGD_P12V_HSC_DLY_R")
	)
	(segment
		(start 397.6243 -74.52106)
		(end 398.07642 -74.06894)
		(width 0.10795)
		(layer "F.Cu")
		(net "PWRGD_P12V_HSC_DLY_R")
	)
	(segment
		(start 398.07642 -74.06894)
		(end 398.07642 -73.69302)
		(width 0.10795)
		(layer "F.Cu")
		(net "PWRGD_P12V_HSC_DLY_R")
	)
	(segment
		(start 397.170656 -74.52106)
		(end 397.6243 -74.52106)
		(width 0.10795)
		(layer "F.Cu")
		(net "PWRGD_P12V_HSC_DLY_R")
	)
	(segment
		(start 397.010636 -74.68108)
		(end 397.170656 -74.52106)
		(width 0.10795)
		(layer "F.Cu")
		(net "PWRGD_P12V_HSC_DLY_R")
	)
	(segment
		(start 398.07642 -73.69302)
		(end 397.750538 -73.367138)
		(width 0.10795)
		(layer "F.Cu")
		(net "PWRGD_P12V_HSC_DLY_R")
	)
	(segment
		(start 396.748 -76.327)
		(end 397.010636 -76.064364)
		(width 0.10795)
		(layer "F.Cu")
		(net "PWRGD_P12V_HSC_DLY_R")
	)
	(segment
		(start 397.010636 -76.064364)
		(end 397.010636 -74.68108)
		(width 0.10795)
		(layer "F.Cu")
		(net "PWRGD_P12V_HSC_DLY_R")
	)
	(segment
		(start 396.748 -76.962)
		(end 396.748 -76.327)
		(width 0.10795)
		(layer "F.Cu")
		(net "PWRGD_P12V_HSC_DLY_R")
	)
	(segment
		(start 396.748 -77.343)
		(end 397.1925 -77.7875)
		(width 0.10795)
		(layer "F.Cu")
		(net "PWRGD_P12V_HSC_DLY_R")
	)
	(via
		(at 396.748 -76.962)
		(size 0.762)
		(drill 0.381)
		(layers "F.Cu" "B.Cu")
		(net "PWRGD_P12V_HSC_DLY_R")
	)
	(segment
		(start 462.878678 -6.909054)
		(end 462.878678 -7.789672)
		(width 0.10795)
		(layer "F.Cu")
		(net "RST_PCIE_RISER1_PERST_R_N")
	)
	(segment
		(start 462.238598 -6.268974)
		(end 462.878678 -6.909054)
		(width 0.10795)
		(layer "F.Cu")
		(net "RST_PCIE_RISER1_PERST_R_N")
	)
	(segment
		(start 462.238598 -5.5118)
		(end 462.238598 -6.268974)
		(width 0.10795)
		(layer "F.Cu")
		(net "RST_PCIE_RISER1_PERST_R_N")
	)
	(via
		(at 462.238598 -5.5118)
		(size 0.508)
		(drill 0.254)
		(layers "F.Cu" "B.Cu")
		(net "RST_PCIE_RISER1_PERST_R_N")
	)
	(segment
		(start 462.4578 -6.2738)
		(end 462.238598 -6.054598)
		(width 0.10795)
		(layer "B.Cu")
		(net "RST_PCIE_RISER1_PERST_R_N")
	)
	(segment
		(start 462.8896 -6.2738)
		(end 462.4578 -6.2738)
		(width 0.10795)
		(layer "B.Cu")
		(net "RST_PCIE_RISER1_PERST_R_N")
	)
	(segment
		(start 462.238598 -6.054598)
		(end 462.238598 -5.5118)
		(width 0.10795)
		(layer "B.Cu")
		(net "RST_PCIE_RISER1_PERST_R_N")
	)
	(segment
		(start 389.01751 -81.582768)
		(end 389.218678 -81.3816)
		(width 0.10795)
		(layer "F.Cu")
		(net "PWRGD_P12V_HSC_DLY")
	)
	(segment
		(start 387.827774 -82.536538)
		(end 388.765542 -82.536538)
		(width 0.10795)
		(layer "F.Cu")
		(net "PWRGD_P12V_HSC_DLY")
	)
	(segment
		(start 399.266156 -79.375)
		(end 398.567656 -78.6765)
		(width 0.10795)
		(layer "F.Cu")
		(net "PWRGD_P12V_HSC_DLY")
	)
	(segment
		(start 394.985494 -80.67548)
		(end 396.23492 -80.67548)
		(width 0.10795)
		(layer "F.Cu")
		(net "PWRGD_P12V_HSC_DLY")
	)
	(segment
		(start 398.67586 -66.41592)
		(end 399.256504 -65.835276)
		(width 0.10795)
		(layer "F.Cu")
		(net "PWRGD_P12V_HSC_DLY")
	)
	(segment
		(start 414.27781 -83.880198)
		(end 414.155636 -84.002372)
		(width 0.10795)
		(layer "F.Cu")
		(net "PWRGD_P12V_HSC_DLY")
	)
	(segment
		(start 397.74876 -78.6765)
		(end 398.145 -78.6765)
		(width 0.10795)
		(layer "F.Cu")
		(net "PWRGD_P12V_HSC_DLY")
	)
	(segment
		(start 414.27781 -83.4009)
		(end 414.27781 -83.880198)
		(width 0.10795)
		(layer "F.Cu")
		(net "PWRGD_P12V_HSC_DLY")
	)
	(segment
		(start 391.942828 -80.9498)
		(end 392.598148 -80.29448)
		(width 0.10795)
		(layer "F.Cu")
		(net "PWRGD_P12V_HSC_DLY")
	)
	(segment
		(start 397.366744 -79.012796)
		(end 397.412464 -79.012796)
		(width 0.10795)
		(layer "F.Cu")
		(net "PWRGD_P12V_HSC_DLY")
	)
	(segment
		(start 391.224008 -80.9498)
		(end 391.942828 -80.9498)
		(width 0.10795)
		(layer "F.Cu")
		(net "PWRGD_P12V_HSC_DLY")
	)
	(segment
		(start 398.567656 -78.6765)
		(end 398.145 -78.6765)
		(width 0.10795)
		(layer "F.Cu")
		(net "PWRGD_P12V_HSC_DLY")
	)
	(segment
		(start 394.06195 -79.751936)
		(end 394.985494 -80.67548)
		(width 0.10795)
		(layer "F.Cu")
		(net "PWRGD_P12V_HSC_DLY")
	)
	(segment
		(start 390.82599 -80.915002)
		(end 390.832594 -80.908398)
		(width 0.10795)
		(layer "F.Cu")
		(net "PWRGD_P12V_HSC_DLY")
	)
	(segment
		(start 393.48283 -78.851252)
		(end 394.06195 -79.430372)
		(width 0.10795)
		(layer "F.Cu")
		(net "PWRGD_P12V_HSC_DLY")
	)
	(segment
		(start 394.8176 -64.8462)
		(end 395.5796 -64.8462)
		(width 0.10795)
		(layer "F.Cu")
		(net "PWRGD_P12V_HSC_DLY")
	)
	(segment
		(start 396.23492 -79.45374)
		(end 396.673324 -79.015336)
		(width 0.10795)
		(layer "F.Cu")
		(net "PWRGD_P12V_HSC_DLY")
	)
	(segment
		(start 392.937746 -78.851252)
		(end 393.48283 -78.851252)
		(width 0.10795)
		(layer "F.Cu")
		(net "PWRGD_P12V_HSC_DLY")
	)
	(segment
		(start 396.494 -65.7606)
		(end 396.494 -66.1416)
		(width 0.10795)
		(layer "F.Cu")
		(net "PWRGD_P12V_HSC_DLY")
	)
	(segment
		(start 399.256504 -65.835276)
		(end 399.256504 -64.9732)
		(width 0.10795)
		(layer "F.Cu")
		(net "PWRGD_P12V_HSC_DLY")
	)
	(segment
		(start 397.412464 -79.012796)
		(end 397.74876 -78.6765)
		(width 0.10795)
		(layer "F.Cu")
		(net "PWRGD_P12V_HSC_DLY")
	)
	(segment
		(start 387.140704 -83.223608)
		(end 387.827774 -82.536538)
		(width 0.10795)
		(layer "F.Cu")
		(net "PWRGD_P12V_HSC_DLY")
	)
	(segment
		(start 391.182606 -80.908398)
		(end 391.224008 -80.9498)
		(width 0.10795)
		(layer "F.Cu")
		(net "PWRGD_P12V_HSC_DLY")
	)
	(segment
		(start 397.364458 -79.015082)
		(end 397.366744 -79.012796)
		(width 0.10795)
		(layer "F.Cu")
		(net "PWRGD_P12V_HSC_DLY")
	)
	(segment
		(start 390.832594 -80.908398)
		(end 391.182606 -80.908398)
		(width 0.10795)
		(layer "F.Cu")
		(net "PWRGD_P12V_HSC_DLY")
	)
	(segment
		(start 396.494 -66.1416)
		(end 396.76832 -66.41592)
		(width 0.10795)
		(layer "F.Cu")
		(net "PWRGD_P12V_HSC_DLY")
	)
	(segment
		(start 396.76832 -66.41592)
		(end 398.67586 -66.41592)
		(width 0.10795)
		(layer "F.Cu")
		(net "PWRGD_P12V_HSC_DLY")
	)
	(segment
		(start 397.364204 -79.015336)
		(end 397.364458 -79.015082)
		(width 0.10795)
		(layer "F.Cu")
		(net "PWRGD_P12V_HSC_DLY")
	)
	(segment
		(start 390.815068 -80.915002)
		(end 390.82599 -80.915002)
		(width 0.10795)
		(layer "F.Cu")
		(net "PWRGD_P12V_HSC_DLY")
	)
	(segment
		(start 390.34847 -81.3816)
		(end 390.815068 -80.915002)
		(width 0.10795)
		(layer "F.Cu")
		(net "PWRGD_P12V_HSC_DLY")
	)
	(segment
		(start 392.598148 -79.19085)
		(end 392.937746 -78.851252)
		(width 0.10795)
		(layer "F.Cu")
		(net "PWRGD_P12V_HSC_DLY")
	)
	(segment
		(start 399.542 -79.375)
		(end 399.266156 -79.375)
		(width 0.10795)
		(layer "F.Cu")
		(net "PWRGD_P12V_HSC_DLY")
	)
	(segment
		(start 392.598148 -80.29448)
		(end 392.598148 -79.19085)
		(width 0.10795)
		(layer "F.Cu")
		(net "PWRGD_P12V_HSC_DLY")
	)
	(segment
		(start 414.155636 -84.002372)
		(end 414.155636 -85.494876)
		(width 0.10795)
		(layer "F.Cu")
		(net "PWRGD_P12V_HSC_DLY")
	)
	(segment
		(start 386.464302 -83.223608)
		(end 387.140704 -83.223608)
		(width 0.10795)
		(layer "F.Cu")
		(net "PWRGD_P12V_HSC_DLY")
	)
	(segment
		(start 388.765542 -82.536538)
		(end 389.01751 -82.28457)
		(width 0.10795)
		(layer "F.Cu")
		(net "PWRGD_P12V_HSC_DLY")
	)
	(segment
		(start 389.218678 -81.3816)
		(end 390.34847 -81.3816)
		(width 0.10795)
		(layer "F.Cu")
		(net "PWRGD_P12V_HSC_DLY")
	)
	(segment
		(start 395.5796 -64.8462)
		(end 396.494 -65.7606)
		(width 0.10795)
		(layer "F.Cu")
		(net "PWRGD_P12V_HSC_DLY")
	)
	(segment
		(start 396.23492 -80.67548)
		(end 396.23492 -79.45374)
		(width 0.10795)
		(layer "F.Cu")
		(net "PWRGD_P12V_HSC_DLY")
	)
	(segment
		(start 389.01751 -82.28457)
		(end 389.01751 -81.582768)
		(width 0.10795)
		(layer "F.Cu")
		(net "PWRGD_P12V_HSC_DLY")
	)
	(segment
		(start 396.673324 -79.015336)
		(end 397.364204 -79.015336)
		(width 0.10795)
		(layer "F.Cu")
		(net "PWRGD_P12V_HSC_DLY")
	)
	(segment
		(start 394.06195 -79.430372)
		(end 394.06195 -79.751936)
		(width 0.10795)
		(layer "F.Cu")
		(net "PWRGD_P12V_HSC_DLY")
	)
	(via
		(at 397.364458 -79.015082)
		(size 0.508)
		(drill 0.254)
		(layers "F.Cu" "B.Cu")
		(net "PWRGD_P12V_HSC_DLY")
	)
	(via
		(at 396.23492 -80.67548)
		(size 0.762)
		(drill 0.381)
		(layers "F.Cu" "B.Cu")
		(net "PWRGD_P12V_HSC_DLY")
	)
	(via
		(at 414.27781 -83.4009)
		(size 0.508)
		(drill 0.254)
		(layers "F.Cu" "B.Cu")
		(net "PWRGD_P12V_HSC_DLY")
	)
	(via
		(at 399.256504 -64.9732)
		(size 0.508)
		(drill 0.254)
		(layers "F.Cu" "B.Cu")
		(net "PWRGD_P12V_HSC_DLY")
	)
	(segment
		(start 404.94966 -80.462882)
		(end 404.182326 -79.695548)
		(width 0.10795)
		(layer "B.Cu")
		(net "PWRGD_P12V_HSC_DLY")
	)
	(segment
		(start 406.491694 -81.731104)
		(end 405.223472 -80.462882)
		(width 0.10795)
		(layer "B.Cu")
		(net "PWRGD_P12V_HSC_DLY")
	)
	(segment
		(start 402.895562 -80.86598)
		(end 402.453094 -80.86598)
		(width 0.10795)
		(layer "B.Cu")
		(net "PWRGD_P12V_HSC_DLY")
	)
	(segment
		(start 414.27781 -83.033616)
		(end 413.617156 -82.372962)
		(width 0.10795)
		(layer "B.Cu")
		(net "PWRGD_P12V_HSC_DLY")
	)
	(segment
		(start 403.491446 -80.270096)
		(end 402.895562 -80.86598)
		(width 0.10795)
		(layer "B.Cu")
		(net "PWRGD_P12V_HSC_DLY")
	)
	(segment
		(start 405.223472 -80.462882)
		(end 404.94966 -80.462882)
		(width 0.10795)
		(layer "B.Cu")
		(net "PWRGD_P12V_HSC_DLY")
	)
	(segment
		(start 402.453094 -80.86598)
		(end 401.800314 -80.2132)
		(width 0.10795)
		(layer "B.Cu")
		(net "PWRGD_P12V_HSC_DLY")
	)
	(segment
		(start 397.43634 -78.9432)
		(end 397.364458 -79.015082)
		(width 0.10795)
		(layer "B.Cu")
		(net "PWRGD_P12V_HSC_DLY")
	)
	(segment
		(start 398.6276 -78.9432)
		(end 397.43634 -78.9432)
		(width 0.10795)
		(layer "B.Cu")
		(net "PWRGD_P12V_HSC_DLY")
	)
	(segment
		(start 404.182326 -79.695548)
		(end 403.738842 -79.695548)
		(width 0.10795)
		(layer "B.Cu")
		(net "PWRGD_P12V_HSC_DLY")
	)
	(segment
		(start 407.78811 -81.731104)
		(end 406.491694 -81.731104)
		(width 0.10795)
		(layer "B.Cu")
		(net "PWRGD_P12V_HSC_DLY")
	)
	(segment
		(start 414.27781 -83.4009)
		(end 414.27781 -83.033616)
		(width 0.10795)
		(layer "B.Cu")
		(net "PWRGD_P12V_HSC_DLY")
	)
	(segment
		(start 403.738842 -79.695548)
		(end 403.491446 -79.942944)
		(width 0.10795)
		(layer "B.Cu")
		(net "PWRGD_P12V_HSC_DLY")
	)
	(segment
		(start 403.491446 -79.942944)
		(end 403.491446 -80.270096)
		(width 0.10795)
		(layer "B.Cu")
		(net "PWRGD_P12V_HSC_DLY")
	)
	(segment
		(start 408.429968 -82.372962)
		(end 407.78811 -81.731104)
		(width 0.10795)
		(layer "B.Cu")
		(net "PWRGD_P12V_HSC_DLY")
	)
	(segment
		(start 413.617156 -82.372962)
		(end 408.429968 -82.372962)
		(width 0.10795)
		(layer "B.Cu")
		(net "PWRGD_P12V_HSC_DLY")
	)
	(segment
		(start 399.8976 -80.2132)
		(end 398.6276 -78.9432)
		(width 0.10795)
		(layer "B.Cu")
		(net "PWRGD_P12V_HSC_DLY")
	)
	(segment
		(start 401.800314 -80.2132)
		(end 399.8976 -80.2132)
		(width 0.10795)
		(layer "B.Cu")
		(net "PWRGD_P12V_HSC_DLY")
	)
	(segment
		(start 395.196568 -66.34988)
		(end 396.871952 -64.674496)
		(width 0.089408)
		(layer "In2.Cu")
		(net "PWRGD_P12V_HSC_DLY")
	)
	(segment
		(start 395.196568 -70.832472)
		(end 395.196568 -66.34988)
		(width 0.089408)
		(layer "In2.Cu")
		(net "PWRGD_P12V_HSC_DLY")
	)
	(segment
		(start 397.364458 -79.015082)
		(end 397.97228 -78.40726)
		(width 0.089408)
		(layer "In2.Cu")
		(net "PWRGD_P12V_HSC_DLY")
	)
	(segment
		(start 396.871952 -64.674496)
		(end 398.608296 -64.674496)
		(width 0.089408)
		(layer "In2.Cu")
		(net "PWRGD_P12V_HSC_DLY")
	)
	(segment
		(start 397.97228 -78.40726)
		(end 397.97228 -73.608184)
		(width 0.089408)
		(layer "In2.Cu")
		(net "PWRGD_P12V_HSC_DLY")
	)
	(segment
		(start 397.97228 -73.608184)
		(end 395.196568 -70.832472)
		(width 0.089408)
		(layer "In2.Cu")
		(net "PWRGD_P12V_HSC_DLY")
	)
	(segment
		(start 398.907 -64.9732)
		(end 399.256504 -64.9732)
		(width 0.089408)
		(layer "In2.Cu")
		(net "PWRGD_P12V_HSC_DLY")
	)
	(segment
		(start 398.608296 -64.674496)
		(end 398.907 -64.9732)
		(width 0.089408)
		(layer "In2.Cu")
		(net "PWRGD_P12V_HSC_DLY")
	)
	(segment
		(start 461.278478 -8.678418)
		(end 461.278478 -7.789672)
		(width 0.127)
		(layer "F.Cu")
		(net "CLK_100M_PCH_SLOTX24_S5_DP")
	)
	(segment
		(start 461.075278 -9.1059)
		(end 461.075278 -8.881618)
		(width 0.127)
		(layer "F.Cu")
		(net "CLK_100M_PCH_SLOTX24_S5_DP")
	)
	(segment
		(start 378.82195 -107.27944)
		(end 379.31725 -107.049316)
		(width 0.127)
		(layer "F.Cu")
		(net "CLK_100M_PCH_SLOTX24_S5_DP")
	)
	(segment
		(start 461.075278 -8.881618)
		(end 461.278478 -8.678418)
		(width 0.127)
		(layer "F.Cu")
		(net "CLK_100M_PCH_SLOTX24_S5_DP")
	)
	(segment
		(start 461.607408 -9.374886)
		(end 461.344264 -9.374886)
		(width 0.127)
		(layer "F.Cu")
		(net "CLK_100M_PCH_SLOTX24_S5_DP")
	)
	(segment
		(start 461.344264 -9.374886)
		(end 461.075278 -9.1059)
		(width 0.127)
		(layer "F.Cu")
		(net "CLK_100M_PCH_SLOTX24_S5_DP")
	)
	(via
		(at 461.607408 -9.374886)
		(size 0.508)
		(drill 0.254)
		(layers "F.Cu" "B.Cu")
		(net "CLK_100M_PCH_SLOTX24_S5_DP")
	)
	(via
		(at 379.31725 -107.049316)
		(size 0.508)
		(drill 0.254)
		(layers "F.Cu" "B.Cu")
		(net "CLK_100M_PCH_SLOTX24_S5_DP")
	)
	(segment
		(start 405.538178 -25.578816)
		(end 403.17166 -26.369264)
		(width 0.1143)
		(layer "In2.Cu")
		(net "CLK_100M_PCH_SLOTX24_S5_DP")
	)
	(segment
		(start 414.195768 -23.2029)
		(end 413.358584 -24.040084)
		(width 0.1143)
		(layer "In2.Cu")
		(net "CLK_100M_PCH_SLOTX24_S5_DP")
	)
	(segment
		(start 408.664918 -25.943306)
		(end 408.231594 -25.943306)
		(width 0.1143)
		(layer "In2.Cu")
		(net "CLK_100M_PCH_SLOTX24_S5_DP")
	)
	(segment
		(start 431.404268 -18.22831)
		(end 430.247552 -17.992852)
		(width 0.1143)
		(layer "In2.Cu")
		(net "CLK_100M_PCH_SLOTX24_S5_DP")
	)
	(segment
		(start 397.104616 -25.154128)
		(end 396.849346 -24.925274)
		(width 0.1143)
		(layer "In2.Cu")
		(net "CLK_100M_PCH_SLOTX24_S5_DP")
	)
	(segment
		(start 371.534944 -95.51543)
		(end 371.534944 -98.323908)
		(width 0.1143)
		(layer "In2.Cu")
		(net "CLK_100M_PCH_SLOTX24_S5_DP")
	)
	(segment
		(start 379.89764 -26.880566)
		(end 378.448824 -25.809702)
		(width 0.1143)
		(layer "In2.Cu")
		(net "CLK_100M_PCH_SLOTX24_S5_DP")
	)
	(segment
		(start 389.764524 -24.262334)
		(end 389.695944 -24.039068)
		(width 0.1143)
		(layer "In2.Cu")
		(net "CLK_100M_PCH_SLOTX24_S5_DP")
	)
	(segment
		(start 372.646956 -42.292016)
		(end 371.754908 -46.75251)
		(width 0.1143)
		(layer "In2.Cu")
		(net "CLK_100M_PCH_SLOTX24_S5_DP")
	)
	(segment
		(start 394.756894 -23.485348)
		(end 394.755624 -23.485602)
		(width 0.1143)
		(layer "In2.Cu")
		(net "CLK_100M_PCH_SLOTX24_S5_DP")
	)
	(segment
		(start 375.513092 -31.533592)
		(end 374.836436 -34.770568)
		(width 0.1143)
		(layer "In2.Cu")
		(net "CLK_100M_PCH_SLOTX24_S5_DP")
	)
	(segment
		(start 439.82513 -17.229074)
		(end 439.77687 -17.19707)
		(width 0.1143)
		(layer "In2.Cu")
		(net "CLK_100M_PCH_SLOTX24_S5_DP")
	)
	(segment
		(start 419.136322 -22.017482)
		(end 418.810948 -22.12594)
		(width 0.1143)
		(layer "In2.Cu")
		(net "CLK_100M_PCH_SLOTX24_S5_DP")
	)
	(segment
		(start 396.34795 -24.476202)
		(end 395.492224 -23.709376)
		(width 0.1143)
		(layer "In2.Cu")
		(net "CLK_100M_PCH_SLOTX24_S5_DP")
	)
	(segment
		(start 419.56609 -21.700236)
		(end 419.240716 -21.808694)
		(width 0.1143)
		(layer "In2.Cu")
		(net "CLK_100M_PCH_SLOTX24_S5_DP")
	)
	(segment
		(start 372.193058 -40.077898)
		(end 372.646956 -42.292016)
		(width 0.1143)
		(layer "In2.Cu")
		(net "CLK_100M_PCH_SLOTX24_S5_DP")
	)
	(segment
		(start 407.222452 -25.578816)
		(end 405.538178 -25.578816)
		(width 0.1143)
		(layer "In2.Cu")
		(net "CLK_100M_PCH_SLOTX24_S5_DP")
	)
	(segment
		(start 394.067792 -23.644352)
		(end 393.085828 -24.25827)
		(width 0.1143)
		(layer "In2.Cu")
		(net "CLK_100M_PCH_SLOTX24_S5_DP")
	)
	(segment
		(start 450.01307 -12.826746)
		(end 444.51778 -16.490188)
		(width 0.1143)
		(layer "In2.Cu")
		(net "CLK_100M_PCH_SLOTX24_S5_DP")
	)
	(segment
		(start 450.9262 -12.64412)
		(end 450.01307 -12.826746)
		(width 0.1143)
		(layer "In2.Cu")
		(net "CLK_100M_PCH_SLOTX24_S5_DP")
	)
	(segment
		(start 454.311004 -14.253718)
		(end 452.312532 -12.921488)
		(width 0.1143)
		(layer "In2.Cu")
		(net "CLK_100M_PCH_SLOTX24_S5_DP")
	)
	(segment
		(start 413.358584 -24.040084)
		(end 411.88767 -24.755856)
		(width 0.1143)
		(layer "In2.Cu")
		(net "CLK_100M_PCH_SLOTX24_S5_DP")
	)
	(segment
		(start 435.090316 -17.47901)
		(end 431.404268 -18.22831)
		(width 0.1143)
		(layer "In2.Cu")
		(net "CLK_100M_PCH_SLOTX24_S5_DP")
	)
	(segment
		(start 378.826268 -106.73334)
		(end 378.870464 -106.803444)
		(width 0.0889)
		(layer "In2.Cu")
		(net "CLK_100M_PCH_SLOTX24_S5_DP")
	)
	(segment
		(start 385.407154 -25.094438)
		(end 384.292856 -25.721818)
		(width 0.1143)
		(layer "In2.Cu")
		(net "CLK_100M_PCH_SLOTX24_S5_DP")
	)
	(segment
		(start 421.253666 -20.49272)
		(end 420.819834 -20.77974)
		(width 0.1143)
		(layer "In2.Cu")
		(net "CLK_100M_PCH_SLOTX24_S5_DP")
	)
	(segment
		(start 376.758454 -105.758234)
		(end 377.591574 -106.591354)
		(width 0.0889)
		(layer "In2.Cu")
		(net "CLK_100M_PCH_SLOTX24_S5_DP")
	)
	(segment
		(start 366.09655 -85.892386)
		(end 366.781842 -89.32037)
		(width 0.1143)
		(layer "In2.Cu")
		(net "CLK_100M_PCH_SLOTX24_S5_DP")
	)
	(segment
		(start 364.59922 -72.656446)
		(end 365.391446 -76.393294)
		(width 0.1143)
		(layer "In2.Cu")
		(net "CLK_100M_PCH_SLOTX24_S5_DP")
	)
	(segment
		(start 365.3917 -79.89443)
		(end 366.343692 -84.656676)
		(width 0.1143)
		(layer "In2.Cu")
		(net "CLK_100M_PCH_SLOTX24_S5_DP")
	)
	(segment
		(start 377.591574 -106.591354)
		(end 377.83135 -106.591354)
		(width 0.0889)
		(layer "In2.Cu")
		(net "CLK_100M_PCH_SLOTX24_S5_DP")
	)
	(segment
		(start 369.55222 -60.003182)
		(end 368.463068 -61.618114)
		(width 0.1143)
		(layer "In2.Cu")
		(net "CLK_100M_PCH_SLOTX24_S5_DP")
	)
	(segment
		(start 378.128784 -25.73782)
		(end 376.417332 -26.298906)
		(width 0.1143)
		(layer "In2.Cu")
		(net "CLK_100M_PCH_SLOTX24_S5_DP")
	)
	(segment
		(start 366.77473 -65.205102)
		(end 366.444276 -66.6623)
		(width 0.1143)
		(layer "In2.Cu")
		(net "CLK_100M_PCH_SLOTX24_S5_DP")
	)
	(segment
		(start 366.781842 -89.32037)
		(end 367.836704 -90.023442)
		(width 0.1143)
		(layer "In2.Cu")
		(net "CLK_100M_PCH_SLOTX24_S5_DP")
	)
	(segment
		(start 439.77687 -17.19707)
		(end 439.777124 -17.19707)
		(width 0.1143)
		(layer "In2.Cu")
		(net "CLK_100M_PCH_SLOTX24_S5_DP")
	)
	(segment
		(start 403.17166 -26.369264)
		(end 401.154392 -26.369264)
		(width 0.1143)
		(layer "In2.Cu")
		(net "CLK_100M_PCH_SLOTX24_S5_DP")
	)
	(segment
		(start 415.058098 -23.2029)
		(end 414.195768 -23.2029)
		(width 0.1143)
		(layer "In2.Cu")
		(net "CLK_100M_PCH_SLOTX24_S5_DP")
	)
	(segment
		(start 408.231594 -25.943306)
		(end 407.222452 -25.578816)
		(width 0.1143)
		(layer "In2.Cu")
		(net "CLK_100M_PCH_SLOTX24_S5_DP")
	)
	(segment
		(start 427.975014 -19.34718)
		(end 427.397418 -19.72945)
		(width 0.1143)
		(layer "In2.Cu")
		(net "CLK_100M_PCH_SLOTX24_S5_DP")
	)
	(segment
		(start 381.7366 -26.930604)
		(end 380.97079 -27.103578)
		(width 0.1143)
		(layer "In2.Cu")
		(net "CLK_100M_PCH_SLOTX24_S5_DP")
	)
	(segment
		(start 386.466588 -23.459694)
		(end 385.407154 -25.094438)
		(width 0.1143)
		(layer "In2.Cu")
		(net "CLK_100M_PCH_SLOTX24_S5_DP")
	)
	(segment
		(start 399.734532 -25.748234)
		(end 398.60347 -25.748234)
		(width 0.1143)
		(layer "In2.Cu")
		(net "CLK_100M_PCH_SLOTX24_S5_DP")
	)
	(segment
		(start 459.885288 -12.798298)
		(end 455.144124 -14.42085)
		(width 0.1143)
		(layer "In2.Cu")
		(net "CLK_100M_PCH_SLOTX24_S5_DP")
	)
	(segment
		(start 425.970954 -20.019772)
		(end 425.005754 -19.823176)
		(width 0.1143)
		(layer "In2.Cu")
		(net "CLK_100M_PCH_SLOTX24_S5_DP")
	)
	(segment
		(start 371.889782 -105.03916)
		(end 372.558818 -105.707434)
		(width 0.1143)
		(layer "In2.Cu")
		(net "CLK_100M_PCH_SLOTX24_S5_DP")
	)
	(segment
		(start 372.987062 -37.179504)
		(end 372.193058 -40.077898)
		(width 0.1143)
		(layer "In2.Cu")
		(net "CLK_100M_PCH_SLOTX24_S5_DP")
	)
	(segment
		(start 380.97079 -27.103578)
		(end 379.89764 -26.880566)
		(width 0.1143)
		(layer "In2.Cu")
		(net "CLK_100M_PCH_SLOTX24_S5_DP")
	)
	(segment
		(start 411.88767 -24.755856)
		(end 409.827222 -25.167844)
		(width 0.1143)
		(layer "In2.Cu")
		(net "CLK_100M_PCH_SLOTX24_S5_DP")
	)
	(segment
		(start 396.616174 -24.937974)
		(end 396.36065 -24.709374)
		(width 0.1143)
		(layer "In2.Cu")
		(net "CLK_100M_PCH_SLOTX24_S5_DP")
	)
	(segment
		(start 389.695944 -24.039068)
		(end 387.882638 -23.07717)
		(width 0.1143)
		(layer "In2.Cu")
		(net "CLK_100M_PCH_SLOTX24_S5_DP")
	)
	(segment
		(start 396.36065 -24.709374)
		(end 396.34795 -24.476202)
		(width 0.1143)
		(layer "In2.Cu")
		(net "CLK_100M_PCH_SLOTX24_S5_DP")
	)
	(segment
		(start 461.126078 -10.963148)
		(end 461.10271 -10.986516)
		(width 0.1143)
		(layer "In2.Cu")
		(net "CLK_100M_PCH_SLOTX24_S5_DP")
	)
	(segment
		(start 409.827222 -25.167844)
		(end 408.664918 -25.943306)
		(width 0.1143)
		(layer "In2.Cu")
		(net "CLK_100M_PCH_SLOTX24_S5_DP")
	)
	(segment
		(start 376.417332 -26.298906)
		(end 375.79554 -27.195526)
		(width 0.1143)
		(layer "In2.Cu")
		(net "CLK_100M_PCH_SLOTX24_S5_DP")
	)
	(segment
		(start 374.922542 -105.707434)
		(end 374.94464 -105.707434)
		(width 0.0889)
		(layer "In2.Cu")
		(net "CLK_100M_PCH_SLOTX24_S5_DP")
	)
	(segment
		(start 371.33149 -99.093274)
		(end 371.33149 -100.36175)
		(width 0.1143)
		(layer "In2.Cu")
		(net "CLK_100M_PCH_SLOTX24_S5_DP")
	)
	(segment
		(start 365.391446 -76.393294)
		(end 365.3917 -76.393294)
		(width 0.1143)
		(layer "In2.Cu")
		(net "CLK_100M_PCH_SLOTX24_S5_DP")
	)
	(segment
		(start 443.370716 -17.568418)
		(end 442.778388 -17.820132)
		(width 0.1143)
		(layer "In2.Cu")
		(net "CLK_100M_PCH_SLOTX24_S5_DP")
	)
	(segment
		(start 420.81958 -20.779486)
		(end 419.56609 -21.700236)
		(width 0.1143)
		(layer "In2.Cu")
		(net "CLK_100M_PCH_SLOTX24_S5_DP")
	)
	(segment
		(start 368.803936 -91.426284)
		(end 371.182138 -93.80474)
		(width 0.1143)
		(layer "In2.Cu")
		(net "CLK_100M_PCH_SLOTX24_S5_DP")
	)
	(segment
		(start 378.448824 -25.809702)
		(end 378.128784 -25.73782)
		(width 0.1143)
		(layer "In2.Cu")
		(net "CLK_100M_PCH_SLOTX24_S5_DP")
	)
	(segment
		(start 374.94464 -105.707434)
		(end 374.99544 -105.758234)
		(width 0.0889)
		(layer "In2.Cu")
		(net "CLK_100M_PCH_SLOTX24_S5_DP")
	)
	(segment
		(start 368.463068 -61.618114)
		(end 368.276632 -62.578234)
		(width 0.1143)
		(layer "In2.Cu")
		(net "CLK_100M_PCH_SLOTX24_S5_DP")
	)
	(segment
		(start 390.59358 -24.515318)
		(end 390.290558 -24.354536)
		(width 0.1143)
		(layer "In2.Cu")
		(net "CLK_100M_PCH_SLOTX24_S5_DP")
	)
	(segment
		(start 424.565318 -19.912838)
		(end 423.622978 -20.104608)
		(width 0.1143)
		(layer "In2.Cu")
		(net "CLK_100M_PCH_SLOTX24_S5_DP")
	)
	(segment
		(start 396.849346 -24.925274)
		(end 396.616174 -24.937974)
		(width 0.1143)
		(layer "In2.Cu")
		(net "CLK_100M_PCH_SLOTX24_S5_DP")
	)
	(segment
		(start 418.810948 -22.12594)
		(end 418.60216 -22.021546)
		(width 0.1143)
		(layer "In2.Cu")
		(net "CLK_100M_PCH_SLOTX24_S5_DP")
	)
	(segment
		(start 368.276632 -62.578234)
		(end 367.852198 -63.207646)
		(width 0.1143)
		(layer "In2.Cu")
		(net "CLK_100M_PCH_SLOTX24_S5_DP")
	)
	(segment
		(start 365.75746 -66.954908)
		(end 364.640876 -68.369434)
		(width 0.1143)
		(layer "In2.Cu")
		(net "CLK_100M_PCH_SLOTX24_S5_DP")
	)
	(segment
		(start 390.290558 -24.354536)
		(end 390.067546 -24.423116)
		(width 0.1143)
		(layer "In2.Cu")
		(net "CLK_100M_PCH_SLOTX24_S5_DP")
	)
	(segment
		(start 375.602754 -27.829764)
		(end 375.712482 -28.035758)
		(width 0.1143)
		(layer "In2.Cu")
		(net "CLK_100M_PCH_SLOTX24_S5_DP")
	)
	(segment
		(start 436.475886 -16.561816)
		(end 435.090316 -17.47901)
		(width 0.1143)
		(layer "In2.Cu")
		(net "CLK_100M_PCH_SLOTX24_S5_DP")
	)
	(segment
		(start 371.33149 -100.36175)
		(end 371.122194 -101.348032)
		(width 0.1143)
		(layer "In2.Cu")
		(net "CLK_100M_PCH_SLOTX24_S5_DP")
	)
	(segment
		(start 418.60216 -22.021546)
		(end 415.058098 -23.2029)
		(width 0.1143)
		(layer "In2.Cu")
		(net "CLK_100M_PCH_SLOTX24_S5_DP")
	)
	(segment
		(start 419.240716 -21.808694)
		(end 419.136322 -22.017482)
		(width 0.1143)
		(layer "In2.Cu")
		(net "CLK_100M_PCH_SLOTX24_S5_DP")
	)
	(segment
		(start 383.133346 -25.977342)
		(end 381.7366 -26.930604)
		(width 0.1143)
		(layer "In2.Cu")
		(net "CLK_100M_PCH_SLOTX24_S5_DP")
	)
	(segment
		(start 442.778388 -17.820132)
		(end 439.82513 -17.229074)
		(width 0.1143)
		(layer "In2.Cu")
		(net "CLK_100M_PCH_SLOTX24_S5_DP")
	)
	(segment
		(start 367.068862 -64.010794)
		(end 367.179098 -64.5668)
		(width 0.1143)
		(layer "In2.Cu")
		(net "CLK_100M_PCH_SLOTX24_S5_DP")
	)
	(segment
		(start 420.819834 -20.77974)
		(end 420.81958 -20.779486)
		(width 0.1143)
		(layer "In2.Cu")
		(net "CLK_100M_PCH_SLOTX24_S5_DP")
	)
	(segment
		(start 394.755624 -23.485602)
		(end 394.067792 -23.644352)
		(width 0.1143)
		(layer "In2.Cu")
		(net "CLK_100M_PCH_SLOTX24_S5_DP")
	)
	(segment
		(start 372.558818 -105.707434)
		(end 374.922542 -105.707434)
		(width 0.1143)
		(layer "In2.Cu")
		(net "CLK_100M_PCH_SLOTX24_S5_DP")
	)
	(segment
		(start 384.292856 -25.721818)
		(end 383.133346 -25.977342)
		(width 0.1143)
		(layer "In2.Cu")
		(net "CLK_100M_PCH_SLOTX24_S5_DP")
	)
	(segment
		(start 423.075608 -20.121626)
		(end 421.253666 -20.49272)
		(width 0.1143)
		(layer "In2.Cu")
		(net "CLK_100M_PCH_SLOTX24_S5_DP")
	)
	(segment
		(start 423.622978 -20.104608)
		(end 423.307764 -20.168616)
		(width 0.1143)
		(layer "In2.Cu")
		(net "CLK_100M_PCH_SLOTX24_S5_DP")
	)
	(segment
		(start 375.61266 -28.363926)
		(end 375.406666 -28.473654)
		(width 0.1143)
		(layer "In2.Cu")
		(net "CLK_100M_PCH_SLOTX24_S5_DP")
	)
	(segment
		(start 390.067546 -24.423116)
		(end 389.764524 -24.262334)
		(width 0.1143)
		(layer "In2.Cu")
		(net "CLK_100M_PCH_SLOTX24_S5_DP")
	)
	(segment
		(start 461.607408 -9.374886)
		(end 461.126078 -9.856216)
		(width 0.1143)
		(layer "In2.Cu")
		(net "CLK_100M_PCH_SLOTX24_S5_DP")
	)
	(segment
		(start 367.240312 -63.620396)
		(end 367.068862 -64.010794)
		(width 0.1143)
		(layer "In2.Cu")
		(net "CLK_100M_PCH_SLOTX24_S5_DP")
	)
	(segment
		(start 437.622188 -16.32966)
		(end 436.475886 -16.561816)
		(width 0.1143)
		(layer "In2.Cu")
		(net "CLK_100M_PCH_SLOTX24_S5_DP")
	)
	(segment
		(start 366.444276 -66.6623)
		(end 365.75746 -66.954908)
		(width 0.1143)
		(layer "In2.Cu")
		(net "CLK_100M_PCH_SLOTX24_S5_DP")
	)
	(segment
		(start 372.002558 -47.993046)
		(end 369.55222 -60.003182)
		(width 0.1143)
		(layer "In2.Cu")
		(net "CLK_100M_PCH_SLOTX24_S5_DP")
	)
	(segment
		(start 375.086372 -29.526992)
		(end 375.513092 -31.533592)
		(width 0.1143)
		(layer "In2.Cu")
		(net "CLK_100M_PCH_SLOTX24_S5_DP")
	)
	(segment
		(start 375.406666 -28.473654)
		(end 375.086372 -29.526992)
		(width 0.1143)
		(layer "In2.Cu")
		(net "CLK_100M_PCH_SLOTX24_S5_DP")
	)
	(segment
		(start 423.307764 -20.168616)
		(end 423.075608 -20.121626)
		(width 0.1143)
		(layer "In2.Cu")
		(net "CLK_100M_PCH_SLOTX24_S5_DP")
	)
	(segment
		(start 461.126078 -9.856216)
		(end 461.126078 -10.963148)
		(width 0.1143)
		(layer "In2.Cu")
		(net "CLK_100M_PCH_SLOTX24_S5_DP")
	)
	(segment
		(start 438.841896 -16.5735)
		(end 437.622188 -16.32966)
		(width 0.1143)
		(layer "In2.Cu")
		(net "CLK_100M_PCH_SLOTX24_S5_DP")
	)
	(segment
		(start 428.517812 -18.527268)
		(end 427.975014 -19.34718)
		(width 0.1143)
		(layer "In2.Cu")
		(net "CLK_100M_PCH_SLOTX24_S5_DP")
	)
	(segment
		(start 374.836436 -34.770568)
		(end 372.987062 -37.179504)
		(width 0.1143)
		(layer "In2.Cu")
		(net "CLK_100M_PCH_SLOTX24_S5_DP")
	)
	(segment
		(start 367.852198 -63.207646)
		(end 367.240312 -63.620396)
		(width 0.1143)
		(layer "In2.Cu")
		(net "CLK_100M_PCH_SLOTX24_S5_DP")
	)
	(segment
		(start 455.144124 -14.42085)
		(end 454.311004 -14.253718)
		(width 0.1143)
		(layer "In2.Cu")
		(net "CLK_100M_PCH_SLOTX24_S5_DP")
	)
	(segment
		(start 371.182138 -93.80474)
		(end 371.690138 -94.842838)
		(width 0.1143)
		(layer "In2.Cu")
		(net "CLK_100M_PCH_SLOTX24_S5_DP")
	)
	(segment
		(start 425.005754 -19.823176)
		(end 424.565318 -19.912838)
		(width 0.1143)
		(layer "In2.Cu")
		(net "CLK_100M_PCH_SLOTX24_S5_DP")
	)
	(segment
		(start 374.99544 -105.758234)
		(end 376.758454 -105.758234)
		(width 0.0889)
		(layer "In2.Cu")
		(net "CLK_100M_PCH_SLOTX24_S5_DP")
	)
	(segment
		(start 371.122194 -101.348032)
		(end 371.889782 -105.03916)
		(width 0.1143)
		(layer "In2.Cu")
		(net "CLK_100M_PCH_SLOTX24_S5_DP")
	)
	(segment
		(start 398.60347 -25.748234)
		(end 397.104616 -25.154128)
		(width 0.1143)
		(layer "In2.Cu")
		(net "CLK_100M_PCH_SLOTX24_S5_DP")
	)
	(segment
		(start 428.916846 -18.263616)
		(end 428.517812 -18.527268)
		(width 0.1143)
		(layer "In2.Cu")
		(net "CLK_100M_PCH_SLOTX24_S5_DP")
	)
	(segment
		(start 444.51778 -16.490188)
		(end 443.370716 -17.568418)
		(width 0.1143)
		(layer "In2.Cu")
		(net "CLK_100M_PCH_SLOTX24_S5_DP")
	)
	(segment
		(start 375.79554 -27.195526)
		(end 375.602754 -27.829764)
		(width 0.1143)
		(layer "In2.Cu")
		(net "CLK_100M_PCH_SLOTX24_S5_DP")
	)
	(segment
		(start 430.247552 -17.992852)
		(end 428.916846 -18.263616)
		(width 0.1143)
		(layer "In2.Cu")
		(net "CLK_100M_PCH_SLOTX24_S5_DP")
	)
	(segment
		(start 452.312532 -12.921488)
		(end 450.9262 -12.64412)
		(width 0.1143)
		(layer "In2.Cu")
		(net "CLK_100M_PCH_SLOTX24_S5_DP")
	)
	(segment
		(start 367.179098 -64.5668)
		(end 366.77473 -65.205102)
		(width 0.1143)
		(layer "In2.Cu")
		(net "CLK_100M_PCH_SLOTX24_S5_DP")
	)
	(segment
		(start 367.836704 -90.023442)
		(end 368.803936 -91.426284)
		(width 0.1143)
		(layer "In2.Cu")
		(net "CLK_100M_PCH_SLOTX24_S5_DP")
	)
	(segment
		(start 365.261398 -70.715378)
		(end 364.59922 -72.656446)
		(width 0.1143)
		(layer "In2.Cu")
		(net "CLK_100M_PCH_SLOTX24_S5_DP")
	)
	(segment
		(start 427.397418 -19.72945)
		(end 425.970954 -20.019772)
		(width 0.1143)
		(layer "In2.Cu")
		(net "CLK_100M_PCH_SLOTX24_S5_DP")
	)
	(segment
		(start 401.154392 -26.369264)
		(end 399.734532 -25.748234)
		(width 0.1143)
		(layer "In2.Cu")
		(net "CLK_100M_PCH_SLOTX24_S5_DP")
	)
	(segment
		(start 375.712482 -28.035758)
		(end 375.61266 -28.363926)
		(width 0.1143)
		(layer "In2.Cu")
		(net "CLK_100M_PCH_SLOTX24_S5_DP")
	)
	(segment
		(start 461.10271 -10.986516)
		(end 460.469234 -12.469622)
		(width 0.1143)
		(layer "In2.Cu")
		(net "CLK_100M_PCH_SLOTX24_S5_DP")
	)
	(segment
		(start 391.685272 -24.263096)
		(end 390.59358 -24.515318)
		(width 0.1143)
		(layer "In2.Cu")
		(net "CLK_100M_PCH_SLOTX24_S5_DP")
	)
	(segment
		(start 395.492224 -23.709376)
		(end 394.756894 -23.485348)
		(width 0.1143)
		(layer "In2.Cu")
		(net "CLK_100M_PCH_SLOTX24_S5_DP")
	)
	(segment
		(start 393.085828 -24.25827)
		(end 392.37539 -24.422354)
		(width 0.1143)
		(layer "In2.Cu")
		(net "CLK_100M_PCH_SLOTX24_S5_DP")
	)
	(segment
		(start 371.754908 -46.75251)
		(end 372.002558 -47.993046)
		(width 0.1143)
		(layer "In2.Cu")
		(net "CLK_100M_PCH_SLOTX24_S5_DP")
	)
	(segment
		(start 460.469234 -12.469622)
		(end 459.885288 -12.798298)
		(width 0.1143)
		(layer "In2.Cu")
		(net "CLK_100M_PCH_SLOTX24_S5_DP")
	)
	(segment
		(start 371.534944 -98.323908)
		(end 371.33149 -99.093274)
		(width 0.1143)
		(layer "In2.Cu")
		(net "CLK_100M_PCH_SLOTX24_S5_DP")
	)
	(segment
		(start 365.3917 -76.393294)
		(end 365.3917 -79.89443)
		(width 0.1143)
		(layer "In2.Cu")
		(net "CLK_100M_PCH_SLOTX24_S5_DP")
	)
	(segment
		(start 392.37539 -24.422354)
		(end 391.685272 -24.263096)
		(width 0.1143)
		(layer "In2.Cu")
		(net "CLK_100M_PCH_SLOTX24_S5_DP")
	)
	(segment
		(start 439.777124 -17.19707)
		(end 438.841896 -16.5735)
		(width 0.1143)
		(layer "In2.Cu")
		(net "CLK_100M_PCH_SLOTX24_S5_DP")
	)
	(segment
		(start 387.882638 -23.07717)
		(end 386.466588 -23.459694)
		(width 0.1143)
		(layer "In2.Cu")
		(net "CLK_100M_PCH_SLOTX24_S5_DP")
	)
	(segment
		(start 364.640876 -68.369434)
		(end 365.261398 -70.715378)
		(width 0.1143)
		(layer "In2.Cu")
		(net "CLK_100M_PCH_SLOTX24_S5_DP")
	)
	(segment
		(start 371.690138 -94.842838)
		(end 371.534944 -95.51543)
		(width 0.1143)
		(layer "In2.Cu")
		(net "CLK_100M_PCH_SLOTX24_S5_DP")
	)
	(segment
		(start 366.343692 -84.656676)
		(end 366.09655 -85.892386)
		(width 0.1143)
		(layer "In2.Cu")
		(net "CLK_100M_PCH_SLOTX24_S5_DP")
	)
	(arc
		(start 378.031248 -106.537506)
		(mid 378.468207 -106.475386)
		(end 378.826268 -106.73334)
		(width 0.0889)
		(layer "In2.Cu")
		(net "CLK_100M_PCH_SLOTX24_S5_DP")
	)
	(arc
		(start 377.83135 -106.591354)
		(mid 377.934863 -106.577658)
		(end 378.031248 -106.537506)
		(width 0.0889)
		(layer "In2.Cu")
		(net "CLK_100M_PCH_SLOTX24_S5_DP")
	)
	(arc
		(start 378.870464 -106.803444)
		(mid 379.062251 -106.983793)
		(end 379.31725 -107.049316)
		(width 0.0889)
		(layer "In2.Cu")
		(net "CLK_100M_PCH_SLOTX24_S5_DP")
	)
	(segment
		(start 460.511144 -9.385046)
		(end 460.770478 -9.125712)
		(width 0.127)
		(layer "F.Cu")
		(net "CLK_100M_PCH_SLOTX24_S5_DN")
	)
	(segment
		(start 460.770478 -8.862568)
		(end 460.478378 -8.570468)
		(width 0.127)
		(layer "F.Cu")
		(net "CLK_100M_PCH_SLOTX24_S5_DN")
	)
	(segment
		(start 377.83135 -107.27944)
		(end 378.32665 -107.049316)
		(width 0.127)
		(layer "F.Cu")
		(net "CLK_100M_PCH_SLOTX24_S5_DN")
	)
	(segment
		(start 460.478378 -8.570468)
		(end 460.478378 -7.789672)
		(width 0.127)
		(layer "F.Cu")
		(net "CLK_100M_PCH_SLOTX24_S5_DN")
	)
	(segment
		(start 460.337408 -9.385046)
		(end 460.511144 -9.385046)
		(width 0.127)
		(layer "F.Cu")
		(net "CLK_100M_PCH_SLOTX24_S5_DN")
	)
	(segment
		(start 460.770478 -9.125712)
		(end 460.770478 -8.862568)
		(width 0.127)
		(layer "F.Cu")
		(net "CLK_100M_PCH_SLOTX24_S5_DN")
	)
	(via
		(at 460.337408 -9.385046)
		(size 0.508)
		(drill 0.254)
		(layers "F.Cu" "B.Cu")
		(net "CLK_100M_PCH_SLOTX24_S5_DN")
	)
	(via
		(at 378.32665 -107.049316)
		(size 0.508)
		(drill 0.254)
		(layers "F.Cu" "B.Cu")
		(net "CLK_100M_PCH_SLOTX24_S5_DN")
	)
	(segment
		(start 371.89283 -40.067992)
		(end 372.34876 -42.292778)
		(width 0.1143)
		(layer "In2.Cu")
		(net "CLK_100M_PCH_SLOTX24_S5_DN")
	)
	(segment
		(start 395.63929 -23.448518)
		(end 394.773912 -23.18512)
		(width 0.1143)
		(layer "In2.Cu")
		(net "CLK_100M_PCH_SLOTX24_S5_DN")
	)
	(segment
		(start 375.26214 -105.948734)
		(end 375.35104 -106.037634)
		(width 0.0889)
		(layer "In2.Cu")
		(net "CLK_100M_PCH_SLOTX24_S5_DN")
	)
	(segment
		(start 386.282184 -23.20671)
		(end 385.200906 -24.874982)
		(width 0.1143)
		(layer "In2.Cu")
		(net "CLK_100M_PCH_SLOTX24_S5_DN")
	)
	(segment
		(start 392.37539 -24.12238)
		(end 391.685272 -23.963122)
		(width 0.1143)
		(layer "In2.Cu")
		(net "CLK_100M_PCH_SLOTX24_S5_DN")
	)
	(segment
		(start 366.192308 -66.451988)
		(end 365.574326 -66.715386)
		(width 0.1143)
		(layer "In2.Cu")
		(net "CLK_100M_PCH_SLOTX24_S5_DN")
	)
	(segment
		(start 383.015236 -25.704038)
		(end 381.617728 -26.657808)
		(width 0.1143)
		(layer "In2.Cu")
		(net "CLK_100M_PCH_SLOTX24_S5_DN")
	)
	(segment
		(start 376.233182 -26.051764)
		(end 375.529348 -27.066748)
		(width 0.1143)
		(layer "In2.Cu")
		(net "CLK_100M_PCH_SLOTX24_S5_DN")
	)
	(segment
		(start 374.784874 -29.514038)
		(end 375.214388 -31.533846)
		(width 0.1143)
		(layer "In2.Cu")
		(net "CLK_100M_PCH_SLOTX24_S5_DN")
	)
	(segment
		(start 366.994186 -63.43396)
		(end 366.994186 -63.454026)
		(width 0.1143)
		(layer "In2.Cu")
		(net "CLK_100M_PCH_SLOTX24_S5_DN")
	)
	(segment
		(start 428.306992 -18.316448)
		(end 427.764194 -19.13636)
		(width 0.1143)
		(layer "In2.Cu")
		(net "CLK_100M_PCH_SLOTX24_S5_DN")
	)
	(segment
		(start 366.04575 -84.656676)
		(end 365.798608 -85.892386)
		(width 0.1143)
		(layer "In2.Cu")
		(net "CLK_100M_PCH_SLOTX24_S5_DN")
	)
	(segment
		(start 431.404268 -17.930114)
		(end 430.247552 -17.694656)
		(width 0.1143)
		(layer "In2.Cu")
		(net "CLK_100M_PCH_SLOTX24_S5_DN")
	)
	(segment
		(start 374.99544 -105.948734)
		(end 375.26214 -105.948734)
		(width 0.0889)
		(layer "In2.Cu")
		(net "CLK_100M_PCH_SLOTX24_S5_DN")
	)
	(segment
		(start 365.0996 -79.923386)
		(end 366.04575 -84.656676)
		(width 0.1143)
		(layer "In2.Cu")
		(net "CLK_100M_PCH_SLOTX24_S5_DN")
	)
	(segment
		(start 370.940838 -93.976952)
		(end 370.941092 -93.976952)
		(width 0.1143)
		(layer "In2.Cu")
		(net "CLK_100M_PCH_SLOTX24_S5_DN")
	)
	(segment
		(start 371.38229 -94.878144)
		(end 371.242844 -95.481902)
		(width 0.1143)
		(layer "In2.Cu")
		(net "CLK_100M_PCH_SLOTX24_S5_DN")
	)
	(segment
		(start 394.690092 -23.200868)
		(end 393.954508 -23.37054)
		(width 0.1143)
		(layer "In2.Cu")
		(net "CLK_100M_PCH_SLOTX24_S5_DN")
	)
	(segment
		(start 459.768448 -12.529058)
		(end 455.124312 -14.118844)
		(width 0.1143)
		(layer "In2.Cu")
		(net "CLK_100M_PCH_SLOTX24_S5_DN")
	)
	(segment
		(start 454.424542 -13.978636)
		(end 452.426578 -12.646406)
		(width 0.1143)
		(layer "In2.Cu")
		(net "CLK_100M_PCH_SLOTX24_S5_DN")
	)
	(segment
		(start 394.691108 -23.200614)
		(end 394.690092 -23.200868)
		(width 0.1143)
		(layer "In2.Cu")
		(net "CLK_100M_PCH_SLOTX24_S5_DN")
	)
	(segment
		(start 365.099346 -76.424282)
		(end 365.0996 -76.424282)
		(width 0.1143)
		(layer "In2.Cu")
		(net "CLK_100M_PCH_SLOTX24_S5_DN")
	)
	(segment
		(start 370.82349 -101.346762)
		(end 371.621558 -105.184194)
		(width 0.1143)
		(layer "In2.Cu")
		(net "CLK_100M_PCH_SLOTX24_S5_DN")
	)
	(segment
		(start 419.4302 -21.4376)
		(end 415.0106 -22.9108)
		(width 0.1143)
		(layer "In2.Cu")
		(net "CLK_100M_PCH_SLOTX24_S5_DN")
	)
	(segment
		(start 371.704362 -47.991522)
		(end 369.277138 -59.888374)
		(width 0.1143)
		(layer "In2.Cu")
		(net "CLK_100M_PCH_SLOTX24_S5_DN")
	)
	(segment
		(start 371.242844 -95.481902)
		(end 371.242844 -98.285808)
		(width 0.1143)
		(layer "In2.Cu")
		(net "CLK_100M_PCH_SLOTX24_S5_DN")
	)
	(segment
		(start 385.200906 -24.874982)
		(end 384.187446 -25.44572)
		(width 0.1143)
		(layer "In2.Cu")
		(net "CLK_100M_PCH_SLOTX24_S5_DN")
	)
	(segment
		(start 450.9262 -12.346178)
		(end 449.899024 -12.55141)
		(width 0.1143)
		(layer "In2.Cu")
		(net "CLK_100M_PCH_SLOTX24_S5_DN")
	)
	(segment
		(start 393.954508 -23.37054)
		(end 392.97229 -23.984458)
		(width 0.1143)
		(layer "In2.Cu")
		(net "CLK_100M_PCH_SLOTX24_S5_DN")
	)
	(segment
		(start 436.362094 -16.286734)
		(end 434.97627 -17.203928)
		(width 0.1143)
		(layer "In2.Cu")
		(net "CLK_100M_PCH_SLOTX24_S5_DN")
	)
	(segment
		(start 375.529348 -27.066748)
		(end 374.784874 -29.514038)
		(width 0.1143)
		(layer "In2.Cu")
		(net "CLK_100M_PCH_SLOTX24_S5_DN")
	)
	(segment
		(start 392.97229 -23.984458)
		(end 392.37539 -24.12238)
		(width 0.1143)
		(layer "In2.Cu")
		(net "CLK_100M_PCH_SLOTX24_S5_DN")
	)
	(segment
		(start 420.646606 -20.544028)
		(end 419.4302 -21.4376)
		(width 0.1143)
		(layer "In2.Cu")
		(net "CLK_100M_PCH_SLOTX24_S5_DN")
	)
	(segment
		(start 368.001042 -62.464188)
		(end 367.641632 -62.99708)
		(width 0.1143)
		(layer "In2.Cu")
		(net "CLK_100M_PCH_SLOTX24_S5_DN")
	)
	(segment
		(start 365.798608 -85.892386)
		(end 366.518952 -89.496392)
		(width 0.1143)
		(layer "In2.Cu")
		(net "CLK_100M_PCH_SLOTX24_S5_DN")
	)
	(segment
		(start 437.621934 -16.031464)
		(end 436.362094 -16.286734)
		(width 0.1143)
		(layer "In2.Cu")
		(net "CLK_100M_PCH_SLOTX24_S5_DN")
	)
	(segment
		(start 365.0996 -76.424282)
		(end 365.0996 -79.923386)
		(width 0.1143)
		(layer "In2.Cu")
		(net "CLK_100M_PCH_SLOTX24_S5_DN")
	)
	(segment
		(start 364.296706 -72.638412)
		(end 365.099346 -76.424282)
		(width 0.1143)
		(layer "In2.Cu")
		(net "CLK_100M_PCH_SLOTX24_S5_DN")
	)
	(segment
		(start 442.747146 -17.51584)
		(end 439.939176 -16.953992)
		(width 0.1143)
		(layer "In2.Cu")
		(net "CLK_100M_PCH_SLOTX24_S5_DN")
	)
	(segment
		(start 434.97627 -17.203928)
		(end 431.404268 -17.930114)
		(width 0.1143)
		(layer "In2.Cu")
		(net "CLK_100M_PCH_SLOTX24_S5_DN")
	)
	(segment
		(start 399.795746 -25.456134)
		(end 398.65935 -25.456134)
		(width 0.1143)
		(layer "In2.Cu")
		(net "CLK_100M_PCH_SLOTX24_S5_DN")
	)
	(segment
		(start 366.869726 -64.509142)
		(end 366.500918 -65.09131)
		(width 0.1143)
		(layer "In2.Cu")
		(net "CLK_100M_PCH_SLOTX24_S5_DN")
	)
	(segment
		(start 371.03939 -99.055174)
		(end 371.03939 -100.331016)
		(width 0.1143)
		(layer "In2.Cu")
		(net "CLK_100M_PCH_SLOTX24_S5_DN")
	)
	(segment
		(start 366.764316 -63.977266)
		(end 366.869726 -64.509142)
		(width 0.1143)
		(layer "In2.Cu")
		(net "CLK_100M_PCH_SLOTX24_S5_DN")
	)
	(segment
		(start 423.306748 -19.87042)
		(end 423.075608 -19.82343)
		(width 0.1143)
		(layer "In2.Cu")
		(net "CLK_100M_PCH_SLOTX24_S5_DN")
	)
	(segment
		(start 460.239364 -12.263628)
		(end 459.768448 -12.529058)
		(width 0.1143)
		(layer "In2.Cu")
		(net "CLK_100M_PCH_SLOTX24_S5_DN")
	)
	(segment
		(start 443.208156 -17.319752)
		(end 442.747146 -17.51584)
		(width 0.1143)
		(layer "In2.Cu")
		(net "CLK_100M_PCH_SLOTX24_S5_DN")
	)
	(segment
		(start 375.70664 -105.948734)
		(end 376.67946 -105.948734)
		(width 0.0889)
		(layer "In2.Cu")
		(net "CLK_100M_PCH_SLOTX24_S5_DN")
	)
	(segment
		(start 425.970954 -19.721576)
		(end 425.005754 -19.52498)
		(width 0.1143)
		(layer "In2.Cu")
		(net "CLK_100M_PCH_SLOTX24_S5_DN")
	)
	(segment
		(start 380.019814 -26.607516)
		(end 378.57303 -25.537922)
		(width 0.1143)
		(layer "In2.Cu")
		(net "CLK_100M_PCH_SLOTX24_S5_DN")
	)
	(segment
		(start 375.61774 -106.037634)
		(end 375.70664 -105.948734)
		(width 0.0889)
		(layer "In2.Cu")
		(net "CLK_100M_PCH_SLOTX24_S5_DN")
	)
	(segment
		(start 368.578384 -91.614244)
		(end 370.940838 -93.976952)
		(width 0.1143)
		(layer "In2.Cu")
		(net "CLK_100M_PCH_SLOTX24_S5_DN")
	)
	(segment
		(start 411.79369 -24.47671)
		(end 409.713176 -24.892762)
		(width 0.1143)
		(layer "In2.Cu")
		(net "CLK_100M_PCH_SLOTX24_S5_DN")
	)
	(segment
		(start 398.65935 -25.456134)
		(end 397.260826 -24.901652)
		(width 0.1143)
		(layer "In2.Cu")
		(net "CLK_100M_PCH_SLOTX24_S5_DN")
	)
	(segment
		(start 378.57303 -25.537922)
		(end 378.114306 -25.435052)
		(width 0.1143)
		(layer "In2.Cu")
		(net "CLK_100M_PCH_SLOTX24_S5_DN")
	)
	(segment
		(start 369.277138 -59.888374)
		(end 368.187478 -61.504068)
		(width 0.1143)
		(layer "In2.Cu")
		(net "CLK_100M_PCH_SLOTX24_S5_DN")
	)
	(segment
		(start 377.51258 -106.781854)
		(end 377.83135 -106.781854)
		(width 0.0889)
		(layer "In2.Cu")
		(net "CLK_100M_PCH_SLOTX24_S5_DN")
	)
	(segment
		(start 372.437914 -105.999534)
		(end 374.922542 -105.999534)
		(width 0.1143)
		(layer "In2.Cu")
		(net "CLK_100M_PCH_SLOTX24_S5_DN")
	)
	(segment
		(start 367.627916 -90.235532)
		(end 368.578384 -91.614244)
		(width 0.1143)
		(layer "In2.Cu")
		(net "CLK_100M_PCH_SLOTX24_S5_DN")
	)
	(segment
		(start 428.8028 -17.988534)
		(end 428.306992 -18.316448)
		(width 0.1143)
		(layer "In2.Cu")
		(net "CLK_100M_PCH_SLOTX24_S5_DN")
	)
	(segment
		(start 387.91769 -22.765004)
		(end 386.282184 -23.20671)
		(width 0.1143)
		(layer "In2.Cu")
		(net "CLK_100M_PCH_SLOTX24_S5_DN")
	)
	(segment
		(start 397.260826 -24.901652)
		(end 395.63929 -23.448518)
		(width 0.1143)
		(layer "In2.Cu")
		(net "CLK_100M_PCH_SLOTX24_S5_DN")
	)
	(segment
		(start 374.922542 -105.999534)
		(end 374.94464 -105.999534)
		(width 0.0889)
		(layer "In2.Cu")
		(net "CLK_100M_PCH_SLOTX24_S5_DN")
	)
	(segment
		(start 371.242844 -98.285808)
		(end 371.03939 -99.055174)
		(width 0.1143)
		(layer "In2.Cu")
		(net "CLK_100M_PCH_SLOTX24_S5_DN")
	)
	(segment
		(start 394.766292 -23.183342)
		(end 394.691108 -23.200614)
		(width 0.1143)
		(layer "In2.Cu")
		(net "CLK_100M_PCH_SLOTX24_S5_DN")
	)
	(segment
		(start 409.713176 -24.892762)
		(end 408.576272 -25.651206)
		(width 0.1143)
		(layer "In2.Cu")
		(net "CLK_100M_PCH_SLOTX24_S5_DN")
	)
	(segment
		(start 372.34876 -42.292778)
		(end 371.456966 -46.75251)
		(width 0.1143)
		(layer "In2.Cu")
		(net "CLK_100M_PCH_SLOTX24_S5_DN")
	)
	(segment
		(start 384.187446 -25.44572)
		(end 383.015236 -25.704038)
		(width 0.1143)
		(layer "In2.Cu")
		(net "CLK_100M_PCH_SLOTX24_S5_DN")
	)
	(segment
		(start 376.67946 -105.948734)
		(end 377.51258 -106.781854)
		(width 0.0889)
		(layer "In2.Cu")
		(net "CLK_100M_PCH_SLOTX24_S5_DN")
	)
	(segment
		(start 452.426578 -12.646406)
		(end 450.9262 -12.346178)
		(width 0.1143)
		(layer "In2.Cu")
		(net "CLK_100M_PCH_SLOTX24_S5_DN")
	)
	(segment
		(start 449.899024 -12.551664)
		(end 444.334392 -16.261588)
		(width 0.1143)
		(layer "In2.Cu")
		(net "CLK_100M_PCH_SLOTX24_S5_DN")
	)
	(segment
		(start 367.641632 -62.99708)
		(end 366.994186 -63.43396)
		(width 0.1143)
		(layer "In2.Cu")
		(net "CLK_100M_PCH_SLOTX24_S5_DN")
	)
	(segment
		(start 425.005754 -19.52498)
		(end 424.780456 -19.5707)
		(width 0.1143)
		(layer "In2.Cu")
		(net "CLK_100M_PCH_SLOTX24_S5_DN")
	)
	(segment
		(start 371.03939 -100.331016)
		(end 370.82349 -101.346762)
		(width 0.1143)
		(layer "In2.Cu")
		(net "CLK_100M_PCH_SLOTX24_S5_DN")
	)
	(segment
		(start 415.0106 -22.9108)
		(end 414.07461 -22.9108)
		(width 0.1143)
		(layer "In2.Cu")
		(net "CLK_100M_PCH_SLOTX24_S5_DN")
	)
	(segment
		(start 413.186626 -23.798784)
		(end 411.79369 -24.47671)
		(width 0.1143)
		(layer "In2.Cu")
		(net "CLK_100M_PCH_SLOTX24_S5_DN")
	)
	(segment
		(start 365.574326 -66.715386)
		(end 364.320836 -68.302886)
		(width 0.1143)
		(layer "In2.Cu")
		(net "CLK_100M_PCH_SLOTX24_S5_DN")
	)
	(segment
		(start 403.123654 -26.077164)
		(end 401.215606 -26.077164)
		(width 0.1143)
		(layer "In2.Cu")
		(net "CLK_100M_PCH_SLOTX24_S5_DN")
	)
	(segment
		(start 366.500918 -65.09131)
		(end 366.192308 -66.451988)
		(width 0.1143)
		(layer "In2.Cu")
		(net "CLK_100M_PCH_SLOTX24_S5_DN")
	)
	(segment
		(start 455.124312 -14.118844)
		(end 454.424542 -13.978636)
		(width 0.1143)
		(layer "In2.Cu")
		(net "CLK_100M_PCH_SLOTX24_S5_DN")
	)
	(segment
		(start 364.320836 -68.302886)
		(end 364.956344 -70.70471)
		(width 0.1143)
		(layer "In2.Cu")
		(net "CLK_100M_PCH_SLOTX24_S5_DN")
	)
	(segment
		(start 460.833978 -9.881616)
		(end 460.833978 -10.871962)
		(width 0.1143)
		(layer "In2.Cu")
		(net "CLK_100M_PCH_SLOTX24_S5_DN")
	)
	(segment
		(start 366.994186 -63.454026)
		(end 366.764316 -63.977266)
		(width 0.1143)
		(layer "In2.Cu")
		(net "CLK_100M_PCH_SLOTX24_S5_DN")
	)
	(segment
		(start 444.334392 -16.261588)
		(end 443.208156 -17.319752)
		(width 0.1143)
		(layer "In2.Cu")
		(net "CLK_100M_PCH_SLOTX24_S5_DN")
	)
	(segment
		(start 407.27376 -25.286716)
		(end 405.49068 -25.286716)
		(width 0.1143)
		(layer "In2.Cu")
		(net "CLK_100M_PCH_SLOTX24_S5_DN")
	)
	(segment
		(start 405.49068 -25.286716)
		(end 403.123654 -26.077164)
		(width 0.1143)
		(layer "In2.Cu")
		(net "CLK_100M_PCH_SLOTX24_S5_DN")
	)
	(segment
		(start 390.63422 -24.205946)
		(end 387.91769 -22.765004)
		(width 0.1143)
		(layer "In2.Cu")
		(net "CLK_100M_PCH_SLOTX24_S5_DN")
	)
	(segment
		(start 374.94464 -105.999534)
		(end 374.99544 -105.948734)
		(width 0.0889)
		(layer "In2.Cu")
		(net "CLK_100M_PCH_SLOTX24_S5_DN")
	)
	(segment
		(start 371.456966 -46.75251)
		(end 371.704362 -47.991522)
		(width 0.1143)
		(layer "In2.Cu")
		(net "CLK_100M_PCH_SLOTX24_S5_DN")
	)
	(segment
		(start 394.773912 -23.18512)
		(end 394.766292 -23.183342)
		(width 0.1143)
		(layer "In2.Cu")
		(net "CLK_100M_PCH_SLOTX24_S5_DN")
	)
	(segment
		(start 381.617728 -26.657808)
		(end 380.96825 -26.80462)
		(width 0.1143)
		(layer "In2.Cu")
		(net "CLK_100M_PCH_SLOTX24_S5_DN")
	)
	(segment
		(start 372.720362 -37.04717)
		(end 371.89283 -40.067992)
		(width 0.1143)
		(layer "In2.Cu")
		(net "CLK_100M_PCH_SLOTX24_S5_DN")
	)
	(segment
		(start 391.685272 -23.963122)
		(end 390.63422 -24.205946)
		(width 0.1143)
		(layer "In2.Cu")
		(net "CLK_100M_PCH_SLOTX24_S5_DN")
	)
	(segment
		(start 366.518952 -89.496392)
		(end 367.627916 -90.235532)
		(width 0.1143)
		(layer "In2.Cu")
		(net "CLK_100M_PCH_SLOTX24_S5_DN")
	)
	(segment
		(start 439.939176 -16.953992)
		(end 438.955942 -16.298418)
		(width 0.1143)
		(layer "In2.Cu")
		(net "CLK_100M_PCH_SLOTX24_S5_DN")
	)
	(segment
		(start 378.114306 -25.435052)
		(end 376.233182 -26.051764)
		(width 0.1143)
		(layer "In2.Cu")
		(net "CLK_100M_PCH_SLOTX24_S5_DN")
	)
	(segment
		(start 408.576272 -25.651206)
		(end 408.282902 -25.651206)
		(width 0.1143)
		(layer "In2.Cu")
		(net "CLK_100M_PCH_SLOTX24_S5_DN")
	)
	(segment
		(start 368.187478 -61.504068)
		(end 368.001042 -62.464188)
		(width 0.1143)
		(layer "In2.Cu")
		(net "CLK_100M_PCH_SLOTX24_S5_DN")
	)
	(segment
		(start 460.833978 -10.871962)
		(end 460.239364 -12.263628)
		(width 0.1143)
		(layer "In2.Cu")
		(net "CLK_100M_PCH_SLOTX24_S5_DN")
	)
	(segment
		(start 421.13962 -20.217638)
		(end 420.646606 -20.544028)
		(width 0.1143)
		(layer "In2.Cu")
		(net "CLK_100M_PCH_SLOTX24_S5_DN")
	)
	(segment
		(start 438.955942 -16.298418)
		(end 437.621934 -16.031464)
		(width 0.1143)
		(layer "In2.Cu")
		(net "CLK_100M_PCH_SLOTX24_S5_DN")
	)
	(segment
		(start 375.214388 -31.533846)
		(end 374.563894 -34.645346)
		(width 0.1143)
		(layer "In2.Cu")
		(net "CLK_100M_PCH_SLOTX24_S5_DN")
	)
	(segment
		(start 424.780456 -19.5707)
		(end 423.306748 -19.87042)
		(width 0.1143)
		(layer "In2.Cu")
		(net "CLK_100M_PCH_SLOTX24_S5_DN")
	)
	(segment
		(start 375.35104 -106.037634)
		(end 375.61774 -106.037634)
		(width 0.0889)
		(layer "In2.Cu")
		(net "CLK_100M_PCH_SLOTX24_S5_DN")
	)
	(segment
		(start 449.899024 -12.55141)
		(end 449.899024 -12.551664)
		(width 0.1143)
		(layer "In2.Cu")
		(net "CLK_100M_PCH_SLOTX24_S5_DN")
	)
	(segment
		(start 370.941092 -93.976952)
		(end 371.38229 -94.878144)
		(width 0.1143)
		(layer "In2.Cu")
		(net "CLK_100M_PCH_SLOTX24_S5_DN")
	)
	(segment
		(start 364.95609 -70.70471)
		(end 364.296706 -72.638412)
		(width 0.1143)
		(layer "In2.Cu")
		(net "CLK_100M_PCH_SLOTX24_S5_DN")
	)
	(segment
		(start 401.215606 -26.077164)
		(end 399.795746 -25.456134)
		(width 0.1143)
		(layer "In2.Cu")
		(net "CLK_100M_PCH_SLOTX24_S5_DN")
	)
	(segment
		(start 374.563894 -34.645346)
		(end 372.720362 -37.04717)
		(width 0.1143)
		(layer "In2.Cu")
		(net "CLK_100M_PCH_SLOTX24_S5_DN")
	)
	(segment
		(start 380.96825 -26.80462)
		(end 380.019814 -26.607516)
		(width 0.1143)
		(layer "In2.Cu")
		(net "CLK_100M_PCH_SLOTX24_S5_DN")
	)
	(segment
		(start 408.282902 -25.651206)
		(end 407.27376 -25.286716)
		(width 0.1143)
		(layer "In2.Cu")
		(net "CLK_100M_PCH_SLOTX24_S5_DN")
	)
	(segment
		(start 430.247552 -17.694656)
		(end 428.8028 -17.988534)
		(width 0.1143)
		(layer "In2.Cu")
		(net "CLK_100M_PCH_SLOTX24_S5_DN")
	)
	(segment
		(start 460.337408 -9.385046)
		(end 460.833978 -9.881616)
		(width 0.1143)
		(layer "In2.Cu")
		(net "CLK_100M_PCH_SLOTX24_S5_DN")
	)
	(segment
		(start 371.621558 -105.184194)
		(end 372.437914 -105.999534)
		(width 0.1143)
		(layer "In2.Cu")
		(net "CLK_100M_PCH_SLOTX24_S5_DN")
	)
	(segment
		(start 423.075608 -19.82343)
		(end 421.13962 -20.217638)
		(width 0.1143)
		(layer "In2.Cu")
		(net "CLK_100M_PCH_SLOTX24_S5_DN")
	)
	(segment
		(start 427.283372 -19.454368)
		(end 425.970954 -19.721576)
		(width 0.1143)
		(layer "In2.Cu")
		(net "CLK_100M_PCH_SLOTX24_S5_DN")
	)
	(segment
		(start 427.764194 -19.13636)
		(end 427.283372 -19.454368)
		(width 0.1143)
		(layer "In2.Cu")
		(net "CLK_100M_PCH_SLOTX24_S5_DN")
	)
	(segment
		(start 364.956344 -70.70471)
		(end 364.95609 -70.70471)
		(width 0.1143)
		(layer "In2.Cu")
		(net "CLK_100M_PCH_SLOTX24_S5_DN")
	)
	(segment
		(start 414.07461 -22.9108)
		(end 413.186626 -23.798784)
		(width 0.1143)
		(layer "In2.Cu")
		(net "CLK_100M_PCH_SLOTX24_S5_DN")
	)
	(arc
		(start 377.83135 -106.781854)
		(mid 377.984295 -106.76177)
		(end 378.126752 -106.702606)
		(width 0.0889)
		(layer "In2.Cu")
		(net "CLK_100M_PCH_SLOTX24_S5_DN")
	)
	(arc
		(start 378.126752 -106.702606)
		(mid 378.422574 -106.660773)
		(end 378.664978 -106.835448)
		(width 0.0889)
		(layer "In2.Cu")
		(net "CLK_100M_PCH_SLOTX24_S5_DN")
	)
	(arc
		(start 378.722636 -106.991404)
		(mid 378.55349 -107.218477)
		(end 378.32665 -107.049316)
		(width 0.0889)
		(layer "In2.Cu")
		(net "CLK_100M_PCH_SLOTX24_S5_DN")
	)
	(arc
		(start 378.664978 -106.835448)
		(mid 378.701977 -106.910403)
		(end 378.722636 -106.991404)
		(width 0.0889)
		(layer "In2.Cu")
		(net "CLK_100M_PCH_SLOTX24_S5_DN")
	)
	(segment
		(start 374.389142 -108.1151)
		(end 374.239536 -108.1151)
		(width 0.0889)
		(layer "F.Cu")
		(net "CLK_100M_PCH_SLOTX24_S4_DP")
	)
	(segment
		(start 375.089928 -108.354876)
		(end 374.628918 -108.354876)
		(width 0.0889)
		(layer "F.Cu")
		(net "CLK_100M_PCH_SLOTX24_S4_DP")
	)
	(segment
		(start 460.46898 -3.08991)
		(end 460.70393 -3.08991)
		(width 0.127)
		(layer "F.Cu")
		(net "CLK_100M_PCH_SLOTX24_S4_DP")
	)
	(segment
		(start 460.478378 -3.755644)
		(end 460.230728 -3.507994)
		(width 0.127)
		(layer "F.Cu")
		(net "CLK_100M_PCH_SLOTX24_S4_DP")
	)
	(segment
		(start 374.239536 -108.1151)
		(end 374.138444 -108.014008)
		(width 0.0889)
		(layer "F.Cu")
		(net "CLK_100M_PCH_SLOTX24_S4_DP")
	)
	(segment
		(start 460.230728 -3.507994)
		(end 460.230728 -3.328162)
		(width 0.127)
		(layer "F.Cu")
		(net "CLK_100M_PCH_SLOTX24_S4_DP")
	)
	(segment
		(start 373.859552 -108.1151)
		(end 373.685308 -108.1151)
		(width 0.0889)
		(layer "F.Cu")
		(net "CLK_100M_PCH_SLOTX24_S4_DP")
	)
	(segment
		(start 460.230728 -3.328162)
		(end 460.46898 -3.08991)
		(width 0.127)
		(layer "F.Cu")
		(net "CLK_100M_PCH_SLOTX24_S4_DP")
	)
	(segment
		(start 373.685308 -108.1151)
		(end 373.492776 -108.307632)
		(width 0.0889)
		(layer "F.Cu")
		(net "CLK_100M_PCH_SLOTX24_S4_DP")
	)
	(segment
		(start 373.960644 -108.014008)
		(end 373.859552 -108.1151)
		(width 0.0889)
		(layer "F.Cu")
		(net "CLK_100M_PCH_SLOTX24_S4_DP")
	)
	(segment
		(start 374.138444 -108.014008)
		(end 373.960644 -108.014008)
		(width 0.0889)
		(layer "F.Cu")
		(net "CLK_100M_PCH_SLOTX24_S4_DP")
	)
	(segment
		(start 374.628918 -108.354876)
		(end 374.389142 -108.1151)
		(width 0.0889)
		(layer "F.Cu")
		(net "CLK_100M_PCH_SLOTX24_S4_DP")
	)
	(segment
		(start 460.478378 -4.386072)
		(end 460.478378 -3.755644)
		(width 0.127)
		(layer "F.Cu")
		(net "CLK_100M_PCH_SLOTX24_S4_DP")
	)
	(segment
		(start 373.492776 -108.307632)
		(end 372.945914 -108.307632)
		(width 0.0889)
		(layer "F.Cu")
		(net "CLK_100M_PCH_SLOTX24_S4_DP")
	)
	(segment
		(start 372.945914 -108.307632)
		(end 372.69166 -108.561886)
		(width 0.0889)
		(layer "F.Cu")
		(net "CLK_100M_PCH_SLOTX24_S4_DP")
	)
	(segment
		(start 372.69166 -108.561886)
		(end 372.69166 -108.715302)
		(width 0.0889)
		(layer "F.Cu")
		(net "CLK_100M_PCH_SLOTX24_S4_DP")
	)
	(via
		(at 372.69166 -108.715302)
		(size 0.508)
		(drill 0.254)
		(layers "F.Cu" "B.Cu")
		(net "CLK_100M_PCH_SLOTX24_S4_DP")
	)
	(via
		(at 460.70393 -3.08991)
		(size 0.508)
		(drill 0.254)
		(layers "F.Cu" "B.Cu")
		(net "CLK_100M_PCH_SLOTX24_S4_DP")
	)
	(segment
		(start 366.353598 -58.178446)
		(end 366.582452 -58.132726)
		(width 0.1143)
		(layer "In2.Cu")
		(net "CLK_100M_PCH_SLOTX24_S4_DP")
	)
	(segment
		(start 440.627516 -13.55979)
		(end 442.408056 -12.928854)
		(width 0.1143)
		(layer "In2.Cu")
		(net "CLK_100M_PCH_SLOTX24_S4_DP")
	)
	(segment
		(start 379.995684 -20.572222)
		(end 381.227838 -19.76247)
		(width 0.1143)
		(layer "In2.Cu")
		(net "CLK_100M_PCH_SLOTX24_S4_DP")
	)
	(segment
		(start 371.837204 -109.12475)
		(end 370.722398 -108.009436)
		(width 0.1143)
		(layer "In2.Cu")
		(net "CLK_100M_PCH_SLOTX24_S4_DP")
	)
	(segment
		(start 363.386624 -66.100706)
		(end 364.465616 -61.009276)
		(width 0.1143)
		(layer "In2.Cu")
		(net "CLK_100M_PCH_SLOTX24_S4_DP")
	)
	(segment
		(start 368.486944 -54.979316)
		(end 369.168172 -51.547268)
		(width 0.1143)
		(layer "In2.Cu")
		(net "CLK_100M_PCH_SLOTX24_S4_DP")
	)
	(segment
		(start 367.290604 -56.773064)
		(end 368.486944 -54.979316)
		(width 0.1143)
		(layer "In2.Cu")
		(net "CLK_100M_PCH_SLOTX24_S4_DP")
	)
	(segment
		(start 363.730032 -87.752428)
		(end 363.662722 -87.416132)
		(width 0.1143)
		(layer "In2.Cu")
		(net "CLK_100M_PCH_SLOTX24_S4_DP")
	)
	(segment
		(start 422.556686 -16.296894)
		(end 425.881292 -15.620492)
		(width 0.1143)
		(layer "In2.Cu")
		(net "CLK_100M_PCH_SLOTX24_S4_DP")
	)
	(segment
		(start 364.465616 -61.009276)
		(end 365.207042 -59.897518)
		(width 0.1143)
		(layer "In2.Cu")
		(net "CLK_100M_PCH_SLOTX24_S4_DP")
	)
	(segment
		(start 369.52936 -104.451404)
		(end 369.112038 -103.927656)
		(width 0.1143)
		(layer "In2.Cu")
		(net "CLK_100M_PCH_SLOTX24_S4_DP")
	)
	(segment
		(start 369.1382 -103.695754)
		(end 368.924586 -103.42753)
		(width 0.1143)
		(layer "In2.Cu")
		(net "CLK_100M_PCH_SLOTX24_S4_DP")
	)
	(segment
		(start 425.881292 -15.620492)
		(end 426.62348 -15.771622)
		(width 0.1143)
		(layer "In2.Cu")
		(net "CLK_100M_PCH_SLOTX24_S4_DP")
	)
	(segment
		(start 368.799618 -96.099122)
		(end 368.477038 -94.580456)
		(width 0.1143)
		(layer "In2.Cu")
		(net "CLK_100M_PCH_SLOTX24_S4_DP")
	)
	(segment
		(start 365.43615 -59.851544)
		(end 365.626396 -59.566302)
		(width 0.1143)
		(layer "In2.Cu")
		(net "CLK_100M_PCH_SLOTX24_S4_DP")
	)
	(segment
		(start 442.408056 -12.928854)
		(end 443.808358 -13.26388)
		(width 0.1143)
		(layer "In2.Cu")
		(net "CLK_100M_PCH_SLOTX24_S4_DP")
	)
	(segment
		(start 445.838834 -12.857226)
		(end 447.69024 -11.623294)
		(width 0.1143)
		(layer "In2.Cu")
		(net "CLK_100M_PCH_SLOTX24_S4_DP")
	)
	(segment
		(start 368.799618 -98.392488)
		(end 368.799618 -96.099122)
		(width 0.1143)
		(layer "In2.Cu")
		(net "CLK_100M_PCH_SLOTX24_S4_DP")
	)
	(segment
		(start 369.866926 -39.496238)
		(end 370.579142 -36.897564)
		(width 0.1143)
		(layer "In2.Cu")
		(net "CLK_100M_PCH_SLOTX24_S4_DP")
	)
	(segment
		(start 402.975318 -20.517866)
		(end 403.169628 -20.388326)
		(width 0.1143)
		(layer "In2.Cu")
		(net "CLK_100M_PCH_SLOTX24_S4_DP")
	)
	(segment
		(start 403.971506 -20.717002)
		(end 404.165816 -20.587462)
		(width 0.1143)
		(layer "In2.Cu")
		(net "CLK_100M_PCH_SLOTX24_S4_DP")
	)
	(segment
		(start 460.2226 -3.885946)
		(end 460.2226 -3.57124)
		(width 0.1143)
		(layer "In2.Cu")
		(net "CLK_100M_PCH_SLOTX24_S4_DP")
	)
	(segment
		(start 436.911242 -14.182852)
		(end 436.910988 -14.182852)
		(width 0.1143)
		(layer "In2.Cu")
		(net "CLK_100M_PCH_SLOTX24_S4_DP")
	)
	(segment
		(start 366.018826 -58.977784)
		(end 366.209072 -58.692542)
		(width 0.1143)
		(layer "In2.Cu")
		(net "CLK_100M_PCH_SLOTX24_S4_DP")
	)
	(segment
		(start 365.580422 -59.337448)
		(end 365.789718 -59.023758)
		(width 0.1143)
		(layer "In2.Cu")
		(net "CLK_100M_PCH_SLOTX24_S4_DP")
	)
	(segment
		(start 415.406586 -17.81175)
		(end 417.223956 -18.175224)
		(width 0.1143)
		(layer "In2.Cu")
		(net "CLK_100M_PCH_SLOTX24_S4_DP")
	)
	(segment
		(start 427.304962 -15.632938)
		(end 427.99889 -15.17396)
		(width 0.1143)
		(layer "In2.Cu")
		(net "CLK_100M_PCH_SLOTX24_S4_DP")
	)
	(segment
		(start 371.561106 -29.033216)
		(end 375.702576 -23.49246)
		(width 0.1143)
		(layer "In2.Cu")
		(net "CLK_100M_PCH_SLOTX24_S4_DP")
	)
	(segment
		(start 370.181378 -35.522154)
		(end 371.561106 -29.033216)
		(width 0.1143)
		(layer "In2.Cu")
		(net "CLK_100M_PCH_SLOTX24_S4_DP")
	)
	(segment
		(start 381.227838 -19.76247)
		(end 388.657592 -18.144236)
		(width 0.1143)
		(layer "In2.Cu")
		(net "CLK_100M_PCH_SLOTX24_S4_DP")
	)
	(segment
		(start 403.505924 -20.455636)
		(end 403.635464 -20.649946)
		(width 0.1143)
		(layer "In2.Cu")
		(net "CLK_100M_PCH_SLOTX24_S4_DP")
	)
	(segment
		(start 436.116984 -14.024356)
		(end 436.911242 -14.182852)
		(width 0.1143)
		(layer "In2.Cu")
		(net "CLK_100M_PCH_SLOTX24_S4_DP")
	)
	(segment
		(start 434.759354 -13.486638)
		(end 435.549802 -13.645896)
		(width 0.1143)
		(layer "In2.Cu")
		(net "CLK_100M_PCH_SLOTX24_S4_DP")
	)
	(segment
		(start 400.176492 -19.789648)
		(end 402.509482 -20.256246)
		(width 0.1143)
		(layer "In2.Cu")
		(net "CLK_100M_PCH_SLOTX24_S4_DP")
	)
	(segment
		(start 402.639022 -20.450556)
		(end 402.975318 -20.517866)
		(width 0.1143)
		(layer "In2.Cu")
		(net "CLK_100M_PCH_SLOTX24_S4_DP")
	)
	(segment
		(start 394.859764 -19.673062)
		(end 397.331692 -20.233894)
		(width 0.1143)
		(layer "In2.Cu")
		(net "CLK_100M_PCH_SLOTX24_S4_DP")
	)
	(segment
		(start 388.657592 -18.144236)
		(end 394.859764 -19.673062)
		(width 0.1143)
		(layer "In2.Cu")
		(net "CLK_100M_PCH_SLOTX24_S4_DP")
	)
	(segment
		(start 448.48018 -10.437876)
		(end 448.859148 -9.869932)
		(width 0.1143)
		(layer "In2.Cu")
		(net "CLK_100M_PCH_SLOTX24_S4_DP")
	)
	(segment
		(start 369.168172 -51.547268)
		(end 368.233198 -48.60036)
		(width 0.1143)
		(layer "In2.Cu")
		(net "CLK_100M_PCH_SLOTX24_S4_DP")
	)
	(segment
		(start 363.468666 -87.286592)
		(end 363.401356 -86.950296)
		(width 0.1143)
		(layer "In2.Cu")
		(net "CLK_100M_PCH_SLOTX24_S4_DP")
	)
	(segment
		(start 363.600492 -87.946484)
		(end 363.730032 -87.752428)
		(width 0.1143)
		(layer "In2.Cu")
		(net "CLK_100M_PCH_SLOTX24_S4_DP")
	)
	(segment
		(start 434.102002 -13.620242)
		(end 434.759354 -13.486638)
		(width 0.1143)
		(layer "In2.Cu")
		(net "CLK_100M_PCH_SLOTX24_S4_DP")
	)
	(segment
		(start 403.169628 -20.388326)
		(end 403.505924 -20.455636)
		(width 0.1143)
		(layer "In2.Cu")
		(net "CLK_100M_PCH_SLOTX24_S4_DP")
	)
	(segment
		(start 365.875062 -91.057984)
		(end 363.968284 -89.785952)
		(width 0.1143)
		(layer "In2.Cu")
		(net "CLK_100M_PCH_SLOTX24_S4_DP")
	)
	(segment
		(start 365.626396 -59.566302)
		(end 365.580422 -59.337448)
		(width 0.1143)
		(layer "In2.Cu")
		(net "CLK_100M_PCH_SLOTX24_S4_DP")
	)
	(segment
		(start 368.233198 -48.60036)
		(end 370.356892 -41.885108)
		(width 0.1143)
		(layer "In2.Cu")
		(net "CLK_100M_PCH_SLOTX24_S4_DP")
	)
	(segment
		(start 366.163352 -58.463688)
		(end 366.353598 -58.178446)
		(width 0.1143)
		(layer "In2.Cu")
		(net "CLK_100M_PCH_SLOTX24_S4_DP")
	)
	(segment
		(start 368.478816 -103.133144)
		(end 368.353848 -102.60457)
		(width 0.1143)
		(layer "In2.Cu")
		(net "CLK_100M_PCH_SLOTX24_S4_DP")
	)
	(segment
		(start 372.69166 -108.715302)
		(end 372.69166 -108.964984)
		(width 0.1143)
		(layer "In2.Cu")
		(net "CLK_100M_PCH_SLOTX24_S4_DP")
	)
	(segment
		(start 450.56806 -8.73125)
		(end 455.514964 -7.741666)
		(width 0.1143)
		(layer "In2.Cu")
		(net "CLK_100M_PCH_SLOTX24_S4_DP")
	)
	(segment
		(start 367.336324 -57.002172)
		(end 367.290604 -56.773064)
		(width 0.1143)
		(layer "In2.Cu")
		(net "CLK_100M_PCH_SLOTX24_S4_DP")
	)
	(segment
		(start 379.026674 -22.230588)
		(end 379.52299 -21.537168)
		(width 0.1143)
		(layer "In2.Cu")
		(net "CLK_100M_PCH_SLOTX24_S4_DP")
	)
	(segment
		(start 369.112038 -103.927656)
		(end 369.1382 -103.695754)
		(width 0.1143)
		(layer "In2.Cu")
		(net "CLK_100M_PCH_SLOTX24_S4_DP")
	)
	(segment
		(start 450.567806 -8.73125)
		(end 450.56806 -8.73125)
		(width 0.1143)
		(layer "In2.Cu")
		(net "CLK_100M_PCH_SLOTX24_S4_DP")
	)
	(segment
		(start 366.582452 -58.132726)
		(end 366.772698 -57.847484)
		(width 0.1143)
		(layer "In2.Cu")
		(net "CLK_100M_PCH_SLOTX24_S4_DP")
	)
	(segment
		(start 408.176984 -19.258026)
		(end 415.406586 -17.81175)
		(width 0.1143)
		(layer "In2.Cu")
		(net "CLK_100M_PCH_SLOTX24_S4_DP")
	)
	(segment
		(start 363.968284 -89.785952)
		(end 363.600492 -87.946484)
		(width 0.1143)
		(layer "In2.Cu")
		(net "CLK_100M_PCH_SLOTX24_S4_DP")
	)
	(segment
		(start 363.401356 -86.950296)
		(end 364.10519 -83.432904)
		(width 0.1143)
		(layer "In2.Cu")
		(net "CLK_100M_PCH_SLOTX24_S4_DP")
	)
	(segment
		(start 367.146078 -57.287414)
		(end 367.336324 -57.002172)
		(width 0.1143)
		(layer "In2.Cu")
		(net "CLK_100M_PCH_SLOTX24_S4_DP")
	)
	(segment
		(start 366.726978 -57.618376)
		(end 366.917224 -57.333134)
		(width 0.1143)
		(layer "In2.Cu")
		(net "CLK_100M_PCH_SLOTX24_S4_DP")
	)
	(segment
		(start 455.514964 -7.741666)
		(end 458.070712 -6.037834)
		(width 0.1143)
		(layer "In2.Cu")
		(net "CLK_100M_PCH_SLOTX24_S4_DP")
	)
	(segment
		(start 432.35499 -14.776958)
		(end 434.102002 -13.620242)
		(width 0.1143)
		(layer "In2.Cu")
		(net "CLK_100M_PCH_SLOTX24_S4_DP")
	)
	(segment
		(start 417.223956 -18.175224)
		(end 422.556686 -16.296894)
		(width 0.1143)
		(layer "In2.Cu")
		(net "CLK_100M_PCH_SLOTX24_S4_DP")
	)
	(segment
		(start 365.789718 -59.023758)
		(end 366.018826 -58.977784)
		(width 0.1143)
		(layer "In2.Cu")
		(net "CLK_100M_PCH_SLOTX24_S4_DP")
	)
	(segment
		(start 366.772698 -57.847484)
		(end 366.726978 -57.618376)
		(width 0.1143)
		(layer "In2.Cu")
		(net "CLK_100M_PCH_SLOTX24_S4_DP")
	)
	(segment
		(start 405.962612 -20.946872)
		(end 406.899364 -20.75942)
		(width 0.1143)
		(layer "In2.Cu")
		(net "CLK_100M_PCH_SLOTX24_S4_DP")
	)
	(segment
		(start 362.075222 -67.056508)
		(end 363.386624 -66.100706)
		(width 0.1143)
		(layer "In2.Cu")
		(net "CLK_100M_PCH_SLOTX24_S4_DP")
	)
	(segment
		(start 366.917224 -57.333134)
		(end 367.146078 -57.287414)
		(width 0.1143)
		(layer "In2.Cu")
		(net "CLK_100M_PCH_SLOTX24_S4_DP")
	)
	(segment
		(start 372.531894 -109.12475)
		(end 371.837204 -109.12475)
		(width 0.1143)
		(layer "In2.Cu")
		(net "CLK_100M_PCH_SLOTX24_S4_DP")
	)
	(segment
		(start 447.69024 -11.623294)
		(end 448.48018 -10.437876)
		(width 0.1143)
		(layer "In2.Cu")
		(net "CLK_100M_PCH_SLOTX24_S4_DP")
	)
	(segment
		(start 435.549802 -13.645896)
		(end 436.116984 -14.024356)
		(width 0.1143)
		(layer "In2.Cu")
		(net "CLK_100M_PCH_SLOTX24_S4_DP")
	)
	(segment
		(start 427.99889 -15.17396)
		(end 428.79772 -15.0114)
		(width 0.1143)
		(layer "In2.Cu")
		(net "CLK_100M_PCH_SLOTX24_S4_DP")
	)
	(segment
		(start 426.62348 -15.771622)
		(end 427.304962 -15.632938)
		(width 0.1143)
		(layer "In2.Cu")
		(net "CLK_100M_PCH_SLOTX24_S4_DP")
	)
	(segment
		(start 363.4486 -76.773024)
		(end 361.709716 -68.577714)
		(width 0.1143)
		(layer "In2.Cu")
		(net "CLK_100M_PCH_SLOTX24_S4_DP")
	)
	(segment
		(start 370.356892 -41.885108)
		(end 369.866926 -39.496238)
		(width 0.1143)
		(layer "In2.Cu")
		(net "CLK_100M_PCH_SLOTX24_S4_DP")
	)
	(segment
		(start 370.579142 -36.897564)
		(end 370.181378 -35.522154)
		(width 0.1143)
		(layer "In2.Cu")
		(net "CLK_100M_PCH_SLOTX24_S4_DP")
	)
	(segment
		(start 375.702576 -23.49246)
		(end 378.556012 -22.595332)
		(width 0.1143)
		(layer "In2.Cu")
		(net "CLK_100M_PCH_SLOTX24_S4_DP")
	)
	(segment
		(start 443.808358 -13.26388)
		(end 445.838834 -12.857226)
		(width 0.1143)
		(layer "In2.Cu")
		(net "CLK_100M_PCH_SLOTX24_S4_DP")
	)
	(segment
		(start 363.4486 -80.336136)
		(end 363.4486 -76.773024)
		(width 0.1143)
		(layer "In2.Cu")
		(net "CLK_100M_PCH_SLOTX24_S4_DP")
	)
	(segment
		(start 370.722398 -108.009436)
		(end 370.073428 -107.058968)
		(width 0.1143)
		(layer "In2.Cu")
		(net "CLK_100M_PCH_SLOTX24_S4_DP")
	)
	(segment
		(start 436.910988 -14.182852)
		(end 436.993792 -14.199362)
		(width 0.1143)
		(layer "In2.Cu")
		(net "CLK_100M_PCH_SLOTX24_S4_DP")
	)
	(segment
		(start 372.69166 -108.964984)
		(end 372.531894 -109.12475)
		(width 0.1143)
		(layer "In2.Cu")
		(net "CLK_100M_PCH_SLOTX24_S4_DP")
	)
	(segment
		(start 458.070712 -6.037834)
		(end 460.2226 -3.885946)
		(width 0.1143)
		(layer "In2.Cu")
		(net "CLK_100M_PCH_SLOTX24_S4_DP")
	)
	(segment
		(start 402.509482 -20.256246)
		(end 402.639022 -20.450556)
		(width 0.1143)
		(layer "In2.Cu")
		(net "CLK_100M_PCH_SLOTX24_S4_DP")
	)
	(segment
		(start 430.000156 -15.256002)
		(end 432.35499 -14.776958)
		(width 0.1143)
		(layer "In2.Cu")
		(net "CLK_100M_PCH_SLOTX24_S4_DP")
	)
	(segment
		(start 365.207042 -59.897518)
		(end 365.43615 -59.851544)
		(width 0.1143)
		(layer "In2.Cu")
		(net "CLK_100M_PCH_SLOTX24_S4_DP")
	)
	(segment
		(start 361.709716 -68.577714)
		(end 362.075222 -67.056508)
		(width 0.1143)
		(layer "In2.Cu")
		(net "CLK_100M_PCH_SLOTX24_S4_DP")
	)
	(segment
		(start 460.2226 -3.57124)
		(end 460.70393 -3.08991)
		(width 0.1143)
		(layer "In2.Cu")
		(net "CLK_100M_PCH_SLOTX24_S4_DP")
	)
	(segment
		(start 369.023392 -99.448112)
		(end 368.799618 -98.392488)
		(width 0.1143)
		(layer "In2.Cu")
		(net "CLK_100M_PCH_SLOTX24_S4_DP")
	)
	(segment
		(start 448.859148 -9.869932)
		(end 450.567806 -8.73125)
		(width 0.1143)
		(layer "In2.Cu")
		(net "CLK_100M_PCH_SLOTX24_S4_DP")
	)
	(segment
		(start 368.477038 -94.580456)
		(end 365.875062 -91.057984)
		(width 0.1143)
		(layer "In2.Cu")
		(net "CLK_100M_PCH_SLOTX24_S4_DP")
	)
	(segment
		(start 428.79772 -15.0114)
		(end 430.000156 -15.256002)
		(width 0.1143)
		(layer "In2.Cu")
		(net "CLK_100M_PCH_SLOTX24_S4_DP")
	)
	(segment
		(start 403.635464 -20.649946)
		(end 403.971506 -20.717002)
		(width 0.1143)
		(layer "In2.Cu")
		(net "CLK_100M_PCH_SLOTX24_S4_DP")
	)
	(segment
		(start 439.340752 -13.302234)
		(end 440.627516 -13.55979)
		(width 0.1143)
		(layer "In2.Cu")
		(net "CLK_100M_PCH_SLOTX24_S4_DP")
	)
	(segment
		(start 407.679652 -19.589496)
		(end 408.176984 -19.258026)
		(width 0.1143)
		(layer "In2.Cu")
		(net "CLK_100M_PCH_SLOTX24_S4_DP")
	)
	(segment
		(start 378.556012 -22.595332)
		(end 379.026674 -22.230588)
		(width 0.1143)
		(layer "In2.Cu")
		(net "CLK_100M_PCH_SLOTX24_S4_DP")
	)
	(segment
		(start 370.073428 -107.058968)
		(end 369.52936 -104.451404)
		(width 0.1143)
		(layer "In2.Cu")
		(net "CLK_100M_PCH_SLOTX24_S4_DP")
	)
	(segment
		(start 406.899364 -20.75942)
		(end 407.679652 -19.589496)
		(width 0.1143)
		(layer "In2.Cu")
		(net "CLK_100M_PCH_SLOTX24_S4_DP")
	)
	(segment
		(start 397.558768 -20.198334)
		(end 400.176492 -19.789648)
		(width 0.1143)
		(layer "In2.Cu")
		(net "CLK_100M_PCH_SLOTX24_S4_DP")
	)
	(segment
		(start 404.165816 -20.587462)
		(end 405.962612 -20.946872)
		(width 0.1143)
		(layer "In2.Cu")
		(net "CLK_100M_PCH_SLOTX24_S4_DP")
	)
	(segment
		(start 368.353848 -102.60457)
		(end 369.023392 -99.448112)
		(width 0.1143)
		(layer "In2.Cu")
		(net "CLK_100M_PCH_SLOTX24_S4_DP")
	)
	(segment
		(start 363.662722 -87.416132)
		(end 363.468666 -87.286592)
		(width 0.1143)
		(layer "In2.Cu")
		(net "CLK_100M_PCH_SLOTX24_S4_DP")
	)
	(segment
		(start 436.993792 -14.199362)
		(end 439.340752 -13.302234)
		(width 0.1143)
		(layer "In2.Cu")
		(net "CLK_100M_PCH_SLOTX24_S4_DP")
	)
	(segment
		(start 368.69243 -103.401368)
		(end 368.478816 -103.133144)
		(width 0.1143)
		(layer "In2.Cu")
		(net "CLK_100M_PCH_SLOTX24_S4_DP")
	)
	(segment
		(start 368.924586 -103.42753)
		(end 368.69243 -103.401368)
		(width 0.1143)
		(layer "In2.Cu")
		(net "CLK_100M_PCH_SLOTX24_S4_DP")
	)
	(segment
		(start 366.209072 -58.692542)
		(end 366.163352 -58.463688)
		(width 0.1143)
		(layer "In2.Cu")
		(net "CLK_100M_PCH_SLOTX24_S4_DP")
	)
	(segment
		(start 364.10519 -83.432904)
		(end 363.4486 -80.336136)
		(width 0.1143)
		(layer "In2.Cu")
		(net "CLK_100M_PCH_SLOTX24_S4_DP")
	)
	(segment
		(start 397.331692 -20.233894)
		(end 397.558768 -20.198334)
		(width 0.1143)
		(layer "In2.Cu")
		(net "CLK_100M_PCH_SLOTX24_S4_DP")
	)
	(segment
		(start 379.52299 -21.537168)
		(end 379.995684 -20.572222)
		(width 0.1143)
		(layer "In2.Cu")
		(net "CLK_100M_PCH_SLOTX24_S4_DP")
	)
	(segment
		(start 459.678278 -4.386072)
		(end 459.678278 -3.755644)
		(width 0.127)
		(layer "F.Cu")
		(net "CLK_100M_PCH_SLOTX24_S4_DN")
	)
	(segment
		(start 459.678278 -3.755644)
		(end 459.925928 -3.507994)
		(width 0.127)
		(layer "F.Cu")
		(net "CLK_100M_PCH_SLOTX24_S4_DN")
	)
	(segment
		(start 374.718072 -108.545376)
		(end 374.549924 -108.545376)
		(width 0.0889)
		(layer "F.Cu")
		(net "CLK_100M_PCH_SLOTX24_S4_DN")
	)
	(segment
		(start 459.925928 -3.328162)
		(end 459.687676 -3.08991)
		(width 0.127)
		(layer "F.Cu")
		(net "CLK_100M_PCH_SLOTX24_S4_DN")
	)
	(segment
		(start 374.7262 -108.548678)
		(end 374.718072 -108.545376)
		(width 0.0889)
		(layer "F.Cu")
		(net "CLK_100M_PCH_SLOTX24_S4_DN")
	)
	(segment
		(start 375.92 -108.354876)
		(end 375.35993 -108.575094)
		(width 0.0889)
		(layer "F.Cu")
		(net "CLK_100M_PCH_SLOTX24_S4_DN")
	)
	(segment
		(start 459.687676 -3.08991)
		(end 459.43393 -3.08991)
		(width 0.127)
		(layer "F.Cu")
		(net "CLK_100M_PCH_SLOTX24_S4_DN")
	)
	(segment
		(start 375.216928 -108.66755)
		(end 375.012712 -108.66755)
		(width 0.0889)
		(layer "F.Cu")
		(net "CLK_100M_PCH_SLOTX24_S4_DN")
	)
	(segment
		(start 375.012712 -108.66755)
		(end 374.7262 -108.548678)
		(width 0.0889)
		(layer "F.Cu")
		(net "CLK_100M_PCH_SLOTX24_S4_DN")
	)
	(segment
		(start 374.310148 -108.3056)
		(end 373.764302 -108.3056)
		(width 0.0889)
		(layer "F.Cu")
		(net "CLK_100M_PCH_SLOTX24_S4_DN")
	)
	(segment
		(start 374.549924 -108.545376)
		(end 374.310148 -108.3056)
		(width 0.0889)
		(layer "F.Cu")
		(net "CLK_100M_PCH_SLOTX24_S4_DN")
	)
	(segment
		(start 459.925928 -3.507994)
		(end 459.925928 -3.328162)
		(width 0.127)
		(layer "F.Cu")
		(net "CLK_100M_PCH_SLOTX24_S4_DN")
	)
	(segment
		(start 373.764302 -108.3056)
		(end 373.3546 -108.715302)
		(width 0.0889)
		(layer "F.Cu")
		(net "CLK_100M_PCH_SLOTX24_S4_DN")
	)
	(segment
		(start 375.35993 -108.575094)
		(end 375.216928 -108.66755)
		(width 0.0889)
		(layer "F.Cu")
		(net "CLK_100M_PCH_SLOTX24_S4_DN")
	)
	(via
		(at 373.3546 -108.715302)
		(size 0.508)
		(drill 0.254)
		(layers "F.Cu" "B.Cu")
		(net "CLK_100M_PCH_SLOTX24_S4_DN")
	)
	(via
		(at 459.43393 -3.08991)
		(size 0.508)
		(drill 0.254)
		(layers "F.Cu" "B.Cu")
		(net "CLK_100M_PCH_SLOTX24_S4_DN")
	)
	(segment
		(start 379.768354 -20.371562)
		(end 381.112776 -19.488404)
		(width 0.1143)
		(layer "In2.Cu")
		(net "CLK_100M_PCH_SLOTX24_S4_DN")
	)
	(segment
		(start 363.1565 -80.36687)
		(end 363.1565 -76.803758)
		(width 0.1143)
		(layer "In2.Cu")
		(net "CLK_100M_PCH_SLOTX24_S4_DN")
	)
	(segment
		(start 365.670338 -91.272868)
		(end 363.705394 -89.962482)
		(width 0.1143)
		(layer "In2.Cu")
		(net "CLK_100M_PCH_SLOTX24_S4_DN")
	)
	(segment
		(start 443.813692 -12.964668)
		(end 445.72428 -12.582398)
		(width 0.1143)
		(layer "In2.Cu")
		(net "CLK_100M_PCH_SLOTX24_S4_DN")
	)
	(segment
		(start 447.47942 -11.412474)
		(end 448.237102 -10.275824)
		(width 0.1143)
		(layer "In2.Cu")
		(net "CLK_100M_PCH_SLOTX24_S4_DN")
	)
	(segment
		(start 440.605926 -13.25753)
		(end 442.392054 -12.624562)
		(width 0.1143)
		(layer "In2.Cu")
		(net "CLK_100M_PCH_SLOTX24_S4_DN")
	)
	(segment
		(start 442.392054 -12.624562)
		(end 443.813692 -12.964668)
		(width 0.1143)
		(layer "In2.Cu")
		(net "CLK_100M_PCH_SLOTX24_S4_DN")
	)
	(segment
		(start 378.418344 -22.332188)
		(end 378.813822 -22.02561)
		(width 0.1143)
		(layer "In2.Cu")
		(net "CLK_100M_PCH_SLOTX24_S4_DN")
	)
	(segment
		(start 368.204242 -94.703138)
		(end 365.670338 -91.272868)
		(width 0.1143)
		(layer "In2.Cu")
		(net "CLK_100M_PCH_SLOTX24_S4_DN")
	)
	(segment
		(start 371.288564 -28.909518)
		(end 375.52503 -23.242016)
		(width 0.1143)
		(layer "In2.Cu")
		(net "CLK_100M_PCH_SLOTX24_S4_DN")
	)
	(segment
		(start 415.407602 -17.514062)
		(end 417.20262 -17.872964)
		(width 0.1143)
		(layer "In2.Cu")
		(net "CLK_100M_PCH_SLOTX24_S4_DN")
	)
	(segment
		(start 372.653052 -109.41685)
		(end 371.716046 -109.41685)
		(width 0.1143)
		(layer "In2.Cu")
		(net "CLK_100M_PCH_SLOTX24_S4_DN")
	)
	(segment
		(start 378.813822 -22.02561)
		(end 379.271276 -21.3868)
		(width 0.1143)
		(layer "In2.Cu")
		(net "CLK_100M_PCH_SLOTX24_S4_DN")
	)
	(segment
		(start 425.939458 -15.334234)
		(end 426.62348 -15.473426)
		(width 0.1143)
		(layer "In2.Cu")
		(net "CLK_100M_PCH_SLOTX24_S4_DN")
	)
	(segment
		(start 361.41025 -68.57365)
		(end 361.816142 -66.883534)
		(width 0.1143)
		(layer "In2.Cu")
		(net "CLK_100M_PCH_SLOTX24_S4_DN")
	)
	(segment
		(start 434.7591 -13.188442)
		(end 435.664102 -13.370814)
		(width 0.1143)
		(layer "In2.Cu")
		(net "CLK_100M_PCH_SLOTX24_S4_DN")
	)
	(segment
		(start 368.054382 -102.608126)
		(end 368.724688 -99.448112)
		(width 0.1143)
		(layer "In2.Cu")
		(net "CLK_100M_PCH_SLOTX24_S4_DN")
	)
	(segment
		(start 363.1565 -76.803758)
		(end 361.41025 -68.57365)
		(width 0.1143)
		(layer "In2.Cu")
		(net "CLK_100M_PCH_SLOTX24_S4_DN")
	)
	(segment
		(start 427.837346 -14.929866)
		(end 427.87951 -14.887702)
		(width 0.1143)
		(layer "In2.Cu")
		(net "CLK_100M_PCH_SLOTX24_S4_DN")
	)
	(segment
		(start 368.212116 -54.863492)
		(end 368.866928 -51.564032)
		(width 0.1143)
		(layer "In2.Cu")
		(net "CLK_100M_PCH_SLOTX24_S4_DN")
	)
	(segment
		(start 363.705394 -89.962482)
		(end 363.103414 -86.950296)
		(width 0.1143)
		(layer "In2.Cu")
		(net "CLK_100M_PCH_SLOTX24_S4_DN")
	)
	(segment
		(start 397.558768 -19.902678)
		(end 400.182842 -19.492976)
		(width 0.1143)
		(layer "In2.Cu")
		(net "CLK_100M_PCH_SLOTX24_S4_DN")
	)
	(segment
		(start 436.23103 -13.74902)
		(end 436.968392 -13.89634)
		(width 0.1143)
		(layer "In2.Cu")
		(net "CLK_100M_PCH_SLOTX24_S4_DN")
	)
	(segment
		(start 427.87951 -14.887702)
		(end 427.940724 -14.887702)
		(width 0.1143)
		(layer "In2.Cu")
		(net "CLK_100M_PCH_SLOTX24_S4_DN")
	)
	(segment
		(start 426.62348 -15.473426)
		(end 427.190916 -15.357856)
		(width 0.1143)
		(layer "In2.Cu")
		(net "CLK_100M_PCH_SLOTX24_S4_DN")
	)
	(segment
		(start 364.191296 -60.892944)
		(end 368.212116 -54.863492)
		(width 0.1143)
		(layer "In2.Cu")
		(net "CLK_100M_PCH_SLOTX24_S4_DN")
	)
	(segment
		(start 369.257326 -104.579166)
		(end 368.209068 -103.262938)
		(width 0.1143)
		(layer "In2.Cu")
		(net "CLK_100M_PCH_SLOTX24_S4_DN")
	)
	(segment
		(start 422.478708 -16.014446)
		(end 425.822872 -15.33398)
		(width 0.1143)
		(layer "In2.Cu")
		(net "CLK_100M_PCH_SLOTX24_S4_DN")
	)
	(segment
		(start 405.962612 -20.64893)
		(end 406.723342 -20.49653)
		(width 0.1143)
		(layer "In2.Cu")
		(net "CLK_100M_PCH_SLOTX24_S4_DN")
	)
	(segment
		(start 368.866928 -51.564032)
		(end 367.92662 -48.600614)
		(width 0.1143)
		(layer "In2.Cu")
		(net "CLK_100M_PCH_SLOTX24_S4_DN")
	)
	(segment
		(start 433.987956 -13.34516)
		(end 434.7591 -13.188442)
		(width 0.1143)
		(layer "In2.Cu")
		(net "CLK_100M_PCH_SLOTX24_S4_DN")
	)
	(segment
		(start 459.9305 -3.58648)
		(end 459.43393 -3.08991)
		(width 0.1143)
		(layer "In2.Cu")
		(net "CLK_100M_PCH_SLOTX24_S4_DN")
	)
	(segment
		(start 375.52503 -23.242016)
		(end 378.418344 -22.332188)
		(width 0.1143)
		(layer "In2.Cu")
		(net "CLK_100M_PCH_SLOTX24_S4_DN")
	)
	(segment
		(start 371.716046 -109.41685)
		(end 370.496592 -108.197142)
		(width 0.1143)
		(layer "In2.Cu")
		(net "CLK_100M_PCH_SLOTX24_S4_DN")
	)
	(segment
		(start 373.3546 -108.715302)
		(end 372.653052 -109.41685)
		(width 0.1143)
		(layer "In2.Cu")
		(net "CLK_100M_PCH_SLOTX24_S4_DN")
	)
	(segment
		(start 379.271276 -21.3868)
		(end 379.768354 -20.371562)
		(width 0.1143)
		(layer "In2.Cu")
		(net "CLK_100M_PCH_SLOTX24_S4_DN")
	)
	(segment
		(start 363.80674 -83.434682)
		(end 363.1565 -80.36687)
		(width 0.1143)
		(layer "In2.Cu")
		(net "CLK_100M_PCH_SLOTX24_S4_DN")
	)
	(segment
		(start 369.880388 -35.533076)
		(end 371.288564 -28.909518)
		(width 0.1143)
		(layer "In2.Cu")
		(net "CLK_100M_PCH_SLOTX24_S4_DN")
	)
	(segment
		(start 363.123988 -65.930526)
		(end 364.191296 -60.892944)
		(width 0.1143)
		(layer "In2.Cu")
		(net "CLK_100M_PCH_SLOTX24_S4_DN")
	)
	(segment
		(start 397.341852 -19.93646)
		(end 397.558768 -19.902678)
		(width 0.1143)
		(layer "In2.Cu")
		(net "CLK_100M_PCH_SLOTX24_S4_DN")
	)
	(segment
		(start 432.240944 -14.501876)
		(end 433.987956 -13.34516)
		(width 0.1143)
		(layer "In2.Cu")
		(net "CLK_100M_PCH_SLOTX24_S4_DN")
	)
	(segment
		(start 417.20262 -17.872964)
		(end 422.478708 -16.014446)
		(width 0.1143)
		(layer "In2.Cu")
		(net "CLK_100M_PCH_SLOTX24_S4_DN")
	)
	(segment
		(start 369.799616 -107.17657)
		(end 369.257326 -104.579166)
		(width 0.1143)
		(layer "In2.Cu")
		(net "CLK_100M_PCH_SLOTX24_S4_DN")
	)
	(segment
		(start 388.661656 -17.844262)
		(end 394.927074 -19.388582)
		(width 0.1143)
		(layer "In2.Cu")
		(net "CLK_100M_PCH_SLOTX24_S4_DN")
	)
	(segment
		(start 430.000156 -14.957806)
		(end 432.240944 -14.501876)
		(width 0.1143)
		(layer "In2.Cu")
		(net "CLK_100M_PCH_SLOTX24_S4_DN")
	)
	(segment
		(start 394.927074 -19.388582)
		(end 397.341852 -19.93646)
		(width 0.1143)
		(layer "In2.Cu")
		(net "CLK_100M_PCH_SLOTX24_S4_DN")
	)
	(segment
		(start 448.237102 -10.275824)
		(end 448.648328 -9.659112)
		(width 0.1143)
		(layer "In2.Cu")
		(net "CLK_100M_PCH_SLOTX24_S4_DN")
	)
	(segment
		(start 445.72428 -12.582398)
		(end 447.47942 -11.412474)
		(width 0.1143)
		(layer "In2.Cu")
		(net "CLK_100M_PCH_SLOTX24_S4_DN")
	)
	(segment
		(start 370.496592 -108.197142)
		(end 369.799616 -107.17657)
		(width 0.1143)
		(layer "In2.Cu")
		(net "CLK_100M_PCH_SLOTX24_S4_DN")
	)
	(segment
		(start 369.566698 -39.486332)
		(end 370.275612 -36.899596)
		(width 0.1143)
		(layer "In2.Cu")
		(net "CLK_100M_PCH_SLOTX24_S4_DN")
	)
	(segment
		(start 435.664102 -13.370814)
		(end 436.23103 -13.74902)
		(width 0.1143)
		(layer "In2.Cu")
		(net "CLK_100M_PCH_SLOTX24_S4_DN")
	)
	(segment
		(start 381.112776 -19.488404)
		(end 388.661656 -17.844262)
		(width 0.1143)
		(layer "In2.Cu")
		(net "CLK_100M_PCH_SLOTX24_S4_DN")
	)
	(segment
		(start 367.92662 -48.600614)
		(end 370.055394 -41.86936)
		(width 0.1143)
		(layer "In2.Cu")
		(net "CLK_100M_PCH_SLOTX24_S4_DN")
	)
	(segment
		(start 363.103414 -86.950296)
		(end 363.80674 -83.434682)
		(width 0.1143)
		(layer "In2.Cu")
		(net "CLK_100M_PCH_SLOTX24_S4_DN")
	)
	(segment
		(start 436.968392 -13.89634)
		(end 439.315352 -12.999212)
		(width 0.1143)
		(layer "In2.Cu")
		(net "CLK_100M_PCH_SLOTX24_S4_DN")
	)
	(segment
		(start 406.723342 -20.49653)
		(end 407.468832 -19.378676)
		(width 0.1143)
		(layer "In2.Cu")
		(net "CLK_100M_PCH_SLOTX24_S4_DN")
	)
	(segment
		(start 370.055394 -41.86936)
		(end 369.566698 -39.486332)
		(width 0.1143)
		(layer "In2.Cu")
		(net "CLK_100M_PCH_SLOTX24_S4_DN")
	)
	(segment
		(start 455.400918 -7.466584)
		(end 457.88453 -5.810758)
		(width 0.1143)
		(layer "In2.Cu")
		(net "CLK_100M_PCH_SLOTX24_S4_DN")
	)
	(segment
		(start 450.506084 -8.421116)
		(end 450.567806 -8.433308)
		(width 0.1143)
		(layer "In2.Cu")
		(net "CLK_100M_PCH_SLOTX24_S4_DN")
	)
	(segment
		(start 448.648328 -9.659112)
		(end 450.506084 -8.421116)
		(width 0.1143)
		(layer "In2.Cu")
		(net "CLK_100M_PCH_SLOTX24_S4_DN")
	)
	(segment
		(start 368.724688 -99.448112)
		(end 368.507518 -98.423222)
		(width 0.1143)
		(layer "In2.Cu")
		(net "CLK_100M_PCH_SLOTX24_S4_DN")
	)
	(segment
		(start 400.182842 -19.492976)
		(end 405.962612 -20.64893)
		(width 0.1143)
		(layer "In2.Cu")
		(net "CLK_100M_PCH_SLOTX24_S4_DN")
	)
	(segment
		(start 425.822872 -15.33398)
		(end 425.823126 -15.334234)
		(width 0.1143)
		(layer "In2.Cu")
		(net "CLK_100M_PCH_SLOTX24_S4_DN")
	)
	(segment
		(start 408.062938 -18.982944)
		(end 415.407602 -17.514062)
		(width 0.1143)
		(layer "In2.Cu")
		(net "CLK_100M_PCH_SLOTX24_S4_DN")
	)
	(segment
		(start 439.315352 -12.999212)
		(end 440.605926 -13.25753)
		(width 0.1143)
		(layer "In2.Cu")
		(net "CLK_100M_PCH_SLOTX24_S4_DN")
	)
	(segment
		(start 368.209068 -103.262938)
		(end 368.054382 -102.608126)
		(width 0.1143)
		(layer "In2.Cu")
		(net "CLK_100M_PCH_SLOTX24_S4_DN")
	)
	(segment
		(start 370.275612 -36.899596)
		(end 369.880388 -35.533076)
		(width 0.1143)
		(layer "In2.Cu")
		(net "CLK_100M_PCH_SLOTX24_S4_DN")
	)
	(segment
		(start 407.468832 -19.378676)
		(end 408.062938 -18.982944)
		(width 0.1143)
		(layer "In2.Cu")
		(net "CLK_100M_PCH_SLOTX24_S4_DN")
	)
	(segment
		(start 459.9305 -3.764788)
		(end 459.9305 -3.58648)
		(width 0.1143)
		(layer "In2.Cu")
		(net "CLK_100M_PCH_SLOTX24_S4_DN")
	)
	(segment
		(start 427.190916 -15.357856)
		(end 427.837346 -14.929866)
		(width 0.1143)
		(layer "In2.Cu")
		(net "CLK_100M_PCH_SLOTX24_S4_DN")
	)
	(segment
		(start 457.88453 -5.810758)
		(end 459.9305 -3.764788)
		(width 0.1143)
		(layer "In2.Cu")
		(net "CLK_100M_PCH_SLOTX24_S4_DN")
	)
	(segment
		(start 368.507518 -96.129856)
		(end 368.204242 -94.703138)
		(width 0.1143)
		(layer "In2.Cu")
		(net "CLK_100M_PCH_SLOTX24_S4_DN")
	)
	(segment
		(start 427.940724 -14.887702)
		(end 428.79772 -14.713204)
		(width 0.1143)
		(layer "In2.Cu")
		(net "CLK_100M_PCH_SLOTX24_S4_DN")
	)
	(segment
		(start 450.567806 -8.433308)
		(end 455.400918 -7.466584)
		(width 0.1143)
		(layer "In2.Cu")
		(net "CLK_100M_PCH_SLOTX24_S4_DN")
	)
	(segment
		(start 428.79772 -14.713204)
		(end 430.000156 -14.957806)
		(width 0.1143)
		(layer "In2.Cu")
		(net "CLK_100M_PCH_SLOTX24_S4_DN")
	)
	(segment
		(start 368.507518 -98.423222)
		(end 368.507518 -96.129856)
		(width 0.1143)
		(layer "In2.Cu")
		(net "CLK_100M_PCH_SLOTX24_S4_DN")
	)
	(segment
		(start 361.816142 -66.883534)
		(end 363.123988 -65.930526)
		(width 0.1143)
		(layer "In2.Cu")
		(net "CLK_100M_PCH_SLOTX24_S4_DN")
	)
	(segment
		(start 425.823126 -15.334234)
		(end 425.939458 -15.334234)
		(width 0.1143)
		(layer "In2.Cu")
		(net "CLK_100M_PCH_SLOTX24_S4_DN")
	)
	(segment
		(start 458.878178 -8.539988)
		(end 458.878178 -7.789672)
		(width 0.127)
		(layer "F.Cu")
		(net "CLK_100M_PCH_SLOTX24_S0_DP")
	)
	(segment
		(start 458.630528 -8.787638)
		(end 458.878178 -8.539988)
		(width 0.127)
		(layer "F.Cu")
		(net "CLK_100M_PCH_SLOTX24_S0_DP")
	)
	(segment
		(start 458.630528 -9.08939)
		(end 458.630528 -8.787638)
		(width 0.127)
		(layer "F.Cu")
		(net "CLK_100M_PCH_SLOTX24_S0_DP")
	)
	(segment
		(start 377.33605 -108.13796)
		(end 377.825 -107.8484)
		(width 0.127)
		(layer "F.Cu")
		(net "CLK_100M_PCH_SLOTX24_S0_DP")
	)
	(segment
		(start 458.837538 -9.2964)
		(end 458.630528 -9.08939)
		(width 0.127)
		(layer "F.Cu")
		(net "CLK_100M_PCH_SLOTX24_S0_DP")
	)
	(segment
		(start 458.837538 -9.681718)
		(end 458.837538 -9.2964)
		(width 0.127)
		(layer "F.Cu")
		(net "CLK_100M_PCH_SLOTX24_S0_DP")
	)
	(segment
		(start 459.324202 -10.168382)
		(end 458.837538 -9.681718)
		(width 0.127)
		(layer "F.Cu")
		(net "CLK_100M_PCH_SLOTX24_S0_DP")
	)
	(via
		(at 459.324202 -10.168382)
		(size 0.508)
		(drill 0.254)
		(layers "F.Cu" "B.Cu")
		(net "CLK_100M_PCH_SLOTX24_S0_DP")
	)
	(via
		(at 377.825 -107.8484)
		(size 0.508)
		(drill 0.254)
		(layers "F.Cu" "B.Cu")
		(net "CLK_100M_PCH_SLOTX24_S0_DP")
	)
	(segment
		(start 363.531404 -70.753478)
		(end 363.531658 -70.753478)
		(width 0.1143)
		(layer "In2.Cu")
		(net "CLK_100M_PCH_SLOTX24_S0_DP")
	)
	(segment
		(start 367.904268 -61.146944)
		(end 367.75136 -61.934344)
		(width 0.1143)
		(layer "In2.Cu")
		(net "CLK_100M_PCH_SLOTX24_S0_DP")
	)
	(segment
		(start 374.029478 -107.3023)
		(end 374.080278 -107.3531)
		(width 0.0889)
		(layer "In2.Cu")
		(net "CLK_100M_PCH_SLOTX24_S0_DP")
	)
	(segment
		(start 374.811798 -107.763564)
		(end 374.982486 -107.763564)
		(width 0.0889)
		(layer "In2.Cu")
		(net "CLK_100M_PCH_SLOTX24_S0_DP")
	)
	(segment
		(start 394.87729 -21.343366)
		(end 394.546074 -21.254466)
		(width 0.1143)
		(layer "In2.Cu")
		(net "CLK_100M_PCH_SLOTX24_S0_DP")
	)
	(segment
		(start 427.47819 -17.680432)
		(end 426.875194 -18.07972)
		(width 0.1143)
		(layer "In2.Cu")
		(net "CLK_100M_PCH_SLOTX24_S0_DP")
	)
	(segment
		(start 375.898918 -25.393396)
		(end 372.76913 -29.580332)
		(width 0.1143)
		(layer "In2.Cu")
		(net "CLK_100M_PCH_SLOTX24_S0_DP")
	)
	(segment
		(start 371.925088 -36.888674)
		(end 371.198394 -39.540942)
		(width 0.1143)
		(layer "In2.Cu")
		(net "CLK_100M_PCH_SLOTX24_S0_DP")
	)
	(segment
		(start 449.710556 -12.130278)
		(end 443.982094 -15.949676)
		(width 0.1143)
		(layer "In2.Cu")
		(net "CLK_100M_PCH_SLOTX24_S0_DP")
	)
	(segment
		(start 404.502874 -22.983698)
		(end 401.61718 -22.983698)
		(width 0.1143)
		(layer "In2.Cu")
		(net "CLK_100M_PCH_SLOTX24_S0_DP")
	)
	(segment
		(start 371.515894 -35.473894)
		(end 371.925088 -36.888674)
		(width 0.1143)
		(layer "In2.Cu")
		(net "CLK_100M_PCH_SLOTX24_S0_DP")
	)
	(segment
		(start 369.655852 -93.851476)
		(end 370.667026 -94.204028)
		(width 0.1143)
		(layer "In2.Cu")
		(net "CLK_100M_PCH_SLOTX24_S0_DP")
	)
	(segment
		(start 443.000638 -16.21282)
		(end 442.669422 -16.301466)
		(width 0.1143)
		(layer "In2.Cu")
		(net "CLK_100M_PCH_SLOTX24_S0_DP")
	)
	(segment
		(start 371.198394 -39.540942)
		(end 371.78742 -42.411142)
		(width 0.1143)
		(layer "In2.Cu")
		(net "CLK_100M_PCH_SLOTX24_S0_DP")
	)
	(segment
		(start 426.875194 -18.07972)
		(end 425.842938 -18.289524)
		(width 0.1143)
		(layer "In2.Cu")
		(net "CLK_100M_PCH_SLOTX24_S0_DP")
	)
	(segment
		(start 365.10468 -87.1474)
		(end 365.524542 -89.247726)
		(width 0.1143)
		(layer "In2.Cu")
		(net "CLK_100M_PCH_SLOTX24_S0_DP")
	)
	(segment
		(start 369.766088 -48.79848)
		(end 370.59108 -51.398932)
		(width 0.1143)
		(layer "In2.Cu")
		(net "CLK_100M_PCH_SLOTX24_S0_DP")
	)
	(segment
		(start 410.361384 -23.078948)
		(end 409.56484 -23.814024)
		(width 0.1143)
		(layer "In2.Cu")
		(net "CLK_100M_PCH_SLOTX24_S0_DP")
	)
	(segment
		(start 415.728658 -22.075394)
		(end 415.673286 -22.047708)
		(width 0.1143)
		(layer "In2.Cu")
		(net "CLK_100M_PCH_SLOTX24_S0_DP")
	)
	(segment
		(start 458.85862 -10.633964)
		(end 458.85862 -11.409934)
		(width 0.1143)
		(layer "In2.Cu")
		(net "CLK_100M_PCH_SLOTX24_S0_DP")
	)
	(segment
		(start 367.75136 -61.934344)
		(end 367.251742 -62.675008)
		(width 0.1143)
		(layer "In2.Cu")
		(net "CLK_100M_PCH_SLOTX24_S0_DP")
	)
	(segment
		(start 383.337054 -21.062696)
		(end 381.15367 -24.035258)
		(width 0.1143)
		(layer "In2.Cu")
		(net "CLK_100M_PCH_SLOTX24_S0_DP")
	)
	(segment
		(start 417.035742 -21.795994)
		(end 416.997642 -21.820886)
		(width 0.1143)
		(layer "In2.Cu")
		(net "CLK_100M_PCH_SLOTX24_S0_DP")
	)
	(segment
		(start 450.8627 -11.8999)
		(end 449.710556 -12.130278)
		(width 0.1143)
		(layer "In2.Cu")
		(net "CLK_100M_PCH_SLOTX24_S0_DP")
	)
	(segment
		(start 458.16393 -12.33805)
		(end 457.921614 -12.580366)
		(width 0.1143)
		(layer "In2.Cu")
		(net "CLK_100M_PCH_SLOTX24_S0_DP")
	)
	(segment
		(start 374.00738 -107.3023)
		(end 374.029478 -107.3023)
		(width 0.0889)
		(layer "In2.Cu")
		(net "CLK_100M_PCH_SLOTX24_S0_DP")
	)
	(segment
		(start 435.849776 -16.016732)
		(end 434.676042 -16.793718)
		(width 0.1143)
		(layer "In2.Cu")
		(net "CLK_100M_PCH_SLOTX24_S0_DP")
	)
	(segment
		(start 376.86742 -107.763564)
		(end 377.380246 -108.27639)
		(width 0.0889)
		(layer "In2.Cu")
		(net "CLK_100M_PCH_SLOTX24_S0_DP")
	)
	(segment
		(start 394.546074 -21.254466)
		(end 394.429488 -21.052028)
		(width 0.1143)
		(layer "In2.Cu")
		(net "CLK_100M_PCH_SLOTX24_S0_DP")
	)
	(segment
		(start 366.487964 -64.41186)
		(end 366.19688 -64.8716)
		(width 0.1143)
		(layer "In2.Cu")
		(net "CLK_100M_PCH_SLOTX24_S0_DP")
	)
	(segment
		(start 372.76913 -29.580332)
		(end 371.515894 -35.473894)
		(width 0.1143)
		(layer "In2.Cu")
		(net "CLK_100M_PCH_SLOTX24_S0_DP")
	)
	(segment
		(start 364.744 -76.48321)
		(end 364.744 -80.163162)
		(width 0.1143)
		(layer "In2.Cu")
		(net "CLK_100M_PCH_SLOTX24_S0_DP")
	)
	(segment
		(start 371.00383 -94.892114)
		(end 370.778024 -95.870268)
		(width 0.1143)
		(layer "In2.Cu")
		(net "CLK_100M_PCH_SLOTX24_S0_DP")
	)
	(segment
		(start 419.217602 -21.076158)
		(end 417.035742 -21.795994)
		(width 0.1143)
		(layer "In2.Cu")
		(net "CLK_100M_PCH_SLOTX24_S0_DP")
	)
	(segment
		(start 375.071386 -107.674664)
		(end 375.350786 -107.674664)
		(width 0.0889)
		(layer "In2.Cu")
		(net "CLK_100M_PCH_SLOTX24_S0_DP")
	)
	(segment
		(start 368.939318 -59.65571)
		(end 368.144044 -60.790836)
		(width 0.1143)
		(layer "In2.Cu")
		(net "CLK_100M_PCH_SLOTX24_S0_DP")
	)
	(segment
		(start 439.323734 -15.772638)
		(end 438.18556 -15.545054)
		(width 0.1143)
		(layer "In2.Cu")
		(net "CLK_100M_PCH_SLOTX24_S0_DP")
	)
	(segment
		(start 443.534292 -16.24076)
		(end 443.203076 -16.329406)
		(width 0.1143)
		(layer "In2.Cu")
		(net "CLK_100M_PCH_SLOTX24_S0_DP")
	)
	(segment
		(start 375.439686 -107.763564)
		(end 375.719086 -107.763564)
		(width 0.0889)
		(layer "In2.Cu")
		(net "CLK_100M_PCH_SLOTX24_S0_DP")
	)
	(segment
		(start 414.714182 -21.855684)
		(end 414.713674 -21.856192)
		(width 0.1143)
		(layer "In2.Cu")
		(net "CLK_100M_PCH_SLOTX24_S0_DP")
	)
	(segment
		(start 429.923194 -17.183608)
		(end 427.47819 -17.680432)
		(width 0.1143)
		(layer "In2.Cu")
		(net "CLK_100M_PCH_SLOTX24_S0_DP")
	)
	(segment
		(start 379.266704 -24.747474)
		(end 378.621036 -24.591264)
		(width 0.1143)
		(layer "In2.Cu")
		(net "CLK_100M_PCH_SLOTX24_S0_DP")
	)
	(segment
		(start 367.189512 -90.357706)
		(end 369.655852 -93.851476)
		(width 0.1143)
		(layer "In2.Cu")
		(net "CLK_100M_PCH_SLOTX24_S0_DP")
	)
	(segment
		(start 442.552836 -16.503904)
		(end 442.22162 -16.59255)
		(width 0.1143)
		(layer "In2.Cu")
		(net "CLK_100M_PCH_SLOTX24_S0_DP")
	)
	(segment
		(start 442.669422 -16.301466)
		(end 442.552836 -16.503904)
		(width 0.1143)
		(layer "In2.Cu")
		(net "CLK_100M_PCH_SLOTX24_S0_DP")
	)
	(segment
		(start 441.585096 -16.592296)
		(end 440.111642 -16.29791)
		(width 0.1143)
		(layer "In2.Cu")
		(net "CLK_100M_PCH_SLOTX24_S0_DP")
	)
	(segment
		(start 374.080278 -107.3531)
		(end 374.401334 -107.3531)
		(width 0.0889)
		(layer "In2.Cu")
		(net "CLK_100M_PCH_SLOTX24_S0_DP")
	)
	(segment
		(start 407.113232 -24.569928)
		(end 406.515824 -23.972774)
		(width 0.1143)
		(layer "In2.Cu")
		(net "CLK_100M_PCH_SLOTX24_S0_DP")
	)
	(segment
		(start 455.328274 -13.548106)
		(end 454.095866 -13.301472)
		(width 0.1143)
		(layer "In2.Cu")
		(net "CLK_100M_PCH_SLOTX24_S0_DP")
	)
	(segment
		(start 458.85862 -11.409934)
		(end 458.16393 -12.104624)
		(width 0.1143)
		(layer "In2.Cu")
		(net "CLK_100M_PCH_SLOTX24_S0_DP")
	)
	(segment
		(start 395.079474 -21.22678)
		(end 394.87729 -21.343366)
		(width 0.1143)
		(layer "In2.Cu")
		(net "CLK_100M_PCH_SLOTX24_S0_DP")
	)
	(segment
		(start 425.842938 -18.289524)
		(end 424.597068 -18.781522)
		(width 0.1143)
		(layer "In2.Cu")
		(net "CLK_100M_PCH_SLOTX24_S0_DP")
	)
	(segment
		(start 383.789682 -20.876768)
		(end 383.337054 -21.062696)
		(width 0.1143)
		(layer "In2.Cu")
		(net "CLK_100M_PCH_SLOTX24_S0_DP")
	)
	(segment
		(start 365.319564 -66.464942)
		(end 363.68863 -68.531486)
		(width 0.1143)
		(layer "In2.Cu")
		(net "CLK_100M_PCH_SLOTX24_S0_DP")
	)
	(segment
		(start 409.56484 -23.814024)
		(end 408.053032 -24.569928)
		(width 0.1143)
		(layer "In2.Cu")
		(net "CLK_100M_PCH_SLOTX24_S0_DP")
	)
	(segment
		(start 363.68863 -68.531486)
		(end 363.876844 -69.315838)
		(width 0.1143)
		(layer "In2.Cu")
		(net "CLK_100M_PCH_SLOTX24_S0_DP")
	)
	(segment
		(start 381.15367 -24.035258)
		(end 379.266704 -24.747474)
		(width 0.1143)
		(layer "In2.Cu")
		(net "CLK_100M_PCH_SLOTX24_S0_DP")
	)
	(segment
		(start 412.716472 -22.25548)
		(end 410.361384 -23.078948)
		(width 0.1143)
		(layer "In2.Cu")
		(net "CLK_100M_PCH_SLOTX24_S0_DP")
	)
	(segment
		(start 371.995446 -107.3023)
		(end 374.00738 -107.3023)
		(width 0.1143)
		(layer "In2.Cu")
		(net "CLK_100M_PCH_SLOTX24_S0_DP")
	)
	(segment
		(start 434.676042 -16.793718)
		(end 431.342546 -17.472152)
		(width 0.1143)
		(layer "In2.Cu")
		(net "CLK_100M_PCH_SLOTX24_S0_DP")
	)
	(segment
		(start 366.19688 -64.8716)
		(end 365.915702 -66.114676)
		(width 0.1143)
		(layer "In2.Cu")
		(net "CLK_100M_PCH_SLOTX24_S0_DP")
	)
	(segment
		(start 442.22162 -16.59255)
		(end 442.019436 -16.475964)
		(width 0.1143)
		(layer "In2.Cu")
		(net "CLK_100M_PCH_SLOTX24_S0_DP")
	)
	(segment
		(start 415.673286 -22.047708)
		(end 414.714182 -21.855684)
		(width 0.1143)
		(layer "In2.Cu")
		(net "CLK_100M_PCH_SLOTX24_S0_DP")
	)
	(segment
		(start 376.176286 -107.763564)
		(end 376.86742 -107.763564)
		(width 0.0889)
		(layer "In2.Cu")
		(net "CLK_100M_PCH_SLOTX24_S0_DP")
	)
	(segment
		(start 374.982486 -107.763564)
		(end 375.071386 -107.674664)
		(width 0.0889)
		(layer "In2.Cu")
		(net "CLK_100M_PCH_SLOTX24_S0_DP")
	)
	(segment
		(start 401.61718 -22.983698)
		(end 395.079474 -21.22678)
		(width 0.1143)
		(layer "In2.Cu")
		(net "CLK_100M_PCH_SLOTX24_S0_DP")
	)
	(segment
		(start 458.16393 -12.104624)
		(end 458.16393 -12.33805)
		(width 0.1143)
		(layer "In2.Cu")
		(net "CLK_100M_PCH_SLOTX24_S0_DP")
	)
	(segment
		(start 454.095866 -13.301472)
		(end 452.477886 -12.222988)
		(width 0.1143)
		(layer "In2.Cu")
		(net "CLK_100M_PCH_SLOTX24_S0_DP")
	)
	(segment
		(start 370.778024 -98.682556)
		(end 370.636292 -99.22002)
		(width 0.1143)
		(layer "In2.Cu")
		(net "CLK_100M_PCH_SLOTX24_S0_DP")
	)
	(segment
		(start 370.778024 -95.870268)
		(end 370.778024 -98.682556)
		(width 0.1143)
		(layer "In2.Cu")
		(net "CLK_100M_PCH_SLOTX24_S0_DP")
	)
	(segment
		(start 440.111642 -16.29791)
		(end 439.323734 -15.772638)
		(width 0.1143)
		(layer "In2.Cu")
		(net "CLK_100M_PCH_SLOTX24_S0_DP")
	)
	(segment
		(start 452.477886 -12.222988)
		(end 450.8627 -11.8999)
		(width 0.1143)
		(layer "In2.Cu")
		(net "CLK_100M_PCH_SLOTX24_S0_DP")
	)
	(segment
		(start 375.350786 -107.674664)
		(end 375.439686 -107.763564)
		(width 0.0889)
		(layer "In2.Cu")
		(net "CLK_100M_PCH_SLOTX24_S0_DP")
	)
	(segment
		(start 370.636292 -99.22002)
		(end 370.41328 -99.383342)
		(width 0.1143)
		(layer "In2.Cu")
		(net "CLK_100M_PCH_SLOTX24_S0_DP")
	)
	(segment
		(start 406.38349 -23.458932)
		(end 406.324816 -23.422102)
		(width 0.1143)
		(layer "In2.Cu")
		(net "CLK_100M_PCH_SLOTX24_S0_DP")
	)
	(segment
		(start 438.18556 -15.545054)
		(end 435.849776 -16.016732)
		(width 0.1143)
		(layer "In2.Cu")
		(net "CLK_100M_PCH_SLOTX24_S0_DP")
	)
	(segment
		(start 414.713674 -21.856192)
		(end 412.716472 -22.25548)
		(width 0.1143)
		(layer "In2.Cu")
		(net "CLK_100M_PCH_SLOTX24_S0_DP")
	)
	(segment
		(start 378.621036 -24.591264)
		(end 375.898918 -25.393396)
		(width 0.1143)
		(layer "In2.Cu")
		(net "CLK_100M_PCH_SLOTX24_S0_DP")
	)
	(segment
		(start 416.997642 -21.820886)
		(end 416.898074 -21.841206)
		(width 0.1143)
		(layer "In2.Cu")
		(net "CLK_100M_PCH_SLOTX24_S0_DP")
	)
	(segment
		(start 408.053032 -24.569928)
		(end 407.113232 -24.569928)
		(width 0.1143)
		(layer "In2.Cu")
		(net "CLK_100M_PCH_SLOTX24_S0_DP")
	)
	(segment
		(start 431.342546 -17.472152)
		(end 429.923194 -17.183608)
		(width 0.1143)
		(layer "In2.Cu")
		(net "CLK_100M_PCH_SLOTX24_S0_DP")
	)
	(segment
		(start 416.744658 -21.871686)
		(end 415.728658 -22.075394)
		(width 0.1143)
		(layer "In2.Cu")
		(net "CLK_100M_PCH_SLOTX24_S0_DP")
	)
	(segment
		(start 370.100098 -100.635308)
		(end 371.269514 -106.256836)
		(width 0.1143)
		(layer "In2.Cu")
		(net "CLK_100M_PCH_SLOTX24_S0_DP")
	)
	(segment
		(start 370.59108 -51.398932)
		(end 368.939318 -59.65571)
		(width 0.1143)
		(layer "In2.Cu")
		(net "CLK_100M_PCH_SLOTX24_S0_DP")
	)
	(segment
		(start 377.380246 -108.27639)
		(end 377.825 -108.27639)
		(width 0.0889)
		(layer "In2.Cu")
		(net "CLK_100M_PCH_SLOTX24_S0_DP")
	)
	(segment
		(start 366.39119 -63.92418)
		(end 366.487964 -64.41186)
		(width 0.1143)
		(layer "In2.Cu")
		(net "CLK_100M_PCH_SLOTX24_S0_DP")
	)
	(segment
		(start 394.429488 -21.052028)
		(end 392.576812 -20.554188)
		(width 0.1143)
		(layer "In2.Cu")
		(net "CLK_100M_PCH_SLOTX24_S0_DP")
	)
	(segment
		(start 367.251742 -62.675008)
		(end 366.809782 -62.97295)
		(width 0.1143)
		(layer "In2.Cu")
		(net "CLK_100M_PCH_SLOTX24_S0_DP")
	)
	(segment
		(start 371.644926 -106.951526)
		(end 371.995446 -107.3023)
		(width 0.1143)
		(layer "In2.Cu")
		(net "CLK_100M_PCH_SLOTX24_S0_DP")
	)
	(segment
		(start 459.324202 -10.168382)
		(end 458.85862 -10.633964)
		(width 0.1143)
		(layer "In2.Cu")
		(net "CLK_100M_PCH_SLOTX24_S0_DP")
	)
	(segment
		(start 364.744 -80.163162)
		(end 365.64824 -84.4296)
		(width 0.1143)
		(layer "In2.Cu")
		(net "CLK_100M_PCH_SLOTX24_S0_DP")
	)
	(segment
		(start 406.324816 -23.422102)
		(end 404.502874 -22.983698)
		(width 0.1143)
		(layer "In2.Cu")
		(net "CLK_100M_PCH_SLOTX24_S0_DP")
	)
	(segment
		(start 366.809782 -62.97295)
		(end 366.39119 -63.92418)
		(width 0.1143)
		(layer "In2.Cu")
		(net "CLK_100M_PCH_SLOTX24_S0_DP")
	)
	(segment
		(start 392.576812 -20.554188)
		(end 388.671054 -22.042628)
		(width 0.1143)
		(layer "In2.Cu")
		(net "CLK_100M_PCH_SLOTX24_S0_DP")
	)
	(segment
		(start 375.719086 -107.763564)
		(end 375.807986 -107.674664)
		(width 0.0889)
		(layer "In2.Cu")
		(net "CLK_100M_PCH_SLOTX24_S0_DP")
	)
	(segment
		(start 443.650878 -16.038576)
		(end 443.534292 -16.24076)
		(width 0.1143)
		(layer "In2.Cu")
		(net "CLK_100M_PCH_SLOTX24_S0_DP")
	)
	(segment
		(start 365.524542 -89.247726)
		(end 367.189512 -90.357706)
		(width 0.1143)
		(layer "In2.Cu")
		(net "CLK_100M_PCH_SLOTX24_S0_DP")
	)
	(segment
		(start 371.78742 -42.411142)
		(end 369.766088 -48.79848)
		(width 0.1143)
		(layer "In2.Cu")
		(net "CLK_100M_PCH_SLOTX24_S0_DP")
	)
	(segment
		(start 363.531404 -70.753732)
		(end 364.744 -76.48321)
		(width 0.1143)
		(layer "In2.Cu")
		(net "CLK_100M_PCH_SLOTX24_S0_DP")
	)
	(segment
		(start 375.807986 -107.674664)
		(end 376.087386 -107.674664)
		(width 0.0889)
		(layer "In2.Cu")
		(net "CLK_100M_PCH_SLOTX24_S0_DP")
	)
	(segment
		(start 406.515824 -23.972774)
		(end 406.38349 -23.458932)
		(width 0.1143)
		(layer "In2.Cu")
		(net "CLK_100M_PCH_SLOTX24_S0_DP")
	)
	(segment
		(start 443.203076 -16.329406)
		(end 443.000638 -16.21282)
		(width 0.1143)
		(layer "In2.Cu")
		(net "CLK_100M_PCH_SLOTX24_S0_DP")
	)
	(segment
		(start 363.876844 -69.315838)
		(end 363.531404 -70.753478)
		(width 0.1143)
		(layer "In2.Cu")
		(net "CLK_100M_PCH_SLOTX24_S0_DP")
	)
	(segment
		(start 371.269514 -106.256836)
		(end 371.644926 -106.951526)
		(width 0.1143)
		(layer "In2.Cu")
		(net "CLK_100M_PCH_SLOTX24_S0_DP")
	)
	(segment
		(start 376.087386 -107.674664)
		(end 376.176286 -107.763564)
		(width 0.0889)
		(layer "In2.Cu")
		(net "CLK_100M_PCH_SLOTX24_S0_DP")
	)
	(segment
		(start 457.921614 -12.580366)
		(end 457.688188 -12.580366)
		(width 0.1143)
		(layer "In2.Cu")
		(net "CLK_100M_PCH_SLOTX24_S0_DP")
	)
	(segment
		(start 365.64824 -84.4296)
		(end 365.10468 -87.1474)
		(width 0.1143)
		(layer "In2.Cu")
		(net "CLK_100M_PCH_SLOTX24_S0_DP")
	)
	(segment
		(start 457.445618 -12.822936)
		(end 455.328274 -13.548106)
		(width 0.1143)
		(layer "In2.Cu")
		(net "CLK_100M_PCH_SLOTX24_S0_DP")
	)
	(segment
		(start 457.688188 -12.580366)
		(end 457.445618 -12.822936)
		(width 0.1143)
		(layer "In2.Cu")
		(net "CLK_100M_PCH_SLOTX24_S0_DP")
	)
	(segment
		(start 365.915702 -66.114676)
		(end 365.319564 -66.464942)
		(width 0.1143)
		(layer "In2.Cu")
		(net "CLK_100M_PCH_SLOTX24_S0_DP")
	)
	(segment
		(start 424.597068 -18.781522)
		(end 424.597068 -18.781776)
		(width 0.1143)
		(layer "In2.Cu")
		(net "CLK_100M_PCH_SLOTX24_S0_DP")
	)
	(segment
		(start 424.597068 -18.781776)
		(end 423.35196 -19.273266)
		(width 0.1143)
		(layer "In2.Cu")
		(net "CLK_100M_PCH_SLOTX24_S0_DP")
	)
	(segment
		(start 423.35196 -19.273266)
		(end 421.02532 -19.774154)
		(width 0.1143)
		(layer "In2.Cu")
		(net "CLK_100M_PCH_SLOTX24_S0_DP")
	)
	(segment
		(start 370.667026 -94.204028)
		(end 371.00383 -94.892114)
		(width 0.1143)
		(layer "In2.Cu")
		(net "CLK_100M_PCH_SLOTX24_S0_DP")
	)
	(segment
		(start 368.144044 -60.790836)
		(end 367.904268 -61.146944)
		(width 0.1143)
		(layer "In2.Cu")
		(net "CLK_100M_PCH_SLOTX24_S0_DP")
	)
	(segment
		(start 363.531658 -70.753478)
		(end 363.531404 -70.753732)
		(width 0.1143)
		(layer "In2.Cu")
		(net "CLK_100M_PCH_SLOTX24_S0_DP")
	)
	(segment
		(start 416.898074 -21.841206)
		(end 416.744658 -21.871686)
		(width 0.1143)
		(layer "In2.Cu")
		(net "CLK_100M_PCH_SLOTX24_S0_DP")
	)
	(segment
		(start 421.02532 -19.774154)
		(end 419.217602 -21.076158)
		(width 0.1143)
		(layer "In2.Cu")
		(net "CLK_100M_PCH_SLOTX24_S0_DP")
	)
	(segment
		(start 374.401334 -107.3531)
		(end 374.811798 -107.763564)
		(width 0.0889)
		(layer "In2.Cu")
		(net "CLK_100M_PCH_SLOTX24_S0_DP")
	)
	(segment
		(start 370.41328 -99.383342)
		(end 370.100098 -100.635308)
		(width 0.1143)
		(layer "In2.Cu")
		(net "CLK_100M_PCH_SLOTX24_S0_DP")
	)
	(segment
		(start 442.019436 -16.475964)
		(end 441.585096 -16.592296)
		(width 0.1143)
		(layer "In2.Cu")
		(net "CLK_100M_PCH_SLOTX24_S0_DP")
	)
	(segment
		(start 443.982094 -15.949676)
		(end 443.650878 -16.038576)
		(width 0.1143)
		(layer "In2.Cu")
		(net "CLK_100M_PCH_SLOTX24_S0_DP")
	)
	(segment
		(start 388.671054 -22.042628)
		(end 383.789682 -20.876768)
		(width 0.1143)
		(layer "In2.Cu")
		(net "CLK_100M_PCH_SLOTX24_S0_DP")
	)
	(arc
		(start 377.825 -108.27639)
		(mid 377.930803 -108.262839)
		(end 378.029978 -108.223558)
		(width 0.0889)
		(layer "In2.Cu")
		(net "CLK_100M_PCH_SLOTX24_S0_DP")
	)
	(arc
		(start 378.029978 -108.223558)
		(mid 378.147689 -108.128813)
		(end 378.22505 -107.999022)
		(width 0.0889)
		(layer "In2.Cu")
		(net "CLK_100M_PCH_SLOTX24_S0_DP")
	)
	(arc
		(start 378.22505 -107.999022)
		(mid 378.225619 -107.881178)
		(end 378.149358 -107.79125)
		(width 0.0889)
		(layer "In2.Cu")
		(net "CLK_100M_PCH_SLOTX24_S0_DP")
	)
	(arc
		(start 378.149358 -107.79125)
		(mid 377.976978 -107.761936)
		(end 377.825 -107.8484)
		(width 0.0889)
		(layer "In2.Cu")
		(net "CLK_100M_PCH_SLOTX24_S0_DP")
	)
	(segment
		(start 458.325728 -8.787638)
		(end 458.078078 -8.539988)
		(width 0.127)
		(layer "F.Cu")
		(net "CLK_100M_PCH_SLOTX24_S0_DN")
	)
	(segment
		(start 458.078078 -8.539988)
		(end 458.078078 -7.789672)
		(width 0.127)
		(layer "F.Cu")
		(net "CLK_100M_PCH_SLOTX24_S0_DN")
	)
	(segment
		(start 458.532738 -9.640062)
		(end 458.532738 -9.422892)
		(width 0.127)
		(layer "F.Cu")
		(net "CLK_100M_PCH_SLOTX24_S0_DN")
	)
	(segment
		(start 458.325728 -9.215882)
		(end 458.325728 -8.787638)
		(width 0.127)
		(layer "F.Cu")
		(net "CLK_100M_PCH_SLOTX24_S0_DN")
	)
	(segment
		(start 458.0382 -10.1346)
		(end 458.532738 -9.640062)
		(width 0.127)
		(layer "F.Cu")
		(net "CLK_100M_PCH_SLOTX24_S0_DN")
	)
	(segment
		(start 378.32665 -108.13796)
		(end 378.8156 -107.8484)
		(width 0.127)
		(layer "F.Cu")
		(net "CLK_100M_PCH_SLOTX24_S0_DN")
	)
	(segment
		(start 458.532738 -9.422892)
		(end 458.325728 -9.215882)
		(width 0.127)
		(layer "F.Cu")
		(net "CLK_100M_PCH_SLOTX24_S0_DN")
	)
	(via
		(at 378.8156 -107.8484)
		(size 0.508)
		(drill 0.254)
		(layers "F.Cu" "B.Cu")
		(net "CLK_100M_PCH_SLOTX24_S0_DN")
	)
	(via
		(at 458.0382 -10.1346)
		(size 0.508)
		(drill 0.254)
		(layers "F.Cu" "B.Cu")
		(net "CLK_100M_PCH_SLOTX24_S0_DN")
	)
	(segment
		(start 458.0382 -10.1346)
		(end 458.56652 -10.66292)
		(width 0.1143)
		(layer "In2.Cu")
		(net "CLK_100M_PCH_SLOTX24_S0_DN")
	)
	(segment
		(start 365.922814 -64.757808)
		(end 365.6584 -65.926716)
		(width 0.1143)
		(layer "In2.Cu")
		(net "CLK_100M_PCH_SLOTX24_S0_DN")
	)
	(segment
		(start 366.982248 -90.570558)
		(end 369.471194 -94.096586)
		(width 0.1143)
		(layer "In2.Cu")
		(net "CLK_100M_PCH_SLOTX24_S0_DN")
	)
	(segment
		(start 365.6584 -65.926716)
		(end 365.124238 -66.240914)
		(width 0.1143)
		(layer "In2.Cu")
		(net "CLK_100M_PCH_SLOTX24_S0_DN")
	)
	(segment
		(start 371.874288 -107.5944)
		(end 374.00738 -107.5944)
		(width 0.1143)
		(layer "In2.Cu")
		(net "CLK_100M_PCH_SLOTX24_S0_DN")
	)
	(segment
		(start 371.214904 -35.484816)
		(end 371.621558 -36.890706)
		(width 0.1143)
		(layer "In2.Cu")
		(net "CLK_100M_PCH_SLOTX24_S0_DN")
	)
	(segment
		(start 366.086644 -63.890906)
		(end 366.178592 -64.354202)
		(width 0.1143)
		(layer "In2.Cu")
		(net "CLK_100M_PCH_SLOTX24_S0_DN")
	)
	(segment
		(start 376.788426 -107.954064)
		(end 377.301252 -108.46689)
		(width 0.0889)
		(layer "In2.Cu")
		(net "CLK_100M_PCH_SLOTX24_S0_DN")
	)
	(segment
		(start 454.209912 -13.02639)
		(end 452.591932 -11.947906)
		(width 0.1143)
		(layer "In2.Cu")
		(net "CLK_100M_PCH_SLOTX24_S0_DN")
	)
	(segment
		(start 365.261652 -89.423494)
		(end 366.982248 -90.570558)
		(width 0.1143)
		(layer "In2.Cu")
		(net "CLK_100M_PCH_SLOTX24_S0_DN")
	)
	(segment
		(start 423.26687 -18.992596)
		(end 420.904162 -19.501358)
		(width 0.1143)
		(layer "In2.Cu")
		(net "CLK_100M_PCH_SLOTX24_S0_DN")
	)
	(segment
		(start 416.687508 -21.585174)
		(end 415.769552 -21.76907)
		(width 0.1143)
		(layer "In2.Cu")
		(net "CLK_100M_PCH_SLOTX24_S0_DN")
	)
	(segment
		(start 438.185306 -15.247112)
		(end 436.37581 -15.611856)
		(width 0.1143)
		(layer "In2.Cu")
		(net "CLK_100M_PCH_SLOTX24_S0_DN")
	)
	(segment
		(start 383.15011 -20.823682)
		(end 380.96952 -23.792434)
		(width 0.1143)
		(layer "In2.Cu")
		(net "CLK_100M_PCH_SLOTX24_S0_DN")
	)
	(segment
		(start 415.769044 -21.768816)
		(end 414.652968 -21.54555)
		(width 0.1143)
		(layer "In2.Cu")
		(net "CLK_100M_PCH_SLOTX24_S0_DN")
	)
	(segment
		(start 443.85992 -15.679928)
		(end 441.57519 -16.292322)
		(width 0.1143)
		(layer "In2.Cu")
		(net "CLK_100M_PCH_SLOTX24_S0_DN")
	)
	(segment
		(start 429.923194 -16.885412)
		(end 427.364398 -17.40535)
		(width 0.1143)
		(layer "In2.Cu")
		(net "CLK_100M_PCH_SLOTX24_S0_DN")
	)
	(segment
		(start 414.652968 -21.54555)
		(end 414.599882 -21.580856)
		(width 0.1143)
		(layer "In2.Cu")
		(net "CLK_100M_PCH_SLOTX24_S0_DN")
	)
	(segment
		(start 370.289836 -51.415442)
		(end 368.664744 -59.538108)
		(width 0.1143)
		(layer "In2.Cu")
		(net "CLK_100M_PCH_SLOTX24_S0_DN")
	)
	(segment
		(start 415.769552 -21.76907)
		(end 415.769044 -21.768816)
		(width 0.1143)
		(layer "In2.Cu")
		(net "CLK_100M_PCH_SLOTX24_S0_DN")
	)
	(segment
		(start 404.537672 -22.691598)
		(end 401.65655 -22.691598)
		(width 0.1143)
		(layer "In2.Cu")
		(net "CLK_100M_PCH_SLOTX24_S0_DN")
	)
	(segment
		(start 370.485924 -95.836994)
		(end 370.485924 -98.644456)
		(width 0.1143)
		(layer "In2.Cu")
		(net "CLK_100M_PCH_SLOTX24_S0_DN")
	)
	(segment
		(start 367.628678 -61.032898)
		(end 367.47577 -61.820298)
		(width 0.1143)
		(layer "In2.Cu")
		(net "CLK_100M_PCH_SLOTX24_S0_DN")
	)
	(segment
		(start 409.3972 -23.5712)
		(end 407.983944 -24.277828)
		(width 0.1143)
		(layer "In2.Cu")
		(net "CLK_100M_PCH_SLOTX24_S0_DN")
	)
	(segment
		(start 367.902998 -60.625228)
		(end 367.628678 -61.032898)
		(width 0.1143)
		(layer "In2.Cu")
		(net "CLK_100M_PCH_SLOTX24_S0_DN")
	)
	(segment
		(start 375.722896 -25.140412)
		(end 372.496588 -29.456634)
		(width 0.1143)
		(layer "In2.Cu")
		(net "CLK_100M_PCH_SLOTX24_S0_DN")
	)
	(segment
		(start 383.765806 -20.570698)
		(end 383.15011 -20.823682)
		(width 0.1143)
		(layer "In2.Cu")
		(net "CLK_100M_PCH_SLOTX24_S0_DN")
	)
	(segment
		(start 374.32234 -107.5436)
		(end 374.732804 -107.954064)
		(width 0.0889)
		(layer "In2.Cu")
		(net "CLK_100M_PCH_SLOTX24_S0_DN")
	)
	(segment
		(start 407.983944 -24.277828)
		(end 407.23439 -24.277828)
		(width 0.1143)
		(layer "In2.Cu")
		(net "CLK_100M_PCH_SLOTX24_S0_DN")
	)
	(segment
		(start 367.041176 -62.464442)
		(end 366.576356 -62.777878)
		(width 0.1143)
		(layer "In2.Cu")
		(net "CLK_100M_PCH_SLOTX24_S0_DN")
	)
	(segment
		(start 369.471194 -94.096586)
		(end 370.457222 -94.440502)
		(width 0.1143)
		(layer "In2.Cu")
		(net "CLK_100M_PCH_SLOTX24_S0_DN")
	)
	(segment
		(start 374.029478 -107.5944)
		(end 374.080278 -107.5436)
		(width 0.0889)
		(layer "In2.Cu")
		(net "CLK_100M_PCH_SLOTX24_S0_DN")
	)
	(segment
		(start 392.561318 -20.247356)
		(end 388.651242 -21.737574)
		(width 0.1143)
		(layer "In2.Cu")
		(net "CLK_100M_PCH_SLOTX24_S0_DN")
	)
	(segment
		(start 363.576362 -69.314822)
		(end 363.231938 -70.749668)
		(width 0.1143)
		(layer "In2.Cu")
		(net "CLK_100M_PCH_SLOTX24_S0_DN")
	)
	(segment
		(start 434.561996 -16.518636)
		(end 431.342546 -17.173956)
		(width 0.1143)
		(layer "In2.Cu")
		(net "CLK_100M_PCH_SLOTX24_S0_DN")
	)
	(segment
		(start 420.904162 -19.501358)
		(end 419.08349 -20.81276)
		(width 0.1143)
		(layer "In2.Cu")
		(net "CLK_100M_PCH_SLOTX24_S0_DN")
	)
	(segment
		(start 416.907218 -21.530564)
		(end 416.884104 -21.545804)
		(width 0.1143)
		(layer "In2.Cu")
		(net "CLK_100M_PCH_SLOTX24_S0_DN")
	)
	(segment
		(start 401.65655 -22.691598)
		(end 392.561318 -20.247356)
		(width 0.1143)
		(layer "In2.Cu")
		(net "CLK_100M_PCH_SLOTX24_S0_DN")
	)
	(segment
		(start 439.43778 -15.497556)
		(end 438.185306 -15.247112)
		(width 0.1143)
		(layer "In2.Cu")
		(net "CLK_100M_PCH_SLOTX24_S0_DN")
	)
	(segment
		(start 370.457222 -94.440502)
		(end 370.695728 -94.92742)
		(width 0.1143)
		(layer "In2.Cu")
		(net "CLK_100M_PCH_SLOTX24_S0_DN")
	)
	(segment
		(start 370.155216 -99.20986)
		(end 369.800378 -100.629212)
		(width 0.1143)
		(layer "In2.Cu")
		(net "CLK_100M_PCH_SLOTX24_S0_DN")
	)
	(segment
		(start 458.56652 -10.66292)
		(end 458.56652 -11.288776)
		(width 0.1143)
		(layer "In2.Cu")
		(net "CLK_100M_PCH_SLOTX24_S0_DN")
	)
	(segment
		(start 374.732804 -107.954064)
		(end 376.788426 -107.954064)
		(width 0.0889)
		(layer "In2.Cu")
		(net "CLK_100M_PCH_SLOTX24_S0_DN")
	)
	(segment
		(start 364.4519 -80.193896)
		(end 365.34979 -84.431378)
		(width 0.1143)
		(layer "In2.Cu")
		(net "CLK_100M_PCH_SLOTX24_S0_DN")
	)
	(segment
		(start 371.485922 -42.395394)
		(end 369.45951 -48.79848)
		(width 0.1143)
		(layer "In2.Cu")
		(net "CLK_100M_PCH_SLOTX24_S0_DN")
	)
	(segment
		(start 414.599882 -21.580856)
		(end 412.639256 -21.973032)
		(width 0.1143)
		(layer "In2.Cu")
		(net "CLK_100M_PCH_SLOTX24_S0_DN")
	)
	(segment
		(start 416.884104 -21.545804)
		(end 416.840416 -21.554694)
		(width 0.1143)
		(layer "In2.Cu")
		(net "CLK_100M_PCH_SLOTX24_S0_DN")
	)
	(segment
		(start 450.8627 -11.601958)
		(end 449.59651 -11.855196)
		(width 0.1143)
		(layer "In2.Cu")
		(net "CLK_100M_PCH_SLOTX24_S0_DN")
	)
	(segment
		(start 419.08349 -20.81276)
		(end 416.907218 -21.530564)
		(width 0.1143)
		(layer "In2.Cu")
		(net "CLK_100M_PCH_SLOTX24_S0_DN")
	)
	(segment
		(start 369.800378 -100.629212)
		(end 370.992146 -106.358182)
		(width 0.1143)
		(layer "In2.Cu")
		(net "CLK_100M_PCH_SLOTX24_S0_DN")
	)
	(segment
		(start 363.231938 -70.749668)
		(end 364.4519 -76.513944)
		(width 0.1143)
		(layer "In2.Cu")
		(net "CLK_100M_PCH_SLOTX24_S0_DN")
	)
	(segment
		(start 366.178592 -64.354202)
		(end 365.922814 -64.757808)
		(width 0.1143)
		(layer "In2.Cu")
		(net "CLK_100M_PCH_SLOTX24_S0_DN")
	)
	(segment
		(start 365.124238 -66.240914)
		(end 363.37113 -68.461636)
		(width 0.1143)
		(layer "In2.Cu")
		(net "CLK_100M_PCH_SLOTX24_S0_DN")
	)
	(segment
		(start 388.651242 -21.737574)
		(end 383.765806 -20.570698)
		(width 0.1143)
		(layer "In2.Cu")
		(net "CLK_100M_PCH_SLOTX24_S0_DN")
	)
	(segment
		(start 363.37113 -68.461636)
		(end 363.576362 -69.314822)
		(width 0.1143)
		(layer "In2.Cu")
		(net "CLK_100M_PCH_SLOTX24_S0_DN")
	)
	(segment
		(start 374.080278 -107.5436)
		(end 374.32234 -107.5436)
		(width 0.0889)
		(layer "In2.Cu")
		(net "CLK_100M_PCH_SLOTX24_S0_DN")
	)
	(segment
		(start 427.364398 -17.40535)
		(end 426.761148 -17.804638)
		(width 0.1143)
		(layer "In2.Cu")
		(net "CLK_100M_PCH_SLOTX24_S0_DN")
	)
	(segment
		(start 406.63749 -23.273258)
		(end 406.439624 -23.149052)
		(width 0.1143)
		(layer "In2.Cu")
		(net "CLK_100M_PCH_SLOTX24_S0_DN")
	)
	(segment
		(start 374.00738 -107.5944)
		(end 374.029478 -107.5944)
		(width 0.0889)
		(layer "In2.Cu")
		(net "CLK_100M_PCH_SLOTX24_S0_DN")
	)
	(segment
		(start 370.380006 -99.045268)
		(end 370.155216 -99.20986)
		(width 0.1143)
		(layer "In2.Cu")
		(net "CLK_100M_PCH_SLOTX24_S0_DN")
	)
	(segment
		(start 367.47577 -61.820298)
		(end 367.041176 -62.464442)
		(width 0.1143)
		(layer "In2.Cu")
		(net "CLK_100M_PCH_SLOTX24_S0_DN")
	)
	(segment
		(start 372.496588 -29.456634)
		(end 371.214904 -35.484816)
		(width 0.1143)
		(layer "In2.Cu")
		(net "CLK_100M_PCH_SLOTX24_S0_DN")
	)
	(segment
		(start 449.59651 -11.855196)
		(end 443.85992 -15.679928)
		(width 0.1143)
		(layer "In2.Cu")
		(net "CLK_100M_PCH_SLOTX24_S0_DN")
	)
	(segment
		(start 369.45951 -48.79848)
		(end 370.289836 -51.415442)
		(width 0.1143)
		(layer "In2.Cu")
		(net "CLK_100M_PCH_SLOTX24_S0_DN")
	)
	(segment
		(start 457.286868 -12.568428)
		(end 455.308208 -13.2461)
		(width 0.1143)
		(layer "In2.Cu")
		(net "CLK_100M_PCH_SLOTX24_S0_DN")
	)
	(segment
		(start 435.735984 -15.74165)
		(end 434.561996 -16.518636)
		(width 0.1143)
		(layer "In2.Cu")
		(net "CLK_100M_PCH_SLOTX24_S0_DN")
	)
	(segment
		(start 436.37581 -15.611856)
		(end 435.735984 -15.74165)
		(width 0.1143)
		(layer "In2.Cu")
		(net "CLK_100M_PCH_SLOTX24_S0_DN")
	)
	(segment
		(start 452.591932 -11.947906)
		(end 450.8627 -11.601958)
		(width 0.1143)
		(layer "In2.Cu")
		(net "CLK_100M_PCH_SLOTX24_S0_DN")
	)
	(segment
		(start 368.664744 -59.538108)
		(end 367.902998 -60.625228)
		(width 0.1143)
		(layer "In2.Cu")
		(net "CLK_100M_PCH_SLOTX24_S0_DN")
	)
	(segment
		(start 425.759626 -18.008346)
		(end 423.26687 -18.992596)
		(width 0.1143)
		(layer "In2.Cu")
		(net "CLK_100M_PCH_SLOTX24_S0_DN")
	)
	(segment
		(start 458.56652 -11.288776)
		(end 457.286868 -12.568428)
		(width 0.1143)
		(layer "In2.Cu")
		(net "CLK_100M_PCH_SLOTX24_S0_DN")
	)
	(segment
		(start 380.96952 -23.792434)
		(end 379.247908 -24.442166)
		(width 0.1143)
		(layer "In2.Cu")
		(net "CLK_100M_PCH_SLOTX24_S0_DN")
	)
	(segment
		(start 378.61367 -24.28875)
		(end 375.722896 -25.140412)
		(width 0.1143)
		(layer "In2.Cu")
		(net "CLK_100M_PCH_SLOTX24_S0_DN")
	)
	(segment
		(start 431.342546 -17.173956)
		(end 429.923194 -16.885412)
		(width 0.1143)
		(layer "In2.Cu")
		(net "CLK_100M_PCH_SLOTX24_S0_DN")
	)
	(segment
		(start 370.485924 -98.644456)
		(end 370.380006 -99.045268)
		(width 0.1143)
		(layer "In2.Cu")
		(net "CLK_100M_PCH_SLOTX24_S0_DN")
	)
	(segment
		(start 364.806738 -87.1474)
		(end 365.261652 -89.423494)
		(width 0.1143)
		(layer "In2.Cu")
		(net "CLK_100M_PCH_SLOTX24_S0_DN")
	)
	(segment
		(start 370.898166 -39.53129)
		(end 371.485922 -42.395394)
		(width 0.1143)
		(layer "In2.Cu")
		(net "CLK_100M_PCH_SLOTX24_S0_DN")
	)
	(segment
		(start 410.207714 -22.82317)
		(end 409.3972 -23.5712)
		(width 0.1143)
		(layer "In2.Cu")
		(net "CLK_100M_PCH_SLOTX24_S0_DN")
	)
	(segment
		(start 370.992146 -106.358182)
		(end 371.407944 -107.128056)
		(width 0.1143)
		(layer "In2.Cu")
		(net "CLK_100M_PCH_SLOTX24_S0_DN")
	)
	(segment
		(start 378.665994 -107.8484)
		(end 378.8156 -107.8484)
		(width 0.0889)
		(layer "In2.Cu")
		(net "CLK_100M_PCH_SLOTX24_S0_DN")
	)
	(segment
		(start 366.576356 -62.777878)
		(end 366.086644 -63.890906)
		(width 0.1143)
		(layer "In2.Cu")
		(net "CLK_100M_PCH_SLOTX24_S0_DN")
	)
	(segment
		(start 406.778968 -23.822406)
		(end 406.63749 -23.273258)
		(width 0.1143)
		(layer "In2.Cu")
		(net "CLK_100M_PCH_SLOTX24_S0_DN")
	)
	(segment
		(start 440.225688 -16.022828)
		(end 439.43778 -15.497556)
		(width 0.1143)
		(layer "In2.Cu")
		(net "CLK_100M_PCH_SLOTX24_S0_DN")
	)
	(segment
		(start 377.301252 -108.46689)
		(end 377.825 -108.46689)
		(width 0.0889)
		(layer "In2.Cu")
		(net "CLK_100M_PCH_SLOTX24_S0_DN")
	)
	(segment
		(start 416.840416 -21.554694)
		(end 416.687508 -21.585174)
		(width 0.1143)
		(layer "In2.Cu")
		(net "CLK_100M_PCH_SLOTX24_S0_DN")
	)
	(segment
		(start 364.4519 -76.513944)
		(end 364.4519 -80.193896)
		(width 0.1143)
		(layer "In2.Cu")
		(net "CLK_100M_PCH_SLOTX24_S0_DN")
	)
	(segment
		(start 371.621558 -36.890706)
		(end 370.898166 -39.53129)
		(width 0.1143)
		(layer "In2.Cu")
		(net "CLK_100M_PCH_SLOTX24_S0_DN")
	)
	(segment
		(start 455.308208 -13.2461)
		(end 454.209912 -13.02639)
		(width 0.1143)
		(layer "In2.Cu")
		(net "CLK_100M_PCH_SLOTX24_S0_DN")
	)
	(segment
		(start 371.407944 -107.128056)
		(end 371.874288 -107.5944)
		(width 0.1143)
		(layer "In2.Cu")
		(net "CLK_100M_PCH_SLOTX24_S0_DN")
	)
	(segment
		(start 370.695728 -94.92742)
		(end 370.485924 -95.836994)
		(width 0.1143)
		(layer "In2.Cu")
		(net "CLK_100M_PCH_SLOTX24_S0_DN")
	)
	(segment
		(start 379.247908 -24.442166)
		(end 378.61367 -24.28875)
		(width 0.1143)
		(layer "In2.Cu")
		(net "CLK_100M_PCH_SLOTX24_S0_DN")
	)
	(segment
		(start 406.439624 -23.149052)
		(end 404.537672 -22.691598)
		(width 0.1143)
		(layer "In2.Cu")
		(net "CLK_100M_PCH_SLOTX24_S0_DN")
	)
	(segment
		(start 412.639256 -21.973032)
		(end 410.207714 -22.82317)
		(width 0.1143)
		(layer "In2.Cu")
		(net "CLK_100M_PCH_SLOTX24_S0_DN")
	)
	(segment
		(start 441.57519 -16.292322)
		(end 440.225688 -16.022828)
		(width 0.1143)
		(layer "In2.Cu")
		(net "CLK_100M_PCH_SLOTX24_S0_DN")
	)
	(segment
		(start 365.34979 -84.431378)
		(end 364.806738 -87.1474)
		(width 0.1143)
		(layer "In2.Cu")
		(net "CLK_100M_PCH_SLOTX24_S0_DN")
	)
	(segment
		(start 407.23439 -24.277828)
		(end 406.778968 -23.822406)
		(width 0.1143)
		(layer "In2.Cu")
		(net "CLK_100M_PCH_SLOTX24_S0_DN")
	)
	(segment
		(start 426.761148 -17.804638)
		(end 425.759626 -18.008346)
		(width 0.1143)
		(layer "In2.Cu")
		(net "CLK_100M_PCH_SLOTX24_S0_DN")
	)
	(arc
		(start 378.403866 -108.066332)
		(mid 378.40995 -108.049525)
		(end 378.41555 -108.03255)
		(width 0.0889)
		(layer "In2.Cu")
		(net "CLK_100M_PCH_SLOTX24_S0_DN")
	)
	(arc
		(start 378.121418 -108.391198)
		(mid 378.291837 -108.254141)
		(end 378.403866 -108.066332)
		(width 0.0889)
		(layer "In2.Cu")
		(net "CLK_100M_PCH_SLOTX24_S0_DN")
	)
	(arc
		(start 377.825 -108.46689)
		(mid 377.977972 -108.447682)
		(end 378.121418 -108.391198)
		(width 0.0889)
		(layer "In2.Cu")
		(net "CLK_100M_PCH_SLOTX24_S0_DN")
	)
	(arc
		(start 378.41555 -108.03255)
		(mid 378.510565 -107.899395)
		(end 378.665994 -107.8484)
		(width 0.0889)
		(layer "In2.Cu")
		(net "CLK_100M_PCH_SLOTX24_S0_DN")
	)
	(segment
		(start 131.089908 -63.334138)
		(end 131.661408 -63.334138)
		(width 0.1016)
		(layer "F.Cu")
		(net "XDP_CPU1_TDO")
	)
	(via
		(at 423.587418 -65.51168)
		(size 0.508)
		(drill 0.254)
		(layers "F.Cu" "B.Cu")
		(net "XDP_CPU1_TDO")
	)
	(via
		(at 455.9808 -133.5278)
		(size 0.508)
		(drill 0.254)
		(layers "F.Cu" "B.Cu")
		(net "XDP_CPU1_TDO")
	)
	(via
		(at 427.02861 -114.753644)
		(size 0.508)
		(drill 0.254)
		(layers "F.Cu" "B.Cu")
		(net "XDP_CPU1_TDO")
	)
	(via
		(at 472.84767 -64.49695)
		(size 0.508)
		(drill 0.254)
		(layers "F.Cu" "B.Cu")
		(net "XDP_CPU1_TDO")
	)
	(via
		(at 423.836592 -67.31)
		(size 0.6604)
		(drill 0.3302)
		(layers "F.Cu" "B.Cu")
		(net "XDP_CPU1_TDO")
	)
	(via
		(at 493.893602 -58.028332)
		(size 0.508)
		(drill 0.254)
		(layers "F.Cu" "B.Cu")
		(net "XDP_CPU1_TDO")
	)
	(via
		(at 131.661408 -63.334138)
		(size 0.508)
		(drill 0.254)
		(layers "F.Cu" "B.Cu")
		(net "XDP_CPU1_TDO")
	)
	(via
		(at 322.100194 -14.74216)
		(size 0.508)
		(drill 0.254)
		(layers "F.Cu" "B.Cu")
		(net "XDP_CPU1_TDO")
	)
	(via
		(at 456.222862 -130.6068)
		(size 0.508)
		(drill 0.254)
		(layers "F.Cu" "B.Cu")
		(net "XDP_CPU1_TDO")
	)
	(via
		(at 179.316888 -22.01164)
		(size 0.508)
		(drill 0.254)
		(layers "F.Cu" "B.Cu")
		(net "XDP_CPU1_TDO")
	)
	(via
		(at 425.912026 4.261866)
		(size 0.508)
		(drill 0.254)
		(layers "F.Cu" "B.Cu")
		(net "XDP_CPU1_TDO")
	)
	(via
		(at 326.354186 3.689096)
		(size 0.508)
		(drill 0.254)
		(layers "F.Cu" "B.Cu")
		(net "XDP_CPU1_TDO")
	)
	(segment
		(start 423.6212 -65.622678)
		(end 424.0022 -66.003678)
		(width 0.10795)
		(layer "B.Cu")
		(net "XDP_CPU1_TDO")
	)
	(segment
		(start 424.0022 -66.003678)
		(end 424.0022 -66.522854)
		(width 0.10795)
		(layer "B.Cu")
		(net "XDP_CPU1_TDO")
	)
	(segment
		(start 427.435518 -111.84001)
		(end 427.435518 -114.346228)
		(width 0.10795)
		(layer "B.Cu")
		(net "XDP_CPU1_TDO")
	)
	(segment
		(start 424.9547 -73.105772)
		(end 425.237148 -73.38822)
		(width 0.10795)
		(layer "B.Cu")
		(net "XDP_CPU1_TDO")
	)
	(segment
		(start 423.836592 -66.688462)
		(end 423.836592 -67.31)
		(width 0.10795)
		(layer "B.Cu")
		(net "XDP_CPU1_TDO")
	)
	(segment
		(start 179.342796 -21.985732)
		(end 179.342796 -20.75307)
		(width 0.10795)
		(layer "B.Cu")
		(net "XDP_CPU1_TDO")
	)
	(segment
		(start 424.0022 -66.522854)
		(end 423.836592 -66.688462)
		(width 0.10795)
		(layer "B.Cu")
		(net "XDP_CPU1_TDO")
	)
	(segment
		(start 457.703428 -128.553972)
		(end 457.703428 -127.9144)
		(width 0.10795)
		(layer "B.Cu")
		(net "XDP_CPU1_TDO")
	)
	(segment
		(start 424.9547 -71.797164)
		(end 424.9547 -73.105772)
		(width 0.10795)
		(layer "B.Cu")
		(net "XDP_CPU1_TDO")
	)
	(segment
		(start 427.435518 -114.346228)
		(end 427.02861 -114.753136)
		(width 0.10795)
		(layer "B.Cu")
		(net "XDP_CPU1_TDO")
	)
	(segment
		(start 456.222862 -130.6068)
		(end 456.222862 -130.034538)
		(width 0.10795)
		(layer "B.Cu")
		(net "XDP_CPU1_TDO")
	)
	(segment
		(start 423.6212 -65.545462)
		(end 423.6212 -65.622678)
		(width 0.10795)
		(layer "B.Cu")
		(net "XDP_CPU1_TDO")
	)
	(segment
		(start 423.836592 -67.31)
		(end 423.836592 -70.679056)
		(width 0.10795)
		(layer "B.Cu")
		(net "XDP_CPU1_TDO")
	)
	(segment
		(start 425.46651 -80.246982)
		(end 425.46651 -109.871002)
		(width 0.10795)
		(layer "B.Cu")
		(net "XDP_CPU1_TDO")
	)
	(segment
		(start 425.237148 -73.38822)
		(end 425.237148 -80.01762)
		(width 0.10795)
		(layer "B.Cu")
		(net "XDP_CPU1_TDO")
	)
	(segment
		(start 425.237148 -80.01762)
		(end 425.46651 -80.246982)
		(width 0.10795)
		(layer "B.Cu")
		(net "XDP_CPU1_TDO")
	)
	(segment
		(start 427.02861 -114.753136)
		(end 427.02861 -114.753644)
		(width 0.10795)
		(layer "B.Cu")
		(net "XDP_CPU1_TDO")
	)
	(segment
		(start 456.222862 -130.034538)
		(end 457.703428 -128.553972)
		(width 0.10795)
		(layer "B.Cu")
		(net "XDP_CPU1_TDO")
	)
	(segment
		(start 179.316888 -22.01164)
		(end 179.342796 -21.985732)
		(width 0.10795)
		(layer "B.Cu")
		(net "XDP_CPU1_TDO")
	)
	(segment
		(start 423.587418 -65.51168)
		(end 423.6212 -65.545462)
		(width 0.10795)
		(layer "B.Cu")
		(net "XDP_CPU1_TDO")
	)
	(segment
		(start 423.836592 -70.679056)
		(end 424.9547 -71.797164)
		(width 0.10795)
		(layer "B.Cu")
		(net "XDP_CPU1_TDO")
	)
	(segment
		(start 425.46651 -109.871002)
		(end 427.435518 -111.84001)
		(width 0.10795)
		(layer "B.Cu")
		(net "XDP_CPU1_TDO")
	)
	(segment
		(start 179.342796 -20.75307)
		(end 178.795426 -20.2057)
		(width 0.10795)
		(layer "B.Cu")
		(net "XDP_CPU1_TDO")
	)
	(segment
		(start 466.204808 3.060446)
		(end 466.204808 3.989578)
		(width 0.089408)
		(layer "In2.Cu")
		(net "XDP_CPU1_TDO")
	)
	(segment
		(start 489.533692 -16.516096)
		(end 488.28452 -17.765268)
		(width 0.089408)
		(layer "In2.Cu")
		(net "XDP_CPU1_TDO")
	)
	(segment
		(start 494.411 -52.3748)
		(end 495.3254 -51.4604)
		(width 0.089408)
		(layer "In2.Cu")
		(net "XDP_CPU1_TDO")
	)
	(segment
		(start 497.751608 -37.484812)
		(end 498.260878 -36.975542)
		(width 0.089408)
		(layer "In2.Cu")
		(net "XDP_CPU1_TDO")
	)
	(segment
		(start 483.075234 -16.558006)
		(end 480.701096 -14.183868)
		(width 0.089408)
		(layer "In2.Cu")
		(net "XDP_CPU1_TDO")
	)
	(segment
		(start 323.0626 -12.827)
		(end 323.9262 -11.9634)
		(width 0.089408)
		(layer "In2.Cu")
		(net "XDP_CPU1_TDO")
	)
	(segment
		(start 479.51771 -9.27608)
		(end 479.51771 -5.508752)
		(width 0.089408)
		(layer "In2.Cu")
		(net "XDP_CPU1_TDO")
	)
	(segment
		(start 494.411 -57.238138)
		(end 494.411 -52.3748)
		(width 0.089408)
		(layer "In2.Cu")
		(net "XDP_CPU1_TDO")
	)
	(segment
		(start 477.874584 -4.854194)
		(end 476.820738 -3.800348)
		(width 0.089408)
		(layer "In2.Cu")
		(net "XDP_CPU1_TDO")
	)
	(segment
		(start 499.175278 -36.975542)
		(end 499.621302 -36.529518)
		(width 0.089408)
		(layer "In2.Cu")
		(net "XDP_CPU1_TDO")
	)
	(segment
		(start 494.411254 -57.238392)
		(end 494.411 -57.238138)
		(width 0.089408)
		(layer "In2.Cu")
		(net "XDP_CPU1_TDO")
	)
	(segment
		(start 495.001804 -17.765268)
		(end 493.752632 -16.516096)
		(width 0.089408)
		(layer "In2.Cu")
		(net "XDP_CPU1_TDO")
	)
	(segment
		(start 480.701096 -10.459466)
		(end 479.51771 -9.27608)
		(width 0.089408)
		(layer "In2.Cu")
		(net "XDP_CPU1_TDO")
	)
	(segment
		(start 480.701096 -14.183868)
		(end 480.701096 -10.459466)
		(width 0.089408)
		(layer "In2.Cu")
		(net "XDP_CPU1_TDO")
	)
	(segment
		(start 498.213888 -49.398428)
		(end 498.213888 -46.535848)
		(width 0.089408)
		(layer "In2.Cu")
		(net "XDP_CPU1_TDO")
	)
	(segment
		(start 464.814666 5.37972)
		(end 427.02988 5.37972)
		(width 0.089408)
		(layer "In2.Cu")
		(net "XDP_CPU1_TDO")
	)
	(segment
		(start 494.411 -57.57037)
		(end 494.411254 -57.570116)
		(width 0.089408)
		(layer "In2.Cu")
		(net "XDP_CPU1_TDO")
	)
	(segment
		(start 487.324908 -17.765268)
		(end 486.117646 -16.558006)
		(width 0.089408)
		(layer "In2.Cu")
		(net "XDP_CPU1_TDO")
	)
	(segment
		(start 496.151916 -51.4604)
		(end 498.213888 -49.398428)
		(width 0.089408)
		(layer "In2.Cu")
		(net "XDP_CPU1_TDO")
	)
	(segment
		(start 493.752632 -16.516096)
		(end 489.533692 -16.516096)
		(width 0.089408)
		(layer "In2.Cu")
		(net "XDP_CPU1_TDO")
	)
	(segment
		(start 467.5632 0.185166)
		(end 467.5632 1.702054)
		(width 0.089408)
		(layer "In2.Cu")
		(net "XDP_CPU1_TDO")
	)
	(segment
		(start 427.02988 5.37972)
		(end 425.912026 4.261866)
		(width 0.089408)
		(layer "In2.Cu")
		(net "XDP_CPU1_TDO")
	)
	(segment
		(start 467.5632 1.702054)
		(end 466.204808 3.060446)
		(width 0.089408)
		(layer "In2.Cu")
		(net "XDP_CPU1_TDO")
	)
	(segment
		(start 486.117646 -16.558006)
		(end 483.075234 -16.558006)
		(width 0.089408)
		(layer "In2.Cu")
		(net "XDP_CPU1_TDO")
	)
	(segment
		(start 322.100194 -14.74216)
		(end 322.109846 -14.74216)
		(width 0.089408)
		(layer "In2.Cu")
		(net "XDP_CPU1_TDO")
	)
	(segment
		(start 498.213888 -46.535848)
		(end 497.751608 -46.073568)
		(width 0.089408)
		(layer "In2.Cu")
		(net "XDP_CPU1_TDO")
	)
	(segment
		(start 488.28452 -17.765268)
		(end 487.324908 -17.765268)
		(width 0.089408)
		(layer "In2.Cu")
		(net "XDP_CPU1_TDO")
	)
	(segment
		(start 323.9262 -11.9634)
		(end 323.9262 1.3462)
		(width 0.089408)
		(layer "In2.Cu")
		(net "XDP_CPU1_TDO")
	)
	(segment
		(start 494.411 -57.785)
		(end 494.411 -57.57037)
		(width 0.089408)
		(layer "In2.Cu")
		(net "XDP_CPU1_TDO")
	)
	(segment
		(start 494.411254 -57.570116)
		(end 494.411254 -57.238392)
		(width 0.089408)
		(layer "In2.Cu")
		(net "XDP_CPU1_TDO")
	)
	(segment
		(start 466.204808 3.989578)
		(end 464.814666 5.37972)
		(width 0.089408)
		(layer "In2.Cu")
		(net "XDP_CPU1_TDO")
	)
	(segment
		(start 494.167668 -58.028332)
		(end 494.411 -57.785)
		(width 0.089408)
		(layer "In2.Cu")
		(net "XDP_CPU1_TDO")
	)
	(segment
		(start 500.539766 -17.765268)
		(end 495.001804 -17.765268)
		(width 0.089408)
		(layer "In2.Cu")
		(net "XDP_CPU1_TDO")
	)
	(segment
		(start 499.621302 -35.400234)
		(end 501.474486 -33.54705)
		(width 0.089408)
		(layer "In2.Cu")
		(net "XDP_CPU1_TDO")
	)
	(segment
		(start 497.751608 -46.073568)
		(end 497.751608 -37.484812)
		(width 0.089408)
		(layer "In2.Cu")
		(net "XDP_CPU1_TDO")
	)
	(segment
		(start 322.109846 -14.74216)
		(end 322.246244 -14.605762)
		(width 0.089408)
		(layer "In2.Cu")
		(net "XDP_CPU1_TDO")
	)
	(segment
		(start 476.820738 -3.800348)
		(end 471.548714 -3.800348)
		(width 0.089408)
		(layer "In2.Cu")
		(net "XDP_CPU1_TDO")
	)
	(segment
		(start 501.474486 -18.699988)
		(end 500.539766 -17.765268)
		(width 0.089408)
		(layer "In2.Cu")
		(net "XDP_CPU1_TDO")
	)
	(segment
		(start 479.51771 -5.508752)
		(end 478.863152 -4.854194)
		(width 0.089408)
		(layer "In2.Cu")
		(net "XDP_CPU1_TDO")
	)
	(segment
		(start 493.893602 -58.028332)
		(end 494.167668 -58.028332)
		(width 0.089408)
		(layer "In2.Cu")
		(net "XDP_CPU1_TDO")
	)
	(segment
		(start 478.863152 -4.854194)
		(end 477.874584 -4.854194)
		(width 0.089408)
		(layer "In2.Cu")
		(net "XDP_CPU1_TDO")
	)
	(segment
		(start 471.548714 -3.800348)
		(end 467.5632 0.185166)
		(width 0.089408)
		(layer "In2.Cu")
		(net "XDP_CPU1_TDO")
	)
	(segment
		(start 323.0626 -14.039342)
		(end 323.0626 -12.827)
		(width 0.089408)
		(layer "In2.Cu")
		(net "XDP_CPU1_TDO")
	)
	(segment
		(start 322.246244 -14.605762)
		(end 322.49618 -14.605762)
		(width 0.089408)
		(layer "In2.Cu")
		(net "XDP_CPU1_TDO")
	)
	(segment
		(start 498.260878 -36.975542)
		(end 499.175278 -36.975542)
		(width 0.089408)
		(layer "In2.Cu")
		(net "XDP_CPU1_TDO")
	)
	(segment
		(start 322.49618 -14.605762)
		(end 323.0626 -14.039342)
		(width 0.089408)
		(layer "In2.Cu")
		(net "XDP_CPU1_TDO")
	)
	(segment
		(start 323.9262 1.3462)
		(end 326.269096 3.689096)
		(width 0.089408)
		(layer "In2.Cu")
		(net "XDP_CPU1_TDO")
	)
	(segment
		(start 499.621302 -36.529518)
		(end 499.621302 -35.400234)
		(width 0.089408)
		(layer "In2.Cu")
		(net "XDP_CPU1_TDO")
	)
	(segment
		(start 326.269096 3.689096)
		(end 326.354186 3.689096)
		(width 0.089408)
		(layer "In2.Cu")
		(net "XDP_CPU1_TDO")
	)
	(segment
		(start 501.474486 -33.54705)
		(end 501.474486 -18.699988)
		(width 0.089408)
		(layer "In2.Cu")
		(net "XDP_CPU1_TDO")
	)
	(segment
		(start 495.3254 -51.4604)
		(end 496.151916 -51.4604)
		(width 0.089408)
		(layer "In2.Cu")
		(net "XDP_CPU1_TDO")
	)
	(segment
		(start 424.974766 -65.49771)
		(end 471.84691 -65.49771)
		(width 0.089408)
		(layer "In4.Cu")
		(net "XDP_CPU1_TDO")
	)
	(segment
		(start 423.651934 -65.51168)
		(end 424.009566 -65.869312)
		(width 0.089408)
		(layer "In4.Cu")
		(net "XDP_CPU1_TDO")
	)
	(segment
		(start 456.222862 -133.285738)
		(end 456.222862 -130.6068)
		(width 0.089408)
		(layer "In4.Cu")
		(net "XDP_CPU1_TDO")
	)
	(segment
		(start 424.009566 -65.869312)
		(end 424.603164 -65.869312)
		(width 0.089408)
		(layer "In4.Cu")
		(net "XDP_CPU1_TDO")
	)
	(segment
		(start 455.9808 -133.5278)
		(end 456.222862 -133.285738)
		(width 0.089408)
		(layer "In4.Cu")
		(net "XDP_CPU1_TDO")
	)
	(segment
		(start 471.84691 -65.49771)
		(end 472.84767 -64.49695)
		(width 0.089408)
		(layer "In4.Cu")
		(net "XDP_CPU1_TDO")
	)
	(segment
		(start 423.587418 -65.51168)
		(end 423.651934 -65.51168)
		(width 0.089408)
		(layer "In4.Cu")
		(net "XDP_CPU1_TDO")
	)
	(segment
		(start 424.603164 -65.869312)
		(end 424.974766 -65.49771)
		(width 0.089408)
		(layer "In4.Cu")
		(net "XDP_CPU1_TDO")
	)
	(segment
		(start 352.552254 5.204714)
		(end 353.411028 4.34594)
		(width 0.089408)
		(layer "In9.Cu")
		(net "XDP_CPU1_TDO")
	)
	(segment
		(start 265.143996 -15.144242)
		(end 264.551922 -15.736316)
		(width 0.089408)
		(layer "In9.Cu")
		(net "XDP_CPU1_TDO")
	)
	(segment
		(start 427.858936 -123.978162)
		(end 427.858936 -121.855484)
		(width 0.089408)
		(layer "In9.Cu")
		(net "XDP_CPU1_TDO")
	)
	(segment
		(start 428.371 -115.759738)
		(end 427.364906 -114.753644)
		(width 0.089408)
		(layer "In9.Cu")
		(net "XDP_CPU1_TDO")
	)
	(segment
		(start 344.019886 5.204714)
		(end 344.6272 4.5974)
		(width 0.089408)
		(layer "In9.Cu")
		(net "XDP_CPU1_TDO")
	)
	(segment
		(start 428.129446 -119.948198)
		(end 427.357286 -119.176038)
		(width 0.089408)
		(layer "In9.Cu")
		(net "XDP_CPU1_TDO")
	)
	(segment
		(start 428.129446 -121.584974)
		(end 428.129446 -119.948198)
		(width 0.089408)
		(layer "In9.Cu")
		(net "XDP_CPU1_TDO")
	)
	(segment
		(start 438.100724 -127.677164)
		(end 438.021222 -127.677164)
		(width 0.089408)
		(layer "In9.Cu")
		(net "XDP_CPU1_TDO")
	)
	(segment
		(start 363.356398 -4.416044)
		(end 367.783872 0.01143)
		(width 0.089408)
		(layer "In9.Cu")
		(net "XDP_CPU1_TDO")
	)
	(segment
		(start 181.360826 -19.80184)
		(end 179.316888 -21.845778)
		(width 0.089408)
		(layer "In9.Cu")
		(net "XDP_CPU1_TDO")
	)
	(segment
		(start 193.111628 -13.799058)
		(end 191.162686 -15.748)
		(width 0.089408)
		(layer "In9.Cu")
		(net "XDP_CPU1_TDO")
	)
	(segment
		(start 187.366656 -16.61287)
		(end 187.07481 -16.904716)
		(width 0.089408)
		(layer "In9.Cu")
		(net "XDP_CPU1_TDO")
	)
	(segment
		(start 261.671816 -15.359888)
		(end 260.706108 -14.39418)
		(width 0.089408)
		(layer "In9.Cu")
		(net "XDP_CPU1_TDO")
	)
	(segment
		(start 260.706108 -14.39418)
		(end 260.706108 -12.284964)
		(width 0.089408)
		(layer "In9.Cu")
		(net "XDP_CPU1_TDO")
	)
	(segment
		(start 260.706108 -12.284964)
		(end 259.5753 -11.154156)
		(width 0.089408)
		(layer "In9.Cu")
		(net "XDP_CPU1_TDO")
	)
	(segment
		(start 438.016142 -127.676148)
		(end 434.901594 -124.5616)
		(width 0.089408)
		(layer "In9.Cu")
		(net "XDP_CPU1_TDO")
	)
	(segment
		(start 355.215444 -4.416044)
		(end 363.356398 -4.416044)
		(width 0.089408)
		(layer "In9.Cu")
		(net "XDP_CPU1_TDO")
	)
	(segment
		(start 264.551922 -15.736316)
		(end 262.410702 -15.736316)
		(width 0.089408)
		(layer "In9.Cu")
		(net "XDP_CPU1_TDO")
	)
	(segment
		(start 446.239138 -133.785864)
		(end 440.881262 -128.427988)
		(width 0.089408)
		(layer "In9.Cu")
		(net "XDP_CPU1_TDO")
	)
	(segment
		(start 450.021198 -136.117076)
		(end 447.689986 -133.785864)
		(width 0.089408)
		(layer "In9.Cu")
		(net "XDP_CPU1_TDO")
	)
	(segment
		(start 438.021222 -127.677164)
		(end 438.020206 -127.676148)
		(width 0.089408)
		(layer "In9.Cu")
		(net "XDP_CPU1_TDO")
	)
	(segment
		(start 321.690238 -14.97711)
		(end 266.015978 -14.97711)
		(width 0.089408)
		(layer "In9.Cu")
		(net "XDP_CPU1_TDO")
	)
	(segment
		(start 191.162686 -15.748)
		(end 187.99683 -15.748)
		(width 0.089408)
		(layer "In9.Cu")
		(net "XDP_CPU1_TDO")
	)
	(segment
		(start 453.391524 -136.117076)
		(end 450.021198 -136.117076)
		(width 0.089408)
		(layer "In9.Cu")
		(net "XDP_CPU1_TDO")
	)
	(segment
		(start 265.848846 -15.144242)
		(end 265.143996 -15.144242)
		(width 0.089408)
		(layer "In9.Cu")
		(net "XDP_CPU1_TDO")
	)
	(segment
		(start 427.357286 -118.063772)
		(end 427.41469 -118.006368)
		(width 0.089408)
		(layer "In9.Cu")
		(net "XDP_CPU1_TDO")
	)
	(segment
		(start 259.5753 -11.154156)
		(end 195.13169 -11.154156)
		(width 0.089408)
		(layer "In9.Cu")
		(net "XDP_CPU1_TDO")
	)
	(segment
		(start 427.946058 -117.474746)
		(end 427.946312 -117.474746)
		(width 0.089408)
		(layer "In9.Cu")
		(net "XDP_CPU1_TDO")
	)
	(segment
		(start 322.100194 -14.74216)
		(end 321.925188 -14.74216)
		(width 0.089408)
		(layer "In9.Cu")
		(net "XDP_CPU1_TDO")
	)
	(segment
		(start 321.925188 -14.74216)
		(end 321.690238 -14.97711)
		(width 0.089408)
		(layer "In9.Cu")
		(net "XDP_CPU1_TDO")
	)
	(segment
		(start 184.277762 -19.80184)
		(end 181.360826 -19.80184)
		(width 0.089408)
		(layer "In9.Cu")
		(net "XDP_CPU1_TDO")
	)
	(segment
		(start 326.354186 3.689096)
		(end 326.494394 3.548888)
		(width 0.089408)
		(layer "In9.Cu")
		(net "XDP_CPU1_TDO")
	)
	(segment
		(start 326.494394 3.548888)
		(end 327.437496 3.548888)
		(width 0.089408)
		(layer "In9.Cu")
		(net "XDP_CPU1_TDO")
	)
	(segment
		(start 353.411028 -0.257048)
		(end 354.4316 -1.27762)
		(width 0.089408)
		(layer "In9.Cu")
		(net "XDP_CPU1_TDO")
	)
	(segment
		(start 187.07481 -18.139156)
		(end 186.523884 -18.690082)
		(width 0.089408)
		(layer "In9.Cu")
		(net "XDP_CPU1_TDO")
	)
	(segment
		(start 424.968416 5.205476)
		(end 425.912026 4.261866)
		(width 0.089408)
		(layer "In9.Cu")
		(net "XDP_CPU1_TDO")
	)
	(segment
		(start 344.985086 4.5974)
		(end 345.5924 5.204714)
		(width 0.089408)
		(layer "In9.Cu")
		(net "XDP_CPU1_TDO")
	)
	(segment
		(start 427.357286 -119.176038)
		(end 427.357286 -118.063772)
		(width 0.089408)
		(layer "In9.Cu")
		(net "XDP_CPU1_TDO")
	)
	(segment
		(start 427.858936 -121.855484)
		(end 428.129446 -121.584974)
		(width 0.089408)
		(layer "In9.Cu")
		(net "XDP_CPU1_TDO")
	)
	(segment
		(start 367.783872 0.01143)
		(end 367.783872 4.324858)
		(width 0.089408)
		(layer "In9.Cu")
		(net "XDP_CPU1_TDO")
	)
	(segment
		(start 327.437496 3.548888)
		(end 327.795636 3.907028)
		(width 0.089408)
		(layer "In9.Cu")
		(net "XDP_CPU1_TDO")
	)
	(segment
		(start 354.4316 -3.6322)
		(end 355.215444 -4.416044)
		(width 0.089408)
		(layer "In9.Cu")
		(net "XDP_CPU1_TDO")
	)
	(segment
		(start 438.020206 -127.676148)
		(end 438.016142 -127.676148)
		(width 0.089408)
		(layer "In9.Cu")
		(net "XDP_CPU1_TDO")
	)
	(segment
		(start 353.411028 4.34594)
		(end 353.411028 -0.257048)
		(width 0.089408)
		(layer "In9.Cu")
		(net "XDP_CPU1_TDO")
	)
	(segment
		(start 327.795636 4.838192)
		(end 328.162158 5.204714)
		(width 0.089408)
		(layer "In9.Cu")
		(net "XDP_CPU1_TDO")
	)
	(segment
		(start 447.689986 -133.785864)
		(end 446.239138 -133.785864)
		(width 0.089408)
		(layer "In9.Cu")
		(net "XDP_CPU1_TDO")
	)
	(segment
		(start 266.015978 -14.97711)
		(end 265.848846 -15.144242)
		(width 0.089408)
		(layer "In9.Cu")
		(net "XDP_CPU1_TDO")
	)
	(segment
		(start 187.07481 -16.904716)
		(end 187.07481 -18.139156)
		(width 0.089408)
		(layer "In9.Cu")
		(net "XDP_CPU1_TDO")
	)
	(segment
		(start 367.783872 4.324858)
		(end 368.66449 5.205476)
		(width 0.089408)
		(layer "In9.Cu")
		(net "XDP_CPU1_TDO")
	)
	(segment
		(start 187.99683 -15.748)
		(end 187.366656 -16.378174)
		(width 0.089408)
		(layer "In9.Cu")
		(net "XDP_CPU1_TDO")
	)
	(segment
		(start 428.371 -117.050058)
		(end 428.371 -115.759738)
		(width 0.089408)
		(layer "In9.Cu")
		(net "XDP_CPU1_TDO")
	)
	(segment
		(start 354.4316 -1.27762)
		(end 354.4316 -3.6322)
		(width 0.089408)
		(layer "In9.Cu")
		(net "XDP_CPU1_TDO")
	)
	(segment
		(start 440.881262 -128.427988)
		(end 438.851548 -128.427988)
		(width 0.089408)
		(layer "In9.Cu")
		(net "XDP_CPU1_TDO")
	)
	(segment
		(start 185.38952 -18.690082)
		(end 184.277762 -19.80184)
		(width 0.089408)
		(layer "In9.Cu")
		(net "XDP_CPU1_TDO")
	)
	(segment
		(start 455.9808 -133.5278)
		(end 453.391524 -136.117076)
		(width 0.089408)
		(layer "In9.Cu")
		(net "XDP_CPU1_TDO")
	)
	(segment
		(start 438.851548 -128.427988)
		(end 438.100724 -127.677164)
		(width 0.089408)
		(layer "In9.Cu")
		(net "XDP_CPU1_TDO")
	)
	(segment
		(start 328.162158 5.204714)
		(end 344.019886 5.204714)
		(width 0.089408)
		(layer "In9.Cu")
		(net "XDP_CPU1_TDO")
	)
	(segment
		(start 427.946312 -117.474746)
		(end 428.371 -117.050058)
		(width 0.089408)
		(layer "In9.Cu")
		(net "XDP_CPU1_TDO")
	)
	(segment
		(start 345.5924 5.204714)
		(end 352.552254 5.204714)
		(width 0.089408)
		(layer "In9.Cu")
		(net "XDP_CPU1_TDO")
	)
	(segment
		(start 195.13169 -11.154156)
		(end 193.111628 -13.174218)
		(width 0.089408)
		(layer "In9.Cu")
		(net "XDP_CPU1_TDO")
	)
	(segment
		(start 186.523884 -18.690082)
		(end 185.38952 -18.690082)
		(width 0.089408)
		(layer "In9.Cu")
		(net "XDP_CPU1_TDO")
	)
	(segment
		(start 187.366656 -16.378174)
		(end 187.366656 -16.61287)
		(width 0.089408)
		(layer "In9.Cu")
		(net "XDP_CPU1_TDO")
	)
	(segment
		(start 427.41469 -118.006114)
		(end 427.946058 -117.474746)
		(width 0.089408)
		(layer "In9.Cu")
		(net "XDP_CPU1_TDO")
	)
	(segment
		(start 262.410702 -15.736316)
		(end 262.034274 -15.359888)
		(width 0.089408)
		(layer "In9.Cu")
		(net "XDP_CPU1_TDO")
	)
	(segment
		(start 262.034274 -15.359888)
		(end 261.671816 -15.359888)
		(width 0.089408)
		(layer "In9.Cu")
		(net "XDP_CPU1_TDO")
	)
	(segment
		(start 327.795636 3.907028)
		(end 327.795636 4.838192)
		(width 0.089408)
		(layer "In9.Cu")
		(net "XDP_CPU1_TDO")
	)
	(segment
		(start 344.6272 4.5974)
		(end 344.985086 4.5974)
		(width 0.089408)
		(layer "In9.Cu")
		(net "XDP_CPU1_TDO")
	)
	(segment
		(start 368.66449 5.205476)
		(end 424.968416 5.205476)
		(width 0.089408)
		(layer "In9.Cu")
		(net "XDP_CPU1_TDO")
	)
	(segment
		(start 427.364906 -114.753644)
		(end 427.02861 -114.753644)
		(width 0.089408)
		(layer "In9.Cu")
		(net "XDP_CPU1_TDO")
	)
	(segment
		(start 179.316888 -21.845778)
		(end 179.316888 -22.01164)
		(width 0.089408)
		(layer "In9.Cu")
		(net "XDP_CPU1_TDO")
	)
	(segment
		(start 428.442374 -124.5616)
		(end 427.858936 -123.978162)
		(width 0.089408)
		(layer "In9.Cu")
		(net "XDP_CPU1_TDO")
	)
	(segment
		(start 193.111628 -13.174218)
		(end 193.111628 -13.799058)
		(width 0.089408)
		(layer "In9.Cu")
		(net "XDP_CPU1_TDO")
	)
	(segment
		(start 427.41469 -118.006368)
		(end 427.41469 -118.006114)
		(width 0.089408)
		(layer "In9.Cu")
		(net "XDP_CPU1_TDO")
	)
	(segment
		(start 434.901594 -124.5616)
		(end 428.442374 -124.5616)
		(width 0.089408)
		(layer "In9.Cu")
		(net "XDP_CPU1_TDO")
	)
	(segment
		(start 173.4312 -29.168344)
		(end 173.4312 -30.013656)
		(width 0.089408)
		(layer "In11.Cu")
		(net "XDP_CPU1_TDO")
	)
	(segment
		(start 142.3416 -57.9628)
		(end 141.6812 -57.9628)
		(width 0.089408)
		(layer "In11.Cu")
		(net "XDP_CPU1_TDO")
	)
	(segment
		(start 138.2776 -59.8932)
		(end 137.8458 -60.325)
		(width 0.089408)
		(layer "In11.Cu")
		(net "XDP_CPU1_TDO")
	)
	(segment
		(start 165.10508 -33.4772)
		(end 159.19958 -35.92322)
		(width 0.089408)
		(layer "In11.Cu")
		(net "XDP_CPU1_TDO")
	)
	(segment
		(start 175.243998 -25.289002)
		(end 174.892208 -25.640792)
		(width 0.089408)
		(layer "In11.Cu")
		(net "XDP_CPU1_TDO")
	)
	(segment
		(start 136.1694 -61.2902)
		(end 135.553958 -61.2902)
		(width 0.089408)
		(layer "In11.Cu")
		(net "XDP_CPU1_TDO")
	)
	(segment
		(start 145.3388 -53.609494)
		(end 143.535908 -57.962292)
		(width 0.089408)
		(layer "In11.Cu")
		(net "XDP_CPU1_TDO")
	)
	(segment
		(start 141.6812 -57.9628)
		(end 141.3256 -58.3184)
		(width 0.089408)
		(layer "In11.Cu")
		(net "XDP_CPU1_TDO")
	)
	(segment
		(start 173.146974 -30.69971)
		(end 171.490132 -32.356552)
		(width 0.089408)
		(layer "In11.Cu")
		(net "XDP_CPU1_TDO")
	)
	(segment
		(start 137.4394 -60.325)
		(end 136.8806 -60.8838)
		(width 0.089408)
		(layer "In11.Cu")
		(net "XDP_CPU1_TDO")
	)
	(segment
		(start 472.84767 -64.49695)
		(end 473.24772 -64.897)
		(width 0.089408)
		(layer "In11.Cu")
		(net "XDP_CPU1_TDO")
	)
	(segment
		(start 143.535908 -57.962292)
		(end 143.2052 -58.293)
		(width 0.089408)
		(layer "In11.Cu")
		(net "XDP_CPU1_TDO")
	)
	(segment
		(start 174.892208 -25.640792)
		(end 173.4312 -29.168344)
		(width 0.089408)
		(layer "In11.Cu")
		(net "XDP_CPU1_TDO")
	)
	(segment
		(start 141.3256 -58.3184)
		(end 140.9446 -58.3184)
		(width 0.089408)
		(layer "In11.Cu")
		(net "XDP_CPU1_TDO")
	)
	(segment
		(start 173.4312 -30.013656)
		(end 173.146974 -30.69971)
		(width 0.089408)
		(layer "In11.Cu")
		(net "XDP_CPU1_TDO")
	)
	(segment
		(start 134.258304 -61.447934)
		(end 134.225538 -61.447934)
		(width 0.0889)
		(layer "In11.Cu")
		(net "XDP_CPU1_TDO")
	)
	(segment
		(start 490.634274 -56.350154)
		(end 492.181134 -56.350154)
		(width 0.089408)
		(layer "In11.Cu")
		(net "XDP_CPU1_TDO")
	)
	(segment
		(start 132.17652 -62.632844)
		(end 132.173218 -62.638686)
		(width 0.0889)
		(layer "In11.Cu")
		(net "XDP_CPU1_TDO")
	)
	(segment
		(start 474.684852 -64.897)
		(end 478.011744 -61.570108)
		(width 0.089408)
		(layer "In11.Cu")
		(net "XDP_CPU1_TDO")
	)
	(segment
		(start 473.24772 -64.897)
		(end 474.684852 -64.897)
		(width 0.089408)
		(layer "In11.Cu")
		(net "XDP_CPU1_TDO")
	)
	(segment
		(start 493.859312 -58.028332)
		(end 493.893602 -58.028332)
		(width 0.089408)
		(layer "In11.Cu")
		(net "XDP_CPU1_TDO")
	)
	(segment
		(start 179.316888 -22.01164)
		(end 179.22748 -22.101048)
		(width 0.089408)
		(layer "In11.Cu")
		(net "XDP_CPU1_TDO")
	)
	(segment
		(start 492.181134 -56.350154)
		(end 493.859312 -58.028332)
		(width 0.089408)
		(layer "In11.Cu")
		(net "XDP_CPU1_TDO")
	)
	(segment
		(start 145.3388 -52.049934)
		(end 145.3388 -53.609494)
		(width 0.089408)
		(layer "In11.Cu")
		(net "XDP_CPU1_TDO")
	)
	(segment
		(start 135.11022 -60.952888)
		(end 135.080248 -60.952888)
		(width 0.0889)
		(layer "In11.Cu")
		(net "XDP_CPU1_TDO")
	)
	(segment
		(start 484.890064 -60.19673)
		(end 486.787698 -60.19673)
		(width 0.089408)
		(layer "In11.Cu")
		(net "XDP_CPU1_TDO")
	)
	(segment
		(start 146.941032 -48.181768)
		(end 145.3388 -52.049934)
		(width 0.089408)
		(layer "In11.Cu")
		(net "XDP_CPU1_TDO")
	)
	(segment
		(start 137.8458 -60.325)
		(end 137.4394 -60.325)
		(width 0.089408)
		(layer "In11.Cu")
		(net "XDP_CPU1_TDO")
	)
	(segment
		(start 179.22748 -22.82952)
		(end 177.84572 -24.21128)
		(width 0.089408)
		(layer "In11.Cu")
		(net "XDP_CPU1_TDO")
	)
	(segment
		(start 168.784524 -33.4772)
		(end 165.10508 -33.4772)
		(width 0.089408)
		(layer "In11.Cu")
		(net "XDP_CPU1_TDO")
	)
	(segment
		(start 140.9446 -58.3184)
		(end 140.4366 -58.8264)
		(width 0.089408)
		(layer "In11.Cu")
		(net "XDP_CPU1_TDO")
	)
	(segment
		(start 132.541264 -62.438534)
		(end 132.519674 -62.438534)
		(width 0.0889)
		(layer "In11.Cu")
		(net "XDP_CPU1_TDO")
	)
	(segment
		(start 179.22748 -22.101048)
		(end 179.22748 -22.82952)
		(width 0.089408)
		(layer "In11.Cu")
		(net "XDP_CPU1_TDO")
	)
	(segment
		(start 143.2052 -58.293)
		(end 142.6718 -58.293)
		(width 0.089408)
		(layer "In11.Cu")
		(net "XDP_CPU1_TDO")
	)
	(segment
		(start 478.011744 -61.570108)
		(end 483.516686 -61.570108)
		(width 0.089408)
		(layer "In11.Cu")
		(net "XDP_CPU1_TDO")
	)
	(segment
		(start 139.573 -59.309)
		(end 139.1666 -59.309)
		(width 0.089408)
		(layer "In11.Cu")
		(net "XDP_CPU1_TDO")
	)
	(segment
		(start 483.516686 -61.570108)
		(end 484.890064 -60.19673)
		(width 0.089408)
		(layer "In11.Cu")
		(net "XDP_CPU1_TDO")
	)
	(segment
		(start 136.8806 -60.8838)
		(end 136.5758 -60.8838)
		(width 0.089408)
		(layer "In11.Cu")
		(net "XDP_CPU1_TDO")
	)
	(segment
		(start 140.0556 -58.8264)
		(end 139.573 -59.309)
		(width 0.089408)
		(layer "In11.Cu")
		(net "XDP_CPU1_TDO")
	)
	(segment
		(start 159.19958 -35.92322)
		(end 146.941032 -48.181768)
		(width 0.089408)
		(layer "In11.Cu")
		(net "XDP_CPU1_TDO")
	)
	(segment
		(start 135.553958 -61.2902)
		(end 135.50138 -61.237622)
		(width 0.089408)
		(layer "In11.Cu")
		(net "XDP_CPU1_TDO")
	)
	(segment
		(start 140.4366 -58.8264)
		(end 140.0556 -58.8264)
		(width 0.089408)
		(layer "In11.Cu")
		(net "XDP_CPU1_TDO")
	)
	(segment
		(start 177.84572 -24.21128)
		(end 175.243998 -25.289002)
		(width 0.089408)
		(layer "In11.Cu")
		(net "XDP_CPU1_TDO")
	)
	(segment
		(start 486.787698 -60.19673)
		(end 490.634274 -56.350154)
		(width 0.089408)
		(layer "In11.Cu")
		(net "XDP_CPU1_TDO")
	)
	(segment
		(start 171.490132 -32.356552)
		(end 168.784524 -33.4772)
		(width 0.089408)
		(layer "In11.Cu")
		(net "XDP_CPU1_TDO")
	)
	(segment
		(start 133.395974 -61.943488)
		(end 133.363208 -61.943488)
		(width 0.0889)
		(layer "In11.Cu")
		(net "XDP_CPU1_TDO")
	)
	(segment
		(start 139.1666 -59.309)
		(end 138.5824 -59.8932)
		(width 0.089408)
		(layer "In11.Cu")
		(net "XDP_CPU1_TDO")
	)
	(segment
		(start 138.5824 -59.8932)
		(end 138.2776 -59.8932)
		(width 0.089408)
		(layer "In11.Cu")
		(net "XDP_CPU1_TDO")
	)
	(segment
		(start 136.5758 -60.8838)
		(end 136.1694 -61.2902)
		(width 0.089408)
		(layer "In11.Cu")
		(net "XDP_CPU1_TDO")
	)
	(segment
		(start 142.6718 -58.293)
		(end 142.3416 -57.9628)
		(width 0.089408)
		(layer "In11.Cu")
		(net "XDP_CPU1_TDO")
	)
	(arc
		(start 132.173218 -62.638686)
		(mid 131.938204 -63.001787)
		(end 131.661408 -63.334138)
		(width 0.0889)
		(layer "In11.Cu")
		(net "XDP_CPU1_TDO")
	)
	(arc
		(start 133.890004 -61.648086)
		(mid 133.681396 -61.860018)
		(end 133.395974 -61.943488)
		(width 0.0889)
		(layer "In11.Cu")
		(net "XDP_CPU1_TDO")
	)
	(arc
		(start 135.441944 -61.152786)
		(mid 135.301865 -61.01005)
		(end 135.11022 -60.952888)
		(width 0.0889)
		(layer "In11.Cu")
		(net "XDP_CPU1_TDO")
	)
	(arc
		(start 133.363208 -61.943488)
		(mid 133.171566 -62.000654)
		(end 133.031484 -62.143386)
		(width 0.0889)
		(layer "In11.Cu")
		(net "XDP_CPU1_TDO")
	)
	(arc
		(start 135.080248 -60.952888)
		(mid 134.888606 -61.010054)
		(end 134.748524 -61.152786)
		(width 0.0889)
		(layer "In11.Cu")
		(net "XDP_CPU1_TDO")
	)
	(arc
		(start 134.225538 -61.447934)
		(mid 134.031688 -61.504284)
		(end 133.890004 -61.648086)
		(width 0.0889)
		(layer "In11.Cu")
		(net "XDP_CPU1_TDO")
	)
	(arc
		(start 133.031484 -62.143386)
		(mid 132.82448 -62.35425)
		(end 132.541264 -62.438534)
		(width 0.0889)
		(layer "In11.Cu")
		(net "XDP_CPU1_TDO")
	)
	(arc
		(start 135.50138 -61.237622)
		(mid 135.469796 -61.196511)
		(end 135.441944 -61.152786)
		(width 0.0889)
		(layer "In11.Cu")
		(net "XDP_CPU1_TDO")
	)
	(arc
		(start 134.748524 -61.152786)
		(mid 134.54152 -61.36365)
		(end 134.258304 -61.447934)
		(width 0.0889)
		(layer "In11.Cu")
		(net "XDP_CPU1_TDO")
	)
	(arc
		(start 132.519674 -62.438534)
		(mid 132.322513 -62.490493)
		(end 132.17652 -62.632844)
		(width 0.0889)
		(layer "In11.Cu")
		(net "XDP_CPU1_TDO")
	)
	(segment
		(start 133.665214 -60.857384)
		(end 134.236714 -60.857384)
		(width 0.10795)
		(layer "F.Cu")
		(net "TP_XDP_CPU1_OBSDATA_B3_MBP5_N")
	)
	(via
		(at 134.236714 -60.857384)
		(size 0.508)
		(drill 0.254)
		(layers "F.Cu" "B.Cu")
		(net "TP_XDP_CPU1_OBSDATA_B3_MBP5_N")
	)
	(segment
		(start 132.806694 -61.352938)
		(end 133.378194 -61.352938)
		(width 0.10795)
		(layer "F.Cu")
		(net "TP_XDP_CPU1_OBSDATA_B2_MBP4_N")
	)
	(via
		(at 133.378194 -61.352938)
		(size 0.508)
		(drill 0.254)
		(layers "F.Cu" "B.Cu")
		(net "TP_XDP_CPU1_OBSDATA_B2_MBP4_N")
	)
	(segment
		(start 133.665214 -63.829184)
		(end 134.236714 -63.829184)
		(width 0.10795)
		(layer "F.Cu")
		(net "TP_XDP_CPU1_OBSDATA_B1_MBP3_N")
	)
	(via
		(at 134.236714 -63.829184)
		(size 0.508)
		(drill 0.254)
		(layers "F.Cu" "B.Cu")
		(net "TP_XDP_CPU1_OBSDATA_B1_MBP3_N")
	)
	(segment
		(start 134.523734 -64.324738)
		(end 135.095234 -64.324738)
		(width 0.10795)
		(layer "F.Cu")
		(net "TP_XDP_CPU1_OBSDATA_B0_MBP2_N")
	)
	(via
		(at 135.095234 -64.324738)
		(size 0.508)
		(drill 0.254)
		(layers "F.Cu" "B.Cu")
		(net "TP_XDP_CPU1_OBSDATA_B0_MBP2_N")
	)
	(segment
		(start 298.665646 -63.829184)
		(end 299.237146 -63.829184)
		(width 0.10795)
		(layer "F.Cu")
		(net "TP_XDP_CPU0_OBSDATA_A1_MBP3_N")
	)
	(via
		(at 299.237146 -63.829184)
		(size 0.508)
		(drill 0.254)
		(layers "F.Cu" "B.Cu")
		(net "TP_XDP_CPU0_OBSDATA_A1_MBP3_N")
	)
	(segment
		(start 299.524166 -64.324738)
		(end 300.095666 -64.324738)
		(width 0.10795)
		(layer "F.Cu")
		(net "TP_XDP_CPU0_OBSDATA_A0_MBP2_N")
	)
	(via
		(at 300.095666 -64.324738)
		(size 0.508)
		(drill 0.254)
		(layers "F.Cu" "B.Cu")
		(net "TP_XDP_CPU0_OBSDATA_A0_MBP2_N")
	)
	(segment
		(start 140.533374 -97.509584)
		(end 148.591016 -97.509584)
		(width 0.10795)
		(layer "F.Cu")
		(net "TP_P3E_CPU1_PE1_MP_TXP<7>")
	)
	(segment
		(start 152.273 -94.9452)
		(end 153.035 -94.1832)
		(width 0.10795)
		(layer "F.Cu")
		(net "TP_P3E_CPU1_PE1_MP_TXP<7>")
	)
	(segment
		(start 151.1554 -94.9452)
		(end 152.273 -94.9452)
		(width 0.10795)
		(layer "F.Cu")
		(net "TP_P3E_CPU1_PE1_MP_TXP<7>")
	)
	(segment
		(start 148.591016 -97.509584)
		(end 151.1554 -94.9452)
		(width 0.10795)
		(layer "F.Cu")
		(net "TP_P3E_CPU1_PE1_MP_TXP<7>")
	)
	(via
		(at 153.035 -94.1832)
		(size 0.762)
		(drill 0.381)
		(layers "F.Cu" "B.Cu")
		(net "TP_P3E_CPU1_PE1_MP_TXP<7>")
	)
	(segment
		(start 150.4442 -94.2086)
		(end 148.628862 -96.023938)
		(width 0.10795)
		(layer "F.Cu")
		(net "TP_P3E_CPU1_PE1_MP_TXP<6>")
	)
	(segment
		(start 151.5364 -94.2086)
		(end 150.4442 -94.2086)
		(width 0.10795)
		(layer "F.Cu")
		(net "TP_P3E_CPU1_PE1_MP_TXP<6>")
	)
	(segment
		(start 148.628862 -96.023938)
		(end 141.391894 -96.023938)
		(width 0.10795)
		(layer "F.Cu")
		(net "TP_P3E_CPU1_PE1_MP_TXP<6>")
	)
	(via
		(at 151.5364 -94.2086)
		(size 0.762)
		(drill 0.381)
		(layers "F.Cu" "B.Cu")
		(net "TP_P3E_CPU1_PE1_MP_TXP<6>")
	)
	(segment
		(start 140.533374 -94.538038)
		(end 141.104874 -94.538038)
		(width 0.10795)
		(layer "F.Cu")
		(net "TP_P3E_CPU1_PE1_MP_TXP<5>")
	)
	(via
		(at 141.104874 -94.538038)
		(size 0.508)
		(drill 0.254)
		(layers "F.Cu" "B.Cu")
		(net "TP_P3E_CPU1_PE1_MP_TXP<5>")
	)
	(segment
		(start 148.955252 -93.547184)
		(end 140.533374 -93.547184)
		(width 0.10795)
		(layer "F.Cu")
		(net "TP_P3E_CPU1_PE1_MP_TXP<4>")
	)
	(segment
		(start 150.833836 -91.6686)
		(end 148.955252 -93.547184)
		(width 0.10795)
		(layer "F.Cu")
		(net "TP_P3E_CPU1_PE1_MP_TXP<4>")
	)
	(segment
		(start 151.5364 -91.6686)
		(end 150.833836 -91.6686)
		(width 0.10795)
		(layer "F.Cu")
		(net "TP_P3E_CPU1_PE1_MP_TXP<4>")
	)
	(via
		(at 151.5364 -91.6686)
		(size 0.762)
		(drill 0.381)
		(layers "F.Cu" "B.Cu")
		(net "TP_P3E_CPU1_PE1_MP_TXP<4>")
	)
	(segment
		(start 139.674854 -92.061538)
		(end 140.246354 -92.061538)
		(width 0.10795)
		(layer "F.Cu")
		(net "TP_P3E_CPU1_PE1_MP_TXP<3>")
	)
	(via
		(at 140.246354 -92.061538)
		(size 0.4826)
		(drill 0.254)
		(layers "F.Cu" "B.Cu")
		(net "TP_P3E_CPU1_PE1_MP_TXP<3>")
	)
	(segment
		(start 151.003 -90.3986)
		(end 148.845016 -92.556584)
		(width 0.10795)
		(layer "F.Cu")
		(net "TP_P3E_CPU1_PE1_MP_TXP<2>")
	)
	(segment
		(start 148.845016 -92.556584)
		(end 140.533374 -92.556584)
		(width 0.10795)
		(layer "F.Cu")
		(net "TP_P3E_CPU1_PE1_MP_TXP<2>")
	)
	(segment
		(start 151.5364 -90.3986)
		(end 151.003 -90.3986)
		(width 0.10795)
		(layer "F.Cu")
		(net "TP_P3E_CPU1_PE1_MP_TXP<2>")
	)
	(via
		(at 151.5364 -90.3986)
		(size 0.762)
		(drill 0.381)
		(layers "F.Cu" "B.Cu")
		(net "TP_P3E_CPU1_PE1_MP_TXP<2>")
	)
	(segment
		(start 142.5956 -91.567)
		(end 143.129 -91.567)
		(width 0.10795)
		(layer "F.Cu")
		(net "TP_P3E_CPU1_PE1_MP_TXP<1>")
	)
	(segment
		(start 142.250414 -91.565984)
		(end 142.594584 -91.565984)
		(width 0.10795)
		(layer "F.Cu")
		(net "TP_P3E_CPU1_PE1_MP_TXP<1>")
	)
	(segment
		(start 142.594584 -91.565984)
		(end 142.5956 -91.567)
		(width 0.10795)
		(layer "F.Cu")
		(net "TP_P3E_CPU1_PE1_MP_TXP<1>")
	)
	(via
		(at 143.129 -91.567)
		(size 0.508)
		(drill 0.254)
		(layers "F.Cu" "B.Cu")
		(net "TP_P3E_CPU1_PE1_MP_TXP<1>")
	)
	(segment
		(start 141.391894 -90.080338)
		(end 141.963394 -90.080338)
		(width 0.10795)
		(layer "F.Cu")
		(net "TP_P3E_CPU1_PE1_MP_TXP<0>")
	)
	(via
		(at 141.963394 -90.080338)
		(size 0.4826)
		(drill 0.254)
		(layers "F.Cu" "B.Cu")
		(net "TP_P3E_CPU1_PE1_MP_TXP<0>")
	)
	(segment
		(start 139.674854 -97.014538)
		(end 140.246354 -97.014538)
		(width 0.10795)
		(layer "F.Cu")
		(net "TP_P3E_CPU1_PE1_MP_TXN<7>")
	)
	(via
		(at 140.246354 -97.014538)
		(size 0.4826)
		(drill 0.254)
		(layers "F.Cu" "B.Cu")
		(net "TP_P3E_CPU1_PE1_MP_TXN<7>")
	)
	(segment
		(start 140.533374 -96.518984)
		(end 141.104874 -96.518984)
		(width 0.10795)
		(layer "F.Cu")
		(net "TP_P3E_CPU1_PE1_MP_TXN<6>")
	)
	(via
		(at 141.104874 -96.518984)
		(size 0.4826)
		(drill 0.254)
		(layers "F.Cu" "B.Cu")
		(net "TP_P3E_CPU1_PE1_MP_TXN<6>")
	)
	(segment
		(start 148.032216 -95.528384)
		(end 140.533374 -95.528384)
		(width 0.10795)
		(layer "F.Cu")
		(net "TP_P3E_CPU1_PE1_MP_TXN<5>")
	)
	(segment
		(start 151.5364 -92.9386)
		(end 150.622 -92.9386)
		(width 0.10795)
		(layer "F.Cu")
		(net "TP_P3E_CPU1_PE1_MP_TXN<5>")
	)
	(segment
		(start 150.622 -92.9386)
		(end 148.032216 -95.528384)
		(width 0.10795)
		(layer "F.Cu")
		(net "TP_P3E_CPU1_PE1_MP_TXN<5>")
	)
	(via
		(at 151.5364 -92.9386)
		(size 0.762)
		(drill 0.381)
		(layers "F.Cu" "B.Cu")
		(net "TP_P3E_CPU1_PE1_MP_TXN<5>")
	)
	(segment
		(start 139.674854 -94.042738)
		(end 140.246354 -94.042738)
		(width 0.10795)
		(layer "F.Cu")
		(net "TP_P3E_CPU1_PE1_MP_TXN<4>")
	)
	(via
		(at 140.246354 -94.042738)
		(size 0.508)
		(drill 0.254)
		(layers "F.Cu" "B.Cu")
		(net "TP_P3E_CPU1_PE1_MP_TXN<4>")
	)
	(segment
		(start 139.674854 -93.052138)
		(end 140.246354 -93.052138)
		(width 0.10795)
		(layer "F.Cu")
		(net "TP_P3E_CPU1_PE1_MP_TXN<3>")
	)
	(via
		(at 140.246354 -93.052138)
		(size 0.508)
		(drill 0.254)
		(layers "F.Cu" "B.Cu")
		(net "TP_P3E_CPU1_PE1_MP_TXN<3>")
	)
	(segment
		(start 141.391894 -93.052138)
		(end 142.039594 -93.052138)
		(width 0.10795)
		(layer "F.Cu")
		(net "TP_P3E_CPU1_PE1_MP_TXN<2>")
	)
	(via
		(at 142.039594 -93.052138)
		(size 0.4826)
		(drill 0.254)
		(layers "F.Cu" "B.Cu")
		(net "TP_P3E_CPU1_PE1_MP_TXN<2>")
	)
	(segment
		(start 148.120862 -92.061538)
		(end 141.391894 -92.061538)
		(width 0.10795)
		(layer "F.Cu")
		(net "TP_P3E_CPU1_PE1_MP_TXN<1>")
	)
	(segment
		(start 151.0538 -89.1286)
		(end 148.120862 -92.061538)
		(width 0.10795)
		(layer "F.Cu")
		(net "TP_P3E_CPU1_PE1_MP_TXN<1>")
	)
	(segment
		(start 151.5364 -89.1286)
		(end 151.0538 -89.1286)
		(width 0.10795)
		(layer "F.Cu")
		(net "TP_P3E_CPU1_PE1_MP_TXN<1>")
	)
	(via
		(at 151.5364 -89.1286)
		(size 0.762)
		(drill 0.381)
		(layers "F.Cu" "B.Cu")
		(net "TP_P3E_CPU1_PE1_MP_TXN<1>")
	)
	(segment
		(start 147.968462 -91.070938)
		(end 141.391894 -91.070938)
		(width 0.10795)
		(layer "F.Cu")
		(net "TP_P3E_CPU1_PE1_MP_TXN<0>")
	)
	(segment
		(start 151.5364 -87.8586)
		(end 151.1808 -87.8586)
		(width 0.10795)
		(layer "F.Cu")
		(net "TP_P3E_CPU1_PE1_MP_TXN<0>")
	)
	(segment
		(start 151.1808 -87.8586)
		(end 147.968462 -91.070938)
		(width 0.10795)
		(layer "F.Cu")
		(net "TP_P3E_CPU1_PE1_MP_TXN<0>")
	)
	(via
		(at 151.5364 -87.8586)
		(size 0.762)
		(drill 0.381)
		(layers "F.Cu" "B.Cu")
		(net "TP_P3E_CPU1_PE1_MP_TXN<0>")
	)
	(segment
		(start 134.523734 -96.023938)
		(end 135.095234 -96.023938)
		(width 0.10795)
		(layer "F.Cu")
		(net "TP_P3E_CPU1_PE1_MP_RXP<7>")
	)
	(via
		(at 135.095234 -96.023938)
		(size 0.4826)
		(drill 0.254)
		(layers "F.Cu" "B.Cu")
		(net "TP_P3E_CPU1_PE1_MP_RXP<7>")
	)
	(segment
		(start 136.240774 -95.033084)
		(end 136.812274 -95.033084)
		(width 0.10795)
		(layer "F.Cu")
		(net "TP_P3E_CPU1_PE1_MP_RXP<6>")
	)
	(via
		(at 136.812274 -95.033084)
		(size 0.4826)
		(drill 0.254)
		(layers "F.Cu" "B.Cu")
		(net "TP_P3E_CPU1_PE1_MP_RXP<6>")
	)
	(segment
		(start 135.382254 -93.547184)
		(end 135.953754 -93.547184)
		(width 0.10795)
		(layer "F.Cu")
		(net "TP_P3E_CPU1_PE1_MP_RXP<5>")
	)
	(via
		(at 135.953754 -93.547184)
		(size 0.4826)
		(drill 0.254)
		(layers "F.Cu" "B.Cu")
		(net "TP_P3E_CPU1_PE1_MP_RXP<5>")
	)
	(segment
		(start 135.382254 -92.556584)
		(end 135.953754 -92.556584)
		(width 0.10795)
		(layer "F.Cu")
		(net "TP_P3E_CPU1_PE1_MP_RXP<4>")
	)
	(via
		(at 135.953754 -92.556584)
		(size 0.4826)
		(drill 0.254)
		(layers "F.Cu" "B.Cu")
		(net "TP_P3E_CPU1_PE1_MP_RXP<4>")
	)
	(segment
		(start 134.523734 -91.070938)
		(end 135.095234 -91.070938)
		(width 0.10795)
		(layer "F.Cu")
		(net "TP_P3E_CPU1_PE1_MP_RXP<3>")
	)
	(via
		(at 135.095234 -91.070938)
		(size 0.4826)
		(drill 0.254)
		(layers "F.Cu" "B.Cu")
		(net "TP_P3E_CPU1_PE1_MP_RXP<3>")
	)
	(segment
		(start 135.382254 -91.565984)
		(end 135.953754 -91.565984)
		(width 0.10795)
		(layer "F.Cu")
		(net "TP_P3E_CPU1_PE1_MP_RXP<2>")
	)
	(via
		(at 135.953754 -91.565984)
		(size 0.4826)
		(drill 0.254)
		(layers "F.Cu" "B.Cu")
		(net "TP_P3E_CPU1_PE1_MP_RXP<2>")
	)
	(segment
		(start 137.670794 -90.575384)
		(end 137.099294 -90.575384)
		(width 0.10795)
		(layer "F.Cu")
		(net "TP_P3E_CPU1_PE1_MP_RXP<1>")
	)
	(via
		(at 137.670794 -90.575384)
		(size 0.4826)
		(drill 0.254)
		(layers "F.Cu" "B.Cu")
		(net "TP_P3E_CPU1_PE1_MP_RXP<1>")
	)
	(segment
		(start 136.240774 -89.089738)
		(end 136.812274 -89.089738)
		(width 0.10795)
		(layer "F.Cu")
		(net "TP_P3E_CPU1_PE1_MP_RXP<0>")
	)
	(via
		(at 136.812274 -89.089738)
		(size 0.4826)
		(drill 0.254)
		(layers "F.Cu" "B.Cu")
		(net "TP_P3E_CPU1_PE1_MP_RXP<0>")
	)
	(segment
		(start 135.382254 -96.518984)
		(end 135.953754 -96.518984)
		(width 0.10795)
		(layer "F.Cu")
		(net "TP_P3E_CPU1_PE1_MP_RXN<7>")
	)
	(via
		(at 135.953754 -96.518984)
		(size 0.4826)
		(drill 0.254)
		(layers "F.Cu" "B.Cu")
		(net "TP_P3E_CPU1_PE1_MP_RXN<7>")
	)
	(segment
		(start 135.382254 -95.528384)
		(end 135.953754 -95.528384)
		(width 0.10795)
		(layer "F.Cu")
		(net "TP_P3E_CPU1_PE1_MP_RXN<6>")
	)
	(via
		(at 135.953754 -95.528384)
		(size 0.508)
		(drill 0.254)
		(layers "F.Cu" "B.Cu")
		(net "TP_P3E_CPU1_PE1_MP_RXN<6>")
	)
	(segment
		(start 135.382254 -94.538038)
		(end 135.953754 -94.538038)
		(width 0.10795)
		(layer "F.Cu")
		(net "TP_P3E_CPU1_PE1_MP_RXN<5>")
	)
	(via
		(at 135.953754 -94.538038)
		(size 0.4826)
		(drill 0.254)
		(layers "F.Cu" "B.Cu")
		(net "TP_P3E_CPU1_PE1_MP_RXN<5>")
	)
	(segment
		(start 134.523734 -93.052138)
		(end 135.095234 -93.052138)
		(width 0.10795)
		(layer "F.Cu")
		(net "TP_P3E_CPU1_PE1_MP_RXN<4>")
	)
	(via
		(at 135.095234 -93.052138)
		(size 0.4826)
		(drill 0.254)
		(layers "F.Cu" "B.Cu")
		(net "TP_P3E_CPU1_PE1_MP_RXN<4>")
	)
	(segment
		(start 134.523734 -92.061538)
		(end 135.095234 -92.061538)
		(width 0.10795)
		(layer "F.Cu")
		(net "TP_P3E_CPU1_PE1_MP_RXN<3>")
	)
	(via
		(at 135.095234 -92.061538)
		(size 0.4826)
		(drill 0.254)
		(layers "F.Cu" "B.Cu")
		(net "TP_P3E_CPU1_PE1_MP_RXN<3>")
	)
	(segment
		(start 136.240774 -92.061538)
		(end 136.812274 -92.061538)
		(width 0.10795)
		(layer "F.Cu")
		(net "TP_P3E_CPU1_PE1_MP_RXN<2>")
	)
	(via
		(at 136.812274 -92.061538)
		(size 0.4826)
		(drill 0.254)
		(layers "F.Cu" "B.Cu")
		(net "TP_P3E_CPU1_PE1_MP_RXN<2>")
	)
	(segment
		(start 136.240774 -91.070938)
		(end 136.812274 -91.070938)
		(width 0.10795)
		(layer "F.Cu")
		(net "TP_P3E_CPU1_PE1_MP_RXN<1>")
	)
	(via
		(at 136.812274 -91.070938)
		(size 0.4826)
		(drill 0.254)
		(layers "F.Cu" "B.Cu")
		(net "TP_P3E_CPU1_PE1_MP_RXN<1>")
	)
	(segment
		(start 136.240774 -90.080338)
		(end 136.812274 -90.080338)
		(width 0.10795)
		(layer "F.Cu")
		(net "TP_P3E_CPU1_PE1_MP_RXN<0>")
	)
	(via
		(at 136.812274 -90.080338)
		(size 0.4826)
		(drill 0.254)
		(layers "F.Cu" "B.Cu")
		(net "TP_P3E_CPU1_PE1_MP_RXN<0>")
	)
	(segment
		(start 408.66314 -62.83198)
		(end 409.361132 -63.529972)
		(width 0.10795)
		(layer "F.Cu")
		(net "SPI_PCH_TPM_MISO_R")
	)
	(segment
		(start 409.361132 -63.529972)
		(end 410.340048 -63.529972)
		(width 0.10795)
		(layer "F.Cu")
		(net "SPI_PCH_TPM_MISO_R")
	)
	(segment
		(start 408.05608 -62.83198)
		(end 408.66314 -62.83198)
		(width 0.10795)
		(layer "F.Cu")
		(net "SPI_PCH_TPM_MISO_R")
	)
	(segment
		(start 407.8351 -62.611)
		(end 408.05608 -62.83198)
		(width 0.10795)
		(layer "F.Cu")
		(net "SPI_PCH_TPM_MISO_R")
	)
	(segment
		(start 407.57094 -61.6204)
		(end 407.5176 -61.6204)
		(width 0.10795)
		(layer "F.Cu")
		(net "SPI_PCH_TPM_CS_R_N")
	)
	(segment
		(start 408.413458 -62.44336)
		(end 408.158696 -62.188598)
		(width 0.10795)
		(layer "F.Cu")
		(net "SPI_PCH_TPM_CS_R_N")
	)
	(segment
		(start 407.014172 -60.253372)
		(end 407.5176 -60.7568)
		(width 0.10795)
		(layer "F.Cu")
		(net "SPI_PCH_TPM_CS_R_N")
	)
	(segment
		(start 410.340048 -62.529974)
		(end 409.148534 -62.529974)
		(width 0.10795)
		(layer "F.Cu")
		(net "SPI_PCH_TPM_CS_R_N")
	)
	(segment
		(start 408.158696 -62.188598)
		(end 408.139138 -62.188598)
		(width 0.10795)
		(layer "F.Cu")
		(net "SPI_PCH_TPM_CS_R_N")
	)
	(segment
		(start 409.148534 -62.529974)
		(end 409.06192 -62.44336)
		(width 0.10795)
		(layer "F.Cu")
		(net "SPI_PCH_TPM_CS_R_N")
	)
	(segment
		(start 409.06192 -62.44336)
		(end 408.413458 -62.44336)
		(width 0.10795)
		(layer "F.Cu")
		(net "SPI_PCH_TPM_CS_R_N")
	)
	(segment
		(start 408.139138 -62.188598)
		(end 407.57094 -61.6204)
		(width 0.10795)
		(layer "F.Cu")
		(net "SPI_PCH_TPM_CS_R_N")
	)
	(segment
		(start 407.5176 -60.7568)
		(end 407.5176 -61.6204)
		(width 0.10795)
		(layer "F.Cu")
		(net "SPI_PCH_TPM_CS_R_N")
	)
	(via
		(at 407.014172 -60.253372)
		(size 0.762)
		(drill 0.381)
		(layers "F.Cu" "B.Cu")
		(net "SPI_PCH_TPM_CS_R_N")
	)
	(via
		(at 370.249196 -4.260596)
		(size 0.6604)
		(drill 0.3302)
		(layers "F.Cu" "B.Cu")
		(net "PD_ME_RCVR_N")
	)
	(segment
		(start 369.7986 -3.81)
		(end 369.7986 -2.743708)
		(width 0.10795)
		(layer "B.Cu")
		(net "PD_ME_RCVR_N")
	)
	(segment
		(start 370.51361 -2.028698)
		(end 370.51361 -0.139192)
		(width 0.10795)
		(layer "B.Cu")
		(net "PD_ME_RCVR_N")
	)
	(segment
		(start 370.2304 2.6924)
		(end 371.348 3.81)
		(width 0.10795)
		(layer "B.Cu")
		(net "PD_ME_RCVR_N")
	)
	(segment
		(start 369.7351 -5.3467)
		(end 369.5954 -5.3467)
		(width 0.10795)
		(layer "B.Cu")
		(net "PD_ME_RCVR_N")
	)
	(segment
		(start 370.249196 -4.260596)
		(end 369.7986 -3.81)
		(width 0.10795)
		(layer "B.Cu")
		(net "PD_ME_RCVR_N")
	)
	(segment
		(start 370.2304 0.144018)
		(end 370.2304 2.6924)
		(width 0.10795)
		(layer "B.Cu")
		(net "PD_ME_RCVR_N")
	)
	(segment
		(start 370.249196 -4.260596)
		(end 370.249196 -4.832604)
		(width 0.10795)
		(layer "B.Cu")
		(net "PD_ME_RCVR_N")
	)
	(segment
		(start 370.51361 -0.139192)
		(end 370.2304 0.144018)
		(width 0.10795)
		(layer "B.Cu")
		(net "PD_ME_RCVR_N")
	)
	(segment
		(start 369.7986 -2.743708)
		(end 370.51361 -2.028698)
		(width 0.10795)
		(layer "B.Cu")
		(net "PD_ME_RCVR_N")
	)
	(segment
		(start 370.249196 -4.832604)
		(end 369.7351 -5.3467)
		(width 0.10795)
		(layer "B.Cu")
		(net "PD_ME_RCVR_N")
	)
	(segment
		(start 379.81255 -123.821444)
		(end 379.31725 -123.59132)
		(width 0.1143)
		(layer "F.Cu")
		(net "P3E_CPU0_PE1_PCH_R_RXP<9>")
	)
	(via
		(at 374.772682 -123.9647)
		(size 0.508)
		(drill 0.254)
		(layers "F.Cu" "B.Cu")
		(net "P3E_CPU0_PE1_PCH_R_RXP<9>")
	)
	(via
		(at 379.81255 -123.821444)
		(size 0.508)
		(drill 0.254)
		(layers "F.Cu" "B.Cu")
		(net "P3E_CPU0_PE1_PCH_R_RXP<9>")
	)
	(segment
		(start 368.716814 -124.389642)
		(end 369.197382 -124.87021)
		(width 0.1143)
		(layer "B.Cu")
		(net "P3E_CPU0_PE1_PCH_R_RXP<9>")
	)
	(segment
		(start 379.474476 -123.821444)
		(end 379.81255 -123.821444)
		(width 0.0889)
		(layer "B.Cu")
		(net "P3E_CPU0_PE1_PCH_R_RXP<9>")
	)
	(segment
		(start 371.77853 -124.551694)
		(end 371.77853 -124.212604)
		(width 0.1143)
		(layer "B.Cu")
		(net "P3E_CPU0_PE1_PCH_R_RXP<9>")
	)
	(segment
		(start 371.77853 -124.212604)
		(end 372.160546 -123.830588)
		(width 0.1143)
		(layer "B.Cu")
		(net "P3E_CPU0_PE1_PCH_R_RXP<9>")
	)
	(segment
		(start 371.460014 -124.87021)
		(end 371.77853 -124.551694)
		(width 0.1143)
		(layer "B.Cu")
		(net "P3E_CPU0_PE1_PCH_R_RXP<9>")
	)
	(segment
		(start 376.77598 -123.9901)
		(end 377.37669 -123.38939)
		(width 0.0889)
		(layer "B.Cu")
		(net "P3E_CPU0_PE1_PCH_R_RXP<9>")
	)
	(segment
		(start 375.247662 -123.9647)
		(end 375.270014 -123.9647)
		(width 0.0889)
		(layer "B.Cu")
		(net "P3E_CPU0_PE1_PCH_R_RXP<9>")
	)
	(segment
		(start 374.285764 -123.830588)
		(end 374.419876 -123.9647)
		(width 0.1143)
		(layer "B.Cu")
		(net "P3E_CPU0_PE1_PCH_R_RXP<9>")
	)
	(segment
		(start 372.160546 -123.830588)
		(end 374.285764 -123.830588)
		(width 0.1143)
		(layer "B.Cu")
		(net "P3E_CPU0_PE1_PCH_R_RXP<9>")
	)
	(segment
		(start 374.772682 -123.9647)
		(end 375.247662 -123.9647)
		(width 0.1143)
		(layer "B.Cu")
		(net "P3E_CPU0_PE1_PCH_R_RXP<9>")
	)
	(segment
		(start 369.197382 -124.87021)
		(end 371.460014 -124.87021)
		(width 0.1143)
		(layer "B.Cu")
		(net "P3E_CPU0_PE1_PCH_R_RXP<9>")
	)
	(segment
		(start 374.419876 -123.9647)
		(end 374.772682 -123.9647)
		(width 0.1143)
		(layer "B.Cu")
		(net "P3E_CPU0_PE1_PCH_R_RXP<9>")
	)
	(segment
		(start 375.270014 -123.9901)
		(end 376.77598 -123.9901)
		(width 0.0889)
		(layer "B.Cu")
		(net "P3E_CPU0_PE1_PCH_R_RXP<9>")
	)
	(segment
		(start 375.270014 -123.9647)
		(end 375.270014 -123.9901)
		(width 0.0889)
		(layer "B.Cu")
		(net "P3E_CPU0_PE1_PCH_R_RXP<9>")
	)
	(segment
		(start 379.409452 -123.75642)
		(end 379.474476 -123.821444)
		(width 0.0889)
		(layer "B.Cu")
		(net "P3E_CPU0_PE1_PCH_R_RXP<9>")
	)
	(arc
		(start 378.126752 -123.309634)
		(mid 378.32665 -123.363133)
		(end 378.526548 -123.309634)
		(width 0.0889)
		(layer "B.Cu")
		(net "P3E_CPU0_PE1_PCH_R_RXP<9>")
	)
	(arc
		(start 377.8123 -123.2154)
		(mid 377.975042 -123.244107)
		(end 378.126752 -123.309634)
		(width 0.0889)
		(layer "B.Cu")
		(net "P3E_CPU0_PE1_PCH_R_RXP<9>")
	)
	(arc
		(start 377.37669 -123.38939)
		(mid 377.57517 -123.254025)
		(end 377.8123 -123.2154)
		(width 0.0889)
		(layer "B.Cu")
		(net "P3E_CPU0_PE1_PCH_R_RXP<9>")
	)
	(arc
		(start 378.526548 -123.309634)
		(mid 379.088816 -123.294192)
		(end 379.409452 -123.75642)
		(width 0.0889)
		(layer "B.Cu")
		(net "P3E_CPU0_PE1_PCH_R_RXP<9>")
	)
	(segment
		(start 379.31725 -121.87428)
		(end 379.743716 -122.0724)
		(width 0.1143)
		(layer "F.Cu")
		(net "P3E_CPU0_PE1_PCH_R_RXP<8>")
	)
	(segment
		(start 379.743716 -122.0724)
		(end 379.81255 -122.104404)
		(width 0.1143)
		(layer "F.Cu")
		(net "P3E_CPU0_PE1_PCH_R_RXP<8>")
	)
	(via
		(at 374.204484 -122.507248)
		(size 0.508)
		(drill 0.254)
		(layers "F.Cu" "B.Cu")
		(net "P3E_CPU0_PE1_PCH_R_RXP<8>")
	)
	(via
		(at 379.81255 -122.104404)
		(size 0.508)
		(drill 0.254)
		(layers "F.Cu" "B.Cu")
		(net "P3E_CPU0_PE1_PCH_R_RXP<8>")
	)
	(segment
		(start 379.554232 -122.421396)
		(end 379.64364 -122.39752)
		(width 0.0889)
		(layer "B.Cu")
		(net "P3E_CPU0_PE1_PCH_R_RXP<8>")
	)
	(segment
		(start 375.727214 -122.80519)
		(end 377.414282 -122.804682)
		(width 0.0889)
		(layer "B.Cu")
		(net "P3E_CPU0_PE1_PCH_R_RXP<8>")
	)
	(segment
		(start 375.172224 -122.77979)
		(end 375.679716 -122.77979)
		(width 0.1143)
		(layer "B.Cu")
		(net "P3E_CPU0_PE1_PCH_R_RXP<8>")
	)
	(segment
		(start 374.204484 -122.507248)
		(end 375.172224 -122.77979)
		(width 0.1143)
		(layer "B.Cu")
		(net "P3E_CPU0_PE1_PCH_R_RXP<8>")
	)
	(segment
		(start 369.167156 -121.900442)
		(end 368.709956 -121.443242)
		(width 0.1143)
		(layer "B.Cu")
		(net "P3E_CPU0_PE1_PCH_R_RXP<8>")
	)
	(segment
		(start 374.204484 -122.507248)
		(end 372.048786 -121.900442)
		(width 0.1143)
		(layer "B.Cu")
		(net "P3E_CPU0_PE1_PCH_R_RXP<8>")
	)
	(segment
		(start 375.679716 -122.77979)
		(end 375.701814 -122.77979)
		(width 0.0889)
		(layer "B.Cu")
		(net "P3E_CPU0_PE1_PCH_R_RXP<8>")
	)
	(segment
		(start 375.701814 -122.77979)
		(end 375.727214 -122.80519)
		(width 0.0889)
		(layer "B.Cu")
		(net "P3E_CPU0_PE1_PCH_R_RXP<8>")
	)
	(segment
		(start 372.048786 -121.900442)
		(end 369.167156 -121.900442)
		(width 0.1143)
		(layer "B.Cu")
		(net "P3E_CPU0_PE1_PCH_R_RXP<8>")
	)
	(segment
		(start 377.414282 -122.804682)
		(end 377.414536 -122.804682)
		(width 0.0889)
		(layer "B.Cu")
		(net "P3E_CPU0_PE1_PCH_R_RXP<8>")
	)
	(segment
		(start 379.64364 -122.39752)
		(end 379.81255 -122.104404)
		(width 0.0889)
		(layer "B.Cu")
		(net "P3E_CPU0_PE1_PCH_R_RXP<8>")
	)
	(segment
		(start 377.414536 -122.804682)
		(end 378.031248 -122.451114)
		(width 0.0889)
		(layer "B.Cu")
		(net "P3E_CPU0_PE1_PCH_R_RXP<8>")
	)
	(arc
		(start 379.021848 -122.451114)
		(mid 379.284504 -122.372777)
		(end 379.554232 -122.421396)
		(width 0.0889)
		(layer "B.Cu")
		(net "P3E_CPU0_PE1_PCH_R_RXP<8>")
	)
	(arc
		(start 378.031248 -122.451114)
		(mid 378.32665 -122.371983)
		(end 378.622052 -122.451114)
		(width 0.0889)
		(layer "B.Cu")
		(net "P3E_CPU0_PE1_PCH_R_RXP<8>")
	)
	(arc
		(start 378.622052 -122.451114)
		(mid 378.82195 -122.504613)
		(end 379.021848 -122.451114)
		(width 0.0889)
		(layer "B.Cu")
		(net "P3E_CPU0_PE1_PCH_R_RXP<8>")
	)
	(segment
		(start 378.498608 -123.528582)
		(end 378.759212 -123.649486)
		(width 0.1143)
		(layer "F.Cu")
		(net "P3E_CPU0_PE1_PCH_R_RXN<9>")
	)
	(segment
		(start 378.32665 -123.59132)
		(end 378.498608 -123.528582)
		(width 0.1143)
		(layer "F.Cu")
		(net "P3E_CPU0_PE1_PCH_R_RXN<9>")
	)
	(segment
		(start 378.759212 -123.649486)
		(end 378.82195 -123.821444)
		(width 0.1143)
		(layer "F.Cu")
		(net "P3E_CPU0_PE1_PCH_R_RXN<9>")
	)
	(via
		(at 378.82195 -123.821444)
		(size 0.508)
		(drill 0.254)
		(layers "F.Cu" "B.Cu")
		(net "P3E_CPU0_PE1_PCH_R_RXN<9>")
	)
	(segment
		(start 375.91746 -124.2695)
		(end 376.00636 -124.1806)
		(width 0.0889)
		(layer "B.Cu")
		(net "P3E_CPU0_PE1_PCH_R_RXN<9>")
	)
	(segment
		(start 375.26976 -124.206)
		(end 375.29516 -124.1806)
		(width 0.0889)
		(layer "B.Cu")
		(net "P3E_CPU0_PE1_PCH_R_RXN<9>")
	)
	(segment
		(start 379.217936 -123.763532)
		(end 379.160024 -123.821444)
		(width 0.0889)
		(layer "B.Cu")
		(net "P3E_CPU0_PE1_PCH_R_RXN<9>")
	)
	(segment
		(start 375.65076 -124.2695)
		(end 375.91746 -124.2695)
		(width 0.0889)
		(layer "B.Cu")
		(net "P3E_CPU0_PE1_PCH_R_RXN<9>")
	)
	(segment
		(start 376.71756 -124.1806)
		(end 376.854974 -124.1806)
		(width 0.0889)
		(layer "B.Cu")
		(net "P3E_CPU0_PE1_PCH_R_RXN<9>")
	)
	(segment
		(start 368.716814 -125.507242)
		(end 369.112546 -125.11151)
		(width 0.1143)
		(layer "B.Cu")
		(net "P3E_CPU0_PE1_PCH_R_RXN<9>")
	)
	(segment
		(start 376.27306 -124.1806)
		(end 376.36196 -124.2695)
		(width 0.0889)
		(layer "B.Cu")
		(net "P3E_CPU0_PE1_PCH_R_RXN<9>")
	)
	(segment
		(start 375.29516 -124.1806)
		(end 375.56186 -124.1806)
		(width 0.0889)
		(layer "B.Cu")
		(net "P3E_CPU0_PE1_PCH_R_RXN<9>")
	)
	(segment
		(start 374.3198 -124.206)
		(end 375.247662 -124.206)
		(width 0.1143)
		(layer "B.Cu")
		(net "P3E_CPU0_PE1_PCH_R_RXN<9>")
	)
	(segment
		(start 377.10618 -123.929394)
		(end 377.23191 -123.929394)
		(width 0.0889)
		(layer "B.Cu")
		(net "P3E_CPU0_PE1_PCH_R_RXN<9>")
	)
	(segment
		(start 376.62866 -124.2695)
		(end 376.71756 -124.1806)
		(width 0.0889)
		(layer "B.Cu")
		(net "P3E_CPU0_PE1_PCH_R_RXN<9>")
	)
	(segment
		(start 377.420632 -123.614942)
		(end 377.513596 -123.521978)
		(width 0.0889)
		(layer "B.Cu")
		(net "P3E_CPU0_PE1_PCH_R_RXN<9>")
	)
	(segment
		(start 371.56009 -125.11151)
		(end 372.01983 -124.65177)
		(width 0.1143)
		(layer "B.Cu")
		(net "P3E_CPU0_PE1_PCH_R_RXN<9>")
	)
	(segment
		(start 372.260622 -124.071888)
		(end 374.185688 -124.071888)
		(width 0.1143)
		(layer "B.Cu")
		(net "P3E_CPU0_PE1_PCH_R_RXN<9>")
	)
	(segment
		(start 372.01983 -124.65177)
		(end 372.01983 -124.31268)
		(width 0.1143)
		(layer "B.Cu")
		(net "P3E_CPU0_PE1_PCH_R_RXN<9>")
	)
	(segment
		(start 376.854974 -124.1806)
		(end 377.10618 -123.929394)
		(width 0.0889)
		(layer "B.Cu")
		(net "P3E_CPU0_PE1_PCH_R_RXN<9>")
	)
	(segment
		(start 372.01983 -124.31268)
		(end 372.260622 -124.071888)
		(width 0.1143)
		(layer "B.Cu")
		(net "P3E_CPU0_PE1_PCH_R_RXN<9>")
	)
	(segment
		(start 379.160024 -123.821444)
		(end 378.82195 -123.821444)
		(width 0.0889)
		(layer "B.Cu")
		(net "P3E_CPU0_PE1_PCH_R_RXN<9>")
	)
	(segment
		(start 375.247662 -124.206)
		(end 375.26976 -124.206)
		(width 0.0889)
		(layer "B.Cu")
		(net "P3E_CPU0_PE1_PCH_R_RXN<9>")
	)
	(segment
		(start 376.00636 -124.1806)
		(end 376.27306 -124.1806)
		(width 0.0889)
		(layer "B.Cu")
		(net "P3E_CPU0_PE1_PCH_R_RXN<9>")
	)
	(segment
		(start 377.513596 -123.521978)
		(end 377.515882 -123.519946)
		(width 0.0889)
		(layer "B.Cu")
		(net "P3E_CPU0_PE1_PCH_R_RXN<9>")
	)
	(segment
		(start 369.112546 -125.11151)
		(end 371.56009 -125.11151)
		(width 0.1143)
		(layer "B.Cu")
		(net "P3E_CPU0_PE1_PCH_R_RXN<9>")
	)
	(segment
		(start 375.56186 -124.1806)
		(end 375.65076 -124.2695)
		(width 0.0889)
		(layer "B.Cu")
		(net "P3E_CPU0_PE1_PCH_R_RXN<9>")
	)
	(segment
		(start 374.185688 -124.071888)
		(end 374.3198 -124.206)
		(width 0.1143)
		(layer "B.Cu")
		(net "P3E_CPU0_PE1_PCH_R_RXN<9>")
	)
	(segment
		(start 377.420632 -123.740672)
		(end 377.420632 -123.614942)
		(width 0.0889)
		(layer "B.Cu")
		(net "P3E_CPU0_PE1_PCH_R_RXN<9>")
	)
	(segment
		(start 376.36196 -124.2695)
		(end 376.62866 -124.2695)
		(width 0.0889)
		(layer "B.Cu")
		(net "P3E_CPU0_PE1_PCH_R_RXN<9>")
	)
	(segment
		(start 377.23191 -123.929394)
		(end 377.420632 -123.740672)
		(width 0.0889)
		(layer "B.Cu")
		(net "P3E_CPU0_PE1_PCH_R_RXN<9>")
	)
	(arc
		(start 377.801378 -123.405646)
		(mid 377.920365 -123.426715)
		(end 378.031248 -123.474734)
		(width 0.0889)
		(layer "B.Cu")
		(net "P3E_CPU0_PE1_PCH_R_RXN<9>")
	)
	(arc
		(start 377.515882 -123.519946)
		(mid 377.645932 -123.431094)
		(end 377.801378 -123.405646)
		(width 0.0889)
		(layer "B.Cu")
		(net "P3E_CPU0_PE1_PCH_R_RXN<9>")
	)
	(arc
		(start 378.031248 -123.474734)
		(mid 378.32665 -123.553865)
		(end 378.622052 -123.474734)
		(width 0.0889)
		(layer "B.Cu")
		(net "P3E_CPU0_PE1_PCH_R_RXN<9>")
	)
	(arc
		(start 378.622052 -123.474734)
		(mid 378.996491 -123.461302)
		(end 379.217936 -123.763532)
		(width 0.0889)
		(layer "B.Cu")
		(net "P3E_CPU0_PE1_PCH_R_RXN<9>")
	)
	(segment
		(start 378.82195 -122.7328)
		(end 379.31725 -122.962924)
		(width 0.1143)
		(layer "F.Cu")
		(net "P3E_CPU0_PE1_PCH_R_RXN<8>")
	)
	(via
		(at 379.31725 -122.962924)
		(size 0.508)
		(drill 0.254)
		(layers "F.Cu" "B.Cu")
		(net "P3E_CPU0_PE1_PCH_R_RXN<8>")
	)
	(via
		(at 372.76278 -122.352308)
		(size 0.508)
		(drill 0.254)
		(layers "F.Cu" "B.Cu")
		(net "P3E_CPU0_PE1_PCH_R_RXN<8>")
	)
	(segment
		(start 379.4125 -122.93727)
		(end 379.31725 -122.962924)
		(width 0.0889)
		(layer "B.Cu")
		(net "P3E_CPU0_PE1_PCH_R_RXN<8>")
	)
	(segment
		(start 377.465336 -122.995182)
		(end 378.126244 -122.616468)
		(width 0.0889)
		(layer "B.Cu")
		(net "P3E_CPU0_PE1_PCH_R_RXN<8>")
	)
	(segment
		(start 375.727468 -122.99569)
		(end 377.414536 -122.995182)
		(width 0.0889)
		(layer "B.Cu")
		(net "P3E_CPU0_PE1_PCH_R_RXN<8>")
	)
	(segment
		(start 379.464824 -122.591068)
		(end 379.511814 -122.764804)
		(width 0.0889)
		(layer "B.Cu")
		(net "P3E_CPU0_PE1_PCH_R_RXN<8>")
	)
	(segment
		(start 378.126244 -122.616468)
		(end 378.126752 -122.616214)
		(width 0.0889)
		(layer "B.Cu")
		(net "P3E_CPU0_PE1_PCH_R_RXN<8>")
	)
	(segment
		(start 371.118892 -122.256042)
		(end 371.004592 -122.141742)
		(width 0.1143)
		(layer "B.Cu")
		(net "P3E_CPU0_PE1_PCH_R_RXN<8>")
	)
	(segment
		(start 375.727214 -122.99569)
		(end 375.727468 -122.99569)
		(width 0.0889)
		(layer "B.Cu")
		(net "P3E_CPU0_PE1_PCH_R_RXN<8>")
	)
	(segment
		(start 379.511814 -122.764804)
		(end 379.4125 -122.93727)
		(width 0.0889)
		(layer "B.Cu")
		(net "P3E_CPU0_PE1_PCH_R_RXN<8>")
	)
	(segment
		(start 369.129056 -122.141742)
		(end 368.709956 -122.560842)
		(width 0.1143)
		(layer "B.Cu")
		(net "P3E_CPU0_PE1_PCH_R_RXN<8>")
	)
	(segment
		(start 375.679716 -123.02109)
		(end 375.701814 -123.02109)
		(width 0.0889)
		(layer "B.Cu")
		(net "P3E_CPU0_PE1_PCH_R_RXN<8>")
	)
	(segment
		(start 372.76278 -122.352308)
		(end 372.015004 -122.141742)
		(width 0.1143)
		(layer "B.Cu")
		(net "P3E_CPU0_PE1_PCH_R_RXN<8>")
	)
	(segment
		(start 372.76278 -122.352308)
		(end 375.139458 -123.02109)
		(width 0.1143)
		(layer "B.Cu")
		(net "P3E_CPU0_PE1_PCH_R_RXN<8>")
	)
	(segment
		(start 372.015004 -122.141742)
		(end 371.588792 -122.141742)
		(width 0.1143)
		(layer "B.Cu")
		(net "P3E_CPU0_PE1_PCH_R_RXN<8>")
	)
	(segment
		(start 377.414536 -122.995182)
		(end 377.465336 -122.995182)
		(width 0.0889)
		(layer "B.Cu")
		(net "P3E_CPU0_PE1_PCH_R_RXN<8>")
	)
	(segment
		(start 371.474492 -122.256042)
		(end 371.118892 -122.256042)
		(width 0.1143)
		(layer "B.Cu")
		(net "P3E_CPU0_PE1_PCH_R_RXN<8>")
	)
	(segment
		(start 371.004592 -122.141742)
		(end 369.129056 -122.141742)
		(width 0.1143)
		(layer "B.Cu")
		(net "P3E_CPU0_PE1_PCH_R_RXN<8>")
	)
	(segment
		(start 371.588792 -122.141742)
		(end 371.474492 -122.256042)
		(width 0.1143)
		(layer "B.Cu")
		(net "P3E_CPU0_PE1_PCH_R_RXN<8>")
	)
	(segment
		(start 375.701814 -123.02109)
		(end 375.727214 -122.99569)
		(width 0.0889)
		(layer "B.Cu")
		(net "P3E_CPU0_PE1_PCH_R_RXN<8>")
	)
	(segment
		(start 375.139458 -123.02109)
		(end 375.679716 -123.02109)
		(width 0.1143)
		(layer "B.Cu")
		(net "P3E_CPU0_PE1_PCH_R_RXN<8>")
	)
	(arc
		(start 378.526548 -122.616214)
		(mid 378.82195 -122.695345)
		(end 379.117352 -122.616214)
		(width 0.0889)
		(layer "B.Cu")
		(net "P3E_CPU0_PE1_PCH_R_RXN<8>")
	)
	(arc
		(start 379.117352 -122.616214)
		(mid 379.288201 -122.56388)
		(end 379.464824 -122.591068)
		(width 0.0889)
		(layer "B.Cu")
		(net "P3E_CPU0_PE1_PCH_R_RXN<8>")
	)
	(arc
		(start 378.126752 -122.616214)
		(mid 378.32665 -122.562715)
		(end 378.526548 -122.616214)
		(width 0.0889)
		(layer "B.Cu")
		(net "P3E_CPU0_PE1_PCH_R_RXN<8>")
	)
	(segment
		(start 383.77495 -122.7328)
		(end 384.27025 -122.962924)
		(width 0.1143)
		(layer "F.Cu")
		(net "P3E_CPU0_PE1_PCH_R_RXP<15>")
	)
	(via
		(at 377.7488 -127.606552)
		(size 0.508)
		(drill 0.254)
		(layers "F.Cu" "B.Cu")
		(net "P3E_CPU0_PE1_PCH_R_RXP<15>")
	)
	(via
		(at 384.27025 -122.962924)
		(size 0.508)
		(drill 0.254)
		(layers "F.Cu" "B.Cu")
		(net "P3E_CPU0_PE1_PCH_R_RXP<15>")
	)
	(segment
		(start 358.180894 -127.519938)
		(end 358.180894 -127.519684)
		(width 0.1143)
		(layer "B.Cu")
		(net "P3E_CPU0_PE1_PCH_R_RXP<15>")
	)
	(segment
		(start 372.554246 -128.3843)
		(end 373.331994 -127.606552)
		(width 0.1143)
		(layer "B.Cu")
		(net "P3E_CPU0_PE1_PCH_R_RXP<15>")
	)
	(segment
		(start 378.47524 -127.33528)
		(end 378.935742 -127.33528)
		(width 0.1143)
		(layer "B.Cu")
		(net "P3E_CPU0_PE1_PCH_R_RXP<15>")
	)
	(segment
		(start 384.3655 -125.78588)
		(end 384.3655 -123.799854)
		(width 0.0889)
		(layer "B.Cu")
		(net "P3E_CPU0_PE1_PCH_R_RXP<15>")
	)
	(segment
		(start 377.7488 -127.606552)
		(end 378.203968 -127.606552)
		(width 0.1143)
		(layer "B.Cu")
		(net "P3E_CPU0_PE1_PCH_R_RXP<15>")
	)
	(segment
		(start 378.203968 -127.606552)
		(end 378.47524 -127.33528)
		(width 0.1143)
		(layer "B.Cu")
		(net "P3E_CPU0_PE1_PCH_R_RXP<15>")
	)
	(segment
		(start 358.112568 -127.504444)
		(end 358.180894 -127.519938)
		(width 0.1143)
		(layer "B.Cu")
		(net "P3E_CPU0_PE1_PCH_R_RXP<15>")
	)
	(segment
		(start 358.180894 -127.519684)
		(end 368.297714 -129.789174)
		(width 0.1143)
		(layer "B.Cu")
		(net "P3E_CPU0_PE1_PCH_R_RXP<15>")
	)
	(segment
		(start 384.70078 -126.12116)
		(end 384.3655 -125.78588)
		(width 0.0889)
		(layer "B.Cu")
		(net "P3E_CPU0_PE1_PCH_R_RXP<15>")
	)
	(segment
		(start 368.297714 -129.789174)
		(end 371.145308 -129.091436)
		(width 0.1143)
		(layer "B.Cu")
		(net "P3E_CPU0_PE1_PCH_R_RXP<15>")
	)
	(segment
		(start 371.852444 -128.3843)
		(end 372.554246 -128.3843)
		(width 0.1143)
		(layer "B.Cu")
		(net "P3E_CPU0_PE1_PCH_R_RXP<15>")
	)
	(segment
		(start 384.10134 -123.25604)
		(end 384.27025 -122.962924)
		(width 0.0889)
		(layer "B.Cu")
		(net "P3E_CPU0_PE1_PCH_R_RXP<15>")
	)
	(segment
		(start 378.98324 -127.30988)
		(end 384.45186 -127.30988)
		(width 0.0889)
		(layer "B.Cu")
		(net "P3E_CPU0_PE1_PCH_R_RXP<15>")
	)
	(segment
		(start 378.935742 -127.33528)
		(end 378.95784 -127.33528)
		(width 0.0889)
		(layer "B.Cu")
		(net "P3E_CPU0_PE1_PCH_R_RXP<15>")
	)
	(segment
		(start 384.45186 -127.30988)
		(end 384.70078 -127.06096)
		(width 0.0889)
		(layer "B.Cu")
		(net "P3E_CPU0_PE1_PCH_R_RXP<15>")
	)
	(segment
		(start 356.807516 -126.199392)
		(end 358.112568 -127.504444)
		(width 0.1143)
		(layer "B.Cu")
		(net "P3E_CPU0_PE1_PCH_R_RXP<15>")
	)
	(segment
		(start 371.145308 -129.091436)
		(end 371.852444 -128.3843)
		(width 0.1143)
		(layer "B.Cu")
		(net "P3E_CPU0_PE1_PCH_R_RXP<15>")
	)
	(segment
		(start 384.12547 -123.345448)
		(end 384.10134 -123.25604)
		(width 0.0889)
		(layer "B.Cu")
		(net "P3E_CPU0_PE1_PCH_R_RXP<15>")
	)
	(segment
		(start 384.70078 -127.06096)
		(end 384.70078 -126.12116)
		(width 0.0889)
		(layer "B.Cu")
		(net "P3E_CPU0_PE1_PCH_R_RXP<15>")
	)
	(segment
		(start 355.178614 -126.624842)
		(end 355.604064 -126.199392)
		(width 0.1143)
		(layer "B.Cu")
		(net "P3E_CPU0_PE1_PCH_R_RXP<15>")
	)
	(segment
		(start 355.604064 -126.199392)
		(end 356.807516 -126.199392)
		(width 0.1143)
		(layer "B.Cu")
		(net "P3E_CPU0_PE1_PCH_R_RXP<15>")
	)
	(segment
		(start 373.331994 -127.606552)
		(end 377.7488 -127.606552)
		(width 0.1143)
		(layer "B.Cu")
		(net "P3E_CPU0_PE1_PCH_R_RXP<15>")
	)
	(segment
		(start 378.95784 -127.33528)
		(end 378.98324 -127.30988)
		(width 0.0889)
		(layer "B.Cu")
		(net "P3E_CPU0_PE1_PCH_R_RXP<15>")
	)
	(arc
		(start 384.3655 -123.799854)
		(mid 384.297471 -123.545189)
		(end 384.12547 -123.345448)
		(width 0.0889)
		(layer "B.Cu")
		(net "P3E_CPU0_PE1_PCH_R_RXP<15>")
	)
	(segment
		(start 383.27965 -123.59132)
		(end 383.77495 -123.821444)
		(width 0.1143)
		(layer "F.Cu")
		(net "P3E_CPU0_PE1_PCH_R_RXN<15>")
	)
	(via
		(at 375.7422 -127.365252)
		(size 0.508)
		(drill 0.254)
		(layers "F.Cu" "B.Cu")
		(net "P3E_CPU0_PE1_PCH_R_RXN<15>")
	)
	(via
		(at 383.77495 -123.821444)
		(size 0.508)
		(drill 0.254)
		(layers "F.Cu" "B.Cu")
		(net "P3E_CPU0_PE1_PCH_R_RXN<15>")
	)
	(segment
		(start 384.0861 -124.422154)
		(end 384.175 -124.333254)
		(width 0.0889)
		(layer "B.Cu")
		(net "P3E_CPU0_PE1_PCH_R_RXN<15>")
	)
	(segment
		(start 382.524 -127.03048)
		(end 382.8034 -127.03048)
		(width 0.0889)
		(layer "B.Cu")
		(net "P3E_CPU0_PE1_PCH_R_RXN<15>")
	)
	(segment
		(start 380.6825 -127.11938)
		(end 380.9619 -127.11938)
		(width 0.0889)
		(layer "B.Cu")
		(net "P3E_CPU0_PE1_PCH_R_RXN<15>")
	)
	(segment
		(start 379.857 -127.03048)
		(end 379.9459 -127.11938)
		(width 0.0889)
		(layer "B.Cu")
		(net "P3E_CPU0_PE1_PCH_R_RXN<15>")
	)
	(segment
		(start 380.3142 -127.03048)
		(end 380.5936 -127.03048)
		(width 0.0889)
		(layer "B.Cu")
		(net "P3E_CPU0_PE1_PCH_R_RXN<15>")
	)
	(segment
		(start 384.51028 -126.200154)
		(end 384.175 -125.864874)
		(width 0.0889)
		(layer "B.Cu")
		(net "P3E_CPU0_PE1_PCH_R_RXN<15>")
	)
	(segment
		(start 382.0668 -127.03048)
		(end 382.1557 -127.11938)
		(width 0.0889)
		(layer "B.Cu")
		(net "P3E_CPU0_PE1_PCH_R_RXN<15>")
	)
	(segment
		(start 380.2253 -127.11938)
		(end 380.3142 -127.03048)
		(width 0.0889)
		(layer "B.Cu")
		(net "P3E_CPU0_PE1_PCH_R_RXN<15>")
	)
	(segment
		(start 380.5936 -127.03048)
		(end 380.6825 -127.11938)
		(width 0.0889)
		(layer "B.Cu")
		(net "P3E_CPU0_PE1_PCH_R_RXN<15>")
	)
	(segment
		(start 368.295174 -129.54127)
		(end 371.022372 -128.872996)
		(width 0.1143)
		(layer "B.Cu")
		(net "P3E_CPU0_PE1_PCH_R_RXN<15>")
	)
	(segment
		(start 381.0508 -127.03048)
		(end 381.3302 -127.03048)
		(width 0.0889)
		(layer "B.Cu")
		(net "P3E_CPU0_PE1_PCH_R_RXN<15>")
	)
	(segment
		(start 382.1557 -127.11938)
		(end 382.4351 -127.11938)
		(width 0.0889)
		(layer "B.Cu")
		(net "P3E_CPU0_PE1_PCH_R_RXN<15>")
	)
	(segment
		(start 384.0861 -125.438154)
		(end 384.0861 -125.158754)
		(width 0.0889)
		(layer "B.Cu")
		(net "P3E_CPU0_PE1_PCH_R_RXN<15>")
	)
	(segment
		(start 378.375164 -127.09398)
		(end 378.935742 -127.09398)
		(width 0.1143)
		(layer "B.Cu")
		(net "P3E_CPU0_PE1_PCH_R_RXN<15>")
	)
	(segment
		(start 384.175 -125.527054)
		(end 384.0861 -125.438154)
		(width 0.0889)
		(layer "B.Cu")
		(net "P3E_CPU0_PE1_PCH_R_RXN<15>")
	)
	(segment
		(start 355.604064 -125.958092)
		(end 356.907592 -125.958092)
		(width 0.1143)
		(layer "B.Cu")
		(net "P3E_CPU0_PE1_PCH_R_RXN<15>")
	)
	(segment
		(start 379.9459 -127.11938)
		(end 380.2253 -127.11938)
		(width 0.0889)
		(layer "B.Cu")
		(net "P3E_CPU0_PE1_PCH_R_RXN<15>")
	)
	(segment
		(start 378.95784 -127.09398)
		(end 378.98324 -127.11938)
		(width 0.0889)
		(layer "B.Cu")
		(net "P3E_CPU0_PE1_PCH_R_RXN<15>")
	)
	(segment
		(start 380.9619 -127.11938)
		(end 381.0508 -127.03048)
		(width 0.0889)
		(layer "B.Cu")
		(net "P3E_CPU0_PE1_PCH_R_RXN<15>")
	)
	(segment
		(start 379.5776 -127.03048)
		(end 379.857 -127.03048)
		(width 0.0889)
		(layer "B.Cu")
		(net "P3E_CPU0_PE1_PCH_R_RXN<15>")
	)
	(segment
		(start 356.907592 -125.958092)
		(end 358.233726 -127.284226)
		(width 0.1143)
		(layer "B.Cu")
		(net "P3E_CPU0_PE1_PCH_R_RXN<15>")
	)
	(segment
		(start 384.175 -125.069854)
		(end 384.175 -124.790454)
		(width 0.0889)
		(layer "B.Cu")
		(net "P3E_CPU0_PE1_PCH_R_RXN<15>")
	)
	(segment
		(start 382.4351 -127.11938)
		(end 382.524 -127.03048)
		(width 0.0889)
		(layer "B.Cu")
		(net "P3E_CPU0_PE1_PCH_R_RXN<15>")
	)
	(segment
		(start 384.175 -124.333254)
		(end 384.175 -123.810268)
		(width 0.0889)
		(layer "B.Cu")
		(net "P3E_CPU0_PE1_PCH_R_RXN<15>")
	)
	(segment
		(start 378.103892 -127.365252)
		(end 378.375164 -127.09398)
		(width 0.1143)
		(layer "B.Cu")
		(net "P3E_CPU0_PE1_PCH_R_RXN<15>")
	)
	(segment
		(start 358.233726 -127.284226)
		(end 368.295174 -129.54127)
		(width 0.1143)
		(layer "B.Cu")
		(net "P3E_CPU0_PE1_PCH_R_RXN<15>")
	)
	(segment
		(start 383.94386 -123.528328)
		(end 383.77495 -123.821444)
		(width 0.0889)
		(layer "B.Cu")
		(net "P3E_CPU0_PE1_PCH_R_RXN<15>")
	)
	(segment
		(start 373.231918 -127.365252)
		(end 375.7422 -127.365252)
		(width 0.1143)
		(layer "B.Cu")
		(net "P3E_CPU0_PE1_PCH_R_RXN<15>")
	)
	(segment
		(start 379.4887 -127.11938)
		(end 379.5776 -127.03048)
		(width 0.0889)
		(layer "B.Cu")
		(net "P3E_CPU0_PE1_PCH_R_RXN<15>")
	)
	(segment
		(start 384.372866 -127.11938)
		(end 384.51028 -126.981966)
		(width 0.0889)
		(layer "B.Cu")
		(net "P3E_CPU0_PE1_PCH_R_RXN<15>")
	)
	(segment
		(start 355.178614 -125.532642)
		(end 355.604064 -125.958092)
		(width 0.1143)
		(layer "B.Cu")
		(net "P3E_CPU0_PE1_PCH_R_RXN<15>")
	)
	(segment
		(start 382.8923 -127.11938)
		(end 384.372866 -127.11938)
		(width 0.0889)
		(layer "B.Cu")
		(net "P3E_CPU0_PE1_PCH_R_RXN<15>")
	)
	(segment
		(start 378.98324 -127.11938)
		(end 379.4887 -127.11938)
		(width 0.0889)
		(layer "B.Cu")
		(net "P3E_CPU0_PE1_PCH_R_RXN<15>")
	)
	(segment
		(start 372.45417 -128.143)
		(end 373.231918 -127.365252)
		(width 0.1143)
		(layer "B.Cu")
		(net "P3E_CPU0_PE1_PCH_R_RXN<15>")
	)
	(segment
		(start 381.3302 -127.03048)
		(end 381.4191 -127.11938)
		(width 0.0889)
		(layer "B.Cu")
		(net "P3E_CPU0_PE1_PCH_R_RXN<15>")
	)
	(segment
		(start 378.935742 -127.09398)
		(end 378.95784 -127.09398)
		(width 0.0889)
		(layer "B.Cu")
		(net "P3E_CPU0_PE1_PCH_R_RXN<15>")
	)
	(segment
		(start 384.175 -125.864874)
		(end 384.175 -125.527054)
		(width 0.0889)
		(layer "B.Cu")
		(net "P3E_CPU0_PE1_PCH_R_RXN<15>")
	)
	(segment
		(start 384.175 -124.790454)
		(end 384.0861 -124.701554)
		(width 0.0889)
		(layer "B.Cu")
		(net "P3E_CPU0_PE1_PCH_R_RXN<15>")
	)
	(segment
		(start 381.4191 -127.11938)
		(end 381.6985 -127.11938)
		(width 0.0889)
		(layer "B.Cu")
		(net "P3E_CPU0_PE1_PCH_R_RXN<15>")
	)
	(segment
		(start 384.0226 -123.507246)
		(end 383.94386 -123.528328)
		(width 0.0889)
		(layer "B.Cu")
		(net "P3E_CPU0_PE1_PCH_R_RXN<15>")
	)
	(segment
		(start 371.752368 -128.143)
		(end 372.45417 -128.143)
		(width 0.1143)
		(layer "B.Cu")
		(net "P3E_CPU0_PE1_PCH_R_RXN<15>")
	)
	(segment
		(start 382.8034 -127.03048)
		(end 382.8923 -127.11938)
		(width 0.0889)
		(layer "B.Cu")
		(net "P3E_CPU0_PE1_PCH_R_RXN<15>")
	)
	(segment
		(start 381.6985 -127.11938)
		(end 381.7874 -127.03048)
		(width 0.0889)
		(layer "B.Cu")
		(net "P3E_CPU0_PE1_PCH_R_RXN<15>")
	)
	(segment
		(start 384.0861 -125.158754)
		(end 384.175 -125.069854)
		(width 0.0889)
		(layer "B.Cu")
		(net "P3E_CPU0_PE1_PCH_R_RXN<15>")
	)
	(segment
		(start 375.7422 -127.365252)
		(end 378.103892 -127.365252)
		(width 0.1143)
		(layer "B.Cu")
		(net "P3E_CPU0_PE1_PCH_R_RXN<15>")
	)
	(segment
		(start 384.0861 -124.701554)
		(end 384.0861 -124.422154)
		(width 0.0889)
		(layer "B.Cu")
		(net "P3E_CPU0_PE1_PCH_R_RXN<15>")
	)
	(segment
		(start 384.51028 -126.981966)
		(end 384.51028 -126.200154)
		(width 0.0889)
		(layer "B.Cu")
		(net "P3E_CPU0_PE1_PCH_R_RXN<15>")
	)
	(segment
		(start 371.022372 -128.872996)
		(end 371.752368 -128.143)
		(width 0.1143)
		(layer "B.Cu")
		(net "P3E_CPU0_PE1_PCH_R_RXN<15>")
	)
	(segment
		(start 381.7874 -127.03048)
		(end 382.0668 -127.03048)
		(width 0.0889)
		(layer "B.Cu")
		(net "P3E_CPU0_PE1_PCH_R_RXN<15>")
	)
	(arc
		(start 384.175 -123.810268)
		(mid 384.132467 -123.641831)
		(end 384.0226 -123.507246)
		(width 0.0889)
		(layer "B.Cu")
		(net "P3E_CPU0_PE1_PCH_R_RXN<15>")
	)
	(segment
		(start 382.3462 -121.900696)
		(end 382.78435 -122.104404)
		(width 0.1143)
		(layer "F.Cu")
		(net "P3E_CPU0_PE1_PCH_R_RXP<14>")
	)
	(segment
		(start 382.28905 -121.87428)
		(end 382.3462 -121.900696)
		(width 0.1143)
		(layer "F.Cu")
		(net "P3E_CPU0_PE1_PCH_R_RXP<14>")
	)
	(via
		(at 373.844566 -126.64059)
		(size 0.508)
		(drill 0.254)
		(layers "F.Cu" "B.Cu")
		(net "P3E_CPU0_PE1_PCH_R_RXP<14>")
	)
	(via
		(at 382.78435 -122.104404)
		(size 0.508)
		(drill 0.254)
		(layers "F.Cu" "B.Cu")
		(net "P3E_CPU0_PE1_PCH_R_RXP<14>")
	)
	(segment
		(start 350.022414 -126.345442)
		(end 350.022414 -126.03099)
		(width 0.1143)
		(layer "B.Cu")
		(net "P3E_CPU0_PE1_PCH_R_RXP<14>")
	)
	(segment
		(start 350.464882 -125.91669)
		(end 350.8375 -125.544072)
		(width 0.1143)
		(layer "B.Cu")
		(net "P3E_CPU0_PE1_PCH_R_RXP<14>")
	)
	(segment
		(start 368.287554 -128.75768)
		(end 370.553488 -128.202436)
		(width 0.1143)
		(layer "B.Cu")
		(net "P3E_CPU0_PE1_PCH_R_RXP<14>")
	)
	(segment
		(start 350.022414 -126.03099)
		(end 350.136714 -125.91669)
		(width 0.1143)
		(layer "B.Cu")
		(net "P3E_CPU0_PE1_PCH_R_RXP<14>")
	)
	(segment
		(start 374.59031 -126.64059)
		(end 375.0564 -126.1745)
		(width 0.1143)
		(layer "B.Cu")
		(net "P3E_CPU0_PE1_PCH_R_RXP<14>")
	)
	(segment
		(start 370.553488 -128.202436)
		(end 371.476524 -127.2794)
		(width 0.1143)
		(layer "B.Cu")
		(net "P3E_CPU0_PE1_PCH_R_RXP<14>")
	)
	(segment
		(start 373.844566 -126.64059)
		(end 374.59031 -126.64059)
		(width 0.1143)
		(layer "B.Cu")
		(net "P3E_CPU0_PE1_PCH_R_RXP<14>")
	)
	(segment
		(start 371.476524 -127.2794)
		(end 372.2624 -127.2794)
		(width 0.1143)
		(layer "B.Cu")
		(net "P3E_CPU0_PE1_PCH_R_RXP<14>")
	)
	(segment
		(start 378.20346 -126.1745)
		(end 378.22886 -126.1491)
		(width 0.0889)
		(layer "B.Cu")
		(net "P3E_CPU0_PE1_PCH_R_RXP<14>")
	)
	(segment
		(start 356.789228 -124.760736)
		(end 358.616758 -126.588266)
		(width 0.1143)
		(layer "B.Cu")
		(net "P3E_CPU0_PE1_PCH_R_RXP<14>")
	)
	(segment
		(start 350.8375 -125.544072)
		(end 350.8375 -125.022356)
		(width 0.1143)
		(layer "B.Cu")
		(net "P3E_CPU0_PE1_PCH_R_RXP<14>")
	)
	(segment
		(start 372.2624 -127.2794)
		(end 372.90121 -126.64059)
		(width 0.1143)
		(layer "B.Cu")
		(net "P3E_CPU0_PE1_PCH_R_RXP<14>")
	)
	(segment
		(start 372.90121 -126.64059)
		(end 373.844566 -126.64059)
		(width 0.1143)
		(layer "B.Cu")
		(net "P3E_CPU0_PE1_PCH_R_RXP<14>")
	)
	(segment
		(start 350.136714 -125.91669)
		(end 350.464882 -125.91669)
		(width 0.1143)
		(layer "B.Cu")
		(net "P3E_CPU0_PE1_PCH_R_RXP<14>")
	)
	(segment
		(start 383.042668 -122.421396)
		(end 382.95326 -122.39752)
		(width 0.0889)
		(layer "B.Cu")
		(net "P3E_CPU0_PE1_PCH_R_RXP<14>")
	)
	(segment
		(start 378.22886 -126.1491)
		(end 382.966214 -126.1491)
		(width 0.0889)
		(layer "B.Cu")
		(net "P3E_CPU0_PE1_PCH_R_RXP<14>")
	)
	(segment
		(start 350.8375 -125.022356)
		(end 351.09912 -124.760736)
		(width 0.1143)
		(layer "B.Cu")
		(net "P3E_CPU0_PE1_PCH_R_RXP<14>")
	)
	(segment
		(start 382.966214 -126.1491)
		(end 383.3749 -125.740414)
		(width 0.0889)
		(layer "B.Cu")
		(net "P3E_CPU0_PE1_PCH_R_RXP<14>")
	)
	(segment
		(start 378.181362 -126.1745)
		(end 378.20346 -126.1745)
		(width 0.0889)
		(layer "B.Cu")
		(net "P3E_CPU0_PE1_PCH_R_RXP<14>")
	)
	(segment
		(start 358.616758 -126.588266)
		(end 368.287554 -128.75768)
		(width 0.1143)
		(layer "B.Cu")
		(net "P3E_CPU0_PE1_PCH_R_RXP<14>")
	)
	(segment
		(start 383.3749 -125.740414)
		(end 383.3749 -123.810268)
		(width 0.0889)
		(layer "B.Cu")
		(net "P3E_CPU0_PE1_PCH_R_RXP<14>")
	)
	(segment
		(start 351.09912 -124.760736)
		(end 356.789228 -124.760736)
		(width 0.1143)
		(layer "B.Cu")
		(net "P3E_CPU0_PE1_PCH_R_RXP<14>")
	)
	(segment
		(start 375.0564 -126.1745)
		(end 378.181362 -126.1745)
		(width 0.1143)
		(layer "B.Cu")
		(net "P3E_CPU0_PE1_PCH_R_RXP<14>")
	)
	(segment
		(start 383.8702 -122.984514)
		(end 383.8702 -122.941334)
		(width 0.0889)
		(layer "B.Cu")
		(net "P3E_CPU0_PE1_PCH_R_RXP<14>")
	)
	(segment
		(start 382.95326 -122.39752)
		(end 382.78435 -122.104404)
		(width 0.0889)
		(layer "B.Cu")
		(net "P3E_CPU0_PE1_PCH_R_RXP<14>")
	)
	(arc
		(start 383.575052 -123.474734)
		(mid 383.785916 -123.26773)
		(end 383.8702 -122.984514)
		(width 0.0889)
		(layer "B.Cu")
		(net "P3E_CPU0_PE1_PCH_R_RXP<14>")
	)
	(arc
		(start 383.8702 -122.941334)
		(mid 383.785919 -122.658117)
		(end 383.575052 -122.451114)
		(width 0.0889)
		(layer "B.Cu")
		(net "P3E_CPU0_PE1_PCH_R_RXP<14>")
	)
	(arc
		(start 383.3749 -123.810268)
		(mid 383.43125 -123.616418)
		(end 383.575052 -123.474734)
		(width 0.0889)
		(layer "B.Cu")
		(net "P3E_CPU0_PE1_PCH_R_RXP<14>")
	)
	(arc
		(start 383.575052 -122.451114)
		(mid 383.312396 -122.372777)
		(end 383.042668 -122.421396)
		(width 0.0889)
		(layer "B.Cu")
		(net "P3E_CPU0_PE1_PCH_R_RXP<14>")
	)
	(segment
		(start 383.229104 -122.82551)
		(end 383.27965 -122.962924)
		(width 0.1143)
		(layer "F.Cu")
		(net "P3E_CPU0_PE1_PCH_R_RXN<14>")
	)
	(segment
		(start 383.096516 -122.7328)
		(end 383.229104 -122.82551)
		(width 0.1143)
		(layer "F.Cu")
		(net "P3E_CPU0_PE1_PCH_R_RXN<14>")
	)
	(segment
		(start 382.78435 -122.7328)
		(end 383.096516 -122.7328)
		(width 0.1143)
		(layer "F.Cu")
		(net "P3E_CPU0_PE1_PCH_R_RXN<14>")
	)
	(via
		(at 383.27965 -122.962924)
		(size 0.508)
		(drill 0.254)
		(layers "F.Cu" "B.Cu")
		(net "P3E_CPU0_PE1_PCH_R_RXN<14>")
	)
	(via
		(at 375.742962 -125.9332)
		(size 0.508)
		(drill 0.254)
		(layers "F.Cu" "B.Cu")
		(net "P3E_CPU0_PE1_PCH_R_RXN<14>")
	)
	(segment
		(start 382.60782 -125.9586)
		(end 382.88722 -125.9586)
		(width 0.0889)
		(layer "B.Cu")
		(net "P3E_CPU0_PE1_PCH_R_RXN<14>")
	)
	(segment
		(start 378.84862 -125.8697)
		(end 378.93752 -125.9586)
		(width 0.0889)
		(layer "B.Cu")
		(net "P3E_CPU0_PE1_PCH_R_RXN<14>")
	)
	(segment
		(start 374.490234 -126.39929)
		(end 374.956324 -125.9332)
		(width 0.1143)
		(layer "B.Cu")
		(net "P3E_CPU0_PE1_PCH_R_RXN<14>")
	)
	(segment
		(start 379.66142 -125.9586)
		(end 379.94082 -125.9586)
		(width 0.0889)
		(layer "B.Cu")
		(net "P3E_CPU0_PE1_PCH_R_RXN<14>")
	)
	(segment
		(start 383.1844 -124.64542)
		(end 383.0955 -124.55652)
		(width 0.0889)
		(layer "B.Cu")
		(net "P3E_CPU0_PE1_PCH_R_RXN<14>")
	)
	(segment
		(start 380.67742 -125.9586)
		(end 380.76632 -125.8697)
		(width 0.0889)
		(layer "B.Cu")
		(net "P3E_CPU0_PE1_PCH_R_RXN<14>")
	)
	(segment
		(start 381.13462 -125.9586)
		(end 381.41402 -125.9586)
		(width 0.0889)
		(layer "B.Cu")
		(net "P3E_CPU0_PE1_PCH_R_RXN<14>")
	)
	(segment
		(start 383.08788 -122.682)
		(end 383.27965 -122.962924)
		(width 0.0889)
		(layer "B.Cu")
		(net "P3E_CPU0_PE1_PCH_R_RXN<14>")
	)
	(segment
		(start 372.801134 -126.39929)
		(end 374.490234 -126.39929)
		(width 0.1143)
		(layer "B.Cu")
		(net "P3E_CPU0_PE1_PCH_R_RXN<14>")
	)
	(segment
		(start 372.162324 -127.0381)
		(end 372.801134 -126.39929)
		(width 0.1143)
		(layer "B.Cu")
		(net "P3E_CPU0_PE1_PCH_R_RXN<14>")
	)
	(segment
		(start 383.0955 -124.27712)
		(end 383.1844 -124.18822)
		(width 0.0889)
		(layer "B.Cu")
		(net "P3E_CPU0_PE1_PCH_R_RXN<14>")
	)
	(segment
		(start 350.022414 -125.560836)
		(end 350.136968 -125.67539)
		(width 0.1143)
		(layer "B.Cu")
		(net "P3E_CPU0_PE1_PCH_R_RXN<14>")
	)
	(segment
		(start 378.93752 -125.9586)
		(end 379.20422 -125.9586)
		(width 0.0889)
		(layer "B.Cu")
		(net "P3E_CPU0_PE1_PCH_R_RXN<14>")
	)
	(segment
		(start 379.29312 -125.8697)
		(end 379.57252 -125.8697)
		(width 0.0889)
		(layer "B.Cu")
		(net "P3E_CPU0_PE1_PCH_R_RXN<14>")
	)
	(segment
		(start 379.94082 -125.9586)
		(end 380.02972 -125.8697)
		(width 0.0889)
		(layer "B.Cu")
		(net "P3E_CPU0_PE1_PCH_R_RXN<14>")
	)
	(segment
		(start 383.1844 -124.92482)
		(end 383.1844 -124.64542)
		(width 0.0889)
		(layer "B.Cu")
		(net "P3E_CPU0_PE1_PCH_R_RXN<14>")
	)
	(segment
		(start 381.41402 -125.9586)
		(end 381.50292 -125.8697)
		(width 0.0889)
		(layer "B.Cu")
		(net "P3E_CPU0_PE1_PCH_R_RXN<14>")
	)
	(segment
		(start 381.78232 -125.8697)
		(end 381.87122 -125.9586)
		(width 0.0889)
		(layer "B.Cu")
		(net "P3E_CPU0_PE1_PCH_R_RXN<14>")
	)
	(segment
		(start 378.20346 -125.9332)
		(end 378.22886 -125.9586)
		(width 0.0889)
		(layer "B.Cu")
		(net "P3E_CPU0_PE1_PCH_R_RXN<14>")
	)
	(segment
		(start 356.889304 -124.519436)
		(end 358.737916 -126.368048)
		(width 0.1143)
		(layer "B.Cu")
		(net "P3E_CPU0_PE1_PCH_R_RXN<14>")
	)
	(segment
		(start 378.58192 -125.8697)
		(end 378.84862 -125.8697)
		(width 0.0889)
		(layer "B.Cu")
		(net "P3E_CPU0_PE1_PCH_R_RXN<14>")
	)
	(segment
		(start 383.1844 -125.66142)
		(end 383.1844 -125.38202)
		(width 0.0889)
		(layer "B.Cu")
		(net "P3E_CPU0_PE1_PCH_R_RXN<14>")
	)
	(segment
		(start 381.87122 -125.9586)
		(end 382.15062 -125.9586)
		(width 0.0889)
		(layer "B.Cu")
		(net "P3E_CPU0_PE1_PCH_R_RXN<14>")
	)
	(segment
		(start 375.742962 -125.9332)
		(end 378.181362 -125.9332)
		(width 0.1143)
		(layer "B.Cu")
		(net "P3E_CPU0_PE1_PCH_R_RXN<14>")
	)
	(segment
		(start 350.136968 -125.67539)
		(end 350.364806 -125.67539)
		(width 0.1143)
		(layer "B.Cu")
		(net "P3E_CPU0_PE1_PCH_R_RXN<14>")
	)
	(segment
		(start 379.57252 -125.8697)
		(end 379.66142 -125.9586)
		(width 0.0889)
		(layer "B.Cu")
		(net "P3E_CPU0_PE1_PCH_R_RXN<14>")
	)
	(segment
		(start 371.376448 -127.0381)
		(end 372.162324 -127.0381)
		(width 0.1143)
		(layer "B.Cu")
		(net "P3E_CPU0_PE1_PCH_R_RXN<14>")
	)
	(segment
		(start 383.0955 -125.01372)
		(end 383.1844 -124.92482)
		(width 0.0889)
		(layer "B.Cu")
		(net "P3E_CPU0_PE1_PCH_R_RXN<14>")
	)
	(segment
		(start 374.956324 -125.9332)
		(end 375.742962 -125.9332)
		(width 0.1143)
		(layer "B.Cu")
		(net "P3E_CPU0_PE1_PCH_R_RXN<14>")
	)
	(segment
		(start 370.430552 -127.983996)
		(end 371.376448 -127.0381)
		(width 0.1143)
		(layer "B.Cu")
		(net "P3E_CPU0_PE1_PCH_R_RXN<14>")
	)
	(segment
		(start 380.30912 -125.8697)
		(end 380.39802 -125.9586)
		(width 0.0889)
		(layer "B.Cu")
		(net "P3E_CPU0_PE1_PCH_R_RXN<14>")
	)
	(segment
		(start 358.737916 -126.368048)
		(end 368.285014 -128.509776)
		(width 0.1143)
		(layer "B.Cu")
		(net "P3E_CPU0_PE1_PCH_R_RXN<14>")
	)
	(segment
		(start 382.51892 -125.8697)
		(end 382.60782 -125.9586)
		(width 0.0889)
		(layer "B.Cu")
		(net "P3E_CPU0_PE1_PCH_R_RXN<14>")
	)
	(segment
		(start 378.181362 -125.9332)
		(end 378.20346 -125.9332)
		(width 0.0889)
		(layer "B.Cu")
		(net "P3E_CPU0_PE1_PCH_R_RXN<14>")
	)
	(segment
		(start 381.04572 -125.8697)
		(end 381.13462 -125.9586)
		(width 0.0889)
		(layer "B.Cu")
		(net "P3E_CPU0_PE1_PCH_R_RXN<14>")
	)
	(segment
		(start 379.20422 -125.9586)
		(end 379.29312 -125.8697)
		(width 0.0889)
		(layer "B.Cu")
		(net "P3E_CPU0_PE1_PCH_R_RXN<14>")
	)
	(segment
		(start 368.285014 -128.509776)
		(end 370.430552 -127.983996)
		(width 0.1143)
		(layer "B.Cu")
		(net "P3E_CPU0_PE1_PCH_R_RXN<14>")
	)
	(segment
		(start 383.0955 -125.29312)
		(end 383.0955 -125.01372)
		(width 0.0889)
		(layer "B.Cu")
		(net "P3E_CPU0_PE1_PCH_R_RXN<14>")
	)
	(segment
		(start 350.364806 -125.67539)
		(end 350.5962 -125.443996)
		(width 0.1143)
		(layer "B.Cu")
		(net "P3E_CPU0_PE1_PCH_R_RXN<14>")
	)
	(segment
		(start 350.5962 -124.92228)
		(end 350.999044 -124.519436)
		(width 0.1143)
		(layer "B.Cu")
		(net "P3E_CPU0_PE1_PCH_R_RXN<14>")
	)
	(segment
		(start 381.50292 -125.8697)
		(end 381.78232 -125.8697)
		(width 0.0889)
		(layer "B.Cu")
		(net "P3E_CPU0_PE1_PCH_R_RXN<14>")
	)
	(segment
		(start 378.49302 -125.9586)
		(end 378.58192 -125.8697)
		(width 0.0889)
		(layer "B.Cu")
		(net "P3E_CPU0_PE1_PCH_R_RXN<14>")
	)
	(segment
		(start 383.1844 -124.18822)
		(end 383.1844 -123.799854)
		(width 0.0889)
		(layer "B.Cu")
		(net "P3E_CPU0_PE1_PCH_R_RXN<14>")
	)
	(segment
		(start 382.15062 -125.9586)
		(end 382.23952 -125.8697)
		(width 0.0889)
		(layer "B.Cu")
		(net "P3E_CPU0_PE1_PCH_R_RXN<14>")
	)
	(segment
		(start 380.76632 -125.8697)
		(end 381.04572 -125.8697)
		(width 0.0889)
		(layer "B.Cu")
		(net "P3E_CPU0_PE1_PCH_R_RXN<14>")
	)
	(segment
		(start 380.02972 -125.8697)
		(end 380.30912 -125.8697)
		(width 0.0889)
		(layer "B.Cu")
		(net "P3E_CPU0_PE1_PCH_R_RXN<14>")
	)
	(segment
		(start 350.022414 -125.227842)
		(end 350.022414 -125.560836)
		(width 0.1143)
		(layer "B.Cu")
		(net "P3E_CPU0_PE1_PCH_R_RXN<14>")
	)
	(segment
		(start 383.1844 -125.38202)
		(end 383.0955 -125.29312)
		(width 0.0889)
		(layer "B.Cu")
		(net "P3E_CPU0_PE1_PCH_R_RXN<14>")
	)
	(segment
		(start 380.39802 -125.9586)
		(end 380.67742 -125.9586)
		(width 0.0889)
		(layer "B.Cu")
		(net "P3E_CPU0_PE1_PCH_R_RXN<14>")
	)
	(segment
		(start 378.22886 -125.9586)
		(end 378.49302 -125.9586)
		(width 0.0889)
		(layer "B.Cu")
		(net "P3E_CPU0_PE1_PCH_R_RXN<14>")
	)
	(segment
		(start 383.132076 -122.591068)
		(end 383.08788 -122.682)
		(width 0.0889)
		(layer "B.Cu")
		(net "P3E_CPU0_PE1_PCH_R_RXN<14>")
	)
	(segment
		(start 350.999044 -124.519436)
		(end 356.889304 -124.519436)
		(width 0.1143)
		(layer "B.Cu")
		(net "P3E_CPU0_PE1_PCH_R_RXN<14>")
	)
	(segment
		(start 350.5962 -125.443996)
		(end 350.5962 -124.92228)
		(width 0.1143)
		(layer "B.Cu")
		(net "P3E_CPU0_PE1_PCH_R_RXN<14>")
	)
	(segment
		(start 382.23952 -125.8697)
		(end 382.51892 -125.8697)
		(width 0.0889)
		(layer "B.Cu")
		(net "P3E_CPU0_PE1_PCH_R_RXN<14>")
	)
	(segment
		(start 382.88722 -125.9586)
		(end 383.1844 -125.66142)
		(width 0.0889)
		(layer "B.Cu")
		(net "P3E_CPU0_PE1_PCH_R_RXN<14>")
	)
	(segment
		(start 383.0955 -124.55652)
		(end 383.0955 -124.27712)
		(width 0.0889)
		(layer "B.Cu")
		(net "P3E_CPU0_PE1_PCH_R_RXN<14>")
	)
	(arc
		(start 383.479548 -123.309634)
		(mid 383.62235 -123.169446)
		(end 383.679446 -122.977656)
		(width 0.0889)
		(layer "B.Cu")
		(net "P3E_CPU0_PE1_PCH_R_RXN<14>")
	)
	(arc
		(start 383.679446 -122.977656)
		(mid 383.679708 -122.963051)
		(end 383.679446 -122.948446)
		(width 0.0889)
		(layer "B.Cu")
		(net "P3E_CPU0_PE1_PCH_R_RXN<14>")
	)
	(arc
		(start 383.479548 -122.616468)
		(mid 383.308728 -122.564027)
		(end 383.132076 -122.591068)
		(width 0.0889)
		(layer "B.Cu")
		(net "P3E_CPU0_PE1_PCH_R_RXN<14>")
	)
	(arc
		(start 383.679446 -122.948446)
		(mid 383.622337 -122.756663)
		(end 383.479548 -122.616468)
		(width 0.0889)
		(layer "B.Cu")
		(net "P3E_CPU0_PE1_PCH_R_RXN<14>")
	)
	(arc
		(start 383.1844 -123.799854)
		(mid 383.268681 -123.516637)
		(end 383.479548 -123.309634)
		(width 0.0889)
		(layer "B.Cu")
		(net "P3E_CPU0_PE1_PCH_R_RXN<14>")
	)
	(segment
		(start 381.858266 -121.192036)
		(end 382.11252 -121.310146)
		(width 0.1143)
		(layer "F.Cu")
		(net "P3E_CPU0_PE1_PCH_R_RXP<13>")
	)
	(segment
		(start 381.79375 -121.01576)
		(end 381.858266 -121.192036)
		(width 0.1143)
		(layer "F.Cu")
		(net "P3E_CPU0_PE1_PCH_R_RXP<13>")
	)
	(segment
		(start 382.113028 -121.3104)
		(end 382.28905 -121.245884)
		(width 0.1143)
		(layer "F.Cu")
		(net "P3E_CPU0_PE1_PCH_R_RXP<13>")
	)
	(segment
		(start 382.11252 -121.310146)
		(end 382.113028 -121.3104)
		(width 0.1143)
		(layer "F.Cu")
		(net "P3E_CPU0_PE1_PCH_R_RXP<13>")
	)
	(via
		(at 367.792 -117.64772)
		(size 0.508)
		(drill 0.254)
		(layers "F.Cu" "B.Cu")
		(net "P3E_CPU0_PE1_PCH_R_RXP<13>")
	)
	(via
		(at 382.28905 -121.245884)
		(size 0.508)
		(drill 0.254)
		(layers "F.Cu" "B.Cu")
		(net "P3E_CPU0_PE1_PCH_R_RXP<13>")
	)
	(segment
		(start 349.584518 -123.129294)
		(end 349.463614 -123.250198)
		(width 0.1143)
		(layer "B.Cu")
		(net "P3E_CPU0_PE1_PCH_R_RXP<13>")
	)
	(segment
		(start 370.535962 -117.62232)
		(end 370.624862 -117.71122)
		(width 0.0889)
		(layer "B.Cu")
		(net "P3E_CPU0_PE1_PCH_R_RXP<13>")
	)
	(segment
		(start 349.463614 -123.250198)
		(end 349.463614 -123.576842)
		(width 0.1143)
		(layer "B.Cu")
		(net "P3E_CPU0_PE1_PCH_R_RXP<13>")
	)
	(segment
		(start 370.904262 -117.71122)
		(end 370.993162 -117.62232)
		(width 0.0889)
		(layer "B.Cu")
		(net "P3E_CPU0_PE1_PCH_R_RXP<13>")
	)
	(segment
		(start 382.141476 -121.61774)
		(end 382.12014 -121.539)
		(width 0.0889)
		(layer "B.Cu")
		(net "P3E_CPU0_PE1_PCH_R_RXP<13>")
	)
	(segment
		(start 383.6797 -121.224294)
		(end 383.6797 -121.25706)
		(width 0.0889)
		(layer "B.Cu")
		(net "P3E_CPU0_PE1_PCH_R_RXP<13>")
	)
	(segment
		(start 367.792 -117.64772)
		(end 370.247164 -117.64772)
		(width 0.1143)
		(layer "B.Cu")
		(net "P3E_CPU0_PE1_PCH_R_RXP<13>")
	)
	(segment
		(start 383.6797 -119.517668)
		(end 383.6797 -119.550434)
		(width 0.0889)
		(layer "B.Cu")
		(net "P3E_CPU0_PE1_PCH_R_RXP<13>")
	)
	(segment
		(start 377.540774 -118.402862)
		(end 378.32665 -118.402862)
		(width 0.0889)
		(layer "B.Cu")
		(net "P3E_CPU0_PE1_PCH_R_RXP<13>")
	)
	(segment
		(start 371.729762 -117.62232)
		(end 372.009162 -117.62232)
		(width 0.0889)
		(layer "B.Cu")
		(net "P3E_CPU0_PE1_PCH_R_RXP<13>")
	)
	(segment
		(start 383.1844 -118.659148)
		(end 383.1844 -118.691914)
		(width 0.0889)
		(layer "B.Cu")
		(net "P3E_CPU0_PE1_PCH_R_RXP<13>")
	)
	(segment
		(start 363.812836 -117.64772)
		(end 350.52762 -121.513346)
		(width 0.1143)
		(layer "B.Cu")
		(net "P3E_CPU0_PE1_PCH_R_RXP<13>")
	)
	(segment
		(start 375.222516 -118.269004)
		(end 375.501916 -118.269004)
		(width 0.0889)
		(layer "B.Cu")
		(net "P3E_CPU0_PE1_PCH_R_RXP<13>")
	)
	(segment
		(start 375.870216 -118.180104)
		(end 375.959116 -118.269004)
		(width 0.0889)
		(layer "B.Cu")
		(net "P3E_CPU0_PE1_PCH_R_RXP<13>")
	)
	(segment
		(start 375.590816 -118.180104)
		(end 375.870216 -118.180104)
		(width 0.0889)
		(layer "B.Cu")
		(net "P3E_CPU0_PE1_PCH_R_RXP<13>")
	)
	(segment
		(start 374.117616 -118.180104)
		(end 374.397016 -118.180104)
		(width 0.0889)
		(layer "B.Cu")
		(net "P3E_CPU0_PE1_PCH_R_RXP<13>")
	)
	(segment
		(start 377.451874 -118.491762)
		(end 377.540774 -118.402862)
		(width 0.0889)
		(layer "B.Cu")
		(net "P3E_CPU0_PE1_PCH_R_RXP<13>")
	)
	(segment
		(start 377.185174 -118.491762)
		(end 377.451874 -118.491762)
		(width 0.0889)
		(layer "B.Cu")
		(net "P3E_CPU0_PE1_PCH_R_RXP<13>")
	)
	(segment
		(start 374.765316 -118.269004)
		(end 374.854216 -118.180104)
		(width 0.0889)
		(layer "B.Cu")
		(net "P3E_CPU0_PE1_PCH_R_RXP<13>")
	)
	(segment
		(start 370.624862 -117.71122)
		(end 370.904262 -117.71122)
		(width 0.0889)
		(layer "B.Cu")
		(net "P3E_CPU0_PE1_PCH_R_RXP<13>")
	)
	(segment
		(start 376.829574 -118.402862)
		(end 377.096274 -118.402862)
		(width 0.0889)
		(layer "B.Cu")
		(net "P3E_CPU0_PE1_PCH_R_RXP<13>")
	)
	(segment
		(start 382.12014 -121.539)
		(end 382.28905 -121.245884)
		(width 0.0889)
		(layer "B.Cu")
		(net "P3E_CPU0_PE1_PCH_R_RXP<13>")
	)
	(segment
		(start 372.466362 -117.62232)
		(end 372.745762 -117.62232)
		(width 0.0889)
		(layer "B.Cu")
		(net "P3E_CPU0_PE1_PCH_R_RXP<13>")
	)
	(segment
		(start 371.640862 -117.71122)
		(end 371.729762 -117.62232)
		(width 0.0889)
		(layer "B.Cu")
		(net "P3E_CPU0_PE1_PCH_R_RXP<13>")
	)
	(segment
		(start 372.098062 -117.71122)
		(end 372.377462 -117.71122)
		(width 0.0889)
		(layer "B.Cu")
		(net "P3E_CPU0_PE1_PCH_R_RXP<13>")
	)
	(segment
		(start 350.242632 -122.818144)
		(end 349.931482 -123.129294)
		(width 0.1143)
		(layer "B.Cu")
		(net "P3E_CPU0_PE1_PCH_R_RXP<13>")
	)
	(segment
		(start 374.854216 -118.180104)
		(end 375.133616 -118.180104)
		(width 0.0889)
		(layer "B.Cu")
		(net "P3E_CPU0_PE1_PCH_R_RXP<13>")
	)
	(segment
		(start 373.749316 -118.269004)
		(end 374.028716 -118.269004)
		(width 0.0889)
		(layer "B.Cu")
		(net "P3E_CPU0_PE1_PCH_R_RXP<13>")
	)
	(segment
		(start 350.242632 -122.013726)
		(end 350.242632 -122.818144)
		(width 0.1143)
		(layer "B.Cu")
		(net "P3E_CPU0_PE1_PCH_R_RXP<13>")
	)
	(segment
		(start 374.485916 -118.269004)
		(end 374.765316 -118.269004)
		(width 0.0889)
		(layer "B.Cu")
		(net "P3E_CPU0_PE1_PCH_R_RXP<13>")
	)
	(segment
		(start 372.009162 -117.62232)
		(end 372.098062 -117.71122)
		(width 0.0889)
		(layer "B.Cu")
		(net "P3E_CPU0_PE1_PCH_R_RXP<13>")
	)
	(segment
		(start 375.133616 -118.180104)
		(end 375.222516 -118.269004)
		(width 0.0889)
		(layer "B.Cu")
		(net "P3E_CPU0_PE1_PCH_R_RXP<13>")
	)
	(segment
		(start 350.52762 -121.513346)
		(end 350.242632 -122.013726)
		(width 0.1143)
		(layer "B.Cu")
		(net "P3E_CPU0_PE1_PCH_R_RXP<13>")
	)
	(segment
		(start 370.993162 -117.62232)
		(end 371.272562 -117.62232)
		(width 0.0889)
		(layer "B.Cu")
		(net "P3E_CPU0_PE1_PCH_R_RXP<13>")
	)
	(segment
		(start 349.931482 -123.129294)
		(end 349.584518 -123.129294)
		(width 0.1143)
		(layer "B.Cu")
		(net "P3E_CPU0_PE1_PCH_R_RXP<13>")
	)
	(segment
		(start 376.327416 -118.180104)
		(end 376.606816 -118.180104)
		(width 0.0889)
		(layer "B.Cu")
		(net "P3E_CPU0_PE1_PCH_R_RXP<13>")
	)
	(segment
		(start 374.028716 -118.269004)
		(end 374.117616 -118.180104)
		(width 0.0889)
		(layer "B.Cu")
		(net "P3E_CPU0_PE1_PCH_R_RXP<13>")
	)
	(segment
		(start 375.501916 -118.269004)
		(end 375.590816 -118.180104)
		(width 0.0889)
		(layer "B.Cu")
		(net "P3E_CPU0_PE1_PCH_R_RXP<13>")
	)
	(segment
		(start 372.377462 -117.71122)
		(end 372.466362 -117.62232)
		(width 0.0889)
		(layer "B.Cu")
		(net "P3E_CPU0_PE1_PCH_R_RXP<13>")
	)
	(segment
		(start 371.272562 -117.62232)
		(end 371.361462 -117.71122)
		(width 0.0889)
		(layer "B.Cu")
		(net "P3E_CPU0_PE1_PCH_R_RXP<13>")
	)
	(segment
		(start 374.397016 -118.180104)
		(end 374.485916 -118.269004)
		(width 0.0889)
		(layer "B.Cu")
		(net "P3E_CPU0_PE1_PCH_R_RXP<13>")
	)
	(segment
		(start 370.294662 -117.62232)
		(end 370.535962 -117.62232)
		(width 0.0889)
		(layer "B.Cu")
		(net "P3E_CPU0_PE1_PCH_R_RXP<13>")
	)
	(segment
		(start 367.792 -117.64772)
		(end 363.812836 -117.64772)
		(width 0.1143)
		(layer "B.Cu")
		(net "P3E_CPU0_PE1_PCH_R_RXP<13>")
	)
	(segment
		(start 370.269262 -117.64772)
		(end 370.294662 -117.62232)
		(width 0.0889)
		(layer "B.Cu")
		(net "P3E_CPU0_PE1_PCH_R_RXP<13>")
	)
	(segment
		(start 372.745762 -117.62232)
		(end 373.303546 -118.180104)
		(width 0.0889)
		(layer "B.Cu")
		(net "P3E_CPU0_PE1_PCH_R_RXP<13>")
	)
	(segment
		(start 376.238516 -118.269004)
		(end 376.327416 -118.180104)
		(width 0.0889)
		(layer "B.Cu")
		(net "P3E_CPU0_PE1_PCH_R_RXP<13>")
	)
	(segment
		(start 375.959116 -118.269004)
		(end 376.238516 -118.269004)
		(width 0.0889)
		(layer "B.Cu")
		(net "P3E_CPU0_PE1_PCH_R_RXP<13>")
	)
	(segment
		(start 370.247164 -117.64772)
		(end 370.269262 -117.64772)
		(width 0.0889)
		(layer "B.Cu")
		(net "P3E_CPU0_PE1_PCH_R_RXP<13>")
	)
	(segment
		(start 376.606816 -118.180104)
		(end 376.829574 -118.402862)
		(width 0.0889)
		(layer "B.Cu")
		(net "P3E_CPU0_PE1_PCH_R_RXP<13>")
	)
	(segment
		(start 371.361462 -117.71122)
		(end 371.640862 -117.71122)
		(width 0.0889)
		(layer "B.Cu")
		(net "P3E_CPU0_PE1_PCH_R_RXP<13>")
	)
	(segment
		(start 373.660416 -118.180104)
		(end 373.749316 -118.269004)
		(width 0.0889)
		(layer "B.Cu")
		(net "P3E_CPU0_PE1_PCH_R_RXP<13>")
	)
	(segment
		(start 384.175 -120.376188)
		(end 384.175 -120.39854)
		(width 0.0889)
		(layer "B.Cu")
		(net "P3E_CPU0_PE1_PCH_R_RXP<13>")
	)
	(segment
		(start 373.303546 -118.180104)
		(end 373.660416 -118.180104)
		(width 0.0889)
		(layer "B.Cu")
		(net "P3E_CPU0_PE1_PCH_R_RXP<13>")
	)
	(segment
		(start 377.096274 -118.402862)
		(end 377.185174 -118.491762)
		(width 0.0889)
		(layer "B.Cu")
		(net "P3E_CPU0_PE1_PCH_R_RXP<13>")
	)
	(arc
		(start 379.612652 -118.323614)
		(mid 379.81255 -118.270115)
		(end 380.012448 -118.323614)
		(width 0.0889)
		(layer "B.Cu")
		(net "P3E_CPU0_PE1_PCH_R_RXP<13>")
	)
	(arc
		(start 383.974848 -120.040654)
		(mid 384.118652 -120.182337)
		(end 384.175 -120.376188)
		(width 0.0889)
		(layer "B.Cu")
		(net "P3E_CPU0_PE1_PCH_R_RXP<13>")
	)
	(arc
		(start 381.993648 -118.323614)
		(mid 382.28905 -118.402745)
		(end 382.584452 -118.323614)
		(width 0.0889)
		(layer "B.Cu")
		(net "P3E_CPU0_PE1_PCH_R_RXP<13>")
	)
	(arc
		(start 384.175 -120.39854)
		(mid 384.11865 -120.59239)
		(end 383.974848 -120.734074)
		(width 0.0889)
		(layer "B.Cu")
		(net "P3E_CPU0_PE1_PCH_R_RXP<13>")
	)
	(arc
		(start 380.603252 -118.323614)
		(mid 380.80315 -118.270115)
		(end 381.003048 -118.323614)
		(width 0.0889)
		(layer "B.Cu")
		(net "P3E_CPU0_PE1_PCH_R_RXP<13>")
	)
	(arc
		(start 383.974848 -120.734074)
		(mid 383.763984 -120.941078)
		(end 383.6797 -121.224294)
		(width 0.0889)
		(layer "B.Cu")
		(net "P3E_CPU0_PE1_PCH_R_RXP<13>")
	)
	(arc
		(start 379.021848 -118.323614)
		(mid 379.31725 -118.402745)
		(end 379.612652 -118.323614)
		(width 0.0889)
		(layer "B.Cu")
		(net "P3E_CPU0_PE1_PCH_R_RXP<13>")
	)
	(arc
		(start 383.479548 -121.592594)
		(mid 383.27965 -121.646093)
		(end 383.079752 -121.592594)
		(width 0.0889)
		(layer "B.Cu")
		(net "P3E_CPU0_PE1_PCH_R_RXP<13>")
	)
	(arc
		(start 382.488948 -121.592594)
		(mid 382.318099 -121.644928)
		(end 382.141476 -121.61774)
		(width 0.0889)
		(layer "B.Cu")
		(net "P3E_CPU0_PE1_PCH_R_RXP<13>")
	)
	(arc
		(start 383.1844 -118.691914)
		(mid 383.268681 -118.975131)
		(end 383.479548 -119.182134)
		(width 0.0889)
		(layer "B.Cu")
		(net "P3E_CPU0_PE1_PCH_R_RXP<13>")
	)
	(arc
		(start 380.012448 -118.323614)
		(mid 380.30785 -118.402745)
		(end 380.603252 -118.323614)
		(width 0.0889)
		(layer "B.Cu")
		(net "P3E_CPU0_PE1_PCH_R_RXP<13>")
	)
	(arc
		(start 381.593852 -118.323614)
		(mid 381.79375 -118.270115)
		(end 381.993648 -118.323614)
		(width 0.0889)
		(layer "B.Cu")
		(net "P3E_CPU0_PE1_PCH_R_RXP<13>")
	)
	(arc
		(start 382.584452 -118.323614)
		(mid 382.78435 -118.270115)
		(end 382.984248 -118.323614)
		(width 0.0889)
		(layer "B.Cu")
		(net "P3E_CPU0_PE1_PCH_R_RXP<13>")
	)
	(arc
		(start 381.003048 -118.323614)
		(mid 381.29845 -118.402745)
		(end 381.593852 -118.323614)
		(width 0.0889)
		(layer "B.Cu")
		(net "P3E_CPU0_PE1_PCH_R_RXP<13>")
	)
	(arc
		(start 383.6797 -121.25706)
		(mid 383.62335 -121.45091)
		(end 383.479548 -121.592594)
		(width 0.0889)
		(layer "B.Cu")
		(net "P3E_CPU0_PE1_PCH_R_RXP<13>")
	)
	(arc
		(start 378.32665 -118.402862)
		(mid 378.479564 -118.382671)
		(end 378.622052 -118.323614)
		(width 0.0889)
		(layer "B.Cu")
		(net "P3E_CPU0_PE1_PCH_R_RXP<13>")
	)
	(arc
		(start 383.6797 -119.550434)
		(mid 383.763981 -119.833651)
		(end 383.974848 -120.040654)
		(width 0.0889)
		(layer "B.Cu")
		(net "P3E_CPU0_PE1_PCH_R_RXP<13>")
	)
	(arc
		(start 378.622052 -118.323614)
		(mid 378.82195 -118.270115)
		(end 379.021848 -118.323614)
		(width 0.0889)
		(layer "B.Cu")
		(net "P3E_CPU0_PE1_PCH_R_RXP<13>")
	)
	(arc
		(start 383.079752 -121.592594)
		(mid 382.78435 -121.513463)
		(end 382.488948 -121.592594)
		(width 0.0889)
		(layer "B.Cu")
		(net "P3E_CPU0_PE1_PCH_R_RXP<13>")
	)
	(arc
		(start 382.984248 -118.323614)
		(mid 383.128052 -118.465297)
		(end 383.1844 -118.659148)
		(width 0.0889)
		(layer "B.Cu")
		(net "P3E_CPU0_PE1_PCH_R_RXP<13>")
	)
	(arc
		(start 383.479548 -119.182134)
		(mid 383.623352 -119.323817)
		(end 383.6797 -119.517668)
		(width 0.0889)
		(layer "B.Cu")
		(net "P3E_CPU0_PE1_PCH_R_RXP<13>")
	)
	(segment
		(start 381.724916 -122.0724)
		(end 381.79375 -122.104404)
		(width 0.1143)
		(layer "F.Cu")
		(net "P3E_CPU0_PE1_PCH_R_RXN<13>")
	)
	(segment
		(start 381.29845 -121.87428)
		(end 381.4064 -121.924318)
		(width 0.1143)
		(layer "F.Cu")
		(net "P3E_CPU0_PE1_PCH_R_RXN<13>")
	)
	(segment
		(start 381.4064 -121.924318)
		(end 381.724916 -122.0724)
		(width 0.1143)
		(layer "F.Cu")
		(net "P3E_CPU0_PE1_PCH_R_RXN<13>")
	)
	(via
		(at 364.617 -117.40642)
		(size 0.508)
		(drill 0.254)
		(layers "F.Cu" "B.Cu")
		(net "P3E_CPU0_PE1_PCH_R_RXN<13>")
	)
	(via
		(at 381.79375 -122.104404)
		(size 0.508)
		(drill 0.254)
		(layers "F.Cu" "B.Cu")
		(net "P3E_CPU0_PE1_PCH_R_RXN<13>")
	)
	(segment
		(start 384.3655 -120.365774)
		(end 384.3655 -120.408954)
		(width 0.0889)
		(layer "B.Cu")
		(net "P3E_CPU0_PE1_PCH_R_RXN<13>")
	)
	(segment
		(start 370.294662 -117.43182)
		(end 372.824756 -117.43182)
		(width 0.0889)
		(layer "B.Cu")
		(net "P3E_CPU0_PE1_PCH_R_RXN<13>")
	)
	(segment
		(start 350.36633 -121.308876)
		(end 350.001332 -121.949718)
		(width 0.1143)
		(layer "B.Cu")
		(net "P3E_CPU0_PE1_PCH_R_RXN<13>")
	)
	(segment
		(start 376.908568 -118.212362)
		(end 378.326396 -118.212362)
		(width 0.0889)
		(layer "B.Cu")
		(net "P3E_CPU0_PE1_PCH_R_RXN<13>")
	)
	(segment
		(start 349.609918 -122.887994)
		(end 349.489014 -122.76709)
		(width 0.1143)
		(layer "B.Cu")
		(net "P3E_CPU0_PE1_PCH_R_RXN<13>")
	)
	(segment
		(start 373.38254 -117.989604)
		(end 376.68581 -117.989604)
		(width 0.0889)
		(layer "B.Cu")
		(net "P3E_CPU0_PE1_PCH_R_RXN<13>")
	)
	(segment
		(start 349.489014 -122.76709)
		(end 349.489014 -122.459242)
		(width 0.1143)
		(layer "B.Cu")
		(net "P3E_CPU0_PE1_PCH_R_RXN<13>")
	)
	(segment
		(start 370.269262 -117.40642)
		(end 370.294662 -117.43182)
		(width 0.0889)
		(layer "B.Cu")
		(net "P3E_CPU0_PE1_PCH_R_RXN<13>")
	)
	(segment
		(start 364.617 -117.40642)
		(end 370.247164 -117.40642)
		(width 0.1143)
		(layer "B.Cu")
		(net "P3E_CPU0_PE1_PCH_R_RXN<13>")
	)
	(segment
		(start 381.96266 -121.811288)
		(end 381.79375 -122.104404)
		(width 0.0889)
		(layer "B.Cu")
		(net "P3E_CPU0_PE1_PCH_R_RXN<13>")
	)
	(segment
		(start 382.052068 -121.787412)
		(end 381.96266 -121.811288)
		(width 0.0889)
		(layer "B.Cu")
		(net "P3E_CPU0_PE1_PCH_R_RXN<13>")
	)
	(segment
		(start 349.831406 -122.887994)
		(end 349.609918 -122.887994)
		(width 0.1143)
		(layer "B.Cu")
		(net "P3E_CPU0_PE1_PCH_R_RXN<13>")
	)
	(segment
		(start 350.001332 -122.718068)
		(end 349.831406 -122.887994)
		(width 0.1143)
		(layer "B.Cu")
		(net "P3E_CPU0_PE1_PCH_R_RXN<13>")
	)
	(segment
		(start 363.778292 -117.40642)
		(end 350.36633 -121.308876)
		(width 0.1143)
		(layer "B.Cu")
		(net "P3E_CPU0_PE1_PCH_R_RXN<13>")
	)
	(segment
		(start 364.617 -117.40642)
		(end 363.778292 -117.40642)
		(width 0.1143)
		(layer "B.Cu")
		(net "P3E_CPU0_PE1_PCH_R_RXN<13>")
	)
	(segment
		(start 376.68581 -117.989604)
		(end 376.908568 -118.212362)
		(width 0.0889)
		(layer "B.Cu")
		(net "P3E_CPU0_PE1_PCH_R_RXN<13>")
	)
	(segment
		(start 370.247164 -117.40642)
		(end 370.269262 -117.40642)
		(width 0.0889)
		(layer "B.Cu")
		(net "P3E_CPU0_PE1_PCH_R_RXN<13>")
	)
	(segment
		(start 372.824756 -117.43182)
		(end 373.38254 -117.989604)
		(width 0.0889)
		(layer "B.Cu")
		(net "P3E_CPU0_PE1_PCH_R_RXN<13>")
	)
	(segment
		(start 383.3749 -118.648734)
		(end 383.3749 -118.6815)
		(width 0.0889)
		(layer "B.Cu")
		(net "P3E_CPU0_PE1_PCH_R_RXN<13>")
	)
	(segment
		(start 383.8702 -119.507254)
		(end 383.8702 -119.54002)
		(width 0.0889)
		(layer "B.Cu")
		(net "P3E_CPU0_PE1_PCH_R_RXN<13>")
	)
	(segment
		(start 383.8702 -121.234708)
		(end 383.8702 -121.267474)
		(width 0.0889)
		(layer "B.Cu")
		(net "P3E_CPU0_PE1_PCH_R_RXN<13>")
	)
	(segment
		(start 350.001332 -121.949718)
		(end 350.001332 -122.718068)
		(width 0.1143)
		(layer "B.Cu")
		(net "P3E_CPU0_PE1_PCH_R_RXN<13>")
	)
	(arc
		(start 383.575052 -121.757694)
		(mid 383.27965 -121.836825)
		(end 382.984248 -121.757694)
		(width 0.0889)
		(layer "B.Cu")
		(net "P3E_CPU0_PE1_PCH_R_RXN<13>")
	)
	(arc
		(start 379.117352 -118.158514)
		(mid 379.31725 -118.212013)
		(end 379.517148 -118.158514)
		(width 0.0889)
		(layer "B.Cu")
		(net "P3E_CPU0_PE1_PCH_R_RXN<13>")
	)
	(arc
		(start 380.107952 -118.158514)
		(mid 380.30785 -118.212013)
		(end 380.507748 -118.158514)
		(width 0.0889)
		(layer "B.Cu")
		(net "P3E_CPU0_PE1_PCH_R_RXN<13>")
	)
	(arc
		(start 383.3749 -118.6815)
		(mid 383.43125 -118.87535)
		(end 383.575052 -119.017034)
		(width 0.0889)
		(layer "B.Cu")
		(net "P3E_CPU0_PE1_PCH_R_RXN<13>")
	)
	(arc
		(start 381.098552 -118.158514)
		(mid 381.29845 -118.212013)
		(end 381.498348 -118.158514)
		(width 0.0889)
		(layer "B.Cu")
		(net "P3E_CPU0_PE1_PCH_R_RXN<13>")
	)
	(arc
		(start 382.984248 -121.757694)
		(mid 382.78435 -121.704195)
		(end 382.584452 -121.757694)
		(width 0.0889)
		(layer "B.Cu")
		(net "P3E_CPU0_PE1_PCH_R_RXN<13>")
	)
	(arc
		(start 382.089152 -118.158514)
		(mid 382.28905 -118.212013)
		(end 382.488948 -118.158514)
		(width 0.0889)
		(layer "B.Cu")
		(net "P3E_CPU0_PE1_PCH_R_RXN<13>")
	)
	(arc
		(start 383.8702 -121.267474)
		(mid 383.785919 -121.550691)
		(end 383.575052 -121.757694)
		(width 0.0889)
		(layer "B.Cu")
		(net "P3E_CPU0_PE1_PCH_R_RXN<13>")
	)
	(arc
		(start 381.498348 -118.158514)
		(mid 381.79375 -118.079383)
		(end 382.089152 -118.158514)
		(width 0.0889)
		(layer "B.Cu")
		(net "P3E_CPU0_PE1_PCH_R_RXN<13>")
	)
	(arc
		(start 378.326396 -118.212362)
		(mid 378.430005 -118.198585)
		(end 378.526548 -118.158514)
		(width 0.0889)
		(layer "B.Cu")
		(net "P3E_CPU0_PE1_PCH_R_RXN<13>")
	)
	(arc
		(start 384.070352 -120.899174)
		(mid 383.926548 -121.040857)
		(end 383.8702 -121.234708)
		(width 0.0889)
		(layer "B.Cu")
		(net "P3E_CPU0_PE1_PCH_R_RXN<13>")
	)
	(arc
		(start 379.517148 -118.158514)
		(mid 379.81255 -118.079383)
		(end 380.107952 -118.158514)
		(width 0.0889)
		(layer "B.Cu")
		(net "P3E_CPU0_PE1_PCH_R_RXN<13>")
	)
	(arc
		(start 378.526548 -118.158514)
		(mid 378.82195 -118.079383)
		(end 379.117352 -118.158514)
		(width 0.0889)
		(layer "B.Cu")
		(net "P3E_CPU0_PE1_PCH_R_RXN<13>")
	)
	(arc
		(start 384.3655 -120.408954)
		(mid 384.281219 -120.692171)
		(end 384.070352 -120.899174)
		(width 0.0889)
		(layer "B.Cu")
		(net "P3E_CPU0_PE1_PCH_R_RXN<13>")
	)
	(arc
		(start 382.488948 -118.158514)
		(mid 382.78435 -118.079383)
		(end 383.079752 -118.158514)
		(width 0.0889)
		(layer "B.Cu")
		(net "P3E_CPU0_PE1_PCH_R_RXN<13>")
	)
	(arc
		(start 383.8702 -119.54002)
		(mid 383.92655 -119.73387)
		(end 384.070352 -119.875554)
		(width 0.0889)
		(layer "B.Cu")
		(net "P3E_CPU0_PE1_PCH_R_RXN<13>")
	)
	(arc
		(start 380.507748 -118.158514)
		(mid 380.80315 -118.079383)
		(end 381.098552 -118.158514)
		(width 0.0889)
		(layer "B.Cu")
		(net "P3E_CPU0_PE1_PCH_R_RXN<13>")
	)
	(arc
		(start 384.070352 -119.875554)
		(mid 384.281216 -120.082558)
		(end 384.3655 -120.365774)
		(width 0.0889)
		(layer "B.Cu")
		(net "P3E_CPU0_PE1_PCH_R_RXN<13>")
	)
	(arc
		(start 383.079752 -118.158514)
		(mid 383.290616 -118.365518)
		(end 383.3749 -118.648734)
		(width 0.0889)
		(layer "B.Cu")
		(net "P3E_CPU0_PE1_PCH_R_RXN<13>")
	)
	(arc
		(start 383.575052 -119.017034)
		(mid 383.785916 -119.224038)
		(end 383.8702 -119.507254)
		(width 0.0889)
		(layer "B.Cu")
		(net "P3E_CPU0_PE1_PCH_R_RXN<13>")
	)
	(arc
		(start 382.584452 -121.757694)
		(mid 382.321796 -121.836031)
		(end 382.052068 -121.787412)
		(width 0.0889)
		(layer "B.Cu")
		(net "P3E_CPU0_PE1_PCH_R_RXN<13>")
	)
	(segment
		(start 381.79375 -122.7328)
		(end 382.1684 -122.90679)
		(width 0.1143)
		(layer "F.Cu")
		(net "P3E_CPU0_PE1_PCH_R_RXP<12>")
	)
	(segment
		(start 382.1684 -122.90679)
		(end 382.28905 -122.962924)
		(width 0.1143)
		(layer "F.Cu")
		(net "P3E_CPU0_PE1_PCH_R_RXP<12>")
	)
	(via
		(at 358.345232 -120.076468)
		(size 0.508)
		(drill 0.254)
		(layers "F.Cu" "B.Cu")
		(net "P3E_CPU0_PE1_PCH_R_RXP<12>")
	)
	(via
		(at 382.28905 -122.962924)
		(size 0.508)
		(drill 0.254)
		(layers "F.Cu" "B.Cu")
		(net "P3E_CPU0_PE1_PCH_R_RXP<12>")
	)
	(segment
		(start 373.23522 -118.958106)
		(end 373.26062 -118.983506)
		(width 0.0889)
		(layer "B.Cu")
		(net "P3E_CPU0_PE1_PCH_R_RXP<12>")
	)
	(segment
		(start 366.357408 -118.836694)
		(end 367.642394 -118.546372)
		(width 0.1143)
		(layer "B.Cu")
		(net "P3E_CPU0_PE1_PCH_R_RXP<12>")
	)
	(segment
		(start 354.937314 -123.056142)
		(end 355.27615 -123.056142)
		(width 0.1143)
		(layer "B.Cu")
		(net "P3E_CPU0_PE1_PCH_R_RXP<12>")
	)
	(segment
		(start 356.084378 -122.524774)
		(end 356.754938 -122.084338)
		(width 0.1143)
		(layer "B.Cu")
		(net "P3E_CPU0_PE1_PCH_R_RXP<12>")
	)
	(segment
		(start 357.379778 -120.35028)
		(end 358.345232 -120.076468)
		(width 0.1143)
		(layer "B.Cu")
		(net "P3E_CPU0_PE1_PCH_R_RXP<12>")
	)
	(segment
		(start 373.213122 -118.958106)
		(end 373.23522 -118.958106)
		(width 0.0889)
		(layer "B.Cu")
		(net "P3E_CPU0_PE1_PCH_R_RXP<12>")
	)
	(segment
		(start 381.3937 -122.093228)
		(end 381.3937 -122.11558)
		(width 0.0889)
		(layer "B.Cu")
		(net "P3E_CPU0_PE1_PCH_R_RXP<12>")
	)
	(segment
		(start 381.889 -121.234708)
		(end 381.889 -121.267474)
		(width 0.0889)
		(layer "B.Cu")
		(net "P3E_CPU0_PE1_PCH_R_RXP<12>")
	)
	(segment
		(start 371.59438 -118.608094)
		(end 373.051324 -118.958106)
		(width 0.1143)
		(layer "B.Cu")
		(net "P3E_CPU0_PE1_PCH_R_RXP<12>")
	)
	(segment
		(start 378.144786 -118.937786)
		(end 378.32665 -118.937786)
		(width 0.0889)
		(layer "B.Cu")
		(net "P3E_CPU0_PE1_PCH_R_RXP<12>")
	)
	(segment
		(start 383.3749 -120.365774)
		(end 383.3749 -120.408954)
		(width 0.0889)
		(layer "B.Cu")
		(net "P3E_CPU0_PE1_PCH_R_RXP<12>")
	)
	(segment
		(start 364.152434 -118.429024)
		(end 366.357408 -118.836694)
		(width 0.1143)
		(layer "B.Cu")
		(net "P3E_CPU0_PE1_PCH_R_RXP<12>")
	)
	(segment
		(start 373.051324 -118.958106)
		(end 373.213122 -118.958106)
		(width 0.1143)
		(layer "B.Cu")
		(net "P3E_CPU0_PE1_PCH_R_RXP<12>")
	)
	(segment
		(start 382.8796 -119.507254)
		(end 382.8796 -119.54002)
		(width 0.0889)
		(layer "B.Cu")
		(net "P3E_CPU0_PE1_PCH_R_RXP<12>")
	)
	(segment
		(start 358.345232 -120.076468)
		(end 364.152434 -118.429024)
		(width 0.1143)
		(layer "B.Cu")
		(net "P3E_CPU0_PE1_PCH_R_RXP<12>")
	)
	(segment
		(start 376.033284 -118.736364)
		(end 377.943364 -118.736364)
		(width 0.0889)
		(layer "B.Cu")
		(net "P3E_CPU0_PE1_PCH_R_RXP<12>")
	)
	(segment
		(start 367.642394 -118.546372)
		(end 369.842796 -118.942358)
		(width 0.1143)
		(layer "B.Cu")
		(net "P3E_CPU0_PE1_PCH_R_RXP<12>")
	)
	(segment
		(start 381.885952 -122.8979)
		(end 381.950976 -122.962924)
		(width 0.0889)
		(layer "B.Cu")
		(net "P3E_CPU0_PE1_PCH_R_RXP<12>")
	)
	(segment
		(start 375.786142 -118.983506)
		(end 376.033284 -118.736364)
		(width 0.0889)
		(layer "B.Cu")
		(net "P3E_CPU0_PE1_PCH_R_RXP<12>")
	)
	(segment
		(start 381.950976 -122.962924)
		(end 382.28905 -122.962924)
		(width 0.0889)
		(layer "B.Cu")
		(net "P3E_CPU0_PE1_PCH_R_RXP<12>")
	)
	(segment
		(start 377.943364 -118.736364)
		(end 378.144786 -118.937786)
		(width 0.0889)
		(layer "B.Cu")
		(net "P3E_CPU0_PE1_PCH_R_RXP<12>")
	)
	(segment
		(start 373.26062 -118.983506)
		(end 375.786142 -118.983506)
		(width 0.0889)
		(layer "B.Cu")
		(net "P3E_CPU0_PE1_PCH_R_RXP<12>")
	)
	(segment
		(start 355.27615 -123.056142)
		(end 356.084378 -122.524774)
		(width 0.1143)
		(layer "B.Cu")
		(net "P3E_CPU0_PE1_PCH_R_RXP<12>")
	)
	(segment
		(start 369.842796 -118.942358)
		(end 371.59438 -118.608094)
		(width 0.1143)
		(layer "B.Cu")
		(net "P3E_CPU0_PE1_PCH_R_RXP<12>")
	)
	(segment
		(start 356.754938 -122.084338)
		(end 357.379778 -120.35028)
		(width 0.1143)
		(layer "B.Cu")
		(net "P3E_CPU0_PE1_PCH_R_RXP<12>")
	)
	(segment
		(start 354.543614 -122.662442)
		(end 354.937314 -123.056142)
		(width 0.1143)
		(layer "B.Cu")
		(net "P3E_CPU0_PE1_PCH_R_RXP<12>")
	)
	(arc
		(start 379.612652 -119.017034)
		(mid 379.81255 -119.070533)
		(end 380.012448 -119.017034)
		(width 0.0889)
		(layer "B.Cu")
		(net "P3E_CPU0_PE1_PCH_R_RXP<12>")
	)
	(arc
		(start 382.8796 -119.54002)
		(mid 382.93595 -119.73387)
		(end 383.079752 -119.875554)
		(width 0.0889)
		(layer "B.Cu")
		(net "P3E_CPU0_PE1_PCH_R_RXP<12>")
	)
	(arc
		(start 381.593852 -121.757694)
		(mid 381.450048 -121.899377)
		(end 381.3937 -122.093228)
		(width 0.0889)
		(layer "B.Cu")
		(net "P3E_CPU0_PE1_PCH_R_RXP<12>")
	)
	(arc
		(start 383.079752 -119.875554)
		(mid 383.290616 -120.082558)
		(end 383.3749 -120.365774)
		(width 0.0889)
		(layer "B.Cu")
		(net "P3E_CPU0_PE1_PCH_R_RXP<12>")
	)
	(arc
		(start 382.089152 -120.899174)
		(mid 381.945348 -121.040857)
		(end 381.889 -121.234708)
		(width 0.0889)
		(layer "B.Cu")
		(net "P3E_CPU0_PE1_PCH_R_RXP<12>")
	)
	(arc
		(start 383.079752 -120.899174)
		(mid 382.78435 -120.978305)
		(end 382.488948 -120.899174)
		(width 0.0889)
		(layer "B.Cu")
		(net "P3E_CPU0_PE1_PCH_R_RXP<12>")
	)
	(arc
		(start 382.584452 -119.017034)
		(mid 382.795316 -119.224038)
		(end 382.8796 -119.507254)
		(width 0.0889)
		(layer "B.Cu")
		(net "P3E_CPU0_PE1_PCH_R_RXP<12>")
	)
	(arc
		(start 381.003048 -119.017034)
		(mid 381.29845 -118.937903)
		(end 381.593852 -119.017034)
		(width 0.0889)
		(layer "B.Cu")
		(net "P3E_CPU0_PE1_PCH_R_RXP<12>")
	)
	(arc
		(start 382.488948 -120.899174)
		(mid 382.28905 -120.845675)
		(end 382.089152 -120.899174)
		(width 0.0889)
		(layer "B.Cu")
		(net "P3E_CPU0_PE1_PCH_R_RXP<12>")
	)
	(arc
		(start 380.603252 -119.017034)
		(mid 380.80315 -119.070533)
		(end 381.003048 -119.017034)
		(width 0.0889)
		(layer "B.Cu")
		(net "P3E_CPU0_PE1_PCH_R_RXP<12>")
	)
	(arc
		(start 380.012448 -119.017034)
		(mid 380.30785 -118.937903)
		(end 380.603252 -119.017034)
		(width 0.0889)
		(layer "B.Cu")
		(net "P3E_CPU0_PE1_PCH_R_RXP<12>")
	)
	(arc
		(start 381.593852 -119.017034)
		(mid 381.79375 -119.070533)
		(end 381.993648 -119.017034)
		(width 0.0889)
		(layer "B.Cu")
		(net "P3E_CPU0_PE1_PCH_R_RXP<12>")
	)
	(arc
		(start 383.3749 -120.408954)
		(mid 383.290619 -120.692171)
		(end 383.079752 -120.899174)
		(width 0.0889)
		(layer "B.Cu")
		(net "P3E_CPU0_PE1_PCH_R_RXP<12>")
	)
	(arc
		(start 381.889 -121.267474)
		(mid 381.804719 -121.550691)
		(end 381.593852 -121.757694)
		(width 0.0889)
		(layer "B.Cu")
		(net "P3E_CPU0_PE1_PCH_R_RXP<12>")
	)
	(arc
		(start 379.021848 -119.017034)
		(mid 379.31725 -118.937903)
		(end 379.612652 -119.017034)
		(width 0.0889)
		(layer "B.Cu")
		(net "P3E_CPU0_PE1_PCH_R_RXP<12>")
	)
	(arc
		(start 378.622052 -119.017034)
		(mid 378.82195 -119.070533)
		(end 379.021848 -119.017034)
		(width 0.0889)
		(layer "B.Cu")
		(net "P3E_CPU0_PE1_PCH_R_RXP<12>")
	)
	(arc
		(start 378.32665 -118.937786)
		(mid 378.479595 -118.95787)
		(end 378.622052 -119.017034)
		(width 0.0889)
		(layer "B.Cu")
		(net "P3E_CPU0_PE1_PCH_R_RXP<12>")
	)
	(arc
		(start 381.593852 -122.451114)
		(mid 381.793225 -122.639642)
		(end 381.885952 -122.8979)
		(width 0.0889)
		(layer "B.Cu")
		(net "P3E_CPU0_PE1_PCH_R_RXP<12>")
	)
	(arc
		(start 381.3937 -122.11558)
		(mid 381.45005 -122.30943)
		(end 381.593852 -122.451114)
		(width 0.0889)
		(layer "B.Cu")
		(net "P3E_CPU0_PE1_PCH_R_RXP<12>")
	)
	(arc
		(start 381.993648 -119.017034)
		(mid 382.28905 -118.937903)
		(end 382.584452 -119.017034)
		(width 0.0889)
		(layer "B.Cu")
		(net "P3E_CPU0_PE1_PCH_R_RXP<12>")
	)
	(segment
		(start 380.80315 -122.7328)
		(end 381.29845 -122.962924)
		(width 0.1143)
		(layer "F.Cu")
		(net "P3E_CPU0_PE1_PCH_R_RXN<12>")
	)
	(via
		(at 381.29845 -122.962924)
		(size 0.508)
		(drill 0.254)
		(layers "F.Cu" "B.Cu")
		(net "P3E_CPU0_PE1_PCH_R_RXN<12>")
	)
	(via
		(at 356.21722 -122.726704)
		(size 0.508)
		(drill 0.254)
		(layers "F.Cu" "B.Cu")
		(net "P3E_CPU0_PE1_PCH_R_RXN<12>")
	)
	(segment
		(start 371.588538 -118.854982)
		(end 373.022622 -119.199406)
		(width 0.1143)
		(layer "B.Cu")
		(net "P3E_CPU0_PE1_PCH_R_RXN<12>")
	)
	(segment
		(start 378.526548 -119.18188)
		(end 378.526548 -119.182134)
		(width 0.0889)
		(layer "B.Cu")
		(net "P3E_CPU0_PE1_PCH_R_RXN<12>")
	)
	(segment
		(start 383.1844 -120.376188)
		(end 383.1844 -120.39854)
		(width 0.0889)
		(layer "B.Cu")
		(net "P3E_CPU0_PE1_PCH_R_RXN<12>")
	)
	(segment
		(start 375.496836 -119.262906)
		(end 375.585736 -119.174006)
		(width 0.0889)
		(layer "B.Cu")
		(net "P3E_CPU0_PE1_PCH_R_RXN<12>")
	)
	(segment
		(start 366.362234 -119.083074)
		(end 367.647728 -118.792752)
		(width 0.1143)
		(layer "B.Cu")
		(net "P3E_CPU0_PE1_PCH_R_RXN<12>")
	)
	(segment
		(start 378.065792 -119.128286)
		(end 378.326904 -119.128286)
		(width 0.0889)
		(layer "B.Cu")
		(net "P3E_CPU0_PE1_PCH_R_RXN<12>")
	)
	(segment
		(start 367.647728 -118.792752)
		(end 369.844066 -119.187976)
		(width 0.1143)
		(layer "B.Cu")
		(net "P3E_CPU0_PE1_PCH_R_RXN<12>")
	)
	(segment
		(start 373.744236 -119.262906)
		(end 374.023636 -119.262906)
		(width 0.0889)
		(layer "B.Cu")
		(net "P3E_CPU0_PE1_PCH_R_RXN<12>")
	)
	(segment
		(start 375.128536 -119.174006)
		(end 375.217436 -119.262906)
		(width 0.0889)
		(layer "B.Cu")
		(net "P3E_CPU0_PE1_PCH_R_RXN<12>")
	)
	(segment
		(start 375.217436 -119.262906)
		(end 375.496836 -119.262906)
		(width 0.0889)
		(layer "B.Cu")
		(net "P3E_CPU0_PE1_PCH_R_RXN<12>")
	)
	(segment
		(start 373.26062 -119.174006)
		(end 373.655336 -119.174006)
		(width 0.0889)
		(layer "B.Cu")
		(net "P3E_CPU0_PE1_PCH_R_RXN<12>")
	)
	(segment
		(start 373.655336 -119.174006)
		(end 373.744236 -119.262906)
		(width 0.0889)
		(layer "B.Cu")
		(net "P3E_CPU0_PE1_PCH_R_RXN<12>")
	)
	(segment
		(start 381.2032 -122.082814)
		(end 381.2032 -122.125994)
		(width 0.0889)
		(layer "B.Cu")
		(net "P3E_CPU0_PE1_PCH_R_RXN<12>")
	)
	(segment
		(start 377.86437 -118.926864)
		(end 378.065792 -119.128286)
		(width 0.0889)
		(layer "B.Cu")
		(net "P3E_CPU0_PE1_PCH_R_RXN<12>")
	)
	(segment
		(start 373.213122 -119.199406)
		(end 373.23522 -119.199406)
		(width 0.0889)
		(layer "B.Cu")
		(net "P3E_CPU0_PE1_PCH_R_RXN<12>")
	)
	(segment
		(start 374.391936 -119.174006)
		(end 374.480836 -119.262906)
		(width 0.0889)
		(layer "B.Cu")
		(net "P3E_CPU0_PE1_PCH_R_RXN<12>")
	)
	(segment
		(start 364.163864 -118.676674)
		(end 366.362234 -119.083074)
		(width 0.1143)
		(layer "B.Cu")
		(net "P3E_CPU0_PE1_PCH_R_RXN<12>")
	)
	(segment
		(start 375.865136 -119.174006)
		(end 376.112278 -118.926864)
		(width 0.0889)
		(layer "B.Cu")
		(net "P3E_CPU0_PE1_PCH_R_RXN<12>")
	)
	(segment
		(start 374.112536 -119.174006)
		(end 374.391936 -119.174006)
		(width 0.0889)
		(layer "B.Cu")
		(net "P3E_CPU0_PE1_PCH_R_RXN<12>")
	)
	(segment
		(start 355.34854 -123.297442)
		(end 356.21722 -122.726704)
		(width 0.1143)
		(layer "B.Cu")
		(net "P3E_CPU0_PE1_PCH_R_RXN<12>")
	)
	(segment
		(start 381.636524 -122.962924)
		(end 381.29845 -122.962924)
		(width 0.0889)
		(layer "B.Cu")
		(net "P3E_CPU0_PE1_PCH_R_RXN<12>")
	)
	(segment
		(start 381.6985 -121.224294)
		(end 381.6985 -121.25706)
		(width 0.0889)
		(layer "B.Cu")
		(net "P3E_CPU0_PE1_PCH_R_RXN<12>")
	)
	(segment
		(start 357.564944 -120.548908)
		(end 364.163864 -118.676674)
		(width 0.1143)
		(layer "B.Cu")
		(net "P3E_CPU0_PE1_PCH_R_RXN<12>")
	)
	(segment
		(start 356.954836 -122.242072)
		(end 357.564944 -120.548908)
		(width 0.1143)
		(layer "B.Cu")
		(net "P3E_CPU0_PE1_PCH_R_RXN<12>")
	)
	(segment
		(start 369.844066 -119.187976)
		(end 371.588538 -118.854982)
		(width 0.1143)
		(layer "B.Cu")
		(net "P3E_CPU0_PE1_PCH_R_RXN<12>")
	)
	(segment
		(start 376.112278 -118.926864)
		(end 377.86437 -118.926864)
		(width 0.0889)
		(layer "B.Cu")
		(net "P3E_CPU0_PE1_PCH_R_RXN<12>")
	)
	(segment
		(start 375.585736 -119.174006)
		(end 375.865136 -119.174006)
		(width 0.0889)
		(layer "B.Cu")
		(net "P3E_CPU0_PE1_PCH_R_RXN<12>")
	)
	(segment
		(start 374.480836 -119.262906)
		(end 374.760236 -119.262906)
		(width 0.0889)
		(layer "B.Cu")
		(net "P3E_CPU0_PE1_PCH_R_RXN<12>")
	)
	(segment
		(start 382.6891 -119.517668)
		(end 382.6891 -119.550434)
		(width 0.0889)
		(layer "B.Cu")
		(net "P3E_CPU0_PE1_PCH_R_RXN<12>")
	)
	(segment
		(start 355.026214 -123.297442)
		(end 355.34854 -123.297442)
		(width 0.1143)
		(layer "B.Cu")
		(net "P3E_CPU0_PE1_PCH_R_RXN<12>")
	)
	(segment
		(start 374.023636 -119.262906)
		(end 374.112536 -119.174006)
		(width 0.0889)
		(layer "B.Cu")
		(net "P3E_CPU0_PE1_PCH_R_RXN<12>")
	)
	(segment
		(start 374.760236 -119.262906)
		(end 374.849136 -119.174006)
		(width 0.0889)
		(layer "B.Cu")
		(net "P3E_CPU0_PE1_PCH_R_RXN<12>")
	)
	(segment
		(start 374.849136 -119.174006)
		(end 375.128536 -119.174006)
		(width 0.0889)
		(layer "B.Cu")
		(net "P3E_CPU0_PE1_PCH_R_RXN<12>")
	)
	(segment
		(start 373.23522 -119.199406)
		(end 373.26062 -119.174006)
		(width 0.0889)
		(layer "B.Cu")
		(net "P3E_CPU0_PE1_PCH_R_RXN<12>")
	)
	(segment
		(start 381.694436 -122.905012)
		(end 381.636524 -122.962924)
		(width 0.0889)
		(layer "B.Cu")
		(net "P3E_CPU0_PE1_PCH_R_RXN<12>")
	)
	(segment
		(start 356.21722 -122.726704)
		(end 356.954836 -122.242072)
		(width 0.1143)
		(layer "B.Cu")
		(net "P3E_CPU0_PE1_PCH_R_RXN<12>")
	)
	(segment
		(start 373.022622 -119.199406)
		(end 373.213122 -119.199406)
		(width 0.1143)
		(layer "B.Cu")
		(net "P3E_CPU0_PE1_PCH_R_RXN<12>")
	)
	(segment
		(start 354.543614 -123.780042)
		(end 355.026214 -123.297442)
		(width 0.1143)
		(layer "B.Cu")
		(net "P3E_CPU0_PE1_PCH_R_RXN<12>")
	)
	(arc
		(start 379.117352 -119.182134)
		(mid 379.31725 -119.128635)
		(end 379.517148 -119.182134)
		(width 0.0889)
		(layer "B.Cu")
		(net "P3E_CPU0_PE1_PCH_R_RXN<12>")
	)
	(arc
		(start 381.098552 -119.182134)
		(mid 381.29845 -119.128635)
		(end 381.498348 -119.182134)
		(width 0.0889)
		(layer "B.Cu")
		(net "P3E_CPU0_PE1_PCH_R_RXN<12>")
	)
	(arc
		(start 383.1844 -120.39854)
		(mid 383.12805 -120.59239)
		(end 382.984248 -120.734074)
		(width 0.0889)
		(layer "B.Cu")
		(net "P3E_CPU0_PE1_PCH_R_RXN<12>")
	)
	(arc
		(start 382.6891 -119.550434)
		(mid 382.773381 -119.833651)
		(end 382.984248 -120.040654)
		(width 0.0889)
		(layer "B.Cu")
		(net "P3E_CPU0_PE1_PCH_R_RXN<12>")
	)
	(arc
		(start 381.498348 -121.592594)
		(mid 381.287484 -121.799598)
		(end 381.2032 -122.082814)
		(width 0.0889)
		(layer "B.Cu")
		(net "P3E_CPU0_PE1_PCH_R_RXN<12>")
	)
	(arc
		(start 381.6985 -121.25706)
		(mid 381.64215 -121.45091)
		(end 381.498348 -121.592594)
		(width 0.0889)
		(layer "B.Cu")
		(net "P3E_CPU0_PE1_PCH_R_RXN<12>")
	)
	(arc
		(start 382.984248 -120.734074)
		(mid 382.78435 -120.787573)
		(end 382.584452 -120.734074)
		(width 0.0889)
		(layer "B.Cu")
		(net "P3E_CPU0_PE1_PCH_R_RXN<12>")
	)
	(arc
		(start 382.488948 -119.182134)
		(mid 382.632752 -119.323817)
		(end 382.6891 -119.517668)
		(width 0.0889)
		(layer "B.Cu")
		(net "P3E_CPU0_PE1_PCH_R_RXN<12>")
	)
	(arc
		(start 380.507748 -119.182134)
		(mid 380.80315 -119.261265)
		(end 381.098552 -119.182134)
		(width 0.0889)
		(layer "B.Cu")
		(net "P3E_CPU0_PE1_PCH_R_RXN<12>")
	)
	(arc
		(start 382.984248 -120.040654)
		(mid 383.128052 -120.182337)
		(end 383.1844 -120.376188)
		(width 0.0889)
		(layer "B.Cu")
		(net "P3E_CPU0_PE1_PCH_R_RXN<12>")
	)
	(arc
		(start 380.107952 -119.182134)
		(mid 380.30785 -119.128635)
		(end 380.507748 -119.182134)
		(width 0.0889)
		(layer "B.Cu")
		(net "P3E_CPU0_PE1_PCH_R_RXN<12>")
	)
	(arc
		(start 382.089152 -119.182134)
		(mid 382.28905 -119.128635)
		(end 382.488948 -119.182134)
		(width 0.0889)
		(layer "B.Cu")
		(net "P3E_CPU0_PE1_PCH_R_RXN<12>")
	)
	(arc
		(start 379.517148 -119.182134)
		(mid 379.81255 -119.261265)
		(end 380.107952 -119.182134)
		(width 0.0889)
		(layer "B.Cu")
		(net "P3E_CPU0_PE1_PCH_R_RXN<12>")
	)
	(arc
		(start 381.993648 -120.734074)
		(mid 381.782784 -120.941078)
		(end 381.6985 -121.224294)
		(width 0.0889)
		(layer "B.Cu")
		(net "P3E_CPU0_PE1_PCH_R_RXN<12>")
	)
	(arc
		(start 381.498348 -119.182134)
		(mid 381.79375 -119.261265)
		(end 382.089152 -119.182134)
		(width 0.0889)
		(layer "B.Cu")
		(net "P3E_CPU0_PE1_PCH_R_RXN<12>")
	)
	(arc
		(start 378.326904 -119.128286)
		(mid 378.430274 -119.141875)
		(end 378.526548 -119.18188)
		(width 0.0889)
		(layer "B.Cu")
		(net "P3E_CPU0_PE1_PCH_R_RXN<12>")
	)
	(arc
		(start 378.526548 -119.182134)
		(mid 378.82195 -119.261265)
		(end 379.117352 -119.182134)
		(width 0.0889)
		(layer "B.Cu")
		(net "P3E_CPU0_PE1_PCH_R_RXN<12>")
	)
	(arc
		(start 381.2032 -122.125994)
		(mid 381.287481 -122.409211)
		(end 381.498348 -122.616214)
		(width 0.0889)
		(layer "B.Cu")
		(net "P3E_CPU0_PE1_PCH_R_RXN<12>")
	)
	(arc
		(start 382.584452 -120.734074)
		(mid 382.28905 -120.654943)
		(end 381.993648 -120.734074)
		(width 0.0889)
		(layer "B.Cu")
		(net "P3E_CPU0_PE1_PCH_R_RXN<12>")
	)
	(arc
		(start 381.498348 -122.616214)
		(mid 381.629544 -122.738105)
		(end 381.694436 -122.905012)
		(width 0.0889)
		(layer "B.Cu")
		(net "P3E_CPU0_PE1_PCH_R_RXN<12>")
	)
	(segment
		(start 382.28905 -120.15724)
		(end 382.3462 -120.183656)
		(width 0.1143)
		(layer "F.Cu")
		(net "P3E_CPU0_PE1_PCH_R_RXP<11>")
	)
	(segment
		(start 382.3462 -120.183656)
		(end 382.78435 -120.387364)
		(width 0.1143)
		(layer "F.Cu")
		(net "P3E_CPU0_PE1_PCH_R_RXP<11>")
	)
	(via
		(at 365.323882 -120.038368)
		(size 0.508)
		(drill 0.254)
		(layers "F.Cu" "B.Cu")
		(net "P3E_CPU0_PE1_PCH_R_RXP<11>")
	)
	(via
		(at 382.78435 -120.387364)
		(size 0.508)
		(drill 0.254)
		(layers "F.Cu" "B.Cu")
		(net "P3E_CPU0_PE1_PCH_R_RXP<11>")
	)
	(segment
		(start 365.323882 -120.038368)
		(end 367.721642 -119.594376)
		(width 0.1143)
		(layer "B.Cu")
		(net "P3E_CPU0_PE1_PCH_R_RXP<11>")
	)
	(segment
		(start 365.323882 -120.038368)
		(end 364.82655 -120.13057)
		(width 0.1143)
		(layer "B.Cu")
		(net "P3E_CPU0_PE1_PCH_R_RXP<11>")
	)
	(segment
		(start 364.826042 -120.13057)
		(end 363.636814 -120.97131)
		(width 0.1143)
		(layer "B.Cu")
		(net "P3E_CPU0_PE1_PCH_R_RXP<11>")
	)
	(segment
		(start 364.82655 -120.13057)
		(end 364.826042 -120.13057)
		(width 0.1143)
		(layer "B.Cu")
		(net "P3E_CPU0_PE1_PCH_R_RXP<11>")
	)
	(segment
		(start 363.636814 -120.97131)
		(end 363.636814 -121.65711)
		(width 0.1143)
		(layer "B.Cu")
		(net "P3E_CPU0_PE1_PCH_R_RXP<11>")
	)
	(segment
		(start 376.744992 -119.796306)
		(end 377.83135 -119.796306)
		(width 0.0889)
		(layer "B.Cu")
		(net "P3E_CPU0_PE1_PCH_R_RXP<11>")
	)
	(segment
		(start 376.124216 -119.760238)
		(end 376.708924 -119.760238)
		(width 0.0889)
		(layer "B.Cu")
		(net "P3E_CPU0_PE1_PCH_R_RXP<11>")
	)
	(segment
		(start 373.080788 -120.421146)
		(end 373.102886 -120.421146)
		(width 0.0889)
		(layer "B.Cu")
		(net "P3E_CPU0_PE1_PCH_R_RXP<11>")
	)
	(segment
		(start 371.567964 -120.421146)
		(end 373.080788 -120.421146)
		(width 0.1143)
		(layer "B.Cu")
		(net "P3E_CPU0_PE1_PCH_R_RXP<11>")
	)
	(segment
		(start 367.721642 -119.594376)
		(end 371.567964 -120.421146)
		(width 0.1143)
		(layer "B.Cu")
		(net "P3E_CPU0_PE1_PCH_R_RXP<11>")
	)
	(segment
		(start 363.463332 -121.830592)
		(end 363.153706 -121.830592)
		(width 0.1143)
		(layer "B.Cu")
		(net "P3E_CPU0_PE1_PCH_R_RXP<11>")
	)
	(segment
		(start 363.636814 -121.65711)
		(end 363.463332 -121.830592)
		(width 0.1143)
		(layer "B.Cu")
		(net "P3E_CPU0_PE1_PCH_R_RXP<11>")
	)
	(segment
		(start 382.381252 -120.32234)
		(end 382.446276 -120.387364)
		(width 0.0889)
		(layer "B.Cu")
		(net "P3E_CPU0_PE1_PCH_R_RXP<11>")
	)
	(segment
		(start 363.153706 -121.830592)
		(end 362.715556 -121.392442)
		(width 0.1143)
		(layer "B.Cu")
		(net "P3E_CPU0_PE1_PCH_R_RXP<11>")
	)
	(segment
		(start 382.446276 -120.387364)
		(end 382.78435 -120.387364)
		(width 0.0889)
		(layer "B.Cu")
		(net "P3E_CPU0_PE1_PCH_R_RXP<11>")
	)
	(segment
		(start 373.128286 -120.446546)
		(end 375.437908 -120.446546)
		(width 0.0889)
		(layer "B.Cu")
		(net "P3E_CPU0_PE1_PCH_R_RXP<11>")
	)
	(segment
		(start 375.437908 -120.446546)
		(end 376.124216 -119.760238)
		(width 0.0889)
		(layer "B.Cu")
		(net "P3E_CPU0_PE1_PCH_R_RXP<11>")
	)
	(segment
		(start 373.102886 -120.421146)
		(end 373.128286 -120.446546)
		(width 0.0889)
		(layer "B.Cu")
		(net "P3E_CPU0_PE1_PCH_R_RXP<11>")
	)
	(segment
		(start 376.708924 -119.760238)
		(end 376.744992 -119.796306)
		(width 0.0889)
		(layer "B.Cu")
		(net "P3E_CPU0_PE1_PCH_R_RXP<11>")
	)
	(arc
		(start 381.098552 -119.875554)
		(mid 381.29845 -119.929053)
		(end 381.498348 -119.875554)
		(width 0.0889)
		(layer "B.Cu")
		(net "P3E_CPU0_PE1_PCH_R_RXP<11>")
	)
	(arc
		(start 378.126752 -119.875554)
		(mid 378.32665 -119.929053)
		(end 378.526548 -119.875554)
		(width 0.0889)
		(layer "B.Cu")
		(net "P3E_CPU0_PE1_PCH_R_RXP<11>")
	)
	(arc
		(start 379.117352 -119.875554)
		(mid 379.31725 -119.929053)
		(end 379.517148 -119.875554)
		(width 0.0889)
		(layer "B.Cu")
		(net "P3E_CPU0_PE1_PCH_R_RXP<11>")
	)
	(arc
		(start 380.107952 -119.875554)
		(mid 380.30785 -119.929053)
		(end 380.507748 -119.875554)
		(width 0.0889)
		(layer "B.Cu")
		(net "P3E_CPU0_PE1_PCH_R_RXP<11>")
	)
	(arc
		(start 381.498348 -119.875554)
		(mid 381.79375 -119.796423)
		(end 382.089152 -119.875554)
		(width 0.0889)
		(layer "B.Cu")
		(net "P3E_CPU0_PE1_PCH_R_RXP<11>")
	)
	(arc
		(start 379.517148 -119.875554)
		(mid 379.81255 -119.796423)
		(end 380.107952 -119.875554)
		(width 0.0889)
		(layer "B.Cu")
		(net "P3E_CPU0_PE1_PCH_R_RXP<11>")
	)
	(arc
		(start 377.83135 -119.796306)
		(mid 377.984295 -119.81639)
		(end 378.126752 -119.875554)
		(width 0.0889)
		(layer "B.Cu")
		(net "P3E_CPU0_PE1_PCH_R_RXP<11>")
	)
	(arc
		(start 382.089152 -119.875554)
		(mid 382.288525 -120.064082)
		(end 382.381252 -120.32234)
		(width 0.0889)
		(layer "B.Cu")
		(net "P3E_CPU0_PE1_PCH_R_RXP<11>")
	)
	(arc
		(start 380.507748 -119.875554)
		(mid 380.80315 -119.796423)
		(end 381.098552 -119.875554)
		(width 0.0889)
		(layer "B.Cu")
		(net "P3E_CPU0_PE1_PCH_R_RXP<11>")
	)
	(arc
		(start 378.526548 -119.875554)
		(mid 378.82195 -119.796423)
		(end 379.117352 -119.875554)
		(width 0.0889)
		(layer "B.Cu")
		(net "P3E_CPU0_PE1_PCH_R_RXP<11>")
	)
	(segment
		(start 381.29845 -120.15724)
		(end 381.4064 -120.207278)
		(width 0.1143)
		(layer "F.Cu")
		(net "P3E_CPU0_PE1_PCH_R_RXN<11>")
	)
	(segment
		(start 381.4064 -120.207278)
		(end 381.79375 -120.387364)
		(width 0.1143)
		(layer "F.Cu")
		(net "P3E_CPU0_PE1_PCH_R_RXN<11>")
	)
	(via
		(at 381.79375 -120.387364)
		(size 0.508)
		(drill 0.254)
		(layers "F.Cu" "B.Cu")
		(net "P3E_CPU0_PE1_PCH_R_RXN<11>")
	)
	(via
		(at 367.383568 -119.902478)
		(size 0.508)
		(drill 0.254)
		(layers "F.Cu" "B.Cu")
		(net "P3E_CPU0_PE1_PCH_R_RXN<11>")
	)
	(segment
		(start 377.55195 -119.986806)
		(end 377.83135 -119.986806)
		(width 0.0889)
		(layer "B.Cu")
		(net "P3E_CPU0_PE1_PCH_R_RXN<11>")
	)
	(segment
		(start 374.412002 -120.725946)
		(end 374.500902 -120.637046)
		(width 0.0889)
		(layer "B.Cu")
		(net "P3E_CPU0_PE1_PCH_R_RXN<11>")
	)
	(segment
		(start 374.043702 -120.637046)
		(end 374.132602 -120.725946)
		(width 0.0889)
		(layer "B.Cu")
		(net "P3E_CPU0_PE1_PCH_R_RXN<11>")
	)
	(segment
		(start 374.869202 -120.725946)
		(end 375.148602 -120.725946)
		(width 0.0889)
		(layer "B.Cu")
		(net "P3E_CPU0_PE1_PCH_R_RXN<11>")
	)
	(segment
		(start 375.237502 -120.637046)
		(end 375.516902 -120.637046)
		(width 0.0889)
		(layer "B.Cu")
		(net "P3E_CPU0_PE1_PCH_R_RXN<11>")
	)
	(segment
		(start 374.132602 -120.725946)
		(end 374.412002 -120.725946)
		(width 0.0889)
		(layer "B.Cu")
		(net "P3E_CPU0_PE1_PCH_R_RXN<11>")
	)
	(segment
		(start 364.922054 -120.358408)
		(end 365.009176 -120.342152)
		(width 0.1143)
		(layer "B.Cu")
		(net "P3E_CPU0_PE1_PCH_R_RXN<11>")
	)
	(segment
		(start 363.153706 -122.071892)
		(end 363.563408 -122.071892)
		(width 0.1143)
		(layer "B.Cu")
		(net "P3E_CPU0_PE1_PCH_R_RXN<11>")
	)
	(segment
		(start 381.827786 -120.4214)
		(end 381.79375 -120.387364)
		(width 0.0889)
		(layer "B.Cu")
		(net "P3E_CPU0_PE1_PCH_R_RXN<11>")
	)
	(segment
		(start 377.46305 -120.075706)
		(end 377.55195 -119.986806)
		(width 0.0889)
		(layer "B.Cu")
		(net "P3E_CPU0_PE1_PCH_R_RXN<11>")
	)
	(segment
		(start 374.780302 -120.637046)
		(end 374.869202 -120.725946)
		(width 0.0889)
		(layer "B.Cu")
		(net "P3E_CPU0_PE1_PCH_R_RXN<11>")
	)
	(segment
		(start 363.878114 -121.757186)
		(end 363.878114 -121.096278)
		(width 0.1143)
		(layer "B.Cu")
		(net "P3E_CPU0_PE1_PCH_R_RXN<11>")
	)
	(segment
		(start 367.718086 -119.840502)
		(end 371.542056 -120.662446)
		(width 0.1143)
		(layer "B.Cu")
		(net "P3E_CPU0_PE1_PCH_R_RXN<11>")
	)
	(segment
		(start 374.500902 -120.637046)
		(end 374.780302 -120.637046)
		(width 0.0889)
		(layer "B.Cu")
		(net "P3E_CPU0_PE1_PCH_R_RXN<11>")
	)
	(segment
		(start 377.09475 -119.986806)
		(end 377.18365 -120.075706)
		(width 0.0889)
		(layer "B.Cu")
		(net "P3E_CPU0_PE1_PCH_R_RXN<11>")
	)
	(segment
		(start 376.20321 -119.950738)
		(end 376.629676 -119.950738)
		(width 0.0889)
		(layer "B.Cu")
		(net "P3E_CPU0_PE1_PCH_R_RXN<11>")
	)
	(segment
		(start 373.102886 -120.662446)
		(end 373.128286 -120.637046)
		(width 0.0889)
		(layer "B.Cu")
		(net "P3E_CPU0_PE1_PCH_R_RXN<11>")
	)
	(segment
		(start 382.189736 -120.329452)
		(end 382.097788 -120.4214)
		(width 0.0889)
		(layer "B.Cu")
		(net "P3E_CPU0_PE1_PCH_R_RXN<11>")
	)
	(segment
		(start 363.878114 -121.096278)
		(end 364.922054 -120.358408)
		(width 0.1143)
		(layer "B.Cu")
		(net "P3E_CPU0_PE1_PCH_R_RXN<11>")
	)
	(segment
		(start 376.629676 -119.950738)
		(end 376.665744 -119.986806)
		(width 0.0889)
		(layer "B.Cu")
		(net "P3E_CPU0_PE1_PCH_R_RXN<11>")
	)
	(segment
		(start 375.148602 -120.725946)
		(end 375.237502 -120.637046)
		(width 0.0889)
		(layer "B.Cu")
		(net "P3E_CPU0_PE1_PCH_R_RXN<11>")
	)
	(segment
		(start 377.18365 -120.075706)
		(end 377.46305 -120.075706)
		(width 0.0889)
		(layer "B.Cu")
		(net "P3E_CPU0_PE1_PCH_R_RXN<11>")
	)
	(segment
		(start 373.128286 -120.637046)
		(end 374.043702 -120.637046)
		(width 0.0889)
		(layer "B.Cu")
		(net "P3E_CPU0_PE1_PCH_R_RXN<11>")
	)
	(segment
		(start 371.542056 -120.662446)
		(end 373.080788 -120.662446)
		(width 0.1143)
		(layer "B.Cu")
		(net "P3E_CPU0_PE1_PCH_R_RXN<11>")
	)
	(segment
		(start 362.715556 -122.510042)
		(end 363.153706 -122.071892)
		(width 0.1143)
		(layer "B.Cu")
		(net "P3E_CPU0_PE1_PCH_R_RXN<11>")
	)
	(segment
		(start 367.383568 -119.902478)
		(end 367.718086 -119.840502)
		(width 0.1143)
		(layer "B.Cu")
		(net "P3E_CPU0_PE1_PCH_R_RXN<11>")
	)
	(segment
		(start 375.516902 -120.637046)
		(end 376.20321 -119.950738)
		(width 0.0889)
		(layer "B.Cu")
		(net "P3E_CPU0_PE1_PCH_R_RXN<11>")
	)
	(segment
		(start 373.080788 -120.662446)
		(end 373.102886 -120.662446)
		(width 0.0889)
		(layer "B.Cu")
		(net "P3E_CPU0_PE1_PCH_R_RXN<11>")
	)
	(segment
		(start 365.009176 -120.342152)
		(end 367.383568 -119.902478)
		(width 0.1143)
		(layer "B.Cu")
		(net "P3E_CPU0_PE1_PCH_R_RXN<11>")
	)
	(segment
		(start 376.665744 -119.986806)
		(end 377.09475 -119.986806)
		(width 0.0889)
		(layer "B.Cu")
		(net "P3E_CPU0_PE1_PCH_R_RXN<11>")
	)
	(segment
		(start 363.563408 -122.071892)
		(end 363.878114 -121.757186)
		(width 0.1143)
		(layer "B.Cu")
		(net "P3E_CPU0_PE1_PCH_R_RXN<11>")
	)
	(segment
		(start 382.097788 -120.4214)
		(end 381.827786 -120.4214)
		(width 0.0889)
		(layer "B.Cu")
		(net "P3E_CPU0_PE1_PCH_R_RXN<11>")
	)
	(arc
		(start 379.612652 -120.040654)
		(mid 379.81255 -119.987155)
		(end 380.012448 -120.040654)
		(width 0.0889)
		(layer "B.Cu")
		(net "P3E_CPU0_PE1_PCH_R_RXN<11>")
	)
	(arc
		(start 377.83135 -119.986806)
		(mid 377.934863 -120.000502)
		(end 378.031248 -120.040654)
		(width 0.0889)
		(layer "B.Cu")
		(net "P3E_CPU0_PE1_PCH_R_RXN<11>")
	)
	(arc
		(start 381.003048 -120.040654)
		(mid 381.29845 -120.119785)
		(end 381.593852 -120.040654)
		(width 0.0889)
		(layer "B.Cu")
		(net "P3E_CPU0_PE1_PCH_R_RXN<11>")
	)
	(arc
		(start 379.021848 -120.040654)
		(mid 379.31725 -120.119785)
		(end 379.612652 -120.040654)
		(width 0.0889)
		(layer "B.Cu")
		(net "P3E_CPU0_PE1_PCH_R_RXN<11>")
	)
	(arc
		(start 380.012448 -120.040654)
		(mid 380.30785 -120.119785)
		(end 380.603252 -120.040654)
		(width 0.0889)
		(layer "B.Cu")
		(net "P3E_CPU0_PE1_PCH_R_RXN<11>")
	)
	(arc
		(start 381.593852 -120.040654)
		(mid 381.79375 -119.987155)
		(end 381.993648 -120.040654)
		(width 0.0889)
		(layer "B.Cu")
		(net "P3E_CPU0_PE1_PCH_R_RXN<11>")
	)
	(arc
		(start 381.993648 -120.040654)
		(mid 382.124844 -120.162545)
		(end 382.189736 -120.329452)
		(width 0.0889)
		(layer "B.Cu")
		(net "P3E_CPU0_PE1_PCH_R_RXN<11>")
	)
	(arc
		(start 380.603252 -120.040654)
		(mid 380.80315 -119.987155)
		(end 381.003048 -120.040654)
		(width 0.0889)
		(layer "B.Cu")
		(net "P3E_CPU0_PE1_PCH_R_RXN<11>")
	)
	(arc
		(start 378.031248 -120.040654)
		(mid 378.32665 -120.119785)
		(end 378.622052 -120.040654)
		(width 0.0889)
		(layer "B.Cu")
		(net "P3E_CPU0_PE1_PCH_R_RXN<11>")
	)
	(arc
		(start 378.622052 -120.040654)
		(mid 378.82195 -119.987155)
		(end 379.021848 -120.040654)
		(width 0.0889)
		(layer "B.Cu")
		(net "P3E_CPU0_PE1_PCH_R_RXN<11>")
	)
	(segment
		(start 380.30785 -123.59132)
		(end 380.80315 -123.821444)
		(width 0.1143)
		(layer "F.Cu")
		(net "P3E_CPU0_PE1_PCH_R_RXP<10>")
	)
	(via
		(at 374.519952 -125.31598)
		(size 0.508)
		(drill 0.254)
		(layers "F.Cu" "B.Cu")
		(net "P3E_CPU0_PE1_PCH_R_RXP<10>")
	)
	(via
		(at 380.80315 -123.821444)
		(size 0.508)
		(drill 0.254)
		(layers "F.Cu" "B.Cu")
		(net "P3E_CPU0_PE1_PCH_R_RXP<10>")
	)
	(segment
		(start 363.109764 -125.119892)
		(end 362.671614 -125.558042)
		(width 0.1143)
		(layer "B.Cu")
		(net "P3E_CPU0_PE1_PCH_R_RXP<10>")
	)
	(segment
		(start 363.834934 -125.864874)
		(end 363.834934 -125.319028)
		(width 0.1143)
		(layer "B.Cu")
		(net "P3E_CPU0_PE1_PCH_R_RXP<10>")
	)
	(segment
		(start 380.63424 -123.528328)
		(end 380.80315 -123.821444)
		(width 0.0889)
		(layer "B.Cu")
		(net "P3E_CPU0_PE1_PCH_R_RXP<10>")
	)
	(segment
		(start 374.519952 -125.31598)
		(end 378.531882 -125.31598)
		(width 0.1143)
		(layer "B.Cu")
		(net "P3E_CPU0_PE1_PCH_R_RXP<10>")
	)
	(segment
		(start 378.55398 -125.31598)
		(end 378.57938 -125.29058)
		(width 0.0889)
		(layer "B.Cu")
		(net "P3E_CPU0_PE1_PCH_R_RXP<10>")
	)
	(segment
		(start 364.88116 -126.9111)
		(end 363.834934 -125.864874)
		(width 0.1143)
		(layer "B.Cu")
		(net "P3E_CPU0_PE1_PCH_R_RXP<10>")
	)
	(segment
		(start 372.832122 -125.31598)
		(end 371.91823 -126.229872)
		(width 0.1143)
		(layer "B.Cu")
		(net "P3E_CPU0_PE1_PCH_R_RXP<10>")
	)
	(segment
		(start 371.91823 -126.229872)
		(end 371.06606 -126.229872)
		(width 0.1143)
		(layer "B.Cu")
		(net "P3E_CPU0_PE1_PCH_R_RXP<10>")
	)
	(segment
		(start 363.834934 -125.319028)
		(end 363.635798 -125.119892)
		(width 0.1143)
		(layer "B.Cu")
		(net "P3E_CPU0_PE1_PCH_R_RXP<10>")
	)
	(segment
		(start 380.5555 -123.507246)
		(end 380.63424 -123.528328)
		(width 0.0889)
		(layer "B.Cu")
		(net "P3E_CPU0_PE1_PCH_R_RXP<10>")
	)
	(segment
		(start 378.531882 -125.31598)
		(end 378.55398 -125.31598)
		(width 0.0889)
		(layer "B.Cu")
		(net "P3E_CPU0_PE1_PCH_R_RXP<10>")
	)
	(segment
		(start 374.519952 -125.31598)
		(end 372.832122 -125.31598)
		(width 0.1143)
		(layer "B.Cu")
		(net "P3E_CPU0_PE1_PCH_R_RXP<10>")
	)
	(segment
		(start 378.57938 -125.29058)
		(end 380.15926 -125.29058)
		(width 0.0889)
		(layer "B.Cu")
		(net "P3E_CPU0_PE1_PCH_R_RXP<10>")
	)
	(segment
		(start 380.15926 -125.29058)
		(end 380.4031 -125.04674)
		(width 0.0889)
		(layer "B.Cu")
		(net "P3E_CPU0_PE1_PCH_R_RXP<10>")
	)
	(segment
		(start 380.4031 -125.04674)
		(end 380.4031 -123.810268)
		(width 0.0889)
		(layer "B.Cu")
		(net "P3E_CPU0_PE1_PCH_R_RXP<10>")
	)
	(segment
		(start 363.635798 -125.119892)
		(end 363.109764 -125.119892)
		(width 0.1143)
		(layer "B.Cu")
		(net "P3E_CPU0_PE1_PCH_R_RXP<10>")
	)
	(segment
		(start 371.06606 -126.229872)
		(end 370.384832 -126.9111)
		(width 0.1143)
		(layer "B.Cu")
		(net "P3E_CPU0_PE1_PCH_R_RXP<10>")
	)
	(segment
		(start 370.384832 -126.9111)
		(end 364.88116 -126.9111)
		(width 0.1143)
		(layer "B.Cu")
		(net "P3E_CPU0_PE1_PCH_R_RXP<10>")
	)
	(arc
		(start 380.4031 -123.810268)
		(mid 380.445633 -123.641831)
		(end 380.5555 -123.507246)
		(width 0.0889)
		(layer "B.Cu")
		(net "P3E_CPU0_PE1_PCH_R_RXP<10>")
	)
	(segment
		(start 379.81255 -122.7328)
		(end 380.30785 -122.962924)
		(width 0.1143)
		(layer "F.Cu")
		(net "P3E_CPU0_PE1_PCH_R_RXN<10>")
	)
	(via
		(at 380.30785 -122.962924)
		(size 0.508)
		(drill 0.254)
		(layers "F.Cu" "B.Cu")
		(net "P3E_CPU0_PE1_PCH_R_RXN<10>")
	)
	(via
		(at 376.9868 -125.07468)
		(size 0.508)
		(drill 0.254)
		(layers "F.Cu" "B.Cu")
		(net "P3E_CPU0_PE1_PCH_R_RXN<10>")
	)
	(segment
		(start 362.671614 -124.440442)
		(end 363.109764 -124.878592)
		(width 0.1143)
		(layer "B.Cu")
		(net "P3E_CPU0_PE1_PCH_R_RXN<10>")
	)
	(segment
		(start 370.965984 -125.988572)
		(end 371.818154 -125.988572)
		(width 0.1143)
		(layer "B.Cu")
		(net "P3E_CPU0_PE1_PCH_R_RXN<10>")
	)
	(segment
		(start 363.109764 -124.878592)
		(end 363.735874 -124.878592)
		(width 0.1143)
		(layer "B.Cu")
		(net "P3E_CPU0_PE1_PCH_R_RXN<10>")
	)
	(segment
		(start 371.818154 -125.988572)
		(end 372.732046 -125.07468)
		(width 0.1143)
		(layer "B.Cu")
		(net "P3E_CPU0_PE1_PCH_R_RXN<10>")
	)
	(segment
		(start 368.037872 -126.5555)
		(end 368.152172 -126.6698)
		(width 0.1143)
		(layer "B.Cu")
		(net "P3E_CPU0_PE1_PCH_R_RXN<10>")
	)
	(segment
		(start 380.2126 -124.967746)
		(end 380.2126 -124.701046)
		(width 0.0889)
		(layer "B.Cu")
		(net "P3E_CPU0_PE1_PCH_R_RXN<10>")
	)
	(segment
		(start 380.1237 -124.345446)
		(end 380.2126 -124.256546)
		(width 0.0889)
		(layer "B.Cu")
		(net "P3E_CPU0_PE1_PCH_R_RXN<10>")
	)
	(segment
		(start 364.076234 -125.764798)
		(end 364.981236 -126.6698)
		(width 0.1143)
		(layer "B.Cu")
		(net "P3E_CPU0_PE1_PCH_R_RXN<10>")
	)
	(segment
		(start 378.55398 -125.07468)
		(end 378.57938 -125.10008)
		(width 0.0889)
		(layer "B.Cu")
		(net "P3E_CPU0_PE1_PCH_R_RXN<10>")
	)
	(segment
		(start 364.076234 -125.218952)
		(end 364.076234 -125.764798)
		(width 0.1143)
		(layer "B.Cu")
		(net "P3E_CPU0_PE1_PCH_R_RXN<10>")
	)
	(segment
		(start 370.284756 -126.6698)
		(end 370.965984 -125.988572)
		(width 0.1143)
		(layer "B.Cu")
		(net "P3E_CPU0_PE1_PCH_R_RXN<10>")
	)
	(segment
		(start 380.2126 -124.701046)
		(end 380.1237 -124.612146)
		(width 0.0889)
		(layer "B.Cu")
		(net "P3E_CPU0_PE1_PCH_R_RXN<10>")
	)
	(segment
		(start 380.080266 -125.10008)
		(end 380.2126 -124.967746)
		(width 0.0889)
		(layer "B.Cu")
		(net "P3E_CPU0_PE1_PCH_R_RXN<10>")
	)
	(segment
		(start 380.1237 -124.612146)
		(end 380.1237 -124.345446)
		(width 0.0889)
		(layer "B.Cu")
		(net "P3E_CPU0_PE1_PCH_R_RXN<10>")
	)
	(segment
		(start 368.152172 -126.6698)
		(end 370.284756 -126.6698)
		(width 0.1143)
		(layer "B.Cu")
		(net "P3E_CPU0_PE1_PCH_R_RXN<10>")
	)
	(segment
		(start 378.531882 -125.07468)
		(end 378.55398 -125.07468)
		(width 0.0889)
		(layer "B.Cu")
		(net "P3E_CPU0_PE1_PCH_R_RXN<10>")
	)
	(segment
		(start 380.2126 -124.256546)
		(end 380.2126 -123.807728)
		(width 0.0889)
		(layer "B.Cu")
		(net "P3E_CPU0_PE1_PCH_R_RXN<10>")
	)
	(segment
		(start 367.694972 -126.5555)
		(end 368.037872 -126.5555)
		(width 0.1143)
		(layer "B.Cu")
		(net "P3E_CPU0_PE1_PCH_R_RXN<10>")
	)
	(segment
		(start 363.735874 -124.878592)
		(end 364.076234 -125.218952)
		(width 0.1143)
		(layer "B.Cu")
		(net "P3E_CPU0_PE1_PCH_R_RXN<10>")
	)
	(segment
		(start 380.47676 -123.25604)
		(end 380.30785 -122.962924)
		(width 0.0889)
		(layer "B.Cu")
		(net "P3E_CPU0_PE1_PCH_R_RXN<10>")
	)
	(segment
		(start 380.45263 -123.345448)
		(end 380.47676 -123.25604)
		(width 0.0889)
		(layer "B.Cu")
		(net "P3E_CPU0_PE1_PCH_R_RXN<10>")
	)
	(segment
		(start 364.981236 -126.6698)
		(end 367.580672 -126.6698)
		(width 0.1143)
		(layer "B.Cu")
		(net "P3E_CPU0_PE1_PCH_R_RXN<10>")
	)
	(segment
		(start 372.732046 -125.07468)
		(end 376.9868 -125.07468)
		(width 0.1143)
		(layer "B.Cu")
		(net "P3E_CPU0_PE1_PCH_R_RXN<10>")
	)
	(segment
		(start 376.9868 -125.07468)
		(end 378.531882 -125.07468)
		(width 0.1143)
		(layer "B.Cu")
		(net "P3E_CPU0_PE1_PCH_R_RXN<10>")
	)
	(segment
		(start 378.57938 -125.10008)
		(end 380.080266 -125.10008)
		(width 0.0889)
		(layer "B.Cu")
		(net "P3E_CPU0_PE1_PCH_R_RXN<10>")
	)
	(segment
		(start 367.580672 -126.6698)
		(end 367.694972 -126.5555)
		(width 0.1143)
		(layer "B.Cu")
		(net "P3E_CPU0_PE1_PCH_R_RXN<10>")
	)
	(arc
		(start 380.2126 -123.799854)
		(mid 380.280629 -123.545189)
		(end 380.45263 -123.345448)
		(width 0.0889)
		(layer "B.Cu")
		(net "P3E_CPU0_PE1_PCH_R_RXN<10>")
	)
	(arc
		(start 380.2126 -123.807728)
		(mid 380.212588 -123.803791)
		(end 380.2126 -123.799854)
		(width 0.0889)
		(layer "B.Cu")
		(net "P3E_CPU0_PE1_PCH_R_RXN<10>")
	)
	(segment
		(start 417.0045 -64.135)
		(end 416.3822 -64.135)
		(width 0.10795)
		(layer "F.Cu")
		(net "IRQ_SPI_TPM_N_R")
	)
	(segment
		(start 417.4998 -61.6712)
		(end 417.0045 -62.1665)
		(width 0.10795)
		(layer "F.Cu")
		(net "IRQ_SPI_TPM_N_R")
	)
	(segment
		(start 417.0045 -62.1665)
		(end 417.0045 -64.135)
		(width 0.10795)
		(layer "F.Cu")
		(net "IRQ_SPI_TPM_N_R")
	)
	(segment
		(start 416.3822 -64.135)
		(end 416.277298 -64.030098)
		(width 0.10795)
		(layer "F.Cu")
		(net "IRQ_SPI_TPM_N_R")
	)
	(segment
		(start 416.277298 -64.030098)
		(end 414.556448 -64.030098)
		(width 0.10795)
		(layer "F.Cu")
		(net "IRQ_SPI_TPM_N_R")
	)
	(via
		(at 417.4998 -61.6712)
		(size 0.762)
		(drill 0.381)
		(layers "F.Cu" "B.Cu")
		(net "IRQ_SPI_TPM_N_R")
	)
	(segment
		(start 402.492464 -112.355122)
		(end 403.243542 -113.1062)
		(width 0.0889)
		(layer "F.Cu")
		(net "IRQ_FORCE_NM_THROTTLE_N")
	)
	(segment
		(start 417.180522 -87.599266)
		(end 416.870642 -87.909146)
		(width 0.10795)
		(layer "F.Cu")
		(net "IRQ_FORCE_NM_THROTTLE_N")
	)
	(segment
		(start 417.9951 -87.6935)
		(end 417.557204 -87.6935)
		(width 0.10795)
		(layer "F.Cu")
		(net "IRQ_FORCE_NM_THROTTLE_N")
	)
	(segment
		(start 400.880072 -112.355122)
		(end 402.492464 -112.355122)
		(width 0.0889)
		(layer "F.Cu")
		(net "IRQ_FORCE_NM_THROTTLE_N")
	)
	(segment
		(start 392.69035 -100.41128)
		(end 393.18565 -100.181156)
		(width 0.10795)
		(layer "F.Cu")
		(net "IRQ_FORCE_NM_THROTTLE_N")
	)
	(segment
		(start 417.46297 -87.599266)
		(end 417.180522 -87.599266)
		(width 0.10795)
		(layer "F.Cu")
		(net "IRQ_FORCE_NM_THROTTLE_N")
	)
	(segment
		(start 417.557204 -87.6935)
		(end 417.46297 -87.599266)
		(width 0.10795)
		(layer "F.Cu")
		(net "IRQ_FORCE_NM_THROTTLE_N")
	)
	(segment
		(start 416.870642 -87.909146)
		(end 416.31997 -87.909146)
		(width 0.10795)
		(layer "F.Cu")
		(net "IRQ_FORCE_NM_THROTTLE_N")
	)
	(via
		(at 417.180522 -87.599266)
		(size 0.508)
		(drill 0.254)
		(layers "F.Cu" "B.Cu")
		(net "IRQ_FORCE_NM_THROTTLE_N")
	)
	(via
		(at 403.243542 -113.1062)
		(size 0.508)
		(drill 0.254)
		(layers "F.Cu" "B.Cu")
		(net "IRQ_FORCE_NM_THROTTLE_N")
	)
	(via
		(at 393.18565 -100.181156)
		(size 0.508)
		(drill 0.254)
		(layers "F.Cu" "B.Cu")
		(net "IRQ_FORCE_NM_THROTTLE_N")
	)
	(via
		(at 403.491954 -86.71814)
		(size 0.508)
		(drill 0.254)
		(layers "F.Cu" "B.Cu")
		(net "IRQ_FORCE_NM_THROTTLE_N")
	)
	(via
		(at 422.75506 -51.095402)
		(size 0.508)
		(drill 0.254)
		(layers "F.Cu" "B.Cu")
		(net "IRQ_FORCE_NM_THROTTLE_N")
	)
	(via
		(at 405.22906 -38.551612)
		(size 0.4572)
		(drill 0.2032)
		(layers "F.Cu" "B.Cu")
		(net "IRQ_FORCE_NM_THROTTLE_N")
	)
	(segment
		(start 405.60371 -37.940234)
		(end 405.60371 -38.176962)
		(width 0.10795)
		(layer "B.Cu")
		(net "IRQ_FORCE_NM_THROTTLE_N")
	)
	(segment
		(start 405.60371 -38.176962)
		(end 405.22906 -38.551612)
		(width 0.10795)
		(layer "B.Cu")
		(net "IRQ_FORCE_NM_THROTTLE_N")
	)
	(segment
		(start 395.705584 -101.76256)
		(end 395.705584 -102.110794)
		(width 0.089408)
		(layer "In2.Cu")
		(net "IRQ_FORCE_NM_THROTTLE_N")
	)
	(segment
		(start 395.1224 -100.7872)
		(end 395.1224 -101.179376)
		(width 0.089408)
		(layer "In2.Cu")
		(net "IRQ_FORCE_NM_THROTTLE_N")
	)
	(segment
		(start 396.194788 -106.29646)
		(end 396.63243 -106.734102)
		(width 0.0889)
		(layer "In2.Cu")
		(net "IRQ_FORCE_NM_THROTTLE_N")
	)
	(segment
		(start 403.243542 -112.769142)
		(end 403.243542 -113.1062)
		(width 0.0889)
		(layer "In2.Cu")
		(net "IRQ_FORCE_NM_THROTTLE_N")
	)
	(segment
		(start 394.5128 -99.7712)
		(end 394.6779 -99.9363)
		(width 0.089408)
		(layer "In2.Cu")
		(net "IRQ_FORCE_NM_THROTTLE_N")
	)
	(segment
		(start 398.871186 -111.363506)
		(end 399.057114 -111.549434)
		(width 0.0889)
		(layer "In2.Cu")
		(net "IRQ_FORCE_NM_THROTTLE_N")
	)
	(segment
		(start 396.5575 -108.75518)
		(end 396.5575 -108.787946)
		(width 0.0889)
		(layer "In2.Cu")
		(net "IRQ_FORCE_NM_THROTTLE_N")
	)
	(segment
		(start 395.1224 -101.179376)
		(end 395.705584 -101.76256)
		(width 0.089408)
		(layer "In2.Cu")
		(net "IRQ_FORCE_NM_THROTTLE_N")
	)
	(segment
		(start 396.555976 -108.601256)
		(end 396.555976 -108.753656)
		(width 0.0889)
		(layer "In2.Cu")
		(net "IRQ_FORCE_NM_THROTTLE_N")
	)
	(segment
		(start 397.776446 -111.363506)
		(end 398.871186 -111.363506)
		(width 0.0889)
		(layer "In2.Cu")
		(net "IRQ_FORCE_NM_THROTTLE_N")
	)
	(segment
		(start 402.023834 -111.549434)
		(end 403.243542 -112.769142)
		(width 0.0889)
		(layer "In2.Cu")
		(net "IRQ_FORCE_NM_THROTTLE_N")
	)
	(segment
		(start 397.0528 -109.6137)
		(end 397.0528 -110.63986)
		(width 0.0889)
		(layer "In2.Cu")
		(net "IRQ_FORCE_NM_THROTTLE_N")
	)
	(segment
		(start 396.555976 -108.753656)
		(end 396.5575 -108.75518)
		(width 0.0889)
		(layer "In2.Cu")
		(net "IRQ_FORCE_NM_THROTTLE_N")
	)
	(segment
		(start 396.63243 -106.734102)
		(end 396.63243 -107.36453)
		(width 0.0889)
		(layer "In2.Cu")
		(net "IRQ_FORCE_NM_THROTTLE_N")
	)
	(segment
		(start 395.758924 -105.541064)
		(end 396.194788 -105.976928)
		(width 0.0889)
		(layer "In2.Cu")
		(net "IRQ_FORCE_NM_THROTTLE_N")
	)
	(segment
		(start 395.758924 -104.182164)
		(end 395.758924 -105.541064)
		(width 0.0889)
		(layer "In2.Cu")
		(net "IRQ_FORCE_NM_THROTTLE_N")
	)
	(segment
		(start 396.194788 -105.976928)
		(end 396.194788 -106.29646)
		(width 0.0889)
		(layer "In2.Cu")
		(net "IRQ_FORCE_NM_THROTTLE_N")
	)
	(segment
		(start 397.0528 -110.63986)
		(end 397.776446 -111.363506)
		(width 0.0889)
		(layer "In2.Cu")
		(net "IRQ_FORCE_NM_THROTTLE_N")
	)
	(segment
		(start 396.63243 -107.36453)
		(end 396.254224 -107.742736)
		(width 0.0889)
		(layer "In2.Cu")
		(net "IRQ_FORCE_NM_THROTTLE_N")
	)
	(segment
		(start 396.32001 -108.36783)
		(end 396.32255 -108.36783)
		(width 0.0889)
		(layer "In2.Cu")
		(net "IRQ_FORCE_NM_THROTTLE_N")
	)
	(segment
		(start 399.057114 -111.549434)
		(end 402.023834 -111.549434)
		(width 0.0889)
		(layer "In2.Cu")
		(net "IRQ_FORCE_NM_THROTTLE_N")
	)
	(segment
		(start 393.65682 -99.7712)
		(end 394.5128 -99.7712)
		(width 0.089408)
		(layer "In2.Cu")
		(net "IRQ_FORCE_NM_THROTTLE_N")
	)
	(segment
		(start 393.246864 -100.181156)
		(end 393.65682 -99.7712)
		(width 0.089408)
		(layer "In2.Cu")
		(net "IRQ_FORCE_NM_THROTTLE_N")
	)
	(segment
		(start 393.18565 -100.181156)
		(end 393.246864 -100.181156)
		(width 0.089408)
		(layer "In2.Cu")
		(net "IRQ_FORCE_NM_THROTTLE_N")
	)
	(segment
		(start 394.6779 -100.3427)
		(end 395.1224 -100.7872)
		(width 0.089408)
		(layer "In2.Cu")
		(net "IRQ_FORCE_NM_THROTTLE_N")
	)
	(segment
		(start 396.254224 -107.742736)
		(end 396.254224 -108.302044)
		(width 0.0889)
		(layer "In2.Cu")
		(net "IRQ_FORCE_NM_THROTTLE_N")
	)
	(segment
		(start 395.705584 -102.110794)
		(end 396.02664 -102.43185)
		(width 0.089408)
		(layer "In2.Cu")
		(net "IRQ_FORCE_NM_THROTTLE_N")
	)
	(segment
		(start 396.32255 -108.36783)
		(end 396.555976 -108.601256)
		(width 0.0889)
		(layer "In2.Cu")
		(net "IRQ_FORCE_NM_THROTTLE_N")
	)
	(segment
		(start 395.648688 -103.915972)
		(end 395.758924 -104.182164)
		(width 0.0889)
		(layer "In2.Cu")
		(net "IRQ_FORCE_NM_THROTTLE_N")
	)
	(segment
		(start 394.6779 -99.9363)
		(end 394.6779 -100.3427)
		(width 0.089408)
		(layer "In2.Cu")
		(net "IRQ_FORCE_NM_THROTTLE_N")
	)
	(segment
		(start 396.254224 -108.302044)
		(end 396.32001 -108.36783)
		(width 0.0889)
		(layer "In2.Cu")
		(net "IRQ_FORCE_NM_THROTTLE_N")
	)
	(arc
		(start 396.852648 -109.278166)
		(mid 396.996452 -109.419849)
		(end 397.0528 -109.6137)
		(width 0.0889)
		(layer "In2.Cu")
		(net "IRQ_FORCE_NM_THROTTLE_N")
	)
	(arc
		(start 396.02664 -102.43185)
		(mid 396.087755 -102.802807)
		(end 395.862048 -103.103426)
		(width 0.0889)
		(layer "In2.Cu")
		(net "IRQ_FORCE_NM_THROTTLE_N")
	)
	(arc
		(start 396.5575 -108.787946)
		(mid 396.641781 -109.071163)
		(end 396.852648 -109.278166)
		(width 0.0889)
		(layer "In2.Cu")
		(net "IRQ_FORCE_NM_THROTTLE_N")
	)
	(arc
		(start 395.862048 -103.103426)
		(mid 395.585877 -103.465181)
		(end 395.648688 -103.915972)
		(width 0.0889)
		(layer "In2.Cu")
		(net "IRQ_FORCE_NM_THROTTLE_N")
	)
	(segment
		(start 404.61438 -86.889336)
		(end 403.66315 -86.889336)
		(width 0.089408)
		(layer "In4.Cu")
		(net "IRQ_FORCE_NM_THROTTLE_N")
	)
	(segment
		(start 416.451288 -88.3285)
		(end 416.160458 -88.3285)
		(width 0.089408)
		(layer "In4.Cu")
		(net "IRQ_FORCE_NM_THROTTLE_N")
	)
	(segment
		(start 406.56129 -88.836246)
		(end 404.61438 -86.889336)
		(width 0.089408)
		(layer "In4.Cu")
		(net "IRQ_FORCE_NM_THROTTLE_N")
	)
	(segment
		(start 403.66315 -86.889336)
		(end 403.491954 -86.71814)
		(width 0.089408)
		(layer "In4.Cu")
		(net "IRQ_FORCE_NM_THROTTLE_N")
	)
	(segment
		(start 416.160458 -88.3285)
		(end 415.811716 -88.677242)
		(width 0.089408)
		(layer "In4.Cu")
		(net "IRQ_FORCE_NM_THROTTLE_N")
	)
	(segment
		(start 417.180522 -87.599266)
		(end 416.451288 -88.3285)
		(width 0.089408)
		(layer "In4.Cu")
		(net "IRQ_FORCE_NM_THROTTLE_N")
	)
	(segment
		(start 411.324552 -88.836246)
		(end 406.56129 -88.836246)
		(width 0.089408)
		(layer "In4.Cu")
		(net "IRQ_FORCE_NM_THROTTLE_N")
	)
	(segment
		(start 411.483556 -88.677242)
		(end 411.324552 -88.836246)
		(width 0.089408)
		(layer "In4.Cu")
		(net "IRQ_FORCE_NM_THROTTLE_N")
	)
	(segment
		(start 415.811716 -88.677242)
		(end 411.483556 -88.677242)
		(width 0.089408)
		(layer "In4.Cu")
		(net "IRQ_FORCE_NM_THROTTLE_N")
	)
	(segment
		(start 412.040578 -62.481968)
		(end 412.5214 -62.96279)
		(width 0.089408)
		(layer "In9.Cu")
		(net "IRQ_FORCE_NM_THROTTLE_N")
	)
	(segment
		(start 412.520892 -63.437262)
		(end 412.520638 -63.437516)
		(width 0.089408)
		(layer "In9.Cu")
		(net "IRQ_FORCE_NM_THROTTLE_N")
	)
	(segment
		(start 411.439106 -68.796408)
		(end 411.439106 -69.696584)
		(width 0.089408)
		(layer "In9.Cu")
		(net "IRQ_FORCE_NM_THROTTLE_N")
	)
	(segment
		(start 399.77822 -90.431874)
		(end 399.77822 -91.752166)
		(width 0.089408)
		(layer "In9.Cu")
		(net "IRQ_FORCE_NM_THROTTLE_N")
	)
	(segment
		(start 412.520892 -63.279274)
		(end 412.520892 -63.437262)
		(width 0.089408)
		(layer "In9.Cu")
		(net "IRQ_FORCE_NM_THROTTLE_N")
	)
	(segment
		(start 398.159986 -93.3704)
		(end 397.34617 -93.3704)
		(width 0.089408)
		(layer "In9.Cu")
		(net "IRQ_FORCE_NM_THROTTLE_N")
	)
	(segment
		(start 412.5214 -62.96279)
		(end 412.5214 -63.120778)
		(width 0.089408)
		(layer "In9.Cu")
		(net "IRQ_FORCE_NM_THROTTLE_N")
	)
	(segment
		(start 397.34617 -93.3704)
		(end 395.072616 -95.643954)
		(width 0.089408)
		(layer "In9.Cu")
		(net "IRQ_FORCE_NM_THROTTLE_N")
	)
	(segment
		(start 412.030418 -68.139818)
		(end 412.030164 -68.140072)
		(width 0.089408)
		(layer "In9.Cu")
		(net "IRQ_FORCE_NM_THROTTLE_N")
	)
	(segment
		(start 412.88335 -56.79948)
		(end 412.635192 -57.047638)
		(width 0.089408)
		(layer "In9.Cu")
		(net "IRQ_FORCE_NM_THROTTLE_N")
	)
	(segment
		(start 420.213028 -51.999896)
		(end 419.073584 -53.13934)
		(width 0.089408)
		(layer "In9.Cu")
		(net "IRQ_FORCE_NM_THROTTLE_N")
	)
	(segment
		(start 409.980384 -70.440042)
		(end 405.383492 -75.036934)
		(width 0.089408)
		(layer "In9.Cu")
		(net "IRQ_FORCE_NM_THROTTLE_N")
	)
	(segment
		(start 405.623268 -84.586826)
		(end 403.491954 -86.71814)
		(width 0.089408)
		(layer "In9.Cu")
		(net "IRQ_FORCE_NM_THROTTLE_N")
	)
	(segment
		(start 412.040578 -68.11264)
		(end 412.030418 -68.1228)
		(width 0.089408)
		(layer "In9.Cu")
		(net "IRQ_FORCE_NM_THROTTLE_N")
	)
	(segment
		(start 403.491954 -86.71814)
		(end 399.77822 -90.431874)
		(width 0.089408)
		(layer "In9.Cu")
		(net "IRQ_FORCE_NM_THROTTLE_N")
	)
	(segment
		(start 405.623268 -78.79842)
		(end 405.623268 -84.586826)
		(width 0.089408)
		(layer "In9.Cu")
		(net "IRQ_FORCE_NM_THROTTLE_N")
	)
	(segment
		(start 414.315402 -56.678576)
		(end 414.194498 -56.79948)
		(width 0.089408)
		(layer "In9.Cu")
		(net "IRQ_FORCE_NM_THROTTLE_N")
	)
	(segment
		(start 422.75506 -51.322986)
		(end 422.07815 -51.999896)
		(width 0.089408)
		(layer "In9.Cu")
		(net "IRQ_FORCE_NM_THROTTLE_N")
	)
	(segment
		(start 395.56563 -98.855022)
		(end 395.26337 -99.157282)
		(width 0.089408)
		(layer "In9.Cu")
		(net "IRQ_FORCE_NM_THROTTLE_N")
	)
	(segment
		(start 395.56563 -98.07321)
		(end 395.56563 -98.855022)
		(width 0.089408)
		(layer "In9.Cu")
		(net "IRQ_FORCE_NM_THROTTLE_N")
	)
	(segment
		(start 414.194498 -56.79948)
		(end 412.88335 -56.79948)
		(width 0.089408)
		(layer "In9.Cu")
		(net "IRQ_FORCE_NM_THROTTLE_N")
	)
	(segment
		(start 416.3314 -54.380638)
		(end 416.3314 -55.106316)
		(width 0.089408)
		(layer "In9.Cu")
		(net "IRQ_FORCE_NM_THROTTLE_N")
	)
	(segment
		(start 412.030418 -68.1228)
		(end 412.030418 -68.139818)
		(width 0.089408)
		(layer "In9.Cu")
		(net "IRQ_FORCE_NM_THROTTLE_N")
	)
	(segment
		(start 395.072616 -95.643954)
		(end 395.072616 -96.277176)
		(width 0.089408)
		(layer "In9.Cu")
		(net "IRQ_FORCE_NM_THROTTLE_N")
	)
	(segment
		(start 411.890464 -58.466228)
		(end 411.890464 -60.012326)
		(width 0.089408)
		(layer "In9.Cu")
		(net "IRQ_FORCE_NM_THROTTLE_N")
	)
	(segment
		(start 412.521146 -63.27902)
		(end 412.520892 -63.279274)
		(width 0.089408)
		(layer "In9.Cu")
		(net "IRQ_FORCE_NM_THROTTLE_N")
	)
	(segment
		(start 411.890464 -60.012326)
		(end 412.040578 -60.16244)
		(width 0.089408)
		(layer "In9.Cu")
		(net "IRQ_FORCE_NM_THROTTLE_N")
	)
	(segment
		(start 394.76807 -96.581722)
		(end 394.76807 -96.91243)
		(width 0.089408)
		(layer "In9.Cu")
		(net "IRQ_FORCE_NM_THROTTLE_N")
	)
	(segment
		(start 395.26337 -99.157282)
		(end 395.26337 -99.37877)
		(width 0.089408)
		(layer "In9.Cu")
		(net "IRQ_FORCE_NM_THROTTLE_N")
	)
	(segment
		(start 399.77822 -91.752166)
		(end 398.159986 -93.3704)
		(width 0.089408)
		(layer "In9.Cu")
		(net "IRQ_FORCE_NM_THROTTLE_N")
	)
	(segment
		(start 412.520638 -66.26225)
		(end 412.494476 -66.288412)
		(width 0.089408)
		(layer "In9.Cu")
		(net "IRQ_FORCE_NM_THROTTLE_N")
	)
	(segment
		(start 393.436856 -99.92995)
		(end 393.18565 -100.181156)
		(width 0.089408)
		(layer "In9.Cu")
		(net "IRQ_FORCE_NM_THROTTLE_N")
	)
	(segment
		(start 395.26337 -97.77095)
		(end 395.56563 -98.07321)
		(width 0.089408)
		(layer "In9.Cu")
		(net "IRQ_FORCE_NM_THROTTLE_N")
	)
	(segment
		(start 395.072616 -96.277176)
		(end 394.76807 -96.581722)
		(width 0.089408)
		(layer "In9.Cu")
		(net "IRQ_FORCE_NM_THROTTLE_N")
	)
	(segment
		(start 410.695648 -70.440042)
		(end 409.980384 -70.440042)
		(width 0.089408)
		(layer "In9.Cu")
		(net "IRQ_FORCE_NM_THROTTLE_N")
	)
	(segment
		(start 416.3314 -55.106316)
		(end 414.75914 -56.678576)
		(width 0.089408)
		(layer "In9.Cu")
		(net "IRQ_FORCE_NM_THROTTLE_N")
	)
	(segment
		(start 405.383492 -75.036934)
		(end 405.383492 -78.558644)
		(width 0.089408)
		(layer "In9.Cu")
		(net "IRQ_FORCE_NM_THROTTLE_N")
	)
	(segment
		(start 422.07815 -51.999896)
		(end 420.213028 -51.999896)
		(width 0.089408)
		(layer "In9.Cu")
		(net "IRQ_FORCE_NM_THROTTLE_N")
	)
	(segment
		(start 412.5214 -63.120778)
		(end 412.521146 -63.121032)
		(width 0.089408)
		(layer "In9.Cu")
		(net "IRQ_FORCE_NM_THROTTLE_N")
	)
	(segment
		(start 414.75914 -56.678576)
		(end 414.315402 -56.678576)
		(width 0.089408)
		(layer "In9.Cu")
		(net "IRQ_FORCE_NM_THROTTLE_N")
	)
	(segment
		(start 412.494476 -66.288412)
		(end 412.494476 -66.292984)
		(width 0.089408)
		(layer "In9.Cu")
		(net "IRQ_FORCE_NM_THROTTLE_N")
	)
	(segment
		(start 393.75715 -99.92995)
		(end 393.436856 -99.92995)
		(width 0.089408)
		(layer "In9.Cu")
		(net "IRQ_FORCE_NM_THROTTLE_N")
	)
	(segment
		(start 412.040578 -60.16244)
		(end 412.040578 -62.481968)
		(width 0.089408)
		(layer "In9.Cu")
		(net "IRQ_FORCE_NM_THROTTLE_N")
	)
	(segment
		(start 412.521146 -63.121032)
		(end 412.521146 -63.27902)
		(width 0.089408)
		(layer "In9.Cu")
		(net "IRQ_FORCE_NM_THROTTLE_N")
	)
	(segment
		(start 412.635192 -57.7215)
		(end 411.890464 -58.466228)
		(width 0.089408)
		(layer "In9.Cu")
		(net "IRQ_FORCE_NM_THROTTLE_N")
	)
	(segment
		(start 412.520638 -63.437516)
		(end 412.520638 -66.26225)
		(width 0.089408)
		(layer "In9.Cu")
		(net "IRQ_FORCE_NM_THROTTLE_N")
	)
	(segment
		(start 412.635192 -57.047638)
		(end 412.635192 -57.7215)
		(width 0.089408)
		(layer "In9.Cu")
		(net "IRQ_FORCE_NM_THROTTLE_N")
	)
	(segment
		(start 412.494476 -66.292984)
		(end 412.040578 -66.746882)
		(width 0.089408)
		(layer "In9.Cu")
		(net "IRQ_FORCE_NM_THROTTLE_N")
	)
	(segment
		(start 394.86332 -99.77882)
		(end 393.90828 -99.77882)
		(width 0.089408)
		(layer "In9.Cu")
		(net "IRQ_FORCE_NM_THROTTLE_N")
	)
	(segment
		(start 411.439106 -69.696584)
		(end 410.695648 -70.440042)
		(width 0.089408)
		(layer "In9.Cu")
		(net "IRQ_FORCE_NM_THROTTLE_N")
	)
	(segment
		(start 395.26337 -99.37877)
		(end 394.86332 -99.77882)
		(width 0.089408)
		(layer "In9.Cu")
		(net "IRQ_FORCE_NM_THROTTLE_N")
	)
	(segment
		(start 419.073584 -53.13934)
		(end 417.572698 -53.13934)
		(width 0.089408)
		(layer "In9.Cu")
		(net "IRQ_FORCE_NM_THROTTLE_N")
	)
	(segment
		(start 412.030164 -68.140072)
		(end 412.030164 -68.20535)
		(width 0.089408)
		(layer "In9.Cu")
		(net "IRQ_FORCE_NM_THROTTLE_N")
	)
	(segment
		(start 412.040578 -66.746882)
		(end 412.040578 -68.11264)
		(width 0.089408)
		(layer "In9.Cu")
		(net "IRQ_FORCE_NM_THROTTLE_N")
	)
	(segment
		(start 394.76807 -96.91243)
		(end 395.26337 -97.40773)
		(width 0.089408)
		(layer "In9.Cu")
		(net "IRQ_FORCE_NM_THROTTLE_N")
	)
	(segment
		(start 412.030164 -68.20535)
		(end 411.439106 -68.796408)
		(width 0.089408)
		(layer "In9.Cu")
		(net "IRQ_FORCE_NM_THROTTLE_N")
	)
	(segment
		(start 395.26337 -97.40773)
		(end 395.26337 -97.77095)
		(width 0.089408)
		(layer "In9.Cu")
		(net "IRQ_FORCE_NM_THROTTLE_N")
	)
	(segment
		(start 422.75506 -51.095402)
		(end 422.75506 -51.322986)
		(width 0.089408)
		(layer "In9.Cu")
		(net "IRQ_FORCE_NM_THROTTLE_N")
	)
	(segment
		(start 405.383492 -78.558644)
		(end 405.623268 -78.79842)
		(width 0.089408)
		(layer "In9.Cu")
		(net "IRQ_FORCE_NM_THROTTLE_N")
	)
	(segment
		(start 393.90828 -99.77882)
		(end 393.75715 -99.92995)
		(width 0.089408)
		(layer "In9.Cu")
		(net "IRQ_FORCE_NM_THROTTLE_N")
	)
	(segment
		(start 417.572698 -53.13934)
		(end 416.3314 -54.380638)
		(width 0.089408)
		(layer "In9.Cu")
		(net "IRQ_FORCE_NM_THROTTLE_N")
	)
	(segment
		(start 422.733216 -51.073558)
		(end 422.75506 -51.095402)
		(width 0.089408)
		(layer "In11.Cu")
		(net "IRQ_FORCE_NM_THROTTLE_N")
	)
	(segment
		(start 419.78707 -46.395132)
		(end 419.78707 -47.174658)
		(width 0.089408)
		(layer "In11.Cu")
		(net "IRQ_FORCE_NM_THROTTLE_N")
	)
	(segment
		(start 420.07028 -47.457868)
		(end 420.07028 -47.458122)
		(width 0.089408)
		(layer "In11.Cu")
		(net "IRQ_FORCE_NM_THROTTLE_N")
	)
	(segment
		(start 410.381196 -44.46016)
		(end 410.986986 -44.46016)
		(width 0.089408)
		(layer "In11.Cu")
		(net "IRQ_FORCE_NM_THROTTLE_N")
	)
	(segment
		(start 408.022806 -44.121324)
		(end 408.615642 -44.71416)
		(width 0.089408)
		(layer "In11.Cu")
		(net "IRQ_FORCE_NM_THROTTLE_N")
	)
	(segment
		(start 418.695886 -45.303948)
		(end 419.78707 -46.395132)
		(width 0.089408)
		(layer "In11.Cu")
		(net "IRQ_FORCE_NM_THROTTLE_N")
	)
	(segment
		(start 405.669496 -40.881808)
		(end 407.815034 -43.027346)
		(width 0.089408)
		(layer "In11.Cu")
		(net "IRQ_FORCE_NM_THROTTLE_N")
	)
	(segment
		(start 404.920196 -40.43045)
		(end 405.371554 -40.881808)
		(width 0.089408)
		(layer "In11.Cu")
		(net "IRQ_FORCE_NM_THROTTLE_N")
	)
	(segment
		(start 416.08121 -44.560236)
		(end 416.824922 -45.303948)
		(width 0.089408)
		(layer "In11.Cu")
		(net "IRQ_FORCE_NM_THROTTLE_N")
	)
	(segment
		(start 414.386776 -44.560236)
		(end 416.08121 -44.560236)
		(width 0.089408)
		(layer "In11.Cu")
		(net "IRQ_FORCE_NM_THROTTLE_N")
	)
	(segment
		(start 419.78707 -47.174658)
		(end 420.07028 -47.457868)
		(width 0.089408)
		(layer "In11.Cu")
		(net "IRQ_FORCE_NM_THROTTLE_N")
	)
	(segment
		(start 410.127196 -44.71416)
		(end 410.381196 -44.46016)
		(width 0.089408)
		(layer "In11.Cu")
		(net "IRQ_FORCE_NM_THROTTLE_N")
	)
	(segment
		(start 421.59174 -49.835562)
		(end 422.733216 -50.977038)
		(width 0.089408)
		(layer "In11.Cu")
		(net "IRQ_FORCE_NM_THROTTLE_N")
	)
	(segment
		(start 410.986986 -44.46016)
		(end 411.315662 -44.788836)
		(width 0.089408)
		(layer "In11.Cu")
		(net "IRQ_FORCE_NM_THROTTLE_N")
	)
	(segment
		(start 407.815034 -43.027346)
		(end 407.815796 -43.027346)
		(width 0.089408)
		(layer "In11.Cu")
		(net "IRQ_FORCE_NM_THROTTLE_N")
	)
	(segment
		(start 404.920196 -38.860476)
		(end 404.920196 -40.43045)
		(width 0.089408)
		(layer "In11.Cu")
		(net "IRQ_FORCE_NM_THROTTLE_N")
	)
	(segment
		(start 421.59174 -48.979582)
		(end 421.59174 -49.835562)
		(width 0.089408)
		(layer "In11.Cu")
		(net "IRQ_FORCE_NM_THROTTLE_N")
	)
	(segment
		(start 412.389066 -44.979336)
		(end 413.967676 -44.979336)
		(width 0.089408)
		(layer "In11.Cu")
		(net "IRQ_FORCE_NM_THROTTLE_N")
	)
	(segment
		(start 408.615642 -44.71416)
		(end 410.127196 -44.71416)
		(width 0.089408)
		(layer "In11.Cu")
		(net "IRQ_FORCE_NM_THROTTLE_N")
	)
	(segment
		(start 405.22906 -38.551612)
		(end 404.920196 -38.860476)
		(width 0.089408)
		(layer "In11.Cu")
		(net "IRQ_FORCE_NM_THROTTLE_N")
	)
	(segment
		(start 422.733216 -50.977038)
		(end 422.733216 -51.073558)
		(width 0.089408)
		(layer "In11.Cu")
		(net "IRQ_FORCE_NM_THROTTLE_N")
	)
	(segment
		(start 413.967676 -44.979336)
		(end 414.386776 -44.560236)
		(width 0.089408)
		(layer "In11.Cu")
		(net "IRQ_FORCE_NM_THROTTLE_N")
	)
	(segment
		(start 411.315662 -44.788836)
		(end 412.198566 -44.788836)
		(width 0.089408)
		(layer "In11.Cu")
		(net "IRQ_FORCE_NM_THROTTLE_N")
	)
	(segment
		(start 412.198566 -44.788836)
		(end 412.389066 -44.979336)
		(width 0.089408)
		(layer "In11.Cu")
		(net "IRQ_FORCE_NM_THROTTLE_N")
	)
	(segment
		(start 405.371554 -40.881808)
		(end 405.669496 -40.881808)
		(width 0.089408)
		(layer "In11.Cu")
		(net "IRQ_FORCE_NM_THROTTLE_N")
	)
	(segment
		(start 407.815796 -43.027346)
		(end 408.022806 -43.234356)
		(width 0.089408)
		(layer "In11.Cu")
		(net "IRQ_FORCE_NM_THROTTLE_N")
	)
	(segment
		(start 416.824922 -45.303948)
		(end 418.695886 -45.303948)
		(width 0.089408)
		(layer "In11.Cu")
		(net "IRQ_FORCE_NM_THROTTLE_N")
	)
	(segment
		(start 408.022806 -43.234356)
		(end 408.022806 -44.121324)
		(width 0.089408)
		(layer "In11.Cu")
		(net "IRQ_FORCE_NM_THROTTLE_N")
	)
	(segment
		(start 420.07028 -47.458122)
		(end 421.59174 -48.979582)
		(width 0.089408)
		(layer "In11.Cu")
		(net "IRQ_FORCE_NM_THROTTLE_N")
	)
	(segment
		(start 491.2868 -138.4808)
		(end 488.696 -138.4808)
		(width 0.10795)
		(layer "F.Cu")
		(net "FM_POST_CARD_PRES_BMC_N")
	)
	(segment
		(start 488.696 -138.4808)
		(end 488.315 -138.8618)
		(width 0.10795)
		(layer "F.Cu")
		(net "FM_POST_CARD_PRES_BMC_N")
	)
	(segment
		(start 407.890218 -33.734756)
		(end 407.514552 -33.35909)
		(width 0.10795)
		(layer "F.Cu")
		(net "FM_POST_CARD_PRES_BMC_N")
	)
	(segment
		(start 407.514552 -33.35909)
		(end 406.77211 -33.35909)
		(width 0.10795)
		(layer "F.Cu")
		(net "FM_POST_CARD_PRES_BMC_N")
	)
	(segment
		(start 406.77211 -33.35909)
		(end 406.6286 -33.5026)
		(width 0.10795)
		(layer "F.Cu")
		(net "FM_POST_CARD_PRES_BMC_N")
	)
	(segment
		(start 492.6076 -137.9982)
		(end 491.7694 -137.9982)
		(width 0.10795)
		(layer "F.Cu")
		(net "FM_POST_CARD_PRES_BMC_N")
	)
	(segment
		(start 491.7694 -137.9982)
		(end 491.2868 -138.4808)
		(width 0.10795)
		(layer "F.Cu")
		(net "FM_POST_CARD_PRES_BMC_N")
	)
	(segment
		(start 492.7092 -138.0998)
		(end 492.6076 -137.9982)
		(width 0.10795)
		(layer "F.Cu")
		(net "FM_POST_CARD_PRES_BMC_N")
	)
	(via
		(at 401.574 -118.2116)
		(size 0.6604)
		(drill 0.3302)
		(layers "F.Cu" "B.Cu")
		(net "FM_POST_CARD_PRES_BMC_N")
	)
	(via
		(at 482.3079 -138.4935)
		(size 0.508)
		(drill 0.254)
		(layers "F.Cu" "B.Cu")
		(net "FM_POST_CARD_PRES_BMC_N")
	)
	(via
		(at 488.315 -138.8618)
		(size 0.508)
		(drill 0.254)
		(layers "F.Cu" "B.Cu")
		(net "FM_POST_CARD_PRES_BMC_N")
	)
	(via
		(at 402.3868 -117.50294)
		(size 0.508)
		(drill 0.254)
		(layers "F.Cu" "B.Cu")
		(net "FM_POST_CARD_PRES_BMC_N")
	)
	(via
		(at 406.6286 -33.5026)
		(size 0.4572)
		(drill 0.2032)
		(layers "F.Cu" "B.Cu")
		(net "FM_POST_CARD_PRES_BMC_N")
	)
	(via
		(at 382.8288 -90.424)
		(size 0.508)
		(drill 0.254)
		(layers "F.Cu" "B.Cu")
		(net "FM_POST_CARD_PRES_BMC_N")
	)
	(via
		(at 492.7092 -138.0998)
		(size 0.508)
		(drill 0.254)
		(layers "F.Cu" "B.Cu")
		(net "FM_POST_CARD_PRES_BMC_N")
	)
	(segment
		(start 488.315 -139.4206)
		(end 488.061 -139.6746)
		(width 0.10795)
		(layer "B.Cu")
		(net "FM_POST_CARD_PRES_BMC_N")
	)
	(segment
		(start 402.3868 -117.85854)
		(end 402.3868 -117.50294)
		(width 0.10795)
		(layer "B.Cu")
		(net "FM_POST_CARD_PRES_BMC_N")
	)
	(segment
		(start 400.756628 -117.179344)
		(end 400.756628 -117.775228)
		(width 0.10795)
		(layer "B.Cu")
		(net "FM_POST_CARD_PRES_BMC_N")
	)
	(segment
		(start 493.7125 -137.4394)
		(end 493.7125 -138.006328)
		(width 0.10795)
		(layer "B.Cu")
		(net "FM_POST_CARD_PRES_BMC_N")
	)
	(segment
		(start 482.8286 -137.9728)
		(end 486.664 -137.9728)
		(width 0.10795)
		(layer "B.Cu")
		(net "FM_POST_CARD_PRES_BMC_N")
	)
	(segment
		(start 400.756628 -117.775228)
		(end 401.193 -118.2116)
		(width 0.10795)
		(layer "B.Cu")
		(net "FM_POST_CARD_PRES_BMC_N")
	)
	(segment
		(start 488.3658 -138.811)
		(end 488.315 -138.8618)
		(width 0.10795)
		(layer "B.Cu")
		(net "FM_POST_CARD_PRES_BMC_N")
	)
	(segment
		(start 401.193 -118.2116)
		(end 401.574 -118.2116)
		(width 0.10795)
		(layer "B.Cu")
		(net "FM_POST_CARD_PRES_BMC_N")
	)
	(segment
		(start 488.061 -139.3698)
		(end 488.061 -139.6746)
		(width 0.10795)
		(layer "B.Cu")
		(net "FM_POST_CARD_PRES_BMC_N")
	)
	(segment
		(start 401.574 -118.2116)
		(end 402.03374 -118.2116)
		(width 0.10795)
		(layer "B.Cu")
		(net "FM_POST_CARD_PRES_BMC_N")
	)
	(segment
		(start 488.315 -138.8618)
		(end 488.315 -139.4206)
		(width 0.10795)
		(layer "B.Cu")
		(net "FM_POST_CARD_PRES_BMC_N")
	)
	(segment
		(start 489.189014 -138.811)
		(end 488.3658 -138.811)
		(width 0.10795)
		(layer "B.Cu")
		(net "FM_POST_CARD_PRES_BMC_N")
	)
	(segment
		(start 492.8108 -138.2014)
		(end 492.7092 -138.0998)
		(width 0.10795)
		(layer "B.Cu")
		(net "FM_POST_CARD_PRES_BMC_N")
	)
	(segment
		(start 402.03374 -118.2116)
		(end 402.3868 -117.85854)
		(width 0.10795)
		(layer "B.Cu")
		(net "FM_POST_CARD_PRES_BMC_N")
	)
	(segment
		(start 493.517428 -138.2014)
		(end 492.8108 -138.2014)
		(width 0.10795)
		(layer "B.Cu")
		(net "FM_POST_CARD_PRES_BMC_N")
	)
	(segment
		(start 493.7125 -138.006328)
		(end 493.517428 -138.2014)
		(width 0.10795)
		(layer "B.Cu")
		(net "FM_POST_CARD_PRES_BMC_N")
	)
	(segment
		(start 486.664 -137.9728)
		(end 488.061 -139.3698)
		(width 0.10795)
		(layer "B.Cu")
		(net "FM_POST_CARD_PRES_BMC_N")
	)
	(segment
		(start 482.3079 -138.4935)
		(end 482.8286 -137.9728)
		(width 0.10795)
		(layer "B.Cu")
		(net "FM_POST_CARD_PRES_BMC_N")
	)
	(segment
		(start 457.326746 -121.013474)
		(end 459.117954 -121.013474)
		(width 0.089408)
		(layer "In2.Cu")
		(net "FM_POST_CARD_PRES_BMC_N")
	)
	(segment
		(start 406.34539 -33.78581)
		(end 406.6286 -33.5026)
		(width 0.089408)
		(layer "In2.Cu")
		(net "FM_POST_CARD_PRES_BMC_N")
	)
	(segment
		(start 388.786878 -59.612784)
		(end 388.786878 -58.700924)
		(width 0.089408)
		(layer "In2.Cu")
		(net "FM_POST_CARD_PRES_BMC_N")
	)
	(segment
		(start 476.489268 -133.834378)
		(end 476.489268 -134.166102)
		(width 0.089408)
		(layer "In2.Cu")
		(net "FM_POST_CARD_PRES_BMC_N")
	)
	(segment
		(start 477.196912 -126.821946)
		(end 477.196912 -129.991612)
		(width 0.089408)
		(layer "In2.Cu")
		(net "FM_POST_CARD_PRES_BMC_N")
	)
	(segment
		(start 388.786624 -60.606432)
		(end 388.786624 -59.613038)
		(width 0.089408)
		(layer "In2.Cu")
		(net "FM_POST_CARD_PRES_BMC_N")
	)
	(segment
		(start 412.10738 -122.677936)
		(end 418.451538 -122.677936)
		(width 0.089408)
		(layer "In2.Cu")
		(net "FM_POST_CARD_PRES_BMC_N")
	)
	(segment
		(start 480.695 -136.8806)
		(end 482.3079 -138.4935)
		(width 0.089408)
		(layer "In2.Cu")
		(net "FM_POST_CARD_PRES_BMC_N")
	)
	(segment
		(start 388.176516 -57.55005)
		(end 387.343904 -56.717438)
		(width 0.089408)
		(layer "In2.Cu")
		(net "FM_POST_CARD_PRES_BMC_N")
	)
	(segment
		(start 396.491206 -37.67709)
		(end 398.221962 -35.946334)
		(width 0.089408)
		(layer "In2.Cu")
		(net "FM_POST_CARD_PRES_BMC_N")
	)
	(segment
		(start 398.587468 -35.946334)
		(end 400.27352 -34.260282)
		(width 0.089408)
		(layer "In2.Cu")
		(net "FM_POST_CARD_PRES_BMC_N")
	)
	(segment
		(start 388.786878 -58.700924)
		(end 388.176516 -58.090562)
		(width 0.089408)
		(layer "In2.Cu")
		(net "FM_POST_CARD_PRES_BMC_N")
	)
	(segment
		(start 439.337196 -121.797318)
		(end 439.767218 -121.367296)
		(width 0.089408)
		(layer "In2.Cu")
		(net "FM_POST_CARD_PRES_BMC_N")
	)
	(segment
		(start 384.81762 -86.950804)
		(end 386.494782 -85.273642)
		(width 0.089408)
		(layer "In2.Cu")
		(net "FM_POST_CARD_PRES_BMC_N")
	)
	(segment
		(start 384.81762 -89.40927)
		(end 384.81762 -86.950804)
		(width 0.089408)
		(layer "In2.Cu")
		(net "FM_POST_CARD_PRES_BMC_N")
	)
	(segment
		(start 470.769188 -121.378726)
		(end 475.451424 -126.060962)
		(width 0.089408)
		(layer "In2.Cu")
		(net "FM_POST_CARD_PRES_BMC_N")
	)
	(segment
		(start 387.054344 -74.059542)
		(end 387.054344 -73.635108)
		(width 0.089408)
		(layer "In2.Cu")
		(net "FM_POST_CARD_PRES_BMC_N")
	)
	(segment
		(start 453.451722 -120.043956)
		(end 456.357228 -120.043956)
		(width 0.089408)
		(layer "In2.Cu")
		(net "FM_POST_CARD_PRES_BMC_N")
	)
	(segment
		(start 466.313266 -121.378726)
		(end 470.769188 -121.378726)
		(width 0.089408)
		(layer "In2.Cu")
		(net "FM_POST_CARD_PRES_BMC_N")
	)
	(segment
		(start 387.200648 -70.484746)
		(end 387.200648 -65.274952)
		(width 0.089408)
		(layer "In2.Cu")
		(net "FM_POST_CARD_PRES_BMC_N")
	)
	(segment
		(start 456.357228 -120.043956)
		(end 457.326746 -121.013474)
		(width 0.089408)
		(layer "In2.Cu")
		(net "FM_POST_CARD_PRES_BMC_N")
	)
	(segment
		(start 459.117954 -121.013474)
		(end 460.33182 -119.799608)
		(width 0.089408)
		(layer "In2.Cu")
		(net "FM_POST_CARD_PRES_BMC_N")
	)
	(segment
		(start 402.3868 -117.50294)
		(end 402.3868 -117.68328)
		(width 0.089408)
		(layer "In2.Cu")
		(net "FM_POST_CARD_PRES_BMC_N")
	)
	(segment
		(start 388.176516 -58.090562)
		(end 388.176516 -57.55005)
		(width 0.089408)
		(layer "In2.Cu")
		(net "FM_POST_CARD_PRES_BMC_N")
	)
	(segment
		(start 402.696172 -117.992652)
		(end 405.49322 -117.992652)
		(width 0.089408)
		(layer "In2.Cu")
		(net "FM_POST_CARD_PRES_BMC_N")
	)
	(segment
		(start 389.785606 -61.605414)
		(end 388.786624 -60.606432)
		(width 0.089408)
		(layer "In2.Cu")
		(net "FM_POST_CARD_PRES_BMC_N")
	)
	(segment
		(start 407.755598 -120.25503)
		(end 407.755598 -121.24182)
		(width 0.089408)
		(layer "In2.Cu")
		(net "FM_POST_CARD_PRES_BMC_N")
	)
	(segment
		(start 386.494782 -85.273642)
		(end 387.719824 -85.273642)
		(width 0.089408)
		(layer "In2.Cu")
		(net "FM_POST_CARD_PRES_BMC_N")
	)
	(segment
		(start 387.054344 -73.635108)
		(end 387.05409 -73.634854)
		(width 0.089408)
		(layer "In2.Cu")
		(net "FM_POST_CARD_PRES_BMC_N")
	)
	(segment
		(start 475.451424 -126.060962)
		(end 476.435928 -126.060962)
		(width 0.089408)
		(layer "In2.Cu")
		(net "FM_POST_CARD_PRES_BMC_N")
	)
	(segment
		(start 383.4384 -90.424)
		(end 384.624072 -91.609672)
		(width 0.089408)
		(layer "In2.Cu")
		(net "FM_POST_CARD_PRES_BMC_N")
	)
	(segment
		(start 386.484622 -78.370684)
		(end 387.3754 -77.479906)
		(width 0.089408)
		(layer "In2.Cu")
		(net "FM_POST_CARD_PRES_BMC_N")
	)
	(segment
		(start 405.49322 -117.992652)
		(end 407.755598 -120.25503)
		(width 0.089408)
		(layer "In2.Cu")
		(net "FM_POST_CARD_PRES_BMC_N")
	)
	(segment
		(start 387.343904 -56.717438)
		(end 387.343904 -43.575224)
		(width 0.089408)
		(layer "In2.Cu")
		(net "FM_POST_CARD_PRES_BMC_N")
	)
	(segment
		(start 476.489268 -134.166102)
		(end 476.490284 -134.167118)
		(width 0.089408)
		(layer "In2.Cu")
		(net "FM_POST_CARD_PRES_BMC_N")
	)
	(segment
		(start 391.276078 -41.383712)
		(end 391.276078 -40.574214)
		(width 0.089408)
		(layer "In2.Cu")
		(net "FM_POST_CARD_PRES_BMC_N")
	)
	(segment
		(start 387.914388 -43.00474)
		(end 389.65505 -43.00474)
		(width 0.089408)
		(layer "In2.Cu")
		(net "FM_POST_CARD_PRES_BMC_N")
	)
	(segment
		(start 411.476698 -123.308618)
		(end 412.10738 -122.677936)
		(width 0.089408)
		(layer "In2.Cu")
		(net "FM_POST_CARD_PRES_BMC_N")
	)
	(segment
		(start 409.822396 -123.308618)
		(end 411.476698 -123.308618)
		(width 0.089408)
		(layer "In2.Cu")
		(net "FM_POST_CARD_PRES_BMC_N")
	)
	(segment
		(start 418.451538 -122.677936)
		(end 419.301168 -123.527566)
		(width 0.089408)
		(layer "In2.Cu")
		(net "FM_POST_CARD_PRES_BMC_N")
	)
	(segment
		(start 464.734148 -119.799608)
		(end 466.313266 -121.378726)
		(width 0.089408)
		(layer "In2.Cu")
		(net "FM_POST_CARD_PRES_BMC_N")
	)
	(segment
		(start 427.023022 -123.297696)
		(end 428.5234 -121.797318)
		(width 0.089408)
		(layer "In2.Cu")
		(net "FM_POST_CARD_PRES_BMC_N")
	)
	(segment
		(start 402.3868 -117.68328)
		(end 402.696172 -117.992652)
		(width 0.089408)
		(layer "In2.Cu")
		(net "FM_POST_CARD_PRES_BMC_N")
	)
	(segment
		(start 439.767218 -121.367296)
		(end 452.128382 -121.367296)
		(width 0.089408)
		(layer "In2.Cu")
		(net "FM_POST_CARD_PRES_BMC_N")
	)
	(segment
		(start 406.34539 -34.150046)
		(end 406.34539 -33.78581)
		(width 0.089408)
		(layer "In2.Cu")
		(net "FM_POST_CARD_PRES_BMC_N")
	)
	(segment
		(start 404.907242 -35.588194)
		(end 406.34539 -34.150046)
		(width 0.089408)
		(layer "In2.Cu")
		(net "FM_POST_CARD_PRES_BMC_N")
	)
	(segment
		(start 460.33182 -119.799608)
		(end 464.734148 -119.799608)
		(width 0.089408)
		(layer "In2.Cu")
		(net "FM_POST_CARD_PRES_BMC_N")
	)
	(segment
		(start 387.343904 -43.575224)
		(end 387.914388 -43.00474)
		(width 0.089408)
		(layer "In2.Cu")
		(net "FM_POST_CARD_PRES_BMC_N")
	)
	(segment
		(start 384.624072 -91.609672)
		(end 384.940048 -91.609672)
		(width 0.089408)
		(layer "In2.Cu")
		(net "FM_POST_CARD_PRES_BMC_N")
	)
	(segment
		(start 423.976546 -123.527566)
		(end 424.206416 -123.297696)
		(width 0.089408)
		(layer "In2.Cu")
		(net "FM_POST_CARD_PRES_BMC_N")
	)
	(segment
		(start 388.187438 -64.791336)
		(end 389.785606 -63.193168)
		(width 0.089408)
		(layer "In2.Cu")
		(net "FM_POST_CARD_PRES_BMC_N")
	)
	(segment
		(start 387.3754 -74.380598)
		(end 387.054344 -74.059542)
		(width 0.089408)
		(layer "In2.Cu")
		(net "FM_POST_CARD_PRES_BMC_N")
	)
	(segment
		(start 402.17979 -34.260282)
		(end 403.507702 -35.588194)
		(width 0.089408)
		(layer "In2.Cu")
		(net "FM_POST_CARD_PRES_BMC_N")
	)
	(segment
		(start 424.206416 -123.297696)
		(end 427.023022 -123.297696)
		(width 0.089408)
		(layer "In2.Cu")
		(net "FM_POST_CARD_PRES_BMC_N")
	)
	(segment
		(start 387.05409 -72.949562)
		(end 387.054344 -72.949308)
		(width 0.089408)
		(layer "In2.Cu")
		(net "FM_POST_CARD_PRES_BMC_N")
	)
	(segment
		(start 476.490284 -135.274304)
		(end 478.09658 -136.8806)
		(width 0.089408)
		(layer "In2.Cu")
		(net "FM_POST_CARD_PRES_BMC_N")
	)
	(segment
		(start 419.301168 -123.527566)
		(end 423.976546 -123.527566)
		(width 0.089408)
		(layer "In2.Cu")
		(net "FM_POST_CARD_PRES_BMC_N")
	)
	(segment
		(start 387.255512 -70.53961)
		(end 387.200648 -70.484746)
		(width 0.089408)
		(layer "In2.Cu")
		(net "FM_POST_CARD_PRES_BMC_N")
	)
	(segment
		(start 387.3754 -77.479906)
		(end 387.3754 -74.380598)
		(width 0.089408)
		(layer "In2.Cu")
		(net "FM_POST_CARD_PRES_BMC_N")
	)
	(segment
		(start 428.5234 -121.797318)
		(end 439.337196 -121.797318)
		(width 0.089408)
		(layer "In2.Cu")
		(net "FM_POST_CARD_PRES_BMC_N")
	)
	(segment
		(start 452.128382 -121.367296)
		(end 453.451722 -120.043956)
		(width 0.089408)
		(layer "In2.Cu")
		(net "FM_POST_CARD_PRES_BMC_N")
	)
	(segment
		(start 477.196912 -129.991612)
		(end 476.490284 -130.69824)
		(width 0.089408)
		(layer "In2.Cu")
		(net "FM_POST_CARD_PRES_BMC_N")
	)
	(segment
		(start 398.221962 -35.946334)
		(end 398.587468 -35.946334)
		(width 0.089408)
		(layer "In2.Cu")
		(net "FM_POST_CARD_PRES_BMC_N")
	)
	(segment
		(start 394.173202 -37.67709)
		(end 396.491206 -37.67709)
		(width 0.089408)
		(layer "In2.Cu")
		(net "FM_POST_CARD_PRES_BMC_N")
	)
	(segment
		(start 476.490284 -134.167118)
		(end 476.490284 -135.274304)
		(width 0.089408)
		(layer "In2.Cu")
		(net "FM_POST_CARD_PRES_BMC_N")
	)
	(segment
		(start 478.09658 -136.8806)
		(end 480.695 -136.8806)
		(width 0.089408)
		(layer "In2.Cu")
		(net "FM_POST_CARD_PRES_BMC_N")
	)
	(segment
		(start 388.394702 -83.618832)
		(end 386.484622 -81.708752)
		(width 0.089408)
		(layer "In2.Cu")
		(net "FM_POST_CARD_PRES_BMC_N")
	)
	(segment
		(start 403.507702 -35.588194)
		(end 404.907242 -35.588194)
		(width 0.089408)
		(layer "In2.Cu")
		(net "FM_POST_CARD_PRES_BMC_N")
	)
	(segment
		(start 407.755598 -121.24182)
		(end 409.822396 -123.308618)
		(width 0.089408)
		(layer "In2.Cu")
		(net "FM_POST_CARD_PRES_BMC_N")
	)
	(segment
		(start 476.435928 -126.060962)
		(end 477.196912 -126.821946)
		(width 0.089408)
		(layer "In2.Cu")
		(net "FM_POST_CARD_PRES_BMC_N")
	)
	(segment
		(start 387.684264 -64.791336)
		(end 388.187438 -64.791336)
		(width 0.089408)
		(layer "In2.Cu")
		(net "FM_POST_CARD_PRES_BMC_N")
	)
	(segment
		(start 389.65505 -43.00474)
		(end 391.276078 -41.383712)
		(width 0.089408)
		(layer "In2.Cu")
		(net "FM_POST_CARD_PRES_BMC_N")
	)
	(segment
		(start 389.785606 -63.193168)
		(end 389.785606 -61.605414)
		(width 0.089408)
		(layer "In2.Cu")
		(net "FM_POST_CARD_PRES_BMC_N")
	)
	(segment
		(start 400.27352 -34.260282)
		(end 402.17979 -34.260282)
		(width 0.089408)
		(layer "In2.Cu")
		(net "FM_POST_CARD_PRES_BMC_N")
	)
	(segment
		(start 387.255512 -71.39559)
		(end 387.255512 -70.53961)
		(width 0.089408)
		(layer "In2.Cu")
		(net "FM_POST_CARD_PRES_BMC_N")
	)
	(segment
		(start 387.05409 -71.597012)
		(end 387.255512 -71.39559)
		(width 0.089408)
		(layer "In2.Cu")
		(net "FM_POST_CARD_PRES_BMC_N")
	)
	(segment
		(start 387.05409 -73.634854)
		(end 387.05409 -72.949562)
		(width 0.089408)
		(layer "In2.Cu")
		(net "FM_POST_CARD_PRES_BMC_N")
	)
	(segment
		(start 387.200648 -65.274952)
		(end 387.684264 -64.791336)
		(width 0.089408)
		(layer "In2.Cu")
		(net "FM_POST_CARD_PRES_BMC_N")
	)
	(segment
		(start 387.054344 -71.86041)
		(end 387.05409 -71.860156)
		(width 0.089408)
		(layer "In2.Cu")
		(net "FM_POST_CARD_PRES_BMC_N")
	)
	(segment
		(start 385.377182 -91.172538)
		(end 385.377182 -89.968832)
		(width 0.089408)
		(layer "In2.Cu")
		(net "FM_POST_CARD_PRES_BMC_N")
	)
	(segment
		(start 385.377182 -89.968832)
		(end 384.81762 -89.40927)
		(width 0.089408)
		(layer "In2.Cu")
		(net "FM_POST_CARD_PRES_BMC_N")
	)
	(segment
		(start 476.490284 -133.833362)
		(end 476.489268 -133.834378)
		(width 0.089408)
		(layer "In2.Cu")
		(net "FM_POST_CARD_PRES_BMC_N")
	)
	(segment
		(start 387.054344 -72.949308)
		(end 387.054344 -71.86041)
		(width 0.089408)
		(layer "In2.Cu")
		(net "FM_POST_CARD_PRES_BMC_N")
	)
	(segment
		(start 387.719824 -85.273642)
		(end 388.394702 -84.598764)
		(width 0.089408)
		(layer "In2.Cu")
		(net "FM_POST_CARD_PRES_BMC_N")
	)
	(segment
		(start 391.276078 -40.574214)
		(end 394.173202 -37.67709)
		(width 0.089408)
		(layer "In2.Cu")
		(net "FM_POST_CARD_PRES_BMC_N")
	)
	(segment
		(start 382.8288 -90.424)
		(end 383.4384 -90.424)
		(width 0.089408)
		(layer "In2.Cu")
		(net "FM_POST_CARD_PRES_BMC_N")
	)
	(segment
		(start 386.484622 -81.708752)
		(end 386.484622 -78.370684)
		(width 0.089408)
		(layer "In2.Cu")
		(net "FM_POST_CARD_PRES_BMC_N")
	)
	(segment
		(start 476.490284 -130.69824)
		(end 476.490284 -133.833362)
		(width 0.089408)
		(layer "In2.Cu")
		(net "FM_POST_CARD_PRES_BMC_N")
	)
	(segment
		(start 387.05409 -71.860156)
		(end 387.05409 -71.597012)
		(width 0.089408)
		(layer "In2.Cu")
		(net "FM_POST_CARD_PRES_BMC_N")
	)
	(segment
		(start 388.786624 -59.613038)
		(end 388.786878 -59.612784)
		(width 0.089408)
		(layer "In2.Cu")
		(net "FM_POST_CARD_PRES_BMC_N")
	)
	(segment
		(start 388.394702 -84.598764)
		(end 388.394702 -83.618832)
		(width 0.089408)
		(layer "In2.Cu")
		(net "FM_POST_CARD_PRES_BMC_N")
	)
	(segment
		(start 384.940048 -91.609672)
		(end 385.377182 -91.172538)
		(width 0.089408)
		(layer "In2.Cu")
		(net "FM_POST_CARD_PRES_BMC_N")
	)
	(segment
		(start 393.137898 -103.853996)
		(end 394.08608 -102.905814)
		(width 0.089408)
		(layer "In9.Cu")
		(net "FM_POST_CARD_PRES_BMC_N")
	)
	(segment
		(start 393.817094 -102.30612)
		(end 391.658602 -102.30612)
		(width 0.089408)
		(layer "In9.Cu")
		(net "FM_POST_CARD_PRES_BMC_N")
	)
	(segment
		(start 399.92808 -113.93932)
		(end 396.315692 -113.93932)
		(width 0.0889)
		(layer "In9.Cu")
		(net "FM_POST_CARD_PRES_BMC_N")
	)
	(segment
		(start 403.40534 -117.50294)
		(end 403.80158 -117.1067)
		(width 0.0889)
		(layer "In9.Cu")
		(net "FM_POST_CARD_PRES_BMC_N")
	)
	(segment
		(start 384.711194 -100.431092)
		(end 384.666236 -100.123244)
		(width 0.0889)
		(layer "In9.Cu")
		(net "FM_POST_CARD_PRES_BMC_N")
	)
	(segment
		(start 394.532612 -108.025692)
		(end 394.532612 -108.012484)
		(width 0.089408)
		(layer "In9.Cu")
		(net "FM_POST_CARD_PRES_BMC_N")
	)
	(segment
		(start 384.962654 -102.30612)
		(end 384.668776 -102.012242)
		(width 0.0889)
		(layer "In9.Cu")
		(net "FM_POST_CARD_PRES_BMC_N")
	)
	(segment
		(start 393.576048 -105.123234)
		(end 393.137898 -104.685084)
		(width 0.089408)
		(layer "In9.Cu")
		(net "FM_POST_CARD_PRES_BMC_N")
	)
	(segment
		(start 384.3274 -100.814886)
		(end 384.711194 -100.431092)
		(width 0.0889)
		(layer "In9.Cu")
		(net "FM_POST_CARD_PRES_BMC_N")
	)
	(segment
		(start 395.758924 -112.914176)
		(end 395.758924 -112.269016)
		(width 0.0889)
		(layer "In9.Cu")
		(net "FM_POST_CARD_PRES_BMC_N")
	)
	(segment
		(start 382.3716 -90.8812)
		(end 382.8288 -90.424)
		(width 0.089408)
		(layer "In9.Cu")
		(net "FM_POST_CARD_PRES_BMC_N")
	)
	(segment
		(start 395.565376 -110.244636)
		(end 395.23162 -109.91088)
		(width 0.089408)
		(layer "In9.Cu")
		(net "FM_POST_CARD_PRES_BMC_N")
	)
	(segment
		(start 382.1938 -95.910146)
		(end 382.1938 -95.0468)
		(width 0.0889)
		(layer "In9.Cu")
		(net "FM_POST_CARD_PRES_BMC_N")
	)
	(segment
		(start 395.565376 -110.60938)
		(end 395.565376 -110.244636)
		(width 0.089408)
		(layer "In9.Cu")
		(net "FM_POST_CARD_PRES_BMC_N")
	)
	(segment
		(start 390.310624 -102.591616)
		(end 390.310624 -102.92207)
		(width 0.0889)
		(layer "In9.Cu")
		(net "FM_POST_CARD_PRES_BMC_N")
	)
	(segment
		(start 403.80158 -117.1067)
		(end 403.80158 -116.51488)
		(width 0.0889)
		(layer "In9.Cu")
		(net "FM_POST_CARD_PRES_BMC_N")
	)
	(segment
		(start 382.1938 -93.9038)
		(end 382.651 -93.4466)
		(width 0.089408)
		(layer "In9.Cu")
		(net "FM_POST_CARD_PRES_BMC_N")
	)
	(segment
		(start 390.310624 -102.92207)
		(end 390.077452 -103.155242)
		(width 0.0889)
		(layer "In9.Cu")
		(net "FM_POST_CARD_PRES_BMC_N")
	)
	(segment
		(start 393.137898 -104.685084)
		(end 393.137898 -103.853996)
		(width 0.089408)
		(layer "In9.Cu")
		(net "FM_POST_CARD_PRES_BMC_N")
	)
	(segment
		(start 384.175 -99.344226)
		(end 384.175 -99.31146)
		(width 0.0889)
		(layer "In9.Cu")
		(net "FM_POST_CARD_PRES_BMC_N")
	)
	(segment
		(start 394.76807 -108.98759)
		(end 394.76807 -108.26115)
		(width 0.089408)
		(layer "In9.Cu")
		(net "FM_POST_CARD_PRES_BMC_N")
	)
	(segment
		(start 395.23162 -109.45114)
		(end 394.76807 -108.98759)
		(width 0.089408)
		(layer "In9.Cu")
		(net "FM_POST_CARD_PRES_BMC_N")
	)
	(segment
		(start 394.532612 -108.012484)
		(end 394.29182 -107.771692)
		(width 0.089408)
		(layer "In9.Cu")
		(net "FM_POST_CARD_PRES_BMC_N")
	)
	(segment
		(start 393.576048 -105.960672)
		(end 393.576048 -105.123234)
		(width 0.089408)
		(layer "In9.Cu")
		(net "FM_POST_CARD_PRES_BMC_N")
	)
	(segment
		(start 382.3716 -91.4146)
		(end 382.3716 -90.8812)
		(width 0.089408)
		(layer "In9.Cu")
		(net "FM_POST_CARD_PRES_BMC_N")
	)
	(segment
		(start 393.748514 -106.133138)
		(end 393.576048 -105.960672)
		(width 0.089408)
		(layer "In9.Cu")
		(net "FM_POST_CARD_PRES_BMC_N")
	)
	(segment
		(start 394.08608 -102.575106)
		(end 393.817094 -102.30612)
		(width 0.089408)
		(layer "In9.Cu")
		(net "FM_POST_CARD_PRES_BMC_N")
	)
	(segment
		(start 390.59612 -102.30612)
		(end 390.310624 -102.591616)
		(width 0.0889)
		(layer "In9.Cu")
		(net "FM_POST_CARD_PRES_BMC_N")
	)
	(segment
		(start 387.955282 -102.30612)
		(end 384.962654 -102.30612)
		(width 0.0889)
		(layer "In9.Cu")
		(net "FM_POST_CARD_PRES_BMC_N")
	)
	(segment
		(start 382.6891 -96.768666)
		(end 382.6891 -96.7359)
		(width 0.0889)
		(layer "In9.Cu")
		(net "FM_POST_CARD_PRES_BMC_N")
	)
	(segment
		(start 396.060676 -113.684304)
		(end 396.060676 -113.215928)
		(width 0.0889)
		(layer "In9.Cu")
		(net "FM_POST_CARD_PRES_BMC_N")
	)
	(segment
		(start 403.80158 -116.51488)
		(end 403.66696 -116.38026)
		(width 0.0889)
		(layer "In9.Cu")
		(net "FM_POST_CARD_PRES_BMC_N")
	)
	(segment
		(start 384.668776 -101.669088)
		(end 384.553968 -101.39172)
		(width 0.0889)
		(layer "In9.Cu")
		(net "FM_POST_CARD_PRES_BMC_N")
	)
	(segment
		(start 383.6797 -98.485706)
		(end 383.6797 -98.45294)
		(width 0.0889)
		(layer "In9.Cu")
		(net "FM_POST_CARD_PRES_BMC_N")
	)
	(segment
		(start 394.29182 -107.771692)
		(end 394.29182 -107.624626)
		(width 0.089408)
		(layer "In9.Cu")
		(net "FM_POST_CARD_PRES_BMC_N")
	)
	(segment
		(start 396.060676 -111.967264)
		(end 396.060676 -111.637064)
		(width 0.0889)
		(layer "In9.Cu")
		(net "FM_POST_CARD_PRES_BMC_N")
	)
	(segment
		(start 390.077452 -103.155242)
		(end 388.804404 -103.155242)
		(width 0.0889)
		(layer "In9.Cu")
		(net "FM_POST_CARD_PRES_BMC_N")
	)
	(segment
		(start 400.62277 -114.63401)
		(end 399.92808 -113.93932)
		(width 0.0889)
		(layer "In9.Cu")
		(net "FM_POST_CARD_PRES_BMC_N")
	)
	(segment
		(start 396.060676 -111.637064)
		(end 395.565376 -111.141764)
		(width 0.0889)
		(layer "In9.Cu")
		(net "FM_POST_CARD_PRES_BMC_N")
	)
	(segment
		(start 403.66696 -116.38026)
		(end 401.756626 -116.38026)
		(width 0.0889)
		(layer "In9.Cu")
		(net "FM_POST_CARD_PRES_BMC_N")
	)
	(segment
		(start 395.758924 -112.269016)
		(end 396.060676 -111.967264)
		(width 0.0889)
		(layer "In9.Cu")
		(net "FM_POST_CARD_PRES_BMC_N")
	)
	(segment
		(start 382.651 -93.4466)
		(end 382.651 -91.694)
		(width 0.089408)
		(layer "In9.Cu")
		(net "FM_POST_CARD_PRES_BMC_N")
	)
	(segment
		(start 396.315692 -113.93932)
		(end 396.060676 -113.684304)
		(width 0.0889)
		(layer "In9.Cu")
		(net "FM_POST_CARD_PRES_BMC_N")
	)
	(segment
		(start 393.748514 -107.08132)
		(end 393.748514 -106.133138)
		(width 0.089408)
		(layer "In9.Cu")
		(net "FM_POST_CARD_PRES_BMC_N")
	)
	(segment
		(start 391.658602 -102.30612)
		(end 390.59612 -102.30612)
		(width 0.0889)
		(layer "In9.Cu")
		(net "FM_POST_CARD_PRES_BMC_N")
	)
	(segment
		(start 384.3274 -101.165152)
		(end 384.3274 -100.814886)
		(width 0.0889)
		(layer "In9.Cu")
		(net "FM_POST_CARD_PRES_BMC_N")
	)
	(segment
		(start 395.565376 -111.141764)
		(end 395.565376 -110.60938)
		(width 0.0889)
		(layer "In9.Cu")
		(net "FM_POST_CARD_PRES_BMC_N")
	)
	(segment
		(start 396.060676 -113.215928)
		(end 395.758924 -112.914176)
		(width 0.0889)
		(layer "In9.Cu")
		(net "FM_POST_CARD_PRES_BMC_N")
	)
	(segment
		(start 395.23162 -109.91088)
		(end 395.23162 -109.45114)
		(width 0.089408)
		(layer "In9.Cu")
		(net "FM_POST_CARD_PRES_BMC_N")
	)
	(segment
		(start 388.804404 -103.155242)
		(end 387.955282 -102.30612)
		(width 0.0889)
		(layer "In9.Cu")
		(net "FM_POST_CARD_PRES_BMC_N")
	)
	(segment
		(start 383.1844 -97.627186)
		(end 383.1844 -97.59442)
		(width 0.0889)
		(layer "In9.Cu")
		(net "FM_POST_CARD_PRES_BMC_N")
	)
	(segment
		(start 400.62277 -115.246404)
		(end 400.62277 -114.63401)
		(width 0.0889)
		(layer "In9.Cu")
		(net "FM_POST_CARD_PRES_BMC_N")
	)
	(segment
		(start 401.756626 -116.38026)
		(end 400.62277 -115.246404)
		(width 0.0889)
		(layer "In9.Cu")
		(net "FM_POST_CARD_PRES_BMC_N")
	)
	(segment
		(start 394.29182 -107.624626)
		(end 393.748514 -107.08132)
		(width 0.089408)
		(layer "In9.Cu")
		(net "FM_POST_CARD_PRES_BMC_N")
	)
	(segment
		(start 394.76807 -108.26115)
		(end 394.532612 -108.025692)
		(width 0.089408)
		(layer "In9.Cu")
		(net "FM_POST_CARD_PRES_BMC_N")
	)
	(segment
		(start 402.3868 -117.50294)
		(end 403.40534 -117.50294)
		(width 0.0889)
		(layer "In9.Cu")
		(net "FM_POST_CARD_PRES_BMC_N")
	)
	(segment
		(start 384.553968 -101.39172)
		(end 384.3274 -101.165152)
		(width 0.0889)
		(layer "In9.Cu")
		(net "FM_POST_CARD_PRES_BMC_N")
	)
	(segment
		(start 382.1938 -95.0468)
		(end 382.1938 -93.9038)
		(width 0.089408)
		(layer "In9.Cu")
		(net "FM_POST_CARD_PRES_BMC_N")
	)
	(segment
		(start 382.651 -91.694)
		(end 382.3716 -91.4146)
		(width 0.089408)
		(layer "In9.Cu")
		(net "FM_POST_CARD_PRES_BMC_N")
	)
	(segment
		(start 394.08608 -102.905814)
		(end 394.08608 -102.575106)
		(width 0.089408)
		(layer "In9.Cu")
		(net "FM_POST_CARD_PRES_BMC_N")
	)
	(segment
		(start 384.668776 -102.012242)
		(end 384.668776 -101.669088)
		(width 0.0889)
		(layer "In9.Cu")
		(net "FM_POST_CARD_PRES_BMC_N")
	)
	(arc
		(start 383.479548 -98.117406)
		(mid 383.268684 -97.910402)
		(end 383.1844 -97.627186)
		(width 0.0889)
		(layer "In9.Cu")
		(net "FM_POST_CARD_PRES_BMC_N")
	)
	(arc
		(start 382.984248 -97.258886)
		(mid 382.773384 -97.051882)
		(end 382.6891 -96.768666)
		(width 0.0889)
		(layer "In9.Cu")
		(net "FM_POST_CARD_PRES_BMC_N")
	)
	(arc
		(start 384.666236 -100.123244)
		(mid 384.601336 -99.956343)
		(end 384.470148 -99.834446)
		(width 0.0889)
		(layer "In9.Cu")
		(net "FM_POST_CARD_PRES_BMC_N")
	)
	(arc
		(start 383.6797 -98.45294)
		(mid 383.62335 -98.25909)
		(end 383.479548 -98.117406)
		(width 0.0889)
		(layer "In9.Cu")
		(net "FM_POST_CARD_PRES_BMC_N")
	)
	(arc
		(start 384.175 -99.31146)
		(mid 384.11865 -99.11761)
		(end 383.974848 -98.975926)
		(width 0.0889)
		(layer "In9.Cu")
		(net "FM_POST_CARD_PRES_BMC_N")
	)
	(arc
		(start 383.974848 -98.975926)
		(mid 383.763984 -98.768922)
		(end 383.6797 -98.485706)
		(width 0.0889)
		(layer "In9.Cu")
		(net "FM_POST_CARD_PRES_BMC_N")
	)
	(arc
		(start 384.470148 -99.834446)
		(mid 384.259284 -99.627442)
		(end 384.175 -99.344226)
		(width 0.0889)
		(layer "In9.Cu")
		(net "FM_POST_CARD_PRES_BMC_N")
	)
	(arc
		(start 382.6891 -96.7359)
		(mid 382.63275 -96.54205)
		(end 382.488948 -96.400366)
		(width 0.0889)
		(layer "In9.Cu")
		(net "FM_POST_CARD_PRES_BMC_N")
	)
	(arc
		(start 382.488948 -96.400366)
		(mid 382.278084 -96.193362)
		(end 382.1938 -95.910146)
		(width 0.0889)
		(layer "In9.Cu")
		(net "FM_POST_CARD_PRES_BMC_N")
	)
	(arc
		(start 383.1844 -97.59442)
		(mid 383.12805 -97.40057)
		(end 382.984248 -97.258886)
		(width 0.0889)
		(layer "In9.Cu")
		(net "FM_POST_CARD_PRES_BMC_N")
	)
	(segment
		(start 381.694944 -93.72981)
		(end 381.694944 -93.237558)
		(width 0.0889)
		(layer "F.Cu")
		(net "FM_ME_RECOVER_N")
	)
	(segment
		(start 381.143002 -91.086178)
		(end 381.143002 -90.734388)
		(width 0.0889)
		(layer "F.Cu")
		(net "FM_ME_RECOVER_N")
	)
	(segment
		(start 381.796036 -93.830902)
		(end 381.694944 -93.72981)
		(width 0.0889)
		(layer "F.Cu")
		(net "FM_ME_RECOVER_N")
	)
	(segment
		(start 381.586486 -93.1291)
		(end 381.586486 -91.529662)
		(width 0.0889)
		(layer "F.Cu")
		(net "FM_ME_RECOVER_N")
	)
	(segment
		(start 381.694944 -93.237558)
		(end 381.586486 -93.1291)
		(width 0.0889)
		(layer "F.Cu")
		(net "FM_ME_RECOVER_N")
	)
	(segment
		(start 381.586486 -91.529662)
		(end 381.143002 -91.086178)
		(width 0.0889)
		(layer "F.Cu")
		(net "FM_ME_RECOVER_N")
	)
	(segment
		(start 381.985012 -94.37497)
		(end 381.796036 -94.185994)
		(width 0.0889)
		(layer "F.Cu")
		(net "FM_ME_RECOVER_N")
	)
	(segment
		(start 381.796036 -94.185994)
		(end 381.796036 -93.830902)
		(width 0.0889)
		(layer "F.Cu")
		(net "FM_ME_RECOVER_N")
	)
	(segment
		(start 381.143002 -90.734388)
		(end 380.554484 -90.14587)
		(width 0.0889)
		(layer "F.Cu")
		(net "FM_ME_RECOVER_N")
	)
	(via
		(at 385.068318 -9.865614)
		(size 0.6604)
		(drill 0.3302)
		(layers "F.Cu" "B.Cu")
		(net "FM_ME_RECOVER_N")
	)
	(via
		(at 386.159756 -20.03552)
		(size 0.508)
		(drill 0.254)
		(layers "F.Cu" "B.Cu")
		(net "FM_ME_RECOVER_N")
	)
	(via
		(at 383.3876 -0.889)
		(size 0.508)
		(drill 0.254)
		(layers "F.Cu" "B.Cu")
		(net "FM_ME_RECOVER_N")
	)
	(via
		(at 380.554484 -90.14587)
		(size 0.508)
		(drill 0.254)
		(layers "F.Cu" "B.Cu")
		(net "FM_ME_RECOVER_N")
	)
	(segment
		(start 381.173736 -6.31825)
		(end 382.697736 -6.31825)
		(width 0.10795)
		(layer "B.Cu")
		(net "FM_ME_RECOVER_N")
	)
	(segment
		(start 366.936528 -0.042418)
		(end 366.936528 -1.525778)
		(width 0.10795)
		(layer "B.Cu")
		(net "FM_ME_RECOVER_N")
	)
	(segment
		(start 382.697736 -6.31825)
		(end 385.068318 -8.688832)
		(width 0.10795)
		(layer "B.Cu")
		(net "FM_ME_RECOVER_N")
	)
	(segment
		(start 380.850902 -1.506982)
		(end 380.850902 -5.995416)
		(width 0.10795)
		(layer "B.Cu")
		(net "FM_ME_RECOVER_N")
	)
	(segment
		(start 381.98425 -0.373634)
		(end 380.850902 -1.506982)
		(width 0.10795)
		(layer "B.Cu")
		(net "FM_ME_RECOVER_N")
	)
	(segment
		(start 367.427764 2.429764)
		(end 367.427764 0.448818)
		(width 0.10795)
		(layer "B.Cu")
		(net "FM_ME_RECOVER_N")
	)
	(segment
		(start 382.872234 -0.373634)
		(end 381.98425 -0.373634)
		(width 0.10795)
		(layer "B.Cu")
		(net "FM_ME_RECOVER_N")
	)
	(segment
		(start 366.936528 -1.525778)
		(end 368.3254 -2.91465)
		(width 0.10795)
		(layer "B.Cu")
		(net "FM_ME_RECOVER_N")
	)
	(segment
		(start 367.427764 0.448818)
		(end 366.936528 -0.042418)
		(width 0.10795)
		(layer "B.Cu")
		(net "FM_ME_RECOVER_N")
	)
	(segment
		(start 367.8174 -7.112)
		(end 369.78971 -7.112)
		(width 0.10795)
		(layer "B.Cu")
		(net "FM_ME_RECOVER_N")
	)
	(segment
		(start 367.4364 -4.724654)
		(end 367.4364 -6.731)
		(width 0.10795)
		(layer "B.Cu")
		(net "FM_ME_RECOVER_N")
	)
	(segment
		(start 385.068318 -18.944082)
		(end 386.159756 -20.03552)
		(width 0.10795)
		(layer "B.Cu")
		(net "FM_ME_RECOVER_N")
	)
	(segment
		(start 368.3254 -3.835654)
		(end 367.4364 -4.724654)
		(width 0.10795)
		(layer "B.Cu")
		(net "FM_ME_RECOVER_N")
	)
	(segment
		(start 385.068318 -9.865614)
		(end 385.068318 -18.944082)
		(width 0.10795)
		(layer "B.Cu")
		(net "FM_ME_RECOVER_N")
	)
	(segment
		(start 368.3254 -2.91465)
		(end 368.3254 -3.835654)
		(width 0.10795)
		(layer "B.Cu")
		(net "FM_ME_RECOVER_N")
	)
	(segment
		(start 369.78971 -7.112)
		(end 371.63121 -5.2705)
		(width 0.10795)
		(layer "B.Cu")
		(net "FM_ME_RECOVER_N")
	)
	(segment
		(start 367.4364 -6.731)
		(end 367.8174 -7.112)
		(width 0.10795)
		(layer "B.Cu")
		(net "FM_ME_RECOVER_N")
	)
	(segment
		(start 380.850902 -5.995416)
		(end 381.173736 -6.31825)
		(width 0.10795)
		(layer "B.Cu")
		(net "FM_ME_RECOVER_N")
	)
	(segment
		(start 385.068318 -8.688832)
		(end 385.068318 -9.865614)
		(width 0.10795)
		(layer "B.Cu")
		(net "FM_ME_RECOVER_N")
	)
	(segment
		(start 371.63121 -5.2705)
		(end 371.983 -5.2705)
		(width 0.10795)
		(layer "B.Cu")
		(net "FM_ME_RECOVER_N")
	)
	(segment
		(start 368.808 3.81)
		(end 367.427764 2.429764)
		(width 0.10795)
		(layer "B.Cu")
		(net "FM_ME_RECOVER_N")
	)
	(segment
		(start 383.3876 -0.889)
		(end 382.872234 -0.373634)
		(width 0.10795)
		(layer "B.Cu")
		(net "FM_ME_RECOVER_N")
	)
	(segment
		(start 382.6891 -0.1905)
		(end 382.3081 -0.1905)
		(width 0.089408)
		(layer "In4.Cu")
		(net "FM_ME_RECOVER_N")
	)
	(segment
		(start 383.3876 -0.889)
		(end 382.6891 -0.1905)
		(width 0.089408)
		(layer "In4.Cu")
		(net "FM_ME_RECOVER_N")
	)
	(segment
		(start 382.3081 -0.1905)
		(end 379.8062 2.3114)
		(width 0.089408)
		(layer "In4.Cu")
		(net "FM_ME_RECOVER_N")
	)
	(segment
		(start 370.3066 2.3114)
		(end 368.808 3.81)
		(width 0.089408)
		(layer "In4.Cu")
		(net "FM_ME_RECOVER_N")
	)
	(segment
		(start 379.8062 2.3114)
		(end 370.3066 2.3114)
		(width 0.089408)
		(layer "In4.Cu")
		(net "FM_ME_RECOVER_N")
	)
	(segment
		(start 392.139424 -37.764466)
		(end 392.139424 -40.313864)
		(width 0.089408)
		(layer "In9.Cu")
		(net "FM_ME_RECOVER_N")
	)
	(segment
		(start 381.5842 -87.65032)
		(end 380.961138 -88.273382)
		(width 0.089408)
		(layer "In9.Cu")
		(net "FM_ME_RECOVER_N")
	)
	(segment
		(start 390.71804 -22.553168)
		(end 390.71804 -25.19299)
		(width 0.089408)
		(layer "In9.Cu")
		(net "FM_ME_RECOVER_N")
	)
	(segment
		(start 390.947656 -42.20972)
		(end 390.947656 -45.21962)
		(width 0.089408)
		(layer "In9.Cu")
		(net "FM_ME_RECOVER_N")
	)
	(segment
		(start 389.108696 -69.660262)
		(end 389.516112 -70.067678)
		(width 0.089408)
		(layer "In9.Cu")
		(net "FM_ME_RECOVER_N")
	)
	(segment
		(start 383.3114 -86.266782)
		(end 383.3114 -86.882986)
		(width 0.089408)
		(layer "In9.Cu")
		(net "FM_ME_RECOVER_N")
	)
	(segment
		(start 386.69468 -81.779872)
		(end 386.69468 -83.338416)
		(width 0.089408)
		(layer "In9.Cu")
		(net "FM_ME_RECOVER_N")
	)
	(segment
		(start 390.714484 -64.424814)
		(end 390.714484 -65.06845)
		(width 0.089408)
		(layer "In9.Cu")
		(net "FM_ME_RECOVER_N")
	)
	(segment
		(start 386.694934 -81.779618)
		(end 386.69468 -81.779872)
		(width 0.089408)
		(layer "In9.Cu")
		(net "FM_ME_RECOVER_N")
	)
	(segment
		(start 382.544066 -87.65032)
		(end 381.5842 -87.65032)
		(width 0.089408)
		(layer "In9.Cu")
		(net "FM_ME_RECOVER_N")
	)
	(segment
		(start 388.62 -31.688024)
		(end 390.316974 -33.384998)
		(width 0.089408)
		(layer "In9.Cu")
		(net "FM_ME_RECOVER_N")
	)
	(segment
		(start 380.961138 -88.273382)
		(end 380.961138 -89.739216)
		(width 0.089408)
		(layer "In9.Cu")
		(net "FM_ME_RECOVER_N")
	)
	(segment
		(start 389.516112 -71.12508)
		(end 388.086346 -72.554846)
		(width 0.089408)
		(layer "In9.Cu")
		(net "FM_ME_RECOVER_N")
	)
	(segment
		(start 388.836154 -30.363414)
		(end 388.836154 -31.051246)
		(width 0.089408)
		(layer "In9.Cu")
		(net "FM_ME_RECOVER_N")
	)
	(segment
		(start 390.82472 -47.58055)
		(end 390.82472 -52.07635)
		(width 0.089408)
		(layer "In9.Cu")
		(net "FM_ME_RECOVER_N")
	)
	(segment
		(start 386.16636 -77.531214)
		(end 386.16636 -79.978758)
		(width 0.089408)
		(layer "In9.Cu")
		(net "FM_ME_RECOVER_N")
	)
	(segment
		(start 391.921238 -26.946606)
		(end 391.921238 -27.27833)
		(width 0.089408)
		(layer "In9.Cu")
		(net "FM_ME_RECOVER_N")
	)
	(segment
		(start 390.714484 -65.06845)
		(end 389.108696 -66.674238)
		(width 0.089408)
		(layer "In9.Cu")
		(net "FM_ME_RECOVER_N")
	)
	(segment
		(start 388.086346 -74.075544)
		(end 388.232904 -74.222102)
		(width 0.089408)
		(layer "In9.Cu")
		(net "FM_ME_RECOVER_N")
	)
	(segment
		(start 388.62 -31.2674)
		(end 388.62 -31.688024)
		(width 0.089408)
		(layer "In9.Cu")
		(net "FM_ME_RECOVER_N")
	)
	(segment
		(start 391.442956 -60.660534)
		(end 390.71423 -61.38926)
		(width 0.089408)
		(layer "In9.Cu")
		(net "FM_ME_RECOVER_N")
	)
	(segment
		(start 391.876026 -26.350976)
		(end 391.876026 -26.901394)
		(width 0.089408)
		(layer "In9.Cu")
		(net "FM_ME_RECOVER_N")
	)
	(segment
		(start 390.71423 -64.42456)
		(end 390.714484 -64.424814)
		(width 0.089408)
		(layer "In9.Cu")
		(net "FM_ME_RECOVER_N")
	)
	(segment
		(start 383.3114 -86.882986)
		(end 382.544066 -87.65032)
		(width 0.089408)
		(layer "In9.Cu")
		(net "FM_ME_RECOVER_N")
	)
	(segment
		(start 390.71804 -25.19299)
		(end 391.876026 -26.350976)
		(width 0.089408)
		(layer "In9.Cu")
		(net "FM_ME_RECOVER_N")
	)
	(segment
		(start 391.921238 -27.27833)
		(end 388.836154 -30.363414)
		(width 0.089408)
		(layer "In9.Cu")
		(net "FM_ME_RECOVER_N")
	)
	(segment
		(start 388.232904 -75.46467)
		(end 386.16636 -77.531214)
		(width 0.089408)
		(layer "In9.Cu")
		(net "FM_ME_RECOVER_N")
	)
	(segment
		(start 386.42417 -20.789138)
		(end 387.379464 -21.744432)
		(width 0.089408)
		(layer "In9.Cu")
		(net "FM_ME_RECOVER_N")
	)
	(segment
		(start 386.214874 -20.03552)
		(end 386.42417 -20.244816)
		(width 0.089408)
		(layer "In9.Cu")
		(net "FM_ME_RECOVER_N")
	)
	(segment
		(start 380.961138 -89.739216)
		(end 380.554484 -90.14587)
		(width 0.089408)
		(layer "In9.Cu")
		(net "FM_ME_RECOVER_N")
	)
	(segment
		(start 391.442956 -59.790838)
		(end 391.442956 -60.660534)
		(width 0.089408)
		(layer "In9.Cu")
		(net "FM_ME_RECOVER_N")
	)
	(segment
		(start 391.671048 -40.78224)
		(end 391.671048 -41.486328)
		(width 0.089408)
		(layer "In9.Cu")
		(net "FM_ME_RECOVER_N")
	)
	(segment
		(start 386.47116 -81.397856)
		(end 386.694934 -81.62163)
		(width 0.089408)
		(layer "In9.Cu")
		(net "FM_ME_RECOVER_N")
	)
	(segment
		(start 390.316974 -33.384998)
		(end 390.316974 -35.942016)
		(width 0.089408)
		(layer "In9.Cu")
		(net "FM_ME_RECOVER_N")
	)
	(segment
		(start 389.108696 -66.674238)
		(end 389.108696 -69.660262)
		(width 0.089408)
		(layer "In9.Cu")
		(net "FM_ME_RECOVER_N")
	)
	(segment
		(start 390.947656 -45.21962)
		(end 390.579864 -45.587412)
		(width 0.089408)
		(layer "In9.Cu")
		(net "FM_ME_RECOVER_N")
	)
	(segment
		(start 386.159756 -20.03552)
		(end 386.214874 -20.03552)
		(width 0.089408)
		(layer "In9.Cu")
		(net "FM_ME_RECOVER_N")
	)
	(segment
		(start 390.015984 -21.851112)
		(end 390.71804 -22.553168)
		(width 0.089408)
		(layer "In9.Cu")
		(net "FM_ME_RECOVER_N")
	)
	(segment
		(start 386.694934 -81.62163)
		(end 386.694934 -81.779618)
		(width 0.089408)
		(layer "In9.Cu")
		(net "FM_ME_RECOVER_N")
	)
	(segment
		(start 384.16103 -85.417152)
		(end 383.3114 -86.266782)
		(width 0.089408)
		(layer "In9.Cu")
		(net "FM_ME_RECOVER_N")
	)
	(segment
		(start 389.516112 -70.067678)
		(end 389.516112 -71.12508)
		(width 0.089408)
		(layer "In9.Cu")
		(net "FM_ME_RECOVER_N")
	)
	(segment
		(start 386.47116 -80.283558)
		(end 386.47116 -81.397856)
		(width 0.089408)
		(layer "In9.Cu")
		(net "FM_ME_RECOVER_N")
	)
	(segment
		(start 391.876026 -26.901394)
		(end 391.921238 -26.946606)
		(width 0.089408)
		(layer "In9.Cu")
		(net "FM_ME_RECOVER_N")
	)
	(segment
		(start 392.139424 -40.313864)
		(end 391.671048 -40.78224)
		(width 0.089408)
		(layer "In9.Cu")
		(net "FM_ME_RECOVER_N")
	)
	(segment
		(start 387.379464 -21.744432)
		(end 387.524752 -21.744432)
		(width 0.089408)
		(layer "In9.Cu")
		(net "FM_ME_RECOVER_N")
	)
	(segment
		(start 386.69468 -83.338416)
		(end 384.615944 -85.417152)
		(width 0.089408)
		(layer "In9.Cu")
		(net "FM_ME_RECOVER_N")
	)
	(segment
		(start 388.232904 -74.222102)
		(end 388.232904 -75.46467)
		(width 0.089408)
		(layer "In9.Cu")
		(net "FM_ME_RECOVER_N")
	)
	(segment
		(start 390.579864 -45.587412)
		(end 390.579864 -47.335694)
		(width 0.089408)
		(layer "In9.Cu")
		(net "FM_ME_RECOVER_N")
	)
	(segment
		(start 386.42417 -20.244816)
		(end 386.42417 -20.789138)
		(width 0.089408)
		(layer "In9.Cu")
		(net "FM_ME_RECOVER_N")
	)
	(segment
		(start 390.316974 -35.942016)
		(end 392.139424 -37.764466)
		(width 0.089408)
		(layer "In9.Cu")
		(net "FM_ME_RECOVER_N")
	)
	(segment
		(start 387.524752 -21.744432)
		(end 387.631432 -21.851112)
		(width 0.089408)
		(layer "In9.Cu")
		(net "FM_ME_RECOVER_N")
	)
	(segment
		(start 388.086346 -72.554846)
		(end 388.086346 -74.075544)
		(width 0.089408)
		(layer "In9.Cu")
		(net "FM_ME_RECOVER_N")
	)
	(segment
		(start 390.82472 -52.07635)
		(end 391.51941 -52.77104)
		(width 0.089408)
		(layer "In9.Cu")
		(net "FM_ME_RECOVER_N")
	)
	(segment
		(start 387.631432 -21.851112)
		(end 390.015984 -21.851112)
		(width 0.089408)
		(layer "In9.Cu")
		(net "FM_ME_RECOVER_N")
	)
	(segment
		(start 391.51941 -52.77104)
		(end 391.51941 -59.714384)
		(width 0.089408)
		(layer "In9.Cu")
		(net "FM_ME_RECOVER_N")
	)
	(segment
		(start 390.579864 -47.335694)
		(end 390.82472 -47.58055)
		(width 0.089408)
		(layer "In9.Cu")
		(net "FM_ME_RECOVER_N")
	)
	(segment
		(start 391.51941 -59.714384)
		(end 391.442956 -59.790838)
		(width 0.089408)
		(layer "In9.Cu")
		(net "FM_ME_RECOVER_N")
	)
	(segment
		(start 388.836154 -31.051246)
		(end 388.62 -31.2674)
		(width 0.089408)
		(layer "In9.Cu")
		(net "FM_ME_RECOVER_N")
	)
	(segment
		(start 386.16636 -79.978758)
		(end 386.47116 -80.283558)
		(width 0.089408)
		(layer "In9.Cu")
		(net "FM_ME_RECOVER_N")
	)
	(segment
		(start 384.615944 -85.417152)
		(end 384.16103 -85.417152)
		(width 0.089408)
		(layer "In9.Cu")
		(net "FM_ME_RECOVER_N")
	)
	(segment
		(start 390.71423 -61.38926)
		(end 390.71423 -64.42456)
		(width 0.089408)
		(layer "In9.Cu")
		(net "FM_ME_RECOVER_N")
	)
	(segment
		(start 391.671048 -41.486328)
		(end 390.947656 -42.20972)
		(width 0.089408)
		(layer "In9.Cu")
		(net "FM_ME_RECOVER_N")
	)
	(segment
		(start 400.734784 -104.04221)
		(end 401.029932 -104.04221)
		(width 0.0889)
		(layer "F.Cu")
		(net "FM_BIOS_MRC_DEBUG_MSG_DIS_N")
	)
	(segment
		(start 401.531328 -104.06126)
		(end 402.527262 -104.06126)
		(width 0.0889)
		(layer "F.Cu")
		(net "FM_BIOS_MRC_DEBUG_MSG_DIS_N")
	)
	(segment
		(start 401.117054 -104.119426)
		(end 401.13839 -104.140762)
		(width 0.0889)
		(layer "F.Cu")
		(net "FM_BIOS_MRC_DEBUG_MSG_DIS_N")
	)
	(segment
		(start 411.09011 -40.93464)
		(end 410.69006 -41.33469)
		(width 0.089408)
		(layer "F.Cu")
		(net "FM_BIOS_MRC_DEBUG_MSG_DIS_N")
	)
	(segment
		(start 401.451826 -104.140762)
		(end 401.531328 -104.06126)
		(width 0.0889)
		(layer "F.Cu")
		(net "FM_BIOS_MRC_DEBUG_MSG_DIS_N")
	)
	(segment
		(start 401.029932 -104.04221)
		(end 401.107148 -104.119426)
		(width 0.0889)
		(layer "F.Cu")
		(net "FM_BIOS_MRC_DEBUG_MSG_DIS_N")
	)
	(segment
		(start 400.05 -104.354884)
		(end 400.42211 -104.354884)
		(width 0.0889)
		(layer "F.Cu")
		(net "FM_BIOS_MRC_DEBUG_MSG_DIS_N")
	)
	(segment
		(start 401.13839 -104.140762)
		(end 401.451826 -104.140762)
		(width 0.0889)
		(layer "F.Cu")
		(net "FM_BIOS_MRC_DEBUG_MSG_DIS_N")
	)
	(segment
		(start 401.107148 -104.119426)
		(end 401.117054 -104.119426)
		(width 0.0889)
		(layer "F.Cu")
		(net "FM_BIOS_MRC_DEBUG_MSG_DIS_N")
	)
	(segment
		(start 400.42211 -104.354884)
		(end 400.734784 -104.04221)
		(width 0.0889)
		(layer "F.Cu")
		(net "FM_BIOS_MRC_DEBUG_MSG_DIS_N")
	)
	(segment
		(start 403.107906 -104.641904)
		(end 403.098 -104.641904)
		(width 0.0889)
		(layer "F.Cu")
		(net "FM_BIOS_MRC_DEBUG_MSG_DIS_N")
	)
	(segment
		(start 402.527262 -104.06126)
		(end 403.107906 -104.641904)
		(width 0.0889)
		(layer "F.Cu")
		(net "FM_BIOS_MRC_DEBUG_MSG_DIS_N")
	)
	(via
		(at 403.098 -104.641904)
		(size 0.508)
		(drill 0.254)
		(layers "F.Cu" "B.Cu")
		(net "FM_BIOS_MRC_DEBUG_MSG_DIS_N")
	)
	(via
		(at 407.48585 -41.874186)
		(size 0.6604)
		(drill 0.3302)
		(layers "F.Cu" "B.Cu")
		(net "FM_BIOS_MRC_DEBUG_MSG_DIS_N")
	)
	(via
		(at 410.69006 -41.33469)
		(size 0.4572)
		(drill 0.2032)
		(layers "F.Cu" "B.Cu")
		(net "FM_BIOS_MRC_DEBUG_MSG_DIS_N")
	)
	(via
		(at 409.387294 -54.9275)
		(size 0.508)
		(drill 0.254)
		(layers "F.Cu" "B.Cu")
		(net "FM_BIOS_MRC_DEBUG_MSG_DIS_N")
	)
	(segment
		(start 408.686 -41.529)
		(end 408.686 -41.1226)
		(width 0.10795)
		(layer "B.Cu")
		(net "FM_BIOS_MRC_DEBUG_MSG_DIS_N")
	)
	(segment
		(start 408.964892 -52.374292)
		(end 406.92832 -50.33772)
		(width 0.10795)
		(layer "B.Cu")
		(net "FM_BIOS_MRC_DEBUG_MSG_DIS_N")
	)
	(segment
		(start 406.92832 -50.33772)
		(end 405.3078 -50.33772)
		(width 0.10795)
		(layer "B.Cu")
		(net "FM_BIOS_MRC_DEBUG_MSG_DIS_N")
	)
	(segment
		(start 408.686 -41.1226)
		(end 408.8892 -40.9194)
		(width 0.10795)
		(layer "B.Cu")
		(net "FM_BIOS_MRC_DEBUG_MSG_DIS_N")
	)
	(segment
		(start 403.874732 -48.904652)
		(end 403.874732 -48.008032)
		(width 0.10795)
		(layer "B.Cu")
		(net "FM_BIOS_MRC_DEBUG_MSG_DIS_N")
	)
	(segment
		(start 407.077672 -44.041314)
		(end 407.077672 -43.12793)
		(width 0.10795)
		(layer "B.Cu")
		(net "FM_BIOS_MRC_DEBUG_MSG_DIS_N")
	)
	(segment
		(start 405.175974 -47.446946)
		(end 406.543002 -46.079918)
		(width 0.10795)
		(layer "B.Cu")
		(net "FM_BIOS_MRC_DEBUG_MSG_DIS_N")
	)
	(segment
		(start 405.3078 -50.33772)
		(end 403.874732 -48.904652)
		(width 0.10795)
		(layer "B.Cu")
		(net "FM_BIOS_MRC_DEBUG_MSG_DIS_N")
	)
	(segment
		(start 403.874732 -48.008032)
		(end 404.435818 -47.446946)
		(width 0.10795)
		(layer "B.Cu")
		(net "FM_BIOS_MRC_DEBUG_MSG_DIS_N")
	)
	(segment
		(start 407.557986 -41.80205)
		(end 408.41295 -41.80205)
		(width 0.10795)
		(layer "B.Cu")
		(net "FM_BIOS_MRC_DEBUG_MSG_DIS_N")
	)
	(segment
		(start 410.082746 -40.9194)
		(end 410.498036 -41.33469)
		(width 0.10795)
		(layer "B.Cu")
		(net "FM_BIOS_MRC_DEBUG_MSG_DIS_N")
	)
	(segment
		(start 406.543002 -46.079918)
		(end 406.543002 -44.575984)
		(width 0.10795)
		(layer "B.Cu")
		(net "FM_BIOS_MRC_DEBUG_MSG_DIS_N")
	)
	(segment
		(start 408.41295 -41.80205)
		(end 408.686 -41.529)
		(width 0.10795)
		(layer "B.Cu")
		(net "FM_BIOS_MRC_DEBUG_MSG_DIS_N")
	)
	(segment
		(start 406.543002 -44.575984)
		(end 407.077672 -44.041314)
		(width 0.10795)
		(layer "B.Cu")
		(net "FM_BIOS_MRC_DEBUG_MSG_DIS_N")
	)
	(segment
		(start 410.498036 -41.33469)
		(end 410.69006 -41.33469)
		(width 0.10795)
		(layer "B.Cu")
		(net "FM_BIOS_MRC_DEBUG_MSG_DIS_N")
	)
	(segment
		(start 407.156158 -43.049444)
		(end 407.156158 -43.042078)
		(width 0.10795)
		(layer "B.Cu")
		(net "FM_BIOS_MRC_DEBUG_MSG_DIS_N")
	)
	(segment
		(start 407.48585 -41.874186)
		(end 407.557986 -41.80205)
		(width 0.10795)
		(layer "B.Cu")
		(net "FM_BIOS_MRC_DEBUG_MSG_DIS_N")
	)
	(segment
		(start 409.198064 -54.9275)
		(end 408.964892 -54.694328)
		(width 0.10795)
		(layer "B.Cu")
		(net "FM_BIOS_MRC_DEBUG_MSG_DIS_N")
	)
	(segment
		(start 407.156158 -43.042078)
		(end 407.48585 -42.712386)
		(width 0.10795)
		(layer "B.Cu")
		(net "FM_BIOS_MRC_DEBUG_MSG_DIS_N")
	)
	(segment
		(start 404.435818 -47.446946)
		(end 405.175974 -47.446946)
		(width 0.10795)
		(layer "B.Cu")
		(net "FM_BIOS_MRC_DEBUG_MSG_DIS_N")
	)
	(segment
		(start 407.077672 -43.12793)
		(end 407.156158 -43.049444)
		(width 0.10795)
		(layer "B.Cu")
		(net "FM_BIOS_MRC_DEBUG_MSG_DIS_N")
	)
	(segment
		(start 409.387294 -54.9275)
		(end 409.198064 -54.9275)
		(width 0.10795)
		(layer "B.Cu")
		(net "FM_BIOS_MRC_DEBUG_MSG_DIS_N")
	)
	(segment
		(start 408.8892 -40.9194)
		(end 410.082746 -40.9194)
		(width 0.10795)
		(layer "B.Cu")
		(net "FM_BIOS_MRC_DEBUG_MSG_DIS_N")
	)
	(segment
		(start 408.964892 -54.694328)
		(end 408.964892 -52.374292)
		(width 0.10795)
		(layer "B.Cu")
		(net "FM_BIOS_MRC_DEBUG_MSG_DIS_N")
	)
	(segment
		(start 407.48585 -42.712386)
		(end 407.48585 -41.874186)
		(width 0.10795)
		(layer "B.Cu")
		(net "FM_BIOS_MRC_DEBUG_MSG_DIS_N")
	)
	(segment
		(start 402.214842 -80.771492)
		(end 402.214842 -82.08899)
		(width 0.089408)
		(layer "In2.Cu")
		(net "FM_BIOS_MRC_DEBUG_MSG_DIS_N")
	)
	(segment
		(start 402.083016 -77.843126)
		(end 402.083016 -78.741016)
		(width 0.089408)
		(layer "In2.Cu")
		(net "FM_BIOS_MRC_DEBUG_MSG_DIS_N")
	)
	(segment
		(start 403.651212 -87.395304)
		(end 403.000464 -87.395304)
		(width 0.089408)
		(layer "In2.Cu")
		(net "FM_BIOS_MRC_DEBUG_MSG_DIS_N")
	)
	(segment
		(start 403.839934 -73.728072)
		(end 403.839934 -74.04989)
		(width 0.089408)
		(layer "In2.Cu")
		(net "FM_BIOS_MRC_DEBUG_MSG_DIS_N")
	)
	(segment
		(start 409.41498 -68.153026)
		(end 403.839934 -73.728072)
		(width 0.089408)
		(layer "In2.Cu")
		(net "FM_BIOS_MRC_DEBUG_MSG_DIS_N")
	)
	(segment
		(start 401.423124 -100.794058)
		(end 401.430236 -100.80117)
		(width 0.089408)
		(layer "In2.Cu")
		(net "FM_BIOS_MRC_DEBUG_MSG_DIS_N")
	)
	(segment
		(start 402.39061 -99.132644)
		(end 401.423124 -100.10013)
		(width 0.089408)
		(layer "In2.Cu")
		(net "FM_BIOS_MRC_DEBUG_MSG_DIS_N")
	)
	(segment
		(start 409.41498 -67.032632)
		(end 409.41498 -68.153026)
		(width 0.089408)
		(layer "In2.Cu")
		(net "FM_BIOS_MRC_DEBUG_MSG_DIS_N")
	)
	(segment
		(start 404.496016 -86.5505)
		(end 403.651212 -87.395304)
		(width 0.089408)
		(layer "In2.Cu")
		(net "FM_BIOS_MRC_DEBUG_MSG_DIS_N")
	)
	(segment
		(start 408.3939 -62.37986)
		(end 408.6733 -62.37986)
		(width 0.089408)
		(layer "In2.Cu")
		(net "FM_BIOS_MRC_DEBUG_MSG_DIS_N")
	)
	(segment
		(start 403.839934 -74.04989)
		(end 403.19198 -74.697844)
		(width 0.089408)
		(layer "In2.Cu")
		(net "FM_BIOS_MRC_DEBUG_MSG_DIS_N")
	)
	(segment
		(start 402.06676 -80.62341)
		(end 402.214842 -80.771492)
		(width 0.089408)
		(layer "In2.Cu")
		(net "FM_BIOS_MRC_DEBUG_MSG_DIS_N")
	)
	(segment
		(start 402.06676 -80.170528)
		(end 402.06676 -80.62341)
		(width 0.089408)
		(layer "In2.Cu")
		(net "FM_BIOS_MRC_DEBUG_MSG_DIS_N")
	)
	(segment
		(start 407.4922 -60.674758)
		(end 407.4922 -61.47816)
		(width 0.089408)
		(layer "In2.Cu")
		(net "FM_BIOS_MRC_DEBUG_MSG_DIS_N")
	)
	(segment
		(start 402.083016 -78.741016)
		(end 402.4884 -79.1464)
		(width 0.089408)
		(layer "In2.Cu")
		(net "FM_BIOS_MRC_DEBUG_MSG_DIS_N")
	)
	(segment
		(start 402.082762 -77.842872)
		(end 402.083016 -77.843126)
		(width 0.089408)
		(layer "In2.Cu")
		(net "FM_BIOS_MRC_DEBUG_MSG_DIS_N")
	)
	(segment
		(start 408.6733 -62.37986)
		(end 409.312364 -63.018924)
		(width 0.089408)
		(layer "In2.Cu")
		(net "FM_BIOS_MRC_DEBUG_MSG_DIS_N")
	)
	(segment
		(start 404.496016 -84.043266)
		(end 404.496016 -86.5505)
		(width 0.089408)
		(layer "In2.Cu")
		(net "FM_BIOS_MRC_DEBUG_MSG_DIS_N")
	)
	(segment
		(start 402.39061 -92.949268)
		(end 402.39061 -99.132644)
		(width 0.089408)
		(layer "In2.Cu")
		(net "FM_BIOS_MRC_DEBUG_MSG_DIS_N")
	)
	(segment
		(start 402.082762 -77.684884)
		(end 402.082762 -77.842872)
		(width 0.089408)
		(layer "In2.Cu")
		(net "FM_BIOS_MRC_DEBUG_MSG_DIS_N")
	)
	(segment
		(start 404.149814 -83.697064)
		(end 404.496016 -84.043266)
		(width 0.089408)
		(layer "In2.Cu")
		(net "FM_BIOS_MRC_DEBUG_MSG_DIS_N")
	)
	(segment
		(start 408.263852 -59.903106)
		(end 407.4922 -60.674758)
		(width 0.089408)
		(layer "In2.Cu")
		(net "FM_BIOS_MRC_DEBUG_MSG_DIS_N")
	)
	(segment
		(start 401.430236 -100.80117)
		(end 401.430236 -103.195882)
		(width 0.089408)
		(layer "In2.Cu")
		(net "FM_BIOS_MRC_DEBUG_MSG_DIS_N")
	)
	(segment
		(start 407.4922 -61.47816)
		(end 408.3939 -62.37986)
		(width 0.089408)
		(layer "In2.Cu")
		(net "FM_BIOS_MRC_DEBUG_MSG_DIS_N")
	)
	(segment
		(start 403.822916 -83.697064)
		(end 404.149814 -83.697064)
		(width 0.089408)
		(layer "In2.Cu")
		(net "FM_BIOS_MRC_DEBUG_MSG_DIS_N")
	)
	(segment
		(start 408.263852 -56.050942)
		(end 408.263852 -59.903106)
		(width 0.089408)
		(layer "In2.Cu")
		(net "FM_BIOS_MRC_DEBUG_MSG_DIS_N")
	)
	(segment
		(start 401.423124 -100.10013)
		(end 401.423124 -100.794058)
		(width 0.089408)
		(layer "In2.Cu")
		(net "FM_BIOS_MRC_DEBUG_MSG_DIS_N")
	)
	(segment
		(start 409.387294 -54.9275)
		(end 408.263852 -56.050942)
		(width 0.089408)
		(layer "In2.Cu")
		(net "FM_BIOS_MRC_DEBUG_MSG_DIS_N")
	)
	(segment
		(start 403.000464 -87.395304)
		(end 401.877276 -88.518492)
		(width 0.089408)
		(layer "In2.Cu")
		(net "FM_BIOS_MRC_DEBUG_MSG_DIS_N")
	)
	(segment
		(start 401.430236 -103.195882)
		(end 402.876258 -104.641904)
		(width 0.089408)
		(layer "In2.Cu")
		(net "FM_BIOS_MRC_DEBUG_MSG_DIS_N")
	)
	(segment
		(start 402.4884 -79.1464)
		(end 402.4884 -79.748888)
		(width 0.089408)
		(layer "In2.Cu")
		(net "FM_BIOS_MRC_DEBUG_MSG_DIS_N")
	)
	(segment
		(start 402.214842 -82.08899)
		(end 403.822916 -83.697064)
		(width 0.089408)
		(layer "In2.Cu")
		(net "FM_BIOS_MRC_DEBUG_MSG_DIS_N")
	)
	(segment
		(start 409.312364 -66.930016)
		(end 409.41498 -67.032632)
		(width 0.089408)
		(layer "In2.Cu")
		(net "FM_BIOS_MRC_DEBUG_MSG_DIS_N")
	)
	(segment
		(start 401.877276 -92.435934)
		(end 402.39061 -92.949268)
		(width 0.089408)
		(layer "In2.Cu")
		(net "FM_BIOS_MRC_DEBUG_MSG_DIS_N")
	)
	(segment
		(start 409.312364 -63.018924)
		(end 409.312364 -66.930016)
		(width 0.089408)
		(layer "In2.Cu")
		(net "FM_BIOS_MRC_DEBUG_MSG_DIS_N")
	)
	(segment
		(start 403.19198 -76.575666)
		(end 402.082762 -77.684884)
		(width 0.089408)
		(layer "In2.Cu")
		(net "FM_BIOS_MRC_DEBUG_MSG_DIS_N")
	)
	(segment
		(start 403.19198 -74.697844)
		(end 403.19198 -76.575666)
		(width 0.089408)
		(layer "In2.Cu")
		(net "FM_BIOS_MRC_DEBUG_MSG_DIS_N")
	)
	(segment
		(start 401.877276 -88.518492)
		(end 401.877276 -92.435934)
		(width 0.089408)
		(layer "In2.Cu")
		(net "FM_BIOS_MRC_DEBUG_MSG_DIS_N")
	)
	(segment
		(start 402.4884 -79.748888)
		(end 402.06676 -80.170528)
		(width 0.089408)
		(layer "In2.Cu")
		(net "FM_BIOS_MRC_DEBUG_MSG_DIS_N")
	)
	(segment
		(start 402.876258 -104.641904)
		(end 403.098 -104.641904)
		(width 0.089408)
		(layer "In2.Cu")
		(net "FM_BIOS_MRC_DEBUG_MSG_DIS_N")
	)
	(segment
		(start 480.812602 -58.010298)
		(end 480.812602 -58.772298)
		(width 0.10795)
		(layer "B.Cu")
		(net "FM_ALL_WAKE_N")
	)
	(segment
		(start 481.971858 -56.647842)
		(end 481.77069 -56.84901)
		(width 0.10795)
		(layer "B.Cu")
		(net "FM_ALL_WAKE_N")
	)
	(segment
		(start 480.5553 -57.1754)
		(end 480.5553 -57.4675)
		(width 0.10795)
		(layer "B.Cu")
		(net "FM_ALL_WAKE_N")
	)
	(segment
		(start 481.77069 -58.069988)
		(end 481.77069 -57.307988)
		(width 0.10795)
		(layer "B.Cu")
		(net "FM_ALL_WAKE_N")
	)
	(segment
		(start 481.971858 -56.090058)
		(end 481.971858 -56.647842)
		(width 0.10795)
		(layer "B.Cu")
		(net "FM_ALL_WAKE_N")
	)
	(segment
		(start 480.5553 -57.4675)
		(end 480.812602 -57.724802)
		(width 0.10795)
		(layer "B.Cu")
		(net "FM_ALL_WAKE_N")
	)
	(segment
		(start 481.77069 -58.831988)
		(end 481.77069 -58.069988)
		(width 0.10795)
		(layer "B.Cu")
		(net "FM_ALL_WAKE_N")
	)
	(segment
		(start 480.872292 -58.831988)
		(end 480.812602 -58.772298)
		(width 0.10795)
		(layer "B.Cu")
		(net "FM_ALL_WAKE_N")
	)
	(segment
		(start 481.77069 -58.831988)
		(end 480.872292 -58.831988)
		(width 0.10795)
		(layer "B.Cu")
		(net "FM_ALL_WAKE_N")
	)
	(segment
		(start 481.77069 -56.84901)
		(end 481.77069 -57.307988)
		(width 0.10795)
		(layer "B.Cu")
		(net "FM_ALL_WAKE_N")
	)
	(segment
		(start 480.812602 -57.724802)
		(end 480.812602 -58.010298)
		(width 0.10795)
		(layer "B.Cu")
		(net "FM_ALL_WAKE_N")
	)
	(via
		(at 416.814 -9.017)
		(size 0.6604)
		(drill 0.3302)
		(layers "F.Cu" "B.Cu")
		(net "VSENSE_P12V_ADM1085")
	)
	(segment
		(start 418.274754 -8.1915)
		(end 418.577268 -7.888986)
		(width 0.254)
		(layer "B.Cu")
		(net "VSENSE_P12V_ADM1085")
	)
	(segment
		(start 418.577268 -7.888986)
		(end 419.4175 -7.888986)
		(width 0.254)
		(layer "B.Cu")
		(net "VSENSE_P12V_ADM1085")
	)
	(segment
		(start 417.576 -8.1915)
		(end 418.274754 -8.1915)
		(width 0.254)
		(layer "B.Cu")
		(net "VSENSE_P12V_ADM1085")
	)
	(segment
		(start 416.814 -9.017)
		(end 417.83 -9.017)
		(width 0.254)
		(layer "B.Cu")
		(net "VSENSE_P12V_ADM1085")
	)
	(segment
		(start 417.576 -8.1915)
		(end 417.097464 -8.1915)
		(width 0.254)
		(layer "B.Cu")
		(net "VSENSE_P12V_ADM1085")
	)
	(segment
		(start 417.097464 -8.1915)
		(end 416.814 -8.474964)
		(width 0.254)
		(layer "B.Cu")
		(net "VSENSE_P12V_ADM1085")
	)
	(segment
		(start 416.814 -8.474964)
		(end 416.814 -9.017)
		(width 0.254)
		(layer "B.Cu")
		(net "VSENSE_P12V_ADM1085")
	)
	(via
		(at 414.401 -3.0988)
		(size 0.6604)
		(drill 0.3302)
		(layers "F.Cu" "B.Cu")
		(net "PWRGD_P5V_R")
	)
	(segment
		(start 415.0995 -6.4516)
		(end 415.798 -7.1501)
		(width 0.10795)
		(layer "B.Cu")
		(net "PWRGD_P5V_R")
	)
	(segment
		(start 414.2105 -4.318)
		(end 414.2105 -3.2893)
		(width 0.10795)
		(layer "B.Cu")
		(net "PWRGD_P5V_R")
	)
	(segment
		(start 414.2105 -4.318)
		(end 415.0995 -4.318)
		(width 0.10795)
		(layer "B.Cu")
		(net "PWRGD_P5V_R")
	)
	(segment
		(start 414.2105 -3.2893)
		(end 414.401 -3.0988)
		(width 0.10795)
		(layer "B.Cu")
		(net "PWRGD_P5V_R")
	)
	(segment
		(start 415.0995 -4.318)
		(end 415.0995 -6.4516)
		(width 0.10795)
		(layer "B.Cu")
		(net "PWRGD_P5V_R")
	)
	(segment
		(start 374.744996 -74.69505)
		(end 375.144792 -75.094846)
		(width 0.1016)
		(layer "F.Cu")
		(net "PWRGD_P5V")
	)
	(via
		(at 385.359148 -20.011136)
		(size 0.508)
		(drill 0.254)
		(layers "F.Cu" "B.Cu")
		(net "PWRGD_P5V")
	)
	(via
		(at 384.0226 -8.6614)
		(size 0.6604)
		(drill 0.3302)
		(layers "F.Cu" "B.Cu")
		(net "PWRGD_P5V")
	)
	(via
		(at 375.144792 -75.094846)
		(size 0.4572)
		(drill 0.2032)
		(layers "F.Cu" "B.Cu")
		(net "PWRGD_P5V")
	)
	(segment
		(start 413.34309 -1.542796)
		(end 413.528002 -1.357884)
		(width 0.10795)
		(layer "B.Cu")
		(net "PWRGD_P5V")
	)
	(segment
		(start 385.359148 -20.011136)
		(end 384.730752 -19.38274)
		(width 0.10795)
		(layer "B.Cu")
		(net "PWRGD_P5V")
	)
	(segment
		(start 413.807402 -3.311398)
		(end 413.807402 -2.388616)
		(width 0.10795)
		(layer "B.Cu")
		(net "PWRGD_P5V")
	)
	(segment
		(start 385.208018 -0.406654)
		(end 385.002532 -0.406654)
		(width 0.10795)
		(layer "B.Cu")
		(net "PWRGD_P5V")
	)
	(segment
		(start 413.3215 -3.7973)
		(end 413.807402 -3.311398)
		(width 0.10795)
		(layer "B.Cu")
		(net "PWRGD_P5V")
	)
	(segment
		(start 413.528002 -1.357884)
		(end 413.528002 1.5113)
		(width 0.10795)
		(layer "B.Cu")
		(net "PWRGD_P5V")
	)
	(segment
		(start 411.963616 3.681984)
		(end 410.817314 4.828286)
		(width 0.10795)
		(layer "B.Cu")
		(net "PWRGD_P5V")
	)
	(segment
		(start 413.807402 -2.388616)
		(end 413.34309 -1.924304)
		(width 0.10795)
		(layer "B.Cu")
		(net "PWRGD_P5V")
	)
	(segment
		(start 413.34309 -1.924304)
		(end 413.34309 -1.542796)
		(width 0.10795)
		(layer "B.Cu")
		(net "PWRGD_P5V")
	)
	(segment
		(start 382.648714 0.623316)
		(end 380.615952 -1.409446)
		(width 0.10795)
		(layer "B.Cu")
		(net "PWRGD_P5V")
	)
	(segment
		(start 384.0226 -9.622536)
		(end 384.0226 -8.6614)
		(width 0.10795)
		(layer "B.Cu")
		(net "PWRGD_P5V")
	)
	(segment
		(start 413.3215 -4.318)
		(end 413.3215 -3.7973)
		(width 0.10795)
		(layer "B.Cu")
		(net "PWRGD_P5V")
	)
	(segment
		(start 410.817314 4.828286)
		(end 394.58265 4.828286)
		(width 0.10795)
		(layer "B.Cu")
		(net "PWRGD_P5V")
	)
	(segment
		(start 394.58265 4.828286)
		(end 393.5857 3.831336)
		(width 0.10795)
		(layer "B.Cu")
		(net "PWRGD_P5V")
	)
	(segment
		(start 382.6002 -6.5532)
		(end 384.0226 -7.9756)
		(width 0.10795)
		(layer "B.Cu")
		(net "PWRGD_P5V")
	)
	(segment
		(start 413.528002 1.5113)
		(end 411.963616 3.075686)
		(width 0.10795)
		(layer "B.Cu")
		(net "PWRGD_P5V")
	)
	(segment
		(start 389.601202 -0.4064)
		(end 385.208272 -0.4064)
		(width 0.10795)
		(layer "B.Cu")
		(net "PWRGD_P5V")
	)
	(segment
		(start 384.730752 -10.330688)
		(end 384.0226 -9.622536)
		(width 0.10795)
		(layer "B.Cu")
		(net "PWRGD_P5V")
	)
	(segment
		(start 385.002532 -0.406654)
		(end 383.972562 0.623316)
		(width 0.10795)
		(layer "B.Cu")
		(net "PWRGD_P5V")
	)
	(segment
		(start 393.5857 3.831336)
		(end 393.5857 3.578098)
		(width 0.10795)
		(layer "B.Cu")
		(net "PWRGD_P5V")
	)
	(segment
		(start 380.615952 -6.092952)
		(end 381.0762 -6.5532)
		(width 0.10795)
		(layer "B.Cu")
		(net "PWRGD_P5V")
	)
	(segment
		(start 411.963616 3.075686)
		(end 411.963616 3.681984)
		(width 0.10795)
		(layer "B.Cu")
		(net "PWRGD_P5V")
	)
	(segment
		(start 393.5857 3.578098)
		(end 389.601202 -0.4064)
		(width 0.10795)
		(layer "B.Cu")
		(net "PWRGD_P5V")
	)
	(segment
		(start 384.0226 -7.9756)
		(end 384.0226 -8.6614)
		(width 0.10795)
		(layer "B.Cu")
		(net "PWRGD_P5V")
	)
	(segment
		(start 380.615952 -1.409446)
		(end 380.615952 -6.092952)
		(width 0.10795)
		(layer "B.Cu")
		(net "PWRGD_P5V")
	)
	(segment
		(start 383.972562 0.623316)
		(end 382.648714 0.623316)
		(width 0.10795)
		(layer "B.Cu")
		(net "PWRGD_P5V")
	)
	(segment
		(start 385.208272 -0.4064)
		(end 385.208018 -0.406654)
		(width 0.10795)
		(layer "B.Cu")
		(net "PWRGD_P5V")
	)
	(segment
		(start 381.0762 -6.5532)
		(end 382.6002 -6.5532)
		(width 0.10795)
		(layer "B.Cu")
		(net "PWRGD_P5V")
	)
	(segment
		(start 384.730752 -19.38274)
		(end 384.730752 -10.330688)
		(width 0.10795)
		(layer "B.Cu")
		(net "PWRGD_P5V")
	)
	(segment
		(start 381.177038 -44.383452)
		(end 381.177292 -44.383198)
		(width 0.089408)
		(layer "In9.Cu")
		(net "PWRGD_P5V")
	)
	(segment
		(start 377.11507 -63.389764)
		(end 377.82754 -63.389764)
		(width 0.089408)
		(layer "In9.Cu")
		(net "PWRGD_P5V")
	)
	(segment
		(start 374.771412 -69.340476)
		(end 375.023888 -69.088)
		(width 0.089408)
		(layer "In9.Cu")
		(net "PWRGD_P5V")
	)
	(segment
		(start 380.111 -37.07765)
		(end 380.111 -35.162744)
		(width 0.089408)
		(layer "In9.Cu")
		(net "PWRGD_P5V")
	)
	(segment
		(start 378.681488 -41.01338)
		(end 378.864876 -40.829992)
		(width 0.089408)
		(layer "In9.Cu")
		(net "PWRGD_P5V")
	)
	(segment
		(start 384.058668 -25.654762)
		(end 384.058922 -25.655016)
		(width 0.089408)
		(layer "In9.Cu")
		(net "PWRGD_P5V")
	)
	(segment
		(start 375.302272 -68.32473)
		(end 375.302272 -67.681348)
		(width 0.089408)
		(layer "In9.Cu")
		(net "PWRGD_P5V")
	)
	(segment
		(start 378.476256 -62.237112)
		(end 378.476002 -62.236858)
		(width 0.089408)
		(layer "In9.Cu")
		(net "PWRGD_P5V")
	)
	(segment
		(start 379.45568 -39.632128)
		(end 380.246636 -39.632128)
		(width 0.089408)
		(layer "In9.Cu")
		(net "PWRGD_P5V")
	)
	(segment
		(start 381.176784 -44.541694)
		(end 381.177038 -44.54144)
		(width 0.089408)
		(layer "In9.Cu")
		(net "PWRGD_P5V")
	)
	(segment
		(start 378.476002 -62.236858)
		(end 378.476002 -59.549284)
		(width 0.089408)
		(layer "In9.Cu")
		(net "PWRGD_P5V")
	)
	(segment
		(start 384.058922 -25.655016)
		(end 384.21691 -25.655016)
		(width 0.089408)
		(layer "In9.Cu")
		(net "PWRGD_P5V")
	)
	(segment
		(start 381.177038 -44.54144)
		(end 381.177038 -44.383452)
		(width 0.089408)
		(layer "In9.Cu")
		(net "PWRGD_P5V")
	)
	(segment
		(start 381.176784 -44.066206)
		(end 381.176784 -44.04741)
		(width 0.089408)
		(layer "In9.Cu")
		(net "PWRGD_P5V")
	)
	(segment
		(start 375.280174 -69.088)
		(end 375.518172 -68.850002)
		(width 0.089408)
		(layer "In9.Cu")
		(net "PWRGD_P5V")
	)
	(segment
		(start 376.344688 -64.160146)
		(end 377.11507 -63.389764)
		(width 0.089408)
		(layer "In9.Cu")
		(net "PWRGD_P5V")
	)
	(segment
		(start 374.771412 -70.396608)
		(end 374.771412 -69.340476)
		(width 0.089408)
		(layer "In9.Cu")
		(net "PWRGD_P5V")
	)
	(segment
		(start 375.144792 -75.094846)
		(end 373.971312 -73.921366)
		(width 0.089408)
		(layer "In9.Cu")
		(net "PWRGD_P5V")
	)
	(segment
		(start 375.302272 -67.681348)
		(end 376.344688 -66.638932)
		(width 0.089408)
		(layer "In9.Cu")
		(net "PWRGD_P5V")
	)
	(segment
		(start 384.21691 -25.655016)
		(end 385.475988 -24.395938)
		(width 0.089408)
		(layer "In9.Cu")
		(net "PWRGD_P5V")
	)
	(segment
		(start 379.975872 -51.186334)
		(end 379.975872 -46.692566)
		(width 0.089408)
		(layer "In9.Cu")
		(net "PWRGD_P5V")
	)
	(segment
		(start 379.847094 -51.315112)
		(end 379.975872 -51.186334)
		(width 0.089408)
		(layer "In9.Cu")
		(net "PWRGD_P5V")
	)
	(segment
		(start 379.975872 -46.692566)
		(end 381.176784 -45.491654)
		(width 0.089408)
		(layer "In9.Cu")
		(net "PWRGD_P5V")
	)
	(segment
		(start 378.30379 -62.913514)
		(end 378.30379 -62.486286)
		(width 0.089408)
		(layer "In9.Cu")
		(net "PWRGD_P5V")
	)
	(segment
		(start 379.052836 -41.923462)
		(end 379.03404 -41.923462)
		(width 0.089408)
		(layer "In9.Cu")
		(net "PWRGD_P5V")
	)
	(segment
		(start 381.55626 -34.350452)
		(end 382.045718 -33.860994)
		(width 0.089408)
		(layer "In9.Cu")
		(net "PWRGD_P5V")
	)
	(segment
		(start 373.971312 -70.940422)
		(end 374.243092 -70.668642)
		(width 0.089408)
		(layer "In9.Cu")
		(net "PWRGD_P5V")
	)
	(segment
		(start 378.476256 -62.31382)
		(end 378.476256 -62.237112)
		(width 0.089408)
		(layer "In9.Cu")
		(net "PWRGD_P5V")
	)
	(segment
		(start 375.518172 -68.54063)
		(end 375.302272 -68.32473)
		(width 0.089408)
		(layer "In9.Cu")
		(net "PWRGD_P5V")
	)
	(segment
		(start 378.864876 -40.222932)
		(end 379.45568 -39.632128)
		(width 0.089408)
		(layer "In9.Cu")
		(net "PWRGD_P5V")
	)
	(segment
		(start 385.122166 -21.26234)
		(end 385.122166 -20.248118)
		(width 0.089408)
		(layer "In9.Cu")
		(net "PWRGD_P5V")
	)
	(segment
		(start 380.422404 -39.45636)
		(end 380.422404 -37.389054)
		(width 0.089408)
		(layer "In9.Cu")
		(net "PWRGD_P5V")
	)
	(segment
		(start 375.023888 -69.088)
		(end 375.280174 -69.088)
		(width 0.089408)
		(layer "In9.Cu")
		(net "PWRGD_P5V")
	)
	(segment
		(start 381.176784 -45.491654)
		(end 381.176784 -44.541694)
		(width 0.089408)
		(layer "In9.Cu")
		(net "PWRGD_P5V")
	)
	(segment
		(start 385.475988 -24.395938)
		(end 385.475988 -22.946614)
		(width 0.089408)
		(layer "In9.Cu")
		(net "PWRGD_P5V")
	)
	(segment
		(start 378.476002 -59.549284)
		(end 379.945646 -58.07964)
		(width 0.089408)
		(layer "In9.Cu")
		(net "PWRGD_P5V")
	)
	(segment
		(start 381.177292 -44.066714)
		(end 381.176784 -44.066206)
		(width 0.089408)
		(layer "In9.Cu")
		(net "PWRGD_P5V")
	)
	(segment
		(start 374.499378 -70.668642)
		(end 374.771412 -70.396608)
		(width 0.089408)
		(layer "In9.Cu")
		(net "PWRGD_P5V")
	)
	(segment
		(start 374.243092 -70.668642)
		(end 374.499378 -70.668642)
		(width 0.089408)
		(layer "In9.Cu")
		(net "PWRGD_P5V")
	)
	(segment
		(start 385.122166 -20.248118)
		(end 385.359148 -20.011136)
		(width 0.089408)
		(layer "In9.Cu")
		(net "PWRGD_P5V")
	)
	(segment
		(start 379.847094 -55.304436)
		(end 379.847094 -51.315112)
		(width 0.089408)
		(layer "In9.Cu")
		(net "PWRGD_P5V")
	)
	(segment
		(start 380.111 -35.162744)
		(end 380.923292 -34.350452)
		(width 0.089408)
		(layer "In9.Cu")
		(net "PWRGD_P5V")
	)
	(segment
		(start 378.864876 -40.829992)
		(end 378.864876 -40.222932)
		(width 0.089408)
		(layer "In9.Cu")
		(net "PWRGD_P5V")
	)
	(segment
		(start 381.177292 -44.383198)
		(end 381.177292 -44.066714)
		(width 0.089408)
		(layer "In9.Cu")
		(net "PWRGD_P5V")
	)
	(segment
		(start 376.344688 -66.638932)
		(end 376.344688 -64.160146)
		(width 0.089408)
		(layer "In9.Cu")
		(net "PWRGD_P5V")
	)
	(segment
		(start 383.598166 -25.654762)
		(end 384.058668 -25.654762)
		(width 0.089408)
		(layer "In9.Cu")
		(net "PWRGD_P5V")
	)
	(segment
		(start 378.30379 -62.486286)
		(end 378.476256 -62.31382)
		(width 0.089408)
		(layer "In9.Cu")
		(net "PWRGD_P5V")
	)
	(segment
		(start 382.045718 -33.860994)
		(end 382.045718 -32.69234)
		(width 0.089408)
		(layer "In9.Cu")
		(net "PWRGD_P5V")
	)
	(segment
		(start 375.518172 -68.850002)
		(end 375.518172 -68.54063)
		(width 0.089408)
		(layer "In9.Cu")
		(net "PWRGD_P5V")
	)
	(segment
		(start 373.971312 -73.921366)
		(end 373.971312 -70.940422)
		(width 0.089408)
		(layer "In9.Cu")
		(net "PWRGD_P5V")
	)
	(segment
		(start 379.945646 -55.402988)
		(end 379.847094 -55.304436)
		(width 0.089408)
		(layer "In9.Cu")
		(net "PWRGD_P5V")
	)
	(segment
		(start 378.681488 -41.57091)
		(end 378.681488 -41.01338)
		(width 0.089408)
		(layer "In9.Cu")
		(net "PWRGD_P5V")
	)
	(segment
		(start 381.176784 -44.04741)
		(end 379.052836 -41.923462)
		(width 0.089408)
		(layer "In9.Cu")
		(net "PWRGD_P5V")
	)
	(segment
		(start 382.045718 -32.69234)
		(end 382.189482 -32.548576)
		(width 0.089408)
		(layer "In9.Cu")
		(net "PWRGD_P5V")
	)
	(segment
		(start 382.189482 -32.548576)
		(end 382.189482 -27.063446)
		(width 0.089408)
		(layer "In9.Cu")
		(net "PWRGD_P5V")
	)
	(segment
		(start 379.945646 -58.07964)
		(end 379.945646 -55.402988)
		(width 0.089408)
		(layer "In9.Cu")
		(net "PWRGD_P5V")
	)
	(segment
		(start 380.422404 -37.389054)
		(end 380.111 -37.07765)
		(width 0.089408)
		(layer "In9.Cu")
		(net "PWRGD_P5V")
	)
	(segment
		(start 380.923292 -34.350452)
		(end 381.55626 -34.350452)
		(width 0.089408)
		(layer "In9.Cu")
		(net "PWRGD_P5V")
	)
	(segment
		(start 377.82754 -63.389764)
		(end 378.30379 -62.913514)
		(width 0.089408)
		(layer "In9.Cu")
		(net "PWRGD_P5V")
	)
	(segment
		(start 380.246636 -39.632128)
		(end 380.422404 -39.45636)
		(width 0.089408)
		(layer "In9.Cu")
		(net "PWRGD_P5V")
	)
	(segment
		(start 385.310634 -22.78126)
		(end 385.310634 -21.450808)
		(width 0.089408)
		(layer "In9.Cu")
		(net "PWRGD_P5V")
	)
	(segment
		(start 385.475988 -22.946614)
		(end 385.310634 -22.78126)
		(width 0.089408)
		(layer "In9.Cu")
		(net "PWRGD_P5V")
	)
	(segment
		(start 385.310634 -21.450808)
		(end 385.122166 -21.26234)
		(width 0.089408)
		(layer "In9.Cu")
		(net "PWRGD_P5V")
	)
	(segment
		(start 379.03404 -41.923462)
		(end 378.681488 -41.57091)
		(width 0.089408)
		(layer "In9.Cu")
		(net "PWRGD_P5V")
	)
	(segment
		(start 382.189482 -27.063446)
		(end 383.598166 -25.654762)
		(width 0.089408)
		(layer "In9.Cu")
		(net "PWRGD_P5V")
	)
	(segment
		(start 474.472 -146.8628)
		(end 474.3196 -146.7104)
		(width 0.10795)
		(layer "F.Cu")
		(net "PWRGD_P3V3_R1")
	)
	(segment
		(start 474.3196 -146.7104)
		(end 474.3196 -145.8849)
		(width 0.10795)
		(layer "F.Cu")
		(net "PWRGD_P3V3_R1")
	)
	(segment
		(start 474.472 -147.5105)
		(end 474.472 -146.8628)
		(width 0.10795)
		(layer "F.Cu")
		(net "PWRGD_P3V3_R1")
	)
	(segment
		(start 473.660216 -32.961834)
		(end 473.108528 -33.513522)
		(width 0.10795)
		(layer "F.Cu")
		(net "CLK_50M_CKMNG_OCP_R")
	)
	(segment
		(start 473.108528 -33.513522)
		(end 473.108528 -34.895028)
		(width 0.10795)
		(layer "F.Cu")
		(net "CLK_50M_CKMNG_OCP_R")
	)
	(segment
		(start 473.108528 -34.895028)
		(end 473.292932 -35.079432)
		(width 0.10795)
		(layer "F.Cu")
		(net "CLK_50M_CKMNG_OCP_R")
	)
	(segment
		(start 473.67825 -35.46475)
		(end 473.80525 -35.46475)
		(width 0.10795)
		(layer "F.Cu")
		(net "CLK_50M_CKMNG_OCP_R")
	)
	(segment
		(start 473.80525 -35.46475)
		(end 474.091 -35.7505)
		(width 0.10795)
		(layer "F.Cu")
		(net "CLK_50M_CKMNG_OCP_R")
	)
	(segment
		(start 474.7895 -32.11068)
		(end 474.199966 -32.11068)
		(width 0.10795)
		(layer "F.Cu")
		(net "CLK_50M_CKMNG_OCP_R")
	)
	(segment
		(start 473.660216 -32.65043)
		(end 473.660216 -32.961834)
		(width 0.10795)
		(layer "F.Cu")
		(net "CLK_50M_CKMNG_OCP_R")
	)
	(segment
		(start 473.292932 -35.079432)
		(end 473.67825 -35.46475)
		(width 0.10795)
		(layer "F.Cu")
		(net "CLK_50M_CKMNG_OCP_R")
	)
	(segment
		(start 474.199966 -32.11068)
		(end 473.660216 -32.65043)
		(width 0.10795)
		(layer "F.Cu")
		(net "CLK_50M_CKMNG_OCP_R")
	)
	(via
		(at 473.292932 -35.079432)
		(size 0.508)
		(drill 0.254)
		(layers "F.Cu" "B.Cu")
		(net "CLK_50M_CKMNG_OCP_R")
	)
	(via
		(at 424.053 -7.239)
		(size 0.6604)
		(drill 0.3302)
		(layers "F.Cu" "B.Cu")
		(net "A_ADM1085_CEXT")
	)
	(segment
		(start 423.7355 -7.5565)
		(end 422.91 -7.5565)
		(width 0.254)
		(layer "B.Cu")
		(net "A_ADM1085_CEXT")
	)
	(segment
		(start 422.91 -7.5565)
		(end 422.3893 -7.5565)
		(width 0.254)
		(layer "B.Cu")
		(net "A_ADM1085_CEXT")
	)
	(segment
		(start 424.053 -7.239)
		(end 423.7355 -7.5565)
		(width 0.254)
		(layer "B.Cu")
		(net "A_ADM1085_CEXT")
	)
	(segment
		(start 422.3893 -7.5565)
		(end 422.0718 -7.239)
		(width 0.254)
		(layer "B.Cu")
		(net "A_ADM1085_CEXT")
	)
	(segment
		(start 422.0718 -7.239)
		(end 421.3225 -7.239)
		(width 0.254)
		(layer "B.Cu")
		(net "A_ADM1085_CEXT")
	)
	(segment
		(start 400.21383 -80.053434)
		(end 400.21383 -80.4291)
		(width 0.10795)
		(layer "F.Cu")
		(net "SPI_PCH_CLK")
	)
	(segment
		(start 402.087334 -75.841352)
		(end 401.7772 -76.151486)
		(width 0.10795)
		(layer "F.Cu")
		(net "SPI_PCH_CLK")
	)
	(segment
		(start 399.198846 -80.53705)
		(end 399.090896 -80.645)
		(width 0.10795)
		(layer "F.Cu")
		(net "SPI_PCH_CLK")
	)
	(segment
		(start 404.271988 -73.4187)
		(end 402.62175 -75.068938)
		(width 0.10795)
		(layer "F.Cu")
		(net "SPI_PCH_CLK")
	)
	(segment
		(start 405.030178 -72.66051)
		(end 403.80793 -72.66051)
		(width 0.10795)
		(layer "F.Cu")
		(net "SPI_PCH_CLK")
	)
	(segment
		(start 401.7772 -78.492096)
		(end 401.604226 -78.66507)
		(width 0.10795)
		(layer "F.Cu")
		(net "SPI_PCH_CLK")
	)
	(segment
		(start 408.3304 -69.360288)
		(end 405.030178 -72.66051)
		(width 0.10795)
		(layer "F.Cu")
		(net "SPI_PCH_CLK")
	)
	(segment
		(start 400.531838 -79.582518)
		(end 400.531838 -79.735426)
		(width 0.10795)
		(layer "F.Cu")
		(net "SPI_PCH_CLK")
	)
	(segment
		(start 408.3304 -68.374768)
		(end 408.43835 -68.482718)
		(width 0.10795)
		(layer "F.Cu")
		(net "SPI_PCH_CLK")
	)
	(segment
		(start 399.090896 -80.847946)
		(end 399.198846 -80.955896)
		(width 0.10795)
		(layer "F.Cu")
		(net "SPI_PCH_CLK")
	)
	(segment
		(start 401.562062 -76.656946)
		(end 401.454112 -76.764896)
		(width 0.10795)
		(layer "F.Cu")
		(net "SPI_PCH_CLK")
	)
	(segment
		(start 408.3304 -69.022468)
		(end 408.3304 -69.360288)
		(width 0.10795)
		(layer "F.Cu")
		(net "SPI_PCH_CLK")
	)
	(segment
		(start 402.839428 -73.78192)
		(end 402.992082 -73.934574)
		(width 0.10795)
		(layer "F.Cu")
		(net "SPI_PCH_CLK")
	)
	(segment
		(start 408.643328 -68.590668)
		(end 408.643328 -68.806568)
		(width 0.10795)
		(layer "F.Cu")
		(net "SPI_PCH_CLK")
	)
	(segment
		(start 400.877786 -78.55331)
		(end 400.877786 -78.706218)
		(width 0.10795)
		(layer "F.Cu")
		(net "SPI_PCH_CLK")
	)
	(segment
		(start 408.535378 -68.482718)
		(end 408.643328 -68.590668)
		(width 0.10795)
		(layer "F.Cu")
		(net "SPI_PCH_CLK")
	)
	(segment
		(start 403.80793 -72.66051)
		(end 402.839428 -73.629012)
		(width 0.10795)
		(layer "F.Cu")
		(net "SPI_PCH_CLK")
	)
	(segment
		(start 401.447762 -78.66507)
		(end 401.183348 -78.400656)
		(width 0.10795)
		(layer "F.Cu")
		(net "SPI_PCH_CLK")
	)
	(segment
		(start 404.132034 -73.125838)
		(end 404.271988 -73.265792)
		(width 0.10795)
		(layer "F.Cu")
		(net "SPI_PCH_CLK")
	)
	(segment
		(start 408.3304 -67.21094)
		(end 408.3304 -68.374768)
		(width 0.10795)
		(layer "F.Cu")
		(net "SPI_PCH_CLK")
	)
	(segment
		(start 401.656042 -79.637382)
		(end 401.503388 -79.790036)
		(width 0.10795)
		(layer "F.Cu")
		(net "SPI_PCH_CLK")
	)
	(segment
		(start 403.14499 -73.934574)
		(end 403.953726 -73.125838)
		(width 0.10795)
		(layer "F.Cu")
		(net "SPI_PCH_CLK")
	)
	(segment
		(start 408.43835 -68.914518)
		(end 408.3304 -69.022468)
		(width 0.10795)
		(layer "F.Cu")
		(net "SPI_PCH_CLK")
	)
	(segment
		(start 400.419316 -79.01178)
		(end 400.266662 -79.164434)
		(width 0.10795)
		(layer "F.Cu")
		(net "SPI_PCH_CLK")
	)
	(segment
		(start 401.183348 -78.400656)
		(end 401.03044 -78.400656)
		(width 0.10795)
		(layer "F.Cu")
		(net "SPI_PCH_CLK")
	)
	(segment
		(start 401.03044 -78.400656)
		(end 400.877786 -78.55331)
		(width 0.10795)
		(layer "F.Cu")
		(net "SPI_PCH_CLK")
	)
	(segment
		(start 400.877786 -78.706218)
		(end 401.656042 -79.484474)
		(width 0.10795)
		(layer "F.Cu")
		(net "SPI_PCH_CLK")
	)
	(segment
		(start 401.35048 -79.790036)
		(end 400.572224 -79.01178)
		(width 0.10795)
		(layer "F.Cu")
		(net "SPI_PCH_CLK")
	)
	(segment
		(start 399.198846 -80.955896)
		(end 400.10588 -80.955896)
		(width 0.10795)
		(layer "F.Cu")
		(net "SPI_PCH_CLK")
	)
	(segment
		(start 400.266662 -79.317342)
		(end 400.531838 -79.582518)
		(width 0.10795)
		(layer "F.Cu")
		(net "SPI_PCH_CLK")
	)
	(segment
		(start 378.695458 -92.15501)
		(end 378.073666 -91.533218)
		(width 0.10795)
		(layer "F.Cu")
		(net "SPI_PCH_CLK")
	)
	(segment
		(start 378.669804 -93.084142)
		(end 378.695458 -93.058488)
		(width 0.10795)
		(layer "F.Cu")
		(net "SPI_PCH_CLK")
	)
	(segment
		(start 401.604226 -78.66507)
		(end 401.447762 -78.66507)
		(width 0.10795)
		(layer "F.Cu")
		(net "SPI_PCH_CLK")
	)
	(segment
		(start 402.839428 -73.629012)
		(end 402.839428 -73.78192)
		(width 0.10795)
		(layer "F.Cu")
		(net "SPI_PCH_CLK")
	)
	(segment
		(start 401.7772 -76.151486)
		(end 401.7772 -76.548996)
		(width 0.10795)
		(layer "F.Cu")
		(net "SPI_PCH_CLK")
	)
	(segment
		(start 400.10588 -80.53705)
		(end 399.198846 -80.53705)
		(width 0.10795)
		(layer "F.Cu")
		(net "SPI_PCH_CLK")
	)
	(segment
		(start 401.503388 -79.790036)
		(end 401.35048 -79.790036)
		(width 0.10795)
		(layer "F.Cu")
		(net "SPI_PCH_CLK")
	)
	(segment
		(start 401.66925 -77.088746)
		(end 401.7772 -77.196696)
		(width 0.10795)
		(layer "F.Cu")
		(net "SPI_PCH_CLK")
	)
	(segment
		(start 401.454112 -76.764896)
		(end 401.454112 -76.980796)
		(width 0.10795)
		(layer "F.Cu")
		(net "SPI_PCH_CLK")
	)
	(segment
		(start 400.10588 -80.955896)
		(end 400.21383 -81.063846)
		(width 0.10795)
		(layer "F.Cu")
		(net "SPI_PCH_CLK")
	)
	(segment
		(start 402.992082 -73.934574)
		(end 403.14499 -73.934574)
		(width 0.10795)
		(layer "F.Cu")
		(net "SPI_PCH_CLK")
	)
	(segment
		(start 402.176742 -75.841352)
		(end 402.087334 -75.841352)
		(width 0.10795)
		(layer "F.Cu")
		(net "SPI_PCH_CLK")
	)
	(segment
		(start 378.695458 -93.058488)
		(end 378.695458 -92.15501)
		(width 0.10795)
		(layer "F.Cu")
		(net "SPI_PCH_CLK")
	)
	(segment
		(start 378.484892 -93.269308)
		(end 378.669804 -93.084396)
		(width 0.10795)
		(layer "F.Cu")
		(net "SPI_PCH_CLK")
	)
	(segment
		(start 402.62175 -75.068938)
		(end 402.62175 -75.396344)
		(width 0.10795)
		(layer "F.Cu")
		(net "SPI_PCH_CLK")
	)
	(segment
		(start 400.21383 -81.063846)
		(end 400.21383 -81.448656)
		(width 0.10795)
		(layer "F.Cu")
		(net "SPI_PCH_CLK")
	)
	(segment
		(start 400.572224 -79.01178)
		(end 400.419316 -79.01178)
		(width 0.10795)
		(layer "F.Cu")
		(net "SPI_PCH_CLK")
	)
	(segment
		(start 408.43835 -68.482718)
		(end 408.535378 -68.482718)
		(width 0.10795)
		(layer "F.Cu")
		(net "SPI_PCH_CLK")
	)
	(segment
		(start 378.669804 -93.084396)
		(end 378.669804 -93.084142)
		(width 0.10795)
		(layer "F.Cu")
		(net "SPI_PCH_CLK")
	)
	(segment
		(start 404.271988 -73.265792)
		(end 404.271988 -73.4187)
		(width 0.10795)
		(layer "F.Cu")
		(net "SPI_PCH_CLK")
	)
	(segment
		(start 400.21383 -80.4291)
		(end 400.10588 -80.53705)
		(width 0.10795)
		(layer "F.Cu")
		(net "SPI_PCH_CLK")
	)
	(segment
		(start 401.454112 -76.980796)
		(end 401.562062 -77.088746)
		(width 0.10795)
		(layer "F.Cu")
		(net "SPI_PCH_CLK")
	)
	(segment
		(start 400.531838 -79.735426)
		(end 400.21383 -80.053434)
		(width 0.10795)
		(layer "F.Cu")
		(net "SPI_PCH_CLK")
	)
	(segment
		(start 408.535378 -68.914518)
		(end 408.43835 -68.914518)
		(width 0.10795)
		(layer "F.Cu")
		(net "SPI_PCH_CLK")
	)
	(segment
		(start 408.643328 -68.806568)
		(end 408.535378 -68.914518)
		(width 0.10795)
		(layer "F.Cu")
		(net "SPI_PCH_CLK")
	)
	(segment
		(start 401.656042 -79.484474)
		(end 401.656042 -79.637382)
		(width 0.10795)
		(layer "F.Cu")
		(net "SPI_PCH_CLK")
	)
	(segment
		(start 401.66925 -76.656946)
		(end 401.562062 -76.656946)
		(width 0.10795)
		(layer "F.Cu")
		(net "SPI_PCH_CLK")
	)
	(segment
		(start 402.62175 -75.396344)
		(end 402.176742 -75.841352)
		(width 0.10795)
		(layer "F.Cu")
		(net "SPI_PCH_CLK")
	)
	(segment
		(start 400.266662 -79.164434)
		(end 400.266662 -79.317342)
		(width 0.10795)
		(layer "F.Cu")
		(net "SPI_PCH_CLK")
	)
	(segment
		(start 407.878026 -66.758566)
		(end 408.3304 -67.21094)
		(width 0.10795)
		(layer "F.Cu")
		(net "SPI_PCH_CLK")
	)
	(segment
		(start 399.090896 -80.645)
		(end 399.090896 -80.847946)
		(width 0.10795)
		(layer "F.Cu")
		(net "SPI_PCH_CLK")
	)
	(segment
		(start 401.562062 -77.088746)
		(end 401.66925 -77.088746)
		(width 0.10795)
		(layer "F.Cu")
		(net "SPI_PCH_CLK")
	)
	(segment
		(start 401.7772 -76.548996)
		(end 401.66925 -76.656946)
		(width 0.10795)
		(layer "F.Cu")
		(net "SPI_PCH_CLK")
	)
	(segment
		(start 403.953726 -73.125838)
		(end 404.132034 -73.125838)
		(width 0.10795)
		(layer "F.Cu")
		(net "SPI_PCH_CLK")
	)
	(segment
		(start 378.484892 -93.959934)
		(end 378.484892 -93.269308)
		(width 0.0889)
		(layer "F.Cu")
		(net "SPI_PCH_CLK")
	)
	(segment
		(start 401.7772 -77.196696)
		(end 401.7772 -78.492096)
		(width 0.10795)
		(layer "F.Cu")
		(net "SPI_PCH_CLK")
	)
	(via
		(at 400.21383 -81.448656)
		(size 0.508)
		(drill 0.254)
		(layers "F.Cu" "B.Cu")
		(net "SPI_PCH_CLK")
	)
	(via
		(at 385.285488 -53.051202)
		(size 0.508)
		(drill 0.254)
		(layers "F.Cu" "B.Cu")
		(net "SPI_PCH_CLK")
	)
	(via
		(at 378.073666 -91.533218)
		(size 0.508)
		(drill 0.254)
		(layers "F.Cu" "B.Cu")
		(net "SPI_PCH_CLK")
	)
	(segment
		(start 385.285488 -53.051202)
		(end 385.285488 -53.219858)
		(width 0.10795)
		(layer "B.Cu")
		(net "SPI_PCH_CLK")
	)
	(segment
		(start 385.385818 -53.982874)
		(end 385.232656 -54.136036)
		(width 0.10795)
		(layer "B.Cu")
		(net "SPI_PCH_CLK")
	)
	(segment
		(start 385.232656 -54.136036)
		(end 385.080256 -54.136036)
		(width 0.10795)
		(layer "B.Cu")
		(net "SPI_PCH_CLK")
	)
	(segment
		(start 385.285488 -53.219858)
		(end 385.106672 -53.398674)
		(width 0.10795)
		(layer "B.Cu")
		(net "SPI_PCH_CLK")
	)
	(segment
		(start 385.106672 -53.398674)
		(end 385.106672 -53.551074)
		(width 0.10795)
		(layer "B.Cu")
		(net "SPI_PCH_CLK")
	)
	(segment
		(start 384.80111 -53.856636)
		(end 384.64871 -53.856636)
		(width 0.10795)
		(layer "B.Cu")
		(net "SPI_PCH_CLK")
	)
	(segment
		(start 385.080256 -54.136036)
		(end 384.80111 -53.856636)
		(width 0.10795)
		(layer "B.Cu")
		(net "SPI_PCH_CLK")
	)
	(segment
		(start 384.64871 -53.856636)
		(end 384.339846 -54.1655)
		(width 0.10795)
		(layer "B.Cu")
		(net "SPI_PCH_CLK")
	)
	(segment
		(start 385.385818 -53.830474)
		(end 385.385818 -53.982874)
		(width 0.10795)
		(layer "B.Cu")
		(net "SPI_PCH_CLK")
	)
	(segment
		(start 385.106672 -53.551074)
		(end 385.385818 -53.830474)
		(width 0.10795)
		(layer "B.Cu")
		(net "SPI_PCH_CLK")
	)
	(segment
		(start 384.339846 -54.1655)
		(end 382.5875 -54.1655)
		(width 0.10795)
		(layer "B.Cu")
		(net "SPI_PCH_CLK")
	)
	(segment
		(start 382.729994 -79.596742)
		(end 382.729994 -80.030828)
		(width 0.089408)
		(layer "In2.Cu")
		(net "SPI_PCH_CLK")
	)
	(segment
		(start 383.60223 -75.9714)
		(end 383.41681 -75.9714)
		(width 0.089408)
		(layer "In2.Cu")
		(net "SPI_PCH_CLK")
	)
	(segment
		(start 384.993388 -55.90921)
		(end 384.546348 -56.35625)
		(width 0.089408)
		(layer "In2.Cu")
		(net "SPI_PCH_CLK")
	)
	(segment
		(start 384.90398 -54.080156)
		(end 384.993388 -54.169564)
		(width 0.089408)
		(layer "In2.Cu")
		(net "SPI_PCH_CLK")
	)
	(segment
		(start 385.620006 -60.960762)
		(end 385.620006 -61.292486)
		(width 0.089408)
		(layer "In2.Cu")
		(net "SPI_PCH_CLK")
	)
	(segment
		(start 384.2512 -53.811932)
		(end 384.2512 -53.990748)
		(width 0.089408)
		(layer "In2.Cu")
		(net "SPI_PCH_CLK")
	)
	(segment
		(start 382.729994 -80.746092)
		(end 382.640586 -80.8355)
		(width 0.089408)
		(layer "In2.Cu")
		(net "SPI_PCH_CLK")
	)
	(segment
		(start 386.6388 -58.782712)
		(end 386.6388 -58.961528)
		(width 0.089408)
		(layer "In2.Cu")
		(net "SPI_PCH_CLK")
	)
	(segment
		(start 382.729994 -82.013806)
		(end 382.59385 -82.14995)
		(width 0.089408)
		(layer "In2.Cu")
		(net "SPI_PCH_CLK")
	)
	(segment
		(start 384.546348 -57.888632)
		(end 384.635756 -57.97804)
		(width 0.089408)
		(layer "In2.Cu")
		(net "SPI_PCH_CLK")
	)
	(segment
		(start 382.442466 -80.8355)
		(end 382.353058 -80.924908)
		(width 0.089408)
		(layer "In2.Cu")
		(net "SPI_PCH_CLK")
	)
	(segment
		(start 381.787146 -81.84896)
		(end 381.787146 -81.974944)
		(width 0.089408)
		(layer "In2.Cu")
		(net "SPI_PCH_CLK")
	)
	(segment
		(start 382.226312 -80.120236)
		(end 382.136904 -80.209644)
		(width 0.089408)
		(layer "In2.Cu")
		(net "SPI_PCH_CLK")
	)
	(segment
		(start 384.546348 -59.140344)
		(end 384.546348 -59.91479)
		(width 0.089408)
		(layer "In2.Cu")
		(net "SPI_PCH_CLK")
	)
	(segment
		(start 382.353058 -80.924908)
		(end 382.353058 -81.103724)
		(width 0.089408)
		(layer "In2.Cu")
		(net "SPI_PCH_CLK")
	)
	(segment
		(start 384.546348 -56.35625)
		(end 384.546348 -57.173368)
		(width 0.089408)
		(layer "In2.Cu")
		(net "SPI_PCH_CLK")
	)
	(segment
		(start 381.787146 -81.974944)
		(end 382.214882 -82.402934)
		(width 0.089408)
		(layer "In2.Cu")
		(net "SPI_PCH_CLK")
	)
	(segment
		(start 384.635756 -57.262776)
		(end 385.787392 -57.262776)
		(width 0.089408)
		(layer "In2.Cu")
		(net "SPI_PCH_CLK")
	)
	(segment
		(start 381.87884 -84.88426)
		(end 381.87884 -86.38032)
		(width 0.089408)
		(layer "In2.Cu")
		(net "SPI_PCH_CLK")
	)
	(segment
		(start 382.640586 -80.120236)
		(end 382.226312 -80.120236)
		(width 0.089408)
		(layer "In2.Cu")
		(net "SPI_PCH_CLK")
	)
	(segment
		(start 386.549392 -58.335672)
		(end 384.635756 -58.335672)
		(width 0.089408)
		(layer "In2.Cu")
		(net "SPI_PCH_CLK")
	)
	(segment
		(start 382.76403 -73.245726)
		(end 383.286 -73.767696)
		(width 0.089408)
		(layer "In2.Cu")
		(net "SPI_PCH_CLK")
	)
	(segment
		(start 382.136904 -80.38846)
		(end 382.226312 -80.477868)
		(width 0.089408)
		(layer "In2.Cu")
		(net "SPI_PCH_CLK")
	)
	(segment
		(start 384.635756 -57.97804)
		(end 386.549392 -57.97804)
		(width 0.089408)
		(layer "In2.Cu")
		(net "SPI_PCH_CLK")
	)
	(segment
		(start 383.86385 -77.4954)
		(end 383.73304 -77.36459)
		(width 0.089408)
		(layer "In2.Cu")
		(net "SPI_PCH_CLK")
	)
	(segment
		(start 384.546348 -58.42508)
		(end 384.546348 -58.603896)
		(width 0.089408)
		(layer "In2.Cu")
		(net "SPI_PCH_CLK")
	)
	(segment
		(start 386.359146 -59.050936)
		(end 386.269738 -59.140344)
		(width 0.089408)
		(layer "In2.Cu")
		(net "SPI_PCH_CLK")
	)
	(segment
		(start 385.077208 -68.740782)
		(end 382.76403 -71.05396)
		(width 0.089408)
		(layer "In2.Cu")
		(net "SPI_PCH_CLK")
	)
	(segment
		(start 383.286 -73.767696)
		(end 383.286 -74.93)
		(width 0.089408)
		(layer "In2.Cu")
		(net "SPI_PCH_CLK")
	)
	(segment
		(start 384.340608 -53.722524)
		(end 384.2512 -53.811932)
		(width 0.089408)
		(layer "In2.Cu")
		(net "SPI_PCH_CLK")
	)
	(segment
		(start 386.549392 -59.050936)
		(end 386.359146 -59.050936)
		(width 0.089408)
		(layer "In2.Cu")
		(net "SPI_PCH_CLK")
	)
	(segment
		(start 383.12344 -78.666848)
		(end 382.640586 -79.149702)
		(width 0.089408)
		(layer "In2.Cu")
		(net "SPI_PCH_CLK")
	)
	(segment
		(start 383.9591 -60.4139)
		(end 385.073144 -60.4139)
		(width 0.089408)
		(layer "In2.Cu")
		(net "SPI_PCH_CLK")
	)
	(segment
		(start 384.90398 -53.722524)
		(end 384.340608 -53.722524)
		(width 0.089408)
		(layer "In2.Cu")
		(net "SPI_PCH_CLK")
	)
	(segment
		(start 382.53924 -84.22386)
		(end 381.87884 -84.88426)
		(width 0.089408)
		(layer "In2.Cu")
		(net "SPI_PCH_CLK")
	)
	(segment
		(start 381.914146 -81.72196)
		(end 381.787146 -81.84896)
		(width 0.089408)
		(layer "In2.Cu")
		(net "SPI_PCH_CLK")
	)
	(segment
		(start 385.822698 -59.050936)
		(end 384.635756 -59.050936)
		(width 0.089408)
		(layer "In2.Cu")
		(net "SPI_PCH_CLK")
	)
	(segment
		(start 384.099308 -56.51881)
		(end 383.968498 -56.388)
		(width 0.089408)
		(layer "In2.Cu")
		(net "SPI_PCH_CLK")
	)
	(segment
		(start 385.787392 -57.620408)
		(end 384.635756 -57.620408)
		(width 0.089408)
		(layer "In2.Cu")
		(net "SPI_PCH_CLK")
	)
	(segment
		(start 382.729994 -81.28254)
		(end 382.729994 -82.013806)
		(width 0.089408)
		(layer "In2.Cu")
		(net "SPI_PCH_CLK")
	)
	(segment
		(start 382.729994 -80.030828)
		(end 382.640586 -80.120236)
		(width 0.089408)
		(layer "In2.Cu")
		(net "SPI_PCH_CLK")
	)
	(segment
		(start 384.230118 -60.0456)
		(end 384.099308 -59.91479)
		(width 0.089408)
		(layer "In2.Cu")
		(net "SPI_PCH_CLK")
	)
	(segment
		(start 384.635756 -58.693304)
		(end 386.549392 -58.693304)
		(width 0.089408)
		(layer "In2.Cu")
		(net "SPI_PCH_CLK")
	)
	(segment
		(start 381.87884 -86.38032)
		(end 380.57074 -87.68842)
		(width 0.089408)
		(layer "In2.Cu")
		(net "SPI_PCH_CLK")
	)
	(segment
		(start 382.353058 -81.103724)
		(end 382.442466 -81.193132)
		(width 0.089408)
		(layer "In2.Cu")
		(net "SPI_PCH_CLK")
	)
	(segment
		(start 382.207008 -79.149702)
		(end 382.1176 -79.23911)
		(width 0.089408)
		(layer "In2.Cu")
		(net "SPI_PCH_CLK")
	)
	(segment
		(start 383.783078 -56.388)
		(end 383.652268 -56.51881)
		(width 0.089408)
		(layer "In2.Cu")
		(net "SPI_PCH_CLK")
	)
	(segment
		(start 384.993388 -54.884828)
		(end 384.993388 -55.90921)
		(width 0.089408)
		(layer "In2.Cu")
		(net "SPI_PCH_CLK")
	)
	(segment
		(start 384.18008 -75.82408)
		(end 384.18008 -77.36459)
		(width 0.089408)
		(layer "In2.Cu")
		(net "SPI_PCH_CLK")
	)
	(segment
		(start 384.340608 -54.437788)
		(end 384.2512 -54.527196)
		(width 0.089408)
		(layer "In2.Cu")
		(net "SPI_PCH_CLK")
	)
	(segment
		(start 384.04927 -77.4954)
		(end 383.86385 -77.4954)
		(width 0.089408)
		(layer "In2.Cu")
		(net "SPI_PCH_CLK")
	)
	(segment
		(start 383.286 -76.10221)
		(end 383.286 -78.14564)
		(width 0.089408)
		(layer "In2.Cu")
		(net "SPI_PCH_CLK")
	)
	(segment
		(start 384.993388 -53.633116)
		(end 384.90398 -53.722524)
		(width 0.089408)
		(layer "In2.Cu")
		(net "SPI_PCH_CLK")
	)
	(segment
		(start 383.73304 -76.10221)
		(end 383.60223 -75.9714)
		(width 0.089408)
		(layer "In2.Cu")
		(net "SPI_PCH_CLK")
	)
	(segment
		(start 386.18033 -60.2742)
		(end 386.001514 -60.2742)
		(width 0.089408)
		(layer "In2.Cu")
		(net "SPI_PCH_CLK")
	)
	(segment
		(start 386.549392 -58.693304)
		(end 386.6388 -58.782712)
		(width 0.089408)
		(layer "In2.Cu")
		(net "SPI_PCH_CLK")
	)
	(segment
		(start 382.76403 -71.05396)
		(end 382.76403 -73.245726)
		(width 0.089408)
		(layer "In2.Cu")
		(net "SPI_PCH_CLK")
	)
	(segment
		(start 378.47397 -91.132914)
		(end 378.073666 -91.533218)
		(width 0.089408)
		(layer "In2.Cu")
		(net "SPI_PCH_CLK")
	)
	(segment
		(start 383.286 -78.14564)
		(end 383.12344 -78.3082)
		(width 0.089408)
		(layer "In2.Cu")
		(net "SPI_PCH_CLK")
	)
	(segment
		(start 385.8768 -57.352184)
		(end 385.8768 -57.531)
		(width 0.089408)
		(layer "In2.Cu")
		(net "SPI_PCH_CLK")
	)
	(segment
		(start 382.04013 -81.72196)
		(end 381.914146 -81.72196)
		(width 0.089408)
		(layer "In2.Cu")
		(net "SPI_PCH_CLK")
	)
	(segment
		(start 383.652268 -60.107068)
		(end 383.9591 -60.4139)
		(width 0.089408)
		(layer "In2.Cu")
		(net "SPI_PCH_CLK")
	)
	(segment
		(start 384.90398 -54.437788)
		(end 384.340608 -54.437788)
		(width 0.089408)
		(layer "In2.Cu")
		(net "SPI_PCH_CLK")
	)
	(segment
		(start 383.41681 -75.9714)
		(end 383.286 -76.10221)
		(width 0.089408)
		(layer "In2.Cu")
		(net "SPI_PCH_CLK")
	)
	(segment
		(start 386.6388 -58.067448)
		(end 386.6388 -58.246264)
		(width 0.089408)
		(layer "In2.Cu")
		(net "SPI_PCH_CLK")
	)
	(segment
		(start 382.442466 -81.193132)
		(end 382.640586 -81.193132)
		(width 0.089408)
		(layer "In2.Cu")
		(net "SPI_PCH_CLK")
	)
	(segment
		(start 382.467866 -82.14995)
		(end 382.04013 -81.72196)
		(width 0.089408)
		(layer "In2.Cu")
		(net "SPI_PCH_CLK")
	)
	(segment
		(start 383.652268 -56.51881)
		(end 383.652268 -60.107068)
		(width 0.089408)
		(layer "In2.Cu")
		(net "SPI_PCH_CLK")
	)
	(segment
		(start 385.285488 -53.051202)
		(end 384.993388 -53.343302)
		(width 0.089408)
		(layer "In2.Cu")
		(net "SPI_PCH_CLK")
	)
	(segment
		(start 386.001514 -60.2742)
		(end 385.912106 -60.184792)
		(width 0.089408)
		(layer "In2.Cu")
		(net "SPI_PCH_CLK")
	)
	(segment
		(start 383.286 -74.93)
		(end 384.18008 -75.82408)
		(width 0.089408)
		(layer "In2.Cu")
		(net "SPI_PCH_CLK")
	)
	(segment
		(start 382.640586 -81.193132)
		(end 382.729994 -81.28254)
		(width 0.089408)
		(layer "In2.Cu")
		(net "SPI_PCH_CLK")
	)
	(segment
		(start 386.269738 -59.140344)
		(end 386.269738 -60.184792)
		(width 0.089408)
		(layer "In2.Cu")
		(net "SPI_PCH_CLK")
	)
	(segment
		(start 384.546348 -58.603896)
		(end 384.635756 -58.693304)
		(width 0.089408)
		(layer "In2.Cu")
		(net "SPI_PCH_CLK")
	)
	(segment
		(start 384.2512 -54.706012)
		(end 384.340608 -54.79542)
		(width 0.089408)
		(layer "In2.Cu")
		(net "SPI_PCH_CLK")
	)
	(segment
		(start 382.214882 -82.528918)
		(end 382.53924 -82.853276)
		(width 0.089408)
		(layer "In2.Cu")
		(net "SPI_PCH_CLK")
	)
	(segment
		(start 383.968498 -56.388)
		(end 383.783078 -56.388)
		(width 0.089408)
		(layer "In2.Cu")
		(net "SPI_PCH_CLK")
	)
	(segment
		(start 386.549392 -57.97804)
		(end 386.6388 -58.067448)
		(width 0.089408)
		(layer "In2.Cu")
		(net "SPI_PCH_CLK")
	)
	(segment
		(start 382.53924 -82.853276)
		(end 382.53924 -84.22386)
		(width 0.089408)
		(layer "In2.Cu")
		(net "SPI_PCH_CLK")
	)
	(segment
		(start 384.2512 -53.990748)
		(end 384.340608 -54.080156)
		(width 0.089408)
		(layer "In2.Cu")
		(net "SPI_PCH_CLK")
	)
	(segment
		(start 377.668536 -89.86139)
		(end 378.47397 -90.666824)
		(width 0.089408)
		(layer "In2.Cu")
		(net "SPI_PCH_CLK")
	)
	(segment
		(start 385.077208 -64.149732)
		(end 385.077208 -68.740782)
		(width 0.089408)
		(layer "In2.Cu")
		(net "SPI_PCH_CLK")
	)
	(segment
		(start 384.993388 -54.169564)
		(end 384.993388 -54.34838)
		(width 0.089408)
		(layer "In2.Cu")
		(net "SPI_PCH_CLK")
	)
	(segment
		(start 386.6388 -58.246264)
		(end 386.549392 -58.335672)
		(width 0.089408)
		(layer "In2.Cu")
		(net "SPI_PCH_CLK")
	)
	(segment
		(start 382.640586 -80.8355)
		(end 382.442466 -80.8355)
		(width 0.089408)
		(layer "In2.Cu")
		(net "SPI_PCH_CLK")
	)
	(segment
		(start 385.787392 -57.262776)
		(end 385.8768 -57.352184)
		(width 0.089408)
		(layer "In2.Cu")
		(net "SPI_PCH_CLK")
	)
	(segment
		(start 378.47397 -90.666824)
		(end 378.47397 -91.132914)
		(width 0.089408)
		(layer "In2.Cu")
		(net "SPI_PCH_CLK")
	)
	(segment
		(start 385.49199 -61.420502)
		(end 385.49199 -63.73495)
		(width 0.089408)
		(layer "In2.Cu")
		(net "SPI_PCH_CLK")
	)
	(segment
		(start 380.57074 -87.68842)
		(end 378.513848 -87.68842)
		(width 0.089408)
		(layer "In2.Cu")
		(net "SPI_PCH_CLK")
	)
	(segment
		(start 384.415538 -60.0456)
		(end 384.230118 -60.0456)
		(width 0.089408)
		(layer "In2.Cu")
		(net "SPI_PCH_CLK")
	)
	(segment
		(start 384.993388 -54.34838)
		(end 384.90398 -54.437788)
		(width 0.089408)
		(layer "In2.Cu")
		(net "SPI_PCH_CLK")
	)
	(segment
		(start 386.269738 -60.184792)
		(end 386.18033 -60.2742)
		(width 0.089408)
		(layer "In2.Cu")
		(net "SPI_PCH_CLK")
	)
	(segment
		(start 382.1176 -79.417926)
		(end 382.207008 -79.507334)
		(width 0.089408)
		(layer "In2.Cu")
		(net "SPI_PCH_CLK")
	)
	(segment
		(start 384.635756 -58.335672)
		(end 384.546348 -58.42508)
		(width 0.089408)
		(layer "In2.Cu")
		(net "SPI_PCH_CLK")
	)
	(segment
		(start 382.1176 -79.23911)
		(end 382.1176 -79.417926)
		(width 0.089408)
		(layer "In2.Cu")
		(net "SPI_PCH_CLK")
	)
	(segment
		(start 386.6388 -58.961528)
		(end 386.549392 -59.050936)
		(width 0.089408)
		(layer "In2.Cu")
		(net "SPI_PCH_CLK")
	)
	(segment
		(start 378.513848 -87.68842)
		(end 377.668536 -88.533732)
		(width 0.089408)
		(layer "In2.Cu")
		(net "SPI_PCH_CLK")
	)
	(segment
		(start 382.640586 -79.507334)
		(end 382.729994 -79.596742)
		(width 0.089408)
		(layer "In2.Cu")
		(net "SPI_PCH_CLK")
	)
	(segment
		(start 382.640586 -80.477868)
		(end 382.729994 -80.567276)
		(width 0.089408)
		(layer "In2.Cu")
		(net "SPI_PCH_CLK")
	)
	(segment
		(start 383.73304 -77.36459)
		(end 383.73304 -76.10221)
		(width 0.089408)
		(layer "In2.Cu")
		(net "SPI_PCH_CLK")
	)
	(segment
		(start 382.214882 -82.402934)
		(end 382.214882 -82.528918)
		(width 0.089408)
		(layer "In2.Cu")
		(net "SPI_PCH_CLK")
	)
	(segment
		(start 382.59385 -82.14995)
		(end 382.467866 -82.14995)
		(width 0.089408)
		(layer "In2.Cu")
		(net "SPI_PCH_CLK")
	)
	(segment
		(start 385.49199 -63.73495)
		(end 385.077208 -64.149732)
		(width 0.089408)
		(layer "In2.Cu")
		(net "SPI_PCH_CLK")
	)
	(segment
		(start 385.912106 -59.140344)
		(end 385.822698 -59.050936)
		(width 0.089408)
		(layer "In2.Cu")
		(net "SPI_PCH_CLK")
	)
	(segment
		(start 382.729994 -80.567276)
		(end 382.729994 -80.746092)
		(width 0.089408)
		(layer "In2.Cu")
		(net "SPI_PCH_CLK")
	)
	(segment
		(start 385.8768 -57.531)
		(end 385.787392 -57.620408)
		(width 0.089408)
		(layer "In2.Cu")
		(net "SPI_PCH_CLK")
	)
	(segment
		(start 384.340608 -54.080156)
		(end 384.90398 -54.080156)
		(width 0.089408)
		(layer "In2.Cu")
		(net "SPI_PCH_CLK")
	)
	(segment
		(start 382.136904 -80.209644)
		(end 382.136904 -80.38846)
		(width 0.089408)
		(layer "In2.Cu")
		(net "SPI_PCH_CLK")
	)
	(segment
		(start 384.635756 -57.620408)
		(end 384.546348 -57.709816)
		(width 0.089408)
		(layer "In2.Cu")
		(net "SPI_PCH_CLK")
	)
	(segment
		(start 384.18008 -77.36459)
		(end 384.04927 -77.4954)
		(width 0.089408)
		(layer "In2.Cu")
		(net "SPI_PCH_CLK")
	)
	(segment
		(start 385.620006 -61.292486)
		(end 385.49199 -61.420502)
		(width 0.089408)
		(layer "In2.Cu")
		(net "SPI_PCH_CLK")
	)
	(segment
		(start 384.546348 -57.709816)
		(end 384.546348 -57.888632)
		(width 0.089408)
		(layer "In2.Cu")
		(net "SPI_PCH_CLK")
	)
	(segment
		(start 382.640586 -79.149702)
		(end 382.207008 -79.149702)
		(width 0.089408)
		(layer "In2.Cu")
		(net "SPI_PCH_CLK")
	)
	(segment
		(start 384.993388 -53.343302)
		(end 384.993388 -53.633116)
		(width 0.089408)
		(layer "In2.Cu")
		(net "SPI_PCH_CLK")
	)
	(segment
		(start 384.340608 -54.79542)
		(end 384.90398 -54.79542)
		(width 0.089408)
		(layer "In2.Cu")
		(net "SPI_PCH_CLK")
	)
	(segment
		(start 383.12344 -78.3082)
		(end 383.12344 -78.666848)
		(width 0.089408)
		(layer "In2.Cu")
		(net "SPI_PCH_CLK")
	)
	(segment
		(start 385.073144 -60.4139)
		(end 385.620006 -60.960762)
		(width 0.089408)
		(layer "In2.Cu")
		(net "SPI_PCH_CLK")
	)
	(segment
		(start 377.668536 -88.533732)
		(end 377.668536 -89.86139)
		(width 0.089408)
		(layer "In2.Cu")
		(net "SPI_PCH_CLK")
	)
	(segment
		(start 384.099308 -59.91479)
		(end 384.099308 -56.51881)
		(width 0.089408)
		(layer "In2.Cu")
		(net "SPI_PCH_CLK")
	)
	(segment
		(start 384.546348 -57.173368)
		(end 384.635756 -57.262776)
		(width 0.089408)
		(layer "In2.Cu")
		(net "SPI_PCH_CLK")
	)
	(segment
		(start 382.226312 -80.477868)
		(end 382.640586 -80.477868)
		(width 0.089408)
		(layer "In2.Cu")
		(net "SPI_PCH_CLK")
	)
	(segment
		(start 384.546348 -59.91479)
		(end 384.415538 -60.0456)
		(width 0.089408)
		(layer "In2.Cu")
		(net "SPI_PCH_CLK")
	)
	(segment
		(start 385.912106 -60.184792)
		(end 385.912106 -59.140344)
		(width 0.089408)
		(layer "In2.Cu")
		(net "SPI_PCH_CLK")
	)
	(segment
		(start 384.2512 -54.527196)
		(end 384.2512 -54.706012)
		(width 0.089408)
		(layer "In2.Cu")
		(net "SPI_PCH_CLK")
	)
	(segment
		(start 384.635756 -59.050936)
		(end 384.546348 -59.140344)
		(width 0.089408)
		(layer "In2.Cu")
		(net "SPI_PCH_CLK")
	)
	(segment
		(start 384.90398 -54.79542)
		(end 384.993388 -54.884828)
		(width 0.089408)
		(layer "In2.Cu")
		(net "SPI_PCH_CLK")
	)
	(segment
		(start 382.207008 -79.507334)
		(end 382.640586 -79.507334)
		(width 0.089408)
		(layer "In2.Cu")
		(net "SPI_PCH_CLK")
	)
	(segment
		(start 384.540252 -85.562948)
		(end 384.666236 -85.562948)
		(width 0.089408)
		(layer "In4.Cu")
		(net "SPI_PCH_CLK")
	)
	(segment
		(start 388.650734 -84.39531)
		(end 390.92505 -84.39531)
		(width 0.089408)
		(layer "In4.Cu")
		(net "SPI_PCH_CLK")
	)
	(segment
		(start 384.793236 -85.30971)
		(end 384.487674 -85.004148)
		(width 0.089408)
		(layer "In4.Cu")
		(net "SPI_PCH_CLK")
	)
	(segment
		(start 378.073666 -91.533218)
		(end 377.604274 -91.063826)
		(width 0.089408)
		(layer "In4.Cu")
		(net "SPI_PCH_CLK")
	)
	(segment
		(start 392.18997 -83.13039)
		(end 393.483338 -83.13039)
		(width 0.089408)
		(layer "In4.Cu")
		(net "SPI_PCH_CLK")
	)
	(segment
		(start 381.57912 -87.299292)
		(end 382.334008 -87.299292)
		(width 0.089408)
		(layer "In4.Cu")
		(net "SPI_PCH_CLK")
	)
	(segment
		(start 388.278116 -84.767928)
		(end 388.650734 -84.39531)
		(width 0.089408)
		(layer "In4.Cu")
		(net "SPI_PCH_CLK")
	)
	(segment
		(start 383.981706 -85.383624)
		(end 384.108452 -85.256878)
		(width 0.089408)
		(layer "In4.Cu")
		(net "SPI_PCH_CLK")
	)
	(segment
		(start 383.981706 -85.510116)
		(end 383.981706 -85.383624)
		(width 0.089408)
		(layer "In4.Cu")
		(net "SPI_PCH_CLK")
	)
	(segment
		(start 384.666236 -85.562948)
		(end 384.793236 -85.435948)
		(width 0.089408)
		(layer "In4.Cu")
		(net "SPI_PCH_CLK")
	)
	(segment
		(start 377.604274 -89.036652)
		(end 378.853954 -87.786972)
		(width 0.089408)
		(layer "In4.Cu")
		(net "SPI_PCH_CLK")
	)
	(segment
		(start 384.487674 -85.004148)
		(end 384.487674 -84.877656)
		(width 0.089408)
		(layer "In4.Cu")
		(net "SPI_PCH_CLK")
	)
	(segment
		(start 384.160268 -86.068916)
		(end 384.287268 -85.941916)
		(width 0.089408)
		(layer "In4.Cu")
		(net "SPI_PCH_CLK")
	)
	(segment
		(start 384.108452 -85.256878)
		(end 384.234436 -85.256878)
		(width 0.089408)
		(layer "In4.Cu")
		(net "SPI_PCH_CLK")
	)
	(segment
		(start 384.034284 -86.068916)
		(end 384.160268 -86.068916)
		(width 0.089408)
		(layer "In4.Cu")
		(net "SPI_PCH_CLK")
	)
	(segment
		(start 390.92505 -84.39531)
		(end 392.18997 -83.13039)
		(width 0.089408)
		(layer "In4.Cu")
		(net "SPI_PCH_CLK")
	)
	(segment
		(start 384.287268 -85.941916)
		(end 384.287268 -85.815678)
		(width 0.089408)
		(layer "In4.Cu")
		(net "SPI_PCH_CLK")
	)
	(segment
		(start 394.780516 -81.833212)
		(end 399.829274 -81.833212)
		(width 0.089408)
		(layer "In4.Cu")
		(net "SPI_PCH_CLK")
	)
	(segment
		(start 382.8161 -86.601046)
		(end 383.494026 -85.92312)
		(width 0.089408)
		(layer "In4.Cu")
		(net "SPI_PCH_CLK")
	)
	(segment
		(start 378.853954 -87.786972)
		(end 381.09144 -87.786972)
		(width 0.089408)
		(layer "In4.Cu")
		(net "SPI_PCH_CLK")
	)
	(segment
		(start 393.483338 -83.13039)
		(end 394.780516 -81.833212)
		(width 0.089408)
		(layer "In4.Cu")
		(net "SPI_PCH_CLK")
	)
	(segment
		(start 382.334008 -87.299292)
		(end 382.8161 -86.8172)
		(width 0.089408)
		(layer "In4.Cu")
		(net "SPI_PCH_CLK")
	)
	(segment
		(start 382.8161 -86.8172)
		(end 382.8161 -86.601046)
		(width 0.089408)
		(layer "In4.Cu")
		(net "SPI_PCH_CLK")
	)
	(segment
		(start 377.604274 -91.063826)
		(end 377.604274 -89.036652)
		(width 0.089408)
		(layer "In4.Cu")
		(net "SPI_PCH_CLK")
	)
	(segment
		(start 399.829274 -81.833212)
		(end 400.21383 -81.448656)
		(width 0.089408)
		(layer "In4.Cu")
		(net "SPI_PCH_CLK")
	)
	(segment
		(start 381.09144 -87.786972)
		(end 381.57912 -87.299292)
		(width 0.089408)
		(layer "In4.Cu")
		(net "SPI_PCH_CLK")
	)
	(segment
		(start 384.793236 -85.435948)
		(end 384.793236 -85.30971)
		(width 0.089408)
		(layer "In4.Cu")
		(net "SPI_PCH_CLK")
	)
	(segment
		(start 384.597402 -84.767928)
		(end 388.278116 -84.767928)
		(width 0.089408)
		(layer "In4.Cu")
		(net "SPI_PCH_CLK")
	)
	(segment
		(start 383.494026 -85.92312)
		(end 383.888488 -85.92312)
		(width 0.089408)
		(layer "In4.Cu")
		(net "SPI_PCH_CLK")
	)
	(segment
		(start 383.888488 -85.92312)
		(end 384.034284 -86.068916)
		(width 0.089408)
		(layer "In4.Cu")
		(net "SPI_PCH_CLK")
	)
	(segment
		(start 384.487674 -84.877656)
		(end 384.597402 -84.767928)
		(width 0.089408)
		(layer "In4.Cu")
		(net "SPI_PCH_CLK")
	)
	(segment
		(start 384.287268 -85.815678)
		(end 383.981706 -85.510116)
		(width 0.089408)
		(layer "In4.Cu")
		(net "SPI_PCH_CLK")
	)
	(segment
		(start 384.234436 -85.256878)
		(end 384.540252 -85.562948)
		(width 0.089408)
		(layer "In4.Cu")
		(net "SPI_PCH_CLK")
	)
	(segment
		(start 366.994694 -118.51259)
		(end 366.868964 -118.51259)
		(width 0.0889)
		(layer "F.Cu")
		(net "P3E_CPU0_PE1_PCH_C_TXN<9>")
	)
	(segment
		(start 363.987842 -117.690392)
		(end 363.987334 -117.690138)
		(width 0.0889)
		(layer "F.Cu")
		(net "P3E_CPU0_PE1_PCH_C_TXN<9>")
	)
	(segment
		(start 354.05695 -118.08079)
		(end 356.441502 -118.786402)
		(width 0.1143)
		(layer "F.Cu")
		(net "P3E_CPU0_PE1_PCH_C_TXN<9>")
	)
	(segment
		(start 346.817442 -118.624858)
		(end 347.36151 -118.08079)
		(width 0.1143)
		(layer "F.Cu")
		(net "P3E_CPU0_PE1_PCH_C_TXN<9>")
	)
	(segment
		(start 375.068084 -119.333264)
		(end 374.235726 -119.333264)
		(width 0.0889)
		(layer "F.Cu")
		(net "P3E_CPU0_PE1_PCH_C_TXN<9>")
	)
	(segment
		(start 372.381272 -120.209818)
		(end 372.292372 -120.298718)
		(width 0.0889)
		(layer "F.Cu")
		(net "P3E_CPU0_PE1_PCH_C_TXN<9>")
	)
	(segment
		(start 370.958872 -120.209818)
		(end 370.869972 -120.298718)
		(width 0.0889)
		(layer "F.Cu")
		(net "P3E_CPU0_PE1_PCH_C_TXN<9>")
	)
	(segment
		(start 375.089928 -119.355108)
		(end 375.068084 -119.333264)
		(width 0.0889)
		(layer "F.Cu")
		(net "P3E_CPU0_PE1_PCH_C_TXN<9>")
	)
	(segment
		(start 340.111588 -119.211598)
		(end 340.111588 -118.836694)
		(width 0.1143)
		(layer "F.Cu")
		(net "P3E_CPU0_PE1_PCH_C_TXN<9>")
	)
	(segment
		(start 365.86922 -118.098316)
		(end 365.78032 -118.009416)
		(width 0.0889)
		(layer "F.Cu")
		(net "P3E_CPU0_PE1_PCH_C_TXN<9>")
	)
	(segment
		(start 367.497614 -119.01551)
		(end 367.371884 -119.01551)
		(width 0.0889)
		(layer "F.Cu")
		(net "P3E_CPU0_PE1_PCH_C_TXN<9>")
	)
	(segment
		(start 368.189002 -119.706898)
		(end 368.000534 -119.51843)
		(width 0.0889)
		(layer "F.Cu")
		(net "P3E_CPU0_PE1_PCH_C_TXN<9>")
	)
	(segment
		(start 365.78032 -118.009416)
		(end 364.67161 -118.009416)
		(width 0.0889)
		(layer "F.Cu")
		(net "P3E_CPU0_PE1_PCH_C_TXN<9>")
	)
	(segment
		(start 364.67161 -118.009416)
		(end 364.161832 -117.729254)
		(width 0.0889)
		(layer "F.Cu")
		(net "P3E_CPU0_PE1_PCH_C_TXN<9>")
	)
	(segment
		(start 368.691922 -120.209818)
		(end 368.503454 -120.02135)
		(width 0.0889)
		(layer "F.Cu")
		(net "P3E_CPU0_PE1_PCH_C_TXN<9>")
	)
	(segment
		(start 368.189002 -119.832628)
		(end 368.189002 -119.706898)
		(width 0.0889)
		(layer "F.Cu")
		(net "P3E_CPU0_PE1_PCH_C_TXN<9>")
	)
	(segment
		(start 371.581172 -120.298718)
		(end 371.314472 -120.298718)
		(width 0.0889)
		(layer "F.Cu")
		(net "P3E_CPU0_PE1_PCH_C_TXN<9>")
	)
	(segment
		(start 366.49152 -118.009416)
		(end 366.22482 -118.009416)
		(width 0.0889)
		(layer "F.Cu")
		(net "P3E_CPU0_PE1_PCH_C_TXN<9>")
	)
	(segment
		(start 366.680242 -118.323868)
		(end 366.680242 -118.198138)
		(width 0.0889)
		(layer "F.Cu")
		(net "P3E_CPU0_PE1_PCH_C_TXN<9>")
	)
	(segment
		(start 358.106218 -118.336568)
		(end 358.679242 -118.181882)
		(width 0.1143)
		(layer "F.Cu")
		(net "P3E_CPU0_PE1_PCH_C_TXN<9>")
	)
	(segment
		(start 340.323424 -118.624858)
		(end 346.817442 -118.624858)
		(width 0.1143)
		(layer "F.Cu")
		(net "P3E_CPU0_PE1_PCH_C_TXN<9>")
	)
	(segment
		(start 366.22482 -118.009416)
		(end 366.13592 -118.098316)
		(width 0.0889)
		(layer "F.Cu")
		(net "P3E_CPU0_PE1_PCH_C_TXN<9>")
	)
	(segment
		(start 372.292372 -120.298718)
		(end 372.025672 -120.298718)
		(width 0.0889)
		(layer "F.Cu")
		(net "P3E_CPU0_PE1_PCH_C_TXN<9>")
	)
	(segment
		(start 370.603272 -120.298718)
		(end 370.514372 -120.209818)
		(width 0.0889)
		(layer "F.Cu")
		(net "P3E_CPU0_PE1_PCH_C_TXN<9>")
	)
	(segment
		(start 367.686082 -119.329708)
		(end 367.686082 -119.203978)
		(width 0.0889)
		(layer "F.Cu")
		(net "P3E_CPU0_PE1_PCH_C_TXN<9>")
	)
	(segment
		(start 373.359172 -120.209818)
		(end 373.092472 -120.209818)
		(width 0.0889)
		(layer "F.Cu")
		(net "P3E_CPU0_PE1_PCH_C_TXN<9>")
	)
	(segment
		(start 370.869972 -120.298718)
		(end 370.603272 -120.298718)
		(width 0.0889)
		(layer "F.Cu")
		(net "P3E_CPU0_PE1_PCH_C_TXN<9>")
	)
	(segment
		(start 372.647972 -120.209818)
		(end 372.381272 -120.209818)
		(width 0.0889)
		(layer "F.Cu")
		(net "P3E_CPU0_PE1_PCH_C_TXN<9>")
	)
	(segment
		(start 370.247672 -120.209818)
		(end 370.158772 -120.298718)
		(width 0.0889)
		(layer "F.Cu")
		(net "P3E_CPU0_PE1_PCH_C_TXN<9>")
	)
	(segment
		(start 366.13592 -118.098316)
		(end 365.86922 -118.098316)
		(width 0.0889)
		(layer "F.Cu")
		(net "P3E_CPU0_PE1_PCH_C_TXN<9>")
	)
	(segment
		(start 363.935518 -117.70487)
		(end 362.021882 -117.278912)
		(width 0.1143)
		(layer "F.Cu")
		(net "P3E_CPU0_PE1_PCH_C_TXN<9>")
	)
	(segment
		(start 371.670072 -120.209818)
		(end 371.581172 -120.298718)
		(width 0.0889)
		(layer "F.Cu")
		(net "P3E_CPU0_PE1_PCH_C_TXN<9>")
	)
	(segment
		(start 371.225572 -120.209818)
		(end 370.958872 -120.209818)
		(width 0.0889)
		(layer "F.Cu")
		(net "P3E_CPU0_PE1_PCH_C_TXN<9>")
	)
	(segment
		(start 364.161832 -117.729254)
		(end 363.987842 -117.690392)
		(width 0.0889)
		(layer "F.Cu")
		(net "P3E_CPU0_PE1_PCH_C_TXN<9>")
	)
	(segment
		(start 368.503454 -120.02135)
		(end 368.377724 -120.02135)
		(width 0.0889)
		(layer "F.Cu")
		(net "P3E_CPU0_PE1_PCH_C_TXN<9>")
	)
	(segment
		(start 371.936772 -120.209818)
		(end 371.670072 -120.209818)
		(width 0.0889)
		(layer "F.Cu")
		(net "P3E_CPU0_PE1_PCH_C_TXN<9>")
	)
	(segment
		(start 374.235726 -119.333264)
		(end 373.359172 -120.209818)
		(width 0.0889)
		(layer "F.Cu")
		(net "P3E_CPU0_PE1_PCH_C_TXN<9>")
	)
	(segment
		(start 363.957108 -117.709696)
		(end 363.935518 -117.70487)
		(width 0.0889)
		(layer "F.Cu")
		(net "P3E_CPU0_PE1_PCH_C_TXN<9>")
	)
	(segment
		(start 369.892072 -120.298718)
		(end 369.803172 -120.209818)
		(width 0.0889)
		(layer "F.Cu")
		(net "P3E_CPU0_PE1_PCH_C_TXN<9>")
	)
	(segment
		(start 366.868964 -118.51259)
		(end 366.680242 -118.323868)
		(width 0.0889)
		(layer "F.Cu")
		(net "P3E_CPU0_PE1_PCH_C_TXN<9>")
	)
	(segment
		(start 368.000534 -119.51843)
		(end 367.874804 -119.51843)
		(width 0.0889)
		(layer "F.Cu")
		(net "P3E_CPU0_PE1_PCH_C_TXN<9>")
	)
	(segment
		(start 369.091972 -120.209818)
		(end 368.691922 -120.209818)
		(width 0.0889)
		(layer "F.Cu")
		(net "P3E_CPU0_PE1_PCH_C_TXN<9>")
	)
	(segment
		(start 347.36151 -118.08079)
		(end 354.05695 -118.08079)
		(width 0.1143)
		(layer "F.Cu")
		(net "P3E_CPU0_PE1_PCH_C_TXN<9>")
	)
	(segment
		(start 366.680242 -118.198138)
		(end 366.49152 -118.009416)
		(width 0.0889)
		(layer "F.Cu")
		(net "P3E_CPU0_PE1_PCH_C_TXN<9>")
	)
	(segment
		(start 369.536472 -120.209818)
		(end 369.447572 -120.298718)
		(width 0.0889)
		(layer "F.Cu")
		(net "P3E_CPU0_PE1_PCH_C_TXN<9>")
	)
	(segment
		(start 372.736872 -120.298718)
		(end 372.647972 -120.209818)
		(width 0.0889)
		(layer "F.Cu")
		(net "P3E_CPU0_PE1_PCH_C_TXN<9>")
	)
	(segment
		(start 370.514372 -120.209818)
		(end 370.247672 -120.209818)
		(width 0.0889)
		(layer "F.Cu")
		(net "P3E_CPU0_PE1_PCH_C_TXN<9>")
	)
	(segment
		(start 367.183162 -118.826788)
		(end 367.183162 -118.701058)
		(width 0.0889)
		(layer "F.Cu")
		(net "P3E_CPU0_PE1_PCH_C_TXN<9>")
	)
	(segment
		(start 367.874804 -119.51843)
		(end 367.686082 -119.329708)
		(width 0.0889)
		(layer "F.Cu")
		(net "P3E_CPU0_PE1_PCH_C_TXN<9>")
	)
	(segment
		(start 367.183162 -118.701058)
		(end 366.994694 -118.51259)
		(width 0.0889)
		(layer "F.Cu")
		(net "P3E_CPU0_PE1_PCH_C_TXN<9>")
	)
	(segment
		(start 367.371884 -119.01551)
		(end 367.183162 -118.826788)
		(width 0.0889)
		(layer "F.Cu")
		(net "P3E_CPU0_PE1_PCH_C_TXN<9>")
	)
	(segment
		(start 372.025672 -120.298718)
		(end 371.936772 -120.209818)
		(width 0.0889)
		(layer "F.Cu")
		(net "P3E_CPU0_PE1_PCH_C_TXN<9>")
	)
	(segment
		(start 373.092472 -120.209818)
		(end 373.003572 -120.298718)
		(width 0.0889)
		(layer "F.Cu")
		(net "P3E_CPU0_PE1_PCH_C_TXN<9>")
	)
	(segment
		(start 367.686082 -119.203978)
		(end 367.497614 -119.01551)
		(width 0.0889)
		(layer "F.Cu")
		(net "P3E_CPU0_PE1_PCH_C_TXN<9>")
	)
	(segment
		(start 373.003572 -120.298718)
		(end 372.736872 -120.298718)
		(width 0.0889)
		(layer "F.Cu")
		(net "P3E_CPU0_PE1_PCH_C_TXN<9>")
	)
	(segment
		(start 371.314472 -120.298718)
		(end 371.225572 -120.209818)
		(width 0.0889)
		(layer "F.Cu")
		(net "P3E_CPU0_PE1_PCH_C_TXN<9>")
	)
	(segment
		(start 369.447572 -120.298718)
		(end 369.180872 -120.298718)
		(width 0.0889)
		(layer "F.Cu")
		(net "P3E_CPU0_PE1_PCH_C_TXN<9>")
	)
	(segment
		(start 356.441502 -118.786402)
		(end 358.106218 -118.336568)
		(width 0.1143)
		(layer "F.Cu")
		(net "P3E_CPU0_PE1_PCH_C_TXN<9>")
	)
	(segment
		(start 368.377724 -120.02135)
		(end 368.189002 -119.832628)
		(width 0.0889)
		(layer "F.Cu")
		(net "P3E_CPU0_PE1_PCH_C_TXN<9>")
	)
	(segment
		(start 363.987334 -117.690138)
		(end 363.957108 -117.709696)
		(width 0.0889)
		(layer "F.Cu")
		(net "P3E_CPU0_PE1_PCH_C_TXN<9>")
	)
	(segment
		(start 362.021882 -117.278912)
		(end 358.679242 -118.181882)
		(width 0.1143)
		(layer "F.Cu")
		(net "P3E_CPU0_PE1_PCH_C_TXN<9>")
	)
	(segment
		(start 370.158772 -120.298718)
		(end 369.892072 -120.298718)
		(width 0.0889)
		(layer "F.Cu")
		(net "P3E_CPU0_PE1_PCH_C_TXN<9>")
	)
	(segment
		(start 340.111588 -118.836694)
		(end 340.323424 -118.624858)
		(width 0.1143)
		(layer "F.Cu")
		(net "P3E_CPU0_PE1_PCH_C_TXN<9>")
	)
	(segment
		(start 369.180872 -120.298718)
		(end 369.091972 -120.209818)
		(width 0.0889)
		(layer "F.Cu")
		(net "P3E_CPU0_PE1_PCH_C_TXN<9>")
	)
	(segment
		(start 369.803172 -120.209818)
		(end 369.536472 -120.209818)
		(width 0.0889)
		(layer "F.Cu")
		(net "P3E_CPU0_PE1_PCH_C_TXN<9>")
	)
	(via
		(at 358.679242 -118.181882)
		(size 0.508)
		(drill 0.254)
		(layers "F.Cu" "B.Cu")
		(net "P3E_CPU0_PE1_PCH_C_TXN<9>")
	)
	(segment
		(start 371.49024 -119.7229)
		(end 371.40134 -119.8118)
		(width 0.0889)
		(layer "F.Cu")
		(net "P3E_CPU0_PE1_PCH_C_TXN<8>")
	)
	(segment
		(start 365.23422 -116.79047)
		(end 364.365032 -116.79047)
		(width 0.1143)
		(layer "F.Cu")
		(net "P3E_CPU0_PE1_PCH_C_TXN<8>")
	)
	(segment
		(start 372.91264 -119.7229)
		(end 372.82374 -119.8118)
		(width 0.0889)
		(layer "F.Cu")
		(net "P3E_CPU0_PE1_PCH_C_TXN<8>")
	)
	(segment
		(start 365.858552 -116.76507)
		(end 365.833152 -116.79047)
		(width 0.0889)
		(layer "F.Cu")
		(net "P3E_CPU0_PE1_PCH_C_TXN<8>")
	)
	(segment
		(start 371.04574 -119.7229)
		(end 370.77904 -119.7229)
		(width 0.0889)
		(layer "F.Cu")
		(net "P3E_CPU0_PE1_PCH_C_TXN<8>")
	)
	(segment
		(start 370.69014 -119.8118)
		(end 370.42344 -119.8118)
		(width 0.0889)
		(layer "F.Cu")
		(net "P3E_CPU0_PE1_PCH_C_TXN<8>")
	)
	(segment
		(start 374.579642 -118.759732)
		(end 374.142508 -118.759732)
		(width 0.0889)
		(layer "F.Cu")
		(net "P3E_CPU0_PE1_PCH_C_TXN<8>")
	)
	(segment
		(start 333.90332 -117.9957)
		(end 333.78902 -118.11)
		(width 0.1143)
		(layer "F.Cu")
		(net "P3E_CPU0_PE1_PCH_C_TXN<8>")
	)
	(segment
		(start 371.40134 -119.8118)
		(end 371.13464 -119.8118)
		(width 0.0889)
		(layer "F.Cu")
		(net "P3E_CPU0_PE1_PCH_C_TXN<8>")
	)
	(segment
		(start 368.470688 -119.031512)
		(end 368.281966 -118.84279)
		(width 0.0889)
		(layer "F.Cu")
		(net "P3E_CPU0_PE1_PCH_C_TXN<8>")
	)
	(segment
		(start 373.944896 -119.083074)
		(end 373.747284 -119.280686)
		(width 0.0889)
		(layer "F.Cu")
		(net "P3E_CPU0_PE1_PCH_C_TXN<8>")
	)
	(segment
		(start 368.784886 -119.34571)
		(end 368.784886 -119.21998)
		(width 0.0889)
		(layer "F.Cu")
		(net "P3E_CPU0_PE1_PCH_C_TXN<8>")
	)
	(segment
		(start 372.20144 -119.7229)
		(end 372.11254 -119.8118)
		(width 0.0889)
		(layer "F.Cu")
		(net "P3E_CPU0_PE1_PCH_C_TXN<8>")
	)
	(segment
		(start 361.755436 -116.213636)
		(end 356.342442 -117.676676)
		(width 0.1143)
		(layer "F.Cu")
		(net "P3E_CPU0_PE1_PCH_C_TXN<8>")
	)
	(segment
		(start 365.833152 -116.79047)
		(end 365.8108 -116.79047)
		(width 0.0889)
		(layer "F.Cu")
		(net "P3E_CPU0_PE1_PCH_C_TXN<8>")
	)
	(segment
		(start 372.82374 -119.8118)
		(end 372.55704 -119.8118)
		(width 0.0889)
		(layer "F.Cu")
		(net "P3E_CPU0_PE1_PCH_C_TXN<8>")
	)
	(segment
		(start 345.731592 -117.088158)
		(end 345.619578 -117.200172)
		(width 0.1143)
		(layer "F.Cu")
		(net "P3E_CPU0_PE1_PCH_C_TXN<8>")
	)
	(segment
		(start 372.11254 -119.8118)
		(end 371.84584 -119.8118)
		(width 0.0889)
		(layer "F.Cu")
		(net "P3E_CPU0_PE1_PCH_C_TXN<8>")
	)
	(segment
		(start 371.75694 -119.7229)
		(end 371.49024 -119.7229)
		(width 0.0889)
		(layer "F.Cu")
		(net "P3E_CPU0_PE1_PCH_C_TXN<8>")
	)
	(segment
		(start 367.276126 -117.71122)
		(end 367.087658 -117.522752)
		(width 0.0889)
		(layer "F.Cu")
		(net "P3E_CPU0_PE1_PCH_C_TXN<8>")
	)
	(segment
		(start 370.06784 -119.7229)
		(end 369.97894 -119.8118)
		(width 0.0889)
		(layer "F.Cu")
		(net "P3E_CPU0_PE1_PCH_C_TXN<8>")
	)
	(segment
		(start 370.33454 -119.7229)
		(end 370.06784 -119.7229)
		(width 0.0889)
		(layer "F.Cu")
		(net "P3E_CPU0_PE1_PCH_C_TXN<8>")
	)
	(segment
		(start 356.342442 -117.676676)
		(end 354.351082 -117.088158)
		(width 0.1143)
		(layer "F.Cu")
		(net "P3E_CPU0_PE1_PCH_C_TXN<8>")
	)
	(segment
		(start 368.281966 -118.84279)
		(end 368.281966 -118.71706)
		(width 0.0889)
		(layer "F.Cu")
		(net "P3E_CPU0_PE1_PCH_C_TXN<8>")
	)
	(segment
		(start 335.598262 -117.200172)
		(end 334.802734 -117.9957)
		(width 0.1143)
		(layer "F.Cu")
		(net "P3E_CPU0_PE1_PCH_C_TXN<8>")
	)
	(segment
		(start 373.621554 -119.280686)
		(end 373.17934 -119.7229)
		(width 0.0889)
		(layer "F.Cu")
		(net "P3E_CPU0_PE1_PCH_C_TXN<8>")
	)
	(segment
		(start 369.287806 -119.7229)
		(end 369.099338 -119.534432)
		(width 0.0889)
		(layer "F.Cu")
		(net "P3E_CPU0_PE1_PCH_C_TXN<8>")
	)
	(segment
		(start 373.747284 -119.280686)
		(end 373.621554 -119.280686)
		(width 0.0889)
		(layer "F.Cu")
		(net "P3E_CPU0_PE1_PCH_C_TXN<8>")
	)
	(segment
		(start 371.84584 -119.8118)
		(end 371.75694 -119.7229)
		(width 0.0889)
		(layer "F.Cu")
		(net "P3E_CPU0_PE1_PCH_C_TXN<8>")
	)
	(segment
		(start 345.619578 -117.200172)
		(end 335.598262 -117.200172)
		(width 0.1143)
		(layer "F.Cu")
		(net "P3E_CPU0_PE1_PCH_C_TXN<8>")
	)
	(segment
		(start 372.55704 -119.8118)
		(end 372.46814 -119.7229)
		(width 0.0889)
		(layer "F.Cu")
		(net "P3E_CPU0_PE1_PCH_C_TXN<8>")
	)
	(segment
		(start 370.42344 -119.8118)
		(end 370.33454 -119.7229)
		(width 0.0889)
		(layer "F.Cu")
		(net "P3E_CPU0_PE1_PCH_C_TXN<8>")
	)
	(segment
		(start 368.093498 -118.528592)
		(end 367.967768 -118.528592)
		(width 0.0889)
		(layer "F.Cu")
		(net "P3E_CPU0_PE1_PCH_C_TXN<8>")
	)
	(segment
		(start 367.590578 -118.025672)
		(end 367.464848 -118.025672)
		(width 0.0889)
		(layer "F.Cu")
		(net "P3E_CPU0_PE1_PCH_C_TXN<8>")
	)
	(segment
		(start 366.961928 -117.522752)
		(end 366.773206 -117.33403)
		(width 0.0889)
		(layer "F.Cu")
		(net "P3E_CPU0_PE1_PCH_C_TXN<8>")
	)
	(segment
		(start 373.944896 -118.957344)
		(end 373.944896 -119.083074)
		(width 0.0889)
		(layer "F.Cu")
		(net "P3E_CPU0_PE1_PCH_C_TXN<8>")
	)
	(segment
		(start 368.973608 -119.534432)
		(end 368.784886 -119.34571)
		(width 0.0889)
		(layer "F.Cu")
		(net "P3E_CPU0_PE1_PCH_C_TXN<8>")
	)
	(segment
		(start 366.773206 -117.2083)
		(end 366.329976 -116.76507)
		(width 0.0889)
		(layer "F.Cu")
		(net "P3E_CPU0_PE1_PCH_C_TXN<8>")
	)
	(segment
		(start 365.8108 -116.79047)
		(end 365.23422 -116.79047)
		(width 0.1143)
		(layer "F.Cu")
		(net "P3E_CPU0_PE1_PCH_C_TXN<8>")
	)
	(segment
		(start 369.099338 -119.534432)
		(end 368.973608 -119.534432)
		(width 0.0889)
		(layer "F.Cu")
		(net "P3E_CPU0_PE1_PCH_C_TXN<8>")
	)
	(segment
		(start 333.78902 -118.11)
		(end 333.78902 -118.5164)
		(width 0.1143)
		(layer "F.Cu")
		(net "P3E_CPU0_PE1_PCH_C_TXN<8>")
	)
	(segment
		(start 367.464848 -118.025672)
		(end 367.276126 -117.83695)
		(width 0.0889)
		(layer "F.Cu")
		(net "P3E_CPU0_PE1_PCH_C_TXN<8>")
	)
	(segment
		(start 367.779046 -118.33987)
		(end 367.779046 -118.21414)
		(width 0.0889)
		(layer "F.Cu")
		(net "P3E_CPU0_PE1_PCH_C_TXN<8>")
	)
	(segment
		(start 371.13464 -119.8118)
		(end 371.04574 -119.7229)
		(width 0.0889)
		(layer "F.Cu")
		(net "P3E_CPU0_PE1_PCH_C_TXN<8>")
	)
	(segment
		(start 334.802734 -117.9957)
		(end 333.90332 -117.9957)
		(width 0.1143)
		(layer "F.Cu")
		(net "P3E_CPU0_PE1_PCH_C_TXN<8>")
	)
	(segment
		(start 367.967768 -118.528592)
		(end 367.779046 -118.33987)
		(width 0.0889)
		(layer "F.Cu")
		(net "P3E_CPU0_PE1_PCH_C_TXN<8>")
	)
	(segment
		(start 368.596418 -119.031512)
		(end 368.470688 -119.031512)
		(width 0.0889)
		(layer "F.Cu")
		(net "P3E_CPU0_PE1_PCH_C_TXN<8>")
	)
	(segment
		(start 367.087658 -117.522752)
		(end 366.961928 -117.522752)
		(width 0.0889)
		(layer "F.Cu")
		(net "P3E_CPU0_PE1_PCH_C_TXN<8>")
	)
	(segment
		(start 368.784886 -119.21998)
		(end 368.596418 -119.031512)
		(width 0.0889)
		(layer "F.Cu")
		(net "P3E_CPU0_PE1_PCH_C_TXN<8>")
	)
	(segment
		(start 369.71224 -119.8118)
		(end 369.62334 -119.7229)
		(width 0.0889)
		(layer "F.Cu")
		(net "P3E_CPU0_PE1_PCH_C_TXN<8>")
	)
	(segment
		(start 372.46814 -119.7229)
		(end 372.20144 -119.7229)
		(width 0.0889)
		(layer "F.Cu")
		(net "P3E_CPU0_PE1_PCH_C_TXN<8>")
	)
	(segment
		(start 370.77904 -119.7229)
		(end 370.69014 -119.8118)
		(width 0.0889)
		(layer "F.Cu")
		(net "P3E_CPU0_PE1_PCH_C_TXN<8>")
	)
	(segment
		(start 367.779046 -118.21414)
		(end 367.590578 -118.025672)
		(width 0.0889)
		(layer "F.Cu")
		(net "P3E_CPU0_PE1_PCH_C_TXN<8>")
	)
	(segment
		(start 373.17934 -119.7229)
		(end 372.91264 -119.7229)
		(width 0.0889)
		(layer "F.Cu")
		(net "P3E_CPU0_PE1_PCH_C_TXN<8>")
	)
	(segment
		(start 369.97894 -119.8118)
		(end 369.71224 -119.8118)
		(width 0.0889)
		(layer "F.Cu")
		(net "P3E_CPU0_PE1_PCH_C_TXN<8>")
	)
	(segment
		(start 366.773206 -117.33403)
		(end 366.773206 -117.2083)
		(width 0.0889)
		(layer "F.Cu")
		(net "P3E_CPU0_PE1_PCH_C_TXN<8>")
	)
	(segment
		(start 354.351082 -117.088158)
		(end 345.731592 -117.088158)
		(width 0.1143)
		(layer "F.Cu")
		(net "P3E_CPU0_PE1_PCH_C_TXN<8>")
	)
	(segment
		(start 374.674892 -118.854982)
		(end 374.579642 -118.759732)
		(width 0.0889)
		(layer "F.Cu")
		(net "P3E_CPU0_PE1_PCH_C_TXN<8>")
	)
	(segment
		(start 364.365032 -116.79047)
		(end 361.755436 -116.213636)
		(width 0.1143)
		(layer "F.Cu")
		(net "P3E_CPU0_PE1_PCH_C_TXN<8>")
	)
	(segment
		(start 367.276126 -117.83695)
		(end 367.276126 -117.71122)
		(width 0.0889)
		(layer "F.Cu")
		(net "P3E_CPU0_PE1_PCH_C_TXN<8>")
	)
	(segment
		(start 369.62334 -119.7229)
		(end 369.287806 -119.7229)
		(width 0.0889)
		(layer "F.Cu")
		(net "P3E_CPU0_PE1_PCH_C_TXN<8>")
	)
	(segment
		(start 368.281966 -118.71706)
		(end 368.093498 -118.528592)
		(width 0.0889)
		(layer "F.Cu")
		(net "P3E_CPU0_PE1_PCH_C_TXN<8>")
	)
	(segment
		(start 366.329976 -116.76507)
		(end 365.858552 -116.76507)
		(width 0.0889)
		(layer "F.Cu")
		(net "P3E_CPU0_PE1_PCH_C_TXN<8>")
	)
	(segment
		(start 374.142508 -118.759732)
		(end 373.944896 -118.957344)
		(width 0.0889)
		(layer "F.Cu")
		(net "P3E_CPU0_PE1_PCH_C_TXN<8>")
	)
	(via
		(at 365.23422 -116.79047)
		(size 0.508)
		(drill 0.254)
		(layers "F.Cu" "B.Cu")
		(net "P3E_CPU0_PE1_PCH_C_TXN<8>")
	)
	(segment
		(start 372.841012 -125.495812)
		(end 372.65229 -125.684534)
		(width 0.0889)
		(layer "F.Cu")
		(net "P3E_CPU0_PE1_PCH_C_TXN<15>")
	)
	(segment
		(start 372.841012 -125.370082)
		(end 372.841012 -125.495812)
		(width 0.0889)
		(layer "F.Cu")
		(net "P3E_CPU0_PE1_PCH_C_TXN<15>")
	)
	(segment
		(start 372.52656 -125.684534)
		(end 372.338092 -125.873002)
		(width 0.0889)
		(layer "F.Cu")
		(net "P3E_CPU0_PE1_PCH_C_TXN<15>")
	)
	(segment
		(start 370.271294 -127.0381)
		(end 370.004594 -127.0381)
		(width 0.0889)
		(layer "F.Cu")
		(net "P3E_CPU0_PE1_PCH_C_TXN<15>")
	)
	(segment
		(start 355.6127 -127.4953)
		(end 350.417384 -127.4953)
		(width 0.1143)
		(layer "F.Cu")
		(net "P3E_CPU0_PE1_PCH_C_TXN<15>")
	)
	(segment
		(start 372.338092 -125.873002)
		(end 372.338092 -125.998732)
		(width 0.0889)
		(layer "F.Cu")
		(net "P3E_CPU0_PE1_PCH_C_TXN<15>")
	)
	(segment
		(start 321.6148 -124.079)
		(end 321.5005 -124.1933)
		(width 0.1143)
		(layer "F.Cu")
		(net "P3E_CPU0_PE1_PCH_C_TXN<15>")
	)
	(segment
		(start 368.80292 -127.23368)
		(end 368.80292 -127.359156)
		(width 0.0889)
		(layer "F.Cu")
		(net "P3E_CPU0_PE1_PCH_C_TXN<15>")
	)
	(segment
		(start 348.808294 -125.88621)
		(end 345.737688 -125.88621)
		(width 0.1143)
		(layer "F.Cu")
		(net "P3E_CPU0_PE1_PCH_C_TXN<15>")
	)
	(segment
		(start 357.745538 -128.43764)
		(end 357.610918 -128.410716)
		(width 0.1143)
		(layer "F.Cu")
		(net "P3E_CPU0_PE1_PCH_C_TXN<15>")
	)
	(segment
		(start 372.338092 -125.998732)
		(end 372.14937 -126.187454)
		(width 0.0889)
		(layer "F.Cu")
		(net "P3E_CPU0_PE1_PCH_C_TXN<15>")
	)
	(segment
		(start 373.02948 -125.181614)
		(end 372.841012 -125.370082)
		(width 0.0889)
		(layer "F.Cu")
		(net "P3E_CPU0_PE1_PCH_C_TXN<15>")
	)
	(segment
		(start 362.71073 -128.5113)
		(end 360.4133 -128.970786)
		(width 0.1143)
		(layer "F.Cu")
		(net "P3E_CPU0_PE1_PCH_C_TXN<15>")
	)
	(segment
		(start 356.237794 -127.4953)
		(end 355.6127 -127.4953)
		(width 0.1143)
		(layer "F.Cu")
		(net "P3E_CPU0_PE1_PCH_C_TXN<15>")
	)
	(segment
		(start 373.5324 -123.826524)
		(end 373.5324 -124.004324)
		(width 0.0889)
		(layer "F.Cu")
		(net "P3E_CPU0_PE1_PCH_C_TXN<15>")
	)
	(segment
		(start 370.715794 -127.0381)
		(end 370.626894 -126.9492)
		(width 0.0889)
		(layer "F.Cu")
		(net "P3E_CPU0_PE1_PCH_C_TXN<15>")
	)
	(segment
		(start 365.830866 -128.5113)
		(end 365.716566 -128.6256)
		(width 0.1143)
		(layer "F.Cu")
		(net "P3E_CPU0_PE1_PCH_C_TXN<15>")
	)
	(segment
		(start 371.835172 -126.375922)
		(end 371.835172 -126.501652)
		(width 0.0889)
		(layer "F.Cu")
		(net "P3E_CPU0_PE1_PCH_C_TXN<15>")
	)
	(segment
		(start 368.80292 -127.359156)
		(end 368.614452 -127.547878)
		(width 0.0889)
		(layer "F.Cu")
		(net "P3E_CPU0_PE1_PCH_C_TXN<15>")
	)
	(segment
		(start 375.00687 -122.251724)
		(end 374.724676 -122.368564)
		(width 0.0889)
		(layer "F.Cu")
		(net "P3E_CPU0_PE1_PCH_C_TXN<15>")
	)
	(segment
		(start 369.204494 -126.9492)
		(end 369.0874 -126.9492)
		(width 0.0889)
		(layer "F.Cu")
		(net "P3E_CPU0_PE1_PCH_C_TXN<15>")
	)
	(segment
		(start 374.724676 -122.368564)
		(end 374.635014 -122.458226)
		(width 0.0889)
		(layer "F.Cu")
		(net "P3E_CPU0_PE1_PCH_C_TXN<15>")
	)
	(segment
		(start 365.259366 -128.5113)
		(end 362.71073 -128.5113)
		(width 0.1143)
		(layer "F.Cu")
		(net "P3E_CPU0_PE1_PCH_C_TXN<15>")
	)
	(segment
		(start 371.835172 -126.501652)
		(end 371.64645 -126.690374)
		(width 0.0889)
		(layer "F.Cu")
		(net "P3E_CPU0_PE1_PCH_C_TXN<15>")
	)
	(segment
		(start 325.344282 -125.598936)
		(end 324.346824 -125.821186)
		(width 0.1143)
		(layer "F.Cu")
		(net "P3E_CPU0_PE1_PCH_C_TXN<15>")
	)
	(segment
		(start 365.716566 -128.6256)
		(end 365.373666 -128.6256)
		(width 0.1143)
		(layer "F.Cu")
		(net "P3E_CPU0_PE1_PCH_C_TXN<15>")
	)
	(segment
		(start 371.52072 -126.690374)
		(end 371.261894 -126.9492)
		(width 0.0889)
		(layer "F.Cu")
		(net "P3E_CPU0_PE1_PCH_C_TXN<15>")
	)
	(segment
		(start 373.5324 -123.149868)
		(end 373.5324 -123.450604)
		(width 0.0889)
		(layer "F.Cu")
		(net "P3E_CPU0_PE1_PCH_C_TXN<15>")
	)
	(segment
		(start 369.0874 -126.9492)
		(end 368.80292 -127.23368)
		(width 0.0889)
		(layer "F.Cu")
		(net "P3E_CPU0_PE1_PCH_C_TXN<15>")
	)
	(segment
		(start 328.728324 -127.352806)
		(end 325.344282 -125.598936)
		(width 0.1143)
		(layer "F.Cu")
		(net "P3E_CPU0_PE1_PCH_C_TXN<15>")
	)
	(segment
		(start 373.63146 -124.281184)
		(end 373.5324 -124.380244)
		(width 0.0889)
		(layer "F.Cu")
		(net "P3E_CPU0_PE1_PCH_C_TXN<15>")
	)
	(segment
		(start 368.614452 -127.547878)
		(end 368.488722 -127.547878)
		(width 0.0889)
		(layer "F.Cu")
		(net "P3E_CPU0_PE1_PCH_C_TXN<15>")
	)
	(segment
		(start 330.154534 -127.068326)
		(end 328.728324 -127.352806)
		(width 0.1143)
		(layer "F.Cu")
		(net "P3E_CPU0_PE1_PCH_C_TXN<15>")
	)
	(segment
		(start 373.63146 -123.549664)
		(end 373.63146 -123.727464)
		(width 0.0889)
		(layer "F.Cu")
		(net "P3E_CPU0_PE1_PCH_C_TXN<15>")
	)
	(segment
		(start 371.261894 -126.9492)
		(end 371.071394 -126.9492)
		(width 0.0889)
		(layer "F.Cu")
		(net "P3E_CPU0_PE1_PCH_C_TXN<15>")
	)
	(segment
		(start 331.71765 -126.098554)
		(end 330.154534 -127.068326)
		(width 0.1143)
		(layer "F.Cu")
		(net "P3E_CPU0_PE1_PCH_C_TXN<15>")
	)
	(segment
		(start 373.15521 -125.181614)
		(end 373.02948 -125.181614)
		(width 0.0889)
		(layer "F.Cu")
		(net "P3E_CPU0_PE1_PCH_C_TXN<15>")
	)
	(segment
		(start 372.02364 -126.187454)
		(end 371.835172 -126.375922)
		(width 0.0889)
		(layer "F.Cu")
		(net "P3E_CPU0_PE1_PCH_C_TXN<15>")
	)
	(segment
		(start 366.982502 -128.5113)
		(end 365.830866 -128.5113)
		(width 0.1143)
		(layer "F.Cu")
		(net "P3E_CPU0_PE1_PCH_C_TXN<15>")
	)
	(segment
		(start 369.594638 -127.003556)
		(end 369.25885 -127.003556)
		(width 0.0889)
		(layer "F.Cu")
		(net "P3E_CPU0_PE1_PCH_C_TXN<15>")
	)
	(segment
		(start 373.63146 -123.727464)
		(end 373.5324 -123.826524)
		(width 0.0889)
		(layer "F.Cu")
		(net "P3E_CPU0_PE1_PCH_C_TXN<15>")
	)
	(segment
		(start 357.7463 -128.437894)
		(end 357.745538 -128.43764)
		(width 0.1143)
		(layer "F.Cu")
		(net "P3E_CPU0_PE1_PCH_C_TXN<15>")
	)
	(segment
		(start 369.648994 -126.9492)
		(end 369.594638 -127.003556)
		(width 0.0889)
		(layer "F.Cu")
		(net "P3E_CPU0_PE1_PCH_C_TXN<15>")
	)
	(segment
		(start 372.14937 -126.187454)
		(end 372.02364 -126.187454)
		(width 0.0889)
		(layer "F.Cu")
		(net "P3E_CPU0_PE1_PCH_C_TXN<15>")
	)
	(segment
		(start 368.111532 -128.050798)
		(end 367.985802 -128.050798)
		(width 0.0889)
		(layer "F.Cu")
		(net "P3E_CPU0_PE1_PCH_C_TXN<15>")
	)
	(segment
		(start 324.346824 -125.821186)
		(end 323.218556 -125.31979)
		(width 0.1143)
		(layer "F.Cu")
		(net "P3E_CPU0_PE1_PCH_C_TXN<15>")
	)
	(segment
		(start 367.0046 -128.5113)
		(end 366.982502 -128.5113)
		(width 0.0889)
		(layer "F.Cu")
		(net "P3E_CPU0_PE1_PCH_C_TXN<15>")
	)
	(segment
		(start 369.915694 -126.9492)
		(end 369.648994 -126.9492)
		(width 0.0889)
		(layer "F.Cu")
		(net "P3E_CPU0_PE1_PCH_C_TXN<15>")
	)
	(segment
		(start 367.03 -128.4859)
		(end 367.0046 -128.5113)
		(width 0.0889)
		(layer "F.Cu")
		(net "P3E_CPU0_PE1_PCH_C_TXN<15>")
	)
	(segment
		(start 373.5324 -124.380244)
		(end 373.5324 -124.678694)
		(width 0.0889)
		(layer "F.Cu")
		(net "P3E_CPU0_PE1_PCH_C_TXN<15>")
	)
	(segment
		(start 370.982494 -127.0381)
		(end 370.715794 -127.0381)
		(width 0.0889)
		(layer "F.Cu")
		(net "P3E_CPU0_PE1_PCH_C_TXN<15>")
	)
	(segment
		(start 373.343932 -124.867162)
		(end 373.343932 -124.992892)
		(width 0.0889)
		(layer "F.Cu")
		(net "P3E_CPU0_PE1_PCH_C_TXN<15>")
	)
	(segment
		(start 369.25885 -127.003556)
		(end 369.204494 -126.9492)
		(width 0.0889)
		(layer "F.Cu")
		(net "P3E_CPU0_PE1_PCH_C_TXN<15>")
	)
	(segment
		(start 373.593868 -123.001786)
		(end 373.5324 -123.149868)
		(width 0.0889)
		(layer "F.Cu")
		(net "P3E_CPU0_PE1_PCH_C_TXN<15>")
	)
	(segment
		(start 373.343932 -124.992892)
		(end 373.15521 -125.181614)
		(width 0.0889)
		(layer "F.Cu")
		(net "P3E_CPU0_PE1_PCH_C_TXN<15>")
	)
	(segment
		(start 323.218556 -125.31979)
		(end 322.755514 -124.64288)
		(width 0.1143)
		(layer "F.Cu")
		(net "P3E_CPU0_PE1_PCH_C_TXN<15>")
	)
	(segment
		(start 375.089928 -122.355102)
		(end 375.089928 -122.334782)
		(width 0.0889)
		(layer "F.Cu")
		(net "P3E_CPU0_PE1_PCH_C_TXN<15>")
	)
	(segment
		(start 370.004594 -127.0381)
		(end 369.915694 -126.9492)
		(width 0.0889)
		(layer "F.Cu")
		(net "P3E_CPU0_PE1_PCH_C_TXN<15>")
	)
	(segment
		(start 370.626894 -126.9492)
		(end 370.360194 -126.9492)
		(width 0.0889)
		(layer "F.Cu")
		(net "P3E_CPU0_PE1_PCH_C_TXN<15>")
	)
	(segment
		(start 373.5324 -124.004324)
		(end 373.63146 -124.103384)
		(width 0.0889)
		(layer "F.Cu")
		(net "P3E_CPU0_PE1_PCH_C_TXN<15>")
	)
	(segment
		(start 371.071394 -126.9492)
		(end 370.982494 -127.0381)
		(width 0.0889)
		(layer "F.Cu")
		(net "P3E_CPU0_PE1_PCH_C_TXN<15>")
	)
	(segment
		(start 368.488722 -127.547878)
		(end 368.300254 -127.736346)
		(width 0.0889)
		(layer "F.Cu")
		(net "P3E_CPU0_PE1_PCH_C_TXN<15>")
	)
	(segment
		(start 367.5507 -128.4859)
		(end 367.03 -128.4859)
		(width 0.0889)
		(layer "F.Cu")
		(net "P3E_CPU0_PE1_PCH_C_TXN<15>")
	)
	(segment
		(start 350.417384 -127.4953)
		(end 348.808294 -125.88621)
		(width 0.1143)
		(layer "F.Cu")
		(net "P3E_CPU0_PE1_PCH_C_TXN<15>")
	)
	(segment
		(start 375.089928 -122.334782)
		(end 375.00687 -122.251724)
		(width 0.0889)
		(layer "F.Cu")
		(net "P3E_CPU0_PE1_PCH_C_TXN<15>")
	)
	(segment
		(start 368.300254 -127.862076)
		(end 368.111532 -128.050798)
		(width 0.0889)
		(layer "F.Cu")
		(net "P3E_CPU0_PE1_PCH_C_TXN<15>")
	)
	(segment
		(start 322.755514 -124.64288)
		(end 321.728846 -124.079)
		(width 0.1143)
		(layer "F.Cu")
		(net "P3E_CPU0_PE1_PCH_C_TXN<15>")
	)
	(segment
		(start 373.5324 -124.678694)
		(end 373.343932 -124.867162)
		(width 0.0889)
		(layer "F.Cu")
		(net "P3E_CPU0_PE1_PCH_C_TXN<15>")
	)
	(segment
		(start 368.300254 -127.736346)
		(end 368.300254 -127.862076)
		(width 0.0889)
		(layer "F.Cu")
		(net "P3E_CPU0_PE1_PCH_C_TXN<15>")
	)
	(segment
		(start 367.985802 -128.050798)
		(end 367.5507 -128.4859)
		(width 0.0889)
		(layer "F.Cu")
		(net "P3E_CPU0_PE1_PCH_C_TXN<15>")
	)
	(segment
		(start 374.635014 -122.458226)
		(end 373.78513 -122.81027)
		(width 0.0889)
		(layer "F.Cu")
		(net "P3E_CPU0_PE1_PCH_C_TXN<15>")
	)
	(segment
		(start 372.65229 -125.684534)
		(end 372.52656 -125.684534)
		(width 0.0889)
		(layer "F.Cu")
		(net "P3E_CPU0_PE1_PCH_C_TXN<15>")
	)
	(segment
		(start 345.737688 -125.88621)
		(end 345.525598 -126.0983)
		(width 0.1143)
		(layer "F.Cu")
		(net "P3E_CPU0_PE1_PCH_C_TXN<15>")
	)
	(segment
		(start 373.5324 -123.450604)
		(end 373.63146 -123.549664)
		(width 0.0889)
		(layer "F.Cu")
		(net "P3E_CPU0_PE1_PCH_C_TXN<15>")
	)
	(segment
		(start 365.373666 -128.6256)
		(end 365.259366 -128.5113)
		(width 0.1143)
		(layer "F.Cu")
		(net "P3E_CPU0_PE1_PCH_C_TXN<15>")
	)
	(segment
		(start 370.360194 -126.9492)
		(end 370.271294 -127.0381)
		(width 0.0889)
		(layer "F.Cu")
		(net "P3E_CPU0_PE1_PCH_C_TXN<15>")
	)
	(segment
		(start 371.64645 -126.690374)
		(end 371.52072 -126.690374)
		(width 0.0889)
		(layer "F.Cu")
		(net "P3E_CPU0_PE1_PCH_C_TXN<15>")
	)
	(segment
		(start 321.728846 -124.079)
		(end 321.6148 -124.079)
		(width 0.1143)
		(layer "F.Cu")
		(net "P3E_CPU0_PE1_PCH_C_TXN<15>")
	)
	(segment
		(start 357.610918 -128.410716)
		(end 356.237794 -127.4953)
		(width 0.1143)
		(layer "F.Cu")
		(net "P3E_CPU0_PE1_PCH_C_TXN<15>")
	)
	(segment
		(start 373.63146 -124.103384)
		(end 373.63146 -124.281184)
		(width 0.0889)
		(layer "F.Cu")
		(net "P3E_CPU0_PE1_PCH_C_TXN<15>")
	)
	(segment
		(start 321.5005 -124.1933)
		(end 321.5005 -124.587)
		(width 0.1143)
		(layer "F.Cu")
		(net "P3E_CPU0_PE1_PCH_C_TXN<15>")
	)
	(segment
		(start 360.4133 -128.970786)
		(end 357.7463 -128.437894)
		(width 0.1143)
		(layer "F.Cu")
		(net "P3E_CPU0_PE1_PCH_C_TXN<15>")
	)
	(segment
		(start 373.78513 -122.81027)
		(end 373.593868 -123.001786)
		(width 0.0889)
		(layer "F.Cu")
		(net "P3E_CPU0_PE1_PCH_C_TXN<15>")
	)
	(segment
		(start 331.717904 -126.0983)
		(end 331.71765 -126.098554)
		(width 0.1143)
		(layer "F.Cu")
		(net "P3E_CPU0_PE1_PCH_C_TXN<15>")
	)
	(segment
		(start 345.525598 -126.0983)
		(end 331.717904 -126.0983)
		(width 0.1143)
		(layer "F.Cu")
		(net "P3E_CPU0_PE1_PCH_C_TXN<15>")
	)
	(via
		(at 355.6127 -127.4953)
		(size 0.508)
		(drill 0.254)
		(layers "F.Cu" "B.Cu")
		(net "P3E_CPU0_PE1_PCH_C_TXN<15>")
	)
	(segment
		(start 369.4176 -126.4412)
		(end 369.3287 -126.3523)
		(width 0.0889)
		(layer "F.Cu")
		(net "P3E_CPU0_PE1_PCH_C_TXN<14>")
	)
	(segment
		(start 370.0399 -126.3523)
		(end 369.7732 -126.3523)
		(width 0.0889)
		(layer "F.Cu")
		(net "P3E_CPU0_PE1_PCH_C_TXN<14>")
	)
	(segment
		(start 368.7064 -126.4412)
		(end 368.6175 -126.3523)
		(width 0.0889)
		(layer "F.Cu")
		(net "P3E_CPU0_PE1_PCH_C_TXN<14>")
	)
	(segment
		(start 371.444012 -125.785118)
		(end 371.25529 -125.97384)
		(width 0.0889)
		(layer "F.Cu")
		(net "P3E_CPU0_PE1_PCH_C_TXN<14>")
	)
	(segment
		(start 370.7511 -126.3523)
		(end 370.4844 -126.3523)
		(width 0.0889)
		(layer "F.Cu")
		(net "P3E_CPU0_PE1_PCH_C_TXN<14>")
	)
	(segment
		(start 366.4966 -127.508)
		(end 366.4077 -127.4191)
		(width 0.0889)
		(layer "F.Cu")
		(net "P3E_CPU0_PE1_PCH_C_TXN<14>")
	)
	(segment
		(start 365.0742 -127.508)
		(end 364.9853 -127.4191)
		(width 0.0889)
		(layer "F.Cu")
		(net "P3E_CPU0_PE1_PCH_C_TXN<14>")
	)
	(segment
		(start 367.1189 -127.4191)
		(end 366.8522 -127.4191)
		(width 0.0889)
		(layer "F.Cu")
		(net "P3E_CPU0_PE1_PCH_C_TXN<14>")
	)
	(segment
		(start 374.484138 -121.854976)
		(end 374.177814 -122.1613)
		(width 0.0889)
		(layer "F.Cu")
		(net "P3E_CPU0_PE1_PCH_C_TXN<14>")
	)
	(segment
		(start 362.978954 -127.4445)
		(end 360.4006 -127.96012)
		(width 0.1143)
		(layer "F.Cu")
		(net "P3E_CPU0_PE1_PCH_C_TXN<14>")
	)
	(segment
		(start 331.488796 -125.112526)
		(end 332.9178 -125.112526)
		(width 0.1143)
		(layer "F.Cu")
		(net "P3E_CPU0_PE1_PCH_C_TXN<14>")
	)
	(segment
		(start 372.2243 -124.256546)
		(end 372.2243 -124.523246)
		(width 0.0889)
		(layer "F.Cu")
		(net "P3E_CPU0_PE1_PCH_C_TXN<14>")
	)
	(segment
		(start 325.50735 -123.31065)
		(end 325.702676 -123.31065)
		(width 0.1143)
		(layer "F.Cu")
		(net "P3E_CPU0_PE1_PCH_C_TXN<14>")
	)
	(segment
		(start 345.050618 -125.112526)
		(end 332.9178 -125.112526)
		(width 0.1143)
		(layer "F.Cu")
		(net "P3E_CPU0_PE1_PCH_C_TXN<14>")
	)
	(segment
		(start 371.12956 -125.97384)
		(end 370.7511 -126.3523)
		(width 0.0889)
		(layer "F.Cu")
		(net "P3E_CPU0_PE1_PCH_C_TXN<14>")
	)
	(segment
		(start 373.357394 -122.501152)
		(end 373.168926 -122.68962)
		(width 0.0889)
		(layer "F.Cu")
		(net "P3E_CPU0_PE1_PCH_C_TXN<14>")
	)
	(segment
		(start 372.351554 -123.506992)
		(end 372.1354 -123.723146)
		(width 0.0889)
		(layer "F.Cu")
		(net "P3E_CPU0_PE1_PCH_C_TXN<14>")
	)
	(segment
		(start 372.980204 -123.004072)
		(end 372.854474 -123.004072)
		(width 0.0889)
		(layer "F.Cu")
		(net "P3E_CPU0_PE1_PCH_C_TXN<14>")
	)
	(segment
		(start 360.4006 -127.96012)
		(end 358.121712 -127.504444)
		(width 0.1143)
		(layer "F.Cu")
		(net "P3E_CPU0_PE1_PCH_C_TXN<14>")
	)
	(segment
		(start 353.948492 -124.721366)
		(end 349.59925 -124.721366)
		(width 0.1143)
		(layer "F.Cu")
		(net "P3E_CPU0_PE1_PCH_C_TXN<14>")
	)
	(segment
		(start 367.63198 -126.90602)
		(end 367.1189 -127.4191)
		(width 0.0889)
		(layer "F.Cu")
		(net "P3E_CPU0_PE1_PCH_C_TXN<14>")
	)
	(segment
		(start 367.75771 -126.90602)
		(end 367.63198 -126.90602)
		(width 0.0889)
		(layer "F.Cu")
		(net "P3E_CPU0_PE1_PCH_C_TXN<14>")
	)
	(segment
		(start 369.6843 -126.4412)
		(end 369.4176 -126.4412)
		(width 0.0889)
		(layer "F.Cu")
		(net "P3E_CPU0_PE1_PCH_C_TXN<14>")
	)
	(segment
		(start 368.6175 -126.3523)
		(end 368.1857 -126.3523)
		(width 0.0889)
		(layer "F.Cu")
		(net "P3E_CPU0_PE1_PCH_C_TXN<14>")
	)
	(segment
		(start 345.684602 -124.478542)
		(end 345.050618 -125.112526)
		(width 0.1143)
		(layer "F.Cu")
		(net "P3E_CPU0_PE1_PCH_C_TXN<14>")
	)
	(segment
		(start 367.946432 -126.717298)
		(end 367.75771 -126.90602)
		(width 0.0889)
		(layer "F.Cu")
		(net "P3E_CPU0_PE1_PCH_C_TXN<14>")
	)
	(segment
		(start 364.622842 -127.4191)
		(end 364.597442 -127.4445)
		(width 0.0889)
		(layer "F.Cu")
		(net "P3E_CPU0_PE1_PCH_C_TXN<14>")
	)
	(segment
		(start 357.156512 -126.860808)
		(end 355.886512 -126.013972)
		(width 0.1143)
		(layer "F.Cu")
		(net "P3E_CPU0_PE1_PCH_C_TXN<14>")
	)
	(segment
		(start 366.0521 -127.508)
		(end 365.7854 -127.508)
		(width 0.0889)
		(layer "F.Cu")
		(net "P3E_CPU0_PE1_PCH_C_TXN<14>")
	)
	(segment
		(start 371.75821 -125.47092)
		(end 371.63248 -125.47092)
		(width 0.0889)
		(layer "F.Cu")
		(net "P3E_CPU0_PE1_PCH_C_TXN<14>")
	)
	(segment
		(start 370.3955 -126.4412)
		(end 370.1288 -126.4412)
		(width 0.0889)
		(layer "F.Cu")
		(net "P3E_CPU0_PE1_PCH_C_TXN<14>")
	)
	(segment
		(start 349.356426 -124.478542)
		(end 345.684602 -124.478542)
		(width 0.1143)
		(layer "F.Cu")
		(net "P3E_CPU0_PE1_PCH_C_TXN<14>")
	)
	(segment
		(start 370.1288 -126.4412)
		(end 370.0399 -126.3523)
		(width 0.0889)
		(layer "F.Cu")
		(net "P3E_CPU0_PE1_PCH_C_TXN<14>")
	)
	(segment
		(start 371.946932 -125.282198)
		(end 371.75821 -125.47092)
		(width 0.0889)
		(layer "F.Cu")
		(net "P3E_CPU0_PE1_PCH_C_TXN<14>")
	)
	(segment
		(start 364.575344 -127.4445)
		(end 362.978954 -127.4445)
		(width 0.1143)
		(layer "F.Cu")
		(net "P3E_CPU0_PE1_PCH_C_TXN<14>")
	)
	(segment
		(start 355.109018 -125.495304)
		(end 353.948492 -124.721366)
		(width 0.1143)
		(layer "F.Cu")
		(net "P3E_CPU0_PE1_PCH_C_TXN<14>")
	)
	(segment
		(start 368.1857 -126.3523)
		(end 367.946432 -126.591568)
		(width 0.0889)
		(layer "F.Cu")
		(net "P3E_CPU0_PE1_PCH_C_TXN<14>")
	)
	(segment
		(start 366.4077 -127.4191)
		(end 366.141 -127.4191)
		(width 0.0889)
		(layer "F.Cu")
		(net "P3E_CPU0_PE1_PCH_C_TXN<14>")
	)
	(segment
		(start 369.3287 -126.3523)
		(end 369.062 -126.3523)
		(width 0.0889)
		(layer "F.Cu")
		(net "P3E_CPU0_PE1_PCH_C_TXN<14>")
	)
	(segment
		(start 355.886512 -126.013972)
		(end 355.109018 -125.495304)
		(width 0.1143)
		(layer "F.Cu")
		(net "P3E_CPU0_PE1_PCH_C_TXN<14>")
	)
	(segment
		(start 372.1354 -124.612146)
		(end 372.1354 -124.968)
		(width 0.0889)
		(layer "F.Cu")
		(net "P3E_CPU0_PE1_PCH_C_TXN<14>")
	)
	(segment
		(start 374.177814 -122.1613)
		(end 373.357394 -122.501152)
		(width 0.0889)
		(layer "F.Cu")
		(net "P3E_CPU0_PE1_PCH_C_TXN<14>")
	)
	(segment
		(start 371.63248 -125.47092)
		(end 371.444012 -125.659388)
		(width 0.0889)
		(layer "F.Cu")
		(net "P3E_CPU0_PE1_PCH_C_TXN<14>")
	)
	(segment
		(start 365.6965 -127.4191)
		(end 365.4298 -127.4191)
		(width 0.0889)
		(layer "F.Cu")
		(net "P3E_CPU0_PE1_PCH_C_TXN<14>")
	)
	(segment
		(start 372.477284 -123.506992)
		(end 372.351554 -123.506992)
		(width 0.0889)
		(layer "F.Cu")
		(net "P3E_CPU0_PE1_PCH_C_TXN<14>")
	)
	(segment
		(start 364.9853 -127.4191)
		(end 364.622842 -127.4191)
		(width 0.0889)
		(layer "F.Cu")
		(net "P3E_CPU0_PE1_PCH_C_TXN<14>")
	)
	(segment
		(start 365.3409 -127.508)
		(end 365.0742 -127.508)
		(width 0.0889)
		(layer "F.Cu")
		(net "P3E_CPU0_PE1_PCH_C_TXN<14>")
	)
	(segment
		(start 367.946432 -126.591568)
		(end 367.946432 -126.717298)
		(width 0.0889)
		(layer "F.Cu")
		(net "P3E_CPU0_PE1_PCH_C_TXN<14>")
	)
	(segment
		(start 372.1354 -123.723146)
		(end 372.1354 -124.167646)
		(width 0.0889)
		(layer "F.Cu")
		(net "P3E_CPU0_PE1_PCH_C_TXN<14>")
	)
	(segment
		(start 329.602592 -126.088648)
		(end 331.488796 -125.112526)
		(width 0.1143)
		(layer "F.Cu")
		(net "P3E_CPU0_PE1_PCH_C_TXN<14>")
	)
	(segment
		(start 325.4375 -123.3805)
		(end 325.50735 -123.31065)
		(width 0.1143)
		(layer "F.Cu")
		(net "P3E_CPU0_PE1_PCH_C_TXN<14>")
	)
	(segment
		(start 369.062 -126.3523)
		(end 368.9731 -126.4412)
		(width 0.0889)
		(layer "F.Cu")
		(net "P3E_CPU0_PE1_PCH_C_TXN<14>")
	)
	(segment
		(start 366.141 -127.4191)
		(end 366.0521 -127.508)
		(width 0.0889)
		(layer "F.Cu")
		(net "P3E_CPU0_PE1_PCH_C_TXN<14>")
	)
	(segment
		(start 371.946932 -125.156468)
		(end 371.946932 -125.282198)
		(width 0.0889)
		(layer "F.Cu")
		(net "P3E_CPU0_PE1_PCH_C_TXN<14>")
	)
	(segment
		(start 370.4844 -126.3523)
		(end 370.3955 -126.4412)
		(width 0.0889)
		(layer "F.Cu")
		(net "P3E_CPU0_PE1_PCH_C_TXN<14>")
	)
	(segment
		(start 328.739246 -126.256288)
		(end 329.602592 -126.088648)
		(width 0.1143)
		(layer "F.Cu")
		(net "P3E_CPU0_PE1_PCH_C_TXN<14>")
	)
	(segment
		(start 371.25529 -125.97384)
		(end 371.12956 -125.97384)
		(width 0.0889)
		(layer "F.Cu")
		(net "P3E_CPU0_PE1_PCH_C_TXN<14>")
	)
	(segment
		(start 365.7854 -127.508)
		(end 365.6965 -127.4191)
		(width 0.0889)
		(layer "F.Cu")
		(net "P3E_CPU0_PE1_PCH_C_TXN<14>")
	)
	(segment
		(start 373.168926 -122.81535)
		(end 372.980204 -123.004072)
		(width 0.0889)
		(layer "F.Cu")
		(net "P3E_CPU0_PE1_PCH_C_TXN<14>")
	)
	(segment
		(start 366.8522 -127.4191)
		(end 366.7633 -127.508)
		(width 0.0889)
		(layer "F.Cu")
		(net "P3E_CPU0_PE1_PCH_C_TXN<14>")
	)
	(segment
		(start 372.666006 -123.31827)
		(end 372.477284 -123.506992)
		(width 0.0889)
		(layer "F.Cu")
		(net "P3E_CPU0_PE1_PCH_C_TXN<14>")
	)
	(segment
		(start 325.702676 -123.31065)
		(end 326.230742 -123.730258)
		(width 0.1143)
		(layer "F.Cu")
		(net "P3E_CPU0_PE1_PCH_C_TXN<14>")
	)
	(segment
		(start 326.230742 -123.730258)
		(end 327.137522 -125.314456)
		(width 0.1143)
		(layer "F.Cu")
		(net "P3E_CPU0_PE1_PCH_C_TXN<14>")
	)
	(segment
		(start 358.121712 -127.504444)
		(end 357.156512 -126.860808)
		(width 0.1143)
		(layer "F.Cu")
		(net "P3E_CPU0_PE1_PCH_C_TXN<14>")
	)
	(segment
		(start 366.7633 -127.508)
		(end 366.4966 -127.508)
		(width 0.0889)
		(layer "F.Cu")
		(net "P3E_CPU0_PE1_PCH_C_TXN<14>")
	)
	(segment
		(start 372.1354 -124.968)
		(end 371.946932 -125.156468)
		(width 0.0889)
		(layer "F.Cu")
		(net "P3E_CPU0_PE1_PCH_C_TXN<14>")
	)
	(segment
		(start 327.137522 -125.314456)
		(end 328.739246 -126.256288)
		(width 0.1143)
		(layer "F.Cu")
		(net "P3E_CPU0_PE1_PCH_C_TXN<14>")
	)
	(segment
		(start 368.9731 -126.4412)
		(end 368.7064 -126.4412)
		(width 0.0889)
		(layer "F.Cu")
		(net "P3E_CPU0_PE1_PCH_C_TXN<14>")
	)
	(segment
		(start 372.2243 -124.523246)
		(end 372.1354 -124.612146)
		(width 0.0889)
		(layer "F.Cu")
		(net "P3E_CPU0_PE1_PCH_C_TXN<14>")
	)
	(segment
		(start 369.7732 -126.3523)
		(end 369.6843 -126.4412)
		(width 0.0889)
		(layer "F.Cu")
		(net "P3E_CPU0_PE1_PCH_C_TXN<14>")
	)
	(segment
		(start 372.1354 -124.167646)
		(end 372.2243 -124.256546)
		(width 0.0889)
		(layer "F.Cu")
		(net "P3E_CPU0_PE1_PCH_C_TXN<14>")
	)
	(segment
		(start 374.674892 -121.854976)
		(end 374.484138 -121.854976)
		(width 0.0889)
		(layer "F.Cu")
		(net "P3E_CPU0_PE1_PCH_C_TXN<14>")
	)
	(segment
		(start 373.168926 -122.68962)
		(end 373.168926 -122.81535)
		(width 0.0889)
		(layer "F.Cu")
		(net "P3E_CPU0_PE1_PCH_C_TXN<14>")
	)
	(segment
		(start 349.59925 -124.721366)
		(end 349.356426 -124.478542)
		(width 0.1143)
		(layer "F.Cu")
		(net "P3E_CPU0_PE1_PCH_C_TXN<14>")
	)
	(segment
		(start 372.666006 -123.19254)
		(end 372.666006 -123.31827)
		(width 0.0889)
		(layer "F.Cu")
		(net "P3E_CPU0_PE1_PCH_C_TXN<14>")
	)
	(segment
		(start 365.4298 -127.4191)
		(end 365.3409 -127.508)
		(width 0.0889)
		(layer "F.Cu")
		(net "P3E_CPU0_PE1_PCH_C_TXN<14>")
	)
	(segment
		(start 372.854474 -123.004072)
		(end 372.666006 -123.19254)
		(width 0.0889)
		(layer "F.Cu")
		(net "P3E_CPU0_PE1_PCH_C_TXN<14>")
	)
	(segment
		(start 364.597442 -127.4445)
		(end 364.575344 -127.4445)
		(width 0.0889)
		(layer "F.Cu")
		(net "P3E_CPU0_PE1_PCH_C_TXN<14>")
	)
	(segment
		(start 371.444012 -125.659388)
		(end 371.444012 -125.785118)
		(width 0.0889)
		(layer "F.Cu")
		(net "P3E_CPU0_PE1_PCH_C_TXN<14>")
	)
	(segment
		(start 325.4375 -123.825)
		(end 325.4375 -123.3805)
		(width 0.1143)
		(layer "F.Cu")
		(net "P3E_CPU0_PE1_PCH_C_TXN<14>")
	)
	(via
		(at 332.9178 -125.112526)
		(size 0.508)
		(drill 0.254)
		(layers "F.Cu" "B.Cu")
		(net "P3E_CPU0_PE1_PCH_C_TXN<14>")
	)
	(segment
		(start 372.088156 -123.210828)
		(end 371.962426 -123.210828)
		(width 0.0889)
		(layer "F.Cu")
		(net "P3E_CPU0_PE1_PCH_C_TXN<13>")
	)
	(segment
		(start 371.585236 -123.713748)
		(end 371.459506 -123.713748)
		(width 0.0889)
		(layer "F.Cu")
		(net "P3E_CPU0_PE1_PCH_C_TXN<13>")
	)
	(segment
		(start 348.510098 -123.09348)
		(end 345.191334 -123.09348)
		(width 0.1143)
		(layer "F.Cu")
		(net "P3E_CPU0_PE1_PCH_C_TXN<13>")
	)
	(segment
		(start 372.276878 -122.896376)
		(end 372.276878 -123.022106)
		(width 0.0889)
		(layer "F.Cu")
		(net "P3E_CPU0_PE1_PCH_C_TXN<13>")
	)
	(segment
		(start 368.925094 -124.8918)
		(end 368.836194 -124.8029)
		(width 0.0889)
		(layer "F.Cu")
		(net "P3E_CPU0_PE1_PCH_C_TXN<13>")
	)
	(segment
		(start 367.27638 -125.30582)
		(end 367.0808 -125.5014)
		(width 0.0889)
		(layer "F.Cu")
		(net "P3E_CPU0_PE1_PCH_C_TXN<13>")
	)
	(segment
		(start 328.007726 -124.107702)
		(end 326.461628 -122.561604)
		(width 0.1143)
		(layer "F.Cu")
		(net "P3E_CPU0_PE1_PCH_C_TXN<13>")
	)
	(segment
		(start 374.464072 -121.331228)
		(end 374.151652 -121.643648)
		(width 0.0889)
		(layer "F.Cu")
		(net "P3E_CPU0_PE1_PCH_C_TXN<13>")
	)
	(segment
		(start 366.62614 -126.3777)
		(end 366.35944 -126.3777)
		(width 0.0889)
		(layer "F.Cu")
		(net "P3E_CPU0_PE1_PCH_C_TXN<13>")
	)
	(segment
		(start 367.7793 -124.8029)
		(end 367.590832 -124.991368)
		(width 0.0889)
		(layer "F.Cu")
		(net "P3E_CPU0_PE1_PCH_C_TXN<13>")
	)
	(segment
		(start 374.927114 -121.289826)
		(end 374.827038 -121.331228)
		(width 0.0889)
		(layer "F.Cu")
		(net "P3E_CPU0_PE1_PCH_C_TXN<13>")
	)
	(segment
		(start 367.0808 -125.92304)
		(end 366.62614 -126.3777)
		(width 0.0889)
		(layer "F.Cu")
		(net "P3E_CPU0_PE1_PCH_C_TXN<13>")
	)
	(segment
		(start 371.071394 -123.91898)
		(end 370.6876 -124.302774)
		(width 0.0889)
		(layer "F.Cu")
		(net "P3E_CPU0_PE1_PCH_C_TXN<13>")
	)
	(segment
		(start 369.991894 -124.8029)
		(end 369.902994 -124.8918)
		(width 0.0889)
		(layer "F.Cu")
		(net "P3E_CPU0_PE1_PCH_C_TXN<13>")
	)
	(segment
		(start 360.120946 -126.895606)
		(end 358.937814 -126.659132)
		(width 0.1143)
		(layer "F.Cu")
		(net "P3E_CPU0_PE1_PCH_C_TXN<13>")
	)
	(segment
		(start 368.480594 -124.8918)
		(end 368.213894 -124.8918)
		(width 0.0889)
		(layer "F.Cu")
		(net "P3E_CPU0_PE1_PCH_C_TXN<13>")
	)
	(segment
		(start 366.27054 -126.4666)
		(end 366.00384 -126.4666)
		(width 0.0889)
		(layer "F.Cu")
		(net "P3E_CPU0_PE1_PCH_C_TXN<13>")
	)
	(segment
		(start 356.69474 -125.07087)
		(end 352.470466 -122.079766)
		(width 0.1143)
		(layer "F.Cu")
		(net "P3E_CPU0_PE1_PCH_C_TXN<13>")
	)
	(segment
		(start 352.470466 -122.079766)
		(end 349.523812 -122.079766)
		(width 0.1143)
		(layer "F.Cu")
		(net "P3E_CPU0_PE1_PCH_C_TXN<13>")
	)
	(segment
		(start 368.124994 -124.8029)
		(end 367.7793 -124.8029)
		(width 0.0889)
		(layer "F.Cu")
		(net "P3E_CPU0_PE1_PCH_C_TXN<13>")
	)
	(segment
		(start 363.9566 -126.4031)
		(end 363.934502 -126.4031)
		(width 0.0889)
		(layer "F.Cu")
		(net "P3E_CPU0_PE1_PCH_C_TXN<13>")
	)
	(segment
		(start 374.827038 -121.331228)
		(end 374.464072 -121.331228)
		(width 0.0889)
		(layer "F.Cu")
		(net "P3E_CPU0_PE1_PCH_C_TXN<13>")
	)
	(segment
		(start 374.151652 -121.643648)
		(end 373.905272 -121.745756)
		(width 0.0889)
		(layer "F.Cu")
		(net "P3E_CPU0_PE1_PCH_C_TXN<13>")
	)
	(segment
		(start 369.280694 -124.8029)
		(end 369.191794 -124.8918)
		(width 0.0889)
		(layer "F.Cu")
		(net "P3E_CPU0_PE1_PCH_C_TXN<13>")
	)
	(segment
		(start 364.84814 -126.4666)
		(end 364.58144 -126.4666)
		(width 0.0889)
		(layer "F.Cu")
		(net "P3E_CPU0_PE1_PCH_C_TXN<13>")
	)
	(segment
		(start 375.02465 -121.289826)
		(end 374.927114 -121.289826)
		(width 0.0889)
		(layer "F.Cu")
		(net "P3E_CPU0_PE1_PCH_C_TXN<13>")
	)
	(segment
		(start 371.773958 -123.399296)
		(end 371.773958 -123.525026)
		(width 0.0889)
		(layer "F.Cu")
		(net "P3E_CPU0_PE1_PCH_C_TXN<13>")
	)
	(segment
		(start 325.4375 -121.250456)
		(end 325.4375 -121.666)
		(width 0.1143)
		(layer "F.Cu")
		(net "P3E_CPU0_PE1_PCH_C_TXN<13>")
	)
	(segment
		(start 367.0808 -125.5014)
		(end 367.0808 -125.92304)
		(width 0.0889)
		(layer "F.Cu")
		(net "P3E_CPU0_PE1_PCH_C_TXN<13>")
	)
	(segment
		(start 366.00384 -126.4666)
		(end 365.91494 -126.3777)
		(width 0.0889)
		(layer "F.Cu")
		(net "P3E_CPU0_PE1_PCH_C_TXN<13>")
	)
	(segment
		(start 367.40211 -125.30582)
		(end 367.27638 -125.30582)
		(width 0.0889)
		(layer "F.Cu")
		(net "P3E_CPU0_PE1_PCH_C_TXN<13>")
	)
	(segment
		(start 366.35944 -126.3777)
		(end 366.27054 -126.4666)
		(width 0.0889)
		(layer "F.Cu")
		(net "P3E_CPU0_PE1_PCH_C_TXN<13>")
	)
	(segment
		(start 372.591076 -122.707908)
		(end 372.465346 -122.707908)
		(width 0.0889)
		(layer "F.Cu")
		(net "P3E_CPU0_PE1_PCH_C_TXN<13>")
	)
	(segment
		(start 373.610632 -121.963942)
		(end 373.494554 -121.915936)
		(width 0.0889)
		(layer "F.Cu")
		(net "P3E_CPU0_PE1_PCH_C_TXN<13>")
	)
	(segment
		(start 372.465346 -122.707908)
		(end 372.276878 -122.896376)
		(width 0.0889)
		(layer "F.Cu")
		(net "P3E_CPU0_PE1_PCH_C_TXN<13>")
	)
	(segment
		(start 370.258594 -124.8029)
		(end 369.991894 -124.8029)
		(width 0.0889)
		(layer "F.Cu")
		(net "P3E_CPU0_PE1_PCH_C_TXN<13>")
	)
	(segment
		(start 344.177112 -124.107702)
		(end 328.007726 -124.107702)
		(width 0.1143)
		(layer "F.Cu")
		(net "P3E_CPU0_PE1_PCH_C_TXN<13>")
	)
	(segment
		(start 369.547394 -124.8029)
		(end 369.280694 -124.8029)
		(width 0.0889)
		(layer "F.Cu")
		(net "P3E_CPU0_PE1_PCH_C_TXN<13>")
	)
	(segment
		(start 365.55934 -126.4666)
		(end 365.29264 -126.4666)
		(width 0.0889)
		(layer "F.Cu")
		(net "P3E_CPU0_PE1_PCH_C_TXN<13>")
	)
	(segment
		(start 368.213894 -124.8918)
		(end 368.124994 -124.8029)
		(width 0.0889)
		(layer "F.Cu")
		(net "P3E_CPU0_PE1_PCH_C_TXN<13>")
	)
	(segment
		(start 363.982 -126.3777)
		(end 363.9566 -126.4031)
		(width 0.0889)
		(layer "F.Cu")
		(net "P3E_CPU0_PE1_PCH_C_TXN<13>")
	)
	(segment
		(start 371.459506 -123.713748)
		(end 371.254274 -123.91898)
		(width 0.0889)
		(layer "F.Cu")
		(net "P3E_CPU0_PE1_PCH_C_TXN<13>")
	)
	(segment
		(start 373.905272 -121.745756)
		(end 373.857266 -121.861834)
		(width 0.0889)
		(layer "F.Cu")
		(net "P3E_CPU0_PE1_PCH_C_TXN<13>")
	)
	(segment
		(start 358.937814 -126.659132)
		(end 356.69474 -125.07087)
		(width 0.1143)
		(layer "F.Cu")
		(net "P3E_CPU0_PE1_PCH_C_TXN<13>")
	)
	(segment
		(start 364.93704 -126.3777)
		(end 364.84814 -126.4666)
		(width 0.0889)
		(layer "F.Cu")
		(net "P3E_CPU0_PE1_PCH_C_TXN<13>")
	)
	(segment
		(start 372.779798 -122.519186)
		(end 372.591076 -122.707908)
		(width 0.0889)
		(layer "F.Cu")
		(net "P3E_CPU0_PE1_PCH_C_TXN<13>")
	)
	(segment
		(start 369.191794 -124.8918)
		(end 368.925094 -124.8918)
		(width 0.0889)
		(layer "F.Cu")
		(net "P3E_CPU0_PE1_PCH_C_TXN<13>")
	)
	(segment
		(start 363.934502 -126.4031)
		(end 362.582206 -126.4031)
		(width 0.1143)
		(layer "F.Cu")
		(net "P3E_CPU0_PE1_PCH_C_TXN<13>")
	)
	(segment
		(start 365.20374 -126.3777)
		(end 364.93704 -126.3777)
		(width 0.0889)
		(layer "F.Cu")
		(net "P3E_CPU0_PE1_PCH_C_TXN<13>")
	)
	(segment
		(start 365.91494 -126.3777)
		(end 365.64824 -126.3777)
		(width 0.0889)
		(layer "F.Cu")
		(net "P3E_CPU0_PE1_PCH_C_TXN<13>")
	)
	(segment
		(start 362.582206 -126.4031)
		(end 360.120946 -126.895606)
		(width 0.1143)
		(layer "F.Cu")
		(net "P3E_CPU0_PE1_PCH_C_TXN<13>")
	)
	(segment
		(start 370.6876 -124.373894)
		(end 370.258594 -124.8029)
		(width 0.0889)
		(layer "F.Cu")
		(net "P3E_CPU0_PE1_PCH_C_TXN<13>")
	)
	(segment
		(start 364.49254 -126.3777)
		(end 363.982 -126.3777)
		(width 0.0889)
		(layer "F.Cu")
		(net "P3E_CPU0_PE1_PCH_C_TXN<13>")
	)
	(segment
		(start 365.64824 -126.3777)
		(end 365.55934 -126.4666)
		(width 0.0889)
		(layer "F.Cu")
		(net "P3E_CPU0_PE1_PCH_C_TXN<13>")
	)
	(segment
		(start 368.836194 -124.8029)
		(end 368.569494 -124.8029)
		(width 0.0889)
		(layer "F.Cu")
		(net "P3E_CPU0_PE1_PCH_C_TXN<13>")
	)
	(segment
		(start 371.962426 -123.210828)
		(end 371.773958 -123.399296)
		(width 0.0889)
		(layer "F.Cu")
		(net "P3E_CPU0_PE1_PCH_C_TXN<13>")
	)
	(segment
		(start 372.779798 -122.393456)
		(end 372.779798 -122.519186)
		(width 0.0889)
		(layer "F.Cu")
		(net "P3E_CPU0_PE1_PCH_C_TXN<13>")
	)
	(segment
		(start 373.494554 -121.915936)
		(end 373.089678 -122.083576)
		(width 0.0889)
		(layer "F.Cu")
		(net "P3E_CPU0_PE1_PCH_C_TXN<13>")
	)
	(segment
		(start 370.6876 -124.302774)
		(end 370.6876 -124.373894)
		(width 0.0889)
		(layer "F.Cu")
		(net "P3E_CPU0_PE1_PCH_C_TXN<13>")
	)
	(segment
		(start 373.857266 -121.861834)
		(end 373.610632 -121.963942)
		(width 0.0889)
		(layer "F.Cu")
		(net "P3E_CPU0_PE1_PCH_C_TXN<13>")
	)
	(segment
		(start 367.590832 -125.117098)
		(end 367.40211 -125.30582)
		(width 0.0889)
		(layer "F.Cu")
		(net "P3E_CPU0_PE1_PCH_C_TXN<13>")
	)
	(segment
		(start 369.636294 -124.8918)
		(end 369.547394 -124.8029)
		(width 0.0889)
		(layer "F.Cu")
		(net "P3E_CPU0_PE1_PCH_C_TXN<13>")
	)
	(segment
		(start 325.542656 -121.1453)
		(end 325.4375 -121.250456)
		(width 0.1143)
		(layer "F.Cu")
		(net "P3E_CPU0_PE1_PCH_C_TXN<13>")
	)
	(segment
		(start 326.461628 -122.561604)
		(end 326.461628 -121.553732)
		(width 0.1143)
		(layer "F.Cu")
		(net "P3E_CPU0_PE1_PCH_C_TXN<13>")
	)
	(segment
		(start 345.191334 -123.09348)
		(end 344.177112 -124.107702)
		(width 0.1143)
		(layer "F.Cu")
		(net "P3E_CPU0_PE1_PCH_C_TXN<13>")
	)
	(segment
		(start 326.053196 -121.1453)
		(end 325.542656 -121.1453)
		(width 0.1143)
		(layer "F.Cu")
		(net "P3E_CPU0_PE1_PCH_C_TXN<13>")
	)
	(segment
		(start 371.254274 -123.91898)
		(end 371.071394 -123.91898)
		(width 0.0889)
		(layer "F.Cu")
		(net "P3E_CPU0_PE1_PCH_C_TXN<13>")
	)
	(segment
		(start 371.773958 -123.525026)
		(end 371.585236 -123.713748)
		(width 0.0889)
		(layer "F.Cu")
		(net "P3E_CPU0_PE1_PCH_C_TXN<13>")
	)
	(segment
		(start 365.29264 -126.4666)
		(end 365.20374 -126.3777)
		(width 0.0889)
		(layer "F.Cu")
		(net "P3E_CPU0_PE1_PCH_C_TXN<13>")
	)
	(segment
		(start 372.276878 -123.022106)
		(end 372.088156 -123.210828)
		(width 0.0889)
		(layer "F.Cu")
		(net "P3E_CPU0_PE1_PCH_C_TXN<13>")
	)
	(segment
		(start 367.590832 -124.991368)
		(end 367.590832 -125.117098)
		(width 0.0889)
		(layer "F.Cu")
		(net "P3E_CPU0_PE1_PCH_C_TXN<13>")
	)
	(segment
		(start 326.461628 -121.553732)
		(end 326.053196 -121.1453)
		(width 0.1143)
		(layer "F.Cu")
		(net "P3E_CPU0_PE1_PCH_C_TXN<13>")
	)
	(segment
		(start 369.902994 -124.8918)
		(end 369.636294 -124.8918)
		(width 0.0889)
		(layer "F.Cu")
		(net "P3E_CPU0_PE1_PCH_C_TXN<13>")
	)
	(segment
		(start 349.523812 -122.079766)
		(end 348.510098 -123.09348)
		(width 0.1143)
		(layer "F.Cu")
		(net "P3E_CPU0_PE1_PCH_C_TXN<13>")
	)
	(segment
		(start 364.58144 -126.4666)
		(end 364.49254 -126.3777)
		(width 0.0889)
		(layer "F.Cu")
		(net "P3E_CPU0_PE1_PCH_C_TXN<13>")
	)
	(segment
		(start 375.089928 -121.355104)
		(end 375.02465 -121.289826)
		(width 0.0889)
		(layer "F.Cu")
		(net "P3E_CPU0_PE1_PCH_C_TXN<13>")
	)
	(segment
		(start 368.569494 -124.8029)
		(end 368.480594 -124.8918)
		(width 0.0889)
		(layer "F.Cu")
		(net "P3E_CPU0_PE1_PCH_C_TXN<13>")
	)
	(segment
		(start 373.089678 -122.083576)
		(end 372.779798 -122.393456)
		(width 0.0889)
		(layer "F.Cu")
		(net "P3E_CPU0_PE1_PCH_C_TXN<13>")
	)
	(via
		(at 356.69474 -125.07087)
		(size 0.508)
		(drill 0.254)
		(layers "F.Cu" "B.Cu")
		(net "P3E_CPU0_PE1_PCH_C_TXN<13>")
	)
	(segment
		(start 364.4011 -123.4821)
		(end 363.786166 -123.4821)
		(width 0.0889)
		(layer "F.Cu")
		(net "P3E_CPU0_PE1_PCH_C_TXN<12>")
	)
	(segment
		(start 322.05422 -120.53316)
		(end 322.05422 -120.094756)
		(width 0.1143)
		(layer "F.Cu")
		(net "P3E_CPU0_PE1_PCH_C_TXN<12>")
	)
	(segment
		(start 357.995982 -123.5964)
		(end 359.912158 -123.5964)
		(width 0.1143)
		(layer "F.Cu")
		(net "P3E_CPU0_PE1_PCH_C_TXN<12>")
	)
	(segment
		(start 322.171822 -119.977154)
		(end 322.466462 -119.977154)
		(width 0.1143)
		(layer "F.Cu")
		(net "P3E_CPU0_PE1_PCH_C_TXN<12>")
	)
	(segment
		(start 364.8456 -123.4821)
		(end 364.7567 -123.571)
		(width 0.0889)
		(layer "F.Cu")
		(net "P3E_CPU0_PE1_PCH_C_TXN<12>")
	)
	(segment
		(start 323.119496 -119.32412)
		(end 323.538342 -119.32412)
		(width 0.1143)
		(layer "F.Cu")
		(net "P3E_CPU0_PE1_PCH_C_TXN<12>")
	)
	(segment
		(start 374.394222 -120.854978)
		(end 373.938292 -121.310908)
		(width 0.0889)
		(layer "F.Cu")
		(net "P3E_CPU0_PE1_PCH_C_TXN<12>")
	)
	(segment
		(start 368.464592 -122.809)
		(end 368.375692 -122.7201)
		(width 0.0889)
		(layer "F.Cu")
		(net "P3E_CPU0_PE1_PCH_C_TXN<12>")
	)
	(segment
		(start 368.731292 -122.809)
		(end 368.464592 -122.809)
		(width 0.0889)
		(layer "F.Cu")
		(net "P3E_CPU0_PE1_PCH_C_TXN<12>")
	)
	(segment
		(start 367.753392 -122.809)
		(end 367.664492 -122.7201)
		(width 0.0889)
		(layer "F.Cu")
		(net "P3E_CPU0_PE1_PCH_C_TXN<12>")
	)
	(segment
		(start 370.242592 -122.7201)
		(end 370.153692 -122.809)
		(width 0.0889)
		(layer "F.Cu")
		(net "P3E_CPU0_PE1_PCH_C_TXN<12>")
	)
	(segment
		(start 365.4679 -123.571)
		(end 365.2012 -123.571)
		(width 0.0889)
		(layer "F.Cu")
		(net "P3E_CPU0_PE1_PCH_C_TXN<12>")
	)
	(segment
		(start 363.430566 -123.571)
		(end 363.341666 -123.4821)
		(width 0.0889)
		(layer "F.Cu")
		(net "P3E_CPU0_PE1_PCH_C_TXN<12>")
	)
	(segment
		(start 372.071392 -122.078242)
		(end 372.022878 -122.19432)
		(width 0.0889)
		(layer "F.Cu")
		(net "P3E_CPU0_PE1_PCH_C_TXN<12>")
	)
	(segment
		(start 373.938292 -121.310908)
		(end 372.729252 -121.807732)
		(width 0.0889)
		(layer "F.Cu")
		(net "P3E_CPU0_PE1_PCH_C_TXN<12>")
	)
	(segment
		(start 329.20051 -122.7074)
		(end 330.638404 -122.7074)
		(width 0.1143)
		(layer "F.Cu")
		(net "P3E_CPU0_PE1_PCH_C_TXN<12>")
	)
	(segment
		(start 322.466462 -119.977154)
		(end 323.119496 -119.32412)
		(width 0.1143)
		(layer "F.Cu")
		(net "P3E_CPU0_PE1_PCH_C_TXN<12>")
	)
	(segment
		(start 363.341666 -123.4821)
		(end 362.922566 -123.4821)
		(width 0.0889)
		(layer "F.Cu")
		(net "P3E_CPU0_PE1_PCH_C_TXN<12>")
	)
	(segment
		(start 362.922566 -123.4821)
		(end 362.897166 -123.5075)
		(width 0.0889)
		(layer "F.Cu")
		(net "P3E_CPU0_PE1_PCH_C_TXN<12>")
	)
	(segment
		(start 353.206304 -121.106946)
		(end 357.995982 -123.5964)
		(width 0.1143)
		(layer "F.Cu")
		(net "P3E_CPU0_PE1_PCH_C_TXN<12>")
	)
	(segment
		(start 366.5347 -123.4821)
		(end 366.268 -123.4821)
		(width 0.0889)
		(layer "F.Cu")
		(net "P3E_CPU0_PE1_PCH_C_TXN<12>")
	)
	(segment
		(start 371.413532 -122.348498)
		(end 371.365018 -122.464576)
		(width 0.0889)
		(layer "F.Cu")
		(net "P3E_CPU0_PE1_PCH_C_TXN<12>")
	)
	(segment
		(start 343.829132 -123.0122)
		(end 345.149932 -121.6914)
		(width 0.1143)
		(layer "F.Cu")
		(net "P3E_CPU0_PE1_PCH_C_TXN<12>")
	)
	(segment
		(start 372.680738 -121.92381)
		(end 372.434104 -122.025156)
		(width 0.0889)
		(layer "F.Cu")
		(net "P3E_CPU0_PE1_PCH_C_TXN<12>")
	)
	(segment
		(start 359.912158 -123.5964)
		(end 360.356658 -123.5075)
		(width 0.1143)
		(layer "F.Cu")
		(net "P3E_CPU0_PE1_PCH_C_TXN<12>")
	)
	(segment
		(start 365.2012 -123.571)
		(end 365.1123 -123.4821)
		(width 0.0889)
		(layer "F.Cu")
		(net "P3E_CPU0_PE1_PCH_C_TXN<12>")
	)
	(segment
		(start 365.1123 -123.4821)
		(end 364.8456 -123.4821)
		(width 0.0889)
		(layer "F.Cu")
		(net "P3E_CPU0_PE1_PCH_C_TXN<12>")
	)
	(segment
		(start 364.49 -123.571)
		(end 364.4011 -123.4821)
		(width 0.0889)
		(layer "F.Cu")
		(net "P3E_CPU0_PE1_PCH_C_TXN<12>")
	)
	(segment
		(start 349.120714 -121.106946)
		(end 353.206304 -121.106946)
		(width 0.1143)
		(layer "F.Cu")
		(net "P3E_CPU0_PE1_PCH_C_TXN<12>")
	)
	(segment
		(start 371.002306 -122.517408)
		(end 370.509292 -122.7201)
		(width 0.0889)
		(layer "F.Cu")
		(net "P3E_CPU0_PE1_PCH_C_TXN<12>")
	)
	(segment
		(start 362.875068 -123.5075)
		(end 362.456222 -123.5075)
		(width 0.1143)
		(layer "F.Cu")
		(net "P3E_CPU0_PE1_PCH_C_TXN<12>")
	)
	(segment
		(start 366.268 -123.4821)
		(end 366.1791 -123.571)
		(width 0.0889)
		(layer "F.Cu")
		(net "P3E_CPU0_PE1_PCH_C_TXN<12>")
	)
	(segment
		(start 369.798092 -122.7201)
		(end 369.531392 -122.7201)
		(width 0.0889)
		(layer "F.Cu")
		(net "P3E_CPU0_PE1_PCH_C_TXN<12>")
	)
	(segment
		(start 323.538342 -119.32412)
		(end 324.128384 -119.914162)
		(width 0.1143)
		(layer "F.Cu")
		(net "P3E_CPU0_PE1_PCH_C_TXN<12>")
	)
	(segment
		(start 363.786166 -123.4821)
		(end 363.697266 -123.571)
		(width 0.0889)
		(layer "F.Cu")
		(net "P3E_CPU0_PE1_PCH_C_TXN<12>")
	)
	(segment
		(start 369.531392 -122.7201)
		(end 369.442492 -122.809)
		(width 0.0889)
		(layer "F.Cu")
		(net "P3E_CPU0_PE1_PCH_C_TXN<12>")
	)
	(segment
		(start 345.149932 -121.6914)
		(end 348.53626 -121.6914)
		(width 0.1143)
		(layer "F.Cu")
		(net "P3E_CPU0_PE1_PCH_C_TXN<12>")
	)
	(segment
		(start 371.660166 -122.247152)
		(end 371.413532 -122.348498)
		(width 0.0889)
		(layer "F.Cu")
		(net "P3E_CPU0_PE1_PCH_C_TXN<12>")
	)
	(segment
		(start 370.153692 -122.809)
		(end 369.886992 -122.809)
		(width 0.0889)
		(layer "F.Cu")
		(net "P3E_CPU0_PE1_PCH_C_TXN<12>")
	)
	(segment
		(start 369.442492 -122.809)
		(end 369.175792 -122.809)
		(width 0.0889)
		(layer "F.Cu")
		(net "P3E_CPU0_PE1_PCH_C_TXN<12>")
	)
	(segment
		(start 363.697266 -123.571)
		(end 363.430566 -123.571)
		(width 0.0889)
		(layer "F.Cu")
		(net "P3E_CPU0_PE1_PCH_C_TXN<12>")
	)
	(segment
		(start 330.943204 -123.0122)
		(end 343.829132 -123.0122)
		(width 0.1143)
		(layer "F.Cu")
		(net "P3E_CPU0_PE1_PCH_C_TXN<12>")
	)
	(segment
		(start 348.53626 -121.6914)
		(end 349.120714 -121.106946)
		(width 0.1143)
		(layer "F.Cu")
		(net "P3E_CPU0_PE1_PCH_C_TXN<12>")
	)
	(segment
		(start 372.729252 -121.807732)
		(end 372.680738 -121.92381)
		(width 0.0889)
		(layer "F.Cu")
		(net "P3E_CPU0_PE1_PCH_C_TXN<12>")
	)
	(segment
		(start 365.8235 -123.4821)
		(end 365.5568 -123.4821)
		(width 0.0889)
		(layer "F.Cu")
		(net "P3E_CPU0_PE1_PCH_C_TXN<12>")
	)
	(segment
		(start 367.108232 -123.034298)
		(end 366.91951 -123.22302)
		(width 0.0889)
		(layer "F.Cu")
		(net "P3E_CPU0_PE1_PCH_C_TXN<12>")
	)
	(segment
		(start 372.318026 -121.976896)
		(end 372.071392 -122.078242)
		(width 0.0889)
		(layer "F.Cu")
		(net "P3E_CPU0_PE1_PCH_C_TXN<12>")
	)
	(segment
		(start 368.820192 -122.7201)
		(end 368.731292 -122.809)
		(width 0.0889)
		(layer "F.Cu")
		(net "P3E_CPU0_PE1_PCH_C_TXN<12>")
	)
	(segment
		(start 368.108992 -122.7201)
		(end 368.020092 -122.809)
		(width 0.0889)
		(layer "F.Cu")
		(net "P3E_CPU0_PE1_PCH_C_TXN<12>")
	)
	(segment
		(start 362.897166 -123.5075)
		(end 362.875068 -123.5075)
		(width 0.0889)
		(layer "F.Cu")
		(net "P3E_CPU0_PE1_PCH_C_TXN<12>")
	)
	(segment
		(start 324.128384 -119.914162)
		(end 326.407272 -119.914162)
		(width 0.1143)
		(layer "F.Cu")
		(net "P3E_CPU0_PE1_PCH_C_TXN<12>")
	)
	(segment
		(start 366.91951 -123.22302)
		(end 366.79378 -123.22302)
		(width 0.0889)
		(layer "F.Cu")
		(net "P3E_CPU0_PE1_PCH_C_TXN<12>")
	)
	(segment
		(start 369.086892 -122.7201)
		(end 368.820192 -122.7201)
		(width 0.0889)
		(layer "F.Cu")
		(net "P3E_CPU0_PE1_PCH_C_TXN<12>")
	)
	(segment
		(start 369.886992 -122.809)
		(end 369.798092 -122.7201)
		(width 0.0889)
		(layer "F.Cu")
		(net "P3E_CPU0_PE1_PCH_C_TXN<12>")
	)
	(segment
		(start 367.664492 -122.7201)
		(end 367.2967 -122.7201)
		(width 0.0889)
		(layer "F.Cu")
		(net "P3E_CPU0_PE1_PCH_C_TXN<12>")
	)
	(segment
		(start 366.79378 -123.22302)
		(end 366.5347 -123.4821)
		(width 0.0889)
		(layer "F.Cu")
		(net "P3E_CPU0_PE1_PCH_C_TXN<12>")
	)
	(segment
		(start 322.05422 -120.094756)
		(end 322.171822 -119.977154)
		(width 0.1143)
		(layer "F.Cu")
		(net "P3E_CPU0_PE1_PCH_C_TXN<12>")
	)
	(segment
		(start 360.356658 -123.5075)
		(end 362.456222 -123.5075)
		(width 0.1143)
		(layer "F.Cu")
		(net "P3E_CPU0_PE1_PCH_C_TXN<12>")
	)
	(segment
		(start 368.375692 -122.7201)
		(end 368.108992 -122.7201)
		(width 0.0889)
		(layer "F.Cu")
		(net "P3E_CPU0_PE1_PCH_C_TXN<12>")
	)
	(segment
		(start 371.776244 -122.295666)
		(end 371.660166 -122.247152)
		(width 0.0889)
		(layer "F.Cu")
		(net "P3E_CPU0_PE1_PCH_C_TXN<12>")
	)
	(segment
		(start 371.118384 -122.565922)
		(end 371.002306 -122.517408)
		(width 0.0889)
		(layer "F.Cu")
		(net "P3E_CPU0_PE1_PCH_C_TXN<12>")
	)
	(segment
		(start 372.434104 -122.025156)
		(end 372.318026 -121.976896)
		(width 0.0889)
		(layer "F.Cu")
		(net "P3E_CPU0_PE1_PCH_C_TXN<12>")
	)
	(segment
		(start 367.2967 -122.7201)
		(end 367.108232 -122.908568)
		(width 0.0889)
		(layer "F.Cu")
		(net "P3E_CPU0_PE1_PCH_C_TXN<12>")
	)
	(segment
		(start 374.674892 -120.854978)
		(end 374.394222 -120.854978)
		(width 0.0889)
		(layer "F.Cu")
		(net "P3E_CPU0_PE1_PCH_C_TXN<12>")
	)
	(segment
		(start 369.175792 -122.809)
		(end 369.086892 -122.7201)
		(width 0.0889)
		(layer "F.Cu")
		(net "P3E_CPU0_PE1_PCH_C_TXN<12>")
	)
	(segment
		(start 366.1791 -123.571)
		(end 365.9124 -123.571)
		(width 0.0889)
		(layer "F.Cu")
		(net "P3E_CPU0_PE1_PCH_C_TXN<12>")
	)
	(segment
		(start 365.5568 -123.4821)
		(end 365.4679 -123.571)
		(width 0.0889)
		(layer "F.Cu")
		(net "P3E_CPU0_PE1_PCH_C_TXN<12>")
	)
	(segment
		(start 367.108232 -122.908568)
		(end 367.108232 -123.034298)
		(width 0.0889)
		(layer "F.Cu")
		(net "P3E_CPU0_PE1_PCH_C_TXN<12>")
	)
	(segment
		(start 371.365018 -122.464576)
		(end 371.118384 -122.565922)
		(width 0.0889)
		(layer "F.Cu")
		(net "P3E_CPU0_PE1_PCH_C_TXN<12>")
	)
	(segment
		(start 372.022878 -122.19432)
		(end 371.776244 -122.295666)
		(width 0.0889)
		(layer "F.Cu")
		(net "P3E_CPU0_PE1_PCH_C_TXN<12>")
	)
	(segment
		(start 364.7567 -123.571)
		(end 364.49 -123.571)
		(width 0.0889)
		(layer "F.Cu")
		(net "P3E_CPU0_PE1_PCH_C_TXN<12>")
	)
	(segment
		(start 326.407272 -119.914162)
		(end 329.20051 -122.7074)
		(width 0.1143)
		(layer "F.Cu")
		(net "P3E_CPU0_PE1_PCH_C_TXN<12>")
	)
	(segment
		(start 370.509292 -122.7201)
		(end 370.242592 -122.7201)
		(width 0.0889)
		(layer "F.Cu")
		(net "P3E_CPU0_PE1_PCH_C_TXN<12>")
	)
	(segment
		(start 365.9124 -123.571)
		(end 365.8235 -123.4821)
		(width 0.0889)
		(layer "F.Cu")
		(net "P3E_CPU0_PE1_PCH_C_TXN<12>")
	)
	(segment
		(start 368.020092 -122.809)
		(end 367.753392 -122.809)
		(width 0.0889)
		(layer "F.Cu")
		(net "P3E_CPU0_PE1_PCH_C_TXN<12>")
	)
	(segment
		(start 330.638404 -122.7074)
		(end 330.943204 -123.0122)
		(width 0.1143)
		(layer "F.Cu")
		(net "P3E_CPU0_PE1_PCH_C_TXN<12>")
	)
	(via
		(at 362.456222 -123.5075)
		(size 0.508)
		(drill 0.254)
		(layers "F.Cu" "B.Cu")
		(net "P3E_CPU0_PE1_PCH_C_TXN<12>")
	)
	(segment
		(start 329.692 -121.4501)
		(end 331.2033 -121.4501)
		(width 0.1143)
		(layer "F.Cu")
		(net "P3E_CPU0_PE1_PCH_C_TXN<11>")
	)
	(segment
		(start 342.843866 -121.7676)
		(end 343.355168 -121.7676)
		(width 0.1143)
		(layer "F.Cu")
		(net "P3E_CPU0_PE1_PCH_C_TXN<11>")
	)
	(segment
		(start 331.2033 -121.4501)
		(end 331.5208 -121.7676)
		(width 0.1143)
		(layer "F.Cu")
		(net "P3E_CPU0_PE1_PCH_C_TXN<11>")
	)
	(segment
		(start 368.1984 -121.539)
		(end 371.747288 -121.539)
		(width 0.0889)
		(layer "F.Cu")
		(net "P3E_CPU0_PE1_PCH_C_TXN<11>")
	)
	(segment
		(start 323.9135 -117.5639)
		(end 324.065392 -117.715792)
		(width 0.1143)
		(layer "F.Cu")
		(net "P3E_CPU0_PE1_PCH_C_TXN<11>")
	)
	(segment
		(start 325.40321 -118.686834)
		(end 326.928734 -118.686834)
		(width 0.1143)
		(layer "F.Cu")
		(net "P3E_CPU0_PE1_PCH_C_TXN<11>")
	)
	(segment
		(start 371.747288 -121.539)
		(end 373.684546 -120.736614)
		(width 0.0889)
		(layer "F.Cu")
		(net "P3E_CPU0_PE1_PCH_C_TXN<11>")
	)
	(segment
		(start 366.376966 -120.324626)
		(end 368.1984 -121.539)
		(width 0.0889)
		(layer "F.Cu")
		(net "P3E_CPU0_PE1_PCH_C_TXN<11>")
	)
	(segment
		(start 362.07192 -119.464582)
		(end 366.376966 -120.324626)
		(width 0.0889)
		(layer "F.Cu")
		(net "P3E_CPU0_PE1_PCH_C_TXN<11>")
	)
	(segment
		(start 323.9135 -117.222016)
		(end 323.9135 -117.5639)
		(width 0.1143)
		(layer "F.Cu")
		(net "P3E_CPU0_PE1_PCH_C_TXN<11>")
	)
	(segment
		(start 348.551754 -119.86387)
		(end 353.416362 -119.86387)
		(width 0.1143)
		(layer "F.Cu")
		(net "P3E_CPU0_PE1_PCH_C_TXN<11>")
	)
	(segment
		(start 362.0516 -119.435372)
		(end 362.07192 -119.464582)
		(width 0.0889)
		(layer "F.Cu")
		(net "P3E_CPU0_PE1_PCH_C_TXN<11>")
	)
	(segment
		(start 374.280176 -120.140984)
		(end 374.778524 -120.140984)
		(width 0.0889)
		(layer "F.Cu")
		(net "P3E_CPU0_PE1_PCH_C_TXN<11>")
	)
	(segment
		(start 375.29643 -120.121426)
		(end 375.92 -120.355106)
		(width 0.0889)
		(layer "F.Cu")
		(net "P3E_CPU0_PE1_PCH_C_TXN<11>")
	)
	(segment
		(start 375.020332 -120.040908)
		(end 375.215912 -120.040908)
		(width 0.0889)
		(layer "F.Cu")
		(net "P3E_CPU0_PE1_PCH_C_TXN<11>")
	)
	(segment
		(start 356.350824 -120.733058)
		(end 361.535726 -119.331994)
		(width 0.1143)
		(layer "F.Cu")
		(net "P3E_CPU0_PE1_PCH_C_TXN<11>")
	)
	(segment
		(start 344.739468 -120.3833)
		(end 348.032324 -120.3833)
		(width 0.1143)
		(layer "F.Cu")
		(net "P3E_CPU0_PE1_PCH_C_TXN<11>")
	)
	(segment
		(start 324.432168 -117.715792)
		(end 325.40321 -118.686834)
		(width 0.1143)
		(layer "F.Cu")
		(net "P3E_CPU0_PE1_PCH_C_TXN<11>")
	)
	(segment
		(start 326.928734 -118.686834)
		(end 329.692 -121.4501)
		(width 0.1143)
		(layer "F.Cu")
		(net "P3E_CPU0_PE1_PCH_C_TXN<11>")
	)
	(segment
		(start 375.215912 -120.040908)
		(end 375.29643 -120.121426)
		(width 0.0889)
		(layer "F.Cu")
		(net "P3E_CPU0_PE1_PCH_C_TXN<11>")
	)
	(segment
		(start 361.535726 -119.331994)
		(end 362.03001 -119.431054)
		(width 0.1143)
		(layer "F.Cu")
		(net "P3E_CPU0_PE1_PCH_C_TXN<11>")
	)
	(segment
		(start 362.03001 -119.431054)
		(end 362.0516 -119.435372)
		(width 0.0889)
		(layer "F.Cu")
		(net "P3E_CPU0_PE1_PCH_C_TXN<11>")
	)
	(segment
		(start 331.5208 -121.7676)
		(end 342.843866 -121.7676)
		(width 0.1143)
		(layer "F.Cu")
		(net "P3E_CPU0_PE1_PCH_C_TXN<11>")
	)
	(segment
		(start 374.778524 -120.140984)
		(end 375.020332 -120.040908)
		(width 0.0889)
		(layer "F.Cu")
		(net "P3E_CPU0_PE1_PCH_C_TXN<11>")
	)
	(segment
		(start 353.416362 -119.86387)
		(end 356.350824 -120.733058)
		(width 0.1143)
		(layer "F.Cu")
		(net "P3E_CPU0_PE1_PCH_C_TXN<11>")
	)
	(segment
		(start 373.684546 -120.736614)
		(end 374.280176 -120.140984)
		(width 0.0889)
		(layer "F.Cu")
		(net "P3E_CPU0_PE1_PCH_C_TXN<11>")
	)
	(segment
		(start 348.032324 -120.3833)
		(end 348.551754 -119.86387)
		(width 0.1143)
		(layer "F.Cu")
		(net "P3E_CPU0_PE1_PCH_C_TXN<11>")
	)
	(segment
		(start 324.065392 -117.715792)
		(end 324.432168 -117.715792)
		(width 0.1143)
		(layer "F.Cu")
		(net "P3E_CPU0_PE1_PCH_C_TXN<11>")
	)
	(segment
		(start 343.355168 -121.7676)
		(end 344.739468 -120.3833)
		(width 0.1143)
		(layer "F.Cu")
		(net "P3E_CPU0_PE1_PCH_C_TXN<11>")
	)
	(via
		(at 342.843866 -121.7676)
		(size 0.508)
		(drill 0.254)
		(layers "F.Cu" "B.Cu")
		(net "P3E_CPU0_PE1_PCH_C_TXN<11>")
	)
	(segment
		(start 367.828068 -120.29186)
		(end 367.606072 -120.144032)
		(width 0.0889)
		(layer "F.Cu")
		(net "P3E_CPU0_PE1_PCH_C_TXN<10>")
	)
	(segment
		(start 365.433864 -119.143526)
		(end 365.32947 -119.213122)
		(width 0.0889)
		(layer "F.Cu")
		(net "P3E_CPU0_PE1_PCH_C_TXN<10>")
	)
	(segment
		(start 364.998 -119.05615)
		(end 363.859572 -118.828312)
		(width 0.0889)
		(layer "F.Cu")
		(net "P3E_CPU0_PE1_PCH_C_TXN<10>")
	)
	(segment
		(start 368.074702 -120.563132)
		(end 367.852706 -120.41505)
		(width 0.0889)
		(layer "F.Cu")
		(net "P3E_CPU0_PE1_PCH_C_TXN<10>")
	)
	(segment
		(start 369.922806 -120.711722)
		(end 369.823746 -120.810782)
		(width 0.0889)
		(layer "F.Cu")
		(net "P3E_CPU0_PE1_PCH_C_TXN<10>")
	)
	(segment
		(start 367.482882 -120.16867)
		(end 367.260886 -120.020588)
		(width 0.0889)
		(layer "F.Cu")
		(net "P3E_CPU0_PE1_PCH_C_TXN<10>")
	)
	(segment
		(start 366.644428 -119.502936)
		(end 366.392968 -119.335296)
		(width 0.0889)
		(layer "F.Cu")
		(net "P3E_CPU0_PE1_PCH_C_TXN<10>")
	)
	(segment
		(start 370.189506 -120.711722)
		(end 369.922806 -120.711722)
		(width 0.0889)
		(layer "F.Cu")
		(net "P3E_CPU0_PE1_PCH_C_TXN<10>")
	)
	(segment
		(start 368.726466 -120.711722)
		(end 368.457988 -120.711722)
		(width 0.0889)
		(layer "F.Cu")
		(net "P3E_CPU0_PE1_PCH_C_TXN<10>")
	)
	(segment
		(start 365.06785 -119.160798)
		(end 364.998 -119.05615)
		(width 0.0889)
		(layer "F.Cu")
		(net "P3E_CPU0_PE1_PCH_C_TXN<10>")
	)
	(segment
		(start 374.361964 -119.759222)
		(end 373.556276 -120.56491)
		(width 0.0889)
		(layer "F.Cu")
		(net "P3E_CPU0_PE1_PCH_C_TXN<10>")
	)
	(segment
		(start 372.018306 -120.810782)
		(end 371.751606 -120.810782)
		(width 0.0889)
		(layer "F.Cu")
		(net "P3E_CPU0_PE1_PCH_C_TXN<10>")
	)
	(segment
		(start 363.807756 -118.844314)
		(end 363.368336 -118.756176)
		(width 0.1143)
		(layer "F.Cu")
		(net "P3E_CPU0_PE1_PCH_C_TXN<10>")
	)
	(segment
		(start 366.131348 -119.282972)
		(end 366.026954 -119.352568)
		(width 0.0889)
		(layer "F.Cu")
		(net "P3E_CPU0_PE1_PCH_C_TXN<10>")
	)
	(segment
		(start 372.117366 -120.711722)
		(end 372.018306 -120.810782)
		(width 0.0889)
		(layer "F.Cu")
		(net "P3E_CPU0_PE1_PCH_C_TXN<10>")
	)
	(segment
		(start 368.457988 -120.711722)
		(end 368.197892 -120.538494)
		(width 0.0889)
		(layer "F.Cu")
		(net "P3E_CPU0_PE1_PCH_C_TXN<10>")
	)
	(segment
		(start 348.191328 -119.117872)
		(end 353.98583 -119.117872)
		(width 0.1143)
		(layer "F.Cu")
		(net "P3E_CPU0_PE1_PCH_C_TXN<10>")
	)
	(segment
		(start 365.32947 -119.213122)
		(end 365.06785 -119.160798)
		(width 0.0889)
		(layer "F.Cu")
		(net "P3E_CPU0_PE1_PCH_C_TXN<10>")
	)
	(segment
		(start 370.288566 -120.810782)
		(end 370.189506 -120.711722)
		(width 0.0889)
		(layer "F.Cu")
		(net "P3E_CPU0_PE1_PCH_C_TXN<10>")
	)
	(segment
		(start 371.286786 -120.810782)
		(end 371.020086 -120.810782)
		(width 0.0889)
		(layer "F.Cu")
		(net "P3E_CPU0_PE1_PCH_C_TXN<10>")
	)
	(segment
		(start 338.41436 -120.759474)
		(end 340.893654 -120.759474)
		(width 0.1143)
		(layer "F.Cu")
		(net "P3E_CPU0_PE1_PCH_C_TXN<10>")
	)
	(segment
		(start 367.260886 -120.020588)
		(end 367.236248 -119.897398)
		(width 0.0889)
		(layer "F.Cu")
		(net "P3E_CPU0_PE1_PCH_C_TXN<10>")
	)
	(segment
		(start 363.829346 -118.848632)
		(end 363.807756 -118.844314)
		(width 0.0889)
		(layer "F.Cu")
		(net "P3E_CPU0_PE1_PCH_C_TXN<10>")
	)
	(segment
		(start 367.236248 -119.897398)
		(end 367.014252 -119.74957)
		(width 0.0889)
		(layer "F.Cu")
		(net "P3E_CPU0_PE1_PCH_C_TXN<10>")
	)
	(segment
		(start 342.044528 -119.6086)
		(end 347.7006 -119.6086)
		(width 0.1143)
		(layer "F.Cu")
		(net "P3E_CPU0_PE1_PCH_C_TXN<10>")
	)
	(segment
		(start 370.555266 -120.810782)
		(end 370.288566 -120.810782)
		(width 0.0889)
		(layer "F.Cu")
		(net "P3E_CPU0_PE1_PCH_C_TXN<10>")
	)
	(segment
		(start 367.852706 -120.41505)
		(end 367.828068 -120.29186)
		(width 0.0889)
		(layer "F.Cu")
		(net "P3E_CPU0_PE1_PCH_C_TXN<10>")
	)
	(segment
		(start 361.35691 -118.47195)
		(end 361.610656 -118.403624)
		(width 0.1143)
		(layer "F.Cu")
		(net "P3E_CPU0_PE1_PCH_C_TXN<10>")
	)
	(segment
		(start 373.556276 -120.56491)
		(end 373.115586 -120.711722)
		(width 0.0889)
		(layer "F.Cu")
		(net "P3E_CPU0_PE1_PCH_C_TXN<10>")
	)
	(segment
		(start 372.483126 -120.810782)
		(end 372.384066 -120.711722)
		(width 0.0889)
		(layer "F.Cu")
		(net "P3E_CPU0_PE1_PCH_C_TXN<10>")
	)
	(segment
		(start 366.669066 -119.626126)
		(end 366.644428 -119.502936)
		(width 0.0889)
		(layer "F.Cu")
		(net "P3E_CPU0_PE1_PCH_C_TXN<10>")
	)
	(segment
		(start 365.765334 -119.300244)
		(end 365.695484 -119.19585)
		(width 0.0889)
		(layer "F.Cu")
		(net "P3E_CPU0_PE1_PCH_C_TXN<10>")
	)
	(segment
		(start 369.092226 -120.810782)
		(end 368.825526 -120.810782)
		(width 0.0889)
		(layer "F.Cu")
		(net "P3E_CPU0_PE1_PCH_C_TXN<10>")
	)
	(segment
		(start 374.674892 -119.85498)
		(end 374.579134 -119.759222)
		(width 0.0889)
		(layer "F.Cu")
		(net "P3E_CPU0_PE1_PCH_C_TXN<10>")
	)
	(segment
		(start 369.823746 -120.810782)
		(end 369.557046 -120.810782)
		(width 0.0889)
		(layer "F.Cu")
		(net "P3E_CPU0_PE1_PCH_C_TXN<10>")
	)
	(segment
		(start 359.27919 -119.03329)
		(end 361.35691 -118.47195)
		(width 0.1143)
		(layer "F.Cu")
		(net "P3E_CPU0_PE1_PCH_C_TXN<10>")
	)
	(segment
		(start 374.579134 -119.759222)
		(end 374.361964 -119.759222)
		(width 0.0889)
		(layer "F.Cu")
		(net "P3E_CPU0_PE1_PCH_C_TXN<10>")
	)
	(segment
		(start 365.695484 -119.19585)
		(end 365.433864 -119.143526)
		(width 0.0889)
		(layer "F.Cu")
		(net "P3E_CPU0_PE1_PCH_C_TXN<10>")
	)
	(segment
		(start 366.026954 -119.352568)
		(end 365.765334 -119.300244)
		(width 0.0889)
		(layer "F.Cu")
		(net "P3E_CPU0_PE1_PCH_C_TXN<10>")
	)
	(segment
		(start 369.191286 -120.711722)
		(end 369.092226 -120.810782)
		(width 0.0889)
		(layer "F.Cu")
		(net "P3E_CPU0_PE1_PCH_C_TXN<10>")
	)
	(segment
		(start 368.197892 -120.538494)
		(end 368.074702 -120.563132)
		(width 0.0889)
		(layer "F.Cu")
		(net "P3E_CPU0_PE1_PCH_C_TXN<10>")
	)
	(segment
		(start 367.014252 -119.74957)
		(end 366.891062 -119.774208)
		(width 0.0889)
		(layer "F.Cu")
		(net "P3E_CPU0_PE1_PCH_C_TXN<10>")
	)
	(segment
		(start 367.606072 -120.144032)
		(end 367.482882 -120.16867)
		(width 0.0889)
		(layer "F.Cu")
		(net "P3E_CPU0_PE1_PCH_C_TXN<10>")
	)
	(segment
		(start 370.654326 -120.711722)
		(end 370.555266 -120.810782)
		(width 0.0889)
		(layer "F.Cu")
		(net "P3E_CPU0_PE1_PCH_C_TXN<10>")
	)
	(segment
		(start 340.893654 -120.759474)
		(end 342.044528 -119.6086)
		(width 0.1143)
		(layer "F.Cu")
		(net "P3E_CPU0_PE1_PCH_C_TXN<10>")
	)
	(segment
		(start 361.610656 -118.403624)
		(end 363.368336 -118.756176)
		(width 0.1143)
		(layer "F.Cu")
		(net "P3E_CPU0_PE1_PCH_C_TXN<10>")
	)
	(segment
		(start 372.848886 -120.711722)
		(end 372.749826 -120.810782)
		(width 0.0889)
		(layer "F.Cu")
		(net "P3E_CPU0_PE1_PCH_C_TXN<10>")
	)
	(segment
		(start 347.7006 -119.6086)
		(end 348.191328 -119.117872)
		(width 0.1143)
		(layer "F.Cu")
		(net "P3E_CPU0_PE1_PCH_C_TXN<10>")
	)
	(segment
		(start 371.020086 -120.810782)
		(end 370.921026 -120.711722)
		(width 0.0889)
		(layer "F.Cu")
		(net "P3E_CPU0_PE1_PCH_C_TXN<10>")
	)
	(segment
		(start 353.98583 -119.117872)
		(end 356.362762 -119.821706)
		(width 0.1143)
		(layer "F.Cu")
		(net "P3E_CPU0_PE1_PCH_C_TXN<10>")
	)
	(segment
		(start 369.457986 -120.711722)
		(end 369.191286 -120.711722)
		(width 0.0889)
		(layer "F.Cu")
		(net "P3E_CPU0_PE1_PCH_C_TXN<10>")
	)
	(segment
		(start 369.557046 -120.810782)
		(end 369.457986 -120.711722)
		(width 0.0889)
		(layer "F.Cu")
		(net "P3E_CPU0_PE1_PCH_C_TXN<10>")
	)
	(segment
		(start 366.891062 -119.774208)
		(end 366.669066 -119.626126)
		(width 0.0889)
		(layer "F.Cu")
		(net "P3E_CPU0_PE1_PCH_C_TXN<10>")
	)
	(segment
		(start 372.749826 -120.810782)
		(end 372.483126 -120.810782)
		(width 0.0889)
		(layer "F.Cu")
		(net "P3E_CPU0_PE1_PCH_C_TXN<10>")
	)
	(segment
		(start 371.751606 -120.810782)
		(end 371.652546 -120.711722)
		(width 0.0889)
		(layer "F.Cu")
		(net "P3E_CPU0_PE1_PCH_C_TXN<10>")
	)
	(segment
		(start 338.293202 -120.880632)
		(end 338.41436 -120.759474)
		(width 0.1143)
		(layer "F.Cu")
		(net "P3E_CPU0_PE1_PCH_C_TXN<10>")
	)
	(segment
		(start 338.293202 -121.282968)
		(end 338.293202 -120.880632)
		(width 0.1143)
		(layer "F.Cu")
		(net "P3E_CPU0_PE1_PCH_C_TXN<10>")
	)
	(segment
		(start 371.385846 -120.711722)
		(end 371.286786 -120.810782)
		(width 0.0889)
		(layer "F.Cu")
		(net "P3E_CPU0_PE1_PCH_C_TXN<10>")
	)
	(segment
		(start 371.652546 -120.711722)
		(end 371.385846 -120.711722)
		(width 0.0889)
		(layer "F.Cu")
		(net "P3E_CPU0_PE1_PCH_C_TXN<10>")
	)
	(segment
		(start 366.392968 -119.335296)
		(end 366.131348 -119.282972)
		(width 0.0889)
		(layer "F.Cu")
		(net "P3E_CPU0_PE1_PCH_C_TXN<10>")
	)
	(segment
		(start 356.362762 -119.821706)
		(end 359.27919 -119.03329)
		(width 0.1143)
		(layer "F.Cu")
		(net "P3E_CPU0_PE1_PCH_C_TXN<10>")
	)
	(segment
		(start 373.115586 -120.711722)
		(end 372.848886 -120.711722)
		(width 0.0889)
		(layer "F.Cu")
		(net "P3E_CPU0_PE1_PCH_C_TXN<10>")
	)
	(segment
		(start 370.921026 -120.711722)
		(end 370.654326 -120.711722)
		(width 0.0889)
		(layer "F.Cu")
		(net "P3E_CPU0_PE1_PCH_C_TXN<10>")
	)
	(segment
		(start 368.825526 -120.810782)
		(end 368.726466 -120.711722)
		(width 0.0889)
		(layer "F.Cu")
		(net "P3E_CPU0_PE1_PCH_C_TXN<10>")
	)
	(segment
		(start 363.859572 -118.828312)
		(end 363.829346 -118.848632)
		(width 0.0889)
		(layer "F.Cu")
		(net "P3E_CPU0_PE1_PCH_C_TXN<10>")
	)
	(segment
		(start 372.384066 -120.711722)
		(end 372.117366 -120.711722)
		(width 0.0889)
		(layer "F.Cu")
		(net "P3E_CPU0_PE1_PCH_C_TXN<10>")
	)
	(via
		(at 363.368336 -118.756176)
		(size 0.508)
		(drill 0.254)
		(layers "F.Cu" "B.Cu")
		(net "P3E_CPU0_PE1_PCH_C_TXN<10>")
	)
	(segment
		(start 354.092002 -117.83949)
		(end 356.44455 -118.53545)
		(width 0.1143)
		(layer "F.Cu")
		(net "P3E_CPU0_PE1_PCH_C_TXP<9>")
	)
	(segment
		(start 375.016776 -119.04345)
		(end 374.777254 -119.142764)
		(width 0.0889)
		(layer "F.Cu")
		(net "P3E_CPU0_PE1_PCH_C_TXP<9>")
	)
	(segment
		(start 364.028228 -117.503956)
		(end 364.009432 -117.473984)
		(width 0.0889)
		(layer "F.Cu")
		(net "P3E_CPU0_PE1_PCH_C_TXP<9>")
	)
	(segment
		(start 374.156732 -119.142764)
		(end 373.280178 -120.019318)
		(width 0.0889)
		(layer "F.Cu")
		(net "P3E_CPU0_PE1_PCH_C_TXP<9>")
	)
	(segment
		(start 356.44455 -118.53545)
		(end 361.091226 -117.280182)
		(width 0.1143)
		(layer "F.Cu")
		(net "P3E_CPU0_PE1_PCH_C_TXP<9>")
	)
	(segment
		(start 375.288302 -119.112284)
		(end 375.219468 -119.04345)
		(width 0.0889)
		(layer "F.Cu")
		(net "P3E_CPU0_PE1_PCH_C_TXP<9>")
	)
	(segment
		(start 374.777254 -119.142764)
		(end 374.156732 -119.142764)
		(width 0.0889)
		(layer "F.Cu")
		(net "P3E_CPU0_PE1_PCH_C_TXP<9>")
	)
	(segment
		(start 363.987842 -117.469158)
		(end 362.016294 -117.030246)
		(width 0.1143)
		(layer "F.Cu")
		(net "P3E_CPU0_PE1_PCH_C_TXP<9>")
	)
	(segment
		(start 366.570514 -117.818916)
		(end 364.720632 -117.818916)
		(width 0.0889)
		(layer "F.Cu")
		(net "P3E_CPU0_PE1_PCH_C_TXP<9>")
	)
	(segment
		(start 362.016294 -117.030246)
		(end 361.091226 -117.280182)
		(width 0.1143)
		(layer "F.Cu")
		(net "P3E_CPU0_PE1_PCH_C_TXP<9>")
	)
	(segment
		(start 364.720632 -117.818916)
		(end 364.229142 -117.54866)
		(width 0.0889)
		(layer "F.Cu")
		(net "P3E_CPU0_PE1_PCH_C_TXP<9>")
	)
	(segment
		(start 375.92 -119.355108)
		(end 375.288302 -119.112284)
		(width 0.0889)
		(layer "F.Cu")
		(net "P3E_CPU0_PE1_PCH_C_TXP<9>")
	)
	(segment
		(start 364.229142 -117.54866)
		(end 364.02899 -117.50421)
		(width 0.0889)
		(layer "F.Cu")
		(net "P3E_CPU0_PE1_PCH_C_TXP<9>")
	)
	(segment
		(start 375.219468 -119.04345)
		(end 375.016776 -119.04345)
		(width 0.0889)
		(layer "F.Cu")
		(net "P3E_CPU0_PE1_PCH_C_TXP<9>")
	)
	(segment
		(start 346.717366 -118.383558)
		(end 347.261434 -117.83949)
		(width 0.1143)
		(layer "F.Cu")
		(net "P3E_CPU0_PE1_PCH_C_TXP<9>")
	)
	(segment
		(start 364.02899 -117.50421)
		(end 364.028736 -117.503956)
		(width 0.0889)
		(layer "F.Cu")
		(net "P3E_CPU0_PE1_PCH_C_TXP<9>")
	)
	(segment
		(start 340.323424 -118.383558)
		(end 346.717366 -118.383558)
		(width 0.1143)
		(layer "F.Cu")
		(net "P3E_CPU0_PE1_PCH_C_TXP<9>")
	)
	(segment
		(start 340.111588 -118.171722)
		(end 340.323424 -118.383558)
		(width 0.1143)
		(layer "F.Cu")
		(net "P3E_CPU0_PE1_PCH_C_TXP<9>")
	)
	(segment
		(start 368.770916 -120.019318)
		(end 366.570514 -117.818916)
		(width 0.0889)
		(layer "F.Cu")
		(net "P3E_CPU0_PE1_PCH_C_TXP<9>")
	)
	(segment
		(start 364.009432 -117.473984)
		(end 363.987842 -117.469158)
		(width 0.0889)
		(layer "F.Cu")
		(net "P3E_CPU0_PE1_PCH_C_TXP<9>")
	)
	(segment
		(start 373.280178 -120.019318)
		(end 368.770916 -120.019318)
		(width 0.0889)
		(layer "F.Cu")
		(net "P3E_CPU0_PE1_PCH_C_TXP<9>")
	)
	(segment
		(start 340.111588 -117.941598)
		(end 340.111588 -118.171722)
		(width 0.1143)
		(layer "F.Cu")
		(net "P3E_CPU0_PE1_PCH_C_TXP<9>")
	)
	(segment
		(start 364.028736 -117.503956)
		(end 364.028228 -117.503956)
		(width 0.0889)
		(layer "F.Cu")
		(net "P3E_CPU0_PE1_PCH_C_TXP<9>")
	)
	(segment
		(start 347.261434 -117.83949)
		(end 354.092002 -117.83949)
		(width 0.1143)
		(layer "F.Cu")
		(net "P3E_CPU0_PE1_PCH_C_TXP<9>")
	)
	(via
		(at 361.091226 -117.280182)
		(size 0.508)
		(drill 0.254)
		(layers "F.Cu" "B.Cu")
		(net "P3E_CPU0_PE1_PCH_C_TXP<9>")
	)
	(segment
		(start 356.34549 -117.425724)
		(end 354.386134 -116.846858)
		(width 0.1143)
		(layer "F.Cu")
		(net "P3E_CPU0_PE1_PCH_C_TXP<8>")
	)
	(segment
		(start 365.858298 -116.57457)
		(end 365.832898 -116.54917)
		(width 0.0889)
		(layer "F.Cu")
		(net "P3E_CPU0_PE1_PCH_C_TXP<8>")
	)
	(segment
		(start 375.504964 -118.854982)
		(end 374.88114 -118.620286)
		(width 0.0889)
		(layer "F.Cu")
		(net "P3E_CPU0_PE1_PCH_C_TXP<8>")
	)
	(segment
		(start 374.830086 -118.569232)
		(end 374.063514 -118.569232)
		(width 0.0889)
		(layer "F.Cu")
		(net "P3E_CPU0_PE1_PCH_C_TXP<8>")
	)
	(segment
		(start 361.749594 -115.965224)
		(end 359.047542 -116.69522)
		(width 0.1143)
		(layer "F.Cu")
		(net "P3E_CPU0_PE1_PCH_C_TXP<8>")
	)
	(segment
		(start 333.87792 -117.7544)
		(end 333.777844 -117.654324)
		(width 0.1143)
		(layer "F.Cu")
		(net "P3E_CPU0_PE1_PCH_C_TXP<8>")
	)
	(segment
		(start 359.047288 -116.695474)
		(end 356.34549 -117.425724)
		(width 0.1143)
		(layer "F.Cu")
		(net "P3E_CPU0_PE1_PCH_C_TXP<8>")
	)
	(segment
		(start 335.498186 -116.958872)
		(end 334.702658 -117.7544)
		(width 0.1143)
		(layer "F.Cu")
		(net "P3E_CPU0_PE1_PCH_C_TXP<8>")
	)
	(segment
		(start 354.386134 -116.846858)
		(end 345.631516 -116.846858)
		(width 0.1143)
		(layer "F.Cu")
		(net "P3E_CPU0_PE1_PCH_C_TXP<8>")
	)
	(segment
		(start 373.100346 -119.5324)
		(end 369.3668 -119.5324)
		(width 0.0889)
		(layer "F.Cu")
		(net "P3E_CPU0_PE1_PCH_C_TXP<8>")
	)
	(segment
		(start 363.36478 -116.322094)
		(end 361.749594 -115.965224)
		(width 0.1143)
		(layer "F.Cu")
		(net "P3E_CPU0_PE1_PCH_C_TXP<8>")
	)
	(segment
		(start 345.631516 -116.846858)
		(end 345.519502 -116.958872)
		(width 0.1143)
		(layer "F.Cu")
		(net "P3E_CPU0_PE1_PCH_C_TXP<8>")
	)
	(segment
		(start 365.8108 -116.54917)
		(end 364.391448 -116.54917)
		(width 0.1143)
		(layer "F.Cu")
		(net "P3E_CPU0_PE1_PCH_C_TXP<8>")
	)
	(segment
		(start 366.40897 -116.57457)
		(end 365.858298 -116.57457)
		(width 0.0889)
		(layer "F.Cu")
		(net "P3E_CPU0_PE1_PCH_C_TXP<8>")
	)
	(segment
		(start 345.519502 -116.958872)
		(end 335.498186 -116.958872)
		(width 0.1143)
		(layer "F.Cu")
		(net "P3E_CPU0_PE1_PCH_C_TXP<8>")
	)
	(segment
		(start 334.702658 -117.7544)
		(end 333.87792 -117.7544)
		(width 0.1143)
		(layer "F.Cu")
		(net "P3E_CPU0_PE1_PCH_C_TXP<8>")
	)
	(segment
		(start 369.3668 -119.5324)
		(end 366.40897 -116.57457)
		(width 0.0889)
		(layer "F.Cu")
		(net "P3E_CPU0_PE1_PCH_C_TXP<8>")
	)
	(segment
		(start 333.777844 -117.654324)
		(end 333.777844 -117.35562)
		(width 0.1143)
		(layer "F.Cu")
		(net "P3E_CPU0_PE1_PCH_C_TXP<8>")
	)
	(segment
		(start 374.88114 -118.620286)
		(end 374.830086 -118.569232)
		(width 0.0889)
		(layer "F.Cu")
		(net "P3E_CPU0_PE1_PCH_C_TXP<8>")
	)
	(segment
		(start 359.047542 -116.69522)
		(end 359.047288 -116.695474)
		(width 0.1143)
		(layer "F.Cu")
		(net "P3E_CPU0_PE1_PCH_C_TXP<8>")
	)
	(segment
		(start 365.832898 -116.54917)
		(end 365.8108 -116.54917)
		(width 0.0889)
		(layer "F.Cu")
		(net "P3E_CPU0_PE1_PCH_C_TXP<8>")
	)
	(segment
		(start 374.063514 -118.569232)
		(end 373.100346 -119.5324)
		(width 0.0889)
		(layer "F.Cu")
		(net "P3E_CPU0_PE1_PCH_C_TXP<8>")
	)
	(segment
		(start 364.391448 -116.54917)
		(end 363.36478 -116.322094)
		(width 0.1143)
		(layer "F.Cu")
		(net "P3E_CPU0_PE1_PCH_C_TXP<8>")
	)
	(via
		(at 363.36478 -116.322094)
		(size 0.508)
		(drill 0.254)
		(layers "F.Cu" "B.Cu")
		(net "P3E_CPU0_PE1_PCH_C_TXP<8>")
	)
	(segment
		(start 321.578224 -123.8377)
		(end 321.790822 -123.8377)
		(width 0.1143)
		(layer "F.Cu")
		(net "P3E_CPU0_PE1_PCH_C_TXP<15>")
	)
	(segment
		(start 331.648816 -125.857)
		(end 345.425522 -125.857)
		(width 0.1143)
		(layer "F.Cu")
		(net "P3E_CPU0_PE1_PCH_C_TXP<15>")
	)
	(segment
		(start 373.3419 -124.5997)
		(end 373.3419 -123.111768)
		(width 0.0889)
		(layer "F.Cu")
		(net "P3E_CPU0_PE1_PCH_C_TXP<15>")
	)
	(segment
		(start 375.034048 -122.034046)
		(end 375.034302 -122.0343)
		(width 0.0889)
		(layer "F.Cu")
		(net "P3E_CPU0_PE1_PCH_C_TXP<15>")
	)
	(segment
		(start 348.90837 -125.64491)
		(end 350.51746 -127.254)
		(width 0.1143)
		(layer "F.Cu")
		(net "P3E_CPU0_PE1_PCH_C_TXP<15>")
	)
	(segment
		(start 322.922138 -124.458984)
		(end 323.379084 -125.127004)
		(width 0.1143)
		(layer "F.Cu")
		(net "P3E_CPU0_PE1_PCH_C_TXP<15>")
	)
	(segment
		(start 373.3419 -123.111768)
		(end 373.432324 -122.893582)
		(width 0.0889)
		(layer "F.Cu")
		(net "P3E_CPU0_PE1_PCH_C_TXP<15>")
	)
	(segment
		(start 345.425522 -125.857)
		(end 345.637612 -125.64491)
		(width 0.1143)
		(layer "F.Cu")
		(net "P3E_CPU0_PE1_PCH_C_TXP<15>")
	)
	(segment
		(start 357.7463 -128.19126)
		(end 360.4133 -128.72466)
		(width 0.1143)
		(layer "F.Cu")
		(net "P3E_CPU0_PE1_PCH_C_TXP<15>")
	)
	(segment
		(start 321.5005 -123.317)
		(end 321.5005 -123.759976)
		(width 0.1143)
		(layer "F.Cu")
		(net "P3E_CPU0_PE1_PCH_C_TXP<15>")
	)
	(segment
		(start 375.308368 -122.108468)
		(end 375.3358 -122.1359)
		(width 0.0889)
		(layer "F.Cu")
		(net "P3E_CPU0_PE1_PCH_C_TXP<15>")
	)
	(segment
		(start 357.745538 -128.191006)
		(end 357.7463 -128.19126)
		(width 0.1143)
		(layer "F.Cu")
		(net "P3E_CPU0_PE1_PCH_C_TXP<15>")
	)
	(segment
		(start 375.129044 -122.0343)
		(end 375.308368 -122.108468)
		(width 0.0889)
		(layer "F.Cu")
		(net "P3E_CPU0_PE1_PCH_C_TXP<15>")
	)
	(segment
		(start 324.37197 -125.568202)
		(end 325.377556 -125.344174)
		(width 0.1143)
		(layer "F.Cu")
		(net "P3E_CPU0_PE1_PCH_C_TXP<15>")
	)
	(segment
		(start 330.064364 -126.840234)
		(end 331.648816 -125.857)
		(width 0.1143)
		(layer "F.Cu")
		(net "P3E_CPU0_PE1_PCH_C_TXP<15>")
	)
	(segment
		(start 367.471706 -128.2954)
		(end 369.008406 -126.7587)
		(width 0.0889)
		(layer "F.Cu")
		(net "P3E_CPU0_PE1_PCH_C_TXP<15>")
	)
	(segment
		(start 356.310946 -127.254)
		(end 357.705152 -128.183132)
		(width 0.1143)
		(layer "F.Cu")
		(net "P3E_CPU0_PE1_PCH_C_TXP<15>")
	)
	(segment
		(start 328.764138 -127.099568)
		(end 330.064364 -126.840234)
		(width 0.1143)
		(layer "F.Cu")
		(net "P3E_CPU0_PE1_PCH_C_TXP<15>")
	)
	(segment
		(start 367.03 -128.2954)
		(end 367.471706 -128.2954)
		(width 0.0889)
		(layer "F.Cu")
		(net "P3E_CPU0_PE1_PCH_C_TXP<15>")
	)
	(segment
		(start 374.616726 -122.20702)
		(end 375.034048 -122.034046)
		(width 0.0889)
		(layer "F.Cu")
		(net "P3E_CPU0_PE1_PCH_C_TXP<15>")
	)
	(segment
		(start 360.4133 -128.72466)
		(end 362.6866 -128.27)
		(width 0.1143)
		(layer "F.Cu")
		(net "P3E_CPU0_PE1_PCH_C_TXP<15>")
	)
	(segment
		(start 348.455996 -125.64491)
		(end 348.90837 -125.64491)
		(width 0.1143)
		(layer "F.Cu")
		(net "P3E_CPU0_PE1_PCH_C_TXP<15>")
	)
	(segment
		(start 357.705152 -128.183132)
		(end 357.745538 -128.191006)
		(width 0.1143)
		(layer "F.Cu")
		(net "P3E_CPU0_PE1_PCH_C_TXP<15>")
	)
	(segment
		(start 371.1829 -126.7587)
		(end 373.3419 -124.5997)
		(width 0.0889)
		(layer "F.Cu")
		(net "P3E_CPU0_PE1_PCH_C_TXP<15>")
	)
	(segment
		(start 367.0046 -128.27)
		(end 367.03 -128.2954)
		(width 0.0889)
		(layer "F.Cu")
		(net "P3E_CPU0_PE1_PCH_C_TXP<15>")
	)
	(segment
		(start 374.527064 -122.296682)
		(end 374.616726 -122.20702)
		(width 0.0889)
		(layer "F.Cu")
		(net "P3E_CPU0_PE1_PCH_C_TXP<15>")
	)
	(segment
		(start 369.008406 -126.7587)
		(end 371.1829 -126.7587)
		(width 0.0889)
		(layer "F.Cu")
		(net "P3E_CPU0_PE1_PCH_C_TXP<15>")
	)
	(segment
		(start 366.982502 -128.27)
		(end 367.0046 -128.27)
		(width 0.0889)
		(layer "F.Cu")
		(net "P3E_CPU0_PE1_PCH_C_TXP<15>")
	)
	(segment
		(start 373.432324 -122.893582)
		(end 373.67718 -122.648726)
		(width 0.0889)
		(layer "F.Cu")
		(net "P3E_CPU0_PE1_PCH_C_TXP<15>")
	)
	(segment
		(start 325.377556 -125.344174)
		(end 328.764138 -127.099568)
		(width 0.1143)
		(layer "F.Cu")
		(net "P3E_CPU0_PE1_PCH_C_TXP<15>")
	)
	(segment
		(start 321.5005 -123.759976)
		(end 321.578224 -123.8377)
		(width 0.1143)
		(layer "F.Cu")
		(net "P3E_CPU0_PE1_PCH_C_TXP<15>")
	)
	(segment
		(start 375.3358 -122.1359)
		(end 375.92 -122.355102)
		(width 0.0889)
		(layer "F.Cu")
		(net "P3E_CPU0_PE1_PCH_C_TXP<15>")
	)
	(segment
		(start 362.6866 -128.27)
		(end 366.982502 -128.27)
		(width 0.1143)
		(layer "F.Cu")
		(net "P3E_CPU0_PE1_PCH_C_TXP<15>")
	)
	(segment
		(start 321.790822 -123.8377)
		(end 322.922138 -124.458984)
		(width 0.1143)
		(layer "F.Cu")
		(net "P3E_CPU0_PE1_PCH_C_TXP<15>")
	)
	(segment
		(start 323.379084 -125.127004)
		(end 324.37197 -125.568202)
		(width 0.1143)
		(layer "F.Cu")
		(net "P3E_CPU0_PE1_PCH_C_TXP<15>")
	)
	(segment
		(start 345.637612 -125.64491)
		(end 348.455996 -125.64491)
		(width 0.1143)
		(layer "F.Cu")
		(net "P3E_CPU0_PE1_PCH_C_TXP<15>")
	)
	(segment
		(start 350.51746 -127.254)
		(end 356.310946 -127.254)
		(width 0.1143)
		(layer "F.Cu")
		(net "P3E_CPU0_PE1_PCH_C_TXP<15>")
	)
	(segment
		(start 373.67718 -122.648726)
		(end 374.527064 -122.296682)
		(width 0.0889)
		(layer "F.Cu")
		(net "P3E_CPU0_PE1_PCH_C_TXP<15>")
	)
	(segment
		(start 375.034302 -122.0343)
		(end 375.129044 -122.0343)
		(width 0.0889)
		(layer "F.Cu")
		(net "P3E_CPU0_PE1_PCH_C_TXP<15>")
	)
	(via
		(at 348.455996 -125.64491)
		(size 0.508)
		(drill 0.254)
		(layers "F.Cu" "B.Cu")
		(net "P3E_CPU0_PE1_PCH_C_TXP<15>")
	)
	(segment
		(start 364.597442 -127.2032)
		(end 364.575344 -127.2032)
		(width 0.0889)
		(layer "F.Cu")
		(net "P3E_CPU0_PE1_PCH_C_TXP<14>")
	)
	(segment
		(start 358.215946 -127.277114)
		(end 356.02037 -125.812804)
		(width 0.1143)
		(layer "F.Cu")
		(net "P3E_CPU0_PE1_PCH_C_TXP<14>")
	)
	(segment
		(start 364.575344 -127.2032)
		(end 362.954824 -127.2032)
		(width 0.1143)
		(layer "F.Cu")
		(net "P3E_CPU0_PE1_PCH_C_TXP<14>")
	)
	(segment
		(start 325.787004 -123.06935)
		(end 325.552054 -123.06935)
		(width 0.1143)
		(layer "F.Cu")
		(net "P3E_CPU0_PE1_PCH_C_TXP<14>")
	)
	(segment
		(start 355.242876 -125.29439)
		(end 354.021644 -124.480066)
		(width 0.1143)
		(layer "F.Cu")
		(net "P3E_CPU0_PE1_PCH_C_TXP<14>")
	)
	(segment
		(start 370.672106 -126.1618)
		(end 368.106706 -126.1618)
		(width 0.0889)
		(layer "F.Cu")
		(net "P3E_CPU0_PE1_PCH_C_TXP<14>")
	)
	(segment
		(start 374.069864 -121.999756)
		(end 373.249444 -122.339608)
		(width 0.0889)
		(layer "F.Cu")
		(net "P3E_CPU0_PE1_PCH_C_TXP<14>")
	)
	(segment
		(start 368.106706 -126.1618)
		(end 367.039906 -127.2286)
		(width 0.0889)
		(layer "F.Cu")
		(net "P3E_CPU0_PE1_PCH_C_TXP<14>")
	)
	(segment
		(start 371.9449 -123.644152)
		(end 371.9449 -124.889006)
		(width 0.0889)
		(layer "F.Cu")
		(net "P3E_CPU0_PE1_PCH_C_TXP<14>")
	)
	(segment
		(start 326.417432 -123.569984)
		(end 325.787004 -123.06935)
		(width 0.1143)
		(layer "F.Cu")
		(net "P3E_CPU0_PE1_PCH_C_TXP<14>")
	)
	(segment
		(start 327.315322 -125.138688)
		(end 326.417432 -123.569984)
		(width 0.1143)
		(layer "F.Cu")
		(net "P3E_CPU0_PE1_PCH_C_TXP<14>")
	)
	(segment
		(start 331.429868 -124.871226)
		(end 329.522582 -125.85827)
		(width 0.1143)
		(layer "F.Cu")
		(net "P3E_CPU0_PE1_PCH_C_TXP<14>")
	)
	(segment
		(start 360.4006 -127.713994)
		(end 358.215946 -127.277114)
		(width 0.1143)
		(layer "F.Cu")
		(net "P3E_CPU0_PE1_PCH_C_TXP<14>")
	)
	(segment
		(start 325.4375 -122.954796)
		(end 325.4375 -122.555)
		(width 0.1143)
		(layer "F.Cu")
		(net "P3E_CPU0_PE1_PCH_C_TXP<14>")
	)
	(segment
		(start 375.504964 -121.854976)
		(end 374.914668 -121.64568)
		(width 0.0889)
		(layer "F.Cu")
		(net "P3E_CPU0_PE1_PCH_C_TXP<14>")
	)
	(segment
		(start 345.584526 -124.237242)
		(end 344.950542 -124.871226)
		(width 0.1143)
		(layer "F.Cu")
		(net "P3E_CPU0_PE1_PCH_C_TXP<14>")
	)
	(segment
		(start 343.3572 -124.871226)
		(end 331.429868 -124.871226)
		(width 0.1143)
		(layer "F.Cu")
		(net "P3E_CPU0_PE1_PCH_C_TXP<14>")
	)
	(segment
		(start 374.83796 -121.568972)
		(end 374.500648 -121.568972)
		(width 0.0889)
		(layer "F.Cu")
		(net "P3E_CPU0_PE1_PCH_C_TXP<14>")
	)
	(segment
		(start 362.954824 -127.2032)
		(end 360.4006 -127.713994)
		(width 0.1143)
		(layer "F.Cu")
		(net "P3E_CPU0_PE1_PCH_C_TXP<14>")
	)
	(segment
		(start 325.552054 -123.06935)
		(end 325.4375 -122.954796)
		(width 0.1143)
		(layer "F.Cu")
		(net "P3E_CPU0_PE1_PCH_C_TXP<14>")
	)
	(segment
		(start 374.500648 -121.568972)
		(end 374.069864 -121.999756)
		(width 0.0889)
		(layer "F.Cu")
		(net "P3E_CPU0_PE1_PCH_C_TXP<14>")
	)
	(segment
		(start 356.02037 -125.812804)
		(end 355.242876 -125.29439)
		(width 0.1143)
		(layer "F.Cu")
		(net "P3E_CPU0_PE1_PCH_C_TXP<14>")
	)
	(segment
		(start 328.782934 -126.00178)
		(end 327.315322 -125.138688)
		(width 0.1143)
		(layer "F.Cu")
		(net "P3E_CPU0_PE1_PCH_C_TXP<14>")
	)
	(segment
		(start 349.699326 -124.480066)
		(end 349.456502 -124.237242)
		(width 0.1143)
		(layer "F.Cu")
		(net "P3E_CPU0_PE1_PCH_C_TXP<14>")
	)
	(segment
		(start 329.522582 -125.85827)
		(end 328.782934 -126.00178)
		(width 0.1143)
		(layer "F.Cu")
		(net "P3E_CPU0_PE1_PCH_C_TXP<14>")
	)
	(segment
		(start 373.249444 -122.339608)
		(end 371.9449 -123.644152)
		(width 0.0889)
		(layer "F.Cu")
		(net "P3E_CPU0_PE1_PCH_C_TXP<14>")
	)
	(segment
		(start 374.914668 -121.64568)
		(end 374.83796 -121.568972)
		(width 0.0889)
		(layer "F.Cu")
		(net "P3E_CPU0_PE1_PCH_C_TXP<14>")
	)
	(segment
		(start 349.456502 -124.237242)
		(end 345.584526 -124.237242)
		(width 0.1143)
		(layer "F.Cu")
		(net "P3E_CPU0_PE1_PCH_C_TXP<14>")
	)
	(segment
		(start 371.9449 -124.889006)
		(end 370.672106 -126.1618)
		(width 0.0889)
		(layer "F.Cu")
		(net "P3E_CPU0_PE1_PCH_C_TXP<14>")
	)
	(segment
		(start 354.021644 -124.480066)
		(end 349.699326 -124.480066)
		(width 0.1143)
		(layer "F.Cu")
		(net "P3E_CPU0_PE1_PCH_C_TXP<14>")
	)
	(segment
		(start 367.039906 -127.2286)
		(end 364.622842 -127.2286)
		(width 0.0889)
		(layer "F.Cu")
		(net "P3E_CPU0_PE1_PCH_C_TXP<14>")
	)
	(segment
		(start 364.622842 -127.2286)
		(end 364.597442 -127.2032)
		(width 0.0889)
		(layer "F.Cu")
		(net "P3E_CPU0_PE1_PCH_C_TXP<14>")
	)
	(segment
		(start 344.950542 -124.871226)
		(end 343.3572 -124.871226)
		(width 0.1143)
		(layer "F.Cu")
		(net "P3E_CPU0_PE1_PCH_C_TXP<14>")
	)
	(via
		(at 343.3572 -124.871226)
		(size 0.508)
		(drill 0.254)
		(layers "F.Cu" "B.Cu")
		(net "P3E_CPU0_PE1_PCH_C_TXP<14>")
	)
	(segment
		(start 363.982 -126.1872)
		(end 363.9566 -126.1618)
		(width 0.0889)
		(layer "F.Cu")
		(net "P3E_CPU0_PE1_PCH_C_TXP<13>")
	)
	(segment
		(start 366.8903 -125.422406)
		(end 366.8903 -125.844046)
		(width 0.0889)
		(layer "F.Cu")
		(net "P3E_CPU0_PE1_PCH_C_TXP<13>")
	)
	(segment
		(start 345.091258 -122.85218)
		(end 344.077036 -123.866402)
		(width 0.1143)
		(layer "F.Cu")
		(net "P3E_CPU0_PE1_PCH_C_TXP<13>")
	)
	(segment
		(start 325.5518 -120.904)
		(end 325.4375 -120.7897)
		(width 0.1143)
		(layer "F.Cu")
		(net "P3E_CPU0_PE1_PCH_C_TXP<13>")
	)
	(segment
		(start 370.4971 -124.22378)
		(end 370.4971 -124.2949)
		(width 0.0889)
		(layer "F.Cu")
		(net "P3E_CPU0_PE1_PCH_C_TXP<13>")
	)
	(segment
		(start 348.410022 -122.85218)
		(end 345.091258 -122.85218)
		(width 0.1143)
		(layer "F.Cu")
		(net "P3E_CPU0_PE1_PCH_C_TXP<13>")
	)
	(segment
		(start 370.9924 -123.72848)
		(end 370.4971 -124.22378)
		(width 0.0889)
		(layer "F.Cu")
		(net "P3E_CPU0_PE1_PCH_C_TXP<13>")
	)
	(segment
		(start 326.702928 -121.453656)
		(end 326.153272 -120.904)
		(width 0.1143)
		(layer "F.Cu")
		(net "P3E_CPU0_PE1_PCH_C_TXP<13>")
	)
	(segment
		(start 375.033794 -121.039382)
		(end 374.788938 -121.140728)
		(width 0.0889)
		(layer "F.Cu")
		(net "P3E_CPU0_PE1_PCH_C_TXP<13>")
	)
	(segment
		(start 359.035604 -126.43231)
		(end 353.564698 -122.55881)
		(width 0.1143)
		(layer "F.Cu")
		(net "P3E_CPU0_PE1_PCH_C_TXP<13>")
	)
	(segment
		(start 372.981728 -121.922032)
		(end 371.17528 -123.72848)
		(width 0.0889)
		(layer "F.Cu")
		(net "P3E_CPU0_PE1_PCH_C_TXP<13>")
	)
	(segment
		(start 370.4971 -124.2949)
		(end 370.1796 -124.6124)
		(width 0.0889)
		(layer "F.Cu")
		(net "P3E_CPU0_PE1_PCH_C_TXP<13>")
	)
	(segment
		(start 325.4375 -120.7897)
		(end 325.4375 -120.396)
		(width 0.1143)
		(layer "F.Cu")
		(net "P3E_CPU0_PE1_PCH_C_TXP<13>")
	)
	(segment
		(start 370.1796 -124.6124)
		(end 367.700306 -124.6124)
		(width 0.0889)
		(layer "F.Cu")
		(net "P3E_CPU0_PE1_PCH_C_TXP<13>")
	)
	(segment
		(start 371.17528 -123.72848)
		(end 370.9924 -123.72848)
		(width 0.0889)
		(layer "F.Cu")
		(net "P3E_CPU0_PE1_PCH_C_TXP<13>")
	)
	(segment
		(start 374.385078 -121.140728)
		(end 374.043702 -121.482104)
		(width 0.0889)
		(layer "F.Cu")
		(net "P3E_CPU0_PE1_PCH_C_TXP<13>")
	)
	(segment
		(start 375.263918 -121.096278)
		(end 375.207022 -121.039382)
		(width 0.0889)
		(layer "F.Cu")
		(net "P3E_CPU0_PE1_PCH_C_TXP<13>")
	)
	(segment
		(start 352.547428 -121.838466)
		(end 349.423736 -121.838466)
		(width 0.1143)
		(layer "F.Cu")
		(net "P3E_CPU0_PE1_PCH_C_TXP<13>")
	)
	(segment
		(start 326.153272 -120.904)
		(end 325.5518 -120.904)
		(width 0.1143)
		(layer "F.Cu")
		(net "P3E_CPU0_PE1_PCH_C_TXP<13>")
	)
	(segment
		(start 375.92 -121.355104)
		(end 375.263918 -121.096278)
		(width 0.0889)
		(layer "F.Cu")
		(net "P3E_CPU0_PE1_PCH_C_TXP<13>")
	)
	(segment
		(start 375.207022 -121.039382)
		(end 375.033794 -121.039382)
		(width 0.0889)
		(layer "F.Cu")
		(net "P3E_CPU0_PE1_PCH_C_TXP<13>")
	)
	(segment
		(start 328.107802 -123.866402)
		(end 326.702928 -122.461528)
		(width 0.1143)
		(layer "F.Cu")
		(net "P3E_CPU0_PE1_PCH_C_TXP<13>")
	)
	(segment
		(start 374.043702 -121.482104)
		(end 372.981728 -121.922032)
		(width 0.0889)
		(layer "F.Cu")
		(net "P3E_CPU0_PE1_PCH_C_TXP<13>")
	)
	(segment
		(start 349.423736 -121.838466)
		(end 348.410022 -122.85218)
		(width 0.1143)
		(layer "F.Cu")
		(net "P3E_CPU0_PE1_PCH_C_TXP<13>")
	)
	(segment
		(start 362.558076 -126.1618)
		(end 360.120946 -126.64948)
		(width 0.1143)
		(layer "F.Cu")
		(net "P3E_CPU0_PE1_PCH_C_TXP<13>")
	)
	(segment
		(start 366.8903 -125.844046)
		(end 366.547146 -126.1872)
		(width 0.0889)
		(layer "F.Cu")
		(net "P3E_CPU0_PE1_PCH_C_TXP<13>")
	)
	(segment
		(start 366.547146 -126.1872)
		(end 363.982 -126.1872)
		(width 0.0889)
		(layer "F.Cu")
		(net "P3E_CPU0_PE1_PCH_C_TXP<13>")
	)
	(segment
		(start 353.564698 -122.55881)
		(end 352.547428 -121.838466)
		(width 0.1143)
		(layer "F.Cu")
		(net "P3E_CPU0_PE1_PCH_C_TXP<13>")
	)
	(segment
		(start 363.934502 -126.1618)
		(end 362.558076 -126.1618)
		(width 0.1143)
		(layer "F.Cu")
		(net "P3E_CPU0_PE1_PCH_C_TXP<13>")
	)
	(segment
		(start 326.702928 -122.461528)
		(end 326.702928 -121.453656)
		(width 0.1143)
		(layer "F.Cu")
		(net "P3E_CPU0_PE1_PCH_C_TXP<13>")
	)
	(segment
		(start 367.700306 -124.6124)
		(end 366.8903 -125.422406)
		(width 0.0889)
		(layer "F.Cu")
		(net "P3E_CPU0_PE1_PCH_C_TXP<13>")
	)
	(segment
		(start 363.9566 -126.1618)
		(end 363.934502 -126.1618)
		(width 0.0889)
		(layer "F.Cu")
		(net "P3E_CPU0_PE1_PCH_C_TXP<13>")
	)
	(segment
		(start 360.120946 -126.64948)
		(end 359.035604 -126.43231)
		(width 0.1143)
		(layer "F.Cu")
		(net "P3E_CPU0_PE1_PCH_C_TXP<13>")
	)
	(segment
		(start 374.788938 -121.140728)
		(end 374.385078 -121.140728)
		(width 0.0889)
		(layer "F.Cu")
		(net "P3E_CPU0_PE1_PCH_C_TXP<13>")
	)
	(segment
		(start 344.077036 -123.866402)
		(end 328.107802 -123.866402)
		(width 0.1143)
		(layer "F.Cu")
		(net "P3E_CPU0_PE1_PCH_C_TXP<13>")
	)
	(via
		(at 353.564698 -122.55881)
		(size 0.508)
		(drill 0.254)
		(layers "F.Cu" "B.Cu")
		(net "P3E_CPU0_PE1_PCH_C_TXP<13>")
	)
	(segment
		(start 331.04328 -122.7709)
		(end 343.729056 -122.7709)
		(width 0.1143)
		(layer "F.Cu")
		(net "P3E_CPU0_PE1_PCH_C_TXP<12>")
	)
	(segment
		(start 366.455706 -123.2916)
		(end 362.922566 -123.2916)
		(width 0.0889)
		(layer "F.Cu")
		(net "P3E_CPU0_PE1_PCH_C_TXP<12>")
	)
	(segment
		(start 359.888028 -123.3551)
		(end 360.332528 -123.2662)
		(width 0.1143)
		(layer "F.Cu")
		(net "P3E_CPU0_PE1_PCH_C_TXP<12>")
	)
	(segment
		(start 374.83161 -120.569228)
		(end 374.410478 -120.569228)
		(width 0.0889)
		(layer "F.Cu")
		(net "P3E_CPU0_PE1_PCH_C_TXP<12>")
	)
	(segment
		(start 353.265486 -120.865646)
		(end 358.055164 -123.3551)
		(width 0.1143)
		(layer "F.Cu")
		(net "P3E_CPU0_PE1_PCH_C_TXP<12>")
	)
	(segment
		(start 343.729056 -122.7709)
		(end 345.049856 -121.4501)
		(width 0.1143)
		(layer "F.Cu")
		(net "P3E_CPU0_PE1_PCH_C_TXP<12>")
	)
	(segment
		(start 322.05422 -119.58574)
		(end 322.204334 -119.735854)
		(width 0.1143)
		(layer "F.Cu")
		(net "P3E_CPU0_PE1_PCH_C_TXP<12>")
	)
	(segment
		(start 367.217706 -122.5296)
		(end 366.455706 -123.2916)
		(width 0.0889)
		(layer "F.Cu")
		(net "P3E_CPU0_PE1_PCH_C_TXP<12>")
	)
	(segment
		(start 324.22846 -119.672862)
		(end 326.507348 -119.672862)
		(width 0.1143)
		(layer "F.Cu")
		(net "P3E_CPU0_PE1_PCH_C_TXP<12>")
	)
	(segment
		(start 362.875068 -123.2662)
		(end 361.088432 -123.2662)
		(width 0.1143)
		(layer "F.Cu")
		(net "P3E_CPU0_PE1_PCH_C_TXP<12>")
	)
	(segment
		(start 373.830596 -121.14911)
		(end 370.471446 -122.5296)
		(width 0.0889)
		(layer "F.Cu")
		(net "P3E_CPU0_PE1_PCH_C_TXP<12>")
	)
	(segment
		(start 330.73848 -122.4661)
		(end 331.04328 -122.7709)
		(width 0.1143)
		(layer "F.Cu")
		(net "P3E_CPU0_PE1_PCH_C_TXP<12>")
	)
	(segment
		(start 323.638418 -119.08282)
		(end 324.22846 -119.672862)
		(width 0.1143)
		(layer "F.Cu")
		(net "P3E_CPU0_PE1_PCH_C_TXP<12>")
	)
	(segment
		(start 322.204334 -119.735854)
		(end 322.366386 -119.735854)
		(width 0.1143)
		(layer "F.Cu")
		(net "P3E_CPU0_PE1_PCH_C_TXP<12>")
	)
	(segment
		(start 326.507348 -119.672862)
		(end 329.300586 -122.4661)
		(width 0.1143)
		(layer "F.Cu")
		(net "P3E_CPU0_PE1_PCH_C_TXP<12>")
	)
	(segment
		(start 329.300586 -122.4661)
		(end 330.73848 -122.4661)
		(width 0.1143)
		(layer "F.Cu")
		(net "P3E_CPU0_PE1_PCH_C_TXP<12>")
	)
	(segment
		(start 370.471446 -122.5296)
		(end 367.217706 -122.5296)
		(width 0.0889)
		(layer "F.Cu")
		(net "P3E_CPU0_PE1_PCH_C_TXP<12>")
	)
	(segment
		(start 362.922566 -123.2916)
		(end 362.897166 -123.2662)
		(width 0.0889)
		(layer "F.Cu")
		(net "P3E_CPU0_PE1_PCH_C_TXP<12>")
	)
	(segment
		(start 374.891554 -120.629172)
		(end 374.83161 -120.569228)
		(width 0.0889)
		(layer "F.Cu")
		(net "P3E_CPU0_PE1_PCH_C_TXP<12>")
	)
	(segment
		(start 322.05422 -119.26316)
		(end 322.05422 -119.58574)
		(width 0.1143)
		(layer "F.Cu")
		(net "P3E_CPU0_PE1_PCH_C_TXP<12>")
	)
	(segment
		(start 348.436184 -121.4501)
		(end 349.020638 -120.865646)
		(width 0.1143)
		(layer "F.Cu")
		(net "P3E_CPU0_PE1_PCH_C_TXP<12>")
	)
	(segment
		(start 374.410478 -120.569228)
		(end 373.830596 -121.14911)
		(width 0.0889)
		(layer "F.Cu")
		(net "P3E_CPU0_PE1_PCH_C_TXP<12>")
	)
	(segment
		(start 362.897166 -123.2662)
		(end 362.875068 -123.2662)
		(width 0.0889)
		(layer "F.Cu")
		(net "P3E_CPU0_PE1_PCH_C_TXP<12>")
	)
	(segment
		(start 358.055164 -123.3551)
		(end 359.888028 -123.3551)
		(width 0.1143)
		(layer "F.Cu")
		(net "P3E_CPU0_PE1_PCH_C_TXP<12>")
	)
	(segment
		(start 345.049856 -121.4501)
		(end 348.436184 -121.4501)
		(width 0.1143)
		(layer "F.Cu")
		(net "P3E_CPU0_PE1_PCH_C_TXP<12>")
	)
	(segment
		(start 323.01942 -119.08282)
		(end 323.638418 -119.08282)
		(width 0.1143)
		(layer "F.Cu")
		(net "P3E_CPU0_PE1_PCH_C_TXP<12>")
	)
	(segment
		(start 349.020638 -120.865646)
		(end 353.265486 -120.865646)
		(width 0.1143)
		(layer "F.Cu")
		(net "P3E_CPU0_PE1_PCH_C_TXP<12>")
	)
	(segment
		(start 360.332528 -123.2662)
		(end 361.088432 -123.2662)
		(width 0.1143)
		(layer "F.Cu")
		(net "P3E_CPU0_PE1_PCH_C_TXP<12>")
	)
	(segment
		(start 375.504964 -120.854978)
		(end 374.891554 -120.629172)
		(width 0.0889)
		(layer "F.Cu")
		(net "P3E_CPU0_PE1_PCH_C_TXP<12>")
	)
	(segment
		(start 322.366386 -119.735854)
		(end 323.01942 -119.08282)
		(width 0.1143)
		(layer "F.Cu")
		(net "P3E_CPU0_PE1_PCH_C_TXP<12>")
	)
	(via
		(at 361.088432 -123.2662)
		(size 0.508)
		(drill 0.254)
		(layers "F.Cu" "B.Cu")
		(net "P3E_CPU0_PE1_PCH_C_TXP<12>")
	)
	(segment
		(start 365.590582 -120.452642)
		(end 365.852202 -120.504966)
		(width 0.0889)
		(layer "F.Cu")
		(net "P3E_CPU0_PE1_PCH_C_TXP<11>")
	)
	(segment
		(start 355.470968 -120.724168)
		(end 355.548184 -120.866408)
		(width 0.1143)
		(layer "F.Cu")
		(net "P3E_CPU0_PE1_PCH_C_TXP<11>")
	)
	(segment
		(start 362.890054 -119.913146)
		(end 362.994702 -119.843296)
		(width 0.0889)
		(layer "F.Cu")
		(net "P3E_CPU0_PE1_PCH_C_TXP<11>")
	)
	(segment
		(start 355.87686 -120.96369)
		(end 356.0191 -120.886728)
		(width 0.1143)
		(layer "F.Cu")
		(net "P3E_CPU0_PE1_PCH_C_TXP<11>")
	)
	(segment
		(start 323.9135 -118.0973)
		(end 323.9135 -118.415816)
		(width 0.1143)
		(layer "F.Cu")
		(net "P3E_CPU0_PE1_PCH_C_TXP<11>")
	)
	(segment
		(start 362.034836 -119.651526)
		(end 362.558838 -119.756174)
		(width 0.0889)
		(layer "F.Cu")
		(net "P3E_CPU0_PE1_PCH_C_TXP<11>")
	)
	(segment
		(start 370.541042 -121.7295)
		(end 370.629942 -121.8184)
		(width 0.0889)
		(layer "F.Cu")
		(net "P3E_CPU0_PE1_PCH_C_TXP<11>")
	)
	(segment
		(start 355.548184 -120.866408)
		(end 355.87686 -120.96369)
		(width 0.1143)
		(layer "F.Cu")
		(net "P3E_CPU0_PE1_PCH_C_TXP<11>")
	)
	(segment
		(start 331.103224 -121.6914)
		(end 329.591924 -121.6914)
		(width 0.1143)
		(layer "F.Cu")
		(net "P3E_CPU0_PE1_PCH_C_TXP<11>")
	)
	(segment
		(start 364.023402 -120.139714)
		(end 364.285022 -120.191784)
		(width 0.0889)
		(layer "F.Cu")
		(net "P3E_CPU0_PE1_PCH_C_TXP<11>")
	)
	(segment
		(start 369.474242 -121.8184)
		(end 369.563142 -121.7295)
		(width 0.0889)
		(layer "F.Cu")
		(net "P3E_CPU0_PE1_PCH_C_TXP<11>")
	)
	(segment
		(start 365.852202 -120.504966)
		(end 365.956596 -120.435116)
		(width 0.0889)
		(layer "F.Cu")
		(net "P3E_CPU0_PE1_PCH_C_TXP<11>")
	)
	(segment
		(start 370.185442 -121.8184)
		(end 370.274342 -121.7295)
		(width 0.0889)
		(layer "F.Cu")
		(net "P3E_CPU0_PE1_PCH_C_TXP<11>")
	)
	(segment
		(start 365.154718 -120.36552)
		(end 365.259112 -120.29567)
		(width 0.0889)
		(layer "F.Cu")
		(net "P3E_CPU0_PE1_PCH_C_TXP<11>")
	)
	(segment
		(start 356.347776 -120.98401)
		(end 361.544108 -119.579898)
		(width 0.1143)
		(layer "F.Cu")
		(net "P3E_CPU0_PE1_PCH_C_TXP<11>")
	)
	(segment
		(start 363.692186 -119.982742)
		(end 363.953806 -120.035066)
		(width 0.0889)
		(layer "F.Cu")
		(net "P3E_CPU0_PE1_PCH_C_TXP<11>")
	)
	(segment
		(start 368.496342 -121.8184)
		(end 368.763042 -121.8184)
		(width 0.0889)
		(layer "F.Cu")
		(net "P3E_CPU0_PE1_PCH_C_TXP<11>")
	)
	(segment
		(start 363.325918 -120.000268)
		(end 363.587538 -120.052592)
		(width 0.0889)
		(layer "F.Cu")
		(net "P3E_CPU0_PE1_PCH_C_TXP<11>")
	)
	(segment
		(start 367.795556 -121.60631)
		(end 367.918746 -121.581672)
		(width 0.0889)
		(layer "F.Cu")
		(net "P3E_CPU0_PE1_PCH_C_TXP<11>")
	)
	(segment
		(start 348.65183 -120.10517)
		(end 353.38131 -120.10517)
		(width 0.1143)
		(layer "F.Cu")
		(net "P3E_CPU0_PE1_PCH_C_TXP<11>")
	)
	(segment
		(start 326.828658 -118.928134)
		(end 325.303134 -118.928134)
		(width 0.1143)
		(layer "F.Cu")
		(net "P3E_CPU0_PE1_PCH_C_TXP<11>")
	)
	(segment
		(start 366.98174 -121.063766)
		(end 367.203736 -121.211848)
		(width 0.0889)
		(layer "F.Cu")
		(net "P3E_CPU0_PE1_PCH_C_TXP<11>")
	)
	(segment
		(start 365.259112 -120.29567)
		(end 365.520732 -120.347994)
		(width 0.0889)
		(layer "F.Cu")
		(net "P3E_CPU0_PE1_PCH_C_TXP<11>")
	)
	(segment
		(start 324.053708 -117.957092)
		(end 323.9135 -118.0973)
		(width 0.1143)
		(layer "F.Cu")
		(net "P3E_CPU0_PE1_PCH_C_TXP<11>")
	)
	(segment
		(start 363.256322 -119.895874)
		(end 363.325918 -120.000268)
		(width 0.0889)
		(layer "F.Cu")
		(net "P3E_CPU0_PE1_PCH_C_TXP<11>")
	)
	(segment
		(start 369.829842 -121.7295)
		(end 369.918742 -121.8184)
		(width 0.0889)
		(layer "F.Cu")
		(net "P3E_CPU0_PE1_PCH_C_TXP<11>")
	)
	(segment
		(start 363.953806 -120.035066)
		(end 364.023402 -120.139714)
		(width 0.0889)
		(layer "F.Cu")
		(net "P3E_CPU0_PE1_PCH_C_TXP<11>")
	)
	(segment
		(start 364.893098 -120.313196)
		(end 365.154718 -120.36552)
		(width 0.0889)
		(layer "F.Cu")
		(net "P3E_CPU0_PE1_PCH_C_TXP<11>")
	)
	(segment
		(start 362.558838 -119.756174)
		(end 362.628434 -119.860822)
		(width 0.0889)
		(layer "F.Cu")
		(net "P3E_CPU0_PE1_PCH_C_TXP<11>")
	)
	(segment
		(start 365.956596 -120.435116)
		(end 366.302544 -120.504204)
		(width 0.0889)
		(layer "F.Cu")
		(net "P3E_CPU0_PE1_PCH_C_TXP<11>")
	)
	(segment
		(start 353.38131 -120.10517)
		(end 355.470968 -120.724168)
		(width 0.1143)
		(layer "F.Cu")
		(net "P3E_CPU0_PE1_PCH_C_TXP<11>")
	)
	(segment
		(start 374.35917 -120.331484)
		(end 375.066306 -120.331484)
		(width 0.0889)
		(layer "F.Cu")
		(net "P3E_CPU0_PE1_PCH_C_TXP<11>")
	)
	(segment
		(start 370.985542 -121.7295)
		(end 371.785388 -121.7295)
		(width 0.0889)
		(layer "F.Cu")
		(net "P3E_CPU0_PE1_PCH_C_TXP<11>")
	)
	(segment
		(start 367.57356 -121.458228)
		(end 367.795556 -121.60631)
		(width 0.0889)
		(layer "F.Cu")
		(net "P3E_CPU0_PE1_PCH_C_TXP<11>")
	)
	(segment
		(start 362.00461 -119.6721)
		(end 362.034836 -119.651526)
		(width 0.0889)
		(layer "F.Cu")
		(net "P3E_CPU0_PE1_PCH_C_TXP<11>")
	)
	(segment
		(start 325.303134 -118.928134)
		(end 324.332092 -117.957092)
		(width 0.1143)
		(layer "F.Cu")
		(net "P3E_CPU0_PE1_PCH_C_TXP<11>")
	)
	(segment
		(start 356.0191 -120.886728)
		(end 356.347776 -120.98401)
		(width 0.1143)
		(layer "F.Cu")
		(net "P3E_CPU0_PE1_PCH_C_TXP<11>")
	)
	(segment
		(start 364.823248 -120.208548)
		(end 364.893098 -120.313196)
		(width 0.0889)
		(layer "F.Cu")
		(net "P3E_CPU0_PE1_PCH_C_TXP<11>")
	)
	(segment
		(start 369.563142 -121.7295)
		(end 369.829842 -121.7295)
		(width 0.0889)
		(layer "F.Cu")
		(net "P3E_CPU0_PE1_PCH_C_TXP<11>")
	)
	(segment
		(start 370.629942 -121.8184)
		(end 370.896642 -121.8184)
		(width 0.0889)
		(layer "F.Cu")
		(net "P3E_CPU0_PE1_PCH_C_TXP<11>")
	)
	(segment
		(start 344.839544 -120.6246)
		(end 348.1324 -120.6246)
		(width 0.1143)
		(layer "F.Cu")
		(net "P3E_CPU0_PE1_PCH_C_TXP<11>")
	)
	(segment
		(start 369.918742 -121.8184)
		(end 370.185442 -121.8184)
		(width 0.0889)
		(layer "F.Cu")
		(net "P3E_CPU0_PE1_PCH_C_TXP<11>")
	)
	(segment
		(start 329.591924 -121.6914)
		(end 326.828658 -118.928134)
		(width 0.1143)
		(layer "F.Cu")
		(net "P3E_CPU0_PE1_PCH_C_TXP<11>")
	)
	(segment
		(start 370.274342 -121.7295)
		(end 370.541042 -121.7295)
		(width 0.0889)
		(layer "F.Cu")
		(net "P3E_CPU0_PE1_PCH_C_TXP<11>")
	)
	(segment
		(start 375.066306 -120.331484)
		(end 375.089928 -120.355106)
		(width 0.0889)
		(layer "F.Cu")
		(net "P3E_CPU0_PE1_PCH_C_TXP<11>")
	)
	(segment
		(start 361.544108 -119.579898)
		(end 361.98302 -119.667782)
		(width 0.1143)
		(layer "F.Cu")
		(net "P3E_CPU0_PE1_PCH_C_TXP<11>")
	)
	(segment
		(start 343.455244 -122.0089)
		(end 344.839544 -120.6246)
		(width 0.1143)
		(layer "F.Cu")
		(net "P3E_CPU0_PE1_PCH_C_TXP<11>")
	)
	(segment
		(start 365.520732 -120.347994)
		(end 365.590582 -120.452642)
		(width 0.0889)
		(layer "F.Cu")
		(net "P3E_CPU0_PE1_PCH_C_TXP<11>")
	)
	(segment
		(start 368.763042 -121.8184)
		(end 368.851942 -121.7295)
		(width 0.0889)
		(layer "F.Cu")
		(net "P3E_CPU0_PE1_PCH_C_TXP<11>")
	)
	(segment
		(start 371.785388 -121.7295)
		(end 373.792496 -120.898158)
		(width 0.0889)
		(layer "F.Cu")
		(net "P3E_CPU0_PE1_PCH_C_TXP<11>")
	)
	(segment
		(start 373.792496 -120.898158)
		(end 374.35917 -120.331484)
		(width 0.0889)
		(layer "F.Cu")
		(net "P3E_CPU0_PE1_PCH_C_TXP<11>")
	)
	(segment
		(start 368.140742 -121.7295)
		(end 368.407442 -121.7295)
		(width 0.0889)
		(layer "F.Cu")
		(net "P3E_CPU0_PE1_PCH_C_TXP<11>")
	)
	(segment
		(start 368.407442 -121.7295)
		(end 368.496342 -121.8184)
		(width 0.0889)
		(layer "F.Cu")
		(net "P3E_CPU0_PE1_PCH_C_TXP<11>")
	)
	(segment
		(start 368.851942 -121.7295)
		(end 369.118642 -121.7295)
		(width 0.0889)
		(layer "F.Cu")
		(net "P3E_CPU0_PE1_PCH_C_TXP<11>")
	)
	(segment
		(start 369.118642 -121.7295)
		(end 369.207542 -121.8184)
		(width 0.0889)
		(layer "F.Cu")
		(net "P3E_CPU0_PE1_PCH_C_TXP<11>")
	)
	(segment
		(start 331.420724 -122.0089)
		(end 331.103224 -121.6914)
		(width 0.1143)
		(layer "F.Cu")
		(net "P3E_CPU0_PE1_PCH_C_TXP<11>")
	)
	(segment
		(start 332.070202 -122.0089)
		(end 331.420724 -122.0089)
		(width 0.1143)
		(layer "F.Cu")
		(net "P3E_CPU0_PE1_PCH_C_TXP<11>")
	)
	(segment
		(start 348.1324 -120.6246)
		(end 348.65183 -120.10517)
		(width 0.1143)
		(layer "F.Cu")
		(net "P3E_CPU0_PE1_PCH_C_TXP<11>")
	)
	(segment
		(start 364.38967 -120.122188)
		(end 364.823248 -120.208802)
		(width 0.0889)
		(layer "F.Cu")
		(net "P3E_CPU0_PE1_PCH_C_TXP<11>")
	)
	(segment
		(start 366.957102 -120.940576)
		(end 366.98174 -121.063766)
		(width 0.0889)
		(layer "F.Cu")
		(net "P3E_CPU0_PE1_PCH_C_TXP<11>")
	)
	(segment
		(start 367.203736 -121.211848)
		(end 367.326926 -121.18721)
		(width 0.0889)
		(layer "F.Cu")
		(net "P3E_CPU0_PE1_PCH_C_TXP<11>")
	)
	(segment
		(start 361.98302 -119.667782)
		(end 362.00461 -119.6721)
		(width 0.0889)
		(layer "F.Cu")
		(net "P3E_CPU0_PE1_PCH_C_TXP<11>")
	)
	(segment
		(start 366.302544 -120.504204)
		(end 366.957102 -120.940576)
		(width 0.0889)
		(layer "F.Cu")
		(net "P3E_CPU0_PE1_PCH_C_TXP<11>")
	)
	(segment
		(start 370.896642 -121.8184)
		(end 370.985542 -121.7295)
		(width 0.0889)
		(layer "F.Cu")
		(net "P3E_CPU0_PE1_PCH_C_TXP<11>")
	)
	(segment
		(start 362.628434 -119.860822)
		(end 362.890054 -119.913146)
		(width 0.0889)
		(layer "F.Cu")
		(net "P3E_CPU0_PE1_PCH_C_TXP<11>")
	)
	(segment
		(start 363.587538 -120.052592)
		(end 363.692186 -119.982742)
		(width 0.0889)
		(layer "F.Cu")
		(net "P3E_CPU0_PE1_PCH_C_TXP<11>")
	)
	(segment
		(start 364.285022 -120.191784)
		(end 364.38967 -120.122188)
		(width 0.0889)
		(layer "F.Cu")
		(net "P3E_CPU0_PE1_PCH_C_TXP<11>")
	)
	(segment
		(start 367.326926 -121.18721)
		(end 367.548922 -121.335038)
		(width 0.0889)
		(layer "F.Cu")
		(net "P3E_CPU0_PE1_PCH_C_TXP<11>")
	)
	(segment
		(start 367.548922 -121.335038)
		(end 367.57356 -121.458228)
		(width 0.0889)
		(layer "F.Cu")
		(net "P3E_CPU0_PE1_PCH_C_TXP<11>")
	)
	(segment
		(start 332.070202 -122.0089)
		(end 343.455244 -122.0089)
		(width 0.1143)
		(layer "F.Cu")
		(net "P3E_CPU0_PE1_PCH_C_TXP<11>")
	)
	(segment
		(start 362.994702 -119.84355)
		(end 363.256322 -119.895874)
		(width 0.0889)
		(layer "F.Cu")
		(net "P3E_CPU0_PE1_PCH_C_TXP<11>")
	)
	(segment
		(start 362.994702 -119.843296)
		(end 362.994702 -119.84355)
		(width 0.0889)
		(layer "F.Cu")
		(net "P3E_CPU0_PE1_PCH_C_TXP<11>")
	)
	(segment
		(start 369.207542 -121.8184)
		(end 369.474242 -121.8184)
		(width 0.0889)
		(layer "F.Cu")
		(net "P3E_CPU0_PE1_PCH_C_TXP<11>")
	)
	(segment
		(start 367.918746 -121.581672)
		(end 368.140742 -121.7295)
		(width 0.0889)
		(layer "F.Cu")
		(net "P3E_CPU0_PE1_PCH_C_TXP<11>")
	)
	(segment
		(start 364.823248 -120.208802)
		(end 364.823248 -120.208548)
		(width 0.0889)
		(layer "F.Cu")
		(net "P3E_CPU0_PE1_PCH_C_TXP<11>")
	)
	(segment
		(start 324.332092 -117.957092)
		(end 324.053708 -117.957092)
		(width 0.1143)
		(layer "F.Cu")
		(net "P3E_CPU0_PE1_PCH_C_TXP<11>")
	)
	(via
		(at 332.070202 -122.0089)
		(size 0.508)
		(drill 0.254)
		(layers "F.Cu" "B.Cu")
		(net "P3E_CPU0_PE1_PCH_C_TXP<11>")
	)
	(segment
		(start 374.28297 -119.568722)
		(end 373.453406 -120.398286)
		(width 0.0889)
		(layer "F.Cu")
		(net "P3E_CPU0_PE1_PCH_C_TXP<10>")
	)
	(segment
		(start 366.46739 -119.155718)
		(end 363.897164 -118.641368)
		(width 0.0889)
		(layer "F.Cu")
		(net "P3E_CPU0_PE1_PCH_C_TXP<10>")
	)
	(segment
		(start 359.946448 -118.603268)
		(end 359.946194 -118.603014)
		(width 0.1143)
		(layer "F.Cu")
		(net "P3E_CPU0_PE1_PCH_C_TXP<10>")
	)
	(segment
		(start 363.87659 -118.61165)
		(end 363.855 -118.607586)
		(width 0.0889)
		(layer "F.Cu")
		(net "P3E_CPU0_PE1_PCH_C_TXP<10>")
	)
	(segment
		(start 347.600524 -119.3673)
		(end 341.944452 -119.3673)
		(width 0.1143)
		(layer "F.Cu")
		(net "P3E_CPU0_PE1_PCH_C_TXP<10>")
	)
	(segment
		(start 348.091252 -118.876572)
		(end 347.600524 -119.3673)
		(width 0.1143)
		(layer "F.Cu")
		(net "P3E_CPU0_PE1_PCH_C_TXP<10>")
	)
	(segment
		(start 359.94594 -118.603268)
		(end 356.36581 -119.570754)
		(width 0.1143)
		(layer "F.Cu")
		(net "P3E_CPU0_PE1_PCH_C_TXP<10>")
	)
	(segment
		(start 375.504964 -119.85498)
		(end 375.06529 -119.699532)
		(width 0.0889)
		(layer "F.Cu")
		(net "P3E_CPU0_PE1_PCH_C_TXP<10>")
	)
	(segment
		(start 363.855 -118.607586)
		(end 361.602528 -118.15572)
		(width 0.1143)
		(layer "F.Cu")
		(net "P3E_CPU0_PE1_PCH_C_TXP<10>")
	)
	(segment
		(start 373.084598 -120.521222)
		(end 368.5159 -120.521222)
		(width 0.0889)
		(layer "F.Cu")
		(net "P3E_CPU0_PE1_PCH_C_TXP<10>")
	)
	(segment
		(start 340.793578 -120.518174)
		(end 338.477352 -120.518174)
		(width 0.1143)
		(layer "F.Cu")
		(net "P3E_CPU0_PE1_PCH_C_TXP<10>")
	)
	(segment
		(start 374.833896 -119.568722)
		(end 374.28297 -119.568722)
		(width 0.0889)
		(layer "F.Cu")
		(net "P3E_CPU0_PE1_PCH_C_TXP<10>")
	)
	(segment
		(start 363.896148 -118.641114)
		(end 363.87659 -118.61165)
		(width 0.0889)
		(layer "F.Cu")
		(net "P3E_CPU0_PE1_PCH_C_TXP<10>")
	)
	(segment
		(start 338.477352 -120.518174)
		(end 338.318602 -120.359424)
		(width 0.1143)
		(layer "F.Cu")
		(net "P3E_CPU0_PE1_PCH_C_TXP<10>")
	)
	(segment
		(start 359.946194 -118.603014)
		(end 359.94594 -118.603268)
		(width 0.1143)
		(layer "F.Cu")
		(net "P3E_CPU0_PE1_PCH_C_TXP<10>")
	)
	(segment
		(start 354.020882 -118.876572)
		(end 348.091252 -118.876572)
		(width 0.1143)
		(layer "F.Cu")
		(net "P3E_CPU0_PE1_PCH_C_TXP<10>")
	)
	(segment
		(start 373.453406 -120.398286)
		(end 373.084598 -120.521222)
		(width 0.0889)
		(layer "F.Cu")
		(net "P3E_CPU0_PE1_PCH_C_TXP<10>")
	)
	(segment
		(start 368.5159 -120.521222)
		(end 366.46739 -119.155718)
		(width 0.0889)
		(layer "F.Cu")
		(net "P3E_CPU0_PE1_PCH_C_TXP<10>")
	)
	(segment
		(start 356.36581 -119.570754)
		(end 354.020882 -118.876572)
		(width 0.1143)
		(layer "F.Cu")
		(net "P3E_CPU0_PE1_PCH_C_TXP<10>")
	)
	(segment
		(start 361.602528 -118.15572)
		(end 359.946448 -118.603268)
		(width 0.1143)
		(layer "F.Cu")
		(net "P3E_CPU0_PE1_PCH_C_TXP<10>")
	)
	(segment
		(start 338.318602 -120.359424)
		(end 338.318602 -120.038368)
		(width 0.1143)
		(layer "F.Cu")
		(net "P3E_CPU0_PE1_PCH_C_TXP<10>")
	)
	(segment
		(start 341.944452 -119.3673)
		(end 340.793578 -120.518174)
		(width 0.1143)
		(layer "F.Cu")
		(net "P3E_CPU0_PE1_PCH_C_TXP<10>")
	)
	(segment
		(start 375.06529 -119.699532)
		(end 374.833896 -119.568722)
		(width 0.0889)
		(layer "F.Cu")
		(net "P3E_CPU0_PE1_PCH_C_TXP<10>")
	)
	(segment
		(start 363.897164 -118.641368)
		(end 363.896148 -118.641114)
		(width 0.0889)
		(layer "F.Cu")
		(net "P3E_CPU0_PE1_PCH_C_TXP<10>")
	)
	(via
		(at 359.946194 -118.603014)
		(size 0.508)
		(drill 0.254)
		(layers "F.Cu" "B.Cu")
		(net "P3E_CPU0_PE1_PCH_C_TXP<10>")
	)
	(segment
		(start 386.74675 -101.039676)
		(end 386.25145 -101.2698)
		(width 0.10795)
		(layer "F.Cu")
		(net "FM_INTRUDER_HDR_PCH_N")
	)
	(via
		(at 386.74675 -101.039676)
		(size 0.508)
		(drill 0.254)
		(layers "F.Cu" "B.Cu")
		(net "FM_INTRUDER_HDR_PCH_N")
	)
	(via
		(at 385.63423 -91.7702)
		(size 0.6604)
		(drill 0.3302)
		(layers "F.Cu" "B.Cu")
		(net "FM_INTRUDER_HDR_PCH_N")
	)
	(segment
		(start 386.6515 -96.758252)
		(end 386.6515 -96.7359)
		(width 0.0889)
		(layer "B.Cu")
		(net "FM_INTRUDER_HDR_PCH_N")
	)
	(segment
		(start 386.08 -89.35085)
		(end 386.08 -88.2015)
		(width 0.10795)
		(layer "B.Cu")
		(net "FM_INTRUDER_HDR_PCH_N")
	)
	(segment
		(start 385.953 -95.25)
		(end 385.826 -95.123)
		(width 0.10795)
		(layer "B.Cu")
		(net "FM_INTRUDER_HDR_PCH_N")
	)
	(segment
		(start 385.450334 -93.133418)
		(end 385.450334 -92.63253)
		(width 0.10795)
		(layer "B.Cu")
		(net "FM_INTRUDER_HDR_PCH_N")
	)
	(segment
		(start 386.1562 -95.910146)
		(end 386.1562 -95.4532)
		(width 0.0889)
		(layer "B.Cu")
		(net "FM_INTRUDER_HDR_PCH_N")
	)
	(segment
		(start 386.1562 -99.344226)
		(end 386.1562 -99.301046)
		(width 0.0889)
		(layer "B.Cu")
		(net "FM_INTRUDER_HDR_PCH_N")
	)
	(segment
		(start 385.826 -93.509084)
		(end 385.450334 -93.133418)
		(width 0.10795)
		(layer "B.Cu")
		(net "FM_INTRUDER_HDR_PCH_N")
	)
	(segment
		(start 385.63423 -89.79662)
		(end 386.08 -89.35085)
		(width 0.10795)
		(layer "B.Cu")
		(net "FM_INTRUDER_HDR_PCH_N")
	)
	(segment
		(start 386.1562 -95.4532)
		(end 385.953 -95.25)
		(width 0.0889)
		(layer "B.Cu")
		(net "FM_INTRUDER_HDR_PCH_N")
	)
	(segment
		(start 386.6515 -98.475292)
		(end 386.6515 -98.45294)
		(width 0.0889)
		(layer "B.Cu")
		(net "FM_INTRUDER_HDR_PCH_N")
	)
	(segment
		(start 385.450334 -92.63253)
		(end 385.63423 -92.448634)
		(width 0.10795)
		(layer "B.Cu")
		(net "FM_INTRUDER_HDR_PCH_N")
	)
	(segment
		(start 386.74675 -101.039676)
		(end 386.91566 -100.74656)
		(width 0.0889)
		(layer "B.Cu")
		(net "FM_INTRUDER_HDR_PCH_N")
	)
	(segment
		(start 386.91566 -100.74656)
		(end 386.89153 -100.657152)
		(width 0.0889)
		(layer "B.Cu")
		(net "FM_INTRUDER_HDR_PCH_N")
	)
	(segment
		(start 385.63423 -92.448634)
		(end 385.63423 -91.7702)
		(width 0.10795)
		(layer "B.Cu")
		(net "FM_INTRUDER_HDR_PCH_N")
	)
	(segment
		(start 385.826 -95.123)
		(end 385.826 -93.509084)
		(width 0.10795)
		(layer "B.Cu")
		(net "FM_INTRUDER_HDR_PCH_N")
	)
	(segment
		(start 386.1562 -97.627186)
		(end 386.1562 -97.584006)
		(width 0.0889)
		(layer "B.Cu")
		(net "FM_INTRUDER_HDR_PCH_N")
	)
	(segment
		(start 386.6515 -100.202746)
		(end 386.6515 -100.16998)
		(width 0.0889)
		(layer "B.Cu")
		(net "FM_INTRUDER_HDR_PCH_N")
	)
	(segment
		(start 385.63423 -91.7702)
		(end 385.63423 -89.79662)
		(width 0.10795)
		(layer "B.Cu")
		(net "FM_INTRUDER_HDR_PCH_N")
	)
	(arc
		(start 386.451348 -99.834446)
		(mid 386.240484 -99.627442)
		(end 386.1562 -99.344226)
		(width 0.0889)
		(layer "B.Cu")
		(net "FM_INTRUDER_HDR_PCH_N")
	)
	(arc
		(start 386.451348 -96.400366)
		(mid 386.240484 -96.193362)
		(end 386.1562 -95.910146)
		(width 0.0889)
		(layer "B.Cu")
		(net "FM_INTRUDER_HDR_PCH_N")
	)
	(arc
		(start 386.6515 -100.16998)
		(mid 386.59515 -99.97613)
		(end 386.451348 -99.834446)
		(width 0.0889)
		(layer "B.Cu")
		(net "FM_INTRUDER_HDR_PCH_N")
	)
	(arc
		(start 386.451348 -98.117406)
		(mid 386.240484 -97.910402)
		(end 386.1562 -97.627186)
		(width 0.0889)
		(layer "B.Cu")
		(net "FM_INTRUDER_HDR_PCH_N")
	)
	(arc
		(start 386.451348 -98.810826)
		(mid 386.595152 -98.669143)
		(end 386.6515 -98.475292)
		(width 0.0889)
		(layer "B.Cu")
		(net "FM_INTRUDER_HDR_PCH_N")
	)
	(arc
		(start 386.1562 -99.301046)
		(mid 386.240481 -99.017829)
		(end 386.451348 -98.810826)
		(width 0.0889)
		(layer "B.Cu")
		(net "FM_INTRUDER_HDR_PCH_N")
	)
	(arc
		(start 386.89153 -100.657152)
		(mid 386.719536 -100.457407)
		(end 386.6515 -100.202746)
		(width 0.0889)
		(layer "B.Cu")
		(net "FM_INTRUDER_HDR_PCH_N")
	)
	(arc
		(start 386.6515 -98.45294)
		(mid 386.59515 -98.25909)
		(end 386.451348 -98.117406)
		(width 0.0889)
		(layer "B.Cu")
		(net "FM_INTRUDER_HDR_PCH_N")
	)
	(arc
		(start 386.1562 -97.584006)
		(mid 386.240481 -97.300789)
		(end 386.451348 -97.093786)
		(width 0.0889)
		(layer "B.Cu")
		(net "FM_INTRUDER_HDR_PCH_N")
	)
	(arc
		(start 386.6515 -96.7359)
		(mid 386.59515 -96.54205)
		(end 386.451348 -96.400366)
		(width 0.0889)
		(layer "B.Cu")
		(net "FM_INTRUDER_HDR_PCH_N")
	)
	(arc
		(start 386.451348 -97.093786)
		(mid 386.595152 -96.952103)
		(end 386.6515 -96.758252)
		(width 0.0889)
		(layer "B.Cu")
		(net "FM_INTRUDER_HDR_PCH_N")
	)
	(segment
		(start 417.895024 -141.732)
		(end 417.895024 -143.158972)
		(width 0.10795)
		(layer "B.Cu")
		(net "PU_DATAIN1_SATA_1_R")
	)
	(segment
		(start 417.895024 -143.158972)
		(end 418.276024 -143.539972)
		(width 0.10795)
		(layer "B.Cu")
		(net "PU_DATAIN1_SATA_1_R")
	)
	(via
		(at 432.29784 -148.68906)
		(size 0.6604)
		(drill 0.3302)
		(layers "F.Cu" "B.Cu")
		(net "PU_DATAIN1_SATA_0_R")
	)
	(segment
		(start 432.82108 -147.504658)
		(end 433.243482 -147.504658)
		(width 0.10795)
		(layer "B.Cu")
		(net "PU_DATAIN1_SATA_0_R")
	)
	(segment
		(start 432.68646 -148.30044)
		(end 432.68646 -147.639278)
		(width 0.10795)
		(layer "B.Cu")
		(net "PU_DATAIN1_SATA_0_R")
	)
	(segment
		(start 432.29784 -148.68906)
		(end 432.68646 -148.30044)
		(width 0.10795)
		(layer "B.Cu")
		(net "PU_DATAIN1_SATA_0_R")
	)
	(segment
		(start 430.276 -143.539972)
		(end 430.276 -144.004284)
		(width 0.10795)
		(layer "B.Cu")
		(net "PU_DATAIN1_SATA_0_R")
	)
	(segment
		(start 432.68646 -147.639278)
		(end 432.82108 -147.504658)
		(width 0.10795)
		(layer "B.Cu")
		(net "PU_DATAIN1_SATA_0_R")
	)
	(segment
		(start 430.276 -144.004284)
		(end 431.2158 -144.944084)
		(width 0.10795)
		(layer "B.Cu")
		(net "PU_DATAIN1_SATA_0_R")
	)
	(segment
		(start 431.2158 -147.60702)
		(end 432.29784 -148.68906)
		(width 0.10795)
		(layer "B.Cu")
		(net "PU_DATAIN1_SATA_0_R")
	)
	(segment
		(start 431.2158 -144.944084)
		(end 431.2158 -147.60702)
		(width 0.10795)
		(layer "B.Cu")
		(net "PU_DATAIN1_SATA_0_R")
	)
	(segment
		(start 417.006024 -141.732)
		(end 417.006024 -142.6464)
		(width 0.10795)
		(layer "B.Cu")
		(net "PD_SATA1_CONTROLLER_TYPE_R")
	)
	(segment
		(start 417.525962 -143.166338)
		(end 417.525962 -144.94002)
		(width 0.10795)
		(layer "B.Cu")
		(net "PD_SATA1_CONTROLLER_TYPE_R")
	)
	(segment
		(start 417.006024 -142.6464)
		(end 417.525962 -143.166338)
		(width 0.10795)
		(layer "B.Cu")
		(net "PD_SATA1_CONTROLLER_TYPE_R")
	)
	(via
		(at 433.243482 -149.6822)
		(size 0.6604)
		(drill 0.3302)
		(layers "F.Cu" "B.Cu")
		(net "PD_SATA0_CONTROLLER_TYPE_R")
	)
	(segment
		(start 430.911 -148.7297)
		(end 430.911 -147.0279)
		(width 0.10795)
		(layer "B.Cu")
		(net "PD_SATA0_CONTROLLER_TYPE_R")
	)
	(segment
		(start 433.243482 -149.686518)
		(end 431.867818 -149.686518)
		(width 0.10795)
		(layer "B.Cu")
		(net "PD_SATA0_CONTROLLER_TYPE_R")
	)
	(segment
		(start 433.243482 -148.520658)
		(end 433.243482 -149.6822)
		(width 0.10795)
		(layer "B.Cu")
		(net "PD_SATA0_CONTROLLER_TYPE_R")
	)
	(segment
		(start 430.911 -147.0279)
		(end 429.525938 -145.642838)
		(width 0.10795)
		(layer "B.Cu")
		(net "PD_SATA0_CONTROLLER_TYPE_R")
	)
	(segment
		(start 433.243482 -149.6822)
		(end 433.243482 -149.686518)
		(width 0.10795)
		(layer "B.Cu")
		(net "PD_SATA0_CONTROLLER_TYPE_R")
	)
	(segment
		(start 431.867818 -149.686518)
		(end 430.911 -148.7297)
		(width 0.10795)
		(layer "B.Cu")
		(net "PD_SATA0_CONTROLLER_TYPE_R")
	)
	(segment
		(start 429.525938 -145.642838)
		(end 429.525938 -144.94002)
		(width 0.10795)
		(layer "B.Cu")
		(net "PD_SATA0_CONTROLLER_TYPE_R")
	)
	(segment
		(start 376.824748 -127.51054)
		(end 376.558048 -127.51054)
		(width 0.0889)
		(layer "F.Cu")
		(net "SATA6G_PCH_PCIE_UP_SATA_TXP<7>")
	)
	(segment
		(start 376.380248 -127.42164)
		(end 376.113548 -127.42164)
		(width 0.0889)
		(layer "F.Cu")
		(net "SATA6G_PCH_PCIE_UP_SATA_TXP<7>")
	)
	(segment
		(start 375.95175 -127.583438)
		(end 375.95175 -128.423162)
		(width 0.0889)
		(layer "F.Cu")
		(net "SATA6G_PCH_PCIE_UP_SATA_TXP<7>")
	)
	(segment
		(start 378.985018 -126.165102)
		(end 378.779786 -126.165102)
		(width 0.0889)
		(layer "F.Cu")
		(net "SATA6G_PCH_PCIE_UP_SATA_TXP<7>")
	)
	(segment
		(start 376.594116 -128.716278)
		(end 376.594116 -128.853184)
		(width 0.0889)
		(layer "F.Cu")
		(net "SATA6G_PCH_PCIE_UP_SATA_TXP<7>")
	)
	(segment
		(start 378.606812 -127.11938)
		(end 378.386594 -127.339598)
		(width 0.0889)
		(layer "F.Cu")
		(net "SATA6G_PCH_PCIE_UP_SATA_TXP<7>")
	)
	(segment
		(start 377.269248 -127.42164)
		(end 377.002548 -127.42164)
		(width 0.0889)
		(layer "F.Cu")
		(net "SATA6G_PCH_PCIE_UP_SATA_TXP<7>")
	)
	(segment
		(start 378.779786 -126.165102)
		(end 378.6886 -126.256288)
		(width 0.0889)
		(layer "F.Cu")
		(net "SATA6G_PCH_PCIE_UP_SATA_TXP<7>")
	)
	(segment
		(start 377.713748 -127.51054)
		(end 377.447048 -127.51054)
		(width 0.0889)
		(layer "F.Cu")
		(net "SATA6G_PCH_PCIE_UP_SATA_TXP<7>")
	)
	(segment
		(start 378.188728 -127.42164)
		(end 377.891548 -127.42164)
		(width 0.0889)
		(layer "F.Cu")
		(net "SATA6G_PCH_PCIE_UP_SATA_TXP<7>")
	)
	(segment
		(start 376.0724 -128.543812)
		(end 376.42165 -128.543812)
		(width 0.0889)
		(layer "F.Cu")
		(net "SATA6G_PCH_PCIE_UP_SATA_TXP<7>")
	)
	(segment
		(start 378.6886 -126.256288)
		(end 378.6886 -126.921768)
		(width 0.0889)
		(layer "F.Cu")
		(net "SATA6G_PCH_PCIE_UP_SATA_TXP<7>")
	)
	(via
		(at 407.922476 -146.939)
		(size 0.508)
		(drill 0.254)
		(layers "F.Cu" "B.Cu")
		(net "SATA6G_PCH_PCIE_UP_SATA_TXP<7>")
	)
	(via
		(at 376.42165 -129.02565)
		(size 0.508)
		(drill 0.254)
		(layers "F.Cu" "B.Cu")
		(net "SATA6G_PCH_PCIE_UP_SATA_TXP<7>")
	)
	(arc
		(start 376.469148 -127.46609)
		(mid 376.428792 -127.435669)
		(end 376.380248 -127.42164)
		(width 0.0889)
		(layer "F.Cu")
		(net "SATA6G_PCH_PCIE_UP_SATA_TXP<7>")
	)
	(arc
		(start 377.802648 -127.46609)
		(mid 377.762292 -127.496511)
		(end 377.713748 -127.51054)
		(width 0.0889)
		(layer "F.Cu")
		(net "SATA6G_PCH_PCIE_UP_SATA_TXP<7>")
	)
	(arc
		(start 376.558048 -127.51054)
		(mid 376.509522 -127.496475)
		(end 376.469148 -127.46609)
		(width 0.0889)
		(layer "F.Cu")
		(net "SATA6G_PCH_PCIE_UP_SATA_TXP<7>")
	)
	(arc
		(start 377.002548 -127.42164)
		(mid 376.954022 -127.435705)
		(end 376.913648 -127.46609)
		(width 0.0889)
		(layer "F.Cu")
		(net "SATA6G_PCH_PCIE_UP_SATA_TXP<7>")
	)
	(arc
		(start 376.113548 -127.42164)
		(mid 375.99914 -127.46903)
		(end 375.95175 -127.583438)
		(width 0.0889)
		(layer "F.Cu")
		(net "SATA6G_PCH_PCIE_UP_SATA_TXP<7>")
	)
	(arc
		(start 376.913648 -127.46609)
		(mid 376.873292 -127.496511)
		(end 376.824748 -127.51054)
		(width 0.0889)
		(layer "F.Cu")
		(net "SATA6G_PCH_PCIE_UP_SATA_TXP<7>")
	)
	(arc
		(start 375.95175 -128.423162)
		(mid 375.987088 -128.508474)
		(end 376.0724 -128.543812)
		(width 0.0889)
		(layer "F.Cu")
		(net "SATA6G_PCH_PCIE_UP_SATA_TXP<7>")
	)
	(arc
		(start 377.891548 -127.42164)
		(mid 377.843022 -127.435705)
		(end 377.802648 -127.46609)
		(width 0.0889)
		(layer "F.Cu")
		(net "SATA6G_PCH_PCIE_UP_SATA_TXP<7>")
	)
	(arc
		(start 376.594116 -128.853184)
		(mid 376.543602 -128.975136)
		(end 376.42165 -129.02565)
		(width 0.0889)
		(layer "F.Cu")
		(net "SATA6G_PCH_PCIE_UP_SATA_TXP<7>")
	)
	(arc
		(start 377.358148 -127.46609)
		(mid 377.317792 -127.435669)
		(end 377.269248 -127.42164)
		(width 0.0889)
		(layer "F.Cu")
		(net "SATA6G_PCH_PCIE_UP_SATA_TXP<7>")
	)
	(arc
		(start 376.42165 -128.543812)
		(mid 376.543602 -128.594326)
		(end 376.594116 -128.716278)
		(width 0.0889)
		(layer "F.Cu")
		(net "SATA6G_PCH_PCIE_UP_SATA_TXP<7>")
	)
	(arc
		(start 378.6886 -126.921768)
		(mid 378.667332 -127.02869)
		(end 378.606812 -127.11938)
		(width 0.0889)
		(layer "F.Cu")
		(net "SATA6G_PCH_PCIE_UP_SATA_TXP<7>")
	)
	(arc
		(start 378.386594 -127.339598)
		(mid 378.295841 -127.400364)
		(end 378.188728 -127.42164)
		(width 0.0889)
		(layer "F.Cu")
		(net "SATA6G_PCH_PCIE_UP_SATA_TXP<7>")
	)
	(arc
		(start 377.447048 -127.51054)
		(mid 377.398522 -127.496475)
		(end 377.358148 -127.46609)
		(width 0.0889)
		(layer "F.Cu")
		(net "SATA6G_PCH_PCIE_UP_SATA_TXP<7>")
	)
	(segment
		(start 408.7114 -146.939)
		(end 408.357578 -147.292822)
		(width 0.1143)
		(layer "B.Cu")
		(net "SATA6G_PCH_PCIE_UP_SATA_TXP<7>")
	)
	(segment
		(start 408.276806 -147.32635)
		(end 408.036776 -147.32635)
		(width 0.1143)
		(layer "B.Cu")
		(net "SATA6G_PCH_PCIE_UP_SATA_TXP<7>")
	)
	(segment
		(start 407.922476 -147.21205)
		(end 407.922476 -146.939)
		(width 0.1143)
		(layer "B.Cu")
		(net "SATA6G_PCH_PCIE_UP_SATA_TXP<7>")
	)
	(arc
		(start 408.357578 -147.292822)
		(mid 408.320519 -147.317584)
		(end 408.276806 -147.32635)
		(width 0.1143)
		(layer "B.Cu")
		(net "SATA6G_PCH_PCIE_UP_SATA_TXP<7>")
	)
	(arc
		(start 408.036776 -147.32635)
		(mid 407.955954 -147.292872)
		(end 407.922476 -147.21205)
		(width 0.1143)
		(layer "B.Cu")
		(net "SATA6G_PCH_PCIE_UP_SATA_TXP<7>")
	)
	(segment
		(start 400.449542 -146.980148)
		(end 402.091144 -146.980148)
		(width 0.1143)
		(layer "In2.Cu")
		(net "SATA6G_PCH_PCIE_UP_SATA_TXP<7>")
	)
	(segment
		(start 396.643098 -140.796518)
		(end 396.985998 -140.796518)
		(width 0.1143)
		(layer "In2.Cu")
		(net "SATA6G_PCH_PCIE_UP_SATA_TXP<7>")
	)
	(segment
		(start 397.316198 -140.961618)
		(end 398.006824 -140.961618)
		(width 0.1143)
		(layer "In2.Cu")
		(net "SATA6G_PCH_PCIE_UP_SATA_TXP<7>")
	)
	(segment
		(start 375.847356 -131.416044)
		(end 376.467116 -132.03555)
		(width 0.1143)
		(layer "In2.Cu")
		(net "SATA6G_PCH_PCIE_UP_SATA_TXP<7>")
	)
	(segment
		(start 399.50136 -146.243802)
		(end 400.087338 -146.82978)
		(width 0.1143)
		(layer "In2.Cu")
		(net "SATA6G_PCH_PCIE_UP_SATA_TXP<7>")
	)
	(segment
		(start 395.719808 -140.961618)
		(end 396.312898 -140.961618)
		(width 0.1143)
		(layer "In2.Cu")
		(net "SATA6G_PCH_PCIE_UP_SATA_TXP<7>")
	)
	(segment
		(start 378.0155 -133.002782)
		(end 378.0155 -134.712456)
		(width 0.1143)
		(layer "In2.Cu")
		(net "SATA6G_PCH_PCIE_UP_SATA_TXP<7>")
	)
	(segment
		(start 376.910854 -132.2197)
		(end 377.232418 -132.2197)
		(width 0.1143)
		(layer "In2.Cu")
		(net "SATA6G_PCH_PCIE_UP_SATA_TXP<7>")
	)
	(segment
		(start 376.1867 -129.307844)
		(end 376.1867 -129.7178)
		(width 0.1143)
		(layer "In2.Cu")
		(net "SATA6G_PCH_PCIE_UP_SATA_TXP<7>")
	)
	(segment
		(start 405.017732 -146.524726)
		(end 405.509476 -147.01647)
		(width 0.1143)
		(layer "In2.Cu")
		(net "SATA6G_PCH_PCIE_UP_SATA_TXP<7>")
	)
	(segment
		(start 394.114782 -140.961618)
		(end 394.716508 -140.961618)
		(width 0.1143)
		(layer "In2.Cu")
		(net "SATA6G_PCH_PCIE_UP_SATA_TXP<7>")
	)
	(segment
		(start 378.260864 -135.304276)
		(end 381.141732 -138.185144)
		(width 0.1143)
		(layer "In2.Cu")
		(net "SATA6G_PCH_PCIE_UP_SATA_TXP<7>")
	)
	(segment
		(start 376.047508 -130.054604)
		(end 375.999756 -130.102356)
		(width 0.1143)
		(layer "In2.Cu")
		(net "SATA6G_PCH_PCIE_UP_SATA_TXP<7>")
	)
	(segment
		(start 375.805954 -130.570224)
		(end 375.8057 -130.56997)
		(width 0.1143)
		(layer "In2.Cu")
		(net "SATA6G_PCH_PCIE_UP_SATA_TXP<7>")
	)
	(segment
		(start 383.924556 -139.459716)
		(end 383.924556 -138.381232)
		(width 0.1143)
		(layer "In2.Cu")
		(net "SATA6G_PCH_PCIE_UP_SATA_TXP<7>")
	)
	(segment
		(start 385.029456 -138.381232)
		(end 385.029456 -139.459716)
		(width 0.1143)
		(layer "In2.Cu")
		(net "SATA6G_PCH_PCIE_UP_SATA_TXP<7>")
	)
	(segment
		(start 376.42165 -129.02565)
		(end 376.220228 -129.227072)
		(width 0.1143)
		(layer "In2.Cu")
		(net "SATA6G_PCH_PCIE_UP_SATA_TXP<7>")
	)
	(segment
		(start 393.441682 -140.796518)
		(end 393.784582 -140.796518)
		(width 0.1143)
		(layer "In2.Cu")
		(net "SATA6G_PCH_PCIE_UP_SATA_TXP<7>")
	)
	(segment
		(start 385.289806 -139.720066)
		(end 385.632706 -139.720066)
		(width 0.1143)
		(layer "In2.Cu")
		(net "SATA6G_PCH_PCIE_UP_SATA_TXP<7>")
	)
	(segment
		(start 381.69088 -139.720066)
		(end 382.038606 -139.720066)
		(width 0.1143)
		(layer "In2.Cu")
		(net "SATA6G_PCH_PCIE_UP_SATA_TXP<7>")
	)
	(segment
		(start 375.8057 -130.56997)
		(end 375.8057 -131.315968)
		(width 0.1143)
		(layer "In2.Cu")
		(net "SATA6G_PCH_PCIE_UP_SATA_TXP<7>")
	)
	(segment
		(start 399.289016 -142.158466)
		(end 399.289016 -145.731738)
		(width 0.1143)
		(layer "In2.Cu")
		(net "SATA6G_PCH_PCIE_UP_SATA_TXP<7>")
	)
	(segment
		(start 403.066758 -146.35734)
		(end 404.61311 -146.35734)
		(width 0.1143)
		(layer "In2.Cu")
		(net "SATA6G_PCH_PCIE_UP_SATA_TXP<7>")
	)
	(segment
		(start 382.298956 -139.459716)
		(end 382.298956 -138.381232)
		(width 0.1143)
		(layer "In2.Cu")
		(net "SATA6G_PCH_PCIE_UP_SATA_TXP<7>")
	)
	(segment
		(start 385.962906 -139.554966)
		(end 386.305806 -139.554966)
		(width 0.1143)
		(layer "In2.Cu")
		(net "SATA6G_PCH_PCIE_UP_SATA_TXP<7>")
	)
	(segment
		(start 398.779746 -141.281404)
		(end 399.029428 -141.531086)
		(width 0.1143)
		(layer "In2.Cu")
		(net "SATA6G_PCH_PCIE_UP_SATA_TXP<7>")
	)
	(segment
		(start 407.594054 -147.267422)
		(end 407.922476 -146.939)
		(width 0.1143)
		(layer "In2.Cu")
		(net "SATA6G_PCH_PCIE_UP_SATA_TXP<7>")
	)
	(segment
		(start 402.28901 -146.897852)
		(end 402.662136 -146.524726)
		(width 0.1143)
		(layer "In2.Cu")
		(net "SATA6G_PCH_PCIE_UP_SATA_TXP<7>")
	)
	(segment
		(start 406.196292 -147.30095)
		(end 407.513282 -147.30095)
		(width 0.1143)
		(layer "In2.Cu")
		(net "SATA6G_PCH_PCIE_UP_SATA_TXP<7>")
	)
	(segment
		(start 395.046708 -140.796518)
		(end 395.389608 -140.796518)
		(width 0.1143)
		(layer "In2.Cu")
		(net "SATA6G_PCH_PCIE_UP_SATA_TXP<7>")
	)
	(segment
		(start 391.342626 -140.081254)
		(end 392.06297 -140.801598)
		(width 0.1143)
		(layer "In2.Cu")
		(net "SATA6G_PCH_PCIE_UP_SATA_TXP<7>")
	)
	(segment
		(start 383.403856 -138.381232)
		(end 383.403856 -139.459716)
		(width 0.1143)
		(layer "In2.Cu")
		(net "SATA6G_PCH_PCIE_UP_SATA_TXP<7>")
	)
	(segment
		(start 386.636006 -139.720066)
		(end 390.470136 -139.720066)
		(width 0.1143)
		(layer "In2.Cu")
		(net "SATA6G_PCH_PCIE_UP_SATA_TXP<7>")
	)
	(segment
		(start 392.448542 -140.961618)
		(end 393.111482 -140.961618)
		(width 0.1143)
		(layer "In2.Cu")
		(net "SATA6G_PCH_PCIE_UP_SATA_TXP<7>")
	)
	(segment
		(start 381.355346 -138.701272)
		(end 381.355346 -139.491974)
		(width 0.1143)
		(layer "In2.Cu")
		(net "SATA6G_PCH_PCIE_UP_SATA_TXP<7>")
	)
	(arc
		(start 402.662136 -146.524726)
		(mid 402.847779 -146.400713)
		(end 403.066758 -146.35734)
		(width 0.1143)
		(layer "In2.Cu")
		(net "SATA6G_PCH_PCIE_UP_SATA_TXP<7>")
	)
	(arc
		(start 376.1867 -129.7178)
		(mid 376.150565 -129.900024)
		(end 376.047508 -130.054604)
		(width 0.1143)
		(layer "In2.Cu")
		(net "SATA6G_PCH_PCIE_UP_SATA_TXP<7>")
	)
	(arc
		(start 381.141732 -138.185144)
		(mid 381.299797 -138.421988)
		(end 381.355346 -138.701272)
		(width 0.1143)
		(layer "In2.Cu")
		(net "SATA6G_PCH_PCIE_UP_SATA_TXP<7>")
	)
	(arc
		(start 404.61311 -146.35734)
		(mid 404.832047 -146.400814)
		(end 405.017732 -146.524726)
		(width 0.1143)
		(layer "In2.Cu")
		(net "SATA6G_PCH_PCIE_UP_SATA_TXP<7>")
	)
	(arc
		(start 381.355346 -139.491974)
		(mid 381.364779 -139.538743)
		(end 381.391414 -139.578334)
		(width 0.1143)
		(layer "In2.Cu")
		(net "SATA6G_PCH_PCIE_UP_SATA_TXP<7>")
	)
	(arc
		(start 398.006824 -140.961618)
		(mid 398.425067 -141.044682)
		(end 398.779746 -141.281404)
		(width 0.1143)
		(layer "In2.Cu")
		(net "SATA6G_PCH_PCIE_UP_SATA_TXP<7>")
	)
	(arc
		(start 383.403856 -139.459716)
		(mid 383.664206 -139.720066)
		(end 383.924556 -139.459716)
		(width 0.1143)
		(layer "In2.Cu")
		(net "SATA6G_PCH_PCIE_UP_SATA_TXP<7>")
	)
	(arc
		(start 382.298956 -138.381232)
		(mid 382.851406 -137.828782)
		(end 383.403856 -138.381232)
		(width 0.1143)
		(layer "In2.Cu")
		(net "SATA6G_PCH_PCIE_UP_SATA_TXP<7>")
	)
	(arc
		(start 393.111482 -140.961618)
		(mid 393.203279 -140.93885)
		(end 393.276582 -140.879068)
		(width 0.1143)
		(layer "In2.Cu")
		(net "SATA6G_PCH_PCIE_UP_SATA_TXP<7>")
	)
	(arc
		(start 395.389608 -140.796518)
		(mid 395.481405 -140.819286)
		(end 395.554708 -140.879068)
		(width 0.1143)
		(layer "In2.Cu")
		(net "SATA6G_PCH_PCIE_UP_SATA_TXP<7>")
	)
	(arc
		(start 383.924556 -138.381232)
		(mid 384.477006 -137.828782)
		(end 385.029456 -138.381232)
		(width 0.1143)
		(layer "In2.Cu")
		(net "SATA6G_PCH_PCIE_UP_SATA_TXP<7>")
	)
	(arc
		(start 375.8057 -131.315968)
		(mid 375.816519 -131.370178)
		(end 375.847356 -131.416044)
		(width 0.1143)
		(layer "In2.Cu")
		(net "SATA6G_PCH_PCIE_UP_SATA_TXP<7>")
	)
	(arc
		(start 386.470906 -139.637516)
		(mid 386.544187 -139.697342)
		(end 386.636006 -139.720066)
		(width 0.1143)
		(layer "In2.Cu")
		(net "SATA6G_PCH_PCIE_UP_SATA_TXP<7>")
	)
	(arc
		(start 405.509476 -147.01647)
		(mid 405.82459 -147.227022)
		(end 406.196292 -147.30095)
		(width 0.1143)
		(layer "In2.Cu")
		(net "SATA6G_PCH_PCIE_UP_SATA_TXP<7>")
	)
	(arc
		(start 390.470136 -139.720066)
		(mid 390.942284 -139.813906)
		(end 391.342626 -140.081254)
		(width 0.1143)
		(layer "In2.Cu")
		(net "SATA6G_PCH_PCIE_UP_SATA_TXP<7>")
	)
	(arc
		(start 397.151098 -140.879068)
		(mid 397.224379 -140.938894)
		(end 397.316198 -140.961618)
		(width 0.1143)
		(layer "In2.Cu")
		(net "SATA6G_PCH_PCIE_UP_SATA_TXP<7>")
	)
	(arc
		(start 402.091144 -146.980148)
		(mid 402.198275 -146.958709)
		(end 402.28901 -146.897852)
		(width 0.1143)
		(layer "In2.Cu")
		(net "SATA6G_PCH_PCIE_UP_SATA_TXP<7>")
	)
	(arc
		(start 393.949682 -140.879068)
		(mid 394.022963 -140.938894)
		(end 394.114782 -140.961618)
		(width 0.1143)
		(layer "In2.Cu")
		(net "SATA6G_PCH_PCIE_UP_SATA_TXP<7>")
	)
	(arc
		(start 376.467116 -132.03555)
		(mid 376.670661 -132.171774)
		(end 376.910854 -132.2197)
		(width 0.1143)
		(layer "In2.Cu")
		(net "SATA6G_PCH_PCIE_UP_SATA_TXP<7>")
	)
	(arc
		(start 394.881608 -140.879068)
		(mid 394.954889 -140.819242)
		(end 395.046708 -140.796518)
		(width 0.1143)
		(layer "In2.Cu")
		(net "SATA6G_PCH_PCIE_UP_SATA_TXP<7>")
	)
	(arc
		(start 407.513282 -147.30095)
		(mid 407.557023 -147.292249)
		(end 407.594054 -147.267422)
		(width 0.1143)
		(layer "In2.Cu")
		(net "SATA6G_PCH_PCIE_UP_SATA_TXP<7>")
	)
	(arc
		(start 385.632706 -139.720066)
		(mid 385.724503 -139.697298)
		(end 385.797806 -139.637516)
		(width 0.1143)
		(layer "In2.Cu")
		(net "SATA6G_PCH_PCIE_UP_SATA_TXP<7>")
	)
	(arc
		(start 378.0155 -134.712456)
		(mid 378.079257 -135.032804)
		(end 378.260864 -135.304276)
		(width 0.1143)
		(layer "In2.Cu")
		(net "SATA6G_PCH_PCIE_UP_SATA_TXP<7>")
	)
	(arc
		(start 376.220228 -129.227072)
		(mid 376.195466 -129.264131)
		(end 376.1867 -129.307844)
		(width 0.1143)
		(layer "In2.Cu")
		(net "SATA6G_PCH_PCIE_UP_SATA_TXP<7>")
	)
	(arc
		(start 399.289016 -145.731738)
		(mid 399.344256 -146.008889)
		(end 399.50136 -146.243802)
		(width 0.1143)
		(layer "In2.Cu")
		(net "SATA6G_PCH_PCIE_UP_SATA_TXP<7>")
	)
	(arc
		(start 393.276582 -140.879068)
		(mid 393.349863 -140.819242)
		(end 393.441682 -140.796518)
		(width 0.1143)
		(layer "In2.Cu")
		(net "SATA6G_PCH_PCIE_UP_SATA_TXP<7>")
	)
	(arc
		(start 396.477998 -140.879068)
		(mid 396.551279 -140.819242)
		(end 396.643098 -140.796518)
		(width 0.1143)
		(layer "In2.Cu")
		(net "SATA6G_PCH_PCIE_UP_SATA_TXP<7>")
	)
	(arc
		(start 394.716508 -140.961618)
		(mid 394.808305 -140.93885)
		(end 394.881608 -140.879068)
		(width 0.1143)
		(layer "In2.Cu")
		(net "SATA6G_PCH_PCIE_UP_SATA_TXP<7>")
	)
	(arc
		(start 395.554708 -140.879068)
		(mid 395.627989 -140.938894)
		(end 395.719808 -140.961618)
		(width 0.1143)
		(layer "In2.Cu")
		(net "SATA6G_PCH_PCIE_UP_SATA_TXP<7>")
	)
	(arc
		(start 392.06297 -140.801598)
		(mid 392.239843 -140.919937)
		(end 392.448542 -140.961618)
		(width 0.1143)
		(layer "In2.Cu")
		(net "SATA6G_PCH_PCIE_UP_SATA_TXP<7>")
	)
	(arc
		(start 382.038606 -139.720066)
		(mid 382.222701 -139.643811)
		(end 382.298956 -139.459716)
		(width 0.1143)
		(layer "In2.Cu")
		(net "SATA6G_PCH_PCIE_UP_SATA_TXP<7>")
	)
	(arc
		(start 400.087338 -146.82978)
		(mid 400.253489 -146.940955)
		(end 400.449542 -146.980148)
		(width 0.1143)
		(layer "In2.Cu")
		(net "SATA6G_PCH_PCIE_UP_SATA_TXP<7>")
	)
	(arc
		(start 381.391414 -139.578334)
		(mid 381.525056 -139.683193)
		(end 381.69088 -139.720066)
		(width 0.1143)
		(layer "In2.Cu")
		(net "SATA6G_PCH_PCIE_UP_SATA_TXP<7>")
	)
	(arc
		(start 385.029456 -139.459716)
		(mid 385.105711 -139.643811)
		(end 385.289806 -139.720066)
		(width 0.1143)
		(layer "In2.Cu")
		(net "SATA6G_PCH_PCIE_UP_SATA_TXP<7>")
	)
	(arc
		(start 393.784582 -140.796518)
		(mid 393.876379 -140.819286)
		(end 393.949682 -140.879068)
		(width 0.1143)
		(layer "In2.Cu")
		(net "SATA6G_PCH_PCIE_UP_SATA_TXP<7>")
	)
	(arc
		(start 396.985998 -140.796518)
		(mid 397.077795 -140.819286)
		(end 397.151098 -140.879068)
		(width 0.1143)
		(layer "In2.Cu")
		(net "SATA6G_PCH_PCIE_UP_SATA_TXP<7>")
	)
	(arc
		(start 377.232418 -132.2197)
		(mid 377.786141 -132.449059)
		(end 378.0155 -133.002782)
		(width 0.1143)
		(layer "In2.Cu")
		(net "SATA6G_PCH_PCIE_UP_SATA_TXP<7>")
	)
	(arc
		(start 399.029428 -141.531086)
		(mid 399.221677 -141.818945)
		(end 399.289016 -142.158466)
		(width 0.1143)
		(layer "In2.Cu")
		(net "SATA6G_PCH_PCIE_UP_SATA_TXP<7>")
	)
	(arc
		(start 375.999756 -130.102356)
		(mid 375.856325 -130.317016)
		(end 375.805954 -130.570224)
		(width 0.1143)
		(layer "In2.Cu")
		(net "SATA6G_PCH_PCIE_UP_SATA_TXP<7>")
	)
	(arc
		(start 385.797806 -139.637516)
		(mid 385.871087 -139.57769)
		(end 385.962906 -139.554966)
		(width 0.1143)
		(layer "In2.Cu")
		(net "SATA6G_PCH_PCIE_UP_SATA_TXP<7>")
	)
	(arc
		(start 396.312898 -140.961618)
		(mid 396.404695 -140.93885)
		(end 396.477998 -140.879068)
		(width 0.1143)
		(layer "In2.Cu")
		(net "SATA6G_PCH_PCIE_UP_SATA_TXP<7>")
	)
	(arc
		(start 386.305806 -139.554966)
		(mid 386.397603 -139.577734)
		(end 386.470906 -139.637516)
		(width 0.1143)
		(layer "In2.Cu")
		(net "SATA6G_PCH_PCIE_UP_SATA_TXP<7>")
	)
	(segment
		(start 377.556522 -128.128014)
		(end 377.556522 -128.488186)
		(width 0.0889)
		(layer "F.Cu")
		(net "SATA6G_PCH_PCIE_UP_SATA_TXP<6>")
	)
	(segment
		(start 378.29363 -128.691386)
		(end 378.29363 -128.9431)
		(width 0.0889)
		(layer "F.Cu")
		(net "SATA6G_PCH_PCIE_UP_SATA_TXP<6>")
	)
	(segment
		(start 379.25629 -126.65837)
		(end 379.25629 -126.9873)
		(width 0.0889)
		(layer "F.Cu")
		(net "SATA6G_PCH_PCIE_UP_SATA_TXP<6>")
	)
	(segment
		(start 379.48489 -125.750066)
		(end 379.461776 -125.77318)
		(width 0.0889)
		(layer "F.Cu")
		(net "SATA6G_PCH_PCIE_UP_SATA_TXP<6>")
	)
	(segment
		(start 378.968 -127.517144)
		(end 378.779532 -127.705612)
		(width 0.0889)
		(layer "F.Cu")
		(net "SATA6G_PCH_PCIE_UP_SATA_TXP<6>")
	)
	(segment
		(start 377.670822 -128.602486)
		(end 378.20473 -128.602486)
		(width 0.0889)
		(layer "F.Cu")
		(net "SATA6G_PCH_PCIE_UP_SATA_TXP<6>")
	)
	(segment
		(start 379.174248 -127.185166)
		(end 379.030992 -127.328422)
		(width 0.0889)
		(layer "F.Cu")
		(net "SATA6G_PCH_PCIE_UP_SATA_TXP<6>")
	)
	(segment
		(start 379.461776 -126.416054)
		(end 379.282452 -126.595378)
		(width 0.0889)
		(layer "F.Cu")
		(net "SATA6G_PCH_PCIE_UP_SATA_TXP<6>")
	)
	(segment
		(start 379.461776 -125.77318)
		(end 379.461776 -126.416054)
		(width 0.0889)
		(layer "F.Cu")
		(net "SATA6G_PCH_PCIE_UP_SATA_TXP<6>")
	)
	(segment
		(start 378.204476 -128.039114)
		(end 377.645422 -128.039114)
		(width 0.0889)
		(layer "F.Cu")
		(net "SATA6G_PCH_PCIE_UP_SATA_TXP<6>")
	)
	(segment
		(start 378.59081 -127.768604)
		(end 378.402342 -127.957072)
		(width 0.0889)
		(layer "F.Cu")
		(net "SATA6G_PCH_PCIE_UP_SATA_TXP<6>")
	)
	(segment
		(start 378.20473 -129.032)
		(end 378.026422 -129.032)
		(width 0.0889)
		(layer "F.Cu")
		(net "SATA6G_PCH_PCIE_UP_SATA_TXP<6>")
	)
	(via
		(at 408.313382 -141.641576)
		(size 0.508)
		(drill 0.254)
		(layers "F.Cu" "B.Cu")
		(net "SATA6G_PCH_PCIE_UP_SATA_TXP<6>")
	)
	(via
		(at 378.026422 -129.032)
		(size 0.508)
		(drill 0.254)
		(layers "F.Cu" "B.Cu")
		(net "SATA6G_PCH_PCIE_UP_SATA_TXP<6>")
	)
	(arc
		(start 378.779532 -127.705612)
		(mid 378.735301 -127.729964)
		(end 378.685298 -127.737108)
		(width 0.0889)
		(layer "F.Cu")
		(net "SATA6G_PCH_PCIE_UP_SATA_TXP<6>")
	)
	(arc
		(start 379.030992 -127.328422)
		(mid 379.00664 -127.372653)
		(end 378.999496 -127.422656)
		(width 0.0889)
		(layer "F.Cu")
		(net "SATA6G_PCH_PCIE_UP_SATA_TXP<6>")
	)
	(arc
		(start 379.25629 -126.9873)
		(mid 379.234968 -127.094402)
		(end 379.174248 -127.185166)
		(width 0.0889)
		(layer "F.Cu")
		(net "SATA6G_PCH_PCIE_UP_SATA_TXP<6>")
	)
	(arc
		(start 379.282452 -126.595378)
		(mid 379.263087 -126.624265)
		(end 379.25629 -126.65837)
		(width 0.0889)
		(layer "F.Cu")
		(net "SATA6G_PCH_PCIE_UP_SATA_TXP<6>")
	)
	(arc
		(start 378.20473 -128.602486)
		(mid 378.267592 -128.628524)
		(end 378.29363 -128.691386)
		(width 0.0889)
		(layer "F.Cu")
		(net "SATA6G_PCH_PCIE_UP_SATA_TXP<6>")
	)
	(arc
		(start 378.402342 -127.957072)
		(mid 378.311575 -128.017784)
		(end 378.204476 -128.039114)
		(width 0.0889)
		(layer "F.Cu")
		(net "SATA6G_PCH_PCIE_UP_SATA_TXP<6>")
	)
	(arc
		(start 378.685298 -127.737108)
		(mid 378.635134 -127.744114)
		(end 378.59081 -127.768604)
		(width 0.0889)
		(layer "F.Cu")
		(net "SATA6G_PCH_PCIE_UP_SATA_TXP<6>")
	)
	(arc
		(start 377.645422 -128.039114)
		(mid 377.58256 -128.065152)
		(end 377.556522 -128.128014)
		(width 0.0889)
		(layer "F.Cu")
		(net "SATA6G_PCH_PCIE_UP_SATA_TXP<6>")
	)
	(arc
		(start 378.29363 -128.9431)
		(mid 378.267592 -129.005962)
		(end 378.20473 -129.032)
		(width 0.0889)
		(layer "F.Cu")
		(net "SATA6G_PCH_PCIE_UP_SATA_TXP<6>")
	)
	(arc
		(start 378.999496 -127.422656)
		(mid 378.99249 -127.47282)
		(end 378.968 -127.517144)
		(width 0.0889)
		(layer "F.Cu")
		(net "SATA6G_PCH_PCIE_UP_SATA_TXP<6>")
	)
	(arc
		(start 377.556522 -128.488186)
		(mid 377.59 -128.569008)
		(end 377.670822 -128.602486)
		(width 0.0889)
		(layer "F.Cu")
		(net "SATA6G_PCH_PCIE_UP_SATA_TXP<6>")
	)
	(segment
		(start 408.313382 -141.641576)
		(end 408.313382 -141.765274)
		(width 0.1143)
		(layer "B.Cu")
		(net "SATA6G_PCH_PCIE_UP_SATA_TXP<6>")
	)
	(segment
		(start 409.605988 -141.476222)
		(end 409.707334 -141.476222)
		(width 0.1143)
		(layer "B.Cu")
		(net "SATA6G_PCH_PCIE_UP_SATA_TXP<6>")
	)
	(segment
		(start 408.427682 -141.879574)
		(end 409.007564 -141.879574)
		(width 0.1143)
		(layer "B.Cu")
		(net "SATA6G_PCH_PCIE_UP_SATA_TXP<6>")
	)
	(segment
		(start 409.788106 -141.442694)
		(end 410.21 -141.0208)
		(width 0.1143)
		(layer "B.Cu")
		(net "SATA6G_PCH_PCIE_UP_SATA_TXP<6>")
	)
	(segment
		(start 409.08859 -141.845792)
		(end 409.354274 -141.580362)
		(width 0.1143)
		(layer "B.Cu")
		(net "SATA6G_PCH_PCIE_UP_SATA_TXP<6>")
	)
	(arc
		(start 409.007564 -141.879574)
		(mid 409.051445 -141.870752)
		(end 409.08859 -141.845792)
		(width 0.1143)
		(layer "B.Cu")
		(net "SATA6G_PCH_PCIE_UP_SATA_TXP<6>")
	)
	(arc
		(start 408.313382 -141.765274)
		(mid 408.34686 -141.846096)
		(end 408.427682 -141.879574)
		(width 0.1143)
		(layer "B.Cu")
		(net "SATA6G_PCH_PCIE_UP_SATA_TXP<6>")
	)
	(arc
		(start 409.707334 -141.476222)
		(mid 409.751075 -141.467521)
		(end 409.788106 -141.442694)
		(width 0.1143)
		(layer "B.Cu")
		(net "SATA6G_PCH_PCIE_UP_SATA_TXP<6>")
	)
	(arc
		(start 409.354274 -141.580362)
		(mid 409.46979 -141.503303)
		(end 409.605988 -141.476222)
		(width 0.1143)
		(layer "B.Cu")
		(net "SATA6G_PCH_PCIE_UP_SATA_TXP<6>")
	)
	(segment
		(start 377.74118 -129.798318)
		(end 377.74118 -129.415286)
		(width 0.1143)
		(layer "In2.Cu")
		(net "SATA6G_PCH_PCIE_UP_SATA_TXP<6>")
	)
	(segment
		(start 379.240542 -129.196084)
		(end 378.294138 -130.142488)
		(width 0.1143)
		(layer "In2.Cu")
		(net "SATA6G_PCH_PCIE_UP_SATA_TXP<6>")
	)
	(segment
		(start 391.870184 -137.96264)
		(end 391.527284 -137.96264)
		(width 0.1143)
		(layer "In2.Cu")
		(net "SATA6G_PCH_PCIE_UP_SATA_TXP<6>")
	)
	(segment
		(start 381.93472 -136.249918)
		(end 381.737616 -136.249918)
		(width 0.1143)
		(layer "In2.Cu")
		(net "SATA6G_PCH_PCIE_UP_SATA_TXP<6>")
	)
	(segment
		(start 402.55571 -144.231614)
		(end 402.55571 -141.587728)
		(width 0.1143)
		(layer "In2.Cu")
		(net "SATA6G_PCH_PCIE_UP_SATA_TXP<6>")
	)
	(segment
		(start 393.507722 -137.96264)
		(end 393.164822 -137.96264)
		(width 0.1143)
		(layer "In2.Cu")
		(net "SATA6G_PCH_PCIE_UP_SATA_TXP<6>")
	)
	(segment
		(start 400.474942 -140.338302)
		(end 400.762724 -140.05052)
		(width 0.1143)
		(layer "In2.Cu")
		(net "SATA6G_PCH_PCIE_UP_SATA_TXP<6>")
	)
	(segment
		(start 379.353064 -130.628898)
		(end 379.798326 -130.183128)
		(width 0.1143)
		(layer "In2.Cu")
		(net "SATA6G_PCH_PCIE_UP_SATA_TXP<6>")
	)
	(segment
		(start 386.829808 -137.14222)
		(end 386.587238 -136.89965)
		(width 0.1143)
		(layer "In2.Cu")
		(net "SATA6G_PCH_PCIE_UP_SATA_TXP<6>")
	)
	(segment
		(start 404.734268 -142.585948)
		(end 404.734268 -144.431766)
		(width 0.1143)
		(layer "In2.Cu")
		(net "SATA6G_PCH_PCIE_UP_SATA_TXP<6>")
	)
	(segment
		(start 391.197084 -138.12774)
		(end 387.900164 -138.12774)
		(width 0.1143)
		(layer "In2.Cu")
		(net "SATA6G_PCH_PCIE_UP_SATA_TXP<6>")
	)
	(segment
		(start 402.769324 -144.622774)
		(end 402.681694 -144.535144)
		(width 0.1143)
		(layer "In2.Cu")
		(net "SATA6G_PCH_PCIE_UP_SATA_TXP<6>")
	)
	(segment
		(start 384.781044 -135.261858)
		(end 384.601974 -135.261858)
		(width 0.1143)
		(layer "In2.Cu")
		(net "SATA6G_PCH_PCIE_UP_SATA_TXP<6>")
	)
	(segment
		(start 404.920958 -142.135098)
		(end 404.92045 -142.135606)
		(width 0.1143)
		(layer "In2.Cu")
		(net "SATA6G_PCH_PCIE_UP_SATA_TXP<6>")
	)
	(segment
		(start 400.475704 -140.706856)
		(end 400.474942 -140.706094)
		(width 0.1143)
		(layer "In2.Cu")
		(net "SATA6G_PCH_PCIE_UP_SATA_TXP<6>")
	)
	(segment
		(start 383.644648 -136.042908)
		(end 383.644648 -135.833358)
		(width 0.1143)
		(layer "In2.Cu")
		(net "SATA6G_PCH_PCIE_UP_SATA_TXP<6>")
	)
	(segment
		(start 378.025406 -129.032)
		(end 378.026422 -129.032)
		(width 0.1143)
		(layer "In2.Cu")
		(net "SATA6G_PCH_PCIE_UP_SATA_TXP<6>")
	)
	(segment
		(start 400.762724 -139.268708)
		(end 399.802604 -138.308588)
		(width 0.1143)
		(layer "In2.Cu")
		(net "SATA6G_PCH_PCIE_UP_SATA_TXP<6>")
	)
	(segment
		(start 377.811284 -129.246122)
		(end 378.025406 -129.032)
		(width 0.1143)
		(layer "In2.Cu")
		(net "SATA6G_PCH_PCIE_UP_SATA_TXP<6>")
	)
	(segment
		(start 408.313382 -141.641576)
		(end 408.03703 -141.917928)
		(width 0.1143)
		(layer "In2.Cu")
		(net "SATA6G_PCH_PCIE_UP_SATA_TXP<6>")
	)
	(segment
		(start 383.073148 -135.261858)
		(end 382.819148 -135.261858)
		(width 0.1143)
		(layer "In2.Cu")
		(net "SATA6G_PCH_PCIE_UP_SATA_TXP<6>")
	)
	(segment
		(start 387.422644 -137.50163)
		(end 387.180074 -137.25906)
		(width 0.1143)
		(layer "In2.Cu")
		(net "SATA6G_PCH_PCIE_UP_SATA_TXP<6>")
	)
	(segment
		(start 381.53975 -136.167622)
		(end 381.485902 -136.113774)
		(width 0.1143)
		(layer "In2.Cu")
		(net "SATA6G_PCH_PCIE_UP_SATA_TXP<6>")
	)
	(segment
		(start 382.150112 -136.146286)
		(end 382.125474 -136.170924)
		(width 0.1143)
		(layer "In2.Cu")
		(net "SATA6G_PCH_PCIE_UP_SATA_TXP<6>")
	)
	(segment
		(start 381.403606 -135.915908)
		(end 381.403606 -135.403082)
		(width 0.1143)
		(layer "In2.Cu")
		(net "SATA6G_PCH_PCIE_UP_SATA_TXP<6>")
	)
	(segment
		(start 399.365216 -138.12774)
		(end 393.837922 -138.12774)
		(width 0.1143)
		(layer "In2.Cu")
		(net "SATA6G_PCH_PCIE_UP_SATA_TXP<6>")
	)
	(segment
		(start 385.877816 -136.190228)
		(end 385.068572 -135.380984)
		(width 0.1143)
		(layer "In2.Cu")
		(net "SATA6G_PCH_PCIE_UP_SATA_TXP<6>")
	)
	(segment
		(start 379.9967 -131.660646)
		(end 379.353318 -131.017264)
		(width 0.1143)
		(layer "In2.Cu")
		(net "SATA6G_PCH_PCIE_UP_SATA_TXP<6>")
	)
	(segment
		(start 402.184108 -140.689838)
		(end 401.926552 -140.432282)
		(width 0.1143)
		(layer "In2.Cu")
		(net "SATA6G_PCH_PCIE_UP_SATA_TXP<6>")
	)
	(segment
		(start 383.904998 -136.240012)
		(end 383.841752 -136.240012)
		(width 0.1143)
		(layer "In2.Cu")
		(net "SATA6G_PCH_PCIE_UP_SATA_TXP<6>")
	)
	(segment
		(start 378.008642 -130.142488)
		(end 377.796044 -129.92989)
		(width 0.1143)
		(layer "In2.Cu")
		(net "SATA6G_PCH_PCIE_UP_SATA_TXP<6>")
	)
	(segment
		(start 381.009652 -134.451598)
		(end 380.418848 -133.860794)
		(width 0.1143)
		(layer "In2.Cu")
		(net "SATA6G_PCH_PCIE_UP_SATA_TXP<6>")
	)
	(segment
		(start 392.834622 -138.12774)
		(end 392.200384 -138.12774)
		(width 0.1143)
		(layer "In2.Cu")
		(net "SATA6G_PCH_PCIE_UP_SATA_TXP<6>")
	)
	(segment
		(start 382.414526 -135.429244)
		(end 382.392174 -135.451596)
		(width 0.1143)
		(layer "In2.Cu")
		(net "SATA6G_PCH_PCIE_UP_SATA_TXP<6>")
	)
	(segment
		(start 384.165348 -135.698484)
		(end 384.165348 -135.979662)
		(width 0.1143)
		(layer "In2.Cu")
		(net "SATA6G_PCH_PCIE_UP_SATA_TXP<6>")
	)
	(segment
		(start 387.754876 -138.067288)
		(end 387.53923 -137.851642)
		(width 0.1143)
		(layer "In2.Cu")
		(net "SATA6G_PCH_PCIE_UP_SATA_TXP<6>")
	)
	(segment
		(start 407.956258 -141.951456)
		(end 405.364188 -141.951456)
		(width 0.1143)
		(layer "In2.Cu")
		(net "SATA6G_PCH_PCIE_UP_SATA_TXP<6>")
	)
	(segment
		(start 401.117816 -140.432282)
		(end 400.843242 -140.706856)
		(width 0.1143)
		(layer "In2.Cu")
		(net "SATA6G_PCH_PCIE_UP_SATA_TXP<6>")
	)
	(segment
		(start 382.224788 -135.856218)
		(end 382.224788 -135.966708)
		(width 0.1143)
		(layer "In2.Cu")
		(net "SATA6G_PCH_PCIE_UP_SATA_TXP<6>")
	)
	(segment
		(start 404.409402 -144.756632)
		(end 403.09165 -144.756632)
		(width 0.1143)
		(layer "In2.Cu")
		(net "SATA6G_PCH_PCIE_UP_SATA_TXP<6>")
	)
	(segment
		(start 380.238 -133.424168)
		(end 380.238 -132.243322)
		(width 0.1143)
		(layer "In2.Cu")
		(net "SATA6G_PCH_PCIE_UP_SATA_TXP<6>")
	)
	(segment
		(start 386.470652 -136.549638)
		(end 386.228082 -136.307068)
		(width 0.1143)
		(layer "In2.Cu")
		(net "SATA6G_PCH_PCIE_UP_SATA_TXP<6>")
	)
	(arc
		(start 392.035284 -138.04519)
		(mid 391.962003 -137.985364)
		(end 391.870184 -137.96264)
		(width 0.1143)
		(layer "In2.Cu")
		(net "SATA6G_PCH_PCIE_UP_SATA_TXP<6>")
	)
	(arc
		(start 384.165348 -135.979662)
		(mid 384.089093 -136.163757)
		(end 383.904998 -136.240012)
		(width 0.1143)
		(layer "In2.Cu")
		(net "SATA6G_PCH_PCIE_UP_SATA_TXP<6>")
	)
	(arc
		(start 401.926552 -140.432282)
		(mid 401.522184 -140.264787)
		(end 401.117816 -140.432282)
		(width 0.1143)
		(layer "In2.Cu")
		(net "SATA6G_PCH_PCIE_UP_SATA_TXP<6>")
	)
	(arc
		(start 400.762724 -140.05052)
		(mid 400.924643 -139.659614)
		(end 400.762724 -139.268708)
		(width 0.1143)
		(layer "In2.Cu")
		(net "SATA6G_PCH_PCIE_UP_SATA_TXP<6>")
	)
	(arc
		(start 393.837922 -138.12774)
		(mid 393.746125 -138.104972)
		(end 393.672822 -138.04519)
		(width 0.1143)
		(layer "In2.Cu")
		(net "SATA6G_PCH_PCIE_UP_SATA_TXP<6>")
	)
	(arc
		(start 392.200384 -138.12774)
		(mid 392.108587 -138.104972)
		(end 392.035284 -138.04519)
		(width 0.1143)
		(layer "In2.Cu")
		(net "SATA6G_PCH_PCIE_UP_SATA_TXP<6>")
	)
	(arc
		(start 379.353318 -131.017264)
		(mid 379.272832 -130.823134)
		(end 379.353064 -130.628898)
		(width 0.1143)
		(layer "In2.Cu")
		(net "SATA6G_PCH_PCIE_UP_SATA_TXP<6>")
	)
	(arc
		(start 402.681694 -144.535144)
		(mid 402.58856 -144.395898)
		(end 402.55571 -144.231614)
		(width 0.1143)
		(layer "In2.Cu")
		(net "SATA6G_PCH_PCIE_UP_SATA_TXP<6>")
	)
	(arc
		(start 384.601974 -135.261858)
		(mid 384.293233 -135.389743)
		(end 384.165348 -135.698484)
		(width 0.1143)
		(layer "In2.Cu")
		(net "SATA6G_PCH_PCIE_UP_SATA_TXP<6>")
	)
	(arc
		(start 377.796044 -129.92989)
		(mid 377.755518 -129.869568)
		(end 377.74118 -129.798318)
		(width 0.1143)
		(layer "In2.Cu")
		(net "SATA6G_PCH_PCIE_UP_SATA_TXP<6>")
	)
	(arc
		(start 380.238 -132.243322)
		(mid 380.175279 -131.928)
		(end 379.9967 -131.660646)
		(width 0.1143)
		(layer "In2.Cu")
		(net "SATA6G_PCH_PCIE_UP_SATA_TXP<6>")
	)
	(arc
		(start 380.065534 -129.537714)
		(mid 379.76722 -129.091346)
		(end 379.240542 -129.196084)
		(width 0.1143)
		(layer "In2.Cu")
		(net "SATA6G_PCH_PCIE_UP_SATA_TXP<6>")
	)
	(arc
		(start 393.164822 -137.96264)
		(mid 393.073025 -137.985408)
		(end 392.999722 -138.04519)
		(width 0.1143)
		(layer "In2.Cu")
		(net "SATA6G_PCH_PCIE_UP_SATA_TXP<6>")
	)
	(arc
		(start 381.403606 -135.403082)
		(mid 381.301327 -134.888126)
		(end 381.009652 -134.451598)
		(width 0.1143)
		(layer "In2.Cu")
		(net "SATA6G_PCH_PCIE_UP_SATA_TXP<6>")
	)
	(arc
		(start 386.529072 -136.724644)
		(mid 386.519482 -136.630595)
		(end 386.470652 -136.549638)
		(width 0.1143)
		(layer "In2.Cu")
		(net "SATA6G_PCH_PCIE_UP_SATA_TXP<6>")
	)
	(arc
		(start 382.224788 -135.966708)
		(mid 382.205306 -136.06391)
		(end 382.150112 -136.146286)
		(width 0.1143)
		(layer "In2.Cu")
		(net "SATA6G_PCH_PCIE_UP_SATA_TXP<6>")
	)
	(arc
		(start 391.527284 -137.96264)
		(mid 391.435487 -137.985408)
		(end 391.362184 -138.04519)
		(width 0.1143)
		(layer "In2.Cu")
		(net "SATA6G_PCH_PCIE_UP_SATA_TXP<6>")
	)
	(arc
		(start 380.418848 -133.860794)
		(mid 380.284995 -133.660468)
		(end 380.238 -133.424168)
		(width 0.1143)
		(layer "In2.Cu")
		(net "SATA6G_PCH_PCIE_UP_SATA_TXP<6>")
	)
	(arc
		(start 382.392174 -135.451596)
		(mid 382.268161 -135.637239)
		(end 382.224788 -135.856218)
		(width 0.1143)
		(layer "In2.Cu")
		(net "SATA6G_PCH_PCIE_UP_SATA_TXP<6>")
	)
	(arc
		(start 386.228082 -136.307068)
		(mid 386.147135 -136.258209)
		(end 386.053076 -136.248648)
		(width 0.1143)
		(layer "In2.Cu")
		(net "SATA6G_PCH_PCIE_UP_SATA_TXP<6>")
	)
	(arc
		(start 383.841752 -136.240012)
		(mid 383.702378 -136.182282)
		(end 383.644648 -136.042908)
		(width 0.1143)
		(layer "In2.Cu")
		(net "SATA6G_PCH_PCIE_UP_SATA_TXP<6>")
	)
	(arc
		(start 400.843242 -140.706856)
		(mid 400.65951 -140.782849)
		(end 400.475704 -140.706856)
		(width 0.1143)
		(layer "In2.Cu")
		(net "SATA6G_PCH_PCIE_UP_SATA_TXP<6>")
	)
	(arc
		(start 408.03703 -141.917928)
		(mid 407.999971 -141.94269)
		(end 407.956258 -141.951456)
		(width 0.1143)
		(layer "In2.Cu")
		(net "SATA6G_PCH_PCIE_UP_SATA_TXP<6>")
	)
	(arc
		(start 387.005068 -137.20064)
		(mid 386.910875 -137.191119)
		(end 386.829808 -137.14222)
		(width 0.1143)
		(layer "In2.Cu")
		(net "SATA6G_PCH_PCIE_UP_SATA_TXP<6>")
	)
	(arc
		(start 379.798326 -130.183128)
		(mid 379.996025 -129.886967)
		(end 380.065534 -129.537714)
		(width 0.1143)
		(layer "In2.Cu")
		(net "SATA6G_PCH_PCIE_UP_SATA_TXP<6>")
	)
	(arc
		(start 386.053076 -136.248648)
		(mid 385.958883 -136.239127)
		(end 385.877816 -136.190228)
		(width 0.1143)
		(layer "In2.Cu")
		(net "SATA6G_PCH_PCIE_UP_SATA_TXP<6>")
	)
	(arc
		(start 387.53923 -137.851642)
		(mid 387.490521 -137.770661)
		(end 387.481064 -137.676636)
		(width 0.1143)
		(layer "In2.Cu")
		(net "SATA6G_PCH_PCIE_UP_SATA_TXP<6>")
	)
	(arc
		(start 391.362184 -138.04519)
		(mid 391.288903 -138.105016)
		(end 391.197084 -138.12774)
		(width 0.1143)
		(layer "In2.Cu")
		(net "SATA6G_PCH_PCIE_UP_SATA_TXP<6>")
	)
	(arc
		(start 393.672822 -138.04519)
		(mid 393.599541 -137.985364)
		(end 393.507722 -137.96264)
		(width 0.1143)
		(layer "In2.Cu")
		(net "SATA6G_PCH_PCIE_UP_SATA_TXP<6>")
	)
	(arc
		(start 399.802604 -138.308588)
		(mid 399.601899 -138.174638)
		(end 399.365216 -138.12774)
		(width 0.1143)
		(layer "In2.Cu")
		(net "SATA6G_PCH_PCIE_UP_SATA_TXP<6>")
	)
	(arc
		(start 387.900164 -138.12774)
		(mid 387.821484 -138.111996)
		(end 387.754876 -138.067288)
		(width 0.1143)
		(layer "In2.Cu")
		(net "SATA6G_PCH_PCIE_UP_SATA_TXP<6>")
	)
	(arc
		(start 383.644648 -135.833358)
		(mid 383.47726 -135.429246)
		(end 383.073148 -135.261858)
		(width 0.1143)
		(layer "In2.Cu")
		(net "SATA6G_PCH_PCIE_UP_SATA_TXP<6>")
	)
	(arc
		(start 382.819148 -135.261858)
		(mid 382.600211 -135.305332)
		(end 382.414526 -135.429244)
		(width 0.1143)
		(layer "In2.Cu")
		(net "SATA6G_PCH_PCIE_UP_SATA_TXP<6>")
	)
	(arc
		(start 404.734268 -144.431766)
		(mid 404.639117 -144.661481)
		(end 404.409402 -144.756632)
		(width 0.1143)
		(layer "In2.Cu")
		(net "SATA6G_PCH_PCIE_UP_SATA_TXP<6>")
	)
	(arc
		(start 386.587238 -136.89965)
		(mid 386.538529 -136.818669)
		(end 386.529072 -136.724644)
		(width 0.1143)
		(layer "In2.Cu")
		(net "SATA6G_PCH_PCIE_UP_SATA_TXP<6>")
	)
	(arc
		(start 405.364188 -141.951456)
		(mid 405.124309 -141.999189)
		(end 404.920958 -142.135098)
		(width 0.1143)
		(layer "In2.Cu")
		(net "SATA6G_PCH_PCIE_UP_SATA_TXP<6>")
	)
	(arc
		(start 387.481064 -137.676636)
		(mid 387.471474 -137.582587)
		(end 387.422644 -137.50163)
		(width 0.1143)
		(layer "In2.Cu")
		(net "SATA6G_PCH_PCIE_UP_SATA_TXP<6>")
	)
	(arc
		(start 378.294138 -130.142488)
		(mid 378.15139 -130.201616)
		(end 378.008642 -130.142488)
		(width 0.1143)
		(layer "In2.Cu")
		(net "SATA6G_PCH_PCIE_UP_SATA_TXP<6>")
	)
	(arc
		(start 377.74118 -129.415286)
		(mid 377.759446 -129.323747)
		(end 377.811284 -129.246122)
		(width 0.1143)
		(layer "In2.Cu")
		(net "SATA6G_PCH_PCIE_UP_SATA_TXP<6>")
	)
	(arc
		(start 381.737616 -136.249918)
		(mid 381.630485 -136.228479)
		(end 381.53975 -136.167622)
		(width 0.1143)
		(layer "In2.Cu")
		(net "SATA6G_PCH_PCIE_UP_SATA_TXP<6>")
	)
	(arc
		(start 385.068572 -135.380984)
		(mid 384.936667 -135.292785)
		(end 384.781044 -135.261858)
		(width 0.1143)
		(layer "In2.Cu")
		(net "SATA6G_PCH_PCIE_UP_SATA_TXP<6>")
	)
	(arc
		(start 387.180074 -137.25906)
		(mid 387.099127 -137.210201)
		(end 387.005068 -137.20064)
		(width 0.1143)
		(layer "In2.Cu")
		(net "SATA6G_PCH_PCIE_UP_SATA_TXP<6>")
	)
	(arc
		(start 400.474942 -140.706094)
		(mid 400.39877 -140.522198)
		(end 400.474942 -140.338302)
		(width 0.1143)
		(layer "In2.Cu")
		(net "SATA6G_PCH_PCIE_UP_SATA_TXP<6>")
	)
	(arc
		(start 382.125474 -136.170924)
		(mid 382.037956 -136.229431)
		(end 381.93472 -136.249918)
		(width 0.1143)
		(layer "In2.Cu")
		(net "SATA6G_PCH_PCIE_UP_SATA_TXP<6>")
	)
	(arc
		(start 392.999722 -138.04519)
		(mid 392.926441 -138.105016)
		(end 392.834622 -138.12774)
		(width 0.1143)
		(layer "In2.Cu")
		(net "SATA6G_PCH_PCIE_UP_SATA_TXP<6>")
	)
	(arc
		(start 404.92045 -142.135606)
		(mid 404.782528 -142.342254)
		(end 404.734268 -142.585948)
		(width 0.1143)
		(layer "In2.Cu")
		(net "SATA6G_PCH_PCIE_UP_SATA_TXP<6>")
	)
	(arc
		(start 403.09165 -144.756632)
		(mid 402.917144 -144.721809)
		(end 402.769324 -144.622774)
		(width 0.1143)
		(layer "In2.Cu")
		(net "SATA6G_PCH_PCIE_UP_SATA_TXP<6>")
	)
	(arc
		(start 402.55571 -141.587728)
		(mid 402.459174 -141.101847)
		(end 402.184108 -140.689838)
		(width 0.1143)
		(layer "In2.Cu")
		(net "SATA6G_PCH_PCIE_UP_SATA_TXP<6>")
	)
	(arc
		(start 381.485902 -136.113774)
		(mid 381.425053 -136.023036)
		(end 381.403606 -135.915908)
		(width 0.1143)
		(layer "In2.Cu")
		(net "SATA6G_PCH_PCIE_UP_SATA_TXP<6>")
	)
	(segment
		(start 379.985016 -126.165102)
		(end 379.889766 -126.260352)
		(width 0.0889)
		(layer "F.Cu")
		(net "SATA6G_PCH_PCIE_UP_SATA_TXP<5>")
	)
	(segment
		(start 379.249686 -132.08)
		(end 379.1458 -132.08)
		(width 0.0889)
		(layer "F.Cu")
		(net "SATA6G_PCH_PCIE_UP_SATA_TXP<5>")
	)
	(segment
		(start 379.408944 -131.807712)
		(end 379.408944 -131.920742)
		(width 0.0889)
		(layer "F.Cu")
		(net "SATA6G_PCH_PCIE_UP_SATA_TXP<5>")
	)
	(segment
		(start 379.295406 -127.984504)
		(end 379.295406 -128.187196)
		(width 0.0889)
		(layer "F.Cu")
		(net "SATA6G_PCH_PCIE_UP_SATA_TXP<5>")
	)
	(segment
		(start 379.384306 -128.364996)
		(end 379.384306 -128.631696)
		(width 0.0889)
		(layer "F.Cu")
		(net "SATA6G_PCH_PCIE_UP_SATA_TXP<5>")
	)
	(segment
		(start 379.889766 -126.260352)
		(end 379.889766 -126.586488)
		(width 0.0889)
		(layer "F.Cu")
		(net "SATA6G_PCH_PCIE_UP_SATA_TXP<5>")
	)
	(segment
		(start 379.213364 -129.216404)
		(end 378.746766 -129.683002)
		(width 0.0889)
		(layer "F.Cu")
		(net "SATA6G_PCH_PCIE_UP_SATA_TXP<5>")
	)
	(segment
		(start 379.7935 -126.682754)
		(end 379.7935 -127.307848)
		(width 0.0889)
		(layer "F.Cu")
		(net "SATA6G_PCH_PCIE_UP_SATA_TXP<5>")
	)
	(segment
		(start 379.295406 -128.809496)
		(end 379.295406 -129.018538)
		(width 0.0889)
		(layer "F.Cu")
		(net "SATA6G_PCH_PCIE_UP_SATA_TXP<5>")
	)
	(segment
		(start 378.720604 -129.745994)
		(end 378.720604 -130.012694)
		(width 0.0889)
		(layer "F.Cu")
		(net "SATA6G_PCH_PCIE_UP_SATA_TXP<5>")
	)
	(segment
		(start 379.693424 -127.549656)
		(end 379.321568 -127.921512)
		(width 0.0889)
		(layer "F.Cu")
		(net "SATA6G_PCH_PCIE_UP_SATA_TXP<5>")
	)
	(segment
		(start 379.889766 -126.586488)
		(end 379.7935 -126.682754)
		(width 0.0889)
		(layer "F.Cu")
		(net "SATA6G_PCH_PCIE_UP_SATA_TXP<5>")
	)
	(segment
		(start 378.720604 -130.634994)
		(end 378.720604 -131.492498)
		(width 0.0889)
		(layer "F.Cu")
		(net "SATA6G_PCH_PCIE_UP_SATA_TXP<5>")
	)
	(segment
		(start 378.809504 -130.190494)
		(end 378.809504 -130.457194)
		(width 0.0889)
		(layer "F.Cu")
		(net "SATA6G_PCH_PCIE_UP_SATA_TXP<5>")
	)
	(segment
		(start 378.851668 -131.623562)
		(end 379.224794 -131.623562)
		(width 0.0889)
		(layer "F.Cu")
		(net "SATA6G_PCH_PCIE_UP_SATA_TXP<5>")
	)
	(via
		(at 406.86355 -144.35455)
		(size 0.508)
		(drill 0.254)
		(layers "F.Cu" "B.Cu")
		(net "SATA6G_PCH_PCIE_UP_SATA_TXP<5>")
	)
	(via
		(at 379.1458 -132.08)
		(size 0.508)
		(drill 0.254)
		(layers "F.Cu" "B.Cu")
		(net "SATA6G_PCH_PCIE_UP_SATA_TXP<5>")
	)
	(arc
		(start 379.295406 -128.187196)
		(mid 379.309471 -128.235722)
		(end 379.339856 -128.276096)
		(width 0.0889)
		(layer "F.Cu")
		(net "SATA6G_PCH_PCIE_UP_SATA_TXP<5>")
	)
	(arc
		(start 378.746766 -129.683002)
		(mid 378.727401 -129.711889)
		(end 378.720604 -129.745994)
		(width 0.0889)
		(layer "F.Cu")
		(net "SATA6G_PCH_PCIE_UP_SATA_TXP<5>")
	)
	(arc
		(start 379.321568 -127.921512)
		(mid 379.302203 -127.950399)
		(end 379.295406 -127.984504)
		(width 0.0889)
		(layer "F.Cu")
		(net "SATA6G_PCH_PCIE_UP_SATA_TXP<5>")
	)
	(arc
		(start 378.720604 -130.012694)
		(mid 378.734669 -130.06122)
		(end 378.765054 -130.101594)
		(width 0.0889)
		(layer "F.Cu")
		(net "SATA6G_PCH_PCIE_UP_SATA_TXP<5>")
	)
	(arc
		(start 378.809504 -130.457194)
		(mid 378.795439 -130.50572)
		(end 378.765054 -130.546094)
		(width 0.0889)
		(layer "F.Cu")
		(net "SATA6G_PCH_PCIE_UP_SATA_TXP<5>")
	)
	(arc
		(start 379.384306 -128.631696)
		(mid 379.370241 -128.680222)
		(end 379.339856 -128.720596)
		(width 0.0889)
		(layer "F.Cu")
		(net "SATA6G_PCH_PCIE_UP_SATA_TXP<5>")
	)
	(arc
		(start 379.224794 -131.623562)
		(mid 379.355008 -131.677498)
		(end 379.408944 -131.807712)
		(width 0.0889)
		(layer "F.Cu")
		(net "SATA6G_PCH_PCIE_UP_SATA_TXP<5>")
	)
	(arc
		(start 379.339856 -128.276096)
		(mid 379.370277 -128.316452)
		(end 379.384306 -128.364996)
		(width 0.0889)
		(layer "F.Cu")
		(net "SATA6G_PCH_PCIE_UP_SATA_TXP<5>")
	)
	(arc
		(start 378.765054 -130.101594)
		(mid 378.795475 -130.14195)
		(end 378.809504 -130.190494)
		(width 0.0889)
		(layer "F.Cu")
		(net "SATA6G_PCH_PCIE_UP_SATA_TXP<5>")
	)
	(arc
		(start 378.720604 -131.492498)
		(mid 378.758992 -131.585174)
		(end 378.851668 -131.623562)
		(width 0.0889)
		(layer "F.Cu")
		(net "SATA6G_PCH_PCIE_UP_SATA_TXP<5>")
	)
	(arc
		(start 379.408944 -131.920742)
		(mid 379.362298 -132.033354)
		(end 379.249686 -132.08)
		(width 0.0889)
		(layer "F.Cu")
		(net "SATA6G_PCH_PCIE_UP_SATA_TXP<5>")
	)
	(arc
		(start 379.339856 -128.720596)
		(mid 379.309435 -128.760952)
		(end 379.295406 -128.809496)
		(width 0.0889)
		(layer "F.Cu")
		(net "SATA6G_PCH_PCIE_UP_SATA_TXP<5>")
	)
	(arc
		(start 379.7935 -127.307848)
		(mid 379.767476 -127.438681)
		(end 379.693424 -127.549656)
		(width 0.0889)
		(layer "F.Cu")
		(net "SATA6G_PCH_PCIE_UP_SATA_TXP<5>")
	)
	(arc
		(start 379.295406 -129.018538)
		(mid 379.274084 -129.12564)
		(end 379.213364 -129.216404)
		(width 0.0889)
		(layer "F.Cu")
		(net "SATA6G_PCH_PCIE_UP_SATA_TXP<5>")
	)
	(arc
		(start 378.765054 -130.546094)
		(mid 378.734633 -130.58645)
		(end 378.720604 -130.634994)
		(width 0.0889)
		(layer "F.Cu")
		(net "SATA6G_PCH_PCIE_UP_SATA_TXP<5>")
	)
	(segment
		(start 410.972 -145.415)
		(end 410.610558 -145.776442)
		(width 0.1143)
		(layer "B.Cu")
		(net "SATA6G_PCH_PCIE_UP_SATA_TXP<5>")
	)
	(segment
		(start 407.298652 -144.7419)
		(end 406.97785 -144.7419)
		(width 0.1143)
		(layer "B.Cu")
		(net "SATA6G_PCH_PCIE_UP_SATA_TXP<5>")
	)
	(segment
		(start 410.529786 -145.80997)
		(end 408.588718 -145.80997)
		(width 0.1143)
		(layer "B.Cu")
		(net "SATA6G_PCH_PCIE_UP_SATA_TXP<5>")
	)
	(segment
		(start 408.46121 -145.757138)
		(end 407.550112 -144.84604)
		(width 0.1143)
		(layer "B.Cu")
		(net "SATA6G_PCH_PCIE_UP_SATA_TXP<5>")
	)
	(segment
		(start 406.86355 -144.6276)
		(end 406.86355 -144.35455)
		(width 0.1143)
		(layer "B.Cu")
		(net "SATA6G_PCH_PCIE_UP_SATA_TXP<5>")
	)
	(arc
		(start 408.588718 -145.80997)
		(mid 408.519705 -145.796242)
		(end 408.46121 -145.757138)
		(width 0.1143)
		(layer "B.Cu")
		(net "SATA6G_PCH_PCIE_UP_SATA_TXP<5>")
	)
	(arc
		(start 407.550112 -144.84604)
		(mid 407.434741 -144.768952)
		(end 407.298652 -144.7419)
		(width 0.1143)
		(layer "B.Cu")
		(net "SATA6G_PCH_PCIE_UP_SATA_TXP<5>")
	)
	(arc
		(start 410.610558 -145.776442)
		(mid 410.573499 -145.801204)
		(end 410.529786 -145.80997)
		(width 0.1143)
		(layer "B.Cu")
		(net "SATA6G_PCH_PCIE_UP_SATA_TXP<5>")
	)
	(arc
		(start 406.97785 -144.7419)
		(mid 406.897028 -144.708422)
		(end 406.86355 -144.6276)
		(width 0.1143)
		(layer "B.Cu")
		(net "SATA6G_PCH_PCIE_UP_SATA_TXP<5>")
	)
	(segment
		(start 406.535128 -144.682972)
		(end 406.86355 -144.35455)
		(width 0.1143)
		(layer "In2.Cu")
		(net "SATA6G_PCH_PCIE_UP_SATA_TXP<5>")
	)
	(segment
		(start 378.9553 -134.261098)
		(end 378.9553 -134.603998)
		(width 0.1143)
		(layer "In2.Cu")
		(net "SATA6G_PCH_PCIE_UP_SATA_TXP<5>")
	)
	(segment
		(start 379.1204 -133.587998)
		(end 379.1204 -133.930898)
		(width 0.1143)
		(layer "In2.Cu")
		(net "SATA6G_PCH_PCIE_UP_SATA_TXP<5>")
	)
	(segment
		(start 406.110694 -144.7165)
		(end 406.454356 -144.7165)
		(width 0.1143)
		(layer "In2.Cu")
		(net "SATA6G_PCH_PCIE_UP_SATA_TXP<5>")
	)
	(segment
		(start 381.219202 -137.04062)
		(end 382.393444 -137.04062)
		(width 0.1143)
		(layer "In2.Cu")
		(net "SATA6G_PCH_PCIE_UP_SATA_TXP<5>")
	)
	(segment
		(start 400.14144 -141.858746)
		(end 400.14144 -142.698978)
		(width 0.1143)
		(layer "In2.Cu")
		(net "SATA6G_PCH_PCIE_UP_SATA_TXP<5>")
	)
	(segment
		(start 378.9553 -134.603998)
		(end 378.955554 -134.603744)
		(width 0.1143)
		(layer "In2.Cu")
		(net "SATA6G_PCH_PCIE_UP_SATA_TXP<5>")
	)
	(segment
		(start 400.280886 -145.72742)
		(end 400.558508 -146.005042)
		(width 0.1143)
		(layer "In2.Cu")
		(net "SATA6G_PCH_PCIE_UP_SATA_TXP<5>")
	)
	(segment
		(start 394.120624 -139.485116)
		(end 394.120624 -139.89431)
		(width 0.1143)
		(layer "In2.Cu")
		(net "SATA6G_PCH_PCIE_UP_SATA_TXP<5>")
	)
	(segment
		(start 394.641324 -139.89431)
		(end 394.641324 -139.485116)
		(width 0.1143)
		(layer "In2.Cu")
		(net "SATA6G_PCH_PCIE_UP_SATA_TXP<5>")
	)
	(segment
		(start 398.454626 -138.932666)
		(end 398.79651 -138.932666)
		(width 0.1143)
		(layer "In2.Cu")
		(net "SATA6G_PCH_PCIE_UP_SATA_TXP<5>")
	)
	(segment
		(start 400.873722 -146.135598)
		(end 401.642834 -146.135598)
		(width 0.1143)
		(layer "In2.Cu")
		(net "SATA6G_PCH_PCIE_UP_SATA_TXP<5>")
	)
	(segment
		(start 399.502884 -139.788392)
		(end 399.502884 -140.706602)
		(width 0.1143)
		(layer "In2.Cu")
		(net "SATA6G_PCH_PCIE_UP_SATA_TXP<5>")
	)
	(segment
		(start 400.30654 -143.029178)
		(end 400.30654 -143.372078)
		(width 0.1143)
		(layer "In2.Cu")
		(net "SATA6G_PCH_PCIE_UP_SATA_TXP<5>")
	)
	(segment
		(start 379.1458 -132.08)
		(end 378.988828 -132.236972)
		(width 0.1143)
		(layer "In2.Cu")
		(net "SATA6G_PCH_PCIE_UP_SATA_TXP<5>")
	)
	(segment
		(start 399.612104 -140.969492)
		(end 399.886678 -141.244066)
		(width 0.1143)
		(layer "In2.Cu")
		(net "SATA6G_PCH_PCIE_UP_SATA_TXP<5>")
	)
	(segment
		(start 397.371824 -139.485116)
		(end 397.371824 -139.89431)
		(width 0.1143)
		(layer "In2.Cu")
		(net "SATA6G_PCH_PCIE_UP_SATA_TXP<5>")
	)
	(segment
		(start 383.396744 -137.04062)
		(end 385.009136 -137.04062)
		(width 0.1143)
		(layer "In2.Cu")
		(net "SATA6G_PCH_PCIE_UP_SATA_TXP<5>")
	)
	(segment
		(start 378.9553 -132.317744)
		(end 378.9553 -133.257798)
		(width 0.1143)
		(layer "In2.Cu")
		(net "SATA6G_PCH_PCIE_UP_SATA_TXP<5>")
	)
	(segment
		(start 392.495024 -139.504166)
		(end 392.495024 -139.89431)
		(width 0.1143)
		(layer "In2.Cu")
		(net "SATA6G_PCH_PCIE_UP_SATA_TXP<5>")
	)
	(segment
		(start 380.801118 -136.725406)
		(end 381.043688 -136.967976)
		(width 0.1143)
		(layer "In2.Cu")
		(net "SATA6G_PCH_PCIE_UP_SATA_TXP<5>")
	)
	(segment
		(start 387.44271 -138.932666)
		(end 391.923524 -138.932666)
		(width 0.1143)
		(layer "In2.Cu")
		(net "SATA6G_PCH_PCIE_UP_SATA_TXP<5>")
	)
	(segment
		(start 393.015724 -139.89431)
		(end 393.015724 -139.485116)
		(width 0.1143)
		(layer "In2.Cu")
		(net "SATA6G_PCH_PCIE_UP_SATA_TXP<5>")
	)
	(segment
		(start 400.30654 -144.375378)
		(end 400.30654 -144.718278)
		(width 0.1143)
		(layer "In2.Cu")
		(net "SATA6G_PCH_PCIE_UP_SATA_TXP<5>")
	)
	(segment
		(start 395.746224 -139.485116)
		(end 395.746224 -139.89431)
		(width 0.1143)
		(layer "In2.Cu")
		(net "SATA6G_PCH_PCIE_UP_SATA_TXP<5>")
	)
	(segment
		(start 400.14144 -145.048478)
		(end 400.14144 -145.391378)
		(width 0.1143)
		(layer "In2.Cu")
		(net "SATA6G_PCH_PCIE_UP_SATA_TXP<5>")
	)
	(segment
		(start 401.983702 -145.994374)
		(end 402.210778 -145.767298)
		(width 0.1143)
		(layer "In2.Cu")
		(net "SATA6G_PCH_PCIE_UP_SATA_TXP<5>")
	)
	(segment
		(start 397.892524 -139.89431)
		(end 397.892524 -139.494768)
		(width 0.1143)
		(layer "In2.Cu")
		(net "SATA6G_PCH_PCIE_UP_SATA_TXP<5>")
	)
	(segment
		(start 396.266924 -139.89431)
		(end 396.266924 -139.485116)
		(width 0.1143)
		(layer "In2.Cu")
		(net "SATA6G_PCH_PCIE_UP_SATA_TXP<5>")
	)
	(segment
		(start 399.220436 -139.107926)
		(end 399.220944 -139.108434)
		(width 0.1143)
		(layer "In2.Cu")
		(net "SATA6G_PCH_PCIE_UP_SATA_TXP<5>")
	)
	(segment
		(start 382.723644 -136.87552)
		(end 383.066544 -136.87552)
		(width 0.1143)
		(layer "In2.Cu")
		(net "SATA6G_PCH_PCIE_UP_SATA_TXP<5>")
	)
	(segment
		(start 379.15088 -135.075168)
		(end 380.091696 -136.015984)
		(width 0.1143)
		(layer "In2.Cu")
		(net "SATA6G_PCH_PCIE_UP_SATA_TXP<5>")
	)
	(segment
		(start 385.575048 -137.275062)
		(end 387.083554 -138.783568)
		(width 0.1143)
		(layer "In2.Cu")
		(net "SATA6G_PCH_PCIE_UP_SATA_TXP<5>")
	)
	(segment
		(start 405.174196 -145.35785)
		(end 405.596344 -144.935702)
		(width 0.1143)
		(layer "In2.Cu")
		(net "SATA6G_PCH_PCIE_UP_SATA_TXP<5>")
	)
	(segment
		(start 380.441962 -136.132824)
		(end 380.684532 -136.375394)
		(width 0.1143)
		(layer "In2.Cu")
		(net "SATA6G_PCH_PCIE_UP_SATA_TXP<5>")
	)
	(segment
		(start 400.14144 -143.702278)
		(end 400.14144 -144.045178)
		(width 0.1143)
		(layer "In2.Cu")
		(net "SATA6G_PCH_PCIE_UP_SATA_TXP<5>")
	)
	(segment
		(start 402.698204 -145.565622)
		(end 404.672546 -145.565622)
		(width 0.1143)
		(layer "In2.Cu")
		(net "SATA6G_PCH_PCIE_UP_SATA_TXP<5>")
	)
	(arc
		(start 383.231644 -136.95807)
		(mid 383.304925 -137.017896)
		(end 383.396744 -137.04062)
		(width 0.1143)
		(layer "In2.Cu")
		(net "SATA6G_PCH_PCIE_UP_SATA_TXP<5>")
	)
	(arc
		(start 385.009136 -137.04062)
		(mid 385.315418 -137.101543)
		(end 385.575048 -137.275062)
		(width 0.1143)
		(layer "In2.Cu")
		(net "SATA6G_PCH_PCIE_UP_SATA_TXP<5>")
	)
	(arc
		(start 395.746224 -139.89431)
		(mid 396.006574 -140.15466)
		(end 396.266924 -139.89431)
		(width 0.1143)
		(layer "In2.Cu")
		(net "SATA6G_PCH_PCIE_UP_SATA_TXP<5>")
	)
	(arc
		(start 400.22399 -142.864078)
		(mid 400.283816 -142.937359)
		(end 400.30654 -143.029178)
		(width 0.1143)
		(layer "In2.Cu")
		(net "SATA6G_PCH_PCIE_UP_SATA_TXP<5>")
	)
	(arc
		(start 380.742952 -136.5504)
		(mid 380.752417 -136.644423)
		(end 380.801118 -136.725406)
		(width 0.1143)
		(layer "In2.Cu")
		(net "SATA6G_PCH_PCIE_UP_SATA_TXP<5>")
	)
	(arc
		(start 402.210778 -145.767298)
		(mid 402.434426 -145.617954)
		(end 402.698204 -145.565622)
		(width 0.1143)
		(layer "In2.Cu")
		(net "SATA6G_PCH_PCIE_UP_SATA_TXP<5>")
	)
	(arc
		(start 393.015724 -139.485116)
		(mid 393.568174 -138.932666)
		(end 394.120624 -139.485116)
		(width 0.1143)
		(layer "In2.Cu")
		(net "SATA6G_PCH_PCIE_UP_SATA_TXP<5>")
	)
	(arc
		(start 401.642834 -146.135598)
		(mid 401.827323 -146.098901)
		(end 401.983702 -145.994374)
		(width 0.1143)
		(layer "In2.Cu")
		(net "SATA6G_PCH_PCIE_UP_SATA_TXP<5>")
	)
	(arc
		(start 400.30654 -144.718278)
		(mid 400.283772 -144.810075)
		(end 400.22399 -144.883378)
		(width 0.1143)
		(layer "In2.Cu")
		(net "SATA6G_PCH_PCIE_UP_SATA_TXP<5>")
	)
	(arc
		(start 387.083554 -138.783568)
		(mid 387.248307 -138.893809)
		(end 387.44271 -138.932666)
		(width 0.1143)
		(layer "In2.Cu")
		(net "SATA6G_PCH_PCIE_UP_SATA_TXP<5>")
	)
	(arc
		(start 380.091696 -136.015984)
		(mid 380.172763 -136.064883)
		(end 380.266956 -136.074404)
		(width 0.1143)
		(layer "In2.Cu")
		(net "SATA6G_PCH_PCIE_UP_SATA_TXP<5>")
	)
	(arc
		(start 400.14144 -142.698978)
		(mid 400.164208 -142.790775)
		(end 400.22399 -142.864078)
		(width 0.1143)
		(layer "In2.Cu")
		(net "SATA6G_PCH_PCIE_UP_SATA_TXP<5>")
	)
	(arc
		(start 405.596344 -144.935702)
		(mid 405.831119 -144.773541)
		(end 406.110694 -144.7165)
		(width 0.1143)
		(layer "In2.Cu")
		(net "SATA6G_PCH_PCIE_UP_SATA_TXP<5>")
	)
	(arc
		(start 378.988828 -132.236972)
		(mid 378.964066 -132.274031)
		(end 378.9553 -132.317744)
		(width 0.1143)
		(layer "In2.Cu")
		(net "SATA6G_PCH_PCIE_UP_SATA_TXP<5>")
	)
	(arc
		(start 400.30654 -143.372078)
		(mid 400.283772 -143.463875)
		(end 400.22399 -143.537178)
		(width 0.1143)
		(layer "In2.Cu")
		(net "SATA6G_PCH_PCIE_UP_SATA_TXP<5>")
	)
	(arc
		(start 381.043688 -136.967976)
		(mid 381.124229 -137.021728)
		(end 381.219202 -137.04062)
		(width 0.1143)
		(layer "In2.Cu")
		(net "SATA6G_PCH_PCIE_UP_SATA_TXP<5>")
	)
	(arc
		(start 404.672546 -145.565622)
		(mid 404.94403 -145.51162)
		(end 405.174196 -145.35785)
		(width 0.1143)
		(layer "In2.Cu")
		(net "SATA6G_PCH_PCIE_UP_SATA_TXP<5>")
	)
	(arc
		(start 398.79651 -138.932666)
		(mid 399.025877 -138.978178)
		(end 399.220436 -139.107926)
		(width 0.1143)
		(layer "In2.Cu")
		(net "SATA6G_PCH_PCIE_UP_SATA_TXP<5>")
	)
	(arc
		(start 399.502884 -140.706602)
		(mid 399.531307 -140.848934)
		(end 399.612104 -140.969492)
		(width 0.1143)
		(layer "In2.Cu")
		(net "SATA6G_PCH_PCIE_UP_SATA_TXP<5>")
	)
	(arc
		(start 394.120624 -139.89431)
		(mid 394.380974 -140.15466)
		(end 394.641324 -139.89431)
		(width 0.1143)
		(layer "In2.Cu")
		(net "SATA6G_PCH_PCIE_UP_SATA_TXP<5>")
	)
	(arc
		(start 406.454356 -144.7165)
		(mid 406.498097 -144.707799)
		(end 406.535128 -144.682972)
		(width 0.1143)
		(layer "In2.Cu")
		(net "SATA6G_PCH_PCIE_UP_SATA_TXP<5>")
	)
	(arc
		(start 378.9553 -133.257798)
		(mid 378.978068 -133.349595)
		(end 379.03785 -133.422898)
		(width 0.1143)
		(layer "In2.Cu")
		(net "SATA6G_PCH_PCIE_UP_SATA_TXP<5>")
	)
	(arc
		(start 392.495024 -139.89431)
		(mid 392.755374 -140.15466)
		(end 393.015724 -139.89431)
		(width 0.1143)
		(layer "In2.Cu")
		(net "SATA6G_PCH_PCIE_UP_SATA_TXP<5>")
	)
	(arc
		(start 399.220944 -139.108434)
		(mid 399.429506 -139.420386)
		(end 399.502884 -139.788392)
		(width 0.1143)
		(layer "In2.Cu")
		(net "SATA6G_PCH_PCIE_UP_SATA_TXP<5>")
	)
	(arc
		(start 400.22399 -143.537178)
		(mid 400.164164 -143.610459)
		(end 400.14144 -143.702278)
		(width 0.1143)
		(layer "In2.Cu")
		(net "SATA6G_PCH_PCIE_UP_SATA_TXP<5>")
	)
	(arc
		(start 396.266924 -139.485116)
		(mid 396.819374 -138.932666)
		(end 397.371824 -139.485116)
		(width 0.1143)
		(layer "In2.Cu")
		(net "SATA6G_PCH_PCIE_UP_SATA_TXP<5>")
	)
	(arc
		(start 400.22399 -144.883378)
		(mid 400.164164 -144.956659)
		(end 400.14144 -145.048478)
		(width 0.1143)
		(layer "In2.Cu")
		(net "SATA6G_PCH_PCIE_UP_SATA_TXP<5>")
	)
	(arc
		(start 379.03785 -133.422898)
		(mid 379.097676 -133.496179)
		(end 379.1204 -133.587998)
		(width 0.1143)
		(layer "In2.Cu")
		(net "SATA6G_PCH_PCIE_UP_SATA_TXP<5>")
	)
	(arc
		(start 380.684532 -136.375394)
		(mid 380.733391 -136.456341)
		(end 380.742952 -136.5504)
		(width 0.1143)
		(layer "In2.Cu")
		(net "SATA6G_PCH_PCIE_UP_SATA_TXP<5>")
	)
	(arc
		(start 379.1204 -133.930898)
		(mid 379.097632 -134.022695)
		(end 379.03785 -134.095998)
		(width 0.1143)
		(layer "In2.Cu")
		(net "SATA6G_PCH_PCIE_UP_SATA_TXP<5>")
	)
	(arc
		(start 397.892524 -139.494768)
		(mid 398.05716 -139.097302)
		(end 398.454626 -138.932666)
		(width 0.1143)
		(layer "In2.Cu")
		(net "SATA6G_PCH_PCIE_UP_SATA_TXP<5>")
	)
	(arc
		(start 382.558544 -136.95807)
		(mid 382.631825 -136.898244)
		(end 382.723644 -136.87552)
		(width 0.1143)
		(layer "In2.Cu")
		(net "SATA6G_PCH_PCIE_UP_SATA_TXP<5>")
	)
	(arc
		(start 391.923524 -138.932666)
		(mid 392.327636 -139.100054)
		(end 392.495024 -139.504166)
		(width 0.1143)
		(layer "In2.Cu")
		(net "SATA6G_PCH_PCIE_UP_SATA_TXP<5>")
	)
	(arc
		(start 400.22399 -144.210278)
		(mid 400.283816 -144.283559)
		(end 400.30654 -144.375378)
		(width 0.1143)
		(layer "In2.Cu")
		(net "SATA6G_PCH_PCIE_UP_SATA_TXP<5>")
	)
	(arc
		(start 382.393444 -137.04062)
		(mid 382.485241 -137.017852)
		(end 382.558544 -136.95807)
		(width 0.1143)
		(layer "In2.Cu")
		(net "SATA6G_PCH_PCIE_UP_SATA_TXP<5>")
	)
	(arc
		(start 399.886678 -141.244066)
		(mid 400.075199 -141.526069)
		(end 400.14144 -141.858746)
		(width 0.1143)
		(layer "In2.Cu")
		(net "SATA6G_PCH_PCIE_UP_SATA_TXP<5>")
	)
	(arc
		(start 383.066544 -136.87552)
		(mid 383.158341 -136.898288)
		(end 383.231644 -136.95807)
		(width 0.1143)
		(layer "In2.Cu")
		(net "SATA6G_PCH_PCIE_UP_SATA_TXP<5>")
	)
	(arc
		(start 400.14144 -145.391378)
		(mid 400.177717 -145.573286)
		(end 400.280886 -145.72742)
		(width 0.1143)
		(layer "In2.Cu")
		(net "SATA6G_PCH_PCIE_UP_SATA_TXP<5>")
	)
	(arc
		(start 380.266956 -136.074404)
		(mid 380.361005 -136.083994)
		(end 380.441962 -136.132824)
		(width 0.1143)
		(layer "In2.Cu")
		(net "SATA6G_PCH_PCIE_UP_SATA_TXP<5>")
	)
	(arc
		(start 379.03785 -134.095998)
		(mid 378.978024 -134.169279)
		(end 378.9553 -134.261098)
		(width 0.1143)
		(layer "In2.Cu")
		(net "SATA6G_PCH_PCIE_UP_SATA_TXP<5>")
	)
	(arc
		(start 400.558508 -146.005042)
		(mid 400.703129 -146.101675)
		(end 400.873722 -146.135598)
		(width 0.1143)
		(layer "In2.Cu")
		(net "SATA6G_PCH_PCIE_UP_SATA_TXP<5>")
	)
	(arc
		(start 394.641324 -139.485116)
		(mid 395.193774 -138.932666)
		(end 395.746224 -139.485116)
		(width 0.1143)
		(layer "In2.Cu")
		(net "SATA6G_PCH_PCIE_UP_SATA_TXP<5>")
	)
	(arc
		(start 400.14144 -144.045178)
		(mid 400.164208 -144.136975)
		(end 400.22399 -144.210278)
		(width 0.1143)
		(layer "In2.Cu")
		(net "SATA6G_PCH_PCIE_UP_SATA_TXP<5>")
	)
	(arc
		(start 397.371824 -139.89431)
		(mid 397.632174 -140.15466)
		(end 397.892524 -139.89431)
		(width 0.1143)
		(layer "In2.Cu")
		(net "SATA6G_PCH_PCIE_UP_SATA_TXP<5>")
	)
	(arc
		(start 378.955554 -134.603744)
		(mid 379.006307 -134.858898)
		(end 379.15088 -135.075168)
		(width 0.1143)
		(layer "In2.Cu")
		(net "SATA6G_PCH_PCIE_UP_SATA_TXP<5>")
	)
	(segment
		(start 379.950218 -128.712468)
		(end 379.950218 -128.979168)
		(width 0.0889)
		(layer "F.Cu")
		(net "SATA6G_PCH_PCIE_UP_SATA_TXP<4>")
	)
	(segment
		(start 380.498096 -125.763274)
		(end 380.498096 -125.889004)
		(width 0.0889)
		(layer "F.Cu")
		(net "SATA6G_PCH_PCIE_UP_SATA_TXP<4>")
	)
	(segment
		(start 379.861318 -128.32715)
		(end 379.861318 -128.534668)
		(width 0.0889)
		(layer "F.Cu")
		(net "SATA6G_PCH_PCIE_UP_SATA_TXP<4>")
	)
	(segment
		(start 380.461266 -126.303786)
		(end 380.349252 -126.574296)
		(width 0.0889)
		(layer "F.Cu")
		(net "SATA6G_PCH_PCIE_UP_SATA_TXP<4>")
	)
	(segment
		(start 380.55804 -130.216656)
		(end 380.614682 -130.273298)
		(width 0.0889)
		(layer "F.Cu")
		(net "SATA6G_PCH_PCIE_UP_SATA_TXP<4>")
	)
	(segment
		(start 381.363728 -130.802888)
		(end 381.363728 -131.006088)
		(width 0.0889)
		(layer "F.Cu")
		(net "SATA6G_PCH_PCIE_UP_SATA_TXP<4>")
	)
	(segment
		(start 380.438152 -127.018796)
		(end 380.438152 -127.285496)
		(width 0.0889)
		(layer "F.Cu")
		(net "SATA6G_PCH_PCIE_UP_SATA_TXP<4>")
	)
	(segment
		(start 379.861318 -129.156968)
		(end 379.861318 -129.423668)
		(width 0.0889)
		(layer "F.Cu")
		(net "SATA6G_PCH_PCIE_UP_SATA_TXP<4>")
	)
	(segment
		(start 380.461266 -125.925834)
		(end 380.461266 -126.303786)
		(width 0.0889)
		(layer "F.Cu")
		(net "SATA6G_PCH_PCIE_UP_SATA_TXP<4>")
	)
	(segment
		(start 379.929644 -129.588006)
		(end 380.118112 -129.776728)
		(width 0.0889)
		(layer "F.Cu")
		(net "SATA6G_PCH_PCIE_UP_SATA_TXP<4>")
	)
	(segment
		(start 380.78664 -130.643884)
		(end 381.204724 -130.643884)
		(width 0.0889)
		(layer "F.Cu")
		(net "SATA6G_PCH_PCIE_UP_SATA_TXP<4>")
	)
	(segment
		(start 381.274828 -131.094988)
		(end 381.16637 -131.094988)
		(width 0.0889)
		(layer "F.Cu")
		(net "SATA6G_PCH_PCIE_UP_SATA_TXP<4>")
	)
	(segment
		(start 380.498096 -125.889004)
		(end 380.461266 -125.925834)
		(width 0.0889)
		(layer "F.Cu")
		(net "SATA6G_PCH_PCIE_UP_SATA_TXP<4>")
	)
	(segment
		(start 380.349252 -127.463296)
		(end 380.349252 -127.573024)
		(width 0.0889)
		(layer "F.Cu")
		(net "SATA6G_PCH_PCIE_UP_SATA_TXP<4>")
	)
	(segment
		(start 380.306834 -129.839466)
		(end 380.495302 -130.028188)
		(width 0.0889)
		(layer "F.Cu")
		(net "SATA6G_PCH_PCIE_UP_SATA_TXP<4>")
	)
	(segment
		(start 380.484888 -125.750066)
		(end 380.498096 -125.763274)
		(width 0.0889)
		(layer "F.Cu")
		(net "SATA6G_PCH_PCIE_UP_SATA_TXP<4>")
	)
	(segment
		(start 380.69647 -130.471164)
		(end 380.69647 -130.553714)
		(width 0.0889)
		(layer "F.Cu")
		(net "SATA6G_PCH_PCIE_UP_SATA_TXP<4>")
	)
	(segment
		(start 380.267464 -127.770636)
		(end 379.96749 -128.070864)
		(width 0.0889)
		(layer "F.Cu")
		(net "SATA6G_PCH_PCIE_UP_SATA_TXP<4>")
	)
	(segment
		(start 380.349252 -126.574296)
		(end 380.349252 -126.840996)
		(width 0.0889)
		(layer "F.Cu")
		(net "SATA6G_PCH_PCIE_UP_SATA_TXP<4>")
	)
	(via
		(at 412.773876 -141.0208)
		(size 0.508)
		(drill 0.254)
		(layers "F.Cu" "B.Cu")
		(net "SATA6G_PCH_PCIE_UP_SATA_TXP<4>")
	)
	(via
		(at 381.16637 -131.094988)
		(size 0.508)
		(drill 0.254)
		(layers "F.Cu" "B.Cu")
		(net "SATA6G_PCH_PCIE_UP_SATA_TXP<4>")
	)
	(arc
		(start 381.363728 -131.006088)
		(mid 381.33769 -131.06895)
		(end 381.274828 -131.094988)
		(width 0.0889)
		(layer "F.Cu")
		(net "SATA6G_PCH_PCIE_UP_SATA_TXP<4>")
	)
	(arc
		(start 379.861318 -129.423668)
		(mid 379.879127 -129.512637)
		(end 379.929644 -129.588006)
		(width 0.0889)
		(layer "F.Cu")
		(net "SATA6G_PCH_PCIE_UP_SATA_TXP<4>")
	)
	(arc
		(start 380.393702 -127.374396)
		(mid 380.363281 -127.414752)
		(end 380.349252 -127.463296)
		(width 0.0889)
		(layer "F.Cu")
		(net "SATA6G_PCH_PCIE_UP_SATA_TXP<4>")
	)
	(arc
		(start 379.96749 -128.070864)
		(mid 379.888922 -128.188449)
		(end 379.861318 -128.32715)
		(width 0.0889)
		(layer "F.Cu")
		(net "SATA6G_PCH_PCIE_UP_SATA_TXP<4>")
	)
	(arc
		(start 380.69647 -130.553714)
		(mid 380.72288 -130.617474)
		(end 380.78664 -130.643884)
		(width 0.0889)
		(layer "F.Cu")
		(net "SATA6G_PCH_PCIE_UP_SATA_TXP<4>")
	)
	(arc
		(start 379.905768 -128.623568)
		(mid 379.936189 -128.663924)
		(end 379.950218 -128.712468)
		(width 0.0889)
		(layer "F.Cu")
		(net "SATA6G_PCH_PCIE_UP_SATA_TXP<4>")
	)
	(arc
		(start 380.438152 -127.285496)
		(mid 380.424087 -127.334022)
		(end 380.393702 -127.374396)
		(width 0.0889)
		(layer "F.Cu")
		(net "SATA6G_PCH_PCIE_UP_SATA_TXP<4>")
	)
	(arc
		(start 379.861318 -128.534668)
		(mid 379.875383 -128.583194)
		(end 379.905768 -128.623568)
		(width 0.0889)
		(layer "F.Cu")
		(net "SATA6G_PCH_PCIE_UP_SATA_TXP<4>")
	)
	(arc
		(start 380.495302 -130.028188)
		(mid 380.519654 -130.072419)
		(end 380.526798 -130.122422)
		(width 0.0889)
		(layer "F.Cu")
		(net "SATA6G_PCH_PCIE_UP_SATA_TXP<4>")
	)
	(arc
		(start 380.349252 -126.840996)
		(mid 380.363317 -126.889522)
		(end 380.393702 -126.929896)
		(width 0.0889)
		(layer "F.Cu")
		(net "SATA6G_PCH_PCIE_UP_SATA_TXP<4>")
	)
	(arc
		(start 380.349252 -127.573024)
		(mid 380.327999 -127.67996)
		(end 380.267464 -127.770636)
		(width 0.0889)
		(layer "F.Cu")
		(net "SATA6G_PCH_PCIE_UP_SATA_TXP<4>")
	)
	(arc
		(start 380.393702 -126.929896)
		(mid 380.424123 -126.970252)
		(end 380.438152 -127.018796)
		(width 0.0889)
		(layer "F.Cu")
		(net "SATA6G_PCH_PCIE_UP_SATA_TXP<4>")
	)
	(arc
		(start 380.526798 -130.122422)
		(mid 380.533748 -130.172416)
		(end 380.55804 -130.216656)
		(width 0.0889)
		(layer "F.Cu")
		(net "SATA6G_PCH_PCIE_UP_SATA_TXP<4>")
	)
	(arc
		(start 380.614682 -130.273298)
		(mid 380.675233 -130.364108)
		(end 380.69647 -130.471164)
		(width 0.0889)
		(layer "F.Cu")
		(net "SATA6G_PCH_PCIE_UP_SATA_TXP<4>")
	)
	(arc
		(start 381.204724 -130.643884)
		(mid 381.317157 -130.690455)
		(end 381.363728 -130.802888)
		(width 0.0889)
		(layer "F.Cu")
		(net "SATA6G_PCH_PCIE_UP_SATA_TXP<4>")
	)
	(arc
		(start 380.2126 -129.80797)
		(mid 380.262592 -129.815097)
		(end 380.306834 -129.839466)
		(width 0.0889)
		(layer "F.Cu")
		(net "SATA6G_PCH_PCIE_UP_SATA_TXP<4>")
	)
	(arc
		(start 379.905768 -129.068068)
		(mid 379.875347 -129.108424)
		(end 379.861318 -129.156968)
		(width 0.0889)
		(layer "F.Cu")
		(net "SATA6G_PCH_PCIE_UP_SATA_TXP<4>")
	)
	(arc
		(start 379.950218 -128.979168)
		(mid 379.936153 -129.027694)
		(end 379.905768 -129.068068)
		(width 0.0889)
		(layer "F.Cu")
		(net "SATA6G_PCH_PCIE_UP_SATA_TXP<4>")
	)
	(arc
		(start 380.118112 -129.776728)
		(mid 380.162488 -129.800997)
		(end 380.2126 -129.80797)
		(width 0.0889)
		(layer "F.Cu")
		(net "SATA6G_PCH_PCIE_UP_SATA_TXP<4>")
	)
	(segment
		(start 412.773876 -141.0208)
		(end 412.773876 -141.29385)
		(width 0.1143)
		(layer "B.Cu")
		(net "SATA6G_PCH_PCIE_UP_SATA_TXP<4>")
	)
	(segment
		(start 413.310578 -141.374622)
		(end 413.6644 -141.0208)
		(width 0.1143)
		(layer "B.Cu")
		(net "SATA6G_PCH_PCIE_UP_SATA_TXP<4>")
	)
	(segment
		(start 412.888176 -141.40815)
		(end 413.229806 -141.40815)
		(width 0.1143)
		(layer "B.Cu")
		(net "SATA6G_PCH_PCIE_UP_SATA_TXP<4>")
	)
	(arc
		(start 413.229806 -141.40815)
		(mid 413.273547 -141.399449)
		(end 413.310578 -141.374622)
		(width 0.1143)
		(layer "B.Cu")
		(net "SATA6G_PCH_PCIE_UP_SATA_TXP<4>")
	)
	(arc
		(start 412.773876 -141.29385)
		(mid 412.807354 -141.374672)
		(end 412.888176 -141.40815)
		(width 0.1143)
		(layer "B.Cu")
		(net "SATA6G_PCH_PCIE_UP_SATA_TXP<4>")
	)
	(segment
		(start 385.615942 -134.173722)
		(end 388.670546 -137.228326)
		(width 0.1143)
		(layer "In2.Cu")
		(net "SATA6G_PCH_PCIE_UP_SATA_TXP<4>")
	)
	(segment
		(start 384.770122 -133.965696)
		(end 385.113022 -133.965696)
		(width 0.1143)
		(layer "In2.Cu")
		(net "SATA6G_PCH_PCIE_UP_SATA_TXP<4>")
	)
	(segment
		(start 404.555198 -139.547092)
		(end 404.74138 -139.547092)
		(width 0.1143)
		(layer "In2.Cu")
		(net "SATA6G_PCH_PCIE_UP_SATA_TXP<4>")
	)
	(segment
		(start 411.566868 -143.629126)
		(end 411.566868 -142.209774)
		(width 0.1143)
		(layer "In2.Cu")
		(net "SATA6G_PCH_PCIE_UP_SATA_TXP<4>")
	)
	(segment
		(start 412.379414 -141.397228)
		(end 412.659576 -141.397228)
		(width 0.1143)
		(layer "In2.Cu")
		(net "SATA6G_PCH_PCIE_UP_SATA_TXP<4>")
	)
	(segment
		(start 410.11602 -141.007338)
		(end 410.66847 -141.008354)
		(width 0.1143)
		(layer "In2.Cu")
		(net "SATA6G_PCH_PCIE_UP_SATA_TXP<4>")
	)
	(segment
		(start 405.77643 -140.88745)
		(end 405.77643 -140.086842)
		(width 0.1143)
		(layer "In2.Cu")
		(net "SATA6G_PCH_PCIE_UP_SATA_TXP<4>")
	)
	(segment
		(start 391.202164 -137.05205)
		(end 391.202164 -137.021062)
		(width 0.1143)
		(layer "In2.Cu")
		(net "SATA6G_PCH_PCIE_UP_SATA_TXP<4>")
	)
	(segment
		(start 407.89098 -139.547092)
		(end 408.575256 -139.547092)
		(width 0.1143)
		(layer "In2.Cu")
		(net "SATA6G_PCH_PCIE_UP_SATA_TXP<4>")
	)
	(segment
		(start 403.34819 -140.968222)
		(end 403.34819 -143.710406)
		(width 0.1143)
		(layer "In2.Cu")
		(net "SATA6G_PCH_PCIE_UP_SATA_TXP<4>")
	)
	(segment
		(start 407.35123 -140.88745)
		(end 407.35123 -140.086842)
		(width 0.1143)
		(layer "In2.Cu")
		(net "SATA6G_PCH_PCIE_UP_SATA_TXP<4>")
	)
	(segment
		(start 390.13892 -136.458706)
		(end 390.139428 -136.458706)
		(width 0.1143)
		(layer "In2.Cu")
		(net "SATA6G_PCH_PCIE_UP_SATA_TXP<4>")
	)
	(segment
		(start 405.28113 -140.086842)
		(end 405.28113 -140.88745)
		(width 0.1143)
		(layer "In2.Cu")
		(net "SATA6G_PCH_PCIE_UP_SATA_TXP<4>")
	)
	(segment
		(start 401.277074 -138.528552)
		(end 401.580604 -138.832082)
		(width 0.1143)
		(layer "In2.Cu")
		(net "SATA6G_PCH_PCIE_UP_SATA_TXP<4>")
	)
	(segment
		(start 383.21234 -133.965696)
		(end 383.766822 -133.965696)
		(width 0.1143)
		(layer "In2.Cu")
		(net "SATA6G_PCH_PCIE_UP_SATA_TXP<4>")
	)
	(segment
		(start 411.176216 -141.515592)
		(end 411.176216 -141.560804)
		(width 0.1143)
		(layer "In2.Cu")
		(net "SATA6G_PCH_PCIE_UP_SATA_TXP<4>")
	)
	(segment
		(start 412.773876 -141.282928)
		(end 412.773876 -141.0208)
		(width 0.1143)
		(layer "In2.Cu")
		(net "SATA6G_PCH_PCIE_UP_SATA_TXP<4>")
	)
	(segment
		(start 389.576564 -137.05205)
		(end 389.576564 -137.021062)
		(width 0.1143)
		(layer "In2.Cu")
		(net "SATA6G_PCH_PCIE_UP_SATA_TXP<4>")
	)
	(segment
		(start 406.85593 -140.086842)
		(end 406.85593 -140.88745)
		(width 0.1143)
		(layer "In2.Cu")
		(net "SATA6G_PCH_PCIE_UP_SATA_TXP<4>")
	)
	(segment
		(start 381.02794 -131.280662)
		(end 381.02794 -133.200394)
		(width 0.1143)
		(layer "In2.Cu")
		(net "SATA6G_PCH_PCIE_UP_SATA_TXP<4>")
	)
	(segment
		(start 402.290026 -139.541504)
		(end 403.087332 -140.33881)
		(width 0.1143)
		(layer "In2.Cu")
		(net "SATA6G_PCH_PCIE_UP_SATA_TXP<4>")
	)
	(segment
		(start 384.097022 -133.800596)
		(end 384.439922 -133.800596)
		(width 0.1143)
		(layer "In2.Cu")
		(net "SATA6G_PCH_PCIE_UP_SATA_TXP<4>")
	)
	(segment
		(start 382.53924 -133.800596)
		(end 382.88214 -133.800596)
		(width 0.1143)
		(layer "In2.Cu")
		(net "SATA6G_PCH_PCIE_UP_SATA_TXP<4>")
	)
	(segment
		(start 404.066502 -139.804394)
		(end 404.159974 -139.710922)
		(width 0.1143)
		(layer "In2.Cu")
		(net "SATA6G_PCH_PCIE_UP_SATA_TXP<4>")
	)
	(segment
		(start 400.917918 -137.935716)
		(end 401.160234 -138.178286)
		(width 0.1143)
		(layer "In2.Cu")
		(net "SATA6G_PCH_PCIE_UP_SATA_TXP<4>")
	)
	(segment
		(start 397.704564 -137.05205)
		(end 397.704564 -137.021062)
		(width 0.1143)
		(layer "In2.Cu")
		(net "SATA6G_PCH_PCIE_UP_SATA_TXP<4>")
	)
	(segment
		(start 396.078964 -137.05205)
		(end 396.078964 -137.021062)
		(width 0.1143)
		(layer "In2.Cu")
		(net "SATA6G_PCH_PCIE_UP_SATA_TXP<4>")
	)
	(segment
		(start 410.623766 -142.113254)
		(end 410.421836 -142.113254)
		(width 0.1143)
		(layer "In2.Cu")
		(net "SATA6G_PCH_PCIE_UP_SATA_TXP<4>")
	)
	(segment
		(start 400.308318 -137.559796)
		(end 400.567652 -137.81913)
		(width 0.1143)
		(layer "In2.Cu")
		(net "SATA6G_PCH_PCIE_UP_SATA_TXP<4>")
	)
	(segment
		(start 394.453364 -137.05205)
		(end 394.453364 -137.021062)
		(width 0.1143)
		(layer "In2.Cu")
		(net "SATA6G_PCH_PCIE_UP_SATA_TXP<4>")
	)
	(segment
		(start 409.13558 -140.107416)
		(end 409.13558 -140.357352)
		(width 0.1143)
		(layer "In2.Cu")
		(net "SATA6G_PCH_PCIE_UP_SATA_TXP<4>")
	)
	(segment
		(start 411.046168 -143.437102)
		(end 411.046168 -143.629126)
		(width 0.1143)
		(layer "In2.Cu")
		(net "SATA6G_PCH_PCIE_UP_SATA_TXP<4>")
	)
	(segment
		(start 381.32893 -133.592824)
		(end 381.58547 -133.849364)
		(width 0.1143)
		(layer "In2.Cu")
		(net "SATA6G_PCH_PCIE_UP_SATA_TXP<4>")
	)
	(segment
		(start 381.86614 -133.965696)
		(end 382.20904 -133.965696)
		(width 0.1143)
		(layer "In2.Cu")
		(net "SATA6G_PCH_PCIE_UP_SATA_TXP<4>")
	)
	(segment
		(start 401.93087 -138.948922)
		(end 402.17344 -139.191492)
		(width 0.1143)
		(layer "In2.Cu")
		(net "SATA6G_PCH_PCIE_UP_SATA_TXP<4>")
	)
	(segment
		(start 398.809464 -137.021062)
		(end 398.809464 -137.05205)
		(width 0.1143)
		(layer "In2.Cu")
		(net "SATA6G_PCH_PCIE_UP_SATA_TXP<4>")
	)
	(segment
		(start 403.946868 -143.733012)
		(end 403.946868 -140.092684)
		(width 0.1143)
		(layer "In2.Cu")
		(net "SATA6G_PCH_PCIE_UP_SATA_TXP<4>")
	)
	(segment
		(start 393.932664 -137.021062)
		(end 393.932664 -137.05205)
		(width 0.1143)
		(layer "In2.Cu")
		(net "SATA6G_PCH_PCIE_UP_SATA_TXP<4>")
	)
	(segment
		(start 397.183864 -137.021062)
		(end 397.183864 -137.05205)
		(width 0.1143)
		(layer "In2.Cu")
		(net "SATA6G_PCH_PCIE_UP_SATA_TXP<4>")
	)
	(segment
		(start 410.161486 -142.373604)
		(end 410.161486 -142.55242)
		(width 0.1143)
		(layer "In2.Cu")
		(net "SATA6G_PCH_PCIE_UP_SATA_TXP<4>")
	)
	(segment
		(start 403.598634 -143.96085)
		(end 403.718776 -143.96085)
		(width 0.1143)
		(layer "In2.Cu")
		(net "SATA6G_PCH_PCIE_UP_SATA_TXP<4>")
	)
	(segment
		(start 388.873238 -137.3124)
		(end 389.316214 -137.3124)
		(width 0.1143)
		(layer "In2.Cu")
		(net "SATA6G_PCH_PCIE_UP_SATA_TXP<4>")
	)
	(segment
		(start 381.09271 -133.356858)
		(end 381.328676 -133.592824)
		(width 0.1143)
		(layer "In2.Cu")
		(net "SATA6G_PCH_PCIE_UP_SATA_TXP<4>")
	)
	(segment
		(start 409.363672 -140.585444)
		(end 409.395168 -140.585444)
		(width 0.1143)
		(layer "In2.Cu")
		(net "SATA6G_PCH_PCIE_UP_SATA_TXP<4>")
	)
	(segment
		(start 403.416008 -143.87322)
		(end 403.43582 -143.893032)
		(width 0.1143)
		(layer "In2.Cu")
		(net "SATA6G_PCH_PCIE_UP_SATA_TXP<4>")
	)
	(segment
		(start 395.558264 -137.021062)
		(end 395.558264 -137.05205)
		(width 0.1143)
		(layer "In2.Cu")
		(net "SATA6G_PCH_PCIE_UP_SATA_TXP<4>")
	)
	(segment
		(start 399.069814 -137.3124)
		(end 399.710402 -137.3124)
		(width 0.1143)
		(layer "In2.Cu")
		(net "SATA6G_PCH_PCIE_UP_SATA_TXP<4>")
	)
	(segment
		(start 381.16637 -131.094988)
		(end 381.061468 -131.19989)
		(width 0.1143)
		(layer "In2.Cu")
		(net "SATA6G_PCH_PCIE_UP_SATA_TXP<4>")
	)
	(segment
		(start 381.328676 -133.592824)
		(end 381.32893 -133.592824)
		(width 0.1143)
		(layer "In2.Cu")
		(net "SATA6G_PCH_PCIE_UP_SATA_TXP<4>")
	)
	(segment
		(start 409.826206 -140.76426)
		(end 410.035502 -140.973556)
		(width 0.1143)
		(layer "In2.Cu")
		(net "SATA6G_PCH_PCIE_UP_SATA_TXP<4>")
	)
	(segment
		(start 403.865842 -143.899636)
		(end 403.885654 -143.879824)
		(width 0.1143)
		(layer "In2.Cu")
		(net "SATA6G_PCH_PCIE_UP_SATA_TXP<4>")
	)
	(segment
		(start 390.681464 -137.000742)
		(end 390.681464 -137.05205)
		(width 0.1143)
		(layer "In2.Cu")
		(net "SATA6G_PCH_PCIE_UP_SATA_TXP<4>")
	)
	(arc
		(start 397.704564 -137.021062)
		(mid 398.257014 -136.468612)
		(end 398.809464 -137.021062)
		(width 0.1143)
		(layer "In2.Cu")
		(net "SATA6G_PCH_PCIE_UP_SATA_TXP<4>")
	)
	(arc
		(start 395.558264 -137.05205)
		(mid 395.818614 -137.3124)
		(end 396.078964 -137.05205)
		(width 0.1143)
		(layer "In2.Cu")
		(net "SATA6G_PCH_PCIE_UP_SATA_TXP<4>")
	)
	(arc
		(start 388.670546 -137.228326)
		(mid 388.763527 -137.290547)
		(end 388.873238 -137.3124)
		(width 0.1143)
		(layer "In2.Cu")
		(net "SATA6G_PCH_PCIE_UP_SATA_TXP<4>")
	)
	(arc
		(start 401.160234 -138.178286)
		(mid 401.209093 -138.259233)
		(end 401.218654 -138.353292)
		(width 0.1143)
		(layer "In2.Cu")
		(net "SATA6G_PCH_PCIE_UP_SATA_TXP<4>")
	)
	(arc
		(start 403.885654 -143.879824)
		(mid 403.930881 -143.81251)
		(end 403.946868 -143.733012)
		(width 0.1143)
		(layer "In2.Cu")
		(net "SATA6G_PCH_PCIE_UP_SATA_TXP<4>")
	)
	(arc
		(start 403.087332 -140.33881)
		(mid 403.280369 -140.627572)
		(end 403.34819 -140.968222)
		(width 0.1143)
		(layer "In2.Cu")
		(net "SATA6G_PCH_PCIE_UP_SATA_TXP<4>")
	)
	(arc
		(start 397.183864 -137.05205)
		(mid 397.444214 -137.3124)
		(end 397.704564 -137.05205)
		(width 0.1143)
		(layer "In2.Cu")
		(net "SATA6G_PCH_PCIE_UP_SATA_TXP<4>")
	)
	(arc
		(start 410.421836 -142.113254)
		(mid 410.237741 -142.189509)
		(end 410.161486 -142.373604)
		(width 0.1143)
		(layer "In2.Cu")
		(net "SATA6G_PCH_PCIE_UP_SATA_TXP<4>")
	)
	(arc
		(start 408.575256 -139.547092)
		(mid 408.971465 -139.711207)
		(end 409.13558 -140.107416)
		(width 0.1143)
		(layer "In2.Cu")
		(net "SATA6G_PCH_PCIE_UP_SATA_TXP<4>")
	)
	(arc
		(start 382.37414 -133.883146)
		(mid 382.447421 -133.82332)
		(end 382.53924 -133.800596)
		(width 0.1143)
		(layer "In2.Cu")
		(net "SATA6G_PCH_PCIE_UP_SATA_TXP<4>")
	)
	(arc
		(start 382.88214 -133.800596)
		(mid 382.973937 -133.823364)
		(end 383.04724 -133.883146)
		(width 0.1143)
		(layer "In2.Cu")
		(net "SATA6G_PCH_PCIE_UP_SATA_TXP<4>")
	)
	(arc
		(start 405.77643 -140.086842)
		(mid 406.31618 -139.547092)
		(end 406.85593 -140.086842)
		(width 0.1143)
		(layer "In2.Cu")
		(net "SATA6G_PCH_PCIE_UP_SATA_TXP<4>")
	)
	(arc
		(start 390.139428 -136.458706)
		(mid 390.522705 -136.617465)
		(end 390.681464 -137.000742)
		(width 0.1143)
		(layer "In2.Cu")
		(net "SATA6G_PCH_PCIE_UP_SATA_TXP<4>")
	)
	(arc
		(start 403.34819 -143.710406)
		(mid 403.365859 -143.798583)
		(end 403.416008 -143.87322)
		(width 0.1143)
		(layer "In2.Cu")
		(net "SATA6G_PCH_PCIE_UP_SATA_TXP<4>")
	)
	(arc
		(start 402.23186 -139.366498)
		(mid 402.241325 -139.460521)
		(end 402.290026 -139.541504)
		(width 0.1143)
		(layer "In2.Cu")
		(net "SATA6G_PCH_PCIE_UP_SATA_TXP<4>")
	)
	(arc
		(start 389.576564 -137.021062)
		(mid 389.741274 -136.623416)
		(end 390.13892 -136.458706)
		(width 0.1143)
		(layer "In2.Cu")
		(net "SATA6G_PCH_PCIE_UP_SATA_TXP<4>")
	)
	(arc
		(start 392.827764 -137.021062)
		(mid 393.380214 -136.468612)
		(end 393.932664 -137.021062)
		(width 0.1143)
		(layer "In2.Cu")
		(net "SATA6G_PCH_PCIE_UP_SATA_TXP<4>")
	)
	(arc
		(start 393.932664 -137.05205)
		(mid 394.193014 -137.3124)
		(end 394.453364 -137.05205)
		(width 0.1143)
		(layer "In2.Cu")
		(net "SATA6G_PCH_PCIE_UP_SATA_TXP<4>")
	)
	(arc
		(start 410.66847 -141.008354)
		(mid 411.02747 -141.156741)
		(end 411.176216 -141.515592)
		(width 0.1143)
		(layer "In2.Cu")
		(net "SATA6G_PCH_PCIE_UP_SATA_TXP<4>")
	)
	(arc
		(start 384.439922 -133.800596)
		(mid 384.531719 -133.823364)
		(end 384.605022 -133.883146)
		(width 0.1143)
		(layer "In2.Cu")
		(net "SATA6G_PCH_PCIE_UP_SATA_TXP<4>")
	)
	(arc
		(start 390.681464 -137.05205)
		(mid 390.941814 -137.3124)
		(end 391.202164 -137.05205)
		(width 0.1143)
		(layer "In2.Cu")
		(net "SATA6G_PCH_PCIE_UP_SATA_TXP<4>")
	)
	(arc
		(start 383.04724 -133.883146)
		(mid 383.120521 -133.942972)
		(end 383.21234 -133.965696)
		(width 0.1143)
		(layer "In2.Cu")
		(net "SATA6G_PCH_PCIE_UP_SATA_TXP<4>")
	)
	(arc
		(start 404.159974 -139.710922)
		(mid 404.341249 -139.589604)
		(end 404.555198 -139.547092)
		(width 0.1143)
		(layer "In2.Cu")
		(net "SATA6G_PCH_PCIE_UP_SATA_TXP<4>")
	)
	(arc
		(start 383.931922 -133.883146)
		(mid 384.005203 -133.82332)
		(end 384.097022 -133.800596)
		(width 0.1143)
		(layer "In2.Cu")
		(net "SATA6G_PCH_PCIE_UP_SATA_TXP<4>")
	)
	(arc
		(start 400.742658 -137.87755)
		(mid 400.836825 -137.886946)
		(end 400.917918 -137.935716)
		(width 0.1143)
		(layer "In2.Cu")
		(net "SATA6G_PCH_PCIE_UP_SATA_TXP<4>")
	)
	(arc
		(start 383.766822 -133.965696)
		(mid 383.858619 -133.942928)
		(end 383.931922 -133.883146)
		(width 0.1143)
		(layer "In2.Cu")
		(net "SATA6G_PCH_PCIE_UP_SATA_TXP<4>")
	)
	(arc
		(start 411.176216 -141.560804)
		(mid 411.014407 -141.951445)
		(end 410.623766 -142.113254)
		(width 0.1143)
		(layer "In2.Cu")
		(net "SATA6G_PCH_PCIE_UP_SATA_TXP<4>")
	)
	(arc
		(start 394.453364 -137.021062)
		(mid 395.005814 -136.468612)
		(end 395.558264 -137.021062)
		(width 0.1143)
		(layer "In2.Cu")
		(net "SATA6G_PCH_PCIE_UP_SATA_TXP<4>")
	)
	(arc
		(start 396.078964 -137.021062)
		(mid 396.631414 -136.468612)
		(end 397.183864 -137.021062)
		(width 0.1143)
		(layer "In2.Cu")
		(net "SATA6G_PCH_PCIE_UP_SATA_TXP<4>")
	)
	(arc
		(start 404.74138 -139.547092)
		(mid 405.123041 -139.705181)
		(end 405.28113 -140.086842)
		(width 0.1143)
		(layer "In2.Cu")
		(net "SATA6G_PCH_PCIE_UP_SATA_TXP<4>")
	)
	(arc
		(start 403.43582 -143.893032)
		(mid 403.510476 -143.943135)
		(end 403.598634 -143.96085)
		(width 0.1143)
		(layer "In2.Cu")
		(net "SATA6G_PCH_PCIE_UP_SATA_TXP<4>")
	)
	(arc
		(start 381.02794 -133.200394)
		(mid 381.044765 -133.285071)
		(end 381.09271 -133.356858)
		(width 0.1143)
		(layer "In2.Cu")
		(net "SATA6G_PCH_PCIE_UP_SATA_TXP<4>")
	)
	(arc
		(start 409.395168 -140.585444)
		(mid 409.628381 -140.632175)
		(end 409.826206 -140.76426)
		(width 0.1143)
		(layer "In2.Cu")
		(net "SATA6G_PCH_PCIE_UP_SATA_TXP<4>")
	)
	(arc
		(start 385.113022 -133.965696)
		(mid 385.385208 -134.019609)
		(end 385.615942 -134.173722)
		(width 0.1143)
		(layer "In2.Cu")
		(net "SATA6G_PCH_PCIE_UP_SATA_TXP<4>")
	)
	(arc
		(start 407.35123 -140.086842)
		(mid 407.509319 -139.705181)
		(end 407.89098 -139.547092)
		(width 0.1143)
		(layer "In2.Cu")
		(net "SATA6G_PCH_PCIE_UP_SATA_TXP<4>")
	)
	(arc
		(start 403.946868 -140.092684)
		(mid 403.977896 -139.936581)
		(end 404.066502 -139.804394)
		(width 0.1143)
		(layer "In2.Cu")
		(net "SATA6G_PCH_PCIE_UP_SATA_TXP<4>")
	)
	(arc
		(start 410.035502 -140.973556)
		(mid 410.072414 -140.998406)
		(end 410.11602 -141.007338)
		(width 0.1143)
		(layer "In2.Cu")
		(net "SATA6G_PCH_PCIE_UP_SATA_TXP<4>")
	)
	(arc
		(start 389.316214 -137.3124)
		(mid 389.500309 -137.236145)
		(end 389.576564 -137.05205)
		(width 0.1143)
		(layer "In2.Cu")
		(net "SATA6G_PCH_PCIE_UP_SATA_TXP<4>")
	)
	(arc
		(start 411.566868 -142.209774)
		(mid 411.804857 -141.635217)
		(end 412.379414 -141.397228)
		(width 0.1143)
		(layer "In2.Cu")
		(net "SATA6G_PCH_PCIE_UP_SATA_TXP<4>")
	)
	(arc
		(start 410.161486 -142.55242)
		(mid 410.237741 -142.736515)
		(end 410.421836 -142.81277)
		(width 0.1143)
		(layer "In2.Cu")
		(net "SATA6G_PCH_PCIE_UP_SATA_TXP<4>")
	)
	(arc
		(start 412.659576 -141.397228)
		(mid 412.740398 -141.36375)
		(end 412.773876 -141.282928)
		(width 0.1143)
		(layer "In2.Cu")
		(net "SATA6G_PCH_PCIE_UP_SATA_TXP<4>")
	)
	(arc
		(start 398.809464 -137.05205)
		(mid 398.885719 -137.236145)
		(end 399.069814 -137.3124)
		(width 0.1143)
		(layer "In2.Cu")
		(net "SATA6G_PCH_PCIE_UP_SATA_TXP<4>")
	)
	(arc
		(start 381.58547 -133.849364)
		(mid 381.714228 -133.935461)
		(end 381.86614 -133.965696)
		(width 0.1143)
		(layer "In2.Cu")
		(net "SATA6G_PCH_PCIE_UP_SATA_TXP<4>")
	)
	(arc
		(start 403.718776 -143.96085)
		(mid 403.798399 -143.944882)
		(end 403.865842 -143.899636)
		(width 0.1143)
		(layer "In2.Cu")
		(net "SATA6G_PCH_PCIE_UP_SATA_TXP<4>")
	)
	(arc
		(start 410.421836 -142.81277)
		(mid 410.863305 -142.995633)
		(end 411.046168 -143.437102)
		(width 0.1143)
		(layer "In2.Cu")
		(net "SATA6G_PCH_PCIE_UP_SATA_TXP<4>")
	)
	(arc
		(start 411.046168 -143.629126)
		(mid 411.306518 -143.889476)
		(end 411.566868 -143.629126)
		(width 0.1143)
		(layer "In2.Cu")
		(net "SATA6G_PCH_PCIE_UP_SATA_TXP<4>")
	)
	(arc
		(start 384.605022 -133.883146)
		(mid 384.678303 -133.942972)
		(end 384.770122 -133.965696)
		(width 0.1143)
		(layer "In2.Cu")
		(net "SATA6G_PCH_PCIE_UP_SATA_TXP<4>")
	)
	(arc
		(start 409.13558 -140.357352)
		(mid 409.202387 -140.518637)
		(end 409.363672 -140.585444)
		(width 0.1143)
		(layer "In2.Cu")
		(net "SATA6G_PCH_PCIE_UP_SATA_TXP<4>")
	)
	(arc
		(start 401.580604 -138.832082)
		(mid 401.661671 -138.880981)
		(end 401.755864 -138.890502)
		(width 0.1143)
		(layer "In2.Cu")
		(net "SATA6G_PCH_PCIE_UP_SATA_TXP<4>")
	)
	(arc
		(start 401.218654 -138.353292)
		(mid 401.228175 -138.447485)
		(end 401.277074 -138.528552)
		(width 0.1143)
		(layer "In2.Cu")
		(net "SATA6G_PCH_PCIE_UP_SATA_TXP<4>")
	)
	(arc
		(start 405.28113 -140.88745)
		(mid 405.52878 -141.1351)
		(end 405.77643 -140.88745)
		(width 0.1143)
		(layer "In2.Cu")
		(net "SATA6G_PCH_PCIE_UP_SATA_TXP<4>")
	)
	(arc
		(start 401.755864 -138.890502)
		(mid 401.849913 -138.900092)
		(end 401.93087 -138.948922)
		(width 0.1143)
		(layer "In2.Cu")
		(net "SATA6G_PCH_PCIE_UP_SATA_TXP<4>")
	)
	(arc
		(start 391.202164 -137.021062)
		(mid 391.754614 -136.468612)
		(end 392.307064 -137.021062)
		(width 0.1143)
		(layer "In2.Cu")
		(net "SATA6G_PCH_PCIE_UP_SATA_TXP<4>")
	)
	(arc
		(start 399.710402 -137.3124)
		(mid 400.033943 -137.376663)
		(end 400.308318 -137.559796)
		(width 0.1143)
		(layer "In2.Cu")
		(net "SATA6G_PCH_PCIE_UP_SATA_TXP<4>")
	)
	(arc
		(start 406.85593 -140.88745)
		(mid 407.10358 -141.1351)
		(end 407.35123 -140.88745)
		(width 0.1143)
		(layer "In2.Cu")
		(net "SATA6G_PCH_PCIE_UP_SATA_TXP<4>")
	)
	(arc
		(start 392.307064 -137.021062)
		(mid 392.567414 -137.281412)
		(end 392.827764 -137.021062)
		(width 0.1143)
		(layer "In2.Cu")
		(net "SATA6G_PCH_PCIE_UP_SATA_TXP<4>")
	)
	(arc
		(start 381.061468 -131.19989)
		(mid 381.036706 -131.236949)
		(end 381.02794 -131.280662)
		(width 0.1143)
		(layer "In2.Cu")
		(net "SATA6G_PCH_PCIE_UP_SATA_TXP<4>")
	)
	(arc
		(start 400.567652 -137.81913)
		(mid 400.648599 -137.867989)
		(end 400.742658 -137.87755)
		(width 0.1143)
		(layer "In2.Cu")
		(net "SATA6G_PCH_PCIE_UP_SATA_TXP<4>")
	)
	(arc
		(start 382.20904 -133.965696)
		(mid 382.300837 -133.942928)
		(end 382.37414 -133.883146)
		(width 0.1143)
		(layer "In2.Cu")
		(net "SATA6G_PCH_PCIE_UP_SATA_TXP<4>")
	)
	(arc
		(start 402.17344 -139.191492)
		(mid 402.222299 -139.272439)
		(end 402.23186 -139.366498)
		(width 0.1143)
		(layer "In2.Cu")
		(net "SATA6G_PCH_PCIE_UP_SATA_TXP<4>")
	)
	(segment
		(start 381.493522 -128.83261)
		(end 381.493522 -129.054606)
		(width 0.0889)
		(layer "F.Cu")
		(net "SATA6G_PCH_PCIE_UP_SATA_TXP<3>")
	)
	(segment
		(start 381.404622 -129.143506)
		(end 381.273558 -129.143506)
		(width 0.0889)
		(layer "F.Cu")
		(net "SATA6G_PCH_PCIE_UP_SATA_TXP<3>")
	)
	(segment
		(start 380.89967 -126.250446)
		(end 380.89967 -126.517146)
		(width 0.0889)
		(layer "F.Cu")
		(net "SATA6G_PCH_PCIE_UP_SATA_TXP<3>")
	)
	(segment
		(start 381.273558 -129.143506)
		(end 381.222758 -129.092706)
		(width 0.0889)
		(layer "F.Cu")
		(net "SATA6G_PCH_PCIE_UP_SATA_TXP<3>")
	)
	(segment
		(start 380.98857 -128.69291)
		(end 381.353822 -128.69291)
		(width 0.0889)
		(layer "F.Cu")
		(net "SATA6G_PCH_PCIE_UP_SATA_TXP<3>")
	)
	(segment
		(start 380.98857 -126.694946)
		(end 380.98857 -126.961646)
		(width 0.0889)
		(layer "F.Cu")
		(net "SATA6G_PCH_PCIE_UP_SATA_TXP<3>")
	)
	(segment
		(start 380.985014 -126.165102)
		(end 380.89967 -126.250446)
		(width 0.0889)
		(layer "F.Cu")
		(net "SATA6G_PCH_PCIE_UP_SATA_TXP<3>")
	)
	(segment
		(start 380.89967 -128.028446)
		(end 380.89967 -128.60401)
		(width 0.0889)
		(layer "F.Cu")
		(net "SATA6G_PCH_PCIE_UP_SATA_TXP<3>")
	)
	(segment
		(start 380.98857 -127.583946)
		(end 380.98857 -127.850646)
		(width 0.0889)
		(layer "F.Cu")
		(net "SATA6G_PCH_PCIE_UP_SATA_TXP<3>")
	)
	(segment
		(start 380.89967 -127.139446)
		(end 380.89967 -127.406146)
		(width 0.0889)
		(layer "F.Cu")
		(net "SATA6G_PCH_PCIE_UP_SATA_TXP<3>")
	)
	(via
		(at 381.222758 -129.092706)
		(size 0.508)
		(drill 0.254)
		(layers "F.Cu" "B.Cu")
		(net "SATA6G_PCH_PCIE_UP_SATA_TXP<3>")
	)
	(via
		(at 419.777926 -146.9009)
		(size 0.508)
		(drill 0.254)
		(layers "F.Cu" "B.Cu")
		(net "SATA6G_PCH_PCIE_UP_SATA_TXP<3>")
	)
	(arc
		(start 380.94412 -127.495046)
		(mid 380.974541 -127.535402)
		(end 380.98857 -127.583946)
		(width 0.0889)
		(layer "F.Cu")
		(net "SATA6G_PCH_PCIE_UP_SATA_TXP<3>")
	)
	(arc
		(start 380.98857 -127.850646)
		(mid 380.974505 -127.899172)
		(end 380.94412 -127.939546)
		(width 0.0889)
		(layer "F.Cu")
		(net "SATA6G_PCH_PCIE_UP_SATA_TXP<3>")
	)
	(arc
		(start 380.89967 -127.406146)
		(mid 380.913735 -127.454672)
		(end 380.94412 -127.495046)
		(width 0.0889)
		(layer "F.Cu")
		(net "SATA6G_PCH_PCIE_UP_SATA_TXP<3>")
	)
	(arc
		(start 380.94412 -127.050546)
		(mid 380.913699 -127.090902)
		(end 380.89967 -127.139446)
		(width 0.0889)
		(layer "F.Cu")
		(net "SATA6G_PCH_PCIE_UP_SATA_TXP<3>")
	)
	(arc
		(start 380.89967 -126.517146)
		(mid 380.913735 -126.565672)
		(end 380.94412 -126.606046)
		(width 0.0889)
		(layer "F.Cu")
		(net "SATA6G_PCH_PCIE_UP_SATA_TXP<3>")
	)
	(arc
		(start 380.98857 -126.961646)
		(mid 380.974505 -127.010172)
		(end 380.94412 -127.050546)
		(width 0.0889)
		(layer "F.Cu")
		(net "SATA6G_PCH_PCIE_UP_SATA_TXP<3>")
	)
	(arc
		(start 381.493522 -129.054606)
		(mid 381.467484 -129.117468)
		(end 381.404622 -129.143506)
		(width 0.0889)
		(layer "F.Cu")
		(net "SATA6G_PCH_PCIE_UP_SATA_TXP<3>")
	)
	(arc
		(start 380.94412 -127.939546)
		(mid 380.913699 -127.979902)
		(end 380.89967 -128.028446)
		(width 0.0889)
		(layer "F.Cu")
		(net "SATA6G_PCH_PCIE_UP_SATA_TXP<3>")
	)
	(arc
		(start 380.89967 -128.60401)
		(mid 380.925708 -128.666872)
		(end 380.98857 -128.69291)
		(width 0.0889)
		(layer "F.Cu")
		(net "SATA6G_PCH_PCIE_UP_SATA_TXP<3>")
	)
	(arc
		(start 381.353822 -128.69291)
		(mid 381.452605 -128.733827)
		(end 381.493522 -128.83261)
		(width 0.0889)
		(layer "F.Cu")
		(net "SATA6G_PCH_PCIE_UP_SATA_TXP<3>")
	)
	(arc
		(start 380.94412 -126.606046)
		(mid 380.974541 -126.646402)
		(end 380.98857 -126.694946)
		(width 0.0889)
		(layer "F.Cu")
		(net "SATA6G_PCH_PCIE_UP_SATA_TXP<3>")
	)
	(segment
		(start 419.777926 -146.9009)
		(end 419.777926 -147.14855)
		(width 0.1143)
		(layer "B.Cu")
		(net "SATA6G_PCH_PCIE_UP_SATA_TXP<3>")
	)
	(segment
		(start 419.892226 -147.26285)
		(end 420.252906 -147.26285)
		(width 0.1143)
		(layer "B.Cu")
		(net "SATA6G_PCH_PCIE_UP_SATA_TXP<3>")
	)
	(segment
		(start 420.333678 -147.229322)
		(end 420.624 -146.939)
		(width 0.1143)
		(layer "B.Cu")
		(net "SATA6G_PCH_PCIE_UP_SATA_TXP<3>")
	)
	(arc
		(start 420.252906 -147.26285)
		(mid 420.296647 -147.254149)
		(end 420.333678 -147.229322)
		(width 0.1143)
		(layer "B.Cu")
		(net "SATA6G_PCH_PCIE_UP_SATA_TXP<3>")
	)
	(arc
		(start 419.777926 -147.14855)
		(mid 419.811404 -147.229372)
		(end 419.892226 -147.26285)
		(width 0.1143)
		(layer "B.Cu")
		(net "SATA6G_PCH_PCIE_UP_SATA_TXP<3>")
	)
	(segment
		(start 387.490208 -134.687056)
		(end 387.732778 -134.929626)
		(width 0.1143)
		(layer "In2.Cu")
		(net "SATA6G_PCH_PCIE_UP_SATA_TXP<3>")
	)
	(segment
		(start 415.81705 -146.343624)
		(end 418.829998 -146.343624)
		(width 0.1143)
		(layer "In2.Cu")
		(net "SATA6G_PCH_PCIE_UP_SATA_TXP<3>")
	)
	(segment
		(start 381.151638 -129.556256)
		(end 381.681482 -129.556256)
		(width 0.1143)
		(layer "In2.Cu")
		(net "SATA6G_PCH_PCIE_UP_SATA_TXP<3>")
	)
	(segment
		(start 410.698442 -140.163042)
		(end 413.098996 -140.163042)
		(width 0.1143)
		(layer "In2.Cu")
		(net "SATA6G_PCH_PCIE_UP_SATA_TXP<3>")
	)
	(segment
		(start 381.02413 -129.338578)
		(end 381.02413 -129.428748)
		(width 0.1143)
		(layer "In2.Cu")
		(net "SATA6G_PCH_PCIE_UP_SATA_TXP<3>")
	)
	(segment
		(start 381.222758 -129.092706)
		(end 381.057658 -129.257806)
		(width 0.1143)
		(layer "In2.Cu")
		(net "SATA6G_PCH_PCIE_UP_SATA_TXP<3>")
	)
	(segment
		(start 382.084072 -132.055362)
		(end 382.991614 -132.962904)
		(width 0.1143)
		(layer "In2.Cu")
		(net "SATA6G_PCH_PCIE_UP_SATA_TXP<3>")
	)
	(segment
		(start 400.12747 -135.915908)
		(end 402.729954 -138.518392)
		(width 0.1143)
		(layer "In2.Cu")
		(net "SATA6G_PCH_PCIE_UP_SATA_TXP<3>")
	)
	(segment
		(start 413.680148 -140.744194)
		(end 413.680148 -141.312138)
		(width 0.1143)
		(layer "In2.Cu")
		(net "SATA6G_PCH_PCIE_UP_SATA_TXP<3>")
	)
	(segment
		(start 419.4937 -142.43558)
		(end 419.4937 -145.078196)
		(width 0.1143)
		(layer "In2.Cu")
		(net "SATA6G_PCH_PCIE_UP_SATA_TXP<3>")
	)
	(segment
		(start 419.777926 -147.21332)
		(end 419.777926 -146.9009)
		(width 0.1143)
		(layer "In2.Cu")
		(net "SATA6G_PCH_PCIE_UP_SATA_TXP<3>")
	)
	(segment
		(start 409.368244 -138.954764)
		(end 410.490162 -140.076682)
		(width 0.1143)
		(layer "In2.Cu")
		(net "SATA6G_PCH_PCIE_UP_SATA_TXP<3>")
	)
	(segment
		(start 383.07264 -132.996432)
		(end 385.397756 -132.996432)
		(width 0.1143)
		(layer "In2.Cu")
		(net "SATA6G_PCH_PCIE_UP_SATA_TXP<3>")
	)
	(segment
		(start 381.97409 -130.969766)
		(end 381.97409 -131.790186)
		(width 0.1143)
		(layer "In2.Cu")
		(net "SATA6G_PCH_PCIE_UP_SATA_TXP<3>")
	)
	(segment
		(start 419.45941 -147.32762)
		(end 419.663626 -147.32762)
		(width 0.1143)
		(layer "In2.Cu")
		(net "SATA6G_PCH_PCIE_UP_SATA_TXP<3>")
	)
	(segment
		(start 382.216406 -130.67919)
		(end 382.008634 -130.886962)
		(width 0.1143)
		(layer "In2.Cu")
		(net "SATA6G_PCH_PCIE_UP_SATA_TXP<3>")
	)
	(segment
		(start 415.653982 -141.734286)
		(end 416.166808 -141.734286)
		(width 0.1143)
		(layer "In2.Cu")
		(net "SATA6G_PCH_PCIE_UP_SATA_TXP<3>")
	)
	(segment
		(start 386.897626 -134.3279)
		(end 387.140196 -134.57047)
		(width 0.1143)
		(layer "In2.Cu")
		(net "SATA6G_PCH_PCIE_UP_SATA_TXP<3>")
	)
	(segment
		(start 382.335278 -130.250438)
		(end 382.335278 -130.391408)
		(width 0.1143)
		(layer "In2.Cu")
		(net "SATA6G_PCH_PCIE_UP_SATA_TXP<3>")
	)
	(segment
		(start 413.826706 -141.66596)
		(end 414.236916 -142.07617)
		(width 0.1143)
		(layer "In2.Cu")
		(net "SATA6G_PCH_PCIE_UP_SATA_TXP<3>")
	)
	(segment
		(start 387.849618 -135.279892)
		(end 388.010908 -135.441182)
		(width 0.1143)
		(layer "In2.Cu")
		(net "SATA6G_PCH_PCIE_UP_SATA_TXP<3>")
	)
	(segment
		(start 415.075116 -142.548102)
		(end 415.075116 -142.313152)
		(width 0.1143)
		(layer "In2.Cu")
		(net "SATA6G_PCH_PCIE_UP_SATA_TXP<3>")
	)
	(segment
		(start 385.685284 -133.115558)
		(end 386.188204 -133.618478)
		(width 0.1143)
		(layer "In2.Cu")
		(net "SATA6G_PCH_PCIE_UP_SATA_TXP<3>")
	)
	(segment
		(start 418.748972 -145.822924)
		(end 415.81705 -145.822924)
		(width 0.1143)
		(layer "In2.Cu")
		(net "SATA6G_PCH_PCIE_UP_SATA_TXP<3>")
	)
	(segment
		(start 403.283674 -138.748008)
		(end 408.868118 -138.748008)
		(width 0.1143)
		(layer "In2.Cu")
		(net "SATA6G_PCH_PCIE_UP_SATA_TXP<3>")
	)
	(segment
		(start 382.014476 -129.693924)
		(end 382.169162 -129.84861)
		(width 0.1143)
		(layer "In2.Cu")
		(net "SATA6G_PCH_PCIE_UP_SATA_TXP<3>")
	)
	(segment
		(start 417.24199 -142.620746)
		(end 417.24199 -142.303754)
		(width 0.1143)
		(layer "In2.Cu")
		(net "SATA6G_PCH_PCIE_UP_SATA_TXP<3>")
	)
	(segment
		(start 417.811458 -141.734286)
		(end 418.792406 -141.734286)
		(width 0.1143)
		(layer "In2.Cu")
		(net "SATA6G_PCH_PCIE_UP_SATA_TXP<3>")
	)
	(segment
		(start 388.515606 -135.650224)
		(end 399.48612 -135.650224)
		(width 0.1143)
		(layer "In2.Cu")
		(net "SATA6G_PCH_PCIE_UP_SATA_TXP<3>")
	)
	(segment
		(start 386.538216 -133.735064)
		(end 386.780786 -133.977634)
		(width 0.1143)
		(layer "In2.Cu")
		(net "SATA6G_PCH_PCIE_UP_SATA_TXP<3>")
	)
	(segment
		(start 416.72129 -142.288768)
		(end 416.72129 -142.620746)
		(width 0.1143)
		(layer "In2.Cu")
		(net "SATA6G_PCH_PCIE_UP_SATA_TXP<3>")
	)
	(segment
		(start 419.2651 -146.778726)
		(end 419.2651 -147.13331)
		(width 0.1143)
		(layer "In2.Cu")
		(net "SATA6G_PCH_PCIE_UP_SATA_TXP<3>")
	)
	(segment
		(start 414.418272 -142.514066)
		(end 414.418272 -142.548102)
		(width 0.1143)
		(layer "In2.Cu")
		(net "SATA6G_PCH_PCIE_UP_SATA_TXP<3>")
	)
	(arc
		(start 388.010908 -135.441182)
		(mid 388.242465 -135.595904)
		(end 388.515606 -135.650224)
		(width 0.1143)
		(layer "In2.Cu")
		(net "SATA6G_PCH_PCIE_UP_SATA_TXP<3>")
	)
	(arc
		(start 416.166808 -141.734286)
		(mid 416.558886 -141.89669)
		(end 416.72129 -142.288768)
		(width 0.1143)
		(layer "In2.Cu")
		(net "SATA6G_PCH_PCIE_UP_SATA_TXP<3>")
	)
	(arc
		(start 408.868118 -138.748008)
		(mid 409.138737 -138.80165)
		(end 409.368244 -138.954764)
		(width 0.1143)
		(layer "In2.Cu")
		(net "SATA6G_PCH_PCIE_UP_SATA_TXP<3>")
	)
	(arc
		(start 418.829998 -146.343624)
		(mid 419.137662 -146.471062)
		(end 419.2651 -146.778726)
		(width 0.1143)
		(layer "In2.Cu")
		(net "SATA6G_PCH_PCIE_UP_SATA_TXP<3>")
	)
	(arc
		(start 386.188204 -133.618478)
		(mid 386.269185 -133.667187)
		(end 386.36321 -133.676644)
		(width 0.1143)
		(layer "In2.Cu")
		(net "SATA6G_PCH_PCIE_UP_SATA_TXP<3>")
	)
	(arc
		(start 387.315202 -134.628636)
		(mid 387.409251 -134.638226)
		(end 387.490208 -134.687056)
		(width 0.1143)
		(layer "In2.Cu")
		(net "SATA6G_PCH_PCIE_UP_SATA_TXP<3>")
	)
	(arc
		(start 415.81705 -145.822924)
		(mid 415.5567 -146.083274)
		(end 415.81705 -146.343624)
		(width 0.1143)
		(layer "In2.Cu")
		(net "SATA6G_PCH_PCIE_UP_SATA_TXP<3>")
	)
	(arc
		(start 419.440614 -147.326604)
		(mid 419.45 -147.327337)
		(end 419.45941 -147.32762)
		(width 0.1143)
		(layer "In2.Cu")
		(net "SATA6G_PCH_PCIE_UP_SATA_TXP<3>")
	)
	(arc
		(start 385.397756 -132.996432)
		(mid 385.553376 -133.027387)
		(end 385.685284 -133.115558)
		(width 0.1143)
		(layer "In2.Cu")
		(net "SATA6G_PCH_PCIE_UP_SATA_TXP<3>")
	)
	(arc
		(start 417.24199 -142.303754)
		(mid 417.408783 -141.901079)
		(end 417.811458 -141.734286)
		(width 0.1143)
		(layer "In2.Cu")
		(net "SATA6G_PCH_PCIE_UP_SATA_TXP<3>")
	)
	(arc
		(start 414.236916 -142.07617)
		(mid 414.371159 -142.277078)
		(end 414.418272 -142.514066)
		(width 0.1143)
		(layer "In2.Cu")
		(net "SATA6G_PCH_PCIE_UP_SATA_TXP<3>")
	)
	(arc
		(start 382.335278 -130.391408)
		(mid 382.304421 -130.547096)
		(end 382.216406 -130.67919)
		(width 0.1143)
		(layer "In2.Cu")
		(net "SATA6G_PCH_PCIE_UP_SATA_TXP<3>")
	)
	(arc
		(start 381.02413 -129.428748)
		(mid 381.061476 -129.51891)
		(end 381.151638 -129.556256)
		(width 0.1143)
		(layer "In2.Cu")
		(net "SATA6G_PCH_PCIE_UP_SATA_TXP<3>")
	)
	(arc
		(start 382.991614 -132.962904)
		(mid 383.028789 -132.987744)
		(end 383.07264 -132.996432)
		(width 0.1143)
		(layer "In2.Cu")
		(net "SATA6G_PCH_PCIE_UP_SATA_TXP<3>")
	)
	(arc
		(start 387.791198 -135.104632)
		(mid 387.800719 -135.198825)
		(end 387.849618 -135.279892)
		(width 0.1143)
		(layer "In2.Cu")
		(net "SATA6G_PCH_PCIE_UP_SATA_TXP<3>")
	)
	(arc
		(start 381.97409 -131.790186)
		(mid 382.002662 -131.933739)
		(end 382.084072 -132.055362)
		(width 0.1143)
		(layer "In2.Cu")
		(net "SATA6G_PCH_PCIE_UP_SATA_TXP<3>")
	)
	(arc
		(start 413.098996 -140.163042)
		(mid 413.509933 -140.333257)
		(end 413.680148 -140.744194)
		(width 0.1143)
		(layer "In2.Cu")
		(net "SATA6G_PCH_PCIE_UP_SATA_TXP<3>")
	)
	(arc
		(start 387.140196 -134.57047)
		(mid 387.221177 -134.619179)
		(end 387.315202 -134.628636)
		(width 0.1143)
		(layer "In2.Cu")
		(net "SATA6G_PCH_PCIE_UP_SATA_TXP<3>")
	)
	(arc
		(start 415.075116 -142.313152)
		(mid 415.244662 -141.903832)
		(end 415.653982 -141.734286)
		(width 0.1143)
		(layer "In2.Cu")
		(net "SATA6G_PCH_PCIE_UP_SATA_TXP<3>")
	)
	(arc
		(start 386.780786 -133.977634)
		(mid 386.829645 -134.058581)
		(end 386.839206 -134.15264)
		(width 0.1143)
		(layer "In2.Cu")
		(net "SATA6G_PCH_PCIE_UP_SATA_TXP<3>")
	)
	(arc
		(start 418.792406 -141.734286)
		(mid 419.288296 -141.93969)
		(end 419.4937 -142.43558)
		(width 0.1143)
		(layer "In2.Cu")
		(net "SATA6G_PCH_PCIE_UP_SATA_TXP<3>")
	)
	(arc
		(start 410.490162 -140.076682)
		(mid 410.585707 -140.140587)
		(end 410.698442 -140.163042)
		(width 0.1143)
		(layer "In2.Cu")
		(net "SATA6G_PCH_PCIE_UP_SATA_TXP<3>")
	)
	(arc
		(start 419.663626 -147.32762)
		(mid 419.744448 -147.294142)
		(end 419.777926 -147.21332)
		(width 0.1143)
		(layer "In2.Cu")
		(net "SATA6G_PCH_PCIE_UP_SATA_TXP<3>")
	)
	(arc
		(start 382.008634 -130.886962)
		(mid 381.983113 -130.924923)
		(end 381.97409 -130.969766)
		(width 0.1143)
		(layer "In2.Cu")
		(net "SATA6G_PCH_PCIE_UP_SATA_TXP<3>")
	)
	(arc
		(start 381.681482 -129.556256)
		(mid 381.86165 -129.592)
		(end 382.014476 -129.693924)
		(width 0.1143)
		(layer "In2.Cu")
		(net "SATA6G_PCH_PCIE_UP_SATA_TXP<3>")
	)
	(arc
		(start 413.680148 -141.312138)
		(mid 413.718237 -141.503625)
		(end 413.826706 -141.66596)
		(width 0.1143)
		(layer "In2.Cu")
		(net "SATA6G_PCH_PCIE_UP_SATA_TXP<3>")
	)
	(arc
		(start 414.418272 -142.548102)
		(mid 414.746694 -142.876524)
		(end 415.075116 -142.548102)
		(width 0.1143)
		(layer "In2.Cu")
		(net "SATA6G_PCH_PCIE_UP_SATA_TXP<3>")
	)
	(arc
		(start 416.72129 -142.620746)
		(mid 416.98164 -142.881096)
		(end 417.24199 -142.620746)
		(width 0.1143)
		(layer "In2.Cu")
		(net "SATA6G_PCH_PCIE_UP_SATA_TXP<3>")
	)
	(arc
		(start 399.48612 -135.650224)
		(mid 399.833227 -135.719268)
		(end 400.12747 -135.915908)
		(width 0.1143)
		(layer "In2.Cu")
		(net "SATA6G_PCH_PCIE_UP_SATA_TXP<3>")
	)
	(arc
		(start 386.36321 -133.676644)
		(mid 386.457259 -133.686234)
		(end 386.538216 -133.735064)
		(width 0.1143)
		(layer "In2.Cu")
		(net "SATA6G_PCH_PCIE_UP_SATA_TXP<3>")
	)
	(arc
		(start 381.057658 -129.257806)
		(mid 381.032896 -129.294865)
		(end 381.02413 -129.338578)
		(width 0.1143)
		(layer "In2.Cu")
		(net "SATA6G_PCH_PCIE_UP_SATA_TXP<3>")
	)
	(arc
		(start 419.2651 -147.13331)
		(mid 419.315517 -147.26389)
		(end 419.440614 -147.326604)
		(width 0.1143)
		(layer "In2.Cu")
		(net "SATA6G_PCH_PCIE_UP_SATA_TXP<3>")
	)
	(arc
		(start 419.4937 -145.078196)
		(mid 419.275574 -145.604798)
		(end 418.748972 -145.822924)
		(width 0.1143)
		(layer "In2.Cu")
		(net "SATA6G_PCH_PCIE_UP_SATA_TXP<3>")
	)
	(arc
		(start 402.729954 -138.518392)
		(mid 402.983988 -138.688225)
		(end 403.283674 -138.748008)
		(width 0.1143)
		(layer "In2.Cu")
		(net "SATA6G_PCH_PCIE_UP_SATA_TXP<3>")
	)
	(arc
		(start 386.839206 -134.15264)
		(mid 386.848727 -134.246833)
		(end 386.897626 -134.3279)
		(width 0.1143)
		(layer "In2.Cu")
		(net "SATA6G_PCH_PCIE_UP_SATA_TXP<3>")
	)
	(arc
		(start 382.169162 -129.84861)
		(mid 382.292211 -130.033)
		(end 382.335278 -130.250438)
		(width 0.1143)
		(layer "In2.Cu")
		(net "SATA6G_PCH_PCIE_UP_SATA_TXP<3>")
	)
	(arc
		(start 387.732778 -134.929626)
		(mid 387.781637 -135.010573)
		(end 387.791198 -135.104632)
		(width 0.1143)
		(layer "In2.Cu")
		(net "SATA6G_PCH_PCIE_UP_SATA_TXP<3>")
	)
	(segment
		(start 382.703832 -130.433064)
		(end 383.010918 -130.74015)
		(width 0.0889)
		(layer "F.Cu")
		(net "SATA6G_PCH_PCIE_UP_SATA_TXP<2>")
	)
	(segment
		(start 382.075182 -129.804414)
		(end 382.26365 -129.992882)
		(width 0.0889)
		(layer "F.Cu")
		(net "SATA6G_PCH_PCIE_UP_SATA_TXP<2>")
	)
	(segment
		(start 383.18186 -131.125468)
		(end 383.582926 -131.125468)
		(width 0.0889)
		(layer "F.Cu")
		(net "SATA6G_PCH_PCIE_UP_SATA_TXP<2>")
	)
	(segment
		(start 382.04902 -129.458974)
		(end 382.04902 -129.741422)
		(width 0.0889)
		(layer "F.Cu")
		(net "SATA6G_PCH_PCIE_UP_SATA_TXP<2>")
	)
	(segment
		(start 383.09296 -130.938016)
		(end 383.09296 -130.9878)
		(width 0.0889)
		(layer "F.Cu")
		(net "SATA6G_PCH_PCIE_UP_SATA_TXP<2>")
	)
	(segment
		(start 382.452372 -130.055874)
		(end 382.64084 -130.244342)
		(width 0.0889)
		(layer "F.Cu")
		(net "SATA6G_PCH_PCIE_UP_SATA_TXP<2>")
	)
	(segment
		(start 381.46863 -126.041404)
		(end 381.46863 -127.48006)
		(width 0.0889)
		(layer "F.Cu")
		(net "SATA6G_PCH_PCIE_UP_SATA_TXP<2>")
	)
	(segment
		(start 381.484886 -125.750066)
		(end 381.430276 -125.804676)
		(width 0.0889)
		(layer "F.Cu")
		(net "SATA6G_PCH_PCIE_UP_SATA_TXP<2>")
	)
	(segment
		(start 381.494792 -127.543052)
		(end 381.966978 -128.015238)
		(width 0.0889)
		(layer "F.Cu")
		(net "SATA6G_PCH_PCIE_UP_SATA_TXP<2>")
	)
	(segment
		(start 381.410972 -125.901704)
		(end 381.46863 -126.041404)
		(width 0.0889)
		(layer "F.Cu")
		(net "SATA6G_PCH_PCIE_UP_SATA_TXP<2>")
	)
	(segment
		(start 383.55905 -131.59359)
		(end 383.54127 -131.61137)
		(width 0.0889)
		(layer "F.Cu")
		(net "SATA6G_PCH_PCIE_UP_SATA_TXP<2>")
	)
	(segment
		(start 382.04902 -128.213104)
		(end 382.04902 -128.836674)
		(width 0.0889)
		(layer "F.Cu")
		(net "SATA6G_PCH_PCIE_UP_SATA_TXP<2>")
	)
	(segment
		(start 383.582926 -131.59359)
		(end 383.55905 -131.59359)
		(width 0.0889)
		(layer "F.Cu")
		(net "SATA6G_PCH_PCIE_UP_SATA_TXP<2>")
	)
	(segment
		(start 382.13792 -129.014474)
		(end 382.13792 -129.281174)
		(width 0.0889)
		(layer "F.Cu")
		(net "SATA6G_PCH_PCIE_UP_SATA_TXP<2>")
	)
	(via
		(at 383.54127 -131.61137)
		(size 0.508)
		(drill 0.254)
		(layers "F.Cu" "B.Cu")
		(net "SATA6G_PCH_PCIE_UP_SATA_TXP<2>")
	)
	(via
		(at 425.3484 -139.838176)
		(size 0.508)
		(drill 0.254)
		(layers "F.Cu" "B.Cu")
		(net "SATA6G_PCH_PCIE_UP_SATA_TXP<2>")
	)
	(arc
		(start 382.358138 -130.024378)
		(mid 382.408174 -130.031424)
		(end 382.452372 -130.055874)
		(width 0.0889)
		(layer "F.Cu")
		(net "SATA6G_PCH_PCIE_UP_SATA_TXP<2>")
	)
	(arc
		(start 382.04902 -129.741422)
		(mid 382.055822 -129.775526)
		(end 382.075182 -129.804414)
		(width 0.0889)
		(layer "F.Cu")
		(net "SATA6G_PCH_PCIE_UP_SATA_TXP<2>")
	)
	(arc
		(start 383.010918 -130.74015)
		(mid 383.07163 -130.830917)
		(end 383.09296 -130.938016)
		(width 0.0889)
		(layer "F.Cu")
		(net "SATA6G_PCH_PCIE_UP_SATA_TXP<2>")
	)
	(arc
		(start 382.64084 -130.244342)
		(mid 382.665276 -130.288684)
		(end 382.672336 -130.33883)
		(width 0.0889)
		(layer "F.Cu")
		(net "SATA6G_PCH_PCIE_UP_SATA_TXP<2>")
	)
	(arc
		(start 382.672336 -130.33883)
		(mid 382.679382 -130.388866)
		(end 382.703832 -130.433064)
		(width 0.0889)
		(layer "F.Cu")
		(net "SATA6G_PCH_PCIE_UP_SATA_TXP<2>")
	)
	(arc
		(start 382.04902 -128.836674)
		(mid 382.063085 -128.8852)
		(end 382.09347 -128.925574)
		(width 0.0889)
		(layer "F.Cu")
		(net "SATA6G_PCH_PCIE_UP_SATA_TXP<2>")
	)
	(arc
		(start 381.46863 -127.48006)
		(mid 381.475432 -127.514164)
		(end 381.494792 -127.543052)
		(width 0.0889)
		(layer "F.Cu")
		(net "SATA6G_PCH_PCIE_UP_SATA_TXP<2>")
	)
	(arc
		(start 382.09347 -129.370074)
		(mid 382.063049 -129.41043)
		(end 382.04902 -129.458974)
		(width 0.0889)
		(layer "F.Cu")
		(net "SATA6G_PCH_PCIE_UP_SATA_TXP<2>")
	)
	(arc
		(start 381.966978 -128.015238)
		(mid 382.02769 -128.106005)
		(end 382.04902 -128.213104)
		(width 0.0889)
		(layer "F.Cu")
		(net "SATA6G_PCH_PCIE_UP_SATA_TXP<2>")
	)
	(arc
		(start 383.582926 -131.125468)
		(mid 383.817114 -131.359656)
		(end 383.582926 -131.59359)
		(width 0.0889)
		(layer "F.Cu")
		(net "SATA6G_PCH_PCIE_UP_SATA_TXP<2>")
	)
	(arc
		(start 383.09296 -130.9878)
		(mid 383.117109 -131.069752)
		(end 383.18186 -131.125468)
		(width 0.0889)
		(layer "F.Cu")
		(net "SATA6G_PCH_PCIE_UP_SATA_TXP<2>")
	)
	(arc
		(start 382.09347 -128.925574)
		(mid 382.123891 -128.96593)
		(end 382.13792 -129.014474)
		(width 0.0889)
		(layer "F.Cu")
		(net "SATA6G_PCH_PCIE_UP_SATA_TXP<2>")
	)
	(arc
		(start 382.13792 -129.281174)
		(mid 382.123855 -129.3297)
		(end 382.09347 -129.370074)
		(width 0.0889)
		(layer "F.Cu")
		(net "SATA6G_PCH_PCIE_UP_SATA_TXP<2>")
	)
	(arc
		(start 382.26365 -129.992882)
		(mid 382.307992 -130.017318)
		(end 382.358138 -130.024378)
		(width 0.0889)
		(layer "F.Cu")
		(net "SATA6G_PCH_PCIE_UP_SATA_TXP<2>")
	)
	(arc
		(start 381.430276 -125.804676)
		(mid 381.4059 -125.850265)
		(end 381.410972 -125.901704)
		(width 0.0889)
		(layer "F.Cu")
		(net "SATA6G_PCH_PCIE_UP_SATA_TXP<2>")
	)
	(segment
		(start 425.196 -141.097)
		(end 424.871642 -140.772642)
		(width 0.1143)
		(layer "B.Cu")
		(net "SATA6G_PCH_PCIE_UP_SATA_TXP<2>")
	)
	(segment
		(start 424.834558 -140.68298)
		(end 424.834558 -140.092684)
		(width 0.1143)
		(layer "B.Cu")
		(net "SATA6G_PCH_PCIE_UP_SATA_TXP<2>")
	)
	(segment
		(start 424.96105 -139.838176)
		(end 425.3484 -139.838176)
		(width 0.1143)
		(layer "B.Cu")
		(net "SATA6G_PCH_PCIE_UP_SATA_TXP<2>")
	)
	(segment
		(start 424.83405 -140.092176)
		(end 424.83405 -139.965176)
		(width 0.1143)
		(layer "B.Cu")
		(net "SATA6G_PCH_PCIE_UP_SATA_TXP<2>")
	)
	(segment
		(start 424.834558 -140.092684)
		(end 424.83405 -140.092176)
		(width 0.1143)
		(layer "B.Cu")
		(net "SATA6G_PCH_PCIE_UP_SATA_TXP<2>")
	)
	(arc
		(start 424.871642 -140.772642)
		(mid 424.844209 -140.731491)
		(end 424.834558 -140.68298)
		(width 0.1143)
		(layer "B.Cu")
		(net "SATA6G_PCH_PCIE_UP_SATA_TXP<2>")
	)
	(arc
		(start 424.83405 -139.965176)
		(mid 424.871247 -139.875373)
		(end 424.96105 -139.838176)
		(width 0.1143)
		(layer "B.Cu")
		(net "SATA6G_PCH_PCIE_UP_SATA_TXP<2>")
	)
	(segment
		(start 424.702478 -139.952476)
		(end 424.702478 -140.297154)
		(width 0.1143)
		(layer "In2.Cu")
		(net "SATA6G_PCH_PCIE_UP_SATA_TXP<2>")
	)
	(segment
		(start 404.737316 -138.095228)
		(end 404.424134 -137.782046)
		(width 0.1143)
		(layer "In2.Cu")
		(net "SATA6G_PCH_PCIE_UP_SATA_TXP<2>")
	)
	(segment
		(start 417.24834 -140.1826)
		(end 414.781492 -140.1826)
		(width 0.1143)
		(layer "In2.Cu")
		(net "SATA6G_PCH_PCIE_UP_SATA_TXP<2>")
	)
	(segment
		(start 403.310344 -136.668256)
		(end 401.525486 -134.883144)
		(width 0.1143)
		(layer "In2.Cu")
		(net "SATA6G_PCH_PCIE_UP_SATA_TXP<2>")
	)
	(segment
		(start 404.074122 -137.782046)
		(end 403.823932 -138.031982)
		(width 0.1143)
		(layer "In2.Cu")
		(net "SATA6G_PCH_PCIE_UP_SATA_TXP<2>")
	)
	(segment
		(start 383.755392 -131.376928)
		(end 383.54127 -131.59105)
		(width 0.1143)
		(layer "In2.Cu")
		(net "SATA6G_PCH_PCIE_UP_SATA_TXP<2>")
	)
	(segment
		(start 385.093972 -131.93903)
		(end 385.093972 -131.59105)
		(width 0.1143)
		(layer "In2.Cu")
		(net "SATA6G_PCH_PCIE_UP_SATA_TXP<2>")
	)
	(segment
		(start 403.060408 -137.268204)
		(end 403.310344 -137.018268)
		(width 0.1143)
		(layer "In2.Cu")
		(net "SATA6G_PCH_PCIE_UP_SATA_TXP<2>")
	)
	(segment
		(start 386.173472 -131.537456)
		(end 386.173472 -131.93903)
		(width 0.1143)
		(layer "In2.Cu")
		(net "SATA6G_PCH_PCIE_UP_SATA_TXP<2>")
	)
	(segment
		(start 425.3484 -139.838176)
		(end 424.816778 -139.838176)
		(width 0.1143)
		(layer "In2.Cu")
		(net "SATA6G_PCH_PCIE_UP_SATA_TXP<2>")
	)
	(segment
		(start 424.22191 -140.777722)
		(end 420.734744 -140.777722)
		(width 0.1143)
		(layer "In2.Cu")
		(net "SATA6G_PCH_PCIE_UP_SATA_TXP<2>")
	)
	(segment
		(start 390.248648 -134.68604)
		(end 386.943346 -131.380738)
		(width 0.1143)
		(layer "In2.Cu")
		(net "SATA6G_PCH_PCIE_UP_SATA_TXP<2>")
	)
	(segment
		(start 401.435824 -134.84606)
		(end 390.634982 -134.84606)
		(width 0.1143)
		(layer "In2.Cu")
		(net "SATA6G_PCH_PCIE_UP_SATA_TXP<2>")
	)
	(segment
		(start 411.19044 -139.159996)
		(end 410.448506 -138.418062)
		(width 0.1143)
		(layer "In2.Cu")
		(net "SATA6G_PCH_PCIE_UP_SATA_TXP<2>")
	)
	(segment
		(start 386.853684 -131.3434)
		(end 386.367528 -131.3434)
		(width 0.1143)
		(layer "In2.Cu")
		(net "SATA6G_PCH_PCIE_UP_SATA_TXP<2>")
	)
	(segment
		(start 414.4264 -140.035534)
		(end 413.90316 -139.512548)
		(width 0.1143)
		(layer "In2.Cu")
		(net "SATA6G_PCH_PCIE_UP_SATA_TXP<2>")
	)
	(segment
		(start 383.54127 -131.59105)
		(end 383.54127 -131.61137)
		(width 0.1143)
		(layer "In2.Cu")
		(net "SATA6G_PCH_PCIE_UP_SATA_TXP<2>")
	)
	(segment
		(start 384.846322 -131.3434)
		(end 383.836418 -131.3434)
		(width 0.1143)
		(layer "In2.Cu")
		(net "SATA6G_PCH_PCIE_UP_SATA_TXP<2>")
	)
	(segment
		(start 417.49599 -140.65631)
		(end 417.49599 -140.43025)
		(width 0.1143)
		(layer "In2.Cu")
		(net "SATA6G_PCH_PCIE_UP_SATA_TXP<2>")
	)
	(segment
		(start 413.59709 -139.385548)
		(end 411.73527 -139.385548)
		(width 0.1143)
		(layer "In2.Cu")
		(net "SATA6G_PCH_PCIE_UP_SATA_TXP<2>")
	)
	(segment
		(start 418.57549 -140.39723)
		(end 418.57549 -140.65631)
		(width 0.1143)
		(layer "In2.Cu")
		(net "SATA6G_PCH_PCIE_UP_SATA_TXP<2>")
	)
	(segment
		(start 420.43858 -140.65504)
		(end 420.003224 -140.219684)
		(width 0.1143)
		(layer "In2.Cu")
		(net "SATA6G_PCH_PCIE_UP_SATA_TXP<2>")
	)
	(segment
		(start 419.913562 -140.1826)
		(end 418.79012 -140.1826)
		(width 0.1143)
		(layer "In2.Cu")
		(net "SATA6G_PCH_PCIE_UP_SATA_TXP<2>")
	)
	(segment
		(start 409.956508 -138.2141)
		(end 405.025352 -138.2141)
		(width 0.1143)
		(layer "In2.Cu")
		(net "SATA6G_PCH_PCIE_UP_SATA_TXP<2>")
	)
	(segment
		(start 404.73757 -138.095228)
		(end 404.737316 -138.095228)
		(width 0.1143)
		(layer "In2.Cu")
		(net "SATA6G_PCH_PCIE_UP_SATA_TXP<2>")
	)
	(arc
		(start 390.634982 -134.84606)
		(mid 390.425916 -134.804456)
		(end 390.248648 -134.68604)
		(width 0.1143)
		(layer "In2.Cu")
		(net "SATA6G_PCH_PCIE_UP_SATA_TXP<2>")
	)
	(arc
		(start 401.525486 -134.883144)
		(mid 401.484335 -134.855711)
		(end 401.435824 -134.84606)
		(width 0.1143)
		(layer "In2.Cu")
		(net "SATA6G_PCH_PCIE_UP_SATA_TXP<2>")
	)
	(arc
		(start 404.424134 -137.782046)
		(mid 404.249128 -137.709482)
		(end 404.074122 -137.782046)
		(width 0.1143)
		(layer "In2.Cu")
		(net "SATA6G_PCH_PCIE_UP_SATA_TXP<2>")
	)
	(arc
		(start 386.173472 -131.93903)
		(mid 385.633722 -132.47878)
		(end 385.093972 -131.93903)
		(width 0.1143)
		(layer "In2.Cu")
		(net "SATA6G_PCH_PCIE_UP_SATA_TXP<2>")
	)
	(arc
		(start 420.003224 -140.219684)
		(mid 419.962073 -140.192251)
		(end 419.913562 -140.1826)
		(width 0.1143)
		(layer "In2.Cu")
		(net "SATA6G_PCH_PCIE_UP_SATA_TXP<2>")
	)
	(arc
		(start 386.367528 -131.3434)
		(mid 386.23031 -131.400238)
		(end 386.173472 -131.537456)
		(width 0.1143)
		(layer "In2.Cu")
		(net "SATA6G_PCH_PCIE_UP_SATA_TXP<2>")
	)
	(arc
		(start 405.025352 -138.2141)
		(mid 404.869664 -138.183243)
		(end 404.73757 -138.095228)
		(width 0.1143)
		(layer "In2.Cu")
		(net "SATA6G_PCH_PCIE_UP_SATA_TXP<2>")
	)
	(arc
		(start 403.310344 -137.018268)
		(mid 403.382908 -136.843262)
		(end 403.310344 -136.668256)
		(width 0.1143)
		(layer "In2.Cu")
		(net "SATA6G_PCH_PCIE_UP_SATA_TXP<2>")
	)
	(arc
		(start 414.781492 -140.1826)
		(mid 414.58931 -140.144391)
		(end 414.4264 -140.035534)
		(width 0.1143)
		(layer "In2.Cu")
		(net "SATA6G_PCH_PCIE_UP_SATA_TXP<2>")
	)
	(arc
		(start 386.943346 -131.380738)
		(mid 386.902238 -131.353114)
		(end 386.853684 -131.3434)
		(width 0.1143)
		(layer "In2.Cu")
		(net "SATA6G_PCH_PCIE_UP_SATA_TXP<2>")
	)
	(arc
		(start 410.448506 -138.418062)
		(mid 410.22279 -138.267151)
		(end 409.956508 -138.2141)
		(width 0.1143)
		(layer "In2.Cu")
		(net "SATA6G_PCH_PCIE_UP_SATA_TXP<2>")
	)
	(arc
		(start 418.79012 -140.1826)
		(mid 418.638354 -140.245464)
		(end 418.57549 -140.39723)
		(width 0.1143)
		(layer "In2.Cu")
		(net "SATA6G_PCH_PCIE_UP_SATA_TXP<2>")
	)
	(arc
		(start 403.823932 -138.031982)
		(mid 403.060345 -138.031919)
		(end 403.060408 -137.268204)
		(width 0.1143)
		(layer "In2.Cu")
		(net "SATA6G_PCH_PCIE_UP_SATA_TXP<2>")
	)
	(arc
		(start 383.836418 -131.3434)
		(mid 383.79258 -131.35212)
		(end 383.755392 -131.376928)
		(width 0.1143)
		(layer "In2.Cu")
		(net "SATA6G_PCH_PCIE_UP_SATA_TXP<2>")
	)
	(arc
		(start 385.093972 -131.59105)
		(mid 385.021437 -131.415935)
		(end 384.846322 -131.3434)
		(width 0.1143)
		(layer "In2.Cu")
		(net "SATA6G_PCH_PCIE_UP_SATA_TXP<2>")
	)
	(arc
		(start 411.73527 -139.385548)
		(mid 411.440429 -139.326936)
		(end 411.19044 -139.159996)
		(width 0.1143)
		(layer "In2.Cu")
		(net "SATA6G_PCH_PCIE_UP_SATA_TXP<2>")
	)
	(arc
		(start 424.702478 -140.297154)
		(mid 424.561723 -140.636967)
		(end 424.22191 -140.777722)
		(width 0.1143)
		(layer "In2.Cu")
		(net "SATA6G_PCH_PCIE_UP_SATA_TXP<2>")
	)
	(arc
		(start 420.734744 -140.777722)
		(mid 420.574444 -140.745854)
		(end 420.43858 -140.65504)
		(width 0.1143)
		(layer "In2.Cu")
		(net "SATA6G_PCH_PCIE_UP_SATA_TXP<2>")
	)
	(arc
		(start 418.57549 -140.65631)
		(mid 418.03574 -141.19606)
		(end 417.49599 -140.65631)
		(width 0.1143)
		(layer "In2.Cu")
		(net "SATA6G_PCH_PCIE_UP_SATA_TXP<2>")
	)
	(arc
		(start 424.816778 -139.838176)
		(mid 424.735956 -139.871654)
		(end 424.702478 -139.952476)
		(width 0.1143)
		(layer "In2.Cu")
		(net "SATA6G_PCH_PCIE_UP_SATA_TXP<2>")
	)
	(arc
		(start 413.90316 -139.512548)
		(mid 413.762777 -139.418528)
		(end 413.59709 -139.385548)
		(width 0.1143)
		(layer "In2.Cu")
		(net "SATA6G_PCH_PCIE_UP_SATA_TXP<2>")
	)
	(arc
		(start 417.49599 -140.43025)
		(mid 417.423455 -140.255135)
		(end 417.24834 -140.1826)
		(width 0.1143)
		(layer "In2.Cu")
		(net "SATA6G_PCH_PCIE_UP_SATA_TXP<2>")
	)
	(segment
		(start 382.266952 -127.515874)
		(end 382.45542 -127.704342)
		(width 0.0889)
		(layer "F.Cu")
		(net "SATA6G_PCH_PCIE_UP_SATA_TXP<1>")
	)
	(segment
		(start 383.334514 -129.29997)
		(end 383.567432 -129.29997)
		(width 0.0889)
		(layer "F.Cu")
		(net "SATA6G_PCH_PCIE_UP_SATA_TXP<1>")
	)
	(segment
		(start 381.9271 -127.301498)
		(end 382.0795 -127.453898)
		(width 0.0889)
		(layer "F.Cu")
		(net "SATA6G_PCH_PCIE_UP_SATA_TXP<1>")
	)
	(segment
		(start 383.684018 -129.34823)
		(end 383.752344 -129.416556)
		(width 0.0889)
		(layer "F.Cu")
		(net "SATA6G_PCH_PCIE_UP_SATA_TXP<1>")
	)
	(segment
		(start 381.978662 -126.553214)
		(end 381.978662 -126.819914)
		(width 0.0889)
		(layer "F.Cu")
		(net "SATA6G_PCH_PCIE_UP_SATA_TXP<1>")
	)
	(segment
		(start 381.985012 -126.165102)
		(end 381.889762 -126.260352)
		(width 0.0889)
		(layer "F.Cu")
		(net "SATA6G_PCH_PCIE_UP_SATA_TXP<1>")
	)
	(segment
		(start 383.64287 -129.70383)
		(end 383.43459 -129.70383)
		(width 0.0889)
		(layer "F.Cu")
		(net "SATA6G_PCH_PCIE_UP_SATA_TXP<1>")
	)
	(segment
		(start 381.889762 -126.997714)
		(end 381.889762 -127.21209)
		(width 0.0889)
		(layer "F.Cu")
		(net "SATA6G_PCH_PCIE_UP_SATA_TXP<1>")
	)
	(segment
		(start 381.889762 -126.260352)
		(end 381.889762 -126.375414)
		(width 0.0889)
		(layer "F.Cu")
		(net "SATA6G_PCH_PCIE_UP_SATA_TXP<1>")
	)
	(segment
		(start 382.518412 -127.893064)
		(end 382.99009 -128.364742)
		(width 0.0889)
		(layer "F.Cu")
		(net "SATA6G_PCH_PCIE_UP_SATA_TXP<1>")
	)
	(segment
		(start 383.12979 -128.702054)
		(end 383.12979 -129.095246)
		(width 0.0889)
		(layer "F.Cu")
		(net "SATA6G_PCH_PCIE_UP_SATA_TXP<1>")
	)
	(via
		(at 383.43459 -129.70383)
		(size 0.508)
		(drill 0.254)
		(layers "F.Cu" "B.Cu")
		(net "SATA6G_PCH_PCIE_UP_SATA_TXP<1>")
	)
	(via
		(at 422.593516 -139.954)
		(size 0.508)
		(drill 0.254)
		(layers "F.Cu" "B.Cu")
		(net "SATA6G_PCH_PCIE_UP_SATA_TXP<1>")
	)
	(arc
		(start 383.567432 -129.29997)
		(mid 383.630516 -129.312518)
		(end 383.684018 -129.34823)
		(width 0.0889)
		(layer "F.Cu")
		(net "SATA6G_PCH_PCIE_UP_SATA_TXP<1>")
	)
	(arc
		(start 382.45542 -127.704342)
		(mid 382.479856 -127.748684)
		(end 382.486916 -127.79883)
		(width 0.0889)
		(layer "F.Cu")
		(net "SATA6G_PCH_PCIE_UP_SATA_TXP<1>")
	)
	(arc
		(start 382.0795 -127.453898)
		(mid 382.123337 -127.477644)
		(end 382.172718 -127.484378)
		(width 0.0889)
		(layer "F.Cu")
		(net "SATA6G_PCH_PCIE_UP_SATA_TXP<1>")
	)
	(arc
		(start 381.978662 -126.819914)
		(mid 381.964597 -126.86844)
		(end 381.934212 -126.908814)
		(width 0.0889)
		(layer "F.Cu")
		(net "SATA6G_PCH_PCIE_UP_SATA_TXP<1>")
	)
	(arc
		(start 381.889762 -127.21209)
		(mid 381.899508 -127.260526)
		(end 381.9271 -127.301498)
		(width 0.0889)
		(layer "F.Cu")
		(net "SATA6G_PCH_PCIE_UP_SATA_TXP<1>")
	)
	(arc
		(start 381.889762 -126.375414)
		(mid 381.903827 -126.42394)
		(end 381.934212 -126.464314)
		(width 0.0889)
		(layer "F.Cu")
		(net "SATA6G_PCH_PCIE_UP_SATA_TXP<1>")
	)
	(arc
		(start 382.172718 -127.484378)
		(mid 382.222754 -127.491424)
		(end 382.266952 -127.515874)
		(width 0.0889)
		(layer "F.Cu")
		(net "SATA6G_PCH_PCIE_UP_SATA_TXP<1>")
	)
	(arc
		(start 382.99009 -128.364742)
		(mid 383.093497 -128.519502)
		(end 383.12979 -128.702054)
		(width 0.0889)
		(layer "F.Cu")
		(net "SATA6G_PCH_PCIE_UP_SATA_TXP<1>")
	)
	(arc
		(start 383.804414 -129.542286)
		(mid 383.757099 -129.656515)
		(end 383.64287 -129.70383)
		(width 0.0889)
		(layer "F.Cu")
		(net "SATA6G_PCH_PCIE_UP_SATA_TXP<1>")
	)
	(arc
		(start 383.752344 -129.416556)
		(mid 383.790888 -129.474241)
		(end 383.804414 -129.542286)
		(width 0.0889)
		(layer "F.Cu")
		(net "SATA6G_PCH_PCIE_UP_SATA_TXP<1>")
	)
	(arc
		(start 383.12979 -129.095246)
		(mid 383.189752 -129.240008)
		(end 383.334514 -129.29997)
		(width 0.0889)
		(layer "F.Cu")
		(net "SATA6G_PCH_PCIE_UP_SATA_TXP<1>")
	)
	(arc
		(start 381.934212 -126.464314)
		(mid 381.964633 -126.50467)
		(end 381.978662 -126.553214)
		(width 0.0889)
		(layer "F.Cu")
		(net "SATA6G_PCH_PCIE_UP_SATA_TXP<1>")
	)
	(arc
		(start 382.486916 -127.79883)
		(mid 382.493962 -127.848866)
		(end 382.518412 -127.893064)
		(width 0.0889)
		(layer "F.Cu")
		(net "SATA6G_PCH_PCIE_UP_SATA_TXP<1>")
	)
	(arc
		(start 381.934212 -126.908814)
		(mid 381.903791 -126.94917)
		(end 381.889762 -126.997714)
		(width 0.0889)
		(layer "F.Cu")
		(net "SATA6G_PCH_PCIE_UP_SATA_TXP<1>")
	)
	(segment
		(start 422.593516 -139.954)
		(end 422.205912 -139.954)
		(width 0.1143)
		(layer "B.Cu")
		(net "SATA6G_PCH_PCIE_UP_SATA_TXP<1>")
	)
	(segment
		(start 422.115996 -140.785596)
		(end 422.402 -141.0716)
		(width 0.1143)
		(layer "B.Cu")
		(net "SATA6G_PCH_PCIE_UP_SATA_TXP<1>")
	)
	(segment
		(start 422.078912 -140.081)
		(end 422.078912 -140.695934)
		(width 0.1143)
		(layer "B.Cu")
		(net "SATA6G_PCH_PCIE_UP_SATA_TXP<1>")
	)
	(arc
		(start 422.078912 -140.695934)
		(mid 422.088545 -140.744452)
		(end 422.115996 -140.785596)
		(width 0.1143)
		(layer "B.Cu")
		(net "SATA6G_PCH_PCIE_UP_SATA_TXP<1>")
	)
	(arc
		(start 422.205912 -139.954)
		(mid 422.116109 -139.991197)
		(end 422.078912 -140.081)
		(width 0.1143)
		(layer "B.Cu")
		(net "SATA6G_PCH_PCIE_UP_SATA_TXP<1>")
	)
	(segment
		(start 421.869362 -138.486134)
		(end 421.955214 -138.571986)
		(width 0.1143)
		(layer "In2.Cu")
		(net "SATA6G_PCH_PCIE_UP_SATA_TXP<1>")
	)
	(segment
		(start 418.714682 -138.843512)
		(end 418.714682 -138.832844)
		(width 0.1143)
		(layer "In2.Cu")
		(net "SATA6G_PCH_PCIE_UP_SATA_TXP<1>")
	)
	(segment
		(start 402.136356 -133.96341)
		(end 404.747476 -136.57453)
		(width 0.1143)
		(layer "In2.Cu")
		(net "SATA6G_PCH_PCIE_UP_SATA_TXP<1>")
	)
	(segment
		(start 390.904222 -133.76148)
		(end 401.649692 -133.76148)
		(width 0.1143)
		(layer "In2.Cu")
		(net "SATA6G_PCH_PCIE_UP_SATA_TXP<1>")
	)
	(segment
		(start 422.275 -139.954)
		(end 422.593516 -139.954)
		(width 0.1143)
		(layer "In2.Cu")
		(net "SATA6G_PCH_PCIE_UP_SATA_TXP<1>")
	)
	(segment
		(start 412.369 -138.293094)
		(end 414.530032 -138.293094)
		(width 0.1143)
		(layer "In2.Cu")
		(net "SATA6G_PCH_PCIE_UP_SATA_TXP<1>")
	)
	(segment
		(start 383.397252 -130.247136)
		(end 383.986532 -130.247136)
		(width 0.1143)
		(layer "In2.Cu")
		(net "SATA6G_PCH_PCIE_UP_SATA_TXP<1>")
	)
	(segment
		(start 384.503168 -130.195574)
		(end 384.518916 -130.211322)
		(width 0.1143)
		(layer "In2.Cu")
		(net "SATA6G_PCH_PCIE_UP_SATA_TXP<1>")
	)
	(segment
		(start 410.980128 -137.314432)
		(end 411.668722 -138.003026)
		(width 0.1143)
		(layer "In2.Cu")
		(net "SATA6G_PCH_PCIE_UP_SATA_TXP<1>")
	)
	(segment
		(start 416.644582 -138.832844)
		(end 416.644582 -138.84275)
		(width 0.1143)
		(layer "In2.Cu")
		(net "SATA6G_PCH_PCIE_UP_SATA_TXP<1>")
	)
	(segment
		(start 384.072892 -130.211322)
		(end 384.08864 -130.195574)
		(width 0.1143)
		(layer "In2.Cu")
		(net "SATA6G_PCH_PCIE_UP_SATA_TXP<1>")
	)
	(segment
		(start 417.139882 -138.84275)
		(end 417.139882 -138.832844)
		(width 0.1143)
		(layer "In2.Cu")
		(net "SATA6G_PCH_PCIE_UP_SATA_TXP<1>")
	)
	(segment
		(start 383.43459 -129.70383)
		(end 383.27203 -129.866136)
		(width 0.1143)
		(layer "In2.Cu")
		(net "SATA6G_PCH_PCIE_UP_SATA_TXP<1>")
	)
	(segment
		(start 415.069782 -138.832844)
		(end 415.069782 -138.843004)
		(width 0.1143)
		(layer "In2.Cu")
		(net "SATA6G_PCH_PCIE_UP_SATA_TXP<1>")
	)
	(segment
		(start 387.464554 -130.369564)
		(end 390.822942 -133.727952)
		(width 0.1143)
		(layer "In2.Cu")
		(net "SATA6G_PCH_PCIE_UP_SATA_TXP<1>")
	)
	(segment
		(start 405.902668 -137.05332)
		(end 410.348938 -137.05332)
		(width 0.1143)
		(layer "In2.Cu")
		(net "SATA6G_PCH_PCIE_UP_SATA_TXP<1>")
	)
	(segment
		(start 418.219382 -138.832844)
		(end 418.219382 -138.843512)
		(width 0.1143)
		(layer "In2.Cu")
		(net "SATA6G_PCH_PCIE_UP_SATA_TXP<1>")
	)
	(segment
		(start 383.206752 -130.024124)
		(end 383.206752 -130.056636)
		(width 0.1143)
		(layer "In2.Cu")
		(net "SATA6G_PCH_PCIE_UP_SATA_TXP<1>")
	)
	(segment
		(start 415.565082 -138.843004)
		(end 415.565082 -138.832844)
		(width 0.1143)
		(layer "In2.Cu")
		(net "SATA6G_PCH_PCIE_UP_SATA_TXP<1>")
	)
	(segment
		(start 384.175 -130.15976)
		(end 384.416808 -130.15976)
		(width 0.1143)
		(layer "In2.Cu")
		(net "SATA6G_PCH_PCIE_UP_SATA_TXP<1>")
	)
	(segment
		(start 384.605276 -130.247136)
		(end 387.168644 -130.247136)
		(width 0.1143)
		(layer "In2.Cu")
		(net "SATA6G_PCH_PCIE_UP_SATA_TXP<1>")
	)
	(segment
		(start 420.829232 -138.293094)
		(end 421.40251 -138.293094)
		(width 0.1143)
		(layer "In2.Cu")
		(net "SATA6G_PCH_PCIE_UP_SATA_TXP<1>")
	)
	(segment
		(start 422.148 -139.037568)
		(end 422.148 -139.827)
		(width 0.1143)
		(layer "In2.Cu")
		(net "SATA6G_PCH_PCIE_UP_SATA_TXP<1>")
	)
	(arc
		(start 383.206752 -130.056636)
		(mid 383.262548 -130.19134)
		(end 383.397252 -130.247136)
		(width 0.1143)
		(layer "In2.Cu")
		(net "SATA6G_PCH_PCIE_UP_SATA_TXP<1>")
	)
	(arc
		(start 421.40251 -138.293094)
		(mid 421.655108 -138.343227)
		(end 421.869362 -138.486134)
		(width 0.1143)
		(layer "In2.Cu")
		(net "SATA6G_PCH_PCIE_UP_SATA_TXP<1>")
	)
	(arc
		(start 383.986532 -130.247136)
		(mid 384.033272 -130.237821)
		(end 384.072892 -130.211322)
		(width 0.1143)
		(layer "In2.Cu")
		(net "SATA6G_PCH_PCIE_UP_SATA_TXP<1>")
	)
	(arc
		(start 384.416808 -130.15976)
		(mid 384.463548 -130.169075)
		(end 384.503168 -130.195574)
		(width 0.1143)
		(layer "In2.Cu")
		(net "SATA6G_PCH_PCIE_UP_SATA_TXP<1>")
	)
	(arc
		(start 417.139882 -138.832844)
		(mid 417.679632 -138.293094)
		(end 418.219382 -138.832844)
		(width 0.1143)
		(layer "In2.Cu")
		(net "SATA6G_PCH_PCIE_UP_SATA_TXP<1>")
	)
	(arc
		(start 422.148 -139.827)
		(mid 422.185197 -139.916803)
		(end 422.275 -139.954)
		(width 0.1143)
		(layer "In2.Cu")
		(net "SATA6G_PCH_PCIE_UP_SATA_TXP<1>")
	)
	(arc
		(start 384.08864 -130.195574)
		(mid 384.128248 -130.169045)
		(end 384.175 -130.15976)
		(width 0.1143)
		(layer "In2.Cu")
		(net "SATA6G_PCH_PCIE_UP_SATA_TXP<1>")
	)
	(arc
		(start 411.668722 -138.003026)
		(mid 411.990012 -138.217705)
		(end 412.369 -138.293094)
		(width 0.1143)
		(layer "In2.Cu")
		(net "SATA6G_PCH_PCIE_UP_SATA_TXP<1>")
	)
	(arc
		(start 384.518916 -130.211322)
		(mid 384.558524 -130.237851)
		(end 384.605276 -130.247136)
		(width 0.1143)
		(layer "In2.Cu")
		(net "SATA6G_PCH_PCIE_UP_SATA_TXP<1>")
	)
	(arc
		(start 404.747476 -136.57453)
		(mid 405.277453 -136.928806)
		(end 405.902668 -137.05332)
		(width 0.1143)
		(layer "In2.Cu")
		(net "SATA6G_PCH_PCIE_UP_SATA_TXP<1>")
	)
	(arc
		(start 421.955214 -138.571986)
		(mid 422.097891 -138.785611)
		(end 422.148 -139.037568)
		(width 0.1143)
		(layer "In2.Cu")
		(net "SATA6G_PCH_PCIE_UP_SATA_TXP<1>")
	)
	(arc
		(start 415.565082 -138.832844)
		(mid 416.104832 -138.293094)
		(end 416.644582 -138.832844)
		(width 0.1143)
		(layer "In2.Cu")
		(net "SATA6G_PCH_PCIE_UP_SATA_TXP<1>")
	)
	(arc
		(start 418.714682 -138.832844)
		(mid 419.254432 -138.293094)
		(end 419.794182 -138.832844)
		(width 0.1143)
		(layer "In2.Cu")
		(net "SATA6G_PCH_PCIE_UP_SATA_TXP<1>")
	)
	(arc
		(start 383.27203 -129.866136)
		(mid 383.22368 -129.938637)
		(end 383.206752 -130.024124)
		(width 0.1143)
		(layer "In2.Cu")
		(net "SATA6G_PCH_PCIE_UP_SATA_TXP<1>")
	)
	(arc
		(start 419.794182 -138.832844)
		(mid 420.041832 -139.080494)
		(end 420.289482 -138.832844)
		(width 0.1143)
		(layer "In2.Cu")
		(net "SATA6G_PCH_PCIE_UP_SATA_TXP<1>")
	)
	(arc
		(start 387.168644 -130.247136)
		(mid 387.328724 -130.279018)
		(end 387.464554 -130.369564)
		(width 0.1143)
		(layer "In2.Cu")
		(net "SATA6G_PCH_PCIE_UP_SATA_TXP<1>")
	)
	(arc
		(start 410.348938 -137.05332)
		(mid 410.690475 -137.121144)
		(end 410.980128 -137.314432)
		(width 0.1143)
		(layer "In2.Cu")
		(net "SATA6G_PCH_PCIE_UP_SATA_TXP<1>")
	)
	(arc
		(start 414.530032 -138.293094)
		(mid 414.911693 -138.451183)
		(end 415.069782 -138.832844)
		(width 0.1143)
		(layer "In2.Cu")
		(net "SATA6G_PCH_PCIE_UP_SATA_TXP<1>")
	)
	(arc
		(start 390.822942 -133.727952)
		(mid 390.860249 -133.752786)
		(end 390.904222 -133.76148)
		(width 0.1143)
		(layer "In2.Cu")
		(net "SATA6G_PCH_PCIE_UP_SATA_TXP<1>")
	)
	(arc
		(start 415.069782 -138.843004)
		(mid 415.317432 -139.090654)
		(end 415.565082 -138.843004)
		(width 0.1143)
		(layer "In2.Cu")
		(net "SATA6G_PCH_PCIE_UP_SATA_TXP<1>")
	)
	(arc
		(start 401.649692 -133.76148)
		(mid 401.91321 -133.813812)
		(end 402.136356 -133.96341)
		(width 0.1143)
		(layer "In2.Cu")
		(net "SATA6G_PCH_PCIE_UP_SATA_TXP<1>")
	)
	(arc
		(start 418.219382 -138.843512)
		(mid 418.467032 -139.091162)
		(end 418.714682 -138.843512)
		(width 0.1143)
		(layer "In2.Cu")
		(net "SATA6G_PCH_PCIE_UP_SATA_TXP<1>")
	)
	(arc
		(start 420.289482 -138.832844)
		(mid 420.447571 -138.451183)
		(end 420.829232 -138.293094)
		(width 0.1143)
		(layer "In2.Cu")
		(net "SATA6G_PCH_PCIE_UP_SATA_TXP<1>")
	)
	(arc
		(start 416.644582 -138.84275)
		(mid 416.892232 -139.0904)
		(end 417.139882 -138.84275)
		(width 0.1143)
		(layer "In2.Cu")
		(net "SATA6G_PCH_PCIE_UP_SATA_TXP<1>")
	)
	(segment
		(start 382.484884 -125.750066)
		(end 382.484884 -125.541024)
		(width 0.0889)
		(layer "F.Cu")
		(net "SATA6G_PCH_PCIE_UP_SATA_TXP<0>")
	)
	(segment
		(start 382.521968 -126.63297)
		(end 382.964944 -127.075946)
		(width 0.0889)
		(layer "F.Cu")
		(net "SATA6G_PCH_PCIE_UP_SATA_TXP<0>")
	)
	(segment
		(start 383.054606 -127.11303)
		(end 383.294382 -127.11303)
		(width 0.0889)
		(layer "F.Cu")
		(net "SATA6G_PCH_PCIE_UP_SATA_TXP<0>")
	)
	(segment
		(start 382.521968 -126.125986)
		(end 382.521968 -126.63297)
		(width 0.0889)
		(layer "F.Cu")
		(net "SATA6G_PCH_PCIE_UP_SATA_TXP<0>")
	)
	(segment
		(start 383.603754 -127.422402)
		(end 383.603754 -127.496824)
		(width 0.0889)
		(layer "F.Cu")
		(net "SATA6G_PCH_PCIE_UP_SATA_TXP<0>")
	)
	(segment
		(start 382.668018 -126.039372)
		(end 382.608582 -126.039372)
		(width 0.0889)
		(layer "F.Cu")
		(net "SATA6G_PCH_PCIE_UP_SATA_TXP<0>")
	)
	(segment
		(start 382.608582 -126.039372)
		(end 382.521968 -126.125986)
		(width 0.0889)
		(layer "F.Cu")
		(net "SATA6G_PCH_PCIE_UP_SATA_TXP<0>")
	)
	(segment
		(start 382.681734 -125.471936)
		(end 382.814068 -125.60427)
		(width 0.0889)
		(layer "F.Cu")
		(net "SATA6G_PCH_PCIE_UP_SATA_TXP<0>")
	)
	(segment
		(start 382.814068 -125.60427)
		(end 382.814068 -125.893322)
		(width 0.0889)
		(layer "F.Cu")
		(net "SATA6G_PCH_PCIE_UP_SATA_TXP<0>")
	)
	(segment
		(start 382.553972 -125.471936)
		(end 382.681734 -125.471936)
		(width 0.0889)
		(layer "F.Cu")
		(net "SATA6G_PCH_PCIE_UP_SATA_TXP<0>")
	)
	(segment
		(start 382.484884 -125.541024)
		(end 382.553972 -125.471936)
		(width 0.0889)
		(layer "F.Cu")
		(net "SATA6G_PCH_PCIE_UP_SATA_TXP<0>")
	)
	(segment
		(start 383.640838 -127.586486)
		(end 383.826004 -127.771652)
		(width 0.0889)
		(layer "F.Cu")
		(net "SATA6G_PCH_PCIE_UP_SATA_TXP<0>")
	)
	(segment
		(start 382.814068 -125.893322)
		(end 382.668018 -126.039372)
		(width 0.0889)
		(layer "F.Cu")
		(net "SATA6G_PCH_PCIE_UP_SATA_TXP<0>")
	)
	(via
		(at 383.826004 -127.771652)
		(size 0.508)
		(drill 0.254)
		(layers "F.Cu" "B.Cu")
		(net "SATA6G_PCH_PCIE_UP_SATA_TXP<0>")
	)
	(via
		(at 427.99 -139.838176)
		(size 0.508)
		(drill 0.254)
		(layers "F.Cu" "B.Cu")
		(net "SATA6G_PCH_PCIE_UP_SATA_TXP<0>")
	)
	(arc
		(start 382.964944 -127.075946)
		(mid 383.006095 -127.103379)
		(end 383.054606 -127.11303)
		(width 0.0889)
		(layer "F.Cu")
		(net "SATA6G_PCH_PCIE_UP_SATA_TXP<0>")
	)
	(arc
		(start 383.603754 -127.496824)
		(mid 383.613387 -127.545342)
		(end 383.640838 -127.586486)
		(width 0.0889)
		(layer "F.Cu")
		(net "SATA6G_PCH_PCIE_UP_SATA_TXP<0>")
	)
	(arc
		(start 383.294382 -127.11303)
		(mid 383.513141 -127.203643)
		(end 383.603754 -127.422402)
		(width 0.0889)
		(layer "F.Cu")
		(net "SATA6G_PCH_PCIE_UP_SATA_TXP<0>")
	)
	(segment
		(start 427.60265 -139.838176)
		(end 427.99 -139.838176)
		(width 0.1143)
		(layer "B.Cu")
		(net "SATA6G_PCH_PCIE_UP_SATA_TXP<0>")
	)
	(segment
		(start 427.34865 -140.55725)
		(end 427.47565 -140.43025)
		(width 0.1143)
		(layer "B.Cu")
		(net "SATA6G_PCH_PCIE_UP_SATA_TXP<0>")
	)
	(segment
		(start 427.736 -141.1986)
		(end 427.385734 -140.848334)
		(width 0.1143)
		(layer "B.Cu")
		(net "SATA6G_PCH_PCIE_UP_SATA_TXP<0>")
	)
	(segment
		(start 427.47565 -140.43025)
		(end 427.47565 -139.965176)
		(width 0.1143)
		(layer "B.Cu")
		(net "SATA6G_PCH_PCIE_UP_SATA_TXP<0>")
	)
	(segment
		(start 427.34865 -140.758672)
		(end 427.34865 -140.55725)
		(width 0.1143)
		(layer "B.Cu")
		(net "SATA6G_PCH_PCIE_UP_SATA_TXP<0>")
	)
	(arc
		(start 427.385734 -140.848334)
		(mid 427.358301 -140.807183)
		(end 427.34865 -140.758672)
		(width 0.1143)
		(layer "B.Cu")
		(net "SATA6G_PCH_PCIE_UP_SATA_TXP<0>")
	)
	(arc
		(start 427.47565 -139.965176)
		(mid 427.512847 -139.875373)
		(end 427.60265 -139.838176)
		(width 0.1143)
		(layer "B.Cu")
		(net "SATA6G_PCH_PCIE_UP_SATA_TXP<0>")
	)
	(segment
		(start 427.50105 -139.296648)
		(end 427.50105 -138.139424)
		(width 0.1143)
		(layer "In2.Cu")
		(net "SATA6G_PCH_PCIE_UP_SATA_TXP<0>")
	)
	(segment
		(start 426.026326 -136.6647)
		(end 421.908224 -136.6647)
		(width 0.1143)
		(layer "In2.Cu")
		(net "SATA6G_PCH_PCIE_UP_SATA_TXP<0>")
	)
	(segment
		(start 419.914324 -136.824974)
		(end 419.914324 -137.261092)
		(width 0.1143)
		(layer "In2.Cu")
		(net "SATA6G_PCH_PCIE_UP_SATA_TXP<0>")
	)
	(segment
		(start 417.844224 -137.245344)
		(end 417.844224 -137.021824)
		(width 0.1143)
		(layer "In2.Cu")
		(net "SATA6G_PCH_PCIE_UP_SATA_TXP<0>")
	)
	(segment
		(start 427.99 -139.838176)
		(end 427.538134 -139.38631)
		(width 0.1143)
		(layer "In2.Cu")
		(net "SATA6G_PCH_PCIE_UP_SATA_TXP<0>")
	)
	(segment
		(start 386.271262 -128.20904)
		(end 383.803906 -128.20904)
		(width 0.1143)
		(layer "In2.Cu")
		(net "SATA6G_PCH_PCIE_UP_SATA_TXP<0>")
	)
	(segment
		(start 391.16889 -132.933186)
		(end 386.567172 -128.331468)
		(width 0.1143)
		(layer "In2.Cu")
		(net "SATA6G_PCH_PCIE_UP_SATA_TXP<0>")
	)
	(segment
		(start 418.339524 -136.860026)
		(end 418.339524 -137.245344)
		(width 0.1143)
		(layer "In2.Cu")
		(net "SATA6G_PCH_PCIE_UP_SATA_TXP<0>")
	)
	(segment
		(start 414.694624 -137.31113)
		(end 414.694624 -137.20445)
		(width 0.1143)
		(layer "In2.Cu")
		(net "SATA6G_PCH_PCIE_UP_SATA_TXP<0>")
	)
	(segment
		(start 411.386782 -136.567672)
		(end 411.242256 -136.423146)
		(width 0.1143)
		(layer "In2.Cu")
		(net "SATA6G_PCH_PCIE_UP_SATA_TXP<0>")
	)
	(segment
		(start 414.154874 -136.6647)
		(end 411.620462 -136.6647)
		(width 0.1143)
		(layer "In2.Cu")
		(net "SATA6G_PCH_PCIE_UP_SATA_TXP<0>")
	)
	(segment
		(start 383.67462 -127.923036)
		(end 383.826004 -127.771652)
		(width 0.1143)
		(layer "In2.Cu")
		(net "SATA6G_PCH_PCIE_UP_SATA_TXP<0>")
	)
	(segment
		(start 420.993824 -137.25144)
		(end 420.993824 -136.824974)
		(width 0.1143)
		(layer "In2.Cu")
		(net "SATA6G_PCH_PCIE_UP_SATA_TXP<0>")
	)
	(segment
		(start 405.083518 -135.792464)
		(end 402.377402 -133.086348)
		(width 0.1143)
		(layer "In2.Cu")
		(net "SATA6G_PCH_PCIE_UP_SATA_TXP<0>")
	)
	(segment
		(start 402.090128 -132.966968)
		(end 391.249662 -132.966968)
		(width 0.1143)
		(layer "In2.Cu")
		(net "SATA6G_PCH_PCIE_UP_SATA_TXP<0>")
	)
	(segment
		(start 415.189924 -137.004552)
		(end 415.189924 -137.31113)
		(width 0.1143)
		(layer "In2.Cu")
		(net "SATA6G_PCH_PCIE_UP_SATA_TXP<0>")
	)
	(segment
		(start 416.764724 -137.021824)
		(end 416.764724 -137.274554)
		(width 0.1143)
		(layer "In2.Cu")
		(net "SATA6G_PCH_PCIE_UP_SATA_TXP<0>")
	)
	(segment
		(start 427.378622 -137.843514)
		(end 426.322236 -136.787128)
		(width 0.1143)
		(layer "In2.Cu")
		(net "SATA6G_PCH_PCIE_UP_SATA_TXP<0>")
	)
	(segment
		(start 416.269424 -137.274554)
		(end 416.269424 -137.004552)
		(width 0.1143)
		(layer "In2.Cu")
		(net "SATA6G_PCH_PCIE_UP_SATA_TXP<0>")
	)
	(segment
		(start 410.81325 -136.2456)
		(end 406.176734 -136.2456)
		(width 0.1143)
		(layer "In2.Cu")
		(net "SATA6G_PCH_PCIE_UP_SATA_TXP<0>")
	)
	(segment
		(start 421.489124 -137.0838)
		(end 421.489124 -137.25144)
		(width 0.1143)
		(layer "In2.Cu")
		(net "SATA6G_PCH_PCIE_UP_SATA_TXP<0>")
	)
	(segment
		(start 419.419024 -137.261092)
		(end 419.419024 -136.860026)
		(width 0.1143)
		(layer "In2.Cu")
		(net "SATA6G_PCH_PCIE_UP_SATA_TXP<0>")
	)
	(segment
		(start 383.642108 -128.047242)
		(end 383.642108 -128.001268)
		(width 0.1143)
		(layer "In2.Cu")
		(net "SATA6G_PCH_PCIE_UP_SATA_TXP<0>")
	)
	(arc
		(start 421.489124 -137.25144)
		(mid 421.241474 -137.49909)
		(end 420.993824 -137.25144)
		(width 0.1143)
		(layer "In2.Cu")
		(net "SATA6G_PCH_PCIE_UP_SATA_TXP<0>")
	)
	(arc
		(start 420.993824 -136.824974)
		(mid 420.454074 -136.285224)
		(end 419.914324 -136.824974)
		(width 0.1143)
		(layer "In2.Cu")
		(net "SATA6G_PCH_PCIE_UP_SATA_TXP<0>")
	)
	(arc
		(start 391.249662 -132.966968)
		(mid 391.205892 -132.95815)
		(end 391.16889 -132.933186)
		(width 0.1143)
		(layer "In2.Cu")
		(net "SATA6G_PCH_PCIE_UP_SATA_TXP<0>")
	)
	(arc
		(start 421.908224 -136.6647)
		(mid 421.611876 -136.787452)
		(end 421.489124 -137.0838)
		(width 0.1143)
		(layer "In2.Cu")
		(net "SATA6G_PCH_PCIE_UP_SATA_TXP<0>")
	)
	(arc
		(start 406.176734 -136.2456)
		(mid 405.585039 -136.127793)
		(end 405.083518 -135.792464)
		(width 0.1143)
		(layer "In2.Cu")
		(net "SATA6G_PCH_PCIE_UP_SATA_TXP<0>")
	)
	(arc
		(start 417.844224 -137.021824)
		(mid 417.304474 -136.482074)
		(end 416.764724 -137.021824)
		(width 0.1143)
		(layer "In2.Cu")
		(net "SATA6G_PCH_PCIE_UP_SATA_TXP<0>")
	)
	(arc
		(start 415.189924 -137.31113)
		(mid 414.942274 -137.55878)
		(end 414.694624 -137.31113)
		(width 0.1143)
		(layer "In2.Cu")
		(net "SATA6G_PCH_PCIE_UP_SATA_TXP<0>")
	)
	(arc
		(start 418.339524 -137.245344)
		(mid 418.091874 -137.492994)
		(end 417.844224 -137.245344)
		(width 0.1143)
		(layer "In2.Cu")
		(net "SATA6G_PCH_PCIE_UP_SATA_TXP<0>")
	)
	(arc
		(start 427.50105 -138.139424)
		(mid 427.469168 -137.979344)
		(end 427.378622 -137.843514)
		(width 0.1143)
		(layer "In2.Cu")
		(net "SATA6G_PCH_PCIE_UP_SATA_TXP<0>")
	)
	(arc
		(start 411.242256 -136.423146)
		(mid 411.045426 -136.291658)
		(end 410.81325 -136.2456)
		(width 0.1143)
		(layer "In2.Cu")
		(net "SATA6G_PCH_PCIE_UP_SATA_TXP<0>")
	)
	(arc
		(start 419.914324 -137.261092)
		(mid 419.666674 -137.508742)
		(end 419.419024 -137.261092)
		(width 0.1143)
		(layer "In2.Cu")
		(net "SATA6G_PCH_PCIE_UP_SATA_TXP<0>")
	)
	(arc
		(start 416.269424 -137.004552)
		(mid 415.729674 -136.464802)
		(end 415.189924 -137.004552)
		(width 0.1143)
		(layer "In2.Cu")
		(net "SATA6G_PCH_PCIE_UP_SATA_TXP<0>")
	)
	(arc
		(start 419.419024 -136.860026)
		(mid 418.879274 -136.320276)
		(end 418.339524 -136.860026)
		(width 0.1143)
		(layer "In2.Cu")
		(net "SATA6G_PCH_PCIE_UP_SATA_TXP<0>")
	)
	(arc
		(start 411.620462 -136.6647)
		(mid 411.493973 -136.639428)
		(end 411.386782 -136.567672)
		(width 0.1143)
		(layer "In2.Cu")
		(net "SATA6G_PCH_PCIE_UP_SATA_TXP<0>")
	)
	(arc
		(start 427.538134 -139.38631)
		(mid 427.510701 -139.345159)
		(end 427.50105 -139.296648)
		(width 0.1143)
		(layer "In2.Cu")
		(net "SATA6G_PCH_PCIE_UP_SATA_TXP<0>")
	)
	(arc
		(start 416.764724 -137.274554)
		(mid 416.517074 -137.522204)
		(end 416.269424 -137.274554)
		(width 0.1143)
		(layer "In2.Cu")
		(net "SATA6G_PCH_PCIE_UP_SATA_TXP<0>")
	)
	(arc
		(start 386.567172 -128.331468)
		(mid 386.43138 -128.240831)
		(end 386.271262 -128.20904)
		(width 0.1143)
		(layer "In2.Cu")
		(net "SATA6G_PCH_PCIE_UP_SATA_TXP<0>")
	)
	(arc
		(start 426.322236 -136.787128)
		(mid 426.186444 -136.696491)
		(end 426.026326 -136.6647)
		(width 0.1143)
		(layer "In2.Cu")
		(net "SATA6G_PCH_PCIE_UP_SATA_TXP<0>")
	)
	(arc
		(start 383.642108 -128.001268)
		(mid 383.650621 -127.958942)
		(end 383.67462 -127.923036)
		(width 0.1143)
		(layer "In2.Cu")
		(net "SATA6G_PCH_PCIE_UP_SATA_TXP<0>")
	)
	(arc
		(start 402.377402 -133.086348)
		(mid 402.24563 -132.998115)
		(end 402.090128 -132.966968)
		(width 0.1143)
		(layer "In2.Cu")
		(net "SATA6G_PCH_PCIE_UP_SATA_TXP<0>")
	)
	(arc
		(start 414.694624 -137.20445)
		(mid 414.536535 -136.822789)
		(end 414.154874 -136.6647)
		(width 0.1143)
		(layer "In2.Cu")
		(net "SATA6G_PCH_PCIE_UP_SATA_TXP<0>")
	)
	(arc
		(start 383.803906 -128.20904)
		(mid 383.689498 -128.16165)
		(end 383.642108 -128.047242)
		(width 0.1143)
		(layer "In2.Cu")
		(net "SATA6G_PCH_PCIE_UP_SATA_TXP<0>")
	)
	(segment
		(start 378.4981 -126.177294)
		(end 378.4981 -126.922022)
		(width 0.0889)
		(layer "F.Cu")
		(net "SATA6G_PCH_PCIE_UP_SATA_TXN<7>")
	)
	(segment
		(start 378.737368 -125.938026)
		(end 378.4981 -126.177294)
		(width 0.0889)
		(layer "F.Cu")
		(net "SATA6G_PCH_PCIE_UP_SATA_TXN<7>")
	)
	(segment
		(start 378.86259 -125.730254)
		(end 378.737368 -125.938026)
		(width 0.0889)
		(layer "F.Cu")
		(net "SATA6G_PCH_PCIE_UP_SATA_TXN<7>")
	)
	(segment
		(start 378.4981 -126.922022)
		(end 378.497846 -126.921768)
		(width 0.0889)
		(layer "F.Cu")
		(net "SATA6G_PCH_PCIE_UP_SATA_TXN<7>")
	)
	(segment
		(start 375.76125 -127.583438)
		(end 375.76125 -129.02565)
		(width 0.0889)
		(layer "F.Cu")
		(net "SATA6G_PCH_PCIE_UP_SATA_TXN<7>")
	)
	(segment
		(start 378.938282 -125.485652)
		(end 378.86259 -125.730254)
		(width 0.0889)
		(layer "F.Cu")
		(net "SATA6G_PCH_PCIE_UP_SATA_TXN<7>")
	)
	(segment
		(start 378.985018 -125.33503)
		(end 378.970794 -125.38075)
		(width 0.0889)
		(layer "F.Cu")
		(net "SATA6G_PCH_PCIE_UP_SATA_TXN<7>")
	)
	(segment
		(start 378.970794 -125.38075)
		(end 378.938282 -125.485652)
		(width 0.0889)
		(layer "F.Cu")
		(net "SATA6G_PCH_PCIE_UP_SATA_TXN<7>")
	)
	(segment
		(start 378.471938 -126.984506)
		(end 378.25172 -127.204978)
		(width 0.0889)
		(layer "F.Cu")
		(net "SATA6G_PCH_PCIE_UP_SATA_TXN<7>")
	)
	(segment
		(start 378.188728 -127.23114)
		(end 376.113548 -127.23114)
		(width 0.0889)
		(layer "F.Cu")
		(net "SATA6G_PCH_PCIE_UP_SATA_TXN<7>")
	)
	(via
		(at 407.922476 -147.955)
		(size 0.508)
		(drill 0.254)
		(layers "F.Cu" "B.Cu")
		(net "SATA6G_PCH_PCIE_UP_SATA_TXN<7>")
	)
	(via
		(at 375.76125 -129.02565)
		(size 0.508)
		(drill 0.254)
		(layers "F.Cu" "B.Cu")
		(net "SATA6G_PCH_PCIE_UP_SATA_TXN<7>")
	)
	(arc
		(start 378.497846 -126.921768)
		(mid 378.491098 -126.955691)
		(end 378.471938 -126.984506)
		(width 0.0889)
		(layer "F.Cu")
		(net "SATA6G_PCH_PCIE_UP_SATA_TXN<7>")
	)
	(arc
		(start 376.113548 -127.23114)
		(mid 375.864436 -127.334326)
		(end 375.76125 -127.583438)
		(width 0.0889)
		(layer "F.Cu")
		(net "SATA6G_PCH_PCIE_UP_SATA_TXN<7>")
	)
	(arc
		(start 378.25172 -127.204978)
		(mid 378.222833 -127.224343)
		(end 378.188728 -127.23114)
		(width 0.0889)
		(layer "F.Cu")
		(net "SATA6G_PCH_PCIE_UP_SATA_TXN<7>")
	)
	(segment
		(start 408.276806 -147.56765)
		(end 408.036776 -147.56765)
		(width 0.1143)
		(layer "B.Cu")
		(net "SATA6G_PCH_PCIE_UP_SATA_TXN<7>")
	)
	(segment
		(start 408.7114 -147.955)
		(end 408.357578 -147.601178)
		(width 0.1143)
		(layer "B.Cu")
		(net "SATA6G_PCH_PCIE_UP_SATA_TXN<7>")
	)
	(segment
		(start 407.922476 -147.68195)
		(end 407.922476 -147.955)
		(width 0.1143)
		(layer "B.Cu")
		(net "SATA6G_PCH_PCIE_UP_SATA_TXN<7>")
	)
	(arc
		(start 408.036776 -147.56765)
		(mid 407.955954 -147.601128)
		(end 407.922476 -147.68195)
		(width 0.1143)
		(layer "B.Cu")
		(net "SATA6G_PCH_PCIE_UP_SATA_TXN<7>")
	)
	(arc
		(start 408.357578 -147.601178)
		(mid 408.320519 -147.576416)
		(end 408.276806 -147.56765)
		(width 0.1143)
		(layer "B.Cu")
		(net "SATA6G_PCH_PCIE_UP_SATA_TXN<7>")
	)
	(segment
		(start 391.13587 -140.28801)
		(end 391.856214 -141.008354)
		(width 0.1143)
		(layer "In2.Cu")
		(net "SATA6G_PCH_PCIE_UP_SATA_TXN<7>")
	)
	(segment
		(start 407.594054 -147.626578)
		(end 407.922476 -147.955)
		(width 0.1143)
		(layer "In2.Cu")
		(net "SATA6G_PCH_PCIE_UP_SATA_TXN<7>")
	)
	(segment
		(start 375.8946 -129.206244)
		(end 375.8946 -129.7178)
		(width 0.1143)
		(layer "In2.Cu")
		(net "SATA6G_PCH_PCIE_UP_SATA_TXN<7>")
	)
	(segment
		(start 381.063246 -138.701526)
		(end 381.063246 -139.492228)
		(width 0.1143)
		(layer "In2.Cu")
		(net "SATA6G_PCH_PCIE_UP_SATA_TXN<7>")
	)
	(segment
		(start 377.7234 -133.002782)
		(end 377.7234 -134.71271)
		(width 0.1143)
		(layer "In2.Cu")
		(net "SATA6G_PCH_PCIE_UP_SATA_TXN<7>")
	)
	(segment
		(start 400.449288 -147.272248)
		(end 402.091398 -147.272248)
		(width 0.1143)
		(layer "In2.Cu")
		(net "SATA6G_PCH_PCIE_UP_SATA_TXN<7>")
	)
	(segment
		(start 392.448542 -141.253718)
		(end 398.006824 -141.253718)
		(width 0.1143)
		(layer "In2.Cu")
		(net "SATA6G_PCH_PCIE_UP_SATA_TXN<7>")
	)
	(segment
		(start 376.9106 -132.5118)
		(end 377.232418 -132.5118)
		(width 0.1143)
		(layer "In2.Cu")
		(net "SATA6G_PCH_PCIE_UP_SATA_TXN<7>")
	)
	(segment
		(start 375.840752 -129.847848)
		(end 375.793 -129.8956)
		(width 0.1143)
		(layer "In2.Cu")
		(net "SATA6G_PCH_PCIE_UP_SATA_TXN<7>")
	)
	(segment
		(start 399.294604 -146.450558)
		(end 399.880582 -147.036536)
		(width 0.1143)
		(layer "In2.Cu")
		(net "SATA6G_PCH_PCIE_UP_SATA_TXN<7>")
	)
	(segment
		(start 383.111756 -138.381232)
		(end 383.111756 -139.459716)
		(width 0.1143)
		(layer "In2.Cu")
		(net "SATA6G_PCH_PCIE_UP_SATA_TXN<7>")
	)
	(segment
		(start 398.996662 -142.158466)
		(end 398.996916 -142.158212)
		(width 0.1143)
		(layer "In2.Cu")
		(net "SATA6G_PCH_PCIE_UP_SATA_TXN<7>")
	)
	(segment
		(start 385.289806 -140.012166)
		(end 390.470136 -140.012166)
		(width 0.1143)
		(layer "In2.Cu")
		(net "SATA6G_PCH_PCIE_UP_SATA_TXN<7>")
	)
	(segment
		(start 398.996916 -142.158212)
		(end 398.996916 -145.731992)
		(width 0.1143)
		(layer "In2.Cu")
		(net "SATA6G_PCH_PCIE_UP_SATA_TXN<7>")
	)
	(segment
		(start 381.184658 -139.784836)
		(end 381.214122 -139.8143)
		(width 0.1143)
		(layer "In2.Cu")
		(net "SATA6G_PCH_PCIE_UP_SATA_TXN<7>")
	)
	(segment
		(start 406.196292 -147.59305)
		(end 407.513282 -147.59305)
		(width 0.1143)
		(layer "In2.Cu")
		(net "SATA6G_PCH_PCIE_UP_SATA_TXN<7>")
	)
	(segment
		(start 384.216656 -139.459716)
		(end 384.216656 -138.381232)
		(width 0.1143)
		(layer "In2.Cu")
		(net "SATA6G_PCH_PCIE_UP_SATA_TXN<7>")
	)
	(segment
		(start 384.737356 -138.381232)
		(end 384.737356 -139.459716)
		(width 0.1143)
		(layer "In2.Cu")
		(net "SATA6G_PCH_PCIE_UP_SATA_TXN<7>")
	)
	(segment
		(start 381.691134 -140.012166)
		(end 382.038606 -140.012166)
		(width 0.1143)
		(layer "In2.Cu")
		(net "SATA6G_PCH_PCIE_UP_SATA_TXN<7>")
	)
	(segment
		(start 378.054108 -135.511032)
		(end 380.934976 -138.3919)
		(width 0.1143)
		(layer "In2.Cu")
		(net "SATA6G_PCH_PCIE_UP_SATA_TXN<7>")
	)
	(segment
		(start 375.6406 -131.6228)
		(end 376.26036 -132.242306)
		(width 0.1143)
		(layer "In2.Cu")
		(net "SATA6G_PCH_PCIE_UP_SATA_TXN<7>")
	)
	(segment
		(start 375.76125 -129.02565)
		(end 375.861072 -129.125472)
		(width 0.1143)
		(layer "In2.Cu")
		(net "SATA6G_PCH_PCIE_UP_SATA_TXN<7>")
	)
	(segment
		(start 404.810976 -146.731482)
		(end 405.30272 -147.223226)
		(width 0.1143)
		(layer "In2.Cu")
		(net "SATA6G_PCH_PCIE_UP_SATA_TXN<7>")
	)
	(segment
		(start 403.066758 -146.64944)
		(end 404.61311 -146.64944)
		(width 0.1143)
		(layer "In2.Cu")
		(net "SATA6G_PCH_PCIE_UP_SATA_TXN<7>")
	)
	(segment
		(start 398.57299 -141.48816)
		(end 398.822672 -141.737842)
		(width 0.1143)
		(layer "In2.Cu")
		(net "SATA6G_PCH_PCIE_UP_SATA_TXN<7>")
	)
	(segment
		(start 402.495766 -147.104608)
		(end 402.868892 -146.731482)
		(width 0.1143)
		(layer "In2.Cu")
		(net "SATA6G_PCH_PCIE_UP_SATA_TXN<7>")
	)
	(segment
		(start 375.5136 -130.570224)
		(end 375.5136 -131.316222)
		(width 0.1143)
		(layer "In2.Cu")
		(net "SATA6G_PCH_PCIE_UP_SATA_TXN<7>")
	)
	(segment
		(start 382.591056 -139.459716)
		(end 382.591056 -138.381232)
		(width 0.1143)
		(layer "In2.Cu")
		(net "SATA6G_PCH_PCIE_UP_SATA_TXN<7>")
	)
	(arc
		(start 398.006824 -141.253718)
		(mid 398.313218 -141.314646)
		(end 398.57299 -141.48816)
		(width 0.1143)
		(layer "In2.Cu")
		(net "SATA6G_PCH_PCIE_UP_SATA_TXN<7>")
	)
	(arc
		(start 398.822672 -141.737842)
		(mid 398.951483 -141.930855)
		(end 398.996662 -142.158466)
		(width 0.1143)
		(layer "In2.Cu")
		(net "SATA6G_PCH_PCIE_UP_SATA_TXN<7>")
	)
	(arc
		(start 375.8946 -129.7178)
		(mid 375.880602 -129.788174)
		(end 375.840752 -129.847848)
		(width 0.1143)
		(layer "In2.Cu")
		(net "SATA6G_PCH_PCIE_UP_SATA_TXN<7>")
	)
	(arc
		(start 398.996916 -145.731992)
		(mid 399.074274 -146.120896)
		(end 399.294604 -146.450558)
		(width 0.1143)
		(layer "In2.Cu")
		(net "SATA6G_PCH_PCIE_UP_SATA_TXN<7>")
	)
	(arc
		(start 391.856214 -141.008354)
		(mid 392.127976 -141.18994)
		(end 392.448542 -141.253718)
		(width 0.1143)
		(layer "In2.Cu")
		(net "SATA6G_PCH_PCIE_UP_SATA_TXN<7>")
	)
	(arc
		(start 404.61311 -146.64944)
		(mid 404.720212 -146.670762)
		(end 404.810976 -146.731482)
		(width 0.1143)
		(layer "In2.Cu")
		(net "SATA6G_PCH_PCIE_UP_SATA_TXN<7>")
	)
	(arc
		(start 399.880582 -147.036536)
		(mid 400.141491 -147.210963)
		(end 400.449288 -147.272248)
		(width 0.1143)
		(layer "In2.Cu")
		(net "SATA6G_PCH_PCIE_UP_SATA_TXN<7>")
	)
	(arc
		(start 390.470136 -140.012166)
		(mid 390.830448 -140.083854)
		(end 391.13587 -140.28801)
		(width 0.1143)
		(layer "In2.Cu")
		(net "SATA6G_PCH_PCIE_UP_SATA_TXN<7>")
	)
	(arc
		(start 402.091398 -147.272248)
		(mid 402.310242 -147.228624)
		(end 402.495766 -147.104608)
		(width 0.1143)
		(layer "In2.Cu")
		(net "SATA6G_PCH_PCIE_UP_SATA_TXN<7>")
	)
	(arc
		(start 405.30272 -147.223226)
		(mid 405.712724 -147.497025)
		(end 406.196292 -147.59305)
		(width 0.1143)
		(layer "In2.Cu")
		(net "SATA6G_PCH_PCIE_UP_SATA_TXN<7>")
	)
	(arc
		(start 376.26036 -132.242306)
		(mid 376.558678 -132.441728)
		(end 376.9106 -132.5118)
		(width 0.1143)
		(layer "In2.Cu")
		(net "SATA6G_PCH_PCIE_UP_SATA_TXN<7>")
	)
	(arc
		(start 407.513282 -147.59305)
		(mid 407.557023 -147.601751)
		(end 407.594054 -147.626578)
		(width 0.1143)
		(layer "In2.Cu")
		(net "SATA6G_PCH_PCIE_UP_SATA_TXN<7>")
	)
	(arc
		(start 381.214122 -139.8143)
		(mid 381.432699 -139.960627)
		(end 381.690626 -140.012166)
		(width 0.1143)
		(layer "In2.Cu")
		(net "SATA6G_PCH_PCIE_UP_SATA_TXN<7>")
	)
	(arc
		(start 377.7234 -134.71271)
		(mid 377.809342 -135.144771)
		(end 378.054108 -135.511032)
		(width 0.1143)
		(layer "In2.Cu")
		(net "SATA6G_PCH_PCIE_UP_SATA_TXN<7>")
	)
	(arc
		(start 375.793 -129.8956)
		(mid 375.586185 -130.20512)
		(end 375.5136 -130.570224)
		(width 0.1143)
		(layer "In2.Cu")
		(net "SATA6G_PCH_PCIE_UP_SATA_TXN<7>")
	)
	(arc
		(start 375.861072 -129.125472)
		(mid 375.885834 -129.162531)
		(end 375.8946 -129.206244)
		(width 0.1143)
		(layer "In2.Cu")
		(net "SATA6G_PCH_PCIE_UP_SATA_TXN<7>")
	)
	(arc
		(start 402.868892 -146.731482)
		(mid 402.959659 -146.67077)
		(end 403.066758 -146.64944)
		(width 0.1143)
		(layer "In2.Cu")
		(net "SATA6G_PCH_PCIE_UP_SATA_TXN<7>")
	)
	(arc
		(start 382.591056 -138.381232)
		(mid 382.851406 -138.120882)
		(end 383.111756 -138.381232)
		(width 0.1143)
		(layer "In2.Cu")
		(net "SATA6G_PCH_PCIE_UP_SATA_TXN<7>")
	)
	(arc
		(start 381.690626 -140.012166)
		(mid 381.69088 -140.012166)
		(end 381.691134 -140.012166)
		(width 0.1143)
		(layer "In2.Cu")
		(net "SATA6G_PCH_PCIE_UP_SATA_TXN<7>")
	)
	(arc
		(start 380.934976 -138.3919)
		(mid 381.029925 -138.533957)
		(end 381.063246 -138.701526)
		(width 0.1143)
		(layer "In2.Cu")
		(net "SATA6G_PCH_PCIE_UP_SATA_TXN<7>")
	)
	(arc
		(start 382.038606 -140.012166)
		(mid 382.429247 -139.850357)
		(end 382.591056 -139.459716)
		(width 0.1143)
		(layer "In2.Cu")
		(net "SATA6G_PCH_PCIE_UP_SATA_TXN<7>")
	)
	(arc
		(start 383.111756 -139.459716)
		(mid 383.664206 -140.012166)
		(end 384.216656 -139.459716)
		(width 0.1143)
		(layer "In2.Cu")
		(net "SATA6G_PCH_PCIE_UP_SATA_TXN<7>")
	)
	(arc
		(start 381.063246 -139.492228)
		(mid 381.094844 -139.650613)
		(end 381.184658 -139.784836)
		(width 0.1143)
		(layer "In2.Cu")
		(net "SATA6G_PCH_PCIE_UP_SATA_TXN<7>")
	)
	(arc
		(start 384.216656 -138.381232)
		(mid 384.477006 -138.120882)
		(end 384.737356 -138.381232)
		(width 0.1143)
		(layer "In2.Cu")
		(net "SATA6G_PCH_PCIE_UP_SATA_TXN<7>")
	)
	(arc
		(start 377.232418 -132.5118)
		(mid 377.579595 -132.655605)
		(end 377.7234 -133.002782)
		(width 0.1143)
		(layer "In2.Cu")
		(net "SATA6G_PCH_PCIE_UP_SATA_TXN<7>")
	)
	(arc
		(start 384.737356 -139.459716)
		(mid 384.899165 -139.850357)
		(end 385.289806 -140.012166)
		(width 0.1143)
		(layer "In2.Cu")
		(net "SATA6G_PCH_PCIE_UP_SATA_TXN<7>")
	)
	(arc
		(start 375.5136 -131.316222)
		(mid 375.546604 -131.482145)
		(end 375.6406 -131.6228)
		(width 0.1143)
		(layer "In2.Cu")
		(net "SATA6G_PCH_PCIE_UP_SATA_TXN<7>")
	)
	(segment
		(start 377.366022 -128.128014)
		(end 377.366022 -129.032)
		(width 0.0889)
		(layer "F.Cu")
		(net "SATA6G_PCH_PCIE_UP_SATA_TXN<6>")
	)
	(segment
		(start 379.321822 -125.38075)
		(end 379.284738 -125.485652)
		(width 0.0889)
		(layer "F.Cu")
		(net "SATA6G_PCH_PCIE_UP_SATA_TXN<6>")
	)
	(segment
		(start 379.271276 -126.068074)
		(end 379.271276 -126.33706)
		(width 0.0889)
		(layer "F.Cu")
		(net "SATA6G_PCH_PCIE_UP_SATA_TXN<6>")
	)
	(segment
		(start 379.039628 -127.050292)
		(end 378.267468 -127.822452)
		(width 0.0889)
		(layer "F.Cu")
		(net "SATA6G_PCH_PCIE_UP_SATA_TXN<6>")
	)
	(segment
		(start 379.271276 -126.33706)
		(end 379.147832 -126.460504)
		(width 0.0889)
		(layer "F.Cu")
		(net "SATA6G_PCH_PCIE_UP_SATA_TXN<6>")
	)
	(segment
		(start 379.17247 -125.59792)
		(end 379.17247 -125.829314)
		(width 0.0889)
		(layer "F.Cu")
		(net "SATA6G_PCH_PCIE_UP_SATA_TXN<6>")
	)
	(segment
		(start 379.17247 -125.829314)
		(end 379.271276 -126.068074)
		(width 0.0889)
		(layer "F.Cu")
		(net "SATA6G_PCH_PCIE_UP_SATA_TXN<6>")
	)
	(segment
		(start 379.48489 -124.919994)
		(end 379.321822 -125.38075)
		(width 0.0889)
		(layer "F.Cu")
		(net "SATA6G_PCH_PCIE_UP_SATA_TXN<6>")
	)
	(segment
		(start 378.204476 -127.848614)
		(end 377.645422 -127.848614)
		(width 0.0889)
		(layer "F.Cu")
		(net "SATA6G_PCH_PCIE_UP_SATA_TXN<6>")
	)
	(segment
		(start 379.06579 -126.65837)
		(end 379.06579 -126.9873)
		(width 0.0889)
		(layer "F.Cu")
		(net "SATA6G_PCH_PCIE_UP_SATA_TXN<6>")
	)
	(segment
		(start 379.284738 -125.485652)
		(end 379.17247 -125.59792)
		(width 0.0889)
		(layer "F.Cu")
		(net "SATA6G_PCH_PCIE_UP_SATA_TXN<6>")
	)
	(via
		(at 408.313382 -142.657576)
		(size 0.508)
		(drill 0.254)
		(layers "F.Cu" "B.Cu")
		(net "SATA6G_PCH_PCIE_UP_SATA_TXN<6>")
	)
	(via
		(at 377.366022 -129.032)
		(size 0.508)
		(drill 0.254)
		(layers "F.Cu" "B.Cu")
		(net "SATA6G_PCH_PCIE_UP_SATA_TXN<6>")
	)
	(arc
		(start 377.645422 -127.848614)
		(mid 377.447856 -127.930448)
		(end 377.366022 -128.128014)
		(width 0.0889)
		(layer "F.Cu")
		(net "SATA6G_PCH_PCIE_UP_SATA_TXN<6>")
	)
	(arc
		(start 379.147832 -126.460504)
		(mid 379.08712 -126.551271)
		(end 379.06579 -126.65837)
		(width 0.0889)
		(layer "F.Cu")
		(net "SATA6G_PCH_PCIE_UP_SATA_TXN<6>")
	)
	(arc
		(start 378.267468 -127.822452)
		(mid 378.238581 -127.841817)
		(end 378.204476 -127.848614)
		(width 0.0889)
		(layer "F.Cu")
		(net "SATA6G_PCH_PCIE_UP_SATA_TXN<6>")
	)
	(arc
		(start 379.06579 -126.9873)
		(mid 379.058988 -127.021404)
		(end 379.039628 -127.050292)
		(width 0.0889)
		(layer "F.Cu")
		(net "SATA6G_PCH_PCIE_UP_SATA_TXN<6>")
	)
	(segment
		(start 410.21 -142.0368)
		(end 409.92425 -141.75105)
		(width 0.1143)
		(layer "B.Cu")
		(net "SATA6G_PCH_PCIE_UP_SATA_TXN<6>")
	)
	(segment
		(start 409.007564 -142.120874)
		(end 408.770582 -142.120874)
		(width 0.1143)
		(layer "B.Cu")
		(net "SATA6G_PCH_PCIE_UP_SATA_TXN<6>")
	)
	(segment
		(start 408.313382 -142.57782)
		(end 408.313382 -142.657576)
		(width 0.1143)
		(layer "B.Cu")
		(net "SATA6G_PCH_PCIE_UP_SATA_TXN<6>")
	)
	(segment
		(start 409.843224 -141.717522)
		(end 409.605988 -141.717522)
		(width 0.1143)
		(layer "B.Cu")
		(net "SATA6G_PCH_PCIE_UP_SATA_TXN<6>")
	)
	(segment
		(start 409.524962 -141.75105)
		(end 409.259278 -142.016734)
		(width 0.1143)
		(layer "B.Cu")
		(net "SATA6G_PCH_PCIE_UP_SATA_TXN<6>")
	)
	(segment
		(start 408.689556 -142.154402)
		(end 408.34691 -142.497048)
		(width 0.1143)
		(layer "B.Cu")
		(net "SATA6G_PCH_PCIE_UP_SATA_TXN<6>")
	)
	(arc
		(start 409.92425 -141.75105)
		(mid 409.887075 -141.72621)
		(end 409.843224 -141.717522)
		(width 0.1143)
		(layer "B.Cu")
		(net "SATA6G_PCH_PCIE_UP_SATA_TXN<6>")
	)
	(arc
		(start 408.770582 -142.120874)
		(mid 408.726744 -142.129594)
		(end 408.689556 -142.154402)
		(width 0.1143)
		(layer "B.Cu")
		(net "SATA6G_PCH_PCIE_UP_SATA_TXN<6>")
	)
	(arc
		(start 408.34691 -142.497048)
		(mid 408.322148 -142.534107)
		(end 408.313382 -142.57782)
		(width 0.1143)
		(layer "B.Cu")
		(net "SATA6G_PCH_PCIE_UP_SATA_TXN<6>")
	)
	(arc
		(start 409.259278 -142.016734)
		(mid 409.143762 -142.093793)
		(end 409.007564 -142.120874)
		(width 0.1143)
		(layer "B.Cu")
		(net "SATA6G_PCH_PCIE_UP_SATA_TXN<6>")
	)
	(arc
		(start 409.605988 -141.717522)
		(mid 409.56215 -141.726242)
		(end 409.524962 -141.75105)
		(width 0.1143)
		(layer "B.Cu")
		(net "SATA6G_PCH_PCIE_UP_SATA_TXN<6>")
	)
	(segment
		(start 401.719796 -140.639038)
		(end 401.977352 -140.896594)
		(width 0.1143)
		(layer "In2.Cu")
		(net "SATA6G_PCH_PCIE_UP_SATA_TXN<6>")
	)
	(segment
		(start 384.601974 -135.553958)
		(end 384.781044 -135.553958)
		(width 0.1143)
		(layer "In2.Cu")
		(net "SATA6G_PCH_PCIE_UP_SATA_TXN<6>")
	)
	(segment
		(start 377.44908 -129.162302)
		(end 377.44908 -129.798318)
		(width 0.1143)
		(layer "In2.Cu")
		(net "SATA6G_PCH_PCIE_UP_SATA_TXN<6>")
	)
	(segment
		(start 382.516888 -135.966708)
		(end 382.516888 -135.856218)
		(width 0.1143)
		(layer "In2.Cu")
		(net "SATA6G_PCH_PCIE_UP_SATA_TXN<6>")
	)
	(segment
		(start 382.819148 -135.553958)
		(end 383.073148 -135.553958)
		(width 0.1143)
		(layer "In2.Cu")
		(net "SATA6G_PCH_PCIE_UP_SATA_TXN<6>")
	)
	(segment
		(start 378.500894 -130.349244)
		(end 379.447044 -129.40284)
		(width 0.1143)
		(layer "In2.Cu")
		(net "SATA6G_PCH_PCIE_UP_SATA_TXN<6>")
	)
	(segment
		(start 381.111252 -135.403082)
		(end 381.111506 -135.402828)
		(width 0.1143)
		(layer "In2.Cu")
		(net "SATA6G_PCH_PCIE_UP_SATA_TXN<6>")
	)
	(segment
		(start 407.93289 -142.277084)
		(end 408.313382 -142.657576)
		(width 0.1143)
		(layer "In2.Cu")
		(net "SATA6G_PCH_PCIE_UP_SATA_TXN<6>")
	)
	(segment
		(start 382.33223 -136.377426)
		(end 382.35636 -136.353296)
		(width 0.1143)
		(layer "In2.Cu")
		(net "SATA6G_PCH_PCIE_UP_SATA_TXN<6>")
	)
	(segment
		(start 382.59893 -135.658352)
		(end 382.621282 -135.636)
		(width 0.1143)
		(layer "In2.Cu")
		(net "SATA6G_PCH_PCIE_UP_SATA_TXN<6>")
	)
	(segment
		(start 405.12746 -142.342108)
		(end 405.127714 -142.341854)
		(width 0.1143)
		(layer "In2.Cu")
		(net "SATA6G_PCH_PCIE_UP_SATA_TXN<6>")
	)
	(segment
		(start 405.364188 -142.243556)
		(end 407.852118 -142.243556)
		(width 0.1143)
		(layer "In2.Cu")
		(net "SATA6G_PCH_PCIE_UP_SATA_TXN<6>")
	)
	(segment
		(start 381.737362 -136.542018)
		(end 381.93472 -136.542018)
		(width 0.1143)
		(layer "In2.Cu")
		(net "SATA6G_PCH_PCIE_UP_SATA_TXN<6>")
	)
	(segment
		(start 401.049998 -140.913612)
		(end 401.324572 -140.639038)
		(width 0.1143)
		(layer "In2.Cu")
		(net "SATA6G_PCH_PCIE_UP_SATA_TXN<6>")
	)
	(segment
		(start 400.555968 -139.843764)
		(end 400.268186 -140.131546)
		(width 0.1143)
		(layer "In2.Cu")
		(net "SATA6G_PCH_PCIE_UP_SATA_TXN<6>")
	)
	(segment
		(start 384.861816 -135.58774)
		(end 387.54812 -138.274044)
		(width 0.1143)
		(layer "In2.Cu")
		(net "SATA6G_PCH_PCIE_UP_SATA_TXN<6>")
	)
	(segment
		(start 381.279146 -136.32053)
		(end 381.332994 -136.374378)
		(width 0.1143)
		(layer "In2.Cu")
		(net "SATA6G_PCH_PCIE_UP_SATA_TXN<6>")
	)
	(segment
		(start 400.268186 -140.91285)
		(end 400.268948 -140.913612)
		(width 0.1143)
		(layer "In2.Cu")
		(net "SATA6G_PCH_PCIE_UP_SATA_TXN<6>")
	)
	(segment
		(start 377.366022 -129.032)
		(end 377.415552 -129.08153)
		(width 0.1143)
		(layer "In2.Cu")
		(net "SATA6G_PCH_PCIE_UP_SATA_TXN<6>")
	)
	(segment
		(start 383.841752 -136.532112)
		(end 383.904998 -136.532112)
		(width 0.1143)
		(layer "In2.Cu")
		(net "SATA6G_PCH_PCIE_UP_SATA_TXN<6>")
	)
	(segment
		(start 379.59157 -129.976626)
		(end 379.146308 -130.422396)
		(width 0.1143)
		(layer "In2.Cu")
		(net "SATA6G_PCH_PCIE_UP_SATA_TXN<6>")
	)
	(segment
		(start 405.026368 -142.585694)
		(end 405.026622 -142.585948)
		(width 0.1143)
		(layer "In2.Cu")
		(net "SATA6G_PCH_PCIE_UP_SATA_TXN<6>")
	)
	(segment
		(start 403.09165 -145.048732)
		(end 404.409402 -145.048732)
		(width 0.1143)
		(layer "In2.Cu")
		(net "SATA6G_PCH_PCIE_UP_SATA_TXN<6>")
	)
	(segment
		(start 387.900164 -138.41984)
		(end 399.365216 -138.41984)
		(width 0.1143)
		(layer "In2.Cu")
		(net "SATA6G_PCH_PCIE_UP_SATA_TXN<6>")
	)
	(segment
		(start 384.457448 -135.979662)
		(end 384.457448 -135.698484)
		(width 0.1143)
		(layer "In2.Cu")
		(net "SATA6G_PCH_PCIE_UP_SATA_TXN<6>")
	)
	(segment
		(start 402.474938 -144.7419)
		(end 402.562568 -144.82953)
		(width 0.1143)
		(layer "In2.Cu")
		(net "SATA6G_PCH_PCIE_UP_SATA_TXN<6>")
	)
	(segment
		(start 399.595848 -138.515344)
		(end 400.555968 -139.475464)
		(width 0.1143)
		(layer "In2.Cu")
		(net "SATA6G_PCH_PCIE_UP_SATA_TXN<6>")
	)
	(segment
		(start 379.146562 -131.22402)
		(end 379.789944 -131.867402)
		(width 0.1143)
		(layer "In2.Cu")
		(net "SATA6G_PCH_PCIE_UP_SATA_TXN<6>")
	)
	(segment
		(start 377.589288 -130.136646)
		(end 377.801886 -130.349244)
		(width 0.1143)
		(layer "In2.Cu")
		(net "SATA6G_PCH_PCIE_UP_SATA_TXN<6>")
	)
	(segment
		(start 405.026368 -144.431766)
		(end 405.026368 -142.585694)
		(width 0.1143)
		(layer "In2.Cu")
		(net "SATA6G_PCH_PCIE_UP_SATA_TXN<6>")
	)
	(segment
		(start 381.111506 -135.402828)
		(end 381.111506 -135.916162)
		(width 0.1143)
		(layer "In2.Cu")
		(net "SATA6G_PCH_PCIE_UP_SATA_TXN<6>")
	)
	(segment
		(start 380.212092 -134.06755)
		(end 380.802896 -134.658354)
		(width 0.1143)
		(layer "In2.Cu")
		(net "SATA6G_PCH_PCIE_UP_SATA_TXN<6>")
	)
	(segment
		(start 379.9459 -132.243068)
		(end 379.9459 -133.424422)
		(width 0.1143)
		(layer "In2.Cu")
		(net "SATA6G_PCH_PCIE_UP_SATA_TXN<6>")
	)
	(segment
		(start 402.26361 -141.587728)
		(end 402.26361 -144.231614)
		(width 0.1143)
		(layer "In2.Cu")
		(net "SATA6G_PCH_PCIE_UP_SATA_TXN<6>")
	)
	(segment
		(start 379.945646 -132.243322)
		(end 379.9459 -132.243068)
		(width 0.1143)
		(layer "In2.Cu")
		(net "SATA6G_PCH_PCIE_UP_SATA_TXN<6>")
	)
	(segment
		(start 383.352548 -135.833358)
		(end 383.352548 -136.042908)
		(width 0.1143)
		(layer "In2.Cu")
		(net "SATA6G_PCH_PCIE_UP_SATA_TXN<6>")
	)
	(segment
		(start 405.127206 -142.342108)
		(end 405.12746 -142.342108)
		(width 0.1143)
		(layer "In2.Cu")
		(net "SATA6G_PCH_PCIE_UP_SATA_TXN<6>")
	)
	(arc
		(start 401.324572 -140.639038)
		(mid 401.522184 -140.557184)
		(end 401.719796 -140.639038)
		(width 0.1143)
		(layer "In2.Cu")
		(net "SATA6G_PCH_PCIE_UP_SATA_TXN<6>")
	)
	(arc
		(start 384.781044 -135.553958)
		(mid 384.8248 -135.562791)
		(end 384.861816 -135.58774)
		(width 0.1143)
		(layer "In2.Cu")
		(net "SATA6G_PCH_PCIE_UP_SATA_TXN<6>")
	)
	(arc
		(start 404.409402 -145.048732)
		(mid 404.845663 -144.868027)
		(end 405.026368 -144.431766)
		(width 0.1143)
		(layer "In2.Cu")
		(net "SATA6G_PCH_PCIE_UP_SATA_TXN<6>")
	)
	(arc
		(start 407.852118 -142.243556)
		(mid 407.895859 -142.252257)
		(end 407.93289 -142.277084)
		(width 0.1143)
		(layer "In2.Cu")
		(net "SATA6G_PCH_PCIE_UP_SATA_TXN<6>")
	)
	(arc
		(start 377.415552 -129.08153)
		(mid 377.440314 -129.118589)
		(end 377.44908 -129.162302)
		(width 0.1143)
		(layer "In2.Cu")
		(net "SATA6G_PCH_PCIE_UP_SATA_TXN<6>")
	)
	(arc
		(start 379.789944 -131.867402)
		(mid 379.905187 -132.039876)
		(end 379.945646 -132.243322)
		(width 0.1143)
		(layer "In2.Cu")
		(net "SATA6G_PCH_PCIE_UP_SATA_TXN<6>")
	)
	(arc
		(start 387.54812 -138.274044)
		(mid 387.709639 -138.381968)
		(end 387.900164 -138.41984)
		(width 0.1143)
		(layer "In2.Cu")
		(net "SATA6G_PCH_PCIE_UP_SATA_TXN<6>")
	)
	(arc
		(start 379.9459 -133.424422)
		(mid 380.015088 -133.772432)
		(end 380.212092 -134.06755)
		(width 0.1143)
		(layer "In2.Cu")
		(net "SATA6G_PCH_PCIE_UP_SATA_TXN<6>")
	)
	(arc
		(start 399.365216 -138.41984)
		(mid 399.490023 -138.444666)
		(end 399.595848 -138.515344)
		(width 0.1143)
		(layer "In2.Cu")
		(net "SATA6G_PCH_PCIE_UP_SATA_TXN<6>")
	)
	(arc
		(start 382.621282 -135.636)
		(mid 382.712049 -135.575288)
		(end 382.819148 -135.553958)
		(width 0.1143)
		(layer "In2.Cu")
		(net "SATA6G_PCH_PCIE_UP_SATA_TXN<6>")
	)
	(arc
		(start 405.127714 -142.341854)
		(mid 405.23618 -142.269223)
		(end 405.364188 -142.243556)
		(width 0.1143)
		(layer "In2.Cu")
		(net "SATA6G_PCH_PCIE_UP_SATA_TXN<6>")
	)
	(arc
		(start 383.904998 -136.532112)
		(mid 384.295639 -136.370303)
		(end 384.457448 -135.979662)
		(width 0.1143)
		(layer "In2.Cu")
		(net "SATA6G_PCH_PCIE_UP_SATA_TXN<6>")
	)
	(arc
		(start 400.268186 -140.131546)
		(mid 400.106373 -140.522198)
		(end 400.268186 -140.91285)
		(width 0.1143)
		(layer "In2.Cu")
		(net "SATA6G_PCH_PCIE_UP_SATA_TXN<6>")
	)
	(arc
		(start 382.35636 -136.353296)
		(mid 382.475143 -136.175999)
		(end 382.516888 -135.966708)
		(width 0.1143)
		(layer "In2.Cu")
		(net "SATA6G_PCH_PCIE_UP_SATA_TXN<6>")
	)
	(arc
		(start 377.44908 -129.798318)
		(mid 377.485521 -129.981432)
		(end 377.589288 -130.136646)
		(width 0.1143)
		(layer "In2.Cu")
		(net "SATA6G_PCH_PCIE_UP_SATA_TXN<6>")
	)
	(arc
		(start 381.93472 -136.542018)
		(mid 382.149841 -136.499246)
		(end 382.33223 -136.377426)
		(width 0.1143)
		(layer "In2.Cu")
		(net "SATA6G_PCH_PCIE_UP_SATA_TXN<6>")
	)
	(arc
		(start 400.555968 -139.475464)
		(mid 400.632245 -139.659614)
		(end 400.555968 -139.843764)
		(width 0.1143)
		(layer "In2.Cu")
		(net "SATA6G_PCH_PCIE_UP_SATA_TXN<6>")
	)
	(arc
		(start 400.268948 -140.913612)
		(mid 400.65951 -141.075425)
		(end 401.049998 -140.913612)
		(width 0.1143)
		(layer "In2.Cu")
		(net "SATA6G_PCH_PCIE_UP_SATA_TXN<6>")
	)
	(arc
		(start 405.026622 -142.585948)
		(mid 405.052659 -142.454021)
		(end 405.127206 -142.342108)
		(width 0.1143)
		(layer "In2.Cu")
		(net "SATA6G_PCH_PCIE_UP_SATA_TXN<6>")
	)
	(arc
		(start 379.146308 -130.422396)
		(mid 378.98054 -130.823223)
		(end 379.146562 -131.22402)
		(width 0.1143)
		(layer "In2.Cu")
		(net "SATA6G_PCH_PCIE_UP_SATA_TXN<6>")
	)
	(arc
		(start 401.977352 -140.896594)
		(mid 402.189228 -141.213689)
		(end 402.26361 -141.587728)
		(width 0.1143)
		(layer "In2.Cu")
		(net "SATA6G_PCH_PCIE_UP_SATA_TXN<6>")
	)
	(arc
		(start 380.802896 -134.658354)
		(mid 381.031226 -135.000025)
		(end 381.111252 -135.403082)
		(width 0.1143)
		(layer "In2.Cu")
		(net "SATA6G_PCH_PCIE_UP_SATA_TXN<6>")
	)
	(arc
		(start 383.073148 -135.553958)
		(mid 383.270714 -135.635792)
		(end 383.352548 -135.833358)
		(width 0.1143)
		(layer "In2.Cu")
		(net "SATA6G_PCH_PCIE_UP_SATA_TXN<6>")
	)
	(arc
		(start 383.352548 -136.042908)
		(mid 383.495833 -136.388827)
		(end 383.841752 -136.532112)
		(width 0.1143)
		(layer "In2.Cu")
		(net "SATA6G_PCH_PCIE_UP_SATA_TXN<6>")
	)
	(arc
		(start 382.516888 -135.856218)
		(mid 382.53821 -135.749116)
		(end 382.59893 -135.658352)
		(width 0.1143)
		(layer "In2.Cu")
		(net "SATA6G_PCH_PCIE_UP_SATA_TXN<6>")
	)
	(arc
		(start 379.447044 -129.40284)
		(mid 379.655151 -129.361292)
		(end 379.77318 -129.537714)
		(width 0.1143)
		(layer "In2.Cu")
		(net "SATA6G_PCH_PCIE_UP_SATA_TXN<6>")
	)
	(arc
		(start 381.332994 -136.374378)
		(mid 381.518505 -136.498425)
		(end 381.737362 -136.542018)
		(width 0.1143)
		(layer "In2.Cu")
		(net "SATA6G_PCH_PCIE_UP_SATA_TXN<6>")
	)
	(arc
		(start 402.26361 -144.231614)
		(mid 402.318525 -144.507778)
		(end 402.474938 -144.7419)
		(width 0.1143)
		(layer "In2.Cu")
		(net "SATA6G_PCH_PCIE_UP_SATA_TXN<6>")
	)
	(arc
		(start 402.562568 -144.82953)
		(mid 402.805299 -144.991781)
		(end 403.09165 -145.048732)
		(width 0.1143)
		(layer "In2.Cu")
		(net "SATA6G_PCH_PCIE_UP_SATA_TXN<6>")
	)
	(arc
		(start 379.77318 -129.537714)
		(mid 379.725976 -129.775206)
		(end 379.59157 -129.976626)
		(width 0.1143)
		(layer "In2.Cu")
		(net "SATA6G_PCH_PCIE_UP_SATA_TXN<6>")
	)
	(arc
		(start 384.457448 -135.698484)
		(mid 384.499779 -135.596289)
		(end 384.601974 -135.553958)
		(width 0.1143)
		(layer "In2.Cu")
		(net "SATA6G_PCH_PCIE_UP_SATA_TXN<6>")
	)
	(arc
		(start 377.801886 -130.349244)
		(mid 378.15139 -130.494013)
		(end 378.500894 -130.349244)
		(width 0.1143)
		(layer "In2.Cu")
		(net "SATA6G_PCH_PCIE_UP_SATA_TXN<6>")
	)
	(arc
		(start 381.111506 -135.916162)
		(mid 381.15513 -136.135006)
		(end 381.279146 -136.32053)
		(width 0.1143)
		(layer "In2.Cu")
		(net "SATA6G_PCH_PCIE_UP_SATA_TXN<6>")
	)
	(segment
		(start 379.603 -126.60376)
		(end 379.603 -127.308102)
		(width 0.0889)
		(layer "F.Cu")
		(net "SATA6G_PCH_PCIE_UP_SATA_TXN<5>")
	)
	(segment
		(start 379.078744 -129.08153)
		(end 378.612146 -129.548128)
		(width 0.0889)
		(layer "F.Cu")
		(net "SATA6G_PCH_PCIE_UP_SATA_TXN<5>")
	)
	(segment
		(start 378.530104 -129.745994)
		(end 378.530104 -131.642104)
		(width 0.0889)
		(layer "F.Cu")
		(net "SATA6G_PCH_PCIE_UP_SATA_TXN<5>")
	)
	(segment
		(start 378.530104 -131.642104)
		(end 378.4854 -132.08)
		(width 0.0889)
		(layer "F.Cu")
		(net "SATA6G_PCH_PCIE_UP_SATA_TXN<5>")
	)
	(segment
		(start 379.699266 -126.507494)
		(end 379.603 -126.60376)
		(width 0.0889)
		(layer "F.Cu")
		(net "SATA6G_PCH_PCIE_UP_SATA_TXN<5>")
	)
	(segment
		(start 379.104906 -127.984504)
		(end 379.104906 -129.018538)
		(width 0.0889)
		(layer "F.Cu")
		(net "SATA6G_PCH_PCIE_UP_SATA_TXN<5>")
	)
	(segment
		(start 379.55855 -127.414782)
		(end 379.186948 -127.786638)
		(width 0.0889)
		(layer "F.Cu")
		(net "SATA6G_PCH_PCIE_UP_SATA_TXN<5>")
	)
	(segment
		(start 379.985016 -125.33503)
		(end 379.96876 -125.38075)
		(width 0.0889)
		(layer "F.Cu")
		(net "SATA6G_PCH_PCIE_UP_SATA_TXN<5>")
	)
	(segment
		(start 379.96876 -125.38075)
		(end 379.931422 -125.485652)
		(width 0.0889)
		(layer "F.Cu")
		(net "SATA6G_PCH_PCIE_UP_SATA_TXN<5>")
	)
	(segment
		(start 379.770894 -125.934978)
		(end 379.699266 -126.006606)
		(width 0.0889)
		(layer "F.Cu")
		(net "SATA6G_PCH_PCIE_UP_SATA_TXN<5>")
	)
	(segment
		(start 379.699266 -126.006606)
		(end 379.699266 -126.507494)
		(width 0.0889)
		(layer "F.Cu")
		(net "SATA6G_PCH_PCIE_UP_SATA_TXN<5>")
	)
	(segment
		(start 379.603 -127.308102)
		(end 379.602746 -127.307848)
		(width 0.0889)
		(layer "F.Cu")
		(net "SATA6G_PCH_PCIE_UP_SATA_TXN<5>")
	)
	(segment
		(start 379.931422 -125.485652)
		(end 379.770894 -125.934978)
		(width 0.0889)
		(layer "F.Cu")
		(net "SATA6G_PCH_PCIE_UP_SATA_TXN<5>")
	)
	(via
		(at 406.86355 -145.37055)
		(size 0.508)
		(drill 0.254)
		(layers "F.Cu" "B.Cu")
		(net "SATA6G_PCH_PCIE_UP_SATA_TXN<5>")
	)
	(via
		(at 378.4854 -132.08)
		(size 0.508)
		(drill 0.254)
		(layers "F.Cu" "B.Cu")
		(net "SATA6G_PCH_PCIE_UP_SATA_TXN<5>")
	)
	(arc
		(start 379.602746 -127.307848)
		(mid 379.591242 -127.365683)
		(end 379.55855 -127.414782)
		(width 0.0889)
		(layer "F.Cu")
		(net "SATA6G_PCH_PCIE_UP_SATA_TXN<5>")
	)
	(arc
		(start 379.104906 -129.018538)
		(mid 379.098104 -129.052642)
		(end 379.078744 -129.08153)
		(width 0.0889)
		(layer "F.Cu")
		(net "SATA6G_PCH_PCIE_UP_SATA_TXN<5>")
	)
	(arc
		(start 379.186948 -127.786638)
		(mid 379.126236 -127.877405)
		(end 379.104906 -127.984504)
		(width 0.0889)
		(layer "F.Cu")
		(net "SATA6G_PCH_PCIE_UP_SATA_TXN<5>")
	)
	(arc
		(start 378.612146 -129.548128)
		(mid 378.551434 -129.638895)
		(end 378.530104 -129.745994)
		(width 0.0889)
		(layer "F.Cu")
		(net "SATA6G_PCH_PCIE_UP_SATA_TXN<5>")
	)
	(segment
		(start 406.86355 -145.0975)
		(end 406.86355 -145.37055)
		(width 0.1143)
		(layer "B.Cu")
		(net "SATA6G_PCH_PCIE_UP_SATA_TXN<5>")
	)
	(segment
		(start 408.290522 -145.927826)
		(end 407.379424 -145.016728)
		(width 0.1143)
		(layer "B.Cu")
		(net "SATA6G_PCH_PCIE_UP_SATA_TXN<5>")
	)
	(segment
		(start 410.972 -146.431)
		(end 410.625798 -146.084798)
		(width 0.1143)
		(layer "B.Cu")
		(net "SATA6G_PCH_PCIE_UP_SATA_TXN<5>")
	)
	(segment
		(start 410.545026 -146.05127)
		(end 408.588718 -146.05127)
		(width 0.1143)
		(layer "B.Cu")
		(net "SATA6G_PCH_PCIE_UP_SATA_TXN<5>")
	)
	(segment
		(start 407.298652 -144.9832)
		(end 406.97785 -144.9832)
		(width 0.1143)
		(layer "B.Cu")
		(net "SATA6G_PCH_PCIE_UP_SATA_TXN<5>")
	)
	(arc
		(start 410.625798 -146.084798)
		(mid 410.588739 -146.060036)
		(end 410.545026 -146.05127)
		(width 0.1143)
		(layer "B.Cu")
		(net "SATA6G_PCH_PCIE_UP_SATA_TXN<5>")
	)
	(arc
		(start 407.379424 -145.016728)
		(mid 407.342365 -144.991966)
		(end 407.298652 -144.9832)
		(width 0.1143)
		(layer "B.Cu")
		(net "SATA6G_PCH_PCIE_UP_SATA_TXN<5>")
	)
	(arc
		(start 408.588718 -146.05127)
		(mid 408.427349 -146.01919)
		(end 408.290522 -145.927826)
		(width 0.1143)
		(layer "B.Cu")
		(net "SATA6G_PCH_PCIE_UP_SATA_TXN<5>")
	)
	(arc
		(start 406.97785 -144.9832)
		(mid 406.897028 -145.016678)
		(end 406.86355 -145.0975)
		(width 0.1143)
		(layer "B.Cu")
		(net "SATA6G_PCH_PCIE_UP_SATA_TXN<5>")
	)
	(segment
		(start 398.454626 -139.224766)
		(end 398.79651 -139.224766)
		(width 0.1143)
		(layer "In2.Cu")
		(net "SATA6G_PCH_PCIE_UP_SATA_TXN<5>")
	)
	(segment
		(start 399.013934 -139.314682)
		(end 399.014188 -139.31519)
		(width 0.1143)
		(layer "In2.Cu")
		(net "SATA6G_PCH_PCIE_UP_SATA_TXN<5>")
	)
	(segment
		(start 387.442456 -139.224766)
		(end 391.923524 -139.224766)
		(width 0.1143)
		(layer "In2.Cu")
		(net "SATA6G_PCH_PCIE_UP_SATA_TXN<5>")
	)
	(segment
		(start 399.210784 -139.788646)
		(end 399.210784 -140.706856)
		(width 0.1143)
		(layer "In2.Cu")
		(net "SATA6G_PCH_PCIE_UP_SATA_TXN<5>")
	)
	(segment
		(start 397.079724 -139.485116)
		(end 397.079724 -139.89431)
		(width 0.1143)
		(layer "In2.Cu")
		(net "SATA6G_PCH_PCIE_UP_SATA_TXN<5>")
	)
	(segment
		(start 395.454124 -139.485116)
		(end 395.454124 -139.89431)
		(width 0.1143)
		(layer "In2.Cu")
		(net "SATA6G_PCH_PCIE_UP_SATA_TXN<5>")
	)
	(segment
		(start 396.559024 -139.89431)
		(end 396.559024 -139.485116)
		(width 0.1143)
		(layer "In2.Cu")
		(net "SATA6G_PCH_PCIE_UP_SATA_TXN<5>")
	)
	(segment
		(start 399.84934 -141.859)
		(end 399.84934 -145.391632)
		(width 0.1143)
		(layer "In2.Cu")
		(net "SATA6G_PCH_PCIE_UP_SATA_TXN<5>")
	)
	(segment
		(start 406.535128 -145.042128)
		(end 406.86355 -145.37055)
		(width 0.1143)
		(layer "In2.Cu")
		(net "SATA6G_PCH_PCIE_UP_SATA_TXN<5>")
	)
	(segment
		(start 394.933424 -139.89431)
		(end 394.933424 -139.485116)
		(width 0.1143)
		(layer "In2.Cu")
		(net "SATA6G_PCH_PCIE_UP_SATA_TXN<5>")
	)
	(segment
		(start 398.184624 -139.89431)
		(end 398.184624 -139.494768)
		(width 0.1143)
		(layer "In2.Cu")
		(net "SATA6G_PCH_PCIE_UP_SATA_TXN<5>")
	)
	(segment
		(start 378.6632 -132.305044)
		(end 378.6632 -134.603744)
		(width 0.1143)
		(layer "In2.Cu")
		(net "SATA6G_PCH_PCIE_UP_SATA_TXN<5>")
	)
	(segment
		(start 378.944124 -135.281924)
		(end 380.836932 -137.174732)
		(width 0.1143)
		(layer "In2.Cu")
		(net "SATA6G_PCH_PCIE_UP_SATA_TXN<5>")
	)
	(segment
		(start 399.405602 -141.176248)
		(end 399.679922 -141.450822)
		(width 0.1143)
		(layer "In2.Cu")
		(net "SATA6G_PCH_PCIE_UP_SATA_TXN<5>")
	)
	(segment
		(start 378.4854 -132.08)
		(end 378.629672 -132.224272)
		(width 0.1143)
		(layer "In2.Cu")
		(net "SATA6G_PCH_PCIE_UP_SATA_TXN<5>")
	)
	(segment
		(start 400.07413 -145.934176)
		(end 400.351752 -146.211798)
		(width 0.1143)
		(layer "In2.Cu")
		(net "SATA6G_PCH_PCIE_UP_SATA_TXN<5>")
	)
	(segment
		(start 406.110694 -145.0086)
		(end 406.454356 -145.0086)
		(width 0.1143)
		(layer "In2.Cu")
		(net "SATA6G_PCH_PCIE_UP_SATA_TXN<5>")
	)
	(segment
		(start 393.307824 -139.89431)
		(end 393.307824 -139.485116)
		(width 0.1143)
		(layer "In2.Cu")
		(net "SATA6G_PCH_PCIE_UP_SATA_TXN<5>")
	)
	(segment
		(start 402.69795 -145.857722)
		(end 404.672546 -145.857722)
		(width 0.1143)
		(layer "In2.Cu")
		(net "SATA6G_PCH_PCIE_UP_SATA_TXN<5>")
	)
	(segment
		(start 381.219202 -137.33272)
		(end 385.009136 -137.33272)
		(width 0.1143)
		(layer "In2.Cu")
		(net "SATA6G_PCH_PCIE_UP_SATA_TXN<5>")
	)
	(segment
		(start 400.873722 -146.427698)
		(end 401.642834 -146.427698)
		(width 0.1143)
		(layer "In2.Cu")
		(net "SATA6G_PCH_PCIE_UP_SATA_TXN<5>")
	)
	(segment
		(start 402.190458 -146.20113)
		(end 402.417534 -145.974054)
		(width 0.1143)
		(layer "In2.Cu")
		(net "SATA6G_PCH_PCIE_UP_SATA_TXN<5>")
	)
	(segment
		(start 392.202924 -139.504166)
		(end 392.202924 -139.89431)
		(width 0.1143)
		(layer "In2.Cu")
		(net "SATA6G_PCH_PCIE_UP_SATA_TXN<5>")
	)
	(segment
		(start 385.368292 -137.481818)
		(end 386.876798 -138.990324)
		(width 0.1143)
		(layer "In2.Cu")
		(net "SATA6G_PCH_PCIE_UP_SATA_TXN<5>")
	)
	(segment
		(start 405.380952 -145.564606)
		(end 405.8031 -145.142458)
		(width 0.1143)
		(layer "In2.Cu")
		(net "SATA6G_PCH_PCIE_UP_SATA_TXN<5>")
	)
	(segment
		(start 393.828524 -139.485116)
		(end 393.828524 -139.89431)
		(width 0.1143)
		(layer "In2.Cu")
		(net "SATA6G_PCH_PCIE_UP_SATA_TXN<5>")
	)
	(arc
		(start 401.642834 -146.427698)
		(mid 401.939158 -146.368849)
		(end 402.190458 -146.20113)
		(width 0.1143)
		(layer "In2.Cu")
		(net "SATA6G_PCH_PCIE_UP_SATA_TXN<5>")
	)
	(arc
		(start 399.014188 -139.31519)
		(mid 399.159552 -139.532369)
		(end 399.210784 -139.788646)
		(width 0.1143)
		(layer "In2.Cu")
		(net "SATA6G_PCH_PCIE_UP_SATA_TXN<5>")
	)
	(arc
		(start 398.79651 -139.224766)
		(mid 398.914178 -139.248078)
		(end 399.013934 -139.314682)
		(width 0.1143)
		(layer "In2.Cu")
		(net "SATA6G_PCH_PCIE_UP_SATA_TXN<5>")
	)
	(arc
		(start 395.454124 -139.89431)
		(mid 396.006574 -140.44676)
		(end 396.559024 -139.89431)
		(width 0.1143)
		(layer "In2.Cu")
		(net "SATA6G_PCH_PCIE_UP_SATA_TXN<5>")
	)
	(arc
		(start 394.933424 -139.485116)
		(mid 395.193774 -139.224766)
		(end 395.454124 -139.485116)
		(width 0.1143)
		(layer "In2.Cu")
		(net "SATA6G_PCH_PCIE_UP_SATA_TXN<5>")
	)
	(arc
		(start 399.210784 -140.706856)
		(mid 399.261525 -140.960917)
		(end 399.405602 -141.176248)
		(width 0.1143)
		(layer "In2.Cu")
		(net "SATA6G_PCH_PCIE_UP_SATA_TXN<5>")
	)
	(arc
		(start 398.184624 -139.494768)
		(mid 398.263706 -139.303848)
		(end 398.454626 -139.224766)
		(width 0.1143)
		(layer "In2.Cu")
		(net "SATA6G_PCH_PCIE_UP_SATA_TXN<5>")
	)
	(arc
		(start 391.923524 -139.224766)
		(mid 392.12109 -139.3066)
		(end 392.202924 -139.504166)
		(width 0.1143)
		(layer "In2.Cu")
		(net "SATA6G_PCH_PCIE_UP_SATA_TXN<5>")
	)
	(arc
		(start 393.828524 -139.89431)
		(mid 394.380974 -140.44676)
		(end 394.933424 -139.89431)
		(width 0.1143)
		(layer "In2.Cu")
		(net "SATA6G_PCH_PCIE_UP_SATA_TXN<5>")
	)
	(arc
		(start 399.84934 -145.391632)
		(mid 399.907803 -145.685253)
		(end 400.07413 -145.934176)
		(width 0.1143)
		(layer "In2.Cu")
		(net "SATA6G_PCH_PCIE_UP_SATA_TXN<5>")
	)
	(arc
		(start 396.559024 -139.485116)
		(mid 396.819374 -139.224766)
		(end 397.079724 -139.485116)
		(width 0.1143)
		(layer "In2.Cu")
		(net "SATA6G_PCH_PCIE_UP_SATA_TXN<5>")
	)
	(arc
		(start 378.6632 -134.603744)
		(mid 378.736222 -134.970763)
		(end 378.944124 -135.281924)
		(width 0.1143)
		(layer "In2.Cu")
		(net "SATA6G_PCH_PCIE_UP_SATA_TXN<5>")
	)
	(arc
		(start 378.629672 -132.224272)
		(mid 378.654434 -132.261331)
		(end 378.6632 -132.305044)
		(width 0.1143)
		(layer "In2.Cu")
		(net "SATA6G_PCH_PCIE_UP_SATA_TXN<5>")
	)
	(arc
		(start 386.876798 -138.990324)
		(mid 387.136323 -139.163763)
		(end 387.442456 -139.224766)
		(width 0.1143)
		(layer "In2.Cu")
		(net "SATA6G_PCH_PCIE_UP_SATA_TXN<5>")
	)
	(arc
		(start 392.202924 -139.89431)
		(mid 392.755374 -140.44676)
		(end 393.307824 -139.89431)
		(width 0.1143)
		(layer "In2.Cu")
		(net "SATA6G_PCH_PCIE_UP_SATA_TXN<5>")
	)
	(arc
		(start 380.836932 -137.174732)
		(mid 381.012348 -137.291785)
		(end 381.219202 -137.33272)
		(width 0.1143)
		(layer "In2.Cu")
		(net "SATA6G_PCH_PCIE_UP_SATA_TXN<5>")
	)
	(arc
		(start 397.079724 -139.89431)
		(mid 397.632174 -140.44676)
		(end 398.184624 -139.89431)
		(width 0.1143)
		(layer "In2.Cu")
		(net "SATA6G_PCH_PCIE_UP_SATA_TXN<5>")
	)
	(arc
		(start 405.8031 -145.142458)
		(mid 405.942967 -145.043521)
		(end 406.110694 -145.0086)
		(width 0.1143)
		(layer "In2.Cu")
		(net "SATA6G_PCH_PCIE_UP_SATA_TXN<5>")
	)
	(arc
		(start 385.009136 -137.33272)
		(mid 385.203568 -137.371507)
		(end 385.368292 -137.481818)
		(width 0.1143)
		(layer "In2.Cu")
		(net "SATA6G_PCH_PCIE_UP_SATA_TXN<5>")
	)
	(arc
		(start 399.679922 -141.450822)
		(mid 399.805191 -141.638066)
		(end 399.84934 -141.859)
		(width 0.1143)
		(layer "In2.Cu")
		(net "SATA6G_PCH_PCIE_UP_SATA_TXN<5>")
	)
	(arc
		(start 404.672546 -145.857722)
		(mid 405.05588 -145.781584)
		(end 405.380952 -145.564606)
		(width 0.1143)
		(layer "In2.Cu")
		(net "SATA6G_PCH_PCIE_UP_SATA_TXN<5>")
	)
	(arc
		(start 400.351752 -146.211798)
		(mid 400.591263 -146.371678)
		(end 400.873722 -146.427698)
		(width 0.1143)
		(layer "In2.Cu")
		(net "SATA6G_PCH_PCIE_UP_SATA_TXN<5>")
	)
	(arc
		(start 402.417534 -145.974054)
		(mid 402.546175 -145.888006)
		(end 402.69795 -145.857722)
		(width 0.1143)
		(layer "In2.Cu")
		(net "SATA6G_PCH_PCIE_UP_SATA_TXN<5>")
	)
	(arc
		(start 406.454356 -145.0086)
		(mid 406.498097 -145.017301)
		(end 406.535128 -145.042128)
		(width 0.1143)
		(layer "In2.Cu")
		(net "SATA6G_PCH_PCIE_UP_SATA_TXN<5>")
	)
	(arc
		(start 393.307824 -139.485116)
		(mid 393.568174 -139.224766)
		(end 393.828524 -139.485116)
		(width 0.1143)
		(layer "In2.Cu")
		(net "SATA6G_PCH_PCIE_UP_SATA_TXN<5>")
	)
	(segment
		(start 380.253748 -125.537214)
		(end 380.217172 -125.57379)
		(width 0.0889)
		(layer "F.Cu")
		(net "SATA6G_PCH_PCIE_UP_SATA_TXN<4>")
	)
	(segment
		(start 380.312422 -125.38075)
		(end 380.273052 -125.485652)
		(width 0.0889)
		(layer "F.Cu")
		(net "SATA6G_PCH_PCIE_UP_SATA_TXN<4>")
	)
	(segment
		(start 380.158752 -126.536196)
		(end 380.158752 -127.573024)
		(width 0.0889)
		(layer "F.Cu")
		(net "SATA6G_PCH_PCIE_UP_SATA_TXN<4>")
	)
	(segment
		(start 380.270766 -126.265686)
		(end 380.158752 -126.536196)
		(width 0.0889)
		(layer "F.Cu")
		(net "SATA6G_PCH_PCIE_UP_SATA_TXN<4>")
	)
	(segment
		(start 380.13259 -127.636016)
		(end 379.832616 -127.93599)
		(width 0.0889)
		(layer "F.Cu")
		(net "SATA6G_PCH_PCIE_UP_SATA_TXN<4>")
	)
	(segment
		(start 380.171198 -125.822202)
		(end 380.270766 -126.062486)
		(width 0.0889)
		(layer "F.Cu")
		(net "SATA6G_PCH_PCIE_UP_SATA_TXN<4>")
	)
	(segment
		(start 380.217172 -125.57379)
		(end 380.171198 -125.684788)
		(width 0.0889)
		(layer "F.Cu")
		(net "SATA6G_PCH_PCIE_UP_SATA_TXN<4>")
	)
	(segment
		(start 380.171198 -125.684788)
		(end 380.171198 -125.822202)
		(width 0.0889)
		(layer "F.Cu")
		(net "SATA6G_PCH_PCIE_UP_SATA_TXN<4>")
	)
	(segment
		(start 380.273052 -125.485652)
		(end 380.253748 -125.537214)
		(width 0.0889)
		(layer "F.Cu")
		(net "SATA6G_PCH_PCIE_UP_SATA_TXN<4>")
	)
	(segment
		(start 380.484888 -124.919994)
		(end 380.312422 -125.38075)
		(width 0.0889)
		(layer "F.Cu")
		(net "SATA6G_PCH_PCIE_UP_SATA_TXN<4>")
	)
	(segment
		(start 380.50597 -130.471164)
		(end 380.50597 -131.094988)
		(width 0.0889)
		(layer "F.Cu")
		(net "SATA6G_PCH_PCIE_UP_SATA_TXN<4>")
	)
	(segment
		(start 379.79477 -129.72288)
		(end 380.479808 -130.407918)
		(width 0.0889)
		(layer "F.Cu")
		(net "SATA6G_PCH_PCIE_UP_SATA_TXN<4>")
	)
	(segment
		(start 380.270766 -126.062486)
		(end 380.270766 -126.265686)
		(width 0.0889)
		(layer "F.Cu")
		(net "SATA6G_PCH_PCIE_UP_SATA_TXN<4>")
	)
	(segment
		(start 379.670818 -128.32715)
		(end 379.670818 -129.423668)
		(width 0.0889)
		(layer "F.Cu")
		(net "SATA6G_PCH_PCIE_UP_SATA_TXN<4>")
	)
	(via
		(at 380.50597 -131.094988)
		(size 0.508)
		(drill 0.254)
		(layers "F.Cu" "B.Cu")
		(net "SATA6G_PCH_PCIE_UP_SATA_TXN<4>")
	)
	(via
		(at 412.773876 -142.0368)
		(size 0.508)
		(drill 0.254)
		(layers "F.Cu" "B.Cu")
		(net "SATA6G_PCH_PCIE_UP_SATA_TXN<4>")
	)
	(arc
		(start 379.670818 -129.423668)
		(mid 379.703029 -129.585606)
		(end 379.79477 -129.72288)
		(width 0.0889)
		(layer "F.Cu")
		(net "SATA6G_PCH_PCIE_UP_SATA_TXN<4>")
	)
	(arc
		(start 380.479808 -130.407918)
		(mid 380.499197 -130.436936)
		(end 380.50597 -130.471164)
		(width 0.0889)
		(layer "F.Cu")
		(net "SATA6G_PCH_PCIE_UP_SATA_TXN<4>")
	)
	(arc
		(start 380.158752 -127.573024)
		(mid 380.15195 -127.607128)
		(end 380.13259 -127.636016)
		(width 0.0889)
		(layer "F.Cu")
		(net "SATA6G_PCH_PCIE_UP_SATA_TXN<4>")
	)
	(arc
		(start 379.832616 -127.93599)
		(mid 379.712784 -128.115471)
		(end 379.670818 -128.32715)
		(width 0.0889)
		(layer "F.Cu")
		(net "SATA6G_PCH_PCIE_UP_SATA_TXN<4>")
	)
	(segment
		(start 412.888176 -141.64945)
		(end 413.229806 -141.64945)
		(width 0.1143)
		(layer "B.Cu")
		(net "SATA6G_PCH_PCIE_UP_SATA_TXN<4>")
	)
	(segment
		(start 413.310578 -141.682978)
		(end 413.6644 -142.0368)
		(width 0.1143)
		(layer "B.Cu")
		(net "SATA6G_PCH_PCIE_UP_SATA_TXN<4>")
	)
	(segment
		(start 412.773876 -142.0368)
		(end 412.773876 -141.76375)
		(width 0.1143)
		(layer "B.Cu")
		(net "SATA6G_PCH_PCIE_UP_SATA_TXN<4>")
	)
	(arc
		(start 413.229806 -141.64945)
		(mid 413.273547 -141.658151)
		(end 413.310578 -141.682978)
		(width 0.1143)
		(layer "B.Cu")
		(net "SATA6G_PCH_PCIE_UP_SATA_TXN<4>")
	)
	(arc
		(start 412.773876 -141.76375)
		(mid 412.807354 -141.682928)
		(end 412.888176 -141.64945)
		(width 0.1143)
		(layer "B.Cu")
		(net "SATA6G_PCH_PCIE_UP_SATA_TXN<4>")
	)
	(segment
		(start 404.74138 -139.839192)
		(end 404.555198 -139.839192)
		(width 0.1143)
		(layer "In2.Cu")
		(net "SATA6G_PCH_PCIE_UP_SATA_TXN<4>")
	)
	(segment
		(start 412.773876 -142.0368)
		(end 412.773876 -141.803628)
		(width 0.1143)
		(layer "In2.Cu")
		(net "SATA6G_PCH_PCIE_UP_SATA_TXN<4>")
	)
	(segment
		(start 410.668216 -141.300708)
		(end 410.115258 -141.299438)
		(width 0.1143)
		(layer "In2.Cu")
		(net "SATA6G_PCH_PCIE_UP_SATA_TXN<4>")
	)
	(segment
		(start 403.71903 -144.25295)
		(end 403.598634 -144.25295)
		(width 0.1143)
		(layer "In2.Cu")
		(net "SATA6G_PCH_PCIE_UP_SATA_TXN<4>")
	)
	(segment
		(start 404.238968 -140.092684)
		(end 404.238968 -143.733012)
		(width 0.1143)
		(layer "In2.Cu")
		(net "SATA6G_PCH_PCIE_UP_SATA_TXN<4>")
	)
	(segment
		(start 404.366984 -139.917424)
		(end 404.273004 -140.011404)
		(width 0.1143)
		(layer "In2.Cu")
		(net "SATA6G_PCH_PCIE_UP_SATA_TXN<4>")
	)
	(segment
		(start 388.46379 -137.435082)
		(end 385.409186 -134.380478)
		(width 0.1143)
		(layer "In2.Cu")
		(net "SATA6G_PCH_PCIE_UP_SATA_TXN<4>")
	)
	(segment
		(start 398.517364 -137.05205)
		(end 398.517364 -137.021062)
		(width 0.1143)
		(layer "In2.Cu")
		(net "SATA6G_PCH_PCIE_UP_SATA_TXN<4>")
	)
	(segment
		(start 395.266164 -137.05205)
		(end 395.266164 -137.021062)
		(width 0.1143)
		(layer "In2.Cu")
		(net "SATA6G_PCH_PCIE_UP_SATA_TXN<4>")
	)
	(segment
		(start 410.754068 -143.629126)
		(end 410.754068 -143.437102)
		(width 0.1143)
		(layer "In2.Cu")
		(net "SATA6G_PCH_PCIE_UP_SATA_TXN<4>")
	)
	(segment
		(start 410.421836 -141.821154)
		(end 410.623766 -141.821154)
		(width 0.1143)
		(layer "In2.Cu")
		(net "SATA6G_PCH_PCIE_UP_SATA_TXN<4>")
	)
	(segment
		(start 389.316214 -137.6045)
		(end 388.872984 -137.6045)
		(width 0.1143)
		(layer "In2.Cu")
		(net "SATA6G_PCH_PCIE_UP_SATA_TXN<4>")
	)
	(segment
		(start 408.84348 -140.357352)
		(end 408.84348 -140.107416)
		(width 0.1143)
		(layer "In2.Cu")
		(net "SATA6G_PCH_PCIE_UP_SATA_TXN<4>")
	)
	(segment
		(start 403.229064 -144.099788)
		(end 403.209252 -144.079976)
		(width 0.1143)
		(layer "In2.Cu")
		(net "SATA6G_PCH_PCIE_UP_SATA_TXN<4>")
	)
	(segment
		(start 408.575256 -139.839192)
		(end 407.89098 -139.839192)
		(width 0.1143)
		(layer "In2.Cu")
		(net "SATA6G_PCH_PCIE_UP_SATA_TXN<4>")
	)
	(segment
		(start 409.39466 -140.877544)
		(end 409.363672 -140.877544)
		(width 0.1143)
		(layer "In2.Cu")
		(net "SATA6G_PCH_PCIE_UP_SATA_TXN<4>")
	)
	(segment
		(start 406.56383 -140.88745)
		(end 406.56383 -140.086842)
		(width 0.1143)
		(layer "In2.Cu")
		(net "SATA6G_PCH_PCIE_UP_SATA_TXN<4>")
	)
	(segment
		(start 393.640564 -137.05205)
		(end 393.640564 -137.021062)
		(width 0.1143)
		(layer "In2.Cu")
		(net "SATA6G_PCH_PCIE_UP_SATA_TXN<4>")
	)
	(segment
		(start 380.73584 -133.200394)
		(end 380.73584 -131.372102)
		(width 0.1143)
		(layer "In2.Cu")
		(net "SATA6G_PCH_PCIE_UP_SATA_TXN<4>")
	)
	(segment
		(start 404.092156 -144.08658)
		(end 404.072344 -144.106392)
		(width 0.1143)
		(layer "In2.Cu")
		(net "SATA6G_PCH_PCIE_UP_SATA_TXN<4>")
	)
	(segment
		(start 404.072344 -144.106392)
		(end 404.072598 -144.106392)
		(width 0.1143)
		(layer "In2.Cu")
		(net "SATA6G_PCH_PCIE_UP_SATA_TXN<4>")
	)
	(segment
		(start 410.884116 -141.560804)
		(end 410.884116 -141.515592)
		(width 0.1143)
		(layer "In2.Cu")
		(net "SATA6G_PCH_PCIE_UP_SATA_TXN<4>")
	)
	(segment
		(start 389.868664 -137.021062)
		(end 389.868664 -137.05205)
		(width 0.1143)
		(layer "In2.Cu")
		(net "SATA6G_PCH_PCIE_UP_SATA_TXN<4>")
	)
	(segment
		(start 390.139174 -136.750806)
		(end 390.13892 -136.750806)
		(width 0.1143)
		(layer "In2.Cu")
		(net "SATA6G_PCH_PCIE_UP_SATA_TXN<4>")
	)
	(segment
		(start 404.273004 -140.011404)
		(end 404.27275 -140.011404)
		(width 0.1143)
		(layer "In2.Cu")
		(net "SATA6G_PCH_PCIE_UP_SATA_TXN<4>")
	)
	(segment
		(start 409.828746 -141.180312)
		(end 409.61945 -140.971016)
		(width 0.1143)
		(layer "In2.Cu")
		(net "SATA6G_PCH_PCIE_UP_SATA_TXN<4>")
	)
	(segment
		(start 381.378714 -134.05612)
		(end 380.885954 -133.563614)
		(width 0.1143)
		(layer "In2.Cu")
		(net "SATA6G_PCH_PCIE_UP_SATA_TXN<4>")
	)
	(segment
		(start 396.371064 -137.021062)
		(end 396.371064 -137.05205)
		(width 0.1143)
		(layer "In2.Cu")
		(net "SATA6G_PCH_PCIE_UP_SATA_TXN<4>")
	)
	(segment
		(start 396.891764 -137.05205)
		(end 396.891764 -137.021062)
		(width 0.1143)
		(layer "In2.Cu")
		(net "SATA6G_PCH_PCIE_UP_SATA_TXN<4>")
	)
	(segment
		(start 391.494264 -137.021062)
		(end 391.494264 -137.05205)
		(width 0.1143)
		(layer "In2.Cu")
		(net "SATA6G_PCH_PCIE_UP_SATA_TXN<4>")
	)
	(segment
		(start 403.05609 -143.710406)
		(end 403.05609 -140.968476)
		(width 0.1143)
		(layer "In2.Cu")
		(net "SATA6G_PCH_PCIE_UP_SATA_TXN<4>")
	)
	(segment
		(start 409.869386 -142.55242)
		(end 409.869386 -142.373604)
		(width 0.1143)
		(layer "In2.Cu")
		(net "SATA6G_PCH_PCIE_UP_SATA_TXN<4>")
	)
	(segment
		(start 394.745464 -137.021062)
		(end 394.745464 -137.05205)
		(width 0.1143)
		(layer "In2.Cu")
		(net "SATA6G_PCH_PCIE_UP_SATA_TXN<4>")
	)
	(segment
		(start 402.880576 -140.545566)
		(end 400.101562 -137.766552)
		(width 0.1143)
		(layer "In2.Cu")
		(net "SATA6G_PCH_PCIE_UP_SATA_TXN<4>")
	)
	(segment
		(start 399.710402 -137.6045)
		(end 399.069814 -137.6045)
		(width 0.1143)
		(layer "In2.Cu")
		(net "SATA6G_PCH_PCIE_UP_SATA_TXN<4>")
	)
	(segment
		(start 406.06853 -140.086842)
		(end 406.06853 -140.88745)
		(width 0.1143)
		(layer "In2.Cu")
		(net "SATA6G_PCH_PCIE_UP_SATA_TXN<4>")
	)
	(segment
		(start 412.659576 -141.689328)
		(end 412.379414 -141.689328)
		(width 0.1143)
		(layer "In2.Cu")
		(net "SATA6G_PCH_PCIE_UP_SATA_TXN<4>")
	)
	(segment
		(start 380.702312 -131.29133)
		(end 380.50597 -131.094988)
		(width 0.1143)
		(layer "In2.Cu")
		(net "SATA6G_PCH_PCIE_UP_SATA_TXN<4>")
	)
	(segment
		(start 411.858968 -142.209774)
		(end 411.858968 -143.629126)
		(width 0.1143)
		(layer "In2.Cu")
		(net "SATA6G_PCH_PCIE_UP_SATA_TXN<4>")
	)
	(segment
		(start 407.64333 -140.086842)
		(end 407.64333 -140.88745)
		(width 0.1143)
		(layer "In2.Cu")
		(net "SATA6G_PCH_PCIE_UP_SATA_TXN<4>")
	)
	(segment
		(start 385.113022 -134.257796)
		(end 381.86614 -134.257796)
		(width 0.1143)
		(layer "In2.Cu")
		(net "SATA6G_PCH_PCIE_UP_SATA_TXN<4>")
	)
	(segment
		(start 397.996664 -137.021062)
		(end 397.996664 -137.05205)
		(width 0.1143)
		(layer "In2.Cu")
		(net "SATA6G_PCH_PCIE_UP_SATA_TXN<4>")
	)
	(segment
		(start 390.389364 -137.05205)
		(end 390.389364 -137.000996)
		(width 0.1143)
		(layer "In2.Cu")
		(net "SATA6G_PCH_PCIE_UP_SATA_TXN<4>")
	)
	(segment
		(start 404.98903 -140.88745)
		(end 404.98903 -140.086842)
		(width 0.1143)
		(layer "In2.Cu")
		(net "SATA6G_PCH_PCIE_UP_SATA_TXN<4>")
	)
	(segment
		(start 410.668724 -141.300454)
		(end 410.668216 -141.300708)
		(width 0.1143)
		(layer "In2.Cu")
		(net "SATA6G_PCH_PCIE_UP_SATA_TXN<4>")
	)
	(arc
		(start 412.773876 -141.803628)
		(mid 412.740398 -141.722806)
		(end 412.659576 -141.689328)
		(width 0.1143)
		(layer "In2.Cu")
		(net "SATA6G_PCH_PCIE_UP_SATA_TXN<4>")
	)
	(arc
		(start 404.27275 -140.011404)
		(mid 404.247725 -140.048667)
		(end 404.238968 -140.092684)
		(width 0.1143)
		(layer "In2.Cu")
		(net "SATA6G_PCH_PCIE_UP_SATA_TXN<4>")
	)
	(arc
		(start 409.61945 -140.971016)
		(mid 409.516304 -140.902041)
		(end 409.39466 -140.877544)
		(width 0.1143)
		(layer "In2.Cu")
		(net "SATA6G_PCH_PCIE_UP_SATA_TXN<4>")
	)
	(arc
		(start 410.421836 -143.10487)
		(mid 410.031195 -142.943061)
		(end 409.869386 -142.55242)
		(width 0.1143)
		(layer "In2.Cu")
		(net "SATA6G_PCH_PCIE_UP_SATA_TXN<4>")
	)
	(arc
		(start 410.623766 -141.821154)
		(mid 410.807861 -141.744899)
		(end 410.884116 -141.560804)
		(width 0.1143)
		(layer "In2.Cu")
		(net "SATA6G_PCH_PCIE_UP_SATA_TXN<4>")
	)
	(arc
		(start 381.86614 -134.257796)
		(mid 381.602378 -134.205424)
		(end 381.378714 -134.05612)
		(width 0.1143)
		(layer "In2.Cu")
		(net "SATA6G_PCH_PCIE_UP_SATA_TXN<4>")
	)
	(arc
		(start 389.868664 -137.05205)
		(mid 389.706855 -137.442691)
		(end 389.316214 -137.6045)
		(width 0.1143)
		(layer "In2.Cu")
		(net "SATA6G_PCH_PCIE_UP_SATA_TXN<4>")
	)
	(arc
		(start 404.98903 -140.086842)
		(mid 404.916495 -139.911727)
		(end 404.74138 -139.839192)
		(width 0.1143)
		(layer "In2.Cu")
		(net "SATA6G_PCH_PCIE_UP_SATA_TXN<4>")
	)
	(arc
		(start 393.640564 -137.021062)
		(mid 393.380214 -136.760712)
		(end 393.119864 -137.021062)
		(width 0.1143)
		(layer "In2.Cu")
		(net "SATA6G_PCH_PCIE_UP_SATA_TXN<4>")
	)
	(arc
		(start 397.996664 -137.05205)
		(mid 397.444214 -137.6045)
		(end 396.891764 -137.05205)
		(width 0.1143)
		(layer "In2.Cu")
		(net "SATA6G_PCH_PCIE_UP_SATA_TXN<4>")
	)
	(arc
		(start 391.494264 -137.05205)
		(mid 390.941814 -137.6045)
		(end 390.389364 -137.05205)
		(width 0.1143)
		(layer "In2.Cu")
		(net "SATA6G_PCH_PCIE_UP_SATA_TXN<4>")
	)
	(arc
		(start 410.754068 -143.437102)
		(mid 410.65676 -143.202178)
		(end 410.421836 -143.10487)
		(width 0.1143)
		(layer "In2.Cu")
		(net "SATA6G_PCH_PCIE_UP_SATA_TXN<4>")
	)
	(arc
		(start 407.89098 -139.839192)
		(mid 407.715865 -139.911727)
		(end 407.64333 -140.086842)
		(width 0.1143)
		(layer "In2.Cu")
		(net "SATA6G_PCH_PCIE_UP_SATA_TXN<4>")
	)
	(arc
		(start 396.891764 -137.021062)
		(mid 396.631414 -136.760712)
		(end 396.371064 -137.021062)
		(width 0.1143)
		(layer "In2.Cu")
		(net "SATA6G_PCH_PCIE_UP_SATA_TXN<4>")
	)
	(arc
		(start 398.517364 -137.021062)
		(mid 398.257014 -136.760712)
		(end 397.996664 -137.021062)
		(width 0.1143)
		(layer "In2.Cu")
		(net "SATA6G_PCH_PCIE_UP_SATA_TXN<4>")
	)
	(arc
		(start 392.014964 -137.021062)
		(mid 391.754614 -136.760712)
		(end 391.494264 -137.021062)
		(width 0.1143)
		(layer "In2.Cu")
		(net "SATA6G_PCH_PCIE_UP_SATA_TXN<4>")
	)
	(arc
		(start 406.56383 -140.086842)
		(mid 406.31618 -139.839192)
		(end 406.06853 -140.086842)
		(width 0.1143)
		(layer "In2.Cu")
		(net "SATA6G_PCH_PCIE_UP_SATA_TXN<4>")
	)
	(arc
		(start 395.266164 -137.021062)
		(mid 395.005814 -136.760712)
		(end 394.745464 -137.021062)
		(width 0.1143)
		(layer "In2.Cu")
		(net "SATA6G_PCH_PCIE_UP_SATA_TXN<4>")
	)
	(arc
		(start 380.73584 -131.372102)
		(mid 380.727139 -131.328361)
		(end 380.702312 -131.29133)
		(width 0.1143)
		(layer "In2.Cu")
		(net "SATA6G_PCH_PCIE_UP_SATA_TXN<4>")
	)
	(arc
		(start 388.872984 -137.6045)
		(mid 388.651545 -137.560471)
		(end 388.46379 -137.435082)
		(width 0.1143)
		(layer "In2.Cu")
		(net "SATA6G_PCH_PCIE_UP_SATA_TXN<4>")
	)
	(arc
		(start 408.84348 -140.107416)
		(mid 408.764919 -139.917753)
		(end 408.575256 -139.839192)
		(width 0.1143)
		(layer "In2.Cu")
		(net "SATA6G_PCH_PCIE_UP_SATA_TXN<4>")
	)
	(arc
		(start 404.555198 -139.839192)
		(mid 404.453305 -139.859549)
		(end 404.366984 -139.917424)
		(width 0.1143)
		(layer "In2.Cu")
		(net "SATA6G_PCH_PCIE_UP_SATA_TXN<4>")
	)
	(arc
		(start 399.069814 -137.6045)
		(mid 398.679173 -137.442691)
		(end 398.517364 -137.05205)
		(width 0.1143)
		(layer "In2.Cu")
		(net "SATA6G_PCH_PCIE_UP_SATA_TXN<4>")
	)
	(arc
		(start 403.209252 -144.079976)
		(mid 403.095902 -143.91043)
		(end 403.05609 -143.710406)
		(width 0.1143)
		(layer "In2.Cu")
		(net "SATA6G_PCH_PCIE_UP_SATA_TXN<4>")
	)
	(arc
		(start 407.64333 -140.88745)
		(mid 407.10358 -141.4272)
		(end 406.56383 -140.88745)
		(width 0.1143)
		(layer "In2.Cu")
		(net "SATA6G_PCH_PCIE_UP_SATA_TXN<4>")
	)
	(arc
		(start 394.745464 -137.05205)
		(mid 394.193014 -137.6045)
		(end 393.640564 -137.05205)
		(width 0.1143)
		(layer "In2.Cu")
		(net "SATA6G_PCH_PCIE_UP_SATA_TXN<4>")
	)
	(arc
		(start 409.869386 -142.373604)
		(mid 410.031195 -141.982963)
		(end 410.421836 -141.821154)
		(width 0.1143)
		(layer "In2.Cu")
		(net "SATA6G_PCH_PCIE_UP_SATA_TXN<4>")
	)
	(arc
		(start 410.115258 -141.299438)
		(mid 409.960185 -141.26829)
		(end 409.828746 -141.180312)
		(width 0.1143)
		(layer "In2.Cu")
		(net "SATA6G_PCH_PCIE_UP_SATA_TXN<4>")
	)
	(arc
		(start 390.13892 -136.750806)
		(mid 389.94782 -136.829962)
		(end 389.868664 -137.021062)
		(width 0.1143)
		(layer "In2.Cu")
		(net "SATA6G_PCH_PCIE_UP_SATA_TXN<4>")
	)
	(arc
		(start 403.05609 -140.968476)
		(mid 403.01044 -140.739537)
		(end 402.880576 -140.545566)
		(width 0.1143)
		(layer "In2.Cu")
		(net "SATA6G_PCH_PCIE_UP_SATA_TXN<4>")
	)
	(arc
		(start 400.101562 -137.766552)
		(mid 399.922096 -137.646637)
		(end 399.710402 -137.6045)
		(width 0.1143)
		(layer "In2.Cu")
		(net "SATA6G_PCH_PCIE_UP_SATA_TXN<4>")
	)
	(arc
		(start 393.119864 -137.021062)
		(mid 392.567414 -137.573512)
		(end 392.014964 -137.021062)
		(width 0.1143)
		(layer "In2.Cu")
		(net "SATA6G_PCH_PCIE_UP_SATA_TXN<4>")
	)
	(arc
		(start 410.884116 -141.515592)
		(mid 410.821014 -141.363377)
		(end 410.668724 -141.300454)
		(width 0.1143)
		(layer "In2.Cu")
		(net "SATA6G_PCH_PCIE_UP_SATA_TXN<4>")
	)
	(arc
		(start 406.06853 -140.88745)
		(mid 405.52878 -141.4272)
		(end 404.98903 -140.88745)
		(width 0.1143)
		(layer "In2.Cu")
		(net "SATA6G_PCH_PCIE_UP_SATA_TXN<4>")
	)
	(arc
		(start 390.389364 -137.000996)
		(mid 390.316085 -136.824085)
		(end 390.139174 -136.750806)
		(width 0.1143)
		(layer "In2.Cu")
		(net "SATA6G_PCH_PCIE_UP_SATA_TXN<4>")
	)
	(arc
		(start 396.371064 -137.05205)
		(mid 395.818614 -137.6045)
		(end 395.266164 -137.05205)
		(width 0.1143)
		(layer "In2.Cu")
		(net "SATA6G_PCH_PCIE_UP_SATA_TXN<4>")
	)
	(arc
		(start 404.072598 -144.106392)
		(mid 403.910395 -144.214866)
		(end 403.71903 -144.25295)
		(width 0.1143)
		(layer "In2.Cu")
		(net "SATA6G_PCH_PCIE_UP_SATA_TXN<4>")
	)
	(arc
		(start 412.379414 -141.689328)
		(mid 412.011403 -141.841763)
		(end 411.858968 -142.209774)
		(width 0.1143)
		(layer "In2.Cu")
		(net "SATA6G_PCH_PCIE_UP_SATA_TXN<4>")
	)
	(arc
		(start 385.409186 -134.380478)
		(mid 385.273333 -134.289607)
		(end 385.113022 -134.257796)
		(width 0.1143)
		(layer "In2.Cu")
		(net "SATA6G_PCH_PCIE_UP_SATA_TXN<4>")
	)
	(arc
		(start 404.238968 -143.733012)
		(mid 404.200781 -143.924431)
		(end 404.092156 -144.08658)
		(width 0.1143)
		(layer "In2.Cu")
		(net "SATA6G_PCH_PCIE_UP_SATA_TXN<4>")
	)
	(arc
		(start 380.885954 -133.563614)
		(mid 380.774741 -133.396938)
		(end 380.73584 -133.200394)
		(width 0.1143)
		(layer "In2.Cu")
		(net "SATA6G_PCH_PCIE_UP_SATA_TXN<4>")
	)
	(arc
		(start 409.363672 -140.877544)
		(mid 408.995841 -140.725183)
		(end 408.84348 -140.357352)
		(width 0.1143)
		(layer "In2.Cu")
		(net "SATA6G_PCH_PCIE_UP_SATA_TXN<4>")
	)
	(arc
		(start 411.858968 -143.629126)
		(mid 411.306518 -144.181576)
		(end 410.754068 -143.629126)
		(width 0.1143)
		(layer "In2.Cu")
		(net "SATA6G_PCH_PCIE_UP_SATA_TXN<4>")
	)
	(arc
		(start 403.598634 -144.25295)
		(mid 403.398607 -144.213144)
		(end 403.229064 -144.099788)
		(width 0.1143)
		(layer "In2.Cu")
		(net "SATA6G_PCH_PCIE_UP_SATA_TXN<4>")
	)
	(segment
		(start 380.697232 -126.010416)
		(end 380.697232 -126.294642)
		(width 0.0889)
		(layer "F.Cu")
		(net "SATA6G_PCH_PCIE_UP_SATA_TXN<3>")
	)
	(segment
		(start 380.713488 -128.654048)
		(end 380.70917 -128.739138)
		(width 0.0889)
		(layer "F.Cu")
		(net "SATA6G_PCH_PCIE_UP_SATA_TXN<3>")
	)
	(segment
		(start 380.985014 -125.33503)
		(end 380.820422 -125.784864)
		(width 0.0889)
		(layer "F.Cu")
		(net "SATA6G_PCH_PCIE_UP_SATA_TXN<3>")
	)
	(segment
		(start 380.697232 -126.294642)
		(end 380.70917 -126.30658)
		(width 0.0889)
		(layer "F.Cu")
		(net "SATA6G_PCH_PCIE_UP_SATA_TXN<3>")
	)
	(segment
		(start 380.70917 -128.65481)
		(end 380.713488 -128.654048)
		(width 0.0889)
		(layer "F.Cu")
		(net "SATA6G_PCH_PCIE_UP_SATA_TXN<3>")
	)
	(segment
		(start 380.70917 -128.739138)
		(end 380.562358 -129.092706)
		(width 0.0889)
		(layer "F.Cu")
		(net "SATA6G_PCH_PCIE_UP_SATA_TXN<3>")
	)
	(segment
		(start 380.820422 -125.784864)
		(end 380.697232 -126.010416)
		(width 0.0889)
		(layer "F.Cu")
		(net "SATA6G_PCH_PCIE_UP_SATA_TXN<3>")
	)
	(segment
		(start 380.70917 -126.30658)
		(end 380.70917 -128.65481)
		(width 0.0889)
		(layer "F.Cu")
		(net "SATA6G_PCH_PCIE_UP_SATA_TXN<3>")
	)
	(via
		(at 419.777926 -147.9169)
		(size 0.508)
		(drill 0.254)
		(layers "F.Cu" "B.Cu")
		(net "SATA6G_PCH_PCIE_UP_SATA_TXN<3>")
	)
	(via
		(at 380.562358 -129.092706)
		(size 0.508)
		(drill 0.254)
		(layers "F.Cu" "B.Cu")
		(net "SATA6G_PCH_PCIE_UP_SATA_TXN<3>")
	)
	(segment
		(start 419.777926 -147.9169)
		(end 419.777926 -147.61845)
		(width 0.1143)
		(layer "B.Cu")
		(net "SATA6G_PCH_PCIE_UP_SATA_TXN<3>")
	)
	(segment
		(start 419.892226 -147.50415)
		(end 420.252906 -147.50415)
		(width 0.1143)
		(layer "B.Cu")
		(net "SATA6G_PCH_PCIE_UP_SATA_TXN<3>")
	)
	(segment
		(start 420.333678 -147.537678)
		(end 420.624 -147.828)
		(width 0.1143)
		(layer "B.Cu")
		(net "SATA6G_PCH_PCIE_UP_SATA_TXN<3>")
	)
	(arc
		(start 420.252906 -147.50415)
		(mid 420.296647 -147.512851)
		(end 420.333678 -147.537678)
		(width 0.1143)
		(layer "B.Cu")
		(net "SATA6G_PCH_PCIE_UP_SATA_TXN<3>")
	)
	(arc
		(start 419.777926 -147.61845)
		(mid 419.811404 -147.537628)
		(end 419.892226 -147.50415)
		(width 0.1143)
		(layer "B.Cu")
		(net "SATA6G_PCH_PCIE_UP_SATA_TXN<3>")
	)
	(segment
		(start 415.367216 -142.548102)
		(end 415.367216 -142.313152)
		(width 0.1143)
		(layer "In2.Cu")
		(net "SATA6G_PCH_PCIE_UP_SATA_TXN<3>")
	)
	(segment
		(start 419.2016 -142.43558)
		(end 419.2016 -145.078196)
		(width 0.1143)
		(layer "In2.Cu")
		(net "SATA6G_PCH_PCIE_UP_SATA_TXN<3>")
	)
	(segment
		(start 413.61995 -141.872716)
		(end 414.03016 -142.282926)
		(width 0.1143)
		(layer "In2.Cu")
		(net "SATA6G_PCH_PCIE_UP_SATA_TXN<3>")
	)
	(segment
		(start 383.07264 -133.288532)
		(end 385.397756 -133.288532)
		(width 0.1143)
		(layer "In2.Cu")
		(net "SATA6G_PCH_PCIE_UP_SATA_TXN<3>")
	)
	(segment
		(start 381.80772 -129.90068)
		(end 381.962406 -130.055366)
		(width 0.1143)
		(layer "In2.Cu")
		(net "SATA6G_PCH_PCIE_UP_SATA_TXN<3>")
	)
	(segment
		(start 419.412166 -147.617434)
		(end 419.444932 -147.620736)
		(width 0.1143)
		(layer "In2.Cu")
		(net "SATA6G_PCH_PCIE_UP_SATA_TXN<3>")
	)
	(segment
		(start 381.877316 -132.262118)
		(end 382.784858 -133.16966)
		(width 0.1143)
		(layer "In2.Cu")
		(net "SATA6G_PCH_PCIE_UP_SATA_TXN<3>")
	)
	(segment
		(start 382.00965 -130.472434)
		(end 381.801878 -130.680206)
		(width 0.1143)
		(layer "In2.Cu")
		(net "SATA6G_PCH_PCIE_UP_SATA_TXN<3>")
	)
	(segment
		(start 410.698442 -140.455142)
		(end 413.098996 -140.455142)
		(width 0.1143)
		(layer "In2.Cu")
		(net "SATA6G_PCH_PCIE_UP_SATA_TXN<3>")
	)
	(segment
		(start 418.973 -146.778726)
		(end 418.973 -147.13331)
		(width 0.1143)
		(layer "In2.Cu")
		(net "SATA6G_PCH_PCIE_UP_SATA_TXN<3>")
	)
	(segment
		(start 409.161488 -139.16152)
		(end 410.283406 -140.283438)
		(width 0.1143)
		(layer "In2.Cu")
		(net "SATA6G_PCH_PCIE_UP_SATA_TXN<3>")
	)
	(segment
		(start 380.562358 -129.092706)
		(end 380.698502 -129.22885)
		(width 0.1143)
		(layer "In2.Cu")
		(net "SATA6G_PCH_PCIE_UP_SATA_TXN<3>")
	)
	(segment
		(start 381.151638 -129.848356)
		(end 381.681482 -129.848356)
		(width 0.1143)
		(layer "In2.Cu")
		(net "SATA6G_PCH_PCIE_UP_SATA_TXN<3>")
	)
	(segment
		(start 417.53409 -142.620746)
		(end 417.53409 -142.303754)
		(width 0.1143)
		(layer "In2.Cu")
		(net "SATA6G_PCH_PCIE_UP_SATA_TXN<3>")
	)
	(segment
		(start 417.811458 -142.026386)
		(end 418.792406 -142.026386)
		(width 0.1143)
		(layer "In2.Cu")
		(net "SATA6G_PCH_PCIE_UP_SATA_TXN<3>")
	)
	(segment
		(start 403.283674 -139.040108)
		(end 408.868372 -139.040108)
		(width 0.1143)
		(layer "In2.Cu")
		(net "SATA6G_PCH_PCIE_UP_SATA_TXN<3>")
	)
	(segment
		(start 415.81705 -146.635724)
		(end 418.829998 -146.635724)
		(width 0.1143)
		(layer "In2.Cu")
		(net "SATA6G_PCH_PCIE_UP_SATA_TXN<3>")
	)
	(segment
		(start 414.126172 -142.513812)
		(end 414.126172 -142.548102)
		(width 0.1143)
		(layer "In2.Cu")
		(net "SATA6G_PCH_PCIE_UP_SATA_TXN<3>")
	)
	(segment
		(start 416.42919 -142.288768)
		(end 416.42919 -142.620746)
		(width 0.1143)
		(layer "In2.Cu")
		(net "SATA6G_PCH_PCIE_UP_SATA_TXN<3>")
	)
	(segment
		(start 385.478528 -133.322314)
		(end 387.804152 -135.647938)
		(width 0.1143)
		(layer "In2.Cu")
		(net "SATA6G_PCH_PCIE_UP_SATA_TXN<3>")
	)
	(segment
		(start 415.653982 -142.026386)
		(end 416.166808 -142.026386)
		(width 0.1143)
		(layer "In2.Cu")
		(net "SATA6G_PCH_PCIE_UP_SATA_TXN<3>")
	)
	(segment
		(start 382.043178 -130.250438)
		(end 382.043178 -130.391408)
		(width 0.1143)
		(layer "In2.Cu")
		(net "SATA6G_PCH_PCIE_UP_SATA_TXN<3>")
	)
	(segment
		(start 388.515606 -135.942324)
		(end 399.48612 -135.942324)
		(width 0.1143)
		(layer "In2.Cu")
		(net "SATA6G_PCH_PCIE_UP_SATA_TXN<3>")
	)
	(segment
		(start 418.748972 -145.530824)
		(end 415.81705 -145.530824)
		(width 0.1143)
		(layer "In2.Cu")
		(net "SATA6G_PCH_PCIE_UP_SATA_TXN<3>")
	)
	(segment
		(start 380.73203 -129.309622)
		(end 380.73203 -129.428748)
		(width 0.1143)
		(layer "In2.Cu")
		(net "SATA6G_PCH_PCIE_UP_SATA_TXN<3>")
	)
	(segment
		(start 413.388048 -140.744194)
		(end 413.388048 -141.312138)
		(width 0.1143)
		(layer "In2.Cu")
		(net "SATA6G_PCH_PCIE_UP_SATA_TXN<3>")
	)
	(segment
		(start 419.514528 -147.653502)
		(end 419.777926 -147.9169)
		(width 0.1143)
		(layer "In2.Cu")
		(net "SATA6G_PCH_PCIE_UP_SATA_TXN<3>")
	)
	(segment
		(start 381.68199 -130.97002)
		(end 381.68199 -131.79044)
		(width 0.1143)
		(layer "In2.Cu")
		(net "SATA6G_PCH_PCIE_UP_SATA_TXN<3>")
	)
	(segment
		(start 399.920714 -136.122664)
		(end 402.523198 -138.725148)
		(width 0.1143)
		(layer "In2.Cu")
		(net "SATA6G_PCH_PCIE_UP_SATA_TXN<3>")
	)
	(arc
		(start 418.973 -147.13331)
		(mid 419.09915 -147.460124)
		(end 419.412166 -147.617434)
		(width 0.1143)
		(layer "In2.Cu")
		(net "SATA6G_PCH_PCIE_UP_SATA_TXN<3>")
	)
	(arc
		(start 416.42919 -142.620746)
		(mid 416.98164 -143.173196)
		(end 417.53409 -142.620746)
		(width 0.1143)
		(layer "In2.Cu")
		(net "SATA6G_PCH_PCIE_UP_SATA_TXN<3>")
	)
	(arc
		(start 402.523198 -138.725148)
		(mid 402.872122 -138.958228)
		(end 403.283674 -139.040108)
		(width 0.1143)
		(layer "In2.Cu")
		(net "SATA6G_PCH_PCIE_UP_SATA_TXN<3>")
	)
	(arc
		(start 382.043178 -130.391408)
		(mid 382.034458 -130.435246)
		(end 382.00965 -130.472434)
		(width 0.1143)
		(layer "In2.Cu")
		(net "SATA6G_PCH_PCIE_UP_SATA_TXN<3>")
	)
	(arc
		(start 413.388048 -141.312138)
		(mid 413.448274 -141.615475)
		(end 413.61995 -141.872716)
		(width 0.1143)
		(layer "In2.Cu")
		(net "SATA6G_PCH_PCIE_UP_SATA_TXN<3>")
	)
	(arc
		(start 381.68199 -131.79044)
		(mid 381.732763 -132.045691)
		(end 381.877316 -132.262118)
		(width 0.1143)
		(layer "In2.Cu")
		(net "SATA6G_PCH_PCIE_UP_SATA_TXN<3>")
	)
	(arc
		(start 408.868372 -139.040108)
		(mid 409.027005 -139.071662)
		(end 409.161488 -139.16152)
		(width 0.1143)
		(layer "In2.Cu")
		(net "SATA6G_PCH_PCIE_UP_SATA_TXN<3>")
	)
	(arc
		(start 415.367216 -142.313152)
		(mid 415.451208 -142.110378)
		(end 415.653982 -142.026386)
		(width 0.1143)
		(layer "In2.Cu")
		(net "SATA6G_PCH_PCIE_UP_SATA_TXN<3>")
	)
	(arc
		(start 381.962406 -130.055366)
		(mid 382.022208 -130.144866)
		(end 382.043178 -130.250438)
		(width 0.1143)
		(layer "In2.Cu")
		(net "SATA6G_PCH_PCIE_UP_SATA_TXN<3>")
	)
	(arc
		(start 381.801878 -130.680206)
		(mid 381.713061 -130.813175)
		(end 381.68199 -130.97002)
		(width 0.1143)
		(layer "In2.Cu")
		(net "SATA6G_PCH_PCIE_UP_SATA_TXN<3>")
	)
	(arc
		(start 418.829998 -146.635724)
		(mid 418.931116 -146.677608)
		(end 418.973 -146.778726)
		(width 0.1143)
		(layer "In2.Cu")
		(net "SATA6G_PCH_PCIE_UP_SATA_TXN<3>")
	)
	(arc
		(start 399.48612 -135.942324)
		(mid 399.721377 -135.989231)
		(end 399.920714 -136.122664)
		(width 0.1143)
		(layer "In2.Cu")
		(net "SATA6G_PCH_PCIE_UP_SATA_TXN<3>")
	)
	(arc
		(start 385.397756 -133.288532)
		(mid 385.441526 -133.29735)
		(end 385.478528 -133.322314)
		(width 0.1143)
		(layer "In2.Cu")
		(net "SATA6G_PCH_PCIE_UP_SATA_TXN<3>")
	)
	(arc
		(start 417.53409 -142.303754)
		(mid 417.615329 -142.107625)
		(end 417.811458 -142.026386)
		(width 0.1143)
		(layer "In2.Cu")
		(net "SATA6G_PCH_PCIE_UP_SATA_TXN<3>")
	)
	(arc
		(start 410.283406 -140.283438)
		(mid 410.473827 -140.410643)
		(end 410.698442 -140.455142)
		(width 0.1143)
		(layer "In2.Cu")
		(net "SATA6G_PCH_PCIE_UP_SATA_TXN<3>")
	)
	(arc
		(start 416.166808 -142.026386)
		(mid 416.35234 -142.103236)
		(end 416.42919 -142.288768)
		(width 0.1143)
		(layer "In2.Cu")
		(net "SATA6G_PCH_PCIE_UP_SATA_TXN<3>")
	)
	(arc
		(start 413.098996 -140.455142)
		(mid 413.303387 -140.539803)
		(end 413.388048 -140.744194)
		(width 0.1143)
		(layer "In2.Cu")
		(net "SATA6G_PCH_PCIE_UP_SATA_TXN<3>")
	)
	(arc
		(start 419.2016 -145.078196)
		(mid 419.069028 -145.398252)
		(end 418.748972 -145.530824)
		(width 0.1143)
		(layer "In2.Cu")
		(net "SATA6G_PCH_PCIE_UP_SATA_TXN<3>")
	)
	(arc
		(start 380.73203 -129.428748)
		(mid 380.85493 -129.725456)
		(end 381.151638 -129.848356)
		(width 0.1143)
		(layer "In2.Cu")
		(net "SATA6G_PCH_PCIE_UP_SATA_TXN<3>")
	)
	(arc
		(start 382.784858 -133.16966)
		(mid 382.916923 -133.257747)
		(end 383.07264 -133.288532)
		(width 0.1143)
		(layer "In2.Cu")
		(net "SATA6G_PCH_PCIE_UP_SATA_TXN<3>")
	)
	(arc
		(start 415.81705 -145.530824)
		(mid 415.2646 -146.083274)
		(end 415.81705 -146.635724)
		(width 0.1143)
		(layer "In2.Cu")
		(net "SATA6G_PCH_PCIE_UP_SATA_TXN<3>")
	)
	(arc
		(start 414.126172 -142.548102)
		(mid 414.746694 -143.168624)
		(end 415.367216 -142.548102)
		(width 0.1143)
		(layer "In2.Cu")
		(net "SATA6G_PCH_PCIE_UP_SATA_TXN<3>")
	)
	(arc
		(start 387.804152 -135.647938)
		(mid 388.130599 -135.865907)
		(end 388.515606 -135.942324)
		(width 0.1143)
		(layer "In2.Cu")
		(net "SATA6G_PCH_PCIE_UP_SATA_TXN<3>")
	)
	(arc
		(start 414.03016 -142.282926)
		(mid 414.101053 -142.388842)
		(end 414.126172 -142.513812)
		(width 0.1143)
		(layer "In2.Cu")
		(net "SATA6G_PCH_PCIE_UP_SATA_TXN<3>")
	)
	(arc
		(start 419.444932 -147.620736)
		(mid 419.482595 -147.631051)
		(end 419.514528 -147.653502)
		(width 0.1143)
		(layer "In2.Cu")
		(net "SATA6G_PCH_PCIE_UP_SATA_TXN<3>")
	)
	(arc
		(start 381.681482 -129.848356)
		(mid 381.749815 -129.861948)
		(end 381.80772 -129.90068)
		(width 0.1143)
		(layer "In2.Cu")
		(net "SATA6G_PCH_PCIE_UP_SATA_TXN<3>")
	)
	(arc
		(start 380.698502 -129.22885)
		(mid 380.723264 -129.265909)
		(end 380.73203 -129.309622)
		(width 0.1143)
		(layer "In2.Cu")
		(net "SATA6G_PCH_PCIE_UP_SATA_TXN<3>")
	)
	(arc
		(start 418.792406 -142.026386)
		(mid 419.08175 -142.146236)
		(end 419.2016 -142.43558)
		(width 0.1143)
		(layer "In2.Cu")
		(net "SATA6G_PCH_PCIE_UP_SATA_TXN<3>")
	)
	(segment
		(start 381.234696 -125.974602)
		(end 381.27813 -126.07925)
		(width 0.0889)
		(layer "F.Cu")
		(net "SATA6G_PCH_PCIE_UP_SATA_TXN<2>")
	)
	(segment
		(start 381.27813 -126.07925)
		(end 381.27813 -127.48006)
		(width 0.0889)
		(layer "F.Cu")
		(net "SATA6G_PCH_PCIE_UP_SATA_TXN<2>")
	)
	(segment
		(start 381.484886 -124.919994)
		(end 381.321564 -125.341634)
		(width 0.0889)
		(layer "F.Cu")
		(net "SATA6G_PCH_PCIE_UP_SATA_TXN<2>")
	)
	(segment
		(start 381.304546 -125.38075)
		(end 381.25908 -125.485652)
		(width 0.0889)
		(layer "F.Cu")
		(net "SATA6G_PCH_PCIE_UP_SATA_TXN<2>")
	)
	(segment
		(start 381.85852 -128.213104)
		(end 381.85852 -129.741422)
		(width 0.0889)
		(layer "F.Cu")
		(net "SATA6G_PCH_PCIE_UP_SATA_TXN<2>")
	)
	(segment
		(start 381.940562 -129.939288)
		(end 382.876298 -130.875024)
		(width 0.0889)
		(layer "F.Cu")
		(net "SATA6G_PCH_PCIE_UP_SATA_TXN<2>")
	)
	(segment
		(start 382.90246 -130.938016)
		(end 382.90246 -131.308602)
		(width 0.0889)
		(layer "F.Cu")
		(net "SATA6G_PCH_PCIE_UP_SATA_TXN<2>")
	)
	(segment
		(start 381.360172 -127.677926)
		(end 381.832358 -128.150112)
		(width 0.0889)
		(layer "F.Cu")
		(net "SATA6G_PCH_PCIE_UP_SATA_TXN<2>")
	)
	(segment
		(start 381.171704 -125.822456)
		(end 381.233426 -125.971808)
		(width 0.0889)
		(layer "F.Cu")
		(net "SATA6G_PCH_PCIE_UP_SATA_TXN<2>")
	)
	(segment
		(start 381.25908 -125.485652)
		(end 381.171704 -125.68682)
		(width 0.0889)
		(layer "F.Cu")
		(net "SATA6G_PCH_PCIE_UP_SATA_TXN<2>")
	)
	(segment
		(start 381.321564 -125.341634)
		(end 381.304546 -125.38075)
		(width 0.0889)
		(layer "F.Cu")
		(net "SATA6G_PCH_PCIE_UP_SATA_TXN<2>")
	)
	(segment
		(start 381.171704 -125.68682)
		(end 381.171704 -125.822456)
		(width 0.0889)
		(layer "F.Cu")
		(net "SATA6G_PCH_PCIE_UP_SATA_TXN<2>")
	)
	(via
		(at 382.88087 -131.61137)
		(size 0.508)
		(drill 0.254)
		(layers "F.Cu" "B.Cu")
		(net "SATA6G_PCH_PCIE_UP_SATA_TXN<2>")
	)
	(via
		(at 424.0784 -139.838176)
		(size 0.508)
		(drill 0.254)
		(layers "F.Cu" "B.Cu")
		(net "SATA6G_PCH_PCIE_UP_SATA_TXN<2>")
	)
	(arc
		(start 382.90246 -131.308602)
		(mid 382.897055 -131.46037)
		(end 382.88087 -131.61137)
		(width 0.0889)
		(layer "F.Cu")
		(net "SATA6G_PCH_PCIE_UP_SATA_TXN<2>")
	)
	(arc
		(start 382.876298 -130.875024)
		(mid 382.895663 -130.903911)
		(end 382.90246 -130.938016)
		(width 0.0889)
		(layer "F.Cu")
		(net "SATA6G_PCH_PCIE_UP_SATA_TXN<2>")
	)
	(arc
		(start 381.832358 -128.150112)
		(mid 381.851723 -128.178999)
		(end 381.85852 -128.213104)
		(width 0.0889)
		(layer "F.Cu")
		(net "SATA6G_PCH_PCIE_UP_SATA_TXN<2>")
	)
	(arc
		(start 381.85852 -129.741422)
		(mid 381.879842 -129.848524)
		(end 381.940562 -129.939288)
		(width 0.0889)
		(layer "F.Cu")
		(net "SATA6G_PCH_PCIE_UP_SATA_TXN<2>")
	)
	(arc
		(start 381.233426 -125.971808)
		(mid 381.234057 -125.973207)
		(end 381.234696 -125.974602)
		(width 0.0889)
		(layer "F.Cu")
		(net "SATA6G_PCH_PCIE_UP_SATA_TXN<2>")
	)
	(arc
		(start 381.27813 -127.48006)
		(mid 381.299452 -127.587162)
		(end 381.360172 -127.677926)
		(width 0.0889)
		(layer "F.Cu")
		(net "SATA6G_PCH_PCIE_UP_SATA_TXN<2>")
	)
	(segment
		(start 424.593258 -140.631164)
		(end 424.593258 -140.19276)
		(width 0.1143)
		(layer "B.Cu")
		(net "SATA6G_PCH_PCIE_UP_SATA_TXN<2>")
	)
	(segment
		(start 424.593258 -140.19276)
		(end 424.59275 -140.192252)
		(width 0.1143)
		(layer "B.Cu")
		(net "SATA6G_PCH_PCIE_UP_SATA_TXN<2>")
	)
	(segment
		(start 424.46575 -139.838176)
		(end 424.0784 -139.838176)
		(width 0.1143)
		(layer "B.Cu")
		(net "SATA6G_PCH_PCIE_UP_SATA_TXN<2>")
	)
	(segment
		(start 424.18 -141.097)
		(end 424.556174 -140.720826)
		(width 0.1143)
		(layer "B.Cu")
		(net "SATA6G_PCH_PCIE_UP_SATA_TXN<2>")
	)
	(segment
		(start 424.59275 -140.192252)
		(end 424.59275 -139.965176)
		(width 0.1143)
		(layer "B.Cu")
		(net "SATA6G_PCH_PCIE_UP_SATA_TXN<2>")
	)
	(arc
		(start 424.59275 -139.965176)
		(mid 424.555553 -139.875373)
		(end 424.46575 -139.838176)
		(width 0.1143)
		(layer "B.Cu")
		(net "SATA6G_PCH_PCIE_UP_SATA_TXN<2>")
	)
	(arc
		(start 424.556174 -140.720826)
		(mid 424.583607 -140.679675)
		(end 424.593258 -140.631164)
		(width 0.1143)
		(layer "B.Cu")
		(net "SATA6G_PCH_PCIE_UP_SATA_TXN<2>")
	)
	(segment
		(start 417.24834 -139.8905)
		(end 414.781746 -139.8905)
		(width 0.1143)
		(layer "In2.Cu")
		(net "SATA6G_PCH_PCIE_UP_SATA_TXN<2>")
	)
	(segment
		(start 404.944072 -137.888472)
		(end 404.63089 -137.57529)
		(width 0.1143)
		(layer "In2.Cu")
		(net "SATA6G_PCH_PCIE_UP_SATA_TXN<2>")
	)
	(segment
		(start 419.913816 -139.8905)
		(end 418.79012 -139.8905)
		(width 0.1143)
		(layer "In2.Cu")
		(net "SATA6G_PCH_PCIE_UP_SATA_TXN<2>")
	)
	(segment
		(start 404.944326 -137.888472)
		(end 404.944072 -137.888472)
		(width 0.1143)
		(layer "In2.Cu")
		(net "SATA6G_PCH_PCIE_UP_SATA_TXN<2>")
	)
	(segment
		(start 409.956254 -137.922)
		(end 405.025352 -137.922)
		(width 0.1143)
		(layer "In2.Cu")
		(net "SATA6G_PCH_PCIE_UP_SATA_TXN<2>")
	)
	(segment
		(start 383.12725 -131.34467)
		(end 382.88087 -131.59105)
		(width 0.1143)
		(layer "In2.Cu")
		(net "SATA6G_PCH_PCIE_UP_SATA_TXN<2>")
	)
	(segment
		(start 414.633156 -139.828778)
		(end 414.109916 -139.305792)
		(width 0.1143)
		(layer "In2.Cu")
		(net "SATA6G_PCH_PCIE_UP_SATA_TXN<2>")
	)
	(segment
		(start 424.410378 -140.012928)
		(end 424.410378 -140.297154)
		(width 0.1143)
		(layer "In2.Cu")
		(net "SATA6G_PCH_PCIE_UP_SATA_TXN<2>")
	)
	(segment
		(start 403.867366 -137.57529)
		(end 403.61743 -137.825226)
		(width 0.1143)
		(layer "In2.Cu")
		(net "SATA6G_PCH_PCIE_UP_SATA_TXN<2>")
	)
	(segment
		(start 403.5171 -136.4615)
		(end 401.731988 -134.676388)
		(width 0.1143)
		(layer "In2.Cu")
		(net "SATA6G_PCH_PCIE_UP_SATA_TXN<2>")
	)
	(segment
		(start 420.645336 -140.448538)
		(end 420.20998 -140.013182)
		(width 0.1143)
		(layer "In2.Cu")
		(net "SATA6G_PCH_PCIE_UP_SATA_TXN<2>")
	)
	(segment
		(start 386.853938 -131.0513)
		(end 386.367528 -131.0513)
		(width 0.1143)
		(layer "In2.Cu")
		(net "SATA6G_PCH_PCIE_UP_SATA_TXN<2>")
	)
	(segment
		(start 403.267164 -137.47496)
		(end 403.5171 -137.225024)
		(width 0.1143)
		(layer "In2.Cu")
		(net "SATA6G_PCH_PCIE_UP_SATA_TXN<2>")
	)
	(segment
		(start 424.0784 -139.838176)
		(end 424.235626 -139.838176)
		(width 0.1143)
		(layer "In2.Cu")
		(net "SATA6G_PCH_PCIE_UP_SATA_TXN<2>")
	)
	(segment
		(start 424.22191 -140.485622)
		(end 420.734998 -140.485622)
		(width 0.1143)
		(layer "In2.Cu")
		(net "SATA6G_PCH_PCIE_UP_SATA_TXN<2>")
	)
	(segment
		(start 418.28339 -140.39723)
		(end 418.28339 -140.65631)
		(width 0.1143)
		(layer "In2.Cu")
		(net "SATA6G_PCH_PCIE_UP_SATA_TXN<2>")
	)
	(segment
		(start 390.455912 -134.479538)
		(end 387.150102 -131.174236)
		(width 0.1143)
		(layer "In2.Cu")
		(net "SATA6G_PCH_PCIE_UP_SATA_TXN<2>")
	)
	(segment
		(start 385.386072 -131.93903)
		(end 385.386072 -131.59105)
		(width 0.1143)
		(layer "In2.Cu")
		(net "SATA6G_PCH_PCIE_UP_SATA_TXN<2>")
	)
	(segment
		(start 387.150102 -131.174236)
		(end 387.150102 -131.173982)
		(width 0.1143)
		(layer "In2.Cu")
		(net "SATA6G_PCH_PCIE_UP_SATA_TXN<2>")
	)
	(segment
		(start 411.397196 -138.95324)
		(end 410.655262 -138.211306)
		(width 0.1143)
		(layer "In2.Cu")
		(net "SATA6G_PCH_PCIE_UP_SATA_TXN<2>")
	)
	(segment
		(start 382.88087 -131.59105)
		(end 382.88087 -131.61137)
		(width 0.1143)
		(layer "In2.Cu")
		(net "SATA6G_PCH_PCIE_UP_SATA_TXN<2>")
	)
	(segment
		(start 413.597344 -139.093448)
		(end 411.735524 -139.093448)
		(width 0.1143)
		(layer "In2.Cu")
		(net "SATA6G_PCH_PCIE_UP_SATA_TXN<2>")
	)
	(segment
		(start 385.881372 -131.537456)
		(end 385.881372 -131.93903)
		(width 0.1143)
		(layer "In2.Cu")
		(net "SATA6G_PCH_PCIE_UP_SATA_TXN<2>")
	)
	(segment
		(start 384.846322 -131.0513)
		(end 383.836418 -131.0513)
		(width 0.1143)
		(layer "In2.Cu")
		(net "SATA6G_PCH_PCIE_UP_SATA_TXN<2>")
	)
	(segment
		(start 401.436078 -134.55396)
		(end 390.63549 -134.55396)
		(width 0.1143)
		(layer "In2.Cu")
		(net "SATA6G_PCH_PCIE_UP_SATA_TXN<2>")
	)
	(segment
		(start 417.78809 -140.65631)
		(end 417.78809 -140.43025)
		(width 0.1143)
		(layer "In2.Cu")
		(net "SATA6G_PCH_PCIE_UP_SATA_TXN<2>")
	)
	(arc
		(start 418.28339 -140.65631)
		(mid 418.03574 -140.90396)
		(end 417.78809 -140.65631)
		(width 0.1143)
		(layer "In2.Cu")
		(net "SATA6G_PCH_PCIE_UP_SATA_TXN<2>")
	)
	(arc
		(start 404.63089 -137.57529)
		(mid 404.249128 -137.417085)
		(end 403.867366 -137.57529)
		(width 0.1143)
		(layer "In2.Cu")
		(net "SATA6G_PCH_PCIE_UP_SATA_TXN<2>")
	)
	(arc
		(start 424.235626 -139.838176)
		(mid 424.359194 -139.88936)
		(end 424.410378 -140.012928)
		(width 0.1143)
		(layer "In2.Cu")
		(net "SATA6G_PCH_PCIE_UP_SATA_TXN<2>")
	)
	(arc
		(start 405.025352 -137.922)
		(mid 404.981514 -137.91328)
		(end 404.944326 -137.888472)
		(width 0.1143)
		(layer "In2.Cu")
		(net "SATA6G_PCH_PCIE_UP_SATA_TXN<2>")
	)
	(arc
		(start 403.5171 -137.225024)
		(mid 403.675305 -136.843262)
		(end 403.5171 -136.4615)
		(width 0.1143)
		(layer "In2.Cu")
		(net "SATA6G_PCH_PCIE_UP_SATA_TXN<2>")
	)
	(arc
		(start 414.109916 -139.305792)
		(mid 413.874746 -139.148656)
		(end 413.597344 -139.093448)
		(width 0.1143)
		(layer "In2.Cu")
		(net "SATA6G_PCH_PCIE_UP_SATA_TXN<2>")
	)
	(arc
		(start 390.63549 -134.55396)
		(mid 390.538288 -134.534625)
		(end 390.455912 -134.479538)
		(width 0.1143)
		(layer "In2.Cu")
		(net "SATA6G_PCH_PCIE_UP_SATA_TXN<2>")
	)
	(arc
		(start 411.735524 -139.093448)
		(mid 411.552436 -139.056954)
		(end 411.397196 -138.95324)
		(width 0.1143)
		(layer "In2.Cu")
		(net "SATA6G_PCH_PCIE_UP_SATA_TXN<2>")
	)
	(arc
		(start 418.79012 -139.8905)
		(mid 418.431808 -140.038918)
		(end 418.28339 -140.39723)
		(width 0.1143)
		(layer "In2.Cu")
		(net "SATA6G_PCH_PCIE_UP_SATA_TXN<2>")
	)
	(arc
		(start 383.836418 -131.0513)
		(mid 383.452645 -131.12741)
		(end 383.12725 -131.34467)
		(width 0.1143)
		(layer "In2.Cu")
		(net "SATA6G_PCH_PCIE_UP_SATA_TXN<2>")
	)
	(arc
		(start 385.881372 -131.93903)
		(mid 385.633722 -132.18668)
		(end 385.386072 -131.93903)
		(width 0.1143)
		(layer "In2.Cu")
		(net "SATA6G_PCH_PCIE_UP_SATA_TXN<2>")
	)
	(arc
		(start 385.386072 -131.59105)
		(mid 385.227983 -131.209389)
		(end 384.846322 -131.0513)
		(width 0.1143)
		(layer "In2.Cu")
		(net "SATA6G_PCH_PCIE_UP_SATA_TXN<2>")
	)
	(arc
		(start 420.20998 -140.013182)
		(mid 420.074085 -139.922443)
		(end 419.913816 -139.8905)
		(width 0.1143)
		(layer "In2.Cu")
		(net "SATA6G_PCH_PCIE_UP_SATA_TXN<2>")
	)
	(arc
		(start 410.655262 -138.211306)
		(mid 410.334539 -137.997099)
		(end 409.956254 -137.922)
		(width 0.1143)
		(layer "In2.Cu")
		(net "SATA6G_PCH_PCIE_UP_SATA_TXN<2>")
	)
	(arc
		(start 403.61743 -137.825226)
		(mid 403.267291 -137.825099)
		(end 403.267164 -137.47496)
		(width 0.1143)
		(layer "In2.Cu")
		(net "SATA6G_PCH_PCIE_UP_SATA_TXN<2>")
	)
	(arc
		(start 420.734998 -140.485622)
		(mid 420.68648 -140.475989)
		(end 420.645336 -140.448538)
		(width 0.1143)
		(layer "In2.Cu")
		(net "SATA6G_PCH_PCIE_UP_SATA_TXN<2>")
	)
	(arc
		(start 387.150102 -131.173982)
		(mid 387.014207 -131.083243)
		(end 386.853938 -131.0513)
		(width 0.1143)
		(layer "In2.Cu")
		(net "SATA6G_PCH_PCIE_UP_SATA_TXN<2>")
	)
	(arc
		(start 386.367528 -131.0513)
		(mid 386.023764 -131.193692)
		(end 385.881372 -131.537456)
		(width 0.1143)
		(layer "In2.Cu")
		(net "SATA6G_PCH_PCIE_UP_SATA_TXN<2>")
	)
	(arc
		(start 424.410378 -140.297154)
		(mid 424.355177 -140.430421)
		(end 424.22191 -140.485622)
		(width 0.1143)
		(layer "In2.Cu")
		(net "SATA6G_PCH_PCIE_UP_SATA_TXN<2>")
	)
	(arc
		(start 414.781746 -139.8905)
		(mid 414.701317 -139.874408)
		(end 414.633156 -139.828778)
		(width 0.1143)
		(layer "In2.Cu")
		(net "SATA6G_PCH_PCIE_UP_SATA_TXN<2>")
	)
	(arc
		(start 417.78809 -140.43025)
		(mid 417.630001 -140.048589)
		(end 417.24834 -139.8905)
		(width 0.1143)
		(layer "In2.Cu")
		(net "SATA6G_PCH_PCIE_UP_SATA_TXN<2>")
	)
	(arc
		(start 401.731988 -134.676388)
		(mid 401.596196 -134.585751)
		(end 401.436078 -134.55396)
		(width 0.1143)
		(layer "In2.Cu")
		(net "SATA6G_PCH_PCIE_UP_SATA_TXN<2>")
	)
	(segment
		(start 381.967994 -125.38075)
		(end 381.928624 -125.485652)
		(width 0.0889)
		(layer "F.Cu")
		(net "SATA6G_PCH_PCIE_UP_SATA_TXN<1>")
	)
	(segment
		(start 381.985012 -125.33503)
		(end 381.967994 -125.38075)
		(width 0.0889)
		(layer "F.Cu")
		(net "SATA6G_PCH_PCIE_UP_SATA_TXN<1>")
	)
	(segment
		(start 381.699262 -126.06528)
		(end 381.699262 -127.21209)
		(width 0.0889)
		(layer "F.Cu")
		(net "SATA6G_PCH_PCIE_UP_SATA_TXN<1>")
	)
	(segment
		(start 382.93929 -128.702054)
		(end 382.93929 -129.305304)
		(width 0.0889)
		(layer "F.Cu")
		(net "SATA6G_PCH_PCIE_UP_SATA_TXN<1>")
	)
	(segment
		(start 381.796036 -125.839728)
		(end 381.699262 -126.06528)
		(width 0.0889)
		(layer "F.Cu")
		(net "SATA6G_PCH_PCIE_UP_SATA_TXN<1>")
	)
	(segment
		(start 382.383792 -128.027938)
		(end 382.383538 -128.027938)
		(width 0.0889)
		(layer "F.Cu")
		(net "SATA6G_PCH_PCIE_UP_SATA_TXN<1>")
	)
	(segment
		(start 382.93929 -129.305304)
		(end 382.77419 -129.70383)
		(width 0.0889)
		(layer "F.Cu")
		(net "SATA6G_PCH_PCIE_UP_SATA_TXN<1>")
	)
	(segment
		(start 381.928624 -125.485652)
		(end 381.796036 -125.839728)
		(width 0.0889)
		(layer "F.Cu")
		(net "SATA6G_PCH_PCIE_UP_SATA_TXN<1>")
	)
	(segment
		(start 382.383538 -128.027938)
		(end 382.855216 -128.499616)
		(width 0.0889)
		(layer "F.Cu")
		(net "SATA6G_PCH_PCIE_UP_SATA_TXN<1>")
	)
	(segment
		(start 381.792226 -127.436372)
		(end 382.383792 -128.027938)
		(width 0.0889)
		(layer "F.Cu")
		(net "SATA6G_PCH_PCIE_UP_SATA_TXN<1>")
	)
	(via
		(at 421.323516 -139.954)
		(size 0.508)
		(drill 0.254)
		(layers "F.Cu" "B.Cu")
		(net "SATA6G_PCH_PCIE_UP_SATA_TXN<1>")
	)
	(via
		(at 382.77419 -129.70383)
		(size 0.508)
		(drill 0.254)
		(layers "F.Cu" "B.Cu")
		(net "SATA6G_PCH_PCIE_UP_SATA_TXN<1>")
	)
	(arc
		(start 381.699262 -127.21209)
		(mid 381.723426 -127.333481)
		(end 381.792226 -127.436372)
		(width 0.0889)
		(layer "F.Cu")
		(net "SATA6G_PCH_PCIE_UP_SATA_TXN<1>")
	)
	(arc
		(start 382.855216 -128.499616)
		(mid 382.917359 -128.59248)
		(end 382.93929 -128.702054)
		(width 0.0889)
		(layer "F.Cu")
		(net "SATA6G_PCH_PCIE_UP_SATA_TXN<1>")
	)
	(segment
		(start 421.800528 -140.784072)
		(end 421.513 -141.0716)
		(width 0.1143)
		(layer "B.Cu")
		(net "SATA6G_PCH_PCIE_UP_SATA_TXN<1>")
	)
	(segment
		(start 421.323516 -139.954)
		(end 421.710612 -139.954)
		(width 0.1143)
		(layer "B.Cu")
		(net "SATA6G_PCH_PCIE_UP_SATA_TXN<1>")
	)
	(segment
		(start 421.837612 -140.081)
		(end 421.837612 -140.69441)
		(width 0.1143)
		(layer "B.Cu")
		(net "SATA6G_PCH_PCIE_UP_SATA_TXN<1>")
	)
	(arc
		(start 421.837612 -140.69441)
		(mid 421.827979 -140.742928)
		(end 421.800528 -140.784072)
		(width 0.1143)
		(layer "B.Cu")
		(net "SATA6G_PCH_PCIE_UP_SATA_TXN<1>")
	)
	(arc
		(start 421.710612 -139.954)
		(mid 421.800415 -139.991197)
		(end 421.837612 -140.081)
		(width 0.1143)
		(layer "B.Cu")
		(net "SATA6G_PCH_PCIE_UP_SATA_TXN<1>")
	)
	(segment
		(start 421.7289 -139.954)
		(end 421.323516 -139.954)
		(width 0.1143)
		(layer "In2.Cu")
		(net "SATA6G_PCH_PCIE_UP_SATA_TXN<1>")
	)
	(segment
		(start 390.904222 -134.05358)
		(end 401.649692 -134.05358)
		(width 0.1143)
		(layer "In2.Cu")
		(net "SATA6G_PCH_PCIE_UP_SATA_TXN<1>")
	)
	(segment
		(start 419.006782 -138.843512)
		(end 419.006782 -138.832844)
		(width 0.1143)
		(layer "In2.Cu")
		(net "SATA6G_PCH_PCIE_UP_SATA_TXN<1>")
	)
	(segment
		(start 414.777682 -138.832844)
		(end 414.777682 -138.843004)
		(width 0.1143)
		(layer "In2.Cu")
		(net "SATA6G_PCH_PCIE_UP_SATA_TXN<1>")
	)
	(segment
		(start 421.662606 -138.69289)
		(end 421.748458 -138.778742)
		(width 0.1143)
		(layer "In2.Cu")
		(net "SATA6G_PCH_PCIE_UP_SATA_TXN<1>")
	)
	(segment
		(start 387.258052 -130.57632)
		(end 390.61644 -133.934708)
		(width 0.1143)
		(layer "In2.Cu")
		(net "SATA6G_PCH_PCIE_UP_SATA_TXN<1>")
	)
	(segment
		(start 401.929092 -134.169658)
		(end 404.54072 -136.781286)
		(width 0.1143)
		(layer "In2.Cu")
		(net "SATA6G_PCH_PCIE_UP_SATA_TXN<1>")
	)
	(segment
		(start 382.914652 -130.04292)
		(end 382.914652 -130.056636)
		(width 0.1143)
		(layer "In2.Cu")
		(net "SATA6G_PCH_PCIE_UP_SATA_TXN<1>")
	)
	(segment
		(start 421.8559 -139.037822)
		(end 421.8559 -139.827)
		(width 0.1143)
		(layer "In2.Cu")
		(net "SATA6G_PCH_PCIE_UP_SATA_TXN<1>")
	)
	(segment
		(start 410.773372 -137.521188)
		(end 411.461966 -138.209782)
		(width 0.1143)
		(layer "In2.Cu")
		(net "SATA6G_PCH_PCIE_UP_SATA_TXN<1>")
	)
	(segment
		(start 416.352482 -138.832844)
		(end 416.352482 -138.84275)
		(width 0.1143)
		(layer "In2.Cu")
		(net "SATA6G_PCH_PCIE_UP_SATA_TXN<1>")
	)
	(segment
		(start 405.902414 -137.34542)
		(end 410.348938 -137.34542)
		(width 0.1143)
		(layer "In2.Cu")
		(net "SATA6G_PCH_PCIE_UP_SATA_TXN<1>")
	)
	(segment
		(start 412.369 -138.585194)
		(end 414.530032 -138.585194)
		(width 0.1143)
		(layer "In2.Cu")
		(net "SATA6G_PCH_PCIE_UP_SATA_TXN<1>")
	)
	(segment
		(start 383.397252 -130.539236)
		(end 387.16839 -130.539236)
		(width 0.1143)
		(layer "In2.Cu")
		(net "SATA6G_PCH_PCIE_UP_SATA_TXN<1>")
	)
	(segment
		(start 420.829232 -138.585194)
		(end 421.40251 -138.585194)
		(width 0.1143)
		(layer "In2.Cu")
		(net "SATA6G_PCH_PCIE_UP_SATA_TXN<1>")
	)
	(segment
		(start 415.857182 -138.843004)
		(end 415.857182 -138.832844)
		(width 0.1143)
		(layer "In2.Cu")
		(net "SATA6G_PCH_PCIE_UP_SATA_TXN<1>")
	)
	(segment
		(start 417.431982 -138.84275)
		(end 417.431982 -138.832844)
		(width 0.1143)
		(layer "In2.Cu")
		(net "SATA6G_PCH_PCIE_UP_SATA_TXN<1>")
	)
	(segment
		(start 417.927282 -138.832844)
		(end 417.927282 -138.843512)
		(width 0.1143)
		(layer "In2.Cu")
		(net "SATA6G_PCH_PCIE_UP_SATA_TXN<1>")
	)
	(arc
		(start 382.914652 -130.056636)
		(mid 383.056002 -130.397886)
		(end 383.397252 -130.539236)
		(width 0.1143)
		(layer "In2.Cu")
		(net "SATA6G_PCH_PCIE_UP_SATA_TXN<1>")
	)
	(arc
		(start 421.40251 -138.585194)
		(mid 421.543272 -138.613175)
		(end 421.662606 -138.69289)
		(width 0.1143)
		(layer "In2.Cu")
		(net "SATA6G_PCH_PCIE_UP_SATA_TXN<1>")
	)
	(arc
		(start 417.431982 -138.832844)
		(mid 417.679632 -138.585194)
		(end 417.927282 -138.832844)
		(width 0.1143)
		(layer "In2.Cu")
		(net "SATA6G_PCH_PCIE_UP_SATA_TXN<1>")
	)
	(arc
		(start 421.8559 -139.827)
		(mid 421.818703 -139.916803)
		(end 421.7289 -139.954)
		(width 0.1143)
		(layer "In2.Cu")
		(net "SATA6G_PCH_PCIE_UP_SATA_TXN<1>")
	)
	(arc
		(start 401.649692 -134.05358)
		(mid 401.800989 -134.083706)
		(end 401.929092 -134.169658)
		(width 0.1143)
		(layer "In2.Cu")
		(net "SATA6G_PCH_PCIE_UP_SATA_TXN<1>")
	)
	(arc
		(start 404.54072 -136.781286)
		(mid 405.16547 -137.19876)
		(end 405.902414 -137.34542)
		(width 0.1143)
		(layer "In2.Cu")
		(net "SATA6G_PCH_PCIE_UP_SATA_TXN<1>")
	)
	(arc
		(start 419.502082 -138.832844)
		(mid 420.041832 -139.372594)
		(end 420.581582 -138.832844)
		(width 0.1143)
		(layer "In2.Cu")
		(net "SATA6G_PCH_PCIE_UP_SATA_TXN<1>")
	)
	(arc
		(start 415.857182 -138.832844)
		(mid 416.104832 -138.585194)
		(end 416.352482 -138.832844)
		(width 0.1143)
		(layer "In2.Cu")
		(net "SATA6G_PCH_PCIE_UP_SATA_TXN<1>")
	)
	(arc
		(start 420.581582 -138.832844)
		(mid 420.654117 -138.657729)
		(end 420.829232 -138.585194)
		(width 0.1143)
		(layer "In2.Cu")
		(net "SATA6G_PCH_PCIE_UP_SATA_TXN<1>")
	)
	(arc
		(start 414.530032 -138.585194)
		(mid 414.705147 -138.657729)
		(end 414.777682 -138.832844)
		(width 0.1143)
		(layer "In2.Cu")
		(net "SATA6G_PCH_PCIE_UP_SATA_TXN<1>")
	)
	(arc
		(start 419.006782 -138.832844)
		(mid 419.254432 -138.585194)
		(end 419.502082 -138.832844)
		(width 0.1143)
		(layer "In2.Cu")
		(net "SATA6G_PCH_PCIE_UP_SATA_TXN<1>")
	)
	(arc
		(start 411.461966 -138.209782)
		(mid 411.878146 -138.487708)
		(end 412.369 -138.585194)
		(width 0.1143)
		(layer "In2.Cu")
		(net "SATA6G_PCH_PCIE_UP_SATA_TXN<1>")
	)
	(arc
		(start 421.748458 -138.778742)
		(mid 421.827965 -138.897594)
		(end 421.8559 -139.037822)
		(width 0.1143)
		(layer "In2.Cu")
		(net "SATA6G_PCH_PCIE_UP_SATA_TXN<1>")
	)
	(arc
		(start 414.777682 -138.843004)
		(mid 415.317432 -139.382754)
		(end 415.857182 -138.843004)
		(width 0.1143)
		(layer "In2.Cu")
		(net "SATA6G_PCH_PCIE_UP_SATA_TXN<1>")
	)
	(arc
		(start 417.927282 -138.843512)
		(mid 418.467032 -139.383262)
		(end 419.006782 -138.843512)
		(width 0.1143)
		(layer "In2.Cu")
		(net "SATA6G_PCH_PCIE_UP_SATA_TXN<1>")
	)
	(arc
		(start 390.61644 -133.934708)
		(mid 390.748505 -134.022795)
		(end 390.904222 -134.05358)
		(width 0.1143)
		(layer "In2.Cu")
		(net "SATA6G_PCH_PCIE_UP_SATA_TXN<1>")
	)
	(arc
		(start 416.352482 -138.84275)
		(mid 416.892232 -139.3825)
		(end 417.431982 -138.84275)
		(width 0.1143)
		(layer "In2.Cu")
		(net "SATA6G_PCH_PCIE_UP_SATA_TXN<1>")
	)
	(arc
		(start 387.16839 -130.539236)
		(mid 387.216908 -130.548869)
		(end 387.258052 -130.57632)
		(width 0.1143)
		(layer "In2.Cu")
		(net "SATA6G_PCH_PCIE_UP_SATA_TXN<1>")
	)
	(arc
		(start 410.348938 -137.34542)
		(mid 410.57864 -137.391093)
		(end 410.773372 -137.521188)
		(width 0.1143)
		(layer "In2.Cu")
		(net "SATA6G_PCH_PCIE_UP_SATA_TXN<1>")
	)
	(arc
		(start 382.77419 -129.70383)
		(mid 382.878142 -129.859406)
		(end 382.914652 -130.04292)
		(width 0.1143)
		(layer "In2.Cu")
		(net "SATA6G_PCH_PCIE_UP_SATA_TXN<1>")
	)
	(segment
		(start 382.17348 -125.678946)
		(end 382.17348 -125.833378)
		(width 0.0889)
		(layer "F.Cu")
		(net "SATA6G_PCH_PCIE_UP_SATA_TXN<0>")
	)
	(segment
		(start 382.303274 -125.38075)
		(end 382.28143 -125.435868)
		(width 0.0889)
		(layer "F.Cu")
		(net "SATA6G_PCH_PCIE_UP_SATA_TXN<0>")
	)
	(segment
		(start 382.331468 -126.711964)
		(end 382.830324 -127.21082)
		(width 0.0889)
		(layer "F.Cu")
		(net "SATA6G_PCH_PCIE_UP_SATA_TXN<0>")
	)
	(segment
		(start 382.484884 -124.919994)
		(end 382.303274 -125.38075)
		(width 0.0889)
		(layer "F.Cu")
		(net "SATA6G_PCH_PCIE_UP_SATA_TXN<0>")
	)
	(segment
		(start 383.37617 -127.586486)
		(end 383.191004 -127.771652)
		(width 0.0889)
		(layer "F.Cu")
		(net "SATA6G_PCH_PCIE_UP_SATA_TXN<0>")
	)
	(segment
		(start 383.413254 -127.422402)
		(end 383.413254 -127.496824)
		(width 0.0889)
		(layer "F.Cu")
		(net "SATA6G_PCH_PCIE_UP_SATA_TXN<0>")
	)
	(segment
		(start 382.259332 -125.485652)
		(end 382.17348 -125.678946)
		(width 0.0889)
		(layer "F.Cu")
		(net "SATA6G_PCH_PCIE_UP_SATA_TXN<0>")
	)
	(segment
		(start 382.17348 -125.833378)
		(end 382.270762 -126.068328)
		(width 0.0889)
		(layer "F.Cu")
		(net "SATA6G_PCH_PCIE_UP_SATA_TXN<0>")
	)
	(segment
		(start 382.28143 -125.435868)
		(end 382.259332 -125.485652)
		(width 0.0889)
		(layer "F.Cu")
		(net "SATA6G_PCH_PCIE_UP_SATA_TXN<0>")
	)
	(segment
		(start 382.331468 -126.27864)
		(end 382.331468 -126.711964)
		(width 0.0889)
		(layer "F.Cu")
		(net "SATA6G_PCH_PCIE_UP_SATA_TXN<0>")
	)
	(segment
		(start 383.054352 -127.30353)
		(end 383.294382 -127.30353)
		(width 0.0889)
		(layer "F.Cu")
		(net "SATA6G_PCH_PCIE_UP_SATA_TXN<0>")
	)
	(segment
		(start 382.270762 -126.068328)
		(end 382.331468 -126.27864)
		(width 0.0889)
		(layer "F.Cu")
		(net "SATA6G_PCH_PCIE_UP_SATA_TXN<0>")
	)
	(via
		(at 426.72 -139.838176)
		(size 0.508)
		(drill 0.254)
		(layers "F.Cu" "B.Cu")
		(net "SATA6G_PCH_PCIE_UP_SATA_TXN<0>")
	)
	(via
		(at 383.191004 -127.771652)
		(size 0.508)
		(drill 0.254)
		(layers "F.Cu" "B.Cu")
		(net "SATA6G_PCH_PCIE_UP_SATA_TXN<0>")
	)
	(arc
		(start 382.830324 -127.21082)
		(mid 382.933137 -127.279421)
		(end 383.054352 -127.30353)
		(width 0.0889)
		(layer "F.Cu")
		(net "SATA6G_PCH_PCIE_UP_SATA_TXN<0>")
	)
	(arc
		(start 383.294382 -127.30353)
		(mid 383.378437 -127.338347)
		(end 383.413254 -127.422402)
		(width 0.0889)
		(layer "F.Cu")
		(net "SATA6G_PCH_PCIE_UP_SATA_TXN<0>")
	)
	(arc
		(start 383.413254 -127.496824)
		(mid 383.403621 -127.545342)
		(end 383.37617 -127.586486)
		(width 0.0889)
		(layer "F.Cu")
		(net "SATA6G_PCH_PCIE_UP_SATA_TXN<0>")
	)
	(segment
		(start 426.72 -141.1986)
		(end 427.070266 -140.848334)
		(width 0.1143)
		(layer "B.Cu")
		(net "SATA6G_PCH_PCIE_UP_SATA_TXN<0>")
	)
	(segment
		(start 427.23435 -140.330174)
		(end 427.23435 -139.965176)
		(width 0.1143)
		(layer "B.Cu")
		(net "SATA6G_PCH_PCIE_UP_SATA_TXN<0>")
	)
	(segment
		(start 427.10735 -140.758672)
		(end 427.10735 -140.457174)
		(width 0.1143)
		(layer "B.Cu")
		(net "SATA6G_PCH_PCIE_UP_SATA_TXN<0>")
	)
	(segment
		(start 427.10735 -140.457174)
		(end 427.23435 -140.330174)
		(width 0.1143)
		(layer "B.Cu")
		(net "SATA6G_PCH_PCIE_UP_SATA_TXN<0>")
	)
	(segment
		(start 427.10735 -139.838176)
		(end 426.72 -139.838176)
		(width 0.1143)
		(layer "B.Cu")
		(net "SATA6G_PCH_PCIE_UP_SATA_TXN<0>")
	)
	(arc
		(start 427.070266 -140.848334)
		(mid 427.097699 -140.807183)
		(end 427.10735 -140.758672)
		(width 0.1143)
		(layer "B.Cu")
		(net "SATA6G_PCH_PCIE_UP_SATA_TXN<0>")
	)
	(arc
		(start 427.23435 -139.965176)
		(mid 427.197153 -139.875373)
		(end 427.10735 -139.838176)
		(width 0.1143)
		(layer "B.Cu")
		(net "SATA6G_PCH_PCIE_UP_SATA_TXN<0>")
	)
	(segment
		(start 414.154874 -136.9568)
		(end 411.620208 -136.9568)
		(width 0.1143)
		(layer "In2.Cu")
		(net "SATA6G_PCH_PCIE_UP_SATA_TXN<0>")
	)
	(segment
		(start 420.701724 -137.25144)
		(end 420.701724 -136.824974)
		(width 0.1143)
		(layer "In2.Cu")
		(net "SATA6G_PCH_PCIE_UP_SATA_TXN<0>")
	)
	(segment
		(start 419.126924 -137.261092)
		(end 419.126924 -136.860026)
		(width 0.1143)
		(layer "In2.Cu")
		(net "SATA6G_PCH_PCIE_UP_SATA_TXN<0>")
	)
	(segment
		(start 386.271008 -128.50114)
		(end 383.803906 -128.50114)
		(width 0.1143)
		(layer "In2.Cu")
		(net "SATA6G_PCH_PCIE_UP_SATA_TXN<0>")
	)
	(segment
		(start 421.781224 -137.0838)
		(end 421.781224 -137.25144)
		(width 0.1143)
		(layer "In2.Cu")
		(net "SATA6G_PCH_PCIE_UP_SATA_TXN<0>")
	)
	(segment
		(start 390.962134 -133.139942)
		(end 386.36067 -128.538224)
		(width 0.1143)
		(layer "In2.Cu")
		(net "SATA6G_PCH_PCIE_UP_SATA_TXN<0>")
	)
	(segment
		(start 417.056824 -137.021824)
		(end 417.056824 -137.274554)
		(width 0.1143)
		(layer "In2.Cu")
		(net "SATA6G_PCH_PCIE_UP_SATA_TXN<0>")
	)
	(segment
		(start 426.72 -139.838176)
		(end 427.171866 -139.38631)
		(width 0.1143)
		(layer "In2.Cu")
		(net "SATA6G_PCH_PCIE_UP_SATA_TXN<0>")
	)
	(segment
		(start 411.180026 -136.774428)
		(end 411.0355 -136.629648)
		(width 0.1143)
		(layer "In2.Cu")
		(net "SATA6G_PCH_PCIE_UP_SATA_TXN<0>")
	)
	(segment
		(start 427.20895 -139.296648)
		(end 427.20895 -138.139678)
		(width 0.1143)
		(layer "In2.Cu")
		(net "SATA6G_PCH_PCIE_UP_SATA_TXN<0>")
	)
	(segment
		(start 383.350008 -128.047242)
		(end 383.350008 -127.989076)
		(width 0.1143)
		(layer "In2.Cu")
		(net "SATA6G_PCH_PCIE_UP_SATA_TXN<0>")
	)
	(segment
		(start 417.552124 -137.245344)
		(end 417.552124 -137.021824)
		(width 0.1143)
		(layer "In2.Cu")
		(net "SATA6G_PCH_PCIE_UP_SATA_TXN<0>")
	)
	(segment
		(start 415.977324 -137.274554)
		(end 415.977324 -137.004552)
		(width 0.1143)
		(layer "In2.Cu")
		(net "SATA6G_PCH_PCIE_UP_SATA_TXN<0>")
	)
	(segment
		(start 402.08962 -133.259068)
		(end 391.249662 -133.259068)
		(width 0.1143)
		(layer "In2.Cu")
		(net "SATA6G_PCH_PCIE_UP_SATA_TXN<0>")
	)
	(segment
		(start 410.81325 -136.5377)
		(end 406.17648 -136.5377)
		(width 0.1143)
		(layer "In2.Cu")
		(net "SATA6G_PCH_PCIE_UP_SATA_TXN<0>")
	)
	(segment
		(start 383.30886 -127.889508)
		(end 383.191004 -127.771652)
		(width 0.1143)
		(layer "In2.Cu")
		(net "SATA6G_PCH_PCIE_UP_SATA_TXN<0>")
	)
	(segment
		(start 420.206424 -136.824974)
		(end 420.206424 -137.261092)
		(width 0.1143)
		(layer "In2.Cu")
		(net "SATA6G_PCH_PCIE_UP_SATA_TXN<0>")
	)
	(segment
		(start 427.171866 -138.050016)
		(end 426.115734 -136.993884)
		(width 0.1143)
		(layer "In2.Cu")
		(net "SATA6G_PCH_PCIE_UP_SATA_TXN<0>")
	)
	(segment
		(start 404.876762 -135.99922)
		(end 402.170392 -133.29285)
		(width 0.1143)
		(layer "In2.Cu")
		(net "SATA6G_PCH_PCIE_UP_SATA_TXN<0>")
	)
	(segment
		(start 414.402524 -137.31113)
		(end 414.402524 -137.20445)
		(width 0.1143)
		(layer "In2.Cu")
		(net "SATA6G_PCH_PCIE_UP_SATA_TXN<0>")
	)
	(segment
		(start 426.026072 -136.9568)
		(end 421.908224 -136.9568)
		(width 0.1143)
		(layer "In2.Cu")
		(net "SATA6G_PCH_PCIE_UP_SATA_TXN<0>")
	)
	(segment
		(start 415.482024 -137.004552)
		(end 415.482024 -137.31113)
		(width 0.1143)
		(layer "In2.Cu")
		(net "SATA6G_PCH_PCIE_UP_SATA_TXN<0>")
	)
	(segment
		(start 418.631624 -136.860026)
		(end 418.631624 -137.245344)
		(width 0.1143)
		(layer "In2.Cu")
		(net "SATA6G_PCH_PCIE_UP_SATA_TXN<0>")
	)
	(arc
		(start 406.17648 -136.5377)
		(mid 405.473072 -136.397708)
		(end 404.876762 -135.99922)
		(width 0.1143)
		(layer "In2.Cu")
		(net "SATA6G_PCH_PCIE_UP_SATA_TXN<0>")
	)
	(arc
		(start 383.803906 -128.50114)
		(mid 383.482952 -128.368196)
		(end 383.350008 -128.047242)
		(width 0.1143)
		(layer "In2.Cu")
		(net "SATA6G_PCH_PCIE_UP_SATA_TXN<0>")
	)
	(arc
		(start 415.482024 -137.31113)
		(mid 414.942274 -137.85088)
		(end 414.402524 -137.31113)
		(width 0.1143)
		(layer "In2.Cu")
		(net "SATA6G_PCH_PCIE_UP_SATA_TXN<0>")
	)
	(arc
		(start 421.908224 -136.9568)
		(mid 421.818421 -136.993997)
		(end 421.781224 -137.0838)
		(width 0.1143)
		(layer "In2.Cu")
		(net "SATA6G_PCH_PCIE_UP_SATA_TXN<0>")
	)
	(arc
		(start 421.781224 -137.25144)
		(mid 421.241474 -137.79119)
		(end 420.701724 -137.25144)
		(width 0.1143)
		(layer "In2.Cu")
		(net "SATA6G_PCH_PCIE_UP_SATA_TXN<0>")
	)
	(arc
		(start 411.0355 -136.629648)
		(mid 410.933516 -136.561597)
		(end 410.81325 -136.5377)
		(width 0.1143)
		(layer "In2.Cu")
		(net "SATA6G_PCH_PCIE_UP_SATA_TXN<0>")
	)
	(arc
		(start 386.36067 -128.538224)
		(mid 386.319519 -128.510791)
		(end 386.271008 -128.50114)
		(width 0.1143)
		(layer "In2.Cu")
		(net "SATA6G_PCH_PCIE_UP_SATA_TXN<0>")
	)
	(arc
		(start 418.631624 -137.245344)
		(mid 418.091874 -137.785094)
		(end 417.552124 -137.245344)
		(width 0.1143)
		(layer "In2.Cu")
		(net "SATA6G_PCH_PCIE_UP_SATA_TXN<0>")
	)
	(arc
		(start 414.402524 -137.20445)
		(mid 414.329989 -137.029335)
		(end 414.154874 -136.9568)
		(width 0.1143)
		(layer "In2.Cu")
		(net "SATA6G_PCH_PCIE_UP_SATA_TXN<0>")
	)
	(arc
		(start 427.171866 -139.38631)
		(mid 427.199299 -139.345159)
		(end 427.20895 -139.296648)
		(width 0.1143)
		(layer "In2.Cu")
		(net "SATA6G_PCH_PCIE_UP_SATA_TXN<0>")
	)
	(arc
		(start 391.249662 -133.259068)
		(mid 391.094042 -133.228113)
		(end 390.962134 -133.139942)
		(width 0.1143)
		(layer "In2.Cu")
		(net "SATA6G_PCH_PCIE_UP_SATA_TXN<0>")
	)
	(arc
		(start 415.977324 -137.004552)
		(mid 415.729674 -136.756902)
		(end 415.482024 -137.004552)
		(width 0.1143)
		(layer "In2.Cu")
		(net "SATA6G_PCH_PCIE_UP_SATA_TXN<0>")
	)
	(arc
		(start 411.620208 -136.9568)
		(mid 411.381967 -136.909411)
		(end 411.180026 -136.774428)
		(width 0.1143)
		(layer "In2.Cu")
		(net "SATA6G_PCH_PCIE_UP_SATA_TXN<0>")
	)
	(arc
		(start 417.056824 -137.274554)
		(mid 416.517074 -137.814304)
		(end 415.977324 -137.274554)
		(width 0.1143)
		(layer "In2.Cu")
		(net "SATA6G_PCH_PCIE_UP_SATA_TXN<0>")
	)
	(arc
		(start 419.126924 -136.860026)
		(mid 418.879274 -136.612376)
		(end 418.631624 -136.860026)
		(width 0.1143)
		(layer "In2.Cu")
		(net "SATA6G_PCH_PCIE_UP_SATA_TXN<0>")
	)
	(arc
		(start 383.350008 -127.989076)
		(mid 383.339312 -127.935212)
		(end 383.30886 -127.889508)
		(width 0.1143)
		(layer "In2.Cu")
		(net "SATA6G_PCH_PCIE_UP_SATA_TXN<0>")
	)
	(arc
		(start 426.115734 -136.993884)
		(mid 426.074583 -136.966451)
		(end 426.026072 -136.9568)
		(width 0.1143)
		(layer "In2.Cu")
		(net "SATA6G_PCH_PCIE_UP_SATA_TXN<0>")
	)
	(arc
		(start 417.552124 -137.021824)
		(mid 417.304474 -136.774174)
		(end 417.056824 -137.021824)
		(width 0.1143)
		(layer "In2.Cu")
		(net "SATA6G_PCH_PCIE_UP_SATA_TXN<0>")
	)
	(arc
		(start 402.170392 -133.29285)
		(mid 402.133363 -133.267951)
		(end 402.08962 -133.259068)
		(width 0.1143)
		(layer "In2.Cu")
		(net "SATA6G_PCH_PCIE_UP_SATA_TXN<0>")
	)
	(arc
		(start 427.20895 -138.139678)
		(mid 427.199317 -138.09116)
		(end 427.171866 -138.050016)
		(width 0.1143)
		(layer "In2.Cu")
		(net "SATA6G_PCH_PCIE_UP_SATA_TXN<0>")
	)
	(arc
		(start 420.701724 -136.824974)
		(mid 420.454074 -136.577324)
		(end 420.206424 -136.824974)
		(width 0.1143)
		(layer "In2.Cu")
		(net "SATA6G_PCH_PCIE_UP_SATA_TXN<0>")
	)
	(arc
		(start 420.206424 -137.261092)
		(mid 419.666674 -137.800842)
		(end 419.126924 -137.261092)
		(width 0.1143)
		(layer "In2.Cu")
		(net "SATA6G_PCH_PCIE_UP_SATA_TXN<0>")
	)
	(segment
		(start 383.77495 -121.01576)
		(end 384.27025 -121.245884)
		(width 0.1143)
		(layer "F.Cu")
		(net "SATA6G_PCH_PCIE_UP_SATA_RXN<7>")
	)
	(via
		(at 384.27025 -121.245884)
		(size 0.508)
		(drill 0.254)
		(layers "F.Cu" "B.Cu")
		(net "SATA6G_PCH_PCIE_UP_SATA_RXN<7>")
	)
	(via
		(at 407.382726 -154.5463)
		(size 0.508)
		(drill 0.254)
		(layers "F.Cu" "B.Cu")
		(net "SATA6G_PCH_PCIE_UP_SATA_RXN<7>")
	)
	(segment
		(start 407.617168 -154.15895)
		(end 407.497026 -154.15895)
		(width 0.1143)
		(layer "B.Cu")
		(net "SATA6G_PCH_PCIE_UP_SATA_RXN<7>")
	)
	(segment
		(start 408.1526 -154.4828)
		(end 407.97861 -154.30881)
		(width 0.1143)
		(layer "B.Cu")
		(net "SATA6G_PCH_PCIE_UP_SATA_RXN<7>")
	)
	(segment
		(start 407.382726 -154.27325)
		(end 407.382726 -154.5463)
		(width 0.1143)
		(layer "B.Cu")
		(net "SATA6G_PCH_PCIE_UP_SATA_RXN<7>")
	)
	(arc
		(start 407.97861 -154.30881)
		(mid 407.812794 -154.197922)
		(end 407.617168 -154.15895)
		(width 0.1143)
		(layer "B.Cu")
		(net "SATA6G_PCH_PCIE_UP_SATA_RXN<7>")
	)
	(arc
		(start 407.497026 -154.15895)
		(mid 407.416204 -154.192428)
		(end 407.382726 -154.27325)
		(width 0.1143)
		(layer "B.Cu")
		(net "SATA6G_PCH_PCIE_UP_SATA_RXN<7>")
	)
	(segment
		(start 383.1336 -124.3076)
		(end 383.1336 -124.329698)
		(width 0.0889)
		(layer "In9.Cu")
		(net "SATA6G_PCH_PCIE_UP_SATA_RXN<7>")
	)
	(segment
		(start 383.1844 -123.799854)
		(end 383.1844 -124.2568)
		(width 0.0889)
		(layer "In9.Cu")
		(net "SATA6G_PCH_PCIE_UP_SATA_RXN<7>")
	)
	(segment
		(start 404.490682 -151.526748)
		(end 404.490936 -151.526494)
		(width 0.1143)
		(layer "In9.Cu")
		(net "SATA6G_PCH_PCIE_UP_SATA_RXN<7>")
	)
	(segment
		(start 384.175 -122.082814)
		(end 384.175 -122.11558)
		(width 0.0889)
		(layer "In9.Cu")
		(net "SATA6G_PCH_PCIE_UP_SATA_RXN<7>")
	)
	(segment
		(start 407.054304 -154.217878)
		(end 407.382726 -154.5463)
		(width 0.1143)
		(layer "In9.Cu")
		(net "SATA6G_PCH_PCIE_UP_SATA_RXN<7>")
	)
	(segment
		(start 406.582372 -154.18435)
		(end 406.973532 -154.18435)
		(width 0.1143)
		(layer "In9.Cu")
		(net "SATA6G_PCH_PCIE_UP_SATA_RXN<7>")
	)
	(segment
		(start 403.815804 -150.804626)
		(end 404.457154 -151.445976)
		(width 0.1143)
		(layer "In9.Cu")
		(net "SATA6G_PCH_PCIE_UP_SATA_RXN<7>")
	)
	(segment
		(start 384.318764 -128.790954)
		(end 384.318764 -130.529584)
		(width 0.1143)
		(layer "In9.Cu")
		(net "SATA6G_PCH_PCIE_UP_SATA_RXN<7>")
	)
	(segment
		(start 384.66014 -121.2977)
		(end 384.666236 -121.303796)
		(width 0.0889)
		(layer "In9.Cu")
		(net "SATA6G_PCH_PCIE_UP_SATA_RXN<7>")
	)
	(segment
		(start 383.1844 -124.2568)
		(end 383.1336 -124.3076)
		(width 0.0889)
		(layer "In9.Cu")
		(net "SATA6G_PCH_PCIE_UP_SATA_RXN<7>")
	)
	(segment
		(start 403.451568 -136.671558)
		(end 403.451568 -137.379456)
		(width 0.1143)
		(layer "In9.Cu")
		(net "SATA6G_PCH_PCIE_UP_SATA_RXN<7>")
	)
	(segment
		(start 384.8608 -131.5212)
		(end 384.8608 -132.147564)
		(width 0.1143)
		(layer "In9.Cu")
		(net "SATA6G_PCH_PCIE_UP_SATA_RXN<7>")
	)
	(segment
		(start 389.236966 -136.523222)
		(end 396.560802 -136.523222)
		(width 0.1143)
		(layer "In9.Cu")
		(net "SATA6G_PCH_PCIE_UP_SATA_RXN<7>")
	)
	(segment
		(start 402.387054 -139.272264)
		(end 402.387054 -149.776434)
		(width 0.1143)
		(layer "In9.Cu")
		(net "SATA6G_PCH_PCIE_UP_SATA_RXN<7>")
	)
	(segment
		(start 382.208786 -126.555754)
		(end 382.208786 -127.699262)
		(width 0.1143)
		(layer "In9.Cu")
		(net "SATA6G_PCH_PCIE_UP_SATA_RXN<7>")
	)
	(segment
		(start 403.381718 -150.771098)
		(end 403.735032 -150.771098)
		(width 0.1143)
		(layer "In9.Cu")
		(net "SATA6G_PCH_PCIE_UP_SATA_RXN<7>")
	)
	(segment
		(start 392.466322 -138.148822)
		(end 397.20901 -138.148822)
		(width 0.1143)
		(layer "In9.Cu")
		(net "SATA6G_PCH_PCIE_UP_SATA_RXN<7>")
	)
	(segment
		(start 403.214078 -137.95248)
		(end 402.735034 -138.431524)
		(width 0.1143)
		(layer "In9.Cu")
		(net "SATA6G_PCH_PCIE_UP_SATA_RXN<7>")
	)
	(segment
		(start 396.560802 -137.043922)
		(end 392.466322 -137.043922)
		(width 0.1143)
		(layer "In9.Cu")
		(net "SATA6G_PCH_PCIE_UP_SATA_RXN<7>")
	)
	(segment
		(start 404.490936 -151.526494)
		(end 404.490936 -152.092914)
		(width 0.1143)
		(layer "In9.Cu")
		(net "SATA6G_PCH_PCIE_UP_SATA_RXN<7>")
	)
	(segment
		(start 384.27025 -121.245884)
		(end 384.535172 -121.245884)
		(width 0.0889)
		(layer "In9.Cu")
		(net "SATA6G_PCH_PCIE_UP_SATA_RXN<7>")
	)
	(segment
		(start 382.442974 -128.265428)
		(end 382.485138 -128.307592)
		(width 0.1143)
		(layer "In9.Cu")
		(net "SATA6G_PCH_PCIE_UP_SATA_RXN<7>")
	)
	(segment
		(start 383.1336 -124.329698)
		(end 383.1336 -125.396498)
		(width 0.1143)
		(layer "In9.Cu")
		(net "SATA6G_PCH_PCIE_UP_SATA_RXN<7>")
	)
	(segment
		(start 382.97739 -128.511554)
		(end 384.039364 -128.511554)
		(width 0.1143)
		(layer "In9.Cu")
		(net "SATA6G_PCH_PCIE_UP_SATA_RXN<7>")
	)
	(segment
		(start 404.609808 -152.380188)
		(end 406.295098 -154.065478)
		(width 0.1143)
		(layer "In9.Cu")
		(net "SATA6G_PCH_PCIE_UP_SATA_RXN<7>")
	)
	(segment
		(start 403.114002 -135.85698)
		(end 403.114256 -135.857234)
		(width 0.1143)
		(layer "In9.Cu")
		(net "SATA6G_PCH_PCIE_UP_SATA_RXN<7>")
	)
	(segment
		(start 384.979672 -132.434838)
		(end 388.949184 -136.40435)
		(width 0.1143)
		(layer "In9.Cu")
		(net "SATA6G_PCH_PCIE_UP_SATA_RXN<7>")
	)
	(segment
		(start 398.241774 -137.72134)
		(end 398.99463 -136.968484)
		(width 0.1143)
		(layer "In9.Cu")
		(net "SATA6G_PCH_PCIE_UP_SATA_RXN<7>")
	)
	(segment
		(start 383.6797 -122.941334)
		(end 383.6797 -122.9741)
		(width 0.0889)
		(layer "In9.Cu")
		(net "SATA6G_PCH_PCIE_UP_SATA_RXN<7>")
	)
	(segment
		(start 403.214078 -137.952226)
		(end 403.214078 -137.95248)
		(width 0.1143)
		(layer "In9.Cu")
		(net "SATA6G_PCH_PCIE_UP_SATA_RXN<7>")
	)
	(segment
		(start 384.494532 -130.953764)
		(end 384.718052 -131.177284)
		(width 0.1143)
		(layer "In9.Cu")
		(net "SATA6G_PCH_PCIE_UP_SATA_RXN<7>")
	)
	(segment
		(start 383.099818 -125.47727)
		(end 382.341628 -126.235714)
		(width 0.1143)
		(layer "In9.Cu")
		(net "SATA6G_PCH_PCIE_UP_SATA_RXN<7>")
	)
	(segment
		(start 402.505926 -150.063708)
		(end 403.094444 -150.652226)
		(width 0.1143)
		(layer "In9.Cu")
		(net "SATA6G_PCH_PCIE_UP_SATA_RXN<7>")
	)
	(arc
		(start 400.245072 -136.196324)
		(mid 400.848069 -135.962273)
		(end 401.431252 -135.682482)
		(width 0.1143)
		(layer "In9.Cu")
		(net "SATA6G_PCH_PCIE_UP_SATA_RXN<7>")
	)
	(arc
		(start 384.470148 -121.592594)
		(mid 384.259284 -121.799598)
		(end 384.175 -122.082814)
		(width 0.0889)
		(layer "In9.Cu")
		(net "SATA6G_PCH_PCIE_UP_SATA_RXN<7>")
	)
	(arc
		(start 383.479548 -123.309634)
		(mid 383.268684 -123.516638)
		(end 383.1844 -123.799854)
		(width 0.0889)
		(layer "In9.Cu")
		(net "SATA6G_PCH_PCIE_UP_SATA_RXN<7>")
	)
	(arc
		(start 384.175 -122.11558)
		(mid 384.11865 -122.30943)
		(end 383.974848 -122.451114)
		(width 0.0889)
		(layer "In9.Cu")
		(net "SATA6G_PCH_PCIE_UP_SATA_RXN<7>")
	)
	(arc
		(start 383.1336 -125.396498)
		(mid 383.124782 -125.440268)
		(end 383.099818 -125.47727)
		(width 0.1143)
		(layer "In9.Cu")
		(net "SATA6G_PCH_PCIE_UP_SATA_RXN<7>")
	)
	(arc
		(start 398.99463 -136.968484)
		(mid 399.574825 -136.509491)
		(end 400.245072 -136.196324)
		(width 0.1143)
		(layer "In9.Cu")
		(net "SATA6G_PCH_PCIE_UP_SATA_RXN<7>")
	)
	(arc
		(start 404.490936 -152.092914)
		(mid 404.521822 -152.248368)
		(end 404.609808 -152.380188)
		(width 0.1143)
		(layer "In9.Cu")
		(net "SATA6G_PCH_PCIE_UP_SATA_RXN<7>")
	)
	(arc
		(start 402.735034 -138.431524)
		(mid 402.477377 -138.817274)
		(end 402.387054 -139.272264)
		(width 0.1143)
		(layer "In9.Cu")
		(net "SATA6G_PCH_PCIE_UP_SATA_RXN<7>")
	)
	(arc
		(start 403.735032 -150.771098)
		(mid 403.778773 -150.779799)
		(end 403.815804 -150.804626)
		(width 0.1143)
		(layer "In9.Cu")
		(net "SATA6G_PCH_PCIE_UP_SATA_RXN<7>")
	)
	(arc
		(start 402.387054 -149.776434)
		(mid 402.41794 -149.931888)
		(end 402.505926 -150.063708)
		(width 0.1143)
		(layer "In9.Cu")
		(net "SATA6G_PCH_PCIE_UP_SATA_RXN<7>")
	)
	(arc
		(start 384.666236 -121.303796)
		(mid 384.601336 -121.470697)
		(end 384.470148 -121.592594)
		(width 0.0889)
		(layer "In9.Cu")
		(net "SATA6G_PCH_PCIE_UP_SATA_RXN<7>")
	)
	(arc
		(start 397.20901 -138.148822)
		(mid 397.76789 -138.037765)
		(end 398.241774 -137.72134)
		(width 0.1143)
		(layer "In9.Cu")
		(net "SATA6G_PCH_PCIE_UP_SATA_RXN<7>")
	)
	(arc
		(start 384.039364 -128.511554)
		(mid 384.23693 -128.593388)
		(end 384.318764 -128.790954)
		(width 0.1143)
		(layer "In9.Cu")
		(net "SATA6G_PCH_PCIE_UP_SATA_RXN<7>")
	)
	(arc
		(start 406.973532 -154.18435)
		(mid 407.017258 -154.193066)
		(end 407.054304 -154.217878)
		(width 0.1143)
		(layer "In9.Cu")
		(net "SATA6G_PCH_PCIE_UP_SATA_RXN<7>")
	)
	(arc
		(start 383.974848 -122.451114)
		(mid 383.763984 -122.658118)
		(end 383.6797 -122.941334)
		(width 0.0889)
		(layer "In9.Cu")
		(net "SATA6G_PCH_PCIE_UP_SATA_RXN<7>")
	)
	(arc
		(start 384.318764 -130.529584)
		(mid 384.364447 -130.75916)
		(end 384.494532 -130.953764)
		(width 0.1143)
		(layer "In9.Cu")
		(net "SATA6G_PCH_PCIE_UP_SATA_RXN<7>")
	)
	(arc
		(start 401.431252 -135.682482)
		(mid 401.810086 -135.536611)
		(end 402.212556 -135.4836)
		(width 0.1143)
		(layer "In9.Cu")
		(net "SATA6G_PCH_PCIE_UP_SATA_RXN<7>")
	)
	(arc
		(start 406.295098 -154.065478)
		(mid 406.426929 -154.153438)
		(end 406.582372 -154.18435)
		(width 0.1143)
		(layer "In9.Cu")
		(net "SATA6G_PCH_PCIE_UP_SATA_RXN<7>")
	)
	(arc
		(start 382.485138 -128.307592)
		(mid 382.710957 -128.458576)
		(end 382.97739 -128.511554)
		(width 0.1143)
		(layer "In9.Cu")
		(net "SATA6G_PCH_PCIE_UP_SATA_RXN<7>")
	)
	(arc
		(start 384.535172 -121.245884)
		(mid 384.60281 -121.259356)
		(end 384.66014 -121.2977)
		(width 0.0889)
		(layer "In9.Cu")
		(net "SATA6G_PCH_PCIE_UP_SATA_RXN<7>")
	)
	(arc
		(start 388.949184 -136.40435)
		(mid 389.081249 -136.492437)
		(end 389.236966 -136.523222)
		(width 0.1143)
		(layer "In9.Cu")
		(net "SATA6G_PCH_PCIE_UP_SATA_RXN<7>")
	)
	(arc
		(start 403.114256 -135.857234)
		(mid 403.363898 -136.230849)
		(end 403.451568 -136.671558)
		(width 0.1143)
		(layer "In9.Cu")
		(net "SATA6G_PCH_PCIE_UP_SATA_RXN<7>")
	)
	(arc
		(start 382.341628 -126.235714)
		(mid 382.243433 -126.382535)
		(end 382.208786 -126.555754)
		(width 0.1143)
		(layer "In9.Cu")
		(net "SATA6G_PCH_PCIE_UP_SATA_RXN<7>")
	)
	(arc
		(start 382.208786 -127.699262)
		(mid 382.269611 -128.005612)
		(end 382.442974 -128.265428)
		(width 0.1143)
		(layer "In9.Cu")
		(net "SATA6G_PCH_PCIE_UP_SATA_RXN<7>")
	)
	(arc
		(start 384.8608 -132.147564)
		(mid 384.891686 -132.303018)
		(end 384.979672 -132.434838)
		(width 0.1143)
		(layer "In9.Cu")
		(net "SATA6G_PCH_PCIE_UP_SATA_RXN<7>")
	)
	(arc
		(start 403.094444 -150.652226)
		(mid 403.226275 -150.740186)
		(end 403.381718 -150.771098)
		(width 0.1143)
		(layer "In9.Cu")
		(net "SATA6G_PCH_PCIE_UP_SATA_RXN<7>")
	)
	(arc
		(start 383.6797 -122.9741)
		(mid 383.62335 -123.16795)
		(end 383.479548 -123.309634)
		(width 0.0889)
		(layer "In9.Cu")
		(net "SATA6G_PCH_PCIE_UP_SATA_RXN<7>")
	)
	(arc
		(start 392.466322 -137.043922)
		(mid 391.913872 -137.596372)
		(end 392.466322 -138.148822)
		(width 0.1143)
		(layer "In9.Cu")
		(net "SATA6G_PCH_PCIE_UP_SATA_RXN<7>")
	)
	(arc
		(start 402.212556 -135.4836)
		(mid 402.700411 -135.58064)
		(end 403.114002 -135.85698)
		(width 0.1143)
		(layer "In9.Cu")
		(net "SATA6G_PCH_PCIE_UP_SATA_RXN<7>")
	)
	(arc
		(start 403.451568 -137.379456)
		(mid 403.389808 -137.689475)
		(end 403.214078 -137.952226)
		(width 0.1143)
		(layer "In9.Cu")
		(net "SATA6G_PCH_PCIE_UP_SATA_RXN<7>")
	)
	(arc
		(start 404.457154 -151.445976)
		(mid 404.48197 -151.48302)
		(end 404.490682 -151.526748)
		(width 0.1143)
		(layer "In9.Cu")
		(net "SATA6G_PCH_PCIE_UP_SATA_RXN<7>")
	)
	(arc
		(start 396.560802 -136.523222)
		(mid 396.821152 -136.783572)
		(end 396.560802 -137.043922)
		(width 0.1143)
		(layer "In9.Cu")
		(net "SATA6G_PCH_PCIE_UP_SATA_RXN<7>")
	)
	(arc
		(start 384.718052 -131.177284)
		(mid 384.823621 -131.335045)
		(end 384.8608 -131.5212)
		(width 0.1143)
		(layer "In9.Cu")
		(net "SATA6G_PCH_PCIE_UP_SATA_RXN<7>")
	)
	(segment
		(start 389.71855 -120.387364)
		(end 389.22325 -120.15724)
		(width 0.1143)
		(layer "F.Cu")
		(net "SATA6G_PCH_PCIE_UP_SATA_RXN<6>")
	)
	(via
		(at 389.71855 -120.387364)
		(size 0.508)
		(drill 0.254)
		(layers "F.Cu" "B.Cu")
		(net "SATA6G_PCH_PCIE_UP_SATA_RXN<6>")
	)
	(via
		(at 407.395426 -151.5745)
		(size 0.508)
		(drill 0.254)
		(layers "F.Cu" "B.Cu")
		(net "SATA6G_PCH_PCIE_UP_SATA_RXN<6>")
	)
	(segment
		(start 408.014678 -151.220678)
		(end 408.305 -151.511)
		(width 0.1143)
		(layer "B.Cu")
		(net "SATA6G_PCH_PCIE_UP_SATA_RXN<6>")
	)
	(segment
		(start 407.395426 -151.5745)
		(end 407.395426 -151.30145)
		(width 0.1143)
		(layer "B.Cu")
		(net "SATA6G_PCH_PCIE_UP_SATA_RXN<6>")
	)
	(segment
		(start 407.509726 -151.18715)
		(end 407.933906 -151.18715)
		(width 0.1143)
		(layer "B.Cu")
		(net "SATA6G_PCH_PCIE_UP_SATA_RXN<6>")
	)
	(arc
		(start 407.933906 -151.18715)
		(mid 407.977647 -151.195851)
		(end 408.014678 -151.220678)
		(width 0.1143)
		(layer "B.Cu")
		(net "SATA6G_PCH_PCIE_UP_SATA_RXN<6>")
	)
	(arc
		(start 407.395426 -151.30145)
		(mid 407.428904 -151.220628)
		(end 407.509726 -151.18715)
		(width 0.1143)
		(layer "B.Cu")
		(net "SATA6G_PCH_PCIE_UP_SATA_RXN<6>")
	)
	(segment
		(start 385.532376 -130.255264)
		(end 385.29006 -130.012948)
		(width 0.1143)
		(layer "In9.Cu")
		(net "SATA6G_PCH_PCIE_UP_SATA_RXN<6>")
	)
	(segment
		(start 405.074882 -140.01242)
		(end 405.070056 -140.016992)
		(width 0.1143)
		(layer "In9.Cu")
		(net "SATA6G_PCH_PCIE_UP_SATA_RXN<6>")
	)
	(segment
		(start 403.562058 -133.729984)
		(end 404.209504 -133.082538)
		(width 0.1143)
		(layer "In9.Cu")
		(net "SATA6G_PCH_PCIE_UP_SATA_RXN<6>")
	)
	(segment
		(start 385.6863 -131.591812)
		(end 385.6863 -130.626612)
		(width 0.1143)
		(layer "In9.Cu")
		(net "SATA6G_PCH_PCIE_UP_SATA_RXN<6>")
	)
	(segment
		(start 403.629114 -132.927344)
		(end 403.629114 -132.927598)
		(width 0.1143)
		(layer "In9.Cu")
		(net "SATA6G_PCH_PCIE_UP_SATA_RXN<6>")
	)
	(segment
		(start 404.032466 -134.82066)
		(end 403.562058 -134.350252)
		(width 0.1143)
		(layer "In9.Cu")
		(net "SATA6G_PCH_PCIE_UP_SATA_RXN<6>")
	)
	(segment
		(start 404.032974 -134.821422)
		(end 404.032466 -134.82066)
		(width 0.1143)
		(layer "In9.Cu")
		(net "SATA6G_PCH_PCIE_UP_SATA_RXN<6>")
	)
	(segment
		(start 405.374348 -149.291802)
		(end 405.07412 -149.591776)
		(width 0.1143)
		(layer "In9.Cu")
		(net "SATA6G_PCH_PCIE_UP_SATA_RXN<6>")
	)
	(segment
		(start 385.130802 -125.86335)
		(end 384.298444 -125.030992)
		(width 0.0889)
		(layer "In9.Cu")
		(net "SATA6G_PCH_PCIE_UP_SATA_RXN<6>")
	)
	(segment
		(start 385.106164 -126.72568)
		(end 385.106164 -126.703582)
		(width 0.0889)
		(layer "In9.Cu")
		(net "SATA6G_PCH_PCIE_UP_SATA_RXN<6>")
	)
	(segment
		(start 405.504904 -149.896576)
		(end 405.742648 -149.660356)
		(width 0.1143)
		(layer "In9.Cu")
		(net "SATA6G_PCH_PCIE_UP_SATA_RXN<6>")
	)
	(segment
		(start 403.841712 -132.714746)
		(end 403.629114 -132.927344)
		(width 0.1143)
		(layer "In9.Cu")
		(net "SATA6G_PCH_PCIE_UP_SATA_RXN<6>")
	)
	(segment
		(start 403.89683 -146.431)
		(end 403.89683 -145.762726)
		(width 0.1143)
		(layer "In9.Cu")
		(net "SATA6G_PCH_PCIE_UP_SATA_RXN<6>")
	)
	(segment
		(start 405.070056 -140.016992)
		(end 404.14194 -140.9446)
		(width 0.1143)
		(layer "In9.Cu")
		(net "SATA6G_PCH_PCIE_UP_SATA_RXN<6>")
	)
	(segment
		(start 404.270718 -138.973052)
		(end 404.270718 -135.3947)
		(width 0.1143)
		(layer "In9.Cu")
		(net "SATA6G_PCH_PCIE_UP_SATA_RXN<6>")
	)
	(segment
		(start 404.254716 -149.220174)
		(end 404.254716 -147.2946)
		(width 0.1143)
		(layer "In9.Cu")
		(net "SATA6G_PCH_PCIE_UP_SATA_RXN<6>")
	)
	(segment
		(start 406.984962 -151.21128)
		(end 406.142698 -151.21128)
		(width 0.1143)
		(layer "In9.Cu")
		(net "SATA6G_PCH_PCIE_UP_SATA_RXN<6>")
	)
	(segment
		(start 403.89683 -142.88389)
		(end 403.89683 -142.29715)
		(width 0.1143)
		(layer "In9.Cu")
		(net "SATA6G_PCH_PCIE_UP_SATA_RXN<6>")
	)
	(segment
		(start 403.34565 -140.17879)
		(end 404.072344 -139.452096)
		(width 0.1143)
		(layer "In9.Cu")
		(net "SATA6G_PCH_PCIE_UP_SATA_RXN<6>")
	)
	(segment
		(start 407.395426 -151.5745)
		(end 407.065734 -151.244808)
		(width 0.1143)
		(layer "In9.Cu")
		(net "SATA6G_PCH_PCIE_UP_SATA_RXN<6>")
	)
	(segment
		(start 405.896318 -139.638024)
		(end 405.896318 -136.364726)
		(width 0.1143)
		(layer "In9.Cu")
		(net "SATA6G_PCH_PCIE_UP_SATA_RXN<6>")
	)
	(segment
		(start 384.6703 -122.9741)
		(end 384.6703 -122.941334)
		(width 0.0889)
		(layer "In9.Cu")
		(net "SATA6G_PCH_PCIE_UP_SATA_RXN<6>")
	)
	(segment
		(start 385.106164 -129.568448)
		(end 385.106164 -126.72568)
		(width 0.1143)
		(layer "In9.Cu")
		(net "SATA6G_PCH_PCIE_UP_SATA_RXN<6>")
	)
	(segment
		(start 403.629114 -132.927598)
		(end 403.46503 -133.091682)
		(width 0.1143)
		(layer "In9.Cu")
		(net "SATA6G_PCH_PCIE_UP_SATA_RXN<6>")
	)
	(segment
		(start 404.457154 -149.591776)
		(end 404.373842 -149.508464)
		(width 0.1143)
		(layer "In9.Cu")
		(net "SATA6G_PCH_PCIE_UP_SATA_RXN<6>")
	)
	(segment
		(start 384.470402 -123.309634)
		(end 384.470148 -123.309634)
		(width 0.0889)
		(layer "In9.Cu")
		(net "SATA6G_PCH_PCIE_UP_SATA_RXN<6>")
	)
	(segment
		(start 385.1656 -122.11558)
		(end 385.1656 -122.082814)
		(width 0.0889)
		(layer "In9.Cu")
		(net "SATA6G_PCH_PCIE_UP_SATA_RXN<6>")
	)
	(segment
		(start 385.6863 -130.626612)
		(end 385.686046 -130.626866)
		(width 0.1143)
		(layer "In9.Cu")
		(net "SATA6G_PCH_PCIE_UP_SATA_RXN<6>")
	)
	(segment
		(start 385.931918 -132.185918)
		(end 385.932172 -132.185918)
		(width 0.1143)
		(layer "In9.Cu")
		(net "SATA6G_PCH_PCIE_UP_SATA_RXN<6>")
	)
	(segment
		(start 403.695154 -144.51965)
		(end 403.827742 -144.51965)
		(width 0.1143)
		(layer "In9.Cu")
		(net "SATA6G_PCH_PCIE_UP_SATA_RXN<6>")
	)
	(segment
		(start 404.146512 -141.6939)
		(end 405.67991 -140.160502)
		(width 0.1143)
		(layer "In9.Cu")
		(net "SATA6G_PCH_PCIE_UP_SATA_RXN<6>")
	)
	(segment
		(start 384.175 -124.732542)
		(end 384.175 -123.807728)
		(width 0.0889)
		(layer "In9.Cu")
		(net "SATA6G_PCH_PCIE_UP_SATA_RXN<6>")
	)
	(segment
		(start 385.106164 -126.703582)
		(end 385.156964 -126.652782)
		(width 0.0889)
		(layer "In9.Cu")
		(net "SATA6G_PCH_PCIE_UP_SATA_RXN<6>")
	)
	(segment
		(start 397.177768 -135.695944)
		(end 389.610346 -135.695944)
		(width 0.1143)
		(layer "In9.Cu")
		(net "SATA6G_PCH_PCIE_UP_SATA_RXN<6>")
	)
	(segment
		(start 405.855424 -151.092408)
		(end 405.504142 -150.741126)
		(width 0.1143)
		(layer "In9.Cu")
		(net "SATA6G_PCH_PCIE_UP_SATA_RXN<6>")
	)
	(segment
		(start 405.375618 -136.364726)
		(end 405.375618 -139.31265)
		(width 0.1143)
		(layer "In9.Cu")
		(net "SATA6G_PCH_PCIE_UP_SATA_RXN<6>")
	)
	(segment
		(start 389.322818 -135.576818)
		(end 385.931918 -132.185918)
		(width 0.1143)
		(layer "In9.Cu")
		(net "SATA6G_PCH_PCIE_UP_SATA_RXN<6>")
	)
	(segment
		(start 385.156964 -126.652782)
		(end 385.156964 -125.926342)
		(width 0.0889)
		(layer "In9.Cu")
		(net "SATA6G_PCH_PCIE_UP_SATA_RXN<6>")
	)
	(segment
		(start 403.89683 -144.450562)
		(end 403.89683 -144.264126)
		(width 0.1143)
		(layer "In9.Cu")
		(net "SATA6G_PCH_PCIE_UP_SATA_RXN<6>")
	)
	(segment
		(start 403.695154 -143.02105)
		(end 403.75967 -143.02105)
		(width 0.1143)
		(layer "In9.Cu")
		(net "SATA6G_PCH_PCIE_UP_SATA_RXN<6>")
	)
	(segment
		(start 385.6609 -121.25706)
		(end 385.6609 -121.224294)
		(width 0.0889)
		(layer "In9.Cu")
		(net "SATA6G_PCH_PCIE_UP_SATA_RXN<6>")
	)
	(arc
		(start 388.528052 -120.734074)
		(mid 388.72795 -120.787573)
		(end 388.927848 -120.734074)
		(width 0.0889)
		(layer "In9.Cu")
		(net "SATA6G_PCH_PCIE_UP_SATA_RXN<6>")
	)
	(arc
		(start 403.562058 -134.350252)
		(mid 403.433596 -134.040118)
		(end 403.562058 -133.729984)
		(width 0.1143)
		(layer "In9.Cu")
		(net "SATA6G_PCH_PCIE_UP_SATA_RXN<6>")
	)
	(arc
		(start 403.695154 -144.06245)
		(mid 403.174454 -143.54175)
		(end 403.695154 -143.02105)
		(width 0.1143)
		(layer "In9.Cu")
		(net "SATA6G_PCH_PCIE_UP_SATA_RXN<6>")
	)
	(arc
		(start 403.89683 -145.762726)
		(mid 403.83776 -145.62012)
		(end 403.695154 -145.56105)
		(width 0.1143)
		(layer "In9.Cu")
		(net "SATA6G_PCH_PCIE_UP_SATA_RXN<6>")
	)
	(arc
		(start 404.096474 -146.913346)
		(mid 403.948712 -146.692015)
		(end 403.89683 -146.431)
		(width 0.1143)
		(layer "In9.Cu")
		(net "SATA6G_PCH_PCIE_UP_SATA_RXN<6>")
	)
	(arc
		(start 405.094186 -139.993624)
		(mid 405.084601 -140.00309)
		(end 405.074882 -140.01242)
		(width 0.1143)
		(layer "In9.Cu")
		(net "SATA6G_PCH_PCIE_UP_SATA_RXN<6>")
	)
	(arc
		(start 403.345904 -140.9446)
		(mid 403.187098 -140.561748)
		(end 403.34565 -140.17879)
		(width 0.1143)
		(layer "In9.Cu")
		(net "SATA6G_PCH_PCIE_UP_SATA_RXN<6>")
	)
	(arc
		(start 387.937248 -120.734074)
		(mid 388.23265 -120.654943)
		(end 388.528052 -120.734074)
		(width 0.0889)
		(layer "In9.Cu")
		(net "SATA6G_PCH_PCIE_UP_SATA_RXN<6>")
	)
	(arc
		(start 405.742648 -149.660356)
		(mid 405.742711 -149.292119)
		(end 405.374348 -149.291802)
		(width 0.1143)
		(layer "In9.Cu")
		(net "SATA6G_PCH_PCIE_UP_SATA_RXN<6>")
	)
	(arc
		(start 403.89683 -144.264126)
		(mid 403.83776 -144.12152)
		(end 403.695154 -144.06245)
		(width 0.1143)
		(layer "In9.Cu")
		(net "SATA6G_PCH_PCIE_UP_SATA_RXN<6>")
	)
	(arc
		(start 405.504142 -150.741126)
		(mid 405.329314 -150.318693)
		(end 405.504904 -149.896576)
		(width 0.1143)
		(layer "In9.Cu")
		(net "SATA6G_PCH_PCIE_UP_SATA_RXN<6>")
	)
	(arc
		(start 405.896318 -136.364726)
		(mid 405.635968 -136.104376)
		(end 405.375618 -136.364726)
		(width 0.1143)
		(layer "In9.Cu")
		(net "SATA6G_PCH_PCIE_UP_SATA_RXN<6>")
	)
	(arc
		(start 385.686046 -130.626866)
		(mid 385.64616 -130.425785)
		(end 385.532376 -130.255264)
		(width 0.1143)
		(layer "In9.Cu")
		(net "SATA6G_PCH_PCIE_UP_SATA_RXN<6>")
	)
	(arc
		(start 388.927848 -120.734074)
		(mid 389.092935 -120.669563)
		(end 389.269732 -120.656858)
		(width 0.0889)
		(layer "In9.Cu")
		(net "SATA6G_PCH_PCIE_UP_SATA_RXN<6>")
	)
	(arc
		(start 385.1656 -122.082814)
		(mid 385.249881 -121.799597)
		(end 385.460748 -121.592594)
		(width 0.0889)
		(layer "In9.Cu")
		(net "SATA6G_PCH_PCIE_UP_SATA_RXN<6>")
	)
	(arc
		(start 386.946648 -120.734074)
		(mid 387.24205 -120.654943)
		(end 387.537452 -120.734074)
		(width 0.0889)
		(layer "In9.Cu")
		(net "SATA6G_PCH_PCIE_UP_SATA_RXN<6>")
	)
	(arc
		(start 389.610346 -135.695944)
		(mid 389.45474 -135.664974)
		(end 389.322818 -135.576818)
		(width 0.1143)
		(layer "In9.Cu")
		(net "SATA6G_PCH_PCIE_UP_SATA_RXN<6>")
	)
	(arc
		(start 403.46503 -133.091682)
		(mid 400.58041 -135.019124)
		(end 397.177768 -135.695944)
		(width 0.1143)
		(layer "In9.Cu")
		(net "SATA6G_PCH_PCIE_UP_SATA_RXN<6>")
	)
	(arc
		(start 404.048976 -134.837932)
		(mid 404.041033 -134.829621)
		(end 404.032974 -134.821422)
		(width 0.1143)
		(layer "In9.Cu")
		(net "SATA6G_PCH_PCIE_UP_SATA_RXN<6>")
	)
	(arc
		(start 404.254716 -147.2946)
		(mid 404.213468 -147.088266)
		(end 404.096474 -146.913346)
		(width 0.1143)
		(layer "In9.Cu")
		(net "SATA6G_PCH_PCIE_UP_SATA_RXN<6>")
	)
	(arc
		(start 407.065734 -151.244808)
		(mid 407.028675 -151.220046)
		(end 406.984962 -151.21128)
		(width 0.1143)
		(layer "In9.Cu")
		(net "SATA6G_PCH_PCIE_UP_SATA_RXN<6>")
	)
	(arc
		(start 384.175 -123.807728)
		(mid 384.257521 -123.520041)
		(end 384.470402 -123.309634)
		(width 0.0889)
		(layer "In9.Cu")
		(net "SATA6G_PCH_PCIE_UP_SATA_RXN<6>")
	)
	(arc
		(start 386.546852 -120.734074)
		(mid 386.74675 -120.787573)
		(end 386.946648 -120.734074)
		(width 0.0889)
		(layer "In9.Cu")
		(net "SATA6G_PCH_PCIE_UP_SATA_RXN<6>")
	)
	(arc
		(start 404.270718 -135.3947)
		(mid 404.213161 -135.095079)
		(end 404.048976 -134.837932)
		(width 0.1143)
		(layer "In9.Cu")
		(net "SATA6G_PCH_PCIE_UP_SATA_RXN<6>")
	)
	(arc
		(start 403.89683 -142.29715)
		(mid 403.961658 -141.970679)
		(end 404.146512 -141.6939)
		(width 0.1143)
		(layer "In9.Cu")
		(net "SATA6G_PCH_PCIE_UP_SATA_RXN<6>")
	)
	(arc
		(start 384.470148 -123.309634)
		(mid 384.613952 -123.167951)
		(end 384.6703 -122.9741)
		(width 0.0889)
		(layer "In9.Cu")
		(net "SATA6G_PCH_PCIE_UP_SATA_RXN<6>")
	)
	(arc
		(start 405.67991 -140.160502)
		(mid 405.840082 -139.920787)
		(end 405.896318 -139.638024)
		(width 0.1143)
		(layer "In9.Cu")
		(net "SATA6G_PCH_PCIE_UP_SATA_RXN<6>")
	)
	(arc
		(start 404.209504 -133.082538)
		(mid 404.209504 -132.714746)
		(end 403.841712 -132.714746)
		(width 0.1143)
		(layer "In9.Cu")
		(net "SATA6G_PCH_PCIE_UP_SATA_RXN<6>")
	)
	(arc
		(start 384.6703 -122.941334)
		(mid 384.754581 -122.658117)
		(end 384.965448 -122.451114)
		(width 0.0889)
		(layer "In9.Cu")
		(net "SATA6G_PCH_PCIE_UP_SATA_RXN<6>")
	)
	(arc
		(start 385.29006 -130.012948)
		(mid 385.153876 -129.808995)
		(end 385.106164 -129.568448)
		(width 0.1143)
		(layer "In9.Cu")
		(net "SATA6G_PCH_PCIE_UP_SATA_RXN<6>")
	)
	(arc
		(start 404.373842 -149.508464)
		(mid 404.285546 -149.37618)
		(end 404.254716 -149.220174)
		(width 0.1143)
		(layer "In9.Cu")
		(net "SATA6G_PCH_PCIE_UP_SATA_RXN<6>")
	)
	(arc
		(start 403.695154 -145.56105)
		(mid 403.174454 -145.04035)
		(end 403.695154 -144.51965)
		(width 0.1143)
		(layer "In9.Cu")
		(net "SATA6G_PCH_PCIE_UP_SATA_RXN<6>")
	)
	(arc
		(start 385.460748 -121.592594)
		(mid 385.604552 -121.450911)
		(end 385.6609 -121.25706)
		(width 0.0889)
		(layer "In9.Cu")
		(net "SATA6G_PCH_PCIE_UP_SATA_RXN<6>")
	)
	(arc
		(start 385.156964 -125.926342)
		(mid 385.150162 -125.892238)
		(end 385.130802 -125.86335)
		(width 0.0889)
		(layer "In9.Cu")
		(net "SATA6G_PCH_PCIE_UP_SATA_RXN<6>")
	)
	(arc
		(start 406.142698 -151.21128)
		(mid 405.987244 -151.180394)
		(end 405.855424 -151.092408)
		(width 0.1143)
		(layer "In9.Cu")
		(net "SATA6G_PCH_PCIE_UP_SATA_RXN<6>")
	)
	(arc
		(start 385.932172 -132.185918)
		(mid 385.750226 -131.913284)
		(end 385.6863 -131.591812)
		(width 0.1143)
		(layer "In9.Cu")
		(net "SATA6G_PCH_PCIE_UP_SATA_RXN<6>")
	)
	(arc
		(start 384.298444 -125.030992)
		(mid 384.207033 -124.894047)
		(end 384.175 -124.732542)
		(width 0.0889)
		(layer "In9.Cu")
		(net "SATA6G_PCH_PCIE_UP_SATA_RXN<6>")
	)
	(arc
		(start 405.07412 -149.591776)
		(mid 404.765674 -149.719427)
		(end 404.457154 -149.591776)
		(width 0.1143)
		(layer "In9.Cu")
		(net "SATA6G_PCH_PCIE_UP_SATA_RXN<6>")
	)
	(arc
		(start 405.375618 -139.31265)
		(mid 405.302638 -139.681136)
		(end 405.094186 -139.993624)
		(width 0.1143)
		(layer "In9.Cu")
		(net "SATA6G_PCH_PCIE_UP_SATA_RXN<6>")
	)
	(arc
		(start 404.14194 -140.9446)
		(mid 403.743922 -141.10939)
		(end 403.345904 -140.9446)
		(width 0.1143)
		(layer "In9.Cu")
		(net "SATA6G_PCH_PCIE_UP_SATA_RXN<6>")
	)
	(arc
		(start 404.072344 -139.452096)
		(mid 404.219147 -139.232295)
		(end 404.270718 -138.973052)
		(width 0.1143)
		(layer "In9.Cu")
		(net "SATA6G_PCH_PCIE_UP_SATA_RXN<6>")
	)
	(arc
		(start 389.269732 -120.656858)
		(mid 389.537256 -120.59395)
		(end 389.71855 -120.387364)
		(width 0.0889)
		(layer "In9.Cu")
		(net "SATA6G_PCH_PCIE_UP_SATA_RXN<6>")
	)
	(arc
		(start 403.75967 -143.02105)
		(mid 403.856657 -142.980877)
		(end 403.89683 -142.88389)
		(width 0.1143)
		(layer "In9.Cu")
		(net "SATA6G_PCH_PCIE_UP_SATA_RXN<6>")
	)
	(arc
		(start 403.827742 -144.51965)
		(mid 403.876595 -144.499415)
		(end 403.89683 -144.450562)
		(width 0.1143)
		(layer "In9.Cu")
		(net "SATA6G_PCH_PCIE_UP_SATA_RXN<6>")
	)
	(arc
		(start 384.965448 -122.451114)
		(mid 385.109252 -122.309431)
		(end 385.1656 -122.11558)
		(width 0.0889)
		(layer "In9.Cu")
		(net "SATA6G_PCH_PCIE_UP_SATA_RXN<6>")
	)
	(arc
		(start 385.6609 -121.224294)
		(mid 385.965343 -120.728817)
		(end 386.546852 -120.734074)
		(width 0.0889)
		(layer "In9.Cu")
		(net "SATA6G_PCH_PCIE_UP_SATA_RXN<6>")
	)
	(arc
		(start 387.537452 -120.734074)
		(mid 387.73735 -120.787573)
		(end 387.937248 -120.734074)
		(width 0.0889)
		(layer "In9.Cu")
		(net "SATA6G_PCH_PCIE_UP_SATA_RXN<6>")
	)
	(segment
		(start 386.74675 -121.01576)
		(end 387.24205 -121.245884)
		(width 0.1143)
		(layer "F.Cu")
		(net "SATA6G_PCH_PCIE_UP_SATA_RXN<5>")
	)
	(via
		(at 409.790646 -153.2255)
		(size 0.508)
		(drill 0.254)
		(layers "F.Cu" "B.Cu")
		(net "SATA6G_PCH_PCIE_UP_SATA_RXN<5>")
	)
	(via
		(at 387.24205 -121.245884)
		(size 0.508)
		(drill 0.254)
		(layers "F.Cu" "B.Cu")
		(net "SATA6G_PCH_PCIE_UP_SATA_RXN<5>")
	)
	(segment
		(start 410.147516 -152.85212)
		(end 410.173678 -152.871678)
		(width 0.1143)
		(layer "B.Cu")
		(net "SATA6G_PCH_PCIE_UP_SATA_RXN<5>")
	)
	(segment
		(start 410.173678 -152.871678)
		(end 410.464 -153.162)
		(width 0.1143)
		(layer "B.Cu")
		(net "SATA6G_PCH_PCIE_UP_SATA_RXN<5>")
	)
	(segment
		(start 409.790646 -153.2255)
		(end 409.790646 -152.95245)
		(width 0.1143)
		(layer "B.Cu")
		(net "SATA6G_PCH_PCIE_UP_SATA_RXN<5>")
	)
	(segment
		(start 409.904946 -152.83815)
		(end 410.092652 -152.83815)
		(width 0.1143)
		(layer "B.Cu")
		(net "SATA6G_PCH_PCIE_UP_SATA_RXN<5>")
	)
	(arc
		(start 409.790646 -152.95245)
		(mid 409.824124 -152.871628)
		(end 409.904946 -152.83815)
		(width 0.1143)
		(layer "B.Cu")
		(net "SATA6G_PCH_PCIE_UP_SATA_RXN<5>")
	)
	(arc
		(start 410.092652 -152.83815)
		(mid 410.120961 -152.841695)
		(end 410.147516 -152.85212)
		(width 0.1143)
		(layer "B.Cu")
		(net "SATA6G_PCH_PCIE_UP_SATA_RXN<5>")
	)
	(segment
		(start 403.713442 -131.822444)
		(end 406.758902 -131.822444)
		(width 0.1143)
		(layer "In9.Cu")
		(net "SATA6G_PCH_PCIE_UP_SATA_RXN<5>")
	)
	(segment
		(start 409.462224 -152.897078)
		(end 409.790646 -153.2255)
		(width 0.1143)
		(layer "In9.Cu")
		(net "SATA6G_PCH_PCIE_UP_SATA_RXN<5>")
	)
	(segment
		(start 385.901184 -126.81331)
		(end 385.901184 -126.835408)
		(width 0.0889)
		(layer "In9.Cu")
		(net "SATA6G_PCH_PCIE_UP_SATA_RXN<5>")
	)
	(segment
		(start 408.522424 -139.126214)
		(end 408.522424 -139.368784)
		(width 0.1143)
		(layer "In9.Cu")
		(net "SATA6G_PCH_PCIE_UP_SATA_RXN<5>")
	)
	(segment
		(start 406.656286 -148.822156)
		(end 407.302208 -148.822156)
		(width 0.1143)
		(layer "In9.Cu")
		(net "SATA6G_PCH_PCIE_UP_SATA_RXN<5>")
	)
	(segment
		(start 385.6609 -122.941334)
		(end 385.6609 -122.9741)
		(width 0.0889)
		(layer "In9.Cu")
		(net "SATA6G_PCH_PCIE_UP_SATA_RXN<5>")
	)
	(segment
		(start 405.044148 -145.865596)
		(end 405.219408 -146.040856)
		(width 0.1143)
		(layer "In9.Cu")
		(net "SATA6G_PCH_PCIE_UP_SATA_RXN<5>")
	)
	(segment
		(start 386.1562 -122.082814)
		(end 386.1562 -122.11558)
		(width 0.0889)
		(layer "In9.Cu")
		(net "SATA6G_PCH_PCIE_UP_SATA_RXN<5>")
	)
	(segment
		(start 404.701248 -142.637256)
		(end 404.701248 -145.037048)
		(width 0.1143)
		(layer "In9.Cu")
		(net "SATA6G_PCH_PCIE_UP_SATA_RXN<5>")
	)
	(segment
		(start 390.201912 -134.7343)
		(end 397.100806 -134.7343)
		(width 0.1143)
		(layer "In9.Cu")
		(net "SATA6G_PCH_PCIE_UP_SATA_RXN<5>")
	)
	(segment
		(start 407.05659 -139.924028)
		(end 404.954232 -142.026386)
		(width 0.1143)
		(layer "In9.Cu")
		(net "SATA6G_PCH_PCIE_UP_SATA_RXN<5>")
	)
	(segment
		(start 409.074874 -138.053064)
		(end 409.323032 -138.053064)
		(width 0.1143)
		(layer "In9.Cu")
		(net "SATA6G_PCH_PCIE_UP_SATA_RXN<5>")
	)
	(segment
		(start 386.72008 -131.508246)
		(end 389.765794 -134.55396)
		(width 0.1143)
		(layer "In9.Cu")
		(net "SATA6G_PCH_PCIE_UP_SATA_RXN<5>")
	)
	(segment
		(start 408.522424 -136.97712)
		(end 408.522424 -137.500614)
		(width 0.1143)
		(layer "In9.Cu")
		(net "SATA6G_PCH_PCIE_UP_SATA_RXN<5>")
	)
	(segment
		(start 385.247642 -124.244862)
		(end 385.925822 -124.923042)
		(width 0.0889)
		(layer "In9.Cu")
		(net "SATA6G_PCH_PCIE_UP_SATA_RXN<5>")
	)
	(segment
		(start 408.207972 -135.58266)
		(end 407.90876 -135.58266)
		(width 0.1143)
		(layer "In9.Cu")
		(net "SATA6G_PCH_PCIE_UP_SATA_RXN<5>")
	)
	(segment
		(start 405.487632 -147.822412)
		(end 406.368504 -148.703284)
		(width 0.1143)
		(layer "In9.Cu")
		(net "SATA6G_PCH_PCIE_UP_SATA_RXN<5>")
	)
	(segment
		(start 385.901184 -126.835408)
		(end 385.901184 -129.158746)
		(width 0.1143)
		(layer "In9.Cu")
		(net "SATA6G_PCH_PCIE_UP_SATA_RXN<5>")
	)
	(segment
		(start 403.24532 -132.18922)
		(end 403.540468 -131.894072)
		(width 0.1143)
		(layer "In9.Cu")
		(net "SATA6G_PCH_PCIE_UP_SATA_RXN<5>")
	)
	(segment
		(start 406.896824 -136.594596)
		(end 406.896824 -138.538966)
		(width 0.1143)
		(layer "In9.Cu")
		(net "SATA6G_PCH_PCIE_UP_SATA_RXN<5>")
	)
	(segment
		(start 386.139436 -129.73431)
		(end 386.13969 -129.734564)
		(width 0.1143)
		(layer "In9.Cu")
		(net "SATA6G_PCH_PCIE_UP_SATA_RXN<5>")
	)
	(segment
		(start 407.645108 -149.893274)
		(end 408.067002 -150.314914)
		(width 0.1143)
		(layer "In9.Cu")
		(net "SATA6G_PCH_PCIE_UP_SATA_RXN<5>")
	)
	(segment
		(start 408.10053 -150.395686)
		(end 408.10053 -151.909018)
		(width 0.1143)
		(layer "In9.Cu")
		(net "SATA6G_PCH_PCIE_UP_SATA_RXN<5>")
	)
	(segment
		(start 408.285442 -152.356058)
		(end 408.635454 -152.70607)
		(width 0.1143)
		(layer "In9.Cu")
		(net "SATA6G_PCH_PCIE_UP_SATA_RXN<5>")
	)
	(segment
		(start 408.001724 -138.538966)
		(end 408.001724 -136.97712)
		(width 0.1143)
		(layer "In9.Cu")
		(net "SATA6G_PCH_PCIE_UP_SATA_RXN<5>")
	)
	(segment
		(start 409.0162 -152.86355)
		(end 409.381452 -152.86355)
		(width 0.1143)
		(layer "In9.Cu")
		(net "SATA6G_PCH_PCIE_UP_SATA_RXN<5>")
	)
	(segment
		(start 385.951984 -126.76251)
		(end 385.901184 -126.81331)
		(width 0.0889)
		(layer "In9.Cu")
		(net "SATA6G_PCH_PCIE_UP_SATA_RXN<5>")
	)
	(segment
		(start 385.1656 -123.807728)
		(end 385.1656 -124.046996)
		(width 0.0889)
		(layer "In9.Cu")
		(net "SATA6G_PCH_PCIE_UP_SATA_RXN<5>")
	)
	(segment
		(start 407.526236 -149.046184)
		(end 407.526236 -149.606)
		(width 0.1143)
		(layer "In9.Cu")
		(net "SATA6G_PCH_PCIE_UP_SATA_RXN<5>")
	)
	(segment
		(start 408.149044 -139.742164)
		(end 407.496264 -139.742164)
		(width 0.1143)
		(layer "In9.Cu")
		(net "SATA6G_PCH_PCIE_UP_SATA_RXN<5>")
	)
	(segment
		(start 386.485638 -130.568954)
		(end 386.485638 -130.941826)
		(width 0.1143)
		(layer "In9.Cu")
		(net "SATA6G_PCH_PCIE_UP_SATA_RXN<5>")
	)
	(segment
		(start 409.323032 -138.573764)
		(end 409.074874 -138.573764)
		(width 0.1143)
		(layer "In9.Cu")
		(net "SATA6G_PCH_PCIE_UP_SATA_RXN<5>")
	)
	(segment
		(start 385.951984 -124.986034)
		(end 385.951984 -126.76251)
		(width 0.0889)
		(layer "In9.Cu")
		(net "SATA6G_PCH_PCIE_UP_SATA_RXN<5>")
	)
	(segment
		(start 405.359616 -146.378676)
		(end 405.359616 -147.512532)
		(width 0.1143)
		(layer "In9.Cu")
		(net "SATA6G_PCH_PCIE_UP_SATA_RXN<5>")
	)
	(segment
		(start 408.522424 -133.585966)
		(end 408.522424 -135.268462)
		(width 0.1143)
		(layer "In9.Cu")
		(net "SATA6G_PCH_PCIE_UP_SATA_RXN<5>")
	)
	(arc
		(start 409.074874 -138.573764)
		(mid 408.684233 -138.735573)
		(end 408.522424 -139.126214)
		(width 0.1143)
		(layer "In9.Cu")
		(net "SATA6G_PCH_PCIE_UP_SATA_RXN<5>")
	)
	(arc
		(start 397.100806 -134.7343)
		(mid 400.426184 -134.072859)
		(end 403.24532 -132.18922)
		(width 0.1143)
		(layer "In9.Cu")
		(net "SATA6G_PCH_PCIE_UP_SATA_RXN<5>")
	)
	(arc
		(start 409.323032 -138.053064)
		(mid 409.583382 -138.313414)
		(end 409.323032 -138.573764)
		(width 0.1143)
		(layer "In9.Cu")
		(net "SATA6G_PCH_PCIE_UP_SATA_RXN<5>")
	)
	(arc
		(start 408.635454 -152.70607)
		(mid 408.810157 -152.82271)
		(end 409.0162 -152.86355)
		(width 0.1143)
		(layer "In9.Cu")
		(net "SATA6G_PCH_PCIE_UP_SATA_RXN<5>")
	)
	(arc
		(start 406.758902 -131.822444)
		(mid 408.0059 -132.338968)
		(end 408.522424 -133.585966)
		(width 0.1143)
		(layer "In9.Cu")
		(net "SATA6G_PCH_PCIE_UP_SATA_RXN<5>")
	)
	(arc
		(start 408.522424 -139.368784)
		(mid 408.413064 -139.632804)
		(end 408.149044 -139.742164)
		(width 0.1143)
		(layer "In9.Cu")
		(net "SATA6G_PCH_PCIE_UP_SATA_RXN<5>")
	)
	(arc
		(start 385.956048 -122.451114)
		(mid 385.745184 -122.658118)
		(end 385.6609 -122.941334)
		(width 0.0889)
		(layer "In9.Cu")
		(net "SATA6G_PCH_PCIE_UP_SATA_RXN<5>")
	)
	(arc
		(start 408.522424 -135.268462)
		(mid 408.430308 -135.490723)
		(end 408.207972 -135.58266)
		(width 0.1143)
		(layer "In9.Cu")
		(net "SATA6G_PCH_PCIE_UP_SATA_RXN<5>")
	)
	(arc
		(start 386.714238 -121.514108)
		(mid 386.324958 -121.690269)
		(end 386.1562 -122.082814)
		(width 0.0889)
		(layer "In9.Cu")
		(net "SATA6G_PCH_PCIE_UP_SATA_RXN<5>")
	)
	(arc
		(start 407.526236 -149.606)
		(mid 407.557122 -149.761454)
		(end 407.645108 -149.893274)
		(width 0.1143)
		(layer "In9.Cu")
		(net "SATA6G_PCH_PCIE_UP_SATA_RXN<5>")
	)
	(arc
		(start 408.10053 -151.909018)
		(mid 408.148552 -152.150909)
		(end 408.285442 -152.356058)
		(width 0.1143)
		(layer "In9.Cu")
		(net "SATA6G_PCH_PCIE_UP_SATA_RXN<5>")
	)
	(arc
		(start 407.496264 -139.742164)
		(mid 407.258358 -139.789393)
		(end 407.05659 -139.924028)
		(width 0.1143)
		(layer "In9.Cu")
		(net "SATA6G_PCH_PCIE_UP_SATA_RXN<5>")
	)
	(arc
		(start 386.13969 -129.734564)
		(mid 386.39562 -130.117356)
		(end 386.485638 -130.568954)
		(width 0.1143)
		(layer "In9.Cu")
		(net "SATA6G_PCH_PCIE_UP_SATA_RXN<5>")
	)
	(arc
		(start 386.485638 -130.941826)
		(mid 386.54657 -131.248331)
		(end 386.72008 -131.508246)
		(width 0.1143)
		(layer "In9.Cu")
		(net "SATA6G_PCH_PCIE_UP_SATA_RXN<5>")
	)
	(arc
		(start 408.001724 -136.97712)
		(mid 408.262074 -136.71677)
		(end 408.522424 -136.97712)
		(width 0.1143)
		(layer "In9.Cu")
		(net "SATA6G_PCH_PCIE_UP_SATA_RXN<5>")
	)
	(arc
		(start 385.901184 -129.158746)
		(mid 385.963102 -129.470208)
		(end 386.139436 -129.73431)
		(width 0.1143)
		(layer "In9.Cu")
		(net "SATA6G_PCH_PCIE_UP_SATA_RXN<5>")
	)
	(arc
		(start 409.381452 -152.86355)
		(mid 409.425193 -152.872251)
		(end 409.462224 -152.897078)
		(width 0.1143)
		(layer "In9.Cu")
		(net "SATA6G_PCH_PCIE_UP_SATA_RXN<5>")
	)
	(arc
		(start 385.1656 -123.799854)
		(mid 385.165586 -123.803791)
		(end 385.1656 -123.807728)
		(width 0.0889)
		(layer "In9.Cu")
		(net "SATA6G_PCH_PCIE_UP_SATA_RXN<5>")
	)
	(arc
		(start 387.24205 -121.245884)
		(mid 387.006396 -121.4356)
		(end 386.714238 -121.514108)
		(width 0.0889)
		(layer "In9.Cu")
		(net "SATA6G_PCH_PCIE_UP_SATA_RXN<5>")
	)
	(arc
		(start 386.1562 -122.11558)
		(mid 386.09985 -122.30943)
		(end 385.956048 -122.451114)
		(width 0.0889)
		(layer "In9.Cu")
		(net "SATA6G_PCH_PCIE_UP_SATA_RXN<5>")
	)
	(arc
		(start 407.302208 -148.822156)
		(mid 407.46062 -148.887772)
		(end 407.526236 -149.046184)
		(width 0.1143)
		(layer "In9.Cu")
		(net "SATA6G_PCH_PCIE_UP_SATA_RXN<5>")
	)
	(arc
		(start 389.765794 -134.55396)
		(mid 389.965916 -134.687521)
		(end 390.201912 -134.7343)
		(width 0.1143)
		(layer "In9.Cu")
		(net "SATA6G_PCH_PCIE_UP_SATA_RXN<5>")
	)
	(arc
		(start 404.701248 -145.037048)
		(mid 404.790291 -145.485438)
		(end 405.044148 -145.865596)
		(width 0.1143)
		(layer "In9.Cu")
		(net "SATA6G_PCH_PCIE_UP_SATA_RXN<5>")
	)
	(arc
		(start 405.359616 -147.512532)
		(mid 405.392851 -147.680175)
		(end 405.487632 -147.822412)
		(width 0.1143)
		(layer "In9.Cu")
		(net "SATA6G_PCH_PCIE_UP_SATA_RXN<5>")
	)
	(arc
		(start 385.6609 -122.9741)
		(mid 385.60455 -123.16795)
		(end 385.460748 -123.309634)
		(width 0.0889)
		(layer "In9.Cu")
		(net "SATA6G_PCH_PCIE_UP_SATA_RXN<5>")
	)
	(arc
		(start 406.368504 -148.703284)
		(mid 406.500569 -148.791371)
		(end 406.656286 -148.822156)
		(width 0.1143)
		(layer "In9.Cu")
		(net "SATA6G_PCH_PCIE_UP_SATA_RXN<5>")
	)
	(arc
		(start 406.896824 -138.538966)
		(mid 407.449274 -139.091162)
		(end 408.001724 -138.538966)
		(width 0.1143)
		(layer "In9.Cu")
		(net "SATA6G_PCH_PCIE_UP_SATA_RXN<5>")
	)
	(arc
		(start 407.90876 -135.58266)
		(mid 407.193213 -135.879049)
		(end 406.896824 -136.594596)
		(width 0.1143)
		(layer "In9.Cu")
		(net "SATA6G_PCH_PCIE_UP_SATA_RXN<5>")
	)
	(arc
		(start 385.460748 -123.309634)
		(mid 385.249884 -123.516638)
		(end 385.1656 -123.799854)
		(width 0.0889)
		(layer "In9.Cu")
		(net "SATA6G_PCH_PCIE_UP_SATA_RXN<5>")
	)
	(arc
		(start 408.522424 -137.500614)
		(mid 408.684233 -137.891255)
		(end 409.074874 -138.053064)
		(width 0.1143)
		(layer "In9.Cu")
		(net "SATA6G_PCH_PCIE_UP_SATA_RXN<5>")
	)
	(arc
		(start 385.925822 -124.923042)
		(mid 385.945187 -124.951929)
		(end 385.951984 -124.986034)
		(width 0.0889)
		(layer "In9.Cu")
		(net "SATA6G_PCH_PCIE_UP_SATA_RXN<5>")
	)
	(arc
		(start 405.219408 -146.040856)
		(mid 405.323054 -146.195834)
		(end 405.359616 -146.378676)
		(width 0.1143)
		(layer "In9.Cu")
		(net "SATA6G_PCH_PCIE_UP_SATA_RXN<5>")
	)
	(arc
		(start 404.954232 -142.026386)
		(mid 404.767016 -142.30667)
		(end 404.701248 -142.637256)
		(width 0.1143)
		(layer "In9.Cu")
		(net "SATA6G_PCH_PCIE_UP_SATA_RXN<5>")
	)
	(arc
		(start 403.540468 -131.894072)
		(mid 403.619843 -131.841098)
		(end 403.713442 -131.822444)
		(width 0.1143)
		(layer "In9.Cu")
		(net "SATA6G_PCH_PCIE_UP_SATA_RXN<5>")
	)
	(arc
		(start 385.1656 -124.046996)
		(mid 385.186922 -124.154098)
		(end 385.247642 -124.244862)
		(width 0.0889)
		(layer "In9.Cu")
		(net "SATA6G_PCH_PCIE_UP_SATA_RXN<5>")
	)
	(arc
		(start 408.067002 -150.314914)
		(mid 408.091847 -150.351957)
		(end 408.10053 -150.395686)
		(width 0.1143)
		(layer "In9.Cu")
		(net "SATA6G_PCH_PCIE_UP_SATA_RXN<5>")
	)
	(segment
		(start 385.75615 -122.7328)
		(end 386.25145 -122.962924)
		(width 0.1143)
		(layer "F.Cu")
		(net "SATA6G_PCH_PCIE_UP_SATA_RXN<4>")
	)
	(via
		(at 409.579826 -149.861016)
		(size 0.508)
		(drill 0.254)
		(layers "F.Cu" "B.Cu")
		(net "SATA6G_PCH_PCIE_UP_SATA_RXN<4>")
	)
	(via
		(at 386.25145 -122.962924)
		(size 0.508)
		(drill 0.254)
		(layers "F.Cu" "B.Cu")
		(net "SATA6G_PCH_PCIE_UP_SATA_RXN<4>")
	)
	(segment
		(start 409.579826 -149.62759)
		(end 409.579826 -149.861016)
		(width 0.1143)
		(layer "B.Cu")
		(net "SATA6G_PCH_PCIE_UP_SATA_RXN<4>")
	)
	(segment
		(start 410.464 -149.95652)
		(end 410.02077 -149.51329)
		(width 0.1143)
		(layer "B.Cu")
		(net "SATA6G_PCH_PCIE_UP_SATA_RXN<4>")
	)
	(segment
		(start 410.02077 -149.51329)
		(end 409.694126 -149.51329)
		(width 0.1143)
		(layer "B.Cu")
		(net "SATA6G_PCH_PCIE_UP_SATA_RXN<4>")
	)
	(arc
		(start 409.694126 -149.51329)
		(mid 409.613304 -149.546768)
		(end 409.579826 -149.62759)
		(width 0.1143)
		(layer "B.Cu")
		(net "SATA6G_PCH_PCIE_UP_SATA_RXN<4>")
	)
	(segment
		(start 411.48889 -137.697718)
		(end 411.378908 -137.697718)
		(width 0.1143)
		(layer "In9.Cu")
		(net "SATA6G_PCH_PCIE_UP_SATA_RXN<4>")
	)
	(segment
		(start 409.311094 -133.574028)
		(end 409.311094 -134.998968)
		(width 0.1143)
		(layer "In9.Cu")
		(net "SATA6G_PCH_PCIE_UP_SATA_RXN<4>")
	)
	(segment
		(start 403.607016 -130.977132)
		(end 406.714198 -130.977132)
		(width 0.1143)
		(layer "In9.Cu")
		(net "SATA6G_PCH_PCIE_UP_SATA_RXN<4>")
	)
	(segment
		(start 387.02615 -129.43205)
		(end 387.042406 -129.448306)
		(width 0.1143)
		(layer "In9.Cu")
		(net "SATA6G_PCH_PCIE_UP_SATA_RXN<4>")
	)
	(segment
		(start 409.160472 -149.508464)
		(end 409.437078 -149.508464)
		(width 0.1143)
		(layer "In9.Cu")
		(net "SATA6G_PCH_PCIE_UP_SATA_RXN<4>")
	)
	(segment
		(start 408.562302 -146.355054)
		(end 408.562302 -146.360388)
		(width 0.1143)
		(layer "In9.Cu")
		(net "SATA6G_PCH_PCIE_UP_SATA_RXN<4>")
	)
	(segment
		(start 386.806694 -124.41047)
		(end 386.806694 -124.79782)
		(width 0.0889)
		(layer "In9.Cu")
		(net "SATA6G_PCH_PCIE_UP_SATA_RXN<4>")
	)
	(segment
		(start 386.755894 -124.84862)
		(end 386.755894 -124.870718)
		(width 0.0889)
		(layer "In9.Cu")
		(net "SATA6G_PCH_PCIE_UP_SATA_RXN<4>")
	)
	(segment
		(start 407.3906 -141.590522)
		(end 407.3906 -144.7292)
		(width 0.1143)
		(layer "In9.Cu")
		(net "SATA6G_PCH_PCIE_UP_SATA_RXN<4>")
	)
	(segment
		(start 409.98394 -140.585698)
		(end 408.395424 -140.585698)
		(width 0.1143)
		(layer "In9.Cu")
		(net "SATA6G_PCH_PCIE_UP_SATA_RXN<4>")
	)
	(segment
		(start 386.755894 -124.870718)
		(end 386.755894 -128.779524)
		(width 0.1143)
		(layer "In9.Cu")
		(net "SATA6G_PCH_PCIE_UP_SATA_RXN<4>")
	)
	(segment
		(start 408.562302 -148.229828)
		(end 408.562302 -148.910294)
		(width 0.1143)
		(layer "In9.Cu")
		(net "SATA6G_PCH_PCIE_UP_SATA_RXN<4>")
	)
	(segment
		(start 409.579826 -149.651212)
		(end 409.579826 -149.861016)
		(width 0.1143)
		(layer "In9.Cu")
		(net "SATA6G_PCH_PCIE_UP_SATA_RXN<4>")
	)
	(segment
		(start 402.662136 -131.62915)
		(end 403.107144 -131.184142)
		(width 0.1143)
		(layer "In9.Cu")
		(net "SATA6G_PCH_PCIE_UP_SATA_RXN<4>")
	)
	(segment
		(start 407.594054 -145.220436)
		(end 408.4447 -146.071082)
		(width 0.1143)
		(layer "In9.Cu")
		(net "SATA6G_PCH_PCIE_UP_SATA_RXN<4>")
	)
	(segment
		(start 387.503416 -130.935984)
		(end 390.203436 -133.637274)
		(width 0.1143)
		(layer "In9.Cu")
		(net "SATA6G_PCH_PCIE_UP_SATA_RXN<4>")
	)
	(segment
		(start 390.490964 -133.7564)
		(end 397.526002 -133.7564)
		(width 0.1143)
		(layer "In9.Cu")
		(net "SATA6G_PCH_PCIE_UP_SATA_RXN<4>")
	)
	(segment
		(start 410.24175 -139.192254)
		(end 410.24175 -140.327888)
		(width 0.1143)
		(layer "In9.Cu")
		(net "SATA6G_PCH_PCIE_UP_SATA_RXN<4>")
	)
	(segment
		(start 410.753306 -137.95629)
		(end 410.753052 -137.956544)
		(width 0.1143)
		(layer "In9.Cu")
		(net "SATA6G_PCH_PCIE_UP_SATA_RXN<4>")
	)
	(segment
		(start 409.863544 -135.551418)
		(end 411.61589 -135.551418)
		(width 0.1143)
		(layer "In9.Cu")
		(net "SATA6G_PCH_PCIE_UP_SATA_RXN<4>")
	)
	(segment
		(start 386.648452 -123.021852)
		(end 386.654548 -123.027948)
		(width 0.0889)
		(layer "In9.Cu")
		(net "SATA6G_PCH_PCIE_UP_SATA_RXN<4>")
	)
	(segment
		(start 409.863544 -137.177018)
		(end 411.48889 -137.177018)
		(width 0.1143)
		(layer "In9.Cu")
		(net "SATA6G_PCH_PCIE_UP_SATA_RXN<4>")
	)
	(segment
		(start 409.982924 -147.574254)
		(end 409.217876 -147.574254)
		(width 0.1143)
		(layer "In9.Cu")
		(net "SATA6G_PCH_PCIE_UP_SATA_RXN<4>")
	)
	(segment
		(start 387.325362 -130.132328)
		(end 387.325362 -130.505962)
		(width 0.1143)
		(layer "In9.Cu")
		(net "SATA6G_PCH_PCIE_UP_SATA_RXN<4>")
	)
	(segment
		(start 411.61589 -136.072118)
		(end 409.863544 -136.072118)
		(width 0.1143)
		(layer "In9.Cu")
		(net "SATA6G_PCH_PCIE_UP_SATA_RXN<4>")
	)
	(segment
		(start 409.255468 -147.053554)
		(end 409.982924 -147.053554)
		(width 0.1143)
		(layer "In9.Cu")
		(net "SATA6G_PCH_PCIE_UP_SATA_RXN<4>")
	)
	(segment
		(start 386.806694 -124.79782)
		(end 386.755894 -124.84862)
		(width 0.0889)
		(layer "In9.Cu")
		(net "SATA6G_PCH_PCIE_UP_SATA_RXN<4>")
	)
	(segment
		(start 386.25145 -122.962924)
		(end 386.506212 -122.962924)
		(width 0.0889)
		(layer "In9.Cu")
		(net "SATA6G_PCH_PCIE_UP_SATA_RXN<4>")
	)
	(arc
		(start 410.753052 -137.956544)
		(mid 410.374658 -138.523606)
		(end 410.24175 -139.192254)
		(width 0.1143)
		(layer "In9.Cu")
		(net "SATA6G_PCH_PCIE_UP_SATA_RXN<4>")
	)
	(arc
		(start 397.526002 -133.7564)
		(mid 400.305618 -133.203576)
		(end 402.662136 -131.62915)
		(width 0.1143)
		(layer "In9.Cu")
		(net "SATA6G_PCH_PCIE_UP_SATA_RXN<4>")
	)
	(arc
		(start 409.311094 -134.998968)
		(mid 409.472903 -135.389609)
		(end 409.863544 -135.551418)
		(width 0.1143)
		(layer "In9.Cu")
		(net "SATA6G_PCH_PCIE_UP_SATA_RXN<4>")
	)
	(arc
		(start 409.437078 -149.508464)
		(mid 409.538016 -149.550274)
		(end 409.579826 -149.651212)
		(width 0.1143)
		(layer "In9.Cu")
		(net "SATA6G_PCH_PCIE_UP_SATA_RXN<4>")
	)
	(arc
		(start 410.24175 -140.327888)
		(mid 410.166239 -140.510187)
		(end 409.98394 -140.585698)
		(width 0.1143)
		(layer "In9.Cu")
		(net "SATA6G_PCH_PCIE_UP_SATA_RXN<4>")
	)
	(arc
		(start 386.654548 -123.027948)
		(mid 386.747256 -123.286218)
		(end 386.946648 -123.474734)
		(width 0.0889)
		(layer "In9.Cu")
		(net "SATA6G_PCH_PCIE_UP_SATA_RXN<4>")
	)
	(arc
		(start 409.217876 -147.574254)
		(mid 408.754315 -147.766267)
		(end 408.562302 -148.229828)
		(width 0.1143)
		(layer "In9.Cu")
		(net "SATA6G_PCH_PCIE_UP_SATA_RXN<4>")
	)
	(arc
		(start 411.378908 -137.697718)
		(mid 411.040377 -137.764735)
		(end 410.753306 -137.95629)
		(width 0.1143)
		(layer "In9.Cu")
		(net "SATA6G_PCH_PCIE_UP_SATA_RXN<4>")
	)
	(arc
		(start 411.61589 -135.551418)
		(mid 411.87624 -135.811768)
		(end 411.61589 -136.072118)
		(width 0.1143)
		(layer "In9.Cu")
		(net "SATA6G_PCH_PCIE_UP_SATA_RXN<4>")
	)
	(arc
		(start 409.982924 -147.053554)
		(mid 410.243274 -147.313904)
		(end 409.982924 -147.574254)
		(width 0.1143)
		(layer "In9.Cu")
		(net "SATA6G_PCH_PCIE_UP_SATA_RXN<4>")
	)
	(arc
		(start 403.107144 -131.184142)
		(mid 403.336501 -131.030953)
		(end 403.607016 -130.977132)
		(width 0.1143)
		(layer "In9.Cu")
		(net "SATA6G_PCH_PCIE_UP_SATA_RXN<4>")
	)
	(arc
		(start 408.562302 -146.360388)
		(mid 408.765326 -146.85053)
		(end 409.255468 -147.053554)
		(width 0.1143)
		(layer "In9.Cu")
		(net "SATA6G_PCH_PCIE_UP_SATA_RXN<4>")
	)
	(arc
		(start 387.042406 -129.448306)
		(mid 387.251756 -129.762237)
		(end 387.325362 -130.132328)
		(width 0.1143)
		(layer "In9.Cu")
		(net "SATA6G_PCH_PCIE_UP_SATA_RXN<4>")
	)
	(arc
		(start 390.203436 -133.637274)
		(mid 390.335355 -133.725419)
		(end 390.490964 -133.7564)
		(width 0.1143)
		(layer "In9.Cu")
		(net "SATA6G_PCH_PCIE_UP_SATA_RXN<4>")
	)
	(arc
		(start 386.946648 -123.474734)
		(mid 387.146959 -123.821444)
		(end 386.946648 -124.168154)
		(width 0.0889)
		(layer "In9.Cu")
		(net "SATA6G_PCH_PCIE_UP_SATA_RXN<4>")
	)
	(arc
		(start 386.755894 -128.779524)
		(mid 386.826137 -129.132657)
		(end 387.02615 -129.43205)
		(width 0.1143)
		(layer "In9.Cu")
		(net "SATA6G_PCH_PCIE_UP_SATA_RXN<4>")
	)
	(arc
		(start 406.714198 -130.977132)
		(mid 408.550481 -131.737745)
		(end 409.311094 -133.574028)
		(width 0.1143)
		(layer "In9.Cu")
		(net "SATA6G_PCH_PCIE_UP_SATA_RXN<4>")
	)
	(arc
		(start 407.3906 -144.7292)
		(mid 407.443412 -144.995086)
		(end 407.594054 -145.220436)
		(width 0.1143)
		(layer "In9.Cu")
		(net "SATA6G_PCH_PCIE_UP_SATA_RXN<4>")
	)
	(arc
		(start 408.4447 -146.071082)
		(mid 408.531755 -146.201369)
		(end 408.562302 -146.355054)
		(width 0.1143)
		(layer "In9.Cu")
		(net "SATA6G_PCH_PCIE_UP_SATA_RXN<4>")
	)
	(arc
		(start 387.325362 -130.505962)
		(mid 387.371634 -130.738677)
		(end 387.503416 -130.935984)
		(width 0.1143)
		(layer "In9.Cu")
		(net "SATA6G_PCH_PCIE_UP_SATA_RXN<4>")
	)
	(arc
		(start 409.863544 -136.072118)
		(mid 409.311094 -136.624568)
		(end 409.863544 -137.177018)
		(width 0.1143)
		(layer "In9.Cu")
		(net "SATA6G_PCH_PCIE_UP_SATA_RXN<4>")
	)
	(arc
		(start 386.506212 -122.962924)
		(mid 386.583196 -122.978237)
		(end 386.648452 -123.021852)
		(width 0.0889)
		(layer "In9.Cu")
		(net "SATA6G_PCH_PCIE_UP_SATA_RXN<4>")
	)
	(arc
		(start 386.946648 -124.168154)
		(mid 386.844252 -124.270575)
		(end 386.806694 -124.41047)
		(width 0.0889)
		(layer "In9.Cu")
		(net "SATA6G_PCH_PCIE_UP_SATA_RXN<4>")
	)
	(arc
		(start 411.48889 -137.177018)
		(mid 411.74924 -137.437368)
		(end 411.48889 -137.697718)
		(width 0.1143)
		(layer "In9.Cu")
		(net "SATA6G_PCH_PCIE_UP_SATA_RXN<4>")
	)
	(arc
		(start 408.395424 -140.585698)
		(mid 407.684906 -140.880004)
		(end 407.3906 -141.590522)
		(width 0.1143)
		(layer "In9.Cu")
		(net "SATA6G_PCH_PCIE_UP_SATA_RXN<4>")
	)
	(arc
		(start 408.562302 -148.910294)
		(mid 408.737502 -149.333264)
		(end 409.160472 -149.508464)
		(width 0.1143)
		(layer "In9.Cu")
		(net "SATA6G_PCH_PCIE_UP_SATA_RXN<4>")
	)
	(segment
		(start 389.22325 -121.87428)
		(end 389.649716 -122.0724)
		(width 0.1143)
		(layer "F.Cu")
		(net "SATA6G_PCH_PCIE_UP_SATA_RXN<3>")
	)
	(segment
		(start 389.649716 -122.0724)
		(end 389.71855 -122.104404)
		(width 0.1143)
		(layer "F.Cu")
		(net "SATA6G_PCH_PCIE_UP_SATA_RXN<3>")
	)
	(via
		(at 389.71855 -122.104404)
		(size 0.508)
		(drill 0.254)
		(layers "F.Cu" "B.Cu")
		(net "SATA6G_PCH_PCIE_UP_SATA_RXN<3>")
	)
	(via
		(at 419.320726 -156.0068)
		(size 0.508)
		(drill 0.254)
		(layers "F.Cu" "B.Cu")
		(net "SATA6G_PCH_PCIE_UP_SATA_RXN<3>")
	)
	(segment
		(start 419.435026 -155.50515)
		(end 420.252906 -155.50515)
		(width 0.1143)
		(layer "B.Cu")
		(net "SATA6G_PCH_PCIE_UP_SATA_RXN<3>")
	)
	(segment
		(start 419.320726 -156.0068)
		(end 419.320726 -155.61945)
		(width 0.1143)
		(layer "B.Cu")
		(net "SATA6G_PCH_PCIE_UP_SATA_RXN<3>")
	)
	(segment
		(start 420.333678 -155.538678)
		(end 420.624 -155.829)
		(width 0.1143)
		(layer "B.Cu")
		(net "SATA6G_PCH_PCIE_UP_SATA_RXN<3>")
	)
	(arc
		(start 420.252906 -155.50515)
		(mid 420.296647 -155.513851)
		(end 420.333678 -155.538678)
		(width 0.1143)
		(layer "B.Cu")
		(net "SATA6G_PCH_PCIE_UP_SATA_RXN<3>")
	)
	(arc
		(start 419.320726 -155.61945)
		(mid 419.354204 -155.538628)
		(end 419.435026 -155.50515)
		(width 0.1143)
		(layer "B.Cu")
		(net "SATA6G_PCH_PCIE_UP_SATA_RXN<3>")
	)
	(segment
		(start 394.081508 -127.28067)
		(end 394.030708 -127.22987)
		(width 0.0889)
		(layer "In9.Cu")
		(net "SATA6G_PCH_PCIE_UP_SATA_RXN<3>")
	)
	(segment
		(start 415.123884 -136.656318)
		(end 415.123884 -135.106156)
		(width 0.1143)
		(layer "In9.Cu")
		(net "SATA6G_PCH_PCIE_UP_SATA_RXN<3>")
	)
	(segment
		(start 421.567356 -142.109698)
		(end 420.864792 -142.109698)
		(width 0.1143)
		(layer "In9.Cu")
		(net "SATA6G_PCH_PCIE_UP_SATA_RXN<3>")
	)
	(segment
		(start 422.401492 -155.194508)
		(end 422.5798 -155.0162)
		(width 0.1143)
		(layer "In9.Cu")
		(net "SATA6G_PCH_PCIE_UP_SATA_RXN<3>")
	)
	(segment
		(start 394.081508 -127.302768)
		(end 394.081508 -127.28067)
		(width 0.0889)
		(layer "In9.Cu")
		(net "SATA6G_PCH_PCIE_UP_SATA_RXN<3>")
	)
	(segment
		(start 422.60647 -152.234646)
		(end 421.517572 -151.145748)
		(width 0.1143)
		(layer "In9.Cu")
		(net "SATA6G_PCH_PCIE_UP_SATA_RXN<3>")
	)
	(segment
		(start 411.738572 -128.0668)
		(end 402.378926 -128.0668)
		(width 0.1143)
		(layer "In9.Cu")
		(net "SATA6G_PCH_PCIE_UP_SATA_RXN<3>")
	)
	(segment
		(start 397.28394 -130.880866)
		(end 394.73886 -130.880866)
		(width 0.1143)
		(layer "In9.Cu")
		(net "SATA6G_PCH_PCIE_UP_SATA_RXN<3>")
	)
	(segment
		(start 389.380476 -122.104404)
		(end 389.71855 -122.104404)
		(width 0.0889)
		(layer "In9.Cu")
		(net "SATA6G_PCH_PCIE_UP_SATA_RXN<3>")
	)
	(segment
		(start 394.081762 -130.22326)
		(end 394.081508 -130.223514)
		(width 0.1143)
		(layer "In9.Cu")
		(net "SATA6G_PCH_PCIE_UP_SATA_RXN<3>")
	)
	(segment
		(start 402.054822 -128.200912)
		(end 400.85391 -129.401824)
		(width 0.1143)
		(layer "In9.Cu")
		(net "SATA6G_PCH_PCIE_UP_SATA_RXN<3>")
	)
	(segment
		(start 392.369802 -126.059946)
		(end 391.592562 -125.282706)
		(width 0.0889)
		(layer "In9.Cu")
		(net "SATA6G_PCH_PCIE_UP_SATA_RXN<3>")
	)
	(segment
		(start 394.081508 -130.223514)
		(end 394.081508 -127.302768)
		(width 0.1143)
		(layer "In9.Cu")
		(net "SATA6G_PCH_PCIE_UP_SATA_RXN<3>")
	)
	(segment
		(start 420.29507 -141.873732)
		(end 415.157412 -136.737344)
		(width 0.1143)
		(layer "In9.Cu")
		(net "SATA6G_PCH_PCIE_UP_SATA_RXN<3>")
	)
	(segment
		(start 419.320726 -156.0068)
		(end 419.320726 -155.64485)
		(width 0.1143)
		(layer "In9.Cu")
		(net "SATA6G_PCH_PCIE_UP_SATA_RXN<3>")
	)
	(segment
		(start 423.2021 -145.085308)
		(end 423.2021 -143.795242)
		(width 0.1143)
		(layer "In9.Cu")
		(net "SATA6G_PCH_PCIE_UP_SATA_RXN<3>")
	)
	(segment
		(start 415.3662 -134.467854)
		(end 415.3662 -133.356858)
		(width 0.1143)
		(layer "In9.Cu")
		(net "SATA6G_PCH_PCIE_UP_SATA_RXN<3>")
	)
	(segment
		(start 393.440412 -126.086108)
		(end 392.432286 -126.086108)
		(width 0.0889)
		(layer "In9.Cu")
		(net "SATA6G_PCH_PCIE_UP_SATA_RXN<3>")
	)
	(segment
		(start 422.973246 -143.243046)
		(end 422.972992 -143.243046)
		(width 0.1143)
		(layer "In9.Cu")
		(net "SATA6G_PCH_PCIE_UP_SATA_RXN<3>")
	)
	(segment
		(start 412.838646 -130.47472)
		(end 412.839662 -129.208022)
		(width 0.1143)
		(layer "In9.Cu")
		(net "SATA6G_PCH_PCIE_UP_SATA_RXN<3>")
	)
	(segment
		(start 421.788082 -146.867372)
		(end 422.94175 -145.713704)
		(width 0.1143)
		(layer "In9.Cu")
		(net "SATA6G_PCH_PCIE_UP_SATA_RXN<3>")
	)
	(segment
		(start 422.972992 -143.243046)
		(end 422.032684 -142.302738)
		(width 0.1143)
		(layer "In9.Cu")
		(net "SATA6G_PCH_PCIE_UP_SATA_RXN<3>")
	)
	(segment
		(start 389.8138 -122.9741)
		(end 389.8138 -122.941334)
		(width 0.0889)
		(layer "In9.Cu")
		(net "SATA6G_PCH_PCIE_UP_SATA_RXN<3>")
	)
	(segment
		(start 419.435026 -155.53055)
		(end 421.590216 -155.53055)
		(width 0.1143)
		(layer "In9.Cu")
		(net "SATA6G_PCH_PCIE_UP_SATA_RXN<3>")
	)
	(segment
		(start 391.15238 -124.842524)
		(end 390.335262 -124.025406)
		(width 0.0889)
		(layer "In9.Cu")
		(net "SATA6G_PCH_PCIE_UP_SATA_RXN<3>")
	)
	(segment
		(start 389.322564 -122.162316)
		(end 389.380476 -122.104404)
		(width 0.0889)
		(layer "In9.Cu")
		(net "SATA6G_PCH_PCIE_UP_SATA_RXN<3>")
	)
	(segment
		(start 390.3091 -123.962922)
		(end 390.3091 -123.807728)
		(width 0.0889)
		(layer "In9.Cu")
		(net "SATA6G_PCH_PCIE_UP_SATA_RXN<3>")
	)
	(segment
		(start 394.030708 -127.22987)
		(end 394.030708 -126.676404)
		(width 0.0889)
		(layer "In9.Cu")
		(net "SATA6G_PCH_PCIE_UP_SATA_RXN<3>")
	)
	(segment
		(start 412.637986 -128.721866)
		(end 412.151322 -128.237488)
		(width 0.1143)
		(layer "In9.Cu")
		(net "SATA6G_PCH_PCIE_UP_SATA_RXN<3>")
	)
	(segment
		(start 421.375332 -150.80234)
		(end 421.375332 -147.862798)
		(width 0.1143)
		(layer "In9.Cu")
		(net "SATA6G_PCH_PCIE_UP_SATA_RXN<3>")
	)
	(segment
		(start 422.725342 -154.66441)
		(end 422.725342 -152.522428)
		(width 0.1143)
		(layer "In9.Cu")
		(net "SATA6G_PCH_PCIE_UP_SATA_RXN<3>")
	)
	(segment
		(start 414.772856 -131.924298)
		(end 414.2105 -131.361942)
		(width 0.1143)
		(layer "In9.Cu")
		(net "SATA6G_PCH_PCIE_UP_SATA_RXN<3>")
	)
	(segment
		(start 390.309354 -123.962668)
		(end 390.3091 -123.962922)
		(width 0.0889)
		(layer "In9.Cu")
		(net "SATA6G_PCH_PCIE_UP_SATA_RXN<3>")
	)
	(segment
		(start 393.94892 -126.478792)
		(end 393.638024 -126.167896)
		(width 0.0889)
		(layer "In9.Cu")
		(net "SATA6G_PCH_PCIE_UP_SATA_RXN<3>")
	)
	(segment
		(start 391.52957 -125.093984)
		(end 391.341102 -124.905516)
		(width 0.0889)
		(layer "In9.Cu")
		(net "SATA6G_PCH_PCIE_UP_SATA_RXN<3>")
	)
	(segment
		(start 394.658342 -130.847084)
		(end 394.11529 -130.304032)
		(width 0.1143)
		(layer "In9.Cu")
		(net "SATA6G_PCH_PCIE_UP_SATA_RXN<3>")
	)
	(arc
		(start 390.3091 -123.807728)
		(mid 390.226727 -123.520048)
		(end 390.013952 -123.309634)
		(width 0.0889)
		(layer "In9.Cu")
		(net "SATA6G_PCH_PCIE_UP_SATA_RXN<3>")
	)
	(arc
		(start 422.94175 -145.713704)
		(mid 423.134369 -145.42538)
		(end 423.2021 -145.085308)
		(width 0.1143)
		(layer "In9.Cu")
		(net "SATA6G_PCH_PCIE_UP_SATA_RXN<3>")
	)
	(arc
		(start 421.517572 -151.145748)
		(mid 421.412296 -150.988191)
		(end 421.375332 -150.80234)
		(width 0.1143)
		(layer "In9.Cu")
		(net "SATA6G_PCH_PCIE_UP_SATA_RXN<3>")
	)
	(arc
		(start 394.73886 -130.880866)
		(mid 394.695226 -130.872)
		(end 394.658342 -130.847084)
		(width 0.1143)
		(layer "In9.Cu")
		(net "SATA6G_PCH_PCIE_UP_SATA_RXN<3>")
	)
	(arc
		(start 415.15284 -135.029956)
		(mid 415.31107 -134.768472)
		(end 415.3662 -134.467854)
		(width 0.1143)
		(layer "In9.Cu")
		(net "SATA6G_PCH_PCIE_UP_SATA_RXN<3>")
	)
	(arc
		(start 400.85391 -129.401824)
		(mid 399.216037 -130.496435)
		(end 397.28394 -130.880866)
		(width 0.1143)
		(layer "In9.Cu")
		(net "SATA6G_PCH_PCIE_UP_SATA_RXN<3>")
	)
	(arc
		(start 419.320726 -155.64485)
		(mid 419.354204 -155.564028)
		(end 419.435026 -155.53055)
		(width 0.1143)
		(layer "In9.Cu")
		(net "SATA6G_PCH_PCIE_UP_SATA_RXN<3>")
	)
	(arc
		(start 392.432286 -126.086108)
		(mid 392.398456 -126.07921)
		(end 392.369802 -126.059946)
		(width 0.0889)
		(layer "In9.Cu")
		(net "SATA6G_PCH_PCIE_UP_SATA_RXN<3>")
	)
	(arc
		(start 412.151322 -128.237488)
		(mid 411.961908 -128.111115)
		(end 411.738572 -128.0668)
		(width 0.1143)
		(layer "In9.Cu")
		(net "SATA6G_PCH_PCIE_UP_SATA_RXN<3>")
	)
	(arc
		(start 422.725342 -152.522428)
		(mid 422.694485 -152.36674)
		(end 422.60647 -152.234646)
		(width 0.1143)
		(layer "In9.Cu")
		(net "SATA6G_PCH_PCIE_UP_SATA_RXN<3>")
	)
	(arc
		(start 422.5798 -155.0162)
		(mid 422.687538 -154.854769)
		(end 422.725342 -154.66441)
		(width 0.1143)
		(layer "In9.Cu")
		(net "SATA6G_PCH_PCIE_UP_SATA_RXN<3>")
	)
	(arc
		(start 391.341102 -124.905516)
		(mid 391.296871 -124.881164)
		(end 391.246868 -124.87402)
		(width 0.0889)
		(layer "In9.Cu")
		(net "SATA6G_PCH_PCIE_UP_SATA_RXN<3>")
	)
	(arc
		(start 391.246868 -124.87402)
		(mid 391.196704 -124.867014)
		(end 391.15238 -124.842524)
		(width 0.0889)
		(layer "In9.Cu")
		(net "SATA6G_PCH_PCIE_UP_SATA_RXN<3>")
	)
	(arc
		(start 415.123884 -135.106156)
		(mid 415.131363 -135.065395)
		(end 415.15284 -135.029956)
		(width 0.1143)
		(layer "In9.Cu")
		(net "SATA6G_PCH_PCIE_UP_SATA_RXN<3>")
	)
	(arc
		(start 421.590216 -155.53055)
		(mid 422.029276 -155.443216)
		(end 422.401492 -155.194508)
		(width 0.1143)
		(layer "In9.Cu")
		(net "SATA6G_PCH_PCIE_UP_SATA_RXN<3>")
	)
	(arc
		(start 415.3662 -133.356858)
		(mid 415.211949 -132.581589)
		(end 414.772856 -131.924298)
		(width 0.1143)
		(layer "In9.Cu")
		(net "SATA6G_PCH_PCIE_UP_SATA_RXN<3>")
	)
	(arc
		(start 422.032684 -142.302738)
		(mid 421.819219 -142.159949)
		(end 421.567356 -142.109698)
		(width 0.1143)
		(layer "In9.Cu")
		(net "SATA6G_PCH_PCIE_UP_SATA_RXN<3>")
	)
	(arc
		(start 389.518652 -122.451114)
		(mid 389.387456 -122.329223)
		(end 389.322564 -122.162316)
		(width 0.0889)
		(layer "In9.Cu")
		(net "SATA6G_PCH_PCIE_UP_SATA_RXN<3>")
	)
	(arc
		(start 390.013952 -123.309634)
		(mid 389.870148 -123.167951)
		(end 389.8138 -122.9741)
		(width 0.0889)
		(layer "In9.Cu")
		(net "SATA6G_PCH_PCIE_UP_SATA_RXN<3>")
	)
	(arc
		(start 391.592562 -125.282706)
		(mid 391.56821 -125.238475)
		(end 391.561066 -125.188472)
		(width 0.0889)
		(layer "In9.Cu")
		(net "SATA6G_PCH_PCIE_UP_SATA_RXN<3>")
	)
	(arc
		(start 421.375332 -147.862798)
		(mid 421.482666 -147.324023)
		(end 421.788082 -146.867372)
		(width 0.1143)
		(layer "In9.Cu")
		(net "SATA6G_PCH_PCIE_UP_SATA_RXN<3>")
	)
	(arc
		(start 394.11529 -130.304032)
		(mid 394.090474 -130.266988)
		(end 394.081762 -130.22326)
		(width 0.1143)
		(layer "In9.Cu")
		(net "SATA6G_PCH_PCIE_UP_SATA_RXN<3>")
	)
	(arc
		(start 390.335262 -124.025406)
		(mid 390.316029 -123.996622)
		(end 390.309354 -123.962668)
		(width 0.0889)
		(layer "In9.Cu")
		(net "SATA6G_PCH_PCIE_UP_SATA_RXN<3>")
	)
	(arc
		(start 420.864792 -142.109698)
		(mid 420.556469 -142.048369)
		(end 420.29507 -141.873732)
		(width 0.1143)
		(layer "In9.Cu")
		(net "SATA6G_PCH_PCIE_UP_SATA_RXN<3>")
	)
	(arc
		(start 393.638024 -126.167896)
		(mid 393.547359 -126.107315)
		(end 393.440412 -126.086108)
		(width 0.0889)
		(layer "In9.Cu")
		(net "SATA6G_PCH_PCIE_UP_SATA_RXN<3>")
	)
	(arc
		(start 414.2105 -131.361942)
		(mid 413.830927 -131.108412)
		(end 413.383222 -131.01955)
		(width 0.1143)
		(layer "In9.Cu")
		(net "SATA6G_PCH_PCIE_UP_SATA_RXN<3>")
	)
	(arc
		(start 415.157412 -136.737344)
		(mid 415.132572 -136.700169)
		(end 415.123884 -136.656318)
		(width 0.1143)
		(layer "In9.Cu")
		(net "SATA6G_PCH_PCIE_UP_SATA_RXN<3>")
	)
	(arc
		(start 391.561066 -125.188472)
		(mid 391.55406 -125.138308)
		(end 391.52957 -125.093984)
		(width 0.0889)
		(layer "In9.Cu")
		(net "SATA6G_PCH_PCIE_UP_SATA_RXN<3>")
	)
	(arc
		(start 423.2021 -143.795242)
		(mid 423.142563 -143.496401)
		(end 422.973246 -143.243046)
		(width 0.1143)
		(layer "In9.Cu")
		(net "SATA6G_PCH_PCIE_UP_SATA_RXN<3>")
	)
	(arc
		(start 389.8138 -122.941334)
		(mid 389.729519 -122.658117)
		(end 389.518652 -122.451114)
		(width 0.0889)
		(layer "In9.Cu")
		(net "SATA6G_PCH_PCIE_UP_SATA_RXN<3>")
	)
	(arc
		(start 413.383222 -131.01955)
		(mid 412.998059 -130.859958)
		(end 412.838646 -130.47472)
		(width 0.1143)
		(layer "In9.Cu")
		(net "SATA6G_PCH_PCIE_UP_SATA_RXN<3>")
	)
	(arc
		(start 412.839662 -129.208022)
		(mid 412.787388 -128.944795)
		(end 412.637986 -128.721866)
		(width 0.1143)
		(layer "In9.Cu")
		(net "SATA6G_PCH_PCIE_UP_SATA_RXN<3>")
	)
	(arc
		(start 394.030708 -126.676404)
		(mid 394.00944 -126.569482)
		(end 393.94892 -126.478792)
		(width 0.0889)
		(layer "In9.Cu")
		(net "SATA6G_PCH_PCIE_UP_SATA_RXN<3>")
	)
	(arc
		(start 402.378926 -128.0668)
		(mid 402.203585 -128.101717)
		(end 402.054822 -128.200912)
		(width 0.1143)
		(layer "In9.Cu")
		(net "SATA6G_PCH_PCIE_UP_SATA_RXN<3>")
	)
	(segment
		(start 387.73735 -122.7328)
		(end 388.23265 -122.962924)
		(width 0.1143)
		(layer "F.Cu")
		(net "SATA6G_PCH_PCIE_UP_SATA_RXN<2>")
	)
	(via
		(at 388.23265 -122.962924)
		(size 0.508)
		(drill 0.254)
		(layers "F.Cu" "B.Cu")
		(net "SATA6G_PCH_PCIE_UP_SATA_RXN<2>")
	)
	(via
		(at 419.734746 -151.8793)
		(size 0.508)
		(drill 0.254)
		(layers "F.Cu" "B.Cu")
		(net "SATA6G_PCH_PCIE_UP_SATA_RXN<2>")
	)
	(segment
		(start 419.849046 -151.457152)
		(end 420.268654 -151.457152)
		(width 0.1143)
		(layer "B.Cu")
		(net "SATA6G_PCH_PCIE_UP_SATA_RXN<2>")
	)
	(segment
		(start 419.734746 -151.8793)
		(end 419.734746 -151.571452)
		(width 0.1143)
		(layer "B.Cu")
		(net "SATA6G_PCH_PCIE_UP_SATA_RXN<2>")
	)
	(segment
		(start 420.34968 -151.49068)
		(end 420.624 -151.765)
		(width 0.1143)
		(layer "B.Cu")
		(net "SATA6G_PCH_PCIE_UP_SATA_RXN<2>")
	)
	(arc
		(start 420.268654 -151.457152)
		(mid 420.312492 -151.465872)
		(end 420.34968 -151.49068)
		(width 0.1143)
		(layer "B.Cu")
		(net "SATA6G_PCH_PCIE_UP_SATA_RXN<2>")
	)
	(arc
		(start 419.734746 -151.571452)
		(mid 419.768224 -151.49063)
		(end 419.849046 -151.457152)
		(width 0.1143)
		(layer "B.Cu")
		(net "SATA6G_PCH_PCIE_UP_SATA_RXN<2>")
	)
	(segment
		(start 413.383222 -138.693144)
		(end 413.651192 -138.693144)
		(width 0.1143)
		(layer "In9.Cu")
		(net "SATA6G_PCH_PCIE_UP_SATA_RXN<2>")
	)
	(segment
		(start 418.459666 -150.249382)
		(end 418.90696 -150.696676)
		(width 0.1143)
		(layer "In9.Cu")
		(net "SATA6G_PCH_PCIE_UP_SATA_RXN<2>")
	)
	(segment
		(start 418.940742 -150.777194)
		(end 418.940742 -151.055832)
		(width 0.1143)
		(layer "In9.Cu")
		(net "SATA6G_PCH_PCIE_UP_SATA_RXN<2>")
	)
	(segment
		(start 412.830772 -139.694412)
		(end 412.830772 -139.882626)
		(width 0.1143)
		(layer "In9.Cu")
		(net "SATA6G_PCH_PCIE_UP_SATA_RXN<2>")
	)
	(segment
		(start 388.0485 -125.133354)
		(end 388.0485 -125.400054)
		(width 0.0889)
		(layer "In9.Cu")
		(net "SATA6G_PCH_PCIE_UP_SATA_RXN<2>")
	)
	(segment
		(start 388.2771 -126.494794)
		(end 388.2771 -126.749302)
		(width 0.0889)
		(layer "In9.Cu")
		(net "SATA6G_PCH_PCIE_UP_SATA_RXN<2>")
	)
	(segment
		(start 391.158222 -132.784088)
		(end 397.51254 -132.784088)
		(width 0.1143)
		(layer "In9.Cu")
		(net "SATA6G_PCH_PCIE_UP_SATA_RXN<2>")
	)
	(segment
		(start 388.536434 -130.33121)
		(end 390.87044 -132.665216)
		(width 0.1143)
		(layer "In9.Cu")
		(net "SATA6G_PCH_PCIE_UP_SATA_RXN<2>")
	)
	(segment
		(start 412.2039 -149.770846)
		(end 412.2039 -149.7711)
		(width 0.1143)
		(layer "In9.Cu")
		(net "SATA6G_PCH_PCIE_UP_SATA_RXN<2>")
	)
	(segment
		(start 403.132036 -129.991612)
		(end 406.929844 -129.991612)
		(width 0.1143)
		(layer "In9.Cu")
		(net "SATA6G_PCH_PCIE_UP_SATA_RXN<2>")
	)
	(segment
		(start 412.830772 -135.32104)
		(end 412.830772 -138.140694)
		(width 0.1143)
		(layer "In9.Cu")
		(net "SATA6G_PCH_PCIE_UP_SATA_RXN<2>")
	)
	(segment
		(start 388.2263 -126.8222)
		(end 388.2263 -129.581656)
		(width 0.1143)
		(layer "In9.Cu")
		(net "SATA6G_PCH_PCIE_UP_SATA_RXN<2>")
	)
	(segment
		(start 418.940488 -150.777448)
		(end 418.940742 -150.777194)
		(width 0.1143)
		(layer "In9.Cu")
		(net "SATA6G_PCH_PCIE_UP_SATA_RXN<2>")
	)
	(segment
		(start 388.1374 -124.688854)
		(end 388.1374 -124.955554)
		(width 0.0889)
		(layer "In9.Cu")
		(net "SATA6G_PCH_PCIE_UP_SATA_RXN<2>")
	)
	(segment
		(start 411.526482 -134.58825)
		(end 412.097982 -134.58825)
		(width 0.1143)
		(layer "In9.Cu")
		(net "SATA6G_PCH_PCIE_UP_SATA_RXN<2>")
	)
	(segment
		(start 411.183328 -139.181078)
		(end 411.183328 -147.831302)
		(width 0.1143)
		(layer "In9.Cu")
		(net "SATA6G_PCH_PCIE_UP_SATA_RXN<2>")
	)
	(segment
		(start 388.2263 -126.800102)
		(end 388.2263 -126.8222)
		(width 0.0889)
		(layer "In9.Cu")
		(net "SATA6G_PCH_PCIE_UP_SATA_RXN<2>")
	)
	(segment
		(start 388.1374 -125.577854)
		(end 388.1374 -126.355094)
		(width 0.0889)
		(layer "In9.Cu")
		(net "SATA6G_PCH_PCIE_UP_SATA_RXN<2>")
	)
	(segment
		(start 388.2771 -126.749302)
		(end 388.2263 -126.800102)
		(width 0.0889)
		(layer "In9.Cu")
		(net "SATA6G_PCH_PCIE_UP_SATA_RXN<2>")
	)
	(segment
		(start 412.302706 -139.882626)
		(end 412.302706 -139.181078)
		(width 0.1143)
		(layer "In9.Cu")
		(net "SATA6G_PCH_PCIE_UP_SATA_RXN<2>")
	)
	(segment
		(start 388.1374 -123.799854)
		(end 388.1374 -124.066554)
		(width 0.0889)
		(layer "In9.Cu")
		(net "SATA6G_PCH_PCIE_UP_SATA_RXN<2>")
	)
	(segment
		(start 413.27705 -150.2156)
		(end 418.379148 -150.2156)
		(width 0.1143)
		(layer "In9.Cu")
		(net "SATA6G_PCH_PCIE_UP_SATA_RXN<2>")
	)
	(segment
		(start 388.0485 -124.244354)
		(end 388.0485 -124.511054)
		(width 0.0889)
		(layer "In9.Cu")
		(net "SATA6G_PCH_PCIE_UP_SATA_RXN<2>")
	)
	(segment
		(start 388.1374 -126.355094)
		(end 388.2771 -126.494794)
		(width 0.0889)
		(layer "In9.Cu")
		(net "SATA6G_PCH_PCIE_UP_SATA_RXN<2>")
	)
	(segment
		(start 402.059902 -130.900678)
		(end 402.853398 -130.107182)
		(width 0.1143)
		(layer "In9.Cu")
		(net "SATA6G_PCH_PCIE_UP_SATA_RXN<2>")
	)
	(segment
		(start 413.651192 -139.213844)
		(end 413.31134 -139.213844)
		(width 0.1143)
		(layer "In9.Cu")
		(net "SATA6G_PCH_PCIE_UP_SATA_RXN<2>")
	)
	(segment
		(start 411.83306 -149.400006)
		(end 412.2039 -149.770846)
		(width 0.1143)
		(layer "In9.Cu")
		(net "SATA6G_PCH_PCIE_UP_SATA_RXN<2>")
	)
	(segment
		(start 419.734746 -151.63165)
		(end 419.734746 -151.8793)
		(width 0.1143)
		(layer "In9.Cu")
		(net "SATA6G_PCH_PCIE_UP_SATA_RXN<2>")
	)
	(segment
		(start 419.40226 -151.51735)
		(end 419.620446 -151.51735)
		(width 0.1143)
		(layer "In9.Cu")
		(net "SATA6G_PCH_PCIE_UP_SATA_RXN<2>")
	)
	(arc
		(start 412.2039 -149.7711)
		(mid 412.696265 -150.100088)
		(end 413.27705 -150.2156)
		(width 0.1143)
		(layer "In9.Cu")
		(net "SATA6G_PCH_PCIE_UP_SATA_RXN<2>")
	)
	(arc
		(start 390.87044 -132.665216)
		(mid 391.002505 -132.753303)
		(end 391.158222 -132.784088)
		(width 0.1143)
		(layer "In9.Cu")
		(net "SATA6G_PCH_PCIE_UP_SATA_RXN<2>")
	)
	(arc
		(start 388.0485 -124.511054)
		(mid 388.062565 -124.55958)
		(end 388.09295 -124.599954)
		(width 0.0889)
		(layer "In9.Cu")
		(net "SATA6G_PCH_PCIE_UP_SATA_RXN<2>")
	)
	(arc
		(start 388.2263 -129.581656)
		(mid 388.306866 -129.987249)
		(end 388.536434 -130.33121)
		(width 0.1143)
		(layer "In9.Cu")
		(net "SATA6G_PCH_PCIE_UP_SATA_RXN<2>")
	)
	(arc
		(start 413.651192 -138.693144)
		(mid 413.911542 -138.953494)
		(end 413.651192 -139.213844)
		(width 0.1143)
		(layer "In9.Cu")
		(net "SATA6G_PCH_PCIE_UP_SATA_RXN<2>")
	)
	(arc
		(start 418.90696 -150.696676)
		(mid 418.931776 -150.73372)
		(end 418.940488 -150.777448)
		(width 0.1143)
		(layer "In9.Cu")
		(net "SATA6G_PCH_PCIE_UP_SATA_RXN<2>")
	)
	(arc
		(start 412.302706 -139.181078)
		(mid 411.743144 -138.621516)
		(end 411.183328 -139.181078)
		(width 0.1143)
		(layer "In9.Cu")
		(net "SATA6G_PCH_PCIE_UP_SATA_RXN<2>")
	)
	(arc
		(start 388.085076 -122.591068)
		(mid 388.219153 -122.563083)
		(end 388.354824 -122.581924)
		(width 0.0889)
		(layer "In9.Cu")
		(net "SATA6G_PCH_PCIE_UP_SATA_RXN<2>")
	)
	(arc
		(start 418.940742 -151.055832)
		(mid 419.075917 -151.382175)
		(end 419.40226 -151.51735)
		(width 0.1143)
		(layer "In9.Cu")
		(net "SATA6G_PCH_PCIE_UP_SATA_RXN<2>")
	)
	(arc
		(start 388.23265 -122.962924)
		(mid 387.973106 -122.850766)
		(end 388.085076 -122.591068)
		(width 0.0889)
		(layer "In9.Cu")
		(net "SATA6G_PCH_PCIE_UP_SATA_RXN<2>")
	)
	(arc
		(start 410.350716 -133.412484)
		(mid 410.69509 -134.243876)
		(end 411.526482 -134.58825)
		(width 0.1143)
		(layer "In9.Cu")
		(net "SATA6G_PCH_PCIE_UP_SATA_RXN<2>")
	)
	(arc
		(start 412.830772 -139.882626)
		(mid 412.566866 -140.146532)
		(end 412.302706 -139.882626)
		(width 0.1143)
		(layer "In9.Cu")
		(net "SATA6G_PCH_PCIE_UP_SATA_RXN<2>")
	)
	(arc
		(start 406.929844 -129.991612)
		(mid 409.348766 -130.993562)
		(end 410.350716 -133.412484)
		(width 0.1143)
		(layer "In9.Cu")
		(net "SATA6G_PCH_PCIE_UP_SATA_RXN<2>")
	)
	(arc
		(start 412.097982 -134.58825)
		(mid 412.616143 -134.802879)
		(end 412.830772 -135.32104)
		(width 0.1143)
		(layer "In9.Cu")
		(net "SATA6G_PCH_PCIE_UP_SATA_RXN<2>")
	)
	(arc
		(start 388.0485 -125.400054)
		(mid 388.062565 -125.44858)
		(end 388.09295 -125.488954)
		(width 0.0889)
		(layer "In9.Cu")
		(net "SATA6G_PCH_PCIE_UP_SATA_RXN<2>")
	)
	(arc
		(start 388.09295 -125.488954)
		(mid 388.123371 -125.52931)
		(end 388.1374 -125.577854)
		(width 0.0889)
		(layer "In9.Cu")
		(net "SATA6G_PCH_PCIE_UP_SATA_RXN<2>")
	)
	(arc
		(start 418.379148 -150.2156)
		(mid 418.422767 -150.224482)
		(end 418.459666 -150.249382)
		(width 0.1143)
		(layer "In9.Cu")
		(net "SATA6G_PCH_PCIE_UP_SATA_RXN<2>")
	)
	(arc
		(start 413.31134 -139.213844)
		(mid 412.971527 -139.354599)
		(end 412.830772 -139.694412)
		(width 0.1143)
		(layer "In9.Cu")
		(net "SATA6G_PCH_PCIE_UP_SATA_RXN<2>")
	)
	(arc
		(start 397.51254 -132.784088)
		(mid 399.973529 -132.294643)
		(end 402.059902 -130.900678)
		(width 0.1143)
		(layer "In9.Cu")
		(net "SATA6G_PCH_PCIE_UP_SATA_RXN<2>")
	)
	(arc
		(start 411.183328 -147.831302)
		(mid 411.352128 -148.6803)
		(end 411.83306 -149.400006)
		(width 0.1143)
		(layer "In9.Cu")
		(net "SATA6G_PCH_PCIE_UP_SATA_RXN<2>")
	)
	(arc
		(start 388.09295 -124.155454)
		(mid 388.062529 -124.19581)
		(end 388.0485 -124.244354)
		(width 0.0889)
		(layer "In9.Cu")
		(net "SATA6G_PCH_PCIE_UP_SATA_RXN<2>")
	)
	(arc
		(start 388.432548 -123.309634)
		(mid 388.221684 -123.516638)
		(end 388.1374 -123.799854)
		(width 0.0889)
		(layer "In9.Cu")
		(net "SATA6G_PCH_PCIE_UP_SATA_RXN<2>")
	)
	(arc
		(start 419.620446 -151.51735)
		(mid 419.701268 -151.550828)
		(end 419.734746 -151.63165)
		(width 0.1143)
		(layer "In9.Cu")
		(net "SATA6G_PCH_PCIE_UP_SATA_RXN<2>")
	)
	(arc
		(start 388.1374 -124.955554)
		(mid 388.123335 -125.00408)
		(end 388.09295 -125.044454)
		(width 0.0889)
		(layer "In9.Cu")
		(net "SATA6G_PCH_PCIE_UP_SATA_RXN<2>")
	)
	(arc
		(start 388.09295 -125.044454)
		(mid 388.062529 -125.08481)
		(end 388.0485 -125.133354)
		(width 0.0889)
		(layer "In9.Cu")
		(net "SATA6G_PCH_PCIE_UP_SATA_RXN<2>")
	)
	(arc
		(start 388.1374 -124.066554)
		(mid 388.123335 -124.11508)
		(end 388.09295 -124.155454)
		(width 0.0889)
		(layer "In9.Cu")
		(net "SATA6G_PCH_PCIE_UP_SATA_RXN<2>")
	)
	(arc
		(start 388.09295 -124.599954)
		(mid 388.123371 -124.64031)
		(end 388.1374 -124.688854)
		(width 0.0889)
		(layer "In9.Cu")
		(net "SATA6G_PCH_PCIE_UP_SATA_RXN<2>")
	)
	(arc
		(start 412.830772 -138.140694)
		(mid 412.992581 -138.531335)
		(end 413.383222 -138.693144)
		(width 0.1143)
		(layer "In9.Cu")
		(net "SATA6G_PCH_PCIE_UP_SATA_RXN<2>")
	)
	(arc
		(start 388.354824 -122.581924)
		(mid 388.630499 -122.920453)
		(end 388.432548 -123.309634)
		(width 0.0889)
		(layer "In9.Cu")
		(net "SATA6G_PCH_PCIE_UP_SATA_RXN<2>")
	)
	(arc
		(start 402.853398 -130.107182)
		(mid 402.981223 -130.021679)
		(end 403.132036 -129.991612)
		(width 0.1143)
		(layer "In9.Cu")
		(net "SATA6G_PCH_PCIE_UP_SATA_RXN<2>")
	)
	(segment
		(start 388.23265 -123.59132)
		(end 388.72795 -123.821444)
		(width 0.1143)
		(layer "F.Cu")
		(net "SATA6G_PCH_PCIE_UP_SATA_RXN<1>")
	)
	(via
		(at 388.72795 -123.821444)
		(size 0.508)
		(drill 0.254)
		(layers "F.Cu" "B.Cu")
		(net "SATA6G_PCH_PCIE_UP_SATA_RXN<1>")
	)
	(via
		(at 421.225726 -153.9875)
		(size 0.508)
		(drill 0.254)
		(layers "F.Cu" "B.Cu")
		(net "SATA6G_PCH_PCIE_UP_SATA_RXN<1>")
	)
	(segment
		(start 422.284906 -153.60015)
		(end 421.340026 -153.60015)
		(width 0.1143)
		(layer "B.Cu")
		(net "SATA6G_PCH_PCIE_UP_SATA_RXN<1>")
	)
	(segment
		(start 421.225726 -153.71445)
		(end 421.225726 -153.9875)
		(width 0.1143)
		(layer "B.Cu")
		(net "SATA6G_PCH_PCIE_UP_SATA_RXN<1>")
	)
	(segment
		(start 422.656 -153.924)
		(end 422.365678 -153.633678)
		(width 0.1143)
		(layer "B.Cu")
		(net "SATA6G_PCH_PCIE_UP_SATA_RXN<1>")
	)
	(arc
		(start 421.340026 -153.60015)
		(mid 421.259204 -153.633628)
		(end 421.225726 -153.71445)
		(width 0.1143)
		(layer "B.Cu")
		(net "SATA6G_PCH_PCIE_UP_SATA_RXN<1>")
	)
	(arc
		(start 422.365678 -153.633678)
		(mid 422.328619 -153.608916)
		(end 422.284906 -153.60015)
		(width 0.1143)
		(layer "B.Cu")
		(net "SATA6G_PCH_PCIE_UP_SATA_RXN<1>")
	)
	(segment
		(start 390.652 -127.9144)
		(end 390.652 -127.892302)
		(width 0.0889)
		(layer "In9.Cu")
		(net "SATA6G_PCH_PCIE_UP_SATA_RXN<1>")
	)
	(segment
		(start 397.333724 -131.985512)
		(end 392.389106 -131.985512)
		(width 0.1143)
		(layer "In9.Cu")
		(net "SATA6G_PCH_PCIE_UP_SATA_RXN<1>")
	)
	(segment
		(start 388.9756 -123.507246)
		(end 388.89686 -123.528328)
		(width 0.0889)
		(layer "In9.Cu")
		(net "SATA6G_PCH_PCIE_UP_SATA_RXN<1>")
	)
	(segment
		(start 390.6139 -126.545594)
		(end 390.6139 -126.278894)
		(width 0.0889)
		(layer "In9.Cu")
		(net "SATA6G_PCH_PCIE_UP_SATA_RXN<1>")
	)
	(segment
		(start 390.7028 -126.990094)
		(end 390.7028 -126.723394)
		(width 0.0889)
		(layer "In9.Cu")
		(net "SATA6G_PCH_PCIE_UP_SATA_RXN<1>")
	)
	(segment
		(start 421.225726 -153.9875)
		(end 420.897304 -153.659078)
		(width 0.1143)
		(layer "In9.Cu")
		(net "SATA6G_PCH_PCIE_UP_SATA_RXN<1>")
	)
	(segment
		(start 390.026906 -125.12167)
		(end 389.838438 -124.933202)
		(width 0.0889)
		(layer "In9.Cu")
		(net "SATA6G_PCH_PCIE_UP_SATA_RXN<1>")
	)
	(segment
		(start 418.973508 -142.347696)
		(end 418.8587 -142.232888)
		(width 0.1143)
		(layer "In9.Cu")
		(net "SATA6G_PCH_PCIE_UP_SATA_RXN<1>")
	)
	(segment
		(start 413.67837 -137.142474)
		(end 413.67837 -134.01167)
		(width 0.1143)
		(layer "In9.Cu")
		(net "SATA6G_PCH_PCIE_UP_SATA_RXN<1>")
	)
	(segment
		(start 419.165278 -144.508474)
		(end 419.165278 -142.81023)
		(width 0.1143)
		(layer "In9.Cu")
		(net "SATA6G_PCH_PCIE_UP_SATA_RXN<1>")
	)
	(segment
		(start 410.617162 -129.1463)
		(end 402.739098 -129.1463)
		(width 0.1143)
		(layer "In9.Cu")
		(net "SATA6G_PCH_PCIE_UP_SATA_RXN<1>")
	)
	(segment
		(start 413.91586 -133.442456)
		(end 413.915352 -133.223508)
		(width 0.1143)
		(layer "In9.Cu")
		(net "SATA6G_PCH_PCIE_UP_SATA_RXN<1>")
	)
	(segment
		(start 390.652 -130.34391)
		(end 390.652 -127.9144)
		(width 0.1143)
		(layer "In9.Cu")
		(net "SATA6G_PCH_PCIE_UP_SATA_RXN<1>")
	)
	(segment
		(start 389.398256 -124.49302)
		(end 389.209788 -124.304552)
		(width 0.0889)
		(layer "In9.Cu")
		(net "SATA6G_PCH_PCIE_UP_SATA_RXN<1>")
	)
	(segment
		(start 420.079932 -145.824702)
		(end 419.448488 -145.193258)
		(width 0.1143)
		(layer "In9.Cu")
		(net "SATA6G_PCH_PCIE_UP_SATA_RXN<1>")
	)
	(segment
		(start 411.083252 -130.7338)
		(end 411.083252 -129.554224)
		(width 0.1143)
		(layer "In9.Cu")
		(net "SATA6G_PCH_PCIE_UP_SATA_RXN<1>")
	)
	(segment
		(start 390.7028 -127.841502)
		(end 390.7028 -127.612394)
		(width 0.0889)
		(layer "In9.Cu")
		(net "SATA6G_PCH_PCIE_UP_SATA_RXN<1>")
	)
	(segment
		(start 390.278366 -125.49886)
		(end 390.089898 -125.310392)
		(width 0.0889)
		(layer "In9.Cu")
		(net "SATA6G_PCH_PCIE_UP_SATA_RXN<1>")
	)
	(segment
		(start 420.295832 -153.21915)
		(end 420.295832 -149.862794)
		(width 0.1143)
		(layer "In9.Cu")
		(net "SATA6G_PCH_PCIE_UP_SATA_RXN<1>")
	)
	(segment
		(start 412.657036 -132.603494)
		(end 411.292548 -131.239006)
		(width 0.1143)
		(layer "In9.Cu")
		(net "SATA6G_PCH_PCIE_UP_SATA_RXN<1>")
	)
	(segment
		(start 413.82315 -133.632448)
		(end 413.859218 -133.592316)
		(width 0.1143)
		(layer "In9.Cu")
		(net "SATA6G_PCH_PCIE_UP_SATA_RXN<1>")
	)
	(segment
		(start 413.852614 -133.06298)
		(end 413.698436 -132.908294)
		(width 0.1143)
		(layer "In9.Cu")
		(net "SATA6G_PCH_PCIE_UP_SATA_RXN<1>")
	)
	(segment
		(start 390.7028 -126.101094)
		(end 390.7028 -125.834394)
		(width 0.0889)
		(layer "In9.Cu")
		(net "SATA6G_PCH_PCIE_UP_SATA_RXN<1>")
	)
	(segment
		(start 416.832034 -143.10995)
		(end 416.831272 -143.109188)
		(width 0.1143)
		(layer "In9.Cu")
		(net "SATA6G_PCH_PCIE_UP_SATA_RXN<1>")
	)
	(segment
		(start 390.676638 -125.771402)
		(end 390.467088 -125.561852)
		(width 0.0889)
		(layer "In9.Cu")
		(net "SATA6G_PCH_PCIE_UP_SATA_RXN<1>")
	)
	(segment
		(start 417.445444 -141.20876)
		(end 413.889444 -137.65276)
		(width 0.1143)
		(layer "In9.Cu")
		(net "SATA6G_PCH_PCIE_UP_SATA_RXN<1>")
	)
	(segment
		(start 419.165278 -142.81023)
		(end 419.165024 -142.810484)
		(width 0.1143)
		(layer "In9.Cu")
		(net "SATA6G_PCH_PCIE_UP_SATA_RXN<1>")
	)
	(segment
		(start 389.649716 -124.87021)
		(end 389.461248 -124.681742)
		(width 0.0889)
		(layer "In9.Cu")
		(net "SATA6G_PCH_PCIE_UP_SATA_RXN<1>")
	)
	(segment
		(start 411.049724 -129.473198)
		(end 410.797502 -129.220976)
		(width 0.1143)
		(layer "In9.Cu")
		(net "SATA6G_PCH_PCIE_UP_SATA_RXN<1>")
	)
	(segment
		(start 420.295832 -146.329146)
		(end 420.295578 -146.3294)
		(width 0.1143)
		(layer "In9.Cu")
		(net "SATA6G_PCH_PCIE_UP_SATA_RXN<1>")
	)
	(segment
		(start 391.820146 -131.7498)
		(end 390.820148 -130.749802)
		(width 0.1143)
		(layer "In9.Cu")
		(net "SATA6G_PCH_PCIE_UP_SATA_RXN<1>")
	)
	(segment
		(start 388.89686 -123.528328)
		(end 388.72795 -123.821444)
		(width 0.0889)
		(layer "In9.Cu")
		(net "SATA6G_PCH_PCIE_UP_SATA_RXN<1>")
	)
	(segment
		(start 390.6139 -127.434594)
		(end 390.6139 -127.167894)
		(width 0.0889)
		(layer "In9.Cu")
		(net "SATA6G_PCH_PCIE_UP_SATA_RXN<1>")
	)
	(segment
		(start 420.816532 -153.62555)
		(end 420.702232 -153.62555)
		(width 0.1143)
		(layer "In9.Cu")
		(net "SATA6G_PCH_PCIE_UP_SATA_RXN<1>")
	)
	(segment
		(start 419.649148 -148.497544)
		(end 420.035482 -148.497544)
		(width 0.1143)
		(layer "In9.Cu")
		(net "SATA6G_PCH_PCIE_UP_SATA_RXN<1>")
	)
	(segment
		(start 416.831272 -142.327884)
		(end 417.445444 -141.713712)
		(width 0.1143)
		(layer "In9.Cu")
		(net "SATA6G_PCH_PCIE_UP_SATA_RXN<1>")
	)
	(segment
		(start 420.035482 -149.602444)
		(end 419.649148 -149.602444)
		(width 0.1143)
		(layer "In9.Cu")
		(net "SATA6G_PCH_PCIE_UP_SATA_RXN<1>")
	)
	(segment
		(start 390.652 -127.892302)
		(end 390.7028 -127.841502)
		(width 0.0889)
		(layer "In9.Cu")
		(net "SATA6G_PCH_PCIE_UP_SATA_RXN<1>")
	)
	(segment
		(start 420.295832 -148.237194)
		(end 420.295832 -146.329146)
		(width 0.1143)
		(layer "In9.Cu")
		(net "SATA6G_PCH_PCIE_UP_SATA_RXN<1>")
	)
	(segment
		(start 420.079932 -145.824448)
		(end 420.079932 -145.824702)
		(width 0.1143)
		(layer "In9.Cu")
		(net "SATA6G_PCH_PCIE_UP_SATA_RXN<1>")
	)
	(segment
		(start 389.128 -124.10694)
		(end 389.128 -123.810268)
		(width 0.0889)
		(layer "In9.Cu")
		(net "SATA6G_PCH_PCIE_UP_SATA_RXN<1>")
	)
	(segment
		(start 413.915352 -133.223508)
		(end 413.915352 -133.213602)
		(width 0.1143)
		(layer "In9.Cu")
		(net "SATA6G_PCH_PCIE_UP_SATA_RXN<1>")
	)
	(segment
		(start 402.658072 -129.179828)
		(end 401.633182 -130.204718)
		(width 0.1143)
		(layer "In9.Cu")
		(net "SATA6G_PCH_PCIE_UP_SATA_RXN<1>")
	)
	(segment
		(start 418.4904 -142.232888)
		(end 417.613338 -143.10995)
		(width 0.1143)
		(layer "In9.Cu")
		(net "SATA6G_PCH_PCIE_UP_SATA_RXN<1>")
	)
	(segment
		(start 420.089584 -145.8341)
		(end 420.079932 -145.824448)
		(width 0.1143)
		(layer "In9.Cu")
		(net "SATA6G_PCH_PCIE_UP_SATA_RXN<1>")
	)
	(segment
		(start 413.599884 -132.8674)
		(end 413.294322 -132.8674)
		(width 0.1143)
		(layer "In9.Cu")
		(net "SATA6G_PCH_PCIE_UP_SATA_RXN<1>")
	)
	(segment
		(start 413.91586 -133.44271)
		(end 413.91586 -133.442456)
		(width 0.1143)
		(layer "In9.Cu")
		(net "SATA6G_PCH_PCIE_UP_SATA_RXN<1>")
	)
	(arc
		(start 389.838438 -124.933202)
		(mid 389.794207 -124.90885)
		(end 389.744204 -124.901706)
		(width 0.0889)
		(layer "In9.Cu")
		(net "SATA6G_PCH_PCIE_UP_SATA_RXN<1>")
	)
	(arc
		(start 389.429752 -124.587508)
		(mid 389.422746 -124.537344)
		(end 389.398256 -124.49302)
		(width 0.0889)
		(layer "In9.Cu")
		(net "SATA6G_PCH_PCIE_UP_SATA_RXN<1>")
	)
	(arc
		(start 419.165024 -142.810484)
		(mid 419.115263 -142.56005)
		(end 418.973508 -142.347696)
		(width 0.1143)
		(layer "In9.Cu")
		(net "SATA6G_PCH_PCIE_UP_SATA_RXN<1>")
	)
	(arc
		(start 390.7028 -127.612394)
		(mid 390.688735 -127.563868)
		(end 390.65835 -127.523494)
		(width 0.0889)
		(layer "In9.Cu")
		(net "SATA6G_PCH_PCIE_UP_SATA_RXN<1>")
	)
	(arc
		(start 390.65835 -127.078994)
		(mid 390.688771 -127.038638)
		(end 390.7028 -126.990094)
		(width 0.0889)
		(layer "In9.Cu")
		(net "SATA6G_PCH_PCIE_UP_SATA_RXN<1>")
	)
	(arc
		(start 390.65835 -127.523494)
		(mid 390.627929 -127.483138)
		(end 390.6139 -127.434594)
		(width 0.0889)
		(layer "In9.Cu")
		(net "SATA6G_PCH_PCIE_UP_SATA_RXN<1>")
	)
	(arc
		(start 392.389106 -131.985512)
		(mid 392.081171 -131.92426)
		(end 391.820146 -131.7498)
		(width 0.1143)
		(layer "In9.Cu")
		(net "SATA6G_PCH_PCIE_UP_SATA_RXN<1>")
	)
	(arc
		(start 390.65835 -126.634494)
		(mid 390.627929 -126.594138)
		(end 390.6139 -126.545594)
		(width 0.0889)
		(layer "In9.Cu")
		(net "SATA6G_PCH_PCIE_UP_SATA_RXN<1>")
	)
	(arc
		(start 420.035482 -148.497544)
		(mid 420.219577 -148.421289)
		(end 420.295832 -148.237194)
		(width 0.1143)
		(layer "In9.Cu")
		(net "SATA6G_PCH_PCIE_UP_SATA_RXN<1>")
	)
	(arc
		(start 417.445444 -141.713712)
		(mid 417.550023 -141.461236)
		(end 417.445444 -141.20876)
		(width 0.1143)
		(layer "In9.Cu")
		(net "SATA6G_PCH_PCIE_UP_SATA_RXN<1>")
	)
	(arc
		(start 390.7028 -125.834394)
		(mid 390.695998 -125.80029)
		(end 390.676638 -125.771402)
		(width 0.0889)
		(layer "In9.Cu")
		(net "SATA6G_PCH_PCIE_UP_SATA_RXN<1>")
	)
	(arc
		(start 419.448488 -145.193258)
		(mid 419.238808 -144.879031)
		(end 419.165278 -144.508474)
		(width 0.1143)
		(layer "In9.Cu")
		(net "SATA6G_PCH_PCIE_UP_SATA_RXN<1>")
	)
	(arc
		(start 390.372854 -125.530356)
		(mid 390.32269 -125.52335)
		(end 390.278366 -125.49886)
		(width 0.0889)
		(layer "In9.Cu")
		(net "SATA6G_PCH_PCIE_UP_SATA_RXN<1>")
	)
	(arc
		(start 413.915352 -133.205474)
		(mid 413.897341 -133.12835)
		(end 413.852614 -133.06298)
		(width 0.1143)
		(layer "In9.Cu")
		(net "SATA6G_PCH_PCIE_UP_SATA_RXN<1>")
	)
	(arc
		(start 420.897304 -153.659078)
		(mid 420.860245 -153.634316)
		(end 420.816532 -153.62555)
		(width 0.1143)
		(layer "In9.Cu")
		(net "SATA6G_PCH_PCIE_UP_SATA_RXN<1>")
	)
	(arc
		(start 389.128 -123.810268)
		(mid 389.085467 -123.641831)
		(end 388.9756 -123.507246)
		(width 0.0889)
		(layer "In9.Cu")
		(net "SATA6G_PCH_PCIE_UP_SATA_RXN<1>")
	)
	(arc
		(start 413.915352 -133.213602)
		(mid 413.915396 -133.209538)
		(end 413.915352 -133.205474)
		(width 0.1143)
		(layer "In9.Cu")
		(net "SATA6G_PCH_PCIE_UP_SATA_RXN<1>")
	)
	(arc
		(start 402.739098 -129.1463)
		(mid 402.69526 -129.15502)
		(end 402.658072 -129.179828)
		(width 0.1143)
		(layer "In9.Cu")
		(net "SATA6G_PCH_PCIE_UP_SATA_RXN<1>")
	)
	(arc
		(start 410.797502 -129.220976)
		(mid 410.714761 -129.16569)
		(end 410.617162 -129.1463)
		(width 0.1143)
		(layer "In9.Cu")
		(net "SATA6G_PCH_PCIE_UP_SATA_RXN<1>")
	)
	(arc
		(start 413.294322 -132.8674)
		(mid 412.949422 -132.798831)
		(end 412.657036 -132.603494)
		(width 0.1143)
		(layer "In9.Cu")
		(net "SATA6G_PCH_PCIE_UP_SATA_RXN<1>")
	)
	(arc
		(start 420.295832 -149.862794)
		(mid 420.219577 -149.678699)
		(end 420.035482 -149.602444)
		(width 0.1143)
		(layer "In9.Cu")
		(net "SATA6G_PCH_PCIE_UP_SATA_RXN<1>")
	)
	(arc
		(start 390.058402 -125.216158)
		(mid 390.051396 -125.165994)
		(end 390.026906 -125.12167)
		(width 0.0889)
		(layer "In9.Cu")
		(net "SATA6G_PCH_PCIE_UP_SATA_RXN<1>")
	)
	(arc
		(start 390.467088 -125.561852)
		(mid 390.422857 -125.5375)
		(end 390.372854 -125.530356)
		(width 0.0889)
		(layer "In9.Cu")
		(net "SATA6G_PCH_PCIE_UP_SATA_RXN<1>")
	)
	(arc
		(start 390.65835 -126.189994)
		(mid 390.688771 -126.149638)
		(end 390.7028 -126.101094)
		(width 0.0889)
		(layer "In9.Cu")
		(net "SATA6G_PCH_PCIE_UP_SATA_RXN<1>")
	)
	(arc
		(start 390.089898 -125.310392)
		(mid 390.065546 -125.266161)
		(end 390.058402 -125.216158)
		(width 0.0889)
		(layer "In9.Cu")
		(net "SATA6G_PCH_PCIE_UP_SATA_RXN<1>")
	)
	(arc
		(start 420.702232 -153.62555)
		(mid 420.414864 -153.506518)
		(end 420.295832 -153.21915)
		(width 0.1143)
		(layer "In9.Cu")
		(net "SATA6G_PCH_PCIE_UP_SATA_RXN<1>")
	)
	(arc
		(start 390.6139 -126.278894)
		(mid 390.627965 -126.230368)
		(end 390.65835 -126.189994)
		(width 0.0889)
		(layer "In9.Cu")
		(net "SATA6G_PCH_PCIE_UP_SATA_RXN<1>")
	)
	(arc
		(start 420.295578 -146.3294)
		(mid 420.242029 -146.061183)
		(end 420.089584 -145.8341)
		(width 0.1143)
		(layer "In9.Cu")
		(net "SATA6G_PCH_PCIE_UP_SATA_RXN<1>")
	)
	(arc
		(start 413.859218 -133.592316)
		(mid 413.901406 -133.522769)
		(end 413.91586 -133.44271)
		(width 0.1143)
		(layer "In9.Cu")
		(net "SATA6G_PCH_PCIE_UP_SATA_RXN<1>")
	)
	(arc
		(start 416.831272 -143.109188)
		(mid 416.669459 -142.718536)
		(end 416.831272 -142.327884)
		(width 0.1143)
		(layer "In9.Cu")
		(net "SATA6G_PCH_PCIE_UP_SATA_RXN<1>")
	)
	(arc
		(start 411.292548 -131.239006)
		(mid 411.137671 -131.007216)
		(end 411.083252 -130.7338)
		(width 0.1143)
		(layer "In9.Cu")
		(net "SATA6G_PCH_PCIE_UP_SATA_RXN<1>")
	)
	(arc
		(start 413.889444 -137.65276)
		(mid 413.733146 -137.41861)
		(end 413.67837 -137.142474)
		(width 0.1143)
		(layer "In9.Cu")
		(net "SATA6G_PCH_PCIE_UP_SATA_RXN<1>")
	)
	(arc
		(start 390.820148 -130.749802)
		(mid 390.695717 -130.563577)
		(end 390.652 -130.34391)
		(width 0.1143)
		(layer "In9.Cu")
		(net "SATA6G_PCH_PCIE_UP_SATA_RXN<1>")
	)
	(arc
		(start 411.083252 -129.554224)
		(mid 411.074532 -129.510386)
		(end 411.049724 -129.473198)
		(width 0.1143)
		(layer "In9.Cu")
		(net "SATA6G_PCH_PCIE_UP_SATA_RXN<1>")
	)
	(arc
		(start 390.6139 -127.167894)
		(mid 390.627965 -127.119368)
		(end 390.65835 -127.078994)
		(width 0.0889)
		(layer "In9.Cu")
		(net "SATA6G_PCH_PCIE_UP_SATA_RXN<1>")
	)
	(arc
		(start 413.67837 -134.01167)
		(mid 413.715695 -133.808666)
		(end 413.82315 -133.632448)
		(width 0.1143)
		(layer "In9.Cu")
		(net "SATA6G_PCH_PCIE_UP_SATA_RXN<1>")
	)
	(arc
		(start 417.613338 -143.10995)
		(mid 417.222686 -143.271763)
		(end 416.832034 -143.10995)
		(width 0.1143)
		(layer "In9.Cu")
		(net "SATA6G_PCH_PCIE_UP_SATA_RXN<1>")
	)
	(arc
		(start 390.7028 -126.723394)
		(mid 390.688735 -126.674868)
		(end 390.65835 -126.634494)
		(width 0.0889)
		(layer "In9.Cu")
		(net "SATA6G_PCH_PCIE_UP_SATA_RXN<1>")
	)
	(arc
		(start 413.698436 -132.908294)
		(mid 413.653234 -132.878028)
		(end 413.599884 -132.8674)
		(width 0.1143)
		(layer "In9.Cu")
		(net "SATA6G_PCH_PCIE_UP_SATA_RXN<1>")
	)
	(arc
		(start 419.649148 -149.602444)
		(mid 419.096698 -149.049994)
		(end 419.649148 -148.497544)
		(width 0.1143)
		(layer "In9.Cu")
		(net "SATA6G_PCH_PCIE_UP_SATA_RXN<1>")
	)
	(arc
		(start 389.209788 -124.304552)
		(mid 389.149207 -124.213887)
		(end 389.128 -124.10694)
		(width 0.0889)
		(layer "In9.Cu")
		(net "SATA6G_PCH_PCIE_UP_SATA_RXN<1>")
	)
	(arc
		(start 389.744204 -124.901706)
		(mid 389.69404 -124.8947)
		(end 389.649716 -124.87021)
		(width 0.0889)
		(layer "In9.Cu")
		(net "SATA6G_PCH_PCIE_UP_SATA_RXN<1>")
	)
	(arc
		(start 389.461248 -124.681742)
		(mid 389.436896 -124.637511)
		(end 389.429752 -124.587508)
		(width 0.0889)
		(layer "In9.Cu")
		(net "SATA6G_PCH_PCIE_UP_SATA_RXN<1>")
	)
	(arc
		(start 401.633182 -130.204718)
		(mid 399.660587 -131.522797)
		(end 397.333724 -131.985512)
		(width 0.1143)
		(layer "In9.Cu")
		(net "SATA6G_PCH_PCIE_UP_SATA_RXN<1>")
	)
	(arc
		(start 418.8587 -142.232888)
		(mid 418.67455 -142.156611)
		(end 418.4904 -142.232888)
		(width 0.1143)
		(layer "In9.Cu")
		(net "SATA6G_PCH_PCIE_UP_SATA_RXN<1>")
	)
	(segment
		(start 389.71855 -121.01576)
		(end 390.21385 -121.245884)
		(width 0.1143)
		(layer "F.Cu")
		(net "SATA6G_PCH_PCIE_UP_SATA_RXN<0>")
	)
	(via
		(at 421.81272 -150.0505)
		(size 0.508)
		(drill 0.254)
		(layers "F.Cu" "B.Cu")
		(net "SATA6G_PCH_PCIE_UP_SATA_RXN<0>")
	)
	(via
		(at 390.21385 -121.245884)
		(size 0.508)
		(drill 0.254)
		(layers "F.Cu" "B.Cu")
		(net "SATA6G_PCH_PCIE_UP_SATA_RXN<0>")
	)
	(segment
		(start 422.41089 -149.69617)
		(end 422.70172 -149.987)
		(width 0.1143)
		(layer "B.Cu")
		(net "SATA6G_PCH_PCIE_UP_SATA_RXN<0>")
	)
	(segment
		(start 421.92702 -149.662642)
		(end 422.330118 -149.662642)
		(width 0.1143)
		(layer "B.Cu")
		(net "SATA6G_PCH_PCIE_UP_SATA_RXN<0>")
	)
	(segment
		(start 421.81272 -150.0505)
		(end 421.81272 -149.776942)
		(width 0.1143)
		(layer "B.Cu")
		(net "SATA6G_PCH_PCIE_UP_SATA_RXN<0>")
	)
	(arc
		(start 422.330118 -149.662642)
		(mid 422.373859 -149.671343)
		(end 422.41089 -149.69617)
		(width 0.1143)
		(layer "B.Cu")
		(net "SATA6G_PCH_PCIE_UP_SATA_RXN<0>")
	)
	(arc
		(start 421.81272 -149.776942)
		(mid 421.846198 -149.69612)
		(end 421.92702 -149.662642)
		(width 0.1143)
		(layer "B.Cu")
		(net "SATA6G_PCH_PCIE_UP_SATA_RXN<0>")
	)
	(segment
		(start 391.2997 -122.11558)
		(end 391.2997 -122.082814)
		(width 0.0889)
		(layer "In9.Cu")
		(net "SATA6G_PCH_PCIE_UP_SATA_RXN<0>")
	)
	(segment
		(start 397.002254 -129.527046)
		(end 396.217902 -128.74244)
		(width 0.1143)
		(layer "In9.Cu")
		(net "SATA6G_PCH_PCIE_UP_SATA_RXN<0>")
	)
	(segment
		(start 395.614906 -125.962156)
		(end 395.543278 -125.962156)
		(width 0.0889)
		(layer "In9.Cu")
		(net "SATA6G_PCH_PCIE_UP_SATA_RXN<0>")
	)
	(segment
		(start 416.730942 -132.76453)
		(end 415.231834 -131.265422)
		(width 0.1143)
		(layer "In9.Cu")
		(net "SATA6G_PCH_PCIE_UP_SATA_RXN<0>")
	)
	(segment
		(start 423.2021 -147.155154)
		(end 424.0657 -146.291554)
		(width 0.1143)
		(layer "In9.Cu")
		(net "SATA6G_PCH_PCIE_UP_SATA_RXN<0>")
	)
	(segment
		(start 395.714728 -126.061978)
		(end 395.6304 -125.97765)
		(width 0.1143)
		(layer "In9.Cu")
		(net "SATA6G_PCH_PCIE_UP_SATA_RXN<0>")
	)
	(segment
		(start 424.985688 -145.9103)
		(end 429.200056 -145.9103)
		(width 0.1143)
		(layer "In9.Cu")
		(net "SATA6G_PCH_PCIE_UP_SATA_RXN<0>")
	)
	(segment
		(start 390.689592 -121.5136)
		(end 390.688322 -121.5136)
		(width 0.0889)
		(layer "In9.Cu")
		(net "SATA6G_PCH_PCIE_UP_SATA_RXN<0>")
	)
	(segment
		(start 430.290224 -145.458688)
		(end 430.834038 -144.914874)
		(width 0.1143)
		(layer "In9.Cu")
		(net "SATA6G_PCH_PCIE_UP_SATA_RXN<0>")
	)
	(segment
		(start 431.1523 -144.146016)
		(end 431.1523 -143.360902)
		(width 0.1143)
		(layer "In9.Cu")
		(net "SATA6G_PCH_PCIE_UP_SATA_RXN<0>")
	)
	(segment
		(start 423.100754 -142.180056)
		(end 422.468294 -141.547596)
		(width 0.1143)
		(layer "In9.Cu")
		(net "SATA6G_PCH_PCIE_UP_SATA_RXN<0>")
	)
	(segment
		(start 392.2903 -124.012452)
		(end 392.2903 -123.799854)
		(width 0.0889)
		(layer "In9.Cu")
		(net "SATA6G_PCH_PCIE_UP_SATA_RXN<0>")
	)
	(segment
		(start 420.466774 -140.911834)
		(end 417.473384 -137.918444)
		(width 0.1143)
		(layer "In9.Cu")
		(net "SATA6G_PCH_PCIE_UP_SATA_RXN<0>")
	)
	(segment
		(start 397.9037 -129.8575)
		(end 397.800322 -129.8575)
		(width 0.1143)
		(layer "In9.Cu")
		(net "SATA6G_PCH_PCIE_UP_SATA_RXN<0>")
	)
	(segment
		(start 421.65778 -141.212062)
		(end 421.191436 -141.212062)
		(width 0.1143)
		(layer "In9.Cu")
		(net "SATA6G_PCH_PCIE_UP_SATA_RXN<0>")
	)
	(segment
		(start 417.089082 -136.990836)
		(end 417.089082 -133.629146)
		(width 0.1143)
		(layer "In9.Cu")
		(net "SATA6G_PCH_PCIE_UP_SATA_RXN<0>")
	)
	(segment
		(start 414.80105 -130.225292)
		(end 414.800796 -130.225546)
		(width 0.1143)
		(layer "In9.Cu")
		(net "SATA6G_PCH_PCIE_UP_SATA_RXN<0>")
	)
	(segment
		(start 396.217902 -128.74244)
		(end 395.956536 -128.48082)
		(width 0.1143)
		(layer "In9.Cu")
		(net "SATA6G_PCH_PCIE_UP_SATA_RXN<0>")
	)
	(segment
		(start 393.8651 -124.399802)
		(end 392.67765 -124.399802)
		(width 0.0889)
		(layer "In9.Cu")
		(net "SATA6G_PCH_PCIE_UP_SATA_RXN<0>")
	)
	(segment
		(start 395.8336 -128.183894)
		(end 395.8336 -126.349252)
		(width 0.1143)
		(layer "In9.Cu")
		(net "SATA6G_PCH_PCIE_UP_SATA_RXN<0>")
	)
	(segment
		(start 401.75053 -127.385318)
		(end 400.250914 -128.884934)
		(width 0.1143)
		(layer "In9.Cu")
		(net "SATA6G_PCH_PCIE_UP_SATA_RXN<0>")
	)
	(segment
		(start 430.196498 -142.4051)
		(end 423.644314 -142.4051)
		(width 0.1143)
		(layer "In9.Cu")
		(net "SATA6G_PCH_PCIE_UP_SATA_RXN<0>")
	)
	(segment
		(start 391.795 -122.9741)
		(end 391.795 -122.941334)
		(width 0.0889)
		(layer "In9.Cu")
		(net "SATA6G_PCH_PCIE_UP_SATA_RXN<0>")
	)
	(segment
		(start 413.572452 -127.112268)
		(end 402.409914 -127.112268)
		(width 0.1143)
		(layer "In9.Cu")
		(net "SATA6G_PCH_PCIE_UP_SATA_RXN<0>")
	)
	(segment
		(start 391.004552 -121.592594)
		(end 391.004552 -121.592848)
		(width 0.0889)
		(layer "In9.Cu")
		(net "SATA6G_PCH_PCIE_UP_SATA_RXN<0>")
	)
	(segment
		(start 421.81272 -150.0505)
		(end 422.16451 -149.69871)
		(width 0.1143)
		(layer "In9.Cu")
		(net "SATA6G_PCH_PCIE_UP_SATA_RXN<0>")
	)
	(segment
		(start 422.245282 -149.665182)
		(end 422.469056 -149.665182)
		(width 0.1143)
		(layer "In9.Cu")
		(net "SATA6G_PCH_PCIE_UP_SATA_RXN<0>")
	)
	(segment
		(start 414.800796 -130.225546)
		(end 414.800796 -128.340612)
		(width 0.1143)
		(layer "In9.Cu")
		(net "SATA6G_PCH_PCIE_UP_SATA_RXN<0>")
	)
	(segment
		(start 422.9354 -149.198838)
		(end 422.9354 -147.799044)
		(width 0.1143)
		(layer "In9.Cu")
		(net "SATA6G_PCH_PCIE_UP_SATA_RXN<0>")
	)
	(segment
		(start 395.543278 -125.962156)
		(end 394.062712 -124.48159)
		(width 0.0889)
		(layer "In9.Cu")
		(net "SATA6G_PCH_PCIE_UP_SATA_RXN<0>")
	)
	(segment
		(start 395.6304 -125.97765)
		(end 395.614906 -125.962156)
		(width 0.0889)
		(layer "In9.Cu")
		(net "SATA6G_PCH_PCIE_UP_SATA_RXN<0>")
	)
	(segment
		(start 392.614658 -124.37364)
		(end 392.316462 -124.075444)
		(width 0.0889)
		(layer "In9.Cu")
		(net "SATA6G_PCH_PCIE_UP_SATA_RXN<0>")
	)
	(arc
		(start 391.499852 -122.451114)
		(mid 391.356048 -122.309431)
		(end 391.2997 -122.11558)
		(width 0.0889)
		(layer "In9.Cu")
		(net "SATA6G_PCH_PCIE_UP_SATA_RXN<0>")
	)
	(arc
		(start 391.004552 -121.592848)
		(mid 390.852626 -121.531142)
		(end 390.689592 -121.5136)
		(width 0.0889)
		(layer "In9.Cu")
		(net "SATA6G_PCH_PCIE_UP_SATA_RXN<0>")
	)
	(arc
		(start 430.834038 -144.914874)
		(mid 431.06958 -144.562076)
		(end 431.1523 -144.146016)
		(width 0.1143)
		(layer "In9.Cu")
		(net "SATA6G_PCH_PCIE_UP_SATA_RXN<0>")
	)
	(arc
		(start 402.409914 -127.112268)
		(mid 402.053059 -127.183215)
		(end 401.75053 -127.385318)
		(width 0.1143)
		(layer "In9.Cu")
		(net "SATA6G_PCH_PCIE_UP_SATA_RXN<0>")
	)
	(arc
		(start 394.062712 -124.48159)
		(mid 393.972047 -124.421009)
		(end 393.8651 -124.399802)
		(width 0.0889)
		(layer "In9.Cu")
		(net "SATA6G_PCH_PCIE_UP_SATA_RXN<0>")
	)
	(arc
		(start 414.800796 -128.340612)
		(mid 414.441022 -127.472042)
		(end 413.572452 -127.112268)
		(width 0.1143)
		(layer "In9.Cu")
		(net "SATA6G_PCH_PCIE_UP_SATA_RXN<0>")
	)
	(arc
		(start 431.1523 -143.360902)
		(mid 430.872352 -142.685048)
		(end 430.196498 -142.4051)
		(width 0.1143)
		(layer "In9.Cu")
		(net "SATA6G_PCH_PCIE_UP_SATA_RXN<0>")
	)
	(arc
		(start 424.0657 -146.291554)
		(mid 424.487807 -146.009515)
		(end 424.985688 -145.9103)
		(width 0.1143)
		(layer "In9.Cu")
		(net "SATA6G_PCH_PCIE_UP_SATA_RXN<0>")
	)
	(arc
		(start 423.644314 -142.4051)
		(mid 423.350143 -142.346661)
		(end 423.100754 -142.180056)
		(width 0.1143)
		(layer "In9.Cu")
		(net "SATA6G_PCH_PCIE_UP_SATA_RXN<0>")
	)
	(arc
		(start 422.468294 -141.547596)
		(mid 422.096384 -141.299283)
		(end 421.65778 -141.212062)
		(width 0.1143)
		(layer "In9.Cu")
		(net "SATA6G_PCH_PCIE_UP_SATA_RXN<0>")
	)
	(arc
		(start 422.469056 -149.665182)
		(mid 422.798811 -149.528593)
		(end 422.9354 -149.198838)
		(width 0.1143)
		(layer "In9.Cu")
		(net "SATA6G_PCH_PCIE_UP_SATA_RXN<0>")
	)
	(arc
		(start 391.2997 -122.082814)
		(mid 391.215419 -121.799597)
		(end 391.004552 -121.592594)
		(width 0.0889)
		(layer "In9.Cu")
		(net "SATA6G_PCH_PCIE_UP_SATA_RXN<0>")
	)
	(arc
		(start 422.16451 -149.69871)
		(mid 422.201569 -149.673948)
		(end 422.245282 -149.665182)
		(width 0.1143)
		(layer "In9.Cu")
		(net "SATA6G_PCH_PCIE_UP_SATA_RXN<0>")
	)
	(arc
		(start 417.089082 -133.629146)
		(mid 416.995952 -133.161243)
		(end 416.730942 -132.76453)
		(width 0.1143)
		(layer "In9.Cu")
		(net "SATA6G_PCH_PCIE_UP_SATA_RXN<0>")
	)
	(arc
		(start 395.956536 -128.48082)
		(mid 395.865617 -128.344561)
		(end 395.8336 -128.183894)
		(width 0.1143)
		(layer "In9.Cu")
		(net "SATA6G_PCH_PCIE_UP_SATA_RXN<0>")
	)
	(arc
		(start 415.231834 -131.265422)
		(mid 414.912944 -130.78822)
		(end 414.80105 -130.225292)
		(width 0.1143)
		(layer "In9.Cu")
		(net "SATA6G_PCH_PCIE_UP_SATA_RXN<0>")
	)
	(arc
		(start 391.795 -122.941334)
		(mid 391.710719 -122.658117)
		(end 391.499852 -122.451114)
		(width 0.0889)
		(layer "In9.Cu")
		(net "SATA6G_PCH_PCIE_UP_SATA_RXN<0>")
	)
	(arc
		(start 422.9354 -147.799044)
		(mid 423.004715 -147.450576)
		(end 423.2021 -147.155154)
		(width 0.1143)
		(layer "In9.Cu")
		(net "SATA6G_PCH_PCIE_UP_SATA_RXN<0>")
	)
	(arc
		(start 390.688322 -121.5136)
		(mid 390.413641 -121.446074)
		(end 390.21385 -121.245884)
		(width 0.0889)
		(layer "In9.Cu")
		(net "SATA6G_PCH_PCIE_UP_SATA_RXN<0>")
	)
	(arc
		(start 429.200056 -145.9103)
		(mid 429.79007 -145.792939)
		(end 430.290224 -145.458688)
		(width 0.1143)
		(layer "In9.Cu")
		(net "SATA6G_PCH_PCIE_UP_SATA_RXN<0>")
	)
	(arc
		(start 421.191436 -141.212062)
		(mid 420.799242 -141.134032)
		(end 420.466774 -140.911834)
		(width 0.1143)
		(layer "In9.Cu")
		(net "SATA6G_PCH_PCIE_UP_SATA_RXN<0>")
	)
	(arc
		(start 392.316462 -124.075444)
		(mid 392.297097 -124.046557)
		(end 392.2903 -124.012452)
		(width 0.0889)
		(layer "In9.Cu")
		(net "SATA6G_PCH_PCIE_UP_SATA_RXN<0>")
	)
	(arc
		(start 392.67765 -124.399802)
		(mid 392.643546 -124.393)
		(end 392.614658 -124.37364)
		(width 0.0889)
		(layer "In9.Cu")
		(net "SATA6G_PCH_PCIE_UP_SATA_RXN<0>")
	)
	(arc
		(start 397.800322 -129.8575)
		(mid 397.368416 -129.771664)
		(end 397.002254 -129.527046)
		(width 0.1143)
		(layer "In9.Cu")
		(net "SATA6G_PCH_PCIE_UP_SATA_RXN<0>")
	)
	(arc
		(start 395.8336 -126.349252)
		(mid 395.802714 -126.193798)
		(end 395.714728 -126.061978)
		(width 0.1143)
		(layer "In9.Cu")
		(net "SATA6G_PCH_PCIE_UP_SATA_RXN<0>")
	)
	(arc
		(start 400.250914 -128.884934)
		(mid 399.174047 -129.604693)
		(end 397.9037 -129.8575)
		(width 0.1143)
		(layer "In9.Cu")
		(net "SATA6G_PCH_PCIE_UP_SATA_RXN<0>")
	)
	(arc
		(start 391.995152 -123.309634)
		(mid 391.851348 -123.167951)
		(end 391.795 -122.9741)
		(width 0.0889)
		(layer "In9.Cu")
		(net "SATA6G_PCH_PCIE_UP_SATA_RXN<0>")
	)
	(arc
		(start 392.2903 -123.799854)
		(mid 392.206019 -123.516637)
		(end 391.995152 -123.309634)
		(width 0.0889)
		(layer "In9.Cu")
		(net "SATA6G_PCH_PCIE_UP_SATA_RXN<0>")
	)
	(arc
		(start 417.473384 -137.918444)
		(mid 417.18896 -137.492868)
		(end 417.089082 -136.990836)
		(width 0.1143)
		(layer "In9.Cu")
		(net "SATA6G_PCH_PCIE_UP_SATA_RXN<0>")
	)
	(via
		(at 12.4968 -86.5251)
		(size 0.508)
		(drill 0.254)
		(layers "F.Cu" "B.Cu")
		(net "A_P12V_STBY_ADR_TRIGGER")
	)
	(via
		(at 20.2184 -85.1408)
		(size 0.508)
		(drill 0.254)
		(layers "F.Cu" "B.Cu")
		(net "A_P12V_STBY_ADR_TRIGGER")
	)
	(via
		(at 11.5443 -88.5444)
		(size 0.6604)
		(drill 0.3302)
		(layers "F.Cu" "B.Cu")
		(net "A_P12V_STBY_ADR_TRIGGER")
	)
	(segment
		(start 19.431 -83.312)
		(end 20.109942 -83.312)
		(width 0.254)
		(layer "B.Cu")
		(net "A_P12V_STBY_ADR_TRIGGER")
	)
	(segment
		(start 11.5443 -87.4776)
		(end 12.4968 -86.5251)
		(width 0.254)
		(layer "B.Cu")
		(net "A_P12V_STBY_ADR_TRIGGER")
	)
	(segment
		(start 19.431 -83.929728)
		(end 19.431 -83.312)
		(width 0.254)
		(layer "B.Cu")
		(net "A_P12V_STBY_ADR_TRIGGER")
	)
	(segment
		(start 20.5994 -84.7598)
		(end 20.729702 -84.7598)
		(width 0.254)
		(layer "B.Cu")
		(net "A_P12V_STBY_ADR_TRIGGER")
	)
	(segment
		(start 20.2184 -85.1408)
		(end 20.5994 -84.7598)
		(width 0.254)
		(layer "B.Cu")
		(net "A_P12V_STBY_ADR_TRIGGER")
	)
	(segment
		(start 11.5443 -88.5444)
		(end 11.5443 -87.4776)
		(width 0.254)
		(layer "B.Cu")
		(net "A_P12V_STBY_ADR_TRIGGER")
	)
	(segment
		(start 20.729702 -84.7598)
		(end 21.034502 -84.455)
		(width 0.254)
		(layer "B.Cu")
		(net "A_P12V_STBY_ADR_TRIGGER")
	)
	(segment
		(start 16.383 -91.2495)
		(end 13.9446 -91.2495)
		(width 0.254)
		(layer "B.Cu")
		(net "A_P12V_STBY_ADR_TRIGGER")
	)
	(segment
		(start 19.4564 -84.3026)
		(end 19.4564 -83.955128)
		(width 0.254)
		(layer "B.Cu")
		(net "A_P12V_STBY_ADR_TRIGGER")
	)
	(segment
		(start 13.3223 -90.6272)
		(end 12.247118 -90.6272)
		(width 0.254)
		(layer "B.Cu")
		(net "A_P12V_STBY_ADR_TRIGGER")
	)
	(segment
		(start 20.109942 -83.312)
		(end 21.034502 -84.23656)
		(width 0.254)
		(layer "B.Cu")
		(net "A_P12V_STBY_ADR_TRIGGER")
	)
	(segment
		(start 21.034502 -84.23656)
		(end 21.034502 -84.455)
		(width 0.254)
		(layer "B.Cu")
		(net "A_P12V_STBY_ADR_TRIGGER")
	)
	(segment
		(start 11.5443 -89.924382)
		(end 11.5443 -88.5444)
		(width 0.254)
		(layer "B.Cu")
		(net "A_P12V_STBY_ADR_TRIGGER")
	)
	(segment
		(start 19.4564 -83.955128)
		(end 19.431 -83.929728)
		(width 0.254)
		(layer "B.Cu")
		(net "A_P12V_STBY_ADR_TRIGGER")
	)
	(segment
		(start 12.247118 -90.6272)
		(end 11.5443 -89.924382)
		(width 0.254)
		(layer "B.Cu")
		(net "A_P12V_STBY_ADR_TRIGGER")
	)
	(segment
		(start 13.9446 -91.2495)
		(end 13.3223 -90.6272)
		(width 0.254)
		(layer "B.Cu")
		(net "A_P12V_STBY_ADR_TRIGGER")
	)
	(segment
		(start 13.135356 -84.096352)
		(end 12.4968 -84.734908)
		(width 0.254)
		(layer "In2.Cu")
		(net "A_P12V_STBY_ADR_TRIGGER")
	)
	(segment
		(start 12.4968 -84.734908)
		(end 12.4968 -86.5251)
		(width 0.254)
		(layer "In2.Cu")
		(net "A_P12V_STBY_ADR_TRIGGER")
	)
	(segment
		(start 17.526 -84.4804)
		(end 17.141952 -84.096352)
		(width 0.254)
		(layer "In2.Cu")
		(net "A_P12V_STBY_ADR_TRIGGER")
	)
	(segment
		(start 19.558 -84.4804)
		(end 17.526 -84.4804)
		(width 0.254)
		(layer "In2.Cu")
		(net "A_P12V_STBY_ADR_TRIGGER")
	)
	(segment
		(start 20.2184 -85.1408)
		(end 19.558 -84.4804)
		(width 0.254)
		(layer "In2.Cu")
		(net "A_P12V_STBY_ADR_TRIGGER")
	)
	(segment
		(start 17.141952 -84.096352)
		(end 13.135356 -84.096352)
		(width 0.254)
		(layer "In2.Cu")
		(net "A_P12V_STBY_ADR_TRIGGER")
	)
	(segment
		(start 18.062448 -82.423)
		(end 18.542 -82.423)
		(width 0.254)
		(layer "F.Cu")
		(net "A_HSC_ISET_S2")
	)
	(segment
		(start 17.808448 -82.677)
		(end 18.062448 -82.423)
		(width 0.254)
		(layer "F.Cu")
		(net "A_HSC_ISET_S2")
	)
	(segment
		(start 17.399 -82.677)
		(end 17.808448 -82.677)
		(width 0.254)
		(layer "F.Cu")
		(net "A_HSC_ISET_S2")
	)
	(segment
		(start 17.78 -83.3628)
		(end 17.7038 -83.439)
		(width 0.254)
		(layer "F.Cu")
		(net "A_HSC_ISET_S")
	)
	(segment
		(start 19.2024 -84.3534)
		(end 19.2024 -85.232494)
		(width 0.254)
		(layer "F.Cu")
		(net "A_HSC_ISET_S")
	)
	(segment
		(start 18.85569 -84.3534)
		(end 18.65249 -84.1502)
		(width 0.254)
		(layer "F.Cu")
		(net "A_HSC_ISET_S")
	)
	(segment
		(start 18.3642 -83.3628)
		(end 17.78 -83.3628)
		(width 0.254)
		(layer "F.Cu")
		(net "A_HSC_ISET_S")
	)
	(segment
		(start 16.099028 -83.976972)
		(end 16.099028 -84.455)
		(width 0.254)
		(layer "F.Cu")
		(net "A_HSC_ISET_S")
	)
	(segment
		(start 19.2024 -85.232494)
		(end 19.304 -85.334094)
		(width 0.254)
		(layer "F.Cu")
		(net "A_HSC_ISET_S")
	)
	(segment
		(start 19.2024 -84.3534)
		(end 18.85569 -84.3534)
		(width 0.254)
		(layer "F.Cu")
		(net "A_HSC_ISET_S")
	)
	(segment
		(start 18.65249 -84.1502)
		(end 18.65249 -83.65109)
		(width 0.254)
		(layer "F.Cu")
		(net "A_HSC_ISET_S")
	)
	(segment
		(start 18.65249 -83.65109)
		(end 18.3642 -83.3628)
		(width 0.254)
		(layer "F.Cu")
		(net "A_HSC_ISET_S")
	)
	(segment
		(start 16.637 -83.439)
		(end 16.099028 -83.976972)
		(width 0.254)
		(layer "F.Cu")
		(net "A_HSC_ISET_S")
	)
	(segment
		(start 17.7038 -83.439)
		(end 16.637 -83.439)
		(width 0.254)
		(layer "F.Cu")
		(net "A_HSC_ISET_S")
	)
	(via
		(at 19.304 -85.334094)
		(size 0.762)
		(drill 0.381)
		(layers "F.Cu" "B.Cu")
		(net "A_HSC_ISET_S")
	)
	(segment
		(start 446.999868 -113.556288)
		(end 446.720468 -113.835688)
		(width 0.1143)
		(layer "F.Cu")
		(net "P3E_OCP_CPU0_PE3_C_TXP<9>")
	)
	(segment
		(start 446.720468 -113.835688)
		(end 446.720468 -114.299492)
		(width 0.1143)
		(layer "F.Cu")
		(net "P3E_OCP_CPU0_PE3_C_TXP<9>")
	)
	(segment
		(start 446.824608 -114.403632)
		(end 447.234818 -114.403632)
		(width 0.1143)
		(layer "F.Cu")
		(net "P3E_OCP_CPU0_PE3_C_TXP<9>")
	)
	(segment
		(start 447.000884 -112.205516)
		(end 446.999868 -112.205516)
		(width 0.1143)
		(layer "F.Cu")
		(net "P3E_OCP_CPU0_PE3_C_TXP<9>")
	)
	(segment
		(start 446.720468 -114.299492)
		(end 446.824608 -114.403632)
		(width 0.1143)
		(layer "F.Cu")
		(net "P3E_OCP_CPU0_PE3_C_TXP<9>")
	)
	(segment
		(start 446.999868 -112.205516)
		(end 446.999868 -113.556288)
		(width 0.1143)
		(layer "F.Cu")
		(net "P3E_OCP_CPU0_PE3_C_TXP<9>")
	)
	(via
		(at 447.234818 -114.403632)
		(size 0.508)
		(drill 0.254)
		(layers "F.Cu" "B.Cu")
		(net "P3E_OCP_CPU0_PE3_C_TXP<9>")
	)
	(segment
		(start 446.834768 -114.403632)
		(end 447.234818 -114.403632)
		(width 0.1143)
		(layer "B.Cu")
		(net "P3E_OCP_CPU0_PE3_C_TXP<9>")
	)
	(segment
		(start 446.70218 -115.2652)
		(end 446.70218 -114.53622)
		(width 0.1143)
		(layer "B.Cu")
		(net "P3E_OCP_CPU0_PE3_C_TXP<9>")
	)
	(segment
		(start 447.04 -115.60302)
		(end 446.70218 -115.2652)
		(width 0.1143)
		(layer "B.Cu")
		(net "P3E_OCP_CPU0_PE3_C_TXP<9>")
	)
	(segment
		(start 446.70218 -114.53622)
		(end 446.834768 -114.403632)
		(width 0.1143)
		(layer "B.Cu")
		(net "P3E_OCP_CPU0_PE3_C_TXP<9>")
	)
	(segment
		(start 443.799976 -112.205516)
		(end 443.799976 -113.556288)
		(width 0.1143)
		(layer "F.Cu")
		(net "P3E_OCP_CPU0_PE3_C_TXP<8>")
	)
	(segment
		(start 443.799976 -113.556288)
		(end 443.520576 -113.835688)
		(width 0.1143)
		(layer "F.Cu")
		(net "P3E_OCP_CPU0_PE3_C_TXP<8>")
	)
	(segment
		(start 443.520576 -113.835688)
		(end 443.520576 -114.289332)
		(width 0.1143)
		(layer "F.Cu")
		(net "P3E_OCP_CPU0_PE3_C_TXP<8>")
	)
	(segment
		(start 443.634876 -114.403632)
		(end 444.034926 -114.403632)
		(width 0.1143)
		(layer "F.Cu")
		(net "P3E_OCP_CPU0_PE3_C_TXP<8>")
	)
	(segment
		(start 443.800992 -112.205516)
		(end 443.799976 -112.205516)
		(width 0.1143)
		(layer "F.Cu")
		(net "P3E_OCP_CPU0_PE3_C_TXP<8>")
	)
	(segment
		(start 443.520576 -114.289332)
		(end 443.634876 -114.403632)
		(width 0.1143)
		(layer "F.Cu")
		(net "P3E_OCP_CPU0_PE3_C_TXP<8>")
	)
	(via
		(at 444.034926 -114.403632)
		(size 0.508)
		(drill 0.254)
		(layers "F.Cu" "B.Cu")
		(net "P3E_OCP_CPU0_PE3_C_TXP<8>")
	)
	(segment
		(start 443.634876 -114.403632)
		(end 444.034926 -114.403632)
		(width 0.1143)
		(layer "B.Cu")
		(net "P3E_OCP_CPU0_PE3_C_TXP<8>")
	)
	(segment
		(start 443.865 -115.60302)
		(end 443.51067 -115.24869)
		(width 0.1143)
		(layer "B.Cu")
		(net "P3E_OCP_CPU0_PE3_C_TXP<8>")
	)
	(segment
		(start 443.51067 -115.24869)
		(end 443.51067 -114.527838)
		(width 0.1143)
		(layer "B.Cu")
		(net "P3E_OCP_CPU0_PE3_C_TXP<8>")
	)
	(segment
		(start 443.51067 -114.527838)
		(end 443.634876 -114.403632)
		(width 0.1143)
		(layer "B.Cu")
		(net "P3E_OCP_CPU0_PE3_C_TXP<8>")
	)
	(segment
		(start 466.200998 -112.205516)
		(end 466.199982 -112.205516)
		(width 0.1143)
		(layer "F.Cu")
		(net "P3E_OCP_CPU0_PE3_C_TXP<15>")
	)
	(segment
		(start 465.920582 -114.32413)
		(end 466.048852 -114.4524)
		(width 0.1143)
		(layer "F.Cu")
		(net "P3E_OCP_CPU0_PE3_C_TXP<15>")
	)
	(segment
		(start 465.920582 -113.835688)
		(end 465.920582 -114.32413)
		(width 0.1143)
		(layer "F.Cu")
		(net "P3E_OCP_CPU0_PE3_C_TXP<15>")
	)
	(segment
		(start 466.048852 -114.4524)
		(end 466.46973 -114.4524)
		(width 0.1143)
		(layer "F.Cu")
		(net "P3E_OCP_CPU0_PE3_C_TXP<15>")
	)
	(segment
		(start 466.199982 -112.205516)
		(end 466.199982 -113.556288)
		(width 0.1143)
		(layer "F.Cu")
		(net "P3E_OCP_CPU0_PE3_C_TXP<15>")
	)
	(segment
		(start 466.199982 -113.556288)
		(end 465.920582 -113.835688)
		(width 0.1143)
		(layer "F.Cu")
		(net "P3E_OCP_CPU0_PE3_C_TXP<15>")
	)
	(via
		(at 466.46973 -114.4524)
		(size 0.508)
		(drill 0.254)
		(layers "F.Cu" "B.Cu")
		(net "P3E_OCP_CPU0_PE3_C_TXP<15>")
	)
	(segment
		(start 465.95538 -115.2144)
		(end 465.95538 -114.5667)
		(width 0.1143)
		(layer "B.Cu")
		(net "P3E_OCP_CPU0_PE3_C_TXP<15>")
	)
	(segment
		(start 466.06968 -114.4524)
		(end 466.46973 -114.4524)
		(width 0.1143)
		(layer "B.Cu")
		(net "P3E_OCP_CPU0_PE3_C_TXP<15>")
	)
	(segment
		(start 466.344 -115.60302)
		(end 465.95538 -115.2144)
		(width 0.1143)
		(layer "B.Cu")
		(net "P3E_OCP_CPU0_PE3_C_TXP<15>")
	)
	(segment
		(start 465.95538 -114.5667)
		(end 466.06968 -114.4524)
		(width 0.1143)
		(layer "B.Cu")
		(net "P3E_OCP_CPU0_PE3_C_TXP<15>")
	)
	(segment
		(start 462.857596 -114.403632)
		(end 463.23504 -114.403632)
		(width 0.1143)
		(layer "F.Cu")
		(net "P3E_OCP_CPU0_PE3_C_TXP<14>")
	)
	(segment
		(start 462.72069 -114.266726)
		(end 462.857596 -114.403632)
		(width 0.1143)
		(layer "F.Cu")
		(net "P3E_OCP_CPU0_PE3_C_TXP<14>")
	)
	(segment
		(start 462.999836 -112.205516)
		(end 462.999836 -113.556542)
		(width 0.1143)
		(layer "F.Cu")
		(net "P3E_OCP_CPU0_PE3_C_TXP<14>")
	)
	(segment
		(start 462.999836 -113.556542)
		(end 462.72069 -113.835688)
		(width 0.1143)
		(layer "F.Cu")
		(net "P3E_OCP_CPU0_PE3_C_TXP<14>")
	)
	(segment
		(start 463.000852 -112.205516)
		(end 462.999836 -112.205516)
		(width 0.1143)
		(layer "F.Cu")
		(net "P3E_OCP_CPU0_PE3_C_TXP<14>")
	)
	(segment
		(start 462.72069 -113.835688)
		(end 462.72069 -114.266726)
		(width 0.1143)
		(layer "F.Cu")
		(net "P3E_OCP_CPU0_PE3_C_TXP<14>")
	)
	(via
		(at 463.23504 -114.403632)
		(size 0.508)
		(drill 0.254)
		(layers "F.Cu" "B.Cu")
		(net "P3E_OCP_CPU0_PE3_C_TXP<14>")
	)
	(segment
		(start 462.83499 -114.403632)
		(end 463.23504 -114.403632)
		(width 0.1143)
		(layer "B.Cu")
		(net "P3E_OCP_CPU0_PE3_C_TXP<14>")
	)
	(segment
		(start 462.698592 -114.54003)
		(end 462.83499 -114.403632)
		(width 0.1143)
		(layer "B.Cu")
		(net "P3E_OCP_CPU0_PE3_C_TXP<14>")
	)
	(segment
		(start 463.042 -115.60302)
		(end 462.698592 -115.259612)
		(width 0.1143)
		(layer "B.Cu")
		(net "P3E_OCP_CPU0_PE3_C_TXP<14>")
	)
	(segment
		(start 462.698592 -115.259612)
		(end 462.698592 -114.54003)
		(width 0.1143)
		(layer "B.Cu")
		(net "P3E_OCP_CPU0_PE3_C_TXP<14>")
	)
	(segment
		(start 459.799944 -113.556288)
		(end 459.520544 -113.835688)
		(width 0.1143)
		(layer "F.Cu")
		(net "P3E_OCP_CPU0_PE3_C_TXP<13>")
	)
	(segment
		(start 459.520544 -114.316002)
		(end 459.608174 -114.403632)
		(width 0.1143)
		(layer "F.Cu")
		(net "P3E_OCP_CPU0_PE3_C_TXP<13>")
	)
	(segment
		(start 459.608174 -114.403632)
		(end 460.034894 -114.403632)
		(width 0.1143)
		(layer "F.Cu")
		(net "P3E_OCP_CPU0_PE3_C_TXP<13>")
	)
	(segment
		(start 459.520544 -113.835688)
		(end 459.520544 -114.316002)
		(width 0.1143)
		(layer "F.Cu")
		(net "P3E_OCP_CPU0_PE3_C_TXP<13>")
	)
	(segment
		(start 459.80096 -112.205516)
		(end 459.799944 -112.205516)
		(width 0.1143)
		(layer "F.Cu")
		(net "P3E_OCP_CPU0_PE3_C_TXP<13>")
	)
	(segment
		(start 459.799944 -112.205516)
		(end 459.799944 -113.556288)
		(width 0.1143)
		(layer "F.Cu")
		(net "P3E_OCP_CPU0_PE3_C_TXP<13>")
	)
	(via
		(at 460.034894 -114.403632)
		(size 0.508)
		(drill 0.254)
		(layers "F.Cu" "B.Cu")
		(net "P3E_OCP_CPU0_PE3_C_TXP<13>")
	)
	(segment
		(start 459.50759 -114.530886)
		(end 459.634844 -114.403632)
		(width 0.1143)
		(layer "B.Cu")
		(net "P3E_OCP_CPU0_PE3_C_TXP<13>")
	)
	(segment
		(start 459.634844 -114.403632)
		(end 460.034894 -114.403632)
		(width 0.1143)
		(layer "B.Cu")
		(net "P3E_OCP_CPU0_PE3_C_TXP<13>")
	)
	(segment
		(start 459.50759 -115.24361)
		(end 459.50759 -114.530886)
		(width 0.1143)
		(layer "B.Cu")
		(net "P3E_OCP_CPU0_PE3_C_TXP<13>")
	)
	(segment
		(start 459.867 -115.60302)
		(end 459.50759 -115.24361)
		(width 0.1143)
		(layer "B.Cu")
		(net "P3E_OCP_CPU0_PE3_C_TXP<13>")
	)
	(segment
		(start 456.599798 -113.556542)
		(end 456.320652 -113.835688)
		(width 0.1143)
		(layer "F.Cu")
		(net "P3E_OCP_CPU0_PE3_C_TXP<12>")
	)
	(segment
		(start 456.320652 -113.835688)
		(end 456.320652 -114.258344)
		(width 0.1143)
		(layer "F.Cu")
		(net "P3E_OCP_CPU0_PE3_C_TXP<12>")
	)
	(segment
		(start 456.46594 -114.403632)
		(end 456.835002 -114.403632)
		(width 0.1143)
		(layer "F.Cu")
		(net "P3E_OCP_CPU0_PE3_C_TXP<12>")
	)
	(segment
		(start 456.600814 -112.205516)
		(end 456.599798 -112.205516)
		(width 0.1143)
		(layer "F.Cu")
		(net "P3E_OCP_CPU0_PE3_C_TXP<12>")
	)
	(segment
		(start 456.599798 -112.205516)
		(end 456.599798 -113.556542)
		(width 0.1143)
		(layer "F.Cu")
		(net "P3E_OCP_CPU0_PE3_C_TXP<12>")
	)
	(segment
		(start 456.320652 -114.258344)
		(end 456.46594 -114.403632)
		(width 0.1143)
		(layer "F.Cu")
		(net "P3E_OCP_CPU0_PE3_C_TXP<12>")
	)
	(via
		(at 456.835002 -114.403632)
		(size 0.508)
		(drill 0.254)
		(layers "F.Cu" "B.Cu")
		(net "P3E_OCP_CPU0_PE3_C_TXP<12>")
	)
	(segment
		(start 456.434952 -114.403632)
		(end 456.835002 -114.403632)
		(width 0.1143)
		(layer "B.Cu")
		(net "P3E_OCP_CPU0_PE3_C_TXP<12>")
	)
	(segment
		(start 456.320652 -114.517932)
		(end 456.434952 -114.403632)
		(width 0.1143)
		(layer "B.Cu")
		(net "P3E_OCP_CPU0_PE3_C_TXP<12>")
	)
	(segment
		(start 456.320652 -115.231672)
		(end 456.320652 -114.517932)
		(width 0.1143)
		(layer "B.Cu")
		(net "P3E_OCP_CPU0_PE3_C_TXP<12>")
	)
	(segment
		(start 456.692 -115.60302)
		(end 456.320652 -115.231672)
		(width 0.1143)
		(layer "B.Cu")
		(net "P3E_OCP_CPU0_PE3_C_TXP<12>")
	)
	(segment
		(start 453.273922 -114.403632)
		(end 453.634856 -114.403632)
		(width 0.1143)
		(layer "F.Cu")
		(net "P3E_OCP_CPU0_PE3_C_TXP<11>")
	)
	(segment
		(start 453.399906 -112.205516)
		(end 453.399906 -113.556288)
		(width 0.1143)
		(layer "F.Cu")
		(net "P3E_OCP_CPU0_PE3_C_TXP<11>")
	)
	(segment
		(start 453.399906 -113.556288)
		(end 453.120506 -113.835688)
		(width 0.1143)
		(layer "F.Cu")
		(net "P3E_OCP_CPU0_PE3_C_TXP<11>")
	)
	(segment
		(start 453.120506 -114.250216)
		(end 453.273922 -114.403632)
		(width 0.1143)
		(layer "F.Cu")
		(net "P3E_OCP_CPU0_PE3_C_TXP<11>")
	)
	(segment
		(start 453.400922 -112.205516)
		(end 453.399906 -112.205516)
		(width 0.1143)
		(layer "F.Cu")
		(net "P3E_OCP_CPU0_PE3_C_TXP<11>")
	)
	(segment
		(start 453.120506 -113.835688)
		(end 453.120506 -114.250216)
		(width 0.1143)
		(layer "F.Cu")
		(net "P3E_OCP_CPU0_PE3_C_TXP<11>")
	)
	(via
		(at 453.634856 -114.403632)
		(size 0.508)
		(drill 0.254)
		(layers "F.Cu" "B.Cu")
		(net "P3E_OCP_CPU0_PE3_C_TXP<11>")
	)
	(segment
		(start 453.517 -115.60302)
		(end 453.120506 -115.206526)
		(width 0.1143)
		(layer "B.Cu")
		(net "P3E_OCP_CPU0_PE3_C_TXP<11>")
	)
	(segment
		(start 453.234806 -114.403632)
		(end 453.634856 -114.403632)
		(width 0.1143)
		(layer "B.Cu")
		(net "P3E_OCP_CPU0_PE3_C_TXP<11>")
	)
	(segment
		(start 453.120506 -115.206526)
		(end 453.120506 -114.517932)
		(width 0.1143)
		(layer "B.Cu")
		(net "P3E_OCP_CPU0_PE3_C_TXP<11>")
	)
	(segment
		(start 453.120506 -114.517932)
		(end 453.234806 -114.403632)
		(width 0.1143)
		(layer "B.Cu")
		(net "P3E_OCP_CPU0_PE3_C_TXP<11>")
	)
	(segment
		(start 450.20103 -112.205516)
		(end 450.200014 -112.205516)
		(width 0.1143)
		(layer "F.Cu")
		(net "P3E_OCP_CPU0_PE3_C_TXP<10>")
	)
	(segment
		(start 450.200014 -112.205516)
		(end 450.200014 -113.556288)
		(width 0.1143)
		(layer "F.Cu")
		(net "P3E_OCP_CPU0_PE3_C_TXP<10>")
	)
	(segment
		(start 450.05752 -114.403632)
		(end 450.434964 -114.403632)
		(width 0.1143)
		(layer "F.Cu")
		(net "P3E_OCP_CPU0_PE3_C_TXP<10>")
	)
	(segment
		(start 449.920614 -114.266726)
		(end 450.05752 -114.403632)
		(width 0.1143)
		(layer "F.Cu")
		(net "P3E_OCP_CPU0_PE3_C_TXP<10>")
	)
	(segment
		(start 449.920614 -113.835688)
		(end 449.920614 -114.266726)
		(width 0.1143)
		(layer "F.Cu")
		(net "P3E_OCP_CPU0_PE3_C_TXP<10>")
	)
	(segment
		(start 450.200014 -113.556288)
		(end 449.920614 -113.835688)
		(width 0.1143)
		(layer "F.Cu")
		(net "P3E_OCP_CPU0_PE3_C_TXP<10>")
	)
	(via
		(at 450.434964 -114.403632)
		(size 0.508)
		(drill 0.254)
		(layers "F.Cu" "B.Cu")
		(net "P3E_OCP_CPU0_PE3_C_TXP<10>")
	)
	(segment
		(start 450.034914 -114.403632)
		(end 450.434964 -114.403632)
		(width 0.1143)
		(layer "B.Cu")
		(net "P3E_OCP_CPU0_PE3_C_TXP<10>")
	)
	(segment
		(start 450.215 -115.60302)
		(end 449.889372 -115.277392)
		(width 0.1143)
		(layer "B.Cu")
		(net "P3E_OCP_CPU0_PE3_C_TXP<10>")
	)
	(segment
		(start 449.889372 -114.549174)
		(end 450.034914 -114.403632)
		(width 0.1143)
		(layer "B.Cu")
		(net "P3E_OCP_CPU0_PE3_C_TXP<10>")
	)
	(segment
		(start 449.889372 -115.277392)
		(end 449.889372 -114.549174)
		(width 0.1143)
		(layer "B.Cu")
		(net "P3E_OCP_CPU0_PE3_C_TXP<10>")
	)
	(segment
		(start 446.375028 -114.403632)
		(end 445.964818 -114.403632)
		(width 0.1143)
		(layer "F.Cu")
		(net "P3E_OCP_CPU0_PE3_C_TXN<9>")
	)
	(segment
		(start 446.200784 -112.205516)
		(end 446.199768 -112.205516)
		(width 0.1143)
		(layer "F.Cu")
		(net "P3E_OCP_CPU0_PE3_C_TXN<9>")
	)
	(segment
		(start 446.199768 -113.556288)
		(end 446.479168 -113.835688)
		(width 0.1143)
		(layer "F.Cu")
		(net "P3E_OCP_CPU0_PE3_C_TXN<9>")
	)
	(segment
		(start 446.199768 -112.205516)
		(end 446.199768 -113.556288)
		(width 0.1143)
		(layer "F.Cu")
		(net "P3E_OCP_CPU0_PE3_C_TXN<9>")
	)
	(segment
		(start 446.479168 -113.835688)
		(end 446.479168 -114.299492)
		(width 0.1143)
		(layer "F.Cu")
		(net "P3E_OCP_CPU0_PE3_C_TXN<9>")
	)
	(segment
		(start 446.479168 -114.299492)
		(end 446.375028 -114.403632)
		(width 0.1143)
		(layer "F.Cu")
		(net "P3E_OCP_CPU0_PE3_C_TXN<9>")
	)
	(via
		(at 445.964818 -114.403632)
		(size 0.508)
		(drill 0.254)
		(layers "F.Cu" "B.Cu")
		(net "P3E_OCP_CPU0_PE3_C_TXN<9>")
	)
	(segment
		(start 446.024 -115.60302)
		(end 446.46088 -115.16614)
		(width 0.1143)
		(layer "B.Cu")
		(net "P3E_OCP_CPU0_PE3_C_TXN<9>")
	)
	(segment
		(start 446.46088 -114.5413)
		(end 446.323212 -114.403632)
		(width 0.1143)
		(layer "B.Cu")
		(net "P3E_OCP_CPU0_PE3_C_TXN<9>")
	)
	(segment
		(start 446.46088 -115.16614)
		(end 446.46088 -114.5413)
		(width 0.1143)
		(layer "B.Cu")
		(net "P3E_OCP_CPU0_PE3_C_TXN<9>")
	)
	(segment
		(start 446.323212 -114.403632)
		(end 445.964818 -114.403632)
		(width 0.1143)
		(layer "B.Cu")
		(net "P3E_OCP_CPU0_PE3_C_TXN<9>")
	)
	(segment
		(start 442.999876 -112.205516)
		(end 442.999876 -113.556288)
		(width 0.1143)
		(layer "F.Cu")
		(net "P3E_OCP_CPU0_PE3_C_TXN<8>")
	)
	(segment
		(start 443.279276 -114.289332)
		(end 443.164976 -114.403632)
		(width 0.1143)
		(layer "F.Cu")
		(net "P3E_OCP_CPU0_PE3_C_TXN<8>")
	)
	(segment
		(start 443.279276 -113.835688)
		(end 443.279276 -114.289332)
		(width 0.1143)
		(layer "F.Cu")
		(net "P3E_OCP_CPU0_PE3_C_TXN<8>")
	)
	(segment
		(start 442.999876 -113.556288)
		(end 443.279276 -113.835688)
		(width 0.1143)
		(layer "F.Cu")
		(net "P3E_OCP_CPU0_PE3_C_TXN<8>")
	)
	(segment
		(start 443.000892 -112.205516)
		(end 442.999876 -112.205516)
		(width 0.1143)
		(layer "F.Cu")
		(net "P3E_OCP_CPU0_PE3_C_TXN<8>")
	)
	(segment
		(start 443.164976 -114.403632)
		(end 442.764926 -114.403632)
		(width 0.1143)
		(layer "F.Cu")
		(net "P3E_OCP_CPU0_PE3_C_TXN<8>")
	)
	(via
		(at 442.764926 -114.403632)
		(size 0.508)
		(drill 0.254)
		(layers "F.Cu" "B.Cu")
		(net "P3E_OCP_CPU0_PE3_C_TXN<8>")
	)
	(segment
		(start 442.849 -115.60302)
		(end 443.26937 -115.18265)
		(width 0.1143)
		(layer "B.Cu")
		(net "P3E_OCP_CPU0_PE3_C_TXN<8>")
	)
	(segment
		(start 443.26937 -115.18265)
		(end 443.26937 -114.532156)
		(width 0.1143)
		(layer "B.Cu")
		(net "P3E_OCP_CPU0_PE3_C_TXN<8>")
	)
	(segment
		(start 443.26937 -114.532156)
		(end 443.140846 -114.403632)
		(width 0.1143)
		(layer "B.Cu")
		(net "P3E_OCP_CPU0_PE3_C_TXN<8>")
	)
	(segment
		(start 443.140846 -114.403632)
		(end 442.764926 -114.403632)
		(width 0.1143)
		(layer "B.Cu")
		(net "P3E_OCP_CPU0_PE3_C_TXN<8>")
	)
	(segment
		(start 465.679282 -113.835688)
		(end 465.679282 -114.32413)
		(width 0.1143)
		(layer "F.Cu")
		(net "P3E_OCP_CPU0_PE3_C_TXN<15>")
	)
	(segment
		(start 465.399882 -113.556288)
		(end 465.679282 -113.835688)
		(width 0.1143)
		(layer "F.Cu")
		(net "P3E_OCP_CPU0_PE3_C_TXN<15>")
	)
	(segment
		(start 465.400898 -112.205516)
		(end 465.399882 -112.205516)
		(width 0.1143)
		(layer "F.Cu")
		(net "P3E_OCP_CPU0_PE3_C_TXN<15>")
	)
	(segment
		(start 465.399882 -112.205516)
		(end 465.399882 -113.556288)
		(width 0.1143)
		(layer "F.Cu")
		(net "P3E_OCP_CPU0_PE3_C_TXN<15>")
	)
	(segment
		(start 465.551012 -114.4524)
		(end 465.19973 -114.4524)
		(width 0.1143)
		(layer "F.Cu")
		(net "P3E_OCP_CPU0_PE3_C_TXN<15>")
	)
	(segment
		(start 465.679282 -114.32413)
		(end 465.551012 -114.4524)
		(width 0.1143)
		(layer "F.Cu")
		(net "P3E_OCP_CPU0_PE3_C_TXN<15>")
	)
	(via
		(at 465.19973 -114.4524)
		(size 0.508)
		(drill 0.254)
		(layers "F.Cu" "B.Cu")
		(net "P3E_OCP_CPU0_PE3_C_TXN<15>")
	)
	(segment
		(start 465.71408 -114.5667)
		(end 465.59978 -114.4524)
		(width 0.1143)
		(layer "B.Cu")
		(net "P3E_OCP_CPU0_PE3_C_TXN<15>")
	)
	(segment
		(start 465.59978 -114.4524)
		(end 465.19973 -114.4524)
		(width 0.1143)
		(layer "B.Cu")
		(net "P3E_OCP_CPU0_PE3_C_TXN<15>")
	)
	(segment
		(start 465.328 -115.60302)
		(end 465.71408 -115.21694)
		(width 0.1143)
		(layer "B.Cu")
		(net "P3E_OCP_CPU0_PE3_C_TXN<15>")
	)
	(segment
		(start 465.71408 -115.21694)
		(end 465.71408 -114.5667)
		(width 0.1143)
		(layer "B.Cu")
		(net "P3E_OCP_CPU0_PE3_C_TXN<15>")
	)
	(segment
		(start 462.201006 -112.205516)
		(end 462.19999 -112.205516)
		(width 0.1143)
		(layer "F.Cu")
		(net "P3E_OCP_CPU0_PE3_C_TXN<14>")
	)
	(segment
		(start 462.47939 -114.266726)
		(end 462.342484 -114.403632)
		(width 0.1143)
		(layer "F.Cu")
		(net "P3E_OCP_CPU0_PE3_C_TXN<14>")
	)
	(segment
		(start 462.342484 -114.403632)
		(end 461.96504 -114.403632)
		(width 0.1143)
		(layer "F.Cu")
		(net "P3E_OCP_CPU0_PE3_C_TXN<14>")
	)
	(segment
		(start 462.47939 -113.835688)
		(end 462.47939 -114.266726)
		(width 0.1143)
		(layer "F.Cu")
		(net "P3E_OCP_CPU0_PE3_C_TXN<14>")
	)
	(segment
		(start 462.19999 -112.205516)
		(end 462.19999 -113.556288)
		(width 0.1143)
		(layer "F.Cu")
		(net "P3E_OCP_CPU0_PE3_C_TXN<14>")
	)
	(segment
		(start 462.19999 -113.556288)
		(end 462.47939 -113.835688)
		(width 0.1143)
		(layer "F.Cu")
		(net "P3E_OCP_CPU0_PE3_C_TXN<14>")
	)
	(via
		(at 461.96504 -114.403632)
		(size 0.508)
		(drill 0.254)
		(layers "F.Cu" "B.Cu")
		(net "P3E_OCP_CPU0_PE3_C_TXN<14>")
	)
	(segment
		(start 462.457292 -115.171728)
		(end 462.457292 -114.526822)
		(width 0.1143)
		(layer "B.Cu")
		(net "P3E_OCP_CPU0_PE3_C_TXN<14>")
	)
	(segment
		(start 462.457292 -114.526822)
		(end 462.334102 -114.403632)
		(width 0.1143)
		(layer "B.Cu")
		(net "P3E_OCP_CPU0_PE3_C_TXN<14>")
	)
	(segment
		(start 462.026 -115.60302)
		(end 462.457292 -115.171728)
		(width 0.1143)
		(layer "B.Cu")
		(net "P3E_OCP_CPU0_PE3_C_TXN<14>")
	)
	(segment
		(start 462.334102 -114.403632)
		(end 461.96504 -114.403632)
		(width 0.1143)
		(layer "B.Cu")
		(net "P3E_OCP_CPU0_PE3_C_TXN<14>")
	)
	(segment
		(start 458.999844 -112.205516)
		(end 458.999844 -113.556288)
		(width 0.1143)
		(layer "F.Cu")
		(net "P3E_OCP_CPU0_PE3_C_TXN<13>")
	)
	(segment
		(start 458.999844 -113.556288)
		(end 459.279244 -113.835688)
		(width 0.1143)
		(layer "F.Cu")
		(net "P3E_OCP_CPU0_PE3_C_TXN<13>")
	)
	(segment
		(start 459.00086 -112.205516)
		(end 458.999844 -112.205516)
		(width 0.1143)
		(layer "F.Cu")
		(net "P3E_OCP_CPU0_PE3_C_TXN<13>")
	)
	(segment
		(start 459.279244 -114.316002)
		(end 459.191614 -114.403632)
		(width 0.1143)
		(layer "F.Cu")
		(net "P3E_OCP_CPU0_PE3_C_TXN<13>")
	)
	(segment
		(start 459.279244 -113.835688)
		(end 459.279244 -114.316002)
		(width 0.1143)
		(layer "F.Cu")
		(net "P3E_OCP_CPU0_PE3_C_TXN<13>")
	)
	(segment
		(start 459.191614 -114.403632)
		(end 458.764894 -114.403632)
		(width 0.1143)
		(layer "F.Cu")
		(net "P3E_OCP_CPU0_PE3_C_TXN<13>")
	)
	(via
		(at 458.764894 -114.403632)
		(size 0.508)
		(drill 0.254)
		(layers "F.Cu" "B.Cu")
		(net "P3E_OCP_CPU0_PE3_C_TXN<13>")
	)
	(segment
		(start 459.151736 -114.403632)
		(end 458.764894 -114.403632)
		(width 0.1143)
		(layer "B.Cu")
		(net "P3E_OCP_CPU0_PE3_C_TXN<13>")
	)
	(segment
		(start 459.26629 -115.18773)
		(end 459.26629 -114.518186)
		(width 0.1143)
		(layer "B.Cu")
		(net "P3E_OCP_CPU0_PE3_C_TXN<13>")
	)
	(segment
		(start 459.26629 -114.518186)
		(end 459.151736 -114.403632)
		(width 0.1143)
		(layer "B.Cu")
		(net "P3E_OCP_CPU0_PE3_C_TXN<13>")
	)
	(segment
		(start 458.851 -115.60302)
		(end 459.26629 -115.18773)
		(width 0.1143)
		(layer "B.Cu")
		(net "P3E_OCP_CPU0_PE3_C_TXN<13>")
	)
	(segment
		(start 456.079352 -114.258344)
		(end 455.934064 -114.403632)
		(width 0.1143)
		(layer "F.Cu")
		(net "P3E_OCP_CPU0_PE3_C_TXN<12>")
	)
	(segment
		(start 455.799952 -113.556288)
		(end 456.079352 -113.835688)
		(width 0.1143)
		(layer "F.Cu")
		(net "P3E_OCP_CPU0_PE3_C_TXN<12>")
	)
	(segment
		(start 455.934064 -114.403632)
		(end 455.565002 -114.403632)
		(width 0.1143)
		(layer "F.Cu")
		(net "P3E_OCP_CPU0_PE3_C_TXN<12>")
	)
	(segment
		(start 456.079352 -113.835688)
		(end 456.079352 -114.258344)
		(width 0.1143)
		(layer "F.Cu")
		(net "P3E_OCP_CPU0_PE3_C_TXN<12>")
	)
	(segment
		(start 455.800968 -112.205516)
		(end 455.799952 -112.205516)
		(width 0.1143)
		(layer "F.Cu")
		(net "P3E_OCP_CPU0_PE3_C_TXN<12>")
	)
	(segment
		(start 455.799952 -112.205516)
		(end 455.799952 -113.556288)
		(width 0.1143)
		(layer "F.Cu")
		(net "P3E_OCP_CPU0_PE3_C_TXN<12>")
	)
	(via
		(at 455.565002 -114.403632)
		(size 0.508)
		(drill 0.254)
		(layers "F.Cu" "B.Cu")
		(net "P3E_OCP_CPU0_PE3_C_TXN<12>")
	)
	(segment
		(start 455.965052 -114.403632)
		(end 455.565002 -114.403632)
		(width 0.1143)
		(layer "B.Cu")
		(net "P3E_OCP_CPU0_PE3_C_TXN<12>")
	)
	(segment
		(start 455.676 -115.60302)
		(end 456.079352 -115.199668)
		(width 0.1143)
		(layer "B.Cu")
		(net "P3E_OCP_CPU0_PE3_C_TXN<12>")
	)
	(segment
		(start 456.079352 -115.199668)
		(end 456.079352 -114.517932)
		(width 0.1143)
		(layer "B.Cu")
		(net "P3E_OCP_CPU0_PE3_C_TXN<12>")
	)
	(segment
		(start 456.079352 -114.517932)
		(end 455.965052 -114.403632)
		(width 0.1143)
		(layer "B.Cu")
		(net "P3E_OCP_CPU0_PE3_C_TXN<12>")
	)
	(segment
		(start 452.599806 -113.556288)
		(end 452.879206 -113.835688)
		(width 0.1143)
		(layer "F.Cu")
		(net "P3E_OCP_CPU0_PE3_C_TXN<11>")
	)
	(segment
		(start 452.600822 -112.205516)
		(end 452.599806 -112.205516)
		(width 0.1143)
		(layer "F.Cu")
		(net "P3E_OCP_CPU0_PE3_C_TXN<11>")
	)
	(segment
		(start 452.879206 -113.835688)
		(end 452.879206 -114.250216)
		(width 0.1143)
		(layer "F.Cu")
		(net "P3E_OCP_CPU0_PE3_C_TXN<11>")
	)
	(segment
		(start 452.72579 -114.403632)
		(end 452.364856 -114.403632)
		(width 0.1143)
		(layer "F.Cu")
		(net "P3E_OCP_CPU0_PE3_C_TXN<11>")
	)
	(segment
		(start 452.599806 -112.205516)
		(end 452.599806 -113.556288)
		(width 0.1143)
		(layer "F.Cu")
		(net "P3E_OCP_CPU0_PE3_C_TXN<11>")
	)
	(segment
		(start 452.879206 -114.250216)
		(end 452.72579 -114.403632)
		(width 0.1143)
		(layer "F.Cu")
		(net "P3E_OCP_CPU0_PE3_C_TXN<11>")
	)
	(via
		(at 452.364856 -114.403632)
		(size 0.508)
		(drill 0.254)
		(layers "F.Cu" "B.Cu")
		(net "P3E_OCP_CPU0_PE3_C_TXN<11>")
	)
	(segment
		(start 452.764906 -114.403632)
		(end 452.364856 -114.403632)
		(width 0.1143)
		(layer "B.Cu")
		(net "P3E_OCP_CPU0_PE3_C_TXN<11>")
	)
	(segment
		(start 452.879206 -115.224814)
		(end 452.879206 -114.517932)
		(width 0.1143)
		(layer "B.Cu")
		(net "P3E_OCP_CPU0_PE3_C_TXN<11>")
	)
	(segment
		(start 452.879206 -114.517932)
		(end 452.764906 -114.403632)
		(width 0.1143)
		(layer "B.Cu")
		(net "P3E_OCP_CPU0_PE3_C_TXN<11>")
	)
	(segment
		(start 452.501 -115.60302)
		(end 452.879206 -115.224814)
		(width 0.1143)
		(layer "B.Cu")
		(net "P3E_OCP_CPU0_PE3_C_TXN<11>")
	)
	(segment
		(start 449.679314 -114.266726)
		(end 449.542408 -114.403632)
		(width 0.1143)
		(layer "F.Cu")
		(net "P3E_OCP_CPU0_PE3_C_TXN<10>")
	)
	(segment
		(start 449.40093 -112.205516)
		(end 449.399914 -112.205516)
		(width 0.1143)
		(layer "F.Cu")
		(net "P3E_OCP_CPU0_PE3_C_TXN<10>")
	)
	(segment
		(start 449.679314 -113.835688)
		(end 449.679314 -114.266726)
		(width 0.1143)
		(layer "F.Cu")
		(net "P3E_OCP_CPU0_PE3_C_TXN<10>")
	)
	(segment
		(start 449.399914 -112.205516)
		(end 449.399914 -113.556288)
		(width 0.1143)
		(layer "F.Cu")
		(net "P3E_OCP_CPU0_PE3_C_TXN<10>")
	)
	(segment
		(start 449.399914 -113.556288)
		(end 449.679314 -113.835688)
		(width 0.1143)
		(layer "F.Cu")
		(net "P3E_OCP_CPU0_PE3_C_TXN<10>")
	)
	(segment
		(start 449.542408 -114.403632)
		(end 449.164964 -114.403632)
		(width 0.1143)
		(layer "F.Cu")
		(net "P3E_OCP_CPU0_PE3_C_TXN<10>")
	)
	(via
		(at 449.164964 -114.403632)
		(size 0.508)
		(drill 0.254)
		(layers "F.Cu" "B.Cu")
		(net "P3E_OCP_CPU0_PE3_C_TXN<10>")
	)
	(segment
		(start 449.199 -115.60302)
		(end 449.648072 -115.153948)
		(width 0.1143)
		(layer "B.Cu")
		(net "P3E_OCP_CPU0_PE3_C_TXN<10>")
	)
	(segment
		(start 449.648072 -114.517932)
		(end 449.533772 -114.403632)
		(width 0.1143)
		(layer "B.Cu")
		(net "P3E_OCP_CPU0_PE3_C_TXN<10>")
	)
	(segment
		(start 449.648072 -115.153948)
		(end 449.648072 -114.517932)
		(width 0.1143)
		(layer "B.Cu")
		(net "P3E_OCP_CPU0_PE3_C_TXN<10>")
	)
	(segment
		(start 449.533772 -114.403632)
		(end 449.164964 -114.403632)
		(width 0.1143)
		(layer "B.Cu")
		(net "P3E_OCP_CPU0_PE3_C_TXN<10>")
	)
	(segment
		(start 377.009406 -9.696196)
		(end 376.678444 -10.027158)
		(width 0.1143)
		(layer "F.Cu")
		(net "P3E_CPU0_PE2_SS_C_TXP<9>")
	)
	(segment
		(start 376.685048 -7.789926)
		(end 376.685048 -8.5979)
		(width 0.1143)
		(layer "F.Cu")
		(net "P3E_CPU0_PE2_SS_C_TXP<9>")
	)
	(segment
		(start 376.685048 -8.5979)
		(end 377.009406 -8.922258)
		(width 0.1143)
		(layer "F.Cu")
		(net "P3E_CPU0_PE2_SS_C_TXP<9>")
	)
	(segment
		(start 377.009406 -8.922258)
		(end 377.009406 -9.696196)
		(width 0.1143)
		(layer "F.Cu")
		(net "P3E_CPU0_PE2_SS_C_TXP<9>")
	)
	(segment
		(start 379.593094 -8.89)
		(end 379.593094 -9.269476)
		(width 0.1143)
		(layer "F.Cu")
		(net "P3E_CPU0_PE2_SS_C_TXN<8>")
	)
	(segment
		(start 379.4887 -9.725914)
		(end 379.815344 -10.052558)
		(width 0.1143)
		(layer "F.Cu")
		(net "P3E_CPU0_PE2_SS_C_TXN<8>")
	)
	(segment
		(start 379.885194 -7.789926)
		(end 379.885194 -8.5979)
		(width 0.1143)
		(layer "F.Cu")
		(net "P3E_CPU0_PE2_SS_C_TXN<8>")
	)
	(segment
		(start 379.593094 -9.269476)
		(end 379.4887 -9.37387)
		(width 0.1143)
		(layer "F.Cu")
		(net "P3E_CPU0_PE2_SS_C_TXN<8>")
	)
	(segment
		(start 379.885194 -8.5979)
		(end 379.593094 -8.89)
		(width 0.1143)
		(layer "F.Cu")
		(net "P3E_CPU0_PE2_SS_C_TXN<8>")
	)
	(segment
		(start 379.4887 -9.37387)
		(end 379.4887 -9.725914)
		(width 0.1143)
		(layer "F.Cu")
		(net "P3E_CPU0_PE2_SS_C_TXN<8>")
	)
	(segment
		(start 393.578842 -9.705086)
		(end 393.578842 -8.905748)
		(width 0.1143)
		(layer "F.Cu")
		(net "P3E_CPU0_PE2_SS_C_TXP<7>")
	)
	(segment
		(start 393.270486 -8.597392)
		(end 393.270486 -7.789672)
		(width 0.1143)
		(layer "F.Cu")
		(net "P3E_CPU0_PE2_SS_C_TXP<7>")
	)
	(segment
		(start 393.578842 -8.905748)
		(end 393.270486 -8.597392)
		(width 0.1143)
		(layer "F.Cu")
		(net "P3E_CPU0_PE2_SS_C_TXP<7>")
	)
	(segment
		(start 393.254992 -10.028936)
		(end 393.578842 -9.705086)
		(width 0.1143)
		(layer "F.Cu")
		(net "P3E_CPU0_PE2_SS_C_TXP<7>")
	)
	(segment
		(start 395.670786 -8.597392)
		(end 395.670786 -7.789672)
		(width 0.1143)
		(layer "F.Cu")
		(net "P3E_CPU0_PE2_SS_C_TXP<6>")
	)
	(segment
		(start 395.902942 -8.829548)
		(end 395.670786 -8.597392)
		(width 0.1143)
		(layer "F.Cu")
		(net "P3E_CPU0_PE2_SS_C_TXP<6>")
	)
	(segment
		(start 395.579092 -10.079736)
		(end 395.902942 -9.755886)
		(width 0.1143)
		(layer "F.Cu")
		(net "P3E_CPU0_PE2_SS_C_TXP<6>")
	)
	(segment
		(start 395.902942 -9.755886)
		(end 395.902942 -8.829548)
		(width 0.1143)
		(layer "F.Cu")
		(net "P3E_CPU0_PE2_SS_C_TXP<6>")
	)
	(segment
		(start 398.030192 -10.028936)
		(end 398.354042 -9.705086)
		(width 0.1143)
		(layer "F.Cu")
		(net "P3E_CPU0_PE2_SS_C_TXP<5>")
	)
	(segment
		(start 398.354042 -8.880348)
		(end 398.071086 -8.597392)
		(width 0.1143)
		(layer "F.Cu")
		(net "P3E_CPU0_PE2_SS_C_TXP<5>")
	)
	(segment
		(start 398.354042 -9.705086)
		(end 398.354042 -8.880348)
		(width 0.1143)
		(layer "F.Cu")
		(net "P3E_CPU0_PE2_SS_C_TXP<5>")
	)
	(segment
		(start 398.071086 -8.597392)
		(end 398.071086 -7.789672)
		(width 0.1143)
		(layer "F.Cu")
		(net "P3E_CPU0_PE2_SS_C_TXP<5>")
	)
	(segment
		(start 400.471386 -8.597392)
		(end 400.471386 -7.789672)
		(width 0.1143)
		(layer "F.Cu")
		(net "P3E_CPU0_PE2_SS_C_TXP<4>")
	)
	(segment
		(start 400.430492 -10.028936)
		(end 400.754342 -9.705086)
		(width 0.1143)
		(layer "F.Cu")
		(net "P3E_CPU0_PE2_SS_C_TXP<4>")
	)
	(segment
		(start 400.754342 -8.880348)
		(end 400.471386 -8.597392)
		(width 0.1143)
		(layer "F.Cu")
		(net "P3E_CPU0_PE2_SS_C_TXP<4>")
	)
	(segment
		(start 400.754342 -9.705086)
		(end 400.754342 -8.880348)
		(width 0.1143)
		(layer "F.Cu")
		(net "P3E_CPU0_PE2_SS_C_TXP<4>")
	)
	(segment
		(start 402.830792 -10.028936)
		(end 403.154642 -9.705086)
		(width 0.1143)
		(layer "F.Cu")
		(net "P3E_CPU0_PE2_SS_C_TXP<3>")
	)
	(segment
		(start 403.154642 -9.705086)
		(end 403.154642 -8.880348)
		(width 0.1143)
		(layer "F.Cu")
		(net "P3E_CPU0_PE2_SS_C_TXP<3>")
	)
	(segment
		(start 402.871686 -8.597392)
		(end 402.871686 -7.789672)
		(width 0.1143)
		(layer "F.Cu")
		(net "P3E_CPU0_PE2_SS_C_TXP<3>")
	)
	(segment
		(start 403.154642 -8.880348)
		(end 402.871686 -8.597392)
		(width 0.1143)
		(layer "F.Cu")
		(net "P3E_CPU0_PE2_SS_C_TXP<3>")
	)
	(segment
		(start 405.231092 -10.028936)
		(end 405.554942 -9.705086)
		(width 0.1143)
		(layer "F.Cu")
		(net "P3E_CPU0_PE2_SS_C_TXP<2>")
	)
	(segment
		(start 405.271986 -8.597392)
		(end 405.271986 -7.789672)
		(width 0.1143)
		(layer "F.Cu")
		(net "P3E_CPU0_PE2_SS_C_TXP<2>")
	)
	(segment
		(start 405.554942 -9.705086)
		(end 405.554942 -8.880348)
		(width 0.1143)
		(layer "F.Cu")
		(net "P3E_CPU0_PE2_SS_C_TXP<2>")
	)
	(segment
		(start 405.554942 -8.880348)
		(end 405.271986 -8.597392)
		(width 0.1143)
		(layer "F.Cu")
		(net "P3E_CPU0_PE2_SS_C_TXP<2>")
	)
	(segment
		(start 408.472386 -8.597392)
		(end 408.472386 -7.789672)
		(width 0.1143)
		(layer "F.Cu")
		(net "P3E_CPU0_PE2_SS_C_TXP<1>")
	)
	(segment
		(start 408.196542 -8.873236)
		(end 408.472386 -8.597392)
		(width 0.1143)
		(layer "F.Cu")
		(net "P3E_CPU0_PE2_SS_C_TXP<1>")
	)
	(segment
		(start 408.196542 -9.703816)
		(end 408.196542 -8.873236)
		(width 0.1143)
		(layer "F.Cu")
		(net "P3E_CPU0_PE2_SS_C_TXP<1>")
	)
	(segment
		(start 408.520392 -10.027666)
		(end 408.196542 -9.703816)
		(width 0.1143)
		(layer "F.Cu")
		(net "P3E_CPU0_PE2_SS_C_TXP<1>")
	)
	(segment
		(start 362.285026 -7.789926)
		(end 362.285026 -8.5979)
		(width 0.1143)
		(layer "F.Cu")
		(net "P3E_CPU0_PE2_SS_C_TXP<15>")
	)
	(segment
		(start 362.600494 -8.913368)
		(end 362.600494 -9.703308)
		(width 0.1143)
		(layer "F.Cu")
		(net "P3E_CPU0_PE2_SS_C_TXP<15>")
	)
	(segment
		(start 362.600494 -9.703308)
		(end 362.276644 -10.027158)
		(width 0.1143)
		(layer "F.Cu")
		(net "P3E_CPU0_PE2_SS_C_TXP<15>")
	)
	(segment
		(start 362.285026 -8.5979)
		(end 362.600494 -8.913368)
		(width 0.1143)
		(layer "F.Cu")
		(net "P3E_CPU0_PE2_SS_C_TXP<15>")
	)
	(segment
		(start 365.485172 -7.789926)
		(end 365.485172 -8.5979)
		(width 0.1143)
		(layer "F.Cu")
		(net "P3E_CPU0_PE2_SS_C_TXP<14>")
	)
	(segment
		(start 365.175292 -9.712706)
		(end 365.489744 -10.027158)
		(width 0.1143)
		(layer "F.Cu")
		(net "P3E_CPU0_PE2_SS_C_TXP<14>")
	)
	(segment
		(start 365.175292 -8.90778)
		(end 365.175292 -9.712706)
		(width 0.1143)
		(layer "F.Cu")
		(net "P3E_CPU0_PE2_SS_C_TXP<14>")
	)
	(segment
		(start 365.485172 -8.5979)
		(end 365.175292 -8.90778)
		(width 0.1143)
		(layer "F.Cu")
		(net "P3E_CPU0_PE2_SS_C_TXP<14>")
	)
	(segment
		(start 367.364518 -8.8773)
		(end 367.364518 -9.739884)
		(width 0.1143)
		(layer "F.Cu")
		(net "P3E_CPU0_PE2_SS_C_TXP<13>")
	)
	(segment
		(start 367.364518 -9.739884)
		(end 367.077244 -10.027158)
		(width 0.1143)
		(layer "F.Cu")
		(net "P3E_CPU0_PE2_SS_C_TXP<13>")
	)
	(segment
		(start 367.085118 -7.789926)
		(end 367.085118 -8.5979)
		(width 0.1143)
		(layer "F.Cu")
		(net "P3E_CPU0_PE2_SS_C_TXP<13>")
	)
	(segment
		(start 367.085118 -8.5979)
		(end 367.364518 -8.8773)
		(width 0.1143)
		(layer "F.Cu")
		(net "P3E_CPU0_PE2_SS_C_TXP<13>")
	)
	(segment
		(start 369.786408 -8.899398)
		(end 369.786408 -9.718294)
		(width 0.1143)
		(layer "F.Cu")
		(net "P3E_CPU0_PE2_SS_C_TXP<12>")
	)
	(segment
		(start 369.485164 -7.789926)
		(end 369.485164 -8.598154)
		(width 0.1143)
		(layer "F.Cu")
		(net "P3E_CPU0_PE2_SS_C_TXP<12>")
	)
	(segment
		(start 369.485164 -8.598154)
		(end 369.786408 -8.899398)
		(width 0.1143)
		(layer "F.Cu")
		(net "P3E_CPU0_PE2_SS_C_TXP<12>")
	)
	(segment
		(start 369.786408 -9.718294)
		(end 369.477544 -10.027158)
		(width 0.1143)
		(layer "F.Cu")
		(net "P3E_CPU0_PE2_SS_C_TXP<12>")
	)
	(segment
		(start 372.444772 -8.838184)
		(end 372.444772 -9.705086)
		(width 0.1143)
		(layer "F.Cu")
		(net "P3E_CPU0_PE2_SS_C_TXP<11>")
	)
	(segment
		(start 372.685056 -8.5979)
		(end 372.444772 -8.838184)
		(width 0.1143)
		(layer "F.Cu")
		(net "P3E_CPU0_PE2_SS_C_TXP<11>")
	)
	(segment
		(start 372.685056 -7.789926)
		(end 372.685056 -8.5979)
		(width 0.1143)
		(layer "F.Cu")
		(net "P3E_CPU0_PE2_SS_C_TXP<11>")
	)
	(segment
		(start 372.444772 -9.705086)
		(end 372.766844 -10.027158)
		(width 0.1143)
		(layer "F.Cu")
		(net "P3E_CPU0_PE2_SS_C_TXP<11>")
	)
	(segment
		(start 374.601232 -8.91413)
		(end 374.601232 -9.70407)
		(width 0.1143)
		(layer "F.Cu")
		(net "P3E_CPU0_PE2_SS_C_TXP<10>")
	)
	(segment
		(start 374.601232 -9.70407)
		(end 374.278144 -10.027158)
		(width 0.1143)
		(layer "F.Cu")
		(net "P3E_CPU0_PE2_SS_C_TXP<10>")
	)
	(segment
		(start 374.285002 -7.789926)
		(end 374.285002 -8.5979)
		(width 0.1143)
		(layer "F.Cu")
		(net "P3E_CPU0_PE2_SS_C_TXP<10>")
	)
	(segment
		(start 374.285002 -8.5979)
		(end 374.601232 -8.91413)
		(width 0.1143)
		(layer "F.Cu")
		(net "P3E_CPU0_PE2_SS_C_TXP<10>")
	)
	(segment
		(start 410.351986 -8.876792)
		(end 410.072586 -8.597392)
		(width 0.1143)
		(layer "F.Cu")
		(net "P3E_CPU0_PE2_SS_C_TXP<0>")
	)
	(segment
		(start 410.252672 -9.704324)
		(end 410.351986 -9.60501)
		(width 0.1143)
		(layer "F.Cu")
		(net "P3E_CPU0_PE2_SS_C_TXP<0>")
	)
	(segment
		(start 410.072586 -8.597392)
		(end 410.072586 -7.789672)
		(width 0.1143)
		(layer "F.Cu")
		(net "P3E_CPU0_PE2_SS_C_TXP<0>")
	)
	(segment
		(start 410.252672 -10.224008)
		(end 410.252672 -9.704324)
		(width 0.1143)
		(layer "F.Cu")
		(net "P3E_CPU0_PE2_SS_C_TXP<0>")
	)
	(segment
		(start 409.928822 -10.547858)
		(end 410.252672 -10.224008)
		(width 0.1143)
		(layer "F.Cu")
		(net "P3E_CPU0_PE2_SS_C_TXP<0>")
	)
	(segment
		(start 410.351986 -9.60501)
		(end 410.351986 -8.876792)
		(width 0.1143)
		(layer "F.Cu")
		(net "P3E_CPU0_PE2_SS_C_TXP<0>")
	)
	(segment
		(start 377.250706 -9.71042)
		(end 377.567444 -10.027158)
		(width 0.1143)
		(layer "F.Cu")
		(net "P3E_CPU0_PE2_SS_C_TXN<9>")
	)
	(segment
		(start 377.485148 -8.5979)
		(end 377.250706 -8.832342)
		(width 0.1143)
		(layer "F.Cu")
		(net "P3E_CPU0_PE2_SS_C_TXN<9>")
	)
	(segment
		(start 377.250706 -8.832342)
		(end 377.250706 -9.71042)
		(width 0.1143)
		(layer "F.Cu")
		(net "P3E_CPU0_PE2_SS_C_TXN<9>")
	)
	(segment
		(start 377.485148 -7.789926)
		(end 377.485148 -8.5979)
		(width 0.1143)
		(layer "F.Cu")
		(net "P3E_CPU0_PE2_SS_C_TXN<9>")
	)
	(segment
		(start 379.2474 -9.273794)
		(end 379.2474 -9.731502)
		(width 0.1143)
		(layer "F.Cu")
		(net "P3E_CPU0_PE2_SS_C_TXP<8>")
	)
	(segment
		(start 379.351794 -8.8646)
		(end 379.351794 -9.1694)
		(width 0.1143)
		(layer "F.Cu")
		(net "P3E_CPU0_PE2_SS_C_TXP<8>")
	)
	(segment
		(start 379.085094 -8.5979)
		(end 379.351794 -8.8646)
		(width 0.1143)
		(layer "F.Cu")
		(net "P3E_CPU0_PE2_SS_C_TXP<8>")
	)
	(segment
		(start 379.351794 -9.1694)
		(end 379.2474 -9.273794)
		(width 0.1143)
		(layer "F.Cu")
		(net "P3E_CPU0_PE2_SS_C_TXP<8>")
	)
	(segment
		(start 379.2474 -9.731502)
		(end 378.926344 -10.052558)
		(width 0.1143)
		(layer "F.Cu")
		(net "P3E_CPU0_PE2_SS_C_TXP<8>")
	)
	(segment
		(start 379.085094 -7.789926)
		(end 379.085094 -8.5979)
		(width 0.1143)
		(layer "F.Cu")
		(net "P3E_CPU0_PE2_SS_C_TXP<8>")
	)
	(segment
		(start 394.070586 -8.597392)
		(end 394.070586 -7.789672)
		(width 0.1143)
		(layer "F.Cu")
		(net "P3E_CPU0_PE2_SS_C_TXN<7>")
	)
	(segment
		(start 393.820142 -8.847836)
		(end 394.070586 -8.597392)
		(width 0.1143)
		(layer "F.Cu")
		(net "P3E_CPU0_PE2_SS_C_TXN<7>")
	)
	(segment
		(start 393.820142 -9.705086)
		(end 393.820142 -8.847836)
		(width 0.1143)
		(layer "F.Cu")
		(net "P3E_CPU0_PE2_SS_C_TXN<7>")
	)
	(segment
		(start 394.143992 -10.028936)
		(end 393.820142 -9.705086)
		(width 0.1143)
		(layer "F.Cu")
		(net "P3E_CPU0_PE2_SS_C_TXN<7>")
	)
	(segment
		(start 396.144242 -8.924036)
		(end 396.470886 -8.597392)
		(width 0.1143)
		(layer "F.Cu")
		(net "P3E_CPU0_PE2_SS_C_TXN<6>")
	)
	(segment
		(start 396.470886 -8.597392)
		(end 396.470886 -7.789672)
		(width 0.1143)
		(layer "F.Cu")
		(net "P3E_CPU0_PE2_SS_C_TXN<6>")
	)
	(segment
		(start 396.144242 -9.755886)
		(end 396.144242 -8.924036)
		(width 0.1143)
		(layer "F.Cu")
		(net "P3E_CPU0_PE2_SS_C_TXN<6>")
	)
	(segment
		(start 396.468092 -10.079736)
		(end 396.144242 -9.755886)
		(width 0.1143)
		(layer "F.Cu")
		(net "P3E_CPU0_PE2_SS_C_TXN<6>")
	)
	(segment
		(start 398.871186 -8.597392)
		(end 398.871186 -7.789672)
		(width 0.1143)
		(layer "F.Cu")
		(net "P3E_CPU0_PE2_SS_C_TXN<5>")
	)
	(segment
		(start 398.595342 -9.705086)
		(end 398.595342 -8.873236)
		(width 0.1143)
		(layer "F.Cu")
		(net "P3E_CPU0_PE2_SS_C_TXN<5>")
	)
	(segment
		(start 398.919192 -10.028936)
		(end 398.595342 -9.705086)
		(width 0.1143)
		(layer "F.Cu")
		(net "P3E_CPU0_PE2_SS_C_TXN<5>")
	)
	(segment
		(start 398.595342 -8.873236)
		(end 398.871186 -8.597392)
		(width 0.1143)
		(layer "F.Cu")
		(net "P3E_CPU0_PE2_SS_C_TXN<5>")
	)
	(segment
		(start 401.319492 -10.028936)
		(end 400.995642 -9.705086)
		(width 0.1143)
		(layer "F.Cu")
		(net "P3E_CPU0_PE2_SS_C_TXN<4>")
	)
	(segment
		(start 400.995642 -9.705086)
		(end 400.995642 -8.873236)
		(width 0.1143)
		(layer "F.Cu")
		(net "P3E_CPU0_PE2_SS_C_TXN<4>")
	)
	(segment
		(start 400.995642 -8.873236)
		(end 401.271486 -8.597392)
		(width 0.1143)
		(layer "F.Cu")
		(net "P3E_CPU0_PE2_SS_C_TXN<4>")
	)
	(segment
		(start 401.271486 -8.597392)
		(end 401.271486 -7.789672)
		(width 0.1143)
		(layer "F.Cu")
		(net "P3E_CPU0_PE2_SS_C_TXN<4>")
	)
	(segment
		(start 403.671786 -8.597392)
		(end 403.671786 -7.789672)
		(width 0.1143)
		(layer "F.Cu")
		(net "P3E_CPU0_PE2_SS_C_TXN<3>")
	)
	(segment
		(start 403.395942 -8.873236)
		(end 403.671786 -8.597392)
		(width 0.1143)
		(layer "F.Cu")
		(net "P3E_CPU0_PE2_SS_C_TXN<3>")
	)
	(segment
		(start 403.719792 -10.028936)
		(end 403.395942 -9.705086)
		(width 0.1143)
		(layer "F.Cu")
		(net "P3E_CPU0_PE2_SS_C_TXN<3>")
	)
	(segment
		(start 403.395942 -9.705086)
		(end 403.395942 -8.873236)
		(width 0.1143)
		(layer "F.Cu")
		(net "P3E_CPU0_PE2_SS_C_TXN<3>")
	)
	(segment
		(start 405.796242 -9.705086)
		(end 405.796242 -8.873236)
		(width 0.1143)
		(layer "F.Cu")
		(net "P3E_CPU0_PE2_SS_C_TXN<2>")
	)
	(segment
		(start 406.072086 -8.597392)
		(end 406.072086 -7.789672)
		(width 0.1143)
		(layer "F.Cu")
		(net "P3E_CPU0_PE2_SS_C_TXN<2>")
	)
	(segment
		(start 405.796242 -8.873236)
		(end 406.072086 -8.597392)
		(width 0.1143)
		(layer "F.Cu")
		(net "P3E_CPU0_PE2_SS_C_TXN<2>")
	)
	(segment
		(start 406.120092 -10.028936)
		(end 405.796242 -9.705086)
		(width 0.1143)
		(layer "F.Cu")
		(net "P3E_CPU0_PE2_SS_C_TXN<2>")
	)
	(segment
		(start 407.955242 -9.703816)
		(end 407.955242 -8.880348)
		(width 0.1143)
		(layer "F.Cu")
		(net "P3E_CPU0_PE2_SS_C_TXN<1>")
	)
	(segment
		(start 407.631392 -10.027666)
		(end 407.955242 -9.703816)
		(width 0.1143)
		(layer "F.Cu")
		(net "P3E_CPU0_PE2_SS_C_TXN<1>")
	)
	(segment
		(start 407.955242 -8.880348)
		(end 407.672286 -8.597392)
		(width 0.1143)
		(layer "F.Cu")
		(net "P3E_CPU0_PE2_SS_C_TXN<1>")
	)
	(segment
		(start 407.672286 -8.597392)
		(end 407.672286 -7.789672)
		(width 0.1143)
		(layer "F.Cu")
		(net "P3E_CPU0_PE2_SS_C_TXN<1>")
	)
	(segment
		(start 363.085126 -7.789926)
		(end 363.085126 -8.5979)
		(width 0.1143)
		(layer "F.Cu")
		(net "P3E_CPU0_PE2_SS_C_TXN<15>")
	)
	(segment
		(start 362.841794 -9.703308)
		(end 363.165644 -10.027158)
		(width 0.1143)
		(layer "F.Cu")
		(net "P3E_CPU0_PE2_SS_C_TXN<15>")
	)
	(segment
		(start 363.085126 -8.5979)
		(end 362.841794 -8.841232)
		(width 0.1143)
		(layer "F.Cu")
		(net "P3E_CPU0_PE2_SS_C_TXN<15>")
	)
	(segment
		(start 362.841794 -8.841232)
		(end 362.841794 -9.703308)
		(width 0.1143)
		(layer "F.Cu")
		(net "P3E_CPU0_PE2_SS_C_TXN<15>")
	)
	(segment
		(start 364.933992 -8.84682)
		(end 364.933992 -9.69391)
		(width 0.1143)
		(layer "F.Cu")
		(net "P3E_CPU0_PE2_SS_C_TXN<14>")
	)
	(segment
		(start 364.685072 -8.5979)
		(end 364.933992 -8.84682)
		(width 0.1143)
		(layer "F.Cu")
		(net "P3E_CPU0_PE2_SS_C_TXN<14>")
	)
	(segment
		(start 364.933992 -9.69391)
		(end 364.600744 -10.027158)
		(width 0.1143)
		(layer "F.Cu")
		(net "P3E_CPU0_PE2_SS_C_TXN<14>")
	)
	(segment
		(start 364.685072 -7.789926)
		(end 364.685072 -8.5979)
		(width 0.1143)
		(layer "F.Cu")
		(net "P3E_CPU0_PE2_SS_C_TXN<14>")
	)
	(segment
		(start 367.605818 -9.666732)
		(end 367.966244 -10.027158)
		(width 0.1143)
		(layer "F.Cu")
		(net "P3E_CPU0_PE2_SS_C_TXN<13>")
	)
	(segment
		(start 367.605818 -8.8773)
		(end 367.605818 -9.666732)
		(width 0.1143)
		(layer "F.Cu")
		(net "P3E_CPU0_PE2_SS_C_TXN<13>")
	)
	(segment
		(start 367.885218 -8.5979)
		(end 367.605818 -8.8773)
		(width 0.1143)
		(layer "F.Cu")
		(net "P3E_CPU0_PE2_SS_C_TXN<13>")
	)
	(segment
		(start 367.885218 -7.789926)
		(end 367.885218 -8.5979)
		(width 0.1143)
		(layer "F.Cu")
		(net "P3E_CPU0_PE2_SS_C_TXN<13>")
	)
	(segment
		(start 370.027708 -8.855202)
		(end 370.027708 -9.688322)
		(width 0.1143)
		(layer "F.Cu")
		(net "P3E_CPU0_PE2_SS_C_TXN<12>")
	)
	(segment
		(start 370.28501 -7.789926)
		(end 370.28501 -8.5979)
		(width 0.1143)
		(layer "F.Cu")
		(net "P3E_CPU0_PE2_SS_C_TXN<12>")
	)
	(segment
		(start 370.28501 -8.5979)
		(end 370.027708 -8.855202)
		(width 0.1143)
		(layer "F.Cu")
		(net "P3E_CPU0_PE2_SS_C_TXN<12>")
	)
	(segment
		(start 370.027708 -9.688322)
		(end 370.366544 -10.027158)
		(width 0.1143)
		(layer "F.Cu")
		(net "P3E_CPU0_PE2_SS_C_TXN<12>")
	)
	(segment
		(start 371.88521 -8.598154)
		(end 372.203472 -8.916416)
		(width 0.1143)
		(layer "F.Cu")
		(net "P3E_CPU0_PE2_SS_C_TXN<11>")
	)
	(segment
		(start 371.88521 -7.789926)
		(end 371.88521 -8.598154)
		(width 0.1143)
		(layer "F.Cu")
		(net "P3E_CPU0_PE2_SS_C_TXN<11>")
	)
	(segment
		(start 372.203472 -8.916416)
		(end 372.203472 -9.70153)
		(width 0.1143)
		(layer "F.Cu")
		(net "P3E_CPU0_PE2_SS_C_TXN<11>")
	)
	(segment
		(start 372.203472 -9.70153)
		(end 371.877844 -10.027158)
		(width 0.1143)
		(layer "F.Cu")
		(net "P3E_CPU0_PE2_SS_C_TXN<11>")
	)
	(segment
		(start 374.842532 -9.702546)
		(end 375.167144 -10.027158)
		(width 0.1143)
		(layer "F.Cu")
		(net "P3E_CPU0_PE2_SS_C_TXN<10>")
	)
	(segment
		(start 374.842532 -8.84047)
		(end 374.842532 -9.702546)
		(width 0.1143)
		(layer "F.Cu")
		(net "P3E_CPU0_PE2_SS_C_TXN<10>")
	)
	(segment
		(start 375.085102 -7.789926)
		(end 375.085102 -8.5979)
		(width 0.1143)
		(layer "F.Cu")
		(net "P3E_CPU0_PE2_SS_C_TXN<10>")
	)
	(segment
		(start 375.085102 -8.5979)
		(end 374.842532 -8.84047)
		(width 0.1143)
		(layer "F.Cu")
		(net "P3E_CPU0_PE2_SS_C_TXN<10>")
	)
	(segment
		(start 410.593286 -8.876792)
		(end 410.872686 -8.597392)
		(width 0.1143)
		(layer "F.Cu")
		(net "P3E_CPU0_PE2_SS_C_TXN<0>")
	)
	(segment
		(start 410.593286 -9.705086)
		(end 410.593286 -8.876792)
		(width 0.1143)
		(layer "F.Cu")
		(net "P3E_CPU0_PE2_SS_C_TXN<0>")
	)
	(segment
		(start 410.493972 -10.224008)
		(end 410.493972 -9.8044)
		(width 0.1143)
		(layer "F.Cu")
		(net "P3E_CPU0_PE2_SS_C_TXN<0>")
	)
	(segment
		(start 410.493972 -9.8044)
		(end 410.593286 -9.705086)
		(width 0.1143)
		(layer "F.Cu")
		(net "P3E_CPU0_PE2_SS_C_TXN<0>")
	)
	(segment
		(start 410.872686 -8.597392)
		(end 410.872686 -7.789672)
		(width 0.1143)
		(layer "F.Cu")
		(net "P3E_CPU0_PE2_SS_C_TXN<0>")
	)
	(segment
		(start 410.817822 -10.547858)
		(end 410.493972 -10.224008)
		(width 0.1143)
		(layer "F.Cu")
		(net "P3E_CPU0_PE2_SS_C_TXN<0>")
	)
	(via
		(at 19.021298 -81.73212)
		(size 0.508)
		(drill 0.254)
		(layers "F.Cu" "B.Cu")
		(net "A_P12V_STBY_FP_TRIGGER")
	)
	(via
		(at 14.2494 -91.9226)
		(size 0.6604)
		(drill 0.3302)
		(layers "F.Cu" "B.Cu")
		(net "A_P12V_STBY_FP_TRIGGER")
	)
	(via
		(at 14.800834 -92.371926)
		(size 0.508)
		(drill 0.254)
		(layers "F.Cu" "B.Cu")
		(net "A_P12V_STBY_FP_TRIGGER")
	)
	(segment
		(start 20.701 -82.953098)
		(end 21.034502 -83.2866)
		(width 0.254)
		(layer "B.Cu")
		(net "A_P12V_STBY_FP_TRIGGER")
	)
	(segment
		(start 19.431 -82.423)
		(end 19.541998 -82.423)
		(width 0.254)
		(layer "B.Cu")
		(net "A_P12V_STBY_FP_TRIGGER")
	)
	(segment
		(start 14.800834 -92.371926)
		(end 14.351508 -91.9226)
		(width 0.254)
		(layer "B.Cu")
		(net "A_P12V_STBY_FP_TRIGGER")
	)
	(segment
		(start 17.272 -91.603068)
		(end 16.7005 -92.174568)
		(width 0.254)
		(layer "B.Cu")
		(net "A_P12V_STBY_FP_TRIGGER")
	)
	(segment
		(start 17.272 -91.2495)
		(end 17.272 -91.603068)
		(width 0.254)
		(layer "B.Cu")
		(net "A_P12V_STBY_FP_TRIGGER")
	)
	(segment
		(start 20.444206 -81.520792)
		(end 20.701 -81.777586)
		(width 0.254)
		(layer "B.Cu")
		(net "A_P12V_STBY_FP_TRIGGER")
	)
	(segment
		(start 20.701 -81.777586)
		(end 20.701 -82.953098)
		(width 0.254)
		(layer "B.Cu")
		(net "A_P12V_STBY_FP_TRIGGER")
	)
	(segment
		(start 16.7005 -92.583)
		(end 16.6497 -92.6338)
		(width 0.254)
		(layer "B.Cu")
		(net "A_P12V_STBY_FP_TRIGGER")
	)
	(segment
		(start 16.6497 -92.6338)
		(end 15.062708 -92.6338)
		(width 0.254)
		(layer "B.Cu")
		(net "A_P12V_STBY_FP_TRIGGER")
	)
	(segment
		(start 19.541998 -82.423)
		(end 20.444206 -81.520792)
		(width 0.254)
		(layer "B.Cu")
		(net "A_P12V_STBY_FP_TRIGGER")
	)
	(segment
		(start 15.062708 -92.6338)
		(end 14.800834 -92.371926)
		(width 0.254)
		(layer "B.Cu")
		(net "A_P12V_STBY_FP_TRIGGER")
	)
	(segment
		(start 14.351508 -91.9226)
		(end 14.2494 -91.9226)
		(width 0.254)
		(layer "B.Cu")
		(net "A_P12V_STBY_FP_TRIGGER")
	)
	(segment
		(start 19.431 -82.423)
		(end 19.431 -82.141822)
		(width 0.254)
		(layer "B.Cu")
		(net "A_P12V_STBY_FP_TRIGGER")
	)
	(segment
		(start 16.7005 -92.174568)
		(end 16.7005 -92.583)
		(width 0.254)
		(layer "B.Cu")
		(net "A_P12V_STBY_FP_TRIGGER")
	)
	(segment
		(start 19.431 -82.141822)
		(end 19.021298 -81.73212)
		(width 0.254)
		(layer "B.Cu")
		(net "A_P12V_STBY_FP_TRIGGER")
	)
	(segment
		(start 19.93519 -85.571838)
		(end 19.93519 -87.176356)
		(width 0.254)
		(layer "In4.Cu")
		(net "A_P12V_STBY_FP_TRIGGER")
	)
	(segment
		(start 19.021298 -84.657946)
		(end 19.93519 -85.571838)
		(width 0.254)
		(layer "In4.Cu")
		(net "A_P12V_STBY_FP_TRIGGER")
	)
	(segment
		(start 19.482054 -88.814148)
		(end 17.448022 -90.84818)
		(width 0.254)
		(layer "In4.Cu")
		(net "A_P12V_STBY_FP_TRIGGER")
	)
	(segment
		(start 19.93519 -87.176356)
		(end 19.482054 -87.629492)
		(width 0.254)
		(layer "In4.Cu")
		(net "A_P12V_STBY_FP_TRIGGER")
	)
	(segment
		(start 19.021298 -81.73212)
		(end 19.021298 -84.657946)
		(width 0.254)
		(layer "In4.Cu")
		(net "A_P12V_STBY_FP_TRIGGER")
	)
	(segment
		(start 19.482054 -87.629492)
		(end 19.482054 -88.814148)
		(width 0.254)
		(layer "In4.Cu")
		(net "A_P12V_STBY_FP_TRIGGER")
	)
	(segment
		(start 17.448022 -91.111578)
		(end 16.000476 -92.559124)
		(width 0.254)
		(layer "In4.Cu")
		(net "A_P12V_STBY_FP_TRIGGER")
	)
	(segment
		(start 16.000476 -92.559124)
		(end 14.988032 -92.559124)
		(width 0.254)
		(layer "In4.Cu")
		(net "A_P12V_STBY_FP_TRIGGER")
	)
	(segment
		(start 17.448022 -90.84818)
		(end 17.448022 -91.111578)
		(width 0.254)
		(layer "In4.Cu")
		(net "A_P12V_STBY_FP_TRIGGER")
	)
	(segment
		(start 14.988032 -92.559124)
		(end 14.800834 -92.371926)
		(width 0.254)
		(layer "In4.Cu")
		(net "A_P12V_STBY_FP_TRIGGER")
	)
	(segment
		(start 21.40839 -75.94219)
		(end 21.4122 -75.946)
		(width 0.254)
		(layer "F.Cu")
		(net "A_HSC_TIMER")
	)
	(segment
		(start 20.5105 -75.94219)
		(end 21.40839 -75.94219)
		(width 0.254)
		(layer "F.Cu")
		(net "A_HSC_TIMER")
	)
	(via
		(at 21.4122 -75.946)
		(size 0.508)
		(drill 0.254)
		(layers "F.Cu" "B.Cu")
		(net "A_HSC_TIMER")
	)
	(segment
		(start 23.876 -76.985876)
		(end 23.363936 -76.473812)
		(width 0.254)
		(layer "B.Cu")
		(net "A_HSC_TIMER")
	)
	(segment
		(start 22.6695 -75.946)
		(end 22.606 -75.946)
		(width 0.254)
		(layer "B.Cu")
		(net "A_HSC_TIMER")
	)
	(segment
		(start 23.876 -77.089)
		(end 23.876 -76.985876)
		(width 0.254)
		(layer "B.Cu")
		(net "A_HSC_TIMER")
	)
	(segment
		(start 22.606 -75.946)
		(end 21.4122 -75.946)
		(width 0.254)
		(layer "B.Cu")
		(net "A_HSC_TIMER")
	)
	(segment
		(start 23.197312 -76.473812)
		(end 22.6695 -75.946)
		(width 0.254)
		(layer "B.Cu")
		(net "A_HSC_TIMER")
	)
	(segment
		(start 23.363936 -76.473812)
		(end 23.197312 -76.473812)
		(width 0.254)
		(layer "B.Cu")
		(net "A_HSC_TIMER")
	)
	(segment
		(start 13.716 -85.471)
		(end 14.7066 -85.471)
		(width 0.254)
		(layer "F.Cu")
		(net "A_HSC_LOW_EN")
	)
	(segment
		(start 10.265918 -105.784904)
		(end 10.265918 -88.514682)
		(width 0.254)
		(layer "F.Cu")
		(net "A_HSC_LOW_EN")
	)
	(segment
		(start 13.46835 -85.71865)
		(end 13.716 -85.471)
		(width 0.254)
		(layer "F.Cu")
		(net "A_HSC_LOW_EN")
	)
	(segment
		(start 13.335 -85.852)
		(end 13.46835 -85.71865)
		(width 0.254)
		(layer "F.Cu")
		(net "A_HSC_LOW_EN")
	)
	(segment
		(start 14.7066 -85.471)
		(end 14.986 -85.1916)
		(width 0.254)
		(layer "F.Cu")
		(net "A_HSC_LOW_EN")
	)
	(segment
		(start 13.675106 -108.707428)
		(end 12.543028 -108.707428)
		(width 0.254)
		(layer "F.Cu")
		(net "A_HSC_LOW_EN")
	)
	(segment
		(start 12.543028 -108.707428)
		(end 11.774424 -107.938824)
		(width 0.254)
		(layer "F.Cu")
		(net "A_HSC_LOW_EN")
	)
	(segment
		(start 14.986 -85.1916)
		(end 14.986 -84.963)
		(width 0.254)
		(layer "F.Cu")
		(net "A_HSC_LOW_EN")
	)
	(segment
		(start 11.8745 -86.1314)
		(end 12.1539 -85.852)
		(width 0.254)
		(layer "F.Cu")
		(net "A_HSC_LOW_EN")
	)
	(segment
		(start 16.749014 -84.87664)
		(end 16.332454 -85.2932)
		(width 0.254)
		(layer "F.Cu")
		(net "A_HSC_LOW_EN")
	)
	(segment
		(start 16.749014 -84.455)
		(end 16.749014 -84.87664)
		(width 0.254)
		(layer "F.Cu")
		(net "A_HSC_LOW_EN")
	)
	(segment
		(start 12.1539 -85.852)
		(end 13.335 -85.852)
		(width 0.254)
		(layer "F.Cu")
		(net "A_HSC_LOW_EN")
	)
	(segment
		(start 15.8242 -85.2932)
		(end 15.494 -84.963)
		(width 0.254)
		(layer "F.Cu")
		(net "A_HSC_LOW_EN")
	)
	(segment
		(start 10.265918 -88.514682)
		(end 11.8745 -86.9061)
		(width 0.254)
		(layer "F.Cu")
		(net "A_HSC_LOW_EN")
	)
	(segment
		(start 15.494 -84.963)
		(end 14.986 -84.963)
		(width 0.254)
		(layer "F.Cu")
		(net "A_HSC_LOW_EN")
	)
	(segment
		(start 11.774424 -107.29341)
		(end 10.265918 -105.784904)
		(width 0.254)
		(layer "F.Cu")
		(net "A_HSC_LOW_EN")
	)
	(segment
		(start 11.8745 -86.9061)
		(end 11.8745 -86.1314)
		(width 0.254)
		(layer "F.Cu")
		(net "A_HSC_LOW_EN")
	)
	(segment
		(start 11.774424 -107.938824)
		(end 11.774424 -107.29341)
		(width 0.254)
		(layer "F.Cu")
		(net "A_HSC_LOW_EN")
	)
	(segment
		(start 16.332454 -85.2932)
		(end 15.8242 -85.2932)
		(width 0.254)
		(layer "F.Cu")
		(net "A_HSC_LOW_EN")
	)
	(via
		(at 13.46835 -85.71865)
		(size 0.508)
		(drill 0.254)
		(layers "F.Cu" "B.Cu")
		(net "A_HSC_LOW_EN")
	)
	(segment
		(start 20.5105 -74.94143)
		(end 21.298916 -74.94143)
		(width 0.254)
		(layer "F.Cu")
		(net "A_HSC_ISET")
	)
	(segment
		(start 21.737066 -74.549)
		(end 21.555964 -74.730102)
		(width 0.254)
		(layer "F.Cu")
		(net "A_HSC_ISET")
	)
	(segment
		(start 19.939 -82.423)
		(end 20.1676 -82.6516)
		(width 0.254)
		(layer "F.Cu")
		(net "A_HSC_ISET")
	)
	(segment
		(start 21.510244 -74.730102)
		(end 21.555964 -74.730102)
		(width 0.254)
		(layer "F.Cu")
		(net "A_HSC_ISET")
	)
	(segment
		(start 21.298916 -74.94143)
		(end 21.510244 -74.730102)
		(width 0.254)
		(layer "F.Cu")
		(net "A_HSC_ISET")
	)
	(segment
		(start 19.431 -82.806032)
		(end 19.2024 -83.034632)
		(width 0.254)
		(layer "F.Cu")
		(net "A_HSC_ISET")
	)
	(segment
		(start 19.431 -82.423)
		(end 19.939 -82.423)
		(width 0.254)
		(layer "F.Cu")
		(net "A_HSC_ISET")
	)
	(segment
		(start 19.2024 -83.034632)
		(end 19.2024 -83.4644)
		(width 0.254)
		(layer "F.Cu")
		(net "A_HSC_ISET")
	)
	(segment
		(start 22.225 -74.549)
		(end 21.737066 -74.549)
		(width 0.254)
		(layer "F.Cu")
		(net "A_HSC_ISET")
	)
	(segment
		(start 19.431 -82.423)
		(end 19.431 -82.806032)
		(width 0.254)
		(layer "F.Cu")
		(net "A_HSC_ISET")
	)
	(via
		(at 21.555964 -74.730102)
		(size 0.508)
		(drill 0.254)
		(layers "F.Cu" "B.Cu")
		(net "A_HSC_ISET")
	)
	(via
		(at 20.1676 -82.6516)
		(size 0.508)
		(drill 0.254)
		(layers "F.Cu" "B.Cu")
		(net "A_HSC_ISET")
	)
	(segment
		(start 21.555964 -74.730102)
		(end 21.858986 -74.42708)
		(width 0.254)
		(layer "B.Cu")
		(net "A_HSC_ISET")
	)
	(segment
		(start 21.858986 -74.42708)
		(end 22.57298 -74.42708)
		(width 0.254)
		(layer "B.Cu")
		(net "A_HSC_ISET")
	)
	(segment
		(start 20.173696 -76.11237)
		(end 20.173696 -80.61706)
		(width 0.254)
		(layer "In2.Cu")
		(net "A_HSC_ISET")
	)
	(segment
		(start 20.6502 -81.093564)
		(end 20.6502 -82.169)
		(width 0.254)
		(layer "In2.Cu")
		(net "A_HSC_ISET")
	)
	(segment
		(start 20.173696 -80.61706)
		(end 20.6502 -81.093564)
		(width 0.254)
		(layer "In2.Cu")
		(net "A_HSC_ISET")
	)
	(segment
		(start 20.6502 -82.169)
		(end 20.1676 -82.6516)
		(width 0.254)
		(layer "In2.Cu")
		(net "A_HSC_ISET")
	)
	(segment
		(start 21.555964 -74.730102)
		(end 20.173696 -76.11237)
		(width 0.254)
		(layer "In2.Cu")
		(net "A_HSC_ISET")
	)
	(segment
		(start 12.1158 -82.296)
		(end 12.7508 -81.661)
		(width 0.254)
		(layer "F.Cu")
		(net "A_HSC_HIGH_EN")
	)
	(segment
		(start 11.666982 -112.207802)
		(end 12.1666 -112.70742)
		(width 0.254)
		(layer "F.Cu")
		(net "A_HSC_HIGH_EN")
	)
	(segment
		(start 12.065 -84.1248)
		(end 11.049 -85.1408)
		(width 0.254)
		(layer "F.Cu")
		(net "A_HSC_HIGH_EN")
	)
	(segment
		(start 12.1158 -82.9056)
		(end 12.1158 -82.296)
		(width 0.254)
		(layer "F.Cu")
		(net "A_HSC_HIGH_EN")
	)
	(segment
		(start 12.7508 -81.661)
		(end 14.6812 -81.661)
		(width 0.254)
		(layer "F.Cu")
		(net "A_HSC_HIGH_EN")
	)
	(segment
		(start 12.1666 -112.70742)
		(end 13.675106 -112.70742)
		(width 0.254)
		(layer "F.Cu")
		(net "A_HSC_HIGH_EN")
	)
	(segment
		(start 15.24 -81.915)
		(end 14.986 -82.169)
		(width 0.254)
		(layer "F.Cu")
		(net "A_HSC_HIGH_EN")
	)
	(segment
		(start 16.749014 -82.677)
		(end 16.749014 -82.281014)
		(width 0.254)
		(layer "F.Cu")
		(net "A_HSC_HIGH_EN")
	)
	(segment
		(start 11.9634 -83.058)
		(end 12.1158 -82.9056)
		(width 0.254)
		(layer "F.Cu")
		(net "A_HSC_HIGH_EN")
	)
	(segment
		(start 11.049 -86.487)
		(end 9.398 -88.138)
		(width 0.254)
		(layer "F.Cu")
		(net "A_HSC_HIGH_EN")
	)
	(segment
		(start 9.398 -88.138)
		(end 9.398 -105.984802)
		(width 0.254)
		(layer "F.Cu")
		(net "A_HSC_HIGH_EN")
	)
	(segment
		(start 11.666982 -108.839)
		(end 11.666982 -112.207802)
		(width 0.254)
		(layer "F.Cu")
		(net "A_HSC_HIGH_EN")
	)
	(segment
		(start 14.6812 -81.661)
		(end 14.986 -81.9658)
		(width 0.254)
		(layer "F.Cu")
		(net "A_HSC_HIGH_EN")
	)
	(segment
		(start 11.032236 -108.204254)
		(end 11.666982 -108.839)
		(width 0.254)
		(layer "F.Cu")
		(net "A_HSC_HIGH_EN")
	)
	(segment
		(start 9.398 -105.984802)
		(end 11.032236 -107.619038)
		(width 0.254)
		(layer "F.Cu")
		(net "A_HSC_HIGH_EN")
	)
	(segment
		(start 14.986 -81.9658)
		(end 14.986 -82.169)
		(width 0.254)
		(layer "F.Cu")
		(net "A_HSC_HIGH_EN")
	)
	(segment
		(start 12.065 -83.1596)
		(end 12.065 -84.1248)
		(width 0.254)
		(layer "F.Cu")
		(net "A_HSC_HIGH_EN")
	)
	(segment
		(start 11.9634 -83.058)
		(end 12.065 -83.1596)
		(width 0.254)
		(layer "F.Cu")
		(net "A_HSC_HIGH_EN")
	)
	(segment
		(start 11.032236 -107.619038)
		(end 11.032236 -108.204254)
		(width 0.254)
		(layer "F.Cu")
		(net "A_HSC_HIGH_EN")
	)
	(segment
		(start 16.749014 -82.281014)
		(end 16.383 -81.915)
		(width 0.254)
		(layer "F.Cu")
		(net "A_HSC_HIGH_EN")
	)
	(segment
		(start 11.049 -85.1408)
		(end 11.049 -86.487)
		(width 0.254)
		(layer "F.Cu")
		(net "A_HSC_HIGH_EN")
	)
	(segment
		(start 16.383 -81.915)
		(end 15.24 -81.915)
		(width 0.254)
		(layer "F.Cu")
		(net "A_HSC_HIGH_EN")
	)
	(via
		(at 11.9634 -83.058)
		(size 0.508)
		(drill 0.254)
		(layers "F.Cu" "B.Cu")
		(net "A_HSC_HIGH_EN")
	)
	(segment
		(start 11.9634 -83.058)
		(end 12.573 -82.4484)
		(width 0.254)
		(layer "B.Cu")
		(net "A_HSC_HIGH_EN")
	)
	(segment
		(start 12.573 -82.4484)
		(end 12.573 -81.3054)
		(width 0.254)
		(layer "B.Cu")
		(net "A_HSC_HIGH_EN")
	)
	(segment
		(start 13.0937 -80.7847)
		(end 14.445488 -80.7847)
		(width 0.254)
		(layer "B.Cu")
		(net "A_HSC_HIGH_EN")
	)
	(segment
		(start 12.573 -81.3054)
		(end 13.0937 -80.7847)
		(width 0.254)
		(layer "B.Cu")
		(net "A_HSC_HIGH_EN")
	)
	(segment
		(start 303.816766 -96.518984)
		(end 304.388266 -96.518984)
		(width 0.1143)
		(layer "F.Cu")
		(net "P3E_CPU0_PE3_OCP_TXP<9>")
	)
	(via
		(at 356.30485 -116.220494)
		(size 0.508)
		(drill 0.254)
		(layers "F.Cu" "B.Cu")
		(net "P3E_CPU0_PE3_OCP_TXP<9>")
	)
	(via
		(at 304.388266 -96.518984)
		(size 0.508)
		(drill 0.254)
		(layers "F.Cu" "B.Cu")
		(net "P3E_CPU0_PE3_OCP_TXP<9>")
	)
	(via
		(at 444.02375 -126.0856)
		(size 0.508)
		(drill 0.254)
		(layers "F.Cu" "B.Cu")
		(net "P3E_CPU0_PE3_OCP_TXP<9>")
	)
	(segment
		(start 443.5094 -125.9713)
		(end 443.6237 -126.0856)
		(width 0.1143)
		(layer "B.Cu")
		(net "P3E_CPU0_PE3_OCP_TXP<9>")
	)
	(segment
		(start 443.524386 -123.246896)
		(end 443.278514 -124.77369)
		(width 0.1143)
		(layer "B.Cu")
		(net "P3E_CPU0_PE3_OCP_TXP<9>")
	)
	(segment
		(start 444.712344 -121.7295)
		(end 443.524386 -123.246896)
		(width 0.1143)
		(layer "B.Cu")
		(net "P3E_CPU0_PE3_OCP_TXP<9>")
	)
	(segment
		(start 446.65265 -117.304566)
		(end 446.411604 -117.721888)
		(width 0.1143)
		(layer "B.Cu")
		(net "P3E_CPU0_PE3_OCP_TXP<9>")
	)
	(segment
		(start 447.04 -116.49202)
		(end 446.65265 -116.87937)
		(width 0.1143)
		(layer "B.Cu")
		(net "P3E_CPU0_PE3_OCP_TXP<9>")
	)
	(segment
		(start 446.411604 -117.721888)
		(end 445.66586 -118.266972)
		(width 0.1143)
		(layer "B.Cu")
		(net "P3E_CPU0_PE3_OCP_TXP<9>")
	)
	(segment
		(start 445.66586 -118.266972)
		(end 444.712344 -121.7295)
		(width 0.1143)
		(layer "B.Cu")
		(net "P3E_CPU0_PE3_OCP_TXP<9>")
	)
	(segment
		(start 443.5094 -125.65761)
		(end 443.5094 -125.9713)
		(width 0.1143)
		(layer "B.Cu")
		(net "P3E_CPU0_PE3_OCP_TXP<9>")
	)
	(segment
		(start 446.65265 -116.87937)
		(end 446.65265 -117.304566)
		(width 0.1143)
		(layer "B.Cu")
		(net "P3E_CPU0_PE3_OCP_TXP<9>")
	)
	(segment
		(start 443.278514 -124.77369)
		(end 443.5094 -125.65761)
		(width 0.1143)
		(layer "B.Cu")
		(net "P3E_CPU0_PE3_OCP_TXP<9>")
	)
	(segment
		(start 443.6237 -126.0856)
		(end 444.02375 -126.0856)
		(width 0.1143)
		(layer "B.Cu")
		(net "P3E_CPU0_PE3_OCP_TXP<9>")
	)
	(segment
		(start 415.90341 -137.59688)
		(end 413.597852 -136.832594)
		(width 0.1143)
		(layer "In4.Cu")
		(net "P3E_CPU0_PE3_OCP_TXP<9>")
	)
	(segment
		(start 355.9556 -118.481348)
		(end 355.9556 -118.138448)
		(width 0.1143)
		(layer "In4.Cu")
		(net "P3E_CPU0_PE3_OCP_TXP<9>")
	)
	(segment
		(start 367.583212 -133.593078)
		(end 367.615724 -133.361938)
		(width 0.1143)
		(layer "In4.Cu")
		(net "P3E_CPU0_PE3_OCP_TXP<9>")
	)
	(segment
		(start 378.28982 -136.609582)
		(end 377.052332 -137.518648)
		(width 0.1143)
		(layer "In4.Cu")
		(net "P3E_CPU0_PE3_OCP_TXP<9>")
	)
	(segment
		(start 410.356812 -137.442702)
		(end 408.488134 -138.780012)
		(width 0.1143)
		(layer "In4.Cu")
		(net "P3E_CPU0_PE3_OCP_TXP<9>")
	)
	(segment
		(start 367.615724 -133.361938)
		(end 367.409222 -133.088126)
		(width 0.1143)
		(layer "In4.Cu")
		(net "P3E_CPU0_PE3_OCP_TXP<9>")
	)
	(segment
		(start 423.060368 -132.164074)
		(end 421.240712 -133.55574)
		(width 0.1143)
		(layer "In4.Cu")
		(net "P3E_CPU0_PE3_OCP_TXP<9>")
	)
	(segment
		(start 355.7905 -120.005348)
		(end 355.7905 -118.646448)
		(width 0.1143)
		(layer "In4.Cu")
		(net "P3E_CPU0_PE3_OCP_TXP<9>")
	)
	(segment
		(start 355.7905 -117.630448)
		(end 355.9556 -117.465348)
		(width 0.1143)
		(layer "In4.Cu")
		(net "P3E_CPU0_PE3_OCP_TXP<9>")
	)
	(segment
		(start 381.15494 -136.515602)
		(end 379.908816 -136.239504)
		(width 0.1143)
		(layer "In4.Cu")
		(net "P3E_CPU0_PE3_OCP_TXP<9>")
	)
	(segment
		(start 419.396926 -136.448038)
		(end 418.217858 -137.113772)
		(width 0.1143)
		(layer "In4.Cu")
		(net "P3E_CPU0_PE3_OCP_TXP<9>")
	)
	(segment
		(start 425.627038 -131.412996)
		(end 423.060368 -132.164074)
		(width 0.1143)
		(layer "In4.Cu")
		(net "P3E_CPU0_PE3_OCP_TXP<9>")
	)
	(segment
		(start 435.429914 -127.150114)
		(end 434.826664 -128.605026)
		(width 0.1143)
		(layer "In4.Cu")
		(net "P3E_CPU0_PE3_OCP_TXP<9>")
	)
	(segment
		(start 437.46547 -125.456188)
		(end 436.302912 -125.937772)
		(width 0.1143)
		(layer "In4.Cu")
		(net "P3E_CPU0_PE3_OCP_TXP<9>")
	)
	(segment
		(start 367.004092 -132.550662)
		(end 366.79759 -132.27685)
		(width 0.1143)
		(layer "In4.Cu")
		(net "P3E_CPU0_PE3_OCP_TXP<9>")
	)
	(segment
		(start 367.987072 -134.128764)
		(end 367.583212 -133.593078)
		(width 0.1143)
		(layer "In4.Cu")
		(net "P3E_CPU0_PE3_OCP_TXP<9>")
	)
	(segment
		(start 356.19055 -115.858544)
		(end 356.30485 -115.972844)
		(width 0.1143)
		(layer "In4.Cu")
		(net "P3E_CPU0_PE3_OCP_TXP<9>")
	)
	(segment
		(start 355.9556 -117.122448)
		(end 355.7905 -116.957348)
		(width 0.1143)
		(layer "In4.Cu")
		(net "P3E_CPU0_PE3_OCP_TXP<9>")
	)
	(segment
		(start 443.165738 -125.2093)
		(end 438.707022 -125.2093)
		(width 0.1143)
		(layer "In4.Cu")
		(net "P3E_CPU0_PE3_OCP_TXP<9>")
	)
	(segment
		(start 376.543824 -137.66165)
		(end 375.169938 -137.31367)
		(width 0.1143)
		(layer "In4.Cu")
		(net "P3E_CPU0_PE3_OCP_TXP<9>")
	)
	(segment
		(start 438.707022 -125.2093)
		(end 437.46547 -125.456188)
		(width 0.1143)
		(layer "In4.Cu")
		(net "P3E_CPU0_PE3_OCP_TXP<9>")
	)
	(segment
		(start 355.7905 -117.973348)
		(end 355.7905 -117.630448)
		(width 0.1143)
		(layer "In4.Cu")
		(net "P3E_CPU0_PE3_OCP_TXP<9>")
	)
	(segment
		(start 427.340776 -131.773168)
		(end 425.627038 -131.412996)
		(width 0.1143)
		(layer "In4.Cu")
		(net "P3E_CPU0_PE3_OCP_TXP<9>")
	)
	(segment
		(start 443.5983 -125.9205)
		(end 443.5983 -125.641862)
		(width 0.1143)
		(layer "In4.Cu")
		(net "P3E_CPU0_PE3_OCP_TXP<9>")
	)
	(segment
		(start 379.908816 -136.239504)
		(end 378.28982 -136.609582)
		(width 0.1143)
		(layer "In4.Cu")
		(net "P3E_CPU0_PE3_OCP_TXP<9>")
	)
	(segment
		(start 368.767868 -135.797544)
		(end 367.987072 -134.128764)
		(width 0.1143)
		(layer "In4.Cu")
		(net "P3E_CPU0_PE3_OCP_TXP<9>")
	)
	(segment
		(start 413.597852 -136.832594)
		(end 410.356812 -137.442448)
		(width 0.1143)
		(layer "In4.Cu")
		(net "P3E_CPU0_PE3_OCP_TXP<9>")
	)
	(segment
		(start 418.217858 -137.113772)
		(end 415.90341 -137.59688)
		(width 0.1143)
		(layer "In4.Cu")
		(net "P3E_CPU0_PE3_OCP_TXP<9>")
	)
	(segment
		(start 366.79759 -132.27685)
		(end 366.56645 -132.244338)
		(width 0.1143)
		(layer "In4.Cu")
		(net "P3E_CPU0_PE3_OCP_TXP<9>")
	)
	(segment
		(start 355.9556 -117.465348)
		(end 355.9556 -117.122448)
		(width 0.1143)
		(layer "In4.Cu")
		(net "P3E_CPU0_PE3_OCP_TXP<9>")
	)
	(segment
		(start 382.483614 -136.097264)
		(end 381.15494 -136.515602)
		(width 0.1143)
		(layer "In4.Cu")
		(net "P3E_CPU0_PE3_OCP_TXP<9>")
	)
	(segment
		(start 355.830124 -124.762768)
		(end 356.346252 -122.534172)
		(width 0.1143)
		(layer "In4.Cu")
		(net "P3E_CPU0_PE3_OCP_TXP<9>")
	)
	(segment
		(start 443.7634 -126.0856)
		(end 443.5983 -125.9205)
		(width 0.1143)
		(layer "In4.Cu")
		(net "P3E_CPU0_PE3_OCP_TXP<9>")
	)
	(segment
		(start 408.488134 -138.780012)
		(end 405.38654 -139.400026)
		(width 0.1143)
		(layer "In4.Cu")
		(net "P3E_CPU0_PE3_OCP_TXP<9>")
	)
	(segment
		(start 356.699058 -127.09398)
		(end 355.830124 -124.762768)
		(width 0.1143)
		(layer "In4.Cu")
		(net "P3E_CPU0_PE3_OCP_TXP<9>")
	)
	(segment
		(start 355.7905 -116.014246)
		(end 355.946202 -115.858544)
		(width 0.1143)
		(layer "In4.Cu")
		(net "P3E_CPU0_PE3_OCP_TXP<9>")
	)
	(segment
		(start 355.946202 -115.858544)
		(end 356.19055 -115.858544)
		(width 0.1143)
		(layer "In4.Cu")
		(net "P3E_CPU0_PE3_OCP_TXP<9>")
	)
	(segment
		(start 428.790354 -131.154932)
		(end 427.340776 -131.773168)
		(width 0.1143)
		(layer "In4.Cu")
		(net "P3E_CPU0_PE3_OCP_TXP<9>")
	)
	(segment
		(start 405.38654 -139.400026)
		(end 386.536438 -135.649462)
		(width 0.1143)
		(layer "In4.Cu")
		(net "P3E_CPU0_PE3_OCP_TXP<9>")
	)
	(segment
		(start 369.476782 -136.135618)
		(end 369.11534 -136.058656)
		(width 0.1143)
		(layer "In4.Cu")
		(net "P3E_CPU0_PE3_OCP_TXP<9>")
	)
	(segment
		(start 436.302912 -125.937772)
		(end 435.429914 -127.150114)
		(width 0.1143)
		(layer "In4.Cu")
		(net "P3E_CPU0_PE3_OCP_TXP<9>")
	)
	(segment
		(start 386.536438 -135.649462)
		(end 383.949194 -136.388856)
		(width 0.1143)
		(layer "In4.Cu")
		(net "P3E_CPU0_PE3_OCP_TXP<9>")
	)
	(segment
		(start 432.671474 -129.54381)
		(end 431.549048 -129.313178)
		(width 0.1143)
		(layer "In4.Cu")
		(net "P3E_CPU0_PE3_OCP_TXP<9>")
	)
	(segment
		(start 355.7905 -116.957348)
		(end 355.7905 -116.014246)
		(width 0.1143)
		(layer "In4.Cu")
		(net "P3E_CPU0_PE3_OCP_TXP<9>")
	)
	(segment
		(start 355.9556 -118.138448)
		(end 355.7905 -117.973348)
		(width 0.1143)
		(layer "In4.Cu")
		(net "P3E_CPU0_PE3_OCP_TXP<9>")
	)
	(segment
		(start 367.409222 -133.088126)
		(end 367.178082 -133.055614)
		(width 0.1143)
		(layer "In4.Cu")
		(net "P3E_CPU0_PE3_OCP_TXP<9>")
	)
	(segment
		(start 373.004334 -136.083294)
		(end 370.783358 -135.617204)
		(width 0.1143)
		(layer "In4.Cu")
		(net "P3E_CPU0_PE3_OCP_TXP<9>")
	)
	(segment
		(start 433.995322 -129.236978)
		(end 432.671474 -129.54381)
		(width 0.1143)
		(layer "In4.Cu")
		(net "P3E_CPU0_PE3_OCP_TXP<9>")
	)
	(segment
		(start 355.7905 -118.646448)
		(end 355.9556 -118.481348)
		(width 0.1143)
		(layer "In4.Cu")
		(net "P3E_CPU0_PE3_OCP_TXP<9>")
	)
	(segment
		(start 366.359948 -131.970526)
		(end 361.163108 -129.912618)
		(width 0.1143)
		(layer "In4.Cu")
		(net "P3E_CPU0_PE3_OCP_TXP<9>")
	)
	(segment
		(start 377.052332 -137.518648)
		(end 376.543824 -137.66165)
		(width 0.1143)
		(layer "In4.Cu")
		(net "P3E_CPU0_PE3_OCP_TXP<9>")
	)
	(segment
		(start 361.163108 -129.912618)
		(end 361.1626 -129.912364)
		(width 0.1143)
		(layer "In4.Cu")
		(net "P3E_CPU0_PE3_OCP_TXP<9>")
	)
	(segment
		(start 434.826664 -128.605026)
		(end 433.995322 -129.236978)
		(width 0.1143)
		(layer "In4.Cu")
		(net "P3E_CPU0_PE3_OCP_TXP<9>")
	)
	(segment
		(start 370.783358 -135.617204)
		(end 369.476782 -136.135618)
		(width 0.1143)
		(layer "In4.Cu")
		(net "P3E_CPU0_PE3_OCP_TXP<9>")
	)
	(segment
		(start 356.346252 -122.534172)
		(end 355.7905 -120.005348)
		(width 0.1143)
		(layer "In4.Cu")
		(net "P3E_CPU0_PE3_OCP_TXP<9>")
	)
	(segment
		(start 369.11534 -136.058656)
		(end 368.767868 -135.797544)
		(width 0.1143)
		(layer "In4.Cu")
		(net "P3E_CPU0_PE3_OCP_TXP<9>")
	)
	(segment
		(start 375.169938 -137.31367)
		(end 373.004334 -136.083294)
		(width 0.1143)
		(layer "In4.Cu")
		(net "P3E_CPU0_PE3_OCP_TXP<9>")
	)
	(segment
		(start 383.949194 -136.388856)
		(end 382.483614 -136.097264)
		(width 0.1143)
		(layer "In4.Cu")
		(net "P3E_CPU0_PE3_OCP_TXP<9>")
	)
	(segment
		(start 429.546004 -130.10388)
		(end 428.790354 -131.154932)
		(width 0.1143)
		(layer "In4.Cu")
		(net "P3E_CPU0_PE3_OCP_TXP<9>")
	)
	(segment
		(start 430.523396 -129.583434)
		(end 429.546004 -130.10388)
		(width 0.1143)
		(layer "In4.Cu")
		(net "P3E_CPU0_PE3_OCP_TXP<9>")
	)
	(segment
		(start 366.97158 -132.781802)
		(end 367.004092 -132.550662)
		(width 0.1143)
		(layer "In4.Cu")
		(net "P3E_CPU0_PE3_OCP_TXP<9>")
	)
	(segment
		(start 444.02375 -126.0856)
		(end 443.7634 -126.0856)
		(width 0.1143)
		(layer "In4.Cu")
		(net "P3E_CPU0_PE3_OCP_TXP<9>")
	)
	(segment
		(start 356.30485 -115.972844)
		(end 356.30485 -116.220494)
		(width 0.1143)
		(layer "In4.Cu")
		(net "P3E_CPU0_PE3_OCP_TXP<9>")
	)
	(segment
		(start 367.178082 -133.055614)
		(end 366.97158 -132.781802)
		(width 0.1143)
		(layer "In4.Cu")
		(net "P3E_CPU0_PE3_OCP_TXP<9>")
	)
	(segment
		(start 421.240712 -133.55574)
		(end 419.396926 -136.448038)
		(width 0.1143)
		(layer "In4.Cu")
		(net "P3E_CPU0_PE3_OCP_TXP<9>")
	)
	(segment
		(start 443.5983 -125.641862)
		(end 443.165738 -125.2093)
		(width 0.1143)
		(layer "In4.Cu")
		(net "P3E_CPU0_PE3_OCP_TXP<9>")
	)
	(segment
		(start 361.1626 -129.912364)
		(end 356.699058 -127.09398)
		(width 0.1143)
		(layer "In4.Cu")
		(net "P3E_CPU0_PE3_OCP_TXP<9>")
	)
	(segment
		(start 431.549048 -129.313178)
		(end 430.523396 -129.583434)
		(width 0.1143)
		(layer "In4.Cu")
		(net "P3E_CPU0_PE3_OCP_TXP<9>")
	)
	(segment
		(start 366.56645 -132.244338)
		(end 366.359948 -131.970526)
		(width 0.1143)
		(layer "In4.Cu")
		(net "P3E_CPU0_PE3_OCP_TXP<9>")
	)
	(segment
		(start 410.356812 -137.442448)
		(end 410.356812 -137.442702)
		(width 0.1143)
		(layer "In4.Cu")
		(net "P3E_CPU0_PE3_OCP_TXP<9>")
	)
	(segment
		(start 309.746142 -97.155762)
		(end 309.756048 -97.165668)
		(width 0.0889)
		(layer "In11.Cu")
		(net "P3E_CPU0_PE3_OCP_TXP<9>")
	)
	(segment
		(start 330.164186 -113.145824)
		(end 330.908914 -113.294668)
		(width 0.1143)
		(layer "In11.Cu")
		(net "P3E_CPU0_PE3_OCP_TXP<9>")
	)
	(segment
		(start 305.656742 -96.476312)
		(end 305.770534 -96.476312)
		(width 0.0889)
		(layer "In11.Cu")
		(net "P3E_CPU0_PE3_OCP_TXP<9>")
	)
	(segment
		(start 308.949598 -96.430338)
		(end 309.075328 -96.556068)
		(width 0.0889)
		(layer "In11.Cu")
		(net "P3E_CPU0_PE3_OCP_TXP<9>")
	)
	(segment
		(start 309.075328 -96.556068)
		(end 309.218584 -96.556068)
		(width 0.0889)
		(layer "In11.Cu")
		(net "P3E_CPU0_PE3_OCP_TXP<9>")
	)
	(segment
		(start 328.32167 -111.778034)
		(end 329.028806 -112.675416)
		(width 0.1143)
		(layer "In11.Cu")
		(net "P3E_CPU0_PE3_OCP_TXP<9>")
	)
	(segment
		(start 307.495194 -95.7453)
		(end 307.672994 -95.7453)
		(width 0.0889)
		(layer "In11.Cu")
		(net "P3E_CPU0_PE3_OCP_TXP<9>")
	)
	(segment
		(start 355.582982 -115.589558)
		(end 355.855524 -115.8621)
		(width 0.1143)
		(layer "In11.Cu")
		(net "P3E_CPU0_PE3_OCP_TXP<9>")
	)
	(segment
		(start 307.949854 -95.84436)
		(end 308.048914 -95.7453)
		(width 0.0889)
		(layer "In11.Cu")
		(net "P3E_CPU0_PE3_OCP_TXP<9>")
	)
	(segment
		(start 307.772054 -95.84436)
		(end 307.949854 -95.84436)
		(width 0.0889)
		(layer "In11.Cu")
		(net "P3E_CPU0_PE3_OCP_TXP<9>")
	)
	(segment
		(start 309.613046 -96.95053)
		(end 309.746142 -97.083626)
		(width 0.0889)
		(layer "In11.Cu")
		(net "P3E_CPU0_PE3_OCP_TXP<9>")
	)
	(segment
		(start 356.123494 -115.8621)
		(end 356.30485 -116.043456)
		(width 0.1143)
		(layer "In11.Cu")
		(net "P3E_CPU0_PE3_OCP_TXP<9>")
	)
	(segment
		(start 310.37911 -97.78873)
		(end 311.182766 -99.225354)
		(width 0.1143)
		(layer "In11.Cu")
		(net "P3E_CPU0_PE3_OCP_TXP<9>")
	)
	(segment
		(start 306.271168 -95.861886)
		(end 306.387754 -95.7453)
		(width 0.0889)
		(layer "In11.Cu")
		(net "P3E_CPU0_PE3_OCP_TXP<9>")
	)
	(segment
		(start 341.478616 -113.625376)
		(end 342.30564 -114.4524)
		(width 0.1143)
		(layer "In11.Cu")
		(net "P3E_CPU0_PE3_OCP_TXP<9>")
	)
	(segment
		(start 354.529644 -114.4524)
		(end 355.374702 -114.80292)
		(width 0.1143)
		(layer "In11.Cu")
		(net "P3E_CPU0_PE3_OCP_TXP<9>")
	)
	(segment
		(start 314.784994 -103.660956)
		(end 327.222866 -108.81233)
		(width 0.1143)
		(layer "In11.Cu")
		(net "P3E_CPU0_PE3_OCP_TXP<9>")
	)
	(segment
		(start 342.30564 -114.4524)
		(end 354.529644 -114.4524)
		(width 0.1143)
		(layer "In11.Cu")
		(net "P3E_CPU0_PE3_OCP_TXP<9>")
	)
	(segment
		(start 306.842414 -95.84436)
		(end 306.941474 -95.7453)
		(width 0.0889)
		(layer "In11.Cu")
		(net "P3E_CPU0_PE3_OCP_TXP<9>")
	)
	(segment
		(start 306.565554 -95.7453)
		(end 306.664614 -95.84436)
		(width 0.0889)
		(layer "In11.Cu")
		(net "P3E_CPU0_PE3_OCP_TXP<9>")
	)
	(segment
		(start 308.68112 -96.161606)
		(end 308.824122 -96.161606)
		(width 0.0889)
		(layer "In11.Cu")
		(net "P3E_CPU0_PE3_OCP_TXP<9>")
	)
	(segment
		(start 305.896264 -96.23679)
		(end 306.037996 -96.095058)
		(width 0.0889)
		(layer "In11.Cu")
		(net "P3E_CPU0_PE3_OCP_TXP<9>")
	)
	(segment
		(start 308.048914 -95.7453)
		(end 308.407816 -95.7453)
		(width 0.0889)
		(layer "In11.Cu")
		(net "P3E_CPU0_PE3_OCP_TXP<9>")
	)
	(segment
		(start 308.55539 -96.035876)
		(end 308.68112 -96.161606)
		(width 0.0889)
		(layer "In11.Cu")
		(net "P3E_CPU0_PE3_OCP_TXP<9>")
	)
	(segment
		(start 308.949598 -96.287082)
		(end 308.949598 -96.430338)
		(width 0.0889)
		(layer "In11.Cu")
		(net "P3E_CPU0_PE3_OCP_TXP<9>")
	)
	(segment
		(start 305.224688 -96.614234)
		(end 305.51882 -96.614234)
		(width 0.0889)
		(layer "In11.Cu")
		(net "P3E_CPU0_PE3_OCP_TXP<9>")
	)
	(segment
		(start 334.122014 -113.387632)
		(end 336.001868 -113.011712)
		(width 0.1143)
		(layer "In11.Cu")
		(net "P3E_CPU0_PE3_OCP_TXP<9>")
	)
	(segment
		(start 355.855524 -115.8621)
		(end 356.123494 -115.8621)
		(width 0.1143)
		(layer "In11.Cu")
		(net "P3E_CPU0_PE3_OCP_TXP<9>")
	)
	(segment
		(start 311.182766 -99.225354)
		(end 314.784994 -103.660956)
		(width 0.1143)
		(layer "In11.Cu")
		(net "P3E_CPU0_PE3_OCP_TXP<9>")
	)
	(segment
		(start 309.46979 -96.95053)
		(end 309.613046 -96.95053)
		(width 0.0889)
		(layer "In11.Cu")
		(net "P3E_CPU0_PE3_OCP_TXP<9>")
	)
	(segment
		(start 309.756048 -97.165668)
		(end 310.37911 -97.78873)
		(width 0.1143)
		(layer "In11.Cu")
		(net "P3E_CPU0_PE3_OCP_TXP<9>")
	)
	(segment
		(start 307.672994 -95.7453)
		(end 307.772054 -95.84436)
		(width 0.0889)
		(layer "In11.Cu")
		(net "P3E_CPU0_PE3_OCP_TXP<9>")
	)
	(segment
		(start 340.409276 -113.1824)
		(end 341.478616 -113.625376)
		(width 0.1143)
		(layer "In11.Cu")
		(net "P3E_CPU0_PE3_OCP_TXP<9>")
	)
	(segment
		(start 330.908914 -113.294668)
		(end 332.151736 -112.993678)
		(width 0.1143)
		(layer "In11.Cu")
		(net "P3E_CPU0_PE3_OCP_TXP<9>")
	)
	(segment
		(start 355.374702 -114.80292)
		(end 355.582982 -115.0112)
		(width 0.1143)
		(layer "In11.Cu")
		(net "P3E_CPU0_PE3_OCP_TXP<9>")
	)
	(segment
		(start 306.941474 -95.7453)
		(end 307.119274 -95.7453)
		(width 0.0889)
		(layer "In11.Cu")
		(net "P3E_CPU0_PE3_OCP_TXP<9>")
	)
	(segment
		(start 304.37709 -96.118934)
		(end 304.399442 -96.118934)
		(width 0.0889)
		(layer "In11.Cu")
		(net "P3E_CPU0_PE3_OCP_TXP<9>")
	)
	(segment
		(start 306.145438 -96.095058)
		(end 306.271168 -95.969328)
		(width 0.0889)
		(layer "In11.Cu")
		(net "P3E_CPU0_PE3_OCP_TXP<9>")
	)
	(segment
		(start 307.119274 -95.7453)
		(end 307.218334 -95.84436)
		(width 0.0889)
		(layer "In11.Cu")
		(net "P3E_CPU0_PE3_OCP_TXP<9>")
	)
	(segment
		(start 306.271168 -95.969328)
		(end 306.271168 -95.861886)
		(width 0.0889)
		(layer "In11.Cu")
		(net "P3E_CPU0_PE3_OCP_TXP<9>")
	)
	(segment
		(start 356.30485 -116.043456)
		(end 356.30485 -116.220494)
		(width 0.1143)
		(layer "In11.Cu")
		(net "P3E_CPU0_PE3_OCP_TXP<9>")
	)
	(segment
		(start 304.03673 -96.327722)
		(end 304.041556 -96.319086)
		(width 0.0889)
		(layer "In11.Cu")
		(net "P3E_CPU0_PE3_OCP_TXP<9>")
	)
	(segment
		(start 304.388266 -96.518984)
		(end 304.388266 -96.857058)
		(width 0.0889)
		(layer "In11.Cu")
		(net "P3E_CPU0_PE3_OCP_TXP<9>")
	)
	(segment
		(start 308.55539 -95.892874)
		(end 308.55539 -96.035876)
		(width 0.0889)
		(layer "In11.Cu")
		(net "P3E_CPU0_PE3_OCP_TXP<9>")
	)
	(segment
		(start 305.51882 -96.614234)
		(end 305.656742 -96.476312)
		(width 0.0889)
		(layer "In11.Cu")
		(net "P3E_CPU0_PE3_OCP_TXP<9>")
	)
	(segment
		(start 306.387754 -95.7453)
		(end 306.565554 -95.7453)
		(width 0.0889)
		(layer "In11.Cu")
		(net "P3E_CPU0_PE3_OCP_TXP<9>")
	)
	(segment
		(start 305.896264 -96.350582)
		(end 305.896264 -96.23679)
		(width 0.0889)
		(layer "In11.Cu")
		(net "P3E_CPU0_PE3_OCP_TXP<9>")
	)
	(segment
		(start 308.824122 -96.161606)
		(end 308.949598 -96.287082)
		(width 0.0889)
		(layer "In11.Cu")
		(net "P3E_CPU0_PE3_OCP_TXP<9>")
	)
	(segment
		(start 309.218584 -96.556068)
		(end 309.34406 -96.681544)
		(width 0.0889)
		(layer "In11.Cu")
		(net "P3E_CPU0_PE3_OCP_TXP<9>")
	)
	(segment
		(start 305.770534 -96.476312)
		(end 305.896264 -96.350582)
		(width 0.0889)
		(layer "In11.Cu")
		(net "P3E_CPU0_PE3_OCP_TXP<9>")
	)
	(segment
		(start 309.746142 -97.083626)
		(end 309.746142 -97.155762)
		(width 0.0889)
		(layer "In11.Cu")
		(net "P3E_CPU0_PE3_OCP_TXP<9>")
	)
	(segment
		(start 309.34406 -96.8248)
		(end 309.46979 -96.95053)
		(width 0.0889)
		(layer "In11.Cu")
		(net "P3E_CPU0_PE3_OCP_TXP<9>")
	)
	(segment
		(start 336.001868 -113.011712)
		(end 336.855308 -113.1824)
		(width 0.1143)
		(layer "In11.Cu")
		(net "P3E_CPU0_PE3_OCP_TXP<9>")
	)
	(segment
		(start 336.855308 -113.1824)
		(end 340.409276 -113.1824)
		(width 0.1143)
		(layer "In11.Cu")
		(net "P3E_CPU0_PE3_OCP_TXP<9>")
	)
	(segment
		(start 304.388266 -96.857058)
		(end 304.330354 -96.91497)
		(width 0.0889)
		(layer "In11.Cu")
		(net "P3E_CPU0_PE3_OCP_TXP<9>")
	)
	(segment
		(start 327.222866 -108.81233)
		(end 328.32167 -111.778034)
		(width 0.1143)
		(layer "In11.Cu")
		(net "P3E_CPU0_PE3_OCP_TXP<9>")
	)
	(segment
		(start 309.34406 -96.681544)
		(end 309.34406 -96.8248)
		(width 0.0889)
		(layer "In11.Cu")
		(net "P3E_CPU0_PE3_OCP_TXP<9>")
	)
	(segment
		(start 306.664614 -95.84436)
		(end 306.842414 -95.84436)
		(width 0.0889)
		(layer "In11.Cu")
		(net "P3E_CPU0_PE3_OCP_TXP<9>")
	)
	(segment
		(start 332.151736 -112.993678)
		(end 334.122014 -113.387632)
		(width 0.1143)
		(layer "In11.Cu")
		(net "P3E_CPU0_PE3_OCP_TXP<9>")
	)
	(segment
		(start 306.037996 -96.095058)
		(end 306.145438 -96.095058)
		(width 0.0889)
		(layer "In11.Cu")
		(net "P3E_CPU0_PE3_OCP_TXP<9>")
	)
	(segment
		(start 307.218334 -95.84436)
		(end 307.396134 -95.84436)
		(width 0.0889)
		(layer "In11.Cu")
		(net "P3E_CPU0_PE3_OCP_TXP<9>")
	)
	(segment
		(start 308.407816 -95.7453)
		(end 308.55539 -95.892874)
		(width 0.0889)
		(layer "In11.Cu")
		(net "P3E_CPU0_PE3_OCP_TXP<9>")
	)
	(segment
		(start 355.582982 -115.0112)
		(end 355.582982 -115.589558)
		(width 0.1143)
		(layer "In11.Cu")
		(net "P3E_CPU0_PE3_OCP_TXP<9>")
	)
	(segment
		(start 329.028806 -112.675416)
		(end 330.164186 -113.145824)
		(width 0.1143)
		(layer "In11.Cu")
		(net "P3E_CPU0_PE3_OCP_TXP<9>")
	)
	(segment
		(start 307.396134 -95.84436)
		(end 307.495194 -95.7453)
		(width 0.0889)
		(layer "In11.Cu")
		(net "P3E_CPU0_PE3_OCP_TXP<9>")
	)
	(arc
		(start 304.041556 -96.719136)
		(mid 303.988086 -96.524073)
		(end 304.03673 -96.327722)
		(width 0.0889)
		(layer "In11.Cu")
		(net "P3E_CPU0_PE3_OCP_TXP<9>")
	)
	(arc
		(start 304.330354 -96.91497)
		(mid 304.163509 -96.850157)
		(end 304.041556 -96.719136)
		(width 0.0889)
		(layer "In11.Cu")
		(net "P3E_CPU0_PE3_OCP_TXP<9>")
	)
	(arc
		(start 304.734976 -96.319086)
		(mid 304.94173 -96.529905)
		(end 305.224688 -96.614234)
		(width 0.0889)
		(layer "In11.Cu")
		(net "P3E_CPU0_PE3_OCP_TXP<9>")
	)
	(arc
		(start 304.399442 -96.118934)
		(mid 304.593292 -96.175284)
		(end 304.734976 -96.319086)
		(width 0.0889)
		(layer "In11.Cu")
		(net "P3E_CPU0_PE3_OCP_TXP<9>")
	)
	(arc
		(start 304.041556 -96.319086)
		(mid 304.183239 -96.175282)
		(end 304.37709 -96.118934)
		(width 0.0889)
		(layer "In11.Cu")
		(net "P3E_CPU0_PE3_OCP_TXP<9>")
	)
	(segment
		(start 303.529746 -97.014538)
		(end 302.958246 -97.014538)
		(width 0.1143)
		(layer "F.Cu")
		(net "P3E_CPU0_PE3_OCP_TXP<8>")
	)
	(via
		(at 303.529746 -97.014538)
		(size 0.508)
		(drill 0.254)
		(layers "F.Cu" "B.Cu")
		(net "P3E_CPU0_PE3_OCP_TXP<8>")
	)
	(via
		(at 354.42525 -115.204494)
		(size 0.508)
		(drill 0.254)
		(layers "F.Cu" "B.Cu")
		(net "P3E_CPU0_PE3_OCP_TXP<8>")
	)
	(via
		(at 440.344306 -127.02159)
		(size 0.508)
		(drill 0.254)
		(layers "F.Cu" "B.Cu")
		(net "P3E_CPU0_PE3_OCP_TXP<8>")
	)
	(segment
		(start 439.829956 -126.90729)
		(end 439.944256 -127.02159)
		(width 0.1143)
		(layer "B.Cu")
		(net "P3E_CPU0_PE3_OCP_TXP<8>")
	)
	(segment
		(start 439.944256 -127.02159)
		(end 440.344306 -127.02159)
		(width 0.1143)
		(layer "B.Cu")
		(net "P3E_CPU0_PE3_OCP_TXP<8>")
	)
	(segment
		(start 439.829956 -125.742954)
		(end 439.829956 -126.90729)
		(width 0.1143)
		(layer "B.Cu")
		(net "P3E_CPU0_PE3_OCP_TXP<8>")
	)
	(segment
		(start 443.865 -116.49202)
		(end 443.47765 -116.87937)
		(width 0.1143)
		(layer "B.Cu")
		(net "P3E_CPU0_PE3_OCP_TXP<8>")
	)
	(segment
		(start 443.47765 -116.87937)
		(end 443.47765 -117.30863)
		(width 0.1143)
		(layer "B.Cu")
		(net "P3E_CPU0_PE3_OCP_TXP<8>")
	)
	(segment
		(start 442.088524 -118.571264)
		(end 439.520076 -124.549154)
		(width 0.1143)
		(layer "B.Cu")
		(net "P3E_CPU0_PE3_OCP_TXP<8>")
	)
	(segment
		(start 443.236858 -117.696996)
		(end 442.088524 -118.571264)
		(width 0.1143)
		(layer "B.Cu")
		(net "P3E_CPU0_PE3_OCP_TXP<8>")
	)
	(segment
		(start 443.47765 -117.30863)
		(end 443.236858 -117.696996)
		(width 0.1143)
		(layer "B.Cu")
		(net "P3E_CPU0_PE3_OCP_TXP<8>")
	)
	(segment
		(start 439.520076 -124.549154)
		(end 439.829956 -125.742954)
		(width 0.1143)
		(layer "B.Cu")
		(net "P3E_CPU0_PE3_OCP_TXP<8>")
	)
	(segment
		(start 418.582348 -137.99566)
		(end 420.055294 -137.164064)
		(width 0.1143)
		(layer "In4.Cu")
		(net "P3E_CPU0_PE3_OCP_TXP<8>")
	)
	(segment
		(start 367.177066 -134.61619)
		(end 368.01552 -136.408668)
		(width 0.1143)
		(layer "In4.Cu")
		(net "P3E_CPU0_PE3_OCP_TXP<8>")
	)
	(segment
		(start 374.786398 -138.177016)
		(end 376.575066 -138.62939)
		(width 0.1143)
		(layer "In4.Cu")
		(net "P3E_CPU0_PE3_OCP_TXP<8>")
	)
	(segment
		(start 353.614736 -115.92179)
		(end 353.614736 -116.668042)
		(width 0.1143)
		(layer "In4.Cu")
		(net "P3E_CPU0_PE3_OCP_TXP<8>")
	)
	(segment
		(start 434.739796 -131.260596)
		(end 436.97652 -131.646168)
		(width 0.1143)
		(layer "In4.Cu")
		(net "P3E_CPU0_PE3_OCP_TXP<8>")
	)
	(segment
		(start 408.886914 -139.658344)
		(end 410.749496 -138.325606)
		(width 0.1143)
		(layer "In4.Cu")
		(net "P3E_CPU0_PE3_OCP_TXP<8>")
	)
	(segment
		(start 439.8645 -128.297432)
		(end 439.8645 -127.3302)
		(width 0.1143)
		(layer "In4.Cu")
		(net "P3E_CPU0_PE3_OCP_TXP<8>")
	)
	(segment
		(start 415.847276 -138.566144)
		(end 418.582348 -137.99566)
		(width 0.1143)
		(layer "In4.Cu")
		(net "P3E_CPU0_PE3_OCP_TXP<8>")
	)
	(segment
		(start 368.71656 -136.934702)
		(end 369.565174 -137.115804)
		(width 0.1143)
		(layer "In4.Cu")
		(net "P3E_CPU0_PE3_OCP_TXP<8>")
	)
	(segment
		(start 378.660152 -137.503916)
		(end 379.944884 -137.210292)
		(width 0.1143)
		(layer "In4.Cu")
		(net "P3E_CPU0_PE3_OCP_TXP<8>")
	)
	(segment
		(start 370.873528 -136.596628)
		(end 372.66753 -136.972802)
		(width 0.1143)
		(layer "In4.Cu")
		(net "P3E_CPU0_PE3_OCP_TXP<8>")
	)
	(segment
		(start 383.98196 -137.357612)
		(end 386.17906 -136.72947)
		(width 0.1143)
		(layer "In4.Cu")
		(net "P3E_CPU0_PE3_OCP_TXP<8>")
	)
	(segment
		(start 420.055294 -137.164064)
		(end 421.946578 -134.19709)
		(width 0.1143)
		(layer "In4.Cu")
		(net "P3E_CPU0_PE3_OCP_TXP<8>")
	)
	(segment
		(start 377.470924 -138.377422)
		(end 378.660152 -137.503916)
		(width 0.1143)
		(layer "In4.Cu")
		(net "P3E_CPU0_PE3_OCP_TXP<8>")
	)
	(segment
		(start 372.66753 -136.972802)
		(end 374.786398 -138.177016)
		(width 0.1143)
		(layer "In4.Cu")
		(net "P3E_CPU0_PE3_OCP_TXP<8>")
	)
	(segment
		(start 440.17311 -127.02159)
		(end 440.344306 -127.02159)
		(width 0.1143)
		(layer "In4.Cu")
		(net "P3E_CPU0_PE3_OCP_TXP<8>")
	)
	(segment
		(start 421.946578 -134.19709)
		(end 423.488104 -133.018276)
		(width 0.1143)
		(layer "In4.Cu")
		(net "P3E_CPU0_PE3_OCP_TXP<8>")
	)
	(segment
		(start 413.536638 -137.800588)
		(end 415.847276 -138.566144)
		(width 0.1143)
		(layer "In4.Cu")
		(net "P3E_CPU0_PE3_OCP_TXP<8>")
	)
	(segment
		(start 354.21316 -123.084336)
		(end 356.04069 -127.98679)
		(width 0.1143)
		(layer "In4.Cu")
		(net "P3E_CPU0_PE3_OCP_TXP<8>")
	)
	(segment
		(start 427.454568 -132.747512)
		(end 430.583594 -131.41198)
		(width 0.1143)
		(layer "In4.Cu")
		(net "P3E_CPU0_PE3_OCP_TXP<8>")
	)
	(segment
		(start 439.8645 -127.3302)
		(end 440.17311 -127.02159)
		(width 0.1143)
		(layer "In4.Cu")
		(net "P3E_CPU0_PE3_OCP_TXP<8>")
	)
	(segment
		(start 423.488104 -133.018276)
		(end 425.687744 -132.374894)
		(width 0.1143)
		(layer "In4.Cu")
		(net "P3E_CPU0_PE3_OCP_TXP<8>")
	)
	(segment
		(start 436.97652 -131.646168)
		(end 438.72912 -131.035298)
		(width 0.1143)
		(layer "In4.Cu")
		(net "P3E_CPU0_PE3_OCP_TXP<8>")
	)
	(segment
		(start 379.944884 -137.210292)
		(end 381.18669 -137.485374)
		(width 0.1143)
		(layer "In4.Cu")
		(net "P3E_CPU0_PE3_OCP_TXP<8>")
	)
	(segment
		(start 386.17906 -136.72947)
		(end 404.908512 -140.45438)
		(width 0.1143)
		(layer "In4.Cu")
		(net "P3E_CPU0_PE3_OCP_TXP<8>")
	)
	(segment
		(start 365.768636 -132.747766)
		(end 367.177066 -134.61619)
		(width 0.1143)
		(layer "In4.Cu")
		(net "P3E_CPU0_PE3_OCP_TXP<8>")
	)
	(segment
		(start 369.565174 -137.115804)
		(end 370.873528 -136.596628)
		(width 0.1143)
		(layer "In4.Cu")
		(net "P3E_CPU0_PE3_OCP_TXP<8>")
	)
	(segment
		(start 356.04069 -127.98679)
		(end 359.89768 -130.422142)
		(width 0.1143)
		(layer "In4.Cu")
		(net "P3E_CPU0_PE3_OCP_TXP<8>")
	)
	(segment
		(start 413.536384 -137.800588)
		(end 413.536638 -137.800588)
		(width 0.1143)
		(layer "In4.Cu")
		(net "P3E_CPU0_PE3_OCP_TXP<8>")
	)
	(segment
		(start 410.749496 -138.325606)
		(end 413.536384 -137.800588)
		(width 0.1143)
		(layer "In4.Cu")
		(net "P3E_CPU0_PE3_OCP_TXP<8>")
	)
	(segment
		(start 438.72912 -131.035298)
		(end 439.8645 -128.297432)
		(width 0.1143)
		(layer "In4.Cu")
		(net "P3E_CPU0_PE3_OCP_TXP<8>")
	)
	(segment
		(start 354.42525 -115.468146)
		(end 354.310696 -115.5827)
		(width 0.1143)
		(layer "In4.Cu")
		(net "P3E_CPU0_PE3_OCP_TXP<8>")
	)
	(segment
		(start 354.331778 -118.023386)
		(end 354.844604 -120.356884)
		(width 0.1143)
		(layer "In4.Cu")
		(net "P3E_CPU0_PE3_OCP_TXP<8>")
	)
	(segment
		(start 354.844604 -120.356884)
		(end 354.21316 -123.084336)
		(width 0.1143)
		(layer "In4.Cu")
		(net "P3E_CPU0_PE3_OCP_TXP<8>")
	)
	(segment
		(start 404.908512 -140.45438)
		(end 408.886914 -139.658344)
		(width 0.1143)
		(layer "In4.Cu")
		(net "P3E_CPU0_PE3_OCP_TXP<8>")
	)
	(segment
		(start 368.01552 -136.408668)
		(end 368.71656 -136.934702)
		(width 0.1143)
		(layer "In4.Cu")
		(net "P3E_CPU0_PE3_OCP_TXP<8>")
	)
	(segment
		(start 430.583594 -131.41198)
		(end 432.895756 -131.875276)
		(width 0.1143)
		(layer "In4.Cu")
		(net "P3E_CPU0_PE3_OCP_TXP<8>")
	)
	(segment
		(start 353.614736 -116.668042)
		(end 354.331778 -118.023386)
		(width 0.1143)
		(layer "In4.Cu")
		(net "P3E_CPU0_PE3_OCP_TXP<8>")
	)
	(segment
		(start 354.310696 -115.5827)
		(end 353.953826 -115.5827)
		(width 0.1143)
		(layer "In4.Cu")
		(net "P3E_CPU0_PE3_OCP_TXP<8>")
	)
	(segment
		(start 359.89768 -130.422142)
		(end 365.768636 -132.747766)
		(width 0.1143)
		(layer "In4.Cu")
		(net "P3E_CPU0_PE3_OCP_TXP<8>")
	)
	(segment
		(start 432.895756 -131.875276)
		(end 434.739796 -131.260596)
		(width 0.1143)
		(layer "In4.Cu")
		(net "P3E_CPU0_PE3_OCP_TXP<8>")
	)
	(segment
		(start 382.517904 -137.066528)
		(end 383.98196 -137.357612)
		(width 0.1143)
		(layer "In4.Cu")
		(net "P3E_CPU0_PE3_OCP_TXP<8>")
	)
	(segment
		(start 381.18669 -137.485374)
		(end 382.517904 -137.066528)
		(width 0.1143)
		(layer "In4.Cu")
		(net "P3E_CPU0_PE3_OCP_TXP<8>")
	)
	(segment
		(start 376.575066 -138.62939)
		(end 377.470924 -138.377422)
		(width 0.1143)
		(layer "In4.Cu")
		(net "P3E_CPU0_PE3_OCP_TXP<8>")
	)
	(segment
		(start 353.953826 -115.5827)
		(end 353.614736 -115.92179)
		(width 0.1143)
		(layer "In4.Cu")
		(net "P3E_CPU0_PE3_OCP_TXP<8>")
	)
	(segment
		(start 354.42525 -115.204494)
		(end 354.42525 -115.468146)
		(width 0.1143)
		(layer "In4.Cu")
		(net "P3E_CPU0_PE3_OCP_TXP<8>")
	)
	(segment
		(start 425.687744 -132.374894)
		(end 427.454568 -132.747512)
		(width 0.1143)
		(layer "In4.Cu")
		(net "P3E_CPU0_PE3_OCP_TXP<8>")
	)
	(segment
		(start 332.15961 -113.383568)
		(end 330.916788 -113.684558)
		(width 0.1143)
		(layer "In11.Cu")
		(net "P3E_CPU0_PE3_OCP_TXP<8>")
	)
	(segment
		(start 317.5381 -105.21315)
		(end 317.221362 -105.081832)
		(width 0.1143)
		(layer "In11.Cu")
		(net "P3E_CPU0_PE3_OCP_TXP<8>")
	)
	(segment
		(start 317.221362 -105.081832)
		(end 317.005462 -105.17124)
		(width 0.1143)
		(layer "In11.Cu")
		(net "P3E_CPU0_PE3_OCP_TXP<8>")
	)
	(segment
		(start 330.20762 -113.542826)
		(end 328.752708 -112.940338)
		(width 0.1143)
		(layer "In11.Cu")
		(net "P3E_CPU0_PE3_OCP_TXP<8>")
	)
	(segment
		(start 304.103532 -97.816924)
		(end 304.041556 -97.709736)
		(width 0.0889)
		(layer "In11.Cu")
		(net "P3E_CPU0_PE3_OCP_TXP<8>")
	)
	(segment
		(start 330.916788 -113.684558)
		(end 330.20762 -113.54308)
		(width 0.1143)
		(layer "In11.Cu")
		(net "P3E_CPU0_PE3_OCP_TXP<8>")
	)
	(segment
		(start 334.122014 -113.776252)
		(end 332.15961 -113.383568)
		(width 0.1143)
		(layer "In11.Cu")
		(net "P3E_CPU0_PE3_OCP_TXP<8>")
	)
	(segment
		(start 335.496408 -113.501424)
		(end 334.122014 -113.776252)
		(width 0.1143)
		(layer "In11.Cu")
		(net "P3E_CPU0_PE3_OCP_TXP<8>")
	)
	(segment
		(start 308.57698 -96.821498)
		(end 308.520592 -96.821498)
		(width 0.0889)
		(layer "In11.Cu")
		(net "P3E_CPU0_PE3_OCP_TXP<8>")
	)
	(segment
		(start 342.056466 -115.4303)
		(end 341.01532 -114.389154)
		(width 0.1143)
		(layer "In11.Cu")
		(net "P3E_CPU0_PE3_OCP_TXP<8>")
	)
	(segment
		(start 303.551082 -97.414588)
		(end 303.51857 -97.414588)
		(width 0.0889)
		(layer "In11.Cu")
		(net "P3E_CPU0_PE3_OCP_TXP<8>")
	)
	(segment
		(start 307.901594 -96.2025)
		(end 307.18379 -96.2025)
		(width 0.0889)
		(layer "In11.Cu")
		(net "P3E_CPU0_PE3_OCP_TXP<8>")
	)
	(segment
		(start 327.00341 -109.316266)
		(end 318.565784 -105.817924)
		(width 0.1143)
		(layer "In11.Cu")
		(net "P3E_CPU0_PE3_OCP_TXP<8>")
	)
	(segment
		(start 306.801774 -96.32188)
		(end 305.213766 -97.909888)
		(width 0.0889)
		(layer "In11.Cu")
		(net "P3E_CPU0_PE3_OCP_TXP<8>")
	)
	(segment
		(start 353.749102 -115.537488)
		(end 353.641914 -115.4303)
		(width 0.1143)
		(layer "In11.Cu")
		(net "P3E_CPU0_PE3_OCP_TXP<8>")
	)
	(segment
		(start 317.943992 -105.560114)
		(end 317.627254 -105.428796)
		(width 0.1143)
		(layer "In11.Cu")
		(net "P3E_CPU0_PE3_OCP_TXP<8>")
	)
	(segment
		(start 353.641914 -115.4303)
		(end 342.056466 -115.4303)
		(width 0.1143)
		(layer "In11.Cu")
		(net "P3E_CPU0_PE3_OCP_TXP<8>")
	)
	(segment
		(start 354.42525 -115.422934)
		(end 354.310696 -115.537488)
		(width 0.1143)
		(layer "In11.Cu")
		(net "P3E_CPU0_PE3_OCP_TXP<8>")
	)
	(segment
		(start 307.18379 -96.2025)
		(end 306.801774 -96.32188)
		(width 0.0889)
		(layer "In11.Cu")
		(net "P3E_CPU0_PE3_OCP_TXP<8>")
	)
	(segment
		(start 314.520326 -104.140762)
		(end 308.57698 -96.821498)
		(width 0.1143)
		(layer "In11.Cu")
		(net "P3E_CPU0_PE3_OCP_TXP<8>")
	)
	(segment
		(start 338.763356 -114.15522)
		(end 335.496408 -113.501424)
		(width 0.1143)
		(layer "In11.Cu")
		(net "P3E_CPU0_PE3_OCP_TXP<8>")
	)
	(segment
		(start 305.213766 -97.909888)
		(end 304.224436 -97.909888)
		(width 0.0889)
		(layer "In11.Cu")
		(net "P3E_CPU0_PE3_OCP_TXP<8>")
	)
	(segment
		(start 318.159638 -105.47096)
		(end 317.943992 -105.560114)
		(width 0.1143)
		(layer "In11.Cu")
		(net "P3E_CPU0_PE3_OCP_TXP<8>")
	)
	(segment
		(start 308.520592 -96.821498)
		(end 307.901594 -96.2025)
		(width 0.0889)
		(layer "In11.Cu")
		(net "P3E_CPU0_PE3_OCP_TXP<8>")
	)
	(segment
		(start 330.20762 -113.54308)
		(end 330.20762 -113.542826)
		(width 0.1143)
		(layer "In11.Cu")
		(net "P3E_CPU0_PE3_OCP_TXP<8>")
	)
	(segment
		(start 327.98512 -111.966502)
		(end 327.00341 -109.316266)
		(width 0.1143)
		(layer "In11.Cu")
		(net "P3E_CPU0_PE3_OCP_TXP<8>")
	)
	(segment
		(start 317.005462 -105.17124)
		(end 314.520326 -104.140762)
		(width 0.1143)
		(layer "In11.Cu")
		(net "P3E_CPU0_PE3_OCP_TXP<8>")
	)
	(segment
		(start 318.565784 -105.817924)
		(end 318.47663 -105.602278)
		(width 0.1143)
		(layer "In11.Cu")
		(net "P3E_CPU0_PE3_OCP_TXP<8>")
	)
	(segment
		(start 304.224436 -97.909888)
		(end 304.103532 -97.816924)
		(width 0.0889)
		(layer "In11.Cu")
		(net "P3E_CPU0_PE3_OCP_TXP<8>")
	)
	(segment
		(start 354.42525 -115.204494)
		(end 354.42525 -115.422934)
		(width 0.1143)
		(layer "In11.Cu")
		(net "P3E_CPU0_PE3_OCP_TXP<8>")
	)
	(segment
		(start 328.752708 -112.940338)
		(end 327.98512 -111.966502)
		(width 0.1143)
		(layer "In11.Cu")
		(net "P3E_CPU0_PE3_OCP_TXP<8>")
	)
	(segment
		(start 341.01532 -114.389154)
		(end 340.450932 -114.15522)
		(width 0.1143)
		(layer "In11.Cu")
		(net "P3E_CPU0_PE3_OCP_TXP<8>")
	)
	(segment
		(start 317.627254 -105.428796)
		(end 317.5381 -105.21315)
		(width 0.1143)
		(layer "In11.Cu")
		(net "P3E_CPU0_PE3_OCP_TXP<8>")
	)
	(segment
		(start 318.47663 -105.602278)
		(end 318.159638 -105.47096)
		(width 0.1143)
		(layer "In11.Cu")
		(net "P3E_CPU0_PE3_OCP_TXP<8>")
	)
	(segment
		(start 354.310696 -115.537488)
		(end 353.749102 -115.537488)
		(width 0.1143)
		(layer "In11.Cu")
		(net "P3E_CPU0_PE3_OCP_TXP<8>")
	)
	(segment
		(start 340.450932 -114.15522)
		(end 338.763356 -114.15522)
		(width 0.1143)
		(layer "In11.Cu")
		(net "P3E_CPU0_PE3_OCP_TXP<8>")
	)
	(arc
		(start 303.51857 -97.414588)
		(mid 303.302906 -97.344248)
		(end 303.160176 -97.167954)
		(width 0.0889)
		(layer "In11.Cu")
		(net "P3E_CPU0_PE3_OCP_TXP<8>")
	)
	(arc
		(start 304.041556 -97.709736)
		(mid 303.834443 -97.498806)
		(end 303.551082 -97.414588)
		(width 0.0889)
		(layer "In11.Cu")
		(net "P3E_CPU0_PE3_OCP_TXP<8>")
	)
	(arc
		(start 303.160176 -97.167954)
		(mid 303.129609 -97.017557)
		(end 303.15789 -96.86671)
		(width 0.0889)
		(layer "In11.Cu")
		(net "P3E_CPU0_PE3_OCP_TXP<8>")
	)
	(arc
		(start 303.15789 -96.86671)
		(mid 303.417732 -96.754696)
		(end 303.529746 -97.014538)
		(width 0.0889)
		(layer "In11.Cu")
		(net "P3E_CPU0_PE3_OCP_TXP<8>")
	)
	(segment
		(start 302.099726 -97.509584)
		(end 302.671226 -97.509584)
		(width 0.1143)
		(layer "F.Cu")
		(net "P3E_CPU0_PE3_OCP_TXP<7>")
	)
	(via
		(at 302.671226 -97.509584)
		(size 0.508)
		(drill 0.254)
		(layers "F.Cu" "B.Cu")
		(net "P3E_CPU0_PE3_OCP_TXP<7>")
	)
	(via
		(at 440.304936 -53.754274)
		(size 0.508)
		(drill 0.254)
		(layers "F.Cu" "B.Cu")
		(net "P3E_CPU0_PE3_OCP_TXP<7>")
	)
	(segment
		(start 440.78525 -53.27396)
		(end 440.304936 -53.754274)
		(width 0.1143)
		(layer "B.Cu")
		(net "P3E_CPU0_PE3_OCP_TXP<7>")
	)
	(segment
		(start 440.4614 -52.2986)
		(end 440.4614 -52.703476)
		(width 0.1143)
		(layer "B.Cu")
		(net "P3E_CPU0_PE3_OCP_TXP<7>")
	)
	(segment
		(start 440.78525 -53.027326)
		(end 440.78525 -53.27396)
		(width 0.1143)
		(layer "B.Cu")
		(net "P3E_CPU0_PE3_OCP_TXP<7>")
	)
	(segment
		(start 440.4614 -52.703476)
		(end 440.78525 -53.027326)
		(width 0.1143)
		(layer "B.Cu")
		(net "P3E_CPU0_PE3_OCP_TXP<7>")
	)
	(segment
		(start 305.439318 -97.966276)
		(end 305.26482 -98.00082)
		(width 0.0889)
		(layer "In4.Cu")
		(net "P3E_CPU0_PE3_OCP_TXP<7>")
	)
	(segment
		(start 439.5343 -54.3687)
		(end 439.3692 -54.5338)
		(width 0.1143)
		(layer "In4.Cu")
		(net "P3E_CPU0_PE3_OCP_TXP<7>")
	)
	(segment
		(start 304.721514 -98.109024)
		(end 304.643536 -98.225864)
		(width 0.0889)
		(layer "In4.Cu")
		(net "P3E_CPU0_PE3_OCP_TXP<7>")
	)
	(segment
		(start 425.02582 -54.586886)
		(end 423.959274 -55.653432)
		(width 0.1143)
		(layer "In4.Cu")
		(net "P3E_CPU0_PE3_OCP_TXP<7>")
	)
	(segment
		(start 388.900924 -52.5907)
		(end 387.420358 -52.5907)
		(width 0.1143)
		(layer "In4.Cu")
		(net "P3E_CPU0_PE3_OCP_TXP<7>")
	)
	(segment
		(start 412.304738 -55.83047)
		(end 412.139638 -55.66537)
		(width 0.1143)
		(layer "In4.Cu")
		(net "P3E_CPU0_PE3_OCP_TXP<7>")
	)
	(segment
		(start 438.3532 -54.5338)
		(end 437.248554 -54.5338)
		(width 0.1143)
		(layer "In4.Cu")
		(net "P3E_CPU0_PE3_OCP_TXP<7>")
	)
	(segment
		(start 403.591776 -53.5559)
		(end 403.121876 -54.0258)
		(width 0.1143)
		(layer "In4.Cu")
		(net "P3E_CPU0_PE3_OCP_TXP<7>")
	)
	(segment
		(start 439.3692 -54.5338)
		(end 439.0263 -54.5338)
		(width 0.1143)
		(layer "In4.Cu")
		(net "P3E_CPU0_PE3_OCP_TXP<7>")
	)
	(segment
		(start 355.099112 -62.0395)
		(end 353.834954 -62.29223)
		(width 0.1143)
		(layer "In4.Cu")
		(net "P3E_CPU0_PE3_OCP_TXP<7>")
	)
	(segment
		(start 345.950794 -61.747146)
		(end 344.340942 -62.060582)
		(width 0.1143)
		(layer "In4.Cu")
		(net "P3E_CPU0_PE3_OCP_TXP<7>")
	)
	(segment
		(start 344.340942 -62.060582)
		(end 343.40419 -61.841634)
		(width 0.1143)
		(layer "In4.Cu")
		(net "P3E_CPU0_PE3_OCP_TXP<7>")
	)
	(segment
		(start 334.37068 -62.087506)
		(end 333.337154 -62.288674)
		(width 0.1143)
		(layer "In4.Cu")
		(net "P3E_CPU0_PE3_OCP_TXP<7>")
	)
	(segment
		(start 423.959274 -55.653432)
		(end 419.800278 -55.653432)
		(width 0.1143)
		(layer "In4.Cu")
		(net "P3E_CPU0_PE3_OCP_TXP<7>")
	)
	(segment
		(start 419.800278 -55.653432)
		(end 419.62324 -55.83047)
		(width 0.1143)
		(layer "In4.Cu")
		(net "P3E_CPU0_PE3_OCP_TXP<7>")
	)
	(segment
		(start 440.7662 -54.0004)
		(end 440.7662 -54.1528)
		(width 0.1143)
		(layer "In4.Cu")
		(net "P3E_CPU0_PE3_OCP_TXP<7>")
	)
	(segment
		(start 439.8772 -54.3687)
		(end 439.5343 -54.3687)
		(width 0.1143)
		(layer "In4.Cu")
		(net "P3E_CPU0_PE3_OCP_TXP<7>")
	)
	(segment
		(start 302.37811 -97.678748)
		(end 302.671226 -97.509584)
		(width 0.0889)
		(layer "In4.Cu")
		(net "P3E_CPU0_PE3_OCP_TXP<7>")
	)
	(segment
		(start 367.710212 -54.19852)
		(end 364.375446 -54.19852)
		(width 0.1143)
		(layer "In4.Cu")
		(net "P3E_CPU0_PE3_OCP_TXP<7>")
	)
	(segment
		(start 325.618602 -72.064372)
		(end 320.393568 -84.678774)
		(width 0.1143)
		(layer "In4.Cu")
		(net "P3E_CPU0_PE3_OCP_TXP<7>")
	)
	(segment
		(start 302.357028 -97.757488)
		(end 302.37811 -97.678748)
		(width 0.0889)
		(layer "In4.Cu")
		(net "P3E_CPU0_PE3_OCP_TXP<7>")
	)
	(segment
		(start 378.029724 -51.258724)
		(end 377.3805 -50.6095)
		(width 0.1143)
		(layer "In4.Cu")
		(net "P3E_CPU0_PE3_OCP_TXP<7>")
	)
	(segment
		(start 428.589694 -53.05171)
		(end 427.054518 -54.586886)
		(width 0.1143)
		(layer "In4.Cu")
		(net "P3E_CPU0_PE3_OCP_TXP<7>")
	)
	(segment
		(start 333.337154 -62.288674)
		(end 331.545438 -63.44793)
		(width 0.1143)
		(layer "In4.Cu")
		(net "P3E_CPU0_PE3_OCP_TXP<7>")
	)
	(segment
		(start 384.351276 -51.258724)
		(end 378.029724 -51.258724)
		(width 0.1143)
		(layer "In4.Cu")
		(net "P3E_CPU0_PE3_OCP_TXP<7>")
	)
	(segment
		(start 391.833862 -54.0258)
		(end 390.944608 -53.136546)
		(width 0.1143)
		(layer "In4.Cu")
		(net "P3E_CPU0_PE3_OCP_TXP<7>")
	)
	(segment
		(start 440.3852 -54.5338)
		(end 440.0423 -54.5338)
		(width 0.1143)
		(layer "In4.Cu")
		(net "P3E_CPU0_PE3_OCP_TXP<7>")
	)
	(segment
		(start 358.981248 -59.592718)
		(end 355.099112 -62.0395)
		(width 0.1143)
		(layer "In4.Cu")
		(net "P3E_CPU0_PE3_OCP_TXP<7>")
	)
	(segment
		(start 436.909464 -53.96103)
		(end 436.666894 -53.718714)
		(width 0.1143)
		(layer "In4.Cu")
		(net "P3E_CPU0_PE3_OCP_TXP<7>")
	)
	(segment
		(start 304.896012 -98.07448)
		(end 304.721514 -98.109024)
		(width 0.0889)
		(layer "In4.Cu")
		(net "P3E_CPU0_PE3_OCP_TXP<7>")
	)
	(segment
		(start 303.640236 -98.425508)
		(end 303.493932 -98.425508)
		(width 0.0889)
		(layer "In4.Cu")
		(net "P3E_CPU0_PE3_OCP_TXP<7>")
	)
	(segment
		(start 436.909464 -54.19471)
		(end 436.909464 -53.96103)
		(width 0.1143)
		(layer "In4.Cu")
		(net "P3E_CPU0_PE3_OCP_TXP<7>")
	)
	(segment
		(start 390.944608 -53.136546)
		(end 389.44677 -53.136546)
		(width 0.1143)
		(layer "In4.Cu")
		(net "P3E_CPU0_PE3_OCP_TXP<7>")
	)
	(segment
		(start 349.939864 -62.042802)
		(end 348.672404 -61.746384)
		(width 0.1143)
		(layer "In4.Cu")
		(net "P3E_CPU0_PE3_OCP_TXP<7>")
	)
	(segment
		(start 307.387498 -97.3582)
		(end 307.3654 -97.3582)
		(width 0.0889)
		(layer "In4.Cu")
		(net "P3E_CPU0_PE3_OCP_TXP<7>")
	)
	(segment
		(start 347.187774 -62.034928)
		(end 345.950794 -61.747146)
		(width 0.1143)
		(layer "In4.Cu")
		(net "P3E_CPU0_PE3_OCP_TXP<7>")
	)
	(segment
		(start 372.806722 -50.6095)
		(end 371.016022 -52.4002)
		(width 0.1143)
		(layer "In4.Cu")
		(net "P3E_CPU0_PE3_OCP_TXP<7>")
	)
	(segment
		(start 407.73477 -55.874666)
		(end 407.14422 -55.874666)
		(width 0.1143)
		(layer "In4.Cu")
		(net "P3E_CPU0_PE3_OCP_TXP<7>")
	)
	(segment
		(start 305.555904 -98.044)
		(end 305.439318 -97.966276)
		(width 0.0889)
		(layer "In4.Cu")
		(net "P3E_CPU0_PE3_OCP_TXP<7>")
	)
	(segment
		(start 403.121876 -54.0258)
		(end 391.833862 -54.0258)
		(width 0.1143)
		(layer "In4.Cu")
		(net "P3E_CPU0_PE3_OCP_TXP<7>")
	)
	(segment
		(start 305.730148 -98.009456)
		(end 305.555904 -98.044)
		(width 0.0889)
		(layer "In4.Cu")
		(net "P3E_CPU0_PE3_OCP_TXP<7>")
	)
	(segment
		(start 305.012598 -98.152204)
		(end 304.896012 -98.07448)
		(width 0.0889)
		(layer "In4.Cu")
		(net "P3E_CPU0_PE3_OCP_TXP<7>")
	)
	(segment
		(start 385.616958 -50.7873)
		(end 384.8227 -50.7873)
		(width 0.1143)
		(layer "In4.Cu")
		(net "P3E_CPU0_PE3_OCP_TXP<7>")
	)
	(segment
		(start 307.3146 -97.409)
		(end 306.85359 -97.409)
		(width 0.0889)
		(layer "In4.Cu")
		(net "P3E_CPU0_PE3_OCP_TXP<7>")
	)
	(segment
		(start 307.714142 -97.3582)
		(end 307.387498 -97.3582)
		(width 0.1143)
		(layer "In4.Cu")
		(net "P3E_CPU0_PE3_OCP_TXP<7>")
	)
	(segment
		(start 440.0423 -54.5338)
		(end 439.8772 -54.3687)
		(width 0.1143)
		(layer "In4.Cu")
		(net "P3E_CPU0_PE3_OCP_TXP<7>")
	)
	(segment
		(start 440.520074 -53.754274)
		(end 440.7662 -54.0004)
		(width 0.1143)
		(layer "In4.Cu")
		(net "P3E_CPU0_PE3_OCP_TXP<7>")
	)
	(segment
		(start 436.433468 -53.718714)
		(end 435.766464 -53.05171)
		(width 0.1143)
		(layer "In4.Cu")
		(net "P3E_CPU0_PE3_OCP_TXP<7>")
	)
	(segment
		(start 377.3805 -50.6095)
		(end 372.806722 -50.6095)
		(width 0.1143)
		(layer "In4.Cu")
		(net "P3E_CPU0_PE3_OCP_TXP<7>")
	)
	(segment
		(start 303.493932 -98.425508)
		(end 302.944276 -98.19767)
		(width 0.0889)
		(layer "In4.Cu")
		(net "P3E_CPU0_PE3_OCP_TXP<7>")
	)
	(segment
		(start 410.99613 -55.83047)
		(end 410.336746 -56.489854)
		(width 0.1143)
		(layer "In4.Cu")
		(net "P3E_CPU0_PE3_OCP_TXP<7>")
	)
	(segment
		(start 363.152436 -55.42153)
		(end 358.981248 -59.592718)
		(width 0.1143)
		(layer "In4.Cu")
		(net "P3E_CPU0_PE3_OCP_TXP<7>")
	)
	(segment
		(start 439.0263 -54.5338)
		(end 438.8612 -54.3687)
		(width 0.1143)
		(layer "In4.Cu")
		(net "P3E_CPU0_PE3_OCP_TXP<7>")
	)
	(segment
		(start 363.395006 -54.945534)
		(end 363.152436 -55.18785)
		(width 0.1143)
		(layer "In4.Cu")
		(net "P3E_CPU0_PE3_OCP_TXP<7>")
	)
	(segment
		(start 331.545438 -63.44793)
		(end 325.618602 -72.064372)
		(width 0.1143)
		(layer "In4.Cu")
		(net "P3E_CPU0_PE3_OCP_TXP<7>")
	)
	(segment
		(start 440.304936 -53.754274)
		(end 440.520074 -53.754274)
		(width 0.1143)
		(layer "In4.Cu")
		(net "P3E_CPU0_PE3_OCP_TXP<7>")
	)
	(segment
		(start 407.14422 -55.874666)
		(end 404.825454 -53.5559)
		(width 0.1143)
		(layer "In4.Cu")
		(net "P3E_CPU0_PE3_OCP_TXP<7>")
	)
	(segment
		(start 436.666894 -53.718714)
		(end 436.433468 -53.718714)
		(width 0.1143)
		(layer "In4.Cu")
		(net "P3E_CPU0_PE3_OCP_TXP<7>")
	)
	(segment
		(start 435.766464 -53.05171)
		(end 428.589694 -53.05171)
		(width 0.1143)
		(layer "In4.Cu")
		(net "P3E_CPU0_PE3_OCP_TXP<7>")
	)
	(segment
		(start 363.628432 -54.945534)
		(end 363.395006 -54.945534)
		(width 0.1143)
		(layer "In4.Cu")
		(net "P3E_CPU0_PE3_OCP_TXP<7>")
	)
	(segment
		(start 369.508532 -52.4002)
		(end 367.710212 -54.19852)
		(width 0.1143)
		(layer "In4.Cu")
		(net "P3E_CPU0_PE3_OCP_TXP<7>")
	)
	(segment
		(start 364.375446 -54.19852)
		(end 363.628432 -54.945534)
		(width 0.1143)
		(layer "In4.Cu")
		(net "P3E_CPU0_PE3_OCP_TXP<7>")
	)
	(segment
		(start 371.016022 -52.4002)
		(end 369.508532 -52.4002)
		(width 0.1143)
		(layer "In4.Cu")
		(net "P3E_CPU0_PE3_OCP_TXP<7>")
	)
	(segment
		(start 411.796738 -55.66537)
		(end 411.631638 -55.83047)
		(width 0.1143)
		(layer "In4.Cu")
		(net "P3E_CPU0_PE3_OCP_TXP<7>")
	)
	(segment
		(start 337.91525 -62.908434)
		(end 334.37068 -62.087506)
		(width 0.1143)
		(layer "In4.Cu")
		(net "P3E_CPU0_PE3_OCP_TXP<7>")
	)
	(segment
		(start 353.834954 -62.29223)
		(end 351.477072 -61.742828)
		(width 0.1143)
		(layer "In4.Cu")
		(net "P3E_CPU0_PE3_OCP_TXP<7>")
	)
	(segment
		(start 389.44677 -53.136546)
		(end 388.900924 -52.5907)
		(width 0.1143)
		(layer "In4.Cu")
		(net "P3E_CPU0_PE3_OCP_TXP<7>")
	)
	(segment
		(start 438.8612 -54.3687)
		(end 438.5183 -54.3687)
		(width 0.1143)
		(layer "In4.Cu")
		(net "P3E_CPU0_PE3_OCP_TXP<7>")
	)
	(segment
		(start 410.336746 -56.489854)
		(end 408.349958 -56.489854)
		(width 0.1143)
		(layer "In4.Cu")
		(net "P3E_CPU0_PE3_OCP_TXP<7>")
	)
	(segment
		(start 384.8227 -50.7873)
		(end 384.351276 -51.258724)
		(width 0.1143)
		(layer "In4.Cu")
		(net "P3E_CPU0_PE3_OCP_TXP<7>")
	)
	(segment
		(start 408.349958 -56.489854)
		(end 407.73477 -55.874666)
		(width 0.1143)
		(layer "In4.Cu")
		(net "P3E_CPU0_PE3_OCP_TXP<7>")
	)
	(segment
		(start 404.825454 -53.5559)
		(end 403.591776 -53.5559)
		(width 0.1143)
		(layer "In4.Cu")
		(net "P3E_CPU0_PE3_OCP_TXP<7>")
	)
	(segment
		(start 306.85359 -97.409)
		(end 305.730148 -98.009456)
		(width 0.0889)
		(layer "In4.Cu")
		(net "P3E_CPU0_PE3_OCP_TXP<7>")
	)
	(segment
		(start 320.393568 -84.678774)
		(end 307.714142 -97.3582)
		(width 0.1143)
		(layer "In4.Cu")
		(net "P3E_CPU0_PE3_OCP_TXP<7>")
	)
	(segment
		(start 305.186842 -98.11766)
		(end 305.012598 -98.152204)
		(width 0.0889)
		(layer "In4.Cu")
		(net "P3E_CPU0_PE3_OCP_TXP<7>")
	)
	(segment
		(start 427.054518 -54.586886)
		(end 425.02582 -54.586886)
		(width 0.1143)
		(layer "In4.Cu")
		(net "P3E_CPU0_PE3_OCP_TXP<7>")
	)
	(segment
		(start 419.62324 -55.83047)
		(end 412.304738 -55.83047)
		(width 0.1143)
		(layer "In4.Cu")
		(net "P3E_CPU0_PE3_OCP_TXP<7>")
	)
	(segment
		(start 302.944276 -98.19767)
		(end 302.65624 -97.909634)
		(width 0.0889)
		(layer "In4.Cu")
		(net "P3E_CPU0_PE3_OCP_TXP<7>")
	)
	(segment
		(start 411.631638 -55.83047)
		(end 410.99613 -55.83047)
		(width 0.1143)
		(layer "In4.Cu")
		(net "P3E_CPU0_PE3_OCP_TXP<7>")
	)
	(segment
		(start 305.26482 -98.00082)
		(end 305.186842 -98.11766)
		(width 0.0889)
		(layer "In4.Cu")
		(net "P3E_CPU0_PE3_OCP_TXP<7>")
	)
	(segment
		(start 387.420358 -52.5907)
		(end 385.616958 -50.7873)
		(width 0.1143)
		(layer "In4.Cu")
		(net "P3E_CPU0_PE3_OCP_TXP<7>")
	)
	(segment
		(start 351.477072 -61.742828)
		(end 349.939864 -62.042802)
		(width 0.1143)
		(layer "In4.Cu")
		(net "P3E_CPU0_PE3_OCP_TXP<7>")
	)
	(segment
		(start 304.643536 -98.225864)
		(end 303.640236 -98.425508)
		(width 0.0889)
		(layer "In4.Cu")
		(net "P3E_CPU0_PE3_OCP_TXP<7>")
	)
	(segment
		(start 363.152436 -55.18785)
		(end 363.152436 -55.42153)
		(width 0.1143)
		(layer "In4.Cu")
		(net "P3E_CPU0_PE3_OCP_TXP<7>")
	)
	(segment
		(start 412.139638 -55.66537)
		(end 411.796738 -55.66537)
		(width 0.1143)
		(layer "In4.Cu")
		(net "P3E_CPU0_PE3_OCP_TXP<7>")
	)
	(segment
		(start 440.7662 -54.1528)
		(end 440.3852 -54.5338)
		(width 0.1143)
		(layer "In4.Cu")
		(net "P3E_CPU0_PE3_OCP_TXP<7>")
	)
	(segment
		(start 307.3654 -97.3582)
		(end 307.3146 -97.409)
		(width 0.0889)
		(layer "In4.Cu")
		(net "P3E_CPU0_PE3_OCP_TXP<7>")
	)
	(segment
		(start 437.248554 -54.5338)
		(end 436.909464 -54.19471)
		(width 0.1143)
		(layer "In4.Cu")
		(net "P3E_CPU0_PE3_OCP_TXP<7>")
	)
	(segment
		(start 348.672404 -61.746384)
		(end 347.187774 -62.034928)
		(width 0.1143)
		(layer "In4.Cu")
		(net "P3E_CPU0_PE3_OCP_TXP<7>")
	)
	(segment
		(start 343.40419 -61.841634)
		(end 337.91525 -62.908434)
		(width 0.1143)
		(layer "In4.Cu")
		(net "P3E_CPU0_PE3_OCP_TXP<7>")
	)
	(segment
		(start 438.5183 -54.3687)
		(end 438.3532 -54.5338)
		(width 0.1143)
		(layer "In4.Cu")
		(net "P3E_CPU0_PE3_OCP_TXP<7>")
	)
	(arc
		(start 302.65624 -97.909634)
		(mid 302.489946 -97.8664)
		(end 302.357028 -97.757488)
		(width 0.0889)
		(layer "In4.Cu")
		(net "P3E_CPU0_PE3_OCP_TXP<7>")
	)
	(segment
		(start 300.382686 -98.500184)
		(end 300.954186 -98.500184)
		(width 0.1143)
		(layer "F.Cu")
		(net "P3E_CPU0_PE3_OCP_TXP<6>")
	)
	(via
		(at 443.51575 -53.754274)
		(size 0.508)
		(drill 0.254)
		(layers "F.Cu" "B.Cu")
		(net "P3E_CPU0_PE3_OCP_TXP<6>")
	)
	(via
		(at 300.954186 -98.500184)
		(size 0.508)
		(drill 0.254)
		(layers "F.Cu" "B.Cu")
		(net "P3E_CPU0_PE3_OCP_TXP<6>")
	)
	(segment
		(start 443.747906 -52.86121)
		(end 443.906656 -52.86121)
		(width 0.1143)
		(layer "B.Cu")
		(net "P3E_CPU0_PE3_OCP_TXP<6>")
	)
	(segment
		(start 444.020956 -52.97551)
		(end 444.020956 -53.249068)
		(width 0.1143)
		(layer "B.Cu")
		(net "P3E_CPU0_PE3_OCP_TXP<6>")
	)
	(segment
		(start 443.633606 -52.342034)
		(end 443.633606 -52.74691)
		(width 0.1143)
		(layer "B.Cu")
		(net "P3E_CPU0_PE3_OCP_TXP<6>")
	)
	(segment
		(start 443.906656 -52.86121)
		(end 444.020956 -52.97551)
		(width 0.1143)
		(layer "B.Cu")
		(net "P3E_CPU0_PE3_OCP_TXP<6>")
	)
	(segment
		(start 443.633606 -52.74691)
		(end 443.747906 -52.86121)
		(width 0.1143)
		(layer "B.Cu")
		(net "P3E_CPU0_PE3_OCP_TXP<6>")
	)
	(segment
		(start 444.020956 -53.249068)
		(end 443.51575 -53.754274)
		(width 0.1143)
		(layer "B.Cu")
		(net "P3E_CPU0_PE3_OCP_TXP<6>")
	)
	(segment
		(start 301.33671 -98.645218)
		(end 301.247302 -98.669348)
		(width 0.0889)
		(layer "In4.Cu")
		(net "P3E_CPU0_PE3_OCP_TXP<6>")
	)
	(segment
		(start 440.286648 -55.2958)
		(end 440.121548 -55.4609)
		(width 0.1143)
		(layer "In4.Cu")
		(net "P3E_CPU0_PE3_OCP_TXP<6>")
	)
	(segment
		(start 377.766326 -51.893724)
		(end 377.117102 -51.2445)
		(width 0.1143)
		(layer "In4.Cu")
		(net "P3E_CPU0_PE3_OCP_TXP<6>")
	)
	(segment
		(start 441.302648 -55.2958)
		(end 441.137548 -55.4609)
		(width 0.1143)
		(layer "In4.Cu")
		(net "P3E_CPU0_PE3_OCP_TXP<6>")
	)
	(segment
		(start 301.247302 -98.669348)
		(end 300.954186 -98.500184)
		(width 0.0889)
		(layer "In4.Cu")
		(net "P3E_CPU0_PE3_OCP_TXP<6>")
	)
	(segment
		(start 383.910078 -53.583078)
		(end 382.220724 -51.893724)
		(width 0.1143)
		(layer "In4.Cu")
		(net "P3E_CPU0_PE3_OCP_TXP<6>")
	)
	(segment
		(start 351.469198 -62.394338)
		(end 349.93199 -62.694312)
		(width 0.1143)
		(layer "In4.Cu")
		(net "P3E_CPU0_PE3_OCP_TXP<6>")
	)
	(segment
		(start 307.231288 -98.63455)
		(end 307.20919 -98.63455)
		(width 0.0889)
		(layer "In4.Cu")
		(net "P3E_CPU0_PE3_OCP_TXP<6>")
	)
	(segment
		(start 441.645548 -55.2958)
		(end 441.302648 -55.2958)
		(width 0.1143)
		(layer "In4.Cu")
		(net "P3E_CPU0_PE3_OCP_TXP<6>")
	)
	(segment
		(start 345.943682 -62.398402)
		(end 344.334338 -62.711838)
		(width 0.1143)
		(layer "In4.Cu")
		(net "P3E_CPU0_PE3_OCP_TXP<6>")
	)
	(segment
		(start 331.978254 -63.980314)
		(end 326.182736 -72.40524)
		(width 0.1143)
		(layer "In4.Cu")
		(net "P3E_CPU0_PE3_OCP_TXP<6>")
	)
	(segment
		(start 402.038312 -55.948834)
		(end 400.77517 -54.685692)
		(width 0.1143)
		(layer "In4.Cu")
		(net "P3E_CPU0_PE3_OCP_TXP<6>")
	)
	(segment
		(start 442.318648 -55.2958)
		(end 442.153548 -55.4609)
		(width 0.1143)
		(layer "In4.Cu")
		(net "P3E_CPU0_PE3_OCP_TXP<6>")
	)
	(segment
		(start 364.86211 -54.9021)
		(end 360.21518 -59.54903)
		(width 0.1143)
		(layer "In4.Cu")
		(net "P3E_CPU0_PE3_OCP_TXP<6>")
	)
	(segment
		(start 419.886638 -56.46547)
		(end 416.020758 -56.46547)
		(width 0.1143)
		(layer "In4.Cu")
		(net "P3E_CPU0_PE3_OCP_TXP<6>")
	)
	(segment
		(start 403.250908 -55.948834)
		(end 402.038312 -55.948834)
		(width 0.1143)
		(layer "In4.Cu")
		(net "P3E_CPU0_PE3_OCP_TXP<6>")
	)
	(segment
		(start 428.352712 -55.233316)
		(end 425.277788 -55.233316)
		(width 0.1143)
		(layer "In4.Cu")
		(net "P3E_CPU0_PE3_OCP_TXP<6>")
	)
	(segment
		(start 320.950844 -85.035898)
		(end 307.352192 -98.63455)
		(width 0.1143)
		(layer "In4.Cu")
		(net "P3E_CPU0_PE3_OCP_TXP<6>")
	)
	(segment
		(start 306.186586 -98.68535)
		(end 305.474116 -99.39782)
		(width 0.0889)
		(layer "In4.Cu")
		(net "P3E_CPU0_PE3_OCP_TXP<6>")
	)
	(segment
		(start 391.43559 -54.685692)
		(end 390.521444 -53.771546)
		(width 0.1143)
		(layer "In4.Cu")
		(net "P3E_CPU0_PE3_OCP_TXP<6>")
	)
	(segment
		(start 390.521444 -53.771546)
		(end 389.183372 -53.771546)
		(width 0.1143)
		(layer "In4.Cu")
		(net "P3E_CPU0_PE3_OCP_TXP<6>")
	)
	(segment
		(start 307.352192 -98.63455)
		(end 307.231288 -98.63455)
		(width 0.1143)
		(layer "In4.Cu")
		(net "P3E_CPU0_PE3_OCP_TXP<6>")
	)
	(segment
		(start 337.706462 -63.599314)
		(end 334.24241 -62.796674)
		(width 0.1143)
		(layer "In4.Cu")
		(net "P3E_CPU0_PE3_OCP_TXP<6>")
	)
	(segment
		(start 303.807368 -99.025456)
		(end 302.8569 -99.0473)
		(width 0.0889)
		(layer "In4.Cu")
		(net "P3E_CPU0_PE3_OCP_TXP<6>")
	)
	(segment
		(start 344.334338 -62.711838)
		(end 343.397332 -62.49289)
		(width 0.1143)
		(layer "In4.Cu")
		(net "P3E_CPU0_PE3_OCP_TXP<6>")
	)
	(segment
		(start 385.728464 -53.583078)
		(end 383.910078 -53.583078)
		(width 0.1143)
		(layer "In4.Cu")
		(net "P3E_CPU0_PE3_OCP_TXP<6>")
	)
	(segment
		(start 425.277788 -55.233316)
		(end 424.222672 -56.288432)
		(width 0.1143)
		(layer "In4.Cu")
		(net "P3E_CPU0_PE3_OCP_TXP<6>")
	)
	(segment
		(start 373.07012 -51.2445)
		(end 371.27942 -53.0352)
		(width 0.1143)
		(layer "In4.Cu")
		(net "P3E_CPU0_PE3_OCP_TXP<6>")
	)
	(segment
		(start 408.099006 -57.1373)
		(end 407.471372 -56.509666)
		(width 0.1143)
		(layer "In4.Cu")
		(net "P3E_CPU0_PE3_OCP_TXP<6>")
	)
	(segment
		(start 443.8904 -53.754274)
		(end 444.0047 -53.868574)
		(width 0.1143)
		(layer "In4.Cu")
		(net "P3E_CPU0_PE3_OCP_TXP<6>")
	)
	(segment
		(start 333.581502 -62.925198)
		(end 331.978254 -63.980314)
		(width 0.1143)
		(layer "In4.Cu")
		(net "P3E_CPU0_PE3_OCP_TXP<6>")
	)
	(segment
		(start 343.397332 -62.49289)
		(end 337.706462 -63.599314)
		(width 0.1143)
		(layer "In4.Cu")
		(net "P3E_CPU0_PE3_OCP_TXP<6>")
	)
	(segment
		(start 442.153548 -55.4609)
		(end 441.810648 -55.4609)
		(width 0.1143)
		(layer "In4.Cu")
		(net "P3E_CPU0_PE3_OCP_TXP<6>")
	)
	(segment
		(start 382.220724 -51.893724)
		(end 377.766326 -51.893724)
		(width 0.1143)
		(layer "In4.Cu")
		(net "P3E_CPU0_PE3_OCP_TXP<6>")
	)
	(segment
		(start 437.065928 -55.4609)
		(end 435.301898 -53.69687)
		(width 0.1143)
		(layer "In4.Cu")
		(net "P3E_CPU0_PE3_OCP_TXP<6>")
	)
	(segment
		(start 414.569148 -57.91708)
		(end 410.790136 -57.91708)
		(width 0.1143)
		(layer "In4.Cu")
		(net "P3E_CPU0_PE3_OCP_TXP<6>")
	)
	(segment
		(start 443.51575 -53.754274)
		(end 443.8904 -53.754274)
		(width 0.1143)
		(layer "In4.Cu")
		(net "P3E_CPU0_PE3_OCP_TXP<6>")
	)
	(segment
		(start 410.010356 -57.1373)
		(end 408.099006 -57.1373)
		(width 0.1143)
		(layer "In4.Cu")
		(net "P3E_CPU0_PE3_OCP_TXP<6>")
	)
	(segment
		(start 441.137548 -55.4609)
		(end 440.794648 -55.4609)
		(width 0.1143)
		(layer "In4.Cu")
		(net "P3E_CPU0_PE3_OCP_TXP<6>")
	)
	(segment
		(start 305.199288 -99.511612)
		(end 304.982118 -99.511612)
		(width 0.0889)
		(layer "In4.Cu")
		(net "P3E_CPU0_PE3_OCP_TXP<6>")
	)
	(segment
		(start 367.90503 -54.9021)
		(end 364.86211 -54.9021)
		(width 0.1143)
		(layer "In4.Cu")
		(net "P3E_CPU0_PE3_OCP_TXP<6>")
	)
	(segment
		(start 304.982118 -99.511612)
		(end 303.807368 -99.025456)
		(width 0.0889)
		(layer "In4.Cu")
		(net "P3E_CPU0_PE3_OCP_TXP<6>")
	)
	(segment
		(start 326.182736 -72.40524)
		(end 320.950844 -85.035898)
		(width 0.1143)
		(layer "In4.Cu")
		(net "P3E_CPU0_PE3_OCP_TXP<6>")
	)
	(segment
		(start 443.169548 -55.4609)
		(end 442.826648 -55.4609)
		(width 0.1143)
		(layer "In4.Cu")
		(net "P3E_CPU0_PE3_OCP_TXP<6>")
	)
	(segment
		(start 377.117102 -51.2445)
		(end 373.07012 -51.2445)
		(width 0.1143)
		(layer "In4.Cu")
		(net "P3E_CPU0_PE3_OCP_TXP<6>")
	)
	(segment
		(start 442.661548 -55.2958)
		(end 442.318648 -55.2958)
		(width 0.1143)
		(layer "In4.Cu")
		(net "P3E_CPU0_PE3_OCP_TXP<6>")
	)
	(segment
		(start 353.98837 -62.981332)
		(end 351.469198 -62.394338)
		(width 0.1143)
		(layer "In4.Cu")
		(net "P3E_CPU0_PE3_OCP_TXP<6>")
	)
	(segment
		(start 307.15839 -98.68535)
		(end 306.186586 -98.68535)
		(width 0.0889)
		(layer "In4.Cu")
		(net "P3E_CPU0_PE3_OCP_TXP<6>")
	)
	(segment
		(start 442.826648 -55.4609)
		(end 442.661548 -55.2958)
		(width 0.1143)
		(layer "In4.Cu")
		(net "P3E_CPU0_PE3_OCP_TXP<6>")
	)
	(segment
		(start 360.21518 -59.54903)
		(end 355.481128 -62.682882)
		(width 0.1143)
		(layer "In4.Cu")
		(net "P3E_CPU0_PE3_OCP_TXP<6>")
	)
	(segment
		(start 400.77517 -54.685692)
		(end 391.43559 -54.685692)
		(width 0.1143)
		(layer "In4.Cu")
		(net "P3E_CPU0_PE3_OCP_TXP<6>")
	)
	(segment
		(start 424.222672 -56.288432)
		(end 420.063676 -56.288432)
		(width 0.1143)
		(layer "In4.Cu")
		(net "P3E_CPU0_PE3_OCP_TXP<6>")
	)
	(segment
		(start 441.810648 -55.4609)
		(end 441.645548 -55.2958)
		(width 0.1143)
		(layer "In4.Cu")
		(net "P3E_CPU0_PE3_OCP_TXP<6>")
	)
	(segment
		(start 386.085842 -53.2257)
		(end 385.728464 -53.583078)
		(width 0.1143)
		(layer "In4.Cu")
		(net "P3E_CPU0_PE3_OCP_TXP<6>")
	)
	(segment
		(start 406.840182 -56.509666)
		(end 406.140666 -55.81015)
		(width 0.1143)
		(layer "In4.Cu")
		(net "P3E_CPU0_PE3_OCP_TXP<6>")
	)
	(segment
		(start 444.0047 -54.625748)
		(end 443.169548 -55.4609)
		(width 0.1143)
		(layer "In4.Cu")
		(net "P3E_CPU0_PE3_OCP_TXP<6>")
	)
	(segment
		(start 369.77193 -53.0352)
		(end 367.90503 -54.9021)
		(width 0.1143)
		(layer "In4.Cu")
		(net "P3E_CPU0_PE3_OCP_TXP<6>")
	)
	(segment
		(start 416.020758 -56.46547)
		(end 414.569148 -57.91708)
		(width 0.1143)
		(layer "In4.Cu")
		(net "P3E_CPU0_PE3_OCP_TXP<6>")
	)
	(segment
		(start 302.214788 -98.405188)
		(end 301.791116 -98.405188)
		(width 0.0889)
		(layer "In4.Cu")
		(net "P3E_CPU0_PE3_OCP_TXP<6>")
	)
	(segment
		(start 444.0047 -53.868574)
		(end 444.0047 -54.625748)
		(width 0.1143)
		(layer "In4.Cu")
		(net "P3E_CPU0_PE3_OCP_TXP<6>")
	)
	(segment
		(start 371.27942 -53.0352)
		(end 369.77193 -53.0352)
		(width 0.1143)
		(layer "In4.Cu")
		(net "P3E_CPU0_PE3_OCP_TXP<6>")
	)
	(segment
		(start 388.637526 -53.2257)
		(end 386.085842 -53.2257)
		(width 0.1143)
		(layer "In4.Cu")
		(net "P3E_CPU0_PE3_OCP_TXP<6>")
	)
	(segment
		(start 440.629548 -55.2958)
		(end 440.286648 -55.2958)
		(width 0.1143)
		(layer "In4.Cu")
		(net "P3E_CPU0_PE3_OCP_TXP<6>")
	)
	(segment
		(start 440.121548 -55.4609)
		(end 437.065928 -55.4609)
		(width 0.1143)
		(layer "In4.Cu")
		(net "P3E_CPU0_PE3_OCP_TXP<6>")
	)
	(segment
		(start 403.389592 -55.81015)
		(end 403.250908 -55.948834)
		(width 0.1143)
		(layer "In4.Cu")
		(net "P3E_CPU0_PE3_OCP_TXP<6>")
	)
	(segment
		(start 347.180662 -62.686184)
		(end 345.943682 -62.398402)
		(width 0.1143)
		(layer "In4.Cu")
		(net "P3E_CPU0_PE3_OCP_TXP<6>")
	)
	(segment
		(start 305.474116 -99.39782)
		(end 305.199288 -99.511612)
		(width 0.0889)
		(layer "In4.Cu")
		(net "P3E_CPU0_PE3_OCP_TXP<6>")
	)
	(segment
		(start 420.063676 -56.288432)
		(end 419.886638 -56.46547)
		(width 0.1143)
		(layer "In4.Cu")
		(net "P3E_CPU0_PE3_OCP_TXP<6>")
	)
	(segment
		(start 406.140666 -55.81015)
		(end 403.389592 -55.81015)
		(width 0.1143)
		(layer "In4.Cu")
		(net "P3E_CPU0_PE3_OCP_TXP<6>")
	)
	(segment
		(start 334.24241 -62.796674)
		(end 333.581502 -62.925198)
		(width 0.1143)
		(layer "In4.Cu")
		(net "P3E_CPU0_PE3_OCP_TXP<6>")
	)
	(segment
		(start 302.8569 -99.0473)
		(end 302.214788 -98.405188)
		(width 0.0889)
		(layer "In4.Cu")
		(net "P3E_CPU0_PE3_OCP_TXP<6>")
	)
	(segment
		(start 355.481128 -62.682882)
		(end 353.98837 -62.981332)
		(width 0.1143)
		(layer "In4.Cu")
		(net "P3E_CPU0_PE3_OCP_TXP<6>")
	)
	(segment
		(start 410.790136 -57.91708)
		(end 410.010356 -57.1373)
		(width 0.1143)
		(layer "In4.Cu")
		(net "P3E_CPU0_PE3_OCP_TXP<6>")
	)
	(segment
		(start 429.889158 -53.69687)
		(end 428.352712 -55.233316)
		(width 0.1143)
		(layer "In4.Cu")
		(net "P3E_CPU0_PE3_OCP_TXP<6>")
	)
	(segment
		(start 389.183372 -53.771546)
		(end 388.637526 -53.2257)
		(width 0.1143)
		(layer "In4.Cu")
		(net "P3E_CPU0_PE3_OCP_TXP<6>")
	)
	(segment
		(start 348.66453 -62.397894)
		(end 347.180662 -62.686184)
		(width 0.1143)
		(layer "In4.Cu")
		(net "P3E_CPU0_PE3_OCP_TXP<6>")
	)
	(segment
		(start 407.471372 -56.509666)
		(end 406.840182 -56.509666)
		(width 0.1143)
		(layer "In4.Cu")
		(net "P3E_CPU0_PE3_OCP_TXP<6>")
	)
	(segment
		(start 435.301898 -53.69687)
		(end 429.889158 -53.69687)
		(width 0.1143)
		(layer "In4.Cu")
		(net "P3E_CPU0_PE3_OCP_TXP<6>")
	)
	(segment
		(start 349.93199 -62.694312)
		(end 348.66453 -62.397894)
		(width 0.1143)
		(layer "In4.Cu")
		(net "P3E_CPU0_PE3_OCP_TXP<6>")
	)
	(segment
		(start 307.20919 -98.63455)
		(end 307.15839 -98.68535)
		(width 0.0889)
		(layer "In4.Cu")
		(net "P3E_CPU0_PE3_OCP_TXP<6>")
	)
	(segment
		(start 440.794648 -55.4609)
		(end 440.629548 -55.2958)
		(width 0.1143)
		(layer "In4.Cu")
		(net "P3E_CPU0_PE3_OCP_TXP<6>")
	)
	(arc
		(start 301.791116 -98.405188)
		(mid 301.536451 -98.473217)
		(end 301.33671 -98.645218)
		(width 0.0889)
		(layer "In4.Cu")
		(net "P3E_CPU0_PE3_OCP_TXP<6>")
	)
	(segment
		(start 300.382686 -99.490784)
		(end 300.954186 -99.490784)
		(width 0.1143)
		(layer "F.Cu")
		(net "P3E_CPU0_PE3_OCP_TXP<5>")
	)
	(via
		(at 300.954186 -99.490784)
		(size 0.508)
		(drill 0.254)
		(layers "F.Cu" "B.Cu")
		(net "P3E_CPU0_PE3_OCP_TXP<5>")
	)
	(via
		(at 446.71615 -53.754274)
		(size 0.508)
		(drill 0.254)
		(layers "F.Cu" "B.Cu")
		(net "P3E_CPU0_PE3_OCP_TXP<5>")
	)
	(segment
		(start 447.249042 -52.989988)
		(end 447.249042 -53.221382)
		(width 0.1143)
		(layer "B.Cu")
		(net "P3E_CPU0_PE3_OCP_TXP<5>")
	)
	(segment
		(start 447.249042 -53.221382)
		(end 446.71615 -53.754274)
		(width 0.1143)
		(layer "B.Cu")
		(net "P3E_CPU0_PE3_OCP_TXP<5>")
	)
	(segment
		(start 447.185288 -52.926234)
		(end 447.249042 -52.989988)
		(width 0.1143)
		(layer "B.Cu")
		(net "P3E_CPU0_PE3_OCP_TXP<5>")
	)
	(segment
		(start 447.026538 -52.926234)
		(end 447.185288 -52.926234)
		(width 0.1143)
		(layer "B.Cu")
		(net "P3E_CPU0_PE3_OCP_TXP<5>")
	)
	(segment
		(start 446.912238 -52.407058)
		(end 446.912238 -52.811934)
		(width 0.1143)
		(layer "B.Cu")
		(net "P3E_CPU0_PE3_OCP_TXP<5>")
	)
	(segment
		(start 446.912238 -52.811934)
		(end 447.026538 -52.926234)
		(width 0.1143)
		(layer "B.Cu")
		(net "P3E_CPU0_PE3_OCP_TXP<5>")
	)
	(segment
		(start 304.930048 -100.003356)
		(end 304.3936 -99.78136)
		(width 0.0889)
		(layer "In4.Cu")
		(net "P3E_CPU0_PE3_OCP_TXP<5>")
	)
	(segment
		(start 447.0908 -53.754274)
		(end 447.169794 -53.833268)
		(width 0.1143)
		(layer "In4.Cu")
		(net "P3E_CPU0_PE3_OCP_TXP<5>")
	)
	(segment
		(start 304.3936 -99.78136)
		(end 303.440592 -99.78136)
		(width 0.0889)
		(layer "In4.Cu")
		(net "P3E_CPU0_PE3_OCP_TXP<5>")
	)
	(segment
		(start 381.943864 -52.528724)
		(end 377.502928 -52.528724)
		(width 0.1143)
		(layer "In4.Cu")
		(net "P3E_CPU0_PE3_OCP_TXP<5>")
	)
	(segment
		(start 405.865076 -56.44515)
		(end 403.843236 -56.44515)
		(width 0.1143)
		(layer "In4.Cu")
		(net "P3E_CPU0_PE3_OCP_TXP<5>")
	)
	(segment
		(start 303.43602 -99.783138)
		(end 302.2092 -100.291646)
		(width 0.0889)
		(layer "In4.Cu")
		(net "P3E_CPU0_PE3_OCP_TXP<5>")
	)
	(segment
		(start 446.451482 -55.115206)
		(end 446.208912 -55.357776)
		(width 0.1143)
		(layer "In4.Cu")
		(net "P3E_CPU0_PE3_OCP_TXP<5>")
	)
	(segment
		(start 300.96714 -99.890834)
		(end 300.9392 -99.890834)
		(width 0.0889)
		(layer "In4.Cu")
		(net "P3E_CPU0_PE3_OCP_TXP<5>")
	)
	(segment
		(start 373.333518 -51.8795)
		(end 371.542818 -53.6702)
		(width 0.1143)
		(layer "In4.Cu")
		(net "P3E_CPU0_PE3_OCP_TXP<5>")
	)
	(segment
		(start 370.134134 -53.6702)
		(end 368.254534 -55.5498)
		(width 0.1143)
		(layer "In4.Cu")
		(net "P3E_CPU0_PE3_OCP_TXP<5>")
	)
	(segment
		(start 345.919552 -63.053214)
		(end 344.293444 -63.369698)
		(width 0.1143)
		(layer "In4.Cu")
		(net "P3E_CPU0_PE3_OCP_TXP<5>")
	)
	(segment
		(start 443.578488 -55.9562)
		(end 443.413388 -56.1213)
		(width 0.1143)
		(layer "In4.Cu")
		(net "P3E_CPU0_PE3_OCP_TXP<5>")
	)
	(segment
		(start 306.910232 -99.33432)
		(end 306.53863 -99.478592)
		(width 0.0889)
		(layer "In4.Cu")
		(net "P3E_CPU0_PE3_OCP_TXP<5>")
	)
	(segment
		(start 302.2092 -100.291646)
		(end 301.980346 -100.386388)
		(width 0.0889)
		(layer "In4.Cu")
		(net "P3E_CPU0_PE3_OCP_TXP<5>")
	)
	(segment
		(start 388.032752 -53.86451)
		(end 386.355336 -53.86451)
		(width 0.1143)
		(layer "In4.Cu")
		(net "P3E_CPU0_PE3_OCP_TXP<5>")
	)
	(segment
		(start 414.832546 -58.55208)
		(end 410.526738 -58.55208)
		(width 0.1143)
		(layer "In4.Cu")
		(net "P3E_CPU0_PE3_OCP_TXP<5>")
	)
	(segment
		(start 410.526738 -58.55208)
		(end 409.746958 -57.7723)
		(width 0.1143)
		(layer "In4.Cu")
		(net "P3E_CPU0_PE3_OCP_TXP<5>")
	)
	(segment
		(start 446.71615 -53.754274)
		(end 447.0908 -53.754274)
		(width 0.1143)
		(layer "In4.Cu")
		(net "P3E_CPU0_PE3_OCP_TXP<5>")
	)
	(segment
		(start 445.445388 -56.1213)
		(end 445.102488 -56.1213)
		(width 0.1143)
		(layer "In4.Cu")
		(net "P3E_CPU0_PE3_OCP_TXP<5>")
	)
	(segment
		(start 425.528994 -55.880508)
		(end 424.48607 -56.923432)
		(width 0.1143)
		(layer "In4.Cu")
		(net "P3E_CPU0_PE3_OCP_TXP<5>")
	)
	(segment
		(start 386.001768 -54.218078)
		(end 383.64668 -54.218078)
		(width 0.1143)
		(layer "In4.Cu")
		(net "P3E_CPU0_PE3_OCP_TXP<5>")
	)
	(segment
		(start 443.413388 -56.1213)
		(end 436.69839 -56.1213)
		(width 0.1143)
		(layer "In4.Cu")
		(net "P3E_CPU0_PE3_OCP_TXP<5>")
	)
	(segment
		(start 401.89785 -56.70677)
		(end 400.511772 -55.320692)
		(width 0.1143)
		(layer "In4.Cu")
		(net "P3E_CPU0_PE3_OCP_TXP<5>")
	)
	(segment
		(start 305.272186 -100.003356)
		(end 304.930048 -100.003356)
		(width 0.0889)
		(layer "In4.Cu")
		(net "P3E_CPU0_PE3_OCP_TXP<5>")
	)
	(segment
		(start 447.169794 -53.833268)
		(end 447.169794 -54.396894)
		(width 0.1143)
		(layer "In4.Cu")
		(net "P3E_CPU0_PE3_OCP_TXP<5>")
	)
	(segment
		(start 446.451482 -54.88178)
		(end 446.451482 -55.115206)
		(width 0.1143)
		(layer "In4.Cu")
		(net "P3E_CPU0_PE3_OCP_TXP<5>")
	)
	(segment
		(start 445.732916 -55.600346)
		(end 445.732916 -55.833772)
		(width 0.1143)
		(layer "In4.Cu")
		(net "P3E_CPU0_PE3_OCP_TXP<5>")
	)
	(segment
		(start 383.64668 -54.218078)
		(end 383.515108 -54.086506)
		(width 0.1143)
		(layer "In4.Cu")
		(net "P3E_CPU0_PE3_OCP_TXP<5>")
	)
	(segment
		(start 407.24836 -57.185052)
		(end 406.604978 -57.185052)
		(width 0.1143)
		(layer "In4.Cu")
		(net "P3E_CPU0_PE3_OCP_TXP<5>")
	)
	(segment
		(start 300.59503 -99.667568)
		(end 300.632114 -99.594924)
		(width 0.0889)
		(layer "In4.Cu")
		(net "P3E_CPU0_PE3_OCP_TXP<5>")
	)
	(segment
		(start 383.515108 -54.086506)
		(end 383.501646 -54.086506)
		(width 0.1143)
		(layer "In4.Cu")
		(net "P3E_CPU0_PE3_OCP_TXP<5>")
	)
	(segment
		(start 306.53863 -99.478592)
		(end 305.272186 -100.003356)
		(width 0.0889)
		(layer "In4.Cu")
		(net "P3E_CPU0_PE3_OCP_TXP<5>")
	)
	(segment
		(start 407.835608 -57.7723)
		(end 407.24836 -57.185052)
		(width 0.1143)
		(layer "In4.Cu")
		(net "P3E_CPU0_PE3_OCP_TXP<5>")
	)
	(segment
		(start 307.093874 -99.33432)
		(end 306.910232 -99.33432)
		(width 0.0889)
		(layer "In4.Cu")
		(net "P3E_CPU0_PE3_OCP_TXP<5>")
	)
	(segment
		(start 353.994974 -63.636906)
		(end 351.461324 -63.045848)
		(width 0.1143)
		(layer "In4.Cu")
		(net "P3E_CPU0_PE3_OCP_TXP<5>")
	)
	(segment
		(start 347.156532 -63.340996)
		(end 345.919552 -63.053214)
		(width 0.1143)
		(layer "In4.Cu")
		(net "P3E_CPU0_PE3_OCP_TXP<5>")
	)
	(segment
		(start 444.594488 -55.9562)
		(end 444.429388 -56.1213)
		(width 0.1143)
		(layer "In4.Cu")
		(net "P3E_CPU0_PE3_OCP_TXP<5>")
	)
	(segment
		(start 300.632114 -99.594924)
		(end 300.954186 -99.490784)
		(width 0.0889)
		(layer "In4.Cu")
		(net "P3E_CPU0_PE3_OCP_TXP<5>")
	)
	(segment
		(start 368.254534 -55.5498)
		(end 365.118396 -55.5498)
		(width 0.1143)
		(layer "In4.Cu")
		(net "P3E_CPU0_PE3_OCP_TXP<5>")
	)
	(segment
		(start 444.086488 -56.1213)
		(end 443.921388 -55.9562)
		(width 0.1143)
		(layer "In4.Cu")
		(net "P3E_CPU0_PE3_OCP_TXP<5>")
	)
	(segment
		(start 420.327074 -56.923432)
		(end 420.150036 -57.10047)
		(width 0.1143)
		(layer "In4.Cu")
		(net "P3E_CPU0_PE3_OCP_TXP<5>")
	)
	(segment
		(start 386.355336 -53.86451)
		(end 386.001768 -54.218078)
		(width 0.1143)
		(layer "In4.Cu")
		(net "P3E_CPU0_PE3_OCP_TXP<5>")
	)
	(segment
		(start 365.118396 -55.5498)
		(end 357.790242 -62.877954)
		(width 0.1143)
		(layer "In4.Cu")
		(net "P3E_CPU0_PE3_OCP_TXP<5>")
	)
	(segment
		(start 349.924116 -63.345822)
		(end 348.656656 -63.049404)
		(width 0.1143)
		(layer "In4.Cu")
		(net "P3E_CPU0_PE3_OCP_TXP<5>")
	)
	(segment
		(start 403.581616 -56.70677)
		(end 401.89785 -56.70677)
		(width 0.1143)
		(layer "In4.Cu")
		(net "P3E_CPU0_PE3_OCP_TXP<5>")
	)
	(segment
		(start 307.623972 -99.28352)
		(end 307.166772 -99.28352)
		(width 0.1143)
		(layer "In4.Cu")
		(net "P3E_CPU0_PE3_OCP_TXP<5>")
	)
	(segment
		(start 444.937388 -55.9562)
		(end 444.594488 -55.9562)
		(width 0.1143)
		(layer "In4.Cu")
		(net "P3E_CPU0_PE3_OCP_TXP<5>")
	)
	(segment
		(start 303.440592 -99.78136)
		(end 303.43602 -99.783138)
		(width 0.0889)
		(layer "In4.Cu")
		(net "P3E_CPU0_PE3_OCP_TXP<5>")
	)
	(segment
		(start 307.144674 -99.28352)
		(end 307.093874 -99.33432)
		(width 0.0889)
		(layer "In4.Cu")
		(net "P3E_CPU0_PE3_OCP_TXP<5>")
	)
	(segment
		(start 436.69839 -56.1213)
		(end 434.90896 -54.33187)
		(width 0.1143)
		(layer "In4.Cu")
		(net "P3E_CPU0_PE3_OCP_TXP<5>")
	)
	(segment
		(start 377.502928 -52.528724)
		(end 376.853704 -51.8795)
		(width 0.1143)
		(layer "In4.Cu")
		(net "P3E_CPU0_PE3_OCP_TXP<5>")
	)
	(segment
		(start 307.166772 -99.28352)
		(end 307.144674 -99.28352)
		(width 0.0889)
		(layer "In4.Cu")
		(net "P3E_CPU0_PE3_OCP_TXP<5>")
	)
	(segment
		(start 344.293444 -63.369698)
		(end 343.352882 -63.151512)
		(width 0.1143)
		(layer "In4.Cu")
		(net "P3E_CPU0_PE3_OCP_TXP<5>")
	)
	(segment
		(start 348.656656 -63.049404)
		(end 347.156532 -63.340996)
		(width 0.1143)
		(layer "In4.Cu")
		(net "P3E_CPU0_PE3_OCP_TXP<5>")
	)
	(segment
		(start 445.732916 -55.833772)
		(end 445.445388 -56.1213)
		(width 0.1143)
		(layer "In4.Cu")
		(net "P3E_CPU0_PE3_OCP_TXP<5>")
	)
	(segment
		(start 409.746958 -57.7723)
		(end 407.835608 -57.7723)
		(width 0.1143)
		(layer "In4.Cu")
		(net "P3E_CPU0_PE3_OCP_TXP<5>")
	)
	(segment
		(start 443.921388 -55.9562)
		(end 443.578488 -55.9562)
		(width 0.1143)
		(layer "In4.Cu")
		(net "P3E_CPU0_PE3_OCP_TXP<5>")
	)
	(segment
		(start 403.843236 -56.44515)
		(end 403.581616 -56.70677)
		(width 0.1143)
		(layer "In4.Cu")
		(net "P3E_CPU0_PE3_OCP_TXP<5>")
	)
	(segment
		(start 390.17575 -54.5973)
		(end 388.765542 -54.5973)
		(width 0.1143)
		(layer "In4.Cu")
		(net "P3E_CPU0_PE3_OCP_TXP<5>")
	)
	(segment
		(start 416.284156 -57.10047)
		(end 414.832546 -58.55208)
		(width 0.1143)
		(layer "In4.Cu")
		(net "P3E_CPU0_PE3_OCP_TXP<5>")
	)
	(segment
		(start 447.169794 -54.396894)
		(end 446.927224 -54.639464)
		(width 0.1143)
		(layer "In4.Cu")
		(net "P3E_CPU0_PE3_OCP_TXP<5>")
	)
	(segment
		(start 376.853704 -51.8795)
		(end 373.333518 -51.8795)
		(width 0.1143)
		(layer "In4.Cu")
		(net "P3E_CPU0_PE3_OCP_TXP<5>")
	)
	(segment
		(start 325.704962 -75.258422)
		(end 321.501262 -85.40623)
		(width 0.1143)
		(layer "In4.Cu")
		(net "P3E_CPU0_PE3_OCP_TXP<5>")
	)
	(segment
		(start 351.461324 -63.045848)
		(end 349.924116 -63.345822)
		(width 0.1143)
		(layer "In4.Cu")
		(net "P3E_CPU0_PE3_OCP_TXP<5>")
	)
	(segment
		(start 383.501646 -54.086506)
		(end 381.943864 -52.528724)
		(width 0.1143)
		(layer "In4.Cu")
		(net "P3E_CPU0_PE3_OCP_TXP<5>")
	)
	(segment
		(start 434.90896 -54.33187)
		(end 430.152556 -54.33187)
		(width 0.1143)
		(layer "In4.Cu")
		(net "P3E_CPU0_PE3_OCP_TXP<5>")
	)
	(segment
		(start 337.064858 -64.3763)
		(end 329.98664 -69.034406)
		(width 0.1143)
		(layer "In4.Cu")
		(net "P3E_CPU0_PE3_OCP_TXP<5>")
	)
	(segment
		(start 446.927224 -54.639464)
		(end 446.693798 -54.639464)
		(width 0.1143)
		(layer "In4.Cu")
		(net "P3E_CPU0_PE3_OCP_TXP<5>")
	)
	(segment
		(start 357.790242 -62.877954)
		(end 353.994974 -63.636906)
		(width 0.1143)
		(layer "In4.Cu")
		(net "P3E_CPU0_PE3_OCP_TXP<5>")
	)
	(segment
		(start 388.765542 -54.5973)
		(end 388.032752 -53.86451)
		(width 0.1143)
		(layer "In4.Cu")
		(net "P3E_CPU0_PE3_OCP_TXP<5>")
	)
	(segment
		(start 428.603918 -55.880508)
		(end 425.528994 -55.880508)
		(width 0.1143)
		(layer "In4.Cu")
		(net "P3E_CPU0_PE3_OCP_TXP<5>")
	)
	(segment
		(start 444.429388 -56.1213)
		(end 444.086488 -56.1213)
		(width 0.1143)
		(layer "In4.Cu")
		(net "P3E_CPU0_PE3_OCP_TXP<5>")
	)
	(segment
		(start 445.102488 -56.1213)
		(end 444.937388 -55.9562)
		(width 0.1143)
		(layer "In4.Cu")
		(net "P3E_CPU0_PE3_OCP_TXP<5>")
	)
	(segment
		(start 446.208912 -55.357776)
		(end 445.975486 -55.357776)
		(width 0.1143)
		(layer "In4.Cu")
		(net "P3E_CPU0_PE3_OCP_TXP<5>")
	)
	(segment
		(start 424.48607 -56.923432)
		(end 420.327074 -56.923432)
		(width 0.1143)
		(layer "In4.Cu")
		(net "P3E_CPU0_PE3_OCP_TXP<5>")
	)
	(segment
		(start 406.604978 -57.185052)
		(end 405.865076 -56.44515)
		(width 0.1143)
		(layer "In4.Cu")
		(net "P3E_CPU0_PE3_OCP_TXP<5>")
	)
	(segment
		(start 371.542818 -53.6702)
		(end 370.134134 -53.6702)
		(width 0.1143)
		(layer "In4.Cu")
		(net "P3E_CPU0_PE3_OCP_TXP<5>")
	)
	(segment
		(start 321.501262 -85.40623)
		(end 307.623972 -99.28352)
		(width 0.1143)
		(layer "In4.Cu")
		(net "P3E_CPU0_PE3_OCP_TXP<5>")
	)
	(segment
		(start 420.150036 -57.10047)
		(end 416.284156 -57.10047)
		(width 0.1143)
		(layer "In4.Cu")
		(net "P3E_CPU0_PE3_OCP_TXP<5>")
	)
	(segment
		(start 430.152556 -54.33187)
		(end 428.603918 -55.880508)
		(width 0.1143)
		(layer "In4.Cu")
		(net "P3E_CPU0_PE3_OCP_TXP<5>")
	)
	(segment
		(start 400.511772 -55.320692)
		(end 390.899142 -55.320692)
		(width 0.1143)
		(layer "In4.Cu")
		(net "P3E_CPU0_PE3_OCP_TXP<5>")
	)
	(segment
		(start 301.980346 -100.386388)
		(end 301.80153 -100.386388)
		(width 0.0889)
		(layer "In4.Cu")
		(net "P3E_CPU0_PE3_OCP_TXP<5>")
	)
	(segment
		(start 390.899142 -55.320692)
		(end 390.17575 -54.5973)
		(width 0.1143)
		(layer "In4.Cu")
		(net "P3E_CPU0_PE3_OCP_TXP<5>")
	)
	(segment
		(start 446.693798 -54.639464)
		(end 446.451482 -54.88178)
		(width 0.1143)
		(layer "In4.Cu")
		(net "P3E_CPU0_PE3_OCP_TXP<5>")
	)
	(segment
		(start 329.98664 -69.034406)
		(end 325.704962 -75.258422)
		(width 0.1143)
		(layer "In4.Cu")
		(net "P3E_CPU0_PE3_OCP_TXP<5>")
	)
	(segment
		(start 343.352882 -63.151512)
		(end 337.064858 -64.3763)
		(width 0.1143)
		(layer "In4.Cu")
		(net "P3E_CPU0_PE3_OCP_TXP<5>")
	)
	(segment
		(start 445.975486 -55.357776)
		(end 445.732916 -55.600346)
		(width 0.1143)
		(layer "In4.Cu")
		(net "P3E_CPU0_PE3_OCP_TXP<5>")
	)
	(arc
		(start 301.80153 -100.386388)
		(mid 301.60768 -100.330038)
		(end 301.465996 -100.186236)
		(width 0.0889)
		(layer "In4.Cu")
		(net "P3E_CPU0_PE3_OCP_TXP<5>")
	)
	(arc
		(start 301.465996 -100.186236)
		(mid 301.255283 -99.973157)
		(end 300.96714 -99.890834)
		(width 0.0889)
		(layer "In4.Cu")
		(net "P3E_CPU0_PE3_OCP_TXP<5>")
	)
	(arc
		(start 300.9392 -99.890834)
		(mid 300.772906 -99.8476)
		(end 300.639988 -99.738688)
		(width 0.0889)
		(layer "In4.Cu")
		(net "P3E_CPU0_PE3_OCP_TXP<5>")
	)
	(arc
		(start 300.639988 -99.738688)
		(mid 300.615653 -99.704301)
		(end 300.59503 -99.667568)
		(width 0.0889)
		(layer "In4.Cu")
		(net "P3E_CPU0_PE3_OCP_TXP<5>")
	)
	(segment
		(start 300.38294 -100.481384)
		(end 300.382686 -100.481638)
		(width 0.1143)
		(layer "F.Cu")
		(net "P3E_CPU0_PE3_OCP_TXP<4>")
	)
	(segment
		(start 300.954186 -100.481384)
		(end 300.38294 -100.481384)
		(width 0.1143)
		(layer "F.Cu")
		(net "P3E_CPU0_PE3_OCP_TXP<4>")
	)
	(via
		(at 449.91655 -53.754274)
		(size 0.508)
		(drill 0.254)
		(layers "F.Cu" "B.Cu")
		(net "P3E_CPU0_PE3_OCP_TXP<4>")
	)
	(via
		(at 300.954186 -100.481384)
		(size 0.508)
		(drill 0.254)
		(layers "F.Cu" "B.Cu")
		(net "P3E_CPU0_PE3_OCP_TXP<4>")
	)
	(segment
		(start 449.96735 -52.811934)
		(end 450.08165 -52.926234)
		(width 0.1143)
		(layer "B.Cu")
		(net "P3E_CPU0_PE3_OCP_TXP<4>")
	)
	(segment
		(start 450.2404 -52.926234)
		(end 450.3547 -53.040534)
		(width 0.1143)
		(layer "B.Cu")
		(net "P3E_CPU0_PE3_OCP_TXP<4>")
	)
	(segment
		(start 449.96735 -52.407058)
		(end 449.96735 -52.811934)
		(width 0.1143)
		(layer "B.Cu")
		(net "P3E_CPU0_PE3_OCP_TXP<4>")
	)
	(segment
		(start 450.3547 -53.316124)
		(end 449.91655 -53.754274)
		(width 0.1143)
		(layer "B.Cu")
		(net "P3E_CPU0_PE3_OCP_TXP<4>")
	)
	(segment
		(start 450.08165 -52.926234)
		(end 450.2404 -52.926234)
		(width 0.1143)
		(layer "B.Cu")
		(net "P3E_CPU0_PE3_OCP_TXP<4>")
	)
	(segment
		(start 450.3547 -53.040534)
		(end 450.3547 -53.316124)
		(width 0.1143)
		(layer "B.Cu")
		(net "P3E_CPU0_PE3_OCP_TXP<4>")
	)
	(segment
		(start 448.691 -56.7563)
		(end 448.5259 -56.5912)
		(width 0.1143)
		(layer "In4.Cu")
		(net "P3E_CPU0_PE3_OCP_TXP<4>")
	)
	(segment
		(start 389.805926 -55.2323)
		(end 388.303262 -55.2323)
		(width 0.1143)
		(layer "In4.Cu")
		(net "P3E_CPU0_PE3_OCP_TXP<4>")
	)
	(segment
		(start 447.675 -56.7563)
		(end 447.5099 -56.5912)
		(width 0.1143)
		(layer "In4.Cu")
		(net "P3E_CPU0_PE3_OCP_TXP<4>")
	)
	(segment
		(start 305.005486 -100.652834)
		(end 304.28692 -100.3554)
		(width 0.0889)
		(layer "In4.Cu")
		(net "P3E_CPU0_PE3_OCP_TXP<4>")
	)
	(segment
		(start 356.785672 -63.809118)
		(end 356.024942 -64.562736)
		(width 0.1143)
		(layer "In4.Cu")
		(net "P3E_CPU0_PE3_OCP_TXP<4>")
	)
	(segment
		(start 448.183 -56.5912)
		(end 448.0179 -56.7563)
		(width 0.1143)
		(layer "In4.Cu")
		(net "P3E_CPU0_PE3_OCP_TXP<4>")
	)
	(segment
		(start 445.9859 -56.7563)
		(end 436.434992 -56.7563)
		(width 0.1143)
		(layer "In4.Cu")
		(net "P3E_CPU0_PE3_OCP_TXP<4>")
	)
	(segment
		(start 401.842224 -57.570624)
		(end 400.2405 -55.9689)
		(width 0.1143)
		(layer "In4.Cu")
		(net "P3E_CPU0_PE3_OCP_TXP<4>")
	)
	(segment
		(start 406.983184 -57.834022)
		(end 406.287732 -57.834022)
		(width 0.1143)
		(layer "In4.Cu")
		(net "P3E_CPU0_PE3_OCP_TXP<4>")
	)
	(segment
		(start 449.27647 -56.51373)
		(end 449.0339 -56.7563)
		(width 0.1143)
		(layer "In4.Cu")
		(net "P3E_CPU0_PE3_OCP_TXP<4>")
	)
	(segment
		(start 428.844456 -56.538368)
		(end 425.769532 -56.538368)
		(width 0.1143)
		(layer "In4.Cu")
		(net "P3E_CPU0_PE3_OCP_TXP<4>")
	)
	(segment
		(start 337.36788 -64.96685)
		(end 330.402946 -69.550534)
		(width 0.1143)
		(layer "In4.Cu")
		(net "P3E_CPU0_PE3_OCP_TXP<4>")
	)
	(segment
		(start 410.23286 -59.18708)
		(end 409.47213 -58.42635)
		(width 0.1143)
		(layer "In4.Cu")
		(net "P3E_CPU0_PE3_OCP_TXP<4>")
	)
	(segment
		(start 344.266774 -64.025018)
		(end 343.32799 -63.806324)
		(width 0.1143)
		(layer "In4.Cu")
		(net "P3E_CPU0_PE3_OCP_TXP<4>")
	)
	(segment
		(start 370.082064 -54.6354)
		(end 368.514884 -56.20258)
		(width 0.1143)
		(layer "In4.Cu")
		(net "P3E_CPU0_PE3_OCP_TXP<4>")
	)
	(segment
		(start 388.303262 -55.2323)
		(end 387.669024 -54.598062)
		(width 0.1143)
		(layer "In4.Cu")
		(net "P3E_CPU0_PE3_OCP_TXP<4>")
	)
	(segment
		(start 449.518786 -56.037988)
		(end 449.27647 -56.280304)
		(width 0.1143)
		(layer "In4.Cu")
		(net "P3E_CPU0_PE3_OCP_TXP<4>")
	)
	(segment
		(start 415.095944 -59.18708)
		(end 410.23286 -59.18708)
		(width 0.1143)
		(layer "In4.Cu")
		(net "P3E_CPU0_PE3_OCP_TXP<4>")
	)
	(segment
		(start 305.688746 -100.52939)
		(end 305.390804 -100.652834)
		(width 0.0889)
		(layer "In4.Cu")
		(net "P3E_CPU0_PE3_OCP_TXP<4>")
	)
	(segment
		(start 349.916242 -63.997332)
		(end 348.648782 -63.700914)
		(width 0.1143)
		(layer "In4.Cu")
		(net "P3E_CPU0_PE3_OCP_TXP<4>")
	)
	(segment
		(start 446.659 -56.7563)
		(end 446.4939 -56.5912)
		(width 0.1143)
		(layer "In4.Cu")
		(net "P3E_CPU0_PE3_OCP_TXP<4>")
	)
	(segment
		(start 450.2912 -53.754274)
		(end 450.4055 -53.868574)
		(width 0.1143)
		(layer "In4.Cu")
		(net "P3E_CPU0_PE3_OCP_TXP<4>")
	)
	(segment
		(start 390.542526 -55.9689)
		(end 389.805926 -55.2323)
		(width 0.1143)
		(layer "In4.Cu")
		(net "P3E_CPU0_PE3_OCP_TXP<4>")
	)
	(segment
		(start 321.948556 -86.000336)
		(end 307.470556 -100.47859)
		(width 0.1143)
		(layer "In4.Cu")
		(net "P3E_CPU0_PE3_OCP_TXP<4>")
	)
	(segment
		(start 350.92767 -63.799974)
		(end 349.916242 -63.997332)
		(width 0.1143)
		(layer "In4.Cu")
		(net "P3E_CPU0_PE3_OCP_TXP<4>")
	)
	(segment
		(start 434.645562 -54.96687)
		(end 430.415954 -54.96687)
		(width 0.1143)
		(layer "In4.Cu")
		(net "P3E_CPU0_PE3_OCP_TXP<4>")
	)
	(segment
		(start 420.590472 -57.558432)
		(end 420.413434 -57.73547)
		(width 0.1143)
		(layer "In4.Cu")
		(net "P3E_CPU0_PE3_OCP_TXP<4>")
	)
	(segment
		(start 303.764442 -100.3554)
		(end 302.493934 -100.881688)
		(width 0.0889)
		(layer "In4.Cu")
		(net "P3E_CPU0_PE3_OCP_TXP<4>")
	)
	(segment
		(start 407.575512 -58.42635)
		(end 406.983184 -57.834022)
		(width 0.1143)
		(layer "In4.Cu")
		(net "P3E_CPU0_PE3_OCP_TXP<4>")
	)
	(segment
		(start 446.4939 -56.5912)
		(end 446.151 -56.5912)
		(width 0.1143)
		(layer "In4.Cu")
		(net "P3E_CPU0_PE3_OCP_TXP<4>")
	)
	(segment
		(start 447.0019 -56.7563)
		(end 446.659 -56.7563)
		(width 0.1143)
		(layer "In4.Cu")
		(net "P3E_CPU0_PE3_OCP_TXP<4>")
	)
	(segment
		(start 446.151 -56.5912)
		(end 445.9859 -56.7563)
		(width 0.1143)
		(layer "In4.Cu")
		(net "P3E_CPU0_PE3_OCP_TXP<4>")
	)
	(segment
		(start 330.402946 -69.550534)
		(end 326.280272 -75.543664)
		(width 0.1143)
		(layer "In4.Cu")
		(net "P3E_CPU0_PE3_OCP_TXP<4>")
	)
	(segment
		(start 372.378732 -53.985668)
		(end 371.729 -54.6354)
		(width 0.1143)
		(layer "In4.Cu")
		(net "P3E_CPU0_PE3_OCP_TXP<4>")
	)
	(segment
		(start 326.280272 -75.543664)
		(end 321.948556 -86.000336)
		(width 0.1143)
		(layer "In4.Cu")
		(net "P3E_CPU0_PE3_OCP_TXP<4>")
	)
	(segment
		(start 450.4055 -55.3847)
		(end 449.752212 -56.037988)
		(width 0.1143)
		(layer "In4.Cu")
		(net "P3E_CPU0_PE3_OCP_TXP<4>")
	)
	(segment
		(start 436.434992 -56.7563)
		(end 434.645562 -54.96687)
		(width 0.1143)
		(layer "In4.Cu")
		(net "P3E_CPU0_PE3_OCP_TXP<4>")
	)
	(segment
		(start 371.729 -54.6354)
		(end 370.082064 -54.6354)
		(width 0.1143)
		(layer "In4.Cu")
		(net "P3E_CPU0_PE3_OCP_TXP<4>")
	)
	(segment
		(start 447.167 -56.5912)
		(end 447.0019 -56.7563)
		(width 0.1143)
		(layer "In4.Cu")
		(net "P3E_CPU0_PE3_OCP_TXP<4>")
	)
	(segment
		(start 302.493934 -100.881688)
		(end 301.043086 -100.881688)
		(width 0.0889)
		(layer "In4.Cu")
		(net "P3E_CPU0_PE3_OCP_TXP<4>")
	)
	(segment
		(start 384.438906 -55.9689)
		(end 381.63373 -53.163724)
		(width 0.1143)
		(layer "In4.Cu")
		(net "P3E_CPU0_PE3_OCP_TXP<4>")
	)
	(segment
		(start 305.390804 -100.652834)
		(end 305.005486 -100.652834)
		(width 0.0889)
		(layer "In4.Cu")
		(net "P3E_CPU0_PE3_OCP_TXP<4>")
	)
	(segment
		(start 448.0179 -56.7563)
		(end 447.675 -56.7563)
		(width 0.1143)
		(layer "In4.Cu")
		(net "P3E_CPU0_PE3_OCP_TXP<4>")
	)
	(segment
		(start 301.043086 -100.881688)
		(end 300.954186 -100.792788)
		(width 0.0889)
		(layer "In4.Cu")
		(net "P3E_CPU0_PE3_OCP_TXP<4>")
	)
	(segment
		(start 375.75109 -53.985668)
		(end 372.378732 -53.985668)
		(width 0.1143)
		(layer "In4.Cu")
		(net "P3E_CPU0_PE3_OCP_TXP<4>")
	)
	(segment
		(start 381.63373 -53.163724)
		(end 376.573034 -53.163724)
		(width 0.1143)
		(layer "In4.Cu")
		(net "P3E_CPU0_PE3_OCP_TXP<4>")
	)
	(segment
		(start 406.024334 -57.570624)
		(end 401.842224 -57.570624)
		(width 0.1143)
		(layer "In4.Cu")
		(net "P3E_CPU0_PE3_OCP_TXP<4>")
	)
	(segment
		(start 304.28692 -100.3554)
		(end 303.764442 -100.3554)
		(width 0.0889)
		(layer "In4.Cu")
		(net "P3E_CPU0_PE3_OCP_TXP<4>")
	)
	(segment
		(start 387.669024 -54.598062)
		(end 386.599684 -54.598062)
		(width 0.1143)
		(layer "In4.Cu")
		(net "P3E_CPU0_PE3_OCP_TXP<4>")
	)
	(segment
		(start 449.27647 -56.280304)
		(end 449.27647 -56.51373)
		(width 0.1143)
		(layer "In4.Cu")
		(net "P3E_CPU0_PE3_OCP_TXP<4>")
	)
	(segment
		(start 376.573034 -53.163724)
		(end 375.75109 -53.985668)
		(width 0.1143)
		(layer "In4.Cu")
		(net "P3E_CPU0_PE3_OCP_TXP<4>")
	)
	(segment
		(start 409.47213 -58.42635)
		(end 407.575512 -58.42635)
		(width 0.1143)
		(layer "In4.Cu")
		(net "P3E_CPU0_PE3_OCP_TXP<4>")
	)
	(segment
		(start 368.514884 -56.20258)
		(end 365.379762 -56.20258)
		(width 0.1143)
		(layer "In4.Cu")
		(net "P3E_CPU0_PE3_OCP_TXP<4>")
	)
	(segment
		(start 300.954186 -100.792788)
		(end 300.954186 -100.481384)
		(width 0.0889)
		(layer "In4.Cu")
		(net "P3E_CPU0_PE3_OCP_TXP<4>")
	)
	(segment
		(start 430.415954 -54.96687)
		(end 428.844456 -56.538368)
		(width 0.1143)
		(layer "In4.Cu")
		(net "P3E_CPU0_PE3_OCP_TXP<4>")
	)
	(segment
		(start 348.648782 -63.700914)
		(end 347.149928 -63.992252)
		(width 0.1143)
		(layer "In4.Cu")
		(net "P3E_CPU0_PE3_OCP_TXP<4>")
	)
	(segment
		(start 347.149928 -63.992252)
		(end 345.912948 -63.70447)
		(width 0.1143)
		(layer "In4.Cu")
		(net "P3E_CPU0_PE3_OCP_TXP<4>")
	)
	(segment
		(start 343.32799 -63.806324)
		(end 337.36788 -64.96685)
		(width 0.1143)
		(layer "In4.Cu")
		(net "P3E_CPU0_PE3_OCP_TXP<4>")
	)
	(segment
		(start 424.749468 -57.558432)
		(end 420.590472 -57.558432)
		(width 0.1143)
		(layer "In4.Cu")
		(net "P3E_CPU0_PE3_OCP_TXP<4>")
	)
	(segment
		(start 400.2405 -55.9689)
		(end 390.542526 -55.9689)
		(width 0.1143)
		(layer "In4.Cu")
		(net "P3E_CPU0_PE3_OCP_TXP<4>")
	)
	(segment
		(start 357.773224 -63.809118)
		(end 356.785672 -63.809118)
		(width 0.1143)
		(layer "In4.Cu")
		(net "P3E_CPU0_PE3_OCP_TXP<4>")
	)
	(segment
		(start 420.413434 -57.73547)
		(end 416.547554 -57.73547)
		(width 0.1143)
		(layer "In4.Cu")
		(net "P3E_CPU0_PE3_OCP_TXP<4>")
	)
	(segment
		(start 356.024942 -64.562736)
		(end 355.384862 -64.690752)
		(width 0.1143)
		(layer "In4.Cu")
		(net "P3E_CPU0_PE3_OCP_TXP<4>")
	)
	(segment
		(start 447.5099 -56.5912)
		(end 447.167 -56.5912)
		(width 0.1143)
		(layer "In4.Cu")
		(net "P3E_CPU0_PE3_OCP_TXP<4>")
	)
	(segment
		(start 448.5259 -56.5912)
		(end 448.183 -56.5912)
		(width 0.1143)
		(layer "In4.Cu")
		(net "P3E_CPU0_PE3_OCP_TXP<4>")
	)
	(segment
		(start 365.379762 -56.20258)
		(end 357.773224 -63.809118)
		(width 0.1143)
		(layer "In4.Cu")
		(net "P3E_CPU0_PE3_OCP_TXP<4>")
	)
	(segment
		(start 355.384862 -64.690752)
		(end 350.92767 -63.799974)
		(width 0.1143)
		(layer "In4.Cu")
		(net "P3E_CPU0_PE3_OCP_TXP<4>")
	)
	(segment
		(start 416.547554 -57.73547)
		(end 415.095944 -59.18708)
		(width 0.1143)
		(layer "In4.Cu")
		(net "P3E_CPU0_PE3_OCP_TXP<4>")
	)
	(segment
		(start 450.4055 -53.868574)
		(end 450.4055 -55.3847)
		(width 0.1143)
		(layer "In4.Cu")
		(net "P3E_CPU0_PE3_OCP_TXP<4>")
	)
	(segment
		(start 449.0339 -56.7563)
		(end 448.691 -56.7563)
		(width 0.1143)
		(layer "In4.Cu")
		(net "P3E_CPU0_PE3_OCP_TXP<4>")
	)
	(segment
		(start 307.470556 -100.47859)
		(end 306.61356 -100.47859)
		(width 0.1143)
		(layer "In4.Cu")
		(net "P3E_CPU0_PE3_OCP_TXP<4>")
	)
	(segment
		(start 449.91655 -53.754274)
		(end 450.2912 -53.754274)
		(width 0.1143)
		(layer "In4.Cu")
		(net "P3E_CPU0_PE3_OCP_TXP<4>")
	)
	(segment
		(start 306.61356 -100.47859)
		(end 306.591462 -100.47859)
		(width 0.0889)
		(layer "In4.Cu")
		(net "P3E_CPU0_PE3_OCP_TXP<4>")
	)
	(segment
		(start 449.752212 -56.037988)
		(end 449.518786 -56.037988)
		(width 0.1143)
		(layer "In4.Cu")
		(net "P3E_CPU0_PE3_OCP_TXP<4>")
	)
	(segment
		(start 406.287732 -57.834022)
		(end 406.024334 -57.570624)
		(width 0.1143)
		(layer "In4.Cu")
		(net "P3E_CPU0_PE3_OCP_TXP<4>")
	)
	(segment
		(start 306.591462 -100.47859)
		(end 306.540662 -100.52939)
		(width 0.0889)
		(layer "In4.Cu")
		(net "P3E_CPU0_PE3_OCP_TXP<4>")
	)
	(segment
		(start 385.228846 -55.9689)
		(end 384.438906 -55.9689)
		(width 0.1143)
		(layer "In4.Cu")
		(net "P3E_CPU0_PE3_OCP_TXP<4>")
	)
	(segment
		(start 386.599684 -54.598062)
		(end 385.228846 -55.9689)
		(width 0.1143)
		(layer "In4.Cu")
		(net "P3E_CPU0_PE3_OCP_TXP<4>")
	)
	(segment
		(start 425.769532 -56.538368)
		(end 424.749468 -57.558432)
		(width 0.1143)
		(layer "In4.Cu")
		(net "P3E_CPU0_PE3_OCP_TXP<4>")
	)
	(segment
		(start 306.540662 -100.52939)
		(end 305.688746 -100.52939)
		(width 0.0889)
		(layer "In4.Cu")
		(net "P3E_CPU0_PE3_OCP_TXP<4>")
	)
	(segment
		(start 345.912948 -63.70447)
		(end 344.266774 -64.025018)
		(width 0.1143)
		(layer "In4.Cu")
		(net "P3E_CPU0_PE3_OCP_TXP<4>")
	)
	(segment
		(start 299.524166 -100.976684)
		(end 300.095666 -100.976684)
		(width 0.1143)
		(layer "F.Cu")
		(net "P3E_CPU0_PE3_OCP_TXP<3>")
	)
	(via
		(at 453.11695 -53.754274)
		(size 0.508)
		(drill 0.254)
		(layers "F.Cu" "B.Cu")
		(net "P3E_CPU0_PE3_OCP_TXP<3>")
	)
	(via
		(at 300.095666 -100.976684)
		(size 0.508)
		(drill 0.254)
		(layers "F.Cu" "B.Cu")
		(net "P3E_CPU0_PE3_OCP_TXP<3>")
	)
	(segment
		(start 453.59955 -52.964334)
		(end 453.59955 -53.271674)
		(width 0.1143)
		(layer "B.Cu")
		(net "P3E_CPU0_PE3_OCP_TXP<3>")
	)
	(segment
		(start 453.2122 -52.735734)
		(end 453.3265 -52.850034)
		(width 0.1143)
		(layer "B.Cu")
		(net "P3E_CPU0_PE3_OCP_TXP<3>")
	)
	(segment
		(start 453.48525 -52.850034)
		(end 453.59955 -52.964334)
		(width 0.1143)
		(layer "B.Cu")
		(net "P3E_CPU0_PE3_OCP_TXP<3>")
	)
	(segment
		(start 453.3265 -52.850034)
		(end 453.48525 -52.850034)
		(width 0.1143)
		(layer "B.Cu")
		(net "P3E_CPU0_PE3_OCP_TXP<3>")
	)
	(segment
		(start 453.2122 -52.330858)
		(end 453.2122 -52.735734)
		(width 0.1143)
		(layer "B.Cu")
		(net "P3E_CPU0_PE3_OCP_TXP<3>")
	)
	(segment
		(start 453.59955 -53.271674)
		(end 453.11695 -53.754274)
		(width 0.1143)
		(layer "B.Cu")
		(net "P3E_CPU0_PE3_OCP_TXP<3>")
	)
	(segment
		(start 389.36041 -55.971186)
		(end 387.012688 -55.971186)
		(width 0.1143)
		(layer "In4.Cu")
		(net "P3E_CPU0_PE3_OCP_TXP<3>")
	)
	(segment
		(start 451.835266 -56.672988)
		(end 451.60184 -56.672988)
		(width 0.1143)
		(layer "In4.Cu")
		(net "P3E_CPU0_PE3_OCP_TXP<3>")
	)
	(segment
		(start 322.500498 -86.347046)
		(end 310.476392 -98.371152)
		(width 0.1143)
		(layer "In4.Cu")
		(net "P3E_CPU0_PE3_OCP_TXP<3>")
	)
	(segment
		(start 451.60184 -56.672988)
		(end 451.359524 -56.915304)
		(width 0.1143)
		(layer "In4.Cu")
		(net "P3E_CPU0_PE3_OCP_TXP<3>")
	)
	(segment
		(start 306.27955 -101.416612)
		(end 306.257452 -101.416612)
		(width 0.0889)
		(layer "In4.Cu")
		(net "P3E_CPU0_PE3_OCP_TXP<3>")
	)
	(segment
		(start 383.283968 -56.64835)
		(end 382.246124 -55.610506)
		(width 0.1143)
		(layer "In4.Cu")
		(net "P3E_CPU0_PE3_OCP_TXP<3>")
	)
	(segment
		(start 452.553578 -55.954676)
		(end 452.320152 -55.954676)
		(width 0.1143)
		(layer "In4.Cu")
		(net "P3E_CPU0_PE3_OCP_TXP<3>")
	)
	(segment
		(start 399.9611 -56.6039)
		(end 389.993124 -56.6039)
		(width 0.1143)
		(layer "In4.Cu")
		(net "P3E_CPU0_PE3_OCP_TXP<3>")
	)
	(segment
		(start 302.15586 -101.776022)
		(end 301.89043 -101.802184)
		(width 0.0889)
		(layer "In4.Cu")
		(net "P3E_CPU0_PE3_OCP_TXP<3>")
	)
	(segment
		(start 301.793402 -101.722428)
		(end 301.527972 -101.74859)
		(width 0.0889)
		(layer "In4.Cu")
		(net "P3E_CPU0_PE3_OCP_TXP<3>")
	)
	(segment
		(start 373.30888 -55.91048)
		(end 372.7196 -55.3212)
		(width 0.1143)
		(layer "In4.Cu")
		(net "P3E_CPU0_PE3_OCP_TXP<3>")
	)
	(segment
		(start 381.272796 -53.798724)
		(end 376.836432 -53.798724)
		(width 0.1143)
		(layer "In4.Cu")
		(net "P3E_CPU0_PE3_OCP_TXP<3>")
	)
	(segment
		(start 302.598074 -101.732334)
		(end 302.501046 -101.652578)
		(width 0.0889)
		(layer "In4.Cu")
		(net "P3E_CPU0_PE3_OCP_TXP<3>")
	)
	(segment
		(start 376.014488 -54.620668)
		(end 375.477532 -54.620668)
		(width 0.1143)
		(layer "In4.Cu")
		(net "P3E_CPU0_PE3_OCP_TXP<3>")
	)
	(segment
		(start 452.077836 -56.430418)
		(end 451.835266 -56.672988)
		(width 0.1143)
		(layer "In4.Cu")
		(net "P3E_CPU0_PE3_OCP_TXP<3>")
	)
	(segment
		(start 337.640168 -65.564004)
		(end 330.836778 -70.041516)
		(width 0.1143)
		(layer "In4.Cu")
		(net "P3E_CPU0_PE3_OCP_TXP<3>")
	)
	(segment
		(start 301.448216 -101.845872)
		(end 301.182786 -101.872034)
		(width 0.0889)
		(layer "In4.Cu")
		(net "P3E_CPU0_PE3_OCP_TXP<3>")
	)
	(segment
		(start 355.439472 -65.35166)
		(end 350.929448 -64.449452)
		(width 0.1143)
		(layer "In4.Cu")
		(net "P3E_CPU0_PE3_OCP_TXP<3>")
	)
	(segment
		(start 303.305718 -101.662484)
		(end 303.20869 -101.582728)
		(width 0.0889)
		(layer "In4.Cu")
		(net "P3E_CPU0_PE3_OCP_TXP<3>")
	)
	(segment
		(start 401.576032 -58.218832)
		(end 399.9611 -56.6039)
		(width 0.1143)
		(layer "In4.Cu")
		(net "P3E_CPU0_PE3_OCP_TXP<3>")
	)
	(segment
		(start 306.206652 -101.467412)
		(end 305.283362 -101.467412)
		(width 0.0889)
		(layer "In4.Cu")
		(net "P3E_CPU0_PE3_OCP_TXP<3>")
	)
	(segment
		(start 304.278792 -101.566472)
		(end 304.013362 -101.592634)
		(width 0.0889)
		(layer "In4.Cu")
		(net "P3E_CPU0_PE3_OCP_TXP<3>")
	)
	(segment
		(start 344.229944 -64.682116)
		(end 343.29243 -64.463168)
		(width 0.1143)
		(layer "In4.Cu")
		(net "P3E_CPU0_PE3_OCP_TXP<3>")
	)
	(segment
		(start 451.359524 -57.14873)
		(end 451.116954 -57.3913)
		(width 0.1143)
		(layer "In4.Cu")
		(net "P3E_CPU0_PE3_OCP_TXP<3>")
	)
	(segment
		(start 453.6059 -54.902354)
		(end 452.553578 -55.954676)
		(width 0.1143)
		(layer "In4.Cu")
		(net "P3E_CPU0_PE3_OCP_TXP<3>")
	)
	(segment
		(start 432.241706 -55.778654)
		(end 431.898806 -55.778654)
		(width 0.1143)
		(layer "In4.Cu")
		(net "P3E_CPU0_PE3_OCP_TXP<3>")
	)
	(segment
		(start 451.116954 -57.3913)
		(end 436.023258 -57.3913)
		(width 0.1143)
		(layer "In4.Cu")
		(net "P3E_CPU0_PE3_OCP_TXP<3>")
	)
	(segment
		(start 425.99864 -57.207658)
		(end 425.012866 -58.193432)
		(width 0.1143)
		(layer "In4.Cu")
		(net "P3E_CPU0_PE3_OCP_TXP<3>")
	)
	(segment
		(start 349.908368 -64.648842)
		(end 348.640908 -64.352424)
		(width 0.1143)
		(layer "In4.Cu")
		(net "P3E_CPU0_PE3_OCP_TXP<3>")
	)
	(segment
		(start 453.4916 -53.754274)
		(end 453.6059 -53.868574)
		(width 0.1143)
		(layer "In4.Cu")
		(net "P3E_CPU0_PE3_OCP_TXP<3>")
	)
	(segment
		(start 416.810952 -58.37047)
		(end 415.359342 -59.82208)
		(width 0.1143)
		(layer "In4.Cu")
		(net "P3E_CPU0_PE3_OCP_TXP<3>")
	)
	(segment
		(start 409.969462 -59.82208)
		(end 409.208732 -59.06135)
		(width 0.1143)
		(layer "In4.Cu")
		(net "P3E_CPU0_PE3_OCP_TXP<3>")
	)
	(segment
		(start 301.89043 -101.802184)
		(end 301.793402 -101.722428)
		(width 0.0889)
		(layer "In4.Cu")
		(net "P3E_CPU0_PE3_OCP_TXP<3>")
	)
	(segment
		(start 405.9936 -58.4708)
		(end 405.741632 -58.218832)
		(width 0.1143)
		(layer "In4.Cu")
		(net "P3E_CPU0_PE3_OCP_TXP<3>")
	)
	(segment
		(start 343.29243 -64.463168)
		(end 337.640168 -65.564004)
		(width 0.1143)
		(layer "In4.Cu")
		(net "P3E_CPU0_PE3_OCP_TXP<3>")
	)
	(segment
		(start 409.208732 -59.06135)
		(end 407.312114 -59.06135)
		(width 0.1143)
		(layer "In4.Cu")
		(net "P3E_CPU0_PE3_OCP_TXP<3>")
	)
	(segment
		(start 431.898806 -55.778654)
		(end 431.733706 -55.613554)
		(width 0.1143)
		(layer "In4.Cu")
		(net "P3E_CPU0_PE3_OCP_TXP<3>")
	)
	(segment
		(start 348.640908 -64.352424)
		(end 347.116908 -64.648588)
		(width 0.1143)
		(layer "In4.Cu")
		(net "P3E_CPU0_PE3_OCP_TXP<3>")
	)
	(segment
		(start 299.80255 -100.807774)
		(end 300.095666 -100.976684)
		(width 0.0889)
		(layer "In4.Cu")
		(net "P3E_CPU0_PE3_OCP_TXP<3>")
	)
	(segment
		(start 330.836778 -70.041516)
		(end 326.859646 -75.823064)
		(width 0.1143)
		(layer "In4.Cu")
		(net "P3E_CPU0_PE3_OCP_TXP<3>")
	)
	(segment
		(start 368.681 -57.056528)
		(end 365.440468 -57.056528)
		(width 0.1143)
		(layer "In4.Cu")
		(net "P3E_CPU0_PE3_OCP_TXP<3>")
	)
	(segment
		(start 356.362508 -65.167002)
		(end 355.439472 -65.35166)
		(width 0.1143)
		(layer "In4.Cu")
		(net "P3E_CPU0_PE3_OCP_TXP<3>")
	)
	(segment
		(start 365.440468 -57.056528)
		(end 358.021382 -64.475614)
		(width 0.1143)
		(layer "In4.Cu")
		(net "P3E_CPU0_PE3_OCP_TXP<3>")
	)
	(segment
		(start 432.406806 -55.613554)
		(end 432.241706 -55.778654)
		(width 0.1143)
		(layer "In4.Cu")
		(net "P3E_CPU0_PE3_OCP_TXP<3>")
	)
	(segment
		(start 431.733706 -55.613554)
		(end 431.390806 -55.613554)
		(width 0.1143)
		(layer "In4.Cu")
		(net "P3E_CPU0_PE3_OCP_TXP<3>")
	)
	(segment
		(start 452.077836 -56.196992)
		(end 452.077836 -56.430418)
		(width 0.1143)
		(layer "In4.Cu")
		(net "P3E_CPU0_PE3_OCP_TXP<3>")
	)
	(segment
		(start 306.257452 -101.416612)
		(end 306.206652 -101.467412)
		(width 0.0889)
		(layer "In4.Cu")
		(net "P3E_CPU0_PE3_OCP_TXP<3>")
	)
	(segment
		(start 406.721564 -58.4708)
		(end 405.9936 -58.4708)
		(width 0.1143)
		(layer "In4.Cu")
		(net "P3E_CPU0_PE3_OCP_TXP<3>")
	)
	(segment
		(start 425.012866 -58.193432)
		(end 420.85387 -58.193432)
		(width 0.1143)
		(layer "In4.Cu")
		(net "P3E_CPU0_PE3_OCP_TXP<3>")
	)
	(segment
		(start 434.410612 -55.778654)
		(end 432.914806 -55.778654)
		(width 0.1143)
		(layer "In4.Cu")
		(net "P3E_CPU0_PE3_OCP_TXP<3>")
	)
	(segment
		(start 453.11695 -53.754274)
		(end 453.4916 -53.754274)
		(width 0.1143)
		(layer "In4.Cu")
		(net "P3E_CPU0_PE3_OCP_TXP<3>")
	)
	(segment
		(start 372.7196 -55.3212)
		(end 370.416328 -55.3212)
		(width 0.1143)
		(layer "In4.Cu")
		(net "P3E_CPU0_PE3_OCP_TXP<3>")
	)
	(segment
		(start 304.013362 -101.592634)
		(end 303.916334 -101.512878)
		(width 0.0889)
		(layer "In4.Cu")
		(net "P3E_CPU0_PE3_OCP_TXP<3>")
	)
	(segment
		(start 370.416328 -55.3212)
		(end 368.681 -57.056528)
		(width 0.1143)
		(layer "In4.Cu")
		(net "P3E_CPU0_PE3_OCP_TXP<3>")
	)
	(segment
		(start 430.502568 -55.778654)
		(end 429.073564 -57.207658)
		(width 0.1143)
		(layer "In4.Cu")
		(net "P3E_CPU0_PE3_OCP_TXP<3>")
	)
	(segment
		(start 387.012688 -55.971186)
		(end 386.335524 -56.64835)
		(width 0.1143)
		(layer "In4.Cu")
		(net "P3E_CPU0_PE3_OCP_TXP<3>")
	)
	(segment
		(start 375.477532 -54.620668)
		(end 374.18772 -55.91048)
		(width 0.1143)
		(layer "In4.Cu")
		(net "P3E_CPU0_PE3_OCP_TXP<3>")
	)
	(segment
		(start 300.10862 -101.376734)
		(end 300.08449 -101.376734)
		(width 0.0889)
		(layer "In4.Cu")
		(net "P3E_CPU0_PE3_OCP_TXP<3>")
	)
	(segment
		(start 303.20869 -101.582728)
		(end 302.94326 -101.60889)
		(width 0.0889)
		(layer "In4.Cu")
		(net "P3E_CPU0_PE3_OCP_TXP<3>")
	)
	(segment
		(start 310.476138 -98.371152)
		(end 307.430678 -101.416612)
		(width 0.1143)
		(layer "In4.Cu")
		(net "P3E_CPU0_PE3_OCP_TXP<3>")
	)
	(segment
		(start 350.929448 -64.449452)
		(end 349.908368 -64.648842)
		(width 0.1143)
		(layer "In4.Cu")
		(net "P3E_CPU0_PE3_OCP_TXP<3>")
	)
	(segment
		(start 307.430678 -101.416612)
		(end 306.27955 -101.416612)
		(width 0.1143)
		(layer "In4.Cu")
		(net "P3E_CPU0_PE3_OCP_TXP<3>")
	)
	(segment
		(start 386.335524 -56.64835)
		(end 383.283968 -56.64835)
		(width 0.1143)
		(layer "In4.Cu")
		(net "P3E_CPU0_PE3_OCP_TXP<3>")
	)
	(segment
		(start 304.623978 -101.443028)
		(end 304.358548 -101.46919)
		(width 0.0889)
		(layer "In4.Cu")
		(net "P3E_CPU0_PE3_OCP_TXP<3>")
	)
	(segment
		(start 303.571148 -101.636322)
		(end 303.305718 -101.662484)
		(width 0.0889)
		(layer "In4.Cu")
		(net "P3E_CPU0_PE3_OCP_TXP<3>")
	)
	(segment
		(start 302.94326 -101.60889)
		(end 302.863504 -101.706172)
		(width 0.0889)
		(layer "In4.Cu")
		(net "P3E_CPU0_PE3_OCP_TXP<3>")
	)
	(segment
		(start 326.859646 -75.823064)
		(end 322.500498 -86.347046)
		(width 0.1143)
		(layer "In4.Cu")
		(net "P3E_CPU0_PE3_OCP_TXP<3>")
	)
	(segment
		(start 305.283362 -101.467412)
		(end 304.721006 -101.522784)
		(width 0.0889)
		(layer "In4.Cu")
		(net "P3E_CPU0_PE3_OCP_TXP<3>")
	)
	(segment
		(start 310.476392 -98.371152)
		(end 310.476138 -98.371152)
		(width 0.1143)
		(layer "In4.Cu")
		(net "P3E_CPU0_PE3_OCP_TXP<3>")
	)
	(segment
		(start 382.246124 -54.772052)
		(end 381.272796 -53.798724)
		(width 0.1143)
		(layer "In4.Cu")
		(net "P3E_CPU0_PE3_OCP_TXP<3>")
	)
	(segment
		(start 304.721006 -101.522784)
		(end 304.623978 -101.443028)
		(width 0.0889)
		(layer "In4.Cu")
		(net "P3E_CPU0_PE3_OCP_TXP<3>")
	)
	(segment
		(start 453.6059 -53.868574)
		(end 453.6059 -54.902354)
		(width 0.1143)
		(layer "In4.Cu")
		(net "P3E_CPU0_PE3_OCP_TXP<3>")
	)
	(segment
		(start 302.863504 -101.706172)
		(end 302.598074 -101.732334)
		(width 0.0889)
		(layer "In4.Cu")
		(net "P3E_CPU0_PE3_OCP_TXP<3>")
	)
	(segment
		(start 374.18772 -55.91048)
		(end 373.30888 -55.91048)
		(width 0.1143)
		(layer "In4.Cu")
		(net "P3E_CPU0_PE3_OCP_TXP<3>")
	)
	(segment
		(start 376.836432 -53.798724)
		(end 376.014488 -54.620668)
		(width 0.1143)
		(layer "In4.Cu")
		(net "P3E_CPU0_PE3_OCP_TXP<3>")
	)
	(segment
		(start 451.359524 -56.915304)
		(end 451.359524 -57.14873)
		(width 0.1143)
		(layer "In4.Cu")
		(net "P3E_CPU0_PE3_OCP_TXP<3>")
	)
	(segment
		(start 420.85387 -58.193432)
		(end 420.676832 -58.37047)
		(width 0.1143)
		(layer "In4.Cu")
		(net "P3E_CPU0_PE3_OCP_TXP<3>")
	)
	(segment
		(start 302.235616 -101.67874)
		(end 302.15586 -101.776022)
		(width 0.0889)
		(layer "In4.Cu")
		(net "P3E_CPU0_PE3_OCP_TXP<3>")
	)
	(segment
		(start 389.993124 -56.6039)
		(end 389.36041 -55.971186)
		(width 0.1143)
		(layer "In4.Cu")
		(net "P3E_CPU0_PE3_OCP_TXP<3>")
	)
	(segment
		(start 405.741632 -58.218832)
		(end 401.576032 -58.218832)
		(width 0.1143)
		(layer "In4.Cu")
		(net "P3E_CPU0_PE3_OCP_TXP<3>")
	)
	(segment
		(start 415.359342 -59.82208)
		(end 409.969462 -59.82208)
		(width 0.1143)
		(layer "In4.Cu")
		(net "P3E_CPU0_PE3_OCP_TXP<3>")
	)
	(segment
		(start 432.749706 -55.613554)
		(end 432.406806 -55.613554)
		(width 0.1143)
		(layer "In4.Cu")
		(net "P3E_CPU0_PE3_OCP_TXP<3>")
	)
	(segment
		(start 429.073564 -57.207658)
		(end 425.99864 -57.207658)
		(width 0.1143)
		(layer "In4.Cu")
		(net "P3E_CPU0_PE3_OCP_TXP<3>")
	)
	(segment
		(start 302.501046 -101.652578)
		(end 302.235616 -101.67874)
		(width 0.0889)
		(layer "In4.Cu")
		(net "P3E_CPU0_PE3_OCP_TXP<3>")
	)
	(segment
		(start 304.358548 -101.46919)
		(end 304.278792 -101.566472)
		(width 0.0889)
		(layer "In4.Cu")
		(net "P3E_CPU0_PE3_OCP_TXP<3>")
	)
	(segment
		(start 382.246124 -55.610506)
		(end 382.246124 -54.772052)
		(width 0.1143)
		(layer "In4.Cu")
		(net "P3E_CPU0_PE3_OCP_TXP<3>")
	)
	(segment
		(start 431.225706 -55.778654)
		(end 430.502568 -55.778654)
		(width 0.1143)
		(layer "In4.Cu")
		(net "P3E_CPU0_PE3_OCP_TXP<3>")
	)
	(segment
		(start 303.650904 -101.53904)
		(end 303.571148 -101.636322)
		(width 0.0889)
		(layer "In4.Cu")
		(net "P3E_CPU0_PE3_OCP_TXP<3>")
	)
	(segment
		(start 431.390806 -55.613554)
		(end 431.225706 -55.778654)
		(width 0.1143)
		(layer "In4.Cu")
		(net "P3E_CPU0_PE3_OCP_TXP<3>")
	)
	(segment
		(start 420.676832 -58.37047)
		(end 416.810952 -58.37047)
		(width 0.1143)
		(layer "In4.Cu")
		(net "P3E_CPU0_PE3_OCP_TXP<3>")
	)
	(segment
		(start 301.527972 -101.74859)
		(end 301.448216 -101.845872)
		(width 0.0889)
		(layer "In4.Cu")
		(net "P3E_CPU0_PE3_OCP_TXP<3>")
	)
	(segment
		(start 436.023258 -57.3913)
		(end 434.410612 -55.778654)
		(width 0.1143)
		(layer "In4.Cu")
		(net "P3E_CPU0_PE3_OCP_TXP<3>")
	)
	(segment
		(start 301.182786 -101.872034)
		(end 300.9392 -101.872034)
		(width 0.0889)
		(layer "In4.Cu")
		(net "P3E_CPU0_PE3_OCP_TXP<3>")
	)
	(segment
		(start 299.72381 -100.82911)
		(end 299.80255 -100.807774)
		(width 0.0889)
		(layer "In4.Cu")
		(net "P3E_CPU0_PE3_OCP_TXP<3>")
	)
	(segment
		(start 452.320152 -55.954676)
		(end 452.077836 -56.196992)
		(width 0.1143)
		(layer "In4.Cu")
		(net "P3E_CPU0_PE3_OCP_TXP<3>")
	)
	(segment
		(start 358.021382 -64.475614)
		(end 357.05923 -64.475614)
		(width 0.1143)
		(layer "In4.Cu")
		(net "P3E_CPU0_PE3_OCP_TXP<3>")
	)
	(segment
		(start 407.312114 -59.06135)
		(end 406.721564 -58.4708)
		(width 0.1143)
		(layer "In4.Cu")
		(net "P3E_CPU0_PE3_OCP_TXP<3>")
	)
	(segment
		(start 303.916334 -101.512878)
		(end 303.650904 -101.53904)
		(width 0.0889)
		(layer "In4.Cu")
		(net "P3E_CPU0_PE3_OCP_TXP<3>")
	)
	(segment
		(start 357.05923 -64.475614)
		(end 356.362508 -65.167002)
		(width 0.1143)
		(layer "In4.Cu")
		(net "P3E_CPU0_PE3_OCP_TXP<3>")
	)
	(segment
		(start 347.116908 -64.648588)
		(end 345.879928 -64.360806)
		(width 0.1143)
		(layer "In4.Cu")
		(net "P3E_CPU0_PE3_OCP_TXP<3>")
	)
	(segment
		(start 432.914806 -55.778654)
		(end 432.749706 -55.613554)
		(width 0.1143)
		(layer "In4.Cu")
		(net "P3E_CPU0_PE3_OCP_TXP<3>")
	)
	(segment
		(start 345.879928 -64.360806)
		(end 344.229944 -64.682116)
		(width 0.1143)
		(layer "In4.Cu")
		(net "P3E_CPU0_PE3_OCP_TXP<3>")
	)
	(arc
		(start 300.08449 -101.376734)
		(mid 299.761466 -101.196855)
		(end 299.72381 -100.82911)
		(width 0.0889)
		(layer "In4.Cu")
		(net "P3E_CPU0_PE3_OCP_TXP<3>")
	)
	(arc
		(start 300.9392 -101.872034)
		(mid 300.747558 -101.814868)
		(end 300.607476 -101.672136)
		(width 0.0889)
		(layer "In4.Cu")
		(net "P3E_CPU0_PE3_OCP_TXP<3>")
	)
	(arc
		(start 300.607476 -101.672136)
		(mid 300.396763 -101.459057)
		(end 300.10862 -101.376734)
		(width 0.0889)
		(layer "In4.Cu")
		(net "P3E_CPU0_PE3_OCP_TXP<3>")
	)
	(segment
		(start 298.665646 -101.471984)
		(end 299.237146 -101.471984)
		(width 0.1143)
		(layer "F.Cu")
		(net "P3E_CPU0_PE3_OCP_TXP<2>")
	)
	(via
		(at 299.237146 -101.471984)
		(size 0.508)
		(drill 0.254)
		(layers "F.Cu" "B.Cu")
		(net "P3E_CPU0_PE3_OCP_TXP<2>")
	)
	(via
		(at 456.317604 -53.906674)
		(size 0.508)
		(drill 0.254)
		(layers "F.Cu" "B.Cu")
		(net "P3E_CPU0_PE3_OCP_TXP<2>")
	)
	(segment
		(start 456.4888 -52.888134)
		(end 456.6031 -53.002434)
		(width 0.1143)
		(layer "B.Cu")
		(net "P3E_CPU0_PE3_OCP_TXP<2>")
	)
	(segment
		(start 456.87615 -53.3908)
		(end 456.360276 -53.906674)
		(width 0.1143)
		(layer "B.Cu")
		(net "P3E_CPU0_PE3_OCP_TXP<2>")
	)
	(segment
		(start 456.87615 -53.116734)
		(end 456.87615 -53.3908)
		(width 0.1143)
		(layer "B.Cu")
		(net "P3E_CPU0_PE3_OCP_TXP<2>")
	)
	(segment
		(start 456.6031 -53.002434)
		(end 456.76185 -53.002434)
		(width 0.1143)
		(layer "B.Cu")
		(net "P3E_CPU0_PE3_OCP_TXP<2>")
	)
	(segment
		(start 456.360276 -53.906674)
		(end 456.317604 -53.906674)
		(width 0.1143)
		(layer "B.Cu")
		(net "P3E_CPU0_PE3_OCP_TXP<2>")
	)
	(segment
		(start 456.76185 -53.002434)
		(end 456.87615 -53.116734)
		(width 0.1143)
		(layer "B.Cu")
		(net "P3E_CPU0_PE3_OCP_TXP<2>")
	)
	(segment
		(start 456.4888 -52.483258)
		(end 456.4888 -52.888134)
		(width 0.1143)
		(layer "B.Cu")
		(net "P3E_CPU0_PE3_OCP_TXP<2>")
	)
	(segment
		(start 415.849816 -60.3504)
		(end 413.873696 -62.32652)
		(width 0.1143)
		(layer "In4.Cu")
		(net "P3E_CPU0_PE3_OCP_TXP<2>")
	)
	(segment
		(start 412.90748 -62.32652)
		(end 411.558232 -60.977272)
		(width 0.1143)
		(layer "In4.Cu")
		(net "P3E_CPU0_PE3_OCP_TXP<2>")
	)
	(segment
		(start 434.889656 -57.417716)
		(end 434.647086 -57.175146)
		(width 0.1143)
		(layer "In4.Cu")
		(net "P3E_CPU0_PE3_OCP_TXP<2>")
	)
	(segment
		(start 355.423216 -66.03238)
		(end 350.844866 -65.116202)
		(width 0.1143)
		(layer "In4.Cu")
		(net "P3E_CPU0_PE3_OCP_TXP<2>")
	)
	(segment
		(start 456.751182 -54.079902)
		(end 456.751182 -54.830218)
		(width 0.1143)
		(layer "In4.Cu")
		(net "P3E_CPU0_PE3_OCP_TXP<2>")
	)
	(segment
		(start 405.728678 -59.10834)
		(end 405.47417 -58.853832)
		(width 0.1143)
		(layer "In4.Cu")
		(net "P3E_CPU0_PE3_OCP_TXP<2>")
	)
	(segment
		(start 454.414382 -57.167018)
		(end 454.171812 -57.409588)
		(width 0.1143)
		(layer "In4.Cu")
		(net "P3E_CPU0_PE3_OCP_TXP<2>")
	)
	(segment
		(start 419.910768 -59.00547)
		(end 418.565838 -60.3504)
		(width 0.1143)
		(layer "In4.Cu")
		(net "P3E_CPU0_PE3_OCP_TXP<2>")
	)
	(segment
		(start 327.468738 -76.05903)
		(end 323.035168 -86.76386)
		(width 0.1143)
		(layer "In4.Cu")
		(net "P3E_CPU0_PE3_OCP_TXP<2>")
	)
	(segment
		(start 407.048716 -59.69635)
		(end 406.460706 -59.10834)
		(width 0.1143)
		(layer "In4.Cu")
		(net "P3E_CPU0_PE3_OCP_TXP<2>")
	)
	(segment
		(start 347.111574 -65.29959)
		(end 345.87561 -65.012062)
		(width 0.1143)
		(layer "In4.Cu")
		(net "P3E_CPU0_PE3_OCP_TXP<2>")
	)
	(segment
		(start 377.09983 -54.433724)
		(end 376.250454 -55.2831)
		(width 0.1143)
		(layer "In4.Cu")
		(net "P3E_CPU0_PE3_OCP_TXP<2>")
	)
	(segment
		(start 434.647086 -56.94172)
		(end 434.40477 -56.699404)
		(width 0.1143)
		(layer "In4.Cu")
		(net "P3E_CPU0_PE3_OCP_TXP<2>")
	)
	(segment
		(start 399.748502 -57.2897)
		(end 390.579356 -57.2897)
		(width 0.1143)
		(layer "In4.Cu")
		(net "P3E_CPU0_PE3_OCP_TXP<2>")
	)
	(segment
		(start 453.69607 -57.651904)
		(end 453.69607 -57.88533)
		(width 0.1143)
		(layer "In4.Cu")
		(net "P3E_CPU0_PE3_OCP_TXP<2>")
	)
	(segment
		(start 376.250454 -55.2831)
		(end 375.8819 -55.2831)
		(width 0.1143)
		(layer "In4.Cu")
		(net "P3E_CPU0_PE3_OCP_TXP<2>")
	)
	(segment
		(start 380.822708 -54.433724)
		(end 377.09983 -54.433724)
		(width 0.1143)
		(layer "In4.Cu")
		(net "P3E_CPU0_PE3_OCP_TXP<2>")
	)
	(segment
		(start 381.510286 -56.065674)
		(end 381.510286 -55.121302)
		(width 0.1143)
		(layer "In4.Cu")
		(net "P3E_CPU0_PE3_OCP_TXP<2>")
	)
	(segment
		(start 307.421788 -102.37724)
		(end 306.980082 -102.37724)
		(width 0.1143)
		(layer "In4.Cu")
		(net "P3E_CPU0_PE3_OCP_TXP<2>")
	)
	(segment
		(start 343.23782 -65.123822)
		(end 337.953858 -66.15303)
		(width 0.1143)
		(layer "In4.Cu")
		(net "P3E_CPU0_PE3_OCP_TXP<2>")
	)
	(segment
		(start 421.117268 -58.828432)
		(end 420.94023 -59.00547)
		(width 0.1143)
		(layer "In4.Cu")
		(net "P3E_CPU0_PE3_OCP_TXP<2>")
	)
	(segment
		(start 306.957984 -102.37724)
		(end 306.907184 -102.42804)
		(width 0.0889)
		(layer "In4.Cu")
		(net "P3E_CPU0_PE3_OCP_TXP<2>")
	)
	(segment
		(start 434.171344 -56.699404)
		(end 433.91328 -56.44134)
		(width 0.1143)
		(layer "In4.Cu")
		(net "P3E_CPU0_PE3_OCP_TXP<2>")
	)
	(segment
		(start 306.12461 -102.33914)
		(end 305.84521 -102.33914)
		(width 0.0889)
		(layer "In4.Cu")
		(net "P3E_CPU0_PE3_OCP_TXP<2>")
	)
	(segment
		(start 456.751182 -54.830218)
		(end 454.890378 -56.691022)
		(width 0.1143)
		(layer "In4.Cu")
		(net "P3E_CPU0_PE3_OCP_TXP<2>")
	)
	(segment
		(start 323.035168 -86.76386)
		(end 307.421788 -102.37724)
		(width 0.1143)
		(layer "In4.Cu")
		(net "P3E_CPU0_PE3_OCP_TXP<2>")
	)
	(segment
		(start 306.980082 -102.37724)
		(end 306.957984 -102.37724)
		(width 0.0889)
		(layer "In4.Cu")
		(net "P3E_CPU0_PE3_OCP_TXP<2>")
	)
	(segment
		(start 410.226256 -60.977272)
		(end 408.945334 -59.69635)
		(width 0.1143)
		(layer "In4.Cu")
		(net "P3E_CPU0_PE3_OCP_TXP<2>")
	)
	(segment
		(start 299.4279 -101.872034)
		(end 299.22216 -101.872034)
		(width 0.0889)
		(layer "In4.Cu")
		(net "P3E_CPU0_PE3_OCP_TXP<2>")
	)
	(segment
		(start 420.94023 -59.00547)
		(end 419.910768 -59.00547)
		(width 0.1143)
		(layer "In4.Cu")
		(net "P3E_CPU0_PE3_OCP_TXP<2>")
	)
	(segment
		(start 434.647086 -57.175146)
		(end 434.647086 -56.94172)
		(width 0.1143)
		(layer "In4.Cu")
		(net "P3E_CPU0_PE3_OCP_TXP<2>")
	)
	(segment
		(start 406.460706 -59.10834)
		(end 405.728678 -59.10834)
		(width 0.1143)
		(layer "In4.Cu")
		(net "P3E_CPU0_PE3_OCP_TXP<2>")
	)
	(segment
		(start 305.75631 -102.42804)
		(end 305.47691 -102.42804)
		(width 0.0889)
		(layer "In4.Cu")
		(net "P3E_CPU0_PE3_OCP_TXP<2>")
	)
	(segment
		(start 425.295568 -58.828432)
		(end 421.117268 -58.828432)
		(width 0.1143)
		(layer "In4.Cu")
		(net "P3E_CPU0_PE3_OCP_TXP<2>")
	)
	(segment
		(start 369.934998 -56.7944)
		(end 369.03787 -57.691528)
		(width 0.1143)
		(layer "In4.Cu")
		(net "P3E_CPU0_PE3_OCP_TXP<2>")
	)
	(segment
		(start 405.47417 -58.853832)
		(end 401.312634 -58.853832)
		(width 0.1143)
		(layer "In4.Cu")
		(net "P3E_CPU0_PE3_OCP_TXP<2>")
	)
	(segment
		(start 369.03787 -57.691528)
		(end 365.745014 -57.691528)
		(width 0.1143)
		(layer "In4.Cu")
		(net "P3E_CPU0_PE3_OCP_TXP<2>")
	)
	(segment
		(start 358.306878 -65.129664)
		(end 357.30434 -65.129664)
		(width 0.1143)
		(layer "In4.Cu")
		(net "P3E_CPU0_PE3_OCP_TXP<2>")
	)
	(segment
		(start 408.945334 -59.69635)
		(end 407.048716 -59.69635)
		(width 0.1143)
		(layer "In4.Cu")
		(net "P3E_CPU0_PE3_OCP_TXP<2>")
	)
	(segment
		(start 306.21351 -102.42804)
		(end 306.12461 -102.33914)
		(width 0.0889)
		(layer "In4.Cu")
		(net "P3E_CPU0_PE3_OCP_TXP<2>")
	)
	(segment
		(start 454.656952 -56.691022)
		(end 454.414382 -56.933592)
		(width 0.1143)
		(layer "In4.Cu")
		(net "P3E_CPU0_PE3_OCP_TXP<2>")
	)
	(segment
		(start 374.3706 -56.7944)
		(end 369.934998 -56.7944)
		(width 0.1143)
		(layer "In4.Cu")
		(net "P3E_CPU0_PE3_OCP_TXP<2>")
	)
	(segment
		(start 356.642416 -65.789302)
		(end 355.423216 -66.03238)
		(width 0.1143)
		(layer "In4.Cu")
		(net "P3E_CPU0_PE3_OCP_TXP<2>")
	)
	(segment
		(start 375.8819 -55.2831)
		(end 374.3706 -56.7944)
		(width 0.1143)
		(layer "In4.Cu")
		(net "P3E_CPU0_PE3_OCP_TXP<2>")
	)
	(segment
		(start 411.558232 -60.977272)
		(end 410.226256 -60.977272)
		(width 0.1143)
		(layer "In4.Cu")
		(net "P3E_CPU0_PE3_OCP_TXP<2>")
	)
	(segment
		(start 305.84521 -102.33914)
		(end 305.75631 -102.42804)
		(width 0.0889)
		(layer "In4.Cu")
		(net "P3E_CPU0_PE3_OCP_TXP<2>")
	)
	(segment
		(start 300.624494 -102.367588)
		(end 299.4279 -101.872034)
		(width 0.0889)
		(layer "In4.Cu")
		(net "P3E_CPU0_PE3_OCP_TXP<2>")
	)
	(segment
		(start 306.907184 -102.42804)
		(end 306.21351 -102.42804)
		(width 0.0889)
		(layer "In4.Cu")
		(net "P3E_CPU0_PE3_OCP_TXP<2>")
	)
	(segment
		(start 418.565838 -60.3504)
		(end 415.849816 -60.3504)
		(width 0.1143)
		(layer "In4.Cu")
		(net "P3E_CPU0_PE3_OCP_TXP<2>")
	)
	(segment
		(start 345.87561 -65.012062)
		(end 344.17508 -65.34277)
		(width 0.1143)
		(layer "In4.Cu")
		(net "P3E_CPU0_PE3_OCP_TXP<2>")
	)
	(segment
		(start 453.69607 -57.88533)
		(end 453.445372 -58.136028)
		(width 0.1143)
		(layer "In4.Cu")
		(net "P3E_CPU0_PE3_OCP_TXP<2>")
	)
	(segment
		(start 390.407144 -57.461912)
		(end 382.906524 -57.461912)
		(width 0.1143)
		(layer "In4.Cu")
		(net "P3E_CPU0_PE3_OCP_TXP<2>")
	)
	(segment
		(start 433.91328 -56.44134)
		(end 430.73828 -56.44134)
		(width 0.1143)
		(layer "In4.Cu")
		(net "P3E_CPU0_PE3_OCP_TXP<2>")
	)
	(segment
		(start 454.890378 -56.691022)
		(end 454.656952 -56.691022)
		(width 0.1143)
		(layer "In4.Cu")
		(net "P3E_CPU0_PE3_OCP_TXP<2>")
	)
	(segment
		(start 454.171812 -57.409588)
		(end 453.938386 -57.409588)
		(width 0.1143)
		(layer "In4.Cu")
		(net "P3E_CPU0_PE3_OCP_TXP<2>")
	)
	(segment
		(start 305.38801 -102.33914)
		(end 305.10861 -102.33914)
		(width 0.0889)
		(layer "In4.Cu")
		(net "P3E_CPU0_PE3_OCP_TXP<2>")
	)
	(segment
		(start 357.30434 -65.129664)
		(end 356.642416 -65.789302)
		(width 0.1143)
		(layer "In4.Cu")
		(net "P3E_CPU0_PE3_OCP_TXP<2>")
	)
	(segment
		(start 365.745014 -57.691528)
		(end 358.306878 -65.129664)
		(width 0.1143)
		(layer "In4.Cu")
		(net "P3E_CPU0_PE3_OCP_TXP<2>")
	)
	(segment
		(start 304.59426 -102.367588)
		(end 300.624494 -102.367588)
		(width 0.0889)
		(layer "In4.Cu")
		(net "P3E_CPU0_PE3_OCP_TXP<2>")
	)
	(segment
		(start 350.844866 -65.116202)
		(end 349.900494 -65.300352)
		(width 0.1143)
		(layer "In4.Cu")
		(net "P3E_CPU0_PE3_OCP_TXP<2>")
	)
	(segment
		(start 434.40477 -56.699404)
		(end 434.171344 -56.699404)
		(width 0.1143)
		(layer "In4.Cu")
		(net "P3E_CPU0_PE3_OCP_TXP<2>")
	)
	(segment
		(start 298.94403 -101.641148)
		(end 299.237146 -101.471984)
		(width 0.0889)
		(layer "In4.Cu")
		(net "P3E_CPU0_PE3_OCP_TXP<2>")
	)
	(segment
		(start 435.365398 -57.893458)
		(end 435.365398 -57.660032)
		(width 0.1143)
		(layer "In4.Cu")
		(net "P3E_CPU0_PE3_OCP_TXP<2>")
	)
	(segment
		(start 344.17508 -65.34277)
		(end 343.23782 -65.123822)
		(width 0.1143)
		(layer "In4.Cu")
		(net "P3E_CPU0_PE3_OCP_TXP<2>")
	)
	(segment
		(start 453.938386 -57.409588)
		(end 453.69607 -57.651904)
		(width 0.1143)
		(layer "In4.Cu")
		(net "P3E_CPU0_PE3_OCP_TXP<2>")
	)
	(segment
		(start 305.47691 -102.42804)
		(end 305.38801 -102.33914)
		(width 0.0889)
		(layer "In4.Cu")
		(net "P3E_CPU0_PE3_OCP_TXP<2>")
	)
	(segment
		(start 454.414382 -56.933592)
		(end 454.414382 -57.167018)
		(width 0.1143)
		(layer "In4.Cu")
		(net "P3E_CPU0_PE3_OCP_TXP<2>")
	)
	(segment
		(start 337.953858 -66.15303)
		(end 331.245972 -70.568058)
		(width 0.1143)
		(layer "In4.Cu")
		(net "P3E_CPU0_PE3_OCP_TXP<2>")
	)
	(segment
		(start 382.906524 -57.461912)
		(end 381.510286 -56.065674)
		(width 0.1143)
		(layer "In4.Cu")
		(net "P3E_CPU0_PE3_OCP_TXP<2>")
	)
	(segment
		(start 435.365398 -57.660032)
		(end 435.123082 -57.417716)
		(width 0.1143)
		(layer "In4.Cu")
		(net "P3E_CPU0_PE3_OCP_TXP<2>")
	)
	(segment
		(start 453.445372 -58.136028)
		(end 435.607968 -58.136028)
		(width 0.1143)
		(layer "In4.Cu")
		(net "P3E_CPU0_PE3_OCP_TXP<2>")
	)
	(segment
		(start 430.73828 -56.44134)
		(end 429.336962 -57.842658)
		(width 0.1143)
		(layer "In4.Cu")
		(net "P3E_CPU0_PE3_OCP_TXP<2>")
	)
	(segment
		(start 435.123082 -57.417716)
		(end 434.889656 -57.417716)
		(width 0.1143)
		(layer "In4.Cu")
		(net "P3E_CPU0_PE3_OCP_TXP<2>")
	)
	(segment
		(start 413.873696 -62.32652)
		(end 412.90748 -62.32652)
		(width 0.1143)
		(layer "In4.Cu")
		(net "P3E_CPU0_PE3_OCP_TXP<2>")
	)
	(segment
		(start 348.633034 -65.003934)
		(end 347.111574 -65.29959)
		(width 0.1143)
		(layer "In4.Cu")
		(net "P3E_CPU0_PE3_OCP_TXP<2>")
	)
	(segment
		(start 305.10861 -102.33914)
		(end 305.01971 -102.42804)
		(width 0.0889)
		(layer "In4.Cu")
		(net "P3E_CPU0_PE3_OCP_TXP<2>")
	)
	(segment
		(start 429.336962 -57.842658)
		(end 426.281342 -57.842658)
		(width 0.1143)
		(layer "In4.Cu")
		(net "P3E_CPU0_PE3_OCP_TXP<2>")
	)
	(segment
		(start 305.01971 -102.42804)
		(end 304.74031 -102.42804)
		(width 0.0889)
		(layer "In4.Cu")
		(net "P3E_CPU0_PE3_OCP_TXP<2>")
	)
	(segment
		(start 304.74031 -102.42804)
		(end 304.59426 -102.367588)
		(width 0.0889)
		(layer "In4.Cu")
		(net "P3E_CPU0_PE3_OCP_TXP<2>")
	)
	(segment
		(start 381.510286 -55.121302)
		(end 380.822708 -54.433724)
		(width 0.1143)
		(layer "In4.Cu")
		(net "P3E_CPU0_PE3_OCP_TXP<2>")
	)
	(segment
		(start 390.579356 -57.2897)
		(end 390.407144 -57.461912)
		(width 0.1143)
		(layer "In4.Cu")
		(net "P3E_CPU0_PE3_OCP_TXP<2>")
	)
	(segment
		(start 401.312634 -58.853832)
		(end 399.748502 -57.2897)
		(width 0.1143)
		(layer "In4.Cu")
		(net "P3E_CPU0_PE3_OCP_TXP<2>")
	)
	(segment
		(start 456.317604 -53.906674)
		(end 456.577954 -53.906674)
		(width 0.1143)
		(layer "In4.Cu")
		(net "P3E_CPU0_PE3_OCP_TXP<2>")
	)
	(segment
		(start 435.607968 -58.136028)
		(end 435.365398 -57.893458)
		(width 0.1143)
		(layer "In4.Cu")
		(net "P3E_CPU0_PE3_OCP_TXP<2>")
	)
	(segment
		(start 426.281342 -57.842658)
		(end 425.295568 -58.828432)
		(width 0.1143)
		(layer "In4.Cu")
		(net "P3E_CPU0_PE3_OCP_TXP<2>")
	)
	(segment
		(start 456.577954 -53.906674)
		(end 456.751182 -54.079902)
		(width 0.1143)
		(layer "In4.Cu")
		(net "P3E_CPU0_PE3_OCP_TXP<2>")
	)
	(segment
		(start 349.900494 -65.300352)
		(end 348.633034 -65.003934)
		(width 0.1143)
		(layer "In4.Cu")
		(net "P3E_CPU0_PE3_OCP_TXP<2>")
	)
	(segment
		(start 331.245972 -70.568058)
		(end 327.468738 -76.05903)
		(width 0.1143)
		(layer "In4.Cu")
		(net "P3E_CPU0_PE3_OCP_TXP<2>")
	)
	(segment
		(start 298.922948 -101.719888)
		(end 298.94403 -101.641148)
		(width 0.0889)
		(layer "In4.Cu")
		(net "P3E_CPU0_PE3_OCP_TXP<2>")
	)
	(arc
		(start 299.22216 -101.872034)
		(mid 299.055866 -101.8288)
		(end 298.922948 -101.719888)
		(width 0.0889)
		(layer "In4.Cu")
		(net "P3E_CPU0_PE3_OCP_TXP<2>")
	)
	(segment
		(start 296.948606 -102.462584)
		(end 297.520106 -102.462584)
		(width 0.1143)
		(layer "F.Cu")
		(net "P3E_CPU0_PE3_OCP_TXP<1>")
	)
	(via
		(at 297.520106 -102.462584)
		(size 0.508)
		(drill 0.254)
		(layers "F.Cu" "B.Cu")
		(net "P3E_CPU0_PE3_OCP_TXP<1>")
	)
	(via
		(at 459.51775 -53.906674)
		(size 0.508)
		(drill 0.254)
		(layers "F.Cu" "B.Cu")
		(net "P3E_CPU0_PE3_OCP_TXP<1>")
	)
	(segment
		(start 459.900782 -52.977034)
		(end 460.015082 -53.091334)
		(width 0.1143)
		(layer "B.Cu")
		(net "P3E_CPU0_PE3_OCP_TXP<1>")
	)
	(segment
		(start 460.015082 -53.091334)
		(end 460.015082 -53.496718)
		(width 0.1143)
		(layer "B.Cu")
		(net "P3E_CPU0_PE3_OCP_TXP<1>")
	)
	(segment
		(start 459.6384 -52.457858)
		(end 459.6384 -52.862734)
		(width 0.1143)
		(layer "B.Cu")
		(net "P3E_CPU0_PE3_OCP_TXP<1>")
	)
	(segment
		(start 459.6384 -52.862734)
		(end 459.7527 -52.977034)
		(width 0.1143)
		(layer "B.Cu")
		(net "P3E_CPU0_PE3_OCP_TXP<1>")
	)
	(segment
		(start 459.605126 -53.906674)
		(end 459.51775 -53.906674)
		(width 0.1143)
		(layer "B.Cu")
		(net "P3E_CPU0_PE3_OCP_TXP<1>")
	)
	(segment
		(start 460.015082 -53.496718)
		(end 459.605126 -53.906674)
		(width 0.1143)
		(layer "B.Cu")
		(net "P3E_CPU0_PE3_OCP_TXP<1>")
	)
	(segment
		(start 459.7527 -52.977034)
		(end 459.900782 -52.977034)
		(width 0.1143)
		(layer "B.Cu")
		(net "P3E_CPU0_PE3_OCP_TXP<1>")
	)
	(segment
		(start 405.410162 -59.744102)
		(end 405.154892 -59.488832)
		(width 0.1143)
		(layer "In4.Cu")
		(net "P3E_CPU0_PE3_OCP_TXP<1>")
	)
	(segment
		(start 421.380666 -59.463432)
		(end 421.203628 -59.64047)
		(width 0.1143)
		(layer "In4.Cu")
		(net "P3E_CPU0_PE3_OCP_TXP<1>")
	)
	(segment
		(start 418.829236 -60.9854)
		(end 416.113214 -60.9854)
		(width 0.1143)
		(layer "In4.Cu")
		(net "P3E_CPU0_PE3_OCP_TXP<1>")
	)
	(segment
		(start 304.4444 -104.14)
		(end 303.787556 -104.14)
		(width 0.0889)
		(layer "In4.Cu")
		(net "P3E_CPU0_PE3_OCP_TXP<1>")
	)
	(segment
		(start 459.105 -55.753)
		(end 458.3176 -55.753)
		(width 0.1143)
		(layer "In4.Cu")
		(net "P3E_CPU0_PE3_OCP_TXP<1>")
	)
	(segment
		(start 432.589178 -62.73165)
		(end 430.767998 -62.73165)
		(width 0.1143)
		(layer "In4.Cu")
		(net "P3E_CPU0_PE3_OCP_TXP<1>")
	)
	(segment
		(start 429.477424 -61.441076)
		(end 429.477424 -59.0296)
		(width 0.1143)
		(layer "In4.Cu")
		(net "P3E_CPU0_PE3_OCP_TXP<1>")
	)
	(segment
		(start 382.050036 -57.63895)
		(end 380.57328 -57.63895)
		(width 0.1143)
		(layer "In4.Cu")
		(net "P3E_CPU0_PE3_OCP_TXP<1>")
	)
	(segment
		(start 390.66089 -58.106564)
		(end 382.51765 -58.106564)
		(width 0.1143)
		(layer "In4.Cu")
		(net "P3E_CPU0_PE3_OCP_TXP<1>")
	)
	(segment
		(start 299.726096 -103.356664)
		(end 299.237146 -102.867714)
		(width 0.0889)
		(layer "In4.Cu")
		(net "P3E_CPU0_PE3_OCP_TXP<1>")
	)
	(segment
		(start 345.867736 -65.663572)
		(end 344.11285 -66.004948)
		(width 0.1143)
		(layer "In4.Cu")
		(net "P3E_CPU0_PE3_OCP_TXP<1>")
	)
	(segment
		(start 455.335894 -60.944506)
		(end 454.497694 -60.944506)
		(width 0.1143)
		(layer "In4.Cu")
		(net "P3E_CPU0_PE3_OCP_TXP<1>")
	)
	(segment
		(start 408.681936 -60.33135)
		(end 406.785318 -60.33135)
		(width 0.1143)
		(layer "In4.Cu")
		(net "P3E_CPU0_PE3_OCP_TXP<1>")
	)
	(segment
		(start 399.485104 -57.9247)
		(end 390.842754 -57.9247)
		(width 0.1143)
		(layer "In4.Cu")
		(net "P3E_CPU0_PE3_OCP_TXP<1>")
	)
	(segment
		(start 307.041042 -103.506016)
		(end 306.825142 -103.416608)
		(width 0.1143)
		(layer "In4.Cu")
		(net "P3E_CPU0_PE3_OCP_TXP<1>")
	)
	(segment
		(start 355.47173 -66.71945)
		(end 350.774254 -65.779904)
		(width 0.1143)
		(layer "In4.Cu")
		(net "P3E_CPU0_PE3_OCP_TXP<1>")
	)
	(segment
		(start 456.3618 -57.7088)
		(end 456.3618 -59.9186)
		(width 0.1143)
		(layer "In4.Cu")
		(net "P3E_CPU0_PE3_OCP_TXP<1>")
	)
	(segment
		(start 428.948088 -58.500264)
		(end 426.522134 -58.500264)
		(width 0.1143)
		(layer "In4.Cu")
		(net "P3E_CPU0_PE3_OCP_TXP<1>")
	)
	(segment
		(start 343.175336 -65.786)
		(end 338.208874 -66.753232)
		(width 0.1143)
		(layer "In4.Cu")
		(net "P3E_CPU0_PE3_OCP_TXP<1>")
	)
	(segment
		(start 375.517918 -57.4294)
		(end 370.198396 -57.4294)
		(width 0.1143)
		(layer "In4.Cu")
		(net "P3E_CPU0_PE3_OCP_TXP<1>")
	)
	(segment
		(start 306.825142 -103.416608)
		(end 306.508404 -103.547672)
		(width 0.1143)
		(layer "In4.Cu")
		(net "P3E_CPU0_PE3_OCP_TXP<1>")
	)
	(segment
		(start 425.558966 -59.463432)
		(end 421.380666 -59.463432)
		(width 0.1143)
		(layer "In4.Cu")
		(net "P3E_CPU0_PE3_OCP_TXP<1>")
	)
	(segment
		(start 406.19807 -59.744102)
		(end 405.410162 -59.744102)
		(width 0.1143)
		(layer "In4.Cu")
		(net "P3E_CPU0_PE3_OCP_TXP<1>")
	)
	(segment
		(start 452.770494 -60.944506)
		(end 434.376322 -60.944506)
		(width 0.1143)
		(layer "In4.Cu")
		(net "P3E_CPU0_PE3_OCP_TXP<1>")
	)
	(segment
		(start 459.8924 -53.906674)
		(end 460.0067 -54.020974)
		(width 0.1143)
		(layer "In4.Cu")
		(net "P3E_CPU0_PE3_OCP_TXP<1>")
	)
	(segment
		(start 460.0067 -54.8513)
		(end 459.105 -55.753)
		(width 0.1143)
		(layer "In4.Cu")
		(net "P3E_CPU0_PE3_OCP_TXP<1>")
	)
	(segment
		(start 401.049236 -59.488832)
		(end 399.485104 -57.9247)
		(width 0.1143)
		(layer "In4.Cu")
		(net "P3E_CPU0_PE3_OCP_TXP<1>")
	)
	(segment
		(start 299.237146 -102.867714)
		(end 299.175678 -102.858062)
		(width 0.0889)
		(layer "In4.Cu")
		(net "P3E_CPU0_PE3_OCP_TXP<1>")
	)
	(segment
		(start 297.771312 -102.607618)
		(end 297.520106 -102.462584)
		(width 0.0889)
		(layer "In4.Cu")
		(net "P3E_CPU0_PE3_OCP_TXP<1>")
	)
	(segment
		(start 460.0067 -54.020974)
		(end 460.0067 -54.8513)
		(width 0.1143)
		(layer "In4.Cu")
		(net "P3E_CPU0_PE3_OCP_TXP<1>")
	)
	(segment
		(start 380.57328 -57.63895)
		(end 379.680978 -56.746648)
		(width 0.1143)
		(layer "In4.Cu")
		(net "P3E_CPU0_PE3_OCP_TXP<1>")
	)
	(segment
		(start 366.046004 -58.330338)
		(end 358.598216 -65.778126)
		(width 0.1143)
		(layer "In4.Cu")
		(net "P3E_CPU0_PE3_OCP_TXP<1>")
	)
	(segment
		(start 426.522134 -58.500264)
		(end 425.558966 -59.463432)
		(width 0.1143)
		(layer "In4.Cu")
		(net "P3E_CPU0_PE3_OCP_TXP<1>")
	)
	(segment
		(start 414.129474 -62.96914)
		(end 412.646114 -62.96914)
		(width 0.1143)
		(layer "In4.Cu")
		(net "P3E_CPU0_PE3_OCP_TXP<1>")
	)
	(segment
		(start 375.651522 -57.563004)
		(end 375.517918 -57.4294)
		(width 0.1143)
		(layer "In4.Cu")
		(net "P3E_CPU0_PE3_OCP_TXP<1>")
	)
	(segment
		(start 416.113214 -60.9854)
		(end 414.129474 -62.96914)
		(width 0.1143)
		(layer "In4.Cu")
		(net "P3E_CPU0_PE3_OCP_TXP<1>")
	)
	(segment
		(start 454.332594 -60.779406)
		(end 453.976994 -60.779406)
		(width 0.1143)
		(layer "In4.Cu")
		(net "P3E_CPU0_PE3_OCP_TXP<1>")
	)
	(segment
		(start 459.51775 -53.906674)
		(end 459.8924 -53.906674)
		(width 0.1143)
		(layer "In4.Cu")
		(net "P3E_CPU0_PE3_OCP_TXP<1>")
	)
	(segment
		(start 297.90263 -102.607618)
		(end 297.771312 -102.607618)
		(width 0.0889)
		(layer "In4.Cu")
		(net "P3E_CPU0_PE3_OCP_TXP<1>")
	)
	(segment
		(start 421.203628 -59.64047)
		(end 420.174166 -59.64047)
		(width 0.1143)
		(layer "In4.Cu")
		(net "P3E_CPU0_PE3_OCP_TXP<1>")
	)
	(segment
		(start 412.646114 -62.96914)
		(end 411.3022 -61.625226)
		(width 0.1143)
		(layer "In4.Cu")
		(net "P3E_CPU0_PE3_OCP_TXP<1>")
	)
	(segment
		(start 420.174166 -59.64047)
		(end 418.829236 -60.9854)
		(width 0.1143)
		(layer "In4.Cu")
		(net "P3E_CPU0_PE3_OCP_TXP<1>")
	)
	(segment
		(start 300.734476 -102.888288)
		(end 300.2661 -103.356664)
		(width 0.0889)
		(layer "In4.Cu")
		(net "P3E_CPU0_PE3_OCP_TXP<1>")
	)
	(segment
		(start 300.2661 -103.356664)
		(end 299.726096 -103.356664)
		(width 0.0889)
		(layer "In4.Cu")
		(net "P3E_CPU0_PE3_OCP_TXP<1>")
	)
	(segment
		(start 429.477424 -59.0296)
		(end 428.948088 -58.500264)
		(width 0.1143)
		(layer "In4.Cu")
		(net "P3E_CPU0_PE3_OCP_TXP<1>")
	)
	(segment
		(start 356.924356 -66.429128)
		(end 355.47173 -66.71945)
		(width 0.1143)
		(layer "In4.Cu")
		(net "P3E_CPU0_PE3_OCP_TXP<1>")
	)
	(segment
		(start 378.441458 -56.746648)
		(end 377.625102 -57.563004)
		(width 0.1143)
		(layer "In4.Cu")
		(net "P3E_CPU0_PE3_OCP_TXP<1>")
	)
	(segment
		(start 304.517298 -104.0892)
		(end 304.4952 -104.0892)
		(width 0.0889)
		(layer "In4.Cu")
		(net "P3E_CPU0_PE3_OCP_TXP<1>")
	)
	(segment
		(start 370.198396 -57.4294)
		(end 369.297458 -58.330338)
		(width 0.1143)
		(layer "In4.Cu")
		(net "P3E_CPU0_PE3_OCP_TXP<1>")
	)
	(segment
		(start 390.842754 -57.9247)
		(end 390.66089 -58.106564)
		(width 0.1143)
		(layer "In4.Cu")
		(net "P3E_CPU0_PE3_OCP_TXP<1>")
	)
	(segment
		(start 358.598216 -65.778126)
		(end 357.57739 -65.778126)
		(width 0.1143)
		(layer "In4.Cu")
		(net "P3E_CPU0_PE3_OCP_TXP<1>")
	)
	(segment
		(start 453.976994 -60.779406)
		(end 453.811894 -60.944506)
		(width 0.1143)
		(layer "In4.Cu")
		(net "P3E_CPU0_PE3_OCP_TXP<1>")
	)
	(segment
		(start 338.208874 -66.753232)
		(end 331.689202 -71.045324)
		(width 0.1143)
		(layer "In4.Cu")
		(net "P3E_CPU0_PE3_OCP_TXP<1>")
	)
	(segment
		(start 430.767998 -62.73165)
		(end 429.477424 -61.441076)
		(width 0.1143)
		(layer "In4.Cu")
		(net "P3E_CPU0_PE3_OCP_TXP<1>")
	)
	(segment
		(start 434.376322 -60.944506)
		(end 432.589178 -62.73165)
		(width 0.1143)
		(layer "In4.Cu")
		(net "P3E_CPU0_PE3_OCP_TXP<1>")
	)
	(segment
		(start 307.35778 -103.374698)
		(end 307.041042 -103.506016)
		(width 0.1143)
		(layer "In4.Cu")
		(net "P3E_CPU0_PE3_OCP_TXP<1>")
	)
	(segment
		(start 382.51765 -58.106564)
		(end 382.050036 -57.63895)
		(width 0.1143)
		(layer "In4.Cu")
		(net "P3E_CPU0_PE3_OCP_TXP<1>")
	)
	(segment
		(start 453.291194 -60.779406)
		(end 452.935594 -60.779406)
		(width 0.1143)
		(layer "In4.Cu")
		(net "P3E_CPU0_PE3_OCP_TXP<1>")
	)
	(segment
		(start 458.3176 -55.753)
		(end 456.3618 -57.7088)
		(width 0.1143)
		(layer "In4.Cu")
		(net "P3E_CPU0_PE3_OCP_TXP<1>")
	)
	(segment
		(start 456.3618 -59.9186)
		(end 455.335894 -60.944506)
		(width 0.1143)
		(layer "In4.Cu")
		(net "P3E_CPU0_PE3_OCP_TXP<1>")
	)
	(segment
		(start 405.154892 -59.488832)
		(end 401.049236 -59.488832)
		(width 0.1143)
		(layer "In4.Cu")
		(net "P3E_CPU0_PE3_OCP_TXP<1>")
	)
	(segment
		(start 323.559932 -87.179658)
		(end 307.35778 -103.374698)
		(width 0.1143)
		(layer "In4.Cu")
		(net "P3E_CPU0_PE3_OCP_TXP<1>")
	)
	(segment
		(start 348.62516 -65.655444)
		(end 347.1037 -65.9511)
		(width 0.1143)
		(layer "In4.Cu")
		(net "P3E_CPU0_PE3_OCP_TXP<1>")
	)
	(segment
		(start 331.689202 -71.045324)
		(end 328.05624 -76.326238)
		(width 0.1143)
		(layer "In4.Cu")
		(net "P3E_CPU0_PE3_OCP_TXP<1>")
	)
	(segment
		(start 350.774254 -65.779904)
		(end 349.894144 -65.951608)
		(width 0.1143)
		(layer "In4.Cu")
		(net "P3E_CPU0_PE3_OCP_TXP<1>")
	)
	(segment
		(start 304.4952 -104.0892)
		(end 304.4444 -104.14)
		(width 0.0889)
		(layer "In4.Cu")
		(net "P3E_CPU0_PE3_OCP_TXP<1>")
	)
	(segment
		(start 369.297458 -58.330338)
		(end 366.046004 -58.330338)
		(width 0.1143)
		(layer "In4.Cu")
		(net "P3E_CPU0_PE3_OCP_TXP<1>")
	)
	(segment
		(start 306.508404 -103.547672)
		(end 306.418996 -103.763572)
		(width 0.1143)
		(layer "In4.Cu")
		(net "P3E_CPU0_PE3_OCP_TXP<1>")
	)
	(segment
		(start 411.3022 -61.625226)
		(end 409.975812 -61.625226)
		(width 0.1143)
		(layer "In4.Cu")
		(net "P3E_CPU0_PE3_OCP_TXP<1>")
	)
	(segment
		(start 298.400216 -102.367588)
		(end 298.357036 -102.367588)
		(width 0.0889)
		(layer "In4.Cu")
		(net "P3E_CPU0_PE3_OCP_TXP<1>")
	)
	(segment
		(start 377.625102 -57.563004)
		(end 375.651522 -57.563004)
		(width 0.1143)
		(layer "In4.Cu")
		(net "P3E_CPU0_PE3_OCP_TXP<1>")
	)
	(segment
		(start 306.418996 -103.763572)
		(end 305.632612 -104.0892)
		(width 0.1143)
		(layer "In4.Cu")
		(net "P3E_CPU0_PE3_OCP_TXP<1>")
	)
	(segment
		(start 347.1037 -65.9511)
		(end 345.867736 -65.663572)
		(width 0.1143)
		(layer "In4.Cu")
		(net "P3E_CPU0_PE3_OCP_TXP<1>")
	)
	(segment
		(start 452.935594 -60.779406)
		(end 452.770494 -60.944506)
		(width 0.1143)
		(layer "In4.Cu")
		(net "P3E_CPU0_PE3_OCP_TXP<1>")
	)
	(segment
		(start 302.535844 -102.888288)
		(end 300.734476 -102.888288)
		(width 0.0889)
		(layer "In4.Cu")
		(net "P3E_CPU0_PE3_OCP_TXP<1>")
	)
	(segment
		(start 406.785318 -60.33135)
		(end 406.19807 -59.744102)
		(width 0.1143)
		(layer "In4.Cu")
		(net "P3E_CPU0_PE3_OCP_TXP<1>")
	)
	(segment
		(start 454.497694 -60.944506)
		(end 454.332594 -60.779406)
		(width 0.1143)
		(layer "In4.Cu")
		(net "P3E_CPU0_PE3_OCP_TXP<1>")
	)
	(segment
		(start 379.680978 -56.746648)
		(end 378.441458 -56.746648)
		(width 0.1143)
		(layer "In4.Cu")
		(net "P3E_CPU0_PE3_OCP_TXP<1>")
	)
	(segment
		(start 328.05624 -76.326238)
		(end 323.559932 -87.179658)
		(width 0.1143)
		(layer "In4.Cu")
		(net "P3E_CPU0_PE3_OCP_TXP<1>")
	)
	(segment
		(start 409.975812 -61.625226)
		(end 408.681936 -60.33135)
		(width 0.1143)
		(layer "In4.Cu")
		(net "P3E_CPU0_PE3_OCP_TXP<1>")
	)
	(segment
		(start 344.11285 -66.004948)
		(end 343.175336 -65.786)
		(width 0.1143)
		(layer "In4.Cu")
		(net "P3E_CPU0_PE3_OCP_TXP<1>")
	)
	(segment
		(start 357.57739 -65.778126)
		(end 356.924356 -66.429128)
		(width 0.1143)
		(layer "In4.Cu")
		(net "P3E_CPU0_PE3_OCP_TXP<1>")
	)
	(segment
		(start 349.894144 -65.951608)
		(end 348.62516 -65.655444)
		(width 0.1143)
		(layer "In4.Cu")
		(net "P3E_CPU0_PE3_OCP_TXP<1>")
	)
	(segment
		(start 305.632612 -104.0892)
		(end 304.517298 -104.0892)
		(width 0.1143)
		(layer "In4.Cu")
		(net "P3E_CPU0_PE3_OCP_TXP<1>")
	)
	(segment
		(start 453.811894 -60.944506)
		(end 453.456294 -60.944506)
		(width 0.1143)
		(layer "In4.Cu")
		(net "P3E_CPU0_PE3_OCP_TXP<1>")
	)
	(segment
		(start 303.787556 -104.14)
		(end 302.535844 -102.888288)
		(width 0.0889)
		(layer "In4.Cu")
		(net "P3E_CPU0_PE3_OCP_TXP<1>")
	)
	(segment
		(start 453.456294 -60.944506)
		(end 453.291194 -60.779406)
		(width 0.1143)
		(layer "In4.Cu")
		(net "P3E_CPU0_PE3_OCP_TXP<1>")
	)
	(arc
		(start 298.890436 -102.662736)
		(mid 298.683432 -102.451872)
		(end 298.400216 -102.367588)
		(width 0.0889)
		(layer "In4.Cu")
		(net "P3E_CPU0_PE3_OCP_TXP<1>")
	)
	(arc
		(start 299.175678 -102.858062)
		(mid 299.010924 -102.792743)
		(end 298.890436 -102.662736)
		(width 0.0889)
		(layer "In4.Cu")
		(net "P3E_CPU0_PE3_OCP_TXP<1>")
	)
	(arc
		(start 298.357036 -102.367588)
		(mid 298.102371 -102.435617)
		(end 297.90263 -102.607618)
		(width 0.0889)
		(layer "In4.Cu")
		(net "P3E_CPU0_PE3_OCP_TXP<1>")
	)
	(segment
		(start 303.816766 -89.584784)
		(end 304.388266 -89.584784)
		(width 0.1143)
		(layer "F.Cu")
		(net "P3E_CPU0_PE3_OCP_TXP<15>")
	)
	(via
		(at 304.388266 -89.584784)
		(size 0.508)
		(drill 0.254)
		(layers "F.Cu" "B.Cu")
		(net "P3E_CPU0_PE3_OCP_TXP<15>")
	)
	(via
		(at 356.977442 -103.703374)
		(size 0.508)
		(drill 0.254)
		(layers "F.Cu" "B.Cu")
		(net "P3E_CPU0_PE3_OCP_TXP<15>")
	)
	(via
		(at 463.32775 -124.18822)
		(size 0.508)
		(drill 0.254)
		(layers "F.Cu" "B.Cu")
		(net "P3E_CPU0_PE3_OCP_TXP<15>")
	)
	(segment
		(start 465.95665 -116.87937)
		(end 465.95665 -117.317012)
		(width 0.1143)
		(layer "B.Cu")
		(net "P3E_CPU0_PE3_OCP_TXP<15>")
	)
	(segment
		(start 462.8134 -123.52909)
		(end 462.8134 -124.07392)
		(width 0.1143)
		(layer "B.Cu")
		(net "P3E_CPU0_PE3_OCP_TXP<15>")
	)
	(segment
		(start 462.9277 -124.18822)
		(end 463.32775 -124.18822)
		(width 0.1143)
		(layer "B.Cu")
		(net "P3E_CPU0_PE3_OCP_TXP<15>")
	)
	(segment
		(start 464.50123 -118.438422)
		(end 464.219036 -118.986808)
		(width 0.1143)
		(layer "B.Cu")
		(net "P3E_CPU0_PE3_OCP_TXP<15>")
	)
	(segment
		(start 464.219036 -118.986808)
		(end 463.19567 -119.766588)
		(width 0.1143)
		(layer "B.Cu")
		(net "P3E_CPU0_PE3_OCP_TXP<15>")
	)
	(segment
		(start 462.8134 -124.07392)
		(end 462.9277 -124.18822)
		(width 0.1143)
		(layer "B.Cu")
		(net "P3E_CPU0_PE3_OCP_TXP<15>")
	)
	(segment
		(start 465.95665 -117.317012)
		(end 465.589874 -117.832632)
		(width 0.1143)
		(layer "B.Cu")
		(net "P3E_CPU0_PE3_OCP_TXP<15>")
	)
	(segment
		(start 462.508092 -122.43816)
		(end 462.8134 -123.52909)
		(width 0.1143)
		(layer "B.Cu")
		(net "P3E_CPU0_PE3_OCP_TXP<15>")
	)
	(segment
		(start 465.589874 -117.832632)
		(end 464.50123 -118.438422)
		(width 0.1143)
		(layer "B.Cu")
		(net "P3E_CPU0_PE3_OCP_TXP<15>")
	)
	(segment
		(start 466.344 -116.49202)
		(end 465.95665 -116.87937)
		(width 0.1143)
		(layer "B.Cu")
		(net "P3E_CPU0_PE3_OCP_TXP<15>")
	)
	(segment
		(start 463.19567 -119.766588)
		(end 462.508092 -122.43816)
		(width 0.1143)
		(layer "B.Cu")
		(net "P3E_CPU0_PE3_OCP_TXP<15>")
	)
	(segment
		(start 356.977442 -103.703374)
		(end 357.299768 -104.0257)
		(width 0.1143)
		(layer "In4.Cu")
		(net "P3E_CPU0_PE3_OCP_TXP<15>")
	)
	(segment
		(start 430.286668 -122.129804)
		(end 432.089052 -121.576592)
		(width 0.1143)
		(layer "In4.Cu")
		(net "P3E_CPU0_PE3_OCP_TXP<15>")
	)
	(segment
		(start 433.492148 -121.54027)
		(end 434.361844 -121.733818)
		(width 0.1143)
		(layer "In4.Cu")
		(net "P3E_CPU0_PE3_OCP_TXP<15>")
	)
	(segment
		(start 376.137932 -127.250444)
		(end 377.151138 -127.466598)
		(width 0.1143)
		(layer "In4.Cu")
		(net "P3E_CPU0_PE3_OCP_TXP<15>")
	)
	(segment
		(start 462.8388 -123.614942)
		(end 462.8388 -124.0282)
		(width 0.1143)
		(layer "In4.Cu")
		(net "P3E_CPU0_PE3_OCP_TXP<15>")
	)
	(segment
		(start 457.997814 -121.799096)
		(end 460.40421 -122.7963)
		(width 0.1143)
		(layer "In4.Cu")
		(net "P3E_CPU0_PE3_OCP_TXP<15>")
	)
	(segment
		(start 385.827524 -126.503176)
		(end 386.883656 -128.09855)
		(width 0.1143)
		(layer "In4.Cu")
		(net "P3E_CPU0_PE3_OCP_TXP<15>")
	)
	(segment
		(start 362.594144 -125.432566)
		(end 362.649516 -125.712474)
		(width 0.1143)
		(layer "In4.Cu")
		(net "P3E_CPU0_PE3_OCP_TXP<15>")
	)
	(segment
		(start 434.361844 -121.733818)
		(end 435.24805 -121.482104)
		(width 0.1143)
		(layer "In4.Cu")
		(net "P3E_CPU0_PE3_OCP_TXP<15>")
	)
	(segment
		(start 408.44216 -127.43307)
		(end 409.447492 -127.234188)
		(width 0.1143)
		(layer "In4.Cu")
		(net "P3E_CPU0_PE3_OCP_TXP<15>")
	)
	(segment
		(start 362.690156 -120.959372)
		(end 362.600748 -121.412)
		(width 0.1143)
		(layer "In4.Cu")
		(net "P3E_CPU0_PE3_OCP_TXP<15>")
	)
	(segment
		(start 432.606196 -121.703846)
		(end 433.492148 -121.54027)
		(width 0.1143)
		(layer "In4.Cu")
		(net "P3E_CPU0_PE3_OCP_TXP<15>")
	)
	(segment
		(start 361.510072 -105.420414)
		(end 361.510072 -109.90707)
		(width 0.1143)
		(layer "In4.Cu")
		(net "P3E_CPU0_PE3_OCP_TXP<15>")
	)
	(segment
		(start 362.69041 -124.946156)
		(end 362.594144 -125.432566)
		(width 0.1143)
		(layer "In4.Cu")
		(net "P3E_CPU0_PE3_OCP_TXP<15>")
	)
	(segment
		(start 409.447492 -127.234188)
		(end 410.044138 -127.352298)
		(width 0.1143)
		(layer "In4.Cu")
		(net "P3E_CPU0_PE3_OCP_TXP<15>")
	)
	(segment
		(start 397.60271 -131.922266)
		(end 408.44216 -127.43307)
		(width 0.1143)
		(layer "In4.Cu")
		(net "P3E_CPU0_PE3_OCP_TXP<15>")
	)
	(segment
		(start 461.341724 -122.7963)
		(end 462.499456 -123.275852)
		(width 0.1143)
		(layer "In4.Cu")
		(net "P3E_CPU0_PE3_OCP_TXP<15>")
	)
	(segment
		(start 454.491344 -118.292626)
		(end 457.997814 -121.799096)
		(width 0.1143)
		(layer "In4.Cu")
		(net "P3E_CPU0_PE3_OCP_TXP<15>")
	)
	(segment
		(start 420.809166 -126.410212)
		(end 424.580304 -127.536702)
		(width 0.1143)
		(layer "In4.Cu")
		(net "P3E_CPU0_PE3_OCP_TXP<15>")
	)
	(segment
		(start 394.373354 -131.87934)
		(end 396.041626 -131.527296)
		(width 0.1143)
		(layer "In4.Cu")
		(net "P3E_CPU0_PE3_OCP_TXP<15>")
	)
	(segment
		(start 384.976624 -125.940058)
		(end 385.827524 -126.503176)
		(width 0.1143)
		(layer "In4.Cu")
		(net "P3E_CPU0_PE3_OCP_TXP<15>")
	)
	(segment
		(start 362.591858 -123.449842)
		(end 362.69041 -123.94819)
		(width 0.1143)
		(layer "In4.Cu")
		(net "P3E_CPU0_PE3_OCP_TXP<15>")
	)
	(segment
		(start 362.591604 -124.447808)
		(end 362.69041 -124.946156)
		(width 0.1143)
		(layer "In4.Cu")
		(net "P3E_CPU0_PE3_OCP_TXP<15>")
	)
	(segment
		(start 362.69041 -123.94819)
		(end 362.591604 -124.447808)
		(width 0.1143)
		(layer "In4.Cu")
		(net "P3E_CPU0_PE3_OCP_TXP<15>")
	)
	(segment
		(start 427.598586 -122.525536)
		(end 428.813976 -121.835926)
		(width 0.1143)
		(layer "In4.Cu")
		(net "P3E_CPU0_PE3_OCP_TXP<15>")
	)
	(segment
		(start 445.623188 -117.8687)
		(end 453.467724 -117.8687)
		(width 0.1143)
		(layer "In4.Cu")
		(net "P3E_CPU0_PE3_OCP_TXP<15>")
	)
	(segment
		(start 412.380684 -127.097028)
		(end 413.875474 -126.490984)
		(width 0.1143)
		(layer "In4.Cu")
		(net "P3E_CPU0_PE3_OCP_TXP<15>")
	)
	(segment
		(start 418.749734 -125.998732)
		(end 420.809166 -126.410212)
		(width 0.1143)
		(layer "In4.Cu")
		(net "P3E_CPU0_PE3_OCP_TXP<15>")
	)
	(segment
		(start 362.70057 -119.910606)
		(end 362.591604 -120.461024)
		(width 0.1143)
		(layer "In4.Cu")
		(net "P3E_CPU0_PE3_OCP_TXP<15>")
	)
	(segment
		(start 377.151138 -127.466598)
		(end 384.000502 -125.74143)
		(width 0.1143)
		(layer "In4.Cu")
		(net "P3E_CPU0_PE3_OCP_TXP<15>")
	)
	(segment
		(start 372.279164 -126.834138)
		(end 375.382536 -127.418084)
		(width 0.1143)
		(layer "In4.Cu")
		(net "P3E_CPU0_PE3_OCP_TXP<15>")
	)
	(segment
		(start 411.06471 -127.357378)
		(end 412.380684 -127.097028)
		(width 0.1143)
		(layer "In4.Cu")
		(net "P3E_CPU0_PE3_OCP_TXP<15>")
	)
	(segment
		(start 360.115358 -104.0257)
		(end 361.510072 -105.420414)
		(width 0.1143)
		(layer "In4.Cu")
		(net "P3E_CPU0_PE3_OCP_TXP<15>")
	)
	(segment
		(start 435.24805 -121.482104)
		(end 436.631588 -120.662192)
		(width 0.1143)
		(layer "In4.Cu")
		(net "P3E_CPU0_PE3_OCP_TXP<15>")
	)
	(segment
		(start 362.516674 -113.340388)
		(end 362.516674 -118.980204)
		(width 0.1143)
		(layer "In4.Cu")
		(net "P3E_CPU0_PE3_OCP_TXP<15>")
	)
	(segment
		(start 362.516674 -118.980204)
		(end 362.70057 -119.910606)
		(width 0.1143)
		(layer "In4.Cu")
		(net "P3E_CPU0_PE3_OCP_TXP<15>")
	)
	(segment
		(start 369.352322 -127.930148)
		(end 372.279164 -126.834138)
		(width 0.1143)
		(layer "In4.Cu")
		(net "P3E_CPU0_PE3_OCP_TXP<15>")
	)
	(segment
		(start 390.574784 -131.960366)
		(end 392.77671 -131.51612)
		(width 0.1143)
		(layer "In4.Cu")
		(net "P3E_CPU0_PE3_OCP_TXP<15>")
	)
	(segment
		(start 460.40421 -122.7963)
		(end 461.341724 -122.7963)
		(width 0.1143)
		(layer "In4.Cu")
		(net "P3E_CPU0_PE3_OCP_TXP<15>")
	)
	(segment
		(start 386.883656 -128.09855)
		(end 387.24459 -129.873248)
		(width 0.1143)
		(layer "In4.Cu")
		(net "P3E_CPU0_PE3_OCP_TXP<15>")
	)
	(segment
		(start 362.6993 -121.910856)
		(end 362.591604 -122.454416)
		(width 0.1143)
		(layer "In4.Cu")
		(net "P3E_CPU0_PE3_OCP_TXP<15>")
	)
	(segment
		(start 436.631588 -120.662192)
		(end 444.368682 -119.123206)
		(width 0.1143)
		(layer "In4.Cu")
		(net "P3E_CPU0_PE3_OCP_TXP<15>")
	)
	(segment
		(start 384.000502 -125.74143)
		(end 384.000502 -125.741684)
		(width 0.1143)
		(layer "In4.Cu")
		(net "P3E_CPU0_PE3_OCP_TXP<15>")
	)
	(segment
		(start 396.041626 -131.527296)
		(end 397.60271 -131.922266)
		(width 0.1143)
		(layer "In4.Cu")
		(net "P3E_CPU0_PE3_OCP_TXP<15>")
	)
	(segment
		(start 425.107608 -127.410464)
		(end 426.736002 -124.732796)
		(width 0.1143)
		(layer "In4.Cu")
		(net "P3E_CPU0_PE3_OCP_TXP<15>")
	)
	(segment
		(start 362.649516 -125.712474)
		(end 363.209332 -126.5428)
		(width 0.1143)
		(layer "In4.Cu")
		(net "P3E_CPU0_PE3_OCP_TXP<15>")
	)
	(segment
		(start 363.920024 -126.824232)
		(end 369.352322 -127.930148)
		(width 0.1143)
		(layer "In4.Cu")
		(net "P3E_CPU0_PE3_OCP_TXP<15>")
	)
	(segment
		(start 361.93095 -110.327948)
		(end 361.93095 -112.754664)
		(width 0.1143)
		(layer "In4.Cu")
		(net "P3E_CPU0_PE3_OCP_TXP<15>")
	)
	(segment
		(start 444.368682 -119.123206)
		(end 445.623188 -117.8687)
		(width 0.1143)
		(layer "In4.Cu")
		(net "P3E_CPU0_PE3_OCP_TXP<15>")
	)
	(segment
		(start 362.600748 -121.412)
		(end 362.6993 -121.910856)
		(width 0.1143)
		(layer "In4.Cu")
		(net "P3E_CPU0_PE3_OCP_TXP<15>")
	)
	(segment
		(start 416.042856 -126.72949)
		(end 418.749734 -125.998732)
		(width 0.1143)
		(layer "In4.Cu")
		(net "P3E_CPU0_PE3_OCP_TXP<15>")
	)
	(segment
		(start 362.591604 -120.461024)
		(end 362.690156 -120.959372)
		(width 0.1143)
		(layer "In4.Cu")
		(net "P3E_CPU0_PE3_OCP_TXP<15>")
	)
	(segment
		(start 462.8388 -124.0282)
		(end 462.99882 -124.18822)
		(width 0.1143)
		(layer "In4.Cu")
		(net "P3E_CPU0_PE3_OCP_TXP<15>")
	)
	(segment
		(start 415.096198 -126.531624)
		(end 416.042856 -126.72949)
		(width 0.1143)
		(layer "In4.Cu")
		(net "P3E_CPU0_PE3_OCP_TXP<15>")
	)
	(segment
		(start 413.875474 -126.490984)
		(end 414.588706 -126.631954)
		(width 0.1143)
		(layer "In4.Cu")
		(net "P3E_CPU0_PE3_OCP_TXP<15>")
	)
	(segment
		(start 357.299768 -104.0257)
		(end 360.115358 -104.0257)
		(width 0.1143)
		(layer "In4.Cu")
		(net "P3E_CPU0_PE3_OCP_TXP<15>")
	)
	(segment
		(start 462.499456 -123.275852)
		(end 462.8388 -123.614942)
		(width 0.1143)
		(layer "In4.Cu")
		(net "P3E_CPU0_PE3_OCP_TXP<15>")
	)
	(segment
		(start 453.467724 -117.8687)
		(end 454.491344 -118.292626)
		(width 0.1143)
		(layer "In4.Cu")
		(net "P3E_CPU0_PE3_OCP_TXP<15>")
	)
	(segment
		(start 428.813976 -121.835926)
		(end 430.286668 -122.129804)
		(width 0.1143)
		(layer "In4.Cu")
		(net "P3E_CPU0_PE3_OCP_TXP<15>")
	)
	(segment
		(start 424.580304 -127.536702)
		(end 425.107608 -127.410464)
		(width 0.1143)
		(layer "In4.Cu")
		(net "P3E_CPU0_PE3_OCP_TXP<15>")
	)
	(segment
		(start 362.591604 -122.454416)
		(end 362.690156 -122.952764)
		(width 0.1143)
		(layer "In4.Cu")
		(net "P3E_CPU0_PE3_OCP_TXP<15>")
	)
	(segment
		(start 410.542486 -127.253746)
		(end 411.06471 -127.357378)
		(width 0.1143)
		(layer "In4.Cu")
		(net "P3E_CPU0_PE3_OCP_TXP<15>")
	)
	(segment
		(start 426.736002 -124.732796)
		(end 427.598586 -122.525536)
		(width 0.1143)
		(layer "In4.Cu")
		(net "P3E_CPU0_PE3_OCP_TXP<15>")
	)
	(segment
		(start 361.93095 -112.754664)
		(end 362.516674 -113.340388)
		(width 0.1143)
		(layer "In4.Cu")
		(net "P3E_CPU0_PE3_OCP_TXP<15>")
	)
	(segment
		(start 392.77671 -131.51612)
		(end 394.373354 -131.87934)
		(width 0.1143)
		(layer "In4.Cu")
		(net "P3E_CPU0_PE3_OCP_TXP<15>")
	)
	(segment
		(start 363.209332 -126.5428)
		(end 363.920024 -126.824232)
		(width 0.1143)
		(layer "In4.Cu")
		(net "P3E_CPU0_PE3_OCP_TXP<15>")
	)
	(segment
		(start 387.24459 -129.873248)
		(end 387.928358 -131.08305)
		(width 0.1143)
		(layer "In4.Cu")
		(net "P3E_CPU0_PE3_OCP_TXP<15>")
	)
	(segment
		(start 361.510072 -109.90707)
		(end 361.93095 -110.327948)
		(width 0.1143)
		(layer "In4.Cu")
		(net "P3E_CPU0_PE3_OCP_TXP<15>")
	)
	(segment
		(start 362.690156 -122.952764)
		(end 362.591858 -123.449842)
		(width 0.1143)
		(layer "In4.Cu")
		(net "P3E_CPU0_PE3_OCP_TXP<15>")
	)
	(segment
		(start 388.780274 -131.586478)
		(end 390.574784 -131.960366)
		(width 0.1143)
		(layer "In4.Cu")
		(net "P3E_CPU0_PE3_OCP_TXP<15>")
	)
	(segment
		(start 384.000502 -125.741684)
		(end 384.976624 -125.940058)
		(width 0.1143)
		(layer "In4.Cu")
		(net "P3E_CPU0_PE3_OCP_TXP<15>")
	)
	(segment
		(start 387.928358 -131.08305)
		(end 388.780274 -131.586478)
		(width 0.1143)
		(layer "In4.Cu")
		(net "P3E_CPU0_PE3_OCP_TXP<15>")
	)
	(segment
		(start 410.044138 -127.352298)
		(end 410.542486 -127.253746)
		(width 0.1143)
		(layer "In4.Cu")
		(net "P3E_CPU0_PE3_OCP_TXP<15>")
	)
	(segment
		(start 414.588706 -126.631954)
		(end 415.096198 -126.531624)
		(width 0.1143)
		(layer "In4.Cu")
		(net "P3E_CPU0_PE3_OCP_TXP<15>")
	)
	(segment
		(start 462.99882 -124.18822)
		(end 463.32775 -124.18822)
		(width 0.1143)
		(layer "In4.Cu")
		(net "P3E_CPU0_PE3_OCP_TXP<15>")
	)
	(segment
		(start 375.382536 -127.418084)
		(end 376.137932 -127.250444)
		(width 0.1143)
		(layer "In4.Cu")
		(net "P3E_CPU0_PE3_OCP_TXP<15>")
	)
	(segment
		(start 432.089052 -121.576592)
		(end 432.606196 -121.703846)
		(width 0.1143)
		(layer "In4.Cu")
		(net "P3E_CPU0_PE3_OCP_TXP<15>")
	)
	(segment
		(start 355.498654 -106.17073)
		(end 355.498654 -104.693212)
		(width 0.1143)
		(layer "In11.Cu")
		(net "P3E_CPU0_PE3_OCP_TXP<15>")
	)
	(segment
		(start 333.583026 -100.026978)
		(end 335.93405 -99.630738)
		(width 0.1143)
		(layer "In11.Cu")
		(net "P3E_CPU0_PE3_OCP_TXP<15>")
	)
	(segment
		(start 304.388266 -89.879678)
		(end 304.493422 -89.984834)
		(width 0.0889)
		(layer "In11.Cu")
		(net "P3E_CPU0_PE3_OCP_TXP<15>")
	)
	(segment
		(start 304.388266 -89.584784)
		(end 304.388266 -89.879678)
		(width 0.0889)
		(layer "In11.Cu")
		(net "P3E_CPU0_PE3_OCP_TXP<15>")
	)
	(segment
		(start 341.830914 -103.644446)
		(end 343.633044 -104.942132)
		(width 0.1143)
		(layer "In11.Cu")
		(net "P3E_CPU0_PE3_OCP_TXP<15>")
	)
	(segment
		(start 338.450936 -99.625404)
		(end 340.05393 -100.325428)
		(width 0.1143)
		(layer "In11.Cu")
		(net "P3E_CPU0_PE3_OCP_TXP<15>")
	)
	(segment
		(start 308.602126 -89.9287)
		(end 316.670436 -91.533218)
		(width 0.1143)
		(layer "In11.Cu")
		(net "P3E_CPU0_PE3_OCP_TXP<15>")
	)
	(segment
		(start 308.17439 -89.9287)
		(end 308.602126 -89.9287)
		(width 0.1143)
		(layer "In11.Cu")
		(net "P3E_CPU0_PE3_OCP_TXP<15>")
	)
	(segment
		(start 308.082442 -89.984834)
		(end 308.138576 -89.9287)
		(width 0.0889)
		(layer "In11.Cu")
		(net "P3E_CPU0_PE3_OCP_TXP<15>")
	)
	(segment
		(start 304.493422 -89.984834)
		(end 308.082442 -89.984834)
		(width 0.0889)
		(layer "In11.Cu")
		(net "P3E_CPU0_PE3_OCP_TXP<15>")
	)
	(segment
		(start 331.658976 -99.697286)
		(end 333.583026 -100.026978)
		(width 0.1143)
		(layer "In11.Cu")
		(net "P3E_CPU0_PE3_OCP_TXP<15>")
	)
	(segment
		(start 337.141566 -99.794314)
		(end 338.450936 -99.625404)
		(width 0.1143)
		(layer "In11.Cu")
		(net "P3E_CPU0_PE3_OCP_TXP<15>")
	)
	(segment
		(start 323.739002 -96.416368)
		(end 331.658976 -99.697286)
		(width 0.1143)
		(layer "In11.Cu")
		(net "P3E_CPU0_PE3_OCP_TXP<15>")
	)
	(segment
		(start 353.685602 -106.898694)
		(end 355.117146 -106.641138)
		(width 0.1143)
		(layer "In11.Cu")
		(net "P3E_CPU0_PE3_OCP_TXP<15>")
	)
	(segment
		(start 356.977442 -104.078024)
		(end 356.977442 -103.703374)
		(width 0.1143)
		(layer "In11.Cu")
		(net "P3E_CPU0_PE3_OCP_TXP<15>")
	)
	(segment
		(start 340.05393 -100.325428)
		(end 340.863174 -101.307646)
		(width 0.1143)
		(layer "In11.Cu")
		(net "P3E_CPU0_PE3_OCP_TXP<15>")
	)
	(segment
		(start 321.463416 -93.518228)
		(end 323.739002 -96.416368)
		(width 0.1143)
		(layer "In11.Cu")
		(net "P3E_CPU0_PE3_OCP_TXP<15>")
	)
	(segment
		(start 355.498654 -104.693212)
		(end 355.999542 -104.192324)
		(width 0.1143)
		(layer "In11.Cu")
		(net "P3E_CPU0_PE3_OCP_TXP<15>")
	)
	(segment
		(start 308.138576 -89.9287)
		(end 308.17439 -89.9287)
		(width 0.0889)
		(layer "In11.Cu")
		(net "P3E_CPU0_PE3_OCP_TXP<15>")
	)
	(segment
		(start 343.633806 -104.942386)
		(end 353.685602 -106.898694)
		(width 0.1143)
		(layer "In11.Cu")
		(net "P3E_CPU0_PE3_OCP_TXP<15>")
	)
	(segment
		(start 356.863142 -104.192324)
		(end 356.977442 -104.078024)
		(width 0.1143)
		(layer "In11.Cu")
		(net "P3E_CPU0_PE3_OCP_TXP<15>")
	)
	(segment
		(start 316.670436 -91.533218)
		(end 321.463416 -93.518228)
		(width 0.1143)
		(layer "In11.Cu")
		(net "P3E_CPU0_PE3_OCP_TXP<15>")
	)
	(segment
		(start 355.999542 -104.192324)
		(end 356.863142 -104.192324)
		(width 0.1143)
		(layer "In11.Cu")
		(net "P3E_CPU0_PE3_OCP_TXP<15>")
	)
	(segment
		(start 343.633044 -104.942132)
		(end 343.633806 -104.942386)
		(width 0.1143)
		(layer "In11.Cu")
		(net "P3E_CPU0_PE3_OCP_TXP<15>")
	)
	(segment
		(start 355.117146 -106.641138)
		(end 355.498654 -106.17073)
		(width 0.1143)
		(layer "In11.Cu")
		(net "P3E_CPU0_PE3_OCP_TXP<15>")
	)
	(segment
		(start 335.93405 -99.630738)
		(end 337.141566 -99.794314)
		(width 0.1143)
		(layer "In11.Cu")
		(net "P3E_CPU0_PE3_OCP_TXP<15>")
	)
	(segment
		(start 340.863174 -101.307646)
		(end 341.830914 -103.644446)
		(width 0.1143)
		(layer "In11.Cu")
		(net "P3E_CPU0_PE3_OCP_TXP<15>")
	)
	(segment
		(start 304.675286 -91.070938)
		(end 305.246786 -91.070938)
		(width 0.1143)
		(layer "F.Cu")
		(net "P3E_CPU0_PE3_OCP_TXP<14>")
	)
	(via
		(at 460.24165 -124.13742)
		(size 0.508)
		(drill 0.254)
		(layers "F.Cu" "B.Cu")
		(net "P3E_CPU0_PE3_OCP_TXP<14>")
	)
	(via
		(at 357.418132 -105.81005)
		(size 0.508)
		(drill 0.254)
		(layers "F.Cu" "B.Cu")
		(net "P3E_CPU0_PE3_OCP_TXP<14>")
	)
	(via
		(at 305.246786 -91.070938)
		(size 0.508)
		(drill 0.254)
		(layers "F.Cu" "B.Cu")
		(net "P3E_CPU0_PE3_OCP_TXP<14>")
	)
	(segment
		(start 459.356714 -122.586496)
		(end 459.7273 -123.706128)
		(width 0.1143)
		(layer "B.Cu")
		(net "P3E_CPU0_PE3_OCP_TXP<14>")
	)
	(segment
		(start 459.7273 -124.02312)
		(end 459.8416 -124.13742)
		(width 0.1143)
		(layer "B.Cu")
		(net "P3E_CPU0_PE3_OCP_TXP<14>")
	)
	(segment
		(start 463.042 -116.49202)
		(end 462.65465 -116.87937)
		(width 0.1143)
		(layer "B.Cu")
		(net "P3E_CPU0_PE3_OCP_TXP<14>")
	)
	(segment
		(start 462.441544 -117.69725)
		(end 462.44129 -117.697504)
		(width 0.1143)
		(layer "B.Cu")
		(net "P3E_CPU0_PE3_OCP_TXP<14>")
	)
	(segment
		(start 459.7273 -123.706128)
		(end 459.7273 -124.02312)
		(width 0.1143)
		(layer "B.Cu")
		(net "P3E_CPU0_PE3_OCP_TXP<14>")
	)
	(segment
		(start 462.44129 -117.697504)
		(end 460.823564 -118.828566)
		(width 0.1143)
		(layer "B.Cu")
		(net "P3E_CPU0_PE3_OCP_TXP<14>")
	)
	(segment
		(start 459.793086 -120.709436)
		(end 459.356714 -122.586496)
		(width 0.1143)
		(layer "B.Cu")
		(net "P3E_CPU0_PE3_OCP_TXP<14>")
	)
	(segment
		(start 462.65465 -117.300756)
		(end 462.44129 -117.69725)
		(width 0.1143)
		(layer "B.Cu")
		(net "P3E_CPU0_PE3_OCP_TXP<14>")
	)
	(segment
		(start 462.44129 -117.69725)
		(end 462.441544 -117.69725)
		(width 0.1143)
		(layer "B.Cu")
		(net "P3E_CPU0_PE3_OCP_TXP<14>")
	)
	(segment
		(start 462.65465 -116.87937)
		(end 462.65465 -117.300756)
		(width 0.1143)
		(layer "B.Cu")
		(net "P3E_CPU0_PE3_OCP_TXP<14>")
	)
	(segment
		(start 459.8416 -124.13742)
		(end 460.24165 -124.13742)
		(width 0.1143)
		(layer "B.Cu")
		(net "P3E_CPU0_PE3_OCP_TXP<14>")
	)
	(segment
		(start 460.823564 -118.828566)
		(end 459.793086 -120.709436)
		(width 0.1143)
		(layer "B.Cu")
		(net "P3E_CPU0_PE3_OCP_TXP<14>")
	)
	(segment
		(start 454.0123 -121.578116)
		(end 453.314562 -119.893842)
		(width 0.1143)
		(layer "In4.Cu")
		(net "P3E_CPU0_PE3_OCP_TXP<14>")
	)
	(segment
		(start 360.875072 -110.170468)
		(end 360.875072 -105.935526)
		(width 0.1143)
		(layer "In4.Cu")
		(net "P3E_CPU0_PE3_OCP_TXP<14>")
	)
	(segment
		(start 362.034582 -119.94007)
		(end 361.875578 -119.135652)
		(width 0.1143)
		(layer "In4.Cu")
		(net "P3E_CPU0_PE3_OCP_TXP<14>")
	)
	(segment
		(start 418.739828 -126.663196)
		(end 416.042856 -127.39116)
		(width 0.1143)
		(layer "In4.Cu")
		(net "P3E_CPU0_PE3_OCP_TXP<14>")
	)
	(segment
		(start 453.27316 -119.852694)
		(end 452.584566 -119.1641)
		(width 0.1143)
		(layer "In4.Cu")
		(net "P3E_CPU0_PE3_OCP_TXP<14>")
	)
	(segment
		(start 424.561762 -128.207008)
		(end 420.71163 -127.056896)
		(width 0.1143)
		(layer "In4.Cu")
		(net "P3E_CPU0_PE3_OCP_TXP<14>")
	)
	(segment
		(start 414.58769 -127.292354)
		(end 413.939482 -127.16383)
		(width 0.1143)
		(layer "In4.Cu")
		(net "P3E_CPU0_PE3_OCP_TXP<14>")
	)
	(segment
		(start 362.03001 -122.952764)
		(end 361.931458 -122.454416)
		(width 0.1143)
		(layer "In4.Cu")
		(net "P3E_CPU0_PE3_OCP_TXP<14>")
	)
	(segment
		(start 459.7527 -124.02312)
		(end 459.7527 -123.685554)
		(width 0.1143)
		(layer "In4.Cu")
		(net "P3E_CPU0_PE3_OCP_TXP<14>")
	)
	(segment
		(start 426.917104 -125.681994)
		(end 425.52112 -127.9779)
		(width 0.1143)
		(layer "In4.Cu")
		(net "P3E_CPU0_PE3_OCP_TXP<14>")
	)
	(segment
		(start 361.931458 -124.447808)
		(end 362.02493 -123.97486)
		(width 0.1143)
		(layer "In4.Cu")
		(net "P3E_CPU0_PE3_OCP_TXP<14>")
	)
	(segment
		(start 432.04384 -124.505212)
		(end 430.61636 -124.870718)
		(width 0.1143)
		(layer "In4.Cu")
		(net "P3E_CPU0_PE3_OCP_TXP<14>")
	)
	(segment
		(start 362.02493 -123.97486)
		(end 361.926378 -123.476512)
		(width 0.1143)
		(layer "In4.Cu")
		(net "P3E_CPU0_PE3_OCP_TXP<14>")
	)
	(segment
		(start 361.26547 -112.987582)
		(end 361.26547 -110.560866)
		(width 0.1143)
		(layer "In4.Cu")
		(net "P3E_CPU0_PE3_OCP_TXP<14>")
	)
	(segment
		(start 377.163838 -128.13157)
		(end 376.140726 -127.913638)
		(width 0.1143)
		(layer "In4.Cu")
		(net "P3E_CPU0_PE3_OCP_TXP<14>")
	)
	(segment
		(start 358.46004 -104.7623)
		(end 358.044242 -105.178098)
		(width 0.1143)
		(layer "In4.Cu")
		(net "P3E_CPU0_PE3_OCP_TXP<14>")
	)
	(segment
		(start 425.52112 -127.9779)
		(end 424.561762 -128.207008)
		(width 0.1143)
		(layer "In4.Cu")
		(net "P3E_CPU0_PE3_OCP_TXP<14>")
	)
	(segment
		(start 413.939482 -127.16383)
		(end 412.604712 -127.705104)
		(width 0.1143)
		(layer "In4.Cu")
		(net "P3E_CPU0_PE3_OCP_TXP<14>")
	)
	(segment
		(start 460.24165 -124.13742)
		(end 459.867 -124.13742)
		(width 0.1143)
		(layer "In4.Cu")
		(net "P3E_CPU0_PE3_OCP_TXP<14>")
	)
	(segment
		(start 408.6352 -128.071118)
		(end 397.678656 -132.609336)
		(width 0.1143)
		(layer "In4.Cu")
		(net "P3E_CPU0_PE3_OCP_TXP<14>")
	)
	(segment
		(start 453.27316 -119.85244)
		(end 453.27316 -119.852694)
		(width 0.1143)
		(layer "In4.Cu")
		(net "P3E_CPU0_PE3_OCP_TXP<14>")
	)
	(segment
		(start 376.140726 -127.913638)
		(end 375.393204 -128.079246)
		(width 0.1143)
		(layer "In4.Cu")
		(net "P3E_CPU0_PE3_OCP_TXP<14>")
	)
	(segment
		(start 452.584566 -119.1641)
		(end 447.928492 -119.1641)
		(width 0.1143)
		(layer "In4.Cu")
		(net "P3E_CPU0_PE3_OCP_TXP<14>")
	)
	(segment
		(start 361.926378 -123.476512)
		(end 362.03001 -122.952764)
		(width 0.1143)
		(layer "In4.Cu")
		(net "P3E_CPU0_PE3_OCP_TXP<14>")
	)
	(segment
		(start 380.773178 -127.222504)
		(end 377.163838 -128.13157)
		(width 0.1143)
		(layer "In4.Cu")
		(net "P3E_CPU0_PE3_OCP_TXP<14>")
	)
	(segment
		(start 362.02874 -125.937772)
		(end 361.931458 -125.444504)
		(width 0.1143)
		(layer "In4.Cu")
		(net "P3E_CPU0_PE3_OCP_TXP<14>")
	)
	(segment
		(start 361.931458 -120.461024)
		(end 362.034582 -119.94007)
		(width 0.1143)
		(layer "In4.Cu")
		(net "P3E_CPU0_PE3_OCP_TXP<14>")
	)
	(segment
		(start 357.929942 -106.285538)
		(end 357.532432 -106.285538)
		(width 0.1143)
		(layer "In4.Cu")
		(net "P3E_CPU0_PE3_OCP_TXP<14>")
	)
	(segment
		(start 397.678656 -132.609336)
		(end 396.028418 -132.192014)
		(width 0.1143)
		(layer "In4.Cu")
		(net "P3E_CPU0_PE3_OCP_TXP<14>")
	)
	(segment
		(start 459.7527 -123.685554)
		(end 458.982572 -122.915426)
		(width 0.1143)
		(layer "In4.Cu")
		(net "P3E_CPU0_PE3_OCP_TXP<14>")
	)
	(segment
		(start 375.393204 -128.079246)
		(end 372.337076 -127.50419)
		(width 0.1143)
		(layer "In4.Cu")
		(net "P3E_CPU0_PE3_OCP_TXP<14>")
	)
	(segment
		(start 410.542486 -127.913892)
		(end 410.043376 -128.012698)
		(width 0.1143)
		(layer "In4.Cu")
		(net "P3E_CPU0_PE3_OCP_TXP<14>")
	)
	(segment
		(start 454.0123 -122.007884)
		(end 454.0123 -121.578116)
		(width 0.1143)
		(layer "In4.Cu")
		(net "P3E_CPU0_PE3_OCP_TXP<14>")
	)
	(segment
		(start 384.363468 -128.237996)
		(end 383.084578 -128.237996)
		(width 0.1143)
		(layer "In4.Cu")
		(net "P3E_CPU0_PE3_OCP_TXP<14>")
	)
	(segment
		(start 411.047438 -128.013968)
		(end 410.542486 -127.913892)
		(width 0.1143)
		(layer "In4.Cu")
		(net "P3E_CPU0_PE3_OCP_TXP<14>")
	)
	(segment
		(start 383.084578 -128.237996)
		(end 381.630174 -127.46228)
		(width 0.1143)
		(layer "In4.Cu")
		(net "P3E_CPU0_PE3_OCP_TXP<14>")
	)
	(segment
		(start 458.982572 -122.915426)
		(end 456.774042 -122.47626)
		(width 0.1143)
		(layer "In4.Cu")
		(net "P3E_CPU0_PE3_OCP_TXP<14>")
	)
	(segment
		(start 361.875578 -119.135652)
		(end 361.875578 -113.59769)
		(width 0.1143)
		(layer "In4.Cu")
		(net "P3E_CPU0_PE3_OCP_TXP<14>")
	)
	(segment
		(start 362.795566 -127.075692)
		(end 362.02874 -125.937772)
		(width 0.1143)
		(layer "In4.Cu")
		(net "P3E_CPU0_PE3_OCP_TXP<14>")
	)
	(segment
		(start 381.630174 -127.46228)
		(end 380.773178 -127.222504)
		(width 0.1143)
		(layer "In4.Cu")
		(net "P3E_CPU0_PE3_OCP_TXP<14>")
	)
	(segment
		(start 453.314562 -119.893842)
		(end 453.27316 -119.85244)
		(width 0.1143)
		(layer "In4.Cu")
		(net "P3E_CPU0_PE3_OCP_TXP<14>")
	)
	(segment
		(start 427.745144 -125.136402)
		(end 426.917104 -125.681994)
		(width 0.1143)
		(layer "In4.Cu")
		(net "P3E_CPU0_PE3_OCP_TXP<14>")
	)
	(segment
		(start 447.928492 -119.1641)
		(end 437.582818 -121.2215)
		(width 0.1143)
		(layer "In4.Cu")
		(net "P3E_CPU0_PE3_OCP_TXP<14>")
	)
	(segment
		(start 412.604712 -127.705104)
		(end 411.047438 -128.013968)
		(width 0.1143)
		(layer "In4.Cu")
		(net "P3E_CPU0_PE3_OCP_TXP<14>")
	)
	(segment
		(start 372.337076 -127.50419)
		(end 369.359434 -128.618996)
		(width 0.1143)
		(layer "In4.Cu")
		(net "P3E_CPU0_PE3_OCP_TXP<14>")
	)
	(segment
		(start 361.931458 -122.454416)
		(end 362.034582 -121.933462)
		(width 0.1143)
		(layer "In4.Cu")
		(net "P3E_CPU0_PE3_OCP_TXP<14>")
	)
	(segment
		(start 416.042856 -127.39116)
		(end 415.092388 -127.192532)
		(width 0.1143)
		(layer "In4.Cu")
		(net "P3E_CPU0_PE3_OCP_TXP<14>")
	)
	(segment
		(start 410.043376 -128.012698)
		(end 409.487878 -127.902716)
		(width 0.1143)
		(layer "In4.Cu")
		(net "P3E_CPU0_PE3_OCP_TXP<14>")
	)
	(segment
		(start 456.774042 -122.47626)
		(end 454.480676 -122.47626)
		(width 0.1143)
		(layer "In4.Cu")
		(net "P3E_CPU0_PE3_OCP_TXP<14>")
	)
	(segment
		(start 360.875072 -105.935526)
		(end 359.701846 -104.7623)
		(width 0.1143)
		(layer "In4.Cu")
		(net "P3E_CPU0_PE3_OCP_TXP<14>")
	)
	(segment
		(start 386.158232 -129.309622)
		(end 384.363468 -128.237996)
		(width 0.1143)
		(layer "In4.Cu")
		(net "P3E_CPU0_PE3_OCP_TXP<14>")
	)
	(segment
		(start 357.532432 -106.285538)
		(end 357.418132 -106.171238)
		(width 0.1143)
		(layer "In4.Cu")
		(net "P3E_CPU0_PE3_OCP_TXP<14>")
	)
	(segment
		(start 454.480676 -122.47626)
		(end 454.0123 -122.007884)
		(width 0.1143)
		(layer "In4.Cu")
		(net "P3E_CPU0_PE3_OCP_TXP<14>")
	)
	(segment
		(start 430.61636 -124.870718)
		(end 429.600614 -124.648214)
		(width 0.1143)
		(layer "In4.Cu")
		(net "P3E_CPU0_PE3_OCP_TXP<14>")
	)
	(segment
		(start 437.582818 -121.2215)
		(end 432.04384 -124.505212)
		(width 0.1143)
		(layer "In4.Cu")
		(net "P3E_CPU0_PE3_OCP_TXP<14>")
	)
	(segment
		(start 363.869478 -127.501396)
		(end 362.795566 -127.075692)
		(width 0.1143)
		(layer "In4.Cu")
		(net "P3E_CPU0_PE3_OCP_TXP<14>")
	)
	(segment
		(start 357.418132 -106.171238)
		(end 357.418132 -105.81005)
		(width 0.1143)
		(layer "In4.Cu")
		(net "P3E_CPU0_PE3_OCP_TXP<14>")
	)
	(segment
		(start 392.755628 -132.181346)
		(end 390.572498 -132.621528)
		(width 0.1143)
		(layer "In4.Cu")
		(net "P3E_CPU0_PE3_OCP_TXP<14>")
	)
	(segment
		(start 369.359434 -128.618996)
		(end 363.869478 -127.501396)
		(width 0.1143)
		(layer "In4.Cu")
		(net "P3E_CPU0_PE3_OCP_TXP<14>")
	)
	(segment
		(start 362.03001 -120.959372)
		(end 361.931458 -120.461024)
		(width 0.1143)
		(layer "In4.Cu")
		(net "P3E_CPU0_PE3_OCP_TXP<14>")
	)
	(segment
		(start 361.931458 -125.444504)
		(end 362.03001 -124.946156)
		(width 0.1143)
		(layer "In4.Cu")
		(net "P3E_CPU0_PE3_OCP_TXP<14>")
	)
	(segment
		(start 362.034582 -121.933462)
		(end 361.93603 -121.43486)
		(width 0.1143)
		(layer "In4.Cu")
		(net "P3E_CPU0_PE3_OCP_TXP<14>")
	)
	(segment
		(start 396.028418 -132.192014)
		(end 394.355574 -132.545328)
		(width 0.1143)
		(layer "In4.Cu")
		(net "P3E_CPU0_PE3_OCP_TXP<14>")
	)
	(segment
		(start 394.355574 -132.545328)
		(end 392.755628 -132.181346)
		(width 0.1143)
		(layer "In4.Cu")
		(net "P3E_CPU0_PE3_OCP_TXP<14>")
	)
	(segment
		(start 429.600614 -124.648214)
		(end 427.745144 -125.136402)
		(width 0.1143)
		(layer "In4.Cu")
		(net "P3E_CPU0_PE3_OCP_TXP<14>")
	)
	(segment
		(start 359.701846 -104.7623)
		(end 358.46004 -104.7623)
		(width 0.1143)
		(layer "In4.Cu")
		(net "P3E_CPU0_PE3_OCP_TXP<14>")
	)
	(segment
		(start 409.487878 -127.902716)
		(end 408.6352 -128.071118)
		(width 0.1143)
		(layer "In4.Cu")
		(net "P3E_CPU0_PE3_OCP_TXP<14>")
	)
	(segment
		(start 390.572498 -132.621528)
		(end 388.543292 -132.198618)
		(width 0.1143)
		(layer "In4.Cu")
		(net "P3E_CPU0_PE3_OCP_TXP<14>")
	)
	(segment
		(start 387.412484 -131.531106)
		(end 386.158232 -129.309622)
		(width 0.1143)
		(layer "In4.Cu")
		(net "P3E_CPU0_PE3_OCP_TXP<14>")
	)
	(segment
		(start 358.044242 -106.171238)
		(end 357.929942 -106.285538)
		(width 0.1143)
		(layer "In4.Cu")
		(net "P3E_CPU0_PE3_OCP_TXP<14>")
	)
	(segment
		(start 361.26547 -110.560866)
		(end 360.875072 -110.170468)
		(width 0.1143)
		(layer "In4.Cu")
		(net "P3E_CPU0_PE3_OCP_TXP<14>")
	)
	(segment
		(start 388.543292 -132.198618)
		(end 387.412484 -131.531106)
		(width 0.1143)
		(layer "In4.Cu")
		(net "P3E_CPU0_PE3_OCP_TXP<14>")
	)
	(segment
		(start 358.044242 -105.178098)
		(end 358.044242 -106.171238)
		(width 0.1143)
		(layer "In4.Cu")
		(net "P3E_CPU0_PE3_OCP_TXP<14>")
	)
	(segment
		(start 459.867 -124.13742)
		(end 459.7527 -124.02312)
		(width 0.1143)
		(layer "In4.Cu")
		(net "P3E_CPU0_PE3_OCP_TXP<14>")
	)
	(segment
		(start 415.092388 -127.192532)
		(end 414.58769 -127.292354)
		(width 0.1143)
		(layer "In4.Cu")
		(net "P3E_CPU0_PE3_OCP_TXP<14>")
	)
	(segment
		(start 361.875578 -113.59769)
		(end 361.26547 -112.987582)
		(width 0.1143)
		(layer "In4.Cu")
		(net "P3E_CPU0_PE3_OCP_TXP<14>")
	)
	(segment
		(start 362.03001 -124.946156)
		(end 361.931458 -124.447808)
		(width 0.1143)
		(layer "In4.Cu")
		(net "P3E_CPU0_PE3_OCP_TXP<14>")
	)
	(segment
		(start 420.71163 -127.056896)
		(end 418.739828 -126.663196)
		(width 0.1143)
		(layer "In4.Cu")
		(net "P3E_CPU0_PE3_OCP_TXP<14>")
	)
	(segment
		(start 361.93603 -121.43486)
		(end 362.03001 -120.959372)
		(width 0.1143)
		(layer "In4.Cu")
		(net "P3E_CPU0_PE3_OCP_TXP<14>")
	)
	(segment
		(start 357.418132 -105.81005)
		(end 356.921562 -106.30662)
		(width 0.1143)
		(layer "In11.Cu")
		(net "P3E_CPU0_PE3_OCP_TXP<14>")
	)
	(segment
		(start 308.40934 -90.9828)
		(end 308.394862 -90.9828)
		(width 0.0889)
		(layer "In11.Cu")
		(net "P3E_CPU0_PE3_OCP_TXP<14>")
	)
	(segment
		(start 336.044286 -100.423726)
		(end 333.581248 -100.838762)
		(width 0.1143)
		(layer "In11.Cu")
		(net "P3E_CPU0_PE3_OCP_TXP<14>")
	)
	(segment
		(start 331.616558 -100.501704)
		(end 323.215508 -97.022158)
		(width 0.1143)
		(layer "In11.Cu")
		(net "P3E_CPU0_PE3_OCP_TXP<14>")
	)
	(segment
		(start 308.394862 -90.9828)
		(end 308.344062 -91.0336)
		(width 0.0889)
		(layer "In11.Cu")
		(net "P3E_CPU0_PE3_OCP_TXP<14>")
	)
	(segment
		(start 308.344062 -91.0336)
		(end 307.692806 -91.0336)
		(width 0.0889)
		(layer "In11.Cu")
		(net "P3E_CPU0_PE3_OCP_TXP<14>")
	)
	(segment
		(start 355.848666 -107.502452)
		(end 355.501194 -107.646724)
		(width 0.1143)
		(layer "In11.Cu")
		(net "P3E_CPU0_PE3_OCP_TXP<14>")
	)
	(segment
		(start 305.264312 -91.470988)
		(end 305.2318 -91.470988)
		(width 0.0889)
		(layer "In11.Cu")
		(net "P3E_CPU0_PE3_OCP_TXP<14>")
	)
	(segment
		(start 343.156286 -105.582212)
		(end 341.39759 -104.318816)
		(width 0.1143)
		(layer "In11.Cu")
		(net "P3E_CPU0_PE3_OCP_TXP<14>")
	)
	(segment
		(start 353.585526 -107.646724)
		(end 343.156286 -105.582212)
		(width 0.1143)
		(layer "In11.Cu")
		(net "P3E_CPU0_PE3_OCP_TXP<14>")
	)
	(segment
		(start 339.723222 -101.054154)
		(end 338.333588 -100.447348)
		(width 0.1143)
		(layer "In11.Cu")
		(net "P3E_CPU0_PE3_OCP_TXP<14>")
	)
	(segment
		(start 355.849174 -107.502198)
		(end 355.848666 -107.502452)
		(width 0.1143)
		(layer "In11.Cu")
		(net "P3E_CPU0_PE3_OCP_TXP<14>")
	)
	(segment
		(start 355.501194 -107.646724)
		(end 353.585526 -107.646724)
		(width 0.1143)
		(layer "In11.Cu")
		(net "P3E_CPU0_PE3_OCP_TXP<14>")
	)
	(segment
		(start 356.921562 -106.30662)
		(end 356.463092 -106.30662)
		(width 0.1143)
		(layer "In11.Cu")
		(net "P3E_CPU0_PE3_OCP_TXP<14>")
	)
	(segment
		(start 333.581248 -100.838762)
		(end 331.616558 -100.501704)
		(width 0.1143)
		(layer "In11.Cu")
		(net "P3E_CPU0_PE3_OCP_TXP<14>")
	)
	(segment
		(start 356.463092 -106.30662)
		(end 356.006908 -106.762804)
		(width 0.1143)
		(layer "In11.Cu")
		(net "P3E_CPU0_PE3_OCP_TXP<14>")
	)
	(segment
		(start 341.39759 -104.318816)
		(end 340.372446 -101.84257)
		(width 0.1143)
		(layer "In11.Cu")
		(net "P3E_CPU0_PE3_OCP_TXP<14>")
	)
	(segment
		(start 321.17538 -94.422722)
		(end 315.901832 -92.238322)
		(width 0.1143)
		(layer "In11.Cu")
		(net "P3E_CPU0_PE3_OCP_TXP<14>")
	)
	(segment
		(start 356.006908 -106.762804)
		(end 356.006908 -107.344464)
		(width 0.1143)
		(layer "In11.Cu")
		(net "P3E_CPU0_PE3_OCP_TXP<14>")
	)
	(segment
		(start 306.336192 -90.967052)
		(end 306.120546 -90.967052)
		(width 0.0889)
		(layer "In11.Cu")
		(net "P3E_CPU0_PE3_OCP_TXP<14>")
	)
	(segment
		(start 315.901832 -92.238322)
		(end 309.589424 -90.9828)
		(width 0.1143)
		(layer "In11.Cu")
		(net "P3E_CPU0_PE3_OCP_TXP<14>")
	)
	(segment
		(start 309.589424 -90.9828)
		(end 308.40934 -90.9828)
		(width 0.1143)
		(layer "In11.Cu")
		(net "P3E_CPU0_PE3_OCP_TXP<14>")
	)
	(segment
		(start 338.333588 -100.447348)
		(end 337.251294 -100.586794)
		(width 0.1143)
		(layer "In11.Cu")
		(net "P3E_CPU0_PE3_OCP_TXP<14>")
	)
	(segment
		(start 356.006908 -107.344464)
		(end 355.849174 -107.502198)
		(width 0.1143)
		(layer "In11.Cu")
		(net "P3E_CPU0_PE3_OCP_TXP<14>")
	)
	(segment
		(start 340.372446 -101.84257)
		(end 339.723222 -101.054154)
		(width 0.1143)
		(layer "In11.Cu")
		(net "P3E_CPU0_PE3_OCP_TXP<14>")
	)
	(segment
		(start 337.251294 -100.586794)
		(end 336.044286 -100.423726)
		(width 0.1143)
		(layer "In11.Cu")
		(net "P3E_CPU0_PE3_OCP_TXP<14>")
	)
	(segment
		(start 304.925222 -91.176602)
		(end 305.246786 -91.070938)
		(width 0.0889)
		(layer "In11.Cu")
		(net "P3E_CPU0_PE3_OCP_TXP<14>")
	)
	(segment
		(start 323.215508 -97.022158)
		(end 321.17538 -94.422722)
		(width 0.1143)
		(layer "In11.Cu")
		(net "P3E_CPU0_PE3_OCP_TXP<14>")
	)
	(segment
		(start 304.888392 -91.249246)
		(end 304.925222 -91.176602)
		(width 0.0889)
		(layer "In11.Cu")
		(net "P3E_CPU0_PE3_OCP_TXP<14>")
	)
	(segment
		(start 307.692806 -91.0336)
		(end 306.336192 -90.967052)
		(width 0.0889)
		(layer "In11.Cu")
		(net "P3E_CPU0_PE3_OCP_TXP<14>")
	)
	(arc
		(start 304.932588 -91.318842)
		(mid 304.908728 -91.285164)
		(end 304.888392 -91.249246)
		(width 0.0889)
		(layer "In11.Cu")
		(net "P3E_CPU0_PE3_OCP_TXP<14>")
	)
	(arc
		(start 306.120546 -90.967052)
		(mid 305.816234 -91.048383)
		(end 305.593496 -91.27109)
		(width 0.0889)
		(layer "In11.Cu")
		(net "P3E_CPU0_PE3_OCP_TXP<14>")
	)
	(arc
		(start 305.593496 -91.27109)
		(mid 305.454503 -91.41317)
		(end 305.264312 -91.470988)
		(width 0.0889)
		(layer "In11.Cu")
		(net "P3E_CPU0_PE3_OCP_TXP<14>")
	)
	(arc
		(start 305.2318 -91.470988)
		(mid 305.065506 -91.427754)
		(end 304.932588 -91.318842)
		(width 0.0889)
		(layer "In11.Cu")
		(net "P3E_CPU0_PE3_OCP_TXP<14>")
	)
	(segment
		(start 303.529746 -92.061538)
		(end 302.958246 -92.061538)
		(width 0.1143)
		(layer "F.Cu")
		(net "P3E_CPU0_PE3_OCP_TXP<13>")
	)
	(via
		(at 457.48575 -124.18822)
		(size 0.508)
		(drill 0.254)
		(layers "F.Cu" "B.Cu")
		(net "P3E_CPU0_PE3_OCP_TXP<13>")
	)
	(via
		(at 359.405428 -105.92816)
		(size 0.508)
		(drill 0.254)
		(layers "F.Cu" "B.Cu")
		(net "P3E_CPU0_PE3_OCP_TXP<13>")
	)
	(via
		(at 303.529746 -92.061538)
		(size 0.508)
		(drill 0.254)
		(layers "F.Cu" "B.Cu")
		(net "P3E_CPU0_PE3_OCP_TXP<13>")
	)
	(segment
		(start 457.23683 -119.10568)
		(end 456.786996 -120.503188)
		(width 0.1143)
		(layer "B.Cu")
		(net "P3E_CPU0_PE3_OCP_TXP<13>")
	)
	(segment
		(start 456.786996 -120.503188)
		(end 457.403708 -122.080274)
		(width 0.1143)
		(layer "B.Cu")
		(net "P3E_CPU0_PE3_OCP_TXP<13>")
	)
	(segment
		(start 459.47965 -116.87937)
		(end 459.47965 -117.317012)
		(width 0.1143)
		(layer "B.Cu")
		(net "P3E_CPU0_PE3_OCP_TXP<13>")
	)
	(segment
		(start 457.403708 -122.080274)
		(end 456.9714 -123.55195)
		(width 0.1143)
		(layer "B.Cu")
		(net "P3E_CPU0_PE3_OCP_TXP<13>")
	)
	(segment
		(start 459.867 -116.49202)
		(end 459.47965 -116.87937)
		(width 0.1143)
		(layer "B.Cu")
		(net "P3E_CPU0_PE3_OCP_TXP<13>")
	)
	(segment
		(start 459.47965 -117.317012)
		(end 459.027784 -117.95252)
		(width 0.1143)
		(layer "B.Cu")
		(net "P3E_CPU0_PE3_OCP_TXP<13>")
	)
	(segment
		(start 459.027784 -117.95252)
		(end 457.23683 -119.10568)
		(width 0.1143)
		(layer "B.Cu")
		(net "P3E_CPU0_PE3_OCP_TXP<13>")
	)
	(segment
		(start 456.9714 -123.55195)
		(end 456.9714 -124.07392)
		(width 0.1143)
		(layer "B.Cu")
		(net "P3E_CPU0_PE3_OCP_TXP<13>")
	)
	(segment
		(start 457.0857 -124.18822)
		(end 457.48575 -124.18822)
		(width 0.1143)
		(layer "B.Cu")
		(net "P3E_CPU0_PE3_OCP_TXP<13>")
	)
	(segment
		(start 456.9714 -124.07392)
		(end 457.0857 -124.18822)
		(width 0.1143)
		(layer "B.Cu")
		(net "P3E_CPU0_PE3_OCP_TXP<13>")
	)
	(segment
		(start 362.380276 -127.607822)
		(end 363.684058 -128.124712)
		(width 0.1143)
		(layer "In4.Cu")
		(net "P3E_CPU0_PE3_OCP_TXP<13>")
	)
	(segment
		(start 359.957116 -106.382058)
		(end 360.240072 -106.665014)
		(width 0.1143)
		(layer "In4.Cu")
		(net "P3E_CPU0_PE3_OCP_TXP<13>")
	)
	(segment
		(start 363.684058 -128.124712)
		(end 369.537488 -129.31648)
		(width 0.1143)
		(layer "In4.Cu")
		(net "P3E_CPU0_PE3_OCP_TXP<13>")
	)
	(segment
		(start 428.055278 -125.715776)
		(end 429.594264 -125.310392)
		(width 0.1143)
		(layer "In4.Cu")
		(net "P3E_CPU0_PE3_OCP_TXP<13>")
	)
	(segment
		(start 361.271058 -125.444504)
		(end 361.415838 -126.176278)
		(width 0.1143)
		(layer "In4.Cu")
		(net "P3E_CPU0_PE3_OCP_TXP<13>")
	)
	(segment
		(start 456.9714 -124.04852)
		(end 457.1111 -124.18822)
		(width 0.1143)
		(layer "In4.Cu")
		(net "P3E_CPU0_PE3_OCP_TXP<13>")
	)
	(segment
		(start 361.36961 -123.94946)
		(end 361.271058 -124.447808)
		(width 0.1143)
		(layer "In4.Cu")
		(net "P3E_CPU0_PE3_OCP_TXP<13>")
	)
	(segment
		(start 424.54322 -128.877822)
		(end 425.93387 -128.545082)
		(width 0.1143)
		(layer "In4.Cu")
		(net "P3E_CPU0_PE3_OCP_TXP<13>")
	)
	(segment
		(start 453.15505 -122.364246)
		(end 453.69353 -122.587512)
		(width 0.1143)
		(layer "In4.Cu")
		(net "P3E_CPU0_PE3_OCP_TXP<13>")
	)
	(segment
		(start 361.36961 -119.962676)
		(end 361.271058 -120.461024)
		(width 0.1143)
		(layer "In4.Cu")
		(net "P3E_CPU0_PE3_OCP_TXP<13>")
	)
	(segment
		(start 385.745482 -131.32054)
		(end 385.745736 -131.321048)
		(width 0.1143)
		(layer "In4.Cu")
		(net "P3E_CPU0_PE3_OCP_TXP<13>")
	)
	(segment
		(start 390.57072 -133.28269)
		(end 392.760454 -132.840984)
		(width 0.1143)
		(layer "In4.Cu")
		(net "P3E_CPU0_PE3_OCP_TXP<13>")
	)
	(segment
		(start 361.36961 -121.956068)
		(end 361.271058 -122.454416)
		(width 0.1143)
		(layer "In4.Cu")
		(net "P3E_CPU0_PE3_OCP_TXP<13>")
	)
	(segment
		(start 361.271058 -122.454416)
		(end 361.36961 -122.952764)
		(width 0.1143)
		(layer "In4.Cu")
		(net "P3E_CPU0_PE3_OCP_TXP<13>")
	)
	(segment
		(start 456.112626 -123.15952)
		(end 456.702414 -123.404122)
		(width 0.1143)
		(layer "In4.Cu")
		(net "P3E_CPU0_PE3_OCP_TXP<13>")
	)
	(segment
		(start 411.041596 -128.672844)
		(end 412.80334 -128.323594)
		(width 0.1143)
		(layer "In4.Cu")
		(net "P3E_CPU0_PE3_OCP_TXP<13>")
	)
	(segment
		(start 432.299364 -125.107954)
		(end 437.334406 -122.122692)
		(width 0.1143)
		(layer "In4.Cu")
		(net "P3E_CPU0_PE3_OCP_TXP<13>")
	)
	(segment
		(start 429.594264 -125.310392)
		(end 430.624996 -125.536198)
		(width 0.1143)
		(layer "In4.Cu")
		(net "P3E_CPU0_PE3_OCP_TXP<13>")
	)
	(segment
		(start 361.36961 -124.946156)
		(end 361.271058 -125.444504)
		(width 0.1143)
		(layer "In4.Cu")
		(net "P3E_CPU0_PE3_OCP_TXP<13>")
	)
	(segment
		(start 414.59912 -127.950214)
		(end 415.088578 -127.85344)
		(width 0.1143)
		(layer "In4.Cu")
		(net "P3E_CPU0_PE3_OCP_TXP<13>")
	)
	(segment
		(start 360.240072 -110.433866)
		(end 360.63047 -110.824264)
		(width 0.1143)
		(layer "In4.Cu")
		(net "P3E_CPU0_PE3_OCP_TXP<13>")
	)
	(segment
		(start 372.699026 -130.056128)
		(end 374.433592 -130.349498)
		(width 0.1143)
		(layer "In4.Cu")
		(net "P3E_CPU0_PE3_OCP_TXP<13>")
	)
	(segment
		(start 414.010602 -127.833882)
		(end 414.59912 -127.950214)
		(width 0.1143)
		(layer "In4.Cu")
		(net "P3E_CPU0_PE3_OCP_TXP<13>")
	)
	(segment
		(start 361.240578 -119.310912)
		(end 361.36961 -119.962676)
		(width 0.1143)
		(layer "In4.Cu")
		(net "P3E_CPU0_PE3_OCP_TXP<13>")
	)
	(segment
		(start 437.33466 -122.122692)
		(end 443.653672 -120.8659)
		(width 0.1143)
		(layer "In4.Cu")
		(net "P3E_CPU0_PE3_OCP_TXP<13>")
	)
	(segment
		(start 397.731742 -133.291072)
		(end 408.83078 -128.692656)
		(width 0.1143)
		(layer "In4.Cu")
		(net "P3E_CPU0_PE3_OCP_TXP<13>")
	)
	(segment
		(start 361.271058 -120.461024)
		(end 361.36961 -120.959372)
		(width 0.1143)
		(layer "In4.Cu")
		(net "P3E_CPU0_PE3_OCP_TXP<13>")
	)
	(segment
		(start 359.537 -106.382058)
		(end 359.957116 -106.382058)
		(width 0.1143)
		(layer "In4.Cu")
		(net "P3E_CPU0_PE3_OCP_TXP<13>")
	)
	(segment
		(start 361.240578 -113.861088)
		(end 361.240578 -119.310912)
		(width 0.1143)
		(layer "In4.Cu")
		(net "P3E_CPU0_PE3_OCP_TXP<13>")
	)
	(segment
		(start 361.36961 -120.959372)
		(end 361.271058 -121.45772)
		(width 0.1143)
		(layer "In4.Cu")
		(net "P3E_CPU0_PE3_OCP_TXP<13>")
	)
	(segment
		(start 394.363194 -133.205474)
		(end 396.01521 -132.856986)
		(width 0.1143)
		(layer "In4.Cu")
		(net "P3E_CPU0_PE3_OCP_TXP<13>")
	)
	(segment
		(start 443.653672 -120.8659)
		(end 446.602358 -120.8659)
		(width 0.1143)
		(layer "In4.Cu")
		(net "P3E_CPU0_PE3_OCP_TXP<13>")
	)
	(segment
		(start 453.69353 -122.587512)
		(end 454.265538 -123.15952)
		(width 0.1143)
		(layer "In4.Cu")
		(net "P3E_CPU0_PE3_OCP_TXP<13>")
	)
	(segment
		(start 408.83078 -128.692656)
		(end 409.495498 -128.561338)
		(width 0.1143)
		(layer "In4.Cu")
		(net "P3E_CPU0_PE3_OCP_TXP<13>")
	)
	(segment
		(start 376.190764 -129.833116)
		(end 378.01804 -130.215386)
		(width 0.1143)
		(layer "In4.Cu")
		(net "P3E_CPU0_PE3_OCP_TXP<13>")
	)
	(segment
		(start 425.93387 -128.545082)
		(end 427.386496 -126.155958)
		(width 0.1143)
		(layer "In4.Cu")
		(net "P3E_CPU0_PE3_OCP_TXP<13>")
	)
	(segment
		(start 452.321168 -122.198384)
		(end 453.15505 -122.364246)
		(width 0.1143)
		(layer "In4.Cu")
		(net "P3E_CPU0_PE3_OCP_TXP<13>")
	)
	(segment
		(start 412.80334 -128.323594)
		(end 414.010602 -127.833882)
		(width 0.1143)
		(layer "In4.Cu")
		(net "P3E_CPU0_PE3_OCP_TXP<13>")
	)
	(segment
		(start 430.624996 -125.536198)
		(end 432.299364 -125.107954)
		(width 0.1143)
		(layer "In4.Cu")
		(net "P3E_CPU0_PE3_OCP_TXP<13>")
	)
	(segment
		(start 388.249922 -132.799074)
		(end 390.57072 -133.28269)
		(width 0.1143)
		(layer "In4.Cu")
		(net "P3E_CPU0_PE3_OCP_TXP<13>")
	)
	(segment
		(start 383.101342 -130.47472)
		(end 385.311142 -131.064508)
		(width 0.1143)
		(layer "In4.Cu")
		(net "P3E_CPU0_PE3_OCP_TXP<13>")
	)
	(segment
		(start 361.36961 -122.952764)
		(end 361.271058 -123.451112)
		(width 0.1143)
		(layer "In4.Cu")
		(net "P3E_CPU0_PE3_OCP_TXP<13>")
	)
	(segment
		(start 361.271058 -123.451112)
		(end 361.36961 -123.94946)
		(width 0.1143)
		(layer "In4.Cu")
		(net "P3E_CPU0_PE3_OCP_TXP<13>")
	)
	(segment
		(start 437.334406 -122.122692)
		(end 437.33466 -122.122438)
		(width 0.1143)
		(layer "In4.Cu")
		(net "P3E_CPU0_PE3_OCP_TXP<13>")
	)
	(segment
		(start 456.702414 -123.404122)
		(end 456.9714 -123.673108)
		(width 0.1143)
		(layer "In4.Cu")
		(net "P3E_CPU0_PE3_OCP_TXP<13>")
	)
	(segment
		(start 378.01804 -130.215386)
		(end 380.613412 -129.59588)
		(width 0.1143)
		(layer "In4.Cu")
		(net "P3E_CPU0_PE3_OCP_TXP<13>")
	)
	(segment
		(start 385.745736 -131.321048)
		(end 388.249922 -132.799074)
		(width 0.1143)
		(layer "In4.Cu")
		(net "P3E_CPU0_PE3_OCP_TXP<13>")
	)
	(segment
		(start 392.760454 -132.840984)
		(end 394.363194 -133.205474)
		(width 0.1143)
		(layer "In4.Cu")
		(net "P3E_CPU0_PE3_OCP_TXP<13>")
	)
	(segment
		(start 410.05125 -128.67132)
		(end 410.542486 -128.574038)
		(width 0.1143)
		(layer "In4.Cu")
		(net "P3E_CPU0_PE3_OCP_TXP<13>")
	)
	(segment
		(start 374.433592 -130.349498)
		(end 376.190764 -129.833116)
		(width 0.1143)
		(layer "In4.Cu")
		(net "P3E_CPU0_PE3_OCP_TXP<13>")
	)
	(segment
		(start 454.265538 -123.15952)
		(end 456.112626 -123.15952)
		(width 0.1143)
		(layer "In4.Cu")
		(net "P3E_CPU0_PE3_OCP_TXP<13>")
	)
	(segment
		(start 360.240072 -106.665014)
		(end 360.240072 -110.433866)
		(width 0.1143)
		(layer "In4.Cu")
		(net "P3E_CPU0_PE3_OCP_TXP<13>")
	)
	(segment
		(start 396.01521 -132.856986)
		(end 397.731742 -133.291072)
		(width 0.1143)
		(layer "In4.Cu")
		(net "P3E_CPU0_PE3_OCP_TXP<13>")
	)
	(segment
		(start 418.744654 -127.343154)
		(end 421.696388 -128.02743)
		(width 0.1143)
		(layer "In4.Cu")
		(net "P3E_CPU0_PE3_OCP_TXP<13>")
	)
	(segment
		(start 448.138804 -121.787158)
		(end 452.321168 -122.198384)
		(width 0.1143)
		(layer "In4.Cu")
		(net "P3E_CPU0_PE3_OCP_TXP<13>")
	)
	(segment
		(start 427.386496 -126.155958)
		(end 428.055278 -125.715776)
		(width 0.1143)
		(layer "In4.Cu")
		(net "P3E_CPU0_PE3_OCP_TXP<13>")
	)
	(segment
		(start 360.63047 -110.824264)
		(end 360.63047 -113.25098)
		(width 0.1143)
		(layer "In4.Cu")
		(net "P3E_CPU0_PE3_OCP_TXP<13>")
	)
	(segment
		(start 370.466112 -129.109216)
		(end 372.699026 -130.056128)
		(width 0.1143)
		(layer "In4.Cu")
		(net "P3E_CPU0_PE3_OCP_TXP<13>")
	)
	(segment
		(start 415.088578 -127.85344)
		(end 416.083496 -128.061466)
		(width 0.1143)
		(layer "In4.Cu")
		(net "P3E_CPU0_PE3_OCP_TXP<13>")
	)
	(segment
		(start 369.537488 -129.31648)
		(end 370.466112 -129.109216)
		(width 0.1143)
		(layer "In4.Cu")
		(net "P3E_CPU0_PE3_OCP_TXP<13>")
	)
	(segment
		(start 410.542486 -128.574038)
		(end 411.041596 -128.672844)
		(width 0.1143)
		(layer "In4.Cu")
		(net "P3E_CPU0_PE3_OCP_TXP<13>")
	)
	(segment
		(start 360.63047 -113.25098)
		(end 361.240578 -113.861088)
		(width 0.1143)
		(layer "In4.Cu")
		(net "P3E_CPU0_PE3_OCP_TXP<13>")
	)
	(segment
		(start 409.495498 -128.561338)
		(end 410.05125 -128.67132)
		(width 0.1143)
		(layer "In4.Cu")
		(net "P3E_CPU0_PE3_OCP_TXP<13>")
	)
	(segment
		(start 359.405428 -106.250486)
		(end 359.537 -106.382058)
		(width 0.1143)
		(layer "In4.Cu")
		(net "P3E_CPU0_PE3_OCP_TXP<13>")
	)
	(segment
		(start 380.613412 -129.59588)
		(end 381.696976 -129.59588)
		(width 0.1143)
		(layer "In4.Cu")
		(net "P3E_CPU0_PE3_OCP_TXP<13>")
	)
	(segment
		(start 361.271058 -124.447808)
		(end 361.36961 -124.946156)
		(width 0.1143)
		(layer "In4.Cu")
		(net "P3E_CPU0_PE3_OCP_TXP<13>")
	)
	(segment
		(start 437.33466 -122.122438)
		(end 437.33466 -122.122692)
		(width 0.1143)
		(layer "In4.Cu")
		(net "P3E_CPU0_PE3_OCP_TXP<13>")
	)
	(segment
		(start 457.1111 -124.18822)
		(end 457.48575 -124.18822)
		(width 0.1143)
		(layer "In4.Cu")
		(net "P3E_CPU0_PE3_OCP_TXP<13>")
	)
	(segment
		(start 456.9714 -123.673108)
		(end 456.9714 -124.04852)
		(width 0.1143)
		(layer "In4.Cu")
		(net "P3E_CPU0_PE3_OCP_TXP<13>")
	)
	(segment
		(start 385.311142 -131.064508)
		(end 385.745482 -131.32054)
		(width 0.1143)
		(layer "In4.Cu")
		(net "P3E_CPU0_PE3_OCP_TXP<13>")
	)
	(segment
		(start 446.602358 -120.8659)
		(end 447.089022 -121.35231)
		(width 0.1143)
		(layer "In4.Cu")
		(net "P3E_CPU0_PE3_OCP_TXP<13>")
	)
	(segment
		(start 359.405428 -105.92816)
		(end 359.405428 -106.250486)
		(width 0.1143)
		(layer "In4.Cu")
		(net "P3E_CPU0_PE3_OCP_TXP<13>")
	)
	(segment
		(start 361.271058 -121.45772)
		(end 361.36961 -121.956068)
		(width 0.1143)
		(layer "In4.Cu")
		(net "P3E_CPU0_PE3_OCP_TXP<13>")
	)
	(segment
		(start 361.415838 -126.176278)
		(end 362.380276 -127.607822)
		(width 0.1143)
		(layer "In4.Cu")
		(net "P3E_CPU0_PE3_OCP_TXP<13>")
	)
	(segment
		(start 421.696388 -128.02743)
		(end 424.54322 -128.877822)
		(width 0.1143)
		(layer "In4.Cu")
		(net "P3E_CPU0_PE3_OCP_TXP<13>")
	)
	(segment
		(start 381.696976 -129.59588)
		(end 383.101342 -130.47472)
		(width 0.1143)
		(layer "In4.Cu")
		(net "P3E_CPU0_PE3_OCP_TXP<13>")
	)
	(segment
		(start 447.089022 -121.35231)
		(end 448.138804 -121.787158)
		(width 0.1143)
		(layer "In4.Cu")
		(net "P3E_CPU0_PE3_OCP_TXP<13>")
	)
	(segment
		(start 416.083496 -128.061466)
		(end 418.744654 -127.343154)
		(width 0.1143)
		(layer "In4.Cu")
		(net "P3E_CPU0_PE3_OCP_TXP<13>")
	)
	(segment
		(start 306.9082 -91.7448)
		(end 306.897024 -91.7448)
		(width 0.0889)
		(layer "In11.Cu")
		(net "P3E_CPU0_PE3_OCP_TXP<13>")
	)
	(segment
		(start 337.838034 -103.842312)
		(end 337.838034 -103.842566)
		(width 0.1143)
		(layer "In11.Cu")
		(net "P3E_CPU0_PE3_OCP_TXP<13>")
	)
	(segment
		(start 358.07015 -107.52455)
		(end 357.371396 -108.223304)
		(width 0.1143)
		(layer "In11.Cu")
		(net "P3E_CPU0_PE3_OCP_TXP<13>")
	)
	(segment
		(start 303.60874 -92.052648)
		(end 303.529746 -92.061538)
		(width 0.0889)
		(layer "In11.Cu")
		(net "P3E_CPU0_PE3_OCP_TXP<13>")
	)
	(segment
		(start 320.649346 -95.226632)
		(end 315.051186 -92.909136)
		(width 0.1143)
		(layer "In11.Cu")
		(net "P3E_CPU0_PE3_OCP_TXP<13>")
	)
	(segment
		(start 315.051186 -92.909136)
		(end 309.19928 -91.7448)
		(width 0.1143)
		(layer "In11.Cu")
		(net "P3E_CPU0_PE3_OCP_TXP<13>")
	)
	(segment
		(start 343.8271 -107.514644)
		(end 342.155272 -106.92765)
		(width 0.1143)
		(layer "In11.Cu")
		(net "P3E_CPU0_PE3_OCP_TXP<13>")
	)
	(segment
		(start 359.405428 -106.282236)
		(end 359.291128 -106.396536)
		(width 0.1143)
		(layer "In11.Cu")
		(net "P3E_CPU0_PE3_OCP_TXP<13>")
	)
	(segment
		(start 337.838034 -103.842566)
		(end 337.786726 -103.852218)
		(width 0.1143)
		(layer "In11.Cu")
		(net "P3E_CPU0_PE3_OCP_TXP<13>")
	)
	(segment
		(start 337.78444 -103.852726)
		(end 336.308192 -104.133904)
		(width 0.1143)
		(layer "In11.Cu")
		(net "P3E_CPU0_PE3_OCP_TXP<13>")
	)
	(segment
		(start 336.308192 -104.133904)
		(end 335.017872 -103.926386)
		(width 0.1143)
		(layer "In11.Cu")
		(net "P3E_CPU0_PE3_OCP_TXP<13>")
	)
	(segment
		(start 304.260504 -91.97975)
		(end 303.60874 -92.052648)
		(width 0.0889)
		(layer "In11.Cu")
		(net "P3E_CPU0_PE3_OCP_TXP<13>")
	)
	(segment
		(start 306.897024 -91.7448)
		(end 306.846224 -91.7956)
		(width 0.0889)
		(layer "In11.Cu")
		(net "P3E_CPU0_PE3_OCP_TXP<13>")
	)
	(segment
		(start 306.13096 -92.1512)
		(end 305.0032 -92.1512)
		(width 0.0889)
		(layer "In11.Cu")
		(net "P3E_CPU0_PE3_OCP_TXP<13>")
	)
	(segment
		(start 358.07015 -106.855006)
		(end 358.07015 -107.52455)
		(width 0.1143)
		(layer "In11.Cu")
		(net "P3E_CPU0_PE3_OCP_TXP<13>")
	)
	(segment
		(start 354.712016 -109.06506)
		(end 351.474024 -109.06506)
		(width 0.1143)
		(layer "In11.Cu")
		(net "P3E_CPU0_PE3_OCP_TXP<13>")
	)
	(segment
		(start 342.155272 -106.92765)
		(end 340.949534 -104.880664)
		(width 0.1143)
		(layer "In11.Cu")
		(net "P3E_CPU0_PE3_OCP_TXP<13>")
	)
	(segment
		(start 354.882958 -108.893864)
		(end 354.882958 -108.894118)
		(width 0.1143)
		(layer "In11.Cu")
		(net "P3E_CPU0_PE3_OCP_TXP<13>")
	)
	(segment
		(start 340.017354 -104.20858)
		(end 337.889596 -103.850948)
		(width 0.1143)
		(layer "In11.Cu")
		(net "P3E_CPU0_PE3_OCP_TXP<13>")
	)
	(segment
		(start 305.0032 -92.1512)
		(end 304.818034 -91.966034)
		(width 0.0889)
		(layer "In11.Cu")
		(net "P3E_CPU0_PE3_OCP_TXP<13>")
	)
	(segment
		(start 306.846224 -91.7956)
		(end 306.48656 -91.7956)
		(width 0.0889)
		(layer "In11.Cu")
		(net "P3E_CPU0_PE3_OCP_TXP<13>")
	)
	(segment
		(start 354.882958 -108.894118)
		(end 354.712016 -109.06506)
		(width 0.1143)
		(layer "In11.Cu")
		(net "P3E_CPU0_PE3_OCP_TXP<13>")
	)
	(segment
		(start 358.52862 -106.396536)
		(end 358.07015 -106.855006)
		(width 0.1143)
		(layer "In11.Cu")
		(net "P3E_CPU0_PE3_OCP_TXP<13>")
	)
	(segment
		(start 359.291128 -106.396536)
		(end 358.52862 -106.396536)
		(width 0.1143)
		(layer "In11.Cu")
		(net "P3E_CPU0_PE3_OCP_TXP<13>")
	)
	(segment
		(start 309.19928 -91.7448)
		(end 306.9082 -91.7448)
		(width 0.1143)
		(layer "In11.Cu")
		(net "P3E_CPU0_PE3_OCP_TXP<13>")
	)
	(segment
		(start 355.395276 -108.381546)
		(end 354.882958 -108.893864)
		(width 0.1143)
		(layer "In11.Cu")
		(net "P3E_CPU0_PE3_OCP_TXP<13>")
	)
	(segment
		(start 337.889596 -103.850948)
		(end 337.889596 -103.850694)
		(width 0.1143)
		(layer "In11.Cu")
		(net "P3E_CPU0_PE3_OCP_TXP<13>")
	)
	(segment
		(start 340.949534 -104.880664)
		(end 340.017354 -104.20858)
		(width 0.1143)
		(layer "In11.Cu")
		(net "P3E_CPU0_PE3_OCP_TXP<13>")
	)
	(segment
		(start 323.849492 -99.301808)
		(end 320.649346 -95.226632)
		(width 0.1143)
		(layer "In11.Cu")
		(net "P3E_CPU0_PE3_OCP_TXP<13>")
	)
	(segment
		(start 337.889596 -103.850694)
		(end 337.838034 -103.842312)
		(width 0.1143)
		(layer "In11.Cu")
		(net "P3E_CPU0_PE3_OCP_TXP<13>")
	)
	(segment
		(start 337.786726 -103.852218)
		(end 337.78444 -103.852726)
		(width 0.1143)
		(layer "In11.Cu")
		(net "P3E_CPU0_PE3_OCP_TXP<13>")
	)
	(segment
		(start 335.017872 -103.926386)
		(end 323.849492 -99.301808)
		(width 0.1143)
		(layer "In11.Cu")
		(net "P3E_CPU0_PE3_OCP_TXP<13>")
	)
	(segment
		(start 345.33078 -106.954574)
		(end 343.8271 -107.514644)
		(width 0.1143)
		(layer "In11.Cu")
		(net "P3E_CPU0_PE3_OCP_TXP<13>")
	)
	(segment
		(start 306.48656 -91.7956)
		(end 306.13096 -92.1512)
		(width 0.0889)
		(layer "In11.Cu")
		(net "P3E_CPU0_PE3_OCP_TXP<13>")
	)
	(segment
		(start 359.405428 -105.92816)
		(end 359.405428 -106.282236)
		(width 0.1143)
		(layer "In11.Cu")
		(net "P3E_CPU0_PE3_OCP_TXP<13>")
	)
	(segment
		(start 357.371396 -108.223304)
		(end 355.778308 -108.223304)
		(width 0.1143)
		(layer "In11.Cu")
		(net "P3E_CPU0_PE3_OCP_TXP<13>")
	)
	(segment
		(start 351.474024 -109.06506)
		(end 345.33078 -106.954574)
		(width 0.1143)
		(layer "In11.Cu")
		(net "P3E_CPU0_PE3_OCP_TXP<13>")
	)
	(segment
		(start 304.818034 -91.966034)
		(end 304.370486 -91.966034)
		(width 0.0889)
		(layer "In11.Cu")
		(net "P3E_CPU0_PE3_OCP_TXP<13>")
	)
	(segment
		(start 355.778308 -108.223304)
		(end 355.395276 -108.381546)
		(width 0.1143)
		(layer "In11.Cu")
		(net "P3E_CPU0_PE3_OCP_TXP<13>")
	)
	(arc
		(start 304.370486 -91.966034)
		(mid 304.315172 -91.970305)
		(end 304.260504 -91.97975)
		(width 0.0889)
		(layer "In11.Cu")
		(net "P3E_CPU0_PE3_OCP_TXP<13>")
	)
	(segment
		(start 303.529746 -94.042738)
		(end 302.958246 -94.042738)
		(width 0.1143)
		(layer "F.Cu")
		(net "P3E_CPU0_PE3_OCP_TXP<12>")
	)
	(via
		(at 454.53935 -124.18822)
		(size 0.508)
		(drill 0.254)
		(layers "F.Cu" "B.Cu")
		(net "P3E_CPU0_PE3_OCP_TXP<12>")
	)
	(via
		(at 303.529746 -94.042738)
		(size 0.508)
		(drill 0.254)
		(layers "F.Cu" "B.Cu")
		(net "P3E_CPU0_PE3_OCP_TXP<12>")
	)
	(via
		(at 355.955092 -109.16285)
		(size 0.508)
		(drill 0.254)
		(layers "F.Cu" "B.Cu")
		(net "P3E_CPU0_PE3_OCP_TXP<12>")
	)
	(segment
		(start 455.33183 -118.359936)
		(end 453.779636 -121.241312)
		(width 0.1143)
		(layer "B.Cu")
		(net "P3E_CPU0_PE3_OCP_TXP<12>")
	)
	(segment
		(start 454.025 -123.673616)
		(end 454.025 -124.07392)
		(width 0.1143)
		(layer "B.Cu")
		(net "P3E_CPU0_PE3_OCP_TXP<12>")
	)
	(segment
		(start 454.1393 -124.18822)
		(end 454.53935 -124.18822)
		(width 0.1143)
		(layer "B.Cu")
		(net "P3E_CPU0_PE3_OCP_TXP<12>")
	)
	(segment
		(start 453.978264 -121.934478)
		(end 453.762364 -122.831606)
		(width 0.1143)
		(layer "B.Cu")
		(net "P3E_CPU0_PE3_OCP_TXP<12>")
	)
	(segment
		(start 453.762364 -122.831606)
		(end 454.025 -123.673616)
		(width 0.1143)
		(layer "B.Cu")
		(net "P3E_CPU0_PE3_OCP_TXP<12>")
	)
	(segment
		(start 456.692 -116.49202)
		(end 456.30465 -116.87937)
		(width 0.1143)
		(layer "B.Cu")
		(net "P3E_CPU0_PE3_OCP_TXP<12>")
	)
	(segment
		(start 453.779636 -121.241312)
		(end 453.978264 -121.934478)
		(width 0.1143)
		(layer "B.Cu")
		(net "P3E_CPU0_PE3_OCP_TXP<12>")
	)
	(segment
		(start 456.018392 -117.848126)
		(end 455.33183 -118.359936)
		(width 0.1143)
		(layer "B.Cu")
		(net "P3E_CPU0_PE3_OCP_TXP<12>")
	)
	(segment
		(start 456.30465 -116.87937)
		(end 456.30465 -117.298978)
		(width 0.1143)
		(layer "B.Cu")
		(net "P3E_CPU0_PE3_OCP_TXP<12>")
	)
	(segment
		(start 456.30465 -117.298978)
		(end 456.018392 -117.848126)
		(width 0.1143)
		(layer "B.Cu")
		(net "P3E_CPU0_PE3_OCP_TXP<12>")
	)
	(segment
		(start 454.025 -124.07392)
		(end 454.1393 -124.18822)
		(width 0.1143)
		(layer "B.Cu")
		(net "P3E_CPU0_PE3_OCP_TXP<12>")
	)
	(segment
		(start 405.406352 -138.037316)
		(end 383.278126 -133.637274)
		(width 0.1143)
		(layer "In4.Cu")
		(net "P3E_CPU0_PE3_OCP_TXP<12>")
	)
	(segment
		(start 447.684906 -124.691394)
		(end 447.148966 -124.155454)
		(width 0.1143)
		(layer "In4.Cu")
		(net "P3E_CPU0_PE3_OCP_TXP<12>")
	)
	(segment
		(start 355.594158 -111.2647)
		(end 356.864158 -111.2647)
		(width 0.1143)
		(layer "In4.Cu")
		(net "P3E_CPU0_PE3_OCP_TXP<12>")
	)
	(segment
		(start 357.421688 -121.39168)
		(end 359.923842 -116.564918)
		(width 0.1143)
		(layer "In4.Cu")
		(net "P3E_CPU0_PE3_OCP_TXP<12>")
	)
	(segment
		(start 451.804532 -123.701556)
		(end 451.136512 -124.369576)
		(width 0.1143)
		(layer "In4.Cu")
		(net "P3E_CPU0_PE3_OCP_TXP<12>")
	)
	(segment
		(start 374.503442 -132.770118)
		(end 372.259098 -131.998974)
		(width 0.1143)
		(layer "In4.Cu")
		(net "P3E_CPU0_PE3_OCP_TXP<12>")
	)
	(segment
		(start 446.699894 -123.071636)
		(end 445.980058 -122.3518)
		(width 0.1143)
		(layer "In4.Cu")
		(net "P3E_CPU0_PE3_OCP_TXP<12>")
	)
	(segment
		(start 427.252384 -130.40233)
		(end 425.633642 -130.061716)
		(width 0.1143)
		(layer "In4.Cu")
		(net "P3E_CPU0_PE3_OCP_TXP<12>")
	)
	(segment
		(start 449.600574 -125.0061)
		(end 448.443858 -125.0061)
		(width 0.1143)
		(layer "In4.Cu")
		(net "P3E_CPU0_PE3_OCP_TXP<12>")
	)
	(segment
		(start 377.188476 -133.938518)
		(end 376.147584 -133.64845)
		(width 0.1143)
		(layer "In4.Cu")
		(net "P3E_CPU0_PE3_OCP_TXP<12>")
	)
	(segment
		(start 428.670466 -129.102104)
		(end 427.94936 -130.104896)
		(width 0.1143)
		(layer "In4.Cu")
		(net "P3E_CPU0_PE3_OCP_TXP<12>")
	)
	(segment
		(start 445.980058 -122.3518)
		(end 443.195202 -122.3518)
		(width 0.1143)
		(layer "In4.Cu")
		(net "P3E_CPU0_PE3_OCP_TXP<12>")
	)
	(segment
		(start 375.208546 -132.906516)
		(end 374.503442 -132.770118)
		(width 0.1143)
		(layer "In4.Cu")
		(net "P3E_CPU0_PE3_OCP_TXP<12>")
	)
	(segment
		(start 443.195202 -122.3518)
		(end 439.796428 -123.026424)
		(width 0.1143)
		(layer "In4.Cu")
		(net "P3E_CPU0_PE3_OCP_TXP<12>")
	)
	(segment
		(start 415.975546 -136.256014)
		(end 413.685736 -135.497316)
		(width 0.1143)
		(layer "In4.Cu")
		(net "P3E_CPU0_PE3_OCP_TXP<12>")
	)
	(segment
		(start 371.027706 -132.273548)
		(end 370.151914 -132.079746)
		(width 0.1143)
		(layer "In4.Cu")
		(net "P3E_CPU0_PE3_OCP_TXP<12>")
	)
	(segment
		(start 434.290216 -126.51613)
		(end 433.82692 -127.633476)
		(width 0.1143)
		(layer "In4.Cu")
		(net "P3E_CPU0_PE3_OCP_TXP<12>")
	)
	(segment
		(start 361.790742 -128.768094)
		(end 357.831644 -126.268226)
		(width 0.1143)
		(layer "In4.Cu")
		(net "P3E_CPU0_PE3_OCP_TXP<12>")
	)
	(segment
		(start 447.148966 -124.155454)
		(end 446.699894 -123.071636)
		(width 0.1143)
		(layer "In4.Cu")
		(net "P3E_CPU0_PE3_OCP_TXP<12>")
	)
	(segment
		(start 413.685736 -135.497316)
		(end 409.78836 -136.231376)
		(width 0.1143)
		(layer "In4.Cu")
		(net "P3E_CPU0_PE3_OCP_TXP<12>")
	)
	(segment
		(start 357.199692 -124.572522)
		(end 357.672132 -122.533156)
		(width 0.1143)
		(layer "In4.Cu")
		(net "P3E_CPU0_PE3_OCP_TXP<12>")
	)
	(segment
		(start 356.864158 -111.2647)
		(end 357.320342 -110.808516)
		(width 0.1143)
		(layer "In4.Cu")
		(net "P3E_CPU0_PE3_OCP_TXP<12>")
	)
	(segment
		(start 356.920546 -109.6518)
		(end 356.069392 -109.6518)
		(width 0.1143)
		(layer "In4.Cu")
		(net "P3E_CPU0_PE3_OCP_TXP<12>")
	)
	(segment
		(start 376.147584 -133.64845)
		(end 375.208546 -132.906516)
		(width 0.1143)
		(layer "In4.Cu")
		(net "P3E_CPU0_PE3_OCP_TXP<12>")
	)
	(segment
		(start 409.78836 -136.231376)
		(end 407.985722 -137.521696)
		(width 0.1143)
		(layer "In4.Cu")
		(net "P3E_CPU0_PE3_OCP_TXP<12>")
	)
	(segment
		(start 433.82692 -127.633476)
		(end 433.311046 -128.025906)
		(width 0.1143)
		(layer "In4.Cu")
		(net "P3E_CPU0_PE3_OCP_TXP<12>")
	)
	(segment
		(start 355.955092 -109.5375)
		(end 355.955092 -109.16285)
		(width 0.1143)
		(layer "In4.Cu")
		(net "P3E_CPU0_PE3_OCP_TXP<12>")
	)
	(segment
		(start 420.271702 -132.66547)
		(end 418.477954 -135.479536)
		(width 0.1143)
		(layer "In4.Cu")
		(net "P3E_CPU0_PE3_OCP_TXP<12>")
	)
	(segment
		(start 372.259098 -131.998974)
		(end 371.027706 -132.273548)
		(width 0.1143)
		(layer "In4.Cu")
		(net "P3E_CPU0_PE3_OCP_TXP<12>")
	)
	(segment
		(start 451.136512 -124.369576)
		(end 449.600574 -125.0061)
		(width 0.1143)
		(layer "In4.Cu")
		(net "P3E_CPU0_PE3_OCP_TXP<12>")
	)
	(segment
		(start 448.443858 -125.0061)
		(end 447.684906 -124.691394)
		(width 0.1143)
		(layer "In4.Cu")
		(net "P3E_CPU0_PE3_OCP_TXP<12>")
	)
	(segment
		(start 454.0504 -124.07392)
		(end 454.0504 -123.842526)
		(width 0.1143)
		(layer "In4.Cu")
		(net "P3E_CPU0_PE3_OCP_TXP<12>")
	)
	(segment
		(start 357.320342 -110.051596)
		(end 356.920546 -109.6518)
		(width 0.1143)
		(layer "In4.Cu")
		(net "P3E_CPU0_PE3_OCP_TXP<12>")
	)
	(segment
		(start 435.529228 -124.79528)
		(end 434.290216 -126.51613)
		(width 0.1143)
		(layer "In4.Cu")
		(net "P3E_CPU0_PE3_OCP_TXP<12>")
	)
	(segment
		(start 356.069646 -114.1349)
		(end 354.9396 -113.004854)
		(width 0.1143)
		(layer "In4.Cu")
		(net "P3E_CPU0_PE3_OCP_TXP<12>")
	)
	(segment
		(start 418.477954 -135.479536)
		(end 417.763706 -135.882634)
		(width 0.1143)
		(layer "In4.Cu")
		(net "P3E_CPU0_PE3_OCP_TXP<12>")
	)
	(segment
		(start 359.923842 -116.564918)
		(end 359.923842 -114.883184)
		(width 0.1143)
		(layer "In4.Cu")
		(net "P3E_CPU0_PE3_OCP_TXP<12>")
	)
	(segment
		(start 354.9396 -111.919258)
		(end 355.594158 -111.2647)
		(width 0.1143)
		(layer "In4.Cu")
		(net "P3E_CPU0_PE3_OCP_TXP<12>")
	)
	(segment
		(start 357.672132 -122.533156)
		(end 357.421688 -121.39168)
		(width 0.1143)
		(layer "In4.Cu")
		(net "P3E_CPU0_PE3_OCP_TXP<12>")
	)
	(segment
		(start 357.831644 -126.268226)
		(end 357.199692 -124.572522)
		(width 0.1143)
		(layer "In4.Cu")
		(net "P3E_CPU0_PE3_OCP_TXP<12>")
	)
	(segment
		(start 383.278126 -133.637274)
		(end 381.937514 -133.961886)
		(width 0.1143)
		(layer "In4.Cu")
		(net "P3E_CPU0_PE3_OCP_TXP<12>")
	)
	(segment
		(start 453.541892 -123.334526)
		(end 452.690992 -123.334526)
		(width 0.1143)
		(layer "In4.Cu")
		(net "P3E_CPU0_PE3_OCP_TXP<12>")
	)
	(segment
		(start 379.840998 -134.016242)
		(end 378.63526 -133.668262)
		(width 0.1143)
		(layer "In4.Cu")
		(net "P3E_CPU0_PE3_OCP_TXP<12>")
	)
	(segment
		(start 454.53935 -124.18822)
		(end 454.1647 -124.18822)
		(width 0.1143)
		(layer "In4.Cu")
		(net "P3E_CPU0_PE3_OCP_TXP<12>")
	)
	(segment
		(start 357.320342 -110.808516)
		(end 357.320342 -110.051596)
		(width 0.1143)
		(layer "In4.Cu")
		(net "P3E_CPU0_PE3_OCP_TXP<12>")
	)
	(segment
		(start 454.1647 -124.18822)
		(end 454.0504 -124.07392)
		(width 0.1143)
		(layer "In4.Cu")
		(net "P3E_CPU0_PE3_OCP_TXP<12>")
	)
	(segment
		(start 431.49139 -127.988568)
		(end 430.0474 -128.368806)
		(width 0.1143)
		(layer "In4.Cu")
		(net "P3E_CPU0_PE3_OCP_TXP<12>")
	)
	(segment
		(start 430.0474 -128.368806)
		(end 428.670466 -129.102104)
		(width 0.1143)
		(layer "In4.Cu")
		(net "P3E_CPU0_PE3_OCP_TXP<12>")
	)
	(segment
		(start 427.94936 -130.104896)
		(end 427.252384 -130.40233)
		(width 0.1143)
		(layer "In4.Cu")
		(net "P3E_CPU0_PE3_OCP_TXP<12>")
	)
	(segment
		(start 439.796428 -123.026424)
		(end 435.529228 -124.79528)
		(width 0.1143)
		(layer "In4.Cu")
		(net "P3E_CPU0_PE3_OCP_TXP<12>")
	)
	(segment
		(start 417.763706 -135.882634)
		(end 415.975546 -136.256014)
		(width 0.1143)
		(layer "In4.Cu")
		(net "P3E_CPU0_PE3_OCP_TXP<12>")
	)
	(segment
		(start 380.93523 -133.677914)
		(end 379.840998 -134.016242)
		(width 0.1143)
		(layer "In4.Cu")
		(net "P3E_CPU0_PE3_OCP_TXP<12>")
	)
	(segment
		(start 356.069392 -109.6518)
		(end 355.955092 -109.5375)
		(width 0.1143)
		(layer "In4.Cu")
		(net "P3E_CPU0_PE3_OCP_TXP<12>")
	)
	(segment
		(start 454.0504 -123.842526)
		(end 453.541892 -123.334526)
		(width 0.1143)
		(layer "In4.Cu")
		(net "P3E_CPU0_PE3_OCP_TXP<12>")
	)
	(segment
		(start 370.151914 -132.079746)
		(end 361.790742 -128.768094)
		(width 0.1143)
		(layer "In4.Cu")
		(net "P3E_CPU0_PE3_OCP_TXP<12>")
	)
	(segment
		(start 432.540664 -128.204468)
		(end 431.49139 -127.988568)
		(width 0.1143)
		(layer "In4.Cu")
		(net "P3E_CPU0_PE3_OCP_TXP<12>")
	)
	(segment
		(start 359.923842 -114.883184)
		(end 359.175558 -114.1349)
		(width 0.1143)
		(layer "In4.Cu")
		(net "P3E_CPU0_PE3_OCP_TXP<12>")
	)
	(segment
		(start 378.63526 -133.668262)
		(end 377.188476 -133.938518)
		(width 0.1143)
		(layer "In4.Cu")
		(net "P3E_CPU0_PE3_OCP_TXP<12>")
	)
	(segment
		(start 425.633642 -130.061716)
		(end 422.465754 -130.988562)
		(width 0.1143)
		(layer "In4.Cu")
		(net "P3E_CPU0_PE3_OCP_TXP<12>")
	)
	(segment
		(start 359.175558 -114.1349)
		(end 356.069646 -114.1349)
		(width 0.1143)
		(layer "In4.Cu")
		(net "P3E_CPU0_PE3_OCP_TXP<12>")
	)
	(segment
		(start 381.937514 -133.961886)
		(end 380.93523 -133.677914)
		(width 0.1143)
		(layer "In4.Cu")
		(net "P3E_CPU0_PE3_OCP_TXP<12>")
	)
	(segment
		(start 407.985722 -137.521696)
		(end 405.406352 -138.037316)
		(width 0.1143)
		(layer "In4.Cu")
		(net "P3E_CPU0_PE3_OCP_TXP<12>")
	)
	(segment
		(start 452.690992 -123.334526)
		(end 451.804532 -123.701556)
		(width 0.1143)
		(layer "In4.Cu")
		(net "P3E_CPU0_PE3_OCP_TXP<12>")
	)
	(segment
		(start 354.9396 -113.004854)
		(end 354.9396 -111.919258)
		(width 0.1143)
		(layer "In4.Cu")
		(net "P3E_CPU0_PE3_OCP_TXP<12>")
	)
	(segment
		(start 422.465754 -130.988562)
		(end 420.271702 -132.66547)
		(width 0.1143)
		(layer "In4.Cu")
		(net "P3E_CPU0_PE3_OCP_TXP<12>")
	)
	(segment
		(start 433.311046 -128.025906)
		(end 432.540664 -128.204468)
		(width 0.1143)
		(layer "In4.Cu")
		(net "P3E_CPU0_PE3_OCP_TXP<12>")
	)
	(segment
		(start 355.955092 -109.5375)
		(end 355.840792 -109.6518)
		(width 0.1143)
		(layer "In11.Cu")
		(net "P3E_CPU0_PE3_OCP_TXP<12>")
	)
	(segment
		(start 319.76822 -95.641668)
		(end 315.141864 -93.72346)
		(width 0.1143)
		(layer "In11.Cu")
		(net "P3E_CPU0_PE3_OCP_TXP<12>")
	)
	(segment
		(start 334.768952 -104.56799)
		(end 322.927472 -99.664266)
		(width 0.1143)
		(layer "In11.Cu")
		(net "P3E_CPU0_PE3_OCP_TXP<12>")
	)
	(segment
		(start 305.263042 -93.202506)
		(end 304.61077 -93.854778)
		(width 0.0889)
		(layer "In11.Cu")
		(net "P3E_CPU0_PE3_OCP_TXP<12>")
	)
	(segment
		(start 354.675948 -110.34014)
		(end 351.456244 -110.34014)
		(width 0.1143)
		(layer "In11.Cu")
		(net "P3E_CPU0_PE3_OCP_TXP<12>")
	)
	(segment
		(start 346.992194 -109.069886)
		(end 346.953332 -109.058964)
		(width 0.1143)
		(layer "In11.Cu")
		(net "P3E_CPU0_PE3_OCP_TXP<12>")
	)
	(segment
		(start 304.388774 -93.94698)
		(end 304.388266 -93.94698)
		(width 0.0889)
		(layer "In11.Cu")
		(net "P3E_CPU0_PE3_OCP_TXP<12>")
	)
	(segment
		(start 303.587658 -94.43847)
		(end 303.529746 -94.380558)
		(width 0.0889)
		(layer "In11.Cu")
		(net "P3E_CPU0_PE3_OCP_TXP<12>")
	)
	(segment
		(start 306.368958 -92.74429)
		(end 305.263042 -93.202506)
		(width 0.0889)
		(layer "In11.Cu")
		(net "P3E_CPU0_PE3_OCP_TXP<12>")
	)
	(segment
		(start 307.05298 -92.74429)
		(end 306.368958 -92.74429)
		(width 0.0889)
		(layer "In11.Cu")
		(net "P3E_CPU0_PE3_OCP_TXP<12>")
	)
	(segment
		(start 336.31759 -104.817164)
		(end 334.768952 -104.56799)
		(width 0.1143)
		(layer "In11.Cu")
		(net "P3E_CPU0_PE3_OCP_TXP<12>")
	)
	(segment
		(start 315.141864 -93.72346)
		(end 309.961788 -92.69349)
		(width 0.1143)
		(layer "In11.Cu")
		(net "P3E_CPU0_PE3_OCP_TXP<12>")
	)
	(segment
		(start 307.10378 -92.69349)
		(end 307.05298 -92.74429)
		(width 0.0889)
		(layer "In11.Cu")
		(net "P3E_CPU0_PE3_OCP_TXP<12>")
	)
	(segment
		(start 342.723724 -108.447586)
		(end 341.881206 -107.78871)
		(width 0.1143)
		(layer "In11.Cu")
		(net "P3E_CPU0_PE3_OCP_TXP<12>")
	)
	(segment
		(start 340.425278 -105.31729)
		(end 339.778594 -104.850946)
		(width 0.1143)
		(layer "In11.Cu")
		(net "P3E_CPU0_PE3_OCP_TXP<12>")
	)
	(segment
		(start 351.456244 -110.34014)
		(end 346.992194 -109.069886)
		(width 0.1143)
		(layer "In11.Cu")
		(net "P3E_CPU0_PE3_OCP_TXP<12>")
	)
	(segment
		(start 355.955092 -109.16285)
		(end 355.955092 -109.5375)
		(width 0.1143)
		(layer "In11.Cu")
		(net "P3E_CPU0_PE3_OCP_TXP<12>")
	)
	(segment
		(start 307.125878 -92.69349)
		(end 307.10378 -92.69349)
		(width 0.0889)
		(layer "In11.Cu")
		(net "P3E_CPU0_PE3_OCP_TXP<12>")
	)
	(segment
		(start 309.961788 -92.69349)
		(end 307.125878 -92.69349)
		(width 0.1143)
		(layer "In11.Cu")
		(net "P3E_CPU0_PE3_OCP_TXP<12>")
	)
	(segment
		(start 355.364288 -109.6518)
		(end 354.675948 -110.34014)
		(width 0.1143)
		(layer "In11.Cu")
		(net "P3E_CPU0_PE3_OCP_TXP<12>")
	)
	(segment
		(start 339.778594 -104.850946)
		(end 337.8454 -104.52608)
		(width 0.1143)
		(layer "In11.Cu")
		(net "P3E_CPU0_PE3_OCP_TXP<12>")
	)
	(segment
		(start 322.927472 -99.664266)
		(end 319.76822 -95.641668)
		(width 0.1143)
		(layer "In11.Cu")
		(net "P3E_CPU0_PE3_OCP_TXP<12>")
	)
	(segment
		(start 344.20048 -109.058964)
		(end 342.723724 -108.447586)
		(width 0.1143)
		(layer "In11.Cu")
		(net "P3E_CPU0_PE3_OCP_TXP<12>")
	)
	(segment
		(start 346.953332 -109.058964)
		(end 344.20048 -109.058964)
		(width 0.1143)
		(layer "In11.Cu")
		(net "P3E_CPU0_PE3_OCP_TXP<12>")
	)
	(segment
		(start 337.8454 -104.52608)
		(end 336.31759 -104.817164)
		(width 0.1143)
		(layer "In11.Cu")
		(net "P3E_CPU0_PE3_OCP_TXP<12>")
	)
	(segment
		(start 303.529746 -94.380558)
		(end 303.529746 -94.042738)
		(width 0.0889)
		(layer "In11.Cu")
		(net "P3E_CPU0_PE3_OCP_TXP<12>")
	)
	(segment
		(start 341.881206 -107.78871)
		(end 340.425278 -105.31729)
		(width 0.1143)
		(layer "In11.Cu")
		(net "P3E_CPU0_PE3_OCP_TXP<12>")
	)
	(segment
		(start 355.840792 -109.6518)
		(end 355.364288 -109.6518)
		(width 0.1143)
		(layer "In11.Cu")
		(net "P3E_CPU0_PE3_OCP_TXP<12>")
	)
	(arc
		(start 304.388266 -93.94698)
		(mid 304.092772 -94.026078)
		(end 303.876456 -94.242382)
		(width 0.0889)
		(layer "In11.Cu")
		(net "P3E_CPU0_PE3_OCP_TXP<12>")
	)
	(arc
		(start 304.61077 -93.854778)
		(mid 304.508947 -93.92297)
		(end 304.388774 -93.94698)
		(width 0.0889)
		(layer "In11.Cu")
		(net "P3E_CPU0_PE3_OCP_TXP<12>")
	)
	(arc
		(start 303.876456 -94.242382)
		(mid 303.754565 -94.373578)
		(end 303.587658 -94.43847)
		(width 0.0889)
		(layer "In11.Cu")
		(net "P3E_CPU0_PE3_OCP_TXP<12>")
	)
	(segment
		(start 303.816766 -94.538038)
		(end 304.388266 -94.538038)
		(width 0.1143)
		(layer "F.Cu")
		(net "P3E_CPU0_PE3_OCP_TXP<11>")
	)
	(via
		(at 304.388266 -94.538038)
		(size 0.508)
		(drill 0.254)
		(layers "F.Cu" "B.Cu")
		(net "P3E_CPU0_PE3_OCP_TXP<11>")
	)
	(via
		(at 449.66255 -123.78817)
		(size 0.508)
		(drill 0.254)
		(layers "F.Cu" "B.Cu")
		(net "P3E_CPU0_PE3_OCP_TXP<11>")
	)
	(via
		(at 357.9622 -109.16285)
		(size 0.508)
		(drill 0.254)
		(layers "F.Cu" "B.Cu")
		(net "P3E_CPU0_PE3_OCP_TXP<11>")
	)
	(segment
		(start 453.517 -116.49202)
		(end 453.12965 -116.87937)
		(width 0.1143)
		(layer "B.Cu")
		(net "P3E_CPU0_PE3_OCP_TXP<11>")
	)
	(segment
		(start 453.12965 -116.87937)
		(end 453.12965 -117.312186)
		(width 0.1143)
		(layer "B.Cu")
		(net "P3E_CPU0_PE3_OCP_TXP<11>")
	)
	(segment
		(start 452.84898 -117.738906)
		(end 450.13626 -119.544338)
		(width 0.1143)
		(layer "B.Cu")
		(net "P3E_CPU0_PE3_OCP_TXP<11>")
	)
	(segment
		(start 450.13626 -119.544338)
		(end 449.750688 -120.1674)
		(width 0.1143)
		(layer "B.Cu")
		(net "P3E_CPU0_PE3_OCP_TXP<11>")
	)
	(segment
		(start 449.2625 -123.78817)
		(end 449.66255 -123.78817)
		(width 0.1143)
		(layer "B.Cu")
		(net "P3E_CPU0_PE3_OCP_TXP<11>")
	)
	(segment
		(start 453.12965 -117.312186)
		(end 452.84898 -117.738906)
		(width 0.1143)
		(layer "B.Cu")
		(net "P3E_CPU0_PE3_OCP_TXP<11>")
	)
	(segment
		(start 450.042026 -121.25706)
		(end 449.1482 -123.290584)
		(width 0.1143)
		(layer "B.Cu")
		(net "P3E_CPU0_PE3_OCP_TXP<11>")
	)
	(segment
		(start 449.1482 -123.290584)
		(end 449.1482 -123.67387)
		(width 0.1143)
		(layer "B.Cu")
		(net "P3E_CPU0_PE3_OCP_TXP<11>")
	)
	(segment
		(start 449.750688 -120.1674)
		(end 450.042026 -121.25706)
		(width 0.1143)
		(layer "B.Cu")
		(net "P3E_CPU0_PE3_OCP_TXP<11>")
	)
	(segment
		(start 449.1482 -123.67387)
		(end 449.2625 -123.78817)
		(width 0.1143)
		(layer "B.Cu")
		(net "P3E_CPU0_PE3_OCP_TXP<11>")
	)
	(segment
		(start 428.351696 -126.305818)
		(end 427.854364 -126.633224)
		(width 0.1143)
		(layer "In4.Cu")
		(net "P3E_CPU0_PE3_OCP_TXP<11>")
	)
	(segment
		(start 357.881428 -124.502672)
		(end 358.336088 -122.536966)
		(width 0.1143)
		(layer "In4.Cu")
		(net "P3E_CPU0_PE3_OCP_TXP<11>")
	)
	(segment
		(start 358.0765 -109.6518)
		(end 357.9622 -109.5375)
		(width 0.1143)
		(layer "In4.Cu")
		(net "P3E_CPU0_PE3_OCP_TXP<11>")
	)
	(segment
		(start 449.66255 -123.78817)
		(end 449.2879 -123.78817)
		(width 0.1143)
		(layer "In4.Cu")
		(net "P3E_CPU0_PE3_OCP_TXP<11>")
	)
	(segment
		(start 359.994708 -111.087154)
		(end 359.592372 -110.684818)
		(width 0.1143)
		(layer "In4.Cu")
		(net "P3E_CPU0_PE3_OCP_TXP<11>")
	)
	(segment
		(start 446.234312 -121.539)
		(end 443.767718 -121.539)
		(width 0.1143)
		(layer "In4.Cu")
		(net "P3E_CPU0_PE3_OCP_TXP<11>")
	)
	(segment
		(start 427.854364 -126.633224)
		(end 426.346874 -129.112264)
		(width 0.1143)
		(layer "In4.Cu")
		(net "P3E_CPU0_PE3_OCP_TXP<11>")
	)
	(segment
		(start 397.919194 -134.00659)
		(end 396.001748 -133.521196)
		(width 0.1143)
		(layer "In4.Cu")
		(net "P3E_CPU0_PE3_OCP_TXP<11>")
	)
	(segment
		(start 443.767718 -121.539)
		(end 437.536844 -122.77852)
		(width 0.1143)
		(layer "In4.Cu")
		(net "P3E_CPU0_PE3_OCP_TXP<11>")
	)
	(segment
		(start 448.911218 -123.028964)
		(end 446.884298 -122.188986)
		(width 0.1143)
		(layer "In4.Cu")
		(net "P3E_CPU0_PE3_OCP_TXP<11>")
	)
	(segment
		(start 432.642772 -125.680216)
		(end 430.562258 -126.211838)
		(width 0.1143)
		(layer "In4.Cu")
		(net "P3E_CPU0_PE3_OCP_TXP<11>")
	)
	(segment
		(start 371.027198 -131.609846)
		(end 370.325142 -131.454398)
		(width 0.1143)
		(layer "In4.Cu")
		(net "P3E_CPU0_PE3_OCP_TXP<11>")
	)
	(segment
		(start 390.568434 -133.943852)
		(end 382.077976 -132.174996)
		(width 0.1143)
		(layer "In4.Cu")
		(net "P3E_CPU0_PE3_OCP_TXP<11>")
	)
	(segment
		(start 382.077976 -132.174996)
		(end 380.834138 -132.609336)
		(width 0.1143)
		(layer "In4.Cu")
		(net "P3E_CPU0_PE3_OCP_TXP<11>")
	)
	(segment
		(start 359.994708 -113.513616)
		(end 359.994708 -111.087154)
		(width 0.1143)
		(layer "In4.Cu")
		(net "P3E_CPU0_PE3_OCP_TXP<11>")
	)
	(segment
		(start 360.571542 -116.722906)
		(end 360.571542 -114.09045)
		(width 0.1143)
		(layer "In4.Cu")
		(net "P3E_CPU0_PE3_OCP_TXP<11>")
	)
	(segment
		(start 394.358114 -133.86816)
		(end 392.752326 -133.50367)
		(width 0.1143)
		(layer "In4.Cu")
		(net "P3E_CPU0_PE3_OCP_TXP<11>")
	)
	(segment
		(start 379.65761 -133.299708)
		(end 378.890276 -133.077966)
		(width 0.1143)
		(layer "In4.Cu")
		(net "P3E_CPU0_PE3_OCP_TXP<11>")
	)
	(segment
		(start 370.325142 -131.454398)
		(end 362.04652 -128.172464)
		(width 0.1143)
		(layer "In4.Cu")
		(net "P3E_CPU0_PE3_OCP_TXP<11>")
	)
	(segment
		(start 362.04652 -128.172464)
		(end 358.388158 -125.862334)
		(width 0.1143)
		(layer "In4.Cu")
		(net "P3E_CPU0_PE3_OCP_TXP<11>")
	)
	(segment
		(start 449.1736 -123.67387)
		(end 449.1736 -123.2916)
		(width 0.1143)
		(layer "In4.Cu")
		(net "P3E_CPU0_PE3_OCP_TXP<11>")
	)
	(segment
		(start 410.719778 -130.170936)
		(end 409.994608 -130.379724)
		(width 0.1143)
		(layer "In4.Cu")
		(net "P3E_CPU0_PE3_OCP_TXP<11>")
	)
	(segment
		(start 437.536844 -122.77852)
		(end 432.642772 -125.680216)
		(width 0.1143)
		(layer "In4.Cu")
		(net "P3E_CPU0_PE3_OCP_TXP<11>")
	)
	(segment
		(start 407.758392 -129.93243)
		(end 397.919194 -134.00659)
		(width 0.1143)
		(layer "In4.Cu")
		(net "P3E_CPU0_PE3_OCP_TXP<11>")
	)
	(segment
		(start 429.549052 -125.99035)
		(end 428.351696 -126.305818)
		(width 0.1143)
		(layer "In4.Cu")
		(net "P3E_CPU0_PE3_OCP_TXP<11>")
	)
	(segment
		(start 421.90416 -128.8161)
		(end 418.007292 -128.8161)
		(width 0.1143)
		(layer "In4.Cu")
		(net "P3E_CPU0_PE3_OCP_TXP<11>")
	)
	(segment
		(start 359.592372 -110.684818)
		(end 359.592372 -110.062518)
		(width 0.1143)
		(layer "In4.Cu")
		(net "P3E_CPU0_PE3_OCP_TXP<11>")
	)
	(segment
		(start 372.29669 -131.327144)
		(end 371.027198 -131.609846)
		(width 0.1143)
		(layer "In4.Cu")
		(net "P3E_CPU0_PE3_OCP_TXP<11>")
	)
	(segment
		(start 430.562258 -126.211838)
		(end 429.549052 -125.99035)
		(width 0.1143)
		(layer "In4.Cu")
		(net "P3E_CPU0_PE3_OCP_TXP<11>")
	)
	(segment
		(start 409.994608 -130.379724)
		(end 407.758392 -129.93243)
		(width 0.1143)
		(layer "In4.Cu")
		(net "P3E_CPU0_PE3_OCP_TXP<11>")
	)
	(segment
		(start 378.890276 -133.077966)
		(end 377.136406 -131.79806)
		(width 0.1143)
		(layer "In4.Cu")
		(net "P3E_CPU0_PE3_OCP_TXP<11>")
	)
	(segment
		(start 380.834138 -132.609336)
		(end 380.109222 -133.160008)
		(width 0.1143)
		(layer "In4.Cu")
		(net "P3E_CPU0_PE3_OCP_TXP<11>")
	)
	(segment
		(start 358.10444 -121.481596)
		(end 360.571542 -116.722906)
		(width 0.1143)
		(layer "In4.Cu")
		(net "P3E_CPU0_PE3_OCP_TXP<11>")
	)
	(segment
		(start 396.001748 -133.521196)
		(end 394.358114 -133.86816)
		(width 0.1143)
		(layer "In4.Cu")
		(net "P3E_CPU0_PE3_OCP_TXP<11>")
	)
	(segment
		(start 374.473978 -132.075174)
		(end 372.29669 -131.327144)
		(width 0.1143)
		(layer "In4.Cu")
		(net "P3E_CPU0_PE3_OCP_TXP<11>")
	)
	(segment
		(start 358.336088 -122.536966)
		(end 358.10444 -121.481596)
		(width 0.1143)
		(layer "In4.Cu")
		(net "P3E_CPU0_PE3_OCP_TXP<11>")
	)
	(segment
		(start 359.592372 -110.062518)
		(end 359.181654 -109.6518)
		(width 0.1143)
		(layer "In4.Cu")
		(net "P3E_CPU0_PE3_OCP_TXP<11>")
	)
	(segment
		(start 449.1736 -123.2916)
		(end 448.911218 -123.028964)
		(width 0.1143)
		(layer "In4.Cu")
		(net "P3E_CPU0_PE3_OCP_TXP<11>")
	)
	(segment
		(start 358.388158 -125.862334)
		(end 357.881428 -124.502672)
		(width 0.1143)
		(layer "In4.Cu")
		(net "P3E_CPU0_PE3_OCP_TXP<11>")
	)
	(segment
		(start 424.430444 -129.57048)
		(end 421.90416 -128.8161)
		(width 0.1143)
		(layer "In4.Cu")
		(net "P3E_CPU0_PE3_OCP_TXP<11>")
	)
	(segment
		(start 359.181654 -109.6518)
		(end 358.0765 -109.6518)
		(width 0.1143)
		(layer "In4.Cu")
		(net "P3E_CPU0_PE3_OCP_TXP<11>")
	)
	(segment
		(start 392.752326 -133.50367)
		(end 390.568434 -133.943852)
		(width 0.1143)
		(layer "In4.Cu")
		(net "P3E_CPU0_PE3_OCP_TXP<11>")
	)
	(segment
		(start 376.333512 -131.642866)
		(end 374.473978 -132.075174)
		(width 0.1143)
		(layer "In4.Cu")
		(net "P3E_CPU0_PE3_OCP_TXP<11>")
	)
	(segment
		(start 446.884298 -122.188986)
		(end 446.234312 -121.539)
		(width 0.1143)
		(layer "In4.Cu")
		(net "P3E_CPU0_PE3_OCP_TXP<11>")
	)
	(segment
		(start 449.2879 -123.78817)
		(end 449.1736 -123.67387)
		(width 0.1143)
		(layer "In4.Cu")
		(net "P3E_CPU0_PE3_OCP_TXP<11>")
	)
	(segment
		(start 377.136406 -131.79806)
		(end 376.333512 -131.642866)
		(width 0.1143)
		(layer "In4.Cu")
		(net "P3E_CPU0_PE3_OCP_TXP<11>")
	)
	(segment
		(start 380.109222 -133.160008)
		(end 379.65761 -133.299708)
		(width 0.1143)
		(layer "In4.Cu")
		(net "P3E_CPU0_PE3_OCP_TXP<11>")
	)
	(segment
		(start 360.571542 -114.09045)
		(end 359.994708 -113.513616)
		(width 0.1143)
		(layer "In4.Cu")
		(net "P3E_CPU0_PE3_OCP_TXP<11>")
	)
	(segment
		(start 426.346874 -129.112264)
		(end 424.430444 -129.57048)
		(width 0.1143)
		(layer "In4.Cu")
		(net "P3E_CPU0_PE3_OCP_TXP<11>")
	)
	(segment
		(start 357.9622 -109.5375)
		(end 357.9622 -109.16285)
		(width 0.1143)
		(layer "In4.Cu")
		(net "P3E_CPU0_PE3_OCP_TXP<11>")
	)
	(segment
		(start 412.98749 -130.93446)
		(end 410.719778 -130.170936)
		(width 0.1143)
		(layer "In4.Cu")
		(net "P3E_CPU0_PE3_OCP_TXP<11>")
	)
	(segment
		(start 418.007292 -128.8161)
		(end 412.98749 -130.93446)
		(width 0.1143)
		(layer "In4.Cu")
		(net "P3E_CPU0_PE3_OCP_TXP<11>")
	)
	(segment
		(start 357.9622 -109.5375)
		(end 357.8479 -109.6518)
		(width 0.1143)
		(layer "In11.Cu")
		(net "P3E_CPU0_PE3_OCP_TXP<11>")
	)
	(segment
		(start 332.2955 -108.2802)
		(end 331.7621 -107.7468)
		(width 0.1143)
		(layer "In11.Cu")
		(net "P3E_CPU0_PE3_OCP_TXP<11>")
	)
	(segment
		(start 309.45709 -94.083378)
		(end 307.775864 -93.386656)
		(width 0.1143)
		(layer "In11.Cu")
		(net "P3E_CPU0_PE3_OCP_TXP<11>")
	)
	(segment
		(start 312.812176 -98.442018)
		(end 311.79897 -96.425004)
		(width 0.1143)
		(layer "In11.Cu")
		(net "P3E_CPU0_PE3_OCP_TXP<11>")
	)
	(segment
		(start 357.8479 -109.6518)
		(end 357.371142 -109.6518)
		(width 0.1143)
		(layer "In11.Cu")
		(net "P3E_CPU0_PE3_OCP_TXP<11>")
	)
	(segment
		(start 344.635836 -110.42015)
		(end 332.63205 -110.42015)
		(width 0.1143)
		(layer "In11.Cu")
		(net "P3E_CPU0_PE3_OCP_TXP<11>")
	)
	(segment
		(start 311.79897 -96.425004)
		(end 309.45709 -94.083378)
		(width 0.1143)
		(layer "In11.Cu")
		(net "P3E_CPU0_PE3_OCP_TXP<11>")
	)
	(segment
		(start 331.7621 -107.7468)
		(end 329.486006 -107.7468)
		(width 0.1143)
		(layer "In11.Cu")
		(net "P3E_CPU0_PE3_OCP_TXP<11>")
	)
	(segment
		(start 304.671222 -94.617794)
		(end 304.54219 -94.642432)
		(width 0.0889)
		(layer "In11.Cu")
		(net "P3E_CPU0_PE3_OCP_TXP<11>")
	)
	(segment
		(start 357.9622 -109.16285)
		(end 357.9622 -109.5375)
		(width 0.1143)
		(layer "In11.Cu")
		(net "P3E_CPU0_PE3_OCP_TXP<11>")
	)
	(segment
		(start 357.371142 -109.6518)
		(end 357.0859 -109.937042)
		(width 0.1143)
		(layer "In11.Cu")
		(net "P3E_CPU0_PE3_OCP_TXP<11>")
	)
	(segment
		(start 329.486006 -107.7468)
		(end 315.74486 -102.053136)
		(width 0.1143)
		(layer "In11.Cu")
		(net "P3E_CPU0_PE3_OCP_TXP<11>")
	)
	(segment
		(start 355.124004 -111.0742)
		(end 354.583492 -111.614712)
		(width 0.1143)
		(layer "In11.Cu")
		(net "P3E_CPU0_PE3_OCP_TXP<11>")
	)
	(segment
		(start 354.583492 -111.614712)
		(end 346.423488 -111.614712)
		(width 0.1143)
		(layer "In11.Cu")
		(net "P3E_CPU0_PE3_OCP_TXP<11>")
	)
	(segment
		(start 356.710742 -111.0742)
		(end 355.124004 -111.0742)
		(width 0.1143)
		(layer "In11.Cu")
		(net "P3E_CPU0_PE3_OCP_TXP<11>")
	)
	(segment
		(start 306.45862 -93.424756)
		(end 305.548284 -93.801946)
		(width 0.0889)
		(layer "In11.Cu")
		(net "P3E_CPU0_PE3_OCP_TXP<11>")
	)
	(segment
		(start 315.74486 -102.053136)
		(end 312.812176 -98.442018)
		(width 0.1143)
		(layer "In11.Cu")
		(net "P3E_CPU0_PE3_OCP_TXP<11>")
	)
	(segment
		(start 332.2955 -110.0836)
		(end 332.2955 -108.2802)
		(width 0.1143)
		(layer "In11.Cu")
		(net "P3E_CPU0_PE3_OCP_TXP<11>")
	)
	(segment
		(start 307.337968 -93.386656)
		(end 307.326792 -93.386656)
		(width 0.0889)
		(layer "In11.Cu")
		(net "P3E_CPU0_PE3_OCP_TXP<11>")
	)
	(segment
		(start 332.63205 -110.42015)
		(end 332.2955 -110.0836)
		(width 0.1143)
		(layer "In11.Cu")
		(net "P3E_CPU0_PE3_OCP_TXP<11>")
	)
	(segment
		(start 307.775864 -93.386656)
		(end 307.337968 -93.386656)
		(width 0.1143)
		(layer "In11.Cu")
		(net "P3E_CPU0_PE3_OCP_TXP<11>")
	)
	(segment
		(start 305.548284 -93.801946)
		(end 304.801524 -94.548706)
		(width 0.0889)
		(layer "In11.Cu")
		(net "P3E_CPU0_PE3_OCP_TXP<11>")
	)
	(segment
		(start 357.0859 -109.937042)
		(end 357.0859 -110.699042)
		(width 0.1143)
		(layer "In11.Cu")
		(net "P3E_CPU0_PE3_OCP_TXP<11>")
	)
	(segment
		(start 304.54219 -94.642432)
		(end 304.388266 -94.538038)
		(width 0.0889)
		(layer "In11.Cu")
		(net "P3E_CPU0_PE3_OCP_TXP<11>")
	)
	(segment
		(start 304.801524 -94.548706)
		(end 304.671222 -94.617794)
		(width 0.0889)
		(layer "In11.Cu")
		(net "P3E_CPU0_PE3_OCP_TXP<11>")
	)
	(segment
		(start 307.288692 -93.424756)
		(end 306.45862 -93.424756)
		(width 0.0889)
		(layer "In11.Cu")
		(net "P3E_CPU0_PE3_OCP_TXP<11>")
	)
	(segment
		(start 307.326792 -93.386656)
		(end 307.288692 -93.424756)
		(width 0.0889)
		(layer "In11.Cu")
		(net "P3E_CPU0_PE3_OCP_TXP<11>")
	)
	(segment
		(start 346.423488 -111.614712)
		(end 344.635836 -110.42015)
		(width 0.1143)
		(layer "In11.Cu")
		(net "P3E_CPU0_PE3_OCP_TXP<11>")
	)
	(segment
		(start 357.0859 -110.699042)
		(end 356.710742 -111.0742)
		(width 0.1143)
		(layer "In11.Cu")
		(net "P3E_CPU0_PE3_OCP_TXP<11>")
	)
	(segment
		(start 303.816766 -95.528384)
		(end 304.388266 -95.528384)
		(width 0.1143)
		(layer "F.Cu")
		(net "P3E_CPU0_PE3_OCP_TXP<10>")
	)
	(via
		(at 304.388266 -95.528384)
		(size 0.508)
		(drill 0.254)
		(layers "F.Cu" "B.Cu")
		(net "P3E_CPU0_PE3_OCP_TXP<10>")
	)
	(via
		(at 446.67805 -126.087124)
		(size 0.508)
		(drill 0.254)
		(layers "F.Cu" "B.Cu")
		(net "P3E_CPU0_PE3_OCP_TXP<10>")
	)
	(via
		(at 358.26065 -116.220494)
		(size 0.508)
		(drill 0.254)
		(layers "F.Cu" "B.Cu")
		(net "P3E_CPU0_PE3_OCP_TXP<10>")
	)
	(segment
		(start 446.9384 -119.719852)
		(end 446.584832 -120.499124)
		(width 0.1143)
		(layer "B.Cu")
		(net "P3E_CPU0_PE3_OCP_TXP<10>")
	)
	(segment
		(start 446.278 -126.087124)
		(end 446.67805 -126.087124)
		(width 0.1143)
		(layer "B.Cu")
		(net "P3E_CPU0_PE3_OCP_TXP<10>")
	)
	(segment
		(start 449.5165 -117.771418)
		(end 446.9384 -119.719852)
		(width 0.1143)
		(layer "B.Cu")
		(net "P3E_CPU0_PE3_OCP_TXP<10>")
	)
	(segment
		(start 447.103246 -122.903996)
		(end 446.1637 -125.177804)
		(width 0.1143)
		(layer "B.Cu")
		(net "P3E_CPU0_PE3_OCP_TXP<10>")
	)
	(segment
		(start 446.1637 -125.972824)
		(end 446.278 -126.087124)
		(width 0.1143)
		(layer "B.Cu")
		(net "P3E_CPU0_PE3_OCP_TXP<10>")
	)
	(segment
		(start 449.82765 -116.87937)
		(end 449.82765 -117.314218)
		(width 0.1143)
		(layer "B.Cu")
		(net "P3E_CPU0_PE3_OCP_TXP<10>")
	)
	(segment
		(start 450.215 -116.49202)
		(end 449.82765 -116.87937)
		(width 0.1143)
		(layer "B.Cu")
		(net "P3E_CPU0_PE3_OCP_TXP<10>")
	)
	(segment
		(start 449.82765 -117.314218)
		(end 449.5165 -117.771418)
		(width 0.1143)
		(layer "B.Cu")
		(net "P3E_CPU0_PE3_OCP_TXP<10>")
	)
	(segment
		(start 446.584832 -120.499124)
		(end 447.103246 -122.903996)
		(width 0.1143)
		(layer "B.Cu")
		(net "P3E_CPU0_PE3_OCP_TXP<10>")
	)
	(segment
		(start 446.1637 -125.177804)
		(end 446.1637 -125.972824)
		(width 0.1143)
		(layer "B.Cu")
		(net "P3E_CPU0_PE3_OCP_TXP<10>")
	)
	(segment
		(start 410.083 -136.835134)
		(end 408.220164 -138.16838)
		(width 0.1143)
		(layer "In4.Cu")
		(net "P3E_CPU0_PE3_OCP_TXP<10>")
	)
	(segment
		(start 430.255172 -128.992122)
		(end 430.255426 -128.992122)
		(width 0.1143)
		(layer "In4.Cu")
		(net "P3E_CPU0_PE3_OCP_TXP<10>")
	)
	(segment
		(start 381.097028 -135.8392)
		(end 379.471936 -135.479282)
		(width 0.1143)
		(layer "In4.Cu")
		(net "P3E_CPU0_PE3_OCP_TXP<10>")
	)
	(segment
		(start 433.61991 -128.659128)
		(end 432.65979 -128.881632)
		(width 0.1143)
		(layer "In4.Cu")
		(net "P3E_CPU0_PE3_OCP_TXP<10>")
	)
	(segment
		(start 357.758492 -119.33428)
		(end 357.758492 -115.967764)
		(width 0.1143)
		(layer "In4.Cu")
		(net "P3E_CPU0_PE3_OCP_TXP<10>")
	)
	(segment
		(start 431.527712 -128.648714)
		(end 430.335182 -128.962658)
		(width 0.1143)
		(layer "In4.Cu")
		(net "P3E_CPU0_PE3_OCP_TXP<10>")
	)
	(segment
		(start 370.863368 -133.618478)
		(end 370.239544 -133.40842)
		(width 0.1143)
		(layer "In4.Cu")
		(net "P3E_CPU0_PE3_OCP_TXP<10>")
	)
	(segment
		(start 438.656984 -124.567188)
		(end 436.984394 -124.899674)
		(width 0.1143)
		(layer "In4.Cu")
		(net "P3E_CPU0_PE3_OCP_TXP<10>")
	)
	(segment
		(start 385.228084 -135.349742)
		(end 384.898392 -135.443976)
		(width 0.1143)
		(layer "In4.Cu")
		(net "P3E_CPU0_PE3_OCP_TXP<10>")
	)
	(segment
		(start 435.94147 -125.331982)
		(end 434.859938 -126.83363)
		(width 0.1143)
		(layer "In4.Cu")
		(net "P3E_CPU0_PE3_OCP_TXP<10>")
	)
	(segment
		(start 434.859938 -126.83363)
		(end 434.325268 -128.122934)
		(width 0.1143)
		(layer "In4.Cu")
		(net "P3E_CPU0_PE3_OCP_TXP<10>")
	)
	(segment
		(start 357.758492 -115.967764)
		(end 357.867712 -115.858544)
		(width 0.1143)
		(layer "In4.Cu")
		(net "P3E_CPU0_PE3_OCP_TXP<10>")
	)
	(segment
		(start 413.642048 -136.165082)
		(end 410.083 -136.835134)
		(width 0.1143)
		(layer "In4.Cu")
		(net "P3E_CPU0_PE3_OCP_TXP<10>")
	)
	(segment
		(start 357.305864 -126.711202)
		(end 356.5017 -124.716286)
		(width 0.1143)
		(layer "In4.Cu")
		(net "P3E_CPU0_PE3_OCP_TXP<10>")
	)
	(segment
		(start 422.763188 -131.576318)
		(end 420.756334 -133.110732)
		(width 0.1143)
		(layer "In4.Cu")
		(net "P3E_CPU0_PE3_OCP_TXP<10>")
	)
	(segment
		(start 420.756334 -133.110732)
		(end 418.951664 -135.942324)
		(width 0.1143)
		(layer "In4.Cu")
		(net "P3E_CPU0_PE3_OCP_TXP<10>")
	)
	(segment
		(start 382.417828 -135.42391)
		(end 381.097028 -135.8392)
		(width 0.1143)
		(layer "In4.Cu")
		(net "P3E_CPU0_PE3_OCP_TXP<10>")
	)
	(segment
		(start 385.341368 -135.145526)
		(end 385.228084 -135.349742)
		(width 0.1143)
		(layer "In4.Cu")
		(net "P3E_CPU0_PE3_OCP_TXP<10>")
	)
	(segment
		(start 356.738682 -121.301764)
		(end 357.7463 -119.357902)
		(width 0.1143)
		(layer "In4.Cu")
		(net "P3E_CPU0_PE3_OCP_TXP<10>")
	)
	(segment
		(start 378.141738 -135.763)
		(end 377.94565 -135.636)
		(width 0.1143)
		(layer "In4.Cu")
		(net "P3E_CPU0_PE3_OCP_TXP<10>")
	)
	(segment
		(start 436.984394 -124.899674)
		(end 435.94147 -125.331982)
		(width 0.1143)
		(layer "In4.Cu")
		(net "P3E_CPU0_PE3_OCP_TXP<10>")
	)
	(segment
		(start 375.711466 -136.281668)
		(end 375.145808 -136.133078)
		(width 0.1143)
		(layer "In4.Cu")
		(net "P3E_CPU0_PE3_OCP_TXP<10>")
	)
	(segment
		(start 377.94565 -135.636)
		(end 377.61037 -135.707628)
		(width 0.1143)
		(layer "In4.Cu")
		(net "P3E_CPU0_PE3_OCP_TXP<10>")
	)
	(segment
		(start 379.470666 -135.479282)
		(end 379.135386 -135.55091)
		(width 0.1143)
		(layer "In4.Cu")
		(net "P3E_CPU0_PE3_OCP_TXP<10>")
	)
	(segment
		(start 446.1891 -125.972824)
		(end 446.1891 -125.456442)
		(width 0.1143)
		(layer "In4.Cu")
		(net "P3E_CPU0_PE3_OCP_TXP<10>")
	)
	(segment
		(start 408.220164 -138.16838)
		(end 405.414734 -138.729212)
		(width 0.1143)
		(layer "In4.Cu")
		(net "P3E_CPU0_PE3_OCP_TXP<10>")
	)
	(segment
		(start 378.477018 -135.691372)
		(end 378.141738 -135.763)
		(width 0.1143)
		(layer "In4.Cu")
		(net "P3E_CPU0_PE3_OCP_TXP<10>")
	)
	(segment
		(start 356.5017 -124.716286)
		(end 357.008176 -122.529346)
		(width 0.1143)
		(layer "In4.Cu")
		(net "P3E_CPU0_PE3_OCP_TXP<10>")
	)
	(segment
		(start 425.637706 -130.735324)
		(end 422.763188 -131.576318)
		(width 0.1143)
		(layer "In4.Cu")
		(net "P3E_CPU0_PE3_OCP_TXP<10>")
	)
	(segment
		(start 384.364484 -135.424926)
		(end 384.2512 -135.629142)
		(width 0.1143)
		(layer "In4.Cu")
		(net "P3E_CPU0_PE3_OCP_TXP<10>")
	)
	(segment
		(start 405.414734 -138.729212)
		(end 386.539486 -134.974838)
		(width 0.1143)
		(layer "In4.Cu")
		(net "P3E_CPU0_PE3_OCP_TXP<10>")
	)
	(segment
		(start 385.67106 -135.051292)
		(end 385.341368 -135.145526)
		(width 0.1143)
		(layer "In4.Cu")
		(net "P3E_CPU0_PE3_OCP_TXP<10>")
	)
	(segment
		(start 378.939298 -135.42391)
		(end 378.604018 -135.495538)
		(width 0.1143)
		(layer "In4.Cu")
		(net "P3E_CPU0_PE3_OCP_TXP<10>")
	)
	(segment
		(start 428.369984 -130.629914)
		(end 427.30166 -131.085844)
		(width 0.1143)
		(layer "In4.Cu")
		(net "P3E_CPU0_PE3_OCP_TXP<10>")
	)
	(segment
		(start 357.7463 -119.357902)
		(end 357.758492 -119.33428)
		(width 0.1143)
		(layer "In4.Cu")
		(net "P3E_CPU0_PE3_OCP_TXP<10>")
	)
	(segment
		(start 446.67805 -126.087124)
		(end 446.3034 -126.087124)
		(width 0.1143)
		(layer "In4.Cu")
		(net "P3E_CPU0_PE3_OCP_TXP<10>")
	)
	(segment
		(start 430.335182 -128.962658)
		(end 430.318418 -128.967484)
		(width 0.1143)
		(layer "In4.Cu")
		(net "P3E_CPU0_PE3_OCP_TXP<10>")
	)
	(segment
		(start 430.255426 -128.992122)
		(end 429.108362 -129.602992)
		(width 0.1143)
		(layer "In4.Cu")
		(net "P3E_CPU0_PE3_OCP_TXP<10>")
	)
	(segment
		(start 446.1891 -125.456442)
		(end 445.299846 -124.567188)
		(width 0.1143)
		(layer "In4.Cu")
		(net "P3E_CPU0_PE3_OCP_TXP<10>")
	)
	(segment
		(start 377.48337 -135.903462)
		(end 375.711466 -136.281668)
		(width 0.1143)
		(layer "In4.Cu")
		(net "P3E_CPU0_PE3_OCP_TXP<10>")
	)
	(segment
		(start 384.898392 -135.443976)
		(end 384.694176 -135.330692)
		(width 0.1143)
		(layer "In4.Cu")
		(net "P3E_CPU0_PE3_OCP_TXP<10>")
	)
	(segment
		(start 378.604018 -135.495538)
		(end 378.477018 -135.691372)
		(width 0.1143)
		(layer "In4.Cu")
		(net "P3E_CPU0_PE3_OCP_TXP<10>")
	)
	(segment
		(start 385.875276 -135.16483)
		(end 385.67106 -135.051292)
		(width 0.1143)
		(layer "In4.Cu")
		(net "P3E_CPU0_PE3_OCP_TXP<10>")
	)
	(segment
		(start 373.877586 -134.507986)
		(end 372.641876 -133.552438)
		(width 0.1143)
		(layer "In4.Cu")
		(net "P3E_CPU0_PE3_OCP_TXP<10>")
	)
	(segment
		(start 427.30166 -131.085844)
		(end 425.637706 -130.735324)
		(width 0.1143)
		(layer "In4.Cu")
		(net "P3E_CPU0_PE3_OCP_TXP<10>")
	)
	(segment
		(start 417.955222 -136.50468)
		(end 415.937192 -136.925558)
		(width 0.1143)
		(layer "In4.Cu")
		(net "P3E_CPU0_PE3_OCP_TXP<10>")
	)
	(segment
		(start 383.921508 -135.723376)
		(end 382.417828 -135.42391)
		(width 0.1143)
		(layer "In4.Cu")
		(net "P3E_CPU0_PE3_OCP_TXP<10>")
	)
	(segment
		(start 384.694176 -135.330692)
		(end 384.364484 -135.424926)
		(width 0.1143)
		(layer "In4.Cu")
		(net "P3E_CPU0_PE3_OCP_TXP<10>")
	)
	(segment
		(start 361.45724 -129.332482)
		(end 357.305864 -126.711202)
		(width 0.1143)
		(layer "In4.Cu")
		(net "P3E_CPU0_PE3_OCP_TXP<10>")
	)
	(segment
		(start 377.61037 -135.707628)
		(end 377.48337 -135.903462)
		(width 0.1143)
		(layer "In4.Cu")
		(net "P3E_CPU0_PE3_OCP_TXP<10>")
	)
	(segment
		(start 379.470666 -135.479536)
		(end 379.470666 -135.479282)
		(width 0.1143)
		(layer "In4.Cu")
		(net "P3E_CPU0_PE3_OCP_TXP<10>")
	)
	(segment
		(start 430.318418 -128.967484)
		(end 430.285398 -128.97612)
		(width 0.1143)
		(layer "In4.Cu")
		(net "P3E_CPU0_PE3_OCP_TXP<10>")
	)
	(segment
		(start 379.135386 -135.55091)
		(end 378.939298 -135.42391)
		(width 0.1143)
		(layer "In4.Cu")
		(net "P3E_CPU0_PE3_OCP_TXP<10>")
	)
	(segment
		(start 384.2512 -135.629142)
		(end 383.921508 -135.723376)
		(width 0.1143)
		(layer "In4.Cu")
		(net "P3E_CPU0_PE3_OCP_TXP<10>")
	)
	(segment
		(start 358.14635 -115.858544)
		(end 358.26065 -115.972844)
		(width 0.1143)
		(layer "In4.Cu")
		(net "P3E_CPU0_PE3_OCP_TXP<10>")
	)
	(segment
		(start 370.239544 -133.40842)
		(end 368.480848 -132.112766)
		(width 0.1143)
		(layer "In4.Cu")
		(net "P3E_CPU0_PE3_OCP_TXP<10>")
	)
	(segment
		(start 418.951664 -135.942324)
		(end 417.955222 -136.50468)
		(width 0.1143)
		(layer "In4.Cu")
		(net "P3E_CPU0_PE3_OCP_TXP<10>")
	)
	(segment
		(start 386.539486 -134.974838)
		(end 385.875276 -135.16483)
		(width 0.1143)
		(layer "In4.Cu")
		(net "P3E_CPU0_PE3_OCP_TXP<10>")
	)
	(segment
		(start 372.641876 -133.552438)
		(end 371.972586 -133.381496)
		(width 0.1143)
		(layer "In4.Cu")
		(net "P3E_CPU0_PE3_OCP_TXP<10>")
	)
	(segment
		(start 429.108362 -129.602992)
		(end 428.369984 -130.629914)
		(width 0.1143)
		(layer "In4.Cu")
		(net "P3E_CPU0_PE3_OCP_TXP<10>")
	)
	(segment
		(start 375.145808 -136.133078)
		(end 374.769126 -135.87349)
		(width 0.1143)
		(layer "In4.Cu")
		(net "P3E_CPU0_PE3_OCP_TXP<10>")
	)
	(segment
		(start 434.325268 -128.122934)
		(end 433.61991 -128.659128)
		(width 0.1143)
		(layer "In4.Cu")
		(net "P3E_CPU0_PE3_OCP_TXP<10>")
	)
	(segment
		(start 357.867712 -115.858544)
		(end 358.14635 -115.858544)
		(width 0.1143)
		(layer "In4.Cu")
		(net "P3E_CPU0_PE3_OCP_TXP<10>")
	)
	(segment
		(start 446.3034 -126.087124)
		(end 446.1891 -125.972824)
		(width 0.1143)
		(layer "In4.Cu")
		(net "P3E_CPU0_PE3_OCP_TXP<10>")
	)
	(segment
		(start 445.299846 -124.567188)
		(end 438.656984 -124.567188)
		(width 0.1143)
		(layer "In4.Cu")
		(net "P3E_CPU0_PE3_OCP_TXP<10>")
	)
	(segment
		(start 357.008176 -122.529346)
		(end 356.738682 -121.301764)
		(width 0.1143)
		(layer "In4.Cu")
		(net "P3E_CPU0_PE3_OCP_TXP<10>")
	)
	(segment
		(start 368.480848 -132.112766)
		(end 361.45724 -129.332482)
		(width 0.1143)
		(layer "In4.Cu")
		(net "P3E_CPU0_PE3_OCP_TXP<10>")
	)
	(segment
		(start 371.972586 -133.381496)
		(end 370.863368 -133.618478)
		(width 0.1143)
		(layer "In4.Cu")
		(net "P3E_CPU0_PE3_OCP_TXP<10>")
	)
	(segment
		(start 374.769126 -135.87349)
		(end 373.877586 -134.507986)
		(width 0.1143)
		(layer "In4.Cu")
		(net "P3E_CPU0_PE3_OCP_TXP<10>")
	)
	(segment
		(start 432.65979 -128.881632)
		(end 431.527712 -128.648714)
		(width 0.1143)
		(layer "In4.Cu")
		(net "P3E_CPU0_PE3_OCP_TXP<10>")
	)
	(segment
		(start 358.26065 -115.972844)
		(end 358.26065 -116.220494)
		(width 0.1143)
		(layer "In4.Cu")
		(net "P3E_CPU0_PE3_OCP_TXP<10>")
	)
	(segment
		(start 415.937192 -136.925558)
		(end 413.642048 -136.165082)
		(width 0.1143)
		(layer "In4.Cu")
		(net "P3E_CPU0_PE3_OCP_TXP<10>")
	)
	(segment
		(start 379.471936 -135.479282)
		(end 379.470666 -135.479536)
		(width 0.1143)
		(layer "In4.Cu")
		(net "P3E_CPU0_PE3_OCP_TXP<10>")
	)
	(segment
		(start 430.285398 -128.97612)
		(end 430.255172 -128.992122)
		(width 0.1143)
		(layer "In4.Cu")
		(net "P3E_CPU0_PE3_OCP_TXP<10>")
	)
	(segment
		(start 308.946804 -95.027496)
		(end 308.803548 -95.027496)
		(width 0.0889)
		(layer "In11.Cu")
		(net "P3E_CPU0_PE3_OCP_TXP<10>")
	)
	(segment
		(start 308.677818 -94.75851)
		(end 308.552342 -94.633034)
		(width 0.0889)
		(layer "In11.Cu")
		(net "P3E_CPU0_PE3_OCP_TXP<10>")
	)
	(segment
		(start 307.769768 -94.72803)
		(end 307.591968 -94.72803)
		(width 0.0889)
		(layer "In11.Cu")
		(net "P3E_CPU0_PE3_OCP_TXP<10>")
	)
	(segment
		(start 308.552342 -94.633034)
		(end 308.41823 -94.633034)
		(width 0.0889)
		(layer "In11.Cu")
		(net "P3E_CPU0_PE3_OCP_TXP<10>")
	)
	(segment
		(start 354.770944 -113.157)
		(end 346.323412 -113.157)
		(width 0.1143)
		(layer "In11.Cu")
		(net "P3E_CPU0_PE3_OCP_TXP<10>")
	)
	(segment
		(start 358.26065 -116.068348)
		(end 358.029002 -115.8367)
		(width 0.1143)
		(layer "In11.Cu")
		(net "P3E_CPU0_PE3_OCP_TXP<10>")
	)
	(segment
		(start 307.496972 -94.633034)
		(end 306.509166 -94.633034)
		(width 0.0889)
		(layer "In11.Cu")
		(net "P3E_CPU0_PE3_OCP_TXP<10>")
	)
	(segment
		(start 308.803548 -95.027496)
		(end 308.677818 -94.901766)
		(width 0.0889)
		(layer "In11.Cu")
		(net "P3E_CPU0_PE3_OCP_TXP<10>")
	)
	(segment
		(start 328.623676 -109.778546)
		(end 328.00544 -108.387134)
		(width 0.1143)
		(layer "In11.Cu")
		(net "P3E_CPU0_PE3_OCP_TXP<10>")
	)
	(segment
		(start 304.041556 -95.328486)
		(end 304.03673 -95.337122)
		(width 0.0889)
		(layer "In11.Cu")
		(net "P3E_CPU0_PE3_OCP_TXP<10>")
	)
	(segment
		(start 305.65217 -95.49003)
		(end 305.518312 -95.623888)
		(width 0.0889)
		(layer "In11.Cu")
		(net "P3E_CPU0_PE3_OCP_TXP<10>")
	)
	(segment
		(start 358.26065 -116.220494)
		(end 358.26065 -116.068348)
		(width 0.1143)
		(layer "In11.Cu")
		(net "P3E_CPU0_PE3_OCP_TXP<10>")
	)
	(segment
		(start 309.19801 -95.421958)
		(end 309.07228 -95.296228)
		(width 0.0889)
		(layer "In11.Cu")
		(net "P3E_CPU0_PE3_OCP_TXP<10>")
	)
	(segment
		(start 307.864764 -94.633034)
		(end 307.769768 -94.72803)
		(width 0.0889)
		(layer "In11.Cu")
		(net "P3E_CPU0_PE3_OCP_TXP<10>")
	)
	(segment
		(start 309.99684 -96.077532)
		(end 309.735728 -95.81642)
		(width 0.0889)
		(layer "In11.Cu")
		(net "P3E_CPU0_PE3_OCP_TXP<10>")
	)
	(segment
		(start 311.750202 -98.67265)
		(end 311.001664 -97.153984)
		(width 0.1143)
		(layer "In11.Cu")
		(net "P3E_CPU0_PE3_OCP_TXP<10>")
	)
	(segment
		(start 305.901852 -95.240348)
		(end 305.901852 -95.3643)
		(width 0.0889)
		(layer "In11.Cu")
		(net "P3E_CPU0_PE3_OCP_TXP<10>")
	)
	(segment
		(start 357.688642 -115.8367)
		(end 357.3907 -115.538758)
		(width 0.1143)
		(layer "In11.Cu")
		(net "P3E_CPU0_PE3_OCP_TXP<10>")
	)
	(segment
		(start 308.677818 -94.901766)
		(end 308.677818 -94.75851)
		(width 0.0889)
		(layer "In11.Cu")
		(net "P3E_CPU0_PE3_OCP_TXP<10>")
	)
	(segment
		(start 304.09515 -95.697548)
		(end 304.388266 -95.528384)
		(width 0.0889)
		(layer "In11.Cu")
		(net "P3E_CPU0_PE3_OCP_TXP<10>")
	)
	(segment
		(start 305.776122 -95.49003)
		(end 305.65217 -95.49003)
		(width 0.0889)
		(layer "In11.Cu")
		(net "P3E_CPU0_PE3_OCP_TXP<10>")
	)
	(segment
		(start 309.99684 -96.14916)
		(end 309.99684 -96.077532)
		(width 0.0889)
		(layer "In11.Cu")
		(net "P3E_CPU0_PE3_OCP_TXP<10>")
	)
	(segment
		(start 305.518312 -95.623888)
		(end 305.060096 -95.623888)
		(width 0.0889)
		(layer "In11.Cu")
		(net "P3E_CPU0_PE3_OCP_TXP<10>")
	)
	(segment
		(start 309.592472 -95.81642)
		(end 309.466742 -95.69069)
		(width 0.0889)
		(layer "In11.Cu")
		(net "P3E_CPU0_PE3_OCP_TXP<10>")
	)
	(segment
		(start 310.004968 -96.157288)
		(end 309.99684 -96.14916)
		(width 0.0889)
		(layer "In11.Cu")
		(net "P3E_CPU0_PE3_OCP_TXP<10>")
	)
	(segment
		(start 305.901852 -95.3643)
		(end 305.776122 -95.49003)
		(width 0.0889)
		(layer "In11.Cu")
		(net "P3E_CPU0_PE3_OCP_TXP<10>")
	)
	(segment
		(start 306.29352 -94.968568)
		(end 306.16779 -95.094298)
		(width 0.0889)
		(layer "In11.Cu")
		(net "P3E_CPU0_PE3_OCP_TXP<10>")
	)
	(segment
		(start 306.509166 -94.633034)
		(end 306.29352 -94.84868)
		(width 0.0889)
		(layer "In11.Cu")
		(net "P3E_CPU0_PE3_OCP_TXP<10>")
	)
	(segment
		(start 307.591968 -94.72803)
		(end 307.496972 -94.633034)
		(width 0.0889)
		(layer "In11.Cu")
		(net "P3E_CPU0_PE3_OCP_TXP<10>")
	)
	(segment
		(start 309.341266 -95.421958)
		(end 309.19801 -95.421958)
		(width 0.0889)
		(layer "In11.Cu")
		(net "P3E_CPU0_PE3_OCP_TXP<10>")
	)
	(segment
		(start 308.14772 -94.725744)
		(end 308.05501 -94.633034)
		(width 0.0889)
		(layer "In11.Cu")
		(net "P3E_CPU0_PE3_OCP_TXP<10>")
	)
	(segment
		(start 355.50094 -113.886996)
		(end 354.770944 -113.157)
		(width 0.1143)
		(layer "In11.Cu")
		(net "P3E_CPU0_PE3_OCP_TXP<10>")
	)
	(segment
		(start 306.29352 -94.84868)
		(end 306.29352 -94.968568)
		(width 0.0889)
		(layer "In11.Cu")
		(net "P3E_CPU0_PE3_OCP_TXP<10>")
	)
	(segment
		(start 304.01641 -95.676212)
		(end 304.09515 -95.697548)
		(width 0.0889)
		(layer "In11.Cu")
		(net "P3E_CPU0_PE3_OCP_TXP<10>")
	)
	(segment
		(start 309.466742 -95.69069)
		(end 309.466742 -95.547434)
		(width 0.0889)
		(layer "In11.Cu")
		(net "P3E_CPU0_PE3_OCP_TXP<10>")
	)
	(segment
		(start 308.32552 -94.725744)
		(end 308.14772 -94.725744)
		(width 0.0889)
		(layer "In11.Cu")
		(net "P3E_CPU0_PE3_OCP_TXP<10>")
	)
	(segment
		(start 328.00544 -108.387134)
		(end 315.3918 -103.156766)
		(width 0.1143)
		(layer "In11.Cu")
		(net "P3E_CPU0_PE3_OCP_TXP<10>")
	)
	(segment
		(start 309.07228 -95.296228)
		(end 309.07228 -95.152972)
		(width 0.0889)
		(layer "In11.Cu")
		(net "P3E_CPU0_PE3_OCP_TXP<10>")
	)
	(segment
		(start 331.763878 -111.87938)
		(end 328.623676 -109.778546)
		(width 0.1143)
		(layer "In11.Cu")
		(net "P3E_CPU0_PE3_OCP_TXP<10>")
	)
	(segment
		(start 315.3918 -103.156766)
		(end 311.750202 -98.67265)
		(width 0.1143)
		(layer "In11.Cu")
		(net "P3E_CPU0_PE3_OCP_TXP<10>")
	)
	(segment
		(start 308.41823 -94.633034)
		(end 308.32552 -94.725744)
		(width 0.0889)
		(layer "In11.Cu")
		(net "P3E_CPU0_PE3_OCP_TXP<10>")
	)
	(segment
		(start 358.029002 -115.8367)
		(end 357.688642 -115.8367)
		(width 0.1143)
		(layer "In11.Cu")
		(net "P3E_CPU0_PE3_OCP_TXP<10>")
	)
	(segment
		(start 309.466742 -95.547434)
		(end 309.341266 -95.421958)
		(width 0.0889)
		(layer "In11.Cu")
		(net "P3E_CPU0_PE3_OCP_TXP<10>")
	)
	(segment
		(start 309.07228 -95.152972)
		(end 308.946804 -95.027496)
		(width 0.0889)
		(layer "In11.Cu")
		(net "P3E_CPU0_PE3_OCP_TXP<10>")
	)
	(segment
		(start 304.4063 -95.128588)
		(end 304.370232 -95.128588)
		(width 0.0889)
		(layer "In11.Cu")
		(net "P3E_CPU0_PE3_OCP_TXP<10>")
	)
	(segment
		(start 309.735728 -95.81642)
		(end 309.592472 -95.81642)
		(width 0.0889)
		(layer "In11.Cu")
		(net "P3E_CPU0_PE3_OCP_TXP<10>")
	)
	(segment
		(start 357.3907 -115.538758)
		(end 357.3907 -114.927126)
		(width 0.1143)
		(layer "In11.Cu")
		(net "P3E_CPU0_PE3_OCP_TXP<10>")
	)
	(segment
		(start 344.412062 -111.87938)
		(end 331.763878 -111.87938)
		(width 0.1143)
		(layer "In11.Cu")
		(net "P3E_CPU0_PE3_OCP_TXP<10>")
	)
	(segment
		(start 357.3907 -114.927126)
		(end 356.951788 -114.488214)
		(width 0.1143)
		(layer "In11.Cu")
		(net "P3E_CPU0_PE3_OCP_TXP<10>")
	)
	(segment
		(start 306.16779 -95.094298)
		(end 306.047902 -95.094298)
		(width 0.0889)
		(layer "In11.Cu")
		(net "P3E_CPU0_PE3_OCP_TXP<10>")
	)
	(segment
		(start 306.047902 -95.094298)
		(end 305.901852 -95.240348)
		(width 0.0889)
		(layer "In11.Cu")
		(net "P3E_CPU0_PE3_OCP_TXP<10>")
	)
	(segment
		(start 311.001664 -97.153984)
		(end 310.004968 -96.157288)
		(width 0.1143)
		(layer "In11.Cu")
		(net "P3E_CPU0_PE3_OCP_TXP<10>")
	)
	(segment
		(start 346.323412 -113.157)
		(end 344.412062 -111.87938)
		(width 0.1143)
		(layer "In11.Cu")
		(net "P3E_CPU0_PE3_OCP_TXP<10>")
	)
	(segment
		(start 308.05501 -94.633034)
		(end 307.864764 -94.633034)
		(width 0.0889)
		(layer "In11.Cu")
		(net "P3E_CPU0_PE3_OCP_TXP<10>")
	)
	(segment
		(start 356.951788 -114.488214)
		(end 355.50094 -113.886996)
		(width 0.1143)
		(layer "In11.Cu")
		(net "P3E_CPU0_PE3_OCP_TXP<10>")
	)
	(arc
		(start 304.03673 -95.337122)
		(mid 303.988817 -95.504407)
		(end 304.01641 -95.676212)
		(width 0.0889)
		(layer "In11.Cu")
		(net "P3E_CPU0_PE3_OCP_TXP<10>")
	)
	(arc
		(start 305.03368 -95.605092)
		(mid 304.863491 -95.489287)
		(end 304.734976 -95.328486)
		(width 0.0889)
		(layer "In11.Cu")
		(net "P3E_CPU0_PE3_OCP_TXP<10>")
	)
	(arc
		(start 304.370232 -95.128588)
		(mid 304.180303 -95.186458)
		(end 304.041556 -95.328486)
		(width 0.0889)
		(layer "In11.Cu")
		(net "P3E_CPU0_PE3_OCP_TXP<10>")
	)
	(arc
		(start 304.734976 -95.328486)
		(mid 304.596232 -95.186453)
		(end 304.4063 -95.128588)
		(width 0.0889)
		(layer "In11.Cu")
		(net "P3E_CPU0_PE3_OCP_TXP<10>")
	)
	(arc
		(start 305.060096 -95.623888)
		(mid 305.046775 -95.614649)
		(end 305.03368 -95.605092)
		(width 0.0889)
		(layer "In11.Cu")
		(net "P3E_CPU0_PE3_OCP_TXP<10>")
	)
	(segment
		(start 296.09034 -101.967538)
		(end 296.66184 -101.967538)
		(width 0.1143)
		(layer "F.Cu")
		(net "P3E_CPU0_PE3_OCP_TXP<0>")
	)
	(via
		(at 462.70799 -53.888894)
		(size 0.508)
		(drill 0.254)
		(layers "F.Cu" "B.Cu")
		(net "P3E_CPU0_PE3_OCP_TXP<0>")
	)
	(via
		(at 296.66184 -101.967538)
		(size 0.508)
		(drill 0.254)
		(layers "F.Cu" "B.Cu")
		(net "P3E_CPU0_PE3_OCP_TXP<0>")
	)
	(segment
		(start 462.8134 -52.837334)
		(end 462.9277 -52.951634)
		(width 0.1143)
		(layer "B.Cu")
		(net "P3E_CPU0_PE3_OCP_TXP<0>")
	)
	(segment
		(start 462.8134 -52.432458)
		(end 462.8134 -52.837334)
		(width 0.1143)
		(layer "B.Cu")
		(net "P3E_CPU0_PE3_OCP_TXP<0>")
	)
	(segment
		(start 463.08645 -52.951634)
		(end 463.20075 -53.065934)
		(width 0.1143)
		(layer "B.Cu")
		(net "P3E_CPU0_PE3_OCP_TXP<0>")
	)
	(segment
		(start 463.20075 -53.396134)
		(end 462.70799 -53.888894)
		(width 0.1143)
		(layer "B.Cu")
		(net "P3E_CPU0_PE3_OCP_TXP<0>")
	)
	(segment
		(start 463.20075 -53.065934)
		(end 463.20075 -53.396134)
		(width 0.1143)
		(layer "B.Cu")
		(net "P3E_CPU0_PE3_OCP_TXP<0>")
	)
	(segment
		(start 462.9277 -52.951634)
		(end 463.08645 -52.951634)
		(width 0.1143)
		(layer "B.Cu")
		(net "P3E_CPU0_PE3_OCP_TXP<0>")
	)
	(segment
		(start 299.879258 -104.264968)
		(end 300.749716 -104.264968)
		(width 0.0889)
		(layer "In4.Cu")
		(net "P3E_CPU0_PE3_OCP_TXP<0>")
	)
	(segment
		(start 414.39846 -63.60414)
		(end 415.0106 -62.992)
		(width 0.1143)
		(layer "In4.Cu")
		(net "P3E_CPU0_PE3_OCP_TXP<0>")
	)
	(segment
		(start 406.92197 -61.147706)
		(end 408.065224 -62.29096)
		(width 0.1143)
		(layer "In4.Cu")
		(net "P3E_CPU0_PE3_OCP_TXP<0>")
	)
	(segment
		(start 461.97393 -57.199022)
		(end 462.22158 -57.199022)
		(width 0.1143)
		(layer "In4.Cu")
		(net "P3E_CPU0_PE3_OCP_TXP<0>")
	)
	(segment
		(start 417.132262 -61.74359)
		(end 418.969444 -61.74359)
		(width 0.1143)
		(layer "In4.Cu")
		(net "P3E_CPU0_PE3_OCP_TXP<0>")
	)
	(segment
		(start 460.99857 -58.422032)
		(end 460.99857 -58.174128)
		(width 0.1143)
		(layer "In4.Cu")
		(net "P3E_CPU0_PE3_OCP_TXP<0>")
	)
	(segment
		(start 428.140368 -59.842908)
		(end 428.842424 -60.544964)
		(width 0.1143)
		(layer "In4.Cu")
		(net "P3E_CPU0_PE3_OCP_TXP<0>")
	)
	(segment
		(start 300.822614 -104.214168)
		(end 301.933864 -104.214168)
		(width 0.1143)
		(layer "In4.Cu")
		(net "P3E_CPU0_PE3_OCP_TXP<0>")
	)
	(segment
		(start 421.644064 -60.098432)
		(end 425.826682 -60.098432)
		(width 0.1143)
		(layer "In4.Cu")
		(net "P3E_CPU0_PE3_OCP_TXP<0>")
	)
	(segment
		(start 415.0106 -62.992)
		(end 416.278568 -62.992)
		(width 0.1143)
		(layer "In4.Cu")
		(net "P3E_CPU0_PE3_OCP_TXP<0>")
	)
	(segment
		(start 303.286668 -104.775)
		(end 305.79187 -104.775)
		(width 0.1143)
		(layer "In4.Cu")
		(net "P3E_CPU0_PE3_OCP_TXP<0>")
	)
	(segment
		(start 328.908156 -76.225146)
		(end 328.936858 -76.172822)
		(width 0.1143)
		(layer "In4.Cu")
		(net "P3E_CPU0_PE3_OCP_TXP<0>")
	)
	(segment
		(start 297.17365 -102.662482)
		(end 297.174158 -102.663498)
		(width 0.0889)
		(layer "In4.Cu")
		(net "P3E_CPU0_PE3_OCP_TXP<0>")
	)
	(segment
		(start 296.66184 -102.305612)
		(end 296.726864 -102.370636)
		(width 0.0889)
		(layer "In4.Cu")
		(net "P3E_CPU0_PE3_OCP_TXP<0>")
	)
	(segment
		(start 372.6434 -58.0644)
		(end 373.640096 -59.061096)
		(width 0.1143)
		(layer "In4.Cu")
		(net "P3E_CPU0_PE3_OCP_TXP<0>")
	)
	(segment
		(start 347.089476 -66.60388)
		(end 348.617286 -66.306954)
		(width 0.1143)
		(layer "In4.Cu")
		(net "P3E_CPU0_PE3_OCP_TXP<0>")
	)
	(segment
		(start 462.46415 -56.956452)
		(end 462.46415 -56.708548)
		(width 0.1143)
		(layer "In4.Cu")
		(net "P3E_CPU0_PE3_OCP_TXP<0>")
	)
	(segment
		(start 297.17619 -102.6668)
		(end 297.246548 -102.788212)
		(width 0.0889)
		(layer "In4.Cu")
		(net "P3E_CPU0_PE3_OCP_TXP<0>")
	)
	(segment
		(start 412.37662 -63.60414)
		(end 414.39846 -63.60414)
		(width 0.1143)
		(layer "In4.Cu")
		(net "P3E_CPU0_PE3_OCP_TXP<0>")
	)
	(segment
		(start 391.1092 -58.5597)
		(end 399.201386 -58.5597)
		(width 0.1143)
		(layer "In4.Cu")
		(net "P3E_CPU0_PE3_OCP_TXP<0>")
	)
	(segment
		(start 401.789392 -61.147706)
		(end 406.92197 -61.147706)
		(width 0.1143)
		(layer "In4.Cu")
		(net "P3E_CPU0_PE3_OCP_TXP<0>")
	)
	(segment
		(start 357.241602 -67.029076)
		(end 357.849424 -66.421254)
		(width 0.1143)
		(layer "In4.Cu")
		(net "P3E_CPU0_PE3_OCP_TXP<0>")
	)
	(segment
		(start 345.85275 -66.316098)
		(end 347.089476 -66.60388)
		(width 0.1143)
		(layer "In4.Cu")
		(net "P3E_CPU0_PE3_OCP_TXP<0>")
	)
	(segment
		(start 332.146656 -71.505318)
		(end 338.453476 -67.35445)
		(width 0.1143)
		(layer "In4.Cu")
		(net "P3E_CPU0_PE3_OCP_TXP<0>")
	)
	(segment
		(start 425.826682 -60.098432)
		(end 426.082206 -59.842908)
		(width 0.1143)
		(layer "In4.Cu")
		(net "P3E_CPU0_PE3_OCP_TXP<0>")
	)
	(segment
		(start 456.490832 -61.579506)
		(end 458.51572 -59.554618)
		(width 0.1143)
		(layer "In4.Cu")
		(net "P3E_CPU0_PE3_OCP_TXP<0>")
	)
	(segment
		(start 416.278568 -62.992)
		(end 416.597338 -62.67323)
		(width 0.1143)
		(layer "In4.Cu")
		(net "P3E_CPU0_PE3_OCP_TXP<0>")
	)
	(segment
		(start 461.73136 -57.689242)
		(end 461.73136 -57.441338)
		(width 0.1143)
		(layer "In4.Cu")
		(net "P3E_CPU0_PE3_OCP_TXP<0>")
	)
	(segment
		(start 460.99857 -58.174128)
		(end 461.24114 -57.931812)
		(width 0.1143)
		(layer "In4.Cu")
		(net "P3E_CPU0_PE3_OCP_TXP<0>")
	)
	(segment
		(start 426.082206 -59.842908)
		(end 428.140368 -59.842908)
		(width 0.1143)
		(layer "In4.Cu")
		(net "P3E_CPU0_PE3_OCP_TXP<0>")
	)
	(segment
		(start 301.933864 -104.214168)
		(end 303.286668 -104.775)
		(width 0.1143)
		(layer "In4.Cu")
		(net "P3E_CPU0_PE3_OCP_TXP<0>")
	)
	(segment
		(start 463.08264 -53.888894)
		(end 462.70799 -53.888894)
		(width 0.1143)
		(layer "In4.Cu")
		(net "P3E_CPU0_PE3_OCP_TXP<0>")
	)
	(segment
		(start 463.19694 -56.223662)
		(end 463.19694 -54.003194)
		(width 0.1143)
		(layer "In4.Cu")
		(net "P3E_CPU0_PE3_OCP_TXP<0>")
	)
	(segment
		(start 462.22158 -57.199022)
		(end 462.46415 -56.956452)
		(width 0.1143)
		(layer "In4.Cu")
		(net "P3E_CPU0_PE3_OCP_TXP<0>")
	)
	(segment
		(start 382.72085 -58.741564)
		(end 390.927336 -58.741564)
		(width 0.1143)
		(layer "In4.Cu")
		(net "P3E_CPU0_PE3_OCP_TXP<0>")
	)
	(segment
		(start 307.647848 -104.00665)
		(end 324.109842 -87.551768)
		(width 0.1143)
		(layer "In4.Cu")
		(net "P3E_CPU0_PE3_OCP_TXP<0>")
	)
	(segment
		(start 459.865984 -59.554618)
		(end 460.99857 -58.422032)
		(width 0.1143)
		(layer "In4.Cu")
		(net "P3E_CPU0_PE3_OCP_TXP<0>")
	)
	(segment
		(start 373.640096 -59.061096)
		(end 379.658118 -59.061096)
		(width 0.1143)
		(layer "In4.Cu")
		(net "P3E_CPU0_PE3_OCP_TXP<0>")
	)
	(segment
		(start 408.065224 -62.29096)
		(end 411.06344 -62.29096)
		(width 0.1143)
		(layer "In4.Cu")
		(net "P3E_CPU0_PE3_OCP_TXP<0>")
	)
	(segment
		(start 338.453476 -67.35445)
		(end 343.139522 -66.442844)
		(width 0.1143)
		(layer "In4.Cu")
		(net "P3E_CPU0_PE3_OCP_TXP<0>")
	)
	(segment
		(start 366.296702 -58.978038)
		(end 369.596162 -58.978038)
		(width 0.1143)
		(layer "In4.Cu")
		(net "P3E_CPU0_PE3_OCP_TXP<0>")
	)
	(segment
		(start 350.761554 -66.432176)
		(end 355.49459 -67.37858)
		(width 0.1143)
		(layer "In4.Cu")
		(net "P3E_CPU0_PE3_OCP_TXP<0>")
	)
	(segment
		(start 381.518668 -59.943746)
		(end 382.72085 -58.741564)
		(width 0.1143)
		(layer "In4.Cu")
		(net "P3E_CPU0_PE3_OCP_TXP<0>")
	)
	(segment
		(start 430.5046 -63.36665)
		(end 432.852576 -63.36665)
		(width 0.1143)
		(layer "In4.Cu")
		(net "P3E_CPU0_PE3_OCP_TXP<0>")
	)
	(segment
		(start 305.79187 -104.775)
		(end 307.647848 -104.00665)
		(width 0.1143)
		(layer "In4.Cu")
		(net "P3E_CPU0_PE3_OCP_TXP<0>")
	)
	(segment
		(start 379.658118 -59.061096)
		(end 380.540768 -59.943746)
		(width 0.1143)
		(layer "In4.Cu")
		(net "P3E_CPU0_PE3_OCP_TXP<0>")
	)
	(segment
		(start 421.467026 -60.27547)
		(end 421.644064 -60.098432)
		(width 0.1143)
		(layer "In4.Cu")
		(net "P3E_CPU0_PE3_OCP_TXP<0>")
	)
	(segment
		(start 349.884746 -66.603372)
		(end 350.761554 -66.432176)
		(width 0.1143)
		(layer "In4.Cu")
		(net "P3E_CPU0_PE3_OCP_TXP<0>")
	)
	(segment
		(start 358.853486 -66.421254)
		(end 366.296702 -58.978038)
		(width 0.1143)
		(layer "In4.Cu")
		(net "P3E_CPU0_PE3_OCP_TXP<0>")
	)
	(segment
		(start 462.70672 -56.466232)
		(end 462.95437 -56.466232)
		(width 0.1143)
		(layer "In4.Cu")
		(net "P3E_CPU0_PE3_OCP_TXP<0>")
	)
	(segment
		(start 428.842424 -61.704474)
		(end 430.5046 -63.36665)
		(width 0.1143)
		(layer "In4.Cu")
		(net "P3E_CPU0_PE3_OCP_TXP<0>")
	)
	(segment
		(start 462.95437 -56.466232)
		(end 463.19694 -56.223662)
		(width 0.1143)
		(layer "In4.Cu")
		(net "P3E_CPU0_PE3_OCP_TXP<0>")
	)
	(segment
		(start 463.19694 -54.003194)
		(end 463.08264 -53.888894)
		(width 0.1143)
		(layer "In4.Cu")
		(net "P3E_CPU0_PE3_OCP_TXP<0>")
	)
	(segment
		(start 369.596162 -58.978038)
		(end 370.5098 -58.0644)
		(width 0.1143)
		(layer "In4.Cu")
		(net "P3E_CPU0_PE3_OCP_TXP<0>")
	)
	(segment
		(start 428.842424 -60.544964)
		(end 428.842424 -61.704474)
		(width 0.1143)
		(layer "In4.Cu")
		(net "P3E_CPU0_PE3_OCP_TXP<0>")
	)
	(segment
		(start 390.927336 -58.741564)
		(end 391.1092 -58.5597)
		(width 0.1143)
		(layer "In4.Cu")
		(net "P3E_CPU0_PE3_OCP_TXP<0>")
	)
	(segment
		(start 399.201386 -58.5597)
		(end 401.789392 -61.147706)
		(width 0.1143)
		(layer "In4.Cu")
		(net "P3E_CPU0_PE3_OCP_TXP<0>")
	)
	(segment
		(start 434.63972 -61.579506)
		(end 456.490832 -61.579506)
		(width 0.1143)
		(layer "In4.Cu")
		(net "P3E_CPU0_PE3_OCP_TXP<0>")
	)
	(segment
		(start 416.597338 -62.278514)
		(end 417.132262 -61.74359)
		(width 0.1143)
		(layer "In4.Cu")
		(net "P3E_CPU0_PE3_OCP_TXP<0>")
	)
	(segment
		(start 343.139522 -66.442844)
		(end 344.078306 -66.661538)
		(width 0.1143)
		(layer "In4.Cu")
		(net "P3E_CPU0_PE3_OCP_TXP<0>")
	)
	(segment
		(start 461.24114 -57.931812)
		(end 461.48879 -57.931812)
		(width 0.1143)
		(layer "In4.Cu")
		(net "P3E_CPU0_PE3_OCP_TXP<0>")
	)
	(segment
		(start 416.597338 -62.67323)
		(end 416.597338 -62.278514)
		(width 0.1143)
		(layer "In4.Cu")
		(net "P3E_CPU0_PE3_OCP_TXP<0>")
	)
	(segment
		(start 418.969444 -61.74359)
		(end 420.437564 -60.27547)
		(width 0.1143)
		(layer "In4.Cu")
		(net "P3E_CPU0_PE3_OCP_TXP<0>")
	)
	(segment
		(start 461.73136 -57.441338)
		(end 461.97393 -57.199022)
		(width 0.1143)
		(layer "In4.Cu")
		(net "P3E_CPU0_PE3_OCP_TXP<0>")
	)
	(segment
		(start 462.46415 -56.708548)
		(end 462.70672 -56.466232)
		(width 0.1143)
		(layer "In4.Cu")
		(net "P3E_CPU0_PE3_OCP_TXP<0>")
	)
	(segment
		(start 411.06344 -62.29096)
		(end 412.37662 -63.60414)
		(width 0.1143)
		(layer "In4.Cu")
		(net "P3E_CPU0_PE3_OCP_TXP<0>")
	)
	(segment
		(start 461.48879 -57.931812)
		(end 461.73136 -57.689242)
		(width 0.1143)
		(layer "In4.Cu")
		(net "P3E_CPU0_PE3_OCP_TXP<0>")
	)
	(segment
		(start 458.51572 -59.554618)
		(end 459.865984 -59.554618)
		(width 0.1143)
		(layer "In4.Cu")
		(net "P3E_CPU0_PE3_OCP_TXP<0>")
	)
	(segment
		(start 296.66184 -101.967538)
		(end 296.66184 -102.305612)
		(width 0.0889)
		(layer "In4.Cu")
		(net "P3E_CPU0_PE3_OCP_TXP<0>")
	)
	(segment
		(start 297.175682 -102.666038)
		(end 297.17619 -102.6668)
		(width 0.0889)
		(layer "In4.Cu")
		(net "P3E_CPU0_PE3_OCP_TXP<0>")
	)
	(segment
		(start 357.849424 -66.421254)
		(end 358.853486 -66.421254)
		(width 0.1143)
		(layer "In4.Cu")
		(net "P3E_CPU0_PE3_OCP_TXP<0>")
	)
	(segment
		(start 300.749716 -104.264968)
		(end 300.800516 -104.214168)
		(width 0.0889)
		(layer "In4.Cu")
		(net "P3E_CPU0_PE3_OCP_TXP<0>")
	)
	(segment
		(start 324.109842 -87.551768)
		(end 328.908156 -76.225146)
		(width 0.1143)
		(layer "In4.Cu")
		(net "P3E_CPU0_PE3_OCP_TXP<0>")
	)
	(segment
		(start 300.800516 -104.214168)
		(end 300.822614 -104.214168)
		(width 0.0889)
		(layer "In4.Cu")
		(net "P3E_CPU0_PE3_OCP_TXP<0>")
	)
	(segment
		(start 328.936858 -76.172822)
		(end 332.146656 -71.505318)
		(width 0.1143)
		(layer "In4.Cu")
		(net "P3E_CPU0_PE3_OCP_TXP<0>")
	)
	(segment
		(start 297.246548 -102.788212)
		(end 298.083732 -103.521256)
		(width 0.0889)
		(layer "In4.Cu")
		(net "P3E_CPU0_PE3_OCP_TXP<0>")
	)
	(segment
		(start 380.540768 -59.943746)
		(end 381.518668 -59.943746)
		(width 0.1143)
		(layer "In4.Cu")
		(net "P3E_CPU0_PE3_OCP_TXP<0>")
	)
	(segment
		(start 297.174158 -102.663498)
		(end 297.175682 -102.666038)
		(width 0.0889)
		(layer "In4.Cu")
		(net "P3E_CPU0_PE3_OCP_TXP<0>")
	)
	(segment
		(start 420.437564 -60.27547)
		(end 421.467026 -60.27547)
		(width 0.1143)
		(layer "In4.Cu")
		(net "P3E_CPU0_PE3_OCP_TXP<0>")
	)
	(segment
		(start 432.852576 -63.36665)
		(end 434.63972 -61.579506)
		(width 0.1143)
		(layer "In4.Cu")
		(net "P3E_CPU0_PE3_OCP_TXP<0>")
	)
	(segment
		(start 355.49459 -67.37858)
		(end 357.241602 -67.029076)
		(width 0.1143)
		(layer "In4.Cu")
		(net "P3E_CPU0_PE3_OCP_TXP<0>")
	)
	(segment
		(start 344.078306 -66.661538)
		(end 345.85275 -66.316098)
		(width 0.1143)
		(layer "In4.Cu")
		(net "P3E_CPU0_PE3_OCP_TXP<0>")
	)
	(segment
		(start 348.617286 -66.306954)
		(end 349.884746 -66.603372)
		(width 0.1143)
		(layer "In4.Cu")
		(net "P3E_CPU0_PE3_OCP_TXP<0>")
	)
	(segment
		(start 298.083732 -103.521256)
		(end 299.879258 -104.264968)
		(width 0.0889)
		(layer "In4.Cu")
		(net "P3E_CPU0_PE3_OCP_TXP<0>")
	)
	(segment
		(start 370.5098 -58.0644)
		(end 372.6434 -58.0644)
		(width 0.1143)
		(layer "In4.Cu")
		(net "P3E_CPU0_PE3_OCP_TXP<0>")
	)
	(arc
		(start 296.726864 -102.370636)
		(mid 296.985076 -102.463259)
		(end 297.17365 -102.662482)
		(width 0.0889)
		(layer "In4.Cu")
		(net "P3E_CPU0_PE3_OCP_TXP<0>")
	)
	(segment
		(start 303.816766 -97.509584)
		(end 304.388266 -97.509584)
		(width 0.1143)
		(layer "F.Cu")
		(net "P3E_CPU0_PE3_OCP_TXN<9>")
	)
	(via
		(at 356.30485 -115.204494)
		(size 0.508)
		(drill 0.254)
		(layers "F.Cu" "B.Cu")
		(net "P3E_CPU0_PE3_OCP_TXN<9>")
	)
	(via
		(at 304.388266 -97.509584)
		(size 0.508)
		(drill 0.254)
		(layers "F.Cu" "B.Cu")
		(net "P3E_CPU0_PE3_OCP_TXN<9>")
	)
	(via
		(at 442.75375 -126.0856)
		(size 0.508)
		(drill 0.254)
		(layers "F.Cu" "B.Cu")
		(net "P3E_CPU0_PE3_OCP_TXN<9>")
	)
	(segment
		(start 443.2681 -125.9713)
		(end 443.1538 -126.0856)
		(width 0.1143)
		(layer "B.Cu")
		(net "P3E_CPU0_PE3_OCP_TXN<9>")
	)
	(segment
		(start 446.41135 -116.87937)
		(end 446.41135 -117.239796)
		(width 0.1143)
		(layer "B.Cu")
		(net "P3E_CPU0_PE3_OCP_TXN<9>")
	)
	(segment
		(start 443.29604 -123.147074)
		(end 443.032134 -124.785374)
		(width 0.1143)
		(layer "B.Cu")
		(net "P3E_CPU0_PE3_OCP_TXN<9>")
	)
	(segment
		(start 445.455548 -118.121684)
		(end 444.49238 -121.618756)
		(width 0.1143)
		(layer "B.Cu")
		(net "P3E_CPU0_PE3_OCP_TXN<9>")
	)
	(segment
		(start 444.49238 -121.618756)
		(end 443.29604 -123.147074)
		(width 0.1143)
		(layer "B.Cu")
		(net "P3E_CPU0_PE3_OCP_TXN<9>")
	)
	(segment
		(start 446.41135 -117.239796)
		(end 446.227962 -117.557042)
		(width 0.1143)
		(layer "B.Cu")
		(net "P3E_CPU0_PE3_OCP_TXN<9>")
	)
	(segment
		(start 446.227962 -117.557042)
		(end 445.455548 -118.121684)
		(width 0.1143)
		(layer "B.Cu")
		(net "P3E_CPU0_PE3_OCP_TXN<9>")
	)
	(segment
		(start 443.2681 -125.688852)
		(end 443.2681 -125.9713)
		(width 0.1143)
		(layer "B.Cu")
		(net "P3E_CPU0_PE3_OCP_TXN<9>")
	)
	(segment
		(start 446.024 -116.49202)
		(end 446.41135 -116.87937)
		(width 0.1143)
		(layer "B.Cu")
		(net "P3E_CPU0_PE3_OCP_TXN<9>")
	)
	(segment
		(start 443.1538 -126.0856)
		(end 442.75375 -126.0856)
		(width 0.1143)
		(layer "B.Cu")
		(net "P3E_CPU0_PE3_OCP_TXN<9>")
	)
	(segment
		(start 443.032134 -124.785374)
		(end 443.2681 -125.688852)
		(width 0.1143)
		(layer "B.Cu")
		(net "P3E_CPU0_PE3_OCP_TXN<9>")
	)
	(segment
		(start 378.41428 -136.880854)
		(end 377.182126 -137.785856)
		(width 0.1143)
		(layer "In4.Cu")
		(net "P3E_CPU0_PE3_OCP_TXN<9>")
	)
	(segment
		(start 356.30485 -115.452144)
		(end 356.30485 -115.204494)
		(width 0.1143)
		(layer "In4.Cu")
		(net "P3E_CPU0_PE3_OCP_TXN<9>")
	)
	(segment
		(start 432.675284 -129.843022)
		(end 431.557176 -129.613152)
		(width 0.1143)
		(layer "In4.Cu")
		(net "P3E_CPU0_PE3_OCP_TXN<9>")
	)
	(segment
		(start 383.96164 -136.689338)
		(end 382.500124 -136.398508)
		(width 0.1143)
		(layer "In4.Cu")
		(net "P3E_CPU0_PE3_OCP_TXN<9>")
	)
	(segment
		(start 375.059956 -137.587228)
		(end 372.899686 -136.3599)
		(width 0.1143)
		(layer "In4.Cu")
		(net "P3E_CPU0_PE3_OCP_TXN<9>")
	)
	(segment
		(start 382.500124 -136.398508)
		(end 381.168148 -136.817862)
		(width 0.1143)
		(layer "In4.Cu")
		(net "P3E_CPU0_PE3_OCP_TXN<9>")
	)
	(segment
		(start 436.49138 -126.176278)
		(end 435.686962 -127.29337)
		(width 0.1143)
		(layer "In4.Cu")
		(net "P3E_CPU0_PE3_OCP_TXN<9>")
	)
	(segment
		(start 386.54863 -135.949944)
		(end 383.96164 -136.689338)
		(width 0.1143)
		(layer "In4.Cu")
		(net "P3E_CPU0_PE3_OCP_TXN<9>")
	)
	(segment
		(start 435.686962 -127.29337)
		(end 435.06644 -128.789938)
		(width 0.1143)
		(layer "In4.Cu")
		(net "P3E_CPU0_PE3_OCP_TXN<9>")
	)
	(segment
		(start 443.04458 -125.5014)
		(end 438.735978 -125.5014)
		(width 0.1143)
		(layer "In4.Cu")
		(net "P3E_CPU0_PE3_OCP_TXN<9>")
	)
	(segment
		(start 376.547634 -137.964164)
		(end 375.059956 -137.587228)
		(width 0.1143)
		(layer "In4.Cu")
		(net "P3E_CPU0_PE3_OCP_TXN<9>")
	)
	(segment
		(start 431.557176 -129.613152)
		(end 430.630838 -129.857246)
		(width 0.1143)
		(layer "In4.Cu")
		(net "P3E_CPU0_PE3_OCP_TXN<9>")
	)
	(segment
		(start 438.735978 -125.5014)
		(end 437.550814 -125.737112)
		(width 0.1143)
		(layer "In4.Cu")
		(net "P3E_CPU0_PE3_OCP_TXN<9>")
	)
	(segment
		(start 419.60419 -136.666732)
		(end 418.321998 -137.390632)
		(width 0.1143)
		(layer "In4.Cu")
		(net "P3E_CPU0_PE3_OCP_TXN<9>")
	)
	(segment
		(start 443.1792 -126.0856)
		(end 443.3062 -125.9586)
		(width 0.1143)
		(layer "In4.Cu")
		(net "P3E_CPU0_PE3_OCP_TXN<9>")
	)
	(segment
		(start 372.899686 -136.3599)
		(end 370.80952 -135.921242)
		(width 0.1143)
		(layer "In4.Cu")
		(net "P3E_CPU0_PE3_OCP_TXN<9>")
	)
	(segment
		(start 425.638722 -131.713986)
		(end 423.194734 -132.42925)
		(width 0.1143)
		(layer "In4.Cu")
		(net "P3E_CPU0_PE3_OCP_TXN<9>")
	)
	(segment
		(start 355.825044 -115.566444)
		(end 356.19055 -115.566444)
		(width 0.1143)
		(layer "In4.Cu")
		(net "P3E_CPU0_PE3_OCP_TXN<9>")
	)
	(segment
		(start 421.459406 -133.7564)
		(end 419.60419 -136.666732)
		(width 0.1143)
		(layer "In4.Cu")
		(net "P3E_CPU0_PE3_OCP_TXN<9>")
	)
	(segment
		(start 418.321998 -137.390632)
		(end 415.886138 -137.898886)
		(width 0.1143)
		(layer "In4.Cu")
		(net "P3E_CPU0_PE3_OCP_TXN<9>")
	)
	(segment
		(start 442.75375 -126.0856)
		(end 443.1792 -126.0856)
		(width 0.1143)
		(layer "In4.Cu")
		(net "P3E_CPU0_PE3_OCP_TXN<9>")
	)
	(segment
		(start 434.122322 -129.507488)
		(end 432.675284 -129.843022)
		(width 0.1143)
		(layer "In4.Cu")
		(net "P3E_CPU0_PE3_OCP_TXN<9>")
	)
	(segment
		(start 435.06644 -128.789938)
		(end 434.122322 -129.507488)
		(width 0.1143)
		(layer "In4.Cu")
		(net "P3E_CPU0_PE3_OCP_TXN<9>")
	)
	(segment
		(start 369.502436 -136.43991)
		(end 368.991388 -136.330944)
		(width 0.1143)
		(layer "In4.Cu")
		(net "P3E_CPU0_PE3_OCP_TXN<9>")
	)
	(segment
		(start 356.046532 -122.532394)
		(end 355.4984 -120.037098)
		(width 0.1143)
		(layer "In4.Cu")
		(net "P3E_CPU0_PE3_OCP_TXN<9>")
	)
	(segment
		(start 405.386794 -139.697968)
		(end 386.54863 -135.949944)
		(width 0.1143)
		(layer "In4.Cu")
		(net "P3E_CPU0_PE3_OCP_TXN<9>")
	)
	(segment
		(start 413.577532 -137.133838)
		(end 410.474414 -137.717784)
		(width 0.1143)
		(layer "In4.Cu")
		(net "P3E_CPU0_PE3_OCP_TXN<9>")
	)
	(segment
		(start 377.182126 -137.785856)
		(end 376.547634 -137.964164)
		(width 0.1143)
		(layer "In4.Cu")
		(net "P3E_CPU0_PE3_OCP_TXN<9>")
	)
	(segment
		(start 379.909832 -136.53897)
		(end 378.41428 -136.880854)
		(width 0.1143)
		(layer "In4.Cu")
		(net "P3E_CPU0_PE3_OCP_TXN<9>")
	)
	(segment
		(start 367.734596 -134.279132)
		(end 366.17656 -132.212588)
		(width 0.1143)
		(layer "In4.Cu")
		(net "P3E_CPU0_PE3_OCP_TXN<9>")
	)
	(segment
		(start 415.886138 -137.898886)
		(end 413.577532 -137.133838)
		(width 0.1143)
		(layer "In4.Cu")
		(net "P3E_CPU0_PE3_OCP_TXN<9>")
	)
	(segment
		(start 423.194734 -132.42925)
		(end 421.459406 -133.7564)
		(width 0.1143)
		(layer "In4.Cu")
		(net "P3E_CPU0_PE3_OCP_TXN<9>")
	)
	(segment
		(start 381.168148 -136.817862)
		(end 379.909832 -136.53897)
		(width 0.1143)
		(layer "In4.Cu")
		(net "P3E_CPU0_PE3_OCP_TXN<9>")
	)
	(segment
		(start 430.630838 -129.857246)
		(end 429.743616 -130.32994)
		(width 0.1143)
		(layer "In4.Cu")
		(net "P3E_CPU0_PE3_OCP_TXN<9>")
	)
	(segment
		(start 355.4984 -120.037098)
		(end 355.4984 -115.893088)
		(width 0.1143)
		(layer "In4.Cu")
		(net "P3E_CPU0_PE3_OCP_TXN<9>")
	)
	(segment
		(start 428.980092 -131.391914)
		(end 427.370748 -132.077968)
		(width 0.1143)
		(layer "In4.Cu")
		(net "P3E_CPU0_PE3_OCP_TXN<9>")
	)
	(segment
		(start 429.743616 -130.32994)
		(end 428.980092 -131.391914)
		(width 0.1143)
		(layer "In4.Cu")
		(net "P3E_CPU0_PE3_OCP_TXN<9>")
	)
	(segment
		(start 437.550814 -125.737112)
		(end 436.49138 -126.176278)
		(width 0.1143)
		(layer "In4.Cu")
		(net "P3E_CPU0_PE3_OCP_TXN<9>")
	)
	(segment
		(start 370.80952 -135.921242)
		(end 369.502436 -136.43991)
		(width 0.1143)
		(layer "In4.Cu")
		(net "P3E_CPU0_PE3_OCP_TXN<9>")
	)
	(segment
		(start 368.991388 -136.330944)
		(end 368.533934 -135.987536)
		(width 0.1143)
		(layer "In4.Cu")
		(net "P3E_CPU0_PE3_OCP_TXN<9>")
	)
	(segment
		(start 356.19055 -115.566444)
		(end 356.30485 -115.452144)
		(width 0.1143)
		(layer "In4.Cu")
		(net "P3E_CPU0_PE3_OCP_TXN<9>")
	)
	(segment
		(start 408.607006 -139.054332)
		(end 405.386794 -139.697968)
		(width 0.1143)
		(layer "In4.Cu")
		(net "P3E_CPU0_PE3_OCP_TXN<9>")
	)
	(segment
		(start 368.533934 -135.987536)
		(end 367.734596 -134.279132)
		(width 0.1143)
		(layer "In4.Cu")
		(net "P3E_CPU0_PE3_OCP_TXN<9>")
	)
	(segment
		(start 427.370748 -132.077968)
		(end 425.638722 -131.713986)
		(width 0.1143)
		(layer "In4.Cu")
		(net "P3E_CPU0_PE3_OCP_TXN<9>")
	)
	(segment
		(start 443.3062 -125.9586)
		(end 443.3062 -125.76302)
		(width 0.1143)
		(layer "In4.Cu")
		(net "P3E_CPU0_PE3_OCP_TXN<9>")
	)
	(segment
		(start 355.525578 -124.78258)
		(end 356.046532 -122.532394)
		(width 0.1143)
		(layer "In4.Cu")
		(net "P3E_CPU0_PE3_OCP_TXN<9>")
	)
	(segment
		(start 355.4984 -115.893088)
		(end 355.825044 -115.566444)
		(width 0.1143)
		(layer "In4.Cu")
		(net "P3E_CPU0_PE3_OCP_TXN<9>")
	)
	(segment
		(start 361.029504 -130.173984)
		(end 356.459536 -127.288544)
		(width 0.1143)
		(layer "In4.Cu")
		(net "P3E_CPU0_PE3_OCP_TXN<9>")
	)
	(segment
		(start 366.17656 -132.212588)
		(end 361.029504 -130.173984)
		(width 0.1143)
		(layer "In4.Cu")
		(net "P3E_CPU0_PE3_OCP_TXN<9>")
	)
	(segment
		(start 443.3062 -125.76302)
		(end 443.04458 -125.5014)
		(width 0.1143)
		(layer "In4.Cu")
		(net "P3E_CPU0_PE3_OCP_TXN<9>")
	)
	(segment
		(start 410.474414 -137.717784)
		(end 408.607006 -139.054332)
		(width 0.1143)
		(layer "In4.Cu")
		(net "P3E_CPU0_PE3_OCP_TXN<9>")
	)
	(segment
		(start 356.459536 -127.288544)
		(end 355.525578 -124.78258)
		(width 0.1143)
		(layer "In4.Cu")
		(net "P3E_CPU0_PE3_OCP_TXN<9>")
	)
	(segment
		(start 327.452736 -108.591096)
		(end 314.965334 -103.419148)
		(width 0.1143)
		(layer "In11.Cu")
		(net "P3E_CPU0_PE3_OCP_TXN<9>")
	)
	(segment
		(start 327.903078 -109.33176)
		(end 327.783952 -109.010196)
		(width 0.1143)
		(layer "In11.Cu")
		(net "P3E_CPU0_PE3_OCP_TXN<9>")
	)
	(segment
		(start 355.976682 -115.57)
		(end 355.875082 -115.4684)
		(width 0.1143)
		(layer "In11.Cu")
		(net "P3E_CPU0_PE3_OCP_TXN<9>")
	)
	(segment
		(start 303.876456 -96.223836)
		(end 303.870106 -96.234504)
		(width 0.0889)
		(layer "In11.Cu")
		(net "P3E_CPU0_PE3_OCP_TXN<9>")
	)
	(segment
		(start 327.783952 -109.010196)
		(end 327.571862 -108.91266)
		(width 0.1143)
		(layer "In11.Cu")
		(net "P3E_CPU0_PE3_OCP_TXN<9>")
	)
	(segment
		(start 356.199694 -115.57)
		(end 355.976682 -115.57)
		(width 0.1143)
		(layer "In11.Cu")
		(net "P3E_CPU0_PE3_OCP_TXN<9>")
	)
	(segment
		(start 306.30876 -95.5548)
		(end 305.439826 -96.423734)
		(width 0.0889)
		(layer "In11.Cu")
		(net "P3E_CPU0_PE3_OCP_TXN<9>")
	)
	(segment
		(start 327.805796 -109.54385)
		(end 327.903078 -109.33176)
		(width 0.1143)
		(layer "In11.Cu")
		(net "P3E_CPU0_PE3_OCP_TXN<9>")
	)
	(segment
		(start 328.579734 -111.633254)
		(end 327.805796 -109.54385)
		(width 0.1143)
		(layer "In11.Cu")
		(net "P3E_CPU0_PE3_OCP_TXN<9>")
	)
	(segment
		(start 305.439826 -96.423734)
		(end 305.228752 -96.423734)
		(width 0.0889)
		(layer "In11.Cu")
		(net "P3E_CPU0_PE3_OCP_TXN<9>")
	)
	(segment
		(start 304.406046 -95.928434)
		(end 304.370486 -95.928434)
		(width 0.0889)
		(layer "In11.Cu")
		(net "P3E_CPU0_PE3_OCP_TXN<9>")
	)
	(segment
		(start 309.883048 -96.950784)
		(end 308.487064 -95.5548)
		(width 0.0889)
		(layer "In11.Cu")
		(net "P3E_CPU0_PE3_OCP_TXN<9>")
	)
	(segment
		(start 330.902818 -112.995456)
		(end 330.24953 -112.8649)
		(width 0.1143)
		(layer "In11.Cu")
		(net "P3E_CPU0_PE3_OCP_TXN<9>")
	)
	(segment
		(start 329.211178 -112.434624)
		(end 328.579734 -111.633254)
		(width 0.1143)
		(layer "In11.Cu")
		(net "P3E_CPU0_PE3_OCP_TXN<9>")
	)
	(segment
		(start 308.487064 -95.5548)
		(end 306.30876 -95.5548)
		(width 0.0889)
		(layer "In11.Cu")
		(net "P3E_CPU0_PE3_OCP_TXN<9>")
	)
	(segment
		(start 342.426798 -114.1603)
		(end 341.644224 -113.377472)
		(width 0.1143)
		(layer "In11.Cu")
		(net "P3E_CPU0_PE3_OCP_TXN<9>")
	)
	(segment
		(start 355.875082 -114.890042)
		(end 355.54031 -114.55527)
		(width 0.1143)
		(layer "In11.Cu")
		(net "P3E_CPU0_PE3_OCP_TXN<9>")
	)
	(segment
		(start 336.884264 -112.8903)
		(end 336.001868 -112.71377)
		(width 0.1143)
		(layer "In11.Cu")
		(net "P3E_CPU0_PE3_OCP_TXN<9>")
	)
	(segment
		(start 309.954422 -96.950784)
		(end 309.883048 -96.950784)
		(width 0.0889)
		(layer "In11.Cu")
		(net "P3E_CPU0_PE3_OCP_TXN<9>")
	)
	(segment
		(start 327.571862 -108.91266)
		(end 327.452736 -108.591096)
		(width 0.1143)
		(layer "In11.Cu")
		(net "P3E_CPU0_PE3_OCP_TXN<9>")
	)
	(segment
		(start 309.96255 -96.958912)
		(end 309.954422 -96.950784)
		(width 0.0889)
		(layer "In11.Cu")
		(net "P3E_CPU0_PE3_OCP_TXN<9>")
	)
	(segment
		(start 354.588064 -114.1603)
		(end 342.426798 -114.1603)
		(width 0.1143)
		(layer "In11.Cu")
		(net "P3E_CPU0_PE3_OCP_TXN<9>")
	)
	(segment
		(start 311.42559 -99.060508)
		(end 310.614314 -97.610676)
		(width 0.1143)
		(layer "In11.Cu")
		(net "P3E_CPU0_PE3_OCP_TXN<9>")
	)
	(segment
		(start 340.467442 -112.8903)
		(end 336.884264 -112.8903)
		(width 0.1143)
		(layer "In11.Cu")
		(net "P3E_CPU0_PE3_OCP_TXN<9>")
	)
	(segment
		(start 356.30485 -115.204494)
		(end 356.30485 -115.464844)
		(width 0.1143)
		(layer "In11.Cu")
		(net "P3E_CPU0_PE3_OCP_TXN<9>")
	)
	(segment
		(start 332.14564 -112.694466)
		(end 330.902818 -112.995456)
		(width 0.1143)
		(layer "In11.Cu")
		(net "P3E_CPU0_PE3_OCP_TXN<9>")
	)
	(segment
		(start 334.122014 -113.08969)
		(end 332.14564 -112.694466)
		(width 0.1143)
		(layer "In11.Cu")
		(net "P3E_CPU0_PE3_OCP_TXN<9>")
	)
	(segment
		(start 355.54031 -114.55527)
		(end 354.588064 -114.1603)
		(width 0.1143)
		(layer "In11.Cu")
		(net "P3E_CPU0_PE3_OCP_TXN<9>")
	)
	(segment
		(start 310.614314 -97.610676)
		(end 309.96255 -96.958912)
		(width 0.1143)
		(layer "In11.Cu")
		(net "P3E_CPU0_PE3_OCP_TXN<9>")
	)
	(segment
		(start 341.644224 -113.377472)
		(end 340.467442 -112.8903)
		(width 0.1143)
		(layer "In11.Cu")
		(net "P3E_CPU0_PE3_OCP_TXN<9>")
	)
	(segment
		(start 336.001868 -112.71377)
		(end 334.122014 -113.08969)
		(width 0.1143)
		(layer "In11.Cu")
		(net "P3E_CPU0_PE3_OCP_TXN<9>")
	)
	(segment
		(start 356.30485 -115.464844)
		(end 356.199694 -115.57)
		(width 0.1143)
		(layer "In11.Cu")
		(net "P3E_CPU0_PE3_OCP_TXN<9>")
	)
	(segment
		(start 355.875082 -115.4684)
		(end 355.875082 -114.890042)
		(width 0.1143)
		(layer "In11.Cu")
		(net "P3E_CPU0_PE3_OCP_TXN<9>")
	)
	(segment
		(start 330.24953 -112.8649)
		(end 329.211178 -112.434624)
		(width 0.1143)
		(layer "In11.Cu")
		(net "P3E_CPU0_PE3_OCP_TXN<9>")
	)
	(segment
		(start 314.965334 -103.419148)
		(end 311.42559 -99.060508)
		(width 0.1143)
		(layer "In11.Cu")
		(net "P3E_CPU0_PE3_OCP_TXN<9>")
	)
	(arc
		(start 304.029364 -96.988376)
		(mid 304.250203 -97.22048)
		(end 304.388266 -97.509584)
		(width 0.0889)
		(layer "In11.Cu")
		(net "P3E_CPU0_PE3_OCP_TXN<9>")
	)
	(arc
		(start 303.876456 -96.814386)
		(mid 303.94428 -96.908969)
		(end 304.029364 -96.988376)
		(width 0.0889)
		(layer "In11.Cu")
		(net "P3E_CPU0_PE3_OCP_TXN<9>")
	)
	(arc
		(start 304.370486 -95.928434)
		(mid 304.085062 -96.011901)
		(end 303.876456 -96.223836)
		(width 0.0889)
		(layer "In11.Cu")
		(net "P3E_CPU0_PE3_OCP_TXN<9>")
	)
	(arc
		(start 303.870106 -96.234504)
		(mid 303.797308 -96.525267)
		(end 303.876456 -96.814386)
		(width 0.0889)
		(layer "In11.Cu")
		(net "P3E_CPU0_PE3_OCP_TXN<9>")
	)
	(arc
		(start 304.900076 -96.223836)
		(mid 304.691468 -96.011904)
		(end 304.406046 -95.928434)
		(width 0.0889)
		(layer "In11.Cu")
		(net "P3E_CPU0_PE3_OCP_TXN<9>")
	)
	(arc
		(start 305.228752 -96.423734)
		(mid 305.038823 -96.365864)
		(end 304.900076 -96.223836)
		(width 0.0889)
		(layer "In11.Cu")
		(net "P3E_CPU0_PE3_OCP_TXN<9>")
	)
	(segment
		(start 302.099726 -96.518984)
		(end 302.671226 -96.518984)
		(width 0.1143)
		(layer "F.Cu")
		(net "P3E_CPU0_PE3_OCP_TXN<8>")
	)
	(via
		(at 302.671226 -96.518984)
		(size 0.508)
		(drill 0.254)
		(layers "F.Cu" "B.Cu")
		(net "P3E_CPU0_PE3_OCP_TXN<8>")
	)
	(via
		(at 439.074306 -127.02159)
		(size 0.508)
		(drill 0.254)
		(layers "F.Cu" "B.Cu")
		(net "P3E_CPU0_PE3_OCP_TXN<8>")
	)
	(via
		(at 354.42525 -116.220494)
		(size 0.508)
		(drill 0.254)
		(layers "F.Cu" "B.Cu")
		(net "P3E_CPU0_PE3_OCP_TXN<8>")
	)
	(segment
		(start 439.474356 -127.02159)
		(end 439.074306 -127.02159)
		(width 0.1143)
		(layer "B.Cu")
		(net "P3E_CPU0_PE3_OCP_TXN<8>")
	)
	(segment
		(start 441.891674 -118.417594)
		(end 439.265568 -124.52985)
		(width 0.1143)
		(layer "B.Cu")
		(net "P3E_CPU0_PE3_OCP_TXN<8>")
	)
	(segment
		(start 439.265568 -124.52985)
		(end 439.588656 -125.773942)
		(width 0.1143)
		(layer "B.Cu")
		(net "P3E_CPU0_PE3_OCP_TXN<8>")
	)
	(segment
		(start 439.588656 -126.90729)
		(end 439.474356 -127.02159)
		(width 0.1143)
		(layer "B.Cu")
		(net "P3E_CPU0_PE3_OCP_TXN<8>")
	)
	(segment
		(start 442.849 -116.49202)
		(end 443.23635 -116.87937)
		(width 0.1143)
		(layer "B.Cu")
		(net "P3E_CPU0_PE3_OCP_TXN<8>")
	)
	(segment
		(start 443.236096 -117.239796)
		(end 443.054994 -117.531896)
		(width 0.1143)
		(layer "B.Cu")
		(net "P3E_CPU0_PE3_OCP_TXN<8>")
	)
	(segment
		(start 443.054994 -117.531896)
		(end 441.891674 -118.417594)
		(width 0.1143)
		(layer "B.Cu")
		(net "P3E_CPU0_PE3_OCP_TXN<8>")
	)
	(segment
		(start 443.23635 -117.239542)
		(end 443.236096 -117.239796)
		(width 0.1143)
		(layer "B.Cu")
		(net "P3E_CPU0_PE3_OCP_TXN<8>")
	)
	(segment
		(start 443.23635 -116.87937)
		(end 443.23635 -117.239542)
		(width 0.1143)
		(layer "B.Cu")
		(net "P3E_CPU0_PE3_OCP_TXN<8>")
	)
	(segment
		(start 439.588656 -125.773942)
		(end 439.588656 -126.90729)
		(width 0.1143)
		(layer "B.Cu")
		(net "P3E_CPU0_PE3_OCP_TXN<8>")
	)
	(segment
		(start 438.940702 -129.331466)
		(end 439.07202 -129.014728)
		(width 0.1143)
		(layer "In4.Cu")
		(net "P3E_CPU0_PE3_OCP_TXN<8>")
	)
	(segment
		(start 419.84803 -136.94537)
		(end 421.727884 -133.996176)
		(width 0.1143)
		(layer "In4.Cu")
		(net "P3E_CPU0_PE3_OCP_TXN<8>")
	)
	(segment
		(start 438.898538 -129.86385)
		(end 439.029856 -129.547112)
		(width 0.1143)
		(layer "In4.Cu")
		(net "P3E_CPU0_PE3_OCP_TXN<8>")
	)
	(segment
		(start 357.16337 -128.349756)
		(end 357.453438 -128.53289)
		(width 0.1143)
		(layer "In4.Cu")
		(net "P3E_CPU0_PE3_OCP_TXN<8>")
	)
	(segment
		(start 439.029856 -129.547112)
		(end 438.940702 -129.331466)
		(width 0.1143)
		(layer "In4.Cu")
		(net "P3E_CPU0_PE3_OCP_TXN<8>")
	)
	(segment
		(start 354.608638 -117.921786)
		(end 355.14407 -120.358662)
		(width 0.1143)
		(layer "In4.Cu")
		(net "P3E_CPU0_PE3_OCP_TXN<8>")
	)
	(segment
		(start 434.716936 -130.960114)
		(end 435.054756 -131.01828)
		(width 0.1143)
		(layer "In4.Cu")
		(net "P3E_CPU0_PE3_OCP_TXN<8>")
	)
	(segment
		(start 353.906836 -116.595398)
		(end 354.608638 -117.921786)
		(width 0.1143)
		(layer "In4.Cu")
		(net "P3E_CPU0_PE3_OCP_TXN<8>")
	)
	(segment
		(start 356.280212 -127.792226)
		(end 356.59441 -127.9906)
		(width 0.1143)
		(layer "In4.Cu")
		(net "P3E_CPU0_PE3_OCP_TXN<8>")
	)
	(segment
		(start 381.173482 -137.183114)
		(end 382.501648 -136.765284)
		(width 0.1143)
		(layer "In4.Cu")
		(net "P3E_CPU0_PE3_OCP_TXN<8>")
	)
	(segment
		(start 354.42525 -115.9891)
		(end 354.31095 -115.8748)
		(width 0.1143)
		(layer "In4.Cu")
		(net "P3E_CPU0_PE3_OCP_TXN<8>")
	)
	(segment
		(start 358.540304 -129.024126)
		(end 358.830118 -129.20726)
		(width 0.1143)
		(layer "In4.Cu")
		(net "P3E_CPU0_PE3_OCP_TXN<8>")
	)
	(segment
		(start 439.07202 -129.014728)
		(end 439.287666 -128.92532)
		(width 0.1143)
		(layer "In4.Cu")
		(net "P3E_CPU0_PE3_OCP_TXN<8>")
	)
	(segment
		(start 435.583584 -130.94208)
		(end 435.718204 -131.132834)
		(width 0.1143)
		(layer "In4.Cu")
		(net "P3E_CPU0_PE3_OCP_TXN<8>")
	)
	(segment
		(start 367.42878 -134.464806)
		(end 368.249454 -136.218676)
		(width 0.1143)
		(layer "In4.Cu")
		(net "P3E_CPU0_PE3_OCP_TXN<8>")
	)
	(segment
		(start 439.5724 -127.3302)
		(end 439.26379 -127.02159)
		(width 0.1143)
		(layer "In4.Cu")
		(net "P3E_CPU0_PE3_OCP_TXN<8>")
	)
	(segment
		(start 413.556704 -137.499344)
		(end 415.864548 -138.264138)
		(width 0.1143)
		(layer "In4.Cu")
		(net "P3E_CPU0_PE3_OCP_TXN<8>")
	)
	(segment
		(start 438.640474 -130.485642)
		(end 438.55132 -130.269996)
		(width 0.1143)
		(layer "In4.Cu")
		(net "P3E_CPU0_PE3_OCP_TXN<8>")
	)
	(segment
		(start 378.535946 -137.232644)
		(end 379.943868 -136.910826)
		(width 0.1143)
		(layer "In4.Cu")
		(net "P3E_CPU0_PE3_OCP_TXN<8>")
	)
	(segment
		(start 435.24551 -130.88366)
		(end 435.583584 -130.94208)
		(width 0.1143)
		(layer "In4.Cu")
		(net "P3E_CPU0_PE3_OCP_TXN<8>")
	)
	(segment
		(start 359.399332 -129.56667)
		(end 359.689146 -129.749804)
		(width 0.1143)
		(layer "In4.Cu")
		(net "P3E_CPU0_PE3_OCP_TXN<8>")
	)
	(segment
		(start 425.67606 -132.07365)
		(end 427.424596 -132.442458)
		(width 0.1143)
		(layer "In4.Cu")
		(net "P3E_CPU0_PE3_OCP_TXN<8>")
	)
	(segment
		(start 439.287666 -128.92532)
		(end 439.5724 -128.239012)
		(width 0.1143)
		(layer "In4.Cu")
		(net "P3E_CPU0_PE3_OCP_TXN<8>")
	)
	(segment
		(start 359.740708 -129.977388)
		(end 360.030522 -130.160522)
		(width 0.1143)
		(layer "In4.Cu")
		(net "P3E_CPU0_PE3_OCP_TXN<8>")
	)
	(segment
		(start 439.26379 -127.02159)
		(end 439.074306 -127.02159)
		(width 0.1143)
		(layer "In4.Cu")
		(net "P3E_CPU0_PE3_OCP_TXN<8>")
	)
	(segment
		(start 360.030522 -130.160522)
		(end 365.952532 -132.506212)
		(width 0.1143)
		(layer "In4.Cu")
		(net "P3E_CPU0_PE3_OCP_TXN<8>")
	)
	(segment
		(start 355.14407 -120.358662)
		(end 354.517706 -123.064524)
		(width 0.1143)
		(layer "In4.Cu")
		(net "P3E_CPU0_PE3_OCP_TXN<8>")
	)
	(segment
		(start 382.501648 -136.765284)
		(end 383.969514 -137.05713)
		(width 0.1143)
		(layer "In4.Cu")
		(net "P3E_CPU0_PE3_OCP_TXN<8>")
	)
	(segment
		(start 376.571002 -138.326876)
		(end 377.340876 -138.110468)
		(width 0.1143)
		(layer "In4.Cu")
		(net "P3E_CPU0_PE3_OCP_TXN<8>")
	)
	(segment
		(start 374.89638 -137.903458)
		(end 376.571002 -138.326876)
		(width 0.1143)
		(layer "In4.Cu")
		(net "P3E_CPU0_PE3_OCP_TXN<8>")
	)
	(segment
		(start 410.631894 -138.05027)
		(end 413.481774 -137.513568)
		(width 0.1143)
		(layer "In4.Cu")
		(net "P3E_CPU0_PE3_OCP_TXN<8>")
	)
	(segment
		(start 432.87696 -131.573524)
		(end 434.716936 -130.960114)
		(width 0.1143)
		(layer "In4.Cu")
		(net "P3E_CPU0_PE3_OCP_TXN<8>")
	)
	(segment
		(start 379.943868 -136.910826)
		(end 381.173482 -137.183114)
		(width 0.1143)
		(layer "In4.Cu")
		(net "P3E_CPU0_PE3_OCP_TXN<8>")
	)
	(segment
		(start 368.249454 -136.218676)
		(end 368.840512 -136.662414)
		(width 0.1143)
		(layer "In4.Cu")
		(net "P3E_CPU0_PE3_OCP_TXN<8>")
	)
	(segment
		(start 415.864548 -138.264138)
		(end 418.478208 -137.7188)
		(width 0.1143)
		(layer "In4.Cu")
		(net "P3E_CPU0_PE3_OCP_TXN<8>")
	)
	(segment
		(start 359.171494 -129.617978)
		(end 359.399332 -129.56667)
		(width 0.1143)
		(layer "In4.Cu")
		(net "P3E_CPU0_PE3_OCP_TXN<8>")
	)
	(segment
		(start 404.908258 -140.156438)
		(end 408.767788 -139.384024)
		(width 0.1143)
		(layer "In4.Cu")
		(net "P3E_CPU0_PE3_OCP_TXN<8>")
	)
	(segment
		(start 391.608564 -137.511028)
		(end 391.80262 -137.381488)
		(width 0.1143)
		(layer "In4.Cu")
		(net "P3E_CPU0_PE3_OCP_TXN<8>")
	)
	(segment
		(start 435.054756 -131.01828)
		(end 435.24551 -130.88366)
		(width 0.1143)
		(layer "In4.Cu")
		(net "P3E_CPU0_PE3_OCP_TXN<8>")
	)
	(segment
		(start 389.61568 -137.114788)
		(end 389.809736 -136.985248)
		(width 0.1143)
		(layer "In4.Cu")
		(net "P3E_CPU0_PE3_OCP_TXN<8>")
	)
	(segment
		(start 357.97109 -128.664716)
		(end 358.022652 -128.8923)
		(width 0.1143)
		(layer "In4.Cu")
		(net "P3E_CPU0_PE3_OCP_TXN<8>")
	)
	(segment
		(start 356.59441 -127.9906)
		(end 356.821994 -127.939038)
		(width 0.1143)
		(layer "In4.Cu")
		(net "P3E_CPU0_PE3_OCP_TXN<8>")
	)
	(segment
		(start 392.26871 -137.642346)
		(end 404.908258 -140.156438)
		(width 0.1143)
		(layer "In4.Cu")
		(net "P3E_CPU0_PE3_OCP_TXN<8>")
	)
	(segment
		(start 372.772178 -136.696196)
		(end 374.89638 -137.903458)
		(width 0.1143)
		(layer "In4.Cu")
		(net "P3E_CPU0_PE3_OCP_TXN<8>")
	)
	(segment
		(start 353.906836 -116.042948)
		(end 353.906836 -116.595398)
		(width 0.1143)
		(layer "In4.Cu")
		(net "P3E_CPU0_PE3_OCP_TXN<8>")
	)
	(segment
		(start 438.509156 -130.80238)
		(end 438.640474 -130.485642)
		(width 0.1143)
		(layer "In4.Cu")
		(net "P3E_CPU0_PE3_OCP_TXN<8>")
	)
	(segment
		(start 357.453438 -128.53289)
		(end 357.681022 -128.481582)
		(width 0.1143)
		(layer "In4.Cu")
		(net "P3E_CPU0_PE3_OCP_TXN<8>")
	)
	(segment
		(start 436.951628 -131.345432)
		(end 438.509156 -130.80238)
		(width 0.1143)
		(layer "In4.Cu")
		(net "P3E_CPU0_PE3_OCP_TXN<8>")
	)
	(segment
		(start 358.830118 -129.20726)
		(end 358.88168 -129.434844)
		(width 0.1143)
		(layer "In4.Cu")
		(net "P3E_CPU0_PE3_OCP_TXN<8>")
	)
	(segment
		(start 369.53952 -136.811512)
		(end 370.847366 -136.29259)
		(width 0.1143)
		(layer "In4.Cu")
		(net "P3E_CPU0_PE3_OCP_TXN<8>")
	)
	(segment
		(start 390.275826 -137.246106)
		(end 390.612122 -137.312908)
		(width 0.1143)
		(layer "In4.Cu")
		(net "P3E_CPU0_PE3_OCP_TXN<8>")
	)
	(segment
		(start 368.840512 -136.662414)
		(end 369.53952 -136.811512)
		(width 0.1143)
		(layer "In4.Cu")
		(net "P3E_CPU0_PE3_OCP_TXN<8>")
	)
	(segment
		(start 392.138916 -137.44829)
		(end 392.26871 -137.642346)
		(width 0.1143)
		(layer "In4.Cu")
		(net "P3E_CPU0_PE3_OCP_TXN<8>")
	)
	(segment
		(start 391.80262 -137.381488)
		(end 392.138916 -137.44829)
		(width 0.1143)
		(layer "In4.Cu")
		(net "P3E_CPU0_PE3_OCP_TXN<8>")
	)
	(segment
		(start 408.767788 -139.384024)
		(end 410.631894 -138.05027)
		(width 0.1143)
		(layer "In4.Cu")
		(net "P3E_CPU0_PE3_OCP_TXN<8>")
	)
	(segment
		(start 418.478208 -137.7188)
		(end 419.84803 -136.94537)
		(width 0.1143)
		(layer "In4.Cu")
		(net "P3E_CPU0_PE3_OCP_TXN<8>")
	)
	(segment
		(start 388.619238 -136.916668)
		(end 388.813294 -136.787128)
		(width 0.1143)
		(layer "In4.Cu")
		(net "P3E_CPU0_PE3_OCP_TXN<8>")
	)
	(segment
		(start 391.272268 -137.444226)
		(end 391.608564 -137.511028)
		(width 0.1143)
		(layer "In4.Cu")
		(net "P3E_CPU0_PE3_OCP_TXN<8>")
	)
	(segment
		(start 439.5724 -128.239012)
		(end 439.5724 -127.3302)
		(width 0.1143)
		(layer "In4.Cu")
		(net "P3E_CPU0_PE3_OCP_TXN<8>")
	)
	(segment
		(start 390.806178 -137.183368)
		(end 391.142474 -137.25017)
		(width 0.1143)
		(layer "In4.Cu")
		(net "P3E_CPU0_PE3_OCP_TXN<8>")
	)
	(segment
		(start 359.689146 -129.749804)
		(end 359.740708 -129.977388)
		(width 0.1143)
		(layer "In4.Cu")
		(net "P3E_CPU0_PE3_OCP_TXN<8>")
	)
	(segment
		(start 357.681022 -128.481582)
		(end 357.97109 -128.664716)
		(width 0.1143)
		(layer "In4.Cu")
		(net "P3E_CPU0_PE3_OCP_TXN<8>")
	)
	(segment
		(start 358.88168 -129.434844)
		(end 359.171494 -129.617978)
		(width 0.1143)
		(layer "In4.Cu")
		(net "P3E_CPU0_PE3_OCP_TXN<8>")
	)
	(segment
		(start 354.42525 -116.220494)
		(end 354.42525 -115.9891)
		(width 0.1143)
		(layer "In4.Cu")
		(net "P3E_CPU0_PE3_OCP_TXN<8>")
	)
	(segment
		(start 390.612122 -137.312908)
		(end 390.806178 -137.183368)
		(width 0.1143)
		(layer "In4.Cu")
		(net "P3E_CPU0_PE3_OCP_TXN<8>")
	)
	(segment
		(start 389.809736 -136.985248)
		(end 390.146032 -137.05205)
		(width 0.1143)
		(layer "In4.Cu")
		(net "P3E_CPU0_PE3_OCP_TXN<8>")
	)
	(segment
		(start 413.482282 -137.513314)
		(end 413.519366 -137.506456)
		(width 0.1143)
		(layer "In4.Cu")
		(net "P3E_CPU0_PE3_OCP_TXN<8>")
	)
	(segment
		(start 435.718204 -131.132834)
		(end 436.951628 -131.345432)
		(width 0.1143)
		(layer "In4.Cu")
		(net "P3E_CPU0_PE3_OCP_TXN<8>")
	)
	(segment
		(start 413.519366 -137.506456)
		(end 413.556704 -137.499344)
		(width 0.1143)
		(layer "In4.Cu")
		(net "P3E_CPU0_PE3_OCP_TXN<8>")
	)
	(segment
		(start 383.969514 -137.05713)
		(end 386.166614 -136.428988)
		(width 0.1143)
		(layer "In4.Cu")
		(net "P3E_CPU0_PE3_OCP_TXN<8>")
	)
	(segment
		(start 354.31095 -115.8748)
		(end 354.074984 -115.8748)
		(width 0.1143)
		(layer "In4.Cu")
		(net "P3E_CPU0_PE3_OCP_TXN<8>")
	)
	(segment
		(start 386.166614 -136.428988)
		(end 388.619238 -136.916668)
		(width 0.1143)
		(layer "In4.Cu")
		(net "P3E_CPU0_PE3_OCP_TXN<8>")
	)
	(segment
		(start 391.142474 -137.25017)
		(end 391.272268 -137.444226)
		(width 0.1143)
		(layer "In4.Cu")
		(net "P3E_CPU0_PE3_OCP_TXN<8>")
	)
	(segment
		(start 438.682638 -129.953258)
		(end 438.898538 -129.86385)
		(width 0.1143)
		(layer "In4.Cu")
		(net "P3E_CPU0_PE3_OCP_TXN<8>")
	)
	(segment
		(start 390.146032 -137.05205)
		(end 390.275826 -137.246106)
		(width 0.1143)
		(layer "In4.Cu")
		(net "P3E_CPU0_PE3_OCP_TXN<8>")
	)
	(segment
		(start 389.14959 -136.85393)
		(end 389.279384 -137.047986)
		(width 0.1143)
		(layer "In4.Cu")
		(net "P3E_CPU0_PE3_OCP_TXN<8>")
	)
	(segment
		(start 356.821994 -127.939038)
		(end 357.112062 -128.122172)
		(width 0.1143)
		(layer "In4.Cu")
		(net "P3E_CPU0_PE3_OCP_TXN<8>")
	)
	(segment
		(start 358.022652 -128.8923)
		(end 358.312466 -129.075434)
		(width 0.1143)
		(layer "In4.Cu")
		(net "P3E_CPU0_PE3_OCP_TXN<8>")
	)
	(segment
		(start 354.074984 -115.8748)
		(end 353.906836 -116.042948)
		(width 0.1143)
		(layer "In4.Cu")
		(net "P3E_CPU0_PE3_OCP_TXN<8>")
	)
	(segment
		(start 354.517706 -123.064524)
		(end 356.280212 -127.792226)
		(width 0.1143)
		(layer "In4.Cu")
		(net "P3E_CPU0_PE3_OCP_TXN<8>")
	)
	(segment
		(start 413.481774 -137.513568)
		(end 413.482282 -137.513314)
		(width 0.1143)
		(layer "In4.Cu")
		(net "P3E_CPU0_PE3_OCP_TXN<8>")
	)
	(segment
		(start 388.813294 -136.787128)
		(end 389.14959 -136.85393)
		(width 0.1143)
		(layer "In4.Cu")
		(net "P3E_CPU0_PE3_OCP_TXN<8>")
	)
	(segment
		(start 427.424596 -132.442458)
		(end 430.552352 -131.107688)
		(width 0.1143)
		(layer "In4.Cu")
		(net "P3E_CPU0_PE3_OCP_TXN<8>")
	)
	(segment
		(start 389.279384 -137.047986)
		(end 389.61568 -137.114788)
		(width 0.1143)
		(layer "In4.Cu")
		(net "P3E_CPU0_PE3_OCP_TXN<8>")
	)
	(segment
		(start 423.353992 -132.7531)
		(end 425.67606 -132.07365)
		(width 0.1143)
		(layer "In4.Cu")
		(net "P3E_CPU0_PE3_OCP_TXN<8>")
	)
	(segment
		(start 370.847366 -136.29259)
		(end 372.772178 -136.696196)
		(width 0.1143)
		(layer "In4.Cu")
		(net "P3E_CPU0_PE3_OCP_TXN<8>")
	)
	(segment
		(start 365.952532 -132.506212)
		(end 367.42878 -134.464806)
		(width 0.1143)
		(layer "In4.Cu")
		(net "P3E_CPU0_PE3_OCP_TXN<8>")
	)
	(segment
		(start 358.312466 -129.075434)
		(end 358.540304 -129.024126)
		(width 0.1143)
		(layer "In4.Cu")
		(net "P3E_CPU0_PE3_OCP_TXN<8>")
	)
	(segment
		(start 438.55132 -130.269996)
		(end 438.682638 -129.953258)
		(width 0.1143)
		(layer "In4.Cu")
		(net "P3E_CPU0_PE3_OCP_TXN<8>")
	)
	(segment
		(start 357.112062 -128.122172)
		(end 357.16337 -128.349756)
		(width 0.1143)
		(layer "In4.Cu")
		(net "P3E_CPU0_PE3_OCP_TXN<8>")
	)
	(segment
		(start 377.340876 -138.110468)
		(end 378.535946 -137.232644)
		(width 0.1143)
		(layer "In4.Cu")
		(net "P3E_CPU0_PE3_OCP_TXN<8>")
	)
	(segment
		(start 430.552352 -131.107688)
		(end 432.87696 -131.573524)
		(width 0.1143)
		(layer "In4.Cu")
		(net "P3E_CPU0_PE3_OCP_TXN<8>")
	)
	(segment
		(start 421.727884 -133.996176)
		(end 423.353992 -132.7531)
		(width 0.1143)
		(layer "In4.Cu")
		(net "P3E_CPU0_PE3_OCP_TXN<8>")
	)
	(segment
		(start 303.876456 -97.80524)
		(end 303.876456 -97.804986)
		(width 0.0889)
		(layer "In11.Cu")
		(net "P3E_CPU0_PE3_OCP_TXN<8>")
	)
	(segment
		(start 307.8226 -96.393)
		(end 307.213 -96.393)
		(width 0.0889)
		(layer "In11.Cu")
		(net "P3E_CPU0_PE3_OCP_TXN<8>")
	)
	(segment
		(start 330.12253 -113.824004)
		(end 328.570336 -113.18113)
		(width 0.1143)
		(layer "In11.Cu")
		(net "P3E_CPU0_PE3_OCP_TXN<8>")
	)
	(segment
		(start 341.935308 -115.7224)
		(end 340.849712 -114.636804)
		(width 0.1143)
		(layer "In11.Cu")
		(net "P3E_CPU0_PE3_OCP_TXN<8>")
	)
	(segment
		(start 354.271072 -115.829588)
		(end 353.627944 -115.829588)
		(width 0.1143)
		(layer "In11.Cu")
		(net "P3E_CPU0_PE3_OCP_TXN<8>")
	)
	(segment
		(start 330.922884 -113.98377)
		(end 330.12253 -113.824004)
		(width 0.1143)
		(layer "In11.Cu")
		(net "P3E_CPU0_PE3_OCP_TXN<8>")
	)
	(segment
		(start 303.957482 -97.94494)
		(end 303.876456 -97.80524)
		(width 0.0889)
		(layer "In11.Cu")
		(net "P3E_CPU0_PE3_OCP_TXN<8>")
	)
	(segment
		(start 354.42525 -116.220494)
		(end 354.42525 -115.983766)
		(width 0.1143)
		(layer "In11.Cu")
		(net "P3E_CPU0_PE3_OCP_TXN<8>")
	)
	(segment
		(start 305.29276 -98.100388)
		(end 304.159412 -98.100388)
		(width 0.0889)
		(layer "In11.Cu")
		(net "P3E_CPU0_PE3_OCP_TXN<8>")
	)
	(segment
		(start 340.849712 -114.636804)
		(end 340.392766 -114.44732)
		(width 0.1143)
		(layer "In11.Cu")
		(net "P3E_CPU0_PE3_OCP_TXN<8>")
	)
	(segment
		(start 328.570336 -113.18113)
		(end 328.139552 -112.634522)
		(width 0.1143)
		(layer "In11.Cu")
		(net "P3E_CPU0_PE3_OCP_TXN<8>")
	)
	(segment
		(start 328.139552 -112.634522)
		(end 328.139298 -112.634014)
		(width 0.1143)
		(layer "In11.Cu")
		(net "P3E_CPU0_PE3_OCP_TXN<8>")
	)
	(segment
		(start 340.392766 -114.44732)
		(end 338.7344 -114.44732)
		(width 0.1143)
		(layer "In11.Cu")
		(net "P3E_CPU0_PE3_OCP_TXN<8>")
	)
	(segment
		(start 303.547272 -97.605088)
		(end 303.511966 -97.605088)
		(width 0.0889)
		(layer "In11.Cu")
		(net "P3E_CPU0_PE3_OCP_TXN<8>")
	)
	(segment
		(start 332.165706 -113.68278)
		(end 330.922884 -113.98377)
		(width 0.1143)
		(layer "In11.Cu")
		(net "P3E_CPU0_PE3_OCP_TXN<8>")
	)
	(segment
		(start 353.520756 -115.7224)
		(end 341.935308 -115.7224)
		(width 0.1143)
		(layer "In11.Cu")
		(net "P3E_CPU0_PE3_OCP_TXN<8>")
	)
	(segment
		(start 308.350158 -96.920558)
		(end 307.8226 -96.393)
		(width 0.0889)
		(layer "In11.Cu")
		(net "P3E_CPU0_PE3_OCP_TXN<8>")
	)
	(segment
		(start 335.496408 -113.799366)
		(end 334.122014 -114.074194)
		(width 0.1143)
		(layer "In11.Cu")
		(net "P3E_CPU0_PE3_OCP_TXN<8>")
	)
	(segment
		(start 307.213 -96.393)
		(end 306.903374 -96.489774)
		(width 0.0889)
		(layer "In11.Cu")
		(net "P3E_CPU0_PE3_OCP_TXN<8>")
	)
	(segment
		(start 314.339986 -104.38257)
		(end 308.350158 -97.005648)
		(width 0.1143)
		(layer "In11.Cu")
		(net "P3E_CPU0_PE3_OCP_TXN<8>")
	)
	(segment
		(start 326.77354 -109.5375)
		(end 322.614036 -107.81284)
		(width 0.1143)
		(layer "In11.Cu")
		(net "P3E_CPU0_PE3_OCP_TXN<8>")
	)
	(segment
		(start 322.614036 -107.81284)
		(end 322.613782 -107.81284)
		(width 0.1143)
		(layer "In11.Cu")
		(net "P3E_CPU0_PE3_OCP_TXN<8>")
	)
	(segment
		(start 304.159412 -98.100388)
		(end 303.957482 -97.94494)
		(width 0.0889)
		(layer "In11.Cu")
		(net "P3E_CPU0_PE3_OCP_TXN<8>")
	)
	(segment
		(start 338.7344 -114.44732)
		(end 335.496408 -113.799366)
		(width 0.1143)
		(layer "In11.Cu")
		(net "P3E_CPU0_PE3_OCP_TXN<8>")
	)
	(segment
		(start 327.727056 -112.111282)
		(end 326.77354 -109.5375)
		(width 0.1143)
		(layer "In11.Cu")
		(net "P3E_CPU0_PE3_OCP_TXN<8>")
	)
	(segment
		(start 353.627944 -115.829588)
		(end 353.520756 -115.7224)
		(width 0.1143)
		(layer "In11.Cu")
		(net "P3E_CPU0_PE3_OCP_TXN<8>")
	)
	(segment
		(start 334.122014 -114.074194)
		(end 332.165706 -113.68278)
		(width 0.1143)
		(layer "In11.Cu")
		(net "P3E_CPU0_PE3_OCP_TXN<8>")
	)
	(segment
		(start 308.350158 -97.005648)
		(end 308.350158 -96.920558)
		(width 0.0889)
		(layer "In11.Cu")
		(net "P3E_CPU0_PE3_OCP_TXN<8>")
	)
	(segment
		(start 306.903374 -96.489774)
		(end 305.29276 -98.100388)
		(width 0.0889)
		(layer "In11.Cu")
		(net "P3E_CPU0_PE3_OCP_TXN<8>")
	)
	(segment
		(start 328.139298 -112.634014)
		(end 327.727056 -112.111282)
		(width 0.1143)
		(layer "In11.Cu")
		(net "P3E_CPU0_PE3_OCP_TXN<8>")
	)
	(segment
		(start 354.42525 -115.983766)
		(end 354.271072 -115.829588)
		(width 0.1143)
		(layer "In11.Cu")
		(net "P3E_CPU0_PE3_OCP_TXN<8>")
	)
	(segment
		(start 322.613782 -107.81284)
		(end 314.339986 -104.38257)
		(width 0.1143)
		(layer "In11.Cu")
		(net "P3E_CPU0_PE3_OCP_TXN<8>")
	)
	(arc
		(start 303.876456 -97.804986)
		(mid 303.737463 -97.662906)
		(end 303.547272 -97.605088)
		(width 0.0889)
		(layer "In11.Cu")
		(net "P3E_CPU0_PE3_OCP_TXN<8>")
	)
	(arc
		(start 302.9839 -97.241106)
		(mid 302.830233 -96.878889)
		(end 302.671226 -96.518984)
		(width 0.0889)
		(layer "In11.Cu")
		(net "P3E_CPU0_PE3_OCP_TXN<8>")
	)
	(arc
		(start 303.511966 -97.605088)
		(mid 303.194285 -97.500937)
		(end 302.9839 -97.241106)
		(width 0.0889)
		(layer "In11.Cu")
		(net "P3E_CPU0_PE3_OCP_TXN<8>")
	)
	(segment
		(start 301.241206 -98.005138)
		(end 301.812706 -98.005138)
		(width 0.1143)
		(layer "F.Cu")
		(net "P3E_CPU0_PE3_OCP_TXN<7>")
	)
	(via
		(at 441.574936 -53.754274)
		(size 0.508)
		(drill 0.254)
		(layers "F.Cu" "B.Cu")
		(net "P3E_CPU0_PE3_OCP_TXN<7>")
	)
	(via
		(at 301.812706 -98.005138)
		(size 0.508)
		(drill 0.254)
		(layers "F.Cu" "B.Cu")
		(net "P3E_CPU0_PE3_OCP_TXN<7>")
	)
	(segment
		(start 441.3504 -52.2986)
		(end 441.3504 -52.703476)
		(width 0.1143)
		(layer "B.Cu")
		(net "P3E_CPU0_PE3_OCP_TXN<7>")
	)
	(segment
		(start 441.02655 -53.027326)
		(end 441.02655 -53.205888)
		(width 0.1143)
		(layer "B.Cu")
		(net "P3E_CPU0_PE3_OCP_TXN<7>")
	)
	(segment
		(start 441.3504 -52.703476)
		(end 441.02655 -53.027326)
		(width 0.1143)
		(layer "B.Cu")
		(net "P3E_CPU0_PE3_OCP_TXN<7>")
	)
	(segment
		(start 441.02655 -53.205888)
		(end 441.574936 -53.754274)
		(width 0.1143)
		(layer "B.Cu")
		(net "P3E_CPU0_PE3_OCP_TXN<7>")
	)
	(segment
		(start 303.455832 -98.616008)
		(end 302.836326 -98.359214)
		(width 0.0889)
		(layer "In4.Cu")
		(net "P3E_CPU0_PE3_OCP_TXN<7>")
	)
	(segment
		(start 353.830128 -62.591188)
		(end 351.471738 -62.041532)
		(width 0.1143)
		(layer "In4.Cu")
		(net "P3E_CPU0_PE3_OCP_TXN<7>")
	)
	(segment
		(start 389.325612 -53.428646)
		(end 388.779766 -52.8828)
		(width 0.1143)
		(layer "In4.Cu")
		(net "P3E_CPU0_PE3_OCP_TXN<7>")
	)
	(segment
		(start 337.909154 -63.207392)
		(end 334.365346 -62.38621)
		(width 0.1143)
		(layer "In4.Cu")
		(net "P3E_CPU0_PE3_OCP_TXN<7>")
	)
	(segment
		(start 390.82345 -53.428646)
		(end 389.325612 -53.428646)
		(width 0.1143)
		(layer "In4.Cu")
		(net "P3E_CPU0_PE3_OCP_TXN<7>")
	)
	(segment
		(start 369.62969 -52.6923)
		(end 367.83137 -54.49062)
		(width 0.1143)
		(layer "In4.Cu")
		(net "P3E_CPU0_PE3_OCP_TXN<7>")
	)
	(segment
		(start 440.506358 -54.8259)
		(end 437.127142 -54.8259)
		(width 0.1143)
		(layer "In4.Cu")
		(net "P3E_CPU0_PE3_OCP_TXN<7>")
	)
	(segment
		(start 424.080432 -55.945532)
		(end 419.921436 -55.945532)
		(width 0.1143)
		(layer "In4.Cu")
		(net "P3E_CPU0_PE3_OCP_TXN<7>")
	)
	(segment
		(start 355.209348 -62.315344)
		(end 353.830128 -62.591188)
		(width 0.1143)
		(layer "In4.Cu")
		(net "P3E_CPU0_PE3_OCP_TXN<7>")
	)
	(segment
		(start 302.19523 -97.860104)
		(end 302.105822 -97.835974)
		(width 0.0889)
		(layer "In4.Cu")
		(net "P3E_CPU0_PE3_OCP_TXN<7>")
	)
	(segment
		(start 333.448406 -62.564772)
		(end 331.75321 -63.661798)
		(width 0.1143)
		(layer "In4.Cu")
		(net "P3E_CPU0_PE3_OCP_TXN<7>")
	)
	(segment
		(start 407.613612 -56.166766)
		(end 407.023062 -56.166766)
		(width 0.1143)
		(layer "In4.Cu")
		(net "P3E_CPU0_PE3_OCP_TXN<7>")
	)
	(segment
		(start 371.13718 -52.6923)
		(end 369.62969 -52.6923)
		(width 0.1143)
		(layer "In4.Cu")
		(net "P3E_CPU0_PE3_OCP_TXN<7>")
	)
	(segment
		(start 377.908566 -51.550824)
		(end 377.259342 -50.9016)
		(width 0.1143)
		(layer "In4.Cu")
		(net "P3E_CPU0_PE3_OCP_TXN<7>")
	)
	(segment
		(start 384.472434 -51.550824)
		(end 377.908566 -51.550824)
		(width 0.1143)
		(layer "In4.Cu")
		(net "P3E_CPU0_PE3_OCP_TXN<7>")
	)
	(segment
		(start 307.3146 -97.5995)
		(end 306.901342 -97.5995)
		(width 0.0889)
		(layer "In4.Cu")
		(net "P3E_CPU0_PE3_OCP_TXN<7>")
	)
	(segment
		(start 372.92788 -50.9016)
		(end 371.13718 -52.6923)
		(width 0.1143)
		(layer "In4.Cu")
		(net "P3E_CPU0_PE3_OCP_TXN<7>")
	)
	(segment
		(start 367.83137 -54.49062)
		(end 364.496604 -54.49062)
		(width 0.1143)
		(layer "In4.Cu")
		(net "P3E_CPU0_PE3_OCP_TXN<7>")
	)
	(segment
		(start 403.243034 -54.3179)
		(end 391.712704 -54.3179)
		(width 0.1143)
		(layer "In4.Cu")
		(net "P3E_CPU0_PE3_OCP_TXN<7>")
	)
	(segment
		(start 387.2992 -52.8828)
		(end 385.4958 -51.0794)
		(width 0.1143)
		(layer "In4.Cu")
		(net "P3E_CPU0_PE3_OCP_TXN<7>")
	)
	(segment
		(start 307.387498 -97.6503)
		(end 307.3654 -97.6503)
		(width 0.0889)
		(layer "In4.Cu")
		(net "P3E_CPU0_PE3_OCP_TXN<7>")
	)
	(segment
		(start 302.105822 -97.835974)
		(end 301.812706 -98.005138)
		(width 0.0889)
		(layer "In4.Cu")
		(net "P3E_CPU0_PE3_OCP_TXN<7>")
	)
	(segment
		(start 348.666816 -62.045088)
		(end 347.182186 -62.333632)
		(width 0.1143)
		(layer "In4.Cu")
		(net "P3E_CPU0_PE3_OCP_TXN<7>")
	)
	(segment
		(start 384.943858 -51.0794)
		(end 384.472434 -51.550824)
		(width 0.1143)
		(layer "In4.Cu")
		(net "P3E_CPU0_PE3_OCP_TXN<7>")
	)
	(segment
		(start 331.75321 -63.661798)
		(end 325.877174 -72.204326)
		(width 0.1143)
		(layer "In4.Cu")
		(net "P3E_CPU0_PE3_OCP_TXN<7>")
	)
	(segment
		(start 428.710852 -53.34381)
		(end 427.175676 -54.878986)
		(width 0.1143)
		(layer "In4.Cu")
		(net "P3E_CPU0_PE3_OCP_TXN<7>")
	)
	(segment
		(start 344.335354 -62.359286)
		(end 343.398602 -62.140338)
		(width 0.1143)
		(layer "In4.Cu")
		(net "P3E_CPU0_PE3_OCP_TXN<7>")
	)
	(segment
		(start 404.704296 -53.848)
		(end 403.712934 -53.848)
		(width 0.1143)
		(layer "In4.Cu")
		(net "P3E_CPU0_PE3_OCP_TXN<7>")
	)
	(segment
		(start 347.182186 -62.333632)
		(end 345.94546 -62.04585)
		(width 0.1143)
		(layer "In4.Cu")
		(net "P3E_CPU0_PE3_OCP_TXN<7>")
	)
	(segment
		(start 425.146978 -54.878986)
		(end 424.080432 -55.945532)
		(width 0.1143)
		(layer "In4.Cu")
		(net "P3E_CPU0_PE3_OCP_TXN<7>")
	)
	(segment
		(start 388.779766 -52.8828)
		(end 387.2992 -52.8828)
		(width 0.1143)
		(layer "In4.Cu")
		(net "P3E_CPU0_PE3_OCP_TXN<7>")
	)
	(segment
		(start 441.0583 -54.0004)
		(end 441.0583 -54.273958)
		(width 0.1143)
		(layer "In4.Cu")
		(net "P3E_CPU0_PE3_OCP_TXN<7>")
	)
	(segment
		(start 441.574936 -53.754274)
		(end 441.304426 -53.754274)
		(width 0.1143)
		(layer "In4.Cu")
		(net "P3E_CPU0_PE3_OCP_TXN<7>")
	)
	(segment
		(start 403.712934 -53.848)
		(end 403.243034 -54.3179)
		(width 0.1143)
		(layer "In4.Cu")
		(net "P3E_CPU0_PE3_OCP_TXN<7>")
	)
	(segment
		(start 427.175676 -54.878986)
		(end 425.146978 -54.878986)
		(width 0.1143)
		(layer "In4.Cu")
		(net "P3E_CPU0_PE3_OCP_TXN<7>")
	)
	(segment
		(start 307.3654 -97.6503)
		(end 307.3146 -97.5995)
		(width 0.0889)
		(layer "In4.Cu")
		(net "P3E_CPU0_PE3_OCP_TXN<7>")
	)
	(segment
		(start 351.471738 -62.041532)
		(end 349.934276 -62.341506)
		(width 0.1143)
		(layer "In4.Cu")
		(net "P3E_CPU0_PE3_OCP_TXN<7>")
	)
	(segment
		(start 349.934276 -62.341506)
		(end 348.666816 -62.045088)
		(width 0.1143)
		(layer "In4.Cu")
		(net "P3E_CPU0_PE3_OCP_TXN<7>")
	)
	(segment
		(start 391.712704 -54.3179)
		(end 390.82345 -53.428646)
		(width 0.1143)
		(layer "In4.Cu")
		(net "P3E_CPU0_PE3_OCP_TXN<7>")
	)
	(segment
		(start 435.645306 -53.34381)
		(end 428.710852 -53.34381)
		(width 0.1143)
		(layer "In4.Cu")
		(net "P3E_CPU0_PE3_OCP_TXN<7>")
	)
	(segment
		(start 408.2288 -56.781954)
		(end 407.613612 -56.166766)
		(width 0.1143)
		(layer "In4.Cu")
		(net "P3E_CPU0_PE3_OCP_TXN<7>")
	)
	(segment
		(start 441.0583 -54.273958)
		(end 440.506358 -54.8259)
		(width 0.1143)
		(layer "In4.Cu")
		(net "P3E_CPU0_PE3_OCP_TXN<7>")
	)
	(segment
		(start 411.117288 -56.12257)
		(end 410.457904 -56.781954)
		(width 0.1143)
		(layer "In4.Cu")
		(net "P3E_CPU0_PE3_OCP_TXN<7>")
	)
	(segment
		(start 302.836326 -98.359214)
		(end 302.56861 -98.091498)
		(width 0.0889)
		(layer "In4.Cu")
		(net "P3E_CPU0_PE3_OCP_TXN<7>")
	)
	(segment
		(start 359.16489 -59.822588)
		(end 355.209348 -62.315344)
		(width 0.1143)
		(layer "In4.Cu")
		(net "P3E_CPU0_PE3_OCP_TXN<7>")
	)
	(segment
		(start 419.744398 -56.12257)
		(end 411.117288 -56.12257)
		(width 0.1143)
		(layer "In4.Cu")
		(net "P3E_CPU0_PE3_OCP_TXN<7>")
	)
	(segment
		(start 307.835554 -97.6503)
		(end 307.387498 -97.6503)
		(width 0.1143)
		(layer "In4.Cu")
		(net "P3E_CPU0_PE3_OCP_TXN<7>")
	)
	(segment
		(start 407.023062 -56.166766)
		(end 404.704296 -53.848)
		(width 0.1143)
		(layer "In4.Cu")
		(net "P3E_CPU0_PE3_OCP_TXN<7>")
	)
	(segment
		(start 437.127142 -54.8259)
		(end 435.645306 -53.34381)
		(width 0.1143)
		(layer "In4.Cu")
		(net "P3E_CPU0_PE3_OCP_TXN<7>")
	)
	(segment
		(start 334.365346 -62.38621)
		(end 333.448406 -62.564772)
		(width 0.1143)
		(layer "In4.Cu")
		(net "P3E_CPU0_PE3_OCP_TXN<7>")
	)
	(segment
		(start 385.4958 -51.0794)
		(end 384.943858 -51.0794)
		(width 0.1143)
		(layer "In4.Cu")
		(net "P3E_CPU0_PE3_OCP_TXN<7>")
	)
	(segment
		(start 320.641472 -84.844382)
		(end 307.835554 -97.6503)
		(width 0.1143)
		(layer "In4.Cu")
		(net "P3E_CPU0_PE3_OCP_TXN<7>")
	)
	(segment
		(start 343.398602 -62.140338)
		(end 337.909154 -63.207392)
		(width 0.1143)
		(layer "In4.Cu")
		(net "P3E_CPU0_PE3_OCP_TXN<7>")
	)
	(segment
		(start 364.496604 -54.49062)
		(end 359.16489 -59.822588)
		(width 0.1143)
		(layer "In4.Cu")
		(net "P3E_CPU0_PE3_OCP_TXN<7>")
	)
	(segment
		(start 305.795172 -98.191066)
		(end 303.659032 -98.616008)
		(width 0.0889)
		(layer "In4.Cu")
		(net "P3E_CPU0_PE3_OCP_TXN<7>")
	)
	(segment
		(start 306.901342 -97.5995)
		(end 305.795172 -98.191066)
		(width 0.0889)
		(layer "In4.Cu")
		(net "P3E_CPU0_PE3_OCP_TXN<7>")
	)
	(segment
		(start 410.457904 -56.781954)
		(end 408.2288 -56.781954)
		(width 0.1143)
		(layer "In4.Cu")
		(net "P3E_CPU0_PE3_OCP_TXN<7>")
	)
	(segment
		(start 441.304426 -53.754274)
		(end 441.0583 -54.0004)
		(width 0.1143)
		(layer "In4.Cu")
		(net "P3E_CPU0_PE3_OCP_TXN<7>")
	)
	(segment
		(start 345.94546 -62.04585)
		(end 344.335354 -62.359286)
		(width 0.1143)
		(layer "In4.Cu")
		(net "P3E_CPU0_PE3_OCP_TXN<7>")
	)
	(segment
		(start 377.259342 -50.9016)
		(end 372.92788 -50.9016)
		(width 0.1143)
		(layer "In4.Cu")
		(net "P3E_CPU0_PE3_OCP_TXN<7>")
	)
	(segment
		(start 303.659032 -98.616008)
		(end 303.455832 -98.616008)
		(width 0.0889)
		(layer "In4.Cu")
		(net "P3E_CPU0_PE3_OCP_TXN<7>")
	)
	(segment
		(start 419.921436 -55.945532)
		(end 419.744398 -56.12257)
		(width 0.1143)
		(layer "In4.Cu")
		(net "P3E_CPU0_PE3_OCP_TXN<7>")
	)
	(segment
		(start 325.877174 -72.204326)
		(end 320.641472 -84.844382)
		(width 0.1143)
		(layer "In4.Cu")
		(net "P3E_CPU0_PE3_OCP_TXN<7>")
	)
	(arc
		(start 302.56861 -98.091498)
		(mid 302.359646 -98.011757)
		(end 302.19523 -97.860104)
		(width 0.0889)
		(layer "In4.Cu")
		(net "P3E_CPU0_PE3_OCP_TXN<7>")
	)
	(segment
		(start 301.241206 -98.995738)
		(end 301.812706 -98.995738)
		(width 0.1143)
		(layer "F.Cu")
		(net "P3E_CPU0_PE3_OCP_TXN<6>")
	)
	(via
		(at 301.812706 -98.995738)
		(size 0.508)
		(drill 0.254)
		(layers "F.Cu" "B.Cu")
		(net "P3E_CPU0_PE3_OCP_TXN<6>")
	)
	(via
		(at 444.78575 -53.754274)
		(size 0.508)
		(drill 0.254)
		(layers "F.Cu" "B.Cu")
		(net "P3E_CPU0_PE3_OCP_TXN<6>")
	)
	(segment
		(start 444.262256 -53.23078)
		(end 444.78575 -53.754274)
		(width 0.1143)
		(layer "B.Cu")
		(net "P3E_CPU0_PE3_OCP_TXN<6>")
	)
	(segment
		(start 444.649606 -52.74691)
		(end 444.535306 -52.86121)
		(width 0.1143)
		(layer "B.Cu")
		(net "P3E_CPU0_PE3_OCP_TXN<6>")
	)
	(segment
		(start 444.649606 -52.342034)
		(end 444.649606 -52.74691)
		(width 0.1143)
		(layer "B.Cu")
		(net "P3E_CPU0_PE3_OCP_TXN<6>")
	)
	(segment
		(start 444.535306 -52.86121)
		(end 444.376556 -52.86121)
		(width 0.1143)
		(layer "B.Cu")
		(net "P3E_CPU0_PE3_OCP_TXN<6>")
	)
	(segment
		(start 444.376556 -52.86121)
		(end 444.262256 -52.97551)
		(width 0.1143)
		(layer "B.Cu")
		(net "P3E_CPU0_PE3_OCP_TXN<6>")
	)
	(segment
		(start 444.262256 -52.97551)
		(end 444.262256 -53.23078)
		(width 0.1143)
		(layer "B.Cu")
		(net "P3E_CPU0_PE3_OCP_TXN<6>")
	)
	(segment
		(start 305.237388 -99.702112)
		(end 304.944018 -99.702112)
		(width 0.0889)
		(layer "In4.Cu")
		(net "P3E_CPU0_PE3_OCP_TXN<6>")
	)
	(segment
		(start 307.473604 -98.92665)
		(end 307.47335 -98.92665)
		(width 0.1143)
		(layer "In4.Cu")
		(net "P3E_CPU0_PE3_OCP_TXN<6>")
	)
	(segment
		(start 304.018442 -99.31908)
		(end 303.772062 -99.217226)
		(width 0.0889)
		(layer "In4.Cu")
		(net "P3E_CPU0_PE3_OCP_TXN<6>")
	)
	(segment
		(start 425.398946 -55.525416)
		(end 424.34383 -56.580532)
		(width 0.1143)
		(layer "In4.Cu")
		(net "P3E_CPU0_PE3_OCP_TXN<6>")
	)
	(segment
		(start 377.645168 -52.185824)
		(end 376.995944 -51.5366)
		(width 0.1143)
		(layer "In4.Cu")
		(net "P3E_CPU0_PE3_OCP_TXN<6>")
	)
	(segment
		(start 414.690306 -58.20918)
		(end 410.668978 -58.20918)
		(width 0.1143)
		(layer "In4.Cu")
		(net "P3E_CPU0_PE3_OCP_TXN<6>")
	)
	(segment
		(start 385.849622 -53.875178)
		(end 383.78892 -53.875178)
		(width 0.1143)
		(layer "In4.Cu")
		(net "P3E_CPU0_PE3_OCP_TXN<6>")
	)
	(segment
		(start 334.237076 -63.095378)
		(end 333.694024 -63.201042)
		(width 0.1143)
		(layer "In4.Cu")
		(net "P3E_CPU0_PE3_OCP_TXN<6>")
	)
	(segment
		(start 301.498508 -98.747834)
		(end 301.53991 -98.90252)
		(width 0.0889)
		(layer "In4.Cu")
		(net "P3E_CPU0_PE3_OCP_TXN<6>")
	)
	(segment
		(start 383.78892 -53.875178)
		(end 382.099566 -52.185824)
		(width 0.1143)
		(layer "In4.Cu")
		(net "P3E_CPU0_PE3_OCP_TXN<6>")
	)
	(segment
		(start 307.231288 -98.926904)
		(end 307.231034 -98.92665)
		(width 0.1143)
		(layer "In4.Cu")
		(net "P3E_CPU0_PE3_OCP_TXN<6>")
	)
	(segment
		(start 428.47387 -55.525416)
		(end 425.398946 -55.525416)
		(width 0.1143)
		(layer "In4.Cu")
		(net "P3E_CPU0_PE3_OCP_TXN<6>")
	)
	(segment
		(start 303.772062 -99.217226)
		(end 302.86198 -99.2378)
		(width 0.0889)
		(layer "In4.Cu")
		(net "P3E_CPU0_PE3_OCP_TXN<6>")
	)
	(segment
		(start 337.701128 -63.898018)
		(end 334.237076 -63.095378)
		(width 0.1143)
		(layer "In4.Cu")
		(net "P3E_CPU0_PE3_OCP_TXN<6>")
	)
	(segment
		(start 444.2968 -54.746906)
		(end 443.290706 -55.753)
		(width 0.1143)
		(layer "In4.Cu")
		(net "P3E_CPU0_PE3_OCP_TXN<6>")
	)
	(segment
		(start 302.135794 -98.595688)
		(end 301.79772 -98.595688)
		(width 0.0889)
		(layer "In4.Cu")
		(net "P3E_CPU0_PE3_OCP_TXN<6>")
	)
	(segment
		(start 351.463864 -62.693042)
		(end 349.926402 -62.993016)
		(width 0.1143)
		(layer "In4.Cu")
		(net "P3E_CPU0_PE3_OCP_TXN<6>")
	)
	(segment
		(start 390.400286 -54.063646)
		(end 389.062214 -54.063646)
		(width 0.1143)
		(layer "In4.Cu")
		(net "P3E_CPU0_PE3_OCP_TXN<6>")
	)
	(segment
		(start 382.099566 -52.185824)
		(end 377.645168 -52.185824)
		(width 0.1143)
		(layer "In4.Cu")
		(net "P3E_CPU0_PE3_OCP_TXN<6>")
	)
	(segment
		(start 302.777906 -99.2378)
		(end 302.135794 -98.595688)
		(width 0.0889)
		(layer "In4.Cu")
		(net "P3E_CPU0_PE3_OCP_TXN<6>")
	)
	(segment
		(start 307.15839 -98.87585)
		(end 306.26558 -98.87585)
		(width 0.0889)
		(layer "In4.Cu")
		(net "P3E_CPU0_PE3_OCP_TXN<6>")
	)
	(segment
		(start 304.42916 -99.489006)
		(end 304.313082 -99.537266)
		(width 0.0889)
		(layer "In4.Cu")
		(net "P3E_CPU0_PE3_OCP_TXN<6>")
	)
	(segment
		(start 326.441054 -72.545448)
		(end 321.198748 -85.201506)
		(width 0.1143)
		(layer "In4.Cu")
		(net "P3E_CPU0_PE3_OCP_TXN<6>")
	)
	(segment
		(start 391.314432 -54.977792)
		(end 390.400286 -54.063646)
		(width 0.1143)
		(layer "In4.Cu")
		(net "P3E_CPU0_PE3_OCP_TXN<6>")
	)
	(segment
		(start 349.926402 -62.993016)
		(end 348.658942 -62.696598)
		(width 0.1143)
		(layer "In4.Cu")
		(net "P3E_CPU0_PE3_OCP_TXN<6>")
	)
	(segment
		(start 344.32875 -63.010542)
		(end 343.391744 -62.791594)
		(width 0.1143)
		(layer "In4.Cu")
		(net "P3E_CPU0_PE3_OCP_TXN<6>")
	)
	(segment
		(start 436.94477 -55.753)
		(end 435.18074 -53.98897)
		(width 0.1143)
		(layer "In4.Cu")
		(net "P3E_CPU0_PE3_OCP_TXN<6>")
	)
	(segment
		(start 444.2968 -53.868574)
		(end 444.2968 -54.746906)
		(width 0.1143)
		(layer "In4.Cu")
		(net "P3E_CPU0_PE3_OCP_TXN<6>")
	)
	(segment
		(start 355.594666 -62.958218)
		(end 353.983544 -63.28029)
		(width 0.1143)
		(layer "In4.Cu")
		(net "P3E_CPU0_PE3_OCP_TXN<6>")
	)
	(segment
		(start 360.401108 -59.776614)
		(end 355.594666 -62.958218)
		(width 0.1143)
		(layer "In4.Cu")
		(net "P3E_CPU0_PE3_OCP_TXN<6>")
	)
	(segment
		(start 302.86198 -99.2378)
		(end 302.777906 -99.2378)
		(width 0.0889)
		(layer "In4.Cu")
		(net "P3E_CPU0_PE3_OCP_TXN<6>")
	)
	(segment
		(start 306.26558 -98.87585)
		(end 305.582066 -99.559364)
		(width 0.0889)
		(layer "In4.Cu")
		(net "P3E_CPU0_PE3_OCP_TXN<6>")
	)
	(segment
		(start 406.719024 -56.801766)
		(end 406.019508 -56.10225)
		(width 0.1143)
		(layer "In4.Cu")
		(net "P3E_CPU0_PE3_OCP_TXN<6>")
	)
	(segment
		(start 301.53991 -98.90252)
		(end 301.73676 -99.016058)
		(width 0.0889)
		(layer "In4.Cu")
		(net "P3E_CPU0_PE3_OCP_TXN<6>")
	)
	(segment
		(start 400.654012 -54.977792)
		(end 391.314432 -54.977792)
		(width 0.1143)
		(layer "In4.Cu")
		(net "P3E_CPU0_PE3_OCP_TXN<6>")
	)
	(segment
		(start 420.007796 -56.75757)
		(end 416.141916 -56.75757)
		(width 0.1143)
		(layer "In4.Cu")
		(net "P3E_CPU0_PE3_OCP_TXN<6>")
	)
	(segment
		(start 386.207 -53.5178)
		(end 385.849622 -53.875178)
		(width 0.1143)
		(layer "In4.Cu")
		(net "P3E_CPU0_PE3_OCP_TXN<6>")
	)
	(segment
		(start 409.889198 -57.4294)
		(end 407.977848 -57.4294)
		(width 0.1143)
		(layer "In4.Cu")
		(net "P3E_CPU0_PE3_OCP_TXN<6>")
	)
	(segment
		(start 348.658942 -62.696598)
		(end 347.175074 -62.984888)
		(width 0.1143)
		(layer "In4.Cu")
		(net "P3E_CPU0_PE3_OCP_TXN<6>")
	)
	(segment
		(start 407.977848 -57.4294)
		(end 407.350214 -56.801766)
		(width 0.1143)
		(layer "In4.Cu")
		(net "P3E_CPU0_PE3_OCP_TXN<6>")
	)
	(segment
		(start 321.198748 -85.201506)
		(end 307.473604 -98.92665)
		(width 0.1143)
		(layer "In4.Cu")
		(net "P3E_CPU0_PE3_OCP_TXN<6>")
	)
	(segment
		(start 307.47335 -98.92665)
		(end 307.473096 -98.926904)
		(width 0.1143)
		(layer "In4.Cu")
		(net "P3E_CPU0_PE3_OCP_TXN<6>")
	)
	(segment
		(start 389.062214 -54.063646)
		(end 388.516368 -53.5178)
		(width 0.1143)
		(layer "In4.Cu")
		(net "P3E_CPU0_PE3_OCP_TXN<6>")
	)
	(segment
		(start 376.995944 -51.5366)
		(end 373.191278 -51.5366)
		(width 0.1143)
		(layer "In4.Cu")
		(net "P3E_CPU0_PE3_OCP_TXN<6>")
	)
	(segment
		(start 332.187042 -64.192912)
		(end 326.441054 -72.545448)
		(width 0.1143)
		(layer "In4.Cu")
		(net "P3E_CPU0_PE3_OCP_TXN<6>")
	)
	(segment
		(start 333.694024 -63.201042)
		(end 332.187042 -64.192912)
		(width 0.1143)
		(layer "In4.Cu")
		(net "P3E_CPU0_PE3_OCP_TXN<6>")
	)
	(segment
		(start 401.917154 -56.240934)
		(end 400.654012 -54.977792)
		(width 0.1143)
		(layer "In4.Cu")
		(net "P3E_CPU0_PE3_OCP_TXN<6>")
	)
	(segment
		(start 307.20919 -98.92665)
		(end 307.15839 -98.87585)
		(width 0.0889)
		(layer "In4.Cu")
		(net "P3E_CPU0_PE3_OCP_TXN<6>")
	)
	(segment
		(start 407.350214 -56.801766)
		(end 406.719024 -56.801766)
		(width 0.1143)
		(layer "In4.Cu")
		(net "P3E_CPU0_PE3_OCP_TXN<6>")
	)
	(segment
		(start 443.290706 -55.753)
		(end 436.94477 -55.753)
		(width 0.1143)
		(layer "In4.Cu")
		(net "P3E_CPU0_PE3_OCP_TXN<6>")
	)
	(segment
		(start 424.34383 -56.580532)
		(end 420.184834 -56.580532)
		(width 0.1143)
		(layer "In4.Cu")
		(net "P3E_CPU0_PE3_OCP_TXN<6>")
	)
	(segment
		(start 388.516368 -53.5178)
		(end 386.207 -53.5178)
		(width 0.1143)
		(layer "In4.Cu")
		(net "P3E_CPU0_PE3_OCP_TXN<6>")
	)
	(segment
		(start 307.231034 -98.92665)
		(end 307.20919 -98.92665)
		(width 0.0889)
		(layer "In4.Cu")
		(net "P3E_CPU0_PE3_OCP_TXN<6>")
	)
	(segment
		(start 416.141916 -56.75757)
		(end 414.690306 -58.20918)
		(width 0.1143)
		(layer "In4.Cu")
		(net "P3E_CPU0_PE3_OCP_TXN<6>")
	)
	(segment
		(start 347.175074 -62.984888)
		(end 345.938348 -62.697106)
		(width 0.1143)
		(layer "In4.Cu")
		(net "P3E_CPU0_PE3_OCP_TXN<6>")
	)
	(segment
		(start 301.73676 -99.016058)
		(end 301.812706 -98.995738)
		(width 0.0889)
		(layer "In4.Cu")
		(net "P3E_CPU0_PE3_OCP_TXN<6>")
	)
	(segment
		(start 304.313082 -99.537266)
		(end 304.066702 -99.435412)
		(width 0.0889)
		(layer "In4.Cu")
		(net "P3E_CPU0_PE3_OCP_TXN<6>")
	)
	(segment
		(start 353.983544 -63.28029)
		(end 351.463864 -62.693042)
		(width 0.1143)
		(layer "In4.Cu")
		(net "P3E_CPU0_PE3_OCP_TXN<6>")
	)
	(segment
		(start 373.191278 -51.5366)
		(end 371.400578 -53.3273)
		(width 0.1143)
		(layer "In4.Cu")
		(net "P3E_CPU0_PE3_OCP_TXN<6>")
	)
	(segment
		(start 368.026188 -55.1942)
		(end 364.983268 -55.1942)
		(width 0.1143)
		(layer "In4.Cu")
		(net "P3E_CPU0_PE3_OCP_TXN<6>")
	)
	(segment
		(start 430.010316 -53.98897)
		(end 428.47387 -55.525416)
		(width 0.1143)
		(layer "In4.Cu")
		(net "P3E_CPU0_PE3_OCP_TXN<6>")
	)
	(segment
		(start 307.473096 -98.926904)
		(end 307.231288 -98.926904)
		(width 0.1143)
		(layer "In4.Cu")
		(net "P3E_CPU0_PE3_OCP_TXN<6>")
	)
	(segment
		(start 420.184834 -56.580532)
		(end 420.007796 -56.75757)
		(width 0.1143)
		(layer "In4.Cu")
		(net "P3E_CPU0_PE3_OCP_TXN<6>")
	)
	(segment
		(start 444.4111 -53.754274)
		(end 444.2968 -53.868574)
		(width 0.1143)
		(layer "In4.Cu")
		(net "P3E_CPU0_PE3_OCP_TXN<6>")
	)
	(segment
		(start 444.78575 -53.754274)
		(end 444.4111 -53.754274)
		(width 0.1143)
		(layer "In4.Cu")
		(net "P3E_CPU0_PE3_OCP_TXN<6>")
	)
	(segment
		(start 435.18074 -53.98897)
		(end 430.010316 -53.98897)
		(width 0.1143)
		(layer "In4.Cu")
		(net "P3E_CPU0_PE3_OCP_TXN<6>")
	)
	(segment
		(start 343.391744 -62.791594)
		(end 337.701128 -63.898018)
		(width 0.1143)
		(layer "In4.Cu")
		(net "P3E_CPU0_PE3_OCP_TXN<6>")
	)
	(segment
		(start 406.019508 -56.10225)
		(end 403.51075 -56.10225)
		(width 0.1143)
		(layer "In4.Cu")
		(net "P3E_CPU0_PE3_OCP_TXN<6>")
	)
	(segment
		(start 364.983268 -55.1942)
		(end 360.401108 -59.776614)
		(width 0.1143)
		(layer "In4.Cu")
		(net "P3E_CPU0_PE3_OCP_TXN<6>")
	)
	(segment
		(start 369.893088 -53.3273)
		(end 368.026188 -55.1942)
		(width 0.1143)
		(layer "In4.Cu")
		(net "P3E_CPU0_PE3_OCP_TXN<6>")
	)
	(segment
		(start 403.51075 -56.10225)
		(end 403.372066 -56.240934)
		(width 0.1143)
		(layer "In4.Cu")
		(net "P3E_CPU0_PE3_OCP_TXN<6>")
	)
	(segment
		(start 403.372066 -56.240934)
		(end 401.917154 -56.240934)
		(width 0.1143)
		(layer "In4.Cu")
		(net "P3E_CPU0_PE3_OCP_TXN<6>")
	)
	(segment
		(start 305.582066 -99.559364)
		(end 305.237388 -99.702112)
		(width 0.0889)
		(layer "In4.Cu")
		(net "P3E_CPU0_PE3_OCP_TXN<6>")
	)
	(segment
		(start 304.066702 -99.435412)
		(end 304.018442 -99.31908)
		(width 0.0889)
		(layer "In4.Cu")
		(net "P3E_CPU0_PE3_OCP_TXN<6>")
	)
	(segment
		(start 304.944018 -99.702112)
		(end 304.42916 -99.489006)
		(width 0.0889)
		(layer "In4.Cu")
		(net "P3E_CPU0_PE3_OCP_TXN<6>")
	)
	(segment
		(start 410.668978 -58.20918)
		(end 409.889198 -57.4294)
		(width 0.1143)
		(layer "In4.Cu")
		(net "P3E_CPU0_PE3_OCP_TXN<6>")
	)
	(segment
		(start 371.400578 -53.3273)
		(end 369.893088 -53.3273)
		(width 0.1143)
		(layer "In4.Cu")
		(net "P3E_CPU0_PE3_OCP_TXN<6>")
	)
	(segment
		(start 345.938348 -62.697106)
		(end 344.32875 -63.010542)
		(width 0.1143)
		(layer "In4.Cu")
		(net "P3E_CPU0_PE3_OCP_TXN<6>")
	)
	(arc
		(start 301.79772 -98.595688)
		(mid 301.631426 -98.638922)
		(end 301.498508 -98.747834)
		(width 0.0889)
		(layer "In4.Cu")
		(net "P3E_CPU0_PE3_OCP_TXN<6>")
	)
	(segment
		(start 299.524166 -99.986338)
		(end 300.095666 -99.986338)
		(width 0.1143)
		(layer "F.Cu")
		(net "P3E_CPU0_PE3_OCP_TXN<5>")
	)
	(via
		(at 300.095666 -99.986338)
		(size 0.508)
		(drill 0.254)
		(layers "F.Cu" "B.Cu")
		(net "P3E_CPU0_PE3_OCP_TXN<5>")
	)
	(via
		(at 447.98615 -53.754274)
		(size 0.508)
		(drill 0.254)
		(layers "F.Cu" "B.Cu")
		(net "P3E_CPU0_PE3_OCP_TXN<5>")
	)
	(segment
		(start 447.655188 -52.926234)
		(end 447.490342 -53.09108)
		(width 0.1143)
		(layer "B.Cu")
		(net "P3E_CPU0_PE3_OCP_TXN<5>")
	)
	(segment
		(start 447.813938 -52.926234)
		(end 447.655188 -52.926234)
		(width 0.1143)
		(layer "B.Cu")
		(net "P3E_CPU0_PE3_OCP_TXN<5>")
	)
	(segment
		(start 447.928238 -52.811934)
		(end 447.813938 -52.926234)
		(width 0.1143)
		(layer "B.Cu")
		(net "P3E_CPU0_PE3_OCP_TXN<5>")
	)
	(segment
		(start 447.490342 -53.09108)
		(end 447.490342 -53.258466)
		(width 0.1143)
		(layer "B.Cu")
		(net "P3E_CPU0_PE3_OCP_TXN<5>")
	)
	(segment
		(start 447.928238 -52.407058)
		(end 447.928238 -52.811934)
		(width 0.1143)
		(layer "B.Cu")
		(net "P3E_CPU0_PE3_OCP_TXN<5>")
	)
	(segment
		(start 447.490342 -53.258466)
		(end 447.98615 -53.754274)
		(width 0.1143)
		(layer "B.Cu")
		(net "P3E_CPU0_PE3_OCP_TXN<5>")
	)
	(segment
		(start 307.144674 -99.57562)
		(end 307.166772 -99.57562)
		(width 0.0889)
		(layer "In4.Cu")
		(net "P3E_CPU0_PE3_OCP_TXN<5>")
	)
	(segment
		(start 351.45599 -63.344552)
		(end 353.990148 -63.935864)
		(width 0.1143)
		(layer "In4.Cu")
		(net "P3E_CPU0_PE3_OCP_TXN<5>")
	)
	(segment
		(start 424.607228 -57.215532)
		(end 425.650152 -56.172608)
		(width 0.1143)
		(layer "In4.Cu")
		(net "P3E_CPU0_PE3_OCP_TXN<5>")
	)
	(segment
		(start 409.6258 -58.0644)
		(end 410.40558 -58.84418)
		(width 0.1143)
		(layer "In4.Cu")
		(net "P3E_CPU0_PE3_OCP_TXN<5>")
	)
	(segment
		(start 304.3555 -99.97186)
		(end 304.891948 -100.193856)
		(width 0.0889)
		(layer "In4.Cu")
		(net "P3E_CPU0_PE3_OCP_TXN<5>")
	)
	(segment
		(start 357.93426 -63.147194)
		(end 365.239554 -55.8419)
		(width 0.1143)
		(layer "In4.Cu")
		(net "P3E_CPU0_PE3_OCP_TXN<5>")
	)
	(segment
		(start 307.745384 -99.57562)
		(end 321.749166 -85.571838)
		(width 0.1143)
		(layer "In4.Cu")
		(net "P3E_CPU0_PE3_OCP_TXN<5>")
	)
	(segment
		(start 348.651068 -63.348108)
		(end 349.918528 -63.644526)
		(width 0.1143)
		(layer "In4.Cu")
		(net "P3E_CPU0_PE3_OCP_TXN<5>")
	)
	(segment
		(start 401.776692 -56.99887)
		(end 403.702774 -56.99887)
		(width 0.1143)
		(layer "In4.Cu")
		(net "P3E_CPU0_PE3_OCP_TXN<5>")
	)
	(segment
		(start 447.6115 -53.754274)
		(end 447.98615 -53.754274)
		(width 0.1143)
		(layer "In4.Cu")
		(net "P3E_CPU0_PE3_OCP_TXN<5>")
	)
	(segment
		(start 325.96328 -75.39863)
		(end 330.195174 -69.247258)
		(width 0.1143)
		(layer "In4.Cu")
		(net "P3E_CPU0_PE3_OCP_TXN<5>")
	)
	(segment
		(start 405.743918 -56.73725)
		(end 406.48382 -57.477152)
		(width 0.1143)
		(layer "In4.Cu")
		(net "P3E_CPU0_PE3_OCP_TXN<5>")
	)
	(segment
		(start 403.702774 -56.99887)
		(end 403.964394 -56.73725)
		(width 0.1143)
		(layer "In4.Cu")
		(net "P3E_CPU0_PE3_OCP_TXN<5>")
	)
	(segment
		(start 420.448232 -57.215532)
		(end 424.607228 -57.215532)
		(width 0.1143)
		(layer "In4.Cu")
		(net "P3E_CPU0_PE3_OCP_TXN<5>")
	)
	(segment
		(start 302.018446 -100.576888)
		(end 303.478692 -99.97186)
		(width 0.0889)
		(layer "In4.Cu")
		(net "P3E_CPU0_PE3_OCP_TXN<5>")
	)
	(segment
		(start 306.946046 -99.52482)
		(end 307.093874 -99.52482)
		(width 0.0889)
		(layer "In4.Cu")
		(net "P3E_CPU0_PE3_OCP_TXN<5>")
	)
	(segment
		(start 406.48382 -57.477152)
		(end 407.127202 -57.477152)
		(width 0.1143)
		(layer "In4.Cu")
		(net "P3E_CPU0_PE3_OCP_TXN<5>")
	)
	(segment
		(start 301.79899 -100.576888)
		(end 302.018446 -100.576888)
		(width 0.0889)
		(layer "In4.Cu")
		(net "P3E_CPU0_PE3_OCP_TXN<5>")
	)
	(segment
		(start 349.918528 -63.644526)
		(end 351.45599 -63.344552)
		(width 0.1143)
		(layer "In4.Cu")
		(net "P3E_CPU0_PE3_OCP_TXN<5>")
	)
	(segment
		(start 373.454676 -52.1716)
		(end 376.732546 -52.1716)
		(width 0.1143)
		(layer "In4.Cu")
		(net "P3E_CPU0_PE3_OCP_TXN<5>")
	)
	(segment
		(start 368.375692 -55.8419)
		(end 370.255292 -53.9623)
		(width 0.1143)
		(layer "In4.Cu")
		(net "P3E_CPU0_PE3_OCP_TXN<5>")
	)
	(segment
		(start 345.914218 -63.351918)
		(end 347.150944 -63.6397)
		(width 0.1143)
		(layer "In4.Cu")
		(net "P3E_CPU0_PE3_OCP_TXN<5>")
	)
	(segment
		(start 303.478692 -99.97186)
		(end 304.3555 -99.97186)
		(width 0.0889)
		(layer "In4.Cu")
		(net "P3E_CPU0_PE3_OCP_TXN<5>")
	)
	(segment
		(start 383.39395 -54.378606)
		(end 383.525522 -54.510178)
		(width 0.1143)
		(layer "In4.Cu")
		(net "P3E_CPU0_PE3_OCP_TXN<5>")
	)
	(segment
		(start 447.461894 -53.90388)
		(end 447.6115 -53.754274)
		(width 0.1143)
		(layer "In4.Cu")
		(net "P3E_CPU0_PE3_OCP_TXN<5>")
	)
	(segment
		(start 407.127202 -57.477152)
		(end 407.71445 -58.0644)
		(width 0.1143)
		(layer "In4.Cu")
		(net "P3E_CPU0_PE3_OCP_TXN<5>")
	)
	(segment
		(start 447.461894 -54.518052)
		(end 447.461894 -53.90388)
		(width 0.1143)
		(layer "In4.Cu")
		(net "P3E_CPU0_PE3_OCP_TXN<5>")
	)
	(segment
		(start 370.255292 -53.9623)
		(end 371.663976 -53.9623)
		(width 0.1143)
		(layer "In4.Cu")
		(net "P3E_CPU0_PE3_OCP_TXN<5>")
	)
	(segment
		(start 387.911594 -54.15661)
		(end 388.644384 -54.8894)
		(width 0.1143)
		(layer "In4.Cu")
		(net "P3E_CPU0_PE3_OCP_TXN<5>")
	)
	(segment
		(start 386.122926 -54.510178)
		(end 386.476494 -54.15661)
		(width 0.1143)
		(layer "In4.Cu")
		(net "P3E_CPU0_PE3_OCP_TXN<5>")
	)
	(segment
		(start 420.271194 -57.39257)
		(end 420.448232 -57.215532)
		(width 0.1143)
		(layer "In4.Cu")
		(net "P3E_CPU0_PE3_OCP_TXN<5>")
	)
	(segment
		(start 330.195174 -69.247258)
		(end 337.17738 -64.652144)
		(width 0.1143)
		(layer "In4.Cu")
		(net "P3E_CPU0_PE3_OCP_TXN<5>")
	)
	(segment
		(start 307.093874 -99.52482)
		(end 307.144674 -99.57562)
		(width 0.0889)
		(layer "In4.Cu")
		(net "P3E_CPU0_PE3_OCP_TXN<5>")
	)
	(segment
		(start 344.28811 -63.668402)
		(end 345.914218 -63.351918)
		(width 0.1143)
		(layer "In4.Cu")
		(net "P3E_CPU0_PE3_OCP_TXN<5>")
	)
	(segment
		(start 445.566546 -56.4134)
		(end 447.461894 -54.518052)
		(width 0.1143)
		(layer "In4.Cu")
		(net "P3E_CPU0_PE3_OCP_TXN<5>")
	)
	(segment
		(start 304.891948 -100.193856)
		(end 305.310286 -100.193856)
		(width 0.0889)
		(layer "In4.Cu")
		(net "P3E_CPU0_PE3_OCP_TXN<5>")
	)
	(segment
		(start 416.405314 -57.39257)
		(end 420.271194 -57.39257)
		(width 0.1143)
		(layer "In4.Cu")
		(net "P3E_CPU0_PE3_OCP_TXN<5>")
	)
	(segment
		(start 321.749166 -85.571838)
		(end 325.96328 -75.39863)
		(width 0.1143)
		(layer "In4.Cu")
		(net "P3E_CPU0_PE3_OCP_TXN<5>")
	)
	(segment
		(start 353.990148 -63.935864)
		(end 357.93426 -63.147194)
		(width 0.1143)
		(layer "In4.Cu")
		(net "P3E_CPU0_PE3_OCP_TXN<5>")
	)
	(segment
		(start 390.777984 -55.612792)
		(end 400.390614 -55.612792)
		(width 0.1143)
		(layer "In4.Cu")
		(net "P3E_CPU0_PE3_OCP_TXN<5>")
	)
	(segment
		(start 381.822706 -52.820824)
		(end 383.380488 -54.378606)
		(width 0.1143)
		(layer "In4.Cu")
		(net "P3E_CPU0_PE3_OCP_TXN<5>")
	)
	(segment
		(start 400.390614 -55.612792)
		(end 401.776692 -56.99887)
		(width 0.1143)
		(layer "In4.Cu")
		(net "P3E_CPU0_PE3_OCP_TXN<5>")
	)
	(segment
		(start 434.787802 -54.62397)
		(end 436.577232 -56.4134)
		(width 0.1143)
		(layer "In4.Cu")
		(net "P3E_CPU0_PE3_OCP_TXN<5>")
	)
	(segment
		(start 377.38177 -52.820824)
		(end 381.822706 -52.820824)
		(width 0.1143)
		(layer "In4.Cu")
		(net "P3E_CPU0_PE3_OCP_TXN<5>")
	)
	(segment
		(start 410.40558 -58.84418)
		(end 414.953704 -58.84418)
		(width 0.1143)
		(layer "In4.Cu")
		(net "P3E_CPU0_PE3_OCP_TXN<5>")
	)
	(segment
		(start 414.953704 -58.84418)
		(end 416.405314 -57.39257)
		(width 0.1143)
		(layer "In4.Cu")
		(net "P3E_CPU0_PE3_OCP_TXN<5>")
	)
	(segment
		(start 425.650152 -56.172608)
		(end 428.725076 -56.172608)
		(width 0.1143)
		(layer "In4.Cu")
		(net "P3E_CPU0_PE3_OCP_TXN<5>")
	)
	(segment
		(start 343.347548 -63.450216)
		(end 344.28811 -63.668402)
		(width 0.1143)
		(layer "In4.Cu")
		(net "P3E_CPU0_PE3_OCP_TXN<5>")
	)
	(segment
		(start 337.17738 -64.652144)
		(end 343.347548 -63.450216)
		(width 0.1143)
		(layer "In4.Cu")
		(net "P3E_CPU0_PE3_OCP_TXN<5>")
	)
	(segment
		(start 307.166772 -99.57562)
		(end 307.745384 -99.57562)
		(width 0.1143)
		(layer "In4.Cu")
		(net "P3E_CPU0_PE3_OCP_TXN<5>")
	)
	(segment
		(start 386.476494 -54.15661)
		(end 387.911594 -54.15661)
		(width 0.1143)
		(layer "In4.Cu")
		(net "P3E_CPU0_PE3_OCP_TXN<5>")
	)
	(segment
		(start 388.644384 -54.8894)
		(end 390.054592 -54.8894)
		(width 0.1143)
		(layer "In4.Cu")
		(net "P3E_CPU0_PE3_OCP_TXN<5>")
	)
	(segment
		(start 301.300896 -100.28174)
		(end 301.300896 -100.281486)
		(width 0.0889)
		(layer "In4.Cu")
		(net "P3E_CPU0_PE3_OCP_TXN<5>")
	)
	(segment
		(start 305.310286 -100.193856)
		(end 306.60975 -99.65563)
		(width 0.0889)
		(layer "In4.Cu")
		(net "P3E_CPU0_PE3_OCP_TXN<5>")
	)
	(segment
		(start 300.941232 -100.081588)
		(end 300.965362 -100.081588)
		(width 0.0889)
		(layer "In4.Cu")
		(net "P3E_CPU0_PE3_OCP_TXN<5>")
	)
	(segment
		(start 390.054592 -54.8894)
		(end 390.777984 -55.612792)
		(width 0.1143)
		(layer "In4.Cu")
		(net "P3E_CPU0_PE3_OCP_TXN<5>")
	)
	(segment
		(start 365.239554 -55.8419)
		(end 368.375692 -55.8419)
		(width 0.1143)
		(layer "In4.Cu")
		(net "P3E_CPU0_PE3_OCP_TXN<5>")
	)
	(segment
		(start 383.380488 -54.378606)
		(end 383.39395 -54.378606)
		(width 0.1143)
		(layer "In4.Cu")
		(net "P3E_CPU0_PE3_OCP_TXN<5>")
	)
	(segment
		(start 430.273714 -54.62397)
		(end 434.787802 -54.62397)
		(width 0.1143)
		(layer "In4.Cu")
		(net "P3E_CPU0_PE3_OCP_TXN<5>")
	)
	(segment
		(start 407.71445 -58.0644)
		(end 409.6258 -58.0644)
		(width 0.1143)
		(layer "In4.Cu")
		(net "P3E_CPU0_PE3_OCP_TXN<5>")
	)
	(segment
		(start 376.732546 -52.1716)
		(end 377.38177 -52.820824)
		(width 0.1143)
		(layer "In4.Cu")
		(net "P3E_CPU0_PE3_OCP_TXN<5>")
	)
	(segment
		(start 347.150944 -63.6397)
		(end 348.651068 -63.348108)
		(width 0.1143)
		(layer "In4.Cu")
		(net "P3E_CPU0_PE3_OCP_TXN<5>")
	)
	(segment
		(start 383.525522 -54.510178)
		(end 386.122926 -54.510178)
		(width 0.1143)
		(layer "In4.Cu")
		(net "P3E_CPU0_PE3_OCP_TXN<5>")
	)
	(segment
		(start 403.964394 -56.73725)
		(end 405.743918 -56.73725)
		(width 0.1143)
		(layer "In4.Cu")
		(net "P3E_CPU0_PE3_OCP_TXN<5>")
	)
	(segment
		(start 436.577232 -56.4134)
		(end 445.566546 -56.4134)
		(width 0.1143)
		(layer "In4.Cu")
		(net "P3E_CPU0_PE3_OCP_TXN<5>")
	)
	(segment
		(start 428.725076 -56.172608)
		(end 430.273714 -54.62397)
		(width 0.1143)
		(layer "In4.Cu")
		(net "P3E_CPU0_PE3_OCP_TXN<5>")
	)
	(segment
		(start 371.663976 -53.9623)
		(end 373.454676 -52.1716)
		(width 0.1143)
		(layer "In4.Cu")
		(net "P3E_CPU0_PE3_OCP_TXN<5>")
	)
	(segment
		(start 306.60975 -99.65563)
		(end 306.946046 -99.52482)
		(width 0.0889)
		(layer "In4.Cu")
		(net "P3E_CPU0_PE3_OCP_TXN<5>")
	)
	(arc
		(start 300.095666 -99.986338)
		(mid 300.465767 -100.007041)
		(end 300.83125 -100.068888)
		(width 0.0889)
		(layer "In4.Cu")
		(net "P3E_CPU0_PE3_OCP_TXN<5>")
	)
	(arc
		(start 300.965362 -100.081588)
		(mid 301.159212 -100.137938)
		(end 301.300896 -100.28174)
		(width 0.0889)
		(layer "In4.Cu")
		(net "P3E_CPU0_PE3_OCP_TXN<5>")
	)
	(arc
		(start 301.300896 -100.281486)
		(mid 301.511249 -100.494458)
		(end 301.79899 -100.576888)
		(width 0.0889)
		(layer "In4.Cu")
		(net "P3E_CPU0_PE3_OCP_TXN<5>")
	)
	(arc
		(start 300.83125 -100.068888)
		(mid 300.885943 -100.077815)
		(end 300.941232 -100.081588)
		(width 0.0889)
		(layer "In4.Cu")
		(net "P3E_CPU0_PE3_OCP_TXN<5>")
	)
	(segment
		(start 300.382686 -101.471984)
		(end 300.954186 -101.471984)
		(width 0.1143)
		(layer "F.Cu")
		(net "P3E_CPU0_PE3_OCP_TXN<4>")
	)
	(via
		(at 451.18655 -53.754274)
		(size 0.508)
		(drill 0.254)
		(layers "F.Cu" "B.Cu")
		(net "P3E_CPU0_PE3_OCP_TXN<4>")
	)
	(via
		(at 300.954186 -101.471984)
		(size 0.508)
		(drill 0.254)
		(layers "F.Cu" "B.Cu")
		(net "P3E_CPU0_PE3_OCP_TXN<4>")
	)
	(segment
		(start 450.98335 -52.811934)
		(end 450.86905 -52.926234)
		(width 0.1143)
		(layer "B.Cu")
		(net "P3E_CPU0_PE3_OCP_TXN<4>")
	)
	(segment
		(start 450.596 -53.040534)
		(end 450.596 -53.202332)
		(width 0.1143)
		(layer "B.Cu")
		(net "P3E_CPU0_PE3_OCP_TXN<4>")
	)
	(segment
		(start 450.596 -53.202332)
		(end 451.147942 -53.754274)
		(width 0.1143)
		(layer "B.Cu")
		(net "P3E_CPU0_PE3_OCP_TXN<4>")
	)
	(segment
		(start 450.86905 -52.926234)
		(end 450.7103 -52.926234)
		(width 0.1143)
		(layer "B.Cu")
		(net "P3E_CPU0_PE3_OCP_TXN<4>")
	)
	(segment
		(start 451.147942 -53.754274)
		(end 451.18655 -53.754274)
		(width 0.1143)
		(layer "B.Cu")
		(net "P3E_CPU0_PE3_OCP_TXN<4>")
	)
	(segment
		(start 450.98335 -52.407058)
		(end 450.98335 -52.811934)
		(width 0.1143)
		(layer "B.Cu")
		(net "P3E_CPU0_PE3_OCP_TXN<4>")
	)
	(segment
		(start 450.7103 -52.926234)
		(end 450.596 -53.040534)
		(width 0.1143)
		(layer "B.Cu")
		(net "P3E_CPU0_PE3_OCP_TXN<4>")
	)
	(segment
		(start 356.906068 -64.101218)
		(end 356.168452 -64.83223)
		(width 0.1143)
		(layer "In4.Cu")
		(net "P3E_CPU0_PE3_OCP_TXN<4>")
	)
	(segment
		(start 349.910654 -64.296036)
		(end 348.643194 -63.999618)
		(width 0.1143)
		(layer "In4.Cu")
		(net "P3E_CPU0_PE3_OCP_TXN<4>")
	)
	(segment
		(start 306.591462 -100.77069)
		(end 306.540662 -100.71989)
		(width 0.0889)
		(layer "In4.Cu")
		(net "P3E_CPU0_PE3_OCP_TXN<4>")
	)
	(segment
		(start 400.119342 -56.261)
		(end 390.421368 -56.261)
		(width 0.1143)
		(layer "In4.Cu")
		(net "P3E_CPU0_PE3_OCP_TXN<4>")
	)
	(segment
		(start 348.643194 -63.999618)
		(end 347.14434 -64.290956)
		(width 0.1143)
		(layer "In4.Cu")
		(net "P3E_CPU0_PE3_OCP_TXN<4>")
	)
	(segment
		(start 415.217102 -59.47918)
		(end 410.111702 -59.47918)
		(width 0.1143)
		(layer "In4.Cu")
		(net "P3E_CPU0_PE3_OCP_TXN<4>")
	)
	(segment
		(start 449.155058 -57.0484)
		(end 436.313834 -57.0484)
		(width 0.1143)
		(layer "In4.Cu")
		(net "P3E_CPU0_PE3_OCP_TXN<4>")
	)
	(segment
		(start 385.350004 -56.261)
		(end 384.317748 -56.261)
		(width 0.1143)
		(layer "In4.Cu")
		(net "P3E_CPU0_PE3_OCP_TXN<4>")
	)
	(segment
		(start 375.872248 -54.277768)
		(end 372.49989 -54.277768)
		(width 0.1143)
		(layer "In4.Cu")
		(net "P3E_CPU0_PE3_OCP_TXN<4>")
	)
	(segment
		(start 303.802542 -100.5459)
		(end 302.532034 -101.072188)
		(width 0.0889)
		(layer "In4.Cu")
		(net "P3E_CPU0_PE3_OCP_TXN<4>")
	)
	(segment
		(start 430.537112 -55.25897)
		(end 428.965614 -56.830468)
		(width 0.1143)
		(layer "In4.Cu")
		(net "P3E_CPU0_PE3_OCP_TXN<4>")
	)
	(segment
		(start 337.480402 -65.242694)
		(end 330.61148 -69.763386)
		(width 0.1143)
		(layer "In4.Cu")
		(net "P3E_CPU0_PE3_OCP_TXN<4>")
	)
	(segment
		(start 409.350972 -58.71845)
		(end 407.454354 -58.71845)
		(width 0.1143)
		(layer "In4.Cu")
		(net "P3E_CPU0_PE3_OCP_TXN<4>")
	)
	(segment
		(start 350.926908 -64.097916)
		(end 349.910654 -64.296036)
		(width 0.1143)
		(layer "In4.Cu")
		(net "P3E_CPU0_PE3_OCP_TXN<4>")
	)
	(segment
		(start 365.50092 -56.49468)
		(end 357.894382 -64.101218)
		(width 0.1143)
		(layer "In4.Cu")
		(net "P3E_CPU0_PE3_OCP_TXN<4>")
	)
	(segment
		(start 388.182104 -55.5244)
		(end 387.547866 -54.890162)
		(width 0.1143)
		(layer "In4.Cu")
		(net "P3E_CPU0_PE3_OCP_TXN<4>")
	)
	(segment
		(start 330.61148 -69.763386)
		(end 326.53859 -75.683872)
		(width 0.1143)
		(layer "In4.Cu")
		(net "P3E_CPU0_PE3_OCP_TXN<4>")
	)
	(segment
		(start 386.720842 -54.890162)
		(end 385.350004 -56.261)
		(width 0.1143)
		(layer "In4.Cu")
		(net "P3E_CPU0_PE3_OCP_TXN<4>")
	)
	(segment
		(start 405.903176 -57.862724)
		(end 401.721066 -57.862724)
		(width 0.1143)
		(layer "In4.Cu")
		(net "P3E_CPU0_PE3_OCP_TXN<4>")
	)
	(segment
		(start 450.6976 -55.505858)
		(end 449.155058 -57.0484)
		(width 0.1143)
		(layer "In4.Cu")
		(net "P3E_CPU0_PE3_OCP_TXN<4>")
	)
	(segment
		(start 389.684768 -55.5244)
		(end 388.182104 -55.5244)
		(width 0.1143)
		(layer "In4.Cu")
		(net "P3E_CPU0_PE3_OCP_TXN<4>")
	)
	(segment
		(start 372.49989 -54.277768)
		(end 371.850158 -54.9275)
		(width 0.1143)
		(layer "In4.Cu")
		(net "P3E_CPU0_PE3_OCP_TXN<4>")
	)
	(segment
		(start 450.6976 -53.868828)
		(end 450.6976 -55.505858)
		(width 0.1143)
		(layer "In4.Cu")
		(net "P3E_CPU0_PE3_OCP_TXN<4>")
	)
	(segment
		(start 416.668712 -58.02757)
		(end 415.217102 -59.47918)
		(width 0.1143)
		(layer "In4.Cu")
		(net "P3E_CPU0_PE3_OCP_TXN<4>")
	)
	(segment
		(start 424.870626 -57.850532)
		(end 420.71163 -57.850532)
		(width 0.1143)
		(layer "In4.Cu")
		(net "P3E_CPU0_PE3_OCP_TXN<4>")
	)
	(segment
		(start 451.18655 -53.754274)
		(end 450.812154 -53.754274)
		(width 0.1143)
		(layer "In4.Cu")
		(net "P3E_CPU0_PE3_OCP_TXN<4>")
	)
	(segment
		(start 304.24882 -100.5459)
		(end 303.802542 -100.5459)
		(width 0.0889)
		(layer "In4.Cu")
		(net "P3E_CPU0_PE3_OCP_TXN<4>")
	)
	(segment
		(start 376.694192 -53.455824)
		(end 375.872248 -54.277768)
		(width 0.1143)
		(layer "In4.Cu")
		(net "P3E_CPU0_PE3_OCP_TXN<4>")
	)
	(segment
		(start 434.524404 -55.25897)
		(end 430.537112 -55.25897)
		(width 0.1143)
		(layer "In4.Cu")
		(net "P3E_CPU0_PE3_OCP_TXN<4>")
	)
	(segment
		(start 343.322656 -64.105028)
		(end 337.480402 -65.242694)
		(width 0.1143)
		(layer "In4.Cu")
		(net "P3E_CPU0_PE3_OCP_TXN<4>")
	)
	(segment
		(start 390.421368 -56.261)
		(end 389.684768 -55.5244)
		(width 0.1143)
		(layer "In4.Cu")
		(net "P3E_CPU0_PE3_OCP_TXN<4>")
	)
	(segment
		(start 306.540662 -100.71989)
		(end 305.726846 -100.71989)
		(width 0.0889)
		(layer "In4.Cu")
		(net "P3E_CPU0_PE3_OCP_TXN<4>")
	)
	(segment
		(start 307.591714 -100.77069)
		(end 306.61356 -100.77069)
		(width 0.1143)
		(layer "In4.Cu")
		(net "P3E_CPU0_PE3_OCP_TXN<4>")
	)
	(segment
		(start 420.71163 -57.850532)
		(end 420.534592 -58.02757)
		(width 0.1143)
		(layer "In4.Cu")
		(net "P3E_CPU0_PE3_OCP_TXN<4>")
	)
	(segment
		(start 355.384862 -64.988694)
		(end 350.926908 -64.097916)
		(width 0.1143)
		(layer "In4.Cu")
		(net "P3E_CPU0_PE3_OCP_TXN<4>")
	)
	(segment
		(start 300.954186 -101.161088)
		(end 300.954186 -101.471984)
		(width 0.0889)
		(layer "In4.Cu")
		(net "P3E_CPU0_PE3_OCP_TXN<4>")
	)
	(segment
		(start 410.111702 -59.47918)
		(end 409.350972 -58.71845)
		(width 0.1143)
		(layer "In4.Cu")
		(net "P3E_CPU0_PE3_OCP_TXN<4>")
	)
	(segment
		(start 301.043086 -101.072188)
		(end 300.954186 -101.161088)
		(width 0.0889)
		(layer "In4.Cu")
		(net "P3E_CPU0_PE3_OCP_TXN<4>")
	)
	(segment
		(start 371.850158 -54.9275)
		(end 370.203222 -54.9275)
		(width 0.1143)
		(layer "In4.Cu")
		(net "P3E_CPU0_PE3_OCP_TXN<4>")
	)
	(segment
		(start 344.261186 -64.323722)
		(end 343.322656 -64.105028)
		(width 0.1143)
		(layer "In4.Cu")
		(net "P3E_CPU0_PE3_OCP_TXN<4>")
	)
	(segment
		(start 420.534592 -58.02757)
		(end 416.668712 -58.02757)
		(width 0.1143)
		(layer "In4.Cu")
		(net "P3E_CPU0_PE3_OCP_TXN<4>")
	)
	(segment
		(start 305.726846 -100.71989)
		(end 305.428904 -100.843334)
		(width 0.0889)
		(layer "In4.Cu")
		(net "P3E_CPU0_PE3_OCP_TXN<4>")
	)
	(segment
		(start 356.168452 -64.83223)
		(end 355.384862 -64.988694)
		(width 0.1143)
		(layer "In4.Cu")
		(net "P3E_CPU0_PE3_OCP_TXN<4>")
	)
	(segment
		(start 381.512572 -53.455824)
		(end 376.694192 -53.455824)
		(width 0.1143)
		(layer "In4.Cu")
		(net "P3E_CPU0_PE3_OCP_TXN<4>")
	)
	(segment
		(start 326.53859 -75.683872)
		(end 322.19646 -86.165944)
		(width 0.1143)
		(layer "In4.Cu")
		(net "P3E_CPU0_PE3_OCP_TXN<4>")
	)
	(segment
		(start 406.862026 -58.126122)
		(end 406.166574 -58.126122)
		(width 0.1143)
		(layer "In4.Cu")
		(net "P3E_CPU0_PE3_OCP_TXN<4>")
	)
	(segment
		(start 305.428904 -100.843334)
		(end 304.967386 -100.843334)
		(width 0.0889)
		(layer "In4.Cu")
		(net "P3E_CPU0_PE3_OCP_TXN<4>")
	)
	(segment
		(start 401.721066 -57.862724)
		(end 400.119342 -56.261)
		(width 0.1143)
		(layer "In4.Cu")
		(net "P3E_CPU0_PE3_OCP_TXN<4>")
	)
	(segment
		(start 347.14434 -64.290956)
		(end 345.907614 -64.003174)
		(width 0.1143)
		(layer "In4.Cu")
		(net "P3E_CPU0_PE3_OCP_TXN<4>")
	)
	(segment
		(start 436.313834 -57.0484)
		(end 434.524404 -55.25897)
		(width 0.1143)
		(layer "In4.Cu")
		(net "P3E_CPU0_PE3_OCP_TXN<4>")
	)
	(segment
		(start 428.965614 -56.830468)
		(end 425.89069 -56.830468)
		(width 0.1143)
		(layer "In4.Cu")
		(net "P3E_CPU0_PE3_OCP_TXN<4>")
	)
	(segment
		(start 370.203222 -54.9275)
		(end 368.636042 -56.49468)
		(width 0.1143)
		(layer "In4.Cu")
		(net "P3E_CPU0_PE3_OCP_TXN<4>")
	)
	(segment
		(start 302.532034 -101.072188)
		(end 301.043086 -101.072188)
		(width 0.0889)
		(layer "In4.Cu")
		(net "P3E_CPU0_PE3_OCP_TXN<4>")
	)
	(segment
		(start 345.907614 -64.003174)
		(end 344.261186 -64.323722)
		(width 0.1143)
		(layer "In4.Cu")
		(net "P3E_CPU0_PE3_OCP_TXN<4>")
	)
	(segment
		(start 322.19646 -86.165944)
		(end 307.591714 -100.77069)
		(width 0.1143)
		(layer "In4.Cu")
		(net "P3E_CPU0_PE3_OCP_TXN<4>")
	)
	(segment
		(start 368.636042 -56.49468)
		(end 365.50092 -56.49468)
		(width 0.1143)
		(layer "In4.Cu")
		(net "P3E_CPU0_PE3_OCP_TXN<4>")
	)
	(segment
		(start 384.317748 -56.261)
		(end 381.512572 -53.455824)
		(width 0.1143)
		(layer "In4.Cu")
		(net "P3E_CPU0_PE3_OCP_TXN<4>")
	)
	(segment
		(start 306.61356 -100.77069)
		(end 306.591462 -100.77069)
		(width 0.0889)
		(layer "In4.Cu")
		(net "P3E_CPU0_PE3_OCP_TXN<4>")
	)
	(segment
		(start 407.454354 -58.71845)
		(end 406.862026 -58.126122)
		(width 0.1143)
		(layer "In4.Cu")
		(net "P3E_CPU0_PE3_OCP_TXN<4>")
	)
	(segment
		(start 387.547866 -54.890162)
		(end 386.720842 -54.890162)
		(width 0.1143)
		(layer "In4.Cu")
		(net "P3E_CPU0_PE3_OCP_TXN<4>")
	)
	(segment
		(start 450.812154 -53.754274)
		(end 450.6976 -53.868828)
		(width 0.1143)
		(layer "In4.Cu")
		(net "P3E_CPU0_PE3_OCP_TXN<4>")
	)
	(segment
		(start 304.967386 -100.843334)
		(end 304.24882 -100.5459)
		(width 0.0889)
		(layer "In4.Cu")
		(net "P3E_CPU0_PE3_OCP_TXN<4>")
	)
	(segment
		(start 406.166574 -58.126122)
		(end 405.903176 -57.862724)
		(width 0.1143)
		(layer "In4.Cu")
		(net "P3E_CPU0_PE3_OCP_TXN<4>")
	)
	(segment
		(start 357.894382 -64.101218)
		(end 356.906068 -64.101218)
		(width 0.1143)
		(layer "In4.Cu")
		(net "P3E_CPU0_PE3_OCP_TXN<4>")
	)
	(segment
		(start 425.89069 -56.830468)
		(end 424.870626 -57.850532)
		(width 0.1143)
		(layer "In4.Cu")
		(net "P3E_CPU0_PE3_OCP_TXN<4>")
	)
	(segment
		(start 298.6659 -100.481384)
		(end 298.665646 -100.481638)
		(width 0.1143)
		(layer "F.Cu")
		(net "P3E_CPU0_PE3_OCP_TXN<3>")
	)
	(segment
		(start 299.237146 -100.481384)
		(end 298.6659 -100.481384)
		(width 0.1143)
		(layer "F.Cu")
		(net "P3E_CPU0_PE3_OCP_TXN<3>")
	)
	(via
		(at 454.38695 -53.754274)
		(size 0.508)
		(drill 0.254)
		(layers "F.Cu" "B.Cu")
		(net "P3E_CPU0_PE3_OCP_TXN<3>")
	)
	(via
		(at 299.237146 -100.481384)
		(size 0.508)
		(drill 0.254)
		(layers "F.Cu" "B.Cu")
		(net "P3E_CPU0_PE3_OCP_TXN<3>")
	)
	(segment
		(start 454.1139 -52.850034)
		(end 453.95515 -52.850034)
		(width 0.1143)
		(layer "B.Cu")
		(net "P3E_CPU0_PE3_OCP_TXN<3>")
	)
	(segment
		(start 454.2282 -52.330858)
		(end 454.2282 -52.735734)
		(width 0.1143)
		(layer "B.Cu")
		(net "P3E_CPU0_PE3_OCP_TXN<3>")
	)
	(segment
		(start 453.95515 -52.850034)
		(end 453.84085 -52.964334)
		(width 0.1143)
		(layer "B.Cu")
		(net "P3E_CPU0_PE3_OCP_TXN<3>")
	)
	(segment
		(start 453.84085 -53.208174)
		(end 454.38695 -53.754274)
		(width 0.1143)
		(layer "B.Cu")
		(net "P3E_CPU0_PE3_OCP_TXN<3>")
	)
	(segment
		(start 453.84085 -52.964334)
		(end 453.84085 -53.208174)
		(width 0.1143)
		(layer "B.Cu")
		(net "P3E_CPU0_PE3_OCP_TXN<3>")
	)
	(segment
		(start 454.2282 -52.735734)
		(end 454.1139 -52.850034)
		(width 0.1143)
		(layer "B.Cu")
		(net "P3E_CPU0_PE3_OCP_TXN<3>")
	)
	(segment
		(start 420.79799 -58.66257)
		(end 416.93211 -58.66257)
		(width 0.1143)
		(layer "In4.Cu")
		(net "P3E_CPU0_PE3_OCP_TXN<3>")
	)
	(segment
		(start 451.238112 -57.6834)
		(end 435.9021 -57.6834)
		(width 0.1143)
		(layer "In4.Cu")
		(net "P3E_CPU0_PE3_OCP_TXN<3>")
	)
	(segment
		(start 337.75269 -65.839848)
		(end 331.045312 -70.254368)
		(width 0.1143)
		(layer "In4.Cu")
		(net "P3E_CPU0_PE3_OCP_TXN<3>")
	)
	(segment
		(start 307.551836 -101.708712)
		(end 306.27955 -101.708712)
		(width 0.1143)
		(layer "In4.Cu")
		(net "P3E_CPU0_PE3_OCP_TXN<3>")
	)
	(segment
		(start 415.4805 -60.11418)
		(end 409.848304 -60.11418)
		(width 0.1143)
		(layer "In4.Cu")
		(net "P3E_CPU0_PE3_OCP_TXN<3>")
	)
	(segment
		(start 425.134024 -58.485532)
		(end 420.975028 -58.485532)
		(width 0.1143)
		(layer "In4.Cu")
		(net "P3E_CPU0_PE3_OCP_TXN<3>")
	)
	(segment
		(start 343.286842 -64.761872)
		(end 337.75269 -65.839848)
		(width 0.1143)
		(layer "In4.Cu")
		(net "P3E_CPU0_PE3_OCP_TXN<3>")
	)
	(segment
		(start 406.600406 -58.7629)
		(end 405.872442 -58.7629)
		(width 0.1143)
		(layer "In4.Cu")
		(net "P3E_CPU0_PE3_OCP_TXN<3>")
	)
	(segment
		(start 349.90278 -64.947546)
		(end 348.63532 -64.651128)
		(width 0.1143)
		(layer "In4.Cu")
		(net "P3E_CPU0_PE3_OCP_TXN<3>")
	)
	(segment
		(start 376.135646 -54.912768)
		(end 375.59869 -54.912768)
		(width 0.1143)
		(layer "In4.Cu")
		(net "P3E_CPU0_PE3_OCP_TXN<3>")
	)
	(segment
		(start 416.93211 -58.66257)
		(end 415.4805 -60.11418)
		(width 0.1143)
		(layer "In4.Cu")
		(net "P3E_CPU0_PE3_OCP_TXN<3>")
	)
	(segment
		(start 301.193454 -102.062534)
		(end 300.941486 -102.062534)
		(width 0.0889)
		(layer "In4.Cu")
		(net "P3E_CPU0_PE3_OCP_TXN<3>")
	)
	(segment
		(start 381.151638 -54.090824)
		(end 376.95759 -54.090824)
		(width 0.1143)
		(layer "In4.Cu")
		(net "P3E_CPU0_PE3_OCP_TXN<3>")
	)
	(segment
		(start 399.839942 -56.896)
		(end 389.871966 -56.896)
		(width 0.1143)
		(layer "In4.Cu")
		(net "P3E_CPU0_PE3_OCP_TXN<3>")
	)
	(segment
		(start 407.190956 -59.35345)
		(end 406.600406 -58.7629)
		(width 0.1143)
		(layer "In4.Cu")
		(net "P3E_CPU0_PE3_OCP_TXN<3>")
	)
	(segment
		(start 331.045312 -70.254368)
		(end 327.118218 -75.963018)
		(width 0.1143)
		(layer "In4.Cu")
		(net "P3E_CPU0_PE3_OCP_TXN<3>")
	)
	(segment
		(start 376.95759 -54.090824)
		(end 376.135646 -54.912768)
		(width 0.1143)
		(layer "In4.Cu")
		(net "P3E_CPU0_PE3_OCP_TXN<3>")
	)
	(segment
		(start 389.871966 -56.896)
		(end 389.239252 -56.263286)
		(width 0.1143)
		(layer "In4.Cu")
		(net "P3E_CPU0_PE3_OCP_TXN<3>")
	)
	(segment
		(start 386.456682 -56.94045)
		(end 383.16281 -56.94045)
		(width 0.1143)
		(layer "In4.Cu")
		(net "P3E_CPU0_PE3_OCP_TXN<3>")
	)
	(segment
		(start 374.308878 -56.20258)
		(end 373.187722 -56.20258)
		(width 0.1143)
		(layer "In4.Cu")
		(net "P3E_CPU0_PE3_OCP_TXN<3>")
	)
	(segment
		(start 430.623726 -56.070754)
		(end 429.194722 -57.499758)
		(width 0.1143)
		(layer "In4.Cu")
		(net "P3E_CPU0_PE3_OCP_TXN<3>")
	)
	(segment
		(start 389.239252 -56.263286)
		(end 387.133846 -56.263286)
		(width 0.1143)
		(layer "In4.Cu")
		(net "P3E_CPU0_PE3_OCP_TXN<3>")
	)
	(segment
		(start 405.872442 -58.7629)
		(end 405.620474 -58.510932)
		(width 0.1143)
		(layer "In4.Cu")
		(net "P3E_CPU0_PE3_OCP_TXN<3>")
	)
	(segment
		(start 347.11132 -64.947292)
		(end 345.874594 -64.65951)
		(width 0.1143)
		(layer "In4.Cu")
		(net "P3E_CPU0_PE3_OCP_TXN<3>")
	)
	(segment
		(start 409.087574 -59.35345)
		(end 407.190956 -59.35345)
		(width 0.1143)
		(layer "In4.Cu")
		(net "P3E_CPU0_PE3_OCP_TXN<3>")
	)
	(segment
		(start 372.598442 -55.6133)
		(end 370.537486 -55.6133)
		(width 0.1143)
		(layer "In4.Cu")
		(net "P3E_CPU0_PE3_OCP_TXN<3>")
	)
	(segment
		(start 299.530262 -100.650294)
		(end 299.237146 -100.481384)
		(width 0.0889)
		(layer "In4.Cu")
		(net "P3E_CPU0_PE3_OCP_TXN<3>")
	)
	(segment
		(start 365.561626 -57.348628)
		(end 358.142286 -64.767968)
		(width 0.1143)
		(layer "In4.Cu")
		(net "P3E_CPU0_PE3_OCP_TXN<3>")
	)
	(segment
		(start 306.257452 -101.708712)
		(end 306.206652 -101.657912)
		(width 0.0889)
		(layer "In4.Cu")
		(net "P3E_CPU0_PE3_OCP_TXN<3>")
	)
	(segment
		(start 300.941486 -102.062534)
		(end 300.941232 -102.062788)
		(width 0.0889)
		(layer "In4.Cu")
		(net "P3E_CPU0_PE3_OCP_TXN<3>")
	)
	(segment
		(start 373.187722 -56.20258)
		(end 372.598442 -55.6133)
		(width 0.1143)
		(layer "In4.Cu")
		(net "P3E_CPU0_PE3_OCP_TXN<3>")
	)
	(segment
		(start 345.874594 -64.65951)
		(end 344.224356 -64.98082)
		(width 0.1143)
		(layer "In4.Cu")
		(net "P3E_CPU0_PE3_OCP_TXN<3>")
	)
	(segment
		(start 381.954024 -55.731664)
		(end 381.954024 -54.89321)
		(width 0.1143)
		(layer "In4.Cu")
		(net "P3E_CPU0_PE3_OCP_TXN<3>")
	)
	(segment
		(start 435.9021 -57.6834)
		(end 434.289454 -56.070754)
		(width 0.1143)
		(layer "In4.Cu")
		(net "P3E_CPU0_PE3_OCP_TXN<3>")
	)
	(segment
		(start 454.38695 -53.754274)
		(end 454.0123 -53.754274)
		(width 0.1143)
		(layer "In4.Cu")
		(net "P3E_CPU0_PE3_OCP_TXN<3>")
	)
	(segment
		(start 350.928686 -64.747394)
		(end 349.90278 -64.947546)
		(width 0.1143)
		(layer "In4.Cu")
		(net "P3E_CPU0_PE3_OCP_TXN<3>")
	)
	(segment
		(start 381.954024 -54.89321)
		(end 381.151638 -54.090824)
		(width 0.1143)
		(layer "In4.Cu")
		(net "P3E_CPU0_PE3_OCP_TXN<3>")
	)
	(segment
		(start 299.554138 -100.739702)
		(end 299.530262 -100.650294)
		(width 0.0889)
		(layer "In4.Cu")
		(net "P3E_CPU0_PE3_OCP_TXN<3>")
	)
	(segment
		(start 306.206652 -101.657912)
		(end 305.29276 -101.657912)
		(width 0.0889)
		(layer "In4.Cu")
		(net "P3E_CPU0_PE3_OCP_TXN<3>")
	)
	(segment
		(start 310.597296 -98.663252)
		(end 307.551836 -101.708712)
		(width 0.1143)
		(layer "In4.Cu")
		(net "P3E_CPU0_PE3_OCP_TXN<3>")
	)
	(segment
		(start 454.0123 -53.754274)
		(end 453.898 -53.868574)
		(width 0.1143)
		(layer "In4.Cu")
		(net "P3E_CPU0_PE3_OCP_TXN<3>")
	)
	(segment
		(start 405.620474 -58.510932)
		(end 401.454874 -58.510932)
		(width 0.1143)
		(layer "In4.Cu")
		(net "P3E_CPU0_PE3_OCP_TXN<3>")
	)
	(segment
		(start 370.537486 -55.6133)
		(end 368.802158 -57.348628)
		(width 0.1143)
		(layer "In4.Cu")
		(net "P3E_CPU0_PE3_OCP_TXN<3>")
	)
	(segment
		(start 420.975028 -58.485532)
		(end 420.79799 -58.66257)
		(width 0.1143)
		(layer "In4.Cu")
		(net "P3E_CPU0_PE3_OCP_TXN<3>")
	)
	(segment
		(start 348.63532 -64.651128)
		(end 347.11132 -64.947292)
		(width 0.1143)
		(layer "In4.Cu")
		(net "P3E_CPU0_PE3_OCP_TXN<3>")
	)
	(segment
		(start 358.142286 -64.767968)
		(end 357.900478 -64.767968)
		(width 0.1143)
		(layer "In4.Cu")
		(net "P3E_CPU0_PE3_OCP_TXN<3>")
	)
	(segment
		(start 306.27955 -101.708712)
		(end 306.257452 -101.708712)
		(width 0.0889)
		(layer "In4.Cu")
		(net "P3E_CPU0_PE3_OCP_TXN<3>")
	)
	(segment
		(start 453.898 -55.023512)
		(end 451.238112 -57.6834)
		(width 0.1143)
		(layer "In4.Cu")
		(net "P3E_CPU0_PE3_OCP_TXN<3>")
	)
	(segment
		(start 344.224356 -64.98082)
		(end 343.286842 -64.761872)
		(width 0.1143)
		(layer "In4.Cu")
		(net "P3E_CPU0_PE3_OCP_TXN<3>")
	)
	(segment
		(start 375.59869 -54.912768)
		(end 374.308878 -56.20258)
		(width 0.1143)
		(layer "In4.Cu")
		(net "P3E_CPU0_PE3_OCP_TXN<3>")
	)
	(segment
		(start 357.900478 -64.767968)
		(end 357.900224 -64.767714)
		(width 0.1143)
		(layer "In4.Cu")
		(net "P3E_CPU0_PE3_OCP_TXN<3>")
	)
	(segment
		(start 356.506018 -65.436242)
		(end 355.439472 -65.649602)
		(width 0.1143)
		(layer "In4.Cu")
		(net "P3E_CPU0_PE3_OCP_TXN<3>")
	)
	(segment
		(start 322.749418 -86.511384)
		(end 310.59755 -98.663252)
		(width 0.1143)
		(layer "In4.Cu")
		(net "P3E_CPU0_PE3_OCP_TXN<3>")
	)
	(segment
		(start 305.29276 -101.657912)
		(end 301.193454 -102.062534)
		(width 0.0889)
		(layer "In4.Cu")
		(net "P3E_CPU0_PE3_OCP_TXN<3>")
	)
	(segment
		(start 357.900224 -64.767714)
		(end 357.179626 -64.767714)
		(width 0.1143)
		(layer "In4.Cu")
		(net "P3E_CPU0_PE3_OCP_TXN<3>")
	)
	(segment
		(start 387.133846 -56.263286)
		(end 386.456682 -56.94045)
		(width 0.1143)
		(layer "In4.Cu")
		(net "P3E_CPU0_PE3_OCP_TXN<3>")
	)
	(segment
		(start 368.802158 -57.348628)
		(end 365.561626 -57.348628)
		(width 0.1143)
		(layer "In4.Cu")
		(net "P3E_CPU0_PE3_OCP_TXN<3>")
	)
	(segment
		(start 429.194722 -57.499758)
		(end 426.119798 -57.499758)
		(width 0.1143)
		(layer "In4.Cu")
		(net "P3E_CPU0_PE3_OCP_TXN<3>")
	)
	(segment
		(start 327.118218 -75.963018)
		(end 322.749418 -86.511384)
		(width 0.1143)
		(layer "In4.Cu")
		(net "P3E_CPU0_PE3_OCP_TXN<3>")
	)
	(segment
		(start 383.16281 -56.94045)
		(end 381.954024 -55.731664)
		(width 0.1143)
		(layer "In4.Cu")
		(net "P3E_CPU0_PE3_OCP_TXN<3>")
	)
	(segment
		(start 453.898 -53.868574)
		(end 453.898 -55.023512)
		(width 0.1143)
		(layer "In4.Cu")
		(net "P3E_CPU0_PE3_OCP_TXN<3>")
	)
	(segment
		(start 409.848304 -60.11418)
		(end 409.087574 -59.35345)
		(width 0.1143)
		(layer "In4.Cu")
		(net "P3E_CPU0_PE3_OCP_TXN<3>")
	)
	(segment
		(start 426.119798 -57.499758)
		(end 425.134024 -58.485532)
		(width 0.1143)
		(layer "In4.Cu")
		(net "P3E_CPU0_PE3_OCP_TXN<3>")
	)
	(segment
		(start 401.454874 -58.510932)
		(end 399.839942 -56.896)
		(width 0.1143)
		(layer "In4.Cu")
		(net "P3E_CPU0_PE3_OCP_TXN<3>")
	)
	(segment
		(start 310.59755 -98.663252)
		(end 310.597296 -98.663252)
		(width 0.1143)
		(layer "In4.Cu")
		(net "P3E_CPU0_PE3_OCP_TXN<3>")
	)
	(segment
		(start 434.289454 -56.070754)
		(end 430.623726 -56.070754)
		(width 0.1143)
		(layer "In4.Cu")
		(net "P3E_CPU0_PE3_OCP_TXN<3>")
	)
	(segment
		(start 357.179626 -64.767714)
		(end 356.506018 -65.436242)
		(width 0.1143)
		(layer "In4.Cu")
		(net "P3E_CPU0_PE3_OCP_TXN<3>")
	)
	(segment
		(start 355.439472 -65.649602)
		(end 350.928686 -64.747394)
		(width 0.1143)
		(layer "In4.Cu")
		(net "P3E_CPU0_PE3_OCP_TXN<3>")
	)
	(segment
		(start 300.110652 -101.567488)
		(end 300.082712 -101.567488)
		(width 0.0889)
		(layer "In4.Cu")
		(net "P3E_CPU0_PE3_OCP_TXN<3>")
	)
	(arc
		(start 300.082712 -101.567488)
		(mid 299.597569 -101.294673)
		(end 299.554138 -100.739702)
		(width 0.0889)
		(layer "In4.Cu")
		(net "P3E_CPU0_PE3_OCP_TXN<3>")
	)
	(arc
		(start 300.941232 -102.062788)
		(mid 300.653087 -101.980469)
		(end 300.442376 -101.767386)
		(width 0.0889)
		(layer "In4.Cu")
		(net "P3E_CPU0_PE3_OCP_TXN<3>")
	)
	(arc
		(start 300.442376 -101.767386)
		(mid 300.302297 -101.62465)
		(end 300.110652 -101.567488)
		(width 0.0889)
		(layer "In4.Cu")
		(net "P3E_CPU0_PE3_OCP_TXN<3>")
	)
	(segment
		(start 297.807126 -101.967538)
		(end 298.378626 -101.967538)
		(width 0.1143)
		(layer "F.Cu")
		(net "P3E_CPU0_PE3_OCP_TXN<2>")
	)
	(via
		(at 457.587604 -53.906674)
		(size 0.508)
		(drill 0.254)
		(layers "F.Cu" "B.Cu")
		(net "P3E_CPU0_PE3_OCP_TXN<2>")
	)
	(via
		(at 298.378626 -101.967538)
		(size 0.508)
		(drill 0.254)
		(layers "F.Cu" "B.Cu")
		(net "P3E_CPU0_PE3_OCP_TXN<2>")
	)
	(segment
		(start 457.23175 -53.002434)
		(end 457.11745 -53.116734)
		(width 0.1143)
		(layer "B.Cu")
		(net "P3E_CPU0_PE3_OCP_TXN<2>")
	)
	(segment
		(start 457.5048 -52.888134)
		(end 457.3905 -53.002434)
		(width 0.1143)
		(layer "B.Cu")
		(net "P3E_CPU0_PE3_OCP_TXN<2>")
	)
	(segment
		(start 457.3905 -53.002434)
		(end 457.23175 -53.002434)
		(width 0.1143)
		(layer "B.Cu")
		(net "P3E_CPU0_PE3_OCP_TXN<2>")
	)
	(segment
		(start 457.11745 -53.116734)
		(end 457.11745 -53.43652)
		(width 0.1143)
		(layer "B.Cu")
		(net "P3E_CPU0_PE3_OCP_TXN<2>")
	)
	(segment
		(start 457.11745 -53.43652)
		(end 457.587604 -53.906674)
		(width 0.1143)
		(layer "B.Cu")
		(net "P3E_CPU0_PE3_OCP_TXN<2>")
	)
	(segment
		(start 457.5048 -52.483258)
		(end 457.5048 -52.888134)
		(width 0.1143)
		(layer "B.Cu")
		(net "P3E_CPU0_PE3_OCP_TXN<2>")
	)
	(segment
		(start 405.60752 -59.40044)
		(end 405.353012 -59.145932)
		(width 0.1143)
		(layer "In4.Cu")
		(net "P3E_CPU0_PE3_OCP_TXN<2>")
	)
	(segment
		(start 307.5432 -102.66934)
		(end 306.980082 -102.66934)
		(width 0.1143)
		(layer "In4.Cu")
		(net "P3E_CPU0_PE3_OCP_TXN<2>")
	)
	(segment
		(start 349.894906 -65.599056)
		(end 348.627446 -65.302638)
		(width 0.1143)
		(layer "In4.Cu")
		(net "P3E_CPU0_PE3_OCP_TXN<2>")
	)
	(segment
		(start 381.218186 -56.186832)
		(end 381.218186 -55.24246)
		(width 0.1143)
		(layer "In4.Cu")
		(net "P3E_CPU0_PE3_OCP_TXN<2>")
	)
	(segment
		(start 304.55616 -102.558088)
		(end 300.586394 -102.558088)
		(width 0.0889)
		(layer "In4.Cu")
		(net "P3E_CPU0_PE3_OCP_TXN<2>")
	)
	(segment
		(start 433.792122 -56.73344)
		(end 430.859438 -56.73344)
		(width 0.1143)
		(layer "In4.Cu")
		(net "P3E_CPU0_PE3_OCP_TXN<2>")
	)
	(segment
		(start 343.232232 -65.422526)
		(end 338.06638 -66.428874)
		(width 0.1143)
		(layer "In4.Cu")
		(net "P3E_CPU0_PE3_OCP_TXN<2>")
	)
	(segment
		(start 369.159028 -57.983628)
		(end 365.866172 -57.983628)
		(width 0.1143)
		(layer "In4.Cu")
		(net "P3E_CPU0_PE3_OCP_TXN<2>")
	)
	(segment
		(start 457.213208 -53.906674)
		(end 457.043282 -54.0766)
		(width 0.1143)
		(layer "In4.Cu")
		(net "P3E_CPU0_PE3_OCP_TXN<2>")
	)
	(segment
		(start 298.76115 -101.822504)
		(end 298.745656 -101.837998)
		(width 0.0889)
		(layer "In4.Cu")
		(net "P3E_CPU0_PE3_OCP_TXN<2>")
	)
	(segment
		(start 378.1806 -54.726078)
		(end 378.180346 -54.725824)
		(width 0.1143)
		(layer "In4.Cu")
		(net "P3E_CPU0_PE3_OCP_TXN<2>")
	)
	(segment
		(start 338.06638 -66.428874)
		(end 338.064602 -66.430144)
		(width 0.1143)
		(layer "In4.Cu")
		(net "P3E_CPU0_PE3_OCP_TXN<2>")
	)
	(segment
		(start 357.425244 -65.421764)
		(end 356.78618 -66.058542)
		(width 0.1143)
		(layer "In4.Cu")
		(net "P3E_CPU0_PE3_OCP_TXN<2>")
	)
	(segment
		(start 457.043282 -54.951376)
		(end 453.56653 -58.428128)
		(width 0.1143)
		(layer "In4.Cu")
		(net "P3E_CPU0_PE3_OCP_TXN<2>")
	)
	(segment
		(start 382.785366 -57.754012)
		(end 381.218186 -56.186832)
		(width 0.1143)
		(layer "In4.Cu")
		(net "P3E_CPU0_PE3_OCP_TXN<2>")
	)
	(segment
		(start 347.10624 -65.598294)
		(end 345.870276 -65.310766)
		(width 0.1143)
		(layer "In4.Cu")
		(net "P3E_CPU0_PE3_OCP_TXN<2>")
	)
	(segment
		(start 380.70155 -54.725824)
		(end 378.69876 -54.725824)
		(width 0.1143)
		(layer "In4.Cu")
		(net "P3E_CPU0_PE3_OCP_TXN<2>")
	)
	(segment
		(start 421.238426 -59.120532)
		(end 421.061388 -59.29757)
		(width 0.1143)
		(layer "In4.Cu")
		(net "P3E_CPU0_PE3_OCP_TXN<2>")
	)
	(segment
		(start 390.528302 -57.754012)
		(end 382.785366 -57.754012)
		(width 0.1143)
		(layer "In4.Cu")
		(net "P3E_CPU0_PE3_OCP_TXN<2>")
	)
	(segment
		(start 457.043282 -54.0766)
		(end 457.043282 -54.951376)
		(width 0.1143)
		(layer "In4.Cu")
		(net "P3E_CPU0_PE3_OCP_TXN<2>")
	)
	(segment
		(start 418.686996 -60.6425)
		(end 415.970974 -60.6425)
		(width 0.1143)
		(layer "In4.Cu")
		(net "P3E_CPU0_PE3_OCP_TXN<2>")
	)
	(segment
		(start 376.371612 -55.5752)
		(end 376.003058 -55.5752)
		(width 0.1143)
		(layer "In4.Cu")
		(net "P3E_CPU0_PE3_OCP_TXN<2>")
	)
	(segment
		(start 378.69876 -54.725824)
		(end 378.698506 -54.726078)
		(width 0.1143)
		(layer "In4.Cu")
		(net "P3E_CPU0_PE3_OCP_TXN<2>")
	)
	(segment
		(start 345.870276 -65.310766)
		(end 344.169492 -65.641474)
		(width 0.1143)
		(layer "In4.Cu")
		(net "P3E_CPU0_PE3_OCP_TXN<2>")
	)
	(segment
		(start 306.980082 -102.66934)
		(end 306.957984 -102.66934)
		(width 0.0889)
		(layer "In4.Cu")
		(net "P3E_CPU0_PE3_OCP_TXN<2>")
	)
	(segment
		(start 300.586394 -102.558088)
		(end 299.3898 -102.062534)
		(width 0.0889)
		(layer "In4.Cu")
		(net "P3E_CPU0_PE3_OCP_TXN<2>")
	)
	(segment
		(start 298.745656 -101.837998)
		(end 298.603162 -101.837998)
		(width 0.0889)
		(layer "In4.Cu")
		(net "P3E_CPU0_PE3_OCP_TXN<2>")
	)
	(segment
		(start 327.72731 -76.198984)
		(end 323.282564 -86.929976)
		(width 0.1143)
		(layer "In4.Cu")
		(net "P3E_CPU0_PE3_OCP_TXN<2>")
	)
	(segment
		(start 298.603162 -101.837998)
		(end 298.378626 -101.967538)
		(width 0.0889)
		(layer "In4.Cu")
		(net "P3E_CPU0_PE3_OCP_TXN<2>")
	)
	(segment
		(start 381.218186 -55.24246)
		(end 380.70155 -54.725824)
		(width 0.1143)
		(layer "In4.Cu")
		(net "P3E_CPU0_PE3_OCP_TXN<2>")
	)
	(segment
		(start 344.169492 -65.641474)
		(end 343.232232 -65.422526)
		(width 0.1143)
		(layer "In4.Cu")
		(net "P3E_CPU0_PE3_OCP_TXN<2>")
	)
	(segment
		(start 406.339548 -59.40044)
		(end 405.60752 -59.40044)
		(width 0.1143)
		(layer "In4.Cu")
		(net "P3E_CPU0_PE3_OCP_TXN<2>")
	)
	(segment
		(start 420.031926 -59.29757)
		(end 418.686996 -60.6425)
		(width 0.1143)
		(layer "In4.Cu")
		(net "P3E_CPU0_PE3_OCP_TXN<2>")
	)
	(segment
		(start 399.627344 -57.5818)
		(end 390.700514 -57.5818)
		(width 0.1143)
		(layer "In4.Cu")
		(net "P3E_CPU0_PE3_OCP_TXN<2>")
	)
	(segment
		(start 435.48681 -58.428128)
		(end 433.792122 -56.73344)
		(width 0.1143)
		(layer "In4.Cu")
		(net "P3E_CPU0_PE3_OCP_TXN<2>")
	)
	(segment
		(start 401.191476 -59.145932)
		(end 399.627344 -57.5818)
		(width 0.1143)
		(layer "In4.Cu")
		(net "P3E_CPU0_PE3_OCP_TXN<2>")
	)
	(segment
		(start 355.423216 -66.330322)
		(end 350.844104 -65.414144)
		(width 0.1143)
		(layer "In4.Cu")
		(net "P3E_CPU0_PE3_OCP_TXN<2>")
	)
	(segment
		(start 406.927558 -59.98845)
		(end 406.339548 -59.40044)
		(width 0.1143)
		(layer "In4.Cu")
		(net "P3E_CPU0_PE3_OCP_TXN<2>")
	)
	(segment
		(start 412.786322 -62.61862)
		(end 411.437074 -61.269372)
		(width 0.1143)
		(layer "In4.Cu")
		(net "P3E_CPU0_PE3_OCP_TXN<2>")
	)
	(segment
		(start 299.3898 -102.062534)
		(end 299.218858 -102.062534)
		(width 0.0889)
		(layer "In4.Cu")
		(net "P3E_CPU0_PE3_OCP_TXN<2>")
	)
	(segment
		(start 323.282564 -86.929976)
		(end 307.5432 -102.66934)
		(width 0.1143)
		(layer "In4.Cu")
		(net "P3E_CPU0_PE3_OCP_TXN<2>")
	)
	(segment
		(start 415.970974 -60.6425)
		(end 413.994854 -62.61862)
		(width 0.1143)
		(layer "In4.Cu")
		(net "P3E_CPU0_PE3_OCP_TXN<2>")
	)
	(segment
		(start 378.698506 -54.726078)
		(end 378.1806 -54.726078)
		(width 0.1143)
		(layer "In4.Cu")
		(net "P3E_CPU0_PE3_OCP_TXN<2>")
	)
	(segment
		(start 413.994854 -62.61862)
		(end 412.786322 -62.61862)
		(width 0.1143)
		(layer "In4.Cu")
		(net "P3E_CPU0_PE3_OCP_TXN<2>")
	)
	(segment
		(start 426.4025 -58.134758)
		(end 425.416726 -59.120532)
		(width 0.1143)
		(layer "In4.Cu")
		(net "P3E_CPU0_PE3_OCP_TXN<2>")
	)
	(segment
		(start 331.454506 -70.78091)
		(end 327.72731 -76.198984)
		(width 0.1143)
		(layer "In4.Cu")
		(net "P3E_CPU0_PE3_OCP_TXN<2>")
	)
	(segment
		(start 374.491758 -57.0865)
		(end 370.056156 -57.0865)
		(width 0.1143)
		(layer "In4.Cu")
		(net "P3E_CPU0_PE3_OCP_TXN<2>")
	)
	(segment
		(start 348.627446 -65.302638)
		(end 347.10624 -65.598294)
		(width 0.1143)
		(layer "In4.Cu")
		(net "P3E_CPU0_PE3_OCP_TXN<2>")
	)
	(segment
		(start 425.416726 -59.120532)
		(end 421.238426 -59.120532)
		(width 0.1143)
		(layer "In4.Cu")
		(net "P3E_CPU0_PE3_OCP_TXN<2>")
	)
	(segment
		(start 429.45812 -58.134758)
		(end 426.4025 -58.134758)
		(width 0.1143)
		(layer "In4.Cu")
		(net "P3E_CPU0_PE3_OCP_TXN<2>")
	)
	(segment
		(start 421.061388 -59.29757)
		(end 420.031926 -59.29757)
		(width 0.1143)
		(layer "In4.Cu")
		(net "P3E_CPU0_PE3_OCP_TXN<2>")
	)
	(segment
		(start 304.70221 -102.61854)
		(end 304.55616 -102.558088)
		(width 0.0889)
		(layer "In4.Cu")
		(net "P3E_CPU0_PE3_OCP_TXN<2>")
	)
	(segment
		(start 365.866172 -57.983628)
		(end 358.428036 -65.421764)
		(width 0.1143)
		(layer "In4.Cu")
		(net "P3E_CPU0_PE3_OCP_TXN<2>")
	)
	(segment
		(start 408.824176 -59.98845)
		(end 406.927558 -59.98845)
		(width 0.1143)
		(layer "In4.Cu")
		(net "P3E_CPU0_PE3_OCP_TXN<2>")
	)
	(segment
		(start 405.353012 -59.145932)
		(end 401.191476 -59.145932)
		(width 0.1143)
		(layer "In4.Cu")
		(net "P3E_CPU0_PE3_OCP_TXN<2>")
	)
	(segment
		(start 376.003058 -55.5752)
		(end 374.491758 -57.0865)
		(width 0.1143)
		(layer "In4.Cu")
		(net "P3E_CPU0_PE3_OCP_TXN<2>")
	)
	(segment
		(start 356.78618 -66.058542)
		(end 355.423216 -66.330322)
		(width 0.1143)
		(layer "In4.Cu")
		(net "P3E_CPU0_PE3_OCP_TXN<2>")
	)
	(segment
		(start 378.180346 -54.725824)
		(end 377.220988 -54.725824)
		(width 0.1143)
		(layer "In4.Cu")
		(net "P3E_CPU0_PE3_OCP_TXN<2>")
	)
	(segment
		(start 410.105098 -61.269372)
		(end 408.824176 -59.98845)
		(width 0.1143)
		(layer "In4.Cu")
		(net "P3E_CPU0_PE3_OCP_TXN<2>")
	)
	(segment
		(start 338.064602 -66.430144)
		(end 331.454506 -70.78091)
		(width 0.1143)
		(layer "In4.Cu")
		(net "P3E_CPU0_PE3_OCP_TXN<2>")
	)
	(segment
		(start 453.56653 -58.428128)
		(end 435.48681 -58.428128)
		(width 0.1143)
		(layer "In4.Cu")
		(net "P3E_CPU0_PE3_OCP_TXN<2>")
	)
	(segment
		(start 377.220988 -54.725824)
		(end 376.371612 -55.5752)
		(width 0.1143)
		(layer "In4.Cu")
		(net "P3E_CPU0_PE3_OCP_TXN<2>")
	)
	(segment
		(start 306.957984 -102.66934)
		(end 306.907184 -102.61854)
		(width 0.0889)
		(layer "In4.Cu")
		(net "P3E_CPU0_PE3_OCP_TXN<2>")
	)
	(segment
		(start 358.428036 -65.421764)
		(end 357.425244 -65.421764)
		(width 0.1143)
		(layer "In4.Cu")
		(net "P3E_CPU0_PE3_OCP_TXN<2>")
	)
	(segment
		(start 306.907184 -102.61854)
		(end 304.70221 -102.61854)
		(width 0.0889)
		(layer "In4.Cu")
		(net "P3E_CPU0_PE3_OCP_TXN<2>")
	)
	(segment
		(start 411.437074 -61.269372)
		(end 410.105098 -61.269372)
		(width 0.1143)
		(layer "In4.Cu")
		(net "P3E_CPU0_PE3_OCP_TXN<2>")
	)
	(segment
		(start 370.056156 -57.0865)
		(end 369.159028 -57.983628)
		(width 0.1143)
		(layer "In4.Cu")
		(net "P3E_CPU0_PE3_OCP_TXN<2>")
	)
	(segment
		(start 430.859438 -56.73344)
		(end 429.45812 -58.134758)
		(width 0.1143)
		(layer "In4.Cu")
		(net "P3E_CPU0_PE3_OCP_TXN<2>")
	)
	(segment
		(start 457.587604 -53.906674)
		(end 457.213208 -53.906674)
		(width 0.1143)
		(layer "In4.Cu")
		(net "P3E_CPU0_PE3_OCP_TXN<2>")
	)
	(segment
		(start 350.844104 -65.414144)
		(end 349.894906 -65.599056)
		(width 0.1143)
		(layer "In4.Cu")
		(net "P3E_CPU0_PE3_OCP_TXN<2>")
	)
	(segment
		(start 390.700514 -57.5818)
		(end 390.528302 -57.754012)
		(width 0.1143)
		(layer "In4.Cu")
		(net "P3E_CPU0_PE3_OCP_TXN<2>")
	)
	(arc
		(start 299.218858 -102.062534)
		(mid 298.962379 -101.995196)
		(end 298.76115 -101.822504)
		(width 0.0889)
		(layer "In4.Cu")
		(net "P3E_CPU0_PE3_OCP_TXN<2>")
	)
	(segment
		(start 297.807126 -102.958138)
		(end 298.378626 -102.958138)
		(width 0.1143)
		(layer "F.Cu")
		(net "P3E_CPU0_PE3_OCP_TXN<1>")
	)
	(via
		(at 460.78775 -53.906674)
		(size 0.508)
		(drill 0.254)
		(layers "F.Cu" "B.Cu")
		(net "P3E_CPU0_PE3_OCP_TXN<1>")
	)
	(via
		(at 298.378626 -102.958138)
		(size 0.508)
		(drill 0.254)
		(layers "F.Cu" "B.Cu")
		(net "P3E_CPU0_PE3_OCP_TXN<1>")
	)
	(segment
		(start 460.78775 -53.906674)
		(end 460.256382 -53.375306)
		(width 0.1143)
		(layer "B.Cu")
		(net "P3E_CPU0_PE3_OCP_TXN<1>")
	)
	(segment
		(start 460.38135 -52.977034)
		(end 460.5401 -52.977034)
		(width 0.1143)
		(layer "B.Cu")
		(net "P3E_CPU0_PE3_OCP_TXN<1>")
	)
	(segment
		(start 460.256382 -53.375306)
		(end 460.256382 -53.102002)
		(width 0.1143)
		(layer "B.Cu")
		(net "P3E_CPU0_PE3_OCP_TXN<1>")
	)
	(segment
		(start 460.6544 -52.862734)
		(end 460.6544 -52.457858)
		(width 0.1143)
		(layer "B.Cu")
		(net "P3E_CPU0_PE3_OCP_TXN<1>")
	)
	(segment
		(start 460.5401 -52.977034)
		(end 460.6544 -52.862734)
		(width 0.1143)
		(layer "B.Cu")
		(net "P3E_CPU0_PE3_OCP_TXN<1>")
	)
	(segment
		(start 460.256382 -53.102002)
		(end 460.38135 -52.977034)
		(width 0.1143)
		(layer "B.Cu")
		(net "P3E_CPU0_PE3_OCP_TXN<1>")
	)
	(segment
		(start 357.698294 -66.070226)
		(end 357.06812 -66.698368)
		(width 0.1143)
		(layer "In4.Cu")
		(net "P3E_CPU0_PE3_OCP_TXN<1>")
	)
	(segment
		(start 331.897736 -71.258176)
		(end 328.314558 -76.4667)
		(width 0.1143)
		(layer "In4.Cu")
		(net "P3E_CPU0_PE3_OCP_TXN<1>")
	)
	(segment
		(start 345.862402 -65.962276)
		(end 344.107262 -66.303652)
		(width 0.1143)
		(layer "In4.Cu")
		(net "P3E_CPU0_PE3_OCP_TXN<1>")
	)
	(segment
		(start 460.2988 -54.021228)
		(end 460.2988 -54.972458)
		(width 0.1143)
		(layer "In4.Cu")
		(net "P3E_CPU0_PE3_OCP_TXN<1>")
	)
	(segment
		(start 347.098366 -66.249804)
		(end 345.862402 -65.962276)
		(width 0.1143)
		(layer "In4.Cu")
		(net "P3E_CPU0_PE3_OCP_TXN<1>")
	)
	(segment
		(start 304.517298 -104.3813)
		(end 304.4952 -104.3813)
		(width 0.0889)
		(layer "In4.Cu")
		(net "P3E_CPU0_PE3_OCP_TXN<1>")
	)
	(segment
		(start 406.076912 -60.036202)
		(end 405.289004 -60.036202)
		(width 0.1143)
		(layer "In4.Cu")
		(net "P3E_CPU0_PE3_OCP_TXN<1>")
	)
	(segment
		(start 301.15129 -103.167688)
		(end 301.06239 -103.078788)
		(width 0.0889)
		(layer "In4.Cu")
		(net "P3E_CPU0_PE3_OCP_TXN<1>")
	)
	(segment
		(start 375.39676 -57.7215)
		(end 370.319554 -57.7215)
		(width 0.1143)
		(layer "In4.Cu")
		(net "P3E_CPU0_PE3_OCP_TXN<1>")
	)
	(segment
		(start 303.708562 -104.3305)
		(end 302.95977 -103.581708)
		(width 0.0889)
		(layer "In4.Cu")
		(net "P3E_CPU0_PE3_OCP_TXN<1>")
	)
	(segment
		(start 301.79899 -103.078788)
		(end 301.51959 -103.078788)
		(width 0.0889)
		(layer "In4.Cu")
		(net "P3E_CPU0_PE3_OCP_TXN<1>")
	)
	(segment
		(start 357.06812 -66.698368)
		(end 355.47173 -67.017392)
		(width 0.1143)
		(layer "In4.Cu")
		(net "P3E_CPU0_PE3_OCP_TXN<1>")
	)
	(segment
		(start 369.418616 -58.622438)
		(end 366.167162 -58.622438)
		(width 0.1143)
		(layer "In4.Cu")
		(net "P3E_CPU0_PE3_OCP_TXN<1>")
	)
	(segment
		(start 379.55982 -57.038748)
		(end 378.562616 -57.038748)
		(width 0.1143)
		(layer "In4.Cu")
		(net "P3E_CPU0_PE3_OCP_TXN<1>")
	)
	(segment
		(start 375.530364 -57.855104)
		(end 375.39676 -57.7215)
		(width 0.1143)
		(layer "In4.Cu")
		(net "P3E_CPU0_PE3_OCP_TXN<1>")
	)
	(segment
		(start 400.928078 -59.780932)
		(end 399.363946 -58.2168)
		(width 0.1143)
		(layer "In4.Cu")
		(net "P3E_CPU0_PE3_OCP_TXN<1>")
	)
	(segment
		(start 301.88789 -103.167688)
		(end 301.79899 -103.078788)
		(width 0.0889)
		(layer "In4.Cu")
		(net "P3E_CPU0_PE3_OCP_TXN<1>")
	)
	(segment
		(start 418.950394 -61.2775)
		(end 416.234372 -61.2775)
		(width 0.1143)
		(layer "In4.Cu")
		(net "P3E_CPU0_PE3_OCP_TXN<1>")
	)
	(segment
		(start 421.324786 -59.93257)
		(end 420.295324 -59.93257)
		(width 0.1143)
		(layer "In4.Cu")
		(net "P3E_CPU0_PE3_OCP_TXN<1>")
	)
	(segment
		(start 416.234372 -61.2775)
		(end 414.250632 -63.26124)
		(width 0.1143)
		(layer "In4.Cu")
		(net "P3E_CPU0_PE3_OCP_TXN<1>")
	)
	(segment
		(start 298.064428 -102.710234)
		(end 298.08551 -102.788974)
		(width 0.0889)
		(layer "In4.Cu")
		(net "P3E_CPU0_PE3_OCP_TXN<1>")
	)
	(segment
		(start 301.43069 -103.167688)
		(end 301.15129 -103.167688)
		(width 0.0889)
		(layer "In4.Cu")
		(net "P3E_CPU0_PE3_OCP_TXN<1>")
	)
	(segment
		(start 430.64684 -63.02375)
		(end 429.185324 -61.562234)
		(width 0.1143)
		(layer "In4.Cu")
		(net "P3E_CPU0_PE3_OCP_TXN<1>")
	)
	(segment
		(start 299.647102 -103.547164)
		(end 299.146468 -103.04653)
		(width 0.0889)
		(layer "In4.Cu")
		(net "P3E_CPU0_PE3_OCP_TXN<1>")
	)
	(segment
		(start 302.645318 -103.392986)
		(end 302.645318 -103.267256)
		(width 0.0889)
		(layer "In4.Cu")
		(net "P3E_CPU0_PE3_OCP_TXN<1>")
	)
	(segment
		(start 302.25619 -103.078788)
		(end 302.16729 -103.167688)
		(width 0.0889)
		(layer "In4.Cu")
		(net "P3E_CPU0_PE3_OCP_TXN<1>")
	)
	(segment
		(start 420.295324 -59.93257)
		(end 418.950394 -61.2775)
		(width 0.1143)
		(layer "In4.Cu")
		(net "P3E_CPU0_PE3_OCP_TXN<1>")
	)
	(segment
		(start 366.167162 -58.622438)
		(end 358.719374 -66.070226)
		(width 0.1143)
		(layer "In4.Cu")
		(net "P3E_CPU0_PE3_OCP_TXN<1>")
	)
	(segment
		(start 378.562616 -57.038748)
		(end 377.74626 -57.855104)
		(width 0.1143)
		(layer "In4.Cu")
		(net "P3E_CPU0_PE3_OCP_TXN<1>")
	)
	(segment
		(start 380.452122 -57.93105)
		(end 379.55982 -57.038748)
		(width 0.1143)
		(layer "In4.Cu")
		(net "P3E_CPU0_PE3_OCP_TXN<1>")
	)
	(segment
		(start 399.363946 -58.2168)
		(end 390.963912 -58.2168)
		(width 0.1143)
		(layer "In4.Cu")
		(net "P3E_CPU0_PE3_OCP_TXN<1>")
	)
	(segment
		(start 338.321396 -67.029076)
		(end 331.897736 -71.258176)
		(width 0.1143)
		(layer "In4.Cu")
		(net "P3E_CPU0_PE3_OCP_TXN<1>")
	)
	(segment
		(start 409.854654 -61.917326)
		(end 408.560778 -60.62345)
		(width 0.1143)
		(layer "In4.Cu")
		(net "P3E_CPU0_PE3_OCP_TXN<1>")
	)
	(segment
		(start 460.2988 -54.972458)
		(end 459.226158 -56.0451)
		(width 0.1143)
		(layer "In4.Cu")
		(net "P3E_CPU0_PE3_OCP_TXN<1>")
	)
	(segment
		(start 349.888556 -66.250312)
		(end 348.619572 -65.954148)
		(width 0.1143)
		(layer "In4.Cu")
		(net "P3E_CPU0_PE3_OCP_TXN<1>")
	)
	(segment
		(start 304.4444 -104.3305)
		(end 303.708562 -104.3305)
		(width 0.0889)
		(layer "In4.Cu")
		(net "P3E_CPU0_PE3_OCP_TXN<1>")
	)
	(segment
		(start 304.4952 -104.3813)
		(end 304.4444 -104.3305)
		(width 0.0889)
		(layer "In4.Cu")
		(net "P3E_CPU0_PE3_OCP_TXN<1>")
	)
	(segment
		(start 344.107262 -66.303652)
		(end 343.169748 -66.084704)
		(width 0.1143)
		(layer "In4.Cu")
		(net "P3E_CPU0_PE3_OCP_TXN<1>")
	)
	(segment
		(start 455.457052 -61.236606)
		(end 434.49748 -61.236606)
		(width 0.1143)
		(layer "In4.Cu")
		(net "P3E_CPU0_PE3_OCP_TXN<1>")
	)
	(segment
		(start 411.181042 -61.917326)
		(end 409.854654 -61.917326)
		(width 0.1143)
		(layer "In4.Cu")
		(net "P3E_CPU0_PE3_OCP_TXN<1>")
	)
	(segment
		(start 348.619572 -65.954148)
		(end 347.098366 -66.249804)
		(width 0.1143)
		(layer "In4.Cu")
		(net "P3E_CPU0_PE3_OCP_TXN<1>")
	)
	(segment
		(start 300.345094 -103.547164)
		(end 299.647102 -103.547164)
		(width 0.0889)
		(layer "In4.Cu")
		(net "P3E_CPU0_PE3_OCP_TXN<1>")
	)
	(segment
		(start 355.47173 -67.017392)
		(end 350.773492 -66.077846)
		(width 0.1143)
		(layer "In4.Cu")
		(net "P3E_CPU0_PE3_OCP_TXN<1>")
	)
	(segment
		(start 302.95977 -103.581708)
		(end 302.83404 -103.581708)
		(width 0.0889)
		(layer "In4.Cu")
		(net "P3E_CPU0_PE3_OCP_TXN<1>")
	)
	(segment
		(start 358.719374 -66.070226)
		(end 357.698294 -66.070226)
		(width 0.1143)
		(layer "In4.Cu")
		(net "P3E_CPU0_PE3_OCP_TXN<1>")
	)
	(segment
		(start 302.16729 -103.167688)
		(end 301.88789 -103.167688)
		(width 0.0889)
		(layer "In4.Cu")
		(net "P3E_CPU0_PE3_OCP_TXN<1>")
	)
	(segment
		(start 298.08551 -102.788974)
		(end 298.378626 -102.958138)
		(width 0.0889)
		(layer "In4.Cu")
		(net "P3E_CPU0_PE3_OCP_TXN<1>")
	)
	(segment
		(start 307.523388 -103.622602)
		(end 305.690778 -104.3813)
		(width 0.1143)
		(layer "In4.Cu")
		(net "P3E_CPU0_PE3_OCP_TXN<1>")
	)
	(segment
		(start 429.185324 -61.562234)
		(end 429.185324 -59.150758)
		(width 0.1143)
		(layer "In4.Cu")
		(net "P3E_CPU0_PE3_OCP_TXN<1>")
	)
	(segment
		(start 323.807582 -87.34552)
		(end 307.523388 -103.622602)
		(width 0.1143)
		(layer "In4.Cu")
		(net "P3E_CPU0_PE3_OCP_TXN<1>")
	)
	(segment
		(start 459.226158 -56.0451)
		(end 458.438758 -56.0451)
		(width 0.1143)
		(layer "In4.Cu")
		(net "P3E_CPU0_PE3_OCP_TXN<1>")
	)
	(segment
		(start 434.49748 -61.236606)
		(end 432.710336 -63.02375)
		(width 0.1143)
		(layer "In4.Cu")
		(net "P3E_CPU0_PE3_OCP_TXN<1>")
	)
	(segment
		(start 302.45685 -103.078788)
		(end 302.25619 -103.078788)
		(width 0.0889)
		(layer "In4.Cu")
		(net "P3E_CPU0_PE3_OCP_TXN<1>")
	)
	(segment
		(start 302.645318 -103.267256)
		(end 302.45685 -103.078788)
		(width 0.0889)
		(layer "In4.Cu")
		(net "P3E_CPU0_PE3_OCP_TXN<1>")
	)
	(segment
		(start 405.289004 -60.036202)
		(end 405.033734 -59.780932)
		(width 0.1143)
		(layer "In4.Cu")
		(net "P3E_CPU0_PE3_OCP_TXN<1>")
	)
	(segment
		(start 301.51959 -103.078788)
		(end 301.43069 -103.167688)
		(width 0.0889)
		(layer "In4.Cu")
		(net "P3E_CPU0_PE3_OCP_TXN<1>")
	)
	(segment
		(start 456.6539 -57.829958)
		(end 456.6539 -60.039758)
		(width 0.1143)
		(layer "In4.Cu")
		(net "P3E_CPU0_PE3_OCP_TXN<1>")
	)
	(segment
		(start 377.74626 -57.855104)
		(end 375.530364 -57.855104)
		(width 0.1143)
		(layer "In4.Cu")
		(net "P3E_CPU0_PE3_OCP_TXN<1>")
	)
	(segment
		(start 305.690778 -104.3813)
		(end 304.517298 -104.3813)
		(width 0.1143)
		(layer "In4.Cu")
		(net "P3E_CPU0_PE3_OCP_TXN<1>")
	)
	(segment
		(start 390.782048 -58.398664)
		(end 382.396492 -58.398664)
		(width 0.1143)
		(layer "In4.Cu")
		(net "P3E_CPU0_PE3_OCP_TXN<1>")
	)
	(segment
		(start 406.66416 -60.62345)
		(end 406.076912 -60.036202)
		(width 0.1143)
		(layer "In4.Cu")
		(net "P3E_CPU0_PE3_OCP_TXN<1>")
	)
	(segment
		(start 301.06239 -103.078788)
		(end 300.81347 -103.078788)
		(width 0.0889)
		(layer "In4.Cu")
		(net "P3E_CPU0_PE3_OCP_TXN<1>")
	)
	(segment
		(start 458.438758 -56.0451)
		(end 456.6539 -57.829958)
		(width 0.1143)
		(layer "In4.Cu")
		(net "P3E_CPU0_PE3_OCP_TXN<1>")
	)
	(segment
		(start 425.680124 -59.755532)
		(end 421.501824 -59.755532)
		(width 0.1143)
		(layer "In4.Cu")
		(net "P3E_CPU0_PE3_OCP_TXN<1>")
	)
	(segment
		(start 390.963912 -58.2168)
		(end 390.782048 -58.398664)
		(width 0.1143)
		(layer "In4.Cu")
		(net "P3E_CPU0_PE3_OCP_TXN<1>")
	)
	(segment
		(start 343.169748 -66.084704)
		(end 338.321396 -67.029076)
		(width 0.1143)
		(layer "In4.Cu")
		(net "P3E_CPU0_PE3_OCP_TXN<1>")
	)
	(segment
		(start 426.643292 -58.792364)
		(end 425.680124 -59.755532)
		(width 0.1143)
		(layer "In4.Cu")
		(net "P3E_CPU0_PE3_OCP_TXN<1>")
	)
	(segment
		(start 460.78775 -53.906674)
		(end 460.413354 -53.906674)
		(width 0.1143)
		(layer "In4.Cu")
		(net "P3E_CPU0_PE3_OCP_TXN<1>")
	)
	(segment
		(start 456.6539 -60.039758)
		(end 455.457052 -61.236606)
		(width 0.1143)
		(layer "In4.Cu")
		(net "P3E_CPU0_PE3_OCP_TXN<1>")
	)
	(segment
		(start 405.033734 -59.780932)
		(end 400.928078 -59.780932)
		(width 0.1143)
		(layer "In4.Cu")
		(net "P3E_CPU0_PE3_OCP_TXN<1>")
	)
	(segment
		(start 298.393612 -102.558088)
		(end 298.36364 -102.558088)
		(width 0.0889)
		(layer "In4.Cu")
		(net "P3E_CPU0_PE3_OCP_TXN<1>")
	)
	(segment
		(start 350.773492 -66.077846)
		(end 349.888556 -66.250312)
		(width 0.1143)
		(layer "In4.Cu")
		(net "P3E_CPU0_PE3_OCP_TXN<1>")
	)
	(segment
		(start 421.501824 -59.755532)
		(end 421.324786 -59.93257)
		(width 0.1143)
		(layer "In4.Cu")
		(net "P3E_CPU0_PE3_OCP_TXN<1>")
	)
	(segment
		(start 460.413354 -53.906674)
		(end 460.2988 -54.021228)
		(width 0.1143)
		(layer "In4.Cu")
		(net "P3E_CPU0_PE3_OCP_TXN<1>")
	)
	(segment
		(start 381.928878 -57.93105)
		(end 380.452122 -57.93105)
		(width 0.1143)
		(layer "In4.Cu")
		(net "P3E_CPU0_PE3_OCP_TXN<1>")
	)
	(segment
		(start 300.81347 -103.078788)
		(end 300.345094 -103.547164)
		(width 0.0889)
		(layer "In4.Cu")
		(net "P3E_CPU0_PE3_OCP_TXN<1>")
	)
	(segment
		(start 382.396492 -58.398664)
		(end 381.928878 -57.93105)
		(width 0.1143)
		(layer "In4.Cu")
		(net "P3E_CPU0_PE3_OCP_TXN<1>")
	)
	(segment
		(start 412.524956 -63.26124)
		(end 411.181042 -61.917326)
		(width 0.1143)
		(layer "In4.Cu")
		(net "P3E_CPU0_PE3_OCP_TXN<1>")
	)
	(segment
		(start 414.250632 -63.26124)
		(end 412.524956 -63.26124)
		(width 0.1143)
		(layer "In4.Cu")
		(net "P3E_CPU0_PE3_OCP_TXN<1>")
	)
	(segment
		(start 370.319554 -57.7215)
		(end 369.418616 -58.622438)
		(width 0.1143)
		(layer "In4.Cu")
		(net "P3E_CPU0_PE3_OCP_TXN<1>")
	)
	(segment
		(start 432.710336 -63.02375)
		(end 430.64684 -63.02375)
		(width 0.1143)
		(layer "In4.Cu")
		(net "P3E_CPU0_PE3_OCP_TXN<1>")
	)
	(segment
		(start 328.314558 -76.4667)
		(end 323.807582 -87.34552)
		(width 0.1143)
		(layer "In4.Cu")
		(net "P3E_CPU0_PE3_OCP_TXN<1>")
	)
	(segment
		(start 302.83404 -103.581708)
		(end 302.645318 -103.392986)
		(width 0.0889)
		(layer "In4.Cu")
		(net "P3E_CPU0_PE3_OCP_TXN<1>")
	)
	(segment
		(start 408.560778 -60.62345)
		(end 406.66416 -60.62345)
		(width 0.1143)
		(layer "In4.Cu")
		(net "P3E_CPU0_PE3_OCP_TXN<1>")
	)
	(segment
		(start 428.82693 -58.792364)
		(end 426.643292 -58.792364)
		(width 0.1143)
		(layer "In4.Cu")
		(net "P3E_CPU0_PE3_OCP_TXN<1>")
	)
	(segment
		(start 429.185324 -59.150758)
		(end 428.82693 -58.792364)
		(width 0.1143)
		(layer "In4.Cu")
		(net "P3E_CPU0_PE3_OCP_TXN<1>")
	)
	(arc
		(start 299.146468 -103.04653)
		(mid 298.903136 -102.95008)
		(end 298.725336 -102.757986)
		(width 0.0889)
		(layer "In4.Cu")
		(net "P3E_CPU0_PE3_OCP_TXN<1>")
	)
	(arc
		(start 298.725336 -102.757986)
		(mid 298.585257 -102.61525)
		(end 298.393612 -102.558088)
		(width 0.0889)
		(layer "In4.Cu")
		(net "P3E_CPU0_PE3_OCP_TXN<1>")
	)
	(arc
		(start 298.36364 -102.558088)
		(mid 298.197346 -102.601322)
		(end 298.064428 -102.710234)
		(width 0.0889)
		(layer "In4.Cu")
		(net "P3E_CPU0_PE3_OCP_TXN<1>")
	)
	(segment
		(start 303.816766 -90.575384)
		(end 304.388266 -90.575384)
		(width 0.1143)
		(layer "F.Cu")
		(net "P3E_CPU0_PE3_OCP_TXN<15>")
	)
	(via
		(at 462.05775 -124.18822)
		(size 0.508)
		(drill 0.254)
		(layers "F.Cu" "B.Cu")
		(net "P3E_CPU0_PE3_OCP_TXN<15>")
	)
	(via
		(at 356.977442 -104.973374)
		(size 0.508)
		(drill 0.254)
		(layers "F.Cu" "B.Cu")
		(net "P3E_CPU0_PE3_OCP_TXN<15>")
	)
	(via
		(at 304.388266 -90.575384)
		(size 0.508)
		(drill 0.254)
		(layers "F.Cu" "B.Cu")
		(net "P3E_CPU0_PE3_OCP_TXN<15>")
	)
	(segment
		(start 465.328 -116.49202)
		(end 465.71535 -116.87937)
		(width 0.1143)
		(layer "B.Cu")
		(net "P3E_CPU0_PE3_OCP_TXN<15>")
	)
	(segment
		(start 464.319874 -118.262908)
		(end 464.029298 -118.827804)
		(width 0.1143)
		(layer "B.Cu")
		(net "P3E_CPU0_PE3_OCP_TXN<15>")
	)
	(segment
		(start 462.258156 -122.4407)
		(end 462.5721 -123.562364)
		(width 0.1143)
		(layer "B.Cu")
		(net "P3E_CPU0_PE3_OCP_TXN<15>")
	)
	(segment
		(start 462.982564 -119.625364)
		(end 462.982564 -119.625618)
		(width 0.1143)
		(layer "B.Cu")
		(net "P3E_CPU0_PE3_OCP_TXN<15>")
	)
	(segment
		(start 464.029298 -118.827804)
		(end 462.982564 -119.625364)
		(width 0.1143)
		(layer "B.Cu")
		(net "P3E_CPU0_PE3_OCP_TXN<15>")
	)
	(segment
		(start 462.4578 -124.18822)
		(end 462.05775 -124.18822)
		(width 0.1143)
		(layer "B.Cu")
		(net "P3E_CPU0_PE3_OCP_TXN<15>")
	)
	(segment
		(start 462.5721 -123.562364)
		(end 462.5721 -124.07392)
		(width 0.1143)
		(layer "B.Cu")
		(net "P3E_CPU0_PE3_OCP_TXN<15>")
	)
	(segment
		(start 465.71535 -117.239796)
		(end 465.424774 -117.648228)
		(width 0.1143)
		(layer "B.Cu")
		(net "P3E_CPU0_PE3_OCP_TXN<15>")
	)
	(segment
		(start 465.424774 -117.648228)
		(end 464.319874 -118.262908)
		(width 0.1143)
		(layer "B.Cu")
		(net "P3E_CPU0_PE3_OCP_TXN<15>")
	)
	(segment
		(start 462.5721 -124.07392)
		(end 462.4578 -124.18822)
		(width 0.1143)
		(layer "B.Cu")
		(net "P3E_CPU0_PE3_OCP_TXN<15>")
	)
	(segment
		(start 465.71535 -116.87937)
		(end 465.71535 -117.239796)
		(width 0.1143)
		(layer "B.Cu")
		(net "P3E_CPU0_PE3_OCP_TXN<15>")
	)
	(segment
		(start 462.982564 -119.625618)
		(end 462.258156 -122.4407)
		(width 0.1143)
		(layer "B.Cu")
		(net "P3E_CPU0_PE3_OCP_TXN<15>")
	)
	(segment
		(start 362.392214 -122.952764)
		(end 362.293916 -123.449842)
		(width 0.1143)
		(layer "In4.Cu")
		(net "P3E_CPU0_PE3_OCP_TXN<15>")
	)
	(segment
		(start 362.296202 -125.432566)
		(end 362.37418 -125.827028)
		(width 0.1143)
		(layer "In4.Cu")
		(net "P3E_CPU0_PE3_OCP_TXN<15>")
	)
	(segment
		(start 454.574656 -119.02313)
		(end 454.817226 -119.265446)
		(width 0.1143)
		(layer "In4.Cu")
		(net "P3E_CPU0_PE3_OCP_TXN<15>")
	)
	(segment
		(start 376.139202 -127.549656)
		(end 377.156726 -127.766572)
		(width 0.1143)
		(layer "In4.Cu")
		(net "P3E_CPU0_PE3_OCP_TXN<15>")
	)
	(segment
		(start 377.156726 -127.766572)
		(end 384.00736 -126.04115)
		(width 0.1143)
		(layer "In4.Cu")
		(net "P3E_CPU0_PE3_OCP_TXN<15>")
	)
	(segment
		(start 418.75964 -126.298706)
		(end 420.738554 -126.694184)
		(width 0.1143)
		(layer "In4.Cu")
		(net "P3E_CPU0_PE3_OCP_TXN<15>")
	)
	(segment
		(start 424.571922 -127.839216)
		(end 425.29379 -127.666496)
		(width 0.1143)
		(layer "In4.Cu")
		(net "P3E_CPU0_PE3_OCP_TXN<15>")
	)
	(segment
		(start 461.283558 -123.0884)
		(end 462.333848 -123.523756)
		(width 0.1143)
		(layer "In4.Cu")
		(net "P3E_CPU0_PE3_OCP_TXN<15>")
	)
	(segment
		(start 388.67334 -131.862576)
		(end 390.573768 -132.258562)
		(width 0.1143)
		(layer "In4.Cu")
		(net "P3E_CPU0_PE3_OCP_TXN<15>")
	)
	(segment
		(start 425.29379 -127.666496)
		(end 426.998892 -124.862844)
		(width 0.1143)
		(layer "In4.Cu")
		(net "P3E_CPU0_PE3_OCP_TXN<15>")
	)
	(segment
		(start 394.371068 -132.178552)
		(end 396.035784 -131.82727)
		(width 0.1143)
		(layer "In4.Cu")
		(net "P3E_CPU0_PE3_OCP_TXN<15>")
	)
	(segment
		(start 462.4324 -124.18822)
		(end 462.05775 -124.18822)
		(width 0.1143)
		(layer "In4.Cu")
		(net "P3E_CPU0_PE3_OCP_TXN<15>")
	)
	(segment
		(start 462.5467 -123.7361)
		(end 462.5467 -124.07392)
		(width 0.1143)
		(layer "In4.Cu")
		(net "P3E_CPU0_PE3_OCP_TXN<15>")
	)
	(segment
		(start 462.5467 -124.07392)
		(end 462.4324 -124.18822)
		(width 0.1143)
		(layer "In4.Cu")
		(net "P3E_CPU0_PE3_OCP_TXN<15>")
	)
	(segment
		(start 457.35621 -121.80443)
		(end 457.589636 -121.80443)
		(width 0.1143)
		(layer "In4.Cu")
		(net "P3E_CPU0_PE3_OCP_TXN<15>")
	)
	(segment
		(start 362.224574 -119.008906)
		(end 362.402628 -119.910606)
		(width 0.1143)
		(layer "In4.Cu")
		(net "P3E_CPU0_PE3_OCP_TXN<15>")
	)
	(segment
		(start 409.447492 -127.53213)
		(end 410.044138 -127.65024)
		(width 0.1143)
		(layer "In4.Cu")
		(net "P3E_CPU0_PE3_OCP_TXN<15>")
	)
	(segment
		(start 414.588706 -126.929896)
		(end 415.094674 -126.82982)
		(width 0.1143)
		(layer "In4.Cu")
		(net "P3E_CPU0_PE3_OCP_TXN<15>")
	)
	(segment
		(start 408.52725 -127.714248)
		(end 409.447492 -127.53213)
		(width 0.1143)
		(layer "In4.Cu")
		(net "P3E_CPU0_PE3_OCP_TXN<15>")
	)
	(segment
		(start 361.63885 -112.875822)
		(end 362.224574 -113.461546)
		(width 0.1143)
		(layer "In4.Cu")
		(net "P3E_CPU0_PE3_OCP_TXN<15>")
	)
	(segment
		(start 385.616704 -126.713996)
		(end 386.608574 -128.212596)
		(width 0.1143)
		(layer "In4.Cu")
		(net "P3E_CPU0_PE3_OCP_TXN<15>")
	)
	(segment
		(start 357.633016 -104.3178)
		(end 359.9942 -104.3178)
		(width 0.1143)
		(layer "In4.Cu")
		(net "P3E_CPU0_PE3_OCP_TXN<15>")
	)
	(segment
		(start 361.217972 -105.541572)
		(end 361.217972 -110.028228)
		(width 0.1143)
		(layer "In4.Cu")
		(net "P3E_CPU0_PE3_OCP_TXN<15>")
	)
	(segment
		(start 362.392468 -123.94819)
		(end 362.293662 -124.447808)
		(width 0.1143)
		(layer "In4.Cu")
		(net "P3E_CPU0_PE3_OCP_TXN<15>")
	)
	(segment
		(start 416.051492 -127.029718)
		(end 418.75964 -126.298706)
		(width 0.1143)
		(layer "In4.Cu")
		(net "P3E_CPU0_PE3_OCP_TXN<15>")
	)
	(segment
		(start 362.293662 -122.454416)
		(end 362.392214 -122.952764)
		(width 0.1143)
		(layer "In4.Cu")
		(net "P3E_CPU0_PE3_OCP_TXN<15>")
	)
	(segment
		(start 413.90443 -126.794514)
		(end 414.588706 -126.929896)
		(width 0.1143)
		(layer "In4.Cu")
		(net "P3E_CPU0_PE3_OCP_TXN<15>")
	)
	(segment
		(start 457.832206 -122.047)
		(end 460.346044 -123.0884)
		(width 0.1143)
		(layer "In4.Cu")
		(net "P3E_CPU0_PE3_OCP_TXN<15>")
	)
	(segment
		(start 457.113894 -121.562114)
		(end 457.35621 -121.80443)
		(width 0.1143)
		(layer "In4.Cu")
		(net "P3E_CPU0_PE3_OCP_TXN<15>")
	)
	(segment
		(start 420.738554 -126.694184)
		(end 424.571922 -127.839216)
		(width 0.1143)
		(layer "In4.Cu")
		(net "P3E_CPU0_PE3_OCP_TXN<15>")
	)
	(segment
		(start 386.608574 -128.212596)
		(end 386.967476 -129.976626)
		(width 0.1143)
		(layer "In4.Cu")
		(net "P3E_CPU0_PE3_OCP_TXN<15>")
	)
	(segment
		(start 410.044138 -127.65024)
		(end 410.542486 -127.551688)
		(width 0.1143)
		(layer "In4.Cu")
		(net "P3E_CPU0_PE3_OCP_TXN<15>")
	)
	(segment
		(start 362.392214 -120.959372)
		(end 362.302806 -121.412)
		(width 0.1143)
		(layer "In4.Cu")
		(net "P3E_CPU0_PE3_OCP_TXN<15>")
	)
	(segment
		(start 436.736998 -120.939306)
		(end 444.5127 -119.3927)
		(width 0.1143)
		(layer "In4.Cu")
		(net "P3E_CPU0_PE3_OCP_TXN<15>")
	)
	(segment
		(start 356.977442 -104.973374)
		(end 357.633016 -104.3178)
		(width 0.1143)
		(layer "In4.Cu")
		(net "P3E_CPU0_PE3_OCP_TXN<15>")
	)
	(segment
		(start 434.37048 -122.035062)
		(end 435.364382 -121.752868)
		(width 0.1143)
		(layer "In4.Cu")
		(net "P3E_CPU0_PE3_OCP_TXN<15>")
	)
	(segment
		(start 386.967476 -129.976626)
		(end 387.71195 -131.294886)
		(width 0.1143)
		(layer "In4.Cu")
		(net "P3E_CPU0_PE3_OCP_TXN<15>")
	)
	(segment
		(start 428.863506 -122.143774)
		(end 430.301908 -122.430794)
		(width 0.1143)
		(layer "In4.Cu")
		(net "P3E_CPU0_PE3_OCP_TXN<15>")
	)
	(segment
		(start 397.625062 -132.229352)
		(end 408.52725 -127.714248)
		(width 0.1143)
		(layer "In4.Cu")
		(net "P3E_CPU0_PE3_OCP_TXN<15>")
	)
	(segment
		(start 361.217972 -110.028228)
		(end 361.63885 -110.449106)
		(width 0.1143)
		(layer "In4.Cu")
		(net "P3E_CPU0_PE3_OCP_TXN<15>")
	)
	(segment
		(start 432.597306 -122.00255)
		(end 433.486814 -121.838466)
		(width 0.1143)
		(layer "In4.Cu")
		(net "P3E_CPU0_PE3_OCP_TXN<15>")
	)
	(segment
		(start 454.325736 -118.54053)
		(end 454.574656 -118.78945)
		(width 0.1143)
		(layer "In4.Cu")
		(net "P3E_CPU0_PE3_OCP_TXN<15>")
	)
	(segment
		(start 430.301908 -122.430794)
		(end 432.097688 -121.879614)
		(width 0.1143)
		(layer "In4.Cu")
		(net "P3E_CPU0_PE3_OCP_TXN<15>")
	)
	(segment
		(start 359.9942 -104.3178)
		(end 361.217972 -105.541572)
		(width 0.1143)
		(layer "In4.Cu")
		(net "P3E_CPU0_PE3_OCP_TXN<15>")
	)
	(segment
		(start 457.589636 -121.80443)
		(end 457.832206 -122.047)
		(width 0.1143)
		(layer "In4.Cu")
		(net "P3E_CPU0_PE3_OCP_TXN<15>")
	)
	(segment
		(start 372.305326 -127.136398)
		(end 375.387362 -127.71628)
		(width 0.1143)
		(layer "In4.Cu")
		(net "P3E_CPU0_PE3_OCP_TXN<15>")
	)
	(segment
		(start 412.464758 -127.378206)
		(end 413.90443 -126.794514)
		(width 0.1143)
		(layer "In4.Cu")
		(net "P3E_CPU0_PE3_OCP_TXN<15>")
	)
	(segment
		(start 411.06471 -127.65532)
		(end 412.464758 -127.378206)
		(width 0.1143)
		(layer "In4.Cu")
		(net "P3E_CPU0_PE3_OCP_TXN<15>")
	)
	(segment
		(start 362.293916 -123.449842)
		(end 362.392468 -123.94819)
		(width 0.1143)
		(layer "In4.Cu")
		(net "P3E_CPU0_PE3_OCP_TXN<15>")
	)
	(segment
		(start 455.050652 -119.265446)
		(end 455.293222 -119.508016)
		(width 0.1143)
		(layer "In4.Cu")
		(net "P3E_CPU0_PE3_OCP_TXN<15>")
	)
	(segment
		(start 433.486814 -121.838466)
		(end 434.37048 -122.035062)
		(width 0.1143)
		(layer "In4.Cu")
		(net "P3E_CPU0_PE3_OCP_TXN<15>")
	)
	(segment
		(start 455.293222 -119.741442)
		(end 455.535538 -119.984012)
		(width 0.1143)
		(layer "In4.Cu")
		(net "P3E_CPU0_PE3_OCP_TXN<15>")
	)
	(segment
		(start 445.7446 -118.1608)
		(end 453.409558 -118.1608)
		(width 0.1143)
		(layer "In4.Cu")
		(net "P3E_CPU0_PE3_OCP_TXN<15>")
	)
	(segment
		(start 363.836458 -127.10541)
		(end 369.376198 -128.23317)
		(width 0.1143)
		(layer "In4.Cu")
		(net "P3E_CPU0_PE3_OCP_TXN<15>")
	)
	(segment
		(start 390.573768 -132.258562)
		(end 392.773154 -131.815078)
		(width 0.1143)
		(layer "In4.Cu")
		(net "P3E_CPU0_PE3_OCP_TXN<15>")
	)
	(segment
		(start 455.769218 -119.984012)
		(end 457.113894 -121.328688)
		(width 0.1143)
		(layer "In4.Cu")
		(net "P3E_CPU0_PE3_OCP_TXN<15>")
	)
	(segment
		(start 362.37418 -125.827028)
		(end 363.017562 -126.781306)
		(width 0.1143)
		(layer "In4.Cu")
		(net "P3E_CPU0_PE3_OCP_TXN<15>")
	)
	(segment
		(start 427.833028 -122.728482)
		(end 428.863506 -122.143774)
		(width 0.1143)
		(layer "In4.Cu")
		(net "P3E_CPU0_PE3_OCP_TXN<15>")
	)
	(segment
		(start 384.862832 -126.21514)
		(end 385.616704 -126.713996)
		(width 0.1143)
		(layer "In4.Cu")
		(net "P3E_CPU0_PE3_OCP_TXN<15>")
	)
	(segment
		(start 362.401358 -121.910856)
		(end 362.293662 -122.454416)
		(width 0.1143)
		(layer "In4.Cu")
		(net "P3E_CPU0_PE3_OCP_TXN<15>")
	)
	(segment
		(start 454.817226 -119.265446)
		(end 455.050652 -119.265446)
		(width 0.1143)
		(layer "In4.Cu")
		(net "P3E_CPU0_PE3_OCP_TXN<15>")
	)
	(segment
		(start 362.402628 -119.910606)
		(end 362.293662 -120.461024)
		(width 0.1143)
		(layer "In4.Cu")
		(net "P3E_CPU0_PE3_OCP_TXN<15>")
	)
	(segment
		(start 432.097688 -121.879614)
		(end 432.597306 -122.00255)
		(width 0.1143)
		(layer "In4.Cu")
		(net "P3E_CPU0_PE3_OCP_TXN<15>")
	)
	(segment
		(start 362.293662 -120.461024)
		(end 362.392214 -120.959372)
		(width 0.1143)
		(layer "In4.Cu")
		(net "P3E_CPU0_PE3_OCP_TXN<15>")
	)
	(segment
		(start 455.535538 -119.984012)
		(end 455.769218 -119.984012)
		(width 0.1143)
		(layer "In4.Cu")
		(net "P3E_CPU0_PE3_OCP_TXN<15>")
	)
	(segment
		(start 387.71195 -131.294886)
		(end 388.67334 -131.862576)
		(width 0.1143)
		(layer "In4.Cu")
		(net "P3E_CPU0_PE3_OCP_TXN<15>")
	)
	(segment
		(start 369.376198 -128.23317)
		(end 372.305326 -127.136398)
		(width 0.1143)
		(layer "In4.Cu")
		(net "P3E_CPU0_PE3_OCP_TXN<15>")
	)
	(segment
		(start 453.409558 -118.1608)
		(end 454.325736 -118.54053)
		(width 0.1143)
		(layer "In4.Cu")
		(net "P3E_CPU0_PE3_OCP_TXN<15>")
	)
	(segment
		(start 462.333848 -123.523756)
		(end 462.5467 -123.7361)
		(width 0.1143)
		(layer "In4.Cu")
		(net "P3E_CPU0_PE3_OCP_TXN<15>")
	)
	(segment
		(start 410.542486 -127.551688)
		(end 411.06471 -127.65532)
		(width 0.1143)
		(layer "In4.Cu")
		(net "P3E_CPU0_PE3_OCP_TXN<15>")
	)
	(segment
		(start 361.63885 -110.449106)
		(end 361.63885 -112.875822)
		(width 0.1143)
		(layer "In4.Cu")
		(net "P3E_CPU0_PE3_OCP_TXN<15>")
	)
	(segment
		(start 362.302806 -121.412)
		(end 362.401358 -121.910856)
		(width 0.1143)
		(layer "In4.Cu")
		(net "P3E_CPU0_PE3_OCP_TXN<15>")
	)
	(segment
		(start 457.113894 -121.328688)
		(end 457.113894 -121.562114)
		(width 0.1143)
		(layer "In4.Cu")
		(net "P3E_CPU0_PE3_OCP_TXN<15>")
	)
	(segment
		(start 362.293662 -124.447808)
		(end 362.392468 -124.946156)
		(width 0.1143)
		(layer "In4.Cu")
		(net "P3E_CPU0_PE3_OCP_TXN<15>")
	)
	(segment
		(start 455.293222 -119.508016)
		(end 455.293222 -119.741442)
		(width 0.1143)
		(layer "In4.Cu")
		(net "P3E_CPU0_PE3_OCP_TXN<15>")
	)
	(segment
		(start 415.094674 -126.82982)
		(end 416.051492 -127.029718)
		(width 0.1143)
		(layer "In4.Cu")
		(net "P3E_CPU0_PE3_OCP_TXN<15>")
	)
	(segment
		(start 444.5127 -119.3927)
		(end 445.7446 -118.1608)
		(width 0.1143)
		(layer "In4.Cu")
		(net "P3E_CPU0_PE3_OCP_TXN<15>")
	)
	(segment
		(start 363.017562 -126.781306)
		(end 363.836458 -127.10541)
		(width 0.1143)
		(layer "In4.Cu")
		(net "P3E_CPU0_PE3_OCP_TXN<15>")
	)
	(segment
		(start 384.00736 -126.04115)
		(end 384.862832 -126.21514)
		(width 0.1143)
		(layer "In4.Cu")
		(net "P3E_CPU0_PE3_OCP_TXN<15>")
	)
	(segment
		(start 454.574656 -118.78945)
		(end 454.574656 -119.02313)
		(width 0.1143)
		(layer "In4.Cu")
		(net "P3E_CPU0_PE3_OCP_TXN<15>")
	)
	(segment
		(start 392.773154 -131.815078)
		(end 394.371068 -132.178552)
		(width 0.1143)
		(layer "In4.Cu")
		(net "P3E_CPU0_PE3_OCP_TXN<15>")
	)
	(segment
		(start 375.387362 -127.71628)
		(end 376.139202 -127.549656)
		(width 0.1143)
		(layer "In4.Cu")
		(net "P3E_CPU0_PE3_OCP_TXN<15>")
	)
	(segment
		(start 435.364382 -121.752868)
		(end 436.736998 -120.939306)
		(width 0.1143)
		(layer "In4.Cu")
		(net "P3E_CPU0_PE3_OCP_TXN<15>")
	)
	(segment
		(start 362.224574 -113.461546)
		(end 362.224574 -119.008906)
		(width 0.1143)
		(layer "In4.Cu")
		(net "P3E_CPU0_PE3_OCP_TXN<15>")
	)
	(segment
		(start 362.392468 -124.946156)
		(end 362.296202 -125.432566)
		(width 0.1143)
		(layer "In4.Cu")
		(net "P3E_CPU0_PE3_OCP_TXN<15>")
	)
	(segment
		(start 460.346044 -123.0884)
		(end 461.283558 -123.0884)
		(width 0.1143)
		(layer "In4.Cu")
		(net "P3E_CPU0_PE3_OCP_TXN<15>")
	)
	(segment
		(start 426.998892 -124.862844)
		(end 427.833028 -122.728482)
		(width 0.1143)
		(layer "In4.Cu")
		(net "P3E_CPU0_PE3_OCP_TXN<15>")
	)
	(segment
		(start 396.035784 -131.82727)
		(end 397.625062 -132.229352)
		(width 0.1143)
		(layer "In4.Cu")
		(net "P3E_CPU0_PE3_OCP_TXN<15>")
	)
	(segment
		(start 340.609936 -101.459792)
		(end 341.592662 -103.833168)
		(width 0.1143)
		(layer "In11.Cu")
		(net "P3E_CPU0_PE3_OCP_TXN<15>")
	)
	(segment
		(start 323.556376 -96.65716)
		(end 331.577442 -99.979734)
		(width 0.1143)
		(layer "In11.Cu")
		(net "P3E_CPU0_PE3_OCP_TXN<15>")
	)
	(segment
		(start 339.872828 -100.565458)
		(end 340.609936 -101.459792)
		(width 0.1143)
		(layer "In11.Cu")
		(net "P3E_CPU0_PE3_OCP_TXN<15>")
	)
	(segment
		(start 308.57317 -90.2208)
		(end 316.585346 -91.814142)
		(width 0.1143)
		(layer "In11.Cu")
		(net "P3E_CPU0_PE3_OCP_TXN<15>")
	)
	(segment
		(start 308.180486 -90.2208)
		(end 308.57317 -90.2208)
		(width 0.1143)
		(layer "In11.Cu")
		(net "P3E_CPU0_PE3_OCP_TXN<15>")
	)
	(segment
		(start 338.40801 -99.925632)
		(end 339.872828 -100.565458)
		(width 0.1143)
		(layer "In11.Cu")
		(net "P3E_CPU0_PE3_OCP_TXN<15>")
	)
	(segment
		(start 321.28079 -93.75902)
		(end 323.556376 -96.65716)
		(width 0.1143)
		(layer "In11.Cu")
		(net "P3E_CPU0_PE3_OCP_TXN<15>")
	)
	(segment
		(start 308.157118 -90.2208)
		(end 308.180486 -90.2208)
		(width 0.0889)
		(layer "In11.Cu")
		(net "P3E_CPU0_PE3_OCP_TXN<15>")
	)
	(segment
		(start 304.388266 -90.274648)
		(end 304.48758 -90.175334)
		(width 0.0889)
		(layer "In11.Cu")
		(net "P3E_CPU0_PE3_OCP_TXN<15>")
	)
	(segment
		(start 356.863142 -104.484424)
		(end 356.977442 -104.598724)
		(width 0.1143)
		(layer "In11.Cu")
		(net "P3E_CPU0_PE3_OCP_TXN<15>")
	)
	(segment
		(start 356.977442 -104.598724)
		(end 356.977442 -104.973374)
		(width 0.1143)
		(layer "In11.Cu")
		(net "P3E_CPU0_PE3_OCP_TXN<15>")
	)
	(segment
		(start 316.585346 -91.814142)
		(end 321.28079 -93.75902)
		(width 0.1143)
		(layer "In11.Cu")
		(net "P3E_CPU0_PE3_OCP_TXN<15>")
	)
	(segment
		(start 333.582518 -100.323396)
		(end 335.938876 -99.926394)
		(width 0.1143)
		(layer "In11.Cu")
		(net "P3E_CPU0_PE3_OCP_TXN<15>")
	)
	(segment
		(start 337.14055 -100.089208)
		(end 338.40801 -99.925632)
		(width 0.1143)
		(layer "In11.Cu")
		(net "P3E_CPU0_PE3_OCP_TXN<15>")
	)
	(segment
		(start 331.577442 -99.979734)
		(end 333.582518 -100.323396)
		(width 0.1143)
		(layer "In11.Cu")
		(net "P3E_CPU0_PE3_OCP_TXN<15>")
	)
	(segment
		(start 343.515442 -105.217214)
		(end 353.68357 -107.196128)
		(width 0.1143)
		(layer "In11.Cu")
		(net "P3E_CPU0_PE3_OCP_TXN<15>")
	)
	(segment
		(start 353.68357 -107.196128)
		(end 355.275896 -106.909362)
		(width 0.1143)
		(layer "In11.Cu")
		(net "P3E_CPU0_PE3_OCP_TXN<15>")
	)
	(segment
		(start 355.790754 -104.81437)
		(end 356.1207 -104.484424)
		(width 0.1143)
		(layer "In11.Cu")
		(net "P3E_CPU0_PE3_OCP_TXN<15>")
	)
	(segment
		(start 355.790754 -106.274362)
		(end 355.790754 -104.81437)
		(width 0.1143)
		(layer "In11.Cu")
		(net "P3E_CPU0_PE3_OCP_TXN<15>")
	)
	(segment
		(start 355.275896 -106.909362)
		(end 355.790754 -106.274362)
		(width 0.1143)
		(layer "In11.Cu")
		(net "P3E_CPU0_PE3_OCP_TXN<15>")
	)
	(segment
		(start 304.48758 -90.175334)
		(end 308.111652 -90.175334)
		(width 0.0889)
		(layer "In11.Cu")
		(net "P3E_CPU0_PE3_OCP_TXN<15>")
	)
	(segment
		(start 341.592662 -103.833168)
		(end 343.51468 -105.21696)
		(width 0.1143)
		(layer "In11.Cu")
		(net "P3E_CPU0_PE3_OCP_TXN<15>")
	)
	(segment
		(start 356.1207 -104.484424)
		(end 356.863142 -104.484424)
		(width 0.1143)
		(layer "In11.Cu")
		(net "P3E_CPU0_PE3_OCP_TXN<15>")
	)
	(segment
		(start 343.51468 -105.21696)
		(end 343.515442 -105.217214)
		(width 0.1143)
		(layer "In11.Cu")
		(net "P3E_CPU0_PE3_OCP_TXN<15>")
	)
	(segment
		(start 308.111652 -90.175334)
		(end 308.157118 -90.2208)
		(width 0.0889)
		(layer "In11.Cu")
		(net "P3E_CPU0_PE3_OCP_TXN<15>")
	)
	(segment
		(start 335.938876 -99.926394)
		(end 337.14055 -100.089208)
		(width 0.1143)
		(layer "In11.Cu")
		(net "P3E_CPU0_PE3_OCP_TXN<15>")
	)
	(segment
		(start 304.388266 -90.575384)
		(end 304.388266 -90.274648)
		(width 0.0889)
		(layer "In11.Cu")
		(net "P3E_CPU0_PE3_OCP_TXN<15>")
	)
	(segment
		(start 303.816766 -91.565984)
		(end 304.388266 -91.565984)
		(width 0.1143)
		(layer "F.Cu")
		(net "P3E_CPU0_PE3_OCP_TXN<14>")
	)
	(via
		(at 458.97165 -124.13742)
		(size 0.508)
		(drill 0.254)
		(layers "F.Cu" "B.Cu")
		(net "P3E_CPU0_PE3_OCP_TXN<14>")
	)
	(via
		(at 357.418132 -107.08005)
		(size 0.508)
		(drill 0.254)
		(layers "F.Cu" "B.Cu")
		(net "P3E_CPU0_PE3_OCP_TXN<14>")
	)
	(via
		(at 304.388266 -91.565984)
		(size 0.508)
		(drill 0.254)
		(layers "F.Cu" "B.Cu")
		(net "P3E_CPU0_PE3_OCP_TXN<14>")
	)
	(segment
		(start 462.41335 -116.87937)
		(end 462.41335 -117.239796)
		(width 0.1143)
		(layer "B.Cu")
		(net "P3E_CPU0_PE3_OCP_TXN<14>")
	)
	(segment
		(start 459.10627 -122.597926)
		(end 459.486 -123.745244)
		(width 0.1143)
		(layer "B.Cu")
		(net "P3E_CPU0_PE3_OCP_TXN<14>")
	)
	(segment
		(start 462.25587 -117.532404)
		(end 461.470756 -118.081298)
		(width 0.1143)
		(layer "B.Cu")
		(net "P3E_CPU0_PE3_OCP_TXN<14>")
	)
	(segment
		(start 461.470756 -118.081552)
		(end 460.638906 -118.662958)
		(width 0.1143)
		(layer "B.Cu")
		(net "P3E_CPU0_PE3_OCP_TXN<14>")
	)
	(segment
		(start 459.486 -124.02312)
		(end 459.3717 -124.13742)
		(width 0.1143)
		(layer "B.Cu")
		(net "P3E_CPU0_PE3_OCP_TXN<14>")
	)
	(segment
		(start 461.470756 -118.081298)
		(end 461.470756 -118.081552)
		(width 0.1143)
		(layer "B.Cu")
		(net "P3E_CPU0_PE3_OCP_TXN<14>")
	)
	(segment
		(start 462.026 -116.49202)
		(end 462.41335 -116.87937)
		(width 0.1143)
		(layer "B.Cu")
		(net "P3E_CPU0_PE3_OCP_TXN<14>")
	)
	(segment
		(start 462.41335 -117.239796)
		(end 462.25587 -117.532404)
		(width 0.1143)
		(layer "B.Cu")
		(net "P3E_CPU0_PE3_OCP_TXN<14>")
	)
	(segment
		(start 459.3717 -124.13742)
		(end 458.97165 -124.13742)
		(width 0.1143)
		(layer "B.Cu")
		(net "P3E_CPU0_PE3_OCP_TXN<14>")
	)
	(segment
		(start 459.486 -123.745244)
		(end 459.486 -124.02312)
		(width 0.1143)
		(layer "B.Cu")
		(net "P3E_CPU0_PE3_OCP_TXN<14>")
	)
	(segment
		(start 460.638906 -118.662958)
		(end 459.565502 -120.622568)
		(width 0.1143)
		(layer "B.Cu")
		(net "P3E_CPU0_PE3_OCP_TXN<14>")
	)
	(segment
		(start 459.565502 -120.622568)
		(end 459.10627 -122.597926)
		(width 0.1143)
		(layer "B.Cu")
		(net "P3E_CPU0_PE3_OCP_TXN<14>")
	)
	(segment
		(start 437.689244 -121.498106)
		(end 432.15687 -124.778008)
		(width 0.1143)
		(layer "In4.Cu")
		(net "P3E_CPU0_PE3_OCP_TXN<14>")
	)
	(segment
		(start 361.753404 -126.052326)
		(end 361.633516 -125.444504)
		(width 0.1143)
		(layer "In4.Cu")
		(net "P3E_CPU0_PE3_OCP_TXN<14>")
	)
	(segment
		(start 458.97165 -124.13742)
		(end 459.3463 -124.13742)
		(width 0.1143)
		(layer "In4.Cu")
		(net "P3E_CPU0_PE3_OCP_TXN<14>")
	)
	(segment
		(start 392.751818 -132.480304)
		(end 390.571482 -132.919724)
		(width 0.1143)
		(layer "In4.Cu")
		(net "P3E_CPU0_PE3_OCP_TXN<14>")
	)
	(segment
		(start 418.749734 -126.96317)
		(end 416.051492 -127.691388)
		(width 0.1143)
		(layer "In4.Cu")
		(net "P3E_CPU0_PE3_OCP_TXN<14>")
	)
	(segment
		(start 430.621694 -125.170946)
		(end 429.606964 -124.948696)
		(width 0.1143)
		(layer "In4.Cu")
		(net "P3E_CPU0_PE3_OCP_TXN<14>")
	)
	(segment
		(start 453.066658 -120.05945)
		(end 452.463408 -119.4562)
		(width 0.1143)
		(layer "In4.Cu")
		(net "P3E_CPU0_PE3_OCP_TXN<14>")
	)
	(segment
		(start 453.7202 -122.129042)
		(end 453.7202 -121.636282)
		(width 0.1143)
		(layer "In4.Cu")
		(net "P3E_CPU0_PE3_OCP_TXN<14>")
	)
	(segment
		(start 361.732068 -122.952764)
		(end 361.633516 -122.454416)
		(width 0.1143)
		(layer "In4.Cu")
		(net "P3E_CPU0_PE3_OCP_TXN<14>")
	)
	(segment
		(start 361.633516 -120.461024)
		(end 361.73664 -119.94007)
		(width 0.1143)
		(layer "In4.Cu")
		(net "P3E_CPU0_PE3_OCP_TXN<14>")
	)
	(segment
		(start 425.707556 -128.233678)
		(end 424.55338 -128.509522)
		(width 0.1143)
		(layer "In4.Cu")
		(net "P3E_CPU0_PE3_OCP_TXN<14>")
	)
	(segment
		(start 394.353288 -132.84454)
		(end 392.751818 -132.480304)
		(width 0.1143)
		(layer "In4.Cu")
		(net "P3E_CPU0_PE3_OCP_TXN<14>")
	)
	(segment
		(start 360.97337 -110.682024)
		(end 360.582972 -110.291626)
		(width 0.1143)
		(layer "In4.Cu")
		(net "P3E_CPU0_PE3_OCP_TXN<14>")
	)
	(segment
		(start 380.769114 -127.524764)
		(end 377.169172 -128.431544)
		(width 0.1143)
		(layer "In4.Cu")
		(net "P3E_CPU0_PE3_OCP_TXN<14>")
	)
	(segment
		(start 440.31154 -121.145046)
		(end 440.117484 -121.015506)
		(width 0.1143)
		(layer "In4.Cu")
		(net "P3E_CPU0_PE3_OCP_TXN<14>")
	)
	(segment
		(start 459.3463 -124.13742)
		(end 459.4606 -124.02312)
		(width 0.1143)
		(layer "In4.Cu")
		(net "P3E_CPU0_PE3_OCP_TXN<14>")
	)
	(segment
		(start 412.688786 -127.986282)
		(end 411.047438 -128.31191)
		(width 0.1143)
		(layer "In4.Cu")
		(net "P3E_CPU0_PE3_OCP_TXN<14>")
	)
	(segment
		(start 358.581198 -105.0544)
		(end 358.336342 -105.299256)
		(width 0.1143)
		(layer "In4.Cu")
		(net "P3E_CPU0_PE3_OCP_TXN<14>")
	)
	(segment
		(start 361.73664 -119.94007)
		(end 361.583478 -119.164354)
		(width 0.1143)
		(layer "In4.Cu")
		(net "P3E_CPU0_PE3_OCP_TXN<14>")
	)
	(segment
		(start 383.011426 -128.530096)
		(end 381.521462 -127.735584)
		(width 0.1143)
		(layer "In4.Cu")
		(net "P3E_CPU0_PE3_OCP_TXN<14>")
	)
	(segment
		(start 424.55338 -128.509522)
		(end 420.641018 -127.340868)
		(width 0.1143)
		(layer "In4.Cu")
		(net "P3E_CPU0_PE3_OCP_TXN<14>")
	)
	(segment
		(start 439.651394 -121.276364)
		(end 439.315098 -121.343166)
		(width 0.1143)
		(layer "In4.Cu")
		(net "P3E_CPU0_PE3_OCP_TXN<14>")
	)
	(segment
		(start 414.58769 -127.590296)
		(end 413.968438 -127.46736)
		(width 0.1143)
		(layer "In4.Cu")
		(net "P3E_CPU0_PE3_OCP_TXN<14>")
	)
	(segment
		(start 440.77763 -120.884188)
		(end 440.647836 -121.078244)
		(width 0.1143)
		(layer "In4.Cu")
		(net "P3E_CPU0_PE3_OCP_TXN<14>")
	)
	(segment
		(start 411.047438 -128.31191)
		(end 410.542994 -128.211834)
		(width 0.1143)
		(layer "In4.Cu")
		(net "P3E_CPU0_PE3_OCP_TXN<14>")
	)
	(segment
		(start 396.022576 -132.491988)
		(end 394.353288 -132.84454)
		(width 0.1143)
		(layer "In4.Cu")
		(net "P3E_CPU0_PE3_OCP_TXN<14>")
	)
	(segment
		(start 440.647836 -121.078244)
		(end 440.31154 -121.145046)
		(width 0.1143)
		(layer "In4.Cu")
		(net "P3E_CPU0_PE3_OCP_TXN<14>")
	)
	(segment
		(start 427.866048 -125.406912)
		(end 427.13275 -125.89002)
		(width 0.1143)
		(layer "In4.Cu")
		(net "P3E_CPU0_PE3_OCP_TXN<14>")
	)
	(segment
		(start 439.781188 -121.082308)
		(end 439.651394 -121.276364)
		(width 0.1143)
		(layer "In4.Cu")
		(net "P3E_CPU0_PE3_OCP_TXN<14>")
	)
	(segment
		(start 361.583478 -113.718848)
		(end 360.97337 -113.10874)
		(width 0.1143)
		(layer "In4.Cu")
		(net "P3E_CPU0_PE3_OCP_TXN<14>")
	)
	(segment
		(start 361.633516 -125.444504)
		(end 361.732068 -124.946156)
		(width 0.1143)
		(layer "In4.Cu")
		(net "P3E_CPU0_PE3_OCP_TXN<14>")
	)
	(segment
		(start 454.359518 -122.76836)
		(end 453.7202 -122.129042)
		(width 0.1143)
		(layer "In4.Cu")
		(net "P3E_CPU0_PE3_OCP_TXN<14>")
	)
	(segment
		(start 360.97337 -113.10874)
		(end 360.97337 -110.682024)
		(width 0.1143)
		(layer "In4.Cu")
		(net "P3E_CPU0_PE3_OCP_TXN<14>")
	)
	(segment
		(start 362.603796 -127.313944)
		(end 361.753404 -126.052326)
		(width 0.1143)
		(layer "In4.Cu")
		(net "P3E_CPU0_PE3_OCP_TXN<14>")
	)
	(segment
		(start 369.38331 -128.922018)
		(end 363.785912 -127.782574)
		(width 0.1143)
		(layer "In4.Cu")
		(net "P3E_CPU0_PE3_OCP_TXN<14>")
	)
	(segment
		(start 437.689244 -121.49836)
		(end 437.689244 -121.498106)
		(width 0.1143)
		(layer "In4.Cu")
		(net "P3E_CPU0_PE3_OCP_TXN<14>")
	)
	(segment
		(start 458.838554 -123.18492)
		(end 456.745086 -122.76836)
		(width 0.1143)
		(layer "In4.Cu")
		(net "P3E_CPU0_PE3_OCP_TXN<14>")
	)
	(segment
		(start 363.785912 -127.782574)
		(end 362.603796 -127.313944)
		(width 0.1143)
		(layer "In4.Cu")
		(net "P3E_CPU0_PE3_OCP_TXN<14>")
	)
	(segment
		(start 420.641018 -127.340868)
		(end 418.749734 -126.96317)
		(width 0.1143)
		(layer "In4.Cu")
		(net "P3E_CPU0_PE3_OCP_TXN<14>")
	)
	(segment
		(start 456.745086 -122.76836)
		(end 454.359518 -122.76836)
		(width 0.1143)
		(layer "In4.Cu")
		(net "P3E_CPU0_PE3_OCP_TXN<14>")
	)
	(segment
		(start 375.39803 -128.377442)
		(end 372.363238 -127.80645)
		(width 0.1143)
		(layer "In4.Cu")
		(net "P3E_CPU0_PE3_OCP_TXN<14>")
	)
	(segment
		(start 439.121042 -121.213626)
		(end 437.689244 -121.49836)
		(width 0.1143)
		(layer "In4.Cu")
		(net "P3E_CPU0_PE3_OCP_TXN<14>")
	)
	(segment
		(start 390.571482 -132.919724)
		(end 388.436358 -132.474716)
		(width 0.1143)
		(layer "In4.Cu")
		(net "P3E_CPU0_PE3_OCP_TXN<14>")
	)
	(segment
		(start 361.732068 -120.959372)
		(end 361.633516 -120.461024)
		(width 0.1143)
		(layer "In4.Cu")
		(net "P3E_CPU0_PE3_OCP_TXN<14>")
	)
	(segment
		(start 384.282696 -128.530096)
		(end 383.011426 -128.530096)
		(width 0.1143)
		(layer "In4.Cu")
		(net "P3E_CPU0_PE3_OCP_TXN<14>")
	)
	(segment
		(start 360.582972 -110.291626)
		(end 360.582972 -106.056684)
		(width 0.1143)
		(layer "In4.Cu")
		(net "P3E_CPU0_PE3_OCP_TXN<14>")
	)
	(segment
		(start 372.363238 -127.80645)
		(end 369.38331 -128.922018)
		(width 0.1143)
		(layer "In4.Cu")
		(net "P3E_CPU0_PE3_OCP_TXN<14>")
	)
	(segment
		(start 358.336342 -106.292396)
		(end 358.0511 -106.577638)
		(width 0.1143)
		(layer "In4.Cu")
		(net "P3E_CPU0_PE3_OCP_TXN<14>")
	)
	(segment
		(start 452.463408 -119.4562)
		(end 447.957448 -119.4562)
		(width 0.1143)
		(layer "In4.Cu")
		(net "P3E_CPU0_PE3_OCP_TXN<14>")
	)
	(segment
		(start 361.628436 -123.476512)
		(end 361.732068 -122.952764)
		(width 0.1143)
		(layer "In4.Cu")
		(net "P3E_CPU0_PE3_OCP_TXN<14>")
	)
	(segment
		(start 429.606964 -124.948696)
		(end 427.866048 -125.406912)
		(width 0.1143)
		(layer "In4.Cu")
		(net "P3E_CPU0_PE3_OCP_TXN<14>")
	)
	(segment
		(start 360.582972 -106.056684)
		(end 359.580688 -105.0544)
		(width 0.1143)
		(layer "In4.Cu")
		(net "P3E_CPU0_PE3_OCP_TXN<14>")
	)
	(segment
		(start 361.732068 -124.946156)
		(end 361.633516 -124.447808)
		(width 0.1143)
		(layer "In4.Cu")
		(net "P3E_CPU0_PE3_OCP_TXN<14>")
	)
	(segment
		(start 361.726988 -123.97486)
		(end 361.628436 -123.476512)
		(width 0.1143)
		(layer "In4.Cu")
		(net "P3E_CPU0_PE3_OCP_TXN<14>")
	)
	(segment
		(start 432.15687 -124.778008)
		(end 430.621694 -125.170946)
		(width 0.1143)
		(layer "In4.Cu")
		(net "P3E_CPU0_PE3_OCP_TXN<14>")
	)
	(segment
		(start 376.141996 -128.212596)
		(end 375.39803 -128.377442)
		(width 0.1143)
		(layer "In4.Cu")
		(net "P3E_CPU0_PE3_OCP_TXN<14>")
	)
	(segment
		(start 441.774072 -120.686068)
		(end 441.644532 -120.880124)
		(width 0.1143)
		(layer "In4.Cu")
		(net "P3E_CPU0_PE3_OCP_TXN<14>")
	)
	(segment
		(start 357.418132 -106.691938)
		(end 357.418132 -107.08005)
		(width 0.1143)
		(layer "In4.Cu")
		(net "P3E_CPU0_PE3_OCP_TXN<14>")
	)
	(segment
		(start 377.169172 -128.431544)
		(end 376.141996 -128.212596)
		(width 0.1143)
		(layer "In4.Cu")
		(net "P3E_CPU0_PE3_OCP_TXN<14>")
	)
	(segment
		(start 410.043376 -128.31064)
		(end 409.487878 -128.200658)
		(width 0.1143)
		(layer "In4.Cu")
		(net "P3E_CPU0_PE3_OCP_TXN<14>")
	)
	(segment
		(start 381.521462 -127.735584)
		(end 380.769114 -127.524764)
		(width 0.1143)
		(layer "In4.Cu")
		(net "P3E_CPU0_PE3_OCP_TXN<14>")
	)
	(segment
		(start 415.090864 -127.490728)
		(end 414.58769 -127.590296)
		(width 0.1143)
		(layer "In4.Cu")
		(net "P3E_CPU0_PE3_OCP_TXN<14>")
	)
	(segment
		(start 410.542994 -128.211834)
		(end 410.043376 -128.31064)
		(width 0.1143)
		(layer "In4.Cu")
		(net "P3E_CPU0_PE3_OCP_TXN<14>")
	)
	(segment
		(start 408.72029 -128.352296)
		(end 397.701008 -132.916422)
		(width 0.1143)
		(layer "In4.Cu")
		(net "P3E_CPU0_PE3_OCP_TXN<14>")
	)
	(segment
		(start 447.957448 -119.4562)
		(end 441.774072 -120.686068)
		(width 0.1143)
		(layer "In4.Cu")
		(net "P3E_CPU0_PE3_OCP_TXN<14>")
	)
	(segment
		(start 388.436358 -132.474716)
		(end 387.196584 -131.742942)
		(width 0.1143)
		(layer "In4.Cu")
		(net "P3E_CPU0_PE3_OCP_TXN<14>")
	)
	(segment
		(start 427.13275 -125.89002)
		(end 425.707556 -128.233678)
		(width 0.1143)
		(layer "In4.Cu")
		(net "P3E_CPU0_PE3_OCP_TXN<14>")
	)
	(segment
		(start 441.113926 -120.817132)
		(end 440.77763 -120.884188)
		(width 0.1143)
		(layer "In4.Cu")
		(net "P3E_CPU0_PE3_OCP_TXN<14>")
	)
	(segment
		(start 413.968438 -127.46736)
		(end 412.688786 -127.986282)
		(width 0.1143)
		(layer "In4.Cu")
		(net "P3E_CPU0_PE3_OCP_TXN<14>")
	)
	(segment
		(start 359.580688 -105.0544)
		(end 358.581198 -105.0544)
		(width 0.1143)
		(layer "In4.Cu")
		(net "P3E_CPU0_PE3_OCP_TXN<14>")
	)
	(segment
		(start 441.308236 -120.946926)
		(end 441.113926 -120.817132)
		(width 0.1143)
		(layer "In4.Cu")
		(net "P3E_CPU0_PE3_OCP_TXN<14>")
	)
	(segment
		(start 387.196584 -131.742942)
		(end 385.941824 -129.52095)
		(width 0.1143)
		(layer "In4.Cu")
		(net "P3E_CPU0_PE3_OCP_TXN<14>")
	)
	(segment
		(start 361.633516 -124.447808)
		(end 361.726988 -123.97486)
		(width 0.1143)
		(layer "In4.Cu")
		(net "P3E_CPU0_PE3_OCP_TXN<14>")
	)
	(segment
		(start 358.0511 -106.577638)
		(end 357.532432 -106.577638)
		(width 0.1143)
		(layer "In4.Cu")
		(net "P3E_CPU0_PE3_OCP_TXN<14>")
	)
	(segment
		(start 409.487878 -128.200658)
		(end 408.72029 -128.352296)
		(width 0.1143)
		(layer "In4.Cu")
		(net "P3E_CPU0_PE3_OCP_TXN<14>")
	)
	(segment
		(start 459.4606 -124.02312)
		(end 459.4606 -123.806712)
		(width 0.1143)
		(layer "In4.Cu")
		(net "P3E_CPU0_PE3_OCP_TXN<14>")
	)
	(segment
		(start 385.941824 -129.52095)
		(end 384.282696 -128.530096)
		(width 0.1143)
		(layer "In4.Cu")
		(net "P3E_CPU0_PE3_OCP_TXN<14>")
	)
	(segment
		(start 361.638088 -121.434606)
		(end 361.732068 -120.959372)
		(width 0.1143)
		(layer "In4.Cu")
		(net "P3E_CPU0_PE3_OCP_TXN<14>")
	)
	(segment
		(start 453.7202 -121.636282)
		(end 453.066658 -120.05945)
		(width 0.1143)
		(layer "In4.Cu")
		(net "P3E_CPU0_PE3_OCP_TXN<14>")
	)
	(segment
		(start 358.336342 -105.299256)
		(end 358.336342 -106.292396)
		(width 0.1143)
		(layer "In4.Cu")
		(net "P3E_CPU0_PE3_OCP_TXN<14>")
	)
	(segment
		(start 441.644532 -120.880124)
		(end 441.308236 -120.946926)
		(width 0.1143)
		(layer "In4.Cu")
		(net "P3E_CPU0_PE3_OCP_TXN<14>")
	)
	(segment
		(start 397.701008 -132.916422)
		(end 396.022576 -132.491988)
		(width 0.1143)
		(layer "In4.Cu")
		(net "P3E_CPU0_PE3_OCP_TXN<14>")
	)
	(segment
		(start 440.117484 -121.015506)
		(end 439.781188 -121.082308)
		(width 0.1143)
		(layer "In4.Cu")
		(net "P3E_CPU0_PE3_OCP_TXN<14>")
	)
	(segment
		(start 459.4606 -123.806712)
		(end 458.838554 -123.18492)
		(width 0.1143)
		(layer "In4.Cu")
		(net "P3E_CPU0_PE3_OCP_TXN<14>")
	)
	(segment
		(start 439.315098 -121.343166)
		(end 439.121042 -121.213626)
		(width 0.1143)
		(layer "In4.Cu")
		(net "P3E_CPU0_PE3_OCP_TXN<14>")
	)
	(segment
		(start 361.73664 -121.933462)
		(end 361.638088 -121.434606)
		(width 0.1143)
		(layer "In4.Cu")
		(net "P3E_CPU0_PE3_OCP_TXN<14>")
	)
	(segment
		(start 416.051492 -127.691388)
		(end 415.090864 -127.490728)
		(width 0.1143)
		(layer "In4.Cu")
		(net "P3E_CPU0_PE3_OCP_TXN<14>")
	)
	(segment
		(start 357.532432 -106.577638)
		(end 357.418132 -106.691938)
		(width 0.1143)
		(layer "In4.Cu")
		(net "P3E_CPU0_PE3_OCP_TXN<14>")
	)
	(segment
		(start 361.633516 -122.454416)
		(end 361.73664 -121.933462)
		(width 0.1143)
		(layer "In4.Cu")
		(net "P3E_CPU0_PE3_OCP_TXN<14>")
	)
	(segment
		(start 361.583478 -119.164354)
		(end 361.583478 -113.718848)
		(width 0.1143)
		(layer "In4.Cu")
		(net "P3E_CPU0_PE3_OCP_TXN<14>")
	)
	(segment
		(start 356.58425 -106.59872)
		(end 356.299008 -106.883962)
		(width 0.1143)
		(layer "In11.Cu")
		(net "P3E_CPU0_PE3_OCP_TXN<14>")
	)
	(segment
		(start 353.556824 -107.938824)
		(end 343.037414 -105.856532)
		(width 0.1143)
		(layer "In11.Cu")
		(net "P3E_CPU0_PE3_OCP_TXN<14>")
	)
	(segment
		(start 339.54212 -101.29393)
		(end 338.290662 -100.747576)
		(width 0.1143)
		(layer "In11.Cu")
		(net "P3E_CPU0_PE3_OCP_TXN<14>")
	)
	(segment
		(start 322.993258 -97.212404)
		(end 320.992754 -94.66326)
		(width 0.1143)
		(layer "In11.Cu")
		(net "P3E_CPU0_PE3_OCP_TXN<14>")
	)
	(segment
		(start 315.816742 -92.519246)
		(end 309.560468 -91.2749)
		(width 0.1143)
		(layer "In11.Cu")
		(net "P3E_CPU0_PE3_OCP_TXN<14>")
	)
	(segment
		(start 333.580994 -101.13518)
		(end 331.535024 -100.784152)
		(width 0.1143)
		(layer "In11.Cu")
		(net "P3E_CPU0_PE3_OCP_TXN<14>")
	)
	(segment
		(start 305.100736 -91.654376)
		(end 304.388266 -91.565984)
		(width 0.0889)
		(layer "In11.Cu")
		(net "P3E_CPU0_PE3_OCP_TXN<14>")
	)
	(segment
		(start 356.299008 -106.883962)
		(end 356.299008 -107.465622)
		(width 0.1143)
		(layer "In11.Cu")
		(net "P3E_CPU0_PE3_OCP_TXN<14>")
	)
	(segment
		(start 338.290662 -100.747576)
		(end 337.250532 -100.881688)
		(width 0.1143)
		(layer "In11.Cu")
		(net "P3E_CPU0_PE3_OCP_TXN<14>")
	)
	(segment
		(start 305.268376 -91.661488)
		(end 305.235356 -91.661488)
		(width 0.0889)
		(layer "In11.Cu")
		(net "P3E_CPU0_PE3_OCP_TXN<14>")
	)
	(segment
		(start 308.40934 -91.2749)
		(end 308.4068 -91.2749)
		(width 0.0889)
		(layer "In11.Cu")
		(net "P3E_CPU0_PE3_OCP_TXN<14>")
	)
	(segment
		(start 355.559614 -107.938824)
		(end 353.556824 -107.938824)
		(width 0.1143)
		(layer "In11.Cu")
		(net "P3E_CPU0_PE3_OCP_TXN<14>")
	)
	(segment
		(start 320.992754 -94.66326)
		(end 315.816742 -92.519246)
		(width 0.1143)
		(layer "In11.Cu")
		(net "P3E_CPU0_PE3_OCP_TXN<14>")
	)
	(segment
		(start 308.4068 -91.2749)
		(end 308.356 -91.2241)
		(width 0.0889)
		(layer "In11.Cu")
		(net "P3E_CPU0_PE3_OCP_TXN<14>")
	)
	(segment
		(start 356.014274 -107.750356)
		(end 355.559614 -107.938824)
		(width 0.1143)
		(layer "In11.Cu")
		(net "P3E_CPU0_PE3_OCP_TXN<14>")
	)
	(segment
		(start 356.936802 -106.59872)
		(end 356.58425 -106.59872)
		(width 0.1143)
		(layer "In11.Cu")
		(net "P3E_CPU0_PE3_OCP_TXN<14>")
	)
	(segment
		(start 308.356 -91.2241)
		(end 307.68798 -91.2241)
		(width 0.0889)
		(layer "In11.Cu")
		(net "P3E_CPU0_PE3_OCP_TXN<14>")
	)
	(segment
		(start 357.418132 -107.08005)
		(end 356.936802 -106.59872)
		(width 0.1143)
		(layer "In11.Cu")
		(net "P3E_CPU0_PE3_OCP_TXN<14>")
	)
	(segment
		(start 305.758342 -91.366594)
		(end 305.758342 -91.366848)
		(width 0.0889)
		(layer "In11.Cu")
		(net "P3E_CPU0_PE3_OCP_TXN<14>")
	)
	(segment
		(start 306.331366 -91.157552)
		(end 306.120546 -91.157552)
		(width 0.0889)
		(layer "In11.Cu")
		(net "P3E_CPU0_PE3_OCP_TXN<14>")
	)
	(segment
		(start 323.032882 -97.262696)
		(end 322.993258 -97.212404)
		(width 0.1143)
		(layer "In11.Cu")
		(net "P3E_CPU0_PE3_OCP_TXN<14>")
	)
	(segment
		(start 307.68798 -91.2241)
		(end 306.331366 -91.157552)
		(width 0.0889)
		(layer "In11.Cu")
		(net "P3E_CPU0_PE3_OCP_TXN<14>")
	)
	(segment
		(start 331.535024 -100.784152)
		(end 323.032882 -97.262696)
		(width 0.1143)
		(layer "In11.Cu")
		(net "P3E_CPU0_PE3_OCP_TXN<14>")
	)
	(segment
		(start 336.049112 -100.719382)
		(end 333.580994 -101.13518)
		(width 0.1143)
		(layer "In11.Cu")
		(net "P3E_CPU0_PE3_OCP_TXN<14>")
	)
	(segment
		(start 341.159338 -104.507538)
		(end 340.119208 -101.994716)
		(width 0.1143)
		(layer "In11.Cu")
		(net "P3E_CPU0_PE3_OCP_TXN<14>")
	)
	(segment
		(start 356.299008 -107.465622)
		(end 356.014274 -107.750356)
		(width 0.1143)
		(layer "In11.Cu")
		(net "P3E_CPU0_PE3_OCP_TXN<14>")
	)
	(segment
		(start 337.250532 -100.881688)
		(end 336.049112 -100.719382)
		(width 0.1143)
		(layer "In11.Cu")
		(net "P3E_CPU0_PE3_OCP_TXN<14>")
	)
	(segment
		(start 343.037414 -105.856532)
		(end 341.159338 -104.507538)
		(width 0.1143)
		(layer "In11.Cu")
		(net "P3E_CPU0_PE3_OCP_TXN<14>")
	)
	(segment
		(start 340.119208 -101.994716)
		(end 339.54212 -101.29393)
		(width 0.1143)
		(layer "In11.Cu")
		(net "P3E_CPU0_PE3_OCP_TXN<14>")
	)
	(segment
		(start 309.560468 -91.2749)
		(end 308.40934 -91.2749)
		(width 0.1143)
		(layer "In11.Cu")
		(net "P3E_CPU0_PE3_OCP_TXN<14>")
	)
	(arc
		(start 305.235356 -91.661488)
		(mid 305.16794 -91.659942)
		(end 305.100736 -91.654376)
		(width 0.0889)
		(layer "In11.Cu")
		(net "P3E_CPU0_PE3_OCP_TXN<14>")
	)
	(arc
		(start 306.120546 -91.157552)
		(mid 305.911361 -91.213432)
		(end 305.758342 -91.366594)
		(width 0.0889)
		(layer "In11.Cu")
		(net "P3E_CPU0_PE3_OCP_TXN<14>")
	)
	(arc
		(start 305.758342 -91.366848)
		(mid 305.551366 -91.57738)
		(end 305.268376 -91.661488)
		(width 0.0889)
		(layer "In11.Cu")
		(net "P3E_CPU0_PE3_OCP_TXN<14>")
	)
	(segment
		(start 303.816766 -92.556584)
		(end 304.388266 -92.556584)
		(width 0.1143)
		(layer "F.Cu")
		(net "P3E_CPU0_PE3_OCP_TXN<13>")
	)
	(via
		(at 304.388266 -92.556584)
		(size 0.508)
		(drill 0.254)
		(layers "F.Cu" "B.Cu")
		(net "P3E_CPU0_PE3_OCP_TXN<13>")
	)
	(via
		(at 359.447084 -107.174284)
		(size 0.508)
		(drill 0.254)
		(layers "F.Cu" "B.Cu")
		(net "P3E_CPU0_PE3_OCP_TXN<13>")
	)
	(via
		(at 456.21575 -124.18822)
		(size 0.508)
		(drill 0.254)
		(layers "F.Cu" "B.Cu")
		(net "P3E_CPU0_PE3_OCP_TXN<13>")
	)
	(segment
		(start 457.033376 -118.94947)
		(end 456.530964 -120.511062)
		(width 0.1143)
		(layer "B.Cu")
		(net "P3E_CPU0_PE3_OCP_TXN<13>")
	)
	(segment
		(start 459.23835 -117.239796)
		(end 458.858112 -117.77472)
		(width 0.1143)
		(layer "B.Cu")
		(net "P3E_CPU0_PE3_OCP_TXN<13>")
	)
	(segment
		(start 458.851 -116.49202)
		(end 459.23835 -116.87937)
		(width 0.1143)
		(layer "B.Cu")
		(net "P3E_CPU0_PE3_OCP_TXN<13>")
	)
	(segment
		(start 458.858112 -117.77472)
		(end 457.033376 -118.94947)
		(width 0.1143)
		(layer "B.Cu")
		(net "P3E_CPU0_PE3_OCP_TXN<13>")
	)
	(segment
		(start 456.530964 -120.511062)
		(end 457.148692 -122.09145)
		(width 0.1143)
		(layer "B.Cu")
		(net "P3E_CPU0_PE3_OCP_TXN<13>")
	)
	(segment
		(start 456.7301 -124.07392)
		(end 456.6158 -124.18822)
		(width 0.1143)
		(layer "B.Cu")
		(net "P3E_CPU0_PE3_OCP_TXN<13>")
	)
	(segment
		(start 456.6158 -124.18822)
		(end 456.21575 -124.18822)
		(width 0.1143)
		(layer "B.Cu")
		(net "P3E_CPU0_PE3_OCP_TXN<13>")
	)
	(segment
		(start 459.23835 -116.87937)
		(end 459.23835 -117.239796)
		(width 0.1143)
		(layer "B.Cu")
		(net "P3E_CPU0_PE3_OCP_TXN<13>")
	)
	(segment
		(start 456.7301 -123.517152)
		(end 456.7301 -124.07392)
		(width 0.1143)
		(layer "B.Cu")
		(net "P3E_CPU0_PE3_OCP_TXN<13>")
	)
	(segment
		(start 457.148692 -122.09145)
		(end 456.7301 -123.517152)
		(width 0.1143)
		(layer "B.Cu")
		(net "P3E_CPU0_PE3_OCP_TXN<13>")
	)
	(segment
		(start 414.59912 -128.248156)
		(end 415.087054 -128.151636)
		(width 0.1143)
		(layer "In4.Cu")
		(net "P3E_CPU0_PE3_OCP_TXN<13>")
	)
	(segment
		(start 437.440324 -122.399552)
		(end 443.682628 -121.158)
		(width 0.1143)
		(layer "In4.Cu")
		(net "P3E_CPU0_PE3_OCP_TXN<13>")
	)
	(segment
		(start 385.550664 -131.736846)
		(end 385.846066 -131.91109)
		(width 0.1143)
		(layer "In4.Cu")
		(net "P3E_CPU0_PE3_OCP_TXN<13>")
	)
	(segment
		(start 392.756898 -133.139942)
		(end 394.360908 -133.504686)
		(width 0.1143)
		(layer "In4.Cu")
		(net "P3E_CPU0_PE3_OCP_TXN<13>")
	)
	(segment
		(start 424.534838 -129.180336)
		(end 426.120306 -128.80086)
		(width 0.1143)
		(layer "In4.Cu")
		(net "P3E_CPU0_PE3_OCP_TXN<13>")
	)
	(segment
		(start 381.612902 -129.88798)
		(end 382.983486 -130.745738)
		(width 0.1143)
		(layer "In4.Cu")
		(net "P3E_CPU0_PE3_OCP_TXN<13>")
	)
	(segment
		(start 446.923414 -121.600214)
		(end 448.067176 -122.07367)
		(width 0.1143)
		(layer "In4.Cu")
		(net "P3E_CPU0_PE3_OCP_TXN<13>")
	)
	(segment
		(start 382.983486 -130.745738)
		(end 385.197096 -131.336542)
		(width 0.1143)
		(layer "In4.Cu")
		(net "P3E_CPU0_PE3_OCP_TXN<13>")
	)
	(segment
		(start 359.835958 -106.674158)
		(end 359.947972 -106.786172)
		(width 0.1143)
		(layer "In4.Cu")
		(net "P3E_CPU0_PE3_OCP_TXN<13>")
	)
	(segment
		(start 453.069706 -122.64517)
		(end 453.527668 -122.835162)
		(width 0.1143)
		(layer "In4.Cu")
		(net "P3E_CPU0_PE3_OCP_TXN<13>")
	)
	(segment
		(start 362.188506 -127.846074)
		(end 363.600492 -128.40589)
		(width 0.1143)
		(layer "In4.Cu")
		(net "P3E_CPU0_PE3_OCP_TXN<13>")
	)
	(segment
		(start 359.447084 -107.174284)
		(end 359.446322 -106.789474)
		(width 0.1143)
		(layer "In4.Cu")
		(net "P3E_CPU0_PE3_OCP_TXN<13>")
	)
	(segment
		(start 456.6793 -123.794266)
		(end 456.6793 -124.09932)
		(width 0.1143)
		(layer "In4.Cu")
		(net "P3E_CPU0_PE3_OCP_TXN<13>")
	)
	(segment
		(start 360.973116 -120.461024)
		(end 361.071668 -120.959372)
		(width 0.1143)
		(layer "In4.Cu")
		(net "P3E_CPU0_PE3_OCP_TXN<13>")
	)
	(segment
		(start 360.948478 -119.339614)
		(end 361.071668 -119.962676)
		(width 0.1143)
		(layer "In4.Cu")
		(net "P3E_CPU0_PE3_OCP_TXN<13>")
	)
	(segment
		(start 360.973116 -123.451112)
		(end 361.071668 -123.94946)
		(width 0.1143)
		(layer "In4.Cu")
		(net "P3E_CPU0_PE3_OCP_TXN<13>")
	)
	(segment
		(start 361.071668 -123.94946)
		(end 360.973116 -124.447808)
		(width 0.1143)
		(layer "In4.Cu")
		(net "P3E_CPU0_PE3_OCP_TXN<13>")
	)
	(segment
		(start 361.071668 -122.952764)
		(end 360.973116 -123.451112)
		(width 0.1143)
		(layer "In4.Cu")
		(net "P3E_CPU0_PE3_OCP_TXN<13>")
	)
	(segment
		(start 361.140502 -126.290832)
		(end 362.188506 -127.846074)
		(width 0.1143)
		(layer "In4.Cu")
		(net "P3E_CPU0_PE3_OCP_TXN<13>")
	)
	(segment
		(start 412.887414 -128.604772)
		(end 414.039558 -128.137412)
		(width 0.1143)
		(layer "In4.Cu")
		(net "P3E_CPU0_PE3_OCP_TXN<13>")
	)
	(segment
		(start 386.720842 -132.427726)
		(end 386.946902 -132.369306)
		(width 0.1143)
		(layer "In4.Cu")
		(net "P3E_CPU0_PE3_OCP_TXN<13>")
	)
	(segment
		(start 360.33837 -110.945422)
		(end 360.33837 -113.372138)
		(width 0.1143)
		(layer "In4.Cu")
		(net "P3E_CPU0_PE3_OCP_TXN<13>")
	)
	(segment
		(start 429.600614 -125.610874)
		(end 430.63033 -125.836426)
		(width 0.1143)
		(layer "In4.Cu")
		(net "P3E_CPU0_PE3_OCP_TXN<13>")
	)
	(segment
		(start 361.071668 -119.962676)
		(end 360.973116 -120.461024)
		(width 0.1143)
		(layer "In4.Cu")
		(net "P3E_CPU0_PE3_OCP_TXN<13>")
	)
	(segment
		(start 360.33837 -113.372138)
		(end 360.948478 -113.982246)
		(width 0.1143)
		(layer "In4.Cu")
		(net "P3E_CPU0_PE3_OCP_TXN<13>")
	)
	(segment
		(start 360.973116 -121.45772)
		(end 361.071668 -121.956068)
		(width 0.1143)
		(layer "In4.Cu")
		(net "P3E_CPU0_PE3_OCP_TXN<13>")
	)
	(segment
		(start 426.120306 -128.80086)
		(end 427.602142 -126.363984)
		(width 0.1143)
		(layer "In4.Cu")
		(net "P3E_CPU0_PE3_OCP_TXN<13>")
	)
	(segment
		(start 427.602142 -126.363984)
		(end 428.175928 -125.986286)
		(width 0.1143)
		(layer "In4.Cu")
		(net "P3E_CPU0_PE3_OCP_TXN<13>")
	)
	(segment
		(start 368.673634 -129.60731)
		(end 369.009676 -129.675636)
		(width 0.1143)
		(layer "In4.Cu")
		(net "P3E_CPU0_PE3_OCP_TXN<13>")
	)
	(segment
		(start 456.5904 -124.18822)
		(end 456.21575 -124.18822)
		(width 0.1143)
		(layer "In4.Cu")
		(net "P3E_CPU0_PE3_OCP_TXN<13>")
	)
	(segment
		(start 456.536806 -123.651772)
		(end 456.6793 -123.794266)
		(width 0.1143)
		(layer "In4.Cu")
		(net "P3E_CPU0_PE3_OCP_TXN<13>")
	)
	(segment
		(start 410.542486 -128.87198)
		(end 411.041596 -128.970786)
		(width 0.1143)
		(layer "In4.Cu")
		(net "P3E_CPU0_PE3_OCP_TXN<13>")
	)
	(segment
		(start 388.142988 -133.075172)
		(end 390.569704 -133.580886)
		(width 0.1143)
		(layer "In4.Cu")
		(net "P3E_CPU0_PE3_OCP_TXN<13>")
	)
	(segment
		(start 386.367274 -132.027168)
		(end 386.425694 -132.253228)
		(width 0.1143)
		(layer "In4.Cu")
		(net "P3E_CPU0_PE3_OCP_TXN<13>")
	)
	(segment
		(start 385.846066 -131.91109)
		(end 386.072126 -131.852924)
		(width 0.1143)
		(layer "In4.Cu")
		(net "P3E_CPU0_PE3_OCP_TXN<13>")
	)
	(segment
		(start 409.495498 -128.85928)
		(end 410.05125 -128.969262)
		(width 0.1143)
		(layer "In4.Cu")
		(net "P3E_CPU0_PE3_OCP_TXN<13>")
	)
	(segment
		(start 372.616476 -130.338576)
		(end 374.451372 -130.648964)
		(width 0.1143)
		(layer "In4.Cu")
		(net "P3E_CPU0_PE3_OCP_TXN<13>")
	)
	(segment
		(start 421.621458 -128.310132)
		(end 424.534838 -129.180336)
		(width 0.1143)
		(layer "In4.Cu")
		(net "P3E_CPU0_PE3_OCP_TXN<13>")
	)
	(segment
		(start 452.278242 -122.48769)
		(end 453.069706 -122.64517)
		(width 0.1143)
		(layer "In4.Cu")
		(net "P3E_CPU0_PE3_OCP_TXN<13>")
	)
	(segment
		(start 369.009676 -129.675636)
		(end 369.20424 -129.546858)
		(width 0.1143)
		(layer "In4.Cu")
		(net "P3E_CPU0_PE3_OCP_TXN<13>")
	)
	(segment
		(start 360.973116 -122.454416)
		(end 361.071668 -122.952764)
		(width 0.1143)
		(layer "In4.Cu")
		(net "P3E_CPU0_PE3_OCP_TXN<13>")
	)
	(segment
		(start 416.092132 -128.361948)
		(end 418.749988 -127.644398)
		(width 0.1143)
		(layer "In4.Cu")
		(net "P3E_CPU0_PE3_OCP_TXN<13>")
	)
	(segment
		(start 367.677954 -129.404618)
		(end 368.013996 -129.472944)
		(width 0.1143)
		(layer "In4.Cu")
		(net "P3E_CPU0_PE3_OCP_TXN<13>")
	)
	(segment
		(start 385.197096 -131.336542)
		(end 385.492498 -131.510786)
		(width 0.1143)
		(layer "In4.Cu")
		(net "P3E_CPU0_PE3_OCP_TXN<13>")
	)
	(segment
		(start 376.202702 -130.134106)
		(end 378.022104 -130.514852)
		(width 0.1143)
		(layer "In4.Cu")
		(net "P3E_CPU0_PE3_OCP_TXN<13>")
	)
	(segment
		(start 396.009114 -133.15696)
		(end 397.558768 -133.548882)
		(width 0.1143)
		(layer "In4.Cu")
		(net "P3E_CPU0_PE3_OCP_TXN<13>")
	)
	(segment
		(start 359.947972 -106.786172)
		(end 359.947972 -110.555024)
		(width 0.1143)
		(layer "In4.Cu")
		(net "P3E_CPU0_PE3_OCP_TXN<13>")
	)
	(segment
		(start 369.540282 -129.615184)
		(end 370.438426 -129.414778)
		(width 0.1143)
		(layer "In4.Cu")
		(net "P3E_CPU0_PE3_OCP_TXN<13>")
	)
	(segment
		(start 454.14438 -123.45162)
		(end 456.054206 -123.45162)
		(width 0.1143)
		(layer "In4.Cu")
		(net "P3E_CPU0_PE3_OCP_TXN<13>")
	)
	(segment
		(start 453.527668 -122.835162)
		(end 454.14438 -123.45162)
		(width 0.1143)
		(layer "In4.Cu")
		(net "P3E_CPU0_PE3_OCP_TXN<13>")
	)
	(segment
		(start 448.067176 -122.07367)
		(end 452.278242 -122.48769)
		(width 0.1143)
		(layer "In4.Cu")
		(net "P3E_CPU0_PE3_OCP_TXN<13>")
	)
	(segment
		(start 367.549176 -129.2098)
		(end 367.677954 -129.404618)
		(width 0.1143)
		(layer "In4.Cu")
		(net "P3E_CPU0_PE3_OCP_TXN<13>")
	)
	(segment
		(start 394.360908 -133.504686)
		(end 396.009114 -133.15696)
		(width 0.1143)
		(layer "In4.Cu")
		(net "P3E_CPU0_PE3_OCP_TXN<13>")
	)
	(segment
		(start 363.600492 -128.40589)
		(end 367.549176 -129.2098)
		(width 0.1143)
		(layer "In4.Cu")
		(net "P3E_CPU0_PE3_OCP_TXN<13>")
	)
	(segment
		(start 428.175928 -125.986286)
		(end 429.600614 -125.610874)
		(width 0.1143)
		(layer "In4.Cu")
		(net "P3E_CPU0_PE3_OCP_TXN<13>")
	)
	(segment
		(start 432.412394 -125.38075)
		(end 437.440324 -122.399552)
		(width 0.1143)
		(layer "In4.Cu")
		(net "P3E_CPU0_PE3_OCP_TXN<13>")
	)
	(segment
		(start 378.022104 -130.514852)
		(end 380.647956 -129.88798)
		(width 0.1143)
		(layer "In4.Cu")
		(net "P3E_CPU0_PE3_OCP_TXN<13>")
	)
	(segment
		(start 385.492498 -131.510786)
		(end 385.550664 -131.736846)
		(width 0.1143)
		(layer "In4.Cu")
		(net "P3E_CPU0_PE3_OCP_TXN<13>")
	)
	(segment
		(start 415.087054 -128.151636)
		(end 416.092132 -128.361948)
		(width 0.1143)
		(layer "In4.Cu")
		(net "P3E_CPU0_PE3_OCP_TXN<13>")
	)
	(segment
		(start 361.071668 -124.946156)
		(end 360.973116 -125.444504)
		(width 0.1143)
		(layer "In4.Cu")
		(net "P3E_CPU0_PE3_OCP_TXN<13>")
	)
	(segment
		(start 374.451372 -130.648964)
		(end 376.202702 -130.134106)
		(width 0.1143)
		(layer "In4.Cu")
		(net "P3E_CPU0_PE3_OCP_TXN<13>")
	)
	(segment
		(start 418.749988 -127.644398)
		(end 421.621458 -128.310132)
		(width 0.1143)
		(layer "In4.Cu")
		(net "P3E_CPU0_PE3_OCP_TXN<13>")
	)
	(segment
		(start 361.071668 -121.956068)
		(end 360.973116 -122.454416)
		(width 0.1143)
		(layer "In4.Cu")
		(net "P3E_CPU0_PE3_OCP_TXN<13>")
	)
	(segment
		(start 360.948478 -113.982246)
		(end 360.948478 -119.339614)
		(width 0.1143)
		(layer "In4.Cu")
		(net "P3E_CPU0_PE3_OCP_TXN<13>")
	)
	(segment
		(start 456.054206 -123.45162)
		(end 456.536806 -123.651772)
		(width 0.1143)
		(layer "In4.Cu")
		(net "P3E_CPU0_PE3_OCP_TXN<13>")
	)
	(segment
		(start 414.039558 -128.137412)
		(end 414.59912 -128.248156)
		(width 0.1143)
		(layer "In4.Cu")
		(net "P3E_CPU0_PE3_OCP_TXN<13>")
	)
	(segment
		(start 360.973116 -124.447808)
		(end 361.071668 -124.946156)
		(width 0.1143)
		(layer "In4.Cu")
		(net "P3E_CPU0_PE3_OCP_TXN<13>")
	)
	(segment
		(start 411.041596 -128.970786)
		(end 412.887414 -128.604772)
		(width 0.1143)
		(layer "In4.Cu")
		(net "P3E_CPU0_PE3_OCP_TXN<13>")
	)
	(segment
		(start 410.05125 -128.969262)
		(end 410.542486 -128.87198)
		(width 0.1143)
		(layer "In4.Cu")
		(net "P3E_CPU0_PE3_OCP_TXN<13>")
	)
	(segment
		(start 360.973116 -125.444504)
		(end 361.140502 -126.290832)
		(width 0.1143)
		(layer "In4.Cu")
		(net "P3E_CPU0_PE3_OCP_TXN<13>")
	)
	(segment
		(start 361.071668 -120.959372)
		(end 360.973116 -121.45772)
		(width 0.1143)
		(layer "In4.Cu")
		(net "P3E_CPU0_PE3_OCP_TXN<13>")
	)
	(segment
		(start 359.947972 -110.555024)
		(end 360.33837 -110.945422)
		(width 0.1143)
		(layer "In4.Cu")
		(net "P3E_CPU0_PE3_OCP_TXN<13>")
	)
	(segment
		(start 430.63033 -125.836426)
		(end 432.412394 -125.38075)
		(width 0.1143)
		(layer "In4.Cu")
		(net "P3E_CPU0_PE3_OCP_TXN<13>")
	)
	(segment
		(start 386.425694 -132.253228)
		(end 386.720842 -132.427726)
		(width 0.1143)
		(layer "In4.Cu")
		(net "P3E_CPU0_PE3_OCP_TXN<13>")
	)
	(segment
		(start 368.208814 -129.344166)
		(end 368.544602 -129.412492)
		(width 0.1143)
		(layer "In4.Cu")
		(net "P3E_CPU0_PE3_OCP_TXN<13>")
	)
	(segment
		(start 446.4812 -121.158)
		(end 446.923414 -121.600214)
		(width 0.1143)
		(layer "In4.Cu")
		(net "P3E_CPU0_PE3_OCP_TXN<13>")
	)
	(segment
		(start 370.438426 -129.414778)
		(end 372.616476 -130.338576)
		(width 0.1143)
		(layer "In4.Cu")
		(net "P3E_CPU0_PE3_OCP_TXN<13>")
	)
	(segment
		(start 390.569704 -133.580886)
		(end 392.756898 -133.139942)
		(width 0.1143)
		(layer "In4.Cu")
		(net "P3E_CPU0_PE3_OCP_TXN<13>")
	)
	(segment
		(start 456.6793 -124.09932)
		(end 456.5904 -124.18822)
		(width 0.1143)
		(layer "In4.Cu")
		(net "P3E_CPU0_PE3_OCP_TXN<13>")
	)
	(segment
		(start 408.91587 -128.973834)
		(end 409.495498 -128.85928)
		(width 0.1143)
		(layer "In4.Cu")
		(net "P3E_CPU0_PE3_OCP_TXN<13>")
	)
	(segment
		(start 397.754094 -133.598158)
		(end 408.91587 -128.973834)
		(width 0.1143)
		(layer "In4.Cu")
		(net "P3E_CPU0_PE3_OCP_TXN<13>")
	)
	(segment
		(start 368.013996 -129.472944)
		(end 368.208814 -129.344166)
		(width 0.1143)
		(layer "In4.Cu")
		(net "P3E_CPU0_PE3_OCP_TXN<13>")
	)
	(segment
		(start 380.647956 -129.88798)
		(end 381.612902 -129.88798)
		(width 0.1143)
		(layer "In4.Cu")
		(net "P3E_CPU0_PE3_OCP_TXN<13>")
	)
	(segment
		(start 359.561638 -106.674158)
		(end 359.835958 -106.674158)
		(width 0.1143)
		(layer "In4.Cu")
		(net "P3E_CPU0_PE3_OCP_TXN<13>")
	)
	(segment
		(start 443.682628 -121.158)
		(end 446.4812 -121.158)
		(width 0.1143)
		(layer "In4.Cu")
		(net "P3E_CPU0_PE3_OCP_TXN<13>")
	)
	(segment
		(start 368.544602 -129.412492)
		(end 368.673634 -129.60731)
		(width 0.1143)
		(layer "In4.Cu")
		(net "P3E_CPU0_PE3_OCP_TXN<13>")
	)
	(segment
		(start 386.072126 -131.852924)
		(end 386.367274 -132.027168)
		(width 0.1143)
		(layer "In4.Cu")
		(net "P3E_CPU0_PE3_OCP_TXN<13>")
	)
	(segment
		(start 397.558768 -133.548882)
		(end 397.754094 -133.598158)
		(width 0.1143)
		(layer "In4.Cu")
		(net "P3E_CPU0_PE3_OCP_TXN<13>")
	)
	(segment
		(start 386.946902 -132.369306)
		(end 388.142988 -133.075172)
		(width 0.1143)
		(layer "In4.Cu")
		(net "P3E_CPU0_PE3_OCP_TXN<13>")
	)
	(segment
		(start 359.446322 -106.789474)
		(end 359.561638 -106.674158)
		(width 0.1143)
		(layer "In4.Cu")
		(net "P3E_CPU0_PE3_OCP_TXN<13>")
	)
	(segment
		(start 369.20424 -129.546858)
		(end 369.540282 -129.615184)
		(width 0.1143)
		(layer "In4.Cu")
		(net "P3E_CPU0_PE3_OCP_TXN<13>")
	)
	(segment
		(start 359.447084 -106.863388)
		(end 359.272332 -106.688636)
		(width 0.1143)
		(layer "In11.Cu")
		(net "P3E_CPU0_PE3_OCP_TXN<13>")
	)
	(segment
		(start 304.924206 -92.3417)
		(end 304.73904 -92.156534)
		(width 0.0889)
		(layer "In11.Cu")
		(net "P3E_CPU0_PE3_OCP_TXN<13>")
	)
	(segment
		(start 358.36225 -107.645708)
		(end 357.492554 -108.515404)
		(width 0.1143)
		(layer "In11.Cu")
		(net "P3E_CPU0_PE3_OCP_TXN<13>")
	)
	(segment
		(start 334.937608 -104.209342)
		(end 323.666866 -99.5426)
		(width 0.1143)
		(layer "In11.Cu")
		(net "P3E_CPU0_PE3_OCP_TXN<13>")
	)
	(segment
		(start 359.447084 -107.174284)
		(end 359.447084 -106.863388)
		(width 0.1143)
		(layer "In11.Cu")
		(net "P3E_CPU0_PE3_OCP_TXN<13>")
	)
	(segment
		(start 340.728808 -105.081832)
		(end 339.901784 -104.48544)
		(width 0.1143)
		(layer "In11.Cu")
		(net "P3E_CPU0_PE3_OCP_TXN<13>")
	)
	(segment
		(start 317.716916 -94.328996)
		(end 314.966096 -93.19006)
		(width 0.1143)
		(layer "In11.Cu")
		(net "P3E_CPU0_PE3_OCP_TXN<13>")
	)
	(segment
		(start 309.170324 -92.0369)
		(end 306.9082 -92.0369)
		(width 0.1143)
		(layer "In11.Cu")
		(net "P3E_CPU0_PE3_OCP_TXN<13>")
	)
	(segment
		(start 343.830402 -107.82554)
		(end 341.95766 -107.167934)
		(width 0.1143)
		(layer "In11.Cu")
		(net "P3E_CPU0_PE3_OCP_TXN<13>")
	)
	(segment
		(start 339.901784 -104.48544)
		(end 337.841336 -104.139238)
		(width 0.1143)
		(layer "In11.Cu")
		(net "P3E_CPU0_PE3_OCP_TXN<13>")
	)
	(segment
		(start 306.565554 -91.9861)
		(end 306.209954 -92.3417)
		(width 0.0889)
		(layer "In11.Cu")
		(net "P3E_CPU0_PE3_OCP_TXN<13>")
	)
	(segment
		(start 306.9082 -92.0369)
		(end 306.8574 -91.9861)
		(width 0.0889)
		(layer "In11.Cu")
		(net "P3E_CPU0_PE3_OCP_TXN<13>")
	)
	(segment
		(start 355.836474 -108.515404)
		(end 355.560884 -108.62945)
		(width 0.1143)
		(layer "In11.Cu")
		(net "P3E_CPU0_PE3_OCP_TXN<13>")
	)
	(segment
		(start 314.966096 -93.19006)
		(end 309.170324 -92.0369)
		(width 0.1143)
		(layer "In11.Cu")
		(net "P3E_CPU0_PE3_OCP_TXN<13>")
	)
	(segment
		(start 304.066702 -92.451428)
		(end 304.388266 -92.556584)
		(width 0.0889)
		(layer "In11.Cu")
		(net "P3E_CPU0_PE3_OCP_TXN<13>")
	)
	(segment
		(start 336.31251 -104.430576)
		(end 334.937608 -104.209342)
		(width 0.1143)
		(layer "In11.Cu")
		(net "P3E_CPU0_PE3_OCP_TXN<13>")
	)
	(segment
		(start 317.716916 -94.32925)
		(end 317.716916 -94.328996)
		(width 0.1143)
		(layer "In11.Cu")
		(net "P3E_CPU0_PE3_OCP_TXN<13>")
	)
	(segment
		(start 337.841336 -104.139238)
		(end 337.83905 -104.139746)
		(width 0.1143)
		(layer "In11.Cu")
		(net "P3E_CPU0_PE3_OCP_TXN<13>")
	)
	(segment
		(start 306.8574 -91.9861)
		(end 306.565554 -91.9861)
		(width 0.0889)
		(layer "In11.Cu")
		(net "P3E_CPU0_PE3_OCP_TXN<13>")
	)
	(segment
		(start 345.33459 -107.264962)
		(end 343.830402 -107.82554)
		(width 0.1143)
		(layer "In11.Cu")
		(net "P3E_CPU0_PE3_OCP_TXN<13>")
	)
	(segment
		(start 358.649778 -106.688636)
		(end 358.36225 -106.976164)
		(width 0.1143)
		(layer "In11.Cu")
		(net "P3E_CPU0_PE3_OCP_TXN<13>")
	)
	(segment
		(start 358.36225 -106.976164)
		(end 358.36225 -107.645708)
		(width 0.1143)
		(layer "In11.Cu")
		(net "P3E_CPU0_PE3_OCP_TXN<13>")
	)
	(segment
		(start 304.73904 -92.156534)
		(end 304.37709 -92.156534)
		(width 0.0889)
		(layer "In11.Cu")
		(net "P3E_CPU0_PE3_OCP_TXN<13>")
	)
	(segment
		(start 304.029872 -92.378784)
		(end 304.066702 -92.451428)
		(width 0.0889)
		(layer "In11.Cu")
		(net "P3E_CPU0_PE3_OCP_TXN<13>")
	)
	(segment
		(start 323.666866 -99.5426)
		(end 320.467228 -95.467678)
		(width 0.1143)
		(layer "In11.Cu")
		(net "P3E_CPU0_PE3_OCP_TXN<13>")
	)
	(segment
		(start 351.425002 -109.35716)
		(end 345.33459 -107.264962)
		(width 0.1143)
		(layer "In11.Cu")
		(net "P3E_CPU0_PE3_OCP_TXN<13>")
	)
	(segment
		(start 320.467228 -95.467678)
		(end 317.716916 -94.32925)
		(width 0.1143)
		(layer "In11.Cu")
		(net "P3E_CPU0_PE3_OCP_TXN<13>")
	)
	(segment
		(start 306.209954 -92.3417)
		(end 304.924206 -92.3417)
		(width 0.0889)
		(layer "In11.Cu")
		(net "P3E_CPU0_PE3_OCP_TXN<13>")
	)
	(segment
		(start 357.492554 -108.515404)
		(end 355.836474 -108.515404)
		(width 0.1143)
		(layer "In11.Cu")
		(net "P3E_CPU0_PE3_OCP_TXN<13>")
	)
	(segment
		(start 354.833174 -109.35716)
		(end 351.425002 -109.35716)
		(width 0.1143)
		(layer "In11.Cu")
		(net "P3E_CPU0_PE3_OCP_TXN<13>")
	)
	(segment
		(start 355.560884 -108.62945)
		(end 354.833174 -109.35716)
		(width 0.1143)
		(layer "In11.Cu")
		(net "P3E_CPU0_PE3_OCP_TXN<13>")
	)
	(segment
		(start 341.95766 -107.167934)
		(end 340.728808 -105.081832)
		(width 0.1143)
		(layer "In11.Cu")
		(net "P3E_CPU0_PE3_OCP_TXN<13>")
	)
	(segment
		(start 359.272332 -106.688636)
		(end 358.649778 -106.688636)
		(width 0.1143)
		(layer "In11.Cu")
		(net "P3E_CPU0_PE3_OCP_TXN<13>")
	)
	(segment
		(start 337.83905 -104.139746)
		(end 336.31251 -104.430576)
		(width 0.1143)
		(layer "In11.Cu")
		(net "P3E_CPU0_PE3_OCP_TXN<13>")
	)
	(arc
		(start 304.301906 -92.165932)
		(mid 304.175601 -92.217702)
		(end 304.074068 -92.308934)
		(width 0.0889)
		(layer "In11.Cu")
		(net "P3E_CPU0_PE3_OCP_TXN<13>")
	)
	(arc
		(start 304.074068 -92.308934)
		(mid 304.050183 -92.342727)
		(end 304.029872 -92.378784)
		(width 0.0889)
		(layer "In11.Cu")
		(net "P3E_CPU0_PE3_OCP_TXN<13>")
	)
	(arc
		(start 304.37709 -92.156534)
		(mid 304.339277 -92.15946)
		(end 304.301906 -92.165932)
		(width 0.0889)
		(layer "In11.Cu")
		(net "P3E_CPU0_PE3_OCP_TXN<13>")
	)
	(segment
		(start 303.529746 -95.033084)
		(end 302.958246 -95.033084)
		(width 0.1143)
		(layer "F.Cu")
		(net "P3E_CPU0_PE3_OCP_TXN<12>")
	)
	(via
		(at 355.955092 -110.43285)
		(size 0.508)
		(drill 0.254)
		(layers "F.Cu" "B.Cu")
		(net "P3E_CPU0_PE3_OCP_TXN<12>")
	)
	(via
		(at 303.529746 -95.033084)
		(size 0.508)
		(drill 0.254)
		(layers "F.Cu" "B.Cu")
		(net "P3E_CPU0_PE3_OCP_TXN<12>")
	)
	(via
		(at 453.26935 -124.18822)
		(size 0.508)
		(drill 0.254)
		(layers "F.Cu" "B.Cu")
		(net "P3E_CPU0_PE3_OCP_TXN<12>")
	)
	(segment
		(start 453.520556 -121.213372)
		(end 453.728582 -121.939812)
		(width 0.1143)
		(layer "B.Cu")
		(net "P3E_CPU0_PE3_OCP_TXN<12>")
	)
	(segment
		(start 456.06335 -116.87937)
		(end 456.06335 -117.239796)
		(width 0.1143)
		(layer "B.Cu")
		(net "P3E_CPU0_PE3_OCP_TXN<12>")
	)
	(segment
		(start 453.7837 -124.07392)
		(end 453.6694 -124.18822)
		(width 0.1143)
		(layer "B.Cu")
		(net "P3E_CPU0_PE3_OCP_TXN<12>")
	)
	(segment
		(start 453.728582 -121.939812)
		(end 453.51192 -122.839988)
		(width 0.1143)
		(layer "B.Cu")
		(net "P3E_CPU0_PE3_OCP_TXN<12>")
	)
	(segment
		(start 455.144632 -118.198392)
		(end 453.520556 -121.213372)
		(width 0.1143)
		(layer "B.Cu")
		(net "P3E_CPU0_PE3_OCP_TXN<12>")
	)
	(segment
		(start 455.829924 -117.687598)
		(end 455.144632 -118.198392)
		(width 0.1143)
		(layer "B.Cu")
		(net "P3E_CPU0_PE3_OCP_TXN<12>")
	)
	(segment
		(start 456.06335 -117.239796)
		(end 455.829924 -117.687598)
		(width 0.1143)
		(layer "B.Cu")
		(net "P3E_CPU0_PE3_OCP_TXN<12>")
	)
	(segment
		(start 455.676 -116.49202)
		(end 456.06335 -116.87937)
		(width 0.1143)
		(layer "B.Cu")
		(net "P3E_CPU0_PE3_OCP_TXN<12>")
	)
	(segment
		(start 453.6694 -124.18822)
		(end 453.26935 -124.18822)
		(width 0.1143)
		(layer "B.Cu")
		(net "P3E_CPU0_PE3_OCP_TXN<12>")
	)
	(segment
		(start 453.51192 -122.839988)
		(end 453.7837 -123.710446)
		(width 0.1143)
		(layer "B.Cu")
		(net "P3E_CPU0_PE3_OCP_TXN<12>")
	)
	(segment
		(start 453.7837 -123.710446)
		(end 453.7837 -124.07392)
		(width 0.1143)
		(layer "B.Cu")
		(net "P3E_CPU0_PE3_OCP_TXN<12>")
	)
	(segment
		(start 383.283968 -133.936486)
		(end 381.931164 -134.264146)
		(width 0.1143)
		(layer "In4.Cu")
		(net "P3E_CPU0_PE3_OCP_TXN<12>")
	)
	(segment
		(start 433.438046 -128.296416)
		(end 432.544474 -128.50368)
		(width 0.1143)
		(layer "In4.Cu")
		(net "P3E_CPU0_PE3_OCP_TXN<12>")
	)
	(segment
		(start 418.685726 -135.697722)
		(end 417.867084 -136.159748)
		(width 0.1143)
		(layer "In4.Cu")
		(net "P3E_CPU0_PE3_OCP_TXN<12>")
	)
	(segment
		(start 438.004712 -124.085858)
		(end 435.71795 -125.033532)
		(width 0.1143)
		(layer "In4.Cu")
		(net "P3E_CPU0_PE3_OCP_TXN<12>")
	)
	(segment
		(start 408.104594 -137.796016)
		(end 405.406606 -138.335258)
		(width 0.1143)
		(layer "In4.Cu")
		(net "P3E_CPU0_PE3_OCP_TXN<12>")
	)
	(segment
		(start 357.592376 -126.463044)
		(end 356.895146 -124.592334)
		(width 0.1143)
		(layer "In4.Cu")
		(net "P3E_CPU0_PE3_OCP_TXN<12>")
	)
	(segment
		(start 413.665416 -135.79856)
		(end 409.905962 -136.506712)
		(width 0.1143)
		(layer "In4.Cu")
		(net "P3E_CPU0_PE3_OCP_TXN<12>")
	)
	(segment
		(start 448.385692 -125.2982)
		(end 447.519298 -124.939044)
		(width 0.1143)
		(layer "In4.Cu")
		(net "P3E_CPU0_PE3_OCP_TXN<12>")
	)
	(segment
		(start 434.547264 -126.659386)
		(end 434.066696 -127.818388)
		(width 0.1143)
		(layer "In4.Cu")
		(net "P3E_CPU0_PE3_OCP_TXN<12>")
	)
	(segment
		(start 354.6475 -113.126012)
		(end 354.6475 -111.7981)
		(width 0.1143)
		(layer "In4.Cu")
		(net "P3E_CPU0_PE3_OCP_TXN<12>")
	)
	(segment
		(start 447.47815 -124.89815)
		(end 446.900808 -124.320808)
		(width 0.1143)
		(layer "In4.Cu")
		(net "P3E_CPU0_PE3_OCP_TXN<12>")
	)
	(segment
		(start 354.6475 -111.7981)
		(end 355.473 -110.9726)
		(width 0.1143)
		(layer "In4.Cu")
		(net "P3E_CPU0_PE3_OCP_TXN<12>")
	)
	(segment
		(start 378.620782 -133.968236)
		(end 377.175522 -134.238238)
		(width 0.1143)
		(layer "In4.Cu")
		(net "P3E_CPU0_PE3_OCP_TXN<12>")
	)
	(segment
		(start 375.083324 -133.180074)
		(end 374.42394 -133.052312)
		(width 0.1143)
		(layer "In4.Cu")
		(net "P3E_CPU0_PE3_OCP_TXN<12>")
	)
	(segment
		(start 356.743 -110.9726)
		(end 357.028242 -110.687358)
		(width 0.1143)
		(layer "In4.Cu")
		(net "P3E_CPU0_PE3_OCP_TXN<12>")
	)
	(segment
		(start 439.565034 -123.43892)
		(end 439.475626 -123.654566)
		(width 0.1143)
		(layer "In4.Cu")
		(net "P3E_CPU0_PE3_OCP_TXN<12>")
	)
	(segment
		(start 450.36359 -125.0061)
		(end 449.658994 -125.2982)
		(width 0.1143)
		(layer "In4.Cu")
		(net "P3E_CPU0_PE3_OCP_TXN<12>")
	)
	(segment
		(start 430.154842 -128.642872)
		(end 428.868078 -129.328164)
		(width 0.1143)
		(layer "In4.Cu")
		(net "P3E_CPU0_PE3_OCP_TXN<12>")
	)
	(segment
		(start 445.8589 -122.6439)
		(end 443.224158 -122.6439)
		(width 0.1143)
		(layer "In4.Cu")
		(net "P3E_CPU0_PE3_OCP_TXN<12>")
	)
	(segment
		(start 361.6579 -129.029714)
		(end 357.592376 -126.463044)
		(width 0.1143)
		(layer "In4.Cu")
		(net "P3E_CPU0_PE3_OCP_TXN<12>")
	)
	(segment
		(start 356.069392 -109.9439)
		(end 355.955092 -110.0582)
		(width 0.1143)
		(layer "In4.Cu")
		(net "P3E_CPU0_PE3_OCP_TXN<12>")
	)
	(segment
		(start 355.955092 -110.0582)
		(end 355.955092 -110.43285)
		(width 0.1143)
		(layer "In4.Cu")
		(net "P3E_CPU0_PE3_OCP_TXN<12>")
	)
	(segment
		(start 446.45199 -123.237244)
		(end 445.8589 -122.6439)
		(width 0.1143)
		(layer "In4.Cu")
		(net "P3E_CPU0_PE3_OCP_TXN<12>")
	)
	(segment
		(start 432.544474 -128.50368)
		(end 431.499518 -128.288542)
		(width 0.1143)
		(layer "In4.Cu")
		(net "P3E_CPU0_PE3_OCP_TXN<12>")
	)
	(segment
		(start 356.895146 -124.592334)
		(end 357.372666 -122.531378)
		(width 0.1143)
		(layer "In4.Cu")
		(net "P3E_CPU0_PE3_OCP_TXN<12>")
	)
	(segment
		(start 357.372666 -122.531378)
		(end 357.113586 -121.35104)
		(width 0.1143)
		(layer "In4.Cu")
		(net "P3E_CPU0_PE3_OCP_TXN<12>")
	)
	(segment
		(start 451.30212 -124.617226)
		(end 450.985382 -124.748544)
		(width 0.1143)
		(layer "In4.Cu")
		(net "P3E_CPU0_PE3_OCP_TXN<12>")
	)
	(segment
		(start 355.473 -110.9726)
		(end 356.743 -110.9726)
		(width 0.1143)
		(layer "In4.Cu")
		(net "P3E_CPU0_PE3_OCP_TXN<12>")
	)
	(segment
		(start 428.868078 -129.328164)
		(end 428.139098 -130.341878)
		(width 0.1143)
		(layer "In4.Cu")
		(net "P3E_CPU0_PE3_OCP_TXN<12>")
	)
	(segment
		(start 447.47815 -124.897896)
		(end 447.47815 -124.89815)
		(width 0.1143)
		(layer "In4.Cu")
		(net "P3E_CPU0_PE3_OCP_TXN<12>")
	)
	(segment
		(start 439.881772 -123.307602)
		(end 439.565034 -123.43892)
		(width 0.1143)
		(layer "In4.Cu")
		(net "P3E_CPU0_PE3_OCP_TXN<12>")
	)
	(segment
		(start 439.158888 -123.785884)
		(end 438.943242 -123.69673)
		(width 0.1143)
		(layer "In4.Cu")
		(net "P3E_CPU0_PE3_OCP_TXN<12>")
	)
	(segment
		(start 439.475626 -123.654566)
		(end 439.158888 -123.785884)
		(width 0.1143)
		(layer "In4.Cu")
		(net "P3E_CPU0_PE3_OCP_TXN<12>")
	)
	(segment
		(start 370.066062 -132.360162)
		(end 361.6579 -129.029714)
		(width 0.1143)
		(layer "In4.Cu")
		(net "P3E_CPU0_PE3_OCP_TXN<12>")
	)
	(segment
		(start 446.900808 -124.320808)
		(end 446.45199 -123.237244)
		(width 0.1143)
		(layer "In4.Cu")
		(net "P3E_CPU0_PE3_OCP_TXN<12>")
	)
	(segment
		(start 425.645326 -130.362706)
		(end 422.599866 -131.253738)
		(width 0.1143)
		(layer "In4.Cu")
		(net "P3E_CPU0_PE3_OCP_TXN<12>")
	)
	(segment
		(start 438.220358 -124.175012)
		(end 438.004712 -124.085858)
		(width 0.1143)
		(layer "In4.Cu")
		(net "P3E_CPU0_PE3_OCP_TXN<12>")
	)
	(segment
		(start 453.7583 -123.963684)
		(end 453.420734 -123.626626)
		(width 0.1143)
		(layer "In4.Cu")
		(net "P3E_CPU0_PE3_OCP_TXN<12>")
	)
	(segment
		(start 450.895974 -124.96419)
		(end 450.579236 -125.095508)
		(width 0.1143)
		(layer "In4.Cu")
		(net "P3E_CPU0_PE3_OCP_TXN<12>")
	)
	(segment
		(start 405.406606 -138.335258)
		(end 383.283968 -133.936486)
		(width 0.1143)
		(layer "In4.Cu")
		(net "P3E_CPU0_PE3_OCP_TXN<12>")
	)
	(segment
		(start 422.599866 -131.253738)
		(end 420.490396 -132.866384)
		(width 0.1143)
		(layer "In4.Cu")
		(net "P3E_CPU0_PE3_OCP_TXN<12>")
	)
	(segment
		(start 371.02796 -132.573014)
		(end 370.066062 -132.360162)
		(width 0.1143)
		(layer "In4.Cu")
		(net "P3E_CPU0_PE3_OCP_TXN<12>")
	)
	(segment
		(start 380.938786 -133.982714)
		(end 379.843792 -134.321296)
		(width 0.1143)
		(layer "In4.Cu")
		(net "P3E_CPU0_PE3_OCP_TXN<12>")
	)
	(segment
		(start 415.958274 -136.558274)
		(end 413.66567 -135.79856)
		(width 0.1143)
		(layer "In4.Cu")
		(net "P3E_CPU0_PE3_OCP_TXN<12>")
	)
	(segment
		(start 435.71795 -125.033532)
		(end 434.547264 -126.659386)
		(width 0.1143)
		(layer "In4.Cu")
		(net "P3E_CPU0_PE3_OCP_TXN<12>")
	)
	(segment
		(start 438.943242 -123.69673)
		(end 438.626504 -123.828048)
		(width 0.1143)
		(layer "In4.Cu")
		(net "P3E_CPU0_PE3_OCP_TXN<12>")
	)
	(segment
		(start 359.0544 -114.427)
		(end 355.948488 -114.427)
		(width 0.1143)
		(layer "In4.Cu")
		(net "P3E_CPU0_PE3_OCP_TXN<12>")
	)
	(segment
		(start 357.028242 -110.687358)
		(end 357.028242 -110.172754)
		(width 0.1143)
		(layer "In4.Cu")
		(net "P3E_CPU0_PE3_OCP_TXN<12>")
	)
	(segment
		(start 356.799388 -109.9439)
		(end 356.069392 -109.9439)
		(width 0.1143)
		(layer "In4.Cu")
		(net "P3E_CPU0_PE3_OCP_TXN<12>")
	)
	(segment
		(start 431.499518 -128.288542)
		(end 430.154842 -128.642872)
		(width 0.1143)
		(layer "In4.Cu")
		(net "P3E_CPU0_PE3_OCP_TXN<12>")
	)
	(segment
		(start 428.139098 -130.341878)
		(end 427.282356 -130.707384)
		(width 0.1143)
		(layer "In4.Cu")
		(net "P3E_CPU0_PE3_OCP_TXN<12>")
	)
	(segment
		(start 355.948488 -114.427)
		(end 354.6475 -113.126012)
		(width 0.1143)
		(layer "In4.Cu")
		(net "P3E_CPU0_PE3_OCP_TXN<12>")
	)
	(segment
		(start 438.537096 -124.043694)
		(end 438.220358 -124.175012)
		(width 0.1143)
		(layer "In4.Cu")
		(net "P3E_CPU0_PE3_OCP_TXN<12>")
	)
	(segment
		(start 453.7583 -124.07392)
		(end 453.7583 -123.963684)
		(width 0.1143)
		(layer "In4.Cu")
		(net "P3E_CPU0_PE3_OCP_TXN<12>")
	)
	(segment
		(start 452.749158 -123.626626)
		(end 451.970394 -123.94946)
		(width 0.1143)
		(layer "In4.Cu")
		(net "P3E_CPU0_PE3_OCP_TXN<12>")
	)
	(segment
		(start 359.631742 -115.004342)
		(end 359.0544 -114.427)
		(width 0.1143)
		(layer "In4.Cu")
		(net "P3E_CPU0_PE3_OCP_TXN<12>")
	)
	(segment
		(start 427.282356 -130.707384)
		(end 425.645326 -130.362706)
		(width 0.1143)
		(layer "In4.Cu")
		(net "P3E_CPU0_PE3_OCP_TXN<12>")
	)
	(segment
		(start 413.66567 -135.79856)
		(end 413.665416 -135.79856)
		(width 0.1143)
		(layer "In4.Cu")
		(net "P3E_CPU0_PE3_OCP_TXN<12>")
	)
	(segment
		(start 417.867084 -136.159748)
		(end 415.958274 -136.558274)
		(width 0.1143)
		(layer "In4.Cu")
		(net "P3E_CPU0_PE3_OCP_TXN<12>")
	)
	(segment
		(start 453.26935 -124.18822)
		(end 453.644 -124.18822)
		(width 0.1143)
		(layer "In4.Cu")
		(net "P3E_CPU0_PE3_OCP_TXN<12>")
	)
	(segment
		(start 359.631742 -116.493544)
		(end 359.631742 -115.004342)
		(width 0.1143)
		(layer "In4.Cu")
		(net "P3E_CPU0_PE3_OCP_TXN<12>")
	)
	(segment
		(start 453.644 -124.18822)
		(end 453.7583 -124.07392)
		(width 0.1143)
		(layer "In4.Cu")
		(net "P3E_CPU0_PE3_OCP_TXN<12>")
	)
	(segment
		(start 443.224158 -122.6439)
		(end 439.881772 -123.307602)
		(width 0.1143)
		(layer "In4.Cu")
		(net "P3E_CPU0_PE3_OCP_TXN<12>")
	)
	(segment
		(start 374.42394 -133.052312)
		(end 372.24208 -132.30225)
		(width 0.1143)
		(layer "In4.Cu")
		(net "P3E_CPU0_PE3_OCP_TXN<12>")
	)
	(segment
		(start 447.519298 -124.939044)
		(end 447.47815 -124.897896)
		(width 0.1143)
		(layer "In4.Cu")
		(net "P3E_CPU0_PE3_OCP_TXN<12>")
	)
	(segment
		(start 438.626504 -123.828048)
		(end 438.537096 -124.043694)
		(width 0.1143)
		(layer "In4.Cu")
		(net "P3E_CPU0_PE3_OCP_TXN<12>")
	)
	(segment
		(start 409.905962 -136.506712)
		(end 408.104594 -137.796016)
		(width 0.1143)
		(layer "In4.Cu")
		(net "P3E_CPU0_PE3_OCP_TXN<12>")
	)
	(segment
		(start 357.028242 -110.172754)
		(end 356.799388 -109.9439)
		(width 0.1143)
		(layer "In4.Cu")
		(net "P3E_CPU0_PE3_OCP_TXN<12>")
	)
	(segment
		(start 450.985382 -124.748544)
		(end 450.895974 -124.96419)
		(width 0.1143)
		(layer "In4.Cu")
		(net "P3E_CPU0_PE3_OCP_TXN<12>")
	)
	(segment
		(start 372.24208 -132.30225)
		(end 371.02796 -132.573014)
		(width 0.1143)
		(layer "In4.Cu")
		(net "P3E_CPU0_PE3_OCP_TXN<12>")
	)
	(segment
		(start 420.490396 -132.866384)
		(end 418.685726 -135.697722)
		(width 0.1143)
		(layer "In4.Cu")
		(net "P3E_CPU0_PE3_OCP_TXN<12>")
	)
	(segment
		(start 434.066696 -127.818388)
		(end 433.438046 -128.296416)
		(width 0.1143)
		(layer "In4.Cu")
		(net "P3E_CPU0_PE3_OCP_TXN<12>")
	)
	(segment
		(start 449.658994 -125.2982)
		(end 448.385692 -125.2982)
		(width 0.1143)
		(layer "In4.Cu")
		(net "P3E_CPU0_PE3_OCP_TXN<12>")
	)
	(segment
		(start 450.579236 -125.095508)
		(end 450.36359 -125.0061)
		(width 0.1143)
		(layer "In4.Cu")
		(net "P3E_CPU0_PE3_OCP_TXN<12>")
	)
	(segment
		(start 376.012456 -133.914388)
		(end 375.083324 -133.180074)
		(width 0.1143)
		(layer "In4.Cu")
		(net "P3E_CPU0_PE3_OCP_TXN<12>")
	)
	(segment
		(start 453.420734 -123.626626)
		(end 452.749158 -123.626626)
		(width 0.1143)
		(layer "In4.Cu")
		(net "P3E_CPU0_PE3_OCP_TXN<12>")
	)
	(segment
		(start 377.175522 -134.238238)
		(end 376.012456 -133.914388)
		(width 0.1143)
		(layer "In4.Cu")
		(net "P3E_CPU0_PE3_OCP_TXN<12>")
	)
	(segment
		(start 451.970394 -123.94946)
		(end 451.30212 -124.617226)
		(width 0.1143)
		(layer "In4.Cu")
		(net "P3E_CPU0_PE3_OCP_TXN<12>")
	)
	(segment
		(start 381.931164 -134.264146)
		(end 380.938786 -133.982714)
		(width 0.1143)
		(layer "In4.Cu")
		(net "P3E_CPU0_PE3_OCP_TXN<12>")
	)
	(segment
		(start 357.113586 -121.35104)
		(end 359.631742 -116.493544)
		(width 0.1143)
		(layer "In4.Cu")
		(net "P3E_CPU0_PE3_OCP_TXN<12>")
	)
	(segment
		(start 379.843792 -134.321296)
		(end 378.620782 -133.968236)
		(width 0.1143)
		(layer "In4.Cu")
		(net "P3E_CPU0_PE3_OCP_TXN<12>")
	)
	(segment
		(start 309.932832 -92.98559)
		(end 307.125878 -92.98559)
		(width 0.1143)
		(layer "In11.Cu")
		(net "P3E_CPU0_PE3_OCP_TXN<12>")
	)
	(segment
		(start 339.663024 -105.127806)
		(end 337.848448 -104.823006)
		(width 0.1143)
		(layer "In11.Cu")
		(net "P3E_CPU0_PE3_OCP_TXN<12>")
	)
	(segment
		(start 342.575134 -108.702348)
		(end 341.657686 -107.984798)
		(width 0.1143)
		(layer "In11.Cu")
		(net "P3E_CPU0_PE3_OCP_TXN<12>")
	)
	(segment
		(start 305.370992 -93.36405)
		(end 304.745644 -93.989398)
		(width 0.0889)
		(layer "In11.Cu")
		(net "P3E_CPU0_PE3_OCP_TXN<12>")
	)
	(segment
		(start 355.485446 -109.9439)
		(end 354.797106 -110.63224)
		(width 0.1143)
		(layer "In11.Cu")
		(net "P3E_CPU0_PE3_OCP_TXN<12>")
	)
	(segment
		(start 303.529746 -94.69501)
		(end 303.529746 -95.033084)
		(width 0.0889)
		(layer "In11.Cu")
		(net "P3E_CPU0_PE3_OCP_TXN<12>")
	)
	(segment
		(start 307.10378 -92.98559)
		(end 307.05298 -92.93479)
		(width 0.0889)
		(layer "In11.Cu")
		(net "P3E_CPU0_PE3_OCP_TXN<12>")
	)
	(segment
		(start 337.848448 -104.823006)
		(end 336.321908 -105.113836)
		(width 0.1143)
		(layer "In11.Cu")
		(net "P3E_CPU0_PE3_OCP_TXN<12>")
	)
	(segment
		(start 336.321908 -105.113836)
		(end 334.688688 -104.850946)
		(width 0.1143)
		(layer "In11.Cu")
		(net "P3E_CPU0_PE3_OCP_TXN<12>")
	)
	(segment
		(start 319.585594 -95.882206)
		(end 319.585594 -95.88246)
		(width 0.1143)
		(layer "In11.Cu")
		(net "P3E_CPU0_PE3_OCP_TXN<12>")
	)
	(segment
		(start 341.657686 -107.984798)
		(end 340.204552 -105.518458)
		(width 0.1143)
		(layer "In11.Cu")
		(net "P3E_CPU0_PE3_OCP_TXN<12>")
	)
	(segment
		(start 355.840792 -109.9439)
		(end 355.485446 -109.9439)
		(width 0.1143)
		(layer "In11.Cu")
		(net "P3E_CPU0_PE3_OCP_TXN<12>")
	)
	(segment
		(start 307.125878 -92.98559)
		(end 307.10378 -92.98559)
		(width 0.0889)
		(layer "In11.Cu")
		(net "P3E_CPU0_PE3_OCP_TXN<12>")
	)
	(segment
		(start 319.585594 -95.88246)
		(end 315.05652 -94.004384)
		(width 0.1143)
		(layer "In11.Cu")
		(net "P3E_CPU0_PE3_OCP_TXN<12>")
	)
	(segment
		(start 354.797106 -110.63224)
		(end 351.414842 -110.63224)
		(width 0.1143)
		(layer "In11.Cu")
		(net "P3E_CPU0_PE3_OCP_TXN<12>")
	)
	(segment
		(start 355.955092 -110.0582)
		(end 355.840792 -109.9439)
		(width 0.1143)
		(layer "In11.Cu")
		(net "P3E_CPU0_PE3_OCP_TXN<12>")
	)
	(segment
		(start 346.912438 -109.351064)
		(end 344.142314 -109.351064)
		(width 0.1143)
		(layer "In11.Cu")
		(net "P3E_CPU0_PE3_OCP_TXN<12>")
	)
	(segment
		(start 334.688688 -104.850946)
		(end 322.744846 -99.905058)
		(width 0.1143)
		(layer "In11.Cu")
		(net "P3E_CPU0_PE3_OCP_TXN<12>")
	)
	(segment
		(start 306.407058 -92.93479)
		(end 305.370992 -93.36405)
		(width 0.0889)
		(layer "In11.Cu")
		(net "P3E_CPU0_PE3_OCP_TXN<12>")
	)
	(segment
		(start 307.05298 -92.93479)
		(end 306.407058 -92.93479)
		(width 0.0889)
		(layer "In11.Cu")
		(net "P3E_CPU0_PE3_OCP_TXN<12>")
	)
	(segment
		(start 344.142314 -109.351064)
		(end 342.575134 -108.702348)
		(width 0.1143)
		(layer "In11.Cu")
		(net "P3E_CPU0_PE3_OCP_TXN<12>")
	)
	(segment
		(start 322.744846 -99.905058)
		(end 319.585594 -95.882206)
		(width 0.1143)
		(layer "In11.Cu")
		(net "P3E_CPU0_PE3_OCP_TXN<12>")
	)
	(segment
		(start 351.414842 -110.63224)
		(end 346.912438 -109.351064)
		(width 0.1143)
		(layer "In11.Cu")
		(net "P3E_CPU0_PE3_OCP_TXN<12>")
	)
	(segment
		(start 304.389028 -94.13748)
		(end 304.388012 -94.13748)
		(width 0.0889)
		(layer "In11.Cu")
		(net "P3E_CPU0_PE3_OCP_TXN<12>")
	)
	(segment
		(start 303.595024 -94.629732)
		(end 303.529746 -94.69501)
		(width 0.0889)
		(layer "In11.Cu")
		(net "P3E_CPU0_PE3_OCP_TXN<12>")
	)
	(segment
		(start 315.05652 -94.004384)
		(end 309.932832 -92.98559)
		(width 0.1143)
		(layer "In11.Cu")
		(net "P3E_CPU0_PE3_OCP_TXN<12>")
	)
	(segment
		(start 355.955092 -110.43285)
		(end 355.955092 -110.0582)
		(width 0.1143)
		(layer "In11.Cu")
		(net "P3E_CPU0_PE3_OCP_TXN<12>")
	)
	(segment
		(start 340.204552 -105.518458)
		(end 339.663024 -105.127806)
		(width 0.1143)
		(layer "In11.Cu")
		(net "P3E_CPU0_PE3_OCP_TXN<12>")
	)
	(arc
		(start 304.388012 -94.13748)
		(mid 304.187971 -94.191125)
		(end 304.041556 -94.337632)
		(width 0.0889)
		(layer "In11.Cu")
		(net "P3E_CPU0_PE3_OCP_TXN<12>")
	)
	(arc
		(start 304.745644 -93.989398)
		(mid 304.582057 -94.098889)
		(end 304.389028 -94.13748)
		(width 0.0889)
		(layer "In11.Cu")
		(net "P3E_CPU0_PE3_OCP_TXN<12>")
	)
	(arc
		(start 304.041556 -94.337632)
		(mid 303.853133 -94.536936)
		(end 303.595024 -94.629732)
		(width 0.0889)
		(layer "In11.Cu")
		(net "P3E_CPU0_PE3_OCP_TXN<12>")
	)
	(segment
		(start 304.675286 -95.033084)
		(end 305.246786 -95.033084)
		(width 0.1143)
		(layer "F.Cu")
		(net "P3E_CPU0_PE3_OCP_TXN<11>")
	)
	(via
		(at 357.9622 -110.43285)
		(size 0.508)
		(drill 0.254)
		(layers "F.Cu" "B.Cu")
		(net "P3E_CPU0_PE3_OCP_TXN<11>")
	)
	(via
		(at 305.246786 -95.033084)
		(size 0.508)
		(drill 0.254)
		(layers "F.Cu" "B.Cu")
		(net "P3E_CPU0_PE3_OCP_TXN<11>")
	)
	(via
		(at 448.39255 -123.78817)
		(size 0.508)
		(drill 0.254)
		(layers "F.Cu" "B.Cu")
		(net "P3E_CPU0_PE3_OCP_TXN<11>")
	)
	(segment
		(start 448.9069 -123.67387)
		(end 448.7926 -123.78817)
		(width 0.1143)
		(layer "B.Cu")
		(net "P3E_CPU0_PE3_OCP_TXN<11>")
	)
	(segment
		(start 449.78701 -121.237502)
		(end 448.9069 -123.239784)
		(width 0.1143)
		(layer "B.Cu")
		(net "P3E_CPU0_PE3_OCP_TXN<11>")
	)
	(segment
		(start 452.88835 -116.87937)
		(end 452.88835 -117.239796)
		(width 0.1143)
		(layer "B.Cu")
		(net "P3E_CPU0_PE3_OCP_TXN<11>")
	)
	(segment
		(start 448.7926 -123.78817)
		(end 448.39255 -123.78817)
		(width 0.1143)
		(layer "B.Cu")
		(net "P3E_CPU0_PE3_OCP_TXN<11>")
	)
	(segment
		(start 449.958714 -119.372634)
		(end 449.490592 -120.129046)
		(width 0.1143)
		(layer "B.Cu")
		(net "P3E_CPU0_PE3_OCP_TXN<11>")
	)
	(segment
		(start 452.674228 -117.56517)
		(end 449.958714 -119.372634)
		(width 0.1143)
		(layer "B.Cu")
		(net "P3E_CPU0_PE3_OCP_TXN<11>")
	)
	(segment
		(start 449.490592 -120.129046)
		(end 449.78701 -121.237502)
		(width 0.1143)
		(layer "B.Cu")
		(net "P3E_CPU0_PE3_OCP_TXN<11>")
	)
	(segment
		(start 452.501 -116.49202)
		(end 452.88835 -116.87937)
		(width 0.1143)
		(layer "B.Cu")
		(net "P3E_CPU0_PE3_OCP_TXN<11>")
	)
	(segment
		(start 452.88835 -117.239796)
		(end 452.674228 -117.56517)
		(width 0.1143)
		(layer "B.Cu")
		(net "P3E_CPU0_PE3_OCP_TXN<11>")
	)
	(segment
		(start 448.9069 -123.239784)
		(end 448.9069 -123.67387)
		(width 0.1143)
		(layer "B.Cu")
		(net "P3E_CPU0_PE3_OCP_TXN<11>")
	)
	(segment
		(start 407.78811 -130.236468)
		(end 397.941546 -134.313676)
		(width 0.1143)
		(layer "In4.Cu")
		(net "P3E_CPU0_PE3_OCP_TXN<11>")
	)
	(segment
		(start 376.3391 -131.94157)
		(end 374.458484 -132.378958)
		(width 0.1143)
		(layer "In4.Cu")
		(net "P3E_CPU0_PE3_OCP_TXN<11>")
	)
	(segment
		(start 423.083736 -129.473452)
		(end 423.083736 -129.473198)
		(width 0.1143)
		(layer "In4.Cu")
		(net "P3E_CPU0_PE3_OCP_TXN<11>")
	)
	(segment
		(start 434.151024 -125.317758)
		(end 433.92471 -125.259846)
		(width 0.1143)
		(layer "In4.Cu")
		(net "P3E_CPU0_PE3_OCP_TXN<11>")
	)
	(segment
		(start 408.897836 -130.458464)
		(end 408.897582 -130.458464)
		(width 0.1143)
		(layer "In4.Cu")
		(net "P3E_CPU0_PE3_OCP_TXN<11>")
	)
	(segment
		(start 412.999174 -131.246626)
		(end 410.71292 -130.477006)
		(width 0.1143)
		(layer "In4.Cu")
		(net "P3E_CPU0_PE3_OCP_TXN<11>")
	)
	(segment
		(start 371.027452 -131.909312)
		(end 370.239036 -131.734814)
		(width 0.1143)
		(layer "In4.Cu")
		(net "P3E_CPU0_PE3_OCP_TXN<11>")
	)
	(segment
		(start 432.755802 -125.953012)
		(end 430.567592 -126.512066)
		(width 0.1143)
		(layer "In4.Cu")
		(net "P3E_CPU0_PE3_OCP_TXN<11>")
	)
	(segment
		(start 433.92471 -125.259846)
		(end 433.629816 -125.434852)
		(width 0.1143)
		(layer "In4.Cu")
		(net "P3E_CPU0_PE3_OCP_TXN<11>")
	)
	(segment
		(start 428.07001 -126.84125)
		(end 426.53331 -129.368042)
		(width 0.1143)
		(layer "In4.Cu")
		(net "P3E_CPU0_PE3_OCP_TXN<11>")
	)
	(segment
		(start 358.036622 -122.535442)
		(end 357.796338 -121.440956)
		(width 0.1143)
		(layer "In4.Cu")
		(net "P3E_CPU0_PE3_OCP_TXN<11>")
	)
	(segment
		(start 446.113154 -121.8311)
		(end 443.796674 -121.8311)
		(width 0.1143)
		(layer "In4.Cu")
		(net "P3E_CPU0_PE3_OCP_TXN<11>")
	)
	(segment
		(start 448.39255 -123.78817)
		(end 448.7672 -123.78817)
		(width 0.1143)
		(layer "In4.Cu")
		(net "P3E_CPU0_PE3_OCP_TXN<11>")
	)
	(segment
		(start 434.445918 -125.142752)
		(end 434.151024 -125.317758)
		(width 0.1143)
		(layer "In4.Cu")
		(net "P3E_CPU0_PE3_OCP_TXN<11>")
	)
	(segment
		(start 359.702608 -111.208312)
		(end 359.300272 -110.805976)
		(width 0.1143)
		(layer "In4.Cu")
		(net "P3E_CPU0_PE3_OCP_TXN<11>")
	)
	(segment
		(start 423.083736 -129.473198)
		(end 421.861234 -129.1082)
		(width 0.1143)
		(layer "In4.Cu")
		(net "P3E_CPU0_PE3_OCP_TXN<11>")
	)
	(segment
		(start 410.007054 -130.680206)
		(end 408.897836 -130.458464)
		(width 0.1143)
		(layer "In4.Cu")
		(net "P3E_CPU0_PE3_OCP_TXN<11>")
	)
	(segment
		(start 359.060496 -109.9439)
		(end 358.0765 -109.9439)
		(width 0.1143)
		(layer "In4.Cu")
		(net "P3E_CPU0_PE3_OCP_TXN<11>")
	)
	(segment
		(start 372.279672 -131.63042)
		(end 371.027452 -131.909312)
		(width 0.1143)
		(layer "In4.Cu")
		(net "P3E_CPU0_PE3_OCP_TXN<11>")
	)
	(segment
		(start 418.066474 -129.1082)
		(end 412.999174 -131.246626)
		(width 0.1143)
		(layer "In4.Cu")
		(net "P3E_CPU0_PE3_OCP_TXN<11>")
	)
	(segment
		(start 380.244858 -133.423914)
		(end 379.660404 -133.604762)
		(width 0.1143)
		(layer "In4.Cu")
		(net "P3E_CPU0_PE3_OCP_TXN<11>")
	)
	(segment
		(start 394.355828 -134.167372)
		(end 392.74877 -133.802628)
		(width 0.1143)
		(layer "In4.Cu")
		(net "P3E_CPU0_PE3_OCP_TXN<11>")
	)
	(segment
		(start 426.53331 -129.368042)
		(end 424.422062 -129.872994)
		(width 0.1143)
		(layer "In4.Cu")
		(net "P3E_CPU0_PE3_OCP_TXN<11>")
	)
	(segment
		(start 374.458484 -132.378958)
		(end 372.279672 -131.63042)
		(width 0.1143)
		(layer "In4.Cu")
		(net "P3E_CPU0_PE3_OCP_TXN<11>")
	)
	(segment
		(start 448.8815 -123.67387)
		(end 448.8815 -123.412758)
		(width 0.1143)
		(layer "In4.Cu")
		(net "P3E_CPU0_PE3_OCP_TXN<11>")
	)
	(segment
		(start 361.913678 -128.434084)
		(end 358.148636 -126.056898)
		(width 0.1143)
		(layer "In4.Cu")
		(net "P3E_CPU0_PE3_OCP_TXN<11>")
	)
	(segment
		(start 357.796338 -121.440956)
		(end 360.279442 -116.651532)
		(width 0.1143)
		(layer "In4.Cu")
		(net "P3E_CPU0_PE3_OCP_TXN<11>")
	)
	(segment
		(start 360.279442 -114.211608)
		(end 359.702608 -113.634774)
		(width 0.1143)
		(layer "In4.Cu")
		(net "P3E_CPU0_PE3_OCP_TXN<11>")
	)
	(segment
		(start 433.050696 -125.778006)
		(end 432.755802 -125.953012)
		(width 0.1143)
		(layer "In4.Cu")
		(net "P3E_CPU0_PE3_OCP_TXN<11>")
	)
	(segment
		(start 357.576882 -124.522484)
		(end 358.036622 -122.535442)
		(width 0.1143)
		(layer "In4.Cu")
		(net "P3E_CPU0_PE3_OCP_TXN<11>")
	)
	(segment
		(start 448.7672 -123.78817)
		(end 448.8815 -123.67387)
		(width 0.1143)
		(layer "In4.Cu")
		(net "P3E_CPU0_PE3_OCP_TXN<11>")
	)
	(segment
		(start 408.897582 -130.458464)
		(end 407.78811 -130.236468)
		(width 0.1143)
		(layer "In4.Cu")
		(net "P3E_CPU0_PE3_OCP_TXN<11>")
	)
	(segment
		(start 443.796674 -121.8311)
		(end 438.65927 -122.853196)
		(width 0.1143)
		(layer "In4.Cu")
		(net "P3E_CPU0_PE3_OCP_TXN<11>")
	)
	(segment
		(start 358.148636 -126.056898)
		(end 357.576882 -124.522484)
		(width 0.1143)
		(layer "In4.Cu")
		(net "P3E_CPU0_PE3_OCP_TXN<11>")
	)
	(segment
		(start 377.016772 -132.072634)
		(end 376.3391 -131.94157)
		(width 0.1143)
		(layer "In4.Cu")
		(net "P3E_CPU0_PE3_OCP_TXN<11>")
	)
	(segment
		(start 359.300272 -110.805976)
		(end 359.300272 -110.183676)
		(width 0.1143)
		(layer "In4.Cu")
		(net "P3E_CPU0_PE3_OCP_TXN<11>")
	)
	(segment
		(start 358.0765 -109.9439)
		(end 357.9622 -110.0582)
		(width 0.1143)
		(layer "In4.Cu")
		(net "P3E_CPU0_PE3_OCP_TXN<11>")
	)
	(segment
		(start 438.529476 -123.047252)
		(end 438.19318 -123.114308)
		(width 0.1143)
		(layer "In4.Cu")
		(net "P3E_CPU0_PE3_OCP_TXN<11>")
	)
	(segment
		(start 434.50383 -124.916692)
		(end 434.445918 -125.142752)
		(width 0.1143)
		(layer "In4.Cu")
		(net "P3E_CPU0_PE3_OCP_TXN<11>")
	)
	(segment
		(start 359.702608 -113.634774)
		(end 359.702608 -111.208312)
		(width 0.1143)
		(layer "In4.Cu")
		(net "P3E_CPU0_PE3_OCP_TXN<11>")
	)
	(segment
		(start 429.555402 -126.290832)
		(end 428.472346 -126.576328)
		(width 0.1143)
		(layer "In4.Cu")
		(net "P3E_CPU0_PE3_OCP_TXN<11>")
	)
	(segment
		(start 424.422062 -129.872994)
		(end 423.083736 -129.473452)
		(width 0.1143)
		(layer "In4.Cu")
		(net "P3E_CPU0_PE3_OCP_TXN<11>")
	)
	(segment
		(start 382.097788 -132.47751)
		(end 380.974092 -132.86994)
		(width 0.1143)
		(layer "In4.Cu")
		(net "P3E_CPU0_PE3_OCP_TXN<11>")
	)
	(segment
		(start 433.629816 -125.434852)
		(end 433.571904 -125.661166)
		(width 0.1143)
		(layer "In4.Cu")
		(net "P3E_CPU0_PE3_OCP_TXN<11>")
	)
	(segment
		(start 438.65927 -122.853196)
		(end 438.529476 -123.047252)
		(width 0.1143)
		(layer "In4.Cu")
		(net "P3E_CPU0_PE3_OCP_TXN<11>")
	)
	(segment
		(start 380.974092 -132.86994)
		(end 380.244858 -133.423914)
		(width 0.1143)
		(layer "In4.Cu")
		(net "P3E_CPU0_PE3_OCP_TXN<11>")
	)
	(segment
		(start 438.19318 -123.114308)
		(end 437.999124 -122.984514)
		(width 0.1143)
		(layer "In4.Cu")
		(net "P3E_CPU0_PE3_OCP_TXN<11>")
	)
	(segment
		(start 378.759466 -133.344412)
		(end 377.016772 -132.072634)
		(width 0.1143)
		(layer "In4.Cu")
		(net "P3E_CPU0_PE3_OCP_TXN<11>")
	)
	(segment
		(start 379.660404 -133.604762)
		(end 378.759466 -133.344412)
		(width 0.1143)
		(layer "In4.Cu")
		(net "P3E_CPU0_PE3_OCP_TXN<11>")
	)
	(segment
		(start 437.999124 -122.984514)
		(end 437.642762 -123.05538)
		(width 0.1143)
		(layer "In4.Cu")
		(net "P3E_CPU0_PE3_OCP_TXN<11>")
	)
	(segment
		(start 395.995652 -133.82117)
		(end 394.355828 -134.167372)
		(width 0.1143)
		(layer "In4.Cu")
		(net "P3E_CPU0_PE3_OCP_TXN<11>")
	)
	(segment
		(start 357.9622 -110.0582)
		(end 357.9622 -110.43285)
		(width 0.1143)
		(layer "In4.Cu")
		(net "P3E_CPU0_PE3_OCP_TXN<11>")
	)
	(segment
		(start 448.8815 -123.412758)
		(end 448.74561 -123.276868)
		(width 0.1143)
		(layer "In4.Cu")
		(net "P3E_CPU0_PE3_OCP_TXN<11>")
	)
	(segment
		(start 437.642762 -123.05538)
		(end 434.50383 -124.916692)
		(width 0.1143)
		(layer "In4.Cu")
		(net "P3E_CPU0_PE3_OCP_TXN<11>")
	)
	(segment
		(start 421.861234 -129.1082)
		(end 418.066474 -129.1082)
		(width 0.1143)
		(layer "In4.Cu")
		(net "P3E_CPU0_PE3_OCP_TXN<11>")
	)
	(segment
		(start 360.279442 -116.651532)
		(end 360.279442 -114.211608)
		(width 0.1143)
		(layer "In4.Cu")
		(net "P3E_CPU0_PE3_OCP_TXN<11>")
	)
	(segment
		(start 433.27701 -125.835918)
		(end 433.050696 -125.778006)
		(width 0.1143)
		(layer "In4.Cu")
		(net "P3E_CPU0_PE3_OCP_TXN<11>")
	)
	(segment
		(start 390.567418 -134.242048)
		(end 382.097788 -132.47751)
		(width 0.1143)
		(layer "In4.Cu")
		(net "P3E_CPU0_PE3_OCP_TXN<11>")
	)
	(segment
		(start 430.567592 -126.512066)
		(end 429.555402 -126.290832)
		(width 0.1143)
		(layer "In4.Cu")
		(net "P3E_CPU0_PE3_OCP_TXN<11>")
	)
	(segment
		(start 428.472346 -126.576328)
		(end 428.07001 -126.84125)
		(width 0.1143)
		(layer "In4.Cu")
		(net "P3E_CPU0_PE3_OCP_TXN<11>")
	)
	(segment
		(start 392.74877 -133.802628)
		(end 390.567418 -134.242048)
		(width 0.1143)
		(layer "In4.Cu")
		(net "P3E_CPU0_PE3_OCP_TXN<11>")
	)
	(segment
		(start 448.74561 -123.276868)
		(end 446.719198 -122.437398)
		(width 0.1143)
		(layer "In4.Cu")
		(net "P3E_CPU0_PE3_OCP_TXN<11>")
	)
	(segment
		(start 397.941546 -134.313676)
		(end 395.995652 -133.82117)
		(width 0.1143)
		(layer "In4.Cu")
		(net "P3E_CPU0_PE3_OCP_TXN<11>")
	)
	(segment
		(start 433.571904 -125.661166)
		(end 433.27701 -125.835918)
		(width 0.1143)
		(layer "In4.Cu")
		(net "P3E_CPU0_PE3_OCP_TXN<11>")
	)
	(segment
		(start 410.71292 -130.477006)
		(end 410.007054 -130.680206)
		(width 0.1143)
		(layer "In4.Cu")
		(net "P3E_CPU0_PE3_OCP_TXN<11>")
	)
	(segment
		(start 446.719198 -122.437398)
		(end 446.113154 -121.8311)
		(width 0.1143)
		(layer "In4.Cu")
		(net "P3E_CPU0_PE3_OCP_TXN<11>")
	)
	(segment
		(start 359.300272 -110.183676)
		(end 359.060496 -109.9439)
		(width 0.1143)
		(layer "In4.Cu")
		(net "P3E_CPU0_PE3_OCP_TXN<11>")
	)
	(segment
		(start 370.239036 -131.734814)
		(end 361.913678 -128.434084)
		(width 0.1143)
		(layer "In4.Cu")
		(net "P3E_CPU0_PE3_OCP_TXN<11>")
	)
	(segment
		(start 332.510892 -110.71225)
		(end 332.0034 -110.204758)
		(width 0.1143)
		(layer "In11.Cu")
		(net "P3E_CPU0_PE3_OCP_TXN<11>")
	)
	(segment
		(start 357.9622 -110.43285)
		(end 357.9622 -110.0582)
		(width 0.1143)
		(layer "In11.Cu")
		(net "P3E_CPU0_PE3_OCP_TXN<11>")
	)
	(segment
		(start 305.021488 -94.598236)
		(end 304.978308 -94.756732)
		(width 0.0889)
		(layer "In11.Cu")
		(net "P3E_CPU0_PE3_OCP_TXN<11>")
	)
	(segment
		(start 312.565288 -98.60153)
		(end 311.55894 -96.598486)
		(width 0.1143)
		(layer "In11.Cu")
		(net "P3E_CPU0_PE3_OCP_TXN<11>")
	)
	(segment
		(start 315.56452 -102.294944)
		(end 312.565288 -98.60153)
		(width 0.1143)
		(layer "In11.Cu")
		(net "P3E_CPU0_PE3_OCP_TXN<11>")
	)
	(segment
		(start 305.234086 -94.385638)
		(end 305.021488 -94.598236)
		(width 0.0889)
		(layer "In11.Cu")
		(net "P3E_CPU0_PE3_OCP_TXN<11>")
	)
	(segment
		(start 346.33408 -111.906812)
		(end 345.850972 -111.583978)
		(width 0.1143)
		(layer "In11.Cu")
		(net "P3E_CPU0_PE3_OCP_TXN<11>")
	)
	(segment
		(start 332.0034 -110.204758)
		(end 332.0034 -108.401358)
		(width 0.1143)
		(layer "In11.Cu")
		(net "P3E_CPU0_PE3_OCP_TXN<11>")
	)
	(segment
		(start 356.8319 -111.3663)
		(end 355.245162 -111.3663)
		(width 0.1143)
		(layer "In11.Cu")
		(net "P3E_CPU0_PE3_OCP_TXN<11>")
	)
	(segment
		(start 305.016154 -94.89948)
		(end 305.246786 -95.033084)
		(width 0.0889)
		(layer "In11.Cu")
		(net "P3E_CPU0_PE3_OCP_TXN<11>")
	)
	(segment
		(start 309.291482 -94.331028)
		(end 307.717698 -93.678756)
		(width 0.1143)
		(layer "In11.Cu")
		(net "P3E_CPU0_PE3_OCP_TXN<11>")
	)
	(segment
		(start 354.70465 -111.906812)
		(end 346.33408 -111.906812)
		(width 0.1143)
		(layer "In11.Cu")
		(net "P3E_CPU0_PE3_OCP_TXN<11>")
	)
	(segment
		(start 305.377088 -94.385638)
		(end 305.234086 -94.385638)
		(width 0.0889)
		(layer "In11.Cu")
		(net "P3E_CPU0_PE3_OCP_TXN<11>")
	)
	(segment
		(start 305.502818 -94.259908)
		(end 305.377088 -94.385638)
		(width 0.0889)
		(layer "In11.Cu")
		(net "P3E_CPU0_PE3_OCP_TXN<11>")
	)
	(segment
		(start 331.640942 -108.0389)
		(end 329.42784 -108.0389)
		(width 0.1143)
		(layer "In11.Cu")
		(net "P3E_CPU0_PE3_OCP_TXN<11>")
	)
	(segment
		(start 305.656234 -93.96349)
		(end 305.502818 -94.116906)
		(width 0.0889)
		(layer "In11.Cu")
		(net "P3E_CPU0_PE3_OCP_TXN<11>")
	)
	(segment
		(start 357.8479 -109.9439)
		(end 357.4923 -109.9439)
		(width 0.1143)
		(layer "In11.Cu")
		(net "P3E_CPU0_PE3_OCP_TXN<11>")
	)
	(segment
		(start 332.0034 -108.401358)
		(end 331.640942 -108.0389)
		(width 0.1143)
		(layer "In11.Cu")
		(net "P3E_CPU0_PE3_OCP_TXN<11>")
	)
	(segment
		(start 307.337968 -93.678756)
		(end 307.31587 -93.678756)
		(width 0.0889)
		(layer "In11.Cu")
		(net "P3E_CPU0_PE3_OCP_TXN<11>")
	)
	(segment
		(start 344.54719 -110.71225)
		(end 332.510892 -110.71225)
		(width 0.1143)
		(layer "In11.Cu")
		(net "P3E_CPU0_PE3_OCP_TXN<11>")
	)
	(segment
		(start 306.124102 -93.847666)
		(end 305.959764 -93.915738)
		(width 0.0889)
		(layer "In11.Cu")
		(net "P3E_CPU0_PE3_OCP_TXN<11>")
	)
	(segment
		(start 345.850972 -111.583978)
		(end 345.850972 -111.583724)
		(width 0.1143)
		(layer "In11.Cu")
		(net "P3E_CPU0_PE3_OCP_TXN<11>")
	)
	(segment
		(start 357.378 -110.0582)
		(end 357.378 -110.8202)
		(width 0.1143)
		(layer "In11.Cu")
		(net "P3E_CPU0_PE3_OCP_TXN<11>")
	)
	(segment
		(start 307.717698 -93.678756)
		(end 307.337968 -93.678756)
		(width 0.1143)
		(layer "In11.Cu")
		(net "P3E_CPU0_PE3_OCP_TXN<11>")
	)
	(segment
		(start 357.9622 -110.0582)
		(end 357.8479 -109.9439)
		(width 0.1143)
		(layer "In11.Cu")
		(net "P3E_CPU0_PE3_OCP_TXN<11>")
	)
	(segment
		(start 306.163218 -93.753432)
		(end 306.124102 -93.847666)
		(width 0.0889)
		(layer "In11.Cu")
		(net "P3E_CPU0_PE3_OCP_TXN<11>")
	)
	(segment
		(start 345.850972 -111.583724)
		(end 344.54719 -110.71225)
		(width 0.1143)
		(layer "In11.Cu")
		(net "P3E_CPU0_PE3_OCP_TXN<11>")
	)
	(segment
		(start 304.978308 -94.756732)
		(end 305.016154 -94.89948)
		(width 0.0889)
		(layer "In11.Cu")
		(net "P3E_CPU0_PE3_OCP_TXN<11>")
	)
	(segment
		(start 311.55894 -96.598486)
		(end 309.291482 -94.331028)
		(width 0.1143)
		(layer "In11.Cu")
		(net "P3E_CPU0_PE3_OCP_TXN<11>")
	)
	(segment
		(start 306.49672 -93.615256)
		(end 306.163218 -93.753432)
		(width 0.0889)
		(layer "In11.Cu")
		(net "P3E_CPU0_PE3_OCP_TXN<11>")
	)
	(segment
		(start 357.4923 -109.9439)
		(end 357.378 -110.0582)
		(width 0.1143)
		(layer "In11.Cu")
		(net "P3E_CPU0_PE3_OCP_TXN<11>")
	)
	(segment
		(start 307.31587 -93.678756)
		(end 307.25237 -93.615256)
		(width 0.0889)
		(layer "In11.Cu")
		(net "P3E_CPU0_PE3_OCP_TXN<11>")
	)
	(segment
		(start 355.245162 -111.3663)
		(end 354.70465 -111.906812)
		(width 0.1143)
		(layer "In11.Cu")
		(net "P3E_CPU0_PE3_OCP_TXN<11>")
	)
	(segment
		(start 357.378 -110.8202)
		(end 356.8319 -111.3663)
		(width 0.1143)
		(layer "In11.Cu")
		(net "P3E_CPU0_PE3_OCP_TXN<11>")
	)
	(segment
		(start 305.959764 -93.915738)
		(end 305.865784 -93.876876)
		(width 0.0889)
		(layer "In11.Cu")
		(net "P3E_CPU0_PE3_OCP_TXN<11>")
	)
	(segment
		(start 329.42784 -108.0389)
		(end 315.56452 -102.294944)
		(width 0.1143)
		(layer "In11.Cu")
		(net "P3E_CPU0_PE3_OCP_TXN<11>")
	)
	(segment
		(start 307.25237 -93.615256)
		(end 306.49672 -93.615256)
		(width 0.0889)
		(layer "In11.Cu")
		(net "P3E_CPU0_PE3_OCP_TXN<11>")
	)
	(segment
		(start 305.865784 -93.876876)
		(end 305.656234 -93.96349)
		(width 0.0889)
		(layer "In11.Cu")
		(net "P3E_CPU0_PE3_OCP_TXN<11>")
	)
	(segment
		(start 305.502818 -94.116906)
		(end 305.502818 -94.259908)
		(width 0.0889)
		(layer "In11.Cu")
		(net "P3E_CPU0_PE3_OCP_TXN<11>")
	)
	(segment
		(start 303.529746 -96.023938)
		(end 302.958246 -96.023938)
		(width 0.1143)
		(layer "F.Cu")
		(net "P3E_CPU0_PE3_OCP_TXN<10>")
	)
	(via
		(at 445.40805 -126.087124)
		(size 0.508)
		(drill 0.254)
		(layers "F.Cu" "B.Cu")
		(net "P3E_CPU0_PE3_OCP_TXN<10>")
	)
	(via
		(at 303.529746 -96.023938)
		(size 0.508)
		(drill 0.254)
		(layers "F.Cu" "B.Cu")
		(net "P3E_CPU0_PE3_OCP_TXN<10>")
	)
	(via
		(at 358.26065 -115.204494)
		(size 0.508)
		(drill 0.254)
		(layers "F.Cu" "B.Cu")
		(net "P3E_CPU0_PE3_OCP_TXN<10>")
	)
	(segment
		(start 446.851278 -122.88139)
		(end 445.9224 -125.129798)
		(width 0.1143)
		(layer "B.Cu")
		(net "P3E_CPU0_PE3_OCP_TXN<10>")
	)
	(segment
		(start 449.58635 -117.239796)
		(end 449.339208 -117.602762)
		(width 0.1143)
		(layer "B.Cu")
		(net "P3E_CPU0_PE3_OCP_TXN<10>")
	)
	(segment
		(start 449.58635 -116.87937)
		(end 449.58635 -117.239796)
		(width 0.1143)
		(layer "B.Cu")
		(net "P3E_CPU0_PE3_OCP_TXN<10>")
	)
	(segment
		(start 449.199 -116.49202)
		(end 449.58635 -116.87937)
		(width 0.1143)
		(layer "B.Cu")
		(net "P3E_CPU0_PE3_OCP_TXN<10>")
	)
	(segment
		(start 445.9224 -125.972824)
		(end 445.8081 -126.087124)
		(width 0.1143)
		(layer "B.Cu")
		(net "P3E_CPU0_PE3_OCP_TXN<10>")
	)
	(segment
		(start 449.339208 -117.602762)
		(end 446.743836 -119.56415)
		(width 0.1143)
		(layer "B.Cu")
		(net "P3E_CPU0_PE3_OCP_TXN<10>")
	)
	(segment
		(start 446.743836 -119.56415)
		(end 446.332102 -120.471946)
		(width 0.1143)
		(layer "B.Cu")
		(net "P3E_CPU0_PE3_OCP_TXN<10>")
	)
	(segment
		(start 446.332102 -120.471946)
		(end 446.851278 -122.88139)
		(width 0.1143)
		(layer "B.Cu")
		(net "P3E_CPU0_PE3_OCP_TXN<10>")
	)
	(segment
		(start 445.8081 -126.087124)
		(end 445.40805 -126.087124)
		(width 0.1143)
		(layer "B.Cu")
		(net "P3E_CPU0_PE3_OCP_TXN<10>")
	)
	(segment
		(start 445.9224 -125.129798)
		(end 445.9224 -125.972824)
		(width 0.1143)
		(layer "B.Cu")
		(net "P3E_CPU0_PE3_OCP_TXN<10>")
	)
	(segment
		(start 361.324398 -129.594102)
		(end 357.069898 -126.908052)
		(width 0.1143)
		(layer "In4.Cu")
		(net "P3E_CPU0_PE3_OCP_TXN<10>")
	)
	(segment
		(start 445.7827 -126.087124)
		(end 445.897 -125.972824)
		(width 0.1143)
		(layer "In4.Cu")
		(net "P3E_CPU0_PE3_OCP_TXN<10>")
	)
	(segment
		(start 373.659654 -134.709154)
		(end 372.511574 -133.82117)
		(width 0.1143)
		(layer "In4.Cu")
		(net "P3E_CPU0_PE3_OCP_TXN<10>")
	)
	(segment
		(start 357.746554 -115.566444)
		(end 358.14635 -115.566444)
		(width 0.1143)
		(layer "In4.Cu")
		(net "P3E_CPU0_PE3_OCP_TXN<10>")
	)
	(segment
		(start 419.158928 -136.161018)
		(end 418.059362 -136.78154)
		(width 0.1143)
		(layer "In4.Cu")
		(net "P3E_CPU0_PE3_OCP_TXN<10>")
	)
	(segment
		(start 430.412652 -129.244344)
		(end 430.399444 -129.248154)
		(width 0.1143)
		(layer "In4.Cu")
		(net "P3E_CPU0_PE3_OCP_TXN<10>")
	)
	(segment
		(start 370.102892 -133.670802)
		(end 368.3381 -132.370576)
		(width 0.1143)
		(layer "In4.Cu")
		(net "P3E_CPU0_PE3_OCP_TXN<10>")
	)
	(segment
		(start 427.331632 -131.390898)
		(end 425.64939 -131.036314)
		(width 0.1143)
		(layer "In4.Cu")
		(net "P3E_CPU0_PE3_OCP_TXN<10>")
	)
	(segment
		(start 415.91992 -137.227818)
		(end 415.91992 -137.227564)
		(width 0.1143)
		(layer "In4.Cu")
		(net "P3E_CPU0_PE3_OCP_TXN<10>")
	)
	(segment
		(start 358.26065 -115.452144)
		(end 358.26065 -115.204494)
		(width 0.1143)
		(layer "In4.Cu")
		(net "P3E_CPU0_PE3_OCP_TXN<10>")
	)
	(segment
		(start 445.897 -125.972824)
		(end 445.897 -125.5776)
		(width 0.1143)
		(layer "In4.Cu")
		(net "P3E_CPU0_PE3_OCP_TXN<10>")
	)
	(segment
		(start 358.14635 -115.566444)
		(end 358.26065 -115.452144)
		(width 0.1143)
		(layer "In4.Cu")
		(net "P3E_CPU0_PE3_OCP_TXN<10>")
	)
	(segment
		(start 435.116986 -126.976886)
		(end 434.565044 -128.307846)
		(width 0.1143)
		(layer "In4.Cu")
		(net "P3E_CPU0_PE3_OCP_TXN<10>")
	)
	(segment
		(start 420.975028 -133.311646)
		(end 419.158928 -136.161018)
		(width 0.1143)
		(layer "In4.Cu")
		(net "P3E_CPU0_PE3_OCP_TXN<10>")
	)
	(segment
		(start 382.434084 -135.725154)
		(end 381.110236 -136.14146)
		(width 0.1143)
		(layer "In4.Cu")
		(net "P3E_CPU0_PE3_OCP_TXN<10>")
	)
	(segment
		(start 425.64939 -131.036314)
		(end 425.64939 -131.036568)
		(width 0.1143)
		(layer "In4.Cu")
		(net "P3E_CPU0_PE3_OCP_TXN<10>")
	)
	(segment
		(start 413.621728 -136.466326)
		(end 413.62122 -136.46658)
		(width 0.1143)
		(layer "In4.Cu")
		(net "P3E_CPU0_PE3_OCP_TXN<10>")
	)
	(segment
		(start 357.069898 -126.908052)
		(end 356.196138 -124.740162)
		(width 0.1143)
		(layer "In4.Cu")
		(net "P3E_CPU0_PE3_OCP_TXN<10>")
	)
	(segment
		(start 372.511574 -133.82117)
		(end 371.96649 -133.681724)
		(width 0.1143)
		(layer "In4.Cu")
		(net "P3E_CPU0_PE3_OCP_TXN<10>")
	)
	(segment
		(start 428.559722 -130.866896)
		(end 427.331632 -131.390898)
		(width 0.1143)
		(layer "In4.Cu")
		(net "P3E_CPU0_PE3_OCP_TXN<10>")
	)
	(segment
		(start 433.74691 -128.929638)
		(end 432.6636 -129.180844)
		(width 0.1143)
		(layer "In4.Cu")
		(net "P3E_CPU0_PE3_OCP_TXN<10>")
	)
	(segment
		(start 415.91992 -137.227564)
		(end 413.621728 -136.466326)
		(width 0.1143)
		(layer "In4.Cu")
		(net "P3E_CPU0_PE3_OCP_TXN<10>")
	)
	(segment
		(start 418.059362 -136.78154)
		(end 415.91992 -137.227818)
		(width 0.1143)
		(layer "In4.Cu")
		(net "P3E_CPU0_PE3_OCP_TXN<10>")
	)
	(segment
		(start 356.196138 -124.740162)
		(end 356.70871 -122.527568)
		(width 0.1143)
		(layer "In4.Cu")
		(net "P3E_CPU0_PE3_OCP_TXN<10>")
	)
	(segment
		(start 445.897 -125.5776)
		(end 445.178688 -124.859288)
		(width 0.1143)
		(layer "In4.Cu")
		(net "P3E_CPU0_PE3_OCP_TXN<10>")
	)
	(segment
		(start 422.8973 -131.841494)
		(end 420.975028 -133.311646)
		(width 0.1143)
		(layer "In4.Cu")
		(net "P3E_CPU0_PE3_OCP_TXN<10>")
	)
	(segment
		(start 408.339036 -138.4427)
		(end 405.414988 -139.027154)
		(width 0.1143)
		(layer "In4.Cu")
		(net "P3E_CPU0_PE3_OCP_TXN<10>")
	)
	(segment
		(start 368.3381 -132.370576)
		(end 361.324398 -129.594102)
		(width 0.1143)
		(layer "In4.Cu")
		(net "P3E_CPU0_PE3_OCP_TXN<10>")
	)
	(segment
		(start 432.6636 -129.180844)
		(end 431.53584 -128.948688)
		(width 0.1143)
		(layer "In4.Cu")
		(net "P3E_CPU0_PE3_OCP_TXN<10>")
	)
	(segment
		(start 430.39284 -129.249932)
		(end 429.305974 -129.829052)
		(width 0.1143)
		(layer "In4.Cu")
		(net "P3E_CPU0_PE3_OCP_TXN<10>")
	)
	(segment
		(start 436.130192 -125.570234)
		(end 435.116986 -126.976886)
		(width 0.1143)
		(layer "In4.Cu")
		(net "P3E_CPU0_PE3_OCP_TXN<10>")
	)
	(segment
		(start 356.70871 -122.527568)
		(end 356.43058 -121.261124)
		(width 0.1143)
		(layer "In4.Cu")
		(net "P3E_CPU0_PE3_OCP_TXN<10>")
	)
	(segment
		(start 430.399444 -129.248154)
		(end 430.39284 -129.249932)
		(width 0.1143)
		(layer "In4.Cu")
		(net "P3E_CPU0_PE3_OCP_TXN<10>")
	)
	(segment
		(start 374.555766 -136.081516)
		(end 373.659654 -134.709154)
		(width 0.1143)
		(layer "In4.Cu")
		(net "P3E_CPU0_PE3_OCP_TXN<10>")
	)
	(segment
		(start 375.704354 -136.581896)
		(end 375.02211 -136.402826)
		(width 0.1143)
		(layer "In4.Cu")
		(net "P3E_CPU0_PE3_OCP_TXN<10>")
	)
	(segment
		(start 425.64939 -131.036568)
		(end 422.8973 -131.841494)
		(width 0.1143)
		(layer "In4.Cu")
		(net "P3E_CPU0_PE3_OCP_TXN<10>")
	)
	(segment
		(start 445.178688 -124.859288)
		(end 438.68594 -124.859288)
		(width 0.1143)
		(layer "In4.Cu")
		(net "P3E_CPU0_PE3_OCP_TXN<10>")
	)
	(segment
		(start 437.069738 -125.180852)
		(end 436.130192 -125.570234)
		(width 0.1143)
		(layer "In4.Cu")
		(net "P3E_CPU0_PE3_OCP_TXN<10>")
	)
	(segment
		(start 383.9337 -136.023858)
		(end 382.434084 -135.725154)
		(width 0.1143)
		(layer "In4.Cu")
		(net "P3E_CPU0_PE3_OCP_TXN<10>")
	)
	(segment
		(start 386.551932 -135.27532)
		(end 383.9337 -136.023858)
		(width 0.1143)
		(layer "In4.Cu")
		(net "P3E_CPU0_PE3_OCP_TXN<10>")
	)
	(segment
		(start 429.305974 -129.829052)
		(end 428.559722 -130.866896)
		(width 0.1143)
		(layer "In4.Cu")
		(net "P3E_CPU0_PE3_OCP_TXN<10>")
	)
	(segment
		(start 434.565044 -128.307846)
		(end 433.74691 -128.929638)
		(width 0.1143)
		(layer "In4.Cu")
		(net "P3E_CPU0_PE3_OCP_TXN<10>")
	)
	(segment
		(start 405.414988 -139.027154)
		(end 386.551932 -135.27532)
		(width 0.1143)
		(layer "In4.Cu")
		(net "P3E_CPU0_PE3_OCP_TXN<10>")
	)
	(segment
		(start 356.43058 -121.261124)
		(end 357.466392 -119.262906)
		(width 0.1143)
		(layer "In4.Cu")
		(net "P3E_CPU0_PE3_OCP_TXN<10>")
	)
	(segment
		(start 431.53584 -128.948688)
		(end 430.412652 -129.244344)
		(width 0.1143)
		(layer "In4.Cu")
		(net "P3E_CPU0_PE3_OCP_TXN<10>")
	)
	(segment
		(start 410.200602 -137.11047)
		(end 408.339036 -138.4427)
		(width 0.1143)
		(layer "In4.Cu")
		(net "P3E_CPU0_PE3_OCP_TXN<10>")
	)
	(segment
		(start 381.110236 -136.14146)
		(end 379.470666 -135.77824)
		(width 0.1143)
		(layer "In4.Cu")
		(net "P3E_CPU0_PE3_OCP_TXN<10>")
	)
	(segment
		(start 357.466392 -115.846606)
		(end 357.746554 -115.566444)
		(width 0.1143)
		(layer "In4.Cu")
		(net "P3E_CPU0_PE3_OCP_TXN<10>")
	)
	(segment
		(start 445.40805 -126.087124)
		(end 445.7827 -126.087124)
		(width 0.1143)
		(layer "In4.Cu")
		(net "P3E_CPU0_PE3_OCP_TXN<10>")
	)
	(segment
		(start 379.470666 -135.77824)
		(end 375.704354 -136.581896)
		(width 0.1143)
		(layer "In4.Cu")
		(net "P3E_CPU0_PE3_OCP_TXN<10>")
	)
	(segment
		(start 371.96649 -133.681724)
		(end 370.846096 -133.920992)
		(width 0.1143)
		(layer "In4.Cu")
		(net "P3E_CPU0_PE3_OCP_TXN<10>")
	)
	(segment
		(start 438.68594 -124.859288)
		(end 437.069738 -125.180598)
		(width 0.1143)
		(layer "In4.Cu")
		(net "P3E_CPU0_PE3_OCP_TXN<10>")
	)
	(segment
		(start 413.62122 -136.466326)
		(end 410.200602 -137.11047)
		(width 0.1143)
		(layer "In4.Cu")
		(net "P3E_CPU0_PE3_OCP_TXN<10>")
	)
	(segment
		(start 413.62122 -136.46658)
		(end 413.62122 -136.466326)
		(width 0.1143)
		(layer "In4.Cu")
		(net "P3E_CPU0_PE3_OCP_TXN<10>")
	)
	(segment
		(start 437.069738 -125.180598)
		(end 437.069738 -125.180852)
		(width 0.1143)
		(layer "In4.Cu")
		(net "P3E_CPU0_PE3_OCP_TXN<10>")
	)
	(segment
		(start 357.466392 -119.262906)
		(end 357.466392 -115.846606)
		(width 0.1143)
		(layer "In4.Cu")
		(net "P3E_CPU0_PE3_OCP_TXN<10>")
	)
	(segment
		(start 370.846096 -133.920992)
		(end 370.102892 -133.670802)
		(width 0.1143)
		(layer "In4.Cu")
		(net "P3E_CPU0_PE3_OCP_TXN<10>")
	)
	(segment
		(start 375.02211 -136.402826)
		(end 374.555766 -136.081516)
		(width 0.1143)
		(layer "In4.Cu")
		(net "P3E_CPU0_PE3_OCP_TXN<10>")
	)
	(segment
		(start 315.57214 -102.914958)
		(end 316.39764 -103.257096)
		(width 0.1143)
		(layer "In11.Cu")
		(net "P3E_CPU0_PE3_OCP_TXN<10>")
	)
	(segment
		(start 354.892102 -112.8649)
		(end 355.666548 -113.639092)
		(width 0.1143)
		(layer "In11.Cu")
		(net "P3E_CPU0_PE3_OCP_TXN<10>")
	)
	(segment
		(start 355.666548 -113.639092)
		(end 357.117396 -114.24031)
		(width 0.1143)
		(layer "In11.Cu")
		(net "P3E_CPU0_PE3_OCP_TXN<10>")
	)
	(segment
		(start 317.8683 -103.688642)
		(end 317.957708 -103.904288)
		(width 0.1143)
		(layer "In11.Cu")
		(net "P3E_CPU0_PE3_OCP_TXN<10>")
	)
	(segment
		(start 316.39764 -103.257096)
		(end 316.613286 -103.167942)
		(width 0.1143)
		(layer "In11.Cu")
		(net "P3E_CPU0_PE3_OCP_TXN<10>")
	)
	(segment
		(start 306.430172 -94.442534)
		(end 308.631336 -94.442534)
		(width 0.0889)
		(layer "In11.Cu")
		(net "P3E_CPU0_PE3_OCP_TXN<10>")
	)
	(segment
		(start 316.930024 -103.29926)
		(end 317.019178 -103.51516)
		(width 0.1143)
		(layer "In11.Cu")
		(net "P3E_CPU0_PE3_OCP_TXN<10>")
	)
	(segment
		(start 317.019178 -103.51516)
		(end 317.335916 -103.646478)
		(width 0.1143)
		(layer "In11.Cu")
		(net "P3E_CPU0_PE3_OCP_TXN<10>")
	)
	(segment
		(start 303.822862 -95.854774)
		(end 303.846738 -95.765366)
		(width 0.0889)
		(layer "In11.Cu")
		(net "P3E_CPU0_PE3_OCP_TXN<10>")
	)
	(segment
		(start 305.439318 -95.433388)
		(end 306.430172 -94.442534)
		(width 0.0889)
		(layer "In11.Cu")
		(net "P3E_CPU0_PE3_OCP_TXN<10>")
	)
	(segment
		(start 311.997852 -98.5139)
		(end 315.57214 -102.914958)
		(width 0.1143)
		(layer "In11.Cu")
		(net "P3E_CPU0_PE3_OCP_TXN<10>")
	)
	(segment
		(start 311.242456 -96.981518)
		(end 311.997852 -98.5139)
		(width 0.1143)
		(layer "In11.Cu")
		(net "P3E_CPU0_PE3_OCP_TXN<10>")
	)
	(segment
		(start 346.412058 -112.864646)
		(end 346.412312 -112.8649)
		(width 0.1143)
		(layer "In11.Cu")
		(net "P3E_CPU0_PE3_OCP_TXN<10>")
	)
	(segment
		(start 357.6828 -114.805968)
		(end 357.6828 -115.4176)
		(width 0.1143)
		(layer "In11.Cu")
		(net "P3E_CPU0_PE3_OCP_TXN<10>")
	)
	(segment
		(start 358.26065 -115.32997)
		(end 358.26065 -115.204494)
		(width 0.1143)
		(layer "In11.Cu")
		(net "P3E_CPU0_PE3_OCP_TXN<10>")
	)
	(segment
		(start 357.6828 -115.4176)
		(end 357.8098 -115.5446)
		(width 0.1143)
		(layer "In11.Cu")
		(net "P3E_CPU0_PE3_OCP_TXN<10>")
	)
	(segment
		(start 308.631336 -94.442534)
		(end 310.124094 -95.935292)
		(width 0.0889)
		(layer "In11.Cu")
		(net "P3E_CPU0_PE3_OCP_TXN<10>")
	)
	(segment
		(start 328.85634 -109.582712)
		(end 331.852778 -111.58728)
		(width 0.1143)
		(layer "In11.Cu")
		(net "P3E_CPU0_PE3_OCP_TXN<10>")
	)
	(segment
		(start 305.11623 -95.433388)
		(end 305.439318 -95.433388)
		(width 0.0889)
		(layer "In11.Cu")
		(net "P3E_CPU0_PE3_OCP_TXN<10>")
	)
	(segment
		(start 316.613286 -103.167942)
		(end 316.930024 -103.29926)
		(width 0.1143)
		(layer "In11.Cu")
		(net "P3E_CPU0_PE3_OCP_TXN<10>")
	)
	(segment
		(start 303.529746 -96.023938)
		(end 303.822862 -95.854774)
		(width 0.0889)
		(layer "In11.Cu")
		(net "P3E_CPU0_PE3_OCP_TXN<10>")
	)
	(segment
		(start 357.117396 -114.24031)
		(end 357.6828 -114.805968)
		(width 0.1143)
		(layer "In11.Cu")
		(net "P3E_CPU0_PE3_OCP_TXN<10>")
	)
	(segment
		(start 310.124094 -95.935292)
		(end 310.19623 -95.935292)
		(width 0.0889)
		(layer "In11.Cu")
		(net "P3E_CPU0_PE3_OCP_TXN<10>")
	)
	(segment
		(start 331.852778 -111.58728)
		(end 344.500708 -111.58728)
		(width 0.1143)
		(layer "In11.Cu")
		(net "P3E_CPU0_PE3_OCP_TXN<10>")
	)
	(segment
		(start 358.04602 -115.5446)
		(end 358.26065 -115.32997)
		(width 0.1143)
		(layer "In11.Cu")
		(net "P3E_CPU0_PE3_OCP_TXN<10>")
	)
	(segment
		(start 317.957708 -103.904288)
		(end 328.22515 -108.161836)
		(width 0.1143)
		(layer "In11.Cu")
		(net "P3E_CPU0_PE3_OCP_TXN<10>")
	)
	(segment
		(start 304.366676 -94.937834)
		(end 304.409856 -94.937834)
		(width 0.0889)
		(layer "In11.Cu")
		(net "P3E_CPU0_PE3_OCP_TXN<10>")
	)
	(segment
		(start 346.412312 -112.8649)
		(end 354.892102 -112.8649)
		(width 0.1143)
		(layer "In11.Cu")
		(net "P3E_CPU0_PE3_OCP_TXN<10>")
	)
	(segment
		(start 317.335916 -103.646478)
		(end 317.551562 -103.557324)
		(width 0.1143)
		(layer "In11.Cu")
		(net "P3E_CPU0_PE3_OCP_TXN<10>")
	)
	(segment
		(start 310.211724 -95.950786)
		(end 311.242456 -96.981518)
		(width 0.1143)
		(layer "In11.Cu")
		(net "P3E_CPU0_PE3_OCP_TXN<10>")
	)
	(segment
		(start 310.19623 -95.935292)
		(end 310.211724 -95.950786)
		(width 0.0889)
		(layer "In11.Cu")
		(net "P3E_CPU0_PE3_OCP_TXN<10>")
	)
	(segment
		(start 328.22515 -108.161836)
		(end 328.85634 -109.582712)
		(width 0.1143)
		(layer "In11.Cu")
		(net "P3E_CPU0_PE3_OCP_TXN<10>")
	)
	(segment
		(start 317.551562 -103.557324)
		(end 317.8683 -103.688642)
		(width 0.1143)
		(layer "In11.Cu")
		(net "P3E_CPU0_PE3_OCP_TXN<10>")
	)
	(segment
		(start 344.500708 -111.58728)
		(end 346.412058 -112.864646)
		(width 0.1143)
		(layer "In11.Cu")
		(net "P3E_CPU0_PE3_OCP_TXN<10>")
	)
	(segment
		(start 357.8098 -115.5446)
		(end 358.04602 -115.5446)
		(width 0.1143)
		(layer "In11.Cu")
		(net "P3E_CPU0_PE3_OCP_TXN<10>")
	)
	(arc
		(start 304.900076 -95.232982)
		(mid 304.99308 -95.349438)
		(end 305.11623 -95.433388)
		(width 0.0889)
		(layer "In11.Cu")
		(net "P3E_CPU0_PE3_OCP_TXN<10>")
	)
	(arc
		(start 303.876456 -95.232982)
		(mid 304.08346 -95.022118)
		(end 304.366676 -94.937834)
		(width 0.0889)
		(layer "In11.Cu")
		(net "P3E_CPU0_PE3_OCP_TXN<10>")
	)
	(arc
		(start 304.409856 -94.937834)
		(mid 304.693073 -95.022115)
		(end 304.900076 -95.232982)
		(width 0.0889)
		(layer "In11.Cu")
		(net "P3E_CPU0_PE3_OCP_TXN<10>")
	)
	(arc
		(start 303.846738 -95.765366)
		(mid 303.798178 -95.495641)
		(end 303.876456 -95.232982)
		(width 0.0889)
		(layer "In11.Cu")
		(net "P3E_CPU0_PE3_OCP_TXN<10>")
	)
	(segment
		(start 296.09034 -102.958138)
		(end 296.66184 -102.958138)
		(width 0.1143)
		(layer "F.Cu")
		(net "P3E_CPU0_PE3_OCP_TXN<0>")
	)
	(via
		(at 296.66184 -102.958138)
		(size 0.508)
		(drill 0.254)
		(layers "F.Cu" "B.Cu")
		(net "P3E_CPU0_PE3_OCP_TXN<0>")
	)
	(via
		(at 463.97799 -53.888894)
		(size 0.508)
		(drill 0.254)
		(layers "F.Cu" "B.Cu")
		(net "P3E_CPU0_PE3_OCP_TXN<0>")
	)
	(segment
		(start 463.8294 -52.432458)
		(end 463.8294 -52.837334)
		(width 0.1143)
		(layer "B.Cu")
		(net "P3E_CPU0_PE3_OCP_TXN<0>")
	)
	(segment
		(start 463.44205 -53.3908)
		(end 463.940144 -53.888894)
		(width 0.1143)
		(layer "B.Cu")
		(net "P3E_CPU0_PE3_OCP_TXN<0>")
	)
	(segment
		(start 463.940144 -53.888894)
		(end 463.97799 -53.888894)
		(width 0.1143)
		(layer "B.Cu")
		(net "P3E_CPU0_PE3_OCP_TXN<0>")
	)
	(segment
		(start 463.7151 -52.951634)
		(end 463.55635 -52.951634)
		(width 0.1143)
		(layer "B.Cu")
		(net "P3E_CPU0_PE3_OCP_TXN<0>")
	)
	(segment
		(start 463.44205 -53.065934)
		(end 463.44205 -53.3908)
		(width 0.1143)
		(layer "B.Cu")
		(net "P3E_CPU0_PE3_OCP_TXN<0>")
	)
	(segment
		(start 463.8294 -52.837334)
		(end 463.7151 -52.951634)
		(width 0.1143)
		(layer "B.Cu")
		(net "P3E_CPU0_PE3_OCP_TXN<0>")
	)
	(segment
		(start 463.55635 -52.951634)
		(end 463.44205 -53.065934)
		(width 0.1143)
		(layer "B.Cu")
		(net "P3E_CPU0_PE3_OCP_TXN<0>")
	)
	(segment
		(start 419.090602 -62.03569)
		(end 420.558722 -60.56757)
		(width 0.1143)
		(layer "In4.Cu")
		(net "P3E_CPU0_PE3_OCP_TXN<0>")
	)
	(segment
		(start 329.177142 -76.339192)
		(end 329.17765 -76.338684)
		(width 0.1143)
		(layer "In4.Cu")
		(net "P3E_CPU0_PE3_OCP_TXN<0>")
	)
	(segment
		(start 416.889438 -62.399672)
		(end 417.25342 -62.03569)
		(width 0.1143)
		(layer "In4.Cu")
		(net "P3E_CPU0_PE3_OCP_TXN<0>")
	)
	(segment
		(start 299.841158 -104.455468)
		(end 300.749716 -104.455468)
		(width 0.0889)
		(layer "In4.Cu")
		(net "P3E_CPU0_PE3_OCP_TXN<0>")
	)
	(segment
		(start 407.944066 -62.58306)
		(end 410.942282 -62.58306)
		(width 0.1143)
		(layer "In4.Cu")
		(net "P3E_CPU0_PE3_OCP_TXN<0>")
	)
	(segment
		(start 379.53696 -59.353196)
		(end 380.41961 -60.235846)
		(width 0.1143)
		(layer "In4.Cu")
		(net "P3E_CPU0_PE3_OCP_TXN<0>")
	)
	(segment
		(start 305.850036 -105.0671)
		(end 307.813456 -104.254554)
		(width 0.1143)
		(layer "In4.Cu")
		(net "P3E_CPU0_PE3_OCP_TXN<0>")
	)
	(segment
		(start 345.847416 -66.614802)
		(end 347.083888 -66.902584)
		(width 0.1143)
		(layer "In4.Cu")
		(net "P3E_CPU0_PE3_OCP_TXN<0>")
	)
	(segment
		(start 380.41961 -60.235846)
		(end 381.639826 -60.235846)
		(width 0.1143)
		(layer "In4.Cu")
		(net "P3E_CPU0_PE3_OCP_TXN<0>")
	)
	(segment
		(start 296.66184 -102.620064)
		(end 296.719498 -102.562406)
		(width 0.0889)
		(layer "In4.Cu")
		(net "P3E_CPU0_PE3_OCP_TXN<0>")
	)
	(segment
		(start 416.399726 -63.2841)
		(end 416.889438 -62.794388)
		(width 0.1143)
		(layer "In4.Cu")
		(net "P3E_CPU0_PE3_OCP_TXN<0>")
	)
	(segment
		(start 348.611698 -66.605658)
		(end 349.879158 -66.90233)
		(width 0.1143)
		(layer "In4.Cu")
		(net "P3E_CPU0_PE3_OCP_TXN<0>")
	)
	(segment
		(start 399.080228 -58.8518)
		(end 401.668234 -61.439806)
		(width 0.1143)
		(layer "In4.Cu")
		(net "P3E_CPU0_PE3_OCP_TXN<0>")
	)
	(segment
		(start 307.813456 -104.254554)
		(end 324.35673 -87.718138)
		(width 0.1143)
		(layer "In4.Cu")
		(net "P3E_CPU0_PE3_OCP_TXN<0>")
	)
	(segment
		(start 357.970582 -66.713354)
		(end 358.974644 -66.713354)
		(width 0.1143)
		(layer "In4.Cu")
		(net "P3E_CPU0_PE3_OCP_TXN<0>")
	)
	(segment
		(start 300.749716 -104.455468)
		(end 300.800516 -104.506268)
		(width 0.0889)
		(layer "In4.Cu")
		(net "P3E_CPU0_PE3_OCP_TXN<0>")
	)
	(segment
		(start 415.131758 -63.2841)
		(end 416.399726 -63.2841)
		(width 0.1143)
		(layer "In4.Cu")
		(net "P3E_CPU0_PE3_OCP_TXN<0>")
	)
	(segment
		(start 297.00855 -102.757986)
		(end 297.009312 -102.759256)
		(width 0.0889)
		(layer "In4.Cu")
		(net "P3E_CPU0_PE3_OCP_TXN<0>")
	)
	(segment
		(start 421.765222 -60.390532)
		(end 425.94784 -60.390532)
		(width 0.1143)
		(layer "In4.Cu")
		(net "P3E_CPU0_PE3_OCP_TXN<0>")
	)
	(segment
		(start 300.822614 -104.506268)
		(end 301.874936 -104.506268)
		(width 0.1143)
		(layer "In4.Cu")
		(net "P3E_CPU0_PE3_OCP_TXN<0>")
	)
	(segment
		(start 297.981878 -103.68534)
		(end 299.841158 -104.455468)
		(width 0.0889)
		(layer "In4.Cu")
		(net "P3E_CPU0_PE3_OCP_TXN<0>")
	)
	(segment
		(start 425.94784 -60.390532)
		(end 426.203364 -60.135008)
		(width 0.1143)
		(layer "In4.Cu")
		(net "P3E_CPU0_PE3_OCP_TXN<0>")
	)
	(segment
		(start 355.49459 -67.676522)
		(end 357.38562 -67.298316)
		(width 0.1143)
		(layer "In4.Cu")
		(net "P3E_CPU0_PE3_OCP_TXN<0>")
	)
	(segment
		(start 301.874936 -104.506268)
		(end 303.228502 -105.0671)
		(width 0.1143)
		(layer "In4.Cu")
		(net "P3E_CPU0_PE3_OCP_TXN<0>")
	)
	(segment
		(start 401.668234 -61.439806)
		(end 406.800812 -61.439806)
		(width 0.1143)
		(layer "In4.Cu")
		(net "P3E_CPU0_PE3_OCP_TXN<0>")
	)
	(segment
		(start 329.17765 -76.33843)
		(end 332.35519 -71.71817)
		(width 0.1143)
		(layer "In4.Cu")
		(net "P3E_CPU0_PE3_OCP_TXN<0>")
	)
	(segment
		(start 463.48904 -54.003194)
		(end 463.60334 -53.888894)
		(width 0.1143)
		(layer "In4.Cu")
		(net "P3E_CPU0_PE3_OCP_TXN<0>")
	)
	(segment
		(start 428.550324 -60.666122)
		(end 428.550324 -61.825632)
		(width 0.1143)
		(layer "In4.Cu")
		(net "P3E_CPU0_PE3_OCP_TXN<0>")
	)
	(segment
		(start 297.010836 -102.76205)
		(end 297.093894 -102.905052)
		(width 0.0889)
		(layer "In4.Cu")
		(net "P3E_CPU0_PE3_OCP_TXN<0>")
	)
	(segment
		(start 347.083888 -66.902584)
		(end 348.611698 -66.605658)
		(width 0.1143)
		(layer "In4.Cu")
		(net "P3E_CPU0_PE3_OCP_TXN<0>")
	)
	(segment
		(start 297.115738 -102.926896)
		(end 297.981878 -103.68534)
		(width 0.0889)
		(layer "In4.Cu")
		(net "P3E_CPU0_PE3_OCP_TXN<0>")
	)
	(segment
		(start 329.17765 -76.338684)
		(end 329.17765 -76.33843)
		(width 0.1143)
		(layer "In4.Cu")
		(net "P3E_CPU0_PE3_OCP_TXN<0>")
	)
	(segment
		(start 456.61199 -61.871606)
		(end 458.636878 -59.846718)
		(width 0.1143)
		(layer "In4.Cu")
		(net "P3E_CPU0_PE3_OCP_TXN<0>")
	)
	(segment
		(start 338.565998 -67.630294)
		(end 343.133934 -66.741548)
		(width 0.1143)
		(layer "In4.Cu")
		(net "P3E_CPU0_PE3_OCP_TXN<0>")
	)
	(segment
		(start 459.987142 -59.846718)
		(end 463.48904 -56.34482)
		(width 0.1143)
		(layer "In4.Cu")
		(net "P3E_CPU0_PE3_OCP_TXN<0>")
	)
	(segment
		(start 416.889438 -62.794388)
		(end 416.889438 -62.399672)
		(width 0.1143)
		(layer "In4.Cu")
		(net "P3E_CPU0_PE3_OCP_TXN<0>")
	)
	(segment
		(start 324.35673 -87.718138)
		(end 329.177142 -76.339192)
		(width 0.1143)
		(layer "In4.Cu")
		(net "P3E_CPU0_PE3_OCP_TXN<0>")
	)
	(segment
		(start 350.760792 -66.730118)
		(end 355.49459 -67.676522)
		(width 0.1143)
		(layer "In4.Cu")
		(net "P3E_CPU0_PE3_OCP_TXN<0>")
	)
	(segment
		(start 370.630958 -58.3565)
		(end 372.522242 -58.3565)
		(width 0.1143)
		(layer "In4.Cu")
		(net "P3E_CPU0_PE3_OCP_TXN<0>")
	)
	(segment
		(start 343.133934 -66.741548)
		(end 344.072718 -66.960242)
		(width 0.1143)
		(layer "In4.Cu")
		(net "P3E_CPU0_PE3_OCP_TXN<0>")
	)
	(segment
		(start 434.760878 -61.871606)
		(end 456.61199 -61.871606)
		(width 0.1143)
		(layer "In4.Cu")
		(net "P3E_CPU0_PE3_OCP_TXN<0>")
	)
	(segment
		(start 372.522242 -58.3565)
		(end 373.518938 -59.353196)
		(width 0.1143)
		(layer "In4.Cu")
		(net "P3E_CPU0_PE3_OCP_TXN<0>")
	)
	(segment
		(start 428.01921 -60.135008)
		(end 428.550324 -60.666122)
		(width 0.1143)
		(layer "In4.Cu")
		(net "P3E_CPU0_PE3_OCP_TXN<0>")
	)
	(segment
		(start 344.072718 -66.960242)
		(end 345.847416 -66.614802)
		(width 0.1143)
		(layer "In4.Cu")
		(net "P3E_CPU0_PE3_OCP_TXN<0>")
	)
	(segment
		(start 297.093894 -102.905052)
		(end 297.115738 -102.926896)
		(width 0.0889)
		(layer "In4.Cu")
		(net "P3E_CPU0_PE3_OCP_TXN<0>")
	)
	(segment
		(start 303.228502 -105.0671)
		(end 305.850036 -105.0671)
		(width 0.1143)
		(layer "In4.Cu")
		(net "P3E_CPU0_PE3_OCP_TXN<0>")
	)
	(segment
		(start 412.255462 -63.89624)
		(end 414.519618 -63.89624)
		(width 0.1143)
		(layer "In4.Cu")
		(net "P3E_CPU0_PE3_OCP_TXN<0>")
	)
	(segment
		(start 358.974644 -66.713354)
		(end 366.41786 -59.270138)
		(width 0.1143)
		(layer "In4.Cu")
		(net "P3E_CPU0_PE3_OCP_TXN<0>")
	)
	(segment
		(start 369.71732 -59.270138)
		(end 370.630958 -58.3565)
		(width 0.1143)
		(layer "In4.Cu")
		(net "P3E_CPU0_PE3_OCP_TXN<0>")
	)
	(segment
		(start 410.942282 -62.58306)
		(end 412.255462 -63.89624)
		(width 0.1143)
		(layer "In4.Cu")
		(net "P3E_CPU0_PE3_OCP_TXN<0>")
	)
	(segment
		(start 357.38562 -67.298316)
		(end 357.970582 -66.713354)
		(width 0.1143)
		(layer "In4.Cu")
		(net "P3E_CPU0_PE3_OCP_TXN<0>")
	)
	(segment
		(start 428.550324 -61.825632)
		(end 430.383442 -63.65875)
		(width 0.1143)
		(layer "In4.Cu")
		(net "P3E_CPU0_PE3_OCP_TXN<0>")
	)
	(segment
		(start 373.518938 -59.353196)
		(end 379.53696 -59.353196)
		(width 0.1143)
		(layer "In4.Cu")
		(net "P3E_CPU0_PE3_OCP_TXN<0>")
	)
	(segment
		(start 296.66184 -102.958138)
		(end 296.66184 -102.620064)
		(width 0.0889)
		(layer "In4.Cu")
		(net "P3E_CPU0_PE3_OCP_TXN<0>")
	)
	(segment
		(start 332.35519 -71.71817)
		(end 338.565998 -67.630294)
		(width 0.1143)
		(layer "In4.Cu")
		(net "P3E_CPU0_PE3_OCP_TXN<0>")
	)
	(segment
		(start 297.009312 -102.759256)
		(end 297.010836 -102.76205)
		(width 0.0889)
		(layer "In4.Cu")
		(net "P3E_CPU0_PE3_OCP_TXN<0>")
	)
	(segment
		(start 381.639826 -60.235846)
		(end 382.842008 -59.033664)
		(width 0.1143)
		(layer "In4.Cu")
		(net "P3E_CPU0_PE3_OCP_TXN<0>")
	)
	(segment
		(start 417.25342 -62.03569)
		(end 419.090602 -62.03569)
		(width 0.1143)
		(layer "In4.Cu")
		(net "P3E_CPU0_PE3_OCP_TXN<0>")
	)
	(segment
		(start 463.48904 -56.34482)
		(end 463.48904 -54.003194)
		(width 0.1143)
		(layer "In4.Cu")
		(net "P3E_CPU0_PE3_OCP_TXN<0>")
	)
	(segment
		(start 432.973734 -63.65875)
		(end 434.760878 -61.871606)
		(width 0.1143)
		(layer "In4.Cu")
		(net "P3E_CPU0_PE3_OCP_TXN<0>")
	)
	(segment
		(start 463.60334 -53.888894)
		(end 463.97799 -53.888894)
		(width 0.1143)
		(layer "In4.Cu")
		(net "P3E_CPU0_PE3_OCP_TXN<0>")
	)
	(segment
		(start 391.230358 -58.8518)
		(end 399.080228 -58.8518)
		(width 0.1143)
		(layer "In4.Cu")
		(net "P3E_CPU0_PE3_OCP_TXN<0>")
	)
	(segment
		(start 349.879158 -66.90233)
		(end 350.760792 -66.730118)
		(width 0.1143)
		(layer "In4.Cu")
		(net "P3E_CPU0_PE3_OCP_TXN<0>")
	)
	(segment
		(start 458.636878 -59.846718)
		(end 459.987142 -59.846718)
		(width 0.1143)
		(layer "In4.Cu")
		(net "P3E_CPU0_PE3_OCP_TXN<0>")
	)
	(segment
		(start 406.800812 -61.439806)
		(end 407.944066 -62.58306)
		(width 0.1143)
		(layer "In4.Cu")
		(net "P3E_CPU0_PE3_OCP_TXN<0>")
	)
	(segment
		(start 426.203364 -60.135008)
		(end 428.01921 -60.135008)
		(width 0.1143)
		(layer "In4.Cu")
		(net "P3E_CPU0_PE3_OCP_TXN<0>")
	)
	(segment
		(start 414.519618 -63.89624)
		(end 415.131758 -63.2841)
		(width 0.1143)
		(layer "In4.Cu")
		(net "P3E_CPU0_PE3_OCP_TXN<0>")
	)
	(segment
		(start 430.383442 -63.65875)
		(end 432.973734 -63.65875)
		(width 0.1143)
		(layer "In4.Cu")
		(net "P3E_CPU0_PE3_OCP_TXN<0>")
	)
	(segment
		(start 300.800516 -104.506268)
		(end 300.822614 -104.506268)
		(width 0.0889)
		(layer "In4.Cu")
		(net "P3E_CPU0_PE3_OCP_TXN<0>")
	)
	(segment
		(start 382.842008 -59.033664)
		(end 391.048494 -59.033664)
		(width 0.1143)
		(layer "In4.Cu")
		(net "P3E_CPU0_PE3_OCP_TXN<0>")
	)
	(segment
		(start 391.048494 -59.033664)
		(end 391.230358 -58.8518)
		(width 0.1143)
		(layer "In4.Cu")
		(net "P3E_CPU0_PE3_OCP_TXN<0>")
	)
	(segment
		(start 420.558722 -60.56757)
		(end 421.588184 -60.56757)
		(width 0.1143)
		(layer "In4.Cu")
		(net "P3E_CPU0_PE3_OCP_TXN<0>")
	)
	(segment
		(start 366.41786 -59.270138)
		(end 369.71732 -59.270138)
		(width 0.1143)
		(layer "In4.Cu")
		(net "P3E_CPU0_PE3_OCP_TXN<0>")
	)
	(segment
		(start 421.588184 -60.56757)
		(end 421.765222 -60.390532)
		(width 0.1143)
		(layer "In4.Cu")
		(net "P3E_CPU0_PE3_OCP_TXN<0>")
	)
	(arc
		(start 297.004994 -102.752398)
		(mid 297.006784 -102.755184)
		(end 297.00855 -102.757986)
		(width 0.0889)
		(layer "In4.Cu")
		(net "P3E_CPU0_PE3_OCP_TXN<0>")
	)
	(arc
		(start 296.719498 -102.562406)
		(mid 296.883675 -102.625223)
		(end 297.004994 -102.752398)
		(width 0.0889)
		(layer "In4.Cu")
		(net "P3E_CPU0_PE3_OCP_TXN<0>")
	)
	(segment
		(start 445.320166 -123.91517)
		(end 445.5922 -123.91517)
		(width 0.1143)
		(layer "F.Cu")
		(net "P3E_CPU0_PE3_OCP_RXP<9>")
	)
	(segment
		(start 445.09182 -123.686824)
		(end 445.320166 -123.91517)
		(width 0.1143)
		(layer "F.Cu")
		(net "P3E_CPU0_PE3_OCP_RXP<9>")
	)
	(segment
		(start 445.400938 -118.342918)
		(end 445.09182 -118.652036)
		(width 0.1143)
		(layer "F.Cu")
		(net "P3E_CPU0_PE3_OCP_RXP<9>")
	)
	(segment
		(start 445.09182 -118.652036)
		(end 445.09182 -123.686824)
		(width 0.1143)
		(layer "F.Cu")
		(net "P3E_CPU0_PE3_OCP_RXP<9>")
	)
	(segment
		(start 298.665646 -94.538038)
		(end 299.237146 -94.538038)
		(width 0.1143)
		(layer "F.Cu")
		(net "P3E_CPU0_PE3_OCP_RXP<9>")
	)
	(segment
		(start 445.400938 -116.993162)
		(end 445.400938 -118.342918)
		(width 0.1143)
		(layer "F.Cu")
		(net "P3E_CPU0_PE3_OCP_RXP<9>")
	)
	(via
		(at 299.237146 -94.538038)
		(size 0.508)
		(drill 0.254)
		(layers "F.Cu" "B.Cu")
		(net "P3E_CPU0_PE3_OCP_RXP<9>")
	)
	(via
		(at 445.5922 -123.91517)
		(size 0.508)
		(drill 0.254)
		(layers "F.Cu" "B.Cu")
		(net "P3E_CPU0_PE3_OCP_RXP<9>")
	)
	(segment
		(start 405.390858 -139.34821)
		(end 411.906212 -138.067288)
		(width 0.1143)
		(layer "In11.Cu")
		(net "P3E_CPU0_PE3_OCP_RXP<9>")
	)
	(segment
		(start 380.750318 -137.67054)
		(end 381.374142 -138.091164)
		(width 0.1143)
		(layer "In11.Cu")
		(net "P3E_CPU0_PE3_OCP_RXP<9>")
	)
	(segment
		(start 300.607476 -97.309686)
		(end 300.60265 -97.318322)
		(width 0.0889)
		(layer "In11.Cu")
		(net "P3E_CPU0_PE3_OCP_RXP<9>")
	)
	(segment
		(start 348.407736 -126.680722)
		(end 352.22561 -127.407416)
		(width 0.1143)
		(layer "In11.Cu")
		(net "P3E_CPU0_PE3_OCP_RXP<9>")
	)
	(segment
		(start 445.112648 -122.812302)
		(end 445.112648 -123.669552)
		(width 0.1143)
		(layer "In11.Cu")
		(net "P3E_CPU0_PE3_OCP_RXP<9>")
	)
	(segment
		(start 304.794412 -100.791772)
		(end 304.866548 -100.791772)
		(width 0.0889)
		(layer "In11.Cu")
		(net "P3E_CPU0_PE3_OCP_RXP<9>")
	)
	(segment
		(start 416.60445 -138.482324)
		(end 417.245038 -138.636502)
		(width 0.1143)
		(layer "In11.Cu")
		(net "P3E_CPU0_PE3_OCP_RXP<9>")
	)
	(segment
		(start 317.609728 -110.853728)
		(end 321.36461 -110.853728)
		(width 0.1143)
		(layer "In11.Cu")
		(net "P3E_CPU0_PE3_OCP_RXP<9>")
	)
	(segment
		(start 304.882042 -100.807266)
		(end 304.882042 -100.807012)
		(width 0.0889)
		(layer "In11.Cu")
		(net "P3E_CPU0_PE3_OCP_RXP<9>")
	)
	(segment
		(start 436.013352 -124.227336)
		(end 440.375294 -122.421396)
		(width 0.1143)
		(layer "In11.Cu")
		(net "P3E_CPU0_PE3_OCP_RXP<9>")
	)
	(segment
		(start 298.94403 -94.706948)
		(end 298.922948 -94.785688)
		(width 0.0889)
		(layer "In11.Cu")
		(net "P3E_CPU0_PE3_OCP_RXP<9>")
	)
	(segment
		(start 443.80785 -122.186954)
		(end 444.647828 -122.347228)
		(width 0.1143)
		(layer "In11.Cu")
		(net "P3E_CPU0_PE3_OCP_RXP<9>")
	)
	(segment
		(start 299.237146 -94.538038)
		(end 298.9834 -94.684088)
		(width 0.0889)
		(layer "In11.Cu")
		(net "P3E_CPU0_PE3_OCP_RXP<9>")
	)
	(segment
		(start 411.906212 -138.067288)
		(end 415.142172 -138.814048)
		(width 0.1143)
		(layer "In11.Cu")
		(net "P3E_CPU0_PE3_OCP_RXP<9>")
	)
	(segment
		(start 303.126394 -99.90582)
		(end 303.195482 -99.877118)
		(width 0.0889)
		(layer "In11.Cu")
		(net "P3E_CPU0_PE3_OCP_RXP<9>")
	)
	(segment
		(start 441.503562 -122.195844)
		(end 441.532264 -122.195844)
		(width 0.1143)
		(layer "In11.Cu")
		(net "P3E_CPU0_PE3_OCP_RXP<9>")
	)
	(segment
		(start 347.099382 -127.140208)
		(end 348.407736 -126.680722)
		(width 0.1143)
		(layer "In11.Cu")
		(net "P3E_CPU0_PE3_OCP_RXP<9>")
	)
	(segment
		(start 300.08449 -95.433134)
		(end 300.10862 -95.433134)
		(width 0.0889)
		(layer "In11.Cu")
		(net "P3E_CPU0_PE3_OCP_RXP<9>")
	)
	(segment
		(start 359.147364 -127.75057)
		(end 361.628944 -127.75057)
		(width 0.1143)
		(layer "In11.Cu")
		(net "P3E_CPU0_PE3_OCP_RXP<9>")
	)
	(segment
		(start 302.382428 -99.597718)
		(end 303.126394 -99.90582)
		(width 0.0889)
		(layer "In11.Cu")
		(net "P3E_CPU0_PE3_OCP_RXP<9>")
	)
	(segment
		(start 300.613826 -97.299018)
		(end 300.607476 -97.309686)
		(width 0.0889)
		(layer "In11.Cu")
		(net "P3E_CPU0_PE3_OCP_RXP<9>")
	)
	(segment
		(start 324.71614 -116.215922)
		(end 329.979782 -121.479564)
		(width 0.1143)
		(layer "In11.Cu")
		(net "P3E_CPU0_PE3_OCP_RXP<9>")
	)
	(segment
		(start 445.112648 -123.669552)
		(end 445.358266 -123.91517)
		(width 0.1143)
		(layer "In11.Cu")
		(net "P3E_CPU0_PE3_OCP_RXP<9>")
	)
	(segment
		(start 417.245038 -138.636502)
		(end 421.20312 -136.90981)
		(width 0.1143)
		(layer "In11.Cu")
		(net "P3E_CPU0_PE3_OCP_RXP<9>")
	)
	(segment
		(start 303.195482 -99.877118)
		(end 303.360074 -99.94519)
		(width 0.0889)
		(layer "In11.Cu")
		(net "P3E_CPU0_PE3_OCP_RXP<9>")
	)
	(segment
		(start 445.358266 -123.91517)
		(end 445.5922 -123.91517)
		(width 0.1143)
		(layer "In11.Cu")
		(net "P3E_CPU0_PE3_OCP_RXP<9>")
	)
	(segment
		(start 305.686206 -101.611176)
		(end 310.263794 -103.50754)
		(width 0.1143)
		(layer "In11.Cu")
		(net "P3E_CPU0_PE3_OCP_RXP<9>")
	)
	(segment
		(start 381.374142 -138.091164)
		(end 387.466332 -139.31011)
		(width 0.1143)
		(layer "In11.Cu")
		(net "P3E_CPU0_PE3_OCP_RXP<9>")
	)
	(segment
		(start 374.17375 -136.951974)
		(end 375.021856 -137.524236)
		(width 0.1143)
		(layer "In11.Cu")
		(net "P3E_CPU0_PE3_OCP_RXP<9>")
	)
	(segment
		(start 300.613826 -96.308418)
		(end 300.607476 -96.319086)
		(width 0.0889)
		(layer "In11.Cu")
		(net "P3E_CPU0_PE3_OCP_RXP<9>")
	)
	(segment
		(start 300.613826 -98.289618)
		(end 300.607476 -98.300286)
		(width 0.0889)
		(layer "In11.Cu")
		(net "P3E_CPU0_PE3_OCP_RXP<9>")
	)
	(segment
		(start 424.249088 -132.435854)
		(end 427.785276 -131.608576)
		(width 0.1143)
		(layer "In11.Cu")
		(net "P3E_CPU0_PE3_OCP_RXP<9>")
	)
	(segment
		(start 433.935886 -128.645158)
		(end 436.012844 -124.227844)
		(width 0.1143)
		(layer "In11.Cu")
		(net "P3E_CPU0_PE3_OCP_RXP<9>")
	)
	(segment
		(start 356.175056 -126.421388)
		(end 359.147364 -127.75057)
		(width 0.1143)
		(layer "In11.Cu")
		(net "P3E_CPU0_PE3_OCP_RXP<9>")
	)
	(segment
		(start 329.979782 -121.479564)
		(end 331.446886 -121.479564)
		(width 0.1143)
		(layer "In11.Cu")
		(net "P3E_CPU0_PE3_OCP_RXP<9>")
	)
	(segment
		(start 370.194332 -133.40842)
		(end 372.11762 -133.40842)
		(width 0.1143)
		(layer "In11.Cu")
		(net "P3E_CPU0_PE3_OCP_RXP<9>")
	)
	(segment
		(start 333.848456 -123.880372)
		(end 339.313266 -123.880372)
		(width 0.1143)
		(layer "In11.Cu")
		(net "P3E_CPU0_PE3_OCP_RXP<9>")
	)
	(segment
		(start 300.607476 -98.300286)
		(end 300.60265 -98.308922)
		(width 0.0889)
		(layer "In11.Cu")
		(net "P3E_CPU0_PE3_OCP_RXP<9>")
	)
	(segment
		(start 361.628944 -127.75057)
		(end 366.592358 -129.806192)
		(width 0.1143)
		(layer "In11.Cu")
		(net "P3E_CPU0_PE3_OCP_RXP<9>")
	)
	(segment
		(start 300.9392 -98.900234)
		(end 300.971966 -98.900234)
		(width 0.0889)
		(layer "In11.Cu")
		(net "P3E_CPU0_PE3_OCP_RXP<9>")
	)
	(segment
		(start 440.375294 -122.421396)
		(end 441.503562 -122.195844)
		(width 0.1143)
		(layer "In11.Cu")
		(net "P3E_CPU0_PE3_OCP_RXP<9>")
	)
	(segment
		(start 373.468392 -135.90651)
		(end 374.17375 -136.951974)
		(width 0.1143)
		(layer "In11.Cu")
		(net "P3E_CPU0_PE3_OCP_RXP<9>")
	)
	(segment
		(start 303.388776 -100.014532)
		(end 304.461672 -100.459032)
		(width 0.0889)
		(layer "In11.Cu")
		(net "P3E_CPU0_PE3_OCP_RXP<9>")
	)
	(segment
		(start 301.798228 -99.395788)
		(end 302.180498 -99.395788)
		(width 0.0889)
		(layer "In11.Cu")
		(net "P3E_CPU0_PE3_OCP_RXP<9>")
	)
	(segment
		(start 378.809504 -137.29335)
		(end 380.750318 -137.67054)
		(width 0.1143)
		(layer "In11.Cu")
		(net "P3E_CPU0_PE3_OCP_RXP<9>")
	)
	(segment
		(start 298.9834 -94.684088)
		(end 298.958 -94.69882)
		(width 0.0889)
		(layer "In11.Cu")
		(net "P3E_CPU0_PE3_OCP_RXP<9>")
	)
	(segment
		(start 344.423746 -124.921518)
		(end 345.657932 -126.750572)
		(width 0.1143)
		(layer "In11.Cu")
		(net "P3E_CPU0_PE3_OCP_RXP<9>")
	)
	(segment
		(start 321.36461 -110.853728)
		(end 324.71614 -114.205258)
		(width 0.1143)
		(layer "In11.Cu")
		(net "P3E_CPU0_PE3_OCP_RXP<9>")
	)
	(segment
		(start 387.466332 -139.31011)
		(end 390.53643 -139.31011)
		(width 0.1143)
		(layer "In11.Cu")
		(net "P3E_CPU0_PE3_OCP_RXP<9>")
	)
	(segment
		(start 300.607476 -96.319086)
		(end 300.60265 -96.327722)
		(width 0.0889)
		(layer "In11.Cu")
		(net "P3E_CPU0_PE3_OCP_RXP<9>")
	)
	(segment
		(start 302.180498 -99.395788)
		(end 302.382428 -99.597718)
		(width 0.0889)
		(layer "In11.Cu")
		(net "P3E_CPU0_PE3_OCP_RXP<9>")
	)
	(segment
		(start 436.012844 -124.227844)
		(end 436.013352 -124.22759)
		(width 0.1143)
		(layer "In11.Cu")
		(net "P3E_CPU0_PE3_OCP_RXP<9>")
	)
	(segment
		(start 352.22561 -127.407416)
		(end 356.175056 -126.421388)
		(width 0.1143)
		(layer "In11.Cu")
		(net "P3E_CPU0_PE3_OCP_RXP<9>")
	)
	(segment
		(start 444.647828 -122.347228)
		(end 445.112648 -122.812302)
		(width 0.1143)
		(layer "In11.Cu")
		(net "P3E_CPU0_PE3_OCP_RXP<9>")
	)
	(segment
		(start 324.71614 -114.205258)
		(end 324.71614 -116.215922)
		(width 0.1143)
		(layer "In11.Cu")
		(net "P3E_CPU0_PE3_OCP_RXP<9>")
	)
	(segment
		(start 441.532264 -122.195844)
		(end 443.80785 -122.186954)
		(width 0.1143)
		(layer "In11.Cu")
		(net "P3E_CPU0_PE3_OCP_RXP<9>")
	)
	(segment
		(start 427.785276 -131.608576)
		(end 430.871884 -129.521966)
		(width 0.1143)
		(layer "In11.Cu")
		(net "P3E_CPU0_PE3_OCP_RXP<9>")
	)
	(segment
		(start 423.42943 -132.961888)
		(end 424.249088 -132.435854)
		(width 0.1143)
		(layer "In11.Cu")
		(net "P3E_CPU0_PE3_OCP_RXP<9>")
	)
	(segment
		(start 372.11762 -133.40842)
		(end 373.468392 -134.759192)
		(width 0.1143)
		(layer "In11.Cu")
		(net "P3E_CPU0_PE3_OCP_RXP<9>")
	)
	(segment
		(start 421.20312 -136.90981)
		(end 423.42943 -132.961888)
		(width 0.1143)
		(layer "In11.Cu")
		(net "P3E_CPU0_PE3_OCP_RXP<9>")
	)
	(segment
		(start 376.321066 -137.776712)
		(end 378.809504 -137.29335)
		(width 0.1143)
		(layer "In11.Cu")
		(net "P3E_CPU0_PE3_OCP_RXP<9>")
	)
	(segment
		(start 339.313266 -123.880372)
		(end 344.423746 -124.921518)
		(width 0.1143)
		(layer "In11.Cu")
		(net "P3E_CPU0_PE3_OCP_RXP<9>")
	)
	(segment
		(start 430.871884 -129.521966)
		(end 433.935886 -128.645158)
		(width 0.1143)
		(layer "In11.Cu")
		(net "P3E_CPU0_PE3_OCP_RXP<9>")
	)
	(segment
		(start 415.142172 -138.814048)
		(end 416.60445 -138.482324)
		(width 0.1143)
		(layer "In11.Cu")
		(net "P3E_CPU0_PE3_OCP_RXP<9>")
	)
	(segment
		(start 303.360074 -99.94519)
		(end 303.388776 -100.014532)
		(width 0.0889)
		(layer "In11.Cu")
		(net "P3E_CPU0_PE3_OCP_RXP<9>")
	)
	(segment
		(start 436.013352 -124.22759)
		(end 436.013352 -124.227336)
		(width 0.1143)
		(layer "In11.Cu")
		(net "P3E_CPU0_PE3_OCP_RXP<9>")
	)
	(segment
		(start 345.657932 -126.750572)
		(end 345.881452 -126.901702)
		(width 0.1143)
		(layer "In11.Cu")
		(net "P3E_CPU0_PE3_OCP_RXP<9>")
	)
	(segment
		(start 373.468392 -134.759192)
		(end 373.468392 -135.90651)
		(width 0.1143)
		(layer "In11.Cu")
		(net "P3E_CPU0_PE3_OCP_RXP<9>")
	)
	(segment
		(start 366.592358 -129.806192)
		(end 370.194332 -133.40842)
		(width 0.1143)
		(layer "In11.Cu")
		(net "P3E_CPU0_PE3_OCP_RXP<9>")
	)
	(segment
		(start 298.958 -94.69882)
		(end 298.94403 -94.706948)
		(width 0.0889)
		(layer "In11.Cu")
		(net "P3E_CPU0_PE3_OCP_RXP<9>")
	)
	(segment
		(start 304.461672 -100.459032)
		(end 304.794412 -100.791772)
		(width 0.0889)
		(layer "In11.Cu")
		(net "P3E_CPU0_PE3_OCP_RXP<9>")
	)
	(segment
		(start 390.53643 -139.31011)
		(end 394.273786 -140.328904)
		(width 0.1143)
		(layer "In11.Cu")
		(net "P3E_CPU0_PE3_OCP_RXP<9>")
	)
	(segment
		(start 345.881452 -126.901702)
		(end 347.099382 -127.140208)
		(width 0.1143)
		(layer "In11.Cu")
		(net "P3E_CPU0_PE3_OCP_RXP<9>")
	)
	(segment
		(start 304.882042 -100.807012)
		(end 305.686206 -101.611176)
		(width 0.1143)
		(layer "In11.Cu")
		(net "P3E_CPU0_PE3_OCP_RXP<9>")
	)
	(segment
		(start 375.021856 -137.524236)
		(end 376.321066 -137.776712)
		(width 0.1143)
		(layer "In11.Cu")
		(net "P3E_CPU0_PE3_OCP_RXP<9>")
	)
	(segment
		(start 331.446886 -121.479564)
		(end 333.848456 -123.880372)
		(width 0.1143)
		(layer "In11.Cu")
		(net "P3E_CPU0_PE3_OCP_RXP<9>")
	)
	(segment
		(start 394.273786 -140.328904)
		(end 399.639028 -139.34821)
		(width 0.1143)
		(layer "In11.Cu")
		(net "P3E_CPU0_PE3_OCP_RXP<9>")
	)
	(segment
		(start 299.219112 -94.937834)
		(end 299.258736 -94.937834)
		(width 0.0889)
		(layer "In11.Cu")
		(net "P3E_CPU0_PE3_OCP_RXP<9>")
	)
	(segment
		(start 310.263794 -103.50754)
		(end 317.609728 -110.853728)
		(width 0.1143)
		(layer "In11.Cu")
		(net "P3E_CPU0_PE3_OCP_RXP<9>")
	)
	(segment
		(start 304.866548 -100.791772)
		(end 304.882042 -100.807266)
		(width 0.0889)
		(layer "In11.Cu")
		(net "P3E_CPU0_PE3_OCP_RXP<9>")
	)
	(segment
		(start 399.639028 -139.34821)
		(end 405.390858 -139.34821)
		(width 0.1143)
		(layer "In11.Cu")
		(net "P3E_CPU0_PE3_OCP_RXP<9>")
	)
	(arc
		(start 300.60265 -96.327722)
		(mid 300.553895 -96.524074)
		(end 300.607476 -96.719136)
		(width 0.0889)
		(layer "In11.Cu")
		(net "P3E_CPU0_PE3_OCP_RXP<9>")
	)
	(arc
		(start 300.971966 -98.900234)
		(mid 301.25739 -98.983701)
		(end 301.465996 -99.195636)
		(width 0.0889)
		(layer "In11.Cu")
		(net "P3E_CPU0_PE3_OCP_RXP<9>")
	)
	(arc
		(start 299.258736 -94.937834)
		(mid 299.541953 -95.022115)
		(end 299.748956 -95.232982)
		(width 0.0889)
		(layer "In11.Cu")
		(net "P3E_CPU0_PE3_OCP_RXP<9>")
	)
	(arc
		(start 301.465996 -99.195636)
		(mid 301.606264 -99.338592)
		(end 301.798228 -99.395788)
		(width 0.0889)
		(layer "In11.Cu")
		(net "P3E_CPU0_PE3_OCP_RXP<9>")
	)
	(arc
		(start 299.748956 -95.232982)
		(mid 299.890639 -95.376786)
		(end 300.08449 -95.433134)
		(width 0.0889)
		(layer "In11.Cu")
		(net "P3E_CPU0_PE3_OCP_RXP<9>")
	)
	(arc
		(start 298.922948 -94.785688)
		(mid 299.054451 -94.894044)
		(end 299.219112 -94.937834)
		(width 0.0889)
		(layer "In11.Cu")
		(net "P3E_CPU0_PE3_OCP_RXP<9>")
	)
	(arc
		(start 300.607476 -97.709736)
		(mid 300.686698 -97.998854)
		(end 300.613826 -98.289618)
		(width 0.0889)
		(layer "In11.Cu")
		(net "P3E_CPU0_PE3_OCP_RXP<9>")
	)
	(arc
		(start 300.60265 -98.308922)
		(mid 300.606397 -98.698178)
		(end 300.9392 -98.900234)
		(width 0.0889)
		(layer "In11.Cu")
		(net "P3E_CPU0_PE3_OCP_RXP<9>")
	)
	(arc
		(start 300.60265 -97.318322)
		(mid 300.553895 -97.514674)
		(end 300.607476 -97.709736)
		(width 0.0889)
		(layer "In11.Cu")
		(net "P3E_CPU0_PE3_OCP_RXP<9>")
	)
	(arc
		(start 300.607476 -96.719136)
		(mid 300.686698 -97.008254)
		(end 300.613826 -97.299018)
		(width 0.0889)
		(layer "In11.Cu")
		(net "P3E_CPU0_PE3_OCP_RXP<9>")
	)
	(arc
		(start 300.10862 -95.433134)
		(mid 300.607501 -95.728571)
		(end 300.613826 -96.308418)
		(width 0.0889)
		(layer "In11.Cu")
		(net "P3E_CPU0_PE3_OCP_RXP<9>")
	)
	(segment
		(start 441.92063 -118.623334)
		(end 441.92063 -123.76785)
		(width 0.1143)
		(layer "F.Cu")
		(net "P3E_CPU0_PE3_OCP_RXP<8>")
	)
	(segment
		(start 442.200792 -116.993162)
		(end 442.200792 -118.343172)
		(width 0.1143)
		(layer "F.Cu")
		(net "P3E_CPU0_PE3_OCP_RXP<8>")
	)
	(segment
		(start 441.92063 -123.76785)
		(end 442.04255 -123.88977)
		(width 0.1143)
		(layer "F.Cu")
		(net "P3E_CPU0_PE3_OCP_RXP<8>")
	)
	(segment
		(start 442.04255 -123.88977)
		(end 442.4426 -123.88977)
		(width 0.1143)
		(layer "F.Cu")
		(net "P3E_CPU0_PE3_OCP_RXP<8>")
	)
	(segment
		(start 296.948606 -95.528384)
		(end 297.520106 -95.528384)
		(width 0.1143)
		(layer "F.Cu")
		(net "P3E_CPU0_PE3_OCP_RXP<8>")
	)
	(segment
		(start 442.200792 -118.343172)
		(end 441.92063 -118.623334)
		(width 0.1143)
		(layer "F.Cu")
		(net "P3E_CPU0_PE3_OCP_RXP<8>")
	)
	(via
		(at 442.4426 -123.88977)
		(size 0.508)
		(drill 0.254)
		(layers "F.Cu" "B.Cu")
		(net "P3E_CPU0_PE3_OCP_RXP<8>")
	)
	(via
		(at 297.520106 -95.528384)
		(size 0.508)
		(drill 0.254)
		(layers "F.Cu" "B.Cu")
		(net "P3E_CPU0_PE3_OCP_RXP<8>")
	)
	(segment
		(start 300.08449 -99.395788)
		(end 300.117256 -99.395788)
		(width 0.0889)
		(layer "In11.Cu")
		(net "P3E_CPU0_PE3_OCP_RXP<8>")
	)
	(segment
		(start 366.209072 -130.369818)
		(end 369.882674 -134.04342)
		(width 0.1143)
		(layer "In11.Cu")
		(net "P3E_CPU0_PE3_OCP_RXP<8>")
	)
	(segment
		(start 299.74413 -98.1964)
		(end 299.748956 -98.205036)
		(width 0.0889)
		(layer "In11.Cu")
		(net "P3E_CPU0_PE3_OCP_RXP<8>")
	)
	(segment
		(start 309.720488 -104.151684)
		(end 317.141098 -111.572294)
		(width 0.1143)
		(layer "In11.Cu")
		(net "P3E_CPU0_PE3_OCP_RXP<8>")
	)
	(segment
		(start 415.141664 -139.467082)
		(end 416.598862 -139.136374)
		(width 0.1143)
		(layer "In11.Cu")
		(net "P3E_CPU0_PE3_OCP_RXP<8>")
	)
	(segment
		(start 301.794672 -100.386134)
		(end 302.17618 -100.386134)
		(width 0.0889)
		(layer "In11.Cu")
		(net "P3E_CPU0_PE3_OCP_RXP<8>")
	)
	(segment
		(start 417.303458 -139.305284)
		(end 423.017696 -136.81329)
		(width 0.1143)
		(layer "In11.Cu")
		(net "P3E_CPU0_PE3_OCP_RXP<8>")
	)
	(segment
		(start 379.230382 -139.598146)
		(end 381.783844 -139.078462)
		(width 0.1143)
		(layer "In11.Cu")
		(net "P3E_CPU0_PE3_OCP_RXP<8>")
	)
	(segment
		(start 431.77206 -133.540246)
		(end 432.383946 -133.072886)
		(width 0.1143)
		(layer "In11.Cu")
		(net "P3E_CPU0_PE3_OCP_RXP<8>")
	)
	(segment
		(start 425.88053 -135.399018)
		(end 427.338998 -134.42696)
		(width 0.1143)
		(layer "In11.Cu")
		(net "P3E_CPU0_PE3_OCP_RXP<8>")
	)
	(segment
		(start 358.913938 -128.387856)
		(end 361.422696 -128.387856)
		(width 0.1143)
		(layer "In11.Cu")
		(net "P3E_CPU0_PE3_OCP_RXP<8>")
	)
	(segment
		(start 305.270154 -102.9335)
		(end 305.562 -102.9335)
		(width 0.0889)
		(layer "In11.Cu")
		(net "P3E_CPU0_PE3_OCP_RXP<8>")
	)
	(segment
		(start 300.9392 -99.890834)
		(end 300.96714 -99.890834)
		(width 0.0889)
		(layer "In11.Cu")
		(net "P3E_CPU0_PE3_OCP_RXP<8>")
	)
	(segment
		(start 344.931492 -127.079502)
		(end 345.537028 -127.48768)
		(width 0.1143)
		(layer "In11.Cu")
		(net "P3E_CPU0_PE3_OCP_RXP<8>")
	)
	(segment
		(start 390.451086 -139.94511)
		(end 394.2461 -140.979906)
		(width 0.1143)
		(layer "In11.Cu")
		(net "P3E_CPU0_PE3_OCP_RXP<8>")
	)
	(segment
		(start 333.502 -124.515372)
		(end 339.150706 -124.515372)
		(width 0.1143)
		(layer "In11.Cu")
		(net "P3E_CPU0_PE3_OCP_RXP<8>")
	)
	(segment
		(start 348.365064 -127.378206)
		(end 352.200464 -128.108456)
		(width 0.1143)
		(layer "In11.Cu")
		(net "P3E_CPU0_PE3_OCP_RXP<8>")
	)
	(segment
		(start 329.744578 -122.14352)
		(end 331.130148 -122.14352)
		(width 0.1143)
		(layer "In11.Cu")
		(net "P3E_CPU0_PE3_OCP_RXP<8>")
	)
	(segment
		(start 319.173352 -111.572294)
		(end 329.744578 -122.14352)
		(width 0.1143)
		(layer "In11.Cu")
		(net "P3E_CPU0_PE3_OCP_RXP<8>")
	)
	(segment
		(start 442.06795 -123.88977)
		(end 442.4426 -123.88977)
		(width 0.1143)
		(layer "In11.Cu")
		(net "P3E_CPU0_PE3_OCP_RXP<8>")
	)
	(segment
		(start 399.687796 -139.984988)
		(end 405.451564 -139.984988)
		(width 0.1143)
		(layer "In11.Cu")
		(net "P3E_CPU0_PE3_OCP_RXP<8>")
	)
	(segment
		(start 343.849452 -125.475238)
		(end 344.931492 -127.079502)
		(width 0.1143)
		(layer "In11.Cu")
		(net "P3E_CPU0_PE3_OCP_RXP<8>")
	)
	(segment
		(start 305.6128 -102.8827)
		(end 305.634898 -102.8827)
		(width 0.0889)
		(layer "In11.Cu")
		(net "P3E_CPU0_PE3_OCP_RXP<8>")
	)
	(segment
		(start 303.108868 -100.772214)
		(end 305.270154 -102.9335)
		(width 0.0889)
		(layer "In11.Cu")
		(net "P3E_CPU0_PE3_OCP_RXP<8>")
	)
	(segment
		(start 299.74413 -97.2058)
		(end 299.748956 -97.214436)
		(width 0.0889)
		(layer "In11.Cu")
		(net "P3E_CPU0_PE3_OCP_RXP<8>")
	)
	(segment
		(start 372.7196 -137.235692)
		(end 373.147336 -137.882122)
		(width 0.1143)
		(layer "In11.Cu")
		(net "P3E_CPU0_PE3_OCP_RXP<8>")
	)
	(segment
		(start 373.147336 -137.882122)
		(end 374.19534 -138.574272)
		(width 0.1143)
		(layer "In11.Cu")
		(net "P3E_CPU0_PE3_OCP_RXP<8>")
	)
	(segment
		(start 297.813222 -95.697548)
		(end 297.90263 -95.673418)
		(width 0.0889)
		(layer "In11.Cu")
		(net "P3E_CPU0_PE3_OCP_RXP<8>")
	)
	(segment
		(start 441.579 -123.0122)
		(end 441.95365 -123.38685)
		(width 0.1143)
		(layer "In11.Cu")
		(net "P3E_CPU0_PE3_OCP_RXP<8>")
	)
	(segment
		(start 417.303204 -139.305284)
		(end 417.303458 -139.305284)
		(width 0.1143)
		(layer "In11.Cu")
		(net "P3E_CPU0_PE3_OCP_RXP<8>")
	)
	(segment
		(start 381.783844 -139.078462)
		(end 386.043932 -139.94511)
		(width 0.1143)
		(layer "In11.Cu")
		(net "P3E_CPU0_PE3_OCP_RXP<8>")
	)
	(segment
		(start 427.338998 -134.42696)
		(end 431.77206 -133.540246)
		(width 0.1143)
		(layer "In11.Cu")
		(net "P3E_CPU0_PE3_OCP_RXP<8>")
	)
	(segment
		(start 305.634898 -102.8827)
		(end 306.655724 -102.8827)
		(width 0.1143)
		(layer "In11.Cu")
		(net "P3E_CPU0_PE3_OCP_RXP<8>")
	)
	(segment
		(start 386.043932 -139.94511)
		(end 390.451086 -139.94511)
		(width 0.1143)
		(layer "In11.Cu")
		(net "P3E_CPU0_PE3_OCP_RXP<8>")
	)
	(segment
		(start 299.22216 -95.928434)
		(end 299.254926 -95.928434)
		(width 0.0889)
		(layer "In11.Cu")
		(net "P3E_CPU0_PE3_OCP_RXP<8>")
	)
	(segment
		(start 345.537028 -127.48768)
		(end 347.152214 -127.803148)
		(width 0.1143)
		(layer "In11.Cu")
		(net "P3E_CPU0_PE3_OCP_RXP<8>")
	)
	(segment
		(start 441.95365 -123.38685)
		(end 441.95365 -123.77547)
		(width 0.1143)
		(layer "In11.Cu")
		(net "P3E_CPU0_PE3_OCP_RXP<8>")
	)
	(segment
		(start 433.651152 -129.700274)
		(end 434.355748 -129.248408)
		(width 0.1143)
		(layer "In11.Cu")
		(net "P3E_CPU0_PE3_OCP_RXP<8>")
	)
	(segment
		(start 301.411132 -100.090986)
		(end 301.465996 -100.186236)
		(width 0.0889)
		(layer "In11.Cu")
		(net "P3E_CPU0_PE3_OCP_RXP<8>")
	)
	(segment
		(start 331.130148 -122.14352)
		(end 333.502 -124.515372)
		(width 0.1143)
		(layer "In11.Cu")
		(net "P3E_CPU0_PE3_OCP_RXP<8>")
	)
	(segment
		(start 306.655724 -102.8827)
		(end 309.720488 -104.151684)
		(width 0.1143)
		(layer "In11.Cu")
		(net "P3E_CPU0_PE3_OCP_RXP<8>")
	)
	(segment
		(start 411.89656 -138.717782)
		(end 415.141664 -139.467082)
		(width 0.1143)
		(layer "In11.Cu")
		(net "P3E_CPU0_PE3_OCP_RXP<8>")
	)
	(segment
		(start 441.95365 -123.77547)
		(end 442.06795 -123.88977)
		(width 0.1143)
		(layer "In11.Cu")
		(net "P3E_CPU0_PE3_OCP_RXP<8>")
	)
	(segment
		(start 299.748956 -98.205036)
		(end 299.755306 -98.215704)
		(width 0.0889)
		(layer "In11.Cu")
		(net "P3E_CPU0_PE3_OCP_RXP<8>")
	)
	(segment
		(start 371.794278 -134.04342)
		(end 372.7196 -134.968742)
		(width 0.1143)
		(layer "In11.Cu")
		(net "P3E_CPU0_PE3_OCP_RXP<8>")
	)
	(segment
		(start 394.2461 -140.979906)
		(end 399.687796 -139.984988)
		(width 0.1143)
		(layer "In11.Cu")
		(net "P3E_CPU0_PE3_OCP_RXP<8>")
	)
	(segment
		(start 339.150706 -124.515372)
		(end 343.849452 -125.475238)
		(width 0.1143)
		(layer "In11.Cu")
		(net "P3E_CPU0_PE3_OCP_RXP<8>")
	)
	(segment
		(start 416.598862 -139.136374)
		(end 416.599116 -139.13612)
		(width 0.1143)
		(layer "In11.Cu")
		(net "P3E_CPU0_PE3_OCP_RXP<8>")
	)
	(segment
		(start 317.141098 -111.572294)
		(end 319.173352 -111.572294)
		(width 0.1143)
		(layer "In11.Cu")
		(net "P3E_CPU0_PE3_OCP_RXP<8>")
	)
	(segment
		(start 347.152214 -127.803148)
		(end 348.365064 -127.378206)
		(width 0.1143)
		(layer "In11.Cu")
		(net "P3E_CPU0_PE3_OCP_RXP<8>")
	)
	(segment
		(start 299.748956 -97.214436)
		(end 299.755306 -97.225104)
		(width 0.0889)
		(layer "In11.Cu")
		(net "P3E_CPU0_PE3_OCP_RXP<8>")
	)
	(segment
		(start 352.200464 -128.108456)
		(end 356.107238 -127.133096)
		(width 0.1143)
		(layer "In11.Cu")
		(net "P3E_CPU0_PE3_OCP_RXP<8>")
	)
	(segment
		(start 372.7196 -134.968742)
		(end 372.7196 -137.235692)
		(width 0.1143)
		(layer "In11.Cu")
		(net "P3E_CPU0_PE3_OCP_RXP<8>")
	)
	(segment
		(start 416.59937 -139.13612)
		(end 417.303204 -139.30503)
		(width 0.1143)
		(layer "In11.Cu")
		(net "P3E_CPU0_PE3_OCP_RXP<8>")
	)
	(segment
		(start 434.355748 -129.248408)
		(end 436.470298 -124.751338)
		(width 0.1143)
		(layer "In11.Cu")
		(net "P3E_CPU0_PE3_OCP_RXP<8>")
	)
	(segment
		(start 424.822874 -135.609838)
		(end 425.88053 -135.399018)
		(width 0.1143)
		(layer "In11.Cu")
		(net "P3E_CPU0_PE3_OCP_RXP<8>")
	)
	(segment
		(start 416.599116 -139.13612)
		(end 416.59937 -139.13612)
		(width 0.1143)
		(layer "In11.Cu")
		(net "P3E_CPU0_PE3_OCP_RXP<8>")
	)
	(segment
		(start 432.383946 -133.072886)
		(end 433.651152 -129.700274)
		(width 0.1143)
		(layer "In11.Cu")
		(net "P3E_CPU0_PE3_OCP_RXP<8>")
	)
	(segment
		(start 361.422696 -128.387856)
		(end 366.209072 -130.369818)
		(width 0.1143)
		(layer "In11.Cu")
		(net "P3E_CPU0_PE3_OCP_RXP<8>")
	)
	(segment
		(start 423.017696 -136.81329)
		(end 424.822874 -135.609838)
		(width 0.1143)
		(layer "In11.Cu")
		(net "P3E_CPU0_PE3_OCP_RXP<8>")
	)
	(segment
		(start 440.666378 -123.0122)
		(end 441.579 -123.0122)
		(width 0.1143)
		(layer "In11.Cu")
		(net "P3E_CPU0_PE3_OCP_RXP<8>")
	)
	(segment
		(start 374.19534 -138.574272)
		(end 379.230382 -139.598146)
		(width 0.1143)
		(layer "In11.Cu")
		(net "P3E_CPU0_PE3_OCP_RXP<8>")
	)
	(segment
		(start 301.39767 -100.090986)
		(end 301.411132 -100.090986)
		(width 0.0889)
		(layer "In11.Cu")
		(net "P3E_CPU0_PE3_OCP_RXP<8>")
	)
	(segment
		(start 417.303204 -139.30503)
		(end 417.303204 -139.305284)
		(width 0.1143)
		(layer "In11.Cu")
		(net "P3E_CPU0_PE3_OCP_RXP<8>")
	)
	(segment
		(start 356.107238 -127.133096)
		(end 358.913938 -128.387856)
		(width 0.1143)
		(layer "In11.Cu")
		(net "P3E_CPU0_PE3_OCP_RXP<8>")
	)
	(segment
		(start 436.470298 -124.751338)
		(end 440.666378 -123.0122)
		(width 0.1143)
		(layer "In11.Cu")
		(net "P3E_CPU0_PE3_OCP_RXP<8>")
	)
	(segment
		(start 305.562 -102.9335)
		(end 305.6128 -102.8827)
		(width 0.0889)
		(layer "In11.Cu")
		(net "P3E_CPU0_PE3_OCP_RXP<8>")
	)
	(segment
		(start 297.520106 -95.528384)
		(end 297.813222 -95.697548)
		(width 0.0889)
		(layer "In11.Cu")
		(net "P3E_CPU0_PE3_OCP_RXP<8>")
	)
	(segment
		(start 405.451564 -139.984988)
		(end 411.89656 -138.717782)
		(width 0.1143)
		(layer "In11.Cu")
		(net "P3E_CPU0_PE3_OCP_RXP<8>")
	)
	(segment
		(start 369.882674 -134.04342)
		(end 371.794278 -134.04342)
		(width 0.1143)
		(layer "In11.Cu")
		(net "P3E_CPU0_PE3_OCP_RXP<8>")
	)
	(arc
		(start 302.17618 -100.386134)
		(mid 302.680919 -100.486421)
		(end 303.108868 -100.772214)
		(width 0.0889)
		(layer "In11.Cu")
		(net "P3E_CPU0_PE3_OCP_RXP<8>")
	)
	(arc
		(start 300.117256 -99.395788)
		(mid 300.400473 -99.480069)
		(end 300.607476 -99.690936)
		(width 0.0889)
		(layer "In11.Cu")
		(net "P3E_CPU0_PE3_OCP_RXP<8>")
	)
	(arc
		(start 299.755306 -97.225104)
		(mid 299.828104 -97.515867)
		(end 299.748956 -97.804986)
		(width 0.0889)
		(layer "In11.Cu")
		(net "P3E_CPU0_PE3_OCP_RXP<8>")
	)
	(arc
		(start 300.607476 -99.690936)
		(mid 300.747555 -99.833672)
		(end 300.9392 -99.890834)
		(width 0.0889)
		(layer "In11.Cu")
		(net "P3E_CPU0_PE3_OCP_RXP<8>")
	)
	(arc
		(start 299.254926 -95.928434)
		(mid 299.753177 -96.231274)
		(end 299.748956 -96.814386)
		(width 0.0889)
		(layer "In11.Cu")
		(net "P3E_CPU0_PE3_OCP_RXP<8>")
	)
	(arc
		(start 301.465996 -100.186236)
		(mid 301.60474 -100.328269)
		(end 301.794672 -100.386134)
		(width 0.0889)
		(layer "In11.Cu")
		(net "P3E_CPU0_PE3_OCP_RXP<8>")
	)
	(arc
		(start 297.90263 -95.673418)
		(mid 298.102175 -95.501614)
		(end 298.356528 -95.433388)
		(width 0.0889)
		(layer "In11.Cu")
		(net "P3E_CPU0_PE3_OCP_RXP<8>")
	)
	(arc
		(start 298.890436 -95.728536)
		(mid 299.030515 -95.871272)
		(end 299.22216 -95.928434)
		(width 0.0889)
		(layer "In11.Cu")
		(net "P3E_CPU0_PE3_OCP_RXP<8>")
	)
	(arc
		(start 300.96714 -99.890834)
		(mid 301.20337 -99.945798)
		(end 301.39767 -100.090986)
		(width 0.0889)
		(layer "In11.Cu")
		(net "P3E_CPU0_PE3_OCP_RXP<8>")
	)
	(arc
		(start 299.748956 -98.795586)
		(mid 299.746208 -99.191053)
		(end 300.08449 -99.395788)
		(width 0.0889)
		(layer "In11.Cu")
		(net "P3E_CPU0_PE3_OCP_RXP<8>")
	)
	(arc
		(start 298.356528 -95.433388)
		(mid 298.378626 -95.432975)
		(end 298.400724 -95.433388)
		(width 0.0889)
		(layer "In11.Cu")
		(net "P3E_CPU0_PE3_OCP_RXP<8>")
	)
	(arc
		(start 299.748956 -96.814386)
		(mid 299.695486 -97.009449)
		(end 299.74413 -97.2058)
		(width 0.0889)
		(layer "In11.Cu")
		(net "P3E_CPU0_PE3_OCP_RXP<8>")
	)
	(arc
		(start 299.748956 -97.804986)
		(mid 299.695486 -98.000049)
		(end 299.74413 -98.1964)
		(width 0.0889)
		(layer "In11.Cu")
		(net "P3E_CPU0_PE3_OCP_RXP<8>")
	)
	(arc
		(start 298.400724 -95.433388)
		(mid 298.683693 -95.517762)
		(end 298.890436 -95.728536)
		(width 0.0889)
		(layer "In11.Cu")
		(net "P3E_CPU0_PE3_OCP_RXP<8>")
	)
	(arc
		(start 299.755306 -98.215704)
		(mid 299.828104 -98.506467)
		(end 299.748956 -98.795586)
		(width 0.0889)
		(layer "In11.Cu")
		(net "P3E_CPU0_PE3_OCP_RXP<8>")
	)
	(segment
		(start 296.09034 -95.033084)
		(end 296.66184 -95.033084)
		(width 0.1143)
		(layer "F.Cu")
		(net "P3E_CPU0_PE3_OCP_RXP<7>")
	)
	(segment
		(start 438.707022 -44.83735)
		(end 439.040016 -44.83735)
		(width 0.1143)
		(layer "F.Cu")
		(net "P3E_CPU0_PE3_OCP_RXP<7>")
	)
	(segment
		(start 439.221372 -45.981874)
		(end 438.940956 -46.26229)
		(width 0.1143)
		(layer "F.Cu")
		(net "P3E_CPU0_PE3_OCP_RXP<7>")
	)
	(segment
		(start 439.221372 -45.018706)
		(end 439.221372 -45.981874)
		(width 0.1143)
		(layer "F.Cu")
		(net "P3E_CPU0_PE3_OCP_RXP<7>")
	)
	(segment
		(start 439.040016 -44.83735)
		(end 439.221372 -45.018706)
		(width 0.1143)
		(layer "F.Cu")
		(net "P3E_CPU0_PE3_OCP_RXP<7>")
	)
	(segment
		(start 438.940956 -46.26229)
		(end 438.940956 -47.481998)
		(width 0.1143)
		(layer "F.Cu")
		(net "P3E_CPU0_PE3_OCP_RXP<7>")
	)
	(via
		(at 438.707022 -44.83735)
		(size 0.508)
		(drill 0.254)
		(layers "F.Cu" "B.Cu")
		(net "P3E_CPU0_PE3_OCP_RXP<7>")
	)
	(via
		(at 296.66184 -95.033084)
		(size 0.508)
		(drill 0.254)
		(layers "F.Cu" "B.Cu")
		(net "P3E_CPU0_PE3_OCP_RXP<7>")
	)
	(segment
		(start 432.707542 -46.019974)
		(end 435.452774 -46.019974)
		(width 0.1143)
		(layer "In4.Cu")
		(net "P3E_CPU0_PE3_OCP_RXP<7>")
	)
	(segment
		(start 439.210704 -44.966382)
		(end 439.081672 -44.83735)
		(width 0.1143)
		(layer "In4.Cu")
		(net "P3E_CPU0_PE3_OCP_RXP<7>")
	)
	(segment
		(start 391.535158 -48.1457)
		(end 392.486642 -48.1457)
		(width 0.1143)
		(layer "In4.Cu")
		(net "P3E_CPU0_PE3_OCP_RXP<7>")
	)
	(segment
		(start 407.628344 -51.484784)
		(end 418.789866 -51.484784)
		(width 0.1143)
		(layer "In4.Cu")
		(net "P3E_CPU0_PE3_OCP_RXP<7>")
	)
	(segment
		(start 422.30294 -50.064416)
		(end 422.494456 -50.255932)
		(width 0.1143)
		(layer "In4.Cu")
		(net "P3E_CPU0_PE3_OCP_RXP<7>")
	)
	(segment
		(start 429.126142 -45.4914)
		(end 432.178968 -45.4914)
		(width 0.1143)
		(layer "In4.Cu")
		(net "P3E_CPU0_PE3_OCP_RXP<7>")
	)
	(segment
		(start 436.0926 -46.3169)
		(end 436.2577 -46.1518)
		(width 0.1143)
		(layer "In4.Cu")
		(net "P3E_CPU0_PE3_OCP_RXP<7>")
	)
	(segment
		(start 366.480344 -47.580804)
		(end 368.38636 -47.580804)
		(width 0.1143)
		(layer "In4.Cu")
		(net "P3E_CPU0_PE3_OCP_RXP<7>")
	)
	(segment
		(start 304.309018 -93.0021)
		(end 305.219862 -93.0021)
		(width 0.0889)
		(layer "In4.Cu")
		(net "P3E_CPU0_PE3_OCP_RXP<7>")
	)
	(segment
		(start 437.2737 -46.1518)
		(end 437.6166 -46.1518)
		(width 0.1143)
		(layer "In4.Cu")
		(net "P3E_CPU0_PE3_OCP_RXP<7>")
	)
	(segment
		(start 439.210704 -45.675296)
		(end 439.210704 -44.966382)
		(width 0.1143)
		(layer "In4.Cu")
		(net "P3E_CPU0_PE3_OCP_RXP<7>")
	)
	(segment
		(start 388.293356 -46.9773)
		(end 390.366758 -46.9773)
		(width 0.1143)
		(layer "In4.Cu")
		(net "P3E_CPU0_PE3_OCP_RXP<7>")
	)
	(segment
		(start 376.390408 -45.856144)
		(end 376.390408 -46.440852)
		(width 0.1143)
		(layer "In4.Cu")
		(net "P3E_CPU0_PE3_OCP_RXP<7>")
	)
	(segment
		(start 437.7817 -46.3169)
		(end 438.5691 -46.3169)
		(width 0.1143)
		(layer "In4.Cu")
		(net "P3E_CPU0_PE3_OCP_RXP<7>")
	)
	(segment
		(start 308.693058 -91.610942)
		(end 317.461138 -82.842862)
		(width 0.1143)
		(layer "In4.Cu")
		(net "P3E_CPU0_PE3_OCP_RXP<7>")
	)
	(segment
		(start 438.5691 -46.3169)
		(end 439.210704 -45.675296)
		(width 0.1143)
		(layer "In4.Cu")
		(net "P3E_CPU0_PE3_OCP_RXP<7>")
	)
	(segment
		(start 368.38636 -47.580804)
		(end 370.526564 -45.4406)
		(width 0.1143)
		(layer "In4.Cu")
		(net "P3E_CPU0_PE3_OCP_RXP<7>")
	)
	(segment
		(start 370.526564 -45.4406)
		(end 375.974864 -45.4406)
		(width 0.1143)
		(layer "In4.Cu")
		(net "P3E_CPU0_PE3_OCP_RXP<7>")
	)
	(segment
		(start 428.8409 -45.776642)
		(end 429.126142 -45.4914)
		(width 0.1143)
		(layer "In4.Cu")
		(net "P3E_CPU0_PE3_OCP_RXP<7>")
	)
	(segment
		(start 423.378884 -48.673258)
		(end 423.929302 -48.12284)
		(width 0.1143)
		(layer "In4.Cu")
		(net "P3E_CPU0_PE3_OCP_RXP<7>")
	)
	(segment
		(start 427.067472 -47.880524)
		(end 427.067472 -47.647098)
		(width 0.1143)
		(layer "In4.Cu")
		(net "P3E_CPU0_PE3_OCP_RXP<7>")
	)
	(segment
		(start 393.447016 -47.185326)
		(end 396.206726 -47.185326)
		(width 0.1143)
		(layer "In4.Cu")
		(net "P3E_CPU0_PE3_OCP_RXP<7>")
	)
	(segment
		(start 437.6166 -46.1518)
		(end 437.7817 -46.3169)
		(width 0.1143)
		(layer "In4.Cu")
		(net "P3E_CPU0_PE3_OCP_RXP<7>")
	)
	(segment
		(start 300.077632 -94.442534)
		(end 300.1137 -94.442534)
		(width 0.0889)
		(layer "In4.Cu")
		(net "P3E_CPU0_PE3_OCP_RXP<7>")
	)
	(segment
		(start 332.817724 -56.206644)
		(end 347.653356 -56.206644)
		(width 0.1143)
		(layer "In4.Cu")
		(net "P3E_CPU0_PE3_OCP_RXP<7>")
	)
	(segment
		(start 307.4162 -92.0242)
		(end 307.438298 -92.0242)
		(width 0.0889)
		(layer "In4.Cu")
		(net "P3E_CPU0_PE3_OCP_RXP<7>")
	)
	(segment
		(start 296.66184 -95.371158)
		(end 296.719498 -95.428816)
		(width 0.0889)
		(layer "In4.Cu")
		(net "P3E_CPU0_PE3_OCP_RXP<7>")
	)
	(segment
		(start 386.207508 -45.2882)
		(end 386.461762 -45.542454)
		(width 0.1143)
		(layer "In4.Cu")
		(net "P3E_CPU0_PE3_OCP_RXP<7>")
	)
	(segment
		(start 306.475892 -92.481908)
		(end 306.640992 -92.316808)
		(width 0.0889)
		(layer "In4.Cu")
		(net "P3E_CPU0_PE3_OCP_RXP<7>")
	)
	(segment
		(start 401.32127 -50.08245)
		(end 406.222708 -50.08245)
		(width 0.1143)
		(layer "In4.Cu")
		(net "P3E_CPU0_PE3_OCP_RXP<7>")
	)
	(segment
		(start 421.621204 -50.064416)
		(end 422.30294 -50.064416)
		(width 0.1143)
		(layer "In4.Cu")
		(net "P3E_CPU0_PE3_OCP_RXP<7>")
	)
	(segment
		(start 297.498516 -94.937834)
		(end 297.53814 -94.937834)
		(width 0.0889)
		(layer "In4.Cu")
		(net "P3E_CPU0_PE3_OCP_RXP<7>")
	)
	(segment
		(start 436.2577 -46.1518)
		(end 436.6006 -46.1518)
		(width 0.1143)
		(layer "In4.Cu")
		(net "P3E_CPU0_PE3_OCP_RXP<7>")
	)
	(segment
		(start 392.486642 -48.1457)
		(end 393.447016 -47.185326)
		(width 0.1143)
		(layer "In4.Cu")
		(net "P3E_CPU0_PE3_OCP_RXP<7>")
	)
	(segment
		(start 376.390408 -46.440852)
		(end 376.793252 -46.843696)
		(width 0.1143)
		(layer "In4.Cu")
		(net "P3E_CPU0_PE3_OCP_RXP<7>")
	)
	(segment
		(start 437.1086 -46.3169)
		(end 437.2737 -46.1518)
		(width 0.1143)
		(layer "In4.Cu")
		(net "P3E_CPU0_PE3_OCP_RXP<7>")
	)
	(segment
		(start 298.360846 -94.442534)
		(end 298.39666 -94.442534)
		(width 0.0889)
		(layer "In4.Cu")
		(net "P3E_CPU0_PE3_OCP_RXP<7>")
	)
	(segment
		(start 375.974864 -45.4406)
		(end 376.390408 -45.856144)
		(width 0.1143)
		(layer "In4.Cu")
		(net "P3E_CPU0_PE3_OCP_RXP<7>")
	)
	(segment
		(start 306.640992 -92.316808)
		(end 307.22443 -92.075)
		(width 0.0889)
		(layer "In4.Cu")
		(net "P3E_CPU0_PE3_OCP_RXP<7>")
	)
	(segment
		(start 301.791116 -93.452188)
		(end 301.823882 -93.452188)
		(width 0.0889)
		(layer "In4.Cu")
		(net "P3E_CPU0_PE3_OCP_RXP<7>")
	)
	(segment
		(start 381.532638 -45.2882)
		(end 386.207508 -45.2882)
		(width 0.1143)
		(layer "In4.Cu")
		(net "P3E_CPU0_PE3_OCP_RXP<7>")
	)
	(segment
		(start 428.8409 -46.107096)
		(end 428.8409 -45.776642)
		(width 0.1143)
		(layer "In4.Cu")
		(net "P3E_CPU0_PE3_OCP_RXP<7>")
	)
	(segment
		(start 432.178968 -45.4914)
		(end 432.707542 -46.019974)
		(width 0.1143)
		(layer "In4.Cu")
		(net "P3E_CPU0_PE3_OCP_RXP<7>")
	)
	(segment
		(start 436.7657 -46.3169)
		(end 437.1086 -46.3169)
		(width 0.1143)
		(layer "In4.Cu")
		(net "P3E_CPU0_PE3_OCP_RXP<7>")
	)
	(segment
		(start 419.921182 -50.353468)
		(end 421.332152 -50.353468)
		(width 0.1143)
		(layer "In4.Cu")
		(net "P3E_CPU0_PE3_OCP_RXP<7>")
	)
	(segment
		(start 307.3654 -92.075)
		(end 307.4162 -92.0242)
		(width 0.0889)
		(layer "In4.Cu")
		(net "P3E_CPU0_PE3_OCP_RXP<7>")
	)
	(segment
		(start 300.941232 -93.947234)
		(end 300.969172 -93.947234)
		(width 0.0889)
		(layer "In4.Cu")
		(net "P3E_CPU0_PE3_OCP_RXP<7>")
	)
	(segment
		(start 435.7497 -46.3169)
		(end 436.0926 -46.3169)
		(width 0.1143)
		(layer "In4.Cu")
		(net "P3E_CPU0_PE3_OCP_RXP<7>")
	)
	(segment
		(start 356.529132 -53.469032)
		(end 357.766112 -53.053996)
		(width 0.1143)
		(layer "In4.Cu")
		(net "P3E_CPU0_PE3_OCP_RXP<7>")
	)
	(segment
		(start 347.653356 -56.206644)
		(end 351.219516 -53.683916)
		(width 0.1143)
		(layer "In4.Cu")
		(net "P3E_CPU0_PE3_OCP_RXP<7>")
	)
	(segment
		(start 376.793252 -46.843696)
		(end 379.977142 -46.843696)
		(width 0.1143)
		(layer "In4.Cu")
		(net "P3E_CPU0_PE3_OCP_RXP<7>")
	)
	(segment
		(start 307.438298 -92.0242)
		(end 307.6956 -92.0242)
		(width 0.1143)
		(layer "In4.Cu")
		(net "P3E_CPU0_PE3_OCP_RXP<7>")
	)
	(segment
		(start 379.977142 -46.843696)
		(end 381.532638 -45.2882)
		(width 0.1143)
		(layer "In4.Cu")
		(net "P3E_CPU0_PE3_OCP_RXP<7>")
	)
	(segment
		(start 427.067472 -47.647098)
		(end 427.309788 -47.404782)
		(width 0.1143)
		(layer "In4.Cu")
		(net "P3E_CPU0_PE3_OCP_RXP<7>")
	)
	(segment
		(start 426.824902 -48.123094)
		(end 427.067472 -47.880524)
		(width 0.1143)
		(layer "In4.Cu")
		(net "P3E_CPU0_PE3_OCP_RXP<7>")
	)
	(segment
		(start 386.85851 -45.542454)
		(end 388.293356 -46.9773)
		(width 0.1143)
		(layer "In4.Cu")
		(net "P3E_CPU0_PE3_OCP_RXP<7>")
	)
	(segment
		(start 296.66184 -95.033084)
		(end 296.66184 -95.371158)
		(width 0.0889)
		(layer "In4.Cu")
		(net "P3E_CPU0_PE3_OCP_RXP<7>")
	)
	(segment
		(start 426.674788 -48.12284)
		(end 426.675042 -48.123094)
		(width 0.1143)
		(layer "In4.Cu")
		(net "P3E_CPU0_PE3_OCP_RXP<7>")
	)
	(segment
		(start 317.461138 -82.842862)
		(end 322.481702 -70.720966)
		(width 0.1143)
		(layer "In4.Cu")
		(net "P3E_CPU0_PE3_OCP_RXP<7>")
	)
	(segment
		(start 305.219862 -93.0021)
		(end 306.475892 -92.481908)
		(width 0.0889)
		(layer "In4.Cu")
		(net "P3E_CPU0_PE3_OCP_RXP<7>")
	)
	(segment
		(start 423.378884 -49.894236)
		(end 423.378884 -48.673258)
		(width 0.1143)
		(layer "In4.Cu")
		(net "P3E_CPU0_PE3_OCP_RXP<7>")
	)
	(segment
		(start 354.408994 -53.046122)
		(end 356.529132 -53.469032)
		(width 0.1143)
		(layer "In4.Cu")
		(net "P3E_CPU0_PE3_OCP_RXP<7>")
	)
	(segment
		(start 422.494456 -50.255932)
		(end 423.017188 -50.255932)
		(width 0.1143)
		(layer "In4.Cu")
		(net "P3E_CPU0_PE3_OCP_RXP<7>")
	)
	(segment
		(start 423.929302 -48.12284)
		(end 426.674788 -48.12284)
		(width 0.1143)
		(layer "In4.Cu")
		(net "P3E_CPU0_PE3_OCP_RXP<7>")
	)
	(segment
		(start 399.328894 -48.090074)
		(end 401.32127 -50.08245)
		(width 0.1143)
		(layer "In4.Cu")
		(net "P3E_CPU0_PE3_OCP_RXP<7>")
	)
	(segment
		(start 297.004994 -95.238824)
		(end 297.008296 -95.232982)
		(width 0.0889)
		(layer "In4.Cu")
		(net "P3E_CPU0_PE3_OCP_RXP<7>")
	)
	(segment
		(start 357.766112 -53.053996)
		(end 361.438444 -50.605436)
		(width 0.1143)
		(layer "In4.Cu")
		(net "P3E_CPU0_PE3_OCP_RXP<7>")
	)
	(segment
		(start 426.675042 -48.123094)
		(end 426.824902 -48.123094)
		(width 0.1143)
		(layer "In4.Cu")
		(net "P3E_CPU0_PE3_OCP_RXP<7>")
	)
	(segment
		(start 423.017188 -50.255932)
		(end 423.378884 -49.894236)
		(width 0.1143)
		(layer "In4.Cu")
		(net "P3E_CPU0_PE3_OCP_RXP<7>")
	)
	(segment
		(start 397.111474 -48.090074)
		(end 399.328894 -48.090074)
		(width 0.1143)
		(layer "In4.Cu")
		(net "P3E_CPU0_PE3_OCP_RXP<7>")
	)
	(segment
		(start 307.6956 -92.0242)
		(end 308.693058 -91.610942)
		(width 0.1143)
		(layer "In4.Cu")
		(net "P3E_CPU0_PE3_OCP_RXP<7>")
	)
	(segment
		(start 427.543214 -47.404782)
		(end 428.8409 -46.107096)
		(width 0.1143)
		(layer "In4.Cu")
		(net "P3E_CPU0_PE3_OCP_RXP<7>")
	)
	(segment
		(start 322.481702 -70.720966)
		(end 332.17231 -56.633618)
		(width 0.1143)
		(layer "In4.Cu")
		(net "P3E_CPU0_PE3_OCP_RXP<7>")
	)
	(segment
		(start 390.366758 -46.9773)
		(end 391.535158 -48.1457)
		(width 0.1143)
		(layer "In4.Cu")
		(net "P3E_CPU0_PE3_OCP_RXP<7>")
	)
	(segment
		(start 427.309788 -47.404782)
		(end 427.543214 -47.404782)
		(width 0.1143)
		(layer "In4.Cu")
		(net "P3E_CPU0_PE3_OCP_RXP<7>")
	)
	(segment
		(start 307.22443 -92.075)
		(end 307.3654 -92.075)
		(width 0.0889)
		(layer "In4.Cu")
		(net "P3E_CPU0_PE3_OCP_RXP<7>")
	)
	(segment
		(start 418.789866 -51.484784)
		(end 419.921182 -50.353468)
		(width 0.1143)
		(layer "In4.Cu")
		(net "P3E_CPU0_PE3_OCP_RXP<7>")
	)
	(segment
		(start 396.206726 -47.185326)
		(end 397.111474 -48.090074)
		(width 0.1143)
		(layer "In4.Cu")
		(net "P3E_CPU0_PE3_OCP_RXP<7>")
	)
	(segment
		(start 435.452774 -46.019974)
		(end 435.7497 -46.3169)
		(width 0.1143)
		(layer "In4.Cu")
		(net "P3E_CPU0_PE3_OCP_RXP<7>")
	)
	(segment
		(start 406.222708 -50.08245)
		(end 407.628344 -51.484784)
		(width 0.1143)
		(layer "In4.Cu")
		(net "P3E_CPU0_PE3_OCP_RXP<7>")
	)
	(segment
		(start 439.081672 -44.83735)
		(end 438.707022 -44.83735)
		(width 0.1143)
		(layer "In4.Cu")
		(net "P3E_CPU0_PE3_OCP_RXP<7>")
	)
	(segment
		(start 332.17231 -56.633618)
		(end 332.817724 -56.206644)
		(width 0.1143)
		(layer "In4.Cu")
		(net "P3E_CPU0_PE3_OCP_RXP<7>")
	)
	(segment
		(start 364.270798 -49.79035)
		(end 366.480344 -47.580804)
		(width 0.1143)
		(layer "In4.Cu")
		(net "P3E_CPU0_PE3_OCP_RXP<7>")
	)
	(segment
		(start 361.438444 -50.605436)
		(end 364.270798 -49.79035)
		(width 0.1143)
		(layer "In4.Cu")
		(net "P3E_CPU0_PE3_OCP_RXP<7>")
	)
	(segment
		(start 421.332152 -50.353468)
		(end 421.621204 -50.064416)
		(width 0.1143)
		(layer "In4.Cu")
		(net "P3E_CPU0_PE3_OCP_RXP<7>")
	)
	(segment
		(start 351.219516 -53.683916)
		(end 354.408994 -53.046122)
		(width 0.1143)
		(layer "In4.Cu")
		(net "P3E_CPU0_PE3_OCP_RXP<7>")
	)
	(segment
		(start 386.461762 -45.542454)
		(end 386.85851 -45.542454)
		(width 0.1143)
		(layer "In4.Cu")
		(net "P3E_CPU0_PE3_OCP_RXP<7>")
	)
	(segment
		(start 436.6006 -46.1518)
		(end 436.7657 -46.3169)
		(width 0.1143)
		(layer "In4.Cu")
		(net "P3E_CPU0_PE3_OCP_RXP<7>")
	)
	(arc
		(start 298.725336 -94.242636)
		(mid 299.237146 -93.947097)
		(end 299.748956 -94.242636)
		(width 0.0889)
		(layer "In4.Cu")
		(net "P3E_CPU0_PE3_OCP_RXP<7>")
	)
	(arc
		(start 297.008296 -95.232982)
		(mid 297.2153 -95.022118)
		(end 297.498516 -94.937834)
		(width 0.0889)
		(layer "In4.Cu")
		(net "P3E_CPU0_PE3_OCP_RXP<7>")
	)
	(arc
		(start 298.39666 -94.442534)
		(mid 298.586589 -94.384664)
		(end 298.725336 -94.242636)
		(width 0.0889)
		(layer "In4.Cu")
		(net "P3E_CPU0_PE3_OCP_RXP<7>")
	)
	(arc
		(start 303.183036 -93.252036)
		(mid 303.529746 -93.452347)
		(end 303.876456 -93.252036)
		(width 0.0889)
		(layer "In4.Cu")
		(net "P3E_CPU0_PE3_OCP_RXP<7>")
	)
	(arc
		(start 302.159416 -93.252036)
		(mid 302.671226 -92.956369)
		(end 303.183036 -93.252036)
		(width 0.0889)
		(layer "In4.Cu")
		(net "P3E_CPU0_PE3_OCP_RXP<7>")
	)
	(arc
		(start 297.53814 -94.937834)
		(mid 297.728069 -94.879964)
		(end 297.866816 -94.737936)
		(width 0.0889)
		(layer "In4.Cu")
		(net "P3E_CPU0_PE3_OCP_RXP<7>")
	)
	(arc
		(start 296.719498 -95.428816)
		(mid 296.883675 -95.365999)
		(end 297.004994 -95.238824)
		(width 0.0889)
		(layer "In4.Cu")
		(net "P3E_CPU0_PE3_OCP_RXP<7>")
	)
	(arc
		(start 300.1137 -94.442534)
		(mid 300.303629 -94.384664)
		(end 300.442376 -94.242636)
		(width 0.0889)
		(layer "In4.Cu")
		(net "P3E_CPU0_PE3_OCP_RXP<7>")
	)
	(arc
		(start 300.969172 -93.947234)
		(mid 301.160814 -93.890068)
		(end 301.300896 -93.747336)
		(width 0.0889)
		(layer "In4.Cu")
		(net "P3E_CPU0_PE3_OCP_RXP<7>")
	)
	(arc
		(start 303.876456 -93.252036)
		(mid 304.05925 -93.069098)
		(end 304.309018 -93.0021)
		(width 0.0889)
		(layer "In4.Cu")
		(net "P3E_CPU0_PE3_OCP_RXP<7>")
	)
	(arc
		(start 299.748956 -94.242636)
		(mid 299.8877 -94.384669)
		(end 300.077632 -94.442534)
		(width 0.0889)
		(layer "In4.Cu")
		(net "P3E_CPU0_PE3_OCP_RXP<7>")
	)
	(arc
		(start 301.823882 -93.452188)
		(mid 302.017732 -93.395838)
		(end 302.159416 -93.252036)
		(width 0.0889)
		(layer "In4.Cu")
		(net "P3E_CPU0_PE3_OCP_RXP<7>")
	)
	(arc
		(start 301.300896 -93.747336)
		(mid 301.5079 -93.536472)
		(end 301.791116 -93.452188)
		(width 0.0889)
		(layer "In4.Cu")
		(net "P3E_CPU0_PE3_OCP_RXP<7>")
	)
	(arc
		(start 297.866816 -94.737936)
		(mid 298.075424 -94.526004)
		(end 298.360846 -94.442534)
		(width 0.0889)
		(layer "In4.Cu")
		(net "P3E_CPU0_PE3_OCP_RXP<7>")
	)
	(arc
		(start 300.442376 -94.242636)
		(mid 300.653089 -94.029557)
		(end 300.941232 -93.947234)
		(width 0.0889)
		(layer "In4.Cu")
		(net "P3E_CPU0_PE3_OCP_RXP<7>")
	)
	(segment
		(start 442.662818 -45.978318)
		(end 442.942218 -46.257718)
		(width 0.1143)
		(layer "F.Cu")
		(net "P3E_CPU0_PE3_OCP_RXP<6>")
	)
	(segment
		(start 443.177168 -44.83735)
		(end 442.844174 -44.83735)
		(width 0.1143)
		(layer "F.Cu")
		(net "P3E_CPU0_PE3_OCP_RXP<6>")
	)
	(segment
		(start 442.844174 -44.83735)
		(end 442.662818 -45.018706)
		(width 0.1143)
		(layer "F.Cu")
		(net "P3E_CPU0_PE3_OCP_RXP<6>")
	)
	(segment
		(start 296.948606 -96.518984)
		(end 297.520106 -96.518984)
		(width 0.1143)
		(layer "F.Cu")
		(net "P3E_CPU0_PE3_OCP_RXP<6>")
	)
	(segment
		(start 442.942218 -47.480728)
		(end 442.940948 -47.481998)
		(width 0.1143)
		(layer "F.Cu")
		(net "P3E_CPU0_PE3_OCP_RXP<6>")
	)
	(segment
		(start 442.942218 -46.257718)
		(end 442.942218 -47.480728)
		(width 0.1143)
		(layer "F.Cu")
		(net "P3E_CPU0_PE3_OCP_RXP<6>")
	)
	(segment
		(start 442.662818 -45.018706)
		(end 442.662818 -45.978318)
		(width 0.1143)
		(layer "F.Cu")
		(net "P3E_CPU0_PE3_OCP_RXP<6>")
	)
	(via
		(at 297.520106 -96.518984)
		(size 0.508)
		(drill 0.254)
		(layers "F.Cu" "B.Cu")
		(net "P3E_CPU0_PE3_OCP_RXP<6>")
	)
	(via
		(at 443.177168 -44.83735)
		(size 0.508)
		(drill 0.254)
		(layers "F.Cu" "B.Cu")
		(net "P3E_CPU0_PE3_OCP_RXP<6>")
	)
	(segment
		(start 304.940462 -92.156534)
		(end 305.118262 -92.156534)
		(width 0.0889)
		(layer "In4.Cu")
		(net "P3E_CPU0_PE3_OCP_RXP<6>")
	)
	(segment
		(start 423.8244 -47.6504)
		(end 425.6786 -47.6504)
		(width 0.1143)
		(layer "In4.Cu")
		(net "P3E_CPU0_PE3_OCP_RXP<6>")
	)
	(segment
		(start 436.187596 -45.063156)
		(end 436.187596 -44.439586)
		(width 0.1143)
		(layer "In4.Cu")
		(net "P3E_CPU0_PE3_OCP_RXP<6>")
	)
	(segment
		(start 386.349748 -44.9453)
		(end 386.604002 -45.199554)
		(width 0.1143)
		(layer "In4.Cu")
		(net "P3E_CPU0_PE3_OCP_RXP<6>")
	)
	(segment
		(start 347.452442 -55.851044)
		(end 351.889314 -52.692046)
		(width 0.1143)
		(layer "In4.Cu")
		(net "P3E_CPU0_PE3_OCP_RXP<6>")
	)
	(segment
		(start 306.057046 -92.156534)
		(end 306.234846 -92.156534)
		(width 0.0889)
		(layer "In4.Cu")
		(net "P3E_CPU0_PE3_OCP_RXP<6>")
	)
	(segment
		(start 418.644832 -51.141884)
		(end 420.867332 -48.919384)
		(width 0.1143)
		(layer "In4.Cu")
		(net "P3E_CPU0_PE3_OCP_RXP<6>")
	)
	(segment
		(start 308.762146 -90.96883)
		(end 308.834282 -90.96883)
		(width 0.0889)
		(layer "In4.Cu")
		(net "P3E_CPU0_PE3_OCP_RXP<6>")
	)
	(segment
		(start 436.187596 -44.439586)
		(end 436.497222 -44.12996)
		(width 0.1143)
		(layer "In4.Cu")
		(net "P3E_CPU0_PE3_OCP_RXP<6>")
	)
	(segment
		(start 427.334934 -46.111922)
		(end 428.323756 -45.1231)
		(width 0.1143)
		(layer "In4.Cu")
		(net "P3E_CPU0_PE3_OCP_RXP<6>")
	)
	(segment
		(start 322.076572 -70.703948)
		(end 331.929486 -56.380888)
		(width 0.1143)
		(layer "In4.Cu")
		(net "P3E_CPU0_PE3_OCP_RXP<6>")
	)
	(segment
		(start 308.834282 -90.96883)
		(end 308.849776 -90.953336)
		(width 0.0889)
		(layer "In4.Cu")
		(net "P3E_CPU0_PE3_OCP_RXP<6>")
	)
	(segment
		(start 300.94301 -93.147134)
		(end 300.975776 -93.147134)
		(width 0.0889)
		(layer "In4.Cu")
		(net "P3E_CPU0_PE3_OCP_RXP<6>")
	)
	(segment
		(start 426.339 -46.437296)
		(end 426.664374 -46.111922)
		(width 0.1143)
		(layer "In4.Cu")
		(net "P3E_CPU0_PE3_OCP_RXP<6>")
	)
	(segment
		(start 407.770584 -51.141884)
		(end 418.644832 -51.141884)
		(width 0.1143)
		(layer "In4.Cu")
		(net "P3E_CPU0_PE3_OCP_RXP<6>")
	)
	(segment
		(start 366.335564 -47.237904)
		(end 368.049556 -47.237904)
		(width 0.1143)
		(layer "In4.Cu")
		(net "P3E_CPU0_PE3_OCP_RXP<6>")
	)
	(segment
		(start 386.604002 -45.199554)
		(end 387.00075 -45.199554)
		(width 0.1143)
		(layer "In4.Cu")
		(net "P3E_CPU0_PE3_OCP_RXP<6>")
	)
	(segment
		(start 442.802772 -44.83735)
		(end 443.177168 -44.83735)
		(width 0.1143)
		(layer "In4.Cu")
		(net "P3E_CPU0_PE3_OCP_RXP<6>")
	)
	(segment
		(start 332.730602 -55.851044)
		(end 347.452442 -55.851044)
		(width 0.1143)
		(layer "In4.Cu")
		(net "P3E_CPU0_PE3_OCP_RXP<6>")
	)
	(segment
		(start 305.219608 -92.25788)
		(end 305.397408 -92.25788)
		(width 0.0889)
		(layer "In4.Cu")
		(net "P3E_CPU0_PE3_OCP_RXP<6>")
	)
	(segment
		(start 441.2869 -46.3931)
		(end 442.2775 -46.3931)
		(width 0.1143)
		(layer "In4.Cu")
		(net "P3E_CPU0_PE3_OCP_RXP<6>")
	)
	(segment
		(start 305.7779 -92.25788)
		(end 305.9557 -92.25788)
		(width 0.0889)
		(layer "In4.Cu")
		(net "P3E_CPU0_PE3_OCP_RXP<6>")
	)
	(segment
		(start 440.176666 -44.12996)
		(end 440.8678 -44.821094)
		(width 0.1143)
		(layer "In4.Cu")
		(net "P3E_CPU0_PE3_OCP_RXP<6>")
	)
	(segment
		(start 388.105396 -46.3042)
		(end 390.9822 -46.3042)
		(width 0.1143)
		(layer "In4.Cu")
		(net "P3E_CPU0_PE3_OCP_RXP<6>")
	)
	(segment
		(start 306.782724 -91.734386)
		(end 307.889148 -91.276678)
		(width 0.0889)
		(layer "In4.Cu")
		(net "P3E_CPU0_PE3_OCP_RXP<6>")
	)
	(segment
		(start 307.889148 -91.276678)
		(end 308.298342 -91.276678)
		(width 0.0889)
		(layer "In4.Cu")
		(net "P3E_CPU0_PE3_OCP_RXP<6>")
	)
	(segment
		(start 442.688218 -44.951904)
		(end 442.802772 -44.83735)
		(width 0.1143)
		(layer "In4.Cu")
		(net "P3E_CPU0_PE3_OCP_RXP<6>")
	)
	(segment
		(start 305.397408 -92.25788)
		(end 305.498754 -92.156534)
		(width 0.0889)
		(layer "In4.Cu")
		(net "P3E_CPU0_PE3_OCP_RXP<6>")
	)
	(segment
		(start 296.643806 -94.633288)
		(end 296.68343 -94.633288)
		(width 0.0889)
		(layer "In4.Cu")
		(net "P3E_CPU0_PE3_OCP_RXP<6>")
	)
	(segment
		(start 368.049556 -47.237904)
		(end 370.227606 -45.059854)
		(width 0.1143)
		(layer "In4.Cu")
		(net "P3E_CPU0_PE3_OCP_RXP<6>")
	)
	(segment
		(start 308.564534 -91.166442)
		(end 308.762146 -90.96883)
		(width 0.0889)
		(layer "In4.Cu")
		(net "P3E_CPU0_PE3_OCP_RXP<6>")
	)
	(segment
		(start 422.555416 -48.919384)
		(end 423.8244 -47.6504)
		(width 0.1143)
		(layer "In4.Cu")
		(net "P3E_CPU0_PE3_OCP_RXP<6>")
	)
	(segment
		(start 331.929486 -56.380888)
		(end 331.929486 -56.381142)
		(width 0.1143)
		(layer "In4.Cu")
		(net "P3E_CPU0_PE3_OCP_RXP<6>")
	)
	(segment
		(start 304.373788 -92.156534)
		(end 304.55997 -92.156534)
		(width 0.0889)
		(layer "In4.Cu")
		(net "P3E_CPU0_PE3_OCP_RXP<6>")
	)
	(segment
		(start 317.111634 -82.691478)
		(end 322.076572 -70.703948)
		(width 0.1143)
		(layer "In4.Cu")
		(net "P3E_CPU0_PE3_OCP_RXP<6>")
	)
	(segment
		(start 440.8678 -44.821094)
		(end 440.8678 -45.974)
		(width 0.1143)
		(layer "In4.Cu")
		(net "P3E_CPU0_PE3_OCP_RXP<6>")
	)
	(segment
		(start 331.929486 -56.381142)
		(end 332.730602 -55.851044)
		(width 0.1143)
		(layer "In4.Cu")
		(net "P3E_CPU0_PE3_OCP_RXP<6>")
	)
	(segment
		(start 390.9822 -46.3042)
		(end 391.680446 -45.605954)
		(width 0.1143)
		(layer "In4.Cu")
		(net "P3E_CPU0_PE3_OCP_RXP<6>")
	)
	(segment
		(start 440.8678 -45.974)
		(end 441.2869 -46.3931)
		(width 0.1143)
		(layer "In4.Cu")
		(net "P3E_CPU0_PE3_OCP_RXP<6>")
	)
	(segment
		(start 297.17365 -94.33814)
		(end 297.176952 -94.332298)
		(width 0.0889)
		(layer "In4.Cu")
		(net "P3E_CPU0_PE3_OCP_RXP<6>")
	)
	(segment
		(start 393.95527 -45.994574)
		(end 394.734796 -46.7741)
		(width 0.1143)
		(layer "In4.Cu")
		(net "P3E_CPU0_PE3_OCP_RXP<6>")
	)
	(segment
		(start 296.686732 -96.423988)
		(end 296.650664 -96.423988)
		(width 0.0889)
		(layer "In4.Cu")
		(net "P3E_CPU0_PE3_OCP_RXP<6>")
	)
	(segment
		(start 304.661316 -92.25788)
		(end 304.839116 -92.25788)
		(width 0.0889)
		(layer "In4.Cu")
		(net "P3E_CPU0_PE3_OCP_RXP<6>")
	)
	(segment
		(start 425.6786 -47.6504)
		(end 426.339 -46.99)
		(width 0.1143)
		(layer "In4.Cu")
		(net "P3E_CPU0_PE3_OCP_RXP<6>")
	)
	(segment
		(start 436.497222 -44.12996)
		(end 440.176666 -44.12996)
		(width 0.1143)
		(layer "In4.Cu")
		(net "P3E_CPU0_PE3_OCP_RXP<6>")
	)
	(segment
		(start 420.867332 -48.919384)
		(end 422.555416 -48.919384)
		(width 0.1143)
		(layer "In4.Cu")
		(net "P3E_CPU0_PE3_OCP_RXP<6>")
	)
	(segment
		(start 297.520106 -96.518984)
		(end 297.227244 -96.687894)
		(width 0.0889)
		(layer "In4.Cu")
		(net "P3E_CPU0_PE3_OCP_RXP<6>")
	)
	(segment
		(start 364.165896 -49.407572)
		(end 366.335564 -47.237904)
		(width 0.1143)
		(layer "In4.Cu")
		(net "P3E_CPU0_PE3_OCP_RXP<6>")
	)
	(segment
		(start 428.323756 -45.1231)
		(end 432.295808 -45.1231)
		(width 0.1143)
		(layer "In4.Cu")
		(net "P3E_CPU0_PE3_OCP_RXP<6>")
	)
	(segment
		(start 370.227606 -45.059854)
		(end 376.485404 -45.059854)
		(width 0.1143)
		(layer "In4.Cu")
		(net "P3E_CPU0_PE3_OCP_RXP<6>")
	)
	(segment
		(start 308.849776 -90.953336)
		(end 317.111634 -82.691478)
		(width 0.1143)
		(layer "In4.Cu")
		(net "P3E_CPU0_PE3_OCP_RXP<6>")
	)
	(segment
		(start 442.2775 -46.3931)
		(end 442.688218 -45.982382)
		(width 0.1143)
		(layer "In4.Cu")
		(net "P3E_CPU0_PE3_OCP_RXP<6>")
	)
	(segment
		(start 387.00075 -45.199554)
		(end 388.105396 -46.3042)
		(width 0.1143)
		(layer "In4.Cu")
		(net "P3E_CPU0_PE3_OCP_RXP<6>")
	)
	(segment
		(start 435.652926 -45.597826)
		(end 436.187596 -45.063156)
		(width 0.1143)
		(layer "In4.Cu")
		(net "P3E_CPU0_PE3_OCP_RXP<6>")
	)
	(segment
		(start 393.371832 -45.994574)
		(end 393.95527 -45.994574)
		(width 0.1143)
		(layer "In4.Cu")
		(net "P3E_CPU0_PE3_OCP_RXP<6>")
	)
	(segment
		(start 406.31872 -49.69002)
		(end 407.770584 -51.141884)
		(width 0.1143)
		(layer "In4.Cu")
		(net "P3E_CPU0_PE3_OCP_RXP<6>")
	)
	(segment
		(start 381.369316 -44.9453)
		(end 386.349748 -44.9453)
		(width 0.1143)
		(layer "In4.Cu")
		(net "P3E_CPU0_PE3_OCP_RXP<6>")
	)
	(segment
		(start 396.301976 -46.7741)
		(end 397.181578 -47.653702)
		(width 0.1143)
		(layer "In4.Cu")
		(net "P3E_CPU0_PE3_OCP_RXP<6>")
	)
	(segment
		(start 397.181578 -47.653702)
		(end 399.528284 -47.653702)
		(width 0.1143)
		(layer "In4.Cu")
		(net "P3E_CPU0_PE3_OCP_RXP<6>")
	)
	(segment
		(start 391.680446 -45.605954)
		(end 392.983212 -45.605954)
		(width 0.1143)
		(layer "In4.Cu")
		(net "P3E_CPU0_PE3_OCP_RXP<6>")
	)
	(segment
		(start 301.79772 -92.652088)
		(end 301.830486 -92.652088)
		(width 0.0889)
		(layer "In4.Cu")
		(net "P3E_CPU0_PE3_OCP_RXP<6>")
	)
	(segment
		(start 306.449476 -92.067634)
		(end 306.782724 -91.734386)
		(width 0.0889)
		(layer "In4.Cu")
		(net "P3E_CPU0_PE3_OCP_RXP<6>")
	)
	(segment
		(start 394.734796 -46.7741)
		(end 396.301976 -46.7741)
		(width 0.1143)
		(layer "In4.Cu")
		(net "P3E_CPU0_PE3_OCP_RXP<6>")
	)
	(segment
		(start 363.050074 -49.407572)
		(end 364.165896 -49.407572)
		(width 0.1143)
		(layer "In4.Cu")
		(net "P3E_CPU0_PE3_OCP_RXP<6>")
	)
	(segment
		(start 297.227244 -96.687894)
		(end 297.137836 -96.663764)
		(width 0.0889)
		(layer "In4.Cu")
		(net "P3E_CPU0_PE3_OCP_RXP<6>")
	)
	(segment
		(start 377.923298 -46.497748)
		(end 379.816868 -46.497748)
		(width 0.1143)
		(layer "In4.Cu")
		(net "P3E_CPU0_PE3_OCP_RXP<6>")
	)
	(segment
		(start 297.520106 -94.137988)
		(end 297.53306 -94.137988)
		(width 0.0889)
		(layer "In4.Cu")
		(net "P3E_CPU0_PE3_OCP_RXP<6>")
	)
	(segment
		(start 379.816868 -46.497748)
		(end 381.369316 -44.9453)
		(width 0.1143)
		(layer "In4.Cu")
		(net "P3E_CPU0_PE3_OCP_RXP<6>")
	)
	(segment
		(start 304.55997 -92.156534)
		(end 304.661316 -92.25788)
		(width 0.0889)
		(layer "In4.Cu")
		(net "P3E_CPU0_PE3_OCP_RXP<6>")
	)
	(segment
		(start 426.664374 -46.111922)
		(end 427.334934 -46.111922)
		(width 0.1143)
		(layer "In4.Cu")
		(net "P3E_CPU0_PE3_OCP_RXP<6>")
	)
	(segment
		(start 304.839116 -92.25788)
		(end 304.940462 -92.156534)
		(width 0.0889)
		(layer "In4.Cu")
		(net "P3E_CPU0_PE3_OCP_RXP<6>")
	)
	(segment
		(start 351.889314 -52.692046)
		(end 363.050074 -49.407572)
		(width 0.1143)
		(layer "In4.Cu")
		(net "P3E_CPU0_PE3_OCP_RXP<6>")
	)
	(segment
		(start 305.9557 -92.25788)
		(end 306.057046 -92.156534)
		(width 0.0889)
		(layer "In4.Cu")
		(net "P3E_CPU0_PE3_OCP_RXP<6>")
	)
	(segment
		(start 308.298342 -91.276678)
		(end 308.564534 -91.166442)
		(width 0.0889)
		(layer "In4.Cu")
		(net "P3E_CPU0_PE3_OCP_RXP<6>")
	)
	(segment
		(start 432.295808 -45.1231)
		(end 432.770534 -45.597826)
		(width 0.1143)
		(layer "In4.Cu")
		(net "P3E_CPU0_PE3_OCP_RXP<6>")
	)
	(segment
		(start 392.983212 -45.605954)
		(end 393.371832 -45.994574)
		(width 0.1143)
		(layer "In4.Cu")
		(net "P3E_CPU0_PE3_OCP_RXP<6>")
	)
	(segment
		(start 306.234846 -92.156534)
		(end 306.449476 -92.067634)
		(width 0.0889)
		(layer "In4.Cu")
		(net "P3E_CPU0_PE3_OCP_RXP<6>")
	)
	(segment
		(start 305.498754 -92.156534)
		(end 305.676554 -92.156534)
		(width 0.0889)
		(layer "In4.Cu")
		(net "P3E_CPU0_PE3_OCP_RXP<6>")
	)
	(segment
		(start 432.770534 -45.597826)
		(end 435.652926 -45.597826)
		(width 0.1143)
		(layer "In4.Cu")
		(net "P3E_CPU0_PE3_OCP_RXP<6>")
	)
	(segment
		(start 442.688218 -45.982382)
		(end 442.688218 -44.951904)
		(width 0.1143)
		(layer "In4.Cu")
		(net "P3E_CPU0_PE3_OCP_RXP<6>")
	)
	(segment
		(start 305.118262 -92.156534)
		(end 305.219608 -92.25788)
		(width 0.0889)
		(layer "In4.Cu")
		(net "P3E_CPU0_PE3_OCP_RXP<6>")
	)
	(segment
		(start 401.564602 -49.69002)
		(end 406.31872 -49.69002)
		(width 0.1143)
		(layer "In4.Cu")
		(net "P3E_CPU0_PE3_OCP_RXP<6>")
	)
	(segment
		(start 399.528284 -47.653702)
		(end 401.564602 -49.69002)
		(width 0.1143)
		(layer "In4.Cu")
		(net "P3E_CPU0_PE3_OCP_RXP<6>")
	)
	(segment
		(start 426.339 -46.99)
		(end 426.339 -46.437296)
		(width 0.1143)
		(layer "In4.Cu")
		(net "P3E_CPU0_PE3_OCP_RXP<6>")
	)
	(segment
		(start 305.676554 -92.156534)
		(end 305.7779 -92.25788)
		(width 0.0889)
		(layer "In4.Cu")
		(net "P3E_CPU0_PE3_OCP_RXP<6>")
	)
	(segment
		(start 298.36364 -93.642688)
		(end 298.396406 -93.642688)
		(width 0.0889)
		(layer "In4.Cu")
		(net "P3E_CPU0_PE3_OCP_RXP<6>")
	)
	(segment
		(start 376.485404 -45.059854)
		(end 377.923298 -46.497748)
		(width 0.1143)
		(layer "In4.Cu")
		(net "P3E_CPU0_PE3_OCP_RXP<6>")
	)
	(arc
		(start 296.31513 -95.823786)
		(mid 296.394261 -95.528384)
		(end 296.31513 -95.232982)
		(width 0.0889)
		(layer "In4.Cu")
		(net "P3E_CPU0_PE3_OCP_RXP<6>")
	)
	(arc
		(start 298.031916 -93.842586)
		(mid 298.171995 -93.69985)
		(end 298.36364 -93.642688)
		(width 0.0889)
		(layer "In4.Cu")
		(net "P3E_CPU0_PE3_OCP_RXP<6>")
	)
	(arc
		(start 300.975776 -93.147134)
		(mid 301.258993 -93.062853)
		(end 301.465996 -92.851986)
		(width 0.0889)
		(layer "In4.Cu")
		(net "P3E_CPU0_PE3_OCP_RXP<6>")
	)
	(arc
		(start 298.396406 -93.642688)
		(mid 298.68183 -93.559221)
		(end 298.890436 -93.347286)
		(width 0.0889)
		(layer "In4.Cu")
		(net "P3E_CPU0_PE3_OCP_RXP<6>")
	)
	(arc
		(start 299.583856 -93.347286)
		(mid 300.095666 -93.642953)
		(end 300.607476 -93.347286)
		(width 0.0889)
		(layer "In4.Cu")
		(net "P3E_CPU0_PE3_OCP_RXP<6>")
	)
	(arc
		(start 297.137836 -96.663764)
		(mid 296.939529 -96.492616)
		(end 296.686732 -96.423988)
		(width 0.0889)
		(layer "In4.Cu")
		(net "P3E_CPU0_PE3_OCP_RXP<6>")
	)
	(arc
		(start 298.890436 -93.347286)
		(mid 299.237146 -93.146975)
		(end 299.583856 -93.347286)
		(width 0.0889)
		(layer "In4.Cu")
		(net "P3E_CPU0_PE3_OCP_RXP<6>")
	)
	(arc
		(start 302.324516 -92.356686)
		(mid 302.671226 -92.156375)
		(end 303.017936 -92.356686)
		(width 0.0889)
		(layer "In4.Cu")
		(net "P3E_CPU0_PE3_OCP_RXP<6>")
	)
	(arc
		(start 300.607476 -93.347286)
		(mid 300.749159 -93.203482)
		(end 300.94301 -93.147134)
		(width 0.0889)
		(layer "In4.Cu")
		(net "P3E_CPU0_PE3_OCP_RXP<6>")
	)
	(arc
		(start 304.041556 -92.356686)
		(mid 304.181824 -92.21373)
		(end 304.373788 -92.156534)
		(width 0.0889)
		(layer "In4.Cu")
		(net "P3E_CPU0_PE3_OCP_RXP<6>")
	)
	(arc
		(start 297.53306 -94.137988)
		(mid 297.821205 -94.055669)
		(end 298.031916 -93.842586)
		(width 0.0889)
		(layer "In4.Cu")
		(net "P3E_CPU0_PE3_OCP_RXP<6>")
	)
	(arc
		(start 297.176952 -94.332298)
		(mid 297.322918 -94.189899)
		(end 297.520106 -94.137988)
		(width 0.0889)
		(layer "In4.Cu")
		(net "P3E_CPU0_PE3_OCP_RXP<6>")
	)
	(arc
		(start 296.68343 -94.633288)
		(mid 296.966647 -94.549007)
		(end 297.17365 -94.33814)
		(width 0.0889)
		(layer "In4.Cu")
		(net "P3E_CPU0_PE3_OCP_RXP<6>")
	)
	(arc
		(start 296.650664 -96.423988)
		(mid 296.312495 -96.21919)
		(end 296.31513 -95.823786)
		(width 0.0889)
		(layer "In4.Cu")
		(net "P3E_CPU0_PE3_OCP_RXP<6>")
	)
	(arc
		(start 301.465996 -92.851986)
		(mid 301.606075 -92.70925)
		(end 301.79772 -92.652088)
		(width 0.0889)
		(layer "In4.Cu")
		(net "P3E_CPU0_PE3_OCP_RXP<6>")
	)
	(arc
		(start 303.017936 -92.356686)
		(mid 303.529746 -92.652353)
		(end 304.041556 -92.356686)
		(width 0.0889)
		(layer "In4.Cu")
		(net "P3E_CPU0_PE3_OCP_RXP<6>")
	)
	(arc
		(start 296.31513 -95.232982)
		(mid 296.310885 -94.840737)
		(end 296.643806 -94.633288)
		(width 0.0889)
		(layer "In4.Cu")
		(net "P3E_CPU0_PE3_OCP_RXP<6>")
	)
	(arc
		(start 301.830486 -92.652088)
		(mid 302.11591 -92.568621)
		(end 302.324516 -92.356686)
		(width 0.0889)
		(layer "In4.Cu")
		(net "P3E_CPU0_PE3_OCP_RXP<6>")
	)
	(segment
		(start 445.8716 -45.009816)
		(end 445.8716 -46.062646)
		(width 0.1143)
		(layer "F.Cu")
		(net "P3E_CPU0_PE3_OCP_RXP<5>")
	)
	(segment
		(start 446.044066 -44.83735)
		(end 445.8716 -45.009816)
		(width 0.1143)
		(layer "F.Cu")
		(net "P3E_CPU0_PE3_OCP_RXP<5>")
	)
	(segment
		(start 446.37706 -44.83735)
		(end 446.044066 -44.83735)
		(width 0.1143)
		(layer "F.Cu")
		(net "P3E_CPU0_PE3_OCP_RXP<5>")
	)
	(segment
		(start 445.8716 -46.062646)
		(end 446.141094 -46.33214)
		(width 0.1143)
		(layer "F.Cu")
		(net "P3E_CPU0_PE3_OCP_RXP<5>")
	)
	(segment
		(start 295.23182 -97.509584)
		(end 295.80332 -97.509584)
		(width 0.1143)
		(layer "F.Cu")
		(net "P3E_CPU0_PE3_OCP_RXP<5>")
	)
	(segment
		(start 446.141094 -46.33214)
		(end 446.141094 -47.481998)
		(width 0.1143)
		(layer "F.Cu")
		(net "P3E_CPU0_PE3_OCP_RXP<5>")
	)
	(via
		(at 295.80332 -97.509584)
		(size 0.508)
		(drill 0.254)
		(layers "F.Cu" "B.Cu")
		(net "P3E_CPU0_PE3_OCP_RXP<5>")
	)
	(via
		(at 446.37706 -44.83735)
		(size 0.508)
		(drill 0.254)
		(layers "F.Cu" "B.Cu")
		(net "P3E_CPU0_PE3_OCP_RXP<5>")
	)
	(segment
		(start 445.88811 -44.722796)
		(end 445.88811 -43.731942)
		(width 0.1143)
		(layer "In4.Cu")
		(net "P3E_CPU0_PE3_OCP_RXP<5>")
	)
	(segment
		(start 423.5958 -46.7868)
		(end 423.2402 -46.7868)
		(width 0.1143)
		(layer "In4.Cu")
		(net "P3E_CPU0_PE3_OCP_RXP<5>")
	)
	(segment
		(start 390.226042 -45.3263)
		(end 388.537958 -45.3263)
		(width 0.1143)
		(layer "In4.Cu")
		(net "P3E_CPU0_PE3_OCP_RXP<5>")
	)
	(segment
		(start 296.096436 -97.678748)
		(end 295.80332 -97.509584)
		(width 0.0889)
		(layer "In4.Cu")
		(net "P3E_CPU0_PE3_OCP_RXP<5>")
	)
	(segment
		(start 331.244194 -55.70601)
		(end 321.237356 -70.251828)
		(width 0.1143)
		(layer "In4.Cu")
		(net "P3E_CPU0_PE3_OCP_RXP<5>")
	)
	(segment
		(start 347.529404 -54.604666)
		(end 340.394544 -54.604666)
		(width 0.1143)
		(layer "In4.Cu")
		(net "P3E_CPU0_PE3_OCP_RXP<5>")
	)
	(segment
		(start 435.793642 -43.20286)
		(end 435.556152 -43.44035)
		(width 0.1143)
		(layer "In4.Cu")
		(net "P3E_CPU0_PE3_OCP_RXP<5>")
	)
	(segment
		(start 304.405792 -90.97518)
		(end 304.405538 -90.975434)
		(width 0.0889)
		(layer "In4.Cu")
		(net "P3E_CPU0_PE3_OCP_RXP<5>")
	)
	(segment
		(start 316.298072 -82.177128)
		(end 310.591454 -87.883746)
		(width 0.1143)
		(layer "In4.Cu")
		(net "P3E_CPU0_PE3_OCP_RXP<5>")
	)
	(segment
		(start 295.296336 -96.2152)
		(end 295.29151 -96.223836)
		(width 0.0889)
		(layer "In4.Cu")
		(net "P3E_CPU0_PE3_OCP_RXP<5>")
	)
	(segment
		(start 306.54117 -89.916508)
		(end 306.54117 -89.988136)
		(width 0.0889)
		(layer "In4.Cu")
		(net "P3E_CPU0_PE3_OCP_RXP<5>")
	)
	(segment
		(start 365.045752 -46.062392)
		(end 360.062526 -49.316894)
		(width 0.1143)
		(layer "In4.Cu")
		(net "P3E_CPU0_PE3_OCP_RXP<5>")
	)
	(segment
		(start 446.37706 -44.83735)
		(end 446.002664 -44.83735)
		(width 0.1143)
		(layer "In4.Cu")
		(net "P3E_CPU0_PE3_OCP_RXP<5>")
	)
	(segment
		(start 423.8752 -46.5074)
		(end 423.5958 -46.7868)
		(width 0.1143)
		(layer "In4.Cu")
		(net "P3E_CPU0_PE3_OCP_RXP<5>")
	)
	(segment
		(start 407.418032 -49.0855)
		(end 406.089104 -47.756572)
		(width 0.1143)
		(layer "In4.Cu")
		(net "P3E_CPU0_PE3_OCP_RXP<5>")
	)
	(segment
		(start 297.008296 -93.252036)
		(end 297.004994 -93.257878)
		(width 0.0889)
		(layer "In4.Cu")
		(net "P3E_CPU0_PE3_OCP_RXP<5>")
	)
	(segment
		(start 368.388138 -40.190674)
		(end 367.025174 -41.553638)
		(width 0.1143)
		(layer "In4.Cu")
		(net "P3E_CPU0_PE3_OCP_RXP<5>")
	)
	(segment
		(start 296.175176 -97.657412)
		(end 296.096436 -97.678748)
		(width 0.0889)
		(layer "In4.Cu")
		(net "P3E_CPU0_PE3_OCP_RXP<5>")
	)
	(segment
		(start 386.387594 -43.395392)
		(end 380.732792 -43.395392)
		(width 0.1143)
		(layer "In4.Cu")
		(net "P3E_CPU0_PE3_OCP_RXP<5>")
	)
	(segment
		(start 420.516558 -47.916084)
		(end 419.707822 -48.72482)
		(width 0.1143)
		(layer "In4.Cu")
		(net "P3E_CPU0_PE3_OCP_RXP<5>")
	)
	(segment
		(start 422.110916 -47.916084)
		(end 420.516558 -47.916084)
		(width 0.1143)
		(layer "In4.Cu")
		(net "P3E_CPU0_PE3_OCP_RXP<5>")
	)
	(segment
		(start 308.290976 -88.8365)
		(end 307.621432 -88.8365)
		(width 0.1143)
		(layer "In4.Cu")
		(net "P3E_CPU0_PE3_OCP_RXP<5>")
	)
	(segment
		(start 425.730162 -45.732192)
		(end 424.211496 -45.732192)
		(width 0.1143)
		(layer "In4.Cu")
		(net "P3E_CPU0_PE3_OCP_RXP<5>")
	)
	(segment
		(start 305.346862 -90.3351)
		(end 304.994564 -90.48115)
		(width 0.0889)
		(layer "In4.Cu")
		(net "P3E_CPU0_PE3_OCP_RXP<5>")
	)
	(segment
		(start 380.732792 -43.395392)
		(end 380.3396 -43.0022)
		(width 0.1143)
		(layer "In4.Cu")
		(net "P3E_CPU0_PE3_OCP_RXP<5>")
	)
	(segment
		(start 393.357354 -44.66844)
		(end 390.883902 -44.66844)
		(width 0.1143)
		(layer "In4.Cu")
		(net "P3E_CPU0_PE3_OCP_RXP<5>")
	)
	(segment
		(start 340.014814 -54.224936)
		(end 334.500728 -54.224936)
		(width 0.1143)
		(layer "In4.Cu")
		(net "P3E_CPU0_PE3_OCP_RXP<5>")
	)
	(segment
		(start 400.66468 -46.700186)
		(end 397.685514 -46.700186)
		(width 0.1143)
		(layer "In4.Cu")
		(net "P3E_CPU0_PE3_OCP_RXP<5>")
	)
	(segment
		(start 306.556664 -89.901014)
		(end 306.54117 -89.916508)
		(width 0.0889)
		(layer "In4.Cu")
		(net "P3E_CPU0_PE3_OCP_RXP<5>")
	)
	(segment
		(start 301.823882 -91.470988)
		(end 301.791116 -91.470988)
		(width 0.0889)
		(layer "In4.Cu")
		(net "P3E_CPU0_PE3_OCP_RXP<5>")
	)
	(segment
		(start 367.025174 -44.08297)
		(end 365.045752 -46.062392)
		(width 0.1143)
		(layer "In4.Cu")
		(net "P3E_CPU0_PE3_OCP_RXP<5>")
	)
	(segment
		(start 413.536384 -48.72482)
		(end 413.175704 -49.0855)
		(width 0.1143)
		(layer "In4.Cu")
		(net "P3E_CPU0_PE3_OCP_RXP<5>")
	)
	(segment
		(start 295.29151 -96.223836)
		(end 295.28516 -96.234504)
		(width 0.0889)
		(layer "In4.Cu")
		(net "P3E_CPU0_PE3_OCP_RXP<5>")
	)
	(segment
		(start 387.124702 -44.1325)
		(end 386.387594 -43.395392)
		(width 0.1143)
		(layer "In4.Cu")
		(net "P3E_CPU0_PE3_OCP_RXP<5>")
	)
	(segment
		(start 446.002664 -44.83735)
		(end 445.88811 -44.722796)
		(width 0.1143)
		(layer "In4.Cu")
		(net "P3E_CPU0_PE3_OCP_RXP<5>")
	)
	(segment
		(start 423.2402 -46.7868)
		(end 422.110916 -47.916084)
		(width 0.1143)
		(layer "In4.Cu")
		(net "P3E_CPU0_PE3_OCP_RXP<5>")
	)
	(segment
		(start 388.537958 -45.3263)
		(end 387.344158 -44.1325)
		(width 0.1143)
		(layer "In4.Cu")
		(net "P3E_CPU0_PE3_OCP_RXP<5>")
	)
	(segment
		(start 424.211496 -45.732192)
		(end 423.8752 -46.068488)
		(width 0.1143)
		(layer "In4.Cu")
		(net "P3E_CPU0_PE3_OCP_RXP<5>")
	)
	(segment
		(start 419.707822 -48.72482)
		(end 413.536384 -48.72482)
		(width 0.1143)
		(layer "In4.Cu")
		(net "P3E_CPU0_PE3_OCP_RXP<5>")
	)
	(segment
		(start 426.882052 -45.110908)
		(end 426.351446 -45.110908)
		(width 0.1143)
		(layer "In4.Cu")
		(net "P3E_CPU0_PE3_OCP_RXP<5>")
	)
	(segment
		(start 298.389802 -92.461588)
		(end 298.357036 -92.461588)
		(width 0.0889)
		(layer "In4.Cu")
		(net "P3E_CPU0_PE3_OCP_RXP<5>")
	)
	(segment
		(start 304.769012 -90.706448)
		(end 304.732182 -90.779854)
		(width 0.0889)
		(layer "In4.Cu")
		(net "P3E_CPU0_PE3_OCP_RXP<5>")
	)
	(segment
		(start 360.062526 -49.316894)
		(end 351.588578 -51.7144)
		(width 0.1143)
		(layer "In4.Cu")
		(net "P3E_CPU0_PE3_OCP_RXP<5>")
	)
	(segment
		(start 375.177558 -41.3639)
		(end 374.37441 -41.3639)
		(width 0.1143)
		(layer "In4.Cu")
		(net "P3E_CPU0_PE3_OCP_RXP<5>")
	)
	(segment
		(start 367.025174 -41.553638)
		(end 367.025174 -44.08297)
		(width 0.1143)
		(layer "In4.Cu")
		(net "P3E_CPU0_PE3_OCP_RXP<5>")
	)
	(segment
		(start 373.201184 -40.190674)
		(end 368.388138 -40.190674)
		(width 0.1143)
		(layer "In4.Cu")
		(net "P3E_CPU0_PE3_OCP_RXP<5>")
	)
	(segment
		(start 393.756388 -45.067474)
		(end 393.357354 -44.66844)
		(width 0.1143)
		(layer "In4.Cu")
		(net "P3E_CPU0_PE3_OCP_RXP<5>")
	)
	(segment
		(start 295.78173 -97.109534)
		(end 295.814496 -97.109534)
		(width 0.0889)
		(layer "In4.Cu")
		(net "P3E_CPU0_PE3_OCP_RXP<5>")
	)
	(segment
		(start 390.883902 -44.66844)
		(end 390.226042 -45.3263)
		(width 0.1143)
		(layer "In4.Cu")
		(net "P3E_CPU0_PE3_OCP_RXP<5>")
	)
	(segment
		(start 306.54117 -89.988136)
		(end 306.194206 -90.3351)
		(width 0.0889)
		(layer "In4.Cu")
		(net "P3E_CPU0_PE3_OCP_RXP<5>")
	)
	(segment
		(start 351.588578 -51.7144)
		(end 347.529404 -54.604666)
		(width 0.1143)
		(layer "In4.Cu")
		(net "P3E_CPU0_PE3_OCP_RXP<5>")
	)
	(segment
		(start 413.175704 -49.0855)
		(end 407.418032 -49.0855)
		(width 0.1143)
		(layer "In4.Cu")
		(net "P3E_CPU0_PE3_OCP_RXP<5>")
	)
	(segment
		(start 435.556152 -43.44035)
		(end 428.55261 -43.44035)
		(width 0.1143)
		(layer "In4.Cu")
		(net "P3E_CPU0_PE3_OCP_RXP<5>")
	)
	(segment
		(start 300.969172 -91.966034)
		(end 300.936406 -91.966034)
		(width 0.0889)
		(layer "In4.Cu")
		(net "P3E_CPU0_PE3_OCP_RXP<5>")
	)
	(segment
		(start 445.88811 -43.731942)
		(end 445.359028 -43.20286)
		(width 0.1143)
		(layer "In4.Cu")
		(net "P3E_CPU0_PE3_OCP_RXP<5>")
	)
	(segment
		(start 380.3396 -43.0022)
		(end 376.815858 -43.0022)
		(width 0.1143)
		(layer "In4.Cu")
		(net "P3E_CPU0_PE3_OCP_RXP<5>")
	)
	(segment
		(start 401.721066 -47.756572)
		(end 400.66468 -46.700186)
		(width 0.1143)
		(layer "In4.Cu")
		(net "P3E_CPU0_PE3_OCP_RXP<5>")
	)
	(segment
		(start 406.089104 -47.756572)
		(end 401.721066 -47.756572)
		(width 0.1143)
		(layer "In4.Cu")
		(net "P3E_CPU0_PE3_OCP_RXP<5>")
	)
	(segment
		(start 296.66184 -93.452188)
		(end 296.64025 -93.452188)
		(width 0.0889)
		(layer "In4.Cu")
		(net "P3E_CPU0_PE3_OCP_RXP<5>")
	)
	(segment
		(start 428.55261 -43.44035)
		(end 426.882052 -45.110908)
		(width 0.1143)
		(layer "In4.Cu")
		(net "P3E_CPU0_PE3_OCP_RXP<5>")
	)
	(segment
		(start 426.351446 -45.110908)
		(end 425.730162 -45.732192)
		(width 0.1143)
		(layer "In4.Cu")
		(net "P3E_CPU0_PE3_OCP_RXP<5>")
	)
	(segment
		(start 295.28516 -94.822518)
		(end 295.29151 -94.833186)
		(width 0.0889)
		(layer "In4.Cu")
		(net "P3E_CPU0_PE3_OCP_RXP<5>")
	)
	(segment
		(start 423.8752 -46.068488)
		(end 423.8752 -46.5074)
		(width 0.1143)
		(layer "In4.Cu")
		(net "P3E_CPU0_PE3_OCP_RXP<5>")
	)
	(segment
		(start 310.591454 -87.883746)
		(end 308.290976 -88.8365)
		(width 0.1143)
		(layer "In4.Cu")
		(net "P3E_CPU0_PE3_OCP_RXP<5>")
	)
	(segment
		(start 332.526894 -54.856888)
		(end 331.244194 -55.70601)
		(width 0.1143)
		(layer "In4.Cu")
		(net "P3E_CPU0_PE3_OCP_RXP<5>")
	)
	(segment
		(start 374.37441 -41.3639)
		(end 373.201184 -40.190674)
		(width 0.1143)
		(layer "In4.Cu")
		(net "P3E_CPU0_PE3_OCP_RXP<5>")
	)
	(segment
		(start 306.194206 -90.3351)
		(end 305.346862 -90.3351)
		(width 0.0889)
		(layer "In4.Cu")
		(net "P3E_CPU0_PE3_OCP_RXP<5>")
	)
	(segment
		(start 340.394544 -54.604666)
		(end 340.014814 -54.224936)
		(width 0.1143)
		(layer "In4.Cu")
		(net "P3E_CPU0_PE3_OCP_RXP<5>")
	)
	(segment
		(start 297.535092 -92.956634)
		(end 297.502326 -92.956634)
		(width 0.0889)
		(layer "In4.Cu")
		(net "P3E_CPU0_PE3_OCP_RXP<5>")
	)
	(segment
		(start 304.994564 -90.48115)
		(end 304.769012 -90.706448)
		(width 0.0889)
		(layer "In4.Cu")
		(net "P3E_CPU0_PE3_OCP_RXP<5>")
	)
	(segment
		(start 387.344158 -44.1325)
		(end 387.124702 -44.1325)
		(width 0.1143)
		(layer "In4.Cu")
		(net "P3E_CPU0_PE3_OCP_RXP<5>")
	)
	(segment
		(start 304.405538 -90.975434)
		(end 304.37455 -90.975434)
		(width 0.0889)
		(layer "In4.Cu")
		(net "P3E_CPU0_PE3_OCP_RXP<5>")
	)
	(segment
		(start 396.794228 -45.8089)
		(end 395.107414 -45.8089)
		(width 0.1143)
		(layer "In4.Cu")
		(net "P3E_CPU0_PE3_OCP_RXP<5>")
	)
	(segment
		(start 397.685514 -46.700186)
		(end 396.794228 -45.8089)
		(width 0.1143)
		(layer "In4.Cu")
		(net "P3E_CPU0_PE3_OCP_RXP<5>")
	)
	(segment
		(start 394.365988 -45.067474)
		(end 393.756388 -45.067474)
		(width 0.1143)
		(layer "In4.Cu")
		(net "P3E_CPU0_PE3_OCP_RXP<5>")
	)
	(segment
		(start 307.621432 -88.8365)
		(end 306.556664 -89.901014)
		(width 0.1143)
		(layer "In4.Cu")
		(net "P3E_CPU0_PE3_OCP_RXP<5>")
	)
	(segment
		(start 321.237356 -70.251828)
		(end 316.298072 -82.177128)
		(width 0.1143)
		(layer "In4.Cu")
		(net "P3E_CPU0_PE3_OCP_RXP<5>")
	)
	(segment
		(start 445.359028 -43.20286)
		(end 435.793642 -43.20286)
		(width 0.1143)
		(layer "In4.Cu")
		(net "P3E_CPU0_PE3_OCP_RXP<5>")
	)
	(segment
		(start 334.500728 -54.224936)
		(end 332.526894 -54.856888)
		(width 0.1143)
		(layer "In4.Cu")
		(net "P3E_CPU0_PE3_OCP_RXP<5>")
	)
	(segment
		(start 376.815858 -43.0022)
		(end 375.177558 -41.3639)
		(width 0.1143)
		(layer "In4.Cu")
		(net "P3E_CPU0_PE3_OCP_RXP<5>")
	)
	(segment
		(start 295.818306 -93.947234)
		(end 295.790366 -93.947234)
		(width 0.0889)
		(layer "In4.Cu")
		(net "P3E_CPU0_PE3_OCP_RXP<5>")
	)
	(segment
		(start 395.107414 -45.8089)
		(end 394.365988 -45.067474)
		(width 0.1143)
		(layer "In4.Cu")
		(net "P3E_CPU0_PE3_OCP_RXP<5>")
	)
	(arc
		(start 295.29151 -95.232982)
		(mid 295.212379 -95.528384)
		(end 295.29151 -95.823786)
		(width 0.0889)
		(layer "In4.Cu")
		(net "P3E_CPU0_PE3_OCP_RXP<5>")
	)
	(arc
		(start 298.725336 -92.261436)
		(mid 298.583653 -92.40524)
		(end 298.389802 -92.461588)
		(width 0.0889)
		(layer "In4.Cu")
		(net "P3E_CPU0_PE3_OCP_RXP<5>")
	)
	(arc
		(start 295.29151 -95.823786)
		(mid 295.34498 -96.018849)
		(end 295.296336 -96.2152)
		(width 0.0889)
		(layer "In4.Cu")
		(net "P3E_CPU0_PE3_OCP_RXP<5>")
	)
	(arc
		(start 296.15003 -93.747336)
		(mid 296.009951 -93.890072)
		(end 295.818306 -93.947234)
		(width 0.0889)
		(layer "In4.Cu")
		(net "P3E_CPU0_PE3_OCP_RXP<5>")
	)
	(arc
		(start 301.791116 -91.470988)
		(mid 301.507899 -91.555269)
		(end 301.300896 -91.766136)
		(width 0.0889)
		(layer "In4.Cu")
		(net "P3E_CPU0_PE3_OCP_RXP<5>")
	)
	(arc
		(start 296.64025 -93.452188)
		(mid 296.357033 -93.536469)
		(end 296.15003 -93.747336)
		(width 0.0889)
		(layer "In4.Cu")
		(net "P3E_CPU0_PE3_OCP_RXP<5>")
	)
	(arc
		(start 295.29151 -94.833186)
		(mid 295.345009 -95.033084)
		(end 295.29151 -95.232982)
		(width 0.0889)
		(layer "In4.Cu")
		(net "P3E_CPU0_PE3_OCP_RXP<5>")
	)
	(arc
		(start 295.790366 -93.947234)
		(mid 295.291485 -94.242671)
		(end 295.28516 -94.822518)
		(width 0.0889)
		(layer "In4.Cu")
		(net "P3E_CPU0_PE3_OCP_RXP<5>")
	)
	(arc
		(start 303.183036 -91.270836)
		(mid 302.671226 -90.975169)
		(end 302.159416 -91.270836)
		(width 0.0889)
		(layer "In4.Cu")
		(net "P3E_CPU0_PE3_OCP_RXP<5>")
	)
	(arc
		(start 300.936406 -91.966034)
		(mid 300.650982 -92.049501)
		(end 300.442376 -92.261436)
		(width 0.0889)
		(layer "In4.Cu")
		(net "P3E_CPU0_PE3_OCP_RXP<5>")
	)
	(arc
		(start 303.876456 -91.270836)
		(mid 303.529746 -91.471147)
		(end 303.183036 -91.270836)
		(width 0.0889)
		(layer "In4.Cu")
		(net "P3E_CPU0_PE3_OCP_RXP<5>")
	)
	(arc
		(start 304.732182 -90.779854)
		(mid 304.593669 -90.918743)
		(end 304.405792 -90.97518)
		(width 0.0889)
		(layer "In4.Cu")
		(net "P3E_CPU0_PE3_OCP_RXP<5>")
	)
	(arc
		(start 295.814496 -97.109534)
		(mid 296.137381 -97.289575)
		(end 296.175176 -97.657412)
		(width 0.0889)
		(layer "In4.Cu")
		(net "P3E_CPU0_PE3_OCP_RXP<5>")
	)
	(arc
		(start 297.866816 -92.756736)
		(mid 297.726737 -92.899472)
		(end 297.535092 -92.956634)
		(width 0.0889)
		(layer "In4.Cu")
		(net "P3E_CPU0_PE3_OCP_RXP<5>")
	)
	(arc
		(start 295.28516 -96.234504)
		(mid 295.289191 -96.810686)
		(end 295.78173 -97.109534)
		(width 0.0889)
		(layer "In4.Cu")
		(net "P3E_CPU0_PE3_OCP_RXP<5>")
	)
	(arc
		(start 304.37455 -90.975434)
		(mid 304.086863 -91.057955)
		(end 303.876456 -91.270836)
		(width 0.0889)
		(layer "In4.Cu")
		(net "P3E_CPU0_PE3_OCP_RXP<5>")
	)
	(arc
		(start 297.502326 -92.956634)
		(mid 297.216902 -93.040101)
		(end 297.008296 -93.252036)
		(width 0.0889)
		(layer "In4.Cu")
		(net "P3E_CPU0_PE3_OCP_RXP<5>")
	)
	(arc
		(start 299.748956 -92.261436)
		(mid 299.237146 -91.965769)
		(end 298.725336 -92.261436)
		(width 0.0889)
		(layer "In4.Cu")
		(net "P3E_CPU0_PE3_OCP_RXP<5>")
	)
	(arc
		(start 301.300896 -91.766136)
		(mid 301.160817 -91.908872)
		(end 300.969172 -91.966034)
		(width 0.0889)
		(layer "In4.Cu")
		(net "P3E_CPU0_PE3_OCP_RXP<5>")
	)
	(arc
		(start 297.004994 -93.257878)
		(mid 296.859028 -93.400277)
		(end 296.66184 -93.452188)
		(width 0.0889)
		(layer "In4.Cu")
		(net "P3E_CPU0_PE3_OCP_RXP<5>")
	)
	(arc
		(start 298.357036 -92.461588)
		(mid 298.073819 -92.545869)
		(end 297.866816 -92.756736)
		(width 0.0889)
		(layer "In4.Cu")
		(net "P3E_CPU0_PE3_OCP_RXP<5>")
	)
	(arc
		(start 300.442376 -92.261436)
		(mid 300.095666 -92.461747)
		(end 299.748956 -92.261436)
		(width 0.0889)
		(layer "In4.Cu")
		(net "P3E_CPU0_PE3_OCP_RXP<5>")
	)
	(arc
		(start 302.159416 -91.270836)
		(mid 302.017733 -91.41464)
		(end 301.823882 -91.470988)
		(width 0.0889)
		(layer "In4.Cu")
		(net "P3E_CPU0_PE3_OCP_RXP<5>")
	)
	(segment
		(start 449.342002 -47.481998)
		(end 449.340986 -47.481998)
		(width 0.1143)
		(layer "F.Cu")
		(net "P3E_CPU0_PE3_OCP_RXP<4>")
	)
	(segment
		(start 449.0593 -45.022008)
		(end 449.0593 -45.9359)
		(width 0.1143)
		(layer "F.Cu")
		(net "P3E_CPU0_PE3_OCP_RXP<4>")
	)
	(segment
		(start 449.576952 -44.83735)
		(end 449.243958 -44.83735)
		(width 0.1143)
		(layer "F.Cu")
		(net "P3E_CPU0_PE3_OCP_RXP<4>")
	)
	(segment
		(start 294.3733 -97.014538)
		(end 294.9448 -97.014538)
		(width 0.1143)
		(layer "F.Cu")
		(net "P3E_CPU0_PE3_OCP_RXP<4>")
	)
	(segment
		(start 449.342002 -46.218602)
		(end 449.342002 -47.481998)
		(width 0.1143)
		(layer "F.Cu")
		(net "P3E_CPU0_PE3_OCP_RXP<4>")
	)
	(segment
		(start 449.0593 -45.9359)
		(end 449.342002 -46.218602)
		(width 0.1143)
		(layer "F.Cu")
		(net "P3E_CPU0_PE3_OCP_RXP<4>")
	)
	(segment
		(start 449.243958 -44.83735)
		(end 449.0593 -45.022008)
		(width 0.1143)
		(layer "F.Cu")
		(net "P3E_CPU0_PE3_OCP_RXP<4>")
	)
	(via
		(at 294.9448 -97.014538)
		(size 0.508)
		(drill 0.254)
		(layers "F.Cu" "B.Cu")
		(net "P3E_CPU0_PE3_OCP_RXP<4>")
	)
	(via
		(at 449.576952 -44.83735)
		(size 0.508)
		(drill 0.254)
		(layers "F.Cu" "B.Cu")
		(net "P3E_CPU0_PE3_OCP_RXP<4>")
	)
	(segment
		(start 308.754272 -88.198452)
		(end 308.564026 -88.270842)
		(width 0.0889)
		(layer "In4.Cu")
		(net "P3E_CPU0_PE3_OCP_RXP<4>")
	)
	(segment
		(start 449.088002 -44.951904)
		(end 449.088002 -45.970698)
		(width 0.1143)
		(layer "In4.Cu")
		(net "P3E_CPU0_PE3_OCP_RXP<4>")
	)
	(segment
		(start 428.01032 -42.99712)
		(end 428.01032 -43.492166)
		(width 0.1143)
		(layer "In4.Cu")
		(net "P3E_CPU0_PE3_OCP_RXP<4>")
	)
	(segment
		(start 294.96766 -97.329752)
		(end 294.96766 -97.037398)
		(width 0.0889)
		(layer "In4.Cu")
		(net "P3E_CPU0_PE3_OCP_RXP<4>")
	)
	(segment
		(start 399.819622 -45.21708)
		(end 398.559274 -45.21708)
		(width 0.1143)
		(layer "In4.Cu")
		(net "P3E_CPU0_PE3_OCP_RXP<4>")
	)
	(segment
		(start 309.000398 -88.001348)
		(end 308.885082 -88.041988)
		(width 0.0889)
		(layer "In4.Cu")
		(net "P3E_CPU0_PE3_OCP_RXP<4>")
	)
	(segment
		(start 394.508228 -44.724574)
		(end 393.898628 -44.724574)
		(width 0.1143)
		(layer "In4.Cu")
		(net "P3E_CPU0_PE3_OCP_RXP<4>")
	)
	(segment
		(start 375.3612 -40.99052)
		(end 374.48617 -40.99052)
		(width 0.1143)
		(layer "In4.Cu")
		(net "P3E_CPU0_PE3_OCP_RXP<4>")
	)
	(segment
		(start 377.004834 -42.634154)
		(end 375.3612 -40.99052)
		(width 0.1143)
		(layer "In4.Cu")
		(net "P3E_CPU0_PE3_OCP_RXP<4>")
	)
	(segment
		(start 421.72001 -47.57039)
		(end 420.322502 -47.57039)
		(width 0.1143)
		(layer "In4.Cu")
		(net "P3E_CPU0_PE3_OCP_RXP<4>")
	)
	(segment
		(start 398.380712 -45.395642)
		(end 395.179296 -45.395642)
		(width 0.1143)
		(layer "In4.Cu")
		(net "P3E_CPU0_PE3_OCP_RXP<4>")
	)
	(segment
		(start 307.987446 -88.286082)
		(end 307.911246 -88.362282)
		(width 0.0889)
		(layer "In4.Cu")
		(net "P3E_CPU0_PE3_OCP_RXP<4>")
	)
	(segment
		(start 448.6529 -46.4058)
		(end 447.7512 -46.4058)
		(width 0.1143)
		(layer "In4.Cu")
		(net "P3E_CPU0_PE3_OCP_RXP<4>")
	)
	(segment
		(start 366.615218 -41.426638)
		(end 366.615218 -43.086528)
		(width 0.1143)
		(layer "In4.Cu")
		(net "P3E_CPU0_PE3_OCP_RXP<4>")
	)
	(segment
		(start 294.886888 -97.410524)
		(end 294.96766 -97.329752)
		(width 0.0889)
		(layer "In4.Cu")
		(net "P3E_CPU0_PE3_OCP_RXP<4>")
	)
	(segment
		(start 359.71734 -49.05121)
		(end 351.570036 -51.297586)
		(width 0.1143)
		(layer "In4.Cu")
		(net "P3E_CPU0_PE3_OCP_RXP<4>")
	)
	(segment
		(start 310.126126 -87.659464)
		(end 309.086504 -88.025224)
		(width 0.1143)
		(layer "In4.Cu")
		(net "P3E_CPU0_PE3_OCP_RXP<4>")
	)
	(segment
		(start 402.004784 -47.402242)
		(end 399.819622 -45.21708)
		(width 0.1143)
		(layer "In4.Cu")
		(net "P3E_CPU0_PE3_OCP_RXP<4>")
	)
	(segment
		(start 297.541696 -92.156534)
		(end 297.520106 -92.156534)
		(width 0.0889)
		(layer "In4.Cu")
		(net "P3E_CPU0_PE3_OCP_RXP<4>")
	)
	(segment
		(start 413.394144 -48.38192)
		(end 413.033464 -48.7426)
		(width 0.1143)
		(layer "In4.Cu")
		(net "P3E_CPU0_PE3_OCP_RXP<4>")
	)
	(segment
		(start 294.59809 -96.223836)
		(end 294.60444 -96.234504)
		(width 0.0889)
		(layer "In4.Cu")
		(net "P3E_CPU0_PE3_OCP_RXP<4>")
	)
	(segment
		(start 308.246526 -88.286082)
		(end 307.987446 -88.286082)
		(width 0.0889)
		(layer "In4.Cu")
		(net "P3E_CPU0_PE3_OCP_RXP<4>")
	)
	(segment
		(start 305.054 -89.789)
		(end 304.667666 -90.175334)
		(width 0.0889)
		(layer "In4.Cu")
		(net "P3E_CPU0_PE3_OCP_RXP<4>")
	)
	(segment
		(start 420.322502 -47.57039)
		(end 419.510972 -48.38192)
		(width 0.1143)
		(layer "In4.Cu")
		(net "P3E_CPU0_PE3_OCP_RXP<4>")
	)
	(segment
		(start 295.82491 -93.147134)
		(end 295.792144 -93.147134)
		(width 0.0889)
		(layer "In4.Cu")
		(net "P3E_CPU0_PE3_OCP_RXP<4>")
	)
	(segment
		(start 305.60772 -89.789)
		(end 305.53152 -89.8652)
		(width 0.0889)
		(layer "In4.Cu")
		(net "P3E_CPU0_PE3_OCP_RXP<4>")
	)
	(segment
		(start 305.308 -89.8652)
		(end 305.2318 -89.789)
		(width 0.0889)
		(layer "In4.Cu")
		(net "P3E_CPU0_PE3_OCP_RXP<4>")
	)
	(segment
		(start 310.66613 -87.308182)
		(end 310.126126 -87.659464)
		(width 0.1143)
		(layer "In4.Cu")
		(net "P3E_CPU0_PE3_OCP_RXP<4>")
	)
	(segment
		(start 296.67962 -92.652088)
		(end 296.646854 -92.652088)
		(width 0.0889)
		(layer "In4.Cu")
		(net "P3E_CPU0_PE3_OCP_RXP<4>")
	)
	(segment
		(start 298.396406 -91.661488)
		(end 298.36364 -91.661488)
		(width 0.0889)
		(layer "In4.Cu")
		(net "P3E_CPU0_PE3_OCP_RXP<4>")
	)
	(segment
		(start 422.9862 -46.101)
		(end 422.9862 -46.3042)
		(width 0.1143)
		(layer "In4.Cu")
		(net "P3E_CPU0_PE3_OCP_RXP<4>")
	)
	(segment
		(start 297.176952 -92.350844)
		(end 297.17365 -92.356686)
		(width 0.0889)
		(layer "In4.Cu")
		(net "P3E_CPU0_PE3_OCP_RXP<4>")
	)
	(segment
		(start 435.54904 -42.85996)
		(end 435.31155 -43.09745)
		(width 0.1143)
		(layer "In4.Cu")
		(net "P3E_CPU0_PE3_OCP_RXP<4>")
	)
	(segment
		(start 308.564026 -88.270842)
		(end 308.436264 -88.213692)
		(width 0.0889)
		(layer "In4.Cu")
		(net "P3E_CPU0_PE3_OCP_RXP<4>")
	)
	(segment
		(start 379.753114 -42.634154)
		(end 377.004834 -42.634154)
		(width 0.1143)
		(layer "In4.Cu")
		(net "P3E_CPU0_PE3_OCP_RXP<4>")
	)
	(segment
		(start 393.499594 -44.32554)
		(end 388.022338 -44.32554)
		(width 0.1143)
		(layer "In4.Cu")
		(net "P3E_CPU0_PE3_OCP_RXP<4>")
	)
	(segment
		(start 413.033464 -48.7426)
		(end 407.581608 -48.7426)
		(width 0.1143)
		(layer "In4.Cu")
		(net "P3E_CPU0_PE3_OCP_RXP<4>")
	)
	(segment
		(start 316.015624 -81.958688)
		(end 310.66613 -87.308182)
		(width 0.1143)
		(layer "In4.Cu")
		(net "P3E_CPU0_PE3_OCP_RXP<4>")
	)
	(segment
		(start 304.667666 -90.175334)
		(end 304.37709 -90.175334)
		(width 0.0889)
		(layer "In4.Cu")
		(net "P3E_CPU0_PE3_OCP_RXP<4>")
	)
	(segment
		(start 406.24125 -47.402242)
		(end 402.004784 -47.402242)
		(width 0.1143)
		(layer "In4.Cu")
		(net "P3E_CPU0_PE3_OCP_RXP<4>")
	)
	(segment
		(start 388.022338 -44.32554)
		(end 387.486398 -43.7896)
		(width 0.1143)
		(layer "In4.Cu")
		(net "P3E_CPU0_PE3_OCP_RXP<4>")
	)
	(segment
		(start 332.27518 -54.572662)
		(end 331.049122 -55.384192)
		(width 0.1143)
		(layer "In4.Cu")
		(net "P3E_CPU0_PE3_OCP_RXP<4>")
	)
	(segment
		(start 334.436974 -53.882036)
		(end 332.27518 -54.572662)
		(width 0.1143)
		(layer "In4.Cu")
		(net "P3E_CPU0_PE3_OCP_RXP<4>")
	)
	(segment
		(start 308.818534 -88.067896)
		(end 308.816248 -88.068658)
		(width 0.0889)
		(layer "In4.Cu")
		(net "P3E_CPU0_PE3_OCP_RXP<4>")
	)
	(segment
		(start 447.7512 -46.4058)
		(end 447.294 -45.9486)
		(width 0.1143)
		(layer "In4.Cu")
		(net "P3E_CPU0_PE3_OCP_RXP<4>")
	)
	(segment
		(start 366.615218 -43.086528)
		(end 362.43641 -47.265336)
		(width 0.1143)
		(layer "In4.Cu")
		(net "P3E_CPU0_PE3_OCP_RXP<4>")
	)
	(segment
		(start 426.782484 -44.720002)
		(end 426.234352 -44.720002)
		(width 0.1143)
		(layer "In4.Cu")
		(net "P3E_CPU0_PE3_OCP_RXP<4>")
	)
	(segment
		(start 302.68291 -90.175334)
		(end 302.659542 -90.175334)
		(width 0.0889)
		(layer "In4.Cu")
		(net "P3E_CPU0_PE3_OCP_RXP<4>")
	)
	(segment
		(start 305.880008 -89.789)
		(end 305.60772 -89.789)
		(width 0.0889)
		(layer "In4.Cu")
		(net "P3E_CPU0_PE3_OCP_RXP<4>")
	)
	(segment
		(start 419.510972 -48.38192)
		(end 413.394144 -48.38192)
		(width 0.1143)
		(layer "In4.Cu")
		(net "P3E_CPU0_PE3_OCP_RXP<4>")
	)
	(segment
		(start 407.581608 -48.7426)
		(end 406.24125 -47.402242)
		(width 0.1143)
		(layer "In4.Cu")
		(net "P3E_CPU0_PE3_OCP_RXP<4>")
	)
	(segment
		(start 428.01032 -43.492166)
		(end 426.782484 -44.720002)
		(width 0.1143)
		(layer "In4.Cu")
		(net "P3E_CPU0_PE3_OCP_RXP<4>")
	)
	(segment
		(start 300.975776 -91.165934)
		(end 300.94301 -91.165934)
		(width 0.0889)
		(layer "In4.Cu")
		(net "P3E_CPU0_PE3_OCP_RXP<4>")
	)
	(segment
		(start 309.086504 -88.025224)
		(end 309.065422 -88.032844)
		(width 0.0889)
		(layer "In4.Cu")
		(net "P3E_CPU0_PE3_OCP_RXP<4>")
	)
	(segment
		(start 449.202556 -44.83735)
		(end 449.088002 -44.951904)
		(width 0.1143)
		(layer "In4.Cu")
		(net "P3E_CPU0_PE3_OCP_RXP<4>")
	)
	(segment
		(start 447.294 -43.5356)
		(end 446.61836 -42.85996)
		(width 0.1143)
		(layer "In4.Cu")
		(net "P3E_CPU0_PE3_OCP_RXP<4>")
	)
	(segment
		(start 423.895266 -45.45711)
		(end 423.63009 -45.45711)
		(width 0.1143)
		(layer "In4.Cu")
		(net "P3E_CPU0_PE3_OCP_RXP<4>")
	)
	(segment
		(start 306.734972 -88.934036)
		(end 306.734972 -89.041732)
		(width 0.0889)
		(layer "In4.Cu")
		(net "P3E_CPU0_PE3_OCP_RXP<4>")
	)
	(segment
		(start 351.570036 -51.297586)
		(end 347.404944 -54.261766)
		(width 0.1143)
		(layer "In4.Cu")
		(net "P3E_CPU0_PE3_OCP_RXP<4>")
	)
	(segment
		(start 386.529834 -43.052492)
		(end 380.974092 -43.052492)
		(width 0.1143)
		(layer "In4.Cu")
		(net "P3E_CPU0_PE3_OCP_RXP<4>")
	)
	(segment
		(start 306.30749 -89.361518)
		(end 306.30749 -89.469214)
		(width 0.0889)
		(layer "In4.Cu")
		(net "P3E_CPU0_PE3_OCP_RXP<4>")
	)
	(segment
		(start 347.404944 -54.261766)
		(end 340.696804 -54.261766)
		(width 0.1143)
		(layer "In4.Cu")
		(net "P3E_CPU0_PE3_OCP_RXP<4>")
	)
	(segment
		(start 308.816248 -88.068658)
		(end 308.815232 -88.069166)
		(width 0.0889)
		(layer "In4.Cu")
		(net "P3E_CPU0_PE3_OCP_RXP<4>")
	)
	(segment
		(start 423.63009 -45.45711)
		(end 422.9862 -46.101)
		(width 0.1143)
		(layer "In4.Cu")
		(net "P3E_CPU0_PE3_OCP_RXP<4>")
	)
	(segment
		(start 430.06645 -43.09745)
		(end 429.2854 -42.3164)
		(width 0.1143)
		(layer "In4.Cu")
		(net "P3E_CPU0_PE3_OCP_RXP<4>")
	)
	(segment
		(start 309.065422 -88.032844)
		(end 309.000398 -88.001348)
		(width 0.0889)
		(layer "In4.Cu")
		(net "P3E_CPU0_PE3_OCP_RXP<4>")
	)
	(segment
		(start 368.194082 -39.847774)
		(end 366.615218 -41.426638)
		(width 0.1143)
		(layer "In4.Cu")
		(net "P3E_CPU0_PE3_OCP_RXP<4>")
	)
	(segment
		(start 294.96258 -93.642688)
		(end 294.929814 -93.642688)
		(width 0.0889)
		(layer "In4.Cu")
		(net "P3E_CPU0_PE3_OCP_RXP<4>")
	)
	(segment
		(start 447.294 -45.9486)
		(end 447.294 -43.5356)
		(width 0.1143)
		(layer "In4.Cu")
		(net "P3E_CPU0_PE3_OCP_RXP<4>")
	)
	(segment
		(start 308.820566 -88.06688)
		(end 308.818534 -88.067896)
		(width 0.0889)
		(layer "In4.Cu")
		(net "P3E_CPU0_PE3_OCP_RXP<4>")
	)
	(segment
		(start 423.89552 -45.456856)
		(end 423.895266 -45.45711)
		(width 0.1143)
		(layer "In4.Cu")
		(net "P3E_CPU0_PE3_OCP_RXP<4>")
	)
	(segment
		(start 307.586126 -88.286082)
		(end 307.382926 -88.286082)
		(width 0.0889)
		(layer "In4.Cu")
		(net "P3E_CPU0_PE3_OCP_RXP<4>")
	)
	(segment
		(start 305.53152 -89.8652)
		(end 305.308 -89.8652)
		(width 0.0889)
		(layer "In4.Cu")
		(net "P3E_CPU0_PE3_OCP_RXP<4>")
	)
	(segment
		(start 374.48617 -40.99052)
		(end 373.343424 -39.847774)
		(width 0.1143)
		(layer "In4.Cu")
		(net "P3E_CPU0_PE3_OCP_RXP<4>")
	)
	(segment
		(start 306.878482 -88.790526)
		(end 306.734972 -88.934036)
		(width 0.0889)
		(layer "In4.Cu")
		(net "P3E_CPU0_PE3_OCP_RXP<4>")
	)
	(segment
		(start 308.815232 -88.069166)
		(end 308.811422 -88.070436)
		(width 0.0889)
		(layer "In4.Cu")
		(net "P3E_CPU0_PE3_OCP_RXP<4>")
	)
	(segment
		(start 387.486398 -43.7896)
		(end 387.266942 -43.7896)
		(width 0.1143)
		(layer "In4.Cu")
		(net "P3E_CPU0_PE3_OCP_RXP<4>")
	)
	(segment
		(start 306.734972 -89.041732)
		(end 306.558696 -89.218008)
		(width 0.0889)
		(layer "In4.Cu")
		(net "P3E_CPU0_PE3_OCP_RXP<4>")
	)
	(segment
		(start 362.43641 -47.265336)
		(end 359.71734 -49.05121)
		(width 0.1143)
		(layer "In4.Cu")
		(net "P3E_CPU0_PE3_OCP_RXP<4>")
	)
	(segment
		(start 307.911246 -88.362282)
		(end 307.662326 -88.362282)
		(width 0.0889)
		(layer "In4.Cu")
		(net "P3E_CPU0_PE3_OCP_RXP<4>")
	)
	(segment
		(start 308.811422 -88.070436)
		(end 308.754272 -88.198452)
		(width 0.0889)
		(layer "In4.Cu")
		(net "P3E_CPU0_PE3_OCP_RXP<4>")
	)
	(segment
		(start 307.662326 -88.362282)
		(end 307.586126 -88.286082)
		(width 0.0889)
		(layer "In4.Cu")
		(net "P3E_CPU0_PE3_OCP_RXP<4>")
	)
	(segment
		(start 373.343424 -39.847774)
		(end 368.194082 -39.847774)
		(width 0.1143)
		(layer "In4.Cu")
		(net "P3E_CPU0_PE3_OCP_RXP<4>")
	)
	(segment
		(start 320.929762 -70.093586)
		(end 316.015624 -81.958688)
		(width 0.1143)
		(layer "In4.Cu")
		(net "P3E_CPU0_PE3_OCP_RXP<4>")
	)
	(segment
		(start 294.60444 -94.822518)
		(end 294.59809 -94.833186)
		(width 0.0889)
		(layer "In4.Cu")
		(net "P3E_CPU0_PE3_OCP_RXP<4>")
	)
	(segment
		(start 306.023518 -89.64549)
		(end 305.880008 -89.789)
		(width 0.0889)
		(layer "In4.Cu")
		(net "P3E_CPU0_PE3_OCP_RXP<4>")
	)
	(segment
		(start 306.451 -89.218008)
		(end 306.30749 -89.361518)
		(width 0.0889)
		(layer "In4.Cu")
		(net "P3E_CPU0_PE3_OCP_RXP<4>")
	)
	(segment
		(start 306.558696 -89.218008)
		(end 306.451 -89.218008)
		(width 0.0889)
		(layer "In4.Cu")
		(net "P3E_CPU0_PE3_OCP_RXP<4>")
	)
	(segment
		(start 307.162454 -88.61425)
		(end 306.986178 -88.790526)
		(width 0.0889)
		(layer "In4.Cu")
		(net "P3E_CPU0_PE3_OCP_RXP<4>")
	)
	(segment
		(start 294.593264 -94.234)
		(end 294.59809 -94.242636)
		(width 0.0889)
		(layer "In4.Cu")
		(net "P3E_CPU0_PE3_OCP_RXP<4>")
	)
	(segment
		(start 340.317074 -53.882036)
		(end 334.436974 -53.882036)
		(width 0.1143)
		(layer "In4.Cu")
		(net "P3E_CPU0_PE3_OCP_RXP<4>")
	)
	(segment
		(start 340.696804 -54.261766)
		(end 340.317074 -53.882036)
		(width 0.1143)
		(layer "In4.Cu")
		(net "P3E_CPU0_PE3_OCP_RXP<4>")
	)
	(segment
		(start 449.088002 -45.970698)
		(end 448.6529 -46.4058)
		(width 0.1143)
		(layer "In4.Cu")
		(net "P3E_CPU0_PE3_OCP_RXP<4>")
	)
	(segment
		(start 306.30749 -89.469214)
		(end 306.131214 -89.64549)
		(width 0.0889)
		(layer "In4.Cu")
		(net "P3E_CPU0_PE3_OCP_RXP<4>")
	)
	(segment
		(start 307.382926 -88.286082)
		(end 307.162454 -88.506554)
		(width 0.0889)
		(layer "In4.Cu")
		(net "P3E_CPU0_PE3_OCP_RXP<4>")
	)
	(segment
		(start 425.497498 -45.456856)
		(end 423.89552 -45.456856)
		(width 0.1143)
		(layer "In4.Cu")
		(net "P3E_CPU0_PE3_OCP_RXP<4>")
	)
	(segment
		(start 306.986178 -88.790526)
		(end 306.878482 -88.790526)
		(width 0.0889)
		(layer "In4.Cu")
		(net "P3E_CPU0_PE3_OCP_RXP<4>")
	)
	(segment
		(start 393.898628 -44.724574)
		(end 393.499594 -44.32554)
		(width 0.1143)
		(layer "In4.Cu")
		(net "P3E_CPU0_PE3_OCP_RXP<4>")
	)
	(segment
		(start 428.69104 -42.3164)
		(end 428.01032 -42.99712)
		(width 0.1143)
		(layer "In4.Cu")
		(net "P3E_CPU0_PE3_OCP_RXP<4>")
	)
	(segment
		(start 294.96766 -97.037398)
		(end 294.9448 -97.014538)
		(width 0.0889)
		(layer "In4.Cu")
		(net "P3E_CPU0_PE3_OCP_RXP<4>")
	)
	(segment
		(start 294.593264 -96.2152)
		(end 294.59809 -96.223836)
		(width 0.0889)
		(layer "In4.Cu")
		(net "P3E_CPU0_PE3_OCP_RXP<4>")
	)
	(segment
		(start 426.234352 -44.720002)
		(end 425.497498 -45.456856)
		(width 0.1143)
		(layer "In4.Cu")
		(net "P3E_CPU0_PE3_OCP_RXP<4>")
	)
	(segment
		(start 380.557278 -42.635678)
		(end 379.754638 -42.635678)
		(width 0.1143)
		(layer "In4.Cu")
		(net "P3E_CPU0_PE3_OCP_RXP<4>")
	)
	(segment
		(start 331.049122 -55.384192)
		(end 320.929762 -70.093586)
		(width 0.1143)
		(layer "In4.Cu")
		(net "P3E_CPU0_PE3_OCP_RXP<4>")
	)
	(segment
		(start 307.162454 -88.506554)
		(end 307.162454 -88.61425)
		(width 0.0889)
		(layer "In4.Cu")
		(net "P3E_CPU0_PE3_OCP_RXP<4>")
	)
	(segment
		(start 387.266942 -43.7896)
		(end 386.529834 -43.052492)
		(width 0.1143)
		(layer "In4.Cu")
		(net "P3E_CPU0_PE3_OCP_RXP<4>")
	)
	(segment
		(start 301.830486 -90.670888)
		(end 301.79772 -90.670888)
		(width 0.0889)
		(layer "In4.Cu")
		(net "P3E_CPU0_PE3_OCP_RXP<4>")
	)
	(segment
		(start 435.31155 -43.09745)
		(end 430.06645 -43.09745)
		(width 0.1143)
		(layer "In4.Cu")
		(net "P3E_CPU0_PE3_OCP_RXP<4>")
	)
	(segment
		(start 305.2318 -89.789)
		(end 305.054 -89.789)
		(width 0.0889)
		(layer "In4.Cu")
		(net "P3E_CPU0_PE3_OCP_RXP<4>")
	)
	(segment
		(start 308.436264 -88.213692)
		(end 308.246526 -88.286082)
		(width 0.0889)
		(layer "In4.Cu")
		(net "P3E_CPU0_PE3_OCP_RXP<4>")
	)
	(segment
		(start 449.576952 -44.83735)
		(end 449.202556 -44.83735)
		(width 0.1143)
		(layer "In4.Cu")
		(net "P3E_CPU0_PE3_OCP_RXP<4>")
	)
	(segment
		(start 395.179296 -45.395642)
		(end 394.508228 -44.724574)
		(width 0.1143)
		(layer "In4.Cu")
		(net "P3E_CPU0_PE3_OCP_RXP<4>")
	)
	(segment
		(start 306.131214 -89.64549)
		(end 306.023518 -89.64549)
		(width 0.0889)
		(layer "In4.Cu")
		(net "P3E_CPU0_PE3_OCP_RXP<4>")
	)
	(segment
		(start 380.974092 -43.052492)
		(end 380.557278 -42.635678)
		(width 0.1143)
		(layer "In4.Cu")
		(net "P3E_CPU0_PE3_OCP_RXP<4>")
	)
	(segment
		(start 429.2854 -42.3164)
		(end 428.69104 -42.3164)
		(width 0.1143)
		(layer "In4.Cu")
		(net "P3E_CPU0_PE3_OCP_RXP<4>")
	)
	(segment
		(start 379.754638 -42.635678)
		(end 379.753114 -42.634154)
		(width 0.1143)
		(layer "In4.Cu")
		(net "P3E_CPU0_PE3_OCP_RXP<4>")
	)
	(segment
		(start 398.559274 -45.21708)
		(end 398.380712 -45.395642)
		(width 0.1143)
		(layer "In4.Cu")
		(net "P3E_CPU0_PE3_OCP_RXP<4>")
	)
	(segment
		(start 422.9862 -46.3042)
		(end 421.72001 -47.57039)
		(width 0.1143)
		(layer "In4.Cu")
		(net "P3E_CPU0_PE3_OCP_RXP<4>")
	)
	(segment
		(start 446.61836 -42.85996)
		(end 435.54904 -42.85996)
		(width 0.1143)
		(layer "In4.Cu")
		(net "P3E_CPU0_PE3_OCP_RXP<4>")
	)
	(segment
		(start 308.885082 -88.041988)
		(end 308.820566 -88.06688)
		(width 0.0889)
		(layer "In4.Cu")
		(net "P3E_CPU0_PE3_OCP_RXP<4>")
	)
	(arc
		(start 298.031916 -91.861386)
		(mid 297.824912 -92.07225)
		(end 297.541696 -92.156534)
		(width 0.0889)
		(layer "In4.Cu")
		(net "P3E_CPU0_PE3_OCP_RXP<4>")
	)
	(arc
		(start 295.45661 -93.347286)
		(mid 295.248002 -93.559218)
		(end 294.96258 -93.642688)
		(width 0.0889)
		(layer "In4.Cu")
		(net "P3E_CPU0_PE3_OCP_RXP<4>")
	)
	(arc
		(start 298.36364 -91.661488)
		(mid 298.171998 -91.718654)
		(end 298.031916 -91.861386)
		(width 0.0889)
		(layer "In4.Cu")
		(net "P3E_CPU0_PE3_OCP_RXP<4>")
	)
	(arc
		(start 302.659542 -90.175334)
		(mid 302.465975 -90.231802)
		(end 302.324516 -90.375486)
		(width 0.0889)
		(layer "In4.Cu")
		(net "P3E_CPU0_PE3_OCP_RXP<4>")
	)
	(arc
		(start 294.929814 -93.642688)
		(mid 294.596896 -93.844679)
		(end 294.593264 -94.234)
		(width 0.0889)
		(layer "In4.Cu")
		(net "P3E_CPU0_PE3_OCP_RXP<4>")
	)
	(arc
		(start 303.017936 -90.375486)
		(mid 302.876471 -90.231812)
		(end 302.68291 -90.175334)
		(width 0.0889)
		(layer "In4.Cu")
		(net "P3E_CPU0_PE3_OCP_RXP<4>")
	)
	(arc
		(start 295.792144 -93.147134)
		(mid 295.598294 -93.203484)
		(end 295.45661 -93.347286)
		(width 0.0889)
		(layer "In4.Cu")
		(net "P3E_CPU0_PE3_OCP_RXP<4>")
	)
	(arc
		(start 294.59809 -95.823786)
		(mid 294.54462 -96.018849)
		(end 294.593264 -96.2152)
		(width 0.0889)
		(layer "In4.Cu")
		(net "P3E_CPU0_PE3_OCP_RXP<4>")
	)
	(arc
		(start 304.37709 -90.175334)
		(mid 304.18324 -90.231684)
		(end 304.041556 -90.375486)
		(width 0.0889)
		(layer "In4.Cu")
		(net "P3E_CPU0_PE3_OCP_RXP<4>")
	)
	(arc
		(start 301.79772 -90.670888)
		(mid 301.606078 -90.728054)
		(end 301.465996 -90.870786)
		(width 0.0889)
		(layer "In4.Cu")
		(net "P3E_CPU0_PE3_OCP_RXP<4>")
	)
	(arc
		(start 296.31513 -92.851986)
		(mid 296.108126 -93.06285)
		(end 295.82491 -93.147134)
		(width 0.0889)
		(layer "In4.Cu")
		(net "P3E_CPU0_PE3_OCP_RXP<4>")
	)
	(arc
		(start 300.94301 -91.165934)
		(mid 300.74916 -91.222284)
		(end 300.607476 -91.366086)
		(width 0.0889)
		(layer "In4.Cu")
		(net "P3E_CPU0_PE3_OCP_RXP<4>")
	)
	(arc
		(start 294.60444 -96.234504)
		(mid 294.677238 -96.525267)
		(end 294.59809 -96.814386)
		(width 0.0889)
		(layer "In4.Cu")
		(net "P3E_CPU0_PE3_OCP_RXP<4>")
	)
	(arc
		(start 294.59809 -94.242636)
		(mid 294.677312 -94.531754)
		(end 294.60444 -94.822518)
		(width 0.0889)
		(layer "In4.Cu")
		(net "P3E_CPU0_PE3_OCP_RXP<4>")
	)
	(arc
		(start 301.465996 -90.870786)
		(mid 301.258992 -91.08165)
		(end 300.975776 -91.165934)
		(width 0.0889)
		(layer "In4.Cu")
		(net "P3E_CPU0_PE3_OCP_RXP<4>")
	)
	(arc
		(start 298.890436 -91.366086)
		(mid 298.681828 -91.578018)
		(end 298.396406 -91.661488)
		(width 0.0889)
		(layer "In4.Cu")
		(net "P3E_CPU0_PE3_OCP_RXP<4>")
	)
	(arc
		(start 304.041556 -90.375486)
		(mid 303.529746 -90.67128)
		(end 303.017936 -90.375486)
		(width 0.0889)
		(layer "In4.Cu")
		(net "P3E_CPU0_PE3_OCP_RXP<4>")
	)
	(arc
		(start 294.59809 -95.232982)
		(mid 294.677221 -95.528384)
		(end 294.59809 -95.823786)
		(width 0.0889)
		(layer "In4.Cu")
		(net "P3E_CPU0_PE3_OCP_RXP<4>")
	)
	(arc
		(start 296.646854 -92.652088)
		(mid 296.455212 -92.709254)
		(end 296.31513 -92.851986)
		(width 0.0889)
		(layer "In4.Cu")
		(net "P3E_CPU0_PE3_OCP_RXP<4>")
	)
	(arc
		(start 302.324516 -90.375486)
		(mid 302.115908 -90.587418)
		(end 301.830486 -90.670888)
		(width 0.0889)
		(layer "In4.Cu")
		(net "P3E_CPU0_PE3_OCP_RXP<4>")
	)
	(arc
		(start 294.59809 -96.814386)
		(mid 294.584495 -97.189035)
		(end 294.886888 -97.410524)
		(width 0.0889)
		(layer "In4.Cu")
		(net "P3E_CPU0_PE3_OCP_RXP<4>")
	)
	(arc
		(start 294.59809 -94.833186)
		(mid 294.544591 -95.033084)
		(end 294.59809 -95.232982)
		(width 0.0889)
		(layer "In4.Cu")
		(net "P3E_CPU0_PE3_OCP_RXP<4>")
	)
	(arc
		(start 300.607476 -91.366086)
		(mid 300.095666 -91.661753)
		(end 299.583856 -91.366086)
		(width 0.0889)
		(layer "In4.Cu")
		(net "P3E_CPU0_PE3_OCP_RXP<4>")
	)
	(arc
		(start 297.17365 -92.356686)
		(mid 296.965042 -92.568618)
		(end 296.67962 -92.652088)
		(width 0.0889)
		(layer "In4.Cu")
		(net "P3E_CPU0_PE3_OCP_RXP<4>")
	)
	(arc
		(start 297.520106 -92.156534)
		(mid 297.322945 -92.208493)
		(end 297.176952 -92.350844)
		(width 0.0889)
		(layer "In4.Cu")
		(net "P3E_CPU0_PE3_OCP_RXP<4>")
	)
	(arc
		(start 299.583856 -91.366086)
		(mid 299.237146 -91.165775)
		(end 298.890436 -91.366086)
		(width 0.0889)
		(layer "In4.Cu")
		(net "P3E_CPU0_PE3_OCP_RXP<4>")
	)
	(segment
		(start 451.741032 -46.163484)
		(end 452.0057 -45.898816)
		(width 0.1143)
		(layer "F.Cu")
		(net "P3E_CPU0_PE3_OCP_RXP<3>")
	)
	(segment
		(start 292.65626 -98.005138)
		(end 293.22776 -98.005138)
		(width 0.1143)
		(layer "F.Cu")
		(net "P3E_CPU0_PE3_OCP_RXP<3>")
	)
	(segment
		(start 451.741032 -47.481998)
		(end 451.741032 -46.163484)
		(width 0.1143)
		(layer "F.Cu")
		(net "P3E_CPU0_PE3_OCP_RXP<3>")
	)
	(segment
		(start 452.0057 -45.898816)
		(end 452.0057 -45.002958)
		(width 0.1143)
		(layer "F.Cu")
		(net "P3E_CPU0_PE3_OCP_RXP<3>")
	)
	(segment
		(start 452.0057 -45.002958)
		(end 451.840092 -44.83735)
		(width 0.1143)
		(layer "F.Cu")
		(net "P3E_CPU0_PE3_OCP_RXP<3>")
	)
	(segment
		(start 451.840092 -44.83735)
		(end 451.507098 -44.83735)
		(width 0.1143)
		(layer "F.Cu")
		(net "P3E_CPU0_PE3_OCP_RXP<3>")
	)
	(via
		(at 451.507098 -44.83735)
		(size 0.508)
		(drill 0.254)
		(layers "F.Cu" "B.Cu")
		(net "P3E_CPU0_PE3_OCP_RXP<3>")
	)
	(via
		(at 293.22776 -98.005138)
		(size 0.508)
		(drill 0.254)
		(layers "F.Cu" "B.Cu")
		(net "P3E_CPU0_PE3_OCP_RXP<3>")
	)
	(segment
		(start 300.082712 -95.433134)
		(end 300.106842 -95.433134)
		(width 0.0889)
		(layer "In4.Cu")
		(net "P3E_CPU0_PE3_OCP_RXP<3>")
	)
	(segment
		(start 348.529402 -56.842406)
		(end 350.64192 -56.133238)
		(width 0.1143)
		(layer "In4.Cu")
		(net "P3E_CPU0_PE3_OCP_RXP<3>")
	)
	(segment
		(start 445.467994 -47.074582)
		(end 451.11416 -47.074582)
		(width 0.1143)
		(layer "In4.Cu")
		(net "P3E_CPU0_PE3_OCP_RXP<3>")
	)
	(segment
		(start 333.0702 -56.842406)
		(end 348.529402 -56.842406)
		(width 0.1143)
		(layer "In4.Cu")
		(net "P3E_CPU0_PE3_OCP_RXP<3>")
	)
	(segment
		(start 435.673246 -47.074582)
		(end 442.762894 -47.074582)
		(width 0.1143)
		(layer "In4.Cu")
		(net "P3E_CPU0_PE3_OCP_RXP<3>")
	)
	(segment
		(start 306.582572 -93.31071)
		(end 306.714652 -93.365574)
		(width 0.0889)
		(layer "In4.Cu")
		(net "P3E_CPU0_PE3_OCP_RXP<3>")
	)
	(segment
		(start 443.270894 -46.909482)
		(end 443.435994 -47.074582)
		(width 0.1143)
		(layer "In4.Cu")
		(net "P3E_CPU0_PE3_OCP_RXP<3>")
	)
	(segment
		(start 443.943994 -46.909482)
		(end 444.286894 -46.909482)
		(width 0.1143)
		(layer "In4.Cu")
		(net "P3E_CPU0_PE3_OCP_RXP<3>")
	)
	(segment
		(start 421.271954 -51.190144)
		(end 421.793162 -51.711352)
		(width 0.1143)
		(layer "In4.Cu")
		(net "P3E_CPU0_PE3_OCP_RXP<3>")
	)
	(segment
		(start 305.847242 -93.723714)
		(end 305.902106 -93.59138)
		(width 0.0889)
		(layer "In4.Cu")
		(net "P3E_CPU0_PE3_OCP_RXP<3>")
	)
	(segment
		(start 407.358596 -52.119784)
		(end 419.053264 -52.119784)
		(width 0.1143)
		(layer "In4.Cu")
		(net "P3E_CPU0_PE3_OCP_RXP<3>")
	)
	(segment
		(start 391.140696 -49.0855)
		(end 394.736828 -49.0855)
		(width 0.1143)
		(layer "In4.Cu")
		(net "P3E_CPU0_PE3_OCP_RXP<3>")
	)
	(segment
		(start 306.41798 -93.378528)
		(end 306.582572 -93.31071)
		(width 0.0889)
		(layer "In4.Cu")
		(net "P3E_CPU0_PE3_OCP_RXP<3>")
	)
	(segment
		(start 308.30266 -92.653866)
		(end 309.071518 -92.13977)
		(width 0.1143)
		(layer "In4.Cu")
		(net "P3E_CPU0_PE3_OCP_RXP<3>")
	)
	(segment
		(start 293.22776 -98.005138)
		(end 292.934644 -98.174048)
		(width 0.0889)
		(layer "In4.Cu")
		(net "P3E_CPU0_PE3_OCP_RXP<3>")
	)
	(segment
		(start 305.198526 -93.690186)
		(end 305.299618 -93.791278)
		(width 0.0889)
		(layer "In4.Cu")
		(net "P3E_CPU0_PE3_OCP_RXP<3>")
	)
	(segment
		(start 434.709062 -48.038766)
		(end 435.673246 -47.074582)
		(width 0.1143)
		(layer "In4.Cu")
		(net "P3E_CPU0_PE3_OCP_RXP<3>")
	)
	(segment
		(start 374.623838 -47.489364)
		(end 380.27356 -47.489364)
		(width 0.1143)
		(layer "In4.Cu")
		(net "P3E_CPU0_PE3_OCP_RXP<3>")
	)
	(segment
		(start 380.27356 -47.489364)
		(end 381.839724 -45.9232)
		(width 0.1143)
		(layer "In4.Cu")
		(net "P3E_CPU0_PE3_OCP_RXP<3>")
	)
	(segment
		(start 305.682904 -93.791278)
		(end 305.847242 -93.723714)
		(width 0.0889)
		(layer "In4.Cu")
		(net "P3E_CPU0_PE3_OCP_RXP<3>")
	)
	(segment
		(start 294.071294 -98.900234)
		(end 294.101266 -98.900234)
		(width 0.0889)
		(layer "In4.Cu")
		(net "P3E_CPU0_PE3_OCP_RXP<3>")
	)
	(segment
		(start 303.5173 -94.442788)
		(end 303.547272 -94.442788)
		(width 0.0889)
		(layer "In4.Cu")
		(net "P3E_CPU0_PE3_OCP_RXP<3>")
	)
	(segment
		(start 297.502326 -96.919034)
		(end 297.535092 -96.919034)
		(width 0.0889)
		(layer "In4.Cu")
		(net "P3E_CPU0_PE3_OCP_RXP<3>")
	)
	(segment
		(start 309.071518 -92.13977)
		(end 318.012064 -83.199224)
		(width 0.1143)
		(layer "In4.Cu")
		(net "P3E_CPU0_PE3_OCP_RXP<3>")
	)
	(segment
		(start 427.93285 -49.898046)
		(end 428.166022 -50.131218)
		(width 0.1143)
		(layer "In4.Cu")
		(net "P3E_CPU0_PE3_OCP_RXP<3>")
	)
	(segment
		(start 304.181256 -93.975682)
		(end 304.626264 -93.791278)
		(width 0.0889)
		(layer "In4.Cu")
		(net "P3E_CPU0_PE3_OCP_RXP<3>")
	)
	(segment
		(start 350.64192 -56.133238)
		(end 353.873816 -53.847238)
		(width 0.1143)
		(layer "In4.Cu")
		(net "P3E_CPU0_PE3_OCP_RXP<3>")
	)
	(segment
		(start 444.451994 -47.074582)
		(end 444.794894 -47.074582)
		(width 0.1143)
		(layer "In4.Cu")
		(net "P3E_CPU0_PE3_OCP_RXP<3>")
	)
	(segment
		(start 451.996048 -44.95165)
		(end 451.881748 -44.83735)
		(width 0.1143)
		(layer "In4.Cu")
		(net "P3E_CPU0_PE3_OCP_RXP<3>")
	)
	(segment
		(start 445.302894 -46.909482)
		(end 445.467994 -47.074582)
		(width 0.1143)
		(layer "In4.Cu")
		(net "P3E_CPU0_PE3_OCP_RXP<3>")
	)
	(segment
		(start 443.435994 -47.074582)
		(end 443.778894 -47.074582)
		(width 0.1143)
		(layer "In4.Cu")
		(net "P3E_CPU0_PE3_OCP_RXP<3>")
	)
	(segment
		(start 303.511712 -94.442534)
		(end 303.5173 -94.442788)
		(width 0.0889)
		(layer "In4.Cu")
		(net "P3E_CPU0_PE3_OCP_RXP<3>")
	)
	(segment
		(start 295.788334 -98.900234)
		(end 295.818306 -98.900234)
		(width 0.0889)
		(layer "In4.Cu")
		(net "P3E_CPU0_PE3_OCP_RXP<3>")
	)
	(segment
		(start 386.198364 -46.177454)
		(end 386.595112 -46.177454)
		(width 0.1143)
		(layer "In4.Cu")
		(net "P3E_CPU0_PE3_OCP_RXP<3>")
	)
	(segment
		(start 419.053264 -52.119784)
		(end 419.982904 -51.190144)
		(width 0.1143)
		(layer "In4.Cu")
		(net "P3E_CPU0_PE3_OCP_RXP<3>")
	)
	(segment
		(start 300.932596 -94.937834)
		(end 300.97222 -94.937834)
		(width 0.0889)
		(layer "In4.Cu")
		(net "P3E_CPU0_PE3_OCP_RXP<3>")
	)
	(segment
		(start 451.11416 -47.074582)
		(end 451.996048 -46.192694)
		(width 0.1143)
		(layer "In4.Cu")
		(net "P3E_CPU0_PE3_OCP_RXP<3>")
	)
	(segment
		(start 381.839724 -45.9232)
		(end 385.94411 -45.9232)
		(width 0.1143)
		(layer "In4.Cu")
		(net "P3E_CPU0_PE3_OCP_RXP<3>")
	)
	(segment
		(start 424.2435 -49.5935)
		(end 424.888914 -48.948086)
		(width 0.1143)
		(layer "In4.Cu")
		(net "P3E_CPU0_PE3_OCP_RXP<3>")
	)
	(segment
		(start 323.07022 -70.98665)
		(end 332.574138 -57.170574)
		(width 0.1143)
		(layer "In4.Cu")
		(net "P3E_CPU0_PE3_OCP_RXP<3>")
	)
	(segment
		(start 293.216584 -98.405188)
		(end 293.24935 -98.405188)
		(width 0.0889)
		(layer "In4.Cu")
		(net "P3E_CPU0_PE3_OCP_RXP<3>")
	)
	(segment
		(start 306.96408 -93.208094)
		(end 308.30266 -92.653866)
		(width 0.1143)
		(layer "In4.Cu")
		(net "P3E_CPU0_PE3_OCP_RXP<3>")
	)
	(segment
		(start 306.943506 -93.216476)
		(end 306.96408 -93.208094)
		(width 0.0889)
		(layer "In4.Cu")
		(net "P3E_CPU0_PE3_OCP_RXP<3>")
	)
	(segment
		(start 306.066698 -93.523562)
		(end 306.198778 -93.578426)
		(width 0.0889)
		(layer "In4.Cu")
		(net "P3E_CPU0_PE3_OCP_RXP<3>")
	)
	(segment
		(start 405.956262 -50.71745)
		(end 407.358596 -52.119784)
		(width 0.1143)
		(layer "In4.Cu")
		(net "P3E_CPU0_PE3_OCP_RXP<3>")
	)
	(segment
		(start 386.595112 -46.177454)
		(end 389.39216 -48.974502)
		(width 0.1143)
		(layer "In4.Cu")
		(net "P3E_CPU0_PE3_OCP_RXP<3>")
	)
	(segment
		(start 318.012064 -83.199224)
		(end 323.069966 -70.98665)
		(width 0.1143)
		(layer "In4.Cu")
		(net "P3E_CPU0_PE3_OCP_RXP<3>")
	)
	(segment
		(start 358.255062 -53.655722)
		(end 361.082844 -51.643534)
		(width 0.1143)
		(layer "In4.Cu")
		(net "P3E_CPU0_PE3_OCP_RXP<3>")
	)
	(segment
		(start 366.83061 -48.215804)
		(end 368.80673 -48.215804)
		(width 0.1143)
		(layer "In4.Cu")
		(net "P3E_CPU0_PE3_OCP_RXP<3>")
	)
	(segment
		(start 298.357036 -96.423988)
		(end 298.389802 -96.423988)
		(width 0.0889)
		(layer "In4.Cu")
		(net "P3E_CPU0_PE3_OCP_RXP<3>")
	)
	(segment
		(start 389.39216 -48.974502)
		(end 391.029698 -48.974502)
		(width 0.1143)
		(layer "In4.Cu")
		(net "P3E_CPU0_PE3_OCP_RXP<3>")
	)
	(segment
		(start 399.87474 -49.534318)
		(end 401.057872 -50.71745)
		(width 0.1143)
		(layer "In4.Cu")
		(net "P3E_CPU0_PE3_OCP_RXP<3>")
	)
	(segment
		(start 434.434234 -48.038766)
		(end 434.709062 -48.038766)
		(width 0.1143)
		(layer "In4.Cu")
		(net "P3E_CPU0_PE3_OCP_RXP<3>")
	)
	(segment
		(start 354.273612 -53.767482)
		(end 356.451916 -54.261004)
		(width 0.1143)
		(layer "In4.Cu")
		(net "P3E_CPU0_PE3_OCP_RXP<3>")
	)
	(segment
		(start 304.626264 -93.791278)
		(end 304.919634 -93.791278)
		(width 0.0889)
		(layer "In4.Cu")
		(net "P3E_CPU0_PE3_OCP_RXP<3>")
	)
	(segment
		(start 306.363116 -93.510862)
		(end 306.41798 -93.378528)
		(width 0.0889)
		(layer "In4.Cu")
		(net "P3E_CPU0_PE3_OCP_RXP<3>")
	)
	(segment
		(start 432.341782 -50.131218)
		(end 434.434234 -48.038766)
		(width 0.1143)
		(layer "In4.Cu")
		(net "P3E_CPU0_PE3_OCP_RXP<3>")
	)
	(segment
		(start 451.996048 -46.192694)
		(end 451.996048 -44.95165)
		(width 0.1143)
		(layer "In4.Cu")
		(net "P3E_CPU0_PE3_OCP_RXP<3>")
	)
	(segment
		(start 296.64025 -98.405188)
		(end 296.66184 -98.405188)
		(width 0.0889)
		(layer "In4.Cu")
		(net "P3E_CPU0_PE3_OCP_RXP<3>")
	)
	(segment
		(start 421.793162 -51.711352)
		(end 422.975278 -51.711352)
		(width 0.1143)
		(layer "In4.Cu")
		(net "P3E_CPU0_PE3_OCP_RXP<3>")
	)
	(segment
		(start 427.528736 -48.948086)
		(end 427.93285 -49.3522)
		(width 0.1143)
		(layer "In4.Cu")
		(net "P3E_CPU0_PE3_OCP_RXP<3>")
	)
	(segment
		(start 306.916328 -93.282516)
		(end 306.943506 -93.216476)
		(width 0.0889)
		(layer "In4.Cu")
		(net "P3E_CPU0_PE3_OCP_RXP<3>")
	)
	(segment
		(start 305.902106 -93.59138)
		(end 306.066698 -93.523562)
		(width 0.0889)
		(layer "In4.Cu")
		(net "P3E_CPU0_PE3_OCP_RXP<3>")
	)
	(segment
		(start 401.057872 -50.71745)
		(end 405.956262 -50.71745)
		(width 0.1143)
		(layer "In4.Cu")
		(net "P3E_CPU0_PE3_OCP_RXP<3>")
	)
	(segment
		(start 370.36121 -46.661324)
		(end 373.795798 -46.661324)
		(width 0.1143)
		(layer "In4.Cu")
		(net "P3E_CPU0_PE3_OCP_RXP<3>")
	)
	(segment
		(start 373.795798 -46.661324)
		(end 374.623838 -47.489364)
		(width 0.1143)
		(layer "In4.Cu")
		(net "P3E_CPU0_PE3_OCP_RXP<3>")
	)
	(segment
		(start 323.069966 -70.98665)
		(end 323.07022 -70.98665)
		(width 0.1143)
		(layer "In4.Cu")
		(net "P3E_CPU0_PE3_OCP_RXP<3>")
	)
	(segment
		(start 444.794894 -47.074582)
		(end 444.959994 -46.909482)
		(width 0.1143)
		(layer "In4.Cu")
		(net "P3E_CPU0_PE3_OCP_RXP<3>")
	)
	(segment
		(start 444.959994 -46.909482)
		(end 445.302894 -46.909482)
		(width 0.1143)
		(layer "In4.Cu")
		(net "P3E_CPU0_PE3_OCP_RXP<3>")
	)
	(segment
		(start 305.299618 -93.791278)
		(end 305.682904 -93.791278)
		(width 0.0889)
		(layer "In4.Cu")
		(net "P3E_CPU0_PE3_OCP_RXP<3>")
	)
	(segment
		(start 428.166022 -50.131218)
		(end 432.341782 -50.131218)
		(width 0.1143)
		(layer "In4.Cu")
		(net "P3E_CPU0_PE3_OCP_RXP<3>")
	)
	(segment
		(start 299.219366 -95.928434)
		(end 299.252132 -95.928434)
		(width 0.0889)
		(layer "In4.Cu")
		(net "P3E_CPU0_PE3_OCP_RXP<3>")
	)
	(segment
		(start 368.80673 -48.215804)
		(end 370.36121 -46.661324)
		(width 0.1143)
		(layer "In4.Cu")
		(net "P3E_CPU0_PE3_OCP_RXP<3>")
	)
	(segment
		(start 394.736828 -49.0855)
		(end 395.185646 -49.534318)
		(width 0.1143)
		(layer "In4.Cu")
		(net "P3E_CPU0_PE3_OCP_RXP<3>")
	)
	(segment
		(start 444.286894 -46.909482)
		(end 444.451994 -47.074582)
		(width 0.1143)
		(layer "In4.Cu")
		(net "P3E_CPU0_PE3_OCP_RXP<3>")
	)
	(segment
		(start 385.94411 -45.9232)
		(end 386.198364 -46.177454)
		(width 0.1143)
		(layer "In4.Cu")
		(net "P3E_CPU0_PE3_OCP_RXP<3>")
	)
	(segment
		(start 419.982904 -51.190144)
		(end 421.271954 -51.190144)
		(width 0.1143)
		(layer "In4.Cu")
		(net "P3E_CPU0_PE3_OCP_RXP<3>")
	)
	(segment
		(start 304.919634 -93.791278)
		(end 305.020726 -93.690186)
		(width 0.0889)
		(layer "In4.Cu")
		(net "P3E_CPU0_PE3_OCP_RXP<3>")
	)
	(segment
		(start 424.888914 -48.948086)
		(end 427.528736 -48.948086)
		(width 0.1143)
		(layer "In4.Cu")
		(net "P3E_CPU0_PE3_OCP_RXP<3>")
	)
	(segment
		(start 306.198778 -93.578426)
		(end 306.363116 -93.510862)
		(width 0.0889)
		(layer "In4.Cu")
		(net "P3E_CPU0_PE3_OCP_RXP<3>")
	)
	(segment
		(start 443.778894 -47.074582)
		(end 443.943994 -46.909482)
		(width 0.1143)
		(layer "In4.Cu")
		(net "P3E_CPU0_PE3_OCP_RXP<3>")
	)
	(segment
		(start 427.93285 -49.3522)
		(end 427.93285 -49.898046)
		(width 0.1143)
		(layer "In4.Cu")
		(net "P3E_CPU0_PE3_OCP_RXP<3>")
	)
	(segment
		(start 442.762894 -47.074582)
		(end 442.927994 -46.909482)
		(width 0.1143)
		(layer "In4.Cu")
		(net "P3E_CPU0_PE3_OCP_RXP<3>")
	)
	(segment
		(start 395.185646 -49.534318)
		(end 399.87474 -49.534318)
		(width 0.1143)
		(layer "In4.Cu")
		(net "P3E_CPU0_PE3_OCP_RXP<3>")
	)
	(segment
		(start 424.2435 -50.44313)
		(end 424.2435 -49.5935)
		(width 0.1143)
		(layer "In4.Cu")
		(net "P3E_CPU0_PE3_OCP_RXP<3>")
	)
	(segment
		(start 442.927994 -46.909482)
		(end 443.270894 -46.909482)
		(width 0.1143)
		(layer "In4.Cu")
		(net "P3E_CPU0_PE3_OCP_RXP<3>")
	)
	(segment
		(start 422.975278 -51.711352)
		(end 424.2435 -50.44313)
		(width 0.1143)
		(layer "In4.Cu")
		(net "P3E_CPU0_PE3_OCP_RXP<3>")
	)
	(segment
		(start 305.020726 -93.690186)
		(end 305.198526 -93.690186)
		(width 0.0889)
		(layer "In4.Cu")
		(net "P3E_CPU0_PE3_OCP_RXP<3>")
	)
	(segment
		(start 364.388654 -50.65776)
		(end 366.83061 -48.215804)
		(width 0.1143)
		(layer "In4.Cu")
		(net "P3E_CPU0_PE3_OCP_RXP<3>")
	)
	(segment
		(start 451.881748 -44.83735)
		(end 451.507098 -44.83735)
		(width 0.1143)
		(layer "In4.Cu")
		(net "P3E_CPU0_PE3_OCP_RXP<3>")
	)
	(segment
		(start 292.934644 -98.174048)
		(end 292.913562 -98.252788)
		(width 0.0889)
		(layer "In4.Cu")
		(net "P3E_CPU0_PE3_OCP_RXP<3>")
	)
	(segment
		(start 353.873816 -53.847238)
		(end 354.273612 -53.767482)
		(width 0.1143)
		(layer "In4.Cu")
		(net "P3E_CPU0_PE3_OCP_RXP<3>")
	)
	(segment
		(start 356.451916 -54.261004)
		(end 358.255062 -53.655722)
		(width 0.1143)
		(layer "In4.Cu")
		(net "P3E_CPU0_PE3_OCP_RXP<3>")
	)
	(segment
		(start 301.794926 -94.442534)
		(end 301.83074 -94.442534)
		(width 0.0889)
		(layer "In4.Cu")
		(net "P3E_CPU0_PE3_OCP_RXP<3>")
	)
	(segment
		(start 332.574138 -57.170574)
		(end 333.0702 -56.842406)
		(width 0.1143)
		(layer "In4.Cu")
		(net "P3E_CPU0_PE3_OCP_RXP<3>")
	)
	(segment
		(start 361.082844 -51.643534)
		(end 364.388654 -50.65776)
		(width 0.1143)
		(layer "In4.Cu")
		(net "P3E_CPU0_PE3_OCP_RXP<3>")
	)
	(segment
		(start 391.029698 -48.974502)
		(end 391.140696 -49.0855)
		(width 0.1143)
		(layer "In4.Cu")
		(net "P3E_CPU0_PE3_OCP_RXP<3>")
	)
	(segment
		(start 306.714652 -93.365574)
		(end 306.916328 -93.282516)
		(width 0.0889)
		(layer "In4.Cu")
		(net "P3E_CPU0_PE3_OCP_RXP<3>")
	)
	(segment
		(start 294.92321 -98.405188)
		(end 294.96639 -98.405188)
		(width 0.0889)
		(layer "In4.Cu")
		(net "P3E_CPU0_PE3_OCP_RXP<3>")
	)
	(arc
		(start 303.876456 -94.24289)
		(mid 304.006785 -94.084113)
		(end 304.181256 -93.975682)
		(width 0.0889)
		(layer "In4.Cu")
		(net "P3E_CPU0_PE3_OCP_RXP<3>")
	)
	(arc
		(start 296.15003 -98.700336)
		(mid 296.357034 -98.489472)
		(end 296.64025 -98.405188)
		(width 0.0889)
		(layer "In4.Cu")
		(net "P3E_CPU0_PE3_OCP_RXP<3>")
	)
	(arc
		(start 303.547272 -94.442788)
		(mid 303.737514 -94.385053)
		(end 303.876456 -94.24289)
		(width 0.0889)
		(layer "In4.Cu")
		(net "P3E_CPU0_PE3_OCP_RXP<3>")
	)
	(arc
		(start 294.101266 -98.900234)
		(mid 294.292908 -98.843068)
		(end 294.43299 -98.700336)
		(width 0.0889)
		(layer "In4.Cu")
		(net "P3E_CPU0_PE3_OCP_RXP<3>")
	)
	(arc
		(start 295.818306 -98.900234)
		(mid 296.009948 -98.843068)
		(end 296.15003 -98.700336)
		(width 0.0889)
		(layer "In4.Cu")
		(net "P3E_CPU0_PE3_OCP_RXP<3>")
	)
	(arc
		(start 300.442376 -95.232982)
		(mid 300.64938 -95.022118)
		(end 300.932596 -94.937834)
		(width 0.0889)
		(layer "In4.Cu")
		(net "P3E_CPU0_PE3_OCP_RXP<3>")
	)
	(arc
		(start 300.97222 -94.937834)
		(mid 301.162149 -94.879964)
		(end 301.300896 -94.737936)
		(width 0.0889)
		(layer "In4.Cu")
		(net "P3E_CPU0_PE3_OCP_RXP<3>")
	)
	(arc
		(start 302.159416 -94.242636)
		(mid 302.671226 -93.947097)
		(end 303.183036 -94.242636)
		(width 0.0889)
		(layer "In4.Cu")
		(net "P3E_CPU0_PE3_OCP_RXP<3>")
	)
	(arc
		(start 293.24935 -98.405188)
		(mid 293.532567 -98.489469)
		(end 293.73957 -98.700336)
		(width 0.0889)
		(layer "In4.Cu")
		(net "P3E_CPU0_PE3_OCP_RXP<3>")
	)
	(arc
		(start 292.913562 -98.252788)
		(mid 293.048124 -98.3627)
		(end 293.216584 -98.405188)
		(width 0.0889)
		(layer "In4.Cu")
		(net "P3E_CPU0_PE3_OCP_RXP<3>")
	)
	(arc
		(start 298.389802 -96.423988)
		(mid 298.583652 -96.367638)
		(end 298.725336 -96.223836)
		(width 0.0889)
		(layer "In4.Cu")
		(net "P3E_CPU0_PE3_OCP_RXP<3>")
	)
	(arc
		(start 297.008296 -97.80524)
		(mid 297.003968 -97.222064)
		(end 297.502326 -96.919034)
		(width 0.0889)
		(layer "In4.Cu")
		(net "P3E_CPU0_PE3_OCP_RXP<3>")
	)
	(arc
		(start 294.43299 -98.700336)
		(mid 294.639994 -98.489472)
		(end 294.92321 -98.405188)
		(width 0.0889)
		(layer "In4.Cu")
		(net "P3E_CPU0_PE3_OCP_RXP<3>")
	)
	(arc
		(start 294.96639 -98.405188)
		(mid 295.249607 -98.489469)
		(end 295.45661 -98.700336)
		(width 0.0889)
		(layer "In4.Cu")
		(net "P3E_CPU0_PE3_OCP_RXP<3>")
	)
	(arc
		(start 297.535092 -96.919034)
		(mid 297.726734 -96.861868)
		(end 297.866816 -96.719136)
		(width 0.0889)
		(layer "In4.Cu")
		(net "P3E_CPU0_PE3_OCP_RXP<3>")
	)
	(arc
		(start 297.866816 -96.719136)
		(mid 298.07382 -96.508272)
		(end 298.357036 -96.423988)
		(width 0.0889)
		(layer "In4.Cu")
		(net "P3E_CPU0_PE3_OCP_RXP<3>")
	)
	(arc
		(start 296.66184 -98.405188)
		(mid 297.008266 -98.205211)
		(end 297.008296 -97.80524)
		(width 0.0889)
		(layer "In4.Cu")
		(net "P3E_CPU0_PE3_OCP_RXP<3>")
	)
	(arc
		(start 298.725336 -96.223836)
		(mid 298.933944 -96.011904)
		(end 299.219366 -95.928434)
		(width 0.0889)
		(layer "In4.Cu")
		(net "P3E_CPU0_PE3_OCP_RXP<3>")
	)
	(arc
		(start 303.183036 -94.242636)
		(mid 303.32178 -94.384669)
		(end 303.511712 -94.442534)
		(width 0.0889)
		(layer "In4.Cu")
		(net "P3E_CPU0_PE3_OCP_RXP<3>")
	)
	(arc
		(start 299.583856 -95.728536)
		(mid 299.794569 -95.515457)
		(end 300.082712 -95.433134)
		(width 0.0889)
		(layer "In4.Cu")
		(net "P3E_CPU0_PE3_OCP_RXP<3>")
	)
	(arc
		(start 299.252132 -95.928434)
		(mid 299.443774 -95.871268)
		(end 299.583856 -95.728536)
		(width 0.0889)
		(layer "In4.Cu")
		(net "P3E_CPU0_PE3_OCP_RXP<3>")
	)
	(arc
		(start 301.300896 -94.737936)
		(mid 301.509504 -94.526004)
		(end 301.794926 -94.442534)
		(width 0.0889)
		(layer "In4.Cu")
		(net "P3E_CPU0_PE3_OCP_RXP<3>")
	)
	(arc
		(start 295.45661 -98.700336)
		(mid 295.596689 -98.843072)
		(end 295.788334 -98.900234)
		(width 0.0889)
		(layer "In4.Cu")
		(net "P3E_CPU0_PE3_OCP_RXP<3>")
	)
	(arc
		(start 293.73957 -98.700336)
		(mid 293.879649 -98.843072)
		(end 294.071294 -98.900234)
		(width 0.0889)
		(layer "In4.Cu")
		(net "P3E_CPU0_PE3_OCP_RXP<3>")
	)
	(arc
		(start 300.106842 -95.433134)
		(mid 300.300692 -95.376784)
		(end 300.442376 -95.232982)
		(width 0.0889)
		(layer "In4.Cu")
		(net "P3E_CPU0_PE3_OCP_RXP<3>")
	)
	(arc
		(start 301.83074 -94.442534)
		(mid 302.020669 -94.384664)
		(end 302.159416 -94.242636)
		(width 0.0889)
		(layer "In4.Cu")
		(net "P3E_CPU0_PE3_OCP_RXP<3>")
	)
	(segment
		(start 455.039984 -44.83735)
		(end 454.70699 -44.83735)
		(width 0.1143)
		(layer "F.Cu")
		(net "P3E_CPU0_PE3_OCP_RXP<2>")
	)
	(segment
		(start 455.1934 -44.990766)
		(end 455.039984 -44.83735)
		(width 0.1143)
		(layer "F.Cu")
		(net "P3E_CPU0_PE3_OCP_RXP<2>")
	)
	(segment
		(start 293.51478 -99.490784)
		(end 294.08628 -99.490784)
		(width 0.1143)
		(layer "F.Cu")
		(net "P3E_CPU0_PE3_OCP_RXP<2>")
	)
	(segment
		(start 454.940924 -47.481998)
		(end 454.940924 -46.163484)
		(width 0.1143)
		(layer "F.Cu")
		(net "P3E_CPU0_PE3_OCP_RXP<2>")
	)
	(segment
		(start 455.1934 -45.911008)
		(end 455.1934 -44.990766)
		(width 0.1143)
		(layer "F.Cu")
		(net "P3E_CPU0_PE3_OCP_RXP<2>")
	)
	(segment
		(start 454.940924 -46.163484)
		(end 455.1934 -45.911008)
		(width 0.1143)
		(layer "F.Cu")
		(net "P3E_CPU0_PE3_OCP_RXP<2>")
	)
	(via
		(at 294.08628 -99.490784)
		(size 0.508)
		(drill 0.254)
		(layers "F.Cu" "B.Cu")
		(net "P3E_CPU0_PE3_OCP_RXP<2>")
	)
	(via
		(at 454.70699 -44.83735)
		(size 0.508)
		(drill 0.254)
		(layers "F.Cu" "B.Cu")
		(net "P3E_CPU0_PE3_OCP_RXP<2>")
	)
	(segment
		(start 441.653168 -47.74057)
		(end 441.996068 -47.74057)
		(width 0.1143)
		(layer "In4.Cu")
		(net "P3E_CPU0_PE3_OCP_RXP<2>")
	)
	(segment
		(start 436.117238 -50.9016)
		(end 439.113168 -47.90567)
		(width 0.1143)
		(layer "In4.Cu")
		(net "P3E_CPU0_PE3_OCP_RXP<2>")
	)
	(segment
		(start 300.074076 -96.423988)
		(end 300.106842 -96.423988)
		(width 0.0889)
		(layer "In4.Cu")
		(net "P3E_CPU0_PE3_OCP_RXP<2>")
	)
	(segment
		(start 307.595524 -94.391988)
		(end 307.617622 -94.391988)
		(width 0.0889)
		(layer "In4.Cu")
		(net "P3E_CPU0_PE3_OCP_RXP<2>")
	)
	(segment
		(start 305.23561 -95.433134)
		(end 305.429666 -95.433134)
		(width 0.0889)
		(layer "In4.Cu")
		(net "P3E_CPU0_PE3_OCP_RXP<2>")
	)
	(segment
		(start 382.130808 -46.5582)
		(end 385.680712 -46.5582)
		(width 0.1143)
		(layer "In4.Cu")
		(net "P3E_CPU0_PE3_OCP_RXP<2>")
	)
	(segment
		(start 297.502326 -98.900234)
		(end 297.535092 -98.900234)
		(width 0.0889)
		(layer "In4.Cu")
		(net "P3E_CPU0_PE3_OCP_RXP<2>")
	)
	(segment
		(start 371.111018 -49.380394)
		(end 371.94617 -48.545242)
		(width 0.1143)
		(layer "In4.Cu")
		(net "P3E_CPU0_PE3_OCP_RXP<2>")
	)
	(segment
		(start 318.56553 -83.560666)
		(end 323.670676 -71.235316)
		(width 0.1143)
		(layer "In4.Cu")
		(net "P3E_CPU0_PE3_OCP_RXP<2>")
	)
	(segment
		(start 297.866816 -98.300286)
		(end 297.860466 -98.289618)
		(width 0.0889)
		(layer "In4.Cu")
		(net "P3E_CPU0_PE3_OCP_RXP<2>")
	)
	(segment
		(start 421.001698 -51.84775)
		(end 421.500808 -52.34686)
		(width 0.1143)
		(layer "In4.Cu")
		(net "P3E_CPU0_PE3_OCP_RXP<2>")
	)
	(segment
		(start 400.794474 -51.35245)
		(end 405.692864 -51.35245)
		(width 0.1143)
		(layer "In4.Cu")
		(net "P3E_CPU0_PE3_OCP_RXP<2>")
	)
	(segment
		(start 307.544724 -94.442788)
		(end 307.595524 -94.391988)
		(width 0.0889)
		(layer "In4.Cu")
		(net "P3E_CPU0_PE3_OCP_RXP<2>")
	)
	(segment
		(start 455.19594 -46.371002)
		(end 455.19594 -44.95165)
		(width 0.1143)
		(layer "In4.Cu")
		(net "P3E_CPU0_PE3_OCP_RXP<2>")
	)
	(segment
		(start 323.670676 -71.235316)
		(end 332.984856 -57.694576)
		(width 0.1143)
		(layer "In4.Cu")
		(net "P3E_CPU0_PE3_OCP_RXP<2>")
	)
	(segment
		(start 374.363488 -48.545242)
		(end 374.781572 -48.127158)
		(width 0.1143)
		(layer "In4.Cu")
		(net "P3E_CPU0_PE3_OCP_RXP<2>")
	)
	(segment
		(start 405.692864 -51.35245)
		(end 407.147014 -52.8066)
		(width 0.1143)
		(layer "In4.Cu")
		(net "P3E_CPU0_PE3_OCP_RXP<2>")
	)
	(segment
		(start 390.7663 -49.609502)
		(end 393.087098 -51.9303)
		(width 0.1143)
		(layer "In4.Cu")
		(net "P3E_CPU0_PE3_OCP_RXP<2>")
	)
	(segment
		(start 414.5026 -52.8066)
		(end 415.210752 -53.514752)
		(width 0.1143)
		(layer "In4.Cu")
		(net "P3E_CPU0_PE3_OCP_RXP<2>")
	)
	(segment
		(start 332.984856 -57.694576)
		(end 333.312262 -57.478422)
		(width 0.1143)
		(layer "In4.Cu")
		(net "P3E_CPU0_PE3_OCP_RXP<2>")
	)
	(segment
		(start 395.930374 -51.016408)
		(end 395.930628 -51.016662)
		(width 0.1143)
		(layer "In4.Cu")
		(net "P3E_CPU0_PE3_OCP_RXP<2>")
	)
	(segment
		(start 407.147014 -52.8066)
		(end 414.5026 -52.8066)
		(width 0.1143)
		(layer "In4.Cu")
		(net "P3E_CPU0_PE3_OCP_RXP<2>")
	)
	(segment
		(start 441.488068 -47.90567)
		(end 441.653168 -47.74057)
		(width 0.1143)
		(layer "In4.Cu")
		(net "P3E_CPU0_PE3_OCP_RXP<2>")
	)
	(segment
		(start 440.637168 -47.74057)
		(end 440.980068 -47.74057)
		(width 0.1143)
		(layer "In4.Cu")
		(net "P3E_CPU0_PE3_OCP_RXP<2>")
	)
	(segment
		(start 453.661272 -47.90567)
		(end 455.19594 -46.371002)
		(width 0.1143)
		(layer "In4.Cu")
		(net "P3E_CPU0_PE3_OCP_RXP<2>")
	)
	(segment
		(start 300.936406 -95.928434)
		(end 300.969172 -95.928434)
		(width 0.0889)
		(layer "In4.Cu")
		(net "P3E_CPU0_PE3_OCP_RXP<2>")
	)
	(segment
		(start 356.449122 -55.03164)
		(end 358.438958 -54.363874)
		(width 0.1143)
		(layer "In4.Cu")
		(net "P3E_CPU0_PE3_OCP_RXP<2>")
	)
	(segment
		(start 297.871642 -98.308922)
		(end 297.866816 -98.300286)
		(width 0.0889)
		(layer "In4.Cu")
		(net "P3E_CPU0_PE3_OCP_RXP<2>")
	)
	(segment
		(start 385.934966 -46.812454)
		(end 386.309108 -46.812454)
		(width 0.1143)
		(layer "In4.Cu")
		(net "P3E_CPU0_PE3_OCP_RXP<2>")
	)
	(segment
		(start 400.458686 -51.016662)
		(end 400.794474 -51.35245)
		(width 0.1143)
		(layer "In4.Cu")
		(net "P3E_CPU0_PE3_OCP_RXP<2>")
	)
	(segment
		(start 393.087098 -51.9303)
		(end 394.774674 -51.9303)
		(width 0.1143)
		(layer "In4.Cu")
		(net "P3E_CPU0_PE3_OCP_RXP<2>")
	)
	(segment
		(start 417.03752 -52.754784)
		(end 419.316154 -52.754784)
		(width 0.1143)
		(layer "In4.Cu")
		(net "P3E_CPU0_PE3_OCP_RXP<2>")
	)
	(segment
		(start 441.145168 -47.90567)
		(end 441.488068 -47.90567)
		(width 0.1143)
		(layer "In4.Cu")
		(net "P3E_CPU0_PE3_OCP_RXP<2>")
	)
	(segment
		(start 296.64025 -99.395788)
		(end 296.66184 -99.395788)
		(width 0.0889)
		(layer "In4.Cu")
		(net "P3E_CPU0_PE3_OCP_RXP<2>")
	)
	(segment
		(start 387.841998 -48.345344)
		(end 387.841998 -49.294542)
		(width 0.1143)
		(layer "In4.Cu")
		(net "P3E_CPU0_PE3_OCP_RXP<2>")
	)
	(segment
		(start 440.129168 -47.90567)
		(end 440.472068 -47.90567)
		(width 0.1143)
		(layer "In4.Cu")
		(net "P3E_CPU0_PE3_OCP_RXP<2>")
	)
	(segment
		(start 380.56185 -48.127158)
		(end 382.130808 -46.5582)
		(width 0.1143)
		(layer "In4.Cu")
		(net "P3E_CPU0_PE3_OCP_RXP<2>")
	)
	(segment
		(start 442.161168 -47.90567)
		(end 453.661272 -47.90567)
		(width 0.1143)
		(layer "In4.Cu")
		(net "P3E_CPU0_PE3_OCP_RXP<2>")
	)
	(segment
		(start 294.92321 -99.395788)
		(end 294.96639 -99.395788)
		(width 0.0889)
		(layer "In4.Cu")
		(net "P3E_CPU0_PE3_OCP_RXP<2>")
	)
	(segment
		(start 355.921564 -55.03164)
		(end 356.449122 -55.03164)
		(width 0.1143)
		(layer "In4.Cu")
		(net "P3E_CPU0_PE3_OCP_RXP<2>")
	)
	(segment
		(start 439.456068 -47.90567)
		(end 439.621168 -47.74057)
		(width 0.1143)
		(layer "In4.Cu")
		(net "P3E_CPU0_PE3_OCP_RXP<2>")
	)
	(segment
		(start 297.004994 -99.201478)
		(end 297.008296 -99.195636)
		(width 0.0889)
		(layer "In4.Cu")
		(net "P3E_CPU0_PE3_OCP_RXP<2>")
	)
	(segment
		(start 439.964068 -47.74057)
		(end 440.129168 -47.90567)
		(width 0.1143)
		(layer "In4.Cu")
		(net "P3E_CPU0_PE3_OCP_RXP<2>")
	)
	(segment
		(start 358.438958 -54.363874)
		(end 361.332018 -52.30495)
		(width 0.1143)
		(layer "In4.Cu")
		(net "P3E_CPU0_PE3_OCP_RXP<2>")
	)
	(segment
		(start 307.7337 -94.391988)
		(end 318.56553 -83.560666)
		(width 0.1143)
		(layer "In4.Cu")
		(net "P3E_CPU0_PE3_OCP_RXP<2>")
	)
	(segment
		(start 294.379396 -99.659948)
		(end 294.468804 -99.635818)
		(width 0.0889)
		(layer "In4.Cu")
		(net "P3E_CPU0_PE3_OCP_RXP<2>")
	)
	(segment
		(start 421.500808 -52.34686)
		(end 423.238168 -52.34686)
		(width 0.1143)
		(layer "In4.Cu")
		(net "P3E_CPU0_PE3_OCP_RXP<2>")
	)
	(segment
		(start 369.055904 -48.850804)
		(end 369.585494 -49.380394)
		(width 0.1143)
		(layer "In4.Cu")
		(net "P3E_CPU0_PE3_OCP_RXP<2>")
	)
	(segment
		(start 369.585494 -49.380394)
		(end 371.111018 -49.380394)
		(width 0.1143)
		(layer "In4.Cu")
		(net "P3E_CPU0_PE3_OCP_RXP<2>")
	)
	(segment
		(start 394.774674 -51.9303)
		(end 395.688566 -51.016408)
		(width 0.1143)
		(layer "In4.Cu")
		(net "P3E_CPU0_PE3_OCP_RXP<2>")
	)
	(segment
		(start 299.219366 -96.919034)
		(end 299.252132 -96.919034)
		(width 0.0889)
		(layer "In4.Cu")
		(net "P3E_CPU0_PE3_OCP_RXP<2>")
	)
	(segment
		(start 294.08628 -99.490784)
		(end 294.379396 -99.659948)
		(width 0.0889)
		(layer "In4.Cu")
		(net "P3E_CPU0_PE3_OCP_RXP<2>")
	)
	(segment
		(start 386.309108 -46.812454)
		(end 387.841998 -48.345344)
		(width 0.1143)
		(layer "In4.Cu")
		(net "P3E_CPU0_PE3_OCP_RXP<2>")
	)
	(segment
		(start 305.429666 -95.433134)
		(end 306.420012 -94.442788)
		(width 0.0889)
		(layer "In4.Cu")
		(net "P3E_CPU0_PE3_OCP_RXP<2>")
	)
	(segment
		(start 371.94617 -48.545242)
		(end 374.363488 -48.545242)
		(width 0.1143)
		(layer "In4.Cu")
		(net "P3E_CPU0_PE3_OCP_RXP<2>")
	)
	(segment
		(start 295.788334 -99.890834)
		(end 295.818306 -99.890834)
		(width 0.0889)
		(layer "In4.Cu")
		(net "P3E_CPU0_PE3_OCP_RXP<2>")
	)
	(segment
		(start 426.944028 -50.9016)
		(end 436.117238 -50.9016)
		(width 0.1143)
		(layer "In4.Cu")
		(net "P3E_CPU0_PE3_OCP_RXP<2>")
	)
	(segment
		(start 424.010074 -51.574954)
		(end 426.270674 -51.574954)
		(width 0.1143)
		(layer "In4.Cu")
		(net "P3E_CPU0_PE3_OCP_RXP<2>")
	)
	(segment
		(start 441.996068 -47.74057)
		(end 442.161168 -47.90567)
		(width 0.1143)
		(layer "In4.Cu")
		(net "P3E_CPU0_PE3_OCP_RXP<2>")
	)
	(segment
		(start 426.270674 -51.574954)
		(end 426.944028 -50.9016)
		(width 0.1143)
		(layer "In4.Cu")
		(net "P3E_CPU0_PE3_OCP_RXP<2>")
	)
	(segment
		(start 298.357036 -97.414588)
		(end 298.389802 -97.414588)
		(width 0.0889)
		(layer "In4.Cu")
		(net "P3E_CPU0_PE3_OCP_RXP<2>")
	)
	(segment
		(start 415.210752 -53.514752)
		(end 416.277552 -53.514752)
		(width 0.1143)
		(layer "In4.Cu")
		(net "P3E_CPU0_PE3_OCP_RXP<2>")
	)
	(segment
		(start 395.688566 -51.016408)
		(end 395.930374 -51.016408)
		(width 0.1143)
		(layer "In4.Cu")
		(net "P3E_CPU0_PE3_OCP_RXP<2>")
	)
	(segment
		(start 364.810294 -51.312064)
		(end 367.272062 -48.850804)
		(width 0.1143)
		(layer "In4.Cu")
		(net "P3E_CPU0_PE3_OCP_RXP<2>")
	)
	(segment
		(start 348.630494 -57.478422)
		(end 355.921564 -55.03164)
		(width 0.1143)
		(layer "In4.Cu")
		(net "P3E_CPU0_PE3_OCP_RXP<2>")
	)
	(segment
		(start 306.420012 -94.442788)
		(end 307.544724 -94.442788)
		(width 0.0889)
		(layer "In4.Cu")
		(net "P3E_CPU0_PE3_OCP_RXP<2>")
	)
	(segment
		(start 419.316408 -52.755038)
		(end 420.223696 -51.84775)
		(width 0.1143)
		(layer "In4.Cu")
		(net "P3E_CPU0_PE3_OCP_RXP<2>")
	)
	(segment
		(start 439.621168 -47.74057)
		(end 439.964068 -47.74057)
		(width 0.1143)
		(layer "In4.Cu")
		(net "P3E_CPU0_PE3_OCP_RXP<2>")
	)
	(segment
		(start 416.277552 -53.514752)
		(end 417.03752 -52.754784)
		(width 0.1143)
		(layer "In4.Cu")
		(net "P3E_CPU0_PE3_OCP_RXP<2>")
	)
	(segment
		(start 455.19594 -44.95165)
		(end 455.08164 -44.83735)
		(width 0.1143)
		(layer "In4.Cu")
		(net "P3E_CPU0_PE3_OCP_RXP<2>")
	)
	(segment
		(start 420.223696 -51.84775)
		(end 421.001698 -51.84775)
		(width 0.1143)
		(layer "In4.Cu")
		(net "P3E_CPU0_PE3_OCP_RXP<2>")
	)
	(segment
		(start 367.272062 -48.850804)
		(end 369.055904 -48.850804)
		(width 0.1143)
		(layer "In4.Cu")
		(net "P3E_CPU0_PE3_OCP_RXP<2>")
	)
	(segment
		(start 455.08164 -44.83735)
		(end 454.70699 -44.83735)
		(width 0.1143)
		(layer "In4.Cu")
		(net "P3E_CPU0_PE3_OCP_RXP<2>")
	)
	(segment
		(start 333.312262 -57.478422)
		(end 348.630494 -57.478422)
		(width 0.1143)
		(layer "In4.Cu")
		(net "P3E_CPU0_PE3_OCP_RXP<2>")
	)
	(segment
		(start 440.472068 -47.90567)
		(end 440.637168 -47.74057)
		(width 0.1143)
		(layer "In4.Cu")
		(net "P3E_CPU0_PE3_OCP_RXP<2>")
	)
	(segment
		(start 388.156958 -49.609502)
		(end 390.7663 -49.609502)
		(width 0.1143)
		(layer "In4.Cu")
		(net "P3E_CPU0_PE3_OCP_RXP<2>")
	)
	(segment
		(start 387.841998 -49.294542)
		(end 388.156958 -49.609502)
		(width 0.1143)
		(layer "In4.Cu")
		(net "P3E_CPU0_PE3_OCP_RXP<2>")
	)
	(segment
		(start 385.680712 -46.5582)
		(end 385.934966 -46.812454)
		(width 0.1143)
		(layer "In4.Cu")
		(net "P3E_CPU0_PE3_OCP_RXP<2>")
	)
	(segment
		(start 440.980068 -47.74057)
		(end 441.145168 -47.90567)
		(width 0.1143)
		(layer "In4.Cu")
		(net "P3E_CPU0_PE3_OCP_RXP<2>")
	)
	(segment
		(start 374.781572 -48.127158)
		(end 380.56185 -48.127158)
		(width 0.1143)
		(layer "In4.Cu")
		(net "P3E_CPU0_PE3_OCP_RXP<2>")
	)
	(segment
		(start 395.930628 -51.016662)
		(end 400.458686 -51.016662)
		(width 0.1143)
		(layer "In4.Cu")
		(net "P3E_CPU0_PE3_OCP_RXP<2>")
	)
	(segment
		(start 423.238168 -52.34686)
		(end 424.010074 -51.574954)
		(width 0.1143)
		(layer "In4.Cu")
		(net "P3E_CPU0_PE3_OCP_RXP<2>")
	)
	(segment
		(start 419.316154 -52.754784)
		(end 419.316408 -52.755038)
		(width 0.1143)
		(layer "In4.Cu")
		(net "P3E_CPU0_PE3_OCP_RXP<2>")
	)
	(segment
		(start 301.799752 -95.433134)
		(end 301.823882 -95.433134)
		(width 0.0889)
		(layer "In4.Cu")
		(net "P3E_CPU0_PE3_OCP_RXP<2>")
	)
	(segment
		(start 307.617622 -94.391988)
		(end 307.7337 -94.391988)
		(width 0.1143)
		(layer "In4.Cu")
		(net "P3E_CPU0_PE3_OCP_RXP<2>")
	)
	(segment
		(start 304.366676 -94.937834)
		(end 304.409856 -94.937834)
		(width 0.0889)
		(layer "In4.Cu")
		(net "P3E_CPU0_PE3_OCP_RXP<2>")
	)
	(segment
		(start 361.332018 -52.30495)
		(end 364.810294 -51.312064)
		(width 0.1143)
		(layer "In4.Cu")
		(net "P3E_CPU0_PE3_OCP_RXP<2>")
	)
	(segment
		(start 439.113168 -47.90567)
		(end 439.456068 -47.90567)
		(width 0.1143)
		(layer "In4.Cu")
		(net "P3E_CPU0_PE3_OCP_RXP<2>")
	)
	(segment
		(start 302.649636 -94.937834)
		(end 302.692816 -94.937834)
		(width 0.0889)
		(layer "In4.Cu")
		(net "P3E_CPU0_PE3_OCP_RXP<2>")
	)
	(arc
		(start 301.823882 -95.433134)
		(mid 302.017732 -95.376784)
		(end 302.159416 -95.232982)
		(width 0.0889)
		(layer "In4.Cu")
		(net "P3E_CPU0_PE3_OCP_RXP<2>")
	)
	(arc
		(start 299.252132 -96.919034)
		(mid 299.443774 -96.861868)
		(end 299.583856 -96.719136)
		(width 0.0889)
		(layer "In4.Cu")
		(net "P3E_CPU0_PE3_OCP_RXP<2>")
	)
	(arc
		(start 300.106842 -96.423988)
		(mid 300.300692 -96.367638)
		(end 300.442376 -96.223836)
		(width 0.0889)
		(layer "In4.Cu")
		(net "P3E_CPU0_PE3_OCP_RXP<2>")
	)
	(arc
		(start 301.300896 -95.728536)
		(mid 301.511609 -95.515457)
		(end 301.799752 -95.433134)
		(width 0.0889)
		(layer "In4.Cu")
		(net "P3E_CPU0_PE3_OCP_RXP<2>")
	)
	(arc
		(start 294.96639 -99.395788)
		(mid 295.249607 -99.480069)
		(end 295.45661 -99.690936)
		(width 0.0889)
		(layer "In4.Cu")
		(net "P3E_CPU0_PE3_OCP_RXP<2>")
	)
	(arc
		(start 300.442376 -96.223836)
		(mid 300.650984 -96.011904)
		(end 300.936406 -95.928434)
		(width 0.0889)
		(layer "In4.Cu")
		(net "P3E_CPU0_PE3_OCP_RXP<2>")
	)
	(arc
		(start 304.409856 -94.937834)
		(mid 304.693073 -95.022115)
		(end 304.900076 -95.232982)
		(width 0.0889)
		(layer "In4.Cu")
		(net "P3E_CPU0_PE3_OCP_RXP<2>")
	)
	(arc
		(start 300.969172 -95.928434)
		(mid 301.160814 -95.871268)
		(end 301.300896 -95.728536)
		(width 0.0889)
		(layer "In4.Cu")
		(net "P3E_CPU0_PE3_OCP_RXP<2>")
	)
	(arc
		(start 297.860466 -98.289618)
		(mid 297.864497 -97.713436)
		(end 298.357036 -97.414588)
		(width 0.0889)
		(layer "In4.Cu")
		(net "P3E_CPU0_PE3_OCP_RXP<2>")
	)
	(arc
		(start 297.535092 -98.900234)
		(mid 297.86801 -98.698243)
		(end 297.871642 -98.308922)
		(width 0.0889)
		(layer "In4.Cu")
		(net "P3E_CPU0_PE3_OCP_RXP<2>")
	)
	(arc
		(start 302.692816 -94.937834)
		(mid 302.976033 -95.022115)
		(end 303.183036 -95.232982)
		(width 0.0889)
		(layer "In4.Cu")
		(net "P3E_CPU0_PE3_OCP_RXP<2>")
	)
	(arc
		(start 298.389802 -97.414588)
		(mid 298.583652 -97.358238)
		(end 298.725336 -97.214436)
		(width 0.0889)
		(layer "In4.Cu")
		(net "P3E_CPU0_PE3_OCP_RXP<2>")
	)
	(arc
		(start 298.725336 -97.214436)
		(mid 298.933944 -97.002504)
		(end 299.219366 -96.919034)
		(width 0.0889)
		(layer "In4.Cu")
		(net "P3E_CPU0_PE3_OCP_RXP<2>")
	)
	(arc
		(start 296.66184 -99.395788)
		(mid 296.859001 -99.343829)
		(end 297.004994 -99.201478)
		(width 0.0889)
		(layer "In4.Cu")
		(net "P3E_CPU0_PE3_OCP_RXP<2>")
	)
	(arc
		(start 303.183036 -95.232982)
		(mid 303.529746 -95.433293)
		(end 303.876456 -95.232982)
		(width 0.0889)
		(layer "In4.Cu")
		(net "P3E_CPU0_PE3_OCP_RXP<2>")
	)
	(arc
		(start 304.900076 -95.232982)
		(mid 305.041759 -95.376786)
		(end 305.23561 -95.433134)
		(width 0.0889)
		(layer "In4.Cu")
		(net "P3E_CPU0_PE3_OCP_RXP<2>")
	)
	(arc
		(start 302.159416 -95.232982)
		(mid 302.36642 -95.022118)
		(end 302.649636 -94.937834)
		(width 0.0889)
		(layer "In4.Cu")
		(net "P3E_CPU0_PE3_OCP_RXP<2>")
	)
	(arc
		(start 295.818306 -99.890834)
		(mid 296.009948 -99.833668)
		(end 296.15003 -99.690936)
		(width 0.0889)
		(layer "In4.Cu")
		(net "P3E_CPU0_PE3_OCP_RXP<2>")
	)
	(arc
		(start 294.468804 -99.635818)
		(mid 294.668549 -99.463824)
		(end 294.92321 -99.395788)
		(width 0.0889)
		(layer "In4.Cu")
		(net "P3E_CPU0_PE3_OCP_RXP<2>")
	)
	(arc
		(start 296.15003 -99.690936)
		(mid 296.357034 -99.480072)
		(end 296.64025 -99.395788)
		(width 0.0889)
		(layer "In4.Cu")
		(net "P3E_CPU0_PE3_OCP_RXP<2>")
	)
	(arc
		(start 297.008296 -99.195636)
		(mid 297.216904 -98.983704)
		(end 297.502326 -98.900234)
		(width 0.0889)
		(layer "In4.Cu")
		(net "P3E_CPU0_PE3_OCP_RXP<2>")
	)
	(arc
		(start 303.876456 -95.232982)
		(mid 304.08346 -95.022118)
		(end 304.366676 -94.937834)
		(width 0.0889)
		(layer "In4.Cu")
		(net "P3E_CPU0_PE3_OCP_RXP<2>")
	)
	(arc
		(start 295.45661 -99.690936)
		(mid 295.596689 -99.833672)
		(end 295.788334 -99.890834)
		(width 0.0889)
		(layer "In4.Cu")
		(net "P3E_CPU0_PE3_OCP_RXP<2>")
	)
	(arc
		(start 299.583856 -96.719136)
		(mid 299.79086 -96.508272)
		(end 300.074076 -96.423988)
		(width 0.0889)
		(layer "In4.Cu")
		(net "P3E_CPU0_PE3_OCP_RXP<2>")
	)
	(segment
		(start 458.24013 -44.83735)
		(end 457.907136 -44.83735)
		(width 0.1143)
		(layer "F.Cu")
		(net "P3E_CPU0_PE3_OCP_RXP<1>")
	)
	(segment
		(start 458.14107 -46.135798)
		(end 458.421486 -45.855382)
		(width 0.1143)
		(layer "F.Cu")
		(net "P3E_CPU0_PE3_OCP_RXP<1>")
	)
	(segment
		(start 292.65626 -98.995738)
		(end 293.22776 -98.995738)
		(width 0.1143)
		(layer "F.Cu")
		(net "P3E_CPU0_PE3_OCP_RXP<1>")
	)
	(segment
		(start 458.421486 -45.018706)
		(end 458.24013 -44.83735)
		(width 0.1143)
		(layer "F.Cu")
		(net "P3E_CPU0_PE3_OCP_RXP<1>")
	)
	(segment
		(start 458.14107 -47.481998)
		(end 458.14107 -46.135798)
		(width 0.1143)
		(layer "F.Cu")
		(net "P3E_CPU0_PE3_OCP_RXP<1>")
	)
	(segment
		(start 458.421486 -45.855382)
		(end 458.421486 -45.018706)
		(width 0.1143)
		(layer "F.Cu")
		(net "P3E_CPU0_PE3_OCP_RXP<1>")
	)
	(via
		(at 457.907136 -44.83735)
		(size 0.508)
		(drill 0.254)
		(layers "F.Cu" "B.Cu")
		(net "P3E_CPU0_PE3_OCP_RXP<1>")
	)
	(via
		(at 293.22776 -98.995738)
		(size 0.508)
		(drill 0.254)
		(layers "F.Cu" "B.Cu")
		(net "P3E_CPU0_PE3_OCP_RXP<1>")
	)
	(segment
		(start 439.719974 -48.552354)
		(end 440.062874 -48.552354)
		(width 0.1143)
		(layer "In4.Cu")
		(net "P3E_CPU0_PE3_OCP_RXP<1>")
	)
	(segment
		(start 307.5432 -95.504)
		(end 319.130426 -83.917028)
		(width 0.1143)
		(layer "In4.Cu")
		(net "P3E_CPU0_PE3_OCP_RXP<1>")
	)
	(segment
		(start 415.043874 -54.301898)
		(end 416.607244 -54.301898)
		(width 0.1143)
		(layer "In4.Cu")
		(net "P3E_CPU0_PE3_OCP_RXP<1>")
	)
	(segment
		(start 370.874798 -50.515012)
		(end 372.209568 -49.180242)
		(width 0.1143)
		(layer "In4.Cu")
		(net "P3E_CPU0_PE3_OCP_RXP<1>")
	)
	(segment
		(start 423.3291 -53.154326)
		(end 424.263312 -52.220114)
		(width 0.1143)
		(layer "In4.Cu")
		(net "P3E_CPU0_PE3_OCP_RXP<1>")
	)
	(segment
		(start 401.087082 -51.993038)
		(end 405.390096 -51.993038)
		(width 0.1143)
		(layer "In4.Cu")
		(net "P3E_CPU0_PE3_OCP_RXP<1>")
	)
	(segment
		(start 356.562152 -55.66664)
		(end 358.829864 -54.905656)
		(width 0.1143)
		(layer "In4.Cu")
		(net "P3E_CPU0_PE3_OCP_RXP<1>")
	)
	(segment
		(start 305.689762 -96.290638)
		(end 306.4256 -95.5548)
		(width 0.0889)
		(layer "In4.Cu")
		(net "P3E_CPU0_PE3_OCP_RXP<1>")
	)
	(segment
		(start 416.607244 -54.301898)
		(end 417.479734 -53.429408)
		(width 0.1143)
		(layer "In4.Cu")
		(net "P3E_CPU0_PE3_OCP_RXP<1>")
	)
	(segment
		(start 375.047764 -48.809148)
		(end 381.136652 -48.809148)
		(width 0.1143)
		(layer "In4.Cu")
		(net "P3E_CPU0_PE3_OCP_RXP<1>")
	)
	(segment
		(start 301.791116 -96.423988)
		(end 301.823882 -96.423988)
		(width 0.0889)
		(layer "In4.Cu")
		(net "P3E_CPU0_PE3_OCP_RXP<1>")
	)
	(segment
		(start 400.514566 -52.565554)
		(end 401.087082 -51.993038)
		(width 0.1143)
		(layer "In4.Cu")
		(net "P3E_CPU0_PE3_OCP_RXP<1>")
	)
	(segment
		(start 436.440072 -51.477164)
		(end 436.452264 -51.477164)
		(width 0.1143)
		(layer "In4.Cu")
		(net "P3E_CPU0_PE3_OCP_RXP<1>")
	)
	(segment
		(start 385.323842 -47.7266)
		(end 386.3086 -47.7266)
		(width 0.1143)
		(layer "In4.Cu")
		(net "P3E_CPU0_PE3_OCP_RXP<1>")
	)
	(segment
		(start 387.89356 -50.244502)
		(end 390.502902 -50.244502)
		(width 0.1143)
		(layer "In4.Cu")
		(net "P3E_CPU0_PE3_OCP_RXP<1>")
	)
	(segment
		(start 293.22776 -98.995738)
		(end 293.22776 -99.333812)
		(width 0.0889)
		(layer "In4.Cu")
		(net "P3E_CPU0_PE3_OCP_RXP<1>")
	)
	(segment
		(start 358.829864 -54.905656)
		(end 361.010454 -53.3527)
		(width 0.1143)
		(layer "In4.Cu")
		(net "P3E_CPU0_PE3_OCP_RXP<1>")
	)
	(segment
		(start 304.949606 -96.293178)
		(end 305.125628 -96.4692)
		(width 0.0889)
		(layer "In4.Cu")
		(net "P3E_CPU0_PE3_OCP_RXP<1>")
	)
	(segment
		(start 442.259974 -48.717454)
		(end 442.602874 -48.717454)
		(width 0.1143)
		(layer "In4.Cu")
		(net "P3E_CPU0_PE3_OCP_RXP<1>")
	)
	(segment
		(start 440.735974 -48.552354)
		(end 441.078874 -48.552354)
		(width 0.1143)
		(layer "In4.Cu")
		(net "P3E_CPU0_PE3_OCP_RXP<1>")
	)
	(segment
		(start 443.275974 -48.717454)
		(end 456.341988 -48.717454)
		(width 0.1143)
		(layer "In4.Cu")
		(net "P3E_CPU0_PE3_OCP_RXP<1>")
	)
	(segment
		(start 414.183576 -53.4416)
		(end 415.043874 -54.301898)
		(width 0.1143)
		(layer "In4.Cu")
		(net "P3E_CPU0_PE3_OCP_RXP<1>")
	)
	(segment
		(start 300.074076 -97.414588)
		(end 300.106842 -97.414588)
		(width 0.0889)
		(layer "In4.Cu")
		(net "P3E_CPU0_PE3_OCP_RXP<1>")
	)
	(segment
		(start 458.396086 -44.95165)
		(end 458.281786 -44.83735)
		(width 0.1143)
		(layer "In4.Cu")
		(net "P3E_CPU0_PE3_OCP_RXP<1>")
	)
	(segment
		(start 294.926766 -100.386134)
		(end 294.96258 -100.386134)
		(width 0.0889)
		(layer "In4.Cu")
		(net "P3E_CPU0_PE3_OCP_RXP<1>")
	)
	(segment
		(start 333.785464 -58.144156)
		(end 348.728792 -58.144156)
		(width 0.1143)
		(layer "In4.Cu")
		(net "P3E_CPU0_PE3_OCP_RXP<1>")
	)
	(segment
		(start 441.243974 -48.717454)
		(end 441.586874 -48.717454)
		(width 0.1143)
		(layer "In4.Cu")
		(net "P3E_CPU0_PE3_OCP_RXP<1>")
	)
	(segment
		(start 425.939458 -53.121814)
		(end 426.247306 -53.121814)
		(width 0.1143)
		(layer "In4.Cu")
		(net "P3E_CPU0_PE3_OCP_RXP<1>")
	)
	(segment
		(start 439.554874 -48.717454)
		(end 439.719974 -48.552354)
		(width 0.1143)
		(layer "In4.Cu")
		(net "P3E_CPU0_PE3_OCP_RXP<1>")
	)
	(segment
		(start 440.570874 -48.717454)
		(end 440.735974 -48.552354)
		(width 0.1143)
		(layer "In4.Cu")
		(net "P3E_CPU0_PE3_OCP_RXP<1>")
	)
	(segment
		(start 458.281786 -44.83735)
		(end 457.907136 -44.83735)
		(width 0.1143)
		(layer "In4.Cu")
		(net "P3E_CPU0_PE3_OCP_RXP<1>")
	)
	(segment
		(start 421.188388 -53.154326)
		(end 423.3291 -53.154326)
		(width 0.1143)
		(layer "In4.Cu")
		(net "P3E_CPU0_PE3_OCP_RXP<1>")
	)
	(segment
		(start 443.110874 -48.552354)
		(end 443.275974 -48.717454)
		(width 0.1143)
		(layer "In4.Cu")
		(net "P3E_CPU0_PE3_OCP_RXP<1>")
	)
	(segment
		(start 366.599724 -51.814222)
		(end 367.899442 -50.515012)
		(width 0.1143)
		(layer "In4.Cu")
		(net "P3E_CPU0_PE3_OCP_RXP<1>")
	)
	(segment
		(start 385.002786 -48.047656)
		(end 385.323842 -47.7266)
		(width 0.1143)
		(layer "In4.Cu")
		(net "P3E_CPU0_PE3_OCP_RXP<1>")
	)
	(segment
		(start 441.078874 -48.552354)
		(end 441.243974 -48.717454)
		(width 0.1143)
		(layer "In4.Cu")
		(net "P3E_CPU0_PE3_OCP_RXP<1>")
	)
	(segment
		(start 417.479734 -53.429408)
		(end 420.913306 -53.429408)
		(width 0.1143)
		(layer "In4.Cu")
		(net "P3E_CPU0_PE3_OCP_RXP<1>")
	)
	(segment
		(start 386.3086 -47.7266)
		(end 386.969 -48.387)
		(width 0.1143)
		(layer "In4.Cu")
		(net "P3E_CPU0_PE3_OCP_RXP<1>")
	)
	(segment
		(start 425.037758 -52.220114)
		(end 425.939458 -53.121814)
		(width 0.1143)
		(layer "In4.Cu")
		(net "P3E_CPU0_PE3_OCP_RXP<1>")
	)
	(segment
		(start 381.136652 -48.809148)
		(end 381.812546 -48.133)
		(width 0.1143)
		(layer "In4.Cu")
		(net "P3E_CPU0_PE3_OCP_RXP<1>")
	)
	(segment
		(start 356.111302 -55.66664)
		(end 356.562152 -55.66664)
		(width 0.1143)
		(layer "In4.Cu")
		(net "P3E_CPU0_PE3_OCP_RXP<1>")
	)
	(segment
		(start 420.913306 -53.429408)
		(end 421.188388 -53.154326)
		(width 0.1143)
		(layer "In4.Cu")
		(net "P3E_CPU0_PE3_OCP_RXP<1>")
	)
	(segment
		(start 427.83252 -51.5366)
		(end 436.380636 -51.5366)
		(width 0.1143)
		(layer "In4.Cu")
		(net "P3E_CPU0_PE3_OCP_RXP<1>")
	)
	(segment
		(start 295.785286 -100.881434)
		(end 295.821354 -100.881434)
		(width 0.0889)
		(layer "In4.Cu")
		(net "P3E_CPU0_PE3_OCP_RXP<1>")
	)
	(segment
		(start 381.812546 -48.133)
		(end 381.812546 -48.133254)
		(width 0.1143)
		(layer "In4.Cu")
		(net "P3E_CPU0_PE3_OCP_RXP<1>")
	)
	(segment
		(start 405.390096 -51.993038)
		(end 406.838658 -53.4416)
		(width 0.1143)
		(layer "In4.Cu")
		(net "P3E_CPU0_PE3_OCP_RXP<1>")
	)
	(segment
		(start 458.396086 -46.663356)
		(end 458.396086 -44.95165)
		(width 0.1143)
		(layer "In4.Cu")
		(net "P3E_CPU0_PE3_OCP_RXP<1>")
	)
	(segment
		(start 293.22776 -99.333812)
		(end 293.292784 -99.398836)
		(width 0.0889)
		(layer "In4.Cu")
		(net "P3E_CPU0_PE3_OCP_RXP<1>")
	)
	(segment
		(start 436.380636 -51.5366)
		(end 436.440072 -51.477164)
		(width 0.1143)
		(layer "In4.Cu")
		(net "P3E_CPU0_PE3_OCP_RXP<1>")
	)
	(segment
		(start 426.247306 -53.121814)
		(end 427.83252 -51.5366)
		(width 0.1143)
		(layer "In4.Cu")
		(net "P3E_CPU0_PE3_OCP_RXP<1>")
	)
	(segment
		(start 298.357036 -99.395788)
		(end 298.389802 -99.395788)
		(width 0.0889)
		(layer "In4.Cu")
		(net "P3E_CPU0_PE3_OCP_RXP<1>")
	)
	(segment
		(start 296.64406 -100.386134)
		(end 296.674032 -100.386134)
		(width 0.0889)
		(layer "In4.Cu")
		(net "P3E_CPU0_PE3_OCP_RXP<1>")
	)
	(segment
		(start 381.898144 -48.047656)
		(end 385.002786 -48.047656)
		(width 0.1143)
		(layer "In4.Cu")
		(net "P3E_CPU0_PE3_OCP_RXP<1>")
	)
	(segment
		(start 306.879498 -95.504)
		(end 307.5432 -95.504)
		(width 0.1143)
		(layer "In4.Cu")
		(net "P3E_CPU0_PE3_OCP_RXP<1>")
	)
	(segment
		(start 361.010454 -53.3527)
		(end 366.599724 -51.814222)
		(width 0.1143)
		(layer "In4.Cu")
		(net "P3E_CPU0_PE3_OCP_RXP<1>")
	)
	(segment
		(start 306.4256 -95.5548)
		(end 306.8066 -95.5548)
		(width 0.0889)
		(layer "In4.Cu")
		(net "P3E_CPU0_PE3_OCP_RXP<1>")
	)
	(segment
		(start 442.094874 -48.552354)
		(end 442.259974 -48.717454)
		(width 0.1143)
		(layer "In4.Cu")
		(net "P3E_CPU0_PE3_OCP_RXP<1>")
	)
	(segment
		(start 333.293466 -58.366914)
		(end 333.785464 -58.144156)
		(width 0.1143)
		(layer "In4.Cu")
		(net "P3E_CPU0_PE3_OCP_RXP<1>")
	)
	(segment
		(start 406.838658 -53.4416)
		(end 414.183576 -53.4416)
		(width 0.1143)
		(layer "In4.Cu")
		(net "P3E_CPU0_PE3_OCP_RXP<1>")
	)
	(segment
		(start 300.936406 -96.919034)
		(end 300.969172 -96.919034)
		(width 0.0889)
		(layer "In4.Cu")
		(net "P3E_CPU0_PE3_OCP_RXP<1>")
	)
	(segment
		(start 439.211974 -48.717454)
		(end 439.554874 -48.717454)
		(width 0.1143)
		(layer "In4.Cu")
		(net "P3E_CPU0_PE3_OCP_RXP<1>")
	)
	(segment
		(start 440.227974 -48.717454)
		(end 440.570874 -48.717454)
		(width 0.1143)
		(layer "In4.Cu")
		(net "P3E_CPU0_PE3_OCP_RXP<1>")
	)
	(segment
		(start 319.130426 -83.917028)
		(end 324.293992 -71.450454)
		(width 0.1143)
		(layer "In4.Cu")
		(net "P3E_CPU0_PE3_OCP_RXP<1>")
	)
	(segment
		(start 442.602874 -48.717454)
		(end 442.767974 -48.552354)
		(width 0.1143)
		(layer "In4.Cu")
		(net "P3E_CPU0_PE3_OCP_RXP<1>")
	)
	(segment
		(start 456.341988 -48.717454)
		(end 458.396086 -46.663356)
		(width 0.1143)
		(layer "In4.Cu")
		(net "P3E_CPU0_PE3_OCP_RXP<1>")
	)
	(segment
		(start 386.969 -48.387)
		(end 386.969 -49.319942)
		(width 0.1143)
		(layer "In4.Cu")
		(net "P3E_CPU0_PE3_OCP_RXP<1>")
	)
	(segment
		(start 306.8574 -95.504)
		(end 306.879498 -95.504)
		(width 0.0889)
		(layer "In4.Cu")
		(net "P3E_CPU0_PE3_OCP_RXP<1>")
	)
	(segment
		(start 294.071294 -99.890834)
		(end 294.099234 -99.890834)
		(width 0.0889)
		(layer "In4.Cu")
		(net "P3E_CPU0_PE3_OCP_RXP<1>")
	)
	(segment
		(start 305.125628 -96.4692)
		(end 305.25847 -96.4692)
		(width 0.0889)
		(layer "In4.Cu")
		(net "P3E_CPU0_PE3_OCP_RXP<1>")
	)
	(segment
		(start 381.812546 -48.133254)
		(end 381.898144 -48.047656)
		(width 0.1143)
		(layer "In4.Cu")
		(net "P3E_CPU0_PE3_OCP_RXP<1>")
	)
	(segment
		(start 386.969 -49.319942)
		(end 387.89356 -50.244502)
		(width 0.1143)
		(layer "In4.Cu")
		(net "P3E_CPU0_PE3_OCP_RXP<1>")
	)
	(segment
		(start 392.823954 -52.565554)
		(end 400.514566 -52.565554)
		(width 0.1143)
		(layer "In4.Cu")
		(net "P3E_CPU0_PE3_OCP_RXP<1>")
	)
	(segment
		(start 436.452264 -51.477164)
		(end 439.211974 -48.717454)
		(width 0.1143)
		(layer "In4.Cu")
		(net "P3E_CPU0_PE3_OCP_RXP<1>")
	)
	(segment
		(start 305.25847 -96.4692)
		(end 305.689762 -96.290638)
		(width 0.0889)
		(layer "In4.Cu")
		(net "P3E_CPU0_PE3_OCP_RXP<1>")
	)
	(segment
		(start 390.502902 -50.244502)
		(end 392.823954 -52.565554)
		(width 0.1143)
		(layer "In4.Cu")
		(net "P3E_CPU0_PE3_OCP_RXP<1>")
	)
	(segment
		(start 441.751974 -48.552354)
		(end 442.094874 -48.552354)
		(width 0.1143)
		(layer "In4.Cu")
		(net "P3E_CPU0_PE3_OCP_RXP<1>")
	)
	(segment
		(start 424.263312 -52.220114)
		(end 425.037758 -52.220114)
		(width 0.1143)
		(layer "In4.Cu")
		(net "P3E_CPU0_PE3_OCP_RXP<1>")
	)
	(segment
		(start 348.728792 -58.144156)
		(end 356.111302 -55.66664)
		(width 0.1143)
		(layer "In4.Cu")
		(net "P3E_CPU0_PE3_OCP_RXP<1>")
	)
	(segment
		(start 441.586874 -48.717454)
		(end 441.751974 -48.552354)
		(width 0.1143)
		(layer "In4.Cu")
		(net "P3E_CPU0_PE3_OCP_RXP<1>")
	)
	(segment
		(start 324.293992 -71.450454)
		(end 333.293466 -58.366914)
		(width 0.1143)
		(layer "In4.Cu")
		(net "P3E_CPU0_PE3_OCP_RXP<1>")
	)
	(segment
		(start 299.219366 -97.909634)
		(end 299.252132 -97.909634)
		(width 0.0889)
		(layer "In4.Cu")
		(net "P3E_CPU0_PE3_OCP_RXP<1>")
	)
	(segment
		(start 367.899442 -50.515012)
		(end 370.874798 -50.515012)
		(width 0.1143)
		(layer "In4.Cu")
		(net "P3E_CPU0_PE3_OCP_RXP<1>")
	)
	(segment
		(start 374.67667 -49.180242)
		(end 375.047764 -48.809148)
		(width 0.1143)
		(layer "In4.Cu")
		(net "P3E_CPU0_PE3_OCP_RXP<1>")
	)
	(segment
		(start 372.209568 -49.180242)
		(end 374.67667 -49.180242)
		(width 0.1143)
		(layer "In4.Cu")
		(net "P3E_CPU0_PE3_OCP_RXP<1>")
	)
	(segment
		(start 306.8066 -95.5548)
		(end 306.8574 -95.504)
		(width 0.0889)
		(layer "In4.Cu")
		(net "P3E_CPU0_PE3_OCP_RXP<1>")
	)
	(segment
		(start 297.507152 -99.890834)
		(end 297.535092 -99.890834)
		(width 0.0889)
		(layer "In4.Cu")
		(net "P3E_CPU0_PE3_OCP_RXP<1>")
	)
	(segment
		(start 440.062874 -48.552354)
		(end 440.227974 -48.717454)
		(width 0.1143)
		(layer "In4.Cu")
		(net "P3E_CPU0_PE3_OCP_RXP<1>")
	)
	(segment
		(start 442.767974 -48.552354)
		(end 443.110874 -48.552354)
		(width 0.1143)
		(layer "In4.Cu")
		(net "P3E_CPU0_PE3_OCP_RXP<1>")
	)
	(arc
		(start 301.823882 -96.423988)
		(mid 302.017732 -96.367638)
		(end 302.159416 -96.223836)
		(width 0.0889)
		(layer "In4.Cu")
		(net "P3E_CPU0_PE3_OCP_RXP<1>")
	)
	(arc
		(start 300.442376 -97.214436)
		(mid 300.650984 -97.002504)
		(end 300.936406 -96.919034)
		(width 0.0889)
		(layer "In4.Cu")
		(net "P3E_CPU0_PE3_OCP_RXP<1>")
	)
	(arc
		(start 299.252132 -97.909634)
		(mid 299.443774 -97.852468)
		(end 299.583856 -97.709736)
		(width 0.0889)
		(layer "In4.Cu")
		(net "P3E_CPU0_PE3_OCP_RXP<1>")
	)
	(arc
		(start 303.876456 -96.223836)
		(mid 304.388266 -95.927915)
		(end 304.900076 -96.223836)
		(width 0.0889)
		(layer "In4.Cu")
		(net "P3E_CPU0_PE3_OCP_RXP<1>")
	)
	(arc
		(start 297.866816 -99.690936)
		(mid 298.07382 -99.480072)
		(end 298.357036 -99.395788)
		(width 0.0889)
		(layer "In4.Cu")
		(net "P3E_CPU0_PE3_OCP_RXP<1>")
	)
	(arc
		(start 296.674032 -100.386134)
		(mid 296.867135 -100.329615)
		(end 297.008296 -100.186236)
		(width 0.0889)
		(layer "In4.Cu")
		(net "P3E_CPU0_PE3_OCP_RXP<1>")
	)
	(arc
		(start 294.099234 -99.890834)
		(mid 294.387379 -99.973153)
		(end 294.59809 -100.186236)
		(width 0.0889)
		(layer "In4.Cu")
		(net "P3E_CPU0_PE3_OCP_RXP<1>")
	)
	(arc
		(start 299.583856 -97.709736)
		(mid 299.79086 -97.498872)
		(end 300.074076 -97.414588)
		(width 0.0889)
		(layer "In4.Cu")
		(net "P3E_CPU0_PE3_OCP_RXP<1>")
	)
	(arc
		(start 295.45661 -100.681536)
		(mid 295.595354 -100.823569)
		(end 295.785286 -100.881434)
		(width 0.0889)
		(layer "In4.Cu")
		(net "P3E_CPU0_PE3_OCP_RXP<1>")
	)
	(arc
		(start 298.389802 -99.395788)
		(mid 298.727971 -99.19099)
		(end 298.725336 -98.795586)
		(width 0.0889)
		(layer "In4.Cu")
		(net "P3E_CPU0_PE3_OCP_RXP<1>")
	)
	(arc
		(start 304.900076 -96.223836)
		(mid 304.923165 -96.259705)
		(end 304.949606 -96.293178)
		(width 0.0889)
		(layer "In4.Cu")
		(net "P3E_CPU0_PE3_OCP_RXP<1>")
	)
	(arc
		(start 297.008296 -100.186236)
		(mid 297.219009 -99.973157)
		(end 297.507152 -99.890834)
		(width 0.0889)
		(layer "In4.Cu")
		(net "P3E_CPU0_PE3_OCP_RXP<1>")
	)
	(arc
		(start 293.292784 -99.398836)
		(mid 293.551054 -99.491544)
		(end 293.73957 -99.690936)
		(width 0.0889)
		(layer "In4.Cu")
		(net "P3E_CPU0_PE3_OCP_RXP<1>")
	)
	(arc
		(start 294.96258 -100.386134)
		(mid 295.248004 -100.469601)
		(end 295.45661 -100.681536)
		(width 0.0889)
		(layer "In4.Cu")
		(net "P3E_CPU0_PE3_OCP_RXP<1>")
	)
	(arc
		(start 298.725336 -98.795586)
		(mid 298.721007 -98.212414)
		(end 299.219366 -97.909634)
		(width 0.0889)
		(layer "In4.Cu")
		(net "P3E_CPU0_PE3_OCP_RXP<1>")
	)
	(arc
		(start 294.59809 -100.186236)
		(mid 294.736834 -100.328269)
		(end 294.926766 -100.386134)
		(width 0.0889)
		(layer "In4.Cu")
		(net "P3E_CPU0_PE3_OCP_RXP<1>")
	)
	(arc
		(start 301.300896 -96.719136)
		(mid 301.5079 -96.508272)
		(end 301.791116 -96.423988)
		(width 0.0889)
		(layer "In4.Cu")
		(net "P3E_CPU0_PE3_OCP_RXP<1>")
	)
	(arc
		(start 293.73957 -99.690936)
		(mid 293.879649 -99.833672)
		(end 294.071294 -99.890834)
		(width 0.0889)
		(layer "In4.Cu")
		(net "P3E_CPU0_PE3_OCP_RXP<1>")
	)
	(arc
		(start 295.821354 -100.881434)
		(mid 296.011283 -100.823564)
		(end 296.15003 -100.681536)
		(width 0.0889)
		(layer "In4.Cu")
		(net "P3E_CPU0_PE3_OCP_RXP<1>")
	)
	(arc
		(start 297.535092 -99.890834)
		(mid 297.726734 -99.833668)
		(end 297.866816 -99.690936)
		(width 0.0889)
		(layer "In4.Cu")
		(net "P3E_CPU0_PE3_OCP_RXP<1>")
	)
	(arc
		(start 300.106842 -97.414588)
		(mid 300.300692 -97.358238)
		(end 300.442376 -97.214436)
		(width 0.0889)
		(layer "In4.Cu")
		(net "P3E_CPU0_PE3_OCP_RXP<1>")
	)
	(arc
		(start 302.159416 -96.223836)
		(mid 302.671226 -95.928042)
		(end 303.183036 -96.223836)
		(width 0.0889)
		(layer "In4.Cu")
		(net "P3E_CPU0_PE3_OCP_RXP<1>")
	)
	(arc
		(start 300.969172 -96.919034)
		(mid 301.160814 -96.861868)
		(end 301.300896 -96.719136)
		(width 0.0889)
		(layer "In4.Cu")
		(net "P3E_CPU0_PE3_OCP_RXP<1>")
	)
	(arc
		(start 303.183036 -96.223836)
		(mid 303.529746 -96.424274)
		(end 303.876456 -96.223836)
		(width 0.0889)
		(layer "In4.Cu")
		(net "P3E_CPU0_PE3_OCP_RXP<1>")
	)
	(arc
		(start 296.15003 -100.681536)
		(mid 296.358638 -100.469604)
		(end 296.64406 -100.386134)
		(width 0.0889)
		(layer "In4.Cu")
		(net "P3E_CPU0_PE3_OCP_RXP<1>")
	)
	(segment
		(start 464.334098 -120.913398)
		(end 464.334098 -118.609872)
		(width 0.1143)
		(layer "F.Cu")
		(net "P3E_CPU0_PE3_OCP_RXP<15>")
	)
	(segment
		(start 464.811618 -121.139458)
		(end 464.560158 -121.139458)
		(width 0.1143)
		(layer "F.Cu")
		(net "P3E_CPU0_PE3_OCP_RXP<15>")
	)
	(segment
		(start 464.600798 -118.343172)
		(end 464.600798 -116.993162)
		(width 0.1143)
		(layer "F.Cu")
		(net "P3E_CPU0_PE3_OCP_RXP<15>")
	)
	(segment
		(start 464.334098 -118.609872)
		(end 464.600798 -118.343172)
		(width 0.1143)
		(layer "F.Cu")
		(net "P3E_CPU0_PE3_OCP_RXP<15>")
	)
	(segment
		(start 464.560158 -121.139458)
		(end 464.334098 -120.913398)
		(width 0.1143)
		(layer "F.Cu")
		(net "P3E_CPU0_PE3_OCP_RXP<15>")
	)
	(segment
		(start 299.524166 -89.089738)
		(end 300.095666 -89.089738)
		(width 0.1143)
		(layer "F.Cu")
		(net "P3E_CPU0_PE3_OCP_RXP<15>")
	)
	(via
		(at 464.811618 -121.139458)
		(size 0.508)
		(drill 0.254)
		(layers "F.Cu" "B.Cu")
		(net "P3E_CPU0_PE3_OCP_RXP<15>")
	)
	(via
		(at 300.095666 -89.089738)
		(size 0.508)
		(drill 0.254)
		(layers "F.Cu" "B.Cu")
		(net "P3E_CPU0_PE3_OCP_RXP<15>")
	)
	(segment
		(start 410.076904 -147.98929)
		(end 410.652976 -147.98929)
		(width 0.1143)
		(layer "In11.Cu")
		(net "P3E_CPU0_PE3_OCP_RXP<15>")
	)
	(segment
		(start 296.15003 -99.290886)
		(end 296.154856 -99.299522)
		(width 0.0889)
		(layer "In11.Cu")
		(net "P3E_CPU0_PE3_OCP_RXP<15>")
	)
	(segment
		(start 300.278038 -104.727502)
		(end 302.014636 -106.4641)
		(width 0.1143)
		(layer "In11.Cu")
		(net "P3E_CPU0_PE3_OCP_RXP<15>")
	)
	(segment
		(start 391.14476 -146.244564)
		(end 391.187686 -146.244564)
		(width 0.1143)
		(layer "In11.Cu")
		(net "P3E_CPU0_PE3_OCP_RXP<15>")
	)
	(segment
		(start 317.1952 -120.7262)
		(end 317.7794 -121.3104)
		(width 0.1143)
		(layer "In11.Cu")
		(net "P3E_CPU0_PE3_OCP_RXP<15>")
	)
	(segment
		(start 298.72559 -102.75824)
		(end 298.80052 -102.888288)
		(width 0.0889)
		(layer "In11.Cu")
		(net "P3E_CPU0_PE3_OCP_RXP<15>")
	)
	(segment
		(start 360.883708 -131.56946)
		(end 361.54614 -131.976114)
		(width 0.1143)
		(layer "In11.Cu")
		(net "P3E_CPU0_PE3_OCP_RXP<15>")
	)
	(segment
		(start 300.106842 -89.489788)
		(end 300.074076 -89.489788)
		(width 0.0889)
		(layer "In11.Cu")
		(net "P3E_CPU0_PE3_OCP_RXP<15>")
	)
	(segment
		(start 298.400216 -89.489788)
		(end 298.357036 -89.489788)
		(width 0.0889)
		(layer "In11.Cu")
		(net "P3E_CPU0_PE3_OCP_RXP<15>")
	)
	(segment
		(start 367.834672 -140.783564)
		(end 374.826276 -142.206218)
		(width 0.1143)
		(layer "In11.Cu")
		(net "P3E_CPU0_PE3_OCP_RXP<15>")
	)
	(segment
		(start 417.467542 -150.083774)
		(end 420.623238 -148.776182)
		(width 0.1143)
		(layer "In11.Cu")
		(net "P3E_CPU0_PE3_OCP_RXP<15>")
	)
	(segment
		(start 380.881382 -143.774668)
		(end 384.29438 -144.453356)
		(width 0.1143)
		(layer "In11.Cu")
		(net "P3E_CPU0_PE3_OCP_RXP<15>")
	)
	(segment
		(start 363.806994 -134.264908)
		(end 364.61192 -135.375904)
		(width 0.1143)
		(layer "In11.Cu")
		(net "P3E_CPU0_PE3_OCP_RXP<15>")
	)
	(segment
		(start 322.690998 -124.5489)
		(end 323.592952 -124.5489)
		(width 0.1143)
		(layer "In11.Cu")
		(net "P3E_CPU0_PE3_OCP_RXP<15>")
	)
	(segment
		(start 424.496738 -146.686524)
		(end 430.464976 -145.66646)
		(width 0.1143)
		(layer "In11.Cu")
		(net "P3E_CPU0_PE3_OCP_RXP<15>")
	)
	(segment
		(start 461.3021 -123.793758)
		(end 461.842358 -123.2535)
		(width 0.1143)
		(layer "In11.Cu")
		(net "P3E_CPU0_PE3_OCP_RXP<15>")
	)
	(segment
		(start 359.743756 -131.56946)
		(end 360.883708 -131.56946)
		(width 0.1143)
		(layer "In11.Cu")
		(net "P3E_CPU0_PE3_OCP_RXP<15>")
	)
	(segment
		(start 435.912514 -143.265398)
		(end 436.943754 -141.527022)
		(width 0.1143)
		(layer "In11.Cu")
		(net "P3E_CPU0_PE3_OCP_RXP<15>")
	)
	(segment
		(start 391.187686 -146.244564)
		(end 394.335 -146.634454)
		(width 0.1143)
		(layer "In11.Cu")
		(net "P3E_CPU0_PE3_OCP_RXP<15>")
	)
	(segment
		(start 294.43299 -96.319086)
		(end 294.437816 -96.327722)
		(width 0.0889)
		(layer "In11.Cu")
		(net "P3E_CPU0_PE3_OCP_RXP<15>")
	)
	(segment
		(start 302.014636 -106.4641)
		(end 305.199542 -106.4641)
		(width 0.1143)
		(layer "In11.Cu")
		(net "P3E_CPU0_PE3_OCP_RXP<15>")
	)
	(segment
		(start 298.360846 -102.558088)
		(end 298.396152 -102.558088)
		(width 0.0889)
		(layer "In11.Cu")
		(net "P3E_CPU0_PE3_OCP_RXP<15>")
	)
	(segment
		(start 464.33105 -121.806208)
		(end 464.33105 -121.30151)
		(width 0.1143)
		(layer "In11.Cu")
		(net "P3E_CPU0_PE3_OCP_RXP<15>")
	)
	(segment
		(start 399.45056 -147.636992)
		(end 402.8821 -148.3233)
		(width 0.1143)
		(layer "In11.Cu")
		(net "P3E_CPU0_PE3_OCP_RXP<15>")
	)
	(segment
		(start 317.7794 -121.3104)
		(end 320.198242 -121.3104)
		(width 0.1143)
		(layer "In11.Cu")
		(net "P3E_CPU0_PE3_OCP_RXP<15>")
	)
	(segment
		(start 437.670194 -141.226032)
		(end 439.641742 -137.931144)
		(width 0.1143)
		(layer "In11.Cu")
		(net "P3E_CPU0_PE3_OCP_RXP<15>")
	)
	(segment
		(start 361.888024 -132.703316)
		(end 361.888786 -132.704078)
		(width 0.1143)
		(layer "In11.Cu")
		(net "P3E_CPU0_PE3_OCP_RXP<15>")
	)
	(segment
		(start 451.128384 -128.688338)
		(end 458.56271 -127.21082)
		(width 0.1143)
		(layer "In11.Cu")
		(net "P3E_CPU0_PE3_OCP_RXP<15>")
	)
	(segment
		(start 361.888786 -132.704078)
		(end 361.891072 -132.704332)
		(width 0.1143)
		(layer "In11.Cu")
		(net "P3E_CPU0_PE3_OCP_RXP<15>")
	)
	(segment
		(start 300.262544 -104.712008)
		(end 300.278038 -104.727502)
		(width 0.0889)
		(layer "In11.Cu")
		(net "P3E_CPU0_PE3_OCP_RXP<15>")
	)
	(segment
		(start 434.110384 -146.333972)
		(end 435.145688 -145.703798)
		(width 0.1143)
		(layer "In11.Cu")
		(net "P3E_CPU0_PE3_OCP_RXP<15>")
	)
	(segment
		(start 365.173006 -140.435076)
		(end 366.992154 -140.927836)
		(width 0.1143)
		(layer "In11.Cu")
		(net "P3E_CPU0_PE3_OCP_RXP<15>")
	)
	(segment
		(start 323.759068 -124.382784)
		(end 324.78599 -124.382784)
		(width 0.1143)
		(layer "In11.Cu")
		(net "P3E_CPU0_PE3_OCP_RXP<15>")
	)
	(segment
		(start 410.652976 -147.98929)
		(end 412.74746 -150.083774)
		(width 0.1143)
		(layer "In11.Cu")
		(net "P3E_CPU0_PE3_OCP_RXP<15>")
	)
	(segment
		(start 397.095726 -148.119338)
		(end 399.45056 -147.636992)
		(width 0.1143)
		(layer "In11.Cu")
		(net "P3E_CPU0_PE3_OCP_RXP<15>")
	)
	(segment
		(start 461.3021 -125.381258)
		(end 461.3021 -123.793758)
		(width 0.1143)
		(layer "In11.Cu")
		(net "P3E_CPU0_PE3_OCP_RXP<15>")
	)
	(segment
		(start 317.1952 -118.459758)
		(end 317.1952 -120.7262)
		(width 0.1143)
		(layer "In11.Cu")
		(net "P3E_CPU0_PE3_OCP_RXP<15>")
	)
	(segment
		(start 420.623238 -148.776182)
		(end 422.054528 -147.74672)
		(width 0.1143)
		(layer "In11.Cu")
		(net "P3E_CPU0_PE3_OCP_RXP<15>")
	)
	(segment
		(start 330.118212 -127.782574)
		(end 331.58938 -129.253742)
		(width 0.1143)
		(layer "In11.Cu")
		(net "P3E_CPU0_PE3_OCP_RXP<15>")
	)
	(segment
		(start 361.892596 -132.706364)
		(end 362.83138 -134.04088)
		(width 0.1143)
		(layer "In11.Cu")
		(net "P3E_CPU0_PE3_OCP_RXP<15>")
	)
	(segment
		(start 396.078456 -147.912328)
		(end 397.095726 -148.119338)
		(width 0.1143)
		(layer "In11.Cu")
		(net "P3E_CPU0_PE3_OCP_RXP<15>")
	)
	(segment
		(start 294.43299 -95.328486)
		(end 294.437816 -95.337122)
		(width 0.0889)
		(layer "In11.Cu")
		(net "P3E_CPU0_PE3_OCP_RXP<15>")
	)
	(segment
		(start 464.493102 -121.139458)
		(end 464.811618 -121.139458)
		(width 0.1143)
		(layer "In11.Cu")
		(net "P3E_CPU0_PE3_OCP_RXP<15>")
	)
	(segment
		(start 322.084192 -124.381006)
		(end 322.523104 -124.381006)
		(width 0.1143)
		(layer "In11.Cu")
		(net "P3E_CPU0_PE3_OCP_RXP<15>")
	)
	(segment
		(start 364.862364 -136.092692)
		(end 364.237524 -138.177016)
		(width 0.1143)
		(layer "In11.Cu")
		(net "P3E_CPU0_PE3_OCP_RXP<15>")
	)
	(segment
		(start 379.265688 -144.083024)
		(end 380.881382 -143.774668)
		(width 0.1143)
		(layer "In11.Cu")
		(net "P3E_CPU0_PE3_OCP_RXP<15>")
	)
	(segment
		(start 300.095666 -89.089738)
		(end 300.388782 -89.258648)
		(width 0.0889)
		(layer "In11.Cu")
		(net "P3E_CPU0_PE3_OCP_RXP<15>")
	)
	(segment
		(start 300.388782 -89.258648)
		(end 300.409864 -89.337388)
		(width 0.0889)
		(layer "In11.Cu")
		(net "P3E_CPU0_PE3_OCP_RXP<15>")
	)
	(segment
		(start 436.943754 -141.527022)
		(end 437.670194 -141.226032)
		(width 0.1143)
		(layer "In11.Cu")
		(net "P3E_CPU0_PE3_OCP_RXP<15>")
	)
	(segment
		(start 439.641742 -137.931144)
		(end 441.019692 -134.80034)
		(width 0.1143)
		(layer "In11.Cu")
		(net "P3E_CPU0_PE3_OCP_RXP<15>")
	)
	(segment
		(start 295.78173 -98.100134)
		(end 295.814496 -98.100134)
		(width 0.0889)
		(layer "In11.Cu")
		(net "P3E_CPU0_PE3_OCP_RXP<15>")
	)
	(segment
		(start 298.725336 -102.757986)
		(end 298.725336 -102.75824)
		(width 0.0889)
		(layer "In11.Cu")
		(net "P3E_CPU0_PE3_OCP_RXP<15>")
	)
	(segment
		(start 294.43299 -93.347286)
		(end 294.437816 -93.355922)
		(width 0.0889)
		(layer "In11.Cu")
		(net "P3E_CPU0_PE3_OCP_RXP<15>")
	)
	(segment
		(start 458.56271 -127.21082)
		(end 461.3021 -125.381258)
		(width 0.1143)
		(layer "In11.Cu")
		(net "P3E_CPU0_PE3_OCP_RXP<15>")
	)
	(segment
		(start 366.992154 -140.927836)
		(end 367.834672 -140.783564)
		(width 0.1143)
		(layer "In11.Cu")
		(net "P3E_CPU0_PE3_OCP_RXP<15>")
	)
	(segment
		(start 404.30069 -148.039582)
		(end 406.091136 -148.781008)
		(width 0.1143)
		(layer "In11.Cu")
		(net "P3E_CPU0_PE3_OCP_RXP<15>")
	)
	(segment
		(start 408.1653 -148.781008)
		(end 410.076904 -147.98929)
		(width 0.1143)
		(layer "In11.Cu")
		(net "P3E_CPU0_PE3_OCP_RXP<15>")
	)
	(segment
		(start 294.42664 -92.346018)
		(end 294.43299 -92.356686)
		(width 0.0889)
		(layer "In11.Cu")
		(net "P3E_CPU0_PE3_OCP_RXP<15>")
	)
	(segment
		(start 447.061844 -131.71551)
		(end 451.128384 -128.688338)
		(width 0.1143)
		(layer "In11.Cu")
		(net "P3E_CPU0_PE3_OCP_RXP<15>")
	)
	(segment
		(start 462.883758 -123.2535)
		(end 464.33105 -121.806208)
		(width 0.1143)
		(layer "In11.Cu")
		(net "P3E_CPU0_PE3_OCP_RXP<15>")
	)
	(segment
		(start 323.592952 -124.5489)
		(end 323.759068 -124.382784)
		(width 0.1143)
		(layer "In11.Cu")
		(net "P3E_CPU0_PE3_OCP_RXP<15>")
	)
	(segment
		(start 406.091136 -148.781008)
		(end 408.1653 -148.781008)
		(width 0.1143)
		(layer "In11.Cu")
		(net "P3E_CPU0_PE3_OCP_RXP<15>")
	)
	(segment
		(start 464.33105 -121.30151)
		(end 464.493102 -121.139458)
		(width 0.1143)
		(layer "In11.Cu")
		(net "P3E_CPU0_PE3_OCP_RXP<15>")
	)
	(segment
		(start 324.78599 -124.382784)
		(end 328.18578 -127.782574)
		(width 0.1143)
		(layer "In11.Cu")
		(net "P3E_CPU0_PE3_OCP_RXP<15>")
	)
	(segment
		(start 336.291174 -131.200652)
		(end 336.291936 -131.200144)
		(width 0.1143)
		(layer "In11.Cu")
		(net "P3E_CPU0_PE3_OCP_RXP<15>")
	)
	(segment
		(start 361.891072 -132.704332)
		(end 361.892596 -132.706364)
		(width 0.1143)
		(layer "In11.Cu")
		(net "P3E_CPU0_PE3_OCP_RXP<15>")
	)
	(segment
		(start 294.955976 -91.470988)
		(end 294.92321 -91.470988)
		(width 0.0889)
		(layer "In11.Cu")
		(net "P3E_CPU0_PE3_OCP_RXP<15>")
	)
	(segment
		(start 388.51967 -144.453356)
		(end 389.655558 -144.983454)
		(width 0.1143)
		(layer "In11.Cu")
		(net "P3E_CPU0_PE3_OCP_RXP<15>")
	)
	(segment
		(start 299.252132 -89.984834)
		(end 299.22216 -89.984834)
		(width 0.0889)
		(layer "In11.Cu")
		(net "P3E_CPU0_PE3_OCP_RXP<15>")
	)
	(segment
		(start 321.5005 -122.612658)
		(end 321.5005 -123.797314)
		(width 0.1143)
		(layer "In11.Cu")
		(net "P3E_CPU0_PE3_OCP_RXP<15>")
	)
	(segment
		(start 394.335 -146.634454)
		(end 395.823186 -147.794726)
		(width 0.1143)
		(layer "In11.Cu")
		(net "P3E_CPU0_PE3_OCP_RXP<15>")
	)
	(segment
		(start 298.725336 -102.75824)
		(end 298.72559 -102.75824)
		(width 0.0889)
		(layer "In11.Cu")
		(net "P3E_CPU0_PE3_OCP_RXP<15>")
	)
	(segment
		(start 331.58938 -129.253742)
		(end 336.291174 -131.200652)
		(width 0.1143)
		(layer "In11.Cu")
		(net "P3E_CPU0_PE3_OCP_RXP<15>")
	)
	(segment
		(start 296.15003 -100.681536)
		(end 296.14368 -100.692204)
		(width 0.0889)
		(layer "In11.Cu")
		(net "P3E_CPU0_PE3_OCP_RXP<15>")
	)
	(segment
		(start 294.43299 -94.737936)
		(end 294.42664 -94.748604)
		(width 0.0889)
		(layer "In11.Cu")
		(net "P3E_CPU0_PE3_OCP_RXP<15>")
	)
	(segment
		(start 294.43299 -92.356686)
		(end 294.437816 -92.365322)
		(width 0.0889)
		(layer "In11.Cu")
		(net "P3E_CPU0_PE3_OCP_RXP<15>")
	)
	(segment
		(start 389.655558 -144.983454)
		(end 390.177528 -145.82521)
		(width 0.1143)
		(layer "In11.Cu")
		(net "P3E_CPU0_PE3_OCP_RXP<15>")
	)
	(segment
		(start 297.008296 -90.280236)
		(end 297.004994 -90.286078)
		(width 0.0889)
		(layer "In11.Cu")
		(net "P3E_CPU0_PE3_OCP_RXP<15>")
	)
	(segment
		(start 441.019692 -134.80034)
		(end 447.061844 -131.71551)
		(width 0.1143)
		(layer "In11.Cu")
		(net "P3E_CPU0_PE3_OCP_RXP<15>")
	)
	(segment
		(start 298.80052 -103.178356)
		(end 300.262544 -104.64038)
		(width 0.0889)
		(layer "In11.Cu")
		(net "P3E_CPU0_PE3_OCP_RXP<15>")
	)
	(segment
		(start 358.644952 -132.024628)
		(end 359.743756 -131.56946)
		(width 0.1143)
		(layer "In11.Cu")
		(net "P3E_CPU0_PE3_OCP_RXP<15>")
	)
	(segment
		(start 297.535092 -89.984834)
		(end 297.502326 -89.984834)
		(width 0.0889)
		(layer "In11.Cu")
		(net "P3E_CPU0_PE3_OCP_RXP<15>")
	)
	(segment
		(start 296.14368 -99.280218)
		(end 296.15003 -99.290886)
		(width 0.0889)
		(layer "In11.Cu")
		(net "P3E_CPU0_PE3_OCP_RXP<15>")
	)
	(segment
		(start 296.66184 -90.480388)
		(end 296.64025 -90.480388)
		(width 0.0889)
		(layer "In11.Cu")
		(net "P3E_CPU0_PE3_OCP_RXP<15>")
	)
	(segment
		(start 361.54614 -131.976114)
		(end 361.888024 -132.703316)
		(width 0.1143)
		(layer "In11.Cu")
		(net "P3E_CPU0_PE3_OCP_RXP<15>")
	)
	(segment
		(start 298.80052 -102.888288)
		(end 298.80052 -103.178356)
		(width 0.0889)
		(layer "In11.Cu")
		(net "P3E_CPU0_PE3_OCP_RXP<15>")
	)
	(segment
		(start 395.823186 -147.794726)
		(end 396.078456 -147.912328)
		(width 0.1143)
		(layer "In11.Cu")
		(net "P3E_CPU0_PE3_OCP_RXP<15>")
	)
	(segment
		(start 321.5005 -123.797314)
		(end 322.084192 -124.381006)
		(width 0.1143)
		(layer "In11.Cu")
		(net "P3E_CPU0_PE3_OCP_RXP<15>")
	)
	(segment
		(start 461.842358 -123.2535)
		(end 462.883758 -123.2535)
		(width 0.1143)
		(layer "In11.Cu")
		(net "P3E_CPU0_PE3_OCP_RXP<15>")
	)
	(segment
		(start 364.237524 -138.177016)
		(end 365.173006 -140.435076)
		(width 0.1143)
		(layer "In11.Cu")
		(net "P3E_CPU0_PE3_OCP_RXP<15>")
	)
	(segment
		(start 433.145184 -146.459956)
		(end 434.110384 -146.333972)
		(width 0.1143)
		(layer "In11.Cu")
		(net "P3E_CPU0_PE3_OCP_RXP<15>")
	)
	(segment
		(start 390.177528 -145.82521)
		(end 391.14476 -146.244564)
		(width 0.1143)
		(layer "In11.Cu")
		(net "P3E_CPU0_PE3_OCP_RXP<15>")
	)
	(segment
		(start 374.826276 -142.206218)
		(end 376.77725 -143.64081)
		(width 0.1143)
		(layer "In11.Cu")
		(net "P3E_CPU0_PE3_OCP_RXP<15>")
	)
	(segment
		(start 305.199542 -106.4641)
		(end 317.1952 -118.459758)
		(width 0.1143)
		(layer "In11.Cu")
		(net "P3E_CPU0_PE3_OCP_RXP<15>")
	)
	(segment
		(start 376.77725 -143.64081)
		(end 379.265688 -144.083024)
		(width 0.1143)
		(layer "In11.Cu")
		(net "P3E_CPU0_PE3_OCP_RXP<15>")
	)
	(segment
		(start 384.29438 -144.453356)
		(end 388.51967 -144.453356)
		(width 0.1143)
		(layer "In11.Cu")
		(net "P3E_CPU0_PE3_OCP_RXP<15>")
	)
	(segment
		(start 297.004994 -101.761798)
		(end 297.008296 -101.76764)
		(width 0.0889)
		(layer "In11.Cu")
		(net "P3E_CPU0_PE3_OCP_RXP<15>")
	)
	(segment
		(start 341.94623 -134.81431)
		(end 355.85527 -134.81431)
		(width 0.1143)
		(layer "In11.Cu")
		(net "P3E_CPU0_PE3_OCP_RXP<15>")
	)
	(segment
		(start 294.42664 -93.336618)
		(end 294.43299 -93.347286)
		(width 0.0889)
		(layer "In11.Cu")
		(net "P3E_CPU0_PE3_OCP_RXP<15>")
	)
	(segment
		(start 320.198242 -121.3104)
		(end 321.5005 -122.612658)
		(width 0.1143)
		(layer "In11.Cu")
		(net "P3E_CPU0_PE3_OCP_RXP<15>")
	)
	(segment
		(start 402.8821 -148.3233)
		(end 404.30069 -148.039582)
		(width 0.1143)
		(layer "In11.Cu")
		(net "P3E_CPU0_PE3_OCP_RXP<15>")
	)
	(segment
		(start 294.92702 -97.605088)
		(end 294.959786 -97.605088)
		(width 0.0889)
		(layer "In11.Cu")
		(net "P3E_CPU0_PE3_OCP_RXP<15>")
	)
	(segment
		(start 322.523104 -124.381006)
		(end 322.690998 -124.5489)
		(width 0.1143)
		(layer "In11.Cu")
		(net "P3E_CPU0_PE3_OCP_RXP<15>")
	)
	(segment
		(start 362.83138 -134.04088)
		(end 363.806994 -134.264908)
		(width 0.1143)
		(layer "In11.Cu")
		(net "P3E_CPU0_PE3_OCP_RXP<15>")
	)
	(segment
		(start 355.85527 -134.81431)
		(end 358.644952 -132.024628)
		(width 0.1143)
		(layer "In11.Cu")
		(net "P3E_CPU0_PE3_OCP_RXP<15>")
	)
	(segment
		(start 294.42664 -96.308418)
		(end 294.43299 -96.319086)
		(width 0.0889)
		(layer "In11.Cu")
		(net "P3E_CPU0_PE3_OCP_RXP<15>")
	)
	(segment
		(start 430.464976 -145.66646)
		(end 433.145184 -146.459956)
		(width 0.1143)
		(layer "In11.Cu")
		(net "P3E_CPU0_PE3_OCP_RXP<15>")
	)
	(segment
		(start 364.61192 -135.375904)
		(end 364.862364 -136.092692)
		(width 0.1143)
		(layer "In11.Cu")
		(net "P3E_CPU0_PE3_OCP_RXP<15>")
	)
	(segment
		(start 435.145688 -145.703798)
		(end 435.912514 -143.265398)
		(width 0.1143)
		(layer "In11.Cu")
		(net "P3E_CPU0_PE3_OCP_RXP<15>")
	)
	(segment
		(start 412.74746 -150.083774)
		(end 417.467542 -150.083774)
		(width 0.1143)
		(layer "In11.Cu")
		(net "P3E_CPU0_PE3_OCP_RXP<15>")
	)
	(segment
		(start 295.818306 -90.975434)
		(end 295.78554 -90.975434)
		(width 0.0889)
		(layer "In11.Cu")
		(net "P3E_CPU0_PE3_OCP_RXP<15>")
	)
	(segment
		(start 328.18578 -127.782574)
		(end 330.118212 -127.782574)
		(width 0.1143)
		(layer "In11.Cu")
		(net "P3E_CPU0_PE3_OCP_RXP<15>")
	)
	(segment
		(start 297.495214 -102.062534)
		(end 297.531282 -102.062534)
		(width 0.0889)
		(layer "In11.Cu")
		(net "P3E_CPU0_PE3_OCP_RXP<15>")
	)
	(segment
		(start 422.054528 -147.74672)
		(end 424.496738 -146.686524)
		(width 0.1143)
		(layer "In11.Cu")
		(net "P3E_CPU0_PE3_OCP_RXP<15>")
	)
	(segment
		(start 337.420204 -133.373876)
		(end 341.94623 -134.81431)
		(width 0.1143)
		(layer "In11.Cu")
		(net "P3E_CPU0_PE3_OCP_RXP<15>")
	)
	(segment
		(start 300.262544 -104.64038)
		(end 300.262544 -104.712008)
		(width 0.0889)
		(layer "In11.Cu")
		(net "P3E_CPU0_PE3_OCP_RXP<15>")
	)
	(segment
		(start 336.291936 -131.200144)
		(end 337.420204 -133.373876)
		(width 0.1143)
		(layer "In11.Cu")
		(net "P3E_CPU0_PE3_OCP_RXP<15>")
	)
	(segment
		(start 296.648886 -101.567488)
		(end 296.66184 -101.567488)
		(width 0.0889)
		(layer "In11.Cu")
		(net "P3E_CPU0_PE3_OCP_RXP<15>")
	)
	(arc
		(start 298.396152 -102.558088)
		(mid 298.586394 -102.615823)
		(end 298.725336 -102.757986)
		(width 0.0889)
		(layer "In11.Cu")
		(net "P3E_CPU0_PE3_OCP_RXP<15>")
	)
	(arc
		(start 294.43299 -94.33814)
		(mid 294.486489 -94.538038)
		(end 294.43299 -94.737936)
		(width 0.0889)
		(layer "In11.Cu")
		(net "P3E_CPU0_PE3_OCP_RXP<15>")
	)
	(arc
		(start 298.890436 -89.784936)
		(mid 298.683432 -89.574072)
		(end 298.400216 -89.489788)
		(width 0.0889)
		(layer "In11.Cu")
		(net "P3E_CPU0_PE3_OCP_RXP<15>")
	)
	(arc
		(start 300.409864 -89.337388)
		(mid 300.275302 -89.4473)
		(end 300.106842 -89.489788)
		(width 0.0889)
		(layer "In11.Cu")
		(net "P3E_CPU0_PE3_OCP_RXP<15>")
	)
	(arc
		(start 296.15003 -98.700336)
		(mid 296.070808 -98.989454)
		(end 296.14368 -99.280218)
		(width 0.0889)
		(layer "In11.Cu")
		(net "P3E_CPU0_PE3_OCP_RXP<15>")
	)
	(arc
		(start 294.92321 -91.470988)
		(mid 294.43082 -91.769921)
		(end 294.42664 -92.346018)
		(width 0.0889)
		(layer "In11.Cu")
		(net "P3E_CPU0_PE3_OCP_RXP<15>")
	)
	(arc
		(start 299.22216 -89.984834)
		(mid 299.030518 -89.927668)
		(end 298.890436 -89.784936)
		(width 0.0889)
		(layer "In11.Cu")
		(net "P3E_CPU0_PE3_OCP_RXP<15>")
	)
	(arc
		(start 297.866816 -89.784936)
		(mid 297.726737 -89.927672)
		(end 297.535092 -89.984834)
		(width 0.0889)
		(layer "In11.Cu")
		(net "P3E_CPU0_PE3_OCP_RXP<15>")
	)
	(arc
		(start 296.64025 -90.480388)
		(mid 296.357033 -90.564669)
		(end 296.15003 -90.775536)
		(width 0.0889)
		(layer "In11.Cu")
		(net "P3E_CPU0_PE3_OCP_RXP<15>")
	)
	(arc
		(start 294.43299 -95.728536)
		(mid 294.353768 -96.017654)
		(end 294.42664 -96.308418)
		(width 0.0889)
		(layer "In11.Cu")
		(net "P3E_CPU0_PE3_OCP_RXP<15>")
	)
	(arc
		(start 294.43299 -96.719136)
		(mid 294.428661 -97.302308)
		(end 294.92702 -97.605088)
		(width 0.0889)
		(layer "In11.Cu")
		(net "P3E_CPU0_PE3_OCP_RXP<15>")
	)
	(arc
		(start 296.15003 -100.28174)
		(mid 296.203529 -100.481638)
		(end 296.15003 -100.681536)
		(width 0.0889)
		(layer "In11.Cu")
		(net "P3E_CPU0_PE3_OCP_RXP<15>")
	)
	(arc
		(start 300.074076 -89.489788)
		(mid 299.790859 -89.574069)
		(end 299.583856 -89.784936)
		(width 0.0889)
		(layer "In11.Cu")
		(net "P3E_CPU0_PE3_OCP_RXP<15>")
	)
	(arc
		(start 294.959786 -97.605088)
		(mid 295.151428 -97.662254)
		(end 295.29151 -97.804986)
		(width 0.0889)
		(layer "In11.Cu")
		(net "P3E_CPU0_PE3_OCP_RXP<15>")
	)
	(arc
		(start 295.78554 -90.975434)
		(mid 295.500116 -91.058901)
		(end 295.29151 -91.270836)
		(width 0.0889)
		(layer "In11.Cu")
		(net "P3E_CPU0_PE3_OCP_RXP<15>")
	)
	(arc
		(start 294.43299 -92.756736)
		(mid 294.353768 -93.045854)
		(end 294.42664 -93.336618)
		(width 0.0889)
		(layer "In11.Cu")
		(net "P3E_CPU0_PE3_OCP_RXP<15>")
	)
	(arc
		(start 296.15003 -90.775536)
		(mid 296.009951 -90.918272)
		(end 295.818306 -90.975434)
		(width 0.0889)
		(layer "In11.Cu")
		(net "P3E_CPU0_PE3_OCP_RXP<15>")
	)
	(arc
		(start 294.437816 -96.327722)
		(mid 294.486571 -96.524074)
		(end 294.43299 -96.719136)
		(width 0.0889)
		(layer "In11.Cu")
		(net "P3E_CPU0_PE3_OCP_RXP<15>")
	)
	(arc
		(start 296.66184 -101.567488)
		(mid 296.859001 -101.619447)
		(end 297.004994 -101.761798)
		(width 0.0889)
		(layer "In11.Cu")
		(net "P3E_CPU0_PE3_OCP_RXP<15>")
	)
	(arc
		(start 294.43299 -93.747336)
		(mid 294.353859 -94.042738)
		(end 294.43299 -94.33814)
		(width 0.0889)
		(layer "In11.Cu")
		(net "P3E_CPU0_PE3_OCP_RXP<15>")
	)
	(arc
		(start 296.14368 -100.692204)
		(mid 296.149857 -101.272136)
		(end 296.648886 -101.567488)
		(width 0.0889)
		(layer "In11.Cu")
		(net "P3E_CPU0_PE3_OCP_RXP<15>")
	)
	(arc
		(start 297.531282 -102.062534)
		(mid 297.725132 -102.118884)
		(end 297.866816 -102.262686)
		(width 0.0889)
		(layer "In11.Cu")
		(net "P3E_CPU0_PE3_OCP_RXP<15>")
	)
	(arc
		(start 296.154856 -99.299522)
		(mid 296.203611 -99.495874)
		(end 296.15003 -99.690936)
		(width 0.0889)
		(layer "In11.Cu")
		(net "P3E_CPU0_PE3_OCP_RXP<15>")
	)
	(arc
		(start 296.15003 -99.690936)
		(mid 296.070899 -99.986338)
		(end 296.15003 -100.28174)
		(width 0.0889)
		(layer "In11.Cu")
		(net "P3E_CPU0_PE3_OCP_RXP<15>")
	)
	(arc
		(start 294.437816 -93.355922)
		(mid 294.486571 -93.552274)
		(end 294.43299 -93.747336)
		(width 0.0889)
		(layer "In11.Cu")
		(net "P3E_CPU0_PE3_OCP_RXP<15>")
	)
	(arc
		(start 294.42664 -94.748604)
		(mid 294.353842 -95.039367)
		(end 294.43299 -95.328486)
		(width 0.0889)
		(layer "In11.Cu")
		(net "P3E_CPU0_PE3_OCP_RXP<15>")
	)
	(arc
		(start 297.004994 -90.286078)
		(mid 296.859028 -90.428477)
		(end 296.66184 -90.480388)
		(width 0.0889)
		(layer "In11.Cu")
		(net "P3E_CPU0_PE3_OCP_RXP<15>")
	)
	(arc
		(start 297.866816 -102.262686)
		(mid 298.075424 -102.474618)
		(end 298.360846 -102.558088)
		(width 0.0889)
		(layer "In11.Cu")
		(net "P3E_CPU0_PE3_OCP_RXP<15>")
	)
	(arc
		(start 295.29151 -91.270836)
		(mid 295.149827 -91.41464)
		(end 294.955976 -91.470988)
		(width 0.0889)
		(layer "In11.Cu")
		(net "P3E_CPU0_PE3_OCP_RXP<15>")
	)
	(arc
		(start 295.814496 -98.100134)
		(mid 296.152665 -98.304932)
		(end 296.15003 -98.700336)
		(width 0.0889)
		(layer "In11.Cu")
		(net "P3E_CPU0_PE3_OCP_RXP<15>")
	)
	(arc
		(start 298.357036 -89.489788)
		(mid 298.073819 -89.574069)
		(end 297.866816 -89.784936)
		(width 0.0889)
		(layer "In11.Cu")
		(net "P3E_CPU0_PE3_OCP_RXP<15>")
	)
	(arc
		(start 294.437816 -95.337122)
		(mid 294.486571 -95.533474)
		(end 294.43299 -95.728536)
		(width 0.0889)
		(layer "In11.Cu")
		(net "P3E_CPU0_PE3_OCP_RXP<15>")
	)
	(arc
		(start 297.502326 -89.984834)
		(mid 297.216902 -90.068301)
		(end 297.008296 -90.280236)
		(width 0.0889)
		(layer "In11.Cu")
		(net "P3E_CPU0_PE3_OCP_RXP<15>")
	)
	(arc
		(start 294.437816 -92.365322)
		(mid 294.486571 -92.561674)
		(end 294.43299 -92.756736)
		(width 0.0889)
		(layer "In11.Cu")
		(net "P3E_CPU0_PE3_OCP_RXP<15>")
	)
	(arc
		(start 295.29151 -97.804986)
		(mid 295.498514 -98.01585)
		(end 295.78173 -98.100134)
		(width 0.0889)
		(layer "In11.Cu")
		(net "P3E_CPU0_PE3_OCP_RXP<15>")
	)
	(arc
		(start 299.583856 -89.784936)
		(mid 299.443777 -89.927672)
		(end 299.252132 -89.984834)
		(width 0.0889)
		(layer "In11.Cu")
		(net "P3E_CPU0_PE3_OCP_RXP<15>")
	)
	(arc
		(start 297.008296 -101.76764)
		(mid 297.213917 -101.977563)
		(end 297.495214 -102.062534)
		(width 0.0889)
		(layer "In11.Cu")
		(net "P3E_CPU0_PE3_OCP_RXP<15>")
	)
	(segment
		(start 461.105758 -121.370598)
		(end 461.22844 -121.49328)
		(width 0.1143)
		(layer "F.Cu")
		(net "P3E_CPU0_PE3_OCP_RXP<14>")
	)
	(segment
		(start 461.105758 -118.638066)
		(end 461.105758 -121.370598)
		(width 0.1143)
		(layer "F.Cu")
		(net "P3E_CPU0_PE3_OCP_RXP<14>")
	)
	(segment
		(start 461.400906 -116.993162)
		(end 461.400906 -118.342918)
		(width 0.1143)
		(layer "F.Cu")
		(net "P3E_CPU0_PE3_OCP_RXP<14>")
	)
	(segment
		(start 461.400906 -118.342918)
		(end 461.105758 -118.638066)
		(width 0.1143)
		(layer "F.Cu")
		(net "P3E_CPU0_PE3_OCP_RXP<14>")
	)
	(segment
		(start 299.524166 -90.080338)
		(end 300.095666 -90.080338)
		(width 0.1143)
		(layer "F.Cu")
		(net "P3E_CPU0_PE3_OCP_RXP<14>")
	)
	(segment
		(start 461.22844 -121.49328)
		(end 461.61325 -121.49328)
		(width 0.1143)
		(layer "F.Cu")
		(net "P3E_CPU0_PE3_OCP_RXP<14>")
	)
	(via
		(at 300.095666 -90.080338)
		(size 0.508)
		(drill 0.254)
		(layers "F.Cu" "B.Cu")
		(net "P3E_CPU0_PE3_OCP_RXP<14>")
	)
	(via
		(at 461.61325 -121.49328)
		(size 0.508)
		(drill 0.254)
		(layers "F.Cu" "B.Cu")
		(net "P3E_CPU0_PE3_OCP_RXP<14>")
	)
	(segment
		(start 296.67962 -91.661488)
		(end 296.646854 -91.661488)
		(width 0.0889)
		(layer "In11.Cu")
		(net "P3E_CPU0_PE3_OCP_RXP<14>")
	)
	(segment
		(start 440.278266 -134.00278)
		(end 445.530986 -131.38785)
		(width 0.1143)
		(layer "In11.Cu")
		(net "P3E_CPU0_PE3_OCP_RXP<14>")
	)
	(segment
		(start 459.849982 -120.6119)
		(end 460.768446 -120.6119)
		(width 0.1143)
		(layer "In11.Cu")
		(net "P3E_CPU0_PE3_OCP_RXP<14>")
	)
	(segment
		(start 297.18 -100.271072)
		(end 297.17365 -100.28174)
		(width 0.0889)
		(layer "In11.Cu")
		(net "P3E_CPU0_PE3_OCP_RXP<14>")
	)
	(segment
		(start 430.454562 -140.945616)
		(end 431.774854 -141.286484)
		(width 0.1143)
		(layer "In11.Cu")
		(net "P3E_CPU0_PE3_OCP_RXP<14>")
	)
	(segment
		(start 445.530986 -131.38785)
		(end 450.529198 -127.667258)
		(width 0.1143)
		(layer "In11.Cu")
		(net "P3E_CPU0_PE3_OCP_RXP<14>")
	)
	(segment
		(start 357.959914 -131.298442)
		(end 359.568242 -130.6322)
		(width 0.1143)
		(layer "In11.Cu")
		(net "P3E_CPU0_PE3_OCP_RXP<14>")
	)
	(segment
		(start 298.393612 -90.670888)
		(end 298.36364 -90.670888)
		(width 0.0889)
		(layer "In11.Cu")
		(net "P3E_CPU0_PE3_OCP_RXP<14>")
	)
	(segment
		(start 299.80255 -90.249248)
		(end 299.778674 -90.338402)
		(width 0.0889)
		(layer "In11.Cu")
		(net "P3E_CPU0_PE3_OCP_RXP<14>")
	)
	(segment
		(start 297.176952 -91.360244)
		(end 297.17365 -91.366086)
		(width 0.0889)
		(layer "In11.Cu")
		(net "P3E_CPU0_PE3_OCP_RXP<14>")
	)
	(segment
		(start 457.937108 -122.52452)
		(end 459.849982 -120.6119)
		(width 0.1143)
		(layer "In11.Cu")
		(net "P3E_CPU0_PE3_OCP_RXP<14>")
	)
	(segment
		(start 366.6363 -138.248898)
		(end 367.015776 -139.164314)
		(width 0.1143)
		(layer "In11.Cu")
		(net "P3E_CPU0_PE3_OCP_RXP<14>")
	)
	(segment
		(start 417.538408 -146.00428)
		(end 417.538662 -146.004026)
		(width 0.1143)
		(layer "In11.Cu")
		(net "P3E_CPU0_PE3_OCP_RXP<14>")
	)
	(segment
		(start 394.511022 -145.59534)
		(end 396.335504 -147.018248)
		(width 0.1143)
		(layer "In11.Cu")
		(net "P3E_CPU0_PE3_OCP_RXP<14>")
	)
	(segment
		(start 324.15734 -122.347228)
		(end 328.603864 -126.793752)
		(width 0.1143)
		(layer "In11.Cu")
		(net "P3E_CPU0_PE3_OCP_RXP<14>")
	)
	(segment
		(start 301.314358 -104.229916)
		(end 301.314612 -104.23017)
		(width 0.0889)
		(layer "In11.Cu")
		(net "P3E_CPU0_PE3_OCP_RXP<14>")
	)
	(segment
		(start 366.6363 -135.029194)
		(end 366.6363 -138.248898)
		(width 0.1143)
		(layer "In11.Cu")
		(net "P3E_CPU0_PE3_OCP_RXP<14>")
	)
	(segment
		(start 390.268714 -144.19707)
		(end 390.693656 -144.882108)
		(width 0.1143)
		(layer "In11.Cu")
		(net "P3E_CPU0_PE3_OCP_RXP<14>")
	)
	(segment
		(start 295.46296 -93.336618)
		(end 295.45661 -93.347286)
		(width 0.0889)
		(layer "In11.Cu")
		(net "P3E_CPU0_PE3_OCP_RXP<14>")
	)
	(segment
		(start 361.588304 -130.6322)
		(end 364.254796 -131.736338)
		(width 0.1143)
		(layer "In11.Cu")
		(net "P3E_CPU0_PE3_OCP_RXP<14>")
	)
	(segment
		(start 302.680878 -105.5243)
		(end 305.7779 -105.5243)
		(width 0.1143)
		(layer "In11.Cu")
		(net "P3E_CPU0_PE3_OCP_RXP<14>")
	)
	(segment
		(start 421.066214 -141.312138)
		(end 421.878252 -141.516354)
		(width 0.1143)
		(layer "In11.Cu")
		(net "P3E_CPU0_PE3_OCP_RXP<14>")
	)
	(segment
		(start 295.45661 -94.737936)
		(end 295.46296 -94.748604)
		(width 0.0889)
		(layer "In11.Cu")
		(net "P3E_CPU0_PE3_OCP_RXP<14>")
	)
	(segment
		(start 418.145722 -145.752312)
		(end 418.571934 -145.3261)
		(width 0.1143)
		(layer "In11.Cu")
		(net "P3E_CPU0_PE3_OCP_RXP<14>")
	)
	(segment
		(start 367.324386 -139.378944)
		(end 378.730764 -141.699234)
		(width 0.1143)
		(layer "In11.Cu")
		(net "P3E_CPU0_PE3_OCP_RXP<14>")
	)
	(segment
		(start 461.26908 -121.49328)
		(end 461.61325 -121.49328)
		(width 0.1143)
		(layer "In11.Cu")
		(net "P3E_CPU0_PE3_OCP_RXP<14>")
	)
	(segment
		(start 318.764158 -117.3099)
		(end 320.485008 -119.03075)
		(width 0.1143)
		(layer "In11.Cu")
		(net "P3E_CPU0_PE3_OCP_RXP<14>")
	)
	(segment
		(start 299.258736 -91.165934)
		(end 299.215556 -91.165934)
		(width 0.0889)
		(layer "In11.Cu")
		(net "P3E_CPU0_PE3_OCP_RXP<14>")
	)
	(segment
		(start 452.862188 -123.2535)
		(end 456.177904 -123.2535)
		(width 0.1143)
		(layer "In11.Cu")
		(net "P3E_CPU0_PE3_OCP_RXP<14>")
	)
	(segment
		(start 426.994574 -141.052296)
		(end 428.256446 -141.357604)
		(width 0.1143)
		(layer "In11.Cu")
		(net "P3E_CPU0_PE3_OCP_RXP<14>")
	)
	(segment
		(start 300.736 -102.7176)
		(end 300.736 -103.004874)
		(width 0.0889)
		(layer "In11.Cu")
		(net "P3E_CPU0_PE3_OCP_RXP<14>")
	)
	(segment
		(start 295.45661 -93.347286)
		(end 295.451784 -93.355922)
		(width 0.0889)
		(layer "In11.Cu")
		(net "P3E_CPU0_PE3_OCP_RXP<14>")
	)
	(segment
		(start 299.22216 -101.872034)
		(end 299.254926 -101.872034)
		(width 0.0889)
		(layer "In11.Cu")
		(net "P3E_CPU0_PE3_OCP_RXP<14>")
	)
	(segment
		(start 298.36745 -101.376734)
		(end 298.39158 -101.376734)
		(width 0.0889)
		(layer "In11.Cu")
		(net "P3E_CPU0_PE3_OCP_RXP<14>")
	)
	(segment
		(start 359.568242 -130.6322)
		(end 361.588304 -130.6322)
		(width 0.1143)
		(layer "In11.Cu")
		(net "P3E_CPU0_PE3_OCP_RXP<14>")
	)
	(segment
		(start 418.571934 -145.3261)
		(end 418.9857 -144.328388)
		(width 0.1143)
		(layer "In11.Cu")
		(net "P3E_CPU0_PE3_OCP_RXP<14>")
	)
	(segment
		(start 295.45661 -95.328486)
		(end 295.451784 -95.337122)
		(width 0.0889)
		(layer "In11.Cu")
		(net "P3E_CPU0_PE3_OCP_RXP<14>")
	)
	(segment
		(start 407.128218 -146.00428)
		(end 408.60091 -146.00428)
		(width 0.1143)
		(layer "In11.Cu")
		(net "P3E_CPU0_PE3_OCP_RXP<14>")
	)
	(segment
		(start 365.992156 -133.473698)
		(end 366.6363 -135.029194)
		(width 0.1143)
		(layer "In11.Cu")
		(net "P3E_CPU0_PE3_OCP_RXP<14>")
	)
	(segment
		(start 300.785784 -103.054658)
		(end 300.785784 -103.232458)
		(width 0.0889)
		(layer "In11.Cu")
		(net "P3E_CPU0_PE3_OCP_RXP<14>")
	)
	(segment
		(start 301.314104 -104.229916)
		(end 301.314358 -104.229916)
		(width 0.0889)
		(layer "In11.Cu")
		(net "P3E_CPU0_PE3_OCP_RXP<14>")
	)
	(segment
		(start 320.485008 -119.03075)
		(end 323.621654 -119.03075)
		(width 0.1143)
		(layer "In11.Cu")
		(net "P3E_CPU0_PE3_OCP_RXP<14>")
	)
	(segment
		(start 297.18254 -99.275646)
		(end 297.17365 -99.290886)
		(width 0.0889)
		(layer "In11.Cu")
		(net "P3E_CPU0_PE3_OCP_RXP<14>")
	)
	(segment
		(start 332.1304 -128.4732)
		(end 336.968338 -130.47599)
		(width 0.1143)
		(layer "In11.Cu")
		(net "P3E_CPU0_PE3_OCP_RXP<14>")
	)
	(segment
		(start 317.5635 -117.3099)
		(end 318.764158 -117.3099)
		(width 0.1143)
		(layer "In11.Cu")
		(net "P3E_CPU0_PE3_OCP_RXP<14>")
	)
	(segment
		(start 300.736 -103.282242)
		(end 300.736 -103.651812)
		(width 0.0889)
		(layer "In11.Cu")
		(net "P3E_CPU0_PE3_OCP_RXP<14>")
	)
	(segment
		(start 406.378156 -146.314668)
		(end 407.128218 -146.00428)
		(width 0.1143)
		(layer "In11.Cu")
		(net "P3E_CPU0_PE3_OCP_RXP<14>")
	)
	(segment
		(start 301.401988 -104.245664)
		(end 301.401988 -104.24541)
		(width 0.0889)
		(layer "In11.Cu")
		(net "P3E_CPU0_PE3_OCP_RXP<14>")
	)
	(segment
		(start 461.13065 -121.35485)
		(end 461.26908 -121.49328)
		(width 0.1143)
		(layer "In11.Cu")
		(net "P3E_CPU0_PE3_OCP_RXP<14>")
	)
	(segment
		(start 450.529198 -127.667258)
		(end 452.001636 -124.114052)
		(width 0.1143)
		(layer "In11.Cu")
		(net "P3E_CPU0_PE3_OCP_RXP<14>")
	)
	(segment
		(start 412.324042 -147.0025)
		(end 413.322262 -146.00428)
		(width 0.1143)
		(layer "In11.Cu")
		(net "P3E_CPU0_PE3_OCP_RXP<14>")
	)
	(segment
		(start 300.385988 -102.367588)
		(end 300.736 -102.7176)
		(width 0.0889)
		(layer "In11.Cu")
		(net "P3E_CPU0_PE3_OCP_RXP<14>")
	)
	(segment
		(start 413.322262 -146.00428)
		(end 417.538408 -146.00428)
		(width 0.1143)
		(layer "In11.Cu")
		(net "P3E_CPU0_PE3_OCP_RXP<14>")
	)
	(segment
		(start 438.89549 -137.062972)
		(end 440.278266 -134.00278)
		(width 0.1143)
		(layer "In11.Cu")
		(net "P3E_CPU0_PE3_OCP_RXP<14>")
	)
	(segment
		(start 418.9857 -144.328388)
		(end 418.9857 -142.423896)
		(width 0.1143)
		(layer "In11.Cu")
		(net "P3E_CPU0_PE3_OCP_RXP<14>")
	)
	(segment
		(start 300.785784 -103.232458)
		(end 300.736 -103.282242)
		(width 0.0889)
		(layer "In11.Cu")
		(net "P3E_CPU0_PE3_OCP_RXP<14>")
	)
	(segment
		(start 390.693656 -144.882108)
		(end 391.470134 -145.219166)
		(width 0.1143)
		(layer "In11.Cu")
		(net "P3E_CPU0_PE3_OCP_RXP<14>")
	)
	(segment
		(start 297.18254 -98.285046)
		(end 297.17365 -98.300286)
		(width 0.0889)
		(layer "In11.Cu")
		(net "P3E_CPU0_PE3_OCP_RXP<14>")
	)
	(segment
		(start 300.736 -103.651812)
		(end 301.314104 -104.229916)
		(width 0.0889)
		(layer "In11.Cu")
		(net "P3E_CPU0_PE3_OCP_RXP<14>")
	)
	(segment
		(start 378.730764 -141.699234)
		(end 380.414276 -141.356842)
		(width 0.1143)
		(layer "In11.Cu")
		(net "P3E_CPU0_PE3_OCP_RXP<14>")
	)
	(segment
		(start 396.335504 -147.018248)
		(end 397.064738 -147.166584)
		(width 0.1143)
		(layer "In11.Cu")
		(net "P3E_CPU0_PE3_OCP_RXP<14>")
	)
	(segment
		(start 301.386494 -104.23017)
		(end 301.401988 -104.245664)
		(width 0.0889)
		(layer "In11.Cu")
		(net "P3E_CPU0_PE3_OCP_RXP<14>")
	)
	(segment
		(start 380.414276 -141.356842)
		(end 385.722876 -143.524224)
		(width 0.1143)
		(layer "In11.Cu")
		(net "P3E_CPU0_PE3_OCP_RXP<14>")
	)
	(segment
		(start 296.650664 -97.414588)
		(end 296.686732 -97.414588)
		(width 0.0889)
		(layer "In11.Cu")
		(net "P3E_CPU0_PE3_OCP_RXP<14>")
	)
	(segment
		(start 336.968338 -130.47599)
		(end 338.050378 -132.562092)
		(width 0.1143)
		(layer "In11.Cu")
		(net "P3E_CPU0_PE3_OCP_RXP<14>")
	)
	(segment
		(start 323.621654 -119.03075)
		(end 324.15734 -119.566436)
		(width 0.1143)
		(layer "In11.Cu")
		(net "P3E_CPU0_PE3_OCP_RXP<14>")
	)
	(segment
		(start 364.254796 -131.736338)
		(end 365.992156 -133.473698)
		(width 0.1143)
		(layer "In11.Cu")
		(net "P3E_CPU0_PE3_OCP_RXP<14>")
	)
	(segment
		(start 461.13065 -120.974104)
		(end 461.13065 -121.35485)
		(width 0.1143)
		(layer "In11.Cu")
		(net "P3E_CPU0_PE3_OCP_RXP<14>")
	)
	(segment
		(start 452.001636 -124.114052)
		(end 452.862188 -123.2535)
		(width 0.1143)
		(layer "In11.Cu")
		(net "P3E_CPU0_PE3_OCP_RXP<14>")
	)
	(segment
		(start 426.182536 -141.242542)
		(end 426.994574 -141.052296)
		(width 0.1143)
		(layer "In11.Cu")
		(net "P3E_CPU0_PE3_OCP_RXP<14>")
	)
	(segment
		(start 301.401988 -104.24541)
		(end 302.680878 -105.5243)
		(width 0.1143)
		(layer "In11.Cu")
		(net "P3E_CPU0_PE3_OCP_RXP<14>")
	)
	(segment
		(start 388.827772 -143.524224)
		(end 390.268714 -144.19707)
		(width 0.1143)
		(layer "In11.Cu")
		(net "P3E_CPU0_PE3_OCP_RXP<14>")
	)
	(segment
		(start 297.507914 -100.881434)
		(end 297.541696 -100.881434)
		(width 0.0889)
		(layer "In11.Cu")
		(net "P3E_CPU0_PE3_OCP_RXP<14>")
	)
	(segment
		(start 385.722876 -143.524224)
		(end 388.827772 -143.524224)
		(width 0.1143)
		(layer "In11.Cu")
		(net "P3E_CPU0_PE3_OCP_RXP<14>")
	)
	(segment
		(start 300.736 -103.004874)
		(end 300.785784 -103.054658)
		(width 0.0889)
		(layer "In11.Cu")
		(net "P3E_CPU0_PE3_OCP_RXP<14>")
	)
	(segment
		(start 300.08449 -102.367588)
		(end 300.385988 -102.367588)
		(width 0.0889)
		(layer "In11.Cu")
		(net "P3E_CPU0_PE3_OCP_RXP<14>")
	)
	(segment
		(start 338.050378 -132.562092)
		(end 342.111076 -133.854444)
		(width 0.1143)
		(layer "In11.Cu")
		(net "P3E_CPU0_PE3_OCP_RXP<14>")
	)
	(segment
		(start 342.111076 -133.854444)
		(end 355.403912 -133.854444)
		(width 0.1143)
		(layer "In11.Cu")
		(net "P3E_CPU0_PE3_OCP_RXP<14>")
	)
	(segment
		(start 418.9857 -142.423896)
		(end 419.690804 -141.718538)
		(width 0.1143)
		(layer "In11.Cu")
		(net "P3E_CPU0_PE3_OCP_RXP<14>")
	)
	(segment
		(start 421.878252 -141.516354)
		(end 424.823128 -140.962888)
		(width 0.1143)
		(layer "In11.Cu")
		(net "P3E_CPU0_PE3_OCP_RXP<14>")
	)
	(segment
		(start 409.59913 -147.0025)
		(end 412.324042 -147.0025)
		(width 0.1143)
		(layer "In11.Cu")
		(net "P3E_CPU0_PE3_OCP_RXP<14>")
	)
	(segment
		(start 397.064738 -147.166584)
		(end 403.554184 -145.753328)
		(width 0.1143)
		(layer "In11.Cu")
		(net "P3E_CPU0_PE3_OCP_RXP<14>")
	)
	(segment
		(start 300.095666 -90.080338)
		(end 299.80255 -90.249248)
		(width 0.0889)
		(layer "In11.Cu")
		(net "P3E_CPU0_PE3_OCP_RXP<14>")
	)
	(segment
		(start 295.46296 -96.308418)
		(end 295.45661 -96.319086)
		(width 0.0889)
		(layer "In11.Cu")
		(net "P3E_CPU0_PE3_OCP_RXP<14>")
	)
	(segment
		(start 417.538662 -146.004026)
		(end 418.145722 -145.752312)
		(width 0.1143)
		(layer "In11.Cu")
		(net "P3E_CPU0_PE3_OCP_RXP<14>")
	)
	(segment
		(start 391.470134 -145.219166)
		(end 394.511022 -145.59534)
		(width 0.1143)
		(layer "In11.Cu")
		(net "P3E_CPU0_PE3_OCP_RXP<14>")
	)
	(segment
		(start 367.015776 -139.164314)
		(end 367.324386 -139.378944)
		(width 0.1143)
		(layer "In11.Cu")
		(net "P3E_CPU0_PE3_OCP_RXP<14>")
	)
	(segment
		(start 403.554184 -145.753328)
		(end 406.378156 -146.314668)
		(width 0.1143)
		(layer "In11.Cu")
		(net "P3E_CPU0_PE3_OCP_RXP<14>")
	)
	(segment
		(start 355.403912 -133.854444)
		(end 357.959914 -131.298442)
		(width 0.1143)
		(layer "In11.Cu")
		(net "P3E_CPU0_PE3_OCP_RXP<14>")
	)
	(segment
		(start 330.450444 -126.793752)
		(end 332.1304 -128.4732)
		(width 0.1143)
		(layer "In11.Cu")
		(net "P3E_CPU0_PE3_OCP_RXP<14>")
	)
	(segment
		(start 324.15734 -119.566436)
		(end 324.15734 -122.347228)
		(width 0.1143)
		(layer "In11.Cu")
		(net "P3E_CPU0_PE3_OCP_RXP<14>")
	)
	(segment
		(start 436.522876 -139.94257)
		(end 438.89549 -137.062972)
		(width 0.1143)
		(layer "In11.Cu")
		(net "P3E_CPU0_PE3_OCP_RXP<14>")
	)
	(segment
		(start 456.177904 -123.2535)
		(end 457.937108 -122.52452)
		(width 0.1143)
		(layer "In11.Cu")
		(net "P3E_CPU0_PE3_OCP_RXP<14>")
	)
	(segment
		(start 301.314612 -104.23017)
		(end 301.386494 -104.23017)
		(width 0.0889)
		(layer "In11.Cu")
		(net "P3E_CPU0_PE3_OCP_RXP<14>")
	)
	(segment
		(start 328.603864 -126.793752)
		(end 330.450444 -126.793752)
		(width 0.1143)
		(layer "In11.Cu")
		(net "P3E_CPU0_PE3_OCP_RXP<14>")
	)
	(segment
		(start 460.768446 -120.6119)
		(end 461.13065 -120.974104)
		(width 0.1143)
		(layer "In11.Cu")
		(net "P3E_CPU0_PE3_OCP_RXP<14>")
	)
	(segment
		(start 408.60091 -146.00428)
		(end 409.59913 -147.0025)
		(width 0.1143)
		(layer "In11.Cu")
		(net "P3E_CPU0_PE3_OCP_RXP<14>")
	)
	(segment
		(start 419.690804 -141.718538)
		(end 421.066214 -141.312138)
		(width 0.1143)
		(layer "In11.Cu")
		(net "P3E_CPU0_PE3_OCP_RXP<14>")
	)
	(segment
		(start 431.774854 -141.286484)
		(end 436.522876 -139.94257)
		(width 0.1143)
		(layer "In11.Cu")
		(net "P3E_CPU0_PE3_OCP_RXP<14>")
	)
	(segment
		(start 424.823128 -140.962888)
		(end 426.182536 -141.242542)
		(width 0.1143)
		(layer "In11.Cu")
		(net "P3E_CPU0_PE3_OCP_RXP<14>")
	)
	(segment
		(start 305.7779 -105.5243)
		(end 317.5635 -117.3099)
		(width 0.1143)
		(layer "In11.Cu")
		(net "P3E_CPU0_PE3_OCP_RXP<14>")
	)
	(segment
		(start 297.541696 -91.165934)
		(end 297.520106 -91.165934)
		(width 0.0889)
		(layer "In11.Cu")
		(net "P3E_CPU0_PE3_OCP_RXP<14>")
	)
	(segment
		(start 295.788334 -96.919034)
		(end 295.8211 -96.919034)
		(width 0.0889)
		(layer "In11.Cu")
		(net "P3E_CPU0_PE3_OCP_RXP<14>")
	)
	(segment
		(start 428.256446 -141.357604)
		(end 430.454562 -140.945616)
		(width 0.1143)
		(layer "In11.Cu")
		(net "P3E_CPU0_PE3_OCP_RXP<14>")
	)
	(segment
		(start 295.45661 -96.319086)
		(end 295.451784 -96.327722)
		(width 0.0889)
		(layer "In11.Cu")
		(net "P3E_CPU0_PE3_OCP_RXP<14>")
	)
	(segment
		(start 295.82491 -92.156534)
		(end 295.792144 -92.156534)
		(width 0.0889)
		(layer "In11.Cu")
		(net "P3E_CPU0_PE3_OCP_RXP<14>")
	)
	(arc
		(start 299.748956 -102.167436)
		(mid 299.890255 -102.3108)
		(end 300.083474 -102.367334)
		(width 0.0889)
		(layer "In11.Cu")
		(net "P3E_CPU0_PE3_OCP_RXP<14>")
	)
	(arc
		(start 299.215556 -91.165934)
		(mid 298.932339 -91.081653)
		(end 298.725336 -90.870786)
		(width 0.0889)
		(layer "In11.Cu")
		(net "P3E_CPU0_PE3_OCP_RXP<14>")
	)
	(arc
		(start 295.45661 -95.728536)
		(mid 295.535832 -96.017654)
		(end 295.46296 -96.308418)
		(width 0.0889)
		(layer "In11.Cu")
		(net "P3E_CPU0_PE3_OCP_RXP<14>")
	)
	(arc
		(start 295.45661 -92.756736)
		(mid 295.535832 -93.045854)
		(end 295.46296 -93.336618)
		(width 0.0889)
		(layer "In11.Cu")
		(net "P3E_CPU0_PE3_OCP_RXP<14>")
	)
	(arc
		(start 297.17365 -91.366086)
		(mid 296.965042 -91.578018)
		(end 296.67962 -91.661488)
		(width 0.0889)
		(layer "In11.Cu")
		(net "P3E_CPU0_PE3_OCP_RXP<14>")
	)
	(arc
		(start 297.17365 -99.690682)
		(mid 297.252999 -99.980054)
		(end 297.18 -100.271072)
		(width 0.0889)
		(layer "In11.Cu")
		(net "P3E_CPU0_PE3_OCP_RXP<14>")
	)
	(arc
		(start 295.45661 -94.33814)
		(mid 295.403111 -94.538038)
		(end 295.45661 -94.737936)
		(width 0.0889)
		(layer "In11.Cu")
		(net "P3E_CPU0_PE3_OCP_RXP<14>")
	)
	(arc
		(start 295.451784 -93.355922)
		(mid 295.403029 -93.552274)
		(end 295.45661 -93.747336)
		(width 0.0889)
		(layer "In11.Cu")
		(net "P3E_CPU0_PE3_OCP_RXP<14>")
	)
	(arc
		(start 296.31513 -91.861386)
		(mid 296.108126 -92.07225)
		(end 295.82491 -92.156534)
		(width 0.0889)
		(layer "In11.Cu")
		(net "P3E_CPU0_PE3_OCP_RXP<14>")
	)
	(arc
		(start 297.17365 -100.28174)
		(mid 297.170725 -100.676378)
		(end 297.507914 -100.881434)
		(width 0.0889)
		(layer "In11.Cu")
		(net "P3E_CPU0_PE3_OCP_RXP<14>")
	)
	(arc
		(start 295.8211 -96.919034)
		(mid 296.106524 -97.002501)
		(end 296.31513 -97.214436)
		(width 0.0889)
		(layer "In11.Cu")
		(net "P3E_CPU0_PE3_OCP_RXP<14>")
	)
	(arc
		(start 297.541696 -100.881434)
		(mid 297.824913 -100.965715)
		(end 298.031916 -101.176582)
		(width 0.0889)
		(layer "In11.Cu")
		(net "P3E_CPU0_PE3_OCP_RXP<14>")
	)
	(arc
		(start 300.083474 -102.367334)
		(mid 300.083982 -102.367461)
		(end 300.08449 -102.367588)
		(width 0.0889)
		(layer "In11.Cu")
		(net "P3E_CPU0_PE3_OCP_RXP<14>")
	)
	(arc
		(start 297.17365 -98.700082)
		(mid 297.252839 -98.986697)
		(end 297.18254 -99.275646)
		(width 0.0889)
		(layer "In11.Cu")
		(net "P3E_CPU0_PE3_OCP_RXP<14>")
	)
	(arc
		(start 298.890436 -101.672136)
		(mid 299.030515 -101.814872)
		(end 299.22216 -101.872034)
		(width 0.0889)
		(layer "In11.Cu")
		(net "P3E_CPU0_PE3_OCP_RXP<14>")
	)
	(arc
		(start 295.46296 -94.748604)
		(mid 295.535758 -95.039367)
		(end 295.45661 -95.328486)
		(width 0.0889)
		(layer "In11.Cu")
		(net "P3E_CPU0_PE3_OCP_RXP<14>")
	)
	(arc
		(start 297.17365 -99.290886)
		(mid 297.120117 -99.490784)
		(end 297.17365 -99.690682)
		(width 0.0889)
		(layer "In11.Cu")
		(net "P3E_CPU0_PE3_OCP_RXP<14>")
	)
	(arc
		(start 295.45661 -93.747336)
		(mid 295.535741 -94.042738)
		(end 295.45661 -94.33814)
		(width 0.0889)
		(layer "In11.Cu")
		(net "P3E_CPU0_PE3_OCP_RXP<14>")
	)
	(arc
		(start 296.646854 -91.661488)
		(mid 296.455212 -91.718654)
		(end 296.31513 -91.861386)
		(width 0.0889)
		(layer "In11.Cu")
		(net "P3E_CPU0_PE3_OCP_RXP<14>")
	)
	(arc
		(start 296.31513 -97.214436)
		(mid 296.456813 -97.35824)
		(end 296.650664 -97.414588)
		(width 0.0889)
		(layer "In11.Cu")
		(net "P3E_CPU0_PE3_OCP_RXP<14>")
	)
	(arc
		(start 297.17365 -98.300286)
		(mid 297.120117 -98.500184)
		(end 297.17365 -98.700082)
		(width 0.0889)
		(layer "In11.Cu")
		(net "P3E_CPU0_PE3_OCP_RXP<14>")
	)
	(arc
		(start 299.778674 -90.338402)
		(mid 299.737694 -90.889811)
		(end 299.258736 -91.165934)
		(width 0.0889)
		(layer "In11.Cu")
		(net "P3E_CPU0_PE3_OCP_RXP<14>")
	)
	(arc
		(start 298.031916 -101.176582)
		(mid 298.173599 -101.320386)
		(end 298.36745 -101.376734)
		(width 0.0889)
		(layer "In11.Cu")
		(net "P3E_CPU0_PE3_OCP_RXP<14>")
	)
	(arc
		(start 298.36364 -90.670888)
		(mid 298.171998 -90.728054)
		(end 298.031916 -90.870786)
		(width 0.0889)
		(layer "In11.Cu")
		(net "P3E_CPU0_PE3_OCP_RXP<14>")
	)
	(arc
		(start 295.451784 -96.327722)
		(mid 295.455531 -96.716978)
		(end 295.788334 -96.919034)
		(width 0.0889)
		(layer "In11.Cu")
		(net "P3E_CPU0_PE3_OCP_RXP<14>")
	)
	(arc
		(start 295.792144 -92.156534)
		(mid 295.453975 -92.361332)
		(end 295.45661 -92.756736)
		(width 0.0889)
		(layer "In11.Cu")
		(net "P3E_CPU0_PE3_OCP_RXP<14>")
	)
	(arc
		(start 296.686732 -97.414588)
		(mid 297.175456 -97.712618)
		(end 297.18254 -98.285046)
		(width 0.0889)
		(layer "In11.Cu")
		(net "P3E_CPU0_PE3_OCP_RXP<14>")
	)
	(arc
		(start 298.031916 -90.870786)
		(mid 297.824912 -91.08165)
		(end 297.541696 -91.165934)
		(width 0.0889)
		(layer "In11.Cu")
		(net "P3E_CPU0_PE3_OCP_RXP<14>")
	)
	(arc
		(start 298.725336 -90.870786)
		(mid 298.585257 -90.72805)
		(end 298.393612 -90.670888)
		(width 0.0889)
		(layer "In11.Cu")
		(net "P3E_CPU0_PE3_OCP_RXP<14>")
	)
	(arc
		(start 295.451784 -95.337122)
		(mid 295.403029 -95.533474)
		(end 295.45661 -95.728536)
		(width 0.0889)
		(layer "In11.Cu")
		(net "P3E_CPU0_PE3_OCP_RXP<14>")
	)
	(arc
		(start 297.520106 -91.165934)
		(mid 297.322945 -91.217893)
		(end 297.176952 -91.360244)
		(width 0.0889)
		(layer "In11.Cu")
		(net "P3E_CPU0_PE3_OCP_RXP<14>")
	)
	(arc
		(start 298.39158 -101.376734)
		(mid 298.679725 -101.459053)
		(end 298.890436 -101.672136)
		(width 0.0889)
		(layer "In11.Cu")
		(net "P3E_CPU0_PE3_OCP_RXP<14>")
	)
	(arc
		(start 299.254926 -101.872034)
		(mid 299.54035 -101.955501)
		(end 299.748956 -102.167436)
		(width 0.0889)
		(layer "In11.Cu")
		(net "P3E_CPU0_PE3_OCP_RXP<14>")
	)
	(segment
		(start 458.4573 -120.38457)
		(end 458.85735 -120.38457)
		(width 0.1143)
		(layer "F.Cu")
		(net "P3E_CPU0_PE3_OCP_RXP<13>")
	)
	(segment
		(start 458.201014 -118.250462)
		(end 457.920598 -118.530878)
		(width 0.1143)
		(layer "F.Cu")
		(net "P3E_CPU0_PE3_OCP_RXP<13>")
	)
	(segment
		(start 458.201014 -116.993162)
		(end 458.201014 -118.250462)
		(width 0.1143)
		(layer "F.Cu")
		(net "P3E_CPU0_PE3_OCP_RXP<13>")
	)
	(segment
		(start 457.920598 -118.530878)
		(end 457.920598 -118.721886)
		(width 0.1143)
		(layer "F.Cu")
		(net "P3E_CPU0_PE3_OCP_RXP<13>")
	)
	(segment
		(start 457.920598 -118.721886)
		(end 458.36332 -119.790718)
		(width 0.1143)
		(layer "F.Cu")
		(net "P3E_CPU0_PE3_OCP_RXP<13>")
	)
	(segment
		(start 458.36332 -120.29059)
		(end 458.4573 -120.38457)
		(width 0.1143)
		(layer "F.Cu")
		(net "P3E_CPU0_PE3_OCP_RXP<13>")
	)
	(segment
		(start 297.807126 -91.070938)
		(end 298.378626 -91.070938)
		(width 0.1143)
		(layer "F.Cu")
		(net "P3E_CPU0_PE3_OCP_RXP<13>")
	)
	(segment
		(start 458.36332 -119.790718)
		(end 458.36332 -120.29059)
		(width 0.1143)
		(layer "F.Cu")
		(net "P3E_CPU0_PE3_OCP_RXP<13>")
	)
	(via
		(at 298.378626 -91.070938)
		(size 0.508)
		(drill 0.254)
		(layers "F.Cu" "B.Cu")
		(net "P3E_CPU0_PE3_OCP_RXP<13>")
	)
	(via
		(at 458.85735 -120.38457)
		(size 0.508)
		(drill 0.254)
		(layers "F.Cu" "B.Cu")
		(net "P3E_CPU0_PE3_OCP_RXP<13>")
	)
	(segment
		(start 330.810362 -126.411228)
		(end 328.747882 -126.411228)
		(width 0.1143)
		(layer "In11.Cu")
		(net "P3E_CPU0_PE3_OCP_RXP<13>")
	)
	(segment
		(start 355.63683 -130.748786)
		(end 353.858322 -129.548636)
		(width 0.1143)
		(layer "In11.Cu")
		(net "P3E_CPU0_PE3_OCP_RXP<13>")
	)
	(segment
		(start 300.110652 -101.567488)
		(end 300.082712 -101.567488)
		(width 0.0889)
		(layer "In11.Cu")
		(net "P3E_CPU0_PE3_OCP_RXP<13>")
	)
	(segment
		(start 301.8536 -103.46436)
		(end 301.8536 -103.235506)
		(width 0.0889)
		(layer "In11.Cu")
		(net "P3E_CPU0_PE3_OCP_RXP<13>")
	)
	(segment
		(start 296.999406 -93.267276)
		(end 297.008296 -93.252036)
		(width 0.0889)
		(layer "In11.Cu")
		(net "P3E_CPU0_PE3_OCP_RXP<13>")
	)
	(segment
		(start 390.239504 -141.519656)
		(end 385.91617 -141.519656)
		(width 0.1143)
		(layer "In11.Cu")
		(net "P3E_CPU0_PE3_OCP_RXP<13>")
	)
	(segment
		(start 428.265336 -141.005814)
		(end 426.996352 -140.698474)
		(width 0.1143)
		(layer "In11.Cu")
		(net "P3E_CPU0_PE3_OCP_RXP<13>")
	)
	(segment
		(start 424.76674 -140.599922)
		(end 422.187624 -141.0843)
		(width 0.1143)
		(layer "In11.Cu")
		(net "P3E_CPU0_PE3_OCP_RXP<13>")
	)
	(segment
		(start 364.543594 -131.445508)
		(end 361.71505 -130.27406)
		(width 0.1143)
		(layer "In11.Cu")
		(net "P3E_CPU0_PE3_OCP_RXP<13>")
	)
	(segment
		(start 438.49671 -137.005822)
		(end 436.358538 -139.600686)
		(width 0.1143)
		(layer "In11.Cu")
		(net "P3E_CPU0_PE3_OCP_RXP<13>")
	)
	(segment
		(start 394.17752 -142.593822)
		(end 390.239504 -141.519656)
		(width 0.1143)
		(layer "In11.Cu")
		(net "P3E_CPU0_PE3_OCP_RXP<13>")
	)
	(segment
		(start 297.871642 -99.299522)
		(end 297.866816 -99.290886)
		(width 0.0889)
		(layer "In11.Cu")
		(net "P3E_CPU0_PE3_OCP_RXP<13>")
	)
	(segment
		(start 299.25518 -101.072188)
		(end 299.219366 -101.072188)
		(width 0.0889)
		(layer "In11.Cu")
		(net "P3E_CPU0_PE3_OCP_RXP<13>")
	)
	(segment
		(start 416.589464 -140.743686)
		(end 415.137854 -141.072616)
		(width 0.1143)
		(layer "In11.Cu")
		(net "P3E_CPU0_PE3_OCP_RXP<13>")
	)
	(segment
		(start 415.137854 -141.072616)
		(end 411.86989 -140.318236)
		(width 0.1143)
		(layer "In11.Cu")
		(net "P3E_CPU0_PE3_OCP_RXP<13>")
	)
	(segment
		(start 306.1335 -104.9655)
		(end 303.182274 -104.9655)
		(width 0.1143)
		(layer "In11.Cu")
		(net "P3E_CPU0_PE3_OCP_RXP<13>")
	)
	(segment
		(start 339.55482 -127.757428)
		(end 335.533492 -128.48463)
		(width 0.1143)
		(layer "In11.Cu")
		(net "P3E_CPU0_PE3_OCP_RXP<13>")
	)
	(segment
		(start 405.561546 -141.558518)
		(end 399.838926 -141.558518)
		(width 0.1143)
		(layer "In11.Cu")
		(net "P3E_CPU0_PE3_OCP_RXP<13>")
	)
	(segment
		(start 431.699162 -140.91158)
		(end 430.466246 -140.593064)
		(width 0.1143)
		(layer "In11.Cu")
		(net "P3E_CPU0_PE3_OCP_RXP<13>")
	)
	(segment
		(start 303.182274 -104.9655)
		(end 302.453548 -104.663748)
		(width 0.1143)
		(layer "In11.Cu")
		(net "P3E_CPU0_PE3_OCP_RXP<13>")
	)
	(segment
		(start 296.66184 -96.614488)
		(end 296.64406 -96.614488)
		(width 0.0889)
		(layer "In11.Cu")
		(net "P3E_CPU0_PE3_OCP_RXP<13>")
	)
	(segment
		(start 458.4827 -120.38457)
		(end 458.3684 -120.49887)
		(width 0.1143)
		(layer "In11.Cu")
		(net "P3E_CPU0_PE3_OCP_RXP<13>")
	)
	(segment
		(start 430.466246 -140.593064)
		(end 428.265336 -141.005814)
		(width 0.1143)
		(layer "In11.Cu")
		(net "P3E_CPU0_PE3_OCP_RXP<13>")
	)
	(segment
		(start 426.17771 -140.88999)
		(end 424.76674 -140.599922)
		(width 0.1143)
		(layer "In11.Cu")
		(net "P3E_CPU0_PE3_OCP_RXP<13>")
	)
	(segment
		(start 451.532752 -124.005848)
		(end 450.684646 -126.053342)
		(width 0.1143)
		(layer "In11.Cu")
		(net "P3E_CPU0_PE3_OCP_RXP<13>")
	)
	(segment
		(start 297.866816 -99.290886)
		(end 297.860466 -99.280218)
		(width 0.0889)
		(layer "In11.Cu")
		(net "P3E_CPU0_PE3_OCP_RXP<13>")
	)
	(segment
		(start 411.86989 -140.318236)
		(end 405.561546 -141.558518)
		(width 0.1143)
		(layer "In11.Cu")
		(net "P3E_CPU0_PE3_OCP_RXP<13>")
	)
	(segment
		(start 298.357036 -91.470988)
		(end 298.389802 -91.470988)
		(width 0.0889)
		(layer "In11.Cu")
		(net "P3E_CPU0_PE3_OCP_RXP<13>")
	)
	(segment
		(start 297.008296 -96.81464)
		(end 297.004994 -96.808798)
		(width 0.0889)
		(layer "In11.Cu")
		(net "P3E_CPU0_PE3_OCP_RXP<13>")
	)
	(segment
		(start 450.684646 -126.053342)
		(end 443.001654 -130.659886)
		(width 0.1143)
		(layer "In11.Cu")
		(net "P3E_CPU0_PE3_OCP_RXP<13>")
	)
	(segment
		(start 443.001654 -130.659886)
		(end 439.236612 -134.353046)
		(width 0.1143)
		(layer "In11.Cu")
		(net "P3E_CPU0_PE3_OCP_RXP<13>")
	)
	(segment
		(start 301.8028 -103.537258)
		(end 301.8028 -103.51516)
		(width 0.0889)
		(layer "In11.Cu")
		(net "P3E_CPU0_PE3_OCP_RXP<13>")
	)
	(segment
		(start 335.533492 -128.48463)
		(end 333.041498 -128.277112)
		(width 0.1143)
		(layer "In11.Cu")
		(net "P3E_CPU0_PE3_OCP_RXP<13>")
	)
	(segment
		(start 333.041498 -128.277112)
		(end 331.318108 -126.918974)
		(width 0.1143)
		(layer "In11.Cu")
		(net "P3E_CPU0_PE3_OCP_RXP<13>")
	)
	(segment
		(start 422.187624 -141.0843)
		(end 420.19347 -140.597128)
		(width 0.1143)
		(layer "In11.Cu")
		(net "P3E_CPU0_PE3_OCP_RXP<13>")
	)
	(segment
		(start 297.502326 -91.966034)
		(end 297.535092 -91.966034)
		(width 0.0889)
		(layer "In11.Cu")
		(net "P3E_CPU0_PE3_OCP_RXP<13>")
	)
	(segment
		(start 324.5739 -122.237246)
		(end 324.5739 -119.4181)
		(width 0.1143)
		(layer "In11.Cu")
		(net "P3E_CPU0_PE3_OCP_RXP<13>")
	)
	(segment
		(start 297.871642 -98.308922)
		(end 297.866816 -98.300286)
		(width 0.0889)
		(layer "In11.Cu")
		(net "P3E_CPU0_PE3_OCP_RXP<13>")
	)
	(segment
		(start 348.143576 -130.029966)
		(end 346.112846 -130.424428)
		(width 0.1143)
		(layer "In11.Cu")
		(net "P3E_CPU0_PE3_OCP_RXP<13>")
	)
	(segment
		(start 300.520354 -101.90226)
		(end 300.442376 -101.767386)
		(width 0.0889)
		(layer "In11.Cu")
		(net "P3E_CPU0_PE3_OCP_RXP<13>")
	)
	(segment
		(start 318.4779 -114.3889)
		(end 315.5569 -114.3889)
		(width 0.1143)
		(layer "In11.Cu")
		(net "P3E_CPU0_PE3_OCP_RXP<13>")
	)
	(segment
		(start 359.505504 -130.27406)
		(end 357.83012 -130.96748)
		(width 0.1143)
		(layer "In11.Cu")
		(net "P3E_CPU0_PE3_OCP_RXP<13>")
	)
	(segment
		(start 458.3684 -121.223024)
		(end 457.429616 -122.161808)
		(width 0.1143)
		(layer "In11.Cu")
		(net "P3E_CPU0_PE3_OCP_RXP<13>")
	)
	(segment
		(start 296.154856 -95.337122)
		(end 296.15003 -95.328486)
		(width 0.0889)
		(layer "In11.Cu")
		(net "P3E_CPU0_PE3_OCP_RXP<13>")
	)
	(segment
		(start 458.85735 -120.38457)
		(end 458.4827 -120.38457)
		(width 0.1143)
		(layer "In11.Cu")
		(net "P3E_CPU0_PE3_OCP_RXP<13>")
	)
	(segment
		(start 343.582752 -129.674366)
		(end 342.890856 -128.648714)
		(width 0.1143)
		(layer "In11.Cu")
		(net "P3E_CPU0_PE3_OCP_RXP<13>")
	)
	(segment
		(start 302.453548 -104.663748)
		(end 301.8028 -104.013)
		(width 0.1143)
		(layer "In11.Cu")
		(net "P3E_CPU0_PE3_OCP_RXP<13>")
	)
	(segment
		(start 455.989436 -122.7582)
		(end 452.7804 -122.7582)
		(width 0.1143)
		(layer "In11.Cu")
		(net "P3E_CPU0_PE3_OCP_RXP<13>")
	)
	(segment
		(start 296.64406 -94.442534)
		(end 296.674032 -94.442534)
		(width 0.0889)
		(layer "In11.Cu")
		(net "P3E_CPU0_PE3_OCP_RXP<13>")
	)
	(segment
		(start 301.8028 -104.013)
		(end 301.8028 -103.537258)
		(width 0.1143)
		(layer "In11.Cu")
		(net "P3E_CPU0_PE3_OCP_RXP<13>")
	)
	(segment
		(start 346.112846 -130.424428)
		(end 344.120724 -130.037586)
		(width 0.1143)
		(layer "In11.Cu")
		(net "P3E_CPU0_PE3_OCP_RXP<13>")
	)
	(segment
		(start 323.2658 -118.11)
		(end 322.199 -118.11)
		(width 0.1143)
		(layer "In11.Cu")
		(net "P3E_CPU0_PE3_OCP_RXP<13>")
	)
	(segment
		(start 297.866816 -98.300286)
		(end 297.860466 -98.289618)
		(width 0.0889)
		(layer "In11.Cu")
		(net "P3E_CPU0_PE3_OCP_RXP<13>")
	)
	(segment
		(start 436.358538 -139.600686)
		(end 431.699162 -140.91158)
		(width 0.1143)
		(layer "In11.Cu")
		(net "P3E_CPU0_PE3_OCP_RXP<13>")
	)
	(segment
		(start 457.429616 -122.161808)
		(end 455.989436 -122.7582)
		(width 0.1143)
		(layer "In11.Cu")
		(net "P3E_CPU0_PE3_OCP_RXP<13>")
	)
	(segment
		(start 322.199 -118.11)
		(end 318.4779 -114.3889)
		(width 0.1143)
		(layer "In11.Cu")
		(net "P3E_CPU0_PE3_OCP_RXP<13>")
	)
	(segment
		(start 452.7804 -122.7582)
		(end 451.532752 -124.005848)
		(width 0.1143)
		(layer "In11.Cu")
		(net "P3E_CPU0_PE3_OCP_RXP<13>")
	)
	(segment
		(start 367.955576 -136.77773)
		(end 366.597692 -133.49986)
		(width 0.1143)
		(layer "In11.Cu")
		(net "P3E_CPU0_PE3_OCP_RXP<13>")
	)
	(segment
		(start 344.120724 -130.037586)
		(end 343.582752 -129.674366)
		(width 0.1143)
		(layer "In11.Cu")
		(net "P3E_CPU0_PE3_OCP_RXP<13>")
	)
	(segment
		(start 418.187124 -141.128496)
		(end 416.589464 -140.743686)
		(width 0.1143)
		(layer "In11.Cu")
		(net "P3E_CPU0_PE3_OCP_RXP<13>")
	)
	(segment
		(start 328.747882 -126.411228)
		(end 324.5739 -122.237246)
		(width 0.1143)
		(layer "In11.Cu")
		(net "P3E_CPU0_PE3_OCP_RXP<13>")
	)
	(segment
		(start 366.597692 -133.49986)
		(end 364.543594 -131.445508)
		(width 0.1143)
		(layer "In11.Cu")
		(net "P3E_CPU0_PE3_OCP_RXP<13>")
	)
	(segment
		(start 298.671742 -91.239848)
		(end 298.378626 -91.070938)
		(width 0.0889)
		(layer "In11.Cu")
		(net "P3E_CPU0_PE3_OCP_RXP<13>")
	)
	(segment
		(start 381.89916 -140.702792)
		(end 379.118114 -141.268958)
		(width 0.1143)
		(layer "In11.Cu")
		(net "P3E_CPU0_PE3_OCP_RXP<13>")
	)
	(segment
		(start 379.118114 -141.268958)
		(end 371.903752 -139.801346)
		(width 0.1143)
		(layer "In11.Cu")
		(net "P3E_CPU0_PE3_OCP_RXP<13>")
	)
	(segment
		(start 348.623128 -129.31902)
		(end 348.143576 -130.029966)
		(width 0.1143)
		(layer "In11.Cu")
		(net "P3E_CPU0_PE3_OCP_RXP<13>")
	)
	(segment
		(start 331.318108 -126.918974)
		(end 330.810362 -126.411228)
		(width 0.1143)
		(layer "In11.Cu")
		(net "P3E_CPU0_PE3_OCP_RXP<13>")
	)
	(segment
		(start 349.176086 -129.211324)
		(end 348.623128 -129.31902)
		(width 0.1143)
		(layer "In11.Cu")
		(net "P3E_CPU0_PE3_OCP_RXP<13>")
	)
	(segment
		(start 458.3684 -120.49887)
		(end 458.3684 -121.223024)
		(width 0.1143)
		(layer "In11.Cu")
		(net "P3E_CPU0_PE3_OCP_RXP<13>")
	)
	(segment
		(start 439.236612 -134.353046)
		(end 438.49671 -137.005822)
		(width 0.1143)
		(layer "In11.Cu")
		(net "P3E_CPU0_PE3_OCP_RXP<13>")
	)
	(segment
		(start 420.19347 -140.597128)
		(end 418.187124 -141.128496)
		(width 0.1143)
		(layer "In11.Cu")
		(net "P3E_CPU0_PE3_OCP_RXP<13>")
	)
	(segment
		(start 426.996352 -140.698474)
		(end 426.17771 -140.88999)
		(width 0.1143)
		(layer "In11.Cu")
		(net "P3E_CPU0_PE3_OCP_RXP<13>")
	)
	(segment
		(start 353.858322 -129.548636)
		(end 352.385122 -129.835148)
		(width 0.1143)
		(layer "In11.Cu")
		(net "P3E_CPU0_PE3_OCP_RXP<13>")
	)
	(segment
		(start 301.8028 -103.51516)
		(end 301.8536 -103.46436)
		(width 0.0889)
		(layer "In11.Cu")
		(net "P3E_CPU0_PE3_OCP_RXP<13>")
	)
	(segment
		(start 371.903752 -139.801346)
		(end 367.955576 -136.77773)
		(width 0.1143)
		(layer "In11.Cu")
		(net "P3E_CPU0_PE3_OCP_RXP<13>")
	)
	(segment
		(start 298.692824 -91.318588)
		(end 298.671742 -91.239848)
		(width 0.0889)
		(layer "In11.Cu")
		(net "P3E_CPU0_PE3_OCP_RXP<13>")
	)
	(segment
		(start 342.385396 -128.307592)
		(end 339.55482 -127.757428)
		(width 0.1143)
		(layer "In11.Cu")
		(net "P3E_CPU0_PE3_OCP_RXP<13>")
	)
	(segment
		(start 298.39666 -100.576888)
		(end 298.357036 -100.576888)
		(width 0.0889)
		(layer "In11.Cu")
		(net "P3E_CPU0_PE3_OCP_RXP<13>")
	)
	(segment
		(start 361.71505 -130.27406)
		(end 359.505504 -130.27406)
		(width 0.1143)
		(layer "In11.Cu")
		(net "P3E_CPU0_PE3_OCP_RXP<13>")
	)
	(segment
		(start 352.385122 -129.835148)
		(end 349.176086 -129.211324)
		(width 0.1143)
		(layer "In11.Cu")
		(net "P3E_CPU0_PE3_OCP_RXP<13>")
	)
	(segment
		(start 385.91617 -141.519656)
		(end 381.89916 -140.702792)
		(width 0.1143)
		(layer "In11.Cu")
		(net "P3E_CPU0_PE3_OCP_RXP<13>")
	)
	(segment
		(start 342.890856 -128.648714)
		(end 342.385396 -128.307592)
		(width 0.1143)
		(layer "In11.Cu")
		(net "P3E_CPU0_PE3_OCP_RXP<13>")
	)
	(segment
		(start 315.5569 -114.3889)
		(end 306.1335 -104.9655)
		(width 0.1143)
		(layer "In11.Cu")
		(net "P3E_CPU0_PE3_OCP_RXP<13>")
	)
	(segment
		(start 357.296974 -131.071366)
		(end 355.63683 -130.748786)
		(width 0.1143)
		(layer "In11.Cu")
		(net "P3E_CPU0_PE3_OCP_RXP<13>")
	)
	(segment
		(start 357.83012 -130.96748)
		(end 357.296974 -131.071366)
		(width 0.1143)
		(layer "In11.Cu")
		(net "P3E_CPU0_PE3_OCP_RXP<13>")
	)
	(segment
		(start 301.8536 -103.235506)
		(end 300.520354 -101.90226)
		(width 0.0889)
		(layer "In11.Cu")
		(net "P3E_CPU0_PE3_OCP_RXP<13>")
	)
	(segment
		(start 297.531282 -97.109534)
		(end 297.495214 -97.109534)
		(width 0.0889)
		(layer "In11.Cu")
		(net "P3E_CPU0_PE3_OCP_RXP<13>")
	)
	(segment
		(start 399.838926 -141.558518)
		(end 394.17752 -142.593822)
		(width 0.1143)
		(layer "In11.Cu")
		(net "P3E_CPU0_PE3_OCP_RXP<13>")
	)
	(segment
		(start 324.5739 -119.4181)
		(end 323.2658 -118.11)
		(width 0.1143)
		(layer "In11.Cu")
		(net "P3E_CPU0_PE3_OCP_RXP<13>")
	)
	(arc
		(start 297.495214 -97.109534)
		(mid 297.213914 -97.024568)
		(end 297.008296 -96.81464)
		(width 0.0889)
		(layer "In11.Cu")
		(net "P3E_CPU0_PE3_OCP_RXP<13>")
	)
	(arc
		(start 297.008296 -92.85224)
		(mid 297.003771 -92.268899)
		(end 297.502326 -91.966034)
		(width 0.0889)
		(layer "In11.Cu")
		(net "P3E_CPU0_PE3_OCP_RXP<13>")
	)
	(arc
		(start 297.866816 -91.766136)
		(mid 298.07382 -91.555272)
		(end 298.357036 -91.470988)
		(width 0.0889)
		(layer "In11.Cu")
		(net "P3E_CPU0_PE3_OCP_RXP<13>")
	)
	(arc
		(start 297.860466 -99.280218)
		(mid 297.787668 -98.989455)
		(end 297.866816 -98.700336)
		(width 0.0889)
		(layer "In11.Cu")
		(net "P3E_CPU0_PE3_OCP_RXP<13>")
	)
	(arc
		(start 298.725336 -100.776786)
		(mid 298.586592 -100.634753)
		(end 298.39666 -100.576888)
		(width 0.0889)
		(layer "In11.Cu")
		(net "P3E_CPU0_PE3_OCP_RXP<13>")
	)
	(arc
		(start 297.866816 -99.690936)
		(mid 297.920286 -99.495873)
		(end 297.871642 -99.299522)
		(width 0.0889)
		(layer "In11.Cu")
		(net "P3E_CPU0_PE3_OCP_RXP<13>")
	)
	(arc
		(start 299.219366 -101.072188)
		(mid 298.933942 -100.988721)
		(end 298.725336 -100.776786)
		(width 0.0889)
		(layer "In11.Cu")
		(net "P3E_CPU0_PE3_OCP_RXP<13>")
	)
	(arc
		(start 297.866816 -98.700336)
		(mid 297.920286 -98.505273)
		(end 297.871642 -98.308922)
		(width 0.0889)
		(layer "In11.Cu")
		(net "P3E_CPU0_PE3_OCP_RXP<13>")
	)
	(arc
		(start 300.442376 -101.767386)
		(mid 300.302297 -101.62465)
		(end 300.110652 -101.567488)
		(width 0.0889)
		(layer "In11.Cu")
		(net "P3E_CPU0_PE3_OCP_RXP<13>")
	)
	(arc
		(start 298.389802 -91.470988)
		(mid 298.558239 -91.428455)
		(end 298.692824 -91.318588)
		(width 0.0889)
		(layer "In11.Cu")
		(net "P3E_CPU0_PE3_OCP_RXP<13>")
	)
	(arc
		(start 297.866816 -97.709736)
		(mid 297.869564 -97.314269)
		(end 297.531282 -97.109534)
		(width 0.0889)
		(layer "In11.Cu")
		(net "P3E_CPU0_PE3_OCP_RXP<13>")
	)
	(arc
		(start 296.674032 -94.442534)
		(mid 297.011215 -94.237474)
		(end 297.008296 -93.84284)
		(width 0.0889)
		(layer "In11.Cu")
		(net "P3E_CPU0_PE3_OCP_RXP<13>")
	)
	(arc
		(start 297.008296 -93.84284)
		(mid 296.929107 -93.556225)
		(end 296.999406 -93.267276)
		(width 0.0889)
		(layer "In11.Cu")
		(net "P3E_CPU0_PE3_OCP_RXP<13>")
	)
	(arc
		(start 297.535092 -91.966034)
		(mid 297.726734 -91.908868)
		(end 297.866816 -91.766136)
		(width 0.0889)
		(layer "In11.Cu")
		(net "P3E_CPU0_PE3_OCP_RXP<13>")
	)
	(arc
		(start 296.15003 -95.328486)
		(mid 296.145701 -94.745314)
		(end 296.64406 -94.442534)
		(width 0.0889)
		(layer "In11.Cu")
		(net "P3E_CPU0_PE3_OCP_RXP<13>")
	)
	(arc
		(start 298.357036 -100.576888)
		(mid 297.861559 -100.272445)
		(end 297.866816 -99.690936)
		(width 0.0889)
		(layer "In11.Cu")
		(net "P3E_CPU0_PE3_OCP_RXP<13>")
	)
	(arc
		(start 296.64406 -96.614488)
		(mid 296.145809 -96.311648)
		(end 296.15003 -95.728536)
		(width 0.0889)
		(layer "In11.Cu")
		(net "P3E_CPU0_PE3_OCP_RXP<13>")
	)
	(arc
		(start 297.004994 -96.808798)
		(mid 296.859028 -96.666399)
		(end 296.66184 -96.614488)
		(width 0.0889)
		(layer "In11.Cu")
		(net "P3E_CPU0_PE3_OCP_RXP<13>")
	)
	(arc
		(start 296.15003 -95.728536)
		(mid 296.2035 -95.533473)
		(end 296.154856 -95.337122)
		(width 0.0889)
		(layer "In11.Cu")
		(net "P3E_CPU0_PE3_OCP_RXP<13>")
	)
	(arc
		(start 297.008296 -93.252036)
		(mid 297.061829 -93.052138)
		(end 297.008296 -92.85224)
		(width 0.0889)
		(layer "In11.Cu")
		(net "P3E_CPU0_PE3_OCP_RXP<13>")
	)
	(arc
		(start 297.860466 -98.289618)
		(mid 297.787668 -97.998855)
		(end 297.866816 -97.709736)
		(width 0.0889)
		(layer "In11.Cu")
		(net "P3E_CPU0_PE3_OCP_RXP<13>")
	)
	(arc
		(start 299.583856 -101.272086)
		(mid 299.445112 -101.130053)
		(end 299.25518 -101.072188)
		(width 0.0889)
		(layer "In11.Cu")
		(net "P3E_CPU0_PE3_OCP_RXP<13>")
	)
	(arc
		(start 300.082712 -101.567488)
		(mid 299.794567 -101.485169)
		(end 299.583856 -101.272086)
		(width 0.0889)
		(layer "In11.Cu")
		(net "P3E_CPU0_PE3_OCP_RXP<13>")
	)
	(segment
		(start 455.000868 -116.993162)
		(end 455.000868 -118.343172)
		(width 0.1143)
		(layer "F.Cu")
		(net "P3E_CPU0_PE3_OCP_RXP<12>")
	)
	(segment
		(start 455.000868 -118.343172)
		(end 454.720706 -118.623334)
		(width 0.1143)
		(layer "F.Cu")
		(net "P3E_CPU0_PE3_OCP_RXP<12>")
	)
	(segment
		(start 455.408538 -121.571004)
		(end 455.579734 -121.7422)
		(width 0.1143)
		(layer "F.Cu")
		(net "P3E_CPU0_PE3_OCP_RXP<12>")
	)
	(segment
		(start 455.408538 -120.943878)
		(end 455.408538 -121.571004)
		(width 0.1143)
		(layer "F.Cu")
		(net "P3E_CPU0_PE3_OCP_RXP<12>")
	)
	(segment
		(start 454.720706 -119.283226)
		(end 455.408538 -120.943878)
		(width 0.1143)
		(layer "F.Cu")
		(net "P3E_CPU0_PE3_OCP_RXP<12>")
	)
	(segment
		(start 455.579734 -121.7422)
		(end 455.92365 -121.7422)
		(width 0.1143)
		(layer "F.Cu")
		(net "P3E_CPU0_PE3_OCP_RXP<12>")
	)
	(segment
		(start 454.720706 -118.623334)
		(end 454.720706 -119.283226)
		(width 0.1143)
		(layer "F.Cu")
		(net "P3E_CPU0_PE3_OCP_RXP<12>")
	)
	(segment
		(start 297.807126 -92.061538)
		(end 298.378626 -92.061538)
		(width 0.1143)
		(layer "F.Cu")
		(net "P3E_CPU0_PE3_OCP_RXP<12>")
	)
	(via
		(at 298.378626 -92.061538)
		(size 0.508)
		(drill 0.254)
		(layers "F.Cu" "B.Cu")
		(net "P3E_CPU0_PE3_OCP_RXP<12>")
	)
	(via
		(at 455.92365 -121.7422)
		(size 0.508)
		(drill 0.254)
		(layers "F.Cu" "B.Cu")
		(net "P3E_CPU0_PE3_OCP_RXP<12>")
	)
	(segment
		(start 355.978714 -127.836676)
		(end 358.685592 -129.0447)
		(width 0.1143)
		(layer "In11.Cu")
		(net "P3E_CPU0_PE3_OCP_RXP<12>")
	)
	(segment
		(start 329.639676 -124.235718)
		(end 329.654662 -124.24029)
		(width 0.1143)
		(layer "In11.Cu")
		(net "P3E_CPU0_PE3_OCP_RXP<12>")
	)
	(segment
		(start 303.812194 -104.1527)
		(end 304.365406 -104.1527)
		(width 0.0889)
		(layer "In11.Cu")
		(net "P3E_CPU0_PE3_OCP_RXP<12>")
	)
	(segment
		(start 405.51354 -140.621512)
		(end 405.513794 -140.621258)
		(width 0.1143)
		(layer "In11.Cu")
		(net "P3E_CPU0_PE3_OCP_RXP<12>")
	)
	(segment
		(start 298.896786 -99.280218)
		(end 298.890436 -99.290886)
		(width 0.0889)
		(layer "In11.Cu")
		(net "P3E_CPU0_PE3_OCP_RXP<12>")
	)
	(segment
		(start 425.491656 -136.503664)
		(end 430.45761 -137.947908)
		(width 0.1143)
		(layer "In11.Cu")
		(net "P3E_CPU0_PE3_OCP_RXP<12>")
	)
	(segment
		(start 298.378626 -92.061538)
		(end 298.08551 -92.230448)
		(width 0.0889)
		(layer "In11.Cu")
		(net "P3E_CPU0_PE3_OCP_RXP<12>")
	)
	(segment
		(start 304.955702 -103.9241)
		(end 305.006502 -103.8733)
		(width 0.0889)
		(layer "In11.Cu")
		(net "P3E_CPU0_PE3_OCP_RXP<12>")
	)
	(segment
		(start 301.726346 -101.315012)
		(end 301.85233 -101.440996)
		(width 0.0889)
		(layer "In11.Cu")
		(net "P3E_CPU0_PE3_OCP_RXP<12>")
	)
	(segment
		(start 454.875646 -120.2817)
		(end 455.4347 -120.840754)
		(width 0.1143)
		(layer "In11.Cu")
		(net "P3E_CPU0_PE3_OCP_RXP<12>")
	)
	(segment
		(start 411.88513 -139.368784)
		(end 415.140394 -140.120116)
		(width 0.1143)
		(layer "In11.Cu")
		(net "P3E_CPU0_PE3_OCP_RXP<12>")
	)
	(segment
		(start 298.896786 -97.299018)
		(end 298.890436 -97.309686)
		(width 0.0889)
		(layer "In11.Cu")
		(net "P3E_CPU0_PE3_OCP_RXP<12>")
	)
	(segment
		(start 306.568602 -103.8733)
		(end 309.655464 -105.152952)
		(width 0.1143)
		(layer "In11.Cu")
		(net "P3E_CPU0_PE3_OCP_RXP<12>")
	)
	(segment
		(start 303.2125 -103.553006)
		(end 303.812194 -104.1527)
		(width 0.0889)
		(layer "In11.Cu")
		(net "P3E_CPU0_PE3_OCP_RXP<12>")
	)
	(segment
		(start 298.896786 -98.289618)
		(end 298.890436 -98.300286)
		(width 0.0889)
		(layer "In11.Cu")
		(net "P3E_CPU0_PE3_OCP_RXP<12>")
	)
	(segment
		(start 326.136 -122.05716)
		(end 327.989946 -123.911106)
		(width 0.1143)
		(layer "In11.Cu")
		(net "P3E_CPU0_PE3_OCP_RXP<12>")
	)
	(segment
		(start 301.604426 -101.315012)
		(end 301.726346 -101.315012)
		(width 0.0889)
		(layer "In11.Cu")
		(net "P3E_CPU0_PE3_OCP_RXP<12>")
	)
	(segment
		(start 394.21816 -141.638274)
		(end 399.779744 -140.621512)
		(width 0.1143)
		(layer "In11.Cu")
		(net "P3E_CPU0_PE3_OCP_RXP<12>")
	)
	(segment
		(start 411.884368 -139.368784)
		(end 411.88513 -139.368784)
		(width 0.1143)
		(layer "In11.Cu")
		(net "P3E_CPU0_PE3_OCP_RXP<12>")
	)
	(segment
		(start 455.549 -121.7422)
		(end 455.92365 -121.7422)
		(width 0.1143)
		(layer "In11.Cu")
		(net "P3E_CPU0_PE3_OCP_RXP<12>")
	)
	(segment
		(start 298.08551 -92.230448)
		(end 298.061634 -92.319602)
		(width 0.0889)
		(layer "In11.Cu")
		(net "P3E_CPU0_PE3_OCP_RXP<12>")
	)
	(segment
		(start 329.654662 -124.24029)
		(end 329.654662 -124.240544)
		(width 0.1143)
		(layer "In11.Cu")
		(net "P3E_CPU0_PE3_OCP_RXP<12>")
	)
	(segment
		(start 365.014002 -130.587496)
		(end 367.409984 -132.983732)
		(width 0.1143)
		(layer "In11.Cu")
		(net "P3E_CPU0_PE3_OCP_RXP<12>")
	)
	(segment
		(start 299.22216 -99.890834)
		(end 299.2501 -99.890834)
		(width 0.0889)
		(layer "In11.Cu")
		(net "P3E_CPU0_PE3_OCP_RXP<12>")
	)
	(segment
		(start 302.09998 -101.688392)
		(end 302.225964 -101.814376)
		(width 0.0889)
		(layer "In11.Cu")
		(net "P3E_CPU0_PE3_OCP_RXP<12>")
	)
	(segment
		(start 347.17101 -128.474216)
		(end 348.382336 -128.067562)
		(width 0.1143)
		(layer "In11.Cu")
		(net "P3E_CPU0_PE3_OCP_RXP<12>")
	)
	(segment
		(start 455.4347 -120.840754)
		(end 455.4347 -121.6279)
		(width 0.1143)
		(layer "In11.Cu")
		(net "P3E_CPU0_PE3_OCP_RXP<12>")
	)
	(segment
		(start 302.58512 -102.190042)
		(end 302.58512 -102.295706)
		(width 0.0889)
		(layer "In11.Cu")
		(net "P3E_CPU0_PE3_OCP_RXP<12>")
	)
	(segment
		(start 430.45761 -137.947908)
		(end 432.52009 -137.561828)
		(width 0.1143)
		(layer "In11.Cu")
		(net "P3E_CPU0_PE3_OCP_RXP<12>")
	)
	(segment
		(start 297.537886 -95.128588)
		(end 297.507914 -95.128588)
		(width 0.0889)
		(layer "In11.Cu")
		(net "P3E_CPU0_PE3_OCP_RXP<12>")
	)
	(segment
		(start 435.61635 -138.2014)
		(end 436.931054 -137.393426)
		(width 0.1143)
		(layer "In11.Cu")
		(net "P3E_CPU0_PE3_OCP_RXP<12>")
	)
	(segment
		(start 450.59981 -123.483878)
		(end 453.802242 -120.2817)
		(width 0.1143)
		(layer "In11.Cu")
		(net "P3E_CPU0_PE3_OCP_RXP<12>")
	)
	(segment
		(start 416.595814 -139.789662)
		(end 417.361878 -139.97432)
		(width 0.1143)
		(layer "In11.Cu")
		(net "P3E_CPU0_PE3_OCP_RXP<12>")
	)
	(segment
		(start 436.931054 -137.393426)
		(end 438.394348 -133.860286)
		(width 0.1143)
		(layer "In11.Cu")
		(net "P3E_CPU0_PE3_OCP_RXP<12>")
	)
	(segment
		(start 298.890436 -98.300286)
		(end 298.88561 -98.308922)
		(width 0.0889)
		(layer "In11.Cu")
		(net "P3E_CPU0_PE3_OCP_RXP<12>")
	)
	(segment
		(start 302.353472 -102.064058)
		(end 302.459136 -102.064058)
		(width 0.0889)
		(layer "In11.Cu")
		(net "P3E_CPU0_PE3_OCP_RXP<12>")
	)
	(segment
		(start 415.140394 -140.120116)
		(end 416.595814 -139.789662)
		(width 0.1143)
		(layer "In11.Cu")
		(net "P3E_CPU0_PE3_OCP_RXP<12>")
	)
	(segment
		(start 344.045286 -127.300228)
		(end 345.22537 -128.096264)
		(width 0.1143)
		(layer "In11.Cu")
		(net "P3E_CPU0_PE3_OCP_RXP<12>")
	)
	(segment
		(start 425.20362 -136.554972)
		(end 425.491656 -136.503664)
		(width 0.1143)
		(layer "In11.Cu")
		(net "P3E_CPU0_PE3_OCP_RXP<12>")
	)
	(segment
		(start 300.077632 -100.386134)
		(end 300.113446 -100.386134)
		(width 0.0889)
		(layer "In11.Cu")
		(net "P3E_CPU0_PE3_OCP_RXP<12>")
	)
	(segment
		(start 367.409984 -132.983732)
		(end 368.748056 -136.214866)
		(width 0.1143)
		(layer "In11.Cu")
		(net "P3E_CPU0_PE3_OCP_RXP<12>")
	)
	(segment
		(start 301.465996 -101.176582)
		(end 301.604426 -101.315012)
		(width 0.0889)
		(layer "In11.Cu")
		(net "P3E_CPU0_PE3_OCP_RXP<12>")
	)
	(segment
		(start 298.36745 -96.423988)
		(end 298.400216 -96.423988)
		(width 0.0889)
		(layer "In11.Cu")
		(net "P3E_CPU0_PE3_OCP_RXP<12>")
	)
	(segment
		(start 298.031916 -93.252036)
		(end 298.038266 -93.262704)
		(width 0.0889)
		(layer "In11.Cu")
		(net "P3E_CPU0_PE3_OCP_RXP<12>")
	)
	(segment
		(start 368.748056 -136.214866)
		(end 372.285006 -138.923268)
		(width 0.1143)
		(layer "In11.Cu")
		(net "P3E_CPU0_PE3_OCP_RXP<12>")
	)
	(segment
		(start 449.824348 -125.35535)
		(end 450.59981 -123.483878)
		(width 0.1143)
		(layer "In11.Cu")
		(net "P3E_CPU0_PE3_OCP_RXP<12>")
	)
	(segment
		(start 316.859412 -112.359694)
		(end 319.046352 -112.359694)
		(width 0.1143)
		(layer "In11.Cu")
		(net "P3E_CPU0_PE3_OCP_RXP<12>")
	)
	(segment
		(start 298.02709 -93.2434)
		(end 298.031916 -93.252036)
		(width 0.0889)
		(layer "In11.Cu")
		(net "P3E_CPU0_PE3_OCP_RXP<12>")
	)
	(segment
		(start 327.989946 -123.911106)
		(end 329.639676 -124.235718)
		(width 0.1143)
		(layer "In11.Cu")
		(net "P3E_CPU0_PE3_OCP_RXP<12>")
	)
	(segment
		(start 345.22537 -128.096264)
		(end 347.17101 -128.474216)
		(width 0.1143)
		(layer "In11.Cu")
		(net "P3E_CPU0_PE3_OCP_RXP<12>")
	)
	(segment
		(start 352.23323 -128.801622)
		(end 355.978714 -127.836676)
		(width 0.1143)
		(layer "In11.Cu")
		(net "P3E_CPU0_PE3_OCP_RXP<12>")
	)
	(segment
		(start 326.136 -119.449342)
		(end 326.136 -122.05716)
		(width 0.1143)
		(layer "In11.Cu")
		(net "P3E_CPU0_PE3_OCP_RXP<12>")
	)
	(segment
		(start 432.52009 -137.561828)
		(end 435.61635 -138.2014)
		(width 0.1143)
		(layer "In11.Cu")
		(net "P3E_CPU0_PE3_OCP_RXP<12>")
	)
	(segment
		(start 302.58512 -102.295706)
		(end 303.2125 -102.923086)
		(width 0.0889)
		(layer "In11.Cu")
		(net "P3E_CPU0_PE3_OCP_RXP<12>")
	)
	(segment
		(start 405.513794 -140.621258)
		(end 411.884368 -139.368784)
		(width 0.1143)
		(layer "In11.Cu")
		(net "P3E_CPU0_PE3_OCP_RXP<12>")
	)
	(segment
		(start 305.0286 -103.8733)
		(end 306.568602 -103.8733)
		(width 0.1143)
		(layer "In11.Cu")
		(net "P3E_CPU0_PE3_OCP_RXP<12>")
	)
	(segment
		(start 301.85233 -101.440996)
		(end 301.85233 -101.562916)
		(width 0.0889)
		(layer "In11.Cu")
		(net "P3E_CPU0_PE3_OCP_RXP<12>")
	)
	(segment
		(start 303.2125 -102.923086)
		(end 303.2125 -103.553006)
		(width 0.0889)
		(layer "In11.Cu")
		(net "P3E_CPU0_PE3_OCP_RXP<12>")
	)
	(segment
		(start 305.006502 -103.8733)
		(end 305.0286 -103.8733)
		(width 0.0889)
		(layer "In11.Cu")
		(net "P3E_CPU0_PE3_OCP_RXP<12>")
	)
	(segment
		(start 298.02709 -94.234)
		(end 298.031916 -94.242636)
		(width 0.0889)
		(layer "In11.Cu")
		(net "P3E_CPU0_PE3_OCP_RXP<12>")
	)
	(segment
		(start 381.807974 -139.732512)
		(end 386.012436 -140.587476)
		(width 0.1143)
		(layer "In11.Cu")
		(net "P3E_CPU0_PE3_OCP_RXP<12>")
	)
	(segment
		(start 348.382336 -128.067562)
		(end 352.23323 -128.801622)
		(width 0.1143)
		(layer "In11.Cu")
		(net "P3E_CPU0_PE3_OCP_RXP<12>")
	)
	(segment
		(start 442.292486 -129.962402)
		(end 449.824348 -125.35535)
		(width 0.1143)
		(layer "In11.Cu")
		(net "P3E_CPU0_PE3_OCP_RXP<12>")
	)
	(segment
		(start 438.394348 -133.860286)
		(end 442.292486 -129.962402)
		(width 0.1143)
		(layer "In11.Cu")
		(net "P3E_CPU0_PE3_OCP_RXP<12>")
	)
	(segment
		(start 319.046352 -112.359694)
		(end 326.136 -119.449342)
		(width 0.1143)
		(layer "In11.Cu")
		(net "P3E_CPU0_PE3_OCP_RXP<12>")
	)
	(segment
		(start 399.779744 -140.621512)
		(end 405.51354 -140.621512)
		(width 0.1143)
		(layer "In11.Cu")
		(net "P3E_CPU0_PE3_OCP_RXP<12>")
	)
	(segment
		(start 304.594006 -103.9241)
		(end 304.955702 -103.9241)
		(width 0.0889)
		(layer "In11.Cu")
		(net "P3E_CPU0_PE3_OCP_RXP<12>")
	)
	(segment
		(start 301.85233 -101.562916)
		(end 301.977806 -101.688392)
		(width 0.0889)
		(layer "In11.Cu")
		(net "P3E_CPU0_PE3_OCP_RXP<12>")
	)
	(segment
		(start 379.037342 -140.296646)
		(end 381.807974 -139.732512)
		(width 0.1143)
		(layer "In11.Cu")
		(net "P3E_CPU0_PE3_OCP_RXP<12>")
	)
	(segment
		(start 386.012436 -140.587476)
		(end 390.36498 -140.587476)
		(width 0.1143)
		(layer "In11.Cu")
		(net "P3E_CPU0_PE3_OCP_RXP<12>")
	)
	(segment
		(start 417.361878 -139.97432)
		(end 425.20362 -136.554972)
		(width 0.1143)
		(layer "In11.Cu")
		(net "P3E_CPU0_PE3_OCP_RXP<12>")
	)
	(segment
		(start 372.285006 -138.923268)
		(end 379.037342 -140.296646)
		(width 0.1143)
		(layer "In11.Cu")
		(net "P3E_CPU0_PE3_OCP_RXP<12>")
	)
	(segment
		(start 453.802242 -120.2817)
		(end 454.875646 -120.2817)
		(width 0.1143)
		(layer "In11.Cu")
		(net "P3E_CPU0_PE3_OCP_RXP<12>")
	)
	(segment
		(start 301.977806 -101.688392)
		(end 302.09998 -101.688392)
		(width 0.0889)
		(layer "In11.Cu")
		(net "P3E_CPU0_PE3_OCP_RXP<12>")
	)
	(segment
		(start 302.459136 -102.064058)
		(end 302.58512 -102.190042)
		(width 0.0889)
		(layer "In11.Cu")
		(net "P3E_CPU0_PE3_OCP_RXP<12>")
	)
	(segment
		(start 302.225964 -101.814376)
		(end 302.225964 -101.93655)
		(width 0.0889)
		(layer "In11.Cu")
		(net "P3E_CPU0_PE3_OCP_RXP<12>")
	)
	(segment
		(start 334.171544 -125.65253)
		(end 341.14994 -125.65253)
		(width 0.1143)
		(layer "In11.Cu")
		(net "P3E_CPU0_PE3_OCP_RXP<12>")
	)
	(segment
		(start 343.202768 -126.051818)
		(end 344.045286 -127.300228)
		(width 0.1143)
		(layer "In11.Cu")
		(net "P3E_CPU0_PE3_OCP_RXP<12>")
	)
	(segment
		(start 358.685592 -129.0447)
		(end 361.16514 -129.0447)
		(width 0.1143)
		(layer "In11.Cu")
		(net "P3E_CPU0_PE3_OCP_RXP<12>")
	)
	(segment
		(start 304.365406 -104.1527)
		(end 304.594006 -103.9241)
		(width 0.0889)
		(layer "In11.Cu")
		(net "P3E_CPU0_PE3_OCP_RXP<12>")
	)
	(segment
		(start 329.654662 -124.240544)
		(end 334.171544 -125.65253)
		(width 0.1143)
		(layer "In11.Cu")
		(net "P3E_CPU0_PE3_OCP_RXP<12>")
	)
	(segment
		(start 361.16514 -129.0447)
		(end 365.014002 -130.587496)
		(width 0.1143)
		(layer "In11.Cu")
		(net "P3E_CPU0_PE3_OCP_RXP<12>")
	)
	(segment
		(start 309.655464 -105.152952)
		(end 316.859412 -112.359694)
		(width 0.1143)
		(layer "In11.Cu")
		(net "P3E_CPU0_PE3_OCP_RXP<12>")
	)
	(segment
		(start 298.890436 -99.290886)
		(end 298.88561 -99.299522)
		(width 0.0889)
		(layer "In11.Cu")
		(net "P3E_CPU0_PE3_OCP_RXP<12>")
	)
	(segment
		(start 298.890436 -97.309686)
		(end 298.88561 -97.318322)
		(width 0.0889)
		(layer "In11.Cu")
		(net "P3E_CPU0_PE3_OCP_RXP<12>")
	)
	(segment
		(start 302.225964 -101.93655)
		(end 302.353472 -102.064058)
		(width 0.0889)
		(layer "In11.Cu")
		(net "P3E_CPU0_PE3_OCP_RXP<12>")
	)
	(segment
		(start 390.36498 -140.587476)
		(end 394.21816 -141.638274)
		(width 0.1143)
		(layer "In11.Cu")
		(net "P3E_CPU0_PE3_OCP_RXP<12>")
	)
	(segment
		(start 300.936152 -100.881434)
		(end 300.975776 -100.881434)
		(width 0.0889)
		(layer "In11.Cu")
		(net "P3E_CPU0_PE3_OCP_RXP<12>")
	)
	(segment
		(start 297.520106 -95.928434)
		(end 297.537886 -95.928434)
		(width 0.0889)
		(layer "In11.Cu")
		(net "P3E_CPU0_PE3_OCP_RXP<12>")
	)
	(segment
		(start 341.14994 -125.65253)
		(end 343.202768 -126.051818)
		(width 0.1143)
		(layer "In11.Cu")
		(net "P3E_CPU0_PE3_OCP_RXP<12>")
	)
	(segment
		(start 455.4347 -121.6279)
		(end 455.549 -121.7422)
		(width 0.1143)
		(layer "In11.Cu")
		(net "P3E_CPU0_PE3_OCP_RXP<12>")
	)
	(arc
		(start 298.400216 -96.423988)
		(mid 298.892606 -96.722921)
		(end 298.896786 -97.299018)
		(width 0.0889)
		(layer "In11.Cu")
		(net "P3E_CPU0_PE3_OCP_RXP<12>")
	)
	(arc
		(start 300.113446 -100.386134)
		(mid 300.39887 -100.469601)
		(end 300.607476 -100.681536)
		(width 0.0889)
		(layer "In11.Cu")
		(net "P3E_CPU0_PE3_OCP_RXP<12>")
	)
	(arc
		(start 298.890436 -97.709736)
		(mid 298.969658 -97.998854)
		(end 298.896786 -98.289618)
		(width 0.0889)
		(layer "In11.Cu")
		(net "P3E_CPU0_PE3_OCP_RXP<12>")
	)
	(arc
		(start 297.537886 -95.928434)
		(mid 297.82331 -96.011901)
		(end 298.031916 -96.223836)
		(width 0.0889)
		(layer "In11.Cu")
		(net "P3E_CPU0_PE3_OCP_RXP<12>")
	)
	(arc
		(start 298.031916 -96.223836)
		(mid 298.173599 -96.36764)
		(end 298.36745 -96.423988)
		(width 0.0889)
		(layer "In11.Cu")
		(net "P3E_CPU0_PE3_OCP_RXP<12>")
	)
	(arc
		(start 297.507914 -95.128588)
		(mid 297.120171 -95.534481)
		(end 297.520106 -95.928434)
		(width 0.0889)
		(layer "In11.Cu")
		(net "P3E_CPU0_PE3_OCP_RXP<12>")
	)
	(arc
		(start 300.607476 -100.681536)
		(mid 300.74622 -100.823569)
		(end 300.936152 -100.881434)
		(width 0.0889)
		(layer "In11.Cu")
		(net "P3E_CPU0_PE3_OCP_RXP<12>")
	)
	(arc
		(start 298.031916 -92.851986)
		(mid 297.978446 -93.047049)
		(end 298.02709 -93.2434)
		(width 0.0889)
		(layer "In11.Cu")
		(net "P3E_CPU0_PE3_OCP_RXP<12>")
	)
	(arc
		(start 298.031916 -93.842586)
		(mid 297.978446 -94.037649)
		(end 298.02709 -94.234)
		(width 0.0889)
		(layer "In11.Cu")
		(net "P3E_CPU0_PE3_OCP_RXP<12>")
	)
	(arc
		(start 298.890436 -98.700336)
		(mid 298.969658 -98.989454)
		(end 298.896786 -99.280218)
		(width 0.0889)
		(layer "In11.Cu")
		(net "P3E_CPU0_PE3_OCP_RXP<12>")
	)
	(arc
		(start 298.88561 -97.318322)
		(mid 298.836855 -97.514674)
		(end 298.890436 -97.709736)
		(width 0.0889)
		(layer "In11.Cu")
		(net "P3E_CPU0_PE3_OCP_RXP<12>")
	)
	(arc
		(start 300.975776 -100.881434)
		(mid 301.258993 -100.965715)
		(end 301.465996 -101.176582)
		(width 0.0889)
		(layer "In11.Cu")
		(net "P3E_CPU0_PE3_OCP_RXP<12>")
	)
	(arc
		(start 298.88561 -98.308922)
		(mid 298.836855 -98.505274)
		(end 298.890436 -98.700336)
		(width 0.0889)
		(layer "In11.Cu")
		(net "P3E_CPU0_PE3_OCP_RXP<12>")
	)
	(arc
		(start 298.061634 -92.319602)
		(mid 298.110194 -92.589327)
		(end 298.031916 -92.851986)
		(width 0.0889)
		(layer "In11.Cu")
		(net "P3E_CPU0_PE3_OCP_RXP<12>")
	)
	(arc
		(start 299.2501 -99.890834)
		(mid 299.538245 -99.973153)
		(end 299.748956 -100.186236)
		(width 0.0889)
		(layer "In11.Cu")
		(net "P3E_CPU0_PE3_OCP_RXP<12>")
	)
	(arc
		(start 298.031916 -94.242636)
		(mid 298.036245 -94.825808)
		(end 297.537886 -95.128588)
		(width 0.0889)
		(layer "In11.Cu")
		(net "P3E_CPU0_PE3_OCP_RXP<12>")
	)
	(arc
		(start 299.748956 -100.186236)
		(mid 299.8877 -100.328269)
		(end 300.077632 -100.386134)
		(width 0.0889)
		(layer "In11.Cu")
		(net "P3E_CPU0_PE3_OCP_RXP<12>")
	)
	(arc
		(start 298.038266 -93.262704)
		(mid 298.111064 -93.553467)
		(end 298.031916 -93.842586)
		(width 0.0889)
		(layer "In11.Cu")
		(net "P3E_CPU0_PE3_OCP_RXP<12>")
	)
	(arc
		(start 298.88561 -99.299522)
		(mid 298.889357 -99.688778)
		(end 299.22216 -99.890834)
		(width 0.0889)
		(layer "In11.Cu")
		(net "P3E_CPU0_PE3_OCP_RXP<12>")
	)
	(segment
		(start 298.665646 -93.547184)
		(end 299.237146 -93.547184)
		(width 0.1143)
		(layer "F.Cu")
		(net "P3E_CPU0_PE3_OCP_RXP<11>")
	)
	(segment
		(start 451.800976 -118.342918)
		(end 451.52056 -118.623334)
		(width 0.1143)
		(layer "F.Cu")
		(net "P3E_CPU0_PE3_OCP_RXP<11>")
	)
	(segment
		(start 451.52056 -118.623334)
		(end 451.52056 -119.502936)
		(width 0.1143)
		(layer "F.Cu")
		(net "P3E_CPU0_PE3_OCP_RXP<11>")
	)
	(segment
		(start 451.54215 -120.66397)
		(end 451.9422 -120.66397)
		(width 0.1143)
		(layer "F.Cu")
		(net "P3E_CPU0_PE3_OCP_RXP<11>")
	)
	(segment
		(start 451.42785 -120.54967)
		(end 451.54215 -120.66397)
		(width 0.1143)
		(layer "F.Cu")
		(net "P3E_CPU0_PE3_OCP_RXP<11>")
	)
	(segment
		(start 451.800976 -116.993162)
		(end 451.800976 -118.342918)
		(width 0.1143)
		(layer "F.Cu")
		(net "P3E_CPU0_PE3_OCP_RXP<11>")
	)
	(segment
		(start 451.52056 -119.502936)
		(end 451.42785 -119.726964)
		(width 0.1143)
		(layer "F.Cu")
		(net "P3E_CPU0_PE3_OCP_RXP<11>")
	)
	(segment
		(start 451.42785 -119.726964)
		(end 451.42785 -120.54967)
		(width 0.1143)
		(layer "F.Cu")
		(net "P3E_CPU0_PE3_OCP_RXP<11>")
	)
	(via
		(at 451.9422 -120.66397)
		(size 0.508)
		(drill 0.254)
		(layers "F.Cu" "B.Cu")
		(net "P3E_CPU0_PE3_OCP_RXP<11>")
	)
	(via
		(at 299.237146 -93.547184)
		(size 0.508)
		(drill 0.254)
		(layers "F.Cu" "B.Cu")
		(net "P3E_CPU0_PE3_OCP_RXP<11>")
	)
	(segment
		(start 351.071688 -124.480066)
		(end 351.778316 -124.342906)
		(width 0.1143)
		(layer "In11.Cu")
		(net "P3E_CPU0_PE3_OCP_RXP<11>")
	)
	(segment
		(start 379.813566 -136.234678)
		(end 381.700786 -137.48385)
		(width 0.1143)
		(layer "In11.Cu")
		(net "P3E_CPU0_PE3_OCP_RXP<11>")
	)
	(segment
		(start 334.204056 -123.245372)
		(end 339.42782 -123.245372)
		(width 0.1143)
		(layer "In11.Cu")
		(net "P3E_CPU0_PE3_OCP_RXP<11>")
	)
	(segment
		(start 451.070726 -119.19458)
		(end 451.4469 -119.570754)
		(width 0.1143)
		(layer "In11.Cu")
		(net "P3E_CPU0_PE3_OCP_RXP<11>")
	)
	(segment
		(start 440.941206 -121.485406)
		(end 443.15253 -121.043192)
		(width 0.1143)
		(layer "In11.Cu")
		(net "P3E_CPU0_PE3_OCP_RXP<11>")
	)
	(segment
		(start 424.001438 -131.83362)
		(end 427.529244 -131.00812)
		(width 0.1143)
		(layer "In11.Cu")
		(net "P3E_CPU0_PE3_OCP_RXP<11>")
	)
	(segment
		(start 433.48275 -128.112266)
		(end 435.548532 -123.719336)
		(width 0.1143)
		(layer "In11.Cu")
		(net "P3E_CPU0_PE3_OCP_RXP<11>")
	)
	(segment
		(start 374.513602 -135.60044)
		(end 375.14784 -136.234678)
		(width 0.1143)
		(layer "In11.Cu")
		(net "P3E_CPU0_PE3_OCP_RXP<11>")
	)
	(segment
		(start 415.14395 -138.161268)
		(end 415.144204 -138.161014)
		(width 0.1143)
		(layer "In11.Cu")
		(net "P3E_CPU0_PE3_OCP_RXP<11>")
	)
	(segment
		(start 399.58899 -138.711686)
		(end 405.328628 -138.711686)
		(width 0.1143)
		(layer "In11.Cu")
		(net "P3E_CPU0_PE3_OCP_RXP<11>")
	)
	(segment
		(start 411.916626 -137.416286)
		(end 411.917388 -137.416286)
		(width 0.1143)
		(layer "In11.Cu")
		(net "P3E_CPU0_PE3_OCP_RXP<11>")
	)
	(segment
		(start 417.18611 -137.96772)
		(end 420.74846 -136.414256)
		(width 0.1143)
		(layer "In11.Cu")
		(net "P3E_CPU0_PE3_OCP_RXP<11>")
	)
	(segment
		(start 449.080382 -121.447052)
		(end 449.080636 -121.447052)
		(width 0.1143)
		(layer "In11.Cu")
		(net "P3E_CPU0_PE3_OCP_RXP<11>")
	)
	(segment
		(start 415.144204 -138.161268)
		(end 416.608768 -137.828782)
		(width 0.1143)
		(layer "In11.Cu")
		(net "P3E_CPU0_PE3_OCP_RXP<11>")
	)
	(segment
		(start 387.554216 -138.67511)
		(end 390.62152 -138.67511)
		(width 0.1143)
		(layer "In11.Cu")
		(net "P3E_CPU0_PE3_OCP_RXP<11>")
	)
	(segment
		(start 352.476562 -124.478542)
		(end 353.376484 -124.303536)
		(width 0.1143)
		(layer "In11.Cu")
		(net "P3E_CPU0_PE3_OCP_RXP<11>")
	)
	(segment
		(start 301.46117 -97.2058)
		(end 301.465996 -97.214436)
		(width 0.0889)
		(layer "In11.Cu")
		(net "P3E_CPU0_PE3_OCP_RXP<11>")
	)
	(segment
		(start 353.376484 -124.303536)
		(end 354.203 -124.464318)
		(width 0.1143)
		(layer "In11.Cu")
		(net "P3E_CPU0_PE3_OCP_RXP<11>")
	)
	(segment
		(start 301.472346 -94.822518)
		(end 301.465996 -94.833186)
		(width 0.0889)
		(layer "In11.Cu")
		(net "P3E_CPU0_PE3_OCP_RXP<11>")
	)
	(segment
		(start 299.237146 -93.547184)
		(end 299.530262 -93.716348)
		(width 0.0889)
		(layer "In11.Cu")
		(net "P3E_CPU0_PE3_OCP_RXP<11>")
	)
	(segment
		(start 302.222916 -98.405188)
		(end 302.919892 -99.102164)
		(width 0.0889)
		(layer "In11.Cu")
		(net "P3E_CPU0_PE3_OCP_RXP<11>")
	)
	(segment
		(start 306.201064 -101.067616)
		(end 311.096152 -103.095298)
		(width 0.1143)
		(layer "In11.Cu")
		(net "P3E_CPU0_PE3_OCP_RXP<11>")
	)
	(segment
		(start 411.917388 -137.416286)
		(end 415.14395 -138.161268)
		(width 0.1143)
		(layer "In11.Cu")
		(net "P3E_CPU0_PE3_OCP_RXP<11>")
	)
	(segment
		(start 299.530262 -93.716348)
		(end 299.61967 -93.692218)
		(width 0.0889)
		(layer "In11.Cu")
		(net "P3E_CPU0_PE3_OCP_RXP<11>")
	)
	(segment
		(start 305.309524 -100.176076)
		(end 306.201064 -101.067616)
		(width 0.1143)
		(layer "In11.Cu")
		(net "P3E_CPU0_PE3_OCP_RXP<11>")
	)
	(segment
		(start 305.29403 -100.160582)
		(end 305.309524 -100.176076)
		(width 0.0889)
		(layer "In11.Cu")
		(net "P3E_CPU0_PE3_OCP_RXP<11>")
	)
	(segment
		(start 330.813918 -119.85625)
		(end 334.204056 -123.245372)
		(width 0.1143)
		(layer "In11.Cu")
		(net "P3E_CPU0_PE3_OCP_RXP<11>")
	)
	(segment
		(start 311.096152 -103.095298)
		(end 317.90894 -109.90834)
		(width 0.1143)
		(layer "In11.Cu")
		(net "P3E_CPU0_PE3_OCP_RXP<11>")
	)
	(segment
		(start 449.402962 -121.12498)
		(end 449.402962 -119.7102)
		(width 0.1143)
		(layer "In11.Cu")
		(net "P3E_CPU0_PE3_OCP_RXP<11>")
	)
	(segment
		(start 430.586134 -128.941322)
		(end 433.48275 -128.112266)
		(width 0.1143)
		(layer "In11.Cu")
		(net "P3E_CPU0_PE3_OCP_RXP<11>")
	)
	(segment
		(start 355.063552 -125.044454)
		(end 355.063806 -125.044962)
		(width 0.1143)
		(layer "In11.Cu")
		(net "P3E_CPU0_PE3_OCP_RXP<11>")
	)
	(segment
		(start 374.513602 -134.890256)
		(end 374.513602 -135.60044)
		(width 0.1143)
		(layer "In11.Cu")
		(net "P3E_CPU0_PE3_OCP_RXP<11>")
	)
	(segment
		(start 301.465996 -97.214436)
		(end 301.472346 -97.225104)
		(width 0.0889)
		(layer "In11.Cu")
		(net "P3E_CPU0_PE3_OCP_RXP<11>")
	)
	(segment
		(start 344.762074 -124.329698)
		(end 350.297496 -124.329698)
		(width 0.1143)
		(layer "In11.Cu")
		(net "P3E_CPU0_PE3_OCP_RXP<11>")
	)
	(segment
		(start 301.80153 -98.405188)
		(end 302.222916 -98.405188)
		(width 0.0889)
		(layer "In11.Cu")
		(net "P3E_CPU0_PE3_OCP_RXP<11>")
	)
	(segment
		(start 325.35114 -113.94186)
		(end 325.35114 -115.952524)
		(width 0.1143)
		(layer "In11.Cu")
		(net "P3E_CPU0_PE3_OCP_RXP<11>")
	)
	(segment
		(start 321.31762 -109.90834)
		(end 325.35114 -113.94186)
		(width 0.1143)
		(layer "In11.Cu")
		(net "P3E_CPU0_PE3_OCP_RXP<11>")
	)
	(segment
		(start 317.90894 -109.90834)
		(end 321.31762 -109.90834)
		(width 0.1143)
		(layer "In11.Cu")
		(net "P3E_CPU0_PE3_OCP_RXP<11>")
	)
	(segment
		(start 355.854254 -125.577854)
		(end 359.25252 -127.09652)
		(width 0.1143)
		(layer "In11.Cu")
		(net "P3E_CPU0_PE3_OCP_RXP<11>")
	)
	(segment
		(start 361.720892 -127.09652)
		(end 367.045748 -129.301748)
		(width 0.1143)
		(layer "In11.Cu")
		(net "P3E_CPU0_PE3_OCP_RXP<11>")
	)
	(segment
		(start 301.46117 -96.2152)
		(end 301.465996 -96.223836)
		(width 0.0889)
		(layer "In11.Cu")
		(net "P3E_CPU0_PE3_OCP_RXP<11>")
	)
	(segment
		(start 449.918582 -119.19458)
		(end 451.070726 -119.19458)
		(width 0.1143)
		(layer "In11.Cu")
		(net "P3E_CPU0_PE3_OCP_RXP<11>")
	)
	(segment
		(start 381.700786 -137.48385)
		(end 387.554216 -138.67511)
		(width 0.1143)
		(layer "In11.Cu")
		(net "P3E_CPU0_PE3_OCP_RXP<11>")
	)
	(segment
		(start 350.297496 -124.329698)
		(end 351.071688 -124.480066)
		(width 0.1143)
		(layer "In11.Cu")
		(net "P3E_CPU0_PE3_OCP_RXP<11>")
	)
	(segment
		(start 305.222148 -100.160582)
		(end 305.29403 -100.160582)
		(width 0.0889)
		(layer "In11.Cu")
		(net "P3E_CPU0_PE3_OCP_RXP<11>")
	)
	(segment
		(start 435.548532 -123.719336)
		(end 440.941206 -121.485406)
		(width 0.1143)
		(layer "In11.Cu")
		(net "P3E_CPU0_PE3_OCP_RXP<11>")
	)
	(segment
		(start 355.063806 -125.044962)
		(end 355.854254 -125.577854)
		(width 0.1143)
		(layer "In11.Cu")
		(net "P3E_CPU0_PE3_OCP_RXP<11>")
	)
	(segment
		(start 416.608768 -137.828782)
		(end 417.18611 -137.96772)
		(width 0.1143)
		(layer "In11.Cu")
		(net "P3E_CPU0_PE3_OCP_RXP<11>")
	)
	(segment
		(start 394.301472 -139.677902)
		(end 399.58899 -138.711686)
		(width 0.1143)
		(layer "In11.Cu")
		(net "P3E_CPU0_PE3_OCP_RXP<11>")
	)
	(segment
		(start 301.465996 -96.223836)
		(end 301.472346 -96.234504)
		(width 0.0889)
		(layer "In11.Cu")
		(net "P3E_CPU0_PE3_OCP_RXP<11>")
	)
	(segment
		(start 367.045748 -129.301748)
		(end 369.9129 -132.1689)
		(width 0.1143)
		(layer "In11.Cu")
		(net "P3E_CPU0_PE3_OCP_RXP<11>")
	)
	(segment
		(start 451.4469 -120.535446)
		(end 451.575424 -120.66397)
		(width 0.1143)
		(layer "In11.Cu")
		(net "P3E_CPU0_PE3_OCP_RXP<11>")
	)
	(segment
		(start 451.4469 -119.570754)
		(end 451.4469 -120.535446)
		(width 0.1143)
		(layer "In11.Cu")
		(net "P3E_CPU0_PE3_OCP_RXP<11>")
	)
	(segment
		(start 449.080636 -121.447052)
		(end 449.402962 -121.12498)
		(width 0.1143)
		(layer "In11.Cu")
		(net "P3E_CPU0_PE3_OCP_RXP<11>")
	)
	(segment
		(start 372.171976 -132.549138)
		(end 374.513602 -134.890256)
		(width 0.1143)
		(layer "In11.Cu")
		(net "P3E_CPU0_PE3_OCP_RXP<11>")
	)
	(segment
		(start 354.203 -124.464318)
		(end 355.063552 -125.044454)
		(width 0.1143)
		(layer "In11.Cu")
		(net "P3E_CPU0_PE3_OCP_RXP<11>")
	)
	(segment
		(start 420.74846 -136.414256)
		(end 422.949878 -132.508244)
		(width 0.1143)
		(layer "In11.Cu")
		(net "P3E_CPU0_PE3_OCP_RXP<11>")
	)
	(segment
		(start 325.35114 -115.952524)
		(end 329.254866 -119.85625)
		(width 0.1143)
		(layer "In11.Cu")
		(net "P3E_CPU0_PE3_OCP_RXP<11>")
	)
	(segment
		(start 329.254866 -119.85625)
		(end 330.813918 -119.85625)
		(width 0.1143)
		(layer "In11.Cu")
		(net "P3E_CPU0_PE3_OCP_RXP<11>")
	)
	(segment
		(start 375.14784 -136.234678)
		(end 379.813566 -136.234678)
		(width 0.1143)
		(layer "In11.Cu")
		(net "P3E_CPU0_PE3_OCP_RXP<11>")
	)
	(segment
		(start 422.949878 -132.508244)
		(end 424.001438 -131.83362)
		(width 0.1143)
		(layer "In11.Cu")
		(net "P3E_CPU0_PE3_OCP_RXP<11>")
	)
	(segment
		(start 300.074076 -93.452188)
		(end 300.117256 -93.452188)
		(width 0.0889)
		(layer "In11.Cu")
		(net "P3E_CPU0_PE3_OCP_RXP<11>")
	)
	(segment
		(start 443.15253 -121.043192)
		(end 447.090546 -121.829576)
		(width 0.1143)
		(layer "In11.Cu")
		(net "P3E_CPU0_PE3_OCP_RXP<11>")
	)
	(segment
		(start 415.144204 -138.161014)
		(end 415.144204 -138.161268)
		(width 0.1143)
		(layer "In11.Cu")
		(net "P3E_CPU0_PE3_OCP_RXP<11>")
	)
	(segment
		(start 359.25252 -127.09652)
		(end 361.720892 -127.09652)
		(width 0.1143)
		(layer "In11.Cu")
		(net "P3E_CPU0_PE3_OCP_RXP<11>")
	)
	(segment
		(start 339.42782 -123.245372)
		(end 344.762074 -124.329698)
		(width 0.1143)
		(layer "In11.Cu")
		(net "P3E_CPU0_PE3_OCP_RXP<11>")
	)
	(segment
		(start 371.256052 -132.1689)
		(end 372.171976 -132.549138)
		(width 0.1143)
		(layer "In11.Cu")
		(net "P3E_CPU0_PE3_OCP_RXP<11>")
	)
	(segment
		(start 449.402962 -119.7102)
		(end 449.918582 -119.19458)
		(width 0.1143)
		(layer "In11.Cu")
		(net "P3E_CPU0_PE3_OCP_RXP<11>")
	)
	(segment
		(start 427.529244 -131.00812)
		(end 430.586134 -128.941322)
		(width 0.1143)
		(layer "In11.Cu")
		(net "P3E_CPU0_PE3_OCP_RXP<11>")
	)
	(segment
		(start 351.778316 -124.342906)
		(end 352.476562 -124.478542)
		(width 0.1143)
		(layer "In11.Cu")
		(net "P3E_CPU0_PE3_OCP_RXP<11>")
	)
	(segment
		(start 447.090546 -121.829576)
		(end 449.080382 -121.447052)
		(width 0.1143)
		(layer "In11.Cu")
		(net "P3E_CPU0_PE3_OCP_RXP<11>")
	)
	(segment
		(start 405.328628 -138.711686)
		(end 411.916626 -137.416286)
		(width 0.1143)
		(layer "In11.Cu")
		(net "P3E_CPU0_PE3_OCP_RXP<11>")
	)
	(segment
		(start 305.076352 -100.014786)
		(end 305.222148 -100.160582)
		(width 0.0889)
		(layer "In11.Cu")
		(net "P3E_CPU0_PE3_OCP_RXP<11>")
	)
	(segment
		(start 302.919892 -99.102164)
		(end 305.076352 -100.014786)
		(width 0.0889)
		(layer "In11.Cu")
		(net "P3E_CPU0_PE3_OCP_RXP<11>")
	)
	(segment
		(start 451.575424 -120.66397)
		(end 451.9422 -120.66397)
		(width 0.1143)
		(layer "In11.Cu")
		(net "P3E_CPU0_PE3_OCP_RXP<11>")
	)
	(segment
		(start 300.9392 -93.947234)
		(end 300.96714 -93.947234)
		(width 0.0889)
		(layer "In11.Cu")
		(net "P3E_CPU0_PE3_OCP_RXP<11>")
	)
	(segment
		(start 369.9129 -132.1689)
		(end 371.256052 -132.1689)
		(width 0.1143)
		(layer "In11.Cu")
		(net "P3E_CPU0_PE3_OCP_RXP<11>")
	)
	(segment
		(start 390.62152 -138.67511)
		(end 394.301472 -139.677902)
		(width 0.1143)
		(layer "In11.Cu")
		(net "P3E_CPU0_PE3_OCP_RXP<11>")
	)
	(arc
		(start 300.96714 -93.947234)
		(mid 301.466021 -94.242671)
		(end 301.472346 -94.822518)
		(width 0.0889)
		(layer "In11.Cu")
		(net "P3E_CPU0_PE3_OCP_RXP<11>")
	)
	(arc
		(start 301.472346 -96.234504)
		(mid 301.545144 -96.525267)
		(end 301.465996 -96.814386)
		(width 0.0889)
		(layer "In11.Cu")
		(net "P3E_CPU0_PE3_OCP_RXP<11>")
	)
	(arc
		(start 300.607476 -93.747336)
		(mid 300.747555 -93.890072)
		(end 300.9392 -93.947234)
		(width 0.0889)
		(layer "In11.Cu")
		(net "P3E_CPU0_PE3_OCP_RXP<11>")
	)
	(arc
		(start 299.61967 -93.692218)
		(mid 299.819415 -93.520224)
		(end 300.074076 -93.452188)
		(width 0.0889)
		(layer "In11.Cu")
		(net "P3E_CPU0_PE3_OCP_RXP<11>")
	)
	(arc
		(start 301.465996 -94.833186)
		(mid 301.412497 -95.033084)
		(end 301.465996 -95.232982)
		(width 0.0889)
		(layer "In11.Cu")
		(net "P3E_CPU0_PE3_OCP_RXP<11>")
	)
	(arc
		(start 301.472346 -97.225104)
		(mid 301.545144 -97.515867)
		(end 301.465996 -97.804986)
		(width 0.0889)
		(layer "In11.Cu")
		(net "P3E_CPU0_PE3_OCP_RXP<11>")
	)
	(arc
		(start 301.465996 -97.804986)
		(mid 301.463248 -98.200453)
		(end 301.80153 -98.405188)
		(width 0.0889)
		(layer "In11.Cu")
		(net "P3E_CPU0_PE3_OCP_RXP<11>")
	)
	(arc
		(start 301.465996 -95.232982)
		(mid 301.545127 -95.528384)
		(end 301.465996 -95.823786)
		(width 0.0889)
		(layer "In11.Cu")
		(net "P3E_CPU0_PE3_OCP_RXP<11>")
	)
	(arc
		(start 301.465996 -95.823786)
		(mid 301.412526 -96.018849)
		(end 301.46117 -96.2152)
		(width 0.0889)
		(layer "In11.Cu")
		(net "P3E_CPU0_PE3_OCP_RXP<11>")
	)
	(arc
		(start 300.117256 -93.452188)
		(mid 300.400473 -93.536469)
		(end 300.607476 -93.747336)
		(width 0.0889)
		(layer "In11.Cu")
		(net "P3E_CPU0_PE3_OCP_RXP<11>")
	)
	(arc
		(start 301.465996 -96.814386)
		(mid 301.412526 -97.009449)
		(end 301.46117 -97.2058)
		(width 0.0889)
		(layer "In11.Cu")
		(net "P3E_CPU0_PE3_OCP_RXP<11>")
	)
	(segment
		(start 297.807126 -93.052138)
		(end 298.378626 -93.052138)
		(width 0.1143)
		(layer "F.Cu")
		(net "P3E_CPU0_PE3_OCP_RXP<10>")
	)
	(segment
		(start 448.22745 -120.70207)
		(end 448.34175 -120.81637)
		(width 0.1143)
		(layer "F.Cu")
		(net "P3E_CPU0_PE3_OCP_RXP<10>")
	)
	(segment
		(start 448.320668 -119.515636)
		(end 448.22745 -119.740934)
		(width 0.1143)
		(layer "F.Cu")
		(net "P3E_CPU0_PE3_OCP_RXP<10>")
	)
	(segment
		(start 448.60083 -116.993162)
		(end 448.60083 -118.343172)
		(width 0.1143)
		(layer "F.Cu")
		(net "P3E_CPU0_PE3_OCP_RXP<10>")
	)
	(segment
		(start 448.22745 -119.740934)
		(end 448.22745 -120.70207)
		(width 0.1143)
		(layer "F.Cu")
		(net "P3E_CPU0_PE3_OCP_RXP<10>")
	)
	(segment
		(start 448.60083 -118.343172)
		(end 448.320668 -118.623334)
		(width 0.1143)
		(layer "F.Cu")
		(net "P3E_CPU0_PE3_OCP_RXP<10>")
	)
	(segment
		(start 448.320668 -118.623334)
		(end 448.320668 -119.515636)
		(width 0.1143)
		(layer "F.Cu")
		(net "P3E_CPU0_PE3_OCP_RXP<10>")
	)
	(segment
		(start 448.34175 -120.81637)
		(end 448.7418 -120.81637)
		(width 0.1143)
		(layer "F.Cu")
		(net "P3E_CPU0_PE3_OCP_RXP<10>")
	)
	(via
		(at 298.378626 -93.052138)
		(size 0.508)
		(drill 0.254)
		(layers "F.Cu" "B.Cu")
		(net "P3E_CPU0_PE3_OCP_RXP<10>")
	)
	(via
		(at 448.7418 -120.81637)
		(size 0.508)
		(drill 0.254)
		(layers "F.Cu" "B.Cu")
		(net "P3E_CPU0_PE3_OCP_RXP<10>")
	)
	(segment
		(start 448.286124 -119.857266)
		(end 448.286124 -120.58396)
		(width 0.1143)
		(layer "In11.Cu")
		(net "P3E_CPU0_PE3_OCP_RXP<10>")
	)
	(segment
		(start 306.143152 -100.00234)
		(end 306.410614 -100.270056)
		(width 0.1143)
		(layer "In11.Cu")
		(net "P3E_CPU0_PE3_OCP_RXP<10>")
	)
	(segment
		(start 376.5677 -133.815836)
		(end 377.64593 -134.031736)
		(width 0.1143)
		(layer "In11.Cu")
		(net "P3E_CPU0_PE3_OCP_RXP<10>")
	)
	(segment
		(start 330.887578 -118.997984)
		(end 334.499966 -122.610372)
		(width 0.1143)
		(layer "In11.Cu")
		(net "P3E_CPU0_PE3_OCP_RXP<10>")
	)
	(segment
		(start 304.09134 -98.987356)
		(end 305.738784 -99.6696)
		(width 0.0889)
		(layer "In11.Cu")
		(net "P3E_CPU0_PE3_OCP_RXP<10>")
	)
	(segment
		(start 375.233946 -132.932678)
		(end 375.900442 -133.37413)
		(width 0.1143)
		(layer "In11.Cu")
		(net "P3E_CPU0_PE3_OCP_RXP<10>")
	)
	(segment
		(start 321.444112 -109.00664)
		(end 325.98614 -113.548668)
		(width 0.1143)
		(layer "In11.Cu")
		(net "P3E_CPU0_PE3_OCP_RXP<10>")
	)
	(segment
		(start 350.964754 -121.538492)
		(end 351.518474 -121.538492)
		(width 0.1143)
		(layer "In11.Cu")
		(net "P3E_CPU0_PE3_OCP_RXP<10>")
	)
	(segment
		(start 356.94112 -125.198378)
		(end 359.398316 -126.440946)
		(width 0.1143)
		(layer "In11.Cu")
		(net "P3E_CPU0_PE3_OCP_RXP<10>")
	)
	(segment
		(start 334.499966 -122.610372)
		(end 339.793072 -122.610372)
		(width 0.1143)
		(layer "In11.Cu")
		(net "P3E_CPU0_PE3_OCP_RXP<10>")
	)
	(segment
		(start 375.900696 -133.37413)
		(end 376.5677 -133.815836)
		(width 0.1143)
		(layer "In11.Cu")
		(net "P3E_CPU0_PE3_OCP_RXP<10>")
	)
	(segment
		(start 377.64593 -134.031736)
		(end 381.843534 -136.809734)
		(width 0.1143)
		(layer "In11.Cu")
		(net "P3E_CPU0_PE3_OCP_RXP<10>")
	)
	(segment
		(start 302.324516 -97.709736)
		(end 302.362362 -97.775522)
		(width 0.0889)
		(layer "In11.Cu")
		(net "P3E_CPU0_PE3_OCP_RXP<10>")
	)
	(segment
		(start 359.398316 -126.440946)
		(end 361.869482 -126.440946)
		(width 0.1143)
		(layer "In11.Cu")
		(net "P3E_CPU0_PE3_OCP_RXP<10>")
	)
	(segment
		(start 351.518474 -121.538492)
		(end 352.759772 -121.779792)
		(width 0.1143)
		(layer "In11.Cu")
		(net "P3E_CPU0_PE3_OCP_RXP<10>")
	)
	(segment
		(start 427.31436 -130.382772)
		(end 430.835054 -128.002792)
		(width 0.1143)
		(layer "In11.Cu")
		(net "P3E_CPU0_PE3_OCP_RXP<10>")
	)
	(segment
		(start 305.738784 -99.6696)
		(end 306.055522 -99.986338)
		(width 0.0889)
		(layer "In11.Cu")
		(net "P3E_CPU0_PE3_OCP_RXP<10>")
	)
	(segment
		(start 447.100706 -119.3673)
		(end 447.796158 -119.3673)
		(width 0.1143)
		(layer "In11.Cu")
		(net "P3E_CPU0_PE3_OCP_RXP<10>")
	)
	(segment
		(start 300.9392 -92.956634)
		(end 300.971966 -92.956634)
		(width 0.0889)
		(layer "In11.Cu")
		(net "P3E_CPU0_PE3_OCP_RXP<10>")
	)
	(segment
		(start 448.518534 -120.81637)
		(end 448.7418 -120.81637)
		(width 0.1143)
		(layer "In11.Cu")
		(net "P3E_CPU0_PE3_OCP_RXP<10>")
	)
	(segment
		(start 361.869482 -126.440946)
		(end 367.485676 -128.76911)
		(width 0.1143)
		(layer "In11.Cu")
		(net "P3E_CPU0_PE3_OCP_RXP<10>")
	)
	(segment
		(start 301.80153 -93.452188)
		(end 301.834296 -93.452188)
		(width 0.0889)
		(layer "In11.Cu")
		(net "P3E_CPU0_PE3_OCP_RXP<10>")
	)
	(segment
		(start 420.842186 -134.947914)
		(end 420.842186 -134.948168)
		(width 0.1143)
		(layer "In11.Cu")
		(net "P3E_CPU0_PE3_OCP_RXP<10>")
	)
	(segment
		(start 387.893052 -138.04011)
		(end 390.70661 -138.04011)
		(width 0.1143)
		(layer "In11.Cu")
		(net "P3E_CPU0_PE3_OCP_RXP<10>")
	)
	(segment
		(start 302.362362 -97.775522)
		(end 302.533558 -97.946718)
		(width 0.0889)
		(layer "In11.Cu")
		(net "P3E_CPU0_PE3_OCP_RXP<10>")
	)
	(segment
		(start 420.299134 -135.91159)
		(end 420.842186 -134.947914)
		(width 0.1143)
		(layer "In11.Cu")
		(net "P3E_CPU0_PE3_OCP_RXP<10>")
	)
	(segment
		(start 356.200202 -124.099574)
		(end 356.94112 -125.198378)
		(width 0.1143)
		(layer "In11.Cu")
		(net "P3E_CPU0_PE3_OCP_RXP<10>")
	)
	(segment
		(start 349.087186 -121.90349)
		(end 350.964754 -121.538492)
		(width 0.1143)
		(layer "In11.Cu")
		(net "P3E_CPU0_PE3_OCP_RXP<10>")
	)
	(segment
		(start 422.472104 -132.056378)
		(end 423.800016 -131.205224)
		(width 0.1143)
		(layer "In11.Cu")
		(net "P3E_CPU0_PE3_OCP_RXP<10>")
	)
	(segment
		(start 302.533558 -97.946718)
		(end 304.09134 -98.987356)
		(width 0.0889)
		(layer "In11.Cu")
		(net "P3E_CPU0_PE3_OCP_RXP<10>")
	)
	(segment
		(start 347.209618 -121.538492)
		(end 349.087186 -121.90349)
		(width 0.1143)
		(layer "In11.Cu")
		(net "P3E_CPU0_PE3_OCP_RXP<10>")
	)
	(segment
		(start 415.186622 -137.498836)
		(end 416.612832 -137.175748)
		(width 0.1143)
		(layer "In11.Cu")
		(net "P3E_CPU0_PE3_OCP_RXP<10>")
	)
	(segment
		(start 325.98614 -115.689126)
		(end 329.294998 -118.997984)
		(width 0.1143)
		(layer "In11.Cu")
		(net "P3E_CPU0_PE3_OCP_RXP<10>")
	)
	(segment
		(start 420.842186 -134.948168)
		(end 422.472104 -132.056378)
		(width 0.1143)
		(layer "In11.Cu")
		(net "P3E_CPU0_PE3_OCP_RXP<10>")
	)
	(segment
		(start 306.142898 -100.001578)
		(end 306.142898 -100.002086)
		(width 0.0889)
		(layer "In11.Cu")
		(net "P3E_CPU0_PE3_OCP_RXP<10>")
	)
	(segment
		(start 306.142898 -100.002086)
		(end 306.143152 -100.00234)
		(width 0.0889)
		(layer "In11.Cu")
		(net "P3E_CPU0_PE3_OCP_RXP<10>")
	)
	(segment
		(start 300.074076 -92.461588)
		(end 300.117256 -92.461588)
		(width 0.0889)
		(layer "In11.Cu")
		(net "P3E_CPU0_PE3_OCP_RXP<10>")
	)
	(segment
		(start 345.111832 -121.538492)
		(end 347.209618 -121.538492)
		(width 0.1143)
		(layer "In11.Cu")
		(net "P3E_CPU0_PE3_OCP_RXP<10>")
	)
	(segment
		(start 447.796158 -119.3673)
		(end 448.286124 -119.857266)
		(width 0.1143)
		(layer "In11.Cu")
		(net "P3E_CPU0_PE3_OCP_RXP<10>")
	)
	(segment
		(start 325.98614 -113.548668)
		(end 325.98614 -115.689126)
		(width 0.1143)
		(layer "In11.Cu")
		(net "P3E_CPU0_PE3_OCP_RXP<10>")
	)
	(segment
		(start 430.835054 -128.002792)
		(end 432.15306 -124.375926)
		(width 0.1143)
		(layer "In11.Cu")
		(net "P3E_CPU0_PE3_OCP_RXP<10>")
	)
	(segment
		(start 405.26716 -138.075162)
		(end 411.97149 -136.756902)
		(width 0.1143)
		(layer "In11.Cu")
		(net "P3E_CPU0_PE3_OCP_RXP<10>")
	)
	(segment
		(start 417.121086 -137.297668)
		(end 417.12134 -137.297668)
		(width 0.1143)
		(layer "In11.Cu")
		(net "P3E_CPU0_PE3_OCP_RXP<10>")
	)
	(segment
		(start 390.70661 -138.04011)
		(end 394.329158 -139.0269)
		(width 0.1143)
		(layer "In11.Cu")
		(net "P3E_CPU0_PE3_OCP_RXP<10>")
	)
	(segment
		(start 432.15306 -124.375926)
		(end 441.60567 -120.460516)
		(width 0.1143)
		(layer "In11.Cu")
		(net "P3E_CPU0_PE3_OCP_RXP<10>")
	)
	(segment
		(start 299.219366 -92.956634)
		(end 299.252132 -92.956634)
		(width 0.0889)
		(layer "In11.Cu")
		(net "P3E_CPU0_PE3_OCP_RXP<10>")
	)
	(segment
		(start 416.612832 -137.175748)
		(end 417.121086 -137.297668)
		(width 0.1143)
		(layer "In11.Cu")
		(net "P3E_CPU0_PE3_OCP_RXP<10>")
	)
	(segment
		(start 298.378626 -93.052138)
		(end 298.378626 -93.390212)
		(width 0.0889)
		(layer "In11.Cu")
		(net "P3E_CPU0_PE3_OCP_RXP<10>")
	)
	(segment
		(start 381.843534 -136.809734)
		(end 387.893052 -138.04011)
		(width 0.1143)
		(layer "In11.Cu")
		(net "P3E_CPU0_PE3_OCP_RXP<10>")
	)
	(segment
		(start 375.900442 -133.37413)
		(end 375.900696 -133.37413)
		(width 0.1143)
		(layer "In11.Cu")
		(net "P3E_CPU0_PE3_OCP_RXP<10>")
	)
	(segment
		(start 298.378626 -93.390212)
		(end 298.436538 -93.448124)
		(width 0.0889)
		(layer "In11.Cu")
		(net "P3E_CPU0_PE3_OCP_RXP<10>")
	)
	(segment
		(start 371.772942 -131.518914)
		(end 373.32031 -132.54355)
		(width 0.1143)
		(layer "In11.Cu")
		(net "P3E_CPU0_PE3_OCP_RXP<10>")
	)
	(segment
		(start 352.759772 -121.779792)
		(end 356.200202 -124.099574)
		(width 0.1143)
		(layer "In11.Cu")
		(net "P3E_CPU0_PE3_OCP_RXP<10>")
	)
	(segment
		(start 306.410614 -100.270056)
		(end 311.728866 -102.664006)
		(width 0.1143)
		(layer "In11.Cu")
		(net "P3E_CPU0_PE3_OCP_RXP<10>")
	)
	(segment
		(start 394.329158 -139.0269)
		(end 399.538952 -138.075162)
		(width 0.1143)
		(layer "In11.Cu")
		(net "P3E_CPU0_PE3_OCP_RXP<10>")
	)
	(segment
		(start 370.23548 -131.518914)
		(end 371.772942 -131.518914)
		(width 0.1143)
		(layer "In11.Cu")
		(net "P3E_CPU0_PE3_OCP_RXP<10>")
	)
	(segment
		(start 367.485676 -128.76911)
		(end 370.23548 -131.518914)
		(width 0.1143)
		(layer "In11.Cu")
		(net "P3E_CPU0_PE3_OCP_RXP<10>")
	)
	(segment
		(start 399.538952 -138.075162)
		(end 405.26716 -138.075162)
		(width 0.1143)
		(layer "In11.Cu")
		(net "P3E_CPU0_PE3_OCP_RXP<10>")
	)
	(segment
		(start 306.127658 -99.986338)
		(end 306.142898 -100.001578)
		(width 0.0889)
		(layer "In11.Cu")
		(net "P3E_CPU0_PE3_OCP_RXP<10>")
	)
	(segment
		(start 339.793072 -122.610372)
		(end 341.826596 -123.02998)
		(width 0.1143)
		(layer "In11.Cu")
		(net "P3E_CPU0_PE3_OCP_RXP<10>")
	)
	(segment
		(start 302.324516 -96.319086)
		(end 302.31969 -96.327722)
		(width 0.0889)
		(layer "In11.Cu")
		(net "P3E_CPU0_PE3_OCP_RXP<10>")
	)
	(segment
		(start 318.071246 -109.00664)
		(end 321.444112 -109.00664)
		(width 0.1143)
		(layer "In11.Cu")
		(net "P3E_CPU0_PE3_OCP_RXP<10>")
	)
	(segment
		(start 302.324516 -94.737936)
		(end 302.330866 -94.748604)
		(width 0.0889)
		(layer "In11.Cu")
		(net "P3E_CPU0_PE3_OCP_RXP<10>")
	)
	(segment
		(start 302.324516 -95.328486)
		(end 302.31969 -95.337122)
		(width 0.0889)
		(layer "In11.Cu")
		(net "P3E_CPU0_PE3_OCP_RXP<10>")
	)
	(segment
		(start 441.60567 -120.460516)
		(end 447.100706 -119.3673)
		(width 0.1143)
		(layer "In11.Cu")
		(net "P3E_CPU0_PE3_OCP_RXP<10>")
	)
	(segment
		(start 344.053414 -122.597164)
		(end 345.111832 -121.538492)
		(width 0.1143)
		(layer "In11.Cu")
		(net "P3E_CPU0_PE3_OCP_RXP<10>")
	)
	(segment
		(start 306.055522 -99.986338)
		(end 306.127658 -99.986338)
		(width 0.0889)
		(layer "In11.Cu")
		(net "P3E_CPU0_PE3_OCP_RXP<10>")
	)
	(segment
		(start 311.728866 -102.664006)
		(end 318.071246 -109.00664)
		(width 0.1143)
		(layer "In11.Cu")
		(net "P3E_CPU0_PE3_OCP_RXP<10>")
	)
	(segment
		(start 373.32031 -132.54355)
		(end 375.233946 -132.932678)
		(width 0.1143)
		(layer "In11.Cu")
		(net "P3E_CPU0_PE3_OCP_RXP<10>")
	)
	(segment
		(start 411.97149 -136.756902)
		(end 415.186622 -137.498836)
		(width 0.1143)
		(layer "In11.Cu")
		(net "P3E_CPU0_PE3_OCP_RXP<10>")
	)
	(segment
		(start 417.12134 -137.297668)
		(end 420.299134 -135.91159)
		(width 0.1143)
		(layer "In11.Cu")
		(net "P3E_CPU0_PE3_OCP_RXP<10>")
	)
	(segment
		(start 448.286124 -120.58396)
		(end 448.518534 -120.81637)
		(width 0.1143)
		(layer "In11.Cu")
		(net "P3E_CPU0_PE3_OCP_RXP<10>")
	)
	(segment
		(start 302.330866 -96.308418)
		(end 302.324516 -96.319086)
		(width 0.0889)
		(layer "In11.Cu")
		(net "P3E_CPU0_PE3_OCP_RXP<10>")
	)
	(segment
		(start 329.294998 -118.997984)
		(end 330.887578 -118.997984)
		(width 0.1143)
		(layer "In11.Cu")
		(net "P3E_CPU0_PE3_OCP_RXP<10>")
	)
	(segment
		(start 423.800016 -131.205224)
		(end 427.31436 -130.382772)
		(width 0.1143)
		(layer "In11.Cu")
		(net "P3E_CPU0_PE3_OCP_RXP<10>")
	)
	(segment
		(start 302.330866 -97.299018)
		(end 302.324516 -97.309686)
		(width 0.0889)
		(layer "In11.Cu")
		(net "P3E_CPU0_PE3_OCP_RXP<10>")
	)
	(segment
		(start 302.324516 -97.309686)
		(end 302.31969 -97.318322)
		(width 0.0889)
		(layer "In11.Cu")
		(net "P3E_CPU0_PE3_OCP_RXP<10>")
	)
	(segment
		(start 341.826596 -123.02998)
		(end 344.053414 -122.597164)
		(width 0.1143)
		(layer "In11.Cu")
		(net "P3E_CPU0_PE3_OCP_RXP<10>")
	)
	(arc
		(start 302.324516 -95.728536)
		(mid 302.403738 -96.017654)
		(end 302.330866 -96.308418)
		(width 0.0889)
		(layer "In11.Cu")
		(net "P3E_CPU0_PE3_OCP_RXP<10>")
	)
	(arc
		(start 302.31969 -95.337122)
		(mid 302.270935 -95.533474)
		(end 302.324516 -95.728536)
		(width 0.0889)
		(layer "In11.Cu")
		(net "P3E_CPU0_PE3_OCP_RXP<10>")
	)
	(arc
		(start 300.607476 -92.756736)
		(mid 300.747555 -92.899472)
		(end 300.9392 -92.956634)
		(width 0.0889)
		(layer "In11.Cu")
		(net "P3E_CPU0_PE3_OCP_RXP<10>")
	)
	(arc
		(start 302.31969 -96.327722)
		(mid 302.270935 -96.524074)
		(end 302.324516 -96.719136)
		(width 0.0889)
		(layer "In11.Cu")
		(net "P3E_CPU0_PE3_OCP_RXP<10>")
	)
	(arc
		(start 300.117256 -92.461588)
		(mid 300.400473 -92.545869)
		(end 300.607476 -92.756736)
		(width 0.0889)
		(layer "In11.Cu")
		(net "P3E_CPU0_PE3_OCP_RXP<10>")
	)
	(arc
		(start 299.252132 -92.956634)
		(mid 299.443774 -92.899468)
		(end 299.583856 -92.756736)
		(width 0.0889)
		(layer "In11.Cu")
		(net "P3E_CPU0_PE3_OCP_RXP<10>")
	)
	(arc
		(start 302.324516 -94.33814)
		(mid 302.271017 -94.538038)
		(end 302.324516 -94.737936)
		(width 0.0889)
		(layer "In11.Cu")
		(net "P3E_CPU0_PE3_OCP_RXP<10>")
	)
	(arc
		(start 302.330866 -94.748604)
		(mid 302.403664 -95.039367)
		(end 302.324516 -95.328486)
		(width 0.0889)
		(layer "In11.Cu")
		(net "P3E_CPU0_PE3_OCP_RXP<10>")
	)
	(arc
		(start 301.834296 -93.452188)
		(mid 302.329773 -93.756631)
		(end 302.324516 -94.33814)
		(width 0.0889)
		(layer "In11.Cu")
		(net "P3E_CPU0_PE3_OCP_RXP<10>")
	)
	(arc
		(start 298.436538 -93.448124)
		(mid 298.603439 -93.383224)
		(end 298.725336 -93.252036)
		(width 0.0889)
		(layer "In11.Cu")
		(net "P3E_CPU0_PE3_OCP_RXP<10>")
	)
	(arc
		(start 302.31969 -97.318322)
		(mid 302.270935 -97.514674)
		(end 302.324516 -97.709736)
		(width 0.0889)
		(layer "In11.Cu")
		(net "P3E_CPU0_PE3_OCP_RXP<10>")
	)
	(arc
		(start 298.725336 -93.252036)
		(mid 298.933944 -93.040104)
		(end 299.219366 -92.956634)
		(width 0.0889)
		(layer "In11.Cu")
		(net "P3E_CPU0_PE3_OCP_RXP<10>")
	)
	(arc
		(start 299.583856 -92.756736)
		(mid 299.79086 -92.545872)
		(end 300.074076 -92.461588)
		(width 0.0889)
		(layer "In11.Cu")
		(net "P3E_CPU0_PE3_OCP_RXP<10>")
	)
	(arc
		(start 300.971966 -92.956634)
		(mid 301.25739 -93.040101)
		(end 301.465996 -93.252036)
		(width 0.0889)
		(layer "In11.Cu")
		(net "P3E_CPU0_PE3_OCP_RXP<10>")
	)
	(arc
		(start 302.324516 -96.719136)
		(mid 302.403738 -97.008254)
		(end 302.330866 -97.299018)
		(width 0.0889)
		(layer "In11.Cu")
		(net "P3E_CPU0_PE3_OCP_RXP<10>")
	)
	(arc
		(start 301.465996 -93.252036)
		(mid 301.607679 -93.39584)
		(end 301.80153 -93.452188)
		(width 0.0889)
		(layer "In11.Cu")
		(net "P3E_CPU0_PE3_OCP_RXP<10>")
	)
	(segment
		(start 293.51478 -100.481638)
		(end 294.08628 -100.481638)
		(width 0.1143)
		(layer "F.Cu")
		(net "P3E_CPU0_PE3_OCP_RXP<0>")
	)
	(segment
		(start 461.340962 -47.481998)
		(end 461.340962 -46.227492)
		(width 0.1143)
		(layer "F.Cu")
		(net "P3E_CPU0_PE3_OCP_RXP<0>")
	)
	(segment
		(start 461.440022 -44.83735)
		(end 461.107028 -44.83735)
		(width 0.1143)
		(layer "F.Cu")
		(net "P3E_CPU0_PE3_OCP_RXP<0>")
	)
	(segment
		(start 461.6069 -45.961554)
		(end 461.6069 -45.004228)
		(width 0.1143)
		(layer "F.Cu")
		(net "P3E_CPU0_PE3_OCP_RXP<0>")
	)
	(segment
		(start 461.340962 -46.227492)
		(end 461.6069 -45.961554)
		(width 0.1143)
		(layer "F.Cu")
		(net "P3E_CPU0_PE3_OCP_RXP<0>")
	)
	(segment
		(start 461.6069 -45.004228)
		(end 461.440022 -44.83735)
		(width 0.1143)
		(layer "F.Cu")
		(net "P3E_CPU0_PE3_OCP_RXP<0>")
	)
	(via
		(at 461.107028 -44.83735)
		(size 0.508)
		(drill 0.254)
		(layers "F.Cu" "B.Cu")
		(net "P3E_CPU0_PE3_OCP_RXP<0>")
	)
	(via
		(at 294.08628 -100.481638)
		(size 0.508)
		(drill 0.254)
		(layers "F.Cu" "B.Cu")
		(net "P3E_CPU0_PE3_OCP_RXP<0>")
	)
	(segment
		(start 304.614834 -96.919034)
		(end 304.37455 -96.919034)
		(width 0.0889)
		(layer "In4.Cu")
		(net "P3E_CPU0_PE3_OCP_RXP<0>")
	)
	(segment
		(start 375.40565 -49.444148)
		(end 375.034556 -49.815242)
		(width 0.1143)
		(layer "In4.Cu")
		(net "P3E_CPU0_PE3_OCP_RXP<0>")
	)
	(segment
		(start 346.013532 -60.928758)
		(end 344.389456 -61.244734)
		(width 0.1143)
		(layer "In4.Cu")
		(net "P3E_CPU0_PE3_OCP_RXP<0>")
	)
	(segment
		(start 463.352642 -51.7525)
		(end 463.009742 -51.7525)
		(width 0.1143)
		(layer "In4.Cu")
		(net "P3E_CPU0_PE3_OCP_RXP<0>")
	)
	(segment
		(start 409.092654 -55.7022)
		(end 408.39644 -55.005986)
		(width 0.1143)
		(layer "In4.Cu")
		(net "P3E_CPU0_PE3_OCP_RXP<0>")
	)
	(segment
		(start 461.828642 -51.9176)
		(end 461.485742 -51.9176)
		(width 0.1143)
		(layer "In4.Cu")
		(net "P3E_CPU0_PE3_OCP_RXP<0>")
	)
	(segment
		(start 361.485942 -54.155594)
		(end 359.825544 -55.259732)
		(width 0.1143)
		(layer "In4.Cu")
		(net "P3E_CPU0_PE3_OCP_RXP<0>")
	)
	(segment
		(start 299.583856 -99.290886)
		(end 299.588682 -99.299522)
		(width 0.0889)
		(layer "In4.Cu")
		(net "P3E_CPU0_PE3_OCP_RXP<0>")
	)
	(segment
		(start 403.274022 -52.63388)
		(end 402.707348 -53.200554)
		(width 0.1143)
		(layer "In4.Cu")
		(net "P3E_CPU0_PE3_OCP_RXP<0>")
	)
	(segment
		(start 305.986434 -96.702372)
		(end 305.618896 -96.94799)
		(width 0.0889)
		(layer "In4.Cu")
		(net "P3E_CPU0_PE3_OCP_RXP<0>")
	)
	(segment
		(start 354.908104 -61.087762)
		(end 354.215192 -60.949332)
		(width 0.1143)
		(layer "In4.Cu")
		(net "P3E_CPU0_PE3_OCP_RXP<0>")
	)
	(segment
		(start 465.5058 -51.288442)
		(end 464.876642 -51.9176)
		(width 0.1143)
		(layer "In4.Cu")
		(net "P3E_CPU0_PE3_OCP_RXP<0>")
	)
	(segment
		(start 381.298958 -49.9491)
		(end 380.794006 -49.444148)
		(width 0.1143)
		(layer "In4.Cu")
		(net "P3E_CPU0_PE3_OCP_RXP<0>")
	)
	(segment
		(start 349.954596 -61.237114)
		(end 348.68739 -60.94095)
		(width 0.1143)
		(layer "In4.Cu")
		(net "P3E_CPU0_PE3_OCP_RXP<0>")
	)
	(segment
		(start 420.477442 -54.404006)
		(end 419.458394 -54.404006)
		(width 0.1143)
		(layer "In4.Cu")
		(net "P3E_CPU0_PE3_OCP_RXP<0>")
	)
	(segment
		(start 461.481678 -44.83735)
		(end 461.595978 -44.95165)
		(width 0.1143)
		(layer "In4.Cu")
		(net "P3E_CPU0_PE3_OCP_RXP<0>")
	)
	(segment
		(start 421.353234 -54.826154)
		(end 421.352726 -54.826154)
		(width 0.1143)
		(layer "In4.Cu")
		(net "P3E_CPU0_PE3_OCP_RXP<0>")
	)
	(segment
		(start 344.389456 -61.244734)
		(end 343.115646 -60.946792)
		(width 0.1143)
		(layer "In4.Cu")
		(net "P3E_CPU0_PE3_OCP_RXP<0>")
	)
	(segment
		(start 355.209856 -61.027564)
		(end 354.908104 -61.087762)
		(width 0.1143)
		(layer "In4.Cu")
		(net "P3E_CPU0_PE3_OCP_RXP<0>")
	)
	(segment
		(start 464.533742 -51.9176)
		(end 464.368642 -51.7525)
		(width 0.1143)
		(layer "In4.Cu")
		(net "P3E_CPU0_PE3_OCP_RXP<0>")
	)
	(segment
		(start 306.204112 -96.50476)
		(end 306.150518 -96.634554)
		(width 0.0889)
		(layer "In4.Cu")
		(net "P3E_CPU0_PE3_OCP_RXP<0>")
	)
	(segment
		(start 300.969172 -97.909634)
		(end 300.936406 -97.909634)
		(width 0.0889)
		(layer "In4.Cu")
		(net "P3E_CPU0_PE3_OCP_RXP<0>")
	)
	(segment
		(start 461.107028 -44.83735)
		(end 461.481678 -44.83735)
		(width 0.1143)
		(layer "In4.Cu")
		(net "P3E_CPU0_PE3_OCP_RXP<0>")
	)
	(segment
		(start 460.977742 -51.7525)
		(end 460.812642 -51.9176)
		(width 0.1143)
		(layer "In4.Cu")
		(net "P3E_CPU0_PE3_OCP_RXP<0>")
	)
	(segment
		(start 310.334406 -93.619828)
		(end 310.334406 -93.620082)
		(width 0.1143)
		(layer "In4.Cu")
		(net "P3E_CPU0_PE3_OCP_RXP<0>")
	)
	(segment
		(start 306.150518 -96.6343)
		(end 305.986434 -96.702372)
		(width 0.0889)
		(layer "In4.Cu")
		(net "P3E_CPU0_PE3_OCP_RXP<0>")
	)
	(segment
		(start 460.812642 -51.9176)
		(end 436.910226 -51.9176)
		(width 0.1143)
		(layer "In4.Cu")
		(net "P3E_CPU0_PE3_OCP_RXP<0>")
	)
	(segment
		(start 337.731354 -61.994034)
		(end 334.471772 -61.237114)
		(width 0.1143)
		(layer "In4.Cu")
		(net "P3E_CPU0_PE3_OCP_RXP<0>")
	)
	(segment
		(start 299.252132 -99.890834)
		(end 299.224192 -99.890834)
		(width 0.0889)
		(layer "In4.Cu")
		(net "P3E_CPU0_PE3_OCP_RXP<0>")
	)
	(segment
		(start 294.10787 -100.881434)
		(end 294.068246 -100.881434)
		(width 0.0889)
		(layer "In4.Cu")
		(net "P3E_CPU0_PE3_OCP_RXP<0>")
	)
	(segment
		(start 462.501742 -51.9176)
		(end 462.336642 -51.7525)
		(width 0.1143)
		(layer "In4.Cu")
		(net "P3E_CPU0_PE3_OCP_RXP<0>")
	)
	(segment
		(start 295.460166 -101.677724)
		(end 295.456864 -101.671882)
		(width 0.0889)
		(layer "In4.Cu")
		(net "P3E_CPU0_PE3_OCP_RXP<0>")
	)
	(segment
		(start 370.689632 -51.6128)
		(end 369.182142 -51.6128)
		(width 0.1143)
		(layer "In4.Cu")
		(net "P3E_CPU0_PE3_OCP_RXP<0>")
	)
	(segment
		(start 306.498244 -96.490282)
		(end 306.368704 -96.436688)
		(width 0.0889)
		(layer "In4.Cu")
		(net "P3E_CPU0_PE3_OCP_RXP<0>")
	)
	(segment
		(start 372.48719 -49.815242)
		(end 370.689632 -51.6128)
		(width 0.1143)
		(layer "In4.Cu")
		(net "P3E_CPU0_PE3_OCP_RXP<0>")
	)
	(segment
		(start 299.577506 -99.280218)
		(end 299.583856 -99.290886)
		(width 0.0889)
		(layer "In4.Cu")
		(net "P3E_CPU0_PE3_OCP_RXP<0>")
	)
	(segment
		(start 411.048454 -54.5338)
		(end 409.880054 -55.7022)
		(width 0.1143)
		(layer "In4.Cu")
		(net "P3E_CPU0_PE3_OCP_RXP<0>")
	)
	(segment
		(start 419.458394 -54.404006)
		(end 418.846 -55.0164)
		(width 0.1143)
		(layer "In4.Cu")
		(net "P3E_CPU0_PE3_OCP_RXP<0>")
	)
	(segment
		(start 465.5058 -48.517556)
		(end 465.5058 -51.288442)
		(width 0.1143)
		(layer "In4.Cu")
		(net "P3E_CPU0_PE3_OCP_RXP<0>")
	)
	(segment
		(start 334.471772 -61.237114)
		(end 333.032862 -61.511434)
		(width 0.1143)
		(layer "In4.Cu")
		(net "P3E_CPU0_PE3_OCP_RXP<0>")
	)
	(segment
		(start 364.2106 -53.41366)
		(end 361.485942 -54.155594)
		(width 0.1143)
		(layer "In4.Cu")
		(net "P3E_CPU0_PE3_OCP_RXP<0>")
	)
	(segment
		(start 414.32353 -54.5338)
		(end 411.048454 -54.5338)
		(width 0.1143)
		(layer "In4.Cu")
		(net "P3E_CPU0_PE3_OCP_RXP<0>")
	)
	(segment
		(start 356.598982 -60.101226)
		(end 355.209856 -61.027564)
		(width 0.1143)
		(layer "In4.Cu")
		(net "P3E_CPU0_PE3_OCP_RXP<0>")
	)
	(segment
		(start 297.531282 -100.881434)
		(end 297.498516 -100.881434)
		(width 0.0889)
		(layer "In4.Cu")
		(net "P3E_CPU0_PE3_OCP_RXP<0>")
	)
	(segment
		(start 461.595978 -45.645324)
		(end 463.272124 -47.32147)
		(width 0.1143)
		(layer "In4.Cu")
		(net "P3E_CPU0_PE3_OCP_RXP<0>")
	)
	(segment
		(start 293.793164 -100.650548)
		(end 294.08628 -100.481638)
		(width 0.0889)
		(layer "In4.Cu")
		(net "P3E_CPU0_PE3_OCP_RXP<0>")
	)
	(segment
		(start 294.9448 -101.376734)
		(end 294.933624 -101.376734)
		(width 0.0889)
		(layer "In4.Cu")
		(net "P3E_CPU0_PE3_OCP_RXP<0>")
	)
	(segment
		(start 375.034556 -49.815242)
		(end 372.48719 -49.815242)
		(width 0.1143)
		(layer "In4.Cu")
		(net "P3E_CPU0_PE3_OCP_RXP<0>")
	)
	(segment
		(start 307.282088 -96.295718)
		(end 306.968398 -96.295718)
		(width 0.0889)
		(layer "In4.Cu")
		(net "P3E_CPU0_PE3_OCP_RXP<0>")
	)
	(segment
		(start 387.688836 -51.684428)
		(end 385.953508 -49.9491)
		(width 0.1143)
		(layer "In4.Cu")
		(net "P3E_CPU0_PE3_OCP_RXP<0>")
	)
	(segment
		(start 367.391442 -53.4035)
		(end 364.22076 -53.4035)
		(width 0.1143)
		(layer "In4.Cu")
		(net "P3E_CPU0_PE3_OCP_RXP<0>")
	)
	(segment
		(start 409.880054 -55.7022)
		(end 409.092654 -55.7022)
		(width 0.1143)
		(layer "In4.Cu")
		(net "P3E_CPU0_PE3_OCP_RXP<0>")
	)
	(segment
		(start 294.96258 -101.37648)
		(end 294.9448 -101.376734)
		(width 0.0889)
		(layer "In4.Cu")
		(net "P3E_CPU0_PE3_OCP_RXP<0>")
	)
	(segment
		(start 319.695322 -84.25942)
		(end 310.334406 -93.619828)
		(width 0.1143)
		(layer "In4.Cu")
		(net "P3E_CPU0_PE3_OCP_RXP<0>")
	)
	(segment
		(start 351.491042 -60.93714)
		(end 349.954596 -61.237114)
		(width 0.1143)
		(layer "In4.Cu")
		(net "P3E_CPU0_PE3_OCP_RXP<0>")
	)
	(segment
		(start 405.047958 -52.63388)
		(end 403.274022 -52.63388)
		(width 0.1143)
		(layer "In4.Cu")
		(net "P3E_CPU0_PE3_OCP_RXP<0>")
	)
	(segment
		(start 463.009742 -51.7525)
		(end 462.844642 -51.9176)
		(width 0.1143)
		(layer "In4.Cu")
		(net "P3E_CPU0_PE3_OCP_RXP<0>")
	)
	(segment
		(start 463.272124 -47.32147)
		(end 464.309714 -47.32147)
		(width 0.1143)
		(layer "In4.Cu")
		(net "P3E_CPU0_PE3_OCP_RXP<0>")
	)
	(segment
		(start 330.993496 -62.83198)
		(end 324.904862 -71.68388)
		(width 0.1143)
		(layer "In4.Cu")
		(net "P3E_CPU0_PE3_OCP_RXP<0>")
	)
	(segment
		(start 390.880092 -51.684428)
		(end 387.688836 -51.684428)
		(width 0.1143)
		(layer "In4.Cu")
		(net "P3E_CPU0_PE3_OCP_RXP<0>")
	)
	(segment
		(start 306.968398 -96.295718)
		(end 306.498244 -96.490282)
		(width 0.0889)
		(layer "In4.Cu")
		(net "P3E_CPU0_PE3_OCP_RXP<0>")
	)
	(segment
		(start 296.66184 -101.376734)
		(end 296.648886 -101.376734)
		(width 0.0889)
		(layer "In4.Cu")
		(net "P3E_CPU0_PE3_OCP_RXP<0>")
	)
	(segment
		(start 300.106842 -98.405188)
		(end 300.074076 -98.405188)
		(width 0.0889)
		(layer "In4.Cu")
		(net "P3E_CPU0_PE3_OCP_RXP<0>")
	)
	(segment
		(start 298.39666 -100.386134)
		(end 298.357036 -100.386134)
		(width 0.0889)
		(layer "In4.Cu")
		(net "P3E_CPU0_PE3_OCP_RXP<0>")
	)
	(segment
		(start 310.334406 -93.620082)
		(end 307.70957 -96.244918)
		(width 0.1143)
		(layer "In4.Cu")
		(net "P3E_CPU0_PE3_OCP_RXP<0>")
	)
	(segment
		(start 461.485742 -51.9176)
		(end 461.320642 -51.7525)
		(width 0.1143)
		(layer "In4.Cu")
		(net "P3E_CPU0_PE3_OCP_RXP<0>")
	)
	(segment
		(start 421.352726 -54.826154)
		(end 421.351964 -54.826916)
		(width 0.1143)
		(layer "In4.Cu")
		(net "P3E_CPU0_PE3_OCP_RXP<0>")
	)
	(segment
		(start 461.595978 -44.95165)
		(end 461.595978 -45.645324)
		(width 0.1143)
		(layer "In4.Cu")
		(net "P3E_CPU0_PE3_OCP_RXP<0>")
	)
	(segment
		(start 352.777552 -61.237114)
		(end 351.491042 -60.93714)
		(width 0.1143)
		(layer "In4.Cu")
		(net "P3E_CPU0_PE3_OCP_RXP<0>")
	)
	(segment
		(start 414.80613 -55.0164)
		(end 414.32353 -54.5338)
		(width 0.1143)
		(layer "In4.Cu")
		(net "P3E_CPU0_PE3_OCP_RXP<0>")
	)
	(segment
		(start 408.39644 -55.005986)
		(end 407.420064 -55.005986)
		(width 0.1143)
		(layer "In4.Cu")
		(net "P3E_CPU0_PE3_OCP_RXP<0>")
	)
	(segment
		(start 307.70957 -96.244918)
		(end 307.354986 -96.244918)
		(width 0.1143)
		(layer "In4.Cu")
		(net "P3E_CPU0_PE3_OCP_RXP<0>")
	)
	(segment
		(start 359.825544 -55.259732)
		(end 356.598982 -60.101226)
		(width 0.1143)
		(layer "In4.Cu")
		(net "P3E_CPU0_PE3_OCP_RXP<0>")
	)
	(segment
		(start 385.953508 -49.9491)
		(end 381.298958 -49.9491)
		(width 0.1143)
		(layer "In4.Cu")
		(net "P3E_CPU0_PE3_OCP_RXP<0>")
	)
	(segment
		(start 364.22076 -53.4035)
		(end 364.2106 -53.41366)
		(width 0.1143)
		(layer "In4.Cu")
		(net "P3E_CPU0_PE3_OCP_RXP<0>")
	)
	(segment
		(start 380.794006 -49.444148)
		(end 375.40565 -49.444148)
		(width 0.1143)
		(layer "In4.Cu")
		(net "P3E_CPU0_PE3_OCP_RXP<0>")
	)
	(segment
		(start 407.420064 -55.005986)
		(end 405.047958 -52.63388)
		(width 0.1143)
		(layer "In4.Cu")
		(net "P3E_CPU0_PE3_OCP_RXP<0>")
	)
	(segment
		(start 421.353996 -54.826916)
		(end 421.353234 -54.826154)
		(width 0.1143)
		(layer "In4.Cu")
		(net "P3E_CPU0_PE3_OCP_RXP<0>")
	)
	(segment
		(start 464.368642 -51.7525)
		(end 464.025742 -51.7525)
		(width 0.1143)
		(layer "In4.Cu")
		(net "P3E_CPU0_PE3_OCP_RXP<0>")
	)
	(segment
		(start 418.846 -55.0164)
		(end 414.80613 -55.0164)
		(width 0.1143)
		(layer "In4.Cu")
		(net "P3E_CPU0_PE3_OCP_RXP<0>")
	)
	(segment
		(start 464.025742 -51.7525)
		(end 463.860642 -51.9176)
		(width 0.1143)
		(layer "In4.Cu")
		(net "P3E_CPU0_PE3_OCP_RXP<0>")
	)
	(segment
		(start 324.904862 -71.68388)
		(end 319.695322 -84.25942)
		(width 0.1143)
		(layer "In4.Cu")
		(net "P3E_CPU0_PE3_OCP_RXP<0>")
	)
	(segment
		(start 463.517742 -51.9176)
		(end 463.352642 -51.7525)
		(width 0.1143)
		(layer "In4.Cu")
		(net "P3E_CPU0_PE3_OCP_RXP<0>")
	)
	(segment
		(start 306.368704 -96.436688)
		(end 306.204112 -96.50476)
		(width 0.0889)
		(layer "In4.Cu")
		(net "P3E_CPU0_PE3_OCP_RXP<0>")
	)
	(segment
		(start 462.336642 -51.7525)
		(end 461.993742 -51.7525)
		(width 0.1143)
		(layer "In4.Cu")
		(net "P3E_CPU0_PE3_OCP_RXP<0>")
	)
	(segment
		(start 392.396218 -53.200554)
		(end 390.880092 -51.684428)
		(width 0.1143)
		(layer "In4.Cu")
		(net "P3E_CPU0_PE3_OCP_RXP<0>")
	)
	(segment
		(start 402.707348 -53.200554)
		(end 392.396218 -53.200554)
		(width 0.1143)
		(layer "In4.Cu")
		(net "P3E_CPU0_PE3_OCP_RXP<0>")
	)
	(segment
		(start 306.150518 -96.634554)
		(end 306.150518 -96.6343)
		(width 0.0889)
		(layer "In4.Cu")
		(net "P3E_CPU0_PE3_OCP_RXP<0>")
	)
	(segment
		(start 464.876642 -51.9176)
		(end 464.533742 -51.9176)
		(width 0.1143)
		(layer "In4.Cu")
		(net "P3E_CPU0_PE3_OCP_RXP<0>")
	)
	(segment
		(start 347.259402 -61.218572)
		(end 346.013532 -60.928758)
		(width 0.1143)
		(layer "In4.Cu")
		(net "P3E_CPU0_PE3_OCP_RXP<0>")
	)
	(segment
		(start 354.215192 -60.949332)
		(end 352.777552 -61.237114)
		(width 0.1143)
		(layer "In4.Cu")
		(net "P3E_CPU0_PE3_OCP_RXP<0>")
	)
	(segment
		(start 297.008296 -101.176582)
		(end 297.004994 -101.182424)
		(width 0.0889)
		(layer "In4.Cu")
		(net "P3E_CPU0_PE3_OCP_RXP<0>")
	)
	(segment
		(start 348.68739 -60.94095)
		(end 347.259402 -61.218572)
		(width 0.1143)
		(layer "In4.Cu")
		(net "P3E_CPU0_PE3_OCP_RXP<0>")
	)
	(segment
		(start 421.351964 -54.826916)
		(end 420.900352 -54.826916)
		(width 0.1143)
		(layer "In4.Cu")
		(net "P3E_CPU0_PE3_OCP_RXP<0>")
	)
	(segment
		(start 424.701716 -53.796946)
		(end 423.671746 -54.826916)
		(width 0.1143)
		(layer "In4.Cu")
		(net "P3E_CPU0_PE3_OCP_RXP<0>")
	)
	(segment
		(start 463.860642 -51.9176)
		(end 463.517742 -51.9176)
		(width 0.1143)
		(layer "In4.Cu")
		(net "P3E_CPU0_PE3_OCP_RXP<0>")
	)
	(segment
		(start 461.993742 -51.7525)
		(end 461.828642 -51.9176)
		(width 0.1143)
		(layer "In4.Cu")
		(net "P3E_CPU0_PE3_OCP_RXP<0>")
	)
	(segment
		(start 369.182142 -51.6128)
		(end 367.391442 -53.4035)
		(width 0.1143)
		(layer "In4.Cu")
		(net "P3E_CPU0_PE3_OCP_RXP<0>")
	)
	(segment
		(start 423.671746 -54.826916)
		(end 421.353996 -54.826916)
		(width 0.1143)
		(layer "In4.Cu")
		(net "P3E_CPU0_PE3_OCP_RXP<0>")
	)
	(segment
		(start 436.620158 -52.207668)
		(end 428.276258 -52.207668)
		(width 0.1143)
		(layer "In4.Cu")
		(net "P3E_CPU0_PE3_OCP_RXP<0>")
	)
	(segment
		(start 333.032862 -61.511434)
		(end 330.993496 -62.83198)
		(width 0.1143)
		(layer "In4.Cu")
		(net "P3E_CPU0_PE3_OCP_RXP<0>")
	)
	(segment
		(start 343.115646 -60.946792)
		(end 337.731354 -61.994034)
		(width 0.1143)
		(layer "In4.Cu")
		(net "P3E_CPU0_PE3_OCP_RXP<0>")
	)
	(segment
		(start 462.844642 -51.9176)
		(end 462.501742 -51.9176)
		(width 0.1143)
		(layer "In4.Cu")
		(net "P3E_CPU0_PE3_OCP_RXP<0>")
	)
	(segment
		(start 464.309714 -47.32147)
		(end 465.5058 -48.517556)
		(width 0.1143)
		(layer "In4.Cu")
		(net "P3E_CPU0_PE3_OCP_RXP<0>")
	)
	(segment
		(start 305.618896 -96.94799)
		(end 305.045364 -97.004378)
		(width 0.0889)
		(layer "In4.Cu")
		(net "P3E_CPU0_PE3_OCP_RXP<0>")
	)
	(segment
		(start 461.320642 -51.7525)
		(end 460.977742 -51.7525)
		(width 0.1143)
		(layer "In4.Cu")
		(net "P3E_CPU0_PE3_OCP_RXP<0>")
	)
	(segment
		(start 420.900352 -54.826916)
		(end 420.477442 -54.404006)
		(width 0.1143)
		(layer "In4.Cu")
		(net "P3E_CPU0_PE3_OCP_RXP<0>")
	)
	(segment
		(start 428.276258 -52.207668)
		(end 426.68698 -53.796946)
		(width 0.1143)
		(layer "In4.Cu")
		(net "P3E_CPU0_PE3_OCP_RXP<0>")
	)
	(segment
		(start 293.772082 -100.729288)
		(end 293.793164 -100.650548)
		(width 0.0889)
		(layer "In4.Cu")
		(net "P3E_CPU0_PE3_OCP_RXP<0>")
	)
	(segment
		(start 307.332888 -96.244918)
		(end 307.282088 -96.295718)
		(width 0.0889)
		(layer "In4.Cu")
		(net "P3E_CPU0_PE3_OCP_RXP<0>")
	)
	(segment
		(start 301.823882 -97.414588)
		(end 301.791116 -97.414588)
		(width 0.0889)
		(layer "In4.Cu")
		(net "P3E_CPU0_PE3_OCP_RXP<0>")
	)
	(segment
		(start 426.68698 -53.796946)
		(end 424.701716 -53.796946)
		(width 0.1143)
		(layer "In4.Cu")
		(net "P3E_CPU0_PE3_OCP_RXP<0>")
	)
	(segment
		(start 436.910226 -51.9176)
		(end 436.620158 -52.207668)
		(width 0.1143)
		(layer "In4.Cu")
		(net "P3E_CPU0_PE3_OCP_RXP<0>")
	)
	(segment
		(start 307.354986 -96.244918)
		(end 307.332888 -96.244918)
		(width 0.0889)
		(layer "In4.Cu")
		(net "P3E_CPU0_PE3_OCP_RXP<0>")
	)
	(segment
		(start 305.045364 -97.004378)
		(end 304.614834 -96.919034)
		(width 0.0889)
		(layer "In4.Cu")
		(net "P3E_CPU0_PE3_OCP_RXP<0>")
	)
	(arc
		(start 299.224192 -99.890834)
		(mid 298.936047 -99.973153)
		(end 298.725336 -100.186236)
		(width 0.0889)
		(layer "In4.Cu")
		(net "P3E_CPU0_PE3_OCP_RXP<0>")
	)
	(arc
		(start 294.59809 -101.176582)
		(mid 294.391086 -100.965718)
		(end 294.10787 -100.881434)
		(width 0.0889)
		(layer "In4.Cu")
		(net "P3E_CPU0_PE3_OCP_RXP<0>")
	)
	(arc
		(start 296.15003 -101.672136)
		(mid 295.806754 -101.872087)
		(end 295.460166 -101.677724)
		(width 0.0889)
		(layer "In4.Cu")
		(net "P3E_CPU0_PE3_OCP_RXP<0>")
	)
	(arc
		(start 300.936406 -97.909634)
		(mid 300.650982 -97.993101)
		(end 300.442376 -98.205036)
		(width 0.0889)
		(layer "In4.Cu")
		(net "P3E_CPU0_PE3_OCP_RXP<0>")
	)
	(arc
		(start 300.442376 -98.205036)
		(mid 300.300693 -98.34884)
		(end 300.106842 -98.405188)
		(width 0.0889)
		(layer "In4.Cu")
		(net "P3E_CPU0_PE3_OCP_RXP<0>")
	)
	(arc
		(start 297.004994 -101.182424)
		(mid 296.859028 -101.324823)
		(end 296.66184 -101.376734)
		(width 0.0889)
		(layer "In4.Cu")
		(net "P3E_CPU0_PE3_OCP_RXP<0>")
	)
	(arc
		(start 303.183036 -97.214436)
		(mid 302.671226 -96.918769)
		(end 302.159416 -97.214436)
		(width 0.0889)
		(layer "In4.Cu")
		(net "P3E_CPU0_PE3_OCP_RXP<0>")
	)
	(arc
		(start 293.933118 -100.851462)
		(mid 293.844782 -100.800686)
		(end 293.772082 -100.729288)
		(width 0.0889)
		(layer "In4.Cu")
		(net "P3E_CPU0_PE3_OCP_RXP<0>")
	)
	(arc
		(start 296.648886 -101.376734)
		(mid 296.360741 -101.459053)
		(end 296.15003 -101.672136)
		(width 0.0889)
		(layer "In4.Cu")
		(net "P3E_CPU0_PE3_OCP_RXP<0>")
	)
	(arc
		(start 298.357036 -100.386134)
		(mid 298.073819 -100.470415)
		(end 297.866816 -100.681282)
		(width 0.0889)
		(layer "In4.Cu")
		(net "P3E_CPU0_PE3_OCP_RXP<0>")
	)
	(arc
		(start 302.159416 -97.214436)
		(mid 302.017733 -97.35824)
		(end 301.823882 -97.414588)
		(width 0.0889)
		(layer "In4.Cu")
		(net "P3E_CPU0_PE3_OCP_RXP<0>")
	)
	(arc
		(start 295.456864 -101.671882)
		(mid 295.248137 -101.45988)
		(end 294.96258 -101.37648)
		(width 0.0889)
		(layer "In4.Cu")
		(net "P3E_CPU0_PE3_OCP_RXP<0>")
	)
	(arc
		(start 299.588682 -99.299522)
		(mid 299.584935 -99.688778)
		(end 299.252132 -99.890834)
		(width 0.0889)
		(layer "In4.Cu")
		(net "P3E_CPU0_PE3_OCP_RXP<0>")
	)
	(arc
		(start 301.300896 -97.709736)
		(mid 301.160817 -97.852472)
		(end 300.969172 -97.909634)
		(width 0.0889)
		(layer "In4.Cu")
		(net "P3E_CPU0_PE3_OCP_RXP<0>")
	)
	(arc
		(start 303.876456 -97.214436)
		(mid 303.529746 -97.414747)
		(end 303.183036 -97.214436)
		(width 0.0889)
		(layer "In4.Cu")
		(net "P3E_CPU0_PE3_OCP_RXP<0>")
	)
	(arc
		(start 297.866816 -100.681282)
		(mid 297.725133 -100.825086)
		(end 297.531282 -100.881434)
		(width 0.0889)
		(layer "In4.Cu")
		(net "P3E_CPU0_PE3_OCP_RXP<0>")
	)
	(arc
		(start 294.933624 -101.376734)
		(mid 294.739774 -101.320384)
		(end 294.59809 -101.176582)
		(width 0.0889)
		(layer "In4.Cu")
		(net "P3E_CPU0_PE3_OCP_RXP<0>")
	)
	(arc
		(start 298.725336 -100.186236)
		(mid 298.586592 -100.328269)
		(end 298.39666 -100.386134)
		(width 0.0889)
		(layer "In4.Cu")
		(net "P3E_CPU0_PE3_OCP_RXP<0>")
	)
	(arc
		(start 300.074076 -98.405188)
		(mid 299.581686 -98.704121)
		(end 299.577506 -99.280218)
		(width 0.0889)
		(layer "In4.Cu")
		(net "P3E_CPU0_PE3_OCP_RXP<0>")
	)
	(arc
		(start 297.498516 -100.881434)
		(mid 297.215299 -100.965715)
		(end 297.008296 -101.176582)
		(width 0.0889)
		(layer "In4.Cu")
		(net "P3E_CPU0_PE3_OCP_RXP<0>")
	)
	(arc
		(start 301.791116 -97.414588)
		(mid 301.507899 -97.498869)
		(end 301.300896 -97.709736)
		(width 0.0889)
		(layer "In4.Cu")
		(net "P3E_CPU0_PE3_OCP_RXP<0>")
	)
	(arc
		(start 304.37455 -96.919034)
		(mid 304.086863 -97.001555)
		(end 303.876456 -97.214436)
		(width 0.0889)
		(layer "In4.Cu")
		(net "P3E_CPU0_PE3_OCP_RXP<0>")
	)
	(arc
		(start 294.068246 -100.881434)
		(mid 293.999376 -100.872336)
		(end 293.933118 -100.851462)
		(width 0.0889)
		(layer "In4.Cu")
		(net "P3E_CPU0_PE3_OCP_RXP<0>")
	)
	(segment
		(start 444.616586 -123.91517)
		(end 444.3222 -123.91517)
		(width 0.1143)
		(layer "F.Cu")
		(net "P3E_CPU0_PE3_OCP_RXN<9>")
	)
	(segment
		(start 444.600838 -118.342918)
		(end 444.599822 -118.343934)
		(width 0.1143)
		(layer "F.Cu")
		(net "P3E_CPU0_PE3_OCP_RXN<9>")
	)
	(segment
		(start 444.85052 -118.594632)
		(end 444.85052 -123.681236)
		(width 0.1143)
		(layer "F.Cu")
		(net "P3E_CPU0_PE3_OCP_RXN<9>")
	)
	(segment
		(start 444.599822 -118.343934)
		(end 444.85052 -118.594632)
		(width 0.1143)
		(layer "F.Cu")
		(net "P3E_CPU0_PE3_OCP_RXN<9>")
	)
	(segment
		(start 297.807126 -95.033084)
		(end 298.378626 -95.033084)
		(width 0.1143)
		(layer "F.Cu")
		(net "P3E_CPU0_PE3_OCP_RXN<9>")
	)
	(segment
		(start 444.600838 -116.993162)
		(end 444.600838 -118.342918)
		(width 0.1143)
		(layer "F.Cu")
		(net "P3E_CPU0_PE3_OCP_RXN<9>")
	)
	(segment
		(start 444.85052 -123.681236)
		(end 444.616586 -123.91517)
		(width 0.1143)
		(layer "F.Cu")
		(net "P3E_CPU0_PE3_OCP_RXN<9>")
	)
	(via
		(at 298.378626 -95.033084)
		(size 0.508)
		(drill 0.254)
		(layers "F.Cu" "B.Cu")
		(net "P3E_CPU0_PE3_OCP_RXN<9>")
	)
	(via
		(at 444.3222 -123.91517)
		(size 0.508)
		(drill 0.254)
		(layers "F.Cu" "B.Cu")
		(net "P3E_CPU0_PE3_OCP_RXN<9>")
	)
	(segment
		(start 348.430088 -126.982474)
		(end 352.233992 -127.706628)
		(width 0.1143)
		(layer "In11.Cu")
		(net "P3E_CPU0_PE3_OCP_RXN<9>")
	)
	(segment
		(start 405.419814 -139.64031)
		(end 411.901386 -138.365992)
		(width 0.1143)
		(layer "In11.Cu")
		(net "P3E_CPU0_PE3_OCP_RXN<9>")
	)
	(segment
		(start 442.257434 -122.65025)
		(end 442.421772 -122.484642)
		(width 0.1143)
		(layer "In11.Cu")
		(net "P3E_CPU0_PE3_OCP_RXN<9>")
	)
	(segment
		(start 415.141664 -139.113768)
		(end 415.142172 -139.113768)
		(width 0.1143)
		(layer "In11.Cu")
		(net "P3E_CPU0_PE3_OCP_RXN<9>")
	)
	(segment
		(start 443.780672 -122.479308)
		(end 444.504572 -122.617484)
		(width 0.1143)
		(layer "In11.Cu")
		(net "P3E_CPU0_PE3_OCP_RXN<9>")
	)
	(segment
		(start 300.447202 -96.2152)
		(end 300.442376 -96.223836)
		(width 0.0889)
		(layer "In11.Cu")
		(net "P3E_CPU0_PE3_OCP_RXN<9>")
	)
	(segment
		(start 374.96623 -137.811002)
		(end 376.321066 -138.0744)
		(width 0.1143)
		(layer "In11.Cu")
		(net "P3E_CPU0_PE3_OCP_RXN<9>")
	)
	(segment
		(start 442.930534 -122.64771)
		(end 443.273434 -122.64644)
		(width 0.1143)
		(layer "In11.Cu")
		(net "P3E_CPU0_PE3_OCP_RXN<9>")
	)
	(segment
		(start 374.96623 -137.811256)
		(end 374.96623 -137.811002)
		(width 0.1143)
		(layer "In11.Cu")
		(net "P3E_CPU0_PE3_OCP_RXN<9>")
	)
	(segment
		(start 421.41013 -137.13841)
		(end 423.648378 -133.168644)
		(width 0.1143)
		(layer "In11.Cu")
		(net "P3E_CPU0_PE3_OCP_RXN<9>")
	)
	(segment
		(start 300.442376 -96.223836)
		(end 300.436026 -96.234504)
		(width 0.0889)
		(layer "In11.Cu")
		(net "P3E_CPU0_PE3_OCP_RXN<9>")
	)
	(segment
		(start 444.820548 -122.93346)
		(end 444.820548 -123.669552)
		(width 0.1143)
		(layer "In11.Cu")
		(net "P3E_CPU0_PE3_OCP_RXN<9>")
	)
	(segment
		(start 301.794926 -99.586288)
		(end 302.101504 -99.586288)
		(width 0.0889)
		(layer "In11.Cu")
		(net "P3E_CPU0_PE3_OCP_RXN<9>")
	)
	(segment
		(start 361.570778 -128.04267)
		(end 366.42675 -130.054096)
		(width 0.1143)
		(layer "In11.Cu")
		(net "P3E_CPU0_PE3_OCP_RXN<9>")
	)
	(segment
		(start 373.176292 -135.995918)
		(end 373.963184 -137.16254)
		(width 0.1143)
		(layer "In11.Cu")
		(net "P3E_CPU0_PE3_OCP_RXN<9>")
	)
	(segment
		(start 370.073174 -133.70052)
		(end 371.996462 -133.70052)
		(width 0.1143)
		(layer "In11.Cu")
		(net "P3E_CPU0_PE3_OCP_RXN<9>")
	)
	(segment
		(start 441.748672 -122.487182)
		(end 441.914534 -122.65152)
		(width 0.1143)
		(layer "In11.Cu")
		(net "P3E_CPU0_PE3_OCP_RXN<9>")
	)
	(segment
		(start 302.274478 -99.759262)
		(end 304.353722 -100.620576)
		(width 0.0889)
		(layer "In11.Cu")
		(net "P3E_CPU0_PE3_OCP_RXN<9>")
	)
	(segment
		(start 417.271962 -138.943588)
		(end 421.41013 -137.13841)
		(width 0.1143)
		(layer "In11.Cu")
		(net "P3E_CPU0_PE3_OCP_RXN<9>")
	)
	(segment
		(start 441.53328 -122.487944)
		(end 441.748672 -122.487182)
		(width 0.1143)
		(layer "In11.Cu")
		(net "P3E_CPU0_PE3_OCP_RXN<9>")
	)
	(segment
		(start 381.259334 -138.366246)
		(end 387.437376 -139.60221)
		(width 0.1143)
		(layer "In11.Cu")
		(net "P3E_CPU0_PE3_OCP_RXN<9>")
	)
	(segment
		(start 304.675286 -101.013768)
		(end 305.520598 -101.85908)
		(width 0.1143)
		(layer "In11.Cu")
		(net "P3E_CPU0_PE3_OCP_RXN<9>")
	)
	(segment
		(start 373.963184 -137.16254)
		(end 374.907556 -137.799826)
		(width 0.1143)
		(layer "In11.Cu")
		(net "P3E_CPU0_PE3_OCP_RXN<9>")
	)
	(segment
		(start 339.283802 -124.172472)
		(end 344.248232 -125.184154)
		(width 0.1143)
		(layer "In11.Cu")
		(net "P3E_CPU0_PE3_OCP_RXN<9>")
	)
	(segment
		(start 444.57493 -123.91517)
		(end 444.3222 -123.91517)
		(width 0.1143)
		(layer "In11.Cu")
		(net "P3E_CPU0_PE3_OCP_RXN<9>")
	)
	(segment
		(start 376.321066 -138.0744)
		(end 378.809504 -137.591038)
		(width 0.1143)
		(layer "In11.Cu")
		(net "P3E_CPU0_PE3_OCP_RXN<9>")
	)
	(segment
		(start 359.08488 -128.04267)
		(end 361.570778 -128.04267)
		(width 0.1143)
		(layer "In11.Cu")
		(net "P3E_CPU0_PE3_OCP_RXN<9>")
	)
	(segment
		(start 444.820548 -123.669552)
		(end 444.57493 -123.91517)
		(width 0.1143)
		(layer "In11.Cu")
		(net "P3E_CPU0_PE3_OCP_RXN<9>")
	)
	(segment
		(start 442.421772 -122.484642)
		(end 442.764672 -122.483118)
		(width 0.1143)
		(layer "In11.Cu")
		(net "P3E_CPU0_PE3_OCP_RXN<9>")
	)
	(segment
		(start 394.261086 -140.62837)
		(end 399.665698 -139.64031)
		(width 0.1143)
		(layer "In11.Cu")
		(net "P3E_CPU0_PE3_OCP_RXN<9>")
	)
	(segment
		(start 300.442376 -97.214436)
		(end 300.436026 -97.225104)
		(width 0.0889)
		(layer "In11.Cu")
		(net "P3E_CPU0_PE3_OCP_RXN<9>")
	)
	(segment
		(start 387.437376 -139.60221)
		(end 390.497314 -139.60221)
		(width 0.1143)
		(layer "In11.Cu")
		(net "P3E_CPU0_PE3_OCP_RXN<9>")
	)
	(segment
		(start 440.460638 -122.70232)
		(end 441.53328 -122.487944)
		(width 0.1143)
		(layer "In11.Cu")
		(net "P3E_CPU0_PE3_OCP_RXN<9>")
	)
	(segment
		(start 442.764672 -122.483118)
		(end 442.930534 -122.64771)
		(width 0.1143)
		(layer "In11.Cu")
		(net "P3E_CPU0_PE3_OCP_RXN<9>")
	)
	(segment
		(start 298.378626 -95.033084)
		(end 298.671742 -94.864174)
		(width 0.0889)
		(layer "In11.Cu")
		(net "P3E_CPU0_PE3_OCP_RXN<9>")
	)
	(segment
		(start 443.273434 -122.64644)
		(end 443.437772 -122.480578)
		(width 0.1143)
		(layer "In11.Cu")
		(net "P3E_CPU0_PE3_OCP_RXN<9>")
	)
	(segment
		(start 380.636272 -137.94613)
		(end 381.259334 -138.366246)
		(width 0.1143)
		(layer "In11.Cu")
		(net "P3E_CPU0_PE3_OCP_RXN<9>")
	)
	(segment
		(start 427.904402 -131.880864)
		(end 430.997106 -129.79019)
		(width 0.1143)
		(layer "In11.Cu")
		(net "P3E_CPU0_PE3_OCP_RXN<9>")
	)
	(segment
		(start 374.907556 -137.799826)
		(end 374.96623 -137.811256)
		(width 0.1143)
		(layer "In11.Cu")
		(net "P3E_CPU0_PE3_OCP_RXN<9>")
	)
	(segment
		(start 352.233992 -127.706628)
		(end 356.147878 -126.72949)
		(width 0.1143)
		(layer "In11.Cu")
		(net "P3E_CPU0_PE3_OCP_RXN<9>")
	)
	(segment
		(start 310.098186 -103.755444)
		(end 317.48857 -111.145828)
		(width 0.1143)
		(layer "In11.Cu")
		(net "P3E_CPU0_PE3_OCP_RXN<9>")
	)
	(segment
		(start 333.727298 -124.172472)
		(end 339.283802 -124.172472)
		(width 0.1143)
		(layer "In11.Cu")
		(net "P3E_CPU0_PE3_OCP_RXN<9>")
	)
	(segment
		(start 304.353722 -100.620576)
		(end 304.659792 -100.926646)
		(width 0.0889)
		(layer "In11.Cu")
		(net "P3E_CPU0_PE3_OCP_RXN<9>")
	)
	(segment
		(start 347.121226 -127.442214)
		(end 348.430088 -126.982474)
		(width 0.1143)
		(layer "In11.Cu")
		(net "P3E_CPU0_PE3_OCP_RXN<9>")
	)
	(segment
		(start 423.648378 -133.168644)
		(end 424.364658 -132.708904)
		(width 0.1143)
		(layer "In11.Cu")
		(net "P3E_CPU0_PE3_OCP_RXN<9>")
	)
	(segment
		(start 300.082712 -95.623888)
		(end 300.110652 -95.623888)
		(width 0.0889)
		(layer "In11.Cu")
		(net "P3E_CPU0_PE3_OCP_RXN<9>")
	)
	(segment
		(start 329.858624 -121.771664)
		(end 331.325728 -121.771664)
		(width 0.1143)
		(layer "In11.Cu")
		(net "P3E_CPU0_PE3_OCP_RXN<9>")
	)
	(segment
		(start 371.996462 -133.70052)
		(end 373.176292 -134.88035)
		(width 0.1143)
		(layer "In11.Cu")
		(net "P3E_CPU0_PE3_OCP_RXN<9>")
	)
	(segment
		(start 324.42404 -116.33708)
		(end 329.858624 -121.771664)
		(width 0.1143)
		(layer "In11.Cu")
		(net "P3E_CPU0_PE3_OCP_RXN<9>")
	)
	(segment
		(start 430.997106 -129.79019)
		(end 434.143912 -128.88976)
		(width 0.1143)
		(layer "In11.Cu")
		(net "P3E_CPU0_PE3_OCP_RXN<9>")
	)
	(segment
		(start 321.243452 -111.145828)
		(end 324.42404 -114.326416)
		(width 0.1143)
		(layer "In11.Cu")
		(net "P3E_CPU0_PE3_OCP_RXN<9>")
	)
	(segment
		(start 324.42404 -114.326416)
		(end 324.42404 -116.33708)
		(width 0.1143)
		(layer "In11.Cu")
		(net "P3E_CPU0_PE3_OCP_RXN<9>")
	)
	(segment
		(start 366.42675 -130.054096)
		(end 370.073174 -133.70052)
		(width 0.1143)
		(layer "In11.Cu")
		(net "P3E_CPU0_PE3_OCP_RXN<9>")
	)
	(segment
		(start 304.659792 -100.926646)
		(end 304.659538 -100.99802)
		(width 0.0889)
		(layer "In11.Cu")
		(net "P3E_CPU0_PE3_OCP_RXN<9>")
	)
	(segment
		(start 434.143912 -128.88976)
		(end 436.229252 -124.454666)
		(width 0.1143)
		(layer "In11.Cu")
		(net "P3E_CPU0_PE3_OCP_RXN<9>")
	)
	(segment
		(start 411.901386 -138.365992)
		(end 415.141664 -139.113768)
		(width 0.1143)
		(layer "In11.Cu")
		(net "P3E_CPU0_PE3_OCP_RXN<9>")
	)
	(segment
		(start 390.497314 -139.60221)
		(end 394.261086 -140.62837)
		(width 0.1143)
		(layer "In11.Cu")
		(net "P3E_CPU0_PE3_OCP_RXN<9>")
	)
	(segment
		(start 378.809504 -137.591038)
		(end 380.636272 -137.94613)
		(width 0.1143)
		(layer "In11.Cu")
		(net "P3E_CPU0_PE3_OCP_RXN<9>")
	)
	(segment
		(start 345.767152 -127.177038)
		(end 347.121226 -127.442214)
		(width 0.1143)
		(layer "In11.Cu")
		(net "P3E_CPU0_PE3_OCP_RXN<9>")
	)
	(segment
		(start 302.101504 -99.586288)
		(end 302.274478 -99.759262)
		(width 0.0889)
		(layer "In11.Cu")
		(net "P3E_CPU0_PE3_OCP_RXN<9>")
	)
	(segment
		(start 444.504572 -122.617484)
		(end 444.820548 -122.93346)
		(width 0.1143)
		(layer "In11.Cu")
		(net "P3E_CPU0_PE3_OCP_RXN<9>")
	)
	(segment
		(start 305.520598 -101.85908)
		(end 310.098186 -103.755444)
		(width 0.1143)
		(layer "In11.Cu")
		(net "P3E_CPU0_PE3_OCP_RXN<9>")
	)
	(segment
		(start 399.665698 -139.64031)
		(end 405.419814 -139.64031)
		(width 0.1143)
		(layer "In11.Cu")
		(net "P3E_CPU0_PE3_OCP_RXN<9>")
	)
	(segment
		(start 373.176292 -134.88035)
		(end 373.176292 -135.995918)
		(width 0.1143)
		(layer "In11.Cu")
		(net "P3E_CPU0_PE3_OCP_RXN<9>")
	)
	(segment
		(start 441.914534 -122.65152)
		(end 442.257434 -122.65025)
		(width 0.1143)
		(layer "In11.Cu")
		(net "P3E_CPU0_PE3_OCP_RXN<9>")
	)
	(segment
		(start 416.602418 -138.782552)
		(end 417.271962 -138.943588)
		(width 0.1143)
		(layer "In11.Cu")
		(net "P3E_CPU0_PE3_OCP_RXN<9>")
	)
	(segment
		(start 300.442376 -98.205036)
		(end 300.436026 -98.215704)
		(width 0.0889)
		(layer "In11.Cu")
		(net "P3E_CPU0_PE3_OCP_RXN<9>")
	)
	(segment
		(start 424.364658 -132.708904)
		(end 427.904402 -131.880864)
		(width 0.1143)
		(layer "In11.Cu")
		(net "P3E_CPU0_PE3_OCP_RXN<9>")
	)
	(segment
		(start 298.671742 -94.864174)
		(end 298.76115 -94.888304)
		(width 0.0889)
		(layer "In11.Cu")
		(net "P3E_CPU0_PE3_OCP_RXN<9>")
	)
	(segment
		(start 436.229252 -124.454666)
		(end 440.460638 -122.70232)
		(width 0.1143)
		(layer "In11.Cu")
		(net "P3E_CPU0_PE3_OCP_RXN<9>")
	)
	(segment
		(start 415.142172 -139.113768)
		(end 416.602418 -138.782552)
		(width 0.1143)
		(layer "In11.Cu")
		(net "P3E_CPU0_PE3_OCP_RXN<9>")
	)
	(segment
		(start 344.248232 -125.184154)
		(end 345.447366 -126.960884)
		(width 0.1143)
		(layer "In11.Cu")
		(net "P3E_CPU0_PE3_OCP_RXN<9>")
	)
	(segment
		(start 356.147878 -126.72949)
		(end 359.08488 -128.04267)
		(width 0.1143)
		(layer "In11.Cu")
		(net "P3E_CPU0_PE3_OCP_RXN<9>")
	)
	(segment
		(start 331.325728 -121.771664)
		(end 333.727298 -124.172472)
		(width 0.1143)
		(layer "In11.Cu")
		(net "P3E_CPU0_PE3_OCP_RXN<9>")
	)
	(segment
		(start 317.48857 -111.145828)
		(end 321.243452 -111.145828)
		(width 0.1143)
		(layer "In11.Cu")
		(net "P3E_CPU0_PE3_OCP_RXN<9>")
	)
	(segment
		(start 304.659538 -100.99802)
		(end 304.675286 -101.013768)
		(width 0.0889)
		(layer "In11.Cu")
		(net "P3E_CPU0_PE3_OCP_RXN<9>")
	)
	(segment
		(start 443.437772 -122.480578)
		(end 443.780672 -122.479308)
		(width 0.1143)
		(layer "In11.Cu")
		(net "P3E_CPU0_PE3_OCP_RXN<9>")
	)
	(segment
		(start 300.447202 -97.2058)
		(end 300.442376 -97.214436)
		(width 0.0889)
		(layer "In11.Cu")
		(net "P3E_CPU0_PE3_OCP_RXN<9>")
	)
	(segment
		(start 300.447202 -98.1964)
		(end 300.442376 -98.205036)
		(width 0.0889)
		(layer "In11.Cu")
		(net "P3E_CPU0_PE3_OCP_RXN<9>")
	)
	(segment
		(start 345.447366 -126.960884)
		(end 345.767152 -127.177038)
		(width 0.1143)
		(layer "In11.Cu")
		(net "P3E_CPU0_PE3_OCP_RXN<9>")
	)
	(segment
		(start 300.932596 -99.090734)
		(end 300.965362 -99.090734)
		(width 0.0889)
		(layer "In11.Cu")
		(net "P3E_CPU0_PE3_OCP_RXN<9>")
	)
	(segment
		(start 299.219366 -95.128588)
		(end 299.25518 -95.128588)
		(width 0.0889)
		(layer "In11.Cu")
		(net "P3E_CPU0_PE3_OCP_RXN<9>")
	)
	(arc
		(start 300.442376 -96.814386)
		(mid 300.495846 -97.009449)
		(end 300.447202 -97.2058)
		(width 0.0889)
		(layer "In11.Cu")
		(net "P3E_CPU0_PE3_OCP_RXN<9>")
	)
	(arc
		(start 300.436026 -97.225104)
		(mid 300.363228 -97.515867)
		(end 300.442376 -97.804986)
		(width 0.0889)
		(layer "In11.Cu")
		(net "P3E_CPU0_PE3_OCP_RXN<9>")
	)
	(arc
		(start 300.442376 -97.804986)
		(mid 300.495846 -98.000049)
		(end 300.447202 -98.1964)
		(width 0.0889)
		(layer "In11.Cu")
		(net "P3E_CPU0_PE3_OCP_RXN<9>")
	)
	(arc
		(start 300.965362 -99.090734)
		(mid 301.159212 -99.147084)
		(end 301.300896 -99.290886)
		(width 0.0889)
		(layer "In11.Cu")
		(net "P3E_CPU0_PE3_OCP_RXN<9>")
	)
	(arc
		(start 298.76115 -94.888304)
		(mid 298.96256 -95.061257)
		(end 299.219366 -95.128588)
		(width 0.0889)
		(layer "In11.Cu")
		(net "P3E_CPU0_PE3_OCP_RXN<9>")
	)
	(arc
		(start 299.25518 -95.128588)
		(mid 299.445109 -95.186458)
		(end 299.583856 -95.328486)
		(width 0.0889)
		(layer "In11.Cu")
		(net "P3E_CPU0_PE3_OCP_RXN<9>")
	)
	(arc
		(start 300.436026 -98.215704)
		(mid 300.440057 -98.791886)
		(end 300.932596 -99.090734)
		(width 0.0889)
		(layer "In11.Cu")
		(net "P3E_CPU0_PE3_OCP_RXN<9>")
	)
	(arc
		(start 300.436026 -96.234504)
		(mid 300.363228 -96.525267)
		(end 300.442376 -96.814386)
		(width 0.0889)
		(layer "In11.Cu")
		(net "P3E_CPU0_PE3_OCP_RXN<9>")
	)
	(arc
		(start 299.583856 -95.328486)
		(mid 299.794569 -95.541565)
		(end 300.082712 -95.623888)
		(width 0.0889)
		(layer "In11.Cu")
		(net "P3E_CPU0_PE3_OCP_RXN<9>")
	)
	(arc
		(start 301.300896 -99.290886)
		(mid 301.509504 -99.502818)
		(end 301.794926 -99.586288)
		(width 0.0889)
		(layer "In11.Cu")
		(net "P3E_CPU0_PE3_OCP_RXN<9>")
	)
	(arc
		(start 300.110652 -95.623888)
		(mid 300.44357 -95.825879)
		(end 300.447202 -96.2152)
		(width 0.0889)
		(layer "In11.Cu")
		(net "P3E_CPU0_PE3_OCP_RXN<9>")
	)
	(segment
		(start 441.400946 -116.993162)
		(end 441.400946 -118.342918)
		(width 0.1143)
		(layer "F.Cu")
		(net "P3E_CPU0_PE3_OCP_RXN<8>")
	)
	(segment
		(start 297.807126 -96.023938)
		(end 298.378626 -96.023938)
		(width 0.1143)
		(layer "F.Cu")
		(net "P3E_CPU0_PE3_OCP_RXN<8>")
	)
	(segment
		(start 441.57265 -123.88977)
		(end 441.1726 -123.88977)
		(width 0.1143)
		(layer "F.Cu")
		(net "P3E_CPU0_PE3_OCP_RXN<8>")
	)
	(segment
		(start 441.67933 -123.78309)
		(end 441.57265 -123.88977)
		(width 0.1143)
		(layer "F.Cu")
		(net "P3E_CPU0_PE3_OCP_RXN<8>")
	)
	(segment
		(start 441.39993 -118.343934)
		(end 441.67933 -118.623334)
		(width 0.1143)
		(layer "F.Cu")
		(net "P3E_CPU0_PE3_OCP_RXN<8>")
	)
	(segment
		(start 441.67933 -118.623334)
		(end 441.67933 -123.78309)
		(width 0.1143)
		(layer "F.Cu")
		(net "P3E_CPU0_PE3_OCP_RXN<8>")
	)
	(segment
		(start 441.400946 -118.342918)
		(end 441.39993 -118.343934)
		(width 0.1143)
		(layer "F.Cu")
		(net "P3E_CPU0_PE3_OCP_RXN<8>")
	)
	(via
		(at 298.378626 -96.023938)
		(size 0.508)
		(drill 0.254)
		(layers "F.Cu" "B.Cu")
		(net "P3E_CPU0_PE3_OCP_RXN<8>")
	)
	(via
		(at 441.1726 -123.88977)
		(size 0.508)
		(drill 0.254)
		(layers "F.Cu" "B.Cu")
		(net "P3E_CPU0_PE3_OCP_RXN<8>")
	)
	(segment
		(start 352.208846 -128.407668)
		(end 354.144326 -127.92456)
		(width 0.1143)
		(layer "In11.Cu")
		(net "P3E_CPU0_PE3_OCP_RXN<8>")
	)
	(segment
		(start 436.68569 -124.979938)
		(end 437.014112 -124.84354)
		(width 0.1143)
		(layer "In11.Cu")
		(net "P3E_CPU0_PE3_OCP_RXN<8>")
	)
	(segment
		(start 331.00899 -122.43562)
		(end 333.380842 -124.807472)
		(width 0.1143)
		(layer "In11.Cu")
		(net "P3E_CPU0_PE3_OCP_RXN<8>")
	)
	(segment
		(start 417.330382 -139.61237)
		(end 423.158412 -137.070846)
		(width 0.1143)
		(layer "In11.Cu")
		(net "P3E_CPU0_PE3_OCP_RXN<8>")
	)
	(segment
		(start 441.537598 -123.88977)
		(end 441.1726 -123.88977)
		(width 0.1143)
		(layer "In11.Cu")
		(net "P3E_CPU0_PE3_OCP_RXN<8>")
	)
	(segment
		(start 299.577506 -98.289618)
		(end 299.583856 -98.300286)
		(width 0.0889)
		(layer "In11.Cu")
		(net "P3E_CPU0_PE3_OCP_RXN<8>")
	)
	(segment
		(start 366.043464 -130.617722)
		(end 369.761516 -134.33552)
		(width 0.1143)
		(layer "In11.Cu")
		(net "P3E_CPU0_PE3_OCP_RXN<8>")
	)
	(segment
		(start 345.422728 -127.76327)
		(end 347.174058 -128.105154)
		(width 0.1143)
		(layer "In11.Cu")
		(net "P3E_CPU0_PE3_OCP_RXN<8>")
	)
	(segment
		(start 303.652936 -101.696012)
		(end 303.762918 -101.696012)
		(width 0.0889)
		(layer "In11.Cu")
		(net "P3E_CPU0_PE3_OCP_RXN<8>")
	)
	(segment
		(start 298.378626 -96.023938)
		(end 298.08551 -95.854774)
		(width 0.0889)
		(layer "In11.Cu")
		(net "P3E_CPU0_PE3_OCP_RXN<8>")
	)
	(segment
		(start 307.942488 -103.910384)
		(end 308.259226 -104.041702)
		(width 0.1143)
		(layer "In11.Cu")
		(net "P3E_CPU0_PE3_OCP_RXN<8>")
	)
	(segment
		(start 303.894744 -101.950266)
		(end 304.020474 -102.075996)
		(width 0.0889)
		(layer "In11.Cu")
		(net "P3E_CPU0_PE3_OCP_RXN<8>")
	)
	(segment
		(start 437.647588 -124.58065)
		(end 437.97601 -124.444252)
		(width 0.1143)
		(layer "In11.Cu")
		(net "P3E_CPU0_PE3_OCP_RXN<8>")
	)
	(segment
		(start 317.01994 -111.864394)
		(end 319.052194 -111.864394)
		(width 0.1143)
		(layer "In11.Cu")
		(net "P3E_CPU0_PE3_OCP_RXN<8>")
	)
	(segment
		(start 386.014468 -140.23721)
		(end 390.41197 -140.23721)
		(width 0.1143)
		(layer "In11.Cu")
		(net "P3E_CPU0_PE3_OCP_RXN<8>")
	)
	(segment
		(start 361.36453 -128.679956)
		(end 366.043464 -130.617722)
		(width 0.1143)
		(layer "In11.Cu")
		(net "P3E_CPU0_PE3_OCP_RXN<8>")
	)
	(segment
		(start 425.994576 -135.674354)
		(end 427.453044 -134.702042)
		(width 0.1143)
		(layer "In11.Cu")
		(net "P3E_CPU0_PE3_OCP_RXN<8>")
	)
	(segment
		(start 299.583856 -97.309686)
		(end 299.588682 -97.318322)
		(width 0.0889)
		(layer "In11.Cu")
		(net "P3E_CPU0_PE3_OCP_RXN<8>")
	)
	(segment
		(start 411.891734 -139.016486)
		(end 415.141156 -139.766802)
		(width 0.1143)
		(layer "In11.Cu")
		(net "P3E_CPU0_PE3_OCP_RXN<8>")
	)
	(segment
		(start 441.66155 -123.508008)
		(end 441.66155 -123.765818)
		(width 0.1143)
		(layer "In11.Cu")
		(net "P3E_CPU0_PE3_OCP_RXN<8>")
	)
	(segment
		(start 304.020474 -102.075996)
		(end 304.142902 -102.075996)
		(width 0.0889)
		(layer "In11.Cu")
		(net "P3E_CPU0_PE3_OCP_RXN<8>")
	)
	(segment
		(start 305.634898 -103.1748)
		(end 306.597558 -103.1748)
		(width 0.1143)
		(layer "In11.Cu")
		(net "P3E_CPU0_PE3_OCP_RXN<8>")
	)
	(segment
		(start 306.914296 -103.306118)
		(end 307.003704 -103.521764)
		(width 0.1143)
		(layer "In11.Cu")
		(net "P3E_CPU0_PE3_OCP_RXN<8>")
	)
	(segment
		(start 347.174058 -128.105154)
		(end 348.38767 -127.679958)
		(width 0.1143)
		(layer "In11.Cu")
		(net "P3E_CPU0_PE3_OCP_RXN<8>")
	)
	(segment
		(start 416.597592 -139.436348)
		(end 417.330382 -139.61237)
		(width 0.1143)
		(layer "In11.Cu")
		(net "P3E_CPU0_PE3_OCP_RXN<8>")
	)
	(segment
		(start 427.453044 -134.702042)
		(end 431.896012 -133.81355)
		(width 0.1143)
		(layer "In11.Cu")
		(net "P3E_CPU0_PE3_OCP_RXN<8>")
	)
	(segment
		(start 303.266856 -101.305614)
		(end 303.372774 -101.305614)
		(width 0.0889)
		(layer "In11.Cu")
		(net "P3E_CPU0_PE3_OCP_RXN<8>")
	)
	(segment
		(start 438.520078 -124.397008)
		(end 438.609232 -124.181362)
		(width 0.1143)
		(layer "In11.Cu")
		(net "P3E_CPU0_PE3_OCP_RXN<8>")
	)
	(segment
		(start 358.851454 -128.679956)
		(end 361.36453 -128.679956)
		(width 0.1143)
		(layer "In11.Cu")
		(net "P3E_CPU0_PE3_OCP_RXN<8>")
	)
	(segment
		(start 307.003704 -103.521764)
		(end 307.320442 -103.652828)
		(width 0.1143)
		(layer "In11.Cu")
		(net "P3E_CPU0_PE3_OCP_RXN<8>")
	)
	(segment
		(start 303.141126 -101.07422)
		(end 303.141126 -101.179884)
		(width 0.0889)
		(layer "In11.Cu")
		(net "P3E_CPU0_PE3_OCP_RXN<8>")
	)
	(segment
		(start 299.577506 -97.299018)
		(end 299.583856 -97.309686)
		(width 0.0889)
		(layer "In11.Cu")
		(net "P3E_CPU0_PE3_OCP_RXN<8>")
	)
	(segment
		(start 438.609232 -124.181362)
		(end 440.724544 -123.3043)
		(width 0.1143)
		(layer "In11.Cu")
		(net "P3E_CPU0_PE3_OCP_RXN<8>")
	)
	(segment
		(start 302.973994 -100.907088)
		(end 303.141126 -101.07422)
		(width 0.0889)
		(layer "In11.Cu")
		(net "P3E_CPU0_PE3_OCP_RXN<8>")
	)
	(segment
		(start 423.158412 -137.070846)
		(end 424.93692 -135.885174)
		(width 0.1143)
		(layer "In11.Cu")
		(net "P3E_CPU0_PE3_OCP_RXN<8>")
	)
	(segment
		(start 354.144072 -127.924306)
		(end 356.08006 -127.441198)
		(width 0.1143)
		(layer "In11.Cu")
		(net "P3E_CPU0_PE3_OCP_RXN<8>")
	)
	(segment
		(start 415.141156 -139.766802)
		(end 416.597592 -139.436348)
		(width 0.1143)
		(layer "In11.Cu")
		(net "P3E_CPU0_PE3_OCP_RXN<8>")
	)
	(segment
		(start 433.890674 -129.894076)
		(end 433.890674 -129.893822)
		(width 0.1143)
		(layer "In11.Cu")
		(net "P3E_CPU0_PE3_OCP_RXN<8>")
	)
	(segment
		(start 339.120988 -124.807472)
		(end 343.673938 -125.73762)
		(width 0.1143)
		(layer "In11.Cu")
		(net "P3E_CPU0_PE3_OCP_RXN<8>")
	)
	(segment
		(start 329.62342 -122.43562)
		(end 331.00899 -122.43562)
		(width 0.1143)
		(layer "In11.Cu")
		(net "P3E_CPU0_PE3_OCP_RXN<8>")
	)
	(segment
		(start 298.08551 -95.854774)
		(end 298.064428 -95.776034)
		(width 0.0889)
		(layer "In11.Cu")
		(net "P3E_CPU0_PE3_OCP_RXN<8>")
	)
	(segment
		(start 305.562 -103.124)
		(end 305.6128 -103.1748)
		(width 0.0889)
		(layer "In11.Cu")
		(net "P3E_CPU0_PE3_OCP_RXN<8>")
	)
	(segment
		(start 300.941232 -100.081588)
		(end 300.965362 -100.081588)
		(width 0.0889)
		(layer "In11.Cu")
		(net "P3E_CPU0_PE3_OCP_RXN<8>")
	)
	(segment
		(start 308.259226 -104.041702)
		(end 308.474872 -103.952294)
		(width 0.1143)
		(layer "In11.Cu")
		(net "P3E_CPU0_PE3_OCP_RXN<8>")
	)
	(segment
		(start 431.896012 -133.81355)
		(end 432.62804 -133.254242)
		(width 0.1143)
		(layer "In11.Cu")
		(net "P3E_CPU0_PE3_OCP_RXN<8>")
	)
	(segment
		(start 299.215556 -96.118934)
		(end 299.248322 -96.118934)
		(width 0.0889)
		(layer "In11.Cu")
		(net "P3E_CPU0_PE3_OCP_RXN<8>")
	)
	(segment
		(start 372.936516 -138.093196)
		(end 374.081548 -138.849354)
		(width 0.1143)
		(layer "In11.Cu")
		(net "P3E_CPU0_PE3_OCP_RXN<8>")
	)
	(segment
		(start 354.144326 -127.92456)
		(end 354.144072 -127.924306)
		(width 0.1143)
		(layer "In11.Cu")
		(net "P3E_CPU0_PE3_OCP_RXN<8>")
	)
	(segment
		(start 307.536342 -103.563674)
		(end 307.85308 -103.694738)
		(width 0.1143)
		(layer "In11.Cu")
		(net "P3E_CPU0_PE3_OCP_RXN<8>")
	)
	(segment
		(start 303.527206 -101.460046)
		(end 303.527206 -101.570282)
		(width 0.0889)
		(layer "In11.Cu")
		(net "P3E_CPU0_PE3_OCP_RXN<8>")
	)
	(segment
		(start 301.300896 -100.28174)
		(end 301.300896 -100.281486)
		(width 0.0889)
		(layer "In11.Cu")
		(net "P3E_CPU0_PE3_OCP_RXN<8>")
	)
	(segment
		(start 437.014112 -124.84354)
		(end 437.230012 -124.932694)
		(width 0.1143)
		(layer "In11.Cu")
		(net "P3E_CPU0_PE3_OCP_RXN<8>")
	)
	(segment
		(start 433.890674 -129.893822)
		(end 434.584348 -129.448814)
		(width 0.1143)
		(layer "In11.Cu")
		(net "P3E_CPU0_PE3_OCP_RXN<8>")
	)
	(segment
		(start 343.673938 -125.73762)
		(end 344.720926 -127.290068)
		(width 0.1143)
		(layer "In11.Cu")
		(net "P3E_CPU0_PE3_OCP_RXN<8>")
	)
	(segment
		(start 301.790608 -100.576634)
		(end 302.17618 -100.576634)
		(width 0.0889)
		(layer "In11.Cu")
		(net "P3E_CPU0_PE3_OCP_RXN<8>")
	)
	(segment
		(start 308.474872 -103.952294)
		(end 309.55488 -104.399588)
		(width 0.1143)
		(layer "In11.Cu")
		(net "P3E_CPU0_PE3_OCP_RXN<8>")
	)
	(segment
		(start 374.081548 -138.849354)
		(end 379.230382 -139.896342)
		(width 0.1143)
		(layer "In11.Cu")
		(net "P3E_CPU0_PE3_OCP_RXN<8>")
	)
	(segment
		(start 437.230012 -124.932694)
		(end 437.558434 -124.796296)
		(width 0.1143)
		(layer "In11.Cu")
		(net "P3E_CPU0_PE3_OCP_RXN<8>")
	)
	(segment
		(start 303.372774 -101.305614)
		(end 303.527206 -101.460046)
		(width 0.0889)
		(layer "In11.Cu")
		(net "P3E_CPU0_PE3_OCP_RXN<8>")
	)
	(segment
		(start 438.191656 -124.533406)
		(end 438.520078 -124.397008)
		(width 0.1143)
		(layer "In11.Cu")
		(net "P3E_CPU0_PE3_OCP_RXN<8>")
	)
	(segment
		(start 440.724544 -123.3043)
		(end 441.457842 -123.3043)
		(width 0.1143)
		(layer "In11.Cu")
		(net "P3E_CPU0_PE3_OCP_RXN<8>")
	)
	(segment
		(start 300.077886 -99.586288)
		(end 300.110652 -99.586288)
		(width 0.0889)
		(layer "In11.Cu")
		(net "P3E_CPU0_PE3_OCP_RXN<8>")
	)
	(segment
		(start 348.38767 -127.679958)
		(end 352.208846 -128.407668)
		(width 0.1143)
		(layer "In11.Cu")
		(net "P3E_CPU0_PE3_OCP_RXN<8>")
	)
	(segment
		(start 344.720926 -127.290068)
		(end 345.422728 -127.76327)
		(width 0.1143)
		(layer "In11.Cu")
		(net "P3E_CPU0_PE3_OCP_RXN<8>")
	)
	(segment
		(start 424.93692 -135.885174)
		(end 425.994576 -135.674354)
		(width 0.1143)
		(layer "In11.Cu")
		(net "P3E_CPU0_PE3_OCP_RXN<8>")
	)
	(segment
		(start 369.761516 -134.33552)
		(end 371.67312 -134.33552)
		(width 0.1143)
		(layer "In11.Cu")
		(net "P3E_CPU0_PE3_OCP_RXN<8>")
	)
	(segment
		(start 304.142902 -102.075996)
		(end 305.190906 -103.124)
		(width 0.0889)
		(layer "In11.Cu")
		(net "P3E_CPU0_PE3_OCP_RXN<8>")
	)
	(segment
		(start 309.55488 -104.399588)
		(end 317.01994 -111.864394)
		(width 0.1143)
		(layer "In11.Cu")
		(net "P3E_CPU0_PE3_OCP_RXN<8>")
	)
	(segment
		(start 390.41197 -140.23721)
		(end 394.2334 -141.279372)
		(width 0.1143)
		(layer "In11.Cu")
		(net "P3E_CPU0_PE3_OCP_RXN<8>")
	)
	(segment
		(start 372.4275 -137.32383)
		(end 372.936516 -138.093196)
		(width 0.1143)
		(layer "In11.Cu")
		(net "P3E_CPU0_PE3_OCP_RXN<8>")
	)
	(segment
		(start 434.584348 -129.448814)
		(end 436.68569 -124.979938)
		(width 0.1143)
		(layer "In11.Cu")
		(net "P3E_CPU0_PE3_OCP_RXN<8>")
	)
	(segment
		(start 305.6128 -103.1748)
		(end 305.634898 -103.1748)
		(width 0.0889)
		(layer "In11.Cu")
		(net "P3E_CPU0_PE3_OCP_RXN<8>")
	)
	(segment
		(start 319.052194 -111.864394)
		(end 329.62342 -122.43562)
		(width 0.1143)
		(layer "In11.Cu")
		(net "P3E_CPU0_PE3_OCP_RXN<8>")
	)
	(segment
		(start 441.457842 -123.3043)
		(end 441.66155 -123.508008)
		(width 0.1143)
		(layer "In11.Cu")
		(net "P3E_CPU0_PE3_OCP_RXN<8>")
	)
	(segment
		(start 437.558434 -124.796296)
		(end 437.647588 -124.58065)
		(width 0.1143)
		(layer "In11.Cu")
		(net "P3E_CPU0_PE3_OCP_RXN<8>")
	)
	(segment
		(start 299.583856 -98.300286)
		(end 299.588682 -98.308922)
		(width 0.0889)
		(layer "In11.Cu")
		(net "P3E_CPU0_PE3_OCP_RXN<8>")
	)
	(segment
		(start 379.230382 -139.896342)
		(end 381.783844 -139.376658)
		(width 0.1143)
		(layer "In11.Cu")
		(net "P3E_CPU0_PE3_OCP_RXN<8>")
	)
	(segment
		(start 432.62804 -133.254242)
		(end 433.890674 -129.894076)
		(width 0.1143)
		(layer "In11.Cu")
		(net "P3E_CPU0_PE3_OCP_RXN<8>")
	)
	(segment
		(start 305.190906 -103.124)
		(end 305.562 -103.124)
		(width 0.0889)
		(layer "In11.Cu")
		(net "P3E_CPU0_PE3_OCP_RXN<8>")
	)
	(segment
		(start 371.67312 -134.33552)
		(end 372.4275 -135.0899)
		(width 0.1143)
		(layer "In11.Cu")
		(net "P3E_CPU0_PE3_OCP_RXN<8>")
	)
	(segment
		(start 372.4275 -135.0899)
		(end 372.4275 -137.32383)
		(width 0.1143)
		(layer "In11.Cu")
		(net "P3E_CPU0_PE3_OCP_RXN<8>")
	)
	(segment
		(start 303.762918 -101.696012)
		(end 303.894744 -101.827838)
		(width 0.0889)
		(layer "In11.Cu")
		(net "P3E_CPU0_PE3_OCP_RXN<8>")
	)
	(segment
		(start 394.2334 -141.279372)
		(end 399.714466 -140.277088)
		(width 0.1143)
		(layer "In11.Cu")
		(net "P3E_CPU0_PE3_OCP_RXN<8>")
	)
	(segment
		(start 307.85308 -103.694738)
		(end 307.942488 -103.910384)
		(width 0.1143)
		(layer "In11.Cu")
		(net "P3E_CPU0_PE3_OCP_RXN<8>")
	)
	(segment
		(start 356.08006 -127.441198)
		(end 358.851454 -128.679956)
		(width 0.1143)
		(layer "In11.Cu")
		(net "P3E_CPU0_PE3_OCP_RXN<8>")
	)
	(segment
		(start 303.527206 -101.570282)
		(end 303.652936 -101.696012)
		(width 0.0889)
		(layer "In11.Cu")
		(net "P3E_CPU0_PE3_OCP_RXN<8>")
	)
	(segment
		(start 441.66155 -123.765818)
		(end 441.537598 -123.88977)
		(width 0.1143)
		(layer "In11.Cu")
		(net "P3E_CPU0_PE3_OCP_RXN<8>")
	)
	(segment
		(start 333.380842 -124.807472)
		(end 339.120988 -124.807472)
		(width 0.1143)
		(layer "In11.Cu")
		(net "P3E_CPU0_PE3_OCP_RXN<8>")
	)
	(segment
		(start 437.97601 -124.444252)
		(end 438.191656 -124.533406)
		(width 0.1143)
		(layer "In11.Cu")
		(net "P3E_CPU0_PE3_OCP_RXN<8>")
	)
	(segment
		(start 306.597558 -103.1748)
		(end 306.914296 -103.306118)
		(width 0.1143)
		(layer "In11.Cu")
		(net "P3E_CPU0_PE3_OCP_RXN<8>")
	)
	(segment
		(start 298.36364 -95.623888)
		(end 298.393612 -95.623888)
		(width 0.0889)
		(layer "In11.Cu")
		(net "P3E_CPU0_PE3_OCP_RXN<8>")
	)
	(segment
		(start 307.320442 -103.652828)
		(end 307.536342 -103.563674)
		(width 0.1143)
		(layer "In11.Cu")
		(net "P3E_CPU0_PE3_OCP_RXN<8>")
	)
	(segment
		(start 303.141126 -101.179884)
		(end 303.266856 -101.305614)
		(width 0.0889)
		(layer "In11.Cu")
		(net "P3E_CPU0_PE3_OCP_RXN<8>")
	)
	(segment
		(start 399.714466 -140.277088)
		(end 405.480774 -140.277088)
		(width 0.1143)
		(layer "In11.Cu")
		(net "P3E_CPU0_PE3_OCP_RXN<8>")
	)
	(segment
		(start 381.783844 -139.376658)
		(end 386.014468 -140.23721)
		(width 0.1143)
		(layer "In11.Cu")
		(net "P3E_CPU0_PE3_OCP_RXN<8>")
	)
	(segment
		(start 303.894744 -101.827838)
		(end 303.894744 -101.950266)
		(width 0.0889)
		(layer "In11.Cu")
		(net "P3E_CPU0_PE3_OCP_RXN<8>")
	)
	(segment
		(start 405.480774 -140.277088)
		(end 411.891734 -139.016486)
		(width 0.1143)
		(layer "In11.Cu")
		(net "P3E_CPU0_PE3_OCP_RXN<8>")
	)
	(arc
		(start 301.300896 -100.281486)
		(mid 301.50765 -100.492305)
		(end 301.790608 -100.576634)
		(width 0.0889)
		(layer "In11.Cu")
		(net "P3E_CPU0_PE3_OCP_RXN<8>")
	)
	(arc
		(start 300.110652 -99.586288)
		(mid 300.302294 -99.643454)
		(end 300.442376 -99.786186)
		(width 0.0889)
		(layer "In11.Cu")
		(net "P3E_CPU0_PE3_OCP_RXN<8>")
	)
	(arc
		(start 302.17618 -100.576634)
		(mid 302.607949 -100.662518)
		(end 302.973994 -100.907088)
		(width 0.0889)
		(layer "In11.Cu")
		(net "P3E_CPU0_PE3_OCP_RXN<8>")
	)
	(arc
		(start 299.248322 -96.118934)
		(mid 299.586491 -96.323732)
		(end 299.583856 -96.719136)
		(width 0.0889)
		(layer "In11.Cu")
		(net "P3E_CPU0_PE3_OCP_RXN<8>")
	)
	(arc
		(start 300.442376 -99.786186)
		(mid 300.653089 -99.999265)
		(end 300.941232 -100.081588)
		(width 0.0889)
		(layer "In11.Cu")
		(net "P3E_CPU0_PE3_OCP_RXN<8>")
	)
	(arc
		(start 299.583856 -97.709736)
		(mid 299.504634 -97.998854)
		(end 299.577506 -98.289618)
		(width 0.0889)
		(layer "In11.Cu")
		(net "P3E_CPU0_PE3_OCP_RXN<8>")
	)
	(arc
		(start 299.583856 -96.719136)
		(mid 299.504634 -97.008254)
		(end 299.577506 -97.299018)
		(width 0.0889)
		(layer "In11.Cu")
		(net "P3E_CPU0_PE3_OCP_RXN<8>")
	)
	(arc
		(start 298.725336 -95.823786)
		(mid 298.93234 -96.03465)
		(end 299.215556 -96.118934)
		(width 0.0889)
		(layer "In11.Cu")
		(net "P3E_CPU0_PE3_OCP_RXN<8>")
	)
	(arc
		(start 299.588682 -97.318322)
		(mid 299.637437 -97.514674)
		(end 299.583856 -97.709736)
		(width 0.0889)
		(layer "In11.Cu")
		(net "P3E_CPU0_PE3_OCP_RXN<8>")
	)
	(arc
		(start 300.965362 -100.081588)
		(mid 301.123986 -100.119351)
		(end 301.254414 -100.217224)
		(width 0.0889)
		(layer "In11.Cu")
		(net "P3E_CPU0_PE3_OCP_RXN<8>")
	)
	(arc
		(start 298.064428 -95.776034)
		(mid 298.197309 -95.667051)
		(end 298.36364 -95.623888)
		(width 0.0889)
		(layer "In11.Cu")
		(net "P3E_CPU0_PE3_OCP_RXN<8>")
	)
	(arc
		(start 299.583856 -98.700336)
		(mid 299.579527 -99.283508)
		(end 300.077886 -99.586288)
		(width 0.0889)
		(layer "In11.Cu")
		(net "P3E_CPU0_PE3_OCP_RXN<8>")
	)
	(arc
		(start 299.588682 -98.308922)
		(mid 299.637437 -98.505274)
		(end 299.583856 -98.700336)
		(width 0.0889)
		(layer "In11.Cu")
		(net "P3E_CPU0_PE3_OCP_RXN<8>")
	)
	(arc
		(start 298.393612 -95.623888)
		(mid 298.585254 -95.681054)
		(end 298.725336 -95.823786)
		(width 0.0889)
		(layer "In11.Cu")
		(net "P3E_CPU0_PE3_OCP_RXN<8>")
	)
	(arc
		(start 301.254414 -100.217224)
		(mid 301.279261 -100.248325)
		(end 301.300896 -100.28174)
		(width 0.0889)
		(layer "In11.Cu")
		(net "P3E_CPU0_PE3_OCP_RXN<8>")
	)
	(segment
		(start 296.66184 -96.023938)
		(end 296.09034 -96.023938)
		(width 0.1143)
		(layer "F.Cu")
		(net "P3E_CPU0_PE3_OCP_RXN<7>")
	)
	(segment
		(start 439.644028 -44.83735)
		(end 439.462672 -45.018706)
		(width 0.1143)
		(layer "F.Cu")
		(net "P3E_CPU0_PE3_OCP_RXN<7>")
	)
	(segment
		(start 439.977022 -44.83735)
		(end 439.644028 -44.83735)
		(width 0.1143)
		(layer "F.Cu")
		(net "P3E_CPU0_PE3_OCP_RXN<7>")
	)
	(segment
		(start 439.462672 -45.978318)
		(end 439.742072 -46.257718)
		(width 0.1143)
		(layer "F.Cu")
		(net "P3E_CPU0_PE3_OCP_RXN<7>")
	)
	(segment
		(start 439.742072 -47.481998)
		(end 439.741056 -47.481998)
		(width 0.1143)
		(layer "F.Cu")
		(net "P3E_CPU0_PE3_OCP_RXN<7>")
	)
	(segment
		(start 439.742072 -46.257718)
		(end 439.742072 -47.481998)
		(width 0.1143)
		(layer "F.Cu")
		(net "P3E_CPU0_PE3_OCP_RXN<7>")
	)
	(segment
		(start 439.462672 -45.018706)
		(end 439.462672 -45.978318)
		(width 0.1143)
		(layer "F.Cu")
		(net "P3E_CPU0_PE3_OCP_RXN<7>")
	)
	(via
		(at 296.66184 -96.023938)
		(size 0.508)
		(drill 0.254)
		(layers "F.Cu" "B.Cu")
		(net "P3E_CPU0_PE3_OCP_RXN<7>")
	)
	(via
		(at 439.977022 -44.83735)
		(size 0.508)
		(drill 0.254)
		(layers "F.Cu" "B.Cu")
		(net "P3E_CPU0_PE3_OCP_RXN<7>")
	)
	(segment
		(start 386.737352 -45.834554)
		(end 386.340604 -45.834554)
		(width 0.1143)
		(layer "In4.Cu")
		(net "P3E_CPU0_PE3_OCP_RXN<7>")
	)
	(segment
		(start 422.373298 -50.548032)
		(end 422.181782 -50.356516)
		(width 0.1143)
		(layer "In4.Cu")
		(net "P3E_CPU0_PE3_OCP_RXN<7>")
	)
	(segment
		(start 307.3654 -92.2655)
		(end 307.26253 -92.2655)
		(width 0.0889)
		(layer "In4.Cu")
		(net "P3E_CPU0_PE3_OCP_RXN<7>")
	)
	(segment
		(start 332.905862 -56.498744)
		(end 332.380844 -56.846216)
		(width 0.1143)
		(layer "In4.Cu")
		(net "P3E_CPU0_PE3_OCP_RXN<7>")
	)
	(segment
		(start 351.337626 -53.958236)
		(end 347.74632 -56.498744)
		(width 0.1143)
		(layer "In4.Cu")
		(net "P3E_CPU0_PE3_OCP_RXN<7>")
	)
	(segment
		(start 381.653796 -45.5803)
		(end 380.098046 -47.13605)
		(width 0.1143)
		(layer "In4.Cu")
		(net "P3E_CPU0_PE3_OCP_RXN<7>")
	)
	(segment
		(start 432.586384 -46.312074)
		(end 432.05781 -45.7835)
		(width 0.1143)
		(layer "In4.Cu")
		(net "P3E_CPU0_PE3_OCP_RXN<7>")
	)
	(segment
		(start 418.911024 -51.776884)
		(end 407.50744 -51.776884)
		(width 0.1143)
		(layer "In4.Cu")
		(net "P3E_CPU0_PE3_OCP_RXN<7>")
	)
	(segment
		(start 332.380844 -56.846216)
		(end 332.380844 -56.845962)
		(width 0.1143)
		(layer "In4.Cu")
		(net "P3E_CPU0_PE3_OCP_RXN<7>")
	)
	(segment
		(start 370.647722 -45.7327)
		(end 368.507518 -47.872904)
		(width 0.1143)
		(layer "In4.Cu")
		(net "P3E_CPU0_PE3_OCP_RXN<7>")
	)
	(segment
		(start 375.853706 -45.7327)
		(end 370.647722 -45.7327)
		(width 0.1143)
		(layer "In4.Cu")
		(net "P3E_CPU0_PE3_OCP_RXN<7>")
	)
	(segment
		(start 368.507518 -47.872904)
		(end 366.601502 -47.872904)
		(width 0.1143)
		(layer "In4.Cu")
		(net "P3E_CPU0_PE3_OCP_RXN<7>")
	)
	(segment
		(start 357.895906 -53.318664)
		(end 356.548182 -53.770784)
		(width 0.1143)
		(layer "In4.Cu")
		(net "P3E_CPU0_PE3_OCP_RXN<7>")
	)
	(segment
		(start 429.133 -46.228254)
		(end 426.94606 -48.415194)
		(width 0.1143)
		(layer "In4.Cu")
		(net "P3E_CPU0_PE3_OCP_RXN<7>")
	)
	(segment
		(start 388.172198 -47.2694)
		(end 386.737352 -45.834554)
		(width 0.1143)
		(layer "In4.Cu")
		(net "P3E_CPU0_PE3_OCP_RXN<7>")
	)
	(segment
		(start 424.05046 -48.41494)
		(end 423.670984 -48.794416)
		(width 0.1143)
		(layer "In4.Cu")
		(net "P3E_CPU0_PE3_OCP_RXN<7>")
	)
	(segment
		(start 300.117256 -94.633288)
		(end 300.074076 -94.633288)
		(width 0.0889)
		(layer "In4.Cu")
		(net "P3E_CPU0_PE3_OCP_RXN<7>")
	)
	(segment
		(start 423.670984 -48.794416)
		(end 423.670984 -50.015394)
		(width 0.1143)
		(layer "In4.Cu")
		(net "P3E_CPU0_PE3_OCP_RXN<7>")
	)
	(segment
		(start 364.424214 -50.050446)
		(end 361.562904 -50.873914)
		(width 0.1143)
		(layer "In4.Cu")
		(net "P3E_CPU0_PE3_OCP_RXN<7>")
	)
	(segment
		(start 297.537886 -95.128588)
		(end 297.507914 -95.128588)
		(width 0.0889)
		(layer "In4.Cu")
		(net "P3E_CPU0_PE3_OCP_RXN<7>")
	)
	(segment
		(start 426.553884 -48.415194)
		(end 426.55363 -48.41494)
		(width 0.1143)
		(layer "In4.Cu")
		(net "P3E_CPU0_PE3_OCP_RXN<7>")
	)
	(segment
		(start 322.740528 -70.860158)
		(end 317.709042 -83.00847)
		(width 0.1143)
		(layer "In4.Cu")
		(net "P3E_CPU0_PE3_OCP_RXN<7>")
	)
	(segment
		(start 429.2473 -45.7835)
		(end 429.133 -45.8978)
		(width 0.1143)
		(layer "In4.Cu")
		(net "P3E_CPU0_PE3_OCP_RXN<7>")
	)
	(segment
		(start 421.742362 -50.356516)
		(end 421.45331 -50.645568)
		(width 0.1143)
		(layer "In4.Cu")
		(net "P3E_CPU0_PE3_OCP_RXN<7>")
	)
	(segment
		(start 361.562904 -50.873914)
		(end 357.895906 -53.318664)
		(width 0.1143)
		(layer "In4.Cu")
		(net "P3E_CPU0_PE3_OCP_RXN<7>")
	)
	(segment
		(start 393.568174 -47.477426)
		(end 392.6078 -48.4378)
		(width 0.1143)
		(layer "In4.Cu")
		(net "P3E_CPU0_PE3_OCP_RXN<7>")
	)
	(segment
		(start 301.830486 -93.642688)
		(end 301.79772 -93.642688)
		(width 0.0889)
		(layer "In4.Cu")
		(net "P3E_CPU0_PE3_OCP_RXN<7>")
	)
	(segment
		(start 392.6078 -48.4378)
		(end 391.414 -48.4378)
		(width 0.1143)
		(layer "In4.Cu")
		(net "P3E_CPU0_PE3_OCP_RXN<7>")
	)
	(segment
		(start 307.438298 -92.3163)
		(end 307.4162 -92.3163)
		(width 0.0889)
		(layer "In4.Cu")
		(net "P3E_CPU0_PE3_OCP_RXN<7>")
	)
	(segment
		(start 347.74632 -56.498744)
		(end 332.905862 -56.498744)
		(width 0.1143)
		(layer "In4.Cu")
		(net "P3E_CPU0_PE3_OCP_RXN<7>")
	)
	(segment
		(start 305.257962 -93.1926)
		(end 304.309272 -93.1926)
		(width 0.0889)
		(layer "In4.Cu")
		(net "P3E_CPU0_PE3_OCP_RXN<7>")
	)
	(segment
		(start 391.414 -48.4378)
		(end 390.2456 -47.2694)
		(width 0.1143)
		(layer "In4.Cu")
		(net "P3E_CPU0_PE3_OCP_RXN<7>")
	)
	(segment
		(start 435.331616 -46.312074)
		(end 432.586384 -46.312074)
		(width 0.1143)
		(layer "In4.Cu")
		(net "P3E_CPU0_PE3_OCP_RXN<7>")
	)
	(segment
		(start 399.207736 -48.382174)
		(end 396.990316 -48.382174)
		(width 0.1143)
		(layer "In4.Cu")
		(net "P3E_CPU0_PE3_OCP_RXN<7>")
	)
	(segment
		(start 379.855984 -47.135796)
		(end 376.672094 -47.135796)
		(width 0.1143)
		(layer "In4.Cu")
		(net "P3E_CPU0_PE3_OCP_RXN<7>")
	)
	(segment
		(start 307.753766 -92.3163)
		(end 307.438298 -92.3163)
		(width 0.1143)
		(layer "In4.Cu")
		(net "P3E_CPU0_PE3_OCP_RXN<7>")
	)
	(segment
		(start 386.08635 -45.5803)
		(end 381.653796 -45.5803)
		(width 0.1143)
		(layer "In4.Cu")
		(net "P3E_CPU0_PE3_OCP_RXN<7>")
	)
	(segment
		(start 401.200112 -50.37455)
		(end 399.207736 -48.382174)
		(width 0.1143)
		(layer "In4.Cu")
		(net "P3E_CPU0_PE3_OCP_RXN<7>")
	)
	(segment
		(start 438.690258 -46.609)
		(end 435.628542 -46.609)
		(width 0.1143)
		(layer "In4.Cu")
		(net "P3E_CPU0_PE3_OCP_RXN<7>")
	)
	(segment
		(start 396.990316 -48.382174)
		(end 396.085568 -47.477426)
		(width 0.1143)
		(layer "In4.Cu")
		(net "P3E_CPU0_PE3_OCP_RXN<7>")
	)
	(segment
		(start 432.05781 -45.7835)
		(end 429.2473 -45.7835)
		(width 0.1143)
		(layer "In4.Cu")
		(net "P3E_CPU0_PE3_OCP_RXN<7>")
	)
	(segment
		(start 423.670984 -50.015394)
		(end 423.138346 -50.548032)
		(width 0.1143)
		(layer "In4.Cu")
		(net "P3E_CPU0_PE3_OCP_RXN<7>")
	)
	(segment
		(start 332.380844 -56.845962)
		(end 322.740528 -70.860158)
		(width 0.1143)
		(layer "In4.Cu")
		(net "P3E_CPU0_PE3_OCP_RXN<7>")
	)
	(segment
		(start 308.858666 -91.858846)
		(end 307.753766 -92.3163)
		(width 0.1143)
		(layer "In4.Cu")
		(net "P3E_CPU0_PE3_OCP_RXN<7>")
	)
	(segment
		(start 396.085568 -47.477426)
		(end 393.568174 -47.477426)
		(width 0.1143)
		(layer "In4.Cu")
		(net "P3E_CPU0_PE3_OCP_RXN<7>")
	)
	(segment
		(start 386.340604 -45.834554)
		(end 386.08635 -45.5803)
		(width 0.1143)
		(layer "In4.Cu")
		(net "P3E_CPU0_PE3_OCP_RXN<7>")
	)
	(segment
		(start 317.709042 -83.00847)
		(end 308.858666 -91.858846)
		(width 0.1143)
		(layer "In4.Cu")
		(net "P3E_CPU0_PE3_OCP_RXN<7>")
	)
	(segment
		(start 439.502804 -44.95165)
		(end 439.502804 -45.796454)
		(width 0.1143)
		(layer "In4.Cu")
		(net "P3E_CPU0_PE3_OCP_RXN<7>")
	)
	(segment
		(start 379.856238 -47.13605)
		(end 379.855984 -47.135796)
		(width 0.1143)
		(layer "In4.Cu")
		(net "P3E_CPU0_PE3_OCP_RXN<7>")
	)
	(segment
		(start 426.55363 -48.41494)
		(end 424.05046 -48.41494)
		(width 0.1143)
		(layer "In4.Cu")
		(net "P3E_CPU0_PE3_OCP_RXN<7>")
	)
	(segment
		(start 380.098046 -47.13605)
		(end 379.856238 -47.13605)
		(width 0.1143)
		(layer "In4.Cu")
		(net "P3E_CPU0_PE3_OCP_RXN<7>")
	)
	(segment
		(start 421.45331 -50.645568)
		(end 420.04234 -50.645568)
		(width 0.1143)
		(layer "In4.Cu")
		(net "P3E_CPU0_PE3_OCP_RXN<7>")
	)
	(segment
		(start 376.098308 -46.56201)
		(end 376.098308 -45.977302)
		(width 0.1143)
		(layer "In4.Cu")
		(net "P3E_CPU0_PE3_OCP_RXN<7>")
	)
	(segment
		(start 420.04234 -50.645568)
		(end 418.911024 -51.776884)
		(width 0.1143)
		(layer "In4.Cu")
		(net "P3E_CPU0_PE3_OCP_RXN<7>")
	)
	(segment
		(start 307.26253 -92.2655)
		(end 306.748942 -92.478352)
		(width 0.0889)
		(layer "In4.Cu")
		(net "P3E_CPU0_PE3_OCP_RXN<7>")
	)
	(segment
		(start 354.408994 -53.344064)
		(end 351.337626 -53.958236)
		(width 0.1143)
		(layer "In4.Cu")
		(net "P3E_CPU0_PE3_OCP_RXN<7>")
	)
	(segment
		(start 307.4162 -92.3163)
		(end 307.3654 -92.2655)
		(width 0.0889)
		(layer "In4.Cu")
		(net "P3E_CPU0_PE3_OCP_RXN<7>")
	)
	(segment
		(start 296.66184 -95.685864)
		(end 296.66184 -96.023938)
		(width 0.0889)
		(layer "In4.Cu")
		(net "P3E_CPU0_PE3_OCP_RXN<7>")
	)
	(segment
		(start 306.748942 -92.478352)
		(end 306.583842 -92.643452)
		(width 0.0889)
		(layer "In4.Cu")
		(net "P3E_CPU0_PE3_OCP_RXN<7>")
	)
	(segment
		(start 439.502804 -45.796454)
		(end 438.690258 -46.609)
		(width 0.1143)
		(layer "In4.Cu")
		(net "P3E_CPU0_PE3_OCP_RXN<7>")
	)
	(segment
		(start 376.672094 -47.135796)
		(end 376.098308 -46.56201)
		(width 0.1143)
		(layer "In4.Cu")
		(net "P3E_CPU0_PE3_OCP_RXN<7>")
	)
	(segment
		(start 422.181782 -50.356516)
		(end 421.742362 -50.356516)
		(width 0.1143)
		(layer "In4.Cu")
		(net "P3E_CPU0_PE3_OCP_RXN<7>")
	)
	(segment
		(start 296.727118 -95.620586)
		(end 296.66184 -95.685864)
		(width 0.0889)
		(layer "In4.Cu")
		(net "P3E_CPU0_PE3_OCP_RXN<7>")
	)
	(segment
		(start 356.548182 -53.770784)
		(end 354.408994 -53.344064)
		(width 0.1143)
		(layer "In4.Cu")
		(net "P3E_CPU0_PE3_OCP_RXN<7>")
	)
	(segment
		(start 406.101804 -50.37455)
		(end 401.200112 -50.37455)
		(width 0.1143)
		(layer "In4.Cu")
		(net "P3E_CPU0_PE3_OCP_RXN<7>")
	)
	(segment
		(start 429.133 -45.8978)
		(end 429.133 -46.228254)
		(width 0.1143)
		(layer "In4.Cu")
		(net "P3E_CPU0_PE3_OCP_RXN<7>")
	)
	(segment
		(start 298.400216 -94.633288)
		(end 298.360592 -94.633288)
		(width 0.0889)
		(layer "In4.Cu")
		(net "P3E_CPU0_PE3_OCP_RXN<7>")
	)
	(segment
		(start 366.601502 -47.872904)
		(end 364.424214 -50.050446)
		(width 0.1143)
		(layer "In4.Cu")
		(net "P3E_CPU0_PE3_OCP_RXN<7>")
	)
	(segment
		(start 423.138346 -50.548032)
		(end 422.373298 -50.548032)
		(width 0.1143)
		(layer "In4.Cu")
		(net "P3E_CPU0_PE3_OCP_RXN<7>")
	)
	(segment
		(start 439.617104 -44.83735)
		(end 439.502804 -44.95165)
		(width 0.1143)
		(layer "In4.Cu")
		(net "P3E_CPU0_PE3_OCP_RXN<7>")
	)
	(segment
		(start 426.94606 -48.415194)
		(end 426.553884 -48.415194)
		(width 0.1143)
		(layer "In4.Cu")
		(net "P3E_CPU0_PE3_OCP_RXN<7>")
	)
	(segment
		(start 435.628542 -46.609)
		(end 435.331616 -46.312074)
		(width 0.1143)
		(layer "In4.Cu")
		(net "P3E_CPU0_PE3_OCP_RXN<7>")
	)
	(segment
		(start 390.2456 -47.2694)
		(end 388.172198 -47.2694)
		(width 0.1143)
		(layer "In4.Cu")
		(net "P3E_CPU0_PE3_OCP_RXN<7>")
	)
	(segment
		(start 376.098308 -45.977302)
		(end 375.853706 -45.7327)
		(width 0.1143)
		(layer "In4.Cu")
		(net "P3E_CPU0_PE3_OCP_RXN<7>")
	)
	(segment
		(start 407.50744 -51.776884)
		(end 406.101804 -50.37455)
		(width 0.1143)
		(layer "In4.Cu")
		(net "P3E_CPU0_PE3_OCP_RXN<7>")
	)
	(segment
		(start 300.96714 -94.137988)
		(end 300.94301 -94.137988)
		(width 0.0889)
		(layer "In4.Cu")
		(net "P3E_CPU0_PE3_OCP_RXN<7>")
	)
	(segment
		(start 439.977022 -44.83735)
		(end 439.617104 -44.83735)
		(width 0.1143)
		(layer "In4.Cu")
		(net "P3E_CPU0_PE3_OCP_RXN<7>")
	)
	(segment
		(start 306.583842 -92.643452)
		(end 305.257962 -93.1926)
		(width 0.0889)
		(layer "In4.Cu")
		(net "P3E_CPU0_PE3_OCP_RXN<7>")
	)
	(arc
		(start 302.324516 -93.347286)
		(mid 302.115908 -93.559218)
		(end 301.830486 -93.642688)
		(width 0.0889)
		(layer "In4.Cu")
		(net "P3E_CPU0_PE3_OCP_RXN<7>")
	)
	(arc
		(start 298.890436 -94.33814)
		(mid 298.683432 -94.549004)
		(end 298.400216 -94.633288)
		(width 0.0889)
		(layer "In4.Cu")
		(net "P3E_CPU0_PE3_OCP_RXN<7>")
	)
	(arc
		(start 303.017936 -93.347286)
		(mid 302.671226 -93.146975)
		(end 302.324516 -93.347286)
		(width 0.0889)
		(layer "In4.Cu")
		(net "P3E_CPU0_PE3_OCP_RXN<7>")
	)
	(arc
		(start 301.79772 -93.642688)
		(mid 301.606078 -93.699854)
		(end 301.465996 -93.842586)
		(width 0.0889)
		(layer "In4.Cu")
		(net "P3E_CPU0_PE3_OCP_RXN<7>")
	)
	(arc
		(start 297.507914 -95.128588)
		(mid 297.314811 -95.185107)
		(end 297.17365 -95.328486)
		(width 0.0889)
		(layer "In4.Cu")
		(net "P3E_CPU0_PE3_OCP_RXN<7>")
	)
	(arc
		(start 304.041556 -93.347286)
		(mid 303.529746 -93.642953)
		(end 303.017936 -93.347286)
		(width 0.0889)
		(layer "In4.Cu")
		(net "P3E_CPU0_PE3_OCP_RXN<7>")
	)
	(arc
		(start 298.031916 -94.833186)
		(mid 297.823308 -95.045118)
		(end 297.537886 -95.128588)
		(width 0.0889)
		(layer "In4.Cu")
		(net "P3E_CPU0_PE3_OCP_RXN<7>")
	)
	(arc
		(start 304.309272 -93.1926)
		(mid 304.154663 -93.234043)
		(end 304.041556 -93.347286)
		(width 0.0889)
		(layer "In4.Cu")
		(net "P3E_CPU0_PE3_OCP_RXN<7>")
	)
	(arc
		(start 297.17365 -95.328486)
		(mid 296.985227 -95.52779)
		(end 296.727118 -95.620586)
		(width 0.0889)
		(layer "In4.Cu")
		(net "P3E_CPU0_PE3_OCP_RXN<7>")
	)
	(arc
		(start 299.583856 -94.33814)
		(mid 299.237146 -94.137829)
		(end 298.890436 -94.33814)
		(width 0.0889)
		(layer "In4.Cu")
		(net "P3E_CPU0_PE3_OCP_RXN<7>")
	)
	(arc
		(start 300.607476 -94.33814)
		(mid 300.400472 -94.549004)
		(end 300.117256 -94.633288)
		(width 0.0889)
		(layer "In4.Cu")
		(net "P3E_CPU0_PE3_OCP_RXN<7>")
	)
	(arc
		(start 301.465996 -93.842586)
		(mid 301.255283 -94.055665)
		(end 300.96714 -94.137988)
		(width 0.0889)
		(layer "In4.Cu")
		(net "P3E_CPU0_PE3_OCP_RXN<7>")
	)
	(arc
		(start 300.074076 -94.633288)
		(mid 299.790859 -94.549007)
		(end 299.583856 -94.33814)
		(width 0.0889)
		(layer "In4.Cu")
		(net "P3E_CPU0_PE3_OCP_RXN<7>")
	)
	(arc
		(start 300.94301 -94.137988)
		(mid 300.74916 -94.194338)
		(end 300.607476 -94.33814)
		(width 0.0889)
		(layer "In4.Cu")
		(net "P3E_CPU0_PE3_OCP_RXN<7>")
	)
	(arc
		(start 298.360592 -94.633288)
		(mid 298.170663 -94.691158)
		(end 298.031916 -94.833186)
		(width 0.0889)
		(layer "In4.Cu")
		(net "P3E_CPU0_PE3_OCP_RXN<7>")
	)
	(segment
		(start 442.421518 -45.969682)
		(end 442.142118 -46.249082)
		(width 0.1143)
		(layer "F.Cu")
		(net "P3E_CPU0_PE3_OCP_RXN<6>")
	)
	(segment
		(start 441.907168 -44.83735)
		(end 442.240162 -44.83735)
		(width 0.1143)
		(layer "F.Cu")
		(net "P3E_CPU0_PE3_OCP_RXN<6>")
	)
	(segment
		(start 442.142118 -46.249082)
		(end 442.142118 -47.481998)
		(width 0.1143)
		(layer "F.Cu")
		(net "P3E_CPU0_PE3_OCP_RXN<6>")
	)
	(segment
		(start 442.240162 -44.83735)
		(end 442.421518 -45.018706)
		(width 0.1143)
		(layer "F.Cu")
		(net "P3E_CPU0_PE3_OCP_RXN<6>")
	)
	(segment
		(start 442.142118 -47.481998)
		(end 442.141102 -47.481998)
		(width 0.1143)
		(layer "F.Cu")
		(net "P3E_CPU0_PE3_OCP_RXN<6>")
	)
	(segment
		(start 296.09034 -97.014538)
		(end 296.66184 -97.014538)
		(width 0.1143)
		(layer "F.Cu")
		(net "P3E_CPU0_PE3_OCP_RXN<6>")
	)
	(segment
		(start 442.421518 -45.018706)
		(end 442.421518 -45.969682)
		(width 0.1143)
		(layer "F.Cu")
		(net "P3E_CPU0_PE3_OCP_RXN<6>")
	)
	(via
		(at 441.907168 -44.83735)
		(size 0.508)
		(drill 0.254)
		(layers "F.Cu" "B.Cu")
		(net "P3E_CPU0_PE3_OCP_RXN<6>")
	)
	(via
		(at 296.66184 -97.014538)
		(size 0.508)
		(drill 0.254)
		(layers "F.Cu" "B.Cu")
		(net "P3E_CPU0_PE3_OCP_RXN<6>")
	)
	(segment
		(start 432.891692 -45.305726)
		(end 435.531768 -45.305726)
		(width 0.1143)
		(layer "In4.Cu")
		(net "P3E_CPU0_PE3_OCP_RXN<6>")
	)
	(segment
		(start 296.66184 -96.614488)
		(end 296.64406 -96.614488)
		(width 0.0889)
		(layer "In4.Cu")
		(net "P3E_CPU0_PE3_OCP_RXN<6>")
	)
	(segment
		(start 435.895496 -44.941998)
		(end 435.895496 -44.318428)
		(width 0.1143)
		(layer "In4.Cu")
		(net "P3E_CPU0_PE3_OCP_RXN<6>")
	)
	(segment
		(start 412.563564 -50.849784)
		(end 412.728664 -50.684684)
		(width 0.1143)
		(layer "In4.Cu")
		(net "P3E_CPU0_PE3_OCP_RXN<6>")
	)
	(segment
		(start 426.543216 -45.819822)
		(end 427.213776 -45.819822)
		(width 0.1143)
		(layer "In4.Cu")
		(net "P3E_CPU0_PE3_OCP_RXN<6>")
	)
	(segment
		(start 363.00791 -49.115472)
		(end 364.044738 -49.115472)
		(width 0.1143)
		(layer "In4.Cu")
		(net "P3E_CPU0_PE3_OCP_RXN<6>")
	)
	(segment
		(start 442.156342 -46.101)
		(end 442.396118 -45.861224)
		(width 0.1143)
		(layer "In4.Cu")
		(net "P3E_CPU0_PE3_OCP_RXN<6>")
	)
	(segment
		(start 441.1599 -45.852842)
		(end 441.408058 -46.101)
		(width 0.1143)
		(layer "In4.Cu")
		(net "P3E_CPU0_PE3_OCP_RXN<6>")
	)
	(segment
		(start 347.35897 -55.558944)
		(end 351.759774 -52.4256)
		(width 0.1143)
		(layer "In4.Cu")
		(net "P3E_CPU0_PE3_OCP_RXN<6>")
	)
	(segment
		(start 418.523674 -50.849784)
		(end 420.746174 -48.627284)
		(width 0.1143)
		(layer "In4.Cu")
		(net "P3E_CPU0_PE3_OCP_RXN<6>")
	)
	(segment
		(start 394.076428 -45.702474)
		(end 394.855954 -46.482)
		(width 0.1143)
		(layer "In4.Cu")
		(net "P3E_CPU0_PE3_OCP_RXN<6>")
	)
	(segment
		(start 388.226554 -46.0121)
		(end 390.861042 -46.0121)
		(width 0.1143)
		(layer "In4.Cu")
		(net "P3E_CPU0_PE3_OCP_RXN<6>")
	)
	(segment
		(start 427.213776 -45.819822)
		(end 428.202598 -44.831)
		(width 0.1143)
		(layer "In4.Cu")
		(net "P3E_CPU0_PE3_OCP_RXN<6>")
	)
	(segment
		(start 308.627526 -90.762074)
		(end 308.64302 -90.74658)
		(width 0.0889)
		(layer "In4.Cu")
		(net "P3E_CPU0_PE3_OCP_RXN<6>")
	)
	(segment
		(start 296.66184 -97.014538)
		(end 296.954702 -96.845628)
		(width 0.0889)
		(layer "In4.Cu")
		(net "P3E_CPU0_PE3_OCP_RXN<6>")
	)
	(segment
		(start 436.376064 -43.83786)
		(end 440.297824 -43.83786)
		(width 0.1143)
		(layer "In4.Cu")
		(net "P3E_CPU0_PE3_OCP_RXN<6>")
	)
	(segment
		(start 412.728664 -50.684684)
		(end 413.071564 -50.684684)
		(width 0.1143)
		(layer "In4.Cu")
		(net "P3E_CPU0_PE3_OCP_RXN<6>")
	)
	(segment
		(start 306.341526 -91.90609)
		(end 306.674774 -91.572842)
		(width 0.0889)
		(layer "In4.Cu")
		(net "P3E_CPU0_PE3_OCP_RXN<6>")
	)
	(segment
		(start 422.434258 -48.627284)
		(end 423.703242 -47.3583)
		(width 0.1143)
		(layer "In4.Cu")
		(net "P3E_CPU0_PE3_OCP_RXN<6>")
	)
	(segment
		(start 307.851048 -91.086178)
		(end 308.260242 -91.086178)
		(width 0.0889)
		(layer "In4.Cu")
		(net "P3E_CPU0_PE3_OCP_RXN<6>")
	)
	(segment
		(start 298.357036 -93.452188)
		(end 298.389802 -93.452188)
		(width 0.0889)
		(layer "In4.Cu")
		(net "P3E_CPU0_PE3_OCP_RXN<6>")
	)
	(segment
		(start 435.531768 -45.305726)
		(end 435.895496 -44.941998)
		(width 0.1143)
		(layer "In4.Cu")
		(net "P3E_CPU0_PE3_OCP_RXN<6>")
	)
	(segment
		(start 413.071564 -50.684684)
		(end 413.236664 -50.849784)
		(width 0.1143)
		(layer "In4.Cu")
		(net "P3E_CPU0_PE3_OCP_RXN<6>")
	)
	(segment
		(start 411.712664 -50.684684)
		(end 412.055564 -50.684684)
		(width 0.1143)
		(layer "In4.Cu")
		(net "P3E_CPU0_PE3_OCP_RXN<6>")
	)
	(segment
		(start 390.861042 -46.0121)
		(end 391.559288 -45.313854)
		(width 0.1143)
		(layer "In4.Cu")
		(net "P3E_CPU0_PE3_OCP_RXN<6>")
	)
	(segment
		(start 393.49299 -45.702474)
		(end 394.076428 -45.702474)
		(width 0.1143)
		(layer "In4.Cu")
		(net "P3E_CPU0_PE3_OCP_RXN<6>")
	)
	(segment
		(start 378.044456 -46.205648)
		(end 379.69571 -46.205648)
		(width 0.1143)
		(layer "In4.Cu")
		(net "P3E_CPU0_PE3_OCP_RXN<6>")
	)
	(segment
		(start 366.214406 -46.945804)
		(end 367.928398 -46.945804)
		(width 0.1143)
		(layer "In4.Cu")
		(net "P3E_CPU0_PE3_OCP_RXN<6>")
	)
	(segment
		(start 387.121908 -44.907454)
		(end 388.226554 -46.0121)
		(width 0.1143)
		(layer "In4.Cu")
		(net "P3E_CPU0_PE3_OCP_RXN<6>")
	)
	(segment
		(start 441.1599 -44.699936)
		(end 441.1599 -45.852842)
		(width 0.1143)
		(layer "In4.Cu")
		(net "P3E_CPU0_PE3_OCP_RXN<6>")
	)
	(segment
		(start 308.260242 -91.086178)
		(end 308.456584 -91.004898)
		(width 0.0889)
		(layer "In4.Cu")
		(net "P3E_CPU0_PE3_OCP_RXN<6>")
	)
	(segment
		(start 370.106448 -44.767754)
		(end 376.606562 -44.767754)
		(width 0.1143)
		(layer "In4.Cu")
		(net "P3E_CPU0_PE3_OCP_RXN<6>")
	)
	(segment
		(start 426.0469 -46.868842)
		(end 426.0469 -46.316138)
		(width 0.1143)
		(layer "In4.Cu")
		(net "P3E_CPU0_PE3_OCP_RXN<6>")
	)
	(segment
		(start 440.297824 -43.83786)
		(end 441.1599 -44.699936)
		(width 0.1143)
		(layer "In4.Cu")
		(net "P3E_CPU0_PE3_OCP_RXN<6>")
	)
	(segment
		(start 396.423134 -46.482)
		(end 397.302736 -47.361602)
		(width 0.1143)
		(layer "In4.Cu")
		(net "P3E_CPU0_PE3_OCP_RXN<6>")
	)
	(segment
		(start 308.456584 -91.004898)
		(end 308.627526 -90.833956)
		(width 0.0889)
		(layer "In4.Cu")
		(net "P3E_CPU0_PE3_OCP_RXN<6>")
	)
	(segment
		(start 412.055564 -50.684684)
		(end 412.220664 -50.849784)
		(width 0.1143)
		(layer "In4.Cu")
		(net "P3E_CPU0_PE3_OCP_RXN<6>")
	)
	(segment
		(start 393.10437 -45.313854)
		(end 393.49299 -45.702474)
		(width 0.1143)
		(layer "In4.Cu")
		(net "P3E_CPU0_PE3_OCP_RXN<6>")
	)
	(segment
		(start 386.470906 -44.6532)
		(end 386.72516 -44.907454)
		(width 0.1143)
		(layer "In4.Cu")
		(net "P3E_CPU0_PE3_OCP_RXN<6>")
	)
	(segment
		(start 397.302736 -47.361602)
		(end 399.649442 -47.361602)
		(width 0.1143)
		(layer "In4.Cu")
		(net "P3E_CPU0_PE3_OCP_RXN<6>")
	)
	(segment
		(start 331.720952 -56.168544)
		(end 332.642718 -55.558944)
		(width 0.1143)
		(layer "In4.Cu")
		(net "P3E_CPU0_PE3_OCP_RXN<6>")
	)
	(segment
		(start 442.281818 -44.83735)
		(end 441.907168 -44.83735)
		(width 0.1143)
		(layer "In4.Cu")
		(net "P3E_CPU0_PE3_OCP_RXN<6>")
	)
	(segment
		(start 379.69571 -46.205648)
		(end 381.248158 -44.6532)
		(width 0.1143)
		(layer "In4.Cu")
		(net "P3E_CPU0_PE3_OCP_RXN<6>")
	)
	(segment
		(start 441.408058 -46.101)
		(end 442.156342 -46.101)
		(width 0.1143)
		(layer "In4.Cu")
		(net "P3E_CPU0_PE3_OCP_RXN<6>")
	)
	(segment
		(start 432.416966 -44.831)
		(end 432.891692 -45.305726)
		(width 0.1143)
		(layer "In4.Cu")
		(net "P3E_CPU0_PE3_OCP_RXN<6>")
	)
	(segment
		(start 401.68576 -49.39792)
		(end 406.439878 -49.39792)
		(width 0.1143)
		(layer "In4.Cu")
		(net "P3E_CPU0_PE3_OCP_RXN<6>")
	)
	(segment
		(start 442.396118 -45.861224)
		(end 442.396118 -44.95165)
		(width 0.1143)
		(layer "In4.Cu")
		(net "P3E_CPU0_PE3_OCP_RXN<6>")
	)
	(segment
		(start 304.370486 -91.966034)
		(end 306.196746 -91.966034)
		(width 0.0889)
		(layer "In4.Cu")
		(net "P3E_CPU0_PE3_OCP_RXN<6>")
	)
	(segment
		(start 308.64302 -90.74658)
		(end 316.86373 -82.52587)
		(width 0.1143)
		(layer "In4.Cu")
		(net "P3E_CPU0_PE3_OCP_RXN<6>")
	)
	(segment
		(start 407.891742 -50.849784)
		(end 411.547564 -50.849784)
		(width 0.1143)
		(layer "In4.Cu")
		(net "P3E_CPU0_PE3_OCP_RXN<6>")
	)
	(segment
		(start 367.928398 -46.945804)
		(end 370.106448 -44.767754)
		(width 0.1143)
		(layer "In4.Cu")
		(net "P3E_CPU0_PE3_OCP_RXN<6>")
	)
	(segment
		(start 376.606562 -44.767754)
		(end 378.044456 -46.205648)
		(width 0.1143)
		(layer "In4.Cu")
		(net "P3E_CPU0_PE3_OCP_RXN<6>")
	)
	(segment
		(start 413.236664 -50.849784)
		(end 418.523674 -50.849784)
		(width 0.1143)
		(layer "In4.Cu")
		(net "P3E_CPU0_PE3_OCP_RXN<6>")
	)
	(segment
		(start 423.703242 -47.3583)
		(end 425.557442 -47.3583)
		(width 0.1143)
		(layer "In4.Cu")
		(net "P3E_CPU0_PE3_OCP_RXN<6>")
	)
	(segment
		(start 386.72516 -44.907454)
		(end 387.121908 -44.907454)
		(width 0.1143)
		(layer "In4.Cu")
		(net "P3E_CPU0_PE3_OCP_RXN<6>")
	)
	(segment
		(start 296.954702 -96.845628)
		(end 296.975784 -96.766888)
		(width 0.0889)
		(layer "In4.Cu")
		(net "P3E_CPU0_PE3_OCP_RXN<6>")
	)
	(segment
		(start 435.895496 -44.318428)
		(end 436.376064 -43.83786)
		(width 0.1143)
		(layer "In4.Cu")
		(net "P3E_CPU0_PE3_OCP_RXN<6>")
	)
	(segment
		(start 364.044738 -49.115472)
		(end 366.214406 -46.945804)
		(width 0.1143)
		(layer "In4.Cu")
		(net "P3E_CPU0_PE3_OCP_RXN<6>")
	)
	(segment
		(start 308.627526 -90.833956)
		(end 308.627526 -90.762074)
		(width 0.0889)
		(layer "In4.Cu")
		(net "P3E_CPU0_PE3_OCP_RXN<6>")
	)
	(segment
		(start 381.248158 -44.6532)
		(end 386.470906 -44.6532)
		(width 0.1143)
		(layer "In4.Cu")
		(net "P3E_CPU0_PE3_OCP_RXN<6>")
	)
	(segment
		(start 300.936406 -92.956634)
		(end 300.969172 -92.956634)
		(width 0.0889)
		(layer "In4.Cu")
		(net "P3E_CPU0_PE3_OCP_RXN<6>")
	)
	(segment
		(start 411.547564 -50.849784)
		(end 411.712664 -50.684684)
		(width 0.1143)
		(layer "In4.Cu")
		(net "P3E_CPU0_PE3_OCP_RXN<6>")
	)
	(segment
		(start 442.396118 -44.95165)
		(end 442.281818 -44.83735)
		(width 0.1143)
		(layer "In4.Cu")
		(net "P3E_CPU0_PE3_OCP_RXN<6>")
	)
	(segment
		(start 426.0469 -46.316138)
		(end 426.543216 -45.819822)
		(width 0.1143)
		(layer "In4.Cu")
		(net "P3E_CPU0_PE3_OCP_RXN<6>")
	)
	(segment
		(start 332.642718 -55.558944)
		(end 347.35897 -55.558944)
		(width 0.1143)
		(layer "In4.Cu")
		(net "P3E_CPU0_PE3_OCP_RXN<6>")
	)
	(segment
		(start 399.649442 -47.361602)
		(end 401.68576 -49.39792)
		(width 0.1143)
		(layer "In4.Cu")
		(net "P3E_CPU0_PE3_OCP_RXN<6>")
	)
	(segment
		(start 428.202598 -44.831)
		(end 432.416966 -44.831)
		(width 0.1143)
		(layer "In4.Cu")
		(net "P3E_CPU0_PE3_OCP_RXN<6>")
	)
	(segment
		(start 297.507152 -93.947234)
		(end 297.535092 -93.947234)
		(width 0.0889)
		(layer "In4.Cu")
		(net "P3E_CPU0_PE3_OCP_RXN<6>")
	)
	(segment
		(start 301.791116 -92.461588)
		(end 301.823882 -92.461588)
		(width 0.0889)
		(layer "In4.Cu")
		(net "P3E_CPU0_PE3_OCP_RXN<6>")
	)
	(segment
		(start 296.154856 -95.337122)
		(end 296.15003 -95.328486)
		(width 0.0889)
		(layer "In4.Cu")
		(net "P3E_CPU0_PE3_OCP_RXN<6>")
	)
	(segment
		(start 406.439878 -49.39792)
		(end 407.891742 -50.849784)
		(width 0.1143)
		(layer "In4.Cu")
		(net "P3E_CPU0_PE3_OCP_RXN<6>")
	)
	(segment
		(start 296.64406 -94.442534)
		(end 296.674032 -94.442534)
		(width 0.0889)
		(layer "In4.Cu")
		(net "P3E_CPU0_PE3_OCP_RXN<6>")
	)
	(segment
		(start 420.746174 -48.627284)
		(end 422.434258 -48.627284)
		(width 0.1143)
		(layer "In4.Cu")
		(net "P3E_CPU0_PE3_OCP_RXN<6>")
	)
	(segment
		(start 394.855954 -46.482)
		(end 396.423134 -46.482)
		(width 0.1143)
		(layer "In4.Cu")
		(net "P3E_CPU0_PE3_OCP_RXN<6>")
	)
	(segment
		(start 351.759774 -52.4256)
		(end 363.00791 -49.115472)
		(width 0.1143)
		(layer "In4.Cu")
		(net "P3E_CPU0_PE3_OCP_RXN<6>")
	)
	(segment
		(start 316.86373 -82.52587)
		(end 321.818254 -70.56374)
		(width 0.1143)
		(layer "In4.Cu")
		(net "P3E_CPU0_PE3_OCP_RXN<6>")
	)
	(segment
		(start 412.220664 -50.849784)
		(end 412.563564 -50.849784)
		(width 0.1143)
		(layer "In4.Cu")
		(net "P3E_CPU0_PE3_OCP_RXN<6>")
	)
	(segment
		(start 391.559288 -45.313854)
		(end 393.10437 -45.313854)
		(width 0.1143)
		(layer "In4.Cu")
		(net "P3E_CPU0_PE3_OCP_RXN<6>")
	)
	(segment
		(start 306.196746 -91.966034)
		(end 306.341526 -91.90609)
		(width 0.0889)
		(layer "In4.Cu")
		(net "P3E_CPU0_PE3_OCP_RXN<6>")
	)
	(segment
		(start 321.818254 -70.56374)
		(end 331.720952 -56.168544)
		(width 0.1143)
		(layer "In4.Cu")
		(net "P3E_CPU0_PE3_OCP_RXN<6>")
	)
	(segment
		(start 425.557442 -47.3583)
		(end 426.0469 -46.868842)
		(width 0.1143)
		(layer "In4.Cu")
		(net "P3E_CPU0_PE3_OCP_RXN<6>")
	)
	(segment
		(start 306.674774 -91.572842)
		(end 307.851048 -91.086178)
		(width 0.0889)
		(layer "In4.Cu")
		(net "P3E_CPU0_PE3_OCP_RXN<6>")
	)
	(arc
		(start 298.725336 -93.252036)
		(mid 299.237146 -92.956369)
		(end 299.748956 -93.252036)
		(width 0.0889)
		(layer "In4.Cu")
		(net "P3E_CPU0_PE3_OCP_RXN<6>")
	)
	(arc
		(start 297.866816 -93.747336)
		(mid 298.07382 -93.536472)
		(end 298.357036 -93.452188)
		(width 0.0889)
		(layer "In4.Cu")
		(net "P3E_CPU0_PE3_OCP_RXN<6>")
	)
	(arc
		(start 297.008296 -94.242636)
		(mid 297.219009 -94.029557)
		(end 297.507152 -93.947234)
		(width 0.0889)
		(layer "In4.Cu")
		(net "P3E_CPU0_PE3_OCP_RXN<6>")
	)
	(arc
		(start 298.389802 -93.452188)
		(mid 298.583652 -93.395838)
		(end 298.725336 -93.252036)
		(width 0.0889)
		(layer "In4.Cu")
		(net "P3E_CPU0_PE3_OCP_RXN<6>")
	)
	(arc
		(start 296.64406 -96.614488)
		(mid 296.145809 -96.311648)
		(end 296.15003 -95.728536)
		(width 0.0889)
		(layer "In4.Cu")
		(net "P3E_CPU0_PE3_OCP_RXN<6>")
	)
	(arc
		(start 296.15003 -95.728536)
		(mid 296.2035 -95.533473)
		(end 296.154856 -95.337122)
		(width 0.0889)
		(layer "In4.Cu")
		(net "P3E_CPU0_PE3_OCP_RXN<6>")
	)
	(arc
		(start 299.748956 -93.252036)
		(mid 300.095666 -93.452347)
		(end 300.442376 -93.252036)
		(width 0.0889)
		(layer "In4.Cu")
		(net "P3E_CPU0_PE3_OCP_RXN<6>")
	)
	(arc
		(start 296.674032 -94.442534)
		(mid 296.867135 -94.386015)
		(end 297.008296 -94.242636)
		(width 0.0889)
		(layer "In4.Cu")
		(net "P3E_CPU0_PE3_OCP_RXN<6>")
	)
	(arc
		(start 303.876456 -92.261436)
		(mid 304.085064 -92.049504)
		(end 304.370486 -91.966034)
		(width 0.0889)
		(layer "In4.Cu")
		(net "P3E_CPU0_PE3_OCP_RXN<6>")
	)
	(arc
		(start 296.975784 -96.766888)
		(mid 296.836307 -96.654644)
		(end 296.66184 -96.614488)
		(width 0.0889)
		(layer "In4.Cu")
		(net "P3E_CPU0_PE3_OCP_RXN<6>")
	)
	(arc
		(start 301.300896 -92.756736)
		(mid 301.5079 -92.545872)
		(end 301.791116 -92.461588)
		(width 0.0889)
		(layer "In4.Cu")
		(net "P3E_CPU0_PE3_OCP_RXN<6>")
	)
	(arc
		(start 300.442376 -93.252036)
		(mid 300.650984 -93.040104)
		(end 300.936406 -92.956634)
		(width 0.0889)
		(layer "In4.Cu")
		(net "P3E_CPU0_PE3_OCP_RXN<6>")
	)
	(arc
		(start 302.159416 -92.261436)
		(mid 302.671226 -91.965769)
		(end 303.183036 -92.261436)
		(width 0.0889)
		(layer "In4.Cu")
		(net "P3E_CPU0_PE3_OCP_RXN<6>")
	)
	(arc
		(start 297.535092 -93.947234)
		(mid 297.726734 -93.890068)
		(end 297.866816 -93.747336)
		(width 0.0889)
		(layer "In4.Cu")
		(net "P3E_CPU0_PE3_OCP_RXN<6>")
	)
	(arc
		(start 301.823882 -92.461588)
		(mid 302.017732 -92.405238)
		(end 302.159416 -92.261436)
		(width 0.0889)
		(layer "In4.Cu")
		(net "P3E_CPU0_PE3_OCP_RXN<6>")
	)
	(arc
		(start 303.183036 -92.261436)
		(mid 303.529746 -92.461747)
		(end 303.876456 -92.261436)
		(width 0.0889)
		(layer "In4.Cu")
		(net "P3E_CPU0_PE3_OCP_RXN<6>")
	)
	(arc
		(start 300.969172 -92.956634)
		(mid 301.160814 -92.899468)
		(end 301.300896 -92.756736)
		(width 0.0889)
		(layer "In4.Cu")
		(net "P3E_CPU0_PE3_OCP_RXN<6>")
	)
	(arc
		(start 296.15003 -95.328486)
		(mid 296.145701 -94.745314)
		(end 296.64406 -94.442534)
		(width 0.0889)
		(layer "In4.Cu")
		(net "P3E_CPU0_PE3_OCP_RXN<6>")
	)
	(segment
		(start 445.34201 -46.36389)
		(end 445.34201 -47.481998)
		(width 0.1143)
		(layer "F.Cu")
		(net "P3E_CPU0_PE3_OCP_RXN<5>")
	)
	(segment
		(start 445.34201 -47.481998)
		(end 445.340994 -47.481998)
		(width 0.1143)
		(layer "F.Cu")
		(net "P3E_CPU0_PE3_OCP_RXN<5>")
	)
	(segment
		(start 445.10706 -44.83735)
		(end 445.440054 -44.83735)
		(width 0.1143)
		(layer "F.Cu")
		(net "P3E_CPU0_PE3_OCP_RXN<5>")
	)
	(segment
		(start 445.440054 -44.83735)
		(end 445.6303 -45.027596)
		(width 0.1143)
		(layer "F.Cu")
		(net "P3E_CPU0_PE3_OCP_RXN<5>")
	)
	(segment
		(start 445.6303 -45.027596)
		(end 445.6303 -46.075346)
		(width 0.1143)
		(layer "F.Cu")
		(net "P3E_CPU0_PE3_OCP_RXN<5>")
	)
	(segment
		(start 296.09034 -98.005138)
		(end 296.66184 -98.005138)
		(width 0.1143)
		(layer "F.Cu")
		(net "P3E_CPU0_PE3_OCP_RXN<5>")
	)
	(segment
		(start 445.6303 -46.075346)
		(end 445.34201 -46.36389)
		(width 0.1143)
		(layer "F.Cu")
		(net "P3E_CPU0_PE3_OCP_RXN<5>")
	)
	(via
		(at 296.66184 -98.005138)
		(size 0.508)
		(drill 0.254)
		(layers "F.Cu" "B.Cu")
		(net "P3E_CPU0_PE3_OCP_RXN<5>")
	)
	(via
		(at 445.10706 -44.83735)
		(size 0.508)
		(drill 0.254)
		(layers "F.Cu" "B.Cu")
		(net "P3E_CPU0_PE3_OCP_RXN<5>")
	)
	(segment
		(start 386.266436 -43.687492)
		(end 380.611634 -43.687492)
		(width 0.1143)
		(layer "In4.Cu")
		(net "P3E_CPU0_PE3_OCP_RXN<5>")
	)
	(segment
		(start 295.816274 -94.137988)
		(end 295.792144 -94.137988)
		(width 0.0889)
		(layer "In4.Cu")
		(net "P3E_CPU0_PE3_OCP_RXN<5>")
	)
	(segment
		(start 443.37097 -43.66006)
		(end 443.20587 -43.49496)
		(width 0.1143)
		(layer "In4.Cu")
		(net "P3E_CPU0_PE3_OCP_RXN<5>")
	)
	(segment
		(start 368.509296 -40.482774)
		(end 367.317274 -41.674796)
		(width 0.1143)
		(layer "In4.Cu")
		(net "P3E_CPU0_PE3_OCP_RXN<5>")
	)
	(segment
		(start 435.9148 -43.49496)
		(end 435.67731 -43.73245)
		(width 0.1143)
		(layer "In4.Cu")
		(net "P3E_CPU0_PE3_OCP_RXN<5>")
	)
	(segment
		(start 297.541696 -93.147134)
		(end 297.520106 -93.147134)
		(width 0.0889)
		(layer "In4.Cu")
		(net "P3E_CPU0_PE3_OCP_RXN<5>")
	)
	(segment
		(start 339.893656 -54.517036)
		(end 334.546448 -54.517036)
		(width 0.1143)
		(layer "In4.Cu")
		(net "P3E_CPU0_PE3_OCP_RXN<5>")
	)
	(segment
		(start 307.74259 -89.1286)
		(end 306.76342 -90.10777)
		(width 0.1143)
		(layer "In4.Cu")
		(net "P3E_CPU0_PE3_OCP_RXN<5>")
	)
	(segment
		(start 300.975776 -92.156534)
		(end 300.94301 -92.156534)
		(width 0.0889)
		(layer "In4.Cu")
		(net "P3E_CPU0_PE3_OCP_RXN<5>")
	)
	(segment
		(start 306.67579 -90.123264)
		(end 306.273454 -90.5256)
		(width 0.0889)
		(layer "In4.Cu")
		(net "P3E_CPU0_PE3_OCP_RXN<5>")
	)
	(segment
		(start 441.17387 -43.49496)
		(end 435.9148 -43.49496)
		(width 0.1143)
		(layer "In4.Cu")
		(net "P3E_CPU0_PE3_OCP_RXN<5>")
	)
	(segment
		(start 340.273386 -54.896766)
		(end 339.893656 -54.517036)
		(width 0.1143)
		(layer "In4.Cu")
		(net "P3E_CPU0_PE3_OCP_RXN<5>")
	)
	(segment
		(start 295.45661 -95.328486)
		(end 295.451784 -95.337122)
		(width 0.0889)
		(layer "In4.Cu")
		(net "P3E_CPU0_PE3_OCP_RXN<5>")
	)
	(segment
		(start 380.218442 -43.2943)
		(end 376.6947 -43.2943)
		(width 0.1143)
		(layer "In4.Cu")
		(net "P3E_CPU0_PE3_OCP_RXN<5>")
	)
	(segment
		(start 296.344848 -97.746566)
		(end 296.368724 -97.835974)
		(width 0.0889)
		(layer "In4.Cu")
		(net "P3E_CPU0_PE3_OCP_RXN<5>")
	)
	(segment
		(start 305.102514 -90.642694)
		(end 304.92573 -90.819478)
		(width 0.0889)
		(layer "In4.Cu")
		(net "P3E_CPU0_PE3_OCP_RXN<5>")
	)
	(segment
		(start 442.18987 -43.49496)
		(end 441.84697 -43.49496)
		(width 0.1143)
		(layer "In4.Cu")
		(net "P3E_CPU0_PE3_OCP_RXN<5>")
	)
	(segment
		(start 442.35497 -43.66006)
		(end 442.18987 -43.49496)
		(width 0.1143)
		(layer "In4.Cu")
		(net "P3E_CPU0_PE3_OCP_RXN<5>")
	)
	(segment
		(start 424.332654 -46.024292)
		(end 424.1673 -46.189646)
		(width 0.1143)
		(layer "In4.Cu")
		(net "P3E_CPU0_PE3_OCP_RXN<5>")
	)
	(segment
		(start 296.67962 -93.642688)
		(end 296.646854 -93.642688)
		(width 0.0889)
		(layer "In4.Cu")
		(net "P3E_CPU0_PE3_OCP_RXN<5>")
	)
	(segment
		(start 305.562762 -90.5256)
		(end 305.384962 -90.5256)
		(width 0.0889)
		(layer "In4.Cu")
		(net "P3E_CPU0_PE3_OCP_RXN<5>")
	)
	(segment
		(start 428.673768 -43.73245)
		(end 427.00321 -45.403008)
		(width 0.1143)
		(layer "In4.Cu")
		(net "P3E_CPU0_PE3_OCP_RXN<5>")
	)
	(segment
		(start 413.296862 -49.3776)
		(end 407.296874 -49.3776)
		(width 0.1143)
		(layer "In4.Cu")
		(net "P3E_CPU0_PE3_OCP_RXN<5>")
	)
	(segment
		(start 347.622876 -54.896766)
		(end 340.273386 -54.896766)
		(width 0.1143)
		(layer "In4.Cu")
		(net "P3E_CPU0_PE3_OCP_RXN<5>")
	)
	(segment
		(start 296.368724 -97.835974)
		(end 296.66184 -98.005138)
		(width 0.0889)
		(layer "In4.Cu")
		(net "P3E_CPU0_PE3_OCP_RXN<5>")
	)
	(segment
		(start 443.20587 -43.49496)
		(end 442.86297 -43.49496)
		(width 0.1143)
		(layer "In4.Cu")
		(net "P3E_CPU0_PE3_OCP_RXN<5>")
	)
	(segment
		(start 424.1673 -46.189646)
		(end 424.1673 -46.628558)
		(width 0.1143)
		(layer "In4.Cu")
		(net "P3E_CPU0_PE3_OCP_RXN<5>")
	)
	(segment
		(start 397.564356 -46.992286)
		(end 396.67307 -46.101)
		(width 0.1143)
		(layer "In4.Cu")
		(net "P3E_CPU0_PE3_OCP_RXN<5>")
	)
	(segment
		(start 373.080026 -40.482774)
		(end 368.509296 -40.482774)
		(width 0.1143)
		(layer "In4.Cu")
		(net "P3E_CPU0_PE3_OCP_RXN<5>")
	)
	(segment
		(start 435.67731 -43.73245)
		(end 428.673768 -43.73245)
		(width 0.1143)
		(layer "In4.Cu")
		(net "P3E_CPU0_PE3_OCP_RXN<5>")
	)
	(segment
		(start 387.003544 -44.4246)
		(end 386.266436 -43.687492)
		(width 0.1143)
		(layer "In4.Cu")
		(net "P3E_CPU0_PE3_OCP_RXN<5>")
	)
	(segment
		(start 442.69787 -43.66006)
		(end 442.35497 -43.66006)
		(width 0.1143)
		(layer "In4.Cu")
		(net "P3E_CPU0_PE3_OCP_RXN<5>")
	)
	(segment
		(start 388.4168 -45.6184)
		(end 387.223 -44.4246)
		(width 0.1143)
		(layer "In4.Cu")
		(net "P3E_CPU0_PE3_OCP_RXN<5>")
	)
	(segment
		(start 351.716848 -51.981862)
		(end 347.622876 -54.896766)
		(width 0.1143)
		(layer "In4.Cu")
		(net "P3E_CPU0_PE3_OCP_RXN<5>")
	)
	(segment
		(start 310.757062 -88.13165)
		(end 308.349142 -89.1286)
		(width 0.1143)
		(layer "In4.Cu")
		(net "P3E_CPU0_PE3_OCP_RXN<5>")
	)
	(segment
		(start 393.236196 -44.96054)
		(end 391.00506 -44.96054)
		(width 0.1143)
		(layer "In4.Cu")
		(net "P3E_CPU0_PE3_OCP_RXN<5>")
	)
	(segment
		(start 306.747926 -90.123264)
		(end 306.67579 -90.123264)
		(width 0.0889)
		(layer "In4.Cu")
		(net "P3E_CPU0_PE3_OCP_RXN<5>")
	)
	(segment
		(start 367.317274 -41.674796)
		(end 367.317274 -44.204128)
		(width 0.1143)
		(layer "In4.Cu")
		(net "P3E_CPU0_PE3_OCP_RXN<5>")
	)
	(segment
		(start 445.59601 -43.8531)
		(end 445.23787 -43.49496)
		(width 0.1143)
		(layer "In4.Cu")
		(net "P3E_CPU0_PE3_OCP_RXN<5>")
	)
	(segment
		(start 423.716958 -47.0789)
		(end 423.361358 -47.0789)
		(width 0.1143)
		(layer "In4.Cu")
		(net "P3E_CPU0_PE3_OCP_RXN<5>")
	)
	(segment
		(start 441.84697 -43.49496)
		(end 441.68187 -43.66006)
		(width 0.1143)
		(layer "In4.Cu")
		(net "P3E_CPU0_PE3_OCP_RXN<5>")
	)
	(segment
		(start 376.6947 -43.2943)
		(end 375.0564 -41.656)
		(width 0.1143)
		(layer "In4.Cu")
		(net "P3E_CPU0_PE3_OCP_RXN<5>")
	)
	(segment
		(start 405.967946 -48.048672)
		(end 401.599908 -48.048672)
		(width 0.1143)
		(layer "In4.Cu")
		(net "P3E_CPU0_PE3_OCP_RXN<5>")
	)
	(segment
		(start 445.59601 -44.72305)
		(end 445.59601 -43.8531)
		(width 0.1143)
		(layer "In4.Cu")
		(net "P3E_CPU0_PE3_OCP_RXN<5>")
	)
	(segment
		(start 444.22187 -43.49496)
		(end 443.87897 -43.49496)
		(width 0.1143)
		(layer "In4.Cu")
		(net "P3E_CPU0_PE3_OCP_RXN<5>")
	)
	(segment
		(start 401.599908 -48.048672)
		(end 400.543522 -46.992286)
		(width 0.1143)
		(layer "In4.Cu")
		(net "P3E_CPU0_PE3_OCP_RXN<5>")
	)
	(segment
		(start 304.92573 -90.819478)
		(end 304.900076 -90.870786)
		(width 0.0889)
		(layer "In4.Cu")
		(net "P3E_CPU0_PE3_OCP_RXN<5>")
	)
	(segment
		(start 444.38697 -43.66006)
		(end 444.22187 -43.49496)
		(width 0.1143)
		(layer "In4.Cu")
		(net "P3E_CPU0_PE3_OCP_RXN<5>")
	)
	(segment
		(start 443.87897 -43.49496)
		(end 443.71387 -43.66006)
		(width 0.1143)
		(layer "In4.Cu")
		(net "P3E_CPU0_PE3_OCP_RXN<5>")
	)
	(segment
		(start 306.76342 -90.10777)
		(end 306.747926 -90.123264)
		(width 0.0889)
		(layer "In4.Cu")
		(net "P3E_CPU0_PE3_OCP_RXN<5>")
	)
	(segment
		(start 445.10706 -44.83735)
		(end 445.48171 -44.83735)
		(width 0.1143)
		(layer "In4.Cu")
		(net "P3E_CPU0_PE3_OCP_RXN<5>")
	)
	(segment
		(start 444.89497 -43.49496)
		(end 444.72987 -43.66006)
		(width 0.1143)
		(layer "In4.Cu")
		(net "P3E_CPU0_PE3_OCP_RXN<5>")
	)
	(segment
		(start 425.85132 -46.024292)
		(end 424.332654 -46.024292)
		(width 0.1143)
		(layer "In4.Cu")
		(net "P3E_CPU0_PE3_OCP_RXN<5>")
	)
	(segment
		(start 419.82898 -49.01692)
		(end 413.657542 -49.01692)
		(width 0.1143)
		(layer "In4.Cu")
		(net "P3E_CPU0_PE3_OCP_RXN<5>")
	)
	(segment
		(start 424.1673 -46.628558)
		(end 423.716958 -47.0789)
		(width 0.1143)
		(layer "In4.Cu")
		(net "P3E_CPU0_PE3_OCP_RXN<5>")
	)
	(segment
		(start 390.3472 -45.6184)
		(end 388.4168 -45.6184)
		(width 0.1143)
		(layer "In4.Cu")
		(net "P3E_CPU0_PE3_OCP_RXN<5>")
	)
	(segment
		(start 444.72987 -43.66006)
		(end 444.38697 -43.66006)
		(width 0.1143)
		(layer "In4.Cu")
		(net "P3E_CPU0_PE3_OCP_RXN<5>")
	)
	(segment
		(start 334.546448 -54.517036)
		(end 332.654656 -55.122826)
		(width 0.1143)
		(layer "In4.Cu")
		(net "P3E_CPU0_PE3_OCP_RXN<5>")
	)
	(segment
		(start 316.545976 -82.342736)
		(end 310.757062 -88.13165)
		(width 0.1143)
		(layer "In4.Cu")
		(net "P3E_CPU0_PE3_OCP_RXN<5>")
	)
	(segment
		(start 427.00321 -45.403008)
		(end 426.472604 -45.403008)
		(width 0.1143)
		(layer "In4.Cu")
		(net "P3E_CPU0_PE3_OCP_RXN<5>")
	)
	(segment
		(start 445.48171 -44.83735)
		(end 445.59601 -44.72305)
		(width 0.1143)
		(layer "In4.Cu")
		(net "P3E_CPU0_PE3_OCP_RXN<5>")
	)
	(segment
		(start 445.23787 -43.49496)
		(end 444.89497 -43.49496)
		(width 0.1143)
		(layer "In4.Cu")
		(net "P3E_CPU0_PE3_OCP_RXN<5>")
	)
	(segment
		(start 413.657542 -49.01692)
		(end 413.296862 -49.3776)
		(width 0.1143)
		(layer "In4.Cu")
		(net "P3E_CPU0_PE3_OCP_RXN<5>")
	)
	(segment
		(start 400.543522 -46.992286)
		(end 397.564356 -46.992286)
		(width 0.1143)
		(layer "In4.Cu")
		(net "P3E_CPU0_PE3_OCP_RXN<5>")
	)
	(segment
		(start 443.71387 -43.66006)
		(end 443.37097 -43.66006)
		(width 0.1143)
		(layer "In4.Cu")
		(net "P3E_CPU0_PE3_OCP_RXN<5>")
	)
	(segment
		(start 420.637716 -48.208184)
		(end 419.82898 -49.01692)
		(width 0.1143)
		(layer "In4.Cu")
		(net "P3E_CPU0_PE3_OCP_RXN<5>")
	)
	(segment
		(start 308.349142 -89.1286)
		(end 307.74259 -89.1286)
		(width 0.1143)
		(layer "In4.Cu")
		(net "P3E_CPU0_PE3_OCP_RXN<5>")
	)
	(segment
		(start 305.661822 -90.62466)
		(end 305.562762 -90.5256)
		(width 0.0889)
		(layer "In4.Cu")
		(net "P3E_CPU0_PE3_OCP_RXN<5>")
	)
	(segment
		(start 301.830486 -91.661488)
		(end 301.79772 -91.661488)
		(width 0.0889)
		(layer "In4.Cu")
		(net "P3E_CPU0_PE3_OCP_RXN<5>")
	)
	(segment
		(start 441.68187 -43.66006)
		(end 441.33897 -43.66006)
		(width 0.1143)
		(layer "In4.Cu")
		(net "P3E_CPU0_PE3_OCP_RXN<5>")
	)
	(segment
		(start 360.184954 -49.58588)
		(end 351.716848 -51.981862)
		(width 0.1143)
		(layer "In4.Cu")
		(net "P3E_CPU0_PE3_OCP_RXN<5>")
	)
	(segment
		(start 393.63523 -45.359574)
		(end 393.236196 -44.96054)
		(width 0.1143)
		(layer "In4.Cu")
		(net "P3E_CPU0_PE3_OCP_RXN<5>")
	)
	(segment
		(start 374.253252 -41.656)
		(end 373.080026 -40.482774)
		(width 0.1143)
		(layer "In4.Cu")
		(net "P3E_CPU0_PE3_OCP_RXN<5>")
	)
	(segment
		(start 394.24483 -45.359574)
		(end 393.63523 -45.359574)
		(width 0.1143)
		(layer "In4.Cu")
		(net "P3E_CPU0_PE3_OCP_RXN<5>")
	)
	(segment
		(start 295.45661 -94.737936)
		(end 295.46296 -94.748604)
		(width 0.0889)
		(layer "In4.Cu")
		(net "P3E_CPU0_PE3_OCP_RXN<5>")
	)
	(segment
		(start 297.176952 -93.341444)
		(end 297.17365 -93.347286)
		(width 0.0889)
		(layer "In4.Cu")
		(net "P3E_CPU0_PE3_OCP_RXN<5>")
	)
	(segment
		(start 304.409856 -91.165934)
		(end 304.37709 -91.165934)
		(width 0.0889)
		(layer "In4.Cu")
		(net "P3E_CPU0_PE3_OCP_RXN<5>")
	)
	(segment
		(start 380.611634 -43.687492)
		(end 380.218442 -43.2943)
		(width 0.1143)
		(layer "In4.Cu")
		(net "P3E_CPU0_PE3_OCP_RXN<5>")
	)
	(segment
		(start 442.86297 -43.49496)
		(end 442.69787 -43.66006)
		(width 0.1143)
		(layer "In4.Cu")
		(net "P3E_CPU0_PE3_OCP_RXN<5>")
	)
	(segment
		(start 394.986256 -46.101)
		(end 394.24483 -45.359574)
		(width 0.1143)
		(layer "In4.Cu")
		(net "P3E_CPU0_PE3_OCP_RXN<5>")
	)
	(segment
		(start 423.361358 -47.0789)
		(end 422.232074 -48.208184)
		(width 0.1143)
		(layer "In4.Cu")
		(net "P3E_CPU0_PE3_OCP_RXN<5>")
	)
	(segment
		(start 305.938682 -90.5256)
		(end 305.839622 -90.62466)
		(width 0.0889)
		(layer "In4.Cu")
		(net "P3E_CPU0_PE3_OCP_RXN<5>")
	)
	(segment
		(start 426.472604 -45.403008)
		(end 425.85132 -46.024292)
		(width 0.1143)
		(layer "In4.Cu")
		(net "P3E_CPU0_PE3_OCP_RXN<5>")
	)
	(segment
		(start 306.273454 -90.5256)
		(end 305.938682 -90.5256)
		(width 0.0889)
		(layer "In4.Cu")
		(net "P3E_CPU0_PE3_OCP_RXN<5>")
	)
	(segment
		(start 295.46296 -96.308418)
		(end 295.45661 -96.319086)
		(width 0.0889)
		(layer "In4.Cu")
		(net "P3E_CPU0_PE3_OCP_RXN<5>")
	)
	(segment
		(start 305.839622 -90.62466)
		(end 305.661822 -90.62466)
		(width 0.0889)
		(layer "In4.Cu")
		(net "P3E_CPU0_PE3_OCP_RXN<5>")
	)
	(segment
		(start 375.0564 -41.656)
		(end 374.253252 -41.656)
		(width 0.1143)
		(layer "In4.Cu")
		(net "P3E_CPU0_PE3_OCP_RXN<5>")
	)
	(segment
		(start 298.396406 -92.652088)
		(end 298.36364 -92.652088)
		(width 0.0889)
		(layer "In4.Cu")
		(net "P3E_CPU0_PE3_OCP_RXN<5>")
	)
	(segment
		(start 387.223 -44.4246)
		(end 387.003544 -44.4246)
		(width 0.1143)
		(layer "In4.Cu")
		(net "P3E_CPU0_PE3_OCP_RXN<5>")
	)
	(segment
		(start 396.67307 -46.101)
		(end 394.986256 -46.101)
		(width 0.1143)
		(layer "In4.Cu")
		(net "P3E_CPU0_PE3_OCP_RXN<5>")
	)
	(segment
		(start 441.33897 -43.66006)
		(end 441.17387 -43.49496)
		(width 0.1143)
		(layer "In4.Cu")
		(net "P3E_CPU0_PE3_OCP_RXN<5>")
	)
	(segment
		(start 391.00506 -44.96054)
		(end 390.3472 -45.6184)
		(width 0.1143)
		(layer "In4.Cu")
		(net "P3E_CPU0_PE3_OCP_RXN<5>")
	)
	(segment
		(start 367.317274 -44.204128)
		(end 365.230918 -46.290484)
		(width 0.1143)
		(layer "In4.Cu")
		(net "P3E_CPU0_PE3_OCP_RXN<5>")
	)
	(segment
		(start 332.654656 -55.122826)
		(end 331.452728 -55.918354)
		(width 0.1143)
		(layer "In4.Cu")
		(net "P3E_CPU0_PE3_OCP_RXN<5>")
	)
	(segment
		(start 295.45661 -96.319086)
		(end 295.451784 -96.327722)
		(width 0.0889)
		(layer "In4.Cu")
		(net "P3E_CPU0_PE3_OCP_RXN<5>")
	)
	(segment
		(start 365.230918 -46.290484)
		(end 360.184954 -49.58588)
		(width 0.1143)
		(layer "In4.Cu")
		(net "P3E_CPU0_PE3_OCP_RXN<5>")
	)
	(segment
		(start 407.296874 -49.3776)
		(end 405.967946 -48.048672)
		(width 0.1143)
		(layer "In4.Cu")
		(net "P3E_CPU0_PE3_OCP_RXN<5>")
	)
	(segment
		(start 331.452728 -55.918354)
		(end 321.495674 -70.392036)
		(width 0.1143)
		(layer "In4.Cu")
		(net "P3E_CPU0_PE3_OCP_RXN<5>")
	)
	(segment
		(start 321.495674 -70.392036)
		(end 316.545976 -82.342736)
		(width 0.1143)
		(layer "In4.Cu")
		(net "P3E_CPU0_PE3_OCP_RXN<5>")
	)
	(segment
		(start 422.232074 -48.208184)
		(end 420.637716 -48.208184)
		(width 0.1143)
		(layer "In4.Cu")
		(net "P3E_CPU0_PE3_OCP_RXN<5>")
	)
	(segment
		(start 305.384962 -90.5256)
		(end 305.102514 -90.642694)
		(width 0.0889)
		(layer "In4.Cu")
		(net "P3E_CPU0_PE3_OCP_RXN<5>")
	)
	(segment
		(start 295.788334 -96.919034)
		(end 295.8211 -96.919034)
		(width 0.0889)
		(layer "In4.Cu")
		(net "P3E_CPU0_PE3_OCP_RXN<5>")
	)
	(arc
		(start 295.8211 -96.919034)
		(mid 296.302811 -97.193643)
		(end 296.344848 -97.746566)
		(width 0.0889)
		(layer "In4.Cu")
		(net "P3E_CPU0_PE3_OCP_RXN<5>")
	)
	(arc
		(start 301.465996 -91.861386)
		(mid 301.258992 -92.07225)
		(end 300.975776 -92.156534)
		(width 0.0889)
		(layer "In4.Cu")
		(net "P3E_CPU0_PE3_OCP_RXN<5>")
	)
	(arc
		(start 304.041556 -91.366086)
		(mid 303.529746 -91.661753)
		(end 303.017936 -91.366086)
		(width 0.0889)
		(layer "In4.Cu")
		(net "P3E_CPU0_PE3_OCP_RXN<5>")
	)
	(arc
		(start 298.36364 -92.652088)
		(mid 298.171998 -92.709254)
		(end 298.031916 -92.851986)
		(width 0.0889)
		(layer "In4.Cu")
		(net "P3E_CPU0_PE3_OCP_RXN<5>")
	)
	(arc
		(start 296.646854 -93.642688)
		(mid 296.455212 -93.699854)
		(end 296.31513 -93.842586)
		(width 0.0889)
		(layer "In4.Cu")
		(net "P3E_CPU0_PE3_OCP_RXN<5>")
	)
	(arc
		(start 300.607476 -92.356686)
		(mid 300.095666 -92.652353)
		(end 299.583856 -92.356686)
		(width 0.0889)
		(layer "In4.Cu")
		(net "P3E_CPU0_PE3_OCP_RXN<5>")
	)
	(arc
		(start 301.79772 -91.661488)
		(mid 301.606078 -91.718654)
		(end 301.465996 -91.861386)
		(width 0.0889)
		(layer "In4.Cu")
		(net "P3E_CPU0_PE3_OCP_RXN<5>")
	)
	(arc
		(start 295.46296 -94.748604)
		(mid 295.535758 -95.039367)
		(end 295.45661 -95.328486)
		(width 0.0889)
		(layer "In4.Cu")
		(net "P3E_CPU0_PE3_OCP_RXN<5>")
	)
	(arc
		(start 295.45661 -95.728536)
		(mid 295.535832 -96.017654)
		(end 295.46296 -96.308418)
		(width 0.0889)
		(layer "In4.Cu")
		(net "P3E_CPU0_PE3_OCP_RXN<5>")
	)
	(arc
		(start 295.451784 -95.337122)
		(mid 295.403029 -95.533474)
		(end 295.45661 -95.728536)
		(width 0.0889)
		(layer "In4.Cu")
		(net "P3E_CPU0_PE3_OCP_RXN<5>")
	)
	(arc
		(start 298.031916 -92.851986)
		(mid 297.824912 -93.06285)
		(end 297.541696 -93.147134)
		(width 0.0889)
		(layer "In4.Cu")
		(net "P3E_CPU0_PE3_OCP_RXN<5>")
	)
	(arc
		(start 304.37709 -91.165934)
		(mid 304.18324 -91.222284)
		(end 304.041556 -91.366086)
		(width 0.0889)
		(layer "In4.Cu")
		(net "P3E_CPU0_PE3_OCP_RXN<5>")
	)
	(arc
		(start 303.017936 -91.366086)
		(mid 302.671226 -91.165775)
		(end 302.324516 -91.366086)
		(width 0.0889)
		(layer "In4.Cu")
		(net "P3E_CPU0_PE3_OCP_RXN<5>")
	)
	(arc
		(start 296.31513 -93.842586)
		(mid 296.104417 -94.055665)
		(end 295.816274 -94.137988)
		(width 0.0889)
		(layer "In4.Cu")
		(net "P3E_CPU0_PE3_OCP_RXN<5>")
	)
	(arc
		(start 302.324516 -91.366086)
		(mid 302.115908 -91.578018)
		(end 301.830486 -91.661488)
		(width 0.0889)
		(layer "In4.Cu")
		(net "P3E_CPU0_PE3_OCP_RXN<5>")
	)
	(arc
		(start 295.451784 -96.327722)
		(mid 295.455531 -96.716978)
		(end 295.788334 -96.919034)
		(width 0.0889)
		(layer "In4.Cu")
		(net "P3E_CPU0_PE3_OCP_RXN<5>")
	)
	(arc
		(start 300.94301 -92.156534)
		(mid 300.74916 -92.212884)
		(end 300.607476 -92.356686)
		(width 0.0889)
		(layer "In4.Cu")
		(net "P3E_CPU0_PE3_OCP_RXN<5>")
	)
	(arc
		(start 304.900076 -90.870786)
		(mid 304.693072 -91.08165)
		(end 304.409856 -91.165934)
		(width 0.0889)
		(layer "In4.Cu")
		(net "P3E_CPU0_PE3_OCP_RXN<5>")
	)
	(arc
		(start 297.520106 -93.147134)
		(mid 297.322945 -93.199093)
		(end 297.176952 -93.341444)
		(width 0.0889)
		(layer "In4.Cu")
		(net "P3E_CPU0_PE3_OCP_RXN<5>")
	)
	(arc
		(start 298.890436 -92.356686)
		(mid 298.681828 -92.568618)
		(end 298.396406 -92.652088)
		(width 0.0889)
		(layer "In4.Cu")
		(net "P3E_CPU0_PE3_OCP_RXN<5>")
	)
	(arc
		(start 295.792144 -94.137988)
		(mid 295.454029 -94.34269)
		(end 295.45661 -94.737936)
		(width 0.0889)
		(layer "In4.Cu")
		(net "P3E_CPU0_PE3_OCP_RXN<5>")
	)
	(arc
		(start 297.17365 -93.347286)
		(mid 296.965042 -93.559218)
		(end 296.67962 -93.642688)
		(width 0.0889)
		(layer "In4.Cu")
		(net "P3E_CPU0_PE3_OCP_RXN<5>")
	)
	(arc
		(start 299.583856 -92.356686)
		(mid 299.237146 -92.156375)
		(end 298.890436 -92.356686)
		(width 0.0889)
		(layer "In4.Cu")
		(net "P3E_CPU0_PE3_OCP_RXN<5>")
	)
	(segment
		(start 448.639946 -44.83735)
		(end 448.818 -45.015404)
		(width 0.1143)
		(layer "F.Cu")
		(net "P3E_CPU0_PE3_OCP_RXN<4>")
	)
	(segment
		(start 448.540886 -46.163484)
		(end 448.540886 -47.481998)
		(width 0.1143)
		(layer "F.Cu")
		(net "P3E_CPU0_PE3_OCP_RXN<4>")
	)
	(segment
		(start 448.818 -45.88637)
		(end 448.540886 -46.163484)
		(width 0.1143)
		(layer "F.Cu")
		(net "P3E_CPU0_PE3_OCP_RXN<4>")
	)
	(segment
		(start 448.818 -45.015404)
		(end 448.818 -45.88637)
		(width 0.1143)
		(layer "F.Cu")
		(net "P3E_CPU0_PE3_OCP_RXN<4>")
	)
	(segment
		(start 448.306952 -44.83735)
		(end 448.639946 -44.83735)
		(width 0.1143)
		(layer "F.Cu")
		(net "P3E_CPU0_PE3_OCP_RXN<4>")
	)
	(segment
		(start 294.3733 -98.005138)
		(end 294.9448 -98.005138)
		(width 0.1143)
		(layer "F.Cu")
		(net "P3E_CPU0_PE3_OCP_RXN<4>")
	)
	(via
		(at 448.306952 -44.83735)
		(size 0.508)
		(drill 0.254)
		(layers "F.Cu" "B.Cu")
		(net "P3E_CPU0_PE3_OCP_RXN<4>")
	)
	(via
		(at 294.9448 -98.005138)
		(size 0.508)
		(drill 0.254)
		(layers "F.Cu" "B.Cu")
		(net "P3E_CPU0_PE3_OCP_RXN<4>")
	)
	(segment
		(start 320.671444 -69.953378)
		(end 315.76772 -81.79308)
		(width 0.1143)
		(layer "In4.Cu")
		(net "P3E_CPU0_PE3_OCP_RXN<4>")
	)
	(segment
		(start 448.65925 -44.83735)
		(end 448.795902 -44.974002)
		(width 0.1143)
		(layer "In4.Cu")
		(net "P3E_CPU0_PE3_OCP_RXN<4>")
	)
	(segment
		(start 427.71822 -43.371008)
		(end 426.661326 -44.427902)
		(width 0.1143)
		(layer "In4.Cu")
		(net "P3E_CPU0_PE3_OCP_RXN<4>")
	)
	(segment
		(start 421.598852 -47.27829)
		(end 420.201344 -47.27829)
		(width 0.1143)
		(layer "In4.Cu")
		(net "P3E_CPU0_PE3_OCP_RXN<4>")
	)
	(segment
		(start 428.569882 -42.0243)
		(end 427.71822 -42.875962)
		(width 0.1143)
		(layer "In4.Cu")
		(net "P3E_CPU0_PE3_OCP_RXN<4>")
	)
	(segment
		(start 393.620752 -44.03344)
		(end 388.143496 -44.03344)
		(width 0.1143)
		(layer "In4.Cu")
		(net "P3E_CPU0_PE3_OCP_RXN<4>")
	)
	(segment
		(start 359.59542 -48.781716)
		(end 351.442782 -51.029616)
		(width 0.1143)
		(layer "In4.Cu")
		(net "P3E_CPU0_PE3_OCP_RXN<4>")
	)
	(segment
		(start 381.09525 -42.760392)
		(end 380.678436 -42.343578)
		(width 0.1143)
		(layer "In4.Cu")
		(net "P3E_CPU0_PE3_OCP_RXN<4>")
	)
	(segment
		(start 398.438116 -44.92498)
		(end 398.259554 -45.103542)
		(width 0.1143)
		(layer "In4.Cu")
		(net "P3E_CPU0_PE3_OCP_RXN<4>")
	)
	(segment
		(start 366.323118 -42.96537)
		(end 362.25099 -47.037498)
		(width 0.1143)
		(layer "In4.Cu")
		(net "P3E_CPU0_PE3_OCP_RXN<4>")
	)
	(segment
		(start 308.937406 -87.821262)
		(end 308.93639 -87.821516)
		(width 0.0889)
		(layer "In4.Cu")
		(net "P3E_CPU0_PE3_OCP_RXN<4>")
	)
	(segment
		(start 413.615886 -48.08982)
		(end 413.272986 -48.08982)
		(width 0.1143)
		(layer "In4.Cu")
		(net "P3E_CPU0_PE3_OCP_RXN<4>")
	)
	(segment
		(start 448.795902 -45.84954)
		(end 448.531742 -46.1137)
		(width 0.1143)
		(layer "In4.Cu")
		(net "P3E_CPU0_PE3_OCP_RXN<4>")
	)
	(segment
		(start 308.989476 -87.749634)
		(end 308.968648 -87.757)
		(width 0.0889)
		(layer "In4.Cu")
		(net "P3E_CPU0_PE3_OCP_RXN<4>")
	)
	(segment
		(start 340.817962 -53.969666)
		(end 340.438232 -53.589936)
		(width 0.1143)
		(layer "In4.Cu")
		(net "P3E_CPU0_PE3_OCP_RXN<4>")
	)
	(segment
		(start 419.389814 -48.08982)
		(end 415.304986 -48.08982)
		(width 0.1143)
		(layer "In4.Cu")
		(net "P3E_CPU0_PE3_OCP_RXN<4>")
	)
	(segment
		(start 332.147672 -54.306724)
		(end 330.840588 -55.171848)
		(width 0.1143)
		(layer "In4.Cu")
		(net "P3E_CPU0_PE3_OCP_RXN<4>")
	)
	(segment
		(start 387.3881 -43.4975)
		(end 386.650992 -42.760392)
		(width 0.1143)
		(layer "In4.Cu")
		(net "P3E_CPU0_PE3_OCP_RXN<4>")
	)
	(segment
		(start 412.912306 -48.4505)
		(end 407.702766 -48.4505)
		(width 0.1143)
		(layer "In4.Cu")
		(net "P3E_CPU0_PE3_OCP_RXN<4>")
	)
	(segment
		(start 426.661326 -44.427902)
		(end 426.113194 -44.427902)
		(width 0.1143)
		(layer "In4.Cu")
		(net "P3E_CPU0_PE3_OCP_RXN<4>")
	)
	(segment
		(start 301.827184 -90.480388)
		(end 301.791116 -90.480388)
		(width 0.0889)
		(layer "In4.Cu")
		(net "P3E_CPU0_PE3_OCP_RXN<4>")
	)
	(segment
		(start 347.311472 -53.969666)
		(end 340.817962 -53.969666)
		(width 0.1143)
		(layer "In4.Cu")
		(net "P3E_CPU0_PE3_OCP_RXN<4>")
	)
	(segment
		(start 423.774362 -45.164756)
		(end 423.774108 -45.16501)
		(width 0.1143)
		(layer "In4.Cu")
		(net "P3E_CPU0_PE3_OCP_RXN<4>")
	)
	(segment
		(start 448.795902 -44.974002)
		(end 448.795902 -45.84954)
		(width 0.1143)
		(layer "In4.Cu")
		(net "P3E_CPU0_PE3_OCP_RXN<4>")
	)
	(segment
		(start 398.259554 -45.103542)
		(end 395.300454 -45.103542)
		(width 0.1143)
		(layer "In4.Cu")
		(net "P3E_CPU0_PE3_OCP_RXN<4>")
	)
	(segment
		(start 304.588672 -89.984834)
		(end 304.37455 -89.984834)
		(width 0.0889)
		(layer "In4.Cu")
		(net "P3E_CPU0_PE3_OCP_RXN<4>")
	)
	(segment
		(start 377.125992 -42.342054)
		(end 375.482358 -40.69842)
		(width 0.1143)
		(layer "In4.Cu")
		(net "P3E_CPU0_PE3_OCP_RXN<4>")
	)
	(segment
		(start 388.143496 -44.03344)
		(end 387.607556 -43.4975)
		(width 0.1143)
		(layer "In4.Cu")
		(net "P3E_CPU0_PE3_OCP_RXN<4>")
	)
	(segment
		(start 447.5861 -45.827442)
		(end 447.5861 -43.414442)
		(width 0.1143)
		(layer "In4.Cu")
		(net "P3E_CPU0_PE3_OCP_RXN<4>")
	)
	(segment
		(start 430.187608 -42.80535)
		(end 429.406558 -42.0243)
		(width 0.1143)
		(layer "In4.Cu")
		(net "P3E_CPU0_PE3_OCP_RXN<4>")
	)
	(segment
		(start 375.482358 -40.69842)
		(end 374.607328 -40.69842)
		(width 0.1143)
		(layer "In4.Cu")
		(net "P3E_CPU0_PE3_OCP_RXN<4>")
	)
	(segment
		(start 309.996078 -87.395558)
		(end 308.989476 -87.749634)
		(width 0.1143)
		(layer "In4.Cu")
		(net "P3E_CPU0_PE3_OCP_RXN<4>")
	)
	(segment
		(start 296.66184 -92.461588)
		(end 296.64025 -92.461588)
		(width 0.0889)
		(layer "In4.Cu")
		(net "P3E_CPU0_PE3_OCP_RXN<4>")
	)
	(segment
		(start 415.139886 -47.92472)
		(end 414.796986 -47.92472)
		(width 0.1143)
		(layer "In4.Cu")
		(net "P3E_CPU0_PE3_OCP_RXN<4>")
	)
	(segment
		(start 380.678436 -42.343578)
		(end 379.875796 -42.343578)
		(width 0.1143)
		(layer "In4.Cu")
		(net "P3E_CPU0_PE3_OCP_RXN<4>")
	)
	(segment
		(start 422.6941 -46.183042)
		(end 421.598852 -47.27829)
		(width 0.1143)
		(layer "In4.Cu")
		(net "P3E_CPU0_PE3_OCP_RXN<4>")
	)
	(segment
		(start 399.94078 -44.92498)
		(end 398.438116 -44.92498)
		(width 0.1143)
		(layer "In4.Cu")
		(net "P3E_CPU0_PE3_OCP_RXN<4>")
	)
	(segment
		(start 305.801014 -89.5985)
		(end 304.975006 -89.5985)
		(width 0.0889)
		(layer "In4.Cu")
		(net "P3E_CPU0_PE3_OCP_RXN<4>")
	)
	(segment
		(start 304.975006 -89.5985)
		(end 304.588672 -89.984834)
		(width 0.0889)
		(layer "In4.Cu")
		(net "P3E_CPU0_PE3_OCP_RXN<4>")
	)
	(segment
		(start 386.650992 -42.760392)
		(end 381.09525 -42.760392)
		(width 0.1143)
		(layer "In4.Cu")
		(net "P3E_CPU0_PE3_OCP_RXN<4>")
	)
	(segment
		(start 294.879522 -97.601786)
		(end 294.9448 -97.667064)
		(width 0.0889)
		(layer "In4.Cu")
		(net "P3E_CPU0_PE3_OCP_RXN<4>")
	)
	(segment
		(start 435.427882 -42.56786)
		(end 435.190392 -42.80535)
		(width 0.1143)
		(layer "In4.Cu")
		(net "P3E_CPU0_PE3_OCP_RXN<4>")
	)
	(segment
		(start 297.535092 -91.966034)
		(end 297.502326 -91.966034)
		(width 0.0889)
		(layer "In4.Cu")
		(net "P3E_CPU0_PE3_OCP_RXN<4>")
	)
	(segment
		(start 414.288986 -48.08982)
		(end 414.123886 -47.92472)
		(width 0.1143)
		(layer "In4.Cu")
		(net "P3E_CPU0_PE3_OCP_RXN<4>")
	)
	(segment
		(start 308.968648 -87.757)
		(end 308.937406 -87.821262)
		(width 0.0889)
		(layer "In4.Cu")
		(net "P3E_CPU0_PE3_OCP_RXN<4>")
	)
	(segment
		(start 308.93639 -87.821516)
		(end 308.93639 -87.82177)
		(width 0.0889)
		(layer "In4.Cu")
		(net "P3E_CPU0_PE3_OCP_RXN<4>")
	)
	(segment
		(start 334.391254 -53.589936)
		(end 332.147672 -54.306724)
		(width 0.1143)
		(layer "In4.Cu")
		(net "P3E_CPU0_PE3_OCP_RXN<4>")
	)
	(segment
		(start 447.5861 -43.414442)
		(end 446.739518 -42.56786)
		(width 0.1143)
		(layer "In4.Cu")
		(net "P3E_CPU0_PE3_OCP_RXN<4>")
	)
	(segment
		(start 435.190392 -42.80535)
		(end 430.187608 -42.80535)
		(width 0.1143)
		(layer "In4.Cu")
		(net "P3E_CPU0_PE3_OCP_RXN<4>")
	)
	(segment
		(start 297.008296 -92.261436)
		(end 297.004994 -92.267278)
		(width 0.0889)
		(layer "In4.Cu")
		(net "P3E_CPU0_PE3_OCP_RXN<4>")
	)
	(segment
		(start 429.406558 -42.0243)
		(end 428.569882 -42.0243)
		(width 0.1143)
		(layer "In4.Cu")
		(net "P3E_CPU0_PE3_OCP_RXN<4>")
	)
	(segment
		(start 366.323118 -41.30548)
		(end 366.323118 -42.96537)
		(width 0.1143)
		(layer "In4.Cu")
		(net "P3E_CPU0_PE3_OCP_RXN<4>")
	)
	(segment
		(start 310.480964 -87.079836)
		(end 309.996078 -87.395558)
		(width 0.1143)
		(layer "In4.Cu")
		(net "P3E_CPU0_PE3_OCP_RXN<4>")
	)
	(segment
		(start 415.304986 -48.08982)
		(end 415.139886 -47.92472)
		(width 0.1143)
		(layer "In4.Cu")
		(net "P3E_CPU0_PE3_OCP_RXN<4>")
	)
	(segment
		(start 294.43299 -95.328486)
		(end 294.437816 -95.337122)
		(width 0.0889)
		(layer "In4.Cu")
		(net "P3E_CPU0_PE3_OCP_RXN<4>")
	)
	(segment
		(start 395.300454 -45.103542)
		(end 394.629386 -44.432474)
		(width 0.1143)
		(layer "In4.Cu")
		(net "P3E_CPU0_PE3_OCP_RXN<4>")
	)
	(segment
		(start 294.43299 -94.737936)
		(end 294.42664 -94.748604)
		(width 0.0889)
		(layer "In4.Cu")
		(net "P3E_CPU0_PE3_OCP_RXN<4>")
	)
	(segment
		(start 308.93639 -87.82177)
		(end 308.819042 -87.863172)
		(width 0.0889)
		(layer "In4.Cu")
		(net "P3E_CPU0_PE3_OCP_RXN<4>")
	)
	(segment
		(start 362.25099 -47.037498)
		(end 359.59542 -48.781716)
		(width 0.1143)
		(layer "In4.Cu")
		(net "P3E_CPU0_PE3_OCP_RXN<4>")
	)
	(segment
		(start 374.607328 -40.69842)
		(end 373.464582 -39.555674)
		(width 0.1143)
		(layer "In4.Cu")
		(net "P3E_CPU0_PE3_OCP_RXN<4>")
	)
	(segment
		(start 402.125942 -47.110142)
		(end 399.94078 -44.92498)
		(width 0.1143)
		(layer "In4.Cu")
		(net "P3E_CPU0_PE3_OCP_RXN<4>")
	)
	(segment
		(start 294.9448 -97.667064)
		(end 294.9448 -98.005138)
		(width 0.0889)
		(layer "In4.Cu")
		(net "P3E_CPU0_PE3_OCP_RXN<4>")
	)
	(segment
		(start 295.818306 -92.956634)
		(end 295.78554 -92.956634)
		(width 0.0889)
		(layer "In4.Cu")
		(net "P3E_CPU0_PE3_OCP_RXN<4>")
	)
	(segment
		(start 294.955976 -93.452188)
		(end 294.92321 -93.452188)
		(width 0.0889)
		(layer "In4.Cu")
		(net "P3E_CPU0_PE3_OCP_RXN<4>")
	)
	(segment
		(start 406.362408 -47.110142)
		(end 402.125942 -47.110142)
		(width 0.1143)
		(layer "In4.Cu")
		(net "P3E_CPU0_PE3_OCP_RXN<4>")
	)
	(segment
		(start 294.42664 -96.308418)
		(end 294.43299 -96.319086)
		(width 0.0889)
		(layer "In4.Cu")
		(net "P3E_CPU0_PE3_OCP_RXN<4>")
	)
	(segment
		(start 448.531742 -46.1137)
		(end 447.872358 -46.1137)
		(width 0.1143)
		(layer "In4.Cu")
		(net "P3E_CPU0_PE3_OCP_RXN<4>")
	)
	(segment
		(start 394.019786 -44.432474)
		(end 393.620752 -44.03344)
		(width 0.1143)
		(layer "In4.Cu")
		(net "P3E_CPU0_PE3_OCP_RXN<4>")
	)
	(segment
		(start 387.607556 -43.4975)
		(end 387.3881 -43.4975)
		(width 0.1143)
		(layer "In4.Cu")
		(net "P3E_CPU0_PE3_OCP_RXN<4>")
	)
	(segment
		(start 340.438232 -53.589936)
		(end 334.391254 -53.589936)
		(width 0.1143)
		(layer "In4.Cu")
		(net "P3E_CPU0_PE3_OCP_RXN<4>")
	)
	(segment
		(start 315.76772 -81.79308)
		(end 310.480964 -87.079836)
		(width 0.1143)
		(layer "In4.Cu")
		(net "P3E_CPU0_PE3_OCP_RXN<4>")
	)
	(segment
		(start 425.37634 -45.164756)
		(end 423.774362 -45.164756)
		(width 0.1143)
		(layer "In4.Cu")
		(net "P3E_CPU0_PE3_OCP_RXN<4>")
	)
	(segment
		(start 308.21122 -88.095582)
		(end 307.303932 -88.095582)
		(width 0.0889)
		(layer "In4.Cu")
		(net "P3E_CPU0_PE3_OCP_RXN<4>")
	)
	(segment
		(start 379.874272 -42.342054)
		(end 377.125992 -42.342054)
		(width 0.1143)
		(layer "In4.Cu")
		(net "P3E_CPU0_PE3_OCP_RXN<4>")
	)
	(segment
		(start 423.774108 -45.16501)
		(end 423.508932 -45.16501)
		(width 0.1143)
		(layer "In4.Cu")
		(net "P3E_CPU0_PE3_OCP_RXN<4>")
	)
	(segment
		(start 307.303932 -88.095582)
		(end 305.801014 -89.5985)
		(width 0.0889)
		(layer "In4.Cu")
		(net "P3E_CPU0_PE3_OCP_RXN<4>")
	)
	(segment
		(start 426.113194 -44.427902)
		(end 425.37634 -45.164756)
		(width 0.1143)
		(layer "In4.Cu")
		(net "P3E_CPU0_PE3_OCP_RXN<4>")
	)
	(segment
		(start 302.68545 -89.984834)
		(end 302.657002 -89.984834)
		(width 0.0889)
		(layer "In4.Cu")
		(net "P3E_CPU0_PE3_OCP_RXN<4>")
	)
	(segment
		(start 298.389802 -91.470988)
		(end 298.357036 -91.470988)
		(width 0.0889)
		(layer "In4.Cu")
		(net "P3E_CPU0_PE3_OCP_RXN<4>")
	)
	(segment
		(start 379.875796 -42.343578)
		(end 379.874272 -42.342054)
		(width 0.1143)
		(layer "In4.Cu")
		(net "P3E_CPU0_PE3_OCP_RXN<4>")
	)
	(segment
		(start 414.123886 -47.92472)
		(end 413.780986 -47.92472)
		(width 0.1143)
		(layer "In4.Cu")
		(net "P3E_CPU0_PE3_OCP_RXN<4>")
	)
	(segment
		(start 330.840588 -55.171848)
		(end 320.671444 -69.953378)
		(width 0.1143)
		(layer "In4.Cu")
		(net "P3E_CPU0_PE3_OCP_RXN<4>")
	)
	(segment
		(start 427.71822 -42.875962)
		(end 427.71822 -43.371008)
		(width 0.1143)
		(layer "In4.Cu")
		(net "P3E_CPU0_PE3_OCP_RXN<4>")
	)
	(segment
		(start 394.629386 -44.432474)
		(end 394.019786 -44.432474)
		(width 0.1143)
		(layer "In4.Cu")
		(net "P3E_CPU0_PE3_OCP_RXN<4>")
	)
	(segment
		(start 368.072924 -39.555674)
		(end 366.323118 -41.30548)
		(width 0.1143)
		(layer "In4.Cu")
		(net "P3E_CPU0_PE3_OCP_RXN<4>")
	)
	(segment
		(start 351.442782 -51.029616)
		(end 347.311472 -53.969666)
		(width 0.1143)
		(layer "In4.Cu")
		(net "P3E_CPU0_PE3_OCP_RXN<4>")
	)
	(segment
		(start 414.796986 -47.92472)
		(end 414.631886 -48.08982)
		(width 0.1143)
		(layer "In4.Cu")
		(net "P3E_CPU0_PE3_OCP_RXN<4>")
	)
	(segment
		(start 300.969172 -90.975434)
		(end 300.936406 -90.975434)
		(width 0.0889)
		(layer "In4.Cu")
		(net "P3E_CPU0_PE3_OCP_RXN<4>")
	)
	(segment
		(start 423.508932 -45.16501)
		(end 422.6941 -45.979842)
		(width 0.1143)
		(layer "In4.Cu")
		(net "P3E_CPU0_PE3_OCP_RXN<4>")
	)
	(segment
		(start 446.739518 -42.56786)
		(end 435.427882 -42.56786)
		(width 0.1143)
		(layer "In4.Cu")
		(net "P3E_CPU0_PE3_OCP_RXN<4>")
	)
	(segment
		(start 422.6941 -45.979842)
		(end 422.6941 -46.183042)
		(width 0.1143)
		(layer "In4.Cu")
		(net "P3E_CPU0_PE3_OCP_RXN<4>")
	)
	(segment
		(start 294.43299 -96.319086)
		(end 294.437816 -96.327722)
		(width 0.0889)
		(layer "In4.Cu")
		(net "P3E_CPU0_PE3_OCP_RXN<4>")
	)
	(segment
		(start 447.872358 -46.1137)
		(end 447.5861 -45.827442)
		(width 0.1143)
		(layer "In4.Cu")
		(net "P3E_CPU0_PE3_OCP_RXN<4>")
	)
	(segment
		(start 308.819042 -87.863172)
		(end 308.21122 -88.095582)
		(width 0.0889)
		(layer "In4.Cu")
		(net "P3E_CPU0_PE3_OCP_RXN<4>")
	)
	(segment
		(start 373.464582 -39.555674)
		(end 368.072924 -39.555674)
		(width 0.1143)
		(layer "In4.Cu")
		(net "P3E_CPU0_PE3_OCP_RXN<4>")
	)
	(segment
		(start 407.702766 -48.4505)
		(end 406.362408 -47.110142)
		(width 0.1143)
		(layer "In4.Cu")
		(net "P3E_CPU0_PE3_OCP_RXN<4>")
	)
	(segment
		(start 413.272986 -48.08982)
		(end 412.912306 -48.4505)
		(width 0.1143)
		(layer "In4.Cu")
		(net "P3E_CPU0_PE3_OCP_RXN<4>")
	)
	(segment
		(start 420.201344 -47.27829)
		(end 419.389814 -48.08982)
		(width 0.1143)
		(layer "In4.Cu")
		(net "P3E_CPU0_PE3_OCP_RXN<4>")
	)
	(segment
		(start 448.306952 -44.83735)
		(end 448.65925 -44.83735)
		(width 0.1143)
		(layer "In4.Cu")
		(net "P3E_CPU0_PE3_OCP_RXN<4>")
	)
	(segment
		(start 414.631886 -48.08982)
		(end 414.288986 -48.08982)
		(width 0.1143)
		(layer "In4.Cu")
		(net "P3E_CPU0_PE3_OCP_RXN<4>")
	)
	(segment
		(start 413.780986 -47.92472)
		(end 413.615886 -48.08982)
		(width 0.1143)
		(layer "In4.Cu")
		(net "P3E_CPU0_PE3_OCP_RXN<4>")
	)
	(arc
		(start 299.748956 -91.270836)
		(mid 299.237146 -90.975169)
		(end 298.725336 -91.270836)
		(width 0.0889)
		(layer "In4.Cu")
		(net "P3E_CPU0_PE3_OCP_RXN<4>")
	)
	(arc
		(start 296.15003 -92.756736)
		(mid 296.009951 -92.899472)
		(end 295.818306 -92.956634)
		(width 0.0889)
		(layer "In4.Cu")
		(net "P3E_CPU0_PE3_OCP_RXN<4>")
	)
	(arc
		(start 298.357036 -91.470988)
		(mid 298.073819 -91.555269)
		(end 297.866816 -91.766136)
		(width 0.0889)
		(layer "In4.Cu")
		(net "P3E_CPU0_PE3_OCP_RXN<4>")
	)
	(arc
		(start 300.442376 -91.270836)
		(mid 300.095666 -91.471147)
		(end 299.748956 -91.270836)
		(width 0.0889)
		(layer "In4.Cu")
		(net "P3E_CPU0_PE3_OCP_RXN<4>")
	)
	(arc
		(start 294.43299 -95.728536)
		(mid 294.353768 -96.017654)
		(end 294.42664 -96.308418)
		(width 0.0889)
		(layer "In4.Cu")
		(net "P3E_CPU0_PE3_OCP_RXN<4>")
	)
	(arc
		(start 297.004994 -92.267278)
		(mid 296.859028 -92.409677)
		(end 296.66184 -92.461588)
		(width 0.0889)
		(layer "In4.Cu")
		(net "P3E_CPU0_PE3_OCP_RXN<4>")
	)
	(arc
		(start 294.43299 -94.33814)
		(mid 294.486489 -94.538038)
		(end 294.43299 -94.737936)
		(width 0.0889)
		(layer "In4.Cu")
		(net "P3E_CPU0_PE3_OCP_RXN<4>")
	)
	(arc
		(start 302.159416 -90.280236)
		(mid 302.019148 -90.423192)
		(end 301.827184 -90.480388)
		(width 0.0889)
		(layer "In4.Cu")
		(net "P3E_CPU0_PE3_OCP_RXN<4>")
	)
	(arc
		(start 294.42664 -94.748604)
		(mid 294.353842 -95.039367)
		(end 294.43299 -95.328486)
		(width 0.0889)
		(layer "In4.Cu")
		(net "P3E_CPU0_PE3_OCP_RXN<4>")
	)
	(arc
		(start 300.936406 -90.975434)
		(mid 300.650982 -91.058901)
		(end 300.442376 -91.270836)
		(width 0.0889)
		(layer "In4.Cu")
		(net "P3E_CPU0_PE3_OCP_RXN<4>")
	)
	(arc
		(start 294.437816 -96.327722)
		(mid 294.486571 -96.524074)
		(end 294.43299 -96.719136)
		(width 0.0889)
		(layer "In4.Cu")
		(net "P3E_CPU0_PE3_OCP_RXN<4>")
	)
	(arc
		(start 294.92321 -93.452188)
		(mid 294.427733 -93.756631)
		(end 294.43299 -94.33814)
		(width 0.0889)
		(layer "In4.Cu")
		(net "P3E_CPU0_PE3_OCP_RXN<4>")
	)
	(arc
		(start 297.502326 -91.966034)
		(mid 297.216902 -92.049501)
		(end 297.008296 -92.261436)
		(width 0.0889)
		(layer "In4.Cu")
		(net "P3E_CPU0_PE3_OCP_RXN<4>")
	)
	(arc
		(start 301.300896 -90.775536)
		(mid 301.160817 -90.918272)
		(end 300.969172 -90.975434)
		(width 0.0889)
		(layer "In4.Cu")
		(net "P3E_CPU0_PE3_OCP_RXN<4>")
	)
	(arc
		(start 301.791116 -90.480388)
		(mid 301.507899 -90.564669)
		(end 301.300896 -90.775536)
		(width 0.0889)
		(layer "In4.Cu")
		(net "P3E_CPU0_PE3_OCP_RXN<4>")
	)
	(arc
		(start 294.43299 -96.719136)
		(mid 294.417485 -97.281278)
		(end 294.879522 -97.601786)
		(width 0.0889)
		(layer "In4.Cu")
		(net "P3E_CPU0_PE3_OCP_RXN<4>")
	)
	(arc
		(start 302.657002 -89.984834)
		(mid 302.369598 -90.067474)
		(end 302.159416 -90.280236)
		(width 0.0889)
		(layer "In4.Cu")
		(net "P3E_CPU0_PE3_OCP_RXN<4>")
	)
	(arc
		(start 303.183036 -90.280236)
		(mid 302.972901 -90.067394)
		(end 302.68545 -89.984834)
		(width 0.0889)
		(layer "In4.Cu")
		(net "P3E_CPU0_PE3_OCP_RXN<4>")
	)
	(arc
		(start 298.725336 -91.270836)
		(mid 298.583653 -91.41464)
		(end 298.389802 -91.470988)
		(width 0.0889)
		(layer "In4.Cu")
		(net "P3E_CPU0_PE3_OCP_RXN<4>")
	)
	(arc
		(start 295.78554 -92.956634)
		(mid 295.500116 -93.040101)
		(end 295.29151 -93.252036)
		(width 0.0889)
		(layer "In4.Cu")
		(net "P3E_CPU0_PE3_OCP_RXN<4>")
	)
	(arc
		(start 297.866816 -91.766136)
		(mid 297.726737 -91.908872)
		(end 297.535092 -91.966034)
		(width 0.0889)
		(layer "In4.Cu")
		(net "P3E_CPU0_PE3_OCP_RXN<4>")
	)
	(arc
		(start 294.437816 -95.337122)
		(mid 294.486571 -95.533474)
		(end 294.43299 -95.728536)
		(width 0.0889)
		(layer "In4.Cu")
		(net "P3E_CPU0_PE3_OCP_RXN<4>")
	)
	(arc
		(start 295.29151 -93.252036)
		(mid 295.149827 -93.39584)
		(end 294.955976 -93.452188)
		(width 0.0889)
		(layer "In4.Cu")
		(net "P3E_CPU0_PE3_OCP_RXN<4>")
	)
	(arc
		(start 303.876456 -90.280236)
		(mid 303.529746 -90.480547)
		(end 303.183036 -90.280236)
		(width 0.0889)
		(layer "In4.Cu")
		(net "P3E_CPU0_PE3_OCP_RXN<4>")
	)
	(arc
		(start 304.37455 -89.984834)
		(mid 304.086863 -90.067355)
		(end 303.876456 -90.280236)
		(width 0.0889)
		(layer "In4.Cu")
		(net "P3E_CPU0_PE3_OCP_RXN<4>")
	)
	(arc
		(start 296.64025 -92.461588)
		(mid 296.357033 -92.545869)
		(end 296.15003 -92.756736)
		(width 0.0889)
		(layer "In4.Cu")
		(net "P3E_CPU0_PE3_OCP_RXN<4>")
	)
	(segment
		(start 452.542148 -46.205902)
		(end 452.247 -45.910754)
		(width 0.1143)
		(layer "F.Cu")
		(net "P3E_CPU0_PE3_OCP_RXN<3>")
	)
	(segment
		(start 452.247 -45.034454)
		(end 452.444104 -44.83735)
		(width 0.1143)
		(layer "F.Cu")
		(net "P3E_CPU0_PE3_OCP_RXN<3>")
	)
	(segment
		(start 452.247 -45.910754)
		(end 452.247 -45.034454)
		(width 0.1143)
		(layer "F.Cu")
		(net "P3E_CPU0_PE3_OCP_RXN<3>")
	)
	(segment
		(start 452.444104 -44.83735)
		(end 452.777098 -44.83735)
		(width 0.1143)
		(layer "F.Cu")
		(net "P3E_CPU0_PE3_OCP_RXN<3>")
	)
	(segment
		(start 452.541132 -47.481998)
		(end 452.542148 -47.481998)
		(width 0.1143)
		(layer "F.Cu")
		(net "P3E_CPU0_PE3_OCP_RXN<3>")
	)
	(segment
		(start 452.542148 -47.481998)
		(end 452.542148 -46.205902)
		(width 0.1143)
		(layer "F.Cu")
		(net "P3E_CPU0_PE3_OCP_RXN<3>")
	)
	(segment
		(start 291.79774 -98.500184)
		(end 292.36924 -98.500184)
		(width 0.1143)
		(layer "F.Cu")
		(net "P3E_CPU0_PE3_OCP_RXN<3>")
	)
	(via
		(at 452.777098 -44.83735)
		(size 0.508)
		(drill 0.254)
		(layers "F.Cu" "B.Cu")
		(net "P3E_CPU0_PE3_OCP_RXN<3>")
	)
	(via
		(at 292.36924 -98.500184)
		(size 0.508)
		(drill 0.254)
		(layers "F.Cu" "B.Cu")
		(net "P3E_CPU0_PE3_OCP_RXN<3>")
	)
	(segment
		(start 424.5356 -50.564288)
		(end 424.5356 -49.714658)
		(width 0.1143)
		(layer "In4.Cu")
		(net "P3E_CPU0_PE3_OCP_RXN<3>")
	)
	(segment
		(start 296.646854 -98.595688)
		(end 296.67962 -98.595688)
		(width 0.0889)
		(layer "In4.Cu")
		(net "P3E_CPU0_PE3_OCP_RXN<3>")
	)
	(segment
		(start 452.288148 -46.313852)
		(end 452.288148 -44.951904)
		(width 0.1143)
		(layer "In4.Cu")
		(net "P3E_CPU0_PE3_OCP_RXN<3>")
	)
	(segment
		(start 434.555392 -48.330866)
		(end 434.83022 -48.330866)
		(width 0.1143)
		(layer "In4.Cu")
		(net "P3E_CPU0_PE3_OCP_RXN<3>")
	)
	(segment
		(start 390.90854 -49.266602)
		(end 391.019538 -49.3776)
		(width 0.1143)
		(layer "In4.Cu")
		(net "P3E_CPU0_PE3_OCP_RXN<3>")
	)
	(segment
		(start 386.473954 -46.469554)
		(end 389.271002 -49.266602)
		(width 0.1143)
		(layer "In4.Cu")
		(net "P3E_CPU0_PE3_OCP_RXN<3>")
	)
	(segment
		(start 428.306484 -50.423318)
		(end 428.306738 -50.423572)
		(width 0.1143)
		(layer "In4.Cu")
		(net "P3E_CPU0_PE3_OCP_RXN<3>")
	)
	(segment
		(start 428.5488 -50.423318)
		(end 432.46294 -50.423318)
		(width 0.1143)
		(layer "In4.Cu")
		(net "P3E_CPU0_PE3_OCP_RXN<3>")
	)
	(segment
		(start 399.753582 -49.826418)
		(end 400.936714 -51.00955)
		(width 0.1143)
		(layer "In4.Cu")
		(net "P3E_CPU0_PE3_OCP_RXN<3>")
	)
	(segment
		(start 301.794672 -94.633288)
		(end 301.834296 -94.633288)
		(width 0.0889)
		(layer "In4.Cu")
		(net "P3E_CPU0_PE3_OCP_RXN<3>")
	)
	(segment
		(start 386.077206 -46.469554)
		(end 386.473954 -46.469554)
		(width 0.1143)
		(layer "In4.Cu")
		(net "P3E_CPU0_PE3_OCP_RXN<3>")
	)
	(segment
		(start 428.306738 -50.423572)
		(end 428.548546 -50.423572)
		(width 0.1143)
		(layer "In4.Cu")
		(net "P3E_CPU0_PE3_OCP_RXN<3>")
	)
	(segment
		(start 374.50268 -47.781464)
		(end 380.152402 -47.781464)
		(width 0.1143)
		(layer "In4.Cu")
		(net "P3E_CPU0_PE3_OCP_RXN<3>")
	)
	(segment
		(start 370.482368 -46.953424)
		(end 373.67464 -46.953424)
		(width 0.1143)
		(layer "In4.Cu")
		(net "P3E_CPU0_PE3_OCP_RXN<3>")
	)
	(segment
		(start 380.394464 -47.781718)
		(end 381.960882 -46.2153)
		(width 0.1143)
		(layer "In4.Cu")
		(net "P3E_CPU0_PE3_OCP_RXN<3>")
	)
	(segment
		(start 354.269802 -54.066186)
		(end 356.467156 -54.564026)
		(width 0.1143)
		(layer "In4.Cu")
		(net "P3E_CPU0_PE3_OCP_RXN<3>")
	)
	(segment
		(start 427.64075 -49.473358)
		(end 427.64075 -50.019204)
		(width 0.1143)
		(layer "In4.Cu")
		(net "P3E_CPU0_PE3_OCP_RXN<3>")
	)
	(segment
		(start 428.548546 -50.423572)
		(end 428.5488 -50.423318)
		(width 0.1143)
		(layer "In4.Cu")
		(net "P3E_CPU0_PE3_OCP_RXN<3>")
	)
	(segment
		(start 309.257954 -92.366846)
		(end 318.259968 -83.364832)
		(width 0.1143)
		(layer "In4.Cu")
		(net "P3E_CPU0_PE3_OCP_RXN<3>")
	)
	(segment
		(start 356.467156 -54.564026)
		(end 358.389174 -53.918866)
		(width 0.1143)
		(layer "In4.Cu")
		(net "P3E_CPU0_PE3_OCP_RXN<3>")
	)
	(segment
		(start 368.927888 -48.507904)
		(end 370.482368 -46.953424)
		(width 0.1143)
		(layer "In4.Cu")
		(net "P3E_CPU0_PE3_OCP_RXN<3>")
	)
	(segment
		(start 298.36364 -96.614488)
		(end 298.396406 -96.614488)
		(width 0.0889)
		(layer "In4.Cu")
		(net "P3E_CPU0_PE3_OCP_RXN<3>")
	)
	(segment
		(start 373.67464 -46.953424)
		(end 374.50268 -47.781464)
		(width 0.1143)
		(layer "In4.Cu")
		(net "P3E_CPU0_PE3_OCP_RXN<3>")
	)
	(segment
		(start 358.389174 -53.918866)
		(end 361.212638 -51.909726)
		(width 0.1143)
		(layer "In4.Cu")
		(net "P3E_CPU0_PE3_OCP_RXN<3>")
	)
	(segment
		(start 405.835104 -51.00955)
		(end 407.237438 -52.411884)
		(width 0.1143)
		(layer "In4.Cu")
		(net "P3E_CPU0_PE3_OCP_RXN<3>")
	)
	(segment
		(start 391.019538 -49.3776)
		(end 394.61567 -49.3776)
		(width 0.1143)
		(layer "In4.Cu")
		(net "P3E_CPU0_PE3_OCP_RXN<3>")
	)
	(segment
		(start 400.936714 -51.00955)
		(end 405.835104 -51.00955)
		(width 0.1143)
		(layer "In4.Cu")
		(net "P3E_CPU0_PE3_OCP_RXN<3>")
	)
	(segment
		(start 395.064488 -49.826418)
		(end 399.753582 -49.826418)
		(width 0.1143)
		(layer "In4.Cu")
		(net "P3E_CPU0_PE3_OCP_RXN<3>")
	)
	(segment
		(start 300.08068 -95.623888)
		(end 300.10862 -95.623888)
		(width 0.0889)
		(layer "In4.Cu")
		(net "P3E_CPU0_PE3_OCP_RXN<3>")
	)
	(segment
		(start 303.508156 -94.633288)
		(end 303.551336 -94.633288)
		(width 0.0889)
		(layer "In4.Cu")
		(net "P3E_CPU0_PE3_OCP_RXN<3>")
	)
	(segment
		(start 304.254154 -94.151704)
		(end 304.664364 -93.981778)
		(width 0.0889)
		(layer "In4.Cu")
		(net "P3E_CPU0_PE3_OCP_RXN<3>")
	)
	(segment
		(start 299.22597 -96.118934)
		(end 299.258736 -96.118934)
		(width 0.0889)
		(layer "In4.Cu")
		(net "P3E_CPU0_PE3_OCP_RXN<3>")
	)
	(segment
		(start 305.72075 -93.981778)
		(end 306.988972 -93.458792)
		(width 0.0889)
		(layer "In4.Cu")
		(net "P3E_CPU0_PE3_OCP_RXN<3>")
	)
	(segment
		(start 307.075586 -93.478096)
		(end 308.44109 -92.912946)
		(width 0.1143)
		(layer "In4.Cu")
		(net "P3E_CPU0_PE3_OCP_RXN<3>")
	)
	(segment
		(start 452.288148 -44.951904)
		(end 452.402702 -44.83735)
		(width 0.1143)
		(layer "In4.Cu")
		(net "P3E_CPU0_PE3_OCP_RXN<3>")
	)
	(segment
		(start 452.402702 -44.83735)
		(end 452.777098 -44.83735)
		(width 0.1143)
		(layer "In4.Cu")
		(net "P3E_CPU0_PE3_OCP_RXN<3>")
	)
	(segment
		(start 407.237438 -52.411884)
		(end 419.174422 -52.411884)
		(width 0.1143)
		(layer "In4.Cu")
		(net "P3E_CPU0_PE3_OCP_RXN<3>")
	)
	(segment
		(start 294.929814 -98.595688)
		(end 294.959786 -98.595688)
		(width 0.0889)
		(layer "In4.Cu")
		(net "P3E_CPU0_PE3_OCP_RXN<3>")
	)
	(segment
		(start 361.212638 -51.909726)
		(end 364.543086 -50.91684)
		(width 0.1143)
		(layer "In4.Cu")
		(net "P3E_CPU0_PE3_OCP_RXN<3>")
	)
	(segment
		(start 421.150796 -51.482244)
		(end 421.672004 -52.003452)
		(width 0.1143)
		(layer "In4.Cu")
		(net "P3E_CPU0_PE3_OCP_RXN<3>")
	)
	(segment
		(start 292.662356 -98.331274)
		(end 292.751764 -98.355404)
		(width 0.0889)
		(layer "In4.Cu")
		(net "P3E_CPU0_PE3_OCP_RXN<3>")
	)
	(segment
		(start 385.822952 -46.2153)
		(end 386.077206 -46.469554)
		(width 0.1143)
		(layer "In4.Cu")
		(net "P3E_CPU0_PE3_OCP_RXN<3>")
	)
	(segment
		(start 451.235318 -47.366682)
		(end 452.288148 -46.313852)
		(width 0.1143)
		(layer "In4.Cu")
		(net "P3E_CPU0_PE3_OCP_RXN<3>")
	)
	(segment
		(start 389.271002 -49.266602)
		(end 390.90854 -49.266602)
		(width 0.1143)
		(layer "In4.Cu")
		(net "P3E_CPU0_PE3_OCP_RXN<3>")
	)
	(segment
		(start 435.794404 -47.366682)
		(end 451.235318 -47.366682)
		(width 0.1143)
		(layer "In4.Cu")
		(net "P3E_CPU0_PE3_OCP_RXN<3>")
	)
	(segment
		(start 304.664364 -93.981778)
		(end 305.72075 -93.981778)
		(width 0.0889)
		(layer "In4.Cu")
		(net "P3E_CPU0_PE3_OCP_RXN<3>")
	)
	(segment
		(start 380.152402 -47.781464)
		(end 380.152656 -47.781718)
		(width 0.1143)
		(layer "In4.Cu")
		(net "P3E_CPU0_PE3_OCP_RXN<3>")
	)
	(segment
		(start 420.104062 -51.482244)
		(end 421.150796 -51.482244)
		(width 0.1143)
		(layer "In4.Cu")
		(net "P3E_CPU0_PE3_OCP_RXN<3>")
	)
	(segment
		(start 308.44109 -92.912946)
		(end 309.257954 -92.366846)
		(width 0.1143)
		(layer "In4.Cu")
		(net "P3E_CPU0_PE3_OCP_RXN<3>")
	)
	(segment
		(start 419.174422 -52.411884)
		(end 420.104062 -51.482244)
		(width 0.1143)
		(layer "In4.Cu")
		(net "P3E_CPU0_PE3_OCP_RXN<3>")
	)
	(segment
		(start 295.78173 -99.090734)
		(end 295.82491 -99.090734)
		(width 0.0889)
		(layer "In4.Cu")
		(net "P3E_CPU0_PE3_OCP_RXN<3>")
	)
	(segment
		(start 432.46294 -50.423318)
		(end 434.555392 -48.330866)
		(width 0.1143)
		(layer "In4.Cu")
		(net "P3E_CPU0_PE3_OCP_RXN<3>")
	)
	(segment
		(start 350.775778 -56.396636)
		(end 353.991926 -54.121558)
		(width 0.1143)
		(layer "In4.Cu")
		(net "P3E_CPU0_PE3_OCP_RXN<3>")
	)
	(segment
		(start 427.407578 -49.240186)
		(end 427.64075 -49.473358)
		(width 0.1143)
		(layer "In4.Cu")
		(net "P3E_CPU0_PE3_OCP_RXN<3>")
	)
	(segment
		(start 427.64075 -50.019204)
		(end 428.044864 -50.423318)
		(width 0.1143)
		(layer "In4.Cu")
		(net "P3E_CPU0_PE3_OCP_RXN<3>")
	)
	(segment
		(start 307.055012 -93.486732)
		(end 307.075586 -93.478096)
		(width 0.0889)
		(layer "In4.Cu")
		(net "P3E_CPU0_PE3_OCP_RXN<3>")
	)
	(segment
		(start 293.20998 -98.595688)
		(end 293.242746 -98.595688)
		(width 0.0889)
		(layer "In4.Cu")
		(net "P3E_CPU0_PE3_OCP_RXN<3>")
	)
	(segment
		(start 424.5356 -49.714658)
		(end 425.010072 -49.240186)
		(width 0.1143)
		(layer "In4.Cu")
		(net "P3E_CPU0_PE3_OCP_RXN<3>")
	)
	(segment
		(start 381.960882 -46.2153)
		(end 385.822952 -46.2153)
		(width 0.1143)
		(layer "In4.Cu")
		(net "P3E_CPU0_PE3_OCP_RXN<3>")
	)
	(segment
		(start 366.951768 -48.507904)
		(end 368.927888 -48.507904)
		(width 0.1143)
		(layer "In4.Cu")
		(net "P3E_CPU0_PE3_OCP_RXN<3>")
	)
	(segment
		(start 348.577154 -57.134506)
		(end 350.775778 -56.396636)
		(width 0.1143)
		(layer "In4.Cu")
		(net "P3E_CPU0_PE3_OCP_RXN<3>")
	)
	(segment
		(start 364.543086 -50.91684)
		(end 366.951768 -48.507904)
		(width 0.1143)
		(layer "In4.Cu")
		(net "P3E_CPU0_PE3_OCP_RXN<3>")
	)
	(segment
		(start 323.328538 -71.126858)
		(end 332.782672 -57.382918)
		(width 0.1143)
		(layer "In4.Cu")
		(net "P3E_CPU0_PE3_OCP_RXN<3>")
	)
	(segment
		(start 306.988972 -93.458792)
		(end 307.055012 -93.486732)
		(width 0.0889)
		(layer "In4.Cu")
		(net "P3E_CPU0_PE3_OCP_RXN<3>")
	)
	(segment
		(start 394.61567 -49.3776)
		(end 395.064488 -49.826418)
		(width 0.1143)
		(layer "In4.Cu")
		(net "P3E_CPU0_PE3_OCP_RXN<3>")
	)
	(segment
		(start 318.259968 -83.364832)
		(end 323.328538 -71.126858)
		(width 0.1143)
		(layer "In4.Cu")
		(net "P3E_CPU0_PE3_OCP_RXN<3>")
	)
	(segment
		(start 297.520106 -97.109534)
		(end 297.541696 -97.109534)
		(width 0.0889)
		(layer "In4.Cu")
		(net "P3E_CPU0_PE3_OCP_RXN<3>")
	)
	(segment
		(start 353.991926 -54.121558)
		(end 354.269802 -54.066186)
		(width 0.1143)
		(layer "In4.Cu")
		(net "P3E_CPU0_PE3_OCP_RXN<3>")
	)
	(segment
		(start 332.782672 -57.382918)
		(end 333.158084 -57.134506)
		(width 0.1143)
		(layer "In4.Cu")
		(net "P3E_CPU0_PE3_OCP_RXN<3>")
	)
	(segment
		(start 421.672004 -52.003452)
		(end 423.096436 -52.003452)
		(width 0.1143)
		(layer "In4.Cu")
		(net "P3E_CPU0_PE3_OCP_RXN<3>")
	)
	(segment
		(start 425.010072 -49.240186)
		(end 427.407578 -49.240186)
		(width 0.1143)
		(layer "In4.Cu")
		(net "P3E_CPU0_PE3_OCP_RXN<3>")
	)
	(segment
		(start 380.152656 -47.781718)
		(end 380.394464 -47.781718)
		(width 0.1143)
		(layer "In4.Cu")
		(net "P3E_CPU0_PE3_OCP_RXN<3>")
	)
	(segment
		(start 292.36924 -98.500184)
		(end 292.662356 -98.331274)
		(width 0.0889)
		(layer "In4.Cu")
		(net "P3E_CPU0_PE3_OCP_RXN<3>")
	)
	(segment
		(start 294.06469 -99.090734)
		(end 294.10787 -99.090734)
		(width 0.0889)
		(layer "In4.Cu")
		(net "P3E_CPU0_PE3_OCP_RXN<3>")
	)
	(segment
		(start 333.158084 -57.134506)
		(end 348.577154 -57.134506)
		(width 0.1143)
		(layer "In4.Cu")
		(net "P3E_CPU0_PE3_OCP_RXN<3>")
	)
	(segment
		(start 428.044864 -50.423318)
		(end 428.306484 -50.423318)
		(width 0.1143)
		(layer "In4.Cu")
		(net "P3E_CPU0_PE3_OCP_RXN<3>")
	)
	(segment
		(start 434.83022 -48.330866)
		(end 435.794404 -47.366682)
		(width 0.1143)
		(layer "In4.Cu")
		(net "P3E_CPU0_PE3_OCP_RXN<3>")
	)
	(segment
		(start 300.936152 -95.128588)
		(end 300.971966 -95.128588)
		(width 0.0889)
		(layer "In4.Cu")
		(net "P3E_CPU0_PE3_OCP_RXN<3>")
	)
	(segment
		(start 423.096436 -52.003452)
		(end 424.5356 -50.564288)
		(width 0.1143)
		(layer "In4.Cu")
		(net "P3E_CPU0_PE3_OCP_RXN<3>")
	)
	(arc
		(start 292.751764 -98.355404)
		(mid 292.953174 -98.528357)
		(end 293.20998 -98.595688)
		(width 0.0889)
		(layer "In4.Cu")
		(net "P3E_CPU0_PE3_OCP_RXN<3>")
	)
	(arc
		(start 299.748956 -95.823786)
		(mid 299.889035 -95.68105)
		(end 300.08068 -95.623888)
		(width 0.0889)
		(layer "In4.Cu")
		(net "P3E_CPU0_PE3_OCP_RXN<3>")
	)
	(arc
		(start 298.396406 -96.614488)
		(mid 298.68183 -96.531021)
		(end 298.890436 -96.319086)
		(width 0.0889)
		(layer "In4.Cu")
		(net "P3E_CPU0_PE3_OCP_RXN<3>")
	)
	(arc
		(start 300.971966 -95.128588)
		(mid 301.25739 -95.045121)
		(end 301.465996 -94.833186)
		(width 0.0889)
		(layer "In4.Cu")
		(net "P3E_CPU0_PE3_OCP_RXN<3>")
	)
	(arc
		(start 304.041556 -94.33814)
		(mid 304.132452 -94.227355)
		(end 304.254154 -94.151704)
		(width 0.0889)
		(layer "In4.Cu")
		(net "P3E_CPU0_PE3_OCP_RXN<3>")
	)
	(arc
		(start 293.57447 -98.795586)
		(mid 293.781474 -99.00645)
		(end 294.06469 -99.090734)
		(width 0.0889)
		(layer "In4.Cu")
		(net "P3E_CPU0_PE3_OCP_RXN<3>")
	)
	(arc
		(start 298.031916 -96.814386)
		(mid 298.171995 -96.67165)
		(end 298.36364 -96.614488)
		(width 0.0889)
		(layer "In4.Cu")
		(net "P3E_CPU0_PE3_OCP_RXN<3>")
	)
	(arc
		(start 293.242746 -98.595688)
		(mid 293.434388 -98.652854)
		(end 293.57447 -98.795586)
		(width 0.0889)
		(layer "In4.Cu")
		(net "P3E_CPU0_PE3_OCP_RXN<3>")
	)
	(arc
		(start 300.607476 -95.328486)
		(mid 300.74622 -95.186453)
		(end 300.936152 -95.128588)
		(width 0.0889)
		(layer "In4.Cu")
		(net "P3E_CPU0_PE3_OCP_RXN<3>")
	)
	(arc
		(start 294.959786 -98.595688)
		(mid 295.151428 -98.652854)
		(end 295.29151 -98.795586)
		(width 0.0889)
		(layer "In4.Cu")
		(net "P3E_CPU0_PE3_OCP_RXN<3>")
	)
	(arc
		(start 301.834296 -94.633288)
		(mid 302.117513 -94.549007)
		(end 302.324516 -94.33814)
		(width 0.0889)
		(layer "In4.Cu")
		(net "P3E_CPU0_PE3_OCP_RXN<3>")
	)
	(arc
		(start 294.10787 -99.090734)
		(mid 294.391087 -99.006453)
		(end 294.59809 -98.795586)
		(width 0.0889)
		(layer "In4.Cu")
		(net "P3E_CPU0_PE3_OCP_RXN<3>")
	)
	(arc
		(start 300.10862 -95.623888)
		(mid 300.396765 -95.541569)
		(end 300.607476 -95.328486)
		(width 0.0889)
		(layer "In4.Cu")
		(net "P3E_CPU0_PE3_OCP_RXN<3>")
	)
	(arc
		(start 295.82491 -99.090734)
		(mid 296.108127 -99.006453)
		(end 296.31513 -98.795586)
		(width 0.0889)
		(layer "In4.Cu")
		(net "P3E_CPU0_PE3_OCP_RXN<3>")
	)
	(arc
		(start 297.17365 -97.709482)
		(mid 297.173733 -97.309541)
		(end 297.520106 -97.109534)
		(width 0.0889)
		(layer "In4.Cu")
		(net "P3E_CPU0_PE3_OCP_RXN<3>")
	)
	(arc
		(start 295.29151 -98.795586)
		(mid 295.498514 -99.00645)
		(end 295.78173 -99.090734)
		(width 0.0889)
		(layer "In4.Cu")
		(net "P3E_CPU0_PE3_OCP_RXN<3>")
	)
	(arc
		(start 303.017936 -94.33814)
		(mid 303.22494 -94.549004)
		(end 303.508156 -94.633288)
		(width 0.0889)
		(layer "In4.Cu")
		(net "P3E_CPU0_PE3_OCP_RXN<3>")
	)
	(arc
		(start 301.465996 -94.833186)
		(mid 301.60474 -94.691153)
		(end 301.794672 -94.633288)
		(width 0.0889)
		(layer "In4.Cu")
		(net "P3E_CPU0_PE3_OCP_RXN<3>")
	)
	(arc
		(start 299.258736 -96.118934)
		(mid 299.541953 -96.034653)
		(end 299.748956 -95.823786)
		(width 0.0889)
		(layer "In4.Cu")
		(net "P3E_CPU0_PE3_OCP_RXN<3>")
	)
	(arc
		(start 296.67962 -98.595688)
		(mid 297.178141 -98.292804)
		(end 297.17365 -97.709482)
		(width 0.0889)
		(layer "In4.Cu")
		(net "P3E_CPU0_PE3_OCP_RXN<3>")
	)
	(arc
		(start 297.541696 -97.109534)
		(mid 297.824913 -97.025253)
		(end 298.031916 -96.814386)
		(width 0.0889)
		(layer "In4.Cu")
		(net "P3E_CPU0_PE3_OCP_RXN<3>")
	)
	(arc
		(start 303.551336 -94.633288)
		(mid 303.834553 -94.549007)
		(end 304.041556 -94.33814)
		(width 0.0889)
		(layer "In4.Cu")
		(net "P3E_CPU0_PE3_OCP_RXN<3>")
	)
	(arc
		(start 296.31513 -98.795586)
		(mid 296.455209 -98.65285)
		(end 296.646854 -98.595688)
		(width 0.0889)
		(layer "In4.Cu")
		(net "P3E_CPU0_PE3_OCP_RXN<3>")
	)
	(arc
		(start 294.59809 -98.795586)
		(mid 294.738169 -98.65285)
		(end 294.929814 -98.595688)
		(width 0.0889)
		(layer "In4.Cu")
		(net "P3E_CPU0_PE3_OCP_RXN<3>")
	)
	(arc
		(start 298.890436 -96.319086)
		(mid 299.032119 -96.175282)
		(end 299.22597 -96.118934)
		(width 0.0889)
		(layer "In4.Cu")
		(net "P3E_CPU0_PE3_OCP_RXN<3>")
	)
	(arc
		(start 302.324516 -94.33814)
		(mid 302.671226 -94.137829)
		(end 303.017936 -94.33814)
		(width 0.0889)
		(layer "In4.Cu")
		(net "P3E_CPU0_PE3_OCP_RXN<3>")
	)
	(segment
		(start 455.74204 -46.218094)
		(end 455.4347 -45.910754)
		(width 0.1143)
		(layer "F.Cu")
		(net "P3E_CPU0_PE3_OCP_RXN<2>")
	)
	(segment
		(start 455.4347 -44.970446)
		(end 455.567796 -44.83735)
		(width 0.1143)
		(layer "F.Cu")
		(net "P3E_CPU0_PE3_OCP_RXN<2>")
	)
	(segment
		(start 455.567796 -44.83735)
		(end 455.97699 -44.83735)
		(width 0.1143)
		(layer "F.Cu")
		(net "P3E_CPU0_PE3_OCP_RXN<2>")
	)
	(segment
		(start 294.3733 -99.986338)
		(end 294.9448 -99.986338)
		(width 0.1143)
		(layer "F.Cu")
		(net "P3E_CPU0_PE3_OCP_RXN<2>")
	)
	(segment
		(start 455.74204 -47.481998)
		(end 455.74204 -46.218094)
		(width 0.1143)
		(layer "F.Cu")
		(net "P3E_CPU0_PE3_OCP_RXN<2>")
	)
	(segment
		(start 455.4347 -45.910754)
		(end 455.4347 -44.970446)
		(width 0.1143)
		(layer "F.Cu")
		(net "P3E_CPU0_PE3_OCP_RXN<2>")
	)
	(segment
		(start 455.741024 -47.481998)
		(end 455.74204 -47.481998)
		(width 0.1143)
		(layer "F.Cu")
		(net "P3E_CPU0_PE3_OCP_RXN<2>")
	)
	(via
		(at 455.97699 -44.83735)
		(size 0.508)
		(drill 0.254)
		(layers "F.Cu" "B.Cu")
		(net "P3E_CPU0_PE3_OCP_RXN<2>")
	)
	(via
		(at 294.9448 -99.986338)
		(size 0.508)
		(drill 0.254)
		(layers "F.Cu" "B.Cu")
		(net "P3E_CPU0_PE3_OCP_RXN<2>")
	)
	(segment
		(start 306.215034 -95.024956)
		(end 306.37353 -94.86646)
		(width 0.0889)
		(layer "In4.Cu")
		(net "P3E_CPU0_PE3_OCP_RXN<2>")
	)
	(segment
		(start 361.460542 -52.572158)
		(end 364.963456 -51.572414)
		(width 0.1143)
		(layer "In4.Cu")
		(net "P3E_CPU0_PE3_OCP_RXN<2>")
	)
	(segment
		(start 387.549898 -48.466502)
		(end 387.549898 -49.4157)
		(width 0.1143)
		(layer "In4.Cu")
		(net "P3E_CPU0_PE3_OCP_RXN<2>")
	)
	(segment
		(start 323.928994 -71.375524)
		(end 333.19339 -57.90692)
		(width 0.1143)
		(layer "In4.Cu")
		(net "P3E_CPU0_PE3_OCP_RXN<2>")
	)
	(segment
		(start 305.50866 -95.623634)
		(end 305.71567 -95.416624)
		(width 0.0889)
		(layer "In4.Cu")
		(net "P3E_CPU0_PE3_OCP_RXN<2>")
	)
	(segment
		(start 306.37353 -94.758764)
		(end 306.499006 -94.633288)
		(width 0.0889)
		(layer "In4.Cu")
		(net "P3E_CPU0_PE3_OCP_RXN<2>")
	)
	(segment
		(start 307.617622 -94.684088)
		(end 307.854858 -94.684088)
		(width 0.1143)
		(layer "In4.Cu")
		(net "P3E_CPU0_PE3_OCP_RXN<2>")
	)
	(segment
		(start 436.238396 -51.1937)
		(end 439.234326 -48.19777)
		(width 0.1143)
		(layer "In4.Cu")
		(net "P3E_CPU0_PE3_OCP_RXN<2>")
	)
	(segment
		(start 374.484646 -48.837342)
		(end 374.90273 -48.419258)
		(width 0.1143)
		(layer "In4.Cu")
		(net "P3E_CPU0_PE3_OCP_RXN<2>")
	)
	(segment
		(start 386.18795 -47.104554)
		(end 387.549898 -48.466502)
		(width 0.1143)
		(layer "In4.Cu")
		(net "P3E_CPU0_PE3_OCP_RXN<2>")
	)
	(segment
		(start 294.9448 -99.986338)
		(end 294.651684 -99.817174)
		(width 0.0889)
		(layer "In4.Cu")
		(net "P3E_CPU0_PE3_OCP_RXN<2>")
	)
	(segment
		(start 455.48804 -46.49216)
		(end 455.48804 -44.951904)
		(width 0.1143)
		(layer "In4.Cu")
		(net "P3E_CPU0_PE3_OCP_RXN<2>")
	)
	(segment
		(start 305.823366 -95.416624)
		(end 305.981862 -95.258128)
		(width 0.0889)
		(layer "In4.Cu")
		(net "P3E_CPU0_PE3_OCP_RXN<2>")
	)
	(segment
		(start 382.251966 -46.8503)
		(end 385.559554 -46.8503)
		(width 0.1143)
		(layer "In4.Cu")
		(net "P3E_CPU0_PE3_OCP_RXN<2>")
	)
	(segment
		(start 356.496874 -55.32374)
		(end 358.57307 -54.627018)
		(width 0.1143)
		(layer "In4.Cu")
		(net "P3E_CPU0_PE3_OCP_RXN<2>")
	)
	(segment
		(start 355.969316 -55.32374)
		(end 356.496874 -55.32374)
		(width 0.1143)
		(layer "In4.Cu")
		(net "P3E_CPU0_PE3_OCP_RXN<2>")
	)
	(segment
		(start 455.48804 -44.951904)
		(end 455.602594 -44.83735)
		(width 0.1143)
		(layer "In4.Cu")
		(net "P3E_CPU0_PE3_OCP_RXN<2>")
	)
	(segment
		(start 294.929814 -99.586288)
		(end 294.959786 -99.586288)
		(width 0.0889)
		(layer "In4.Cu")
		(net "P3E_CPU0_PE3_OCP_RXN<2>")
	)
	(segment
		(start 367.39322 -49.142904)
		(end 368.934746 -49.142904)
		(width 0.1143)
		(layer "In4.Cu")
		(net "P3E_CPU0_PE3_OCP_RXN<2>")
	)
	(segment
		(start 392.96594 -52.2224)
		(end 394.895832 -52.2224)
		(width 0.1143)
		(layer "In4.Cu")
		(net "P3E_CPU0_PE3_OCP_RXN<2>")
	)
	(segment
		(start 298.038266 -98.215704)
		(end 298.031916 -98.205036)
		(width 0.0889)
		(layer "In4.Cu")
		(net "P3E_CPU0_PE3_OCP_RXN<2>")
	)
	(segment
		(start 306.107338 -95.024956)
		(end 306.215034 -95.024956)
		(width 0.0889)
		(layer "In4.Cu")
		(net "P3E_CPU0_PE3_OCP_RXN<2>")
	)
	(segment
		(start 385.813808 -47.104554)
		(end 386.18795 -47.104554)
		(width 0.1143)
		(layer "In4.Cu")
		(net "P3E_CPU0_PE3_OCP_RXN<2>")
	)
	(segment
		(start 380.440692 -48.419258)
		(end 380.440946 -48.419512)
		(width 0.1143)
		(layer "In4.Cu")
		(net "P3E_CPU0_PE3_OCP_RXN<2>")
	)
	(segment
		(start 300.94301 -96.118934)
		(end 300.975776 -96.118934)
		(width 0.0889)
		(layer "In4.Cu")
		(net "P3E_CPU0_PE3_OCP_RXN<2>")
	)
	(segment
		(start 302.653192 -95.128588)
		(end 302.68926 -95.128588)
		(width 0.0889)
		(layer "In4.Cu")
		(net "P3E_CPU0_PE3_OCP_RXN<2>")
	)
	(segment
		(start 417.158678 -53.046884)
		(end 419.43782 -53.046884)
		(width 0.1143)
		(layer "In4.Cu")
		(net "P3E_CPU0_PE3_OCP_RXN<2>")
	)
	(segment
		(start 426.391832 -51.867054)
		(end 427.065186 -51.1937)
		(width 0.1143)
		(layer "In4.Cu")
		(net "P3E_CPU0_PE3_OCP_RXN<2>")
	)
	(segment
		(start 368.934746 -49.142904)
		(end 369.464336 -49.672494)
		(width 0.1143)
		(layer "In4.Cu")
		(net "P3E_CPU0_PE3_OCP_RXN<2>")
	)
	(segment
		(start 387.549898 -49.4157)
		(end 388.0358 -49.901602)
		(width 0.1143)
		(layer "In4.Cu")
		(net "P3E_CPU0_PE3_OCP_RXN<2>")
	)
	(segment
		(start 300.08068 -96.614488)
		(end 300.113446 -96.614488)
		(width 0.0889)
		(layer "In4.Cu")
		(net "P3E_CPU0_PE3_OCP_RXN<2>")
	)
	(segment
		(start 380.682754 -48.419512)
		(end 382.251966 -46.8503)
		(width 0.1143)
		(layer "In4.Cu")
		(net "P3E_CPU0_PE3_OCP_RXN<2>")
	)
	(segment
		(start 388.0358 -49.901602)
		(end 390.645142 -49.901602)
		(width 0.1143)
		(layer "In4.Cu")
		(net "P3E_CPU0_PE3_OCP_RXN<2>")
	)
	(segment
		(start 307.544724 -94.633288)
		(end 307.595524 -94.684088)
		(width 0.0889)
		(layer "In4.Cu")
		(net "P3E_CPU0_PE3_OCP_RXN<2>")
	)
	(segment
		(start 421.37965 -52.63896)
		(end 423.359326 -52.63896)
		(width 0.1143)
		(layer "In4.Cu")
		(net "P3E_CPU0_PE3_OCP_RXN<2>")
	)
	(segment
		(start 305.981862 -95.258128)
		(end 305.981862 -95.150432)
		(width 0.0889)
		(layer "In4.Cu")
		(net "P3E_CPU0_PE3_OCP_RXN<2>")
	)
	(segment
		(start 407.025856 -53.0987)
		(end 414.381442 -53.0987)
		(width 0.1143)
		(layer "In4.Cu")
		(net "P3E_CPU0_PE3_OCP_RXN<2>")
	)
	(segment
		(start 380.440946 -48.419512)
		(end 380.682754 -48.419512)
		(width 0.1143)
		(layer "In4.Cu")
		(net "P3E_CPU0_PE3_OCP_RXN<2>")
	)
	(segment
		(start 306.499006 -94.633288)
		(end 307.544724 -94.633288)
		(width 0.0889)
		(layer "In4.Cu")
		(net "P3E_CPU0_PE3_OCP_RXN<2>")
	)
	(segment
		(start 307.854858 -94.684088)
		(end 318.813434 -83.726274)
		(width 0.1143)
		(layer "In4.Cu")
		(net "P3E_CPU0_PE3_OCP_RXN<2>")
	)
	(segment
		(start 306.37353 -94.86646)
		(end 306.37353 -94.758764)
		(width 0.0889)
		(layer "In4.Cu")
		(net "P3E_CPU0_PE3_OCP_RXN<2>")
	)
	(segment
		(start 305.246786 -95.623634)
		(end 305.50866 -95.623634)
		(width 0.0889)
		(layer "In4.Cu")
		(net "P3E_CPU0_PE3_OCP_RXN<2>")
	)
	(segment
		(start 405.571706 -51.64455)
		(end 407.025856 -53.0987)
		(width 0.1143)
		(layer "In4.Cu")
		(net "P3E_CPU0_PE3_OCP_RXN<2>")
	)
	(segment
		(start 297.17365 -99.290886)
		(end 297.176952 -99.285044)
		(width 0.0889)
		(layer "In4.Cu")
		(net "P3E_CPU0_PE3_OCP_RXN<2>")
	)
	(segment
		(start 318.813434 -83.726274)
		(end 323.928994 -71.375524)
		(width 0.1143)
		(layer "In4.Cu")
		(net "P3E_CPU0_PE3_OCP_RXN<2>")
	)
	(segment
		(start 439.234326 -48.19777)
		(end 453.78243 -48.19777)
		(width 0.1143)
		(layer "In4.Cu")
		(net "P3E_CPU0_PE3_OCP_RXN<2>")
	)
	(segment
		(start 390.645142 -49.901602)
		(end 392.96594 -52.2224)
		(width 0.1143)
		(layer "In4.Cu")
		(net "P3E_CPU0_PE3_OCP_RXN<2>")
	)
	(segment
		(start 423.359326 -52.63896)
		(end 424.131232 -51.867054)
		(width 0.1143)
		(layer "In4.Cu")
		(net "P3E_CPU0_PE3_OCP_RXN<2>")
	)
	(segment
		(start 374.90273 -48.419258)
		(end 380.440692 -48.419258)
		(width 0.1143)
		(layer "In4.Cu")
		(net "P3E_CPU0_PE3_OCP_RXN<2>")
	)
	(segment
		(start 400.673316 -51.64455)
		(end 405.571706 -51.64455)
		(width 0.1143)
		(layer "In4.Cu")
		(net "P3E_CPU0_PE3_OCP_RXN<2>")
	)
	(segment
		(start 394.895832 -52.2224)
		(end 395.80947 -51.308762)
		(width 0.1143)
		(layer "In4.Cu")
		(net "P3E_CPU0_PE3_OCP_RXN<2>")
	)
	(segment
		(start 348.678246 -57.770522)
		(end 355.969316 -55.32374)
		(width 0.1143)
		(layer "In4.Cu")
		(net "P3E_CPU0_PE3_OCP_RXN<2>")
	)
	(segment
		(start 294.651684 -99.817174)
		(end 294.630602 -99.738434)
		(width 0.0889)
		(layer "In4.Cu")
		(net "P3E_CPU0_PE3_OCP_RXN<2>")
	)
	(segment
		(start 416.39871 -53.806852)
		(end 417.158678 -53.046884)
		(width 0.1143)
		(layer "In4.Cu")
		(net "P3E_CPU0_PE3_OCP_RXN<2>")
	)
	(segment
		(start 298.36364 -97.605088)
		(end 298.396406 -97.605088)
		(width 0.0889)
		(layer "In4.Cu")
		(net "P3E_CPU0_PE3_OCP_RXN<2>")
	)
	(segment
		(start 453.78243 -48.19777)
		(end 455.48804 -46.49216)
		(width 0.1143)
		(layer "In4.Cu")
		(net "P3E_CPU0_PE3_OCP_RXN<2>")
	)
	(segment
		(start 385.559554 -46.8503)
		(end 385.813808 -47.104554)
		(width 0.1143)
		(layer "In4.Cu")
		(net "P3E_CPU0_PE3_OCP_RXN<2>")
	)
	(segment
		(start 372.067328 -48.837342)
		(end 374.484646 -48.837342)
		(width 0.1143)
		(layer "In4.Cu")
		(net "P3E_CPU0_PE3_OCP_RXN<2>")
	)
	(segment
		(start 333.19339 -57.90692)
		(end 333.400146 -57.770522)
		(width 0.1143)
		(layer "In4.Cu")
		(net "P3E_CPU0_PE3_OCP_RXN<2>")
	)
	(segment
		(start 304.370232 -95.128588)
		(end 304.4063 -95.128588)
		(width 0.0889)
		(layer "In4.Cu")
		(net "P3E_CPU0_PE3_OCP_RXN<2>")
	)
	(segment
		(start 371.232176 -49.672494)
		(end 372.067328 -48.837342)
		(width 0.1143)
		(layer "In4.Cu")
		(net "P3E_CPU0_PE3_OCP_RXN<2>")
	)
	(segment
		(start 364.963456 -51.572414)
		(end 367.39322 -49.142904)
		(width 0.1143)
		(layer "In4.Cu")
		(net "P3E_CPU0_PE3_OCP_RXN<2>")
	)
	(segment
		(start 420.344854 -52.13985)
		(end 420.88054 -52.13985)
		(width 0.1143)
		(layer "In4.Cu")
		(net "P3E_CPU0_PE3_OCP_RXN<2>")
	)
	(segment
		(start 414.381442 -53.0987)
		(end 415.089594 -53.806852)
		(width 0.1143)
		(layer "In4.Cu")
		(net "P3E_CPU0_PE3_OCP_RXN<2>")
	)
	(segment
		(start 298.031916 -98.205036)
		(end 298.02709 -98.1964)
		(width 0.0889)
		(layer "In4.Cu")
		(net "P3E_CPU0_PE3_OCP_RXN<2>")
	)
	(segment
		(start 305.981862 -95.150432)
		(end 306.107338 -95.024956)
		(width 0.0889)
		(layer "In4.Cu")
		(net "P3E_CPU0_PE3_OCP_RXN<2>")
	)
	(segment
		(start 299.22597 -97.109534)
		(end 299.258736 -97.109534)
		(width 0.0889)
		(layer "In4.Cu")
		(net "P3E_CPU0_PE3_OCP_RXN<2>")
	)
	(segment
		(start 297.520106 -99.090734)
		(end 297.541696 -99.090734)
		(width 0.0889)
		(layer "In4.Cu")
		(net "P3E_CPU0_PE3_OCP_RXN<2>")
	)
	(segment
		(start 301.79772 -95.623888)
		(end 301.82566 -95.623888)
		(width 0.0889)
		(layer "In4.Cu")
		(net "P3E_CPU0_PE3_OCP_RXN<2>")
	)
	(segment
		(start 455.602594 -44.83735)
		(end 455.97699 -44.83735)
		(width 0.1143)
		(layer "In4.Cu")
		(net "P3E_CPU0_PE3_OCP_RXN<2>")
	)
	(segment
		(start 358.57307 -54.627018)
		(end 361.460542 -52.572158)
		(width 0.1143)
		(layer "In4.Cu")
		(net "P3E_CPU0_PE3_OCP_RXN<2>")
	)
	(segment
		(start 424.131232 -51.867054)
		(end 426.391832 -51.867054)
		(width 0.1143)
		(layer "In4.Cu")
		(net "P3E_CPU0_PE3_OCP_RXN<2>")
	)
	(segment
		(start 307.595524 -94.684088)
		(end 307.617622 -94.684088)
		(width 0.0889)
		(layer "In4.Cu")
		(net "P3E_CPU0_PE3_OCP_RXN<2>")
	)
	(segment
		(start 296.646854 -99.586288)
		(end 296.67962 -99.586288)
		(width 0.0889)
		(layer "In4.Cu")
		(net "P3E_CPU0_PE3_OCP_RXN<2>")
	)
	(segment
		(start 420.88054 -52.13985)
		(end 421.37965 -52.63896)
		(width 0.1143)
		(layer "In4.Cu")
		(net "P3E_CPU0_PE3_OCP_RXN<2>")
	)
	(segment
		(start 415.089594 -53.806852)
		(end 416.39871 -53.806852)
		(width 0.1143)
		(layer "In4.Cu")
		(net "P3E_CPU0_PE3_OCP_RXN<2>")
	)
	(segment
		(start 369.464336 -49.672494)
		(end 371.232176 -49.672494)
		(width 0.1143)
		(layer "In4.Cu")
		(net "P3E_CPU0_PE3_OCP_RXN<2>")
	)
	(segment
		(start 305.71567 -95.416624)
		(end 305.823366 -95.416624)
		(width 0.0889)
		(layer "In4.Cu")
		(net "P3E_CPU0_PE3_OCP_RXN<2>")
	)
	(segment
		(start 395.80947 -51.308762)
		(end 400.337528 -51.308762)
		(width 0.1143)
		(layer "In4.Cu")
		(net "P3E_CPU0_PE3_OCP_RXN<2>")
	)
	(segment
		(start 427.065186 -51.1937)
		(end 436.238396 -51.1937)
		(width 0.1143)
		(layer "In4.Cu")
		(net "P3E_CPU0_PE3_OCP_RXN<2>")
	)
	(segment
		(start 419.43782 -53.046884)
		(end 420.344854 -52.13985)
		(width 0.1143)
		(layer "In4.Cu")
		(net "P3E_CPU0_PE3_OCP_RXN<2>")
	)
	(segment
		(start 400.337528 -51.308762)
		(end 400.673316 -51.64455)
		(width 0.1143)
		(layer "In4.Cu")
		(net "P3E_CPU0_PE3_OCP_RXN<2>")
	)
	(segment
		(start 333.400146 -57.770522)
		(end 348.678246 -57.770522)
		(width 0.1143)
		(layer "In4.Cu")
		(net "P3E_CPU0_PE3_OCP_RXN<2>")
	)
	(segment
		(start 305.233832 -95.623888)
		(end 305.232562 -95.623888)
		(width 0.0889)
		(layer "In4.Cu")
		(net "P3E_CPU0_PE3_OCP_RXN<2>")
	)
	(arc
		(start 294.630602 -99.738434)
		(mid 294.763483 -99.629451)
		(end 294.929814 -99.586288)
		(width 0.0889)
		(layer "In4.Cu")
		(net "P3E_CPU0_PE3_OCP_RXN<2>")
	)
	(arc
		(start 301.465996 -95.823786)
		(mid 301.606075 -95.68105)
		(end 301.79772 -95.623888)
		(width 0.0889)
		(layer "In4.Cu")
		(net "P3E_CPU0_PE3_OCP_RXN<2>")
	)
	(arc
		(start 295.781222 -100.081334)
		(mid 295.80332 -100.081747)
		(end 295.825418 -100.081334)
		(width 0.0889)
		(layer "In4.Cu")
		(net "P3E_CPU0_PE3_OCP_RXN<2>")
	)
	(arc
		(start 302.324516 -95.328486)
		(mid 302.46326 -95.186453)
		(end 302.653192 -95.128588)
		(width 0.0889)
		(layer "In4.Cu")
		(net "P3E_CPU0_PE3_OCP_RXN<2>")
	)
	(arc
		(start 295.825418 -100.081334)
		(mid 296.108354 -99.996938)
		(end 296.31513 -99.786186)
		(width 0.0889)
		(layer "In4.Cu")
		(net "P3E_CPU0_PE3_OCP_RXN<2>")
	)
	(arc
		(start 300.975776 -96.118934)
		(mid 301.258993 -96.034653)
		(end 301.465996 -95.823786)
		(width 0.0889)
		(layer "In4.Cu")
		(net "P3E_CPU0_PE3_OCP_RXN<2>")
	)
	(arc
		(start 296.31513 -99.786186)
		(mid 296.455209 -99.64345)
		(end 296.646854 -99.586288)
		(width 0.0889)
		(layer "In4.Cu")
		(net "P3E_CPU0_PE3_OCP_RXN<2>")
	)
	(arc
		(start 297.176952 -99.285044)
		(mid 297.322918 -99.142645)
		(end 297.520106 -99.090734)
		(width 0.0889)
		(layer "In4.Cu")
		(net "P3E_CPU0_PE3_OCP_RXN<2>")
	)
	(arc
		(start 305.232562 -95.623888)
		(mid 305.239673 -95.623698)
		(end 305.246786 -95.623634)
		(width 0.0889)
		(layer "In4.Cu")
		(net "P3E_CPU0_PE3_OCP_RXN<2>")
	)
	(arc
		(start 299.748956 -96.814386)
		(mid 299.889035 -96.67165)
		(end 300.08068 -96.614488)
		(width 0.0889)
		(layer "In4.Cu")
		(net "P3E_CPU0_PE3_OCP_RXN<2>")
	)
	(arc
		(start 298.396406 -97.605088)
		(mid 298.68183 -97.521621)
		(end 298.890436 -97.309686)
		(width 0.0889)
		(layer "In4.Cu")
		(net "P3E_CPU0_PE3_OCP_RXN<2>")
	)
	(arc
		(start 298.02709 -98.1964)
		(mid 298.030837 -97.807144)
		(end 298.36364 -97.605088)
		(width 0.0889)
		(layer "In4.Cu")
		(net "P3E_CPU0_PE3_OCP_RXN<2>")
	)
	(arc
		(start 304.041556 -95.328486)
		(mid 304.1803 -95.186453)
		(end 304.370232 -95.128588)
		(width 0.0889)
		(layer "In4.Cu")
		(net "P3E_CPU0_PE3_OCP_RXN<2>")
	)
	(arc
		(start 304.734976 -95.328486)
		(mid 304.945689 -95.541565)
		(end 305.233832 -95.623888)
		(width 0.0889)
		(layer "In4.Cu")
		(net "P3E_CPU0_PE3_OCP_RXN<2>")
	)
	(arc
		(start 295.29151 -99.786186)
		(mid 295.498297 -99.996919)
		(end 295.781222 -100.081334)
		(width 0.0889)
		(layer "In4.Cu")
		(net "P3E_CPU0_PE3_OCP_RXN<2>")
	)
	(arc
		(start 297.541696 -99.090734)
		(mid 298.034086 -98.791801)
		(end 298.038266 -98.215704)
		(width 0.0889)
		(layer "In4.Cu")
		(net "P3E_CPU0_PE3_OCP_RXN<2>")
	)
	(arc
		(start 303.017936 -95.328486)
		(mid 303.529746 -95.624025)
		(end 304.041556 -95.328486)
		(width 0.0889)
		(layer "In4.Cu")
		(net "P3E_CPU0_PE3_OCP_RXN<2>")
	)
	(arc
		(start 294.959786 -99.586288)
		(mid 295.151428 -99.643454)
		(end 295.29151 -99.786186)
		(width 0.0889)
		(layer "In4.Cu")
		(net "P3E_CPU0_PE3_OCP_RXN<2>")
	)
	(arc
		(start 301.82566 -95.623888)
		(mid 302.113805 -95.541569)
		(end 302.324516 -95.328486)
		(width 0.0889)
		(layer "In4.Cu")
		(net "P3E_CPU0_PE3_OCP_RXN<2>")
	)
	(arc
		(start 302.68926 -95.128588)
		(mid 302.879189 -95.186458)
		(end 303.017936 -95.328486)
		(width 0.0889)
		(layer "In4.Cu")
		(net "P3E_CPU0_PE3_OCP_RXN<2>")
	)
	(arc
		(start 300.113446 -96.614488)
		(mid 300.39887 -96.531021)
		(end 300.607476 -96.319086)
		(width 0.0889)
		(layer "In4.Cu")
		(net "P3E_CPU0_PE3_OCP_RXN<2>")
	)
	(arc
		(start 296.67962 -99.586288)
		(mid 296.965044 -99.502821)
		(end 297.17365 -99.290886)
		(width 0.0889)
		(layer "In4.Cu")
		(net "P3E_CPU0_PE3_OCP_RXN<2>")
	)
	(arc
		(start 298.890436 -97.309686)
		(mid 299.032119 -97.165882)
		(end 299.22597 -97.109534)
		(width 0.0889)
		(layer "In4.Cu")
		(net "P3E_CPU0_PE3_OCP_RXN<2>")
	)
	(arc
		(start 300.607476 -96.319086)
		(mid 300.749159 -96.175282)
		(end 300.94301 -96.118934)
		(width 0.0889)
		(layer "In4.Cu")
		(net "P3E_CPU0_PE3_OCP_RXN<2>")
	)
	(arc
		(start 299.258736 -97.109534)
		(mid 299.541953 -97.025253)
		(end 299.748956 -96.814386)
		(width 0.0889)
		(layer "In4.Cu")
		(net "P3E_CPU0_PE3_OCP_RXN<2>")
	)
	(arc
		(start 304.4063 -95.128588)
		(mid 304.596229 -95.186458)
		(end 304.734976 -95.328486)
		(width 0.0889)
		(layer "In4.Cu")
		(net "P3E_CPU0_PE3_OCP_RXN<2>")
	)
	(segment
		(start 458.662786 -45.81271)
		(end 458.662786 -45.018706)
		(width 0.1143)
		(layer "F.Cu")
		(net "P3E_CPU0_PE3_OCP_RXN<1>")
	)
	(segment
		(start 292.65626 -99.986338)
		(end 293.22776 -99.986338)
		(width 0.1143)
		(layer "F.Cu")
		(net "P3E_CPU0_PE3_OCP_RXN<1>")
	)
	(segment
		(start 458.940916 -47.481998)
		(end 458.942186 -47.480728)
		(width 0.1143)
		(layer "F.Cu")
		(net "P3E_CPU0_PE3_OCP_RXN<1>")
	)
	(segment
		(start 458.844142 -44.83735)
		(end 459.177136 -44.83735)
		(width 0.1143)
		(layer "F.Cu")
		(net "P3E_CPU0_PE3_OCP_RXN<1>")
	)
	(segment
		(start 458.662786 -45.018706)
		(end 458.844142 -44.83735)
		(width 0.1143)
		(layer "F.Cu")
		(net "P3E_CPU0_PE3_OCP_RXN<1>")
	)
	(segment
		(start 458.942186 -46.09211)
		(end 458.662786 -45.81271)
		(width 0.1143)
		(layer "F.Cu")
		(net "P3E_CPU0_PE3_OCP_RXN<1>")
	)
	(segment
		(start 458.942186 -47.480728)
		(end 458.942186 -46.09211)
		(width 0.1143)
		(layer "F.Cu")
		(net "P3E_CPU0_PE3_OCP_RXN<1>")
	)
	(via
		(at 293.22776 -99.986338)
		(size 0.508)
		(drill 0.254)
		(layers "F.Cu" "B.Cu")
		(net "P3E_CPU0_PE3_OCP_RXN<1>")
	)
	(via
		(at 459.177136 -44.83735)
		(size 0.508)
		(drill 0.254)
		(layers "F.Cu" "B.Cu")
		(net "P3E_CPU0_PE3_OCP_RXN<1>")
	)
	(segment
		(start 427.953678 -51.8287)
		(end 436.501794 -51.8287)
		(width 0.1143)
		(layer "In4.Cu")
		(net "P3E_CPU0_PE3_OCP_RXN<1>")
	)
	(segment
		(start 385.445 -48.0187)
		(end 386.187442 -48.0187)
		(width 0.1143)
		(layer "In4.Cu")
		(net "P3E_CPU0_PE3_OCP_RXN<1>")
	)
	(segment
		(start 304.827432 -96.442022)
		(end 304.81651 -96.4311)
		(width 0.0889)
		(layer "In4.Cu")
		(net "P3E_CPU0_PE3_OCP_RXN<1>")
	)
	(segment
		(start 297.17365 -100.28174)
		(end 297.176952 -100.275898)
		(width 0.0889)
		(layer "In4.Cu")
		(net "P3E_CPU0_PE3_OCP_RXN<1>")
	)
	(segment
		(start 414.922716 -54.593998)
		(end 416.728402 -54.593998)
		(width 0.1143)
		(layer "In4.Cu")
		(net "P3E_CPU0_PE3_OCP_RXN<1>")
	)
	(segment
		(start 385.123944 -48.339756)
		(end 385.445 -48.0187)
		(width 0.1143)
		(layer "In4.Cu")
		(net "P3E_CPU0_PE3_OCP_RXN<1>")
	)
	(segment
		(start 306.879498 -95.7961)
		(end 307.664358 -95.7961)
		(width 0.1143)
		(layer "In4.Cu")
		(net "P3E_CPU0_PE3_OCP_RXN<1>")
	)
	(segment
		(start 305.797712 -96.452182)
		(end 306.504594 -95.7453)
		(width 0.0889)
		(layer "In4.Cu")
		(net "P3E_CPU0_PE3_OCP_RXN<1>")
	)
	(segment
		(start 305.04638 -96.6597)
		(end 305.29657 -96.6597)
		(width 0.0889)
		(layer "In4.Cu")
		(net "P3E_CPU0_PE3_OCP_RXN<1>")
	)
	(segment
		(start 425.8183 -53.413914)
		(end 426.368464 -53.413914)
		(width 0.1143)
		(layer "In4.Cu")
		(net "P3E_CPU0_PE3_OCP_RXN<1>")
	)
	(segment
		(start 439.333132 -49.009554)
		(end 456.463146 -49.009554)
		(width 0.1143)
		(layer "In4.Cu")
		(net "P3E_CPU0_PE3_OCP_RXN<1>")
	)
	(segment
		(start 374.797828 -49.472342)
		(end 375.168922 -49.101248)
		(width 0.1143)
		(layer "In4.Cu")
		(net "P3E_CPU0_PE3_OCP_RXN<1>")
	)
	(segment
		(start 356.159054 -55.95874)
		(end 356.609904 -55.95874)
		(width 0.1143)
		(layer "In4.Cu")
		(net "P3E_CPU0_PE3_OCP_RXN<1>")
	)
	(segment
		(start 401.20824 -52.285138)
		(end 405.268938 -52.285138)
		(width 0.1143)
		(layer "In4.Cu")
		(net "P3E_CPU0_PE3_OCP_RXN<1>")
	)
	(segment
		(start 458.688186 -44.951904)
		(end 458.80274 -44.83735)
		(width 0.1143)
		(layer "In4.Cu")
		(net "P3E_CPU0_PE3_OCP_RXN<1>")
	)
	(segment
		(start 386.6769 -48.508158)
		(end 386.6769 -49.4411)
		(width 0.1143)
		(layer "In4.Cu")
		(net "P3E_CPU0_PE3_OCP_RXN<1>")
	)
	(segment
		(start 299.22597 -98.100134)
		(end 299.258736 -98.100134)
		(width 0.0889)
		(layer "In4.Cu")
		(net "P3E_CPU0_PE3_OCP_RXN<1>")
	)
	(segment
		(start 381.25781 -49.101248)
		(end 382.019302 -48.339756)
		(width 0.1143)
		(layer "In4.Cu")
		(net "P3E_CPU0_PE3_OCP_RXN<1>")
	)
	(segment
		(start 421.034464 -53.721508)
		(end 421.309546 -53.446426)
		(width 0.1143)
		(layer "In4.Cu")
		(net "P3E_CPU0_PE3_OCP_RXN<1>")
	)
	(segment
		(start 333.48803 -58.599578)
		(end 333.84871 -58.436256)
		(width 0.1143)
		(layer "In4.Cu")
		(net "P3E_CPU0_PE3_OCP_RXN<1>")
	)
	(segment
		(start 306.8574 -95.7961)
		(end 306.879498 -95.7961)
		(width 0.0889)
		(layer "In4.Cu")
		(net "P3E_CPU0_PE3_OCP_RXN<1>")
	)
	(segment
		(start 417.600892 -53.721508)
		(end 421.034464 -53.721508)
		(width 0.1143)
		(layer "In4.Cu")
		(net "P3E_CPU0_PE3_OCP_RXN<1>")
	)
	(segment
		(start 405.268938 -52.285138)
		(end 406.7175 -53.7337)
		(width 0.1143)
		(layer "In4.Cu")
		(net "P3E_CPU0_PE3_OCP_RXN<1>")
	)
	(segment
		(start 416.728402 -54.593998)
		(end 417.600892 -53.721508)
		(width 0.1143)
		(layer "In4.Cu")
		(net "P3E_CPU0_PE3_OCP_RXN<1>")
	)
	(segment
		(start 294.92321 -100.576888)
		(end 294.962834 -100.576888)
		(width 0.0889)
		(layer "In4.Cu")
		(net "P3E_CPU0_PE3_OCP_RXN<1>")
	)
	(segment
		(start 366.751616 -52.075588)
		(end 368.0206 -50.807112)
		(width 0.1143)
		(layer "In4.Cu")
		(net "P3E_CPU0_PE3_OCP_RXN<1>")
	)
	(segment
		(start 458.80274 -44.83735)
		(end 459.177136 -44.83735)
		(width 0.1143)
		(layer "In4.Cu")
		(net "P3E_CPU0_PE3_OCP_RXN<1>")
	)
	(segment
		(start 423.450258 -53.446426)
		(end 424.38447 -52.512214)
		(width 0.1143)
		(layer "In4.Cu")
		(net "P3E_CPU0_PE3_OCP_RXN<1>")
	)
	(segment
		(start 300.08068 -97.605088)
		(end 300.113446 -97.605088)
		(width 0.0889)
		(layer "In4.Cu")
		(net "P3E_CPU0_PE3_OCP_RXN<1>")
	)
	(segment
		(start 356.609904 -55.95874)
		(end 358.963976 -55.1688)
		(width 0.1143)
		(layer "In4.Cu")
		(net "P3E_CPU0_PE3_OCP_RXN<1>")
	)
	(segment
		(start 382.019302 -48.339756)
		(end 385.123944 -48.339756)
		(width 0.1143)
		(layer "In4.Cu")
		(net "P3E_CPU0_PE3_OCP_RXN<1>")
	)
	(segment
		(start 306.8066 -95.7453)
		(end 306.8574 -95.7961)
		(width 0.0889)
		(layer "In4.Cu")
		(net "P3E_CPU0_PE3_OCP_RXN<1>")
	)
	(segment
		(start 426.368464 -53.413914)
		(end 427.953678 -51.8287)
		(width 0.1143)
		(layer "In4.Cu")
		(net "P3E_CPU0_PE3_OCP_RXN<1>")
	)
	(segment
		(start 400.635724 -52.857654)
		(end 401.20824 -52.285138)
		(width 0.1143)
		(layer "In4.Cu")
		(net "P3E_CPU0_PE3_OCP_RXN<1>")
	)
	(segment
		(start 319.378838 -84.08162)
		(end 324.55231 -71.590662)
		(width 0.1143)
		(layer "In4.Cu")
		(net "P3E_CPU0_PE3_OCP_RXN<1>")
	)
	(segment
		(start 372.330726 -49.472342)
		(end 374.797828 -49.472342)
		(width 0.1143)
		(layer "In4.Cu")
		(net "P3E_CPU0_PE3_OCP_RXN<1>")
	)
	(segment
		(start 300.94301 -97.109534)
		(end 300.975776 -97.109534)
		(width 0.0889)
		(layer "In4.Cu")
		(net "P3E_CPU0_PE3_OCP_RXN<1>")
	)
	(segment
		(start 436.573422 -51.769264)
		(end 439.333132 -49.009554)
		(width 0.1143)
		(layer "In4.Cu")
		(net "P3E_CPU0_PE3_OCP_RXN<1>")
	)
	(segment
		(start 436.501794 -51.8287)
		(end 436.56123 -51.769264)
		(width 0.1143)
		(layer "In4.Cu")
		(net "P3E_CPU0_PE3_OCP_RXN<1>")
	)
	(segment
		(start 424.38447 -52.512214)
		(end 424.9166 -52.512214)
		(width 0.1143)
		(layer "In4.Cu")
		(net "P3E_CPU0_PE3_OCP_RXN<1>")
	)
	(segment
		(start 305.29657 -96.6597)
		(end 305.797712 -96.452182)
		(width 0.0889)
		(layer "In4.Cu")
		(net "P3E_CPU0_PE3_OCP_RXN<1>")
	)
	(segment
		(start 406.7175 -53.7337)
		(end 414.062418 -53.7337)
		(width 0.1143)
		(layer "In4.Cu")
		(net "P3E_CPU0_PE3_OCP_RXN<1>")
	)
	(segment
		(start 348.776544 -58.436256)
		(end 356.159054 -55.95874)
		(width 0.1143)
		(layer "In4.Cu")
		(net "P3E_CPU0_PE3_OCP_RXN<1>")
	)
	(segment
		(start 414.062418 -53.7337)
		(end 414.922716 -54.593998)
		(width 0.1143)
		(layer "In4.Cu")
		(net "P3E_CPU0_PE3_OCP_RXN<1>")
	)
	(segment
		(start 368.0206 -50.807112)
		(end 370.995956 -50.807112)
		(width 0.1143)
		(layer "In4.Cu")
		(net "P3E_CPU0_PE3_OCP_RXN<1>")
	)
	(segment
		(start 386.6769 -49.4411)
		(end 387.772402 -50.536602)
		(width 0.1143)
		(layer "In4.Cu")
		(net "P3E_CPU0_PE3_OCP_RXN<1>")
	)
	(segment
		(start 296.643806 -100.576888)
		(end 296.68343 -100.576888)
		(width 0.0889)
		(layer "In4.Cu")
		(net "P3E_CPU0_PE3_OCP_RXN<1>")
	)
	(segment
		(start 436.56123 -51.769264)
		(end 436.573422 -51.769264)
		(width 0.1143)
		(layer "In4.Cu")
		(net "P3E_CPU0_PE3_OCP_RXN<1>")
	)
	(segment
		(start 370.995956 -50.807112)
		(end 372.330726 -49.472342)
		(width 0.1143)
		(layer "In4.Cu")
		(net "P3E_CPU0_PE3_OCP_RXN<1>")
	)
	(segment
		(start 294.073326 -100.081588)
		(end 294.097456 -100.081588)
		(width 0.0889)
		(layer "In4.Cu")
		(net "P3E_CPU0_PE3_OCP_RXN<1>")
	)
	(segment
		(start 333.84871 -58.436256)
		(end 348.776544 -58.436256)
		(width 0.1143)
		(layer "In4.Cu")
		(net "P3E_CPU0_PE3_OCP_RXN<1>")
	)
	(segment
		(start 424.9166 -52.512214)
		(end 425.8183 -53.413914)
		(width 0.1143)
		(layer "In4.Cu")
		(net "P3E_CPU0_PE3_OCP_RXN<1>")
	)
	(segment
		(start 304.81651 -96.4311)
		(end 304.81651 -96.42983)
		(width 0.0889)
		(layer "In4.Cu")
		(net "P3E_CPU0_PE3_OCP_RXN<1>")
	)
	(segment
		(start 295.78554 -101.072188)
		(end 295.8211 -101.072188)
		(width 0.0889)
		(layer "In4.Cu")
		(net "P3E_CPU0_PE3_OCP_RXN<1>")
	)
	(segment
		(start 293.22776 -99.986338)
		(end 293.22776 -99.648264)
		(width 0.0889)
		(layer "In4.Cu")
		(net "P3E_CPU0_PE3_OCP_RXN<1>")
	)
	(segment
		(start 301.79772 -96.614488)
		(end 301.830486 -96.614488)
		(width 0.0889)
		(layer "In4.Cu")
		(net "P3E_CPU0_PE3_OCP_RXN<1>")
	)
	(segment
		(start 375.168922 -49.101248)
		(end 381.25781 -49.101248)
		(width 0.1143)
		(layer "In4.Cu")
		(net "P3E_CPU0_PE3_OCP_RXN<1>")
	)
	(segment
		(start 392.702796 -52.857654)
		(end 400.635724 -52.857654)
		(width 0.1143)
		(layer "In4.Cu")
		(net "P3E_CPU0_PE3_OCP_RXN<1>")
	)
	(segment
		(start 293.22776 -99.648264)
		(end 293.285672 -99.590352)
		(width 0.0889)
		(layer "In4.Cu")
		(net "P3E_CPU0_PE3_OCP_RXN<1>")
	)
	(segment
		(start 319.37833 -84.082636)
		(end 319.378838 -84.08162)
		(width 0.1143)
		(layer "In4.Cu")
		(net "P3E_CPU0_PE3_OCP_RXN<1>")
	)
	(segment
		(start 387.772402 -50.536602)
		(end 390.381744 -50.536602)
		(width 0.1143)
		(layer "In4.Cu")
		(net "P3E_CPU0_PE3_OCP_RXN<1>")
	)
	(segment
		(start 361.137962 -53.620924)
		(end 366.751616 -52.075588)
		(width 0.1143)
		(layer "In4.Cu")
		(net "P3E_CPU0_PE3_OCP_RXN<1>")
	)
	(segment
		(start 386.187442 -48.0187)
		(end 386.6769 -48.508158)
		(width 0.1143)
		(layer "In4.Cu")
		(net "P3E_CPU0_PE3_OCP_RXN<1>")
	)
	(segment
		(start 421.309546 -53.446426)
		(end 423.450258 -53.446426)
		(width 0.1143)
		(layer "In4.Cu")
		(net "P3E_CPU0_PE3_OCP_RXN<1>")
	)
	(segment
		(start 456.463146 -49.009554)
		(end 458.688186 -46.784514)
		(width 0.1143)
		(layer "In4.Cu")
		(net "P3E_CPU0_PE3_OCP_RXN<1>")
	)
	(segment
		(start 458.688186 -46.784514)
		(end 458.688186 -44.951904)
		(width 0.1143)
		(layer "In4.Cu")
		(net "P3E_CPU0_PE3_OCP_RXN<1>")
	)
	(segment
		(start 358.963976 -55.1688)
		(end 361.137962 -53.620924)
		(width 0.1143)
		(layer "In4.Cu")
		(net "P3E_CPU0_PE3_OCP_RXN<1>")
	)
	(segment
		(start 304.81651 -96.42983)
		(end 305.04638 -96.6597)
		(width 0.0889)
		(layer "In4.Cu")
		(net "P3E_CPU0_PE3_OCP_RXN<1>")
	)
	(segment
		(start 307.664358 -95.7961)
		(end 319.37833 -84.082636)
		(width 0.1143)
		(layer "In4.Cu")
		(net "P3E_CPU0_PE3_OCP_RXN<1>")
	)
	(segment
		(start 390.381744 -50.536602)
		(end 392.702796 -52.857654)
		(width 0.1143)
		(layer "In4.Cu")
		(net "P3E_CPU0_PE3_OCP_RXN<1>")
	)
	(segment
		(start 298.36364 -99.586288)
		(end 298.396406 -99.586288)
		(width 0.0889)
		(layer "In4.Cu")
		(net "P3E_CPU0_PE3_OCP_RXN<1>")
	)
	(segment
		(start 324.55231 -71.590662)
		(end 333.48803 -58.599578)
		(width 0.1143)
		(layer "In4.Cu")
		(net "P3E_CPU0_PE3_OCP_RXN<1>")
	)
	(segment
		(start 297.520106 -100.081588)
		(end 297.53306 -100.081588)
		(width 0.0889)
		(layer "In4.Cu")
		(net "P3E_CPU0_PE3_OCP_RXN<1>")
	)
	(segment
		(start 306.504594 -95.7453)
		(end 306.8066 -95.7453)
		(width 0.0889)
		(layer "In4.Cu")
		(net "P3E_CPU0_PE3_OCP_RXN<1>")
	)
	(arc
		(start 304.041556 -96.319086)
		(mid 304.388266 -96.118775)
		(end 304.734976 -96.319086)
		(width 0.0889)
		(layer "In4.Cu")
		(net "P3E_CPU0_PE3_OCP_RXN<1>")
	)
	(arc
		(start 300.113446 -97.605088)
		(mid 300.39887 -97.521621)
		(end 300.607476 -97.309686)
		(width 0.0889)
		(layer "In4.Cu")
		(net "P3E_CPU0_PE3_OCP_RXN<1>")
	)
	(arc
		(start 299.258736 -98.100134)
		(mid 299.541953 -98.015853)
		(end 299.748956 -97.804986)
		(width 0.0889)
		(layer "In4.Cu")
		(net "P3E_CPU0_PE3_OCP_RXN<1>")
	)
	(arc
		(start 303.017936 -96.319086)
		(mid 303.529746 -96.614753)
		(end 304.041556 -96.319086)
		(width 0.0889)
		(layer "In4.Cu")
		(net "P3E_CPU0_PE3_OCP_RXN<1>")
	)
	(arc
		(start 295.8211 -101.072188)
		(mid 296.106524 -100.988721)
		(end 296.31513 -100.776786)
		(width 0.0889)
		(layer "In4.Cu")
		(net "P3E_CPU0_PE3_OCP_RXN<1>")
	)
	(arc
		(start 298.031916 -99.786186)
		(mid 298.171995 -99.64345)
		(end 298.36364 -99.586288)
		(width 0.0889)
		(layer "In4.Cu")
		(net "P3E_CPU0_PE3_OCP_RXN<1>")
	)
	(arc
		(start 300.607476 -97.309686)
		(mid 300.749159 -97.165882)
		(end 300.94301 -97.109534)
		(width 0.0889)
		(layer "In4.Cu")
		(net "P3E_CPU0_PE3_OCP_RXN<1>")
	)
	(arc
		(start 304.734976 -96.319086)
		(mid 304.769033 -96.371944)
		(end 304.808128 -96.421194)
		(width 0.0889)
		(layer "In4.Cu")
		(net "P3E_CPU0_PE3_OCP_RXN<1>")
	)
	(arc
		(start 298.396406 -99.586288)
		(mid 298.894657 -99.283448)
		(end 298.890436 -98.700336)
		(width 0.0889)
		(layer "In4.Cu")
		(net "P3E_CPU0_PE3_OCP_RXN<1>")
	)
	(arc
		(start 301.830486 -96.614488)
		(mid 302.11591 -96.531021)
		(end 302.324516 -96.319086)
		(width 0.0889)
		(layer "In4.Cu")
		(net "P3E_CPU0_PE3_OCP_RXN<1>")
	)
	(arc
		(start 296.31513 -100.776786)
		(mid 296.453874 -100.634753)
		(end 296.643806 -100.576888)
		(width 0.0889)
		(layer "In4.Cu")
		(net "P3E_CPU0_PE3_OCP_RXN<1>")
	)
	(arc
		(start 300.975776 -97.109534)
		(mid 301.258993 -97.025253)
		(end 301.465996 -96.814386)
		(width 0.0889)
		(layer "In4.Cu")
		(net "P3E_CPU0_PE3_OCP_RXN<1>")
	)
	(arc
		(start 298.890436 -98.700336)
		(mid 298.887688 -98.304869)
		(end 299.22597 -98.100134)
		(width 0.0889)
		(layer "In4.Cu")
		(net "P3E_CPU0_PE3_OCP_RXN<1>")
	)
	(arc
		(start 304.808128 -96.421194)
		(mid 304.817664 -96.431715)
		(end 304.827432 -96.442022)
		(width 0.0889)
		(layer "In4.Cu")
		(net "P3E_CPU0_PE3_OCP_RXN<1>")
	)
	(arc
		(start 301.465996 -96.814386)
		(mid 301.606075 -96.67165)
		(end 301.79772 -96.614488)
		(width 0.0889)
		(layer "In4.Cu")
		(net "P3E_CPU0_PE3_OCP_RXN<1>")
	)
	(arc
		(start 295.29151 -100.776786)
		(mid 295.500118 -100.988718)
		(end 295.78554 -101.072188)
		(width 0.0889)
		(layer "In4.Cu")
		(net "P3E_CPU0_PE3_OCP_RXN<1>")
	)
	(arc
		(start 294.097456 -100.081588)
		(mid 294.291306 -100.137938)
		(end 294.43299 -100.28174)
		(width 0.0889)
		(layer "In4.Cu")
		(net "P3E_CPU0_PE3_OCP_RXN<1>")
	)
	(arc
		(start 294.962834 -100.576888)
		(mid 295.152763 -100.634758)
		(end 295.29151 -100.776786)
		(width 0.0889)
		(layer "In4.Cu")
		(net "P3E_CPU0_PE3_OCP_RXN<1>")
	)
	(arc
		(start 297.176952 -100.275898)
		(mid 297.322918 -100.133499)
		(end 297.520106 -100.081588)
		(width 0.0889)
		(layer "In4.Cu")
		(net "P3E_CPU0_PE3_OCP_RXN<1>")
	)
	(arc
		(start 293.285672 -99.590352)
		(mid 293.452517 -99.655165)
		(end 293.57447 -99.786186)
		(width 0.0889)
		(layer "In4.Cu")
		(net "P3E_CPU0_PE3_OCP_RXN<1>")
	)
	(arc
		(start 296.68343 -100.576888)
		(mid 296.966647 -100.492607)
		(end 297.17365 -100.28174)
		(width 0.0889)
		(layer "In4.Cu")
		(net "P3E_CPU0_PE3_OCP_RXN<1>")
	)
	(arc
		(start 293.57447 -99.786186)
		(mid 293.785183 -99.999265)
		(end 294.073326 -100.081588)
		(width 0.0889)
		(layer "In4.Cu")
		(net "P3E_CPU0_PE3_OCP_RXN<1>")
	)
	(arc
		(start 294.43299 -100.28174)
		(mid 294.639994 -100.492604)
		(end 294.92321 -100.576888)
		(width 0.0889)
		(layer "In4.Cu")
		(net "P3E_CPU0_PE3_OCP_RXN<1>")
	)
	(arc
		(start 302.324516 -96.319086)
		(mid 302.671226 -96.118775)
		(end 303.017936 -96.319086)
		(width 0.0889)
		(layer "In4.Cu")
		(net "P3E_CPU0_PE3_OCP_RXN<1>")
	)
	(arc
		(start 299.748956 -97.804986)
		(mid 299.889035 -97.66225)
		(end 300.08068 -97.605088)
		(width 0.0889)
		(layer "In4.Cu")
		(net "P3E_CPU0_PE3_OCP_RXN<1>")
	)
	(arc
		(start 297.53306 -100.081588)
		(mid 297.821205 -99.999269)
		(end 298.031916 -99.786186)
		(width 0.0889)
		(layer "In4.Cu")
		(net "P3E_CPU0_PE3_OCP_RXN<1>")
	)
	(segment
		(start 463.800952 -116.993162)
		(end 463.800952 -118.342918)
		(width 0.1143)
		(layer "F.Cu")
		(net "P3E_CPU0_PE3_OCP_RXN<15>")
	)
	(segment
		(start 463.799936 -118.343934)
		(end 464.092798 -118.636796)
		(width 0.1143)
		(layer "F.Cu")
		(net "P3E_CPU0_PE3_OCP_RXN<15>")
	)
	(segment
		(start 300.382686 -89.584784)
		(end 300.954186 -89.584784)
		(width 0.1143)
		(layer "F.Cu")
		(net "P3E_CPU0_PE3_OCP_RXN<15>")
	)
	(segment
		(start 463.800952 -118.342918)
		(end 463.799936 -118.343934)
		(width 0.1143)
		(layer "F.Cu")
		(net "P3E_CPU0_PE3_OCP_RXN<15>")
	)
	(segment
		(start 464.092798 -120.918478)
		(end 463.871818 -121.139458)
		(width 0.1143)
		(layer "F.Cu")
		(net "P3E_CPU0_PE3_OCP_RXN<15>")
	)
	(segment
		(start 463.871818 -121.139458)
		(end 463.625438 -121.139458)
		(width 0.1143)
		(layer "F.Cu")
		(net "P3E_CPU0_PE3_OCP_RXN<15>")
	)
	(segment
		(start 464.092798 -118.636796)
		(end 464.092798 -120.918478)
		(width 0.1143)
		(layer "F.Cu")
		(net "P3E_CPU0_PE3_OCP_RXN<15>")
	)
	(via
		(at 463.625438 -121.139458)
		(size 0.508)
		(drill 0.254)
		(layers "F.Cu" "B.Cu")
		(net "P3E_CPU0_PE3_OCP_RXN<15>")
	)
	(via
		(at 300.954186 -89.584784)
		(size 0.508)
		(drill 0.254)
		(layers "F.Cu" "B.Cu")
		(net "P3E_CPU0_PE3_OCP_RXN<15>")
	)
	(segment
		(start 300.4693 -104.505506)
		(end 300.484794 -104.521)
		(width 0.0889)
		(layer "In11.Cu")
		(net "P3E_CPU0_PE3_OCP_RXN<15>")
	)
	(segment
		(start 458.448664 -126.935484)
		(end 458.733906 -126.744984)
		(width 0.1143)
		(layer "In11.Cu")
		(net "P3E_CPU0_PE3_OCP_RXN<15>")
	)
	(segment
		(start 299.179488 -103.28783)
		(end 299.305218 -103.28783)
		(width 0.0889)
		(layer "In11.Cu")
		(net "P3E_CPU0_PE3_OCP_RXN<15>")
	)
	(segment
		(start 367.006378 -140.628878)
		(end 367.839244 -140.486384)
		(width 0.1143)
		(layer "In11.Cu")
		(net "P3E_CPU0_PE3_OCP_RXN<15>")
	)
	(segment
		(start 298.99102 -103.099362)
		(end 299.179488 -103.28783)
		(width 0.0889)
		(layer "In11.Cu")
		(net "P3E_CPU0_PE3_OCP_RXN<15>")
	)
	(segment
		(start 391.20572 -145.952464)
		(end 394.451078 -146.354292)
		(width 0.1143)
		(layer "In11.Cu")
		(net "P3E_CPU0_PE3_OCP_RXN<15>")
	)
	(segment
		(start 464.03895 -121.30659)
		(end 463.871818 -121.139458)
		(width 0.1143)
		(layer "In11.Cu")
		(net "P3E_CPU0_PE3_OCP_RXN<15>")
	)
	(segment
		(start 294.593264 -92.2528)
		(end 294.59809 -92.261436)
		(width 0.0889)
		(layer "In11.Cu")
		(net "P3E_CPU0_PE3_OCP_RXN<15>")
	)
	(segment
		(start 461.01 -125.225048)
		(end 461.01 -123.6726)
		(width 0.1143)
		(layer "In11.Cu")
		(net "P3E_CPU0_PE3_OCP_RXN<15>")
	)
	(segment
		(start 451.007226 -128.414272)
		(end 455.459338 -127.52959)
		(width 0.1143)
		(layer "In11.Cu")
		(net "P3E_CPU0_PE3_OCP_RXN<15>")
	)
	(segment
		(start 410.018738 -147.69719)
		(end 410.774134 -147.69719)
		(width 0.1143)
		(layer "In11.Cu")
		(net "P3E_CPU0_PE3_OCP_RXN<15>")
	)
	(segment
		(start 300.954186 -89.584784)
		(end 300.66107 -89.415874)
		(width 0.0889)
		(layer "In11.Cu")
		(net "P3E_CPU0_PE3_OCP_RXN<15>")
	)
	(segment
		(start 297.541696 -90.175334)
		(end 297.520106 -90.175334)
		(width 0.0889)
		(layer "In11.Cu")
		(net "P3E_CPU0_PE3_OCP_RXN<15>")
	)
	(segment
		(start 298.393612 -89.680288)
		(end 298.36364 -89.680288)
		(width 0.0889)
		(layer "In11.Cu")
		(net "P3E_CPU0_PE3_OCP_RXN<15>")
	)
	(segment
		(start 376.895614 -143.364966)
		(end 379.26391 -143.785844)
		(width 0.1143)
		(layer "In11.Cu")
		(net "P3E_CPU0_PE3_OCP_RXN<15>")
	)
	(segment
		(start 295.788334 -97.909634)
		(end 295.8211 -97.909634)
		(width 0.0889)
		(layer "In11.Cu")
		(net "P3E_CPU0_PE3_OCP_RXN<15>")
	)
	(segment
		(start 460.138272 -125.807216)
		(end 461.01 -125.225048)
		(width 0.1143)
		(layer "In11.Cu")
		(net "P3E_CPU0_PE3_OCP_RXN<15>")
	)
	(segment
		(start 298.36745 -102.367588)
		(end 298.400216 -102.367588)
		(width 0.0889)
		(layer "In11.Cu")
		(net "P3E_CPU0_PE3_OCP_RXN<15>")
	)
	(segment
		(start 321.7926 -123.676156)
		(end 322.20535 -124.088906)
		(width 0.1143)
		(layer "In11.Cu")
		(net "P3E_CPU0_PE3_OCP_RXN<15>")
	)
	(segment
		(start 299.49394 -103.476552)
		(end 299.49394 -103.602282)
		(width 0.0889)
		(layer "In11.Cu")
		(net "P3E_CPU0_PE3_OCP_RXN<15>")
	)
	(segment
		(start 317.4873 -120.605042)
		(end 317.900558 -121.0183)
		(width 0.1143)
		(layer "In11.Cu")
		(net "P3E_CPU0_PE3_OCP_RXN<15>")
	)
	(segment
		(start 462.7626 -122.9614)
		(end 464.03895 -121.68505)
		(width 0.1143)
		(layer "In11.Cu")
		(net "P3E_CPU0_PE3_OCP_RXN<15>")
	)
	(segment
		(start 300.113446 -89.680288)
		(end 300.08068 -89.680288)
		(width 0.0889)
		(layer "In11.Cu")
		(net "P3E_CPU0_PE3_OCP_RXN<15>")
	)
	(segment
		(start 456.585574 -127.137414)
		(end 456.92187 -127.070612)
		(width 0.1143)
		(layer "In11.Cu")
		(net "P3E_CPU0_PE3_OCP_RXN<15>")
	)
	(segment
		(start 322.20535 -124.088906)
		(end 322.644262 -124.088906)
		(width 0.1143)
		(layer "In11.Cu")
		(net "P3E_CPU0_PE3_OCP_RXN<15>")
	)
	(segment
		(start 456.92187 -127.070612)
		(end 457.115926 -127.200406)
		(width 0.1143)
		(layer "In11.Cu")
		(net "P3E_CPU0_PE3_OCP_RXN<15>")
	)
	(segment
		(start 434.011324 -146.052286)
		(end 434.45557 -145.781776)
		(width 0.1143)
		(layer "In11.Cu")
		(net "P3E_CPU0_PE3_OCP_RXN<15>")
	)
	(segment
		(start 448.910202 -129.769362)
		(end 449.141088 -129.803144)
		(width 0.1143)
		(layer "In11.Cu")
		(net "P3E_CPU0_PE3_OCP_RXN<15>")
	)
	(segment
		(start 455.925428 -127.268478)
		(end 456.119484 -127.398272)
		(width 0.1143)
		(layer "In11.Cu")
		(net "P3E_CPU0_PE3_OCP_RXN<15>")
	)
	(segment
		(start 337.623912 -133.132068)
		(end 341.991696 -134.52221)
		(width 0.1143)
		(layer "In11.Cu")
		(net "P3E_CPU0_PE3_OCP_RXN<15>")
	)
	(segment
		(start 294.96258 -91.661488)
		(end 294.929814 -91.661488)
		(width 0.0889)
		(layer "In11.Cu")
		(net "P3E_CPU0_PE3_OCP_RXN<15>")
	)
	(segment
		(start 328.306938 -127.490474)
		(end 330.23937 -127.490474)
		(width 0.1143)
		(layer "In11.Cu")
		(net "P3E_CPU0_PE3_OCP_RXN<15>")
	)
	(segment
		(start 457.918312 -126.872492)
		(end 458.112368 -127.002286)
		(width 0.1143)
		(layer "In11.Cu")
		(net "P3E_CPU0_PE3_OCP_RXN<15>")
	)
	(segment
		(start 459.293468 -126.37135)
		(end 459.57871 -126.18085)
		(width 0.1143)
		(layer "In11.Cu")
		(net "P3E_CPU0_PE3_OCP_RXN<15>")
	)
	(segment
		(start 449.141088 -129.803144)
		(end 451.007226 -128.414272)
		(width 0.1143)
		(layer "In11.Cu")
		(net "P3E_CPU0_PE3_OCP_RXN<15>")
	)
	(segment
		(start 296.31513 -99.195636)
		(end 296.32148 -99.206304)
		(width 0.0889)
		(layer "In11.Cu")
		(net "P3E_CPU0_PE3_OCP_RXN<15>")
	)
	(segment
		(start 358.479344 -131.776978)
		(end 359.68559 -131.27736)
		(width 0.1143)
		(layer "In11.Cu")
		(net "P3E_CPU0_PE3_OCP_RXN<15>")
	)
	(segment
		(start 365.388144 -140.190474)
		(end 367.006378 -140.628878)
		(width 0.1143)
		(layer "In11.Cu")
		(net "P3E_CPU0_PE3_OCP_RXN<15>")
	)
	(segment
		(start 320.3194 -121.0183)
		(end 321.7926 -122.4915)
		(width 0.1143)
		(layer "In11.Cu")
		(net "P3E_CPU0_PE3_OCP_RXN<15>")
	)
	(segment
		(start 412.868618 -149.791674)
		(end 417.409376 -149.791674)
		(width 0.1143)
		(layer "In11.Cu")
		(net "P3E_CPU0_PE3_OCP_RXN<15>")
	)
	(segment
		(start 420.480744 -148.51888)
		(end 420.48049 -148.518626)
		(width 0.1143)
		(layer "In11.Cu")
		(net "P3E_CPU0_PE3_OCP_RXN<15>")
	)
	(segment
		(start 420.48049 -148.518626)
		(end 421.909494 -147.491196)
		(width 0.1143)
		(layer "In11.Cu")
		(net "P3E_CPU0_PE3_OCP_RXN<15>")
	)
	(segment
		(start 395.976094 -147.54352)
		(end 396.169896 -147.632674)
		(width 0.1143)
		(layer "In11.Cu")
		(net "P3E_CPU0_PE3_OCP_RXN<15>")
	)
	(segment
		(start 364.547404 -138.161268)
		(end 365.388144 -140.190474)
		(width 0.1143)
		(layer "In11.Cu")
		(net "P3E_CPU0_PE3_OCP_RXN<15>")
	)
	(segment
		(start 461.01 -123.6726)
		(end 461.7212 -122.9614)
		(width 0.1143)
		(layer "In11.Cu")
		(net "P3E_CPU0_PE3_OCP_RXN<15>")
	)
	(segment
		(start 299.682408 -103.79075)
		(end 299.808138 -103.79075)
		(width 0.0889)
		(layer "In11.Cu")
		(net "P3E_CPU0_PE3_OCP_RXN<15>")
	)
	(segment
		(start 294.59809 -96.223836)
		(end 294.60444 -96.234504)
		(width 0.0889)
		(layer "In11.Cu")
		(net "P3E_CPU0_PE3_OCP_RXN<15>")
	)
	(segment
		(start 359.68559 -131.27736)
		(end 360.966258 -131.27736)
		(width 0.1143)
		(layer "In11.Cu")
		(net "P3E_CPU0_PE3_OCP_RXN<15>")
	)
	(segment
		(start 296.310304 -99.187)
		(end 296.31513 -99.195636)
		(width 0.0889)
		(layer "In11.Cu")
		(net "P3E_CPU0_PE3_OCP_RXN<15>")
	)
	(segment
		(start 299.99686 -104.105202)
		(end 300.397164 -104.505506)
		(width 0.0889)
		(layer "In11.Cu")
		(net "P3E_CPU0_PE3_OCP_RXN<15>")
	)
	(segment
		(start 389.857996 -144.755362)
		(end 390.37768 -145.593562)
		(width 0.1143)
		(layer "In11.Cu")
		(net "P3E_CPU0_PE3_OCP_RXN<15>")
	)
	(segment
		(start 363.006132 -133.781038)
		(end 363.97946 -134.004558)
		(width 0.1143)
		(layer "In11.Cu")
		(net "P3E_CPU0_PE3_OCP_RXN<15>")
	)
	(segment
		(start 294.59809 -93.252036)
		(end 294.60444 -93.262704)
		(width 0.0889)
		(layer "In11.Cu")
		(net "P3E_CPU0_PE3_OCP_RXN<15>")
	)
	(segment
		(start 410.774134 -147.69719)
		(end 412.868618 -149.791674)
		(width 0.1143)
		(layer "In11.Cu")
		(net "P3E_CPU0_PE3_OCP_RXN<15>")
	)
	(segment
		(start 299.305218 -103.28783)
		(end 299.49394 -103.476552)
		(width 0.0889)
		(layer "In11.Cu")
		(net "P3E_CPU0_PE3_OCP_RXN<15>")
	)
	(segment
		(start 294.60444 -94.822518)
		(end 294.59809 -94.833186)
		(width 0.0889)
		(layer "In11.Cu")
		(net "P3E_CPU0_PE3_OCP_RXN<15>")
	)
	(segment
		(start 302.135794 -106.172)
		(end 305.3207 -106.172)
		(width 0.1143)
		(layer "In11.Cu")
		(net "P3E_CPU0_PE3_OCP_RXN<15>")
	)
	(segment
		(start 299.99686 -103.979472)
		(end 299.99686 -104.105202)
		(width 0.0889)
		(layer "In11.Cu")
		(net "P3E_CPU0_PE3_OCP_RXN<15>")
	)
	(segment
		(start 362.13034 -132.536184)
		(end 363.006132 -133.781038)
		(width 0.1143)
		(layer "In11.Cu")
		(net "P3E_CPU0_PE3_OCP_RXN<15>")
	)
	(segment
		(start 300.397164 -104.505506)
		(end 300.4693 -104.505506)
		(width 0.0889)
		(layer "In11.Cu")
		(net "P3E_CPU0_PE3_OCP_RXN<15>")
	)
	(segment
		(start 457.115926 -127.200406)
		(end 457.452222 -127.133604)
		(width 0.1143)
		(layer "In11.Cu")
		(net "P3E_CPU0_PE3_OCP_RXN<15>")
	)
	(segment
		(start 322.812156 -124.2568)
		(end 323.471794 -124.2568)
		(width 0.1143)
		(layer "In11.Cu")
		(net "P3E_CPU0_PE3_OCP_RXN<15>")
	)
	(segment
		(start 404.330408 -147.735544)
		(end 406.149302 -148.488908)
		(width 0.1143)
		(layer "In11.Cu")
		(net "P3E_CPU0_PE3_OCP_RXN<15>")
	)
	(segment
		(start 362.130848 -132.532628)
		(end 362.13034 -132.536184)
		(width 0.1143)
		(layer "In11.Cu")
		(net "P3E_CPU0_PE3_OCP_RXN<15>")
	)
	(segment
		(start 300.66107 -89.415874)
		(end 300.571662 -89.440004)
		(width 0.0889)
		(layer "In11.Cu")
		(net "P3E_CPU0_PE3_OCP_RXN<15>")
	)
	(segment
		(start 295.82491 -91.165934)
		(end 295.792144 -91.165934)
		(width 0.0889)
		(layer "In11.Cu")
		(net "P3E_CPU0_PE3_OCP_RXN<15>")
	)
	(segment
		(start 458.779372 -126.51613)
		(end 459.064614 -126.32563)
		(width 0.1143)
		(layer "In11.Cu")
		(net "P3E_CPU0_PE3_OCP_RXN<15>")
	)
	(segment
		(start 317.4873 -118.3386)
		(end 317.4873 -120.605042)
		(width 0.1143)
		(layer "In11.Cu")
		(net "P3E_CPU0_PE3_OCP_RXN<15>")
	)
	(segment
		(start 417.409376 -149.791674)
		(end 420.479982 -148.519134)
		(width 0.1143)
		(layer "In11.Cu")
		(net "P3E_CPU0_PE3_OCP_RXN<15>")
	)
	(segment
		(start 424.412664 -146.40433)
		(end 430.482756 -145.366994)
		(width 0.1143)
		(layer "In11.Cu")
		(net "P3E_CPU0_PE3_OCP_RXN<15>")
	)
	(segment
		(start 439.381646 -137.796778)
		(end 440.79414 -134.587488)
		(width 0.1143)
		(layer "In11.Cu")
		(net "P3E_CPU0_PE3_OCP_RXN<15>")
	)
	(segment
		(start 459.624176 -125.951996)
		(end 459.909418 -125.761496)
		(width 0.1143)
		(layer "In11.Cu")
		(net "P3E_CPU0_PE3_OCP_RXN<15>")
	)
	(segment
		(start 294.593264 -93.2434)
		(end 294.59809 -93.252036)
		(width 0.0889)
		(layer "In11.Cu")
		(net "P3E_CPU0_PE3_OCP_RXN<15>")
	)
	(segment
		(start 437.469026 -140.993114)
		(end 439.381646 -137.796778)
		(width 0.1143)
		(layer "In11.Cu")
		(net "P3E_CPU0_PE3_OCP_RXN<15>")
	)
	(segment
		(start 459.57871 -126.18085)
		(end 459.624176 -125.951996)
		(width 0.1143)
		(layer "In11.Cu")
		(net "P3E_CPU0_PE3_OCP_RXN<15>")
	)
	(segment
		(start 374.947688 -141.93266)
		(end 376.895614 -143.364966)
		(width 0.1143)
		(layer "In11.Cu")
		(net "P3E_CPU0_PE3_OCP_RXN<15>")
	)
	(segment
		(start 456.119484 -127.398272)
		(end 456.45578 -127.33147)
		(width 0.1143)
		(layer "In11.Cu")
		(net "P3E_CPU0_PE3_OCP_RXN<15>")
	)
	(segment
		(start 317.900558 -121.0183)
		(end 320.3194 -121.0183)
		(width 0.1143)
		(layer "In11.Cu")
		(net "P3E_CPU0_PE3_OCP_RXN<15>")
	)
	(segment
		(start 323.63791 -124.090684)
		(end 324.907148 -124.090684)
		(width 0.1143)
		(layer "In11.Cu")
		(net "P3E_CPU0_PE3_OCP_RXN<15>")
	)
	(segment
		(start 298.99102 -102.83698)
		(end 298.99102 -103.099362)
		(width 0.0889)
		(layer "In11.Cu")
		(net "P3E_CPU0_PE3_OCP_RXN<15>")
	)
	(segment
		(start 391.205466 -145.952464)
		(end 391.20572 -145.952464)
		(width 0.1143)
		(layer "In11.Cu")
		(net "P3E_CPU0_PE3_OCP_RXN<15>")
	)
	(segment
		(start 297.17365 -101.671882)
		(end 297.176952 -101.677724)
		(width 0.0889)
		(layer "In11.Cu")
		(net "P3E_CPU0_PE3_OCP_RXN<15>")
	)
	(segment
		(start 434.899816 -145.511266)
		(end 435.643782 -143.145256)
		(width 0.1143)
		(layer "In11.Cu")
		(net "P3E_CPU0_PE3_OCP_RXN<15>")
	)
	(segment
		(start 446.906904 -131.466336)
		(end 448.601338 -130.204972)
		(width 0.1143)
		(layer "In11.Cu")
		(net "P3E_CPU0_PE3_OCP_RXN<15>")
	)
	(segment
		(start 458.733906 -126.744984)
		(end 458.779372 -126.51613)
		(width 0.1143)
		(layer "In11.Cu")
		(net "P3E_CPU0_PE3_OCP_RXN<15>")
	)
	(segment
		(start 458.112368 -127.002286)
		(end 458.448664 -126.935484)
		(width 0.1143)
		(layer "In11.Cu")
		(net "P3E_CPU0_PE3_OCP_RXN<15>")
	)
	(segment
		(start 299.49394 -103.602282)
		(end 299.682408 -103.79075)
		(width 0.0889)
		(layer "In11.Cu")
		(net "P3E_CPU0_PE3_OCP_RXN<15>")
	)
	(segment
		(start 448.601338 -130.204972)
		(end 448.63512 -129.974086)
		(width 0.1143)
		(layer "In11.Cu")
		(net "P3E_CPU0_PE3_OCP_RXN<15>")
	)
	(segment
		(start 360.966258 -131.27736)
		(end 361.77347 -131.772914)
		(width 0.1143)
		(layer "In11.Cu")
		(net "P3E_CPU0_PE3_OCP_RXN<15>")
	)
	(segment
		(start 434.455824 -145.781776)
		(end 434.899816 -145.511266)
		(width 0.1143)
		(layer "In11.Cu")
		(net "P3E_CPU0_PE3_OCP_RXN<15>")
	)
	(segment
		(start 464.03895 -121.68505)
		(end 464.03895 -121.30659)
		(width 0.1143)
		(layer "In11.Cu")
		(net "P3E_CPU0_PE3_OCP_RXN<15>")
	)
	(segment
		(start 406.149302 -148.488908)
		(end 408.107134 -148.488908)
		(width 0.1143)
		(layer "In11.Cu")
		(net "P3E_CPU0_PE3_OCP_RXN<15>")
	)
	(segment
		(start 388.584694 -144.161256)
		(end 389.857996 -144.755362)
		(width 0.1143)
		(layer "In11.Cu")
		(net "P3E_CPU0_PE3_OCP_RXN<15>")
	)
	(segment
		(start 459.064614 -126.32563)
		(end 459.293468 -126.37135)
		(width 0.1143)
		(layer "In11.Cu")
		(net "P3E_CPU0_PE3_OCP_RXN<15>")
	)
	(segment
		(start 299.258736 -90.175334)
		(end 299.215556 -90.175334)
		(width 0.0889)
		(layer "In11.Cu")
		(net "P3E_CPU0_PE3_OCP_RXN<15>")
	)
	(segment
		(start 420.479982 -148.519134)
		(end 420.480744 -148.51888)
		(width 0.1143)
		(layer "In11.Cu")
		(net "P3E_CPU0_PE3_OCP_RXN<15>")
	)
	(segment
		(start 455.589132 -127.335534)
		(end 455.925428 -127.268478)
		(width 0.1143)
		(layer "In11.Cu")
		(net "P3E_CPU0_PE3_OCP_RXN<15>")
	)
	(segment
		(start 435.643782 -143.145256)
		(end 436.742078 -141.294358)
		(width 0.1143)
		(layer "In11.Cu")
		(net "P3E_CPU0_PE3_OCP_RXN<15>")
	)
	(segment
		(start 408.107134 -148.488908)
		(end 410.018738 -147.69719)
		(width 0.1143)
		(layer "In11.Cu")
		(net "P3E_CPU0_PE3_OCP_RXN<15>")
	)
	(segment
		(start 402.8821 -148.025358)
		(end 404.330408 -147.735544)
		(width 0.1143)
		(layer "In11.Cu")
		(net "P3E_CPU0_PE3_OCP_RXN<15>")
	)
	(segment
		(start 299.808138 -103.79075)
		(end 299.99686 -103.979472)
		(width 0.0889)
		(layer "In11.Cu")
		(net "P3E_CPU0_PE3_OCP_RXN<15>")
	)
	(segment
		(start 380.882652 -143.47698)
		(end 384.323336 -144.161256)
		(width 0.1143)
		(layer "In11.Cu")
		(net "P3E_CPU0_PE3_OCP_RXN<15>")
	)
	(segment
		(start 384.323336 -144.161256)
		(end 388.584694 -144.161256)
		(width 0.1143)
		(layer "In11.Cu")
		(net "P3E_CPU0_PE3_OCP_RXN<15>")
	)
	(segment
		(start 294.593264 -94.234)
		(end 294.59809 -94.242636)
		(width 0.0889)
		(layer "In11.Cu")
		(net "P3E_CPU0_PE3_OCP_RXN<15>")
	)
	(segment
		(start 296.67962 -90.670888)
		(end 296.646854 -90.670888)
		(width 0.0889)
		(layer "In11.Cu")
		(net "P3E_CPU0_PE3_OCP_RXN<15>")
	)
	(segment
		(start 430.482756 -145.366994)
		(end 433.168806 -146.162268)
		(width 0.1143)
		(layer "In11.Cu")
		(net "P3E_CPU0_PE3_OCP_RXN<15>")
	)
	(segment
		(start 364.873794 -135.238998)
		(end 365.16945 -136.085834)
		(width 0.1143)
		(layer "In11.Cu")
		(net "P3E_CPU0_PE3_OCP_RXN<15>")
	)
	(segment
		(start 463.871818 -121.139458)
		(end 463.625438 -121.139458)
		(width 0.1143)
		(layer "In11.Cu")
		(net "P3E_CPU0_PE3_OCP_RXN<15>")
	)
	(segment
		(start 336.502502 -130.97129)
		(end 337.623912 -133.132068)
		(width 0.1143)
		(layer "In11.Cu")
		(net "P3E_CPU0_PE3_OCP_RXN<15>")
	)
	(segment
		(start 305.3207 -106.172)
		(end 317.4873 -118.3386)
		(width 0.1143)
		(layer "In11.Cu")
		(net "P3E_CPU0_PE3_OCP_RXN<15>")
	)
	(segment
		(start 397.095472 -147.821142)
		(end 399.449798 -147.338796)
		(width 0.1143)
		(layer "In11.Cu")
		(net "P3E_CPU0_PE3_OCP_RXN<15>")
	)
	(segment
		(start 341.991696 -134.52221)
		(end 355.734112 -134.52221)
		(width 0.1143)
		(layer "In11.Cu")
		(net "P3E_CPU0_PE3_OCP_RXN<15>")
	)
	(segment
		(start 455.459338 -127.52959)
		(end 455.589132 -127.335534)
		(width 0.1143)
		(layer "In11.Cu")
		(net "P3E_CPU0_PE3_OCP_RXN<15>")
	)
	(segment
		(start 355.734112 -134.52221)
		(end 358.479344 -131.776978)
		(width 0.1143)
		(layer "In11.Cu")
		(net "P3E_CPU0_PE3_OCP_RXN<15>")
	)
	(segment
		(start 456.45578 -127.33147)
		(end 456.45578 -127.331724)
		(width 0.1143)
		(layer "In11.Cu")
		(net "P3E_CPU0_PE3_OCP_RXN<15>")
	)
	(segment
		(start 322.644262 -124.088906)
		(end 322.812156 -124.2568)
		(width 0.1143)
		(layer "In11.Cu")
		(net "P3E_CPU0_PE3_OCP_RXN<15>")
	)
	(segment
		(start 330.23937 -127.490474)
		(end 331.754988 -129.005838)
		(width 0.1143)
		(layer "In11.Cu")
		(net "P3E_CPU0_PE3_OCP_RXN<15>")
	)
	(segment
		(start 394.451078 -146.354292)
		(end 395.976094 -147.54352)
		(width 0.1143)
		(layer "In11.Cu")
		(net "P3E_CPU0_PE3_OCP_RXN<15>")
	)
	(segment
		(start 436.742078 -141.294358)
		(end 437.469026 -140.993114)
		(width 0.1143)
		(layer "In11.Cu")
		(net "P3E_CPU0_PE3_OCP_RXN<15>")
	)
	(segment
		(start 296.650664 -101.376734)
		(end 296.67962 -101.376734)
		(width 0.0889)
		(layer "In11.Cu")
		(net "P3E_CPU0_PE3_OCP_RXN<15>")
	)
	(segment
		(start 461.7212 -122.9614)
		(end 462.7626 -122.9614)
		(width 0.1143)
		(layer "In11.Cu")
		(net "P3E_CPU0_PE3_OCP_RXN<15>")
	)
	(segment
		(start 421.909494 -147.491196)
		(end 424.412664 -146.40433)
		(width 0.1143)
		(layer "In11.Cu")
		(net "P3E_CPU0_PE3_OCP_RXN<15>")
	)
	(segment
		(start 361.77347 -131.772914)
		(end 362.130848 -132.532628)
		(width 0.1143)
		(layer "In11.Cu")
		(net "P3E_CPU0_PE3_OCP_RXN<15>")
	)
	(segment
		(start 433.168806 -146.162268)
		(end 434.011324 -146.052286)
		(width 0.1143)
		(layer "In11.Cu")
		(net "P3E_CPU0_PE3_OCP_RXN<15>")
	)
	(segment
		(start 363.97946 -134.004558)
		(end 364.873794 -135.238998)
		(width 0.1143)
		(layer "In11.Cu")
		(net "P3E_CPU0_PE3_OCP_RXN<15>")
	)
	(segment
		(start 457.582016 -126.939548)
		(end 457.918312 -126.872492)
		(width 0.1143)
		(layer "In11.Cu")
		(net "P3E_CPU0_PE3_OCP_RXN<15>")
	)
	(segment
		(start 300.484794 -104.521)
		(end 302.135794 -106.172)
		(width 0.1143)
		(layer "In11.Cu")
		(net "P3E_CPU0_PE3_OCP_RXN<15>")
	)
	(segment
		(start 457.452222 -127.133604)
		(end 457.582016 -126.939548)
		(width 0.1143)
		(layer "In11.Cu")
		(net "P3E_CPU0_PE3_OCP_RXN<15>")
	)
	(segment
		(start 379.26391 -143.785844)
		(end 380.882652 -143.47698)
		(width 0.1143)
		(layer "In11.Cu")
		(net "P3E_CPU0_PE3_OCP_RXN<15>")
	)
	(segment
		(start 294.933624 -97.414588)
		(end 294.96639 -97.414588)
		(width 0.0889)
		(layer "In11.Cu")
		(net "P3E_CPU0_PE3_OCP_RXN<15>")
	)
	(segment
		(start 297.176952 -90.369644)
		(end 297.17365 -90.375486)
		(width 0.0889)
		(layer "In11.Cu")
		(net "P3E_CPU0_PE3_OCP_RXN<15>")
	)
	(segment
		(start 294.593264 -96.2152)
		(end 294.59809 -96.223836)
		(width 0.0889)
		(layer "In11.Cu")
		(net "P3E_CPU0_PE3_OCP_RXN<15>")
	)
	(segment
		(start 321.7926 -122.4915)
		(end 321.7926 -123.676156)
		(width 0.1143)
		(layer "In11.Cu")
		(net "P3E_CPU0_PE3_OCP_RXN<15>")
	)
	(segment
		(start 459.909418 -125.761496)
		(end 460.138272 -125.807216)
		(width 0.1143)
		(layer "In11.Cu")
		(net "P3E_CPU0_PE3_OCP_RXN<15>")
	)
	(segment
		(start 456.45578 -127.331724)
		(end 456.585574 -127.137414)
		(width 0.1143)
		(layer "In11.Cu")
		(net "P3E_CPU0_PE3_OCP_RXN<15>")
	)
	(segment
		(start 331.754988 -129.005838)
		(end 336.502502 -130.97129)
		(width 0.1143)
		(layer "In11.Cu")
		(net "P3E_CPU0_PE3_OCP_RXN<15>")
	)
	(segment
		(start 399.449798 -147.338796)
		(end 402.8821 -148.025358)
		(width 0.1143)
		(layer "In11.Cu")
		(net "P3E_CPU0_PE3_OCP_RXN<15>")
	)
	(segment
		(start 296.32148 -100.766118)
		(end 296.31513 -100.776786)
		(width 0.0889)
		(layer "In11.Cu")
		(net "P3E_CPU0_PE3_OCP_RXN<15>")
	)
	(segment
		(start 294.59809 -92.261436)
		(end 294.60444 -92.272104)
		(width 0.0889)
		(layer "In11.Cu")
		(net "P3E_CPU0_PE3_OCP_RXN<15>")
	)
	(segment
		(start 296.310304 -100.1776)
		(end 296.31513 -100.186236)
		(width 0.0889)
		(layer "In11.Cu")
		(net "P3E_CPU0_PE3_OCP_RXN<15>")
	)
	(segment
		(start 323.471794 -124.2568)
		(end 323.63791 -124.090684)
		(width 0.1143)
		(layer "In11.Cu")
		(net "P3E_CPU0_PE3_OCP_RXN<15>")
	)
	(segment
		(start 396.169896 -147.632674)
		(end 397.095472 -147.821142)
		(width 0.1143)
		(layer "In11.Cu")
		(net "P3E_CPU0_PE3_OCP_RXN<15>")
	)
	(segment
		(start 298.890436 -102.662736)
		(end 298.99102 -102.83698)
		(width 0.0889)
		(layer "In11.Cu")
		(net "P3E_CPU0_PE3_OCP_RXN<15>")
	)
	(segment
		(start 324.907148 -124.090684)
		(end 328.306938 -127.490474)
		(width 0.1143)
		(layer "In11.Cu")
		(net "P3E_CPU0_PE3_OCP_RXN<15>")
	)
	(segment
		(start 297.520106 -101.872034)
		(end 297.537886 -101.872034)
		(width 0.0889)
		(layer "In11.Cu")
		(net "P3E_CPU0_PE3_OCP_RXN<15>")
	)
	(segment
		(start 367.839244 -140.486384)
		(end 374.947688 -141.93266)
		(width 0.1143)
		(layer "In11.Cu")
		(net "P3E_CPU0_PE3_OCP_RXN<15>")
	)
	(segment
		(start 448.63512 -129.974086)
		(end 448.910202 -129.769362)
		(width 0.1143)
		(layer "In11.Cu")
		(net "P3E_CPU0_PE3_OCP_RXN<15>")
	)
	(segment
		(start 365.16945 -136.085834)
		(end 364.547404 -138.161268)
		(width 0.1143)
		(layer "In11.Cu")
		(net "P3E_CPU0_PE3_OCP_RXN<15>")
	)
	(segment
		(start 390.37768 -145.593562)
		(end 391.205466 -145.952464)
		(width 0.1143)
		(layer "In11.Cu")
		(net "P3E_CPU0_PE3_OCP_RXN<15>")
	)
	(segment
		(start 434.45557 -145.781776)
		(end 434.455824 -145.781776)
		(width 0.1143)
		(layer "In11.Cu")
		(net "P3E_CPU0_PE3_OCP_RXN<15>")
	)
	(segment
		(start 440.79414 -134.587488)
		(end 446.906904 -131.466336)
		(width 0.1143)
		(layer "In11.Cu")
		(net "P3E_CPU0_PE3_OCP_RXN<15>")
	)
	(arc
		(start 294.59809 -92.851986)
		(mid 294.54462 -93.047049)
		(end 294.593264 -93.2434)
		(width 0.0889)
		(layer "In11.Cu")
		(net "P3E_CPU0_PE3_OCP_RXN<15>")
	)
	(arc
		(start 294.59809 -94.242636)
		(mid 294.677312 -94.531754)
		(end 294.60444 -94.822518)
		(width 0.0889)
		(layer "In11.Cu")
		(net "P3E_CPU0_PE3_OCP_RXN<15>")
	)
	(arc
		(start 300.08068 -89.680288)
		(mid 299.889038 -89.737454)
		(end 299.748956 -89.880186)
		(width 0.0889)
		(layer "In11.Cu")
		(net "P3E_CPU0_PE3_OCP_RXN<15>")
	)
	(arc
		(start 295.8211 -97.909634)
		(mid 296.319351 -98.212474)
		(end 296.31513 -98.795586)
		(width 0.0889)
		(layer "In11.Cu")
		(net "P3E_CPU0_PE3_OCP_RXN<15>")
	)
	(arc
		(start 295.792144 -91.165934)
		(mid 295.598294 -91.222284)
		(end 295.45661 -91.366086)
		(width 0.0889)
		(layer "In11.Cu")
		(net "P3E_CPU0_PE3_OCP_RXN<15>")
	)
	(arc
		(start 295.45661 -91.366086)
		(mid 295.248002 -91.578018)
		(end 294.96258 -91.661488)
		(width 0.0889)
		(layer "In11.Cu")
		(net "P3E_CPU0_PE3_OCP_RXN<15>")
	)
	(arc
		(start 296.31513 -98.795586)
		(mid 296.26166 -98.990649)
		(end 296.310304 -99.187)
		(width 0.0889)
		(layer "In11.Cu")
		(net "P3E_CPU0_PE3_OCP_RXN<15>")
	)
	(arc
		(start 297.537886 -101.872034)
		(mid 297.82331 -101.955501)
		(end 298.031916 -102.167436)
		(width 0.0889)
		(layer "In11.Cu")
		(net "P3E_CPU0_PE3_OCP_RXN<15>")
	)
	(arc
		(start 297.176952 -101.677724)
		(mid 297.322918 -101.820123)
		(end 297.520106 -101.872034)
		(width 0.0889)
		(layer "In11.Cu")
		(net "P3E_CPU0_PE3_OCP_RXN<15>")
	)
	(arc
		(start 294.59809 -95.823786)
		(mid 294.54462 -96.018849)
		(end 294.593264 -96.2152)
		(width 0.0889)
		(layer "In11.Cu")
		(net "P3E_CPU0_PE3_OCP_RXN<15>")
	)
	(arc
		(start 294.59809 -93.842586)
		(mid 294.54462 -94.037649)
		(end 294.593264 -94.234)
		(width 0.0889)
		(layer "In11.Cu")
		(net "P3E_CPU0_PE3_OCP_RXN<15>")
	)
	(arc
		(start 296.31513 -90.870786)
		(mid 296.108126 -91.08165)
		(end 295.82491 -91.165934)
		(width 0.0889)
		(layer "In11.Cu")
		(net "P3E_CPU0_PE3_OCP_RXN<15>")
	)
	(arc
		(start 296.31513 -100.776786)
		(mid 296.312547 -101.172033)
		(end 296.650664 -101.376734)
		(width 0.0889)
		(layer "In11.Cu")
		(net "P3E_CPU0_PE3_OCP_RXN<15>")
	)
	(arc
		(start 298.725336 -89.880186)
		(mid 298.585257 -89.73745)
		(end 298.393612 -89.680288)
		(width 0.0889)
		(layer "In11.Cu")
		(net "P3E_CPU0_PE3_OCP_RXN<15>")
	)
	(arc
		(start 294.59809 -95.232982)
		(mid 294.677221 -95.528384)
		(end 294.59809 -95.823786)
		(width 0.0889)
		(layer "In11.Cu")
		(net "P3E_CPU0_PE3_OCP_RXN<15>")
	)
	(arc
		(start 296.646854 -90.670888)
		(mid 296.455212 -90.728054)
		(end 296.31513 -90.870786)
		(width 0.0889)
		(layer "In11.Cu")
		(net "P3E_CPU0_PE3_OCP_RXN<15>")
	)
	(arc
		(start 297.520106 -90.175334)
		(mid 297.322945 -90.227293)
		(end 297.176952 -90.369644)
		(width 0.0889)
		(layer "In11.Cu")
		(net "P3E_CPU0_PE3_OCP_RXN<15>")
	)
	(arc
		(start 299.748956 -89.880186)
		(mid 299.541952 -90.09105)
		(end 299.258736 -90.175334)
		(width 0.0889)
		(layer "In11.Cu")
		(net "P3E_CPU0_PE3_OCP_RXN<15>")
	)
	(arc
		(start 298.031916 -102.167436)
		(mid 298.173599 -102.31124)
		(end 298.36745 -102.367588)
		(width 0.0889)
		(layer "In11.Cu")
		(net "P3E_CPU0_PE3_OCP_RXN<15>")
	)
	(arc
		(start 295.45661 -97.709736)
		(mid 295.596689 -97.852472)
		(end 295.788334 -97.909634)
		(width 0.0889)
		(layer "In11.Cu")
		(net "P3E_CPU0_PE3_OCP_RXN<15>")
	)
	(arc
		(start 294.96639 -97.414588)
		(mid 295.249607 -97.498869)
		(end 295.45661 -97.709736)
		(width 0.0889)
		(layer "In11.Cu")
		(net "P3E_CPU0_PE3_OCP_RXN<15>")
	)
	(arc
		(start 294.60444 -93.262704)
		(mid 294.677238 -93.553467)
		(end 294.59809 -93.842586)
		(width 0.0889)
		(layer "In11.Cu")
		(net "P3E_CPU0_PE3_OCP_RXN<15>")
	)
	(arc
		(start 298.400216 -102.367588)
		(mid 298.683433 -102.451869)
		(end 298.890436 -102.662736)
		(width 0.0889)
		(layer "In11.Cu")
		(net "P3E_CPU0_PE3_OCP_RXN<15>")
	)
	(arc
		(start 297.17365 -90.375486)
		(mid 296.965042 -90.587418)
		(end 296.67962 -90.670888)
		(width 0.0889)
		(layer "In11.Cu")
		(net "P3E_CPU0_PE3_OCP_RXN<15>")
	)
	(arc
		(start 294.929814 -91.661488)
		(mid 294.596896 -91.863479)
		(end 294.593264 -92.2528)
		(width 0.0889)
		(layer "In11.Cu")
		(net "P3E_CPU0_PE3_OCP_RXN<15>")
	)
	(arc
		(start 294.60444 -96.234504)
		(mid 294.677238 -96.525267)
		(end 294.59809 -96.814386)
		(width 0.0889)
		(layer "In11.Cu")
		(net "P3E_CPU0_PE3_OCP_RXN<15>")
	)
	(arc
		(start 294.60444 -92.272104)
		(mid 294.677238 -92.562867)
		(end 294.59809 -92.851986)
		(width 0.0889)
		(layer "In11.Cu")
		(net "P3E_CPU0_PE3_OCP_RXN<15>")
	)
	(arc
		(start 296.31513 -99.786186)
		(mid 296.26166 -99.981249)
		(end 296.310304 -100.1776)
		(width 0.0889)
		(layer "In11.Cu")
		(net "P3E_CPU0_PE3_OCP_RXN<15>")
	)
	(arc
		(start 299.215556 -90.175334)
		(mid 298.932339 -90.091053)
		(end 298.725336 -89.880186)
		(width 0.0889)
		(layer "In11.Cu")
		(net "P3E_CPU0_PE3_OCP_RXN<15>")
	)
	(arc
		(start 294.59809 -96.814386)
		(mid 294.595342 -97.209853)
		(end 294.933624 -97.414588)
		(width 0.0889)
		(layer "In11.Cu")
		(net "P3E_CPU0_PE3_OCP_RXN<15>")
	)
	(arc
		(start 298.031916 -89.880186)
		(mid 297.824912 -90.09105)
		(end 297.541696 -90.175334)
		(width 0.0889)
		(layer "In11.Cu")
		(net "P3E_CPU0_PE3_OCP_RXN<15>")
	)
	(arc
		(start 296.32148 -99.206304)
		(mid 296.394278 -99.497067)
		(end 296.31513 -99.786186)
		(width 0.0889)
		(layer "In11.Cu")
		(net "P3E_CPU0_PE3_OCP_RXN<15>")
	)
	(arc
		(start 296.31513 -100.186236)
		(mid 296.394352 -100.475354)
		(end 296.32148 -100.766118)
		(width 0.0889)
		(layer "In11.Cu")
		(net "P3E_CPU0_PE3_OCP_RXN<15>")
	)
	(arc
		(start 296.67962 -101.376734)
		(mid 296.964982 -101.460122)
		(end 297.17365 -101.671882)
		(width 0.0889)
		(layer "In11.Cu")
		(net "P3E_CPU0_PE3_OCP_RXN<15>")
	)
	(arc
		(start 300.571662 -89.440004)
		(mid 300.370252 -89.612957)
		(end 300.113446 -89.680288)
		(width 0.0889)
		(layer "In11.Cu")
		(net "P3E_CPU0_PE3_OCP_RXN<15>")
	)
	(arc
		(start 298.36364 -89.680288)
		(mid 298.171998 -89.737454)
		(end 298.031916 -89.880186)
		(width 0.0889)
		(layer "In11.Cu")
		(net "P3E_CPU0_PE3_OCP_RXN<15>")
	)
	(arc
		(start 294.59809 -94.833186)
		(mid 294.544591 -95.033084)
		(end 294.59809 -95.232982)
		(width 0.0889)
		(layer "In11.Cu")
		(net "P3E_CPU0_PE3_OCP_RXN<15>")
	)
	(segment
		(start 460.864458 -118.608602)
		(end 460.864458 -121.36882)
		(width 0.1143)
		(layer "F.Cu")
		(net "P3E_CPU0_PE3_OCP_RXN<14>")
	)
	(segment
		(start 460.739998 -121.49328)
		(end 460.34325 -121.49328)
		(width 0.1143)
		(layer "F.Cu")
		(net "P3E_CPU0_PE3_OCP_RXN<14>")
	)
	(segment
		(start 460.600806 -116.993162)
		(end 460.600806 -118.342918)
		(width 0.1143)
		(layer "F.Cu")
		(net "P3E_CPU0_PE3_OCP_RXN<14>")
	)
	(segment
		(start 460.864458 -121.36882)
		(end 460.739998 -121.49328)
		(width 0.1143)
		(layer "F.Cu")
		(net "P3E_CPU0_PE3_OCP_RXN<14>")
	)
	(segment
		(start 298.665646 -90.575384)
		(end 299.237146 -90.575384)
		(width 0.1143)
		(layer "F.Cu")
		(net "P3E_CPU0_PE3_OCP_RXN<14>")
	)
	(segment
		(start 460.59979 -118.343934)
		(end 460.864458 -118.608602)
		(width 0.1143)
		(layer "F.Cu")
		(net "P3E_CPU0_PE3_OCP_RXN<14>")
	)
	(segment
		(start 460.600806 -118.342918)
		(end 460.59979 -118.343934)
		(width 0.1143)
		(layer "F.Cu")
		(net "P3E_CPU0_PE3_OCP_RXN<14>")
	)
	(via
		(at 460.34325 -121.49328)
		(size 0.508)
		(drill 0.254)
		(layers "F.Cu" "B.Cu")
		(net "P3E_CPU0_PE3_OCP_RXN<14>")
	)
	(via
		(at 299.237146 -90.575384)
		(size 0.508)
		(drill 0.254)
		(layers "F.Cu" "B.Cu")
		(net "P3E_CPU0_PE3_OCP_RXN<14>")
	)
	(segment
		(start 297.008296 -98.205036)
		(end 296.999406 -98.220276)
		(width 0.0889)
		(layer "In11.Cu")
		(net "P3E_CPU0_PE3_OCP_RXN<14>")
	)
	(segment
		(start 394.394944 -145.875502)
		(end 396.155672 -147.248626)
		(width 0.1143)
		(layer "In11.Cu")
		(net "P3E_CPU0_PE3_OCP_RXN<14>")
	)
	(segment
		(start 301.17923 -104.36479)
		(end 301.17923 -104.436164)
		(width 0.0889)
		(layer "In11.Cu")
		(net "P3E_CPU0_PE3_OCP_RXN<14>")
	)
	(segment
		(start 391.39241 -145.5039)
		(end 394.394944 -145.875502)
		(width 0.1143)
		(layer "In11.Cu")
		(net "P3E_CPU0_PE3_OCP_RXN<14>")
	)
	(segment
		(start 459.439264 -121.435876)
		(end 459.97114 -120.904)
		(width 0.1143)
		(layer "In11.Cu")
		(net "P3E_CPU0_PE3_OCP_RXN<14>")
	)
	(segment
		(start 295.29151 -93.252036)
		(end 295.28516 -93.262704)
		(width 0.0889)
		(layer "In11.Cu")
		(net "P3E_CPU0_PE3_OCP_RXN<14>")
	)
	(segment
		(start 458.807312 -122.231404)
		(end 458.807312 -122.067828)
		(width 0.1143)
		(layer "In11.Cu")
		(net "P3E_CPU0_PE3_OCP_RXN<14>")
	)
	(segment
		(start 323.86524 -119.687594)
		(end 323.86524 -122.468386)
		(width 0.1143)
		(layer "In11.Cu")
		(net "P3E_CPU0_PE3_OCP_RXN<14>")
	)
	(segment
		(start 355.52507 -134.146544)
		(end 358.125522 -131.546092)
		(width 0.1143)
		(layer "In11.Cu")
		(net "P3E_CPU0_PE3_OCP_RXN<14>")
	)
	(segment
		(start 318.643 -117.602)
		(end 320.36385 -119.32285)
		(width 0.1143)
		(layer "In11.Cu")
		(net "P3E_CPU0_PE3_OCP_RXN<14>")
	)
	(segment
		(start 297.502326 -101.072188)
		(end 297.53814 -101.072188)
		(width 0.0889)
		(layer "In11.Cu")
		(net "P3E_CPU0_PE3_OCP_RXN<14>")
	)
	(segment
		(start 302.55972 -105.8164)
		(end 305.656742 -105.8164)
		(width 0.1143)
		(layer "In11.Cu")
		(net "P3E_CPU0_PE3_OCP_RXN<14>")
	)
	(segment
		(start 426.993558 -141.352778)
		(end 428.248572 -141.656308)
		(width 0.1143)
		(layer "In11.Cu")
		(net "P3E_CPU0_PE3_OCP_RXN<14>")
	)
	(segment
		(start 460.647288 -120.904)
		(end 460.83855 -121.095262)
		(width 0.1143)
		(layer "In11.Cu")
		(net "P3E_CPU0_PE3_OCP_RXN<14>")
	)
	(segment
		(start 331.964792 -128.721104)
		(end 336.758026 -130.705098)
		(width 0.1143)
		(layer "In11.Cu")
		(net "P3E_CPU0_PE3_OCP_RXN<14>")
	)
	(segment
		(start 458.102716 -122.772424)
		(end 458.40142 -122.47372)
		(width 0.1143)
		(layer "In11.Cu")
		(net "P3E_CPU0_PE3_OCP_RXN<14>")
	)
	(segment
		(start 366.3442 -135.08736)
		(end 366.3442 -138.307064)
		(width 0.1143)
		(layer "In11.Cu")
		(net "P3E_CPU0_PE3_OCP_RXN<14>")
	)
	(segment
		(start 458.564996 -122.47372)
		(end 458.807312 -122.231404)
		(width 0.1143)
		(layer "In11.Cu")
		(net "P3E_CPU0_PE3_OCP_RXN<14>")
	)
	(segment
		(start 417.596828 -146.29638)
		(end 418.31133 -146.000216)
		(width 0.1143)
		(layer "In11.Cu")
		(net "P3E_CPU0_PE3_OCP_RXN<14>")
	)
	(segment
		(start 336.758026 -130.705098)
		(end 337.84667 -132.8039)
		(width 0.1143)
		(layer "In11.Cu")
		(net "P3E_CPU0_PE3_OCP_RXN<14>")
	)
	(segment
		(start 323.86524 -122.468386)
		(end 328.482706 -127.085852)
		(width 0.1143)
		(layer "In11.Cu")
		(net "P3E_CPU0_PE3_OCP_RXN<14>")
	)
	(segment
		(start 396.277084 -147.304506)
		(end 397.06677 -147.465288)
		(width 0.1143)
		(layer "In11.Cu")
		(net "P3E_CPU0_PE3_OCP_RXN<14>")
	)
	(segment
		(start 456.23607 -123.5456)
		(end 457.163932 -123.161298)
		(width 0.1143)
		(layer "In11.Cu")
		(net "P3E_CPU0_PE3_OCP_RXN<14>")
	)
	(segment
		(start 450.768466 -127.85344)
		(end 452.24954 -124.27966)
		(width 0.1143)
		(layer "In11.Cu")
		(net "P3E_CPU0_PE3_OCP_RXN<14>")
	)
	(segment
		(start 419.2778 -144.386554)
		(end 419.2778 -142.545054)
		(width 0.1143)
		(layer "In11.Cu")
		(net "P3E_CPU0_PE3_OCP_RXN<14>")
	)
	(segment
		(start 403.556978 -146.051778)
		(end 406.40762 -146.618706)
		(width 0.1143)
		(layer "In11.Cu")
		(net "P3E_CPU0_PE3_OCP_RXN<14>")
	)
	(segment
		(start 359.626408 -130.9243)
		(end 361.530138 -130.9243)
		(width 0.1143)
		(layer "In11.Cu")
		(net "P3E_CPU0_PE3_OCP_RXN<14>")
	)
	(segment
		(start 408.479752 -146.29638)
		(end 409.477972 -147.2946)
		(width 0.1143)
		(layer "In11.Cu")
		(net "P3E_CPU0_PE3_OCP_RXN<14>")
	)
	(segment
		(start 421.869108 -141.815312)
		(end 424.820588 -141.26083)
		(width 0.1143)
		(layer "In11.Cu")
		(net "P3E_CPU0_PE3_OCP_RXN<14>")
	)
	(segment
		(start 364.089188 -131.984242)
		(end 365.744252 -133.639306)
		(width 0.1143)
		(layer "In11.Cu")
		(net "P3E_CPU0_PE3_OCP_RXN<14>")
	)
	(segment
		(start 452.24954 -124.27966)
		(end 452.983346 -123.5456)
		(width 0.1143)
		(layer "In11.Cu")
		(net "P3E_CPU0_PE3_OCP_RXN<14>")
	)
	(segment
		(start 431.77841 -141.589252)
		(end 436.690262 -140.198856)
		(width 0.1143)
		(layer "In11.Cu")
		(net "P3E_CPU0_PE3_OCP_RXN<14>")
	)
	(segment
		(start 300.5455 -102.796594)
		(end 300.5455 -103.730806)
		(width 0.0889)
		(layer "In11.Cu")
		(net "P3E_CPU0_PE3_OCP_RXN<14>")
	)
	(segment
		(start 459.196948 -121.821448)
		(end 459.439264 -121.579132)
		(width 0.1143)
		(layer "In11.Cu")
		(net "P3E_CPU0_PE3_OCP_RXN<14>")
	)
	(segment
		(start 418.819838 -145.491708)
		(end 419.2778 -144.386554)
		(width 0.1143)
		(layer "In11.Cu")
		(net "P3E_CPU0_PE3_OCP_RXN<14>")
	)
	(segment
		(start 297.535092 -90.975434)
		(end 297.502326 -90.975434)
		(width 0.0889)
		(layer "In11.Cu")
		(net "P3E_CPU0_PE3_OCP_RXN<14>")
	)
	(segment
		(start 418.31133 -146.000216)
		(end 418.819838 -145.491708)
		(width 0.1143)
		(layer "In11.Cu")
		(net "P3E_CPU0_PE3_OCP_RXN<14>")
	)
	(segment
		(start 397.06677 -147.465288)
		(end 403.556978 -146.051778)
		(width 0.1143)
		(layer "In11.Cu")
		(net "P3E_CPU0_PE3_OCP_RXN<14>")
	)
	(segment
		(start 300.890178 -104.075738)
		(end 301.17923 -104.36479)
		(width 0.0889)
		(layer "In11.Cu")
		(net "P3E_CPU0_PE3_OCP_RXN<14>")
	)
	(segment
		(start 459.439264 -121.579132)
		(end 459.439264 -121.435876)
		(width 0.1143)
		(layer "In11.Cu")
		(net "P3E_CPU0_PE3_OCP_RXN<14>")
	)
	(segment
		(start 457.69657 -123.119388)
		(end 457.785978 -122.903742)
		(width 0.1143)
		(layer "In11.Cu")
		(net "P3E_CPU0_PE3_OCP_RXN<14>")
	)
	(segment
		(start 323.500496 -119.32285)
		(end 323.86524 -119.687594)
		(width 0.1143)
		(layer "In11.Cu")
		(net "P3E_CPU0_PE3_OCP_RXN<14>")
	)
	(segment
		(start 300.5455 -103.730806)
		(end 300.890178 -104.075484)
		(width 0.0889)
		(layer "In11.Cu")
		(net "P3E_CPU0_PE3_OCP_RXN<14>")
	)
	(segment
		(start 385.665472 -143.816324)
		(end 388.762748 -143.816324)
		(width 0.1143)
		(layer "In11.Cu")
		(net "P3E_CPU0_PE3_OCP_RXN<14>")
	)
	(segment
		(start 295.296336 -94.234)
		(end 295.29151 -94.242636)
		(width 0.0889)
		(layer "In11.Cu")
		(net "P3E_CPU0_PE3_OCP_RXN<14>")
	)
	(segment
		(start 380.385828 -141.66088)
		(end 385.665472 -143.816324)
		(width 0.1143)
		(layer "In11.Cu")
		(net "P3E_CPU0_PE3_OCP_RXN<14>")
	)
	(segment
		(start 296.66184 -91.470988)
		(end 296.64025 -91.470988)
		(width 0.0889)
		(layer "In11.Cu")
		(net "P3E_CPU0_PE3_OCP_RXN<14>")
	)
	(segment
		(start 390.066276 -144.425162)
		(end 390.493504 -145.113756)
		(width 0.1143)
		(layer "In11.Cu")
		(net "P3E_CPU0_PE3_OCP_RXN<14>")
	)
	(segment
		(start 330.329286 -127.085852)
		(end 331.964792 -128.721104)
		(width 0.1143)
		(layer "In11.Cu")
		(net "P3E_CPU0_PE3_OCP_RXN<14>")
	)
	(segment
		(start 297.008296 -91.270836)
		(end 297.004994 -91.276678)
		(width 0.0889)
		(layer "In11.Cu")
		(net "P3E_CPU0_PE3_OCP_RXN<14>")
	)
	(segment
		(start 419.2778 -142.545054)
		(end 419.844982 -141.977872)
		(width 0.1143)
		(layer "In11.Cu")
		(net "P3E_CPU0_PE3_OCP_RXN<14>")
	)
	(segment
		(start 459.053692 -121.821448)
		(end 459.196948 -121.821448)
		(width 0.1143)
		(layer "In11.Cu")
		(net "P3E_CPU0_PE3_OCP_RXN<14>")
	)
	(segment
		(start 460.83855 -121.095262)
		(end 460.83855 -121.35485)
		(width 0.1143)
		(layer "In11.Cu")
		(net "P3E_CPU0_PE3_OCP_RXN<14>")
	)
	(segment
		(start 460.70012 -121.49328)
		(end 460.34325 -121.49328)
		(width 0.1143)
		(layer "In11.Cu")
		(net "P3E_CPU0_PE3_OCP_RXN<14>")
	)
	(segment
		(start 378.730764 -141.99743)
		(end 380.385828 -141.66088)
		(width 0.1143)
		(layer "In11.Cu")
		(net "P3E_CPU0_PE3_OCP_RXN<14>")
	)
	(segment
		(start 295.78173 -97.109534)
		(end 295.814496 -97.109534)
		(width 0.0889)
		(layer "In11.Cu")
		(net "P3E_CPU0_PE3_OCP_RXN<14>")
	)
	(segment
		(start 424.820588 -141.26083)
		(end 426.1866 -141.541754)
		(width 0.1143)
		(layer "In11.Cu")
		(net "P3E_CPU0_PE3_OCP_RXN<14>")
	)
	(segment
		(start 295.296336 -93.2434)
		(end 295.29151 -93.252036)
		(width 0.0889)
		(layer "In11.Cu")
		(net "P3E_CPU0_PE3_OCP_RXN<14>")
	)
	(segment
		(start 298.365672 -101.567488)
		(end 298.393612 -101.567488)
		(width 0.0889)
		(layer "In11.Cu")
		(net "P3E_CPU0_PE3_OCP_RXN<14>")
	)
	(segment
		(start 297.008296 -99.195636)
		(end 296.999406 -99.210876)
		(width 0.0889)
		(layer "In11.Cu")
		(net "P3E_CPU0_PE3_OCP_RXN<14>")
	)
	(segment
		(start 300.077886 -102.558088)
		(end 300.306994 -102.558088)
		(width 0.0889)
		(layer "In11.Cu")
		(net "P3E_CPU0_PE3_OCP_RXN<14>")
	)
	(segment
		(start 428.248572 -141.656308)
		(end 430.444402 -141.244828)
		(width 0.1143)
		(layer "In11.Cu")
		(net "P3E_CPU0_PE3_OCP_RXN<14>")
	)
	(segment
		(start 458.40142 -122.47372)
		(end 458.564996 -122.47372)
		(width 0.1143)
		(layer "In11.Cu")
		(net "P3E_CPU0_PE3_OCP_RXN<14>")
	)
	(segment
		(start 426.1866 -141.541754)
		(end 426.993558 -141.352778)
		(width 0.1143)
		(layer "In11.Cu")
		(net "P3E_CPU0_PE3_OCP_RXN<14>")
	)
	(segment
		(start 396.155672 -147.248626)
		(end 396.277084 -147.304506)
		(width 0.1143)
		(layer "In11.Cu")
		(net "P3E_CPU0_PE3_OCP_RXN<14>")
	)
	(segment
		(start 366.77854 -139.355322)
		(end 367.207038 -139.653264)
		(width 0.1143)
		(layer "In11.Cu")
		(net "P3E_CPU0_PE3_OCP_RXN<14>")
	)
	(segment
		(start 457.379832 -123.250706)
		(end 457.69657 -123.119388)
		(width 0.1143)
		(layer "In11.Cu")
		(net "P3E_CPU0_PE3_OCP_RXN<14>")
	)
	(segment
		(start 301.238666 -104.4956)
		(end 302.55972 -105.8164)
		(width 0.1143)
		(layer "In11.Cu")
		(net "P3E_CPU0_PE3_OCP_RXN<14>")
	)
	(segment
		(start 342.06561 -134.146544)
		(end 355.52507 -134.146544)
		(width 0.1143)
		(layer "In11.Cu")
		(net "P3E_CPU0_PE3_OCP_RXN<14>")
	)
	(segment
		(start 300.890178 -104.075484)
		(end 300.890178 -104.075738)
		(width 0.0889)
		(layer "In11.Cu")
		(net "P3E_CPU0_PE3_OCP_RXN<14>")
	)
	(segment
		(start 457.163932 -123.161298)
		(end 457.379832 -123.250706)
		(width 0.1143)
		(layer "In11.Cu")
		(net "P3E_CPU0_PE3_OCP_RXN<14>")
	)
	(segment
		(start 452.983346 -123.5456)
		(end 456.23607 -123.5456)
		(width 0.1143)
		(layer "In11.Cu")
		(net "P3E_CPU0_PE3_OCP_RXN<14>")
	)
	(segment
		(start 295.296336 -96.2152)
		(end 295.29151 -96.223836)
		(width 0.0889)
		(layer "In11.Cu")
		(net "P3E_CPU0_PE3_OCP_RXN<14>")
	)
	(segment
		(start 299.215556 -102.062534)
		(end 299.248322 -102.062534)
		(width 0.0889)
		(layer "In11.Cu")
		(net "P3E_CPU0_PE3_OCP_RXN<14>")
	)
	(segment
		(start 367.207038 -139.653264)
		(end 378.730764 -141.99743)
		(width 0.1143)
		(layer "In11.Cu")
		(net "P3E_CPU0_PE3_OCP_RXN<14>")
	)
	(segment
		(start 439.145934 -137.218928)
		(end 440.501786 -134.218172)
		(width 0.1143)
		(layer "In11.Cu")
		(net "P3E_CPU0_PE3_OCP_RXN<14>")
	)
	(segment
		(start 409.477972 -147.2946)
		(end 412.4452 -147.2946)
		(width 0.1143)
		(layer "In11.Cu")
		(net "P3E_CPU0_PE3_OCP_RXN<14>")
	)
	(segment
		(start 299.237146 -90.575384)
		(end 299.530262 -90.406474)
		(width 0.0889)
		(layer "In11.Cu")
		(net "P3E_CPU0_PE3_OCP_RXN<14>")
	)
	(segment
		(start 388.762748 -143.816324)
		(end 390.066276 -144.425162)
		(width 0.1143)
		(layer "In11.Cu")
		(net "P3E_CPU0_PE3_OCP_RXN<14>")
	)
	(segment
		(start 445.684656 -131.63804)
		(end 450.768466 -127.85344)
		(width 0.1143)
		(layer "In11.Cu")
		(net "P3E_CPU0_PE3_OCP_RXN<14>")
	)
	(segment
		(start 413.44342 -146.29638)
		(end 417.596828 -146.29638)
		(width 0.1143)
		(layer "In11.Cu")
		(net "P3E_CPU0_PE3_OCP_RXN<14>")
	)
	(segment
		(start 317.442342 -117.602)
		(end 318.643 -117.602)
		(width 0.1143)
		(layer "In11.Cu")
		(net "P3E_CPU0_PE3_OCP_RXN<14>")
	)
	(segment
		(start 457.785978 -122.903742)
		(end 458.102716 -122.772424)
		(width 0.1143)
		(layer "In11.Cu")
		(net "P3E_CPU0_PE3_OCP_RXN<14>")
	)
	(segment
		(start 406.40762 -146.618706)
		(end 407.186384 -146.29638)
		(width 0.1143)
		(layer "In11.Cu")
		(net "P3E_CPU0_PE3_OCP_RXN<14>")
	)
	(segment
		(start 295.29151 -96.223836)
		(end 295.28516 -96.234504)
		(width 0.0889)
		(layer "In11.Cu")
		(net "P3E_CPU0_PE3_OCP_RXN<14>")
	)
	(segment
		(start 366.3442 -138.307064)
		(end 366.77854 -139.355322)
		(width 0.1143)
		(layer "In11.Cu")
		(net "P3E_CPU0_PE3_OCP_RXN<14>")
	)
	(segment
		(start 295.28516 -94.822518)
		(end 295.29151 -94.833186)
		(width 0.0889)
		(layer "In11.Cu")
		(net "P3E_CPU0_PE3_OCP_RXN<14>")
	)
	(segment
		(start 440.501786 -134.218172)
		(end 445.684656 -131.63804)
		(width 0.1143)
		(layer "In11.Cu")
		(net "P3E_CPU0_PE3_OCP_RXN<14>")
	)
	(segment
		(start 365.744252 -133.639306)
		(end 366.3442 -135.08736)
		(width 0.1143)
		(layer "In11.Cu")
		(net "P3E_CPU0_PE3_OCP_RXN<14>")
	)
	(segment
		(start 328.482706 -127.085852)
		(end 330.329286 -127.085852)
		(width 0.1143)
		(layer "In11.Cu")
		(net "P3E_CPU0_PE3_OCP_RXN<14>")
	)
	(segment
		(start 407.186384 -146.29638)
		(end 408.479752 -146.29638)
		(width 0.1143)
		(layer "In11.Cu")
		(net "P3E_CPU0_PE3_OCP_RXN<14>")
	)
	(segment
		(start 295.818306 -91.966034)
		(end 295.78554 -91.966034)
		(width 0.0889)
		(layer "In11.Cu")
		(net "P3E_CPU0_PE3_OCP_RXN<14>")
	)
	(segment
		(start 299.530262 -90.406474)
		(end 299.609002 -90.42781)
		(width 0.0889)
		(layer "In11.Cu")
		(net "P3E_CPU0_PE3_OCP_RXN<14>")
	)
	(segment
		(start 430.444402 -141.244828)
		(end 431.77841 -141.589252)
		(width 0.1143)
		(layer "In11.Cu")
		(net "P3E_CPU0_PE3_OCP_RXN<14>")
	)
	(segment
		(start 301.17923 -104.436164)
		(end 301.238666 -104.4956)
		(width 0.0889)
		(layer "In11.Cu")
		(net "P3E_CPU0_PE3_OCP_RXN<14>")
	)
	(segment
		(start 458.807312 -122.067828)
		(end 459.053692 -121.821448)
		(width 0.1143)
		(layer "In11.Cu")
		(net "P3E_CPU0_PE3_OCP_RXN<14>")
	)
	(segment
		(start 419.844982 -141.977872)
		(end 421.072564 -141.61516)
		(width 0.1143)
		(layer "In11.Cu")
		(net "P3E_CPU0_PE3_OCP_RXN<14>")
	)
	(segment
		(start 299.252132 -90.975434)
		(end 299.22216 -90.975434)
		(width 0.0889)
		(layer "In11.Cu")
		(net "P3E_CPU0_PE3_OCP_RXN<14>")
	)
	(segment
		(start 361.530138 -130.9243)
		(end 364.089188 -131.984242)
		(width 0.1143)
		(layer "In11.Cu")
		(net "P3E_CPU0_PE3_OCP_RXN<14>")
	)
	(segment
		(start 436.690262 -140.198856)
		(end 439.145934 -137.218928)
		(width 0.1143)
		(layer "In11.Cu")
		(net "P3E_CPU0_PE3_OCP_RXN<14>")
	)
	(segment
		(start 337.84667 -132.8039)
		(end 342.06561 -134.146544)
		(width 0.1143)
		(layer "In11.Cu")
		(net "P3E_CPU0_PE3_OCP_RXN<14>")
	)
	(segment
		(start 300.306994 -102.558088)
		(end 300.5455 -102.796594)
		(width 0.0889)
		(layer "In11.Cu")
		(net "P3E_CPU0_PE3_OCP_RXN<14>")
	)
	(segment
		(start 412.4452 -147.2946)
		(end 413.44342 -146.29638)
		(width 0.1143)
		(layer "In11.Cu")
		(net "P3E_CPU0_PE3_OCP_RXN<14>")
	)
	(segment
		(start 358.125522 -131.546092)
		(end 359.626408 -130.9243)
		(width 0.1143)
		(layer "In11.Cu")
		(net "P3E_CPU0_PE3_OCP_RXN<14>")
	)
	(segment
		(start 421.072564 -141.61516)
		(end 421.869108 -141.815312)
		(width 0.1143)
		(layer "In11.Cu")
		(net "P3E_CPU0_PE3_OCP_RXN<14>")
	)
	(segment
		(start 296.64406 -97.605088)
		(end 296.66184 -97.605088)
		(width 0.0889)
		(layer "In11.Cu")
		(net "P3E_CPU0_PE3_OCP_RXN<14>")
	)
	(segment
		(start 460.83855 -121.35485)
		(end 460.70012 -121.49328)
		(width 0.1143)
		(layer "In11.Cu")
		(net "P3E_CPU0_PE3_OCP_RXN<14>")
	)
	(segment
		(start 390.493504 -145.113756)
		(end 391.39241 -145.5039)
		(width 0.1143)
		(layer "In11.Cu")
		(net "P3E_CPU0_PE3_OCP_RXN<14>")
	)
	(segment
		(start 320.36385 -119.32285)
		(end 323.500496 -119.32285)
		(width 0.1143)
		(layer "In11.Cu")
		(net "P3E_CPU0_PE3_OCP_RXN<14>")
	)
	(segment
		(start 305.656742 -105.8164)
		(end 317.442342 -117.602)
		(width 0.1143)
		(layer "In11.Cu")
		(net "P3E_CPU0_PE3_OCP_RXN<14>")
	)
	(segment
		(start 298.400216 -90.480388)
		(end 298.357036 -90.480388)
		(width 0.0889)
		(layer "In11.Cu")
		(net "P3E_CPU0_PE3_OCP_RXN<14>")
	)
	(segment
		(start 459.97114 -120.904)
		(end 460.647288 -120.904)
		(width 0.1143)
		(layer "In11.Cu")
		(net "P3E_CPU0_PE3_OCP_RXN<14>")
	)
	(arc
		(start 298.393612 -101.567488)
		(mid 298.585254 -101.624654)
		(end 298.725336 -101.767386)
		(width 0.0889)
		(layer "In11.Cu")
		(net "P3E_CPU0_PE3_OCP_RXN<14>")
	)
	(arc
		(start 299.248322 -102.062534)
		(mid 299.442172 -102.118884)
		(end 299.583856 -102.262686)
		(width 0.0889)
		(layer "In11.Cu")
		(net "P3E_CPU0_PE3_OCP_RXN<14>")
	)
	(arc
		(start 298.357036 -90.480388)
		(mid 298.073819 -90.564669)
		(end 297.866816 -90.775536)
		(width 0.0889)
		(layer "In11.Cu")
		(net "P3E_CPU0_PE3_OCP_RXN<14>")
	)
	(arc
		(start 299.583856 -102.262686)
		(mid 299.792464 -102.474618)
		(end 300.077886 -102.558088)
		(width 0.0889)
		(layer "In11.Cu")
		(net "P3E_CPU0_PE3_OCP_RXN<14>")
	)
	(arc
		(start 295.29151 -95.232982)
		(mid 295.212379 -95.528384)
		(end 295.29151 -95.823786)
		(width 0.0889)
		(layer "In11.Cu")
		(net "P3E_CPU0_PE3_OCP_RXN<14>")
	)
	(arc
		(start 297.008296 -100.186236)
		(mid 297.003967 -100.769408)
		(end 297.502326 -101.072188)
		(width 0.0889)
		(layer "In11.Cu")
		(net "P3E_CPU0_PE3_OCP_RXN<14>")
	)
	(arc
		(start 295.29151 -95.823786)
		(mid 295.34498 -96.018849)
		(end 295.296336 -96.2152)
		(width 0.0889)
		(layer "In11.Cu")
		(net "P3E_CPU0_PE3_OCP_RXN<14>")
	)
	(arc
		(start 295.29151 -94.833186)
		(mid 295.345009 -95.033084)
		(end 295.29151 -95.232982)
		(width 0.0889)
		(layer "In11.Cu")
		(net "P3E_CPU0_PE3_OCP_RXN<14>")
	)
	(arc
		(start 295.29151 -92.851986)
		(mid 295.34498 -93.047049)
		(end 295.296336 -93.2434)
		(width 0.0889)
		(layer "In11.Cu")
		(net "P3E_CPU0_PE3_OCP_RXN<14>")
	)
	(arc
		(start 297.008296 -99.78644)
		(mid 297.061829 -99.986338)
		(end 297.008296 -100.186236)
		(width 0.0889)
		(layer "In11.Cu")
		(net "P3E_CPU0_PE3_OCP_RXN<14>")
	)
	(arc
		(start 297.866816 -101.272086)
		(mid 298.077529 -101.485165)
		(end 298.365672 -101.567488)
		(width 0.0889)
		(layer "In11.Cu")
		(net "P3E_CPU0_PE3_OCP_RXN<14>")
	)
	(arc
		(start 299.609002 -90.42781)
		(mid 299.572262 -90.793949)
		(end 299.252132 -90.975434)
		(width 0.0889)
		(layer "In11.Cu")
		(net "P3E_CPU0_PE3_OCP_RXN<14>")
	)
	(arc
		(start 297.004994 -91.276678)
		(mid 296.859028 -91.419077)
		(end 296.66184 -91.470988)
		(width 0.0889)
		(layer "In11.Cu")
		(net "P3E_CPU0_PE3_OCP_RXN<14>")
	)
	(arc
		(start 296.66184 -97.605088)
		(mid 297.008266 -97.805065)
		(end 297.008296 -98.205036)
		(width 0.0889)
		(layer "In11.Cu")
		(net "P3E_CPU0_PE3_OCP_RXN<14>")
	)
	(arc
		(start 295.29151 -94.242636)
		(mid 295.212288 -94.531754)
		(end 295.28516 -94.822518)
		(width 0.0889)
		(layer "In11.Cu")
		(net "P3E_CPU0_PE3_OCP_RXN<14>")
	)
	(arc
		(start 295.78554 -91.966034)
		(mid 295.287289 -92.268874)
		(end 295.29151 -92.851986)
		(width 0.0889)
		(layer "In11.Cu")
		(net "P3E_CPU0_PE3_OCP_RXN<14>")
	)
	(arc
		(start 295.28516 -93.262704)
		(mid 295.212362 -93.553467)
		(end 295.29151 -93.842586)
		(width 0.0889)
		(layer "In11.Cu")
		(net "P3E_CPU0_PE3_OCP_RXN<14>")
	)
	(arc
		(start 296.999406 -99.210876)
		(mid 296.929009 -99.499827)
		(end 297.008296 -99.78644)
		(width 0.0889)
		(layer "In11.Cu")
		(net "P3E_CPU0_PE3_OCP_RXN<14>")
	)
	(arc
		(start 295.29151 -93.842586)
		(mid 295.34498 -94.037649)
		(end 295.296336 -94.234)
		(width 0.0889)
		(layer "In11.Cu")
		(net "P3E_CPU0_PE3_OCP_RXN<14>")
	)
	(arc
		(start 295.28516 -96.234504)
		(mid 295.289191 -96.810686)
		(end 295.78173 -97.109534)
		(width 0.0889)
		(layer "In11.Cu")
		(net "P3E_CPU0_PE3_OCP_RXN<14>")
	)
	(arc
		(start 297.008296 -98.79584)
		(mid 297.061829 -98.995738)
		(end 297.008296 -99.195636)
		(width 0.0889)
		(layer "In11.Cu")
		(net "P3E_CPU0_PE3_OCP_RXN<14>")
	)
	(arc
		(start 297.502326 -90.975434)
		(mid 297.216902 -91.058901)
		(end 297.008296 -91.270836)
		(width 0.0889)
		(layer "In11.Cu")
		(net "P3E_CPU0_PE3_OCP_RXN<14>")
	)
	(arc
		(start 298.725336 -101.767386)
		(mid 298.93234 -101.97825)
		(end 299.215556 -102.062534)
		(width 0.0889)
		(layer "In11.Cu")
		(net "P3E_CPU0_PE3_OCP_RXN<14>")
	)
	(arc
		(start 296.15003 -91.766136)
		(mid 296.009951 -91.908872)
		(end 295.818306 -91.966034)
		(width 0.0889)
		(layer "In11.Cu")
		(net "P3E_CPU0_PE3_OCP_RXN<14>")
	)
	(arc
		(start 296.15003 -97.309686)
		(mid 296.358638 -97.521618)
		(end 296.64406 -97.605088)
		(width 0.0889)
		(layer "In11.Cu")
		(net "P3E_CPU0_PE3_OCP_RXN<14>")
	)
	(arc
		(start 298.890436 -90.775536)
		(mid 298.683432 -90.564672)
		(end 298.400216 -90.480388)
		(width 0.0889)
		(layer "In11.Cu")
		(net "P3E_CPU0_PE3_OCP_RXN<14>")
	)
	(arc
		(start 299.22216 -90.975434)
		(mid 299.030518 -90.918268)
		(end 298.890436 -90.775536)
		(width 0.0889)
		(layer "In11.Cu")
		(net "P3E_CPU0_PE3_OCP_RXN<14>")
	)
	(arc
		(start 297.53814 -101.072188)
		(mid 297.728069 -101.130058)
		(end 297.866816 -101.272086)
		(width 0.0889)
		(layer "In11.Cu")
		(net "P3E_CPU0_PE3_OCP_RXN<14>")
	)
	(arc
		(start 297.866816 -90.775536)
		(mid 297.726737 -90.918272)
		(end 297.535092 -90.975434)
		(width 0.0889)
		(layer "In11.Cu")
		(net "P3E_CPU0_PE3_OCP_RXN<14>")
	)
	(arc
		(start 296.999406 -98.220276)
		(mid 296.929009 -98.509227)
		(end 297.008296 -98.79584)
		(width 0.0889)
		(layer "In11.Cu")
		(net "P3E_CPU0_PE3_OCP_RXN<14>")
	)
	(arc
		(start 295.814496 -97.109534)
		(mid 296.008346 -97.165884)
		(end 296.15003 -97.309686)
		(width 0.0889)
		(layer "In11.Cu")
		(net "P3E_CPU0_PE3_OCP_RXN<14>")
	)
	(arc
		(start 296.64025 -91.470988)
		(mid 296.357033 -91.555269)
		(end 296.15003 -91.766136)
		(width 0.0889)
		(layer "In11.Cu")
		(net "P3E_CPU0_PE3_OCP_RXN<14>")
	)
	(segment
		(start 457.400914 -116.993162)
		(end 457.400914 -118.241318)
		(width 0.1143)
		(layer "F.Cu")
		(net "P3E_CPU0_PE3_OCP_RXN<13>")
	)
	(segment
		(start 457.399898 -118.242334)
		(end 457.679298 -118.521734)
		(width 0.1143)
		(layer "F.Cu")
		(net "P3E_CPU0_PE3_OCP_RXN<13>")
	)
	(segment
		(start 457.679298 -118.769892)
		(end 458.12202 -119.838724)
		(width 0.1143)
		(layer "F.Cu")
		(net "P3E_CPU0_PE3_OCP_RXN<13>")
	)
	(segment
		(start 458.12202 -120.24995)
		(end 457.9874 -120.38457)
		(width 0.1143)
		(layer "F.Cu")
		(net "P3E_CPU0_PE3_OCP_RXN<13>")
	)
	(segment
		(start 457.9874 -120.38457)
		(end 457.58735 -120.38457)
		(width 0.1143)
		(layer "F.Cu")
		(net "P3E_CPU0_PE3_OCP_RXN<13>")
	)
	(segment
		(start 457.679298 -118.521734)
		(end 457.679298 -118.769892)
		(width 0.1143)
		(layer "F.Cu")
		(net "P3E_CPU0_PE3_OCP_RXN<13>")
	)
	(segment
		(start 298.665646 -91.565984)
		(end 299.237146 -91.565984)
		(width 0.1143)
		(layer "F.Cu")
		(net "P3E_CPU0_PE3_OCP_RXN<13>")
	)
	(segment
		(start 457.400914 -118.241318)
		(end 457.399898 -118.242334)
		(width 0.1143)
		(layer "F.Cu")
		(net "P3E_CPU0_PE3_OCP_RXN<13>")
	)
	(segment
		(start 458.12202 -119.838724)
		(end 458.12202 -120.24995)
		(width 0.1143)
		(layer "F.Cu")
		(net "P3E_CPU0_PE3_OCP_RXN<13>")
	)
	(via
		(at 299.237146 -91.565984)
		(size 0.508)
		(drill 0.254)
		(layers "F.Cu" "B.Cu")
		(net "P3E_CPU0_PE3_OCP_RXN<13>")
	)
	(via
		(at 457.58735 -120.38457)
		(size 0.508)
		(drill 0.254)
		(layers "F.Cu" "B.Cu")
		(net "P3E_CPU0_PE3_OCP_RXN<13>")
	)
	(segment
		(start 451.284848 -123.84024)
		(end 450.451474 -125.852174)
		(width 0.1143)
		(layer "In11.Cu")
		(net "P3E_CPU0_PE3_OCP_RXN<13>")
	)
	(segment
		(start 307.72735 -105.912666)
		(end 307.47589 -105.661206)
		(width 0.1143)
		(layer "In11.Cu")
		(net "P3E_CPU0_PE3_OCP_RXN<13>")
	)
	(segment
		(start 308.212236 -106.397552)
		(end 307.97881 -106.397552)
		(width 0.1143)
		(layer "In11.Cu")
		(net "P3E_CPU0_PE3_OCP_RXN<13>")
	)
	(segment
		(start 302.619156 -104.415844)
		(end 302.0949 -103.891588)
		(width 0.1143)
		(layer "In11.Cu")
		(net "P3E_CPU0_PE3_OCP_RXN<13>")
	)
	(segment
		(start 430.476406 -140.293852)
		(end 428.273718 -140.706856)
		(width 0.1143)
		(layer "In11.Cu")
		(net "P3E_CPU0_PE3_OCP_RXN<13>")
	)
	(segment
		(start 368.195606 -136.593326)
		(end 366.845596 -133.334252)
		(width 0.1143)
		(layer "In11.Cu")
		(net "P3E_CPU0_PE3_OCP_RXN<13>")
	)
	(segment
		(start 434.235098 -139.894564)
		(end 433.904898 -139.987274)
		(width 0.1143)
		(layer "In11.Cu")
		(net "P3E_CPU0_PE3_OCP_RXN<13>")
	)
	(segment
		(start 302.0441 -103.156512)
		(end 301.242222 -102.354634)
		(width 0.0889)
		(layer "In11.Cu")
		(net "P3E_CPU0_PE3_OCP_RXN<13>")
	)
	(segment
		(start 357.296974 -130.773678)
		(end 355.75113 -130.473196)
		(width 0.1143)
		(layer "In11.Cu")
		(net "P3E_CPU0_PE3_OCP_RXN<13>")
	)
	(segment
		(start 330.93152 -126.119128)
		(end 328.86904 -126.119128)
		(width 0.1143)
		(layer "In11.Cu")
		(net "P3E_CPU0_PE3_OCP_RXN<13>")
	)
	(segment
		(start 309.200296 -107.619038)
		(end 309.200296 -107.385358)
		(width 0.1143)
		(layer "In11.Cu")
		(net "P3E_CPU0_PE3_OCP_RXN<13>")
	)
	(segment
		(start 335.519268 -128.190244)
		(end 335.519014 -128.18999)
		(width 0.1143)
		(layer "In11.Cu")
		(net "P3E_CPU0_PE3_OCP_RXN<13>")
	)
	(segment
		(start 298.031916 -98.205036)
		(end 298.02709 -98.1964)
		(width 0.0889)
		(layer "In11.Cu")
		(net "P3E_CPU0_PE3_OCP_RXN<13>")
	)
	(segment
		(start 306.254658 -104.6734)
		(end 303.24044 -104.6734)
		(width 0.1143)
		(layer "In11.Cu")
		(net "P3E_CPU0_PE3_OCP_RXN<13>")
	)
	(segment
		(start 301.116492 -102.085902)
		(end 300.97349 -102.085902)
		(width 0.0889)
		(layer "In11.Cu")
		(net "P3E_CPU0_PE3_OCP_RXN<13>")
	)
	(segment
		(start 297.537886 -96.919034)
		(end 297.520106 -96.919034)
		(width 0.0889)
		(layer "In11.Cu")
		(net "P3E_CPU0_PE3_OCP_RXN<13>")
	)
	(segment
		(start 342.499696 -128.032002)
		(end 339.55736 -127.459994)
		(width 0.1143)
		(layer "In11.Cu")
		(net "P3E_CPU0_PE3_OCP_RXN<13>")
	)
	(segment
		(start 428.273718 -140.706856)
		(end 426.997368 -140.397992)
		(width 0.1143)
		(layer "In11.Cu")
		(net "P3E_CPU0_PE3_OCP_RXN<13>")
	)
	(segment
		(start 420.190676 -140.29563)
		(end 418.183822 -140.826998)
		(width 0.1143)
		(layer "In11.Cu")
		(net "P3E_CPU0_PE3_OCP_RXN<13>")
	)
	(segment
		(start 298.031916 -99.195636)
		(end 298.02709 -99.187)
		(width 0.0889)
		(layer "In11.Cu")
		(net "P3E_CPU0_PE3_OCP_RXN<13>")
	)
	(segment
		(start 306.506118 -104.92486)
		(end 306.254658 -104.6734)
		(width 0.1143)
		(layer "In11.Cu")
		(net "P3E_CPU0_PE3_OCP_RXN<13>")
	)
	(segment
		(start 434.883052 -139.712192)
		(end 434.679344 -139.597892)
		(width 0.1143)
		(layer "In11.Cu")
		(net "P3E_CPU0_PE3_OCP_RXN<13>")
	)
	(segment
		(start 450.451474 -125.852174)
		(end 442.821568 -130.426968)
		(width 0.1143)
		(layer "In11.Cu")
		(net "P3E_CPU0_PE3_OCP_RXN<13>")
	)
	(segment
		(start 328.86904 -126.119128)
		(end 324.866 -122.116088)
		(width 0.1143)
		(layer "In11.Cu")
		(net "P3E_CPU0_PE3_OCP_RXN<13>")
	)
	(segment
		(start 297.176952 -96.724724)
		(end 297.17365 -96.718882)
		(width 0.0889)
		(layer "In11.Cu")
		(net "P3E_CPU0_PE3_OCP_RXN<13>")
	)
	(segment
		(start 300.672754 -101.785166)
		(end 300.607476 -101.672136)
		(width 0.0889)
		(layer "In11.Cu")
		(net "P3E_CPU0_PE3_OCP_RXN<13>")
	)
	(segment
		(start 435.860952 -139.43711)
		(end 435.657498 -139.32281)
		(width 0.1143)
		(layer "In11.Cu")
		(net "P3E_CPU0_PE3_OCP_RXN<13>")
	)
	(segment
		(start 300.97349 -102.085902)
		(end 300.672754 -101.785166)
		(width 0.0889)
		(layer "In11.Cu")
		(net "P3E_CPU0_PE3_OCP_RXN<13>")
	)
	(segment
		(start 458.0763 -120.49887)
		(end 458.0763 -121.101866)
		(width 0.1143)
		(layer "In11.Cu")
		(net "P3E_CPU0_PE3_OCP_RXN<13>")
	)
	(segment
		(start 348.448376 -129.055114)
		(end 347.968824 -129.76606)
		(width 0.1143)
		(layer "In11.Cu")
		(net "P3E_CPU0_PE3_OCP_RXN<13>")
	)
	(segment
		(start 297.17365 -93.347286)
		(end 297.18254 -93.332046)
		(width 0.0889)
		(layer "In11.Cu")
		(net "P3E_CPU0_PE3_OCP_RXN<13>")
	)
	(segment
		(start 435.327298 -139.415774)
		(end 435.212998 -139.619228)
		(width 0.1143)
		(layer "In11.Cu")
		(net "P3E_CPU0_PE3_OCP_RXN<13>")
	)
	(segment
		(start 355.75113 -130.473196)
		(end 353.921314 -129.238756)
		(width 0.1143)
		(layer "In11.Cu")
		(net "P3E_CPU0_PE3_OCP_RXN<13>")
	)
	(segment
		(start 431.69586 -140.608812)
		(end 430.476406 -140.293852)
		(width 0.1143)
		(layer "In11.Cu")
		(net "P3E_CPU0_PE3_OCP_RXN<13>")
	)
	(segment
		(start 301.242222 -102.354634)
		(end 301.242222 -102.211632)
		(width 0.0889)
		(layer "In11.Cu")
		(net "P3E_CPU0_PE3_OCP_RXN<13>")
	)
	(segment
		(start 344.235024 -129.761996)
		(end 343.793318 -129.464054)
		(width 0.1143)
		(layer "In11.Cu")
		(net "P3E_CPU0_PE3_OCP_RXN<13>")
	)
	(segment
		(start 424.76928 -140.302234)
		(end 422.195752 -140.785342)
		(width 0.1143)
		(layer "In11.Cu")
		(net "P3E_CPU0_PE3_OCP_RXN<13>")
	)
	(segment
		(start 307.72735 -106.146092)
		(end 307.72735 -105.912666)
		(width 0.1143)
		(layer "In11.Cu")
		(net "P3E_CPU0_PE3_OCP_RXN<13>")
	)
	(segment
		(start 303.24044 -104.6734)
		(end 302.619156 -104.415844)
		(width 0.1143)
		(layer "In11.Cu")
		(net "P3E_CPU0_PE3_OCP_RXN<13>")
	)
	(segment
		(start 300.10862 -101.376734)
		(end 300.08449 -101.376734)
		(width 0.0889)
		(layer "In11.Cu")
		(net "P3E_CPU0_PE3_OCP_RXN<13>")
	)
	(segment
		(start 302.0949 -103.537258)
		(end 302.0949 -103.51516)
		(width 0.0889)
		(layer "In11.Cu")
		(net "P3E_CPU0_PE3_OCP_RXN<13>")
	)
	(segment
		(start 390.278874 -141.227556)
		(end 385.945634 -141.227556)
		(width 0.1143)
		(layer "In11.Cu")
		(net "P3E_CPU0_PE3_OCP_RXN<13>")
	)
	(segment
		(start 298.038266 -99.206304)
		(end 298.031916 -99.195636)
		(width 0.0889)
		(layer "In11.Cu")
		(net "P3E_CPU0_PE3_OCP_RXN<13>")
	)
	(segment
		(start 301.242222 -102.211632)
		(end 301.116492 -102.085902)
		(width 0.0889)
		(layer "In11.Cu")
		(net "P3E_CPU0_PE3_OCP_RXN<13>")
	)
	(segment
		(start 366.845596 -133.334252)
		(end 364.709202 -131.197604)
		(width 0.1143)
		(layer "In11.Cu")
		(net "P3E_CPU0_PE3_OCP_RXN<13>")
	)
	(segment
		(start 298.36364 -91.661488)
		(end 298.396406 -91.661488)
		(width 0.0889)
		(layer "In11.Cu")
		(net "P3E_CPU0_PE3_OCP_RXN<13>")
	)
	(segment
		(start 308.948836 -107.133898)
		(end 308.715156 -107.133898)
		(width 0.1143)
		(layer "In11.Cu")
		(net "P3E_CPU0_PE3_OCP_RXN<13>")
	)
	(segment
		(start 324.866 -119.296942)
		(end 323.386958 -117.8179)
		(width 0.1143)
		(layer "In11.Cu")
		(net "P3E_CPU0_PE3_OCP_RXN<13>")
	)
	(segment
		(start 458.0763 -121.101866)
		(end 457.264008 -121.913904)
		(width 0.1143)
		(layer "In11.Cu")
		(net "P3E_CPU0_PE3_OCP_RXN<13>")
	)
	(segment
		(start 322.320158 -117.8179)
		(end 318.599058 -114.0968)
		(width 0.1143)
		(layer "In11.Cu")
		(net "P3E_CPU0_PE3_OCP_RXN<13>")
	)
	(segment
		(start 299.258736 -100.881434)
		(end 299.219112 -100.881434)
		(width 0.0889)
		(layer "In11.Cu")
		(net "P3E_CPU0_PE3_OCP_RXN<13>")
	)
	(segment
		(start 457.962 -120.38457)
		(end 458.0763 -120.49887)
		(width 0.1143)
		(layer "In11.Cu")
		(net "P3E_CPU0_PE3_OCP_RXN<13>")
	)
	(segment
		(start 349.176086 -128.913636)
		(end 348.448376 -129.055114)
		(width 0.1143)
		(layer "In11.Cu")
		(net "P3E_CPU0_PE3_OCP_RXN<13>")
	)
	(segment
		(start 457.264008 -121.913904)
		(end 455.93127 -122.4661)
		(width 0.1143)
		(layer "In11.Cu")
		(net "P3E_CPU0_PE3_OCP_RXN<13>")
	)
	(segment
		(start 434.679344 -139.597892)
		(end 434.349398 -139.690856)
		(width 0.1143)
		(layer "In11.Cu")
		(net "P3E_CPU0_PE3_OCP_RXN<13>")
	)
	(segment
		(start 307.47589 -105.661206)
		(end 307.242464 -105.661206)
		(width 0.1143)
		(layer "In11.Cu")
		(net "P3E_CPU0_PE3_OCP_RXN<13>")
	)
	(segment
		(start 307.242464 -105.661206)
		(end 306.991004 -105.409746)
		(width 0.1143)
		(layer "In11.Cu")
		(net "P3E_CPU0_PE3_OCP_RXN<13>")
	)
	(segment
		(start 306.991004 -105.17632)
		(end 306.739544 -104.92486)
		(width 0.1143)
		(layer "In11.Cu")
		(net "P3E_CPU0_PE3_OCP_RXN<13>")
	)
	(segment
		(start 346.112846 -130.12674)
		(end 344.235024 -129.761996)
		(width 0.1143)
		(layer "In11.Cu")
		(net "P3E_CPU0_PE3_OCP_RXN<13>")
	)
	(segment
		(start 302.0949 -103.51516)
		(end 302.0441 -103.46436)
		(width 0.0889)
		(layer "In11.Cu")
		(net "P3E_CPU0_PE3_OCP_RXN<13>")
	)
	(segment
		(start 433.256944 -140.169646)
		(end 431.69586 -140.608812)
		(width 0.1143)
		(layer "In11.Cu")
		(net "P3E_CPU0_PE3_OCP_RXN<13>")
	)
	(segment
		(start 357.745538 -130.686302)
		(end 357.296974 -130.773678)
		(width 0.1143)
		(layer "In11.Cu")
		(net "P3E_CPU0_PE3_OCP_RXN<13>")
	)
	(segment
		(start 442.821568 -130.426968)
		(end 438.976008 -134.199122)
		(width 0.1143)
		(layer "In11.Cu")
		(net "P3E_CPU0_PE3_OCP_RXN<13>")
	)
	(segment
		(start 433.371244 -139.965938)
		(end 433.256944 -140.169646)
		(width 0.1143)
		(layer "In11.Cu")
		(net "P3E_CPU0_PE3_OCP_RXN<13>")
	)
	(segment
		(start 433.904898 -139.987274)
		(end 433.701444 -139.872974)
		(width 0.1143)
		(layer "In11.Cu")
		(net "P3E_CPU0_PE3_OCP_RXN<13>")
	)
	(segment
		(start 331.498702 -126.689358)
		(end 331.498702 -126.68631)
		(width 0.1143)
		(layer "In11.Cu")
		(net "P3E_CPU0_PE3_OCP_RXN<13>")
	)
	(segment
		(start 298.038266 -98.215704)
		(end 298.031916 -98.205036)
		(width 0.0889)
		(layer "In11.Cu")
		(net "P3E_CPU0_PE3_OCP_RXN<13>")
	)
	(segment
		(start 306.739544 -104.92486)
		(end 306.506118 -104.92486)
		(width 0.1143)
		(layer "In11.Cu")
		(net "P3E_CPU0_PE3_OCP_RXN<13>")
	)
	(segment
		(start 422.195752 -140.785342)
		(end 420.190676 -140.29563)
		(width 0.1143)
		(layer "In11.Cu")
		(net "P3E_CPU0_PE3_OCP_RXN<13>")
	)
	(segment
		(start 307.97881 -106.397552)
		(end 307.72735 -106.146092)
		(width 0.1143)
		(layer "In11.Cu")
		(net "P3E_CPU0_PE3_OCP_RXN<13>")
	)
	(segment
		(start 434.349398 -139.690856)
		(end 434.235098 -139.894564)
		(width 0.1143)
		(layer "In11.Cu")
		(net "P3E_CPU0_PE3_OCP_RXN<13>")
	)
	(segment
		(start 302.0949 -103.891588)
		(end 302.0949 -103.537258)
		(width 0.1143)
		(layer "In11.Cu")
		(net "P3E_CPU0_PE3_OCP_RXN<13>")
	)
	(segment
		(start 298.94403 -91.397074)
		(end 299.237146 -91.565984)
		(width 0.0889)
		(layer "In11.Cu")
		(net "P3E_CPU0_PE3_OCP_RXN<13>")
	)
	(segment
		(start 347.968824 -129.76606)
		(end 346.112846 -130.12674)
		(width 0.1143)
		(layer "In11.Cu")
		(net "P3E_CPU0_PE3_OCP_RXN<13>")
	)
	(segment
		(start 379.118114 -140.970762)
		(end 372.027958 -139.528296)
		(width 0.1143)
		(layer "In11.Cu")
		(net "P3E_CPU0_PE3_OCP_RXN<13>")
	)
	(segment
		(start 399.812256 -141.266418)
		(end 394.19022 -142.294356)
		(width 0.1143)
		(layer "In11.Cu")
		(net "P3E_CPU0_PE3_OCP_RXN<13>")
	)
	(segment
		(start 315.678058 -114.0968)
		(end 309.200296 -107.619038)
		(width 0.1143)
		(layer "In11.Cu")
		(net "P3E_CPU0_PE3_OCP_RXN<13>")
	)
	(segment
		(start 333.153258 -127.992886)
		(end 333.153258 -127.99314)
		(width 0.1143)
		(layer "In11.Cu")
		(net "P3E_CPU0_PE3_OCP_RXN<13>")
	)
	(segment
		(start 352.385122 -129.53746)
		(end 349.176086 -128.913636)
		(width 0.1143)
		(layer "In11.Cu")
		(net "P3E_CPU0_PE3_OCP_RXN<13>")
	)
	(segment
		(start 339.55736 -127.459994)
		(end 339.556852 -127.459994)
		(width 0.1143)
		(layer "In11.Cu")
		(net "P3E_CPU0_PE3_OCP_RXN<13>")
	)
	(segment
		(start 318.599058 -114.0968)
		(end 315.678058 -114.0968)
		(width 0.1143)
		(layer "In11.Cu")
		(net "P3E_CPU0_PE3_OCP_RXN<13>")
	)
	(segment
		(start 333.153258 -127.99314)
		(end 331.498702 -126.689358)
		(width 0.1143)
		(layer "In11.Cu")
		(net "P3E_CPU0_PE3_OCP_RXN<13>")
	)
	(segment
		(start 296.643806 -94.633288)
		(end 296.68343 -94.633288)
		(width 0.0889)
		(layer "In11.Cu")
		(net "P3E_CPU0_PE3_OCP_RXN<13>")
	)
	(segment
		(start 426.997368 -140.397992)
		(end 426.173646 -140.590778)
		(width 0.1143)
		(layer "In11.Cu")
		(net "P3E_CPU0_PE3_OCP_RXN<13>")
	)
	(segment
		(start 296.686732 -96.423988)
		(end 296.650664 -96.423988)
		(width 0.0889)
		(layer "In11.Cu")
		(net "P3E_CPU0_PE3_OCP_RXN<13>")
	)
	(segment
		(start 353.921314 -129.238756)
		(end 352.385122 -129.53746)
		(width 0.1143)
		(layer "In11.Cu")
		(net "P3E_CPU0_PE3_OCP_RXN<13>")
	)
	(segment
		(start 306.991004 -105.409746)
		(end 306.991004 -105.17632)
		(width 0.1143)
		(layer "In11.Cu")
		(net "P3E_CPU0_PE3_OCP_RXN<13>")
	)
	(segment
		(start 308.463696 -106.649012)
		(end 308.212236 -106.397552)
		(width 0.1143)
		(layer "In11.Cu")
		(net "P3E_CPU0_PE3_OCP_RXN<13>")
	)
	(segment
		(start 309.200296 -107.385358)
		(end 308.948836 -107.133898)
		(width 0.1143)
		(layer "In11.Cu")
		(net "P3E_CPU0_PE3_OCP_RXN<13>")
	)
	(segment
		(start 426.173646 -140.590778)
		(end 424.76928 -140.302234)
		(width 0.1143)
		(layer "In11.Cu")
		(net "P3E_CPU0_PE3_OCP_RXN<13>")
	)
	(segment
		(start 308.463696 -106.882438)
		(end 308.463696 -106.649012)
		(width 0.1143)
		(layer "In11.Cu")
		(net "P3E_CPU0_PE3_OCP_RXN<13>")
	)
	(segment
		(start 418.183822 -140.826998)
		(end 416.591496 -140.443712)
		(width 0.1143)
		(layer "In11.Cu")
		(net "P3E_CPU0_PE3_OCP_RXN<13>")
	)
	(segment
		(start 335.519014 -128.18999)
		(end 333.153512 -127.99314)
		(width 0.1143)
		(layer "In11.Cu")
		(net "P3E_CPU0_PE3_OCP_RXN<13>")
	)
	(segment
		(start 436.191152 -139.344146)
		(end 435.860952 -139.43711)
		(width 0.1143)
		(layer "In11.Cu")
		(net "P3E_CPU0_PE3_OCP_RXN<13>")
	)
	(segment
		(start 438.976008 -134.199122)
		(end 438.231788 -136.867646)
		(width 0.1143)
		(layer "In11.Cu")
		(net "P3E_CPU0_PE3_OCP_RXN<13>")
	)
	(segment
		(start 339.556852 -127.459994)
		(end 335.519268 -128.190244)
		(width 0.1143)
		(layer "In11.Cu")
		(net "P3E_CPU0_PE3_OCP_RXN<13>")
	)
	(segment
		(start 452.659242 -122.4661)
		(end 451.284848 -123.84024)
		(width 0.1143)
		(layer "In11.Cu")
		(net "P3E_CPU0_PE3_OCP_RXN<13>")
	)
	(segment
		(start 457.58735 -120.38457)
		(end 457.962 -120.38457)
		(width 0.1143)
		(layer "In11.Cu")
		(net "P3E_CPU0_PE3_OCP_RXN<13>")
	)
	(segment
		(start 435.657498 -139.32281)
		(end 435.327298 -139.415774)
		(width 0.1143)
		(layer "In11.Cu")
		(net "P3E_CPU0_PE3_OCP_RXN<13>")
	)
	(segment
		(start 411.874716 -140.019532)
		(end 405.533098 -141.266418)
		(width 0.1143)
		(layer "In11.Cu")
		(net "P3E_CPU0_PE3_OCP_RXN<13>")
	)
	(segment
		(start 415.138362 -140.772896)
		(end 411.874716 -140.019532)
		(width 0.1143)
		(layer "In11.Cu")
		(net "P3E_CPU0_PE3_OCP_RXN<13>")
	)
	(segment
		(start 298.396406 -100.386134)
		(end 298.360592 -100.386134)
		(width 0.0889)
		(layer "In11.Cu")
		(net "P3E_CPU0_PE3_OCP_RXN<13>")
	)
	(segment
		(start 385.945634 -141.227556)
		(end 381.89916 -140.404596)
		(width 0.1143)
		(layer "In11.Cu")
		(net "P3E_CPU0_PE3_OCP_RXN<13>")
	)
	(segment
		(start 343.793318 -129.464054)
		(end 343.101422 -128.438402)
		(width 0.1143)
		(layer "In11.Cu")
		(net "P3E_CPU0_PE3_OCP_RXN<13>")
	)
	(segment
		(start 331.498702 -126.68631)
		(end 330.93152 -126.119128)
		(width 0.1143)
		(layer "In11.Cu")
		(net "P3E_CPU0_PE3_OCP_RXN<13>")
	)
	(segment
		(start 394.19022 -142.294356)
		(end 390.278874 -141.227556)
		(width 0.1143)
		(layer "In11.Cu")
		(net "P3E_CPU0_PE3_OCP_RXN<13>")
	)
	(segment
		(start 433.701444 -139.872974)
		(end 433.371244 -139.965938)
		(width 0.1143)
		(layer "In11.Cu")
		(net "P3E_CPU0_PE3_OCP_RXN<13>")
	)
	(segment
		(start 324.866 -122.116088)
		(end 324.866 -119.296942)
		(width 0.1143)
		(layer "In11.Cu")
		(net "P3E_CPU0_PE3_OCP_RXN<13>")
	)
	(segment
		(start 405.533098 -141.266418)
		(end 399.812256 -141.266418)
		(width 0.1143)
		(layer "In11.Cu")
		(net "P3E_CPU0_PE3_OCP_RXN<13>")
	)
	(segment
		(start 381.89916 -140.404596)
		(end 379.118114 -140.970762)
		(width 0.1143)
		(layer "In11.Cu")
		(net "P3E_CPU0_PE3_OCP_RXN<13>")
	)
	(segment
		(start 308.715156 -107.133898)
		(end 308.463696 -106.882438)
		(width 0.1143)
		(layer "In11.Cu")
		(net "P3E_CPU0_PE3_OCP_RXN<13>")
	)
	(segment
		(start 438.231788 -136.867646)
		(end 436.191152 -139.344146)
		(width 0.1143)
		(layer "In11.Cu")
		(net "P3E_CPU0_PE3_OCP_RXN<13>")
	)
	(segment
		(start 298.854622 -91.421204)
		(end 298.94403 -91.397074)
		(width 0.0889)
		(layer "In11.Cu")
		(net "P3E_CPU0_PE3_OCP_RXN<13>")
	)
	(segment
		(start 359.447338 -129.98196)
		(end 357.745538 -130.686302)
		(width 0.1143)
		(layer "In11.Cu")
		(net "P3E_CPU0_PE3_OCP_RXN<13>")
	)
	(segment
		(start 323.386958 -117.8179)
		(end 322.320158 -117.8179)
		(width 0.1143)
		(layer "In11.Cu")
		(net "P3E_CPU0_PE3_OCP_RXN<13>")
	)
	(segment
		(start 302.0441 -103.46436)
		(end 302.0441 -103.156512)
		(width 0.0889)
		(layer "In11.Cu")
		(net "P3E_CPU0_PE3_OCP_RXN<13>")
	)
	(segment
		(start 343.101422 -128.438402)
		(end 342.499696 -128.032002)
		(width 0.1143)
		(layer "In11.Cu")
		(net "P3E_CPU0_PE3_OCP_RXN<13>")
	)
	(segment
		(start 416.591496 -140.443712)
		(end 415.138362 -140.772896)
		(width 0.1143)
		(layer "In11.Cu")
		(net "P3E_CPU0_PE3_OCP_RXN<13>")
	)
	(segment
		(start 297.520106 -92.156534)
		(end 297.541696 -92.156534)
		(width 0.0889)
		(layer "In11.Cu")
		(net "P3E_CPU0_PE3_OCP_RXN<13>")
	)
	(segment
		(start 435.212998 -139.619228)
		(end 434.883052 -139.712192)
		(width 0.1143)
		(layer "In11.Cu")
		(net "P3E_CPU0_PE3_OCP_RXN<13>")
	)
	(segment
		(start 372.027958 -139.528296)
		(end 368.195606 -136.593326)
		(width 0.1143)
		(layer "In11.Cu")
		(net "P3E_CPU0_PE3_OCP_RXN<13>")
	)
	(segment
		(start 455.93127 -122.4661)
		(end 452.659242 -122.4661)
		(width 0.1143)
		(layer "In11.Cu")
		(net "P3E_CPU0_PE3_OCP_RXN<13>")
	)
	(segment
		(start 364.709202 -131.197604)
		(end 361.773216 -129.98196)
		(width 0.1143)
		(layer "In11.Cu")
		(net "P3E_CPU0_PE3_OCP_RXN<13>")
	)
	(segment
		(start 361.773216 -129.98196)
		(end 359.447338 -129.98196)
		(width 0.1143)
		(layer "In11.Cu")
		(net "P3E_CPU0_PE3_OCP_RXN<13>")
	)
	(segment
		(start 333.153512 -127.99314)
		(end 333.153258 -127.992886)
		(width 0.1143)
		(layer "In11.Cu")
		(net "P3E_CPU0_PE3_OCP_RXN<13>")
	)
	(arc
		(start 296.31513 -95.823786)
		(mid 296.394261 -95.528384)
		(end 296.31513 -95.232982)
		(width 0.0889)
		(layer "In11.Cu")
		(net "P3E_CPU0_PE3_OCP_RXN<13>")
	)
	(arc
		(start 297.520106 -96.919034)
		(mid 297.322945 -96.867075)
		(end 297.176952 -96.724724)
		(width 0.0889)
		(layer "In11.Cu")
		(net "P3E_CPU0_PE3_OCP_RXN<13>")
	)
	(arc
		(start 296.68343 -94.633288)
		(mid 297.17896 -94.328749)
		(end 297.17365 -93.747082)
		(width 0.0889)
		(layer "In11.Cu")
		(net "P3E_CPU0_PE3_OCP_RXN<13>")
	)
	(arc
		(start 296.650664 -96.423988)
		(mid 296.312495 -96.21919)
		(end 296.31513 -95.823786)
		(width 0.0889)
		(layer "In11.Cu")
		(net "P3E_CPU0_PE3_OCP_RXN<13>")
	)
	(arc
		(start 297.541696 -92.156534)
		(mid 297.824913 -92.072253)
		(end 298.031916 -91.861386)
		(width 0.0889)
		(layer "In11.Cu")
		(net "P3E_CPU0_PE3_OCP_RXN<13>")
	)
	(arc
		(start 298.031916 -97.804986)
		(mid 298.036245 -97.221814)
		(end 297.537886 -96.919034)
		(width 0.0889)
		(layer "In11.Cu")
		(net "P3E_CPU0_PE3_OCP_RXN<13>")
	)
	(arc
		(start 296.31513 -95.232982)
		(mid 296.310885 -94.840737)
		(end 296.643806 -94.633288)
		(width 0.0889)
		(layer "In11.Cu")
		(net "P3E_CPU0_PE3_OCP_RXN<13>")
	)
	(arc
		(start 297.18254 -93.332046)
		(mid 297.252937 -93.043095)
		(end 297.17365 -92.756482)
		(width 0.0889)
		(layer "In11.Cu")
		(net "P3E_CPU0_PE3_OCP_RXN<13>")
	)
	(arc
		(start 297.17365 -93.747082)
		(mid 297.120117 -93.547184)
		(end 297.17365 -93.347286)
		(width 0.0889)
		(layer "In11.Cu")
		(net "P3E_CPU0_PE3_OCP_RXN<13>")
	)
	(arc
		(start 298.031916 -99.786186)
		(mid 298.111138 -99.497068)
		(end 298.038266 -99.206304)
		(width 0.0889)
		(layer "In11.Cu")
		(net "P3E_CPU0_PE3_OCP_RXN<13>")
	)
	(arc
		(start 298.396406 -91.661488)
		(mid 298.653228 -91.594187)
		(end 298.854622 -91.421204)
		(width 0.0889)
		(layer "In11.Cu")
		(net "P3E_CPU0_PE3_OCP_RXN<13>")
	)
	(arc
		(start 299.748956 -101.176582)
		(mid 299.541952 -100.965718)
		(end 299.258736 -100.881434)
		(width 0.0889)
		(layer "In11.Cu")
		(net "P3E_CPU0_PE3_OCP_RXN<13>")
	)
	(arc
		(start 298.031916 -91.861386)
		(mid 298.171995 -91.71865)
		(end 298.36364 -91.661488)
		(width 0.0889)
		(layer "In11.Cu")
		(net "P3E_CPU0_PE3_OCP_RXN<13>")
	)
	(arc
		(start 298.02709 -99.187)
		(mid 297.978335 -98.990648)
		(end 298.031916 -98.795586)
		(width 0.0889)
		(layer "In11.Cu")
		(net "P3E_CPU0_PE3_OCP_RXN<13>")
	)
	(arc
		(start 300.607476 -101.672136)
		(mid 300.396763 -101.459057)
		(end 300.10862 -101.376734)
		(width 0.0889)
		(layer "In11.Cu")
		(net "P3E_CPU0_PE3_OCP_RXN<13>")
	)
	(arc
		(start 297.17365 -92.756482)
		(mid 297.173733 -92.356541)
		(end 297.520106 -92.156534)
		(width 0.0889)
		(layer "In11.Cu")
		(net "P3E_CPU0_PE3_OCP_RXN<13>")
	)
	(arc
		(start 298.360592 -100.386134)
		(mid 298.027623 -100.178586)
		(end 298.031916 -99.786186)
		(width 0.0889)
		(layer "In11.Cu")
		(net "P3E_CPU0_PE3_OCP_RXN<13>")
	)
	(arc
		(start 299.219112 -100.881434)
		(mid 299.029183 -100.823564)
		(end 298.890436 -100.681536)
		(width 0.0889)
		(layer "In11.Cu")
		(net "P3E_CPU0_PE3_OCP_RXN<13>")
	)
	(arc
		(start 298.890436 -100.681536)
		(mid 298.681828 -100.469604)
		(end 298.396406 -100.386134)
		(width 0.0889)
		(layer "In11.Cu")
		(net "P3E_CPU0_PE3_OCP_RXN<13>")
	)
	(arc
		(start 298.02709 -98.1964)
		(mid 297.978335 -98.000048)
		(end 298.031916 -97.804986)
		(width 0.0889)
		(layer "In11.Cu")
		(net "P3E_CPU0_PE3_OCP_RXN<13>")
	)
	(arc
		(start 297.17365 -96.718882)
		(mid 296.968029 -96.508959)
		(end 296.686732 -96.423988)
		(width 0.0889)
		(layer "In11.Cu")
		(net "P3E_CPU0_PE3_OCP_RXN<13>")
	)
	(arc
		(start 298.031916 -98.795586)
		(mid 298.111138 -98.506468)
		(end 298.038266 -98.215704)
		(width 0.0889)
		(layer "In11.Cu")
		(net "P3E_CPU0_PE3_OCP_RXN<13>")
	)
	(arc
		(start 300.08449 -101.376734)
		(mid 299.89064 -101.320384)
		(end 299.748956 -101.176582)
		(width 0.0889)
		(layer "In11.Cu")
		(net "P3E_CPU0_PE3_OCP_RXN<13>")
	)
	(segment
		(start 455.167238 -121.572782)
		(end 454.99782 -121.7422)
		(width 0.1143)
		(layer "F.Cu")
		(net "P3E_CPU0_PE3_OCP_RXN<12>")
	)
	(segment
		(start 454.201022 -116.993162)
		(end 454.201022 -118.342918)
		(width 0.1143)
		(layer "F.Cu")
		(net "P3E_CPU0_PE3_OCP_RXN<12>")
	)
	(segment
		(start 454.201022 -118.342918)
		(end 454.200006 -118.343934)
		(width 0.1143)
		(layer "F.Cu")
		(net "P3E_CPU0_PE3_OCP_RXN<12>")
	)
	(segment
		(start 455.167238 -120.991884)
		(end 455.167238 -121.572782)
		(width 0.1143)
		(layer "F.Cu")
		(net "P3E_CPU0_PE3_OCP_RXN<12>")
	)
	(segment
		(start 454.99782 -121.7422)
		(end 454.65365 -121.7422)
		(width 0.1143)
		(layer "F.Cu")
		(net "P3E_CPU0_PE3_OCP_RXN<12>")
	)
	(segment
		(start 296.948606 -92.556584)
		(end 297.520106 -92.556584)
		(width 0.1143)
		(layer "F.Cu")
		(net "P3E_CPU0_PE3_OCP_RXN<12>")
	)
	(segment
		(start 454.200006 -118.343934)
		(end 454.479406 -118.623334)
		(width 0.1143)
		(layer "F.Cu")
		(net "P3E_CPU0_PE3_OCP_RXN<12>")
	)
	(segment
		(start 454.479406 -118.623334)
		(end 454.479406 -119.331232)
		(width 0.1143)
		(layer "F.Cu")
		(net "P3E_CPU0_PE3_OCP_RXN<12>")
	)
	(segment
		(start 454.479406 -119.331232)
		(end 455.167238 -120.991884)
		(width 0.1143)
		(layer "F.Cu")
		(net "P3E_CPU0_PE3_OCP_RXN<12>")
	)
	(via
		(at 454.65365 -121.7422)
		(size 0.508)
		(drill 0.254)
		(layers "F.Cu" "B.Cu")
		(net "P3E_CPU0_PE3_OCP_RXN<12>")
	)
	(via
		(at 297.520106 -92.556584)
		(size 0.508)
		(drill 0.254)
		(layers "F.Cu" "B.Cu")
		(net "P3E_CPU0_PE3_OCP_RXN<12>")
	)
	(segment
		(start 297.860466 -93.336618)
		(end 297.866816 -93.347286)
		(width 0.0889)
		(layer "In11.Cu")
		(net "P3E_CPU0_PE3_OCP_RXN<12>")
	)
	(segment
		(start 358.623362 -129.3368)
		(end 361.108752 -129.3368)
		(width 0.1143)
		(layer "In11.Cu")
		(net "P3E_CPU0_PE3_OCP_RXN<12>")
	)
	(segment
		(start 368.507772 -136.399016)
		(end 372.1608 -139.196318)
		(width 0.1143)
		(layer "In11.Cu")
		(net "P3E_CPU0_PE3_OCP_RXN<12>")
	)
	(segment
		(start 304.673 -104.1146)
		(end 304.955702 -104.1146)
		(width 0.0889)
		(layer "In11.Cu")
		(net "P3E_CPU0_PE3_OCP_RXN<12>")
	)
	(segment
		(start 325.8439 -119.5705)
		(end 325.8439 -122.178318)
		(width 0.1143)
		(layer "In11.Cu")
		(net "P3E_CPU0_PE3_OCP_RXN<12>")
	)
	(segment
		(start 298.730162 -97.2058)
		(end 298.725336 -97.214436)
		(width 0.0889)
		(layer "In11.Cu")
		(net "P3E_CPU0_PE3_OCP_RXN<12>")
	)
	(segment
		(start 450.847714 -123.649486)
		(end 452.618856 -121.878344)
		(width 0.1143)
		(layer "In11.Cu")
		(net "P3E_CPU0_PE3_OCP_RXN<12>")
	)
	(segment
		(start 453.669908 -120.827292)
		(end 453.9234 -120.5738)
		(width 0.1143)
		(layer "In11.Cu")
		(net "P3E_CPU0_PE3_OCP_RXN<12>")
	)
	(segment
		(start 306.510436 -104.1654)
		(end 309.489856 -105.400602)
		(width 0.1143)
		(layer "In11.Cu")
		(net "P3E_CPU0_PE3_OCP_RXN<12>")
	)
	(segment
		(start 379.037342 -140.594842)
		(end 381.807974 -140.030708)
		(width 0.1143)
		(layer "In11.Cu")
		(net "P3E_CPU0_PE3_OCP_RXN<12>")
	)
	(segment
		(start 298.360846 -96.614488)
		(end 298.393612 -96.614488)
		(width 0.0889)
		(layer "In11.Cu")
		(net "P3E_CPU0_PE3_OCP_RXN<12>")
	)
	(segment
		(start 326.409304 -122.743722)
		(end 326.409304 -122.977148)
		(width 0.1143)
		(layer "In11.Cu")
		(net "P3E_CPU0_PE3_OCP_RXN<12>")
	)
	(segment
		(start 354.097336 -128.623314)
		(end 354.097336 -128.62306)
		(width 0.1143)
		(layer "In11.Cu")
		(net "P3E_CPU0_PE3_OCP_RXN<12>")
	)
	(segment
		(start 305.006502 -104.1654)
		(end 305.0286 -104.1654)
		(width 0.0889)
		(layer "In11.Cu")
		(net "P3E_CPU0_PE3_OCP_RXN<12>")
	)
	(segment
		(start 453.9234 -120.5738)
		(end 454.754488 -120.5738)
		(width 0.1143)
		(layer "In11.Cu")
		(net "P3E_CPU0_PE3_OCP_RXN<12>")
	)
	(segment
		(start 297.866816 -93.347286)
		(end 297.871642 -93.355922)
		(width 0.0889)
		(layer "In11.Cu")
		(net "P3E_CPU0_PE3_OCP_RXN<12>")
	)
	(segment
		(start 303.7332 -104.3432)
		(end 304.4444 -104.3432)
		(width 0.0889)
		(layer "In11.Cu")
		(net "P3E_CPU0_PE3_OCP_RXN<12>")
	)
	(segment
		(start 425.288964 -136.836658)
		(end 425.475654 -136.803384)
		(width 0.1143)
		(layer "In11.Cu")
		(net "P3E_CPU0_PE3_OCP_RXN<12>")
	)
	(segment
		(start 325.8439 -122.178318)
		(end 326.409304 -122.743722)
		(width 0.1143)
		(layer "In11.Cu")
		(net "P3E_CPU0_PE3_OCP_RXN<12>")
	)
	(segment
		(start 298.725336 -97.214436)
		(end 298.718986 -97.225104)
		(width 0.0889)
		(layer "In11.Cu")
		(net "P3E_CPU0_PE3_OCP_RXN<12>")
	)
	(segment
		(start 355.952806 -128.145032)
		(end 358.623362 -129.3368)
		(width 0.1143)
		(layer "In11.Cu")
		(net "P3E_CPU0_PE3_OCP_RXN<12>")
	)
	(segment
		(start 318.925194 -112.651794)
		(end 325.8439 -119.5705)
		(width 0.1143)
		(layer "In11.Cu")
		(net "P3E_CPU0_PE3_OCP_RXN<12>")
	)
	(segment
		(start 432.517296 -137.85977)
		(end 435.670706 -138.511026)
		(width 0.1143)
		(layer "In11.Cu")
		(net "P3E_CPU0_PE3_OCP_RXN<12>")
	)
	(segment
		(start 438.642252 -134.025894)
		(end 442.474604 -130.193542)
		(width 0.1143)
		(layer "In11.Cu")
		(net "P3E_CPU0_PE3_OCP_RXN<12>")
	)
	(segment
		(start 364.848902 -130.836162)
		(end 367.16208 -133.14934)
		(width 0.1143)
		(layer "In11.Cu")
		(net "P3E_CPU0_PE3_OCP_RXN<12>")
	)
	(segment
		(start 411.879542 -139.667488)
		(end 415.139886 -140.419836)
		(width 0.1143)
		(layer "In11.Cu")
		(net "P3E_CPU0_PE3_OCP_RXN<12>")
	)
	(segment
		(start 442.474604 -130.193542)
		(end 450.058028 -125.555248)
		(width 0.1143)
		(layer "In11.Cu")
		(net "P3E_CPU0_PE3_OCP_RXN<12>")
	)
	(segment
		(start 326.8853 -123.219718)
		(end 327.12787 -123.462288)
		(width 0.1143)
		(layer "In11.Cu")
		(net "P3E_CPU0_PE3_OCP_RXN<12>")
	)
	(segment
		(start 452.618856 -121.878344)
		(end 452.780908 -121.878344)
		(width 0.1143)
		(layer "In11.Cu")
		(net "P3E_CPU0_PE3_OCP_RXN<12>")
	)
	(segment
		(start 390.32561 -140.879576)
		(end 394.20546 -141.93774)
		(width 0.1143)
		(layer "In11.Cu")
		(net "P3E_CPU0_PE3_OCP_RXN<12>")
	)
	(segment
		(start 300.936406 -101.072188)
		(end 300.97222 -101.072188)
		(width 0.0889)
		(layer "In11.Cu")
		(net "P3E_CPU0_PE3_OCP_RXN<12>")
	)
	(segment
		(start 453.023224 -121.636028)
		(end 453.023224 -121.473976)
		(width 0.1143)
		(layer "In11.Cu")
		(net "P3E_CPU0_PE3_OCP_RXN<12>")
	)
	(segment
		(start 327.12787 -123.462288)
		(end 327.12787 -123.695714)
		(width 0.1143)
		(layer "In11.Cu")
		(net "P3E_CPU0_PE3_OCP_RXN<12>")
	)
	(segment
		(start 300.074076 -100.576888)
		(end 300.1137 -100.576888)
		(width 0.0889)
		(layer "In11.Cu")
		(net "P3E_CPU0_PE3_OCP_RXN<12>")
	)
	(segment
		(start 298.725336 -99.195636)
		(end 298.718986 -99.206304)
		(width 0.0889)
		(layer "In11.Cu")
		(net "P3E_CPU0_PE3_OCP_RXN<12>")
	)
	(segment
		(start 303.022 -103.632)
		(end 303.7332 -104.3432)
		(width 0.0889)
		(layer "In11.Cu")
		(net "P3E_CPU0_PE3_OCP_RXN<12>")
	)
	(segment
		(start 298.725336 -98.205036)
		(end 298.718986 -98.215704)
		(width 0.0889)
		(layer "In11.Cu")
		(net "P3E_CPU0_PE3_OCP_RXN<12>")
	)
	(segment
		(start 299.224192 -100.081588)
		(end 299.248322 -100.081588)
		(width 0.0889)
		(layer "In11.Cu")
		(net "P3E_CPU0_PE3_OCP_RXN<12>")
	)
	(segment
		(start 455.0283 -121.7422)
		(end 454.65365 -121.7422)
		(width 0.1143)
		(layer "In11.Cu")
		(net "P3E_CPU0_PE3_OCP_RXN<12>")
	)
	(segment
		(start 316.738254 -112.651794)
		(end 318.925194 -112.651794)
		(width 0.1143)
		(layer "In11.Cu")
		(net "P3E_CPU0_PE3_OCP_RXN<12>")
	)
	(segment
		(start 327.12787 -123.695714)
		(end 327.370186 -123.93803)
		(width 0.1143)
		(layer "In11.Cu")
		(net "P3E_CPU0_PE3_OCP_RXN<12>")
	)
	(segment
		(start 298.730162 -99.187)
		(end 298.725336 -99.195636)
		(width 0.0889)
		(layer "In11.Cu")
		(net "P3E_CPU0_PE3_OCP_RXN<12>")
	)
	(segment
		(start 297.53814 -94.937834)
		(end 297.498516 -94.937834)
		(width 0.0889)
		(layer "In11.Cu")
		(net "P3E_CPU0_PE3_OCP_RXN<12>")
	)
	(segment
		(start 309.489856 -105.400602)
		(end 316.738254 -112.651794)
		(width 0.1143)
		(layer "In11.Cu")
		(net "P3E_CPU0_PE3_OCP_RXN<12>")
	)
	(segment
		(start 454.754488 -120.5738)
		(end 455.1426 -120.961912)
		(width 0.1143)
		(layer "In11.Cu")
		(net "P3E_CPU0_PE3_OCP_RXN<12>")
	)
	(segment
		(start 430.442878 -138.247882)
		(end 432.517296 -137.85977)
		(width 0.1143)
		(layer "In11.Cu")
		(net "P3E_CPU0_PE3_OCP_RXN<12>")
	)
	(segment
		(start 354.097336 -128.62306)
		(end 355.952806 -128.145032)
		(width 0.1143)
		(layer "In11.Cu")
		(net "P3E_CPU0_PE3_OCP_RXN<12>")
	)
	(segment
		(start 343.02827 -126.31547)
		(end 343.83472 -127.510794)
		(width 0.1143)
		(layer "In11.Cu")
		(net "P3E_CPU0_PE3_OCP_RXN<12>")
	)
	(segment
		(start 334.12684 -125.94463)
		(end 341.121746 -125.94463)
		(width 0.1143)
		(layer "In11.Cu")
		(net "P3E_CPU0_PE3_OCP_RXN<12>")
	)
	(segment
		(start 367.16208 -133.14934)
		(end 368.507772 -136.399016)
		(width 0.1143)
		(layer "In11.Cu")
		(net "P3E_CPU0_PE3_OCP_RXN<12>")
	)
	(segment
		(start 435.670706 -138.511026)
		(end 437.164734 -137.592816)
		(width 0.1143)
		(layer "In11.Cu")
		(net "P3E_CPU0_PE3_OCP_RXN<12>")
	)
	(segment
		(start 301.313342 -101.293676)
		(end 303.022 -103.00208)
		(width 0.0889)
		(layer "In11.Cu")
		(net "P3E_CPU0_PE3_OCP_RXN<12>")
	)
	(segment
		(start 304.955702 -104.1146)
		(end 305.006502 -104.1654)
		(width 0.0889)
		(layer "In11.Cu")
		(net "P3E_CPU0_PE3_OCP_RXN<12>")
	)
	(segment
		(start 372.1608 -139.196318)
		(end 379.037342 -140.594842)
		(width 0.1143)
		(layer "In11.Cu")
		(net "P3E_CPU0_PE3_OCP_RXN<12>")
	)
	(segment
		(start 453.023224 -121.473976)
		(end 453.26554 -121.23166)
		(width 0.1143)
		(layer "In11.Cu")
		(net "P3E_CPU0_PE3_OCP_RXN<12>")
	)
	(segment
		(start 399.806414 -140.913612)
		(end 405.54148 -140.913612)
		(width 0.1143)
		(layer "In11.Cu")
		(net "P3E_CPU0_PE3_OCP_RXN<12>")
	)
	(segment
		(start 347.190822 -128.775714)
		(end 348.40291 -128.36906)
		(width 0.1143)
		(layer "In11.Cu")
		(net "P3E_CPU0_PE3_OCP_RXN<12>")
	)
	(segment
		(start 361.108752 -129.3368)
		(end 364.848902 -130.836162)
		(width 0.1143)
		(layer "In11.Cu")
		(net "P3E_CPU0_PE3_OCP_RXN<12>")
	)
	(segment
		(start 326.651874 -123.219718)
		(end 326.8853 -123.219718)
		(width 0.1143)
		(layer "In11.Cu")
		(net "P3E_CPU0_PE3_OCP_RXN<12>")
	)
	(segment
		(start 301.300896 -101.272086)
		(end 301.313342 -101.293676)
		(width 0.0889)
		(layer "In11.Cu")
		(net "P3E_CPU0_PE3_OCP_RXN<12>")
	)
	(segment
		(start 425.475654 -136.803384)
		(end 430.442878 -138.247882)
		(width 0.1143)
		(layer "In11.Cu")
		(net "P3E_CPU0_PE3_OCP_RXN<12>")
	)
	(segment
		(start 415.139886 -140.419836)
		(end 416.593782 -140.08989)
		(width 0.1143)
		(layer "In11.Cu")
		(net "P3E_CPU0_PE3_OCP_RXN<12>")
	)
	(segment
		(start 343.83472 -127.510794)
		(end 345.111324 -128.371854)
		(width 0.1143)
		(layer "In11.Cu")
		(net "P3E_CPU0_PE3_OCP_RXN<12>")
	)
	(segment
		(start 453.26554 -121.23166)
		(end 453.427592 -121.23166)
		(width 0.1143)
		(layer "In11.Cu")
		(net "P3E_CPU0_PE3_OCP_RXN<12>")
	)
	(segment
		(start 352.242882 -129.100834)
		(end 354.097336 -128.623314)
		(width 0.1143)
		(layer "In11.Cu")
		(net "P3E_CPU0_PE3_OCP_RXN<12>")
	)
	(segment
		(start 453.427592 -121.23166)
		(end 453.669908 -120.989344)
		(width 0.1143)
		(layer "In11.Cu")
		(net "P3E_CPU0_PE3_OCP_RXN<12>")
	)
	(segment
		(start 297.813222 -92.387674)
		(end 297.891962 -92.40901)
		(width 0.0889)
		(layer "In11.Cu")
		(net "P3E_CPU0_PE3_OCP_RXN<12>")
	)
	(segment
		(start 329.56754 -124.519436)
		(end 334.12684 -125.94463)
		(width 0.1143)
		(layer "In11.Cu")
		(net "P3E_CPU0_PE3_OCP_RXN<12>")
	)
	(segment
		(start 298.730162 -98.1964)
		(end 298.725336 -98.205036)
		(width 0.0889)
		(layer "In11.Cu")
		(net "P3E_CPU0_PE3_OCP_RXN<12>")
	)
	(segment
		(start 455.1426 -121.6279)
		(end 455.0283 -121.7422)
		(width 0.1143)
		(layer "In11.Cu")
		(net "P3E_CPU0_PE3_OCP_RXN<12>")
	)
	(segment
		(start 345.111324 -128.371854)
		(end 347.190822 -128.775714)
		(width 0.1143)
		(layer "In11.Cu")
		(net "P3E_CPU0_PE3_OCP_RXN<12>")
	)
	(segment
		(start 304.4444 -104.3432)
		(end 304.673 -104.1146)
		(width 0.0889)
		(layer "In11.Cu")
		(net "P3E_CPU0_PE3_OCP_RXN<12>")
	)
	(segment
		(start 381.807974 -140.030708)
		(end 385.982972 -140.879576)
		(width 0.1143)
		(layer "In11.Cu")
		(net "P3E_CPU0_PE3_OCP_RXN<12>")
	)
	(segment
		(start 416.593782 -140.08989)
		(end 417.388802 -140.281406)
		(width 0.1143)
		(layer "In11.Cu")
		(net "P3E_CPU0_PE3_OCP_RXN<12>")
	)
	(segment
		(start 297.495214 -96.118934)
		(end 297.531282 -96.118934)
		(width 0.0889)
		(layer "In11.Cu")
		(net "P3E_CPU0_PE3_OCP_RXN<12>")
	)
	(segment
		(start 452.780908 -121.878344)
		(end 453.023224 -121.636028)
		(width 0.1143)
		(layer "In11.Cu")
		(net "P3E_CPU0_PE3_OCP_RXN<12>")
	)
	(segment
		(start 453.669908 -120.989344)
		(end 453.669908 -120.827292)
		(width 0.1143)
		(layer "In11.Cu")
		(net "P3E_CPU0_PE3_OCP_RXN<12>")
	)
	(segment
		(start 341.121746 -125.94463)
		(end 343.02827 -126.31547)
		(width 0.1143)
		(layer "In11.Cu")
		(net "P3E_CPU0_PE3_OCP_RXN<12>")
	)
	(segment
		(start 327.603612 -123.93803)
		(end 327.846182 -124.1806)
		(width 0.1143)
		(layer "In11.Cu")
		(net "P3E_CPU0_PE3_OCP_RXN<12>")
	)
	(segment
		(start 303.022 -103.00208)
		(end 303.022 -103.632)
		(width 0.0889)
		(layer "In11.Cu")
		(net "P3E_CPU0_PE3_OCP_RXN<12>")
	)
	(segment
		(start 348.40291 -128.36906)
		(end 352.242882 -129.100834)
		(width 0.1143)
		(layer "In11.Cu")
		(net "P3E_CPU0_PE3_OCP_RXN<12>")
	)
	(segment
		(start 455.1426 -120.961912)
		(end 455.1426 -121.6279)
		(width 0.1143)
		(layer "In11.Cu")
		(net "P3E_CPU0_PE3_OCP_RXN<12>")
	)
	(segment
		(start 327.846182 -124.1806)
		(end 329.56754 -124.519436)
		(width 0.1143)
		(layer "In11.Cu")
		(net "P3E_CPU0_PE3_OCP_RXN<12>")
	)
	(segment
		(start 405.54148 -140.913612)
		(end 411.879542 -139.667488)
		(width 0.1143)
		(layer "In11.Cu")
		(net "P3E_CPU0_PE3_OCP_RXN<12>")
	)
	(segment
		(start 437.164734 -137.592816)
		(end 438.642252 -134.025894)
		(width 0.1143)
		(layer "In11.Cu")
		(net "P3E_CPU0_PE3_OCP_RXN<12>")
	)
	(segment
		(start 327.370186 -123.93803)
		(end 327.603612 -123.93803)
		(width 0.1143)
		(layer "In11.Cu")
		(net "P3E_CPU0_PE3_OCP_RXN<12>")
	)
	(segment
		(start 297.520106 -92.556584)
		(end 297.813222 -92.387674)
		(width 0.0889)
		(layer "In11.Cu")
		(net "P3E_CPU0_PE3_OCP_RXN<12>")
	)
	(segment
		(start 450.058028 -125.555248)
		(end 450.847714 -123.649486)
		(width 0.1143)
		(layer "In11.Cu")
		(net "P3E_CPU0_PE3_OCP_RXN<12>")
	)
	(segment
		(start 385.982972 -140.879576)
		(end 390.32561 -140.879576)
		(width 0.1143)
		(layer "In11.Cu")
		(net "P3E_CPU0_PE3_OCP_RXN<12>")
	)
	(segment
		(start 305.0286 -104.1654)
		(end 306.510436 -104.1654)
		(width 0.1143)
		(layer "In11.Cu")
		(net "P3E_CPU0_PE3_OCP_RXN<12>")
	)
	(segment
		(start 326.409304 -122.977148)
		(end 326.651874 -123.219718)
		(width 0.1143)
		(layer "In11.Cu")
		(net "P3E_CPU0_PE3_OCP_RXN<12>")
	)
	(segment
		(start 394.20546 -141.93774)
		(end 399.806414 -140.913612)
		(width 0.1143)
		(layer "In11.Cu")
		(net "P3E_CPU0_PE3_OCP_RXN<12>")
	)
	(segment
		(start 417.388802 -140.281406)
		(end 425.288964 -136.836658)
		(width 0.1143)
		(layer "In11.Cu")
		(net "P3E_CPU0_PE3_OCP_RXN<12>")
	)
	(arc
		(start 299.248322 -100.081588)
		(mid 299.442172 -100.137938)
		(end 299.583856 -100.28174)
		(width 0.0889)
		(layer "In11.Cu")
		(net "P3E_CPU0_PE3_OCP_RXN<12>")
	)
	(arc
		(start 297.891962 -92.40901)
		(mid 297.919205 -92.585749)
		(end 297.866816 -92.756736)
		(width 0.0889)
		(layer "In11.Cu")
		(net "P3E_CPU0_PE3_OCP_RXN<12>")
	)
	(arc
		(start 300.1137 -100.576888)
		(mid 300.303629 -100.634758)
		(end 300.442376 -100.776786)
		(width 0.0889)
		(layer "In11.Cu")
		(net "P3E_CPU0_PE3_OCP_RXN<12>")
	)
	(arc
		(start 300.97222 -101.072188)
		(mid 301.162149 -101.130058)
		(end 301.300896 -101.272086)
		(width 0.0889)
		(layer "In11.Cu")
		(net "P3E_CPU0_PE3_OCP_RXN<12>")
	)
	(arc
		(start 297.866816 -94.33814)
		(mid 297.871061 -94.730385)
		(end 297.53814 -94.937834)
		(width 0.0889)
		(layer "In11.Cu")
		(net "P3E_CPU0_PE3_OCP_RXN<12>")
	)
	(arc
		(start 298.725336 -97.804986)
		(mid 298.778806 -98.000049)
		(end 298.730162 -98.1964)
		(width 0.0889)
		(layer "In11.Cu")
		(net "P3E_CPU0_PE3_OCP_RXN<12>")
	)
	(arc
		(start 297.871642 -93.355922)
		(mid 297.920397 -93.552274)
		(end 297.866816 -93.747336)
		(width 0.0889)
		(layer "In11.Cu")
		(net "P3E_CPU0_PE3_OCP_RXN<12>")
	)
	(arc
		(start 298.393612 -96.614488)
		(mid 298.72653 -96.816479)
		(end 298.730162 -97.2058)
		(width 0.0889)
		(layer "In11.Cu")
		(net "P3E_CPU0_PE3_OCP_RXN<12>")
	)
	(arc
		(start 300.442376 -100.776786)
		(mid 300.650984 -100.988718)
		(end 300.936406 -101.072188)
		(width 0.0889)
		(layer "In11.Cu")
		(net "P3E_CPU0_PE3_OCP_RXN<12>")
	)
	(arc
		(start 298.725336 -98.795586)
		(mid 298.778806 -98.990649)
		(end 298.730162 -99.187)
		(width 0.0889)
		(layer "In11.Cu")
		(net "P3E_CPU0_PE3_OCP_RXN<12>")
	)
	(arc
		(start 298.718986 -98.215704)
		(mid 298.646188 -98.506467)
		(end 298.725336 -98.795586)
		(width 0.0889)
		(layer "In11.Cu")
		(net "P3E_CPU0_PE3_OCP_RXN<12>")
	)
	(arc
		(start 298.718986 -99.206304)
		(mid 298.725163 -99.786236)
		(end 299.224192 -100.081588)
		(width 0.0889)
		(layer "In11.Cu")
		(net "P3E_CPU0_PE3_OCP_RXN<12>")
	)
	(arc
		(start 297.866816 -92.756736)
		(mid 297.787594 -93.045854)
		(end 297.860466 -93.336618)
		(width 0.0889)
		(layer "In11.Cu")
		(net "P3E_CPU0_PE3_OCP_RXN<12>")
	)
	(arc
		(start 299.583856 -100.28174)
		(mid 299.79086 -100.492604)
		(end 300.074076 -100.576888)
		(width 0.0889)
		(layer "In11.Cu")
		(net "P3E_CPU0_PE3_OCP_RXN<12>")
	)
	(arc
		(start 297.866816 -96.319086)
		(mid 298.075424 -96.531018)
		(end 298.360846 -96.614488)
		(width 0.0889)
		(layer "In11.Cu")
		(net "P3E_CPU0_PE3_OCP_RXN<12>")
	)
	(arc
		(start 297.531282 -96.118934)
		(mid 297.725132 -96.175284)
		(end 297.866816 -96.319086)
		(width 0.0889)
		(layer "In11.Cu")
		(net "P3E_CPU0_PE3_OCP_RXN<12>")
	)
	(arc
		(start 298.718986 -97.225104)
		(mid 298.646188 -97.515867)
		(end 298.725336 -97.804986)
		(width 0.0889)
		(layer "In11.Cu")
		(net "P3E_CPU0_PE3_OCP_RXN<12>")
	)
	(arc
		(start 297.498516 -94.937834)
		(mid 296.929164 -95.526734)
		(end 297.495214 -96.118934)
		(width 0.0889)
		(layer "In11.Cu")
		(net "P3E_CPU0_PE3_OCP_RXN<12>")
	)
	(arc
		(start 297.866816 -93.747336)
		(mid 297.787685 -94.042738)
		(end 297.866816 -94.33814)
		(width 0.0889)
		(layer "In11.Cu")
		(net "P3E_CPU0_PE3_OCP_RXN<12>")
	)
	(segment
		(start 451.27926 -119.45493)
		(end 451.18655 -119.678958)
		(width 0.1143)
		(layer "F.Cu")
		(net "P3E_CPU0_PE3_OCP_RXN<11>")
	)
	(segment
		(start 451.18655 -120.54967)
		(end 451.07225 -120.66397)
		(width 0.1143)
		(layer "F.Cu")
		(net "P3E_CPU0_PE3_OCP_RXN<11>")
	)
	(segment
		(start 451.07225 -120.66397)
		(end 450.6722 -120.66397)
		(width 0.1143)
		(layer "F.Cu")
		(net "P3E_CPU0_PE3_OCP_RXN<11>")
	)
	(segment
		(start 451.18655 -119.678958)
		(end 451.18655 -120.54967)
		(width 0.1143)
		(layer "F.Cu")
		(net "P3E_CPU0_PE3_OCP_RXN<11>")
	)
	(segment
		(start 450.99986 -118.343934)
		(end 451.27926 -118.623334)
		(width 0.1143)
		(layer "F.Cu")
		(net "P3E_CPU0_PE3_OCP_RXN<11>")
	)
	(segment
		(start 451.000876 -116.993162)
		(end 451.000876 -118.342918)
		(width 0.1143)
		(layer "F.Cu")
		(net "P3E_CPU0_PE3_OCP_RXN<11>")
	)
	(segment
		(start 451.000876 -118.342918)
		(end 450.99986 -118.343934)
		(width 0.1143)
		(layer "F.Cu")
		(net "P3E_CPU0_PE3_OCP_RXN<11>")
	)
	(segment
		(start 451.27926 -118.623334)
		(end 451.27926 -119.45493)
		(width 0.1143)
		(layer "F.Cu")
		(net "P3E_CPU0_PE3_OCP_RXN<11>")
	)
	(segment
		(start 299.524166 -94.042738)
		(end 300.095666 -94.042738)
		(width 0.1143)
		(layer "F.Cu")
		(net "P3E_CPU0_PE3_OCP_RXN<11>")
	)
	(via
		(at 300.095666 -94.042738)
		(size 0.508)
		(drill 0.254)
		(layers "F.Cu" "B.Cu")
		(net "P3E_CPU0_PE3_OCP_RXN<11>")
	)
	(via
		(at 450.6722 -120.66397)
		(size 0.508)
		(drill 0.254)
		(layers "F.Cu" "B.Cu")
		(net "P3E_CPU0_PE3_OCP_RXN<11>")
	)
	(segment
		(start 305.087274 -100.295202)
		(end 305.087274 -100.367338)
		(width 0.0889)
		(layer "In11.Cu")
		(net "P3E_CPU0_PE3_OCP_RXN<11>")
	)
	(segment
		(start 306.035456 -101.31552)
		(end 310.930544 -103.343202)
		(width 0.1143)
		(layer "In11.Cu")
		(net "P3E_CPU0_PE3_OCP_RXN<11>")
	)
	(segment
		(start 433.690776 -128.356868)
		(end 435.76494 -123.946158)
		(width 0.1143)
		(layer "In11.Cu")
		(net "P3E_CPU0_PE3_OCP_RXN<11>")
	)
	(segment
		(start 302.442372 -99.01682)
		(end 302.565054 -99.01682)
		(width 0.0889)
		(layer "In11.Cu")
		(net "P3E_CPU0_PE3_OCP_RXN<11>")
	)
	(segment
		(start 302.565054 -99.01682)
		(end 302.811434 -99.2632)
		(width 0.0889)
		(layer "In11.Cu")
		(net "P3E_CPU0_PE3_OCP_RXN<11>")
	)
	(segment
		(start 300.095666 -94.042738)
		(end 299.80255 -93.873574)
		(width 0.0889)
		(layer "In11.Cu")
		(net "P3E_CPU0_PE3_OCP_RXN<11>")
	)
	(segment
		(start 334.082644 -123.537472)
		(end 339.398356 -123.537472)
		(width 0.1143)
		(layer "In11.Cu")
		(net "P3E_CPU0_PE3_OCP_RXN<11>")
	)
	(segment
		(start 374.221502 -135.011414)
		(end 374.221502 -135.721598)
		(width 0.1143)
		(layer "In11.Cu")
		(net "P3E_CPU0_PE3_OCP_RXN<11>")
	)
	(segment
		(start 450.03974 -119.48668)
		(end 450.949568 -119.48668)
		(width 0.1143)
		(layer "In11.Cu")
		(net "P3E_CPU0_PE3_OCP_RXN<11>")
	)
	(segment
		(start 301.300896 -94.737936)
		(end 301.294546 -94.748604)
		(width 0.0889)
		(layer "In11.Cu")
		(net "P3E_CPU0_PE3_OCP_RXN<11>")
	)
	(segment
		(start 447.088768 -122.127518)
		(end 447.438272 -122.060208)
		(width 0.1143)
		(layer "In11.Cu")
		(net "P3E_CPU0_PE3_OCP_RXN<11>")
	)
	(segment
		(start 301.300896 -97.309686)
		(end 301.305722 -97.318322)
		(width 0.0889)
		(layer "In11.Cu")
		(net "P3E_CPU0_PE3_OCP_RXN<11>")
	)
	(segment
		(start 420.954962 -136.64311)
		(end 423.168826 -132.715)
		(width 0.1143)
		(layer "In11.Cu")
		(net "P3E_CPU0_PE3_OCP_RXN<11>")
	)
	(segment
		(start 399.61566 -139.003786)
		(end 405.357838 -139.003786)
		(width 0.1143)
		(layer "In11.Cu")
		(net "P3E_CPU0_PE3_OCP_RXN<11>")
	)
	(segment
		(start 352.476562 -124.77623)
		(end 353.376484 -124.601224)
		(width 0.1143)
		(layer "In11.Cu")
		(net "P3E_CPU0_PE3_OCP_RXN<11>")
	)
	(segment
		(start 361.662726 -127.38862)
		(end 366.880394 -129.549652)
		(width 0.1143)
		(layer "In11.Cu")
		(net "P3E_CPU0_PE3_OCP_RXN<11>")
	)
	(segment
		(start 302.316642 -98.89109)
		(end 302.442372 -99.01682)
		(width 0.0889)
		(layer "In11.Cu")
		(net "P3E_CPU0_PE3_OCP_RXN<11>")
	)
	(segment
		(start 447.088768 -122.127264)
		(end 447.088768 -122.127518)
		(width 0.1143)
		(layer "In11.Cu")
		(net "P3E_CPU0_PE3_OCP_RXN<11>")
	)
	(segment
		(start 302.97501 -99.332288)
		(end 303.020984 -99.445826)
		(width 0.0889)
		(layer "In11.Cu")
		(net "P3E_CPU0_PE3_OCP_RXN<11>")
	)
	(segment
		(start 449.695062 -121.246138)
		(end 449.695062 -120.709944)
		(width 0.1143)
		(layer "In11.Cu")
		(net "P3E_CPU0_PE3_OCP_RXN<11>")
	)
	(segment
		(start 303.784762 -99.675188)
		(end 303.948338 -99.744276)
		(width 0.0889)
		(layer "In11.Cu")
		(net "P3E_CPU0_PE3_OCP_RXN<11>")
	)
	(segment
		(start 301.300896 -96.319086)
		(end 301.305722 -96.327722)
		(width 0.0889)
		(layer "In11.Cu")
		(net "P3E_CPU0_PE3_OCP_RXN<11>")
	)
	(segment
		(start 423.168826 -132.715)
		(end 424.117008 -132.10667)
		(width 0.1143)
		(layer "In11.Cu")
		(net "P3E_CPU0_PE3_OCP_RXN<11>")
	)
	(segment
		(start 325.05904 -116.073682)
		(end 329.133708 -120.14835)
		(width 0.1143)
		(layer "In11.Cu")
		(net "P3E_CPU0_PE3_OCP_RXN<11>")
	)
	(segment
		(start 354.088954 -124.739908)
		(end 355.71176 -125.834394)
		(width 0.1143)
		(layer "In11.Cu")
		(net "P3E_CPU0_PE3_OCP_RXN<11>")
	)
	(segment
		(start 303.020984 -99.445826)
		(end 303.184814 -99.515168)
		(width 0.0889)
		(layer "In11.Cu")
		(net "P3E_CPU0_PE3_OCP_RXN<11>")
	)
	(segment
		(start 303.948338 -99.744276)
		(end 303.994312 -99.857814)
		(width 0.0889)
		(layer "In11.Cu")
		(net "P3E_CPU0_PE3_OCP_RXN<11>")
	)
	(segment
		(start 304.967894 -100.175822)
		(end 305.087274 -100.295202)
		(width 0.0889)
		(layer "In11.Cu")
		(net "P3E_CPU0_PE3_OCP_RXN<11>")
	)
	(segment
		(start 375.026682 -136.526778)
		(end 379.725428 -136.526778)
		(width 0.1143)
		(layer "In11.Cu")
		(net "P3E_CPU0_PE3_OCP_RXN<11>")
	)
	(segment
		(start 449.695062 -119.831358)
		(end 450.03974 -119.48668)
		(width 0.1143)
		(layer "In11.Cu")
		(net "P3E_CPU0_PE3_OCP_RXN<11>")
	)
	(segment
		(start 301.300896 -95.328486)
		(end 301.305722 -95.337122)
		(width 0.0889)
		(layer "In11.Cu")
		(net "P3E_CPU0_PE3_OCP_RXN<11>")
	)
	(segment
		(start 299.80255 -93.873574)
		(end 299.781468 -93.794834)
		(width 0.0889)
		(layer "In11.Cu")
		(net "P3E_CPU0_PE3_OCP_RXN<11>")
	)
	(segment
		(start 416.606736 -138.12901)
		(end 417.213034 -138.274806)
		(width 0.1143)
		(layer "In11.Cu")
		(net "P3E_CPU0_PE3_OCP_RXN<11>")
	)
	(segment
		(start 302.316642 -98.768408)
		(end 302.316642 -98.89109)
		(width 0.0889)
		(layer "In11.Cu")
		(net "P3E_CPU0_PE3_OCP_RXN<11>")
	)
	(segment
		(start 443.15253 -121.341134)
		(end 447.088768 -122.127264)
		(width 0.1143)
		(layer "In11.Cu")
		(net "P3E_CPU0_PE3_OCP_RXN<11>")
	)
	(segment
		(start 317.787782 -110.20044)
		(end 321.196462 -110.20044)
		(width 0.1143)
		(layer "In11.Cu")
		(net "P3E_CPU0_PE3_OCP_RXN<11>")
	)
	(segment
		(start 372.006368 -132.796788)
		(end 374.221502 -135.011414)
		(width 0.1143)
		(layer "In11.Cu")
		(net "P3E_CPU0_PE3_OCP_RXN<11>")
	)
	(segment
		(start 303.507648 -99.65182)
		(end 303.671478 -99.721162)
		(width 0.0889)
		(layer "In11.Cu")
		(net "P3E_CPU0_PE3_OCP_RXN<11>")
	)
	(segment
		(start 329.133708 -120.14835)
		(end 330.69276 -120.14835)
		(width 0.1143)
		(layer "In11.Cu")
		(net "P3E_CPU0_PE3_OCP_RXN<11>")
	)
	(segment
		(start 325.05904 -114.063018)
		(end 325.05904 -116.073682)
		(width 0.1143)
		(layer "In11.Cu")
		(net "P3E_CPU0_PE3_OCP_RXN<11>")
	)
	(segment
		(start 447.96837 -122.126502)
		(end 448.09918 -121.933208)
		(width 0.1143)
		(layer "In11.Cu")
		(net "P3E_CPU0_PE3_OCP_RXN<11>")
	)
	(segment
		(start 305.102768 -100.382832)
		(end 306.035456 -101.31552)
		(width 0.1143)
		(layer "In11.Cu")
		(net "P3E_CPU0_PE3_OCP_RXN<11>")
	)
	(segment
		(start 302.97501 -99.332542)
		(end 302.97501 -99.332288)
		(width 0.0889)
		(layer "In11.Cu")
		(net "P3E_CPU0_PE3_OCP_RXN<11>")
	)
	(segment
		(start 353.376484 -124.601224)
		(end 354.088954 -124.739908)
		(width 0.1143)
		(layer "In11.Cu")
		(net "P3E_CPU0_PE3_OCP_RXN<11>")
	)
	(segment
		(start 387.524752 -138.96721)
		(end 390.582404 -138.96721)
		(width 0.1143)
		(layer "In11.Cu")
		(net "P3E_CPU0_PE3_OCP_RXN<11>")
	)
	(segment
		(start 304.480976 -100.063808)
		(end 304.64506 -100.13315)
		(width 0.0889)
		(layer "In11.Cu")
		(net "P3E_CPU0_PE3_OCP_RXN<11>")
	)
	(segment
		(start 450.993764 -120.66397)
		(end 450.6722 -120.66397)
		(width 0.1143)
		(layer "In11.Cu")
		(net "P3E_CPU0_PE3_OCP_RXN<11>")
	)
	(segment
		(start 449.805298 -120.256808)
		(end 449.695062 -120.146572)
		(width 0.1143)
		(layer "In11.Cu")
		(net "P3E_CPU0_PE3_OCP_RXN<11>")
	)
	(segment
		(start 305.087274 -100.367338)
		(end 305.102768 -100.382832)
		(width 0.0889)
		(layer "In11.Cu")
		(net "P3E_CPU0_PE3_OCP_RXN<11>")
	)
	(segment
		(start 411.912562 -137.71499)
		(end 415.143442 -138.460988)
		(width 0.1143)
		(layer "In11.Cu")
		(net "P3E_CPU0_PE3_OCP_RXN<11>")
	)
	(segment
		(start 330.69276 -120.14835)
		(end 334.082644 -123.537472)
		(width 0.1143)
		(layer "In11.Cu")
		(net "P3E_CPU0_PE3_OCP_RXN<11>")
	)
	(segment
		(start 449.695062 -120.146572)
		(end 449.695062 -119.831358)
		(width 0.1143)
		(layer "In11.Cu")
		(net "P3E_CPU0_PE3_OCP_RXN<11>")
	)
	(segment
		(start 321.196462 -110.20044)
		(end 325.05904 -114.063018)
		(width 0.1143)
		(layer "In11.Cu")
		(net "P3E_CPU0_PE3_OCP_RXN<11>")
	)
	(segment
		(start 415.143442 -138.460988)
		(end 416.606736 -138.12901)
		(width 0.1143)
		(layer "In11.Cu")
		(net "P3E_CPU0_PE3_OCP_RXN<11>")
	)
	(segment
		(start 351.071688 -124.777754)
		(end 351.778316 -124.640594)
		(width 0.1143)
		(layer "In11.Cu")
		(net "P3E_CPU0_PE3_OCP_RXN<11>")
	)
	(segment
		(start 390.582404 -138.96721)
		(end 394.288772 -139.977368)
		(width 0.1143)
		(layer "In11.Cu")
		(net "P3E_CPU0_PE3_OCP_RXN<11>")
	)
	(segment
		(start 300.08068 -93.642688)
		(end 300.110652 -93.642688)
		(width 0.0889)
		(layer "In11.Cu")
		(net "P3E_CPU0_PE3_OCP_RXN<11>")
	)
	(segment
		(start 381.58674 -137.758932)
		(end 387.524752 -138.96721)
		(width 0.1143)
		(layer "In11.Cu")
		(net "P3E_CPU0_PE3_OCP_RXN<11>")
	)
	(segment
		(start 451.1548 -120.502934)
		(end 450.993764 -120.66397)
		(width 0.1143)
		(layer "In11.Cu")
		(net "P3E_CPU0_PE3_OCP_RXN<11>")
	)
	(segment
		(start 303.184814 -99.515168)
		(end 303.298098 -99.469194)
		(width 0.0889)
		(layer "In11.Cu")
		(net "P3E_CPU0_PE3_OCP_RXN<11>")
	)
	(segment
		(start 302.811434 -99.2632)
		(end 302.97501 -99.332542)
		(width 0.0889)
		(layer "In11.Cu")
		(net "P3E_CPU0_PE3_OCP_RXN<11>")
	)
	(segment
		(start 304.158142 -99.927156)
		(end 304.271426 -99.881182)
		(width 0.0889)
		(layer "In11.Cu")
		(net "P3E_CPU0_PE3_OCP_RXN<11>")
	)
	(segment
		(start 301.294546 -97.299018)
		(end 301.300896 -97.309686)
		(width 0.0889)
		(layer "In11.Cu")
		(net "P3E_CPU0_PE3_OCP_RXN<11>")
	)
	(segment
		(start 435.76494 -123.946158)
		(end 441.02655 -121.76633)
		(width 0.1143)
		(layer "In11.Cu")
		(net "P3E_CPU0_PE3_OCP_RXN<11>")
	)
	(segment
		(start 339.398356 -123.537472)
		(end 344.732102 -124.621798)
		(width 0.1143)
		(layer "In11.Cu")
		(net "P3E_CPU0_PE3_OCP_RXN<11>")
	)
	(segment
		(start 447.438272 -122.060208)
		(end 447.631566 -122.191272)
		(width 0.1143)
		(layer "In11.Cu")
		(net "P3E_CPU0_PE3_OCP_RXN<11>")
	)
	(segment
		(start 304.75809 -100.087176)
		(end 304.967894 -100.175822)
		(width 0.0889)
		(layer "In11.Cu")
		(net "P3E_CPU0_PE3_OCP_RXN<11>")
	)
	(segment
		(start 430.711356 -129.209546)
		(end 433.690776 -128.356868)
		(width 0.1143)
		(layer "In11.Cu")
		(net "P3E_CPU0_PE3_OCP_RXN<11>")
	)
	(segment
		(start 369.791742 -132.461)
		(end 371.197632 -132.461)
		(width 0.1143)
		(layer "In11.Cu")
		(net "P3E_CPU0_PE3_OCP_RXN<11>")
	)
	(segment
		(start 302.143922 -98.595688)
		(end 302.316642 -98.768408)
		(width 0.0889)
		(layer "In11.Cu")
		(net "P3E_CPU0_PE3_OCP_RXN<11>")
	)
	(segment
		(start 394.288772 -139.977368)
		(end 399.61566 -139.003786)
		(width 0.1143)
		(layer "In11.Cu")
		(net "P3E_CPU0_PE3_OCP_RXN<11>")
	)
	(segment
		(start 417.213034 -138.274806)
		(end 420.954962 -136.64311)
		(width 0.1143)
		(layer "In11.Cu")
		(net "P3E_CPU0_PE3_OCP_RXN<11>")
	)
	(segment
		(start 300.941232 -94.137988)
		(end 300.965362 -94.137988)
		(width 0.0889)
		(layer "In11.Cu")
		(net "P3E_CPU0_PE3_OCP_RXN<11>")
	)
	(segment
		(start 449.224146 -121.717054)
		(end 449.695062 -121.246138)
		(width 0.1143)
		(layer "In11.Cu")
		(net "P3E_CPU0_PE3_OCP_RXN<11>")
	)
	(segment
		(start 366.880394 -129.549652)
		(end 369.791742 -132.461)
		(width 0.1143)
		(layer "In11.Cu")
		(net "P3E_CPU0_PE3_OCP_RXN<11>")
	)
	(segment
		(start 304.271426 -99.881182)
		(end 304.435002 -99.95027)
		(width 0.0889)
		(layer "In11.Cu")
		(net "P3E_CPU0_PE3_OCP_RXN<11>")
	)
	(segment
		(start 351.778316 -124.640594)
		(end 352.476562 -124.77623)
		(width 0.1143)
		(layer "In11.Cu")
		(net "P3E_CPU0_PE3_OCP_RXN<11>")
	)
	(segment
		(start 374.221502 -135.721598)
		(end 375.026682 -136.526778)
		(width 0.1143)
		(layer "In11.Cu")
		(net "P3E_CPU0_PE3_OCP_RXN<11>")
	)
	(segment
		(start 301.294546 -96.308418)
		(end 301.300896 -96.319086)
		(width 0.0889)
		(layer "In11.Cu")
		(net "P3E_CPU0_PE3_OCP_RXN<11>")
	)
	(segment
		(start 344.732102 -124.621798)
		(end 350.269302 -124.621798)
		(width 0.1143)
		(layer "In11.Cu")
		(net "P3E_CPU0_PE3_OCP_RXN<11>")
	)
	(segment
		(start 355.71176 -125.834394)
		(end 359.190036 -127.38862)
		(width 0.1143)
		(layer "In11.Cu")
		(net "P3E_CPU0_PE3_OCP_RXN<11>")
	)
	(segment
		(start 447.631566 -122.191272)
		(end 447.96837 -122.126502)
		(width 0.1143)
		(layer "In11.Cu")
		(net "P3E_CPU0_PE3_OCP_RXN<11>")
	)
	(segment
		(start 427.64837 -131.280408)
		(end 430.711356 -129.209546)
		(width 0.1143)
		(layer "In11.Cu")
		(net "P3E_CPU0_PE3_OCP_RXN<11>")
	)
	(segment
		(start 371.197632 -132.461)
		(end 372.006368 -132.796788)
		(width 0.1143)
		(layer "In11.Cu")
		(net "P3E_CPU0_PE3_OCP_RXN<11>")
	)
	(segment
		(start 303.461674 -99.538282)
		(end 303.507648 -99.65182)
		(width 0.0889)
		(layer "In11.Cu")
		(net "P3E_CPU0_PE3_OCP_RXN<11>")
	)
	(segment
		(start 448.09918 -121.933208)
		(end 449.224146 -121.717054)
		(width 0.1143)
		(layer "In11.Cu")
		(net "P3E_CPU0_PE3_OCP_RXN<11>")
	)
	(segment
		(start 301.79899 -98.595688)
		(end 302.143922 -98.595688)
		(width 0.0889)
		(layer "In11.Cu")
		(net "P3E_CPU0_PE3_OCP_RXN<11>")
	)
	(segment
		(start 450.949568 -119.48668)
		(end 451.1548 -119.691912)
		(width 0.1143)
		(layer "In11.Cu")
		(net "P3E_CPU0_PE3_OCP_RXN<11>")
	)
	(segment
		(start 449.805298 -120.599708)
		(end 449.805298 -120.256808)
		(width 0.1143)
		(layer "In11.Cu")
		(net "P3E_CPU0_PE3_OCP_RXN<11>")
	)
	(segment
		(start 303.298098 -99.469194)
		(end 303.461674 -99.538282)
		(width 0.0889)
		(layer "In11.Cu")
		(net "P3E_CPU0_PE3_OCP_RXN<11>")
	)
	(segment
		(start 441.02655 -121.76633)
		(end 443.15253 -121.341134)
		(width 0.1143)
		(layer "In11.Cu")
		(net "P3E_CPU0_PE3_OCP_RXN<11>")
	)
	(segment
		(start 303.671478 -99.721162)
		(end 303.784762 -99.675188)
		(width 0.0889)
		(layer "In11.Cu")
		(net "P3E_CPU0_PE3_OCP_RXN<11>")
	)
	(segment
		(start 405.357838 -139.003786)
		(end 411.912562 -137.71499)
		(width 0.1143)
		(layer "In11.Cu")
		(net "P3E_CPU0_PE3_OCP_RXN<11>")
	)
	(segment
		(start 304.435002 -99.95027)
		(end 304.480976 -100.063808)
		(width 0.0889)
		(layer "In11.Cu")
		(net "P3E_CPU0_PE3_OCP_RXN<11>")
	)
	(segment
		(start 303.994312 -99.857814)
		(end 304.158142 -99.927156)
		(width 0.0889)
		(layer "In11.Cu")
		(net "P3E_CPU0_PE3_OCP_RXN<11>")
	)
	(segment
		(start 359.190036 -127.38862)
		(end 361.662726 -127.38862)
		(width 0.1143)
		(layer "In11.Cu")
		(net "P3E_CPU0_PE3_OCP_RXN<11>")
	)
	(segment
		(start 310.930544 -103.343202)
		(end 317.787782 -110.20044)
		(width 0.1143)
		(layer "In11.Cu")
		(net "P3E_CPU0_PE3_OCP_RXN<11>")
	)
	(segment
		(start 451.1548 -119.691912)
		(end 451.1548 -120.502934)
		(width 0.1143)
		(layer "In11.Cu")
		(net "P3E_CPU0_PE3_OCP_RXN<11>")
	)
	(segment
		(start 304.64506 -100.13315)
		(end 304.75809 -100.087176)
		(width 0.0889)
		(layer "In11.Cu")
		(net "P3E_CPU0_PE3_OCP_RXN<11>")
	)
	(segment
		(start 449.695062 -120.709944)
		(end 449.805298 -120.599708)
		(width 0.1143)
		(layer "In11.Cu")
		(net "P3E_CPU0_PE3_OCP_RXN<11>")
	)
	(segment
		(start 379.725428 -136.526778)
		(end 381.58674 -137.758932)
		(width 0.1143)
		(layer "In11.Cu")
		(net "P3E_CPU0_PE3_OCP_RXN<11>")
	)
	(segment
		(start 350.269302 -124.621798)
		(end 351.071688 -124.777754)
		(width 0.1143)
		(layer "In11.Cu")
		(net "P3E_CPU0_PE3_OCP_RXN<11>")
	)
	(segment
		(start 424.117008 -132.10667)
		(end 427.64837 -131.280408)
		(width 0.1143)
		(layer "In11.Cu")
		(net "P3E_CPU0_PE3_OCP_RXN<11>")
	)
	(arc
		(start 301.300896 -95.728536)
		(mid 301.221674 -96.017654)
		(end 301.294546 -96.308418)
		(width 0.0889)
		(layer "In11.Cu")
		(net "P3E_CPU0_PE3_OCP_RXN<11>")
	)
	(arc
		(start 300.965362 -94.137988)
		(mid 301.303477 -94.34269)
		(end 301.300896 -94.737936)
		(width 0.0889)
		(layer "In11.Cu")
		(net "P3E_CPU0_PE3_OCP_RXN<11>")
	)
	(arc
		(start 301.305722 -97.318322)
		(mid 301.354477 -97.514674)
		(end 301.300896 -97.709736)
		(width 0.0889)
		(layer "In11.Cu")
		(net "P3E_CPU0_PE3_OCP_RXN<11>")
	)
	(arc
		(start 299.781468 -93.794834)
		(mid 299.914349 -93.685851)
		(end 300.08068 -93.642688)
		(width 0.0889)
		(layer "In11.Cu")
		(net "P3E_CPU0_PE3_OCP_RXN<11>")
	)
	(arc
		(start 301.294546 -94.748604)
		(mid 301.221748 -95.039367)
		(end 301.300896 -95.328486)
		(width 0.0889)
		(layer "In11.Cu")
		(net "P3E_CPU0_PE3_OCP_RXN<11>")
	)
	(arc
		(start 301.300896 -97.709736)
		(mid 301.297725 -98.294464)
		(end 301.79899 -98.595688)
		(width 0.0889)
		(layer "In11.Cu")
		(net "P3E_CPU0_PE3_OCP_RXN<11>")
	)
	(arc
		(start 300.442376 -93.842586)
		(mid 300.653089 -94.055665)
		(end 300.941232 -94.137988)
		(width 0.0889)
		(layer "In11.Cu")
		(net "P3E_CPU0_PE3_OCP_RXN<11>")
	)
	(arc
		(start 301.300896 -96.719136)
		(mid 301.221674 -97.008254)
		(end 301.294546 -97.299018)
		(width 0.0889)
		(layer "In11.Cu")
		(net "P3E_CPU0_PE3_OCP_RXN<11>")
	)
	(arc
		(start 300.110652 -93.642688)
		(mid 300.302294 -93.699854)
		(end 300.442376 -93.842586)
		(width 0.0889)
		(layer "In11.Cu")
		(net "P3E_CPU0_PE3_OCP_RXN<11>")
	)
	(arc
		(start 301.305722 -96.327722)
		(mid 301.354477 -96.524074)
		(end 301.300896 -96.719136)
		(width 0.0889)
		(layer "In11.Cu")
		(net "P3E_CPU0_PE3_OCP_RXN<11>")
	)
	(arc
		(start 301.305722 -95.337122)
		(mid 301.354477 -95.533474)
		(end 301.300896 -95.728536)
		(width 0.0889)
		(layer "In11.Cu")
		(net "P3E_CPU0_PE3_OCP_RXN<11>")
	)
	(segment
		(start 447.799968 -118.343934)
		(end 448.079368 -118.623334)
		(width 0.1143)
		(layer "F.Cu")
		(net "P3E_CPU0_PE3_OCP_RXN<10>")
	)
	(segment
		(start 447.87185 -120.81637)
		(end 447.4718 -120.81637)
		(width 0.1143)
		(layer "F.Cu")
		(net "P3E_CPU0_PE3_OCP_RXN<10>")
	)
	(segment
		(start 447.98615 -119.692928)
		(end 447.98615 -120.70207)
		(width 0.1143)
		(layer "F.Cu")
		(net "P3E_CPU0_PE3_OCP_RXN<10>")
	)
	(segment
		(start 447.800984 -116.993162)
		(end 447.800984 -118.342918)
		(width 0.1143)
		(layer "F.Cu")
		(net "P3E_CPU0_PE3_OCP_RXN<10>")
	)
	(segment
		(start 448.079368 -118.623334)
		(end 448.079368 -119.46763)
		(width 0.1143)
		(layer "F.Cu")
		(net "P3E_CPU0_PE3_OCP_RXN<10>")
	)
	(segment
		(start 448.079368 -119.46763)
		(end 447.98615 -119.692928)
		(width 0.1143)
		(layer "F.Cu")
		(net "P3E_CPU0_PE3_OCP_RXN<10>")
	)
	(segment
		(start 447.98615 -120.70207)
		(end 447.87185 -120.81637)
		(width 0.1143)
		(layer "F.Cu")
		(net "P3E_CPU0_PE3_OCP_RXN<10>")
	)
	(segment
		(start 297.807126 -94.042738)
		(end 298.378626 -94.042738)
		(width 0.1143)
		(layer "F.Cu")
		(net "P3E_CPU0_PE3_OCP_RXN<10>")
	)
	(segment
		(start 447.800984 -118.342918)
		(end 447.799968 -118.343934)
		(width 0.1143)
		(layer "F.Cu")
		(net "P3E_CPU0_PE3_OCP_RXN<10>")
	)
	(via
		(at 298.378626 -94.042738)
		(size 0.508)
		(drill 0.254)
		(layers "F.Cu" "B.Cu")
		(net "P3E_CPU0_PE3_OCP_RXN<10>")
	)
	(via
		(at 447.4718 -120.81637)
		(size 0.508)
		(drill 0.254)
		(layers "F.Cu" "B.Cu")
		(net "P3E_CPU0_PE3_OCP_RXN<10>")
	)
	(segment
		(start 381.729488 -137.084816)
		(end 387.863588 -138.33221)
		(width 0.1143)
		(layer "In11.Cu")
		(net "P3E_CPU0_PE3_OCP_RXN<10>")
	)
	(segment
		(start 300.932596 -93.147134)
		(end 300.965362 -93.147134)
		(width 0.0889)
		(layer "In11.Cu")
		(net "P3E_CPU0_PE3_OCP_RXN<10>")
	)
	(segment
		(start 298.378626 -93.704664)
		(end 298.443904 -93.639386)
		(width 0.0889)
		(layer "In11.Cu")
		(net "P3E_CPU0_PE3_OCP_RXN<10>")
	)
	(segment
		(start 325.69404 -113.669826)
		(end 325.69404 -115.810284)
		(width 0.1143)
		(layer "In11.Cu")
		(net "P3E_CPU0_PE3_OCP_RXN<10>")
	)
	(segment
		(start 349.087186 -122.201178)
		(end 350.992948 -121.830592)
		(width 0.1143)
		(layer "In11.Cu")
		(net "P3E_CPU0_PE3_OCP_RXN<10>")
	)
	(segment
		(start 370.114322 -131.811014)
		(end 371.684804 -131.811014)
		(width 0.1143)
		(layer "In11.Cu")
		(net "P3E_CPU0_PE3_OCP_RXN<10>")
	)
	(segment
		(start 359.328466 -126.733046)
		(end 361.811316 -126.733046)
		(width 0.1143)
		(layer "In11.Cu")
		(net "P3E_CPU0_PE3_OCP_RXN<10>")
	)
	(segment
		(start 394.316458 -139.326366)
		(end 399.565622 -138.367262)
		(width 0.1143)
		(layer "In11.Cu")
		(net "P3E_CPU0_PE3_OCP_RXN<10>")
	)
	(segment
		(start 341.824818 -123.327922)
		(end 344.196924 -122.866912)
		(width 0.1143)
		(layer "In11.Cu")
		(net "P3E_CPU0_PE3_OCP_RXN<10>")
	)
	(segment
		(start 350.992948 -121.830592)
		(end 351.49028 -121.830592)
		(width 0.1143)
		(layer "In11.Cu")
		(net "P3E_CPU0_PE3_OCP_RXN<10>")
	)
	(segment
		(start 423.915332 -131.478274)
		(end 427.433486 -130.65506)
		(width 0.1143)
		(layer "In11.Cu")
		(net "P3E_CPU0_PE3_OCP_RXN<10>")
	)
	(segment
		(start 415.186114 -137.798556)
		(end 416.6108 -137.475722)
		(width 0.1143)
		(layer "In11.Cu")
		(net "P3E_CPU0_PE3_OCP_RXN<10>")
	)
	(segment
		(start 422.691052 -132.263134)
		(end 423.915332 -131.478274)
		(width 0.1143)
		(layer "In11.Cu")
		(net "P3E_CPU0_PE3_OCP_RXN<10>")
	)
	(segment
		(start 302.159416 -97.214436)
		(end 302.153066 -97.225104)
		(width 0.0889)
		(layer "In11.Cu")
		(net "P3E_CPU0_PE3_OCP_RXN<10>")
	)
	(segment
		(start 432.383692 -124.596652)
		(end 441.69076 -120.74144)
		(width 0.1143)
		(layer "In11.Cu")
		(net "P3E_CPU0_PE3_OCP_RXN<10>")
	)
	(segment
		(start 304.00117 -99.156266)
		(end 305.630834 -99.831144)
		(width 0.0889)
		(layer "In11.Cu")
		(net "P3E_CPU0_PE3_OCP_RXN<10>")
	)
	(segment
		(start 302.412146 -98.0948)
		(end 302.833786 -98.376486)
		(width 0.0889)
		(layer "In11.Cu")
		(net "P3E_CPU0_PE3_OCP_RXN<10>")
	)
	(segment
		(start 445.942212 -120.012714)
		(end 446.27927 -119.945404)
		(width 0.1143)
		(layer "In11.Cu")
		(net "P3E_CPU0_PE3_OCP_RXN<10>")
	)
	(segment
		(start 431.07737 -128.191768)
		(end 432.383692 -124.596652)
		(width 0.1143)
		(layer "In11.Cu")
		(net "P3E_CPU0_PE3_OCP_RXN<10>")
	)
	(segment
		(start 352.645726 -122.055382)
		(end 354.317808 -123.182888)
		(width 0.1143)
		(layer "In11.Cu")
		(net "P3E_CPU0_PE3_OCP_RXN<10>")
	)
	(segment
		(start 302.2092 -97.8916)
		(end 302.209708 -97.892362)
		(width 0.0889)
		(layer "In11.Cu")
		(net "P3E_CPU0_PE3_OCP_RXN<10>")
	)
	(segment
		(start 305.920902 -100.193348)
		(end 305.936396 -100.208842)
		(width 0.0889)
		(layer "In11.Cu")
		(net "P3E_CPU0_PE3_OCP_RXN<10>")
	)
	(segment
		(start 416.6108 -137.475722)
		(end 417.14801 -137.604754)
		(width 0.1143)
		(layer "In11.Cu")
		(net "P3E_CPU0_PE3_OCP_RXN<10>")
	)
	(segment
		(start 303.468786 -98.897948)
		(end 303.5808 -98.875596)
		(width 0.0889)
		(layer "In11.Cu")
		(net "P3E_CPU0_PE3_OCP_RXN<10>")
	)
	(segment
		(start 302.159416 -96.223836)
		(end 302.153066 -96.234504)
		(width 0.0889)
		(layer "In11.Cu")
		(net "P3E_CPU0_PE3_OCP_RXN<10>")
	)
	(segment
		(start 329.17384 -119.290084)
		(end 330.76642 -119.290084)
		(width 0.1143)
		(layer "In11.Cu")
		(net "P3E_CPU0_PE3_OCP_RXN<10>")
	)
	(segment
		(start 447.675 -119.6594)
		(end 447.994024 -119.978424)
		(width 0.1143)
		(layer "In11.Cu")
		(net "P3E_CPU0_PE3_OCP_RXN<10>")
	)
	(segment
		(start 303.5808 -98.875596)
		(end 303.60874 -98.894138)
		(width 0.0889)
		(layer "In11.Cu")
		(net "P3E_CPU0_PE3_OCP_RXN<10>")
	)
	(segment
		(start 305.920902 -100.121212)
		(end 305.920902 -100.193348)
		(width 0.0889)
		(layer "In11.Cu")
		(net "P3E_CPU0_PE3_OCP_RXN<10>")
	)
	(segment
		(start 367.320068 -129.01676)
		(end 370.114322 -131.811014)
		(width 0.1143)
		(layer "In11.Cu")
		(net "P3E_CPU0_PE3_OCP_RXN<10>")
	)
	(segment
		(start 299.22597 -93.147134)
		(end 299.258736 -93.147134)
		(width 0.0889)
		(layer "In11.Cu")
		(net "P3E_CPU0_PE3_OCP_RXN<10>")
	)
	(segment
		(start 390.667494 -138.33221)
		(end 394.316458 -139.326366)
		(width 0.1143)
		(layer "In11.Cu")
		(net "P3E_CPU0_PE3_OCP_RXN<10>")
	)
	(segment
		(start 330.76642 -119.290084)
		(end 334.378808 -122.902472)
		(width 0.1143)
		(layer "In11.Cu")
		(net "P3E_CPU0_PE3_OCP_RXN<10>")
	)
	(segment
		(start 445.381126 -120.116092)
		(end 445.464692 -119.99087)
		(width 0.1143)
		(layer "In11.Cu")
		(net "P3E_CPU0_PE3_OCP_RXN<10>")
	)
	(segment
		(start 325.69404 -115.810284)
		(end 329.17384 -119.290084)
		(width 0.1143)
		(layer "In11.Cu")
		(net "P3E_CPU0_PE3_OCP_RXN<10>")
	)
	(segment
		(start 302.159416 -97.804986)
		(end 302.2092 -97.8916)
		(width 0.0889)
		(layer "In11.Cu")
		(net "P3E_CPU0_PE3_OCP_RXN<10>")
	)
	(segment
		(start 427.433486 -130.65506)
		(end 431.07737 -128.191768)
		(width 0.1143)
		(layer "In11.Cu")
		(net "P3E_CPU0_PE3_OCP_RXN<10>")
	)
	(segment
		(start 447.129662 -119.6594)
		(end 447.675 -119.6594)
		(width 0.1143)
		(layer "In11.Cu")
		(net "P3E_CPU0_PE3_OCP_RXN<10>")
	)
	(segment
		(start 361.811316 -126.733046)
		(end 367.320068 -129.01676)
		(width 0.1143)
		(layer "In11.Cu")
		(net "P3E_CPU0_PE3_OCP_RXN<10>")
	)
	(segment
		(start 305.936396 -100.208842)
		(end 306.241704 -100.514404)
		(width 0.1143)
		(layer "In11.Cu")
		(net "P3E_CPU0_PE3_OCP_RXN<10>")
	)
	(segment
		(start 345.233244 -121.830592)
		(end 347.181424 -121.830592)
		(width 0.1143)
		(layer "In11.Cu")
		(net "P3E_CPU0_PE3_OCP_RXN<10>")
	)
	(segment
		(start 344.196924 -122.866912)
		(end 345.233244 -121.830592)
		(width 0.1143)
		(layer "In11.Cu")
		(net "P3E_CPU0_PE3_OCP_RXN<10>")
	)
	(segment
		(start 303.13376 -98.577146)
		(end 303.298352 -98.686874)
		(width 0.0889)
		(layer "In11.Cu")
		(net "P3E_CPU0_PE3_OCP_RXN<10>")
	)
	(segment
		(start 317.950088 -109.29874)
		(end 321.322954 -109.29874)
		(width 0.1143)
		(layer "In11.Cu")
		(net "P3E_CPU0_PE3_OCP_RXN<10>")
	)
	(segment
		(start 443.30493 -120.420638)
		(end 444.9191 -120.099582)
		(width 0.1143)
		(layer "In11.Cu")
		(net "P3E_CPU0_PE3_OCP_RXN<10>")
	)
	(segment
		(start 376.454162 -134.091172)
		(end 377.532392 -134.307072)
		(width 0.1143)
		(layer "In11.Cu")
		(net "P3E_CPU0_PE3_OCP_RXN<10>")
	)
	(segment
		(start 411.966664 -137.055606)
		(end 415.186114 -137.798556)
		(width 0.1143)
		(layer "In11.Cu")
		(net "P3E_CPU0_PE3_OCP_RXN<10>")
	)
	(segment
		(start 420.505382 -136.140952)
		(end 422.691052 -132.263134)
		(width 0.1143)
		(layer "In11.Cu")
		(net "P3E_CPU0_PE3_OCP_RXN<10>")
	)
	(segment
		(start 303.007014 -98.602292)
		(end 303.13376 -98.577146)
		(width 0.0889)
		(layer "In11.Cu")
		(net "P3E_CPU0_PE3_OCP_RXN<10>")
	)
	(segment
		(start 303.60874 -98.894138)
		(end 304.00117 -99.156266)
		(width 0.0889)
		(layer "In11.Cu")
		(net "P3E_CPU0_PE3_OCP_RXN<10>")
	)
	(segment
		(start 303.320704 -98.799142)
		(end 303.468786 -98.897948)
		(width 0.0889)
		(layer "In11.Cu")
		(net "P3E_CPU0_PE3_OCP_RXN<10>")
	)
	(segment
		(start 302.164242 -96.2152)
		(end 302.159416 -96.223836)
		(width 0.0889)
		(layer "In11.Cu")
		(net "P3E_CPU0_PE3_OCP_RXN<10>")
	)
	(segment
		(start 441.69076 -120.74144)
		(end 443.304676 -120.420384)
		(width 0.1143)
		(layer "In11.Cu")
		(net "P3E_CPU0_PE3_OCP_RXN<10>")
	)
	(segment
		(start 303.298352 -98.686874)
		(end 303.320704 -98.799142)
		(width 0.0889)
		(layer "In11.Cu")
		(net "P3E_CPU0_PE3_OCP_RXN<10>")
	)
	(segment
		(start 375.1199 -133.20776)
		(end 376.454162 -134.091172)
		(width 0.1143)
		(layer "In11.Cu")
		(net "P3E_CPU0_PE3_OCP_RXN<10>")
	)
	(segment
		(start 377.532392 -134.307072)
		(end 381.729488 -137.084816)
		(width 0.1143)
		(layer "In11.Cu")
		(net "P3E_CPU0_PE3_OCP_RXN<10>")
	)
	(segment
		(start 446.369186 -119.810784)
		(end 447.129662 -119.6594)
		(width 0.1143)
		(layer "In11.Cu")
		(net "P3E_CPU0_PE3_OCP_RXN<10>")
	)
	(segment
		(start 306.241704 -100.514404)
		(end 311.559956 -102.908608)
		(width 0.1143)
		(layer "In11.Cu")
		(net "P3E_CPU0_PE3_OCP_RXN<10>")
	)
	(segment
		(start 443.304676 -120.420384)
		(end 443.30493 -120.420638)
		(width 0.1143)
		(layer "In11.Cu")
		(net "P3E_CPU0_PE3_OCP_RXN<10>")
	)
	(segment
		(start 446.27927 -119.945404)
		(end 446.369186 -119.810784)
		(width 0.1143)
		(layer "In11.Cu")
		(net "P3E_CPU0_PE3_OCP_RXN<10>")
	)
	(segment
		(start 447.771774 -120.81637)
		(end 447.4718 -120.81637)
		(width 0.1143)
		(layer "In11.Cu")
		(net "P3E_CPU0_PE3_OCP_RXN<10>")
	)
	(segment
		(start 351.49028 -121.830592)
		(end 352.645726 -122.055382)
		(width 0.1143)
		(layer "In11.Cu")
		(net "P3E_CPU0_PE3_OCP_RXN<10>")
	)
	(segment
		(start 405.295608 -138.367262)
		(end 411.966664 -137.055606)
		(width 0.1143)
		(layer "In11.Cu")
		(net "P3E_CPU0_PE3_OCP_RXN<10>")
	)
	(segment
		(start 300.08068 -92.652088)
		(end 300.110652 -92.652088)
		(width 0.0889)
		(layer "In11.Cu")
		(net "P3E_CPU0_PE3_OCP_RXN<10>")
	)
	(segment
		(start 447.994024 -120.59412)
		(end 447.771774 -120.81637)
		(width 0.1143)
		(layer "In11.Cu")
		(net "P3E_CPU0_PE3_OCP_RXN<10>")
	)
	(segment
		(start 355.989636 -124.31014)
		(end 356.741222 -125.424946)
		(width 0.1143)
		(layer "In11.Cu")
		(net "P3E_CPU0_PE3_OCP_RXN<10>")
	)
	(segment
		(start 445.044068 -120.183402)
		(end 445.381126 -120.116092)
		(width 0.1143)
		(layer "In11.Cu")
		(net "P3E_CPU0_PE3_OCP_RXN<10>")
	)
	(segment
		(start 347.181424 -121.830592)
		(end 349.087186 -122.201178)
		(width 0.1143)
		(layer "In11.Cu")
		(net "P3E_CPU0_PE3_OCP_RXN<10>")
	)
	(segment
		(start 302.858932 -98.503486)
		(end 303.007014 -98.602292)
		(width 0.0889)
		(layer "In11.Cu")
		(net "P3E_CPU0_PE3_OCP_RXN<10>")
	)
	(segment
		(start 417.148264 -137.604754)
		(end 420.505382 -136.140952)
		(width 0.1143)
		(layer "In11.Cu")
		(net "P3E_CPU0_PE3_OCP_RXN<10>")
	)
	(segment
		(start 445.807846 -119.922544)
		(end 445.942212 -120.012714)
		(width 0.1143)
		(layer "In11.Cu")
		(net "P3E_CPU0_PE3_OCP_RXN<10>")
	)
	(segment
		(start 302.153066 -94.822518)
		(end 302.159416 -94.833186)
		(width 0.0889)
		(layer "In11.Cu")
		(net "P3E_CPU0_PE3_OCP_RXN<10>")
	)
	(segment
		(start 302.164242 -94.234)
		(end 302.159416 -94.242636)
		(width 0.0889)
		(layer "In11.Cu")
		(net "P3E_CPU0_PE3_OCP_RXN<10>")
	)
	(segment
		(start 302.833786 -98.376486)
		(end 302.858932 -98.503486)
		(width 0.0889)
		(layer "In11.Cu")
		(net "P3E_CPU0_PE3_OCP_RXN<10>")
	)
	(segment
		(start 417.14801 -137.604754)
		(end 417.148264 -137.604754)
		(width 0.1143)
		(layer "In11.Cu")
		(net "P3E_CPU0_PE3_OCP_RXN<10>")
	)
	(segment
		(start 447.994024 -119.978424)
		(end 447.994024 -120.59412)
		(width 0.1143)
		(layer "In11.Cu")
		(net "P3E_CPU0_PE3_OCP_RXN<10>")
	)
	(segment
		(start 444.9191 -120.099582)
		(end 445.044068 -120.183402)
		(width 0.1143)
		(layer "In11.Cu")
		(net "P3E_CPU0_PE3_OCP_RXN<10>")
	)
	(segment
		(start 387.863588 -138.33221)
		(end 390.667494 -138.33221)
		(width 0.1143)
		(layer "In11.Cu")
		(net "P3E_CPU0_PE3_OCP_RXN<10>")
	)
	(segment
		(start 305.630834 -99.831144)
		(end 305.920902 -100.121212)
		(width 0.0889)
		(layer "In11.Cu")
		(net "P3E_CPU0_PE3_OCP_RXN<10>")
	)
	(segment
		(start 356.741222 -125.424946)
		(end 359.328466 -126.733046)
		(width 0.1143)
		(layer "In11.Cu")
		(net "P3E_CPU0_PE3_OCP_RXN<10>")
	)
	(segment
		(start 311.559956 -102.908608)
		(end 317.950088 -109.29874)
		(width 0.1143)
		(layer "In11.Cu")
		(net "P3E_CPU0_PE3_OCP_RXN<10>")
	)
	(segment
		(start 339.7631 -122.902472)
		(end 341.824818 -123.327922)
		(width 0.1143)
		(layer "In11.Cu")
		(net "P3E_CPU0_PE3_OCP_RXN<10>")
	)
	(segment
		(start 302.164242 -97.2058)
		(end 302.159416 -97.214436)
		(width 0.0889)
		(layer "In11.Cu")
		(net "P3E_CPU0_PE3_OCP_RXN<10>")
	)
	(segment
		(start 334.378808 -122.902472)
		(end 339.7631 -122.902472)
		(width 0.1143)
		(layer "In11.Cu")
		(net "P3E_CPU0_PE3_OCP_RXN<10>")
	)
	(segment
		(start 302.209708 -97.892362)
		(end 302.412146 -98.0948)
		(width 0.0889)
		(layer "In11.Cu")
		(net "P3E_CPU0_PE3_OCP_RXN<10>")
	)
	(segment
		(start 371.684804 -131.811014)
		(end 373.206264 -132.818632)
		(width 0.1143)
		(layer "In11.Cu")
		(net "P3E_CPU0_PE3_OCP_RXN<10>")
	)
	(segment
		(start 301.794926 -93.642688)
		(end 301.827692 -93.642688)
		(width 0.0889)
		(layer "In11.Cu")
		(net "P3E_CPU0_PE3_OCP_RXN<10>")
	)
	(segment
		(start 445.464692 -119.99087)
		(end 445.807846 -119.922544)
		(width 0.1143)
		(layer "In11.Cu")
		(net "P3E_CPU0_PE3_OCP_RXN<10>")
	)
	(segment
		(start 321.322954 -109.29874)
		(end 325.69404 -113.669826)
		(width 0.1143)
		(layer "In11.Cu")
		(net "P3E_CPU0_PE3_OCP_RXN<10>")
	)
	(segment
		(start 399.565622 -138.367262)
		(end 405.295608 -138.367262)
		(width 0.1143)
		(layer "In11.Cu")
		(net "P3E_CPU0_PE3_OCP_RXN<10>")
	)
	(segment
		(start 354.317808 -123.182888)
		(end 355.989636 -124.31014)
		(width 0.1143)
		(layer "In11.Cu")
		(net "P3E_CPU0_PE3_OCP_RXN<10>")
	)
	(segment
		(start 373.206264 -132.818632)
		(end 375.1199 -133.20776)
		(width 0.1143)
		(layer "In11.Cu")
		(net "P3E_CPU0_PE3_OCP_RXN<10>")
	)
	(segment
		(start 298.378626 -94.042738)
		(end 298.378626 -93.704664)
		(width 0.0889)
		(layer "In11.Cu")
		(net "P3E_CPU0_PE3_OCP_RXN<10>")
	)
	(arc
		(start 302.153066 -96.234504)
		(mid 302.080268 -96.525267)
		(end 302.159416 -96.814386)
		(width 0.0889)
		(layer "In11.Cu")
		(net "P3E_CPU0_PE3_OCP_RXN<10>")
	)
	(arc
		(start 298.890436 -93.347286)
		(mid 299.032119 -93.203482)
		(end 299.22597 -93.147134)
		(width 0.0889)
		(layer "In11.Cu")
		(net "P3E_CPU0_PE3_OCP_RXN<10>")
	)
	(arc
		(start 299.748956 -92.851986)
		(mid 299.889035 -92.70925)
		(end 300.08068 -92.652088)
		(width 0.0889)
		(layer "In11.Cu")
		(net "P3E_CPU0_PE3_OCP_RXN<10>")
	)
	(arc
		(start 301.300896 -93.347286)
		(mid 301.509504 -93.559218)
		(end 301.794926 -93.642688)
		(width 0.0889)
		(layer "In11.Cu")
		(net "P3E_CPU0_PE3_OCP_RXN<10>")
	)
	(arc
		(start 302.159416 -94.242636)
		(mid 302.080194 -94.531754)
		(end 302.153066 -94.822518)
		(width 0.0889)
		(layer "In11.Cu")
		(net "P3E_CPU0_PE3_OCP_RXN<10>")
	)
	(arc
		(start 302.159416 -95.232982)
		(mid 302.080285 -95.528384)
		(end 302.159416 -95.823786)
		(width 0.0889)
		(layer "In11.Cu")
		(net "P3E_CPU0_PE3_OCP_RXN<10>")
	)
	(arc
		(start 302.159416 -94.833186)
		(mid 302.212915 -95.033084)
		(end 302.159416 -95.232982)
		(width 0.0889)
		(layer "In11.Cu")
		(net "P3E_CPU0_PE3_OCP_RXN<10>")
	)
	(arc
		(start 299.258736 -93.147134)
		(mid 299.541953 -93.062853)
		(end 299.748956 -92.851986)
		(width 0.0889)
		(layer "In11.Cu")
		(net "P3E_CPU0_PE3_OCP_RXN<10>")
	)
	(arc
		(start 300.965362 -93.147134)
		(mid 301.159212 -93.203484)
		(end 301.300896 -93.347286)
		(width 0.0889)
		(layer "In11.Cu")
		(net "P3E_CPU0_PE3_OCP_RXN<10>")
	)
	(arc
		(start 302.153066 -97.225104)
		(mid 302.080268 -97.515867)
		(end 302.159416 -97.804986)
		(width 0.0889)
		(layer "In11.Cu")
		(net "P3E_CPU0_PE3_OCP_RXN<10>")
	)
	(arc
		(start 300.110652 -92.652088)
		(mid 300.302294 -92.709254)
		(end 300.442376 -92.851986)
		(width 0.0889)
		(layer "In11.Cu")
		(net "P3E_CPU0_PE3_OCP_RXN<10>")
	)
	(arc
		(start 298.443904 -93.639386)
		(mid 298.702041 -93.546632)
		(end 298.890436 -93.347286)
		(width 0.0889)
		(layer "In11.Cu")
		(net "P3E_CPU0_PE3_OCP_RXN<10>")
	)
	(arc
		(start 302.159416 -95.823786)
		(mid 302.212886 -96.018849)
		(end 302.164242 -96.2152)
		(width 0.0889)
		(layer "In11.Cu")
		(net "P3E_CPU0_PE3_OCP_RXN<10>")
	)
	(arc
		(start 300.442376 -92.851986)
		(mid 300.64938 -93.06285)
		(end 300.932596 -93.147134)
		(width 0.0889)
		(layer "In11.Cu")
		(net "P3E_CPU0_PE3_OCP_RXN<10>")
	)
	(arc
		(start 301.827692 -93.642688)
		(mid 302.16061 -93.844679)
		(end 302.164242 -94.234)
		(width 0.0889)
		(layer "In11.Cu")
		(net "P3E_CPU0_PE3_OCP_RXN<10>")
	)
	(arc
		(start 302.159416 -96.814386)
		(mid 302.212886 -97.009449)
		(end 302.164242 -97.2058)
		(width 0.0889)
		(layer "In11.Cu")
		(net "P3E_CPU0_PE3_OCP_RXN<10>")
	)
	(segment
		(start 462.141062 -47.481998)
		(end 462.142078 -47.481998)
		(width 0.1143)
		(layer "F.Cu")
		(net "P3E_CPU0_PE3_OCP_RXN<0>")
	)
	(segment
		(start 462.044034 -44.83735)
		(end 462.377028 -44.83735)
		(width 0.1143)
		(layer "F.Cu")
		(net "P3E_CPU0_PE3_OCP_RXN<0>")
	)
	(segment
		(start 461.8482 -45.9867)
		(end 461.8482 -45.033184)
		(width 0.1143)
		(layer "F.Cu")
		(net "P3E_CPU0_PE3_OCP_RXN<0>")
	)
	(segment
		(start 292.65626 -100.976684)
		(end 293.22776 -100.976684)
		(width 0.1143)
		(layer "F.Cu")
		(net "P3E_CPU0_PE3_OCP_RXN<0>")
	)
	(segment
		(start 462.142078 -46.280578)
		(end 461.8482 -45.9867)
		(width 0.1143)
		(layer "F.Cu")
		(net "P3E_CPU0_PE3_OCP_RXN<0>")
	)
	(segment
		(start 462.142078 -47.481998)
		(end 462.142078 -46.280578)
		(width 0.1143)
		(layer "F.Cu")
		(net "P3E_CPU0_PE3_OCP_RXN<0>")
	)
	(segment
		(start 461.8482 -45.033184)
		(end 462.044034 -44.83735)
		(width 0.1143)
		(layer "F.Cu")
		(net "P3E_CPU0_PE3_OCP_RXN<0>")
	)
	(via
		(at 293.22776 -100.976684)
		(size 0.508)
		(drill 0.254)
		(layers "F.Cu" "B.Cu")
		(net "P3E_CPU0_PE3_OCP_RXN<0>")
	)
	(via
		(at 462.377028 -44.83735)
		(size 0.508)
		(drill 0.254)
		(layers "F.Cu" "B.Cu")
		(net "P3E_CPU0_PE3_OCP_RXN<0>")
	)
	(segment
		(start 464.430872 -47.02937)
		(end 465.7979 -48.396398)
		(width 0.1143)
		(layer "In4.Cu")
		(net "P3E_CPU0_PE3_OCP_RXN<0>")
	)
	(segment
		(start 385.83235 -50.2412)
		(end 381.1778 -50.2412)
		(width 0.1143)
		(layer "In4.Cu")
		(net "P3E_CPU0_PE3_OCP_RXN<0>")
	)
	(segment
		(start 348.681802 -61.239654)
		(end 347.254068 -61.517276)
		(width 0.1143)
		(layer "In4.Cu")
		(net "P3E_CPU0_PE3_OCP_RXN<0>")
	)
	(segment
		(start 367.5126 -53.6956)
		(end 364.287308 -53.6956)
		(width 0.1143)
		(layer "In4.Cu")
		(net "P3E_CPU0_PE3_OCP_RXN<0>")
	)
	(segment
		(start 375.526808 -49.736248)
		(end 375.155714 -50.107342)
		(width 0.1143)
		(layer "In4.Cu")
		(net "P3E_CPU0_PE3_OCP_RXN<0>")
	)
	(segment
		(start 403.39518 -52.92598)
		(end 402.828506 -53.492654)
		(width 0.1143)
		(layer "In4.Cu")
		(net "P3E_CPU0_PE3_OCP_RXN<0>")
	)
	(segment
		(start 408.971496 -55.9943)
		(end 408.275282 -55.298086)
		(width 0.1143)
		(layer "In4.Cu")
		(net "P3E_CPU0_PE3_OCP_RXN<0>")
	)
	(segment
		(start 325.16318 -71.824088)
		(end 319.943226 -84.425028)
		(width 0.1143)
		(layer "In4.Cu")
		(net "P3E_CPU0_PE3_OCP_RXN<0>")
	)
	(segment
		(start 462.377028 -44.83735)
		(end 462.002378 -44.83735)
		(width 0.1143)
		(layer "In4.Cu")
		(net "P3E_CPU0_PE3_OCP_RXN<0>")
	)
	(segment
		(start 351.485454 -61.235844)
		(end 349.949008 -61.536072)
		(width 0.1143)
		(layer "In4.Cu")
		(net "P3E_CPU0_PE3_OCP_RXN<0>")
	)
	(segment
		(start 418.967158 -55.3085)
		(end 414.684972 -55.3085)
		(width 0.1143)
		(layer "In4.Cu")
		(net "P3E_CPU0_PE3_OCP_RXN<0>")
	)
	(segment
		(start 436.741316 -52.499768)
		(end 428.397416 -52.499768)
		(width 0.1143)
		(layer "In4.Cu")
		(net "P3E_CPU0_PE3_OCP_RXN<0>")
	)
	(segment
		(start 461.888078 -44.95165)
		(end 461.888078 -45.524166)
		(width 0.1143)
		(layer "In4.Cu")
		(net "P3E_CPU0_PE3_OCP_RXN<0>")
	)
	(segment
		(start 392.27506 -53.492654)
		(end 390.758934 -51.976528)
		(width 0.1143)
		(layer "In4.Cu")
		(net "P3E_CPU0_PE3_OCP_RXN<0>")
	)
	(segment
		(start 426.808138 -54.089046)
		(end 424.822874 -54.089046)
		(width 0.1143)
		(layer "In4.Cu")
		(net "P3E_CPU0_PE3_OCP_RXN<0>")
	)
	(segment
		(start 300.113446 -98.595688)
		(end 300.08068 -98.595688)
		(width 0.0889)
		(layer "In4.Cu")
		(net "P3E_CPU0_PE3_OCP_RXN<0>")
	)
	(segment
		(start 410.001212 -55.9943)
		(end 408.971496 -55.9943)
		(width 0.1143)
		(layer "In4.Cu")
		(net "P3E_CPU0_PE3_OCP_RXN<0>")
	)
	(segment
		(start 346.008198 -61.227462)
		(end 344.383868 -61.543438)
		(width 0.1143)
		(layer "In4.Cu")
		(net "P3E_CPU0_PE3_OCP_RXN<0>")
	)
	(segment
		(start 461.888078 -45.524166)
		(end 463.393282 -47.02937)
		(width 0.1143)
		(layer "In4.Cu")
		(net "P3E_CPU0_PE3_OCP_RXN<0>")
	)
	(segment
		(start 294.104314 -101.072188)
		(end 294.104314 -101.071934)
		(width 0.0889)
		(layer "In4.Cu")
		(net "P3E_CPU0_PE3_OCP_RXN<0>")
	)
	(segment
		(start 402.828506 -53.492654)
		(end 392.27506 -53.492654)
		(width 0.1143)
		(layer "In4.Cu")
		(net "P3E_CPU0_PE3_OCP_RXN<0>")
	)
	(segment
		(start 300.975776 -98.100134)
		(end 300.94301 -98.100134)
		(width 0.0889)
		(layer "In4.Cu")
		(net "P3E_CPU0_PE3_OCP_RXN<0>")
	)
	(segment
		(start 297.176952 -101.266244)
		(end 297.17365 -101.272086)
		(width 0.0889)
		(layer "In4.Cu")
		(net "P3E_CPU0_PE3_OCP_RXN<0>")
	)
	(segment
		(start 293.604442 -100.976684)
		(end 293.22776 -100.976684)
		(width 0.0889)
		(layer "In4.Cu")
		(net "P3E_CPU0_PE3_OCP_RXN<0>")
	)
	(segment
		(start 297.541696 -101.071934)
		(end 297.520106 -101.071934)
		(width 0.0889)
		(layer "In4.Cu")
		(net "P3E_CPU0_PE3_OCP_RXN<0>")
	)
	(segment
		(start 420.356284 -54.696106)
		(end 419.579552 -54.696106)
		(width 0.1143)
		(layer "In4.Cu")
		(net "P3E_CPU0_PE3_OCP_RXN<0>")
	)
	(segment
		(start 354.215192 -61.247274)
		(end 352.77298 -61.536072)
		(width 0.1143)
		(layer "In4.Cu")
		(net "P3E_CPU0_PE3_OCP_RXN<0>")
	)
	(segment
		(start 294.945054 -101.567488)
		(end 294.9321 -101.567742)
		(width 0.0889)
		(layer "In4.Cu")
		(net "P3E_CPU0_PE3_OCP_RXN<0>")
	)
	(segment
		(start 404.9268 -52.92598)
		(end 403.39518 -52.92598)
		(width 0.1143)
		(layer "In4.Cu")
		(net "P3E_CPU0_PE3_OCP_RXN<0>")
	)
	(segment
		(start 352.77298 -61.536072)
		(end 351.485454 -61.235844)
		(width 0.1143)
		(layer "In4.Cu")
		(net "P3E_CPU0_PE3_OCP_RXN<0>")
	)
	(segment
		(start 298.400216 -100.576888)
		(end 298.360592 -100.576888)
		(width 0.0889)
		(layer "In4.Cu")
		(net "P3E_CPU0_PE3_OCP_RXN<0>")
	)
	(segment
		(start 349.949008 -61.536072)
		(end 348.681802 -61.239654)
		(width 0.1143)
		(layer "In4.Cu")
		(net "P3E_CPU0_PE3_OCP_RXN<0>")
	)
	(segment
		(start 296.674794 -101.567488)
		(end 296.646854 -101.567488)
		(width 0.0889)
		(layer "In4.Cu")
		(net "P3E_CPU0_PE3_OCP_RXN<0>")
	)
	(segment
		(start 319.943226 -84.425028)
		(end 307.830728 -96.537018)
		(width 0.1143)
		(layer "In4.Cu")
		(net "P3E_CPU0_PE3_OCP_RXN<0>")
	)
	(segment
		(start 463.393282 -47.02937)
		(end 464.430872 -47.02937)
		(width 0.1143)
		(layer "In4.Cu")
		(net "P3E_CPU0_PE3_OCP_RXN<0>")
	)
	(segment
		(start 419.579552 -54.696106)
		(end 418.967158 -55.3085)
		(width 0.1143)
		(layer "In4.Cu")
		(net "P3E_CPU0_PE3_OCP_RXN<0>")
	)
	(segment
		(start 428.397416 -52.499768)
		(end 426.808138 -54.089046)
		(width 0.1143)
		(layer "In4.Cu")
		(net "P3E_CPU0_PE3_OCP_RXN<0>")
	)
	(segment
		(start 370.81079 -51.9049)
		(end 369.3033 -51.9049)
		(width 0.1143)
		(layer "In4.Cu")
		(net "P3E_CPU0_PE3_OCP_RXN<0>")
	)
	(segment
		(start 372.608348 -50.107342)
		(end 370.81079 -51.9049)
		(width 0.1143)
		(layer "In4.Cu")
		(net "P3E_CPU0_PE3_OCP_RXN<0>")
	)
	(segment
		(start 305.68519 -97.132902)
		(end 305.035966 -97.19691)
		(width 0.0889)
		(layer "In4.Cu")
		(net "P3E_CPU0_PE3_OCP_RXN<0>")
	)
	(segment
		(start 464.9978 -52.2097)
		(end 437.031384 -52.2097)
		(width 0.1143)
		(layer "In4.Cu")
		(net "P3E_CPU0_PE3_OCP_RXN<0>")
	)
	(segment
		(start 337.72602 -62.292738)
		(end 334.46593 -61.535818)
		(width 0.1143)
		(layer "In4.Cu")
		(net "P3E_CPU0_PE3_OCP_RXN<0>")
	)
	(segment
		(start 307.354986 -96.537018)
		(end 307.332888 -96.537018)
		(width 0.0889)
		(layer "In4.Cu")
		(net "P3E_CPU0_PE3_OCP_RXN<0>")
	)
	(segment
		(start 360.03611 -55.470552)
		(end 356.809802 -60.312046)
		(width 0.1143)
		(layer "In4.Cu")
		(net "P3E_CPU0_PE3_OCP_RXN<0>")
	)
	(segment
		(start 299.2501 -100.081588)
		(end 299.22597 -100.081588)
		(width 0.0889)
		(layer "In4.Cu")
		(net "P3E_CPU0_PE3_OCP_RXN<0>")
	)
	(segment
		(start 347.254068 -61.517276)
		(end 346.008198 -61.227462)
		(width 0.1143)
		(layer "In4.Cu")
		(net "P3E_CPU0_PE3_OCP_RXN<0>")
	)
	(segment
		(start 465.7979 -48.396398)
		(end 465.7979 -51.4096)
		(width 0.1143)
		(layer "In4.Cu")
		(net "P3E_CPU0_PE3_OCP_RXN<0>")
	)
	(segment
		(start 380.672848 -49.736248)
		(end 375.526808 -49.736248)
		(width 0.1143)
		(layer "In4.Cu")
		(net "P3E_CPU0_PE3_OCP_RXN<0>")
	)
	(segment
		(start 306.076604 -96.871282)
		(end 305.68519 -97.132902)
		(width 0.0889)
		(layer "In4.Cu")
		(net "P3E_CPU0_PE3_OCP_RXN<0>")
	)
	(segment
		(start 390.758934 -51.976528)
		(end 387.567678 -51.976528)
		(width 0.1143)
		(layer "In4.Cu")
		(net "P3E_CPU0_PE3_OCP_RXN<0>")
	)
	(segment
		(start 408.275282 -55.298086)
		(end 407.298906 -55.298086)
		(width 0.1143)
		(layer "In4.Cu")
		(net "P3E_CPU0_PE3_OCP_RXN<0>")
	)
	(segment
		(start 307.282088 -96.486218)
		(end 307.006498 -96.486218)
		(width 0.0889)
		(layer "In4.Cu")
		(net "P3E_CPU0_PE3_OCP_RXN<0>")
	)
	(segment
		(start 307.830728 -96.537018)
		(end 307.354986 -96.537018)
		(width 0.1143)
		(layer "In4.Cu")
		(net "P3E_CPU0_PE3_OCP_RXN<0>")
	)
	(segment
		(start 465.7979 -51.4096)
		(end 464.9978 -52.2097)
		(width 0.1143)
		(layer "In4.Cu")
		(net "P3E_CPU0_PE3_OCP_RXN<0>")
	)
	(segment
		(start 305.035966 -97.19691)
		(end 304.596038 -97.109534)
		(width 0.0889)
		(layer "In4.Cu")
		(net "P3E_CPU0_PE3_OCP_RXN<0>")
	)
	(segment
		(start 424.822874 -54.089046)
		(end 423.792904 -55.119016)
		(width 0.1143)
		(layer "In4.Cu")
		(net "P3E_CPU0_PE3_OCP_RXN<0>")
	)
	(segment
		(start 364.287308 -53.6956)
		(end 361.60837 -54.425088)
		(width 0.1143)
		(layer "In4.Cu")
		(net "P3E_CPU0_PE3_OCP_RXN<0>")
	)
	(segment
		(start 361.60837 -54.425088)
		(end 360.03611 -55.470552)
		(width 0.1143)
		(layer "In4.Cu")
		(net "P3E_CPU0_PE3_OCP_RXN<0>")
	)
	(segment
		(start 414.684972 -55.3085)
		(end 414.202372 -54.8259)
		(width 0.1143)
		(layer "In4.Cu")
		(net "P3E_CPU0_PE3_OCP_RXN<0>")
	)
	(segment
		(start 407.298906 -55.298086)
		(end 404.9268 -52.92598)
		(width 0.1143)
		(layer "In4.Cu")
		(net "P3E_CPU0_PE3_OCP_RXN<0>")
	)
	(segment
		(start 344.383868 -61.543438)
		(end 343.110058 -61.245496)
		(width 0.1143)
		(layer "In4.Cu")
		(net "P3E_CPU0_PE3_OCP_RXN<0>")
	)
	(segment
		(start 414.202372 -54.8259)
		(end 411.169612 -54.8259)
		(width 0.1143)
		(layer "In4.Cu")
		(net "P3E_CPU0_PE3_OCP_RXN<0>")
	)
	(segment
		(start 423.792904 -55.119016)
		(end 420.779194 -55.119016)
		(width 0.1143)
		(layer "In4.Cu")
		(net "P3E_CPU0_PE3_OCP_RXN<0>")
	)
	(segment
		(start 369.3033 -51.9049)
		(end 367.5126 -53.6956)
		(width 0.1143)
		(layer "In4.Cu")
		(net "P3E_CPU0_PE3_OCP_RXN<0>")
	)
	(segment
		(start 375.155714 -50.107342)
		(end 372.608348 -50.107342)
		(width 0.1143)
		(layer "In4.Cu")
		(net "P3E_CPU0_PE3_OCP_RXN<0>")
	)
	(segment
		(start 307.332888 -96.537018)
		(end 307.282088 -96.486218)
		(width 0.0889)
		(layer "In4.Cu")
		(net "P3E_CPU0_PE3_OCP_RXN<0>")
	)
	(segment
		(start 411.169612 -54.8259)
		(end 410.001212 -55.9943)
		(width 0.1143)
		(layer "In4.Cu")
		(net "P3E_CPU0_PE3_OCP_RXN<0>")
	)
	(segment
		(start 462.002378 -44.83735)
		(end 461.888078 -44.95165)
		(width 0.1143)
		(layer "In4.Cu")
		(net "P3E_CPU0_PE3_OCP_RXN<0>")
	)
	(segment
		(start 387.567678 -51.976528)
		(end 385.83235 -50.2412)
		(width 0.1143)
		(layer "In4.Cu")
		(net "P3E_CPU0_PE3_OCP_RXN<0>")
	)
	(segment
		(start 354.908104 -61.385704)
		(end 354.215192 -61.247274)
		(width 0.1143)
		(layer "In4.Cu")
		(net "P3E_CPU0_PE3_OCP_RXN<0>")
	)
	(segment
		(start 299.748956 -99.195636)
		(end 299.755306 -99.206304)
		(width 0.0889)
		(layer "In4.Cu")
		(net "P3E_CPU0_PE3_OCP_RXN<0>")
	)
	(segment
		(start 420.779194 -55.119016)
		(end 420.356284 -54.696106)
		(width 0.1143)
		(layer "In4.Cu")
		(net "P3E_CPU0_PE3_OCP_RXN<0>")
	)
	(segment
		(start 381.1778 -50.2412)
		(end 380.672848 -49.736248)
		(width 0.1143)
		(layer "In4.Cu")
		(net "P3E_CPU0_PE3_OCP_RXN<0>")
	)
	(segment
		(start 307.006498 -96.486218)
		(end 306.076604 -96.871282)
		(width 0.0889)
		(layer "In4.Cu")
		(net "P3E_CPU0_PE3_OCP_RXN<0>")
	)
	(segment
		(start 333.143606 -61.787786)
		(end 331.201268 -63.045594)
		(width 0.1143)
		(layer "In4.Cu")
		(net "P3E_CPU0_PE3_OCP_RXN<0>")
	)
	(segment
		(start 299.74413 -99.187)
		(end 299.748956 -99.195636)
		(width 0.0889)
		(layer "In4.Cu")
		(net "P3E_CPU0_PE3_OCP_RXN<0>")
	)
	(segment
		(start 304.596038 -97.109534)
		(end 304.37709 -97.109534)
		(width 0.0889)
		(layer "In4.Cu")
		(net "P3E_CPU0_PE3_OCP_RXN<0>")
	)
	(segment
		(start 301.830486 -97.605088)
		(end 301.79772 -97.605088)
		(width 0.0889)
		(layer "In4.Cu")
		(net "P3E_CPU0_PE3_OCP_RXN<0>")
	)
	(segment
		(start 437.031384 -52.2097)
		(end 436.741316 -52.499768)
		(width 0.1143)
		(layer "In4.Cu")
		(net "P3E_CPU0_PE3_OCP_RXN<0>")
	)
	(segment
		(start 334.46593 -61.535818)
		(end 333.143606 -61.787786)
		(width 0.1143)
		(layer "In4.Cu")
		(net "P3E_CPU0_PE3_OCP_RXN<0>")
	)
	(segment
		(start 331.201268 -63.045594)
		(end 325.16318 -71.824088)
		(width 0.1143)
		(layer "In4.Cu")
		(net "P3E_CPU0_PE3_OCP_RXN<0>")
	)
	(segment
		(start 355.323902 -61.3029)
		(end 354.908104 -61.385704)
		(width 0.1143)
		(layer "In4.Cu")
		(net "P3E_CPU0_PE3_OCP_RXN<0>")
	)
	(segment
		(start 356.809802 -60.312046)
		(end 355.323902 -61.3029)
		(width 0.1143)
		(layer "In4.Cu")
		(net "P3E_CPU0_PE3_OCP_RXN<0>")
	)
	(segment
		(start 343.110058 -61.245496)
		(end 337.72602 -62.292738)
		(width 0.1143)
		(layer "In4.Cu")
		(net "P3E_CPU0_PE3_OCP_RXN<0>")
	)
	(arc
		(start 300.607476 -98.300286)
		(mid 300.398868 -98.512218)
		(end 300.113446 -98.595688)
		(width 0.0889)
		(layer "In4.Cu")
		(net "P3E_CPU0_PE3_OCP_RXN<0>")
	)
	(arc
		(start 298.360592 -100.576888)
		(mid 298.170663 -100.634758)
		(end 298.031916 -100.776786)
		(width 0.0889)
		(layer "In4.Cu")
		(net "P3E_CPU0_PE3_OCP_RXN<0>")
	)
	(arc
		(start 298.031916 -100.776786)
		(mid 297.824912 -100.98765)
		(end 297.541696 -101.071934)
		(width 0.0889)
		(layer "In4.Cu")
		(net "P3E_CPU0_PE3_OCP_RXN<0>")
	)
	(arc
		(start 297.520106 -101.071934)
		(mid 297.322945 -101.123893)
		(end 297.176952 -101.266244)
		(width 0.0889)
		(layer "In4.Cu")
		(net "P3E_CPU0_PE3_OCP_RXN<0>")
	)
	(arc
		(start 294.064182 -101.071934)
		(mid 293.960221 -101.058792)
		(end 293.86022 -101.027484)
		(width 0.0889)
		(layer "In4.Cu")
		(net "P3E_CPU0_PE3_OCP_RXN<0>")
	)
	(arc
		(start 303.017936 -97.309686)
		(mid 302.671226 -97.109375)
		(end 302.324516 -97.309686)
		(width 0.0889)
		(layer "In4.Cu")
		(net "P3E_CPU0_PE3_OCP_RXN<0>")
	)
	(arc
		(start 296.646854 -101.567488)
		(mid 296.455212 -101.624654)
		(end 296.31513 -101.767386)
		(width 0.0889)
		(layer "In4.Cu")
		(net "P3E_CPU0_PE3_OCP_RXN<0>")
	)
	(arc
		(start 302.324516 -97.309686)
		(mid 302.115908 -97.521618)
		(end 301.830486 -97.605088)
		(width 0.0889)
		(layer "In4.Cu")
		(net "P3E_CPU0_PE3_OCP_RXN<0>")
	)
	(arc
		(start 297.17365 -101.272086)
		(mid 296.962937 -101.485165)
		(end 296.674794 -101.567488)
		(width 0.0889)
		(layer "In4.Cu")
		(net "P3E_CPU0_PE3_OCP_RXN<0>")
	)
	(arc
		(start 295.288208 -101.761798)
		(mid 295.142242 -101.619399)
		(end 294.945054 -101.567488)
		(width 0.0889)
		(layer "In4.Cu")
		(net "P3E_CPU0_PE3_OCP_RXN<0>")
	)
	(arc
		(start 294.43299 -101.272086)
		(mid 294.294246 -101.130053)
		(end 294.104314 -101.072188)
		(width 0.0889)
		(layer "In4.Cu")
		(net "P3E_CPU0_PE3_OCP_RXN<0>")
	)
	(arc
		(start 301.79772 -97.605088)
		(mid 301.606078 -97.662254)
		(end 301.465996 -97.804986)
		(width 0.0889)
		(layer "In4.Cu")
		(net "P3E_CPU0_PE3_OCP_RXN<0>")
	)
	(arc
		(start 300.94301 -98.100134)
		(mid 300.74916 -98.156484)
		(end 300.607476 -98.300286)
		(width 0.0889)
		(layer "In4.Cu")
		(net "P3E_CPU0_PE3_OCP_RXN<0>")
	)
	(arc
		(start 299.755306 -99.206304)
		(mid 299.749129 -99.786236)
		(end 299.2501 -100.081588)
		(width 0.0889)
		(layer "In4.Cu")
		(net "P3E_CPU0_PE3_OCP_RXN<0>")
	)
	(arc
		(start 304.37709 -97.109534)
		(mid 304.18324 -97.165884)
		(end 304.041556 -97.309686)
		(width 0.0889)
		(layer "In4.Cu")
		(net "P3E_CPU0_PE3_OCP_RXN<0>")
	)
	(arc
		(start 301.465996 -97.804986)
		(mid 301.258992 -98.01585)
		(end 300.975776 -98.100134)
		(width 0.0889)
		(layer "In4.Cu")
		(net "P3E_CPU0_PE3_OCP_RXN<0>")
	)
	(arc
		(start 294.9321 -101.567742)
		(mid 294.643806 -101.485334)
		(end 294.43299 -101.272086)
		(width 0.0889)
		(layer "In4.Cu")
		(net "P3E_CPU0_PE3_OCP_RXN<0>")
	)
	(arc
		(start 296.31513 -101.767386)
		(mid 295.800075 -102.062917)
		(end 295.288208 -101.761798)
		(width 0.0889)
		(layer "In4.Cu")
		(net "P3E_CPU0_PE3_OCP_RXN<0>")
	)
	(arc
		(start 299.22597 -100.081588)
		(mid 299.03212 -100.137938)
		(end 298.890436 -100.28174)
		(width 0.0889)
		(layer "In4.Cu")
		(net "P3E_CPU0_PE3_OCP_RXN<0>")
	)
	(arc
		(start 304.041556 -97.309686)
		(mid 303.529746 -97.605353)
		(end 303.017936 -97.309686)
		(width 0.0889)
		(layer "In4.Cu")
		(net "P3E_CPU0_PE3_OCP_RXN<0>")
	)
	(arc
		(start 294.104314 -101.071934)
		(mid 294.084248 -101.071431)
		(end 294.064182 -101.071934)
		(width 0.0889)
		(layer "In4.Cu")
		(net "P3E_CPU0_PE3_OCP_RXN<0>")
	)
	(arc
		(start 293.86022 -101.027484)
		(mid 293.734827 -100.989519)
		(end 293.604442 -100.976684)
		(width 0.0889)
		(layer "In4.Cu")
		(net "P3E_CPU0_PE3_OCP_RXN<0>")
	)
	(arc
		(start 298.890436 -100.28174)
		(mid 298.683432 -100.492604)
		(end 298.400216 -100.576888)
		(width 0.0889)
		(layer "In4.Cu")
		(net "P3E_CPU0_PE3_OCP_RXN<0>")
	)
	(arc
		(start 300.08068 -98.595688)
		(mid 299.747762 -98.797679)
		(end 299.74413 -99.187)
		(width 0.0889)
		(layer "In4.Cu")
		(net "P3E_CPU0_PE3_OCP_RXN<0>")
	)
	(segment
		(start 359.920286 -78.410562)
		(end 359.91927 -78.248002)
		(width 0.1143)
		(layer "F.Cu")
		(net "P3E_CPU0_PE1_SS_TXP<7>")
	)
	(segment
		(start 340.042246 -92.57538)
		(end 341.729568 -92.219526)
		(width 0.1143)
		(layer "F.Cu")
		(net "P3E_CPU0_PE1_SS_TXP<7>")
	)
	(segment
		(start 360.032554 -78.133194)
		(end 360.510582 -78.129892)
		(width 0.1143)
		(layer "F.Cu")
		(net "P3E_CPU0_PE1_SS_TXP<7>")
	)
	(segment
		(start 327.600056 -98.84918)
		(end 328.82967 -95.597726)
		(width 0.1143)
		(layer "F.Cu")
		(net "P3E_CPU0_PE1_SS_TXP<7>")
	)
	(segment
		(start 328.82967 -95.597726)
		(end 332.286864 -93.2942)
		(width 0.1143)
		(layer "F.Cu")
		(net "P3E_CPU0_PE1_SS_TXP<7>")
	)
	(segment
		(start 332.286864 -93.2942)
		(end 337.404202 -92.047822)
		(width 0.1143)
		(layer "F.Cu")
		(net "P3E_CPU0_PE1_SS_TXP<7>")
	)
	(segment
		(start 344.579956 -90.677238)
		(end 348.461838 -91.454478)
		(width 0.1143)
		(layer "F.Cu")
		(net "P3E_CPU0_PE1_SS_TXP<7>")
	)
	(segment
		(start 343.81567 -90.829892)
		(end 344.579956 -90.677238)
		(width 0.1143)
		(layer "F.Cu")
		(net "P3E_CPU0_PE1_SS_TXP<7>")
	)
	(segment
		(start 359.173018 -82.31505)
		(end 359.920286 -81.567782)
		(width 0.1143)
		(layer "F.Cu")
		(net "P3E_CPU0_PE1_SS_TXP<7>")
	)
	(segment
		(start 359.91927 -78.248002)
		(end 360.032554 -78.133194)
		(width 0.1143)
		(layer "F.Cu")
		(net "P3E_CPU0_PE1_SS_TXP<7>")
	)
	(segment
		(start 308.895496 -98.154998)
		(end 308.873398 -98.154998)
		(width 0.0889)
		(layer "F.Cu")
		(net "P3E_CPU0_PE1_SS_TXP<7>")
	)
	(segment
		(start 327.318878 -99.5934)
		(end 327.010522 -100.408486)
		(width 0.1143)
		(layer "F.Cu")
		(net "P3E_CPU0_PE1_SS_TXP<7>")
	)
	(segment
		(start 327.010522 -100.408486)
		(end 320.69913 -104.96677)
		(width 0.1143)
		(layer "F.Cu")
		(net "P3E_CPU0_PE1_SS_TXP<7>")
	)
	(segment
		(start 327.318878 -99.5934)
		(end 327.600056 -98.84918)
		(width 0.1143)
		(layer "F.Cu")
		(net "P3E_CPU0_PE1_SS_TXP<7>")
	)
	(segment
		(start 352.064574 -90.735404)
		(end 354.522786 -91.227402)
		(width 0.1143)
		(layer "F.Cu")
		(net "P3E_CPU0_PE1_SS_TXP<7>")
	)
	(segment
		(start 308.365906 -98.129598)
		(end 307.841396 -97.605088)
		(width 0.0889)
		(layer "F.Cu")
		(net "P3E_CPU0_PE1_SS_TXP<7>")
	)
	(segment
		(start 356.782116 -89.324942)
		(end 356.782116 -88.533732)
		(width 0.1143)
		(layer "F.Cu")
		(net "P3E_CPU0_PE1_SS_TXP<7>")
	)
	(segment
		(start 356.782116 -88.533732)
		(end 359.173018 -86.14283)
		(width 0.1143)
		(layer "F.Cu")
		(net "P3E_CPU0_PE1_SS_TXP<7>")
	)
	(segment
		(start 337.404202 -92.047822)
		(end 340.042246 -92.57538)
		(width 0.1143)
		(layer "F.Cu")
		(net "P3E_CPU0_PE1_SS_TXP<7>")
	)
	(segment
		(start 320.69913 -104.96677)
		(end 317.354204 -105.710228)
		(width 0.1143)
		(layer "F.Cu")
		(net "P3E_CPU0_PE1_SS_TXP<7>")
	)
	(segment
		(start 354.522786 -91.227402)
		(end 356.309422 -90.033856)
		(width 0.1143)
		(layer "F.Cu")
		(net "P3E_CPU0_PE1_SS_TXP<7>")
	)
	(segment
		(start 317.354204 -105.710228)
		(end 315.176408 -105.14076)
		(width 0.1143)
		(layer "F.Cu")
		(net "P3E_CPU0_PE1_SS_TXP<7>")
	)
	(segment
		(start 348.461838 -91.454478)
		(end 352.064574 -90.735404)
		(width 0.1143)
		(layer "F.Cu")
		(net "P3E_CPU0_PE1_SS_TXP<7>")
	)
	(segment
		(start 315.176408 -105.14076)
		(end 313.119262 -103.662734)
		(width 0.1143)
		(layer "F.Cu")
		(net "P3E_CPU0_PE1_SS_TXP<7>")
	)
	(segment
		(start 310.67121 -98.640138)
		(end 309.56631 -98.154998)
		(width 0.1143)
		(layer "F.Cu")
		(net "P3E_CPU0_PE1_SS_TXP<7>")
	)
	(segment
		(start 359.920286 -81.567782)
		(end 359.920286 -78.410562)
		(width 0.1143)
		(layer "F.Cu")
		(net "P3E_CPU0_PE1_SS_TXP<7>")
	)
	(segment
		(start 307.841396 -97.605088)
		(end 306.37861 -97.605088)
		(width 0.0889)
		(layer "F.Cu")
		(net "P3E_CPU0_PE1_SS_TXP<7>")
	)
	(segment
		(start 308.847998 -98.129598)
		(end 308.365906 -98.129598)
		(width 0.0889)
		(layer "F.Cu")
		(net "P3E_CPU0_PE1_SS_TXP<7>")
	)
	(segment
		(start 356.309422 -90.033856)
		(end 356.782116 -89.324942)
		(width 0.1143)
		(layer "F.Cu")
		(net "P3E_CPU0_PE1_SS_TXP<7>")
	)
	(segment
		(start 359.173018 -86.14283)
		(end 359.173018 -82.31505)
		(width 0.1143)
		(layer "F.Cu")
		(net "P3E_CPU0_PE1_SS_TXP<7>")
	)
	(segment
		(start 341.729568 -92.219526)
		(end 343.81567 -90.829892)
		(width 0.1143)
		(layer "F.Cu")
		(net "P3E_CPU0_PE1_SS_TXP<7>")
	)
	(segment
		(start 308.873398 -98.154998)
		(end 308.847998 -98.129598)
		(width 0.0889)
		(layer "F.Cu")
		(net "P3E_CPU0_PE1_SS_TXP<7>")
	)
	(segment
		(start 309.56631 -98.154998)
		(end 308.895496 -98.154998)
		(width 0.1143)
		(layer "F.Cu")
		(net "P3E_CPU0_PE1_SS_TXP<7>")
	)
	(segment
		(start 313.119262 -103.662734)
		(end 310.67121 -98.640138)
		(width 0.1143)
		(layer "F.Cu")
		(net "P3E_CPU0_PE1_SS_TXP<7>")
	)
	(via
		(at 327.318878 -99.5934)
		(size 0.508)
		(drill 0.254)
		(layers "F.Cu" "B.Cu")
		(net "P3E_CPU0_PE1_SS_TXP<7>")
	)
	(via
		(at 360.510582 -78.129892)
		(size 0.508)
		(drill 0.254)
		(layers "F.Cu" "B.Cu")
		(net "P3E_CPU0_PE1_SS_TXP<7>")
	)
	(arc
		(start 305.880516 -97.309686)
		(mid 305.739217 -97.166322)
		(end 305.545998 -97.109788)
		(width 0.0889)
		(layer "F.Cu")
		(net "P3E_CPU0_PE1_SS_TXP<7>")
	)
	(arc
		(start 305.272948 -97.206562)
		(mid 305.251729 -97.488638)
		(end 305.533806 -97.509584)
		(width 0.0889)
		(layer "F.Cu")
		(net "P3E_CPU0_PE1_SS_TXP<7>")
	)
	(arc
		(start 305.545998 -97.109788)
		(mid 305.400401 -97.132588)
		(end 305.272948 -97.206562)
		(width 0.0889)
		(layer "F.Cu")
		(net "P3E_CPU0_PE1_SS_TXP<7>")
	)
	(arc
		(start 306.37861 -97.605088)
		(mid 306.090923 -97.522567)
		(end 305.880516 -97.309686)
		(width 0.0889)
		(layer "F.Cu")
		(net "P3E_CPU0_PE1_SS_TXP<7>")
	)
	(segment
		(start 359.84688 -77.923136)
		(end 360.303826 -77.923136)
		(width 0.1143)
		(layer "B.Cu")
		(net "P3E_CPU0_PE1_SS_TXP<7>")
	)
	(segment
		(start 360.303826 -77.923136)
		(end 360.510582 -78.129892)
		(width 0.1143)
		(layer "B.Cu")
		(net "P3E_CPU0_PE1_SS_TXP<7>")
	)
	(segment
		(start 327.68667 -95.1738)
		(end 327.68667 -95.174054)
		(width 0.1143)
		(layer "F.Cu")
		(net "P3E_CPU0_PE1_SS_TXP<6>")
	)
	(segment
		(start 334.077056 -90.838528)
		(end 332.753716 -91.117928)
		(width 0.1143)
		(layer "F.Cu")
		(net "P3E_CPU0_PE1_SS_TXP<6>")
	)
	(segment
		(start 356.834948 -80.665574)
		(end 356.949248 -80.779874)
		(width 0.1143)
		(layer "F.Cu")
		(net "P3E_CPU0_PE1_SS_TXP<6>")
	)
	(segment
		(start 356.834948 -78.13802)
		(end 356.949248 -78.25232)
		(width 0.1143)
		(layer "F.Cu")
		(net "P3E_CPU0_PE1_SS_TXP<6>")
	)
	(segment
		(start 328.028808 -94.269814)
		(end 327.68667 -95.1738)
		(width 0.1143)
		(layer "F.Cu")
		(net "P3E_CPU0_PE1_SS_TXP<6>")
	)
	(segment
		(start 327.68667 -95.174054)
		(end 326.371458 -98.64852)
		(width 0.1143)
		(layer "F.Cu")
		(net "P3E_CPU0_PE1_SS_TXP<6>")
	)
	(segment
		(start 355.686868 -86.777322)
		(end 355.619558 -87.113618)
		(width 0.1143)
		(layer "F.Cu")
		(net "P3E_CPU0_PE1_SS_TXP<6>")
	)
	(segment
		(start 355.866446 -85.880702)
		(end 355.799136 -86.216998)
		(width 0.1143)
		(layer "F.Cu")
		(net "P3E_CPU0_PE1_SS_TXP<6>")
	)
	(segment
		(start 355.619558 -87.113618)
		(end 355.484938 -87.203026)
		(width 0.1143)
		(layer "F.Cu")
		(net "P3E_CPU0_PE1_SS_TXP<6>")
	)
	(segment
		(start 356.329996 -85.417406)
		(end 355.866446 -85.880702)
		(width 0.1143)
		(layer "F.Cu")
		(net "P3E_CPU0_PE1_SS_TXP<6>")
	)
	(segment
		(start 355.664516 -86.30666)
		(end 355.597206 -86.642702)
		(width 0.1143)
		(layer "F.Cu")
		(net "P3E_CPU0_PE1_SS_TXP<6>")
	)
	(segment
		(start 320.11366 -103.839518)
		(end 317.40602 -104.439466)
		(width 0.1143)
		(layer "F.Cu")
		(net "P3E_CPU0_PE1_SS_TXP<6>")
	)
	(segment
		(start 311.58815 -97.66046)
		(end 309.932578 -96.933766)
		(width 0.1143)
		(layer "F.Cu")
		(net "P3E_CPU0_PE1_SS_TXP<6>")
	)
	(segment
		(start 317.40602 -104.439466)
		(end 315.63056 -103.969566)
		(width 0.1143)
		(layer "F.Cu")
		(net "P3E_CPU0_PE1_SS_TXP<6>")
	)
	(segment
		(start 307.419756 -96.29394)
		(end 307.140356 -96.29394)
		(width 0.0889)
		(layer "F.Cu")
		(net "P3E_CPU0_PE1_SS_TXP<6>")
	)
	(segment
		(start 308.81193 -96.933766)
		(end 308.789832 -96.933766)
		(width 0.0889)
		(layer "F.Cu")
		(net "P3E_CPU0_PE1_SS_TXP<6>")
	)
	(segment
		(start 308.764432 -96.959166)
		(end 308.364382 -96.959166)
		(width 0.0889)
		(layer "F.Cu")
		(net "P3E_CPU0_PE1_SS_TXP<6>")
	)
	(segment
		(start 355.198426 -89.215722)
		(end 354.169472 -89.9033)
		(width 0.1143)
		(layer "F.Cu")
		(net "P3E_CPU0_PE1_SS_TXP<6>")
	)
	(segment
		(start 307.518816 -96.393)
		(end 307.419756 -96.29394)
		(width 0.0889)
		(layer "F.Cu")
		(net "P3E_CPU0_PE1_SS_TXP<6>")
	)
	(segment
		(start 306.640738 -96.393)
		(end 306.60975 -96.423988)
		(width 0.0889)
		(layer "F.Cu")
		(net "P3E_CPU0_PE1_SS_TXP<6>")
	)
	(segment
		(start 356.949248 -80.208374)
		(end 356.834948 -80.322674)
		(width 0.1143)
		(layer "F.Cu")
		(net "P3E_CPU0_PE1_SS_TXP<6>")
	)
	(segment
		(start 344.511122 -89.315036)
		(end 342.783922 -89.66073)
		(width 0.1143)
		(layer "F.Cu")
		(net "P3E_CPU0_PE1_SS_TXP<6>")
	)
	(segment
		(start 355.484938 -87.203026)
		(end 355.417628 -87.539322)
		(width 0.1143)
		(layer "F.Cu")
		(net "P3E_CPU0_PE1_SS_TXP<6>")
	)
	(segment
		(start 306.105052 -96.189546)
		(end 306.392326 -96.023938)
		(width 0.0889)
		(layer "F.Cu")
		(net "P3E_CPU0_PE1_SS_TXP<6>")
	)
	(segment
		(start 355.597206 -86.642702)
		(end 355.686868 -86.777322)
		(width 0.1143)
		(layer "F.Cu")
		(net "P3E_CPU0_PE1_SS_TXP<6>")
	)
	(segment
		(start 307.041296 -96.393)
		(end 306.640738 -96.393)
		(width 0.0889)
		(layer "F.Cu")
		(net "P3E_CPU0_PE1_SS_TXP<6>")
	)
	(segment
		(start 356.949248 -78.25232)
		(end 356.949248 -79.293974)
		(width 0.1143)
		(layer "F.Cu")
		(net "P3E_CPU0_PE1_SS_TXP<6>")
	)
	(segment
		(start 335.659476 -91.155012)
		(end 334.077056 -90.838528)
		(width 0.1143)
		(layer "F.Cu")
		(net "P3E_CPU0_PE1_SS_TXP<6>")
	)
	(segment
		(start 308.364382 -96.959166)
		(end 307.798216 -96.393)
		(width 0.0889)
		(layer "F.Cu")
		(net "P3E_CPU0_PE1_SS_TXP<6>")
	)
	(segment
		(start 332.753716 -91.117928)
		(end 328.028808 -94.269814)
		(width 0.1143)
		(layer "F.Cu")
		(net "P3E_CPU0_PE1_SS_TXP<6>")
	)
	(segment
		(start 356.834948 -79.751174)
		(end 356.949248 -79.865474)
		(width 0.1143)
		(layer "F.Cu")
		(net "P3E_CPU0_PE1_SS_TXP<6>")
	)
	(segment
		(start 323.874384 -101.121464)
		(end 320.11366 -103.839518)
		(width 0.1143)
		(layer "F.Cu")
		(net "P3E_CPU0_PE1_SS_TXP<6>")
	)
	(segment
		(start 356.834948 -80.322674)
		(end 356.834948 -80.665574)
		(width 0.1143)
		(layer "F.Cu")
		(net "P3E_CPU0_PE1_SS_TXP<6>")
	)
	(segment
		(start 341.479886 -90.530172)
		(end 338.805012 -91.06535)
		(width 0.1143)
		(layer "F.Cu")
		(net "P3E_CPU0_PE1_SS_TXP<6>")
	)
	(segment
		(start 352.092006 -89.487756)
		(end 348.72803 -90.159078)
		(width 0.1143)
		(layer "F.Cu")
		(net "P3E_CPU0_PE1_SS_TXP<6>")
	)
	(segment
		(start 307.140356 -96.29394)
		(end 307.041296 -96.393)
		(width 0.0889)
		(layer "F.Cu")
		(net "P3E_CPU0_PE1_SS_TXP<6>")
	)
	(segment
		(start 337.408266 -90.786458)
		(end 335.659476 -91.155012)
		(width 0.1143)
		(layer "F.Cu")
		(net "P3E_CPU0_PE1_SS_TXP<6>")
	)
	(segment
		(start 356.834948 -79.408274)
		(end 356.834948 -79.751174)
		(width 0.1143)
		(layer "F.Cu")
		(net "P3E_CPU0_PE1_SS_TXP<6>")
	)
	(segment
		(start 306.081938 -96.27616)
		(end 306.105052 -96.189546)
		(width 0.0889)
		(layer "F.Cu")
		(net "P3E_CPU0_PE1_SS_TXP<6>")
	)
	(segment
		(start 355.417628 -87.539322)
		(end 355.50729 -87.673942)
		(width 0.1143)
		(layer "F.Cu")
		(net "P3E_CPU0_PE1_SS_TXP<6>")
	)
	(segment
		(start 338.805012 -91.06535)
		(end 337.408266 -90.786458)
		(width 0.1143)
		(layer "F.Cu")
		(net "P3E_CPU0_PE1_SS_TXP<6>")
	)
	(segment
		(start 326.023478 -99.568254)
		(end 323.874384 -101.121464)
		(width 0.1143)
		(layer "F.Cu")
		(net "P3E_CPU0_PE1_SS_TXP<6>")
	)
	(segment
		(start 326.371458 -98.64852)
		(end 326.023478 -99.568254)
		(width 0.1143)
		(layer "F.Cu")
		(net "P3E_CPU0_PE1_SS_TXP<6>")
	)
	(segment
		(start 309.932578 -96.933766)
		(end 308.81193 -96.933766)
		(width 0.1143)
		(layer "F.Cu")
		(net "P3E_CPU0_PE1_SS_TXP<6>")
	)
	(segment
		(start 356.949248 -80.779874)
		(end 356.949248 -81.891124)
		(width 0.1143)
		(layer "F.Cu")
		(net "P3E_CPU0_PE1_SS_TXP<6>")
	)
	(segment
		(start 356.371398 -78.13802)
		(end 356.834948 -78.13802)
		(width 0.1143)
		(layer "F.Cu")
		(net "P3E_CPU0_PE1_SS_TXP<6>")
	)
	(segment
		(start 314.141612 -102.89921)
		(end 311.58815 -97.66046)
		(width 0.1143)
		(layer "F.Cu")
		(net "P3E_CPU0_PE1_SS_TXP<6>")
	)
	(segment
		(start 356.329996 -82.510376)
		(end 356.329996 -85.417406)
		(width 0.1143)
		(layer "F.Cu")
		(net "P3E_CPU0_PE1_SS_TXP<6>")
	)
	(segment
		(start 356.949248 -81.891124)
		(end 356.329996 -82.510376)
		(width 0.1143)
		(layer "F.Cu")
		(net "P3E_CPU0_PE1_SS_TXP<6>")
	)
	(segment
		(start 342.783922 -89.66073)
		(end 341.479886 -90.530172)
		(width 0.1143)
		(layer "F.Cu")
		(net "P3E_CPU0_PE1_SS_TXP<6>")
	)
	(segment
		(start 307.798216 -96.393)
		(end 307.518816 -96.393)
		(width 0.0889)
		(layer "F.Cu")
		(net "P3E_CPU0_PE1_SS_TXP<6>")
	)
	(segment
		(start 356.949248 -79.865474)
		(end 356.949248 -80.208374)
		(width 0.1143)
		(layer "F.Cu")
		(net "P3E_CPU0_PE1_SS_TXP<6>")
	)
	(segment
		(start 355.799136 -86.216998)
		(end 355.664516 -86.30666)
		(width 0.1143)
		(layer "F.Cu")
		(net "P3E_CPU0_PE1_SS_TXP<6>")
	)
	(segment
		(start 355.50729 -87.673942)
		(end 355.198426 -89.215722)
		(width 0.1143)
		(layer "F.Cu")
		(net "P3E_CPU0_PE1_SS_TXP<6>")
	)
	(segment
		(start 348.72803 -90.159078)
		(end 344.511122 -89.315036)
		(width 0.1143)
		(layer "F.Cu")
		(net "P3E_CPU0_PE1_SS_TXP<6>")
	)
	(segment
		(start 308.789832 -96.933766)
		(end 308.764432 -96.959166)
		(width 0.0889)
		(layer "F.Cu")
		(net "P3E_CPU0_PE1_SS_TXP<6>")
	)
	(segment
		(start 356.949248 -79.293974)
		(end 356.834948 -79.408274)
		(width 0.1143)
		(layer "F.Cu")
		(net "P3E_CPU0_PE1_SS_TXP<6>")
	)
	(segment
		(start 354.169472 -89.9033)
		(end 352.092006 -89.487756)
		(width 0.1143)
		(layer "F.Cu")
		(net "P3E_CPU0_PE1_SS_TXP<6>")
	)
	(segment
		(start 315.63056 -103.969566)
		(end 314.141612 -102.89921)
		(width 0.1143)
		(layer "F.Cu")
		(net "P3E_CPU0_PE1_SS_TXP<6>")
	)
	(segment
		(start 306.60975 -96.423988)
		(end 306.38115 -96.423988)
		(width 0.0889)
		(layer "F.Cu")
		(net "P3E_CPU0_PE1_SS_TXP<6>")
	)
	(via
		(at 356.371398 -78.13802)
		(size 0.508)
		(drill 0.254)
		(layers "F.Cu" "B.Cu")
		(net "P3E_CPU0_PE1_SS_TXP<6>")
	)
	(via
		(at 327.68667 -95.1738)
		(size 0.508)
		(drill 0.254)
		(layers "F.Cu" "B.Cu")
		(net "P3E_CPU0_PE1_SS_TXP<6>")
	)
	(arc
		(start 306.38115 -96.423988)
		(mid 306.215376 -96.382782)
		(end 306.081938 -96.27616)
		(width 0.0889)
		(layer "F.Cu")
		(net "P3E_CPU0_PE1_SS_TXP<6>")
	)
	(segment
		(start 356.371398 -78.131416)
		(end 356.371398 -78.13802)
		(width 0.1143)
		(layer "B.Cu")
		(net "P3E_CPU0_PE1_SS_TXP<6>")
	)
	(segment
		(start 355.736398 -77.915516)
		(end 356.155498 -77.915516)
		(width 0.1143)
		(layer "B.Cu")
		(net "P3E_CPU0_PE1_SS_TXP<6>")
	)
	(segment
		(start 356.155498 -77.915516)
		(end 356.371398 -78.131416)
		(width 0.1143)
		(layer "B.Cu")
		(net "P3E_CPU0_PE1_SS_TXP<6>")
	)
	(segment
		(start 354.336096 -79.857346)
		(end 354.12299 -80.708754)
		(width 0.1143)
		(layer "F.Cu")
		(net "P3E_CPU0_PE1_SS_TXP<5>")
	)
	(segment
		(start 355.116638 -84.07527)
		(end 354.674424 -84.738972)
		(width 0.1143)
		(layer "F.Cu")
		(net "P3E_CPU0_PE1_SS_TXP<5>")
	)
	(segment
		(start 349.789242 -86.557104)
		(end 349.192342 -86.954614)
		(width 0.1143)
		(layer "F.Cu")
		(net "P3E_CPU0_PE1_SS_TXP<5>")
	)
	(segment
		(start 352.40214 -85.917786)
		(end 352.065844 -85.985096)
		(width 0.1143)
		(layer "F.Cu")
		(net "P3E_CPU0_PE1_SS_TXP<5>")
	)
	(segment
		(start 325.220838 -98.927412)
		(end 326.18553 -96.376998)
		(width 0.1143)
		(layer "F.Cu")
		(net "P3E_CPU0_PE1_SS_TXP<5>")
	)
	(segment
		(start 307.548534 -95.433134)
		(end 307.822854 -95.707454)
		(width 0.0889)
		(layer "F.Cu")
		(net "P3E_CPU0_PE1_SS_TXP<5>")
	)
	(segment
		(start 335.741772 -90.132154)
		(end 334.173576 -89.818972)
		(width 0.1143)
		(layer "F.Cu")
		(net "P3E_CPU0_PE1_SS_TXP<5>")
	)
	(segment
		(start 351.639886 -86.186772)
		(end 351.50552 -86.09711)
		(width 0.1143)
		(layer "F.Cu")
		(net "P3E_CPU0_PE1_SS_TXP<5>")
	)
	(segment
		(start 317.044832 -103.33101)
		(end 320.033904 -102.667816)
		(width 0.1143)
		(layer "F.Cu")
		(net "P3E_CPU0_PE1_SS_TXP<5>")
	)
	(segment
		(start 334.173576 -89.818972)
		(end 332.23327 -90.228166)
		(width 0.1143)
		(layer "F.Cu")
		(net "P3E_CPU0_PE1_SS_TXP<5>")
	)
	(segment
		(start 320.033904 -102.667816)
		(end 325.220838 -98.927412)
		(width 0.1143)
		(layer "F.Cu")
		(net "P3E_CPU0_PE1_SS_TXP<5>")
	)
	(segment
		(start 312.314844 -96.89973)
		(end 314.924186 -102.25532)
		(width 0.1143)
		(layer "F.Cu")
		(net "P3E_CPU0_PE1_SS_TXP<5>")
	)
	(segment
		(start 354.458524 -81.795366)
		(end 354.608384 -81.856072)
		(width 0.1143)
		(layer "F.Cu")
		(net "P3E_CPU0_PE1_SS_TXP<5>")
	)
	(segment
		(start 349.192342 -86.954614)
		(end 348.67342 -87.732616)
		(width 0.1143)
		(layer "F.Cu")
		(net "P3E_CPU0_PE1_SS_TXP<5>")
	)
	(segment
		(start 316.05855 -103.070152)
		(end 317.044832 -103.33101)
		(width 0.1143)
		(layer "F.Cu")
		(net "P3E_CPU0_PE1_SS_TXP<5>")
	)
	(segment
		(start 354.12299 -80.708754)
		(end 354.385626 -81.329784)
		(width 0.1143)
		(layer "F.Cu")
		(net "P3E_CPU0_PE1_SS_TXP<5>")
	)
	(segment
		(start 332.23327 -90.228166)
		(end 327.256902 -93.543882)
		(width 0.1143)
		(layer "F.Cu")
		(net "P3E_CPU0_PE1_SS_TXP<5>")
	)
	(segment
		(start 307.822854 -95.707454)
		(end 308.48046 -95.707454)
		(width 0.0889)
		(layer "F.Cu")
		(net "P3E_CPU0_PE1_SS_TXP<5>")
	)
	(segment
		(start 354.32492 -81.479644)
		(end 354.458524 -81.795366)
		(width 0.1143)
		(layer "F.Cu")
		(net "P3E_CPU0_PE1_SS_TXP<5>")
	)
	(segment
		(start 344.708988 -87.949024)
		(end 342.651842 -88.360504)
		(width 0.1143)
		(layer "F.Cu")
		(net "P3E_CPU0_PE1_SS_TXP<5>")
	)
	(segment
		(start 327.256902 -93.543882)
		(end 326.18553 -96.376998)
		(width 0.1143)
		(layer "F.Cu")
		(net "P3E_CPU0_PE1_SS_TXP<5>")
	)
	(segment
		(start 354.608384 -81.856072)
		(end 354.741988 -82.172048)
		(width 0.1143)
		(layer "F.Cu")
		(net "P3E_CPU0_PE1_SS_TXP<5>")
	)
	(segment
		(start 351.079562 -86.29904)
		(end 349.789242 -86.557104)
		(width 0.1143)
		(layer "F.Cu")
		(net "P3E_CPU0_PE1_SS_TXP<5>")
	)
	(segment
		(start 351.169224 -86.16442)
		(end 351.079562 -86.29904)
		(width 0.1143)
		(layer "F.Cu")
		(net "P3E_CPU0_PE1_SS_TXP<5>")
	)
	(segment
		(start 337.520026 -89.75725)
		(end 335.741772 -90.132154)
		(width 0.1143)
		(layer "F.Cu")
		(net "P3E_CPU0_PE1_SS_TXP<5>")
	)
	(segment
		(start 355.286564 -83.458812)
		(end 355.116638 -84.07527)
		(width 0.1143)
		(layer "F.Cu")
		(net "P3E_CPU0_PE1_SS_TXP<5>")
	)
	(segment
		(start 342.651842 -88.360504)
		(end 340.647782 -89.696544)
		(width 0.1143)
		(layer "F.Cu")
		(net "P3E_CPU0_PE1_SS_TXP<5>")
	)
	(segment
		(start 354.964746 -82.698336)
		(end 355.286564 -83.458812)
		(width 0.1143)
		(layer "F.Cu")
		(net "P3E_CPU0_PE1_SS_TXP<5>")
	)
	(segment
		(start 354.18014 -79.51597)
		(end 354.336096 -79.857346)
		(width 0.1143)
		(layer "F.Cu")
		(net "P3E_CPU0_PE1_SS_TXP<5>")
	)
	(segment
		(start 310.18988 -95.966788)
		(end 312.314844 -96.89973)
		(width 0.1143)
		(layer "F.Cu")
		(net "P3E_CPU0_PE1_SS_TXP<5>")
	)
	(segment
		(start 354.06584 -78.13802)
		(end 354.18014 -78.25232)
		(width 0.1143)
		(layer "F.Cu")
		(net "P3E_CPU0_PE1_SS_TXP<5>")
	)
	(segment
		(start 351.976182 -86.119462)
		(end 351.639886 -86.186772)
		(width 0.1143)
		(layer "F.Cu")
		(net "P3E_CPU0_PE1_SS_TXP<5>")
	)
	(segment
		(start 305.533806 -94.538038)
		(end 305.689 -94.9579)
		(width 0.0889)
		(layer "F.Cu")
		(net "P3E_CPU0_PE1_SS_TXP<5>")
	)
	(segment
		(start 352.872802 -85.940138)
		(end 352.536506 -86.007448)
		(width 0.1143)
		(layer "F.Cu")
		(net "P3E_CPU0_PE1_SS_TXP<5>")
	)
	(segment
		(start 306.38115 -95.433134)
		(end 307.548534 -95.433134)
		(width 0.0889)
		(layer "F.Cu")
		(net "P3E_CPU0_PE1_SS_TXP<5>")
	)
	(segment
		(start 354.674424 -84.738972)
		(end 352.872802 -85.940138)
		(width 0.1143)
		(layer "F.Cu")
		(net "P3E_CPU0_PE1_SS_TXP<5>")
	)
	(segment
		(start 346.151454 -88.237314)
		(end 344.708988 -87.949024)
		(width 0.1143)
		(layer "F.Cu")
		(net "P3E_CPU0_PE1_SS_TXP<5>")
	)
	(segment
		(start 354.385626 -81.329784)
		(end 354.32492 -81.479644)
		(width 0.1143)
		(layer "F.Cu")
		(net "P3E_CPU0_PE1_SS_TXP<5>")
	)
	(segment
		(start 309.287672 -95.966788)
		(end 309.30977 -95.966788)
		(width 0.0889)
		(layer "F.Cu")
		(net "P3E_CPU0_PE1_SS_TXP<5>")
	)
	(segment
		(start 340.647782 -89.696544)
		(end 338.933028 -90.039698)
		(width 0.1143)
		(layer "F.Cu")
		(net "P3E_CPU0_PE1_SS_TXP<5>")
	)
	(segment
		(start 352.065844 -85.985096)
		(end 351.976182 -86.119462)
		(width 0.1143)
		(layer "F.Cu")
		(net "P3E_CPU0_PE1_SS_TXP<5>")
	)
	(segment
		(start 338.933028 -90.039698)
		(end 337.520026 -89.75725)
		(width 0.1143)
		(layer "F.Cu")
		(net "P3E_CPU0_PE1_SS_TXP<5>")
	)
	(segment
		(start 353.60229 -78.13802)
		(end 354.06584 -78.13802)
		(width 0.1143)
		(layer "F.Cu")
		(net "P3E_CPU0_PE1_SS_TXP<5>")
	)
	(segment
		(start 314.924186 -102.25532)
		(end 316.05855 -103.070152)
		(width 0.1143)
		(layer "F.Cu")
		(net "P3E_CPU0_PE1_SS_TXP<5>")
	)
	(segment
		(start 354.681282 -82.321654)
		(end 354.814886 -82.63763)
		(width 0.1143)
		(layer "F.Cu")
		(net "P3E_CPU0_PE1_SS_TXP<5>")
	)
	(segment
		(start 308.765194 -95.992188)
		(end 309.262272 -95.992188)
		(width 0.0889)
		(layer "F.Cu")
		(net "P3E_CPU0_PE1_SS_TXP<5>")
	)
	(segment
		(start 308.48046 -95.707454)
		(end 308.765194 -95.992188)
		(width 0.0889)
		(layer "F.Cu")
		(net "P3E_CPU0_PE1_SS_TXP<5>")
	)
	(segment
		(start 354.18014 -78.25232)
		(end 354.18014 -79.51597)
		(width 0.1143)
		(layer "F.Cu")
		(net "P3E_CPU0_PE1_SS_TXP<5>")
	)
	(segment
		(start 352.536506 -86.007448)
		(end 352.40214 -85.917786)
		(width 0.1143)
		(layer "F.Cu")
		(net "P3E_CPU0_PE1_SS_TXP<5>")
	)
	(segment
		(start 309.30977 -95.966788)
		(end 310.18988 -95.966788)
		(width 0.1143)
		(layer "F.Cu")
		(net "P3E_CPU0_PE1_SS_TXP<5>")
	)
	(segment
		(start 354.814886 -82.63763)
		(end 354.964746 -82.698336)
		(width 0.1143)
		(layer "F.Cu")
		(net "P3E_CPU0_PE1_SS_TXP<5>")
	)
	(segment
		(start 354.741988 -82.172048)
		(end 354.681282 -82.321654)
		(width 0.1143)
		(layer "F.Cu")
		(net "P3E_CPU0_PE1_SS_TXP<5>")
	)
	(segment
		(start 351.50552 -86.09711)
		(end 351.169224 -86.16442)
		(width 0.1143)
		(layer "F.Cu")
		(net "P3E_CPU0_PE1_SS_TXP<5>")
	)
	(segment
		(start 348.67342 -87.732616)
		(end 346.151454 -88.237314)
		(width 0.1143)
		(layer "F.Cu")
		(net "P3E_CPU0_PE1_SS_TXP<5>")
	)
	(segment
		(start 309.262272 -95.992188)
		(end 309.287672 -95.966788)
		(width 0.0889)
		(layer "F.Cu")
		(net "P3E_CPU0_PE1_SS_TXP<5>")
	)
	(via
		(at 326.18553 -96.376998)
		(size 0.508)
		(drill 0.254)
		(layers "F.Cu" "B.Cu")
		(net "P3E_CPU0_PE1_SS_TXP<5>")
	)
	(via
		(at 353.60229 -78.13802)
		(size 0.508)
		(drill 0.254)
		(layers "F.Cu" "B.Cu")
		(net "P3E_CPU0_PE1_SS_TXP<5>")
	)
	(arc
		(start 306.045616 -95.232982)
		(mid 306.187299 -95.376786)
		(end 306.38115 -95.433134)
		(width 0.0889)
		(layer "F.Cu")
		(net "P3E_CPU0_PE1_SS_TXP<5>")
	)
	(arc
		(start 305.689 -94.9579)
		(mid 305.710078 -94.964113)
		(end 305.73091 -94.971108)
		(width 0.0889)
		(layer "F.Cu")
		(net "P3E_CPU0_PE1_SS_TXP<5>")
	)
	(arc
		(start 305.73091 -94.971108)
		(mid 305.911632 -95.07395)
		(end 306.045616 -95.232982)
		(width 0.0889)
		(layer "F.Cu")
		(net "P3E_CPU0_PE1_SS_TXP<5>")
	)
	(segment
		(start 353.38639 -77.915516)
		(end 353.60229 -78.131416)
		(width 0.1143)
		(layer "B.Cu")
		(net "P3E_CPU0_PE1_SS_TXP<5>")
	)
	(segment
		(start 352.96729 -77.915516)
		(end 353.38639 -77.915516)
		(width 0.1143)
		(layer "B.Cu")
		(net "P3E_CPU0_PE1_SS_TXP<5>")
	)
	(segment
		(start 353.60229 -78.131416)
		(end 353.60229 -78.13802)
		(width 0.1143)
		(layer "B.Cu")
		(net "P3E_CPU0_PE1_SS_TXP<5>")
	)
	(segment
		(start 351.56394 -83.714082)
		(end 351.373694 -83.999324)
		(width 0.1143)
		(layer "F.Cu")
		(net "P3E_CPU0_PE1_SS_TXP<4>")
	)
	(segment
		(start 322.627752 -90.104722)
		(end 313.033664 -95.011494)
		(width 0.1143)
		(layer "F.Cu")
		(net "P3E_CPU0_PE1_SS_TXP<4>")
	)
	(segment
		(start 305.223418 -93.79966)
		(end 305.246532 -93.713046)
		(width 0.0889)
		(layer "F.Cu")
		(net "P3E_CPU0_PE1_SS_TXP<4>")
	)
	(segment
		(start 309.79364 -95.036894)
		(end 309.69458 -94.937834)
		(width 0.0889)
		(layer "F.Cu")
		(net "P3E_CPU0_PE1_SS_TXP<4>")
	)
	(segment
		(start 347.290644 -86.763352)
		(end 345.5035 -86.405974)
		(width 0.1143)
		(layer "F.Cu")
		(net "P3E_CPU0_PE1_SS_TXP<4>")
	)
	(segment
		(start 347.878654 -86.64575)
		(end 347.290644 -86.763352)
		(width 0.1143)
		(layer "F.Cu")
		(net "P3E_CPU0_PE1_SS_TXP<4>")
	)
	(segment
		(start 313.033664 -95.011494)
		(end 310.334406 -95.011494)
		(width 0.1143)
		(layer "F.Cu")
		(net "P3E_CPU0_PE1_SS_TXP<4>")
	)
	(segment
		(start 333.853536 -86.089998)
		(end 324.993 -89.033858)
		(width 0.1143)
		(layer "F.Cu")
		(net "P3E_CPU0_PE1_SS_TXP<4>")
	)
	(segment
		(start 352.41992 -82.635852)
		(end 352.229674 -82.921348)
		(width 0.1143)
		(layer "F.Cu")
		(net "P3E_CPU0_PE1_SS_TXP<4>")
	)
	(segment
		(start 343.987374 -86.708996)
		(end 343.651078 -86.776306)
		(width 0.1143)
		(layer "F.Cu")
		(net "P3E_CPU0_PE1_SS_TXP<4>")
	)
	(segment
		(start 309.03672 -95.036894)
		(end 308.93766 -94.937834)
		(width 0.0889)
		(layer "F.Cu")
		(net "P3E_CPU0_PE1_SS_TXP<4>")
	)
	(segment
		(start 351.912682 -83.396836)
		(end 351.722436 -83.682332)
		(width 0.1143)
		(layer "F.Cu")
		(net "P3E_CPU0_PE1_SS_TXP<4>")
	)
	(segment
		(start 350.878902 -84.94776)
		(end 350.077532 -85.481668)
		(width 0.1143)
		(layer "F.Cu")
		(net "P3E_CPU0_PE1_SS_TXP<4>")
	)
	(segment
		(start 308.65826 -94.937834)
		(end 308.5592 -95.036894)
		(width 0.0889)
		(layer "F.Cu")
		(net "P3E_CPU0_PE1_SS_TXP<4>")
	)
	(segment
		(start 351.237042 -78.890368)
		(end 351.94113 -79.9465)
		(width 0.1143)
		(layer "F.Cu")
		(net "P3E_CPU0_PE1_SS_TXP<4>")
	)
	(segment
		(start 350.077532 -85.481668)
		(end 349.429324 -85.611462)
		(width 0.1143)
		(layer "F.Cu")
		(net "P3E_CPU0_PE1_SS_TXP<4>")
	)
	(segment
		(start 324.221856 -89.290144)
		(end 324.221602 -89.28989)
		(width 0.1143)
		(layer "F.Cu")
		(net "P3E_CPU0_PE1_SS_TXP<4>")
	)
	(segment
		(start 309.41518 -94.937834)
		(end 309.31612 -95.036894)
		(width 0.0889)
		(layer "F.Cu")
		(net "P3E_CPU0_PE1_SS_TXP<4>")
	)
	(segment
		(start 352.229674 -82.921348)
		(end 352.071178 -82.953098)
		(width 0.1143)
		(layer "F.Cu")
		(net "P3E_CPU0_PE1_SS_TXP<4>")
	)
	(segment
		(start 342.754458 -86.95563)
		(end 339.93709 -85.810852)
		(width 0.1143)
		(layer "F.Cu")
		(net "P3E_CPU0_PE1_SS_TXP<4>")
	)
	(segment
		(start 343.516712 -86.686644)
		(end 343.180416 -86.753954)
		(width 0.1143)
		(layer "F.Cu")
		(net "P3E_CPU0_PE1_SS_TXP<4>")
	)
	(segment
		(start 308.2798 -95.036894)
		(end 307.68544 -94.442534)
		(width 0.0889)
		(layer "F.Cu")
		(net "P3E_CPU0_PE1_SS_TXP<4>")
	)
	(segment
		(start 308.5592 -95.036894)
		(end 308.2798 -95.036894)
		(width 0.0889)
		(layer "F.Cu")
		(net "P3E_CPU0_PE1_SS_TXP<4>")
	)
	(segment
		(start 335.410556 -86.372954)
		(end 333.853536 -86.089998)
		(width 0.1143)
		(layer "F.Cu")
		(net "P3E_CPU0_PE1_SS_TXP<4>")
	)
	(segment
		(start 324.993254 -89.033858)
		(end 324.221856 -89.290144)
		(width 0.1143)
		(layer "F.Cu")
		(net "P3E_CPU0_PE1_SS_TXP<4>")
	)
	(segment
		(start 351.373694 -83.999324)
		(end 351.405444 -84.15782)
		(width 0.1143)
		(layer "F.Cu")
		(net "P3E_CPU0_PE1_SS_TXP<4>")
	)
	(segment
		(start 345.5035 -86.405974)
		(end 344.547698 -86.596982)
		(width 0.1143)
		(layer "F.Cu")
		(net "P3E_CPU0_PE1_SS_TXP<4>")
	)
	(segment
		(start 351.94113 -79.9465)
		(end 352.449638 -82.488024)
		(width 0.1143)
		(layer "F.Cu")
		(net "P3E_CPU0_PE1_SS_TXP<4>")
	)
	(segment
		(start 305.54676 -93.947234)
		(end 305.51882 -93.947234)
		(width 0.0889)
		(layer "F.Cu")
		(net "P3E_CPU0_PE1_SS_TXP<4>")
	)
	(segment
		(start 310.334406 -95.011494)
		(end 310.312308 -95.011494)
		(width 0.0889)
		(layer "F.Cu")
		(net "P3E_CPU0_PE1_SS_TXP<4>")
	)
	(segment
		(start 343.180416 -86.753954)
		(end 343.090754 -86.88832)
		(width 0.1143)
		(layer "F.Cu")
		(net "P3E_CPU0_PE1_SS_TXP<4>")
	)
	(segment
		(start 343.090754 -86.88832)
		(end 342.754458 -86.95563)
		(width 0.1143)
		(layer "F.Cu")
		(net "P3E_CPU0_PE1_SS_TXP<4>")
	)
	(segment
		(start 344.413332 -86.50732)
		(end 344.077036 -86.57463)
		(width 0.1143)
		(layer "F.Cu")
		(net "P3E_CPU0_PE1_SS_TXP<4>")
	)
	(segment
		(start 351.237042 -78.17104)
		(end 351.237042 -78.890368)
		(width 0.1143)
		(layer "F.Cu")
		(net "P3E_CPU0_PE1_SS_TXP<4>")
	)
	(segment
		(start 336.950558 -85.9282)
		(end 335.410556 -86.372954)
		(width 0.1143)
		(layer "F.Cu")
		(net "P3E_CPU0_PE1_SS_TXP<4>")
	)
	(segment
		(start 344.077036 -86.57463)
		(end 343.987374 -86.708996)
		(width 0.1143)
		(layer "F.Cu")
		(net "P3E_CPU0_PE1_SS_TXP<4>")
	)
	(segment
		(start 339.93709 -85.810852)
		(end 338.260944 -86.2076)
		(width 0.1143)
		(layer "F.Cu")
		(net "P3E_CPU0_PE1_SS_TXP<4>")
	)
	(segment
		(start 305.246532 -93.713046)
		(end 305.533806 -93.547184)
		(width 0.0889)
		(layer "F.Cu")
		(net "P3E_CPU0_PE1_SS_TXP<4>")
	)
	(segment
		(start 352.449638 -82.488024)
		(end 352.41992 -82.635852)
		(width 0.1143)
		(layer "F.Cu")
		(net "P3E_CPU0_PE1_SS_TXP<4>")
	)
	(segment
		(start 324.221602 -89.28989)
		(end 322.627752 -90.104722)
		(width 0.1143)
		(layer "F.Cu")
		(net "P3E_CPU0_PE1_SS_TXP<4>")
	)
	(segment
		(start 351.122742 -78.05674)
		(end 351.237042 -78.17104)
		(width 0.1143)
		(layer "F.Cu")
		(net "P3E_CPU0_PE1_SS_TXP<4>")
	)
	(segment
		(start 308.93766 -94.937834)
		(end 308.65826 -94.937834)
		(width 0.0889)
		(layer "F.Cu")
		(net "P3E_CPU0_PE1_SS_TXP<4>")
	)
	(segment
		(start 309.31612 -95.036894)
		(end 309.03672 -95.036894)
		(width 0.0889)
		(layer "F.Cu")
		(net "P3E_CPU0_PE1_SS_TXP<4>")
	)
	(segment
		(start 344.547698 -86.596982)
		(end 344.413332 -86.50732)
		(width 0.1143)
		(layer "F.Cu")
		(net "P3E_CPU0_PE1_SS_TXP<4>")
	)
	(segment
		(start 351.405444 -84.15782)
		(end 350.878902 -84.94776)
		(width 0.1143)
		(layer "F.Cu")
		(net "P3E_CPU0_PE1_SS_TXP<4>")
	)
	(segment
		(start 309.69458 -94.937834)
		(end 309.41518 -94.937834)
		(width 0.0889)
		(layer "F.Cu")
		(net "P3E_CPU0_PE1_SS_TXP<4>")
	)
	(segment
		(start 352.071178 -82.953098)
		(end 351.880932 -83.23834)
		(width 0.1143)
		(layer "F.Cu")
		(net "P3E_CPU0_PE1_SS_TXP<4>")
	)
	(segment
		(start 349.429324 -85.611462)
		(end 347.878654 -86.64575)
		(width 0.1143)
		(layer "F.Cu")
		(net "P3E_CPU0_PE1_SS_TXP<4>")
	)
	(segment
		(start 310.312308 -95.011494)
		(end 310.286908 -95.036894)
		(width 0.0889)
		(layer "F.Cu")
		(net "P3E_CPU0_PE1_SS_TXP<4>")
	)
	(segment
		(start 307.68544 -94.442534)
		(end 306.374292 -94.442534)
		(width 0.0889)
		(layer "F.Cu")
		(net "P3E_CPU0_PE1_SS_TXP<4>")
	)
	(segment
		(start 343.651078 -86.776306)
		(end 343.516712 -86.686644)
		(width 0.1143)
		(layer "F.Cu")
		(net "P3E_CPU0_PE1_SS_TXP<4>")
	)
	(segment
		(start 324.993 -89.033858)
		(end 324.993254 -89.033858)
		(width 0.1143)
		(layer "F.Cu")
		(net "P3E_CPU0_PE1_SS_TXP<4>")
	)
	(segment
		(start 338.260944 -86.2076)
		(end 336.950558 -85.9282)
		(width 0.1143)
		(layer "F.Cu")
		(net "P3E_CPU0_PE1_SS_TXP<4>")
	)
	(segment
		(start 310.286908 -95.036894)
		(end 309.79364 -95.036894)
		(width 0.0889)
		(layer "F.Cu")
		(net "P3E_CPU0_PE1_SS_TXP<4>")
	)
	(segment
		(start 351.722436 -83.682332)
		(end 351.56394 -83.714082)
		(width 0.1143)
		(layer "F.Cu")
		(net "P3E_CPU0_PE1_SS_TXP<4>")
	)
	(segment
		(start 351.880932 -83.23834)
		(end 351.912682 -83.396836)
		(width 0.1143)
		(layer "F.Cu")
		(net "P3E_CPU0_PE1_SS_TXP<4>")
	)
	(segment
		(start 350.659192 -78.05674)
		(end 351.122742 -78.05674)
		(width 0.1143)
		(layer "F.Cu")
		(net "P3E_CPU0_PE1_SS_TXP<4>")
	)
	(via
		(at 324.993254 -89.033858)
		(size 0.508)
		(drill 0.254)
		(layers "F.Cu" "B.Cu")
		(net "P3E_CPU0_PE1_SS_TXP<4>")
	)
	(via
		(at 350.659192 -78.05674)
		(size 0.508)
		(drill 0.254)
		(layers "F.Cu" "B.Cu")
		(net "P3E_CPU0_PE1_SS_TXP<4>")
	)
	(arc
		(start 305.51882 -93.947234)
		(mid 305.355182 -93.905339)
		(end 305.223418 -93.79966)
		(width 0.0889)
		(layer "F.Cu")
		(net "P3E_CPU0_PE1_SS_TXP<4>")
	)
	(arc
		(start 306.045616 -94.242636)
		(mid 305.834903 -94.029557)
		(end 305.54676 -93.947234)
		(width 0.0889)
		(layer "F.Cu")
		(net "P3E_CPU0_PE1_SS_TXP<4>")
	)
	(arc
		(start 306.374292 -94.442534)
		(mid 306.184363 -94.384664)
		(end 306.045616 -94.242636)
		(width 0.0889)
		(layer "F.Cu")
		(net "P3E_CPU0_PE1_SS_TXP<4>")
	)
	(segment
		(start 350.443292 -77.834236)
		(end 350.659192 -78.050136)
		(width 0.1143)
		(layer "B.Cu")
		(net "P3E_CPU0_PE1_SS_TXP<4>")
	)
	(segment
		(start 350.659192 -78.050136)
		(end 350.659192 -78.05674)
		(width 0.1143)
		(layer "B.Cu")
		(net "P3E_CPU0_PE1_SS_TXP<4>")
	)
	(segment
		(start 350.024192 -77.834236)
		(end 350.443292 -77.834236)
		(width 0.1143)
		(layer "B.Cu")
		(net "P3E_CPU0_PE1_SS_TXP<4>")
	)
	(segment
		(start 308.793134 -94.028768)
		(end 308.771036 -94.028768)
		(width 0.0889)
		(layer "F.Cu")
		(net "P3E_CPU0_PE1_SS_TXP<3>")
	)
	(segment
		(start 321.879468 -89.37371)
		(end 321.879214 -89.37371)
		(width 0.1143)
		(layer "F.Cu")
		(net "P3E_CPU0_PE1_SS_TXP<3>")
	)
	(segment
		(start 343.606882 -83.566508)
		(end 343.942924 -83.498944)
		(width 0.1143)
		(layer "F.Cu")
		(net "P3E_CPU0_PE1_SS_TXP<3>")
	)
	(segment
		(start 348.27591 -78.01102)
		(end 347.81236 -78.01102)
		(width 0.1143)
		(layer "F.Cu")
		(net "P3E_CPU0_PE1_SS_TXP<3>")
	)
	(segment
		(start 344.032586 -83.364578)
		(end 344.368882 -83.297268)
		(width 0.1143)
		(layer "F.Cu")
		(net "P3E_CPU0_PE1_SS_TXP<3>")
	)
	(segment
		(start 323.88683 -88.346788)
		(end 338.02701 -83.649058)
		(width 0.1143)
		(layer "F.Cu")
		(net "P3E_CPU0_PE1_SS_TXP<3>")
	)
	(segment
		(start 312.77941 -94.028768)
		(end 308.793134 -94.028768)
		(width 0.1143)
		(layer "F.Cu")
		(net "P3E_CPU0_PE1_SS_TXP<3>")
	)
	(segment
		(start 345.736164 -83.140042)
		(end 345.825572 -83.005422)
		(width 0.1143)
		(layer "F.Cu")
		(net "P3E_CPU0_PE1_SS_TXP<3>")
	)
	(segment
		(start 308.099206 -94.054168)
		(end 307.497226 -93.452188)
		(width 0.0889)
		(layer "F.Cu")
		(net "P3E_CPU0_PE1_SS_TXP<3>")
	)
	(segment
		(start 307.497226 -93.452188)
		(end 306.377848 -93.452188)
		(width 0.0889)
		(layer "F.Cu")
		(net "P3E_CPU0_PE1_SS_TXP<3>")
	)
	(segment
		(start 305.551586 -92.956634)
		(end 305.51882 -92.956634)
		(width 0.0889)
		(layer "F.Cu")
		(net "P3E_CPU0_PE1_SS_TXP<3>")
	)
	(segment
		(start 344.929206 -83.185)
		(end 345.265248 -83.11769)
		(width 0.1143)
		(layer "F.Cu")
		(net "P3E_CPU0_PE1_SS_TXP<3>")
	)
	(segment
		(start 343.942924 -83.498944)
		(end 344.032586 -83.364578)
		(width 0.1143)
		(layer "F.Cu")
		(net "P3E_CPU0_PE1_SS_TXP<3>")
	)
	(segment
		(start 348.39021 -78.95209)
		(end 348.39021 -78.12532)
		(width 0.1143)
		(layer "F.Cu")
		(net "P3E_CPU0_PE1_SS_TXP<3>")
	)
	(segment
		(start 321.879214 -89.37371)
		(end 323.88683 -88.346788)
		(width 0.1143)
		(layer "F.Cu")
		(net "P3E_CPU0_PE1_SS_TXP<3>")
	)
	(segment
		(start 304.82794 -92.481146)
		(end 304.675286 -92.061538)
		(width 0.0889)
		(layer "F.Cu")
		(net "P3E_CPU0_PE1_SS_TXP<3>")
	)
	(segment
		(start 316.717172 -92.014548)
		(end 317.202312 -91.76639)
		(width 0.1143)
		(layer "F.Cu")
		(net "P3E_CPU0_PE1_SS_TXP<3>")
	)
	(segment
		(start 346.296488 -83.027774)
		(end 347.86062 -82.714338)
		(width 0.1143)
		(layer "F.Cu")
		(net "P3E_CPU0_PE1_SS_TXP<3>")
	)
	(segment
		(start 348.909386 -82.015076)
		(end 349.254318 -80.598264)
		(width 0.1143)
		(layer "F.Cu")
		(net "P3E_CPU0_PE1_SS_TXP<3>")
	)
	(segment
		(start 338.02701 -83.649058)
		(end 340.62035 -84.164678)
		(width 0.1143)
		(layer "F.Cu")
		(net "P3E_CPU0_PE1_SS_TXP<3>")
	)
	(segment
		(start 349.254318 -80.598264)
		(end 348.39021 -78.95209)
		(width 0.1143)
		(layer "F.Cu")
		(net "P3E_CPU0_PE1_SS_TXP<3>")
	)
	(segment
		(start 343.046304 -83.678776)
		(end 343.135966 -83.544156)
		(width 0.1143)
		(layer "F.Cu")
		(net "P3E_CPU0_PE1_SS_TXP<3>")
	)
	(segment
		(start 345.265248 -83.11769)
		(end 345.399868 -83.207352)
		(width 0.1143)
		(layer "F.Cu")
		(net "P3E_CPU0_PE1_SS_TXP<3>")
	)
	(segment
		(start 346.161868 -82.938112)
		(end 346.296488 -83.027774)
		(width 0.1143)
		(layer "F.Cu")
		(net "P3E_CPU0_PE1_SS_TXP<3>")
	)
	(segment
		(start 343.472262 -83.476846)
		(end 343.606882 -83.566508)
		(width 0.1143)
		(layer "F.Cu")
		(net "P3E_CPU0_PE1_SS_TXP<3>")
	)
	(segment
		(start 316.164468 -92.29725)
		(end 312.77941 -94.028768)
		(width 0.1143)
		(layer "F.Cu")
		(net "P3E_CPU0_PE1_SS_TXP<3>")
	)
	(segment
		(start 316.717172 -92.014548)
		(end 316.164468 -92.29725)
		(width 0.1143)
		(layer "F.Cu")
		(net "P3E_CPU0_PE1_SS_TXP<3>")
	)
	(segment
		(start 343.135966 -83.544156)
		(end 343.472262 -83.476846)
		(width 0.1143)
		(layer "F.Cu")
		(net "P3E_CPU0_PE1_SS_TXP<3>")
	)
	(segment
		(start 317.202312 -91.76639)
		(end 321.879468 -89.37371)
		(width 0.1143)
		(layer "F.Cu")
		(net "P3E_CPU0_PE1_SS_TXP<3>")
	)
	(segment
		(start 340.62035 -84.164678)
		(end 343.046304 -83.678776)
		(width 0.1143)
		(layer "F.Cu")
		(net "P3E_CPU0_PE1_SS_TXP<3>")
	)
	(segment
		(start 345.825572 -83.005422)
		(end 346.161868 -82.938112)
		(width 0.1143)
		(layer "F.Cu")
		(net "P3E_CPU0_PE1_SS_TXP<3>")
	)
	(segment
		(start 308.745636 -94.054168)
		(end 308.099206 -94.054168)
		(width 0.0889)
		(layer "F.Cu")
		(net "P3E_CPU0_PE1_SS_TXP<3>")
	)
	(segment
		(start 347.86062 -82.714338)
		(end 348.909386 -82.015076)
		(width 0.1143)
		(layer "F.Cu")
		(net "P3E_CPU0_PE1_SS_TXP<3>")
	)
	(segment
		(start 348.39021 -78.12532)
		(end 348.27591 -78.01102)
		(width 0.1143)
		(layer "F.Cu")
		(net "P3E_CPU0_PE1_SS_TXP<3>")
	)
	(segment
		(start 344.839544 -83.31962)
		(end 344.929206 -83.185)
		(width 0.1143)
		(layer "F.Cu")
		(net "P3E_CPU0_PE1_SS_TXP<3>")
	)
	(segment
		(start 344.368882 -83.297268)
		(end 344.503248 -83.38693)
		(width 0.1143)
		(layer "F.Cu")
		(net "P3E_CPU0_PE1_SS_TXP<3>")
	)
	(segment
		(start 308.771036 -94.028768)
		(end 308.745636 -94.054168)
		(width 0.0889)
		(layer "F.Cu")
		(net "P3E_CPU0_PE1_SS_TXP<3>")
	)
	(segment
		(start 344.503248 -83.38693)
		(end 344.839544 -83.31962)
		(width 0.1143)
		(layer "F.Cu")
		(net "P3E_CPU0_PE1_SS_TXP<3>")
	)
	(segment
		(start 345.399868 -83.207352)
		(end 345.736164 -83.140042)
		(width 0.1143)
		(layer "F.Cu")
		(net "P3E_CPU0_PE1_SS_TXP<3>")
	)
	(via
		(at 316.717172 -92.014548)
		(size 0.508)
		(drill 0.254)
		(layers "F.Cu" "B.Cu")
		(net "P3E_CPU0_PE1_SS_TXP<3>")
	)
	(via
		(at 347.81236 -78.01102)
		(size 0.508)
		(drill 0.254)
		(layers "F.Cu" "B.Cu")
		(net "P3E_CPU0_PE1_SS_TXP<3>")
	)
	(arc
		(start 306.377848 -93.452188)
		(mid 306.185831 -93.39508)
		(end 306.045616 -93.252036)
		(width 0.0889)
		(layer "F.Cu")
		(net "P3E_CPU0_PE1_SS_TXP<3>")
	)
	(arc
		(start 305.187096 -92.756736)
		(mid 305.05977 -92.603293)
		(end 304.888646 -92.500958)
		(width 0.0889)
		(layer "F.Cu")
		(net "P3E_CPU0_PE1_SS_TXP<3>")
	)
	(arc
		(start 305.51882 -92.956634)
		(mid 305.327178 -92.899468)
		(end 305.187096 -92.756736)
		(width 0.0889)
		(layer "F.Cu")
		(net "P3E_CPU0_PE1_SS_TXP<3>")
	)
	(arc
		(start 306.045616 -93.252036)
		(mid 305.837008 -93.040104)
		(end 305.551586 -92.956634)
		(width 0.0889)
		(layer "F.Cu")
		(net "P3E_CPU0_PE1_SS_TXP<3>")
	)
	(arc
		(start 304.888646 -92.500958)
		(mid 304.85856 -92.490232)
		(end 304.82794 -92.481146)
		(width 0.0889)
		(layer "F.Cu")
		(net "P3E_CPU0_PE1_SS_TXP<3>")
	)
	(segment
		(start 347.59646 -77.788516)
		(end 347.81236 -78.004416)
		(width 0.1143)
		(layer "B.Cu")
		(net "P3E_CPU0_PE1_SS_TXP<3>")
	)
	(segment
		(start 347.81236 -78.004416)
		(end 347.81236 -78.01102)
		(width 0.1143)
		(layer "B.Cu")
		(net "P3E_CPU0_PE1_SS_TXP<3>")
	)
	(segment
		(start 347.17736 -77.788516)
		(end 347.59646 -77.788516)
		(width 0.1143)
		(layer "B.Cu")
		(net "P3E_CPU0_PE1_SS_TXP<3>")
	)
	(segment
		(start 312.518298 -93.04274)
		(end 309.146702 -93.04274)
		(width 0.1143)
		(layer "F.Cu")
		(net "P3E_CPU0_PE1_SS_TXP<2>")
	)
	(segment
		(start 309.124604 -93.04274)
		(end 309.099204 -93.06814)
		(width 0.0889)
		(layer "F.Cu")
		(net "P3E_CPU0_PE1_SS_TXP<2>")
	)
	(segment
		(start 344.960702 -79.159608)
		(end 344.306906 -79.813404)
		(width 0.1143)
		(layer "F.Cu")
		(net "P3E_CPU0_PE1_SS_TXP<2>")
	)
	(segment
		(start 308.253892 -93.06814)
		(end 307.64734 -92.461588)
		(width 0.0889)
		(layer "F.Cu")
		(net "P3E_CPU0_PE1_SS_TXP<2>")
	)
	(segment
		(start 341.021162 -82.814414)
		(end 340.880446 -82.734658)
		(width 0.1143)
		(layer "F.Cu")
		(net "P3E_CPU0_PE1_SS_TXP<2>")
	)
	(segment
		(start 340.549992 -82.826352)
		(end 340.47049 -82.967068)
		(width 0.1143)
		(layer "F.Cu")
		(net "P3E_CPU0_PE1_SS_TXP<2>")
	)
	(segment
		(start 343.902538 -80.217518)
		(end 343.639394 -80.480662)
		(width 0.1143)
		(layer "F.Cu")
		(net "P3E_CPU0_PE1_SS_TXP<2>")
	)
	(segment
		(start 343.510108 -80.798162)
		(end 343.36101 -80.8609)
		(width 0.1143)
		(layer "F.Cu")
		(net "P3E_CPU0_PE1_SS_TXP<2>")
	)
	(segment
		(start 343.231724 -81.1784)
		(end 343.294462 -81.327498)
		(width 0.1143)
		(layer "F.Cu")
		(net "P3E_CPU0_PE1_SS_TXP<2>")
	)
	(segment
		(start 344.145108 -79.813404)
		(end 343.902538 -80.05572)
		(width 0.1143)
		(layer "F.Cu")
		(net "P3E_CPU0_PE1_SS_TXP<2>")
	)
	(segment
		(start 345.070176 -77.89926)
		(end 345.533726 -77.89926)
		(width 0.1143)
		(layer "F.Cu")
		(net "P3E_CPU0_PE1_SS_TXP<2>")
	)
	(segment
		(start 344.306906 -79.813404)
		(end 344.145108 -79.813404)
		(width 0.1143)
		(layer "F.Cu")
		(net "P3E_CPU0_PE1_SS_TXP<2>")
	)
	(segment
		(start 345.648026 -78.01356)
		(end 345.648026 -78.916022)
		(width 0.1143)
		(layer "F.Cu")
		(net "P3E_CPU0_PE1_SS_TXP<2>")
	)
	(segment
		(start 305.82108 -92.722446)
		(end 305.533806 -92.556584)
		(width 0.0889)
		(layer "F.Cu")
		(net "P3E_CPU0_PE1_SS_TXP<2>")
	)
	(segment
		(start 342.901016 -82.292698)
		(end 341.902288 -82.569812)
		(width 0.1143)
		(layer "F.Cu")
		(net "P3E_CPU0_PE1_SS_TXP<2>")
	)
	(segment
		(start 340.47049 -82.967068)
		(end 340.140036 -83.058762)
		(width 0.1143)
		(layer "F.Cu")
		(net "P3E_CPU0_PE1_SS_TXP<2>")
	)
	(segment
		(start 307.64734 -92.461588)
		(end 306.370736 -92.461588)
		(width 0.0889)
		(layer "F.Cu")
		(net "P3E_CPU0_PE1_SS_TXP<2>")
	)
	(segment
		(start 305.920902 -92.695522)
		(end 305.82108 -92.722446)
		(width 0.0889)
		(layer "F.Cu")
		(net "P3E_CPU0_PE1_SS_TXP<2>")
	)
	(segment
		(start 341.431118 -82.582004)
		(end 341.351616 -82.72272)
		(width 0.1143)
		(layer "F.Cu")
		(net "P3E_CPU0_PE1_SS_TXP<2>")
	)
	(segment
		(start 341.351616 -82.72272)
		(end 341.021162 -82.814414)
		(width 0.1143)
		(layer "F.Cu")
		(net "P3E_CPU0_PE1_SS_TXP<2>")
	)
	(segment
		(start 343.294462 -81.327498)
		(end 342.901016 -82.292698)
		(width 0.1143)
		(layer "F.Cu")
		(net "P3E_CPU0_PE1_SS_TXP<2>")
	)
	(segment
		(start 309.146702 -93.04274)
		(end 309.124604 -93.04274)
		(width 0.0889)
		(layer "F.Cu")
		(net "P3E_CPU0_PE1_SS_TXP<2>")
	)
	(segment
		(start 340.880446 -82.734658)
		(end 340.549992 -82.826352)
		(width 0.1143)
		(layer "F.Cu")
		(net "P3E_CPU0_PE1_SS_TXP<2>")
	)
	(segment
		(start 323.407024 -87.473028)
		(end 321.543172 -88.42629)
		(width 0.1143)
		(layer "F.Cu")
		(net "P3E_CPU0_PE1_SS_TXP<2>")
	)
	(segment
		(start 337.984338 -82.629756)
		(end 323.407786 -87.47252)
		(width 0.1143)
		(layer "F.Cu")
		(net "P3E_CPU0_PE1_SS_TXP<2>")
	)
	(segment
		(start 341.761572 -82.49031)
		(end 341.431118 -82.582004)
		(width 0.1143)
		(layer "F.Cu")
		(net "P3E_CPU0_PE1_SS_TXP<2>")
	)
	(segment
		(start 345.40444 -79.159608)
		(end 344.960702 -79.159608)
		(width 0.1143)
		(layer "F.Cu")
		(net "P3E_CPU0_PE1_SS_TXP<2>")
	)
	(segment
		(start 321.543172 -88.42629)
		(end 312.518298 -93.04274)
		(width 0.1143)
		(layer "F.Cu")
		(net "P3E_CPU0_PE1_SS_TXP<2>")
	)
	(segment
		(start 323.407786 -87.47252)
		(end 323.407024 -87.473028)
		(width 0.1143)
		(layer "F.Cu")
		(net "P3E_CPU0_PE1_SS_TXP<2>")
	)
	(segment
		(start 341.902288 -82.569812)
		(end 341.761572 -82.49031)
		(width 0.1143)
		(layer "F.Cu")
		(net "P3E_CPU0_PE1_SS_TXP<2>")
	)
	(segment
		(start 343.36101 -80.8609)
		(end 343.231724 -81.1784)
		(width 0.1143)
		(layer "F.Cu")
		(net "P3E_CPU0_PE1_SS_TXP<2>")
	)
	(segment
		(start 343.639394 -80.480662)
		(end 343.510108 -80.798162)
		(width 0.1143)
		(layer "F.Cu")
		(net "P3E_CPU0_PE1_SS_TXP<2>")
	)
	(segment
		(start 340.140036 -83.058762)
		(end 337.984338 -82.629756)
		(width 0.1143)
		(layer "F.Cu")
		(net "P3E_CPU0_PE1_SS_TXP<2>")
	)
	(segment
		(start 343.902538 -80.05572)
		(end 343.902538 -80.217518)
		(width 0.1143)
		(layer "F.Cu")
		(net "P3E_CPU0_PE1_SS_TXP<2>")
	)
	(segment
		(start 309.099204 -93.06814)
		(end 308.253892 -93.06814)
		(width 0.0889)
		(layer "F.Cu")
		(net "P3E_CPU0_PE1_SS_TXP<2>")
	)
	(segment
		(start 345.648026 -78.916022)
		(end 345.40444 -79.159608)
		(width 0.1143)
		(layer "F.Cu")
		(net "P3E_CPU0_PE1_SS_TXP<2>")
	)
	(segment
		(start 345.533726 -77.89926)
		(end 345.648026 -78.01356)
		(width 0.1143)
		(layer "F.Cu")
		(net "P3E_CPU0_PE1_SS_TXP<2>")
	)
	(via
		(at 345.070176 -77.89926)
		(size 0.508)
		(drill 0.254)
		(layers "F.Cu" "B.Cu")
		(net "P3E_CPU0_PE1_SS_TXP<2>")
	)
	(via
		(at 321.543172 -88.42629)
		(size 0.508)
		(drill 0.254)
		(layers "F.Cu" "B.Cu")
		(net "P3E_CPU0_PE1_SS_TXP<2>")
	)
	(arc
		(start 306.370736 -92.461588)
		(mid 306.119446 -92.527848)
		(end 305.920902 -92.695522)
		(width 0.0889)
		(layer "F.Cu")
		(net "P3E_CPU0_PE1_SS_TXP<2>")
	)
	(segment
		(start 344.872056 -77.694536)
		(end 345.070176 -77.892656)
		(width 0.1143)
		(layer "B.Cu")
		(net "P3E_CPU0_PE1_SS_TXP<2>")
	)
	(segment
		(start 344.435176 -77.694536)
		(end 344.872056 -77.694536)
		(width 0.1143)
		(layer "B.Cu")
		(net "P3E_CPU0_PE1_SS_TXP<2>")
	)
	(segment
		(start 345.070176 -77.892656)
		(end 345.070176 -77.89926)
		(width 0.1143)
		(layer "B.Cu")
		(net "P3E_CPU0_PE1_SS_TXP<2>")
	)
	(segment
		(start 338.540852 -81.74482)
		(end 338.450936 -81.610454)
		(width 0.1143)
		(layer "F.Cu")
		(net "P3E_CPU0_PE1_SS_TXP<1>")
	)
	(segment
		(start 334.902556 -82.35696)
		(end 334.577182 -82.46491)
		(width 0.1143)
		(layer "F.Cu")
		(net "P3E_CPU0_PE1_SS_TXP<1>")
	)
	(segment
		(start 308.744112 -91.96578)
		(end 309.204106 -91.96578)
		(width 0.0889)
		(layer "F.Cu")
		(net "P3E_CPU0_PE1_SS_TXP<1>")
	)
	(segment
		(start 332.443582 -83.29422)
		(end 332.29931 -83.22183)
		(width 0.1143)
		(layer "F.Cu")
		(net "P3E_CPU0_PE1_SS_TXP<1>")
	)
	(segment
		(start 309.204106 -91.96578)
		(end 309.306468 -92.068142)
		(width 0.0889)
		(layer "F.Cu")
		(net "P3E_CPU0_PE1_SS_TXP<1>")
	)
	(segment
		(start 334.179164 -82.71764)
		(end 334.034638 -82.64525)
		(width 0.1143)
		(layer "F.Cu")
		(net "P3E_CPU0_PE1_SS_TXP<1>")
	)
	(segment
		(start 342.714072 -77.91704)
		(end 342.907112 -78.11008)
		(width 0.1143)
		(layer "F.Cu")
		(net "P3E_CPU0_PE1_SS_TXP<1>")
	)
	(segment
		(start 333.709264 -82.7532)
		(end 333.636874 -82.897726)
		(width 0.1143)
		(layer "F.Cu")
		(net "P3E_CPU0_PE1_SS_TXP<1>")
	)
	(segment
		(start 333.636874 -82.897726)
		(end 333.3115 -83.00593)
		(width 0.1143)
		(layer "F.Cu")
		(net "P3E_CPU0_PE1_SS_TXP<1>")
	)
	(segment
		(start 334.577182 -82.46491)
		(end 334.504538 -82.609436)
		(width 0.1143)
		(layer "F.Cu")
		(net "P3E_CPU0_PE1_SS_TXP<1>")
	)
	(segment
		(start 307.250846 -91.565984)
		(end 306.963572 -91.731846)
		(width 0.0889)
		(layer "F.Cu")
		(net "P3E_CPU0_PE1_SS_TXP<1>")
	)
	(segment
		(start 309.938166 -92.042742)
		(end 309.960264 -92.042742)
		(width 0.0889)
		(layer "F.Cu")
		(net "P3E_CPU0_PE1_SS_TXP<1>")
	)
	(segment
		(start 307.608732 -91.86672)
		(end 307.888132 -91.86672)
		(width 0.0889)
		(layer "F.Cu")
		(net "P3E_CPU0_PE1_SS_TXP<1>")
	)
	(segment
		(start 309.960264 -92.042742)
		(end 312.028586 -92.042742)
		(width 0.1143)
		(layer "F.Cu")
		(net "P3E_CPU0_PE1_SS_TXP<1>")
	)
	(segment
		(start 341.71128 -80.815434)
		(end 341.114126 -81.656682)
		(width 0.1143)
		(layer "F.Cu")
		(net "P3E_CPU0_PE1_SS_TXP<1>")
	)
	(segment
		(start 334.504538 -82.609436)
		(end 334.179164 -82.71764)
		(width 0.1143)
		(layer "F.Cu")
		(net "P3E_CPU0_PE1_SS_TXP<1>")
	)
	(segment
		(start 307.888132 -91.86672)
		(end 307.987192 -91.96578)
		(width 0.0889)
		(layer "F.Cu")
		(net "P3E_CPU0_PE1_SS_TXP<1>")
	)
	(segment
		(start 342.301068 -77.91704)
		(end 342.714072 -77.91704)
		(width 0.1143)
		(layer "F.Cu")
		(net "P3E_CPU0_PE1_SS_TXP<1>")
	)
	(segment
		(start 333.166974 -82.93354)
		(end 332.8416 -83.04149)
		(width 0.1143)
		(layer "F.Cu")
		(net "P3E_CPU0_PE1_SS_TXP<1>")
	)
	(segment
		(start 308.266592 -91.96578)
		(end 308.365652 -91.86672)
		(width 0.0889)
		(layer "F.Cu")
		(net "P3E_CPU0_PE1_SS_TXP<1>")
	)
	(segment
		(start 331.973682 -83.32978)
		(end 331.901292 -83.474306)
		(width 0.1143)
		(layer "F.Cu")
		(net "P3E_CPU0_PE1_SS_TXP<1>")
	)
	(segment
		(start 307.230272 -91.96578)
		(end 307.509672 -91.96578)
		(width 0.0889)
		(layer "F.Cu")
		(net "P3E_CPU0_PE1_SS_TXP<1>")
	)
	(segment
		(start 333.3115 -83.00593)
		(end 333.166974 -82.93354)
		(width 0.1143)
		(layer "F.Cu")
		(net "P3E_CPU0_PE1_SS_TXP<1>")
	)
	(segment
		(start 341.9983 -79.555086)
		(end 341.71128 -80.815434)
		(width 0.1143)
		(layer "F.Cu")
		(net "P3E_CPU0_PE1_SS_TXP<1>")
	)
	(segment
		(start 338.450936 -81.610454)
		(end 338.11464 -81.543652)
		(width 0.1143)
		(layer "F.Cu")
		(net "P3E_CPU0_PE1_SS_TXP<1>")
	)
	(segment
		(start 341.113872 -81.656682)
		(end 339.854286 -82.006186)
		(width 0.1143)
		(layer "F.Cu")
		(net "P3E_CPU0_PE1_SS_TXP<1>")
	)
	(segment
		(start 337.980274 -81.633314)
		(end 337.643978 -81.566512)
		(width 0.1143)
		(layer "F.Cu")
		(net "P3E_CPU0_PE1_SS_TXP<1>")
	)
	(segment
		(start 312.028586 -92.042742)
		(end 322.227956 -86.796118)
		(width 0.1143)
		(layer "F.Cu")
		(net "P3E_CPU0_PE1_SS_TXP<1>")
	)
	(segment
		(start 342.58377 -79.241142)
		(end 342.310974 -79.241142)
		(width 0.1143)
		(layer "F.Cu")
		(net "P3E_CPU0_PE1_SS_TXP<1>")
	)
	(segment
		(start 309.306468 -92.068142)
		(end 309.912766 -92.068142)
		(width 0.0889)
		(layer "F.Cu")
		(net "P3E_CPU0_PE1_SS_TXP<1>")
	)
	(segment
		(start 308.645052 -91.86672)
		(end 308.744112 -91.96578)
		(width 0.0889)
		(layer "F.Cu")
		(net "P3E_CPU0_PE1_SS_TXP<1>")
	)
	(segment
		(start 322.820538 -86.491318)
		(end 322.227956 -86.796118)
		(width 0.1143)
		(layer "F.Cu")
		(net "P3E_CPU0_PE1_SS_TXP<1>")
	)
	(segment
		(start 332.76921 -83.186016)
		(end 332.443582 -83.29422)
		(width 0.1143)
		(layer "F.Cu")
		(net "P3E_CPU0_PE1_SS_TXP<1>")
	)
	(segment
		(start 306.963572 -91.731846)
		(end 306.940458 -91.81846)
		(width 0.0889)
		(layer "F.Cu")
		(net "P3E_CPU0_PE1_SS_TXP<1>")
	)
	(segment
		(start 308.365652 -91.86672)
		(end 308.645052 -91.86672)
		(width 0.0889)
		(layer "F.Cu")
		(net "P3E_CPU0_PE1_SS_TXP<1>")
	)
	(segment
		(start 337.643978 -81.566512)
		(end 335.047082 -82.42935)
		(width 0.1143)
		(layer "F.Cu")
		(net "P3E_CPU0_PE1_SS_TXP<1>")
	)
	(segment
		(start 339.854286 -82.006186)
		(end 338.540852 -81.74482)
		(width 0.1143)
		(layer "F.Cu")
		(net "P3E_CPU0_PE1_SS_TXP<1>")
	)
	(segment
		(start 332.29931 -83.22183)
		(end 331.973682 -83.32978)
		(width 0.1143)
		(layer "F.Cu")
		(net "P3E_CPU0_PE1_SS_TXP<1>")
	)
	(segment
		(start 331.901292 -83.474306)
		(end 322.820538 -86.491318)
		(width 0.1143)
		(layer "F.Cu")
		(net "P3E_CPU0_PE1_SS_TXP<1>")
	)
	(segment
		(start 342.907112 -78.9178)
		(end 342.58377 -79.241142)
		(width 0.1143)
		(layer "F.Cu")
		(net "P3E_CPU0_PE1_SS_TXP<1>")
	)
	(segment
		(start 342.907112 -78.11008)
		(end 342.907112 -78.9178)
		(width 0.1143)
		(layer "F.Cu")
		(net "P3E_CPU0_PE1_SS_TXP<1>")
	)
	(segment
		(start 341.114126 -81.656682)
		(end 341.113872 -81.656682)
		(width 0.1143)
		(layer "F.Cu")
		(net "P3E_CPU0_PE1_SS_TXP<1>")
	)
	(segment
		(start 338.11464 -81.543652)
		(end 337.980274 -81.633314)
		(width 0.1143)
		(layer "F.Cu")
		(net "P3E_CPU0_PE1_SS_TXP<1>")
	)
	(segment
		(start 332.8416 -83.04149)
		(end 332.76921 -83.186016)
		(width 0.1143)
		(layer "F.Cu")
		(net "P3E_CPU0_PE1_SS_TXP<1>")
	)
	(segment
		(start 307.987192 -91.96578)
		(end 308.266592 -91.96578)
		(width 0.0889)
		(layer "F.Cu")
		(net "P3E_CPU0_PE1_SS_TXP<1>")
	)
	(segment
		(start 334.034638 -82.64525)
		(end 333.709264 -82.7532)
		(width 0.1143)
		(layer "F.Cu")
		(net "P3E_CPU0_PE1_SS_TXP<1>")
	)
	(segment
		(start 342.310974 -79.241142)
		(end 341.9983 -79.555086)
		(width 0.1143)
		(layer "F.Cu")
		(net "P3E_CPU0_PE1_SS_TXP<1>")
	)
	(segment
		(start 335.047082 -82.42935)
		(end 334.902556 -82.35696)
		(width 0.1143)
		(layer "F.Cu")
		(net "P3E_CPU0_PE1_SS_TXP<1>")
	)
	(segment
		(start 307.509672 -91.96578)
		(end 307.608732 -91.86672)
		(width 0.0889)
		(layer "F.Cu")
		(net "P3E_CPU0_PE1_SS_TXP<1>")
	)
	(segment
		(start 309.912766 -92.068142)
		(end 309.938166 -92.042742)
		(width 0.0889)
		(layer "F.Cu")
		(net "P3E_CPU0_PE1_SS_TXP<1>")
	)
	(via
		(at 342.301068 -77.91704)
		(size 0.508)
		(drill 0.254)
		(layers "F.Cu" "B.Cu")
		(net "P3E_CPU0_PE1_SS_TXP<1>")
	)
	(via
		(at 322.227956 -86.796118)
		(size 0.508)
		(drill 0.254)
		(layers "F.Cu" "B.Cu")
		(net "P3E_CPU0_PE1_SS_TXP<1>")
	)
	(arc
		(start 306.940458 -91.81846)
		(mid 307.069741 -91.922848)
		(end 307.230272 -91.96578)
		(width 0.0889)
		(layer "F.Cu")
		(net "P3E_CPU0_PE1_SS_TXP<1>")
	)
	(segment
		(start 342.301068 -77.910436)
		(end 342.301068 -77.91704)
		(width 0.1143)
		(layer "B.Cu")
		(net "P3E_CPU0_PE1_SS_TXP<1>")
	)
	(segment
		(start 341.666068 -77.694536)
		(end 342.085168 -77.694536)
		(width 0.1143)
		(layer "B.Cu")
		(net "P3E_CPU0_PE1_SS_TXP<1>")
	)
	(segment
		(start 342.085168 -77.694536)
		(end 342.301068 -77.910436)
		(width 0.1143)
		(layer "B.Cu")
		(net "P3E_CPU0_PE1_SS_TXP<1>")
	)
	(segment
		(start 336.820256 -79.461614)
		(end 336.88274 -79.312516)
		(width 0.1143)
		(layer "F.Cu")
		(net "P3E_CPU0_PE1_SS_TXP<0>")
	)
	(segment
		(start 307.85435 -91.094814)
		(end 307.73497 -90.975434)
		(width 0.0889)
		(layer "F.Cu")
		(net "P3E_CPU0_PE1_SS_TXP<0>")
	)
	(segment
		(start 306.464462 -90.484198)
		(end 306.392326 -90.412062)
		(width 0.0889)
		(layer "F.Cu")
		(net "P3E_CPU0_PE1_SS_TXP<0>")
	)
	(segment
		(start 336.354166 -79.52994)
		(end 336.503264 -79.59217)
		(width 0.1143)
		(layer "F.Cu")
		(net "P3E_CPU0_PE1_SS_TXP<0>")
	)
	(segment
		(start 335.12887 -80.157066)
		(end 335.1911 -80.007968)
		(width 0.1143)
		(layer "F.Cu")
		(net "P3E_CPU0_PE1_SS_TXP<0>")
	)
	(segment
		(start 334.811878 -80.287368)
		(end 335.12887 -80.157066)
		(width 0.1143)
		(layer "F.Cu")
		(net "P3E_CPU0_PE1_SS_TXP<0>")
	)
	(segment
		(start 334.283304 -80.504792)
		(end 334.345534 -80.355694)
		(width 0.1143)
		(layer "F.Cu")
		(net "P3E_CPU0_PE1_SS_TXP<0>")
	)
	(segment
		(start 335.657444 -79.939896)
		(end 335.97469 -79.80934)
		(width 0.1143)
		(layer "F.Cu")
		(net "P3E_CPU0_PE1_SS_TXP<0>")
	)
	(segment
		(start 335.1911 -80.007968)
		(end 335.508346 -79.877412)
		(width 0.1143)
		(layer "F.Cu")
		(net "P3E_CPU0_PE1_SS_TXP<0>")
	)
	(segment
		(start 309.188358 -91.069414)
		(end 309.162958 -91.094814)
		(width 0.0889)
		(layer "F.Cu")
		(net "P3E_CPU0_PE1_SS_TXP<0>")
	)
	(segment
		(start 339.594952 -79.190088)
		(end 339.967316 -78.817724)
		(width 0.1143)
		(layer "F.Cu")
		(net "P3E_CPU0_PE1_SS_TXP<0>")
	)
	(segment
		(start 307.73497 -90.975434)
		(end 307.23586 -90.975434)
		(width 0.0889)
		(layer "F.Cu")
		(net "P3E_CPU0_PE1_SS_TXP<0>")
	)
	(segment
		(start 337.89493 -79.019908)
		(end 339.320124 -79.305404)
		(width 0.1143)
		(layer "F.Cu")
		(net "P3E_CPU0_PE1_SS_TXP<0>")
	)
	(segment
		(start 334.662526 -80.225138)
		(end 334.811878 -80.287368)
		(width 0.1143)
		(layer "F.Cu")
		(net "P3E_CPU0_PE1_SS_TXP<0>")
	)
	(segment
		(start 335.508346 -79.877412)
		(end 335.657444 -79.939896)
		(width 0.1143)
		(layer "F.Cu")
		(net "P3E_CPU0_PE1_SS_TXP<0>")
	)
	(segment
		(start 337.199732 -79.182214)
		(end 337.34883 -79.244444)
		(width 0.1143)
		(layer "F.Cu")
		(net "P3E_CPU0_PE1_SS_TXP<0>")
	)
	(segment
		(start 311.500266 -91.069414)
		(end 309.210456 -91.069414)
		(width 0.1143)
		(layer "F.Cu")
		(net "P3E_CPU0_PE1_SS_TXP<0>")
	)
	(segment
		(start 336.503264 -79.59217)
		(end 336.820256 -79.461614)
		(width 0.1143)
		(layer "F.Cu")
		(net "P3E_CPU0_PE1_SS_TXP<0>")
	)
	(segment
		(start 339.967316 -78.817724)
		(end 339.967316 -78.015846)
		(width 0.1143)
		(layer "F.Cu")
		(net "P3E_CPU0_PE1_SS_TXP<0>")
	)
	(segment
		(start 334.345534 -80.355694)
		(end 334.662526 -80.225138)
		(width 0.1143)
		(layer "F.Cu")
		(net "P3E_CPU0_PE1_SS_TXP<0>")
	)
	(segment
		(start 321.56527 -85.733636)
		(end 311.500266 -91.069414)
		(width 0.1143)
		(layer "F.Cu")
		(net "P3E_CPU0_PE1_SS_TXP<0>")
	)
	(segment
		(start 339.86851 -77.91704)
		(end 339.40496 -77.91704)
		(width 0.1143)
		(layer "F.Cu")
		(net "P3E_CPU0_PE1_SS_TXP<0>")
	)
	(segment
		(start 323.773546 -84.825586)
		(end 334.283304 -80.504792)
		(width 0.1143)
		(layer "F.Cu")
		(net "P3E_CPU0_PE1_SS_TXP<0>")
	)
	(segment
		(start 335.97469 -79.80934)
		(end 336.03692 -79.660242)
		(width 0.1143)
		(layer "F.Cu")
		(net "P3E_CPU0_PE1_SS_TXP<0>")
	)
	(segment
		(start 323.773546 -84.825586)
		(end 321.56527 -85.733636)
		(width 0.1143)
		(layer "F.Cu")
		(net "P3E_CPU0_PE1_SS_TXP<0>")
	)
	(segment
		(start 306.392326 -90.412062)
		(end 306.392326 -90.080338)
		(width 0.0889)
		(layer "F.Cu")
		(net "P3E_CPU0_PE1_SS_TXP<0>")
	)
	(segment
		(start 309.210456 -91.069414)
		(end 309.188358 -91.069414)
		(width 0.0889)
		(layer "F.Cu")
		(net "P3E_CPU0_PE1_SS_TXP<0>")
	)
	(segment
		(start 339.320124 -79.305404)
		(end 339.594952 -79.190088)
		(width 0.1143)
		(layer "F.Cu")
		(net "P3E_CPU0_PE1_SS_TXP<0>")
	)
	(segment
		(start 337.34883 -79.244444)
		(end 337.89493 -79.019908)
		(width 0.1143)
		(layer "F.Cu")
		(net "P3E_CPU0_PE1_SS_TXP<0>")
	)
	(segment
		(start 309.162958 -91.094814)
		(end 307.85435 -91.094814)
		(width 0.0889)
		(layer "F.Cu")
		(net "P3E_CPU0_PE1_SS_TXP<0>")
	)
	(segment
		(start 336.03692 -79.660242)
		(end 336.354166 -79.52994)
		(width 0.1143)
		(layer "F.Cu")
		(net "P3E_CPU0_PE1_SS_TXP<0>")
	)
	(segment
		(start 339.967316 -78.015846)
		(end 339.86851 -77.91704)
		(width 0.1143)
		(layer "F.Cu")
		(net "P3E_CPU0_PE1_SS_TXP<0>")
	)
	(segment
		(start 336.88274 -79.312516)
		(end 337.199732 -79.182214)
		(width 0.1143)
		(layer "F.Cu")
		(net "P3E_CPU0_PE1_SS_TXP<0>")
	)
	(via
		(at 339.40496 -77.91704)
		(size 0.508)
		(drill 0.254)
		(layers "F.Cu" "B.Cu")
		(net "P3E_CPU0_PE1_SS_TXP<0>")
	)
	(via
		(at 323.773546 -84.825586)
		(size 0.508)
		(drill 0.254)
		(layers "F.Cu" "B.Cu")
		(net "P3E_CPU0_PE1_SS_TXP<0>")
	)
	(arc
		(start 307.23586 -90.975434)
		(mid 307.044218 -90.918268)
		(end 306.904136 -90.775536)
		(width 0.0889)
		(layer "F.Cu")
		(net "P3E_CPU0_PE1_SS_TXP<0>")
	)
	(arc
		(start 306.486306 -90.487246)
		(mid 306.475398 -90.485622)
		(end 306.464462 -90.484198)
		(width 0.0889)
		(layer "F.Cu")
		(net "P3E_CPU0_PE1_SS_TXP<0>")
	)
	(arc
		(start 306.904136 -90.775536)
		(mid 306.727756 -90.584229)
		(end 306.486306 -90.487246)
		(width 0.0889)
		(layer "F.Cu")
		(net "P3E_CPU0_PE1_SS_TXP<0>")
	)
	(segment
		(start 338.76996 -77.694536)
		(end 339.18906 -77.694536)
		(width 0.1143)
		(layer "B.Cu")
		(net "P3E_CPU0_PE1_SS_TXP<0>")
	)
	(segment
		(start 339.40496 -77.910436)
		(end 339.40496 -77.91704)
		(width 0.1143)
		(layer "B.Cu")
		(net "P3E_CPU0_PE1_SS_TXP<0>")
	)
	(segment
		(start 339.18906 -77.694536)
		(end 339.40496 -77.910436)
		(width 0.1143)
		(layer "B.Cu")
		(net "P3E_CPU0_PE1_SS_TXP<0>")
	)
	(segment
		(start 330.45527 -94.224094)
		(end 330.296774 -94.192598)
		(width 0.1143)
		(layer "F.Cu")
		(net "P3E_CPU0_PE1_SS_TXN<7>")
	)
	(segment
		(start 326.809608 -100.255324)
		(end 320.598038 -104.741726)
		(width 0.1143)
		(layer "F.Cu")
		(net "P3E_CPU0_PE1_SS_TXN<7>")
	)
	(segment
		(start 331.818742 -93.178376)
		(end 331.533246 -93.368368)
		(width 0.1143)
		(layer "F.Cu")
		(net "P3E_CPU0_PE1_SS_TXN<7>")
	)
	(segment
		(start 307.92039 -97.414588)
		(end 306.38115 -97.414588)
		(width 0.0889)
		(layer "F.Cu")
		(net "P3E_CPU0_PE1_SS_TXN<7>")
	)
	(segment
		(start 330.772262 -93.875606)
		(end 330.740766 -94.034102)
		(width 0.1143)
		(layer "F.Cu")
		(net "P3E_CPU0_PE1_SS_TXN<7>")
	)
	(segment
		(start 328.631296 -95.439738)
		(end 328.023474 -97.04705)
		(width 0.1143)
		(layer "F.Cu")
		(net "P3E_CPU0_PE1_SS_TXN<7>")
	)
	(segment
		(start 356.540816 -89.25179)
		(end 356.135178 -89.859866)
		(width 0.1143)
		(layer "F.Cu")
		(net "P3E_CPU0_PE1_SS_TXN<7>")
	)
	(segment
		(start 317.358776 -105.461816)
		(end 315.280802 -104.91851)
		(width 0.1143)
		(layer "F.Cu")
		(net "P3E_CPU0_PE1_SS_TXN<7>")
	)
	(segment
		(start 313.309508 -103.502206)
		(end 310.849518 -98.454718)
		(width 0.1143)
		(layer "F.Cu")
		(net "P3E_CPU0_PE1_SS_TXN<7>")
	)
	(segment
		(start 328.023474 -97.04705)
		(end 326.809608 -100.255324)
		(width 0.1143)
		(layer "F.Cu")
		(net "P3E_CPU0_PE1_SS_TXN<7>")
	)
	(segment
		(start 308.895496 -97.913698)
		(end 308.873398 -97.913698)
		(width 0.0889)
		(layer "F.Cu")
		(net "P3E_CPU0_PE1_SS_TXN<7>")
	)
	(segment
		(start 329.250548 -94.889828)
		(end 329.218798 -95.048324)
		(width 0.1143)
		(layer "F.Cu")
		(net "P3E_CPU0_PE1_SS_TXN<7>")
	)
	(segment
		(start 358.931718 -86.042754)
		(end 356.540816 -88.433656)
		(width 0.1143)
		(layer "F.Cu")
		(net "P3E_CPU0_PE1_SS_TXN<7>")
	)
	(segment
		(start 332.188312 -93.069664)
		(end 331.977238 -93.210126)
		(width 0.1143)
		(layer "F.Cu")
		(net "P3E_CPU0_PE1_SS_TXN<7>")
	)
	(segment
		(start 329.53579 -94.699582)
		(end 329.250548 -94.889828)
		(width 0.1143)
		(layer "F.Cu")
		(net "P3E_CPU0_PE1_SS_TXN<7>")
	)
	(segment
		(start 332.533752 -92.98559)
		(end 332.188312 -93.069664)
		(width 0.1143)
		(layer "F.Cu")
		(net "P3E_CPU0_PE1_SS_TXN<7>")
	)
	(segment
		(start 329.694286 -94.731332)
		(end 329.53579 -94.699582)
		(width 0.1143)
		(layer "F.Cu")
		(net "P3E_CPU0_PE1_SS_TXN<7>")
	)
	(segment
		(start 331.501496 -93.526864)
		(end 331.216254 -93.71711)
		(width 0.1143)
		(layer "F.Cu")
		(net "P3E_CPU0_PE1_SS_TXN<7>")
	)
	(segment
		(start 330.296774 -94.192598)
		(end 330.011532 -94.38259)
		(width 0.1143)
		(layer "F.Cu")
		(net "P3E_CPU0_PE1_SS_TXN<7>")
	)
	(segment
		(start 337.399122 -91.80068)
		(end 333.121254 -92.842588)
		(width 0.1143)
		(layer "F.Cu")
		(net "P3E_CPU0_PE1_SS_TXN<7>")
	)
	(segment
		(start 359.67797 -78.253844)
		(end 359.678478 -78.330552)
		(width 0.1143)
		(layer "F.Cu")
		(net "P3E_CPU0_PE1_SS_TXN<7>")
	)
	(segment
		(start 359.08488 -78.139036)
		(end 359.558844 -78.135734)
		(width 0.1143)
		(layer "F.Cu")
		(net "P3E_CPU0_PE1_SS_TXN<7>")
	)
	(segment
		(start 329.979782 -94.541086)
		(end 329.694286 -94.731332)
		(width 0.1143)
		(layer "F.Cu")
		(net "P3E_CPU0_PE1_SS_TXN<7>")
	)
	(segment
		(start 359.678224 -78.340458)
		(end 359.678986 -78.412086)
		(width 0.1143)
		(layer "F.Cu")
		(net "P3E_CPU0_PE1_SS_TXN<7>")
	)
	(segment
		(start 359.678986 -78.412086)
		(end 359.678986 -81.467706)
		(width 0.1143)
		(layer "F.Cu")
		(net "P3E_CPU0_PE1_SS_TXN<7>")
	)
	(segment
		(start 332.625192 -92.835222)
		(end 332.533752 -92.98559)
		(width 0.1143)
		(layer "F.Cu")
		(net "P3E_CPU0_PE1_SS_TXN<7>")
	)
	(segment
		(start 341.634318 -91.992958)
		(end 340.040976 -92.329)
		(width 0.1143)
		(layer "F.Cu")
		(net "P3E_CPU0_PE1_SS_TXN<7>")
	)
	(segment
		(start 354.471986 -90.971116)
		(end 352.064574 -90.489278)
		(width 0.1143)
		(layer "F.Cu")
		(net "P3E_CPU0_PE1_SS_TXN<7>")
	)
	(segment
		(start 331.216254 -93.71711)
		(end 331.057758 -93.68536)
		(width 0.1143)
		(layer "F.Cu")
		(net "P3E_CPU0_PE1_SS_TXN<7>")
	)
	(segment
		(start 359.558844 -78.135734)
		(end 359.67797 -78.253844)
		(width 0.1143)
		(layer "F.Cu")
		(net "P3E_CPU0_PE1_SS_TXN<7>")
	)
	(segment
		(start 352.064574 -90.489278)
		(end 348.461838 -91.208352)
		(width 0.1143)
		(layer "F.Cu")
		(net "P3E_CPU0_PE1_SS_TXN<7>")
	)
	(segment
		(start 359.678986 -81.467706)
		(end 358.931718 -82.214974)
		(width 0.1143)
		(layer "F.Cu")
		(net "P3E_CPU0_PE1_SS_TXN<7>")
	)
	(segment
		(start 331.977238 -93.210126)
		(end 331.818742 -93.178376)
		(width 0.1143)
		(layer "F.Cu")
		(net "P3E_CPU0_PE1_SS_TXN<7>")
	)
	(segment
		(start 331.057758 -93.68536)
		(end 330.772262 -93.875606)
		(width 0.1143)
		(layer "F.Cu")
		(net "P3E_CPU0_PE1_SS_TXN<7>")
	)
	(segment
		(start 348.461838 -91.208352)
		(end 344.579956 -90.431112)
		(width 0.1143)
		(layer "F.Cu")
		(net "P3E_CPU0_PE1_SS_TXN<7>")
	)
	(segment
		(start 359.678224 -78.330552)
		(end 359.678224 -78.340458)
		(width 0.1143)
		(layer "F.Cu")
		(net "P3E_CPU0_PE1_SS_TXN<7>")
	)
	(segment
		(start 329.218798 -95.048324)
		(end 328.631296 -95.439738)
		(width 0.1143)
		(layer "F.Cu")
		(net "P3E_CPU0_PE1_SS_TXN<7>")
	)
	(segment
		(start 330.011532 -94.38259)
		(end 329.979782 -94.541086)
		(width 0.1143)
		(layer "F.Cu")
		(net "P3E_CPU0_PE1_SS_TXN<7>")
	)
	(segment
		(start 333.121254 -92.842588)
		(end 332.970886 -92.750894)
		(width 0.1143)
		(layer "F.Cu")
		(net "P3E_CPU0_PE1_SS_TXN<7>")
	)
	(segment
		(start 359.678478 -78.330552)
		(end 359.678224 -78.330552)
		(width 0.1143)
		(layer "F.Cu")
		(net "P3E_CPU0_PE1_SS_TXN<7>")
	)
	(segment
		(start 331.533246 -93.368368)
		(end 331.501496 -93.526864)
		(width 0.1143)
		(layer "F.Cu")
		(net "P3E_CPU0_PE1_SS_TXN<7>")
	)
	(segment
		(start 356.540816 -88.433656)
		(end 356.540816 -89.25179)
		(width 0.1143)
		(layer "F.Cu")
		(net "P3E_CPU0_PE1_SS_TXN<7>")
	)
	(segment
		(start 340.040976 -92.329)
		(end 337.399122 -91.80068)
		(width 0.1143)
		(layer "F.Cu")
		(net "P3E_CPU0_PE1_SS_TXN<7>")
	)
	(segment
		(start 315.280802 -104.91851)
		(end 313.309508 -103.502206)
		(width 0.1143)
		(layer "F.Cu")
		(net "P3E_CPU0_PE1_SS_TXN<7>")
	)
	(segment
		(start 308.847998 -97.939098)
		(end 308.4449 -97.939098)
		(width 0.0889)
		(layer "F.Cu")
		(net "P3E_CPU0_PE1_SS_TXN<7>")
	)
	(segment
		(start 308.4449 -97.939098)
		(end 307.92039 -97.414588)
		(width 0.0889)
		(layer "F.Cu")
		(net "P3E_CPU0_PE1_SS_TXN<7>")
	)
	(segment
		(start 308.873398 -97.913698)
		(end 308.847998 -97.939098)
		(width 0.0889)
		(layer "F.Cu")
		(net "P3E_CPU0_PE1_SS_TXN<7>")
	)
	(segment
		(start 320.598038 -104.741726)
		(end 317.358776 -105.461816)
		(width 0.1143)
		(layer "F.Cu")
		(net "P3E_CPU0_PE1_SS_TXN<7>")
	)
	(segment
		(start 356.135178 -89.859866)
		(end 354.471986 -90.971116)
		(width 0.1143)
		(layer "F.Cu")
		(net "P3E_CPU0_PE1_SS_TXN<7>")
	)
	(segment
		(start 358.931718 -82.214974)
		(end 358.931718 -86.042754)
		(width 0.1143)
		(layer "F.Cu")
		(net "P3E_CPU0_PE1_SS_TXN<7>")
	)
	(segment
		(start 343.72169 -90.602054)
		(end 341.634318 -91.992958)
		(width 0.1143)
		(layer "F.Cu")
		(net "P3E_CPU0_PE1_SS_TXN<7>")
	)
	(segment
		(start 310.849518 -98.454718)
		(end 309.61711 -97.913698)
		(width 0.1143)
		(layer "F.Cu")
		(net "P3E_CPU0_PE1_SS_TXN<7>")
	)
	(segment
		(start 330.740766 -94.034102)
		(end 330.45527 -94.224094)
		(width 0.1143)
		(layer "F.Cu")
		(net "P3E_CPU0_PE1_SS_TXN<7>")
	)
	(segment
		(start 332.970886 -92.750894)
		(end 332.625192 -92.835222)
		(width 0.1143)
		(layer "F.Cu")
		(net "P3E_CPU0_PE1_SS_TXN<7>")
	)
	(segment
		(start 309.61711 -97.913698)
		(end 308.895496 -97.913698)
		(width 0.1143)
		(layer "F.Cu")
		(net "P3E_CPU0_PE1_SS_TXN<7>")
	)
	(segment
		(start 344.579956 -90.431112)
		(end 343.72169 -90.602054)
		(width 0.1143)
		(layer "F.Cu")
		(net "P3E_CPU0_PE1_SS_TXN<7>")
	)
	(via
		(at 359.08488 -78.139036)
		(size 0.508)
		(drill 0.254)
		(layers "F.Cu" "B.Cu")
		(net "P3E_CPU0_PE1_SS_TXN<7>")
	)
	(via
		(at 328.023474 -97.04705)
		(size 0.508)
		(drill 0.254)
		(layers "F.Cu" "B.Cu")
		(net "P3E_CPU0_PE1_SS_TXN<7>")
	)
	(arc
		(start 305.551586 -96.919034)
		(mid 305.110119 -96.936355)
		(end 304.675286 -97.014538)
		(width 0.0889)
		(layer "F.Cu")
		(net "P3E_CPU0_PE1_SS_TXN<7>")
	)
	(arc
		(start 306.38115 -97.414588)
		(mid 306.1873 -97.358238)
		(end 306.045616 -97.214436)
		(width 0.0889)
		(layer "F.Cu")
		(net "P3E_CPU0_PE1_SS_TXN<7>")
	)
	(arc
		(start 306.045616 -97.214436)
		(mid 305.837008 -97.002504)
		(end 305.551586 -96.919034)
		(width 0.0889)
		(layer "F.Cu")
		(net "P3E_CPU0_PE1_SS_TXN<7>")
	)
	(segment
		(start 358.44988 -77.923136)
		(end 358.86898 -77.923136)
		(width 0.1143)
		(layer "B.Cu")
		(net "P3E_CPU0_PE1_SS_TXN<7>")
	)
	(segment
		(start 358.86898 -77.923136)
		(end 359.08488 -78.139036)
		(width 0.1143)
		(layer "B.Cu")
		(net "P3E_CPU0_PE1_SS_TXN<7>")
	)
	(segment
		(start 328.227182 -94.427548)
		(end 332.848966 -91.344496)
		(width 0.1143)
		(layer "F.Cu")
		(net "P3E_CPU0_PE1_SS_TXN<6>")
	)
	(segment
		(start 317.40094 -104.687878)
		(end 315.525912 -104.191562)
		(width 0.1143)
		(layer "F.Cu")
		(net "P3E_CPU0_PE1_SS_TXN<6>")
	)
	(segment
		(start 356.08895 -85.999828)
		(end 356.571296 -85.517482)
		(width 0.1143)
		(layer "F.Cu")
		(net "P3E_CPU0_PE1_SS_TXN<6>")
	)
	(segment
		(start 308.81193 -97.175066)
		(end 308.789832 -97.175066)
		(width 0.0889)
		(layer "F.Cu")
		(net "P3E_CPU0_PE1_SS_TXN<6>")
	)
	(segment
		(start 306.719732 -96.5835)
		(end 306.688744 -96.614488)
		(width 0.0889)
		(layer "F.Cu")
		(net "P3E_CPU0_PE1_SS_TXN<6>")
	)
	(segment
		(start 326.597518 -98.734118)
		(end 326.224138 -99.721162)
		(width 0.1143)
		(layer "F.Cu")
		(net "P3E_CPU0_PE1_SS_TXN<6>")
	)
	(segment
		(start 341.57412 -90.757502)
		(end 342.878156 -89.88806)
		(width 0.1143)
		(layer "F.Cu")
		(net "P3E_CPU0_PE1_SS_TXN<6>")
	)
	(segment
		(start 306.688744 -96.614488)
		(end 306.374546 -96.614488)
		(width 0.0889)
		(layer "F.Cu")
		(net "P3E_CPU0_PE1_SS_TXN<6>")
	)
	(segment
		(start 335.660746 -91.401392)
		(end 337.409536 -91.032838)
		(width 0.1143)
		(layer "F.Cu")
		(net "P3E_CPU0_PE1_SS_TXN<6>")
	)
	(segment
		(start 356.571296 -85.517482)
		(end 356.571296 -82.610452)
		(width 0.1143)
		(layer "F.Cu")
		(net "P3E_CPU0_PE1_SS_TXN<6>")
	)
	(segment
		(start 326.942704 -97.822258)
		(end 327.248012 -97.0153)
		(width 0.1143)
		(layer "F.Cu")
		(net "P3E_CPU0_PE1_SS_TXN<6>")
	)
	(segment
		(start 326.224138 -99.721162)
		(end 322.402454 -102.483412)
		(width 0.1143)
		(layer "F.Cu")
		(net "P3E_CPU0_PE1_SS_TXN<6>")
	)
	(segment
		(start 311.409842 -97.84588)
		(end 309.881778 -97.175066)
		(width 0.1143)
		(layer "F.Cu")
		(net "P3E_CPU0_PE1_SS_TXN<6>")
	)
	(segment
		(start 352.092006 -89.733882)
		(end 354.220272 -90.159586)
		(width 0.1143)
		(layer "F.Cu")
		(net "P3E_CPU0_PE1_SS_TXN<6>")
	)
	(segment
		(start 308.789832 -97.175066)
		(end 308.764432 -97.149666)
		(width 0.0889)
		(layer "F.Cu")
		(net "P3E_CPU0_PE1_SS_TXN<6>")
	)
	(segment
		(start 355.415596 -89.36101)
		(end 356.08895 -85.999828)
		(width 0.1143)
		(layer "F.Cu")
		(net "P3E_CPU0_PE1_SS_TXN<6>")
	)
	(segment
		(start 315.525912 -104.191562)
		(end 313.951366 -103.059738)
		(width 0.1143)
		(layer "F.Cu")
		(net "P3E_CPU0_PE1_SS_TXN<6>")
	)
	(segment
		(start 308.764432 -97.149666)
		(end 308.285388 -97.149666)
		(width 0.0889)
		(layer "F.Cu")
		(net "P3E_CPU0_PE1_SS_TXN<6>")
	)
	(segment
		(start 342.878156 -89.88806)
		(end 344.511122 -89.561162)
		(width 0.1143)
		(layer "F.Cu")
		(net "P3E_CPU0_PE1_SS_TXN<6>")
	)
	(segment
		(start 356.571296 -82.610452)
		(end 357.190548 -81.9912)
		(width 0.1143)
		(layer "F.Cu")
		(net "P3E_CPU0_PE1_SS_TXN<6>")
	)
	(segment
		(start 337.409536 -91.032838)
		(end 338.805012 -91.311476)
		(width 0.1143)
		(layer "F.Cu")
		(net "P3E_CPU0_PE1_SS_TXN<6>")
	)
	(segment
		(start 357.190548 -81.9912)
		(end 357.190548 -78.25232)
		(width 0.1143)
		(layer "F.Cu")
		(net "P3E_CPU0_PE1_SS_TXN<6>")
	)
	(segment
		(start 354.220272 -90.159586)
		(end 355.415596 -89.36101)
		(width 0.1143)
		(layer "F.Cu")
		(net "P3E_CPU0_PE1_SS_TXN<6>")
	)
	(segment
		(start 348.72803 -90.405204)
		(end 352.092006 -89.733882)
		(width 0.1143)
		(layer "F.Cu")
		(net "P3E_CPU0_PE1_SS_TXN<6>")
	)
	(segment
		(start 308.285388 -97.149666)
		(end 307.719222 -96.5835)
		(width 0.0889)
		(layer "F.Cu")
		(net "P3E_CPU0_PE1_SS_TXN<6>")
	)
	(segment
		(start 322.402454 -102.483412)
		(end 320.214752 -104.064562)
		(width 0.1143)
		(layer "F.Cu")
		(net "P3E_CPU0_PE1_SS_TXN<6>")
	)
	(segment
		(start 338.805012 -91.311476)
		(end 341.57412 -90.757502)
		(width 0.1143)
		(layer "F.Cu")
		(net "P3E_CPU0_PE1_SS_TXN<6>")
	)
	(segment
		(start 357.304848 -78.13802)
		(end 357.768398 -78.13802)
		(width 0.1143)
		(layer "F.Cu")
		(net "P3E_CPU0_PE1_SS_TXN<6>")
	)
	(segment
		(start 320.214752 -104.064562)
		(end 317.40094 -104.687878)
		(width 0.1143)
		(layer "F.Cu")
		(net "P3E_CPU0_PE1_SS_TXN<6>")
	)
	(segment
		(start 307.719222 -96.5835)
		(end 306.719732 -96.5835)
		(width 0.0889)
		(layer "F.Cu")
		(net "P3E_CPU0_PE1_SS_TXN<6>")
	)
	(segment
		(start 309.881778 -97.175066)
		(end 308.81193 -97.175066)
		(width 0.1143)
		(layer "F.Cu")
		(net "P3E_CPU0_PE1_SS_TXN<6>")
	)
	(segment
		(start 332.848966 -91.344496)
		(end 334.078326 -91.084908)
		(width 0.1143)
		(layer "F.Cu")
		(net "P3E_CPU0_PE1_SS_TXN<6>")
	)
	(segment
		(start 334.078326 -91.084908)
		(end 335.660746 -91.401392)
		(width 0.1143)
		(layer "F.Cu")
		(net "P3E_CPU0_PE1_SS_TXN<6>")
	)
	(segment
		(start 327.248012 -97.0153)
		(end 328.227182 -94.427548)
		(width 0.1143)
		(layer "F.Cu")
		(net "P3E_CPU0_PE1_SS_TXN<6>")
	)
	(segment
		(start 326.942704 -97.822258)
		(end 326.597518 -98.734118)
		(width 0.1143)
		(layer "F.Cu")
		(net "P3E_CPU0_PE1_SS_TXN<6>")
	)
	(segment
		(start 344.511122 -89.561162)
		(end 348.72803 -90.405204)
		(width 0.1143)
		(layer "F.Cu")
		(net "P3E_CPU0_PE1_SS_TXN<6>")
	)
	(segment
		(start 313.951366 -103.059738)
		(end 311.409842 -97.84588)
		(width 0.1143)
		(layer "F.Cu")
		(net "P3E_CPU0_PE1_SS_TXN<6>")
	)
	(segment
		(start 357.190548 -78.25232)
		(end 357.304848 -78.13802)
		(width 0.1143)
		(layer "F.Cu")
		(net "P3E_CPU0_PE1_SS_TXN<6>")
	)
	(via
		(at 357.768398 -78.13802)
		(size 0.508)
		(drill 0.254)
		(layers "F.Cu" "B.Cu")
		(net "P3E_CPU0_PE1_SS_TXN<6>")
	)
	(via
		(at 326.942704 -97.822258)
		(size 0.508)
		(drill 0.254)
		(layers "F.Cu" "B.Cu")
		(net "P3E_CPU0_PE1_SS_TXN<6>")
	)
	(arc
		(start 306.374546 -96.614488)
		(mid 305.951473 -96.590535)
		(end 305.533806 -96.518984)
		(width 0.0889)
		(layer "F.Cu")
		(net "P3E_CPU0_PE1_SS_TXN<6>")
	)
	(segment
		(start 357.552498 -77.915516)
		(end 357.768398 -78.131416)
		(width 0.1143)
		(layer "B.Cu")
		(net "P3E_CPU0_PE1_SS_TXN<6>")
	)
	(segment
		(start 357.768398 -78.131416)
		(end 357.768398 -78.13802)
		(width 0.1143)
		(layer "B.Cu")
		(net "P3E_CPU0_PE1_SS_TXN<6>")
	)
	(segment
		(start 357.133398 -77.915516)
		(end 357.552498 -77.915516)
		(width 0.1143)
		(layer "B.Cu")
		(net "P3E_CPU0_PE1_SS_TXN<6>")
	)
	(segment
		(start 314.73394 -102.415848)
		(end 315.953902 -103.292148)
		(width 0.1143)
		(layer "F.Cu")
		(net "P3E_CPU0_PE1_SS_TXN<5>")
	)
	(segment
		(start 309.30977 -96.208088)
		(end 310.13908 -96.208088)
		(width 0.1143)
		(layer "F.Cu")
		(net "P3E_CPU0_PE1_SS_TXN<5>")
	)
	(segment
		(start 310.13908 -96.208088)
		(end 312.136536 -97.08515)
		(width 0.1143)
		(layer "F.Cu")
		(net "P3E_CPU0_PE1_SS_TXN<5>")
	)
	(segment
		(start 308.401466 -95.897954)
		(end 308.6862 -96.182688)
		(width 0.0889)
		(layer "F.Cu")
		(net "P3E_CPU0_PE1_SS_TXN<5>")
	)
	(segment
		(start 325.42099 -99.080828)
		(end 325.732648 -98.256852)
		(width 0.1143)
		(layer "F.Cu")
		(net "P3E_CPU0_PE1_SS_TXN<5>")
	)
	(segment
		(start 354.42144 -78.25232)
		(end 354.42144 -79.463392)
		(width 0.1143)
		(layer "F.Cu")
		(net "P3E_CPU0_PE1_SS_TXN<5>")
	)
	(segment
		(start 354.53574 -78.13802)
		(end 354.42144 -78.25232)
		(width 0.1143)
		(layer "F.Cu")
		(net "P3E_CPU0_PE1_SS_TXN<5>")
	)
	(segment
		(start 340.742016 -89.923874)
		(end 338.933028 -90.285824)
		(width 0.1143)
		(layer "F.Cu")
		(net "P3E_CPU0_PE1_SS_TXN<5>")
	)
	(segment
		(start 344.708988 -88.19515)
		(end 342.746076 -88.587834)
		(width 0.1143)
		(layer "F.Cu")
		(net "P3E_CPU0_PE1_SS_TXN<5>")
	)
	(segment
		(start 338.933028 -90.285824)
		(end 337.521296 -90.00363)
		(width 0.1143)
		(layer "F.Cu")
		(net "P3E_CPU0_PE1_SS_TXN<5>")
	)
	(segment
		(start 334.174846 -90.065352)
		(end 332.32852 -90.454734)
		(width 0.1143)
		(layer "F.Cu")
		(net "P3E_CPU0_PE1_SS_TXN<5>")
	)
	(segment
		(start 354.99929 -78.13802)
		(end 354.53574 -78.13802)
		(width 0.1143)
		(layer "F.Cu")
		(net "P3E_CPU0_PE1_SS_TXN<5>")
	)
	(segment
		(start 306.379626 -95.623634)
		(end 307.46954 -95.623634)
		(width 0.0889)
		(layer "F.Cu")
		(net "P3E_CPU0_PE1_SS_TXN<5>")
	)
	(segment
		(start 335.743042 -90.378534)
		(end 334.174846 -90.065352)
		(width 0.1143)
		(layer "F.Cu")
		(net "P3E_CPU0_PE1_SS_TXN<5>")
	)
	(segment
		(start 346.151454 -88.48344)
		(end 344.708988 -88.19515)
		(width 0.1143)
		(layer "F.Cu")
		(net "P3E_CPU0_PE1_SS_TXN<5>")
	)
	(segment
		(start 352.967036 -86.167468)
		(end 349.883476 -86.784434)
		(width 0.1143)
		(layer "F.Cu")
		(net "P3E_CPU0_PE1_SS_TXN<5>")
	)
	(segment
		(start 342.746076 -88.587834)
		(end 340.742016 -89.923874)
		(width 0.1143)
		(layer "F.Cu")
		(net "P3E_CPU0_PE1_SS_TXN<5>")
	)
	(segment
		(start 354.376736 -80.689196)
		(end 355.54158 -83.442048)
		(width 0.1143)
		(layer "F.Cu")
		(net "P3E_CPU0_PE1_SS_TXN<5>")
	)
	(segment
		(start 307.74386 -95.897954)
		(end 308.401466 -95.897954)
		(width 0.0889)
		(layer "F.Cu")
		(net "P3E_CPU0_PE1_SS_TXN<5>")
	)
	(segment
		(start 354.590858 -79.833978)
		(end 354.376736 -80.689196)
		(width 0.1143)
		(layer "F.Cu")
		(net "P3E_CPU0_PE1_SS_TXN<5>")
	)
	(segment
		(start 354.848668 -84.913216)
		(end 352.967036 -86.167468)
		(width 0.1143)
		(layer "F.Cu")
		(net "P3E_CPU0_PE1_SS_TXN<5>")
	)
	(segment
		(start 315.953902 -103.292148)
		(end 317.039752 -103.579422)
		(width 0.1143)
		(layer "F.Cu")
		(net "P3E_CPU0_PE1_SS_TXN<5>")
	)
	(segment
		(start 306.379372 -95.623888)
		(end 306.379626 -95.623634)
		(width 0.0889)
		(layer "F.Cu")
		(net "P3E_CPU0_PE1_SS_TXN<5>")
	)
	(segment
		(start 355.54158 -83.442048)
		(end 355.338634 -84.17814)
		(width 0.1143)
		(layer "F.Cu")
		(net "P3E_CPU0_PE1_SS_TXN<5>")
	)
	(segment
		(start 348.819216 -87.949532)
		(end 346.151454 -88.48344)
		(width 0.1143)
		(layer "F.Cu")
		(net "P3E_CPU0_PE1_SS_TXN<5>")
	)
	(segment
		(start 332.32852 -90.454734)
		(end 327.455276 -93.70187)
		(width 0.1143)
		(layer "F.Cu")
		(net "P3E_CPU0_PE1_SS_TXN<5>")
	)
	(segment
		(start 349.366586 -87.128858)
		(end 348.819216 -87.949532)
		(width 0.1143)
		(layer "F.Cu")
		(net "P3E_CPU0_PE1_SS_TXN<5>")
	)
	(segment
		(start 337.521296 -90.00363)
		(end 335.743042 -90.378534)
		(width 0.1143)
		(layer "F.Cu")
		(net "P3E_CPU0_PE1_SS_TXN<5>")
	)
	(segment
		(start 307.46954 -95.623634)
		(end 307.74386 -95.897954)
		(width 0.0889)
		(layer "F.Cu")
		(net "P3E_CPU0_PE1_SS_TXN<5>")
	)
	(segment
		(start 320.134742 -102.89286)
		(end 325.42099 -99.080828)
		(width 0.1143)
		(layer "F.Cu")
		(net "P3E_CPU0_PE1_SS_TXN<5>")
	)
	(segment
		(start 354.42144 -79.463392)
		(end 354.590858 -79.833978)
		(width 0.1143)
		(layer "F.Cu")
		(net "P3E_CPU0_PE1_SS_TXN<5>")
	)
	(segment
		(start 327.455276 -93.70187)
		(end 325.732648 -98.256852)
		(width 0.1143)
		(layer "F.Cu")
		(net "P3E_CPU0_PE1_SS_TXN<5>")
	)
	(segment
		(start 309.262272 -96.182688)
		(end 309.287672 -96.208088)
		(width 0.0889)
		(layer "F.Cu")
		(net "P3E_CPU0_PE1_SS_TXN<5>")
	)
	(segment
		(start 349.883476 -86.784434)
		(end 349.366586 -87.128858)
		(width 0.1143)
		(layer "F.Cu")
		(net "P3E_CPU0_PE1_SS_TXN<5>")
	)
	(segment
		(start 312.136536 -97.08515)
		(end 314.73394 -102.415848)
		(width 0.1143)
		(layer "F.Cu")
		(net "P3E_CPU0_PE1_SS_TXN<5>")
	)
	(segment
		(start 308.6862 -96.182688)
		(end 309.262272 -96.182688)
		(width 0.0889)
		(layer "F.Cu")
		(net "P3E_CPU0_PE1_SS_TXN<5>")
	)
	(segment
		(start 305.533806 -95.528384)
		(end 305.667156 -95.151194)
		(width 0.0889)
		(layer "F.Cu")
		(net "P3E_CPU0_PE1_SS_TXN<5>")
	)
	(segment
		(start 317.039752 -103.579422)
		(end 320.134742 -102.89286)
		(width 0.1143)
		(layer "F.Cu")
		(net "P3E_CPU0_PE1_SS_TXN<5>")
	)
	(segment
		(start 309.287672 -96.208088)
		(end 309.30977 -96.208088)
		(width 0.0889)
		(layer "F.Cu")
		(net "P3E_CPU0_PE1_SS_TXN<5>")
	)
	(segment
		(start 355.338634 -84.17814)
		(end 354.848668 -84.913216)
		(width 0.1143)
		(layer "F.Cu")
		(net "P3E_CPU0_PE1_SS_TXN<5>")
	)
	(via
		(at 354.99929 -78.13802)
		(size 0.508)
		(drill 0.254)
		(layers "F.Cu" "B.Cu")
		(net "P3E_CPU0_PE1_SS_TXN<5>")
	)
	(via
		(at 325.732648 -98.256852)
		(size 0.508)
		(drill 0.254)
		(layers "F.Cu" "B.Cu")
		(net "P3E_CPU0_PE1_SS_TXN<5>")
	)
	(arc
		(start 305.667156 -95.151194)
		(mid 305.789673 -95.220777)
		(end 305.880516 -95.328486)
		(width 0.0889)
		(layer "F.Cu")
		(net "P3E_CPU0_PE1_SS_TXN<5>")
	)
	(arc
		(start 305.880516 -95.328486)
		(mid 306.091229 -95.541565)
		(end 306.379372 -95.623888)
		(width 0.0889)
		(layer "F.Cu")
		(net "P3E_CPU0_PE1_SS_TXN<5>")
	)
	(segment
		(start 354.36429 -77.915516)
		(end 354.78339 -77.915516)
		(width 0.1143)
		(layer "B.Cu")
		(net "P3E_CPU0_PE1_SS_TXN<5>")
	)
	(segment
		(start 354.78339 -77.915516)
		(end 354.99929 -78.131416)
		(width 0.1143)
		(layer "B.Cu")
		(net "P3E_CPU0_PE1_SS_TXN<5>")
	)
	(segment
		(start 354.99929 -78.131416)
		(end 354.99929 -78.13802)
		(width 0.1143)
		(layer "B.Cu")
		(net "P3E_CPU0_PE1_SS_TXN<5>")
	)
	(segment
		(start 342.730836 -87.206582)
		(end 345.5035 -86.6521)
		(width 0.1143)
		(layer "F.Cu")
		(net "P3E_CPU0_PE1_SS_TXN<4>")
	)
	(segment
		(start 304.96256 -93.876876)
		(end 305.062382 -93.9038)
		(width 0.0889)
		(layer "F.Cu")
		(net "P3E_CPU0_PE1_SS_TXN<4>")
	)
	(segment
		(start 349.523558 -85.838792)
		(end 350.171766 -85.709252)
		(width 0.1143)
		(layer "F.Cu")
		(net "P3E_CPU0_PE1_SS_TXN<4>")
	)
	(segment
		(start 351.053146 -85.122004)
		(end 352.64725 -82.73034)
		(width 0.1143)
		(layer "F.Cu")
		(net "P3E_CPU0_PE1_SS_TXN<4>")
	)
	(segment
		(start 305.520852 -94.137988)
		(end 305.544982 -94.137988)
		(width 0.0889)
		(layer "F.Cu")
		(net "P3E_CPU0_PE1_SS_TXN<4>")
	)
	(segment
		(start 352.16846 -79.852266)
		(end 351.478342 -78.817216)
		(width 0.1143)
		(layer "F.Cu")
		(net "P3E_CPU0_PE1_SS_TXN<4>")
	)
	(segment
		(start 345.5035 -86.6521)
		(end 347.290644 -87.009478)
		(width 0.1143)
		(layer "F.Cu")
		(net "P3E_CPU0_PE1_SS_TXN<4>")
	)
	(segment
		(start 336.959448 -86.176866)
		(end 338.263738 -86.454996)
		(width 0.1143)
		(layer "F.Cu")
		(net "P3E_CPU0_PE1_SS_TXN<4>")
	)
	(segment
		(start 310.334406 -95.252794)
		(end 313.092338 -95.252794)
		(width 0.1143)
		(layer "F.Cu")
		(net "P3E_CPU0_PE1_SS_TXN<4>")
	)
	(segment
		(start 306.370736 -94.633288)
		(end 306.37099 -94.633034)
		(width 0.0889)
		(layer "F.Cu")
		(net "P3E_CPU0_PE1_SS_TXN<4>")
	)
	(segment
		(start 313.092338 -95.252794)
		(end 322.737734 -90.31986)
		(width 0.1143)
		(layer "F.Cu")
		(net "P3E_CPU0_PE1_SS_TXN<4>")
	)
	(segment
		(start 352.695764 -82.488024)
		(end 352.16846 -79.852266)
		(width 0.1143)
		(layer "F.Cu")
		(net "P3E_CPU0_PE1_SS_TXN<4>")
	)
	(segment
		(start 352.64725 -82.73034)
		(end 352.695764 -82.488024)
		(width 0.1143)
		(layer "F.Cu")
		(net "P3E_CPU0_PE1_SS_TXN<4>")
	)
	(segment
		(start 333.871316 -86.338664)
		(end 335.423002 -86.620604)
		(width 0.1143)
		(layer "F.Cu")
		(net "P3E_CPU0_PE1_SS_TXN<4>")
	)
	(segment
		(start 351.592642 -78.05674)
		(end 352.056192 -78.05674)
		(width 0.1143)
		(layer "F.Cu")
		(net "P3E_CPU0_PE1_SS_TXN<4>")
	)
	(segment
		(start 307.606446 -94.633034)
		(end 308.200806 -95.227394)
		(width 0.0889)
		(layer "F.Cu")
		(net "P3E_CPU0_PE1_SS_TXN<4>")
	)
	(segment
		(start 335.423002 -86.620604)
		(end 336.959448 -86.176866)
		(width 0.1143)
		(layer "F.Cu")
		(net "P3E_CPU0_PE1_SS_TXN<4>")
	)
	(segment
		(start 310.286908 -95.227394)
		(end 310.312308 -95.252794)
		(width 0.0889)
		(layer "F.Cu")
		(net "P3E_CPU0_PE1_SS_TXN<4>")
	)
	(segment
		(start 351.478342 -78.817216)
		(end 351.478342 -78.17104)
		(width 0.1143)
		(layer "F.Cu")
		(net "P3E_CPU0_PE1_SS_TXN<4>")
	)
	(segment
		(start 324.313804 -89.513918)
		(end 333.871316 -86.338664)
		(width 0.1143)
		(layer "F.Cu")
		(net "P3E_CPU0_PE1_SS_TXN<4>")
	)
	(segment
		(start 306.37099 -94.633034)
		(end 307.606446 -94.633034)
		(width 0.0889)
		(layer "F.Cu")
		(net "P3E_CPU0_PE1_SS_TXN<4>")
	)
	(segment
		(start 304.675286 -94.042738)
		(end 304.96256 -93.876876)
		(width 0.0889)
		(layer "F.Cu")
		(net "P3E_CPU0_PE1_SS_TXN<4>")
	)
	(segment
		(start 322.737734 -90.31986)
		(end 324.313804 -89.513918)
		(width 0.1143)
		(layer "F.Cu")
		(net "P3E_CPU0_PE1_SS_TXN<4>")
	)
	(segment
		(start 308.200806 -95.227394)
		(end 310.286908 -95.227394)
		(width 0.0889)
		(layer "F.Cu")
		(net "P3E_CPU0_PE1_SS_TXN<4>")
	)
	(segment
		(start 350.171766 -85.709252)
		(end 351.053146 -85.122004)
		(width 0.1143)
		(layer "F.Cu")
		(net "P3E_CPU0_PE1_SS_TXN<4>")
	)
	(segment
		(start 339.917532 -86.063582)
		(end 342.730836 -87.206582)
		(width 0.1143)
		(layer "F.Cu")
		(net "P3E_CPU0_PE1_SS_TXN<4>")
	)
	(segment
		(start 338.263738 -86.454996)
		(end 339.917532 -86.063582)
		(width 0.1143)
		(layer "F.Cu")
		(net "P3E_CPU0_PE1_SS_TXN<4>")
	)
	(segment
		(start 351.478342 -78.17104)
		(end 351.592642 -78.05674)
		(width 0.1143)
		(layer "F.Cu")
		(net "P3E_CPU0_PE1_SS_TXN<4>")
	)
	(segment
		(start 310.312308 -95.252794)
		(end 310.334406 -95.252794)
		(width 0.0889)
		(layer "F.Cu")
		(net "P3E_CPU0_PE1_SS_TXN<4>")
	)
	(segment
		(start 347.972888 -86.87308)
		(end 349.523558 -85.838792)
		(width 0.1143)
		(layer "F.Cu")
		(net "P3E_CPU0_PE1_SS_TXN<4>")
	)
	(segment
		(start 347.290644 -87.009478)
		(end 347.972888 -86.87308)
		(width 0.1143)
		(layer "F.Cu")
		(net "P3E_CPU0_PE1_SS_TXN<4>")
	)
	(via
		(at 352.056192 -78.05674)
		(size 0.508)
		(drill 0.254)
		(layers "F.Cu" "B.Cu")
		(net "P3E_CPU0_PE1_SS_TXN<4>")
	)
	(via
		(at 322.737734 -90.31986)
		(size 0.508)
		(drill 0.254)
		(layers "F.Cu" "B.Cu")
		(net "P3E_CPU0_PE1_SS_TXN<4>")
	)
	(arc
		(start 305.062382 -93.9038)
		(mid 305.264777 -94.073431)
		(end 305.520852 -94.137988)
		(width 0.0889)
		(layer "F.Cu")
		(net "P3E_CPU0_PE1_SS_TXN<4>")
	)
	(arc
		(start 305.544982 -94.137988)
		(mid 305.738832 -94.194338)
		(end 305.880516 -94.33814)
		(width 0.0889)
		(layer "F.Cu")
		(net "P3E_CPU0_PE1_SS_TXN<4>")
	)
	(arc
		(start 305.880516 -94.33814)
		(mid 306.08752 -94.549004)
		(end 306.370736 -94.633288)
		(width 0.0889)
		(layer "F.Cu")
		(net "P3E_CPU0_PE1_SS_TXN<4>")
	)
	(segment
		(start 351.421192 -77.834236)
		(end 351.840292 -77.834236)
		(width 0.1143)
		(layer "B.Cu")
		(net "P3E_CPU0_PE1_SS_TXN<4>")
	)
	(segment
		(start 351.840292 -77.834236)
		(end 352.056192 -78.050136)
		(width 0.1143)
		(layer "B.Cu")
		(net "P3E_CPU0_PE1_SS_TXN<4>")
	)
	(segment
		(start 352.056192 -78.050136)
		(end 352.056192 -78.05674)
		(width 0.1143)
		(layer "B.Cu")
		(net "P3E_CPU0_PE1_SS_TXN<4>")
	)
	(segment
		(start 348.63151 -78.12532)
		(end 348.63151 -78.8924)
		(width 0.1143)
		(layer "F.Cu")
		(net "P3E_CPU0_PE1_SS_TXN<3>")
	)
	(segment
		(start 340.620604 -84.410804)
		(end 338.042504 -83.898232)
		(width 0.1143)
		(layer "F.Cu")
		(net "P3E_CPU0_PE1_SS_TXN<3>")
	)
	(segment
		(start 323.980302 -88.570054)
		(end 320.743834 -90.225626)
		(width 0.1143)
		(layer "F.Cu")
		(net "P3E_CPU0_PE1_SS_TXN<3>")
	)
	(segment
		(start 338.042504 -83.898232)
		(end 323.980302 -88.570054)
		(width 0.1143)
		(layer "F.Cu")
		(net "P3E_CPU0_PE1_SS_TXN<3>")
	)
	(segment
		(start 348.63151 -78.8924)
		(end 349.51035 -80.566768)
		(width 0.1143)
		(layer "F.Cu")
		(net "P3E_CPU0_PE1_SS_TXN<3>")
	)
	(segment
		(start 308.793134 -94.270068)
		(end 308.771036 -94.270068)
		(width 0.0889)
		(layer "F.Cu")
		(net "P3E_CPU0_PE1_SS_TXN<3>")
	)
	(segment
		(start 308.020212 -94.244668)
		(end 307.418232 -93.642688)
		(width 0.0889)
		(layer "F.Cu")
		(net "P3E_CPU0_PE1_SS_TXN<3>")
	)
	(segment
		(start 349.12173 -82.163666)
		(end 347.954854 -82.941668)
		(width 0.1143)
		(layer "F.Cu")
		(net "P3E_CPU0_PE1_SS_TXN<3>")
	)
	(segment
		(start 307.418232 -93.642688)
		(end 306.374546 -93.642688)
		(width 0.0889)
		(layer "F.Cu")
		(net "P3E_CPU0_PE1_SS_TXN<3>")
	)
	(segment
		(start 320.743834 -90.225626)
		(end 320.743834 -90.22588)
		(width 0.1143)
		(layer "F.Cu")
		(net "P3E_CPU0_PE1_SS_TXN<3>")
	)
	(segment
		(start 304.819812 -92.678758)
		(end 304.675286 -93.052138)
		(width 0.0889)
		(layer "F.Cu")
		(net "P3E_CPU0_PE1_SS_TXN<3>")
	)
	(segment
		(start 312.837576 -94.270068)
		(end 308.793134 -94.270068)
		(width 0.1143)
		(layer "F.Cu")
		(net "P3E_CPU0_PE1_SS_TXN<3>")
	)
	(segment
		(start 320.74358 -90.22588)
		(end 320.74358 -90.226134)
		(width 0.1143)
		(layer "F.Cu")
		(net "P3E_CPU0_PE1_SS_TXN<3>")
	)
	(segment
		(start 349.20936 -78.01102)
		(end 348.74581 -78.01102)
		(width 0.1143)
		(layer "F.Cu")
		(net "P3E_CPU0_PE1_SS_TXN<3>")
	)
	(segment
		(start 305.544982 -93.147134)
		(end 305.512216 -93.147134)
		(width 0.0889)
		(layer "F.Cu")
		(net "P3E_CPU0_PE1_SS_TXN<3>")
	)
	(segment
		(start 316.274196 -92.512134)
		(end 312.837576 -94.270068)
		(width 0.1143)
		(layer "F.Cu")
		(net "P3E_CPU0_PE1_SS_TXN<3>")
	)
	(segment
		(start 349.51035 -80.566768)
		(end 349.12173 -82.163666)
		(width 0.1143)
		(layer "F.Cu")
		(net "P3E_CPU0_PE1_SS_TXN<3>")
	)
	(segment
		(start 308.771036 -94.270068)
		(end 308.745636 -94.244668)
		(width 0.0889)
		(layer "F.Cu")
		(net "P3E_CPU0_PE1_SS_TXN<3>")
	)
	(segment
		(start 320.74358 -90.226134)
		(end 316.274196 -92.512134)
		(width 0.1143)
		(layer "F.Cu")
		(net "P3E_CPU0_PE1_SS_TXN<3>")
	)
	(segment
		(start 308.745636 -94.244668)
		(end 308.020212 -94.244668)
		(width 0.0889)
		(layer "F.Cu")
		(net "P3E_CPU0_PE1_SS_TXN<3>")
	)
	(segment
		(start 348.74581 -78.01102)
		(end 348.63151 -78.12532)
		(width 0.1143)
		(layer "F.Cu")
		(net "P3E_CPU0_PE1_SS_TXN<3>")
	)
	(segment
		(start 320.743834 -90.22588)
		(end 320.74358 -90.22588)
		(width 0.1143)
		(layer "F.Cu")
		(net "P3E_CPU0_PE1_SS_TXN<3>")
	)
	(segment
		(start 347.954854 -82.941668)
		(end 340.620604 -84.410804)
		(width 0.1143)
		(layer "F.Cu")
		(net "P3E_CPU0_PE1_SS_TXN<3>")
	)
	(via
		(at 349.20936 -78.01102)
		(size 0.508)
		(drill 0.254)
		(layers "F.Cu" "B.Cu")
		(net "P3E_CPU0_PE1_SS_TXN<3>")
	)
	(via
		(at 320.743834 -90.22588)
		(size 0.508)
		(drill 0.254)
		(layers "F.Cu" "B.Cu")
		(net "P3E_CPU0_PE1_SS_TXN<3>")
	)
	(arc
		(start 306.374546 -93.642688)
		(mid 306.089122 -93.559221)
		(end 305.880516 -93.347286)
		(width 0.0889)
		(layer "F.Cu")
		(net "P3E_CPU0_PE1_SS_TXN<3>")
	)
	(arc
		(start 305.512216 -93.147134)
		(mid 305.228999 -93.062853)
		(end 305.021996 -92.851986)
		(width 0.0889)
		(layer "F.Cu")
		(net "P3E_CPU0_PE1_SS_TXN<3>")
	)
	(arc
		(start 305.880516 -93.347286)
		(mid 305.738833 -93.203482)
		(end 305.544982 -93.147134)
		(width 0.0889)
		(layer "F.Cu")
		(net "P3E_CPU0_PE1_SS_TXN<3>")
	)
	(arc
		(start 305.021996 -92.851986)
		(mid 304.935715 -92.74809)
		(end 304.819812 -92.678758)
		(width 0.0889)
		(layer "F.Cu")
		(net "P3E_CPU0_PE1_SS_TXN<3>")
	)
	(segment
		(start 349.20936 -78.004416)
		(end 349.20936 -78.01102)
		(width 0.1143)
		(layer "B.Cu")
		(net "P3E_CPU0_PE1_SS_TXN<3>")
	)
	(segment
		(start 348.99346 -77.788516)
		(end 349.20936 -78.004416)
		(width 0.1143)
		(layer "B.Cu")
		(net "P3E_CPU0_PE1_SS_TXN<3>")
	)
	(segment
		(start 348.57436 -77.788516)
		(end 348.99346 -77.788516)
		(width 0.1143)
		(layer "B.Cu")
		(net "P3E_CPU0_PE1_SS_TXN<3>")
	)
	(segment
		(start 307.265324 -92.652088)
		(end 307.568346 -92.652088)
		(width 0.0889)
		(layer "F.Cu")
		(net "P3E_CPU0_PE1_SS_TXN<2>")
	)
	(segment
		(start 308.174898 -93.25864)
		(end 309.099204 -93.25864)
		(width 0.0889)
		(layer "F.Cu")
		(net "P3E_CPU0_PE1_SS_TXN<2>")
	)
	(segment
		(start 345.060778 -79.400908)
		(end 345.504516 -79.400908)
		(width 0.1143)
		(layer "F.Cu")
		(net "P3E_CPU0_PE1_SS_TXN<2>")
	)
	(segment
		(start 306.392326 -93.052138)
		(end 306.105052 -92.886276)
		(width 0.0889)
		(layer "F.Cu")
		(net "P3E_CPU0_PE1_SS_TXN<2>")
	)
	(segment
		(start 308.023514 -93.107256)
		(end 308.174898 -93.25864)
		(width 0.0889)
		(layer "F.Cu")
		(net "P3E_CPU0_PE1_SS_TXN<2>")
	)
	(segment
		(start 346.003626 -77.89926)
		(end 346.467176 -77.89926)
		(width 0.1143)
		(layer "F.Cu")
		(net "P3E_CPU0_PE1_SS_TXN<2>")
	)
	(segment
		(start 340.14918 -83.306666)
		(end 343.079832 -82.493612)
		(width 0.1143)
		(layer "F.Cu")
		(net "P3E_CPU0_PE1_SS_TXN<2>")
	)
	(segment
		(start 309.124604 -93.28404)
		(end 309.146702 -93.28404)
		(width 0.0889)
		(layer "F.Cu")
		(net "P3E_CPU0_PE1_SS_TXN<2>")
	)
	(segment
		(start 307.568346 -92.652088)
		(end 307.685948 -92.76969)
		(width 0.0889)
		(layer "F.Cu")
		(net "P3E_CPU0_PE1_SS_TXN<2>")
	)
	(segment
		(start 312.576464 -93.28404)
		(end 318.628014 -90.188542)
		(width 0.1143)
		(layer "F.Cu")
		(net "P3E_CPU0_PE1_SS_TXN<2>")
	)
	(segment
		(start 343.079832 -82.493612)
		(end 343.844626 -80.61706)
		(width 0.1143)
		(layer "F.Cu")
		(net "P3E_CPU0_PE1_SS_TXN<2>")
	)
	(segment
		(start 337.999832 -82.879184)
		(end 337.999832 -82.87893)
		(width 0.1143)
		(layer "F.Cu")
		(net "P3E_CPU0_PE1_SS_TXN<2>")
	)
	(segment
		(start 306.105052 -92.886276)
		(end 306.081938 -92.799662)
		(width 0.0889)
		(layer "F.Cu")
		(net "P3E_CPU0_PE1_SS_TXN<2>")
	)
	(segment
		(start 309.099204 -93.25864)
		(end 309.124604 -93.28404)
		(width 0.0889)
		(layer "F.Cu")
		(net "P3E_CPU0_PE1_SS_TXN<2>")
	)
	(segment
		(start 345.889326 -79.016098)
		(end 345.889326 -78.01356)
		(width 0.1143)
		(layer "F.Cu")
		(net "P3E_CPU0_PE1_SS_TXN<2>")
	)
	(segment
		(start 307.685948 -92.76969)
		(end 307.685948 -92.909644)
		(width 0.0889)
		(layer "F.Cu")
		(net "P3E_CPU0_PE1_SS_TXN<2>")
	)
	(segment
		(start 306.886864 -92.751148)
		(end 307.166264 -92.751148)
		(width 0.0889)
		(layer "F.Cu")
		(net "P3E_CPU0_PE1_SS_TXN<2>")
	)
	(segment
		(start 307.685948 -92.909644)
		(end 307.88356 -93.107256)
		(width 0.0889)
		(layer "F.Cu")
		(net "P3E_CPU0_PE1_SS_TXN<2>")
	)
	(segment
		(start 307.166264 -92.751148)
		(end 307.265324 -92.652088)
		(width 0.0889)
		(layer "F.Cu")
		(net "P3E_CPU0_PE1_SS_TXN<2>")
	)
	(segment
		(start 307.88356 -93.107256)
		(end 308.023514 -93.107256)
		(width 0.0889)
		(layer "F.Cu")
		(net "P3E_CPU0_PE1_SS_TXN<2>")
	)
	(segment
		(start 323.500496 -87.696294)
		(end 337.999832 -82.879184)
		(width 0.1143)
		(layer "F.Cu")
		(net "P3E_CPU0_PE1_SS_TXN<2>")
	)
	(segment
		(start 345.504516 -79.400908)
		(end 345.889326 -79.016098)
		(width 0.1143)
		(layer "F.Cu")
		(net "P3E_CPU0_PE1_SS_TXN<2>")
	)
	(segment
		(start 323.500496 -87.696548)
		(end 323.500496 -87.696294)
		(width 0.1143)
		(layer "F.Cu")
		(net "P3E_CPU0_PE1_SS_TXN<2>")
	)
	(segment
		(start 345.889326 -78.01356)
		(end 346.003626 -77.89926)
		(width 0.1143)
		(layer "F.Cu")
		(net "P3E_CPU0_PE1_SS_TXN<2>")
	)
	(segment
		(start 306.37734 -92.652088)
		(end 306.787804 -92.652088)
		(width 0.0889)
		(layer "F.Cu")
		(net "P3E_CPU0_PE1_SS_TXN<2>")
	)
	(segment
		(start 337.999832 -82.87893)
		(end 340.14918 -83.306666)
		(width 0.1143)
		(layer "F.Cu")
		(net "P3E_CPU0_PE1_SS_TXN<2>")
	)
	(segment
		(start 309.146702 -93.28404)
		(end 312.576464 -93.28404)
		(width 0.1143)
		(layer "F.Cu")
		(net "P3E_CPU0_PE1_SS_TXN<2>")
	)
	(segment
		(start 343.844626 -80.61706)
		(end 345.060778 -79.400908)
		(width 0.1143)
		(layer "F.Cu")
		(net "P3E_CPU0_PE1_SS_TXN<2>")
	)
	(segment
		(start 306.787804 -92.652088)
		(end 306.886864 -92.751148)
		(width 0.0889)
		(layer "F.Cu")
		(net "P3E_CPU0_PE1_SS_TXN<2>")
	)
	(segment
		(start 318.628014 -90.188542)
		(end 323.500496 -87.696548)
		(width 0.1143)
		(layer "F.Cu")
		(net "P3E_CPU0_PE1_SS_TXN<2>")
	)
	(via
		(at 318.628014 -90.188542)
		(size 0.508)
		(drill 0.254)
		(layers "F.Cu" "B.Cu")
		(net "P3E_CPU0_PE1_SS_TXN<2>")
	)
	(via
		(at 346.467176 -77.89926)
		(size 0.508)
		(drill 0.254)
		(layers "F.Cu" "B.Cu")
		(net "P3E_CPU0_PE1_SS_TXN<2>")
	)
	(arc
		(start 306.081938 -92.799662)
		(mid 306.213719 -92.694016)
		(end 306.37734 -92.652088)
		(width 0.0889)
		(layer "F.Cu")
		(net "P3E_CPU0_PE1_SS_TXN<2>")
	)
	(segment
		(start 345.832176 -77.694536)
		(end 346.262452 -77.694536)
		(width 0.1143)
		(layer "B.Cu")
		(net "P3E_CPU0_PE1_SS_TXN<2>")
	)
	(segment
		(start 346.262452 -77.694536)
		(end 346.467176 -77.89926)
		(width 0.1143)
		(layer "B.Cu")
		(net "P3E_CPU0_PE1_SS_TXN<2>")
	)
	(segment
		(start 341.93607 -80.916018)
		(end 341.261192 -81.866486)
		(width 0.1143)
		(layer "F.Cu")
		(net "P3E_CPU0_PE1_SS_TXN<1>")
	)
	(segment
		(start 312.08726 -92.284042)
		(end 316.895226 -89.810844)
		(width 0.1143)
		(layer "F.Cu")
		(net "P3E_CPU0_PE1_SS_TXN<1>")
	)
	(segment
		(start 309.960264 -92.284042)
		(end 312.08726 -92.284042)
		(width 0.1143)
		(layer "F.Cu")
		(net "P3E_CPU0_PE1_SS_TXN<1>")
	)
	(segment
		(start 309.227474 -92.258642)
		(end 309.912766 -92.258642)
		(width 0.0889)
		(layer "F.Cu")
		(net "P3E_CPU0_PE1_SS_TXN<1>")
	)
	(segment
		(start 337.660234 -81.81594)
		(end 322.914772 -86.71433)
		(width 0.1143)
		(layer "F.Cu")
		(net "P3E_CPU0_PE1_SS_TXN<1>")
	)
	(segment
		(start 343.148412 -78.067916)
		(end 343.148412 -79.017876)
		(width 0.1143)
		(layer "F.Cu")
		(net "P3E_CPU0_PE1_SS_TXN<1>")
	)
	(segment
		(start 343.148412 -79.017876)
		(end 342.683846 -79.482442)
		(width 0.1143)
		(layer "F.Cu")
		(net "P3E_CPU0_PE1_SS_TXN<1>")
	)
	(segment
		(start 342.683846 -79.482442)
		(end 342.411304 -79.482442)
		(width 0.1143)
		(layer "F.Cu")
		(net "P3E_CPU0_PE1_SS_TXN<1>")
	)
	(segment
		(start 343.299288 -77.91704)
		(end 343.148412 -78.067916)
		(width 0.1143)
		(layer "F.Cu")
		(net "P3E_CPU0_PE1_SS_TXN<1>")
	)
	(segment
		(start 307.22316 -92.15628)
		(end 309.125112 -92.15628)
		(width 0.0889)
		(layer "F.Cu")
		(net "P3E_CPU0_PE1_SS_TXN<1>")
	)
	(segment
		(start 306.392326 -92.061538)
		(end 306.6796 -91.895676)
		(width 0.0889)
		(layer "F.Cu")
		(net "P3E_CPU0_PE1_SS_TXN<1>")
	)
	(segment
		(start 343.698068 -77.91704)
		(end 343.299288 -77.91704)
		(width 0.1143)
		(layer "F.Cu")
		(net "P3E_CPU0_PE1_SS_TXN<1>")
	)
	(segment
		(start 309.912766 -92.258642)
		(end 309.938166 -92.284042)
		(width 0.0889)
		(layer "F.Cu")
		(net "P3E_CPU0_PE1_SS_TXN<1>")
	)
	(segment
		(start 342.411304 -79.482442)
		(end 342.218264 -79.676244)
		(width 0.1143)
		(layer "F.Cu")
		(net "P3E_CPU0_PE1_SS_TXN<1>")
	)
	(segment
		(start 306.6796 -91.895676)
		(end 306.779422 -91.9226)
		(width 0.0889)
		(layer "F.Cu")
		(net "P3E_CPU0_PE1_SS_TXN<1>")
	)
	(segment
		(start 339.86343 -82.25409)
		(end 337.660234 -81.81594)
		(width 0.1143)
		(layer "F.Cu")
		(net "P3E_CPU0_PE1_SS_TXN<1>")
	)
	(segment
		(start 322.914518 -86.714584)
		(end 316.895226 -89.810844)
		(width 0.1143)
		(layer "F.Cu")
		(net "P3E_CPU0_PE1_SS_TXN<1>")
	)
	(segment
		(start 322.914772 -86.71433)
		(end 322.914518 -86.714584)
		(width 0.1143)
		(layer "F.Cu")
		(net "P3E_CPU0_PE1_SS_TXN<1>")
	)
	(segment
		(start 341.261192 -81.866486)
		(end 339.86343 -82.25409)
		(width 0.1143)
		(layer "F.Cu")
		(net "P3E_CPU0_PE1_SS_TXN<1>")
	)
	(segment
		(start 309.125112 -92.15628)
		(end 309.227474 -92.258642)
		(width 0.0889)
		(layer "F.Cu")
		(net "P3E_CPU0_PE1_SS_TXN<1>")
	)
	(segment
		(start 342.218264 -79.676244)
		(end 341.93607 -80.916018)
		(width 0.1143)
		(layer "F.Cu")
		(net "P3E_CPU0_PE1_SS_TXN<1>")
	)
	(segment
		(start 309.938166 -92.284042)
		(end 309.960264 -92.284042)
		(width 0.0889)
		(layer "F.Cu")
		(net "P3E_CPU0_PE1_SS_TXN<1>")
	)
	(via
		(at 316.895226 -89.810844)
		(size 0.508)
		(drill 0.254)
		(layers "F.Cu" "B.Cu")
		(net "P3E_CPU0_PE1_SS_TXN<1>")
	)
	(via
		(at 343.698068 -77.91704)
		(size 0.508)
		(drill 0.254)
		(layers "F.Cu" "B.Cu")
		(net "P3E_CPU0_PE1_SS_TXN<1>")
	)
	(arc
		(start 306.779422 -91.9226)
		(mid 306.975274 -92.088838)
		(end 307.22316 -92.15628)
		(width 0.0889)
		(layer "F.Cu")
		(net "P3E_CPU0_PE1_SS_TXN<1>")
	)
	(segment
		(start 343.482168 -77.694536)
		(end 343.063068 -77.694536)
		(width 0.1143)
		(layer "B.Cu")
		(net "P3E_CPU0_PE1_SS_TXN<1>")
	)
	(segment
		(start 343.698068 -77.91704)
		(end 343.698068 -77.910436)
		(width 0.1143)
		(layer "B.Cu")
		(net "P3E_CPU0_PE1_SS_TXN<1>")
	)
	(segment
		(start 343.698068 -77.910436)
		(end 343.482168 -77.694536)
		(width 0.1143)
		(layer "B.Cu")
		(net "P3E_CPU0_PE1_SS_TXN<1>")
	)
	(segment
		(start 340.208616 -78.9178)
		(end 339.732112 -79.394304)
		(width 0.1143)
		(layer "F.Cu")
		(net "P3E_CPU0_PE1_SS_TXN<0>")
	)
	(segment
		(start 307.655976 -91.165934)
		(end 307.229256 -91.165934)
		(width 0.0889)
		(layer "F.Cu")
		(net "P3E_CPU0_PE1_SS_TXN<0>")
	)
	(segment
		(start 321.668394 -85.95233)
		(end 311.560464 -91.310714)
		(width 0.1143)
		(layer "F.Cu")
		(net "P3E_CPU0_PE1_SS_TXN<0>")
	)
	(segment
		(start 340.33841 -77.91704)
		(end 340.208616 -78.046834)
		(width 0.1143)
		(layer "F.Cu")
		(net "P3E_CPU0_PE1_SS_TXN<0>")
	)
	(segment
		(start 326.526144 -83.954874)
		(end 321.668394 -85.95233)
		(width 0.1143)
		(layer "F.Cu")
		(net "P3E_CPU0_PE1_SS_TXN<0>")
	)
	(segment
		(start 309.210456 -91.310714)
		(end 309.188358 -91.310714)
		(width 0.0889)
		(layer "F.Cu")
		(net "P3E_CPU0_PE1_SS_TXN<0>")
	)
	(segment
		(start 340.208616 -78.046834)
		(end 340.208616 -78.9178)
		(width 0.1143)
		(layer "F.Cu")
		(net "P3E_CPU0_PE1_SS_TXN<0>")
	)
	(segment
		(start 307.775356 -91.285314)
		(end 307.655976 -91.165934)
		(width 0.0889)
		(layer "F.Cu")
		(net "P3E_CPU0_PE1_SS_TXN<0>")
	)
	(segment
		(start 309.188358 -91.310714)
		(end 309.162958 -91.285314)
		(width 0.0889)
		(layer "F.Cu")
		(net "P3E_CPU0_PE1_SS_TXN<0>")
	)
	(segment
		(start 306.455826 -90.675714)
		(end 306.392326 -90.739214)
		(width 0.0889)
		(layer "F.Cu")
		(net "P3E_CPU0_PE1_SS_TXN<0>")
	)
	(segment
		(start 326.526398 -83.955128)
		(end 326.526144 -83.954874)
		(width 0.1143)
		(layer "F.Cu")
		(net "P3E_CPU0_PE1_SS_TXN<0>")
	)
	(segment
		(start 337.91906 -79.271114)
		(end 326.526398 -83.955128)
		(width 0.1143)
		(layer "F.Cu")
		(net "P3E_CPU0_PE1_SS_TXN<0>")
	)
	(segment
		(start 309.162958 -91.285314)
		(end 307.775356 -91.285314)
		(width 0.0889)
		(layer "F.Cu")
		(net "P3E_CPU0_PE1_SS_TXN<0>")
	)
	(segment
		(start 339.732112 -79.394304)
		(end 339.34527 -79.55661)
		(width 0.1143)
		(layer "F.Cu")
		(net "P3E_CPU0_PE1_SS_TXN<0>")
	)
	(segment
		(start 311.560464 -91.310714)
		(end 309.210456 -91.310714)
		(width 0.1143)
		(layer "F.Cu")
		(net "P3E_CPU0_PE1_SS_TXN<0>")
	)
	(segment
		(start 340.80196 -77.91704)
		(end 340.33841 -77.91704)
		(width 0.1143)
		(layer "F.Cu")
		(net "P3E_CPU0_PE1_SS_TXN<0>")
	)
	(segment
		(start 306.392326 -90.739214)
		(end 306.392326 -91.070938)
		(width 0.0889)
		(layer "F.Cu")
		(net "P3E_CPU0_PE1_SS_TXN<0>")
	)
	(segment
		(start 339.34527 -79.55661)
		(end 337.91906 -79.271114)
		(width 0.1143)
		(layer "F.Cu")
		(net "P3E_CPU0_PE1_SS_TXN<0>")
	)
	(via
		(at 326.526144 -83.954874)
		(size 0.508)
		(drill 0.254)
		(layers "F.Cu" "B.Cu")
		(net "P3E_CPU0_PE1_SS_TXN<0>")
	)
	(via
		(at 340.80196 -77.91704)
		(size 0.508)
		(drill 0.254)
		(layers "F.Cu" "B.Cu")
		(net "P3E_CPU0_PE1_SS_TXN<0>")
	)
	(arc
		(start 307.229256 -91.165934)
		(mid 306.946039 -91.081653)
		(end 306.739036 -90.870786)
		(width 0.0889)
		(layer "F.Cu")
		(net "P3E_CPU0_PE1_SS_TXN<0>")
	)
	(arc
		(start 306.739036 -90.870786)
		(mid 306.619453 -90.741269)
		(end 306.455826 -90.675714)
		(width 0.0889)
		(layer "F.Cu")
		(net "P3E_CPU0_PE1_SS_TXN<0>")
	)
	(segment
		(start 340.16696 -77.694536)
		(end 340.58606 -77.694536)
		(width 0.1143)
		(layer "B.Cu")
		(net "P3E_CPU0_PE1_SS_TXN<0>")
	)
	(segment
		(start 340.58606 -77.694536)
		(end 340.80196 -77.910436)
		(width 0.1143)
		(layer "B.Cu")
		(net "P3E_CPU0_PE1_SS_TXN<0>")
	)
	(segment
		(start 340.80196 -77.910436)
		(end 340.80196 -77.91704)
		(width 0.1143)
		(layer "B.Cu")
		(net "P3E_CPU0_PE1_SS_TXN<0>")
	)
	(segment
		(start 299.524166 -96.023938)
		(end 300.095666 -96.023938)
		(width 0.1143)
		(layer "F.Cu")
		(net "P3E_CPU0_PE1_SS_RXP<7>")
	)
	(via
		(at 300.095666 -96.023938)
		(size 0.508)
		(drill 0.254)
		(layers "F.Cu" "B.Cu")
		(net "P3E_CPU0_PE1_SS_RXP<7>")
	)
	(via
		(at 353.5426 -60.4266)
		(size 0.508)
		(drill 0.254)
		(layers "F.Cu" "B.Cu")
		(net "P3E_CPU0_PE1_SS_RXP<7>")
	)
	(segment
		(start 353.484434 -60.368434)
		(end 353.5426 -60.4266)
		(width 0.1143)
		(layer "B.Cu")
		(net "P3E_CPU0_PE1_SS_RXP<7>")
	)
	(segment
		(start 352.904806 -60.368434)
		(end 353.484434 -60.368434)
		(width 0.1143)
		(layer "B.Cu")
		(net "P3E_CPU0_PE1_SS_RXP<7>")
	)
	(segment
		(start 330.220574 -66.255138)
		(end 331.806042 -66.824352)
		(width 0.1143)
		(layer "In2.Cu")
		(net "P3E_CPU0_PE1_SS_RXP<7>")
	)
	(segment
		(start 301.798228 -96.423988)
		(end 301.830994 -96.423988)
		(width 0.0889)
		(layer "In2.Cu")
		(net "P3E_CPU0_PE1_SS_RXP<7>")
	)
	(segment
		(start 335.005172 -65.437004)
		(end 336.146902 -65.437004)
		(width 0.1143)
		(layer "In2.Cu")
		(net "P3E_CPU0_PE1_SS_RXP<7>")
	)
	(segment
		(start 313.792616 -93.69679)
		(end 322.890134 -86.411816)
		(width 0.1143)
		(layer "In2.Cu")
		(net "P3E_CPU0_PE1_SS_RXP<7>")
	)
	(segment
		(start 327.25614 -69.44614)
		(end 327.44283 -68.720462)
		(width 0.1143)
		(layer "In2.Cu")
		(net "P3E_CPU0_PE1_SS_RXP<7>")
	)
	(segment
		(start 327.085198 -70.11035)
		(end 326.966326 -69.909182)
		(width 0.1143)
		(layer "In2.Cu")
		(net "P3E_CPU0_PE1_SS_RXP<7>")
	)
	(segment
		(start 326.966326 -69.909182)
		(end 327.054972 -69.565012)
		(width 0.1143)
		(layer "In2.Cu")
		(net "P3E_CPU0_PE1_SS_RXP<7>")
	)
	(segment
		(start 306.409598 -95.494856)
		(end 307.565298 -95.494856)
		(width 0.0889)
		(layer "In2.Cu")
		(net "P3E_CPU0_PE1_SS_RXP<7>")
	)
	(segment
		(start 326.996552 -70.454774)
		(end 327.085198 -70.11035)
		(width 0.1143)
		(layer "In2.Cu")
		(net "P3E_CPU0_PE1_SS_RXP<7>")
	)
	(segment
		(start 300.388782 -96.192848)
		(end 300.47819 -96.168718)
		(width 0.0889)
		(layer "In2.Cu")
		(net "P3E_CPU0_PE1_SS_RXP<7>")
	)
	(segment
		(start 326.795638 -70.573392)
		(end 326.996552 -70.454774)
		(width 0.1143)
		(layer "In2.Cu")
		(net "P3E_CPU0_PE1_SS_RXP<7>")
	)
	(segment
		(start 326.736964 -71.463408)
		(end 326.82561 -71.118984)
		(width 0.1143)
		(layer "In2.Cu")
		(net "P3E_CPU0_PE1_SS_RXP<7>")
	)
	(segment
		(start 338.90712 -64.90208)
		(end 339.508592 -64.300608)
		(width 0.1143)
		(layer "In2.Cu")
		(net "P3E_CPU0_PE1_SS_RXP<7>")
	)
	(segment
		(start 304.619914 -96.928686)
		(end 304.7365 -96.8121)
		(width 0.0889)
		(layer "In2.Cu")
		(net "P3E_CPU0_PE1_SS_RXP<7>")
	)
	(segment
		(start 307.565298 -95.494856)
		(end 307.616098 -95.444056)
		(width 0.0889)
		(layer "In2.Cu")
		(net "P3E_CPU0_PE1_SS_RXP<7>")
	)
	(segment
		(start 353.964494 -60.4266)
		(end 353.5426 -60.4266)
		(width 0.1143)
		(layer "In2.Cu")
		(net "P3E_CPU0_PE1_SS_RXP<7>")
	)
	(segment
		(start 339.508592 -64.300608)
		(end 350.481138 -64.300608)
		(width 0.1143)
		(layer "In2.Cu")
		(net "P3E_CPU0_PE1_SS_RXP<7>")
	)
	(segment
		(start 354.078794 -60.702952)
		(end 354.078794 -60.5409)
		(width 0.1143)
		(layer "In2.Cu")
		(net "P3E_CPU0_PE1_SS_RXP<7>")
	)
	(segment
		(start 326.82561 -71.118984)
		(end 326.706992 -70.917816)
		(width 0.1143)
		(layer "In2.Cu")
		(net "P3E_CPU0_PE1_SS_RXP<7>")
	)
	(segment
		(start 308.181756 -95.444056)
		(end 313.792616 -93.69679)
		(width 0.1143)
		(layer "In2.Cu")
		(net "P3E_CPU0_PE1_SS_RXP<7>")
	)
	(segment
		(start 307.638196 -95.444056)
		(end 308.181756 -95.444056)
		(width 0.1143)
		(layer "In2.Cu")
		(net "P3E_CPU0_PE1_SS_RXP<7>")
	)
	(segment
		(start 303.511458 -96.423988)
		(end 303.548034 -96.423988)
		(width 0.0889)
		(layer "In2.Cu")
		(net "P3E_CPU0_PE1_SS_RXP<7>")
	)
	(segment
		(start 336.681826 -64.90208)
		(end 338.90712 -64.90208)
		(width 0.1143)
		(layer "In2.Cu")
		(net "P3E_CPU0_PE1_SS_RXP<7>")
	)
	(segment
		(start 307.616098 -95.444056)
		(end 307.638196 -95.444056)
		(width 0.0889)
		(layer "In2.Cu")
		(net "P3E_CPU0_PE1_SS_RXP<7>")
	)
	(segment
		(start 327.054972 -69.565012)
		(end 327.25614 -69.44614)
		(width 0.1143)
		(layer "In2.Cu")
		(net "P3E_CPU0_PE1_SS_RXP<7>")
	)
	(segment
		(start 300.095666 -96.023938)
		(end 300.388782 -96.192848)
		(width 0.0889)
		(layer "In2.Cu")
		(net "P3E_CPU0_PE1_SS_RXP<7>")
	)
	(segment
		(start 354.078794 -60.5409)
		(end 353.964494 -60.4266)
		(width 0.1143)
		(layer "In2.Cu")
		(net "P3E_CPU0_PE1_SS_RXP<7>")
	)
	(segment
		(start 304.7365 -96.8121)
		(end 305.092354 -96.8121)
		(width 0.0889)
		(layer "In2.Cu")
		(net "P3E_CPU0_PE1_SS_RXP<7>")
	)
	(segment
		(start 331.806042 -66.824352)
		(end 332.47584 -66.62547)
		(width 0.1143)
		(layer "In2.Cu")
		(net "P3E_CPU0_PE1_SS_RXP<7>")
	)
	(segment
		(start 304.37074 -96.919034)
		(end 304.401982 -96.919034)
		(width 0.0889)
		(layer "In2.Cu")
		(net "P3E_CPU0_PE1_SS_RXP<7>")
	)
	(segment
		(start 302.6537 -96.919034)
		(end 302.688752 -96.919034)
		(width 0.0889)
		(layer "In2.Cu")
		(net "P3E_CPU0_PE1_SS_RXP<7>")
	)
	(segment
		(start 326.447404 -71.92645)
		(end 326.53605 -71.582026)
		(width 0.1143)
		(layer "In2.Cu")
		(net "P3E_CPU0_PE1_SS_RXP<7>")
	)
	(segment
		(start 304.495962 -96.928686)
		(end 304.619914 -96.928686)
		(width 0.0889)
		(layer "In2.Cu")
		(net "P3E_CPU0_PE1_SS_RXP<7>")
	)
	(segment
		(start 322.890134 -86.411816)
		(end 326.566022 -72.127618)
		(width 0.1143)
		(layer "In2.Cu")
		(net "P3E_CPU0_PE1_SS_RXP<7>")
	)
	(segment
		(start 350.481138 -64.300608)
		(end 354.078794 -60.702952)
		(width 0.1143)
		(layer "In2.Cu")
		(net "P3E_CPU0_PE1_SS_RXP<7>")
	)
	(segment
		(start 329.197208 -66.618358)
		(end 330.220574 -66.255138)
		(width 0.1143)
		(layer "In2.Cu")
		(net "P3E_CPU0_PE1_SS_RXP<7>")
	)
	(segment
		(start 326.706992 -70.917816)
		(end 326.795638 -70.573392)
		(width 0.1143)
		(layer "In2.Cu")
		(net "P3E_CPU0_PE1_SS_RXP<7>")
	)
	(segment
		(start 305.092354 -96.8121)
		(end 306.409598 -95.494856)
		(width 0.0889)
		(layer "In2.Cu")
		(net "P3E_CPU0_PE1_SS_RXP<7>")
	)
	(segment
		(start 326.566022 -72.127618)
		(end 326.447404 -71.92645)
		(width 0.1143)
		(layer "In2.Cu")
		(net "P3E_CPU0_PE1_SS_RXP<7>")
	)
	(segment
		(start 336.146902 -65.437004)
		(end 336.681826 -64.90208)
		(width 0.1143)
		(layer "In2.Cu")
		(net "P3E_CPU0_PE1_SS_RXP<7>")
	)
	(segment
		(start 332.47584 -66.62547)
		(end 335.005172 -65.437004)
		(width 0.1143)
		(layer "In2.Cu")
		(net "P3E_CPU0_PE1_SS_RXP<7>")
	)
	(segment
		(start 327.44283 -68.720462)
		(end 329.197208 -66.618358)
		(width 0.1143)
		(layer "In2.Cu")
		(net "P3E_CPU0_PE1_SS_RXP<7>")
	)
	(segment
		(start 326.53605 -71.582026)
		(end 326.736964 -71.463408)
		(width 0.1143)
		(layer "In2.Cu")
		(net "P3E_CPU0_PE1_SS_RXP<7>")
	)
	(arc
		(start 304.041556 -96.719136)
		(mid 304.180549 -96.861216)
		(end 304.37074 -96.919034)
		(width 0.0889)
		(layer "In2.Cu")
		(net "P3E_CPU0_PE1_SS_RXP<7>")
	)
	(arc
		(start 303.548034 -96.423988)
		(mid 303.833081 -96.507516)
		(end 304.041556 -96.719136)
		(width 0.0889)
		(layer "In2.Cu")
		(net "P3E_CPU0_PE1_SS_RXP<7>")
	)
	(arc
		(start 304.401982 -96.919034)
		(mid 304.449165 -96.921981)
		(end 304.495962 -96.928686)
		(width 0.0889)
		(layer "In2.Cu")
		(net "P3E_CPU0_PE1_SS_RXP<7>")
	)
	(arc
		(start 300.47819 -96.168718)
		(mid 300.987056 -95.928815)
		(end 301.465996 -96.223836)
		(width 0.0889)
		(layer "In2.Cu")
		(net "P3E_CPU0_PE1_SS_RXP<7>")
	)
	(arc
		(start 302.688752 -96.919034)
		(mid 302.878994 -96.861299)
		(end 303.017936 -96.719136)
		(width 0.0889)
		(layer "In2.Cu")
		(net "P3E_CPU0_PE1_SS_RXP<7>")
	)
	(arc
		(start 301.465996 -96.223836)
		(mid 301.606264 -96.366792)
		(end 301.798228 -96.423988)
		(width 0.0889)
		(layer "In2.Cu")
		(net "P3E_CPU0_PE1_SS_RXP<7>")
	)
	(arc
		(start 302.324516 -96.719136)
		(mid 302.463509 -96.861216)
		(end 302.6537 -96.919034)
		(width 0.0889)
		(layer "In2.Cu")
		(net "P3E_CPU0_PE1_SS_RXP<7>")
	)
	(arc
		(start 303.017936 -96.719136)
		(mid 303.226355 -96.507423)
		(end 303.511458 -96.423988)
		(width 0.0889)
		(layer "In2.Cu")
		(net "P3E_CPU0_PE1_SS_RXP<7>")
	)
	(arc
		(start 301.830994 -96.423988)
		(mid 302.116041 -96.507516)
		(end 302.324516 -96.719136)
		(width 0.0889)
		(layer "In2.Cu")
		(net "P3E_CPU0_PE1_SS_RXP<7>")
	)
	(segment
		(start 301.241206 -95.033084)
		(end 301.812706 -95.033084)
		(width 0.1143)
		(layer "F.Cu")
		(net "P3E_CPU0_PE1_SS_RXP<6>")
	)
	(via
		(at 350.7486 -60.4266)
		(size 0.508)
		(drill 0.254)
		(layers "F.Cu" "B.Cu")
		(net "P3E_CPU0_PE1_SS_RXP<6>")
	)
	(via
		(at 301.812706 -95.033084)
		(size 0.508)
		(drill 0.254)
		(layers "F.Cu" "B.Cu")
		(net "P3E_CPU0_PE1_SS_RXP<6>")
	)
	(segment
		(start 350.690434 -60.368434)
		(end 350.7486 -60.4266)
		(width 0.1143)
		(layer "B.Cu")
		(net "P3E_CPU0_PE1_SS_RXP<6>")
	)
	(segment
		(start 350.110806 -60.368434)
		(end 350.690434 -60.368434)
		(width 0.1143)
		(layer "B.Cu")
		(net "P3E_CPU0_PE1_SS_RXP<6>")
	)
	(segment
		(start 330.86929 -65.773046)
		(end 330.242672 -65.548002)
		(width 0.1143)
		(layer "In2.Cu")
		(net "P3E_CPU0_PE1_SS_RXP<6>")
	)
	(segment
		(start 325.78294 -71.159116)
		(end 325.582026 -71.277734)
		(width 0.1143)
		(layer "In2.Cu")
		(net "P3E_CPU0_PE1_SS_RXP<6>")
	)
	(segment
		(start 336.418428 -64.26708)
		(end 335.883504 -64.802004)
		(width 0.1143)
		(layer "In2.Cu")
		(net "P3E_CPU0_PE1_SS_RXP<6>")
	)
	(segment
		(start 331.403198 -65.789302)
		(end 331.080618 -65.673224)
		(width 0.1143)
		(layer "In2.Cu")
		(net "P3E_CPU0_PE1_SS_RXP<6>")
	)
	(segment
		(start 325.611998 -71.823326)
		(end 325.523352 -72.167496)
		(width 0.1143)
		(layer "In2.Cu")
		(net "P3E_CPU0_PE1_SS_RXP<6>")
	)
	(segment
		(start 326.390762 -68.797678)
		(end 325.78294 -71.159116)
		(width 0.1143)
		(layer "In2.Cu")
		(net "P3E_CPU0_PE1_SS_RXP<6>")
	)
	(segment
		(start 325.582026 -71.277734)
		(end 325.49338 -71.622158)
		(width 0.1143)
		(layer "In2.Cu")
		(net "P3E_CPU0_PE1_SS_RXP<6>")
	)
	(segment
		(start 325.49338 -71.622158)
		(end 325.611998 -71.823326)
		(width 0.1143)
		(layer "In2.Cu")
		(net "P3E_CPU0_PE1_SS_RXP<6>")
	)
	(segment
		(start 325.233792 -72.630792)
		(end 325.35241 -72.831706)
		(width 0.1143)
		(layer "In2.Cu")
		(net "P3E_CPU0_PE1_SS_RXP<6>")
	)
	(segment
		(start 349.878142 -62.10554)
		(end 349.878142 -62.338966)
		(width 0.1143)
		(layer "In2.Cu")
		(net "P3E_CPU0_PE1_SS_RXP<6>")
	)
	(segment
		(start 304.403252 -95.928434)
		(end 304.37328 -95.928434)
		(width 0.0889)
		(layer "In2.Cu")
		(net "P3E_CPU0_PE1_SS_RXP<6>")
	)
	(segment
		(start 351.30105 -60.916058)
		(end 350.354138 -61.86297)
		(width 0.1143)
		(layer "In2.Cu")
		(net "P3E_CPU0_PE1_SS_RXP<6>")
	)
	(segment
		(start 305.841146 -95.433134)
		(end 305.233832 -95.433134)
		(width 0.0889)
		(layer "In2.Cu")
		(net "P3E_CPU0_PE1_SS_RXP<6>")
	)
	(segment
		(start 313.747404 -92.738194)
		(end 308.418738 -94.391988)
		(width 0.1143)
		(layer "In2.Cu")
		(net "P3E_CPU0_PE1_SS_RXP<6>")
	)
	(segment
		(start 350.120712 -61.86297)
		(end 349.878142 -62.10554)
		(width 0.1143)
		(layer "In2.Cu")
		(net "P3E_CPU0_PE1_SS_RXP<6>")
	)
	(segment
		(start 339.245194 -63.665608)
		(end 338.643722 -64.26708)
		(width 0.1143)
		(layer "In2.Cu")
		(net "P3E_CPU0_PE1_SS_RXP<6>")
	)
	(segment
		(start 307.77688 -94.442788)
		(end 306.831492 -94.442788)
		(width 0.0889)
		(layer "In2.Cu")
		(net "P3E_CPU0_PE1_SS_RXP<6>")
	)
	(segment
		(start 325.322438 -72.286368)
		(end 325.233792 -72.630792)
		(width 0.1143)
		(layer "In2.Cu")
		(net "P3E_CPU0_PE1_SS_RXP<6>")
	)
	(segment
		(start 335.883504 -64.802004)
		(end 334.84312 -64.802004)
		(width 0.1143)
		(layer "In2.Cu")
		(net "P3E_CPU0_PE1_SS_RXP<6>")
	)
	(segment
		(start 332.42504 -65.9384)
		(end 331.8256 -66.1162)
		(width 0.1143)
		(layer "In2.Cu")
		(net "P3E_CPU0_PE1_SS_RXP<6>")
	)
	(segment
		(start 351.18675 -60.4266)
		(end 351.30105 -60.5409)
		(width 0.1143)
		(layer "In2.Cu")
		(net "P3E_CPU0_PE1_SS_RXP<6>")
	)
	(segment
		(start 331.080618 -65.673224)
		(end 330.86929 -65.773046)
		(width 0.1143)
		(layer "In2.Cu")
		(net "P3E_CPU0_PE1_SS_RXP<6>")
	)
	(segment
		(start 308.418738 -94.391988)
		(end 307.849778 -94.391988)
		(width 0.1143)
		(layer "In2.Cu")
		(net "P3E_CPU0_PE1_SS_RXP<6>")
	)
	(segment
		(start 331.8256 -66.1162)
		(end 331.502766 -66.000376)
		(width 0.1143)
		(layer "In2.Cu")
		(net "P3E_CPU0_PE1_SS_RXP<6>")
	)
	(segment
		(start 301.82566 -95.433134)
		(end 301.80153 -95.433134)
		(width 0.0889)
		(layer "In2.Cu")
		(net "P3E_CPU0_PE1_SS_RXP<6>")
	)
	(segment
		(start 350.354138 -61.86297)
		(end 350.120712 -61.86297)
		(width 0.1143)
		(layer "In2.Cu")
		(net "P3E_CPU0_PE1_SS_RXP<6>")
	)
	(segment
		(start 306.831492 -94.442788)
		(end 305.841146 -95.433134)
		(width 0.0889)
		(layer "In2.Cu")
		(net "P3E_CPU0_PE1_SS_RXP<6>")
	)
	(segment
		(start 338.643722 -64.26708)
		(end 336.418428 -64.26708)
		(width 0.1143)
		(layer "In2.Cu")
		(net "P3E_CPU0_PE1_SS_RXP<6>")
	)
	(segment
		(start 348.5515 -63.665608)
		(end 339.245194 -63.665608)
		(width 0.1143)
		(layer "In2.Cu")
		(net "P3E_CPU0_PE1_SS_RXP<6>")
	)
	(segment
		(start 307.82768 -94.391988)
		(end 307.77688 -94.442788)
		(width 0.0889)
		(layer "In2.Cu")
		(net "P3E_CPU0_PE1_SS_RXP<6>")
	)
	(segment
		(start 330.242672 -65.548002)
		(end 328.686922 -66.099182)
		(width 0.1143)
		(layer "In2.Cu")
		(net "P3E_CPU0_PE1_SS_RXP<6>")
	)
	(segment
		(start 325.35241 -72.831706)
		(end 321.912234 -86.200234)
		(width 0.1143)
		(layer "In2.Cu")
		(net "P3E_CPU0_PE1_SS_RXP<6>")
	)
	(segment
		(start 307.849778 -94.391988)
		(end 307.82768 -94.391988)
		(width 0.0889)
		(layer "In2.Cu")
		(net "P3E_CPU0_PE1_SS_RXP<6>")
	)
	(segment
		(start 349.878142 -62.338966)
		(end 348.5515 -63.665608)
		(width 0.1143)
		(layer "In2.Cu")
		(net "P3E_CPU0_PE1_SS_RXP<6>")
	)
	(segment
		(start 328.686922 -66.099182)
		(end 326.390762 -68.797678)
		(width 0.1143)
		(layer "In2.Cu")
		(net "P3E_CPU0_PE1_SS_RXP<6>")
	)
	(segment
		(start 334.84312 -64.802004)
		(end 332.42504 -65.9384)
		(width 0.1143)
		(layer "In2.Cu")
		(net "P3E_CPU0_PE1_SS_RXP<6>")
	)
	(segment
		(start 321.912234 -86.200234)
		(end 313.747404 -92.738194)
		(width 0.1143)
		(layer "In2.Cu")
		(net "P3E_CPU0_PE1_SS_RXP<6>")
	)
	(segment
		(start 351.30105 -60.5409)
		(end 351.30105 -60.916058)
		(width 0.1143)
		(layer "In2.Cu")
		(net "P3E_CPU0_PE1_SS_RXP<6>")
	)
	(segment
		(start 350.7486 -60.4266)
		(end 351.18675 -60.4266)
		(width 0.1143)
		(layer "In2.Cu")
		(net "P3E_CPU0_PE1_SS_RXP<6>")
	)
	(segment
		(start 325.523352 -72.167496)
		(end 325.322438 -72.286368)
		(width 0.1143)
		(layer "In2.Cu")
		(net "P3E_CPU0_PE1_SS_RXP<6>")
	)
	(segment
		(start 302.686212 -95.928434)
		(end 302.65624 -95.928434)
		(width 0.0889)
		(layer "In2.Cu")
		(net "P3E_CPU0_PE1_SS_RXP<6>")
	)
	(segment
		(start 331.502766 -66.000376)
		(end 331.403198 -65.789302)
		(width 0.1143)
		(layer "In2.Cu")
		(net "P3E_CPU0_PE1_SS_RXP<6>")
	)
	(arc
		(start 304.041556 -95.728536)
		(mid 303.834769 -95.517803)
		(end 303.551844 -95.433388)
		(width 0.0889)
		(layer "In2.Cu")
		(net "P3E_CPU0_PE1_SS_RXP<6>")
	)
	(arc
		(start 301.498508 -95.280734)
		(mid 301.531896 -94.99992)
		(end 301.812706 -95.033084)
		(width 0.0889)
		(layer "In2.Cu")
		(net "P3E_CPU0_PE1_SS_RXP<6>")
	)
	(arc
		(start 303.551844 -95.433388)
		(mid 303.529746 -95.432975)
		(end 303.507648 -95.433388)
		(width 0.0889)
		(layer "In2.Cu")
		(net "P3E_CPU0_PE1_SS_RXP<6>")
	)
	(arc
		(start 303.507648 -95.433388)
		(mid 303.224712 -95.517784)
		(end 303.017936 -95.728536)
		(width 0.0889)
		(layer "In2.Cu")
		(net "P3E_CPU0_PE1_SS_RXP<6>")
	)
	(arc
		(start 303.017936 -95.728536)
		(mid 302.877857 -95.871272)
		(end 302.686212 -95.928434)
		(width 0.0889)
		(layer "In2.Cu")
		(net "P3E_CPU0_PE1_SS_RXP<6>")
	)
	(arc
		(start 301.80153 -95.433134)
		(mid 301.633093 -95.390601)
		(end 301.498508 -95.280734)
		(width 0.0889)
		(layer "In2.Cu")
		(net "P3E_CPU0_PE1_SS_RXP<6>")
	)
	(arc
		(start 304.37328 -95.928434)
		(mid 304.181638 -95.871268)
		(end 304.041556 -95.728536)
		(width 0.0889)
		(layer "In2.Cu")
		(net "P3E_CPU0_PE1_SS_RXP<6>")
	)
	(arc
		(start 302.65624 -95.928434)
		(mid 302.464598 -95.871268)
		(end 302.324516 -95.728536)
		(width 0.0889)
		(layer "In2.Cu")
		(net "P3E_CPU0_PE1_SS_RXP<6>")
	)
	(arc
		(start 305.233832 -95.433134)
		(mid 304.945687 -95.515453)
		(end 304.734976 -95.728536)
		(width 0.0889)
		(layer "In2.Cu")
		(net "P3E_CPU0_PE1_SS_RXP<6>")
	)
	(arc
		(start 304.734976 -95.728536)
		(mid 304.594897 -95.871272)
		(end 304.403252 -95.928434)
		(width 0.0889)
		(layer "In2.Cu")
		(net "P3E_CPU0_PE1_SS_RXP<6>")
	)
	(arc
		(start 302.324516 -95.728536)
		(mid 302.113803 -95.515457)
		(end 301.82566 -95.433134)
		(width 0.0889)
		(layer "In2.Cu")
		(net "P3E_CPU0_PE1_SS_RXP<6>")
	)
	(segment
		(start 300.382686 -93.547184)
		(end 300.954186 -93.547184)
		(width 0.1143)
		(layer "F.Cu")
		(net "P3E_CPU0_PE1_SS_RXP<5>")
	)
	(via
		(at 347.9546 -60.4266)
		(size 0.508)
		(drill 0.254)
		(layers "F.Cu" "B.Cu")
		(net "P3E_CPU0_PE1_SS_RXP<5>")
	)
	(via
		(at 300.954186 -93.547184)
		(size 0.508)
		(drill 0.254)
		(layers "F.Cu" "B.Cu")
		(net "P3E_CPU0_PE1_SS_RXP<5>")
	)
	(segment
		(start 347.896434 -60.368434)
		(end 347.9546 -60.4266)
		(width 0.1143)
		(layer "B.Cu")
		(net "P3E_CPU0_PE1_SS_RXP<5>")
	)
	(segment
		(start 347.316806 -60.368434)
		(end 347.896434 -60.368434)
		(width 0.1143)
		(layer "B.Cu")
		(net "P3E_CPU0_PE1_SS_RXP<5>")
	)
	(segment
		(start 324.33387 -73.207372)
		(end 324.248272 -73.53935)
		(width 0.1143)
		(layer "In2.Cu")
		(net "P3E_CPU0_PE1_SS_RXP<5>")
	)
	(segment
		(start 301.830486 -94.442534)
		(end 301.794672 -94.442534)
		(width 0.0889)
		(layer "In2.Cu")
		(net "P3E_CPU0_PE1_SS_RXP<5>")
	)
	(segment
		(start 302.68926 -94.937834)
		(end 302.653192 -94.937834)
		(width 0.0889)
		(layer "In2.Cu")
		(net "P3E_CPU0_PE1_SS_RXP<5>")
	)
	(segment
		(start 324.080378 -74.191114)
		(end 323.995034 -74.523346)
		(width 0.1143)
		(layer "In2.Cu")
		(net "P3E_CPU0_PE1_SS_RXP<5>")
	)
	(segment
		(start 323.708268 -74.973942)
		(end 323.82714 -75.17511)
		(width 0.1143)
		(layer "In2.Cu")
		(net "P3E_CPU0_PE1_SS_RXP<5>")
	)
	(segment
		(start 348.50705 -60.5409)
		(end 348.50705 -61.949838)
		(width 0.1143)
		(layer "In2.Cu")
		(net "P3E_CPU0_PE1_SS_RXP<5>")
	)
	(segment
		(start 348.50705 -61.949838)
		(end 347.42628 -63.030608)
		(width 0.1143)
		(layer "In2.Cu")
		(net "P3E_CPU0_PE1_SS_RXP<5>")
	)
	(segment
		(start 307.886862 -93.348302)
		(end 306.828698 -93.348302)
		(width 0.0889)
		(layer "In2.Cu")
		(net "P3E_CPU0_PE1_SS_RXP<5>")
	)
	(segment
		(start 301.019464 -93.950536)
		(end 300.954186 -93.885258)
		(width 0.0889)
		(layer "In2.Cu")
		(net "P3E_CPU0_PE1_SS_RXP<5>")
	)
	(segment
		(start 313.327796 -91.983052)
		(end 309.086504 -93.297502)
		(width 0.1143)
		(layer "In2.Cu")
		(net "P3E_CPU0_PE1_SS_RXP<5>")
	)
	(segment
		(start 323.995034 -74.523346)
		(end 323.793866 -74.641964)
		(width 0.1143)
		(layer "In2.Cu")
		(net "P3E_CPU0_PE1_SS_RXP<5>")
	)
	(segment
		(start 323.793866 -74.641964)
		(end 323.708268 -74.973942)
		(width 0.1143)
		(layer "In2.Cu")
		(net "P3E_CPU0_PE1_SS_RXP<5>")
	)
	(segment
		(start 307.937662 -93.297502)
		(end 307.886862 -93.348302)
		(width 0.0889)
		(layer "In2.Cu")
		(net "P3E_CPU0_PE1_SS_RXP<5>")
	)
	(segment
		(start 331.159358 -64.167004)
		(end 328.035666 -65.635124)
		(width 0.1143)
		(layer "In2.Cu")
		(net "P3E_CPU0_PE1_SS_RXP<5>")
	)
	(segment
		(start 324.50151 -72.555354)
		(end 324.300596 -72.674226)
		(width 0.1143)
		(layer "In2.Cu")
		(net "P3E_CPU0_PE1_SS_RXP<5>")
	)
	(segment
		(start 338.380324 -63.63208)
		(end 336.15503 -63.63208)
		(width 0.1143)
		(layer "In2.Cu")
		(net "P3E_CPU0_PE1_SS_RXP<5>")
	)
	(segment
		(start 324.248272 -73.53935)
		(end 324.047104 -73.657968)
		(width 0.1143)
		(layer "In2.Cu")
		(net "P3E_CPU0_PE1_SS_RXP<5>")
	)
	(segment
		(start 321.102736 -85.757258)
		(end 313.327796 -91.983052)
		(width 0.1143)
		(layer "In2.Cu")
		(net "P3E_CPU0_PE1_SS_RXP<5>")
	)
	(segment
		(start 325.499984 -68.677536)
		(end 324.50151 -72.555354)
		(width 0.1143)
		(layer "In2.Cu")
		(net "P3E_CPU0_PE1_SS_RXP<5>")
	)
	(segment
		(start 300.954186 -93.885258)
		(end 300.954186 -93.547184)
		(width 0.0889)
		(layer "In2.Cu")
		(net "P3E_CPU0_PE1_SS_RXP<5>")
	)
	(segment
		(start 307.95976 -93.297502)
		(end 307.937662 -93.297502)
		(width 0.0889)
		(layer "In2.Cu")
		(net "P3E_CPU0_PE1_SS_RXP<5>")
	)
	(segment
		(start 305.7779 -94.3991)
		(end 305.146964 -94.3991)
		(width 0.0889)
		(layer "In2.Cu")
		(net "P3E_CPU0_PE1_SS_RXP<5>")
	)
	(segment
		(start 336.15503 -63.63208)
		(end 335.620106 -64.167004)
		(width 0.1143)
		(layer "In2.Cu")
		(net "P3E_CPU0_PE1_SS_RXP<5>")
	)
	(segment
		(start 323.96176 -73.9902)
		(end 324.080378 -74.191114)
		(width 0.1143)
		(layer "In2.Cu")
		(net "P3E_CPU0_PE1_SS_RXP<5>")
	)
	(segment
		(start 335.620106 -64.167004)
		(end 331.159358 -64.167004)
		(width 0.1143)
		(layer "In2.Cu")
		(net "P3E_CPU0_PE1_SS_RXP<5>")
	)
	(segment
		(start 338.981796 -63.030608)
		(end 338.380324 -63.63208)
		(width 0.1143)
		(layer "In2.Cu")
		(net "P3E_CPU0_PE1_SS_RXP<5>")
	)
	(segment
		(start 309.086504 -93.297502)
		(end 307.95976 -93.297502)
		(width 0.1143)
		(layer "In2.Cu")
		(net "P3E_CPU0_PE1_SS_RXP<5>")
	)
	(segment
		(start 328.035666 -65.635124)
		(end 325.499984 -68.677536)
		(width 0.1143)
		(layer "In2.Cu")
		(net "P3E_CPU0_PE1_SS_RXP<5>")
	)
	(segment
		(start 323.82714 -75.17511)
		(end 321.102736 -85.757258)
		(width 0.1143)
		(layer "In2.Cu")
		(net "P3E_CPU0_PE1_SS_RXP<5>")
	)
	(segment
		(start 347.9546 -60.4266)
		(end 348.39275 -60.4266)
		(width 0.1143)
		(layer "In2.Cu")
		(net "P3E_CPU0_PE1_SS_RXP<5>")
	)
	(segment
		(start 303.547526 -94.442534)
		(end 303.511966 -94.442534)
		(width 0.0889)
		(layer "In2.Cu")
		(net "P3E_CPU0_PE1_SS_RXP<5>")
	)
	(segment
		(start 348.39275 -60.4266)
		(end 348.50705 -60.5409)
		(width 0.1143)
		(layer "In2.Cu")
		(net "P3E_CPU0_PE1_SS_RXP<5>")
	)
	(segment
		(start 324.214998 -73.006204)
		(end 324.33387 -73.207372)
		(width 0.1143)
		(layer "In2.Cu")
		(net "P3E_CPU0_PE1_SS_RXP<5>")
	)
	(segment
		(start 324.300596 -72.674226)
		(end 324.214998 -73.006204)
		(width 0.1143)
		(layer "In2.Cu")
		(net "P3E_CPU0_PE1_SS_RXP<5>")
	)
	(segment
		(start 304.4063 -94.937834)
		(end 304.370232 -94.937834)
		(width 0.0889)
		(layer "In2.Cu")
		(net "P3E_CPU0_PE1_SS_RXP<5>")
	)
	(segment
		(start 306.828698 -93.348302)
		(end 305.7779 -94.3991)
		(width 0.0889)
		(layer "In2.Cu")
		(net "P3E_CPU0_PE1_SS_RXP<5>")
	)
	(segment
		(start 347.42628 -63.030608)
		(end 338.981796 -63.030608)
		(width 0.1143)
		(layer "In2.Cu")
		(net "P3E_CPU0_PE1_SS_RXP<5>")
	)
	(segment
		(start 324.047104 -73.657968)
		(end 323.96176 -73.9902)
		(width 0.1143)
		(layer "In2.Cu")
		(net "P3E_CPU0_PE1_SS_RXP<5>")
	)
	(arc
		(start 304.734976 -94.737936)
		(mid 304.596232 -94.879969)
		(end 304.4063 -94.937834)
		(width 0.0889)
		(layer "In2.Cu")
		(net "P3E_CPU0_PE1_SS_RXP<5>")
	)
	(arc
		(start 305.146964 -94.3991)
		(mid 304.910209 -94.531121)
		(end 304.734976 -94.737936)
		(width 0.0889)
		(layer "In2.Cu")
		(net "P3E_CPU0_PE1_SS_RXP<5>")
	)
	(arc
		(start 304.370232 -94.937834)
		(mid 304.180303 -94.879964)
		(end 304.041556 -94.737936)
		(width 0.0889)
		(layer "In2.Cu")
		(net "P3E_CPU0_PE1_SS_RXP<5>")
	)
	(arc
		(start 301.465996 -94.242636)
		(mid 301.277573 -94.043332)
		(end 301.019464 -93.950536)
		(width 0.0889)
		(layer "In2.Cu")
		(net "P3E_CPU0_PE1_SS_RXP<5>")
	)
	(arc
		(start 302.324516 -94.737936)
		(mid 302.115908 -94.526004)
		(end 301.830486 -94.442534)
		(width 0.0889)
		(layer "In2.Cu")
		(net "P3E_CPU0_PE1_SS_RXP<5>")
	)
	(arc
		(start 303.511966 -94.442534)
		(mid 303.226542 -94.526001)
		(end 303.017936 -94.737936)
		(width 0.0889)
		(layer "In2.Cu")
		(net "P3E_CPU0_PE1_SS_RXP<5>")
	)
	(arc
		(start 301.794672 -94.442534)
		(mid 301.604743 -94.384664)
		(end 301.465996 -94.242636)
		(width 0.0889)
		(layer "In2.Cu")
		(net "P3E_CPU0_PE1_SS_RXP<5>")
	)
	(arc
		(start 303.017936 -94.737936)
		(mid 302.879192 -94.879969)
		(end 302.68926 -94.937834)
		(width 0.0889)
		(layer "In2.Cu")
		(net "P3E_CPU0_PE1_SS_RXP<5>")
	)
	(arc
		(start 302.653192 -94.937834)
		(mid 302.463263 -94.879964)
		(end 302.324516 -94.737936)
		(width 0.0889)
		(layer "In2.Cu")
		(net "P3E_CPU0_PE1_SS_RXP<5>")
	)
	(arc
		(start 304.041556 -94.737936)
		(mid 303.832948 -94.526004)
		(end 303.547526 -94.442534)
		(width 0.0889)
		(layer "In2.Cu")
		(net "P3E_CPU0_PE1_SS_RXP<5>")
	)
	(segment
		(start 300.382686 -92.556584)
		(end 300.954186 -92.556584)
		(width 0.1143)
		(layer "F.Cu")
		(net "P3E_CPU0_PE1_SS_RXP<4>")
	)
	(via
		(at 300.954186 -92.556584)
		(size 0.508)
		(drill 0.254)
		(layers "F.Cu" "B.Cu")
		(net "P3E_CPU0_PE1_SS_RXP<4>")
	)
	(via
		(at 345.1606 -60.4266)
		(size 0.508)
		(drill 0.254)
		(layers "F.Cu" "B.Cu")
		(net "P3E_CPU0_PE1_SS_RXP<4>")
	)
	(segment
		(start 345.102434 -60.368434)
		(end 345.1606 -60.4266)
		(width 0.1143)
		(layer "B.Cu")
		(net "P3E_CPU0_PE1_SS_RXP<4>")
	)
	(segment
		(start 344.522806 -60.368434)
		(end 345.102434 -60.368434)
		(width 0.1143)
		(layer "B.Cu")
		(net "P3E_CPU0_PE1_SS_RXP<4>")
	)
	(segment
		(start 300.971966 -92.956634)
		(end 300.9392 -92.956634)
		(width 0.0889)
		(layer "In2.Cu")
		(net "P3E_CPU0_PE1_SS_RXP<4>")
	)
	(segment
		(start 306.677568 -92.653866)
		(end 306.626768 -92.704666)
		(width 0.0889)
		(layer "In2.Cu")
		(net "P3E_CPU0_PE1_SS_RXP<4>")
	)
	(segment
		(start 305.597052 -93.349064)
		(end 305.597052 -93.474794)
		(width 0.0889)
		(layer "In2.Cu")
		(net "P3E_CPU0_PE1_SS_RXP<4>")
	)
	(segment
		(start 303.62779 -93.452188)
		(end 303.508156 -93.452188)
		(width 0.0889)
		(layer "In2.Cu")
		(net "P3E_CPU0_PE1_SS_RXP<4>")
	)
	(segment
		(start 327.542906 -65.13068)
		(end 324.5485 -68.72478)
		(width 0.1143)
		(layer "In2.Cu")
		(net "P3E_CPU0_PE1_SS_RXP<4>")
	)
	(segment
		(start 323.940678 -71.086218)
		(end 323.739764 -71.204836)
		(width 0.1143)
		(layer "In2.Cu")
		(net "P3E_CPU0_PE1_SS_RXP<4>")
	)
	(segment
		(start 323.910706 -70.54088)
		(end 324.029324 -70.741794)
		(width 0.1143)
		(layer "In2.Cu")
		(net "P3E_CPU0_PE1_SS_RXP<4>")
	)
	(segment
		(start 338.116926 -62.99708)
		(end 335.891632 -62.99708)
		(width 0.1143)
		(layer "In2.Cu")
		(net "P3E_CPU0_PE1_SS_RXP<4>")
	)
	(segment
		(start 308.788308 -92.653866)
		(end 306.699666 -92.653866)
		(width 0.1143)
		(layer "In2.Cu")
		(net "P3E_CPU0_PE1_SS_RXP<4>")
	)
	(segment
		(start 301.834296 -93.452188)
		(end 301.80153 -93.452188)
		(width 0.0889)
		(layer "In2.Cu")
		(net "P3E_CPU0_PE1_SS_RXP<4>")
	)
	(segment
		(start 344.67546 -62.395608)
		(end 338.718398 -62.395608)
		(width 0.1143)
		(layer "In2.Cu")
		(net "P3E_CPU0_PE1_SS_RXP<4>")
	)
	(segment
		(start 323.739764 -71.204836)
		(end 323.651118 -71.54926)
		(width 0.1143)
		(layer "In2.Cu")
		(net "P3E_CPU0_PE1_SS_RXP<4>")
	)
	(segment
		(start 345.1606 -60.4266)
		(end 345.59875 -60.4266)
		(width 0.1143)
		(layer "In2.Cu")
		(net "P3E_CPU0_PE1_SS_RXP<4>")
	)
	(segment
		(start 324.25894 -69.187822)
		(end 324.170294 -69.532246)
		(width 0.1143)
		(layer "In2.Cu")
		(net "P3E_CPU0_PE1_SS_RXP<4>")
	)
	(segment
		(start 323.651118 -71.54926)
		(end 323.769736 -71.750428)
		(width 0.1143)
		(layer "In2.Cu")
		(net "P3E_CPU0_PE1_SS_RXP<4>")
	)
	(segment
		(start 345.71305 -60.5409)
		(end 345.71305 -61.358018)
		(width 0.1143)
		(layer "In2.Cu")
		(net "P3E_CPU0_PE1_SS_RXP<4>")
	)
	(segment
		(start 324.288912 -69.733414)
		(end 324.200266 -70.077584)
		(width 0.1143)
		(layer "In2.Cu")
		(net "P3E_CPU0_PE1_SS_RXP<4>")
	)
	(segment
		(start 320.28384 -85.296756)
		(end 312.554112 -91.48699)
		(width 0.1143)
		(layer "In2.Cu")
		(net "P3E_CPU0_PE1_SS_RXP<4>")
	)
	(segment
		(start 324.170294 -69.532246)
		(end 324.288912 -69.733414)
		(width 0.1143)
		(layer "In2.Cu")
		(net "P3E_CPU0_PE1_SS_RXP<4>")
	)
	(segment
		(start 330.943458 -63.532004)
		(end 327.542906 -65.13068)
		(width 0.1143)
		(layer "In2.Cu")
		(net "P3E_CPU0_PE1_SS_RXP<4>")
	)
	(segment
		(start 312.554112 -91.48699)
		(end 308.788308 -92.653866)
		(width 0.1143)
		(layer "In2.Cu")
		(net "P3E_CPU0_PE1_SS_RXP<4>")
	)
	(segment
		(start 305.373786 -93.69806)
		(end 305.094386 -93.69806)
		(width 0.0889)
		(layer "In2.Cu")
		(net "P3E_CPU0_PE1_SS_RXP<4>")
	)
	(segment
		(start 324.459854 -69.069204)
		(end 324.25894 -69.187822)
		(width 0.1143)
		(layer "In2.Cu")
		(net "P3E_CPU0_PE1_SS_RXP<4>")
	)
	(segment
		(start 323.480176 -72.21347)
		(end 323.39153 -72.557894)
		(width 0.1143)
		(layer "In2.Cu")
		(net "P3E_CPU0_PE1_SS_RXP<4>")
	)
	(segment
		(start 305.794664 -93.151452)
		(end 305.597052 -93.349064)
		(width 0.0889)
		(layer "In2.Cu")
		(net "P3E_CPU0_PE1_SS_RXP<4>")
	)
	(segment
		(start 345.59875 -60.4266)
		(end 345.71305 -60.5409)
		(width 0.1143)
		(layer "In2.Cu")
		(net "P3E_CPU0_PE1_SS_RXP<4>")
	)
	(segment
		(start 302.686212 -93.947234)
		(end 302.65624 -93.947234)
		(width 0.0889)
		(layer "In2.Cu")
		(net "P3E_CPU0_PE1_SS_RXP<4>")
	)
	(segment
		(start 324.200266 -70.077584)
		(end 323.999352 -70.196456)
		(width 0.1143)
		(layer "In2.Cu")
		(net "P3E_CPU0_PE1_SS_RXP<4>")
	)
	(segment
		(start 304.726086 -93.60916)
		(end 304.637186 -93.69806)
		(width 0.0889)
		(layer "In2.Cu")
		(net "P3E_CPU0_PE1_SS_RXP<4>")
	)
	(segment
		(start 335.891632 -62.99708)
		(end 335.356708 -63.532004)
		(width 0.1143)
		(layer "In2.Cu")
		(net "P3E_CPU0_PE1_SS_RXP<4>")
	)
	(segment
		(start 300.66107 -92.725748)
		(end 300.954186 -92.556584)
		(width 0.0889)
		(layer "In2.Cu")
		(net "P3E_CPU0_PE1_SS_RXP<4>")
	)
	(segment
		(start 323.510148 -72.758808)
		(end 320.28384 -85.296756)
		(width 0.1143)
		(layer "In2.Cu")
		(net "P3E_CPU0_PE1_SS_RXP<4>")
	)
	(segment
		(start 304.141632 -93.583506)
		(end 303.62779 -93.452188)
		(width 0.0889)
		(layer "In2.Cu")
		(net "P3E_CPU0_PE1_SS_RXP<4>")
	)
	(segment
		(start 323.39153 -72.557894)
		(end 323.510148 -72.758808)
		(width 0.1143)
		(layer "In2.Cu")
		(net "P3E_CPU0_PE1_SS_RXP<4>")
	)
	(segment
		(start 338.718398 -62.395608)
		(end 338.116926 -62.99708)
		(width 0.1143)
		(layer "In2.Cu")
		(net "P3E_CPU0_PE1_SS_RXP<4>")
	)
	(segment
		(start 306.699666 -92.653866)
		(end 306.677568 -92.653866)
		(width 0.0889)
		(layer "In2.Cu")
		(net "P3E_CPU0_PE1_SS_RXP<4>")
	)
	(segment
		(start 323.68109 -72.094598)
		(end 323.480176 -72.21347)
		(width 0.1143)
		(layer "In2.Cu")
		(net "P3E_CPU0_PE1_SS_RXP<4>")
	)
	(segment
		(start 304.296572 -93.69806)
		(end 304.141632 -93.583506)
		(width 0.0889)
		(layer "In2.Cu")
		(net "P3E_CPU0_PE1_SS_RXP<4>")
	)
	(segment
		(start 305.005486 -93.60916)
		(end 304.726086 -93.60916)
		(width 0.0889)
		(layer "In2.Cu")
		(net "P3E_CPU0_PE1_SS_RXP<4>")
	)
	(segment
		(start 305.597052 -93.474794)
		(end 305.373786 -93.69806)
		(width 0.0889)
		(layer "In2.Cu")
		(net "P3E_CPU0_PE1_SS_RXP<4>")
	)
	(segment
		(start 305.920394 -93.151452)
		(end 305.794664 -93.151452)
		(width 0.0889)
		(layer "In2.Cu")
		(net "P3E_CPU0_PE1_SS_RXP<4>")
	)
	(segment
		(start 324.029324 -70.741794)
		(end 323.940678 -71.086218)
		(width 0.1143)
		(layer "In2.Cu")
		(net "P3E_CPU0_PE1_SS_RXP<4>")
	)
	(segment
		(start 324.5485 -68.72478)
		(end 324.459854 -69.069204)
		(width 0.1143)
		(layer "In2.Cu")
		(net "P3E_CPU0_PE1_SS_RXP<4>")
	)
	(segment
		(start 304.637186 -93.69806)
		(end 304.296572 -93.69806)
		(width 0.0889)
		(layer "In2.Cu")
		(net "P3E_CPU0_PE1_SS_RXP<4>")
	)
	(segment
		(start 300.639988 -92.804488)
		(end 300.66107 -92.725748)
		(width 0.0889)
		(layer "In2.Cu")
		(net "P3E_CPU0_PE1_SS_RXP<4>")
	)
	(segment
		(start 305.094386 -93.69806)
		(end 305.005486 -93.60916)
		(width 0.0889)
		(layer "In2.Cu")
		(net "P3E_CPU0_PE1_SS_RXP<4>")
	)
	(segment
		(start 323.999352 -70.196456)
		(end 323.910706 -70.54088)
		(width 0.1143)
		(layer "In2.Cu")
		(net "P3E_CPU0_PE1_SS_RXP<4>")
	)
	(segment
		(start 306.36718 -92.704666)
		(end 305.920394 -93.151452)
		(width 0.0889)
		(layer "In2.Cu")
		(net "P3E_CPU0_PE1_SS_RXP<4>")
	)
	(segment
		(start 345.71305 -61.358018)
		(end 344.67546 -62.395608)
		(width 0.1143)
		(layer "In2.Cu")
		(net "P3E_CPU0_PE1_SS_RXP<4>")
	)
	(segment
		(start 306.626768 -92.704666)
		(end 306.36718 -92.704666)
		(width 0.0889)
		(layer "In2.Cu")
		(net "P3E_CPU0_PE1_SS_RXP<4>")
	)
	(segment
		(start 323.769736 -71.750428)
		(end 323.68109 -72.094598)
		(width 0.1143)
		(layer "In2.Cu")
		(net "P3E_CPU0_PE1_SS_RXP<4>")
	)
	(segment
		(start 335.356708 -63.532004)
		(end 330.943458 -63.532004)
		(width 0.1143)
		(layer "In2.Cu")
		(net "P3E_CPU0_PE1_SS_RXP<4>")
	)
	(arc
		(start 302.65624 -93.947234)
		(mid 302.464598 -93.890068)
		(end 302.324516 -93.747336)
		(width 0.0889)
		(layer "In2.Cu")
		(net "P3E_CPU0_PE1_SS_RXP<4>")
	)
	(arc
		(start 301.80153 -93.452188)
		(mid 301.60768 -93.395838)
		(end 301.465996 -93.252036)
		(width 0.0889)
		(layer "In2.Cu")
		(net "P3E_CPU0_PE1_SS_RXP<4>")
	)
	(arc
		(start 302.324516 -93.747336)
		(mid 302.117512 -93.536472)
		(end 301.834296 -93.452188)
		(width 0.0889)
		(layer "In2.Cu")
		(net "P3E_CPU0_PE1_SS_RXP<4>")
	)
	(arc
		(start 301.465996 -93.252036)
		(mid 301.257388 -93.040104)
		(end 300.971966 -92.956634)
		(width 0.0889)
		(layer "In2.Cu")
		(net "P3E_CPU0_PE1_SS_RXP<4>")
	)
	(arc
		(start 303.017936 -93.747336)
		(mid 302.877857 -93.890072)
		(end 302.686212 -93.947234)
		(width 0.0889)
		(layer "In2.Cu")
		(net "P3E_CPU0_PE1_SS_RXP<4>")
	)
	(arc
		(start 303.508156 -93.452188)
		(mid 303.224939 -93.536469)
		(end 303.017936 -93.747336)
		(width 0.0889)
		(layer "In2.Cu")
		(net "P3E_CPU0_PE1_SS_RXP<4>")
	)
	(arc
		(start 300.9392 -92.956634)
		(mid 300.772906 -92.9134)
		(end 300.639988 -92.804488)
		(width 0.0889)
		(layer "In2.Cu")
		(net "P3E_CPU0_PE1_SS_RXP<4>")
	)
	(segment
		(start 299.524166 -91.070938)
		(end 300.095666 -91.070938)
		(width 0.1143)
		(layer "F.Cu")
		(net "P3E_CPU0_PE1_SS_RXP<3>")
	)
	(via
		(at 342.3666 -60.4266)
		(size 0.508)
		(drill 0.254)
		(layers "F.Cu" "B.Cu")
		(net "P3E_CPU0_PE1_SS_RXP<3>")
	)
	(via
		(at 300.095666 -91.070938)
		(size 0.508)
		(drill 0.254)
		(layers "F.Cu" "B.Cu")
		(net "P3E_CPU0_PE1_SS_RXP<3>")
	)
	(segment
		(start 342.308434 -60.368434)
		(end 342.3666 -60.4266)
		(width 0.1143)
		(layer "B.Cu")
		(net "P3E_CPU0_PE1_SS_RXP<3>")
	)
	(segment
		(start 341.728806 -60.368434)
		(end 342.308434 -60.368434)
		(width 0.1143)
		(layer "B.Cu")
		(net "P3E_CPU0_PE1_SS_RXP<3>")
	)
	(segment
		(start 322.531232 -72.923146)
		(end 322.442586 -73.26757)
		(width 0.1143)
		(layer "In2.Cu")
		(net "P3E_CPU0_PE1_SS_RXP<3>")
	)
	(segment
		(start 322.412614 -72.722232)
		(end 322.531232 -72.923146)
		(width 0.1143)
		(layer "In2.Cu")
		(net "P3E_CPU0_PE1_SS_RXP<3>")
	)
	(segment
		(start 312.135774 -90.80246)
		(end 308.313074 -91.98737)
		(width 0.1143)
		(layer "In2.Cu")
		(net "P3E_CPU0_PE1_SS_RXP<3>")
	)
	(segment
		(start 308.313074 -91.98737)
		(end 305.863498 -91.991434)
		(width 0.1143)
		(layer "In2.Cu")
		(net "P3E_CPU0_PE1_SS_RXP<3>")
	)
	(segment
		(start 338.455 -61.760608)
		(end 337.853528 -62.36208)
		(width 0.1143)
		(layer "In2.Cu")
		(net "P3E_CPU0_PE1_SS_RXP<3>")
	)
	(segment
		(start 322.50126 -72.377808)
		(end 322.412614 -72.722232)
		(width 0.1143)
		(layer "In2.Cu")
		(net "P3E_CPU0_PE1_SS_RXP<3>")
	)
	(segment
		(start 342.91905 -60.5409)
		(end 342.91905 -61.312552)
		(width 0.1143)
		(layer "In2.Cu")
		(net "P3E_CPU0_PE1_SS_RXP<3>")
	)
	(segment
		(start 321.899534 -74.714354)
		(end 322.018152 -74.915522)
		(width 0.1143)
		(layer "In2.Cu")
		(net "P3E_CPU0_PE1_SS_RXP<3>")
	)
	(segment
		(start 323.582538 -68.841874)
		(end 322.702428 -72.25919)
		(width 0.1143)
		(layer "In2.Cu")
		(net "P3E_CPU0_PE1_SS_RXP<3>")
	)
	(segment
		(start 305.863498 -91.991434)
		(end 304.949352 -92.905834)
		(width 0.1143)
		(layer "In2.Cu")
		(net "P3E_CPU0_PE1_SS_RXP<3>")
	)
	(segment
		(start 322.702428 -72.25919)
		(end 322.50126 -72.377808)
		(width 0.1143)
		(layer "In2.Cu")
		(net "P3E_CPU0_PE1_SS_RXP<3>")
	)
	(segment
		(start 303.551336 -92.461588)
		(end 303.508156 -92.461588)
		(width 0.0889)
		(layer "In2.Cu")
		(net "P3E_CPU0_PE1_SS_RXP<3>")
	)
	(segment
		(start 322.152772 -73.730612)
		(end 322.271644 -73.931526)
		(width 0.1143)
		(layer "In2.Cu")
		(net "P3E_CPU0_PE1_SS_RXP<3>")
	)
	(segment
		(start 300.095666 -91.409012)
		(end 300.095666 -91.070938)
		(width 0.0889)
		(layer "In2.Cu")
		(net "P3E_CPU0_PE1_SS_RXP<3>")
	)
	(segment
		(start 300.971966 -91.966034)
		(end 300.9392 -91.966034)
		(width 0.0889)
		(layer "In2.Cu")
		(net "P3E_CPU0_PE1_SS_RXP<3>")
	)
	(segment
		(start 304.949352 -92.905834)
		(end 304.847498 -92.905834)
		(width 0.1143)
		(layer "In2.Cu")
		(net "P3E_CPU0_PE1_SS_RXP<3>")
	)
	(segment
		(start 335.09331 -62.897004)
		(end 330.623164 -62.897004)
		(width 0.1143)
		(layer "In2.Cu")
		(net "P3E_CPU0_PE1_SS_RXP<3>")
	)
	(segment
		(start 321.985132 -74.382376)
		(end 321.899534 -74.714354)
		(width 0.1143)
		(layer "In2.Cu")
		(net "P3E_CPU0_PE1_SS_RXP<3>")
	)
	(segment
		(start 335.628234 -62.36208)
		(end 335.09331 -62.897004)
		(width 0.1143)
		(layer "In2.Cu")
		(net "P3E_CPU0_PE1_SS_RXP<3>")
	)
	(segment
		(start 342.80475 -60.4266)
		(end 342.91905 -60.5409)
		(width 0.1143)
		(layer "In2.Cu")
		(net "P3E_CPU0_PE1_SS_RXP<3>")
	)
	(segment
		(start 319.431416 -84.96046)
		(end 312.135774 -90.80246)
		(width 0.1143)
		(layer "In2.Cu")
		(net "P3E_CPU0_PE1_SS_RXP<3>")
	)
	(segment
		(start 322.018152 -74.915522)
		(end 319.431416 -84.96046)
		(width 0.1143)
		(layer "In2.Cu")
		(net "P3E_CPU0_PE1_SS_RXP<3>")
	)
	(segment
		(start 302.686212 -92.956634)
		(end 302.65624 -92.956634)
		(width 0.0889)
		(layer "In2.Cu")
		(net "P3E_CPU0_PE1_SS_RXP<3>")
	)
	(segment
		(start 322.442586 -73.26757)
		(end 322.241418 -73.386188)
		(width 0.1143)
		(layer "In2.Cu")
		(net "P3E_CPU0_PE1_SS_RXP<3>")
	)
	(segment
		(start 342.470994 -61.760608)
		(end 338.455 -61.760608)
		(width 0.1143)
		(layer "In2.Cu")
		(net "P3E_CPU0_PE1_SS_RXP<3>")
	)
	(segment
		(start 322.271644 -73.931526)
		(end 322.186046 -74.263504)
		(width 0.1143)
		(layer "In2.Cu")
		(net "P3E_CPU0_PE1_SS_RXP<3>")
	)
	(segment
		(start 337.853528 -62.36208)
		(end 335.628234 -62.36208)
		(width 0.1143)
		(layer "In2.Cu")
		(net "P3E_CPU0_PE1_SS_RXP<3>")
	)
	(segment
		(start 304.7746 -92.956634)
		(end 304.37328 -92.956634)
		(width 0.0889)
		(layer "In2.Cu")
		(net "P3E_CPU0_PE1_SS_RXP<3>")
	)
	(segment
		(start 342.91905 -61.312552)
		(end 342.470994 -61.760608)
		(width 0.1143)
		(layer "In2.Cu")
		(net "P3E_CPU0_PE1_SS_RXP<3>")
	)
	(segment
		(start 342.3666 -60.4266)
		(end 342.80475 -60.4266)
		(width 0.1143)
		(layer "In2.Cu")
		(net "P3E_CPU0_PE1_SS_RXP<3>")
	)
	(segment
		(start 327.19137 -64.510158)
		(end 323.582538 -68.841874)
		(width 0.1143)
		(layer "In2.Cu")
		(net "P3E_CPU0_PE1_SS_RXP<3>")
	)
	(segment
		(start 304.8254 -92.905834)
		(end 304.7746 -92.956634)
		(width 0.0889)
		(layer "In2.Cu")
		(net "P3E_CPU0_PE1_SS_RXP<3>")
	)
	(segment
		(start 330.623164 -62.897004)
		(end 327.19137 -64.510158)
		(width 0.1143)
		(layer "In2.Cu")
		(net "P3E_CPU0_PE1_SS_RXP<3>")
	)
	(segment
		(start 322.186046 -74.263504)
		(end 321.985132 -74.382376)
		(width 0.1143)
		(layer "In2.Cu")
		(net "P3E_CPU0_PE1_SS_RXP<3>")
	)
	(segment
		(start 300.16069 -91.474036)
		(end 300.095666 -91.409012)
		(width 0.0889)
		(layer "In2.Cu")
		(net "P3E_CPU0_PE1_SS_RXP<3>")
	)
	(segment
		(start 322.241418 -73.386188)
		(end 322.152772 -73.730612)
		(width 0.1143)
		(layer "In2.Cu")
		(net "P3E_CPU0_PE1_SS_RXP<3>")
	)
	(segment
		(start 301.834296 -92.461588)
		(end 301.80153 -92.461588)
		(width 0.0889)
		(layer "In2.Cu")
		(net "P3E_CPU0_PE1_SS_RXP<3>")
	)
	(segment
		(start 304.847498 -92.905834)
		(end 304.8254 -92.905834)
		(width 0.0889)
		(layer "In2.Cu")
		(net "P3E_CPU0_PE1_SS_RXP<3>")
	)
	(arc
		(start 304.041556 -92.756736)
		(mid 303.834552 -92.545872)
		(end 303.551336 -92.461588)
		(width 0.0889)
		(layer "In2.Cu")
		(net "P3E_CPU0_PE1_SS_RXP<3>")
	)
	(arc
		(start 302.324516 -92.756736)
		(mid 302.117512 -92.545872)
		(end 301.834296 -92.461588)
		(width 0.0889)
		(layer "In2.Cu")
		(net "P3E_CPU0_PE1_SS_RXP<3>")
	)
	(arc
		(start 301.80153 -92.461588)
		(mid 301.60768 -92.405238)
		(end 301.465996 -92.261436)
		(width 0.0889)
		(layer "In2.Cu")
		(net "P3E_CPU0_PE1_SS_RXP<3>")
	)
	(arc
		(start 304.37328 -92.956634)
		(mid 304.181638 -92.899468)
		(end 304.041556 -92.756736)
		(width 0.0889)
		(layer "In2.Cu")
		(net "P3E_CPU0_PE1_SS_RXP<3>")
	)
	(arc
		(start 300.607476 -91.766136)
		(mid 300.418948 -91.566763)
		(end 300.16069 -91.474036)
		(width 0.0889)
		(layer "In2.Cu")
		(net "P3E_CPU0_PE1_SS_RXP<3>")
	)
	(arc
		(start 302.65624 -92.956634)
		(mid 302.464598 -92.899468)
		(end 302.324516 -92.756736)
		(width 0.0889)
		(layer "In2.Cu")
		(net "P3E_CPU0_PE1_SS_RXP<3>")
	)
	(arc
		(start 300.9392 -91.966034)
		(mid 300.747558 -91.908868)
		(end 300.607476 -91.766136)
		(width 0.0889)
		(layer "In2.Cu")
		(net "P3E_CPU0_PE1_SS_RXP<3>")
	)
	(arc
		(start 303.508156 -92.461588)
		(mid 303.224939 -92.545869)
		(end 303.017936 -92.756736)
		(width 0.0889)
		(layer "In2.Cu")
		(net "P3E_CPU0_PE1_SS_RXP<3>")
	)
	(arc
		(start 303.017936 -92.756736)
		(mid 302.877857 -92.899472)
		(end 302.686212 -92.956634)
		(width 0.0889)
		(layer "In2.Cu")
		(net "P3E_CPU0_PE1_SS_RXP<3>")
	)
	(arc
		(start 301.465996 -92.261436)
		(mid 301.257388 -92.049504)
		(end 300.971966 -91.966034)
		(width 0.0889)
		(layer "In2.Cu")
		(net "P3E_CPU0_PE1_SS_RXP<3>")
	)
	(segment
		(start 300.382686 -91.565984)
		(end 300.954186 -91.565984)
		(width 0.1143)
		(layer "F.Cu")
		(net "P3E_CPU0_PE1_SS_RXP<2>")
	)
	(via
		(at 339.5726 -60.4266)
		(size 0.508)
		(drill 0.254)
		(layers "F.Cu" "B.Cu")
		(net "P3E_CPU0_PE1_SS_RXP<2>")
	)
	(via
		(at 300.954186 -91.565984)
		(size 0.508)
		(drill 0.254)
		(layers "F.Cu" "B.Cu")
		(net "P3E_CPU0_PE1_SS_RXP<2>")
	)
	(segment
		(start 338.934806 -60.368434)
		(end 339.514434 -60.368434)
		(width 0.1143)
		(layer "B.Cu")
		(net "P3E_CPU0_PE1_SS_RXP<2>")
	)
	(segment
		(start 339.514434 -60.368434)
		(end 339.5726 -60.4266)
		(width 0.1143)
		(layer "B.Cu")
		(net "P3E_CPU0_PE1_SS_RXP<2>")
	)
	(segment
		(start 340.12505 -60.8584)
		(end 340.12505 -60.5409)
		(width 0.1143)
		(layer "In2.Cu")
		(net "P3E_CPU0_PE1_SS_RXP<2>")
	)
	(segment
		(start 305.645058 -91.181428)
		(end 305.884072 -90.942414)
		(width 0.0889)
		(layer "In2.Cu")
		(net "P3E_CPU0_PE1_SS_RXP<2>")
	)
	(segment
		(start 303.508156 -91.470988)
		(end 303.551336 -91.470988)
		(width 0.0889)
		(layer "In2.Cu")
		(net "P3E_CPU0_PE1_SS_RXP<2>")
	)
	(segment
		(start 301.183548 -91.470988)
		(end 301.834296 -91.470988)
		(width 0.0889)
		(layer "In2.Cu")
		(net "P3E_CPU0_PE1_SS_RXP<2>")
	)
	(segment
		(start 330.316586 -62.262004)
		(end 334.829912 -62.262004)
		(width 0.1143)
		(layer "In2.Cu")
		(net "P3E_CPU0_PE1_SS_RXP<2>")
	)
	(segment
		(start 322.112132 -70.156578)
		(end 322.197476 -69.8246)
		(width 0.1143)
		(layer "In2.Cu")
		(net "P3E_CPU0_PE1_SS_RXP<2>")
	)
	(segment
		(start 322.197476 -69.8246)
		(end 322.398644 -69.705728)
		(width 0.1143)
		(layer "In2.Cu")
		(net "P3E_CPU0_PE1_SS_RXP<2>")
	)
	(segment
		(start 304.37328 -91.966034)
		(end 304.403252 -91.966034)
		(width 0.0889)
		(layer "In2.Cu")
		(net "P3E_CPU0_PE1_SS_RXP<2>")
	)
	(segment
		(start 321.684904 -71.816976)
		(end 321.885818 -71.698358)
		(width 0.1143)
		(layer "In2.Cu")
		(net "P3E_CPU0_PE1_SS_RXP<2>")
	)
	(segment
		(start 305.884072 -90.942414)
		(end 306.337716 -90.942414)
		(width 0.0889)
		(layer "In2.Cu")
		(net "P3E_CPU0_PE1_SS_RXP<2>")
	)
	(segment
		(start 318.59855 -84.472526)
		(end 321.714622 -72.362568)
		(width 0.1143)
		(layer "In2.Cu")
		(net "P3E_CPU0_PE1_SS_RXP<2>")
	)
	(segment
		(start 321.714876 -72.362568)
		(end 321.596258 -72.1614)
		(width 0.1143)
		(layer "In2.Cu")
		(net "P3E_CPU0_PE1_SS_RXP<2>")
	)
	(segment
		(start 335.364836 -61.72708)
		(end 337.59013 -61.72708)
		(width 0.1143)
		(layer "In2.Cu")
		(net "P3E_CPU0_PE1_SS_RXP<2>")
	)
	(segment
		(start 340.12505 -60.5409)
		(end 340.01075 -60.4266)
		(width 0.1143)
		(layer "In2.Cu")
		(net "P3E_CPU0_PE1_SS_RXP<2>")
	)
	(segment
		(start 302.65624 -91.966034)
		(end 302.686212 -91.966034)
		(width 0.0889)
		(layer "In2.Cu")
		(net "P3E_CPU0_PE1_SS_RXP<2>")
	)
	(segment
		(start 334.829912 -62.262004)
		(end 335.364836 -61.72708)
		(width 0.1143)
		(layer "In2.Cu")
		(net "P3E_CPU0_PE1_SS_RXP<2>")
	)
	(segment
		(start 322.57619 -69.015356)
		(end 326.841612 -63.895732)
		(width 0.1143)
		(layer "In2.Cu")
		(net "P3E_CPU0_PE1_SS_RXP<2>")
	)
	(segment
		(start 340.01075 -60.4266)
		(end 339.5726 -60.4266)
		(width 0.1143)
		(layer "In2.Cu")
		(net "P3E_CPU0_PE1_SS_RXP<2>")
	)
	(segment
		(start 318.598804 -84.472526)
		(end 318.59855 -84.472526)
		(width 0.1143)
		(layer "In2.Cu")
		(net "P3E_CPU0_PE1_SS_RXP<2>")
	)
	(segment
		(start 321.714622 -72.362568)
		(end 321.714876 -72.362568)
		(width 0.1143)
		(layer "In2.Cu")
		(net "P3E_CPU0_PE1_SS_RXP<2>")
	)
	(segment
		(start 321.596258 -72.1614)
		(end 321.684904 -71.816976)
		(width 0.1143)
		(layer "In2.Cu")
		(net "P3E_CPU0_PE1_SS_RXP<2>")
	)
	(segment
		(start 339.871558 -61.111892)
		(end 340.12505 -60.8584)
		(width 0.1143)
		(layer "In2.Cu")
		(net "P3E_CPU0_PE1_SS_RXP<2>")
	)
	(segment
		(start 305.593496 -91.270836)
		(end 305.645058 -91.181428)
		(width 0.0889)
		(layer "In2.Cu")
		(net "P3E_CPU0_PE1_SS_RXP<2>")
	)
	(segment
		(start 311.389776 -90.24493)
		(end 318.598804 -84.472526)
		(width 0.1143)
		(layer "In2.Cu")
		(net "P3E_CPU0_PE1_SS_RXP<2>")
	)
	(segment
		(start 307.64734 -91.2622)
		(end 307.69814 -91.2114)
		(width 0.0889)
		(layer "In2.Cu")
		(net "P3E_CPU0_PE1_SS_RXP<2>")
	)
	(segment
		(start 337.59013 -61.72708)
		(end 338.205318 -61.111892)
		(width 0.1143)
		(layer "In2.Cu")
		(net "P3E_CPU0_PE1_SS_RXP<2>")
	)
	(segment
		(start 326.841612 -63.895732)
		(end 330.316586 -62.262004)
		(width 0.1143)
		(layer "In2.Cu")
		(net "P3E_CPU0_PE1_SS_RXP<2>")
	)
	(segment
		(start 321.885818 -71.698358)
		(end 321.974464 -71.353934)
		(width 0.1143)
		(layer "In2.Cu")
		(net "P3E_CPU0_PE1_SS_RXP<2>")
	)
	(segment
		(start 322.398644 -69.705728)
		(end 322.57619 -69.015356)
		(width 0.1143)
		(layer "In2.Cu")
		(net "P3E_CPU0_PE1_SS_RXP<2>")
	)
	(segment
		(start 306.657502 -91.2622)
		(end 307.64734 -91.2622)
		(width 0.0889)
		(layer "In2.Cu")
		(net "P3E_CPU0_PE1_SS_RXP<2>")
	)
	(segment
		(start 306.337716 -90.942414)
		(end 306.657502 -91.2622)
		(width 0.0889)
		(layer "In2.Cu")
		(net "P3E_CPU0_PE1_SS_RXP<2>")
	)
	(segment
		(start 321.944492 -70.808342)
		(end 322.145406 -70.689724)
		(width 0.1143)
		(layer "In2.Cu")
		(net "P3E_CPU0_PE1_SS_RXP<2>")
	)
	(segment
		(start 305.225196 -91.470988)
		(end 305.261264 -91.470988)
		(width 0.0889)
		(layer "In2.Cu")
		(net "P3E_CPU0_PE1_SS_RXP<2>")
	)
	(segment
		(start 322.23075 -70.357746)
		(end 322.112132 -70.156578)
		(width 0.1143)
		(layer "In2.Cu")
		(net "P3E_CPU0_PE1_SS_RXP<2>")
	)
	(segment
		(start 338.205318 -61.111892)
		(end 339.871558 -61.111892)
		(width 0.1143)
		(layer "In2.Cu")
		(net "P3E_CPU0_PE1_SS_RXP<2>")
	)
	(segment
		(start 322.145406 -70.689724)
		(end 322.23075 -70.357746)
		(width 0.1143)
		(layer "In2.Cu")
		(net "P3E_CPU0_PE1_SS_RXP<2>")
	)
	(segment
		(start 321.974464 -71.353934)
		(end 321.855846 -71.152766)
		(width 0.1143)
		(layer "In2.Cu")
		(net "P3E_CPU0_PE1_SS_RXP<2>")
	)
	(segment
		(start 307.69814 -91.2114)
		(end 307.720238 -91.2114)
		(width 0.0889)
		(layer "In2.Cu")
		(net "P3E_CPU0_PE1_SS_RXP<2>")
	)
	(segment
		(start 321.855846 -71.152766)
		(end 321.944492 -70.808342)
		(width 0.1143)
		(layer "In2.Cu")
		(net "P3E_CPU0_PE1_SS_RXP<2>")
	)
	(segment
		(start 307.720238 -91.2114)
		(end 308.273196 -91.2114)
		(width 0.1143)
		(layer "In2.Cu")
		(net "P3E_CPU0_PE1_SS_RXP<2>")
	)
	(segment
		(start 308.273196 -91.2114)
		(end 311.389776 -90.24493)
		(width 0.1143)
		(layer "In2.Cu")
		(net "P3E_CPU0_PE1_SS_RXP<2>")
	)
	(arc
		(start 303.017936 -91.766136)
		(mid 303.22494 -91.555272)
		(end 303.508156 -91.470988)
		(width 0.0889)
		(layer "In2.Cu")
		(net "P3E_CPU0_PE1_SS_RXP<2>")
	)
	(arc
		(start 303.551336 -91.470988)
		(mid 303.834553 -91.555269)
		(end 304.041556 -91.766136)
		(width 0.0889)
		(layer "In2.Cu")
		(net "P3E_CPU0_PE1_SS_RXP<2>")
	)
	(arc
		(start 304.041556 -91.766136)
		(mid 304.181635 -91.908872)
		(end 304.37328 -91.966034)
		(width 0.0889)
		(layer "In2.Cu")
		(net "P3E_CPU0_PE1_SS_RXP<2>")
	)
	(arc
		(start 302.324516 -91.766136)
		(mid 302.464595 -91.908872)
		(end 302.65624 -91.966034)
		(width 0.0889)
		(layer "In2.Cu")
		(net "P3E_CPU0_PE1_SS_RXP<2>")
	)
	(arc
		(start 305.261264 -91.470988)
		(mid 305.453281 -91.41388)
		(end 305.593496 -91.270836)
		(width 0.0889)
		(layer "In2.Cu")
		(net "P3E_CPU0_PE1_SS_RXP<2>")
	)
	(arc
		(start 302.686212 -91.966034)
		(mid 302.877854 -91.908868)
		(end 303.017936 -91.766136)
		(width 0.0889)
		(layer "In2.Cu")
		(net "P3E_CPU0_PE1_SS_RXP<2>")
	)
	(arc
		(start 301.834296 -91.470988)
		(mid 302.117513 -91.555269)
		(end 302.324516 -91.766136)
		(width 0.0889)
		(layer "In2.Cu")
		(net "P3E_CPU0_PE1_SS_RXP<2>")
	)
	(arc
		(start 304.403252 -91.966034)
		(mid 304.594894 -91.908868)
		(end 304.734976 -91.766136)
		(width 0.0889)
		(layer "In2.Cu")
		(net "P3E_CPU0_PE1_SS_RXP<2>")
	)
	(arc
		(start 300.954186 -91.565984)
		(mid 301.059418 -91.49567)
		(end 301.183548 -91.470988)
		(width 0.0889)
		(layer "In2.Cu")
		(net "P3E_CPU0_PE1_SS_RXP<2>")
	)
	(arc
		(start 304.734976 -91.766136)
		(mid 304.94198 -91.555272)
		(end 305.225196 -91.470988)
		(width 0.0889)
		(layer "In2.Cu")
		(net "P3E_CPU0_PE1_SS_RXP<2>")
	)
	(segment
		(start 302.099726 -90.575384)
		(end 302.671226 -90.575384)
		(width 0.1143)
		(layer "F.Cu")
		(net "P3E_CPU0_PE1_SS_RXP<1>")
	)
	(via
		(at 302.671226 -90.575384)
		(size 0.508)
		(drill 0.254)
		(layers "F.Cu" "B.Cu")
		(net "P3E_CPU0_PE1_SS_RXP<1>")
	)
	(via
		(at 336.7786 -60.4266)
		(size 0.508)
		(drill 0.254)
		(layers "F.Cu" "B.Cu")
		(net "P3E_CPU0_PE1_SS_RXP<1>")
	)
	(segment
		(start 336.140806 -60.368434)
		(end 336.720434 -60.368434)
		(width 0.1143)
		(layer "B.Cu")
		(net "P3E_CPU0_PE1_SS_RXP<1>")
	)
	(segment
		(start 336.720434 -60.368434)
		(end 336.7786 -60.4266)
		(width 0.1143)
		(layer "B.Cu")
		(net "P3E_CPU0_PE1_SS_RXP<1>")
	)
	(segment
		(start 308.4068 -89.98458)
		(end 307.756052 -89.98458)
		(width 0.0889)
		(layer "In2.Cu")
		(net "P3E_CPU0_PE1_SS_RXP<1>")
	)
	(segment
		(start 321.252342 -69.849746)
		(end 321.051174 -69.968364)
		(width 0.1143)
		(layer "In2.Cu")
		(net "P3E_CPU0_PE1_SS_RXP<1>")
	)
	(segment
		(start 320.70294 -71.321422)
		(end 320.821812 -71.52259)
		(width 0.1143)
		(layer "In2.Cu")
		(net "P3E_CPU0_PE1_SS_RXP<1>")
	)
	(segment
		(start 321.340988 -69.505322)
		(end 321.252342 -69.849746)
		(width 0.1143)
		(layer "In2.Cu")
		(net "P3E_CPU0_PE1_SS_RXP<1>")
	)
	(segment
		(start 305.241706 -90.2208)
		(end 304.898044 -90.564208)
		(width 0.0889)
		(layer "In2.Cu")
		(net "P3E_CPU0_PE1_SS_RXP<1>")
	)
	(segment
		(start 321.0814 -70.513956)
		(end 320.992754 -70.85838)
		(width 0.1143)
		(layer "In2.Cu")
		(net "P3E_CPU0_PE1_SS_RXP<1>")
	)
	(segment
		(start 306.592986 -90.1319)
		(end 306.326286 -90.1319)
		(width 0.0889)
		(layer "In2.Cu")
		(net "P3E_CPU0_PE1_SS_RXP<1>")
	)
	(segment
		(start 320.962528 -70.312788)
		(end 321.0814 -70.513956)
		(width 0.1143)
		(layer "In2.Cu")
		(net "P3E_CPU0_PE1_SS_RXP<1>")
	)
	(segment
		(start 334.566514 -61.627004)
		(end 329.941174 -61.627004)
		(width 0.1143)
		(layer "In2.Cu")
		(net "P3E_CPU0_PE1_SS_RXP<1>")
	)
	(segment
		(start 320.821812 -71.52259)
		(end 320.733166 -71.867014)
		(width 0.1143)
		(layer "In2.Cu")
		(net "P3E_CPU0_PE1_SS_RXP<1>")
	)
	(segment
		(start 320.562224 -72.53097)
		(end 320.473578 -72.875394)
		(width 0.1143)
		(layer "In2.Cu")
		(net "P3E_CPU0_PE1_SS_RXP<1>")
	)
	(segment
		(start 320.791586 -70.976998)
		(end 320.70294 -71.321422)
		(width 0.1143)
		(layer "In2.Cu")
		(net "P3E_CPU0_PE1_SS_RXP<1>")
	)
	(segment
		(start 337.33105 -60.622434)
		(end 337.33105 -60.858908)
		(width 0.1143)
		(layer "In2.Cu")
		(net "P3E_CPU0_PE1_SS_RXP<1>")
	)
	(segment
		(start 311.119012 -89.266776)
		(end 308.917848 -89.93378)
		(width 0.1143)
		(layer "In2.Cu")
		(net "P3E_CPU0_PE1_SS_RXP<1>")
	)
	(segment
		(start 305.970686 -90.2208)
		(end 305.881786 -90.1319)
		(width 0.0889)
		(layer "In2.Cu")
		(net "P3E_CPU0_PE1_SS_RXP<1>")
	)
	(segment
		(start 320.992754 -70.85838)
		(end 320.791586 -70.976998)
		(width 0.1143)
		(layer "In2.Cu")
		(net "P3E_CPU0_PE1_SS_RXP<1>")
	)
	(segment
		(start 326.593454 -63.201042)
		(end 321.340988 -69.505322)
		(width 0.1143)
		(layer "In2.Cu")
		(net "P3E_CPU0_PE1_SS_RXP<1>")
	)
	(segment
		(start 335.101438 -61.09208)
		(end 334.566514 -61.627004)
		(width 0.1143)
		(layer "In2.Cu")
		(net "P3E_CPU0_PE1_SS_RXP<1>")
	)
	(segment
		(start 321.051174 -69.968364)
		(end 320.962528 -70.312788)
		(width 0.1143)
		(layer "In2.Cu")
		(net "P3E_CPU0_PE1_SS_RXP<1>")
	)
	(segment
		(start 306.326286 -90.1319)
		(end 306.237386 -90.2208)
		(width 0.0889)
		(layer "In2.Cu")
		(net "P3E_CPU0_PE1_SS_RXP<1>")
	)
	(segment
		(start 337.097878 -61.09208)
		(end 335.101438 -61.09208)
		(width 0.1143)
		(layer "In2.Cu")
		(net "P3E_CPU0_PE1_SS_RXP<1>")
	)
	(segment
		(start 307.756052 -89.98458)
		(end 307.146198 -90.2208)
		(width 0.0889)
		(layer "In2.Cu")
		(net "P3E_CPU0_PE1_SS_RXP<1>")
	)
	(segment
		(start 336.7786 -60.4266)
		(end 337.135216 -60.4266)
		(width 0.1143)
		(layer "In2.Cu")
		(net "P3E_CPU0_PE1_SS_RXP<1>")
	)
	(segment
		(start 306.237386 -90.2208)
		(end 305.970686 -90.2208)
		(width 0.0889)
		(layer "In2.Cu")
		(net "P3E_CPU0_PE1_SS_RXP<1>")
	)
	(segment
		(start 337.135216 -60.4266)
		(end 337.33105 -60.622434)
		(width 0.1143)
		(layer "In2.Cu")
		(net "P3E_CPU0_PE1_SS_RXP<1>")
	)
	(segment
		(start 302.357028 -90.823288)
		(end 302.37811 -90.744548)
		(width 0.0889)
		(layer "In2.Cu")
		(net "P3E_CPU0_PE1_SS_RXP<1>")
	)
	(segment
		(start 320.531998 -71.985632)
		(end 320.443352 -72.330056)
		(width 0.1143)
		(layer "In2.Cu")
		(net "P3E_CPU0_PE1_SS_RXP<1>")
	)
	(segment
		(start 337.33105 -60.858908)
		(end 337.097878 -61.09208)
		(width 0.1143)
		(layer "In2.Cu")
		(net "P3E_CPU0_PE1_SS_RXP<1>")
	)
	(segment
		(start 320.473578 -72.875394)
		(end 320.27241 -72.994012)
		(width 0.1143)
		(layer "In2.Cu")
		(net "P3E_CPU0_PE1_SS_RXP<1>")
	)
	(segment
		(start 320.183764 -73.338436)
		(end 320.302636 -73.53935)
		(width 0.1143)
		(layer "In2.Cu")
		(net "P3E_CPU0_PE1_SS_RXP<1>")
	)
	(segment
		(start 320.733166 -71.867014)
		(end 320.531998 -71.985632)
		(width 0.1143)
		(layer "In2.Cu")
		(net "P3E_CPU0_PE1_SS_RXP<1>")
	)
	(segment
		(start 305.615086 -90.1319)
		(end 305.526186 -90.2208)
		(width 0.0889)
		(layer "In2.Cu")
		(net "P3E_CPU0_PE1_SS_RXP<1>")
	)
	(segment
		(start 320.302636 -73.53935)
		(end 317.586614 -84.087462)
		(width 0.1143)
		(layer "In2.Cu")
		(net "P3E_CPU0_PE1_SS_RXP<1>")
	)
	(segment
		(start 302.686212 -90.975434)
		(end 302.65624 -90.975434)
		(width 0.0889)
		(layer "In2.Cu")
		(net "P3E_CPU0_PE1_SS_RXP<1>")
	)
	(segment
		(start 304.735738 -90.774012)
		(end 304.734976 -90.775536)
		(width 0.0889)
		(layer "In2.Cu")
		(net "P3E_CPU0_PE1_SS_RXP<1>")
	)
	(segment
		(start 329.941174 -61.627004)
		(end 326.593454 -63.201042)
		(width 0.1143)
		(layer "In2.Cu")
		(net "P3E_CPU0_PE1_SS_RXP<1>")
	)
	(segment
		(start 303.551336 -90.480388)
		(end 303.508156 -90.480388)
		(width 0.0889)
		(layer "In2.Cu")
		(net "P3E_CPU0_PE1_SS_RXP<1>")
	)
	(segment
		(start 306.681886 -90.2208)
		(end 306.592986 -90.1319)
		(width 0.0889)
		(layer "In2.Cu")
		(net "P3E_CPU0_PE1_SS_RXP<1>")
	)
	(segment
		(start 305.526186 -90.2208)
		(end 305.241706 -90.2208)
		(width 0.0889)
		(layer "In2.Cu")
		(net "P3E_CPU0_PE1_SS_RXP<1>")
	)
	(segment
		(start 308.479698 -89.93378)
		(end 308.4576 -89.93378)
		(width 0.0889)
		(layer "In2.Cu")
		(net "P3E_CPU0_PE1_SS_RXP<1>")
	)
	(segment
		(start 307.146198 -90.2208)
		(end 306.681886 -90.2208)
		(width 0.0889)
		(layer "In2.Cu")
		(net "P3E_CPU0_PE1_SS_RXP<1>")
	)
	(segment
		(start 305.881786 -90.1319)
		(end 305.615086 -90.1319)
		(width 0.0889)
		(layer "In2.Cu")
		(net "P3E_CPU0_PE1_SS_RXP<1>")
	)
	(segment
		(start 302.37811 -90.744548)
		(end 302.671226 -90.575384)
		(width 0.0889)
		(layer "In2.Cu")
		(net "P3E_CPU0_PE1_SS_RXP<1>")
	)
	(segment
		(start 317.586614 -84.087462)
		(end 311.119012 -89.266776)
		(width 0.1143)
		(layer "In2.Cu")
		(net "P3E_CPU0_PE1_SS_RXP<1>")
	)
	(segment
		(start 308.917848 -89.93378)
		(end 308.479698 -89.93378)
		(width 0.1143)
		(layer "In2.Cu")
		(net "P3E_CPU0_PE1_SS_RXP<1>")
	)
	(segment
		(start 308.4576 -89.93378)
		(end 308.4068 -89.98458)
		(width 0.0889)
		(layer "In2.Cu")
		(net "P3E_CPU0_PE1_SS_RXP<1>")
	)
	(segment
		(start 320.27241 -72.994012)
		(end 320.183764 -73.338436)
		(width 0.1143)
		(layer "In2.Cu")
		(net "P3E_CPU0_PE1_SS_RXP<1>")
	)
	(segment
		(start 304.405792 -90.975434)
		(end 304.37328 -90.975434)
		(width 0.0889)
		(layer "In2.Cu")
		(net "P3E_CPU0_PE1_SS_RXP<1>")
	)
	(segment
		(start 320.443352 -72.330056)
		(end 320.562224 -72.53097)
		(width 0.1143)
		(layer "In2.Cu")
		(net "P3E_CPU0_PE1_SS_RXP<1>")
	)
	(arc
		(start 304.898044 -90.564208)
		(mid 304.817831 -90.65428)
		(end 304.748438 -90.75293)
		(width 0.0889)
		(layer "In2.Cu")
		(net "P3E_CPU0_PE1_SS_RXP<1>")
	)
	(arc
		(start 303.017936 -90.775536)
		(mid 302.877857 -90.918272)
		(end 302.686212 -90.975434)
		(width 0.0889)
		(layer "In2.Cu")
		(net "P3E_CPU0_PE1_SS_RXP<1>")
	)
	(arc
		(start 304.37328 -90.975434)
		(mid 304.181638 -90.918268)
		(end 304.041556 -90.775536)
		(width 0.0889)
		(layer "In2.Cu")
		(net "P3E_CPU0_PE1_SS_RXP<1>")
	)
	(arc
		(start 302.65624 -90.975434)
		(mid 302.489946 -90.9322)
		(end 302.357028 -90.823288)
		(width 0.0889)
		(layer "In2.Cu")
		(net "P3E_CPU0_PE1_SS_RXP<1>")
	)
	(arc
		(start 304.748438 -90.75293)
		(mid 304.741982 -90.763407)
		(end 304.735738 -90.774012)
		(width 0.0889)
		(layer "In2.Cu")
		(net "P3E_CPU0_PE1_SS_RXP<1>")
	)
	(arc
		(start 303.508156 -90.480388)
		(mid 303.224939 -90.564669)
		(end 303.017936 -90.775536)
		(width 0.0889)
		(layer "In2.Cu")
		(net "P3E_CPU0_PE1_SS_RXP<1>")
	)
	(arc
		(start 304.734976 -90.775536)
		(mid 304.595983 -90.917616)
		(end 304.405792 -90.975434)
		(width 0.0889)
		(layer "In2.Cu")
		(net "P3E_CPU0_PE1_SS_RXP<1>")
	)
	(arc
		(start 304.041556 -90.775536)
		(mid 303.834552 -90.564672)
		(end 303.551336 -90.480388)
		(width 0.0889)
		(layer "In2.Cu")
		(net "P3E_CPU0_PE1_SS_RXP<1>")
	)
	(segment
		(start 301.241206 -89.089738)
		(end 301.812706 -89.089738)
		(width 0.1143)
		(layer "F.Cu")
		(net "P3E_CPU0_PE1_SS_RXP<0>")
	)
	(via
		(at 301.812706 -89.089738)
		(size 0.508)
		(drill 0.254)
		(layers "F.Cu" "B.Cu")
		(net "P3E_CPU0_PE1_SS_RXP<0>")
	)
	(via
		(at 334.0354 -60.36183)
		(size 0.508)
		(drill 0.254)
		(layers "F.Cu" "B.Cu")
		(net "P3E_CPU0_PE1_SS_RXP<0>")
	)
	(segment
		(start 333.346806 -60.368434)
		(end 334.01 -60.368434)
		(width 0.1143)
		(layer "B.Cu")
		(net "P3E_CPU0_PE1_SS_RXP<0>")
	)
	(segment
		(start 334.01 -60.36183)
		(end 334.0354 -60.36183)
		(width 0.1143)
		(layer "B.Cu")
		(net "P3E_CPU0_PE1_SS_RXP<0>")
	)
	(segment
		(start 334.01 -60.368434)
		(end 334.01 -60.36183)
		(width 0.1143)
		(layer "B.Cu")
		(net "P3E_CPU0_PE1_SS_RXP<0>")
	)
	(segment
		(start 311.184544 -87.915496)
		(end 316.735714 -83.470242)
		(width 0.1143)
		(layer "In2.Cu")
		(net "P3E_CPU0_PE1_SS_RXP<0>")
	)
	(segment
		(start 320.033904 -70.650354)
		(end 319.915286 -70.449186)
		(width 0.1143)
		(layer "In2.Cu")
		(net "P3E_CPU0_PE1_SS_RXP<0>")
	)
	(segment
		(start 334.53705 -60.5409)
		(end 334.35798 -60.36183)
		(width 0.1143)
		(layer "In2.Cu")
		(net "P3E_CPU0_PE1_SS_RXP<0>")
	)
	(segment
		(start 316.735714 -83.470242)
		(end 319.514982 -72.667622)
		(width 0.1143)
		(layer "In2.Cu")
		(net "P3E_CPU0_PE1_SS_RXP<0>")
	)
	(segment
		(start 334.35798 -60.36183)
		(end 334.0354 -60.36183)
		(width 0.1143)
		(layer "In2.Cu")
		(net "P3E_CPU0_PE1_SS_RXP<0>")
	)
	(segment
		(start 326.457564 -62.243462)
		(end 329.079098 -61.011308)
		(width 0.1143)
		(layer "In2.Cu")
		(net "P3E_CPU0_PE1_SS_RXP<0>")
	)
	(segment
		(start 334.53705 -60.75807)
		(end 334.53705 -60.5409)
		(width 0.1143)
		(layer "In2.Cu")
		(net "P3E_CPU0_PE1_SS_RXP<0>")
	)
	(segment
		(start 305.3969 -89.5985)
		(end 305.4477 -89.5477)
		(width 0.0889)
		(layer "In2.Cu")
		(net "P3E_CPU0_PE1_SS_RXP<0>")
	)
	(segment
		(start 319.744344 -71.113396)
		(end 319.945258 -70.994778)
		(width 0.1143)
		(layer "In2.Cu")
		(net "P3E_CPU0_PE1_SS_RXP<0>")
	)
	(segment
		(start 303.508156 -89.489788)
		(end 303.551336 -89.489788)
		(width 0.0889)
		(layer "In2.Cu")
		(net "P3E_CPU0_PE1_SS_RXP<0>")
	)
	(segment
		(start 319.774316 -71.658988)
		(end 319.655698 -71.45782)
		(width 0.1143)
		(layer "In2.Cu")
		(net "P3E_CPU0_PE1_SS_RXP<0>")
	)
	(segment
		(start 305.469798 -89.5477)
		(end 306.06746 -89.5477)
		(width 0.1143)
		(layer "In2.Cu")
		(net "P3E_CPU0_PE1_SS_RXP<0>")
	)
	(segment
		(start 320.293492 -69.64172)
		(end 326.457564 -62.243462)
		(width 0.1143)
		(layer "In2.Cu")
		(net "P3E_CPU0_PE1_SS_RXP<0>")
	)
	(segment
		(start 319.68567 -72.003412)
		(end 319.774316 -71.658988)
		(width 0.1143)
		(layer "In2.Cu")
		(net "P3E_CPU0_PE1_SS_RXP<0>")
	)
	(segment
		(start 304.37328 -89.984834)
		(end 304.588672 -89.984834)
		(width 0.0889)
		(layer "In2.Cu")
		(net "P3E_CPU0_PE1_SS_RXP<0>")
	)
	(segment
		(start 319.655698 -71.45782)
		(end 319.744344 -71.113396)
		(width 0.1143)
		(layer "In2.Cu")
		(net "P3E_CPU0_PE1_SS_RXP<0>")
	)
	(segment
		(start 333.54645 -60.496958)
		(end 333.54645 -60.75045)
		(width 0.1143)
		(layer "In2.Cu")
		(net "P3E_CPU0_PE1_SS_RXP<0>")
	)
	(segment
		(start 320.003932 -70.104762)
		(end 320.204846 -69.986144)
		(width 0.1143)
		(layer "In2.Cu")
		(net "P3E_CPU0_PE1_SS_RXP<0>")
	)
	(segment
		(start 302.65624 -89.984834)
		(end 302.686212 -89.984834)
		(width 0.0889)
		(layer "In2.Cu")
		(net "P3E_CPU0_PE1_SS_RXP<0>")
	)
	(segment
		(start 319.514982 -72.667622)
		(end 319.39611 -72.466454)
		(width 0.1143)
		(layer "In2.Cu")
		(net "P3E_CPU0_PE1_SS_RXP<0>")
	)
	(segment
		(start 333.769208 -60.973208)
		(end 334.321912 -60.973208)
		(width 0.1143)
		(layer "In2.Cu")
		(net "P3E_CPU0_PE1_SS_RXP<0>")
	)
	(segment
		(start 307.510434 -88.720676)
		(end 311.184544 -87.915496)
		(width 0.1143)
		(layer "In2.Cu")
		(net "P3E_CPU0_PE1_SS_RXP<0>")
	)
	(segment
		(start 329.079098 -61.011308)
		(end 332.080108 -59.95035)
		(width 0.1143)
		(layer "In2.Cu")
		(net "P3E_CPU0_PE1_SS_RXP<0>")
	)
	(segment
		(start 306.06746 -89.5477)
		(end 307.510434 -88.720676)
		(width 0.1143)
		(layer "In2.Cu")
		(net "P3E_CPU0_PE1_SS_RXP<0>")
	)
	(segment
		(start 304.975006 -89.5985)
		(end 305.3969 -89.5985)
		(width 0.0889)
		(layer "In2.Cu")
		(net "P3E_CPU0_PE1_SS_RXP<0>")
	)
	(segment
		(start 332.080108 -59.95035)
		(end 332.999842 -59.95035)
		(width 0.1143)
		(layer "In2.Cu")
		(net "P3E_CPU0_PE1_SS_RXP<0>")
	)
	(segment
		(start 319.915286 -70.449186)
		(end 320.003932 -70.104762)
		(width 0.1143)
		(layer "In2.Cu")
		(net "P3E_CPU0_PE1_SS_RXP<0>")
	)
	(segment
		(start 319.945258 -70.994778)
		(end 320.033904 -70.650354)
		(width 0.1143)
		(layer "In2.Cu")
		(net "P3E_CPU0_PE1_SS_RXP<0>")
	)
	(segment
		(start 304.588672 -89.984834)
		(end 304.975006 -89.5985)
		(width 0.0889)
		(layer "In2.Cu")
		(net "P3E_CPU0_PE1_SS_RXP<0>")
	)
	(segment
		(start 305.4477 -89.5477)
		(end 305.469798 -89.5477)
		(width 0.0889)
		(layer "In2.Cu")
		(net "P3E_CPU0_PE1_SS_RXP<0>")
	)
	(segment
		(start 320.204846 -69.986144)
		(end 320.293492 -69.64172)
		(width 0.1143)
		(layer "In2.Cu")
		(net "P3E_CPU0_PE1_SS_RXP<0>")
	)
	(segment
		(start 301.812706 -89.089738)
		(end 301.812706 -89.427812)
		(width 0.0889)
		(layer "In2.Cu")
		(net "P3E_CPU0_PE1_SS_RXP<0>")
	)
	(segment
		(start 334.321912 -60.973208)
		(end 334.53705 -60.75807)
		(width 0.1143)
		(layer "In2.Cu")
		(net "P3E_CPU0_PE1_SS_RXP<0>")
	)
	(segment
		(start 319.39611 -72.466454)
		(end 319.484756 -72.12203)
		(width 0.1143)
		(layer "In2.Cu")
		(net "P3E_CPU0_PE1_SS_RXP<0>")
	)
	(segment
		(start 333.54645 -60.75045)
		(end 333.769208 -60.973208)
		(width 0.1143)
		(layer "In2.Cu")
		(net "P3E_CPU0_PE1_SS_RXP<0>")
	)
	(segment
		(start 301.812706 -89.427812)
		(end 301.87773 -89.492836)
		(width 0.0889)
		(layer "In2.Cu")
		(net "P3E_CPU0_PE1_SS_RXP<0>")
	)
	(segment
		(start 332.999842 -59.95035)
		(end 333.54645 -60.496958)
		(width 0.1143)
		(layer "In2.Cu")
		(net "P3E_CPU0_PE1_SS_RXP<0>")
	)
	(segment
		(start 319.484756 -72.12203)
		(end 319.68567 -72.003412)
		(width 0.1143)
		(layer "In2.Cu")
		(net "P3E_CPU0_PE1_SS_RXP<0>")
	)
	(arc
		(start 301.87773 -89.492836)
		(mid 302.136 -89.585544)
		(end 302.324516 -89.784936)
		(width 0.0889)
		(layer "In2.Cu")
		(net "P3E_CPU0_PE1_SS_RXP<0>")
	)
	(arc
		(start 302.324516 -89.784936)
		(mid 302.464595 -89.927672)
		(end 302.65624 -89.984834)
		(width 0.0889)
		(layer "In2.Cu")
		(net "P3E_CPU0_PE1_SS_RXP<0>")
	)
	(arc
		(start 303.017936 -89.784936)
		(mid 303.22494 -89.574072)
		(end 303.508156 -89.489788)
		(width 0.0889)
		(layer "In2.Cu")
		(net "P3E_CPU0_PE1_SS_RXP<0>")
	)
	(arc
		(start 304.041556 -89.784936)
		(mid 304.181635 -89.927672)
		(end 304.37328 -89.984834)
		(width 0.0889)
		(layer "In2.Cu")
		(net "P3E_CPU0_PE1_SS_RXP<0>")
	)
	(arc
		(start 303.551336 -89.489788)
		(mid 303.834553 -89.574069)
		(end 304.041556 -89.784936)
		(width 0.0889)
		(layer "In2.Cu")
		(net "P3E_CPU0_PE1_SS_RXP<0>")
	)
	(arc
		(start 302.686212 -89.984834)
		(mid 302.877854 -89.927668)
		(end 303.017936 -89.784936)
		(width 0.0889)
		(layer "In2.Cu")
		(net "P3E_CPU0_PE1_SS_RXP<0>")
	)
	(segment
		(start 300.382686 -96.518984)
		(end 300.954186 -96.518984)
		(width 0.1143)
		(layer "F.Cu")
		(net "P3E_CPU0_PE1_SS_RXN<7>")
	)
	(via
		(at 300.954186 -96.518984)
		(size 0.508)
		(drill 0.254)
		(layers "F.Cu" "B.Cu")
		(net "P3E_CPU0_PE1_SS_RXN<7>")
	)
	(via
		(at 354.9396 -60.4266)
		(size 0.508)
		(drill 0.254)
		(layers "F.Cu" "B.Cu")
		(net "P3E_CPU0_PE1_SS_RXN<7>")
	)
	(segment
		(start 354.301806 -60.368434)
		(end 354.881434 -60.368434)
		(width 0.1143)
		(layer "B.Cu")
		(net "P3E_CPU0_PE1_SS_RXN<7>")
	)
	(segment
		(start 354.881434 -60.368434)
		(end 354.9396 -60.4266)
		(width 0.1143)
		(layer "B.Cu")
		(net "P3E_CPU0_PE1_SS_RXN<7>")
	)
	(segment
		(start 354.370894 -60.557156)
		(end 354.50145 -60.4266)
		(width 0.1143)
		(layer "In2.Cu")
		(net "P3E_CPU0_PE1_SS_RXN<7>")
	)
	(segment
		(start 304.815494 -97.0026)
		(end 305.171348 -97.0026)
		(width 0.0889)
		(layer "In2.Cu")
		(net "P3E_CPU0_PE1_SS_RXN<7>")
	)
	(segment
		(start 307.616098 -95.736156)
		(end 307.638196 -95.736156)
		(width 0.0889)
		(layer "In2.Cu")
		(net "P3E_CPU0_PE1_SS_RXN<7>")
	)
	(segment
		(start 329.370182 -66.867024)
		(end 330.220066 -66.565526)
		(width 0.1143)
		(layer "In2.Cu")
		(net "P3E_CPU0_PE1_SS_RXN<7>")
	)
	(segment
		(start 304.476658 -97.119186)
		(end 304.698908 -97.119186)
		(width 0.0889)
		(layer "In2.Cu")
		(net "P3E_CPU0_PE1_SS_RXN<7>")
	)
	(segment
		(start 305.485546 -96.814132)
		(end 305.674268 -96.62541)
		(width 0.0889)
		(layer "In2.Cu")
		(net "P3E_CPU0_PE1_SS_RXN<7>")
	)
	(segment
		(start 331.797406 -67.131692)
		(end 332.57998 -66.899282)
		(width 0.1143)
		(layer "In2.Cu")
		(net "P3E_CPU0_PE1_SS_RXN<7>")
	)
	(segment
		(start 354.50145 -60.4266)
		(end 354.9396 -60.4266)
		(width 0.1143)
		(layer "In2.Cu")
		(net "P3E_CPU0_PE1_SS_RXN<7>")
	)
	(segment
		(start 304.698908 -97.119186)
		(end 304.815494 -97.0026)
		(width 0.0889)
		(layer "In2.Cu")
		(net "P3E_CPU0_PE1_SS_RXN<7>")
	)
	(segment
		(start 339.028278 -65.19418)
		(end 339.62975 -64.592708)
		(width 0.1143)
		(layer "In2.Cu")
		(net "P3E_CPU0_PE1_SS_RXN<7>")
	)
	(segment
		(start 313.932316 -93.959426)
		(end 323.14896 -86.579202)
		(width 0.1143)
		(layer "In2.Cu")
		(net "P3E_CPU0_PE1_SS_RXN<7>")
	)
	(segment
		(start 305.674268 -96.62541)
		(end 305.674268 -96.49968)
		(width 0.0889)
		(layer "In2.Cu")
		(net "P3E_CPU0_PE1_SS_RXN<7>")
	)
	(segment
		(start 302.649636 -97.109534)
		(end 302.692816 -97.109534)
		(width 0.0889)
		(layer "In2.Cu")
		(net "P3E_CPU0_PE1_SS_RXN<7>")
	)
	(segment
		(start 301.794926 -96.614488)
		(end 301.827692 -96.614488)
		(width 0.0889)
		(layer "In2.Cu")
		(net "P3E_CPU0_PE1_SS_RXN<7>")
	)
	(segment
		(start 306.488592 -95.685356)
		(end 307.565298 -95.685356)
		(width 0.0889)
		(layer "In2.Cu")
		(net "P3E_CPU0_PE1_SS_RXN<7>")
	)
	(segment
		(start 354.370894 -60.82411)
		(end 354.370894 -60.557156)
		(width 0.1143)
		(layer "In2.Cu")
		(net "P3E_CPU0_PE1_SS_RXN<7>")
	)
	(segment
		(start 339.62975 -64.592708)
		(end 350.602296 -64.592708)
		(width 0.1143)
		(layer "In2.Cu")
		(net "P3E_CPU0_PE1_SS_RXN<7>")
	)
	(segment
		(start 305.171348 -97.0026)
		(end 305.359816 -96.814132)
		(width 0.0889)
		(layer "In2.Cu")
		(net "P3E_CPU0_PE1_SS_RXN<7>")
	)
	(segment
		(start 304.366676 -97.109534)
		(end 304.399442 -97.109534)
		(width 0.0889)
		(layer "In2.Cu")
		(net "P3E_CPU0_PE1_SS_RXN<7>")
	)
	(segment
		(start 307.638196 -95.736156)
		(end 308.226206 -95.736156)
		(width 0.1143)
		(layer "In2.Cu")
		(net "P3E_CPU0_PE1_SS_RXN<7>")
	)
	(segment
		(start 306.177188 -96.12249)
		(end 306.177188 -95.99676)
		(width 0.0889)
		(layer "In2.Cu")
		(net "P3E_CPU0_PE1_SS_RXN<7>")
	)
	(segment
		(start 323.14896 -86.579202)
		(end 327.70953 -68.857114)
		(width 0.1143)
		(layer "In2.Cu")
		(net "P3E_CPU0_PE1_SS_RXN<7>")
	)
	(segment
		(start 335.07045 -65.729104)
		(end 336.26806 -65.729104)
		(width 0.1143)
		(layer "In2.Cu")
		(net "P3E_CPU0_PE1_SS_RXN<7>")
	)
	(segment
		(start 305.674268 -96.49968)
		(end 305.862736 -96.311212)
		(width 0.0889)
		(layer "In2.Cu")
		(net "P3E_CPU0_PE1_SS_RXN<7>")
	)
	(segment
		(start 336.26806 -65.729104)
		(end 336.802984 -65.19418)
		(width 0.1143)
		(layer "In2.Cu")
		(net "P3E_CPU0_PE1_SS_RXN<7>")
	)
	(segment
		(start 350.602296 -64.592708)
		(end 354.370894 -60.82411)
		(width 0.1143)
		(layer "In2.Cu")
		(net "P3E_CPU0_PE1_SS_RXN<7>")
	)
	(segment
		(start 303.51476 -96.614488)
		(end 303.544732 -96.614488)
		(width 0.0889)
		(layer "In2.Cu")
		(net "P3E_CPU0_PE1_SS_RXN<7>")
	)
	(segment
		(start 305.988466 -96.311212)
		(end 306.177188 -96.12249)
		(width 0.0889)
		(layer "In2.Cu")
		(net "P3E_CPU0_PE1_SS_RXN<7>")
	)
	(segment
		(start 300.66107 -96.350074)
		(end 300.639988 -96.271334)
		(width 0.0889)
		(layer "In2.Cu")
		(net "P3E_CPU0_PE1_SS_RXN<7>")
	)
	(segment
		(start 330.220066 -66.565526)
		(end 331.797406 -67.131692)
		(width 0.1143)
		(layer "In2.Cu")
		(net "P3E_CPU0_PE1_SS_RXN<7>")
	)
	(segment
		(start 306.177188 -95.99676)
		(end 306.488592 -95.685356)
		(width 0.0889)
		(layer "In2.Cu")
		(net "P3E_CPU0_PE1_SS_RXN<7>")
	)
	(segment
		(start 336.802984 -65.19418)
		(end 339.028278 -65.19418)
		(width 0.1143)
		(layer "In2.Cu")
		(net "P3E_CPU0_PE1_SS_RXN<7>")
	)
	(segment
		(start 300.954186 -96.518984)
		(end 300.66107 -96.350074)
		(width 0.0889)
		(layer "In2.Cu")
		(net "P3E_CPU0_PE1_SS_RXN<7>")
	)
	(segment
		(start 308.226206 -95.736156)
		(end 313.932316 -93.959426)
		(width 0.1143)
		(layer "In2.Cu")
		(net "P3E_CPU0_PE1_SS_RXN<7>")
	)
	(segment
		(start 327.70953 -68.857114)
		(end 329.370182 -66.867024)
		(width 0.1143)
		(layer "In2.Cu")
		(net "P3E_CPU0_PE1_SS_RXN<7>")
	)
	(segment
		(start 332.57998 -66.899282)
		(end 335.07045 -65.729104)
		(width 0.1143)
		(layer "In2.Cu")
		(net "P3E_CPU0_PE1_SS_RXN<7>")
	)
	(segment
		(start 305.862736 -96.311212)
		(end 305.988466 -96.311212)
		(width 0.0889)
		(layer "In2.Cu")
		(net "P3E_CPU0_PE1_SS_RXN<7>")
	)
	(segment
		(start 305.359816 -96.814132)
		(end 305.485546 -96.814132)
		(width 0.0889)
		(layer "In2.Cu")
		(net "P3E_CPU0_PE1_SS_RXN<7>")
	)
	(segment
		(start 307.565298 -95.685356)
		(end 307.616098 -95.736156)
		(width 0.0889)
		(layer "In2.Cu")
		(net "P3E_CPU0_PE1_SS_RXN<7>")
	)
	(arc
		(start 303.183036 -96.814386)
		(mid 303.323115 -96.67165)
		(end 303.51476 -96.614488)
		(width 0.0889)
		(layer "In2.Cu")
		(net "P3E_CPU0_PE1_SS_RXN<7>")
	)
	(arc
		(start 302.692816 -97.109534)
		(mid 302.976033 -97.025253)
		(end 303.183036 -96.814386)
		(width 0.0889)
		(layer "In2.Cu")
		(net "P3E_CPU0_PE1_SS_RXN<7>")
	)
	(arc
		(start 303.876456 -96.814386)
		(mid 304.08346 -97.02525)
		(end 304.366676 -97.109534)
		(width 0.0889)
		(layer "In2.Cu")
		(net "P3E_CPU0_PE1_SS_RXN<7>")
	)
	(arc
		(start 303.544732 -96.614488)
		(mid 303.736374 -96.671654)
		(end 303.876456 -96.814386)
		(width 0.0889)
		(layer "In2.Cu")
		(net "P3E_CPU0_PE1_SS_RXN<7>")
	)
	(arc
		(start 301.827692 -96.614488)
		(mid 302.019334 -96.671654)
		(end 302.159416 -96.814386)
		(width 0.0889)
		(layer "In2.Cu")
		(net "P3E_CPU0_PE1_SS_RXN<7>")
	)
	(arc
		(start 301.300896 -96.319086)
		(mid 301.509504 -96.531018)
		(end 301.794926 -96.614488)
		(width 0.0889)
		(layer "In2.Cu")
		(net "P3E_CPU0_PE1_SS_RXN<7>")
	)
	(arc
		(start 300.639988 -96.271334)
		(mid 300.983064 -96.119868)
		(end 301.300896 -96.319086)
		(width 0.0889)
		(layer "In2.Cu")
		(net "P3E_CPU0_PE1_SS_RXN<7>")
	)
	(arc
		(start 302.159416 -96.814386)
		(mid 302.36642 -97.02525)
		(end 302.649636 -97.109534)
		(width 0.0889)
		(layer "In2.Cu")
		(net "P3E_CPU0_PE1_SS_RXN<7>")
	)
	(arc
		(start 304.399442 -97.109534)
		(mid 304.438287 -97.112467)
		(end 304.476658 -97.119186)
		(width 0.0889)
		(layer "In2.Cu")
		(net "P3E_CPU0_PE1_SS_RXN<7>")
	)
	(segment
		(start 300.382686 -95.528384)
		(end 300.954186 -95.528384)
		(width 0.1143)
		(layer "F.Cu")
		(net "P3E_CPU0_PE1_SS_RXN<6>")
	)
	(via
		(at 352.1456 -60.4266)
		(size 0.508)
		(drill 0.254)
		(layers "F.Cu" "B.Cu")
		(net "P3E_CPU0_PE1_SS_RXN<6>")
	)
	(via
		(at 300.954186 -95.528384)
		(size 0.508)
		(drill 0.254)
		(layers "F.Cu" "B.Cu")
		(net "P3E_CPU0_PE1_SS_RXN<6>")
	)
	(segment
		(start 351.507806 -60.368434)
		(end 352.087434 -60.368434)
		(width 0.1143)
		(layer "B.Cu")
		(net "P3E_CPU0_PE1_SS_RXN<6>")
	)
	(segment
		(start 352.087434 -60.368434)
		(end 352.1456 -60.4266)
		(width 0.1143)
		(layer "B.Cu")
		(net "P3E_CPU0_PE1_SS_RXN<6>")
	)
	(segment
		(start 332.52918 -66.212212)
		(end 334.908398 -65.094104)
		(width 0.1143)
		(layer "In2.Cu")
		(net "P3E_CPU0_PE1_SS_RXN<6>")
	)
	(segment
		(start 301.799752 -95.623888)
		(end 301.827692 -95.623888)
		(width 0.0889)
		(layer "In2.Cu")
		(net "P3E_CPU0_PE1_SS_RXN<6>")
	)
	(segment
		(start 307.77688 -94.633288)
		(end 307.82768 -94.684088)
		(width 0.0889)
		(layer "In2.Cu")
		(net "P3E_CPU0_PE1_SS_RXN<6>")
	)
	(segment
		(start 307.849778 -94.684088)
		(end 308.463188 -94.684088)
		(width 0.1143)
		(layer "In2.Cu")
		(net "P3E_CPU0_PE1_SS_RXN<6>")
	)
	(segment
		(start 322.17106 -86.36762)
		(end 326.656954 -68.9356)
		(width 0.1143)
		(layer "In2.Cu")
		(net "P3E_CPU0_PE1_SS_RXN<6>")
	)
	(segment
		(start 331.816964 -66.42354)
		(end 332.52918 -66.212212)
		(width 0.1143)
		(layer "In2.Cu")
		(net "P3E_CPU0_PE1_SS_RXN<6>")
	)
	(segment
		(start 330.242164 -65.85839)
		(end 331.816964 -66.42354)
		(width 0.1143)
		(layer "In2.Cu")
		(net "P3E_CPU0_PE1_SS_RXN<6>")
	)
	(segment
		(start 336.539586 -64.55918)
		(end 338.76488 -64.55918)
		(width 0.1143)
		(layer "In2.Cu")
		(net "P3E_CPU0_PE1_SS_RXN<6>")
	)
	(segment
		(start 300.954186 -95.528384)
		(end 301.247302 -95.359474)
		(width 0.0889)
		(layer "In2.Cu")
		(net "P3E_CPU0_PE1_SS_RXN<6>")
	)
	(segment
		(start 326.656954 -68.9356)
		(end 328.858626 -66.34861)
		(width 0.1143)
		(layer "In2.Cu")
		(net "P3E_CPU0_PE1_SS_RXN<6>")
	)
	(segment
		(start 351.70745 -60.4266)
		(end 352.1456 -60.4266)
		(width 0.1143)
		(layer "In2.Cu")
		(net "P3E_CPU0_PE1_SS_RXN<6>")
	)
	(segment
		(start 334.908398 -65.094104)
		(end 336.004662 -65.094104)
		(width 0.1143)
		(layer "In2.Cu")
		(net "P3E_CPU0_PE1_SS_RXN<6>")
	)
	(segment
		(start 348.672658 -63.957708)
		(end 351.59315 -61.037216)
		(width 0.1143)
		(layer "In2.Cu")
		(net "P3E_CPU0_PE1_SS_RXN<6>")
	)
	(segment
		(start 305.92014 -95.623634)
		(end 306.910486 -94.633288)
		(width 0.0889)
		(layer "In2.Cu")
		(net "P3E_CPU0_PE1_SS_RXN<6>")
	)
	(segment
		(start 301.247302 -95.359474)
		(end 301.33671 -95.383604)
		(width 0.0889)
		(layer "In2.Cu")
		(net "P3E_CPU0_PE1_SS_RXN<6>")
	)
	(segment
		(start 336.004662 -65.094104)
		(end 336.539586 -64.55918)
		(width 0.1143)
		(layer "In2.Cu")
		(net "P3E_CPU0_PE1_SS_RXN<6>")
	)
	(segment
		(start 313.88685 -93.00083)
		(end 322.17106 -86.36762)
		(width 0.1143)
		(layer "In2.Cu")
		(net "P3E_CPU0_PE1_SS_RXN<6>")
	)
	(segment
		(start 339.366352 -63.957708)
		(end 348.672658 -63.957708)
		(width 0.1143)
		(layer "In2.Cu")
		(net "P3E_CPU0_PE1_SS_RXN<6>")
	)
	(segment
		(start 328.858626 -66.34861)
		(end 330.242164 -65.85839)
		(width 0.1143)
		(layer "In2.Cu")
		(net "P3E_CPU0_PE1_SS_RXN<6>")
	)
	(segment
		(start 305.236372 -95.623634)
		(end 305.92014 -95.623634)
		(width 0.0889)
		(layer "In2.Cu")
		(net "P3E_CPU0_PE1_SS_RXN<6>")
	)
	(segment
		(start 304.366676 -96.118934)
		(end 304.409856 -96.118934)
		(width 0.0889)
		(layer "In2.Cu")
		(net "P3E_CPU0_PE1_SS_RXN<6>")
	)
	(segment
		(start 338.76488 -64.55918)
		(end 339.366352 -63.957708)
		(width 0.1143)
		(layer "In2.Cu")
		(net "P3E_CPU0_PE1_SS_RXN<6>")
	)
	(segment
		(start 302.649636 -96.118934)
		(end 302.692816 -96.118934)
		(width 0.0889)
		(layer "In2.Cu")
		(net "P3E_CPU0_PE1_SS_RXN<6>")
	)
	(segment
		(start 351.59315 -61.037216)
		(end 351.59315 -60.5409)
		(width 0.1143)
		(layer "In2.Cu")
		(net "P3E_CPU0_PE1_SS_RXN<6>")
	)
	(segment
		(start 303.51476 -95.623888)
		(end 303.544732 -95.623888)
		(width 0.0889)
		(layer "In2.Cu")
		(net "P3E_CPU0_PE1_SS_RXN<6>")
	)
	(segment
		(start 351.59315 -60.5409)
		(end 351.70745 -60.4266)
		(width 0.1143)
		(layer "In2.Cu")
		(net "P3E_CPU0_PE1_SS_RXN<6>")
	)
	(segment
		(start 307.82768 -94.684088)
		(end 307.849778 -94.684088)
		(width 0.0889)
		(layer "In2.Cu")
		(net "P3E_CPU0_PE1_SS_RXN<6>")
	)
	(segment
		(start 308.463188 -94.684088)
		(end 313.88685 -93.00083)
		(width 0.1143)
		(layer "In2.Cu")
		(net "P3E_CPU0_PE1_SS_RXN<6>")
	)
	(segment
		(start 306.910486 -94.633288)
		(end 307.77688 -94.633288)
		(width 0.0889)
		(layer "In2.Cu")
		(net "P3E_CPU0_PE1_SS_RXN<6>")
	)
	(arc
		(start 301.33671 -95.383604)
		(mid 301.540282 -95.557601)
		(end 301.799752 -95.623888)
		(width 0.0889)
		(layer "In2.Cu")
		(net "P3E_CPU0_PE1_SS_RXN<6>")
	)
	(arc
		(start 304.900076 -95.823786)
		(mid 305.040155 -95.68105)
		(end 305.2318 -95.623888)
		(width 0.0889)
		(layer "In2.Cu")
		(net "P3E_CPU0_PE1_SS_RXN<6>")
	)
	(arc
		(start 304.409856 -96.118934)
		(mid 304.693073 -96.034653)
		(end 304.900076 -95.823786)
		(width 0.0889)
		(layer "In2.Cu")
		(net "P3E_CPU0_PE1_SS_RXN<6>")
	)
	(arc
		(start 303.876456 -95.823786)
		(mid 304.08346 -96.03465)
		(end 304.366676 -96.118934)
		(width 0.0889)
		(layer "In2.Cu")
		(net "P3E_CPU0_PE1_SS_RXN<6>")
	)
	(arc
		(start 302.692816 -96.118934)
		(mid 302.976033 -96.034653)
		(end 303.183036 -95.823786)
		(width 0.0889)
		(layer "In2.Cu")
		(net "P3E_CPU0_PE1_SS_RXN<6>")
	)
	(arc
		(start 302.159416 -95.823786)
		(mid 302.36642 -96.03465)
		(end 302.649636 -96.118934)
		(width 0.0889)
		(layer "In2.Cu")
		(net "P3E_CPU0_PE1_SS_RXN<6>")
	)
	(arc
		(start 303.183036 -95.823786)
		(mid 303.323115 -95.68105)
		(end 303.51476 -95.623888)
		(width 0.0889)
		(layer "In2.Cu")
		(net "P3E_CPU0_PE1_SS_RXN<6>")
	)
	(arc
		(start 305.2318 -95.623888)
		(mid 305.234086 -95.623755)
		(end 305.236372 -95.623634)
		(width 0.0889)
		(layer "In2.Cu")
		(net "P3E_CPU0_PE1_SS_RXN<6>")
	)
	(arc
		(start 301.827692 -95.623888)
		(mid 302.019334 -95.681054)
		(end 302.159416 -95.823786)
		(width 0.0889)
		(layer "In2.Cu")
		(net "P3E_CPU0_PE1_SS_RXN<6>")
	)
	(arc
		(start 303.544732 -95.623888)
		(mid 303.736374 -95.681054)
		(end 303.876456 -95.823786)
		(width 0.0889)
		(layer "In2.Cu")
		(net "P3E_CPU0_PE1_SS_RXN<6>")
	)
	(segment
		(start 300.382686 -94.538038)
		(end 300.954186 -94.538038)
		(width 0.1143)
		(layer "F.Cu")
		(net "P3E_CPU0_PE1_SS_RXN<5>")
	)
	(via
		(at 349.3516 -60.4266)
		(size 0.508)
		(drill 0.254)
		(layers "F.Cu" "B.Cu")
		(net "P3E_CPU0_PE1_SS_RXN<5>")
	)
	(via
		(at 300.954186 -94.538038)
		(size 0.508)
		(drill 0.254)
		(layers "F.Cu" "B.Cu")
		(net "P3E_CPU0_PE1_SS_RXN<5>")
	)
	(segment
		(start 348.713806 -60.368434)
		(end 349.293434 -60.368434)
		(width 0.1143)
		(layer "B.Cu")
		(net "P3E_CPU0_PE1_SS_RXN<5>")
	)
	(segment
		(start 349.293434 -60.368434)
		(end 349.3516 -60.4266)
		(width 0.1143)
		(layer "B.Cu")
		(net "P3E_CPU0_PE1_SS_RXN<5>")
	)
	(segment
		(start 331.224636 -64.459104)
		(end 335.741264 -64.459104)
		(width 0.1143)
		(layer "In2.Cu")
		(net "P3E_CPU0_PE1_SS_RXN<5>")
	)
	(segment
		(start 348.91345 -60.4266)
		(end 349.3516 -60.4266)
		(width 0.1143)
		(layer "In2.Cu")
		(net "P3E_CPU0_PE1_SS_RXN<5>")
	)
	(segment
		(start 335.741264 -64.459104)
		(end 336.276188 -63.92418)
		(width 0.1143)
		(layer "In2.Cu")
		(net "P3E_CPU0_PE1_SS_RXN<5>")
	)
	(segment
		(start 321.361562 -85.924644)
		(end 325.766684 -68.814442)
		(width 0.1143)
		(layer "In2.Cu")
		(net "P3E_CPU0_PE1_SS_RXN<5>")
	)
	(segment
		(start 307.937662 -93.589602)
		(end 307.95976 -93.589602)
		(width 0.0889)
		(layer "In2.Cu")
		(net "P3E_CPU0_PE1_SS_RXN<5>")
	)
	(segment
		(start 348.79915 -62.070996)
		(end 348.79915 -60.5409)
		(width 0.1143)
		(layer "In2.Cu")
		(net "P3E_CPU0_PE1_SS_RXN<5>")
	)
	(segment
		(start 300.954186 -94.538038)
		(end 300.954186 -94.199964)
		(width 0.0889)
		(layer "In2.Cu")
		(net "P3E_CPU0_PE1_SS_RXN<5>")
	)
	(segment
		(start 303.511712 -94.633288)
		(end 303.54778 -94.633288)
		(width 0.0889)
		(layer "In2.Cu")
		(net "P3E_CPU0_PE1_SS_RXN<5>")
	)
	(segment
		(start 304.370486 -95.128588)
		(end 304.406046 -95.128588)
		(width 0.0889)
		(layer "In2.Cu")
		(net "P3E_CPU0_PE1_SS_RXN<5>")
	)
	(segment
		(start 305.181 -94.5896)
		(end 305.856894 -94.5896)
		(width 0.0889)
		(layer "In2.Cu")
		(net "P3E_CPU0_PE1_SS_RXN<5>")
	)
	(segment
		(start 348.79915 -60.5409)
		(end 348.91345 -60.4266)
		(width 0.1143)
		(layer "In2.Cu")
		(net "P3E_CPU0_PE1_SS_RXN<5>")
	)
	(segment
		(start 338.501482 -63.92418)
		(end 339.102954 -63.322708)
		(width 0.1143)
		(layer "In2.Cu")
		(net "P3E_CPU0_PE1_SS_RXN<5>")
	)
	(segment
		(start 336.276188 -63.92418)
		(end 338.501482 -63.92418)
		(width 0.1143)
		(layer "In2.Cu")
		(net "P3E_CPU0_PE1_SS_RXN<5>")
	)
	(segment
		(start 306.907692 -93.538802)
		(end 307.886862 -93.538802)
		(width 0.0889)
		(layer "In2.Cu")
		(net "P3E_CPU0_PE1_SS_RXN<5>")
	)
	(segment
		(start 307.886862 -93.538802)
		(end 307.937662 -93.589602)
		(width 0.0889)
		(layer "In2.Cu")
		(net "P3E_CPU0_PE1_SS_RXN<5>")
	)
	(segment
		(start 300.954186 -94.199964)
		(end 301.012098 -94.142052)
		(width 0.0889)
		(layer "In2.Cu")
		(net "P3E_CPU0_PE1_SS_RXN<5>")
	)
	(segment
		(start 301.791116 -94.633288)
		(end 301.83074 -94.633288)
		(width 0.0889)
		(layer "In2.Cu")
		(net "P3E_CPU0_PE1_SS_RXN<5>")
	)
	(segment
		(start 347.547438 -63.322708)
		(end 348.79915 -62.070996)
		(width 0.1143)
		(layer "In2.Cu")
		(net "P3E_CPU0_PE1_SS_RXN<5>")
	)
	(segment
		(start 328.2188 -65.872106)
		(end 331.224636 -64.459104)
		(width 0.1143)
		(layer "In2.Cu")
		(net "P3E_CPU0_PE1_SS_RXN<5>")
	)
	(segment
		(start 307.95976 -93.589602)
		(end 309.130954 -93.589602)
		(width 0.1143)
		(layer "In2.Cu")
		(net "P3E_CPU0_PE1_SS_RXN<5>")
	)
	(segment
		(start 302.653446 -95.128588)
		(end 302.689006 -95.128588)
		(width 0.0889)
		(layer "In2.Cu")
		(net "P3E_CPU0_PE1_SS_RXN<5>")
	)
	(segment
		(start 305.856894 -94.5896)
		(end 306.907692 -93.538802)
		(width 0.0889)
		(layer "In2.Cu")
		(net "P3E_CPU0_PE1_SS_RXN<5>")
	)
	(segment
		(start 325.766684 -68.814442)
		(end 328.2188 -65.872106)
		(width 0.1143)
		(layer "In2.Cu")
		(net "P3E_CPU0_PE1_SS_RXN<5>")
	)
	(segment
		(start 309.130954 -93.589602)
		(end 313.467242 -92.245688)
		(width 0.1143)
		(layer "In2.Cu")
		(net "P3E_CPU0_PE1_SS_RXN<5>")
	)
	(segment
		(start 313.467242 -92.245688)
		(end 321.361562 -85.924644)
		(width 0.1143)
		(layer "In2.Cu")
		(net "P3E_CPU0_PE1_SS_RXN<5>")
	)
	(segment
		(start 339.102954 -63.322708)
		(end 347.547438 -63.322708)
		(width 0.1143)
		(layer "In2.Cu")
		(net "P3E_CPU0_PE1_SS_RXN<5>")
	)
	(arc
		(start 303.876456 -94.833186)
		(mid 304.085064 -95.045118)
		(end 304.370486 -95.128588)
		(width 0.0889)
		(layer "In2.Cu")
		(net "P3E_CPU0_PE1_SS_RXN<5>")
	)
	(arc
		(start 303.183036 -94.833186)
		(mid 303.32178 -94.691153)
		(end 303.511712 -94.633288)
		(width 0.0889)
		(layer "In2.Cu")
		(net "P3E_CPU0_PE1_SS_RXN<5>")
	)
	(arc
		(start 304.900076 -94.833186)
		(mid 305.020059 -94.687777)
		(end 305.181 -94.5896)
		(width 0.0889)
		(layer "In2.Cu")
		(net "P3E_CPU0_PE1_SS_RXN<5>")
	)
	(arc
		(start 303.54778 -94.633288)
		(mid 303.737709 -94.691158)
		(end 303.876456 -94.833186)
		(width 0.0889)
		(layer "In2.Cu")
		(net "P3E_CPU0_PE1_SS_RXN<5>")
	)
	(arc
		(start 301.83074 -94.633288)
		(mid 302.020669 -94.691158)
		(end 302.159416 -94.833186)
		(width 0.0889)
		(layer "In2.Cu")
		(net "P3E_CPU0_PE1_SS_RXN<5>")
	)
	(arc
		(start 304.406046 -95.128588)
		(mid 304.69147 -95.045121)
		(end 304.900076 -94.833186)
		(width 0.0889)
		(layer "In2.Cu")
		(net "P3E_CPU0_PE1_SS_RXN<5>")
	)
	(arc
		(start 301.300896 -94.33814)
		(mid 301.5079 -94.549004)
		(end 301.791116 -94.633288)
		(width 0.0889)
		(layer "In2.Cu")
		(net "P3E_CPU0_PE1_SS_RXN<5>")
	)
	(arc
		(start 302.159416 -94.833186)
		(mid 302.368024 -95.045118)
		(end 302.653446 -95.128588)
		(width 0.0889)
		(layer "In2.Cu")
		(net "P3E_CPU0_PE1_SS_RXN<5>")
	)
	(arc
		(start 301.012098 -94.142052)
		(mid 301.178999 -94.206952)
		(end 301.300896 -94.33814)
		(width 0.0889)
		(layer "In2.Cu")
		(net "P3E_CPU0_PE1_SS_RXN<5>")
	)
	(arc
		(start 302.689006 -95.128588)
		(mid 302.97443 -95.045121)
		(end 303.183036 -94.833186)
		(width 0.0889)
		(layer "In2.Cu")
		(net "P3E_CPU0_PE1_SS_RXN<5>")
	)
	(segment
		(start 299.524166 -93.052138)
		(end 300.095666 -93.052138)
		(width 0.1143)
		(layer "F.Cu")
		(net "P3E_CPU0_PE1_SS_RXN<4>")
	)
	(via
		(at 346.5576 -60.4266)
		(size 0.508)
		(drill 0.254)
		(layers "F.Cu" "B.Cu")
		(net "P3E_CPU0_PE1_SS_RXN<4>")
	)
	(via
		(at 300.095666 -93.052138)
		(size 0.508)
		(drill 0.254)
		(layers "F.Cu" "B.Cu")
		(net "P3E_CPU0_PE1_SS_RXN<4>")
	)
	(segment
		(start 345.919806 -60.368434)
		(end 346.499434 -60.368434)
		(width 0.1143)
		(layer "B.Cu")
		(net "P3E_CPU0_PE1_SS_RXN<4>")
	)
	(segment
		(start 346.499434 -60.368434)
		(end 346.5576 -60.4266)
		(width 0.1143)
		(layer "B.Cu")
		(net "P3E_CPU0_PE1_SS_RXN<4>")
	)
	(segment
		(start 306.699666 -92.945966)
		(end 306.677568 -92.945966)
		(width 0.0889)
		(layer "In2.Cu")
		(net "P3E_CPU0_PE1_SS_RXN<4>")
	)
	(segment
		(start 306.626768 -92.895166)
		(end 306.446174 -92.895166)
		(width 0.0889)
		(layer "In2.Cu")
		(net "P3E_CPU0_PE1_SS_RXN<4>")
	)
	(segment
		(start 346.00515 -60.5409)
		(end 346.00515 -61.479176)
		(width 0.1143)
		(layer "In2.Cu")
		(net "P3E_CPU0_PE1_SS_RXN<4>")
	)
	(segment
		(start 346.11945 -60.4266)
		(end 346.00515 -60.5409)
		(width 0.1143)
		(layer "In2.Cu")
		(net "P3E_CPU0_PE1_SS_RXN<4>")
	)
	(segment
		(start 300.388782 -92.882974)
		(end 300.095666 -93.052138)
		(width 0.0889)
		(layer "In2.Cu")
		(net "P3E_CPU0_PE1_SS_RXN<4>")
	)
	(segment
		(start 304.05832 -93.75902)
		(end 303.60366 -93.642688)
		(width 0.0889)
		(layer "In2.Cu")
		(net "P3E_CPU0_PE1_SS_RXN<4>")
	)
	(segment
		(start 300.965362 -93.147134)
		(end 300.932596 -93.147134)
		(width 0.0889)
		(layer "In2.Cu")
		(net "P3E_CPU0_PE1_SS_RXN<4>")
	)
	(segment
		(start 303.60366 -93.642688)
		(end 303.51476 -93.642688)
		(width 0.0889)
		(layer "In2.Cu")
		(net "P3E_CPU0_PE1_SS_RXN<4>")
	)
	(segment
		(start 306.446174 -92.895166)
		(end 305.45278 -93.88856)
		(width 0.0889)
		(layer "In2.Cu")
		(net "P3E_CPU0_PE1_SS_RXN<4>")
	)
	(segment
		(start 324.8152 -68.861432)
		(end 320.542666 -85.464142)
		(width 0.1143)
		(layer "In2.Cu")
		(net "P3E_CPU0_PE1_SS_RXN<4>")
	)
	(segment
		(start 346.5576 -60.4266)
		(end 346.11945 -60.4266)
		(width 0.1143)
		(layer "In2.Cu")
		(net "P3E_CPU0_PE1_SS_RXN<4>")
	)
	(segment
		(start 327.72604 -65.367662)
		(end 324.8152 -68.861432)
		(width 0.1143)
		(layer "In2.Cu")
		(net "P3E_CPU0_PE1_SS_RXN<4>")
	)
	(segment
		(start 344.796618 -62.687708)
		(end 338.839556 -62.687708)
		(width 0.1143)
		(layer "In2.Cu")
		(net "P3E_CPU0_PE1_SS_RXN<4>")
	)
	(segment
		(start 301.827692 -93.642688)
		(end 301.794926 -93.642688)
		(width 0.0889)
		(layer "In2.Cu")
		(net "P3E_CPU0_PE1_SS_RXN<4>")
	)
	(segment
		(start 346.00515 -61.479176)
		(end 344.796618 -62.687708)
		(width 0.1143)
		(layer "In2.Cu")
		(net "P3E_CPU0_PE1_SS_RXN<4>")
	)
	(segment
		(start 336.01279 -63.28918)
		(end 335.477866 -63.824104)
		(width 0.1143)
		(layer "In2.Cu")
		(net "P3E_CPU0_PE1_SS_RXN<4>")
	)
	(segment
		(start 308.832758 -92.945966)
		(end 306.699666 -92.945966)
		(width 0.1143)
		(layer "In2.Cu")
		(net "P3E_CPU0_PE1_SS_RXN<4>")
	)
	(segment
		(start 306.677568 -92.945966)
		(end 306.626768 -92.895166)
		(width 0.0889)
		(layer "In2.Cu")
		(net "P3E_CPU0_PE1_SS_RXN<4>")
	)
	(segment
		(start 338.238084 -63.28918)
		(end 336.01279 -63.28918)
		(width 0.1143)
		(layer "In2.Cu")
		(net "P3E_CPU0_PE1_SS_RXN<4>")
	)
	(segment
		(start 300.47819 -92.907104)
		(end 300.388782 -92.882974)
		(width 0.0889)
		(layer "In2.Cu")
		(net "P3E_CPU0_PE1_SS_RXN<4>")
	)
	(segment
		(start 338.839556 -62.687708)
		(end 338.238084 -63.28918)
		(width 0.1143)
		(layer "In2.Cu")
		(net "P3E_CPU0_PE1_SS_RXN<4>")
	)
	(segment
		(start 335.477866 -63.824104)
		(end 331.008736 -63.824104)
		(width 0.1143)
		(layer "In2.Cu")
		(net "P3E_CPU0_PE1_SS_RXN<4>")
	)
	(segment
		(start 305.45278 -93.88856)
		(end 304.23358 -93.88856)
		(width 0.0889)
		(layer "In2.Cu")
		(net "P3E_CPU0_PE1_SS_RXN<4>")
	)
	(segment
		(start 320.542666 -85.464142)
		(end 312.693558 -91.749626)
		(width 0.1143)
		(layer "In2.Cu")
		(net "P3E_CPU0_PE1_SS_RXN<4>")
	)
	(segment
		(start 331.008736 -63.824104)
		(end 327.72604 -65.367662)
		(width 0.1143)
		(layer "In2.Cu")
		(net "P3E_CPU0_PE1_SS_RXN<4>")
	)
	(segment
		(start 304.23358 -93.88856)
		(end 304.05832 -93.75902)
		(width 0.0889)
		(layer "In2.Cu")
		(net "P3E_CPU0_PE1_SS_RXN<4>")
	)
	(segment
		(start 312.693558 -91.749626)
		(end 308.832758 -92.945966)
		(width 0.1143)
		(layer "In2.Cu")
		(net "P3E_CPU0_PE1_SS_RXN<4>")
	)
	(arc
		(start 302.159416 -93.842586)
		(mid 302.019337 -93.69985)
		(end 301.827692 -93.642688)
		(width 0.0889)
		(layer "In2.Cu")
		(net "P3E_CPU0_PE1_SS_RXN<4>")
	)
	(arc
		(start 303.51476 -93.642688)
		(mid 303.323118 -93.699854)
		(end 303.183036 -93.842586)
		(width 0.0889)
		(layer "In2.Cu")
		(net "P3E_CPU0_PE1_SS_RXN<4>")
	)
	(arc
		(start 301.794926 -93.642688)
		(mid 301.509502 -93.559221)
		(end 301.300896 -93.347286)
		(width 0.0889)
		(layer "In2.Cu")
		(net "P3E_CPU0_PE1_SS_RXN<4>")
	)
	(arc
		(start 302.649128 -94.137734)
		(mid 302.366192 -94.053338)
		(end 302.159416 -93.842586)
		(width 0.0889)
		(layer "In2.Cu")
		(net "P3E_CPU0_PE1_SS_RXN<4>")
	)
	(arc
		(start 300.932596 -93.147134)
		(mid 300.677931 -93.079105)
		(end 300.47819 -92.907104)
		(width 0.0889)
		(layer "In2.Cu")
		(net "P3E_CPU0_PE1_SS_RXN<4>")
	)
	(arc
		(start 302.693324 -94.137734)
		(mid 302.671226 -94.138147)
		(end 302.649128 -94.137734)
		(width 0.0889)
		(layer "In2.Cu")
		(net "P3E_CPU0_PE1_SS_RXN<4>")
	)
	(arc
		(start 303.183036 -93.842586)
		(mid 302.976249 -94.053319)
		(end 302.693324 -94.137734)
		(width 0.0889)
		(layer "In2.Cu")
		(net "P3E_CPU0_PE1_SS_RXN<4>")
	)
	(arc
		(start 301.300896 -93.347286)
		(mid 301.159213 -93.203482)
		(end 300.965362 -93.147134)
		(width 0.0889)
		(layer "In2.Cu")
		(net "P3E_CPU0_PE1_SS_RXN<4>")
	)
	(segment
		(start 299.524166 -92.061538)
		(end 300.095666 -92.061538)
		(width 0.1143)
		(layer "F.Cu")
		(net "P3E_CPU0_PE1_SS_RXN<3>")
	)
	(via
		(at 300.095666 -92.061538)
		(size 0.508)
		(drill 0.254)
		(layers "F.Cu" "B.Cu")
		(net "P3E_CPU0_PE1_SS_RXN<3>")
	)
	(via
		(at 343.7636 -60.4266)
		(size 0.508)
		(drill 0.254)
		(layers "F.Cu" "B.Cu")
		(net "P3E_CPU0_PE1_SS_RXN<3>")
	)
	(segment
		(start 343.705434 -60.368434)
		(end 343.7636 -60.4266)
		(width 0.1143)
		(layer "B.Cu")
		(net "P3E_CPU0_PE1_SS_RXN<3>")
	)
	(segment
		(start 343.125806 -60.368434)
		(end 343.705434 -60.368434)
		(width 0.1143)
		(layer "B.Cu")
		(net "P3E_CPU0_PE1_SS_RXN<3>")
	)
	(segment
		(start 308.360064 -92.278708)
		(end 308.357778 -92.27947)
		(width 0.1143)
		(layer "In2.Cu")
		(net "P3E_CPU0_PE1_SS_RXN<3>")
	)
	(segment
		(start 343.21115 -61.43371)
		(end 342.592152 -62.052708)
		(width 0.1143)
		(layer "In2.Cu")
		(net "P3E_CPU0_PE1_SS_RXN<3>")
	)
	(segment
		(start 337.974686 -62.65418)
		(end 335.749392 -62.65418)
		(width 0.1143)
		(layer "In2.Cu")
		(net "P3E_CPU0_PE1_SS_RXN<3>")
	)
	(segment
		(start 300.153578 -91.665552)
		(end 300.095666 -91.723464)
		(width 0.0889)
		(layer "In2.Cu")
		(net "P3E_CPU0_PE1_SS_RXN<3>")
	)
	(segment
		(start 305.07051 -93.197934)
		(end 304.847498 -93.197934)
		(width 0.1143)
		(layer "In2.Cu")
		(net "P3E_CPU0_PE1_SS_RXN<3>")
	)
	(segment
		(start 323.849238 -68.978526)
		(end 319.690242 -85.127846)
		(width 0.1143)
		(layer "In2.Cu")
		(net "P3E_CPU0_PE1_SS_RXN<3>")
	)
	(segment
		(start 302.692816 -93.147134)
		(end 302.649636 -93.147134)
		(width 0.0889)
		(layer "In2.Cu")
		(net "P3E_CPU0_PE1_SS_RXN<3>")
	)
	(segment
		(start 308.313582 -92.27947)
		(end 305.98491 -92.283534)
		(width 0.1143)
		(layer "In2.Cu")
		(net "P3E_CPU0_PE1_SS_RXN<3>")
	)
	(segment
		(start 338.576158 -62.052708)
		(end 337.974686 -62.65418)
		(width 0.1143)
		(layer "In2.Cu")
		(net "P3E_CPU0_PE1_SS_RXN<3>")
	)
	(segment
		(start 330.688442 -63.189104)
		(end 327.374504 -64.74714)
		(width 0.1143)
		(layer "In2.Cu")
		(net "P3E_CPU0_PE1_SS_RXN<3>")
	)
	(segment
		(start 342.592152 -62.052708)
		(end 338.576158 -62.052708)
		(width 0.1143)
		(layer "In2.Cu")
		(net "P3E_CPU0_PE1_SS_RXN<3>")
	)
	(segment
		(start 301.827692 -92.652088)
		(end 301.794926 -92.652088)
		(width 0.0889)
		(layer "In2.Cu")
		(net "P3E_CPU0_PE1_SS_RXN<3>")
	)
	(segment
		(start 304.8254 -93.197934)
		(end 304.7746 -93.147134)
		(width 0.0889)
		(layer "In2.Cu")
		(net "P3E_CPU0_PE1_SS_RXN<3>")
	)
	(segment
		(start 304.7746 -93.147134)
		(end 304.366676 -93.147134)
		(width 0.0889)
		(layer "In2.Cu")
		(net "P3E_CPU0_PE1_SS_RXN<3>")
	)
	(segment
		(start 304.847498 -93.197934)
		(end 304.8254 -93.197934)
		(width 0.0889)
		(layer "In2.Cu")
		(net "P3E_CPU0_PE1_SS_RXN<3>")
	)
	(segment
		(start 335.749392 -62.65418)
		(end 335.214468 -63.189104)
		(width 0.1143)
		(layer "In2.Cu")
		(net "P3E_CPU0_PE1_SS_RXN<3>")
	)
	(segment
		(start 335.214468 -63.189104)
		(end 330.688442 -63.189104)
		(width 0.1143)
		(layer "In2.Cu")
		(net "P3E_CPU0_PE1_SS_RXN<3>")
	)
	(segment
		(start 300.965362 -92.156534)
		(end 300.932596 -92.156534)
		(width 0.0889)
		(layer "In2.Cu")
		(net "P3E_CPU0_PE1_SS_RXN<3>")
	)
	(segment
		(start 343.21115 -60.5409)
		(end 343.21115 -61.43371)
		(width 0.1143)
		(layer "In2.Cu")
		(net "P3E_CPU0_PE1_SS_RXN<3>")
	)
	(segment
		(start 300.095666 -91.723464)
		(end 300.095666 -92.061538)
		(width 0.0889)
		(layer "In2.Cu")
		(net "P3E_CPU0_PE1_SS_RXN<3>")
	)
	(segment
		(start 305.98491 -92.283534)
		(end 305.07051 -93.197934)
		(width 0.1143)
		(layer "In2.Cu")
		(net "P3E_CPU0_PE1_SS_RXN<3>")
	)
	(segment
		(start 319.690242 -85.127846)
		(end 312.27522 -91.065096)
		(width 0.1143)
		(layer "In2.Cu")
		(net "P3E_CPU0_PE1_SS_RXN<3>")
	)
	(segment
		(start 308.357778 -92.27947)
		(end 308.313582 -92.27947)
		(width 0.1143)
		(layer "In2.Cu")
		(net "P3E_CPU0_PE1_SS_RXN<3>")
	)
	(segment
		(start 303.544732 -92.652088)
		(end 303.51476 -92.652088)
		(width 0.0889)
		(layer "In2.Cu")
		(net "P3E_CPU0_PE1_SS_RXN<3>")
	)
	(segment
		(start 343.7636 -60.4266)
		(end 343.32545 -60.4266)
		(width 0.1143)
		(layer "In2.Cu")
		(net "P3E_CPU0_PE1_SS_RXN<3>")
	)
	(segment
		(start 312.27522 -91.065096)
		(end 308.360064 -92.278708)
		(width 0.1143)
		(layer "In2.Cu")
		(net "P3E_CPU0_PE1_SS_RXN<3>")
	)
	(segment
		(start 343.32545 -60.4266)
		(end 343.21115 -60.5409)
		(width 0.1143)
		(layer "In2.Cu")
		(net "P3E_CPU0_PE1_SS_RXN<3>")
	)
	(segment
		(start 327.374504 -64.74714)
		(end 323.849238 -68.978526)
		(width 0.1143)
		(layer "In2.Cu")
		(net "P3E_CPU0_PE1_SS_RXN<3>")
	)
	(arc
		(start 303.876456 -92.851986)
		(mid 303.736377 -92.70925)
		(end 303.544732 -92.652088)
		(width 0.0889)
		(layer "In2.Cu")
		(net "P3E_CPU0_PE1_SS_RXN<3>")
	)
	(arc
		(start 300.932596 -92.156534)
		(mid 300.649379 -92.072253)
		(end 300.442376 -91.861386)
		(width 0.0889)
		(layer "In2.Cu")
		(net "P3E_CPU0_PE1_SS_RXN<3>")
	)
	(arc
		(start 301.300896 -92.356686)
		(mid 301.159213 -92.212882)
		(end 300.965362 -92.156534)
		(width 0.0889)
		(layer "In2.Cu")
		(net "P3E_CPU0_PE1_SS_RXN<3>")
	)
	(arc
		(start 303.183036 -92.851986)
		(mid 302.976032 -93.06285)
		(end 302.692816 -93.147134)
		(width 0.0889)
		(layer "In2.Cu")
		(net "P3E_CPU0_PE1_SS_RXN<3>")
	)
	(arc
		(start 301.794926 -92.652088)
		(mid 301.509502 -92.568621)
		(end 301.300896 -92.356686)
		(width 0.0889)
		(layer "In2.Cu")
		(net "P3E_CPU0_PE1_SS_RXN<3>")
	)
	(arc
		(start 304.366676 -93.147134)
		(mid 304.083459 -93.062853)
		(end 303.876456 -92.851986)
		(width 0.0889)
		(layer "In2.Cu")
		(net "P3E_CPU0_PE1_SS_RXN<3>")
	)
	(arc
		(start 302.649636 -93.147134)
		(mid 302.366419 -93.062853)
		(end 302.159416 -92.851986)
		(width 0.0889)
		(layer "In2.Cu")
		(net "P3E_CPU0_PE1_SS_RXN<3>")
	)
	(arc
		(start 303.51476 -92.652088)
		(mid 303.323118 -92.709254)
		(end 303.183036 -92.851986)
		(width 0.0889)
		(layer "In2.Cu")
		(net "P3E_CPU0_PE1_SS_RXN<3>")
	)
	(arc
		(start 300.442376 -91.861386)
		(mid 300.320431 -91.730354)
		(end 300.153578 -91.665552)
		(width 0.0889)
		(layer "In2.Cu")
		(net "P3E_CPU0_PE1_SS_RXN<3>")
	)
	(arc
		(start 302.159416 -92.851986)
		(mid 302.019337 -92.70925)
		(end 301.827692 -92.652088)
		(width 0.0889)
		(layer "In2.Cu")
		(net "P3E_CPU0_PE1_SS_RXN<3>")
	)
	(segment
		(start 301.241206 -92.061538)
		(end 301.812706 -92.061538)
		(width 0.1143)
		(layer "F.Cu")
		(net "P3E_CPU0_PE1_SS_RXN<2>")
	)
	(via
		(at 301.812706 -92.061538)
		(size 0.508)
		(drill 0.254)
		(layers "F.Cu" "B.Cu")
		(net "P3E_CPU0_PE1_SS_RXN<2>")
	)
	(via
		(at 340.9696 -60.4266)
		(size 0.508)
		(drill 0.254)
		(layers "F.Cu" "B.Cu")
		(net "P3E_CPU0_PE1_SS_RXN<2>")
	)
	(segment
		(start 340.911434 -60.368434)
		(end 340.9696 -60.4266)
		(width 0.1143)
		(layer "B.Cu")
		(net "P3E_CPU0_PE1_SS_RXN<2>")
	)
	(segment
		(start 340.331806 -60.368434)
		(end 340.911434 -60.368434)
		(width 0.1143)
		(layer "B.Cu")
		(net "P3E_CPU0_PE1_SS_RXN<2>")
	)
	(segment
		(start 302.689514 -92.156534)
		(end 302.652938 -92.156534)
		(width 0.0889)
		(layer "In2.Cu")
		(net "P3E_CPU0_PE1_SS_RXN<2>")
	)
	(segment
		(start 335.485994 -62.01918)
		(end 334.95107 -62.554104)
		(width 0.1143)
		(layer "In2.Cu")
		(net "P3E_CPU0_PE1_SS_RXN<2>")
	)
	(segment
		(start 340.9696 -60.4266)
		(end 340.53145 -60.4266)
		(width 0.1143)
		(layer "In2.Cu")
		(net "P3E_CPU0_PE1_SS_RXN<2>")
	)
	(segment
		(start 301.51959 -91.892374)
		(end 301.812706 -92.061538)
		(width 0.0889)
		(layer "In2.Cu")
		(net "P3E_CPU0_PE1_SS_RXN<2>")
	)
	(segment
		(start 327.024746 -64.132714)
		(end 322.84289 -69.152008)
		(width 0.1143)
		(layer "In2.Cu")
		(net "P3E_CPU0_PE1_SS_RXN<2>")
	)
	(segment
		(start 339.992716 -61.403992)
		(end 338.326476 -61.403992)
		(width 0.1143)
		(layer "In2.Cu")
		(net "P3E_CPU0_PE1_SS_RXN<2>")
	)
	(segment
		(start 311.529222 -90.507566)
		(end 308.3179 -91.5035)
		(width 0.1143)
		(layer "In2.Cu")
		(net "P3E_CPU0_PE1_SS_RXN<2>")
	)
	(segment
		(start 305.963066 -91.132914)
		(end 305.797712 -91.298522)
		(width 0.0889)
		(layer "In2.Cu")
		(net "P3E_CPU0_PE1_SS_RXN<2>")
	)
	(segment
		(start 308.3179 -91.5035)
		(end 307.720238 -91.5035)
		(width 0.1143)
		(layer "In2.Cu")
		(net "P3E_CPU0_PE1_SS_RXN<2>")
	)
	(segment
		(start 307.69814 -91.5035)
		(end 307.64734 -91.4527)
		(width 0.0889)
		(layer "In2.Cu")
		(net "P3E_CPU0_PE1_SS_RXN<2>")
	)
	(segment
		(start 301.830232 -91.661488)
		(end 301.794926 -91.661488)
		(width 0.0889)
		(layer "In2.Cu")
		(net "P3E_CPU0_PE1_SS_RXN<2>")
	)
	(segment
		(start 338.326476 -61.403992)
		(end 337.711288 -62.01918)
		(width 0.1143)
		(layer "In2.Cu")
		(net "P3E_CPU0_PE1_SS_RXN<2>")
	)
	(segment
		(start 330.381864 -62.554104)
		(end 327.024746 -64.132714)
		(width 0.1143)
		(layer "In2.Cu")
		(net "P3E_CPU0_PE1_SS_RXN<2>")
	)
	(segment
		(start 305.264566 -91.661488)
		(end 305.22926 -91.661488)
		(width 0.0889)
		(layer "In2.Cu")
		(net "P3E_CPU0_PE1_SS_RXN<2>")
	)
	(segment
		(start 307.64734 -91.4527)
		(end 307.289708 -91.4527)
		(width 0.0889)
		(layer "In2.Cu")
		(net "P3E_CPU0_PE1_SS_RXN<2>")
	)
	(segment
		(start 340.53145 -60.4266)
		(end 340.41715 -60.5409)
		(width 0.1143)
		(layer "In2.Cu")
		(net "P3E_CPU0_PE1_SS_RXN<2>")
	)
	(segment
		(start 318.857376 -84.640166)
		(end 311.529222 -90.507566)
		(width 0.1143)
		(layer "In2.Cu")
		(net "P3E_CPU0_PE1_SS_RXN<2>")
	)
	(segment
		(start 322.84289 -69.152008)
		(end 318.857376 -84.640166)
		(width 0.1143)
		(layer "In2.Cu")
		(net "P3E_CPU0_PE1_SS_RXN<2>")
	)
	(segment
		(start 306.578508 -91.4527)
		(end 306.258722 -91.132914)
		(width 0.0889)
		(layer "In2.Cu")
		(net "P3E_CPU0_PE1_SS_RXN<2>")
	)
	(segment
		(start 340.41715 -60.5409)
		(end 340.41715 -60.979558)
		(width 0.1143)
		(layer "In2.Cu")
		(net "P3E_CPU0_PE1_SS_RXN<2>")
	)
	(segment
		(start 306.258722 -91.132914)
		(end 305.963066 -91.132914)
		(width 0.0889)
		(layer "In2.Cu")
		(net "P3E_CPU0_PE1_SS_RXN<2>")
	)
	(segment
		(start 307.289708 -91.4527)
		(end 307.200808 -91.5416)
		(width 0.0889)
		(layer "In2.Cu")
		(net "P3E_CPU0_PE1_SS_RXN<2>")
	)
	(segment
		(start 307.200808 -91.5416)
		(end 306.934108 -91.5416)
		(width 0.0889)
		(layer "In2.Cu")
		(net "P3E_CPU0_PE1_SS_RXN<2>")
	)
	(segment
		(start 334.95107 -62.554104)
		(end 330.381864 -62.554104)
		(width 0.1143)
		(layer "In2.Cu")
		(net "P3E_CPU0_PE1_SS_RXN<2>")
	)
	(segment
		(start 307.720238 -91.5035)
		(end 307.69814 -91.5035)
		(width 0.0889)
		(layer "In2.Cu")
		(net "P3E_CPU0_PE1_SS_RXN<2>")
	)
	(segment
		(start 337.711288 -62.01918)
		(end 335.485994 -62.01918)
		(width 0.1143)
		(layer "In2.Cu")
		(net "P3E_CPU0_PE1_SS_RXN<2>")
	)
	(segment
		(start 340.41715 -60.979558)
		(end 339.992716 -61.403992)
		(width 0.1143)
		(layer "In2.Cu")
		(net "P3E_CPU0_PE1_SS_RXN<2>")
	)
	(segment
		(start 306.934108 -91.5416)
		(end 306.845208 -91.4527)
		(width 0.0889)
		(layer "In2.Cu")
		(net "P3E_CPU0_PE1_SS_RXN<2>")
	)
	(segment
		(start 301.498254 -91.81338)
		(end 301.51959 -91.892374)
		(width 0.0889)
		(layer "In2.Cu")
		(net "P3E_CPU0_PE1_SS_RXN<2>")
	)
	(segment
		(start 304.406554 -92.156534)
		(end 304.369978 -92.156534)
		(width 0.0889)
		(layer "In2.Cu")
		(net "P3E_CPU0_PE1_SS_RXN<2>")
	)
	(segment
		(start 305.797712 -91.298522)
		(end 305.758596 -91.366086)
		(width 0.0889)
		(layer "In2.Cu")
		(net "P3E_CPU0_PE1_SS_RXN<2>")
	)
	(segment
		(start 306.845208 -91.4527)
		(end 306.578508 -91.4527)
		(width 0.0889)
		(layer "In2.Cu")
		(net "P3E_CPU0_PE1_SS_RXN<2>")
	)
	(segment
		(start 303.547272 -91.661488)
		(end 303.51222 -91.661488)
		(width 0.0889)
		(layer "In2.Cu")
		(net "P3E_CPU0_PE1_SS_RXN<2>")
	)
	(segment
		(start 301.498508 -91.813634)
		(end 301.498254 -91.81338)
		(width 0.0889)
		(layer "In2.Cu")
		(net "P3E_CPU0_PE1_SS_RXN<2>")
	)
	(arc
		(start 303.51222 -91.661488)
		(mid 303.321978 -91.719223)
		(end 303.183036 -91.861386)
		(width 0.0889)
		(layer "In2.Cu")
		(net "P3E_CPU0_PE1_SS_RXN<2>")
	)
	(arc
		(start 303.876456 -91.861386)
		(mid 303.737463 -91.719306)
		(end 303.547272 -91.661488)
		(width 0.0889)
		(layer "In2.Cu")
		(net "P3E_CPU0_PE1_SS_RXN<2>")
	)
	(arc
		(start 303.183036 -91.861386)
		(mid 302.974617 -92.073099)
		(end 302.689514 -92.156534)
		(width 0.0889)
		(layer "In2.Cu")
		(net "P3E_CPU0_PE1_SS_RXN<2>")
	)
	(arc
		(start 302.159416 -91.861386)
		(mid 302.020423 -91.719306)
		(end 301.830232 -91.661488)
		(width 0.0889)
		(layer "In2.Cu")
		(net "P3E_CPU0_PE1_SS_RXN<2>")
	)
	(arc
		(start 304.900076 -91.861386)
		(mid 304.691657 -92.073099)
		(end 304.406554 -92.156534)
		(width 0.0889)
		(layer "In2.Cu")
		(net "P3E_CPU0_PE1_SS_RXN<2>")
	)
	(arc
		(start 304.369978 -92.156534)
		(mid 304.084931 -92.073006)
		(end 303.876456 -91.861386)
		(width 0.0889)
		(layer "In2.Cu")
		(net "P3E_CPU0_PE1_SS_RXN<2>")
	)
	(arc
		(start 305.758596 -91.366086)
		(mid 305.549988 -91.578018)
		(end 305.264566 -91.661488)
		(width 0.0889)
		(layer "In2.Cu")
		(net "P3E_CPU0_PE1_SS_RXN<2>")
	)
	(arc
		(start 305.22926 -91.661488)
		(mid 305.039018 -91.719223)
		(end 304.900076 -91.861386)
		(width 0.0889)
		(layer "In2.Cu")
		(net "P3E_CPU0_PE1_SS_RXN<2>")
	)
	(arc
		(start 301.794926 -91.661488)
		(mid 301.630152 -91.705274)
		(end 301.498508 -91.813634)
		(width 0.0889)
		(layer "In2.Cu")
		(net "P3E_CPU0_PE1_SS_RXN<2>")
	)
	(arc
		(start 302.652938 -92.156534)
		(mid 302.367891 -92.073006)
		(end 302.159416 -91.861386)
		(width 0.0889)
		(layer "In2.Cu")
		(net "P3E_CPU0_PE1_SS_RXN<2>")
	)
	(segment
		(start 301.241206 -91.070938)
		(end 301.812706 -91.070938)
		(width 0.1143)
		(layer "F.Cu")
		(net "P3E_CPU0_PE1_SS_RXN<1>")
	)
	(via
		(at 338.1756 -60.4266)
		(size 0.508)
		(drill 0.254)
		(layers "F.Cu" "B.Cu")
		(net "P3E_CPU0_PE1_SS_RXN<1>")
	)
	(via
		(at 301.812706 -91.070938)
		(size 0.508)
		(drill 0.254)
		(layers "F.Cu" "B.Cu")
		(net "P3E_CPU0_PE1_SS_RXN<1>")
	)
	(segment
		(start 338.117434 -60.368434)
		(end 338.1756 -60.4266)
		(width 0.1143)
		(layer "B.Cu")
		(net "P3E_CPU0_PE1_SS_RXN<1>")
	)
	(segment
		(start 337.537806 -60.368434)
		(end 338.117434 -60.368434)
		(width 0.1143)
		(layer "B.Cu")
		(net "P3E_CPU0_PE1_SS_RXN<1>")
	)
	(segment
		(start 317.84544 -84.254848)
		(end 311.257696 -89.530174)
		(width 0.1143)
		(layer "In2.Cu")
		(net "P3E_CPU0_PE1_SS_RXN<1>")
	)
	(segment
		(start 337.62315 -60.5409)
		(end 337.62315 -60.980066)
		(width 0.1143)
		(layer "In2.Cu")
		(net "P3E_CPU0_PE1_SS_RXN<1>")
	)
	(segment
		(start 326.776588 -63.438024)
		(end 321.607688 -69.641974)
		(width 0.1143)
		(layer "In2.Cu")
		(net "P3E_CPU0_PE1_SS_RXN<1>")
	)
	(segment
		(start 337.73745 -60.4266)
		(end 337.62315 -60.5409)
		(width 0.1143)
		(layer "In2.Cu")
		(net "P3E_CPU0_PE1_SS_RXN<1>")
	)
	(segment
		(start 307.791866 -90.17508)
		(end 307.182012 -90.4113)
		(width 0.0889)
		(layer "In2.Cu")
		(net "P3E_CPU0_PE1_SS_RXN<1>")
	)
	(segment
		(start 303.544732 -90.670888)
		(end 303.51476 -90.670888)
		(width 0.0889)
		(layer "In2.Cu")
		(net "P3E_CPU0_PE1_SS_RXN<1>")
	)
	(segment
		(start 304.903378 -90.864944)
		(end 304.903378 -90.865452)
		(width 0.0889)
		(layer "In2.Cu")
		(net "P3E_CPU0_PE1_SS_RXN<1>")
	)
	(segment
		(start 335.222596 -61.38418)
		(end 334.687672 -61.919104)
		(width 0.1143)
		(layer "In2.Cu")
		(net "P3E_CPU0_PE1_SS_RXN<1>")
	)
	(segment
		(start 321.607688 -69.641974)
		(end 317.84544 -84.254848)
		(width 0.1143)
		(layer "In2.Cu")
		(net "P3E_CPU0_PE1_SS_RXN<1>")
	)
	(segment
		(start 338.1756 -60.4266)
		(end 337.73745 -60.4266)
		(width 0.1143)
		(layer "In2.Cu")
		(net "P3E_CPU0_PE1_SS_RXN<1>")
	)
	(segment
		(start 334.687672 -61.919104)
		(end 330.006452 -61.919104)
		(width 0.1143)
		(layer "In2.Cu")
		(net "P3E_CPU0_PE1_SS_RXN<1>")
	)
	(segment
		(start 337.219036 -61.38418)
		(end 335.222596 -61.38418)
		(width 0.1143)
		(layer "In2.Cu")
		(net "P3E_CPU0_PE1_SS_RXN<1>")
	)
	(segment
		(start 308.961282 -90.22588)
		(end 308.479698 -90.22588)
		(width 0.1143)
		(layer "In2.Cu")
		(net "P3E_CPU0_PE1_SS_RXN<1>")
	)
	(segment
		(start 302.692816 -91.165934)
		(end 302.649636 -91.165934)
		(width 0.0889)
		(layer "In2.Cu")
		(net "P3E_CPU0_PE1_SS_RXN<1>")
	)
	(segment
		(start 330.006452 -61.919104)
		(end 326.776588 -63.438024)
		(width 0.1143)
		(layer "In2.Cu")
		(net "P3E_CPU0_PE1_SS_RXN<1>")
	)
	(segment
		(start 308.4068 -90.17508)
		(end 307.791866 -90.17508)
		(width 0.0889)
		(layer "In2.Cu")
		(net "P3E_CPU0_PE1_SS_RXN<1>")
	)
	(segment
		(start 308.479698 -90.22588)
		(end 308.4576 -90.22588)
		(width 0.0889)
		(layer "In2.Cu")
		(net "P3E_CPU0_PE1_SS_RXN<1>")
	)
	(segment
		(start 307.182012 -90.4113)
		(end 305.3207 -90.4113)
		(width 0.0889)
		(layer "In2.Cu")
		(net "P3E_CPU0_PE1_SS_RXN<1>")
	)
	(segment
		(start 305.3207 -90.4113)
		(end 305.032918 -90.699082)
		(width 0.0889)
		(layer "In2.Cu")
		(net "P3E_CPU0_PE1_SS_RXN<1>")
	)
	(segment
		(start 311.257696 -89.530174)
		(end 308.961282 -90.22588)
		(width 0.1143)
		(layer "In2.Cu")
		(net "P3E_CPU0_PE1_SS_RXN<1>")
	)
	(segment
		(start 308.4576 -90.22588)
		(end 308.4068 -90.17508)
		(width 0.0889)
		(layer "In2.Cu")
		(net "P3E_CPU0_PE1_SS_RXN<1>")
	)
	(segment
		(start 302.105822 -90.901774)
		(end 301.812706 -91.070938)
		(width 0.0889)
		(layer "In2.Cu")
		(net "P3E_CPU0_PE1_SS_RXN<1>")
	)
	(segment
		(start 302.19523 -90.925904)
		(end 302.105822 -90.901774)
		(width 0.0889)
		(layer "In2.Cu")
		(net "P3E_CPU0_PE1_SS_RXN<1>")
	)
	(segment
		(start 304.409602 -91.165934)
		(end 304.369978 -91.165934)
		(width 0.0889)
		(layer "In2.Cu")
		(net "P3E_CPU0_PE1_SS_RXN<1>")
	)
	(segment
		(start 337.62315 -60.980066)
		(end 337.219036 -61.38418)
		(width 0.1143)
		(layer "In2.Cu")
		(net "P3E_CPU0_PE1_SS_RXN<1>")
	)
	(arc
		(start 303.183036 -90.870786)
		(mid 302.976032 -91.08165)
		(end 302.692816 -91.165934)
		(width 0.0889)
		(layer "In2.Cu")
		(net "P3E_CPU0_PE1_SS_RXN<1>")
	)
	(arc
		(start 305.032918 -90.699082)
		(mid 304.96307 -90.778046)
		(end 304.903378 -90.864944)
		(width 0.0889)
		(layer "In2.Cu")
		(net "P3E_CPU0_PE1_SS_RXN<1>")
	)
	(arc
		(start 303.876456 -90.870786)
		(mid 303.736377 -90.72805)
		(end 303.544732 -90.670888)
		(width 0.0889)
		(layer "In2.Cu")
		(net "P3E_CPU0_PE1_SS_RXN<1>")
	)
	(arc
		(start 304.903378 -90.865452)
		(mid 304.695739 -91.080195)
		(end 304.409602 -91.165934)
		(width 0.0889)
		(layer "In2.Cu")
		(net "P3E_CPU0_PE1_SS_RXN<1>")
	)
	(arc
		(start 304.369978 -91.165934)
		(mid 304.084931 -91.082406)
		(end 303.876456 -90.870786)
		(width 0.0889)
		(layer "In2.Cu")
		(net "P3E_CPU0_PE1_SS_RXN<1>")
	)
	(arc
		(start 303.51476 -90.670888)
		(mid 303.323118 -90.728054)
		(end 303.183036 -90.870786)
		(width 0.0889)
		(layer "In2.Cu")
		(net "P3E_CPU0_PE1_SS_RXN<1>")
	)
	(arc
		(start 302.649636 -91.165934)
		(mid 302.394971 -91.097905)
		(end 302.19523 -90.925904)
		(width 0.0889)
		(layer "In2.Cu")
		(net "P3E_CPU0_PE1_SS_RXN<1>")
	)
	(segment
		(start 301.241206 -90.080338)
		(end 301.812706 -90.080338)
		(width 0.1143)
		(layer "F.Cu")
		(net "P3E_CPU0_PE1_SS_RXN<0>")
	)
	(via
		(at 301.812706 -90.080338)
		(size 0.508)
		(drill 0.254)
		(layers "F.Cu" "B.Cu")
		(net "P3E_CPU0_PE1_SS_RXN<0>")
	)
	(via
		(at 335.353406 -60.368434)
		(size 0.508)
		(drill 0.254)
		(layers "F.Cu" "B.Cu")
		(net "P3E_CPU0_PE1_SS_RXN<0>")
	)
	(segment
		(start 335.353406 -60.368434)
		(end 334.743806 -60.368434)
		(width 0.1143)
		(layer "B.Cu")
		(net "P3E_CPU0_PE1_SS_RXN<0>")
	)
	(segment
		(start 333.64805 -61.265308)
		(end 334.44307 -61.265308)
		(width 0.1143)
		(layer "In2.Cu")
		(net "P3E_CPU0_PE1_SS_RXN<0>")
	)
	(segment
		(start 326.4662 -62.689994)
		(end 326.640698 -62.480444)
		(width 0.1143)
		(layer "In2.Cu")
		(net "P3E_CPU0_PE1_SS_RXN<0>")
	)
	(segment
		(start 311.31383 -88.18626)
		(end 316.99454 -83.637374)
		(width 0.1143)
		(layer "In2.Cu")
		(net "P3E_CPU0_PE1_SS_RXN<0>")
	)
	(segment
		(start 335.001616 -60.368434)
		(end 335.353406 -60.368434)
		(width 0.1143)
		(layer "In2.Cu")
		(net "P3E_CPU0_PE1_SS_RXN<0>")
	)
	(segment
		(start 302.649636 -90.175334)
		(end 302.692816 -90.175334)
		(width 0.0889)
		(layer "In2.Cu")
		(net "P3E_CPU0_PE1_SS_RXN<0>")
	)
	(segment
		(start 334.44307 -61.265308)
		(end 334.82915 -60.879228)
		(width 0.1143)
		(layer "In2.Cu")
		(net "P3E_CPU0_PE1_SS_RXN<0>")
	)
	(segment
		(start 329.19035 -61.282072)
		(end 332.1304 -60.24245)
		(width 0.1143)
		(layer "In2.Cu")
		(net "P3E_CPU0_PE1_SS_RXN<0>")
	)
	(segment
		(start 334.82915 -60.879228)
		(end 334.82915 -60.5409)
		(width 0.1143)
		(layer "In2.Cu")
		(net "P3E_CPU0_PE1_SS_RXN<0>")
	)
	(segment
		(start 301.812706 -90.080338)
		(end 301.812706 -89.742264)
		(width 0.0889)
		(layer "In2.Cu")
		(net "P3E_CPU0_PE1_SS_RXN<0>")
	)
	(segment
		(start 305.469798 -89.8398)
		(end 306.145438 -89.8398)
		(width 0.1143)
		(layer "In2.Cu")
		(net "P3E_CPU0_PE1_SS_RXN<0>")
	)
	(segment
		(start 306.145438 -89.8398)
		(end 307.61686 -88.99652)
		(width 0.1143)
		(layer "In2.Cu")
		(net "P3E_CPU0_PE1_SS_RXN<0>")
	)
	(segment
		(start 307.61686 -88.99652)
		(end 311.31383 -88.18626)
		(width 0.1143)
		(layer "In2.Cu")
		(net "P3E_CPU0_PE1_SS_RXN<0>")
	)
	(segment
		(start 326.640698 -62.480444)
		(end 329.19035 -61.282072)
		(width 0.1143)
		(layer "In2.Cu")
		(net "P3E_CPU0_PE1_SS_RXN<0>")
	)
	(segment
		(start 320.560192 -69.778372)
		(end 326.4662 -62.689994)
		(width 0.1143)
		(layer "In2.Cu")
		(net "P3E_CPU0_PE1_SS_RXN<0>")
	)
	(segment
		(start 332.1304 -60.24245)
		(end 332.878684 -60.24245)
		(width 0.1143)
		(layer "In2.Cu")
		(net "P3E_CPU0_PE1_SS_RXN<0>")
	)
	(segment
		(start 333.25435 -60.618116)
		(end 333.25435 -60.871608)
		(width 0.1143)
		(layer "In2.Cu")
		(net "P3E_CPU0_PE1_SS_RXN<0>")
	)
	(segment
		(start 301.812706 -89.742264)
		(end 301.870618 -89.684352)
		(width 0.0889)
		(layer "In2.Cu")
		(net "P3E_CPU0_PE1_SS_RXN<0>")
	)
	(segment
		(start 303.51476 -89.680288)
		(end 303.544732 -89.680288)
		(width 0.0889)
		(layer "In2.Cu")
		(net "P3E_CPU0_PE1_SS_RXN<0>")
	)
	(segment
		(start 332.878684 -60.24245)
		(end 333.25435 -60.618116)
		(width 0.1143)
		(layer "In2.Cu")
		(net "P3E_CPU0_PE1_SS_RXN<0>")
	)
	(segment
		(start 305.4477 -89.8398)
		(end 305.469798 -89.8398)
		(width 0.0889)
		(layer "In2.Cu")
		(net "P3E_CPU0_PE1_SS_RXN<0>")
	)
	(segment
		(start 305.3969 -89.789)
		(end 305.4477 -89.8398)
		(width 0.0889)
		(layer "In2.Cu")
		(net "P3E_CPU0_PE1_SS_RXN<0>")
	)
	(segment
		(start 334.82915 -60.5409)
		(end 335.001616 -60.368434)
		(width 0.1143)
		(layer "In2.Cu")
		(net "P3E_CPU0_PE1_SS_RXN<0>")
	)
	(segment
		(start 305.054 -89.789)
		(end 305.3969 -89.789)
		(width 0.0889)
		(layer "In2.Cu")
		(net "P3E_CPU0_PE1_SS_RXN<0>")
	)
	(segment
		(start 333.25435 -60.871608)
		(end 333.64805 -61.265308)
		(width 0.1143)
		(layer "In2.Cu")
		(net "P3E_CPU0_PE1_SS_RXN<0>")
	)
	(segment
		(start 304.366676 -90.175334)
		(end 304.667666 -90.175334)
		(width 0.0889)
		(layer "In2.Cu")
		(net "P3E_CPU0_PE1_SS_RXN<0>")
	)
	(segment
		(start 304.667666 -90.175334)
		(end 305.054 -89.789)
		(width 0.0889)
		(layer "In2.Cu")
		(net "P3E_CPU0_PE1_SS_RXN<0>")
	)
	(segment
		(start 316.99454 -83.637374)
		(end 320.560192 -69.778372)
		(width 0.1143)
		(layer "In2.Cu")
		(net "P3E_CPU0_PE1_SS_RXN<0>")
	)
	(arc
		(start 301.870618 -89.684352)
		(mid 302.037463 -89.749165)
		(end 302.159416 -89.880186)
		(width 0.0889)
		(layer "In2.Cu")
		(net "P3E_CPU0_PE1_SS_RXN<0>")
	)
	(arc
		(start 302.692816 -90.175334)
		(mid 302.976033 -90.091053)
		(end 303.183036 -89.880186)
		(width 0.0889)
		(layer "In2.Cu")
		(net "P3E_CPU0_PE1_SS_RXN<0>")
	)
	(arc
		(start 303.183036 -89.880186)
		(mid 303.323115 -89.73745)
		(end 303.51476 -89.680288)
		(width 0.0889)
		(layer "In2.Cu")
		(net "P3E_CPU0_PE1_SS_RXN<0>")
	)
	(arc
		(start 303.876456 -89.880186)
		(mid 304.08346 -90.09105)
		(end 304.366676 -90.175334)
		(width 0.0889)
		(layer "In2.Cu")
		(net "P3E_CPU0_PE1_SS_RXN<0>")
	)
	(arc
		(start 302.159416 -89.880186)
		(mid 302.36642 -90.09105)
		(end 302.649636 -90.175334)
		(width 0.0889)
		(layer "In2.Cu")
		(net "P3E_CPU0_PE1_SS_RXN<0>")
	)
	(arc
		(start 303.544732 -89.680288)
		(mid 303.736374 -89.737454)
		(end 303.876456 -89.880186)
		(width 0.0889)
		(layer "In2.Cu")
		(net "P3E_CPU0_PE1_SS_RXN<0>")
	)
	(segment
		(start 308.295548 -99.956874)
		(end 308.521862 -100.0506)
		(width 0.0889)
		(layer "F.Cu")
		(net "P3E_CPU0_PE1_PCH_TXP<9>")
	)
	(segment
		(start 308.723538 -100.0252)
		(end 308.99354 -100.0252)
		(width 0.1143)
		(layer "F.Cu")
		(net "P3E_CPU0_PE1_PCH_TXP<9>")
	)
	(segment
		(start 308.70144 -100.0252)
		(end 308.723538 -100.0252)
		(width 0.0889)
		(layer "F.Cu")
		(net "P3E_CPU0_PE1_PCH_TXP<9>")
	)
	(segment
		(start 330.304394 -119.09933)
		(end 334.129126 -119.09933)
		(width 0.1143)
		(layer "F.Cu")
		(net "P3E_CPU0_PE1_PCH_TXP<9>")
	)
	(segment
		(start 308.99354 -100.0252)
		(end 309.217314 -100.174806)
		(width 0.1143)
		(layer "F.Cu")
		(net "P3E_CPU0_PE1_PCH_TXP<9>")
	)
	(segment
		(start 307.560726 -99.408742)
		(end 307.80736 -99.511104)
		(width 0.0889)
		(layer "F.Cu")
		(net "P3E_CPU0_PE1_PCH_TXP<9>")
	)
	(segment
		(start 334.243426 -118.98503)
		(end 334.586326 -118.98503)
		(width 0.1143)
		(layer "F.Cu")
		(net "P3E_CPU0_PE1_PCH_TXP<9>")
	)
	(segment
		(start 306.614576 -99.395788)
		(end 306.715668 -99.294696)
		(width 0.0889)
		(layer "F.Cu")
		(net "P3E_CPU0_PE1_PCH_TXP<9>")
	)
	(segment
		(start 339.222588 -118.336568)
		(end 339.222588 -117.941598)
		(width 0.1143)
		(layer "F.Cu")
		(net "P3E_CPU0_PE1_PCH_TXP<9>")
	)
	(segment
		(start 309.217314 -100.174806)
		(end 311.509664 -104.878886)
		(width 0.1143)
		(layer "F.Cu")
		(net "P3E_CPU0_PE1_PCH_TXP<9>")
	)
	(segment
		(start 307.429916 -99.463352)
		(end 307.560726 -99.408742)
		(width 0.0889)
		(layer "F.Cu")
		(net "P3E_CPU0_PE1_PCH_TXP<9>")
	)
	(segment
		(start 334.700626 -119.09933)
		(end 335.043526 -119.09933)
		(width 0.1143)
		(layer "F.Cu")
		(net "P3E_CPU0_PE1_PCH_TXP<9>")
	)
	(segment
		(start 307.266594 -99.395788)
		(end 307.429916 -99.463352)
		(width 0.0889)
		(layer "F.Cu")
		(net "P3E_CPU0_PE1_PCH_TXP<9>")
	)
	(segment
		(start 308.521862 -100.0506)
		(end 308.67604 -100.0506)
		(width 0.0889)
		(layer "F.Cu")
		(net "P3E_CPU0_PE1_PCH_TXP<9>")
	)
	(segment
		(start 328.667364 -117.4623)
		(end 328.828908 -117.4623)
		(width 0.1143)
		(layer "F.Cu")
		(net "P3E_CPU0_PE1_PCH_TXP<9>")
	)
	(segment
		(start 321.459352 -111.78667)
		(end 326.362822 -116.69014)
		(width 0.1143)
		(layer "F.Cu")
		(net "P3E_CPU0_PE1_PCH_TXP<9>")
	)
	(segment
		(start 306.715668 -99.294696)
		(end 306.982368 -99.294696)
		(width 0.0889)
		(layer "F.Cu")
		(net "P3E_CPU0_PE1_PCH_TXP<9>")
	)
	(segment
		(start 307.861462 -99.641914)
		(end 308.065424 -99.72675)
		(width 0.0889)
		(layer "F.Cu")
		(net "P3E_CPU0_PE1_PCH_TXP<9>")
	)
	(segment
		(start 307.08346 -99.395788)
		(end 307.266594 -99.395788)
		(width 0.0889)
		(layer "F.Cu")
		(net "P3E_CPU0_PE1_PCH_TXP<9>")
	)
	(segment
		(start 335.043526 -119.09933)
		(end 335.655666 -118.48719)
		(width 0.1143)
		(layer "F.Cu")
		(net "P3E_CPU0_PE1_PCH_TXP<9>")
	)
	(segment
		(start 335.655666 -118.48719)
		(end 339.071966 -118.48719)
		(width 0.1143)
		(layer "F.Cu")
		(net "P3E_CPU0_PE1_PCH_TXP<9>")
	)
	(segment
		(start 306.105052 -99.161346)
		(end 306.081938 -99.24796)
		(width 0.0889)
		(layer "F.Cu")
		(net "P3E_CPU0_PE1_PCH_TXP<9>")
	)
	(segment
		(start 326.362822 -116.69014)
		(end 327.895204 -116.69014)
		(width 0.1143)
		(layer "F.Cu")
		(net "P3E_CPU0_PE1_PCH_TXP<9>")
	)
	(segment
		(start 318.263778 -109.56798)
		(end 321.459352 -111.78667)
		(width 0.1143)
		(layer "F.Cu")
		(net "P3E_CPU0_PE1_PCH_TXP<9>")
	)
	(segment
		(start 308.67604 -100.0506)
		(end 308.70144 -100.0252)
		(width 0.0889)
		(layer "F.Cu")
		(net "P3E_CPU0_PE1_PCH_TXP<9>")
	)
	(segment
		(start 327.895204 -116.69014)
		(end 328.667364 -117.4623)
		(width 0.1143)
		(layer "F.Cu")
		(net "P3E_CPU0_PE1_PCH_TXP<9>")
	)
	(segment
		(start 329.071478 -117.704616)
		(end 329.071478 -117.866414)
		(width 0.1143)
		(layer "F.Cu")
		(net "P3E_CPU0_PE1_PCH_TXP<9>")
	)
	(segment
		(start 306.392326 -98.995738)
		(end 306.105052 -99.161346)
		(width 0.0889)
		(layer "F.Cu")
		(net "P3E_CPU0_PE1_PCH_TXP<9>")
	)
	(segment
		(start 311.509664 -104.878886)
		(end 318.263778 -109.56798)
		(width 0.1143)
		(layer "F.Cu")
		(net "P3E_CPU0_PE1_PCH_TXP<9>")
	)
	(segment
		(start 329.071478 -117.866414)
		(end 330.304394 -119.09933)
		(width 0.1143)
		(layer "F.Cu")
		(net "P3E_CPU0_PE1_PCH_TXP<9>")
	)
	(segment
		(start 334.129126 -119.09933)
		(end 334.243426 -118.98503)
		(width 0.1143)
		(layer "F.Cu")
		(net "P3E_CPU0_PE1_PCH_TXP<9>")
	)
	(segment
		(start 328.828908 -117.4623)
		(end 329.071478 -117.704616)
		(width 0.1143)
		(layer "F.Cu")
		(net "P3E_CPU0_PE1_PCH_TXP<9>")
	)
	(segment
		(start 334.586326 -118.98503)
		(end 334.700626 -119.09933)
		(width 0.1143)
		(layer "F.Cu")
		(net "P3E_CPU0_PE1_PCH_TXP<9>")
	)
	(segment
		(start 308.065424 -99.72675)
		(end 308.295548 -99.956874)
		(width 0.0889)
		(layer "F.Cu")
		(net "P3E_CPU0_PE1_PCH_TXP<9>")
	)
	(segment
		(start 307.80736 -99.511104)
		(end 307.861462 -99.641914)
		(width 0.0889)
		(layer "F.Cu")
		(net "P3E_CPU0_PE1_PCH_TXP<9>")
	)
	(segment
		(start 339.071966 -118.48719)
		(end 339.222588 -118.336568)
		(width 0.1143)
		(layer "F.Cu")
		(net "P3E_CPU0_PE1_PCH_TXP<9>")
	)
	(segment
		(start 306.38115 -99.395788)
		(end 306.614576 -99.395788)
		(width 0.0889)
		(layer "F.Cu")
		(net "P3E_CPU0_PE1_PCH_TXP<9>")
	)
	(segment
		(start 306.982368 -99.294696)
		(end 307.08346 -99.395788)
		(width 0.0889)
		(layer "F.Cu")
		(net "P3E_CPU0_PE1_PCH_TXP<9>")
	)
	(via
		(at 318.263778 -109.56798)
		(size 0.508)
		(drill 0.254)
		(layers "F.Cu" "B.Cu")
		(net "P3E_CPU0_PE1_PCH_TXP<9>")
	)
	(arc
		(start 306.081938 -99.24796)
		(mid 306.215407 -99.354519)
		(end 306.38115 -99.395788)
		(width 0.0889)
		(layer "F.Cu")
		(net "P3E_CPU0_PE1_PCH_TXP<9>")
	)
	(segment
		(start 332.888844 -117.681756)
		(end 332.7654 -117.8052)
		(width 0.1143)
		(layer "F.Cu")
		(net "P3E_CPU0_PE1_PCH_TXP<8>")
	)
	(segment
		(start 309.448708 -99.0346)
		(end 309.092854 -99.0346)
		(width 0.1143)
		(layer "F.Cu")
		(net "P3E_CPU0_PE1_PCH_TXP<8>")
	)
	(segment
		(start 318.272668 -107.3531)
		(end 314.857384 -105.98785)
		(width 0.1143)
		(layer "F.Cu")
		(net "P3E_CPU0_PE1_PCH_TXP<8>")
	)
	(segment
		(start 304.388012 -98.170746)
		(end 304.675286 -98.005138)
		(width 0.0889)
		(layer "F.Cu")
		(net "P3E_CPU0_PE1_PCH_TXP<8>")
	)
	(segment
		(start 304.364898 -98.25736)
		(end 304.388012 -98.170746)
		(width 0.0889)
		(layer "F.Cu")
		(net "P3E_CPU0_PE1_PCH_TXP<8>")
	)
	(segment
		(start 332.888844 -117.35562)
		(end 332.888844 -117.681756)
		(width 0.1143)
		(layer "F.Cu")
		(net "P3E_CPU0_PE1_PCH_TXP<8>")
	)
	(segment
		(start 309.092854 -99.0346)
		(end 309.070756 -99.0346)
		(width 0.0889)
		(layer "F.Cu")
		(net "P3E_CPU0_PE1_PCH_TXP<8>")
	)
	(segment
		(start 305.551586 -97.909634)
		(end 305.51501 -97.909634)
		(width 0.0889)
		(layer "F.Cu")
		(net "P3E_CPU0_PE1_PCH_TXP<8>")
	)
	(segment
		(start 307.709062 -98.685604)
		(end 307.661056 -98.569272)
		(width 0.0889)
		(layer "F.Cu")
		(net "P3E_CPU0_PE1_PCH_TXP<8>")
	)
	(segment
		(start 307.955442 -98.787712)
		(end 307.709062 -98.685604)
		(width 0.0889)
		(layer "F.Cu")
		(net "P3E_CPU0_PE1_PCH_TXP<8>")
	)
	(segment
		(start 307.414676 -98.467164)
		(end 307.298598 -98.515424)
		(width 0.0889)
		(layer "F.Cu")
		(net "P3E_CPU0_PE1_PCH_TXP<8>")
	)
	(segment
		(start 309.045356 -99.06)
		(end 308.61254 -99.06)
		(width 0.0889)
		(layer "F.Cu")
		(net "P3E_CPU0_PE1_PCH_TXP<8>")
	)
	(segment
		(start 312.271156 -104.1781)
		(end 310.132984 -99.492308)
		(width 0.1143)
		(layer "F.Cu")
		(net "P3E_CPU0_PE1_PCH_TXP<8>")
	)
	(segment
		(start 307.661056 -98.569272)
		(end 307.414676 -98.467164)
		(width 0.0889)
		(layer "F.Cu")
		(net "P3E_CPU0_PE1_PCH_TXP<8>")
	)
	(segment
		(start 310.132984 -99.492308)
		(end 309.448708 -99.0346)
		(width 0.1143)
		(layer "F.Cu")
		(net "P3E_CPU0_PE1_PCH_TXP<8>")
	)
	(segment
		(start 308.318154 -98.841814)
		(end 308.071774 -98.739452)
		(width 0.0889)
		(layer "F.Cu")
		(net "P3E_CPU0_PE1_PCH_TXP<8>")
	)
	(segment
		(start 326.81672 -110.768638)
		(end 318.272668 -107.3531)
		(width 0.1143)
		(layer "F.Cu")
		(net "P3E_CPU0_PE1_PCH_TXP<8>")
	)
	(segment
		(start 314.857384 -105.98785)
		(end 312.271156 -104.1781)
		(width 0.1143)
		(layer "F.Cu")
		(net "P3E_CPU0_PE1_PCH_TXP<8>")
	)
	(segment
		(start 332.7654 -117.8052)
		(end 330.553822 -117.8052)
		(width 0.1143)
		(layer "F.Cu")
		(net "P3E_CPU0_PE1_PCH_TXP<8>")
	)
	(segment
		(start 307.298598 -98.515424)
		(end 307.032914 -98.405188)
		(width 0.0889)
		(layer "F.Cu")
		(net "P3E_CPU0_PE1_PCH_TXP<8>")
	)
	(segment
		(start 307.032914 -98.405188)
		(end 306.38115 -98.405188)
		(width 0.0889)
		(layer "F.Cu")
		(net "P3E_CPU0_PE1_PCH_TXP<8>")
	)
	(segment
		(start 305.022758 -98.204274)
		(end 305.021996 -98.205036)
		(width 0.0889)
		(layer "F.Cu")
		(net "P3E_CPU0_PE1_PCH_TXP<8>")
	)
	(segment
		(start 328.43089 -115.682268)
		(end 328.43089 -112.970564)
		(width 0.1143)
		(layer "F.Cu")
		(net "P3E_CPU0_PE1_PCH_TXP<8>")
	)
	(segment
		(start 309.070756 -99.0346)
		(end 309.045356 -99.06)
		(width 0.0889)
		(layer "F.Cu")
		(net "P3E_CPU0_PE1_PCH_TXP<8>")
	)
	(segment
		(start 308.36616 -98.957892)
		(end 308.318154 -98.841814)
		(width 0.0889)
		(layer "F.Cu")
		(net "P3E_CPU0_PE1_PCH_TXP<8>")
	)
	(segment
		(start 308.071774 -98.739452)
		(end 307.955442 -98.787712)
		(width 0.0889)
		(layer "F.Cu")
		(net "P3E_CPU0_PE1_PCH_TXP<8>")
	)
	(segment
		(start 308.61254 -99.06)
		(end 308.36616 -98.957892)
		(width 0.0889)
		(layer "F.Cu")
		(net "P3E_CPU0_PE1_PCH_TXP<8>")
	)
	(segment
		(start 330.553822 -117.8052)
		(end 328.43089 -115.682268)
		(width 0.1143)
		(layer "F.Cu")
		(net "P3E_CPU0_PE1_PCH_TXP<8>")
	)
	(segment
		(start 328.43089 -112.970564)
		(end 326.81672 -110.768638)
		(width 0.1143)
		(layer "F.Cu")
		(net "P3E_CPU0_PE1_PCH_TXP<8>")
	)
	(via
		(at 318.272668 -107.3531)
		(size 0.508)
		(drill 0.254)
		(layers "F.Cu" "B.Cu")
		(net "P3E_CPU0_PE1_PCH_TXP<8>")
	)
	(arc
		(start 305.021996 -98.205036)
		(mid 305.017137 -98.213221)
		(end 305.01209 -98.221292)
		(width 0.0889)
		(layer "F.Cu")
		(net "P3E_CPU0_PE1_PCH_TXP<8>")
	)
	(arc
		(start 305.01209 -98.221292)
		(mid 304.872471 -98.353189)
		(end 304.687478 -98.404934)
		(width 0.0889)
		(layer "F.Cu")
		(net "P3E_CPU0_PE1_PCH_TXP<8>")
	)
	(arc
		(start 306.045616 -98.205036)
		(mid 305.837008 -97.993104)
		(end 305.551586 -97.909634)
		(width 0.0889)
		(layer "F.Cu")
		(net "P3E_CPU0_PE1_PCH_TXP<8>")
	)
	(arc
		(start 305.51501 -97.909634)
		(mid 305.230598 -97.992974)
		(end 305.022758 -98.204274)
		(width 0.0889)
		(layer "F.Cu")
		(net "P3E_CPU0_PE1_PCH_TXP<8>")
	)
	(arc
		(start 304.687478 -98.404934)
		(mid 304.508902 -98.368896)
		(end 304.364898 -98.25736)
		(width 0.0889)
		(layer "F.Cu")
		(net "P3E_CPU0_PE1_PCH_TXP<8>")
	)
	(arc
		(start 306.38115 -98.405188)
		(mid 306.1873 -98.348838)
		(end 306.045616 -98.205036)
		(width 0.0889)
		(layer "F.Cu")
		(net "P3E_CPU0_PE1_PCH_TXP<8>")
	)
	(segment
		(start 371.374162 -119.226584)
		(end 371.250464 -119.226584)
		(width 0.0889)
		(layer "F.Cu")
		(net "P3E_CPU0_PE1_PCH_TXP<7>")
	)
	(segment
		(start 374.192038 -118.378478)
		(end 374.144794 -118.331234)
		(width 0.0889)
		(layer "F.Cu")
		(net "P3E_CPU0_PE1_PCH_TXP<7>")
	)
	(segment
		(start 371.028468 -118.88089)
		(end 370.882672 -118.88089)
		(width 0.0889)
		(layer "F.Cu")
		(net "P3E_CPU0_PE1_PCH_TXP<7>")
	)
	(segment
		(start 371.124734 -118.977156)
		(end 371.028468 -118.88089)
		(width 0.0889)
		(layer "F.Cu")
		(net "P3E_CPU0_PE1_PCH_TXP<7>")
	)
	(segment
		(start 370.254276 -118.971822)
		(end 370.076476 -118.971822)
		(width 0.0889)
		(layer "F.Cu")
		(net "P3E_CPU0_PE1_PCH_TXP<7>")
	)
	(segment
		(start 369.709192 -118.680484)
		(end 369.709192 -118.539768)
		(width 0.0889)
		(layer "F.Cu")
		(net "P3E_CPU0_PE1_PCH_TXP<7>")
	)
	(segment
		(start 369.406424 -118.237)
		(end 369.316 -118.237)
		(width 0.0889)
		(layer "F.Cu")
		(net "P3E_CPU0_PE1_PCH_TXP<7>")
	)
	(segment
		(start 370.076476 -118.971822)
		(end 369.985544 -118.88089)
		(width 0.0889)
		(layer "F.Cu")
		(net "P3E_CPU0_PE1_PCH_TXP<7>")
	)
	(segment
		(start 371.124734 -119.100854)
		(end 371.124734 -118.977156)
		(width 0.0889)
		(layer "F.Cu")
		(net "P3E_CPU0_PE1_PCH_TXP<7>")
	)
	(segment
		(start 371.250464 -119.226584)
		(end 371.124734 -119.100854)
		(width 0.0889)
		(layer "F.Cu")
		(net "P3E_CPU0_PE1_PCH_TXP<7>")
	)
	(segment
		(start 374.022366 -118.331234)
		(end 373.0244 -119.3292)
		(width 0.0889)
		(layer "F.Cu")
		(net "P3E_CPU0_PE1_PCH_TXP<7>")
	)
	(segment
		(start 370.523008 -118.88089)
		(end 370.345208 -118.88089)
		(width 0.0889)
		(layer "F.Cu")
		(net "P3E_CPU0_PE1_PCH_TXP<7>")
	)
	(segment
		(start 369.709192 -118.539768)
		(end 369.406424 -118.237)
		(width 0.0889)
		(layer "F.Cu")
		(net "P3E_CPU0_PE1_PCH_TXP<7>")
	)
	(segment
		(start 369.909598 -118.88089)
		(end 369.709192 -118.680484)
		(width 0.0889)
		(layer "F.Cu")
		(net "P3E_CPU0_PE1_PCH_TXP<7>")
	)
	(segment
		(start 373.0244 -119.3292)
		(end 371.476778 -119.3292)
		(width 0.0889)
		(layer "F.Cu")
		(net "P3E_CPU0_PE1_PCH_TXP<7>")
	)
	(segment
		(start 370.345208 -118.88089)
		(end 370.254276 -118.971822)
		(width 0.0889)
		(layer "F.Cu")
		(net "P3E_CPU0_PE1_PCH_TXP<7>")
	)
	(segment
		(start 374.812306 -118.378732)
		(end 374.634506 -118.378732)
		(width 0.0889)
		(layer "F.Cu")
		(net "P3E_CPU0_PE1_PCH_TXP<7>")
	)
	(segment
		(start 370.882672 -118.88089)
		(end 370.79174 -118.971822)
		(width 0.0889)
		(layer "F.Cu")
		(net "P3E_CPU0_PE1_PCH_TXP<7>")
	)
	(segment
		(start 369.985544 -118.88089)
		(end 369.909598 -118.88089)
		(width 0.0889)
		(layer "F.Cu")
		(net "P3E_CPU0_PE1_PCH_TXP<7>")
	)
	(segment
		(start 375.031 -118.296182)
		(end 374.894856 -118.296182)
		(width 0.0889)
		(layer "F.Cu")
		(net "P3E_CPU0_PE1_PCH_TXP<7>")
	)
	(segment
		(start 371.476778 -119.3292)
		(end 371.374162 -119.226584)
		(width 0.0889)
		(layer "F.Cu")
		(net "P3E_CPU0_PE1_PCH_TXP<7>")
	)
	(segment
		(start 374.634506 -118.378732)
		(end 374.587008 -118.331234)
		(width 0.0889)
		(layer "F.Cu")
		(net "P3E_CPU0_PE1_PCH_TXP<7>")
	)
	(segment
		(start 370.61394 -118.971822)
		(end 370.523008 -118.88089)
		(width 0.0889)
		(layer "F.Cu")
		(net "P3E_CPU0_PE1_PCH_TXP<7>")
	)
	(segment
		(start 374.369838 -118.378478)
		(end 374.192038 -118.378478)
		(width 0.0889)
		(layer "F.Cu")
		(net "P3E_CPU0_PE1_PCH_TXP<7>")
	)
	(segment
		(start 370.79174 -118.971822)
		(end 370.61394 -118.971822)
		(width 0.0889)
		(layer "F.Cu")
		(net "P3E_CPU0_PE1_PCH_TXP<7>")
	)
	(segment
		(start 374.894856 -118.296182)
		(end 374.812306 -118.378732)
		(width 0.0889)
		(layer "F.Cu")
		(net "P3E_CPU0_PE1_PCH_TXP<7>")
	)
	(segment
		(start 375.089928 -118.35511)
		(end 375.031 -118.296182)
		(width 0.0889)
		(layer "F.Cu")
		(net "P3E_CPU0_PE1_PCH_TXP<7>")
	)
	(segment
		(start 374.144794 -118.331234)
		(end 374.022366 -118.331234)
		(width 0.0889)
		(layer "F.Cu")
		(net "P3E_CPU0_PE1_PCH_TXP<7>")
	)
	(segment
		(start 374.587008 -118.331234)
		(end 374.417082 -118.331234)
		(width 0.0889)
		(layer "F.Cu")
		(net "P3E_CPU0_PE1_PCH_TXP<7>")
	)
	(segment
		(start 374.417082 -118.331234)
		(end 374.369838 -118.378478)
		(width 0.0889)
		(layer "F.Cu")
		(net "P3E_CPU0_PE1_PCH_TXP<7>")
	)
	(via
		(at 359.000298 -80.323182)
		(size 0.508)
		(drill 0.254)
		(layers "F.Cu" "B.Cu")
		(net "P3E_CPU0_PE1_PCH_TXP<7>")
	)
	(via
		(at 369.316 -118.237)
		(size 0.508)
		(drill 0.254)
		(layers "F.Cu" "B.Cu")
		(net "P3E_CPU0_PE1_PCH_TXP<7>")
	)
	(segment
		(start 358.104186 -79.79156)
		(end 357.812086 -80.08366)
		(width 0.1143)
		(layer "B.Cu")
		(net "P3E_CPU0_PE1_PCH_TXP<7>")
	)
	(segment
		(start 358.094026 -80.762856)
		(end 358.560624 -80.762856)
		(width 0.1143)
		(layer "B.Cu")
		(net "P3E_CPU0_PE1_PCH_TXP<7>")
	)
	(segment
		(start 357.812086 -80.08366)
		(end 357.812086 -80.480916)
		(width 0.1143)
		(layer "B.Cu")
		(net "P3E_CPU0_PE1_PCH_TXP<7>")
	)
	(segment
		(start 358.91724 -79.79156)
		(end 358.104186 -79.79156)
		(width 0.1143)
		(layer "B.Cu")
		(net "P3E_CPU0_PE1_PCH_TXP<7>")
	)
	(segment
		(start 359.84688 -78.812136)
		(end 359.84688 -78.86192)
		(width 0.1143)
		(layer "B.Cu")
		(net "P3E_CPU0_PE1_PCH_TXP<7>")
	)
	(segment
		(start 358.560624 -80.762856)
		(end 359.000298 -80.323182)
		(width 0.1143)
		(layer "B.Cu")
		(net "P3E_CPU0_PE1_PCH_TXP<7>")
	)
	(segment
		(start 359.84688 -78.86192)
		(end 358.91724 -79.79156)
		(width 0.1143)
		(layer "B.Cu")
		(net "P3E_CPU0_PE1_PCH_TXP<7>")
	)
	(segment
		(start 357.812086 -80.480916)
		(end 358.094026 -80.762856)
		(width 0.1143)
		(layer "B.Cu")
		(net "P3E_CPU0_PE1_PCH_TXP<7>")
	)
	(segment
		(start 362.257594 -98.437446)
		(end 363.565694 -105.047542)
		(width 0.1143)
		(layer "In4.Cu")
		(net "P3E_CPU0_PE1_PCH_TXP<7>")
	)
	(segment
		(start 361.593638 -88.060022)
		(end 361.723686 -88.254078)
		(width 0.1143)
		(layer "In4.Cu")
		(net "P3E_CPU0_PE1_PCH_TXP<7>")
	)
	(segment
		(start 369.2652 -118.7958)
		(end 369.4684 -118.5926)
		(width 0.1143)
		(layer "In4.Cu")
		(net "P3E_CPU0_PE1_PCH_TXP<7>")
	)
	(segment
		(start 363.45241 -107.612688)
		(end 363.664754 -108.6866)
		(width 0.1143)
		(layer "In4.Cu")
		(net "P3E_CPU0_PE1_PCH_TXP<7>")
	)
	(segment
		(start 361.463082 -88.720422)
		(end 361.396534 -89.056718)
		(width 0.1143)
		(layer "In4.Cu")
		(net "P3E_CPU0_PE1_PCH_TXP<7>")
	)
	(segment
		(start 367.094516 -117.601492)
		(end 367.094516 -117.834918)
		(width 0.1143)
		(layer "In4.Cu")
		(net "P3E_CPU0_PE1_PCH_TXP<7>")
	)
	(segment
		(start 361.92079 -87.257382)
		(end 361.854242 -87.593678)
		(width 0.1143)
		(layer "In4.Cu")
		(net "P3E_CPU0_PE1_PCH_TXP<7>")
	)
	(segment
		(start 367.570512 -118.077488)
		(end 367.812828 -118.319804)
		(width 0.1143)
		(layer "In4.Cu")
		(net "P3E_CPU0_PE1_PCH_TXP<7>")
	)
	(segment
		(start 363.565694 -105.047542)
		(end 363.452664 -105.61955)
		(width 0.1143)
		(layer "In4.Cu")
		(net "P3E_CPU0_PE1_PCH_TXP<7>")
	)
	(segment
		(start 361.372658 -82.423254)
		(end 362.040932 -85.79993)
		(width 0.1143)
		(layer "In4.Cu")
		(net "P3E_CPU0_PE1_PCH_TXP<7>")
	)
	(segment
		(start 369.4684 -118.3894)
		(end 369.316 -118.237)
		(width 0.1143)
		(layer "In4.Cu")
		(net "P3E_CPU0_PE1_PCH_TXP<7>")
	)
	(segment
		(start 367.812828 -118.319804)
		(end 367.812828 -118.55323)
		(width 0.1143)
		(layer "In4.Cu")
		(net "P3E_CPU0_PE1_PCH_TXP<7>")
	)
	(segment
		(start 368.055398 -118.7958)
		(end 369.2652 -118.7958)
		(width 0.1143)
		(layer "In4.Cu")
		(net "P3E_CPU0_PE1_PCH_TXP<7>")
	)
	(segment
		(start 369.4684 -118.5926)
		(end 369.4684 -118.3894)
		(width 0.1143)
		(layer "In4.Cu")
		(net "P3E_CPU0_PE1_PCH_TXP<7>")
	)
	(segment
		(start 359.000298 -80.323182)
		(end 359.336848 -80.659732)
		(width 0.1143)
		(layer "In4.Cu")
		(net "P3E_CPU0_PE1_PCH_TXP<7>")
	)
	(segment
		(start 365.7854 -116.525802)
		(end 366.618774 -117.359176)
		(width 0.1143)
		(layer "In4.Cu")
		(net "P3E_CPU0_PE1_PCH_TXP<7>")
	)
	(segment
		(start 361.660186 -87.723726)
		(end 361.593638 -88.060022)
		(width 0.1143)
		(layer "In4.Cu")
		(net "P3E_CPU0_PE1_PCH_TXP<7>")
	)
	(segment
		(start 363.452664 -105.61955)
		(end 363.551216 -106.117898)
		(width 0.1143)
		(layer "In4.Cu")
		(net "P3E_CPU0_PE1_PCH_TXP<7>")
	)
	(segment
		(start 363.551216 -106.117898)
		(end 363.452664 -106.616246)
		(width 0.1143)
		(layer "In4.Cu")
		(net "P3E_CPU0_PE1_PCH_TXP<7>")
	)
	(segment
		(start 364.339124 -109.736382)
		(end 365.104426 -110.125764)
		(width 0.1143)
		(layer "In4.Cu")
		(net "P3E_CPU0_PE1_PCH_TXP<7>")
	)
	(segment
		(start 362.040932 -85.79993)
		(end 361.790996 -87.063326)
		(width 0.1143)
		(layer "In4.Cu")
		(net "P3E_CPU0_PE1_PCH_TXP<7>")
	)
	(segment
		(start 365.7854 -111.20247)
		(end 365.7854 -116.525802)
		(width 0.1143)
		(layer "In4.Cu")
		(net "P3E_CPU0_PE1_PCH_TXP<7>")
	)
	(segment
		(start 361.723686 -88.254078)
		(end 361.657138 -88.590374)
		(width 0.1143)
		(layer "In4.Cu")
		(net "P3E_CPU0_PE1_PCH_TXP<7>")
	)
	(segment
		(start 361.790996 -87.063326)
		(end 361.92079 -87.257382)
		(width 0.1143)
		(layer "In4.Cu")
		(net "P3E_CPU0_PE1_PCH_TXP<7>")
	)
	(segment
		(start 367.812828 -118.55323)
		(end 368.055398 -118.7958)
		(width 0.1143)
		(layer "In4.Cu")
		(net "P3E_CPU0_PE1_PCH_TXP<7>")
	)
	(segment
		(start 361.854242 -87.593678)
		(end 361.660186 -87.723726)
		(width 0.1143)
		(layer "In4.Cu")
		(net "P3E_CPU0_PE1_PCH_TXP<7>")
	)
	(segment
		(start 361.657138 -88.590374)
		(end 361.463082 -88.720422)
		(width 0.1143)
		(layer "In4.Cu")
		(net "P3E_CPU0_PE1_PCH_TXP<7>")
	)
	(segment
		(start 366.618774 -117.359176)
		(end 366.8522 -117.359176)
		(width 0.1143)
		(layer "In4.Cu")
		(net "P3E_CPU0_PE1_PCH_TXP<7>")
	)
	(segment
		(start 362.755434 -95.921576)
		(end 362.257594 -98.437446)
		(width 0.1143)
		(layer "In4.Cu")
		(net "P3E_CPU0_PE1_PCH_TXP<7>")
	)
	(segment
		(start 367.337086 -118.077488)
		(end 367.570512 -118.077488)
		(width 0.1143)
		(layer "In4.Cu")
		(net "P3E_CPU0_PE1_PCH_TXP<7>")
	)
	(segment
		(start 363.550962 -107.11434)
		(end 363.45241 -107.612688)
		(width 0.1143)
		(layer "In4.Cu")
		(net "P3E_CPU0_PE1_PCH_TXP<7>")
	)
	(segment
		(start 365.104426 -110.12551)
		(end 365.7854 -111.20247)
		(width 0.1143)
		(layer "In4.Cu")
		(net "P3E_CPU0_PE1_PCH_TXP<7>")
	)
	(segment
		(start 367.094516 -117.834918)
		(end 367.337086 -118.077488)
		(width 0.1143)
		(layer "In4.Cu")
		(net "P3E_CPU0_PE1_PCH_TXP<7>")
	)
	(segment
		(start 366.8522 -117.359176)
		(end 367.094516 -117.601492)
		(width 0.1143)
		(layer "In4.Cu")
		(net "P3E_CPU0_PE1_PCH_TXP<7>")
	)
	(segment
		(start 363.664754 -108.6866)
		(end 364.339124 -109.736382)
		(width 0.1143)
		(layer "In4.Cu")
		(net "P3E_CPU0_PE1_PCH_TXP<7>")
	)
	(segment
		(start 361.396534 -89.056718)
		(end 362.755434 -95.921576)
		(width 0.1143)
		(layer "In4.Cu")
		(net "P3E_CPU0_PE1_PCH_TXP<7>")
	)
	(segment
		(start 359.336848 -80.659732)
		(end 359.609136 -80.659732)
		(width 0.1143)
		(layer "In4.Cu")
		(net "P3E_CPU0_PE1_PCH_TXP<7>")
	)
	(segment
		(start 365.104426 -110.125764)
		(end 365.104426 -110.12551)
		(width 0.1143)
		(layer "In4.Cu")
		(net "P3E_CPU0_PE1_PCH_TXP<7>")
	)
	(segment
		(start 359.609136 -80.659732)
		(end 361.372658 -82.423254)
		(width 0.1143)
		(layer "In4.Cu")
		(net "P3E_CPU0_PE1_PCH_TXP<7>")
	)
	(segment
		(start 363.452664 -106.616246)
		(end 363.550962 -107.11434)
		(width 0.1143)
		(layer "In4.Cu")
		(net "P3E_CPU0_PE1_PCH_TXP<7>")
	)
	(segment
		(start 371.728746 -118.667022)
		(end 371.728746 -118.573042)
		(width 0.0889)
		(layer "F.Cu")
		(net "P3E_CPU0_PE1_PCH_TXP<6>")
	)
	(segment
		(start 371.728746 -118.573042)
		(end 371.392704 -118.237)
		(width 0.0889)
		(layer "F.Cu")
		(net "P3E_CPU0_PE1_PCH_TXP<6>")
	)
	(segment
		(start 372.509034 -118.82755)
		(end 372.347744 -118.82755)
		(width 0.0889)
		(layer "F.Cu")
		(net "P3E_CPU0_PE1_PCH_TXP<6>")
	)
	(segment
		(start 374.367552 -117.841776)
		(end 374.189752 -117.841776)
		(width 0.0889)
		(layer "F.Cu")
		(net "P3E_CPU0_PE1_PCH_TXP<6>")
	)
	(segment
		(start 372.070884 -118.926864)
		(end 371.97157 -118.82755)
		(width 0.0889)
		(layer "F.Cu")
		(net "P3E_CPU0_PE1_PCH_TXP<6>")
	)
	(segment
		(start 371.392704 -118.237)
		(end 371.2972 -118.237)
		(width 0.0889)
		(layer "F.Cu")
		(net "P3E_CPU0_PE1_PCH_TXP<6>")
	)
	(segment
		(start 374.624092 -117.759734)
		(end 374.449594 -117.759734)
		(width 0.0889)
		(layer "F.Cu")
		(net "P3E_CPU0_PE1_PCH_TXP<6>")
	)
	(segment
		(start 374.674892 -117.854984)
		(end 374.674892 -117.810534)
		(width 0.0889)
		(layer "F.Cu")
		(net "P3E_CPU0_PE1_PCH_TXP<6>")
	)
	(segment
		(start 371.889274 -118.82755)
		(end 371.728746 -118.667022)
		(width 0.0889)
		(layer "F.Cu")
		(net "P3E_CPU0_PE1_PCH_TXP<6>")
	)
	(segment
		(start 374.10771 -117.759734)
		(end 373.974106 -117.759734)
		(width 0.0889)
		(layer "F.Cu")
		(net "P3E_CPU0_PE1_PCH_TXP<6>")
	)
	(segment
		(start 374.449594 -117.759734)
		(end 374.367552 -117.841776)
		(width 0.0889)
		(layer "F.Cu")
		(net "P3E_CPU0_PE1_PCH_TXP<6>")
	)
	(segment
		(start 371.97157 -118.82755)
		(end 371.889274 -118.82755)
		(width 0.0889)
		(layer "F.Cu")
		(net "P3E_CPU0_PE1_PCH_TXP<6>")
	)
	(segment
		(start 372.347744 -118.82755)
		(end 372.24843 -118.926864)
		(width 0.0889)
		(layer "F.Cu")
		(net "P3E_CPU0_PE1_PCH_TXP<6>")
	)
	(segment
		(start 372.806976 -118.926864)
		(end 372.608348 -118.926864)
		(width 0.0889)
		(layer "F.Cu")
		(net "P3E_CPU0_PE1_PCH_TXP<6>")
	)
	(segment
		(start 374.189752 -117.841776)
		(end 374.10771 -117.759734)
		(width 0.0889)
		(layer "F.Cu")
		(net "P3E_CPU0_PE1_PCH_TXP<6>")
	)
	(segment
		(start 372.608348 -118.926864)
		(end 372.509034 -118.82755)
		(width 0.0889)
		(layer "F.Cu")
		(net "P3E_CPU0_PE1_PCH_TXP<6>")
	)
	(segment
		(start 372.24843 -118.926864)
		(end 372.070884 -118.926864)
		(width 0.0889)
		(layer "F.Cu")
		(net "P3E_CPU0_PE1_PCH_TXP<6>")
	)
	(segment
		(start 374.674892 -117.810534)
		(end 374.624092 -117.759734)
		(width 0.0889)
		(layer "F.Cu")
		(net "P3E_CPU0_PE1_PCH_TXP<6>")
	)
	(segment
		(start 373.974106 -117.759734)
		(end 372.806976 -118.926864)
		(width 0.0889)
		(layer "F.Cu")
		(net "P3E_CPU0_PE1_PCH_TXP<6>")
	)
	(via
		(at 371.2972 -118.237)
		(size 0.508)
		(drill 0.254)
		(layers "F.Cu" "B.Cu")
		(net "P3E_CPU0_PE1_PCH_TXP<6>")
	)
	(via
		(at 355.741732 -80.354678)
		(size 0.508)
		(drill 0.254)
		(layers "F.Cu" "B.Cu")
		(net "P3E_CPU0_PE1_PCH_TXP<6>")
	)
	(segment
		(start 355.736398 -79.115158)
		(end 355.736398 -78.804516)
		(width 0.1143)
		(layer "B.Cu")
		(net "P3E_CPU0_PE1_PCH_TXP<6>")
	)
	(segment
		(start 355.981 -79.35976)
		(end 355.736398 -79.115158)
		(width 0.1143)
		(layer "B.Cu")
		(net "P3E_CPU0_PE1_PCH_TXP<6>")
	)
	(segment
		(start 356.597712 -79.62392)
		(end 356.333552 -79.35976)
		(width 0.1143)
		(layer "B.Cu")
		(net "P3E_CPU0_PE1_PCH_TXP<6>")
	)
	(segment
		(start 356.333552 -79.35976)
		(end 355.981 -79.35976)
		(width 0.1143)
		(layer "B.Cu")
		(net "P3E_CPU0_PE1_PCH_TXP<6>")
	)
	(segment
		(start 356.381812 -80.726788)
		(end 356.597712 -80.510888)
		(width 0.1143)
		(layer "B.Cu")
		(net "P3E_CPU0_PE1_PCH_TXP<6>")
	)
	(segment
		(start 356.113842 -80.726788)
		(end 356.381812 -80.726788)
		(width 0.1143)
		(layer "B.Cu")
		(net "P3E_CPU0_PE1_PCH_TXP<6>")
	)
	(segment
		(start 356.597712 -80.510888)
		(end 356.597712 -79.62392)
		(width 0.1143)
		(layer "B.Cu")
		(net "P3E_CPU0_PE1_PCH_TXP<6>")
	)
	(segment
		(start 355.741732 -80.354678)
		(end 356.113842 -80.726788)
		(width 0.1143)
		(layer "B.Cu")
		(net "P3E_CPU0_PE1_PCH_TXP<6>")
	)
	(segment
		(start 366.99825 -119.664734)
		(end 366.99825 -119.431308)
		(width 0.1143)
		(layer "In4.Cu")
		(net "P3E_CPU0_PE1_PCH_TXP<6>")
	)
	(segment
		(start 362.792264 -105.61955)
		(end 362.872274 -105.21569)
		(width 0.1143)
		(layer "In4.Cu")
		(net "P3E_CPU0_PE1_PCH_TXP<6>")
	)
	(segment
		(start 368.634264 -119.907304)
		(end 367.24082 -119.907304)
		(width 0.1143)
		(layer "In4.Cu")
		(net "P3E_CPU0_PE1_PCH_TXP<6>")
	)
	(segment
		(start 370.158264 -119.742204)
		(end 369.815364 -119.742204)
		(width 0.1143)
		(layer "In4.Cu")
		(net "P3E_CPU0_PE1_PCH_TXP<6>")
	)
	(segment
		(start 362.79201 -107.612688)
		(end 362.888276 -107.126278)
		(width 0.1143)
		(layer "In4.Cu")
		(net "P3E_CPU0_PE1_PCH_TXP<6>")
	)
	(segment
		(start 362.872274 -105.21569)
		(end 361.563666 -98.607626)
		(width 0.1143)
		(layer "In4.Cu")
		(net "P3E_CPU0_PE1_PCH_TXP<6>")
	)
	(segment
		(start 369.142264 -119.742204)
		(end 368.799364 -119.742204)
		(width 0.1143)
		(layer "In4.Cu")
		(net "P3E_CPU0_PE1_PCH_TXP<6>")
	)
	(segment
		(start 370.323364 -119.907304)
		(end 370.158264 -119.742204)
		(width 0.1143)
		(layer "In4.Cu")
		(net "P3E_CPU0_PE1_PCH_TXP<6>")
	)
	(segment
		(start 366.279938 -118.712996)
		(end 366.037368 -118.470426)
		(width 0.1143)
		(layer "In4.Cu")
		(net "P3E_CPU0_PE1_PCH_TXP<6>")
	)
	(segment
		(start 362.789724 -106.628946)
		(end 362.890816 -106.117898)
		(width 0.1143)
		(layer "In4.Cu")
		(net "P3E_CPU0_PE1_PCH_TXP<6>")
	)
	(segment
		(start 364.654592 -110.62335)
		(end 363.744764 -110.160562)
		(width 0.1143)
		(layer "In4.Cu")
		(net "P3E_CPU0_PE1_PCH_TXP<6>")
	)
	(segment
		(start 362.888276 -107.126278)
		(end 362.789724 -106.628946)
		(width 0.1143)
		(layer "In4.Cu")
		(net "P3E_CPU0_PE1_PCH_TXP<6>")
	)
	(segment
		(start 366.755934 -119.188992)
		(end 366.522508 -119.188992)
		(width 0.1143)
		(layer "In4.Cu")
		(net "P3E_CPU0_PE1_PCH_TXP<6>")
	)
	(segment
		(start 369.815364 -119.742204)
		(end 369.650264 -119.907304)
		(width 0.1143)
		(layer "In4.Cu")
		(net "P3E_CPU0_PE1_PCH_TXP<6>")
	)
	(segment
		(start 362.095288 -95.921576)
		(end 360.742738 -89.08796)
		(width 0.1143)
		(layer "In4.Cu")
		(net "P3E_CPU0_PE1_PCH_TXP<6>")
	)
	(segment
		(start 371.48135 -118.759986)
		(end 371.48135 -119.092218)
		(width 0.1143)
		(layer "In4.Cu")
		(net "P3E_CPU0_PE1_PCH_TXP<6>")
	)
	(segment
		(start 359.83037 -82.016346)
		(end 358.038146 -82.016346)
		(width 0.1143)
		(layer "In4.Cu")
		(net "P3E_CPU0_PE1_PCH_TXP<6>")
	)
	(segment
		(start 361.387136 -85.831426)
		(end 360.82986 -83.015836)
		(width 0.1143)
		(layer "In4.Cu")
		(net "P3E_CPU0_PE1_PCH_TXP<6>")
	)
	(segment
		(start 365.803942 -118.470426)
		(end 365.125 -117.791484)
		(width 0.1143)
		(layer "In4.Cu")
		(net "P3E_CPU0_PE1_PCH_TXP<6>")
	)
	(segment
		(start 371.48135 -119.092218)
		(end 370.666264 -119.907304)
		(width 0.1143)
		(layer "In4.Cu")
		(net "P3E_CPU0_PE1_PCH_TXP<6>")
	)
	(segment
		(start 368.799364 -119.742204)
		(end 368.634264 -119.907304)
		(width 0.1143)
		(layer "In4.Cu")
		(net "P3E_CPU0_PE1_PCH_TXP<6>")
	)
	(segment
		(start 369.307364 -119.907304)
		(end 369.142264 -119.742204)
		(width 0.1143)
		(layer "In4.Cu")
		(net "P3E_CPU0_PE1_PCH_TXP<6>")
	)
	(segment
		(start 360.742738 -89.08796)
		(end 361.387136 -85.831426)
		(width 0.1143)
		(layer "In4.Cu")
		(net "P3E_CPU0_PE1_PCH_TXP<6>")
	)
	(segment
		(start 366.99825 -119.431308)
		(end 366.755934 -119.188992)
		(width 0.1143)
		(layer "In4.Cu")
		(net "P3E_CPU0_PE1_PCH_TXP<6>")
	)
	(segment
		(start 362.890816 -106.117898)
		(end 362.792264 -105.61955)
		(width 0.1143)
		(layer "In4.Cu")
		(net "P3E_CPU0_PE1_PCH_TXP<6>")
	)
	(segment
		(start 356.71252 -80.69072)
		(end 356.077774 -80.69072)
		(width 0.1143)
		(layer "In4.Cu")
		(net "P3E_CPU0_PE1_PCH_TXP<6>")
	)
	(segment
		(start 365.125 -117.791484)
		(end 365.125 -111.367062)
		(width 0.1143)
		(layer "In4.Cu")
		(net "P3E_CPU0_PE1_PCH_TXP<6>")
	)
	(segment
		(start 367.24082 -119.907304)
		(end 366.99825 -119.664734)
		(width 0.1143)
		(layer "In4.Cu")
		(net "P3E_CPU0_PE1_PCH_TXP<6>")
	)
	(segment
		(start 366.037368 -118.470426)
		(end 365.803942 -118.470426)
		(width 0.1143)
		(layer "In4.Cu")
		(net "P3E_CPU0_PE1_PCH_TXP<6>")
	)
	(segment
		(start 363.744764 -110.160562)
		(end 363.096302 -109.15142)
		(width 0.1143)
		(layer "In4.Cu")
		(net "P3E_CPU0_PE1_PCH_TXP<6>")
	)
	(segment
		(start 369.650264 -119.907304)
		(end 369.307364 -119.907304)
		(width 0.1143)
		(layer "In4.Cu")
		(net "P3E_CPU0_PE1_PCH_TXP<6>")
	)
	(segment
		(start 371.2972 -118.237)
		(end 371.2972 -118.575836)
		(width 0.1143)
		(layer "In4.Cu")
		(net "P3E_CPU0_PE1_PCH_TXP<6>")
	)
	(segment
		(start 356.077774 -80.69072)
		(end 355.741732 -80.354678)
		(width 0.1143)
		(layer "In4.Cu")
		(net "P3E_CPU0_PE1_PCH_TXP<6>")
	)
	(segment
		(start 365.125 -111.367062)
		(end 364.875572 -110.9726)
		(width 0.1143)
		(layer "In4.Cu")
		(net "P3E_CPU0_PE1_PCH_TXP<6>")
	)
	(segment
		(start 370.666264 -119.907304)
		(end 370.323364 -119.907304)
		(width 0.1143)
		(layer "In4.Cu")
		(net "P3E_CPU0_PE1_PCH_TXP<6>")
	)
	(segment
		(start 363.096302 -109.15142)
		(end 362.79201 -107.612688)
		(width 0.1143)
		(layer "In4.Cu")
		(net "P3E_CPU0_PE1_PCH_TXP<6>")
	)
	(segment
		(start 361.563666 -98.607626)
		(end 362.095288 -95.921576)
		(width 0.1143)
		(layer "In4.Cu")
		(net "P3E_CPU0_PE1_PCH_TXP<6>")
	)
	(segment
		(start 364.875572 -110.9726)
		(end 364.654592 -110.62335)
		(width 0.1143)
		(layer "In4.Cu")
		(net "P3E_CPU0_PE1_PCH_TXP<6>")
	)
	(segment
		(start 371.2972 -118.575836)
		(end 371.48135 -118.759986)
		(width 0.1143)
		(layer "In4.Cu")
		(net "P3E_CPU0_PE1_PCH_TXP<6>")
	)
	(segment
		(start 360.82986 -83.015836)
		(end 359.83037 -82.016346)
		(width 0.1143)
		(layer "In4.Cu")
		(net "P3E_CPU0_PE1_PCH_TXP<6>")
	)
	(segment
		(start 366.279938 -118.946422)
		(end 366.279938 -118.712996)
		(width 0.1143)
		(layer "In4.Cu")
		(net "P3E_CPU0_PE1_PCH_TXP<6>")
	)
	(segment
		(start 366.522508 -119.188992)
		(end 366.279938 -118.946422)
		(width 0.1143)
		(layer "In4.Cu")
		(net "P3E_CPU0_PE1_PCH_TXP<6>")
	)
	(segment
		(start 358.038146 -82.016346)
		(end 356.71252 -80.69072)
		(width 0.1143)
		(layer "In4.Cu")
		(net "P3E_CPU0_PE1_PCH_TXP<6>")
	)
	(segment
		(start 369.512342 -117.43309)
		(end 369.316 -117.236748)
		(width 0.0889)
		(layer "F.Cu")
		(net "P3E_CPU0_PE1_PCH_TXP<5>")
	)
	(segment
		(start 371.336824 -117.741446)
		(end 371.245638 -117.741446)
		(width 0.0889)
		(layer "F.Cu")
		(net "P3E_CPU0_PE1_PCH_TXP<5>")
	)
	(segment
		(start 370.523008 -117.43309)
		(end 370.345208 -117.43309)
		(width 0.0889)
		(layer "F.Cu")
		(net "P3E_CPU0_PE1_PCH_TXP<5>")
	)
	(segment
		(start 371.119908 -117.52453)
		(end 371.028468 -117.43309)
		(width 0.0889)
		(layer "F.Cu")
		(net "P3E_CPU0_PE1_PCH_TXP<5>")
	)
	(segment
		(start 372.395242 -117.905276)
		(end 372.217442 -117.905276)
		(width 0.0889)
		(layer "F.Cu")
		(net "P3E_CPU0_PE1_PCH_TXP<5>")
	)
	(segment
		(start 371.432328 -117.83695)
		(end 371.336824 -117.741446)
		(width 0.0889)
		(layer "F.Cu")
		(net "P3E_CPU0_PE1_PCH_TXP<5>")
	)
	(segment
		(start 372.217442 -117.905276)
		(end 372.149116 -117.83695)
		(width 0.0889)
		(layer "F.Cu")
		(net "P3E_CPU0_PE1_PCH_TXP<5>")
	)
	(segment
		(start 370.61394 -117.524022)
		(end 370.523008 -117.43309)
		(width 0.0889)
		(layer "F.Cu")
		(net "P3E_CPU0_PE1_PCH_TXP<5>")
	)
	(segment
		(start 372.463568 -117.83695)
		(end 372.395242 -117.905276)
		(width 0.0889)
		(layer "F.Cu")
		(net "P3E_CPU0_PE1_PCH_TXP<5>")
	)
	(segment
		(start 372.149116 -117.83695)
		(end 371.432328 -117.83695)
		(width 0.0889)
		(layer "F.Cu")
		(net "P3E_CPU0_PE1_PCH_TXP<5>")
	)
	(segment
		(start 371.028468 -117.43309)
		(end 370.882672 -117.43309)
		(width 0.0889)
		(layer "F.Cu")
		(net "P3E_CPU0_PE1_PCH_TXP<5>")
	)
	(segment
		(start 369.985544 -117.43309)
		(end 369.512342 -117.43309)
		(width 0.0889)
		(layer "F.Cu")
		(net "P3E_CPU0_PE1_PCH_TXP<5>")
	)
	(segment
		(start 375.039382 -117.304566)
		(end 374.886728 -117.304566)
		(width 0.0889)
		(layer "F.Cu")
		(net "P3E_CPU0_PE1_PCH_TXP<5>")
	)
	(segment
		(start 370.882672 -117.43309)
		(end 370.79174 -117.524022)
		(width 0.0889)
		(layer "F.Cu")
		(net "P3E_CPU0_PE1_PCH_TXP<5>")
	)
	(segment
		(start 374.369838 -117.378734)
		(end 374.192038 -117.378734)
		(width 0.0889)
		(layer "F.Cu")
		(net "P3E_CPU0_PE1_PCH_TXP<5>")
	)
	(segment
		(start 374.860058 -117.331236)
		(end 374.417336 -117.331236)
		(width 0.0889)
		(layer "F.Cu")
		(net "P3E_CPU0_PE1_PCH_TXP<5>")
	)
	(segment
		(start 369.316 -117.236748)
		(end 369.316 -116.7892)
		(width 0.0889)
		(layer "F.Cu")
		(net "P3E_CPU0_PE1_PCH_TXP<5>")
	)
	(segment
		(start 370.076476 -117.524022)
		(end 369.985544 -117.43309)
		(width 0.0889)
		(layer "F.Cu")
		(net "P3E_CPU0_PE1_PCH_TXP<5>")
	)
	(segment
		(start 371.119908 -117.615716)
		(end 371.119908 -117.52453)
		(width 0.0889)
		(layer "F.Cu")
		(net "P3E_CPU0_PE1_PCH_TXP<5>")
	)
	(segment
		(start 373.75211 -117.331236)
		(end 373.246396 -117.83695)
		(width 0.0889)
		(layer "F.Cu")
		(net "P3E_CPU0_PE1_PCH_TXP<5>")
	)
	(segment
		(start 371.245638 -117.741446)
		(end 371.119908 -117.615716)
		(width 0.0889)
		(layer "F.Cu")
		(net "P3E_CPU0_PE1_PCH_TXP<5>")
	)
	(segment
		(start 374.14454 -117.331236)
		(end 373.75211 -117.331236)
		(width 0.0889)
		(layer "F.Cu")
		(net "P3E_CPU0_PE1_PCH_TXP<5>")
	)
	(segment
		(start 370.79174 -117.524022)
		(end 370.61394 -117.524022)
		(width 0.0889)
		(layer "F.Cu")
		(net "P3E_CPU0_PE1_PCH_TXP<5>")
	)
	(segment
		(start 375.089928 -117.355112)
		(end 375.039382 -117.304566)
		(width 0.0889)
		(layer "F.Cu")
		(net "P3E_CPU0_PE1_PCH_TXP<5>")
	)
	(segment
		(start 374.886728 -117.304566)
		(end 374.860058 -117.331236)
		(width 0.0889)
		(layer "F.Cu")
		(net "P3E_CPU0_PE1_PCH_TXP<5>")
	)
	(segment
		(start 370.254276 -117.524022)
		(end 370.076476 -117.524022)
		(width 0.0889)
		(layer "F.Cu")
		(net "P3E_CPU0_PE1_PCH_TXP<5>")
	)
	(segment
		(start 373.246396 -117.83695)
		(end 372.463568 -117.83695)
		(width 0.0889)
		(layer "F.Cu")
		(net "P3E_CPU0_PE1_PCH_TXP<5>")
	)
	(segment
		(start 374.192038 -117.378734)
		(end 374.14454 -117.331236)
		(width 0.0889)
		(layer "F.Cu")
		(net "P3E_CPU0_PE1_PCH_TXP<5>")
	)
	(segment
		(start 370.345208 -117.43309)
		(end 370.254276 -117.524022)
		(width 0.0889)
		(layer "F.Cu")
		(net "P3E_CPU0_PE1_PCH_TXP<5>")
	)
	(segment
		(start 374.417336 -117.331236)
		(end 374.369838 -117.378734)
		(width 0.0889)
		(layer "F.Cu")
		(net "P3E_CPU0_PE1_PCH_TXP<5>")
	)
	(via
		(at 369.316 -116.7892)
		(size 0.508)
		(drill 0.254)
		(layers "F.Cu" "B.Cu")
		(net "P3E_CPU0_PE1_PCH_TXP<5>")
	)
	(via
		(at 353.625404 -81.142332)
		(size 0.508)
		(drill 0.254)
		(layers "F.Cu" "B.Cu")
		(net "P3E_CPU0_PE1_PCH_TXP<5>")
	)
	(segment
		(start 352.24974 -80.541876)
		(end 352.24974 -80.278478)
		(width 0.1143)
		(layer "B.Cu")
		(net "P3E_CPU0_PE1_PCH_TXP<5>")
	)
	(segment
		(start 352.24974 -79.574644)
		(end 352.561144 -79.26324)
		(width 0.1143)
		(layer "B.Cu")
		(net "P3E_CPU0_PE1_PCH_TXP<5>")
	)
	(segment
		(start 352.24974 -79.706978)
		(end 352.24974 -79.574644)
		(width 0.1143)
		(layer "B.Cu")
		(net "P3E_CPU0_PE1_PCH_TXP<5>")
	)
	(segment
		(start 352.13544 -79.821278)
		(end 352.24974 -79.706978)
		(width 0.1143)
		(layer "B.Cu")
		(net "P3E_CPU0_PE1_PCH_TXP<5>")
	)
	(segment
		(start 353.487228 -80.7974)
		(end 352.505264 -80.7974)
		(width 0.1143)
		(layer "B.Cu")
		(net "P3E_CPU0_PE1_PCH_TXP<5>")
	)
	(segment
		(start 352.561144 -79.26324)
		(end 353.057714 -79.26324)
		(width 0.1143)
		(layer "B.Cu")
		(net "P3E_CPU0_PE1_PCH_TXP<5>")
	)
	(segment
		(start 352.24974 -80.278478)
		(end 352.13544 -80.164178)
		(width 0.1143)
		(layer "B.Cu")
		(net "P3E_CPU0_PE1_PCH_TXP<5>")
	)
	(segment
		(start 353.625404 -81.142332)
		(end 353.625404 -80.935576)
		(width 0.1143)
		(layer "B.Cu")
		(net "P3E_CPU0_PE1_PCH_TXP<5>")
	)
	(segment
		(start 353.625404 -80.935576)
		(end 353.487228 -80.7974)
		(width 0.1143)
		(layer "B.Cu")
		(net "P3E_CPU0_PE1_PCH_TXP<5>")
	)
	(segment
		(start 352.505264 -80.7974)
		(end 352.24974 -80.541876)
		(width 0.1143)
		(layer "B.Cu")
		(net "P3E_CPU0_PE1_PCH_TXP<5>")
	)
	(segment
		(start 352.13544 -80.164178)
		(end 352.13544 -79.821278)
		(width 0.1143)
		(layer "B.Cu")
		(net "P3E_CPU0_PE1_PCH_TXP<5>")
	)
	(segment
		(start 353.057714 -79.26324)
		(end 353.13874 -79.182214)
		(width 0.1143)
		(layer "B.Cu")
		(net "P3E_CPU0_PE1_PCH_TXP<5>")
	)
	(segment
		(start 353.13874 -79.182214)
		(end 353.13874 -78.975966)
		(width 0.1143)
		(layer "B.Cu")
		(net "P3E_CPU0_PE1_PCH_TXP<5>")
	)
	(segment
		(start 353.13874 -78.975966)
		(end 352.96729 -78.804516)
		(width 0.1143)
		(layer "B.Cu")
		(net "P3E_CPU0_PE1_PCH_TXP<5>")
	)
	(segment
		(start 366.9792 -116.526564)
		(end 367.10493 -116.526564)
		(width 0.0889)
		(layer "In4.Cu")
		(net "P3E_CPU0_PE1_PCH_TXP<5>")
	)
	(segment
		(start 364.809024 -109.248702)
		(end 365.556546 -109.628686)
		(width 0.1143)
		(layer "In4.Cu")
		(net "P3E_CPU0_PE1_PCH_TXP<5>")
	)
	(segment
		(start 369.675156 -117.304058)
		(end 369.675156 -117.148356)
		(width 0.0889)
		(layer "In4.Cu")
		(net "P3E_CPU0_PE1_PCH_TXP<5>")
	)
	(segment
		(start 363.383068 -100.704142)
		(end 364.234222 -105.005886)
		(width 0.1143)
		(layer "In4.Cu")
		(net "P3E_CPU0_PE1_PCH_TXP<5>")
	)
	(segment
		(start 366.770412 -116.317776)
		(end 366.9792 -116.526564)
		(width 0.0889)
		(layer "In4.Cu")
		(net "P3E_CPU0_PE1_PCH_TXP<5>")
	)
	(segment
		(start 369.675156 -117.148356)
		(end 369.316 -116.7892)
		(width 0.0889)
		(layer "In4.Cu")
		(net "P3E_CPU0_PE1_PCH_TXP<5>")
	)
	(segment
		(start 361.096052 -81.011776)
		(end 361.924092 -81.839816)
		(width 0.1143)
		(layer "In4.Cu")
		(net "P3E_CPU0_PE1_PCH_TXP<5>")
	)
	(segment
		(start 360.377486 -80.059784)
		(end 360.377486 -80.29321)
		(width 0.1143)
		(layer "In4.Cu")
		(net "P3E_CPU0_PE1_PCH_TXP<5>")
	)
	(segment
		(start 352.679 -81.788)
		(end 353.765866 -81.788)
		(width 0.1143)
		(layer "In4.Cu")
		(net "P3E_CPU0_PE1_PCH_TXP<5>")
	)
	(segment
		(start 354.615496 -79.4004)
		(end 359.484676 -79.4004)
		(width 0.1143)
		(layer "In4.Cu")
		(net "P3E_CPU0_PE1_PCH_TXP<5>")
	)
	(segment
		(start 367.796572 -117.218206)
		(end 367.796572 -117.343936)
		(width 0.0889)
		(layer "In4.Cu")
		(net "P3E_CPU0_PE1_PCH_TXP<5>")
	)
	(segment
		(start 368.19967 -117.443504)
		(end 368.46637 -117.443504)
		(width 0.0889)
		(layer "In4.Cu")
		(net "P3E_CPU0_PE1_PCH_TXP<5>")
	)
	(segment
		(start 365.877348 -110.136178)
		(end 366.105186 -110.187486)
		(width 0.1143)
		(layer "In4.Cu")
		(net "P3E_CPU0_PE1_PCH_TXP<5>")
	)
	(segment
		(start 369.26647 -117.532404)
		(end 369.44681 -117.532404)
		(width 0.0889)
		(layer "In4.Cu")
		(net "P3E_CPU0_PE1_PCH_TXP<5>")
	)
	(segment
		(start 363.446314 -100.17379)
		(end 363.512862 -100.510086)
		(width 0.1143)
		(layer "In4.Cu")
		(net "P3E_CPU0_PE1_PCH_TXP<5>")
	)
	(segment
		(start 352.470466 -81.579466)
		(end 352.679 -81.788)
		(width 0.1143)
		(layer "In4.Cu")
		(net "P3E_CPU0_PE1_PCH_TXP<5>")
	)
	(segment
		(start 363.185964 -99.707446)
		(end 363.252512 -100.043996)
		(width 0.1143)
		(layer "In4.Cu")
		(net "P3E_CPU0_PE1_PCH_TXP<5>")
	)
	(segment
		(start 364.234222 -105.005886)
		(end 364.11281 -105.61955)
		(width 0.1143)
		(layer "In4.Cu")
		(net "P3E_CPU0_PE1_PCH_TXP<5>")
	)
	(segment
		(start 368.46637 -117.443504)
		(end 368.55527 -117.532404)
		(width 0.0889)
		(layer "In4.Cu")
		(net "P3E_CPU0_PE1_PCH_TXP<5>")
	)
	(segment
		(start 364.11281 -105.61955)
		(end 364.211362 -106.117898)
		(width 0.1143)
		(layer "In4.Cu")
		(net "P3E_CPU0_PE1_PCH_TXP<5>")
	)
	(segment
		(start 360.853482 -80.53578)
		(end 361.096052 -80.778096)
		(width 0.1143)
		(layer "In4.Cu")
		(net "P3E_CPU0_PE1_PCH_TXP<5>")
	)
	(segment
		(start 360.377486 -80.29321)
		(end 360.620056 -80.53578)
		(width 0.1143)
		(layer "In4.Cu")
		(net "P3E_CPU0_PE1_PCH_TXP<5>")
	)
	(segment
		(start 364.211362 -106.117898)
		(end 364.11281 -106.616246)
		(width 0.1143)
		(layer "In4.Cu")
		(net "P3E_CPU0_PE1_PCH_TXP<5>")
	)
	(segment
		(start 367.796572 -117.343936)
		(end 367.98504 -117.532404)
		(width 0.0889)
		(layer "In4.Cu")
		(net "P3E_CPU0_PE1_PCH_TXP<5>")
	)
	(segment
		(start 367.10493 -116.526564)
		(end 367.293652 -116.715286)
		(width 0.0889)
		(layer "In4.Cu")
		(net "P3E_CPU0_PE1_PCH_TXP<5>")
	)
	(segment
		(start 360.620056 -80.53578)
		(end 360.853482 -80.53578)
		(width 0.1143)
		(layer "In4.Cu")
		(net "P3E_CPU0_PE1_PCH_TXP<5>")
	)
	(segment
		(start 363.512862 -100.510086)
		(end 363.383068 -100.704142)
		(width 0.1143)
		(layer "In4.Cu")
		(net "P3E_CPU0_PE1_PCH_TXP<5>")
	)
	(segment
		(start 352.470466 -81.132934)
		(end 352.470466 -81.579466)
		(width 0.1143)
		(layer "In4.Cu")
		(net "P3E_CPU0_PE1_PCH_TXP<5>")
	)
	(segment
		(start 367.98504 -117.532404)
		(end 368.11077 -117.532404)
		(width 0.0889)
		(layer "In4.Cu")
		(net "P3E_CPU0_PE1_PCH_TXP<5>")
	)
	(segment
		(start 362.789978 -86.216236)
		(end 362.142532 -89.488772)
		(width 0.1143)
		(layer "In4.Cu")
		(net "P3E_CPU0_PE1_PCH_TXP<5>")
	)
	(segment
		(start 366.4204 -110.994952)
		(end 366.4204 -115.895882)
		(width 0.1143)
		(layer "In4.Cu")
		(net "P3E_CPU0_PE1_PCH_TXP<5>")
	)
	(segment
		(start 367.293652 -116.841016)
		(end 367.48212 -117.029484)
		(width 0.0889)
		(layer "In4.Cu")
		(net "P3E_CPU0_PE1_PCH_TXP<5>")
	)
	(segment
		(start 368.82197 -117.532404)
		(end 368.91087 -117.443504)
		(width 0.0889)
		(layer "In4.Cu")
		(net "P3E_CPU0_PE1_PCH_TXP<5>")
	)
	(segment
		(start 359.90149 -79.817214)
		(end 360.13517 -79.817214)
		(width 0.1143)
		(layer "In4.Cu")
		(net "P3E_CPU0_PE1_PCH_TXP<5>")
	)
	(segment
		(start 365.877348 -110.135924)
		(end 365.877348 -110.136178)
		(width 0.1143)
		(layer "In4.Cu")
		(net "P3E_CPU0_PE1_PCH_TXP<5>")
	)
	(segment
		(start 353.765866 -81.788)
		(end 354.352098 -81.201768)
		(width 0.1143)
		(layer "In4.Cu")
		(net "P3E_CPU0_PE1_PCH_TXP<5>")
	)
	(segment
		(start 366.105186 -110.187486)
		(end 366.288574 -110.4773)
		(width 0.1143)
		(layer "In4.Cu")
		(net "P3E_CPU0_PE1_PCH_TXP<5>")
	)
	(segment
		(start 361.096052 -80.778096)
		(end 361.096052 -81.011776)
		(width 0.1143)
		(layer "In4.Cu")
		(net "P3E_CPU0_PE1_PCH_TXP<5>")
	)
	(segment
		(start 367.60785 -117.029484)
		(end 367.796572 -117.218206)
		(width 0.0889)
		(layer "In4.Cu")
		(net "P3E_CPU0_PE1_PCH_TXP<5>")
	)
	(segment
		(start 354.352098 -79.663798)
		(end 354.615496 -79.4004)
		(width 0.1143)
		(layer "In4.Cu")
		(net "P3E_CPU0_PE1_PCH_TXP<5>")
	)
	(segment
		(start 364.194344 -108.025438)
		(end 364.809024 -109.248702)
		(width 0.1143)
		(layer "In4.Cu")
		(net "P3E_CPU0_PE1_PCH_TXP<5>")
	)
	(segment
		(start 365.556546 -109.628686)
		(end 365.877348 -110.135924)
		(width 0.1143)
		(layer "In4.Cu")
		(net "P3E_CPU0_PE1_PCH_TXP<5>")
	)
	(segment
		(start 352.7806 -80.8228)
		(end 352.470466 -81.132934)
		(width 0.1143)
		(layer "In4.Cu")
		(net "P3E_CPU0_PE1_PCH_TXP<5>")
	)
	(segment
		(start 368.11077 -117.532404)
		(end 368.19967 -117.443504)
		(width 0.0889)
		(layer "In4.Cu")
		(net "P3E_CPU0_PE1_PCH_TXP<5>")
	)
	(segment
		(start 366.770412 -116.246148)
		(end 366.770412 -116.317776)
		(width 0.0889)
		(layer "In4.Cu")
		(net "P3E_CPU0_PE1_PCH_TXP<5>")
	)
	(segment
		(start 359.484676 -79.4004)
		(end 359.90149 -79.817214)
		(width 0.1143)
		(layer "In4.Cu")
		(net "P3E_CPU0_PE1_PCH_TXP<5>")
	)
	(segment
		(start 366.237266 -110.705138)
		(end 366.4204 -110.994952)
		(width 0.1143)
		(layer "In4.Cu")
		(net "P3E_CPU0_PE1_PCH_TXP<5>")
	)
	(segment
		(start 353.305872 -80.8228)
		(end 352.7806 -80.8228)
		(width 0.1143)
		(layer "In4.Cu")
		(net "P3E_CPU0_PE1_PCH_TXP<5>")
	)
	(segment
		(start 360.13517 -79.817214)
		(end 360.377486 -80.059784)
		(width 0.1143)
		(layer "In4.Cu")
		(net "P3E_CPU0_PE1_PCH_TXP<5>")
	)
	(segment
		(start 368.91087 -117.443504)
		(end 369.17757 -117.443504)
		(width 0.0889)
		(layer "In4.Cu")
		(net "P3E_CPU0_PE1_PCH_TXP<5>")
	)
	(segment
		(start 354.352098 -81.201768)
		(end 354.352098 -79.663798)
		(width 0.1143)
		(layer "In4.Cu")
		(net "P3E_CPU0_PE1_PCH_TXP<5>")
	)
	(segment
		(start 363.24921 -99.177094)
		(end 363.315758 -99.51339)
		(width 0.1143)
		(layer "In4.Cu")
		(net "P3E_CPU0_PE1_PCH_TXP<5>")
	)
	(segment
		(start 363.415834 -95.92183)
		(end 362.926376 -98.396298)
		(width 0.1143)
		(layer "In4.Cu")
		(net "P3E_CPU0_PE1_PCH_TXP<5>")
	)
	(segment
		(start 369.17757 -117.443504)
		(end 369.26647 -117.532404)
		(width 0.0889)
		(layer "In4.Cu")
		(net "P3E_CPU0_PE1_PCH_TXP<5>")
	)
	(segment
		(start 369.44681 -117.532404)
		(end 369.675156 -117.304058)
		(width 0.0889)
		(layer "In4.Cu")
		(net "P3E_CPU0_PE1_PCH_TXP<5>")
	)
	(segment
		(start 353.625404 -81.142332)
		(end 353.305872 -80.8228)
		(width 0.1143)
		(layer "In4.Cu")
		(net "P3E_CPU0_PE1_PCH_TXP<5>")
	)
	(segment
		(start 367.293652 -116.715286)
		(end 367.293652 -116.841016)
		(width 0.0889)
		(layer "In4.Cu")
		(net "P3E_CPU0_PE1_PCH_TXP<5>")
	)
	(segment
		(start 364.20806 -107.097068)
		(end 364.109508 -107.595416)
		(width 0.1143)
		(layer "In4.Cu")
		(net "P3E_CPU0_PE1_PCH_TXP<5>")
	)
	(segment
		(start 366.288574 -110.4773)
		(end 366.237266 -110.705138)
		(width 0.1143)
		(layer "In4.Cu")
		(net "P3E_CPU0_PE1_PCH_TXP<5>")
	)
	(segment
		(start 362.926376 -98.396298)
		(end 363.055154 -99.0473)
		(width 0.1143)
		(layer "In4.Cu")
		(net "P3E_CPU0_PE1_PCH_TXP<5>")
	)
	(segment
		(start 362.142532 -89.488772)
		(end 363.415834 -95.92183)
		(width 0.1143)
		(layer "In4.Cu")
		(net "P3E_CPU0_PE1_PCH_TXP<5>")
	)
	(segment
		(start 363.315758 -99.51339)
		(end 363.185964 -99.707446)
		(width 0.1143)
		(layer "In4.Cu")
		(net "P3E_CPU0_PE1_PCH_TXP<5>")
	)
	(segment
		(start 366.4204 -115.895882)
		(end 366.754918 -116.230654)
		(width 0.1143)
		(layer "In4.Cu")
		(net "P3E_CPU0_PE1_PCH_TXP<5>")
	)
	(segment
		(start 366.754918 -116.230654)
		(end 366.770412 -116.246148)
		(width 0.0889)
		(layer "In4.Cu")
		(net "P3E_CPU0_PE1_PCH_TXP<5>")
	)
	(segment
		(start 368.55527 -117.532404)
		(end 368.82197 -117.532404)
		(width 0.0889)
		(layer "In4.Cu")
		(net "P3E_CPU0_PE1_PCH_TXP<5>")
	)
	(segment
		(start 363.252512 -100.043996)
		(end 363.446314 -100.17379)
		(width 0.1143)
		(layer "In4.Cu")
		(net "P3E_CPU0_PE1_PCH_TXP<5>")
	)
	(segment
		(start 364.11281 -106.616246)
		(end 364.20806 -107.097068)
		(width 0.1143)
		(layer "In4.Cu")
		(net "P3E_CPU0_PE1_PCH_TXP<5>")
	)
	(segment
		(start 364.109508 -107.595416)
		(end 364.194344 -108.025438)
		(width 0.1143)
		(layer "In4.Cu")
		(net "P3E_CPU0_PE1_PCH_TXP<5>")
	)
	(segment
		(start 367.48212 -117.029484)
		(end 367.60785 -117.029484)
		(width 0.0889)
		(layer "In4.Cu")
		(net "P3E_CPU0_PE1_PCH_TXP<5>")
	)
	(segment
		(start 363.055154 -99.0473)
		(end 363.24921 -99.177094)
		(width 0.1143)
		(layer "In4.Cu")
		(net "P3E_CPU0_PE1_PCH_TXP<5>")
	)
	(segment
		(start 361.924092 -81.839816)
		(end 362.789978 -86.216236)
		(width 0.1143)
		(layer "In4.Cu")
		(net "P3E_CPU0_PE1_PCH_TXP<5>")
	)
	(segment
		(start 371.728746 -117.219222)
		(end 371.728746 -117.125242)
		(width 0.0889)
		(layer "F.Cu")
		(net "P3E_CPU0_PE1_PCH_TXP<4>")
	)
	(segment
		(start 372.509034 -117.37975)
		(end 372.337584 -117.37975)
		(width 0.0889)
		(layer "F.Cu")
		(net "P3E_CPU0_PE1_PCH_TXP<4>")
	)
	(segment
		(start 371.889274 -117.37975)
		(end 371.728746 -117.219222)
		(width 0.0889)
		(layer "F.Cu")
		(net "P3E_CPU0_PE1_PCH_TXP<4>")
	)
	(segment
		(start 374.26773 -116.860828)
		(end 374.08993 -116.860828)
		(width 0.0889)
		(layer "F.Cu")
		(net "P3E_CPU0_PE1_PCH_TXP<4>")
	)
	(segment
		(start 372.585234 -117.45595)
		(end 372.509034 -117.37975)
		(width 0.0889)
		(layer "F.Cu")
		(net "P3E_CPU0_PE1_PCH_TXP<4>")
	)
	(segment
		(start 372.337584 -117.37975)
		(end 372.261384 -117.45595)
		(width 0.0889)
		(layer "F.Cu")
		(net "P3E_CPU0_PE1_PCH_TXP<4>")
	)
	(segment
		(start 373.25554 -117.16639)
		(end 373.12981 -117.16639)
		(width 0.0889)
		(layer "F.Cu")
		(net "P3E_CPU0_PE1_PCH_TXP<4>")
	)
	(segment
		(start 373.536464 -116.759736)
		(end 373.38127 -116.91493)
		(width 0.0889)
		(layer "F.Cu")
		(net "P3E_CPU0_PE1_PCH_TXP<4>")
	)
	(segment
		(start 373.38127 -117.04066)
		(end 373.25554 -117.16639)
		(width 0.0889)
		(layer "F.Cu")
		(net "P3E_CPU0_PE1_PCH_TXP<4>")
	)
	(segment
		(start 372.84025 -117.45595)
		(end 372.585234 -117.45595)
		(width 0.0889)
		(layer "F.Cu")
		(net "P3E_CPU0_PE1_PCH_TXP<4>")
	)
	(segment
		(start 374.674892 -116.854986)
		(end 374.674892 -116.81079)
		(width 0.0889)
		(layer "F.Cu")
		(net "P3E_CPU0_PE1_PCH_TXP<4>")
	)
	(segment
		(start 371.728746 -117.125242)
		(end 371.392704 -116.7892)
		(width 0.0889)
		(layer "F.Cu")
		(net "P3E_CPU0_PE1_PCH_TXP<4>")
	)
	(segment
		(start 373.12981 -117.16639)
		(end 372.84025 -117.45595)
		(width 0.0889)
		(layer "F.Cu")
		(net "P3E_CPU0_PE1_PCH_TXP<4>")
	)
	(segment
		(start 372.261384 -117.45595)
		(end 372.05793 -117.45595)
		(width 0.0889)
		(layer "F.Cu")
		(net "P3E_CPU0_PE1_PCH_TXP<4>")
	)
	(segment
		(start 374.623838 -116.759736)
		(end 374.368822 -116.759736)
		(width 0.0889)
		(layer "F.Cu")
		(net "P3E_CPU0_PE1_PCH_TXP<4>")
	)
	(segment
		(start 374.674892 -116.81079)
		(end 374.623838 -116.759736)
		(width 0.0889)
		(layer "F.Cu")
		(net "P3E_CPU0_PE1_PCH_TXP<4>")
	)
	(segment
		(start 373.38127 -116.91493)
		(end 373.38127 -117.04066)
		(width 0.0889)
		(layer "F.Cu")
		(net "P3E_CPU0_PE1_PCH_TXP<4>")
	)
	(segment
		(start 371.98173 -117.37975)
		(end 371.889274 -117.37975)
		(width 0.0889)
		(layer "F.Cu")
		(net "P3E_CPU0_PE1_PCH_TXP<4>")
	)
	(segment
		(start 373.988838 -116.759736)
		(end 373.536464 -116.759736)
		(width 0.0889)
		(layer "F.Cu")
		(net "P3E_CPU0_PE1_PCH_TXP<4>")
	)
	(segment
		(start 371.392704 -116.7892)
		(end 371.2972 -116.7892)
		(width 0.0889)
		(layer "F.Cu")
		(net "P3E_CPU0_PE1_PCH_TXP<4>")
	)
	(segment
		(start 372.05793 -117.45595)
		(end 371.98173 -117.37975)
		(width 0.0889)
		(layer "F.Cu")
		(net "P3E_CPU0_PE1_PCH_TXP<4>")
	)
	(segment
		(start 374.368822 -116.759736)
		(end 374.26773 -116.860828)
		(width 0.0889)
		(layer "F.Cu")
		(net "P3E_CPU0_PE1_PCH_TXP<4>")
	)
	(segment
		(start 374.08993 -116.860828)
		(end 373.988838 -116.759736)
		(width 0.0889)
		(layer "F.Cu")
		(net "P3E_CPU0_PE1_PCH_TXP<4>")
	)
	(via
		(at 350.749616 -81.215738)
		(size 0.508)
		(drill 0.254)
		(layers "F.Cu" "B.Cu")
		(net "P3E_CPU0_PE1_PCH_TXP<4>")
	)
	(via
		(at 371.2972 -116.7892)
		(size 0.508)
		(drill 0.254)
		(layers "F.Cu" "B.Cu")
		(net "P3E_CPU0_PE1_PCH_TXP<4>")
	)
	(segment
		(start 349.9612 -79.781146)
		(end 349.9612 -79.465424)
		(width 0.1143)
		(layer "B.Cu")
		(net "P3E_CPU0_PE1_PCH_TXP<4>")
	)
	(segment
		(start 350.749616 -81.215738)
		(end 350.370648 -80.83677)
		(width 0.1143)
		(layer "B.Cu")
		(net "P3E_CPU0_PE1_PCH_TXP<4>")
	)
	(segment
		(start 349.9612 -80.352646)
		(end 349.8469 -80.238346)
		(width 0.1143)
		(layer "B.Cu")
		(net "P3E_CPU0_PE1_PCH_TXP<4>")
	)
	(segment
		(start 349.9612 -80.577436)
		(end 349.9612 -80.352646)
		(width 0.1143)
		(layer "B.Cu")
		(net "P3E_CPU0_PE1_PCH_TXP<4>")
	)
	(segment
		(start 349.9612 -79.465424)
		(end 350.218756 -79.207868)
		(width 0.1143)
		(layer "B.Cu")
		(net "P3E_CPU0_PE1_PCH_TXP<4>")
	)
	(segment
		(start 350.370648 -80.83677)
		(end 350.220534 -80.83677)
		(width 0.1143)
		(layer "B.Cu")
		(net "P3E_CPU0_PE1_PCH_TXP<4>")
	)
	(segment
		(start 350.024192 -78.851252)
		(end 350.024192 -78.723236)
		(width 0.1143)
		(layer "B.Cu")
		(net "P3E_CPU0_PE1_PCH_TXP<4>")
	)
	(segment
		(start 350.218756 -79.207868)
		(end 350.218756 -79.045816)
		(width 0.1143)
		(layer "B.Cu")
		(net "P3E_CPU0_PE1_PCH_TXP<4>")
	)
	(segment
		(start 350.218756 -79.045816)
		(end 350.024192 -78.851252)
		(width 0.1143)
		(layer "B.Cu")
		(net "P3E_CPU0_PE1_PCH_TXP<4>")
	)
	(segment
		(start 349.8469 -80.238346)
		(end 349.8469 -79.895446)
		(width 0.1143)
		(layer "B.Cu")
		(net "P3E_CPU0_PE1_PCH_TXP<4>")
	)
	(segment
		(start 349.8469 -79.895446)
		(end 349.9612 -79.781146)
		(width 0.1143)
		(layer "B.Cu")
		(net "P3E_CPU0_PE1_PCH_TXP<4>")
	)
	(segment
		(start 350.220534 -80.83677)
		(end 349.9612 -80.577436)
		(width 0.1143)
		(layer "B.Cu")
		(net "P3E_CPU0_PE1_PCH_TXP<4>")
	)
	(segment
		(start 368.704114 -106.946954)
		(end 368.506756 -107.943904)
		(width 0.1143)
		(layer "In4.Cu")
		(net "P3E_CPU0_PE1_PCH_TXP<4>")
	)
	(segment
		(start 359.79989 -76.133452)
		(end 360.297984 -76.0349)
		(width 0.1143)
		(layer "In4.Cu")
		(net "P3E_CPU0_PE1_PCH_TXP<4>")
	)
	(segment
		(start 368.51209 -108.9152)
		(end 368.511836 -108.9152)
		(width 0.1143)
		(layer "In4.Cu")
		(net "P3E_CPU0_PE1_PCH_TXP<4>")
	)
	(segment
		(start 368.90833 -116.07165)
		(end 368.99723 -115.98275)
		(width 0.0889)
		(layer "In4.Cu")
		(net "P3E_CPU0_PE1_PCH_TXP<4>")
	)
	(segment
		(start 365.602774 -105.676954)
		(end 367.68532 -105.192068)
		(width 0.1143)
		(layer "In4.Cu")
		(net "P3E_CPU0_PE1_PCH_TXP<4>")
	)
	(segment
		(start 360.297984 -76.0349)
		(end 360.811064 -76.1365)
		(width 0.1143)
		(layer "In4.Cu")
		(net "P3E_CPU0_PE1_PCH_TXP<4>")
	)
	(segment
		(start 361.754166 -80.73898)
		(end 362.173266 -81.30159)
		(width 0.1143)
		(layer "In4.Cu")
		(net "P3E_CPU0_PE1_PCH_TXP<4>")
	)
	(segment
		(start 368.506756 -107.943904)
		(end 368.605562 -108.442252)
		(width 0.1143)
		(layer "In4.Cu")
		(net "P3E_CPU0_PE1_PCH_TXP<4>")
	)
	(segment
		(start 371.2972 -116.490496)
		(end 371.2972 -116.7892)
		(width 0.0889)
		(layer "In4.Cu")
		(net "P3E_CPU0_PE1_PCH_TXP<4>")
	)
	(segment
		(start 368.605562 -108.442252)
		(end 368.51209 -108.9152)
		(width 0.1143)
		(layer "In4.Cu")
		(net "P3E_CPU0_PE1_PCH_TXP<4>")
	)
	(segment
		(start 368.583718 -112.538764)
		(end 368.389662 -112.668812)
		(width 0.1143)
		(layer "In4.Cu")
		(net "P3E_CPU0_PE1_PCH_TXP<4>")
	)
	(segment
		(start 367.850928 -115.594384)
		(end 367.866422 -115.609878)
		(width 0.0889)
		(layer "In4.Cu")
		(net "P3E_CPU0_PE1_PCH_TXP<4>")
	)
	(segment
		(start 368.50447 -109.949488)
		(end 368.50447 -109.949996)
		(width 0.1143)
		(layer "In4.Cu")
		(net "P3E_CPU0_PE1_PCH_TXP<4>")
	)
	(segment
		(start 355.81336 -76.133452)
		(end 356.311708 -76.0349)
		(width 0.1143)
		(layer "In4.Cu")
		(net "P3E_CPU0_PE1_PCH_TXP<4>")
	)
	(segment
		(start 371.511576 -116.27612)
		(end 371.2972 -116.490496)
		(width 0.0889)
		(layer "In4.Cu")
		(net "P3E_CPU0_PE1_PCH_TXP<4>")
	)
	(segment
		(start 350.749616 -81.215738)
		(end 351.091754 -80.8736)
		(width 0.1143)
		(layer "In4.Cu")
		(net "P3E_CPU0_PE1_PCH_TXP<4>")
	)
	(segment
		(start 363.436154 -97.648522)
		(end 364.916212 -105.132886)
		(width 0.1143)
		(layer "In4.Cu")
		(net "P3E_CPU0_PE1_PCH_TXP<4>")
	)
	(segment
		(start 359.301542 -76.0349)
		(end 359.79989 -76.133452)
		(width 0.1143)
		(layer "In4.Cu")
		(net "P3E_CPU0_PE1_PCH_TXP<4>")
	)
	(segment
		(start 351.81667 -80.8736)
		(end 352.418142 -80.272128)
		(width 0.1143)
		(layer "In4.Cu")
		(net "P3E_CPU0_PE1_PCH_TXP<4>")
	)
	(segment
		(start 368.511836 -108.9152)
		(end 368.610388 -109.413548)
		(width 0.1143)
		(layer "In4.Cu")
		(net "P3E_CPU0_PE1_PCH_TXP<4>")
	)
	(segment
		(start 358.304846 -76.0349)
		(end 358.803194 -76.133452)
		(width 0.1143)
		(layer "In4.Cu")
		(net "P3E_CPU0_PE1_PCH_TXP<4>")
	)
	(segment
		(start 361.108498 -77.477874)
		(end 361.754166 -80.739234)
		(width 0.1143)
		(layer "In4.Cu")
		(net "P3E_CPU0_PE1_PCH_TXP<4>")
	)
	(segment
		(start 368.704114 -111.929672)
		(end 368.583718 -112.538764)
		(width 0.1143)
		(layer "In4.Cu")
		(net "P3E_CPU0_PE1_PCH_TXP<4>")
	)
	(segment
		(start 370.41963 -115.98275)
		(end 371.26545 -115.98275)
		(width 0.0889)
		(layer "In4.Cu")
		(net "P3E_CPU0_PE1_PCH_TXP<4>")
	)
	(segment
		(start 353.156012 -76.155042)
		(end 353.465384 -76.063348)
		(width 0.1143)
		(layer "In4.Cu")
		(net "P3E_CPU0_PE1_PCH_TXP<4>")
	)
	(segment
		(start 356.311708 -76.0349)
		(end 356.810056 -76.133452)
		(width 0.1143)
		(layer "In4.Cu")
		(net "P3E_CPU0_PE1_PCH_TXP<4>")
	)
	(segment
		(start 368.12601 -114.001804)
		(end 368.256058 -114.19586)
		(width 0.1143)
		(layer "In4.Cu")
		(net "P3E_CPU0_PE1_PCH_TXP<4>")
	)
	(segment
		(start 368.212116 -114.41811)
		(end 367.68405 -114.946176)
		(width 0.1143)
		(layer "In4.Cu")
		(net "P3E_CPU0_PE1_PCH_TXP<4>")
	)
	(segment
		(start 361.754166 -80.739234)
		(end 361.754166 -80.73898)
		(width 0.1143)
		(layer "In4.Cu")
		(net "P3E_CPU0_PE1_PCH_TXP<4>")
	)
	(segment
		(start 371.26545 -115.98275)
		(end 371.511576 -116.228876)
		(width 0.0889)
		(layer "In4.Cu")
		(net "P3E_CPU0_PE1_PCH_TXP<4>")
	)
	(segment
		(start 353.465384 -76.063348)
		(end 353.819968 -76.133452)
		(width 0.1143)
		(layer "In4.Cu")
		(net "P3E_CPU0_PE1_PCH_TXP<4>")
	)
	(segment
		(start 358.803194 -76.133452)
		(end 359.301542 -76.0349)
		(width 0.1143)
		(layer "In4.Cu")
		(net "P3E_CPU0_PE1_PCH_TXP<4>")
	)
	(segment
		(start 369.70843 -115.98275)
		(end 369.97513 -115.98275)
		(width 0.0889)
		(layer "In4.Cu")
		(net "P3E_CPU0_PE1_PCH_TXP<4>")
	)
	(segment
		(start 356.810056 -76.133452)
		(end 357.308404 -76.0349)
		(width 0.1143)
		(layer "In4.Cu")
		(net "P3E_CPU0_PE1_PCH_TXP<4>")
	)
	(segment
		(start 368.386614 -113.53546)
		(end 368.192558 -113.665508)
		(width 0.1143)
		(layer "In4.Cu")
		(net "P3E_CPU0_PE1_PCH_TXP<4>")
	)
	(segment
		(start 369.97513 -115.98275)
		(end 370.06403 -116.07165)
		(width 0.0889)
		(layer "In4.Cu")
		(net "P3E_CPU0_PE1_PCH_TXP<4>")
	)
	(segment
		(start 368.603022 -110.447328)
		(end 368.506756 -110.933992)
		(width 0.1143)
		(layer "In4.Cu")
		(net "P3E_CPU0_PE1_PCH_TXP<4>")
	)
	(segment
		(start 357.308404 -76.0349)
		(end 357.806752 -76.133452)
		(width 0.1143)
		(layer "In4.Cu")
		(net "P3E_CPU0_PE1_PCH_TXP<4>")
	)
	(segment
		(start 363.864398 -95.485204)
		(end 363.436154 -97.648522)
		(width 0.1143)
		(layer "In4.Cu")
		(net "P3E_CPU0_PE1_PCH_TXP<4>")
	)
	(segment
		(start 352.993198 -76.317856)
		(end 353.156012 -76.155042)
		(width 0.1143)
		(layer "In4.Cu")
		(net "P3E_CPU0_PE1_PCH_TXP<4>")
	)
	(segment
		(start 368.323114 -113.005108)
		(end 368.453162 -113.199164)
		(width 0.1143)
		(layer "In4.Cu")
		(net "P3E_CPU0_PE1_PCH_TXP<4>")
	)
	(segment
		(start 362.59135 -89.052146)
		(end 363.864398 -95.485204)
		(width 0.1143)
		(layer "In4.Cu")
		(net "P3E_CPU0_PE1_PCH_TXP<4>")
	)
	(segment
		(start 363.149388 -86.232238)
		(end 362.59135 -89.052146)
		(width 0.1143)
		(layer "In4.Cu")
		(net "P3E_CPU0_PE1_PCH_TXP<4>")
	)
	(segment
		(start 360.811064 -76.1365)
		(end 361.12704 -76.371958)
		(width 0.1143)
		(layer "In4.Cu")
		(net "P3E_CPU0_PE1_PCH_TXP<4>")
	)
	(segment
		(start 368.64163 -116.07165)
		(end 368.90833 -116.07165)
		(width 0.0889)
		(layer "In4.Cu")
		(net "P3E_CPU0_PE1_PCH_TXP<4>")
	)
	(segment
		(start 352.418142 -79.770732)
		(end 352.993198 -79.195676)
		(width 0.1143)
		(layer "In4.Cu")
		(net "P3E_CPU0_PE1_PCH_TXP<4>")
	)
	(segment
		(start 370.06403 -116.07165)
		(end 370.33073 -116.07165)
		(width 0.0889)
		(layer "In4.Cu")
		(net "P3E_CPU0_PE1_PCH_TXP<4>")
	)
	(segment
		(start 369.61953 -116.07165)
		(end 369.70843 -115.98275)
		(width 0.0889)
		(layer "In4.Cu")
		(net "P3E_CPU0_PE1_PCH_TXP<4>")
	)
	(segment
		(start 368.31143 -115.98275)
		(end 368.55273 -115.98275)
		(width 0.0889)
		(layer "In4.Cu")
		(net "P3E_CPU0_PE1_PCH_TXP<4>")
	)
	(segment
		(start 357.806752 -76.133452)
		(end 358.304846 -76.0349)
		(width 0.1143)
		(layer "In4.Cu")
		(net "P3E_CPU0_PE1_PCH_TXP<4>")
	)
	(segment
		(start 370.33073 -116.07165)
		(end 370.41963 -115.98275)
		(width 0.0889)
		(layer "In4.Cu")
		(net "P3E_CPU0_PE1_PCH_TXP<4>")
	)
	(segment
		(start 368.453162 -113.199164)
		(end 368.386614 -113.53546)
		(width 0.1143)
		(layer "In4.Cu")
		(net "P3E_CPU0_PE1_PCH_TXP<4>")
	)
	(segment
		(start 364.916212 -105.132886)
		(end 365.602774 -105.676954)
		(width 0.1143)
		(layer "In4.Cu")
		(net "P3E_CPU0_PE1_PCH_TXP<4>")
	)
	(segment
		(start 367.850674 -115.59413)
		(end 367.850928 -115.594384)
		(width 0.1143)
		(layer "In4.Cu")
		(net "P3E_CPU0_PE1_PCH_TXP<4>")
	)
	(segment
		(start 369.35283 -116.07165)
		(end 369.61953 -116.07165)
		(width 0.0889)
		(layer "In4.Cu")
		(net "P3E_CPU0_PE1_PCH_TXP<4>")
	)
	(segment
		(start 367.866422 -115.609878)
		(end 367.938558 -115.609878)
		(width 0.0889)
		(layer "In4.Cu")
		(net "P3E_CPU0_PE1_PCH_TXP<4>")
	)
	(segment
		(start 351.091754 -80.8736)
		(end 351.81667 -80.8736)
		(width 0.1143)
		(layer "In4.Cu")
		(net "P3E_CPU0_PE1_PCH_TXP<4>")
	)
	(segment
		(start 353.819968 -76.133452)
		(end 354.318316 -76.0349)
		(width 0.1143)
		(layer "In4.Cu")
		(net "P3E_CPU0_PE1_PCH_TXP<4>")
	)
	(segment
		(start 368.50447 -109.949996)
		(end 368.603022 -110.447328)
		(width 0.1143)
		(layer "In4.Cu")
		(net "P3E_CPU0_PE1_PCH_TXP<4>")
	)
	(segment
		(start 368.610388 -109.413548)
		(end 368.50447 -109.949488)
		(width 0.1143)
		(layer "In4.Cu")
		(net "P3E_CPU0_PE1_PCH_TXP<4>")
	)
	(segment
		(start 368.192558 -113.665508)
		(end 368.12601 -114.001804)
		(width 0.1143)
		(layer "In4.Cu")
		(net "P3E_CPU0_PE1_PCH_TXP<4>")
	)
	(segment
		(start 354.318316 -76.0349)
		(end 354.816664 -76.133452)
		(width 0.1143)
		(layer "In4.Cu")
		(net "P3E_CPU0_PE1_PCH_TXP<4>")
	)
	(segment
		(start 362.173266 -81.30159)
		(end 363.149388 -86.232238)
		(width 0.1143)
		(layer "In4.Cu")
		(net "P3E_CPU0_PE1_PCH_TXP<4>")
	)
	(segment
		(start 361.26166 -76.704444)
		(end 361.108498 -77.477874)
		(width 0.1143)
		(layer "In4.Cu")
		(net "P3E_CPU0_PE1_PCH_TXP<4>")
	)
	(segment
		(start 354.816664 -76.133452)
		(end 355.315012 -76.0349)
		(width 0.1143)
		(layer "In4.Cu")
		(net "P3E_CPU0_PE1_PCH_TXP<4>")
	)
	(segment
		(start 367.938558 -115.609878)
		(end 368.31143 -115.98275)
		(width 0.0889)
		(layer "In4.Cu")
		(net "P3E_CPU0_PE1_PCH_TXP<4>")
	)
	(segment
		(start 368.55273 -115.98275)
		(end 368.64163 -116.07165)
		(width 0.0889)
		(layer "In4.Cu")
		(net "P3E_CPU0_PE1_PCH_TXP<4>")
	)
	(segment
		(start 368.99723 -115.98275)
		(end 369.26393 -115.98275)
		(width 0.0889)
		(layer "In4.Cu")
		(net "P3E_CPU0_PE1_PCH_TXP<4>")
	)
	(segment
		(start 368.389662 -112.668812)
		(end 368.323114 -113.005108)
		(width 0.1143)
		(layer "In4.Cu")
		(net "P3E_CPU0_PE1_PCH_TXP<4>")
	)
	(segment
		(start 368.256058 -114.19586)
		(end 368.212116 -114.41811)
		(width 0.1143)
		(layer "In4.Cu")
		(net "P3E_CPU0_PE1_PCH_TXP<4>")
	)
	(segment
		(start 355.315012 -76.0349)
		(end 355.81336 -76.133452)
		(width 0.1143)
		(layer "In4.Cu")
		(net "P3E_CPU0_PE1_PCH_TXP<4>")
	)
	(segment
		(start 352.418142 -80.272128)
		(end 352.418142 -79.770732)
		(width 0.1143)
		(layer "In4.Cu")
		(net "P3E_CPU0_PE1_PCH_TXP<4>")
	)
	(segment
		(start 368.506756 -110.933992)
		(end 368.704114 -111.929672)
		(width 0.1143)
		(layer "In4.Cu")
		(net "P3E_CPU0_PE1_PCH_TXP<4>")
	)
	(segment
		(start 368.406426 -105.442004)
		(end 368.704114 -106.946954)
		(width 0.1143)
		(layer "In4.Cu")
		(net "P3E_CPU0_PE1_PCH_TXP<4>")
	)
	(segment
		(start 367.68405 -114.946176)
		(end 367.68405 -115.427252)
		(width 0.1143)
		(layer "In4.Cu")
		(net "P3E_CPU0_PE1_PCH_TXP<4>")
	)
	(segment
		(start 361.12704 -76.371958)
		(end 361.26166 -76.704444)
		(width 0.1143)
		(layer "In4.Cu")
		(net "P3E_CPU0_PE1_PCH_TXP<4>")
	)
	(segment
		(start 371.511576 -116.228876)
		(end 371.511576 -116.27612)
		(width 0.0889)
		(layer "In4.Cu")
		(net "P3E_CPU0_PE1_PCH_TXP<4>")
	)
	(segment
		(start 367.68532 -105.192068)
		(end 368.406426 -105.442004)
		(width 0.1143)
		(layer "In4.Cu")
		(net "P3E_CPU0_PE1_PCH_TXP<4>")
	)
	(segment
		(start 367.68405 -115.427252)
		(end 367.850674 -115.593876)
		(width 0.1143)
		(layer "In4.Cu")
		(net "P3E_CPU0_PE1_PCH_TXP<4>")
	)
	(segment
		(start 352.993198 -79.195676)
		(end 352.993198 -76.317856)
		(width 0.1143)
		(layer "In4.Cu")
		(net "P3E_CPU0_PE1_PCH_TXP<4>")
	)
	(segment
		(start 369.26393 -115.98275)
		(end 369.35283 -116.07165)
		(width 0.0889)
		(layer "In4.Cu")
		(net "P3E_CPU0_PE1_PCH_TXP<4>")
	)
	(segment
		(start 367.850674 -115.593876)
		(end 367.850674 -115.59413)
		(width 0.1143)
		(layer "In4.Cu")
		(net "P3E_CPU0_PE1_PCH_TXP<4>")
	)
	(segment
		(start 369.985544 -115.98529)
		(end 369.909598 -115.98529)
		(width 0.0889)
		(layer "F.Cu")
		(net "P3E_CPU0_PE1_PCH_TXP<3>")
	)
	(segment
		(start 371.028468 -115.98529)
		(end 370.882672 -115.98529)
		(width 0.0889)
		(layer "F.Cu")
		(net "P3E_CPU0_PE1_PCH_TXP<3>")
	)
	(segment
		(start 372.384574 -116.463826)
		(end 372.206774 -116.463826)
		(width 0.0889)
		(layer "F.Cu")
		(net "P3E_CPU0_PE1_PCH_TXP<3>")
	)
	(segment
		(start 371.119908 -116.167916)
		(end 371.119908 -116.07673)
		(width 0.0889)
		(layer "F.Cu")
		(net "P3E_CPU0_PE1_PCH_TXP<3>")
	)
	(segment
		(start 375.041922 -116.307108)
		(end 374.883934 -116.307108)
		(width 0.0889)
		(layer "F.Cu")
		(net "P3E_CPU0_PE1_PCH_TXP<3>")
	)
	(segment
		(start 369.406424 -115.3414)
		(end 369.316 -115.3414)
		(width 0.0889)
		(layer "F.Cu")
		(net "P3E_CPU0_PE1_PCH_TXP<3>")
	)
	(segment
		(start 370.254276 -116.076222)
		(end 370.076476 -116.076222)
		(width 0.0889)
		(layer "F.Cu")
		(net "P3E_CPU0_PE1_PCH_TXP<3>")
	)
	(segment
		(start 372.45925 -116.38915)
		(end 372.384574 -116.463826)
		(width 0.0889)
		(layer "F.Cu")
		(net "P3E_CPU0_PE1_PCH_TXP<3>")
	)
	(segment
		(start 370.882672 -115.98529)
		(end 370.79174 -116.076222)
		(width 0.0889)
		(layer "F.Cu")
		(net "P3E_CPU0_PE1_PCH_TXP<3>")
	)
	(segment
		(start 373.23395 -116.38915)
		(end 372.45925 -116.38915)
		(width 0.0889)
		(layer "F.Cu")
		(net "P3E_CPU0_PE1_PCH_TXP<3>")
	)
	(segment
		(start 374.417336 -116.331238)
		(end 374.369838 -116.378736)
		(width 0.0889)
		(layer "F.Cu")
		(net "P3E_CPU0_PE1_PCH_TXP<3>")
	)
	(segment
		(start 374.192038 -116.378736)
		(end 374.14454 -116.331238)
		(width 0.0889)
		(layer "F.Cu")
		(net "P3E_CPU0_PE1_PCH_TXP<3>")
	)
	(segment
		(start 370.79174 -116.076222)
		(end 370.61394 -116.076222)
		(width 0.0889)
		(layer "F.Cu")
		(net "P3E_CPU0_PE1_PCH_TXP<3>")
	)
	(segment
		(start 373.291862 -116.331238)
		(end 373.23395 -116.38915)
		(width 0.0889)
		(layer "F.Cu")
		(net "P3E_CPU0_PE1_PCH_TXP<3>")
	)
	(segment
		(start 371.432328 -116.38915)
		(end 371.336824 -116.293646)
		(width 0.0889)
		(layer "F.Cu")
		(net "P3E_CPU0_PE1_PCH_TXP<3>")
	)
	(segment
		(start 371.336824 -116.293646)
		(end 371.245638 -116.293646)
		(width 0.0889)
		(layer "F.Cu")
		(net "P3E_CPU0_PE1_PCH_TXP<3>")
	)
	(segment
		(start 374.634506 -116.378736)
		(end 374.587008 -116.331238)
		(width 0.0889)
		(layer "F.Cu")
		(net "P3E_CPU0_PE1_PCH_TXP<3>")
	)
	(segment
		(start 369.709192 -115.644168)
		(end 369.406424 -115.3414)
		(width 0.0889)
		(layer "F.Cu")
		(net "P3E_CPU0_PE1_PCH_TXP<3>")
	)
	(segment
		(start 374.883934 -116.307108)
		(end 374.812306 -116.378736)
		(width 0.0889)
		(layer "F.Cu")
		(net "P3E_CPU0_PE1_PCH_TXP<3>")
	)
	(segment
		(start 369.709192 -115.784884)
		(end 369.709192 -115.644168)
		(width 0.0889)
		(layer "F.Cu")
		(net "P3E_CPU0_PE1_PCH_TXP<3>")
	)
	(segment
		(start 371.119908 -116.07673)
		(end 371.028468 -115.98529)
		(width 0.0889)
		(layer "F.Cu")
		(net "P3E_CPU0_PE1_PCH_TXP<3>")
	)
	(segment
		(start 375.089928 -116.355114)
		(end 375.041922 -116.307108)
		(width 0.0889)
		(layer "F.Cu")
		(net "P3E_CPU0_PE1_PCH_TXP<3>")
	)
	(segment
		(start 374.14454 -116.331238)
		(end 373.291862 -116.331238)
		(width 0.0889)
		(layer "F.Cu")
		(net "P3E_CPU0_PE1_PCH_TXP<3>")
	)
	(segment
		(start 370.345208 -115.98529)
		(end 370.254276 -116.076222)
		(width 0.0889)
		(layer "F.Cu")
		(net "P3E_CPU0_PE1_PCH_TXP<3>")
	)
	(segment
		(start 370.523008 -115.98529)
		(end 370.345208 -115.98529)
		(width 0.0889)
		(layer "F.Cu")
		(net "P3E_CPU0_PE1_PCH_TXP<3>")
	)
	(segment
		(start 374.587008 -116.331238)
		(end 374.417336 -116.331238)
		(width 0.0889)
		(layer "F.Cu")
		(net "P3E_CPU0_PE1_PCH_TXP<3>")
	)
	(segment
		(start 369.909598 -115.98529)
		(end 369.709192 -115.784884)
		(width 0.0889)
		(layer "F.Cu")
		(net "P3E_CPU0_PE1_PCH_TXP<3>")
	)
	(segment
		(start 372.132098 -116.38915)
		(end 371.432328 -116.38915)
		(width 0.0889)
		(layer "F.Cu")
		(net "P3E_CPU0_PE1_PCH_TXP<3>")
	)
	(segment
		(start 372.206774 -116.463826)
		(end 372.132098 -116.38915)
		(width 0.0889)
		(layer "F.Cu")
		(net "P3E_CPU0_PE1_PCH_TXP<3>")
	)
	(segment
		(start 374.812306 -116.378736)
		(end 374.634506 -116.378736)
		(width 0.0889)
		(layer "F.Cu")
		(net "P3E_CPU0_PE1_PCH_TXP<3>")
	)
	(segment
		(start 371.245638 -116.293646)
		(end 371.119908 -116.167916)
		(width 0.0889)
		(layer "F.Cu")
		(net "P3E_CPU0_PE1_PCH_TXP<3>")
	)
	(segment
		(start 370.61394 -116.076222)
		(end 370.523008 -115.98529)
		(width 0.0889)
		(layer "F.Cu")
		(net "P3E_CPU0_PE1_PCH_TXP<3>")
	)
	(segment
		(start 374.369838 -116.378736)
		(end 374.192038 -116.378736)
		(width 0.0889)
		(layer "F.Cu")
		(net "P3E_CPU0_PE1_PCH_TXP<3>")
	)
	(segment
		(start 370.076476 -116.076222)
		(end 369.985544 -115.98529)
		(width 0.0889)
		(layer "F.Cu")
		(net "P3E_CPU0_PE1_PCH_TXP<3>")
	)
	(via
		(at 369.316 -115.3414)
		(size 0.508)
		(drill 0.254)
		(layers "F.Cu" "B.Cu")
		(net "P3E_CPU0_PE1_PCH_TXP<3>")
	)
	(via
		(at 348.25686 -81.07553)
		(size 0.508)
		(drill 0.254)
		(layers "F.Cu" "B.Cu")
		(net "P3E_CPU0_PE1_PCH_TXP<3>")
	)
	(segment
		(start 346.97924 -80.257142)
		(end 347.334078 -80.61198)
		(width 0.1143)
		(layer "B.Cu")
		(net "P3E_CPU0_PE1_PCH_TXP<3>")
	)
	(segment
		(start 346.97924 -80.023462)
		(end 346.97924 -80.257142)
		(width 0.1143)
		(layer "B.Cu")
		(net "P3E_CPU0_PE1_PCH_TXP<3>")
	)
	(segment
		(start 346.86494 -79.909162)
		(end 346.97924 -80.023462)
		(width 0.1143)
		(layer "B.Cu")
		(net "P3E_CPU0_PE1_PCH_TXP<3>")
	)
	(segment
		(start 347.17736 -78.677516)
		(end 347.17736 -79.12608)
		(width 0.1143)
		(layer "B.Cu")
		(net "P3E_CPU0_PE1_PCH_TXP<3>")
	)
	(segment
		(start 346.97924 -79.3242)
		(end 346.97924 -79.451962)
		(width 0.1143)
		(layer "B.Cu")
		(net "P3E_CPU0_PE1_PCH_TXP<3>")
	)
	(segment
		(start 348.25686 -80.73136)
		(end 348.25686 -81.07553)
		(width 0.1143)
		(layer "B.Cu")
		(net "P3E_CPU0_PE1_PCH_TXP<3>")
	)
	(segment
		(start 346.86494 -79.566262)
		(end 346.86494 -79.909162)
		(width 0.1143)
		(layer "B.Cu")
		(net "P3E_CPU0_PE1_PCH_TXP<3>")
	)
	(segment
		(start 348.13748 -80.61198)
		(end 348.25686 -80.73136)
		(width 0.1143)
		(layer "B.Cu")
		(net "P3E_CPU0_PE1_PCH_TXP<3>")
	)
	(segment
		(start 347.17736 -79.12608)
		(end 346.97924 -79.3242)
		(width 0.1143)
		(layer "B.Cu")
		(net "P3E_CPU0_PE1_PCH_TXP<3>")
	)
	(segment
		(start 346.97924 -79.451962)
		(end 346.86494 -79.566262)
		(width 0.1143)
		(layer "B.Cu")
		(net "P3E_CPU0_PE1_PCH_TXP<3>")
	)
	(segment
		(start 347.334078 -80.61198)
		(end 348.13748 -80.61198)
		(width 0.1143)
		(layer "B.Cu")
		(net "P3E_CPU0_PE1_PCH_TXP<3>")
	)
	(segment
		(start 363.970062 -92.51696)
		(end 363.903514 -92.180664)
		(width 0.1143)
		(layer "In4.Cu")
		(net "P3E_CPU0_PE1_PCH_TXP<3>")
	)
	(segment
		(start 364.997492 -100.93325)
		(end 364.221776 -97.015554)
		(width 0.1143)
		(layer "In4.Cu")
		(net "P3E_CPU0_PE1_PCH_TXP<3>")
	)
	(segment
		(start 363.772704 -91.520264)
		(end 363.706156 -91.183968)
		(width 0.1143)
		(layer "In4.Cu")
		(net "P3E_CPU0_PE1_PCH_TXP<3>")
	)
	(segment
		(start 363.836204 -90.989912)
		(end 363.769656 -90.653616)
		(width 0.1143)
		(layer "In4.Cu")
		(net "P3E_CPU0_PE1_PCH_TXP<3>")
	)
	(segment
		(start 350.781366 -75.655678)
		(end 350.471994 -75.803506)
		(width 0.1143)
		(layer "In4.Cu")
		(net "P3E_CPU0_PE1_PCH_TXP<3>")
	)
	(segment
		(start 359.301542 -75.3745)
		(end 358.803194 -75.473052)
		(width 0.1143)
		(layer "In4.Cu")
		(net "P3E_CPU0_PE1_PCH_TXP<3>")
	)
	(segment
		(start 366.182656 -102.346506)
		(end 364.997492 -100.93325)
		(width 0.1143)
		(layer "In4.Cu")
		(net "P3E_CPU0_PE1_PCH_TXP<3>")
	)
	(segment
		(start 363.638846 -89.993216)
		(end 363.572298 -89.65692)
		(width 0.1143)
		(layer "In4.Cu")
		(net "P3E_CPU0_PE1_PCH_TXP<3>")
	)
	(segment
		(start 348.59341 -80.73898)
		(end 348.25686 -81.07553)
		(width 0.1143)
		(layer "In4.Cu")
		(net "P3E_CPU0_PE1_PCH_TXP<3>")
	)
	(segment
		(start 369.167156 -109.936788)
		(end 369.266978 -109.432852)
		(width 0.1143)
		(layer "In4.Cu")
		(net "P3E_CPU0_PE1_PCH_TXP<3>")
	)
	(segment
		(start 369.167156 -107.943904)
		(end 369.364514 -106.947208)
		(width 0.1143)
		(layer "In4.Cu")
		(net "P3E_CPU0_PE1_PCH_TXP<3>")
	)
	(segment
		(start 361.080558 -75.52944)
		(end 360.297984 -75.374754)
		(width 0.1143)
		(layer "In4.Cu")
		(net "P3E_CPU0_PE1_PCH_TXP<3>")
	)
	(segment
		(start 361.659424 -75.960986)
		(end 361.080558 -75.52944)
		(width 0.1143)
		(layer "In4.Cu")
		(net "P3E_CPU0_PE1_PCH_TXP<3>")
	)
	(segment
		(start 369.36426 -111.930434)
		(end 369.167156 -110.933738)
		(width 0.1143)
		(layer "In4.Cu")
		(net "P3E_CPU0_PE1_PCH_TXP<3>")
	)
	(segment
		(start 367.887504 -104.09682)
		(end 367.1443 -102.994714)
		(width 0.1143)
		(layer "In4.Cu")
		(net "P3E_CPU0_PE1_PCH_TXP<3>")
	)
	(segment
		(start 356.810056 -75.473052)
		(end 356.337108 -75.37958)
		(width 0.1143)
		(layer "In4.Cu")
		(net "P3E_CPU0_PE1_PCH_TXP<3>")
	)
	(segment
		(start 363.809534 -86.232238)
		(end 362.780834 -81.032858)
		(width 0.1143)
		(layer "In4.Cu")
		(net "P3E_CPU0_PE1_PCH_TXP<3>")
	)
	(segment
		(start 369.364514 -106.947208)
		(end 368.940334 -104.804464)
		(width 0.1143)
		(layer "In4.Cu")
		(net "P3E_CPU0_PE1_PCH_TXP<3>")
	)
	(segment
		(start 368.97818 -113.884202)
		(end 369.36426 -111.930434)
		(width 0.1143)
		(layer "In4.Cu")
		(net "P3E_CPU0_PE1_PCH_TXP<3>")
	)
	(segment
		(start 367.1443 -102.994714)
		(end 366.182656 -102.346506)
		(width 0.1143)
		(layer "In4.Cu")
		(net "P3E_CPU0_PE1_PCH_TXP<3>")
	)
	(segment
		(start 369.167156 -110.933738)
		(end 369.265708 -110.43539)
		(width 0.1143)
		(layer "In4.Cu")
		(net "P3E_CPU0_PE1_PCH_TXP<3>")
	)
	(segment
		(start 355.83876 -75.478132)
		(end 355.315012 -75.3745)
		(width 0.1143)
		(layer "In4.Cu")
		(net "P3E_CPU0_PE1_PCH_TXP<3>")
	)
	(segment
		(start 352.823272 -75.473052)
		(end 352.264218 -75.362562)
		(width 0.1143)
		(layer "In4.Cu")
		(net "P3E_CPU0_PE1_PCH_TXP<3>")
	)
	(segment
		(start 364.625128 -94.976696)
		(end 364.163864 -92.647008)
		(width 0.1143)
		(layer "In4.Cu")
		(net "P3E_CPU0_PE1_PCH_TXP<3>")
	)
	(segment
		(start 354.29571 -75.369928)
		(end 353.797108 -75.46848)
		(width 0.1143)
		(layer "In4.Cu")
		(net "P3E_CPU0_PE1_PCH_TXP<3>")
	)
	(segment
		(start 363.509052 -90.187272)
		(end 363.638846 -89.993216)
		(width 0.1143)
		(layer "In4.Cu")
		(net "P3E_CPU0_PE1_PCH_TXP<3>")
	)
	(segment
		(start 364.033308 -91.986608)
		(end 363.96676 -91.650312)
		(width 0.1143)
		(layer "In4.Cu")
		(net "P3E_CPU0_PE1_PCH_TXP<3>")
	)
	(segment
		(start 361.934506 -76.64069)
		(end 361.659424 -75.960986)
		(width 0.1143)
		(layer "In4.Cu")
		(net "P3E_CPU0_PE1_PCH_TXP<3>")
	)
	(segment
		(start 364.163864 -92.647008)
		(end 363.970062 -92.51696)
		(width 0.1143)
		(layer "In4.Cu")
		(net "P3E_CPU0_PE1_PCH_TXP<3>")
	)
	(segment
		(start 369.168426 -108.934504)
		(end 369.265708 -108.442252)
		(width 0.1143)
		(layer "In4.Cu")
		(net "P3E_CPU0_PE1_PCH_TXP<3>")
	)
	(segment
		(start 364.221776 -97.015554)
		(end 364.625128 -94.976696)
		(width 0.1143)
		(layer "In4.Cu")
		(net "P3E_CPU0_PE1_PCH_TXP<3>")
	)
	(segment
		(start 356.337108 -75.37958)
		(end 355.83876 -75.478132)
		(width 0.1143)
		(layer "In4.Cu")
		(net "P3E_CPU0_PE1_PCH_TXP<3>")
	)
	(segment
		(start 363.769656 -90.653616)
		(end 363.5756 -90.523568)
		(width 0.1143)
		(layer "In4.Cu")
		(net "P3E_CPU0_PE1_PCH_TXP<3>")
	)
	(segment
		(start 369.167156 -109.937296)
		(end 369.167156 -109.936788)
		(width 0.1143)
		(layer "In4.Cu")
		(net "P3E_CPU0_PE1_PCH_TXP<3>")
	)
	(segment
		(start 358.803194 -75.473052)
		(end 358.304846 -75.3745)
		(width 0.1143)
		(layer "In4.Cu")
		(net "P3E_CPU0_PE1_PCH_TXP<3>")
	)
	(segment
		(start 369.504468 -114.938048)
		(end 369.187476 -114.621056)
		(width 0.1143)
		(layer "In4.Cu")
		(net "P3E_CPU0_PE1_PCH_TXP<3>")
	)
	(segment
		(start 362.360972 -80.46974)
		(end 361.768644 -77.477874)
		(width 0.1143)
		(layer "In4.Cu")
		(net "P3E_CPU0_PE1_PCH_TXP<3>")
	)
	(segment
		(start 355.315012 -75.3745)
		(end 354.816664 -75.473052)
		(width 0.1143)
		(layer "In4.Cu")
		(net "P3E_CPU0_PE1_PCH_TXP<3>")
	)
	(segment
		(start 363.96676 -91.650312)
		(end 363.772704 -91.520264)
		(width 0.1143)
		(layer "In4.Cu")
		(net "P3E_CPU0_PE1_PCH_TXP<3>")
	)
	(segment
		(start 349.013272 -80.73898)
		(end 348.59341 -80.73898)
		(width 0.1143)
		(layer "In4.Cu")
		(net "P3E_CPU0_PE1_PCH_TXP<3>")
	)
	(segment
		(start 363.5756 -90.523568)
		(end 363.509052 -90.187272)
		(width 0.1143)
		(layer "In4.Cu")
		(net "P3E_CPU0_PE1_PCH_TXP<3>")
	)
	(segment
		(start 350.076516 -79.675736)
		(end 349.013272 -80.73898)
		(width 0.1143)
		(layer "In4.Cu")
		(net "P3E_CPU0_PE1_PCH_TXP<3>")
	)
	(segment
		(start 363.378242 -89.526872)
		(end 363.311694 -89.190576)
		(width 0.1143)
		(layer "In4.Cu")
		(net "P3E_CPU0_PE1_PCH_TXP<3>")
	)
	(segment
		(start 360.297984 -75.374754)
		(end 359.79989 -75.473052)
		(width 0.1143)
		(layer "In4.Cu")
		(net "P3E_CPU0_PE1_PCH_TXP<3>")
	)
	(segment
		(start 361.768644 -77.477874)
		(end 361.934506 -76.64069)
		(width 0.1143)
		(layer "In4.Cu")
		(net "P3E_CPU0_PE1_PCH_TXP<3>")
	)
	(segment
		(start 357.806752 -75.473052)
		(end 357.308404 -75.3745)
		(width 0.1143)
		(layer "In4.Cu")
		(net "P3E_CPU0_PE1_PCH_TXP<3>")
	)
	(segment
		(start 353.32162 -75.3745)
		(end 352.823272 -75.473052)
		(width 0.1143)
		(layer "In4.Cu")
		(net "P3E_CPU0_PE1_PCH_TXP<3>")
	)
	(segment
		(start 363.706156 -91.183968)
		(end 363.836204 -90.989912)
		(width 0.1143)
		(layer "In4.Cu")
		(net "P3E_CPU0_PE1_PCH_TXP<3>")
	)
	(segment
		(start 352.264218 -75.362562)
		(end 350.781366 -75.655678)
		(width 0.1143)
		(layer "In4.Cu")
		(net "P3E_CPU0_PE1_PCH_TXP<3>")
	)
	(segment
		(start 363.311694 -89.190576)
		(end 363.441742 -88.99652)
		(width 0.1143)
		(layer "In4.Cu")
		(net "P3E_CPU0_PE1_PCH_TXP<3>")
	)
	(segment
		(start 369.316 -115.3414)
		(end 369.504468 -115.152932)
		(width 0.1143)
		(layer "In4.Cu")
		(net "P3E_CPU0_PE1_PCH_TXP<3>")
	)
	(segment
		(start 363.903514 -92.180664)
		(end 364.033308 -91.986608)
		(width 0.1143)
		(layer "In4.Cu")
		(net "P3E_CPU0_PE1_PCH_TXP<3>")
	)
	(segment
		(start 369.265708 -110.43539)
		(end 369.167156 -109.937296)
		(width 0.1143)
		(layer "In4.Cu")
		(net "P3E_CPU0_PE1_PCH_TXP<3>")
	)
	(segment
		(start 363.572298 -89.65692)
		(end 363.378242 -89.526872)
		(width 0.1143)
		(layer "In4.Cu")
		(net "P3E_CPU0_PE1_PCH_TXP<3>")
	)
	(segment
		(start 350.471994 -75.803506)
		(end 350.076516 -76.20381)
		(width 0.1143)
		(layer "In4.Cu")
		(net "P3E_CPU0_PE1_PCH_TXP<3>")
	)
	(segment
		(start 353.797108 -75.46848)
		(end 353.32162 -75.3745)
		(width 0.1143)
		(layer "In4.Cu")
		(net "P3E_CPU0_PE1_PCH_TXP<3>")
	)
	(segment
		(start 359.79989 -75.473052)
		(end 359.301542 -75.3745)
		(width 0.1143)
		(layer "In4.Cu")
		(net "P3E_CPU0_PE1_PCH_TXP<3>")
	)
	(segment
		(start 362.780834 -81.032858)
		(end 362.78058 -81.032858)
		(width 0.1143)
		(layer "In4.Cu")
		(net "P3E_CPU0_PE1_PCH_TXP<3>")
	)
	(segment
		(start 369.187476 -114.621056)
		(end 368.97818 -113.884202)
		(width 0.1143)
		(layer "In4.Cu")
		(net "P3E_CPU0_PE1_PCH_TXP<3>")
	)
	(segment
		(start 369.265708 -108.442252)
		(end 369.167156 -107.943904)
		(width 0.1143)
		(layer "In4.Cu")
		(net "P3E_CPU0_PE1_PCH_TXP<3>")
	)
	(segment
		(start 368.940334 -104.804464)
		(end 367.887504 -104.09682)
		(width 0.1143)
		(layer "In4.Cu")
		(net "P3E_CPU0_PE1_PCH_TXP<3>")
	)
	(segment
		(start 357.308404 -75.3745)
		(end 356.810056 -75.473052)
		(width 0.1143)
		(layer "In4.Cu")
		(net "P3E_CPU0_PE1_PCH_TXP<3>")
	)
	(segment
		(start 350.076516 -76.20381)
		(end 350.076516 -79.675736)
		(width 0.1143)
		(layer "In4.Cu")
		(net "P3E_CPU0_PE1_PCH_TXP<3>")
	)
	(segment
		(start 354.816664 -75.473052)
		(end 354.29571 -75.369928)
		(width 0.1143)
		(layer "In4.Cu")
		(net "P3E_CPU0_PE1_PCH_TXP<3>")
	)
	(segment
		(start 363.35208 -88.543892)
		(end 363.809534 -86.232238)
		(width 0.1143)
		(layer "In4.Cu")
		(net "P3E_CPU0_PE1_PCH_TXP<3>")
	)
	(segment
		(start 369.266978 -109.432852)
		(end 369.168426 -108.934504)
		(width 0.1143)
		(layer "In4.Cu")
		(net "P3E_CPU0_PE1_PCH_TXP<3>")
	)
	(segment
		(start 358.304846 -75.3745)
		(end 357.806752 -75.473052)
		(width 0.1143)
		(layer "In4.Cu")
		(net "P3E_CPU0_PE1_PCH_TXP<3>")
	)
	(segment
		(start 362.78058 -81.032858)
		(end 362.360972 -80.46974)
		(width 0.1143)
		(layer "In4.Cu")
		(net "P3E_CPU0_PE1_PCH_TXP<3>")
	)
	(segment
		(start 369.504468 -115.152932)
		(end 369.504468 -114.938048)
		(width 0.1143)
		(layer "In4.Cu")
		(net "P3E_CPU0_PE1_PCH_TXP<3>")
	)
	(segment
		(start 363.441742 -88.99652)
		(end 363.35208 -88.543892)
		(width 0.1143)
		(layer "In4.Cu")
		(net "P3E_CPU0_PE1_PCH_TXP<3>")
	)
	(segment
		(start 374.03659 -115.86083)
		(end 373.935498 -115.759738)
		(width 0.0889)
		(layer "F.Cu")
		(net "P3E_CPU0_PE1_PCH_TXP<2>")
	)
	(segment
		(start 373.935498 -115.759738)
		(end 373.757698 -115.759738)
		(width 0.0889)
		(layer "F.Cu")
		(net "P3E_CPU0_PE1_PCH_TXP<2>")
	)
	(segment
		(start 371.59946 -115.517676)
		(end 371.423184 -115.3414)
		(width 0.0889)
		(layer "F.Cu")
		(net "P3E_CPU0_PE1_PCH_TXP<2>")
	)
	(segment
		(start 371.423184 -115.3414)
		(end 371.2972 -115.3414)
		(width 0.0889)
		(layer "F.Cu")
		(net "P3E_CPU0_PE1_PCH_TXP<2>")
	)
	(segment
		(start 371.941852 -115.93195)
		(end 371.59946 -115.589558)
		(width 0.0889)
		(layer "F.Cu")
		(net "P3E_CPU0_PE1_PCH_TXP<2>")
	)
	(segment
		(start 373.191278 -115.759738)
		(end 373.019066 -115.93195)
		(width 0.0889)
		(layer "F.Cu")
		(net "P3E_CPU0_PE1_PCH_TXP<2>")
	)
	(segment
		(start 373.656606 -115.86083)
		(end 373.478806 -115.86083)
		(width 0.0889)
		(layer "F.Cu")
		(net "P3E_CPU0_PE1_PCH_TXP<2>")
	)
	(segment
		(start 373.478806 -115.86083)
		(end 373.377714 -115.759738)
		(width 0.0889)
		(layer "F.Cu")
		(net "P3E_CPU0_PE1_PCH_TXP<2>")
	)
	(segment
		(start 373.757698 -115.759738)
		(end 373.656606 -115.86083)
		(width 0.0889)
		(layer "F.Cu")
		(net "P3E_CPU0_PE1_PCH_TXP<2>")
	)
	(segment
		(start 374.315482 -115.759738)
		(end 374.21439 -115.86083)
		(width 0.0889)
		(layer "F.Cu")
		(net "P3E_CPU0_PE1_PCH_TXP<2>")
	)
	(segment
		(start 373.377714 -115.759738)
		(end 373.191278 -115.759738)
		(width 0.0889)
		(layer "F.Cu")
		(net "P3E_CPU0_PE1_PCH_TXP<2>")
	)
	(segment
		(start 374.674892 -115.854988)
		(end 374.579642 -115.759738)
		(width 0.0889)
		(layer "F.Cu")
		(net "P3E_CPU0_PE1_PCH_TXP<2>")
	)
	(segment
		(start 374.579642 -115.759738)
		(end 374.315482 -115.759738)
		(width 0.0889)
		(layer "F.Cu")
		(net "P3E_CPU0_PE1_PCH_TXP<2>")
	)
	(segment
		(start 374.21439 -115.86083)
		(end 374.03659 -115.86083)
		(width 0.0889)
		(layer "F.Cu")
		(net "P3E_CPU0_PE1_PCH_TXP<2>")
	)
	(segment
		(start 373.019066 -115.93195)
		(end 371.941852 -115.93195)
		(width 0.0889)
		(layer "F.Cu")
		(net "P3E_CPU0_PE1_PCH_TXP<2>")
	)
	(segment
		(start 371.59946 -115.589558)
		(end 371.59946 -115.517676)
		(width 0.0889)
		(layer "F.Cu")
		(net "P3E_CPU0_PE1_PCH_TXP<2>")
	)
	(via
		(at 345.514676 -80.98155)
		(size 0.508)
		(drill 0.254)
		(layers "F.Cu" "B.Cu")
		(net "P3E_CPU0_PE1_PCH_TXP<2>")
	)
	(via
		(at 371.2972 -115.3414)
		(size 0.508)
		(drill 0.254)
		(layers "F.Cu" "B.Cu")
		(net "P3E_CPU0_PE1_PCH_TXP<2>")
	)
	(segment
		(start 344.671396 -79.106268)
		(end 344.671396 -78.934056)
		(width 0.1143)
		(layer "B.Cu")
		(net "P3E_CPU0_PE1_PCH_TXP<2>")
	)
	(segment
		(start 345.13774 -80.604614)
		(end 344.905838 -80.604614)
		(width 0.1143)
		(layer "B.Cu")
		(net "P3E_CPU0_PE1_PCH_TXP<2>")
	)
	(segment
		(start 344.435176 -78.697836)
		(end 344.435176 -78.583536)
		(width 0.1143)
		(layer "B.Cu")
		(net "P3E_CPU0_PE1_PCH_TXP<2>")
	)
	(segment
		(start 344.54846 -80.247236)
		(end 344.54846 -80.021176)
		(width 0.1143)
		(layer "B.Cu")
		(net "P3E_CPU0_PE1_PCH_TXP<2>")
	)
	(segment
		(start 344.43416 -79.906876)
		(end 344.43416 -79.563976)
		(width 0.1143)
		(layer "B.Cu")
		(net "P3E_CPU0_PE1_PCH_TXP<2>")
	)
	(segment
		(start 344.671396 -78.934056)
		(end 344.435176 -78.697836)
		(width 0.1143)
		(layer "B.Cu")
		(net "P3E_CPU0_PE1_PCH_TXP<2>")
	)
	(segment
		(start 344.54846 -79.449676)
		(end 344.54846 -79.229204)
		(width 0.1143)
		(layer "B.Cu")
		(net "P3E_CPU0_PE1_PCH_TXP<2>")
	)
	(segment
		(start 344.905838 -80.604614)
		(end 344.54846 -80.247236)
		(width 0.1143)
		(layer "B.Cu")
		(net "P3E_CPU0_PE1_PCH_TXP<2>")
	)
	(segment
		(start 345.514676 -80.98155)
		(end 345.13774 -80.604614)
		(width 0.1143)
		(layer "B.Cu")
		(net "P3E_CPU0_PE1_PCH_TXP<2>")
	)
	(segment
		(start 344.54846 -79.229204)
		(end 344.671396 -79.106268)
		(width 0.1143)
		(layer "B.Cu")
		(net "P3E_CPU0_PE1_PCH_TXP<2>")
	)
	(segment
		(start 344.54846 -80.021176)
		(end 344.43416 -79.906876)
		(width 0.1143)
		(layer "B.Cu")
		(net "P3E_CPU0_PE1_PCH_TXP<2>")
	)
	(segment
		(start 344.43416 -79.563976)
		(end 344.54846 -79.449676)
		(width 0.1143)
		(layer "B.Cu")
		(net "P3E_CPU0_PE1_PCH_TXP<2>")
	)
	(segment
		(start 369.908582 -110.348776)
		(end 369.827302 -109.937296)
		(width 0.1143)
		(layer "In4.Cu")
		(net "P3E_CPU0_PE1_PCH_TXP<2>")
	)
	(segment
		(start 370.717318 -112.928908)
		(end 370.717318 -112.856772)
		(width 0.0889)
		(layer "In4.Cu")
		(net "P3E_CPU0_PE1_PCH_TXP<2>")
	)
	(segment
		(start 357.308404 -74.7141)
		(end 356.810056 -74.812652)
		(width 0.1143)
		(layer "In4.Cu")
		(net "P3E_CPU0_PE1_PCH_TXP<2>")
	)
	(segment
		(start 353.797108 -74.80808)
		(end 353.32162 -74.7141)
		(width 0.1143)
		(layer "In4.Cu")
		(net "P3E_CPU0_PE1_PCH_TXP<2>")
	)
	(segment
		(start 367.665762 -102.43058)
		(end 367.665508 -102.43058)
		(width 0.1143)
		(layer "In4.Cu")
		(net "P3E_CPU0_PE1_PCH_TXP<2>")
	)
	(segment
		(start 355.315012 -74.7141)
		(end 354.816664 -74.812652)
		(width 0.1143)
		(layer "In4.Cu")
		(net "P3E_CPU0_PE1_PCH_TXP<2>")
	)
	(segment
		(start 365.354616 -98.743262)
		(end 365.492284 -98.537268)
		(width 0.1143)
		(layer "In4.Cu")
		(net "P3E_CPU0_PE1_PCH_TXP<2>")
	)
	(segment
		(start 364.390686 -89.765378)
		(end 364.324138 -89.429082)
		(width 0.1143)
		(layer "In4.Cu")
		(net "P3E_CPU0_PE1_PCH_TXP<2>")
	)
	(segment
		(start 367.665508 -102.43058)
		(end 367.410492 -102.175564)
		(width 0.1143)
		(layer "In4.Cu")
		(net "P3E_CPU0_PE1_PCH_TXP<2>")
	)
	(segment
		(start 369.925854 -108.442252)
		(end 369.827556 -107.943904)
		(width 0.1143)
		(layer "In4.Cu")
		(net "P3E_CPU0_PE1_PCH_TXP<2>")
	)
	(segment
		(start 356.337108 -74.71918)
		(end 355.83876 -74.817732)
		(width 0.1143)
		(layer "In4.Cu")
		(net "P3E_CPU0_PE1_PCH_TXP<2>")
	)
	(segment
		(start 364.256828 -88.23833)
		(end 364.16488 -87.773002)
		(width 0.1143)
		(layer "In4.Cu")
		(net "P3E_CPU0_PE1_PCH_TXP<2>")
	)
	(segment
		(start 358.803194 -74.812906)
		(end 358.292146 -74.711814)
		(width 0.1143)
		(layer "In4.Cu")
		(net "P3E_CPU0_PE1_PCH_TXP<2>")
	)
	(segment
		(start 358.292146 -74.711814)
		(end 357.794814 -74.810366)
		(width 0.1143)
		(layer "In4.Cu")
		(net "P3E_CPU0_PE1_PCH_TXP<2>")
	)
	(segment
		(start 361.349544 -74.922126)
		(end 360.298492 -74.714354)
		(width 0.1143)
		(layer "In4.Cu")
		(net "P3E_CPU0_PE1_PCH_TXP<2>")
	)
	(segment
		(start 355.83876 -74.817732)
		(end 355.315012 -74.7141)
		(width 0.1143)
		(layer "In4.Cu")
		(net "P3E_CPU0_PE1_PCH_TXP<2>")
	)
	(segment
		(start 365.290862 -97.52076)
		(end 365.224314 -97.184464)
		(width 0.1143)
		(layer "In4.Cu")
		(net "P3E_CPU0_PE1_PCH_TXP<2>")
	)
	(segment
		(start 362.607352 -76.576936)
		(end 362.191808 -75.550014)
		(width 0.1143)
		(layer "In4.Cu")
		(net "P3E_CPU0_PE1_PCH_TXP<2>")
	)
	(segment
		(start 364.127034 -88.432386)
		(end 364.256828 -88.23833)
		(width 0.1143)
		(layer "In4.Cu")
		(net "P3E_CPU0_PE1_PCH_TXP<2>")
	)
	(segment
		(start 364.588044 -90.762074)
		(end 364.521496 -90.425778)
		(width 0.1143)
		(layer "In4.Cu")
		(net "P3E_CPU0_PE1_PCH_TXP<2>")
	)
	(segment
		(start 352.823272 -74.812652)
		(end 351.433892 -74.538332)
		(width 0.1143)
		(layer "In4.Cu")
		(net "P3E_CPU0_PE1_PCH_TXP<2>")
	)
	(segment
		(start 370.732812 -112.841278)
		(end 370.938552 -112.635538)
		(width 0.1143)
		(layer "In4.Cu")
		(net "P3E_CPU0_PE1_PCH_TXP<2>")
	)
	(segment
		(start 365.421164 -99.079812)
		(end 365.354616 -98.743262)
		(width 0.1143)
		(layer "In4.Cu")
		(net "P3E_CPU0_PE1_PCH_TXP<2>")
	)
	(segment
		(start 369.94338 -114.5921)
		(end 369.94338 -113.702846)
		(width 0.0889)
		(layer "In4.Cu")
		(net "P3E_CPU0_PE1_PCH_TXP<2>")
	)
	(segment
		(start 354.29571 -74.709528)
		(end 353.797108 -74.80808)
		(width 0.1143)
		(layer "In4.Cu")
		(net "P3E_CPU0_PE1_PCH_TXP<2>")
	)
	(segment
		(start 346.717112 -80.645)
		(end 345.851226 -80.645)
		(width 0.1143)
		(layer "In4.Cu")
		(net "P3E_CPU0_PE1_PCH_TXP<2>")
	)
	(segment
		(start 365.224314 -97.184464)
		(end 365.625888 -95.15602)
		(width 0.1143)
		(layer "In4.Cu")
		(net "P3E_CPU0_PE1_PCH_TXP<2>")
	)
	(segment
		(start 356.810056 -74.812652)
		(end 356.337108 -74.71918)
		(width 0.1143)
		(layer "In4.Cu")
		(net "P3E_CPU0_PE1_PCH_TXP<2>")
	)
	(segment
		(start 364.7821 -90.891868)
		(end 364.588044 -90.762074)
		(width 0.1143)
		(layer "In4.Cu")
		(net "P3E_CPU0_PE1_PCH_TXP<2>")
	)
	(segment
		(start 364.469934 -86.232238)
		(end 363.387386 -80.762856)
		(width 0.1143)
		(layer "In4.Cu")
		(net "P3E_CPU0_PE1_PCH_TXP<2>")
	)
	(segment
		(start 368.543078 -103.731568)
		(end 367.665762 -102.43058)
		(width 0.1143)
		(layer "In4.Cu")
		(net "P3E_CPU0_PE1_PCH_TXP<2>")
	)
	(segment
		(start 365.492284 -98.537268)
		(end 365.425736 -98.200972)
		(width 0.1143)
		(layer "In4.Cu")
		(net "P3E_CPU0_PE1_PCH_TXP<2>")
	)
	(segment
		(start 347.316552 -76.279502)
		(end 347.316552 -79.200502)
		(width 0.1143)
		(layer "In4.Cu")
		(net "P3E_CPU0_PE1_PCH_TXP<2>")
	)
	(segment
		(start 353.32162 -74.7141)
		(end 352.823272 -74.812652)
		(width 0.1143)
		(layer "In4.Cu")
		(net "P3E_CPU0_PE1_PCH_TXP<2>")
	)
	(segment
		(start 364.16488 -87.773002)
		(end 364.469934 -86.232238)
		(width 0.1143)
		(layer "In4.Cu")
		(net "P3E_CPU0_PE1_PCH_TXP<2>")
	)
	(segment
		(start 364.387638 -88.89873)
		(end 364.193582 -88.768682)
		(width 0.1143)
		(layer "In4.Cu")
		(net "P3E_CPU0_PE1_PCH_TXP<2>")
	)
	(segment
		(start 364.193582 -88.768682)
		(end 364.127034 -88.432386)
		(width 0.1143)
		(layer "In4.Cu")
		(net "P3E_CPU0_PE1_PCH_TXP<2>")
	)
	(segment
		(start 364.324138 -89.429082)
		(end 364.454186 -89.235026)
		(width 0.1143)
		(layer "In4.Cu")
		(net "P3E_CPU0_PE1_PCH_TXP<2>")
	)
	(segment
		(start 370.800884 -111.593884)
		(end 369.908582 -110.348776)
		(width 0.1143)
		(layer "In4.Cu")
		(net "P3E_CPU0_PE1_PCH_TXP<2>")
	)
	(segment
		(start 359.79989 -74.812906)
		(end 359.301542 -74.714354)
		(width 0.1143)
		(layer "In4.Cu")
		(net "P3E_CPU0_PE1_PCH_TXP<2>")
	)
	(segment
		(start 351.433892 -74.538332)
		(end 348.01175 -75.584304)
		(width 0.1143)
		(layer "In4.Cu")
		(net "P3E_CPU0_PE1_PCH_TXP<2>")
	)
	(segment
		(start 369.828572 -108.934504)
		(end 369.925854 -108.442252)
		(width 0.1143)
		(layer "In4.Cu")
		(net "P3E_CPU0_PE1_PCH_TXP<2>")
	)
	(segment
		(start 357.794814 -74.810366)
		(end 357.308404 -74.7141)
		(width 0.1143)
		(layer "In4.Cu")
		(net "P3E_CPU0_PE1_PCH_TXP<2>")
	)
	(segment
		(start 365.625888 -95.15602)
		(end 364.7821 -90.891868)
		(width 0.1143)
		(layer "In4.Cu")
		(net "P3E_CPU0_PE1_PCH_TXP<2>")
	)
	(segment
		(start 362.191808 -75.550014)
		(end 361.349544 -74.922126)
		(width 0.1143)
		(layer "In4.Cu")
		(net "P3E_CPU0_PE1_PCH_TXP<2>")
	)
	(segment
		(start 362.967778 -80.199738)
		(end 362.967524 -80.19923)
		(width 0.1143)
		(layer "In4.Cu")
		(net "P3E_CPU0_PE1_PCH_TXP<2>")
	)
	(segment
		(start 348.01175 -75.584304)
		(end 347.316552 -76.279502)
		(width 0.1143)
		(layer "In4.Cu")
		(net "P3E_CPU0_PE1_PCH_TXP<2>")
	)
	(segment
		(start 362.967778 -80.199992)
		(end 362.967778 -80.199738)
		(width 0.1143)
		(layer "In4.Cu")
		(net "P3E_CPU0_PE1_PCH_TXP<2>")
	)
	(segment
		(start 370.024406 -106.948478)
		(end 369.52428 -104.41559)
		(width 0.1143)
		(layer "In4.Cu")
		(net "P3E_CPU0_PE1_PCH_TXP<2>")
	)
	(segment
		(start 368.575082 -103.779066)
		(end 368.542824 -103.731568)
		(width 0.1143)
		(layer "In4.Cu")
		(net "P3E_CPU0_PE1_PCH_TXP<2>")
	)
	(segment
		(start 369.827556 -107.943904)
		(end 370.024406 -106.948478)
		(width 0.1143)
		(layer "In4.Cu")
		(net "P3E_CPU0_PE1_PCH_TXP<2>")
	)
	(segment
		(start 347.1164 -80.245712)
		(end 346.717112 -80.645)
		(width 0.1143)
		(layer "In4.Cu")
		(net "P3E_CPU0_PE1_PCH_TXP<2>")
	)
	(segment
		(start 371.5131 -115.03152)
		(end 371.396768 -114.915188)
		(width 0.0889)
		(layer "In4.Cu")
		(net "P3E_CPU0_PE1_PCH_TXP<2>")
	)
	(segment
		(start 369.927378 -109.432852)
		(end 369.828572 -108.934504)
		(width 0.1143)
		(layer "In4.Cu")
		(net "P3E_CPU0_PE1_PCH_TXP<2>")
	)
	(segment
		(start 371.396768 -114.915188)
		(end 370.266468 -114.915188)
		(width 0.0889)
		(layer "In4.Cu")
		(net "P3E_CPU0_PE1_PCH_TXP<2>")
	)
	(segment
		(start 347.316552 -79.200502)
		(end 347.1164 -79.400654)
		(width 0.1143)
		(layer "In4.Cu")
		(net "P3E_CPU0_PE1_PCH_TXP<2>")
	)
	(segment
		(start 364.454186 -89.235026)
		(end 364.387638 -88.89873)
		(width 0.1143)
		(layer "In4.Cu")
		(net "P3E_CPU0_PE1_PCH_TXP<2>")
	)
	(segment
		(start 364.521496 -90.425778)
		(end 364.65129 -90.231722)
		(width 0.1143)
		(layer "In4.Cu")
		(net "P3E_CPU0_PE1_PCH_TXP<2>")
	)
	(segment
		(start 364.584742 -89.895172)
		(end 364.390686 -89.765378)
		(width 0.1143)
		(layer "In4.Cu")
		(net "P3E_CPU0_PE1_PCH_TXP<2>")
	)
	(segment
		(start 365.99241 -101.061012)
		(end 365.627158 -99.21748)
		(width 0.1143)
		(layer "In4.Cu")
		(net "P3E_CPU0_PE1_PCH_TXP<2>")
	)
	(segment
		(start 365.219742 -98.06305)
		(end 365.153194 -97.726754)
		(width 0.1143)
		(layer "In4.Cu")
		(net "P3E_CPU0_PE1_PCH_TXP<2>")
	)
	(segment
		(start 367.410492 -102.175564)
		(end 366.200436 -101.374448)
		(width 0.1143)
		(layer "In4.Cu")
		(net "P3E_CPU0_PE1_PCH_TXP<2>")
	)
	(segment
		(start 370.266468 -114.915188)
		(end 369.94338 -114.5921)
		(width 0.0889)
		(layer "In4.Cu")
		(net "P3E_CPU0_PE1_PCH_TXP<2>")
	)
	(segment
		(start 369.94338 -113.702846)
		(end 370.717318 -112.928908)
		(width 0.0889)
		(layer "In4.Cu")
		(net "P3E_CPU0_PE1_PCH_TXP<2>")
	)
	(segment
		(start 360.298492 -74.714354)
		(end 359.79989 -74.812906)
		(width 0.1143)
		(layer "In4.Cu")
		(net "P3E_CPU0_PE1_PCH_TXP<2>")
	)
	(segment
		(start 370.938552 -112.271556)
		(end 370.800884 -111.593884)
		(width 0.1143)
		(layer "In4.Cu")
		(net "P3E_CPU0_PE1_PCH_TXP<2>")
	)
	(segment
		(start 369.52428 -104.41559)
		(end 368.575082 -103.779066)
		(width 0.1143)
		(layer "In4.Cu")
		(net "P3E_CPU0_PE1_PCH_TXP<2>")
	)
	(segment
		(start 354.816664 -74.812652)
		(end 354.29571 -74.709528)
		(width 0.1143)
		(layer "In4.Cu")
		(net "P3E_CPU0_PE1_PCH_TXP<2>")
	)
	(segment
		(start 369.827302 -109.937296)
		(end 369.927378 -109.432852)
		(width 0.1143)
		(layer "In4.Cu")
		(net "P3E_CPU0_PE1_PCH_TXP<2>")
	)
	(segment
		(start 359.301542 -74.714354)
		(end 358.803194 -74.812906)
		(width 0.1143)
		(layer "In4.Cu")
		(net "P3E_CPU0_PE1_PCH_TXP<2>")
	)
	(segment
		(start 365.153194 -97.726754)
		(end 365.290862 -97.52076)
		(width 0.1143)
		(layer "In4.Cu")
		(net "P3E_CPU0_PE1_PCH_TXP<2>")
	)
	(segment
		(start 362.967524 -80.19923)
		(end 362.42879 -77.477874)
		(width 0.1143)
		(layer "In4.Cu")
		(net "P3E_CPU0_PE1_PCH_TXP<2>")
	)
	(segment
		(start 370.717318 -112.856772)
		(end 370.732812 -112.841278)
		(width 0.0889)
		(layer "In4.Cu")
		(net "P3E_CPU0_PE1_PCH_TXP<2>")
	)
	(segment
		(start 371.5131 -115.1255)
		(end 371.5131 -115.03152)
		(width 0.0889)
		(layer "In4.Cu")
		(net "P3E_CPU0_PE1_PCH_TXP<2>")
	)
	(segment
		(start 363.387386 -80.762856)
		(end 362.967778 -80.199992)
		(width 0.1143)
		(layer "In4.Cu")
		(net "P3E_CPU0_PE1_PCH_TXP<2>")
	)
	(segment
		(start 365.627158 -99.21748)
		(end 365.421164 -99.079812)
		(width 0.1143)
		(layer "In4.Cu")
		(net "P3E_CPU0_PE1_PCH_TXP<2>")
	)
	(segment
		(start 364.65129 -90.231722)
		(end 364.584742 -89.895172)
		(width 0.1143)
		(layer "In4.Cu")
		(net "P3E_CPU0_PE1_PCH_TXP<2>")
	)
	(segment
		(start 368.542824 -103.731568)
		(end 368.543078 -103.731568)
		(width 0.1143)
		(layer "In4.Cu")
		(net "P3E_CPU0_PE1_PCH_TXP<2>")
	)
	(segment
		(start 362.42879 -77.477874)
		(end 362.607352 -76.576936)
		(width 0.1143)
		(layer "In4.Cu")
		(net "P3E_CPU0_PE1_PCH_TXP<2>")
	)
	(segment
		(start 371.2972 -115.3414)
		(end 371.5131 -115.1255)
		(width 0.0889)
		(layer "In4.Cu")
		(net "P3E_CPU0_PE1_PCH_TXP<2>")
	)
	(segment
		(start 347.1164 -79.400654)
		(end 347.1164 -80.245712)
		(width 0.1143)
		(layer "In4.Cu")
		(net "P3E_CPU0_PE1_PCH_TXP<2>")
	)
	(segment
		(start 366.200436 -101.374448)
		(end 365.99241 -101.061012)
		(width 0.1143)
		(layer "In4.Cu")
		(net "P3E_CPU0_PE1_PCH_TXP<2>")
	)
	(segment
		(start 345.851226 -80.645)
		(end 345.514676 -80.98155)
		(width 0.1143)
		(layer "In4.Cu")
		(net "P3E_CPU0_PE1_PCH_TXP<2>")
	)
	(segment
		(start 365.425736 -98.200972)
		(end 365.219742 -98.06305)
		(width 0.1143)
		(layer "In4.Cu")
		(net "P3E_CPU0_PE1_PCH_TXP<2>")
	)
	(segment
		(start 370.938552 -112.635538)
		(end 370.938552 -112.271556)
		(width 0.1143)
		(layer "In4.Cu")
		(net "P3E_CPU0_PE1_PCH_TXP<2>")
	)
	(segment
		(start 373.748554 -115.33124)
		(end 373.612156 -115.33124)
		(width 0.0889)
		(layer "F.Cu")
		(net "P3E_CPU0_PE1_PCH_TXP<1>")
	)
	(segment
		(start 372.993412 -115.146836)
		(end 372.993412 -115.004342)
		(width 0.0889)
		(layer "F.Cu")
		(net "P3E_CPU0_PE1_PCH_TXP<1>")
	)
	(segment
		(start 374.64873 -115.378484)
		(end 374.601486 -115.33124)
		(width 0.0889)
		(layer "F.Cu")
		(net "P3E_CPU0_PE1_PCH_TXP<1>")
	)
	(segment
		(start 372.993412 -115.004342)
		(end 372.90502 -114.91595)
		(width 0.0889)
		(layer "F.Cu")
		(net "P3E_CPU0_PE1_PCH_TXP<1>")
	)
	(segment
		(start 374.601486 -115.33124)
		(end 374.439434 -115.33124)
		(width 0.0889)
		(layer "F.Cu")
		(net "P3E_CPU0_PE1_PCH_TXP<1>")
	)
	(segment
		(start 371.2464 -114.553492)
		(end 371.2464 -114.299238)
		(width 0.0889)
		(layer "F.Cu")
		(net "P3E_CPU0_PE1_PCH_TXP<1>")
	)
	(segment
		(start 373.261636 -115.272566)
		(end 373.119142 -115.272566)
		(width 0.0889)
		(layer "F.Cu")
		(net "P3E_CPU0_PE1_PCH_TXP<1>")
	)
	(segment
		(start 373.795544 -115.37823)
		(end 373.748554 -115.33124)
		(width 0.0889)
		(layer "F.Cu")
		(net "P3E_CPU0_PE1_PCH_TXP<1>")
	)
	(segment
		(start 371.608858 -114.91595)
		(end 371.2464 -114.553492)
		(width 0.0889)
		(layer "F.Cu")
		(net "P3E_CPU0_PE1_PCH_TXP<1>")
	)
	(segment
		(start 374.908572 -115.296442)
		(end 374.82653 -115.378484)
		(width 0.0889)
		(layer "F.Cu")
		(net "P3E_CPU0_PE1_PCH_TXP<1>")
	)
	(segment
		(start 372.90502 -114.91595)
		(end 371.608858 -114.91595)
		(width 0.0889)
		(layer "F.Cu")
		(net "P3E_CPU0_PE1_PCH_TXP<1>")
	)
	(segment
		(start 374.82653 -115.378484)
		(end 374.64873 -115.378484)
		(width 0.0889)
		(layer "F.Cu")
		(net "P3E_CPU0_PE1_PCH_TXP<1>")
	)
	(segment
		(start 374.439434 -115.33124)
		(end 374.392444 -115.37823)
		(width 0.0889)
		(layer "F.Cu")
		(net "P3E_CPU0_PE1_PCH_TXP<1>")
	)
	(segment
		(start 375.031254 -115.296442)
		(end 374.908572 -115.296442)
		(width 0.0889)
		(layer "F.Cu")
		(net "P3E_CPU0_PE1_PCH_TXP<1>")
	)
	(segment
		(start 374.392444 -115.37823)
		(end 374.214644 -115.37823)
		(width 0.0889)
		(layer "F.Cu")
		(net "P3E_CPU0_PE1_PCH_TXP<1>")
	)
	(segment
		(start 374.167654 -115.33124)
		(end 374.020334 -115.33124)
		(width 0.0889)
		(layer "F.Cu")
		(net "P3E_CPU0_PE1_PCH_TXP<1>")
	)
	(segment
		(start 375.089928 -115.355116)
		(end 375.031254 -115.296442)
		(width 0.0889)
		(layer "F.Cu")
		(net "P3E_CPU0_PE1_PCH_TXP<1>")
	)
	(segment
		(start 374.020334 -115.33124)
		(end 373.973344 -115.37823)
		(width 0.0889)
		(layer "F.Cu")
		(net "P3E_CPU0_PE1_PCH_TXP<1>")
	)
	(segment
		(start 373.119142 -115.272566)
		(end 372.993412 -115.146836)
		(width 0.0889)
		(layer "F.Cu")
		(net "P3E_CPU0_PE1_PCH_TXP<1>")
	)
	(segment
		(start 373.973344 -115.37823)
		(end 373.795544 -115.37823)
		(width 0.0889)
		(layer "F.Cu")
		(net "P3E_CPU0_PE1_PCH_TXP<1>")
	)
	(segment
		(start 373.612156 -115.33124)
		(end 373.565928 -115.377468)
		(width 0.0889)
		(layer "F.Cu")
		(net "P3E_CPU0_PE1_PCH_TXP<1>")
	)
	(segment
		(start 374.214644 -115.37823)
		(end 374.167654 -115.33124)
		(width 0.0889)
		(layer "F.Cu")
		(net "P3E_CPU0_PE1_PCH_TXP<1>")
	)
	(segment
		(start 373.366538 -115.377468)
		(end 373.261636 -115.272566)
		(width 0.0889)
		(layer "F.Cu")
		(net "P3E_CPU0_PE1_PCH_TXP<1>")
	)
	(segment
		(start 373.565928 -115.377468)
		(end 373.366538 -115.377468)
		(width 0.0889)
		(layer "F.Cu")
		(net "P3E_CPU0_PE1_PCH_TXP<1>")
	)
	(via
		(at 342.680036 -81.57083)
		(size 0.508)
		(drill 0.254)
		(layers "F.Cu" "B.Cu")
		(net "P3E_CPU0_PE1_PCH_TXP<1>")
	)
	(via
		(at 371.2464 -114.299238)
		(size 0.508)
		(drill 0.254)
		(layers "F.Cu" "B.Cu")
		(net "P3E_CPU0_PE1_PCH_TXP<1>")
	)
	(segment
		(start 341.8332 -80.621886)
		(end 341.8332 -80.964786)
		(width 0.1143)
		(layer "B.Cu")
		(net "P3E_CPU0_PE1_PCH_TXP<1>")
	)
	(segment
		(start 341.8332 -80.050386)
		(end 341.7189 -80.164686)
		(width 0.1143)
		(layer "B.Cu")
		(net "P3E_CPU0_PE1_PCH_TXP<1>")
	)
	(segment
		(start 341.8332 -80.964786)
		(end 342.088724 -81.22031)
		(width 0.1143)
		(layer "B.Cu")
		(net "P3E_CPU0_PE1_PCH_TXP<1>")
	)
	(segment
		(start 341.8332 -78.750668)
		(end 341.8332 -79.135986)
		(width 0.1143)
		(layer "B.Cu")
		(net "P3E_CPU0_PE1_PCH_TXP<1>")
	)
	(segment
		(start 341.7189 -79.593186)
		(end 341.8332 -79.707486)
		(width 0.1143)
		(layer "B.Cu")
		(net "P3E_CPU0_PE1_PCH_TXP<1>")
	)
	(segment
		(start 341.7189 -80.164686)
		(end 341.7189 -80.507586)
		(width 0.1143)
		(layer "B.Cu")
		(net "P3E_CPU0_PE1_PCH_TXP<1>")
	)
	(segment
		(start 341.7189 -79.250286)
		(end 341.7189 -79.593186)
		(width 0.1143)
		(layer "B.Cu")
		(net "P3E_CPU0_PE1_PCH_TXP<1>")
	)
	(segment
		(start 342.329516 -81.22031)
		(end 342.680036 -81.57083)
		(width 0.1143)
		(layer "B.Cu")
		(net "P3E_CPU0_PE1_PCH_TXP<1>")
	)
	(segment
		(start 342.088724 -81.22031)
		(end 342.329516 -81.22031)
		(width 0.1143)
		(layer "B.Cu")
		(net "P3E_CPU0_PE1_PCH_TXP<1>")
	)
	(segment
		(start 341.666068 -78.583536)
		(end 341.8332 -78.750668)
		(width 0.1143)
		(layer "B.Cu")
		(net "P3E_CPU0_PE1_PCH_TXP<1>")
	)
	(segment
		(start 341.8332 -79.135986)
		(end 341.7189 -79.250286)
		(width 0.1143)
		(layer "B.Cu")
		(net "P3E_CPU0_PE1_PCH_TXP<1>")
	)
	(segment
		(start 341.8332 -79.707486)
		(end 341.8332 -80.050386)
		(width 0.1143)
		(layer "B.Cu")
		(net "P3E_CPU0_PE1_PCH_TXP<1>")
	)
	(segment
		(start 341.7189 -80.507586)
		(end 341.8332 -80.621886)
		(width 0.1143)
		(layer "B.Cu")
		(net "P3E_CPU0_PE1_PCH_TXP<1>")
	)
	(segment
		(start 372.72722 -107.944666)
		(end 372.528084 -108.06684)
		(width 0.1143)
		(layer "In4.Cu")
		(net "P3E_CPU0_PE1_PCH_TXP<1>")
	)
	(segment
		(start 363.994446 -80.494124)
		(end 363.994192 -80.494124)
		(width 0.1143)
		(layer "In4.Cu")
		(net "P3E_CPU0_PE1_PCH_TXP<1>")
	)
	(segment
		(start 373.202962 -108.238544)
		(end 373.073168 -108.027216)
		(width 0.1143)
		(layer "In4.Cu")
		(net "P3E_CPU0_PE1_PCH_TXP<1>")
	)
	(segment
		(start 363.280198 -76.513182)
		(end 362.724446 -75.139042)
		(width 0.1143)
		(layer "In4.Cu")
		(net "P3E_CPU0_PE1_PCH_TXP<1>")
	)
	(segment
		(start 363.994192 -80.494124)
		(end 363.574838 -79.93126)
		(width 0.1143)
		(layer "In4.Cu")
		(net "P3E_CPU0_PE1_PCH_TXP<1>")
	)
	(segment
		(start 344.588338 -80.480408)
		(end 343.822782 -81.245964)
		(width 0.1143)
		(layer "In4.Cu")
		(net "P3E_CPU0_PE1_PCH_TXP<1>")
	)
	(segment
		(start 368.36477 -95.803974)
		(end 368.534188 -94.973902)
		(width 0.1143)
		(layer "In4.Cu")
		(net "P3E_CPU0_PE1_PCH_TXP<1>")
	)
	(segment
		(start 353.336352 -74.050906)
		(end 352.823272 -74.152252)
		(width 0.1143)
		(layer "In4.Cu")
		(net "P3E_CPU0_PE1_PCH_TXP<1>")
	)
	(segment
		(start 353.813364 -74.144886)
		(end 353.336352 -74.050906)
		(width 0.1143)
		(layer "In4.Cu")
		(net "P3E_CPU0_PE1_PCH_TXP<1>")
	)
	(segment
		(start 372.072408 -107.788456)
		(end 371.710966 -107.702096)
		(width 0.1143)
		(layer "In4.Cu")
		(net "P3E_CPU0_PE1_PCH_TXP<1>")
	)
	(segment
		(start 374.568212 -108.988098)
		(end 374.49379 -108.621322)
		(width 0.1143)
		(layer "In4.Cu")
		(net "P3E_CPU0_PE1_PCH_TXP<1>")
	)
	(segment
		(start 365.551974 -90.592402)
		(end 365.024416 -88.31072)
		(width 0.1143)
		(layer "In4.Cu")
		(net "P3E_CPU0_PE1_PCH_TXP<1>")
	)
	(segment
		(start 368.52225 -97.21088)
		(end 368.685318 -96.409764)
		(width 0.1143)
		(layer "In4.Cu")
		(net "P3E_CPU0_PE1_PCH_TXP<1>")
	)
	(segment
		(start 358.292146 -74.051414)
		(end 357.794814 -74.149966)
		(width 0.1143)
		(layer "In4.Cu")
		(net "P3E_CPU0_PE1_PCH_TXP<1>")
	)
	(segment
		(start 362.724446 -75.139042)
		(end 361.620308 -74.315574)
		(width 0.1143)
		(layer "In4.Cu")
		(net "P3E_CPU0_PE1_PCH_TXP<1>")
	)
	(segment
		(start 369.588034 -102.523544)
		(end 368.754152 -101.501702)
		(width 0.1143)
		(layer "In4.Cu")
		(net "P3E_CPU0_PE1_PCH_TXP<1>")
	)
	(segment
		(start 343.822782 -81.245964)
		(end 343.004902 -81.245964)
		(width 0.1143)
		(layer "In4.Cu")
		(net "P3E_CPU0_PE1_PCH_TXP<1>")
	)
	(segment
		(start 360.297984 -74.054208)
		(end 359.78973 -74.154792)
		(width 0.1143)
		(layer "In4.Cu")
		(net "P3E_CPU0_PE1_PCH_TXP<1>")
	)
	(segment
		(start 344.588338 -76.129134)
		(end 344.588338 -80.480408)
		(width 0.1143)
		(layer "In4.Cu")
		(net "P3E_CPU0_PE1_PCH_TXP<1>")
	)
	(segment
		(start 368.534188 -94.973902)
		(end 365.551974 -90.592402)
		(width 0.1143)
		(layer "In4.Cu")
		(net "P3E_CPU0_PE1_PCH_TXP<1>")
	)
	(segment
		(start 373.611394 -110.631224)
		(end 374.414034 -110.20806)
		(width 0.1143)
		(layer "In4.Cu")
		(net "P3E_CPU0_PE1_PCH_TXP<1>")
	)
	(segment
		(start 372.863618 -112.193324)
		(end 373.172736 -111.547656)
		(width 0.1143)
		(layer "In4.Cu")
		(net "P3E_CPU0_PE1_PCH_TXP<1>")
	)
	(segment
		(start 359.78973 -74.154792)
		(end 359.290874 -74.055986)
		(width 0.1143)
		(layer "In4.Cu")
		(net "P3E_CPU0_PE1_PCH_TXP<1>")
	)
	(segment
		(start 357.794814 -74.149966)
		(end 357.308404 -74.0537)
		(width 0.1143)
		(layer "In4.Cu")
		(net "P3E_CPU0_PE1_PCH_TXP<1>")
	)
	(segment
		(start 356.337108 -74.059034)
		(end 355.83876 -74.157586)
		(width 0.1143)
		(layer "In4.Cu")
		(net "P3E_CPU0_PE1_PCH_TXP<1>")
	)
	(segment
		(start 373.095012 -111.327438)
		(end 373.243094 -111.018066)
		(width 0.1143)
		(layer "In4.Cu")
		(net "P3E_CPU0_PE1_PCH_TXP<1>")
	)
	(segment
		(start 343.004902 -81.245964)
		(end 342.680036 -81.57083)
		(width 0.1143)
		(layer "In4.Cu")
		(net "P3E_CPU0_PE1_PCH_TXP<1>")
	)
	(segment
		(start 368.759232 -99.203002)
		(end 368.594386 -98.394266)
		(width 0.1143)
		(layer "In4.Cu")
		(net "P3E_CPU0_PE1_PCH_TXP<1>")
	)
	(segment
		(start 374.49379 -108.621322)
		(end 374.228868 -108.303314)
		(width 0.1143)
		(layer "In4.Cu")
		(net "P3E_CPU0_PE1_PCH_TXP<1>")
	)
	(segment
		(start 359.290874 -74.055986)
		(end 358.803194 -74.152506)
		(width 0.1143)
		(layer "In4.Cu")
		(net "P3E_CPU0_PE1_PCH_TXP<1>")
	)
	(segment
		(start 354.816664 -74.152506)
		(end 354.29571 -74.049382)
		(width 0.1143)
		(layer "In4.Cu")
		(net "P3E_CPU0_PE1_PCH_TXP<1>")
	)
	(segment
		(start 374.5484 -109.801152)
		(end 374.43918 -109.359446)
		(width 0.1143)
		(layer "In4.Cu")
		(net "P3E_CPU0_PE1_PCH_TXP<1>")
	)
	(segment
		(start 357.308404 -74.0537)
		(end 356.810056 -74.152506)
		(width 0.1143)
		(layer "In4.Cu")
		(net "P3E_CPU0_PE1_PCH_TXP<1>")
	)
	(segment
		(start 368.678714 -97.979484)
		(end 368.52225 -97.21088)
		(width 0.1143)
		(layer "In4.Cu")
		(net "P3E_CPU0_PE1_PCH_TXP<1>")
	)
	(segment
		(start 371.710966 -107.702096)
		(end 370.719096 -107.123738)
		(width 0.1143)
		(layer "In4.Cu")
		(net "P3E_CPU0_PE1_PCH_TXP<1>")
	)
	(segment
		(start 368.594386 -98.394266)
		(end 368.678714 -97.979484)
		(width 0.1143)
		(layer "In4.Cu")
		(net "P3E_CPU0_PE1_PCH_TXP<1>")
	)
	(segment
		(start 365.024416 -88.31072)
		(end 365.282988 -87.004398)
		(width 0.1143)
		(layer "In4.Cu")
		(net "P3E_CPU0_PE1_PCH_TXP<1>")
	)
	(segment
		(start 355.83876 -74.157586)
		(end 355.315012 -74.053954)
		(width 0.1143)
		(layer "In4.Cu")
		(net "P3E_CPU0_PE1_PCH_TXP<1>")
	)
	(segment
		(start 363.574838 -79.93126)
		(end 363.08919 -77.478382)
		(width 0.1143)
		(layer "In4.Cu")
		(net "P3E_CPU0_PE1_PCH_TXP<1>")
	)
	(segment
		(start 371.438424 -114.107214)
		(end 371.438424 -113.618518)
		(width 0.1143)
		(layer "In4.Cu")
		(net "P3E_CPU0_PE1_PCH_TXP<1>")
	)
	(segment
		(start 374.43918 -109.359446)
		(end 374.568212 -108.988098)
		(width 0.1143)
		(layer "In4.Cu")
		(net "P3E_CPU0_PE1_PCH_TXP<1>")
	)
	(segment
		(start 373.073168 -108.027216)
		(end 372.72722 -107.944666)
		(width 0.1143)
		(layer "In4.Cu")
		(net "P3E_CPU0_PE1_PCH_TXP<1>")
	)
	(segment
		(start 373.243094 -111.018066)
		(end 373.463312 -110.940596)
		(width 0.1143)
		(layer "In4.Cu")
		(net "P3E_CPU0_PE1_PCH_TXP<1>")
	)
	(segment
		(start 373.548656 -108.321094)
		(end 373.202962 -108.238544)
		(width 0.1143)
		(layer "In4.Cu")
		(net "P3E_CPU0_PE1_PCH_TXP<1>")
	)
	(segment
		(start 373.759984 -108.1913)
		(end 373.548656 -108.321094)
		(width 0.1143)
		(layer "In4.Cu")
		(net "P3E_CPU0_PE1_PCH_TXP<1>")
	)
	(segment
		(start 368.685318 -96.409764)
		(end 368.36477 -95.803974)
		(width 0.1143)
		(layer "In4.Cu")
		(net "P3E_CPU0_PE1_PCH_TXP<1>")
	)
	(segment
		(start 373.463312 -110.940596)
		(end 373.611394 -110.631224)
		(width 0.1143)
		(layer "In4.Cu")
		(net "P3E_CPU0_PE1_PCH_TXP<1>")
	)
	(segment
		(start 374.228868 -108.303314)
		(end 373.759984 -108.1913)
		(width 0.1143)
		(layer "In4.Cu")
		(net "P3E_CPU0_PE1_PCH_TXP<1>")
	)
	(segment
		(start 355.315012 -74.053954)
		(end 354.816664 -74.152506)
		(width 0.1143)
		(layer "In4.Cu")
		(net "P3E_CPU0_PE1_PCH_TXP<1>")
	)
	(segment
		(start 370.719096 -107.123738)
		(end 370.129308 -104.135428)
		(width 0.1143)
		(layer "In4.Cu")
		(net "P3E_CPU0_PE1_PCH_TXP<1>")
	)
	(segment
		(start 368.5159 -100.45954)
		(end 368.759232 -99.203002)
		(width 0.1143)
		(layer "In4.Cu")
		(net "P3E_CPU0_PE1_PCH_TXP<1>")
	)
	(segment
		(start 356.810056 -74.152506)
		(end 356.337108 -74.059034)
		(width 0.1143)
		(layer "In4.Cu")
		(net "P3E_CPU0_PE1_PCH_TXP<1>")
	)
	(segment
		(start 354.29571 -74.049382)
		(end 353.813364 -74.144886)
		(width 0.1143)
		(layer "In4.Cu")
		(net "P3E_CPU0_PE1_PCH_TXP<1>")
	)
	(segment
		(start 358.803194 -74.152506)
		(end 358.292146 -74.051414)
		(width 0.1143)
		(layer "In4.Cu")
		(net "P3E_CPU0_PE1_PCH_TXP<1>")
	)
	(segment
		(start 361.620308 -74.315574)
		(end 360.297984 -74.054208)
		(width 0.1143)
		(layer "In4.Cu")
		(net "P3E_CPU0_PE1_PCH_TXP<1>")
	)
	(segment
		(start 371.438424 -113.618518)
		(end 372.863618 -112.193324)
		(width 0.1143)
		(layer "In4.Cu")
		(net "P3E_CPU0_PE1_PCH_TXP<1>")
	)
	(segment
		(start 372.528084 -108.06684)
		(end 372.194582 -107.987338)
		(width 0.1143)
		(layer "In4.Cu")
		(net "P3E_CPU0_PE1_PCH_TXP<1>")
	)
	(segment
		(start 374.414034 -110.20806)
		(end 374.5484 -109.801152)
		(width 0.1143)
		(layer "In4.Cu")
		(net "P3E_CPU0_PE1_PCH_TXP<1>")
	)
	(segment
		(start 352.823272 -74.152252)
		(end 350.86417 -73.765664)
		(width 0.1143)
		(layer "In4.Cu")
		(net "P3E_CPU0_PE1_PCH_TXP<1>")
	)
	(segment
		(start 372.194582 -107.987338)
		(end 372.072408 -107.788456)
		(width 0.1143)
		(layer "In4.Cu")
		(net "P3E_CPU0_PE1_PCH_TXP<1>")
	)
	(segment
		(start 370.129308 -104.135428)
		(end 369.588034 -102.523544)
		(width 0.1143)
		(layer "In4.Cu")
		(net "P3E_CPU0_PE1_PCH_TXP<1>")
	)
	(segment
		(start 365.282988 -87.004398)
		(end 363.994446 -80.494124)
		(width 0.1143)
		(layer "In4.Cu")
		(net "P3E_CPU0_PE1_PCH_TXP<1>")
	)
	(segment
		(start 363.08919 -77.478382)
		(end 363.280198 -76.513182)
		(width 0.1143)
		(layer "In4.Cu")
		(net "P3E_CPU0_PE1_PCH_TXP<1>")
	)
	(segment
		(start 371.2464 -114.299238)
		(end 371.438424 -114.107214)
		(width 0.1143)
		(layer "In4.Cu")
		(net "P3E_CPU0_PE1_PCH_TXP<1>")
	)
	(segment
		(start 368.754152 -101.501702)
		(end 368.5159 -100.45954)
		(width 0.1143)
		(layer "In4.Cu")
		(net "P3E_CPU0_PE1_PCH_TXP<1>")
	)
	(segment
		(start 350.86417 -73.765664)
		(end 345.229942 -75.48753)
		(width 0.1143)
		(layer "In4.Cu")
		(net "P3E_CPU0_PE1_PCH_TXP<1>")
	)
	(segment
		(start 345.229942 -75.48753)
		(end 344.588338 -76.129134)
		(width 0.1143)
		(layer "In4.Cu")
		(net "P3E_CPU0_PE1_PCH_TXP<1>")
	)
	(segment
		(start 373.172736 -111.547656)
		(end 373.095012 -111.327438)
		(width 0.1143)
		(layer "In4.Cu")
		(net "P3E_CPU0_PE1_PCH_TXP<1>")
	)
	(segment
		(start 316.045088 -122.873262)
		(end 313.4614 -120.670574)
		(width 0.1143)
		(layer "F.Cu")
		(net "P3E_CPU0_PE1_PCH_TXP<15>")
	)
	(segment
		(start 310.902096 -118.487952)
		(end 313.4614 -120.670574)
		(width 0.1143)
		(layer "F.Cu")
		(net "P3E_CPU0_PE1_PCH_TXP<15>")
	)
	(segment
		(start 318.2239 -123.88596)
		(end 317.500254 -123.340114)
		(width 0.1143)
		(layer "F.Cu")
		(net "P3E_CPU0_PE1_PCH_TXP<15>")
	)
	(segment
		(start 306.9844 -110.246414)
		(end 310.902096 -118.487952)
		(width 0.1143)
		(layer "F.Cu")
		(net "P3E_CPU0_PE1_PCH_TXP<15>")
	)
	(segment
		(start 301.67834 -104.522016)
		(end 303.200054 -106.04373)
		(width 0.0889)
		(layer "F.Cu")
		(net "P3E_CPU0_PE1_PCH_TXP<15>")
	)
	(segment
		(start 300.953932 -102.133146)
		(end 300.927262 -102.232714)
		(width 0.0889)
		(layer "F.Cu")
		(net "P3E_CPU0_PE1_PCH_TXP<15>")
	)
	(segment
		(start 301.241206 -101.967538)
		(end 300.953932 -102.133146)
		(width 0.0889)
		(layer "F.Cu")
		(net "P3E_CPU0_PE1_PCH_TXP<15>")
	)
	(segment
		(start 300.928278 -103.874824)
		(end 301.367952 -104.314498)
		(width 0.0889)
		(layer "F.Cu")
		(net "P3E_CPU0_PE1_PCH_TXP<15>")
	)
	(segment
		(start 320.6115 -123.317)
		(end 320.6115 -123.7234)
		(width 0.1143)
		(layer "F.Cu")
		(net "P3E_CPU0_PE1_PCH_TXP<15>")
	)
	(segment
		(start 300.840902 -103.66375)
		(end 300.928278 -103.874824)
		(width 0.0889)
		(layer "F.Cu")
		(net "P3E_CPU0_PE1_PCH_TXP<15>")
	)
	(segment
		(start 306.724812 -109.700314)
		(end 306.890674 -109.759496)
		(width 0.1143)
		(layer "F.Cu")
		(net "P3E_CPU0_PE1_PCH_TXP<15>")
	)
	(segment
		(start 307.043328 -110.080552)
		(end 306.9844 -110.246414)
		(width 0.1143)
		(layer "F.Cu")
		(net "P3E_CPU0_PE1_PCH_TXP<15>")
	)
	(segment
		(start 303.73955 -106.54665)
		(end 306.572158 -109.379258)
		(width 0.1143)
		(layer "F.Cu")
		(net "P3E_CPU0_PE1_PCH_TXP<15>")
	)
	(segment
		(start 303.200054 -106.04373)
		(end 303.325784 -106.04373)
		(width 0.0889)
		(layer "F.Cu")
		(net "P3E_CPU0_PE1_PCH_TXP<15>")
	)
	(segment
		(start 300.840902 -102.96144)
		(end 300.840902 -103.66375)
		(width 0.0889)
		(layer "F.Cu")
		(net "P3E_CPU0_PE1_PCH_TXP<15>")
	)
	(segment
		(start 303.702974 -106.54665)
		(end 303.73955 -106.54665)
		(width 0.0889)
		(layer "F.Cu")
		(net "P3E_CPU0_PE1_PCH_TXP<15>")
	)
	(segment
		(start 317.500254 -123.340114)
		(end 316.045088 -122.873262)
		(width 0.1143)
		(layer "F.Cu")
		(net "P3E_CPU0_PE1_PCH_TXP<15>")
	)
	(segment
		(start 303.514506 -106.232452)
		(end 303.514506 -106.358182)
		(width 0.0889)
		(layer "F.Cu")
		(net "P3E_CPU0_PE1_PCH_TXP<15>")
	)
	(segment
		(start 306.572158 -109.379258)
		(end 306.724812 -109.700314)
		(width 0.1143)
		(layer "F.Cu")
		(net "P3E_CPU0_PE1_PCH_TXP<15>")
	)
	(segment
		(start 303.325784 -106.04373)
		(end 303.514506 -106.232452)
		(width 0.0889)
		(layer "F.Cu")
		(net "P3E_CPU0_PE1_PCH_TXP<15>")
	)
	(segment
		(start 303.514506 -106.358182)
		(end 303.702974 -106.54665)
		(width 0.0889)
		(layer "F.Cu")
		(net "P3E_CPU0_PE1_PCH_TXP<15>")
	)
	(segment
		(start 320.44894 -123.88596)
		(end 318.2239 -123.88596)
		(width 0.1143)
		(layer "F.Cu")
		(net "P3E_CPU0_PE1_PCH_TXP<15>")
	)
	(segment
		(start 320.6115 -123.7234)
		(end 320.44894 -123.88596)
		(width 0.1143)
		(layer "F.Cu")
		(net "P3E_CPU0_PE1_PCH_TXP<15>")
	)
	(segment
		(start 306.890674 -109.759496)
		(end 307.043328 -110.080552)
		(width 0.1143)
		(layer "F.Cu")
		(net "P3E_CPU0_PE1_PCH_TXP<15>")
	)
	(segment
		(start 301.367952 -104.314498)
		(end 301.67834 -104.522016)
		(width 0.0889)
		(layer "F.Cu")
		(net "P3E_CPU0_PE1_PCH_TXP<15>")
	)
	(via
		(at 313.4614 -120.670574)
		(size 0.508)
		(drill 0.254)
		(layers "F.Cu" "B.Cu")
		(net "P3E_CPU0_PE1_PCH_TXP<15>")
	)
	(arc
		(start 300.935136 -102.252526)
		(mid 300.97183 -102.509851)
		(end 300.894496 -102.757986)
		(width 0.0889)
		(layer "F.Cu")
		(net "P3E_CPU0_PE1_PCH_TXP<15>")
	)
	(arc
		(start 300.894496 -102.757986)
		(mid 300.854085 -102.856128)
		(end 300.840902 -102.96144)
		(width 0.0889)
		(layer "F.Cu")
		(net "P3E_CPU0_PE1_PCH_TXP<15>")
	)
	(arc
		(start 300.927262 -102.232714)
		(mid 300.931288 -102.242585)
		(end 300.935136 -102.252526)
		(width 0.0889)
		(layer "F.Cu")
		(net "P3E_CPU0_PE1_PCH_TXP<15>")
	)
	(segment
		(start 324.470776 -123.0757)
		(end 324.5485 -122.997976)
		(width 0.1143)
		(layer "F.Cu")
		(net "P3E_CPU0_PE1_PCH_TXP<14>")
	)
	(segment
		(start 303.531524 -104.939338)
		(end 303.531524 -104.813608)
		(width 0.0889)
		(layer "F.Cu")
		(net "P3E_CPU0_PE1_PCH_TXP<14>")
	)
	(segment
		(start 319.160906 -122.118628)
		(end 319.665858 -122.62358)
		(width 0.1143)
		(layer "F.Cu")
		(net "P3E_CPU0_PE1_PCH_TXP<14>")
	)
	(segment
		(start 317.31331 -122.118628)
		(end 319.160906 -122.118628)
		(width 0.1143)
		(layer "F.Cu")
		(net "P3E_CPU0_PE1_PCH_TXP<14>")
	)
	(segment
		(start 322.35394 -122.62358)
		(end 322.80606 -123.0757)
		(width 0.1143)
		(layer "F.Cu")
		(net "P3E_CPU0_PE1_PCH_TXP<14>")
	)
	(segment
		(start 304.537364 -105.945178)
		(end 304.537364 -105.819448)
		(width 0.0889)
		(layer "F.Cu")
		(net "P3E_CPU0_PE1_PCH_TXP<14>")
	)
	(segment
		(start 304.034444 -105.316528)
		(end 303.845722 -105.127806)
		(width 0.0889)
		(layer "F.Cu")
		(net "P3E_CPU0_PE1_PCH_TXP<14>")
	)
	(segment
		(start 301.725584 -101.329744)
		(end 301.812452 -101.306376)
		(width 0.0889)
		(layer "F.Cu")
		(net "P3E_CPU0_PE1_PCH_TXP<14>")
	)
	(segment
		(start 305.040284 -106.448098)
		(end 305.040284 -106.322368)
		(width 0.0889)
		(layer "F.Cu")
		(net "P3E_CPU0_PE1_PCH_TXP<14>")
	)
	(segment
		(start 324.5485 -122.997976)
		(end 324.5485 -122.555)
		(width 0.1143)
		(layer "F.Cu")
		(net "P3E_CPU0_PE1_PCH_TXP<14>")
	)
	(segment
		(start 304.034444 -105.442258)
		(end 304.034444 -105.316528)
		(width 0.0889)
		(layer "F.Cu")
		(net "P3E_CPU0_PE1_PCH_TXP<14>")
	)
	(segment
		(start 301.860458 -103.497634)
		(end 301.860458 -102.849426)
		(width 0.0889)
		(layer "F.Cu")
		(net "P3E_CPU0_PE1_PCH_TXP<14>")
	)
	(segment
		(start 304.725832 -106.133646)
		(end 304.537364 -105.945178)
		(width 0.0889)
		(layer "F.Cu")
		(net "P3E_CPU0_PE1_PCH_TXP<14>")
	)
	(segment
		(start 306.2986 -107.6706)
		(end 306.05603 -107.42803)
		(width 0.1143)
		(layer "F.Cu")
		(net "P3E_CPU0_PE1_PCH_TXP<14>")
	)
	(segment
		(start 308.02707 -109.39907)
		(end 307.349144 -108.721144)
		(width 0.1143)
		(layer "F.Cu")
		(net "P3E_CPU0_PE1_PCH_TXP<14>")
	)
	(segment
		(start 306.702714 -107.912916)
		(end 306.460144 -107.6706)
		(width 0.1143)
		(layer "F.Cu")
		(net "P3E_CPU0_PE1_PCH_TXP<14>")
	)
	(segment
		(start 306.702714 -108.074714)
		(end 306.702714 -107.912916)
		(width 0.1143)
		(layer "F.Cu")
		(net "P3E_CPU0_PE1_PCH_TXP<14>")
	)
	(segment
		(start 301.74819 -102.271322)
		(end 301.753016 -102.262686)
		(width 0.0889)
		(layer "F.Cu")
		(net "P3E_CPU0_PE1_PCH_TXP<14>")
	)
	(segment
		(start 305.040284 -106.322368)
		(end 304.851562 -106.133646)
		(width 0.0889)
		(layer "F.Cu")
		(net "P3E_CPU0_PE1_PCH_TXP<14>")
	)
	(segment
		(start 303.217072 -104.624886)
		(end 303.028604 -104.436418)
		(width 0.0889)
		(layer "F.Cu")
		(net "P3E_CPU0_PE1_PCH_TXP<14>")
	)
	(segment
		(start 304.851562 -106.133646)
		(end 304.725832 -106.133646)
		(width 0.0889)
		(layer "F.Cu")
		(net "P3E_CPU0_PE1_PCH_TXP<14>")
	)
	(segment
		(start 319.665858 -122.62358)
		(end 322.35394 -122.62358)
		(width 0.1143)
		(layer "F.Cu")
		(net "P3E_CPU0_PE1_PCH_TXP<14>")
	)
	(segment
		(start 303.845722 -105.127806)
		(end 303.719992 -105.127806)
		(width 0.0889)
		(layer "F.Cu")
		(net "P3E_CPU0_PE1_PCH_TXP<14>")
	)
	(segment
		(start 307.106828 -108.31703)
		(end 306.94503 -108.31703)
		(width 0.1143)
		(layer "F.Cu")
		(net "P3E_CPU0_PE1_PCH_TXP<14>")
	)
	(segment
		(start 307.349144 -108.5596)
		(end 307.106828 -108.31703)
		(width 0.1143)
		(layer "F.Cu")
		(net "P3E_CPU0_PE1_PCH_TXP<14>")
	)
	(segment
		(start 304.537364 -105.819448)
		(end 304.348642 -105.630726)
		(width 0.0889)
		(layer "F.Cu")
		(net "P3E_CPU0_PE1_PCH_TXP<14>")
	)
	(segment
		(start 312.320432 -118.354348)
		(end 308.02707 -109.39907)
		(width 0.1143)
		(layer "F.Cu")
		(net "P3E_CPU0_PE1_PCH_TXP<14>")
	)
	(segment
		(start 301.812452 -101.306376)
		(end 302.099726 -101.471984)
		(width 0.0889)
		(layer "F.Cu")
		(net "P3E_CPU0_PE1_PCH_TXP<14>")
	)
	(segment
		(start 302.646842 -104.436418)
		(end 301.968154 -103.75773)
		(width 0.0889)
		(layer "F.Cu")
		(net "P3E_CPU0_PE1_PCH_TXP<14>")
	)
	(segment
		(start 303.028604 -104.436418)
		(end 302.646842 -104.436418)
		(width 0.0889)
		(layer "F.Cu")
		(net "P3E_CPU0_PE1_PCH_TXP<14>")
	)
	(segment
		(start 304.348642 -105.630726)
		(end 304.222912 -105.630726)
		(width 0.0889)
		(layer "F.Cu")
		(net "P3E_CPU0_PE1_PCH_TXP<14>")
	)
	(segment
		(start 312.963814 -118.839488)
		(end 317.31331 -122.118628)
		(width 0.1143)
		(layer "F.Cu")
		(net "P3E_CPU0_PE1_PCH_TXP<14>")
	)
	(segment
		(start 301.968154 -103.75773)
		(end 301.860458 -103.497634)
		(width 0.0889)
		(layer "F.Cu")
		(net "P3E_CPU0_PE1_PCH_TXP<14>")
	)
	(segment
		(start 303.531524 -104.813608)
		(end 303.342802 -104.624886)
		(width 0.0889)
		(layer "F.Cu")
		(net "P3E_CPU0_PE1_PCH_TXP<14>")
	)
	(segment
		(start 307.349144 -108.721144)
		(end 307.349144 -108.5596)
		(width 0.1143)
		(layer "F.Cu")
		(net "P3E_CPU0_PE1_PCH_TXP<14>")
	)
	(segment
		(start 301.860458 -102.849426)
		(end 301.753016 -102.662736)
		(width 0.0889)
		(layer "F.Cu")
		(net "P3E_CPU0_PE1_PCH_TXP<14>")
	)
	(segment
		(start 301.753016 -102.262686)
		(end 301.759366 -102.252018)
		(width 0.0889)
		(layer "F.Cu")
		(net "P3E_CPU0_PE1_PCH_TXP<14>")
	)
	(segment
		(start 303.719992 -105.127806)
		(end 303.531524 -104.939338)
		(width 0.0889)
		(layer "F.Cu")
		(net "P3E_CPU0_PE1_PCH_TXP<14>")
	)
	(segment
		(start 322.80606 -123.0757)
		(end 324.470776 -123.0757)
		(width 0.1143)
		(layer "F.Cu")
		(net "P3E_CPU0_PE1_PCH_TXP<14>")
	)
	(segment
		(start 301.753016 -102.662736)
		(end 301.753016 -102.662482)
		(width 0.0889)
		(layer "F.Cu")
		(net "P3E_CPU0_PE1_PCH_TXP<14>")
	)
	(segment
		(start 306.460144 -107.6706)
		(end 306.2986 -107.6706)
		(width 0.1143)
		(layer "F.Cu")
		(net "P3E_CPU0_PE1_PCH_TXP<14>")
	)
	(segment
		(start 306.040536 -107.412536)
		(end 306.004722 -107.412536)
		(width 0.0889)
		(layer "F.Cu")
		(net "P3E_CPU0_PE1_PCH_TXP<14>")
	)
	(segment
		(start 304.222912 -105.630726)
		(end 304.034444 -105.442258)
		(width 0.0889)
		(layer "F.Cu")
		(net "P3E_CPU0_PE1_PCH_TXP<14>")
	)
	(segment
		(start 306.004722 -107.412536)
		(end 305.040284 -106.448098)
		(width 0.0889)
		(layer "F.Cu")
		(net "P3E_CPU0_PE1_PCH_TXP<14>")
	)
	(segment
		(start 306.94503 -108.31703)
		(end 306.702714 -108.074714)
		(width 0.1143)
		(layer "F.Cu")
		(net "P3E_CPU0_PE1_PCH_TXP<14>")
	)
	(segment
		(start 303.342802 -104.624886)
		(end 303.217072 -104.624886)
		(width 0.0889)
		(layer "F.Cu")
		(net "P3E_CPU0_PE1_PCH_TXP<14>")
	)
	(segment
		(start 306.05603 -107.42803)
		(end 306.040536 -107.412536)
		(width 0.0889)
		(layer "F.Cu")
		(net "P3E_CPU0_PE1_PCH_TXP<14>")
	)
	(segment
		(start 312.963814 -118.839488)
		(end 312.320432 -118.354348)
		(width 0.1143)
		(layer "F.Cu")
		(net "P3E_CPU0_PE1_PCH_TXP<14>")
	)
	(via
		(at 312.963814 -118.839488)
		(size 0.508)
		(drill 0.254)
		(layers "F.Cu" "B.Cu")
		(net "P3E_CPU0_PE1_PCH_TXP<14>")
	)
	(arc
		(start 301.759366 -102.252018)
		(mid 301.832164 -101.961255)
		(end 301.753016 -101.672136)
		(width 0.0889)
		(layer "F.Cu")
		(net "P3E_CPU0_PE1_PCH_TXP<14>")
	)
	(arc
		(start 301.753016 -101.672136)
		(mid 301.700675 -101.504027)
		(end 301.725584 -101.329744)
		(width 0.0889)
		(layer "F.Cu")
		(net "P3E_CPU0_PE1_PCH_TXP<14>")
	)
	(arc
		(start 301.753016 -102.662482)
		(mid 301.699548 -102.467531)
		(end 301.74819 -102.271322)
		(width 0.0889)
		(layer "F.Cu")
		(net "P3E_CPU0_PE1_PCH_TXP<14>")
	)
	(segment
		(start 324.5485 -120.838976)
		(end 324.470776 -120.9167)
		(width 0.1143)
		(layer "F.Cu")
		(net "P3E_CPU0_PE1_PCH_TXP<13>")
	)
	(segment
		(start 305.437794 -104.995218)
		(end 305.40198 -104.995218)
		(width 0.0889)
		(layer "F.Cu")
		(net "P3E_CPU0_PE1_PCH_TXP<13>")
	)
	(segment
		(start 307.833522 -107.390946)
		(end 307.833522 -107.229148)
		(width 0.1143)
		(layer "F.Cu")
		(net "P3E_CPU0_PE1_PCH_TXP<13>")
	)
	(segment
		(start 302.671734 -102.239572)
		(end 302.670464 -102.238302)
		(width 0.0889)
		(layer "F.Cu")
		(net "P3E_CPU0_PE1_PCH_TXP<13>")
	)
	(segment
		(start 303.038256 -103.406956)
		(end 302.87722 -103.406956)
		(width 0.0889)
		(layer "F.Cu")
		(net "P3E_CPU0_PE1_PCH_TXP<13>")
	)
	(segment
		(start 319.564004 -121.145808)
		(end 318.254634 -121.145808)
		(width 0.1143)
		(layer "F.Cu")
		(net "P3E_CPU0_PE1_PCH_TXP<13>")
	)
	(segment
		(start 302.611536 -100.776786)
		(end 302.617886 -100.766118)
		(width 0.0889)
		(layer "F.Cu")
		(net "P3E_CPU0_PE1_PCH_TXP<13>")
	)
	(segment
		(start 324.470776 -120.9167)
		(end 322.695824 -120.9167)
		(width 0.1143)
		(layer "F.Cu")
		(net "P3E_CPU0_PE1_PCH_TXP<13>")
	)
	(segment
		(start 319.845436 -121.42724)
		(end 319.564004 -121.145808)
		(width 0.1143)
		(layer "F.Cu")
		(net "P3E_CPU0_PE1_PCH_TXP<13>")
	)
	(segment
		(start 312.7883 -117.02542)
		(end 308.545484 -108.102908)
		(width 0.1143)
		(layer "F.Cu")
		(net "P3E_CPU0_PE1_PCH_TXP<13>")
	)
	(segment
		(start 305.453288 -105.010712)
		(end 305.437794 -104.995218)
		(width 0.0889)
		(layer "F.Cu")
		(net "P3E_CPU0_PE1_PCH_TXP<13>")
	)
	(segment
		(start 305.40198 -104.995218)
		(end 304.969926 -104.563164)
		(width 0.0889)
		(layer "F.Cu")
		(net "P3E_CPU0_PE1_PCH_TXP<13>")
	)
	(segment
		(start 302.579278 -102.918006)
		(end 302.73371 -102.574344)
		(width 0.0889)
		(layer "F.Cu")
		(net "P3E_CPU0_PE1_PCH_TXP<13>")
	)
	(segment
		(start 312.788554 -117.026182)
		(end 312.7883 -117.02542)
		(width 0.1143)
		(layer "F.Cu")
		(net "P3E_CPU0_PE1_PCH_TXP<13>")
	)
	(segment
		(start 322.695824 -120.9167)
		(end 322.185284 -121.42724)
		(width 0.1143)
		(layer "F.Cu")
		(net "P3E_CPU0_PE1_PCH_TXP<13>")
	)
	(segment
		(start 303.646078 -104.014778)
		(end 303.038256 -103.406956)
		(width 0.0889)
		(layer "F.Cu")
		(net "P3E_CPU0_PE1_PCH_TXP<13>")
	)
	(segment
		(start 316.037468 -119.474742)
		(end 312.789062 -117.02669)
		(width 0.1143)
		(layer "F.Cu")
		(net "P3E_CPU0_PE1_PCH_TXP<13>")
	)
	(segment
		(start 302.87722 -103.406956)
		(end 302.579278 -103.109014)
		(width 0.0889)
		(layer "F.Cu")
		(net "P3E_CPU0_PE1_PCH_TXP<13>")
	)
	(segment
		(start 324.5485 -120.396)
		(end 324.5485 -120.838976)
		(width 0.1143)
		(layer "F.Cu")
		(net "P3E_CPU0_PE1_PCH_TXP<13>")
	)
	(segment
		(start 322.185284 -121.42724)
		(end 319.845436 -121.42724)
		(width 0.1143)
		(layer "F.Cu")
		(net "P3E_CPU0_PE1_PCH_TXP<13>")
	)
	(segment
		(start 304.312828 -104.290876)
		(end 303.646078 -104.014778)
		(width 0.0889)
		(layer "F.Cu")
		(net "P3E_CPU0_PE1_PCH_TXP<13>")
	)
	(segment
		(start 316.037468 -119.474996)
		(end 316.037468 -119.474742)
		(width 0.1143)
		(layer "F.Cu")
		(net "P3E_CPU0_PE1_PCH_TXP<13>")
	)
	(segment
		(start 302.644302 -100.251768)
		(end 302.670972 -100.151946)
		(width 0.0889)
		(layer "F.Cu")
		(net "P3E_CPU0_PE1_PCH_TXP<13>")
	)
	(segment
		(start 307.590952 -106.986832)
		(end 307.429408 -106.986832)
		(width 0.1143)
		(layer "F.Cu")
		(net "P3E_CPU0_PE1_PCH_TXP<13>")
	)
	(segment
		(start 304.428906 -104.24287)
		(end 304.312828 -104.290876)
		(width 0.0889)
		(layer "F.Cu")
		(net "P3E_CPU0_PE1_PCH_TXP<13>")
	)
	(segment
		(start 304.723546 -104.461056)
		(end 304.67554 -104.344978)
		(width 0.0889)
		(layer "F.Cu")
		(net "P3E_CPU0_PE1_PCH_TXP<13>")
	)
	(segment
		(start 302.670718 -102.238302)
		(end 302.672242 -102.236778)
		(width 0.0889)
		(layer "F.Cu")
		(net "P3E_CPU0_PE1_PCH_TXP<13>")
	)
	(segment
		(start 307.833522 -107.229148)
		(end 307.590952 -106.986832)
		(width 0.1143)
		(layer "F.Cu")
		(net "P3E_CPU0_PE1_PCH_TXP<13>")
	)
	(segment
		(start 312.789062 -117.02669)
		(end 312.788554 -117.026182)
		(width 0.1143)
		(layer "F.Cu")
		(net "P3E_CPU0_PE1_PCH_TXP<13>")
	)
	(segment
		(start 302.579278 -103.109014)
		(end 302.579278 -102.918006)
		(width 0.0889)
		(layer "F.Cu")
		(net "P3E_CPU0_PE1_PCH_TXP<13>")
	)
	(segment
		(start 304.969926 -104.563164)
		(end 304.723546 -104.461056)
		(width 0.0889)
		(layer "F.Cu")
		(net "P3E_CPU0_PE1_PCH_TXP<13>")
	)
	(segment
		(start 302.670972 -100.151946)
		(end 302.958246 -99.986338)
		(width 0.0889)
		(layer "F.Cu")
		(net "P3E_CPU0_PE1_PCH_TXP<13>")
	)
	(segment
		(start 304.67554 -104.344978)
		(end 304.428906 -104.24287)
		(width 0.0889)
		(layer "F.Cu")
		(net "P3E_CPU0_PE1_PCH_TXP<13>")
	)
	(segment
		(start 307.429408 -106.986832)
		(end 305.453288 -105.010712)
		(width 0.1143)
		(layer "F.Cu")
		(net "P3E_CPU0_PE1_PCH_TXP<13>")
	)
	(segment
		(start 318.254634 -121.145808)
		(end 316.037722 -119.474996)
		(width 0.1143)
		(layer "F.Cu")
		(net "P3E_CPU0_PE1_PCH_TXP<13>")
	)
	(segment
		(start 316.037722 -119.474996)
		(end 316.037468 -119.474996)
		(width 0.1143)
		(layer "F.Cu")
		(net "P3E_CPU0_PE1_PCH_TXP<13>")
	)
	(segment
		(start 308.545484 -108.102908)
		(end 307.833522 -107.390946)
		(width 0.1143)
		(layer "F.Cu")
		(net "P3E_CPU0_PE1_PCH_TXP<13>")
	)
	(segment
		(start 302.670464 -102.238302)
		(end 302.670718 -102.238302)
		(width 0.0889)
		(layer "F.Cu")
		(net "P3E_CPU0_PE1_PCH_TXP<13>")
	)
	(via
		(at 316.037722 -119.474996)
		(size 0.508)
		(drill 0.254)
		(layers "F.Cu" "B.Cu")
		(net "P3E_CPU0_PE1_PCH_TXP<13>")
	)
	(arc
		(start 302.617886 -100.766118)
		(mid 302.68946 -100.522494)
		(end 302.652176 -100.271326)
		(width 0.0889)
		(layer "F.Cu")
		(net "P3E_CPU0_PE1_PCH_TXP<13>")
	)
	(arc
		(start 302.652176 -100.271326)
		(mid 302.648327 -100.261512)
		(end 302.644302 -100.251768)
		(width 0.0889)
		(layer "F.Cu")
		(net "P3E_CPU0_PE1_PCH_TXP<13>")
	)
	(arc
		(start 302.611536 -101.176582)
		(mid 302.558037 -100.976684)
		(end 302.611536 -100.776786)
		(width 0.0889)
		(layer "F.Cu")
		(net "P3E_CPU0_PE1_PCH_TXP<13>")
	)
	(arc
		(start 302.611536 -101.767386)
		(mid 302.690667 -101.471984)
		(end 302.611536 -101.176582)
		(width 0.0889)
		(layer "F.Cu")
		(net "P3E_CPU0_PE1_PCH_TXP<13>")
	)
	(arc
		(start 302.655986 -102.219506)
		(mid 302.56105 -102.000593)
		(end 302.611536 -101.767386)
		(width 0.0889)
		(layer "F.Cu")
		(net "P3E_CPU0_PE1_PCH_TXP<13>")
	)
	(arc
		(start 302.73371 -102.574344)
		(mid 302.754841 -102.397318)
		(end 302.671734 -102.239572)
		(width 0.0889)
		(layer "F.Cu")
		(net "P3E_CPU0_PE1_PCH_TXP<13>")
	)
	(arc
		(start 302.672242 -102.236778)
		(mid 302.663984 -102.228265)
		(end 302.655986 -102.219506)
		(width 0.0889)
		(layer "F.Cu")
		(net "P3E_CPU0_PE1_PCH_TXP<13>")
	)
	(segment
		(start 318.614806 -119.44858)
		(end 313.45124 -115.989354)
		(width 0.1143)
		(layer "F.Cu")
		(net "P3E_CPU0_PE1_PCH_TXP<12>")
	)
	(segment
		(start 303.701958 -101.89718)
		(end 303.4411 -101.636322)
		(width 0.0889)
		(layer "F.Cu")
		(net "P3E_CPU0_PE1_PCH_TXP<12>")
	)
	(segment
		(start 307.247036 -104.763062)
		(end 307.004466 -104.520492)
		(width 0.1143)
		(layer "F.Cu")
		(net "P3E_CPU0_PE1_PCH_TXP<12>")
	)
	(segment
		(start 304.428906 -102.341426)
		(end 304.42916 -102.341426)
		(width 0.0889)
		(layer "F.Cu")
		(net "P3E_CPU0_PE1_PCH_TXP<12>")
	)
	(segment
		(start 307.489352 -105.167176)
		(end 307.247036 -104.924606)
		(width 0.1143)
		(layer "F.Cu")
		(net "P3E_CPU0_PE1_PCH_TXP<12>")
	)
	(segment
		(start 302.56226 -99.122992)
		(end 302.099726 -98.500184)
		(width 0.0889)
		(layer "F.Cu")
		(net "P3E_CPU0_PE1_PCH_TXP<12>")
	)
	(segment
		(start 319.147952 -119.805704)
		(end 318.614806 -119.44858)
		(width 0.1143)
		(layer "F.Cu")
		(net "P3E_CPU0_PE1_PCH_TXP<12>")
	)
	(segment
		(start 308.91099 -106.588814)
		(end 307.893466 -105.57129)
		(width 0.1143)
		(layer "F.Cu")
		(net "P3E_CPU0_PE1_PCH_TXP<12>")
	)
	(segment
		(start 306.426362 -104.103932)
		(end 306.410868 -104.088438)
		(width 0.0889)
		(layer "F.Cu")
		(net "P3E_CPU0_PE1_PCH_TXP<12>")
	)
	(segment
		(start 303.4411 -101.636322)
		(end 303.4411 -101.32187)
		(width 0.0889)
		(layer "F.Cu")
		(net "P3E_CPU0_PE1_PCH_TXP<12>")
	)
	(segment
		(start 307.65115 -105.167176)
		(end 307.489352 -105.167176)
		(width 0.1143)
		(layer "F.Cu")
		(net "P3E_CPU0_PE1_PCH_TXP<12>")
	)
	(segment
		(start 321.16522 -119.65178)
		(end 321.011296 -119.805704)
		(width 0.1143)
		(layer "F.Cu")
		(net "P3E_CPU0_PE1_PCH_TXP<12>")
	)
	(segment
		(start 306.410868 -104.088438)
		(end 306.375308 -104.088438)
		(width 0.0889)
		(layer "F.Cu")
		(net "P3E_CPU0_PE1_PCH_TXP<12>")
	)
	(segment
		(start 307.893466 -105.57129)
		(end 307.893466 -105.409492)
		(width 0.1143)
		(layer "F.Cu")
		(net "P3E_CPU0_PE1_PCH_TXP<12>")
	)
	(segment
		(start 304.31613 -102.145592)
		(end 304.067464 -101.89718)
		(width 0.0889)
		(layer "F.Cu")
		(net "P3E_CPU0_PE1_PCH_TXP<12>")
	)
	(segment
		(start 304.067464 -101.89718)
		(end 303.701958 -101.89718)
		(width 0.0889)
		(layer "F.Cu")
		(net "P3E_CPU0_PE1_PCH_TXP<12>")
	)
	(segment
		(start 307.004466 -104.520492)
		(end 306.842922 -104.520492)
		(width 0.1143)
		(layer "F.Cu")
		(net "P3E_CPU0_PE1_PCH_TXP<12>")
	)
	(segment
		(start 306.375308 -104.088438)
		(end 304.715418 -102.428802)
		(width 0.0889)
		(layer "F.Cu")
		(net "P3E_CPU0_PE1_PCH_TXP<12>")
	)
	(segment
		(start 304.42916 -102.341934)
		(end 304.428906 -102.341426)
		(width 0.0889)
		(layer "F.Cu")
		(net "P3E_CPU0_PE1_PCH_TXP<12>")
	)
	(segment
		(start 307.247036 -104.924606)
		(end 307.247036 -104.763062)
		(width 0.1143)
		(layer "F.Cu")
		(net "P3E_CPU0_PE1_PCH_TXP<12>")
	)
	(segment
		(start 306.842922 -104.520492)
		(end 306.426362 -104.103932)
		(width 0.1143)
		(layer "F.Cu")
		(net "P3E_CPU0_PE1_PCH_TXP<12>")
	)
	(segment
		(start 303.4411 -101.32187)
		(end 303.470056 -101.272086)
		(width 0.0889)
		(layer "F.Cu")
		(net "P3E_CPU0_PE1_PCH_TXP<12>")
	)
	(segment
		(start 304.42916 -102.341426)
		(end 304.31613 -102.145592)
		(width 0.0889)
		(layer "F.Cu")
		(net "P3E_CPU0_PE1_PCH_TXP<12>")
	)
	(segment
		(start 321.011296 -119.805704)
		(end 319.147952 -119.805704)
		(width 0.1143)
		(layer "F.Cu")
		(net "P3E_CPU0_PE1_PCH_TXP<12>")
	)
	(segment
		(start 321.16522 -119.26316)
		(end 321.16522 -119.65178)
		(width 0.1143)
		(layer "F.Cu")
		(net "P3E_CPU0_PE1_PCH_TXP<12>")
	)
	(segment
		(start 313.45124 -115.989354)
		(end 308.91099 -106.588814)
		(width 0.1143)
		(layer "F.Cu")
		(net "P3E_CPU0_PE1_PCH_TXP<12>")
	)
	(segment
		(start 304.715418 -102.428802)
		(end 304.599594 -102.40899)
		(width 0.0889)
		(layer "F.Cu")
		(net "P3E_CPU0_PE1_PCH_TXP<12>")
	)
	(segment
		(start 302.979836 -99.395788)
		(end 302.94707 -99.395788)
		(width 0.0889)
		(layer "F.Cu")
		(net "P3E_CPU0_PE1_PCH_TXP<12>")
	)
	(segment
		(start 303.476406 -100.692204)
		(end 303.470056 -100.681536)
		(width 0.0889)
		(layer "F.Cu")
		(net "P3E_CPU0_PE1_PCH_TXP<12>")
	)
	(segment
		(start 307.893466 -105.409492)
		(end 307.65115 -105.167176)
		(width 0.1143)
		(layer "F.Cu")
		(net "P3E_CPU0_PE1_PCH_TXP<12>")
	)
	(via
		(at 318.614806 -119.44858)
		(size 0.508)
		(drill 0.254)
		(layers "F.Cu" "B.Cu")
		(net "P3E_CPU0_PE1_PCH_TXP<12>")
	)
	(arc
		(start 303.470056 -100.681536)
		(mid 303.416557 -100.481638)
		(end 303.470056 -100.28174)
		(width 0.0889)
		(layer "F.Cu")
		(net "P3E_CPU0_PE1_PCH_TXP<12>")
	)
	(arc
		(start 303.470056 -101.272086)
		(mid 303.549278 -100.982968)
		(end 303.476406 -100.692204)
		(width 0.0889)
		(layer "F.Cu")
		(net "P3E_CPU0_PE1_PCH_TXP<12>")
	)
	(arc
		(start 304.599594 -102.40899)
		(mid 304.51092 -102.384252)
		(end 304.42916 -102.341934)
		(width 0.0889)
		(layer "F.Cu")
		(net "P3E_CPU0_PE1_PCH_TXP<12>")
	)
	(arc
		(start 302.94707 -99.395788)
		(mid 302.75322 -99.339438)
		(end 302.611536 -99.195636)
		(width 0.0889)
		(layer "F.Cu")
		(net "P3E_CPU0_PE1_PCH_TXP<12>")
	)
	(arc
		(start 302.611536 -99.195636)
		(mid 302.588254 -99.158394)
		(end 302.56226 -99.122992)
		(width 0.0889)
		(layer "F.Cu")
		(net "P3E_CPU0_PE1_PCH_TXP<12>")
	)
	(arc
		(start 303.470056 -100.28174)
		(mid 303.47531 -99.700232)
		(end 302.979836 -99.395788)
		(width 0.0889)
		(layer "F.Cu")
		(net "P3E_CPU0_PE1_PCH_TXP<12>")
	)
	(segment
		(start 305.582066 -101.100382)
		(end 305.692048 -101.100382)
		(width 0.0889)
		(layer "F.Cu")
		(net "P3E_CPU0_PE1_PCH_TXP<11>")
	)
	(segment
		(start 307.188108 -103.266494)
		(end 307.37683 -103.455216)
		(width 0.0889)
		(layer "F.Cu")
		(net "P3E_CPU0_PE1_PCH_TXP<11>")
	)
	(segment
		(start 306.87391 -102.952296)
		(end 306.99964 -102.952296)
		(width 0.0889)
		(layer "F.Cu")
		(net "P3E_CPU0_PE1_PCH_TXP<11>")
	)
	(segment
		(start 307.691028 -103.769414)
		(end 307.87975 -103.958136)
		(width 0.0889)
		(layer "F.Cu")
		(net "P3E_CPU0_PE1_PCH_TXP<11>")
	)
	(segment
		(start 308.37251 -104.361234)
		(end 308.823614 -104.812338)
		(width 0.1143)
		(layer "F.Cu")
		(net "P3E_CPU0_PE1_PCH_TXP<11>")
	)
	(segment
		(start 315.472064 -115.050062)
		(end 317.480188 -116.388642)
		(width 0.1143)
		(layer "F.Cu")
		(net "P3E_CPU0_PE1_PCH_TXP<11>")
	)
	(segment
		(start 307.188108 -103.140764)
		(end 307.188108 -103.266494)
		(width 0.0889)
		(layer "F.Cu")
		(net "P3E_CPU0_PE1_PCH_TXP<11>")
	)
	(segment
		(start 306.685188 -102.763574)
		(end 306.87391 -102.952296)
		(width 0.0889)
		(layer "F.Cu")
		(net "P3E_CPU0_PE1_PCH_TXP<11>")
	)
	(segment
		(start 317.480188 -116.388642)
		(end 317.833248 -116.741702)
		(width 0.1143)
		(layer "F.Cu")
		(net "P3E_CPU0_PE1_PCH_TXP<11>")
	)
	(segment
		(start 306.99964 -102.952296)
		(end 307.188108 -103.140764)
		(width 0.0889)
		(layer "F.Cu")
		(net "P3E_CPU0_PE1_PCH_TXP<11>")
	)
	(segment
		(start 320.2305 -118.4275)
		(end 319.519046 -118.4275)
		(width 0.1143)
		(layer "F.Cu")
		(net "P3E_CPU0_PE1_PCH_TXP<11>")
	)
	(segment
		(start 308.00548 -103.958136)
		(end 308.357016 -104.309672)
		(width 0.0889)
		(layer "F.Cu")
		(net "P3E_CPU0_PE1_PCH_TXP<11>")
	)
	(segment
		(start 306.49672 -102.449376)
		(end 306.685188 -102.637844)
		(width 0.0889)
		(layer "F.Cu")
		(net "P3E_CPU0_PE1_PCH_TXP<11>")
	)
	(segment
		(start 303.816766 -99.490784)
		(end 303.529492 -99.325176)
		(width 0.0889)
		(layer "F.Cu")
		(net "P3E_CPU0_PE1_PCH_TXP<11>")
	)
	(segment
		(start 323.0245 -118.415816)
		(end 323.0245 -118.081552)
		(width 0.1143)
		(layer "F.Cu")
		(net "P3E_CPU0_PE1_PCH_TXP<11>")
	)
	(segment
		(start 320.699384 -117.958616)
		(end 320.2305 -118.4275)
		(width 0.1143)
		(layer "F.Cu")
		(net "P3E_CPU0_PE1_PCH_TXP<11>")
	)
	(segment
		(start 305.692048 -101.100382)
		(end 305.9938 -101.402134)
		(width 0.0889)
		(layer "F.Cu")
		(net "P3E_CPU0_PE1_PCH_TXP<11>")
	)
	(segment
		(start 323.0245 -118.081552)
		(end 322.901564 -117.958616)
		(width 0.1143)
		(layer "F.Cu")
		(net "P3E_CPU0_PE1_PCH_TXP<11>")
	)
	(segment
		(start 322.901564 -117.958616)
		(end 320.699384 -117.958616)
		(width 0.1143)
		(layer "F.Cu")
		(net "P3E_CPU0_PE1_PCH_TXP<11>")
	)
	(segment
		(start 306.37099 -102.449376)
		(end 306.49672 -102.449376)
		(width 0.0889)
		(layer "F.Cu")
		(net "P3E_CPU0_PE1_PCH_TXP<11>")
	)
	(segment
		(start 308.357016 -104.34574)
		(end 308.37251 -104.361234)
		(width 0.0889)
		(layer "F.Cu")
		(net "P3E_CPU0_PE1_PCH_TXP<11>")
	)
	(segment
		(start 307.691028 -103.643684)
		(end 307.691028 -103.769414)
		(width 0.0889)
		(layer "F.Cu")
		(net "P3E_CPU0_PE1_PCH_TXP<11>")
	)
	(segment
		(start 305.9938 -101.402134)
		(end 305.9938 -101.946456)
		(width 0.0889)
		(layer "F.Cu")
		(net "P3E_CPU0_PE1_PCH_TXP<11>")
	)
	(segment
		(start 319.519046 -118.4275)
		(end 317.833248 -116.741702)
		(width 0.1143)
		(layer "F.Cu")
		(net "P3E_CPU0_PE1_PCH_TXP<11>")
	)
	(segment
		(start 307.87975 -103.958136)
		(end 308.00548 -103.958136)
		(width 0.0889)
		(layer "F.Cu")
		(net "P3E_CPU0_PE1_PCH_TXP<11>")
	)
	(segment
		(start 313.363356 -113.644426)
		(end 315.472064 -115.050062)
		(width 0.1143)
		(layer "F.Cu")
		(net "P3E_CPU0_PE1_PCH_TXP<11>")
	)
	(segment
		(start 303.529492 -99.325176)
		(end 303.506378 -99.238562)
		(width 0.0889)
		(layer "F.Cu")
		(net "P3E_CPU0_PE1_PCH_TXP<11>")
	)
	(segment
		(start 305.9938 -101.946456)
		(end 306.182268 -102.134924)
		(width 0.0889)
		(layer "F.Cu")
		(net "P3E_CPU0_PE1_PCH_TXP<11>")
	)
	(segment
		(start 307.37683 -103.455216)
		(end 307.50256 -103.455216)
		(width 0.0889)
		(layer "F.Cu")
		(net "P3E_CPU0_PE1_PCH_TXP<11>")
	)
	(segment
		(start 308.823614 -104.812338)
		(end 308.82336 -104.812338)
		(width 0.1143)
		(layer "F.Cu")
		(net "P3E_CPU0_PE1_PCH_TXP<11>")
	)
	(segment
		(start 306.182268 -102.260654)
		(end 306.37099 -102.449376)
		(width 0.0889)
		(layer "F.Cu")
		(net "P3E_CPU0_PE1_PCH_TXP<11>")
	)
	(segment
		(start 308.357016 -104.309672)
		(end 308.357016 -104.34574)
		(width 0.0889)
		(layer "F.Cu")
		(net "P3E_CPU0_PE1_PCH_TXP<11>")
	)
	(segment
		(start 306.685188 -102.637844)
		(end 306.685188 -102.763574)
		(width 0.0889)
		(layer "F.Cu")
		(net "P3E_CPU0_PE1_PCH_TXP<11>")
	)
	(segment
		(start 307.50256 -103.455216)
		(end 307.691028 -103.643684)
		(width 0.0889)
		(layer "F.Cu")
		(net "P3E_CPU0_PE1_PCH_TXP<11>")
	)
	(segment
		(start 308.82336 -104.812338)
		(end 313.363356 -113.644426)
		(width 0.1143)
		(layer "F.Cu")
		(net "P3E_CPU0_PE1_PCH_TXP<11>")
	)
	(segment
		(start 304.653696 -100.576888)
		(end 304.69332 -100.576888)
		(width 0.0889)
		(layer "F.Cu")
		(net "P3E_CPU0_PE1_PCH_TXP<11>")
	)
	(segment
		(start 306.182268 -102.134924)
		(end 306.182268 -102.260654)
		(width 0.0889)
		(layer "F.Cu")
		(net "P3E_CPU0_PE1_PCH_TXP<11>")
	)
	(via
		(at 317.833248 -116.741702)
		(size 0.508)
		(drill 0.254)
		(layers "F.Cu" "B.Cu")
		(net "P3E_CPU0_PE1_PCH_TXP<11>")
	)
	(arc
		(start 304.69332 -100.576888)
		(mid 304.883249 -100.634758)
		(end 305.021996 -100.776786)
		(width 0.0889)
		(layer "F.Cu")
		(net "P3E_CPU0_PE1_PCH_TXP<11>")
	)
	(arc
		(start 303.828958 -99.090734)
		(mid 304.1666 -99.29591)
		(end 304.163476 -99.690936)
		(width 0.0889)
		(layer "F.Cu")
		(net "P3E_CPU0_PE1_PCH_TXP<11>")
	)
	(arc
		(start 303.804828 -99.090734)
		(mid 303.816893 -99.090548)
		(end 303.828958 -99.090734)
		(width 0.0889)
		(layer "F.Cu")
		(net "P3E_CPU0_PE1_PCH_TXP<11>")
	)
	(arc
		(start 305.021996 -100.776786)
		(mid 305.258676 -101.013594)
		(end 305.582066 -101.100382)
		(width 0.0889)
		(layer "F.Cu")
		(net "P3E_CPU0_PE1_PCH_TXP<11>")
	)
	(arc
		(start 303.506378 -99.238562)
		(mid 303.639505 -99.132171)
		(end 303.804828 -99.090734)
		(width 0.0889)
		(layer "F.Cu")
		(net "P3E_CPU0_PE1_PCH_TXP<11>")
	)
	(arc
		(start 304.163476 -99.690936)
		(mid 304.158222 -100.272444)
		(end 304.653696 -100.576888)
		(width 0.0889)
		(layer "F.Cu")
		(net "P3E_CPU0_PE1_PCH_TXP<11>")
	)
	(segment
		(start 304.675286 -99.327462)
		(end 304.747422 -99.399598)
		(width 0.0889)
		(layer "F.Cu")
		(net "P3E_CPU0_PE1_PCH_TXP<10>")
	)
	(segment
		(start 316.725808 -111.872522)
		(end 316.757812 -112.031018)
		(width 0.1143)
		(layer "F.Cu")
		(net "P3E_CPU0_PE1_PCH_TXP<10>")
	)
	(segment
		(start 337.241896 -120.553734)
		(end 337.429602 -120.366028)
		(width 0.1143)
		(layer "F.Cu")
		(net "P3E_CPU0_PE1_PCH_TXP<10>")
	)
	(segment
		(start 327.335642 -117.710204)
		(end 329.698858 -120.07342)
		(width 0.1143)
		(layer "F.Cu")
		(net "P3E_CPU0_PE1_PCH_TXP<10>")
	)
	(segment
		(start 337.429602 -120.366028)
		(end 337.429602 -120.038368)
		(width 0.1143)
		(layer "F.Cu")
		(net "P3E_CPU0_PE1_PCH_TXP<10>")
	)
	(segment
		(start 305.915822 -100.04679)
		(end 305.91633 -100.04679)
		(width 0.0889)
		(layer "F.Cu")
		(net "P3E_CPU0_PE1_PCH_TXP<10>")
	)
	(segment
		(start 318.394588 -113.12017)
		(end 321.64147 -115.281202)
		(width 0.1143)
		(layer "F.Cu")
		(net "P3E_CPU0_PE1_PCH_TXP<10>")
	)
	(segment
		(start 331.397102 -120.07342)
		(end 331.877416 -120.553734)
		(width 0.1143)
		(layer "F.Cu")
		(net "P3E_CPU0_PE1_PCH_TXP<10>")
	)
	(segment
		(start 315.520578 -111.20755)
		(end 315.679074 -111.1758)
		(width 0.1143)
		(layer "F.Cu")
		(net "P3E_CPU0_PE1_PCH_TXP<10>")
	)
	(segment
		(start 315.96457 -111.365792)
		(end 315.996574 -111.524288)
		(width 0.1143)
		(layer "F.Cu")
		(net "P3E_CPU0_PE1_PCH_TXP<10>")
	)
	(segment
		(start 305.91633 -100.04679)
		(end 307.818028 -101.948488)
		(width 0.0889)
		(layer "F.Cu")
		(net "P3E_CPU0_PE1_PCH_TXP<10>")
	)
	(segment
		(start 331.877416 -120.553734)
		(end 337.241896 -120.553734)
		(width 0.1143)
		(layer "F.Cu")
		(net "P3E_CPU0_PE1_PCH_TXP<10>")
	)
	(segment
		(start 307.86959 -101.963982)
		(end 310.036464 -104.13111)
		(width 0.1143)
		(layer "F.Cu")
		(net "P3E_CPU0_PE1_PCH_TXP<10>")
	)
	(segment
		(start 305.597306 -99.893882)
		(end 305.597306 -99.894136)
		(width 0.0889)
		(layer "F.Cu")
		(net "P3E_CPU0_PE1_PCH_TXP<10>")
	)
	(segment
		(start 312.420762 -109.144562)
		(end 315.520578 -111.20755)
		(width 0.1143)
		(layer "F.Cu")
		(net "P3E_CPU0_PE1_PCH_TXP<10>")
	)
	(segment
		(start 307.818028 -101.948488)
		(end 307.854096 -101.948488)
		(width 0.0889)
		(layer "F.Cu")
		(net "P3E_CPU0_PE1_PCH_TXP<10>")
	)
	(segment
		(start 310.036464 -104.13111)
		(end 312.420762 -109.144562)
		(width 0.1143)
		(layer "F.Cu")
		(net "P3E_CPU0_PE1_PCH_TXP<10>")
	)
	(segment
		(start 315.679074 -111.1758)
		(end 315.96457 -111.365792)
		(width 0.1143)
		(layer "F.Cu")
		(net "P3E_CPU0_PE1_PCH_TXP<10>")
	)
	(segment
		(start 321.64147 -115.281456)
		(end 323.406008 -115.281456)
		(width 0.1143)
		(layer "F.Cu")
		(net "P3E_CPU0_PE1_PCH_TXP<10>")
	)
	(segment
		(start 316.440312 -111.68253)
		(end 316.725808 -111.872522)
		(width 0.1143)
		(layer "F.Cu")
		(net "P3E_CPU0_PE1_PCH_TXP<10>")
	)
	(segment
		(start 325.834756 -117.710204)
		(end 327.335642 -117.710204)
		(width 0.1143)
		(layer "F.Cu")
		(net "P3E_CPU0_PE1_PCH_TXP<10>")
	)
	(segment
		(start 305.51882 -99.890834)
		(end 305.547268 -99.890834)
		(width 0.0889)
		(layer "F.Cu")
		(net "P3E_CPU0_PE1_PCH_TXP<10>")
	)
	(segment
		(start 304.675286 -98.995738)
		(end 304.675286 -99.327462)
		(width 0.0889)
		(layer "F.Cu")
		(net "P3E_CPU0_PE1_PCH_TXP<10>")
	)
	(segment
		(start 323.406008 -115.281456)
		(end 325.834756 -117.710204)
		(width 0.1143)
		(layer "F.Cu")
		(net "P3E_CPU0_PE1_PCH_TXP<10>")
	)
	(segment
		(start 329.698858 -120.07342)
		(end 331.397102 -120.07342)
		(width 0.1143)
		(layer "F.Cu")
		(net "P3E_CPU0_PE1_PCH_TXP<10>")
	)
	(segment
		(start 315.996574 -111.524288)
		(end 316.281816 -111.71428)
		(width 0.1143)
		(layer "F.Cu")
		(net "P3E_CPU0_PE1_PCH_TXP<10>")
	)
	(segment
		(start 321.64147 -115.281202)
		(end 321.64147 -115.281456)
		(width 0.1143)
		(layer "F.Cu")
		(net "P3E_CPU0_PE1_PCH_TXP<10>")
	)
	(segment
		(start 316.281816 -111.71428)
		(end 316.440312 -111.68253)
		(width 0.1143)
		(layer "F.Cu")
		(net "P3E_CPU0_PE1_PCH_TXP<10>")
	)
	(segment
		(start 307.854096 -101.948488)
		(end 307.86959 -101.963982)
		(width 0.0889)
		(layer "F.Cu")
		(net "P3E_CPU0_PE1_PCH_TXP<10>")
	)
	(segment
		(start 316.757812 -112.031018)
		(end 318.394588 -113.12017)
		(width 0.1143)
		(layer "F.Cu")
		(net "P3E_CPU0_PE1_PCH_TXP<10>")
	)
	(via
		(at 318.394588 -113.12017)
		(size 0.508)
		(drill 0.254)
		(layers "F.Cu" "B.Cu")
		(net "P3E_CPU0_PE1_PCH_TXP<10>")
	)
	(arc
		(start 304.769266 -99.402646)
		(mid 305.010696 -99.499659)
		(end 305.187096 -99.690936)
		(width 0.0889)
		(layer "F.Cu")
		(net "P3E_CPU0_PE1_PCH_TXP<10>")
	)
	(arc
		(start 305.187096 -99.690936)
		(mid 305.327175 -99.833672)
		(end 305.51882 -99.890834)
		(width 0.0889)
		(layer "F.Cu")
		(net "P3E_CPU0_PE1_PCH_TXP<10>")
	)
	(arc
		(start 305.597306 -99.894136)
		(mid 305.769626 -99.943218)
		(end 305.915822 -100.04679)
		(width 0.0889)
		(layer "F.Cu")
		(net "P3E_CPU0_PE1_PCH_TXP<10>")
	)
	(arc
		(start 305.547268 -99.890834)
		(mid 305.572319 -99.891829)
		(end 305.597306 -99.893882)
		(width 0.0889)
		(layer "F.Cu")
		(net "P3E_CPU0_PE1_PCH_TXP<10>")
	)
	(arc
		(start 304.747422 -99.399598)
		(mid 304.758359 -99.401018)
		(end 304.769266 -99.402646)
		(width 0.0889)
		(layer "F.Cu")
		(net "P3E_CPU0_PE1_PCH_TXP<10>")
	)
	(segment
		(start 373.97309 -114.794792)
		(end 373.880634 -114.702336)
		(width 0.0889)
		(layer "F.Cu")
		(net "P3E_CPU0_PE1_PCH_TXP<0>")
	)
	(segment
		(start 374.243346 -114.702336)
		(end 374.15089 -114.794792)
		(width 0.0889)
		(layer "F.Cu")
		(net "P3E_CPU0_PE1_PCH_TXP<0>")
	)
	(segment
		(start 373.880634 -114.702336)
		(end 373.71401 -114.702336)
		(width 0.0889)
		(layer "F.Cu")
		(net "P3E_CPU0_PE1_PCH_TXP<0>")
	)
	(segment
		(start 374.674892 -114.85499)
		(end 374.522238 -114.702336)
		(width 0.0889)
		(layer "F.Cu")
		(net "P3E_CPU0_PE1_PCH_TXP<0>")
	)
	(segment
		(start 374.522238 -114.702336)
		(end 374.243346 -114.702336)
		(width 0.0889)
		(layer "F.Cu")
		(net "P3E_CPU0_PE1_PCH_TXP<0>")
	)
	(segment
		(start 373.310912 -114.299238)
		(end 373.2276 -114.299238)
		(width 0.0889)
		(layer "F.Cu")
		(net "P3E_CPU0_PE1_PCH_TXP<0>")
	)
	(segment
		(start 373.71401 -114.702336)
		(end 373.310912 -114.299238)
		(width 0.0889)
		(layer "F.Cu")
		(net "P3E_CPU0_PE1_PCH_TXP<0>")
	)
	(segment
		(start 374.15089 -114.794792)
		(end 373.97309 -114.794792)
		(width 0.0889)
		(layer "F.Cu")
		(net "P3E_CPU0_PE1_PCH_TXP<0>")
	)
	(via
		(at 373.2276 -114.299238)
		(size 0.508)
		(drill 0.254)
		(layers "F.Cu" "B.Cu")
		(net "P3E_CPU0_PE1_PCH_TXP<0>")
	)
	(via
		(at 340.70925 -81.19745)
		(size 0.508)
		(drill 0.254)
		(layers "F.Cu" "B.Cu")
		(net "P3E_CPU0_PE1_PCH_TXP<0>")
	)
	(segment
		(start 340.013544 -80.71358)
		(end 339.3313 -80.031336)
		(width 0.1143)
		(layer "B.Cu")
		(net "P3E_CPU0_PE1_PCH_TXP<0>")
	)
	(segment
		(start 340.517734 -80.71358)
		(end 340.013544 -80.71358)
		(width 0.1143)
		(layer "B.Cu")
		(net "P3E_CPU0_PE1_PCH_TXP<0>")
	)
	(segment
		(start 338.76996 -78.72476)
		(end 338.76996 -78.583536)
		(width 0.1143)
		(layer "B.Cu")
		(net "P3E_CPU0_PE1_PCH_TXP<0>")
	)
	(segment
		(start 339.3313 -79.2861)
		(end 338.76996 -78.72476)
		(width 0.1143)
		(layer "B.Cu")
		(net "P3E_CPU0_PE1_PCH_TXP<0>")
	)
	(segment
		(start 340.70925 -81.19745)
		(end 340.70925 -80.905096)
		(width 0.1143)
		(layer "B.Cu")
		(net "P3E_CPU0_PE1_PCH_TXP<0>")
	)
	(segment
		(start 339.3313 -80.031336)
		(end 339.3313 -79.2861)
		(width 0.1143)
		(layer "B.Cu")
		(net "P3E_CPU0_PE1_PCH_TXP<0>")
	)
	(segment
		(start 340.70925 -80.905096)
		(end 340.517734 -80.71358)
		(width 0.1143)
		(layer "B.Cu")
		(net "P3E_CPU0_PE1_PCH_TXP<0>")
	)
	(segment
		(start 360.297984 -73.393808)
		(end 359.78973 -73.494392)
		(width 0.1143)
		(layer "In4.Cu")
		(net "P3E_CPU0_PE1_PCH_TXP<0>")
	)
	(segment
		(start 364.600998 -80.223614)
		(end 364.181644 -79.661258)
		(width 0.1143)
		(layer "In4.Cu")
		(net "P3E_CPU0_PE1_PCH_TXP<0>")
	)
	(segment
		(start 366.53216 -90.599514)
		(end 366.33912 -90.31605)
		(width 0.1143)
		(layer "In4.Cu")
		(net "P3E_CPU0_PE1_PCH_TXP<0>")
	)
	(segment
		(start 341.757 -80.296258)
		(end 341.344758 -80.7085)
		(width 0.1143)
		(layer "In4.Cu")
		(net "P3E_CPU0_PE1_PCH_TXP<0>")
	)
	(segment
		(start 369.145312 -95.609918)
		(end 369.37569 -94.482412)
		(width 0.1143)
		(layer "In4.Cu")
		(net "P3E_CPU0_PE1_PCH_TXP<0>")
	)
	(segment
		(start 367.675668 -92.278962)
		(end 367.482628 -91.995498)
		(width 0.1143)
		(layer "In4.Cu")
		(net "P3E_CPU0_PE1_PCH_TXP<0>")
	)
	(segment
		(start 366.954562 -90.926412)
		(end 366.761522 -90.642948)
		(width 0.1143)
		(layer "In4.Cu")
		(net "P3E_CPU0_PE1_PCH_TXP<0>")
	)
	(segment
		(start 361.888786 -73.70826)
		(end 360.297984 -73.393808)
		(width 0.1143)
		(layer "In4.Cu")
		(net "P3E_CPU0_PE1_PCH_TXP<0>")
	)
	(segment
		(start 356.337108 -73.399142)
		(end 355.83876 -73.497186)
		(width 0.1143)
		(layer "In4.Cu")
		(net "P3E_CPU0_PE1_PCH_TXP<0>")
	)
	(segment
		(start 354.29571 -73.388982)
		(end 353.812856 -73.484486)
		(width 0.1143)
		(layer "In4.Cu")
		(net "P3E_CPU0_PE1_PCH_TXP<0>")
	)
	(segment
		(start 375.097802 -111.082328)
		(end 374.963944 -110.607602)
		(width 0.1143)
		(layer "In4.Cu")
		(net "P3E_CPU0_PE1_PCH_TXP<0>")
	)
	(segment
		(start 355.315012 -73.393808)
		(end 354.816664 -73.492106)
		(width 0.1143)
		(layer "In4.Cu")
		(net "P3E_CPU0_PE1_PCH_TXP<0>")
	)
	(segment
		(start 369.419378 -99.205542)
		(end 369.256818 -98.406712)
		(width 0.1143)
		(layer "In4.Cu")
		(net "P3E_CPU0_PE1_PCH_TXP<0>")
	)
	(segment
		(start 375.114312 -109.390434)
		(end 375.238264 -109.033056)
		(width 0.1143)
		(layer "In4.Cu")
		(net "P3E_CPU0_PE1_PCH_TXP<0>")
	)
	(segment
		(start 370.171472 -102.225856)
		(end 369.382294 -101.258878)
		(width 0.1143)
		(layer "In4.Cu")
		(net "P3E_CPU0_PE1_PCH_TXP<0>")
	)
	(segment
		(start 357.794814 -73.489566)
		(end 357.30815 -73.3933)
		(width 0.1143)
		(layer "In4.Cu")
		(net "P3E_CPU0_PE1_PCH_TXP<0>")
	)
	(segment
		(start 374.644158 -112.00003)
		(end 375.097802 -111.082328)
		(width 0.1143)
		(layer "In4.Cu")
		(net "P3E_CPU0_PE1_PCH_TXP<0>")
	)
	(segment
		(start 344.344244 -75.080622)
		(end 343.337642 -75.627484)
		(width 0.1143)
		(layer "In4.Cu")
		(net "P3E_CPU0_PE1_PCH_TXP<0>")
	)
	(segment
		(start 369.256818 -98.406712)
		(end 369.341908 -97.98939)
		(width 0.1143)
		(layer "In4.Cu")
		(net "P3E_CPU0_PE1_PCH_TXP<0>")
	)
	(segment
		(start 369.37569 -94.482412)
		(end 367.90503 -92.322396)
		(width 0.1143)
		(layer "In4.Cu")
		(net "P3E_CPU0_PE1_PCH_TXP<0>")
	)
	(segment
		(start 373.529098 -106.190288)
		(end 372.833646 -106.325416)
		(width 0.1143)
		(layer "In4.Cu")
		(net "P3E_CPU0_PE1_PCH_TXP<0>")
	)
	(segment
		(start 352.823272 -73.491852)
		(end 350.830134 -73.09866)
		(width 0.1143)
		(layer "In4.Cu")
		(net "P3E_CPU0_PE1_PCH_TXP<0>")
	)
	(segment
		(start 367.526316 -91.766136)
		(end 367.333276 -91.482672)
		(width 0.1143)
		(layer "In4.Cu")
		(net "P3E_CPU0_PE1_PCH_TXP<0>")
	)
	(segment
		(start 357.30815 -73.3933)
		(end 356.809548 -73.49236)
		(width 0.1143)
		(layer "In4.Cu")
		(net "P3E_CPU0_PE1_PCH_TXP<0>")
	)
	(segment
		(start 372.210584 -106.093768)
		(end 371.16893 -105.195116)
		(width 0.1143)
		(layer "In4.Cu")
		(net "P3E_CPU0_PE1_PCH_TXP<0>")
	)
	(segment
		(start 363.74959 -77.477874)
		(end 363.953298 -76.449428)
		(width 0.1143)
		(layer "In4.Cu")
		(net "P3E_CPU0_PE1_PCH_TXP<0>")
	)
	(segment
		(start 364.181136 -79.65948)
		(end 363.749336 -77.477874)
		(width 0.1143)
		(layer "In4.Cu")
		(net "P3E_CPU0_PE1_PCH_TXP<0>")
	)
	(segment
		(start 364.181644 -79.661258)
		(end 364.181136 -79.65948)
		(width 0.1143)
		(layer "In4.Cu")
		(net "P3E_CPU0_PE1_PCH_TXP<0>")
	)
	(segment
		(start 359.78973 -73.494392)
		(end 359.29062 -73.395586)
		(width 0.1143)
		(layer "In4.Cu")
		(net "P3E_CPU0_PE1_PCH_TXP<0>")
	)
	(segment
		(start 365.948976 -87.034624)
		(end 364.600998 -80.223614)
		(width 0.1143)
		(layer "In4.Cu")
		(net "P3E_CPU0_PE1_PCH_TXP<0>")
	)
	(segment
		(start 369.382294 -101.258878)
		(end 369.198906 -100.320094)
		(width 0.1143)
		(layer "In4.Cu")
		(net "P3E_CPU0_PE1_PCH_TXP<0>")
	)
	(segment
		(start 353.812856 -73.484486)
		(end 353.336352 -73.390506)
		(width 0.1143)
		(layer "In4.Cu")
		(net "P3E_CPU0_PE1_PCH_TXP<0>")
	)
	(segment
		(start 367.333276 -91.482672)
		(end 367.103914 -91.439238)
		(width 0.1143)
		(layer "In4.Cu")
		(net "P3E_CPU0_PE1_PCH_TXP<0>")
	)
	(segment
		(start 356.809548 -73.49236)
		(end 356.337108 -73.399142)
		(width 0.1143)
		(layer "In4.Cu")
		(net "P3E_CPU0_PE1_PCH_TXP<0>")
	)
	(segment
		(start 340.82355 -80.7085)
		(end 340.70925 -80.8228)
		(width 0.1143)
		(layer "In4.Cu")
		(net "P3E_CPU0_PE1_PCH_TXP<0>")
	)
	(segment
		(start 355.83876 -73.497186)
		(end 355.315012 -73.393808)
		(width 0.1143)
		(layer "In4.Cu")
		(net "P3E_CPU0_PE1_PCH_TXP<0>")
	)
	(segment
		(start 363.953298 -76.449428)
		(end 363.25683 -74.72807)
		(width 0.1143)
		(layer "In4.Cu")
		(net "P3E_CPU0_PE1_PCH_TXP<0>")
	)
	(segment
		(start 353.336352 -73.390506)
		(end 352.823272 -73.491852)
		(width 0.1143)
		(layer "In4.Cu")
		(net "P3E_CPU0_PE1_PCH_TXP<0>")
	)
	(segment
		(start 366.33912 -90.31605)
		(end 366.382554 -90.086688)
		(width 0.1143)
		(layer "In4.Cu")
		(net "P3E_CPU0_PE1_PCH_TXP<0>")
	)
	(segment
		(start 363.25683 -74.72807)
		(end 361.888786 -73.70826)
		(width 0.1143)
		(layer "In4.Cu")
		(net "P3E_CPU0_PE1_PCH_TXP<0>")
	)
	(segment
		(start 343.337642 -75.627484)
		(end 342.01862 -75.627484)
		(width 0.1143)
		(layer "In4.Cu")
		(net "P3E_CPU0_PE1_PCH_TXP<0>")
	)
	(segment
		(start 354.816664 -73.492106)
		(end 354.29571 -73.388982)
		(width 0.1143)
		(layer "In4.Cu")
		(net "P3E_CPU0_PE1_PCH_TXP<0>")
	)
	(segment
		(start 340.70925 -80.8228)
		(end 340.70925 -81.19745)
		(width 0.1143)
		(layer "In4.Cu")
		(net "P3E_CPU0_PE1_PCH_TXP<0>")
	)
	(segment
		(start 359.29062 -73.395586)
		(end 358.803194 -73.492106)
		(width 0.1143)
		(layer "In4.Cu")
		(net "P3E_CPU0_PE1_PCH_TXP<0>")
	)
	(segment
		(start 373.2276 -114.299238)
		(end 373.41175 -114.115088)
		(width 0.1143)
		(layer "In4.Cu")
		(net "P3E_CPU0_PE1_PCH_TXP<0>")
	)
	(segment
		(start 374.924574 -107.48645)
		(end 374.445276 -106.480102)
		(width 0.1143)
		(layer "In4.Cu")
		(net "P3E_CPU0_PE1_PCH_TXP<0>")
	)
	(segment
		(start 371.16893 -105.195116)
		(end 370.171472 -102.225856)
		(width 0.1143)
		(layer "In4.Cu")
		(net "P3E_CPU0_PE1_PCH_TXP<0>")
	)
	(segment
		(start 365.737648 -88.10371)
		(end 365.948976 -87.034624)
		(width 0.1143)
		(layer "In4.Cu")
		(net "P3E_CPU0_PE1_PCH_TXP<0>")
	)
	(segment
		(start 369.341908 -97.98939)
		(end 369.186968 -97.22866)
		(width 0.1143)
		(layer "In4.Cu")
		(net "P3E_CPU0_PE1_PCH_TXP<0>")
	)
	(segment
		(start 373.41175 -114.115088)
		(end 373.41175 -113.232692)
		(width 0.1143)
		(layer "In4.Cu")
		(net "P3E_CPU0_PE1_PCH_TXP<0>")
	)
	(segment
		(start 375.222008 -109.82706)
		(end 375.114312 -109.390434)
		(width 0.1143)
		(layer "In4.Cu")
		(net "P3E_CPU0_PE1_PCH_TXP<0>")
	)
	(segment
		(start 372.833646 -106.325416)
		(end 372.210584 -106.093768)
		(width 0.1143)
		(layer "In4.Cu")
		(net "P3E_CPU0_PE1_PCH_TXP<0>")
	)
	(segment
		(start 374.963944 -110.607602)
		(end 375.222008 -109.82706)
		(width 0.1143)
		(layer "In4.Cu")
		(net "P3E_CPU0_PE1_PCH_TXP<0>")
	)
	(segment
		(start 369.198906 -100.320094)
		(end 369.419378 -99.205542)
		(width 0.1143)
		(layer "In4.Cu")
		(net "P3E_CPU0_PE1_PCH_TXP<0>")
	)
	(segment
		(start 350.830134 -73.09866)
		(end 344.344244 -75.080622)
		(width 0.1143)
		(layer "In4.Cu")
		(net "P3E_CPU0_PE1_PCH_TXP<0>")
	)
	(segment
		(start 374.445276 -106.480102)
		(end 373.529098 -106.190288)
		(width 0.1143)
		(layer "In4.Cu")
		(net "P3E_CPU0_PE1_PCH_TXP<0>")
	)
	(segment
		(start 366.076992 -89.637616)
		(end 365.737648 -88.10371)
		(width 0.1143)
		(layer "In4.Cu")
		(net "P3E_CPU0_PE1_PCH_TXP<0>")
	)
	(segment
		(start 358.292146 -73.391014)
		(end 357.794814 -73.489566)
		(width 0.1143)
		(layer "In4.Cu")
		(net "P3E_CPU0_PE1_PCH_TXP<0>")
	)
	(segment
		(start 369.186968 -97.22866)
		(end 369.413282 -96.11614)
		(width 0.1143)
		(layer "In4.Cu")
		(net "P3E_CPU0_PE1_PCH_TXP<0>")
	)
	(segment
		(start 358.803194 -73.492106)
		(end 358.292146 -73.391014)
		(width 0.1143)
		(layer "In4.Cu")
		(net "P3E_CPU0_PE1_PCH_TXP<0>")
	)
	(segment
		(start 373.41175 -113.232692)
		(end 374.644158 -112.00003)
		(width 0.1143)
		(layer "In4.Cu")
		(net "P3E_CPU0_PE1_PCH_TXP<0>")
	)
	(segment
		(start 366.761522 -90.642948)
		(end 366.53216 -90.599514)
		(width 0.1143)
		(layer "In4.Cu")
		(net "P3E_CPU0_PE1_PCH_TXP<0>")
	)
	(segment
		(start 341.757 -75.889104)
		(end 341.757 -80.296258)
		(width 0.1143)
		(layer "In4.Cu")
		(net "P3E_CPU0_PE1_PCH_TXP<0>")
	)
	(segment
		(start 375.238264 -109.033056)
		(end 374.924574 -107.48645)
		(width 0.1143)
		(layer "In4.Cu")
		(net "P3E_CPU0_PE1_PCH_TXP<0>")
	)
	(segment
		(start 366.382554 -90.086688)
		(end 366.076992 -89.637616)
		(width 0.1143)
		(layer "In4.Cu")
		(net "P3E_CPU0_PE1_PCH_TXP<0>")
	)
	(segment
		(start 366.910874 -91.155774)
		(end 366.954562 -90.926412)
		(width 0.1143)
		(layer "In4.Cu")
		(net "P3E_CPU0_PE1_PCH_TXP<0>")
	)
	(segment
		(start 367.482628 -91.995498)
		(end 367.526316 -91.766136)
		(width 0.1143)
		(layer "In4.Cu")
		(net "P3E_CPU0_PE1_PCH_TXP<0>")
	)
	(segment
		(start 363.749336 -77.477874)
		(end 363.74959 -77.477874)
		(width 0.1143)
		(layer "In4.Cu")
		(net "P3E_CPU0_PE1_PCH_TXP<0>")
	)
	(segment
		(start 342.01862 -75.627484)
		(end 341.757 -75.889104)
		(width 0.1143)
		(layer "In4.Cu")
		(net "P3E_CPU0_PE1_PCH_TXP<0>")
	)
	(segment
		(start 367.90503 -92.322396)
		(end 367.675668 -92.278962)
		(width 0.1143)
		(layer "In4.Cu")
		(net "P3E_CPU0_PE1_PCH_TXP<0>")
	)
	(segment
		(start 369.413282 -96.11614)
		(end 369.145312 -95.609918)
		(width 0.1143)
		(layer "In4.Cu")
		(net "P3E_CPU0_PE1_PCH_TXP<0>")
	)
	(segment
		(start 367.103914 -91.439238)
		(end 366.910874 -91.155774)
		(width 0.1143)
		(layer "In4.Cu")
		(net "P3E_CPU0_PE1_PCH_TXP<0>")
	)
	(segment
		(start 341.344758 -80.7085)
		(end 340.82355 -80.7085)
		(width 0.1143)
		(layer "In4.Cu")
		(net "P3E_CPU0_PE1_PCH_TXP<0>")
	)
	(segment
		(start 312.822336 -106.08437)
		(end 313.104022 -106.27995)
		(width 0.1143)
		(layer "F.Cu")
		(net "P3E_CPU0_PE1_PCH_TXN<9>")
	)
	(segment
		(start 339.222588 -118.879112)
		(end 339.222588 -119.211598)
		(width 0.1143)
		(layer "F.Cu")
		(net "P3E_CPU0_PE1_PCH_TXN<9>")
	)
	(segment
		(start 312.381646 -105.917492)
		(end 312.663332 -106.113072)
		(width 0.1143)
		(layer "F.Cu")
		(net "P3E_CPU0_PE1_PCH_TXN<9>")
	)
	(segment
		(start 312.663332 -106.113072)
		(end 312.822336 -106.08437)
		(width 0.1143)
		(layer "F.Cu")
		(net "P3E_CPU0_PE1_PCH_TXN<9>")
	)
	(segment
		(start 326.262746 -116.93144)
		(end 327.795128 -116.93144)
		(width 0.1143)
		(layer "F.Cu")
		(net "P3E_CPU0_PE1_PCH_TXN<9>")
	)
	(segment
		(start 330.204318 -119.34063)
		(end 335.143602 -119.34063)
		(width 0.1143)
		(layer "F.Cu")
		(net "P3E_CPU0_PE1_PCH_TXN<9>")
	)
	(segment
		(start 313.132724 -106.438954)
		(end 313.41441 -106.634534)
		(width 0.1143)
		(layer "F.Cu")
		(net "P3E_CPU0_PE1_PCH_TXN<9>")
	)
	(segment
		(start 308.920134 -100.2665)
		(end 309.028846 -100.339144)
		(width 0.1143)
		(layer "F.Cu")
		(net "P3E_CPU0_PE1_PCH_TXN<9>")
	)
	(segment
		(start 308.67604 -100.2411)
		(end 308.70144 -100.2665)
		(width 0.0889)
		(layer "F.Cu")
		(net "P3E_CPU0_PE1_PCH_TXN<9>")
	)
	(segment
		(start 309.028846 -100.339144)
		(end 311.32018 -105.041446)
		(width 0.1143)
		(layer "F.Cu")
		(net "P3E_CPU0_PE1_PCH_TXN<9>")
	)
	(segment
		(start 311.912254 -105.59161)
		(end 312.071258 -105.562908)
		(width 0.1143)
		(layer "F.Cu")
		(net "P3E_CPU0_PE1_PCH_TXN<9>")
	)
	(segment
		(start 312.071258 -105.562908)
		(end 312.352944 -105.758488)
		(width 0.1143)
		(layer "F.Cu")
		(net "P3E_CPU0_PE1_PCH_TXN<9>")
	)
	(segment
		(start 305.82108 -99.325176)
		(end 305.920902 -99.3521)
		(width 0.0889)
		(layer "F.Cu")
		(net "P3E_CPU0_PE1_PCH_TXN<9>")
	)
	(segment
		(start 305.533806 -99.490784)
		(end 305.82108 -99.325176)
		(width 0.0889)
		(layer "F.Cu")
		(net "P3E_CPU0_PE1_PCH_TXN<9>")
	)
	(segment
		(start 308.70144 -100.2665)
		(end 308.723538 -100.2665)
		(width 0.0889)
		(layer "F.Cu")
		(net "P3E_CPU0_PE1_PCH_TXN<9>")
	)
	(segment
		(start 311.601866 -105.237026)
		(end 311.630568 -105.39603)
		(width 0.1143)
		(layer "F.Cu")
		(net "P3E_CPU0_PE1_PCH_TXN<9>")
	)
	(segment
		(start 311.32018 -105.041446)
		(end 311.601866 -105.237026)
		(width 0.1143)
		(layer "F.Cu")
		(net "P3E_CPU0_PE1_PCH_TXN<9>")
	)
	(segment
		(start 308.187598 -100.118418)
		(end 308.483762 -100.2411)
		(width 0.0889)
		(layer "F.Cu")
		(net "P3E_CPU0_PE1_PCH_TXN<9>")
	)
	(segment
		(start 320.428112 -111.364522)
		(end 321.303904 -111.972598)
		(width 0.1143)
		(layer "F.Cu")
		(net "P3E_CPU0_PE1_PCH_TXN<9>")
	)
	(segment
		(start 312.352944 -105.758488)
		(end 312.381646 -105.917492)
		(width 0.1143)
		(layer "F.Cu")
		(net "P3E_CPU0_PE1_PCH_TXN<9>")
	)
	(segment
		(start 313.573414 -106.605832)
		(end 320.428112 -111.364522)
		(width 0.1143)
		(layer "F.Cu")
		(net "P3E_CPU0_PE1_PCH_TXN<9>")
	)
	(segment
		(start 308.483762 -100.2411)
		(end 308.67604 -100.2411)
		(width 0.0889)
		(layer "F.Cu")
		(net "P3E_CPU0_PE1_PCH_TXN<9>")
	)
	(segment
		(start 306.374546 -99.586288)
		(end 307.228494 -99.586288)
		(width 0.0889)
		(layer "F.Cu")
		(net "P3E_CPU0_PE1_PCH_TXN<9>")
	)
	(segment
		(start 307.228494 -99.586288)
		(end 307.957474 -99.888294)
		(width 0.0889)
		(layer "F.Cu")
		(net "P3E_CPU0_PE1_PCH_TXN<9>")
	)
	(segment
		(start 339.071966 -118.72849)
		(end 339.222588 -118.879112)
		(width 0.1143)
		(layer "F.Cu")
		(net "P3E_CPU0_PE1_PCH_TXN<9>")
	)
	(segment
		(start 307.957474 -99.888294)
		(end 308.187598 -100.118418)
		(width 0.0889)
		(layer "F.Cu")
		(net "P3E_CPU0_PE1_PCH_TXN<9>")
	)
	(segment
		(start 308.723538 -100.2665)
		(end 308.920134 -100.2665)
		(width 0.1143)
		(layer "F.Cu")
		(net "P3E_CPU0_PE1_PCH_TXN<9>")
	)
	(segment
		(start 313.104022 -106.27995)
		(end 313.132724 -106.438954)
		(width 0.1143)
		(layer "F.Cu")
		(net "P3E_CPU0_PE1_PCH_TXN<9>")
	)
	(segment
		(start 335.755742 -118.72849)
		(end 339.071966 -118.72849)
		(width 0.1143)
		(layer "F.Cu")
		(net "P3E_CPU0_PE1_PCH_TXN<9>")
	)
	(segment
		(start 313.41441 -106.634534)
		(end 313.573414 -106.605832)
		(width 0.1143)
		(layer "F.Cu")
		(net "P3E_CPU0_PE1_PCH_TXN<9>")
	)
	(segment
		(start 321.303904 -111.972598)
		(end 326.262746 -116.93144)
		(width 0.1143)
		(layer "F.Cu")
		(net "P3E_CPU0_PE1_PCH_TXN<9>")
	)
	(segment
		(start 311.630568 -105.39603)
		(end 311.912254 -105.59161)
		(width 0.1143)
		(layer "F.Cu")
		(net "P3E_CPU0_PE1_PCH_TXN<9>")
	)
	(segment
		(start 335.143602 -119.34063)
		(end 335.755742 -118.72849)
		(width 0.1143)
		(layer "F.Cu")
		(net "P3E_CPU0_PE1_PCH_TXN<9>")
	)
	(segment
		(start 327.795128 -116.93144)
		(end 330.204318 -119.34063)
		(width 0.1143)
		(layer "F.Cu")
		(net "P3E_CPU0_PE1_PCH_TXN<9>")
	)
	(via
		(at 320.428112 -111.364522)
		(size 0.508)
		(drill 0.254)
		(layers "F.Cu" "B.Cu")
		(net "P3E_CPU0_PE1_PCH_TXN<9>")
	)
	(arc
		(start 305.920902 -99.3521)
		(mid 306.121128 -99.520699)
		(end 306.374546 -99.586288)
		(width 0.0889)
		(layer "F.Cu")
		(net "P3E_CPU0_PE1_PCH_TXN<9>")
	)
	(segment
		(start 305.175412 -98.321368)
		(end 305.172364 -98.324416)
		(width 0.0889)
		(layer "F.Cu")
		(net "P3E_CPU0_PE1_PCH_TXN<8>")
	)
	(segment
		(start 327.041256 -111.48314)
		(end 327.040748 -111.48314)
		(width 0.1143)
		(layer "F.Cu")
		(net "P3E_CPU0_PE1_PCH_TXN<8>")
	)
	(segment
		(start 332.90002 -118.5164)
		(end 332.90002 -118.1608)
		(width 0.1143)
		(layer "F.Cu")
		(net "P3E_CPU0_PE1_PCH_TXN<8>")
	)
	(segment
		(start 332.78572 -118.0465)
		(end 330.453746 -118.0465)
		(width 0.1143)
		(layer "F.Cu")
		(net "P3E_CPU0_PE1_PCH_TXN<8>")
	)
	(segment
		(start 309.045356 -99.2505)
		(end 308.57444 -99.2505)
		(width 0.0889)
		(layer "F.Cu")
		(net "P3E_CPU0_PE1_PCH_TXN<8>")
	)
	(segment
		(start 309.092854 -99.2759)
		(end 309.070756 -99.2759)
		(width 0.0889)
		(layer "F.Cu")
		(net "P3E_CPU0_PE1_PCH_TXN<8>")
	)
	(segment
		(start 320.390774 -108.460032)
		(end 314.741814 -106.201718)
		(width 0.1143)
		(layer "F.Cu")
		(net "P3E_CPU0_PE1_PCH_TXN<8>")
	)
	(segment
		(start 327.040748 -111.48314)
		(end 326.662796 -110.967266)
		(width 0.1143)
		(layer "F.Cu")
		(net "P3E_CPU0_PE1_PCH_TXN<8>")
	)
	(segment
		(start 305.548284 -98.100134)
		(end 305.518312 -98.100134)
		(width 0.0889)
		(layer "F.Cu")
		(net "P3E_CPU0_PE1_PCH_TXN<8>")
	)
	(segment
		(start 304.693066 -98.595688)
		(end 304.657506 -98.595688)
		(width 0.0889)
		(layer "F.Cu")
		(net "P3E_CPU0_PE1_PCH_TXN<8>")
	)
	(segment
		(start 328.18959 -115.782344)
		(end 328.18959 -113.049558)
		(width 0.1143)
		(layer "F.Cu")
		(net "P3E_CPU0_PE1_PCH_TXN<8>")
	)
	(segment
		(start 309.941722 -99.654868)
		(end 309.375302 -99.2759)
		(width 0.1143)
		(layer "F.Cu")
		(net "P3E_CPU0_PE1_PCH_TXN<8>")
	)
	(segment
		(start 309.070756 -99.2759)
		(end 309.045356 -99.2505)
		(width 0.0889)
		(layer "F.Cu")
		(net "P3E_CPU0_PE1_PCH_TXN<8>")
	)
	(segment
		(start 312.078878 -104.33812)
		(end 309.941722 -99.654868)
		(width 0.1143)
		(layer "F.Cu")
		(net "P3E_CPU0_PE1_PCH_TXN<8>")
	)
	(segment
		(start 326.662796 -110.967266)
		(end 320.390774 -108.460032)
		(width 0.1143)
		(layer "F.Cu")
		(net "P3E_CPU0_PE1_PCH_TXN<8>")
	)
	(segment
		(start 328.18959 -113.049558)
		(end 327.041256 -111.48314)
		(width 0.1143)
		(layer "F.Cu")
		(net "P3E_CPU0_PE1_PCH_TXN<8>")
	)
	(segment
		(start 314.741814 -106.201718)
		(end 312.078878 -104.33812)
		(width 0.1143)
		(layer "F.Cu")
		(net "P3E_CPU0_PE1_PCH_TXN<8>")
	)
	(segment
		(start 332.90002 -118.1608)
		(end 332.78572 -118.0465)
		(width 0.1143)
		(layer "F.Cu")
		(net "P3E_CPU0_PE1_PCH_TXN<8>")
	)
	(segment
		(start 306.993798 -98.595688)
		(end 306.37861 -98.595688)
		(width 0.0889)
		(layer "F.Cu")
		(net "P3E_CPU0_PE1_PCH_TXN<8>")
	)
	(segment
		(start 308.57444 -99.2505)
		(end 306.993798 -98.595688)
		(width 0.0889)
		(layer "F.Cu")
		(net "P3E_CPU0_PE1_PCH_TXN<8>")
	)
	(segment
		(start 309.375302 -99.2759)
		(end 309.092854 -99.2759)
		(width 0.1143)
		(layer "F.Cu")
		(net "P3E_CPU0_PE1_PCH_TXN<8>")
	)
	(segment
		(start 305.188112 -98.299524)
		(end 305.175412 -98.321368)
		(width 0.0889)
		(layer "F.Cu")
		(net "P3E_CPU0_PE1_PCH_TXN<8>")
	)
	(segment
		(start 330.453746 -118.0465)
		(end 328.18959 -115.782344)
		(width 0.1143)
		(layer "F.Cu")
		(net "P3E_CPU0_PE1_PCH_TXN<8>")
	)
	(via
		(at 320.390774 -108.460032)
		(size 0.508)
		(drill 0.254)
		(layers "F.Cu" "B.Cu")
		(net "P3E_CPU0_PE1_PCH_TXN<8>")
	)
	(arc
		(start 304.657506 -98.595688)
		(mid 304.234433 -98.571735)
		(end 303.816766 -98.500184)
		(width 0.0889)
		(layer "F.Cu")
		(net "P3E_CPU0_PE1_PCH_TXN<8>")
	)
	(arc
		(start 306.37861 -98.595688)
		(mid 306.090923 -98.513167)
		(end 305.880516 -98.300286)
		(width 0.0889)
		(layer "F.Cu")
		(net "P3E_CPU0_PE1_PCH_TXN<8>")
	)
	(arc
		(start 305.518312 -98.100134)
		(mid 305.327446 -98.157171)
		(end 305.188112 -98.299524)
		(width 0.0889)
		(layer "F.Cu")
		(net "P3E_CPU0_PE1_PCH_TXN<8>")
	)
	(arc
		(start 305.172364 -98.324416)
		(mid 304.966253 -98.5193)
		(end 304.693066 -98.595688)
		(width 0.0889)
		(layer "F.Cu")
		(net "P3E_CPU0_PE1_PCH_TXN<8>")
	)
	(arc
		(start 305.880516 -98.300286)
		(mid 305.740248 -98.15733)
		(end 305.548284 -98.100134)
		(width 0.0889)
		(layer "F.Cu")
		(net "P3E_CPU0_PE1_PCH_TXN<8>")
	)
	(segment
		(start 371.107462 -118.69039)
		(end 369.988592 -118.69039)
		(width 0.0889)
		(layer "F.Cu")
		(net "P3E_CPU0_PE1_PCH_TXN<7>")
	)
	(segment
		(start 375.304812 -118.12397)
		(end 375.224548 -118.043706)
		(width 0.0889)
		(layer "F.Cu")
		(net "P3E_CPU0_PE1_PCH_TXN<7>")
	)
	(segment
		(start 375.004076 -118.043706)
		(end 374.769888 -118.140734)
		(width 0.0889)
		(layer "F.Cu")
		(net "P3E_CPU0_PE1_PCH_TXN<7>")
	)
	(segment
		(start 375.224548 -118.043706)
		(end 375.004076 -118.043706)
		(width 0.0889)
		(layer "F.Cu")
		(net "P3E_CPU0_PE1_PCH_TXN<7>")
	)
	(segment
		(start 369.899692 -118.60149)
		(end 369.899692 -118.42242)
		(width 0.0889)
		(layer "F.Cu")
		(net "P3E_CPU0_PE1_PCH_TXN<7>")
	)
	(segment
		(start 371.555772 -119.1387)
		(end 371.107462 -118.69039)
		(width 0.0889)
		(layer "F.Cu")
		(net "P3E_CPU0_PE1_PCH_TXN<7>")
	)
	(segment
		(start 369.988592 -118.69039)
		(end 369.899692 -118.60149)
		(width 0.0889)
		(layer "F.Cu")
		(net "P3E_CPU0_PE1_PCH_TXN<7>")
	)
	(segment
		(start 373.943372 -118.140734)
		(end 372.945406 -119.1387)
		(width 0.0889)
		(layer "F.Cu")
		(net "P3E_CPU0_PE1_PCH_TXN<7>")
	)
	(segment
		(start 372.945406 -119.1387)
		(end 371.555772 -119.1387)
		(width 0.0889)
		(layer "F.Cu")
		(net "P3E_CPU0_PE1_PCH_TXN<7>")
	)
	(segment
		(start 375.92 -118.35511)
		(end 375.304812 -118.12397)
		(width 0.0889)
		(layer "F.Cu")
		(net "P3E_CPU0_PE1_PCH_TXN<7>")
	)
	(segment
		(start 369.899692 -118.42242)
		(end 369.9764 -118.237)
		(width 0.0889)
		(layer "F.Cu")
		(net "P3E_CPU0_PE1_PCH_TXN<7>")
	)
	(segment
		(start 374.769888 -118.140734)
		(end 373.943372 -118.140734)
		(width 0.0889)
		(layer "F.Cu")
		(net "P3E_CPU0_PE1_PCH_TXN<7>")
	)
	(via
		(at 369.9764 -118.237)
		(size 0.508)
		(drill 0.254)
		(layers "F.Cu" "B.Cu")
		(net "P3E_CPU0_PE1_PCH_TXN<7>")
	)
	(via
		(at 359.000298 -81.288382)
		(size 0.508)
		(drill 0.254)
		(layers "F.Cu" "B.Cu")
		(net "P3E_CPU0_PE1_PCH_TXN<7>")
	)
	(segment
		(start 357.570786 -80.580992)
		(end 357.99395 -81.004156)
		(width 0.1143)
		(layer "B.Cu")
		(net "P3E_CPU0_PE1_PCH_TXN<7>")
	)
	(segment
		(start 358.721406 -79.30769)
		(end 358.721406 -79.469234)
		(width 0.1143)
		(layer "B.Cu")
		(net "P3E_CPU0_PE1_PCH_TXN<7>")
	)
	(segment
		(start 358.44988 -79.036164)
		(end 358.721406 -79.30769)
		(width 0.1143)
		(layer "B.Cu")
		(net "P3E_CPU0_PE1_PCH_TXN<7>")
	)
	(segment
		(start 358.721406 -79.469234)
		(end 358.64038 -79.55026)
		(width 0.1143)
		(layer "B.Cu")
		(net "P3E_CPU0_PE1_PCH_TXN<7>")
	)
	(segment
		(start 358.00411 -79.55026)
		(end 357.570786 -79.983584)
		(width 0.1143)
		(layer "B.Cu")
		(net "P3E_CPU0_PE1_PCH_TXN<7>")
	)
	(segment
		(start 358.716072 -81.004156)
		(end 359.000298 -81.288382)
		(width 0.1143)
		(layer "B.Cu")
		(net "P3E_CPU0_PE1_PCH_TXN<7>")
	)
	(segment
		(start 358.64038 -79.55026)
		(end 358.00411 -79.55026)
		(width 0.1143)
		(layer "B.Cu")
		(net "P3E_CPU0_PE1_PCH_TXN<7>")
	)
	(segment
		(start 357.570786 -79.983584)
		(end 357.570786 -80.580992)
		(width 0.1143)
		(layer "B.Cu")
		(net "P3E_CPU0_PE1_PCH_TXN<7>")
	)
	(segment
		(start 357.99395 -81.004156)
		(end 358.716072 -81.004156)
		(width 0.1143)
		(layer "B.Cu")
		(net "P3E_CPU0_PE1_PCH_TXN<7>")
	)
	(segment
		(start 358.44988 -78.812136)
		(end 358.44988 -79.036164)
		(width 0.1143)
		(layer "B.Cu")
		(net "P3E_CPU0_PE1_PCH_TXN<7>")
	)
	(segment
		(start 363.154722 -105.61955)
		(end 363.253274 -106.117898)
		(width 0.1143)
		(layer "In4.Cu")
		(net "P3E_CPU0_PE1_PCH_TXN<7>")
	)
	(segment
		(start 363.267752 -105.047542)
		(end 363.154722 -105.61955)
		(width 0.1143)
		(layer "In4.Cu")
		(net "P3E_CPU0_PE1_PCH_TXN<7>")
	)
	(segment
		(start 367.93424 -119.0879)
		(end 369.386358 -119.0879)
		(width 0.1143)
		(layer "In4.Cu")
		(net "P3E_CPU0_PE1_PCH_TXN<7>")
	)
	(segment
		(start 369.386358 -119.0879)
		(end 369.7605 -118.713758)
		(width 0.1143)
		(layer "In4.Cu")
		(net "P3E_CPU0_PE1_PCH_TXN<7>")
	)
	(segment
		(start 363.25302 -107.11434)
		(end 363.154468 -107.612688)
		(width 0.1143)
		(layer "In4.Cu")
		(net "P3E_CPU0_PE1_PCH_TXN<7>")
	)
	(segment
		(start 363.253274 -106.117898)
		(end 363.154722 -106.616246)
		(width 0.1143)
		(layer "In4.Cu")
		(net "P3E_CPU0_PE1_PCH_TXN<7>")
	)
	(segment
		(start 369.7605 -118.713758)
		(end 369.7605 -118.4529)
		(width 0.1143)
		(layer "In4.Cu")
		(net "P3E_CPU0_PE1_PCH_TXN<7>")
	)
	(segment
		(start 361.74299 -85.79993)
		(end 361.098592 -89.056718)
		(width 0.1143)
		(layer "In4.Cu")
		(net "P3E_CPU0_PE1_PCH_TXN<7>")
	)
	(segment
		(start 369.7605 -118.4529)
		(end 369.9764 -118.237)
		(width 0.1143)
		(layer "In4.Cu")
		(net "P3E_CPU0_PE1_PCH_TXN<7>")
	)
	(segment
		(start 365.4933 -116.64696)
		(end 367.93424 -119.0879)
		(width 0.1143)
		(layer "In4.Cu")
		(net "P3E_CPU0_PE1_PCH_TXN<7>")
	)
	(segment
		(start 364.136178 -109.960918)
		(end 364.900464 -110.349792)
		(width 0.1143)
		(layer "In4.Cu")
		(net "P3E_CPU0_PE1_PCH_TXN<7>")
	)
	(segment
		(start 361.103164 -82.567272)
		(end 361.74299 -85.79993)
		(width 0.1143)
		(layer "In4.Cu")
		(net "P3E_CPU0_PE1_PCH_TXN<7>")
	)
	(segment
		(start 359.000298 -81.288382)
		(end 359.336848 -80.951832)
		(width 0.1143)
		(layer "In4.Cu")
		(net "P3E_CPU0_PE1_PCH_TXN<7>")
	)
	(segment
		(start 364.900464 -110.349792)
		(end 365.4933 -111.287306)
		(width 0.1143)
		(layer "In4.Cu")
		(net "P3E_CPU0_PE1_PCH_TXN<7>")
	)
	(segment
		(start 359.336848 -80.951832)
		(end 359.487978 -80.951832)
		(width 0.1143)
		(layer "In4.Cu")
		(net "P3E_CPU0_PE1_PCH_TXN<7>")
	)
	(segment
		(start 359.487978 -80.951832)
		(end 361.103164 -82.567272)
		(width 0.1143)
		(layer "In4.Cu")
		(net "P3E_CPU0_PE1_PCH_TXN<7>")
	)
	(segment
		(start 363.154722 -106.616246)
		(end 363.25302 -107.11434)
		(width 0.1143)
		(layer "In4.Cu")
		(net "P3E_CPU0_PE1_PCH_TXN<7>")
	)
	(segment
		(start 363.154468 -107.612688)
		(end 363.38891 -108.797852)
		(width 0.1143)
		(layer "In4.Cu")
		(net "P3E_CPU0_PE1_PCH_TXN<7>")
	)
	(segment
		(start 362.457492 -95.921576)
		(end 361.959652 -98.437446)
		(width 0.1143)
		(layer "In4.Cu")
		(net "P3E_CPU0_PE1_PCH_TXN<7>")
	)
	(segment
		(start 361.098592 -89.056718)
		(end 362.457492 -95.921576)
		(width 0.1143)
		(layer "In4.Cu")
		(net "P3E_CPU0_PE1_PCH_TXN<7>")
	)
	(segment
		(start 361.959652 -98.437446)
		(end 363.267752 -105.047542)
		(width 0.1143)
		(layer "In4.Cu")
		(net "P3E_CPU0_PE1_PCH_TXN<7>")
	)
	(segment
		(start 363.38891 -108.797852)
		(end 364.136178 -109.960918)
		(width 0.1143)
		(layer "In4.Cu")
		(net "P3E_CPU0_PE1_PCH_TXN<7>")
	)
	(segment
		(start 365.4933 -111.287306)
		(end 365.4933 -116.64696)
		(width 0.1143)
		(layer "In4.Cu")
		(net "P3E_CPU0_PE1_PCH_TXN<7>")
	)
	(segment
		(start 371.968268 -118.63705)
		(end 371.919246 -118.588028)
		(width 0.0889)
		(layer "F.Cu")
		(net "P3E_CPU0_PE1_PCH_TXN<6>")
	)
	(segment
		(start 374.90019 -117.635782)
		(end 374.833642 -117.569234)
		(width 0.0889)
		(layer "F.Cu")
		(net "P3E_CPU0_PE1_PCH_TXN<6>")
	)
	(segment
		(start 371.919246 -118.275354)
		(end 371.9576 -118.237)
		(width 0.0889)
		(layer "F.Cu")
		(net "P3E_CPU0_PE1_PCH_TXN<6>")
	)
	(segment
		(start 372.827296 -118.63705)
		(end 371.968268 -118.63705)
		(width 0.0889)
		(layer "F.Cu")
		(net "P3E_CPU0_PE1_PCH_TXN<6>")
	)
	(segment
		(start 371.919246 -118.588028)
		(end 371.919246 -118.275354)
		(width 0.0889)
		(layer "F.Cu")
		(net "P3E_CPU0_PE1_PCH_TXN<6>")
	)
	(segment
		(start 375.504964 -117.854984)
		(end 374.90019 -117.635782)
		(width 0.0889)
		(layer "F.Cu")
		(net "P3E_CPU0_PE1_PCH_TXN<6>")
	)
	(segment
		(start 373.895112 -117.569234)
		(end 372.827296 -118.63705)
		(width 0.0889)
		(layer "F.Cu")
		(net "P3E_CPU0_PE1_PCH_TXN<6>")
	)
	(segment
		(start 374.833642 -117.569234)
		(end 373.895112 -117.569234)
		(width 0.0889)
		(layer "F.Cu")
		(net "P3E_CPU0_PE1_PCH_TXN<6>")
	)
	(via
		(at 355.741732 -81.319878)
		(size 0.508)
		(drill 0.254)
		(layers "F.Cu" "B.Cu")
		(net "P3E_CPU0_PE1_PCH_TXN<6>")
	)
	(via
		(at 371.9576 -118.237)
		(size 0.508)
		(drill 0.254)
		(layers "F.Cu" "B.Cu")
		(net "P3E_CPU0_PE1_PCH_TXN<6>")
	)
	(segment
		(start 357.133398 -79.058516)
		(end 357.133398 -78.804516)
		(width 0.1143)
		(layer "B.Cu")
		(net "P3E_CPU0_PE1_PCH_TXN<6>")
	)
	(segment
		(start 356.839012 -79.352902)
		(end 357.133398 -79.058516)
		(width 0.1143)
		(layer "B.Cu")
		(net "P3E_CPU0_PE1_PCH_TXN<6>")
	)
	(segment
		(start 355.741732 -81.319878)
		(end 356.093522 -80.968088)
		(width 0.1143)
		(layer "B.Cu")
		(net "P3E_CPU0_PE1_PCH_TXN<6>")
	)
	(segment
		(start 356.093522 -80.968088)
		(end 356.481888 -80.968088)
		(width 0.1143)
		(layer "B.Cu")
		(net "P3E_CPU0_PE1_PCH_TXN<6>")
	)
	(segment
		(start 356.839012 -80.610964)
		(end 356.839012 -79.352902)
		(width 0.1143)
		(layer "B.Cu")
		(net "P3E_CPU0_PE1_PCH_TXN<6>")
	)
	(segment
		(start 356.481888 -80.968088)
		(end 356.839012 -80.610964)
		(width 0.1143)
		(layer "B.Cu")
		(net "P3E_CPU0_PE1_PCH_TXN<6>")
	)
	(segment
		(start 362.494068 -107.612688)
		(end 362.590334 -107.126278)
		(width 0.1143)
		(layer "In4.Cu")
		(net "P3E_CPU0_PE1_PCH_TXN<6>")
	)
	(segment
		(start 370.787422 -120.199404)
		(end 367.119662 -120.199404)
		(width 0.1143)
		(layer "In4.Cu")
		(net "P3E_CPU0_PE1_PCH_TXN<6>")
	)
	(segment
		(start 361.089194 -85.831426)
		(end 360.560366 -83.1596)
		(width 0.1143)
		(layer "In4.Cu")
		(net "P3E_CPU0_PE1_PCH_TXN<6>")
	)
	(segment
		(start 360.444796 -89.08796)
		(end 361.089194 -85.831426)
		(width 0.1143)
		(layer "In4.Cu")
		(net "P3E_CPU0_PE1_PCH_TXN<6>")
	)
	(segment
		(start 371.77345 -119.213376)
		(end 370.787422 -120.199404)
		(width 0.1143)
		(layer "In4.Cu")
		(net "P3E_CPU0_PE1_PCH_TXN<6>")
	)
	(segment
		(start 362.574332 -105.21569)
		(end 361.265724 -98.607626)
		(width 0.1143)
		(layer "In4.Cu")
		(net "P3E_CPU0_PE1_PCH_TXN<6>")
	)
	(segment
		(start 364.45063 -110.847378)
		(end 363.541818 -110.385098)
		(width 0.1143)
		(layer "In4.Cu")
		(net "P3E_CPU0_PE1_PCH_TXN<6>")
	)
	(segment
		(start 362.592874 -106.117898)
		(end 362.494322 -105.61955)
		(width 0.1143)
		(layer "In4.Cu")
		(net "P3E_CPU0_PE1_PCH_TXN<6>")
	)
	(segment
		(start 361.797346 -95.921576)
		(end 360.444796 -89.08796)
		(width 0.1143)
		(layer "In4.Cu")
		(net "P3E_CPU0_PE1_PCH_TXN<6>")
	)
	(segment
		(start 367.119662 -120.199404)
		(end 364.8329 -117.912642)
		(width 0.1143)
		(layer "In4.Cu")
		(net "P3E_CPU0_PE1_PCH_TXN<6>")
	)
	(segment
		(start 362.494322 -105.61955)
		(end 362.574332 -105.21569)
		(width 0.1143)
		(layer "In4.Cu")
		(net "P3E_CPU0_PE1_PCH_TXN<6>")
	)
	(segment
		(start 362.491782 -106.628946)
		(end 362.592874 -106.117898)
		(width 0.1143)
		(layer "In4.Cu")
		(net "P3E_CPU0_PE1_PCH_TXN<6>")
	)
	(segment
		(start 362.820458 -109.262672)
		(end 362.494068 -107.612688)
		(width 0.1143)
		(layer "In4.Cu")
		(net "P3E_CPU0_PE1_PCH_TXN<6>")
	)
	(segment
		(start 371.77345 -118.772178)
		(end 371.77345 -119.213376)
		(width 0.1143)
		(layer "In4.Cu")
		(net "P3E_CPU0_PE1_PCH_TXN<6>")
	)
	(segment
		(start 360.560366 -83.1596)
		(end 359.709212 -82.308446)
		(width 0.1143)
		(layer "In4.Cu")
		(net "P3E_CPU0_PE1_PCH_TXN<6>")
	)
	(segment
		(start 362.590334 -107.126278)
		(end 362.491782 -106.628946)
		(width 0.1143)
		(layer "In4.Cu")
		(net "P3E_CPU0_PE1_PCH_TXN<6>")
	)
	(segment
		(start 356.07879 -80.98282)
		(end 355.741732 -81.319878)
		(width 0.1143)
		(layer "In4.Cu")
		(net "P3E_CPU0_PE1_PCH_TXN<6>")
	)
	(segment
		(start 364.8329 -117.912642)
		(end 364.8329 -111.451898)
		(width 0.1143)
		(layer "In4.Cu")
		(net "P3E_CPU0_PE1_PCH_TXN<6>")
	)
	(segment
		(start 356.591362 -80.98282)
		(end 356.07879 -80.98282)
		(width 0.1143)
		(layer "In4.Cu")
		(net "P3E_CPU0_PE1_PCH_TXN<6>")
	)
	(segment
		(start 357.916988 -82.308446)
		(end 356.591362 -80.98282)
		(width 0.1143)
		(layer "In4.Cu")
		(net "P3E_CPU0_PE1_PCH_TXN<6>")
	)
	(segment
		(start 371.9576 -118.237)
		(end 371.9576 -118.588028)
		(width 0.1143)
		(layer "In4.Cu")
		(net "P3E_CPU0_PE1_PCH_TXN<6>")
	)
	(segment
		(start 364.8329 -111.451898)
		(end 364.529878 -110.9726)
		(width 0.1143)
		(layer "In4.Cu")
		(net "P3E_CPU0_PE1_PCH_TXN<6>")
	)
	(segment
		(start 363.541818 -110.385098)
		(end 362.820458 -109.262672)
		(width 0.1143)
		(layer "In4.Cu")
		(net "P3E_CPU0_PE1_PCH_TXN<6>")
	)
	(segment
		(start 359.709212 -82.308446)
		(end 357.916988 -82.308446)
		(width 0.1143)
		(layer "In4.Cu")
		(net "P3E_CPU0_PE1_PCH_TXN<6>")
	)
	(segment
		(start 361.265724 -98.607626)
		(end 361.797346 -95.921576)
		(width 0.1143)
		(layer "In4.Cu")
		(net "P3E_CPU0_PE1_PCH_TXN<6>")
	)
	(segment
		(start 364.529878 -110.9726)
		(end 364.45063 -110.847378)
		(width 0.1143)
		(layer "In4.Cu")
		(net "P3E_CPU0_PE1_PCH_TXN<6>")
	)
	(segment
		(start 371.9576 -118.588028)
		(end 371.77345 -118.772178)
		(width 0.1143)
		(layer "In4.Cu")
		(net "P3E_CPU0_PE1_PCH_TXN<6>")
	)
	(segment
		(start 375.217944 -117.0432)
		(end 375.017538 -117.0432)
		(width 0.0889)
		(layer "F.Cu")
		(net "P3E_CPU0_PE1_PCH_TXN<5>")
	)
	(segment
		(start 369.899692 -116.865908)
		(end 369.9764 -116.7892)
		(width 0.0889)
		(layer "F.Cu")
		(net "P3E_CPU0_PE1_PCH_TXN<5>")
	)
	(segment
		(start 375.017538 -117.0432)
		(end 374.78208 -117.140736)
		(width 0.0889)
		(layer "F.Cu")
		(net "P3E_CPU0_PE1_PCH_TXN<5>")
	)
	(segment
		(start 373.673116 -117.140736)
		(end 373.167402 -117.64645)
		(width 0.0889)
		(layer "F.Cu")
		(net "P3E_CPU0_PE1_PCH_TXN<5>")
	)
	(segment
		(start 369.988592 -117.24259)
		(end 369.899692 -117.15369)
		(width 0.0889)
		(layer "F.Cu")
		(net "P3E_CPU0_PE1_PCH_TXN<5>")
	)
	(segment
		(start 373.167402 -117.64645)
		(end 371.511322 -117.64645)
		(width 0.0889)
		(layer "F.Cu")
		(net "P3E_CPU0_PE1_PCH_TXN<5>")
	)
	(segment
		(start 371.107462 -117.24259)
		(end 369.988592 -117.24259)
		(width 0.0889)
		(layer "F.Cu")
		(net "P3E_CPU0_PE1_PCH_TXN<5>")
	)
	(segment
		(start 369.899692 -117.15369)
		(end 369.899692 -116.865908)
		(width 0.0889)
		(layer "F.Cu")
		(net "P3E_CPU0_PE1_PCH_TXN<5>")
	)
	(segment
		(start 375.292366 -117.117622)
		(end 375.217944 -117.0432)
		(width 0.0889)
		(layer "F.Cu")
		(net "P3E_CPU0_PE1_PCH_TXN<5>")
	)
	(segment
		(start 374.78208 -117.140736)
		(end 373.673116 -117.140736)
		(width 0.0889)
		(layer "F.Cu")
		(net "P3E_CPU0_PE1_PCH_TXN<5>")
	)
	(segment
		(start 371.511322 -117.64645)
		(end 371.107462 -117.24259)
		(width 0.0889)
		(layer "F.Cu")
		(net "P3E_CPU0_PE1_PCH_TXN<5>")
	)
	(segment
		(start 375.92 -117.355112)
		(end 375.292366 -117.117622)
		(width 0.0889)
		(layer "F.Cu")
		(net "P3E_CPU0_PE1_PCH_TXN<5>")
	)
	(via
		(at 369.9764 -116.7892)
		(size 0.508)
		(drill 0.254)
		(layers "F.Cu" "B.Cu")
		(net "P3E_CPU0_PE1_PCH_TXN<5>")
	)
	(via
		(at 353.625404 -80.177132)
		(size 0.508)
		(drill 0.254)
		(layers "F.Cu" "B.Cu")
		(net "P3E_CPU0_PE1_PCH_TXN<5>")
	)
	(segment
		(start 353.246436 -80.5561)
		(end 352.60534 -80.5561)
		(width 0.1143)
		(layer "B.Cu")
		(net "P3E_CPU0_PE1_PCH_TXN<5>")
	)
	(segment
		(start 353.625404 -80.177132)
		(end 353.246436 -80.5561)
		(width 0.1143)
		(layer "B.Cu")
		(net "P3E_CPU0_PE1_PCH_TXN<5>")
	)
	(segment
		(start 352.66122 -79.50454)
		(end 353.15779 -79.50454)
		(width 0.1143)
		(layer "B.Cu")
		(net "P3E_CPU0_PE1_PCH_TXN<5>")
	)
	(segment
		(start 353.30003 -79.3623)
		(end 353.846638 -79.3623)
		(width 0.1143)
		(layer "B.Cu")
		(net "P3E_CPU0_PE1_PCH_TXN<5>")
	)
	(segment
		(start 353.15779 -79.50454)
		(end 353.30003 -79.3623)
		(width 0.1143)
		(layer "B.Cu")
		(net "P3E_CPU0_PE1_PCH_TXN<5>")
	)
	(segment
		(start 353.846638 -79.3623)
		(end 354.36429 -78.844648)
		(width 0.1143)
		(layer "B.Cu")
		(net "P3E_CPU0_PE1_PCH_TXN<5>")
	)
	(segment
		(start 352.49104 -79.67472)
		(end 352.66122 -79.50454)
		(width 0.1143)
		(layer "B.Cu")
		(net "P3E_CPU0_PE1_PCH_TXN<5>")
	)
	(segment
		(start 352.60534 -80.5561)
		(end 352.49104 -80.4418)
		(width 0.1143)
		(layer "B.Cu")
		(net "P3E_CPU0_PE1_PCH_TXN<5>")
	)
	(segment
		(start 354.36429 -78.844648)
		(end 354.36429 -78.804516)
		(width 0.1143)
		(layer "B.Cu")
		(net "P3E_CPU0_PE1_PCH_TXN<5>")
	)
	(segment
		(start 352.49104 -80.4418)
		(end 352.49104 -79.67472)
		(width 0.1143)
		(layer "B.Cu")
		(net "P3E_CPU0_PE1_PCH_TXN<5>")
	)
	(segment
		(start 353.271836 -80.5307)
		(end 352.659442 -80.5307)
		(width 0.1143)
		(layer "In4.Cu")
		(net "P3E_CPU0_PE1_PCH_TXN<5>")
	)
	(segment
		(start 366.548162 -116.437156)
		(end 366.563656 -116.45265)
		(width 0.0889)
		(layer "In4.Cu")
		(net "P3E_CPU0_PE1_PCH_TXN<5>")
	)
	(segment
		(start 352.557842 -82.0801)
		(end 353.887024 -82.0801)
		(width 0.1143)
		(layer "In4.Cu")
		(net "P3E_CPU0_PE1_PCH_TXN<5>")
	)
	(segment
		(start 369.865656 -116.899944)
		(end 369.9764 -116.7892)
		(width 0.0889)
		(layer "In4.Cu")
		(net "P3E_CPU0_PE1_PCH_TXN<5>")
	)
	(segment
		(start 363.93628 -105.005886)
		(end 363.814868 -105.61955)
		(width 0.1143)
		(layer "In4.Cu")
		(net "P3E_CPU0_PE1_PCH_TXN<5>")
	)
	(segment
		(start 354.644198 -79.784956)
		(end 354.736654 -79.6925)
		(width 0.1143)
		(layer "In4.Cu")
		(net "P3E_CPU0_PE1_PCH_TXN<5>")
	)
	(segment
		(start 366.1283 -111.079788)
		(end 366.1283 -116.01704)
		(width 0.1143)
		(layer "In4.Cu")
		(net "P3E_CPU0_PE1_PCH_TXN<5>")
	)
	(segment
		(start 362.628434 -98.396298)
		(end 363.93628 -105.005886)
		(width 0.1143)
		(layer "In4.Cu")
		(net "P3E_CPU0_PE1_PCH_TXN<5>")
	)
	(segment
		(start 364.591092 -109.465618)
		(end 365.35233 -109.852714)
		(width 0.1143)
		(layer "In4.Cu")
		(net "P3E_CPU0_PE1_PCH_TXN<5>")
	)
	(segment
		(start 352.178366 -81.700624)
		(end 352.557842 -82.0801)
		(width 0.1143)
		(layer "In4.Cu")
		(net "P3E_CPU0_PE1_PCH_TXN<5>")
	)
	(segment
		(start 365.35233 -109.852714)
		(end 365.352584 -109.852714)
		(width 0.1143)
		(layer "In4.Cu")
		(net "P3E_CPU0_PE1_PCH_TXN<5>")
	)
	(segment
		(start 366.1283 -116.01704)
		(end 366.548162 -116.437156)
		(width 0.1143)
		(layer "In4.Cu")
		(net "P3E_CPU0_PE1_PCH_TXN<5>")
	)
	(segment
		(start 354.736654 -79.6925)
		(end 359.363518 -79.6925)
		(width 0.1143)
		(layer "In4.Cu")
		(net "P3E_CPU0_PE1_PCH_TXN<5>")
	)
	(segment
		(start 363.910118 -107.097068)
		(end 363.811566 -107.595416)
		(width 0.1143)
		(layer "In4.Cu")
		(net "P3E_CPU0_PE1_PCH_TXN<5>")
	)
	(segment
		(start 352.178366 -81.011776)
		(end 352.178366 -81.700624)
		(width 0.1143)
		(layer "In4.Cu")
		(net "P3E_CPU0_PE1_PCH_TXN<5>")
	)
	(segment
		(start 367.906046 -117.722904)
		(end 369.525804 -117.722904)
		(width 0.0889)
		(layer "In4.Cu")
		(net "P3E_CPU0_PE1_PCH_TXN<5>")
	)
	(segment
		(start 353.625404 -80.177132)
		(end 353.271836 -80.5307)
		(width 0.1143)
		(layer "In4.Cu")
		(net "P3E_CPU0_PE1_PCH_TXN<5>")
	)
	(segment
		(start 363.811566 -107.595416)
		(end 363.915198 -108.121196)
		(width 0.1143)
		(layer "In4.Cu")
		(net "P3E_CPU0_PE1_PCH_TXN<5>")
	)
	(segment
		(start 369.525804 -117.722904)
		(end 369.865656 -117.383052)
		(width 0.0889)
		(layer "In4.Cu")
		(net "P3E_CPU0_PE1_PCH_TXN<5>")
	)
	(segment
		(start 354.644198 -81.322926)
		(end 354.644198 -79.784956)
		(width 0.1143)
		(layer "In4.Cu")
		(net "P3E_CPU0_PE1_PCH_TXN<5>")
	)
	(segment
		(start 363.915198 -108.121196)
		(end 364.591092 -109.465618)
		(width 0.1143)
		(layer "In4.Cu")
		(net "P3E_CPU0_PE1_PCH_TXN<5>")
	)
	(segment
		(start 366.635792 -116.45265)
		(end 367.906046 -117.722904)
		(width 0.0889)
		(layer "In4.Cu")
		(net "P3E_CPU0_PE1_PCH_TXN<5>")
	)
	(segment
		(start 365.352584 -109.852714)
		(end 366.1283 -111.079788)
		(width 0.1143)
		(layer "In4.Cu")
		(net "P3E_CPU0_PE1_PCH_TXN<5>")
	)
	(segment
		(start 363.91342 -106.117898)
		(end 363.814868 -106.616246)
		(width 0.1143)
		(layer "In4.Cu")
		(net "P3E_CPU0_PE1_PCH_TXN<5>")
	)
	(segment
		(start 363.814868 -105.61955)
		(end 363.91342 -106.117898)
		(width 0.1143)
		(layer "In4.Cu")
		(net "P3E_CPU0_PE1_PCH_TXN<5>")
	)
	(segment
		(start 353.887024 -82.0801)
		(end 354.644198 -81.322926)
		(width 0.1143)
		(layer "In4.Cu")
		(net "P3E_CPU0_PE1_PCH_TXN<5>")
	)
	(segment
		(start 369.865656 -117.383052)
		(end 369.865656 -116.899944)
		(width 0.0889)
		(layer "In4.Cu")
		(net "P3E_CPU0_PE1_PCH_TXN<5>")
	)
	(segment
		(start 361.844336 -89.487756)
		(end 363.117892 -95.92183)
		(width 0.1143)
		(layer "In4.Cu")
		(net "P3E_CPU0_PE1_PCH_TXN<5>")
	)
	(segment
		(start 362.492036 -86.216236)
		(end 361.844336 -89.487756)
		(width 0.1143)
		(layer "In4.Cu")
		(net "P3E_CPU0_PE1_PCH_TXN<5>")
	)
	(segment
		(start 363.117892 -95.92183)
		(end 362.628434 -98.396298)
		(width 0.1143)
		(layer "In4.Cu")
		(net "P3E_CPU0_PE1_PCH_TXN<5>")
	)
	(segment
		(start 359.363518 -79.6925)
		(end 361.654598 -81.983834)
		(width 0.1143)
		(layer "In4.Cu")
		(net "P3E_CPU0_PE1_PCH_TXN<5>")
	)
	(segment
		(start 366.563656 -116.45265)
		(end 366.635792 -116.45265)
		(width 0.0889)
		(layer "In4.Cu")
		(net "P3E_CPU0_PE1_PCH_TXN<5>")
	)
	(segment
		(start 363.814868 -106.616246)
		(end 363.910118 -107.097068)
		(width 0.1143)
		(layer "In4.Cu")
		(net "P3E_CPU0_PE1_PCH_TXN<5>")
	)
	(segment
		(start 352.659442 -80.5307)
		(end 352.178366 -81.011776)
		(width 0.1143)
		(layer "In4.Cu")
		(net "P3E_CPU0_PE1_PCH_TXN<5>")
	)
	(segment
		(start 361.654598 -81.983834)
		(end 362.492036 -86.216236)
		(width 0.1143)
		(layer "In4.Cu")
		(net "P3E_CPU0_PE1_PCH_TXN<5>")
	)
	(segment
		(start 371.919246 -117.140228)
		(end 371.919246 -116.827554)
		(width 0.0889)
		(layer "F.Cu")
		(net "P3E_CPU0_PE1_PCH_TXN<4>")
	)
	(segment
		(start 373.45747 -116.569236)
		(end 372.837456 -117.18925)
		(width 0.0889)
		(layer "F.Cu")
		(net "P3E_CPU0_PE1_PCH_TXN<4>")
	)
	(segment
		(start 374.833896 -116.569236)
		(end 373.45747 -116.569236)
		(width 0.0889)
		(layer "F.Cu")
		(net "P3E_CPU0_PE1_PCH_TXN<4>")
	)
	(segment
		(start 372.837456 -117.18925)
		(end 371.968268 -117.18925)
		(width 0.0889)
		(layer "F.Cu")
		(net "P3E_CPU0_PE1_PCH_TXN<4>")
	)
	(segment
		(start 371.968268 -117.18925)
		(end 371.919246 -117.140228)
		(width 0.0889)
		(layer "F.Cu")
		(net "P3E_CPU0_PE1_PCH_TXN<4>")
	)
	(segment
		(start 375.504964 -116.854986)
		(end 374.918732 -116.654072)
		(width 0.0889)
		(layer "F.Cu")
		(net "P3E_CPU0_PE1_PCH_TXN<4>")
	)
	(segment
		(start 374.918732 -116.654072)
		(end 374.833896 -116.569236)
		(width 0.0889)
		(layer "F.Cu")
		(net "P3E_CPU0_PE1_PCH_TXN<4>")
	)
	(segment
		(start 371.919246 -116.827554)
		(end 371.9576 -116.7892)
		(width 0.0889)
		(layer "F.Cu")
		(net "P3E_CPU0_PE1_PCH_TXN<4>")
	)
	(via
		(at 350.749616 -80.250538)
		(size 0.508)
		(drill 0.254)
		(layers "F.Cu" "B.Cu")
		(net "P3E_CPU0_PE1_PCH_TXN<4>")
	)
	(via
		(at 371.9576 -116.7892)
		(size 0.508)
		(drill 0.254)
		(layers "F.Cu" "B.Cu")
		(net "P3E_CPU0_PE1_PCH_TXN<4>")
	)
	(segment
		(start 350.3168 -79.4512)
		(end 350.7994 -79.4512)
		(width 0.1143)
		(layer "B.Cu")
		(net "P3E_CPU0_PE1_PCH_TXN<4>")
	)
	(segment
		(start 350.749616 -80.250538)
		(end 350.404684 -80.59547)
		(width 0.1143)
		(layer "B.Cu")
		(net "P3E_CPU0_PE1_PCH_TXN<4>")
	)
	(segment
		(start 350.2025 -79.5655)
		(end 350.3168 -79.4512)
		(width 0.1143)
		(layer "B.Cu")
		(net "P3E_CPU0_PE1_PCH_TXN<4>")
	)
	(segment
		(start 350.32061 -80.59547)
		(end 350.2025 -80.47736)
		(width 0.1143)
		(layer "B.Cu")
		(net "P3E_CPU0_PE1_PCH_TXN<4>")
	)
	(segment
		(start 351.421192 -78.829408)
		(end 351.421192 -78.723236)
		(width 0.1143)
		(layer "B.Cu")
		(net "P3E_CPU0_PE1_PCH_TXN<4>")
	)
	(segment
		(start 350.404684 -80.59547)
		(end 350.32061 -80.59547)
		(width 0.1143)
		(layer "B.Cu")
		(net "P3E_CPU0_PE1_PCH_TXN<4>")
	)
	(segment
		(start 350.7994 -79.4512)
		(end 351.421192 -78.829408)
		(width 0.1143)
		(layer "B.Cu")
		(net "P3E_CPU0_PE1_PCH_TXN<4>")
	)
	(segment
		(start 350.2025 -80.47736)
		(end 350.2025 -79.5655)
		(width 0.1143)
		(layer "B.Cu")
		(net "P3E_CPU0_PE1_PCH_TXN<4>")
	)
	(segment
		(start 355.81336 -75.83551)
		(end 356.311708 -75.736958)
		(width 0.1143)
		(layer "In4.Cu")
		(net "P3E_CPU0_PE1_PCH_TXN<4>")
	)
	(segment
		(start 368.072924 -115.47475)
		(end 368.390424 -115.79225)
		(width 0.0889)
		(layer "In4.Cu")
		(net "P3E_CPU0_PE1_PCH_TXN<4>")
	)
	(segment
		(start 363.44733 -86.232238)
		(end 362.889292 -89.052146)
		(width 0.1143)
		(layer "In4.Cu")
		(net "P3E_CPU0_PE1_PCH_TXN<4>")
	)
	(segment
		(start 368.900964 -110.447328)
		(end 368.804698 -110.934246)
		(width 0.1143)
		(layer "In4.Cu")
		(net "P3E_CPU0_PE1_PCH_TXN<4>")
	)
	(segment
		(start 354.816664 -75.83551)
		(end 355.315012 -75.736958)
		(width 0.1143)
		(layer "In4.Cu")
		(net "P3E_CPU0_PE1_PCH_TXN<4>")
	)
	(segment
		(start 368.90833 -109.413548)
		(end 368.802412 -109.949488)
		(width 0.1143)
		(layer "In4.Cu")
		(net "P3E_CPU0_PE1_PCH_TXN<4>")
	)
	(segment
		(start 368.812318 -110.9726)
		(end 369.002056 -111.929672)
		(width 0.1143)
		(layer "In4.Cu")
		(net "P3E_CPU0_PE1_PCH_TXN<4>")
	)
	(segment
		(start 357.806752 -75.83551)
		(end 358.304846 -75.736958)
		(width 0.1143)
		(layer "In4.Cu")
		(net "P3E_CPU0_PE1_PCH_TXN<4>")
	)
	(segment
		(start 368.390424 -115.79225)
		(end 371.344444 -115.79225)
		(width 0.0889)
		(layer "In4.Cu")
		(net "P3E_CPU0_PE1_PCH_TXN<4>")
	)
	(segment
		(start 367.701322 -104.888284)
		(end 368.660426 -105.22077)
		(width 0.1143)
		(layer "In4.Cu")
		(net "P3E_CPU0_PE1_PCH_TXN<4>")
	)
	(segment
		(start 369.002056 -106.946954)
		(end 368.804698 -107.943904)
		(width 0.1143)
		(layer "In4.Cu")
		(net "P3E_CPU0_PE1_PCH_TXN<4>")
	)
	(segment
		(start 369.002056 -111.929672)
		(end 368.48161 -114.561874)
		(width 0.1143)
		(layer "In4.Cu")
		(net "P3E_CPU0_PE1_PCH_TXN<4>")
	)
	(segment
		(start 352.701098 -79.074518)
		(end 352.701098 -76.196698)
		(width 0.1143)
		(layer "In4.Cu")
		(net "P3E_CPU0_PE1_PCH_TXN<4>")
	)
	(segment
		(start 371.702076 -116.27612)
		(end 371.9576 -116.531644)
		(width 0.0889)
		(layer "In4.Cu")
		(net "P3E_CPU0_PE1_PCH_TXN<4>")
	)
	(segment
		(start 368.903504 -108.442252)
		(end 368.810032 -108.9152)
		(width 0.1143)
		(layer "In4.Cu")
		(net "P3E_CPU0_PE1_PCH_TXN<4>")
	)
	(segment
		(start 352.126042 -79.649574)
		(end 352.701098 -79.074518)
		(width 0.1143)
		(layer "In4.Cu")
		(net "P3E_CPU0_PE1_PCH_TXN<4>")
	)
	(segment
		(start 368.810032 -108.9152)
		(end 368.809778 -108.9152)
		(width 0.1143)
		(layer "In4.Cu")
		(net "P3E_CPU0_PE1_PCH_TXN<4>")
	)
	(segment
		(start 365.673894 -105.360216)
		(end 367.701322 -104.888284)
		(width 0.1143)
		(layer "In4.Cu")
		(net "P3E_CPU0_PE1_PCH_TXN<4>")
	)
	(segment
		(start 368.804698 -110.934246)
		(end 368.812318 -110.9726)
		(width 0.1143)
		(layer "In4.Cu")
		(net "P3E_CPU0_PE1_PCH_TXN<4>")
	)
	(segment
		(start 368.48161 -114.561874)
		(end 367.97615 -115.067334)
		(width 0.1143)
		(layer "In4.Cu")
		(net "P3E_CPU0_PE1_PCH_TXN<4>")
	)
	(segment
		(start 367.97615 -115.306094)
		(end 368.05743 -115.387374)
		(width 0.1143)
		(layer "In4.Cu")
		(net "P3E_CPU0_PE1_PCH_TXN<4>")
	)
	(segment
		(start 367.97615 -115.067334)
		(end 367.97615 -115.306094)
		(width 0.1143)
		(layer "In4.Cu")
		(net "P3E_CPU0_PE1_PCH_TXN<4>")
	)
	(segment
		(start 361.367324 -76.186538)
		(end 361.56519 -76.675742)
		(width 0.1143)
		(layer "In4.Cu")
		(net "P3E_CPU0_PE1_PCH_TXN<4>")
	)
	(segment
		(start 360.93273 -75.862688)
		(end 361.367324 -76.186538)
		(width 0.1143)
		(layer "In4.Cu")
		(net "P3E_CPU0_PE1_PCH_TXN<4>")
	)
	(segment
		(start 362.027978 -80.617568)
		(end 362.447332 -81.180432)
		(width 0.1143)
		(layer "In4.Cu")
		(net "P3E_CPU0_PE1_PCH_TXN<4>")
	)
	(segment
		(start 360.297984 -75.736958)
		(end 360.93273 -75.862688)
		(width 0.1143)
		(layer "In4.Cu")
		(net "P3E_CPU0_PE1_PCH_TXN<4>")
	)
	(segment
		(start 357.308404 -75.736958)
		(end 357.806752 -75.83551)
		(width 0.1143)
		(layer "In4.Cu")
		(net "P3E_CPU0_PE1_PCH_TXN<4>")
	)
	(segment
		(start 368.05743 -115.387374)
		(end 368.072924 -115.402868)
		(width 0.0889)
		(layer "In4.Cu")
		(net "P3E_CPU0_PE1_PCH_TXN<4>")
	)
	(segment
		(start 355.315012 -75.736958)
		(end 355.81336 -75.83551)
		(width 0.1143)
		(layer "In4.Cu")
		(net "P3E_CPU0_PE1_PCH_TXN<4>")
	)
	(segment
		(start 368.802412 -109.949488)
		(end 368.900964 -110.447328)
		(width 0.1143)
		(layer "In4.Cu")
		(net "P3E_CPU0_PE1_PCH_TXN<4>")
	)
	(segment
		(start 358.803194 -75.83551)
		(end 359.301542 -75.736958)
		(width 0.1143)
		(layer "In4.Cu")
		(net "P3E_CPU0_PE1_PCH_TXN<4>")
	)
	(segment
		(start 364.16234 -95.485204)
		(end 363.734096 -97.648522)
		(width 0.1143)
		(layer "In4.Cu")
		(net "P3E_CPU0_PE1_PCH_TXN<4>")
	)
	(segment
		(start 353.001834 -75.895962)
		(end 353.451414 -75.762612)
		(width 0.1143)
		(layer "In4.Cu")
		(net "P3E_CPU0_PE1_PCH_TXN<4>")
	)
	(segment
		(start 359.301542 -75.736958)
		(end 359.79989 -75.83551)
		(width 0.1143)
		(layer "In4.Cu")
		(net "P3E_CPU0_PE1_PCH_TXN<4>")
	)
	(segment
		(start 354.318316 -75.736958)
		(end 354.816664 -75.83551)
		(width 0.1143)
		(layer "In4.Cu")
		(net "P3E_CPU0_PE1_PCH_TXN<4>")
	)
	(segment
		(start 368.072924 -115.402868)
		(end 368.072924 -115.47475)
		(width 0.0889)
		(layer "In4.Cu")
		(net "P3E_CPU0_PE1_PCH_TXN<4>")
	)
	(segment
		(start 371.702076 -116.149882)
		(end 371.702076 -116.27612)
		(width 0.0889)
		(layer "In4.Cu")
		(net "P3E_CPU0_PE1_PCH_TXN<4>")
	)
	(segment
		(start 356.311708 -75.736958)
		(end 356.810056 -75.83551)
		(width 0.1143)
		(layer "In4.Cu")
		(net "P3E_CPU0_PE1_PCH_TXN<4>")
	)
	(segment
		(start 361.40644 -77.477874)
		(end 362.027978 -80.617568)
		(width 0.1143)
		(layer "In4.Cu")
		(net "P3E_CPU0_PE1_PCH_TXN<4>")
	)
	(segment
		(start 353.451414 -75.762612)
		(end 353.819968 -75.83551)
		(width 0.1143)
		(layer "In4.Cu")
		(net "P3E_CPU0_PE1_PCH_TXN<4>")
	)
	(segment
		(start 352.701098 -76.196698)
		(end 353.001834 -75.895962)
		(width 0.1143)
		(layer "In4.Cu")
		(net "P3E_CPU0_PE1_PCH_TXN<4>")
	)
	(segment
		(start 368.809778 -108.9152)
		(end 368.90833 -109.413548)
		(width 0.1143)
		(layer "In4.Cu")
		(net "P3E_CPU0_PE1_PCH_TXN<4>")
	)
	(segment
		(start 352.126042 -80.15097)
		(end 352.126042 -79.649574)
		(width 0.1143)
		(layer "In4.Cu")
		(net "P3E_CPU0_PE1_PCH_TXN<4>")
	)
	(segment
		(start 356.810056 -75.83551)
		(end 357.308404 -75.736958)
		(width 0.1143)
		(layer "In4.Cu")
		(net "P3E_CPU0_PE1_PCH_TXN<4>")
	)
	(segment
		(start 362.447332 -81.180432)
		(end 363.44733 -86.232238)
		(width 0.1143)
		(layer "In4.Cu")
		(net "P3E_CPU0_PE1_PCH_TXN<4>")
	)
	(segment
		(start 371.344444 -115.79225)
		(end 371.702076 -116.149882)
		(width 0.0889)
		(layer "In4.Cu")
		(net "P3E_CPU0_PE1_PCH_TXN<4>")
	)
	(segment
		(start 362.889292 -89.052146)
		(end 364.16234 -95.485204)
		(width 0.1143)
		(layer "In4.Cu")
		(net "P3E_CPU0_PE1_PCH_TXN<4>")
	)
	(segment
		(start 363.734096 -97.648522)
		(end 365.18215 -104.97058)
		(width 0.1143)
		(layer "In4.Cu")
		(net "P3E_CPU0_PE1_PCH_TXN<4>")
	)
	(segment
		(start 371.9576 -116.531644)
		(end 371.9576 -116.7892)
		(width 0.0889)
		(layer "In4.Cu")
		(net "P3E_CPU0_PE1_PCH_TXN<4>")
	)
	(segment
		(start 361.56519 -76.675742)
		(end 361.40644 -77.477874)
		(width 0.1143)
		(layer "In4.Cu")
		(net "P3E_CPU0_PE1_PCH_TXN<4>")
	)
	(segment
		(start 358.304846 -75.736958)
		(end 358.803194 -75.83551)
		(width 0.1143)
		(layer "In4.Cu")
		(net "P3E_CPU0_PE1_PCH_TXN<4>")
	)
	(segment
		(start 351.695512 -80.5815)
		(end 352.126042 -80.15097)
		(width 0.1143)
		(layer "In4.Cu")
		(net "P3E_CPU0_PE1_PCH_TXN<4>")
	)
	(segment
		(start 365.18215 -104.97058)
		(end 365.673894 -105.360216)
		(width 0.1143)
		(layer "In4.Cu")
		(net "P3E_CPU0_PE1_PCH_TXN<4>")
	)
	(segment
		(start 353.819968 -75.83551)
		(end 354.318316 -75.736958)
		(width 0.1143)
		(layer "In4.Cu")
		(net "P3E_CPU0_PE1_PCH_TXN<4>")
	)
	(segment
		(start 351.080578 -80.5815)
		(end 351.695512 -80.5815)
		(width 0.1143)
		(layer "In4.Cu")
		(net "P3E_CPU0_PE1_PCH_TXN<4>")
	)
	(segment
		(start 368.804698 -107.943904)
		(end 368.903504 -108.442252)
		(width 0.1143)
		(layer "In4.Cu")
		(net "P3E_CPU0_PE1_PCH_TXN<4>")
	)
	(segment
		(start 350.749616 -80.250538)
		(end 351.080578 -80.5815)
		(width 0.1143)
		(layer "In4.Cu")
		(net "P3E_CPU0_PE1_PCH_TXN<4>")
	)
	(segment
		(start 359.79989 -75.83551)
		(end 360.297984 -75.736958)
		(width 0.1143)
		(layer "In4.Cu")
		(net "P3E_CPU0_PE1_PCH_TXN<4>")
	)
	(segment
		(start 368.660426 -105.22077)
		(end 369.002056 -106.946954)
		(width 0.1143)
		(layer "In4.Cu")
		(net "P3E_CPU0_PE1_PCH_TXN<4>")
	)
	(segment
		(start 369.988592 -115.79479)
		(end 369.899692 -115.70589)
		(width 0.0889)
		(layer "F.Cu")
		(net "P3E_CPU0_PE1_PCH_TXN<3>")
	)
	(segment
		(start 371.107462 -115.79479)
		(end 369.988592 -115.79479)
		(width 0.0889)
		(layer "F.Cu")
		(net "P3E_CPU0_PE1_PCH_TXN<3>")
	)
	(segment
		(start 375.223532 -116.043202)
		(end 375.01703 -116.043202)
		(width 0.0889)
		(layer "F.Cu")
		(net "P3E_CPU0_PE1_PCH_TXN<3>")
	)
	(segment
		(start 373.212868 -116.140738)
		(end 373.154956 -116.19865)
		(width 0.0889)
		(layer "F.Cu")
		(net "P3E_CPU0_PE1_PCH_TXN<3>")
	)
	(segment
		(start 375.92 -116.355114)
		(end 375.31167 -116.13134)
		(width 0.0889)
		(layer "F.Cu")
		(net "P3E_CPU0_PE1_PCH_TXN<3>")
	)
	(segment
		(start 375.01703 -116.043202)
		(end 374.781826 -116.140738)
		(width 0.0889)
		(layer "F.Cu")
		(net "P3E_CPU0_PE1_PCH_TXN<3>")
	)
	(segment
		(start 371.511322 -116.19865)
		(end 371.107462 -115.79479)
		(width 0.0889)
		(layer "F.Cu")
		(net "P3E_CPU0_PE1_PCH_TXN<3>")
	)
	(segment
		(start 373.154956 -116.19865)
		(end 371.511322 -116.19865)
		(width 0.0889)
		(layer "F.Cu")
		(net "P3E_CPU0_PE1_PCH_TXN<3>")
	)
	(segment
		(start 369.899692 -115.70589)
		(end 369.899692 -115.418108)
		(width 0.0889)
		(layer "F.Cu")
		(net "P3E_CPU0_PE1_PCH_TXN<3>")
	)
	(segment
		(start 375.31167 -116.13134)
		(end 375.223532 -116.043202)
		(width 0.0889)
		(layer "F.Cu")
		(net "P3E_CPU0_PE1_PCH_TXN<3>")
	)
	(segment
		(start 374.781826 -116.140738)
		(end 373.212868 -116.140738)
		(width 0.0889)
		(layer "F.Cu")
		(net "P3E_CPU0_PE1_PCH_TXN<3>")
	)
	(segment
		(start 369.899692 -115.418108)
		(end 369.9764 -115.3414)
		(width 0.0889)
		(layer "F.Cu")
		(net "P3E_CPU0_PE1_PCH_TXN<3>")
	)
	(via
		(at 348.25686 -80.11033)
		(size 0.508)
		(drill 0.254)
		(layers "F.Cu" "B.Cu")
		(net "P3E_CPU0_PE1_PCH_TXN<3>")
	)
	(via
		(at 369.9764 -115.3414)
		(size 0.508)
		(drill 0.254)
		(layers "F.Cu" "B.Cu")
		(net "P3E_CPU0_PE1_PCH_TXN<3>")
	)
	(segment
		(start 347.434154 -80.37068)
		(end 347.22054 -80.157066)
		(width 0.1143)
		(layer "B.Cu")
		(net "P3E_CPU0_PE1_PCH_TXN<3>")
	)
	(segment
		(start 347.99651 -80.37068)
		(end 347.434154 -80.37068)
		(width 0.1143)
		(layer "B.Cu")
		(net "P3E_CPU0_PE1_PCH_TXN<3>")
	)
	(segment
		(start 348.57436 -78.745588)
		(end 348.57436 -78.677516)
		(width 0.1143)
		(layer "B.Cu")
		(net "P3E_CPU0_PE1_PCH_TXN<3>")
	)
	(segment
		(start 348.029276 -79.290672)
		(end 348.57436 -78.745588)
		(width 0.1143)
		(layer "B.Cu")
		(net "P3E_CPU0_PE1_PCH_TXN<3>")
	)
	(segment
		(start 348.25686 -80.11033)
		(end 347.99651 -80.37068)
		(width 0.1143)
		(layer "B.Cu")
		(net "P3E_CPU0_PE1_PCH_TXN<3>")
	)
	(segment
		(start 347.22054 -79.424276)
		(end 347.354144 -79.290672)
		(width 0.1143)
		(layer "B.Cu")
		(net "P3E_CPU0_PE1_PCH_TXN<3>")
	)
	(segment
		(start 347.354144 -79.290672)
		(end 348.029276 -79.290672)
		(width 0.1143)
		(layer "B.Cu")
		(net "P3E_CPU0_PE1_PCH_TXN<3>")
	)
	(segment
		(start 347.22054 -80.157066)
		(end 347.22054 -79.424276)
		(width 0.1143)
		(layer "B.Cu")
		(net "P3E_CPU0_PE1_PCH_TXN<3>")
	)
	(segment
		(start 369.465098 -109.937296)
		(end 369.56492 -109.432852)
		(width 0.1143)
		(layer "In4.Cu")
		(net "P3E_CPU0_PE1_PCH_TXN<3>")
	)
	(segment
		(start 362.238036 -76.611988)
		(end 361.899708 -75.775566)
		(width 0.1143)
		(layer "In4.Cu")
		(net "P3E_CPU0_PE1_PCH_TXN<3>")
	)
	(segment
		(start 349.784416 -76.083668)
		(end 349.784416 -79.554578)
		(width 0.1143)
		(layer "In4.Cu")
		(net "P3E_CPU0_PE1_PCH_TXN<3>")
	)
	(segment
		(start 356.810056 -75.17511)
		(end 356.337108 -75.081638)
		(width 0.1143)
		(layer "In4.Cu")
		(net "P3E_CPU0_PE1_PCH_TXN<3>")
	)
	(segment
		(start 369.466368 -108.934504)
		(end 369.56365 -108.442252)
		(width 0.1143)
		(layer "In4.Cu")
		(net "P3E_CPU0_PE1_PCH_TXN<3>")
	)
	(segment
		(start 363.053376 -80.909668)
		(end 362.634784 -80.348074)
		(width 0.1143)
		(layer "In4.Cu")
		(net "P3E_CPU0_PE1_PCH_TXN<3>")
	)
	(segment
		(start 357.308404 -75.076558)
		(end 356.810056 -75.17511)
		(width 0.1143)
		(layer "In4.Cu")
		(net "P3E_CPU0_PE1_PCH_TXN<3>")
	)
	(segment
		(start 369.796568 -115.161568)
		(end 369.796568 -114.81689)
		(width 0.1143)
		(layer "In4.Cu")
		(net "P3E_CPU0_PE1_PCH_TXN<3>")
	)
	(segment
		(start 355.83876 -75.18019)
		(end 355.315012 -75.076558)
		(width 0.1143)
		(layer "In4.Cu")
		(net "P3E_CPU0_PE1_PCH_TXN<3>")
	)
	(segment
		(start 369.56365 -110.43539)
		(end 369.465098 -109.937296)
		(width 0.1143)
		(layer "In4.Cu")
		(net "P3E_CPU0_PE1_PCH_TXN<3>")
	)
	(segment
		(start 353.797108 -75.170538)
		(end 353.32162 -75.076558)
		(width 0.1143)
		(layer "In4.Cu")
		(net "P3E_CPU0_PE1_PCH_TXN<3>")
	)
	(segment
		(start 366.380268 -102.12705)
		(end 365.269526 -100.802948)
		(width 0.1143)
		(layer "In4.Cu")
		(net "P3E_CPU0_PE1_PCH_TXN<3>")
	)
	(segment
		(start 352.264218 -75.06462)
		(end 350.688656 -75.376024)
		(width 0.1143)
		(layer "In4.Cu")
		(net "P3E_CPU0_PE1_PCH_TXN<3>")
	)
	(segment
		(start 369.465098 -107.943904)
		(end 369.662456 -106.947208)
		(width 0.1143)
		(layer "In4.Cu")
		(net "P3E_CPU0_PE1_PCH_TXN<3>")
	)
	(segment
		(start 363.650022 -88.543892)
		(end 364.107476 -86.232238)
		(width 0.1143)
		(layer "In4.Cu")
		(net "P3E_CPU0_PE1_PCH_TXN<3>")
	)
	(segment
		(start 358.304846 -75.076558)
		(end 357.806752 -75.17511)
		(width 0.1143)
		(layer "In4.Cu")
		(net "P3E_CPU0_PE1_PCH_TXN<3>")
	)
	(segment
		(start 369.56492 -109.432852)
		(end 369.466368 -108.934504)
		(width 0.1143)
		(layer "In4.Cu")
		(net "P3E_CPU0_PE1_PCH_TXN<3>")
	)
	(segment
		(start 348.892114 -80.44688)
		(end 348.59341 -80.44688)
		(width 0.1143)
		(layer "In4.Cu")
		(net "P3E_CPU0_PE1_PCH_TXN<3>")
	)
	(segment
		(start 364.519718 -97.015554)
		(end 364.92307 -94.976696)
		(width 0.1143)
		(layer "In4.Cu")
		(net "P3E_CPU0_PE1_PCH_TXN<3>")
	)
	(segment
		(start 352.823272 -75.17511)
		(end 352.264218 -75.06462)
		(width 0.1143)
		(layer "In4.Cu")
		(net "P3E_CPU0_PE1_PCH_TXN<3>")
	)
	(segment
		(start 361.202224 -75.255628)
		(end 360.297984 -75.076812)
		(width 0.1143)
		(layer "In4.Cu")
		(net "P3E_CPU0_PE1_PCH_TXN<3>")
	)
	(segment
		(start 358.803194 -75.17511)
		(end 358.304846 -75.076558)
		(width 0.1143)
		(layer "In4.Cu")
		(net "P3E_CPU0_PE1_PCH_TXN<3>")
	)
	(segment
		(start 354.29571 -75.071986)
		(end 353.797108 -75.170538)
		(width 0.1143)
		(layer "In4.Cu")
		(net "P3E_CPU0_PE1_PCH_TXN<3>")
	)
	(segment
		(start 368.09807 -103.886)
		(end 367.354866 -102.784148)
		(width 0.1143)
		(layer "In4.Cu")
		(net "P3E_CPU0_PE1_PCH_TXN<3>")
	)
	(segment
		(start 360.297984 -75.076812)
		(end 359.79989 -75.17511)
		(width 0.1143)
		(layer "In4.Cu")
		(net "P3E_CPU0_PE1_PCH_TXN<3>")
	)
	(segment
		(start 356.337108 -75.081638)
		(end 355.83876 -75.18019)
		(width 0.1143)
		(layer "In4.Cu")
		(net "P3E_CPU0_PE1_PCH_TXN<3>")
	)
	(segment
		(start 359.301542 -75.076558)
		(end 358.803194 -75.17511)
		(width 0.1143)
		(layer "In4.Cu")
		(net "P3E_CPU0_PE1_PCH_TXN<3>")
	)
	(segment
		(start 350.688656 -75.376024)
		(end 350.300036 -75.561698)
		(width 0.1143)
		(layer "In4.Cu")
		(net "P3E_CPU0_PE1_PCH_TXN<3>")
	)
	(segment
		(start 369.447826 -114.468148)
		(end 369.278408 -113.87201)
		(width 0.1143)
		(layer "In4.Cu")
		(net "P3E_CPU0_PE1_PCH_TXN<3>")
	)
	(segment
		(start 369.56365 -108.442252)
		(end 369.465098 -107.943904)
		(width 0.1143)
		(layer "In4.Cu")
		(net "P3E_CPU0_PE1_PCH_TXN<3>")
	)
	(segment
		(start 354.816664 -75.17511)
		(end 354.29571 -75.071986)
		(width 0.1143)
		(layer "In4.Cu")
		(net "P3E_CPU0_PE1_PCH_TXN<3>")
	)
	(segment
		(start 359.79989 -75.17511)
		(end 359.301542 -75.076558)
		(width 0.1143)
		(layer "In4.Cu")
		(net "P3E_CPU0_PE1_PCH_TXN<3>")
	)
	(segment
		(start 355.315012 -75.076558)
		(end 354.816664 -75.17511)
		(width 0.1143)
		(layer "In4.Cu")
		(net "P3E_CPU0_PE1_PCH_TXN<3>")
	)
	(segment
		(start 350.300036 -75.561698)
		(end 349.784416 -76.083668)
		(width 0.1143)
		(layer "In4.Cu")
		(net "P3E_CPU0_PE1_PCH_TXN<3>")
	)
	(segment
		(start 348.59341 -80.44688)
		(end 348.25686 -80.11033)
		(width 0.1143)
		(layer "In4.Cu")
		(net "P3E_CPU0_PE1_PCH_TXN<3>")
	)
	(segment
		(start 364.92307 -94.976696)
		(end 363.650022 -88.543892)
		(width 0.1143)
		(layer "In4.Cu")
		(net "P3E_CPU0_PE1_PCH_TXN<3>")
	)
	(segment
		(start 369.278408 -113.87201)
		(end 369.662202 -111.930434)
		(width 0.1143)
		(layer "In4.Cu")
		(net "P3E_CPU0_PE1_PCH_TXN<3>")
	)
	(segment
		(start 357.806752 -75.17511)
		(end 357.308404 -75.076558)
		(width 0.1143)
		(layer "In4.Cu")
		(net "P3E_CPU0_PE1_PCH_TXN<3>")
	)
	(segment
		(start 353.32162 -75.076558)
		(end 352.823272 -75.17511)
		(width 0.1143)
		(layer "In4.Cu")
		(net "P3E_CPU0_PE1_PCH_TXN<3>")
	)
	(segment
		(start 361.899708 -75.775566)
		(end 361.202224 -75.255628)
		(width 0.1143)
		(layer "In4.Cu")
		(net "P3E_CPU0_PE1_PCH_TXN<3>")
	)
	(segment
		(start 367.354866 -102.784148)
		(end 366.380268 -102.12705)
		(width 0.1143)
		(layer "In4.Cu")
		(net "P3E_CPU0_PE1_PCH_TXN<3>")
	)
	(segment
		(start 363.054646 -80.911446)
		(end 363.053376 -80.909668)
		(width 0.1143)
		(layer "In4.Cu")
		(net "P3E_CPU0_PE1_PCH_TXN<3>")
	)
	(segment
		(start 369.662456 -106.947208)
		(end 369.203732 -104.629204)
		(width 0.1143)
		(layer "In4.Cu")
		(net "P3E_CPU0_PE1_PCH_TXN<3>")
	)
	(segment
		(start 369.465098 -110.933738)
		(end 369.56365 -110.43539)
		(width 0.1143)
		(layer "In4.Cu")
		(net "P3E_CPU0_PE1_PCH_TXN<3>")
	)
	(segment
		(start 365.269526 -100.802948)
		(end 364.519718 -97.015554)
		(width 0.1143)
		(layer "In4.Cu")
		(net "P3E_CPU0_PE1_PCH_TXN<3>")
	)
	(segment
		(start 369.203732 -104.629204)
		(end 368.09807 -103.886)
		(width 0.1143)
		(layer "In4.Cu")
		(net "P3E_CPU0_PE1_PCH_TXN<3>")
	)
	(segment
		(start 369.796568 -114.81689)
		(end 369.447826 -114.468148)
		(width 0.1143)
		(layer "In4.Cu")
		(net "P3E_CPU0_PE1_PCH_TXN<3>")
	)
	(segment
		(start 349.784416 -79.554578)
		(end 348.892114 -80.44688)
		(width 0.1143)
		(layer "In4.Cu")
		(net "P3E_CPU0_PE1_PCH_TXN<3>")
	)
	(segment
		(start 362.634784 -80.348074)
		(end 362.066586 -77.477874)
		(width 0.1143)
		(layer "In4.Cu")
		(net "P3E_CPU0_PE1_PCH_TXN<3>")
	)
	(segment
		(start 369.662202 -111.930434)
		(end 369.465098 -110.933738)
		(width 0.1143)
		(layer "In4.Cu")
		(net "P3E_CPU0_PE1_PCH_TXN<3>")
	)
	(segment
		(start 362.066586 -77.477874)
		(end 362.238036 -76.611988)
		(width 0.1143)
		(layer "In4.Cu")
		(net "P3E_CPU0_PE1_PCH_TXN<3>")
	)
	(segment
		(start 364.107476 -86.232238)
		(end 363.054646 -80.911446)
		(width 0.1143)
		(layer "In4.Cu")
		(net "P3E_CPU0_PE1_PCH_TXN<3>")
	)
	(segment
		(start 369.9764 -115.3414)
		(end 369.796568 -115.161568)
		(width 0.1143)
		(layer "In4.Cu")
		(net "P3E_CPU0_PE1_PCH_TXN<3>")
	)
	(segment
		(start 374.892316 -115.628674)
		(end 374.83288 -115.569238)
		(width 0.0889)
		(layer "F.Cu")
		(net "P3E_CPU0_PE1_PCH_TXN<2>")
	)
	(segment
		(start 372.020846 -115.74145)
		(end 371.9576 -115.678204)
		(width 0.0889)
		(layer "F.Cu")
		(net "P3E_CPU0_PE1_PCH_TXN<2>")
	)
	(segment
		(start 373.112284 -115.569238)
		(end 372.940072 -115.74145)
		(width 0.0889)
		(layer "F.Cu")
		(net "P3E_CPU0_PE1_PCH_TXN<2>")
	)
	(segment
		(start 372.940072 -115.74145)
		(end 372.020846 -115.74145)
		(width 0.0889)
		(layer "F.Cu")
		(net "P3E_CPU0_PE1_PCH_TXN<2>")
	)
	(segment
		(start 375.504964 -115.854988)
		(end 374.892316 -115.628674)
		(width 0.0889)
		(layer "F.Cu")
		(net "P3E_CPU0_PE1_PCH_TXN<2>")
	)
	(segment
		(start 371.9576 -115.678204)
		(end 371.9576 -115.3414)
		(width 0.0889)
		(layer "F.Cu")
		(net "P3E_CPU0_PE1_PCH_TXN<2>")
	)
	(segment
		(start 374.83288 -115.569238)
		(end 373.112284 -115.569238)
		(width 0.0889)
		(layer "F.Cu")
		(net "P3E_CPU0_PE1_PCH_TXN<2>")
	)
	(via
		(at 371.9576 -115.3414)
		(size 0.508)
		(drill 0.254)
		(layers "F.Cu" "B.Cu")
		(net "P3E_CPU0_PE1_PCH_TXN<2>")
	)
	(via
		(at 345.514676 -80.01635)
		(size 0.508)
		(drill 0.254)
		(layers "F.Cu" "B.Cu")
		(net "P3E_CPU0_PE1_PCH_TXN<2>")
	)
	(segment
		(start 345.167712 -80.363314)
		(end 345.005914 -80.363314)
		(width 0.1143)
		(layer "B.Cu")
		(net "P3E_CPU0_PE1_PCH_TXN<2>")
	)
	(segment
		(start 344.78976 -80.14716)
		(end 344.78976 -79.32928)
		(width 0.1143)
		(layer "B.Cu")
		(net "P3E_CPU0_PE1_PCH_TXN<2>")
	)
	(segment
		(start 344.78976 -79.32928)
		(end 344.91422 -79.20482)
		(width 0.1143)
		(layer "B.Cu")
		(net "P3E_CPU0_PE1_PCH_TXN<2>")
	)
	(segment
		(start 345.514676 -80.01635)
		(end 345.167712 -80.363314)
		(width 0.1143)
		(layer "B.Cu")
		(net "P3E_CPU0_PE1_PCH_TXN<2>")
	)
	(segment
		(start 345.278964 -79.20482)
		(end 345.832176 -78.651608)
		(width 0.1143)
		(layer "B.Cu")
		(net "P3E_CPU0_PE1_PCH_TXN<2>")
	)
	(segment
		(start 345.832176 -78.651608)
		(end 345.832176 -78.583536)
		(width 0.1143)
		(layer "B.Cu")
		(net "P3E_CPU0_PE1_PCH_TXN<2>")
	)
	(segment
		(start 344.91422 -79.20482)
		(end 345.278964 -79.20482)
		(width 0.1143)
		(layer "B.Cu")
		(net "P3E_CPU0_PE1_PCH_TXN<2>")
	)
	(segment
		(start 345.005914 -80.363314)
		(end 344.78976 -80.14716)
		(width 0.1143)
		(layer "B.Cu")
		(net "P3E_CPU0_PE1_PCH_TXN<2>")
	)
	(segment
		(start 371.7036 -114.952526)
		(end 371.475762 -114.724688)
		(width 0.0889)
		(layer "In4.Cu")
		(net "P3E_CPU0_PE1_PCH_TXN<2>")
	)
	(segment
		(start 365.9124 -95.099124)
		(end 364.462822 -87.773002)
		(width 0.1143)
		(layer "In4.Cu")
		(net "P3E_CPU0_PE1_PCH_TXN<2>")
	)
	(segment
		(start 362.726732 -77.477874)
		(end 362.910882 -76.548234)
		(width 0.1143)
		(layer "In4.Cu")
		(net "P3E_CPU0_PE1_PCH_TXN<2>")
	)
	(segment
		(start 346.8243 -80.124554)
		(end 346.595954 -80.3529)
		(width 0.1143)
		(layer "In4.Cu")
		(net "P3E_CPU0_PE1_PCH_TXN<2>")
	)
	(segment
		(start 349.637604 -74.781664)
		(end 349.637604 -74.781918)
		(width 0.1143)
		(layer "In4.Cu")
		(net "P3E_CPU0_PE1_PCH_TXN<2>")
	)
	(segment
		(start 370.448078 -113.593372)
		(end 370.6368 -113.40465)
		(width 0.0889)
		(layer "In4.Cu")
		(net "P3E_CPU0_PE1_PCH_TXN<2>")
	)
	(segment
		(start 354.29571 -74.411586)
		(end 353.797108 -74.510138)
		(width 0.1143)
		(layer "In4.Cu")
		(net "P3E_CPU0_PE1_PCH_TXN<2>")
	)
	(segment
		(start 359.79989 -74.514964)
		(end 359.301542 -74.416412)
		(width 0.1143)
		(layer "In4.Cu")
		(net "P3E_CPU0_PE1_PCH_TXN<2>")
	)
	(segment
		(start 358.803194 -74.514964)
		(end 358.292146 -74.413872)
		(width 0.1143)
		(layer "In4.Cu")
		(net "P3E_CPU0_PE1_PCH_TXN<2>")
	)
	(segment
		(start 360.298492 -74.416412)
		(end 359.79989 -74.514964)
		(width 0.1143)
		(layer "In4.Cu")
		(net "P3E_CPU0_PE1_PCH_TXN<2>")
	)
	(segment
		(start 363.661198 -80.641444)
		(end 363.241336 -80.077818)
		(width 0.1143)
		(layer "In4.Cu")
		(net "P3E_CPU0_PE1_PCH_TXN<2>")
	)
	(segment
		(start 370.939314 -113.048034)
		(end 371.230652 -112.756696)
		(width 0.1143)
		(layer "In4.Cu")
		(net "P3E_CPU0_PE1_PCH_TXN<2>")
	)
	(segment
		(start 355.315012 -74.416158)
		(end 354.816664 -74.51471)
		(width 0.1143)
		(layer "In4.Cu")
		(net "P3E_CPU0_PE1_PCH_TXN<2>")
	)
	(segment
		(start 370.92382 -113.063528)
		(end 370.939314 -113.048034)
		(width 0.0889)
		(layer "In4.Cu")
		(net "P3E_CPU0_PE1_PCH_TXN<2>")
	)
	(segment
		(start 364.462822 -87.773002)
		(end 364.767876 -86.232238)
		(width 0.1143)
		(layer "In4.Cu")
		(net "P3E_CPU0_PE1_PCH_TXN<2>")
	)
	(segment
		(start 356.337108 -74.421238)
		(end 355.83876 -74.51979)
		(width 0.1143)
		(layer "In4.Cu")
		(net "P3E_CPU0_PE1_PCH_TXN<2>")
	)
	(segment
		(start 370.345462 -114.724688)
		(end 370.13388 -114.513106)
		(width 0.0889)
		(layer "In4.Cu")
		(net "P3E_CPU0_PE1_PCH_TXN<2>")
	)
	(segment
		(start 370.22532 -109.432852)
		(end 370.126514 -108.934504)
		(width 0.1143)
		(layer "In4.Cu")
		(net "P3E_CPU0_PE1_PCH_TXN<2>")
	)
	(segment
		(start 355.83876 -74.51979)
		(end 355.315012 -74.416158)
		(width 0.1143)
		(layer "In4.Cu")
		(net "P3E_CPU0_PE1_PCH_TXN<2>")
	)
	(segment
		(start 366.411256 -101.163628)
		(end 366.268 -100.947474)
		(width 0.1143)
		(layer "In4.Cu")
		(net "P3E_CPU0_PE1_PCH_TXN<2>")
	)
	(segment
		(start 369.787424 -104.24033)
		(end 368.785394 -103.568246)
		(width 0.1143)
		(layer "In4.Cu")
		(net "P3E_CPU0_PE1_PCH_TXN<2>")
	)
	(segment
		(start 367.59642 -101.94798)
		(end 366.411256 -101.163628)
		(width 0.1143)
		(layer "In4.Cu")
		(net "P3E_CPU0_PE1_PCH_TXN<2>")
	)
	(segment
		(start 370.322348 -113.593372)
		(end 370.448078 -113.593372)
		(width 0.0889)
		(layer "In4.Cu")
		(net "P3E_CPU0_PE1_PCH_TXN<2>")
	)
	(segment
		(start 362.910882 -76.548234)
		(end 362.432092 -75.364594)
		(width 0.1143)
		(layer "In4.Cu")
		(net "P3E_CPU0_PE1_PCH_TXN<2>")
	)
	(segment
		(start 371.230652 -112.242092)
		(end 371.07495 -111.474504)
		(width 0.1143)
		(layer "In4.Cu")
		(net "P3E_CPU0_PE1_PCH_TXN<2>")
	)
	(segment
		(start 347.024452 -76.158344)
		(end 347.024452 -79.079344)
		(width 0.1143)
		(layer "In4.Cu")
		(net "P3E_CPU0_PE1_PCH_TXN<2>")
	)
	(segment
		(start 366.268 -100.947474)
		(end 365.522256 -97.184464)
		(width 0.1143)
		(layer "In4.Cu")
		(net "P3E_CPU0_PE1_PCH_TXN<2>")
	)
	(segment
		(start 357.308404 -74.416158)
		(end 356.810056 -74.51471)
		(width 0.1143)
		(layer "In4.Cu")
		(net "P3E_CPU0_PE1_PCH_TXN<2>")
	)
	(segment
		(start 371.9576 -115.3414)
		(end 371.7036 -115.0874)
		(width 0.0889)
		(layer "In4.Cu")
		(net "P3E_CPU0_PE1_PCH_TXN<2>")
	)
	(segment
		(start 370.852192 -113.063528)
		(end 370.92382 -113.063528)
		(width 0.0889)
		(layer "In4.Cu")
		(net "P3E_CPU0_PE1_PCH_TXN<2>")
	)
	(segment
		(start 351.418652 -74.237342)
		(end 349.637604 -74.781664)
		(width 0.1143)
		(layer "In4.Cu")
		(net "P3E_CPU0_PE1_PCH_TXN<2>")
	)
	(segment
		(start 371.475762 -114.724688)
		(end 370.345462 -114.724688)
		(width 0.0889)
		(layer "In4.Cu")
		(net "P3E_CPU0_PE1_PCH_TXN<2>")
	)
	(segment
		(start 363.241336 -80.077818)
		(end 362.726732 -77.477874)
		(width 0.1143)
		(layer "In4.Cu")
		(net "P3E_CPU0_PE1_PCH_TXN<2>")
	)
	(segment
		(start 371.7036 -115.0874)
		(end 371.7036 -114.952526)
		(width 0.0889)
		(layer "In4.Cu")
		(net "P3E_CPU0_PE1_PCH_TXN<2>")
	)
	(segment
		(start 370.6368 -113.40465)
		(end 370.6368 -113.27892)
		(width 0.0889)
		(layer "In4.Cu")
		(net "P3E_CPU0_PE1_PCH_TXN<2>")
	)
	(segment
		(start 347.856556 -75.325986)
		(end 347.024452 -76.158344)
		(width 0.1143)
		(layer "In4.Cu")
		(net "P3E_CPU0_PE1_PCH_TXN<2>")
	)
	(segment
		(start 370.6368 -113.27892)
		(end 370.852192 -113.063528)
		(width 0.0889)
		(layer "In4.Cu")
		(net "P3E_CPU0_PE1_PCH_TXN<2>")
	)
	(segment
		(start 370.126514 -108.934504)
		(end 370.223796 -108.442252)
		(width 0.1143)
		(layer "In4.Cu")
		(net "P3E_CPU0_PE1_PCH_TXN<2>")
	)
	(segment
		(start 365.92383 -95.110554)
		(end 365.9124 -95.099124)
		(width 0.1143)
		(layer "In4.Cu")
		(net "P3E_CPU0_PE1_PCH_TXN<2>")
	)
	(segment
		(start 347.024452 -79.079344)
		(end 346.8243 -79.279496)
		(width 0.1143)
		(layer "In4.Cu")
		(net "P3E_CPU0_PE1_PCH_TXN<2>")
	)
	(segment
		(start 346.595954 -80.3529)
		(end 345.851226 -80.3529)
		(width 0.1143)
		(layer "In4.Cu")
		(net "P3E_CPU0_PE1_PCH_TXN<2>")
	)
	(segment
		(start 371.230652 -112.756696)
		(end 371.230652 -112.242092)
		(width 0.1143)
		(layer "In4.Cu")
		(net "P3E_CPU0_PE1_PCH_TXN<2>")
	)
	(segment
		(start 349.637604 -74.781918)
		(end 347.856556 -75.325986)
		(width 0.1143)
		(layer "In4.Cu")
		(net "P3E_CPU0_PE1_PCH_TXN<2>")
	)
	(segment
		(start 370.13388 -114.513106)
		(end 370.13388 -113.78184)
		(width 0.0889)
		(layer "In4.Cu")
		(net "P3E_CPU0_PE1_PCH_TXN<2>")
	)
	(segment
		(start 371.07495 -111.474504)
		(end 370.183156 -110.230412)
		(width 0.1143)
		(layer "In4.Cu")
		(net "P3E_CPU0_PE1_PCH_TXN<2>")
	)
	(segment
		(start 352.823272 -74.51471)
		(end 351.418652 -74.237342)
		(width 0.1143)
		(layer "In4.Cu")
		(net "P3E_CPU0_PE1_PCH_TXN<2>")
	)
	(segment
		(start 370.322348 -106.948478)
		(end 369.787424 -104.24033)
		(width 0.1143)
		(layer "In4.Cu")
		(net "P3E_CPU0_PE1_PCH_TXN<2>")
	)
	(segment
		(start 353.797108 -74.510138)
		(end 353.32162 -74.416158)
		(width 0.1143)
		(layer "In4.Cu")
		(net "P3E_CPU0_PE1_PCH_TXN<2>")
	)
	(segment
		(start 356.810056 -74.51471)
		(end 356.337108 -74.421238)
		(width 0.1143)
		(layer "In4.Cu")
		(net "P3E_CPU0_PE1_PCH_TXN<2>")
	)
	(segment
		(start 370.125244 -109.937296)
		(end 370.22532 -109.432852)
		(width 0.1143)
		(layer "In4.Cu")
		(net "P3E_CPU0_PE1_PCH_TXN<2>")
	)
	(segment
		(start 345.851226 -80.3529)
		(end 345.514676 -80.01635)
		(width 0.1143)
		(layer "In4.Cu")
		(net "P3E_CPU0_PE1_PCH_TXN<2>")
	)
	(segment
		(start 367.89233 -102.24389)
		(end 367.59642 -101.94798)
		(width 0.1143)
		(layer "In4.Cu")
		(net "P3E_CPU0_PE1_PCH_TXN<2>")
	)
	(segment
		(start 362.432092 -75.364594)
		(end 361.47121 -74.648314)
		(width 0.1143)
		(layer "In4.Cu")
		(net "P3E_CPU0_PE1_PCH_TXN<2>")
	)
	(segment
		(start 361.47121 -74.648314)
		(end 360.298492 -74.416412)
		(width 0.1143)
		(layer "In4.Cu")
		(net "P3E_CPU0_PE1_PCH_TXN<2>")
	)
	(segment
		(start 365.92383 -95.156274)
		(end 365.92383 -95.110554)
		(width 0.1143)
		(layer "In4.Cu")
		(net "P3E_CPU0_PE1_PCH_TXN<2>")
	)
	(segment
		(start 364.767876 -86.232238)
		(end 363.661198 -80.641444)
		(width 0.1143)
		(layer "In4.Cu")
		(net "P3E_CPU0_PE1_PCH_TXN<2>")
	)
	(segment
		(start 357.794814 -74.512424)
		(end 357.308404 -74.416158)
		(width 0.1143)
		(layer "In4.Cu")
		(net "P3E_CPU0_PE1_PCH_TXN<2>")
	)
	(segment
		(start 370.13388 -113.78184)
		(end 370.322348 -113.593372)
		(width 0.0889)
		(layer "In4.Cu")
		(net "P3E_CPU0_PE1_PCH_TXN<2>")
	)
	(segment
		(start 370.183156 -110.230412)
		(end 370.125244 -109.937296)
		(width 0.1143)
		(layer "In4.Cu")
		(net "P3E_CPU0_PE1_PCH_TXN<2>")
	)
	(segment
		(start 354.816664 -74.51471)
		(end 354.29571 -74.411586)
		(width 0.1143)
		(layer "In4.Cu")
		(net "P3E_CPU0_PE1_PCH_TXN<2>")
	)
	(segment
		(start 368.785394 -103.568246)
		(end 367.89233 -102.24389)
		(width 0.1143)
		(layer "In4.Cu")
		(net "P3E_CPU0_PE1_PCH_TXN<2>")
	)
	(segment
		(start 370.223796 -108.442252)
		(end 370.125498 -107.944158)
		(width 0.1143)
		(layer "In4.Cu")
		(net "P3E_CPU0_PE1_PCH_TXN<2>")
	)
	(segment
		(start 353.32162 -74.416158)
		(end 352.823272 -74.51471)
		(width 0.1143)
		(layer "In4.Cu")
		(net "P3E_CPU0_PE1_PCH_TXN<2>")
	)
	(segment
		(start 358.292146 -74.413872)
		(end 357.794814 -74.512424)
		(width 0.1143)
		(layer "In4.Cu")
		(net "P3E_CPU0_PE1_PCH_TXN<2>")
	)
	(segment
		(start 370.125498 -107.944158)
		(end 370.322348 -106.948478)
		(width 0.1143)
		(layer "In4.Cu")
		(net "P3E_CPU0_PE1_PCH_TXN<2>")
	)
	(segment
		(start 359.301542 -74.416412)
		(end 358.803194 -74.514964)
		(width 0.1143)
		(layer "In4.Cu")
		(net "P3E_CPU0_PE1_PCH_TXN<2>")
	)
	(segment
		(start 346.8243 -79.279496)
		(end 346.8243 -80.124554)
		(width 0.1143)
		(layer "In4.Cu")
		(net "P3E_CPU0_PE1_PCH_TXN<2>")
	)
	(segment
		(start 365.522256 -97.184464)
		(end 365.92383 -95.156274)
		(width 0.1143)
		(layer "In4.Cu")
		(net "P3E_CPU0_PE1_PCH_TXN<2>")
	)
	(segment
		(start 371.9068 -114.615468)
		(end 371.9068 -114.299238)
		(width 0.0889)
		(layer "F.Cu")
		(net "P3E_CPU0_PE1_PCH_TXN<1>")
	)
	(segment
		(start 375.01322 -115.04295)
		(end 374.776746 -115.14074)
		(width 0.0889)
		(layer "F.Cu")
		(net "P3E_CPU0_PE1_PCH_TXN<1>")
	)
	(segment
		(start 373.399304 -115.14074)
		(end 372.984014 -114.72545)
		(width 0.0889)
		(layer "F.Cu")
		(net "P3E_CPU0_PE1_PCH_TXN<1>")
	)
	(segment
		(start 372.016782 -114.72545)
		(end 371.9068 -114.615468)
		(width 0.0889)
		(layer "F.Cu")
		(net "P3E_CPU0_PE1_PCH_TXN<1>")
	)
	(segment
		(start 375.309892 -115.1255)
		(end 375.227342 -115.04295)
		(width 0.0889)
		(layer "F.Cu")
		(net "P3E_CPU0_PE1_PCH_TXN<1>")
	)
	(segment
		(start 372.984014 -114.72545)
		(end 372.016782 -114.72545)
		(width 0.0889)
		(layer "F.Cu")
		(net "P3E_CPU0_PE1_PCH_TXN<1>")
	)
	(segment
		(start 375.92 -115.355116)
		(end 375.309892 -115.1255)
		(width 0.0889)
		(layer "F.Cu")
		(net "P3E_CPU0_PE1_PCH_TXN<1>")
	)
	(segment
		(start 374.776746 -115.14074)
		(end 373.399304 -115.14074)
		(width 0.0889)
		(layer "F.Cu")
		(net "P3E_CPU0_PE1_PCH_TXN<1>")
	)
	(segment
		(start 375.227342 -115.04295)
		(end 375.01322 -115.04295)
		(width 0.0889)
		(layer "F.Cu")
		(net "P3E_CPU0_PE1_PCH_TXN<1>")
	)
	(via
		(at 342.680036 -80.628744)
		(size 0.508)
		(drill 0.254)
		(layers "F.Cu" "B.Cu")
		(net "P3E_CPU0_PE1_PCH_TXN<1>")
	)
	(via
		(at 371.9068 -114.299238)
		(size 0.508)
		(drill 0.254)
		(layers "F.Cu" "B.Cu")
		(net "P3E_CPU0_PE1_PCH_TXN<1>")
	)
	(segment
		(start 342.32977 -80.97901)
		(end 342.1888 -80.97901)
		(width 0.1143)
		(layer "B.Cu")
		(net "P3E_CPU0_PE1_PCH_TXN<1>")
	)
	(segment
		(start 342.1888 -80.97901)
		(end 342.0745 -80.86471)
		(width 0.1143)
		(layer "B.Cu")
		(net "P3E_CPU0_PE1_PCH_TXN<1>")
	)
	(segment
		(start 342.0745 -79.28356)
		(end 342.1888 -79.16926)
		(width 0.1143)
		(layer "B.Cu")
		(net "P3E_CPU0_PE1_PCH_TXN<1>")
	)
	(segment
		(start 342.5952 -79.1718)
		(end 343.063068 -78.703932)
		(width 0.1143)
		(layer "B.Cu")
		(net "P3E_CPU0_PE1_PCH_TXN<1>")
	)
	(segment
		(start 343.063068 -78.703932)
		(end 343.063068 -78.583536)
		(width 0.1143)
		(layer "B.Cu")
		(net "P3E_CPU0_PE1_PCH_TXN<1>")
	)
	(segment
		(start 342.59266 -79.16926)
		(end 342.5952 -79.1718)
		(width 0.1143)
		(layer "B.Cu")
		(net "P3E_CPU0_PE1_PCH_TXN<1>")
	)
	(segment
		(start 342.1888 -79.16926)
		(end 342.59266 -79.16926)
		(width 0.1143)
		(layer "B.Cu")
		(net "P3E_CPU0_PE1_PCH_TXN<1>")
	)
	(segment
		(start 342.680036 -80.628744)
		(end 342.32977 -80.97901)
		(width 0.1143)
		(layer "B.Cu")
		(net "P3E_CPU0_PE1_PCH_TXN<1>")
	)
	(segment
		(start 342.0745 -80.86471)
		(end 342.0745 -79.28356)
		(width 0.1143)
		(layer "B.Cu")
		(net "P3E_CPU0_PE1_PCH_TXN<1>")
	)
	(segment
		(start 368.97691 -97.979484)
		(end 368.820446 -97.21088)
		(width 0.1143)
		(layer "In4.Cu")
		(net "P3E_CPU0_PE1_PCH_TXN<1>")
	)
	(segment
		(start 374.870472 -109.008418)
		(end 374.81764 -108.746798)
		(width 0.1143)
		(layer "In4.Cu")
		(net "P3E_CPU0_PE1_PCH_TXN<1>")
	)
	(segment
		(start 373.10568 -112.36452)
		(end 373.833136 -110.844584)
		(width 0.1143)
		(layer "In4.Cu")
		(net "P3E_CPU0_PE1_PCH_TXN<1>")
	)
	(segment
		(start 358.803194 -73.854564)
		(end 358.292146 -73.753472)
		(width 0.1143)
		(layer "In4.Cu")
		(net "P3E_CPU0_PE1_PCH_TXN<1>")
	)
	(segment
		(start 353.336352 -73.752964)
		(end 352.823272 -73.85431)
		(width 0.1143)
		(layer "In4.Cu")
		(net "P3E_CPU0_PE1_PCH_TXN<1>")
	)
	(segment
		(start 361.741466 -74.041254)
		(end 361.741212 -74.041508)
		(width 0.1143)
		(layer "In4.Cu")
		(net "P3E_CPU0_PE1_PCH_TXN<1>")
	)
	(segment
		(start 344.296238 -80.35925)
		(end 343.701624 -80.953864)
		(width 0.1143)
		(layer "In4.Cu")
		(net "P3E_CPU0_PE1_PCH_TXN<1>")
	)
	(segment
		(start 345.074748 -75.229212)
		(end 344.296238 -76.007976)
		(width 0.1143)
		(layer "In4.Cu")
		(net "P3E_CPU0_PE1_PCH_TXN<1>")
	)
	(segment
		(start 344.296238 -76.007976)
		(end 344.296238 -80.35925)
		(width 0.1143)
		(layer "In4.Cu")
		(net "P3E_CPU0_PE1_PCH_TXN<1>")
	)
	(segment
		(start 355.83876 -73.859644)
		(end 355.315012 -73.756012)
		(width 0.1143)
		(layer "In4.Cu")
		(net "P3E_CPU0_PE1_PCH_TXN<1>")
	)
	(segment
		(start 368.814604 -100.45446)
		(end 369.057174 -99.201478)
		(width 0.1143)
		(layer "In4.Cu")
		(net "P3E_CPU0_PE1_PCH_TXN<1>")
	)
	(segment
		(start 360.297984 -73.756266)
		(end 359.78973 -73.85685)
		(width 0.1143)
		(layer "In4.Cu")
		(net "P3E_CPU0_PE1_PCH_TXN<1>")
	)
	(segment
		(start 363.387132 -77.477874)
		(end 363.583728 -76.48448)
		(width 0.1143)
		(layer "In4.Cu")
		(net "P3E_CPU0_PE1_PCH_TXN<1>")
	)
	(segment
		(start 343.701624 -80.953864)
		(end 343.005156 -80.953864)
		(width 0.1143)
		(layer "In4.Cu")
		(net "P3E_CPU0_PE1_PCH_TXN<1>")
	)
	(segment
		(start 374.81764 -108.746798)
		(end 374.817386 -108.746544)
		(width 0.1143)
		(layer "In4.Cu")
		(net "P3E_CPU0_PE1_PCH_TXN<1>")
	)
	(segment
		(start 368.67211 -95.759778)
		(end 368.845084 -94.911418)
		(width 0.1143)
		(layer "In4.Cu")
		(net "P3E_CPU0_PE1_PCH_TXN<1>")
	)
	(segment
		(start 357.308404 -73.755758)
		(end 356.810056 -73.854564)
		(width 0.1143)
		(layer "In4.Cu")
		(net "P3E_CPU0_PE1_PCH_TXN<1>")
	)
	(segment
		(start 354.816664 -73.854564)
		(end 354.29571 -73.75144)
		(width 0.1143)
		(layer "In4.Cu")
		(net "P3E_CPU0_PE1_PCH_TXN<1>")
	)
	(segment
		(start 369.84813 -102.380034)
		(end 369.0239 -101.369876)
		(width 0.1143)
		(layer "In4.Cu")
		(net "P3E_CPU0_PE1_PCH_TXN<1>")
	)
	(segment
		(start 359.78973 -73.85685)
		(end 359.29062 -73.758044)
		(width 0.1143)
		(layer "In4.Cu")
		(net "P3E_CPU0_PE1_PCH_TXN<1>")
	)
	(segment
		(start 356.810056 -73.854564)
		(end 356.337108 -73.761092)
		(width 0.1143)
		(layer "In4.Cu")
		(net "P3E_CPU0_PE1_PCH_TXN<1>")
	)
	(segment
		(start 357.794814 -73.852024)
		(end 357.308404 -73.755758)
		(width 0.1143)
		(layer "In4.Cu")
		(net "P3E_CPU0_PE1_PCH_TXN<1>")
	)
	(segment
		(start 365.824262 -90.473276)
		(end 365.824262 -90.473022)
		(width 0.1143)
		(layer "In4.Cu")
		(net "P3E_CPU0_PE1_PCH_TXN<1>")
	)
	(segment
		(start 374.852184 -109.812836)
		(end 374.743726 -109.373416)
		(width 0.1143)
		(layer "In4.Cu")
		(net "P3E_CPU0_PE1_PCH_TXN<1>")
	)
	(segment
		(start 374.817386 -108.746544)
		(end 374.76557 -108.490766)
		(width 0.1143)
		(layer "In4.Cu")
		(net "P3E_CPU0_PE1_PCH_TXN<1>")
	)
	(segment
		(start 363.583728 -76.48448)
		(end 362.96473 -74.953622)
		(width 0.1143)
		(layer "In4.Cu")
		(net "P3E_CPU0_PE1_PCH_TXN<1>")
	)
	(segment
		(start 370.412264 -104.060244)
		(end 369.84813 -102.380034)
		(width 0.1143)
		(layer "In4.Cu")
		(net "P3E_CPU0_PE1_PCH_TXN<1>")
	)
	(segment
		(start 364.268258 -80.372458)
		(end 364.268258 -80.372712)
		(width 0.1143)
		(layer "In4.Cu")
		(net "P3E_CPU0_PE1_PCH_TXN<1>")
	)
	(segment
		(start 365.824262 -90.473022)
		(end 365.323374 -88.305894)
		(width 0.1143)
		(layer "In4.Cu")
		(net "P3E_CPU0_PE1_PCH_TXN<1>")
	)
	(segment
		(start 373.833136 -110.844584)
		(end 374.654572 -110.411514)
		(width 0.1143)
		(layer "In4.Cu")
		(net "P3E_CPU0_PE1_PCH_TXN<1>")
	)
	(segment
		(start 362.96473 -74.953622)
		(end 361.741466 -74.041254)
		(width 0.1143)
		(layer "In4.Cu")
		(net "P3E_CPU0_PE1_PCH_TXN<1>")
	)
	(segment
		(start 371.730524 -114.122962)
		(end 371.730524 -113.739676)
		(width 0.1143)
		(layer "In4.Cu")
		(net "P3E_CPU0_PE1_PCH_TXN<1>")
	)
	(segment
		(start 354.29571 -73.75144)
		(end 353.81311 -73.846944)
		(width 0.1143)
		(layer "In4.Cu")
		(net "P3E_CPU0_PE1_PCH_TXN<1>")
	)
	(segment
		(start 355.315012 -73.756012)
		(end 354.816664 -73.854564)
		(width 0.1143)
		(layer "In4.Cu")
		(net "P3E_CPU0_PE1_PCH_TXN<1>")
	)
	(segment
		(start 371.9068 -114.299238)
		(end 371.730524 -114.122962)
		(width 0.1143)
		(layer "In4.Cu")
		(net "P3E_CPU0_PE1_PCH_TXN<1>")
	)
	(segment
		(start 352.823272 -73.85431)
		(end 350.84893 -73.464674)
		(width 0.1143)
		(layer "In4.Cu")
		(net "P3E_CPU0_PE1_PCH_TXN<1>")
	)
	(segment
		(start 364.268258 -80.372712)
		(end 363.84865 -79.809594)
		(width 0.1143)
		(layer "In4.Cu")
		(net "P3E_CPU0_PE1_PCH_TXN<1>")
	)
	(segment
		(start 359.29062 -73.758044)
		(end 358.803194 -73.854564)
		(width 0.1143)
		(layer "In4.Cu")
		(net "P3E_CPU0_PE1_PCH_TXN<1>")
	)
	(segment
		(start 368.991896 -96.364044)
		(end 368.67211 -95.759778)
		(width 0.1143)
		(layer "In4.Cu")
		(net "P3E_CPU0_PE1_PCH_TXN<1>")
	)
	(segment
		(start 358.292146 -73.753472)
		(end 357.794814 -73.852024)
		(width 0.1143)
		(layer "In4.Cu")
		(net "P3E_CPU0_PE1_PCH_TXN<1>")
	)
	(segment
		(start 369.057174 -99.201478)
		(end 368.892582 -98.394266)
		(width 0.1143)
		(layer "In4.Cu")
		(net "P3E_CPU0_PE1_PCH_TXN<1>")
	)
	(segment
		(start 370.980208 -106.93781)
		(end 370.412264 -104.060244)
		(width 0.1143)
		(layer "In4.Cu")
		(net "P3E_CPU0_PE1_PCH_TXN<1>")
	)
	(segment
		(start 353.81311 -73.846944)
		(end 353.336352 -73.752964)
		(width 0.1143)
		(layer "In4.Cu")
		(net "P3E_CPU0_PE1_PCH_TXN<1>")
	)
	(segment
		(start 343.005156 -80.953864)
		(end 342.680036 -80.628744)
		(width 0.1143)
		(layer "In4.Cu")
		(net "P3E_CPU0_PE1_PCH_TXN<1>")
	)
	(segment
		(start 374.743726 -109.373416)
		(end 374.870472 -109.008418)
		(width 0.1143)
		(layer "In4.Cu")
		(net "P3E_CPU0_PE1_PCH_TXN<1>")
	)
	(segment
		(start 365.58093 -87.004398)
		(end 364.268258 -80.372458)
		(width 0.1143)
		(layer "In4.Cu")
		(net "P3E_CPU0_PE1_PCH_TXN<1>")
	)
	(segment
		(start 368.845084 -94.911418)
		(end 365.824262 -90.473276)
		(width 0.1143)
		(layer "In4.Cu")
		(net "P3E_CPU0_PE1_PCH_TXN<1>")
	)
	(segment
		(start 356.337108 -73.761092)
		(end 355.83876 -73.859644)
		(width 0.1143)
		(layer "In4.Cu")
		(net "P3E_CPU0_PE1_PCH_TXN<1>")
	)
	(segment
		(start 374.391174 -108.041694)
		(end 371.820186 -107.427522)
		(width 0.1143)
		(layer "In4.Cu")
		(net "P3E_CPU0_PE1_PCH_TXN<1>")
	)
	(segment
		(start 371.820186 -107.427522)
		(end 370.980208 -106.93781)
		(width 0.1143)
		(layer "In4.Cu")
		(net "P3E_CPU0_PE1_PCH_TXN<1>")
	)
	(segment
		(start 374.654572 -110.411514)
		(end 374.852184 -109.812836)
		(width 0.1143)
		(layer "In4.Cu")
		(net "P3E_CPU0_PE1_PCH_TXN<1>")
	)
	(segment
		(start 350.84893 -73.464674)
		(end 345.074748 -75.229212)
		(width 0.1143)
		(layer "In4.Cu")
		(net "P3E_CPU0_PE1_PCH_TXN<1>")
	)
	(segment
		(start 368.892582 -98.394266)
		(end 368.97691 -97.979484)
		(width 0.1143)
		(layer "In4.Cu")
		(net "P3E_CPU0_PE1_PCH_TXN<1>")
	)
	(segment
		(start 369.0239 -101.369876)
		(end 368.814604 -100.45446)
		(width 0.1143)
		(layer "In4.Cu")
		(net "P3E_CPU0_PE1_PCH_TXN<1>")
	)
	(segment
		(start 368.992658 -96.365568)
		(end 368.991896 -96.364044)
		(width 0.1143)
		(layer "In4.Cu")
		(net "P3E_CPU0_PE1_PCH_TXN<1>")
	)
	(segment
		(start 368.820446 -97.21088)
		(end 368.992658 -96.365568)
		(width 0.1143)
		(layer "In4.Cu")
		(net "P3E_CPU0_PE1_PCH_TXN<1>")
	)
	(segment
		(start 363.84865 -79.809594)
		(end 363.387132 -77.477874)
		(width 0.1143)
		(layer "In4.Cu")
		(net "P3E_CPU0_PE1_PCH_TXN<1>")
	)
	(segment
		(start 365.323374 -88.305894)
		(end 365.58093 -87.004398)
		(width 0.1143)
		(layer "In4.Cu")
		(net "P3E_CPU0_PE1_PCH_TXN<1>")
	)
	(segment
		(start 371.730524 -113.739676)
		(end 373.10568 -112.36452)
		(width 0.1143)
		(layer "In4.Cu")
		(net "P3E_CPU0_PE1_PCH_TXN<1>")
	)
	(segment
		(start 361.741212 -74.041508)
		(end 360.297984 -73.756266)
		(width 0.1143)
		(layer "In4.Cu")
		(net "P3E_CPU0_PE1_PCH_TXN<1>")
	)
	(segment
		(start 374.76557 -108.490766)
		(end 374.391174 -108.041694)
		(width 0.1143)
		(layer "In4.Cu")
		(net "P3E_CPU0_PE1_PCH_TXN<1>")
	)
	(segment
		(start 317.387478 -123.557538)
		(end 318.143128 -124.12726)
		(width 0.1143)
		(layer "F.Cu")
		(net "P3E_CPU0_PE1_PCH_TXN<15>")
	)
	(segment
		(start 300.766734 -103.982774)
		(end 301.246286 -104.46258)
		(width 0.0889)
		(layer "F.Cu")
		(net "P3E_CPU0_PE1_PCH_TXN<15>")
	)
	(segment
		(start 311.222136 -119.078502)
		(end 315.9252 -123.0884)
		(width 0.1143)
		(layer "F.Cu")
		(net "P3E_CPU0_PE1_PCH_TXN<15>")
	)
	(segment
		(start 300.382686 -102.462584)
		(end 300.66996 -102.296976)
		(width 0.0889)
		(layer "F.Cu")
		(net "P3E_CPU0_PE1_PCH_TXN<15>")
	)
	(segment
		(start 300.650402 -103.70185)
		(end 300.766734 -103.982774)
		(width 0.0889)
		(layer "F.Cu")
		(net "P3E_CPU0_PE1_PCH_TXN<15>")
	)
	(segment
		(start 303.568862 -106.682286)
		(end 303.568862 -106.717338)
		(width 0.0889)
		(layer "F.Cu")
		(net "P3E_CPU0_PE1_PCH_TXN<15>")
	)
	(segment
		(start 315.9252 -123.0884)
		(end 317.387478 -123.557538)
		(width 0.1143)
		(layer "F.Cu")
		(net "P3E_CPU0_PE1_PCH_TXN<15>")
	)
	(segment
		(start 300.650402 -102.962202)
		(end 300.650402 -103.70185)
		(width 0.0889)
		(layer "F.Cu")
		(net "P3E_CPU0_PE1_PCH_TXN<15>")
	)
	(segment
		(start 301.246286 -104.46258)
		(end 301.556674 -104.670098)
		(width 0.0889)
		(layer "F.Cu")
		(net "P3E_CPU0_PE1_PCH_TXN<15>")
	)
	(segment
		(start 318.143128 -124.12726)
		(end 320.4972 -124.12726)
		(width 0.1143)
		(layer "F.Cu")
		(net "P3E_CPU0_PE1_PCH_TXN<15>")
	)
	(segment
		(start 320.6115 -124.24156)
		(end 320.6115 -124.587)
		(width 0.1143)
		(layer "F.Cu")
		(net "P3E_CPU0_PE1_PCH_TXN<15>")
	)
	(segment
		(start 320.4972 -124.12726)
		(end 320.6115 -124.24156)
		(width 0.1143)
		(layer "F.Cu")
		(net "P3E_CPU0_PE1_PCH_TXN<15>")
	)
	(segment
		(start 300.66996 -102.296976)
		(end 300.756828 -102.320344)
		(width 0.0889)
		(layer "F.Cu")
		(net "P3E_CPU0_PE1_PCH_TXN<15>")
	)
	(segment
		(start 310.706008 -118.63832)
		(end 311.222136 -119.078502)
		(width 0.1143)
		(layer "F.Cu")
		(net "P3E_CPU0_PE1_PCH_TXN<15>")
	)
	(segment
		(start 306.371498 -109.519974)
		(end 309.20309 -115.477544)
		(width 0.1143)
		(layer "F.Cu")
		(net "P3E_CPU0_PE1_PCH_TXN<15>")
	)
	(segment
		(start 301.556674 -104.670098)
		(end 303.568862 -106.682286)
		(width 0.0889)
		(layer "F.Cu")
		(net "P3E_CPU0_PE1_PCH_TXN<15>")
	)
	(segment
		(start 303.568862 -106.717338)
		(end 306.371498 -109.519974)
		(width 0.1143)
		(layer "F.Cu")
		(net "P3E_CPU0_PE1_PCH_TXN<15>")
	)
	(segment
		(start 309.20309 -115.477544)
		(end 310.706008 -118.63832)
		(width 0.1143)
		(layer "F.Cu")
		(net "P3E_CPU0_PE1_PCH_TXN<15>")
	)
	(via
		(at 311.222136 -119.078502)
		(size 0.508)
		(drill 0.254)
		(layers "F.Cu" "B.Cu")
		(net "P3E_CPU0_PE1_PCH_TXN<15>")
	)
	(arc
		(start 300.729396 -102.662736)
		(mid 300.66993 -102.807201)
		(end 300.650402 -102.962202)
		(width 0.0889)
		(layer "F.Cu")
		(net "P3E_CPU0_PE1_PCH_TXN<15>")
	)
	(arc
		(start 300.756828 -102.320344)
		(mid 300.78167 -102.494622)
		(end 300.729396 -102.662736)
		(width 0.0889)
		(layer "F.Cu")
		(net "P3E_CPU0_PE1_PCH_TXN<15>")
	)
	(segment
		(start 301.55515 -101.242114)
		(end 301.52848 -101.142292)
		(width 0.0889)
		(layer "F.Cu")
		(net "P3E_CPU0_PE1_PCH_TXN<14>")
	)
	(segment
		(start 302.567848 -104.626918)
		(end 301.80661 -103.86568)
		(width 0.0889)
		(layer "F.Cu")
		(net "P3E_CPU0_PE1_PCH_TXN<14>")
	)
	(segment
		(start 301.669958 -103.535734)
		(end 301.669958 -102.90048)
		(width 0.0889)
		(layer "F.Cu")
		(net "P3E_CPU0_PE1_PCH_TXN<14>")
	)
	(segment
		(start 301.669958 -102.90048)
		(end 301.587916 -102.757986)
		(width 0.0889)
		(layer "F.Cu")
		(net "P3E_CPU0_PE1_PCH_TXN<14>")
	)
	(segment
		(start 301.587916 -102.167436)
		(end 301.592742 -102.1588)
		(width 0.0889)
		(layer "F.Cu")
		(net "P3E_CPU0_PE1_PCH_TXN<14>")
	)
	(segment
		(start 324.5485 -123.825)
		(end 324.5485 -123.4313)
		(width 0.1143)
		(layer "F.Cu")
		(net "P3E_CPU0_PE1_PCH_TXN<14>")
	)
	(segment
		(start 322.705984 -123.317)
		(end 322.253864 -122.86488)
		(width 0.1143)
		(layer "F.Cu")
		(net "P3E_CPU0_PE1_PCH_TXN<14>")
	)
	(segment
		(start 307.827172 -109.540548)
		(end 307.826918 -109.540548)
		(width 0.1143)
		(layer "F.Cu")
		(net "P3E_CPU0_PE1_PCH_TXN<14>")
	)
	(segment
		(start 319.565782 -122.86488)
		(end 319.06083 -122.359928)
		(width 0.1143)
		(layer "F.Cu")
		(net "P3E_CPU0_PE1_PCH_TXN<14>")
	)
	(segment
		(start 305.885088 -107.598464)
		(end 305.869594 -107.58297)
		(width 0.0889)
		(layer "F.Cu")
		(net "P3E_CPU0_PE1_PCH_TXN<14>")
	)
	(segment
		(start 319.06083 -122.359928)
		(end 317.232538 -122.359928)
		(width 0.1143)
		(layer "F.Cu")
		(net "P3E_CPU0_PE1_PCH_TXN<14>")
	)
	(segment
		(start 322.253864 -122.86488)
		(end 319.565782 -122.86488)
		(width 0.1143)
		(layer "F.Cu")
		(net "P3E_CPU0_PE1_PCH_TXN<14>")
	)
	(segment
		(start 301.80661 -103.86568)
		(end 301.669958 -103.535734)
		(width 0.0889)
		(layer "F.Cu")
		(net "P3E_CPU0_PE1_PCH_TXN<14>")
	)
	(segment
		(start 301.581566 -102.178104)
		(end 301.587916 -102.167436)
		(width 0.0889)
		(layer "F.Cu")
		(net "P3E_CPU0_PE1_PCH_TXN<14>")
	)
	(segment
		(start 302.94961 -104.626918)
		(end 302.567848 -104.626918)
		(width 0.0889)
		(layer "F.Cu")
		(net "P3E_CPU0_PE1_PCH_TXN<14>")
	)
	(segment
		(start 307.826918 -109.540548)
		(end 305.885088 -107.598464)
		(width 0.1143)
		(layer "F.Cu")
		(net "P3E_CPU0_PE1_PCH_TXN<14>")
	)
	(segment
		(start 312.128154 -118.511828)
		(end 307.827172 -109.540548)
		(width 0.1143)
		(layer "F.Cu")
		(net "P3E_CPU0_PE1_PCH_TXN<14>")
	)
	(segment
		(start 324.4342 -123.317)
		(end 322.705984 -123.317)
		(width 0.1143)
		(layer "F.Cu")
		(net "P3E_CPU0_PE1_PCH_TXN<14>")
	)
	(segment
		(start 314.889388 -120.593612)
		(end 312.128154 -118.511828)
		(width 0.1143)
		(layer "F.Cu")
		(net "P3E_CPU0_PE1_PCH_TXN<14>")
	)
	(segment
		(start 305.869594 -107.547156)
		(end 302.94961 -104.626918)
		(width 0.0889)
		(layer "F.Cu")
		(net "P3E_CPU0_PE1_PCH_TXN<14>")
	)
	(segment
		(start 317.232538 -122.359928)
		(end 314.889388 -120.593612)
		(width 0.1143)
		(layer "F.Cu")
		(net "P3E_CPU0_PE1_PCH_TXN<14>")
	)
	(segment
		(start 324.5485 -123.4313)
		(end 324.4342 -123.317)
		(width 0.1143)
		(layer "F.Cu")
		(net "P3E_CPU0_PE1_PCH_TXN<14>")
	)
	(segment
		(start 301.52848 -101.142292)
		(end 301.241206 -100.976684)
		(width 0.0889)
		(layer "F.Cu")
		(net "P3E_CPU0_PE1_PCH_TXN<14>")
	)
	(segment
		(start 305.869594 -107.58297)
		(end 305.869594 -107.547156)
		(width 0.0889)
		(layer "F.Cu")
		(net "P3E_CPU0_PE1_PCH_TXN<14>")
	)
	(via
		(at 314.889388 -120.593612)
		(size 0.508)
		(drill 0.254)
		(layers "F.Cu" "B.Cu")
		(net "P3E_CPU0_PE1_PCH_TXN<14>")
	)
	(arc
		(start 301.587916 -102.757986)
		(mid 301.508694 -102.468868)
		(end 301.581566 -102.178104)
		(width 0.0889)
		(layer "F.Cu")
		(net "P3E_CPU0_PE1_PCH_TXN<14>")
	)
	(arc
		(start 301.587916 -101.767386)
		(mid 301.510677 -101.519243)
		(end 301.547276 -101.261926)
		(width 0.0889)
		(layer "F.Cu")
		(net "P3E_CPU0_PE1_PCH_TXN<14>")
	)
	(arc
		(start 301.547276 -101.261926)
		(mid 301.551123 -101.251984)
		(end 301.55515 -101.242114)
		(width 0.0889)
		(layer "F.Cu")
		(net "P3E_CPU0_PE1_PCH_TXN<14>")
	)
	(arc
		(start 301.592742 -102.1588)
		(mid 301.641497 -101.962448)
		(end 301.587916 -101.767386)
		(width 0.0889)
		(layer "F.Cu")
		(net "P3E_CPU0_PE1_PCH_TXN<14>")
	)
	(segment
		(start 318.173862 -121.387108)
		(end 317.00724 -120.508014)
		(width 0.1143)
		(layer "F.Cu")
		(net "P3E_CPU0_PE1_PCH_TXN<13>")
	)
	(segment
		(start 324.3707 -121.158)
		(end 322.7959 -121.158)
		(width 0.1143)
		(layer "F.Cu")
		(net "P3E_CPU0_PE1_PCH_TXN<13>")
	)
	(segment
		(start 305.2826 -105.1814)
		(end 308.345332 -108.244132)
		(width 0.1143)
		(layer "F.Cu")
		(net "P3E_CPU0_PE1_PCH_TXN<13>")
	)
	(segment
		(start 305.267106 -105.165906)
		(end 305.2826 -105.1814)
		(width 0.0889)
		(layer "F.Cu")
		(net "P3E_CPU0_PE1_PCH_TXN<13>")
	)
	(segment
		(start 304.861976 -104.724708)
		(end 305.267106 -105.129838)
		(width 0.0889)
		(layer "F.Cu")
		(net "P3E_CPU0_PE1_PCH_TXN<13>")
	)
	(segment
		(start 319.463928 -121.387108)
		(end 318.173862 -121.387108)
		(width 0.1143)
		(layer "F.Cu")
		(net "P3E_CPU0_PE1_PCH_TXN<13>")
	)
	(segment
		(start 302.798226 -103.597456)
		(end 302.959262 -103.597456)
		(width 0.0889)
		(layer "F.Cu")
		(net "P3E_CPU0_PE1_PCH_TXN<13>")
	)
	(segment
		(start 302.099726 -100.481638)
		(end 302.387 -100.31603)
		(width 0.0889)
		(layer "F.Cu")
		(net "P3E_CPU0_PE1_PCH_TXN<13>")
	)
	(segment
		(start 324.5485 -121.3358)
		(end 324.3707 -121.158)
		(width 0.1143)
		(layer "F.Cu")
		(net "P3E_CPU0_PE1_PCH_TXN<13>")
	)
	(segment
		(start 303.55286 -104.191054)
		(end 303.573434 -104.191054)
		(width 0.0889)
		(layer "F.Cu")
		(net "P3E_CPU0_PE1_PCH_TXN<13>")
	)
	(segment
		(start 317.00724 -120.508014)
		(end 317.006986 -120.508014)
		(width 0.1143)
		(layer "F.Cu")
		(net "P3E_CPU0_PE1_PCH_TXN<13>")
	)
	(segment
		(start 317.006986 -120.50776)
		(end 317.006986 -120.508014)
		(width 0.1143)
		(layer "F.Cu")
		(net "P3E_CPU0_PE1_PCH_TXN<13>")
	)
	(segment
		(start 302.51273 -102.345236)
		(end 302.51273 -102.350062)
		(width 0.0889)
		(layer "F.Cu")
		(net "P3E_CPU0_PE1_PCH_TXN<13>")
	)
	(segment
		(start 324.5485 -121.666)
		(end 324.5485 -121.3358)
		(width 0.1143)
		(layer "F.Cu")
		(net "P3E_CPU0_PE1_PCH_TXN<13>")
	)
	(segment
		(start 302.446436 -100.681536)
		(end 302.443134 -100.68687)
		(width 0.0889)
		(layer "F.Cu")
		(net "P3E_CPU0_PE1_PCH_TXN<13>")
	)
	(segment
		(start 312.606182 -117.191282)
		(end 317.006986 -120.50776)
		(width 0.1143)
		(layer "F.Cu")
		(net "P3E_CPU0_PE1_PCH_TXN<13>")
	)
	(segment
		(start 305.267106 -105.129838)
		(end 305.267106 -105.165906)
		(width 0.0889)
		(layer "F.Cu")
		(net "P3E_CPU0_PE1_PCH_TXN<13>")
	)
	(segment
		(start 303.573434 -104.191054)
		(end 304.861976 -104.724708)
		(width 0.0889)
		(layer "F.Cu")
		(net "P3E_CPU0_PE1_PCH_TXN<13>")
	)
	(segment
		(start 302.388778 -102.877112)
		(end 302.388778 -103.188008)
		(width 0.0889)
		(layer "F.Cu")
		(net "P3E_CPU0_PE1_PCH_TXN<13>")
	)
	(segment
		(start 312.575194 -117.13972)
		(end 312.606182 -117.191282)
		(width 0.1143)
		(layer "F.Cu")
		(net "P3E_CPU0_PE1_PCH_TXN<13>")
	)
	(segment
		(start 302.959262 -103.597456)
		(end 303.55286 -104.191054)
		(width 0.0889)
		(layer "F.Cu")
		(net "P3E_CPU0_PE1_PCH_TXN<13>")
	)
	(segment
		(start 322.7959 -121.158)
		(end 322.28536 -121.66854)
		(width 0.1143)
		(layer "F.Cu")
		(net "P3E_CPU0_PE1_PCH_TXN<13>")
	)
	(segment
		(start 322.28536 -121.66854)
		(end 319.74536 -121.66854)
		(width 0.1143)
		(layer "F.Cu")
		(net "P3E_CPU0_PE1_PCH_TXN<13>")
	)
	(segment
		(start 302.387 -100.31603)
		(end 302.473614 -100.339398)
		(width 0.0889)
		(layer "F.Cu")
		(net "P3E_CPU0_PE1_PCH_TXN<13>")
	)
	(segment
		(start 302.388778 -103.188008)
		(end 302.798226 -103.597456)
		(width 0.0889)
		(layer "F.Cu")
		(net "P3E_CPU0_PE1_PCH_TXN<13>")
	)
	(segment
		(start 302.51273 -102.350062)
		(end 302.537114 -102.374446)
		(width 0.0889)
		(layer "F.Cu")
		(net "P3E_CPU0_PE1_PCH_TXN<13>")
	)
	(segment
		(start 319.74536 -121.66854)
		(end 319.463928 -121.387108)
		(width 0.1143)
		(layer "F.Cu")
		(net "P3E_CPU0_PE1_PCH_TXN<13>")
	)
	(segment
		(start 308.345332 -108.244132)
		(end 312.575194 -117.13972)
		(width 0.1143)
		(layer "F.Cu")
		(net "P3E_CPU0_PE1_PCH_TXN<13>")
	)
	(segment
		(start 302.55972 -102.496366)
		(end 302.388778 -102.877112)
		(width 0.0889)
		(layer "F.Cu")
		(net "P3E_CPU0_PE1_PCH_TXN<13>")
	)
	(via
		(at 317.006986 -120.508014)
		(size 0.508)
		(drill 0.254)
		(layers "F.Cu" "B.Cu")
		(net "P3E_CPU0_PE1_PCH_TXN<13>")
	)
	(arc
		(start 302.446436 -101.672136)
		(mid 302.37138 -102.019341)
		(end 302.51273 -102.345236)
		(width 0.0889)
		(layer "F.Cu")
		(net "P3E_CPU0_PE1_PCH_TXN<13>")
	)
	(arc
		(start 302.537114 -102.374446)
		(mid 302.56743 -102.431898)
		(end 302.55972 -102.496366)
		(width 0.0889)
		(layer "F.Cu")
		(net "P3E_CPU0_PE1_PCH_TXN<13>")
	)
	(arc
		(start 302.443134 -100.68687)
		(mid 302.367336 -100.979785)
		(end 302.446436 -101.271832)
		(width 0.0889)
		(layer "F.Cu")
		(net "P3E_CPU0_PE1_PCH_TXN<13>")
	)
	(arc
		(start 302.473614 -100.339398)
		(mid 302.498594 -100.513535)
		(end 302.446436 -100.681536)
		(width 0.0889)
		(layer "F.Cu")
		(net "P3E_CPU0_PE1_PCH_TXN<13>")
	)
	(arc
		(start 302.446436 -101.271832)
		(mid 302.500062 -101.471984)
		(end 302.446436 -101.672136)
		(width 0.0889)
		(layer "F.Cu")
		(net "P3E_CPU0_PE1_PCH_TXN<13>")
	)
	(segment
		(start 306.239926 -104.258872)
		(end 306.255674 -104.27462)
		(width 0.0889)
		(layer "F.Cu")
		(net "P3E_CPU0_PE1_PCH_TXN<12>")
	)
	(segment
		(start 304.812192 -102.79507)
		(end 304.812192 -102.9208)
		(width 0.0889)
		(layer "F.Cu")
		(net "P3E_CPU0_PE1_PCH_TXN<12>")
	)
	(segment
		(start 302.940466 -99.586288)
		(end 302.973232 -99.586288)
		(width 0.0889)
		(layer "F.Cu")
		(net "P3E_CPU0_PE1_PCH_TXN<12>")
	)
	(segment
		(start 305.818032 -103.80091)
		(end 305.818032 -103.92664)
		(width 0.0889)
		(layer "F.Cu")
		(net "P3E_CPU0_PE1_PCH_TXN<12>")
	)
	(segment
		(start 306.239926 -104.222804)
		(end 306.239926 -104.258872)
		(width 0.0889)
		(layer "F.Cu")
		(net "P3E_CPU0_PE1_PCH_TXN<12>")
	)
	(segment
		(start 306.132484 -104.115362)
		(end 306.239926 -104.222804)
		(width 0.0889)
		(layer "F.Cu")
		(net "P3E_CPU0_PE1_PCH_TXN<12>")
	)
	(segment
		(start 321.16522 -120.53316)
		(end 321.16522 -120.212612)
		(width 0.1143)
		(layer "F.Cu")
		(net "P3E_CPU0_PE1_PCH_TXN<12>")
	)
	(segment
		(start 302.099726 -99.490784)
		(end 302.184308 -99.19462)
		(width 0.0889)
		(layer "F.Cu")
		(net "P3E_CPU0_PE1_PCH_TXN<12>")
	)
	(segment
		(start 302.184308 -99.19462)
		(end 302.186594 -99.193858)
		(width 0.0889)
		(layer "F.Cu")
		(net "P3E_CPU0_PE1_PCH_TXN<12>")
	)
	(segment
		(start 303.2506 -101.270308)
		(end 303.2506 -101.715316)
		(width 0.0889)
		(layer "F.Cu")
		(net "P3E_CPU0_PE1_PCH_TXN<12>")
	)
	(segment
		(start 303.309782 -100.1776)
		(end 303.304956 -100.186236)
		(width 0.0889)
		(layer "F.Cu")
		(net "P3E_CPU0_PE1_PCH_TXN<12>")
	)
	(segment
		(start 304.163222 -102.262178)
		(end 304.163476 -102.262686)
		(width 0.0889)
		(layer "F.Cu")
		(net "P3E_CPU0_PE1_PCH_TXN<12>")
	)
	(segment
		(start 304.163476 -102.262686)
		(end 304.284634 -102.472744)
		(width 0.0889)
		(layer "F.Cu")
		(net "P3E_CPU0_PE1_PCH_TXN<12>")
	)
	(segment
		(start 313.262518 -116.153438)
		(end 314.752736 -117.151658)
		(width 0.1143)
		(layer "F.Cu")
		(net "P3E_CPU0_PE1_PCH_TXN<12>")
	)
	(segment
		(start 321.16522 -120.212612)
		(end 320.999612 -120.047004)
		(width 0.1143)
		(layer "F.Cu")
		(net "P3E_CPU0_PE1_PCH_TXN<12>")
	)
	(segment
		(start 305.126644 -103.109522)
		(end 305.315112 -103.29799)
		(width 0.0889)
		(layer "F.Cu")
		(net "P3E_CPU0_PE1_PCH_TXN<12>")
	)
	(segment
		(start 308.711346 -106.7308)
		(end 313.262518 -116.153438)
		(width 0.1143)
		(layer "F.Cu")
		(net "P3E_CPU0_PE1_PCH_TXN<12>")
	)
	(segment
		(start 306.255674 -104.27462)
		(end 308.711346 -106.7308)
		(width 0.1143)
		(layer "F.Cu")
		(net "P3E_CPU0_PE1_PCH_TXN<12>")
	)
	(segment
		(start 305.818032 -103.92664)
		(end 306.006754 -104.115362)
		(width 0.0889)
		(layer "F.Cu")
		(net "P3E_CPU0_PE1_PCH_TXN<12>")
	)
	(segment
		(start 303.298606 -100.766118)
		(end 303.304956 -100.776786)
		(width 0.0889)
		(layer "F.Cu")
		(net "P3E_CPU0_PE1_PCH_TXN<12>")
	)
	(segment
		(start 303.304956 -101.176582)
		(end 303.2506 -101.270308)
		(width 0.0889)
		(layer "F.Cu")
		(net "P3E_CPU0_PE1_PCH_TXN<12>")
	)
	(segment
		(start 305.315112 -103.29799)
		(end 305.315112 -103.42372)
		(width 0.0889)
		(layer "F.Cu")
		(net "P3E_CPU0_PE1_PCH_TXN<12>")
	)
	(segment
		(start 305.629564 -103.612442)
		(end 305.818032 -103.80091)
		(width 0.0889)
		(layer "F.Cu")
		(net "P3E_CPU0_PE1_PCH_TXN<12>")
	)
	(segment
		(start 303.2506 -101.715316)
		(end 303.622964 -102.08768)
		(width 0.0889)
		(layer "F.Cu")
		(net "P3E_CPU0_PE1_PCH_TXN<12>")
	)
	(segment
		(start 303.98847 -102.08768)
		(end 304.163222 -102.262178)
		(width 0.0889)
		(layer "F.Cu")
		(net "P3E_CPU0_PE1_PCH_TXN<12>")
	)
	(segment
		(start 304.567336 -102.59695)
		(end 304.623724 -102.606602)
		(width 0.0889)
		(layer "F.Cu")
		(net "P3E_CPU0_PE1_PCH_TXN<12>")
	)
	(segment
		(start 314.752736 -117.151912)
		(end 314.752736 -117.151658)
		(width 0.1143)
		(layer "F.Cu")
		(net "P3E_CPU0_PE1_PCH_TXN<12>")
	)
	(segment
		(start 305.315112 -103.42372)
		(end 305.503834 -103.612442)
		(width 0.0889)
		(layer "F.Cu")
		(net "P3E_CPU0_PE1_PCH_TXN<12>")
	)
	(segment
		(start 305.503834 -103.612442)
		(end 305.629564 -103.612442)
		(width 0.0889)
		(layer "F.Cu")
		(net "P3E_CPU0_PE1_PCH_TXN<12>")
	)
	(segment
		(start 304.812192 -102.9208)
		(end 305.000914 -103.109522)
		(width 0.0889)
		(layer "F.Cu")
		(net "P3E_CPU0_PE1_PCH_TXN<12>")
	)
	(segment
		(start 304.623724 -102.606602)
		(end 304.812192 -102.79507)
		(width 0.0889)
		(layer "F.Cu")
		(net "P3E_CPU0_PE1_PCH_TXN<12>")
	)
	(segment
		(start 305.000914 -103.109522)
		(end 305.126644 -103.109522)
		(width 0.0889)
		(layer "F.Cu")
		(net "P3E_CPU0_PE1_PCH_TXN<12>")
	)
	(segment
		(start 303.622964 -102.08768)
		(end 303.98847 -102.08768)
		(width 0.0889)
		(layer "F.Cu")
		(net "P3E_CPU0_PE1_PCH_TXN<12>")
	)
	(segment
		(start 320.999612 -120.047004)
		(end 319.074546 -120.047004)
		(width 0.1143)
		(layer "F.Cu")
		(net "P3E_CPU0_PE1_PCH_TXN<12>")
	)
	(segment
		(start 319.074546 -120.047004)
		(end 314.752736 -117.151912)
		(width 0.1143)
		(layer "F.Cu")
		(net "P3E_CPU0_PE1_PCH_TXN<12>")
	)
	(segment
		(start 306.006754 -104.115362)
		(end 306.132484 -104.115362)
		(width 0.0889)
		(layer "F.Cu")
		(net "P3E_CPU0_PE1_PCH_TXN<12>")
	)
	(via
		(at 314.752736 -117.151658)
		(size 0.508)
		(drill 0.254)
		(layers "F.Cu" "B.Cu")
		(net "P3E_CPU0_PE1_PCH_TXN<12>")
	)
	(arc
		(start 302.973232 -99.586288)
		(mid 303.30615 -99.788279)
		(end 303.309782 -100.1776)
		(width 0.0889)
		(layer "F.Cu")
		(net "P3E_CPU0_PE1_PCH_TXN<12>")
	)
	(arc
		(start 303.304956 -100.776786)
		(mid 303.358455 -100.976684)
		(end 303.304956 -101.176582)
		(width 0.0889)
		(layer "F.Cu")
		(net "P3E_CPU0_PE1_PCH_TXN<12>")
	)
	(arc
		(start 303.304956 -100.186236)
		(mid 303.225734 -100.475354)
		(end 303.298606 -100.766118)
		(width 0.0889)
		(layer "F.Cu")
		(net "P3E_CPU0_PE1_PCH_TXN<12>")
	)
	(arc
		(start 302.446436 -99.290886)
		(mid 302.655044 -99.502818)
		(end 302.940466 -99.586288)
		(width 0.0889)
		(layer "F.Cu")
		(net "P3E_CPU0_PE1_PCH_TXN<12>")
	)
	(arc
		(start 304.284634 -102.472744)
		(mid 304.304301 -102.48735)
		(end 304.324512 -102.501192)
		(width 0.0889)
		(layer "F.Cu")
		(net "P3E_CPU0_PE1_PCH_TXN<12>")
	)
	(arc
		(start 304.324512 -102.501192)
		(mid 304.440985 -102.561593)
		(end 304.567336 -102.59695)
		(width 0.0889)
		(layer "F.Cu")
		(net "P3E_CPU0_PE1_PCH_TXN<12>")
	)
	(arc
		(start 302.186594 -99.193858)
		(mid 302.333966 -99.1957)
		(end 302.446436 -99.290886)
		(width 0.0889)
		(layer "F.Cu")
		(net "P3E_CPU0_PE1_PCH_TXN<12>")
	)
	(segment
		(start 303.24552 -99.161346)
		(end 302.958246 -98.995738)
		(width 0.0889)
		(layer "F.Cu")
		(net "P3E_CPU0_PE1_PCH_TXN<11>")
	)
	(segment
		(start 320.130424 -118.1862)
		(end 320.599308 -117.717316)
		(width 0.1143)
		(layer "F.Cu")
		(net "P3E_CPU0_PE1_PCH_TXN<11>")
	)
	(segment
		(start 309.17769 -104.973374)
		(end 309.020972 -104.66832)
		(width 0.1143)
		(layer "F.Cu")
		(net "P3E_CPU0_PE1_PCH_TXN<11>")
	)
	(segment
		(start 319.016126 -117.583204)
		(end 319.619122 -118.1862)
		(width 0.1143)
		(layer "F.Cu")
		(net "P3E_CPU0_PE1_PCH_TXN<11>")
	)
	(segment
		(start 305.771042 -100.909882)
		(end 305.582066 -100.909882)
		(width 0.0889)
		(layer "F.Cu")
		(net "P3E_CPU0_PE1_PCH_TXN<11>")
	)
	(segment
		(start 303.834546 -98.900234)
		(end 303.798986 -98.900234)
		(width 0.0889)
		(layer "F.Cu")
		(net "P3E_CPU0_PE1_PCH_TXN<11>")
	)
	(segment
		(start 323.0245 -117.564916)
		(end 323.0245 -117.222016)
		(width 0.1143)
		(layer "F.Cu")
		(net "P3E_CPU0_PE1_PCH_TXN<11>")
	)
	(segment
		(start 320.599308 -117.717316)
		(end 322.8721 -117.717316)
		(width 0.1143)
		(layer "F.Cu")
		(net "P3E_CPU0_PE1_PCH_TXN<11>")
	)
	(segment
		(start 309.439056 -105.481628)
		(end 309.488332 -105.327704)
		(width 0.1143)
		(layer "F.Cu")
		(net "P3E_CPU0_PE1_PCH_TXN<11>")
	)
	(segment
		(start 317.114428 -115.854734)
		(end 313.548776 -113.47704)
		(width 0.1143)
		(layer "F.Cu")
		(net "P3E_CPU0_PE1_PCH_TXN<11>")
	)
	(segment
		(start 319.016126 -117.583204)
		(end 317.634112 -116.200936)
		(width 0.1143)
		(layer "F.Cu")
		(net "P3E_CPU0_PE1_PCH_TXN<11>")
	)
	(segment
		(start 309.331614 -105.02265)
		(end 309.17769 -104.973374)
		(width 0.1143)
		(layer "F.Cu")
		(net "P3E_CPU0_PE1_PCH_TXN<11>")
	)
	(segment
		(start 304.701702 -100.386388)
		(end 304.66284 -100.386388)
		(width 0.0889)
		(layer "F.Cu")
		(net "P3E_CPU0_PE1_PCH_TXN<11>")
	)
	(segment
		(start 322.8721 -117.717316)
		(end 323.0245 -117.564916)
		(width 0.1143)
		(layer "F.Cu")
		(net "P3E_CPU0_PE1_PCH_TXN<11>")
	)
	(segment
		(start 317.634112 -116.200936)
		(end 317.114428 -115.854734)
		(width 0.1143)
		(layer "F.Cu")
		(net "P3E_CPU0_PE1_PCH_TXN<11>")
	)
	(segment
		(start 306.1843 -101.867208)
		(end 306.1843 -101.32314)
		(width 0.0889)
		(layer "F.Cu")
		(net "P3E_CPU0_PE1_PCH_TXN<11>")
	)
	(segment
		(start 304.66284 -100.386388)
		(end 304.657252 -100.386134)
		(width 0.0889)
		(layer "F.Cu")
		(net "P3E_CPU0_PE1_PCH_TXN<11>")
	)
	(segment
		(start 308.527704 -104.175052)
		(end 308.492144 -104.175052)
		(width 0.0889)
		(layer "F.Cu")
		(net "P3E_CPU0_PE1_PCH_TXN<11>")
	)
	(segment
		(start 308.492144 -104.175052)
		(end 306.1843 -101.867208)
		(width 0.0889)
		(layer "F.Cu")
		(net "P3E_CPU0_PE1_PCH_TXN<11>")
	)
	(segment
		(start 309.488332 -105.327704)
		(end 309.331614 -105.02265)
		(width 0.1143)
		(layer "F.Cu")
		(net "P3E_CPU0_PE1_PCH_TXN<11>")
	)
	(segment
		(start 309.020972 -104.66832)
		(end 308.543198 -104.190546)
		(width 0.1143)
		(layer "F.Cu")
		(net "P3E_CPU0_PE1_PCH_TXN<11>")
	)
	(segment
		(start 306.1843 -101.32314)
		(end 305.771042 -100.909882)
		(width 0.0889)
		(layer "F.Cu")
		(net "P3E_CPU0_PE1_PCH_TXN<11>")
	)
	(segment
		(start 308.543198 -104.190546)
		(end 308.527704 -104.175052)
		(width 0.0889)
		(layer "F.Cu")
		(net "P3E_CPU0_PE1_PCH_TXN<11>")
	)
	(segment
		(start 313.548776 -113.47704)
		(end 309.439056 -105.481628)
		(width 0.1143)
		(layer "F.Cu")
		(net "P3E_CPU0_PE1_PCH_TXN<11>")
	)
	(segment
		(start 319.619122 -118.1862)
		(end 320.130424 -118.1862)
		(width 0.1143)
		(layer "F.Cu")
		(net "P3E_CPU0_PE1_PCH_TXN<11>")
	)
	(segment
		(start 303.345342 -99.134422)
		(end 303.24552 -99.161346)
		(width 0.0889)
		(layer "F.Cu")
		(net "P3E_CPU0_PE1_PCH_TXN<11>")
	)
	(via
		(at 319.016126 -117.583204)
		(size 0.508)
		(drill 0.254)
		(layers "F.Cu" "B.Cu")
		(net "P3E_CPU0_PE1_PCH_TXN<11>")
	)
	(arc
		(start 305.187096 -100.681536)
		(mid 304.982187 -100.471834)
		(end 304.701702 -100.386388)
		(width 0.0889)
		(layer "F.Cu")
		(net "P3E_CPU0_PE1_PCH_TXN<11>")
	)
	(arc
		(start 303.798986 -98.900234)
		(mid 303.554889 -98.961175)
		(end 303.358296 -99.118166)
		(width 0.0889)
		(layer "F.Cu")
		(net "P3E_CPU0_PE1_PCH_TXN<11>")
	)
	(arc
		(start 305.582066 -100.909882)
		(mid 305.353989 -100.848627)
		(end 305.187096 -100.681536)
		(width 0.0889)
		(layer "F.Cu")
		(net "P3E_CPU0_PE1_PCH_TXN<11>")
	)
	(arc
		(start 304.328576 -99.786186)
		(mid 304.332905 -99.203014)
		(end 303.834546 -98.900234)
		(width 0.0889)
		(layer "F.Cu")
		(net "P3E_CPU0_PE1_PCH_TXN<11>")
	)
	(arc
		(start 303.358296 -99.118166)
		(mid 303.351748 -99.126237)
		(end 303.345342 -99.134422)
		(width 0.0889)
		(layer "F.Cu")
		(net "P3E_CPU0_PE1_PCH_TXN<11>")
	)
	(arc
		(start 304.657252 -100.386134)
		(mid 304.324283 -100.178586)
		(end 304.328576 -99.786186)
		(width 0.0889)
		(layer "F.Cu")
		(net "P3E_CPU0_PE1_PCH_TXN<11>")
	)
	(segment
		(start 306.970684 -101.496622)
		(end 307.096668 -101.496622)
		(width 0.0889)
		(layer "F.Cu")
		(net "P3E_CPU0_PE1_PCH_TXN<10>")
	)
	(segment
		(start 306.781962 -101.18217)
		(end 306.781962 -101.3079)
		(width 0.0889)
		(layer "F.Cu")
		(net "P3E_CPU0_PE1_PCH_TXN<10>")
	)
	(segment
		(start 309.836566 -104.272842)
		(end 312.231278 -109.308646)
		(width 0.1143)
		(layer "F.Cu")
		(net "P3E_CPU0_PE1_PCH_TXN<10>")
	)
	(segment
		(start 329.598782 -120.31472)
		(end 331.297026 -120.31472)
		(width 0.1143)
		(layer "F.Cu")
		(net "P3E_CPU0_PE1_PCH_TXN<10>")
	)
	(segment
		(start 304.675286 -99.986338)
		(end 304.675286 -99.654614)
		(width 0.0889)
		(layer "F.Cu")
		(net "P3E_CPU0_PE1_PCH_TXN<10>")
	)
	(segment
		(start 327.235566 -117.951504)
		(end 329.598782 -120.31472)
		(width 0.1143)
		(layer "F.Cu")
		(net "P3E_CPU0_PE1_PCH_TXN<10>")
	)
	(segment
		(start 304.675286 -99.654614)
		(end 304.738786 -99.591114)
		(width 0.0889)
		(layer "F.Cu")
		(net "P3E_CPU0_PE1_PCH_TXN<10>")
	)
	(segment
		(start 331.77734 -120.795034)
		(end 337.241896 -120.795034)
		(width 0.1143)
		(layer "F.Cu")
		(net "P3E_CPU0_PE1_PCH_TXN<10>")
	)
	(segment
		(start 307.096668 -101.496622)
		(end 307.690774 -102.090728)
		(width 0.0889)
		(layer "F.Cu")
		(net "P3E_CPU0_PE1_PCH_TXN<10>")
	)
	(segment
		(start 320.23431 -114.635026)
		(end 321.568318 -115.522756)
		(width 0.1143)
		(layer "F.Cu")
		(net "P3E_CPU0_PE1_PCH_TXN<10>")
	)
	(segment
		(start 306.279042 -100.80498)
		(end 306.467764 -100.993702)
		(width 0.0889)
		(layer "F.Cu")
		(net "P3E_CPU0_PE1_PCH_TXN<10>")
	)
	(segment
		(start 306.467764 -100.993702)
		(end 306.593494 -100.993702)
		(width 0.0889)
		(layer "F.Cu")
		(net "P3E_CPU0_PE1_PCH_TXN<10>")
	)
	(segment
		(start 307.690774 -102.126542)
		(end 307.698902 -102.13467)
		(width 0.0889)
		(layer "F.Cu")
		(net "P3E_CPU0_PE1_PCH_TXN<10>")
	)
	(segment
		(start 306.593494 -100.993702)
		(end 306.781962 -101.18217)
		(width 0.0889)
		(layer "F.Cu")
		(net "P3E_CPU0_PE1_PCH_TXN<10>")
	)
	(segment
		(start 337.404202 -120.95734)
		(end 337.404202 -121.282968)
		(width 0.1143)
		(layer "F.Cu")
		(net "P3E_CPU0_PE1_PCH_TXN<10>")
	)
	(segment
		(start 306.279042 -100.679504)
		(end 306.279042 -100.80498)
		(width 0.0889)
		(layer "F.Cu")
		(net "P3E_CPU0_PE1_PCH_TXN<10>")
	)
	(segment
		(start 321.568318 -115.522756)
		(end 323.305932 -115.522756)
		(width 0.1143)
		(layer "F.Cu")
		(net "P3E_CPU0_PE1_PCH_TXN<10>")
	)
	(segment
		(start 312.231278 -109.308646)
		(end 320.23431 -114.635026)
		(width 0.1143)
		(layer "F.Cu")
		(net "P3E_CPU0_PE1_PCH_TXN<10>")
	)
	(segment
		(start 337.241896 -120.795034)
		(end 337.404202 -120.95734)
		(width 0.1143)
		(layer "F.Cu")
		(net "P3E_CPU0_PE1_PCH_TXN<10>")
	)
	(segment
		(start 305.520852 -100.081588)
		(end 305.521106 -100.081334)
		(width 0.0889)
		(layer "F.Cu")
		(net "P3E_CPU0_PE1_PCH_TXN<10>")
	)
	(segment
		(start 325.73468 -117.951504)
		(end 327.235566 -117.951504)
		(width 0.1143)
		(layer "F.Cu")
		(net "P3E_CPU0_PE1_PCH_TXN<10>")
	)
	(segment
		(start 323.305932 -115.522756)
		(end 325.73468 -117.951504)
		(width 0.1143)
		(layer "F.Cu")
		(net "P3E_CPU0_PE1_PCH_TXN<10>")
	)
	(segment
		(start 331.297026 -120.31472)
		(end 331.77734 -120.795034)
		(width 0.1143)
		(layer "F.Cu")
		(net "P3E_CPU0_PE1_PCH_TXN<10>")
	)
	(segment
		(start 305.521106 -100.081334)
		(end 305.542696 -100.081334)
		(width 0.0889)
		(layer "F.Cu")
		(net "P3E_CPU0_PE1_PCH_TXN<10>")
	)
	(segment
		(start 305.781202 -100.181664)
		(end 306.279042 -100.679504)
		(width 0.0889)
		(layer "F.Cu")
		(net "P3E_CPU0_PE1_PCH_TXN<10>")
	)
	(segment
		(start 307.690774 -102.090728)
		(end 307.690774 -102.126542)
		(width 0.0889)
		(layer "F.Cu")
		(net "P3E_CPU0_PE1_PCH_TXN<10>")
	)
	(segment
		(start 307.698902 -102.13467)
		(end 309.836566 -104.272842)
		(width 0.1143)
		(layer "F.Cu")
		(net "P3E_CPU0_PE1_PCH_TXN<10>")
	)
	(segment
		(start 306.781962 -101.3079)
		(end 306.970684 -101.496622)
		(width 0.0889)
		(layer "F.Cu")
		(net "P3E_CPU0_PE1_PCH_TXN<10>")
	)
	(via
		(at 320.23431 -114.635026)
		(size 0.508)
		(drill 0.254)
		(layers "F.Cu" "B.Cu")
		(net "P3E_CPU0_PE1_PCH_TXN<10>")
	)
	(arc
		(start 304.738786 -99.591114)
		(mid 304.902389 -99.656704)
		(end 305.021996 -99.786186)
		(width 0.0889)
		(layer "F.Cu")
		(net "P3E_CPU0_PE1_PCH_TXN<10>")
	)
	(arc
		(start 305.021996 -99.786186)
		(mid 305.232709 -99.999265)
		(end 305.520852 -100.081588)
		(width 0.0889)
		(layer "F.Cu")
		(net "P3E_CPU0_PE1_PCH_TXN<10>")
	)
	(arc
		(start 305.576732 -100.08362)
		(mid 305.687358 -100.115146)
		(end 305.781202 -100.181664)
		(width 0.0889)
		(layer "F.Cu")
		(net "P3E_CPU0_PE1_PCH_TXN<10>")
	)
	(arc
		(start 305.542696 -100.081334)
		(mid 305.559738 -100.082119)
		(end 305.576732 -100.08362)
		(width 0.0889)
		(layer "F.Cu")
		(net "P3E_CPU0_PE1_PCH_TXN<10>")
	)
	(segment
		(start 375.504964 -114.85499)
		(end 375.013982 -114.659664)
		(width 0.0889)
		(layer "F.Cu")
		(net "P3E_CPU0_PE1_PCH_TXN<0>")
	)
	(segment
		(start 374.798336 -114.511836)
		(end 374.100598 -114.511836)
		(width 0.0889)
		(layer "F.Cu")
		(net "P3E_CPU0_PE1_PCH_TXN<0>")
	)
	(segment
		(start 374.100598 -114.511836)
		(end 373.888 -114.299238)
		(width 0.0889)
		(layer "F.Cu")
		(net "P3E_CPU0_PE1_PCH_TXN<0>")
	)
	(segment
		(start 374.930162 -114.643662)
		(end 374.798336 -114.511836)
		(width 0.0889)
		(layer "F.Cu")
		(net "P3E_CPU0_PE1_PCH_TXN<0>")
	)
	(segment
		(start 375.013982 -114.659664)
		(end 374.930162 -114.643662)
		(width 0.0889)
		(layer "F.Cu")
		(net "P3E_CPU0_PE1_PCH_TXN<0>")
	)
	(via
		(at 340.70925 -79.92745)
		(size 0.508)
		(drill 0.254)
		(layers "F.Cu" "B.Cu")
		(net "P3E_CPU0_PE1_PCH_TXN<0>")
	)
	(via
		(at 373.888 -114.299238)
		(size 0.508)
		(drill 0.254)
		(layers "F.Cu" "B.Cu")
		(net "P3E_CPU0_PE1_PCH_TXN<0>")
	)
	(segment
		(start 340.16696 -79.04734)
		(end 340.16696 -78.583536)
		(width 0.1143)
		(layer "B.Cu")
		(net "P3E_CPU0_PE1_PCH_TXN<0>")
	)
	(segment
		(start 340.594696 -80.47228)
		(end 340.11362 -80.47228)
		(width 0.1143)
		(layer "B.Cu")
		(net "P3E_CPU0_PE1_PCH_TXN<0>")
	)
	(segment
		(start 340.05266 -79.16164)
		(end 340.16696 -79.04734)
		(width 0.1143)
		(layer "B.Cu")
		(net "P3E_CPU0_PE1_PCH_TXN<0>")
	)
	(segment
		(start 339.5726 -79.93126)
		(end 339.5726 -79.2861)
		(width 0.1143)
		(layer "B.Cu")
		(net "P3E_CPU0_PE1_PCH_TXN<0>")
	)
	(segment
		(start 340.11362 -80.47228)
		(end 339.5726 -79.93126)
		(width 0.1143)
		(layer "B.Cu")
		(net "P3E_CPU0_PE1_PCH_TXN<0>")
	)
	(segment
		(start 340.70925 -80.357726)
		(end 340.594696 -80.47228)
		(width 0.1143)
		(layer "B.Cu")
		(net "P3E_CPU0_PE1_PCH_TXN<0>")
	)
	(segment
		(start 339.69706 -79.16164)
		(end 340.05266 -79.16164)
		(width 0.1143)
		(layer "B.Cu")
		(net "P3E_CPU0_PE1_PCH_TXN<0>")
	)
	(segment
		(start 339.5726 -79.2861)
		(end 339.69706 -79.16164)
		(width 0.1143)
		(layer "B.Cu")
		(net "P3E_CPU0_PE1_PCH_TXN<0>")
	)
	(segment
		(start 340.70925 -79.92745)
		(end 340.70925 -80.357726)
		(width 0.1143)
		(layer "B.Cu")
		(net "P3E_CPU0_PE1_PCH_TXN<0>")
	)
	(segment
		(start 359.29062 -73.097644)
		(end 358.803194 -73.194164)
		(width 0.1143)
		(layer "In4.Cu")
		(net "P3E_CPU0_PE1_PCH_TXN<0>")
	)
	(segment
		(start 369.68684 -94.419928)
		(end 368.146584 -92.158058)
		(width 0.1143)
		(layer "In4.Cu")
		(net "P3E_CPU0_PE1_PCH_TXN<0>")
	)
	(segment
		(start 343.26322 -75.335384)
		(end 341.897462 -75.335384)
		(width 0.1143)
		(layer "In4.Cu")
		(net "P3E_CPU0_PE1_PCH_TXN<0>")
	)
	(segment
		(start 371.42039 -105.026206)
		(end 370.431568 -102.082346)
		(width 0.1143)
		(layer "In4.Cu")
		(net "P3E_CPU0_PE1_PCH_TXN<0>")
	)
	(segment
		(start 340.82355 -80.4164)
		(end 340.70925 -80.3021)
		(width 0.1143)
		(layer "In4.Cu")
		(net "P3E_CPU0_PE1_PCH_TXN<0>")
	)
	(segment
		(start 375.526046 -109.838744)
		(end 375.419112 -109.404658)
		(width 0.1143)
		(layer "In4.Cu")
		(net "P3E_CPU0_PE1_PCH_TXN<0>")
	)
	(segment
		(start 357.30815 -73.095358)
		(end 356.809548 -73.194418)
		(width 0.1143)
		(layer "In4.Cu")
		(net "P3E_CPU0_PE1_PCH_TXN<0>")
	)
	(segment
		(start 364.455202 -79.539084)
		(end 364.047278 -77.478636)
		(width 0.1143)
		(layer "In4.Cu")
		(net "P3E_CPU0_PE1_PCH_TXN<0>")
	)
	(segment
		(start 359.78973 -73.19645)
		(end 359.29062 -73.097644)
		(width 0.1143)
		(layer "In4.Cu")
		(net "P3E_CPU0_PE1_PCH_TXN<0>")
	)
	(segment
		(start 369.71732 -99.20478)
		(end 369.555014 -98.406712)
		(width 0.1143)
		(layer "In4.Cu")
		(net "P3E_CPU0_PE1_PCH_TXN<0>")
	)
	(segment
		(start 340.70925 -80.3021)
		(end 340.70925 -79.92745)
		(width 0.1143)
		(layer "In4.Cu")
		(net "P3E_CPU0_PE1_PCH_TXN<0>")
	)
	(segment
		(start 369.720622 -96.071944)
		(end 369.452652 -95.565722)
		(width 0.1143)
		(layer "In4.Cu")
		(net "P3E_CPU0_PE1_PCH_TXN<0>")
	)
	(segment
		(start 369.65509 -101.130862)
		(end 369.496848 -100.320348)
		(width 0.1143)
		(layer "In4.Cu")
		(net "P3E_CPU0_PE1_PCH_TXN<0>")
	)
	(segment
		(start 366.350296 -89.519506)
		(end 366.036098 -88.100408)
		(width 0.1143)
		(layer "In4.Cu")
		(net "P3E_CPU0_PE1_PCH_TXN<0>")
	)
	(segment
		(start 369.640104 -97.98939)
		(end 369.485164 -97.22866)
		(width 0.1143)
		(layer "In4.Cu")
		(net "P3E_CPU0_PE1_PCH_TXN<0>")
	)
	(segment
		(start 368.146584 -92.158058)
		(end 368.146584 -92.157804)
		(width 0.1143)
		(layer "In4.Cu")
		(net "P3E_CPU0_PE1_PCH_TXN<0>")
	)
	(segment
		(start 355.838506 -73.199244)
		(end 355.315012 -73.095866)
		(width 0.1143)
		(layer "In4.Cu")
		(net "P3E_CPU0_PE1_PCH_TXN<0>")
	)
	(segment
		(start 364.455456 -79.539592)
		(end 364.455202 -79.539084)
		(width 0.1143)
		(layer "In4.Cu")
		(net "P3E_CPU0_PE1_PCH_TXN<0>")
	)
	(segment
		(start 355.315012 -73.095866)
		(end 354.816664 -73.194164)
		(width 0.1143)
		(layer "In4.Cu")
		(net "P3E_CPU0_PE1_PCH_TXN<0>")
	)
	(segment
		(start 358.292146 -73.093072)
		(end 357.794814 -73.191624)
		(width 0.1143)
		(layer "In4.Cu")
		(net "P3E_CPU0_PE1_PCH_TXN<0>")
	)
	(segment
		(start 375.40946 -111.11103)
		(end 375.269506 -110.61446)
		(width 0.1143)
		(layer "In4.Cu")
		(net "P3E_CPU0_PE1_PCH_TXN<0>")
	)
	(segment
		(start 360.297984 -73.095866)
		(end 359.78973 -73.19645)
		(width 0.1143)
		(layer "In4.Cu")
		(net "P3E_CPU0_PE1_PCH_TXN<0>")
	)
	(segment
		(start 364.87481 -80.101948)
		(end 364.455456 -79.539592)
		(width 0.1143)
		(layer "In4.Cu")
		(net "P3E_CPU0_PE1_PCH_TXN<0>")
	)
	(segment
		(start 374.654572 -106.239564)
		(end 373.54637 -105.889298)
		(width 0.1143)
		(layer "In4.Cu")
		(net "P3E_CPU0_PE1_PCH_TXN<0>")
	)
	(segment
		(start 350.814894 -72.79767)
		(end 344.230706 -74.809858)
		(width 0.1143)
		(layer "In4.Cu")
		(net "P3E_CPU0_PE1_PCH_TXN<0>")
	)
	(segment
		(start 375.525792 -109.838744)
		(end 375.526046 -109.838744)
		(width 0.1143)
		(layer "In4.Cu")
		(net "P3E_CPU0_PE1_PCH_TXN<0>")
	)
	(segment
		(start 364.047278 -77.478636)
		(end 364.256828 -76.420726)
		(width 0.1143)
		(layer "In4.Cu")
		(net "P3E_CPU0_PE1_PCH_TXN<0>")
	)
	(segment
		(start 372.858538 -106.022902)
		(end 372.361714 -105.838244)
		(width 0.1143)
		(layer "In4.Cu")
		(net "P3E_CPU0_PE1_PCH_TXN<0>")
	)
	(segment
		(start 356.809548 -73.194418)
		(end 356.809294 -73.194418)
		(width 0.1143)
		(layer "In4.Cu")
		(net "P3E_CPU0_PE1_PCH_TXN<0>")
	)
	(segment
		(start 375.269506 -110.61446)
		(end 375.525792 -109.838744)
		(width 0.1143)
		(layer "In4.Cu")
		(net "P3E_CPU0_PE1_PCH_TXN<0>")
	)
	(segment
		(start 373.70385 -114.115088)
		(end 373.70385 -113.35385)
		(width 0.1143)
		(layer "In4.Cu")
		(net "P3E_CPU0_PE1_PCH_TXN<0>")
	)
	(segment
		(start 356.337108 -73.1012)
		(end 355.838506 -73.199244)
		(width 0.1143)
		(layer "In4.Cu")
		(net "P3E_CPU0_PE1_PCH_TXN<0>")
	)
	(segment
		(start 369.555014 -98.406712)
		(end 369.640104 -97.98939)
		(width 0.1143)
		(layer "In4.Cu")
		(net "P3E_CPU0_PE1_PCH_TXN<0>")
	)
	(segment
		(start 370.431568 -102.082346)
		(end 369.65509 -101.130862)
		(width 0.1143)
		(layer "In4.Cu")
		(net "P3E_CPU0_PE1_PCH_TXN<0>")
	)
	(segment
		(start 341.4649 -80.1751)
		(end 341.2236 -80.4164)
		(width 0.1143)
		(layer "In4.Cu")
		(net "P3E_CPU0_PE1_PCH_TXN<0>")
	)
	(segment
		(start 375.418604 -109.404658)
		(end 375.540524 -109.053376)
		(width 0.1143)
		(layer "In4.Cu")
		(net "P3E_CPU0_PE1_PCH_TXN<0>")
	)
	(segment
		(start 354.29571 -73.09104)
		(end 353.812856 -73.186544)
		(width 0.1143)
		(layer "In4.Cu")
		(net "P3E_CPU0_PE1_PCH_TXN<0>")
	)
	(segment
		(start 363.497114 -74.54265)
		(end 362.010452 -73.434448)
		(width 0.1143)
		(layer "In4.Cu")
		(net "P3E_CPU0_PE1_PCH_TXN<0>")
	)
	(segment
		(start 353.336352 -73.092564)
		(end 352.823272 -73.19391)
		(width 0.1143)
		(layer "In4.Cu")
		(net "P3E_CPU0_PE1_PCH_TXN<0>")
	)
	(segment
		(start 353.812856 -73.186544)
		(end 353.336352 -73.092564)
		(width 0.1143)
		(layer "In4.Cu")
		(net "P3E_CPU0_PE1_PCH_TXN<0>")
	)
	(segment
		(start 341.897462 -75.335384)
		(end 341.4649 -75.767946)
		(width 0.1143)
		(layer "In4.Cu")
		(net "P3E_CPU0_PE1_PCH_TXN<0>")
	)
	(segment
		(start 375.419112 -109.404658)
		(end 375.418604 -109.404658)
		(width 0.1143)
		(layer "In4.Cu")
		(net "P3E_CPU0_PE1_PCH_TXN<0>")
	)
	(segment
		(start 341.4649 -75.767946)
		(end 341.4649 -80.1751)
		(width 0.1143)
		(layer "In4.Cu")
		(net "P3E_CPU0_PE1_PCH_TXN<0>")
	)
	(segment
		(start 341.2236 -80.4164)
		(end 340.82355 -80.4164)
		(width 0.1143)
		(layer "In4.Cu")
		(net "P3E_CPU0_PE1_PCH_TXN<0>")
	)
	(segment
		(start 364.256828 -76.420726)
		(end 363.497114 -74.54265)
		(width 0.1143)
		(layer "In4.Cu")
		(net "P3E_CPU0_PE1_PCH_TXN<0>")
	)
	(segment
		(start 375.540524 -109.053376)
		(end 375.20372 -107.393232)
		(width 0.1143)
		(layer "In4.Cu")
		(net "P3E_CPU0_PE1_PCH_TXN<0>")
	)
	(segment
		(start 366.036098 -88.100408)
		(end 366.246918 -87.034624)
		(width 0.1143)
		(layer "In4.Cu")
		(net "P3E_CPU0_PE1_PCH_TXN<0>")
	)
	(segment
		(start 372.361714 -105.838244)
		(end 371.42039 -105.026206)
		(width 0.1143)
		(layer "In4.Cu")
		(net "P3E_CPU0_PE1_PCH_TXN<0>")
	)
	(segment
		(start 373.54637 -105.889298)
		(end 372.858538 -106.022902)
		(width 0.1143)
		(layer "In4.Cu")
		(net "P3E_CPU0_PE1_PCH_TXN<0>")
	)
	(segment
		(start 369.496848 -100.320348)
		(end 369.71732 -99.20478)
		(width 0.1143)
		(layer "In4.Cu")
		(net "P3E_CPU0_PE1_PCH_TXN<0>")
	)
	(segment
		(start 344.230706 -74.809858)
		(end 343.26322 -75.335384)
		(width 0.1143)
		(layer "In4.Cu")
		(net "P3E_CPU0_PE1_PCH_TXN<0>")
	)
	(segment
		(start 375.20372 -107.393232)
		(end 374.654572 -106.239564)
		(width 0.1143)
		(layer "In4.Cu")
		(net "P3E_CPU0_PE1_PCH_TXN<0>")
	)
	(segment
		(start 369.485164 -97.22866)
		(end 369.720622 -96.071944)
		(width 0.1143)
		(layer "In4.Cu")
		(net "P3E_CPU0_PE1_PCH_TXN<0>")
	)
	(segment
		(start 362.00969 -73.434194)
		(end 360.297984 -73.095866)
		(width 0.1143)
		(layer "In4.Cu")
		(net "P3E_CPU0_PE1_PCH_TXN<0>")
	)
	(segment
		(start 356.809294 -73.194418)
		(end 356.337108 -73.1012)
		(width 0.1143)
		(layer "In4.Cu")
		(net "P3E_CPU0_PE1_PCH_TXN<0>")
	)
	(segment
		(start 373.888 -114.299238)
		(end 373.70385 -114.115088)
		(width 0.1143)
		(layer "In4.Cu")
		(net "P3E_CPU0_PE1_PCH_TXN<0>")
	)
	(segment
		(start 369.452652 -95.565722)
		(end 369.68684 -94.419928)
		(width 0.1143)
		(layer "In4.Cu")
		(net "P3E_CPU0_PE1_PCH_TXN<0>")
	)
	(segment
		(start 366.246918 -87.034624)
		(end 364.87481 -80.101948)
		(width 0.1143)
		(layer "In4.Cu")
		(net "P3E_CPU0_PE1_PCH_TXN<0>")
	)
	(segment
		(start 374.88495 -112.17275)
		(end 375.40946 -111.11103)
		(width 0.1143)
		(layer "In4.Cu")
		(net "P3E_CPU0_PE1_PCH_TXN<0>")
	)
	(segment
		(start 368.146584 -92.157804)
		(end 366.350296 -89.519506)
		(width 0.1143)
		(layer "In4.Cu")
		(net "P3E_CPU0_PE1_PCH_TXN<0>")
	)
	(segment
		(start 357.794814 -73.191624)
		(end 357.30815 -73.095358)
		(width 0.1143)
		(layer "In4.Cu")
		(net "P3E_CPU0_PE1_PCH_TXN<0>")
	)
	(segment
		(start 352.823272 -73.19391)
		(end 350.814894 -72.79767)
		(width 0.1143)
		(layer "In4.Cu")
		(net "P3E_CPU0_PE1_PCH_TXN<0>")
	)
	(segment
		(start 354.816664 -73.194164)
		(end 354.29571 -73.09104)
		(width 0.1143)
		(layer "In4.Cu")
		(net "P3E_CPU0_PE1_PCH_TXN<0>")
	)
	(segment
		(start 358.803194 -73.194164)
		(end 358.292146 -73.093072)
		(width 0.1143)
		(layer "In4.Cu")
		(net "P3E_CPU0_PE1_PCH_TXN<0>")
	)
	(segment
		(start 373.70385 -113.35385)
		(end 374.88495 -112.17275)
		(width 0.1143)
		(layer "In4.Cu")
		(net "P3E_CPU0_PE1_PCH_TXN<0>")
	)
	(segment
		(start 362.010452 -73.434448)
		(end 362.00969 -73.434194)
		(width 0.1143)
		(layer "In4.Cu")
		(net "P3E_CPU0_PE1_PCH_TXN<0>")
	)
	(segment
		(start 299.524166 -97.014538)
		(end 300.095666 -97.014538)
		(width 0.1143)
		(layer "F.Cu")
		(net "P3E_CPU0_PE1_PCH_RXP<9>")
	)
	(via
		(at 300.095666 -97.014538)
		(size 0.508)
		(drill 0.254)
		(layers "F.Cu" "B.Cu")
		(net "P3E_CPU0_PE1_PCH_RXP<9>")
	)
	(via
		(at 364.856014 -124.288042)
		(size 0.508)
		(drill 0.254)
		(layers "F.Cu" "B.Cu")
		(net "P3E_CPU0_PE1_PCH_RXP<9>")
	)
	(segment
		(start 365.402114 -124.834142)
		(end 364.856014 -124.288042)
		(width 0.1143)
		(layer "B.Cu")
		(net "P3E_CPU0_PE1_PCH_RXP<9>")
	)
	(segment
		(start 367.637314 -124.834142)
		(end 365.402114 -124.834142)
		(width 0.1143)
		(layer "B.Cu")
		(net "P3E_CPU0_PE1_PCH_RXP<9>")
	)
	(segment
		(start 367.827814 -124.389642)
		(end 367.827814 -124.643642)
		(width 0.1143)
		(layer "B.Cu")
		(net "P3E_CPU0_PE1_PCH_RXP<9>")
	)
	(segment
		(start 367.827814 -124.643642)
		(end 367.637314 -124.834142)
		(width 0.1143)
		(layer "B.Cu")
		(net "P3E_CPU0_PE1_PCH_RXP<9>")
	)
	(segment
		(start 303.421288 -98.62058)
		(end 303.332388 -98.53168)
		(width 0.0889)
		(layer "In2.Cu")
		(net "P3E_CPU0_PE1_PCH_RXP<9>")
	)
	(segment
		(start 328.544428 -110.5027)
		(end 327.9775 -109.727746)
		(width 0.1143)
		(layer "In2.Cu")
		(net "P3E_CPU0_PE1_PCH_RXP<9>")
	)
	(segment
		(start 339.998558 -119.390922)
		(end 339.478112 -119.494808)
		(width 0.1143)
		(layer "In2.Cu")
		(net "P3E_CPU0_PE1_PCH_RXP<9>")
	)
	(segment
		(start 338.947506 -119.432324)
		(end 338.817966 -119.626634)
		(width 0.1143)
		(layer "In2.Cu")
		(net "P3E_CPU0_PE1_PCH_RXP<9>")
	)
	(segment
		(start 304.65522 -98.62058)
		(end 304.157888 -98.62058)
		(width 0.0889)
		(layer "In2.Cu")
		(net "P3E_CPU0_PE1_PCH_RXP<9>")
	)
	(segment
		(start 329.343512 -117.192806)
		(end 329.828652 -115.26774)
		(width 0.1143)
		(layer "In2.Cu")
		(net "P3E_CPU0_PE1_PCH_RXP<9>")
	)
	(segment
		(start 329.657964 -118.51894)
		(end 329.343512 -117.192806)
		(width 0.1143)
		(layer "In2.Cu")
		(net "P3E_CPU0_PE1_PCH_RXP<9>")
	)
	(segment
		(start 312.550556 -99.357942)
		(end 309.204868 -97.349564)
		(width 0.1143)
		(layer "In2.Cu")
		(net "P3E_CPU0_PE1_PCH_RXP<9>")
	)
	(segment
		(start 363.81563 -124.789692)
		(end 363.05998 -124.034042)
		(width 0.1143)
		(layer "In2.Cu")
		(net "P3E_CPU0_PE1_PCH_RXP<9>")
	)
	(segment
		(start 302.44288 -98.62058)
		(end 302.227488 -98.405188)
		(width 0.0889)
		(layer "In2.Cu")
		(net "P3E_CPU0_PE1_PCH_RXP<9>")
	)
	(segment
		(start 360.937556 -120.4087)
		(end 358.34193 -119.857266)
		(width 0.1143)
		(layer "In2.Cu")
		(net "P3E_CPU0_PE1_PCH_RXP<9>")
	)
	(segment
		(start 309.204868 -97.349564)
		(end 307.97246 -97.349564)
		(width 0.1143)
		(layer "In2.Cu")
		(net "P3E_CPU0_PE1_PCH_RXP<9>")
	)
	(segment
		(start 339.478112 -119.494808)
		(end 339.283802 -119.365268)
		(width 0.1143)
		(layer "In2.Cu")
		(net "P3E_CPU0_PE1_PCH_RXP<9>")
	)
	(segment
		(start 302.964088 -98.62058)
		(end 302.44288 -98.62058)
		(width 0.0889)
		(layer "In2.Cu")
		(net "P3E_CPU0_PE1_PCH_RXP<9>")
	)
	(segment
		(start 300.117256 -97.414588)
		(end 300.08449 -97.414588)
		(width 0.0889)
		(layer "In2.Cu")
		(net "P3E_CPU0_PE1_PCH_RXP<9>")
	)
	(segment
		(start 306.637436 -97.400364)
		(end 305.9684 -98.0694)
		(width 0.0889)
		(layer "In2.Cu")
		(net "P3E_CPU0_PE1_PCH_RXP<9>")
	)
	(segment
		(start 330.059538 -118.92026)
		(end 329.657964 -118.51894)
		(width 0.1143)
		(layer "In2.Cu")
		(net "P3E_CPU0_PE1_PCH_RXP<9>")
	)
	(segment
		(start 336.688684 -119.656098)
		(end 336.107786 -119.171212)
		(width 0.1143)
		(layer "In2.Cu")
		(net "P3E_CPU0_PE1_PCH_RXP<9>")
	)
	(segment
		(start 329.828652 -115.26774)
		(end 328.544428 -110.5027)
		(width 0.1143)
		(layer "In2.Cu")
		(net "P3E_CPU0_PE1_PCH_RXP<9>")
	)
	(segment
		(start 354.595938 -120.60682)
		(end 343.088976 -118.305326)
		(width 0.1143)
		(layer "In2.Cu")
		(net "P3E_CPU0_PE1_PCH_RXP<9>")
	)
	(segment
		(start 339.283802 -119.365268)
		(end 338.947506 -119.432324)
		(width 0.1143)
		(layer "In2.Cu")
		(net "P3E_CPU0_PE1_PCH_RXP<9>")
	)
	(segment
		(start 304.157888 -98.62058)
		(end 304.068988 -98.53168)
		(width 0.0889)
		(layer "In2.Cu")
		(net "P3E_CPU0_PE1_PCH_RXP<9>")
	)
	(segment
		(start 299.781468 -97.262188)
		(end 299.80255 -97.183448)
		(width 0.0889)
		(layer "In2.Cu")
		(net "P3E_CPU0_PE1_PCH_RXP<9>")
	)
	(segment
		(start 303.052988 -98.53168)
		(end 302.964088 -98.62058)
		(width 0.0889)
		(layer "In2.Cu")
		(net "P3E_CPU0_PE1_PCH_RXP<9>")
	)
	(segment
		(start 364.856014 -124.675392)
		(end 364.741714 -124.789692)
		(width 0.1143)
		(layer "In2.Cu")
		(net "P3E_CPU0_PE1_PCH_RXP<9>")
	)
	(segment
		(start 333.045562 -118.706392)
		(end 330.949808 -119.125746)
		(width 0.1143)
		(layer "In2.Cu")
		(net "P3E_CPU0_PE1_PCH_RXP<9>")
	)
	(segment
		(start 303.332388 -98.53168)
		(end 303.052988 -98.53168)
		(width 0.0889)
		(layer "In2.Cu")
		(net "P3E_CPU0_PE1_PCH_RXP<9>")
	)
	(segment
		(start 338.280756 -119.733822)
		(end 337.625944 -119.864632)
		(width 0.1143)
		(layer "In2.Cu")
		(net "P3E_CPU0_PE1_PCH_RXP<9>")
	)
	(segment
		(start 327.9775 -109.727746)
		(end 323.574918 -107.694984)
		(width 0.1143)
		(layer "In2.Cu")
		(net "P3E_CPU0_PE1_PCH_RXP<9>")
	)
	(segment
		(start 338.817966 -119.626634)
		(end 338.280756 -119.733568)
		(width 0.1143)
		(layer "In2.Cu")
		(net "P3E_CPU0_PE1_PCH_RXP<9>")
	)
	(segment
		(start 307.97246 -97.349564)
		(end 307.950362 -97.349564)
		(width 0.0889)
		(layer "In2.Cu")
		(net "P3E_CPU0_PE1_PCH_RXP<9>")
	)
	(segment
		(start 304.068988 -98.53168)
		(end 303.789588 -98.53168)
		(width 0.0889)
		(layer "In2.Cu")
		(net "P3E_CPU0_PE1_PCH_RXP<9>")
	)
	(segment
		(start 340.995 -118.724172)
		(end 339.999066 -119.390922)
		(width 0.1143)
		(layer "In2.Cu")
		(net "P3E_CPU0_PE1_PCH_RXP<9>")
	)
	(segment
		(start 364.856014 -124.288042)
		(end 364.856014 -124.675392)
		(width 0.1143)
		(layer "In2.Cu")
		(net "P3E_CPU0_PE1_PCH_RXP<9>")
	)
	(segment
		(start 307.950362 -97.349564)
		(end 307.899562 -97.400364)
		(width 0.0889)
		(layer "In2.Cu")
		(net "P3E_CPU0_PE1_PCH_RXP<9>")
	)
	(segment
		(start 358.34193 -119.857266)
		(end 354.595938 -120.60682)
		(width 0.1143)
		(layer "In2.Cu")
		(net "P3E_CPU0_PE1_PCH_RXP<9>")
	)
	(segment
		(start 307.899562 -97.400364)
		(end 306.637436 -97.400364)
		(width 0.0889)
		(layer "In2.Cu")
		(net "P3E_CPU0_PE1_PCH_RXP<9>")
	)
	(segment
		(start 364.741714 -124.789692)
		(end 363.81563 -124.789692)
		(width 0.1143)
		(layer "In2.Cu")
		(net "P3E_CPU0_PE1_PCH_RXP<9>")
	)
	(segment
		(start 337.625944 -119.864632)
		(end 336.688684 -119.656098)
		(width 0.1143)
		(layer "In2.Cu")
		(net "P3E_CPU0_PE1_PCH_RXP<9>")
	)
	(segment
		(start 305.9684 -98.0694)
		(end 305.2064 -98.0694)
		(width 0.0889)
		(layer "In2.Cu")
		(net "P3E_CPU0_PE1_PCH_RXP<9>")
	)
	(segment
		(start 343.088976 -118.305326)
		(end 340.995 -118.724172)
		(width 0.1143)
		(layer "In2.Cu")
		(net "P3E_CPU0_PE1_PCH_RXP<9>")
	)
	(segment
		(start 314.444634 -101.967538)
		(end 312.550556 -99.357942)
		(width 0.1143)
		(layer "In2.Cu")
		(net "P3E_CPU0_PE1_PCH_RXP<9>")
	)
	(segment
		(start 363.05998 -124.034042)
		(end 360.937556 -120.4087)
		(width 0.1143)
		(layer "In2.Cu")
		(net "P3E_CPU0_PE1_PCH_RXP<9>")
	)
	(segment
		(start 302.227488 -98.405188)
		(end 301.80153 -98.405188)
		(width 0.0889)
		(layer "In2.Cu")
		(net "P3E_CPU0_PE1_PCH_RXP<9>")
	)
	(segment
		(start 305.2064 -98.0694)
		(end 304.65522 -98.62058)
		(width 0.0889)
		(layer "In2.Cu")
		(net "P3E_CPU0_PE1_PCH_RXP<9>")
	)
	(segment
		(start 323.574918 -107.694984)
		(end 314.444634 -101.967538)
		(width 0.1143)
		(layer "In2.Cu")
		(net "P3E_CPU0_PE1_PCH_RXP<9>")
	)
	(segment
		(start 303.789588 -98.53168)
		(end 303.700688 -98.62058)
		(width 0.0889)
		(layer "In2.Cu")
		(net "P3E_CPU0_PE1_PCH_RXP<9>")
	)
	(segment
		(start 338.280756 -119.733568)
		(end 338.280756 -119.733822)
		(width 0.1143)
		(layer "In2.Cu")
		(net "P3E_CPU0_PE1_PCH_RXP<9>")
	)
	(segment
		(start 299.80255 -97.183448)
		(end 300.095666 -97.014538)
		(width 0.0889)
		(layer "In2.Cu")
		(net "P3E_CPU0_PE1_PCH_RXP<9>")
	)
	(segment
		(start 336.107786 -119.171212)
		(end 333.045562 -118.706392)
		(width 0.1143)
		(layer "In2.Cu")
		(net "P3E_CPU0_PE1_PCH_RXP<9>")
	)
	(segment
		(start 330.949808 -119.125746)
		(end 330.059538 -118.92026)
		(width 0.1143)
		(layer "In2.Cu")
		(net "P3E_CPU0_PE1_PCH_RXP<9>")
	)
	(segment
		(start 339.999066 -119.390922)
		(end 339.998558 -119.390922)
		(width 0.1143)
		(layer "In2.Cu")
		(net "P3E_CPU0_PE1_PCH_RXP<9>")
	)
	(segment
		(start 303.700688 -98.62058)
		(end 303.421288 -98.62058)
		(width 0.0889)
		(layer "In2.Cu")
		(net "P3E_CPU0_PE1_PCH_RXP<9>")
	)
	(segment
		(start 300.971966 -97.909634)
		(end 300.9392 -97.909634)
		(width 0.0889)
		(layer "In2.Cu")
		(net "P3E_CPU0_PE1_PCH_RXP<9>")
	)
	(arc
		(start 301.80153 -98.405188)
		(mid 301.60768 -98.348838)
		(end 301.465996 -98.205036)
		(width 0.0889)
		(layer "In2.Cu")
		(net "P3E_CPU0_PE1_PCH_RXP<9>")
	)
	(arc
		(start 300.9392 -97.909634)
		(mid 300.747558 -97.852468)
		(end 300.607476 -97.709736)
		(width 0.0889)
		(layer "In2.Cu")
		(net "P3E_CPU0_PE1_PCH_RXP<9>")
	)
	(arc
		(start 300.607476 -97.709736)
		(mid 300.400472 -97.498872)
		(end 300.117256 -97.414588)
		(width 0.0889)
		(layer "In2.Cu")
		(net "P3E_CPU0_PE1_PCH_RXP<9>")
	)
	(arc
		(start 301.465996 -98.205036)
		(mid 301.257388 -97.993104)
		(end 300.971966 -97.909634)
		(width 0.0889)
		(layer "In2.Cu")
		(net "P3E_CPU0_PE1_PCH_RXP<9>")
	)
	(arc
		(start 300.08449 -97.414588)
		(mid 299.916053 -97.372055)
		(end 299.781468 -97.262188)
		(width 0.0889)
		(layer "In2.Cu")
		(net "P3E_CPU0_PE1_PCH_RXP<9>")
	)
	(segment
		(start 298.665646 -95.528384)
		(end 299.237146 -95.528384)
		(width 0.1143)
		(layer "F.Cu")
		(net "P3E_CPU0_PE1_PCH_RXP<8>")
	)
	(via
		(at 299.237146 -95.528384)
		(size 0.508)
		(drill 0.254)
		(layers "F.Cu" "B.Cu")
		(net "P3E_CPU0_PE1_PCH_RXP<8>")
	)
	(via
		(at 364.844584 -121.333514)
		(size 0.508)
		(drill 0.254)
		(layers "F.Cu" "B.Cu")
		(net "P3E_CPU0_PE1_PCH_RXP<8>")
	)
	(segment
		(start 365.393478 -121.882408)
		(end 364.844584 -121.333514)
		(width 0.1143)
		(layer "B.Cu")
		(net "P3E_CPU0_PE1_PCH_RXP<8>")
	)
	(segment
		(start 367.820956 -121.708164)
		(end 367.646712 -121.882408)
		(width 0.1143)
		(layer "B.Cu")
		(net "P3E_CPU0_PE1_PCH_RXP<8>")
	)
	(segment
		(start 367.646712 -121.882408)
		(end 365.393478 -121.882408)
		(width 0.1143)
		(layer "B.Cu")
		(net "P3E_CPU0_PE1_PCH_RXP<8>")
	)
	(segment
		(start 367.820956 -121.443242)
		(end 367.820956 -121.708164)
		(width 0.1143)
		(layer "B.Cu")
		(net "P3E_CPU0_PE1_PCH_RXP<8>")
	)
	(segment
		(start 323.935598 -106.917744)
		(end 315.089286 -101.368098)
		(width 0.1143)
		(layer "In2.Cu")
		(net "P3E_CPU0_PE1_PCH_RXP<8>")
	)
	(segment
		(start 299.302424 -95.931736)
		(end 299.237146 -95.866458)
		(width 0.0889)
		(layer "In2.Cu")
		(net "P3E_CPU0_PE1_PCH_RXP<8>")
	)
	(segment
		(start 300.117256 -96.423988)
		(end 300.08449 -96.423988)
		(width 0.0889)
		(layer "In2.Cu")
		(net "P3E_CPU0_PE1_PCH_RXP<8>")
	)
	(segment
		(start 340.651084 -114.1603)
		(end 338.804758 -114.1603)
		(width 0.1143)
		(layer "In2.Cu")
		(net "P3E_CPU0_PE1_PCH_RXP<8>")
	)
	(segment
		(start 363.443774 -121.86793)
		(end 361.336844 -119.760746)
		(width 0.1143)
		(layer "In2.Cu")
		(net "P3E_CPU0_PE1_PCH_RXP<8>")
	)
	(segment
		(start 361.336844 -119.760746)
		(end 357.829104 -119.016018)
		(width 0.1143)
		(layer "In2.Cu")
		(net "P3E_CPU0_PE1_PCH_RXP<8>")
	)
	(segment
		(start 364.745016 -121.86793)
		(end 363.443774 -121.86793)
		(width 0.1143)
		(layer "In2.Cu")
		(net "P3E_CPU0_PE1_PCH_RXP<8>")
	)
	(segment
		(start 341.497412 -115.225068)
		(end 341.207344 -114.494818)
		(width 0.1143)
		(layer "In2.Cu")
		(net "P3E_CPU0_PE1_PCH_RXP<8>")
	)
	(segment
		(start 304.5206 -97.9678)
		(end 304.241454 -97.9678)
		(width 0.0889)
		(layer "In2.Cu")
		(net "P3E_CPU0_PE1_PCH_RXP<8>")
	)
	(segment
		(start 305.12385 -97.36455)
		(end 304.5206 -97.9678)
		(width 0.0889)
		(layer "In2.Cu")
		(net "P3E_CPU0_PE1_PCH_RXP<8>")
	)
	(segment
		(start 303.551336 -97.414588)
		(end 303.508156 -97.414588)
		(width 0.0889)
		(layer "In2.Cu")
		(net "P3E_CPU0_PE1_PCH_RXP<8>")
	)
	(segment
		(start 341.497666 -115.22583)
		(end 341.497412 -115.225068)
		(width 0.1143)
		(layer "In2.Cu")
		(net "P3E_CPU0_PE1_PCH_RXP<8>")
	)
	(segment
		(start 302.686212 -97.909634)
		(end 302.65624 -97.909634)
		(width 0.0889)
		(layer "In2.Cu")
		(net "P3E_CPU0_PE1_PCH_RXP<8>")
	)
	(segment
		(start 305.818794 -97.36455)
		(end 305.12385 -97.36455)
		(width 0.0889)
		(layer "In2.Cu")
		(net "P3E_CPU0_PE1_PCH_RXP<8>")
	)
	(segment
		(start 344.140282 -117.804184)
		(end 342.183212 -116.500656)
		(width 0.1143)
		(layer "In2.Cu")
		(net "P3E_CPU0_PE1_PCH_RXP<8>")
	)
	(segment
		(start 315.089286 -101.368098)
		(end 313.058556 -98.570796)
		(width 0.1143)
		(layer "In2.Cu")
		(net "P3E_CPU0_PE1_PCH_RXP<8>")
	)
	(segment
		(start 304.120804 -97.84715)
		(end 304.041556 -97.709736)
		(width 0.0889)
		(layer "In2.Cu")
		(net "P3E_CPU0_PE1_PCH_RXP<8>")
	)
	(segment
		(start 341.207344 -114.494818)
		(end 340.651084 -114.1603)
		(width 0.1143)
		(layer "In2.Cu")
		(net "P3E_CPU0_PE1_PCH_RXP<8>")
	)
	(segment
		(start 307.372512 -96.35236)
		(end 307.350414 -96.35236)
		(width 0.0889)
		(layer "In2.Cu")
		(net "P3E_CPU0_PE1_PCH_RXP<8>")
	)
	(segment
		(start 331.398372 -112.994186)
		(end 331.02423 -112.620044)
		(width 0.1143)
		(layer "In2.Cu")
		(net "P3E_CPU0_PE1_PCH_RXP<8>")
	)
	(segment
		(start 342.183212 -116.500656)
		(end 341.739728 -115.835176)
		(width 0.1143)
		(layer "In2.Cu")
		(net "P3E_CPU0_PE1_PCH_RXP<8>")
	)
	(segment
		(start 328.392028 -108.920788)
		(end 323.935598 -106.917744)
		(width 0.1143)
		(layer "In2.Cu")
		(net "P3E_CPU0_PE1_PCH_RXP<8>")
	)
	(segment
		(start 299.237146 -95.866458)
		(end 299.237146 -95.528384)
		(width 0.0889)
		(layer "In2.Cu")
		(net "P3E_CPU0_PE1_PCH_RXP<8>")
	)
	(segment
		(start 304.121058 -97.847658)
		(end 304.120804 -97.84715)
		(width 0.0889)
		(layer "In2.Cu")
		(net "P3E_CPU0_PE1_PCH_RXP<8>")
	)
	(segment
		(start 341.739728 -115.835176)
		(end 341.497666 -115.22583)
		(width 0.1143)
		(layer "In2.Cu")
		(net "P3E_CPU0_PE1_PCH_RXP<8>")
	)
	(segment
		(start 337.085432 -113.70183)
		(end 335.727294 -114.0079)
		(width 0.1143)
		(layer "In2.Cu")
		(net "P3E_CPU0_PE1_PCH_RXP<8>")
	)
	(segment
		(start 307.299614 -96.40316)
		(end 306.780184 -96.40316)
		(width 0.0889)
		(layer "In2.Cu")
		(net "P3E_CPU0_PE1_PCH_RXP<8>")
	)
	(segment
		(start 306.780184 -96.40316)
		(end 305.818794 -97.36455)
		(width 0.0889)
		(layer "In2.Cu")
		(net "P3E_CPU0_PE1_PCH_RXP<8>")
	)
	(segment
		(start 304.241454 -97.9678)
		(end 304.121058 -97.847658)
		(width 0.0889)
		(layer "In2.Cu")
		(net "P3E_CPU0_PE1_PCH_RXP<8>")
	)
	(segment
		(start 338.804758 -114.1603)
		(end 337.085432 -113.70183)
		(width 0.1143)
		(layer "In2.Cu")
		(net "P3E_CPU0_PE1_PCH_RXP<8>")
	)
	(segment
		(start 331.02423 -111.55299)
		(end 328.392028 -108.920788)
		(width 0.1143)
		(layer "In2.Cu")
		(net "P3E_CPU0_PE1_PCH_RXP<8>")
	)
	(segment
		(start 335.727294 -114.0079)
		(end 331.398372 -112.994186)
		(width 0.1143)
		(layer "In2.Cu")
		(net "P3E_CPU0_PE1_PCH_RXP<8>")
	)
	(segment
		(start 331.02423 -112.620044)
		(end 331.02423 -111.55299)
		(width 0.1143)
		(layer "In2.Cu")
		(net "P3E_CPU0_PE1_PCH_RXP<8>")
	)
	(segment
		(start 364.844584 -121.768362)
		(end 364.745016 -121.86793)
		(width 0.1143)
		(layer "In2.Cu")
		(net "P3E_CPU0_PE1_PCH_RXP<8>")
	)
	(segment
		(start 364.844584 -121.333514)
		(end 364.844584 -121.768362)
		(width 0.1143)
		(layer "In2.Cu")
		(net "P3E_CPU0_PE1_PCH_RXP<8>")
	)
	(segment
		(start 301.834296 -97.414588)
		(end 301.80153 -97.414588)
		(width 0.0889)
		(layer "In2.Cu")
		(net "P3E_CPU0_PE1_PCH_RXP<8>")
	)
	(segment
		(start 357.829104 -119.016018)
		(end 353.983798 -119.832882)
		(width 0.1143)
		(layer "In2.Cu")
		(net "P3E_CPU0_PE1_PCH_RXP<8>")
	)
	(segment
		(start 313.058556 -98.570796)
		(end 309.364888 -96.35236)
		(width 0.1143)
		(layer "In2.Cu")
		(net "P3E_CPU0_PE1_PCH_RXP<8>")
	)
	(segment
		(start 353.983798 -119.832882)
		(end 344.140282 -117.804184)
		(width 0.1143)
		(layer "In2.Cu")
		(net "P3E_CPU0_PE1_PCH_RXP<8>")
	)
	(segment
		(start 300.971966 -96.919034)
		(end 300.9392 -96.919034)
		(width 0.0889)
		(layer "In2.Cu")
		(net "P3E_CPU0_PE1_PCH_RXP<8>")
	)
	(segment
		(start 307.350414 -96.35236)
		(end 307.299614 -96.40316)
		(width 0.0889)
		(layer "In2.Cu")
		(net "P3E_CPU0_PE1_PCH_RXP<8>")
	)
	(segment
		(start 309.364888 -96.35236)
		(end 307.372512 -96.35236)
		(width 0.1143)
		(layer "In2.Cu")
		(net "P3E_CPU0_PE1_PCH_RXP<8>")
	)
	(arc
		(start 303.017936 -97.709736)
		(mid 302.877857 -97.852472)
		(end 302.686212 -97.909634)
		(width 0.0889)
		(layer "In2.Cu")
		(net "P3E_CPU0_PE1_PCH_RXP<8>")
	)
	(arc
		(start 300.607476 -96.719136)
		(mid 300.400472 -96.508272)
		(end 300.117256 -96.423988)
		(width 0.0889)
		(layer "In2.Cu")
		(net "P3E_CPU0_PE1_PCH_RXP<8>")
	)
	(arc
		(start 302.324516 -97.709736)
		(mid 302.117512 -97.498872)
		(end 301.834296 -97.414588)
		(width 0.0889)
		(layer "In2.Cu")
		(net "P3E_CPU0_PE1_PCH_RXP<8>")
	)
	(arc
		(start 302.65624 -97.909634)
		(mid 302.464598 -97.852468)
		(end 302.324516 -97.709736)
		(width 0.0889)
		(layer "In2.Cu")
		(net "P3E_CPU0_PE1_PCH_RXP<8>")
	)
	(arc
		(start 303.508156 -97.414588)
		(mid 303.224939 -97.498869)
		(end 303.017936 -97.709736)
		(width 0.0889)
		(layer "In2.Cu")
		(net "P3E_CPU0_PE1_PCH_RXP<8>")
	)
	(arc
		(start 304.041556 -97.709736)
		(mid 303.834552 -97.498872)
		(end 303.551336 -97.414588)
		(width 0.0889)
		(layer "In2.Cu")
		(net "P3E_CPU0_PE1_PCH_RXP<8>")
	)
	(arc
		(start 300.9392 -96.919034)
		(mid 300.747558 -96.861868)
		(end 300.607476 -96.719136)
		(width 0.0889)
		(layer "In2.Cu")
		(net "P3E_CPU0_PE1_PCH_RXP<8>")
	)
	(arc
		(start 301.465996 -97.214436)
		(mid 301.257388 -97.002504)
		(end 300.971966 -96.919034)
		(width 0.0889)
		(layer "In2.Cu")
		(net "P3E_CPU0_PE1_PCH_RXP<8>")
	)
	(arc
		(start 301.80153 -97.414588)
		(mid 301.60768 -97.358238)
		(end 301.465996 -97.214436)
		(width 0.0889)
		(layer "In2.Cu")
		(net "P3E_CPU0_PE1_PCH_RXP<8>")
	)
	(arc
		(start 300.08449 -96.423988)
		(mid 299.89064 -96.367638)
		(end 299.748956 -96.223836)
		(width 0.0889)
		(layer "In2.Cu")
		(net "P3E_CPU0_PE1_PCH_RXP<8>")
	)
	(arc
		(start 299.748956 -96.223836)
		(mid 299.560533 -96.024532)
		(end 299.302424 -95.931736)
		(width 0.0889)
		(layer "In2.Cu")
		(net "P3E_CPU0_PE1_PCH_RXP<8>")
	)
	(segment
		(start 381.120904 -121.310654)
		(end 381.29845 -121.245884)
		(width 0.1143)
		(layer "F.Cu")
		(net "P3E_CPU0_PE1_PCH_RXP<7>")
	)
	(segment
		(start 380.80315 -121.01576)
		(end 380.868174 -121.19356)
		(width 0.1143)
		(layer "F.Cu")
		(net "P3E_CPU0_PE1_PCH_RXP<7>")
	)
	(segment
		(start 380.868174 -121.19356)
		(end 381.120904 -121.310654)
		(width 0.1143)
		(layer "F.Cu")
		(net "P3E_CPU0_PE1_PCH_RXP<7>")
	)
	(via
		(at 349.890588 -67.4624)
		(size 0.508)
		(drill 0.254)
		(layers "F.Cu" "B.Cu")
		(net "P3E_CPU0_PE1_PCH_RXP<7>")
	)
	(via
		(at 381.29845 -121.245884)
		(size 0.508)
		(drill 0.254)
		(layers "F.Cu" "B.Cu")
		(net "P3E_CPU0_PE1_PCH_RXP<7>")
	)
	(via
		(at 352.301048 -63.573152)
		(size 0.508)
		(drill 0.254)
		(layers "F.Cu" "B.Cu")
		(net "P3E_CPU0_PE1_PCH_RXP<7>")
	)
	(segment
		(start 353.434142 -61.78677)
		(end 352.904806 -61.257434)
		(width 0.1143)
		(layer "B.Cu")
		(net "P3E_CPU0_PE1_PCH_RXP<7>")
	)
	(segment
		(start 353.434142 -62.440058)
		(end 353.434142 -61.78677)
		(width 0.1143)
		(layer "B.Cu")
		(net "P3E_CPU0_PE1_PCH_RXP<7>")
	)
	(segment
		(start 349.890588 -67.4624)
		(end 350.215708 -67.13728)
		(width 0.1143)
		(layer "B.Cu")
		(net "P3E_CPU0_PE1_PCH_RXP<7>")
	)
	(segment
		(start 352.301048 -63.573152)
		(end 353.434142 -62.440058)
		(width 0.1143)
		(layer "B.Cu")
		(net "P3E_CPU0_PE1_PCH_RXP<7>")
	)
	(segment
		(start 350.215708 -67.13728)
		(end 350.215708 -65.658492)
		(width 0.1143)
		(layer "B.Cu")
		(net "P3E_CPU0_PE1_PCH_RXP<7>")
	)
	(segment
		(start 350.215708 -65.658492)
		(end 352.301048 -63.573152)
		(width 0.1143)
		(layer "B.Cu")
		(net "P3E_CPU0_PE1_PCH_RXP<7>")
	)
	(segment
		(start 377.37161 -122.7709)
		(end 377.806458 -123.205748)
		(width 0.0889)
		(layer "In2.Cu")
		(net "P3E_CPU0_PE1_PCH_RXP<7>")
	)
	(segment
		(start 337.3628 -112.056926)
		(end 337.3628 -112.6744)
		(width 0.1143)
		(layer "In2.Cu")
		(net "P3E_CPU0_PE1_PCH_RXP<7>")
	)
	(segment
		(start 330.008992 -84.954364)
		(end 330.197206 -85.256116)
		(width 0.1143)
		(layer "In2.Cu")
		(net "P3E_CPU0_PE1_PCH_RXP<7>")
	)
	(segment
		(start 329.593448 -84.600034)
		(end 329.781662 -84.901786)
		(width 0.1143)
		(layer "In2.Cu")
		(net "P3E_CPU0_PE1_PCH_RXP<7>")
	)
	(segment
		(start 331.77734 -67.83959)
		(end 330.16317 -67.260216)
		(width 0.1143)
		(layer "In2.Cu")
		(net "P3E_CPU0_PE1_PCH_RXP<7>")
	)
	(segment
		(start 332.2828 -108.213906)
		(end 332.2828 -110.508542)
		(width 0.1143)
		(layer "In2.Cu")
		(net "P3E_CPU0_PE1_PCH_RXP<7>")
	)
	(segment
		(start 372.714774 -122.25528)
		(end 372.994174 -122.25528)
		(width 0.0889)
		(layer "In2.Cu")
		(net "P3E_CPU0_PE1_PCH_RXP<7>")
	)
	(segment
		(start 373.819674 -122.34418)
		(end 374.099074 -122.34418)
		(width 0.0889)
		(layer "In2.Cu")
		(net "P3E_CPU0_PE1_PCH_RXP<7>")
	)
	(segment
		(start 370.911374 -122.29338)
		(end 370.962174 -122.34418)
		(width 0.0889)
		(layer "In2.Cu")
		(net "P3E_CPU0_PE1_PCH_RXP<7>")
	)
	(segment
		(start 328.491088 -82.832956)
		(end 328.679302 -83.134708)
		(width 0.1143)
		(layer "In2.Cu")
		(net "P3E_CPU0_PE1_PCH_RXP<7>")
	)
	(segment
		(start 327.855326 -71.750936)
		(end 326.762872 -75.988672)
		(width 0.1143)
		(layer "In2.Cu")
		(net "P3E_CPU0_PE1_PCH_RXP<7>")
	)
	(segment
		(start 377.09221 -122.7709)
		(end 377.37161 -122.7709)
		(width 0.0889)
		(layer "In2.Cu")
		(net "P3E_CPU0_PE1_PCH_RXP<7>")
	)
	(segment
		(start 350.154494 -65.618868)
		(end 349.921322 -65.385696)
		(width 0.1143)
		(layer "In2.Cu")
		(net "P3E_CPU0_PE1_PCH_RXP<7>")
	)
	(segment
		(start 350.154494 -67.198494)
		(end 350.154494 -65.618868)
		(width 0.1143)
		(layer "In2.Cu")
		(net "P3E_CPU0_PE1_PCH_RXP<7>")
	)
	(segment
		(start 348.003622 -65.550796)
		(end 347.838522 -65.385696)
		(width 0.1143)
		(layer "In2.Cu")
		(net "P3E_CPU0_PE1_PCH_RXP<7>")
	)
	(segment
		(start 374.187974 -122.25528)
		(end 374.467374 -122.25528)
		(width 0.0889)
		(layer "In2.Cu")
		(net "P3E_CPU0_PE1_PCH_RXP<7>")
	)
	(segment
		(start 328.395584 -70.316344)
		(end 328.309986 -70.648576)
		(width 0.1143)
		(layer "In2.Cu")
		(net "P3E_CPU0_PE1_PCH_RXP<7>")
	)
	(segment
		(start 336.687922 -111.545116)
		(end 337.188556 -111.882682)
		(width 0.1143)
		(layer "In2.Cu")
		(net "P3E_CPU0_PE1_PCH_RXP<7>")
	)
	(segment
		(start 376.72391 -122.682)
		(end 377.00331 -122.682)
		(width 0.0889)
		(layer "In2.Cu")
		(net "P3E_CPU0_PE1_PCH_RXP<7>")
	)
	(segment
		(start 372.346474 -122.34418)
		(end 372.625874 -122.34418)
		(width 0.0889)
		(layer "In2.Cu")
		(net "P3E_CPU0_PE1_PCH_RXP<7>")
	)
	(segment
		(start 332.849982 -111.075724)
		(end 334.270096 -111.075724)
		(width 0.1143)
		(layer "In2.Cu")
		(net "P3E_CPU0_PE1_PCH_RXP<7>")
	)
	(segment
		(start 330.332842 -85.785198)
		(end 330.560172 -85.837776)
		(width 0.1143)
		(layer "In2.Cu")
		(net "P3E_CPU0_PE1_PCH_RXP<7>")
	)
	(segment
		(start 377.00331 -122.682)
		(end 377.09221 -122.7709)
		(width 0.0889)
		(layer "In2.Cu")
		(net "P3E_CPU0_PE1_PCH_RXP<7>")
	)
	(segment
		(start 330.695808 -86.367112)
		(end 331.15758 -87.107522)
		(width 0.1143)
		(layer "In2.Cu")
		(net "P3E_CPU0_PE1_PCH_RXP<7>")
	)
	(segment
		(start 330.962 -107.188)
		(end 332.2828 -108.213906)
		(width 0.1143)
		(layer "In2.Cu")
		(net "P3E_CPU0_PE1_PCH_RXP<7>")
	)
	(segment
		(start 347.838522 -65.385696)
		(end 347.482922 -65.385696)
		(width 0.1143)
		(layer "In2.Cu")
		(net "P3E_CPU0_PE1_PCH_RXP<7>")
	)
	(segment
		(start 329.646026 -84.372704)
		(end 329.593448 -84.600034)
		(width 0.1143)
		(layer "In2.Cu")
		(net "P3E_CPU0_PE1_PCH_RXP<7>")
	)
	(segment
		(start 344.97264 -115.335812)
		(end 346.067888 -115.548918)
		(width 0.1143)
		(layer "In2.Cu")
		(net "P3E_CPU0_PE1_PCH_RXP<7>")
	)
	(segment
		(start 328.309986 -70.648576)
		(end 328.108818 -70.767194)
		(width 0.1143)
		(layer "In2.Cu")
		(net "P3E_CPU0_PE1_PCH_RXP<7>")
	)
	(segment
		(start 346.785692 -116.033042)
		(end 347.289628 -116.78031)
		(width 0.1143)
		(layer "In2.Cu")
		(net "P3E_CPU0_PE1_PCH_RXP<7>")
	)
	(segment
		(start 326.762872 -75.988672)
		(end 327.939908 -81.94929)
		(width 0.1143)
		(layer "In2.Cu")
		(net "P3E_CPU0_PE1_PCH_RXP<7>")
	)
	(segment
		(start 328.649076 -69.332602)
		(end 328.563478 -69.66458)
		(width 0.1143)
		(layer "In2.Cu")
		(net "P3E_CPU0_PE1_PCH_RXP<7>")
	)
	(segment
		(start 328.108818 -70.767194)
		(end 328.02322 -71.099172)
		(width 0.1143)
		(layer "In2.Cu")
		(net "P3E_CPU0_PE1_PCH_RXP<7>")
	)
	(segment
		(start 343.307416 -114.212624)
		(end 344.97264 -115.335812)
		(width 0.1143)
		(layer "In2.Cu")
		(net "P3E_CPU0_PE1_PCH_RXP<7>")
	)
	(segment
		(start 336.713576 -66.369946)
		(end 335.2165 -66.369946)
		(width 0.1143)
		(layer "In2.Cu")
		(net "P3E_CPU0_PE1_PCH_RXP<7>")
	)
	(segment
		(start 332.62443 -67.58813)
		(end 331.77734 -67.83959)
		(width 0.1143)
		(layer "In2.Cu")
		(net "P3E_CPU0_PE1_PCH_RXP<7>")
	)
	(segment
		(start 370.889276 -122.29338)
		(end 370.911374 -122.29338)
		(width 0.0889)
		(layer "In2.Cu")
		(net "P3E_CPU0_PE1_PCH_RXP<7>")
	)
	(segment
		(start 371.178074 -122.34418)
		(end 371.266974 -122.25528)
		(width 0.0889)
		(layer "In2.Cu")
		(net "P3E_CPU0_PE1_PCH_RXP<7>")
	)
	(segment
		(start 370.962174 -122.34418)
		(end 371.178074 -122.34418)
		(width 0.0889)
		(layer "In2.Cu")
		(net "P3E_CPU0_PE1_PCH_RXP<7>")
	)
	(segment
		(start 328.02322 -71.099172)
		(end 328.141838 -71.30034)
		(width 0.1143)
		(layer "In2.Cu")
		(net "P3E_CPU0_PE1_PCH_RXP<7>")
	)
	(segment
		(start 376.63501 -122.7709)
		(end 376.72391 -122.682)
		(width 0.0889)
		(layer "In2.Cu")
		(net "P3E_CPU0_PE1_PCH_RXP<7>")
	)
	(segment
		(start 328.530458 -69.131434)
		(end 328.649076 -69.332602)
		(width 0.1143)
		(layer "In2.Cu")
		(net "P3E_CPU0_PE1_PCH_RXP<7>")
	)
	(segment
		(start 371.533674 -122.25528)
		(end 371.622574 -122.34418)
		(width 0.0889)
		(layer "In2.Cu")
		(net "P3E_CPU0_PE1_PCH_RXP<7>")
	)
	(segment
		(start 375.203974 -122.25528)
		(end 375.292874 -122.34418)
		(width 0.0889)
		(layer "In2.Cu")
		(net "P3E_CPU0_PE1_PCH_RXP<7>")
	)
	(segment
		(start 379.7173 -122.9741)
		(end 379.7173 -122.941334)
		(width 0.0889)
		(layer "In2.Cu")
		(net "P3E_CPU0_PE1_PCH_RXP<7>")
	)
	(segment
		(start 371.978174 -122.25528)
		(end 372.257574 -122.25528)
		(width 0.0889)
		(layer "In2.Cu")
		(net "P3E_CPU0_PE1_PCH_RXP<7>")
	)
	(segment
		(start 373.451374 -122.25528)
		(end 373.730774 -122.25528)
		(width 0.0889)
		(layer "In2.Cu")
		(net "P3E_CPU0_PE1_PCH_RXP<7>")
	)
	(segment
		(start 330.315062 -104.168702)
		(end 330.962 -107.188)
		(width 0.1143)
		(layer "In2.Cu")
		(net "P3E_CPU0_PE1_PCH_RXP<7>")
	)
	(segment
		(start 328.276966 -70.11543)
		(end 328.395584 -70.316344)
		(width 0.1143)
		(layer "In2.Cu")
		(net "P3E_CPU0_PE1_PCH_RXP<7>")
	)
	(segment
		(start 330.560172 -85.837776)
		(end 330.748386 -86.139528)
		(width 0.1143)
		(layer "In2.Cu")
		(net "P3E_CPU0_PE1_PCH_RXP<7>")
	)
	(segment
		(start 337.3628 -112.6744)
		(end 337.559904 -112.871504)
		(width 0.1143)
		(layer "In2.Cu")
		(net "P3E_CPU0_PE1_PCH_RXP<7>")
	)
	(segment
		(start 346.962222 -65.550796)
		(end 346.797122 -65.385696)
		(width 0.1143)
		(layer "In2.Cu")
		(net "P3E_CPU0_PE1_PCH_RXP<7>")
	)
	(segment
		(start 374.556274 -122.34418)
		(end 374.835674 -122.34418)
		(width 0.0889)
		(layer "In2.Cu")
		(net "P3E_CPU0_PE1_PCH_RXP<7>")
	)
	(segment
		(start 329.230482 -84.01812)
		(end 329.457812 -84.070952)
		(width 0.1143)
		(layer "In2.Cu")
		(net "P3E_CPU0_PE1_PCH_RXP<7>")
	)
	(segment
		(start 354.618544 -118.496842)
		(end 358.408478 -117.759988)
		(width 0.1143)
		(layer "In2.Cu")
		(net "P3E_CPU0_PE1_PCH_RXP<7>")
	)
	(segment
		(start 374.835674 -122.34418)
		(end 374.924574 -122.25528)
		(width 0.0889)
		(layer "In2.Cu")
		(net "P3E_CPU0_PE1_PCH_RXP<7>")
	)
	(segment
		(start 330.218288 -97.7646)
		(end 330.889102 -101.215698)
		(width 0.1143)
		(layer "In2.Cu")
		(net "P3E_CPU0_PE1_PCH_RXP<7>")
	)
	(segment
		(start 328.543666 -82.605372)
		(end 328.491088 -82.832956)
		(width 0.1143)
		(layer "In2.Cu")
		(net "P3E_CPU0_PE1_PCH_RXP<7>")
	)
	(segment
		(start 348.359222 -65.550796)
		(end 348.003622 -65.550796)
		(width 0.1143)
		(layer "In2.Cu")
		(net "P3E_CPU0_PE1_PCH_RXP<7>")
	)
	(segment
		(start 328.128122 -82.251042)
		(end 328.355452 -82.30362)
		(width 0.1143)
		(layer "In2.Cu")
		(net "P3E_CPU0_PE1_PCH_RXP<7>")
	)
	(segment
		(start 340.032594 -65.385696)
		(end 339.509354 -65.908936)
		(width 0.1143)
		(layer "In2.Cu")
		(net "P3E_CPU0_PE1_PCH_RXP<7>")
	)
	(segment
		(start 339.509354 -65.908936)
		(end 337.174586 -65.908936)
		(width 0.1143)
		(layer "In2.Cu")
		(net "P3E_CPU0_PE1_PCH_RXP<7>")
	)
	(segment
		(start 335.2165 -66.369946)
		(end 332.62443 -67.58813)
		(width 0.1143)
		(layer "In2.Cu")
		(net "P3E_CPU0_PE1_PCH_RXP<7>")
	)
	(segment
		(start 330.873608 -94.393258)
		(end 330.218288 -97.7646)
		(width 0.1143)
		(layer "In2.Cu")
		(net "P3E_CPU0_PE1_PCH_RXP<7>")
	)
	(segment
		(start 328.141838 -71.30034)
		(end 328.05624 -71.632318)
		(width 0.1143)
		(layer "In2.Cu")
		(net "P3E_CPU0_PE1_PCH_RXP<7>")
	)
	(segment
		(start 349.045022 -65.550796)
		(end 348.879922 -65.385696)
		(width 0.1143)
		(layer "In2.Cu")
		(net "P3E_CPU0_PE1_PCH_RXP<7>")
	)
	(segment
		(start 346.797122 -65.385696)
		(end 340.032594 -65.385696)
		(width 0.1143)
		(layer "In2.Cu")
		(net "P3E_CPU0_PE1_PCH_RXP<7>")
	)
	(segment
		(start 331.15758 -87.107522)
		(end 330.307696 -91.48064)
		(width 0.1143)
		(layer "In2.Cu")
		(net "P3E_CPU0_PE1_PCH_RXP<7>")
	)
	(segment
		(start 381.150876 -120.874028)
		(end 381.068834 -120.98782)
		(width 0.0889)
		(layer "In2.Cu")
		(net "P3E_CPU0_PE1_PCH_RXP<7>")
	)
	(segment
		(start 349.400622 -65.550796)
		(end 349.045022 -65.550796)
		(width 0.1143)
		(layer "In2.Cu")
		(net "P3E_CPU0_PE1_PCH_RXP<7>")
	)
	(segment
		(start 374.924574 -122.25528)
		(end 375.203974 -122.25528)
		(width 0.0889)
		(layer "In2.Cu")
		(net "P3E_CPU0_PE1_PCH_RXP<7>")
	)
	(segment
		(start 337.174586 -65.908936)
		(end 336.713576 -66.369946)
		(width 0.1143)
		(layer "In2.Cu")
		(net "P3E_CPU0_PE1_PCH_RXP<7>")
	)
	(segment
		(start 348.524322 -65.385696)
		(end 348.359222 -65.550796)
		(width 0.1143)
		(layer "In2.Cu")
		(net "P3E_CPU0_PE1_PCH_RXP<7>")
	)
	(segment
		(start 342.579198 -114.070892)
		(end 343.307416 -114.212624)
		(width 0.1143)
		(layer "In2.Cu")
		(net "P3E_CPU0_PE1_PCH_RXP<7>")
	)
	(segment
		(start 381.25273 -121.238772)
		(end 381.29845 -121.245884)
		(width 0.0889)
		(layer "In2.Cu")
		(net "P3E_CPU0_PE1_PCH_RXP<7>")
	)
	(segment
		(start 348.879922 -65.385696)
		(end 348.524322 -65.385696)
		(width 0.1143)
		(layer "In2.Cu")
		(net "P3E_CPU0_PE1_PCH_RXP<7>")
	)
	(segment
		(start 337.559904 -112.871504)
		(end 340.7664 -112.871504)
		(width 0.1143)
		(layer "In2.Cu")
		(net "P3E_CPU0_PE1_PCH_RXP<7>")
	)
	(segment
		(start 329.094846 -83.489038)
		(end 329.042268 -83.716368)
		(width 0.1143)
		(layer "In2.Cu")
		(net "P3E_CPU0_PE1_PCH_RXP<7>")
	)
	(segment
		(start 329.781662 -84.901786)
		(end 330.008992 -84.954364)
		(width 0.1143)
		(layer "In2.Cu")
		(net "P3E_CPU0_PE1_PCH_RXP<7>")
	)
	(segment
		(start 328.616056 -68.799456)
		(end 328.530458 -69.131434)
		(width 0.1143)
		(layer "In2.Cu")
		(net "P3E_CPU0_PE1_PCH_RXP<7>")
	)
	(segment
		(start 330.144628 -85.483446)
		(end 330.332842 -85.785198)
		(width 0.1143)
		(layer "In2.Cu")
		(net "P3E_CPU0_PE1_PCH_RXP<7>")
	)
	(segment
		(start 346.067888 -115.548918)
		(end 346.785692 -116.033042)
		(width 0.1143)
		(layer "In2.Cu")
		(net "P3E_CPU0_PE1_PCH_RXP<7>")
	)
	(segment
		(start 361.448604 -118.350538)
		(end 365.60633 -119.818912)
		(width 0.1143)
		(layer "In2.Cu")
		(net "P3E_CPU0_PE1_PCH_RXP<7>")
	)
	(segment
		(start 374.467374 -122.25528)
		(end 374.556274 -122.34418)
		(width 0.0889)
		(layer "In2.Cu")
		(net "P3E_CPU0_PE1_PCH_RXP<7>")
	)
	(segment
		(start 329.042268 -83.716368)
		(end 329.230482 -84.01812)
		(width 0.1143)
		(layer "In2.Cu")
		(net "P3E_CPU0_PE1_PCH_RXP<7>")
	)
	(segment
		(start 328.906632 -83.187286)
		(end 329.094846 -83.489038)
		(width 0.1143)
		(layer "In2.Cu")
		(net "P3E_CPU0_PE1_PCH_RXP<7>")
	)
	(segment
		(start 327.939908 -81.94929)
		(end 328.128122 -82.251042)
		(width 0.1143)
		(layer "In2.Cu")
		(net "P3E_CPU0_PE1_PCH_RXP<7>")
	)
	(segment
		(start 329.805284 -67.386962)
		(end 328.616056 -68.799456)
		(width 0.1143)
		(layer "In2.Cu")
		(net "P3E_CPU0_PE1_PCH_RXP<7>")
	)
	(segment
		(start 381.068834 -120.98782)
		(end 381.25273 -121.238772)
		(width 0.0889)
		(layer "In2.Cu")
		(net "P3E_CPU0_PE1_PCH_RXP<7>")
	)
	(segment
		(start 342.02878 -113.700814)
		(end 342.579198 -114.070892)
		(width 0.1143)
		(layer "In2.Cu")
		(net "P3E_CPU0_PE1_PCH_RXP<7>")
	)
	(segment
		(start 373.362474 -122.34418)
		(end 373.451374 -122.25528)
		(width 0.0889)
		(layer "In2.Cu")
		(net "P3E_CPU0_PE1_PCH_RXP<7>")
	)
	(segment
		(start 340.7664 -112.871504)
		(end 341.210138 -112.957864)
		(width 0.1143)
		(layer "In2.Cu")
		(net "P3E_CPU0_PE1_PCH_RXP<7>")
	)
	(segment
		(start 349.921322 -65.385696)
		(end 349.565722 -65.385696)
		(width 0.1143)
		(layer "In2.Cu")
		(net "P3E_CPU0_PE1_PCH_RXP<7>")
	)
	(segment
		(start 330.889102 -101.215698)
		(end 330.315062 -104.168702)
		(width 0.1143)
		(layer "In2.Cu")
		(net "P3E_CPU0_PE1_PCH_RXP<7>")
	)
	(segment
		(start 349.890588 -67.4624)
		(end 350.154494 -67.198494)
		(width 0.1143)
		(layer "In2.Cu")
		(net "P3E_CPU0_PE1_PCH_RXP<7>")
	)
	(segment
		(start 332.2828 -110.508542)
		(end 332.849982 -111.075724)
		(width 0.1143)
		(layer "In2.Cu")
		(net "P3E_CPU0_PE1_PCH_RXP<7>")
	)
	(segment
		(start 347.317822 -65.550796)
		(end 346.962222 -65.550796)
		(width 0.1143)
		(layer "In2.Cu")
		(net "P3E_CPU0_PE1_PCH_RXP<7>")
	)
	(segment
		(start 373.083074 -122.34418)
		(end 373.362474 -122.34418)
		(width 0.0889)
		(layer "In2.Cu")
		(net "P3E_CPU0_PE1_PCH_RXP<7>")
	)
	(segment
		(start 349.565722 -65.385696)
		(end 349.400622 -65.550796)
		(width 0.1143)
		(layer "In2.Cu")
		(net "P3E_CPU0_PE1_PCH_RXP<7>")
	)
	(segment
		(start 328.563478 -69.66458)
		(end 328.362564 -69.783198)
		(width 0.1143)
		(layer "In2.Cu")
		(net "P3E_CPU0_PE1_PCH_RXP<7>")
	)
	(segment
		(start 372.994174 -122.25528)
		(end 373.083074 -122.34418)
		(width 0.0889)
		(layer "In2.Cu")
		(net "P3E_CPU0_PE1_PCH_RXP<7>")
	)
	(segment
		(start 329.457812 -84.070952)
		(end 329.646026 -84.372704)
		(width 0.1143)
		(layer "In2.Cu")
		(net "P3E_CPU0_PE1_PCH_RXP<7>")
	)
	(segment
		(start 369.809268 -122.29338)
		(end 370.889276 -122.29338)
		(width 0.1143)
		(layer "In2.Cu")
		(net "P3E_CPU0_PE1_PCH_RXP<7>")
	)
	(segment
		(start 330.197206 -85.256116)
		(end 330.144628 -85.483446)
		(width 0.1143)
		(layer "In2.Cu")
		(net "P3E_CPU0_PE1_PCH_RXP<7>")
	)
	(segment
		(start 334.270096 -111.075724)
		(end 336.687922 -111.545116)
		(width 0.1143)
		(layer "In2.Cu")
		(net "P3E_CPU0_PE1_PCH_RXP<7>")
	)
	(segment
		(start 371.622574 -122.34418)
		(end 371.889274 -122.34418)
		(width 0.0889)
		(layer "In2.Cu")
		(net "P3E_CPU0_PE1_PCH_RXP<7>")
	)
	(segment
		(start 375.292874 -122.34418)
		(end 375.572274 -122.34418)
		(width 0.0889)
		(layer "In2.Cu")
		(net "P3E_CPU0_PE1_PCH_RXP<7>")
	)
	(segment
		(start 371.266974 -122.25528)
		(end 371.533674 -122.25528)
		(width 0.0889)
		(layer "In2.Cu")
		(net "P3E_CPU0_PE1_PCH_RXP<7>")
	)
	(segment
		(start 328.355452 -82.30362)
		(end 328.543666 -82.605372)
		(width 0.1143)
		(layer "In2.Cu")
		(net "P3E_CPU0_PE1_PCH_RXP<7>")
	)
	(segment
		(start 375.572274 -122.34418)
		(end 375.998994 -122.7709)
		(width 0.0889)
		(layer "In2.Cu")
		(net "P3E_CPU0_PE1_PCH_RXP<7>")
	)
	(segment
		(start 373.730774 -122.25528)
		(end 373.819674 -122.34418)
		(width 0.0889)
		(layer "In2.Cu")
		(net "P3E_CPU0_PE1_PCH_RXP<7>")
	)
	(segment
		(start 365.60633 -119.818912)
		(end 369.809268 -122.29338)
		(width 0.1143)
		(layer "In2.Cu")
		(net "P3E_CPU0_PE1_PCH_RXP<7>")
	)
	(segment
		(start 380.2126 -122.11558)
		(end 380.2126 -122.082814)
		(width 0.0889)
		(layer "In2.Cu")
		(net "P3E_CPU0_PE1_PCH_RXP<7>")
	)
	(segment
		(start 330.748386 -86.139528)
		(end 330.695808 -86.367112)
		(width 0.1143)
		(layer "In2.Cu")
		(net "P3E_CPU0_PE1_PCH_RXP<7>")
	)
	(segment
		(start 328.05624 -71.632318)
		(end 327.855326 -71.750936)
		(width 0.1143)
		(layer "In2.Cu")
		(net "P3E_CPU0_PE1_PCH_RXP<7>")
	)
	(segment
		(start 341.792814 -113.350802)
		(end 342.02878 -113.700814)
		(width 0.1143)
		(layer "In2.Cu")
		(net "P3E_CPU0_PE1_PCH_RXP<7>")
	)
	(segment
		(start 371.889274 -122.34418)
		(end 371.978174 -122.25528)
		(width 0.0889)
		(layer "In2.Cu")
		(net "P3E_CPU0_PE1_PCH_RXP<7>")
	)
	(segment
		(start 374.099074 -122.34418)
		(end 374.187974 -122.25528)
		(width 0.0889)
		(layer "In2.Cu")
		(net "P3E_CPU0_PE1_PCH_RXP<7>")
	)
	(segment
		(start 347.482922 -65.385696)
		(end 347.317822 -65.550796)
		(width 0.1143)
		(layer "In2.Cu")
		(net "P3E_CPU0_PE1_PCH_RXP<7>")
	)
	(segment
		(start 330.307696 -91.48064)
		(end 330.873608 -94.393258)
		(width 0.1143)
		(layer "In2.Cu")
		(net "P3E_CPU0_PE1_PCH_RXP<7>")
	)
	(segment
		(start 347.89745 -117.190266)
		(end 354.618544 -118.496842)
		(width 0.1143)
		(layer "In2.Cu")
		(net "P3E_CPU0_PE1_PCH_RXP<7>")
	)
	(segment
		(start 341.210138 -112.957864)
		(end 341.792814 -113.350802)
		(width 0.1143)
		(layer "In2.Cu")
		(net "P3E_CPU0_PE1_PCH_RXP<7>")
	)
	(segment
		(start 375.998994 -122.7709)
		(end 376.63501 -122.7709)
		(width 0.0889)
		(layer "In2.Cu")
		(net "P3E_CPU0_PE1_PCH_RXP<7>")
	)
	(segment
		(start 337.188556 -111.882682)
		(end 337.3628 -112.056926)
		(width 0.1143)
		(layer "In2.Cu")
		(net "P3E_CPU0_PE1_PCH_RXP<7>")
	)
	(segment
		(start 328.362564 -69.783198)
		(end 328.276966 -70.11543)
		(width 0.1143)
		(layer "In2.Cu")
		(net "P3E_CPU0_PE1_PCH_RXP<7>")
	)
	(segment
		(start 328.679302 -83.134708)
		(end 328.906632 -83.187286)
		(width 0.1143)
		(layer "In2.Cu")
		(net "P3E_CPU0_PE1_PCH_RXP<7>")
	)
	(segment
		(start 372.625874 -122.34418)
		(end 372.714774 -122.25528)
		(width 0.0889)
		(layer "In2.Cu")
		(net "P3E_CPU0_PE1_PCH_RXP<7>")
	)
	(segment
		(start 347.289628 -116.78031)
		(end 347.89745 -117.190266)
		(width 0.1143)
		(layer "In2.Cu")
		(net "P3E_CPU0_PE1_PCH_RXP<7>")
	)
	(segment
		(start 330.16317 -67.260216)
		(end 329.805284 -67.386962)
		(width 0.1143)
		(layer "In2.Cu")
		(net "P3E_CPU0_PE1_PCH_RXP<7>")
	)
	(segment
		(start 372.257574 -122.25528)
		(end 372.346474 -122.34418)
		(width 0.0889)
		(layer "In2.Cu")
		(net "P3E_CPU0_PE1_PCH_RXP<7>")
	)
	(segment
		(start 358.408478 -117.759988)
		(end 361.448604 -118.350538)
		(width 0.1143)
		(layer "In2.Cu")
		(net "P3E_CPU0_PE1_PCH_RXP<7>")
	)
	(arc
		(start 379.517402 -123.309634)
		(mid 379.661026 -123.167899)
		(end 379.7173 -122.9741)
		(width 0.0889)
		(layer "In2.Cu")
		(net "P3E_CPU0_PE1_PCH_RXP<7>")
	)
	(arc
		(start 380.2126 -122.082814)
		(mid 380.296971 -121.799448)
		(end 380.508002 -121.59234)
		(width 0.0889)
		(layer "In2.Cu")
		(net "P3E_CPU0_PE1_PCH_RXP<7>")
	)
	(arc
		(start 381.6985 -121.260616)
		(mid 381.698762 -121.246011)
		(end 381.6985 -121.231406)
		(width 0.0889)
		(layer "In2.Cu")
		(net "P3E_CPU0_PE1_PCH_RXP<7>")
	)
	(arc
		(start 378.126752 -123.309634)
		(mid 378.32665 -123.363133)
		(end 378.526548 -123.309634)
		(width 0.0889)
		(layer "In2.Cu")
		(net "P3E_CPU0_PE1_PCH_RXP<7>")
	)
	(arc
		(start 380.012448 -122.451114)
		(mid 380.156252 -122.309431)
		(end 380.2126 -122.11558)
		(width 0.0889)
		(layer "In2.Cu")
		(net "P3E_CPU0_PE1_PCH_RXP<7>")
	)
	(arc
		(start 378.526548 -123.309634)
		(mid 378.82195 -123.230503)
		(end 379.117352 -123.309634)
		(width 0.0889)
		(layer "In2.Cu")
		(net "P3E_CPU0_PE1_PCH_RXP<7>")
	)
	(arc
		(start 380.508002 -121.59234)
		(mid 380.803323 -121.513369)
		(end 381.098552 -121.592594)
		(width 0.0889)
		(layer "In2.Cu")
		(net "P3E_CPU0_PE1_PCH_RXP<7>")
	)
	(arc
		(start 381.498602 -121.592594)
		(mid 381.64149 -121.452439)
		(end 381.6985 -121.260616)
		(width 0.0889)
		(layer "In2.Cu")
		(net "P3E_CPU0_PE1_PCH_RXP<7>")
	)
	(arc
		(start 377.806458 -123.205748)
		(mid 377.972098 -123.240758)
		(end 378.126752 -123.309634)
		(width 0.0889)
		(layer "In2.Cu")
		(net "P3E_CPU0_PE1_PCH_RXP<7>")
	)
	(arc
		(start 381.6985 -121.231406)
		(mid 381.641369 -121.039656)
		(end 381.498602 -120.899428)
		(width 0.0889)
		(layer "In2.Cu")
		(net "P3E_CPU0_PE1_PCH_RXP<7>")
	)
	(arc
		(start 381.098552 -121.592594)
		(mid 381.298594 -121.64622)
		(end 381.498602 -121.592594)
		(width 0.0889)
		(layer "In2.Cu")
		(net "P3E_CPU0_PE1_PCH_RXP<7>")
	)
	(arc
		(start 379.7173 -122.941334)
		(mid 379.801581 -122.658117)
		(end 380.012448 -122.451114)
		(width 0.0889)
		(layer "In2.Cu")
		(net "P3E_CPU0_PE1_PCH_RXP<7>")
	)
	(arc
		(start 381.498602 -120.899428)
		(mid 381.327648 -120.846835)
		(end 381.150876 -120.874028)
		(width 0.0889)
		(layer "In2.Cu")
		(net "P3E_CPU0_PE1_PCH_RXP<7>")
	)
	(arc
		(start 379.117352 -123.309634)
		(mid 379.317394 -123.36326)
		(end 379.517402 -123.309634)
		(width 0.0889)
		(layer "In2.Cu")
		(net "P3E_CPU0_PE1_PCH_RXP<7>")
	)
	(segment
		(start 378.753116 -122.0724)
		(end 378.82195 -122.104404)
		(width 0.1143)
		(layer "F.Cu")
		(net "P3E_CPU0_PE1_PCH_RXP<6>")
	)
	(segment
		(start 378.32665 -121.87428)
		(end 378.753116 -122.0724)
		(width 0.1143)
		(layer "F.Cu")
		(net "P3E_CPU0_PE1_PCH_RXP<6>")
	)
	(via
		(at 378.82195 -122.104404)
		(size 0.508)
		(drill 0.254)
		(layers "F.Cu" "B.Cu")
		(net "P3E_CPU0_PE1_PCH_RXP<6>")
	)
	(via
		(at 347.048074 -65.767966)
		(size 0.508)
		(drill 0.254)
		(layers "F.Cu" "B.Cu")
		(net "P3E_CPU0_PE1_PCH_RXP<6>")
	)
	(via
		(at 347.043248 -67.44335)
		(size 0.508)
		(drill 0.254)
		(layers "F.Cu" "B.Cu")
		(net "P3E_CPU0_PE1_PCH_RXP<6>")
	)
	(segment
		(start 348.205044 -63.42126)
		(end 348.79915 -62.827154)
		(width 0.1143)
		(layer "B.Cu")
		(net "P3E_CPU0_PE1_PCH_RXP<6>")
	)
	(segment
		(start 347.22816 -64.398144)
		(end 347.589856 -64.398144)
		(width 0.1143)
		(layer "B.Cu")
		(net "P3E_CPU0_PE1_PCH_RXP<6>")
	)
	(segment
		(start 347.226636 -68.23456)
		(end 347.112336 -68.34886)
		(width 0.1143)
		(layer "B.Cu")
		(net "P3E_CPU0_PE1_PCH_RXP<6>")
	)
	(segment
		(start 346.615512 -68.144136)
		(end 346.615512 -67.541394)
		(width 0.1143)
		(layer "B.Cu")
		(net "P3E_CPU0_PE1_PCH_RXP<6>")
	)
	(segment
		(start 347.916246 -68.34886)
		(end 347.683836 -68.34886)
		(width 0.1143)
		(layer "B.Cu")
		(net "P3E_CPU0_PE1_PCH_RXP<6>")
	)
	(segment
		(start 349.160846 -62.827154)
		(end 350.021144 -63.687452)
		(width 0.1143)
		(layer "B.Cu")
		(net "P3E_CPU0_PE1_PCH_RXP<6>")
	)
	(segment
		(start 347.683836 -68.34886)
		(end 347.569536 -68.23456)
		(width 0.1143)
		(layer "B.Cu")
		(net "P3E_CPU0_PE1_PCH_RXP<6>")
	)
	(segment
		(start 348.79915 -62.827154)
		(end 349.160846 -62.827154)
		(width 0.1143)
		(layer "B.Cu")
		(net "P3E_CPU0_PE1_PCH_RXP<6>")
	)
	(segment
		(start 347.048074 -65.767966)
		(end 346.634054 -65.353946)
		(width 0.1143)
		(layer "B.Cu")
		(net "P3E_CPU0_PE1_PCH_RXP<6>")
	)
	(segment
		(start 348.986856 -64.725804)
		(end 348.986856 -64.564768)
		(width 0.1143)
		(layer "B.Cu")
		(net "P3E_CPU0_PE1_PCH_RXP<6>")
	)
	(segment
		(start 348.205044 -63.782956)
		(end 348.205044 -63.42126)
		(width 0.1143)
		(layer "B.Cu")
		(net "P3E_CPU0_PE1_PCH_RXP<6>")
	)
	(segment
		(start 347.048074 -65.767966)
		(end 348.50324 -67.223132)
		(width 0.1143)
		(layer "B.Cu")
		(net "P3E_CPU0_PE1_PCH_RXP<6>")
	)
	(segment
		(start 346.713556 -67.44335)
		(end 347.043248 -67.44335)
		(width 0.1143)
		(layer "B.Cu")
		(net "P3E_CPU0_PE1_PCH_RXP<6>")
	)
	(segment
		(start 346.615512 -67.541394)
		(end 346.713556 -67.44335)
		(width 0.1143)
		(layer "B.Cu")
		(net "P3E_CPU0_PE1_PCH_RXP<6>")
	)
	(segment
		(start 346.634054 -64.99225)
		(end 347.22816 -64.398144)
		(width 0.1143)
		(layer "B.Cu")
		(net "P3E_CPU0_PE1_PCH_RXP<6>")
	)
	(segment
		(start 346.634054 -65.353946)
		(end 346.634054 -64.99225)
		(width 0.1143)
		(layer "B.Cu")
		(net "P3E_CPU0_PE1_PCH_RXP<6>")
	)
	(segment
		(start 350.845882 -62.79769)
		(end 350.731582 -62.68339)
		(width 0.1143)
		(layer "B.Cu")
		(net "P3E_CPU0_PE1_PCH_RXP<6>")
	)
	(segment
		(start 347.569536 -68.23456)
		(end 347.226636 -68.23456)
		(width 0.1143)
		(layer "B.Cu")
		(net "P3E_CPU0_PE1_PCH_RXP<6>")
	)
	(segment
		(start 350.845882 -62.22619)
		(end 350.845882 -61.792358)
		(width 0.1143)
		(layer "B.Cu")
		(net "P3E_CPU0_PE1_PCH_RXP<6>")
	)
	(segment
		(start 350.53143 -61.678058)
		(end 350.110806 -61.257434)
		(width 0.1143)
		(layer "B.Cu")
		(net "P3E_CPU0_PE1_PCH_RXP<6>")
	)
	(segment
		(start 350.845882 -63.02375)
		(end 350.845882 -62.79769)
		(width 0.1143)
		(layer "B.Cu")
		(net "P3E_CPU0_PE1_PCH_RXP<6>")
	)
	(segment
		(start 348.371668 -65.179956)
		(end 348.532704 -65.179956)
		(width 0.1143)
		(layer "B.Cu")
		(net "P3E_CPU0_PE1_PCH_RXP<6>")
	)
	(segment
		(start 350.731582 -61.678058)
		(end 350.53143 -61.678058)
		(width 0.1143)
		(layer "B.Cu")
		(net "P3E_CPU0_PE1_PCH_RXP<6>")
	)
	(segment
		(start 350.731582 -62.34049)
		(end 350.845882 -62.22619)
		(width 0.1143)
		(layer "B.Cu")
		(net "P3E_CPU0_PE1_PCH_RXP<6>")
	)
	(segment
		(start 347.112336 -68.34886)
		(end 346.820236 -68.34886)
		(width 0.1143)
		(layer "B.Cu")
		(net "P3E_CPU0_PE1_PCH_RXP<6>")
	)
	(segment
		(start 350.845882 -61.792358)
		(end 350.731582 -61.678058)
		(width 0.1143)
		(layer "B.Cu")
		(net "P3E_CPU0_PE1_PCH_RXP<6>")
	)
	(segment
		(start 348.986856 -64.564768)
		(end 348.205044 -63.782956)
		(width 0.1143)
		(layer "B.Cu")
		(net "P3E_CPU0_PE1_PCH_RXP<6>")
	)
	(segment
		(start 347.589856 -64.398144)
		(end 348.371668 -65.179956)
		(width 0.1143)
		(layer "B.Cu")
		(net "P3E_CPU0_PE1_PCH_RXP<6>")
	)
	(segment
		(start 350.731582 -62.68339)
		(end 350.731582 -62.34049)
		(width 0.1143)
		(layer "B.Cu")
		(net "P3E_CPU0_PE1_PCH_RXP<6>")
	)
	(segment
		(start 346.820236 -68.34886)
		(end 346.615512 -68.144136)
		(width 0.1143)
		(layer "B.Cu")
		(net "P3E_CPU0_PE1_PCH_RXP<6>")
	)
	(segment
		(start 350.021144 -63.687452)
		(end 350.18218 -63.687452)
		(width 0.1143)
		(layer "B.Cu")
		(net "P3E_CPU0_PE1_PCH_RXP<6>")
	)
	(segment
		(start 348.50324 -67.223132)
		(end 348.50324 -67.761866)
		(width 0.1143)
		(layer "B.Cu")
		(net "P3E_CPU0_PE1_PCH_RXP<6>")
	)
	(segment
		(start 350.18218 -63.687452)
		(end 350.845882 -63.02375)
		(width 0.1143)
		(layer "B.Cu")
		(net "P3E_CPU0_PE1_PCH_RXP<6>")
	)
	(segment
		(start 348.532704 -65.179956)
		(end 348.986856 -64.725804)
		(width 0.1143)
		(layer "B.Cu")
		(net "P3E_CPU0_PE1_PCH_RXP<6>")
	)
	(segment
		(start 348.50324 -67.761866)
		(end 347.916246 -68.34886)
		(width 0.1143)
		(layer "B.Cu")
		(net "P3E_CPU0_PE1_PCH_RXP<6>")
	)
	(segment
		(start 347.697806 -115.67795)
		(end 347.457776 -115.516406)
		(width 0.1143)
		(layer "In2.Cu")
		(net "P3E_CPU0_PE1_PCH_RXP<6>")
	)
	(segment
		(start 377.320048 -121.955052)
		(end 376.111262 -121.955052)
		(width 0.0889)
		(layer "In2.Cu")
		(net "P3E_CPU0_PE1_PCH_RXP<6>")
	)
	(segment
		(start 347.160596 -114.68354)
		(end 347.112336 -114.610896)
		(width 0.1143)
		(layer "In2.Cu")
		(net "P3E_CPU0_PE1_PCH_RXP<6>")
	)
	(segment
		(start 360.653838 -117.653054)
		(end 358.394 -117.213888)
		(width 0.1143)
		(layer "In2.Cu")
		(net "P3E_CPU0_PE1_PCH_RXP<6>")
	)
	(segment
		(start 331.694282 -86.955884)
		(end 328.160126 -81.289398)
		(width 0.1143)
		(layer "In2.Cu")
		(net "P3E_CPU0_PE1_PCH_RXP<6>")
	)
	(segment
		(start 336.95005 -66.736214)
		(end 337.434428 -66.251836)
		(width 0.1143)
		(layer "In2.Cu")
		(net "P3E_CPU0_PE1_PCH_RXP<6>")
	)
	(segment
		(start 337.858608 -111.730536)
		(end 336.931 -111.105188)
		(width 0.1143)
		(layer "In2.Cu")
		(net "P3E_CPU0_PE1_PCH_RXP<6>")
	)
	(segment
		(start 346.7354 -67.135502)
		(end 347.043248 -67.44335)
		(width 0.1143)
		(layer "In2.Cu")
		(net "P3E_CPU0_PE1_PCH_RXP<6>")
	)
	(segment
		(start 377.571254 -121.703846)
		(end 377.320048 -121.955052)
		(width 0.0889)
		(layer "In2.Cu")
		(net "P3E_CPU0_PE1_PCH_RXP<6>")
	)
	(segment
		(start 374.86844 -121.75998)
		(end 374.81764 -121.81078)
		(width 0.0889)
		(layer "In2.Cu")
		(net "P3E_CPU0_PE1_PCH_RXP<6>")
	)
	(segment
		(start 329.145392 -69.605906)
		(end 335.251044 -66.736214)
		(width 0.1143)
		(layer "In2.Cu")
		(net "P3E_CPU0_PE1_PCH_RXP<6>")
	)
	(segment
		(start 375.91619 -121.75998)
		(end 374.86844 -121.75998)
		(width 0.0889)
		(layer "In2.Cu")
		(net "P3E_CPU0_PE1_PCH_RXP<6>")
	)
	(segment
		(start 331.65669 -106.762804)
		(end 331.130402 -104.04983)
		(width 0.1143)
		(layer "In2.Cu")
		(net "P3E_CPU0_PE1_PCH_RXP<6>")
	)
	(segment
		(start 350.753172 -115.918742)
		(end 349.715836 -115.717066)
		(width 0.1143)
		(layer "In2.Cu")
		(net "P3E_CPU0_PE1_PCH_RXP<6>")
	)
	(segment
		(start 378.65304 -121.811288)
		(end 378.563632 -121.787412)
		(width 0.0889)
		(layer "In2.Cu")
		(net "P3E_CPU0_PE1_PCH_RXP<6>")
	)
	(segment
		(start 341.891112 -111.92637)
		(end 341.179404 -111.92637)
		(width 0.1143)
		(layer "In2.Cu")
		(net "P3E_CPU0_PE1_PCH_RXP<6>")
	)
	(segment
		(start 378.82195 -122.104404)
		(end 378.65304 -121.811288)
		(width 0.0889)
		(layer "In2.Cu")
		(net "P3E_CPU0_PE1_PCH_RXP<6>")
	)
	(segment
		(start 369.667282 -121.81078)
		(end 365.544862 -119.381016)
		(width 0.1143)
		(layer "In2.Cu")
		(net "P3E_CPU0_PE1_PCH_RXP<6>")
	)
	(segment
		(start 347.268038 -115.234466)
		(end 347.160596 -114.68354)
		(width 0.1143)
		(layer "In2.Cu")
		(net "P3E_CPU0_PE1_PCH_RXP<6>")
	)
	(segment
		(start 343.116408 -113.1951)
		(end 342.651842 -113.1951)
		(width 0.1143)
		(layer "In2.Cu")
		(net "P3E_CPU0_PE1_PCH_RXP<6>")
	)
	(segment
		(start 354.62337 -117.946932)
		(end 353.411282 -117.71122)
		(width 0.1143)
		(layer "In2.Cu")
		(net "P3E_CPU0_PE1_PCH_RXP<6>")
	)
	(segment
		(start 331.130402 -104.04983)
		(end 331.53985 -101.941884)
		(width 0.1143)
		(layer "In2.Cu")
		(net "P3E_CPU0_PE1_PCH_RXP<6>")
	)
	(segment
		(start 342.651842 -113.1951)
		(end 342.138 -112.681258)
		(width 0.1143)
		(layer "In2.Cu")
		(net "P3E_CPU0_PE1_PCH_RXP<6>")
	)
	(segment
		(start 377.831096 -121.703846)
		(end 377.571254 -121.703846)
		(width 0.0889)
		(layer "In2.Cu")
		(net "P3E_CPU0_PE1_PCH_RXP<6>")
	)
	(segment
		(start 346.930218 -114.488214)
		(end 346.235782 -114.353086)
		(width 0.1143)
		(layer "In2.Cu")
		(net "P3E_CPU0_PE1_PCH_RXP<6>")
	)
	(segment
		(start 335.251044 -66.736214)
		(end 336.95005 -66.736214)
		(width 0.1143)
		(layer "In2.Cu")
		(net "P3E_CPU0_PE1_PCH_RXP<6>")
	)
	(segment
		(start 344.788236 -114.32286)
		(end 343.116408 -113.1951)
		(width 0.1143)
		(layer "In2.Cu")
		(net "P3E_CPU0_PE1_PCH_RXP<6>")
	)
	(segment
		(start 365.5441 -119.380762)
		(end 360.653838 -117.653054)
		(width 0.1143)
		(layer "In2.Cu")
		(net "P3E_CPU0_PE1_PCH_RXP<6>")
	)
	(segment
		(start 331.53985 -101.941884)
		(end 330.746862 -97.862136)
		(width 0.1143)
		(layer "In2.Cu")
		(net "P3E_CPU0_PE1_PCH_RXP<6>")
	)
	(segment
		(start 333.590646 -110.61065)
		(end 333.22895 -110.248954)
		(width 0.1143)
		(layer "In2.Cu")
		(net "P3E_CPU0_PE1_PCH_RXP<6>")
	)
	(segment
		(start 345.590368 -114.478562)
		(end 344.788236 -114.32286)
		(width 0.1143)
		(layer "In2.Cu")
		(net "P3E_CPU0_PE1_PCH_RXP<6>")
	)
	(segment
		(start 330.746862 -97.862136)
		(end 331.413612 -94.433136)
		(width 0.1143)
		(layer "In2.Cu")
		(net "P3E_CPU0_PE1_PCH_RXP<6>")
	)
	(segment
		(start 331.413612 -94.433136)
		(end 330.827126 -91.417394)
		(width 0.1143)
		(layer "In2.Cu")
		(net "P3E_CPU0_PE1_PCH_RXP<6>")
	)
	(segment
		(start 340.234778 -65.728596)
		(end 346.450158 -65.728596)
		(width 0.1143)
		(layer "In2.Cu")
		(net "P3E_CPU0_PE1_PCH_RXP<6>")
	)
	(segment
		(start 332.694534 -107.462828)
		(end 331.65669 -106.762804)
		(width 0.1143)
		(layer "In2.Cu")
		(net "P3E_CPU0_PE1_PCH_RXP<6>")
	)
	(segment
		(start 346.7354 -66.013838)
		(end 346.7354 -67.135502)
		(width 0.1143)
		(layer "In2.Cu")
		(net "P3E_CPU0_PE1_PCH_RXP<6>")
	)
	(segment
		(start 347.457776 -115.516406)
		(end 347.268038 -115.234466)
		(width 0.1143)
		(layer "In2.Cu")
		(net "P3E_CPU0_PE1_PCH_RXP<6>")
	)
	(segment
		(start 346.450158 -65.728596)
		(end 346.7354 -66.013838)
		(width 0.1143)
		(layer "In2.Cu")
		(net "P3E_CPU0_PE1_PCH_RXP<6>")
	)
	(segment
		(start 339.711538 -66.251836)
		(end 340.234778 -65.728596)
		(width 0.1143)
		(layer "In2.Cu")
		(net "P3E_CPU0_PE1_PCH_RXP<6>")
	)
	(segment
		(start 346.235782 -114.353086)
		(end 345.590368 -114.478562)
		(width 0.1143)
		(layer "In2.Cu")
		(net "P3E_CPU0_PE1_PCH_RXP<6>")
	)
	(segment
		(start 353.411282 -117.71122)
		(end 350.753172 -115.918742)
		(width 0.1143)
		(layer "In2.Cu")
		(net "P3E_CPU0_PE1_PCH_RXP<6>")
	)
	(segment
		(start 358.394 -117.213888)
		(end 354.62337 -117.946932)
		(width 0.1143)
		(layer "In2.Cu")
		(net "P3E_CPU0_PE1_PCH_RXP<6>")
	)
	(segment
		(start 342.138 -112.173258)
		(end 341.891112 -111.92637)
		(width 0.1143)
		(layer "In2.Cu")
		(net "P3E_CPU0_PE1_PCH_RXP<6>")
	)
	(segment
		(start 336.931 -111.105188)
		(end 334.386936 -110.61065)
		(width 0.1143)
		(layer "In2.Cu")
		(net "P3E_CPU0_PE1_PCH_RXP<6>")
	)
	(segment
		(start 333.22895 -110.248954)
		(end 333.22895 -108.255054)
		(width 0.1143)
		(layer "In2.Cu")
		(net "P3E_CPU0_PE1_PCH_RXP<6>")
	)
	(segment
		(start 333.22895 -108.255054)
		(end 332.694534 -107.462828)
		(width 0.1143)
		(layer "In2.Cu")
		(net "P3E_CPU0_PE1_PCH_RXP<6>")
	)
	(segment
		(start 340.025228 -111.702088)
		(end 338.868766 -111.926878)
		(width 0.1143)
		(layer "In2.Cu")
		(net "P3E_CPU0_PE1_PCH_RXP<6>")
	)
	(segment
		(start 337.434428 -66.251836)
		(end 339.711538 -66.251836)
		(width 0.1143)
		(layer "In2.Cu")
		(net "P3E_CPU0_PE1_PCH_RXP<6>")
	)
	(segment
		(start 349.715836 -115.717066)
		(end 348.807278 -115.893596)
		(width 0.1143)
		(layer "In2.Cu")
		(net "P3E_CPU0_PE1_PCH_RXP<6>")
	)
	(segment
		(start 328.160126 -81.289398)
		(end 327.281794 -76.84389)
		(width 0.1143)
		(layer "In2.Cu")
		(net "P3E_CPU0_PE1_PCH_RXP<6>")
	)
	(segment
		(start 365.544354 -119.380762)
		(end 365.5441 -119.380762)
		(width 0.1143)
		(layer "In2.Cu")
		(net "P3E_CPU0_PE1_PCH_RXP<6>")
	)
	(segment
		(start 330.827126 -91.417394)
		(end 331.693774 -86.955884)
		(width 0.1143)
		(layer "In2.Cu")
		(net "P3E_CPU0_PE1_PCH_RXP<6>")
	)
	(segment
		(start 334.386936 -110.61065)
		(end 333.590646 -110.61065)
		(width 0.1143)
		(layer "In2.Cu")
		(net "P3E_CPU0_PE1_PCH_RXP<6>")
	)
	(segment
		(start 365.544862 -119.381016)
		(end 365.544354 -119.380762)
		(width 0.1143)
		(layer "In2.Cu")
		(net "P3E_CPU0_PE1_PCH_RXP<6>")
	)
	(segment
		(start 341.179404 -111.92637)
		(end 340.025228 -111.702088)
		(width 0.1143)
		(layer "In2.Cu")
		(net "P3E_CPU0_PE1_PCH_RXP<6>")
	)
	(segment
		(start 327.281794 -76.84389)
		(end 329.145392 -69.605906)
		(width 0.1143)
		(layer "In2.Cu")
		(net "P3E_CPU0_PE1_PCH_RXP<6>")
	)
	(segment
		(start 342.138 -112.681258)
		(end 342.138 -112.173258)
		(width 0.1143)
		(layer "In2.Cu")
		(net "P3E_CPU0_PE1_PCH_RXP<6>")
	)
	(segment
		(start 376.111262 -121.955052)
		(end 375.91619 -121.75998)
		(width 0.0889)
		(layer "In2.Cu")
		(net "P3E_CPU0_PE1_PCH_RXP<6>")
	)
	(segment
		(start 374.81764 -121.81078)
		(end 374.795542 -121.81078)
		(width 0.0889)
		(layer "In2.Cu")
		(net "P3E_CPU0_PE1_PCH_RXP<6>")
	)
	(segment
		(start 374.795542 -121.81078)
		(end 369.667282 -121.81078)
		(width 0.1143)
		(layer "In2.Cu")
		(net "P3E_CPU0_PE1_PCH_RXP<6>")
	)
	(segment
		(start 331.693774 -86.955884)
		(end 331.694282 -86.955884)
		(width 0.1143)
		(layer "In2.Cu")
		(net "P3E_CPU0_PE1_PCH_RXP<6>")
	)
	(segment
		(start 348.807278 -115.893596)
		(end 347.697806 -115.67795)
		(width 0.1143)
		(layer "In2.Cu")
		(net "P3E_CPU0_PE1_PCH_RXP<6>")
	)
	(segment
		(start 347.112336 -114.610896)
		(end 346.930218 -114.488214)
		(width 0.1143)
		(layer "In2.Cu")
		(net "P3E_CPU0_PE1_PCH_RXP<6>")
	)
	(segment
		(start 338.868766 -111.926878)
		(end 337.858608 -111.730536)
		(width 0.1143)
		(layer "In2.Cu")
		(net "P3E_CPU0_PE1_PCH_RXP<6>")
	)
	(arc
		(start 378.031248 -121.757694)
		(mid 377.934722 -121.717559)
		(end 377.831096 -121.703846)
		(width 0.0889)
		(layer "In2.Cu")
		(net "P3E_CPU0_PE1_PCH_RXP<6>")
	)
	(arc
		(start 378.563632 -121.787412)
		(mid 378.293907 -121.835972)
		(end 378.031248 -121.757694)
		(width 0.0889)
		(layer "In2.Cu")
		(net "P3E_CPU0_PE1_PCH_RXP<6>")
	)
	(segment
		(start 378.82195 -121.01576)
		(end 379.31725 -121.245884)
		(width 0.1143)
		(layer "F.Cu")
		(net "P3E_CPU0_PE1_PCH_RXP<5>")
	)
	(via
		(at 343.526872 -67.48653)
		(size 0.508)
		(drill 0.254)
		(layers "F.Cu" "B.Cu")
		(net "P3E_CPU0_PE1_PCH_RXP<5>")
	)
	(via
		(at 379.31725 -121.245884)
		(size 0.508)
		(drill 0.254)
		(layers "F.Cu" "B.Cu")
		(net "P3E_CPU0_PE1_PCH_RXP<5>")
	)
	(via
		(at 346.163392 -64.086232)
		(size 0.508)
		(drill 0.254)
		(layers "F.Cu" "B.Cu")
		(net "P3E_CPU0_PE1_PCH_RXP<5>")
	)
	(segment
		(start 347.884242 -62.365382)
		(end 346.163392 -64.086232)
		(width 0.1143)
		(layer "B.Cu")
		(net "P3E_CPU0_PE1_PCH_RXP<5>")
	)
	(segment
		(start 347.884242 -61.82487)
		(end 347.884242 -62.365382)
		(width 0.1143)
		(layer "B.Cu")
		(net "P3E_CPU0_PE1_PCH_RXP<5>")
	)
	(segment
		(start 343.888822 -67.12458)
		(end 343.526872 -67.48653)
		(width 0.1143)
		(layer "B.Cu")
		(net "P3E_CPU0_PE1_PCH_RXP<5>")
	)
	(segment
		(start 347.316806 -61.257434)
		(end 347.884242 -61.82487)
		(width 0.1143)
		(layer "B.Cu")
		(net "P3E_CPU0_PE1_PCH_RXP<5>")
	)
	(segment
		(start 343.888822 -66.360802)
		(end 343.888822 -67.12458)
		(width 0.1143)
		(layer "B.Cu")
		(net "P3E_CPU0_PE1_PCH_RXP<5>")
	)
	(segment
		(start 346.163392 -64.086232)
		(end 343.888822 -66.360802)
		(width 0.1143)
		(layer "B.Cu")
		(net "P3E_CPU0_PE1_PCH_RXP<5>")
	)
	(segment
		(start 348.35211 -91.035378)
		(end 342.824054 -89.929462)
		(width 0.1143)
		(layer "In2.Cu")
		(net "P3E_CPU0_PE1_PCH_RXP<5>")
	)
	(segment
		(start 329.50785 -72.184768)
		(end 329.593702 -71.85279)
		(width 0.1143)
		(layer "In2.Cu")
		(net "P3E_CPU0_PE1_PCH_RXP<5>")
	)
	(segment
		(start 333.719932 -87.688928)
		(end 333.531972 -87.387176)
		(width 0.1143)
		(layer "In2.Cu")
		(net "P3E_CPU0_PE1_PCH_RXP<5>")
	)
	(segment
		(start 377.913392 -120.8024)
		(end 377.578112 -120.8024)
		(width 0.0889)
		(layer "In2.Cu")
		(net "P3E_CPU0_PE1_PCH_RXP<5>")
	)
	(segment
		(start 375.942098 -120.755156)
		(end 375.853198 -120.666256)
		(width 0.0889)
		(layer "In2.Cu")
		(net "P3E_CPU0_PE1_PCH_RXP<5>")
	)
	(segment
		(start 360.23296 -102.535736)
		(end 358.90835 -101.626924)
		(width 0.1143)
		(layer "In2.Cu")
		(net "P3E_CPU0_PE1_PCH_RXP<5>")
	)
	(segment
		(start 329.203558 -79.237078)
		(end 329.009756 -79.10703)
		(width 0.1143)
		(layer "In2.Cu")
		(net "P3E_CPU0_PE1_PCH_RXP<5>")
	)
	(segment
		(start 374.837198 -120.666256)
		(end 374.748298 -120.755156)
		(width 0.0889)
		(layer "In2.Cu")
		(net "P3E_CPU0_PE1_PCH_RXP<5>")
	)
	(segment
		(start 374.379998 -120.666256)
		(end 374.100598 -120.666256)
		(width 0.0889)
		(layer "In2.Cu")
		(net "P3E_CPU0_PE1_PCH_RXP<5>")
	)
	(segment
		(start 334.13573 -88.043512)
		(end 333.947516 -87.74176)
		(width 0.1143)
		(layer "In2.Cu")
		(net "P3E_CPU0_PE1_PCH_RXP<5>")
	)
	(segment
		(start 329.084178 -73.82002)
		(end 329.2856 -73.701402)
		(width 0.1143)
		(layer "In2.Cu")
		(net "P3E_CPU0_PE1_PCH_RXP<5>")
	)
	(segment
		(start 362.29671 -117.194838)
		(end 361.519724 -116.234464)
		(width 0.1143)
		(layer "In2.Cu")
		(net "P3E_CPU0_PE1_PCH_RXP<5>")
	)
	(segment
		(start 379.655324 -121.245884)
		(end 379.713236 -121.303796)
		(width 0.0889)
		(layer "In2.Cu")
		(net "P3E_CPU0_PE1_PCH_RXP<5>")
	)
	(segment
		(start 337.404202 -67.663314)
		(end 337.88858 -67.178936)
		(width 0.1143)
		(layer "In2.Cu")
		(net "P3E_CPU0_PE1_PCH_RXP<5>")
	)
	(segment
		(start 329.270106 -79.573374)
		(end 329.203558 -79.237078)
		(width 0.1143)
		(layer "In2.Cu")
		(net "P3E_CPU0_PE1_PCH_RXP<5>")
	)
	(segment
		(start 378.9172 -121.25706)
		(end 378.9172 -121.224294)
		(width 0.0889)
		(layer "In2.Cu")
		(net "P3E_CPU0_PE1_PCH_RXP<5>")
	)
	(segment
		(start 375.484898 -120.755156)
		(end 375.205498 -120.755156)
		(width 0.0889)
		(layer "In2.Cu")
		(net "P3E_CPU0_PE1_PCH_RXP<5>")
	)
	(segment
		(start 336.937858 -90.171778)
		(end 334.271112 -88.572594)
		(width 0.1143)
		(layer "In2.Cu")
		(net "P3E_CPU0_PE1_PCH_RXP<5>")
	)
	(segment
		(start 361.12958 -112.011206)
		(end 360.873802 -111.21009)
		(width 0.1143)
		(layer "In2.Cu")
		(net "P3E_CPU0_PE1_PCH_RXP<5>")
	)
	(segment
		(start 329.795124 -71.734426)
		(end 329.880976 -71.402448)
		(width 0.1143)
		(layer "In2.Cu")
		(net "P3E_CPU0_PE1_PCH_RXP<5>")
	)
	(segment
		(start 358.17048 -94.442534)
		(end 357.160322 -93.661484)
		(width 0.1143)
		(layer "In2.Cu")
		(net "P3E_CPU0_PE1_PCH_RXP<5>")
	)
	(segment
		(start 333.531972 -87.387176)
		(end 333.58455 -87.159846)
		(width 0.1143)
		(layer "In2.Cu")
		(net "P3E_CPU0_PE1_PCH_RXP<5>")
	)
	(segment
		(start 332.980792 -86.50351)
		(end 333.03337 -86.27618)
		(width 0.1143)
		(layer "In2.Cu")
		(net "P3E_CPU0_PE1_PCH_RXP<5>")
	)
	(segment
		(start 375.205498 -120.755156)
		(end 375.116598 -120.666256)
		(width 0.0889)
		(layer "In2.Cu")
		(net "P3E_CPU0_PE1_PCH_RXP<5>")
	)
	(segment
		(start 360.873802 -111.21009)
		(end 361.211368 -109.973364)
		(width 0.1143)
		(layer "In2.Cu")
		(net "P3E_CPU0_PE1_PCH_RXP<5>")
	)
	(segment
		(start 373.275098 -120.755156)
		(end 372.995698 -120.755156)
		(width 0.0889)
		(layer "In2.Cu")
		(net "P3E_CPU0_PE1_PCH_RXP<5>")
	)
	(segment
		(start 365.713518 -118.402354)
		(end 362.29671 -117.194838)
		(width 0.1143)
		(layer "In2.Cu")
		(net "P3E_CPU0_PE1_PCH_RXP<5>")
	)
	(segment
		(start 374.748298 -120.755156)
		(end 374.468898 -120.755156)
		(width 0.0889)
		(layer "In2.Cu")
		(net "P3E_CPU0_PE1_PCH_RXP<5>")
	)
	(segment
		(start 343.953592 -67.272154)
		(end 343.739216 -67.48653)
		(width 0.1143)
		(layer "In2.Cu")
		(net "P3E_CPU0_PE1_PCH_RXP<5>")
	)
	(segment
		(start 333.03337 -86.27618)
		(end 332.84541 -85.974428)
		(width 0.1143)
		(layer "In2.Cu")
		(net "P3E_CPU0_PE1_PCH_RXP<5>")
	)
	(segment
		(start 369.6208 -120.704356)
		(end 365.713518 -118.402354)
		(width 0.1143)
		(layer "In2.Cu")
		(net "P3E_CPU0_PE1_PCH_RXP<5>")
	)
	(segment
		(start 372.944898 -120.704356)
		(end 372.9228 -120.704356)
		(width 0.0889)
		(layer "In2.Cu")
		(net "P3E_CPU0_PE1_PCH_RXP<5>")
	)
	(segment
		(start 333.169006 -86.805262)
		(end 332.980792 -86.50351)
		(width 0.1143)
		(layer "In2.Cu")
		(net "P3E_CPU0_PE1_PCH_RXP<5>")
	)
	(segment
		(start 377.578112 -120.8024)
		(end 377.530868 -120.755156)
		(width 0.0889)
		(layer "In2.Cu")
		(net "P3E_CPU0_PE1_PCH_RXP<5>")
	)
	(segment
		(start 329.540362 -72.717914)
		(end 329.626214 -72.385936)
		(width 0.1143)
		(layer "In2.Cu")
		(net "P3E_CPU0_PE1_PCH_RXP<5>")
	)
	(segment
		(start 361.211368 -109.973364)
		(end 360.7943 -108.005118)
		(width 0.1143)
		(layer "In2.Cu")
		(net "P3E_CPU0_PE1_PCH_RXP<5>")
	)
	(segment
		(start 329.593702 -71.85279)
		(end 329.795124 -71.734426)
		(width 0.1143)
		(layer "In2.Cu")
		(net "P3E_CPU0_PE1_PCH_RXP<5>")
	)
	(segment
		(start 339.673692 -90.719148)
		(end 336.937858 -90.171778)
		(width 0.1143)
		(layer "In2.Cu")
		(net "P3E_CPU0_PE1_PCH_RXP<5>")
	)
	(segment
		(start 373.732298 -120.755156)
		(end 373.643398 -120.666256)
		(width 0.0889)
		(layer "In2.Cu")
		(net "P3E_CPU0_PE1_PCH_RXP<5>")
	)
	(segment
		(start 340.619334 -66.655696)
		(end 343.737692 -66.655696)
		(width 0.1143)
		(layer "In2.Cu")
		(net "P3E_CPU0_PE1_PCH_RXP<5>")
	)
	(segment
		(start 332.84541 -85.974428)
		(end 332.617826 -85.921596)
		(width 0.1143)
		(layer "In2.Cu")
		(net "P3E_CPU0_PE1_PCH_RXP<5>")
	)
	(segment
		(start 343.953592 -66.871596)
		(end 343.953592 -67.272154)
		(width 0.1143)
		(layer "In2.Cu")
		(net "P3E_CPU0_PE1_PCH_RXP<5>")
	)
	(segment
		(start 342.824054 -89.929462)
		(end 339.673692 -90.719148)
		(width 0.1143)
		(layer "In2.Cu")
		(net "P3E_CPU0_PE1_PCH_RXP<5>")
	)
	(segment
		(start 329.2856 -73.701402)
		(end 329.371452 -73.369678)
		(width 0.1143)
		(layer "In2.Cu")
		(net "P3E_CPU0_PE1_PCH_RXP<5>")
	)
	(segment
		(start 372.9228 -120.704356)
		(end 369.6208 -120.704356)
		(width 0.1143)
		(layer "In2.Cu")
		(net "P3E_CPU0_PE1_PCH_RXP<5>")
	)
	(segment
		(start 360.614976 -113.89741)
		(end 361.12958 -112.011206)
		(width 0.1143)
		(layer "In2.Cu")
		(net "P3E_CPU0_PE1_PCH_RXP<5>")
	)
	(segment
		(start 374.100598 -120.666256)
		(end 374.011698 -120.755156)
		(width 0.0889)
		(layer "In2.Cu")
		(net "P3E_CPU0_PE1_PCH_RXP<5>")
	)
	(segment
		(start 375.853198 -120.666256)
		(end 375.573798 -120.666256)
		(width 0.0889)
		(layer "In2.Cu")
		(net "P3E_CPU0_PE1_PCH_RXP<5>")
	)
	(segment
		(start 329.762612 -71.20128)
		(end 330.011278 -70.24116)
		(width 0.1143)
		(layer "In2.Cu")
		(net "P3E_CPU0_PE1_PCH_RXP<5>")
	)
	(segment
		(start 375.573798 -120.666256)
		(end 375.484898 -120.755156)
		(width 0.0889)
		(layer "In2.Cu")
		(net "P3E_CPU0_PE1_PCH_RXP<5>")
	)
	(segment
		(start 328.812652 -78.110334)
		(end 328.449178 -76.271628)
		(width 0.1143)
		(layer "In2.Cu")
		(net "P3E_CPU0_PE1_PCH_RXP<5>")
	)
	(segment
		(start 357.892096 -98.796348)
		(end 358.54894 -96.17202)
		(width 0.1143)
		(layer "In2.Cu")
		(net "P3E_CPU0_PE1_PCH_RXP<5>")
	)
	(segment
		(start 334.082898 -88.270842)
		(end 334.13573 -88.043512)
		(width 0.1143)
		(layer "In2.Cu")
		(net "P3E_CPU0_PE1_PCH_RXP<5>")
	)
	(segment
		(start 357.160322 -93.661484)
		(end 355.312472 -90.89009)
		(width 0.1143)
		(layer "In2.Cu")
		(net "P3E_CPU0_PE1_PCH_RXP<5>")
	)
	(segment
		(start 378.031248 -120.734074)
		(end 377.913392 -120.8024)
		(width 0.0889)
		(layer "In2.Cu")
		(net "P3E_CPU0_PE1_PCH_RXP<5>")
	)
	(segment
		(start 343.737692 -66.655696)
		(end 343.953592 -66.871596)
		(width 0.1143)
		(layer "In2.Cu")
		(net "P3E_CPU0_PE1_PCH_RXP<5>")
	)
	(segment
		(start 340.096094 -67.178936)
		(end 340.619334 -66.655696)
		(width 0.1143)
		(layer "In2.Cu")
		(net "P3E_CPU0_PE1_PCH_RXP<5>")
	)
	(segment
		(start 332.482444 -85.392514)
		(end 332.29423 -85.090762)
		(width 0.1143)
		(layer "In2.Cu")
		(net "P3E_CPU0_PE1_PCH_RXP<5>")
	)
	(segment
		(start 361.519724 -116.234464)
		(end 360.614976 -113.89741)
		(width 0.1143)
		(layer "In2.Cu")
		(net "P3E_CPU0_PE1_PCH_RXP<5>")
	)
	(segment
		(start 334.271112 -88.572594)
		(end 334.082898 -88.270842)
		(width 0.1143)
		(layer "In2.Cu")
		(net "P3E_CPU0_PE1_PCH_RXP<5>")
	)
	(segment
		(start 332.429612 -85.619844)
		(end 332.482444 -85.392514)
		(width 0.1143)
		(layer "In2.Cu")
		(net "P3E_CPU0_PE1_PCH_RXP<5>")
	)
	(segment
		(start 377.530868 -120.755156)
		(end 375.942098 -120.755156)
		(width 0.0889)
		(layer "In2.Cu")
		(net "P3E_CPU0_PE1_PCH_RXP<5>")
	)
	(segment
		(start 329.880976 -71.402448)
		(end 329.762612 -71.20128)
		(width 0.1143)
		(layer "In2.Cu")
		(net "P3E_CPU0_PE1_PCH_RXP<5>")
	)
	(segment
		(start 358.90835 -101.626924)
		(end 357.892096 -98.796348)
		(width 0.1143)
		(layer "In2.Cu")
		(net "P3E_CPU0_PE1_PCH_RXP<5>")
	)
	(segment
		(start 379.31725 -121.245884)
		(end 379.655324 -121.245884)
		(width 0.0889)
		(layer "In2.Cu")
		(net "P3E_CPU0_PE1_PCH_RXP<5>")
	)
	(segment
		(start 329.626214 -72.385936)
		(end 329.50785 -72.184768)
		(width 0.1143)
		(layer "In2.Cu")
		(net "P3E_CPU0_PE1_PCH_RXP<5>")
	)
	(segment
		(start 372.995698 -120.755156)
		(end 372.944898 -120.704356)
		(width 0.0889)
		(layer "In2.Cu")
		(net "P3E_CPU0_PE1_PCH_RXP<5>")
	)
	(segment
		(start 373.643398 -120.666256)
		(end 373.363998 -120.666256)
		(width 0.0889)
		(layer "In2.Cu")
		(net "P3E_CPU0_PE1_PCH_RXP<5>")
	)
	(segment
		(start 332.066646 -85.03793)
		(end 329.307444 -80.613758)
		(width 0.1143)
		(layer "In2.Cu")
		(net "P3E_CPU0_PE1_PCH_RXP<5>")
	)
	(segment
		(start 329.006708 -78.240382)
		(end 328.812652 -78.110334)
		(width 0.1143)
		(layer "In2.Cu")
		(net "P3E_CPU0_PE1_PCH_RXP<5>")
	)
	(segment
		(start 352.189796 -90.254582)
		(end 348.35211 -91.035378)
		(width 0.1143)
		(layer "In2.Cu")
		(net "P3E_CPU0_PE1_PCH_RXP<5>")
	)
	(segment
		(start 329.073002 -78.576678)
		(end 329.006708 -78.240382)
		(width 0.1143)
		(layer "In2.Cu")
		(net "P3E_CPU0_PE1_PCH_RXP<5>")
	)
	(segment
		(start 333.947516 -87.74176)
		(end 333.719932 -87.688928)
		(width 0.1143)
		(layer "In2.Cu")
		(net "P3E_CPU0_PE1_PCH_RXP<5>")
	)
	(segment
		(start 333.58455 -87.159846)
		(end 333.396336 -86.858094)
		(width 0.1143)
		(layer "In2.Cu")
		(net "P3E_CPU0_PE1_PCH_RXP<5>")
	)
	(segment
		(start 329.009756 -79.10703)
		(end 328.943208 -78.770734)
		(width 0.1143)
		(layer "In2.Cu")
		(net "P3E_CPU0_PE1_PCH_RXP<5>")
	)
	(segment
		(start 375.116598 -120.666256)
		(end 374.837198 -120.666256)
		(width 0.0889)
		(layer "In2.Cu")
		(net "P3E_CPU0_PE1_PCH_RXP<5>")
	)
	(segment
		(start 333.396336 -86.858094)
		(end 333.169006 -86.805262)
		(width 0.1143)
		(layer "In2.Cu")
		(net "P3E_CPU0_PE1_PCH_RXP<5>")
	)
	(segment
		(start 332.617826 -85.921596)
		(end 332.429612 -85.619844)
		(width 0.1143)
		(layer "In2.Cu")
		(net "P3E_CPU0_PE1_PCH_RXP<5>")
	)
	(segment
		(start 329.253088 -73.168256)
		(end 329.33894 -72.836278)
		(width 0.1143)
		(layer "In2.Cu")
		(net "P3E_CPU0_PE1_PCH_RXP<5>")
	)
	(segment
		(start 329.307444 -80.613758)
		(end 329.140058 -79.76743)
		(width 0.1143)
		(layer "In2.Cu")
		(net "P3E_CPU0_PE1_PCH_RXP<5>")
	)
	(segment
		(start 343.739216 -67.48653)
		(end 343.526872 -67.48653)
		(width 0.1143)
		(layer "In2.Cu")
		(net "P3E_CPU0_PE1_PCH_RXP<5>")
	)
	(segment
		(start 329.140058 -79.76743)
		(end 329.270106 -79.573374)
		(width 0.1143)
		(layer "In2.Cu")
		(net "P3E_CPU0_PE1_PCH_RXP<5>")
	)
	(segment
		(start 373.363998 -120.666256)
		(end 373.275098 -120.755156)
		(width 0.0889)
		(layer "In2.Cu")
		(net "P3E_CPU0_PE1_PCH_RXP<5>")
	)
	(segment
		(start 360.7943 -103.391716)
		(end 360.23296 -102.535736)
		(width 0.1143)
		(layer "In2.Cu")
		(net "P3E_CPU0_PE1_PCH_RXP<5>")
	)
	(segment
		(start 337.88858 -67.178936)
		(end 340.096094 -67.178936)
		(width 0.1143)
		(layer "In2.Cu")
		(net "P3E_CPU0_PE1_PCH_RXP<5>")
	)
	(segment
		(start 328.943208 -78.770734)
		(end 329.073002 -78.576678)
		(width 0.1143)
		(layer "In2.Cu")
		(net "P3E_CPU0_PE1_PCH_RXP<5>")
	)
	(segment
		(start 328.449178 -76.271628)
		(end 329.084178 -73.82002)
		(width 0.1143)
		(layer "In2.Cu")
		(net "P3E_CPU0_PE1_PCH_RXP<5>")
	)
	(segment
		(start 335.493614 -67.663314)
		(end 337.404202 -67.663314)
		(width 0.1143)
		(layer "In2.Cu")
		(net "P3E_CPU0_PE1_PCH_RXP<5>")
	)
	(segment
		(start 329.33894 -72.836278)
		(end 329.540362 -72.717914)
		(width 0.1143)
		(layer "In2.Cu")
		(net "P3E_CPU0_PE1_PCH_RXP<5>")
	)
	(segment
		(start 374.468898 -120.755156)
		(end 374.379998 -120.666256)
		(width 0.0889)
		(layer "In2.Cu")
		(net "P3E_CPU0_PE1_PCH_RXP<5>")
	)
	(segment
		(start 358.54894 -96.17202)
		(end 358.17048 -94.442534)
		(width 0.1143)
		(layer "In2.Cu")
		(net "P3E_CPU0_PE1_PCH_RXP<5>")
	)
	(segment
		(start 355.312472 -90.89009)
		(end 352.189796 -90.254582)
		(width 0.1143)
		(layer "In2.Cu")
		(net "P3E_CPU0_PE1_PCH_RXP<5>")
	)
	(segment
		(start 360.7943 -108.005118)
		(end 360.7943 -103.391716)
		(width 0.1143)
		(layer "In2.Cu")
		(net "P3E_CPU0_PE1_PCH_RXP<5>")
	)
	(segment
		(start 329.371452 -73.369678)
		(end 329.253088 -73.168256)
		(width 0.1143)
		(layer "In2.Cu")
		(net "P3E_CPU0_PE1_PCH_RXP<5>")
	)
	(segment
		(start 332.29423 -85.090762)
		(end 332.066646 -85.03793)
		(width 0.1143)
		(layer "In2.Cu")
		(net "P3E_CPU0_PE1_PCH_RXP<5>")
	)
	(segment
		(start 330.011278 -70.24116)
		(end 335.493614 -67.663314)
		(width 0.1143)
		(layer "In2.Cu")
		(net "P3E_CPU0_PE1_PCH_RXP<5>")
	)
	(segment
		(start 374.011698 -120.755156)
		(end 373.732298 -120.755156)
		(width 0.0889)
		(layer "In2.Cu")
		(net "P3E_CPU0_PE1_PCH_RXP<5>")
	)
	(arc
		(start 378.9172 -121.224294)
		(mid 378.612757 -120.728817)
		(end 378.031248 -120.734074)
		(width 0.0889)
		(layer "In2.Cu")
		(net "P3E_CPU0_PE1_PCH_RXP<5>")
	)
	(arc
		(start 379.713236 -121.303796)
		(mid 379.293794 -121.645394)
		(end 378.9172 -121.25706)
		(width 0.0889)
		(layer "In2.Cu")
		(net "P3E_CPU0_PE1_PCH_RXP<5>")
	)
	(segment
		(start 379.81255 -120.387364)
		(end 379.31725 -120.15724)
		(width 0.1143)
		(layer "F.Cu")
		(net "P3E_CPU0_PE1_PCH_RXP<4>")
	)
	(via
		(at 341.291672 -68.09613)
		(size 0.508)
		(drill 0.254)
		(layers "F.Cu" "B.Cu")
		(net "P3E_CPU0_PE1_PCH_RXP<4>")
	)
	(via
		(at 379.81255 -120.387364)
		(size 0.508)
		(drill 0.254)
		(layers "F.Cu" "B.Cu")
		(net "P3E_CPU0_PE1_PCH_RXP<4>")
	)
	(via
		(at 342.04656 -66.242184)
		(size 0.508)
		(drill 0.254)
		(layers "F.Cu" "B.Cu")
		(net "P3E_CPU0_PE1_PCH_RXP<4>")
	)
	(segment
		(start 345.115642 -63.173102)
		(end 345.115642 -61.85027)
		(width 0.1143)
		(layer "B.Cu")
		(net "P3E_CPU0_PE1_PCH_RXP<4>")
	)
	(segment
		(start 345.115642 -61.85027)
		(end 344.522806 -61.257434)
		(width 0.1143)
		(layer "B.Cu")
		(net "P3E_CPU0_PE1_PCH_RXP<4>")
	)
	(segment
		(start 341.291672 -68.09613)
		(end 341.65667 -67.731132)
		(width 0.1143)
		(layer "B.Cu")
		(net "P3E_CPU0_PE1_PCH_RXP<4>")
	)
	(segment
		(start 341.65667 -67.731132)
		(end 341.65667 -66.632074)
		(width 0.1143)
		(layer "B.Cu")
		(net "P3E_CPU0_PE1_PCH_RXP<4>")
	)
	(segment
		(start 342.04656 -66.242184)
		(end 345.115642 -63.173102)
		(width 0.1143)
		(layer "B.Cu")
		(net "P3E_CPU0_PE1_PCH_RXP<4>")
	)
	(segment
		(start 341.65667 -66.632074)
		(end 342.04656 -66.242184)
		(width 0.1143)
		(layer "B.Cu")
		(net "P3E_CPU0_PE1_PCH_RXP<4>")
	)
	(segment
		(start 372.906798 -119.6721)
		(end 372.627398 -119.6721)
		(width 0.0889)
		(layer "In2.Cu")
		(net "P3E_CPU0_PE1_PCH_RXP<4>")
	)
	(segment
		(start 374.011698 -119.761)
		(end 373.732298 -119.761)
		(width 0.0889)
		(layer "In2.Cu")
		(net "P3E_CPU0_PE1_PCH_RXP<4>")
	)
	(segment
		(start 341.406226 -67.327272)
		(end 341.607394 -67.52844)
		(width 0.1143)
		(layer "In2.Cu")
		(net "P3E_CPU0_PE1_PCH_RXP<4>")
	)
	(segment
		(start 374.100598 -119.6721)
		(end 374.011698 -119.761)
		(width 0.0889)
		(layer "In2.Cu")
		(net "P3E_CPU0_PE1_PCH_RXP<4>")
	)
	(segment
		(start 360.162348 -99.3775)
		(end 359.615486 -98.426524)
		(width 0.1143)
		(layer "In2.Cu")
		(net "P3E_CPU0_PE1_PCH_RXP<4>")
	)
	(segment
		(start 333.043784 -84.156804)
		(end 332.862428 -83.865974)
		(width 0.1143)
		(layer "In2.Cu")
		(net "P3E_CPU0_PE1_PCH_RXP<4>")
	)
	(segment
		(start 358.954324 -94.518226)
		(end 358.89692 -94.180152)
		(width 0.1143)
		(layer "In2.Cu")
		(net "P3E_CPU0_PE1_PCH_RXP<4>")
	)
	(segment
		(start 367.000282 -118.292118)
		(end 366.941862 -118.066058)
		(width 0.1143)
		(layer "In2.Cu")
		(net "P3E_CPU0_PE1_PCH_RXP<4>")
	)
	(segment
		(start 377.961652 -119.78005)
		(end 377.942602 -119.761)
		(width 0.0889)
		(layer "In2.Cu")
		(net "P3E_CPU0_PE1_PCH_RXP<4>")
	)
	(segment
		(start 359.371138 -95.993458)
		(end 359.313988 -95.65513)
		(width 0.1143)
		(layer "In2.Cu")
		(net "P3E_CPU0_PE1_PCH_RXP<4>")
	)
	(segment
		(start 374.468898 -119.761)
		(end 374.379998 -119.6721)
		(width 0.0889)
		(layer "In2.Cu")
		(net "P3E_CPU0_PE1_PCH_RXP<4>")
	)
	(segment
		(start 358.95407 -94.518226)
		(end 358.954324 -94.518226)
		(width 0.1143)
		(layer "In2.Cu")
		(net "P3E_CPU0_PE1_PCH_RXP<4>")
	)
	(segment
		(start 368.78387 -119.34317)
		(end 368.72545 -119.11711)
		(width 0.1143)
		(layer "In2.Cu")
		(net "P3E_CPU0_PE1_PCH_RXP<4>")
	)
	(segment
		(start 332.862428 -83.865974)
		(end 332.634844 -83.813142)
		(width 0.1143)
		(layer "In2.Cu")
		(net "P3E_CPU0_PE1_PCH_RXP<4>")
	)
	(segment
		(start 359.123742 -95.519748)
		(end 359.066592 -95.181928)
		(width 0.1143)
		(layer "In2.Cu")
		(net "P3E_CPU0_PE1_PCH_RXP<4>")
	)
	(segment
		(start 359.20172 -94.991682)
		(end 359.14457 -94.653608)
		(width 0.1143)
		(layer "In2.Cu")
		(net "P3E_CPU0_PE1_PCH_RXP<4>")
	)
	(segment
		(start 332.991206 -84.384388)
		(end 333.043784 -84.156804)
		(width 0.1143)
		(layer "In2.Cu")
		(net "P3E_CPU0_PE1_PCH_RXP<4>")
	)
	(segment
		(start 359.313988 -95.65513)
		(end 359.123488 -95.520002)
		(width 0.1143)
		(layer "In2.Cu")
		(net "P3E_CPU0_PE1_PCH_RXP<4>")
	)
	(segment
		(start 359.235756 -96.183704)
		(end 359.371138 -95.993458)
		(width 0.1143)
		(layer "In2.Cu")
		(net "P3E_CPU0_PE1_PCH_RXP<4>")
	)
	(segment
		(start 359.292906 -96.521778)
		(end 359.293414 -96.521778)
		(width 0.1143)
		(layer "In2.Cu")
		(net "P3E_CPU0_PE1_PCH_RXP<4>")
	)
	(segment
		(start 367.828322 -118.588282)
		(end 367.521744 -118.407688)
		(width 0.1143)
		(layer "In2.Cu")
		(net "P3E_CPU0_PE1_PCH_RXP<4>")
	)
	(segment
		(start 330.249022 -79.987902)
		(end 329.485244 -76.121768)
		(width 0.1143)
		(layer "In2.Cu")
		(net "P3E_CPU0_PE1_PCH_RXP<4>")
	)
	(segment
		(start 373.363998 -119.6721)
		(end 373.275098 -119.761)
		(width 0.0889)
		(layer "In2.Cu")
		(net "P3E_CPU0_PE1_PCH_RXP<4>")
	)
	(segment
		(start 359.615486 -98.426524)
		(end 359.405428 -97.18548)
		(width 0.1143)
		(layer "In2.Cu")
		(net "P3E_CPU0_PE1_PCH_RXP<4>")
	)
	(segment
		(start 361.794044 -111.997236)
		(end 361.556808 -111.253524)
		(width 0.1143)
		(layer "In2.Cu")
		(net "P3E_CPU0_PE1_PCH_RXP<4>")
	)
	(segment
		(start 341.607394 -67.780408)
		(end 341.291672 -68.09613)
		(width 0.1143)
		(layer "In2.Cu")
		(net "P3E_CPU0_PE1_PCH_RXP<4>")
	)
	(segment
		(start 338.175092 -67.81419)
		(end 340.359238 -67.81419)
		(width 0.1143)
		(layer "In2.Cu")
		(net "P3E_CPU0_PE1_PCH_RXP<4>")
	)
	(segment
		(start 359.23601 -96.183704)
		(end 359.235756 -96.183704)
		(width 0.1143)
		(layer "In2.Cu")
		(net "P3E_CPU0_PE1_PCH_RXP<4>")
	)
	(segment
		(start 368.193066 -118.994936)
		(end 367.886488 -118.814342)
		(width 0.1143)
		(layer "In2.Cu")
		(net "P3E_CPU0_PE1_PCH_RXP<4>")
	)
	(segment
		(start 366.4204 -117.950234)
		(end 365.937546 -117.665754)
		(width 0.1143)
		(layer "In2.Cu")
		(net "P3E_CPU0_PE1_PCH_RXP<4>")
	)
	(segment
		(start 330.800202 -80.871568)
		(end 330.85278 -80.643984)
		(width 0.1143)
		(layer "In2.Cu")
		(net "P3E_CPU0_PE1_PCH_RXP<4>")
	)
	(segment
		(start 330.93914 -70.508622)
		(end 335.638648 -68.298314)
		(width 0.1143)
		(layer "In2.Cu")
		(net "P3E_CPU0_PE1_PCH_RXP<4>")
	)
	(segment
		(start 367.521744 -118.407688)
		(end 367.295684 -118.466108)
		(width 0.1143)
		(layer "In2.Cu")
		(net "P3E_CPU0_PE1_PCH_RXP<4>")
	)
	(segment
		(start 331.351382 -81.755234)
		(end 331.40396 -81.52765)
		(width 0.1143)
		(layer "In2.Cu")
		(net "P3E_CPU0_PE1_PCH_RXP<4>")
	)
	(segment
		(start 375.484898 -119.761)
		(end 375.205498 -119.761)
		(width 0.0889)
		(layer "In2.Cu")
		(net "P3E_CPU0_PE1_PCH_RXP<4>")
	)
	(segment
		(start 330.988416 -81.17332)
		(end 330.800202 -80.871568)
		(width 0.1143)
		(layer "In2.Cu")
		(net "P3E_CPU0_PE1_PCH_RXP<4>")
	)
	(segment
		(start 375.116598 -119.6721)
		(end 374.837198 -119.6721)
		(width 0.0889)
		(layer "In2.Cu")
		(net "P3E_CPU0_PE1_PCH_RXP<4>")
	)
	(segment
		(start 331.215746 -81.225898)
		(end 330.988416 -81.17332)
		(width 0.1143)
		(layer "In2.Cu")
		(net "P3E_CPU0_PE1_PCH_RXP<4>")
	)
	(segment
		(start 372.627398 -119.6721)
		(end 372.538498 -119.761)
		(width 0.0889)
		(layer "In2.Cu")
		(net "P3E_CPU0_PE1_PCH_RXP<4>")
	)
	(segment
		(start 332.453488 -83.522312)
		(end 332.50632 -83.294982)
		(width 0.1143)
		(layer "In2.Cu")
		(net "P3E_CPU0_PE1_PCH_RXP<4>")
	)
	(segment
		(start 372.538498 -119.761)
		(end 372.259098 -119.761)
		(width 0.0889)
		(layer "In2.Cu")
		(net "P3E_CPU0_PE1_PCH_RXP<4>")
	)
	(segment
		(start 372.995698 -119.761)
		(end 372.906798 -119.6721)
		(width 0.0889)
		(layer "In2.Cu")
		(net "P3E_CPU0_PE1_PCH_RXP<4>")
	)
	(segment
		(start 366.64646 -117.891814)
		(end 366.4204 -117.950234)
		(width 0.1143)
		(layer "In2.Cu")
		(net "P3E_CPU0_PE1_PCH_RXP<4>")
	)
	(segment
		(start 374.748298 -119.761)
		(end 374.468898 -119.761)
		(width 0.0889)
		(layer "In2.Cu")
		(net "P3E_CPU0_PE1_PCH_RXP<4>")
	)
	(segment
		(start 335.470246 -88.358726)
		(end 332.991206 -84.384388)
		(width 0.1143)
		(layer "In2.Cu")
		(net "P3E_CPU0_PE1_PCH_RXP<4>")
	)
	(segment
		(start 331.40396 -81.52765)
		(end 331.215746 -81.225898)
		(width 0.1143)
		(layer "In2.Cu")
		(net "P3E_CPU0_PE1_PCH_RXP<4>")
	)
	(segment
		(start 359.405428 -97.18548)
		(end 359.540556 -96.99498)
		(width 0.1143)
		(layer "In2.Cu")
		(net "P3E_CPU0_PE1_PCH_RXP<4>")
	)
	(segment
		(start 361.286552 -113.855754)
		(end 361.794044 -111.997236)
		(width 0.1143)
		(layer "In2.Cu")
		(net "P3E_CPU0_PE1_PCH_RXP<4>")
	)
	(segment
		(start 330.437236 -80.289654)
		(end 330.249022 -79.987902)
		(width 0.1143)
		(layer "In2.Cu")
		(net "P3E_CPU0_PE1_PCH_RXP<4>")
	)
	(segment
		(start 374.379998 -119.6721)
		(end 374.100598 -119.6721)
		(width 0.0889)
		(layer "In2.Cu")
		(net "P3E_CPU0_PE1_PCH_RXP<4>")
	)
	(segment
		(start 359.123488 -95.520002)
		(end 359.123742 -95.519748)
		(width 0.1143)
		(layer "In2.Cu")
		(net "P3E_CPU0_PE1_PCH_RXP<4>")
	)
	(segment
		(start 369.406678 -119.7102)
		(end 368.78387 -119.34317)
		(width 0.1143)
		(layer "In2.Cu")
		(net "P3E_CPU0_PE1_PCH_RXP<4>")
	)
	(segment
		(start 332.50632 -83.294982)
		(end 332.318106 -82.99323)
		(width 0.1143)
		(layer "In2.Cu")
		(net "P3E_CPU0_PE1_PCH_RXP<4>")
	)
	(segment
		(start 352.126042 -89.543128)
		(end 348.371668 -90.293952)
		(width 0.1143)
		(layer "In2.Cu")
		(net "P3E_CPU0_PE1_PCH_RXP<4>")
	)
	(segment
		(start 371.801898 -119.761)
		(end 371.13718 -119.761)
		(width 0.0889)
		(layer "In2.Cu")
		(net "P3E_CPU0_PE1_PCH_RXP<4>")
	)
	(segment
		(start 335.638648 -68.298314)
		(end 337.690968 -68.298314)
		(width 0.1143)
		(layer "In2.Cu")
		(net "P3E_CPU0_PE1_PCH_RXP<4>")
	)
	(segment
		(start 360.848656 -101.390958)
		(end 360.352594 -101.05644)
		(width 0.1143)
		(layer "In2.Cu")
		(net "P3E_CPU0_PE1_PCH_RXP<4>")
	)
	(segment
		(start 379.4125 -120.39854)
		(end 379.4125 -120.365774)
		(width 0.0889)
		(layer "In2.Cu")
		(net "P3E_CPU0_PE1_PCH_RXP<4>")
	)
	(segment
		(start 373.275098 -119.761)
		(end 372.995698 -119.761)
		(width 0.0889)
		(layer "In2.Cu")
		(net "P3E_CPU0_PE1_PCH_RXP<4>")
	)
	(segment
		(start 374.837198 -119.6721)
		(end 374.748298 -119.761)
		(width 0.0889)
		(layer "In2.Cu")
		(net "P3E_CPU0_PE1_PCH_RXP<4>")
	)
	(segment
		(start 359.14457 -94.653608)
		(end 358.95407 -94.518226)
		(width 0.1143)
		(layer "In2.Cu")
		(net "P3E_CPU0_PE1_PCH_RXP<4>")
	)
	(segment
		(start 361.4293 -107.870498)
		(end 361.4293 -102.251256)
		(width 0.1143)
		(layer "In2.Cu")
		(net "P3E_CPU0_PE1_PCH_RXP<4>")
	)
	(segment
		(start 340.359238 -67.81419)
		(end 340.846156 -67.327272)
		(width 0.1143)
		(layer "In2.Cu")
		(net "P3E_CPU0_PE1_PCH_RXP<4>")
	)
	(segment
		(start 366.941862 -118.066058)
		(end 366.64646 -117.891814)
		(width 0.1143)
		(layer "In2.Cu")
		(net "P3E_CPU0_PE1_PCH_RXP<4>")
	)
	(segment
		(start 332.090522 -82.940398)
		(end 331.902308 -82.638646)
		(width 0.1143)
		(layer "In2.Cu")
		(net "P3E_CPU0_PE1_PCH_RXP<4>")
	)
	(segment
		(start 331.95514 -82.411316)
		(end 331.766926 -82.109564)
		(width 0.1143)
		(layer "In2.Cu")
		(net "P3E_CPU0_PE1_PCH_RXP<4>")
	)
	(segment
		(start 358.89692 -94.180152)
		(end 357.611172 -93.185234)
		(width 0.1143)
		(layer "In2.Cu")
		(net "P3E_CPU0_PE1_PCH_RXP<4>")
	)
	(segment
		(start 332.634844 -83.813142)
		(end 332.453488 -83.522312)
		(width 0.1143)
		(layer "In2.Cu")
		(net "P3E_CPU0_PE1_PCH_RXP<4>")
	)
	(segment
		(start 359.066338 -95.181928)
		(end 359.20172 -94.991682)
		(width 0.1143)
		(layer "In2.Cu")
		(net "P3E_CPU0_PE1_PCH_RXP<4>")
	)
	(segment
		(start 368.419126 -118.936516)
		(end 368.193066 -118.994936)
		(width 0.1143)
		(layer "In2.Cu")
		(net "P3E_CPU0_PE1_PCH_RXP<4>")
	)
	(segment
		(start 371.13718 -119.761)
		(end 371.08638 -119.7102)
		(width 0.0889)
		(layer "In2.Cu")
		(net "P3E_CPU0_PE1_PCH_RXP<4>")
	)
	(segment
		(start 340.846156 -67.327272)
		(end 341.406226 -67.327272)
		(width 0.1143)
		(layer "In2.Cu")
		(net "P3E_CPU0_PE1_PCH_RXP<4>")
	)
	(segment
		(start 355.640132 -90.22969)
		(end 352.126042 -89.543128)
		(width 0.1143)
		(layer "In2.Cu")
		(net "P3E_CPU0_PE1_PCH_RXP<4>")
	)
	(segment
		(start 371.08638 -119.7102)
		(end 371.064282 -119.7102)
		(width 0.0889)
		(layer "In2.Cu")
		(net "P3E_CPU0_PE1_PCH_RXP<4>")
	)
	(segment
		(start 359.540556 -96.99498)
		(end 359.483406 -96.656906)
		(width 0.1143)
		(layer "In2.Cu")
		(net "P3E_CPU0_PE1_PCH_RXP<4>")
	)
	(segment
		(start 337.690968 -68.298314)
		(end 338.175092 -67.81419)
		(width 0.1143)
		(layer "In2.Cu")
		(net "P3E_CPU0_PE1_PCH_RXP<4>")
	)
	(segment
		(start 371.064282 -119.7102)
		(end 369.406678 -119.7102)
		(width 0.1143)
		(layer "In2.Cu")
		(net "P3E_CPU0_PE1_PCH_RXP<4>")
	)
	(segment
		(start 359.066592 -95.181928)
		(end 359.066338 -95.181928)
		(width 0.1143)
		(layer "In2.Cu")
		(net "P3E_CPU0_PE1_PCH_RXP<4>")
	)
	(segment
		(start 342.791034 -89.177622)
		(end 339.690456 -89.954862)
		(width 0.1143)
		(layer "In2.Cu")
		(net "P3E_CPU0_PE1_PCH_RXP<4>")
	)
	(segment
		(start 331.539596 -82.056732)
		(end 331.351382 -81.755234)
		(width 0.1143)
		(layer "In2.Cu")
		(net "P3E_CPU0_PE1_PCH_RXP<4>")
	)
	(segment
		(start 371.890798 -119.6721)
		(end 371.801898 -119.761)
		(width 0.0889)
		(layer "In2.Cu")
		(net "P3E_CPU0_PE1_PCH_RXP<4>")
	)
	(segment
		(start 332.318106 -82.99323)
		(end 332.090522 -82.940398)
		(width 0.1143)
		(layer "In2.Cu")
		(net "P3E_CPU0_PE1_PCH_RXP<4>")
	)
	(segment
		(start 372.170198 -119.6721)
		(end 371.890798 -119.6721)
		(width 0.0889)
		(layer "In2.Cu")
		(net "P3E_CPU0_PE1_PCH_RXP<4>")
	)
	(segment
		(start 375.942098 -119.761)
		(end 375.853198 -119.6721)
		(width 0.0889)
		(layer "In2.Cu")
		(net "P3E_CPU0_PE1_PCH_RXP<4>")
	)
	(segment
		(start 348.371668 -90.293444)
		(end 342.791034 -89.177622)
		(width 0.1143)
		(layer "In2.Cu")
		(net "P3E_CPU0_PE1_PCH_RXP<4>")
	)
	(segment
		(start 375.573798 -119.6721)
		(end 375.484898 -119.761)
		(width 0.0889)
		(layer "In2.Cu")
		(net "P3E_CPU0_PE1_PCH_RXP<4>")
	)
	(segment
		(start 330.85278 -80.643984)
		(end 330.664566 -80.342232)
		(width 0.1143)
		(layer "In2.Cu")
		(net "P3E_CPU0_PE1_PCH_RXP<4>")
	)
	(segment
		(start 331.902308 -82.638646)
		(end 331.95514 -82.411316)
		(width 0.1143)
		(layer "In2.Cu")
		(net "P3E_CPU0_PE1_PCH_RXP<4>")
	)
	(segment
		(start 379.81255 -120.387364)
		(end 379.98146 -120.094248)
		(width 0.0889)
		(layer "In2.Cu")
		(net "P3E_CPU0_PE1_PCH_RXP<4>")
	)
	(segment
		(start 339.690456 -89.954862)
		(end 337.351878 -89.487248)
		(width 0.1143)
		(layer "In2.Cu")
		(net "P3E_CPU0_PE1_PCH_RXP<4>")
	)
	(segment
		(start 362.586016 -116.482368)
		(end 362.046012 -115.814602)
		(width 0.1143)
		(layer "In2.Cu")
		(net "P3E_CPU0_PE1_PCH_RXP<4>")
	)
	(segment
		(start 373.643398 -119.6721)
		(end 373.363998 -119.6721)
		(width 0.0889)
		(layer "In2.Cu")
		(net "P3E_CPU0_PE1_PCH_RXP<4>")
	)
	(segment
		(start 367.886488 -118.814342)
		(end 367.828322 -118.588282)
		(width 0.1143)
		(layer "In2.Cu")
		(net "P3E_CPU0_PE1_PCH_RXP<4>")
	)
	(segment
		(start 357.611172 -93.185234)
		(end 355.640132 -90.22969)
		(width 0.1143)
		(layer "In2.Cu")
		(net "P3E_CPU0_PE1_PCH_RXP<4>")
	)
	(segment
		(start 361.556808 -111.253524)
		(end 361.888532 -110.038134)
		(width 0.1143)
		(layer "In2.Cu")
		(net "P3E_CPU0_PE1_PCH_RXP<4>")
	)
	(segment
		(start 337.351878 -89.487248)
		(end 335.470246 -88.358726)
		(width 0.1143)
		(layer "In2.Cu")
		(net "P3E_CPU0_PE1_PCH_RXP<4>")
	)
	(segment
		(start 372.259098 -119.761)
		(end 372.170198 -119.6721)
		(width 0.0889)
		(layer "In2.Cu")
		(net "P3E_CPU0_PE1_PCH_RXP<4>")
	)
	(segment
		(start 341.607394 -67.52844)
		(end 341.607394 -67.780408)
		(width 0.1143)
		(layer "In2.Cu")
		(net "P3E_CPU0_PE1_PCH_RXP<4>")
	)
	(segment
		(start 329.485244 -76.121768)
		(end 330.93914 -70.508622)
		(width 0.1143)
		(layer "In2.Cu")
		(net "P3E_CPU0_PE1_PCH_RXP<4>")
	)
	(segment
		(start 368.72545 -119.11711)
		(end 368.419126 -118.936516)
		(width 0.1143)
		(layer "In2.Cu")
		(net "P3E_CPU0_PE1_PCH_RXP<4>")
	)
	(segment
		(start 361.888532 -110.038134)
		(end 361.4293 -107.870498)
		(width 0.1143)
		(layer "In2.Cu")
		(net "P3E_CPU0_PE1_PCH_RXP<4>")
	)
	(segment
		(start 375.205498 -119.761)
		(end 375.116598 -119.6721)
		(width 0.0889)
		(layer "In2.Cu")
		(net "P3E_CPU0_PE1_PCH_RXP<4>")
	)
	(segment
		(start 330.664566 -80.342232)
		(end 330.437236 -80.289654)
		(width 0.1143)
		(layer "In2.Cu")
		(net "P3E_CPU0_PE1_PCH_RXP<4>")
	)
	(segment
		(start 359.483406 -96.656906)
		(end 359.292906 -96.521778)
		(width 0.1143)
		(layer "In2.Cu")
		(net "P3E_CPU0_PE1_PCH_RXP<4>")
	)
	(segment
		(start 377.942602 -119.761)
		(end 375.942098 -119.761)
		(width 0.0889)
		(layer "In2.Cu")
		(net "P3E_CPU0_PE1_PCH_RXP<4>")
	)
	(segment
		(start 359.914952 -100.40747)
		(end 360.162348 -99.3775)
		(width 0.1143)
		(layer "In2.Cu")
		(net "P3E_CPU0_PE1_PCH_RXP<4>")
	)
	(segment
		(start 367.295684 -118.466108)
		(end 367.000282 -118.292118)
		(width 0.1143)
		(layer "In2.Cu")
		(net "P3E_CPU0_PE1_PCH_RXP<4>")
	)
	(segment
		(start 375.853198 -119.6721)
		(end 375.573798 -119.6721)
		(width 0.0889)
		(layer "In2.Cu")
		(net "P3E_CPU0_PE1_PCH_RXP<4>")
	)
	(segment
		(start 365.937546 -117.665754)
		(end 362.586016 -116.482368)
		(width 0.1143)
		(layer "In2.Cu")
		(net "P3E_CPU0_PE1_PCH_RXP<4>")
	)
	(segment
		(start 373.732298 -119.761)
		(end 373.643398 -119.6721)
		(width 0.0889)
		(layer "In2.Cu")
		(net "P3E_CPU0_PE1_PCH_RXP<4>")
	)
	(segment
		(start 348.371668 -90.293952)
		(end 348.371668 -90.293444)
		(width 0.1143)
		(layer "In2.Cu")
		(net "P3E_CPU0_PE1_PCH_RXP<4>")
	)
	(segment
		(start 380.2126 -120.376188)
		(end 380.2126 -120.39854)
		(width 0.0889)
		(layer "In2.Cu")
		(net "P3E_CPU0_PE1_PCH_RXP<4>")
	)
	(segment
		(start 331.766926 -82.109564)
		(end 331.539596 -82.056732)
		(width 0.1143)
		(layer "In2.Cu")
		(net "P3E_CPU0_PE1_PCH_RXP<4>")
	)
	(segment
		(start 378.126752 -119.875554)
		(end 377.961652 -119.78005)
		(width 0.0889)
		(layer "In2.Cu")
		(net "P3E_CPU0_PE1_PCH_RXP<4>")
	)
	(segment
		(start 361.4293 -102.251256)
		(end 360.848656 -101.390958)
		(width 0.1143)
		(layer "In2.Cu")
		(net "P3E_CPU0_PE1_PCH_RXP<4>")
	)
	(segment
		(start 379.98146 -120.094248)
		(end 380.0602 -120.073166)
		(width 0.0889)
		(layer "In2.Cu")
		(net "P3E_CPU0_PE1_PCH_RXP<4>")
	)
	(segment
		(start 362.046012 -115.814602)
		(end 361.286552 -113.855754)
		(width 0.1143)
		(layer "In2.Cu")
		(net "P3E_CPU0_PE1_PCH_RXP<4>")
	)
	(segment
		(start 360.352594 -101.05644)
		(end 359.914952 -100.40747)
		(width 0.1143)
		(layer "In2.Cu")
		(net "P3E_CPU0_PE1_PCH_RXP<4>")
	)
	(segment
		(start 359.293414 -96.521778)
		(end 359.23601 -96.183704)
		(width 0.1143)
		(layer "In2.Cu")
		(net "P3E_CPU0_PE1_PCH_RXP<4>")
	)
	(arc
		(start 380.0602 -120.073166)
		(mid 380.170112 -120.207728)
		(end 380.2126 -120.376188)
		(width 0.0889)
		(layer "In2.Cu")
		(net "P3E_CPU0_PE1_PCH_RXP<4>")
	)
	(arc
		(start 378.526548 -119.875554)
		(mid 378.32665 -119.929053)
		(end 378.126752 -119.875554)
		(width 0.0889)
		(layer "In2.Cu")
		(net "P3E_CPU0_PE1_PCH_RXP<4>")
	)
	(arc
		(start 379.4125 -120.365774)
		(mid 379.108057 -119.870297)
		(end 378.526548 -119.875554)
		(width 0.0889)
		(layer "In2.Cu")
		(net "P3E_CPU0_PE1_PCH_RXP<4>")
	)
	(arc
		(start 379.612652 -120.734074)
		(mid 379.468848 -120.592391)
		(end 379.4125 -120.39854)
		(width 0.0889)
		(layer "In2.Cu")
		(net "P3E_CPU0_PE1_PCH_RXP<4>")
	)
	(arc
		(start 380.2126 -120.39854)
		(mid 380.15625 -120.59239)
		(end 380.012448 -120.734074)
		(width 0.0889)
		(layer "In2.Cu")
		(net "P3E_CPU0_PE1_PCH_RXP<4>")
	)
	(arc
		(start 380.012448 -120.734074)
		(mid 379.81255 -120.787573)
		(end 379.612652 -120.734074)
		(width 0.0889)
		(layer "In2.Cu")
		(net "P3E_CPU0_PE1_PCH_RXP<4>")
	)
	(segment
		(start 378.82195 -119.29872)
		(end 379.31725 -119.528844)
		(width 0.1143)
		(layer "F.Cu")
		(net "P3E_CPU0_PE1_PCH_RXP<3>")
	)
	(via
		(at 379.31725 -119.528844)
		(size 0.508)
		(drill 0.254)
		(layers "F.Cu" "B.Cu")
		(net "P3E_CPU0_PE1_PCH_RXP<3>")
	)
	(via
		(at 340.324948 -65.189608)
		(size 0.508)
		(drill 0.254)
		(layers "F.Cu" "B.Cu")
		(net "P3E_CPU0_PE1_PCH_RXP<3>")
	)
	(via
		(at 339.457792 -69.02577)
		(size 0.508)
		(drill 0.254)
		(layers "F.Cu" "B.Cu")
		(net "P3E_CPU0_PE1_PCH_RXP<3>")
	)
	(segment
		(start 339.814154 -68.669408)
		(end 339.814154 -65.700402)
		(width 0.1143)
		(layer "B.Cu")
		(net "P3E_CPU0_PE1_PCH_RXP<3>")
	)
	(segment
		(start 339.457792 -69.02577)
		(end 339.814154 -68.669408)
		(width 0.1143)
		(layer "B.Cu")
		(net "P3E_CPU0_PE1_PCH_RXP<3>")
	)
	(segment
		(start 342.321642 -63.192914)
		(end 342.321642 -61.85027)
		(width 0.1143)
		(layer "B.Cu")
		(net "P3E_CPU0_PE1_PCH_RXP<3>")
	)
	(segment
		(start 340.324948 -65.189608)
		(end 342.321642 -63.192914)
		(width 0.1143)
		(layer "B.Cu")
		(net "P3E_CPU0_PE1_PCH_RXP<3>")
	)
	(segment
		(start 342.321642 -61.85027)
		(end 341.728806 -61.257434)
		(width 0.1143)
		(layer "B.Cu")
		(net "P3E_CPU0_PE1_PCH_RXP<3>")
	)
	(segment
		(start 339.814154 -65.700402)
		(end 340.324948 -65.189608)
		(width 0.1143)
		(layer "B.Cu")
		(net "P3E_CPU0_PE1_PCH_RXP<3>")
	)
	(segment
		(start 340.192868 -86.200488)
		(end 340.714076 -86.317074)
		(width 0.1143)
		(layer "In2.Cu")
		(net "P3E_CPU0_PE1_PCH_RXP<3>")
	)
	(segment
		(start 333.45501 -81.830672)
		(end 333.683864 -81.877154)
		(width 0.1143)
		(layer "In2.Cu")
		(net "P3E_CPU0_PE1_PCH_RXP<3>")
	)
	(segment
		(start 361.522264 -99.16795)
		(end 362.0643 -101.715062)
		(width 0.1143)
		(layer "In2.Cu")
		(net "P3E_CPU0_PE1_PCH_RXP<3>")
	)
	(segment
		(start 338.442554 -68.44919)
		(end 337.956144 -68.9356)
		(width 0.1143)
		(layer "In2.Cu")
		(net "P3E_CPU0_PE1_PCH_RXP<3>")
	)
	(segment
		(start 340.91118 -86.191852)
		(end 341.245952 -86.266782)
		(width 0.1143)
		(layer "In2.Cu")
		(net "P3E_CPU0_PE1_PCH_RXP<3>")
	)
	(segment
		(start 370.33454 -117.3734)
		(end 370.356638 -117.3734)
		(width 0.0889)
		(layer "In2.Cu")
		(net "P3E_CPU0_PE1_PCH_RXP<3>")
	)
	(segment
		(start 378.284232 -118.298722)
		(end 378.52604 -118.158768)
		(width 0.0889)
		(layer "In2.Cu")
		(net "P3E_CPU0_PE1_PCH_RXP<3>")
	)
	(segment
		(start 361.593892 -96.321626)
		(end 361.860592 -97.574608)
		(width 0.1143)
		(layer "In2.Cu")
		(net "P3E_CPU0_PE1_PCH_RXP<3>")
	)
	(segment
		(start 339.650832 -68.44919)
		(end 338.442554 -68.44919)
		(width 0.1143)
		(layer "In2.Cu")
		(net "P3E_CPU0_PE1_PCH_RXP<3>")
	)
	(segment
		(start 362.57103 -110.193836)
		(end 362.27385 -111.285782)
		(width 0.1143)
		(layer "In2.Cu")
		(net "P3E_CPU0_PE1_PCH_RXP<3>")
	)
	(segment
		(start 351.98177 -85.488018)
		(end 352.629978 -85.614002)
		(width 0.1143)
		(layer "In2.Cu")
		(net "P3E_CPU0_PE1_PCH_RXP<3>")
	)
	(segment
		(start 332.70698 -77.97165)
		(end 332.775306 -78.307692)
		(width 0.1143)
		(layer "In2.Cu")
		(net "P3E_CPU0_PE1_PCH_RXP<3>")
	)
	(segment
		(start 342.637618 -86.746842)
		(end 343.38641 -86.914228)
		(width 0.1143)
		(layer "In2.Cu")
		(net "P3E_CPU0_PE1_PCH_RXP<3>")
	)
	(segment
		(start 367.297208 -117.3734)
		(end 370.33454 -117.3734)
		(width 0.1143)
		(layer "In2.Cu")
		(net "P3E_CPU0_PE1_PCH_RXP<3>")
	)
	(segment
		(start 365.591852 -116.595652)
		(end 365.915194 -116.709952)
		(width 0.1143)
		(layer "In2.Cu")
		(net "P3E_CPU0_PE1_PCH_RXP<3>")
	)
	(segment
		(start 361.58932 -94.46768)
		(end 361.782868 -95.430848)
		(width 0.1143)
		(layer "In2.Cu")
		(net "P3E_CPU0_PE1_PCH_RXP<3>")
	)
	(segment
		(start 337.82381 -85.671152)
		(end 339.536024 -86.053676)
		(width 0.1143)
		(layer "In2.Cu")
		(net "P3E_CPU0_PE1_PCH_RXP<3>")
	)
	(segment
		(start 355.116384 -85.447124)
		(end 355.58095 -85.76056)
		(width 0.1143)
		(layer "In2.Cu")
		(net "P3E_CPU0_PE1_PCH_RXP<3>")
	)
	(segment
		(start 332.754224 -75.318874)
		(end 332.376272 -77.175106)
		(width 0.1143)
		(layer "In2.Cu")
		(net "P3E_CPU0_PE1_PCH_RXP<3>")
	)
	(segment
		(start 362.102146 -114.198654)
		(end 362.31576 -114.292888)
		(width 0.1143)
		(layer "In2.Cu")
		(net "P3E_CPU0_PE1_PCH_RXP<3>")
	)
	(segment
		(start 331.13726 -72.294242)
		(end 331.267816 -72.988424)
		(width 0.1143)
		(layer "In2.Cu")
		(net "P3E_CPU0_PE1_PCH_RXP<3>")
	)
	(segment
		(start 370.407438 -117.4242)
		(end 372.800626 -117.4242)
		(width 0.0889)
		(layer "In2.Cu")
		(net "P3E_CPU0_PE1_PCH_RXP<3>")
	)
	(segment
		(start 373.191786 -117.03304)
		(end 374.462294 -117.03304)
		(width 0.0889)
		(layer "In2.Cu")
		(net "P3E_CPU0_PE1_PCH_RXP<3>")
	)
	(segment
		(start 362.439712 -114.612674)
		(end 362.345224 -114.826288)
		(width 0.1143)
		(layer "In2.Cu")
		(net "P3E_CPU0_PE1_PCH_RXP<3>")
	)
	(segment
		(start 366.339374 -117.034818)
		(end 366.54994 -116.934234)
		(width 0.1143)
		(layer "In2.Cu")
		(net "P3E_CPU0_PE1_PCH_RXP<3>")
	)
	(segment
		(start 333.285338 -80.813402)
		(end 333.15656 -81.00822)
		(width 0.1143)
		(layer "In2.Cu")
		(net "P3E_CPU0_PE1_PCH_RXP<3>")
	)
	(segment
		(start 339.536024 -86.053676)
		(end 339.733128 -85.928708)
		(width 0.1143)
		(layer "In2.Cu")
		(net "P3E_CPU0_PE1_PCH_RXP<3>")
	)
	(segment
		(start 343.38641 -86.914228)
		(end 343.735914 -86.848188)
		(width 0.1143)
		(layer "In2.Cu")
		(net "P3E_CPU0_PE1_PCH_RXP<3>")
	)
	(segment
		(start 379.17247 -119.14632)
		(end 379.14834 -119.235728)
		(width 0.0889)
		(layer "In2.Cu")
		(net "P3E_CPU0_PE1_PCH_RXP<3>")
	)
	(segment
		(start 365.381286 -116.69649)
		(end 365.591852 -116.595652)
		(width 0.1143)
		(layer "In2.Cu")
		(net "P3E_CPU0_PE1_PCH_RXP<3>")
	)
	(segment
		(start 339.765132 -68.71843)
		(end 339.765132 -68.56349)
		(width 0.1143)
		(layer "In2.Cu")
		(net "P3E_CPU0_PE1_PCH_RXP<3>")
	)
	(segment
		(start 339.733128 -85.928708)
		(end 340.067646 -86.003384)
		(width 0.1143)
		(layer "In2.Cu")
		(net "P3E_CPU0_PE1_PCH_RXP<3>")
	)
	(segment
		(start 376.184414 -118.75516)
		(end 377.672854 -118.75516)
		(width 0.0889)
		(layer "In2.Cu")
		(net "P3E_CPU0_PE1_PCH_RXP<3>")
	)
	(segment
		(start 333.826358 -82.392012)
		(end 334.535526 -83.464146)
		(width 0.1143)
		(layer "In2.Cu")
		(net "P3E_CPU0_PE1_PCH_RXP<3>")
	)
	(segment
		(start 332.658466 -74.848212)
		(end 332.754224 -75.318874)
		(width 0.1143)
		(layer "In2.Cu")
		(net "P3E_CPU0_PE1_PCH_RXP<3>")
	)
	(segment
		(start 339.765132 -68.56349)
		(end 339.650832 -68.44919)
		(width 0.1143)
		(layer "In2.Cu")
		(net "P3E_CPU0_PE1_PCH_RXP<3>")
	)
	(segment
		(start 332.376272 -77.175106)
		(end 332.512162 -77.842872)
		(width 0.1143)
		(layer "In2.Cu")
		(net "P3E_CPU0_PE1_PCH_RXP<3>")
	)
	(segment
		(start 378.52604 -118.158768)
		(end 378.526548 -118.158514)
		(width 0.0889)
		(layer "In2.Cu")
		(net "P3E_CPU0_PE1_PCH_RXP<3>")
	)
	(segment
		(start 362.4961 -111.982758)
		(end 362.259626 -112.848136)
		(width 0.1143)
		(layer "In2.Cu")
		(net "P3E_CPU0_PE1_PCH_RXP<3>")
	)
	(segment
		(start 342.637364 -86.746842)
		(end 342.637618 -86.746842)
		(width 0.1143)
		(layer "In2.Cu")
		(net "P3E_CPU0_PE1_PCH_RXP<3>")
	)
	(segment
		(start 354.303076 -85.288882)
		(end 355.116384 -85.447124)
		(width 0.1143)
		(layer "In2.Cu")
		(net "P3E_CPU0_PE1_PCH_RXP<3>")
	)
	(segment
		(start 335.536032 -84.135468)
		(end 337.82381 -85.671152)
		(width 0.1143)
		(layer "In2.Cu")
		(net "P3E_CPU0_PE1_PCH_RXP<3>")
	)
	(segment
		(start 332.646528 -78.50251)
		(end 333.022194 -80.348582)
		(width 0.1143)
		(layer "In2.Cu")
		(net "P3E_CPU0_PE1_PCH_RXP<3>")
	)
	(segment
		(start 355.712014 -85.95487)
		(end 356.597966 -90.5129)
		(width 0.1143)
		(layer "In2.Cu")
		(net "P3E_CPU0_PE1_PCH_RXP<3>")
	)
	(segment
		(start 362.92282 -115.828064)
		(end 362.92282 -115.82781)
		(width 0.1143)
		(layer "In2.Cu")
		(net "P3E_CPU0_PE1_PCH_RXP<3>")
	)
	(segment
		(start 334.535526 -83.464146)
		(end 334.976978 -83.760564)
		(width 0.1143)
		(layer "In2.Cu")
		(net "P3E_CPU0_PE1_PCH_RXP<3>")
	)
	(segment
		(start 361.978448 -113.878868)
		(end 362.102146 -114.198654)
		(width 0.1143)
		(layer "In2.Cu")
		(net "P3E_CPU0_PE1_PCH_RXP<3>")
	)
	(segment
		(start 343.735914 -86.848188)
		(end 343.867486 -86.655402)
		(width 0.1143)
		(layer "In2.Cu")
		(net "P3E_CPU0_PE1_PCH_RXP<3>")
	)
	(segment
		(start 335.79816 -68.9356)
		(end 331.525118 -70.94601)
		(width 0.1143)
		(layer "In2.Cu")
		(net "P3E_CPU0_PE1_PCH_RXP<3>")
	)
	(segment
		(start 362.559092 -115.378484)
		(end 362.92282 -115.828064)
		(width 0.1143)
		(layer "In2.Cu")
		(net "P3E_CPU0_PE1_PCH_RXP<3>")
	)
	(segment
		(start 366.873282 -117.048534)
		(end 366.973866 -117.2591)
		(width 0.1143)
		(layer "In2.Cu")
		(net "P3E_CPU0_PE1_PCH_RXP<3>")
	)
	(segment
		(start 378.283978 -118.298722)
		(end 378.284232 -118.298722)
		(width 0.0889)
		(layer "In2.Cu")
		(net "P3E_CPU0_PE1_PCH_RXP<3>")
	)
	(segment
		(start 362.259626 -112.848136)
		(end 362.25861 -112.8522)
		(width 0.1143)
		(layer "In2.Cu")
		(net "P3E_CPU0_PE1_PCH_RXP<3>")
	)
	(segment
		(start 340.067646 -86.003384)
		(end 340.192868 -86.200488)
		(width 0.1143)
		(layer "In2.Cu")
		(net "P3E_CPU0_PE1_PCH_RXP<3>")
	)
	(segment
		(start 350.27108 -86.374986)
		(end 351.42551 -85.596222)
		(width 0.1143)
		(layer "In2.Cu")
		(net "P3E_CPU0_PE1_PCH_RXP<3>")
	)
	(segment
		(start 333.15656 -81.00822)
		(end 333.26578 -81.544668)
		(width 0.1143)
		(layer "In2.Cu")
		(net "P3E_CPU0_PE1_PCH_RXP<3>")
	)
	(segment
		(start 333.26578 -81.544668)
		(end 333.45501 -81.830672)
		(width 0.1143)
		(layer "In2.Cu")
		(net "P3E_CPU0_PE1_PCH_RXP<3>")
	)
	(segment
		(start 359.52557 -93.849444)
		(end 361.150408 -94.175072)
		(width 0.1143)
		(layer "In2.Cu")
		(net "P3E_CPU0_PE1_PCH_RXP<3>")
	)
	(segment
		(start 361.782868 -95.430848)
		(end 361.593892 -96.321626)
		(width 0.1143)
		(layer "In2.Cu")
		(net "P3E_CPU0_PE1_PCH_RXP<3>")
	)
	(segment
		(start 333.683864 -81.877154)
		(end 333.87284 -82.163158)
		(width 0.1143)
		(layer "In2.Cu")
		(net "P3E_CPU0_PE1_PCH_RXP<3>")
	)
	(segment
		(start 333.217012 -80.47736)
		(end 333.285338 -80.813402)
		(width 0.1143)
		(layer "In2.Cu")
		(net "P3E_CPU0_PE1_PCH_RXP<3>")
	)
	(segment
		(start 366.016032 -116.920772)
		(end 366.339374 -117.034818)
		(width 0.1143)
		(layer "In2.Cu")
		(net "P3E_CPU0_PE1_PCH_RXP<3>")
	)
	(segment
		(start 334.976978 -83.760564)
		(end 335.206086 -83.715352)
		(width 0.1143)
		(layer "In2.Cu")
		(net "P3E_CPU0_PE1_PCH_RXP<3>")
	)
	(segment
		(start 339.457792 -69.02577)
		(end 339.765132 -68.71843)
		(width 0.1143)
		(layer "In2.Cu")
		(net "P3E_CPU0_PE1_PCH_RXP<3>")
	)
	(segment
		(start 362.31576 -114.292888)
		(end 362.439712 -114.612674)
		(width 0.1143)
		(layer "In2.Cu")
		(net "P3E_CPU0_PE1_PCH_RXP<3>")
	)
	(segment
		(start 362.081572 -113.501678)
		(end 361.978448 -113.878868)
		(width 0.1143)
		(layer "In2.Cu")
		(net "P3E_CPU0_PE1_PCH_RXP<3>")
	)
	(segment
		(start 343.867486 -86.655402)
		(end 344.216736 -86.589362)
		(width 0.1143)
		(layer "In2.Cu")
		(net "P3E_CPU0_PE1_PCH_RXP<3>")
	)
	(segment
		(start 341.37092 -86.463886)
		(end 342.637364 -86.746842)
		(width 0.1143)
		(layer "In2.Cu")
		(net "P3E_CPU0_PE1_PCH_RXP<3>")
	)
	(segment
		(start 370.356638 -117.3734)
		(end 370.407438 -117.4242)
		(width 0.0889)
		(layer "In2.Cu")
		(net "P3E_CPU0_PE1_PCH_RXP<3>")
	)
	(segment
		(start 372.800626 -117.4242)
		(end 373.191786 -117.03304)
		(width 0.0889)
		(layer "In2.Cu")
		(net "P3E_CPU0_PE1_PCH_RXP<3>")
	)
	(segment
		(start 379.4125 -118.648734)
		(end 379.4125 -118.691914)
		(width 0.0889)
		(layer "In2.Cu")
		(net "P3E_CPU0_PE1_PCH_RXP<3>")
	)
	(segment
		(start 365.915194 -116.709952)
		(end 366.016032 -116.920772)
		(width 0.1143)
		(layer "In2.Cu")
		(net "P3E_CPU0_PE1_PCH_RXP<3>")
	)
	(segment
		(start 348.646242 -86.700868)
		(end 350.27108 -86.374986)
		(width 0.1143)
		(layer "In2.Cu")
		(net "P3E_CPU0_PE1_PCH_RXP<3>")
	)
	(segment
		(start 332.775306 -78.307692)
		(end 332.646528 -78.50251)
		(width 0.1143)
		(layer "In2.Cu")
		(net "P3E_CPU0_PE1_PCH_RXP<3>")
	)
	(segment
		(start 366.973866 -117.2591)
		(end 367.297208 -117.3734)
		(width 0.1143)
		(layer "In2.Cu")
		(net "P3E_CPU0_PE1_PCH_RXP<3>")
	)
	(segment
		(start 374.462294 -117.03304)
		(end 376.184414 -118.75516)
		(width 0.0889)
		(layer "In2.Cu")
		(net "P3E_CPU0_PE1_PCH_RXP<3>")
	)
	(segment
		(start 344.409776 -86.720934)
		(end 345.63558 -86.48954)
		(width 0.1143)
		(layer "In2.Cu")
		(net "P3E_CPU0_PE1_PCH_RXP<3>")
	)
	(segment
		(start 366.54994 -116.934234)
		(end 366.873282 -117.048534)
		(width 0.1143)
		(layer "In2.Cu")
		(net "P3E_CPU0_PE1_PCH_RXP<3>")
	)
	(segment
		(start 335.206086 -83.715352)
		(end 335.49082 -83.906614)
		(width 0.1143)
		(layer "In2.Cu")
		(net "P3E_CPU0_PE1_PCH_RXP<3>")
	)
	(segment
		(start 362.0643 -101.715062)
		(end 362.0643 -107.803188)
		(width 0.1143)
		(layer "In2.Cu")
		(net "P3E_CPU0_PE1_PCH_RXP<3>")
	)
	(segment
		(start 331.267816 -72.988424)
		(end 332.658466 -74.848212)
		(width 0.1143)
		(layer "In2.Cu")
		(net "P3E_CPU0_PE1_PCH_RXP<3>")
	)
	(segment
		(start 362.374434 -113.054892)
		(end 362.284264 -113.385854)
		(width 0.1143)
		(layer "In2.Cu")
		(net "P3E_CPU0_PE1_PCH_RXP<3>")
	)
	(segment
		(start 333.022194 -80.348582)
		(end 333.217012 -80.47736)
		(width 0.1143)
		(layer "In2.Cu")
		(net "P3E_CPU0_PE1_PCH_RXP<3>")
	)
	(segment
		(start 344.216736 -86.589362)
		(end 344.409776 -86.720934)
		(width 0.1143)
		(layer "In2.Cu")
		(net "P3E_CPU0_PE1_PCH_RXP<3>")
	)
	(segment
		(start 379.14834 -119.235728)
		(end 379.31725 -119.528844)
		(width 0.0889)
		(layer "In2.Cu")
		(net "P3E_CPU0_PE1_PCH_RXP<3>")
	)
	(segment
		(start 340.714076 -86.317074)
		(end 340.91118 -86.191852)
		(width 0.1143)
		(layer "In2.Cu")
		(net "P3E_CPU0_PE1_PCH_RXP<3>")
	)
	(segment
		(start 351.42551 -85.596222)
		(end 351.98177 -85.488018)
		(width 0.1143)
		(layer "In2.Cu")
		(net "P3E_CPU0_PE1_PCH_RXP<3>")
	)
	(segment
		(start 335.49082 -83.906614)
		(end 335.536032 -84.135468)
		(width 0.1143)
		(layer "In2.Cu")
		(net "P3E_CPU0_PE1_PCH_RXP<3>")
	)
	(segment
		(start 352.629978 -85.614002)
		(end 354.303076 -85.288882)
		(width 0.1143)
		(layer "In2.Cu")
		(net "P3E_CPU0_PE1_PCH_RXP<3>")
	)
	(segment
		(start 337.956144 -68.9356)
		(end 335.79816 -68.9356)
		(width 0.1143)
		(layer "In2.Cu")
		(net "P3E_CPU0_PE1_PCH_RXP<3>")
	)
	(segment
		(start 345.63558 -86.48954)
		(end 346.657676 -86.695788)
		(width 0.1143)
		(layer "In2.Cu")
		(net "P3E_CPU0_PE1_PCH_RXP<3>")
	)
	(segment
		(start 346.657676 -86.695788)
		(end 347.940884 -86.417658)
		(width 0.1143)
		(layer "In2.Cu")
		(net "P3E_CPU0_PE1_PCH_RXP<3>")
	)
	(segment
		(start 362.284264 -113.385854)
		(end 362.081572 -113.501678)
		(width 0.1143)
		(layer "In2.Cu")
		(net "P3E_CPU0_PE1_PCH_RXP<3>")
	)
	(segment
		(start 361.860592 -97.574608)
		(end 361.522264 -99.16795)
		(width 0.1143)
		(layer "In2.Cu")
		(net "P3E_CPU0_PE1_PCH_RXP<3>")
	)
	(segment
		(start 341.245952 -86.266782)
		(end 341.37092 -86.463886)
		(width 0.1143)
		(layer "In2.Cu")
		(net "P3E_CPU0_PE1_PCH_RXP<3>")
	)
	(segment
		(start 362.27385 -111.285782)
		(end 362.4961 -111.982758)
		(width 0.1143)
		(layer "In2.Cu")
		(net "P3E_CPU0_PE1_PCH_RXP<3>")
	)
	(segment
		(start 377.672854 -118.75516)
		(end 378.283978 -118.298722)
		(width 0.0889)
		(layer "In2.Cu")
		(net "P3E_CPU0_PE1_PCH_RXP<3>")
	)
	(segment
		(start 358.073706 -92.726002)
		(end 359.52557 -93.849444)
		(width 0.1143)
		(layer "In2.Cu")
		(net "P3E_CPU0_PE1_PCH_RXP<3>")
	)
	(segment
		(start 347.940884 -86.417658)
		(end 348.646242 -86.700868)
		(width 0.1143)
		(layer "In2.Cu")
		(net "P3E_CPU0_PE1_PCH_RXP<3>")
	)
	(segment
		(start 355.58095 -85.76056)
		(end 355.712014 -85.95487)
		(width 0.1143)
		(layer "In2.Cu")
		(net "P3E_CPU0_PE1_PCH_RXP<3>")
	)
	(segment
		(start 333.87284 -82.163158)
		(end 333.826358 -82.392012)
		(width 0.1143)
		(layer "In2.Cu")
		(net "P3E_CPU0_PE1_PCH_RXP<3>")
	)
	(segment
		(start 332.512162 -77.842872)
		(end 332.70698 -77.97165)
		(width 0.1143)
		(layer "In2.Cu")
		(net "P3E_CPU0_PE1_PCH_RXP<3>")
	)
	(segment
		(start 362.345224 -114.826288)
		(end 362.559092 -115.378484)
		(width 0.1143)
		(layer "In2.Cu")
		(net "P3E_CPU0_PE1_PCH_RXP<3>")
	)
	(segment
		(start 356.597966 -90.5129)
		(end 358.073706 -92.726002)
		(width 0.1143)
		(layer "In2.Cu")
		(net "P3E_CPU0_PE1_PCH_RXP<3>")
	)
	(segment
		(start 362.0643 -107.803188)
		(end 362.57103 -110.193836)
		(width 0.1143)
		(layer "In2.Cu")
		(net "P3E_CPU0_PE1_PCH_RXP<3>")
	)
	(segment
		(start 331.525118 -70.94601)
		(end 331.13726 -72.294242)
		(width 0.1143)
		(layer "In2.Cu")
		(net "P3E_CPU0_PE1_PCH_RXP<3>")
	)
	(segment
		(start 362.92282 -115.82781)
		(end 365.381286 -116.69649)
		(width 0.1143)
		(layer "In2.Cu")
		(net "P3E_CPU0_PE1_PCH_RXP<3>")
	)
	(segment
		(start 362.25861 -112.8522)
		(end 362.374434 -113.054892)
		(width 0.1143)
		(layer "In2.Cu")
		(net "P3E_CPU0_PE1_PCH_RXP<3>")
	)
	(segment
		(start 361.150408 -94.175072)
		(end 361.58932 -94.46768)
		(width 0.1143)
		(layer "In2.Cu")
		(net "P3E_CPU0_PE1_PCH_RXP<3>")
	)
	(arc
		(start 379.4125 -118.691914)
		(mid 379.344471 -118.946579)
		(end 379.17247 -119.14632)
		(width 0.0889)
		(layer "In2.Cu")
		(net "P3E_CPU0_PE1_PCH_RXP<3>")
	)
	(arc
		(start 378.526548 -118.158514)
		(mid 378.82195 -118.079383)
		(end 379.117352 -118.158514)
		(width 0.0889)
		(layer "In2.Cu")
		(net "P3E_CPU0_PE1_PCH_RXP<3>")
	)
	(arc
		(start 379.117352 -118.158514)
		(mid 379.328216 -118.365518)
		(end 379.4125 -118.648734)
		(width 0.0889)
		(layer "In2.Cu")
		(net "P3E_CPU0_PE1_PCH_RXP<3>")
	)
	(segment
		(start 377.33605 -118.4402)
		(end 377.197874 -117.777514)
		(width 0.1143)
		(layer "F.Cu")
		(net "P3E_CPU0_PE1_PCH_RXP<2>")
	)
	(segment
		(start 377.197874 -117.777514)
		(end 377.19762 -117.77726)
		(width 0.1143)
		(layer "F.Cu")
		(net "P3E_CPU0_PE1_PCH_RXP<2>")
	)
	(via
		(at 337.863434 -70.11289)
		(size 0.508)
		(drill 0.254)
		(layers "F.Cu" "B.Cu")
		(net "P3E_CPU0_PE1_PCH_RXP<2>")
	)
	(via
		(at 337.53171 -67.744594)
		(size 0.508)
		(drill 0.254)
		(layers "F.Cu" "B.Cu")
		(net "P3E_CPU0_PE1_PCH_RXP<2>")
	)
	(via
		(at 377.19762 -117.77726)
		(size 0.508)
		(drill 0.254)
		(layers "F.Cu" "B.Cu")
		(net "P3E_CPU0_PE1_PCH_RXP<2>")
	)
	(segment
		(start 337.53171 -67.744594)
		(end 337.53171 -64.285622)
		(width 0.1143)
		(layer "B.Cu")
		(net "P3E_CPU0_PE1_PCH_RXP<2>")
	)
	(segment
		(start 338.138262 -69.837808)
		(end 338.1375 -69.837046)
		(width 0.1143)
		(layer "B.Cu")
		(net "P3E_CPU0_PE1_PCH_RXP<2>")
	)
	(segment
		(start 337.53171 -68.277486)
		(end 337.53171 -67.744594)
		(width 0.1143)
		(layer "B.Cu")
		(net "P3E_CPU0_PE1_PCH_RXP<2>")
	)
	(segment
		(start 337.53171 -64.285622)
		(end 339.537548 -62.279784)
		(width 0.1143)
		(layer "B.Cu")
		(net "P3E_CPU0_PE1_PCH_RXP<2>")
	)
	(segment
		(start 337.863434 -70.11289)
		(end 338.138262 -69.837808)
		(width 0.1143)
		(layer "B.Cu")
		(net "P3E_CPU0_PE1_PCH_RXP<2>")
	)
	(segment
		(start 339.537548 -62.279784)
		(end 339.537548 -61.860176)
		(width 0.1143)
		(layer "B.Cu")
		(net "P3E_CPU0_PE1_PCH_RXP<2>")
	)
	(segment
		(start 338.1375 -69.837046)
		(end 338.1375 -68.883276)
		(width 0.1143)
		(layer "B.Cu")
		(net "P3E_CPU0_PE1_PCH_RXP<2>")
	)
	(segment
		(start 338.1375 -68.883276)
		(end 337.53171 -68.277486)
		(width 0.1143)
		(layer "B.Cu")
		(net "P3E_CPU0_PE1_PCH_RXP<2>")
	)
	(segment
		(start 339.537548 -61.860176)
		(end 338.934806 -61.257434)
		(width 0.1143)
		(layer "B.Cu")
		(net "P3E_CPU0_PE1_PCH_RXP<2>")
	)
	(segment
		(start 357.259128 -90.233246)
		(end 358.572308 -92.202254)
		(width 0.1143)
		(layer "In2.Cu")
		(net "P3E_CPU0_PE1_PCH_RXP<2>")
	)
	(segment
		(start 340.193884 -83.638136)
		(end 340.309962 -83.840574)
		(width 0.1143)
		(layer "In2.Cu")
		(net "P3E_CPU0_PE1_PCH_RXP<2>")
	)
	(segment
		(start 344.189558 -84.891626)
		(end 344.39225 -84.775548)
		(width 0.1143)
		(layer "In2.Cu")
		(net "P3E_CPU0_PE1_PCH_RXP<2>")
	)
	(segment
		(start 355.430836 -84.194396)
		(end 355.806248 -84.267294)
		(width 0.1143)
		(layer "In2.Cu")
		(net "P3E_CPU0_PE1_PCH_RXP<2>")
	)
	(segment
		(start 375.679716 -117.1956)
		(end 375.868438 -117.384322)
		(width 0.0889)
		(layer "In2.Cu")
		(net "P3E_CPU0_PE1_PCH_RXP<2>")
	)
	(segment
		(start 338.299806 -83.295998)
		(end 338.64296 -83.388962)
		(width 0.1143)
		(layer "In2.Cu")
		(net "P3E_CPU0_PE1_PCH_RXP<2>")
	)
	(segment
		(start 375.176796 -116.69268)
		(end 375.365518 -116.881402)
		(width 0.0889)
		(layer "In2.Cu")
		(net "P3E_CPU0_PE1_PCH_RXP<2>")
	)
	(segment
		(start 338.09305 -69.883274)
		(end 338.0994 -69.883274)
		(width 0.1143)
		(layer "In2.Cu")
		(net "P3E_CPU0_PE1_PCH_RXP<2>")
	)
	(segment
		(start 331.823822 -72.328786)
		(end 331.90307 -72.74941)
		(width 0.1143)
		(layer "In2.Cu")
		(net "P3E_CPU0_PE1_PCH_RXP<2>")
	)
	(segment
		(start 340.843362 -83.814158)
		(end 341.174324 -83.90382)
		(width 0.1143)
		(layer "In2.Cu")
		(net "P3E_CPU0_PE1_PCH_RXP<2>")
	)
	(segment
		(start 375.553986 -117.1956)
		(end 375.679716 -117.1956)
		(width 0.0889)
		(layer "In2.Cu")
		(net "P3E_CPU0_PE1_PCH_RXP<2>")
	)
	(segment
		(start 350.007174 -85.50021)
		(end 351.169986 -84.715858)
		(width 0.1143)
		(layer "In2.Cu")
		(net "P3E_CPU0_PE1_PCH_RXP<2>")
	)
	(segment
		(start 375.365518 -116.881402)
		(end 375.365518 -117.007132)
		(width 0.0889)
		(layer "In2.Cu")
		(net "P3E_CPU0_PE1_PCH_RXP<2>")
	)
	(segment
		(start 372.581678 -115.912392)
		(end 372.670578 -116.001292)
		(width 0.0889)
		(layer "In2.Cu")
		(net "P3E_CPU0_PE1_PCH_RXP<2>")
	)
	(segment
		(start 362.174536 -99.169728)
		(end 362.6993 -101.63937)
		(width 0.1143)
		(layer "In2.Cu")
		(net "P3E_CPU0_PE1_PCH_RXP<2>")
	)
	(segment
		(start 371.036088 -115.950492)
		(end 371.058186 -115.950492)
		(width 0.0889)
		(layer "In2.Cu")
		(net "P3E_CPU0_PE1_PCH_RXP<2>")
	)
	(segment
		(start 343.411556 -84.509864)
		(end 343.742518 -84.599526)
		(width 0.1143)
		(layer "In2.Cu")
		(net "P3E_CPU0_PE1_PCH_RXP<2>")
	)
	(segment
		(start 339.304884 -83.568286)
		(end 339.648038 -83.66125)
		(width 0.1143)
		(layer "In2.Cu")
		(net "P3E_CPU0_PE1_PCH_RXP<2>")
	)
	(segment
		(start 339.85073 -83.545172)
		(end 340.193884 -83.638136)
		(width 0.1143)
		(layer "In2.Cu")
		(net "P3E_CPU0_PE1_PCH_RXP<2>")
	)
	(segment
		(start 374.004078 -115.912392)
		(end 374.092978 -116.001292)
		(width 0.0889)
		(layer "In2.Cu")
		(net "P3E_CPU0_PE1_PCH_RXP<2>")
	)
	(segment
		(start 366.71504 -115.950492)
		(end 371.036088 -115.950492)
		(width 0.1143)
		(layer "In2.Cu")
		(net "P3E_CPU0_PE1_PCH_RXP<2>")
	)
	(segment
		(start 356.414578 -84.83092)
		(end 356.498398 -85.262466)
		(width 0.1143)
		(layer "In2.Cu")
		(net "P3E_CPU0_PE1_PCH_RXP<2>")
	)
	(segment
		(start 365.113316 -112.45596)
		(end 364.765844 -113.72977)
		(width 0.1143)
		(layer "In2.Cu")
		(net "P3E_CPU0_PE1_PCH_RXP<2>")
	)
	(segment
		(start 337.863434 -70.11289)
		(end 338.09305 -69.883274)
		(width 0.1143)
		(layer "In2.Cu")
		(net "P3E_CPU0_PE1_PCH_RXP<2>")
	)
	(segment
		(start 365.14405 -114.916458)
		(end 366.71504 -115.950492)
		(width 0.1143)
		(layer "In2.Cu")
		(net "P3E_CPU0_PE1_PCH_RXP<2>")
	)
	(segment
		(start 344.39225 -84.775548)
		(end 344.723212 -84.86521)
		(width 0.1143)
		(layer "In2.Cu")
		(net "P3E_CPU0_PE1_PCH_RXP<2>")
	)
	(segment
		(start 338.183474 -83.09356)
		(end 338.299806 -83.295998)
		(width 0.1143)
		(layer "In2.Cu")
		(net "P3E_CPU0_PE1_PCH_RXP<2>")
	)
	(segment
		(start 338.0994 -69.883274)
		(end 338.0994 -69.704458)
		(width 0.1143)
		(layer "In2.Cu")
		(net "P3E_CPU0_PE1_PCH_RXP<2>")
	)
	(segment
		(start 363.157516 -109.688376)
		(end 364.555278 -110.702852)
		(width 0.1143)
		(layer "In2.Cu")
		(net "P3E_CPU0_PE1_PCH_RXP<2>")
	)
	(segment
		(start 341.621618 -84.19592)
		(end 341.824056 -84.079842)
		(width 0.1143)
		(layer "In2.Cu")
		(net "P3E_CPU0_PE1_PCH_RXP<2>")
	)
	(segment
		(start 343.858596 -84.801964)
		(end 344.189558 -84.891626)
		(width 0.1143)
		(layer "In2.Cu")
		(net "P3E_CPU0_PE1_PCH_RXP<2>")
	)
	(segment
		(start 377.60021 -117.881146)
		(end 377.496324 -117.77726)
		(width 0.089408)
		(layer "In2.Cu")
		(net "P3E_CPU0_PE1_PCH_RXP<2>")
	)
	(segment
		(start 375.051066 -116.69268)
		(end 375.176796 -116.69268)
		(width 0.0889)
		(layer "In2.Cu")
		(net "P3E_CPU0_PE1_PCH_RXP<2>")
	)
	(segment
		(start 372.670578 -116.001292)
		(end 372.937278 -116.001292)
		(width 0.0889)
		(layer "In2.Cu")
		(net "P3E_CPU0_PE1_PCH_RXP<2>")
	)
	(segment
		(start 335.627472 -82.571844)
		(end 335.830164 -82.455766)
		(width 0.1143)
		(layer "In2.Cu")
		(net "P3E_CPU0_PE1_PCH_RXP<2>")
	)
	(segment
		(start 375.365518 -117.007132)
		(end 375.553986 -117.1956)
		(width 0.0889)
		(layer "In2.Cu")
		(net "P3E_CPU0_PE1_PCH_RXP<2>")
	)
	(segment
		(start 345.170252 -85.15731)
		(end 346.090748 -84.869528)
		(width 0.1143)
		(layer "In2.Cu")
		(net "P3E_CPU0_PE1_PCH_RXP<2>")
	)
	(segment
		(start 371.108986 -116.001292)
		(end 372.226078 -116.001292)
		(width 0.0889)
		(layer "In2.Cu")
		(net "P3E_CPU0_PE1_PCH_RXP<2>")
	)
	(segment
		(start 372.937278 -116.001292)
		(end 373.026178 -115.912392)
		(width 0.0889)
		(layer "In2.Cu")
		(net "P3E_CPU0_PE1_PCH_RXP<2>")
	)
	(segment
		(start 374.092978 -116.001292)
		(end 374.359678 -116.001292)
		(width 0.0889)
		(layer "In2.Cu")
		(net "P3E_CPU0_PE1_PCH_RXP<2>")
	)
	(segment
		(start 336.173318 -82.54873)
		(end 336.289396 -82.751168)
		(width 0.1143)
		(layer "In2.Cu")
		(net "P3E_CPU0_PE1_PCH_RXP<2>")
	)
	(segment
		(start 340.640924 -83.930236)
		(end 340.843362 -83.814158)
		(width 0.1143)
		(layer "In2.Cu")
		(net "P3E_CPU0_PE1_PCH_RXP<2>")
	)
	(segment
		(start 356.395782 -85.790786)
		(end 357.259128 -90.233246)
		(width 0.1143)
		(layer "In2.Cu")
		(net "P3E_CPU0_PE1_PCH_RXP<2>")
	)
	(segment
		(start 348.73565 -85.441028)
		(end 349.429324 -85.612478)
		(width 0.1143)
		(layer "In2.Cu")
		(net "P3E_CPU0_PE1_PCH_RXP<2>")
	)
	(segment
		(start 339.648038 -83.66125)
		(end 339.85073 -83.545172)
		(width 0.1143)
		(layer "In2.Cu")
		(net "P3E_CPU0_PE1_PCH_RXP<2>")
	)
	(segment
		(start 373.648478 -116.001292)
		(end 373.737378 -115.912392)
		(width 0.0889)
		(layer "In2.Cu")
		(net "P3E_CPU0_PE1_PCH_RXP<2>")
	)
	(segment
		(start 334.33512 -80.744822)
		(end 334.288384 -80.973422)
		(width 0.1143)
		(layer "In2.Cu")
		(net "P3E_CPU0_PE1_PCH_RXP<2>")
	)
	(segment
		(start 331.90307 -72.74941)
		(end 333.351378 -74.686668)
		(width 0.1143)
		(layer "In2.Cu")
		(net "P3E_CPU0_PE1_PCH_RXP<2>")
	)
	(segment
		(start 362.51642 -97.559368)
		(end 362.174536 -99.169728)
		(width 0.1143)
		(layer "In2.Cu")
		(net "P3E_CPU0_PE1_PCH_RXP<2>")
	)
	(segment
		(start 338.64296 -83.388962)
		(end 338.845398 -83.272884)
		(width 0.1143)
		(layer "In2.Cu")
		(net "P3E_CPU0_PE1_PCH_RXP<2>")
	)
	(segment
		(start 362.6993 -101.63937)
		(end 362.6993 -107.52582)
		(width 0.1143)
		(layer "In2.Cu")
		(net "P3E_CPU0_PE1_PCH_RXP<2>")
	)
	(segment
		(start 344.723212 -84.86521)
		(end 344.83929 -85.067648)
		(width 0.1143)
		(layer "In2.Cu")
		(net "P3E_CPU0_PE1_PCH_RXP<2>")
	)
	(segment
		(start 346.090748 -84.869528)
		(end 347.054678 -85.198458)
		(width 0.1143)
		(layer "In2.Cu")
		(net "P3E_CPU0_PE1_PCH_RXP<2>")
	)
	(segment
		(start 360.72318 -92.633292)
		(end 361.935776 -93.441774)
		(width 0.1143)
		(layer "In2.Cu")
		(net "P3E_CPU0_PE1_PCH_RXP<2>")
	)
	(segment
		(start 342.27135 -84.371942)
		(end 343.208864 -84.625942)
		(width 0.1143)
		(layer "In2.Cu")
		(net "P3E_CPU0_PE1_PCH_RXP<2>")
	)
	(segment
		(start 336.835242 -82.728054)
		(end 337.178396 -82.821018)
		(width 0.1143)
		(layer "In2.Cu")
		(net "P3E_CPU0_PE1_PCH_RXP<2>")
	)
	(segment
		(start 351.169986 -84.715858)
		(end 351.906078 -84.572856)
		(width 0.1143)
		(layer "In2.Cu")
		(net "P3E_CPU0_PE1_PCH_RXP<2>")
	)
	(segment
		(start 374.862598 -116.504212)
		(end 375.051066 -116.69268)
		(width 0.0889)
		(layer "In2.Cu")
		(net "P3E_CPU0_PE1_PCH_RXP<2>")
	)
	(segment
		(start 362.264452 -96.375982)
		(end 362.51642 -97.559368)
		(width 0.1143)
		(layer "In2.Cu")
		(net "P3E_CPU0_PE1_PCH_RXP<2>")
	)
	(segment
		(start 337.84032 -83.000596)
		(end 338.183474 -83.09356)
		(width 0.1143)
		(layer "In2.Cu")
		(net "P3E_CPU0_PE1_PCH_RXP<2>")
	)
	(segment
		(start 341.290656 -84.106258)
		(end 341.621618 -84.19592)
		(width 0.1143)
		(layer "In2.Cu")
		(net "P3E_CPU0_PE1_PCH_RXP<2>")
	)
	(segment
		(start 336.632804 -82.844386)
		(end 336.835242 -82.728054)
		(width 0.1143)
		(layer "In2.Cu")
		(net "P3E_CPU0_PE1_PCH_RXP<2>")
	)
	(segment
		(start 336.289396 -82.751168)
		(end 336.632804 -82.844386)
		(width 0.1143)
		(layer "In2.Cu")
		(net "P3E_CPU0_PE1_PCH_RXP<2>")
	)
	(segment
		(start 334.862932 -81.842102)
		(end 335.284318 -82.47888)
		(width 0.1143)
		(layer "In2.Cu")
		(net "P3E_CPU0_PE1_PCH_RXP<2>")
	)
	(segment
		(start 333.148178 -76.9493)
		(end 333.82458 -80.272636)
		(width 0.1143)
		(layer "In2.Cu")
		(net "P3E_CPU0_PE1_PCH_RXP<2>")
	)
	(segment
		(start 347.054678 -85.198458)
		(end 347.89872 -84.981542)
		(width 0.1143)
		(layer "In2.Cu")
		(net "P3E_CPU0_PE1_PCH_RXP<2>")
	)
	(segment
		(start 375.868438 -117.384322)
		(end 375.868438 -117.510052)
		(width 0.0889)
		(layer "In2.Cu")
		(net "P3E_CPU0_PE1_PCH_RXP<2>")
	)
	(segment
		(start 358.572308 -92.202254)
		(end 360.72318 -92.633292)
		(width 0.1143)
		(layer "In2.Cu")
		(net "P3E_CPU0_PE1_PCH_RXP<2>")
	)
	(segment
		(start 334.713326 -81.31683)
		(end 334.909668 -81.613248)
		(width 0.1143)
		(layer "In2.Cu")
		(net "P3E_CPU0_PE1_PCH_RXP<2>")
	)
	(segment
		(start 335.284318 -82.47888)
		(end 335.627472 -82.571844)
		(width 0.1143)
		(layer "In2.Cu")
		(net "P3E_CPU0_PE1_PCH_RXP<2>")
	)
	(segment
		(start 341.824056 -84.079842)
		(end 342.155018 -84.169504)
		(width 0.1143)
		(layer "In2.Cu")
		(net "P3E_CPU0_PE1_PCH_RXP<2>")
	)
	(segment
		(start 338.0994 -69.704458)
		(end 337.984592 -69.58965)
		(width 0.1143)
		(layer "In2.Cu")
		(net "P3E_CPU0_PE1_PCH_RXP<2>")
	)
	(segment
		(start 355.806248 -84.267294)
		(end 356.22484 -84.549234)
		(width 0.1143)
		(layer "In2.Cu")
		(net "P3E_CPU0_PE1_PCH_RXP<2>")
	)
	(segment
		(start 362.509816 -95.220028)
		(end 362.264452 -96.375982)
		(width 0.1143)
		(layer "In2.Cu")
		(net "P3E_CPU0_PE1_PCH_RXP<2>")
	)
	(segment
		(start 334.138778 -80.44815)
		(end 334.33512 -80.744822)
		(width 0.1143)
		(layer "In2.Cu")
		(net "P3E_CPU0_PE1_PCH_RXP<2>")
	)
	(segment
		(start 334.288384 -80.973422)
		(end 334.484726 -81.270094)
		(width 0.1143)
		(layer "In2.Cu")
		(net "P3E_CPU0_PE1_PCH_RXP<2>")
	)
	(segment
		(start 374.673876 -116.18976)
		(end 374.862598 -116.378482)
		(width 0.0889)
		(layer "In2.Cu")
		(net "P3E_CPU0_PE1_PCH_RXP<2>")
	)
	(segment
		(start 362.6993 -107.52582)
		(end 363.157516 -109.688376)
		(width 0.1143)
		(layer "In2.Cu")
		(net "P3E_CPU0_PE1_PCH_RXP<2>")
	)
	(segment
		(start 338.845398 -83.272884)
		(end 339.188806 -83.365848)
		(width 0.1143)
		(layer "In2.Cu")
		(net "P3E_CPU0_PE1_PCH_RXP<2>")
	)
	(segment
		(start 337.178396 -82.821018)
		(end 337.294728 -83.02371)
		(width 0.1143)
		(layer "In2.Cu")
		(net "P3E_CPU0_PE1_PCH_RXP<2>")
	)
	(segment
		(start 334.909668 -81.613248)
		(end 334.862932 -81.842102)
		(width 0.1143)
		(layer "In2.Cu")
		(net "P3E_CPU0_PE1_PCH_RXP<2>")
	)
	(segment
		(start 374.548146 -116.18976)
		(end 374.673876 -116.18976)
		(width 0.0889)
		(layer "In2.Cu")
		(net "P3E_CPU0_PE1_PCH_RXP<2>")
	)
	(segment
		(start 334.484726 -81.270094)
		(end 334.713326 -81.31683)
		(width 0.1143)
		(layer "In2.Cu")
		(net "P3E_CPU0_PE1_PCH_RXP<2>")
	)
	(segment
		(start 351.906078 -84.572856)
		(end 352.69551 -84.726272)
		(width 0.1143)
		(layer "In2.Cu")
		(net "P3E_CPU0_PE1_PCH_RXP<2>")
	)
	(segment
		(start 372.226078 -116.001292)
		(end 372.314978 -115.912392)
		(width 0.0889)
		(layer "In2.Cu")
		(net "P3E_CPU0_PE1_PCH_RXP<2>")
	)
	(segment
		(start 373.737378 -115.912392)
		(end 374.004078 -115.912392)
		(width 0.0889)
		(layer "In2.Cu")
		(net "P3E_CPU0_PE1_PCH_RXP<2>")
	)
	(segment
		(start 337.637882 -83.116674)
		(end 337.84032 -83.000596)
		(width 0.1143)
		(layer "In2.Cu")
		(net "P3E_CPU0_PE1_PCH_RXP<2>")
	)
	(segment
		(start 364.765844 -113.72977)
		(end 365.14405 -114.916458)
		(width 0.1143)
		(layer "In2.Cu")
		(net "P3E_CPU0_PE1_PCH_RXP<2>")
	)
	(segment
		(start 349.429324 -85.612478)
		(end 350.007174 -85.50021)
		(width 0.1143)
		(layer "In2.Cu")
		(net "P3E_CPU0_PE1_PCH_RXP<2>")
	)
	(segment
		(start 377.496324 -117.77726)
		(end 377.19762 -117.77726)
		(width 0.089408)
		(layer "In2.Cu")
		(net "P3E_CPU0_PE1_PCH_RXP<2>")
	)
	(segment
		(start 372.314978 -115.912392)
		(end 372.581678 -115.912392)
		(width 0.0889)
		(layer "In2.Cu")
		(net "P3E_CPU0_PE1_PCH_RXP<2>")
	)
	(segment
		(start 376.57913 -118.220744)
		(end 377.475242 -118.220744)
		(width 0.0889)
		(layer "In2.Cu")
		(net "P3E_CPU0_PE1_PCH_RXP<2>")
	)
	(segment
		(start 361.935776 -93.441774)
		(end 362.509816 -95.220028)
		(width 0.1143)
		(layer "In2.Cu")
		(net "P3E_CPU0_PE1_PCH_RXP<2>")
	)
	(segment
		(start 343.208864 -84.625942)
		(end 343.411556 -84.509864)
		(width 0.1143)
		(layer "In2.Cu")
		(net "P3E_CPU0_PE1_PCH_RXP<2>")
	)
	(segment
		(start 333.909924 -80.401668)
		(end 334.138778 -80.44815)
		(width 0.1143)
		(layer "In2.Cu")
		(net "P3E_CPU0_PE1_PCH_RXP<2>")
	)
	(segment
		(start 343.742518 -84.599526)
		(end 343.858596 -84.801964)
		(width 0.1143)
		(layer "In2.Cu")
		(net "P3E_CPU0_PE1_PCH_RXP<2>")
	)
	(segment
		(start 339.188806 -83.365848)
		(end 339.304884 -83.568286)
		(width 0.1143)
		(layer "In2.Cu")
		(net "P3E_CPU0_PE1_PCH_RXP<2>")
	)
	(segment
		(start 377.60021 -118.095776)
		(end 377.60021 -117.881146)
		(width 0.089408)
		(layer "In2.Cu")
		(net "P3E_CPU0_PE1_PCH_RXP<2>")
	)
	(segment
		(start 374.359678 -116.001292)
		(end 374.548146 -116.18976)
		(width 0.0889)
		(layer "In2.Cu")
		(net "P3E_CPU0_PE1_PCH_RXP<2>")
	)
	(segment
		(start 375.868438 -117.510052)
		(end 376.57913 -118.220744)
		(width 0.0889)
		(layer "In2.Cu")
		(net "P3E_CPU0_PE1_PCH_RXP<2>")
	)
	(segment
		(start 356.498398 -85.262466)
		(end 356.395782 -85.790786)
		(width 0.1143)
		(layer "In2.Cu")
		(net "P3E_CPU0_PE1_PCH_RXP<2>")
	)
	(segment
		(start 373.026178 -115.912392)
		(end 373.292878 -115.912392)
		(width 0.0889)
		(layer "In2.Cu")
		(net "P3E_CPU0_PE1_PCH_RXP<2>")
	)
	(segment
		(start 347.89872 -84.981542)
		(end 348.73565 -85.441028)
		(width 0.1143)
		(layer "In2.Cu")
		(net "P3E_CPU0_PE1_PCH_RXP<2>")
	)
	(segment
		(start 333.82458 -80.272636)
		(end 333.909924 -80.401668)
		(width 0.1143)
		(layer "In2.Cu")
		(net "P3E_CPU0_PE1_PCH_RXP<2>")
	)
	(segment
		(start 377.475242 -118.220744)
		(end 377.60021 -118.095776)
		(width 0.089408)
		(layer "In2.Cu")
		(net "P3E_CPU0_PE1_PCH_RXP<2>")
	)
	(segment
		(start 337.984592 -69.58965)
		(end 335.92262 -69.58965)
		(width 0.1143)
		(layer "In2.Cu")
		(net "P3E_CPU0_PE1_PCH_RXP<2>")
	)
	(segment
		(start 335.92262 -69.58965)
		(end 332.093824 -71.390764)
		(width 0.1143)
		(layer "In2.Cu")
		(net "P3E_CPU0_PE1_PCH_RXP<2>")
	)
	(segment
		(start 341.174324 -83.90382)
		(end 341.290656 -84.106258)
		(width 0.1143)
		(layer "In2.Cu")
		(net "P3E_CPU0_PE1_PCH_RXP<2>")
	)
	(segment
		(start 374.862598 -116.378482)
		(end 374.862598 -116.504212)
		(width 0.0889)
		(layer "In2.Cu")
		(net "P3E_CPU0_PE1_PCH_RXP<2>")
	)
	(segment
		(start 364.555278 -110.702852)
		(end 365.113316 -112.45596)
		(width 0.1143)
		(layer "In2.Cu")
		(net "P3E_CPU0_PE1_PCH_RXP<2>")
	)
	(segment
		(start 344.83929 -85.067648)
		(end 345.170252 -85.15731)
		(width 0.1143)
		(layer "In2.Cu")
		(net "P3E_CPU0_PE1_PCH_RXP<2>")
	)
	(segment
		(start 337.294728 -83.02371)
		(end 337.637882 -83.116674)
		(width 0.1143)
		(layer "In2.Cu")
		(net "P3E_CPU0_PE1_PCH_RXP<2>")
	)
	(segment
		(start 352.69551 -84.726272)
		(end 355.430836 -84.194396)
		(width 0.1143)
		(layer "In2.Cu")
		(net "P3E_CPU0_PE1_PCH_RXP<2>")
	)
	(segment
		(start 373.381778 -116.001292)
		(end 373.648478 -116.001292)
		(width 0.0889)
		(layer "In2.Cu")
		(net "P3E_CPU0_PE1_PCH_RXP<2>")
	)
	(segment
		(start 332.093824 -71.390764)
		(end 331.823822 -72.328786)
		(width 0.1143)
		(layer "In2.Cu")
		(net "P3E_CPU0_PE1_PCH_RXP<2>")
	)
	(segment
		(start 335.830164 -82.455766)
		(end 336.173318 -82.54873)
		(width 0.1143)
		(layer "In2.Cu")
		(net "P3E_CPU0_PE1_PCH_RXP<2>")
	)
	(segment
		(start 373.292878 -115.912392)
		(end 373.381778 -116.001292)
		(width 0.0889)
		(layer "In2.Cu")
		(net "P3E_CPU0_PE1_PCH_RXP<2>")
	)
	(segment
		(start 340.309962 -83.840574)
		(end 340.640924 -83.930236)
		(width 0.1143)
		(layer "In2.Cu")
		(net "P3E_CPU0_PE1_PCH_RXP<2>")
	)
	(segment
		(start 342.155018 -84.169504)
		(end 342.27135 -84.371942)
		(width 0.1143)
		(layer "In2.Cu")
		(net "P3E_CPU0_PE1_PCH_RXP<2>")
	)
	(segment
		(start 333.351378 -74.686668)
		(end 333.479902 -75.318366)
		(width 0.1143)
		(layer "In2.Cu")
		(net "P3E_CPU0_PE1_PCH_RXP<2>")
	)
	(segment
		(start 333.479902 -75.318366)
		(end 333.148178 -76.9493)
		(width 0.1143)
		(layer "In2.Cu")
		(net "P3E_CPU0_PE1_PCH_RXP<2>")
	)
	(segment
		(start 356.22484 -84.549234)
		(end 356.414578 -84.83092)
		(width 0.1143)
		(layer "In2.Cu")
		(net "P3E_CPU0_PE1_PCH_RXP<2>")
	)
	(segment
		(start 371.058186 -115.950492)
		(end 371.108986 -116.001292)
		(width 0.0889)
		(layer "In2.Cu")
		(net "P3E_CPU0_PE1_PCH_RXP<2>")
	)
	(segment
		(start 379.81255 -118.670324)
		(end 379.31725 -118.4402)
		(width 0.1143)
		(layer "F.Cu")
		(net "P3E_CPU0_PE1_PCH_RXP<1>")
	)
	(via
		(at 336.17154 -69.283072)
		(size 0.508)
		(drill 0.254)
		(layers "F.Cu" "B.Cu")
		(net "P3E_CPU0_PE1_PCH_RXP<1>")
	)
	(via
		(at 379.81255 -118.670324)
		(size 0.508)
		(drill 0.254)
		(layers "F.Cu" "B.Cu")
		(net "P3E_CPU0_PE1_PCH_RXP<1>")
	)
	(via
		(at 336.228436 -71.034402)
		(size 0.508)
		(drill 0.254)
		(layers "F.Cu" "B.Cu")
		(net "P3E_CPU0_PE1_PCH_RXP<1>")
	)
	(segment
		(start 336.738722 -62.139322)
		(end 336.738722 -62.842902)
		(width 0.1143)
		(layer "B.Cu")
		(net "P3E_CPU0_PE1_PCH_RXP<1>")
	)
	(segment
		(start 336.4992 -70.763638)
		(end 336.228436 -71.034402)
		(width 0.1143)
		(layer "B.Cu")
		(net "P3E_CPU0_PE1_PCH_RXP<1>")
	)
	(segment
		(start 336.17154 -69.283072)
		(end 336.17154 -69.910706)
		(width 0.1143)
		(layer "B.Cu")
		(net "P3E_CPU0_PE1_PCH_RXP<1>")
	)
	(segment
		(start 336.140806 -61.257434)
		(end 336.140806 -61.541406)
		(width 0.1143)
		(layer "B.Cu")
		(net "P3E_CPU0_PE1_PCH_RXP<1>")
	)
	(segment
		(start 336.738722 -62.842902)
		(end 336.17154 -63.410084)
		(width 0.1143)
		(layer "B.Cu")
		(net "P3E_CPU0_PE1_PCH_RXP<1>")
	)
	(segment
		(start 336.4992 -70.238366)
		(end 336.4992 -70.763638)
		(width 0.1143)
		(layer "B.Cu")
		(net "P3E_CPU0_PE1_PCH_RXP<1>")
	)
	(segment
		(start 336.17154 -63.410084)
		(end 336.17154 -69.283072)
		(width 0.1143)
		(layer "B.Cu")
		(net "P3E_CPU0_PE1_PCH_RXP<1>")
	)
	(segment
		(start 336.140806 -61.541406)
		(end 336.738722 -62.139322)
		(width 0.1143)
		(layer "B.Cu")
		(net "P3E_CPU0_PE1_PCH_RXP<1>")
	)
	(segment
		(start 336.17154 -69.910706)
		(end 336.4992 -70.238366)
		(width 0.1143)
		(layer "B.Cu")
		(net "P3E_CPU0_PE1_PCH_RXP<1>")
	)
	(segment
		(start 336.414872 -70.515226)
		(end 336.29219 -70.369176)
		(width 0.1143)
		(layer "In2.Cu")
		(net "P3E_CPU0_PE1_PCH_RXP<1>")
	)
	(segment
		(start 365.79048 -112.39627)
		(end 365.438944 -113.68405)
		(width 0.1143)
		(layer "In2.Cu")
		(net "P3E_CPU0_PE1_PCH_RXP<1>")
	)
	(segment
		(start 365.69015 -111.53521)
		(end 365.794036 -111.862108)
		(width 0.1143)
		(layer "In2.Cu")
		(net "P3E_CPU0_PE1_PCH_RXP<1>")
	)
	(segment
		(start 333.83601 -77.13599)
		(end 334.084168 -78.240128)
		(width 0.1143)
		(layer "In2.Cu")
		(net "P3E_CPU0_PE1_PCH_RXP<1>")
	)
	(segment
		(start 357.281988 -86.661752)
		(end 357.476298 -86.791292)
		(width 0.1143)
		(layer "In2.Cu")
		(net "P3E_CPU0_PE1_PCH_RXP<1>")
	)
	(segment
		(start 333.437484 -73.479914)
		(end 333.979012 -74.204068)
		(width 0.1143)
		(layer "In2.Cu")
		(net "P3E_CPU0_PE1_PCH_RXP<1>")
	)
	(segment
		(start 335.8896 -79.523082)
		(end 335.92262 -79.754222)
		(width 0.1143)
		(layer "In2.Cu")
		(net "P3E_CPU0_PE1_PCH_RXP<1>")
	)
	(segment
		(start 338.365338 -81.585308)
		(end 338.596224 -81.552034)
		(width 0.1143)
		(layer "In2.Cu")
		(net "P3E_CPU0_PE1_PCH_RXP<1>")
	)
	(segment
		(start 357.303324 -85.05698)
		(end 357.134668 -85.924644)
		(width 0.1143)
		(layer "In2.Cu")
		(net "P3E_CPU0_PE1_PCH_RXP<1>")
	)
	(segment
		(start 335.4451 -70.759574)
		(end 335.134712 -70.90537)
		(width 0.1143)
		(layer "In2.Cu")
		(net "P3E_CPU0_PE1_PCH_RXP<1>")
	)
	(segment
		(start 357.165402 -84.347558)
		(end 357.303324 -85.05698)
		(width 0.1143)
		(layer "In2.Cu")
		(net "P3E_CPU0_PE1_PCH_RXP<1>")
	)
	(segment
		(start 336.2071 -79.967328)
		(end 336.43824 -79.934308)
		(width 0.1143)
		(layer "In2.Cu")
		(net "P3E_CPU0_PE1_PCH_RXP<1>")
	)
	(segment
		(start 357.476298 -86.791292)
		(end 357.543354 -87.127588)
		(width 0.1143)
		(layer "In2.Cu")
		(net "P3E_CPU0_PE1_PCH_RXP<1>")
	)
	(segment
		(start 335.134712 -70.90537)
		(end 334.915002 -70.826122)
		(width 0.1143)
		(layer "In2.Cu")
		(net "P3E_CPU0_PE1_PCH_RXP<1>")
	)
	(segment
		(start 376.40768 -115.824)
		(end 377.1138 -115.824)
		(width 0.0889)
		(layer "In2.Cu")
		(net "P3E_CPU0_PE1_PCH_RXP<1>")
	)
	(segment
		(start 362.508546 -93.025722)
		(end 363.207046 -95.185738)
		(width 0.1143)
		(layer "In2.Cu")
		(net "P3E_CPU0_PE1_PCH_RXP<1>")
	)
	(segment
		(start 380.215648 -118.735348)
		(end 380.150624 -118.670324)
		(width 0.0889)
		(layer "In2.Cu")
		(net "P3E_CPU0_PE1_PCH_RXP<1>")
	)
	(segment
		(start 362.84662 -99.128834)
		(end 363.3343 -101.522276)
		(width 0.1143)
		(layer "In2.Cu")
		(net "P3E_CPU0_PE1_PCH_RXP<1>")
	)
	(segment
		(start 338.903818 -81.988914)
		(end 339.178138 -82.194654)
		(width 0.1143)
		(layer "In2.Cu")
		(net "P3E_CPU0_PE1_PCH_RXP<1>")
	)
	(segment
		(start 352.632264 -82.786728)
		(end 352.76282 -82.59318)
		(width 0.1143)
		(layer "In2.Cu")
		(net "P3E_CPU0_PE1_PCH_RXP<1>")
	)
	(segment
		(start 357.820214 -89.35593)
		(end 358.464104 -90.32875)
		(width 0.1143)
		(layer "In2.Cu")
		(net "P3E_CPU0_PE1_PCH_RXP<1>")
	)
	(segment
		(start 347.606366 -83.159854)
		(end 348.3102 -83.41614)
		(width 0.1143)
		(layer "In2.Cu")
		(net "P3E_CPU0_PE1_PCH_RXP<1>")
	)
	(segment
		(start 336.414872 -70.847966)
		(end 336.414872 -70.515226)
		(width 0.1143)
		(layer "In2.Cu")
		(net "P3E_CPU0_PE1_PCH_RXP<1>")
	)
	(segment
		(start 363.3343 -101.522276)
		(end 363.3343 -107.45851)
		(width 0.1143)
		(layer "In2.Cu")
		(net "P3E_CPU0_PE1_PCH_RXP<1>")
	)
	(segment
		(start 334.256126 -78.504796)
		(end 334.540606 -78.718156)
		(width 0.1143)
		(layer "In2.Cu")
		(net "P3E_CPU0_PE1_PCH_RXP<1>")
	)
	(segment
		(start 335.92262 -79.754222)
		(end 336.2071 -79.967328)
		(width 0.1143)
		(layer "In2.Cu")
		(net "P3E_CPU0_PE1_PCH_RXP<1>")
	)
	(segment
		(start 335.0895 -79.129382)
		(end 335.37398 -79.342742)
		(width 0.1143)
		(layer "In2.Cu")
		(net "P3E_CPU0_PE1_PCH_RXP<1>")
	)
	(segment
		(start 350.337374 -83.022186)
		(end 350.880426 -83.127596)
		(width 0.1143)
		(layer "In2.Cu")
		(net "P3E_CPU0_PE1_PCH_RXP<1>")
	)
	(segment
		(start 358.464104 -90.32875)
		(end 362.508546 -93.025722)
		(width 0.1143)
		(layer "In2.Cu")
		(net "P3E_CPU0_PE1_PCH_RXP<1>")
	)
	(segment
		(start 365.794036 -111.862108)
		(end 365.686594 -112.069372)
		(width 0.1143)
		(layer "In2.Cu")
		(net "P3E_CPU0_PE1_PCH_RXP<1>")
	)
	(segment
		(start 353.09937 -82.527902)
		(end 353.293172 -82.658458)
		(width 0.1143)
		(layer "In2.Cu")
		(net "P3E_CPU0_PE1_PCH_RXP<1>")
	)
	(segment
		(start 352.76282 -82.59318)
		(end 353.09937 -82.527902)
		(width 0.1143)
		(layer "In2.Cu")
		(net "P3E_CPU0_PE1_PCH_RXP<1>")
	)
	(segment
		(start 333.476854 -71.502016)
		(end 333.227934 -72.36587)
		(width 0.1143)
		(layer "In2.Cu")
		(net "P3E_CPU0_PE1_PCH_RXP<1>")
	)
	(segment
		(start 365.686594 -112.069372)
		(end 365.79048 -112.39627)
		(width 0.1143)
		(layer "In2.Cu")
		(net "P3E_CPU0_PE1_PCH_RXP<1>")
	)
	(segment
		(start 374.06326 -113.47958)
		(end 376.40768 -115.824)
		(width 0.0889)
		(layer "In2.Cu")
		(net "P3E_CPU0_PE1_PCH_RXP<1>")
	)
	(segment
		(start 365.674656 -114.422682)
		(end 366.685068 -115.0874)
		(width 0.1143)
		(layer "In2.Cu")
		(net "P3E_CPU0_PE1_PCH_RXP<1>")
	)
	(segment
		(start 334.771746 -78.685136)
		(end 335.056226 -78.898242)
		(width 0.1143)
		(layer "In2.Cu")
		(net "P3E_CPU0_PE1_PCH_RXP<1>")
	)
	(segment
		(start 377.80087 -117.433598)
		(end 378.031248 -117.299994)
		(width 0.0889)
		(layer "In2.Cu")
		(net "P3E_CPU0_PE1_PCH_RXP<1>")
	)
	(segment
		(start 367.878106 -115.1382)
		(end 369.536726 -113.47958)
		(width 0.0889)
		(layer "In2.Cu")
		(net "P3E_CPU0_PE1_PCH_RXP<1>")
	)
	(segment
		(start 333.899256 -76.825348)
		(end 333.83601 -77.13599)
		(width 0.1143)
		(layer "In2.Cu")
		(net "P3E_CPU0_PE1_PCH_RXP<1>")
	)
	(segment
		(start 367.5634 -115.1382)
		(end 367.878106 -115.1382)
		(width 0.0889)
		(layer "In2.Cu")
		(net "P3E_CPU0_PE1_PCH_RXP<1>")
	)
	(segment
		(start 377.712478 -117.433598)
		(end 377.80087 -117.433598)
		(width 0.0889)
		(layer "In2.Cu")
		(net "P3E_CPU0_PE1_PCH_RXP<1>")
	)
	(segment
		(start 367.5126 -115.0874)
		(end 367.5634 -115.1382)
		(width 0.0889)
		(layer "In2.Cu")
		(net "P3E_CPU0_PE1_PCH_RXP<1>")
	)
	(segment
		(start 337.271614 -80.559148)
		(end 337.556094 -80.772254)
		(width 0.1143)
		(layer "In2.Cu")
		(net "P3E_CPU0_PE1_PCH_RXP<1>")
	)
	(segment
		(start 335.37398 -79.342742)
		(end 335.60512 -79.309722)
		(width 0.1143)
		(layer "In2.Cu")
		(net "P3E_CPU0_PE1_PCH_RXP<1>")
	)
	(segment
		(start 333.227934 -72.36587)
		(end 333.437484 -73.479914)
		(width 0.1143)
		(layer "In2.Cu")
		(net "P3E_CPU0_PE1_PCH_RXP<1>")
	)
	(segment
		(start 334.094074 -76.69657)
		(end 333.899256 -76.825348)
		(width 0.1143)
		(layer "In2.Cu")
		(net "P3E_CPU0_PE1_PCH_RXP<1>")
	)
	(segment
		(start 377.3932 -116.1034)
		(end 377.3932 -117.11432)
		(width 0.0889)
		(layer "In2.Cu")
		(net "P3E_CPU0_PE1_PCH_RXP<1>")
	)
	(segment
		(start 338.870798 -81.757774)
		(end 338.903818 -81.988914)
		(width 0.1143)
		(layer "In2.Cu")
		(net "P3E_CPU0_PE1_PCH_RXP<1>")
	)
	(segment
		(start 336.755994 -80.378808)
		(end 337.040474 -80.592168)
		(width 0.1143)
		(layer "In2.Cu")
		(net "P3E_CPU0_PE1_PCH_RXP<1>")
	)
	(segment
		(start 356.245668 -82.98307)
		(end 357.165402 -84.347558)
		(width 0.1143)
		(layer "In2.Cu")
		(net "P3E_CPU0_PE1_PCH_RXP<1>")
	)
	(segment
		(start 365.438944 -113.68405)
		(end 365.674656 -114.422682)
		(width 0.1143)
		(layer "In2.Cu")
		(net "P3E_CPU0_PE1_PCH_RXP<1>")
	)
	(segment
		(start 350.880426 -83.127596)
		(end 351.63506 -82.980784)
		(width 0.1143)
		(layer "In2.Cu")
		(net "P3E_CPU0_PE1_PCH_RXP<1>")
	)
	(segment
		(start 365.482886 -111.428022)
		(end 365.69015 -111.53521)
		(width 0.1143)
		(layer "In2.Cu")
		(net "P3E_CPU0_PE1_PCH_RXP<1>")
	)
	(segment
		(start 353.293172 -82.658458)
		(end 353.934014 -82.533744)
		(width 0.1143)
		(layer "In2.Cu")
		(net "P3E_CPU0_PE1_PCH_RXP<1>")
	)
	(segment
		(start 336.29219 -70.369176)
		(end 335.996788 -70.317868)
		(width 0.1143)
		(layer "In2.Cu")
		(net "P3E_CPU0_PE1_PCH_RXP<1>")
	)
	(segment
		(start 353.934014 -82.533744)
		(end 356.245668 -82.98307)
		(width 0.1143)
		(layer "In2.Cu")
		(net "P3E_CPU0_PE1_PCH_RXP<1>")
	)
	(segment
		(start 334.084168 -78.240128)
		(end 334.256126 -78.504796)
		(width 0.1143)
		(layer "In2.Cu")
		(net "P3E_CPU0_PE1_PCH_RXP<1>")
	)
	(segment
		(start 336.228436 -71.034402)
		(end 336.414872 -70.847966)
		(width 0.1143)
		(layer "In2.Cu")
		(net "P3E_CPU0_PE1_PCH_RXP<1>")
	)
	(segment
		(start 335.524094 -70.539864)
		(end 335.4451 -70.759574)
		(width 0.1143)
		(layer "In2.Cu")
		(net "P3E_CPU0_PE1_PCH_RXP<1>")
	)
	(segment
		(start 381.3937 -118.648734)
		(end 381.3937 -118.691914)
		(width 0.0889)
		(layer "In2.Cu")
		(net "P3E_CPU0_PE1_PCH_RXP<1>")
	)
	(segment
		(start 345.938094 -83.070446)
		(end 346.873322 -83.33105)
		(width 0.1143)
		(layer "In2.Cu")
		(net "P3E_CPU0_PE1_PCH_RXP<1>")
	)
	(segment
		(start 377.1138 -115.824)
		(end 377.3932 -116.1034)
		(width 0.0889)
		(layer "In2.Cu")
		(net "P3E_CPU0_PE1_PCH_RXP<1>")
	)
	(segment
		(start 363.17301 -97.590102)
		(end 362.84662 -99.128834)
		(width 0.1143)
		(layer "In2.Cu")
		(net "P3E_CPU0_PE1_PCH_RXP<1>")
	)
	(segment
		(start 362.934758 -96.466152)
		(end 363.17301 -97.590102)
		(width 0.1143)
		(layer "In2.Cu")
		(net "P3E_CPU0_PE1_PCH_RXP<1>")
	)
	(segment
		(start 334.205834 -75.318874)
		(end 334.033622 -76.16571)
		(width 0.1143)
		(layer "In2.Cu")
		(net "P3E_CPU0_PE1_PCH_RXP<1>")
	)
	(segment
		(start 351.63506 -82.980784)
		(end 351.765616 -82.787236)
		(width 0.1143)
		(layer "In2.Cu")
		(net "P3E_CPU0_PE1_PCH_RXP<1>")
	)
	(segment
		(start 357.413814 -87.321898)
		(end 357.820214 -89.35593)
		(width 0.1143)
		(layer "In2.Cu")
		(net "P3E_CPU0_PE1_PCH_RXP<1>")
	)
	(segment
		(start 334.1624 -76.360528)
		(end 334.094074 -76.69657)
		(width 0.1143)
		(layer "In2.Cu")
		(net "P3E_CPU0_PE1_PCH_RXP<1>")
	)
	(segment
		(start 363.729016 -109.314488)
		(end 365.135668 -110.335822)
		(width 0.1143)
		(layer "In2.Cu")
		(net "P3E_CPU0_PE1_PCH_RXP<1>")
	)
	(segment
		(start 357.134668 -85.924644)
		(end 357.281988 -86.661752)
		(width 0.1143)
		(layer "In2.Cu")
		(net "P3E_CPU0_PE1_PCH_RXP<1>")
	)
	(segment
		(start 346.873322 -83.33105)
		(end 347.606366 -83.159854)
		(width 0.1143)
		(layer "In2.Cu")
		(net "P3E_CPU0_PE1_PCH_RXP<1>")
	)
	(segment
		(start 363.207046 -95.185738)
		(end 362.934758 -96.466152)
		(width 0.1143)
		(layer "In2.Cu")
		(net "P3E_CPU0_PE1_PCH_RXP<1>")
	)
	(segment
		(start 365.135668 -110.335822)
		(end 365.482886 -111.428022)
		(width 0.1143)
		(layer "In2.Cu")
		(net "P3E_CPU0_PE1_PCH_RXP<1>")
	)
	(segment
		(start 333.979012 -74.204068)
		(end 334.205834 -75.318874)
		(width 0.1143)
		(layer "In2.Cu")
		(net "P3E_CPU0_PE1_PCH_RXP<1>")
	)
	(segment
		(start 351.765616 -82.787236)
		(end 352.102166 -82.721704)
		(width 0.1143)
		(layer "In2.Cu")
		(net "P3E_CPU0_PE1_PCH_RXP<1>")
	)
	(segment
		(start 339.178138 -82.194654)
		(end 343.250012 -83.861656)
		(width 0.1143)
		(layer "In2.Cu")
		(net "P3E_CPU0_PE1_PCH_RXP<1>")
	)
	(segment
		(start 366.685068 -115.0874)
		(end 367.5126 -115.0874)
		(width 0.1143)
		(layer "In2.Cu")
		(net "P3E_CPU0_PE1_PCH_RXP<1>")
	)
	(segment
		(start 377.3932 -117.11432)
		(end 377.712478 -117.433598)
		(width 0.0889)
		(layer "In2.Cu")
		(net "P3E_CPU0_PE1_PCH_RXP<1>")
	)
	(segment
		(start 337.040474 -80.592168)
		(end 337.271614 -80.559148)
		(width 0.1143)
		(layer "In2.Cu")
		(net "P3E_CPU0_PE1_PCH_RXP<1>")
	)
	(segment
		(start 343.250012 -83.861656)
		(end 345.938094 -83.070446)
		(width 0.1143)
		(layer "In2.Cu")
		(net "P3E_CPU0_PE1_PCH_RXP<1>")
	)
	(segment
		(start 352.295714 -82.85226)
		(end 352.632264 -82.786728)
		(width 0.1143)
		(layer "In2.Cu")
		(net "P3E_CPU0_PE1_PCH_RXP<1>")
	)
	(segment
		(start 334.033622 -76.16571)
		(end 334.1624 -76.360528)
		(width 0.1143)
		(layer "In2.Cu")
		(net "P3E_CPU0_PE1_PCH_RXP<1>")
	)
	(segment
		(start 363.3343 -107.45851)
		(end 363.729016 -109.314488)
		(width 0.1143)
		(layer "In2.Cu")
		(net "P3E_CPU0_PE1_PCH_RXP<1>")
	)
	(segment
		(start 336.72272 -80.147668)
		(end 336.755994 -80.378808)
		(width 0.1143)
		(layer "In2.Cu")
		(net "P3E_CPU0_PE1_PCH_RXP<1>")
	)
	(segment
		(start 380.150624 -118.670324)
		(end 379.81255 -118.670324)
		(width 0.0889)
		(layer "In2.Cu")
		(net "P3E_CPU0_PE1_PCH_RXP<1>")
	)
	(segment
		(start 337.556094 -80.772254)
		(end 337.589114 -81.003394)
		(width 0.1143)
		(layer "In2.Cu")
		(net "P3E_CPU0_PE1_PCH_RXP<1>")
	)
	(segment
		(start 380.8984 -117.790214)
		(end 380.8984 -117.82298)
		(width 0.0889)
		(layer "In2.Cu")
		(net "P3E_CPU0_PE1_PCH_RXP<1>")
	)
	(segment
		(start 335.996788 -70.317868)
		(end 335.524094 -70.539864)
		(width 0.1143)
		(layer "In2.Cu")
		(net "P3E_CPU0_PE1_PCH_RXP<1>")
	)
	(segment
		(start 369.536726 -113.47958)
		(end 374.06326 -113.47958)
		(width 0.0889)
		(layer "In2.Cu")
		(net "P3E_CPU0_PE1_PCH_RXP<1>")
	)
	(segment
		(start 334.540606 -78.718156)
		(end 334.771746 -78.685136)
		(width 0.1143)
		(layer "In2.Cu")
		(net "P3E_CPU0_PE1_PCH_RXP<1>")
	)
	(segment
		(start 335.60512 -79.309722)
		(end 335.8896 -79.523082)
		(width 0.1143)
		(layer "In2.Cu")
		(net "P3E_CPU0_PE1_PCH_RXP<1>")
	)
	(segment
		(start 352.102166 -82.721704)
		(end 352.295714 -82.85226)
		(width 0.1143)
		(layer "In2.Cu")
		(net "P3E_CPU0_PE1_PCH_RXP<1>")
	)
	(segment
		(start 348.3102 -83.41614)
		(end 350.337374 -83.022186)
		(width 0.1143)
		(layer "In2.Cu")
		(net "P3E_CPU0_PE1_PCH_RXP<1>")
	)
	(segment
		(start 334.915002 -70.826122)
		(end 333.476854 -71.502016)
		(width 0.1143)
		(layer "In2.Cu")
		(net "P3E_CPU0_PE1_PCH_RXP<1>")
	)
	(segment
		(start 338.596224 -81.552034)
		(end 338.870798 -81.757774)
		(width 0.1143)
		(layer "In2.Cu")
		(net "P3E_CPU0_PE1_PCH_RXP<1>")
	)
	(segment
		(start 336.43824 -79.934308)
		(end 336.72272 -80.147668)
		(width 0.1143)
		(layer "In2.Cu")
		(net "P3E_CPU0_PE1_PCH_RXP<1>")
	)
	(segment
		(start 357.543354 -87.127588)
		(end 357.413814 -87.321898)
		(width 0.1143)
		(layer "In2.Cu")
		(net "P3E_CPU0_PE1_PCH_RXP<1>")
	)
	(segment
		(start 337.589114 -81.003394)
		(end 338.365338 -81.585308)
		(width 0.1143)
		(layer "In2.Cu")
		(net "P3E_CPU0_PE1_PCH_RXP<1>")
	)
	(segment
		(start 335.056226 -78.898242)
		(end 335.0895 -79.129382)
		(width 0.1143)
		(layer "In2.Cu")
		(net "P3E_CPU0_PE1_PCH_RXP<1>")
	)
	(arc
		(start 381.3937 -118.691914)
		(mid 380.824918 -119.260867)
		(end 380.215648 -118.735348)
		(width 0.0889)
		(layer "In2.Cu")
		(net "P3E_CPU0_PE1_PCH_RXP<1>")
	)
	(arc
		(start 380.8984 -117.82298)
		(mid 380.95475 -118.01683)
		(end 381.098552 -118.158514)
		(width 0.0889)
		(layer "In2.Cu")
		(net "P3E_CPU0_PE1_PCH_RXP<1>")
	)
	(arc
		(start 380.012448 -117.299994)
		(mid 380.593956 -117.29474)
		(end 380.8984 -117.790214)
		(width 0.0889)
		(layer "In2.Cu")
		(net "P3E_CPU0_PE1_PCH_RXP<1>")
	)
	(arc
		(start 379.021848 -117.299994)
		(mid 379.31725 -117.220863)
		(end 379.612652 -117.299994)
		(width 0.0889)
		(layer "In2.Cu")
		(net "P3E_CPU0_PE1_PCH_RXP<1>")
	)
	(arc
		(start 381.098552 -118.158514)
		(mid 381.309416 -118.365518)
		(end 381.3937 -118.648734)
		(width 0.0889)
		(layer "In2.Cu")
		(net "P3E_CPU0_PE1_PCH_RXP<1>")
	)
	(arc
		(start 378.031248 -117.299994)
		(mid 378.32665 -117.220863)
		(end 378.622052 -117.299994)
		(width 0.0889)
		(layer "In2.Cu")
		(net "P3E_CPU0_PE1_PCH_RXP<1>")
	)
	(arc
		(start 378.622052 -117.299994)
		(mid 378.82195 -117.353493)
		(end 379.021848 -117.299994)
		(width 0.0889)
		(layer "In2.Cu")
		(net "P3E_CPU0_PE1_PCH_RXP<1>")
	)
	(arc
		(start 379.612652 -117.299994)
		(mid 379.81255 -117.353493)
		(end 380.012448 -117.299994)
		(width 0.0889)
		(layer "In2.Cu")
		(net "P3E_CPU0_PE1_PCH_RXP<1>")
	)
	(segment
		(start 295.23182 -98.500184)
		(end 295.80332 -98.500184)
		(width 0.1143)
		(layer "F.Cu")
		(net "P3E_CPU0_PE1_PCH_RXP<15>")
	)
	(via
		(at 295.80332 -98.500184)
		(size 0.508)
		(drill 0.254)
		(layers "F.Cu" "B.Cu")
		(net "P3E_CPU0_PE1_PCH_RXP<15>")
	)
	(via
		(at 351.343214 -126.64313)
		(size 0.508)
		(drill 0.254)
		(layers "F.Cu" "B.Cu")
		(net "P3E_CPU0_PE1_PCH_RXP<15>")
	)
	(segment
		(start 354.289614 -126.313946)
		(end 354.17506 -126.199392)
		(width 0.1143)
		(layer "B.Cu")
		(net "P3E_CPU0_PE1_PCH_RXP<15>")
	)
	(segment
		(start 351.813876 -126.199392)
		(end 351.807526 -126.193042)
		(width 0.1143)
		(layer "B.Cu")
		(net "P3E_CPU0_PE1_PCH_RXP<15>")
	)
	(segment
		(start 351.793302 -126.193042)
		(end 351.343214 -126.64313)
		(width 0.1143)
		(layer "B.Cu")
		(net "P3E_CPU0_PE1_PCH_RXP<15>")
	)
	(segment
		(start 354.289614 -126.624842)
		(end 354.289614 -126.313946)
		(width 0.1143)
		(layer "B.Cu")
		(net "P3E_CPU0_PE1_PCH_RXP<15>")
	)
	(segment
		(start 354.17506 -126.199392)
		(end 351.813876 -126.199392)
		(width 0.1143)
		(layer "B.Cu")
		(net "P3E_CPU0_PE1_PCH_RXP<15>")
	)
	(segment
		(start 351.807526 -126.193042)
		(end 351.793302 -126.193042)
		(width 0.1143)
		(layer "B.Cu")
		(net "P3E_CPU0_PE1_PCH_RXP<15>")
	)
	(segment
		(start 347.815154 -124.408184)
		(end 346.822776 -124.591064)
		(width 0.1143)
		(layer "In2.Cu")
		(net "P3E_CPU0_PE1_PCH_RXP<15>")
	)
	(segment
		(start 339.156548 -123.996196)
		(end 332.241144 -125.465332)
		(width 0.1143)
		(layer "In2.Cu")
		(net "P3E_CPU0_PE1_PCH_RXP<15>")
	)
	(segment
		(start 302.29175 -102.558088)
		(end 302.20285 -102.646988)
		(width 0.0889)
		(layer "In2.Cu")
		(net "P3E_CPU0_PE1_PCH_RXP<15>")
	)
	(segment
		(start 323.822822 -118.135654)
		(end 323.761354 -117.901466)
		(width 0.1143)
		(layer "In2.Cu")
		(net "P3E_CPU0_PE1_PCH_RXP<15>")
	)
	(segment
		(start 301.92345 -102.646988)
		(end 301.83455 -102.558088)
		(width 0.0889)
		(layer "In2.Cu")
		(net "P3E_CPU0_PE1_PCH_RXP<15>")
	)
	(segment
		(start 303.02835 -102.558088)
		(end 302.93945 -102.646988)
		(width 0.0889)
		(layer "In2.Cu")
		(net "P3E_CPU0_PE1_PCH_RXP<15>")
	)
	(segment
		(start 324.892924 -119.60733)
		(end 323.822822 -118.135654)
		(width 0.1143)
		(layer "In2.Cu")
		(net "P3E_CPU0_PE1_PCH_RXP<15>")
	)
	(segment
		(start 303.29505 -102.558088)
		(end 303.02835 -102.558088)
		(width 0.0889)
		(layer "In2.Cu")
		(net "P3E_CPU0_PE1_PCH_RXP<15>")
	)
	(segment
		(start 298.393612 -101.567488)
		(end 298.365672 -101.567488)
		(width 0.0889)
		(layer "In2.Cu")
		(net "P3E_CPU0_PE1_PCH_RXP<15>")
	)
	(segment
		(start 326.758554 -123.997974)
		(end 326.131936 -123.1392)
		(width 0.1143)
		(layer "In2.Cu")
		(net "P3E_CPU0_PE1_PCH_RXP<15>")
	)
	(segment
		(start 296.674032 -100.576888)
		(end 296.64025 -100.576888)
		(width 0.0889)
		(layer "In2.Cu")
		(net "P3E_CPU0_PE1_PCH_RXP<15>")
	)
	(segment
		(start 350.659192 -126.162816)
		(end 347.815154 -124.408184)
		(width 0.1143)
		(layer "In2.Cu")
		(net "P3E_CPU0_PE1_PCH_RXP<15>")
	)
	(segment
		(start 301.83455 -102.558088)
		(end 301.55515 -102.558088)
		(width 0.0889)
		(layer "In2.Cu")
		(net "P3E_CPU0_PE1_PCH_RXP<15>")
	)
	(segment
		(start 296.154856 -99.299522)
		(end 296.15003 -99.290886)
		(width 0.0889)
		(layer "In2.Cu")
		(net "P3E_CPU0_PE1_PCH_RXP<15>")
	)
	(segment
		(start 351.343214 -126.64313)
		(end 351.344992 -126.278132)
		(width 0.1143)
		(layer "In2.Cu")
		(net "P3E_CPU0_PE1_PCH_RXP<15>")
	)
	(segment
		(start 307.258466 -103.29545)
		(end 306.272692 -103.29545)
		(width 0.1143)
		(layer "In2.Cu")
		(net "P3E_CPU0_PE1_PCH_RXP<15>")
	)
	(segment
		(start 295.431464 -98.648012)
		(end 295.510204 -98.669348)
		(width 0.0889)
		(layer "In2.Cu")
		(net "P3E_CPU0_PE1_PCH_RXP<15>")
	)
	(segment
		(start 302.57115 -102.558088)
		(end 302.29175 -102.558088)
		(width 0.0889)
		(layer "In2.Cu")
		(net "P3E_CPU0_PE1_PCH_RXP<15>")
	)
	(segment
		(start 301.09795 -102.558088)
		(end 300.81855 -102.558088)
		(width 0.0889)
		(layer "In2.Cu")
		(net "P3E_CPU0_PE1_PCH_RXP<15>")
	)
	(segment
		(start 300.72965 -102.646988)
		(end 300.45025 -102.646988)
		(width 0.0889)
		(layer "In2.Cu")
		(net "P3E_CPU0_PE1_PCH_RXP<15>")
	)
	(segment
		(start 296.15003 -99.290886)
		(end 296.14368 -99.280218)
		(width 0.0889)
		(layer "In2.Cu")
		(net "P3E_CPU0_PE1_PCH_RXP<15>")
	)
	(segment
		(start 342.62568 -124.678694)
		(end 339.156548 -123.996196)
		(width 0.1143)
		(layer "In2.Cu")
		(net "P3E_CPU0_PE1_PCH_RXP<15>")
	)
	(segment
		(start 319.839086 -112.296956)
		(end 307.258466 -103.29545)
		(width 0.1143)
		(layer "In2.Cu")
		(net "P3E_CPU0_PE1_PCH_RXP<15>")
	)
	(segment
		(start 345.5162 -124.562616)
		(end 344.138758 -124.36221)
		(width 0.1143)
		(layer "In2.Cu")
		(net "P3E_CPU0_PE1_PCH_RXP<15>")
	)
	(segment
		(start 301.55515 -102.558088)
		(end 301.46625 -102.646988)
		(width 0.0889)
		(layer "In2.Cu")
		(net "P3E_CPU0_PE1_PCH_RXP<15>")
	)
	(segment
		(start 304.714402 -102.653846)
		(end 304.483262 -102.558088)
		(width 0.0889)
		(layer "In2.Cu")
		(net "P3E_CPU0_PE1_PCH_RXP<15>")
	)
	(segment
		(start 301.18685 -102.646988)
		(end 301.09795 -102.558088)
		(width 0.0889)
		(layer "In2.Cu")
		(net "P3E_CPU0_PE1_PCH_RXP<15>")
	)
	(segment
		(start 300.36135 -102.558088)
		(end 300.08195 -102.558088)
		(width 0.0889)
		(layer "In2.Cu")
		(net "P3E_CPU0_PE1_PCH_RXP<15>")
	)
	(segment
		(start 297.53814 -101.072188)
		(end 297.502326 -101.072188)
		(width 0.0889)
		(layer "In2.Cu")
		(net "P3E_CPU0_PE1_PCH_RXP<15>")
	)
	(segment
		(start 346.822776 -124.591064)
		(end 346.152724 -124.42063)
		(width 0.1143)
		(layer "In2.Cu")
		(net "P3E_CPU0_PE1_PCH_RXP<15>")
	)
	(segment
		(start 299.248322 -102.062534)
		(end 299.215556 -102.062534)
		(width 0.0889)
		(layer "In2.Cu")
		(net "P3E_CPU0_PE1_PCH_RXP<15>")
	)
	(segment
		(start 305.305206 -103.24465)
		(end 304.714402 -102.653846)
		(width 0.0889)
		(layer "In2.Cu")
		(net "P3E_CPU0_PE1_PCH_RXP<15>")
	)
	(segment
		(start 344.138758 -124.36221)
		(end 342.62568 -124.678694)
		(width 0.1143)
		(layer "In2.Cu")
		(net "P3E_CPU0_PE1_PCH_RXP<15>")
	)
	(segment
		(start 302.20285 -102.646988)
		(end 301.92345 -102.646988)
		(width 0.0889)
		(layer "In2.Cu")
		(net "P3E_CPU0_PE1_PCH_RXP<15>")
	)
	(segment
		(start 304.483262 -102.558088)
		(end 303.73955 -102.558088)
		(width 0.0889)
		(layer "In2.Cu")
		(net "P3E_CPU0_PE1_PCH_RXP<15>")
	)
	(segment
		(start 301.46625 -102.646988)
		(end 301.18685 -102.646988)
		(width 0.0889)
		(layer "In2.Cu")
		(net "P3E_CPU0_PE1_PCH_RXP<15>")
	)
	(segment
		(start 303.65065 -102.646988)
		(end 303.38395 -102.646988)
		(width 0.0889)
		(layer "In2.Cu")
		(net "P3E_CPU0_PE1_PCH_RXP<15>")
	)
	(segment
		(start 323.761354 -117.901466)
		(end 319.839086 -112.296956)
		(width 0.1143)
		(layer "In2.Cu")
		(net "P3E_CPU0_PE1_PCH_RXP<15>")
	)
	(segment
		(start 295.510204 -98.669348)
		(end 295.80332 -98.500184)
		(width 0.0889)
		(layer "In2.Cu")
		(net "P3E_CPU0_PE1_PCH_RXP<15>")
	)
	(segment
		(start 303.73955 -102.558088)
		(end 303.65065 -102.646988)
		(width 0.0889)
		(layer "In2.Cu")
		(net "P3E_CPU0_PE1_PCH_RXP<15>")
	)
	(segment
		(start 296.154856 -98.308922)
		(end 296.15003 -98.300286)
		(width 0.0889)
		(layer "In2.Cu")
		(net "P3E_CPU0_PE1_PCH_RXP<15>")
	)
	(segment
		(start 346.152724 -124.42063)
		(end 345.5162 -124.562616)
		(width 0.1143)
		(layer "In2.Cu")
		(net "P3E_CPU0_PE1_PCH_RXP<15>")
	)
	(segment
		(start 295.814496 -98.100134)
		(end 295.792144 -98.100134)
		(width 0.0889)
		(layer "In2.Cu")
		(net "P3E_CPU0_PE1_PCH_RXP<15>")
	)
	(segment
		(start 302.66005 -102.646988)
		(end 302.57115 -102.558088)
		(width 0.0889)
		(layer "In2.Cu")
		(net "P3E_CPU0_PE1_PCH_RXP<15>")
	)
	(segment
		(start 302.93945 -102.646988)
		(end 302.66005 -102.646988)
		(width 0.0889)
		(layer "In2.Cu")
		(net "P3E_CPU0_PE1_PCH_RXP<15>")
	)
	(segment
		(start 332.241144 -125.465332)
		(end 326.758554 -123.997974)
		(width 0.1143)
		(layer "In2.Cu")
		(net "P3E_CPU0_PE1_PCH_RXP<15>")
	)
	(segment
		(start 306.272692 -103.29545)
		(end 306.250594 -103.29545)
		(width 0.0889)
		(layer "In2.Cu")
		(net "P3E_CPU0_PE1_PCH_RXP<15>")
	)
	(segment
		(start 306.199794 -103.24465)
		(end 305.305206 -103.24465)
		(width 0.0889)
		(layer "In2.Cu")
		(net "P3E_CPU0_PE1_PCH_RXP<15>")
	)
	(segment
		(start 300.81855 -102.558088)
		(end 300.72965 -102.646988)
		(width 0.0889)
		(layer "In2.Cu")
		(net "P3E_CPU0_PE1_PCH_RXP<15>")
	)
	(segment
		(start 303.38395 -102.646988)
		(end 303.29505 -102.558088)
		(width 0.0889)
		(layer "In2.Cu")
		(net "P3E_CPU0_PE1_PCH_RXP<15>")
	)
	(segment
		(start 295.45661 -98.300286)
		(end 295.451784 -98.308922)
		(width 0.0889)
		(layer "In2.Cu")
		(net "P3E_CPU0_PE1_PCH_RXP<15>")
	)
	(segment
		(start 351.344992 -126.278132)
		(end 351.229676 -126.162816)
		(width 0.1143)
		(layer "In2.Cu")
		(net "P3E_CPU0_PE1_PCH_RXP<15>")
	)
	(segment
		(start 300.45025 -102.646988)
		(end 300.36135 -102.558088)
		(width 0.0889)
		(layer "In2.Cu")
		(net "P3E_CPU0_PE1_PCH_RXP<15>")
	)
	(segment
		(start 351.229676 -126.162816)
		(end 350.659192 -126.162816)
		(width 0.1143)
		(layer "In2.Cu")
		(net "P3E_CPU0_PE1_PCH_RXP<15>")
	)
	(segment
		(start 306.250594 -103.29545)
		(end 306.199794 -103.24465)
		(width 0.0889)
		(layer "In2.Cu")
		(net "P3E_CPU0_PE1_PCH_RXP<15>")
	)
	(segment
		(start 326.131936 -123.1392)
		(end 324.892924 -119.60733)
		(width 0.1143)
		(layer "In2.Cu")
		(net "P3E_CPU0_PE1_PCH_RXP<15>")
	)
	(arc
		(start 295.792144 -98.100134)
		(mid 295.598294 -98.156484)
		(end 295.45661 -98.300286)
		(width 0.0889)
		(layer "In2.Cu")
		(net "P3E_CPU0_PE1_PCH_RXP<15>")
	)
	(arc
		(start 299.215556 -102.062534)
		(mid 298.932339 -101.978253)
		(end 298.725336 -101.767386)
		(width 0.0889)
		(layer "In2.Cu")
		(net "P3E_CPU0_PE1_PCH_RXP<15>")
	)
	(arc
		(start 295.451784 -98.308922)
		(mid 295.403871 -98.476207)
		(end 295.431464 -98.648012)
		(width 0.0889)
		(layer "In2.Cu")
		(net "P3E_CPU0_PE1_PCH_RXP<15>")
	)
	(arc
		(start 296.64025 -100.576888)
		(mid 296.144773 -100.272445)
		(end 296.15003 -99.690936)
		(width 0.0889)
		(layer "In2.Cu")
		(net "P3E_CPU0_PE1_PCH_RXP<15>")
	)
	(arc
		(start 296.15003 -98.700336)
		(mid 296.2035 -98.505273)
		(end 296.154856 -98.308922)
		(width 0.0889)
		(layer "In2.Cu")
		(net "P3E_CPU0_PE1_PCH_RXP<15>")
	)
	(arc
		(start 299.583856 -102.262686)
		(mid 299.442173 -102.118882)
		(end 299.248322 -102.062534)
		(width 0.0889)
		(layer "In2.Cu")
		(net "P3E_CPU0_PE1_PCH_RXP<15>")
	)
	(arc
		(start 297.866816 -101.272086)
		(mid 297.728072 -101.130053)
		(end 297.53814 -101.072188)
		(width 0.0889)
		(layer "In2.Cu")
		(net "P3E_CPU0_PE1_PCH_RXP<15>")
	)
	(arc
		(start 296.15003 -99.690936)
		(mid 296.2035 -99.495873)
		(end 296.154856 -99.299522)
		(width 0.0889)
		(layer "In2.Cu")
		(net "P3E_CPU0_PE1_PCH_RXP<15>")
	)
	(arc
		(start 298.725336 -101.767386)
		(mid 298.585257 -101.62465)
		(end 298.393612 -101.567488)
		(width 0.0889)
		(layer "In2.Cu")
		(net "P3E_CPU0_PE1_PCH_RXP<15>")
	)
	(arc
		(start 298.365672 -101.567488)
		(mid 298.077527 -101.485169)
		(end 297.866816 -101.272086)
		(width 0.0889)
		(layer "In2.Cu")
		(net "P3E_CPU0_PE1_PCH_RXP<15>")
	)
	(arc
		(start 297.502326 -101.072188)
		(mid 297.216902 -100.988721)
		(end 297.008296 -100.776786)
		(width 0.0889)
		(layer "In2.Cu")
		(net "P3E_CPU0_PE1_PCH_RXP<15>")
	)
	(arc
		(start 297.008296 -100.776786)
		(mid 296.867139 -100.633401)
		(end 296.674032 -100.576888)
		(width 0.0889)
		(layer "In2.Cu")
		(net "P3E_CPU0_PE1_PCH_RXP<15>")
	)
	(arc
		(start 300.08195 -102.558088)
		(mid 299.794263 -102.475567)
		(end 299.583856 -102.262686)
		(width 0.0889)
		(layer "In2.Cu")
		(net "P3E_CPU0_PE1_PCH_RXP<15>")
	)
	(arc
		(start 296.15003 -98.300286)
		(mid 296.008347 -98.156482)
		(end 295.814496 -98.100134)
		(width 0.0889)
		(layer "In2.Cu")
		(net "P3E_CPU0_PE1_PCH_RXP<15>")
	)
	(arc
		(start 296.14368 -99.280218)
		(mid 296.070882 -98.989455)
		(end 296.15003 -98.700336)
		(width 0.0889)
		(layer "In2.Cu")
		(net "P3E_CPU0_PE1_PCH_RXP<15>")
	)
	(segment
		(start 295.23182 -99.490784)
		(end 295.80332 -99.490784)
		(width 0.1143)
		(layer "F.Cu")
		(net "P3E_CPU0_PE1_PCH_RXP<14>")
	)
	(via
		(at 295.80332 -99.490784)
		(size 0.508)
		(drill 0.254)
		(layers "F.Cu" "B.Cu")
		(net "P3E_CPU0_PE1_PCH_RXP<14>")
	)
	(via
		(at 346.17152 -126.379224)
		(size 0.508)
		(drill 0.254)
		(layers "F.Cu" "B.Cu")
		(net "P3E_CPU0_PE1_PCH_RXP<14>")
	)
	(segment
		(start 349.133414 -126.009146)
		(end 349.01886 -125.894592)
		(width 0.1143)
		(layer "B.Cu")
		(net "P3E_CPU0_PE1_PCH_RXP<14>")
	)
	(segment
		(start 346.656152 -125.894592)
		(end 346.17152 -126.379224)
		(width 0.1143)
		(layer "B.Cu")
		(net "P3E_CPU0_PE1_PCH_RXP<14>")
	)
	(segment
		(start 349.133414 -126.345442)
		(end 349.133414 -126.009146)
		(width 0.1143)
		(layer "B.Cu")
		(net "P3E_CPU0_PE1_PCH_RXP<14>")
	)
	(segment
		(start 349.01886 -125.894592)
		(end 346.656152 -125.894592)
		(width 0.1143)
		(layer "B.Cu")
		(net "P3E_CPU0_PE1_PCH_RXP<14>")
	)
	(segment
		(start 345.44381 -125.602238)
		(end 346.17152 -126.329948)
		(width 0.1143)
		(layer "In2.Cu")
		(net "P3E_CPU0_PE1_PCH_RXP<14>")
	)
	(segment
		(start 303.721008 -104.2797)
		(end 306.851812 -104.2797)
		(width 0.0889)
		(layer "In2.Cu")
		(net "P3E_CPU0_PE1_PCH_RXP<14>")
	)
	(segment
		(start 325.537576 -123.85802)
		(end 326.765158 -125.540262)
		(width 0.1143)
		(layer "In2.Cu")
		(net "P3E_CPU0_PE1_PCH_RXP<14>")
	)
	(segment
		(start 303.125886 -103.684578)
		(end 303.721008 -104.2797)
		(width 0.0889)
		(layer "In2.Cu")
		(net "P3E_CPU0_PE1_PCH_RXP<14>")
	)
	(segment
		(start 295.78554 -101.072188)
		(end 295.821354 -101.072188)
		(width 0.0889)
		(layer "In2.Cu")
		(net "P3E_CPU0_PE1_PCH_RXP<14>")
	)
	(segment
		(start 309.136542 -105.8037)
		(end 309.136796 -105.8037)
		(width 0.0889)
		(layer "In2.Cu")
		(net "P3E_CPU0_PE1_PCH_RXP<14>")
	)
	(segment
		(start 320.061844 -119.167148)
		(end 321.81292 -119.606314)
		(width 0.1143)
		(layer "In2.Cu")
		(net "P3E_CPU0_PE1_PCH_RXP<14>")
	)
	(segment
		(start 297.004994 -101.761798)
		(end 297.008296 -101.76764)
		(width 0.0889)
		(layer "In2.Cu")
		(net "P3E_CPU0_PE1_PCH_RXP<14>")
	)
	(segment
		(start 297.495214 -102.062534)
		(end 297.531282 -102.062534)
		(width 0.0889)
		(layer "In2.Cu")
		(net "P3E_CPU0_PE1_PCH_RXP<14>")
	)
	(segment
		(start 299.247306 -103.053388)
		(end 299.24756 -103.053642)
		(width 0.0889)
		(layer "In2.Cu")
		(net "P3E_CPU0_PE1_PCH_RXP<14>")
	)
	(segment
		(start 323.72935 -119.407178)
		(end 324.188836 -120.013984)
		(width 0.1143)
		(layer "In2.Cu")
		(net "P3E_CPU0_PE1_PCH_RXP<14>")
	)
	(segment
		(start 299.224192 -103.053388)
		(end 299.247306 -103.053388)
		(width 0.0889)
		(layer "In2.Cu")
		(net "P3E_CPU0_PE1_PCH_RXP<14>")
	)
	(segment
		(start 309.150766 -105.874566)
		(end 309.169054 -105.886758)
		(width 0.0889)
		(layer "In2.Cu")
		(net "P3E_CPU0_PE1_PCH_RXP<14>")
	)
	(segment
		(start 309.136796 -105.8037)
		(end 309.150766 -105.874566)
		(width 0.0889)
		(layer "In2.Cu")
		(net "P3E_CPU0_PE1_PCH_RXP<14>")
	)
	(segment
		(start 342.509856 -125.535944)
		(end 344.068146 -125.209808)
		(width 0.1143)
		(layer "In2.Cu")
		(net "P3E_CPU0_PE1_PCH_RXP<14>")
	)
	(segment
		(start 299.583602 -103.253286)
		(end 299.619162 -103.315262)
		(width 0.0889)
		(layer "In2.Cu")
		(net "P3E_CPU0_PE1_PCH_RXP<14>")
	)
	(segment
		(start 309.169054 -105.886758)
		(end 317.000128 -111.121952)
		(width 0.1143)
		(layer "In2.Cu")
		(net "P3E_CPU0_PE1_PCH_RXP<14>")
	)
	(segment
		(start 301.895256 -103.174546)
		(end 303.125886 -103.684578)
		(width 0.0889)
		(layer "In2.Cu")
		(net "P3E_CPU0_PE1_PCH_RXP<14>")
	)
	(segment
		(start 318.670432 -117.163596)
		(end 320.061844 -119.167148)
		(width 0.1143)
		(layer "In2.Cu")
		(net "P3E_CPU0_PE1_PCH_RXP<14>")
	)
	(segment
		(start 298.360846 -102.558088)
		(end 298.393612 -102.558088)
		(width 0.0889)
		(layer "In2.Cu")
		(net "P3E_CPU0_PE1_PCH_RXP<14>")
	)
	(segment
		(start 330.398374 -126.51232)
		(end 338.59724 -124.770642)
		(width 0.1143)
		(layer "In2.Cu")
		(net "P3E_CPU0_PE1_PCH_RXP<14>")
	)
	(segment
		(start 324.188836 -120.013984)
		(end 325.537576 -123.85802)
		(width 0.1143)
		(layer "In2.Cu")
		(net "P3E_CPU0_PE1_PCH_RXP<14>")
	)
	(segment
		(start 317.000128 -111.121952)
		(end 318.670432 -117.163596)
		(width 0.1143)
		(layer "In2.Cu")
		(net "P3E_CPU0_PE1_PCH_RXP<14>")
	)
	(segment
		(start 338.59724 -124.770642)
		(end 342.509856 -125.535944)
		(width 0.1143)
		(layer "In2.Cu")
		(net "P3E_CPU0_PE1_PCH_RXP<14>")
	)
	(segment
		(start 321.81292 -119.606314)
		(end 322.74129 -119.130064)
		(width 0.1143)
		(layer "In2.Cu")
		(net "P3E_CPU0_PE1_PCH_RXP<14>")
	)
	(segment
		(start 299.930058 -103.625904)
		(end 300.60519 -103.625904)
		(width 0.0889)
		(layer "In2.Cu")
		(net "P3E_CPU0_PE1_PCH_RXP<14>")
	)
	(segment
		(start 326.765158 -125.540262)
		(end 330.398374 -126.51232)
		(width 0.1143)
		(layer "In2.Cu")
		(net "P3E_CPU0_PE1_PCH_RXP<14>")
	)
	(segment
		(start 322.74129 -119.130064)
		(end 323.72935 -119.407178)
		(width 0.1143)
		(layer "In2.Cu")
		(net "P3E_CPU0_PE1_PCH_RXP<14>")
	)
	(segment
		(start 306.851812 -104.2797)
		(end 309.136542 -105.8037)
		(width 0.0889)
		(layer "In2.Cu")
		(net "P3E_CPU0_PE1_PCH_RXP<14>")
	)
	(segment
		(start 299.619162 -103.315262)
		(end 299.930058 -103.625904)
		(width 0.0889)
		(layer "In2.Cu")
		(net "P3E_CPU0_PE1_PCH_RXP<14>")
	)
	(segment
		(start 300.60519 -103.625904)
		(end 301.056548 -103.174546)
		(width 0.0889)
		(layer "In2.Cu")
		(net "P3E_CPU0_PE1_PCH_RXP<14>")
	)
	(segment
		(start 296.64406 -101.567488)
		(end 296.66184 -101.567488)
		(width 0.0889)
		(layer "In2.Cu")
		(net "P3E_CPU0_PE1_PCH_RXP<14>")
	)
	(segment
		(start 301.056548 -103.174546)
		(end 301.895256 -103.174546)
		(width 0.0889)
		(layer "In2.Cu")
		(net "P3E_CPU0_PE1_PCH_RXP<14>")
	)
	(segment
		(start 346.17152 -126.329948)
		(end 346.17152 -126.379224)
		(width 0.1143)
		(layer "In2.Cu")
		(net "P3E_CPU0_PE1_PCH_RXP<14>")
	)
	(segment
		(start 344.068146 -125.209808)
		(end 345.44381 -125.602238)
		(width 0.1143)
		(layer "In2.Cu")
		(net "P3E_CPU0_PE1_PCH_RXP<14>")
	)
	(arc
		(start 297.531282 -102.062534)
		(mid 297.725132 -102.118884)
		(end 297.866816 -102.262686)
		(width 0.0889)
		(layer "In2.Cu")
		(net "P3E_CPU0_PE1_PCH_RXP<14>")
	)
	(arc
		(start 295.29151 -100.186236)
		(mid 295.212288 -100.475354)
		(end 295.28516 -100.766118)
		(width 0.0889)
		(layer "In2.Cu")
		(net "P3E_CPU0_PE1_PCH_RXP<14>")
	)
	(arc
		(start 297.866816 -102.262686)
		(mid 298.075424 -102.474618)
		(end 298.360846 -102.558088)
		(width 0.0889)
		(layer "In2.Cu")
		(net "P3E_CPU0_PE1_PCH_RXP<14>")
	)
	(arc
		(start 295.821354 -101.072188)
		(mid 296.011283 -101.130058)
		(end 296.15003 -101.272086)
		(width 0.0889)
		(layer "In2.Cu")
		(net "P3E_CPU0_PE1_PCH_RXP<14>")
	)
	(arc
		(start 298.393612 -102.558088)
		(mid 298.585254 -102.615254)
		(end 298.725336 -102.757986)
		(width 0.0889)
		(layer "In2.Cu")
		(net "P3E_CPU0_PE1_PCH_RXP<14>")
	)
	(arc
		(start 299.24756 -103.053642)
		(mid 299.44159 -103.10967)
		(end 299.583602 -103.253286)
		(width 0.0889)
		(layer "In2.Cu")
		(net "P3E_CPU0_PE1_PCH_RXP<14>")
	)
	(arc
		(start 295.28516 -100.766118)
		(mid 295.494675 -100.985672)
		(end 295.78554 -101.072188)
		(width 0.0889)
		(layer "In2.Cu")
		(net "P3E_CPU0_PE1_PCH_RXP<14>")
	)
	(arc
		(start 298.725336 -102.757986)
		(mid 298.936049 -102.971065)
		(end 299.224192 -103.053388)
		(width 0.0889)
		(layer "In2.Cu")
		(net "P3E_CPU0_PE1_PCH_RXP<14>")
	)
	(arc
		(start 296.15003 -101.272086)
		(mid 296.358638 -101.484018)
		(end 296.64406 -101.567488)
		(width 0.0889)
		(layer "In2.Cu")
		(net "P3E_CPU0_PE1_PCH_RXP<14>")
	)
	(arc
		(start 295.80332 -99.490784)
		(mid 295.528156 -99.824338)
		(end 295.29151 -100.186236)
		(width 0.0889)
		(layer "In2.Cu")
		(net "P3E_CPU0_PE1_PCH_RXP<14>")
	)
	(arc
		(start 296.66184 -101.567488)
		(mid 296.859001 -101.619447)
		(end 297.004994 -101.761798)
		(width 0.0889)
		(layer "In2.Cu")
		(net "P3E_CPU0_PE1_PCH_RXP<14>")
	)
	(arc
		(start 297.008296 -101.76764)
		(mid 297.213917 -101.977563)
		(end 297.495214 -102.062534)
		(width 0.0889)
		(layer "In2.Cu")
		(net "P3E_CPU0_PE1_PCH_RXP<14>")
	)
	(segment
		(start 296.948606 -100.481638)
		(end 297.519852 -100.481638)
		(width 0.1143)
		(layer "F.Cu")
		(net "P3E_CPU0_PE1_PCH_RXP<13>")
	)
	(segment
		(start 297.519852 -100.481638)
		(end 297.520106 -100.481384)
		(width 0.1143)
		(layer "F.Cu")
		(net "P3E_CPU0_PE1_PCH_RXP<13>")
	)
	(via
		(at 297.520106 -100.481384)
		(size 0.508)
		(drill 0.254)
		(layers "F.Cu" "B.Cu")
		(net "P3E_CPU0_PE1_PCH_RXP<13>")
	)
	(via
		(at 345.628214 -123.576842)
		(size 0.508)
		(drill 0.254)
		(layers "F.Cu" "B.Cu")
		(net "P3E_CPU0_PE1_PCH_RXP<13>")
	)
	(segment
		(start 345.628214 -123.576842)
		(end 346.079064 -123.125992)
		(width 0.1143)
		(layer "B.Cu")
		(net "P3E_CPU0_PE1_PCH_RXP<13>")
	)
	(segment
		(start 348.46006 -123.125992)
		(end 348.574614 -123.240546)
		(width 0.1143)
		(layer "B.Cu")
		(net "P3E_CPU0_PE1_PCH_RXP<13>")
	)
	(segment
		(start 346.079064 -123.125992)
		(end 348.46006 -123.125992)
		(width 0.1143)
		(layer "B.Cu")
		(net "P3E_CPU0_PE1_PCH_RXP<13>")
	)
	(segment
		(start 348.574614 -123.240546)
		(end 348.574614 -123.576842)
		(width 0.1143)
		(layer "B.Cu")
		(net "P3E_CPU0_PE1_PCH_RXP<13>")
	)
	(segment
		(start 302.46955 -101.74986)
		(end 302.38065 -101.83876)
		(width 0.0889)
		(layer "In2.Cu")
		(net "P3E_CPU0_PE1_PCH_RXP<13>")
	)
	(segment
		(start 301.420022 -102.062788)
		(end 300.941232 -102.062788)
		(width 0.0889)
		(layer "In2.Cu")
		(net "P3E_CPU0_PE1_PCH_RXP<13>")
	)
	(segment
		(start 345.628214 -123.221242)
		(end 345.513914 -123.106942)
		(width 0.1143)
		(layer "In2.Cu")
		(net "P3E_CPU0_PE1_PCH_RXP<13>")
	)
	(segment
		(start 332.471776 -124.765308)
		(end 327.31329 -123.38431)
		(width 0.1143)
		(layer "In2.Cu")
		(net "P3E_CPU0_PE1_PCH_RXP<13>")
	)
	(segment
		(start 345.513914 -123.106942)
		(end 345.315286 -123.106942)
		(width 0.1143)
		(layer "In2.Cu")
		(net "P3E_CPU0_PE1_PCH_RXP<13>")
	)
	(segment
		(start 302.38065 -101.83876)
		(end 302.10125 -101.83876)
		(width 0.0889)
		(layer "In2.Cu")
		(net "P3E_CPU0_PE1_PCH_RXP<13>")
	)
	(segment
		(start 307.232558 -102.086664)
		(end 306.001928 -102.086664)
		(width 0.1143)
		(layer "In2.Cu")
		(net "P3E_CPU0_PE1_PCH_RXP<13>")
	)
	(segment
		(start 306.001928 -102.086664)
		(end 305.97983 -102.086664)
		(width 0.0889)
		(layer "In2.Cu")
		(net "P3E_CPU0_PE1_PCH_RXP<13>")
	)
	(segment
		(start 298.39666 -100.576888)
		(end 298.360846 -100.576888)
		(width 0.0889)
		(layer "In2.Cu")
		(net "P3E_CPU0_PE1_PCH_RXP<13>")
	)
	(segment
		(start 297.227244 -100.312474)
		(end 297.520106 -100.481384)
		(width 0.0889)
		(layer "In2.Cu")
		(net "P3E_CPU0_PE1_PCH_RXP<13>")
	)
	(segment
		(start 305.92903 -102.035864)
		(end 305.070256 -102.035864)
		(width 0.0889)
		(layer "In2.Cu")
		(net "P3E_CPU0_PE1_PCH_RXP<13>")
	)
	(segment
		(start 326.806306 -122.68962)
		(end 325.688452 -119.50319)
		(width 0.1143)
		(layer "In2.Cu")
		(net "P3E_CPU0_PE1_PCH_RXP<13>")
	)
	(segment
		(start 302.10125 -101.83876)
		(end 302.01235 -101.74986)
		(width 0.0889)
		(layer "In2.Cu")
		(net "P3E_CPU0_PE1_PCH_RXP<13>")
	)
	(segment
		(start 319.85204 -111.115348)
		(end 307.232558 -102.086664)
		(width 0.1143)
		(layer "In2.Cu")
		(net "P3E_CPU0_PE1_PCH_RXP<13>")
	)
	(segment
		(start 299.248322 -101.071934)
		(end 299.215556 -101.071934)
		(width 0.0889)
		(layer "In2.Cu")
		(net "P3E_CPU0_PE1_PCH_RXP<13>")
	)
	(segment
		(start 302.74895 -101.74986)
		(end 302.46955 -101.74986)
		(width 0.0889)
		(layer "In2.Cu")
		(net "P3E_CPU0_PE1_PCH_RXP<13>")
	)
	(segment
		(start 303.20615 -101.74986)
		(end 303.11725 -101.83876)
		(width 0.0889)
		(layer "In2.Cu")
		(net "P3E_CPU0_PE1_PCH_RXP<13>")
	)
	(segment
		(start 303.11725 -101.83876)
		(end 302.83785 -101.83876)
		(width 0.0889)
		(layer "In2.Cu")
		(net "P3E_CPU0_PE1_PCH_RXP<13>")
	)
	(segment
		(start 342.427052 -123.883928)
		(end 339.438742 -123.28525)
		(width 0.1143)
		(layer "In2.Cu")
		(net "P3E_CPU0_PE1_PCH_RXP<13>")
	)
	(segment
		(start 327.31329 -123.38431)
		(end 326.806306 -122.68962)
		(width 0.1143)
		(layer "In2.Cu")
		(net "P3E_CPU0_PE1_PCH_RXP<13>")
	)
	(segment
		(start 345.315286 -123.106942)
		(end 344.8558 -123.325382)
		(width 0.1143)
		(layer "In2.Cu")
		(net "P3E_CPU0_PE1_PCH_RXP<13>")
	)
	(segment
		(start 302.83785 -101.83876)
		(end 302.74895 -101.74986)
		(width 0.0889)
		(layer "In2.Cu")
		(net "P3E_CPU0_PE1_PCH_RXP<13>")
	)
	(segment
		(start 339.438742 -123.28525)
		(end 332.471776 -124.765308)
		(width 0.1143)
		(layer "In2.Cu")
		(net "P3E_CPU0_PE1_PCH_RXP<13>")
	)
	(segment
		(start 325.688452 -119.50319)
		(end 324.640194 -118.061486)
		(width 0.1143)
		(layer "In2.Cu")
		(net "P3E_CPU0_PE1_PCH_RXP<13>")
	)
	(segment
		(start 345.628214 -123.576842)
		(end 345.628214 -123.221242)
		(width 0.1143)
		(layer "In2.Cu")
		(net "P3E_CPU0_PE1_PCH_RXP<13>")
	)
	(segment
		(start 324.564248 -117.772942)
		(end 319.85204 -111.115348)
		(width 0.1143)
		(layer "In2.Cu")
		(net "P3E_CPU0_PE1_PCH_RXP<13>")
	)
	(segment
		(start 305.070256 -102.035864)
		(end 304.784252 -101.74986)
		(width 0.0889)
		(layer "In2.Cu")
		(net "P3E_CPU0_PE1_PCH_RXP<13>")
	)
	(segment
		(start 301.73295 -101.74986)
		(end 301.420022 -102.062788)
		(width 0.0889)
		(layer "In2.Cu")
		(net "P3E_CPU0_PE1_PCH_RXP<13>")
	)
	(segment
		(start 302.01235 -101.74986)
		(end 301.73295 -101.74986)
		(width 0.0889)
		(layer "In2.Cu")
		(net "P3E_CPU0_PE1_PCH_RXP<13>")
	)
	(segment
		(start 304.784252 -101.74986)
		(end 303.20615 -101.74986)
		(width 0.0889)
		(layer "In2.Cu")
		(net "P3E_CPU0_PE1_PCH_RXP<13>")
	)
	(segment
		(start 344.8558 -123.325382)
		(end 342.427052 -123.883928)
		(width 0.1143)
		(layer "In2.Cu")
		(net "P3E_CPU0_PE1_PCH_RXP<13>")
	)
	(segment
		(start 300.110652 -101.567488)
		(end 300.082712 -101.567488)
		(width 0.0889)
		(layer "In2.Cu")
		(net "P3E_CPU0_PE1_PCH_RXP<13>")
	)
	(segment
		(start 324.640194 -118.061486)
		(end 324.564248 -117.772942)
		(width 0.1143)
		(layer "In2.Cu")
		(net "P3E_CPU0_PE1_PCH_RXP<13>")
	)
	(segment
		(start 305.97983 -102.086664)
		(end 305.92903 -102.035864)
		(width 0.0889)
		(layer "In2.Cu")
		(net "P3E_CPU0_PE1_PCH_RXP<13>")
	)
	(segment
		(start 297.206162 -100.233734)
		(end 297.227244 -100.312474)
		(width 0.0889)
		(layer "In2.Cu")
		(net "P3E_CPU0_PE1_PCH_RXP<13>")
	)
	(arc
		(start 299.583856 -101.272086)
		(mid 299.442173 -101.128282)
		(end 299.248322 -101.071934)
		(width 0.0889)
		(layer "In2.Cu")
		(net "P3E_CPU0_PE1_PCH_RXP<13>")
	)
	(arc
		(start 297.532298 -100.081588)
		(mid 297.520233 -100.08141)
		(end 297.508168 -100.081588)
		(width 0.0889)
		(layer "In2.Cu")
		(net "P3E_CPU0_PE1_PCH_RXP<13>")
	)
	(arc
		(start 300.442376 -101.767386)
		(mid 300.302297 -101.62465)
		(end 300.110652 -101.567488)
		(width 0.0889)
		(layer "In2.Cu")
		(net "P3E_CPU0_PE1_PCH_RXP<13>")
	)
	(arc
		(start 298.725336 -100.776786)
		(mid 298.586592 -100.634753)
		(end 298.39666 -100.576888)
		(width 0.0889)
		(layer "In2.Cu")
		(net "P3E_CPU0_PE1_PCH_RXP<13>")
	)
	(arc
		(start 300.941232 -102.062788)
		(mid 300.653087 -101.980469)
		(end 300.442376 -101.767386)
		(width 0.0889)
		(layer "In2.Cu")
		(net "P3E_CPU0_PE1_PCH_RXP<13>")
	)
	(arc
		(start 300.082712 -101.567488)
		(mid 299.794567 -101.485169)
		(end 299.583856 -101.272086)
		(width 0.0889)
		(layer "In2.Cu")
		(net "P3E_CPU0_PE1_PCH_RXP<13>")
	)
	(arc
		(start 299.215556 -101.071934)
		(mid 298.932339 -100.987653)
		(end 298.725336 -100.776786)
		(width 0.0889)
		(layer "In2.Cu")
		(net "P3E_CPU0_PE1_PCH_RXP<13>")
	)
	(arc
		(start 297.508168 -100.081588)
		(mid 297.340324 -100.124211)
		(end 297.206162 -100.233734)
		(width 0.0889)
		(layer "In2.Cu")
		(net "P3E_CPU0_PE1_PCH_RXP<13>")
	)
	(arc
		(start 297.866816 -100.281486)
		(mid 297.72555 -100.138036)
		(end 297.532298 -100.081588)
		(width 0.0889)
		(layer "In2.Cu")
		(net "P3E_CPU0_PE1_PCH_RXP<13>")
	)
	(arc
		(start 298.360846 -100.576888)
		(mid 298.075422 -100.493421)
		(end 297.866816 -100.281486)
		(width 0.0889)
		(layer "In2.Cu")
		(net "P3E_CPU0_PE1_PCH_RXP<13>")
	)
	(segment
		(start 297.807126 -98.995738)
		(end 298.378626 -98.995738)
		(width 0.1143)
		(layer "F.Cu")
		(net "P3E_CPU0_PE1_PCH_RXP<12>")
	)
	(via
		(at 298.378626 -98.995738)
		(size 0.508)
		(drill 0.254)
		(layers "F.Cu" "B.Cu")
		(net "P3E_CPU0_PE1_PCH_RXP<12>")
	)
	(via
		(at 350.784414 -122.57405)
		(size 0.508)
		(drill 0.254)
		(layers "F.Cu" "B.Cu")
		(net "P3E_CPU0_PE1_PCH_RXP<12>")
	)
	(segment
		(start 351.304606 -123.094242)
		(end 353.464622 -123.094242)
		(width 0.1143)
		(layer "B.Cu")
		(net "P3E_CPU0_PE1_PCH_RXP<12>")
	)
	(segment
		(start 350.784414 -122.57405)
		(end 351.304606 -123.094242)
		(width 0.1143)
		(layer "B.Cu")
		(net "P3E_CPU0_PE1_PCH_RXP<12>")
	)
	(segment
		(start 353.654614 -122.90425)
		(end 353.654614 -122.662442)
		(width 0.1143)
		(layer "B.Cu")
		(net "P3E_CPU0_PE1_PCH_RXP<12>")
	)
	(segment
		(start 353.464622 -123.094242)
		(end 353.654614 -122.90425)
		(width 0.1143)
		(layer "B.Cu")
		(net "P3E_CPU0_PE1_PCH_RXP<12>")
	)
	(segment
		(start 299.22216 -99.890834)
		(end 299.2501 -99.890834)
		(width 0.0889)
		(layer "In2.Cu")
		(net "P3E_CPU0_PE1_PCH_RXP<12>")
	)
	(segment
		(start 306.072286 -100.881434)
		(end 306.123086 -100.830634)
		(width 0.0889)
		(layer "In2.Cu")
		(net "P3E_CPU0_PE1_PCH_RXP<12>")
	)
	(segment
		(start 301.558452 -100.792534)
		(end 301.647352 -100.881434)
		(width 0.0889)
		(layer "In2.Cu")
		(net "P3E_CPU0_PE1_PCH_RXP<12>")
	)
	(segment
		(start 325.455788 -116.67236)
		(end 325.650606 -116.801392)
		(width 0.1143)
		(layer "In2.Cu")
		(net "P3E_CPU0_PE1_PCH_RXP<12>")
	)
	(segment
		(start 320.431668 -110.217712)
		(end 324.046342 -112.61217)
		(width 0.1143)
		(layer "In2.Cu")
		(net "P3E_CPU0_PE1_PCH_RXP<12>")
	)
	(segment
		(start 324.046342 -112.61217)
		(end 324.888606 -113.88471)
		(width 0.1143)
		(layer "In2.Cu")
		(net "P3E_CPU0_PE1_PCH_RXP<12>")
	)
	(segment
		(start 304.476658 -100.371148)
		(end 304.986944 -100.881434)
		(width 0.0889)
		(layer "In2.Cu")
		(net "P3E_CPU0_PE1_PCH_RXP<12>")
	)
	(segment
		(start 331.387196 -122.612658)
		(end 331.592428 -122.501152)
		(width 0.1143)
		(layer "In2.Cu")
		(net "P3E_CPU0_PE1_PCH_RXP<12>")
	)
	(segment
		(start 331.592428 -122.501152)
		(end 331.921104 -122.598688)
		(width 0.1143)
		(layer "In2.Cu")
		(net "P3E_CPU0_PE1_PCH_RXP<12>")
	)
	(segment
		(start 302.422306 -100.881434)
		(end 302.511206 -100.792534)
		(width 0.0889)
		(layer "In2.Cu")
		(net "P3E_CPU0_PE1_PCH_RXP<12>")
	)
	(segment
		(start 350.525588 -122.832876)
		(end 350.784414 -122.57405)
		(width 0.1143)
		(layer "In2.Cu")
		(net "P3E_CPU0_PE1_PCH_RXP<12>")
	)
	(segment
		(start 301.291752 -100.792534)
		(end 301.558452 -100.792534)
		(width 0.0889)
		(layer "In2.Cu")
		(net "P3E_CPU0_PE1_PCH_RXP<12>")
	)
	(segment
		(start 330.947014 -122.30989)
		(end 331.05852 -122.515122)
		(width 0.1143)
		(layer "In2.Cu")
		(net "P3E_CPU0_PE1_PCH_RXP<12>")
	)
	(segment
		(start 301.647352 -100.881434)
		(end 302.422306 -100.881434)
		(width 0.0889)
		(layer "In2.Cu")
		(net "P3E_CPU0_PE1_PCH_RXP<12>")
	)
	(segment
		(start 304.986944 -100.881434)
		(end 306.072286 -100.881434)
		(width 0.0889)
		(layer "In2.Cu")
		(net "P3E_CPU0_PE1_PCH_RXP<12>")
	)
	(segment
		(start 347.642688 -121.595896)
		(end 349.540576 -122.832876)
		(width 0.1143)
		(layer "In2.Cu")
		(net "P3E_CPU0_PE1_PCH_RXP<12>")
	)
	(segment
		(start 298.08551 -99.164648)
		(end 298.064428 -99.243388)
		(width 0.0889)
		(layer "In2.Cu")
		(net "P3E_CPU0_PE1_PCH_RXP<12>")
	)
	(segment
		(start 303.669192 -100.371148)
		(end 304.476658 -100.371148)
		(width 0.0889)
		(layer "In2.Cu")
		(net "P3E_CPU0_PE1_PCH_RXP<12>")
	)
	(segment
		(start 302.511206 -100.792534)
		(end 302.790606 -100.792534)
		(width 0.0889)
		(layer "In2.Cu")
		(net "P3E_CPU0_PE1_PCH_RXP<12>")
	)
	(segment
		(start 302.879506 -100.881434)
		(end 303.158906 -100.881434)
		(width 0.0889)
		(layer "In2.Cu")
		(net "P3E_CPU0_PE1_PCH_RXP<12>")
	)
	(segment
		(start 307.30698 -100.830634)
		(end 320.428112 -110.21822)
		(width 0.1143)
		(layer "In2.Cu")
		(net "P3E_CPU0_PE1_PCH_RXP<12>")
	)
	(segment
		(start 303.158906 -100.881434)
		(end 303.669192 -100.371148)
		(width 0.0889)
		(layer "In2.Cu")
		(net "P3E_CPU0_PE1_PCH_RXP<12>")
	)
	(segment
		(start 343.752932 -122.439938)
		(end 345.224862 -121.458736)
		(width 0.1143)
		(layer "In2.Cu")
		(net "P3E_CPU0_PE1_PCH_RXP<12>")
	)
	(segment
		(start 346.604082 -121.182892)
		(end 347.642688 -121.595896)
		(width 0.1143)
		(layer "In2.Cu")
		(net "P3E_CPU0_PE1_PCH_RXP<12>")
	)
	(segment
		(start 330.618338 -122.212354)
		(end 330.947014 -122.30989)
		(width 0.1143)
		(layer "In2.Cu")
		(net "P3E_CPU0_PE1_PCH_RXP<12>")
	)
	(segment
		(start 331.05852 -122.515122)
		(end 331.387196 -122.612658)
		(width 0.1143)
		(layer "In2.Cu")
		(net "P3E_CPU0_PE1_PCH_RXP<12>")
	)
	(segment
		(start 325.718932 -117.137434)
		(end 325.590154 -117.331998)
		(width 0.1143)
		(layer "In2.Cu")
		(net "P3E_CPU0_PE1_PCH_RXP<12>")
	)
	(segment
		(start 301.202852 -100.881434)
		(end 301.291752 -100.792534)
		(width 0.0889)
		(layer "In2.Cu")
		(net "P3E_CPU0_PE1_PCH_RXP<12>")
	)
	(segment
		(start 330.413106 -122.32386)
		(end 330.618338 -122.212354)
		(width 0.1143)
		(layer "In2.Cu")
		(net "P3E_CPU0_PE1_PCH_RXP<12>")
	)
	(segment
		(start 325.650606 -116.801392)
		(end 325.718932 -117.137434)
		(width 0.1143)
		(layer "In2.Cu")
		(net "P3E_CPU0_PE1_PCH_RXP<12>")
	)
	(segment
		(start 298.378626 -98.995738)
		(end 298.08551 -99.164648)
		(width 0.0889)
		(layer "In2.Cu")
		(net "P3E_CPU0_PE1_PCH_RXP<12>")
	)
	(segment
		(start 331.921104 -122.598688)
		(end 332.03261 -122.80392)
		(width 0.1143)
		(layer "In2.Cu")
		(net "P3E_CPU0_PE1_PCH_RXP<12>")
	)
	(segment
		(start 349.540576 -122.832876)
		(end 350.525588 -122.832876)
		(width 0.1143)
		(layer "In2.Cu")
		(net "P3E_CPU0_PE1_PCH_RXP<12>")
	)
	(segment
		(start 340.088728 -122.18924)
		(end 342.474804 -122.695462)
		(width 0.1143)
		(layer "In2.Cu")
		(net "P3E_CPU0_PE1_PCH_RXP<12>")
	)
	(segment
		(start 298.36745 -99.395788)
		(end 298.400216 -99.395788)
		(width 0.0889)
		(layer "In2.Cu")
		(net "P3E_CPU0_PE1_PCH_RXP<12>")
	)
	(segment
		(start 325.590154 -117.331998)
		(end 325.65848 -117.66804)
		(width 0.1143)
		(layer "In2.Cu")
		(net "P3E_CPU0_PE1_PCH_RXP<12>")
	)
	(segment
		(start 302.790606 -100.792534)
		(end 302.879506 -100.881434)
		(width 0.0889)
		(layer "In2.Cu")
		(net "P3E_CPU0_PE1_PCH_RXP<12>")
	)
	(segment
		(start 300.077632 -100.386134)
		(end 300.113446 -100.386134)
		(width 0.0889)
		(layer "In2.Cu")
		(net "P3E_CPU0_PE1_PCH_RXP<12>")
	)
	(segment
		(start 300.936152 -100.881434)
		(end 301.202852 -100.881434)
		(width 0.0889)
		(layer "In2.Cu")
		(net "P3E_CPU0_PE1_PCH_RXP<12>")
	)
	(segment
		(start 320.429382 -110.218474)
		(end 320.431668 -110.217712)
		(width 0.1143)
		(layer "In2.Cu")
		(net "P3E_CPU0_PE1_PCH_RXP<12>")
	)
	(segment
		(start 306.123086 -100.830634)
		(end 306.145184 -100.830634)
		(width 0.0889)
		(layer "In2.Cu")
		(net "P3E_CPU0_PE1_PCH_RXP<12>")
	)
	(segment
		(start 342.474804 -122.695462)
		(end 343.752932 -122.439938)
		(width 0.1143)
		(layer "In2.Cu")
		(net "P3E_CPU0_PE1_PCH_RXP<12>")
	)
	(segment
		(start 325.65848 -117.66804)
		(end 328.356468 -121.072656)
		(width 0.1143)
		(layer "In2.Cu")
		(net "P3E_CPU0_PE1_PCH_RXP<12>")
	)
	(segment
		(start 345.224862 -121.458736)
		(end 346.604082 -121.182892)
		(width 0.1143)
		(layer "In2.Cu")
		(net "P3E_CPU0_PE1_PCH_RXP<12>")
	)
	(segment
		(start 334.1878 -123.44273)
		(end 340.088728 -122.18924)
		(width 0.1143)
		(layer "In2.Cu")
		(net "P3E_CPU0_PE1_PCH_RXP<12>")
	)
	(segment
		(start 306.145184 -100.830634)
		(end 307.30698 -100.830634)
		(width 0.1143)
		(layer "In2.Cu")
		(net "P3E_CPU0_PE1_PCH_RXP<12>")
	)
	(segment
		(start 324.888606 -113.88471)
		(end 325.455788 -116.67236)
		(width 0.1143)
		(layer "In2.Cu")
		(net "P3E_CPU0_PE1_PCH_RXP<12>")
	)
	(segment
		(start 320.428112 -110.21822)
		(end 320.429382 -110.218474)
		(width 0.1143)
		(layer "In2.Cu")
		(net "P3E_CPU0_PE1_PCH_RXP<12>")
	)
	(segment
		(start 328.356468 -121.072656)
		(end 329.690984 -122.109738)
		(width 0.1143)
		(layer "In2.Cu")
		(net "P3E_CPU0_PE1_PCH_RXP<12>")
	)
	(segment
		(start 332.03261 -122.80392)
		(end 334.1878 -123.44273)
		(width 0.1143)
		(layer "In2.Cu")
		(net "P3E_CPU0_PE1_PCH_RXP<12>")
	)
	(segment
		(start 329.690984 -122.109738)
		(end 330.413106 -122.32386)
		(width 0.1143)
		(layer "In2.Cu")
		(net "P3E_CPU0_PE1_PCH_RXP<12>")
	)
	(arc
		(start 299.2501 -99.890834)
		(mid 299.538245 -99.973153)
		(end 299.748956 -100.186236)
		(width 0.0889)
		(layer "In2.Cu")
		(net "P3E_CPU0_PE1_PCH_RXP<12>")
	)
	(arc
		(start 299.748956 -100.186236)
		(mid 299.8877 -100.328269)
		(end 300.077632 -100.386134)
		(width 0.0889)
		(layer "In2.Cu")
		(net "P3E_CPU0_PE1_PCH_RXP<12>")
	)
	(arc
		(start 298.890436 -99.690936)
		(mid 299.030515 -99.833672)
		(end 299.22216 -99.890834)
		(width 0.0889)
		(layer "In2.Cu")
		(net "P3E_CPU0_PE1_PCH_RXP<12>")
	)
	(arc
		(start 298.064428 -99.243388)
		(mid 298.19899 -99.3533)
		(end 298.36745 -99.395788)
		(width 0.0889)
		(layer "In2.Cu")
		(net "P3E_CPU0_PE1_PCH_RXP<12>")
	)
	(arc
		(start 300.113446 -100.386134)
		(mid 300.39887 -100.469601)
		(end 300.607476 -100.681536)
		(width 0.0889)
		(layer "In2.Cu")
		(net "P3E_CPU0_PE1_PCH_RXP<12>")
	)
	(arc
		(start 300.607476 -100.681536)
		(mid 300.74622 -100.823569)
		(end 300.936152 -100.881434)
		(width 0.0889)
		(layer "In2.Cu")
		(net "P3E_CPU0_PE1_PCH_RXP<12>")
	)
	(arc
		(start 298.400216 -99.395788)
		(mid 298.683433 -99.480069)
		(end 298.890436 -99.690936)
		(width 0.0889)
		(layer "In2.Cu")
		(net "P3E_CPU0_PE1_PCH_RXP<12>")
	)
	(segment
		(start 296.948606 -97.509584)
		(end 297.520106 -97.509584)
		(width 0.1143)
		(layer "F.Cu")
		(net "P3E_CPU0_PE1_PCH_RXP<11>")
	)
	(via
		(at 358.912414 -121.265442)
		(size 0.508)
		(drill 0.254)
		(layers "F.Cu" "B.Cu")
		(net "P3E_CPU0_PE1_PCH_RXP<11>")
	)
	(via
		(at 297.520106 -97.509584)
		(size 0.508)
		(drill 0.254)
		(layers "F.Cu" "B.Cu")
		(net "P3E_CPU0_PE1_PCH_RXP<11>")
	)
	(segment
		(start 359.477564 -121.830592)
		(end 358.912414 -121.265442)
		(width 0.1143)
		(layer "B.Cu")
		(net "P3E_CPU0_PE1_PCH_RXP<11>")
	)
	(segment
		(start 361.826556 -121.57964)
		(end 361.575604 -121.830592)
		(width 0.1143)
		(layer "B.Cu")
		(net "P3E_CPU0_PE1_PCH_RXP<11>")
	)
	(segment
		(start 361.826556 -121.392442)
		(end 361.826556 -121.57964)
		(width 0.1143)
		(layer "B.Cu")
		(net "P3E_CPU0_PE1_PCH_RXP<11>")
	)
	(segment
		(start 361.575604 -121.830592)
		(end 359.477564 -121.830592)
		(width 0.1143)
		(layer "B.Cu")
		(net "P3E_CPU0_PE1_PCH_RXP<11>")
	)
	(segment
		(start 307.170836 -98.57232)
		(end 306.407566 -98.57232)
		(width 0.0889)
		(layer "In2.Cu")
		(net "P3E_CPU0_PE1_PCH_RXP<11>")
	)
	(segment
		(start 297.520106 -97.847658)
		(end 297.520106 -97.509584)
		(width 0.0889)
		(layer "In2.Cu")
		(net "P3E_CPU0_PE1_PCH_RXP<11>")
	)
	(segment
		(start 307.243734 -98.52152)
		(end 307.221636 -98.52152)
		(width 0.0889)
		(layer "In2.Cu")
		(net "P3E_CPU0_PE1_PCH_RXP<11>")
	)
	(segment
		(start 328.962004 -118.93296)
		(end 328.528172 -117.104922)
		(width 0.1143)
		(layer "In2.Cu")
		(net "P3E_CPU0_PE1_PCH_RXP<11>")
	)
	(segment
		(start 323.392292 -108.552488)
		(end 313.492388 -102.341172)
		(width 0.1143)
		(layer "In2.Cu")
		(net "P3E_CPU0_PE1_PCH_RXP<11>")
	)
	(segment
		(start 300.117256 -98.405188)
		(end 300.08449 -98.405188)
		(width 0.0889)
		(layer "In2.Cu")
		(net "P3E_CPU0_PE1_PCH_RXP<11>")
	)
	(segment
		(start 300.971966 -98.900234)
		(end 300.9392 -98.900234)
		(width 0.0889)
		(layer "In2.Cu")
		(net "P3E_CPU0_PE1_PCH_RXP<11>")
	)
	(segment
		(start 311.930796 -100.190046)
		(end 309.075836 -98.52152)
		(width 0.1143)
		(layer "In2.Cu")
		(net "P3E_CPU0_PE1_PCH_RXP<11>")
	)
	(segment
		(start 330.511658 -120.137174)
		(end 328.962004 -118.93296)
		(width 0.1143)
		(layer "In2.Cu")
		(net "P3E_CPU0_PE1_PCH_RXP<11>")
	)
	(segment
		(start 297.578018 -97.90557)
		(end 297.520106 -97.847658)
		(width 0.0889)
		(layer "In2.Cu")
		(net "P3E_CPU0_PE1_PCH_RXP<11>")
	)
	(segment
		(start 307.221636 -98.52152)
		(end 307.170836 -98.57232)
		(width 0.0889)
		(layer "In2.Cu")
		(net "P3E_CPU0_PE1_PCH_RXP<11>")
	)
	(segment
		(start 305.569874 -99.410012)
		(end 304.858166 -99.410012)
		(width 0.0889)
		(layer "In2.Cu")
		(net "P3E_CPU0_PE1_PCH_RXP<11>")
	)
	(segment
		(start 358.912414 -121.265442)
		(end 358.912414 -121.653808)
		(width 0.1143)
		(layer "In2.Cu")
		(net "P3E_CPU0_PE1_PCH_RXP<11>")
	)
	(segment
		(start 302.083724 -99.395788)
		(end 301.80153 -99.395788)
		(width 0.0889)
		(layer "In2.Cu")
		(net "P3E_CPU0_PE1_PCH_RXP<11>")
	)
	(segment
		(start 343.473024 -119.038116)
		(end 341.52586 -119.427244)
		(width 0.1143)
		(layer "In2.Cu")
		(net "P3E_CPU0_PE1_PCH_RXP<11>")
	)
	(segment
		(start 298.400216 -97.414588)
		(end 298.357036 -97.414588)
		(width 0.0889)
		(layer "In2.Cu")
		(net "P3E_CPU0_PE1_PCH_RXP<11>")
	)
	(segment
		(start 302.287178 -99.192334)
		(end 302.083724 -99.395788)
		(width 0.0889)
		(layer "In2.Cu")
		(net "P3E_CPU0_PE1_PCH_RXP<11>")
	)
	(segment
		(start 304.640488 -99.192334)
		(end 302.287178 -99.192334)
		(width 0.0889)
		(layer "In2.Cu")
		(net "P3E_CPU0_PE1_PCH_RXP<11>")
	)
	(segment
		(start 358.912414 -121.653808)
		(end 358.798114 -121.768108)
		(width 0.1143)
		(layer "In2.Cu")
		(net "P3E_CPU0_PE1_PCH_RXP<11>")
	)
	(segment
		(start 327.28916 -110.33887)
		(end 323.392292 -108.552488)
		(width 0.1143)
		(layer "In2.Cu")
		(net "P3E_CPU0_PE1_PCH_RXP<11>")
	)
	(segment
		(start 335.312004 -121.877582)
		(end 330.511658 -120.137174)
		(width 0.1143)
		(layer "In2.Cu")
		(net "P3E_CPU0_PE1_PCH_RXP<11>")
	)
	(segment
		(start 329.033124 -115.38585)
		(end 329.057 -115.30457)
		(width 0.1143)
		(layer "In2.Cu")
		(net "P3E_CPU0_PE1_PCH_RXP<11>")
	)
	(segment
		(start 358.798114 -121.768108)
		(end 356.585774 -121.768108)
		(width 0.1143)
		(layer "In2.Cu")
		(net "P3E_CPU0_PE1_PCH_RXP<11>")
	)
	(segment
		(start 341.52586 -119.427244)
		(end 339.050376 -121.085102)
		(width 0.1143)
		(layer "In2.Cu")
		(net "P3E_CPU0_PE1_PCH_RXP<11>")
	)
	(segment
		(start 356.585774 -121.768108)
		(end 343.473024 -119.038116)
		(width 0.1143)
		(layer "In2.Cu")
		(net "P3E_CPU0_PE1_PCH_RXP<11>")
	)
	(segment
		(start 306.407566 -98.57232)
		(end 305.569874 -99.410012)
		(width 0.0889)
		(layer "In2.Cu")
		(net "P3E_CPU0_PE1_PCH_RXP<11>")
	)
	(segment
		(start 309.075836 -98.52152)
		(end 307.243734 -98.52152)
		(width 0.1143)
		(layer "In2.Cu")
		(net "P3E_CPU0_PE1_PCH_RXP<11>")
	)
	(segment
		(start 313.492388 -102.341172)
		(end 311.930796 -100.190046)
		(width 0.1143)
		(layer "In2.Cu")
		(net "P3E_CPU0_PE1_PCH_RXP<11>")
	)
	(segment
		(start 327.83018 -111.02594)
		(end 327.28916 -110.33887)
		(width 0.1143)
		(layer "In2.Cu")
		(net "P3E_CPU0_PE1_PCH_RXP<11>")
	)
	(segment
		(start 304.858166 -99.410012)
		(end 304.640488 -99.192334)
		(width 0.0889)
		(layer "In2.Cu")
		(net "P3E_CPU0_PE1_PCH_RXP<11>")
	)
	(segment
		(start 328.528172 -117.104922)
		(end 329.03287 -115.38585)
		(width 0.1143)
		(layer "In2.Cu")
		(net "P3E_CPU0_PE1_PCH_RXP<11>")
	)
	(segment
		(start 329.057 -115.30457)
		(end 327.83018 -111.02594)
		(width 0.1143)
		(layer "In2.Cu")
		(net "P3E_CPU0_PE1_PCH_RXP<11>")
	)
	(segment
		(start 339.050376 -121.085102)
		(end 335.312004 -121.877582)
		(width 0.1143)
		(layer "In2.Cu")
		(net "P3E_CPU0_PE1_PCH_RXP<11>")
	)
	(segment
		(start 329.03287 -115.38585)
		(end 329.033124 -115.38585)
		(width 0.1143)
		(layer "In2.Cu")
		(net "P3E_CPU0_PE1_PCH_RXP<11>")
	)
	(segment
		(start 299.254926 -97.909634)
		(end 299.22216 -97.909634)
		(width 0.0889)
		(layer "In2.Cu")
		(net "P3E_CPU0_PE1_PCH_RXP<11>")
	)
	(arc
		(start 300.607476 -98.700336)
		(mid 300.400472 -98.489472)
		(end 300.117256 -98.405188)
		(width 0.0889)
		(layer "In2.Cu")
		(net "P3E_CPU0_PE1_PCH_RXP<11>")
	)
	(arc
		(start 297.866816 -97.709736)
		(mid 297.744871 -97.840768)
		(end 297.578018 -97.90557)
		(width 0.0889)
		(layer "In2.Cu")
		(net "P3E_CPU0_PE1_PCH_RXP<11>")
	)
	(arc
		(start 301.465996 -99.195636)
		(mid 301.257388 -98.983704)
		(end 300.971966 -98.900234)
		(width 0.0889)
		(layer "In2.Cu")
		(net "P3E_CPU0_PE1_PCH_RXP<11>")
	)
	(arc
		(start 298.357036 -97.414588)
		(mid 298.073819 -97.498869)
		(end 297.866816 -97.709736)
		(width 0.0889)
		(layer "In2.Cu")
		(net "P3E_CPU0_PE1_PCH_RXP<11>")
	)
	(arc
		(start 299.748956 -98.205036)
		(mid 299.540348 -97.993104)
		(end 299.254926 -97.909634)
		(width 0.0889)
		(layer "In2.Cu")
		(net "P3E_CPU0_PE1_PCH_RXP<11>")
	)
	(arc
		(start 301.80153 -99.395788)
		(mid 301.60768 -99.339438)
		(end 301.465996 -99.195636)
		(width 0.0889)
		(layer "In2.Cu")
		(net "P3E_CPU0_PE1_PCH_RXP<11>")
	)
	(arc
		(start 298.890436 -97.709736)
		(mid 298.683432 -97.498872)
		(end 298.400216 -97.414588)
		(width 0.0889)
		(layer "In2.Cu")
		(net "P3E_CPU0_PE1_PCH_RXP<11>")
	)
	(arc
		(start 300.9392 -98.900234)
		(mid 300.747558 -98.843068)
		(end 300.607476 -98.700336)
		(width 0.0889)
		(layer "In2.Cu")
		(net "P3E_CPU0_PE1_PCH_RXP<11>")
	)
	(arc
		(start 300.08449 -98.405188)
		(mid 299.89064 -98.348838)
		(end 299.748956 -98.205036)
		(width 0.0889)
		(layer "In2.Cu")
		(net "P3E_CPU0_PE1_PCH_RXP<11>")
	)
	(arc
		(start 299.22216 -97.909634)
		(mid 299.030518 -97.852468)
		(end 298.890436 -97.709736)
		(width 0.0889)
		(layer "In2.Cu")
		(net "P3E_CPU0_PE1_PCH_RXP<11>")
	)
	(segment
		(start 298.378626 -98.005138)
		(end 297.807126 -98.005138)
		(width 0.1143)
		(layer "F.Cu")
		(net "P3E_CPU0_PE1_PCH_RXP<10>")
	)
	(via
		(at 298.378626 -98.005138)
		(size 0.508)
		(drill 0.254)
		(layers "F.Cu" "B.Cu")
		(net "P3E_CPU0_PE1_PCH_RXP<10>")
	)
	(via
		(at 358.836214 -125.532642)
		(size 0.508)
		(drill 0.254)
		(layers "F.Cu" "B.Cu")
		(net "P3E_CPU0_PE1_PCH_RXP<10>")
	)
	(segment
		(start 361.782614 -125.558042)
		(end 361.782614 -125.330966)
		(width 0.1143)
		(layer "B.Cu")
		(net "P3E_CPU0_PE1_PCH_RXP<10>")
	)
	(segment
		(start 361.782614 -125.330966)
		(end 361.557824 -125.106176)
		(width 0.1143)
		(layer "B.Cu")
		(net "P3E_CPU0_PE1_PCH_RXP<10>")
	)
	(segment
		(start 359.26268 -125.106176)
		(end 358.836214 -125.532642)
		(width 0.1143)
		(layer "B.Cu")
		(net "P3E_CPU0_PE1_PCH_RXP<10>")
	)
	(segment
		(start 361.557824 -125.106176)
		(end 359.26268 -125.106176)
		(width 0.1143)
		(layer "B.Cu")
		(net "P3E_CPU0_PE1_PCH_RXP<10>")
	)
	(segment
		(start 300.968664 -100.081334)
		(end 300.932596 -100.081334)
		(width 0.0889)
		(layer "In2.Cu")
		(net "P3E_CPU0_PE1_PCH_RXP<10>")
	)
	(segment
		(start 300.110652 -99.586288)
		(end 300.077886 -99.586288)
		(width 0.0889)
		(layer "In2.Cu")
		(net "P3E_CPU0_PE1_PCH_RXP<10>")
	)
	(segment
		(start 354.155248 -123.343924)
		(end 354.120704 -123.113038)
		(width 0.1143)
		(layer "In2.Cu")
		(net "P3E_CPU0_PE1_PCH_RXP<10>")
	)
	(segment
		(start 304.667158 -100.028248)
		(end 302.719994 -100.028248)
		(width 0.0889)
		(layer "In2.Cu")
		(net "P3E_CPU0_PE1_PCH_RXP<10>")
	)
	(segment
		(start 312.677302 -103.061516)
		(end 312.630058 -103.031544)
		(width 0.1143)
		(layer "In2.Cu")
		(net "P3E_CPU0_PE1_PCH_RXP<10>")
	)
	(segment
		(start 306.862734 -99.5299)
		(end 306.131214 -100.26142)
		(width 0.0889)
		(layer "In2.Cu")
		(net "P3E_CPU0_PE1_PCH_RXP<10>")
	)
	(segment
		(start 326.20712 -117.223286)
		(end 324.456298 -110.523782)
		(width 0.1143)
		(layer "In2.Cu")
		(net "P3E_CPU0_PE1_PCH_RXP<10>")
	)
	(segment
		(start 324.456298 -110.523782)
		(end 312.677556 -103.061516)
		(width 0.1143)
		(layer "In2.Cu")
		(net "P3E_CPU0_PE1_PCH_RXP<10>")
	)
	(segment
		(start 306.131214 -100.26142)
		(end 304.90033 -100.26142)
		(width 0.0889)
		(layer "In2.Cu")
		(net "P3E_CPU0_PE1_PCH_RXP<10>")
	)
	(segment
		(start 308.27726 -99.5807)
		(end 308.22646 -99.5299)
		(width 0.0889)
		(layer "In2.Cu")
		(net "P3E_CPU0_PE1_PCH_RXP<10>")
	)
	(segment
		(start 298.695618 -98.263202)
		(end 298.671742 -98.174048)
		(width 0.0889)
		(layer "In2.Cu")
		(net "P3E_CPU0_PE1_PCH_RXP<10>")
	)
	(segment
		(start 308.664102 -99.5807)
		(end 308.299358 -99.5807)
		(width 0.1143)
		(layer "In2.Cu")
		(net "P3E_CPU0_PE1_PCH_RXP<10>")
	)
	(segment
		(start 354.120704 -123.113038)
		(end 352.64979 -122.024902)
		(width 0.1143)
		(layer "In2.Cu")
		(net "P3E_CPU0_PE1_PCH_RXP<10>")
	)
	(segment
		(start 352.64979 -122.024902)
		(end 352.64979 -122.025156)
		(width 0.1143)
		(layer "In2.Cu")
		(net "P3E_CPU0_PE1_PCH_RXP<10>")
	)
	(segment
		(start 358.836214 -125.532642)
		(end 358.836214 -125.180852)
		(width 0.1143)
		(layer "In2.Cu")
		(net "P3E_CPU0_PE1_PCH_RXP<10>")
	)
	(segment
		(start 342.409018 -122.329448)
		(end 340.619842 -121.94921)
		(width 0.1143)
		(layer "In2.Cu")
		(net "P3E_CPU0_PE1_PCH_RXP<10>")
	)
	(segment
		(start 346.797884 -120.782588)
		(end 345.114372 -121.119392)
		(width 0.1143)
		(layer "In2.Cu")
		(net "P3E_CPU0_PE1_PCH_RXP<10>")
	)
	(segment
		(start 312.630058 -103.031544)
		(end 311.20207 -101.06406)
		(width 0.1143)
		(layer "In2.Cu")
		(net "P3E_CPU0_PE1_PCH_RXP<10>")
	)
	(segment
		(start 354.661724 -123.513342)
		(end 354.430838 -123.547886)
		(width 0.1143)
		(layer "In2.Cu")
		(net "P3E_CPU0_PE1_PCH_RXP<10>")
	)
	(segment
		(start 328.60107 -120.62841)
		(end 326.20712 -117.223286)
		(width 0.1143)
		(layer "In2.Cu")
		(net "P3E_CPU0_PE1_PCH_RXP<10>")
	)
	(segment
		(start 340.079076 -121.834148)
		(end 334.76057 -122.964194)
		(width 0.1143)
		(layer "In2.Cu")
		(net "P3E_CPU0_PE1_PCH_RXP<10>")
	)
	(segment
		(start 312.677556 -103.061516)
		(end 312.677302 -103.061516)
		(width 0.1143)
		(layer "In2.Cu")
		(net "P3E_CPU0_PE1_PCH_RXP<10>")
	)
	(segment
		(start 340.619842 -121.948956)
		(end 340.079076 -121.834148)
		(width 0.1143)
		(layer "In2.Cu")
		(net "P3E_CPU0_PE1_PCH_RXP<10>")
	)
	(segment
		(start 352.64979 -122.025156)
		(end 346.797884 -120.782588)
		(width 0.1143)
		(layer "In2.Cu")
		(net "P3E_CPU0_PE1_PCH_RXP<10>")
	)
	(segment
		(start 340.619842 -121.94921)
		(end 340.619842 -121.948956)
		(width 0.1143)
		(layer "In2.Cu")
		(net "P3E_CPU0_PE1_PCH_RXP<10>")
	)
	(segment
		(start 308.299358 -99.5807)
		(end 308.27726 -99.5807)
		(width 0.0889)
		(layer "In2.Cu")
		(net "P3E_CPU0_PE1_PCH_RXP<10>")
	)
	(segment
		(start 358.836214 -125.180852)
		(end 358.724962 -125.0696)
		(width 0.1143)
		(layer "In2.Cu")
		(net "P3E_CPU0_PE1_PCH_RXP<10>")
	)
	(segment
		(start 358.07523 -125.0696)
		(end 355.672898 -124.261626)
		(width 0.1143)
		(layer "In2.Cu")
		(net "P3E_CPU0_PE1_PCH_RXP<10>")
	)
	(segment
		(start 302.168306 -100.579936)
		(end 301.817532 -100.579936)
		(width 0.0889)
		(layer "In2.Cu")
		(net "P3E_CPU0_PE1_PCH_RXP<10>")
	)
	(segment
		(start 345.114372 -121.119392)
		(end 343.681304 -122.074686)
		(width 0.1143)
		(layer "In2.Cu")
		(net "P3E_CPU0_PE1_PCH_RXP<10>")
	)
	(segment
		(start 354.430838 -123.547886)
		(end 354.155248 -123.343924)
		(width 0.1143)
		(layer "In2.Cu")
		(net "P3E_CPU0_PE1_PCH_RXP<10>")
	)
	(segment
		(start 329.803506 -121.562622)
		(end 328.60107 -120.62841)
		(width 0.1143)
		(layer "In2.Cu")
		(net "P3E_CPU0_PE1_PCH_RXP<10>")
	)
	(segment
		(start 299.248322 -99.090734)
		(end 299.215556 -99.090734)
		(width 0.0889)
		(layer "In2.Cu")
		(net "P3E_CPU0_PE1_PCH_RXP<10>")
	)
	(segment
		(start 298.671742 -98.174048)
		(end 298.378626 -98.005138)
		(width 0.0889)
		(layer "In2.Cu")
		(net "P3E_CPU0_PE1_PCH_RXP<10>")
	)
	(segment
		(start 302.719994 -100.028248)
		(end 302.168306 -100.579936)
		(width 0.0889)
		(layer "In2.Cu")
		(net "P3E_CPU0_PE1_PCH_RXP<10>")
	)
	(segment
		(start 308.22646 -99.5299)
		(end 306.862734 -99.5299)
		(width 0.0889)
		(layer "In2.Cu")
		(net "P3E_CPU0_PE1_PCH_RXP<10>")
	)
	(segment
		(start 311.20207 -101.06406)
		(end 308.664102 -99.5807)
		(width 0.1143)
		(layer "In2.Cu")
		(net "P3E_CPU0_PE1_PCH_RXP<10>")
	)
	(segment
		(start 358.724962 -125.0696)
		(end 358.07523 -125.0696)
		(width 0.1143)
		(layer "In2.Cu")
		(net "P3E_CPU0_PE1_PCH_RXP<10>")
	)
	(segment
		(start 334.76057 -122.964194)
		(end 329.803506 -121.562622)
		(width 0.1143)
		(layer "In2.Cu")
		(net "P3E_CPU0_PE1_PCH_RXP<10>")
	)
	(segment
		(start 343.681304 -122.074686)
		(end 342.409018 -122.329448)
		(width 0.1143)
		(layer "In2.Cu")
		(net "P3E_CPU0_PE1_PCH_RXP<10>")
	)
	(segment
		(start 304.90033 -100.26142)
		(end 304.667158 -100.028248)
		(width 0.0889)
		(layer "In2.Cu")
		(net "P3E_CPU0_PE1_PCH_RXP<10>")
	)
	(segment
		(start 355.672898 -124.261626)
		(end 354.661724 -123.513342)
		(width 0.1143)
		(layer "In2.Cu")
		(net "P3E_CPU0_PE1_PCH_RXP<10>")
	)
	(arc
		(start 299.583856 -99.290886)
		(mid 299.442173 -99.147082)
		(end 299.248322 -99.090734)
		(width 0.0889)
		(layer "In2.Cu")
		(net "P3E_CPU0_PE1_PCH_RXP<10>")
	)
	(arc
		(start 300.442376 -99.786186)
		(mid 300.302297 -99.64345)
		(end 300.110652 -99.586288)
		(width 0.0889)
		(layer "In2.Cu")
		(net "P3E_CPU0_PE1_PCH_RXP<10>")
	)
	(arc
		(start 301.817532 -100.579936)
		(mid 301.519267 -100.499887)
		(end 301.300896 -100.281486)
		(width 0.0889)
		(layer "In2.Cu")
		(net "P3E_CPU0_PE1_PCH_RXP<10>")
	)
	(arc
		(start 300.077886 -99.586288)
		(mid 299.792462 -99.502821)
		(end 299.583856 -99.290886)
		(width 0.0889)
		(layer "In2.Cu")
		(net "P3E_CPU0_PE1_PCH_RXP<10>")
	)
	(arc
		(start 301.300896 -100.281486)
		(mid 301.160628 -100.13853)
		(end 300.968664 -100.081334)
		(width 0.0889)
		(layer "In2.Cu")
		(net "P3E_CPU0_PE1_PCH_RXP<10>")
	)
	(arc
		(start 300.932596 -100.081334)
		(mid 300.649379 -99.997053)
		(end 300.442376 -99.786186)
		(width 0.0889)
		(layer "In2.Cu")
		(net "P3E_CPU0_PE1_PCH_RXP<10>")
	)
	(arc
		(start 299.215556 -99.090734)
		(mid 298.736739 -98.814522)
		(end 298.695618 -98.263202)
		(width 0.0889)
		(layer "In2.Cu")
		(net "P3E_CPU0_PE1_PCH_RXP<10>")
	)
	(segment
		(start 377.33605 -116.72316)
		(end 377.83135 -116.953284)
		(width 0.1143)
		(layer "F.Cu")
		(net "P3E_CPU0_PE1_PCH_RXP<0>")
	)
	(via
		(at 334.962754 -71.81342)
		(size 0.508)
		(drill 0.254)
		(layers "F.Cu" "B.Cu")
		(net "P3E_CPU0_PE1_PCH_RXP<0>")
	)
	(via
		(at 334.847438 -64.831214)
		(size 0.508)
		(drill 0.254)
		(layers "F.Cu" "B.Cu")
		(net "P3E_CPU0_PE1_PCH_RXP<0>")
	)
	(via
		(at 377.83135 -116.953284)
		(size 0.508)
		(drill 0.254)
		(layers "F.Cu" "B.Cu")
		(net "P3E_CPU0_PE1_PCH_RXP<0>")
	)
	(segment
		(start 335.28762 -71.488554)
		(end 335.28762 -70.917562)
		(width 0.1143)
		(layer "B.Cu")
		(net "P3E_CPU0_PE1_PCH_RXP<0>")
	)
	(segment
		(start 334.847438 -70.47738)
		(end 334.847438 -64.831214)
		(width 0.1143)
		(layer "B.Cu")
		(net "P3E_CPU0_PE1_PCH_RXP<0>")
	)
	(segment
		(start 334.847438 -63.537592)
		(end 334.04556 -62.735714)
		(width 0.1143)
		(layer "B.Cu")
		(net "P3E_CPU0_PE1_PCH_RXP<0>")
	)
	(segment
		(start 334.04556 -61.956188)
		(end 333.346806 -61.257434)
		(width 0.1143)
		(layer "B.Cu")
		(net "P3E_CPU0_PE1_PCH_RXP<0>")
	)
	(segment
		(start 334.04556 -62.735714)
		(end 334.04556 -61.956188)
		(width 0.1143)
		(layer "B.Cu")
		(net "P3E_CPU0_PE1_PCH_RXP<0>")
	)
	(segment
		(start 335.28762 -70.917562)
		(end 334.847438 -70.47738)
		(width 0.1143)
		(layer "B.Cu")
		(net "P3E_CPU0_PE1_PCH_RXP<0>")
	)
	(segment
		(start 334.962754 -71.81342)
		(end 335.28762 -71.488554)
		(width 0.1143)
		(layer "B.Cu")
		(net "P3E_CPU0_PE1_PCH_RXP<0>")
	)
	(segment
		(start 334.847438 -64.831214)
		(end 334.847438 -63.537592)
		(width 0.1143)
		(layer "B.Cu")
		(net "P3E_CPU0_PE1_PCH_RXP<0>")
	)
	(segment
		(start 357.918258 -82.921348)
		(end 358.237536 -83.136486)
		(width 0.1143)
		(layer "In2.Cu")
		(net "P3E_CPU0_PE1_PCH_RXP<0>")
	)
	(segment
		(start 375.561606 -114.203734)
		(end 375.759218 -114.401346)
		(width 0.0889)
		(layer "In2.Cu")
		(net "P3E_CPU0_PE1_PCH_RXP<0>")
	)
	(segment
		(start 363.6772 -107.42168)
		(end 364.018322 -109.025944)
		(width 0.1143)
		(layer "In2.Cu")
		(net "P3E_CPU0_PE1_PCH_RXP<0>")
	)
	(segment
		(start 367.4364 -114.6429)
		(end 367.906554 -114.6429)
		(width 0.0889)
		(layer "In2.Cu")
		(net "P3E_CPU0_PE1_PCH_RXP<0>")
	)
	(segment
		(start 376.947176 -115.0112)
		(end 377.212352 -115.276376)
		(width 0.0889)
		(layer "In2.Cu")
		(net "P3E_CPU0_PE1_PCH_RXP<0>")
	)
	(segment
		(start 367.363502 -114.6937)
		(end 367.3856 -114.6937)
		(width 0.0889)
		(layer "In2.Cu")
		(net "P3E_CPU0_PE1_PCH_RXP<0>")
	)
	(segment
		(start 358.644444 -86.523322)
		(end 358.633014 -86.582758)
		(width 0.1143)
		(layer "In2.Cu")
		(net "P3E_CPU0_PE1_PCH_RXP<0>")
	)
	(segment
		(start 345.935554 -82.711036)
		(end 346.880942 -82.974434)
		(width 0.1143)
		(layer "In2.Cu")
		(net "P3E_CPU0_PE1_PCH_RXP<0>")
	)
	(segment
		(start 358.245664 -88.573864)
		(end 358.444292 -89.594944)
		(width 0.1143)
		(layer "In2.Cu")
		(net "P3E_CPU0_PE1_PCH_RXP<0>")
	)
	(segment
		(start 363.531658 -97.60966)
		(end 363.21111 -99.122484)
		(width 0.1143)
		(layer "In2.Cu")
		(net "P3E_CPU0_PE1_PCH_RXP<0>")
	)
	(segment
		(start 358.633014 -86.582758)
		(end 358.62133 -86.642194)
		(width 0.1143)
		(layer "In2.Cu")
		(net "P3E_CPU0_PE1_PCH_RXP<0>")
	)
	(segment
		(start 378.7267 -116.083588)
		(end 378.7267 -116.10594)
		(width 0.0889)
		(layer "In2.Cu")
		(net "P3E_CPU0_PE1_PCH_RXP<0>")
	)
	(segment
		(start 334.962754 -71.81342)
		(end 335.2165 -72.067166)
		(width 0.1143)
		(layer "In2.Cu")
		(net "P3E_CPU0_PE1_PCH_RXP<0>")
	)
	(segment
		(start 358.644444 -86.523068)
		(end 358.644444 -86.523322)
		(width 0.1143)
		(layer "In2.Cu")
		(net "P3E_CPU0_PE1_PCH_RXP<0>")
	)
	(segment
		(start 366.23879 -112.064292)
		(end 365.815118 -113.618264)
		(width 0.1143)
		(layer "In2.Cu")
		(net "P3E_CPU0_PE1_PCH_RXP<0>")
	)
	(segment
		(start 376.369072 -115.0112)
		(end 376.947176 -115.0112)
		(width 0.0889)
		(layer "In2.Cu")
		(net "P3E_CPU0_PE1_PCH_RXP<0>")
	)
	(segment
		(start 335.50352 -73.12152)
		(end 336.153252 -73.12152)
		(width 0.1143)
		(layer "In2.Cu")
		(net "P3E_CPU0_PE1_PCH_RXP<0>")
	)
	(segment
		(start 343.315036 -83.482434)
		(end 345.935554 -82.711036)
		(width 0.1143)
		(layer "In2.Cu")
		(net "P3E_CPU0_PE1_PCH_RXP<0>")
	)
	(segment
		(start 363.6772 -101.353366)
		(end 363.6772 -107.42168)
		(width 0.1143)
		(layer "In2.Cu")
		(net "P3E_CPU0_PE1_PCH_RXP<0>")
	)
	(segment
		(start 374.717564 -113.485422)
		(end 374.915176 -113.683034)
		(width 0.0889)
		(layer "In2.Cu")
		(net "P3E_CPU0_PE1_PCH_RXP<0>")
	)
	(segment
		(start 378.234448 -116.88826)
		(end 378.169424 -116.953284)
		(width 0.0889)
		(layer "In2.Cu")
		(net "P3E_CPU0_PE1_PCH_RXP<0>")
	)
	(segment
		(start 375.040906 -113.683034)
		(end 375.238264 -113.880392)
		(width 0.0889)
		(layer "In2.Cu")
		(net "P3E_CPU0_PE1_PCH_RXP<0>")
	)
	(segment
		(start 362.836714 -92.828364)
		(end 363.577124 -95.118682)
		(width 0.1143)
		(layer "In2.Cu")
		(net "P3E_CPU0_PE1_PCH_RXP<0>")
	)
	(segment
		(start 376.08256 -114.724688)
		(end 376.369072 -115.0112)
		(width 0.0889)
		(layer "In2.Cu")
		(net "P3E_CPU0_PE1_PCH_RXP<0>")
	)
	(segment
		(start 347.63837 -82.804)
		(end 348.207076 -83.01101)
		(width 0.1143)
		(layer "In2.Cu")
		(net "P3E_CPU0_PE1_PCH_RXP<0>")
	)
	(segment
		(start 375.759218 -114.401346)
		(end 375.759218 -114.527076)
		(width 0.0889)
		(layer "In2.Cu")
		(net "P3E_CPU0_PE1_PCH_RXP<0>")
	)
	(segment
		(start 335.2165 -72.067166)
		(end 335.2165 -72.8345)
		(width 0.1143)
		(layer "In2.Cu")
		(net "P3E_CPU0_PE1_PCH_RXP<0>")
	)
	(segment
		(start 369.387374 -113.16208)
		(end 374.519952 -113.16208)
		(width 0.0889)
		(layer "In2.Cu")
		(net "P3E_CPU0_PE1_PCH_RXP<0>")
	)
	(segment
		(start 348.62389 -82.91195)
		(end 349.746062 -82.15503)
		(width 0.1143)
		(layer "In2.Cu")
		(net "P3E_CPU0_PE1_PCH_RXP<0>")
	)
	(segment
		(start 350.693482 -81.971388)
		(end 350.772984 -81.971388)
		(width 0.1143)
		(layer "In2.Cu")
		(net "P3E_CPU0_PE1_PCH_RXP<0>")
	)
	(segment
		(start 335.2165 -72.8345)
		(end 335.50352 -73.12152)
		(width 0.1143)
		(layer "In2.Cu")
		(net "P3E_CPU0_PE1_PCH_RXP<0>")
	)
	(segment
		(start 375.95683 -114.724688)
		(end 376.08256 -114.724688)
		(width 0.0889)
		(layer "In2.Cu")
		(net "P3E_CPU0_PE1_PCH_RXP<0>")
	)
	(segment
		(start 336.153252 -73.12152)
		(end 336.648806 -73.34885)
		(width 0.1143)
		(layer "In2.Cu")
		(net "P3E_CPU0_PE1_PCH_RXP<0>")
	)
	(segment
		(start 358.830372 -85.567266)
		(end 358.644444 -86.523068)
		(width 0.1143)
		(layer "In2.Cu")
		(net "P3E_CPU0_PE1_PCH_RXP<0>")
	)
	(segment
		(start 377.983242 -115.830858)
		(end 378.126752 -115.748054)
		(width 0.0889)
		(layer "In2.Cu")
		(net "P3E_CPU0_PE1_PCH_RXP<0>")
	)
	(segment
		(start 377.212352 -115.276376)
		(end 377.212352 -115.568984)
		(width 0.0889)
		(layer "In2.Cu")
		(net "P3E_CPU0_PE1_PCH_RXP<0>")
	)
	(segment
		(start 363.290358 -96.469962)
		(end 363.531658 -97.60966)
		(width 0.1143)
		(layer "In2.Cu")
		(net "P3E_CPU0_PE1_PCH_RXP<0>")
	)
	(segment
		(start 349.746062 -82.15503)
		(end 350.693482 -81.971388)
		(width 0.1143)
		(layer "In2.Cu")
		(net "P3E_CPU0_PE1_PCH_RXP<0>")
	)
	(segment
		(start 352.374962 -82.283046)
		(end 353.504754 -82.063336)
		(width 0.1143)
		(layer "In2.Cu")
		(net "P3E_CPU0_PE1_PCH_RXP<0>")
	)
	(segment
		(start 375.759218 -114.527076)
		(end 375.95683 -114.724688)
		(width 0.0889)
		(layer "In2.Cu")
		(net "P3E_CPU0_PE1_PCH_RXP<0>")
	)
	(segment
		(start 374.519952 -113.16208)
		(end 374.717564 -113.359692)
		(width 0.0889)
		(layer "In2.Cu")
		(net "P3E_CPU0_PE1_PCH_RXP<0>")
	)
	(segment
		(start 347.627956 -82.80019)
		(end 347.63837 -82.804)
		(width 0.1143)
		(layer "In2.Cu")
		(net "P3E_CPU0_PE1_PCH_RXP<0>")
	)
	(segment
		(start 350.772984 -81.971388)
		(end 352.374962 -82.283046)
		(width 0.1143)
		(layer "In2.Cu")
		(net "P3E_CPU0_PE1_PCH_RXP<0>")
	)
	(segment
		(start 358.62133 -86.642194)
		(end 358.621076 -86.642194)
		(width 0.1143)
		(layer "In2.Cu")
		(net "P3E_CPU0_PE1_PCH_RXP<0>")
	)
	(segment
		(start 366.780064 -114.6937)
		(end 367.363502 -114.6937)
		(width 0.1143)
		(layer "In2.Cu")
		(net "P3E_CPU0_PE1_PCH_RXP<0>")
	)
	(segment
		(start 365.647478 -110.205266)
		(end 366.23879 -112.064292)
		(width 0.1143)
		(layer "In2.Cu")
		(net "P3E_CPU0_PE1_PCH_RXP<0>")
	)
	(segment
		(start 375.238264 -114.006122)
		(end 375.435876 -114.203734)
		(width 0.0889)
		(layer "In2.Cu")
		(net "P3E_CPU0_PE1_PCH_RXP<0>")
	)
	(segment
		(start 358.237536 -83.136486)
		(end 358.406446 -83.387184)
		(width 0.1143)
		(layer "In2.Cu")
		(net "P3E_CPU0_PE1_PCH_RXP<0>")
	)
	(segment
		(start 358.835706 -90.161364)
		(end 362.836714 -92.828364)
		(width 0.1143)
		(layer "In2.Cu")
		(net "P3E_CPU0_PE1_PCH_RXP<0>")
	)
	(segment
		(start 377.514104 -115.870736)
		(end 377.943364 -115.870736)
		(width 0.0889)
		(layer "In2.Cu")
		(net "P3E_CPU0_PE1_PCH_RXP<0>")
	)
	(segment
		(start 367.906554 -114.6429)
		(end 369.387374 -113.16208)
		(width 0.0889)
		(layer "In2.Cu")
		(net "P3E_CPU0_PE1_PCH_RXP<0>")
	)
	(segment
		(start 377.943364 -115.870736)
		(end 377.983242 -115.830858)
		(width 0.0889)
		(layer "In2.Cu")
		(net "P3E_CPU0_PE1_PCH_RXP<0>")
	)
	(segment
		(start 346.880942 -82.974434)
		(end 347.627956 -82.80019)
		(width 0.1143)
		(layer "In2.Cu")
		(net "P3E_CPU0_PE1_PCH_RXP<0>")
	)
	(segment
		(start 374.717564 -113.359692)
		(end 374.717564 -113.485422)
		(width 0.0889)
		(layer "In2.Cu")
		(net "P3E_CPU0_PE1_PCH_RXP<0>")
	)
	(segment
		(start 364.018322 -109.025944)
		(end 365.647478 -110.205266)
		(width 0.1143)
		(layer "In2.Cu")
		(net "P3E_CPU0_PE1_PCH_RXP<0>")
	)
	(segment
		(start 375.238264 -113.880392)
		(end 375.238264 -114.006122)
		(width 0.0889)
		(layer "In2.Cu")
		(net "P3E_CPU0_PE1_PCH_RXP<0>")
	)
	(segment
		(start 339.408262 -81.882488)
		(end 343.315036 -83.482434)
		(width 0.1143)
		(layer "In2.Cu")
		(net "P3E_CPU0_PE1_PCH_RXP<0>")
	)
	(segment
		(start 336.648806 -73.34885)
		(end 339.408262 -81.882488)
		(width 0.1143)
		(layer "In2.Cu")
		(net "P3E_CPU0_PE1_PCH_RXP<0>")
	)
	(segment
		(start 358.406446 -83.387184)
		(end 358.830372 -85.567266)
		(width 0.1143)
		(layer "In2.Cu")
		(net "P3E_CPU0_PE1_PCH_RXP<0>")
	)
	(segment
		(start 378.169424 -116.953284)
		(end 377.83135 -116.953284)
		(width 0.0889)
		(layer "In2.Cu")
		(net "P3E_CPU0_PE1_PCH_RXP<0>")
	)
	(segment
		(start 358.794304 -90.119962)
		(end 358.835706 -90.161364)
		(width 0.1143)
		(layer "In2.Cu")
		(net "P3E_CPU0_PE1_PCH_RXP<0>")
	)
	(segment
		(start 367.3856 -114.6937)
		(end 367.4364 -114.6429)
		(width 0.0889)
		(layer "In2.Cu")
		(net "P3E_CPU0_PE1_PCH_RXP<0>")
	)
	(segment
		(start 363.21111 -99.122484)
		(end 363.6772 -101.353366)
		(width 0.1143)
		(layer "In2.Cu")
		(net "P3E_CPU0_PE1_PCH_RXP<0>")
	)
	(segment
		(start 348.207076 -83.01101)
		(end 348.62389 -82.91195)
		(width 0.1143)
		(layer "In2.Cu")
		(net "P3E_CPU0_PE1_PCH_RXP<0>")
	)
	(segment
		(start 377.212352 -115.568984)
		(end 377.514104 -115.870736)
		(width 0.0889)
		(layer "In2.Cu")
		(net "P3E_CPU0_PE1_PCH_RXP<0>")
	)
	(segment
		(start 358.444292 -89.594944)
		(end 358.794304 -90.119962)
		(width 0.1143)
		(layer "In2.Cu")
		(net "P3E_CPU0_PE1_PCH_RXP<0>")
	)
	(segment
		(start 353.504754 -82.063336)
		(end 357.918258 -82.921348)
		(width 0.1143)
		(layer "In2.Cu")
		(net "P3E_CPU0_PE1_PCH_RXP<0>")
	)
	(segment
		(start 374.915176 -113.683034)
		(end 375.040906 -113.683034)
		(width 0.0889)
		(layer "In2.Cu")
		(net "P3E_CPU0_PE1_PCH_RXP<0>")
	)
	(segment
		(start 375.435876 -114.203734)
		(end 375.561606 -114.203734)
		(width 0.0889)
		(layer "In2.Cu")
		(net "P3E_CPU0_PE1_PCH_RXP<0>")
	)
	(segment
		(start 365.815118 -113.618264)
		(end 365.992156 -114.175286)
		(width 0.1143)
		(layer "In2.Cu")
		(net "P3E_CPU0_PE1_PCH_RXP<0>")
	)
	(segment
		(start 365.992156 -114.175286)
		(end 366.780064 -114.6937)
		(width 0.1143)
		(layer "In2.Cu")
		(net "P3E_CPU0_PE1_PCH_RXP<0>")
	)
	(segment
		(start 363.577124 -95.118682)
		(end 363.290358 -96.469962)
		(width 0.1143)
		(layer "In2.Cu")
		(net "P3E_CPU0_PE1_PCH_RXP<0>")
	)
	(segment
		(start 358.621076 -86.642194)
		(end 358.245664 -88.573864)
		(width 0.1143)
		(layer "In2.Cu")
		(net "P3E_CPU0_PE1_PCH_RXP<0>")
	)
	(arc
		(start 378.7267 -116.10594)
		(mid 378.67035 -116.29979)
		(end 378.526548 -116.441474)
		(width 0.0889)
		(layer "In2.Cu")
		(net "P3E_CPU0_PE1_PCH_RXP<0>")
	)
	(arc
		(start 378.526548 -115.748054)
		(mid 378.670352 -115.889737)
		(end 378.7267 -116.083588)
		(width 0.0889)
		(layer "In2.Cu")
		(net "P3E_CPU0_PE1_PCH_RXP<0>")
	)
	(arc
		(start 378.526548 -116.441474)
		(mid 378.327175 -116.630002)
		(end 378.234448 -116.88826)
		(width 0.0889)
		(layer "In2.Cu")
		(net "P3E_CPU0_PE1_PCH_RXP<0>")
	)
	(arc
		(start 378.126752 -115.748054)
		(mid 378.32665 -115.694555)
		(end 378.526548 -115.748054)
		(width 0.0889)
		(layer "In2.Cu")
		(net "P3E_CPU0_PE1_PCH_RXP<0>")
	)
	(segment
		(start 298.665646 -97.509584)
		(end 299.237146 -97.509584)
		(width 0.1143)
		(layer "F.Cu")
		(net "P3E_CPU0_PE1_PCH_RXN<9>")
	)
	(via
		(at 364.881414 -125.583442)
		(size 0.508)
		(drill 0.254)
		(layers "F.Cu" "B.Cu")
		(net "P3E_CPU0_PE1_PCH_RXN<9>")
	)
	(via
		(at 299.237146 -97.509584)
		(size 0.508)
		(drill 0.254)
		(layers "F.Cu" "B.Cu")
		(net "P3E_CPU0_PE1_PCH_RXN<9>")
	)
	(segment
		(start 364.881414 -125.481842)
		(end 364.881414 -125.583442)
		(width 0.1143)
		(layer "B.Cu")
		(net "P3E_CPU0_PE1_PCH_RXN<9>")
	)
	(segment
		(start 367.827814 -125.507242)
		(end 367.827814 -125.227842)
		(width 0.1143)
		(layer "B.Cu")
		(net "P3E_CPU0_PE1_PCH_RXN<9>")
	)
	(segment
		(start 367.675414 -125.075442)
		(end 365.287814 -125.075442)
		(width 0.1143)
		(layer "B.Cu")
		(net "P3E_CPU0_PE1_PCH_RXN<9>")
	)
	(segment
		(start 365.287814 -125.075442)
		(end 364.881414 -125.481842)
		(width 0.1143)
		(layer "B.Cu")
		(net "P3E_CPU0_PE1_PCH_RXN<9>")
	)
	(segment
		(start 367.827814 -125.227842)
		(end 367.675414 -125.075442)
		(width 0.1143)
		(layer "B.Cu")
		(net "P3E_CPU0_PE1_PCH_RXN<9>")
	)
	(segment
		(start 337.622642 -120.163336)
		(end 336.555334 -119.925846)
		(width 0.1143)
		(layer "In2.Cu")
		(net "P3E_CPU0_PE1_PCH_RXN<9>")
	)
	(segment
		(start 300.110652 -97.605088)
		(end 300.077886 -97.605088)
		(width 0.0889)
		(layer "In2.Cu")
		(net "P3E_CPU0_PE1_PCH_RXN<9>")
	)
	(segment
		(start 299.61967 -97.364804)
		(end 299.530262 -97.340674)
		(width 0.0889)
		(layer "In2.Cu")
		(net "P3E_CPU0_PE1_PCH_RXN<9>")
	)
	(segment
		(start 302.363886 -98.81108)
		(end 302.148494 -98.595688)
		(width 0.0889)
		(layer "In2.Cu")
		(net "P3E_CPU0_PE1_PCH_RXN<9>")
	)
	(segment
		(start 329.526646 -115.27028)
		(end 328.276204 -110.631224)
		(width 0.1143)
		(layer "In2.Cu")
		(net "P3E_CPU0_PE1_PCH_RXN<9>")
	)
	(segment
		(start 306.71643 -97.590864)
		(end 306.047394 -98.2599)
		(width 0.0889)
		(layer "In2.Cu")
		(net "P3E_CPU0_PE1_PCH_RXN<9>")
	)
	(segment
		(start 330.94549 -119.424704)
		(end 329.912218 -119.186198)
		(width 0.1143)
		(layer "In2.Cu")
		(net "P3E_CPU0_PE1_PCH_RXN<9>")
	)
	(segment
		(start 329.912218 -119.186198)
		(end 329.392788 -118.667022)
		(width 0.1143)
		(layer "In2.Cu")
		(net "P3E_CPU0_PE1_PCH_RXN<9>")
	)
	(segment
		(start 363.694472 -125.081792)
		(end 362.826808 -124.214128)
		(width 0.1143)
		(layer "In2.Cu")
		(net "P3E_CPU0_PE1_PCH_RXN<9>")
	)
	(segment
		(start 323.434456 -107.952032)
		(end 314.241434 -102.184962)
		(width 0.1143)
		(layer "In2.Cu")
		(net "P3E_CPU0_PE1_PCH_RXN<9>")
	)
	(segment
		(start 360.750612 -120.66778)
		(end 358.340152 -120.155716)
		(width 0.1143)
		(layer "In2.Cu")
		(net "P3E_CPU0_PE1_PCH_RXN<9>")
	)
	(segment
		(start 329.042776 -117.190774)
		(end 329.526646 -115.27028)
		(width 0.1143)
		(layer "In2.Cu")
		(net "P3E_CPU0_PE1_PCH_RXN<9>")
	)
	(segment
		(start 343.088976 -118.603268)
		(end 341.1093 -118.999254)
		(width 0.1143)
		(layer "In2.Cu")
		(net "P3E_CPU0_PE1_PCH_RXN<9>")
	)
	(segment
		(start 300.965362 -98.100134)
		(end 300.932596 -98.100134)
		(width 0.0889)
		(layer "In2.Cu")
		(net "P3E_CPU0_PE1_PCH_RXN<9>")
	)
	(segment
		(start 327.786238 -109.961426)
		(end 323.434456 -107.952032)
		(width 0.1143)
		(layer "In2.Cu")
		(net "P3E_CPU0_PE1_PCH_RXN<9>")
	)
	(segment
		(start 299.530262 -97.340674)
		(end 299.237146 -97.509584)
		(width 0.0889)
		(layer "In2.Cu")
		(net "P3E_CPU0_PE1_PCH_RXN<9>")
	)
	(segment
		(start 336.555334 -119.925846)
		(end 335.983326 -119.447818)
		(width 0.1143)
		(layer "In2.Cu")
		(net "P3E_CPU0_PE1_PCH_RXN<9>")
	)
	(segment
		(start 306.047394 -98.2599)
		(end 305.285394 -98.2599)
		(width 0.0889)
		(layer "In2.Cu")
		(net "P3E_CPU0_PE1_PCH_RXN<9>")
	)
	(segment
		(start 314.241434 -102.184962)
		(end 312.349642 -99.579176)
		(width 0.1143)
		(layer "In2.Cu")
		(net "P3E_CPU0_PE1_PCH_RXN<9>")
	)
	(segment
		(start 307.899562 -97.590864)
		(end 306.71643 -97.590864)
		(width 0.0889)
		(layer "In2.Cu")
		(net "P3E_CPU0_PE1_PCH_RXN<9>")
	)
	(segment
		(start 364.881414 -125.583442)
		(end 364.881414 -125.196092)
		(width 0.1143)
		(layer "In2.Cu")
		(net "P3E_CPU0_PE1_PCH_RXN<9>")
	)
	(segment
		(start 309.123842 -97.641664)
		(end 307.97246 -97.641664)
		(width 0.1143)
		(layer "In2.Cu")
		(net "P3E_CPU0_PE1_PCH_RXN<9>")
	)
	(segment
		(start 302.148494 -98.595688)
		(end 301.79899 -98.595688)
		(width 0.0889)
		(layer "In2.Cu")
		(net "P3E_CPU0_PE1_PCH_RXN<9>")
	)
	(segment
		(start 340.113366 -119.666004)
		(end 337.622642 -120.163336)
		(width 0.1143)
		(layer "In2.Cu")
		(net "P3E_CPU0_PE1_PCH_RXN<9>")
	)
	(segment
		(start 312.349642 -99.579176)
		(end 309.123842 -97.641664)
		(width 0.1143)
		(layer "In2.Cu")
		(net "P3E_CPU0_PE1_PCH_RXN<9>")
	)
	(segment
		(start 328.276458 -110.631224)
		(end 327.786238 -109.961426)
		(width 0.1143)
		(layer "In2.Cu")
		(net "P3E_CPU0_PE1_PCH_RXN<9>")
	)
	(segment
		(start 358.340152 -120.155716)
		(end 354.595938 -120.904762)
		(width 0.1143)
		(layer "In2.Cu")
		(net "P3E_CPU0_PE1_PCH_RXN<9>")
	)
	(segment
		(start 364.767114 -125.081792)
		(end 363.694472 -125.081792)
		(width 0.1143)
		(layer "In2.Cu")
		(net "P3E_CPU0_PE1_PCH_RXN<9>")
	)
	(segment
		(start 307.950362 -97.641664)
		(end 307.899562 -97.590864)
		(width 0.0889)
		(layer "In2.Cu")
		(net "P3E_CPU0_PE1_PCH_RXN<9>")
	)
	(segment
		(start 362.826808 -124.214128)
		(end 360.750612 -120.66778)
		(width 0.1143)
		(layer "In2.Cu")
		(net "P3E_CPU0_PE1_PCH_RXN<9>")
	)
	(segment
		(start 341.1093 -118.999254)
		(end 340.113366 -119.666004)
		(width 0.1143)
		(layer "In2.Cu")
		(net "P3E_CPU0_PE1_PCH_RXN<9>")
	)
	(segment
		(start 307.97246 -97.641664)
		(end 307.950362 -97.641664)
		(width 0.0889)
		(layer "In2.Cu")
		(net "P3E_CPU0_PE1_PCH_RXN<9>")
	)
	(segment
		(start 333.05242 -119.003064)
		(end 330.94549 -119.424704)
		(width 0.1143)
		(layer "In2.Cu")
		(net "P3E_CPU0_PE1_PCH_RXN<9>")
	)
	(segment
		(start 328.276204 -110.631224)
		(end 328.276458 -110.631224)
		(width 0.1143)
		(layer "In2.Cu")
		(net "P3E_CPU0_PE1_PCH_RXN<9>")
	)
	(segment
		(start 354.595938 -120.904762)
		(end 343.088976 -118.603268)
		(width 0.1143)
		(layer "In2.Cu")
		(net "P3E_CPU0_PE1_PCH_RXN<9>")
	)
	(segment
		(start 304.734214 -98.81108)
		(end 302.363886 -98.81108)
		(width 0.0889)
		(layer "In2.Cu")
		(net "P3E_CPU0_PE1_PCH_RXN<9>")
	)
	(segment
		(start 335.983326 -119.447818)
		(end 333.05242 -119.003064)
		(width 0.1143)
		(layer "In2.Cu")
		(net "P3E_CPU0_PE1_PCH_RXN<9>")
	)
	(segment
		(start 305.285394 -98.2599)
		(end 304.734214 -98.81108)
		(width 0.0889)
		(layer "In2.Cu")
		(net "P3E_CPU0_PE1_PCH_RXN<9>")
	)
	(segment
		(start 329.392788 -118.667022)
		(end 329.042776 -117.190774)
		(width 0.1143)
		(layer "In2.Cu")
		(net "P3E_CPU0_PE1_PCH_RXN<9>")
	)
	(segment
		(start 364.881414 -125.196092)
		(end 364.767114 -125.081792)
		(width 0.1143)
		(layer "In2.Cu")
		(net "P3E_CPU0_PE1_PCH_RXN<9>")
	)
	(arc
		(start 301.300896 -98.300286)
		(mid 301.159213 -98.156482)
		(end 300.965362 -98.100134)
		(width 0.0889)
		(layer "In2.Cu")
		(net "P3E_CPU0_PE1_PCH_RXN<9>")
	)
	(arc
		(start 300.932596 -98.100134)
		(mid 300.649379 -98.015853)
		(end 300.442376 -97.804986)
		(width 0.0889)
		(layer "In2.Cu")
		(net "P3E_CPU0_PE1_PCH_RXN<9>")
	)
	(arc
		(start 300.442376 -97.804986)
		(mid 300.302297 -97.66225)
		(end 300.110652 -97.605088)
		(width 0.0889)
		(layer "In2.Cu")
		(net "P3E_CPU0_PE1_PCH_RXN<9>")
	)
	(arc
		(start 301.79899 -98.595688)
		(mid 301.511303 -98.513167)
		(end 301.300896 -98.300286)
		(width 0.0889)
		(layer "In2.Cu")
		(net "P3E_CPU0_PE1_PCH_RXN<9>")
	)
	(arc
		(start 300.077886 -97.605088)
		(mid 299.821064 -97.537787)
		(end 299.61967 -97.364804)
		(width 0.0889)
		(layer "In2.Cu")
		(net "P3E_CPU0_PE1_PCH_RXN<9>")
	)
	(segment
		(start 298.665646 -96.518984)
		(end 299.237146 -96.518984)
		(width 0.1143)
		(layer "F.Cu")
		(net "P3E_CPU0_PE1_PCH_RXN<8>")
	)
	(via
		(at 299.237146 -96.518984)
		(size 0.508)
		(drill 0.254)
		(layers "F.Cu" "B.Cu")
		(net "P3E_CPU0_PE1_PCH_RXN<8>")
	)
	(via
		(at 364.8964 -122.6566)
		(size 0.508)
		(drill 0.254)
		(layers "F.Cu" "B.Cu")
		(net "P3E_CPU0_PE1_PCH_RXN<8>")
	)
	(segment
		(start 367.820956 -122.560842)
		(end 367.820956 -122.294396)
		(width 0.1143)
		(layer "B.Cu")
		(net "P3E_CPU0_PE1_PCH_RXN<8>")
	)
	(segment
		(start 365.429292 -122.123708)
		(end 364.8964 -122.6566)
		(width 0.1143)
		(layer "B.Cu")
		(net "P3E_CPU0_PE1_PCH_RXN<8>")
	)
	(segment
		(start 367.820956 -122.294396)
		(end 367.650268 -122.123708)
		(width 0.1143)
		(layer "B.Cu")
		(net "P3E_CPU0_PE1_PCH_RXN<8>")
	)
	(segment
		(start 367.650268 -122.123708)
		(end 365.429292 -122.123708)
		(width 0.1143)
		(layer "B.Cu")
		(net "P3E_CPU0_PE1_PCH_RXN<8>")
	)
	(segment
		(start 340.569804 -114.4524)
		(end 338.766404 -114.4524)
		(width 0.1143)
		(layer "In2.Cu")
		(net "P3E_CPU0_PE1_PCH_RXN<8>")
	)
	(segment
		(start 307.350414 -96.64446)
		(end 307.299614 -96.59366)
		(width 0.0889)
		(layer "In2.Cu")
		(net "P3E_CPU0_PE1_PCH_RXN<8>")
	)
	(segment
		(start 301.827692 -97.605088)
		(end 301.794926 -97.605088)
		(width 0.0889)
		(layer "In2.Cu")
		(net "P3E_CPU0_PE1_PCH_RXN<8>")
	)
	(segment
		(start 299.295058 -96.122998)
		(end 299.237146 -96.18091)
		(width 0.0889)
		(layer "In2.Cu")
		(net "P3E_CPU0_PE1_PCH_RXN<8>")
	)
	(segment
		(start 338.766404 -114.4524)
		(end 337.07959 -114.00282)
		(width 0.1143)
		(layer "In2.Cu")
		(net "P3E_CPU0_PE1_PCH_RXN<8>")
	)
	(segment
		(start 341.22614 -115.333526)
		(end 341.225886 -115.333272)
		(width 0.1143)
		(layer "In2.Cu")
		(net "P3E_CPU0_PE1_PCH_RXN<8>")
	)
	(segment
		(start 304.599594 -98.1583)
		(end 304.16246 -98.1583)
		(width 0.0889)
		(layer "In2.Cu")
		(net "P3E_CPU0_PE1_PCH_RXN<8>")
	)
	(segment
		(start 344.025474 -118.079012)
		(end 341.972646 -116.711476)
		(width 0.1143)
		(layer "In2.Cu")
		(net "P3E_CPU0_PE1_PCH_RXN<8>")
	)
	(segment
		(start 357.829104 -119.314722)
		(end 353.984814 -120.131332)
		(width 0.1143)
		(layer "In2.Cu")
		(net "P3E_CPU0_PE1_PCH_RXN<8>")
	)
	(segment
		(start 341.972646 -116.711476)
		(end 341.479378 -115.971828)
		(width 0.1143)
		(layer "In2.Cu")
		(net "P3E_CPU0_PE1_PCH_RXN<8>")
	)
	(segment
		(start 340.97214 -114.694462)
		(end 340.569804 -114.4524)
		(width 0.1143)
		(layer "In2.Cu")
		(net "P3E_CPU0_PE1_PCH_RXN<8>")
	)
	(segment
		(start 341.479378 -115.971828)
		(end 341.22614 -115.333526)
		(width 0.1143)
		(layer "In2.Cu")
		(net "P3E_CPU0_PE1_PCH_RXN<8>")
	)
	(segment
		(start 299.237146 -96.18091)
		(end 299.237146 -96.518984)
		(width 0.0889)
		(layer "In2.Cu")
		(net "P3E_CPU0_PE1_PCH_RXN<8>")
	)
	(segment
		(start 328.223118 -109.16539)
		(end 323.797422 -107.176062)
		(width 0.1143)
		(layer "In2.Cu")
		(net "P3E_CPU0_PE1_PCH_RXN<8>")
	)
	(segment
		(start 305.897788 -97.55505)
		(end 305.202844 -97.55505)
		(width 0.0889)
		(layer "In2.Cu")
		(net "P3E_CPU0_PE1_PCH_RXN<8>")
	)
	(segment
		(start 305.202844 -97.55505)
		(end 304.599594 -98.1583)
		(width 0.0889)
		(layer "In2.Cu")
		(net "P3E_CPU0_PE1_PCH_RXN<8>")
	)
	(segment
		(start 341.225886 -115.333272)
		(end 340.97214 -114.694462)
		(width 0.1143)
		(layer "In2.Cu")
		(net "P3E_CPU0_PE1_PCH_RXN<8>")
	)
	(segment
		(start 300.965362 -97.109534)
		(end 300.932596 -97.109534)
		(width 0.0889)
		(layer "In2.Cu")
		(net "P3E_CPU0_PE1_PCH_RXN<8>")
	)
	(segment
		(start 364.73003 -122.16003)
		(end 363.322616 -122.16003)
		(width 0.1143)
		(layer "In2.Cu")
		(net "P3E_CPU0_PE1_PCH_RXN<8>")
	)
	(segment
		(start 307.372512 -96.64446)
		(end 307.350414 -96.64446)
		(width 0.0889)
		(layer "In2.Cu")
		(net "P3E_CPU0_PE1_PCH_RXN<8>")
	)
	(segment
		(start 364.8964 -122.6566)
		(end 364.8964 -122.3264)
		(width 0.1143)
		(layer "In2.Cu")
		(net "P3E_CPU0_PE1_PCH_RXN<8>")
	)
	(segment
		(start 323.797422 -107.176062)
		(end 314.886086 -101.585522)
		(width 0.1143)
		(layer "In2.Cu")
		(net "P3E_CPU0_PE1_PCH_RXN<8>")
	)
	(segment
		(start 353.984814 -120.131332)
		(end 344.025474 -118.079012)
		(width 0.1143)
		(layer "In2.Cu")
		(net "P3E_CPU0_PE1_PCH_RXN<8>")
	)
	(segment
		(start 364.8964 -122.3264)
		(end 364.73003 -122.16003)
		(width 0.1143)
		(layer "In2.Cu")
		(net "P3E_CPU0_PE1_PCH_RXN<8>")
	)
	(segment
		(start 304.16246 -98.1583)
		(end 303.96815 -97.964244)
		(width 0.0889)
		(layer "In2.Cu")
		(net "P3E_CPU0_PE1_PCH_RXN<8>")
	)
	(segment
		(start 330.73213 -112.741202)
		(end 330.73213 -111.674148)
		(width 0.1143)
		(layer "In2.Cu")
		(net "P3E_CPU0_PE1_PCH_RXN<8>")
	)
	(segment
		(start 335.726024 -114.30762)
		(end 331.250544 -113.25987)
		(width 0.1143)
		(layer "In2.Cu")
		(net "P3E_CPU0_PE1_PCH_RXN<8>")
	)
	(segment
		(start 331.250544 -113.25987)
		(end 330.73213 -112.741202)
		(width 0.1143)
		(layer "In2.Cu")
		(net "P3E_CPU0_PE1_PCH_RXN<8>")
	)
	(segment
		(start 307.299614 -96.59366)
		(end 306.859178 -96.59366)
		(width 0.0889)
		(layer "In2.Cu")
		(net "P3E_CPU0_PE1_PCH_RXN<8>")
	)
	(segment
		(start 337.07959 -114.00282)
		(end 335.726024 -114.30762)
		(width 0.1143)
		(layer "In2.Cu")
		(net "P3E_CPU0_PE1_PCH_RXN<8>")
	)
	(segment
		(start 363.322616 -122.16003)
		(end 361.191302 -120.028716)
		(width 0.1143)
		(layer "In2.Cu")
		(net "P3E_CPU0_PE1_PCH_RXN<8>")
	)
	(segment
		(start 361.191302 -120.028716)
		(end 357.829104 -119.314722)
		(width 0.1143)
		(layer "In2.Cu")
		(net "P3E_CPU0_PE1_PCH_RXN<8>")
	)
	(segment
		(start 300.110652 -96.614488)
		(end 300.077886 -96.614488)
		(width 0.0889)
		(layer "In2.Cu")
		(net "P3E_CPU0_PE1_PCH_RXN<8>")
	)
	(segment
		(start 309.283862 -96.64446)
		(end 307.372512 -96.64446)
		(width 0.1143)
		(layer "In2.Cu")
		(net "P3E_CPU0_PE1_PCH_RXN<8>")
	)
	(segment
		(start 303.96815 -97.964244)
		(end 303.876456 -97.804986)
		(width 0.0889)
		(layer "In2.Cu")
		(net "P3E_CPU0_PE1_PCH_RXN<8>")
	)
	(segment
		(start 330.73213 -111.674148)
		(end 328.223118 -109.16539)
		(width 0.1143)
		(layer "In2.Cu")
		(net "P3E_CPU0_PE1_PCH_RXN<8>")
	)
	(segment
		(start 302.692816 -98.100134)
		(end 302.649636 -98.100134)
		(width 0.0889)
		(layer "In2.Cu")
		(net "P3E_CPU0_PE1_PCH_RXN<8>")
	)
	(segment
		(start 306.859178 -96.59366)
		(end 305.897788 -97.55505)
		(width 0.0889)
		(layer "In2.Cu")
		(net "P3E_CPU0_PE1_PCH_RXN<8>")
	)
	(segment
		(start 314.886086 -101.585522)
		(end 312.85688 -98.79076)
		(width 0.1143)
		(layer "In2.Cu")
		(net "P3E_CPU0_PE1_PCH_RXN<8>")
	)
	(segment
		(start 312.85688 -98.79076)
		(end 309.283862 -96.64446)
		(width 0.1143)
		(layer "In2.Cu")
		(net "P3E_CPU0_PE1_PCH_RXN<8>")
	)
	(segment
		(start 303.547272 -97.605088)
		(end 303.51476 -97.605088)
		(width 0.0889)
		(layer "In2.Cu")
		(net "P3E_CPU0_PE1_PCH_RXN<8>")
	)
	(arc
		(start 303.183036 -97.804986)
		(mid 302.976032 -98.01585)
		(end 302.692816 -98.100134)
		(width 0.0889)
		(layer "In2.Cu")
		(net "P3E_CPU0_PE1_PCH_RXN<8>")
	)
	(arc
		(start 299.583856 -96.319086)
		(mid 299.461965 -96.18789)
		(end 299.295058 -96.122998)
		(width 0.0889)
		(layer "In2.Cu")
		(net "P3E_CPU0_PE1_PCH_RXN<8>")
	)
	(arc
		(start 301.300896 -97.309686)
		(mid 301.159213 -97.165882)
		(end 300.965362 -97.109534)
		(width 0.0889)
		(layer "In2.Cu")
		(net "P3E_CPU0_PE1_PCH_RXN<8>")
	)
	(arc
		(start 303.51476 -97.605088)
		(mid 303.323118 -97.662254)
		(end 303.183036 -97.804986)
		(width 0.0889)
		(layer "In2.Cu")
		(net "P3E_CPU0_PE1_PCH_RXN<8>")
	)
	(arc
		(start 302.649636 -98.100134)
		(mid 302.366419 -98.015853)
		(end 302.159416 -97.804986)
		(width 0.0889)
		(layer "In2.Cu")
		(net "P3E_CPU0_PE1_PCH_RXN<8>")
	)
	(arc
		(start 302.159416 -97.804986)
		(mid 302.019337 -97.66225)
		(end 301.827692 -97.605088)
		(width 0.0889)
		(layer "In2.Cu")
		(net "P3E_CPU0_PE1_PCH_RXN<8>")
	)
	(arc
		(start 300.442376 -96.814386)
		(mid 300.302297 -96.67165)
		(end 300.110652 -96.614488)
		(width 0.0889)
		(layer "In2.Cu")
		(net "P3E_CPU0_PE1_PCH_RXN<8>")
	)
	(arc
		(start 300.077886 -96.614488)
		(mid 299.792462 -96.531021)
		(end 299.583856 -96.319086)
		(width 0.0889)
		(layer "In2.Cu")
		(net "P3E_CPU0_PE1_PCH_RXN<8>")
	)
	(arc
		(start 303.876456 -97.804986)
		(mid 303.737463 -97.662906)
		(end 303.547272 -97.605088)
		(width 0.0889)
		(layer "In2.Cu")
		(net "P3E_CPU0_PE1_PCH_RXN<8>")
	)
	(arc
		(start 300.932596 -97.109534)
		(mid 300.649379 -97.025253)
		(end 300.442376 -96.814386)
		(width 0.0889)
		(layer "In2.Cu")
		(net "P3E_CPU0_PE1_PCH_RXN<8>")
	)
	(arc
		(start 301.794926 -97.605088)
		(mid 301.509502 -97.521621)
		(end 301.300896 -97.309686)
		(width 0.0889)
		(layer "In2.Cu")
		(net "P3E_CPU0_PE1_PCH_RXN<8>")
	)
	(segment
		(start 380.30785 -120.15724)
		(end 380.80315 -120.387364)
		(width 0.1143)
		(layer "F.Cu")
		(net "P3E_CPU0_PE1_PCH_RXN<7>")
	)
	(via
		(at 380.80315 -120.387364)
		(size 0.508)
		(drill 0.254)
		(layers "F.Cu" "B.Cu")
		(net "P3E_CPU0_PE1_PCH_RXN<7>")
	)
	(via
		(at 351.147888 -65.067688)
		(size 0.508)
		(drill 0.254)
		(layers "F.Cu" "B.Cu")
		(net "P3E_CPU0_PE1_PCH_RXN<7>")
	)
	(via
		(at 350.781874 -67.4624)
		(size 0.508)
		(drill 0.254)
		(layers "F.Cu" "B.Cu")
		(net "P3E_CPU0_PE1_PCH_RXN<7>")
	)
	(segment
		(start 351.147888 -65.067688)
		(end 353.675442 -62.540134)
		(width 0.1143)
		(layer "B.Cu")
		(net "P3E_CPU0_PE1_PCH_RXN<7>")
	)
	(segment
		(start 353.675442 -62.540134)
		(end 353.675442 -61.883798)
		(width 0.1143)
		(layer "B.Cu")
		(net "P3E_CPU0_PE1_PCH_RXN<7>")
	)
	(segment
		(start 350.781874 -67.4624)
		(end 350.457008 -67.137534)
		(width 0.1143)
		(layer "B.Cu")
		(net "P3E_CPU0_PE1_PCH_RXN<7>")
	)
	(segment
		(start 353.675442 -61.883798)
		(end 354.301806 -61.257434)
		(width 0.1143)
		(layer "B.Cu")
		(net "P3E_CPU0_PE1_PCH_RXN<7>")
	)
	(segment
		(start 350.457008 -65.758568)
		(end 351.147888 -65.067688)
		(width 0.1143)
		(layer "B.Cu")
		(net "P3E_CPU0_PE1_PCH_RXN<7>")
	)
	(segment
		(start 350.457008 -67.137534)
		(end 350.457008 -65.758568)
		(width 0.1143)
		(layer "B.Cu")
		(net "P3E_CPU0_PE1_PCH_RXN<7>")
	)
	(segment
		(start 330.016866 -104.171242)
		(end 330.698602 -107.353354)
		(width 0.1143)
		(layer "In2.Cu")
		(net "P3E_CPU0_PE1_PCH_RXN<7>")
	)
	(segment
		(start 331.785976 -67.53225)
		(end 330.163932 -66.949828)
		(width 0.1143)
		(layer "In2.Cu")
		(net "P3E_CPU0_PE1_PCH_RXN<7>")
	)
	(segment
		(start 375.49328 -122.53468)
		(end 375.92 -122.9614)
		(width 0.0889)
		(layer "In2.Cu")
		(net "P3E_CPU0_PE1_PCH_RXN<7>")
	)
	(segment
		(start 331.9907 -110.6297)
		(end 332.728824 -111.367824)
		(width 0.1143)
		(layer "In2.Cu")
		(net "P3E_CPU0_PE1_PCH_RXN<7>")
	)
	(segment
		(start 342.465152 -114.346482)
		(end 343.193116 -114.488214)
		(width 0.1143)
		(layer "In2.Cu")
		(net "P3E_CPU0_PE1_PCH_RXN<7>")
	)
	(segment
		(start 381.889 -121.267474)
		(end 381.889 -121.224294)
		(width 0.0889)
		(layer "In2.Cu")
		(net "P3E_CPU0_PE1_PCH_RXN<7>")
	)
	(segment
		(start 350.04248 -65.093596)
		(end 339.911436 -65.093596)
		(width 0.1143)
		(layer "In2.Cu")
		(net "P3E_CPU0_PE1_PCH_RXN<7>")
	)
	(segment
		(start 361.371642 -118.63324)
		(end 365.482378 -120.085104)
		(width 0.1143)
		(layer "In2.Cu")
		(net "P3E_CPU0_PE1_PCH_RXN<7>")
	)
	(segment
		(start 378.621798 -123.474734)
		(end 378.622052 -123.474734)
		(width 0.0889)
		(layer "In2.Cu")
		(net "P3E_CPU0_PE1_PCH_RXN<7>")
	)
	(segment
		(start 350.446594 -65.49771)
		(end 350.04248 -65.093596)
		(width 0.1143)
		(layer "In2.Cu")
		(net "P3E_CPU0_PE1_PCH_RXN<7>")
	)
	(segment
		(start 332.728824 -111.367824)
		(end 334.241902 -111.367824)
		(width 0.1143)
		(layer "In2.Cu")
		(net "P3E_CPU0_PE1_PCH_RXN<7>")
	)
	(segment
		(start 370.911374 -122.58548)
		(end 370.962174 -122.53468)
		(width 0.0889)
		(layer "In2.Cu")
		(net "P3E_CPU0_PE1_PCH_RXN<7>")
	)
	(segment
		(start 339.388196 -65.616836)
		(end 337.053428 -65.616836)
		(width 0.1143)
		(layer "In2.Cu")
		(net "P3E_CPU0_PE1_PCH_RXN<7>")
	)
	(segment
		(start 341.818214 -113.911634)
		(end 342.465152 -114.346482)
		(width 0.1143)
		(layer "In2.Cu")
		(net "P3E_CPU0_PE1_PCH_RXN<7>")
	)
	(segment
		(start 336.573876 -111.820706)
		(end 337.001866 -112.10925)
		(width 0.1143)
		(layer "In2.Cu")
		(net "P3E_CPU0_PE1_PCH_RXN<7>")
	)
	(segment
		(start 379.9078 -122.984514)
		(end 379.9078 -122.951748)
		(width 0.0889)
		(layer "In2.Cu")
		(net "P3E_CPU0_PE1_PCH_RXN<7>")
	)
	(segment
		(start 336.592418 -66.077846)
		(end 335.151222 -66.077846)
		(width 0.1143)
		(layer "In2.Cu")
		(net "P3E_CPU0_PE1_PCH_RXN<7>")
	)
	(segment
		(start 332.520036 -67.314318)
		(end 331.785976 -67.53225)
		(width 0.1143)
		(layer "In2.Cu")
		(net "P3E_CPU0_PE1_PCH_RXN<7>")
	)
	(segment
		(start 354.618544 -118.79453)
		(end 358.408478 -118.057676)
		(width 0.1143)
		(layer "In2.Cu")
		(net "P3E_CPU0_PE1_PCH_RXN<7>")
	)
	(segment
		(start 380.97206 -120.68048)
		(end 380.80315 -120.387364)
		(width 0.0889)
		(layer "In2.Cu")
		(net "P3E_CPU0_PE1_PCH_RXN<7>")
	)
	(segment
		(start 369.73002 -122.585734)
		(end 369.730274 -122.58548)
		(width 0.1143)
		(layer "In2.Cu")
		(net "P3E_CPU0_PE1_PCH_RXN<7>")
	)
	(segment
		(start 341.096346 -113.233454)
		(end 341.582248 -113.561368)
		(width 0.1143)
		(layer "In2.Cu")
		(net "P3E_CPU0_PE1_PCH_RXN<7>")
	)
	(segment
		(start 329.9206 -97.7646)
		(end 330.591414 -101.215698)
		(width 0.1143)
		(layer "In2.Cu")
		(net "P3E_CPU0_PE1_PCH_RXN<7>")
	)
	(segment
		(start 330.163932 -66.949828)
		(end 329.632818 -67.138042)
		(width 0.1143)
		(layer "In2.Cu")
		(net "P3E_CPU0_PE1_PCH_RXN<7>")
	)
	(segment
		(start 358.408478 -118.057676)
		(end 361.371642 -118.63324)
		(width 0.1143)
		(layer "In2.Cu")
		(net "P3E_CPU0_PE1_PCH_RXN<7>")
	)
	(segment
		(start 330.698602 -107.353354)
		(end 331.9907 -108.356908)
		(width 0.1143)
		(layer "In2.Cu")
		(net "P3E_CPU0_PE1_PCH_RXN<7>")
	)
	(segment
		(start 328.34961 -68.662042)
		(end 326.463406 -75.980036)
		(width 0.1143)
		(layer "In2.Cu")
		(net "P3E_CPU0_PE1_PCH_RXN<7>")
	)
	(segment
		(start 327.663556 -82.05851)
		(end 330.848716 -87.164672)
		(width 0.1143)
		(layer "In2.Cu")
		(net "P3E_CPU0_PE1_PCH_RXN<7>")
	)
	(segment
		(start 330.57592 -94.393258)
		(end 329.9206 -97.7646)
		(width 0.1143)
		(layer "In2.Cu")
		(net "P3E_CPU0_PE1_PCH_RXN<7>")
	)
	(segment
		(start 377.292616 -122.9614)
		(end 377.723146 -123.39193)
		(width 0.0889)
		(layer "In2.Cu")
		(net "P3E_CPU0_PE1_PCH_RXN<7>")
	)
	(segment
		(start 340.738206 -113.163604)
		(end 341.095838 -113.233454)
		(width 0.1143)
		(layer "In2.Cu")
		(net "P3E_CPU0_PE1_PCH_RXN<7>")
	)
	(segment
		(start 381.061468 -120.704356)
		(end 380.97206 -120.68048)
		(width 0.0889)
		(layer "In2.Cu")
		(net "P3E_CPU0_PE1_PCH_RXN<7>")
	)
	(segment
		(start 370.962174 -122.53468)
		(end 375.49328 -122.53468)
		(width 0.0889)
		(layer "In2.Cu")
		(net "P3E_CPU0_PE1_PCH_RXN<7>")
	)
	(segment
		(start 335.151222 -66.077846)
		(end 332.520036 -67.314318)
		(width 0.1143)
		(layer "In2.Cu")
		(net "P3E_CPU0_PE1_PCH_RXN<7>")
	)
	(segment
		(start 370.889276 -122.58548)
		(end 370.911374 -122.58548)
		(width 0.0889)
		(layer "In2.Cu")
		(net "P3E_CPU0_PE1_PCH_RXN<7>")
	)
	(segment
		(start 350.446594 -67.12712)
		(end 350.446594 -65.49771)
		(width 0.1143)
		(layer "In2.Cu")
		(net "P3E_CPU0_PE1_PCH_RXN<7>")
	)
	(segment
		(start 365.482378 -120.085104)
		(end 369.73002 -122.585734)
		(width 0.1143)
		(layer "In2.Cu")
		(net "P3E_CPU0_PE1_PCH_RXN<7>")
	)
	(segment
		(start 345.953588 -115.824508)
		(end 346.575126 -116.243608)
		(width 0.1143)
		(layer "In2.Cu")
		(net "P3E_CPU0_PE1_PCH_RXN<7>")
	)
	(segment
		(start 343.193116 -114.488214)
		(end 344.85834 -115.611402)
		(width 0.1143)
		(layer "In2.Cu")
		(net "P3E_CPU0_PE1_PCH_RXN<7>")
	)
	(segment
		(start 341.095838 -113.233454)
		(end 341.096346 -113.233454)
		(width 0.1143)
		(layer "In2.Cu")
		(net "P3E_CPU0_PE1_PCH_RXN<7>")
	)
	(segment
		(start 347.78315 -117.465856)
		(end 354.618544 -118.79453)
		(width 0.1143)
		(layer "In2.Cu")
		(net "P3E_CPU0_PE1_PCH_RXN<7>")
	)
	(segment
		(start 347.079062 -116.990876)
		(end 347.78315 -117.465856)
		(width 0.1143)
		(layer "In2.Cu")
		(net "P3E_CPU0_PE1_PCH_RXN<7>")
	)
	(segment
		(start 334.241902 -111.367824)
		(end 336.573876 -111.820706)
		(width 0.1143)
		(layer "In2.Cu")
		(net "P3E_CPU0_PE1_PCH_RXN<7>")
	)
	(segment
		(start 344.85834 -115.611402)
		(end 345.953588 -115.824508)
		(width 0.1143)
		(layer "In2.Cu")
		(net "P3E_CPU0_PE1_PCH_RXN<7>")
	)
	(segment
		(start 350.781874 -67.4624)
		(end 350.446594 -67.12712)
		(width 0.1143)
		(layer "In2.Cu")
		(net "P3E_CPU0_PE1_PCH_RXN<7>")
	)
	(segment
		(start 330.591414 -101.215698)
		(end 330.016866 -104.171242)
		(width 0.1143)
		(layer "In2.Cu")
		(net "P3E_CPU0_PE1_PCH_RXN<7>")
	)
	(segment
		(start 330.848716 -87.164672)
		(end 330.010008 -91.48064)
		(width 0.1143)
		(layer "In2.Cu")
		(net "P3E_CPU0_PE1_PCH_RXN<7>")
	)
	(segment
		(start 346.575126 -116.243608)
		(end 347.079062 -116.990876)
		(width 0.1143)
		(layer "In2.Cu")
		(net "P3E_CPU0_PE1_PCH_RXN<7>")
	)
	(segment
		(start 330.010008 -91.48064)
		(end 330.57592 -94.393258)
		(width 0.1143)
		(layer "In2.Cu")
		(net "P3E_CPU0_PE1_PCH_RXN<7>")
	)
	(segment
		(start 380.4031 -122.125994)
		(end 380.4031 -122.093228)
		(width 0.0889)
		(layer "In2.Cu")
		(net "P3E_CPU0_PE1_PCH_RXN<7>")
	)
	(segment
		(start 337.001866 -112.10925)
		(end 337.0707 -112.178084)
		(width 0.1143)
		(layer "In2.Cu")
		(net "P3E_CPU0_PE1_PCH_RXN<7>")
	)
	(segment
		(start 375.92 -122.9614)
		(end 377.292616 -122.9614)
		(width 0.0889)
		(layer "In2.Cu")
		(net "P3E_CPU0_PE1_PCH_RXN<7>")
	)
	(segment
		(start 326.463406 -75.980036)
		(end 327.663556 -82.05851)
		(width 0.1143)
		(layer "In2.Cu")
		(net "P3E_CPU0_PE1_PCH_RXN<7>")
	)
	(segment
		(start 369.730274 -122.58548)
		(end 370.889276 -122.58548)
		(width 0.1143)
		(layer "In2.Cu")
		(net "P3E_CPU0_PE1_PCH_RXN<7>")
	)
	(segment
		(start 337.0707 -112.178084)
		(end 337.0707 -112.795558)
		(width 0.1143)
		(layer "In2.Cu")
		(net "P3E_CPU0_PE1_PCH_RXN<7>")
	)
	(segment
		(start 337.0707 -112.795558)
		(end 337.438746 -113.163604)
		(width 0.1143)
		(layer "In2.Cu")
		(net "P3E_CPU0_PE1_PCH_RXN<7>")
	)
	(segment
		(start 329.632818 -67.138042)
		(end 328.34961 -68.662042)
		(width 0.1143)
		(layer "In2.Cu")
		(net "P3E_CPU0_PE1_PCH_RXN<7>")
	)
	(segment
		(start 341.582248 -113.561368)
		(end 341.818214 -113.911634)
		(width 0.1143)
		(layer "In2.Cu")
		(net "P3E_CPU0_PE1_PCH_RXN<7>")
	)
	(segment
		(start 337.438746 -113.163604)
		(end 340.738206 -113.163604)
		(width 0.1143)
		(layer "In2.Cu")
		(net "P3E_CPU0_PE1_PCH_RXN<7>")
	)
	(segment
		(start 337.053428 -65.616836)
		(end 336.592418 -66.077846)
		(width 0.1143)
		(layer "In2.Cu")
		(net "P3E_CPU0_PE1_PCH_RXN<7>")
	)
	(segment
		(start 339.911436 -65.093596)
		(end 339.388196 -65.616836)
		(width 0.1143)
		(layer "In2.Cu")
		(net "P3E_CPU0_PE1_PCH_RXN<7>")
	)
	(segment
		(start 331.9907 -108.356908)
		(end 331.9907 -110.6297)
		(width 0.1143)
		(layer "In2.Cu")
		(net "P3E_CPU0_PE1_PCH_RXN<7>")
	)
	(arc
		(start 381.593852 -121.757694)
		(mid 381.804716 -121.55069)
		(end 381.889 -121.267474)
		(width 0.0889)
		(layer "In2.Cu")
		(net "P3E_CPU0_PE1_PCH_RXN<7>")
	)
	(arc
		(start 378.031248 -123.474734)
		(mid 378.32654 -123.553865)
		(end 378.621798 -123.474734)
		(width 0.0889)
		(layer "In2.Cu")
		(net "P3E_CPU0_PE1_PCH_RXN<7>")
	)
	(arc
		(start 379.021848 -123.474734)
		(mid 379.31725 -123.553865)
		(end 379.612652 -123.474734)
		(width 0.0889)
		(layer "In2.Cu")
		(net "P3E_CPU0_PE1_PCH_RXN<7>")
	)
	(arc
		(start 381.593852 -120.734074)
		(mid 381.331196 -120.655737)
		(end 381.061468 -120.704356)
		(width 0.0889)
		(layer "In2.Cu")
		(net "P3E_CPU0_PE1_PCH_RXN<7>")
	)
	(arc
		(start 379.9078 -122.951748)
		(mid 379.96415 -122.757898)
		(end 380.107952 -122.616214)
		(width 0.0889)
		(layer "In2.Cu")
		(net "P3E_CPU0_PE1_PCH_RXN<7>")
	)
	(arc
		(start 380.603252 -121.757694)
		(mid 380.80315 -121.704195)
		(end 381.003048 -121.757694)
		(width 0.0889)
		(layer "In2.Cu")
		(net "P3E_CPU0_PE1_PCH_RXN<7>")
	)
	(arc
		(start 381.889 -121.224294)
		(mid 381.804719 -120.941077)
		(end 381.593852 -120.734074)
		(width 0.0889)
		(layer "In2.Cu")
		(net "P3E_CPU0_PE1_PCH_RXN<7>")
	)
	(arc
		(start 380.4031 -122.093228)
		(mid 380.45945 -121.899378)
		(end 380.603252 -121.757694)
		(width 0.0889)
		(layer "In2.Cu")
		(net "P3E_CPU0_PE1_PCH_RXN<7>")
	)
	(arc
		(start 379.612652 -123.474734)
		(mid 379.823516 -123.26773)
		(end 379.9078 -122.984514)
		(width 0.0889)
		(layer "In2.Cu")
		(net "P3E_CPU0_PE1_PCH_RXN<7>")
	)
	(arc
		(start 378.622052 -123.474734)
		(mid 378.82195 -123.421235)
		(end 379.021848 -123.474734)
		(width 0.0889)
		(layer "In2.Cu")
		(net "P3E_CPU0_PE1_PCH_RXN<7>")
	)
	(arc
		(start 381.003048 -121.757694)
		(mid 381.29845 -121.836825)
		(end 381.593852 -121.757694)
		(width 0.0889)
		(layer "In2.Cu")
		(net "P3E_CPU0_PE1_PCH_RXN<7>")
	)
	(arc
		(start 377.723146 -123.39193)
		(mid 377.882665 -123.41299)
		(end 378.031248 -123.474734)
		(width 0.0889)
		(layer "In2.Cu")
		(net "P3E_CPU0_PE1_PCH_RXN<7>")
	)
	(arc
		(start 380.107952 -122.616214)
		(mid 380.318816 -122.40921)
		(end 380.4031 -122.125994)
		(width 0.0889)
		(layer "In2.Cu")
		(net "P3E_CPU0_PE1_PCH_RXN<7>")
	)
	(segment
		(start 377.83135 -121.01576)
		(end 378.32665 -121.245884)
		(width 0.1143)
		(layer "F.Cu")
		(net "P3E_CPU0_PE1_PCH_RXN<6>")
	)
	(via
		(at 348.445836 -66.824352)
		(size 0.508)
		(drill 0.254)
		(layers "F.Cu" "B.Cu")
		(net "P3E_CPU0_PE1_PCH_RXN<6>")
	)
	(via
		(at 378.32665 -121.245884)
		(size 0.508)
		(drill 0.254)
		(layers "F.Cu" "B.Cu")
		(net "P3E_CPU0_PE1_PCH_RXN<6>")
	)
	(via
		(at 346.151962 -67.44335)
		(size 0.508)
		(drill 0.254)
		(layers "F.Cu" "B.Cu")
		(net "P3E_CPU0_PE1_PCH_RXN<6>")
	)
	(segment
		(start 347.328236 -64.639444)
		(end 347.48978 -64.639444)
		(width 0.1143)
		(layer "B.Cu")
		(net "P3E_CPU0_PE1_PCH_RXN<6>")
	)
	(segment
		(start 348.446344 -63.68288)
		(end 348.446344 -63.521336)
		(width 0.1143)
		(layer "B.Cu")
		(net "P3E_CPU0_PE1_PCH_RXN<6>")
	)
	(segment
		(start 348.74454 -67.861942)
		(end 348.74454 -67.123056)
		(width 0.1143)
		(layer "B.Cu")
		(net "P3E_CPU0_PE1_PCH_RXN<6>")
	)
	(segment
		(start 349.228156 -64.464692)
		(end 348.446344 -63.68288)
		(width 0.1143)
		(layer "B.Cu")
		(net "P3E_CPU0_PE1_PCH_RXN<6>")
	)
	(segment
		(start 348.74454 -67.123056)
		(end 348.445836 -66.824352)
		(width 0.1143)
		(layer "B.Cu")
		(net "P3E_CPU0_PE1_PCH_RXN<6>")
	)
	(segment
		(start 347.48978 -64.639444)
		(end 348.271592 -65.421256)
		(width 0.1143)
		(layer "B.Cu")
		(net "P3E_CPU0_PE1_PCH_RXN<6>")
	)
	(segment
		(start 351.087182 -63.123826)
		(end 351.087182 -61.678058)
		(width 0.1143)
		(layer "B.Cu")
		(net "P3E_CPU0_PE1_PCH_RXN<6>")
	)
	(segment
		(start 346.875354 -65.25387)
		(end 346.875354 -65.092326)
		(width 0.1143)
		(layer "B.Cu")
		(net "P3E_CPU0_PE1_PCH_RXN<6>")
	)
	(segment
		(start 351.087182 -61.678058)
		(end 351.507806 -61.257434)
		(width 0.1143)
		(layer "B.Cu")
		(net "P3E_CPU0_PE1_PCH_RXN<6>")
	)
	(segment
		(start 350.282256 -63.928752)
		(end 351.087182 -63.123826)
		(width 0.1143)
		(layer "B.Cu")
		(net "P3E_CPU0_PE1_PCH_RXN<6>")
	)
	(segment
		(start 348.446344 -63.521336)
		(end 348.899226 -63.068454)
		(width 0.1143)
		(layer "B.Cu")
		(net "P3E_CPU0_PE1_PCH_RXN<6>")
	)
	(segment
		(start 349.228156 -64.82588)
		(end 349.228156 -64.464692)
		(width 0.1143)
		(layer "B.Cu")
		(net "P3E_CPU0_PE1_PCH_RXN<6>")
	)
	(segment
		(start 346.374212 -68.244212)
		(end 346.72016 -68.59016)
		(width 0.1143)
		(layer "B.Cu")
		(net "P3E_CPU0_PE1_PCH_RXN<6>")
	)
	(segment
		(start 348.271592 -65.421256)
		(end 348.63278 -65.421256)
		(width 0.1143)
		(layer "B.Cu")
		(net "P3E_CPU0_PE1_PCH_RXN<6>")
	)
	(segment
		(start 346.374212 -67.6656)
		(end 346.374212 -68.244212)
		(width 0.1143)
		(layer "B.Cu")
		(net "P3E_CPU0_PE1_PCH_RXN<6>")
	)
	(segment
		(start 348.63278 -65.421256)
		(end 349.228156 -64.82588)
		(width 0.1143)
		(layer "B.Cu")
		(net "P3E_CPU0_PE1_PCH_RXN<6>")
	)
	(segment
		(start 349.06077 -63.068454)
		(end 349.921068 -63.928752)
		(width 0.1143)
		(layer "B.Cu")
		(net "P3E_CPU0_PE1_PCH_RXN<6>")
	)
	(segment
		(start 346.151962 -67.44335)
		(end 346.374212 -67.6656)
		(width 0.1143)
		(layer "B.Cu")
		(net "P3E_CPU0_PE1_PCH_RXN<6>")
	)
	(segment
		(start 346.875354 -65.092326)
		(end 347.328236 -64.639444)
		(width 0.1143)
		(layer "B.Cu")
		(net "P3E_CPU0_PE1_PCH_RXN<6>")
	)
	(segment
		(start 348.899226 -63.068454)
		(end 349.06077 -63.068454)
		(width 0.1143)
		(layer "B.Cu")
		(net "P3E_CPU0_PE1_PCH_RXN<6>")
	)
	(segment
		(start 348.016322 -68.59016)
		(end 348.74454 -67.861942)
		(width 0.1143)
		(layer "B.Cu")
		(net "P3E_CPU0_PE1_PCH_RXN<6>")
	)
	(segment
		(start 349.921068 -63.928752)
		(end 350.282256 -63.928752)
		(width 0.1143)
		(layer "B.Cu")
		(net "P3E_CPU0_PE1_PCH_RXN<6>")
	)
	(segment
		(start 348.445836 -66.824352)
		(end 346.875354 -65.25387)
		(width 0.1143)
		(layer "B.Cu")
		(net "P3E_CPU0_PE1_PCH_RXN<6>")
	)
	(segment
		(start 346.72016 -68.59016)
		(end 348.016322 -68.59016)
		(width 0.1143)
		(layer "B.Cu")
		(net "P3E_CPU0_PE1_PCH_RXN<6>")
	)
	(segment
		(start 375.995184 -121.56948)
		(end 375.702322 -121.56948)
		(width 0.0889)
		(layer "In2.Cu")
		(net "P3E_CPU0_PE1_PCH_RXN<6>")
	)
	(segment
		(start 346.235782 -114.055398)
		(end 345.590368 -114.180874)
		(width 0.1143)
		(layer "In2.Cu")
		(net "P3E_CPU0_PE1_PCH_RXN<6>")
	)
	(segment
		(start 337.071208 -67.028314)
		(end 337.555586 -66.543936)
		(width 0.1143)
		(layer "In2.Cu")
		(net "P3E_CPU0_PE1_PCH_RXN<6>")
	)
	(segment
		(start 342.4301 -112.0521)
		(end 342.01227 -111.63427)
		(width 0.1143)
		(layer "In2.Cu")
		(net "P3E_CPU0_PE1_PCH_RXN<6>")
	)
	(segment
		(start 337.555586 -66.543936)
		(end 339.832696 -66.543936)
		(width 0.1143)
		(layer "In2.Cu")
		(net "P3E_CPU0_PE1_PCH_RXN<6>")
	)
	(segment
		(start 329.394058 -69.8119)
		(end 335.316322 -67.028314)
		(width 0.1143)
		(layer "In2.Cu")
		(net "P3E_CPU0_PE1_PCH_RXN<6>")
	)
	(segment
		(start 331.42809 -104.04983)
		(end 331.837538 -101.941884)
		(width 0.1143)
		(layer "In2.Cu")
		(net "P3E_CPU0_PE1_PCH_RXN<6>")
	)
	(segment
		(start 328.436478 -81.180178)
		(end 328.36993 -80.843882)
		(width 0.1143)
		(layer "In2.Cu")
		(net "P3E_CPU0_PE1_PCH_RXN<6>")
	)
	(segment
		(start 356.42423 -117.13083)
		(end 356.08768 -117.196362)
		(width 0.1143)
		(layer "In2.Cu")
		(net "P3E_CPU0_PE1_PCH_RXN<6>")
	)
	(segment
		(start 349.715836 -115.419378)
		(end 348.807278 -115.595908)
		(width 0.1143)
		(layer "In2.Cu")
		(net "P3E_CPU0_PE1_PCH_RXN<6>")
	)
	(segment
		(start 348.807278 -115.595908)
		(end 347.811852 -115.40236)
		(width 0.1143)
		(layer "In2.Cu")
		(net "P3E_CPU0_PE1_PCH_RXN<6>")
	)
	(segment
		(start 351.380806 -115.790218)
		(end 351.151444 -115.834922)
		(width 0.1143)
		(layer "In2.Cu")
		(net "P3E_CPU0_PE1_PCH_RXN<6>")
	)
	(segment
		(start 342.01227 -111.63427)
		(end 341.207598 -111.63427)
		(width 0.1143)
		(layer "In2.Cu")
		(net "P3E_CPU0_PE1_PCH_RXN<6>")
	)
	(segment
		(start 328.43343 -80.31353)
		(end 328.239628 -80.183482)
		(width 0.1143)
		(layer "In2.Cu")
		(net "P3E_CPU0_PE1_PCH_RXN<6>")
	)
	(segment
		(start 328.042524 -79.186786)
		(end 327.58126 -76.852526)
		(width 0.1143)
		(layer "In2.Cu")
		(net "P3E_CPU0_PE1_PCH_RXN<6>")
	)
	(segment
		(start 375.334022 -121.48058)
		(end 375.245122 -121.56948)
		(width 0.0889)
		(layer "In2.Cu")
		(net "P3E_CPU0_PE1_PCH_RXN<6>")
	)
	(segment
		(start 355.957124 -117.38991)
		(end 355.62032 -117.455442)
		(width 0.1143)
		(layer "In2.Cu")
		(net "P3E_CPU0_PE1_PCH_RXN<6>")
	)
	(segment
		(start 331.920596 -106.588306)
		(end 331.42809 -104.04983)
		(width 0.1143)
		(layer "In2.Cu")
		(net "P3E_CPU0_PE1_PCH_RXN<6>")
	)
	(segment
		(start 355.090222 -117.390164)
		(end 354.959666 -117.583712)
		(width 0.1143)
		(layer "In2.Cu")
		(net "P3E_CPU0_PE1_PCH_RXN<6>")
	)
	(segment
		(start 343.205816 -112.903)
		(end 342.773 -112.903)
		(width 0.1143)
		(layer "In2.Cu")
		(net "P3E_CPU0_PE1_PCH_RXN<6>")
	)
	(segment
		(start 344.902282 -114.04727)
		(end 343.205816 -112.903)
		(width 0.1143)
		(layer "In2.Cu")
		(net "P3E_CPU0_PE1_PCH_RXN<6>")
	)
	(segment
		(start 330.63815 -84.709762)
		(end 330.585318 -84.62518)
		(width 0.1143)
		(layer "In2.Cu")
		(net "P3E_CPU0_PE1_PCH_RXN<6>")
	)
	(segment
		(start 354.959666 -117.583712)
		(end 354.623116 -117.649244)
		(width 0.1143)
		(layer "In2.Cu")
		(net "P3E_CPU0_PE1_PCH_RXN<6>")
	)
	(segment
		(start 351.993962 -116.402866)
		(end 351.709482 -116.211096)
		(width 0.1143)
		(layer "In2.Cu")
		(net "P3E_CPU0_PE1_PCH_RXN<6>")
	)
	(segment
		(start 342.773 -112.903)
		(end 342.4301 -112.5601)
		(width 0.1143)
		(layer "In2.Cu")
		(net "P3E_CPU0_PE1_PCH_RXN<6>")
	)
	(segment
		(start 338.868766 -111.62919)
		(end 337.972654 -111.454946)
		(width 0.1143)
		(layer "In2.Cu")
		(net "P3E_CPU0_PE1_PCH_RXN<6>")
	)
	(segment
		(start 334.41513 -110.31855)
		(end 333.711804 -110.31855)
		(width 0.1143)
		(layer "In2.Cu")
		(net "P3E_CPU0_PE1_PCH_RXN<6>")
	)
	(segment
		(start 328.303128 -79.65313)
		(end 328.23658 -79.316834)
		(width 0.1143)
		(layer "In2.Cu")
		(net "P3E_CPU0_PE1_PCH_RXN<6>")
	)
	(segment
		(start 330.994258 -85.281008)
		(end 331.04709 -85.053678)
		(width 0.1143)
		(layer "In2.Cu")
		(net "P3E_CPU0_PE1_PCH_RXN<6>")
	)
	(segment
		(start 331.04455 -97.862136)
		(end 331.7113 -94.433136)
		(width 0.1143)
		(layer "In2.Cu")
		(net "P3E_CPU0_PE1_PCH_RXN<6>")
	)
	(segment
		(start 346.4433 -67.152012)
		(end 346.151962 -67.44335)
		(width 0.1143)
		(layer "In2.Cu")
		(net "P3E_CPU0_PE1_PCH_RXN<6>")
	)
	(segment
		(start 328.499978 -80.649826)
		(end 328.43343 -80.31353)
		(width 0.1143)
		(layer "In2.Cu")
		(net "P3E_CPU0_PE1_PCH_RXN<6>")
	)
	(segment
		(start 329.433936 -82.46745)
		(end 329.25258 -82.176366)
		(width 0.1143)
		(layer "In2.Cu")
		(net "P3E_CPU0_PE1_PCH_RXN<6>")
	)
	(segment
		(start 332.9051 -107.252262)
		(end 331.920596 -106.588306)
		(width 0.1143)
		(layer "In2.Cu")
		(net "P3E_CPU0_PE1_PCH_RXN<6>")
	)
	(segment
		(start 328.36993 -80.843882)
		(end 328.499978 -80.649826)
		(width 0.1143)
		(layer "In2.Cu")
		(net "P3E_CPU0_PE1_PCH_RXN<6>")
	)
	(segment
		(start 330.45654 -84.418932)
		(end 330.509372 -84.191602)
		(width 0.1143)
		(layer "In2.Cu")
		(net "P3E_CPU0_PE1_PCH_RXN<6>")
	)
	(segment
		(start 356.617778 -117.261386)
		(end 356.42423 -117.13083)
		(width 0.1143)
		(layer "In2.Cu")
		(net "P3E_CPU0_PE1_PCH_RXN<6>")
	)
	(segment
		(start 374.795542 -121.51868)
		(end 369.747038 -121.51868)
		(width 0.1143)
		(layer "In2.Cu")
		(net "P3E_CPU0_PE1_PCH_RXN<6>")
	)
	(segment
		(start 358.393746 -116.9162)
		(end 356.617778 -117.261386)
		(width 0.1143)
		(layer "In2.Cu")
		(net "P3E_CPU0_PE1_PCH_RXN<6>")
	)
	(segment
		(start 369.747038 -121.51868)
		(end 365.668814 -119.114824)
		(width 0.1143)
		(layer "In2.Cu")
		(net "P3E_CPU0_PE1_PCH_RXN<6>")
	)
	(segment
		(start 329.024996 -82.123534)
		(end 328.436478 -81.180178)
		(width 0.1143)
		(layer "In2.Cu")
		(net "P3E_CPU0_PE1_PCH_RXN<6>")
	)
	(segment
		(start 347.044264 -114.212624)
		(end 346.235782 -114.055398)
		(width 0.1143)
		(layer "In2.Cu")
		(net "P3E_CPU0_PE1_PCH_RXN<6>")
	)
	(segment
		(start 352.507296 -116.549932)
		(end 352.22307 -116.358416)
		(width 0.1143)
		(layer "In2.Cu")
		(net "P3E_CPU0_PE1_PCH_RXN<6>")
	)
	(segment
		(start 330.100432 -83.847686)
		(end 329.919076 -83.556856)
		(width 0.1143)
		(layer "In2.Cu")
		(net "P3E_CPU0_PE1_PCH_RXN<6>")
	)
	(segment
		(start 332.002892 -86.89848)
		(end 330.994258 -85.281008)
		(width 0.1143)
		(layer "In2.Cu")
		(net "P3E_CPU0_PE1_PCH_RXN<6>")
	)
	(segment
		(start 329.919076 -83.556856)
		(end 329.971654 -83.329526)
		(width 0.1143)
		(layer "In2.Cu")
		(net "P3E_CPU0_PE1_PCH_RXN<6>")
	)
	(segment
		(start 328.17308 -79.847186)
		(end 328.303128 -79.65313)
		(width 0.1143)
		(layer "In2.Cu")
		(net "P3E_CPU0_PE1_PCH_RXN<6>")
	)
	(segment
		(start 333.711804 -110.31855)
		(end 333.52105 -110.127796)
		(width 0.1143)
		(layer "In2.Cu")
		(net "P3E_CPU0_PE1_PCH_RXN<6>")
	)
	(segment
		(start 342.4301 -112.5601)
		(end 342.4301 -112.0521)
		(width 0.1143)
		(layer "In2.Cu")
		(net "P3E_CPU0_PE1_PCH_RXN<6>")
	)
	(segment
		(start 330.327762 -83.900518)
		(end 330.100432 -83.847686)
		(width 0.1143)
		(layer "In2.Cu")
		(net "P3E_CPU0_PE1_PCH_RXN<6>")
	)
	(segment
		(start 351.151444 -115.834922)
		(end 350.867218 -115.643152)
		(width 0.1143)
		(layer "In2.Cu")
		(net "P3E_CPU0_PE1_PCH_RXN<6>")
	)
	(segment
		(start 375.613422 -121.48058)
		(end 375.334022 -121.48058)
		(width 0.0889)
		(layer "In2.Cu")
		(net "P3E_CPU0_PE1_PCH_RXN<6>")
	)
	(segment
		(start 340.355936 -66.020696)
		(end 346.329 -66.020696)
		(width 0.1143)
		(layer "In2.Cu")
		(net "P3E_CPU0_PE1_PCH_RXN<6>")
	)
	(segment
		(start 331.7113 -94.433136)
		(end 331.124814 -91.417394)
		(width 0.1143)
		(layer "In2.Cu")
		(net "P3E_CPU0_PE1_PCH_RXN<6>")
	)
	(segment
		(start 354.623116 -117.649244)
		(end 353.525328 -117.43563)
		(width 0.1143)
		(layer "In2.Cu")
		(net "P3E_CPU0_PE1_PCH_RXN<6>")
	)
	(segment
		(start 328.23658 -79.316834)
		(end 328.042524 -79.186786)
		(width 0.1143)
		(layer "In2.Cu")
		(net "P3E_CPU0_PE1_PCH_RXN<6>")
	)
	(segment
		(start 350.867218 -115.643152)
		(end 349.715836 -115.419378)
		(width 0.1143)
		(layer "In2.Cu")
		(net "P3E_CPU0_PE1_PCH_RXN<6>")
	)
	(segment
		(start 377.241054 -121.764552)
		(end 376.190256 -121.764552)
		(width 0.0889)
		(layer "In2.Cu")
		(net "P3E_CPU0_PE1_PCH_RXN<6>")
	)
	(segment
		(start 347.43644 -114.570256)
		(end 347.323918 -114.400838)
		(width 0.1143)
		(layer "In2.Cu")
		(net "P3E_CPU0_PE1_PCH_RXN<6>")
	)
	(segment
		(start 375.702322 -121.56948)
		(end 375.613422 -121.48058)
		(width 0.0889)
		(layer "In2.Cu")
		(net "P3E_CPU0_PE1_PCH_RXN<6>")
	)
	(segment
		(start 351.665032 -115.981988)
		(end 351.380806 -115.790218)
		(width 0.1143)
		(layer "In2.Cu")
		(net "P3E_CPU0_PE1_PCH_RXN<6>")
	)
	(segment
		(start 374.81764 -121.51868)
		(end 374.795542 -121.51868)
		(width 0.0889)
		(layer "In2.Cu")
		(net "P3E_CPU0_PE1_PCH_RXN<6>")
	)
	(segment
		(start 333.52105 -108.165646)
		(end 332.9051 -107.252262)
		(width 0.1143)
		(layer "In2.Cu")
		(net "P3E_CPU0_PE1_PCH_RXN<6>")
	)
	(segment
		(start 355.426772 -117.324886)
		(end 355.090222 -117.390164)
		(width 0.1143)
		(layer "In2.Cu")
		(net "P3E_CPU0_PE1_PCH_RXN<6>")
	)
	(segment
		(start 374.86844 -121.56948)
		(end 374.81764 -121.51868)
		(width 0.0889)
		(layer "In2.Cu")
		(net "P3E_CPU0_PE1_PCH_RXN<6>")
	)
	(segment
		(start 378.32665 -121.245884)
		(end 378.49556 -121.539)
		(width 0.0889)
		(layer "In2.Cu")
		(net "P3E_CPU0_PE1_PCH_RXN<6>")
	)
	(segment
		(start 347.811852 -115.40236)
		(end 347.668342 -115.30584)
		(width 0.1143)
		(layer "In2.Cu")
		(net "P3E_CPU0_PE1_PCH_RXN<6>")
	)
	(segment
		(start 377.83135 -121.513346)
		(end 377.49226 -121.513346)
		(width 0.0889)
		(layer "In2.Cu")
		(net "P3E_CPU0_PE1_PCH_RXN<6>")
	)
	(segment
		(start 356.08768 -117.196362)
		(end 355.957124 -117.38991)
		(width 0.1143)
		(layer "In2.Cu")
		(net "P3E_CPU0_PE1_PCH_RXN<6>")
	)
	(segment
		(start 333.52105 -110.127796)
		(end 333.52105 -108.165646)
		(width 0.1143)
		(layer "In2.Cu")
		(net "P3E_CPU0_PE1_PCH_RXN<6>")
	)
	(segment
		(start 335.316322 -67.028314)
		(end 337.071208 -67.028314)
		(width 0.1143)
		(layer "In2.Cu")
		(net "P3E_CPU0_PE1_PCH_RXN<6>")
	)
	(segment
		(start 330.509372 -84.191602)
		(end 330.327762 -83.900518)
		(width 0.1143)
		(layer "In2.Cu")
		(net "P3E_CPU0_PE1_PCH_RXN<6>")
	)
	(segment
		(start 339.832696 -66.543936)
		(end 340.355936 -66.020696)
		(width 0.1143)
		(layer "In2.Cu")
		(net "P3E_CPU0_PE1_PCH_RXN<6>")
	)
	(segment
		(start 331.124814 -91.417394)
		(end 332.002892 -86.89848)
		(width 0.1143)
		(layer "In2.Cu")
		(net "P3E_CPU0_PE1_PCH_RXN<6>")
	)
	(segment
		(start 327.58126 -76.852526)
		(end 329.394058 -69.8119)
		(width 0.1143)
		(layer "In2.Cu")
		(net "P3E_CPU0_PE1_PCH_RXN<6>")
	)
	(segment
		(start 329.25258 -82.176366)
		(end 329.024996 -82.123534)
		(width 0.1143)
		(layer "In2.Cu")
		(net "P3E_CPU0_PE1_PCH_RXN<6>")
	)
	(segment
		(start 330.86548 -84.762594)
		(end 330.63815 -84.709762)
		(width 0.1143)
		(layer "In2.Cu")
		(net "P3E_CPU0_PE1_PCH_RXN<6>")
	)
	(segment
		(start 329.790298 -83.038442)
		(end 329.562714 -82.98561)
		(width 0.1143)
		(layer "In2.Cu")
		(net "P3E_CPU0_PE1_PCH_RXN<6>")
	)
	(segment
		(start 331.04709 -85.053678)
		(end 330.86548 -84.762594)
		(width 0.1143)
		(layer "In2.Cu")
		(net "P3E_CPU0_PE1_PCH_RXN<6>")
	)
	(segment
		(start 329.381358 -82.69478)
		(end 329.433936 -82.46745)
		(width 0.1143)
		(layer "In2.Cu")
		(net "P3E_CPU0_PE1_PCH_RXN<6>")
	)
	(segment
		(start 347.323918 -114.400838)
		(end 347.044264 -114.212624)
		(width 0.1143)
		(layer "In2.Cu")
		(net "P3E_CPU0_PE1_PCH_RXN<6>")
	)
	(segment
		(start 345.590368 -114.180874)
		(end 344.902282 -114.04727)
		(width 0.1143)
		(layer "In2.Cu")
		(net "P3E_CPU0_PE1_PCH_RXN<6>")
	)
	(segment
		(start 377.49226 -121.513346)
		(end 377.241054 -121.764552)
		(width 0.0889)
		(layer "In2.Cu")
		(net "P3E_CPU0_PE1_PCH_RXN<6>")
	)
	(segment
		(start 347.543628 -115.12042)
		(end 347.43644 -114.570256)
		(width 0.1143)
		(layer "In2.Cu")
		(net "P3E_CPU0_PE1_PCH_RXN<6>")
	)
	(segment
		(start 329.971654 -83.329526)
		(end 329.790298 -83.038442)
		(width 0.1143)
		(layer "In2.Cu")
		(net "P3E_CPU0_PE1_PCH_RXN<6>")
	)
	(segment
		(start 346.329 -66.020696)
		(end 346.4433 -66.134996)
		(width 0.1143)
		(layer "In2.Cu")
		(net "P3E_CPU0_PE1_PCH_RXN<6>")
	)
	(segment
		(start 328.239628 -80.183482)
		(end 328.17308 -79.847186)
		(width 0.1143)
		(layer "In2.Cu")
		(net "P3E_CPU0_PE1_PCH_RXN<6>")
	)
	(segment
		(start 352.22307 -116.358416)
		(end 351.993962 -116.402866)
		(width 0.1143)
		(layer "In2.Cu")
		(net "P3E_CPU0_PE1_PCH_RXN<6>")
	)
	(segment
		(start 341.207598 -111.63427)
		(end 340.025228 -111.4044)
		(width 0.1143)
		(layer "In2.Cu")
		(net "P3E_CPU0_PE1_PCH_RXN<6>")
	)
	(segment
		(start 378.49556 -121.539)
		(end 378.474224 -121.61774)
		(width 0.0889)
		(layer "In2.Cu")
		(net "P3E_CPU0_PE1_PCH_RXN<6>")
	)
	(segment
		(start 337.972654 -111.454946)
		(end 337.045046 -110.829598)
		(width 0.1143)
		(layer "In2.Cu")
		(net "P3E_CPU0_PE1_PCH_RXN<6>")
	)
	(segment
		(start 329.562714 -82.98561)
		(end 329.381358 -82.69478)
		(width 0.1143)
		(layer "In2.Cu")
		(net "P3E_CPU0_PE1_PCH_RXN<6>")
	)
	(segment
		(start 347.668342 -115.30584)
		(end 347.543628 -115.12042)
		(width 0.1143)
		(layer "In2.Cu")
		(net "P3E_CPU0_PE1_PCH_RXN<6>")
	)
	(segment
		(start 365.668814 -119.114824)
		(end 360.7308 -117.370352)
		(width 0.1143)
		(layer "In2.Cu")
		(net "P3E_CPU0_PE1_PCH_RXN<6>")
	)
	(segment
		(start 353.525328 -117.43563)
		(end 352.552 -116.779294)
		(width 0.1143)
		(layer "In2.Cu")
		(net "P3E_CPU0_PE1_PCH_RXN<6>")
	)
	(segment
		(start 355.62032 -117.455442)
		(end 355.426772 -117.324886)
		(width 0.1143)
		(layer "In2.Cu")
		(net "P3E_CPU0_PE1_PCH_RXN<6>")
	)
	(segment
		(start 376.190256 -121.764552)
		(end 375.995184 -121.56948)
		(width 0.0889)
		(layer "In2.Cu")
		(net "P3E_CPU0_PE1_PCH_RXN<6>")
	)
	(segment
		(start 375.245122 -121.56948)
		(end 374.86844 -121.56948)
		(width 0.0889)
		(layer "In2.Cu")
		(net "P3E_CPU0_PE1_PCH_RXN<6>")
	)
	(segment
		(start 352.552 -116.779294)
		(end 352.507296 -116.549932)
		(width 0.1143)
		(layer "In2.Cu")
		(net "P3E_CPU0_PE1_PCH_RXN<6>")
	)
	(segment
		(start 337.045046 -110.829598)
		(end 334.41513 -110.31855)
		(width 0.1143)
		(layer "In2.Cu")
		(net "P3E_CPU0_PE1_PCH_RXN<6>")
	)
	(segment
		(start 351.709482 -116.211096)
		(end 351.665032 -115.981988)
		(width 0.1143)
		(layer "In2.Cu")
		(net "P3E_CPU0_PE1_PCH_RXN<6>")
	)
	(segment
		(start 331.837538 -101.941884)
		(end 331.04455 -97.862136)
		(width 0.1143)
		(layer "In2.Cu")
		(net "P3E_CPU0_PE1_PCH_RXN<6>")
	)
	(segment
		(start 360.7308 -117.370352)
		(end 358.393746 -116.9162)
		(width 0.1143)
		(layer "In2.Cu")
		(net "P3E_CPU0_PE1_PCH_RXN<6>")
	)
	(segment
		(start 346.4433 -66.134996)
		(end 346.4433 -67.152012)
		(width 0.1143)
		(layer "In2.Cu")
		(net "P3E_CPU0_PE1_PCH_RXN<6>")
	)
	(segment
		(start 340.025228 -111.4044)
		(end 338.868766 -111.62919)
		(width 0.1143)
		(layer "In2.Cu")
		(net "P3E_CPU0_PE1_PCH_RXN<6>")
	)
	(segment
		(start 330.585318 -84.62518)
		(end 330.45654 -84.418932)
		(width 0.1143)
		(layer "In2.Cu")
		(net "P3E_CPU0_PE1_PCH_RXN<6>")
	)
	(arc
		(start 378.474224 -121.61774)
		(mid 378.297595 -121.645009)
		(end 378.126752 -121.592594)
		(width 0.0889)
		(layer "In2.Cu")
		(net "P3E_CPU0_PE1_PCH_RXN<6>")
	)
	(arc
		(start 378.126752 -121.592594)
		(mid 377.984266 -121.533527)
		(end 377.83135 -121.513346)
		(width 0.0889)
		(layer "In2.Cu")
		(net "P3E_CPU0_PE1_PCH_RXN<6>")
	)
	(segment
		(start 379.81255 -121.01576)
		(end 380.30785 -121.245884)
		(width 0.1143)
		(layer "F.Cu")
		(net "P3E_CPU0_PE1_PCH_RXN<5>")
	)
	(via
		(at 380.30785 -121.245884)
		(size 0.508)
		(drill 0.254)
		(layers "F.Cu" "B.Cu")
		(net "P3E_CPU0_PE1_PCH_RXN<5>")
	)
	(via
		(at 347.682312 -62.908688)
		(size 0.508)
		(drill 0.254)
		(layers "F.Cu" "B.Cu")
		(net "P3E_CPU0_PE1_PCH_RXN<5>")
	)
	(via
		(at 344.492072 -67.48653)
		(size 0.508)
		(drill 0.254)
		(layers "F.Cu" "B.Cu")
		(net "P3E_CPU0_PE1_PCH_RXN<5>")
	)
	(segment
		(start 348.125542 -62.465458)
		(end 348.125542 -61.845698)
		(width 0.1143)
		(layer "B.Cu")
		(net "P3E_CPU0_PE1_PCH_RXN<5>")
	)
	(segment
		(start 348.125542 -61.845698)
		(end 348.713806 -61.257434)
		(width 0.1143)
		(layer "B.Cu")
		(net "P3E_CPU0_PE1_PCH_RXN<5>")
	)
	(segment
		(start 347.682312 -62.908688)
		(end 348.125542 -62.465458)
		(width 0.1143)
		(layer "B.Cu")
		(net "P3E_CPU0_PE1_PCH_RXN<5>")
	)
	(segment
		(start 344.130122 -66.460878)
		(end 347.682312 -62.908688)
		(width 0.1143)
		(layer "B.Cu")
		(net "P3E_CPU0_PE1_PCH_RXN<5>")
	)
	(segment
		(start 344.492072 -67.48653)
		(end 344.130122 -67.12458)
		(width 0.1143)
		(layer "B.Cu")
		(net "P3E_CPU0_PE1_PCH_RXN<5>")
	)
	(segment
		(start 344.130122 -67.12458)
		(end 344.130122 -66.460878)
		(width 0.1143)
		(layer "B.Cu")
		(net "P3E_CPU0_PE1_PCH_RXN<5>")
	)
	(segment
		(start 355.136196 -91.152472)
		(end 356.94366 -93.863414)
		(width 0.1143)
		(layer "In2.Cu")
		(net "P3E_CPU0_PE1_PCH_RXN<5>")
	)
	(segment
		(start 379.969776 -121.245884)
		(end 380.30785 -121.245884)
		(width 0.0889)
		(layer "In2.Cu")
		(net "P3E_CPU0_PE1_PCH_RXN<5>")
	)
	(segment
		(start 372.9228 -120.996456)
		(end 372.944898 -120.996456)
		(width 0.0889)
		(layer "In2.Cu")
		(net "P3E_CPU0_PE1_PCH_RXN<5>")
	)
	(segment
		(start 377.9647 -120.9929)
		(end 378.126752 -120.899174)
		(width 0.0889)
		(layer "In2.Cu")
		(net "P3E_CPU0_PE1_PCH_RXN<5>")
	)
	(segment
		(start 344.245692 -67.24015)
		(end 344.245692 -66.750438)
		(width 0.1143)
		(layer "In2.Cu")
		(net "P3E_CPU0_PE1_PCH_RXN<5>")
	)
	(segment
		(start 360.910886 -109.964728)
		(end 360.569002 -111.216694)
		(width 0.1143)
		(layer "In2.Cu")
		(net "P3E_CPU0_PE1_PCH_RXN<5>")
	)
	(segment
		(start 377.499118 -120.9929)
		(end 377.9647 -120.9929)
		(width 0.0889)
		(layer "In2.Cu")
		(net "P3E_CPU0_PE1_PCH_RXN<5>")
	)
	(segment
		(start 340.498176 -66.363596)
		(end 339.974936 -66.886836)
		(width 0.1143)
		(layer "In2.Cu")
		(net "P3E_CPU0_PE1_PCH_RXN<5>")
	)
	(segment
		(start 377.451874 -120.945656)
		(end 377.499118 -120.9929)
		(width 0.0889)
		(layer "In2.Cu")
		(net "P3E_CPU0_PE1_PCH_RXN<5>")
	)
	(segment
		(start 348.352618 -91.333574)
		(end 352.189796 -90.552778)
		(width 0.1143)
		(layer "In2.Cu")
		(net "P3E_CPU0_PE1_PCH_RXN<5>")
	)
	(segment
		(start 328.149458 -76.262992)
		(end 329.031092 -80.722978)
		(width 0.1143)
		(layer "In2.Cu")
		(net "P3E_CPU0_PE1_PCH_RXN<5>")
	)
	(segment
		(start 329.031092 -80.722978)
		(end 334.060546 -88.78697)
		(width 0.1143)
		(layer "In2.Cu")
		(net "P3E_CPU0_PE1_PCH_RXN<5>")
	)
	(segment
		(start 372.944898 -120.996456)
		(end 372.995698 -120.945656)
		(width 0.0889)
		(layer "In2.Cu")
		(net "P3E_CPU0_PE1_PCH_RXN<5>")
	)
	(segment
		(start 337.283044 -67.371214)
		(end 335.428336 -67.371214)
		(width 0.1143)
		(layer "In2.Cu")
		(net "P3E_CPU0_PE1_PCH_RXN<5>")
	)
	(segment
		(start 360.82478 -112.01781)
		(end 360.307636 -113.913412)
		(width 0.1143)
		(layer "In2.Cu")
		(net "P3E_CPU0_PE1_PCH_RXN<5>")
	)
	(segment
		(start 360.569002 -111.216694)
		(end 360.82478 -112.01781)
		(width 0.1143)
		(layer "In2.Cu")
		(net "P3E_CPU0_PE1_PCH_RXN<5>")
	)
	(segment
		(start 358.665018 -101.81463)
		(end 360.020108 -102.74427)
		(width 0.1143)
		(layer "In2.Cu")
		(net "P3E_CPU0_PE1_PCH_RXN<5>")
	)
	(segment
		(start 360.020108 -102.74427)
		(end 360.5022 -103.479092)
		(width 0.1143)
		(layer "In2.Cu")
		(net "P3E_CPU0_PE1_PCH_RXN<5>")
	)
	(segment
		(start 379.904752 -121.310908)
		(end 379.969776 -121.245884)
		(width 0.0889)
		(layer "In2.Cu")
		(net "P3E_CPU0_PE1_PCH_RXN<5>")
	)
	(segment
		(start 361.263692 -116.3828)
		(end 362.12145 -117.442742)
		(width 0.1143)
		(layer "In2.Cu")
		(net "P3E_CPU0_PE1_PCH_RXN<5>")
	)
	(segment
		(start 337.767422 -66.886836)
		(end 337.283044 -67.371214)
		(width 0.1143)
		(layer "In2.Cu")
		(net "P3E_CPU0_PE1_PCH_RXN<5>")
	)
	(segment
		(start 360.307636 -113.913412)
		(end 361.263692 -116.3828)
		(width 0.1143)
		(layer "In2.Cu")
		(net "P3E_CPU0_PE1_PCH_RXN<5>")
	)
	(segment
		(start 334.060546 -88.78697)
		(end 336.830924 -90.448384)
		(width 0.1143)
		(layer "In2.Cu")
		(net "P3E_CPU0_PE1_PCH_RXN<5>")
	)
	(segment
		(start 343.85885 -66.363596)
		(end 340.498176 -66.363596)
		(width 0.1143)
		(layer "In2.Cu")
		(net "P3E_CPU0_PE1_PCH_RXN<5>")
	)
	(segment
		(start 344.492072 -67.48653)
		(end 344.245692 -67.24015)
		(width 0.1143)
		(layer "In2.Cu")
		(net "P3E_CPU0_PE1_PCH_RXN<5>")
	)
	(segment
		(start 342.831166 -90.228928)
		(end 348.352618 -91.333574)
		(width 0.1143)
		(layer "In2.Cu")
		(net "P3E_CPU0_PE1_PCH_RXN<5>")
	)
	(segment
		(start 356.94366 -93.863414)
		(end 357.90759 -94.608904)
		(width 0.1143)
		(layer "In2.Cu")
		(net "P3E_CPU0_PE1_PCH_RXN<5>")
	)
	(segment
		(start 358.248712 -96.167448)
		(end 357.587042 -98.811588)
		(width 0.1143)
		(layer "In2.Cu")
		(net "P3E_CPU0_PE1_PCH_RXN<5>")
	)
	(segment
		(start 365.589566 -118.668546)
		(end 369.541044 -120.996456)
		(width 0.1143)
		(layer "In2.Cu")
		(net "P3E_CPU0_PE1_PCH_RXN<5>")
	)
	(segment
		(start 378.7267 -121.234708)
		(end 378.7267 -121.267474)
		(width 0.0889)
		(layer "In2.Cu")
		(net "P3E_CPU0_PE1_PCH_RXN<5>")
	)
	(segment
		(start 339.680804 -91.018614)
		(end 342.831166 -90.228928)
		(width 0.1143)
		(layer "In2.Cu")
		(net "P3E_CPU0_PE1_PCH_RXN<5>")
	)
	(segment
		(start 352.189796 -90.552778)
		(end 355.136196 -91.152472)
		(width 0.1143)
		(layer "In2.Cu")
		(net "P3E_CPU0_PE1_PCH_RXN<5>")
	)
	(segment
		(start 339.974936 -66.886836)
		(end 337.767422 -66.886836)
		(width 0.1143)
		(layer "In2.Cu")
		(net "P3E_CPU0_PE1_PCH_RXN<5>")
	)
	(segment
		(start 372.995698 -120.945656)
		(end 377.451874 -120.945656)
		(width 0.0889)
		(layer "In2.Cu")
		(net "P3E_CPU0_PE1_PCH_RXN<5>")
	)
	(segment
		(start 335.428336 -67.371214)
		(end 329.762866 -70.035166)
		(width 0.1143)
		(layer "In2.Cu")
		(net "P3E_CPU0_PE1_PCH_RXN<5>")
	)
	(segment
		(start 360.5022 -103.479092)
		(end 360.5022 -108.035852)
		(width 0.1143)
		(layer "In2.Cu")
		(net "P3E_CPU0_PE1_PCH_RXN<5>")
	)
	(segment
		(start 329.762866 -70.035166)
		(end 328.149458 -76.262992)
		(width 0.1143)
		(layer "In2.Cu")
		(net "P3E_CPU0_PE1_PCH_RXN<5>")
	)
	(segment
		(start 336.830924 -90.448384)
		(end 339.680804 -91.018614)
		(width 0.1143)
		(layer "In2.Cu")
		(net "P3E_CPU0_PE1_PCH_RXN<5>")
	)
	(segment
		(start 344.245692 -66.750438)
		(end 343.85885 -66.363596)
		(width 0.1143)
		(layer "In2.Cu")
		(net "P3E_CPU0_PE1_PCH_RXN<5>")
	)
	(segment
		(start 362.12145 -117.442742)
		(end 365.589566 -118.668546)
		(width 0.1143)
		(layer "In2.Cu")
		(net "P3E_CPU0_PE1_PCH_RXN<5>")
	)
	(segment
		(start 369.541044 -120.996456)
		(end 372.9228 -120.996456)
		(width 0.1143)
		(layer "In2.Cu")
		(net "P3E_CPU0_PE1_PCH_RXN<5>")
	)
	(segment
		(start 357.90759 -94.608904)
		(end 358.248712 -96.167448)
		(width 0.1143)
		(layer "In2.Cu")
		(net "P3E_CPU0_PE1_PCH_RXN<5>")
	)
	(segment
		(start 357.587042 -98.811588)
		(end 358.665018 -101.81463)
		(width 0.1143)
		(layer "In2.Cu")
		(net "P3E_CPU0_PE1_PCH_RXN<5>")
	)
	(segment
		(start 360.5022 -108.035852)
		(end 360.910886 -109.964728)
		(width 0.1143)
		(layer "In2.Cu")
		(net "P3E_CPU0_PE1_PCH_RXN<5>")
	)
	(arc
		(start 378.126752 -120.899174)
		(mid 378.521999 -120.896591)
		(end 378.7267 -121.234708)
		(width 0.0889)
		(layer "In2.Cu")
		(net "P3E_CPU0_PE1_PCH_RXN<5>")
	)
	(arc
		(start 378.7267 -121.267474)
		(mid 379.295482 -121.836427)
		(end 379.904752 -121.310908)
		(width 0.0889)
		(layer "In2.Cu")
		(net "P3E_CPU0_PE1_PCH_RXN<5>")
	)
	(segment
		(start 379.81255 -119.29872)
		(end 379.878082 -119.3292)
		(width 0.1143)
		(layer "F.Cu")
		(net "P3E_CPU0_PE1_PCH_RXN<4>")
	)
	(segment
		(start 379.878082 -119.3292)
		(end 380.30785 -119.528844)
		(width 0.1143)
		(layer "F.Cu")
		(net "P3E_CPU0_PE1_PCH_RXN<4>")
	)
	(via
		(at 380.30785 -119.528844)
		(size 0.508)
		(drill 0.254)
		(layers "F.Cu" "B.Cu")
		(net "P3E_CPU0_PE1_PCH_RXN<4>")
	)
	(via
		(at 343.831672 -64.798448)
		(size 0.508)
		(drill 0.254)
		(layers "F.Cu" "B.Cu")
		(net "P3E_CPU0_PE1_PCH_RXN<4>")
	)
	(via
		(at 342.256872 -68.09613)
		(size 0.508)
		(drill 0.254)
		(layers "F.Cu" "B.Cu")
		(net "P3E_CPU0_PE1_PCH_RXN<4>")
	)
	(segment
		(start 341.89797 -66.73215)
		(end 343.831672 -64.798448)
		(width 0.1143)
		(layer "B.Cu")
		(net "P3E_CPU0_PE1_PCH_RXN<4>")
	)
	(segment
		(start 345.356942 -61.820298)
		(end 345.919806 -61.257434)
		(width 0.1143)
		(layer "B.Cu")
		(net "P3E_CPU0_PE1_PCH_RXN<4>")
	)
	(segment
		(start 343.831672 -64.798448)
		(end 345.356942 -63.273178)
		(width 0.1143)
		(layer "B.Cu")
		(net "P3E_CPU0_PE1_PCH_RXN<4>")
	)
	(segment
		(start 345.356942 -63.273178)
		(end 345.356942 -61.820298)
		(width 0.1143)
		(layer "B.Cu")
		(net "P3E_CPU0_PE1_PCH_RXN<4>")
	)
	(segment
		(start 342.256872 -68.09613)
		(end 341.89797 -67.737228)
		(width 0.1143)
		(layer "B.Cu")
		(net "P3E_CPU0_PE1_PCH_RXN<4>")
	)
	(segment
		(start 341.89797 -67.737228)
		(end 341.89797 -66.73215)
		(width 0.1143)
		(layer "B.Cu")
		(net "P3E_CPU0_PE1_PCH_RXN<4>")
	)
	(segment
		(start 359.600754 -100.464366)
		(end 360.142028 -101.267006)
		(width 0.1143)
		(layer "In2.Cu")
		(net "P3E_CPU0_PE1_PCH_RXN<4>")
	)
	(segment
		(start 361.1372 -107.901232)
		(end 361.58805 -110.029498)
		(width 0.1143)
		(layer "In2.Cu")
		(net "P3E_CPU0_PE1_PCH_RXN<4>")
	)
	(segment
		(start 329.97267 -80.097122)
		(end 330.189332 -80.44434)
		(width 0.1143)
		(layer "In2.Cu")
		(net "P3E_CPU0_PE1_PCH_RXN<4>")
	)
	(segment
		(start 329.185524 -76.113132)
		(end 329.97267 -80.097122)
		(width 0.1143)
		(layer "In2.Cu")
		(net "P3E_CPU0_PE1_PCH_RXN<4>")
	)
	(segment
		(start 361.1372 -102.340664)
		(end 361.1372 -107.901232)
		(width 0.1143)
		(layer "In2.Cu")
		(net "P3E_CPU0_PE1_PCH_RXN<4>")
	)
	(segment
		(start 377.877578 -119.9515)
		(end 378.031248 -120.040654)
		(width 0.0889)
		(layer "In2.Cu")
		(net "P3E_CPU0_PE1_PCH_RXN<4>")
	)
	(segment
		(start 341.527384 -67.035172)
		(end 340.724998 -67.035172)
		(width 0.1143)
		(layer "In2.Cu")
		(net "P3E_CPU0_PE1_PCH_RXN<4>")
	)
	(segment
		(start 371.08638 -120.0023)
		(end 371.13718 -119.9515)
		(width 0.0889)
		(layer "In2.Cu")
		(net "P3E_CPU0_PE1_PCH_RXN<4>")
	)
	(segment
		(start 338.053934 -67.52209)
		(end 337.56981 -68.006214)
		(width 0.1143)
		(layer "In2.Cu")
		(net "P3E_CPU0_PE1_PCH_RXN<4>")
	)
	(segment
		(start 348.371668 -90.591894)
		(end 352.126804 -89.84107)
		(width 0.1143)
		(layer "In2.Cu")
		(net "P3E_CPU0_PE1_PCH_RXN<4>")
	)
	(segment
		(start 365.813594 -117.931946)
		(end 369.326922 -120.0023)
		(width 0.1143)
		(layer "In2.Cu")
		(net "P3E_CPU0_PE1_PCH_RXN<4>")
	)
	(segment
		(start 369.326922 -120.0023)
		(end 371.064282 -120.0023)
		(width 0.1143)
		(layer "In2.Cu")
		(net "P3E_CPU0_PE1_PCH_RXN<4>")
	)
	(segment
		(start 371.064282 -120.0023)
		(end 371.08638 -120.0023)
		(width 0.0889)
		(layer "In2.Cu")
		(net "P3E_CPU0_PE1_PCH_RXN<4>")
	)
	(segment
		(start 340.724998 -67.035172)
		(end 340.23808 -67.52209)
		(width 0.1143)
		(layer "In2.Cu")
		(net "P3E_CPU0_PE1_PCH_RXN<4>")
	)
	(segment
		(start 358.627934 -94.341442)
		(end 359.336086 -98.526854)
		(width 0.1143)
		(layer "In2.Cu")
		(net "P3E_CPU0_PE1_PCH_RXN<4>")
	)
	(segment
		(start 339.697568 -90.254328)
		(end 342.798146 -89.477088)
		(width 0.1143)
		(layer "In2.Cu")
		(net "P3E_CPU0_PE1_PCH_RXN<4>")
	)
	(segment
		(start 361.58805 -110.029498)
		(end 361.252008 -111.259874)
		(width 0.1143)
		(layer "In2.Cu")
		(net "P3E_CPU0_PE1_PCH_RXN<4>")
	)
	(segment
		(start 359.850944 -99.422458)
		(end 359.600754 -100.464366)
		(width 0.1143)
		(layer "In2.Cu")
		(net "P3E_CPU0_PE1_PCH_RXN<4>")
	)
	(segment
		(start 360.142028 -101.267006)
		(end 360.638344 -101.601524)
		(width 0.1143)
		(layer "In2.Cu")
		(net "P3E_CPU0_PE1_PCH_RXN<4>")
	)
	(segment
		(start 330.189332 -80.44434)
		(end 330.189078 -80.44434)
		(width 0.1143)
		(layer "In2.Cu")
		(net "P3E_CPU0_PE1_PCH_RXN<4>")
	)
	(segment
		(start 352.126804 -89.84107)
		(end 355.464618 -90.493088)
		(width 0.1143)
		(layer "In2.Cu")
		(net "P3E_CPU0_PE1_PCH_RXN<4>")
	)
	(segment
		(start 341.899494 -67.738752)
		(end 341.899494 -67.407282)
		(width 0.1143)
		(layer "In2.Cu")
		(net "P3E_CPU0_PE1_PCH_RXN<4>")
	)
	(segment
		(start 380.13894 -119.82196)
		(end 380.30785 -119.528844)
		(width 0.0889)
		(layer "In2.Cu")
		(net "P3E_CPU0_PE1_PCH_RXN<4>")
	)
	(segment
		(start 330.189078 -80.44434)
		(end 330.189332 -80.444594)
		(width 0.1143)
		(layer "In2.Cu")
		(net "P3E_CPU0_PE1_PCH_RXN<4>")
	)
	(segment
		(start 337.244944 -89.763854)
		(end 339.697568 -90.254328)
		(width 0.1143)
		(layer "In2.Cu")
		(net "P3E_CPU0_PE1_PCH_RXN<4>")
	)
	(segment
		(start 342.256872 -68.09613)
		(end 341.899494 -67.738752)
		(width 0.1143)
		(layer "In2.Cu")
		(net "P3E_CPU0_PE1_PCH_RXN<4>")
	)
	(segment
		(start 355.464618 -90.493088)
		(end 357.39451 -93.387164)
		(width 0.1143)
		(layer "In2.Cu")
		(net "P3E_CPU0_PE1_PCH_RXN<4>")
	)
	(segment
		(start 335.25968 -88.573102)
		(end 337.244944 -89.763854)
		(width 0.1143)
		(layer "In2.Cu")
		(net "P3E_CPU0_PE1_PCH_RXN<4>")
	)
	(segment
		(start 361.489244 -112.003586)
		(end 360.979212 -113.87201)
		(width 0.1143)
		(layer "In2.Cu")
		(net "P3E_CPU0_PE1_PCH_RXN<4>")
	)
	(segment
		(start 330.189332 -80.444594)
		(end 335.25968 -88.573102)
		(width 0.1143)
		(layer "In2.Cu")
		(net "P3E_CPU0_PE1_PCH_RXN<4>")
	)
	(segment
		(start 337.56981 -68.006214)
		(end 335.57337 -68.006214)
		(width 0.1143)
		(layer "In2.Cu")
		(net "P3E_CPU0_PE1_PCH_RXN<4>")
	)
	(segment
		(start 330.690728 -70.302628)
		(end 329.185524 -76.113132)
		(width 0.1143)
		(layer "In2.Cu")
		(net "P3E_CPU0_PE1_PCH_RXN<4>")
	)
	(segment
		(start 361.78998 -115.962938)
		(end 362.410756 -116.730272)
		(width 0.1143)
		(layer "In2.Cu")
		(net "P3E_CPU0_PE1_PCH_RXN<4>")
	)
	(segment
		(start 340.23808 -67.52209)
		(end 338.053934 -67.52209)
		(width 0.1143)
		(layer "In2.Cu")
		(net "P3E_CPU0_PE1_PCH_RXN<4>")
	)
	(segment
		(start 371.13718 -119.9515)
		(end 377.877578 -119.9515)
		(width 0.0889)
		(layer "In2.Cu")
		(net "P3E_CPU0_PE1_PCH_RXN<4>")
	)
	(segment
		(start 380.16307 -119.911368)
		(end 380.13894 -119.82196)
		(width 0.0889)
		(layer "In2.Cu")
		(net "P3E_CPU0_PE1_PCH_RXN<4>")
	)
	(segment
		(start 361.252008 -111.259874)
		(end 361.489244 -112.003586)
		(width 0.1143)
		(layer "In2.Cu")
		(net "P3E_CPU0_PE1_PCH_RXN<4>")
	)
	(segment
		(start 360.638344 -101.601524)
		(end 361.1372 -102.340664)
		(width 0.1143)
		(layer "In2.Cu")
		(net "P3E_CPU0_PE1_PCH_RXN<4>")
	)
	(segment
		(start 360.979212 -113.87201)
		(end 361.78998 -115.962938)
		(width 0.1143)
		(layer "In2.Cu")
		(net "P3E_CPU0_PE1_PCH_RXN<4>")
	)
	(segment
		(start 341.899494 -67.407282)
		(end 341.527384 -67.035172)
		(width 0.1143)
		(layer "In2.Cu")
		(net "P3E_CPU0_PE1_PCH_RXN<4>")
	)
	(segment
		(start 342.798146 -89.477088)
		(end 348.371668 -90.591894)
		(width 0.1143)
		(layer "In2.Cu")
		(net "P3E_CPU0_PE1_PCH_RXN<4>")
	)
	(segment
		(start 380.4031 -120.408954)
		(end 380.4031 -120.365774)
		(width 0.0889)
		(layer "In2.Cu")
		(net "P3E_CPU0_PE1_PCH_RXN<4>")
	)
	(segment
		(start 362.410756 -116.730272)
		(end 365.813594 -117.931946)
		(width 0.1143)
		(layer "In2.Cu")
		(net "P3E_CPU0_PE1_PCH_RXN<4>")
	)
	(segment
		(start 359.336086 -98.526854)
		(end 359.850944 -99.422458)
		(width 0.1143)
		(layer "In2.Cu")
		(net "P3E_CPU0_PE1_PCH_RXN<4>")
	)
	(segment
		(start 357.39451 -93.387164)
		(end 358.627934 -94.341442)
		(width 0.1143)
		(layer "In2.Cu")
		(net "P3E_CPU0_PE1_PCH_RXN<4>")
	)
	(segment
		(start 335.57337 -68.006214)
		(end 330.690728 -70.302628)
		(width 0.1143)
		(layer "In2.Cu")
		(net "P3E_CPU0_PE1_PCH_RXN<4>")
	)
	(segment
		(start 379.222 -120.376188)
		(end 379.222 -120.408954)
		(width 0.0889)
		(layer "In2.Cu")
		(net "P3E_CPU0_PE1_PCH_RXN<4>")
	)
	(arc
		(start 379.222 -120.408954)
		(mid 379.306281 -120.692171)
		(end 379.517148 -120.899174)
		(width 0.0889)
		(layer "In2.Cu")
		(net "P3E_CPU0_PE1_PCH_RXN<4>")
	)
	(arc
		(start 378.031248 -120.040654)
		(mid 378.32665 -120.119785)
		(end 378.622052 -120.040654)
		(width 0.0889)
		(layer "In2.Cu")
		(net "P3E_CPU0_PE1_PCH_RXN<4>")
	)
	(arc
		(start 378.622052 -120.040654)
		(mid 379.017299 -120.038071)
		(end 379.222 -120.376188)
		(width 0.0889)
		(layer "In2.Cu")
		(net "P3E_CPU0_PE1_PCH_RXN<4>")
	)
	(arc
		(start 379.517148 -120.899174)
		(mid 379.81255 -120.978305)
		(end 380.107952 -120.899174)
		(width 0.0889)
		(layer "In2.Cu")
		(net "P3E_CPU0_PE1_PCH_RXN<4>")
	)
	(arc
		(start 380.4031 -120.365774)
		(mid 380.335071 -120.111109)
		(end 380.16307 -119.911368)
		(width 0.0889)
		(layer "In2.Cu")
		(net "P3E_CPU0_PE1_PCH_RXN<4>")
	)
	(arc
		(start 380.107952 -120.899174)
		(mid 380.318816 -120.69217)
		(end 380.4031 -120.408954)
		(width 0.0889)
		(layer "In2.Cu")
		(net "P3E_CPU0_PE1_PCH_RXN<4>")
	)
	(segment
		(start 378.376688 -118.577106)
		(end 378.685298 -118.720108)
		(width 0.1143)
		(layer "F.Cu")
		(net "P3E_CPU0_PE1_PCH_RXN<3>")
	)
	(segment
		(start 378.685298 -118.720108)
		(end 378.82195 -118.670324)
		(width 0.1143)
		(layer "F.Cu")
		(net "P3E_CPU0_PE1_PCH_RXN<3>")
	)
	(segment
		(start 378.32665 -118.4402)
		(end 378.376688 -118.577106)
		(width 0.1143)
		(layer "F.Cu")
		(net "P3E_CPU0_PE1_PCH_RXN<3>")
	)
	(via
		(at 378.82195 -118.670324)
		(size 0.508)
		(drill 0.254)
		(layers "F.Cu" "B.Cu")
		(net "P3E_CPU0_PE1_PCH_RXN<3>")
	)
	(via
		(at 340.422992 -69.02577)
		(size 0.508)
		(drill 0.254)
		(layers "F.Cu" "B.Cu")
		(net "P3E_CPU0_PE1_PCH_RXN<3>")
	)
	(via
		(at 342.057482 -63.79845)
		(size 0.508)
		(drill 0.254)
		(layers "F.Cu" "B.Cu")
		(net "P3E_CPU0_PE1_PCH_RXN<3>")
	)
	(segment
		(start 342.562942 -63.29299)
		(end 342.057482 -63.79845)
		(width 0.1143)
		(layer "B.Cu")
		(net "P3E_CPU0_PE1_PCH_RXN<3>")
	)
	(segment
		(start 342.057482 -63.79845)
		(end 340.055454 -65.800478)
		(width 0.1143)
		(layer "B.Cu")
		(net "P3E_CPU0_PE1_PCH_RXN<3>")
	)
	(segment
		(start 340.055454 -65.800478)
		(end 340.055454 -68.658232)
		(width 0.1143)
		(layer "B.Cu")
		(net "P3E_CPU0_PE1_PCH_RXN<3>")
	)
	(segment
		(start 342.562942 -61.820298)
		(end 342.562942 -63.29299)
		(width 0.1143)
		(layer "B.Cu")
		(net "P3E_CPU0_PE1_PCH_RXN<3>")
	)
	(segment
		(start 343.125806 -61.257434)
		(end 342.562942 -61.820298)
		(width 0.1143)
		(layer "B.Cu")
		(net "P3E_CPU0_PE1_PCH_RXN<3>")
	)
	(segment
		(start 340.055454 -68.658232)
		(end 340.422992 -69.02577)
		(width 0.1143)
		(layer "B.Cu")
		(net "P3E_CPU0_PE1_PCH_RXN<3>")
	)
	(segment
		(start 374.542812 -117.508782)
		(end 374.740424 -117.706394)
		(width 0.0889)
		(layer "In2.Cu")
		(net "P3E_CPU0_PE1_PCH_RXN<3>")
	)
	(segment
		(start 350.385888 -86.650068)
		(end 351.53981 -85.871812)
		(width 0.1143)
		(layer "In2.Cu")
		(net "P3E_CPU0_PE1_PCH_RXN<3>")
	)
	(segment
		(start 361.484418 -95.429324)
		(end 361.295188 -96.321626)
		(width 0.1143)
		(layer "In2.Cu")
		(net "P3E_CPU0_PE1_PCH_RXN<3>")
	)
	(segment
		(start 334.324198 -83.674204)
		(end 337.706462 -85.944456)
		(width 0.1143)
		(layer "In2.Cu")
		(net "P3E_CPU0_PE1_PCH_RXN<3>")
	)
	(segment
		(start 361.671108 -113.894616)
		(end 362.30306 -115.52682)
		(width 0.1143)
		(layer "In2.Cu")
		(net "P3E_CPU0_PE1_PCH_RXN<3>")
	)
	(segment
		(start 356.322376 -90.626946)
		(end 357.857044 -92.927932)
		(width 0.1143)
		(layer "In2.Cu")
		(net "P3E_CPU0_PE1_PCH_RXN<3>")
	)
	(segment
		(start 354.303076 -85.58657)
		(end 355.002084 -85.722714)
		(width 0.1143)
		(layer "In2.Cu")
		(net "P3E_CPU0_PE1_PCH_RXN<3>")
	)
	(segment
		(start 378.99086 -118.96344)
		(end 378.82195 -118.670324)
		(width 0.0889)
		(layer "In2.Cu")
		(net "P3E_CPU0_PE1_PCH_RXN<3>")
	)
	(segment
		(start 330.837286 -72.280018)
		(end 330.993242 -73.109074)
		(width 0.1143)
		(layer "In2.Cu")
		(net "P3E_CPU0_PE1_PCH_RXN<3>")
	)
	(segment
		(start 378.388372 -118.458742)
		(end 378.622052 -118.323614)
		(width 0.0889)
		(layer "In2.Cu")
		(net "P3E_CPU0_PE1_PCH_RXN<3>")
	)
	(segment
		(start 375.387108 -118.227348)
		(end 375.584466 -118.424706)
		(width 0.0889)
		(layer "In2.Cu")
		(net "P3E_CPU0_PE1_PCH_RXN<3>")
	)
	(segment
		(start 355.370384 -85.971126)
		(end 355.436424 -86.068916)
		(width 0.1143)
		(layer "In2.Cu")
		(net "P3E_CPU0_PE1_PCH_RXN<3>")
	)
	(segment
		(start 376.10542 -118.94566)
		(end 377.736354 -118.94566)
		(width 0.0889)
		(layer "In2.Cu")
		(net "P3E_CPU0_PE1_PCH_RXN<3>")
	)
	(segment
		(start 373.6467 -117.22354)
		(end 373.7356 -117.31244)
		(width 0.0889)
		(layer "In2.Cu")
		(net "P3E_CPU0_PE1_PCH_RXN<3>")
	)
	(segment
		(start 375.584466 -118.550436)
		(end 375.782078 -118.748048)
		(width 0.0889)
		(layer "In2.Cu")
		(net "P3E_CPU0_PE1_PCH_RXN<3>")
	)
	(segment
		(start 375.782078 -118.748048)
		(end 375.907808 -118.748048)
		(width 0.0889)
		(layer "In2.Cu")
		(net "P3E_CPU0_PE1_PCH_RXN<3>")
	)
	(segment
		(start 361.97794 -112.770666)
		(end 361.97667 -112.775746)
		(width 0.1143)
		(layer "In2.Cu")
		(net "P3E_CPU0_PE1_PCH_RXN<3>")
	)
	(segment
		(start 343.38133 -87.212678)
		(end 345.633802 -86.787228)
		(width 0.1143)
		(layer "In2.Cu")
		(net "P3E_CPU0_PE1_PCH_RXN<3>")
	)
	(segment
		(start 370.33454 -117.6655)
		(end 370.356638 -117.6655)
		(width 0.0889)
		(layer "In2.Cu")
		(net "P3E_CPU0_PE1_PCH_RXN<3>")
	)
	(segment
		(start 371.49532 -117.7036)
		(end 371.77472 -117.7036)
		(width 0.0889)
		(layer "In2.Cu")
		(net "P3E_CPU0_PE1_PCH_RXN<3>")
	)
	(segment
		(start 361.561888 -97.574608)
		(end 361.22356 -99.16795)
		(width 0.1143)
		(layer "In2.Cu")
		(net "P3E_CPU0_PE1_PCH_RXN<3>")
	)
	(segment
		(start 357.857044 -92.927932)
		(end 359.400856 -94.122494)
		(width 0.1143)
		(layer "In2.Cu")
		(net "P3E_CPU0_PE1_PCH_RXN<3>")
	)
	(segment
		(start 374.740424 -117.706394)
		(end 374.866154 -117.706394)
		(width 0.0889)
		(layer "In2.Cu")
		(net "P3E_CPU0_PE1_PCH_RXN<3>")
	)
	(segment
		(start 338.321396 -68.15709)
		(end 337.834986 -68.6435)
		(width 0.1143)
		(layer "In2.Cu")
		(net "P3E_CPU0_PE1_PCH_RXN<3>")
	)
	(segment
		(start 331.28077 -70.737984)
		(end 330.837286 -72.280018)
		(width 0.1143)
		(layer "In2.Cu")
		(net "P3E_CPU0_PE1_PCH_RXN<3>")
	)
	(segment
		(start 355.002084 -85.722714)
		(end 355.370384 -85.971126)
		(width 0.1143)
		(layer "In2.Cu")
		(net "P3E_CPU0_PE1_PCH_RXN<3>")
	)
	(segment
		(start 379.222 -118.659148)
		(end 379.222 -118.6815)
		(width 0.0889)
		(layer "In2.Cu")
		(net "P3E_CPU0_PE1_PCH_RXN<3>")
	)
	(segment
		(start 340.057232 -68.66001)
		(end 340.057232 -68.442332)
		(width 0.1143)
		(layer "In2.Cu")
		(net "P3E_CPU0_PE1_PCH_RXN<3>")
	)
	(segment
		(start 361.7722 -101.74605)
		(end 361.7722 -107.833922)
		(width 0.1143)
		(layer "In2.Cu")
		(net "P3E_CPU0_PE1_PCH_RXN<3>")
	)
	(segment
		(start 346.659708 -86.994238)
		(end 347.91523 -86.722204)
		(width 0.1143)
		(layer "In2.Cu")
		(net "P3E_CPU0_PE1_PCH_RXN<3>")
	)
	(segment
		(start 374.3833 -117.22354)
		(end 374.542812 -117.383052)
		(width 0.0889)
		(layer "In2.Cu")
		(net "P3E_CPU0_PE1_PCH_RXN<3>")
	)
	(segment
		(start 374.542812 -117.383052)
		(end 374.542812 -117.508782)
		(width 0.0889)
		(layer "In2.Cu")
		(net "P3E_CPU0_PE1_PCH_RXN<3>")
	)
	(segment
		(start 362.74756 -116.075968)
		(end 367.246916 -117.6655)
		(width 0.1143)
		(layer "In2.Cu")
		(net "P3E_CPU0_PE1_PCH_RXN<3>")
	)
	(segment
		(start 352.629978 -85.91169)
		(end 354.303076 -85.58657)
		(width 0.1143)
		(layer "In2.Cu")
		(net "P3E_CPU0_PE1_PCH_RXN<3>")
	)
	(segment
		(start 374.1039 -117.22354)
		(end 374.3833 -117.22354)
		(width 0.0889)
		(layer "In2.Cu")
		(net "P3E_CPU0_PE1_PCH_RXN<3>")
	)
	(segment
		(start 367.246916 -117.6655)
		(end 370.33454 -117.6655)
		(width 0.1143)
		(layer "In2.Cu")
		(net "P3E_CPU0_PE1_PCH_RXN<3>")
	)
	(segment
		(start 337.834986 -68.6435)
		(end 335.732628 -68.6435)
		(width 0.1143)
		(layer "In2.Cu")
		(net "P3E_CPU0_PE1_PCH_RXN<3>")
	)
	(segment
		(start 332.078076 -77.175106)
		(end 332.990698 -81.658714)
		(width 0.1143)
		(layer "In2.Cu")
		(net "P3E_CPU0_PE1_PCH_RXN<3>")
	)
	(segment
		(start 351.53981 -85.871812)
		(end 351.98177 -85.785706)
		(width 0.1143)
		(layer "In2.Cu")
		(net "P3E_CPU0_PE1_PCH_RXN<3>")
	)
	(segment
		(start 339.77199 -68.15709)
		(end 338.321396 -68.15709)
		(width 0.1143)
		(layer "In2.Cu")
		(net "P3E_CPU0_PE1_PCH_RXN<3>")
	)
	(segment
		(start 359.400856 -94.122494)
		(end 361.036362 -94.450154)
		(width 0.1143)
		(layer "In2.Cu")
		(net "P3E_CPU0_PE1_PCH_RXN<3>")
	)
	(segment
		(start 372.14302 -117.6147)
		(end 372.23192 -117.7036)
		(width 0.0889)
		(layer "In2.Cu")
		(net "P3E_CPU0_PE1_PCH_RXN<3>")
	)
	(segment
		(start 371.77472 -117.7036)
		(end 371.86362 -117.6147)
		(width 0.0889)
		(layer "In2.Cu")
		(net "P3E_CPU0_PE1_PCH_RXN<3>")
	)
	(segment
		(start 372.51132 -117.7036)
		(end 372.60022 -117.6147)
		(width 0.0889)
		(layer "In2.Cu")
		(net "P3E_CPU0_PE1_PCH_RXN<3>")
	)
	(segment
		(start 379.0696 -118.984522)
		(end 378.99086 -118.96344)
		(width 0.0889)
		(layer "In2.Cu")
		(net "P3E_CPU0_PE1_PCH_RXN<3>")
	)
	(segment
		(start 351.98177 -85.785706)
		(end 352.629978 -85.91169)
		(width 0.1143)
		(layer "In2.Cu")
		(net "P3E_CPU0_PE1_PCH_RXN<3>")
	)
	(segment
		(start 361.036362 -94.450154)
		(end 361.326684 -94.643702)
		(width 0.1143)
		(layer "In2.Cu")
		(net "P3E_CPU0_PE1_PCH_RXN<3>")
	)
	(segment
		(start 332.385162 -74.97064)
		(end 332.456028 -75.318874)
		(width 0.1143)
		(layer "In2.Cu")
		(net "P3E_CPU0_PE1_PCH_RXN<3>")
	)
	(segment
		(start 361.326684 -94.643702)
		(end 361.484418 -95.429324)
		(width 0.1143)
		(layer "In2.Cu")
		(net "P3E_CPU0_PE1_PCH_RXN<3>")
	)
	(segment
		(start 374.015 -117.31244)
		(end 374.1039 -117.22354)
		(width 0.0889)
		(layer "In2.Cu")
		(net "P3E_CPU0_PE1_PCH_RXN<3>")
	)
	(segment
		(start 361.22356 -99.16795)
		(end 361.7722 -101.74605)
		(width 0.1143)
		(layer "In2.Cu")
		(net "P3E_CPU0_PE1_PCH_RXN<3>")
	)
	(segment
		(start 355.436424 -86.068916)
		(end 356.322376 -90.626946)
		(width 0.1143)
		(layer "In2.Cu")
		(net "P3E_CPU0_PE1_PCH_RXN<3>")
	)
	(segment
		(start 372.60022 -117.6147)
		(end 372.87962 -117.6147)
		(width 0.0889)
		(layer "In2.Cu")
		(net "P3E_CPU0_PE1_PCH_RXN<3>")
	)
	(segment
		(start 373.7356 -117.31244)
		(end 374.015 -117.31244)
		(width 0.0889)
		(layer "In2.Cu")
		(net "P3E_CPU0_PE1_PCH_RXN<3>")
	)
	(segment
		(start 340.422992 -69.02577)
		(end 340.057232 -68.66001)
		(width 0.1143)
		(layer "In2.Cu")
		(net "P3E_CPU0_PE1_PCH_RXN<3>")
	)
	(segment
		(start 370.407438 -117.6147)
		(end 371.40642 -117.6147)
		(width 0.0889)
		(layer "In2.Cu")
		(net "P3E_CPU0_PE1_PCH_RXN<3>")
	)
	(segment
		(start 362.270548 -110.1852)
		(end 361.969304 -111.292386)
		(width 0.1143)
		(layer "In2.Cu")
		(net "P3E_CPU0_PE1_PCH_RXN<3>")
	)
	(segment
		(start 371.86362 -117.6147)
		(end 372.14302 -117.6147)
		(width 0.0889)
		(layer "In2.Cu")
		(net "P3E_CPU0_PE1_PCH_RXN<3>")
	)
	(segment
		(start 372.87962 -117.6147)
		(end 373.27078 -117.22354)
		(width 0.0889)
		(layer "In2.Cu")
		(net "P3E_CPU0_PE1_PCH_RXN<3>")
	)
	(segment
		(start 361.97667 -112.775746)
		(end 361.671108 -113.894616)
		(width 0.1143)
		(layer "In2.Cu")
		(net "P3E_CPU0_PE1_PCH_RXN<3>")
	)
	(segment
		(start 375.063766 -118.029736)
		(end 375.261378 -118.227348)
		(width 0.0889)
		(layer "In2.Cu")
		(net "P3E_CPU0_PE1_PCH_RXN<3>")
	)
	(segment
		(start 372.23192 -117.7036)
		(end 372.51132 -117.7036)
		(width 0.0889)
		(layer "In2.Cu")
		(net "P3E_CPU0_PE1_PCH_RXN<3>")
	)
	(segment
		(start 332.990698 -81.658714)
		(end 334.324198 -83.674204)
		(width 0.1143)
		(layer "In2.Cu")
		(net "P3E_CPU0_PE1_PCH_RXN<3>")
	)
	(segment
		(start 362.1913 -111.989616)
		(end 361.97794 -112.770666)
		(width 0.1143)
		(layer "In2.Cu")
		(net "P3E_CPU0_PE1_PCH_RXN<3>")
	)
	(segment
		(start 377.736354 -118.94566)
		(end 378.388372 -118.458742)
		(width 0.0889)
		(layer "In2.Cu")
		(net "P3E_CPU0_PE1_PCH_RXN<3>")
	)
	(segment
		(start 337.706462 -85.944456)
		(end 343.38133 -87.212678)
		(width 0.1143)
		(layer "In2.Cu")
		(net "P3E_CPU0_PE1_PCH_RXN<3>")
	)
	(segment
		(start 348.618302 -87.004652)
		(end 350.385888 -86.650068)
		(width 0.1143)
		(layer "In2.Cu")
		(net "P3E_CPU0_PE1_PCH_RXN<3>")
	)
	(segment
		(start 370.356638 -117.6655)
		(end 370.407438 -117.6147)
		(width 0.0889)
		(layer "In2.Cu")
		(net "P3E_CPU0_PE1_PCH_RXN<3>")
	)
	(segment
		(start 361.969304 -111.292386)
		(end 362.1913 -111.989616)
		(width 0.1143)
		(layer "In2.Cu")
		(net "P3E_CPU0_PE1_PCH_RXN<3>")
	)
	(segment
		(start 335.732628 -68.6435)
		(end 331.28077 -70.737984)
		(width 0.1143)
		(layer "In2.Cu")
		(net "P3E_CPU0_PE1_PCH_RXN<3>")
	)
	(segment
		(start 361.7722 -107.833922)
		(end 362.270548 -110.1852)
		(width 0.1143)
		(layer "In2.Cu")
		(net "P3E_CPU0_PE1_PCH_RXN<3>")
	)
	(segment
		(start 345.633802 -86.787228)
		(end 346.659708 -86.994238)
		(width 0.1143)
		(layer "In2.Cu")
		(net "P3E_CPU0_PE1_PCH_RXN<3>")
	)
	(segment
		(start 330.993242 -73.109074)
		(end 332.385162 -74.97064)
		(width 0.1143)
		(layer "In2.Cu")
		(net "P3E_CPU0_PE1_PCH_RXN<3>")
	)
	(segment
		(start 375.063766 -117.904006)
		(end 375.063766 -118.029736)
		(width 0.0889)
		(layer "In2.Cu")
		(net "P3E_CPU0_PE1_PCH_RXN<3>")
	)
	(segment
		(start 371.40642 -117.6147)
		(end 371.49532 -117.7036)
		(width 0.0889)
		(layer "In2.Cu")
		(net "P3E_CPU0_PE1_PCH_RXN<3>")
	)
	(segment
		(start 375.261378 -118.227348)
		(end 375.387108 -118.227348)
		(width 0.0889)
		(layer "In2.Cu")
		(net "P3E_CPU0_PE1_PCH_RXN<3>")
	)
	(segment
		(start 375.584466 -118.424706)
		(end 375.584466 -118.550436)
		(width 0.0889)
		(layer "In2.Cu")
		(net "P3E_CPU0_PE1_PCH_RXN<3>")
	)
	(segment
		(start 361.295188 -96.321626)
		(end 361.561888 -97.574608)
		(width 0.1143)
		(layer "In2.Cu")
		(net "P3E_CPU0_PE1_PCH_RXN<3>")
	)
	(segment
		(start 375.907808 -118.748048)
		(end 376.10542 -118.94566)
		(width 0.0889)
		(layer "In2.Cu")
		(net "P3E_CPU0_PE1_PCH_RXN<3>")
	)
	(segment
		(start 362.30306 -115.52682)
		(end 362.74756 -116.075968)
		(width 0.1143)
		(layer "In2.Cu")
		(net "P3E_CPU0_PE1_PCH_RXN<3>")
	)
	(segment
		(start 332.456028 -75.318874)
		(end 332.078076 -77.175106)
		(width 0.1143)
		(layer "In2.Cu")
		(net "P3E_CPU0_PE1_PCH_RXN<3>")
	)
	(segment
		(start 340.057232 -68.442332)
		(end 339.77199 -68.15709)
		(width 0.1143)
		(layer "In2.Cu")
		(net "P3E_CPU0_PE1_PCH_RXN<3>")
	)
	(segment
		(start 374.866154 -117.706394)
		(end 375.063766 -117.904006)
		(width 0.0889)
		(layer "In2.Cu")
		(net "P3E_CPU0_PE1_PCH_RXN<3>")
	)
	(segment
		(start 373.27078 -117.22354)
		(end 373.6467 -117.22354)
		(width 0.0889)
		(layer "In2.Cu")
		(net "P3E_CPU0_PE1_PCH_RXN<3>")
	)
	(segment
		(start 347.91523 -86.722204)
		(end 348.618302 -87.004652)
		(width 0.1143)
		(layer "In2.Cu")
		(net "P3E_CPU0_PE1_PCH_RXN<3>")
	)
	(arc
		(start 379.222 -118.6815)
		(mid 379.179467 -118.849937)
		(end 379.0696 -118.984522)
		(width 0.0889)
		(layer "In2.Cu")
		(net "P3E_CPU0_PE1_PCH_RXN<3>")
	)
	(arc
		(start 378.622052 -118.323614)
		(mid 378.82195 -118.270115)
		(end 379.021848 -118.323614)
		(width 0.0889)
		(layer "In2.Cu")
		(net "P3E_CPU0_PE1_PCH_RXN<3>")
	)
	(arc
		(start 379.021848 -118.323614)
		(mid 379.165652 -118.465297)
		(end 379.222 -118.659148)
		(width 0.0889)
		(layer "In2.Cu")
		(net "P3E_CPU0_PE1_PCH_RXN<3>")
	)
	(segment
		(start 377.90755 -117.790722)
		(end 378.1171 -117.888004)
		(width 0.1143)
		(layer "F.Cu")
		(net "P3E_CPU0_PE1_PCH_RXN<2>")
	)
	(segment
		(start 378.1171 -117.888004)
		(end 378.32665 -117.811804)
		(width 0.1143)
		(layer "F.Cu")
		(net "P3E_CPU0_PE1_PCH_RXN<2>")
	)
	(segment
		(start 377.83135 -117.58168)
		(end 377.90755 -117.790722)
		(width 0.1143)
		(layer "F.Cu")
		(net "P3E_CPU0_PE1_PCH_RXN<2>")
	)
	(via
		(at 378.32665 -117.811804)
		(size 0.508)
		(drill 0.254)
		(layers "F.Cu" "B.Cu")
		(net "P3E_CPU0_PE1_PCH_RXN<2>")
	)
	(via
		(at 338.75472 -70.11289)
		(size 0.508)
		(drill 0.254)
		(layers "F.Cu" "B.Cu")
		(net "P3E_CPU0_PE1_PCH_RXN<2>")
	)
	(via
		(at 337.77301 -64.898778)
		(size 0.508)
		(drill 0.254)
		(layers "F.Cu" "B.Cu")
		(net "P3E_CPU0_PE1_PCH_RXN<2>")
	)
	(segment
		(start 338.75472 -70.11289)
		(end 338.3788 -69.73697)
		(width 0.1143)
		(layer "B.Cu")
		(net "P3E_CPU0_PE1_PCH_RXN<2>")
	)
	(segment
		(start 337.77301 -64.898778)
		(end 337.77301 -64.385698)
		(width 0.1143)
		(layer "B.Cu")
		(net "P3E_CPU0_PE1_PCH_RXN<2>")
	)
	(segment
		(start 339.778848 -61.810392)
		(end 340.331806 -61.257434)
		(width 0.1143)
		(layer "B.Cu")
		(net "P3E_CPU0_PE1_PCH_RXN<2>")
	)
	(segment
		(start 337.77301 -68.17741)
		(end 337.77301 -64.898778)
		(width 0.1143)
		(layer "B.Cu")
		(net "P3E_CPU0_PE1_PCH_RXN<2>")
	)
	(segment
		(start 339.778848 -62.37986)
		(end 339.778848 -61.810392)
		(width 0.1143)
		(layer "B.Cu")
		(net "P3E_CPU0_PE1_PCH_RXN<2>")
	)
	(segment
		(start 337.77301 -64.385698)
		(end 339.778848 -62.37986)
		(width 0.1143)
		(layer "B.Cu")
		(net "P3E_CPU0_PE1_PCH_RXN<2>")
	)
	(segment
		(start 338.3788 -69.73697)
		(end 338.3788 -68.7832)
		(width 0.1143)
		(layer "B.Cu")
		(net "P3E_CPU0_PE1_PCH_RXN<2>")
	)
	(segment
		(start 338.3788 -68.7832)
		(end 337.77301 -68.17741)
		(width 0.1143)
		(layer "B.Cu")
		(net "P3E_CPU0_PE1_PCH_RXN<2>")
	)
	(segment
		(start 377.892056 -117.811804)
		(end 378.32665 -117.811804)
		(width 0.089408)
		(layer "In2.Cu")
		(net "P3E_CPU0_PE1_PCH_RXN<2>")
	)
	(segment
		(start 356.20071 -85.26272)
		(end 356.098094 -85.790786)
		(width 0.1143)
		(layer "In2.Cu")
		(net "P3E_CPU0_PE1_PCH_RXN<2>")
	)
	(segment
		(start 364.30585 -110.882938)
		(end 364.80877 -112.46231)
		(width 0.1143)
		(layer "In2.Cu")
		(net "P3E_CPU0_PE1_PCH_RXN<2>")
	)
	(segment
		(start 351.906078 -84.870544)
		(end 352.69551 -85.02396)
		(width 0.1143)
		(layer "In2.Cu")
		(net "P3E_CPU0_PE1_PCH_RXN<2>")
	)
	(segment
		(start 377.791218 -118.175024)
		(end 377.791218 -117.912642)
		(width 0.089408)
		(layer "In2.Cu")
		(net "P3E_CPU0_PE1_PCH_RXN<2>")
	)
	(segment
		(start 371.036088 -116.242592)
		(end 371.058186 -116.242592)
		(width 0.0889)
		(layer "In2.Cu")
		(net "P3E_CPU0_PE1_PCH_RXN<2>")
	)
	(segment
		(start 331.84973 -71.182738)
		(end 331.523848 -72.314562)
		(width 0.1143)
		(layer "In2.Cu")
		(net "P3E_CPU0_PE1_PCH_RXN<2>")
	)
	(segment
		(start 374.280684 -116.191792)
		(end 376.500898 -118.412006)
		(width 0.0889)
		(layer "In2.Cu")
		(net "P3E_CPU0_PE1_PCH_RXN<2>")
	)
	(segment
		(start 356.098094 -85.790786)
		(end 356.983538 -90.34653)
		(width 0.1143)
		(layer "In2.Cu")
		(net "P3E_CPU0_PE1_PCH_RXN<2>")
	)
	(segment
		(start 362.4072 -107.556554)
		(end 362.89488 -109.85881)
		(width 0.1143)
		(layer "In2.Cu")
		(net "P3E_CPU0_PE1_PCH_RXN<2>")
	)
	(segment
		(start 335.101438 -82.732118)
		(end 345.175332 -85.461856)
		(width 0.1143)
		(layer "In2.Cu")
		(net "P3E_CPU0_PE1_PCH_RXN<2>")
	)
	(segment
		(start 377.791218 -117.912642)
		(end 377.892056 -117.811804)
		(width 0.089408)
		(layer "In2.Cu")
		(net "P3E_CPU0_PE1_PCH_RXN<2>")
	)
	(segment
		(start 376.500898 -118.412006)
		(end 377.554236 -118.412006)
		(width 0.0889)
		(layer "In2.Cu")
		(net "P3E_CPU0_PE1_PCH_RXN<2>")
	)
	(segment
		(start 361.965748 -96.375982)
		(end 362.217716 -97.559368)
		(width 0.1143)
		(layer "In2.Cu")
		(net "P3E_CPU0_PE1_PCH_RXN<2>")
	)
	(segment
		(start 349.421196 -85.91169)
		(end 350.12122 -85.7758)
		(width 0.1143)
		(layer "In2.Cu")
		(net "P3E_CPU0_PE1_PCH_RXN<2>")
	)
	(segment
		(start 333.732886 -80.66405)
		(end 333.73314 -80.66405)
		(width 0.1143)
		(layer "In2.Cu")
		(net "P3E_CPU0_PE1_PCH_RXN<2>")
	)
	(segment
		(start 346.086684 -85.176868)
		(end 347.042994 -85.503258)
		(width 0.1143)
		(layer "In2.Cu")
		(net "P3E_CPU0_PE1_PCH_RXN<2>")
	)
	(segment
		(start 347.85935 -85.293454)
		(end 348.628462 -85.715602)
		(width 0.1143)
		(layer "In2.Cu")
		(net "P3E_CPU0_PE1_PCH_RXN<2>")
	)
	(segment
		(start 350.12122 -85.7758)
		(end 351.284032 -84.991448)
		(width 0.1143)
		(layer "In2.Cu")
		(net "P3E_CPU0_PE1_PCH_RXN<2>")
	)
	(segment
		(start 361.688888 -93.628464)
		(end 362.20781 -95.235522)
		(width 0.1143)
		(layer "In2.Cu")
		(net "P3E_CPU0_PE1_PCH_RXN<2>")
	)
	(segment
		(start 356.138988 -84.944966)
		(end 356.20071 -85.26272)
		(width 0.1143)
		(layer "In2.Cu")
		(net "P3E_CPU0_PE1_PCH_RXN<2>")
	)
	(segment
		(start 333.73314 -80.66405)
		(end 335.101438 -82.732118)
		(width 0.1143)
		(layer "In2.Cu")
		(net "P3E_CPU0_PE1_PCH_RXN<2>")
	)
	(segment
		(start 332.849982 -76.9493)
		(end 333.549498 -80.386682)
		(width 0.1143)
		(layer "In2.Cu")
		(net "P3E_CPU0_PE1_PCH_RXN<2>")
	)
	(segment
		(start 362.89488 -109.85881)
		(end 364.30585 -110.882938)
		(width 0.1143)
		(layer "In2.Cu")
		(net "P3E_CPU0_PE1_PCH_RXN<2>")
	)
	(segment
		(start 371.108986 -116.191792)
		(end 374.280684 -116.191792)
		(width 0.0889)
		(layer "In2.Cu")
		(net "P3E_CPU0_PE1_PCH_RXN<2>")
	)
	(segment
		(start 356.014274 -84.7598)
		(end 356.138988 -84.944966)
		(width 0.1143)
		(layer "In2.Cu")
		(net "P3E_CPU0_PE1_PCH_RXN<2>")
	)
	(segment
		(start 331.523848 -72.314562)
		(end 331.628496 -72.87006)
		(width 0.1143)
		(layer "In2.Cu")
		(net "P3E_CPU0_PE1_PCH_RXN<2>")
	)
	(segment
		(start 331.628496 -72.87006)
		(end 333.078074 -74.809096)
		(width 0.1143)
		(layer "In2.Cu")
		(net "P3E_CPU0_PE1_PCH_RXN<2>")
	)
	(segment
		(start 347.042994 -85.503258)
		(end 347.85935 -85.293454)
		(width 0.1143)
		(layer "In2.Cu")
		(net "P3E_CPU0_PE1_PCH_RXN<2>")
	)
	(segment
		(start 335.857342 -69.29755)
		(end 331.84973 -71.182738)
		(width 0.1143)
		(layer "In2.Cu")
		(net "P3E_CPU0_PE1_PCH_RXN<2>")
	)
	(segment
		(start 333.549498 -80.386682)
		(end 333.732886 -80.66405)
		(width 0.1143)
		(layer "In2.Cu")
		(net "P3E_CPU0_PE1_PCH_RXN<2>")
	)
	(segment
		(start 355.430836 -84.492084)
		(end 355.692202 -84.542884)
		(width 0.1143)
		(layer "In2.Cu")
		(net "P3E_CPU0_PE1_PCH_RXN<2>")
	)
	(segment
		(start 338.75472 -70.11289)
		(end 338.729574 -70.11289)
		(width 0.1143)
		(layer "In2.Cu")
		(net "P3E_CPU0_PE1_PCH_RXN<2>")
	)
	(segment
		(start 360.609134 -92.908374)
		(end 361.688888 -93.628464)
		(width 0.1143)
		(layer "In2.Cu")
		(net "P3E_CPU0_PE1_PCH_RXN<2>")
	)
	(segment
		(start 366.62741 -116.242592)
		(end 371.036088 -116.242592)
		(width 0.1143)
		(layer "In2.Cu")
		(net "P3E_CPU0_PE1_PCH_RXN<2>")
	)
	(segment
		(start 364.896908 -115.103656)
		(end 366.62741 -116.242592)
		(width 0.1143)
		(layer "In2.Cu")
		(net "P3E_CPU0_PE1_PCH_RXN<2>")
	)
	(segment
		(start 362.217716 -97.559368)
		(end 361.875832 -99.169728)
		(width 0.1143)
		(layer "In2.Cu")
		(net "P3E_CPU0_PE1_PCH_RXN<2>")
	)
	(segment
		(start 358.396286 -92.46489)
		(end 360.609134 -92.908374)
		(width 0.1143)
		(layer "In2.Cu")
		(net "P3E_CPU0_PE1_PCH_RXN<2>")
	)
	(segment
		(start 333.181706 -75.318366)
		(end 332.849982 -76.9493)
		(width 0.1143)
		(layer "In2.Cu")
		(net "P3E_CPU0_PE1_PCH_RXN<2>")
	)
	(segment
		(start 364.80877 -112.46231)
		(end 364.461044 -113.73612)
		(width 0.1143)
		(layer "In2.Cu")
		(net "P3E_CPU0_PE1_PCH_RXN<2>")
	)
	(segment
		(start 348.628462 -85.715602)
		(end 349.421196 -85.91169)
		(width 0.1143)
		(layer "In2.Cu")
		(net "P3E_CPU0_PE1_PCH_RXN<2>")
	)
	(segment
		(start 338.511642 -69.703442)
		(end 338.10575 -69.29755)
		(width 0.1143)
		(layer "In2.Cu")
		(net "P3E_CPU0_PE1_PCH_RXN<2>")
	)
	(segment
		(start 338.10575 -69.29755)
		(end 335.857342 -69.29755)
		(width 0.1143)
		(layer "In2.Cu")
		(net "P3E_CPU0_PE1_PCH_RXN<2>")
	)
	(segment
		(start 356.983538 -90.34653)
		(end 358.396286 -92.46489)
		(width 0.1143)
		(layer "In2.Cu")
		(net "P3E_CPU0_PE1_PCH_RXN<2>")
	)
	(segment
		(start 352.69551 -85.02396)
		(end 355.430836 -84.492084)
		(width 0.1143)
		(layer "In2.Cu")
		(net "P3E_CPU0_PE1_PCH_RXN<2>")
	)
	(segment
		(start 362.20781 -95.235522)
		(end 361.965748 -96.375982)
		(width 0.1143)
		(layer "In2.Cu")
		(net "P3E_CPU0_PE1_PCH_RXN<2>")
	)
	(segment
		(start 338.729574 -70.11289)
		(end 338.511642 -69.894958)
		(width 0.1143)
		(layer "In2.Cu")
		(net "P3E_CPU0_PE1_PCH_RXN<2>")
	)
	(segment
		(start 364.461044 -113.73612)
		(end 364.896908 -115.103656)
		(width 0.1143)
		(layer "In2.Cu")
		(net "P3E_CPU0_PE1_PCH_RXN<2>")
	)
	(segment
		(start 362.4072 -101.67112)
		(end 362.4072 -107.556554)
		(width 0.1143)
		(layer "In2.Cu")
		(net "P3E_CPU0_PE1_PCH_RXN<2>")
	)
	(segment
		(start 351.284032 -84.991448)
		(end 351.906078 -84.870544)
		(width 0.1143)
		(layer "In2.Cu")
		(net "P3E_CPU0_PE1_PCH_RXN<2>")
	)
	(segment
		(start 377.554236 -118.412006)
		(end 377.791218 -118.175024)
		(width 0.0889)
		(layer "In2.Cu")
		(net "P3E_CPU0_PE1_PCH_RXN<2>")
	)
	(segment
		(start 371.058186 -116.242592)
		(end 371.108986 -116.191792)
		(width 0.0889)
		(layer "In2.Cu")
		(net "P3E_CPU0_PE1_PCH_RXN<2>")
	)
	(segment
		(start 345.175332 -85.461856)
		(end 346.086684 -85.176868)
		(width 0.1143)
		(layer "In2.Cu")
		(net "P3E_CPU0_PE1_PCH_RXN<2>")
	)
	(segment
		(start 361.875832 -99.169728)
		(end 362.4072 -101.67112)
		(width 0.1143)
		(layer "In2.Cu")
		(net "P3E_CPU0_PE1_PCH_RXN<2>")
	)
	(segment
		(start 355.692202 -84.542884)
		(end 356.014274 -84.7598)
		(width 0.1143)
		(layer "In2.Cu")
		(net "P3E_CPU0_PE1_PCH_RXN<2>")
	)
	(segment
		(start 338.511642 -69.894958)
		(end 338.511642 -69.703442)
		(width 0.1143)
		(layer "In2.Cu")
		(net "P3E_CPU0_PE1_PCH_RXN<2>")
	)
	(segment
		(start 333.078074 -74.809096)
		(end 333.181706 -75.318366)
		(width 0.1143)
		(layer "In2.Cu")
		(net "P3E_CPU0_PE1_PCH_RXN<2>")
	)
	(segment
		(start 380.799848 -118.6688)
		(end 380.80315 -118.670324)
		(width 0.1143)
		(layer "F.Cu")
		(net "P3E_CPU0_PE1_PCH_RXN<1>")
	)
	(segment
		(start 380.30785 -118.4402)
		(end 380.799848 -118.6688)
		(width 0.1143)
		(layer "F.Cu")
		(net "P3E_CPU0_PE1_PCH_RXN<1>")
	)
	(via
		(at 380.80315 -118.670324)
		(size 0.508)
		(drill 0.254)
		(layers "F.Cu" "B.Cu")
		(net "P3E_CPU0_PE1_PCH_RXN<1>")
	)
	(via
		(at 336.41284 -66.284348)
		(size 0.508)
		(drill 0.254)
		(layers "F.Cu" "B.Cu")
		(net "P3E_CPU0_PE1_PCH_RXN<1>")
	)
	(via
		(at 337.119722 -71.034402)
		(size 0.508)
		(drill 0.254)
		(layers "F.Cu" "B.Cu")
		(net "P3E_CPU0_PE1_PCH_RXN<1>")
	)
	(segment
		(start 336.7405 -70.13829)
		(end 336.7405 -70.65518)
		(width 0.1143)
		(layer "B.Cu")
		(net "P3E_CPU0_PE1_PCH_RXN<1>")
	)
	(segment
		(start 336.980022 -62.155578)
		(end 336.980022 -62.942978)
		(width 0.1143)
		(layer "B.Cu")
		(net "P3E_CPU0_PE1_PCH_RXN<1>")
	)
	(segment
		(start 336.7405 -70.65518)
		(end 337.119722 -71.034402)
		(width 0.1143)
		(layer "B.Cu")
		(net "P3E_CPU0_PE1_PCH_RXN<1>")
	)
	(segment
		(start 336.41284 -66.284348)
		(end 336.41284 -69.81063)
		(width 0.1143)
		(layer "B.Cu")
		(net "P3E_CPU0_PE1_PCH_RXN<1>")
	)
	(segment
		(start 336.41284 -69.81063)
		(end 336.7405 -70.13829)
		(width 0.1143)
		(layer "B.Cu")
		(net "P3E_CPU0_PE1_PCH_RXN<1>")
	)
	(segment
		(start 337.537806 -61.597794)
		(end 336.980022 -62.155578)
		(width 0.1143)
		(layer "B.Cu")
		(net "P3E_CPU0_PE1_PCH_RXN<1>")
	)
	(segment
		(start 336.41284 -63.51016)
		(end 336.41284 -66.284348)
		(width 0.1143)
		(layer "B.Cu")
		(net "P3E_CPU0_PE1_PCH_RXN<1>")
	)
	(segment
		(start 337.537806 -61.257434)
		(end 337.537806 -61.597794)
		(width 0.1143)
		(layer "B.Cu")
		(net "P3E_CPU0_PE1_PCH_RXN<1>")
	)
	(segment
		(start 336.980022 -62.942978)
		(end 336.41284 -63.51016)
		(width 0.1143)
		(layer "B.Cu")
		(net "P3E_CPU0_PE1_PCH_RXN<1>")
	)
	(segment
		(start 350.880426 -83.425284)
		(end 353.934014 -82.831432)
		(width 0.1143)
		(layer "In2.Cu")
		(net "P3E_CPU0_PE1_PCH_RXN<1>")
	)
	(segment
		(start 373.336566 -113.75898)
		(end 373.615966 -113.75898)
		(width 0.0889)
		(layer "In2.Cu")
		(net "P3E_CPU0_PE1_PCH_RXN<1>")
	)
	(segment
		(start 336.706972 -70.408546)
		(end 336.44713 -70.099428)
		(width 0.1143)
		(layer "In2.Cu")
		(net "P3E_CPU0_PE1_PCH_RXN<1>")
	)
	(segment
		(start 334.461866 -79.02448)
		(end 339.03285 -82.45094)
		(width 0.1143)
		(layer "In2.Cu")
		(net "P3E_CPU0_PE1_PCH_RXN<1>")
	)
	(segment
		(start 371.037866 -113.67008)
		(end 371.126766 -113.75898)
		(width 0.0889)
		(layer "In2.Cu")
		(net "P3E_CPU0_PE1_PCH_RXN<1>")
	)
	(segment
		(start 380.465076 -118.670324)
		(end 380.80315 -118.670324)
		(width 0.0889)
		(layer "In2.Cu")
		(net "P3E_CPU0_PE1_PCH_RXN<1>")
	)
	(segment
		(start 370.758466 -113.67008)
		(end 371.037866 -113.67008)
		(width 0.0889)
		(layer "In2.Cu")
		(net "P3E_CPU0_PE1_PCH_RXN<1>")
	)
	(segment
		(start 356.836726 -85.925406)
		(end 357.544878 -89.469468)
		(width 0.1143)
		(layer "In2.Cu")
		(net "P3E_CPU0_PE1_PCH_RXN<1>")
	)
	(segment
		(start 357.005636 -85.056726)
		(end 356.83698 -85.924644)
		(width 0.1143)
		(layer "In2.Cu")
		(net "P3E_CPU0_PE1_PCH_RXN<1>")
	)
	(segment
		(start 369.443508 -113.842292)
		(end 369.61572 -113.67008)
		(width 0.0889)
		(layer "In2.Cu")
		(net "P3E_CPU0_PE1_PCH_RXN<1>")
	)
	(segment
		(start 333.612744 -76.767182)
		(end 333.612998 -76.767182)
		(width 0.1143)
		(layer "In2.Cu")
		(net "P3E_CPU0_PE1_PCH_RXN<1>")
	)
	(segment
		(start 333.16291 -73.600564)
		(end 333.705708 -74.32675)
		(width 0.1143)
		(layer "In2.Cu")
		(net "P3E_CPU0_PE1_PCH_RXN<1>")
	)
	(segment
		(start 363.0422 -107.489244)
		(end 363.46638 -109.485176)
		(width 0.1143)
		(layer "In2.Cu")
		(net "P3E_CPU0_PE1_PCH_RXN<1>")
	)
	(segment
		(start 374.96369 -114.775234)
		(end 375.08942 -114.775234)
		(width 0.0889)
		(layer "In2.Cu")
		(net "P3E_CPU0_PE1_PCH_RXN<1>")
	)
	(segment
		(start 365.134398 -113.6904)
		(end 365.427514 -114.610134)
		(width 0.1143)
		(layer "In2.Cu")
		(net "P3E_CPU0_PE1_PCH_RXN<1>")
	)
	(segment
		(start 337.119722 -71.034402)
		(end 336.706972 -70.621652)
		(width 0.1143)
		(layer "In2.Cu")
		(net "P3E_CPU0_PE1_PCH_RXN<1>")
	)
	(segment
		(start 376.328686 -116.0145)
		(end 377.034806 -116.0145)
		(width 0.0889)
		(layer "In2.Cu")
		(net "P3E_CPU0_PE1_PCH_RXN<1>")
	)
	(segment
		(start 380.7079 -117.794278)
		(end 380.7079 -117.82552)
		(width 0.0889)
		(layer "In2.Cu")
		(net "P3E_CPU0_PE1_PCH_RXN<1>")
	)
	(segment
		(start 380.407164 -118.728236)
		(end 380.465076 -118.670324)
		(width 0.0889)
		(layer "In2.Cu")
		(net "P3E_CPU0_PE1_PCH_RXN<1>")
	)
	(segment
		(start 367.5126 -115.3795)
		(end 367.5634 -115.3287)
		(width 0.0889)
		(layer "In2.Cu")
		(net "P3E_CPU0_PE1_PCH_RXN<1>")
	)
	(segment
		(start 381.2032 -118.652798)
		(end 381.2032 -118.68785)
		(width 0.0889)
		(layer "In2.Cu")
		(net "P3E_CPU0_PE1_PCH_RXN<1>")
	)
	(segment
		(start 374.245378 -113.931192)
		(end 374.245378 -114.056922)
		(width 0.0889)
		(layer "In2.Cu")
		(net "P3E_CPU0_PE1_PCH_RXN<1>")
	)
	(segment
		(start 371.774466 -113.67008)
		(end 371.863366 -113.75898)
		(width 0.0889)
		(layer "In2.Cu")
		(net "P3E_CPU0_PE1_PCH_RXN<1>")
	)
	(segment
		(start 374.766078 -114.577622)
		(end 374.96369 -114.775234)
		(width 0.0889)
		(layer "In2.Cu")
		(net "P3E_CPU0_PE1_PCH_RXN<1>")
	)
	(segment
		(start 375.610374 -115.296188)
		(end 375.807732 -115.493546)
		(width 0.0889)
		(layer "In2.Cu")
		(net "P3E_CPU0_PE1_PCH_RXN<1>")
	)
	(segment
		(start 334.46212 -79.02448)
		(end 334.461866 -79.02448)
		(width 0.1143)
		(layer "In2.Cu")
		(net "P3E_CPU0_PE1_PCH_RXN<1>")
	)
	(segment
		(start 362.636054 -96.466152)
		(end 362.874306 -97.590102)
		(width 0.1143)
		(layer "In2.Cu")
		(net "P3E_CPU0_PE1_PCH_RXN<1>")
	)
	(segment
		(start 369.61572 -113.67008)
		(end 370.301266 -113.67008)
		(width 0.0889)
		(layer "In2.Cu")
		(net "P3E_CPU0_PE1_PCH_RXN<1>")
	)
	(segment
		(start 333.232506 -71.293736)
		(end 333.232252 -71.294498)
		(width 0.1143)
		(layer "In2.Cu")
		(net "P3E_CPU0_PE1_PCH_RXN<1>")
	)
	(segment
		(start 336.44713 -70.099428)
		(end 335.955894 -70.014084)
		(width 0.1143)
		(layer "In2.Cu")
		(net "P3E_CPU0_PE1_PCH_RXN<1>")
	)
	(segment
		(start 374.245378 -114.056922)
		(end 374.442736 -114.25428)
		(width 0.0889)
		(layer "In2.Cu")
		(net "P3E_CPU0_PE1_PCH_RXN<1>")
	)
	(segment
		(start 363.0422 -101.55174)
		(end 363.0422 -107.489244)
		(width 0.1143)
		(layer "In2.Cu")
		(net "P3E_CPU0_PE1_PCH_RXN<1>")
	)
	(segment
		(start 374.766078 -114.451892)
		(end 374.766078 -114.577622)
		(width 0.0889)
		(layer "In2.Cu")
		(net "P3E_CPU0_PE1_PCH_RXN<1>")
	)
	(segment
		(start 362.54817 -99.127564)
		(end 363.0422 -101.55174)
		(width 0.1143)
		(layer "In2.Cu")
		(net "P3E_CPU0_PE1_PCH_RXN<1>")
	)
	(segment
		(start 377.633484 -117.624098)
		(end 377.852178 -117.624098)
		(width 0.0889)
		(layer "In2.Cu")
		(net "P3E_CPU0_PE1_PCH_RXN<1>")
	)
	(segment
		(start 333.81061 -78.355444)
		(end 334.039464 -78.707488)
		(width 0.1143)
		(layer "In2.Cu")
		(net "P3E_CPU0_PE1_PCH_RXN<1>")
	)
	(segment
		(start 373.615966 -113.75898)
		(end 373.704866 -113.67008)
		(width 0.0889)
		(layer "In2.Cu")
		(net "P3E_CPU0_PE1_PCH_RXN<1>")
	)
	(segment
		(start 373.984266 -113.67008)
		(end 374.245378 -113.931192)
		(width 0.0889)
		(layer "In2.Cu")
		(net "P3E_CPU0_PE1_PCH_RXN<1>")
	)
	(segment
		(start 371.406166 -113.75898)
		(end 371.495066 -113.67008)
		(width 0.0889)
		(layer "In2.Cu")
		(net "P3E_CPU0_PE1_PCH_RXN<1>")
	)
	(segment
		(start 373.704866 -113.67008)
		(end 373.984266 -113.67008)
		(width 0.0889)
		(layer "In2.Cu")
		(net "P3E_CPU0_PE1_PCH_RXN<1>")
	)
	(segment
		(start 370.301266 -113.67008)
		(end 370.390166 -113.75898)
		(width 0.0889)
		(layer "In2.Cu")
		(net "P3E_CPU0_PE1_PCH_RXN<1>")
	)
	(segment
		(start 369.443508 -113.968022)
		(end 369.443508 -113.842292)
		(width 0.0889)
		(layer "In2.Cu")
		(net "P3E_CPU0_PE1_PCH_RXN<1>")
	)
	(segment
		(start 356.889812 -84.461604)
		(end 357.005636 -85.056726)
		(width 0.1143)
		(layer "In2.Cu")
		(net "P3E_CPU0_PE1_PCH_RXN<1>")
	)
	(segment
		(start 377.2027 -116.182394)
		(end 377.2027 -117.193314)
		(width 0.0889)
		(layer "In2.Cu")
		(net "P3E_CPU0_PE1_PCH_RXN<1>")
	)
	(segment
		(start 348.286324 -83.7184)
		(end 350.337374 -83.319874)
		(width 0.1143)
		(layer "In2.Cu")
		(net "P3E_CPU0_PE1_PCH_RXN<1>")
	)
	(segment
		(start 353.934014 -82.831432)
		(end 356.070916 -83.246976)
		(width 0.1143)
		(layer "In2.Cu")
		(net "P3E_CPU0_PE1_PCH_RXN<1>")
	)
	(segment
		(start 356.070916 -83.246976)
		(end 356.889812 -84.461604)
		(width 0.1143)
		(layer "In2.Cu")
		(net "P3E_CPU0_PE1_PCH_RXN<1>")
	)
	(segment
		(start 365.485934 -112.40262)
		(end 365.134398 -113.6904)
		(width 0.1143)
		(layer "In2.Cu")
		(net "P3E_CPU0_PE1_PCH_RXN<1>")
	)
	(segment
		(start 372.142766 -113.75898)
		(end 372.231666 -113.67008)
		(width 0.0889)
		(layer "In2.Cu")
		(net "P3E_CPU0_PE1_PCH_RXN<1>")
	)
	(segment
		(start 368.725196 -114.686334)
		(end 368.922808 -114.488722)
		(width 0.0889)
		(layer "In2.Cu")
		(net "P3E_CPU0_PE1_PCH_RXN<1>")
	)
	(segment
		(start 345.94038 -83.374484)
		(end 346.866972 -83.632548)
		(width 0.1143)
		(layer "In2.Cu")
		(net "P3E_CPU0_PE1_PCH_RXN<1>")
	)
	(segment
		(start 350.337374 -83.319874)
		(end 350.880426 -83.425284)
		(width 0.1143)
		(layer "In2.Cu")
		(net "P3E_CPU0_PE1_PCH_RXN<1>")
	)
	(segment
		(start 375.08942 -114.775234)
		(end 375.287032 -114.972846)
		(width 0.0889)
		(layer "In2.Cu")
		(net "P3E_CPU0_PE1_PCH_RXN<1>")
	)
	(segment
		(start 367.9571 -115.3287)
		(end 368.599466 -114.686334)
		(width 0.0889)
		(layer "In2.Cu")
		(net "P3E_CPU0_PE1_PCH_RXN<1>")
	)
	(segment
		(start 377.034806 -116.0145)
		(end 377.2027 -116.182394)
		(width 0.0889)
		(layer "In2.Cu")
		(net "P3E_CPU0_PE1_PCH_RXN<1>")
	)
	(segment
		(start 356.836726 -85.924898)
		(end 356.836726 -85.925406)
		(width 0.1143)
		(layer "In2.Cu")
		(net "P3E_CPU0_PE1_PCH_RXN<1>")
	)
	(segment
		(start 333.907638 -75.318874)
		(end 333.612744 -76.767182)
		(width 0.1143)
		(layer "In2.Cu")
		(net "P3E_CPU0_PE1_PCH_RXN<1>")
	)
	(segment
		(start 369.245896 -114.165634)
		(end 369.443508 -113.968022)
		(width 0.0889)
		(layer "In2.Cu")
		(net "P3E_CPU0_PE1_PCH_RXN<1>")
	)
	(segment
		(start 370.669566 -113.75898)
		(end 370.758466 -113.67008)
		(width 0.0889)
		(layer "In2.Cu")
		(net "P3E_CPU0_PE1_PCH_RXN<1>")
	)
	(segment
		(start 333.612998 -76.767182)
		(end 333.537052 -77.139038)
		(width 0.1143)
		(layer "In2.Cu")
		(net "P3E_CPU0_PE1_PCH_RXN<1>")
	)
	(segment
		(start 377.852178 -117.624098)
		(end 378.126752 -117.46484)
		(width 0.0889)
		(layer "In2.Cu")
		(net "P3E_CPU0_PE1_PCH_RXN<1>")
	)
	(segment
		(start 372.231666 -113.67008)
		(end 372.511066 -113.67008)
		(width 0.0889)
		(layer "In2.Cu")
		(net "P3E_CPU0_PE1_PCH_RXN<1>")
	)
	(segment
		(start 357.544878 -89.469468)
		(end 358.252776 -90.539316)
		(width 0.1143)
		(layer "In2.Cu")
		(net "P3E_CPU0_PE1_PCH_RXN<1>")
	)
	(segment
		(start 336.706972 -70.621652)
		(end 336.706972 -70.408546)
		(width 0.1143)
		(layer "In2.Cu")
		(net "P3E_CPU0_PE1_PCH_RXN<1>")
	)
	(segment
		(start 364.88624 -110.515908)
		(end 365.485934 -112.40262)
		(width 0.1143)
		(layer "In2.Cu")
		(net "P3E_CPU0_PE1_PCH_RXN<1>")
	)
	(segment
		(start 333.232252 -71.294498)
		(end 333.232506 -71.294498)
		(width 0.1143)
		(layer "In2.Cu")
		(net "P3E_CPU0_PE1_PCH_RXN<1>")
	)
	(segment
		(start 333.705708 -74.32675)
		(end 333.907638 -75.318874)
		(width 0.1143)
		(layer "In2.Cu")
		(net "P3E_CPU0_PE1_PCH_RXN<1>")
	)
	(segment
		(start 371.126766 -113.75898)
		(end 371.406166 -113.75898)
		(width 0.0889)
		(layer "In2.Cu")
		(net "P3E_CPU0_PE1_PCH_RXN<1>")
	)
	(segment
		(start 343.234264 -84.171028)
		(end 345.94038 -83.374484)
		(width 0.1143)
		(layer "In2.Cu")
		(net "P3E_CPU0_PE1_PCH_RXN<1>")
	)
	(segment
		(start 376.005344 -115.816888)
		(end 376.131074 -115.816888)
		(width 0.0889)
		(layer "In2.Cu")
		(net "P3E_CPU0_PE1_PCH_RXN<1>")
	)
	(segment
		(start 372.879366 -113.75898)
		(end 372.968266 -113.67008)
		(width 0.0889)
		(layer "In2.Cu")
		(net "P3E_CPU0_PE1_PCH_RXN<1>")
	)
	(segment
		(start 365.427514 -114.610134)
		(end 366.597438 -115.3795)
		(width 0.1143)
		(layer "In2.Cu")
		(net "P3E_CPU0_PE1_PCH_RXN<1>")
	)
	(segment
		(start 375.484644 -115.296188)
		(end 375.610374 -115.296188)
		(width 0.0889)
		(layer "In2.Cu")
		(net "P3E_CPU0_PE1_PCH_RXN<1>")
	)
	(segment
		(start 362.874306 -97.590102)
		(end 362.54817 -99.127564)
		(width 0.1143)
		(layer "In2.Cu")
		(net "P3E_CPU0_PE1_PCH_RXN<1>")
	)
	(segment
		(start 347.588078 -83.464146)
		(end 348.286324 -83.7184)
		(width 0.1143)
		(layer "In2.Cu")
		(net "P3E_CPU0_PE1_PCH_RXN<1>")
	)
	(segment
		(start 366.597438 -115.3795)
		(end 367.490502 -115.3795)
		(width 0.1143)
		(layer "In2.Cu")
		(net "P3E_CPU0_PE1_PCH_RXN<1>")
	)
	(segment
		(start 358.252776 -90.539316)
		(end 362.261912 -93.212412)
		(width 0.1143)
		(layer "In2.Cu")
		(net "P3E_CPU0_PE1_PCH_RXN<1>")
	)
	(segment
		(start 368.599466 -114.686334)
		(end 368.725196 -114.686334)
		(width 0.0889)
		(layer "In2.Cu")
		(net "P3E_CPU0_PE1_PCH_RXN<1>")
	)
	(segment
		(start 373.247666 -113.67008)
		(end 373.336566 -113.75898)
		(width 0.0889)
		(layer "In2.Cu")
		(net "P3E_CPU0_PE1_PCH_RXN<1>")
	)
	(segment
		(start 375.287032 -114.972846)
		(end 375.287032 -115.098576)
		(width 0.0889)
		(layer "In2.Cu")
		(net "P3E_CPU0_PE1_PCH_RXN<1>")
	)
	(segment
		(start 333.537052 -77.139038)
		(end 333.81061 -78.355444)
		(width 0.1143)
		(layer "In2.Cu")
		(net "P3E_CPU0_PE1_PCH_RXN<1>")
	)
	(segment
		(start 368.922808 -114.362992)
		(end 369.120166 -114.165634)
		(width 0.0889)
		(layer "In2.Cu")
		(net "P3E_CPU0_PE1_PCH_RXN<1>")
	)
	(segment
		(start 363.46638 -109.485176)
		(end 364.88624 -110.515908)
		(width 0.1143)
		(layer "In2.Cu")
		(net "P3E_CPU0_PE1_PCH_RXN<1>")
	)
	(segment
		(start 339.03285 -82.45094)
		(end 343.234264 -84.171028)
		(width 0.1143)
		(layer "In2.Cu")
		(net "P3E_CPU0_PE1_PCH_RXN<1>")
	)
	(segment
		(start 371.863366 -113.75898)
		(end 372.142766 -113.75898)
		(width 0.0889)
		(layer "In2.Cu")
		(net "P3E_CPU0_PE1_PCH_RXN<1>")
	)
	(segment
		(start 372.968266 -113.67008)
		(end 373.247666 -113.67008)
		(width 0.0889)
		(layer "In2.Cu")
		(net "P3E_CPU0_PE1_PCH_RXN<1>")
	)
	(segment
		(start 375.807732 -115.493546)
		(end 375.807732 -115.619276)
		(width 0.0889)
		(layer "In2.Cu")
		(net "P3E_CPU0_PE1_PCH_RXN<1>")
	)
	(segment
		(start 371.495066 -113.67008)
		(end 371.774466 -113.67008)
		(width 0.0889)
		(layer "In2.Cu")
		(net "P3E_CPU0_PE1_PCH_RXN<1>")
	)
	(segment
		(start 333.232506 -71.294498)
		(end 332.92796 -72.351646)
		(width 0.1143)
		(layer "In2.Cu")
		(net "P3E_CPU0_PE1_PCH_RXN<1>")
	)
	(segment
		(start 369.120166 -114.165634)
		(end 369.245896 -114.165634)
		(width 0.0889)
		(layer "In2.Cu")
		(net "P3E_CPU0_PE1_PCH_RXN<1>")
	)
	(segment
		(start 375.807732 -115.619276)
		(end 376.005344 -115.816888)
		(width 0.0889)
		(layer "In2.Cu")
		(net "P3E_CPU0_PE1_PCH_RXN<1>")
	)
	(segment
		(start 334.039464 -78.707488)
		(end 334.46212 -79.02448)
		(width 0.1143)
		(layer "In2.Cu")
		(net "P3E_CPU0_PE1_PCH_RXN<1>")
	)
	(segment
		(start 362.90504 -95.201232)
		(end 362.636054 -96.466152)
		(width 0.1143)
		(layer "In2.Cu")
		(net "P3E_CPU0_PE1_PCH_RXN<1>")
	)
	(segment
		(start 372.511066 -113.67008)
		(end 372.599966 -113.75898)
		(width 0.0889)
		(layer "In2.Cu")
		(net "P3E_CPU0_PE1_PCH_RXN<1>")
	)
	(segment
		(start 374.568466 -114.25428)
		(end 374.766078 -114.451892)
		(width 0.0889)
		(layer "In2.Cu")
		(net "P3E_CPU0_PE1_PCH_RXN<1>")
	)
	(segment
		(start 375.287032 -115.098576)
		(end 375.484644 -115.296188)
		(width 0.0889)
		(layer "In2.Cu")
		(net "P3E_CPU0_PE1_PCH_RXN<1>")
	)
	(segment
		(start 346.866972 -83.632548)
		(end 347.588078 -83.464146)
		(width 0.1143)
		(layer "In2.Cu")
		(net "P3E_CPU0_PE1_PCH_RXN<1>")
	)
	(segment
		(start 367.5634 -115.3287)
		(end 367.9571 -115.3287)
		(width 0.0889)
		(layer "In2.Cu")
		(net "P3E_CPU0_PE1_PCH_RXN<1>")
	)
	(segment
		(start 374.442736 -114.25428)
		(end 374.568466 -114.25428)
		(width 0.0889)
		(layer "In2.Cu")
		(net "P3E_CPU0_PE1_PCH_RXN<1>")
	)
	(segment
		(start 335.955894 -70.014084)
		(end 333.232506 -71.293736)
		(width 0.1143)
		(layer "In2.Cu")
		(net "P3E_CPU0_PE1_PCH_RXN<1>")
	)
	(segment
		(start 367.490502 -115.3795)
		(end 367.5126 -115.3795)
		(width 0.0889)
		(layer "In2.Cu")
		(net "P3E_CPU0_PE1_PCH_RXN<1>")
	)
	(segment
		(start 362.261912 -93.212412)
		(end 362.90504 -95.201232)
		(width 0.1143)
		(layer "In2.Cu")
		(net "P3E_CPU0_PE1_PCH_RXN<1>")
	)
	(segment
		(start 332.92796 -72.351646)
		(end 333.16291 -73.600564)
		(width 0.1143)
		(layer "In2.Cu")
		(net "P3E_CPU0_PE1_PCH_RXN<1>")
	)
	(segment
		(start 377.2027 -117.193314)
		(end 377.633484 -117.624098)
		(width 0.0889)
		(layer "In2.Cu")
		(net "P3E_CPU0_PE1_PCH_RXN<1>")
	)
	(segment
		(start 356.83698 -85.924644)
		(end 356.836726 -85.924898)
		(width 0.1143)
		(layer "In2.Cu")
		(net "P3E_CPU0_PE1_PCH_RXN<1>")
	)
	(segment
		(start 368.922808 -114.488722)
		(end 368.922808 -114.362992)
		(width 0.0889)
		(layer "In2.Cu")
		(net "P3E_CPU0_PE1_PCH_RXN<1>")
	)
	(segment
		(start 376.131074 -115.816888)
		(end 376.328686 -116.0145)
		(width 0.0889)
		(layer "In2.Cu")
		(net "P3E_CPU0_PE1_PCH_RXN<1>")
	)
	(segment
		(start 370.390166 -113.75898)
		(end 370.669566 -113.75898)
		(width 0.0889)
		(layer "In2.Cu")
		(net "P3E_CPU0_PE1_PCH_RXN<1>")
	)
	(segment
		(start 372.599966 -113.75898)
		(end 372.879366 -113.75898)
		(width 0.0889)
		(layer "In2.Cu")
		(net "P3E_CPU0_PE1_PCH_RXN<1>")
	)
	(arc
		(start 379.117098 -117.465094)
		(mid 379.31725 -117.411468)
		(end 379.517402 -117.465094)
		(width 0.0889)
		(layer "In2.Cu")
		(net "P3E_CPU0_PE1_PCH_RXN<1>")
	)
	(arc
		(start 378.526802 -117.465094)
		(mid 378.82195 -117.544099)
		(end 379.117098 -117.465094)
		(width 0.0889)
		(layer "In2.Cu")
		(net "P3E_CPU0_PE1_PCH_RXN<1>")
	)
	(arc
		(start 379.517402 -117.465094)
		(mid 379.81255 -117.544099)
		(end 380.107698 -117.465094)
		(width 0.0889)
		(layer "In2.Cu")
		(net "P3E_CPU0_PE1_PCH_RXN<1>")
	)
	(arc
		(start 381.2032 -118.68785)
		(mid 380.823449 -119.069757)
		(end 380.407164 -118.728236)
		(width 0.0889)
		(layer "In2.Cu")
		(net "P3E_CPU0_PE1_PCH_RXN<1>")
	)
	(arc
		(start 381.003302 -118.323614)
		(mid 381.145382 -118.462607)
		(end 381.2032 -118.652798)
		(width 0.0889)
		(layer "In2.Cu")
		(net "P3E_CPU0_PE1_PCH_RXN<1>")
	)
	(arc
		(start 378.126752 -117.46484)
		(mid 378.326823 -117.411375)
		(end 378.526802 -117.465094)
		(width 0.0889)
		(layer "In2.Cu")
		(net "P3E_CPU0_PE1_PCH_RXN<1>")
	)
	(arc
		(start 380.7079 -117.82552)
		(mid 380.790421 -118.113207)
		(end 381.003302 -118.323614)
		(width 0.0889)
		(layer "In2.Cu")
		(net "P3E_CPU0_PE1_PCH_RXN<1>")
	)
	(arc
		(start 380.107698 -117.465094)
		(mid 380.500389 -117.460809)
		(end 380.7079 -117.794278)
		(width 0.0889)
		(layer "In2.Cu")
		(net "P3E_CPU0_PE1_PCH_RXN<1>")
	)
	(segment
		(start 294.3733 -98.995738)
		(end 294.9448 -98.995738)
		(width 0.1143)
		(layer "F.Cu")
		(net "P3E_CPU0_PE1_PCH_RXN<15>")
	)
	(via
		(at 351.348802 -125.392942)
		(size 0.508)
		(drill 0.254)
		(layers "F.Cu" "B.Cu")
		(net "P3E_CPU0_PE1_PCH_RXN<15>")
	)
	(via
		(at 294.9448 -98.995738)
		(size 0.508)
		(drill 0.254)
		(layers "F.Cu" "B.Cu")
		(net "P3E_CPU0_PE1_PCH_RXN<15>")
	)
	(segment
		(start 354.126292 -125.958092)
		(end 354.289614 -125.79477)
		(width 0.1143)
		(layer "B.Cu")
		(net "P3E_CPU0_PE1_PCH_RXN<15>")
	)
	(segment
		(start 351.913952 -125.958092)
		(end 354.126292 -125.958092)
		(width 0.1143)
		(layer "B.Cu")
		(net "P3E_CPU0_PE1_PCH_RXN<15>")
	)
	(segment
		(start 351.348802 -125.392942)
		(end 351.913952 -125.958092)
		(width 0.1143)
		(layer "B.Cu")
		(net "P3E_CPU0_PE1_PCH_RXN<15>")
	)
	(segment
		(start 354.289614 -125.79477)
		(end 354.289614 -125.532642)
		(width 0.1143)
		(layer "B.Cu")
		(net "P3E_CPU0_PE1_PCH_RXN<15>")
	)
	(segment
		(start 296.32148 -99.206304)
		(end 296.31513 -99.195636)
		(width 0.0889)
		(layer "In2.Cu")
		(net "P3E_CPU0_PE1_PCH_RXN<15>")
	)
	(segment
		(start 295.261792 -98.737166)
		(end 295.237916 -98.826574)
		(width 0.0889)
		(layer "In2.Cu")
		(net "P3E_CPU0_PE1_PCH_RXN<15>")
	)
	(segment
		(start 306.272692 -103.00335)
		(end 306.250594 -103.00335)
		(width 0.0889)
		(layer "In2.Cu")
		(net "P3E_CPU0_PE1_PCH_RXN<15>")
	)
	(segment
		(start 325.154544 -119.47017)
		(end 324.091554 -118.0084)
		(width 0.1143)
		(layer "In2.Cu")
		(net "P3E_CPU0_PE1_PCH_RXN<15>")
	)
	(segment
		(start 306.250594 -103.00335)
		(end 306.199794 -103.05415)
		(width 0.0889)
		(layer "In2.Cu")
		(net "P3E_CPU0_PE1_PCH_RXN<15>")
	)
	(segment
		(start 306.199794 -103.05415)
		(end 305.3842 -103.05415)
		(width 0.0889)
		(layer "In2.Cu")
		(net "P3E_CPU0_PE1_PCH_RXN<15>")
	)
	(segment
		(start 326.393302 -123.001786)
		(end 325.154544 -119.47017)
		(width 0.1143)
		(layer "In2.Cu")
		(net "P3E_CPU0_PE1_PCH_RXN<15>")
	)
	(segment
		(start 304.521362 -102.367588)
		(end 300.08449 -102.367588)
		(width 0.0889)
		(layer "In2.Cu")
		(net "P3E_CPU0_PE1_PCH_RXN<15>")
	)
	(segment
		(start 345.505024 -124.26569)
		(end 344.129614 -124.065538)
		(width 0.1143)
		(layer "In2.Cu")
		(net "P3E_CPU0_PE1_PCH_RXN<15>")
	)
	(segment
		(start 350.74225 -125.870716)
		(end 347.872812 -124.100336)
		(width 0.1143)
		(layer "In2.Cu")
		(net "P3E_CPU0_PE1_PCH_RXN<15>")
	)
	(segment
		(start 351.347024 -125.75794)
		(end 351.234248 -125.870716)
		(width 0.1143)
		(layer "In2.Cu")
		(net "P3E_CPU0_PE1_PCH_RXN<15>")
	)
	(segment
		(start 326.933814 -123.74245)
		(end 326.393302 -123.001786)
		(width 0.1143)
		(layer "In2.Cu")
		(net "P3E_CPU0_PE1_PCH_RXN<15>")
	)
	(segment
		(start 296.32148 -98.215704)
		(end 296.31513 -98.205036)
		(width 0.0889)
		(layer "In2.Cu")
		(net "P3E_CPU0_PE1_PCH_RXN<15>")
	)
	(segment
		(start 346.157042 -124.120148)
		(end 345.505024 -124.26569)
		(width 0.1143)
		(layer "In2.Cu")
		(net "P3E_CPU0_PE1_PCH_RXN<15>")
	)
	(segment
		(start 346.559632 -124.22251)
		(end 346.157042 -124.120148)
		(width 0.1143)
		(layer "In2.Cu")
		(net "P3E_CPU0_PE1_PCH_RXN<15>")
	)
	(segment
		(start 305.3842 -103.05415)
		(end 304.822352 -102.492302)
		(width 0.0889)
		(layer "In2.Cu")
		(net "P3E_CPU0_PE1_PCH_RXN<15>")
	)
	(segment
		(start 324.091554 -118.0084)
		(end 324.030848 -117.776752)
		(width 0.1143)
		(layer "In2.Cu")
		(net "P3E_CPU0_PE1_PCH_RXN<15>")
	)
	(segment
		(start 296.31513 -99.195636)
		(end 296.310304 -99.187)
		(width 0.0889)
		(layer "In2.Cu")
		(net "P3E_CPU0_PE1_PCH_RXN<15>")
	)
	(segment
		(start 347.872812 -124.100336)
		(end 346.832936 -124.292106)
		(width 0.1143)
		(layer "In2.Cu")
		(net "P3E_CPU0_PE1_PCH_RXN<15>")
	)
	(segment
		(start 344.129614 -124.065538)
		(end 342.623902 -124.380498)
		(width 0.1143)
		(layer "In2.Cu")
		(net "P3E_CPU0_PE1_PCH_RXN<15>")
	)
	(segment
		(start 295.237916 -98.826574)
		(end 294.9448 -98.995738)
		(width 0.0889)
		(layer "In2.Cu")
		(net "P3E_CPU0_PE1_PCH_RXN<15>")
	)
	(segment
		(start 351.348802 -125.392942)
		(end 351.347024 -125.75794)
		(width 0.1143)
		(layer "In2.Cu")
		(net "P3E_CPU0_PE1_PCH_RXN<15>")
	)
	(segment
		(start 320.049906 -112.088422)
		(end 307.352446 -103.00335)
		(width 0.1143)
		(layer "In2.Cu")
		(net "P3E_CPU0_PE1_PCH_RXN<15>")
	)
	(segment
		(start 296.67962 -100.386134)
		(end 296.643806 -100.386134)
		(width 0.0889)
		(layer "In2.Cu")
		(net "P3E_CPU0_PE1_PCH_RXN<15>")
	)
	(segment
		(start 297.541696 -100.881434)
		(end 297.507914 -100.881434)
		(width 0.0889)
		(layer "In2.Cu")
		(net "P3E_CPU0_PE1_PCH_RXN<15>")
	)
	(segment
		(start 298.39158 -101.376734)
		(end 298.36745 -101.376734)
		(width 0.0889)
		(layer "In2.Cu")
		(net "P3E_CPU0_PE1_PCH_RXN<15>")
	)
	(segment
		(start 342.623902 -124.380498)
		(end 339.154262 -123.698)
		(width 0.1143)
		(layer "In2.Cu")
		(net "P3E_CPU0_PE1_PCH_RXN<15>")
	)
	(segment
		(start 304.822352 -102.492302)
		(end 304.521362 -102.367588)
		(width 0.0889)
		(layer "In2.Cu")
		(net "P3E_CPU0_PE1_PCH_RXN<15>")
	)
	(segment
		(start 295.8211 -97.909634)
		(end 295.78554 -97.909634)
		(width 0.0889)
		(layer "In2.Cu")
		(net "P3E_CPU0_PE1_PCH_RXN<15>")
	)
	(segment
		(start 332.249018 -125.16485)
		(end 326.933814 -123.74245)
		(width 0.1143)
		(layer "In2.Cu")
		(net "P3E_CPU0_PE1_PCH_RXN<15>")
	)
	(segment
		(start 295.29151 -98.205036)
		(end 295.28516 -98.215704)
		(width 0.0889)
		(layer "In2.Cu")
		(net "P3E_CPU0_PE1_PCH_RXN<15>")
	)
	(segment
		(start 324.030848 -117.776752)
		(end 320.049906 -112.088422)
		(width 0.1143)
		(layer "In2.Cu")
		(net "P3E_CPU0_PE1_PCH_RXN<15>")
	)
	(segment
		(start 351.234248 -125.870716)
		(end 350.74225 -125.870716)
		(width 0.1143)
		(layer "In2.Cu")
		(net "P3E_CPU0_PE1_PCH_RXN<15>")
	)
	(segment
		(start 299.254926 -101.872034)
		(end 299.22216 -101.872034)
		(width 0.0889)
		(layer "In2.Cu")
		(net "P3E_CPU0_PE1_PCH_RXN<15>")
	)
	(segment
		(start 346.832936 -124.292106)
		(end 346.559632 -124.22251)
		(width 0.1143)
		(layer "In2.Cu")
		(net "P3E_CPU0_PE1_PCH_RXN<15>")
	)
	(segment
		(start 339.154262 -123.698)
		(end 332.249018 -125.16485)
		(width 0.1143)
		(layer "In2.Cu")
		(net "P3E_CPU0_PE1_PCH_RXN<15>")
	)
	(segment
		(start 307.352446 -103.00335)
		(end 306.272692 -103.00335)
		(width 0.1143)
		(layer "In2.Cu")
		(net "P3E_CPU0_PE1_PCH_RXN<15>")
	)
	(arc
		(start 295.28516 -98.215704)
		(mid 295.212765 -98.473716)
		(end 295.261792 -98.737166)
		(width 0.0889)
		(layer "In2.Cu")
		(net "P3E_CPU0_PE1_PCH_RXN<15>")
	)
	(arc
		(start 299.22216 -101.872034)
		(mid 299.030518 -101.814868)
		(end 298.890436 -101.672136)
		(width 0.0889)
		(layer "In2.Cu")
		(net "P3E_CPU0_PE1_PCH_RXN<15>")
	)
	(arc
		(start 298.36745 -101.376734)
		(mid 298.1736 -101.320384)
		(end 298.031916 -101.176582)
		(width 0.0889)
		(layer "In2.Cu")
		(net "P3E_CPU0_PE1_PCH_RXN<15>")
	)
	(arc
		(start 296.31513 -99.786186)
		(mid 296.394352 -99.497068)
		(end 296.32148 -99.206304)
		(width 0.0889)
		(layer "In2.Cu")
		(net "P3E_CPU0_PE1_PCH_RXN<15>")
	)
	(arc
		(start 298.890436 -101.672136)
		(mid 298.679723 -101.459057)
		(end 298.39158 -101.376734)
		(width 0.0889)
		(layer "In2.Cu")
		(net "P3E_CPU0_PE1_PCH_RXN<15>")
	)
	(arc
		(start 296.31513 -98.205036)
		(mid 296.106522 -97.993104)
		(end 295.8211 -97.909634)
		(width 0.0889)
		(layer "In2.Cu")
		(net "P3E_CPU0_PE1_PCH_RXN<15>")
	)
	(arc
		(start 296.31513 -98.795586)
		(mid 296.394352 -98.506468)
		(end 296.32148 -98.215704)
		(width 0.0889)
		(layer "In2.Cu")
		(net "P3E_CPU0_PE1_PCH_RXN<15>")
	)
	(arc
		(start 298.031916 -101.176582)
		(mid 297.824912 -100.965718)
		(end 297.541696 -100.881434)
		(width 0.0889)
		(layer "In2.Cu")
		(net "P3E_CPU0_PE1_PCH_RXN<15>")
	)
	(arc
		(start 296.310304 -99.187)
		(mid 296.261549 -98.990648)
		(end 296.31513 -98.795586)
		(width 0.0889)
		(layer "In2.Cu")
		(net "P3E_CPU0_PE1_PCH_RXN<15>")
	)
	(arc
		(start 297.17365 -100.681536)
		(mid 296.965042 -100.469604)
		(end 296.67962 -100.386134)
		(width 0.0889)
		(layer "In2.Cu")
		(net "P3E_CPU0_PE1_PCH_RXN<15>")
	)
	(arc
		(start 297.507914 -100.881434)
		(mid 297.314811 -100.824915)
		(end 297.17365 -100.681536)
		(width 0.0889)
		(layer "In2.Cu")
		(net "P3E_CPU0_PE1_PCH_RXN<15>")
	)
	(arc
		(start 300.08449 -102.367588)
		(mid 299.89064 -102.311238)
		(end 299.748956 -102.167436)
		(width 0.0889)
		(layer "In2.Cu")
		(net "P3E_CPU0_PE1_PCH_RXN<15>")
	)
	(arc
		(start 299.748956 -102.167436)
		(mid 299.540348 -101.955504)
		(end 299.254926 -101.872034)
		(width 0.0889)
		(layer "In2.Cu")
		(net "P3E_CPU0_PE1_PCH_RXN<15>")
	)
	(arc
		(start 296.643806 -100.386134)
		(mid 296.310837 -100.178586)
		(end 296.31513 -99.786186)
		(width 0.0889)
		(layer "In2.Cu")
		(net "P3E_CPU0_PE1_PCH_RXN<15>")
	)
	(arc
		(start 295.78554 -97.909634)
		(mid 295.500116 -97.993101)
		(end 295.29151 -98.205036)
		(width 0.0889)
		(layer "In2.Cu")
		(net "P3E_CPU0_PE1_PCH_RXN<15>")
	)
	(segment
		(start 295.23182 -100.481638)
		(end 295.80332 -100.481638)
		(width 0.1143)
		(layer "F.Cu")
		(net "P3E_CPU0_PE1_PCH_RXN<14>")
	)
	(via
		(at 295.80332 -100.481638)
		(size 0.508)
		(drill 0.254)
		(layers "F.Cu" "B.Cu")
		(net "P3E_CPU0_PE1_PCH_RXN<14>")
	)
	(via
		(at 346.161614 -125.177042)
		(size 0.508)
		(drill 0.254)
		(layers "F.Cu" "B.Cu")
		(net "P3E_CPU0_PE1_PCH_RXN<14>")
	)
	(segment
		(start 349.01886 -125.653292)
		(end 349.133414 -125.538738)
		(width 0.1143)
		(layer "B.Cu")
		(net "P3E_CPU0_PE1_PCH_RXN<14>")
	)
	(segment
		(start 346.637864 -125.653292)
		(end 349.01886 -125.653292)
		(width 0.1143)
		(layer "B.Cu")
		(net "P3E_CPU0_PE1_PCH_RXN<14>")
	)
	(segment
		(start 346.161614 -125.177042)
		(end 346.637864 -125.653292)
		(width 0.1143)
		(layer "B.Cu")
		(net "P3E_CPU0_PE1_PCH_RXN<14>")
	)
	(segment
		(start 349.133414 -125.538738)
		(end 349.133414 -125.227842)
		(width 0.1143)
		(layer "B.Cu")
		(net "P3E_CPU0_PE1_PCH_RXN<14>")
	)
	(segment
		(start 307.254402 -104.21239)
		(end 307.476398 -104.360472)
		(width 0.0889)
		(layer "In2.Cu")
		(net "P3E_CPU0_PE1_PCH_RXN<14>")
	)
	(segment
		(start 295.80332 -100.143564)
		(end 295.745408 -100.085652)
		(width 0.0889)
		(layer "In2.Cu")
		(net "P3E_CPU0_PE1_PCH_RXN<14>")
	)
	(segment
		(start 346.03944 -125.623066)
		(end 346.161614 -125.500892)
		(width 0.1143)
		(layer "In2.Cu")
		(net "P3E_CPU0_PE1_PCH_RXN<14>")
	)
	(segment
		(start 323.903086 -119.152162)
		(end 324.44944 -119.87403)
		(width 0.1143)
		(layer "In2.Cu")
		(net "P3E_CPU0_PE1_PCH_RXN<14>")
	)
	(segment
		(start 298.36745 -102.367588)
		(end 298.400216 -102.367588)
		(width 0.0889)
		(layer "In2.Cu")
		(net "P3E_CPU0_PE1_PCH_RXN<14>")
	)
	(segment
		(start 304.425858 -104.0003)
		(end 304.692558 -104.0003)
		(width 0.0889)
		(layer "In2.Cu")
		(net "P3E_CPU0_PE1_PCH_RXN<14>")
	)
	(segment
		(start 346.161614 -125.500892)
		(end 346.161614 -125.177042)
		(width 0.1143)
		(layer "In2.Cu")
		(net "P3E_CPU0_PE1_PCH_RXN<14>")
	)
	(segment
		(start 299.748956 -103.158036)
		(end 299.77207 -103.198422)
		(width 0.0889)
		(layer "In2.Cu")
		(net "P3E_CPU0_PE1_PCH_RXN<14>")
	)
	(segment
		(start 325.798942 -123.720606)
		(end 326.940418 -125.284738)
		(width 0.1143)
		(layer "In2.Cu")
		(net "P3E_CPU0_PE1_PCH_RXN<14>")
	)
	(segment
		(start 306.909724 -104.0892)
		(end 307.131212 -104.236774)
		(width 0.0889)
		(layer "In2.Cu")
		(net "P3E_CPU0_PE1_PCH_RXN<14>")
	)
	(segment
		(start 344.079068 -124.909072)
		(end 345.596718 -125.341888)
		(width 0.1143)
		(layer "In2.Cu")
		(net "P3E_CPU0_PE1_PCH_RXN<14>")
	)
	(segment
		(start 306.203858 -104.0892)
		(end 306.909724 -104.0892)
		(width 0.0889)
		(layer "In2.Cu")
		(net "P3E_CPU0_PE1_PCH_RXN<14>")
	)
	(segment
		(start 307.131212 -104.237028)
		(end 307.254402 -104.21239)
		(width 0.0889)
		(layer "In2.Cu")
		(net "P3E_CPU0_PE1_PCH_RXN<14>")
	)
	(segment
		(start 299.77207 -103.198422)
		(end 300.009052 -103.435404)
		(width 0.0889)
		(layer "In2.Cu")
		(net "P3E_CPU0_PE1_PCH_RXN<14>")
	)
	(segment
		(start 342.507824 -125.237748)
		(end 344.079068 -124.909072)
		(width 0.1143)
		(layer "In2.Cu")
		(net "P3E_CPU0_PE1_PCH_RXN<14>")
	)
	(segment
		(start 317.252858 -110.939326)
		(end 318.93891 -117.037612)
		(width 0.1143)
		(layer "In2.Cu")
		(net "P3E_CPU0_PE1_PCH_RXN<14>")
	)
	(segment
		(start 295.785286 -100.881434)
		(end 295.8211 -100.881434)
		(width 0.0889)
		(layer "In2.Cu")
		(net "P3E_CPU0_PE1_PCH_RXN<14>")
	)
	(segment
		(start 299.23232 -102.862888)
		(end 299.249846 -102.862888)
		(width 0.0889)
		(layer "In2.Cu")
		(net "P3E_CPU0_PE1_PCH_RXN<14>")
	)
	(segment
		(start 309.331614 -105.643934)
		(end 317.252858 -110.939326)
		(width 0.1143)
		(layer "In2.Cu")
		(net "P3E_CPU0_PE1_PCH_RXN<14>")
	)
	(segment
		(start 345.596718 -125.341888)
		(end 345.877896 -125.623066)
		(width 0.1143)
		(layer "In2.Cu")
		(net "P3E_CPU0_PE1_PCH_RXN<14>")
	)
	(segment
		(start 308.068218 -104.754934)
		(end 308.092856 -104.878124)
		(width 0.0889)
		(layer "In2.Cu")
		(net "P3E_CPU0_PE1_PCH_RXN<14>")
	)
	(segment
		(start 302.307752 -103.042974)
		(end 302.565816 -103.149908)
		(width 0.0889)
		(layer "In2.Cu")
		(net "P3E_CPU0_PE1_PCH_RXN<14>")
	)
	(segment
		(start 322.709794 -118.817644)
		(end 323.903086 -119.152162)
		(width 0.1143)
		(layer "In2.Cu")
		(net "P3E_CPU0_PE1_PCH_RXN<14>")
	)
	(segment
		(start 304.781458 -104.0892)
		(end 305.048158 -104.0892)
		(width 0.0889)
		(layer "In2.Cu")
		(net "P3E_CPU0_PE1_PCH_RXN<14>")
	)
	(segment
		(start 345.877896 -125.623066)
		(end 346.03944 -125.623066)
		(width 0.1143)
		(layer "In2.Cu")
		(net "P3E_CPU0_PE1_PCH_RXN<14>")
	)
	(segment
		(start 297.17365 -101.671882)
		(end 297.176952 -101.677724)
		(width 0.0889)
		(layer "In2.Cu")
		(net "P3E_CPU0_PE1_PCH_RXN<14>")
	)
	(segment
		(start 305.048158 -104.0892)
		(end 305.137058 -104.0003)
		(width 0.0889)
		(layer "In2.Cu")
		(net "P3E_CPU0_PE1_PCH_RXN<14>")
	)
	(segment
		(start 303.800002 -104.0892)
		(end 304.336958 -104.0892)
		(width 0.0889)
		(layer "In2.Cu")
		(net "P3E_CPU0_PE1_PCH_RXN<14>")
	)
	(segment
		(start 309.243476 -105.645712)
		(end 309.331614 -105.643934)
		(width 0.0889)
		(layer "In2.Cu")
		(net "P3E_CPU0_PE1_PCH_RXN<14>")
	)
	(segment
		(start 300.977554 -102.984046)
		(end 301.933356 -102.984046)
		(width 0.0889)
		(layer "In2.Cu")
		(net "P3E_CPU0_PE1_PCH_RXN<14>")
	)
	(segment
		(start 305.759358 -104.0892)
		(end 305.848258 -104.0003)
		(width 0.0889)
		(layer "In2.Cu")
		(net "P3E_CPU0_PE1_PCH_RXN<14>")
	)
	(segment
		(start 330.406248 -126.211838)
		(end 338.594954 -124.472446)
		(width 0.1143)
		(layer "In2.Cu")
		(net "P3E_CPU0_PE1_PCH_RXN<14>")
	)
	(segment
		(start 295.80332 -100.481638)
		(end 295.80332 -100.143564)
		(width 0.0889)
		(layer "In2.Cu")
		(net "P3E_CPU0_PE1_PCH_RXN<14>")
	)
	(segment
		(start 306.114958 -104.0003)
		(end 306.203858 -104.0892)
		(width 0.0889)
		(layer "In2.Cu")
		(net "P3E_CPU0_PE1_PCH_RXN<14>")
	)
	(segment
		(start 297.520106 -101.872034)
		(end 297.537886 -101.872034)
		(width 0.0889)
		(layer "In2.Cu")
		(net "P3E_CPU0_PE1_PCH_RXN<14>")
	)
	(segment
		(start 309.24246 -105.64495)
		(end 309.243476 -105.645712)
		(width 0.0889)
		(layer "In2.Cu")
		(net "P3E_CPU0_PE1_PCH_RXN<14>")
	)
	(segment
		(start 308.092856 -104.878124)
		(end 309.24246 -105.64495)
		(width 0.0889)
		(layer "In2.Cu")
		(net "P3E_CPU0_PE1_PCH_RXN<14>")
	)
	(segment
		(start 302.613822 -103.265986)
		(end 303.233836 -103.523034)
		(width 0.0889)
		(layer "In2.Cu")
		(net "P3E_CPU0_PE1_PCH_RXN<14>")
	)
	(segment
		(start 304.692558 -104.0003)
		(end 304.781458 -104.0892)
		(width 0.0889)
		(layer "In2.Cu")
		(net "P3E_CPU0_PE1_PCH_RXN<14>")
	)
	(segment
		(start 296.650664 -101.376988)
		(end 296.686732 -101.376988)
		(width 0.0889)
		(layer "In2.Cu")
		(net "P3E_CPU0_PE1_PCH_RXN<14>")
	)
	(segment
		(start 301.933356 -102.984046)
		(end 302.19142 -103.09098)
		(width 0.0889)
		(layer "In2.Cu")
		(net "P3E_CPU0_PE1_PCH_RXN<14>")
	)
	(segment
		(start 307.476398 -104.360472)
		(end 307.501036 -104.483662)
		(width 0.0889)
		(layer "In2.Cu")
		(net "P3E_CPU0_PE1_PCH_RXN<14>")
	)
	(segment
		(start 318.93891 -117.037612)
		(end 320.23939 -118.910354)
		(width 0.1143)
		(layer "In2.Cu")
		(net "P3E_CPU0_PE1_PCH_RXN<14>")
	)
	(segment
		(start 307.131212 -104.236774)
		(end 307.131212 -104.237028)
		(width 0.0889)
		(layer "In2.Cu")
		(net "P3E_CPU0_PE1_PCH_RXN<14>")
	)
	(segment
		(start 326.940418 -125.284738)
		(end 330.406248 -126.211838)
		(width 0.1143)
		(layer "In2.Cu")
		(net "P3E_CPU0_PE1_PCH_RXN<14>")
	)
	(segment
		(start 307.501036 -104.483662)
		(end 307.723032 -104.631744)
		(width 0.0889)
		(layer "In2.Cu")
		(net "P3E_CPU0_PE1_PCH_RXN<14>")
	)
	(segment
		(start 307.846222 -104.607106)
		(end 308.068218 -104.754934)
		(width 0.0889)
		(layer "In2.Cu")
		(net "P3E_CPU0_PE1_PCH_RXN<14>")
	)
	(segment
		(start 300.009052 -103.435404)
		(end 300.526196 -103.435404)
		(width 0.0889)
		(layer "In2.Cu")
		(net "P3E_CPU0_PE1_PCH_RXN<14>")
	)
	(segment
		(start 338.594954 -124.472446)
		(end 342.507824 -125.237748)
		(width 0.1143)
		(layer "In2.Cu")
		(net "P3E_CPU0_PE1_PCH_RXN<14>")
	)
	(segment
		(start 307.723032 -104.631744)
		(end 307.846222 -104.607106)
		(width 0.0889)
		(layer "In2.Cu")
		(net "P3E_CPU0_PE1_PCH_RXN<14>")
	)
	(segment
		(start 305.848258 -104.0003)
		(end 306.114958 -104.0003)
		(width 0.0889)
		(layer "In2.Cu")
		(net "P3E_CPU0_PE1_PCH_RXN<14>")
	)
	(segment
		(start 320.23939 -118.910354)
		(end 321.77736 -119.29618)
		(width 0.1143)
		(layer "In2.Cu")
		(net "P3E_CPU0_PE1_PCH_RXN<14>")
	)
	(segment
		(start 305.137058 -104.0003)
		(end 305.403758 -104.0003)
		(width 0.0889)
		(layer "In2.Cu")
		(net "P3E_CPU0_PE1_PCH_RXN<14>")
	)
	(segment
		(start 303.233836 -103.523034)
		(end 303.800002 -104.0892)
		(width 0.0889)
		(layer "In2.Cu")
		(net "P3E_CPU0_PE1_PCH_RXN<14>")
	)
	(segment
		(start 302.19142 -103.09098)
		(end 302.307752 -103.042974)
		(width 0.0889)
		(layer "In2.Cu")
		(net "P3E_CPU0_PE1_PCH_RXN<14>")
	)
	(segment
		(start 321.77736 -119.29618)
		(end 322.709794 -118.817644)
		(width 0.1143)
		(layer "In2.Cu")
		(net "P3E_CPU0_PE1_PCH_RXN<14>")
	)
	(segment
		(start 305.492658 -104.0892)
		(end 305.759358 -104.0892)
		(width 0.0889)
		(layer "In2.Cu")
		(net "P3E_CPU0_PE1_PCH_RXN<14>")
	)
	(segment
		(start 304.336958 -104.0892)
		(end 304.425858 -104.0003)
		(width 0.0889)
		(layer "In2.Cu")
		(net "P3E_CPU0_PE1_PCH_RXN<14>")
	)
	(segment
		(start 300.526196 -103.435404)
		(end 300.977554 -102.984046)
		(width 0.0889)
		(layer "In2.Cu")
		(net "P3E_CPU0_PE1_PCH_RXN<14>")
	)
	(segment
		(start 302.565816 -103.149908)
		(end 302.613822 -103.265986)
		(width 0.0889)
		(layer "In2.Cu")
		(net "P3E_CPU0_PE1_PCH_RXN<14>")
	)
	(segment
		(start 305.403758 -104.0003)
		(end 305.492658 -104.0892)
		(width 0.0889)
		(layer "In2.Cu")
		(net "P3E_CPU0_PE1_PCH_RXN<14>")
	)
	(segment
		(start 324.44944 -119.87403)
		(end 325.798942 -123.720606)
		(width 0.1143)
		(layer "In2.Cu")
		(net "P3E_CPU0_PE1_PCH_RXN<14>")
	)
	(arc
		(start 295.45661 -100.281486)
		(mid 295.403132 -100.477289)
		(end 295.452546 -100.67417)
		(width 0.0889)
		(layer "In2.Cu")
		(net "P3E_CPU0_PE1_PCH_RXN<14>")
	)
	(arc
		(start 297.537886 -101.872034)
		(mid 297.82331 -101.955501)
		(end 298.031916 -102.167436)
		(width 0.0889)
		(layer "In2.Cu")
		(net "P3E_CPU0_PE1_PCH_RXN<14>")
	)
	(arc
		(start 295.452546 -100.67417)
		(mid 295.591808 -100.821305)
		(end 295.785286 -100.881434)
		(width 0.0889)
		(layer "In2.Cu")
		(net "P3E_CPU0_PE1_PCH_RXN<14>")
	)
	(arc
		(start 295.8211 -100.881434)
		(mid 296.106524 -100.964901)
		(end 296.31513 -101.176836)
		(width 0.0889)
		(layer "In2.Cu")
		(net "P3E_CPU0_PE1_PCH_RXN<14>")
	)
	(arc
		(start 295.745408 -100.085652)
		(mid 295.578521 -100.150415)
		(end 295.45661 -100.281486)
		(width 0.0889)
		(layer "In2.Cu")
		(net "P3E_CPU0_PE1_PCH_RXN<14>")
	)
	(arc
		(start 299.249846 -102.862888)
		(mid 299.538038 -102.945091)
		(end 299.748956 -103.158036)
		(width 0.0889)
		(layer "In2.Cu")
		(net "P3E_CPU0_PE1_PCH_RXN<14>")
	)
	(arc
		(start 298.400216 -102.367588)
		(mid 298.683433 -102.451869)
		(end 298.890436 -102.662736)
		(width 0.0889)
		(layer "In2.Cu")
		(net "P3E_CPU0_PE1_PCH_RXN<14>")
	)
	(arc
		(start 296.686732 -101.376988)
		(mid 296.968032 -101.461954)
		(end 297.17365 -101.671882)
		(width 0.0889)
		(layer "In2.Cu")
		(net "P3E_CPU0_PE1_PCH_RXN<14>")
	)
	(arc
		(start 296.31513 -101.176836)
		(mid 296.456813 -101.32064)
		(end 296.650664 -101.376988)
		(width 0.0889)
		(layer "In2.Cu")
		(net "P3E_CPU0_PE1_PCH_RXN<14>")
	)
	(arc
		(start 297.176952 -101.677724)
		(mid 297.322918 -101.820123)
		(end 297.520106 -101.872034)
		(width 0.0889)
		(layer "In2.Cu")
		(net "P3E_CPU0_PE1_PCH_RXN<14>")
	)
	(arc
		(start 298.031916 -102.167436)
		(mid 298.173599 -102.31124)
		(end 298.36745 -102.367588)
		(width 0.0889)
		(layer "In2.Cu")
		(net "P3E_CPU0_PE1_PCH_RXN<14>")
	)
	(arc
		(start 298.890436 -102.662736)
		(mid 299.034884 -102.808067)
		(end 299.23232 -102.862888)
		(width 0.0889)
		(layer "In2.Cu")
		(net "P3E_CPU0_PE1_PCH_RXN<14>")
	)
	(segment
		(start 296.09034 -99.986338)
		(end 296.66184 -99.986338)
		(width 0.1143)
		(layer "F.Cu")
		(net "P3E_CPU0_PE1_PCH_RXN<13>")
	)
	(via
		(at 345.659202 -122.344942)
		(size 0.508)
		(drill 0.254)
		(layers "F.Cu" "B.Cu")
		(net "P3E_CPU0_PE1_PCH_RXN<13>")
	)
	(via
		(at 296.66184 -99.986338)
		(size 0.508)
		(drill 0.254)
		(layers "F.Cu" "B.Cu")
		(net "P3E_CPU0_PE1_PCH_RXN<13>")
	)
	(segment
		(start 348.600014 -122.741182)
		(end 348.456504 -122.884692)
		(width 0.1143)
		(layer "B.Cu")
		(net "P3E_CPU0_PE1_PCH_RXN<13>")
	)
	(segment
		(start 348.600014 -122.459242)
		(end 348.600014 -122.741182)
		(width 0.1143)
		(layer "B.Cu")
		(net "P3E_CPU0_PE1_PCH_RXN<13>")
	)
	(segment
		(start 346.198952 -122.884692)
		(end 345.659202 -122.344942)
		(width 0.1143)
		(layer "B.Cu")
		(net "P3E_CPU0_PE1_PCH_RXN<13>")
	)
	(segment
		(start 348.456504 -122.884692)
		(end 346.198952 -122.884692)
		(width 0.1143)
		(layer "B.Cu")
		(net "P3E_CPU0_PE1_PCH_RXN<13>")
	)
	(segment
		(start 320.062098 -110.906306)
		(end 307.326538 -101.794564)
		(width 0.1143)
		(layer "In2.Cu")
		(net "P3E_CPU0_PE1_PCH_RXN<13>")
	)
	(segment
		(start 306.001928 -101.794564)
		(end 305.97983 -101.794564)
		(width 0.0889)
		(layer "In2.Cu")
		(net "P3E_CPU0_PE1_PCH_RXN<13>")
	)
	(segment
		(start 297.537886 -99.890834)
		(end 297.502326 -99.890834)
		(width 0.0889)
		(layer "In2.Cu")
		(net "P3E_CPU0_PE1_PCH_RXN<13>")
	)
	(segment
		(start 297.04411 -100.131118)
		(end 296.954702 -100.155248)
		(width 0.0889)
		(layer "In2.Cu")
		(net "P3E_CPU0_PE1_PCH_RXN<13>")
	)
	(segment
		(start 299.258736 -100.881434)
		(end 299.22597 -100.881434)
		(width 0.0889)
		(layer "In2.Cu")
		(net "P3E_CPU0_PE1_PCH_RXN<13>")
	)
	(segment
		(start 305.92903 -101.845364)
		(end 305.14925 -101.845364)
		(width 0.0889)
		(layer "In2.Cu")
		(net "P3E_CPU0_PE1_PCH_RXN<13>")
	)
	(segment
		(start 344.75928 -123.04776)
		(end 342.422734 -123.58497)
		(width 0.1143)
		(layer "In2.Cu")
		(net "P3E_CPU0_PE1_PCH_RXN<13>")
	)
	(segment
		(start 305.14925 -101.845364)
		(end 304.863246 -101.55936)
		(width 0.0889)
		(layer "In2.Cu")
		(net "P3E_CPU0_PE1_PCH_RXN<13>")
	)
	(segment
		(start 296.954702 -100.155248)
		(end 296.66184 -99.986338)
		(width 0.0889)
		(layer "In2.Cu")
		(net "P3E_CPU0_PE1_PCH_RXN<13>")
	)
	(segment
		(start 345.513914 -122.814842)
		(end 345.249246 -122.814842)
		(width 0.1143)
		(layer "In2.Cu")
		(net "P3E_CPU0_PE1_PCH_RXN<13>")
	)
	(segment
		(start 307.326538 -101.794564)
		(end 306.001928 -101.794564)
		(width 0.1143)
		(layer "In2.Cu")
		(net "P3E_CPU0_PE1_PCH_RXN<13>")
	)
	(segment
		(start 305.97983 -101.794564)
		(end 305.92903 -101.845364)
		(width 0.0889)
		(layer "In2.Cu")
		(net "P3E_CPU0_PE1_PCH_RXN<13>")
	)
	(segment
		(start 339.436964 -122.9868)
		(end 332.47965 -124.464826)
		(width 0.1143)
		(layer "In2.Cu")
		(net "P3E_CPU0_PE1_PCH_RXN<13>")
	)
	(segment
		(start 325.950072 -119.36603)
		(end 324.908926 -117.933978)
		(width 0.1143)
		(layer "In2.Cu")
		(net "P3E_CPU0_PE1_PCH_RXN<13>")
	)
	(segment
		(start 327.48855 -123.128786)
		(end 327.067672 -122.552206)
		(width 0.1143)
		(layer "In2.Cu")
		(net "P3E_CPU0_PE1_PCH_RXN<13>")
	)
	(segment
		(start 342.422734 -123.58497)
		(end 339.436964 -122.9868)
		(width 0.1143)
		(layer "In2.Cu")
		(net "P3E_CPU0_PE1_PCH_RXN<13>")
	)
	(segment
		(start 345.659202 -122.669554)
		(end 345.513914 -122.814842)
		(width 0.1143)
		(layer "In2.Cu")
		(net "P3E_CPU0_PE1_PCH_RXN<13>")
	)
	(segment
		(start 324.833488 -117.647212)
		(end 320.062098 -110.906306)
		(width 0.1143)
		(layer "In2.Cu")
		(net "P3E_CPU0_PE1_PCH_RXN<13>")
	)
	(segment
		(start 304.863246 -101.55936)
		(end 301.653956 -101.55936)
		(width 0.0889)
		(layer "In2.Cu")
		(net "P3E_CPU0_PE1_PCH_RXN<13>")
	)
	(segment
		(start 301.653956 -101.55936)
		(end 301.341028 -101.872288)
		(width 0.0889)
		(layer "In2.Cu")
		(net "P3E_CPU0_PE1_PCH_RXN<13>")
	)
	(segment
		(start 327.067672 -122.552206)
		(end 325.950072 -119.36603)
		(width 0.1143)
		(layer "In2.Cu")
		(net "P3E_CPU0_PE1_PCH_RXN<13>")
	)
	(segment
		(start 345.659202 -122.344942)
		(end 345.659202 -122.669554)
		(width 0.1143)
		(layer "In2.Cu")
		(net "P3E_CPU0_PE1_PCH_RXN<13>")
	)
	(segment
		(start 300.10862 -101.376734)
		(end 300.08449 -101.376734)
		(width 0.0889)
		(layer "In2.Cu")
		(net "P3E_CPU0_PE1_PCH_RXN<13>")
	)
	(segment
		(start 298.400216 -100.386134)
		(end 298.360592 -100.386134)
		(width 0.0889)
		(layer "In2.Cu")
		(net "P3E_CPU0_PE1_PCH_RXN<13>")
	)
	(segment
		(start 324.908926 -117.933978)
		(end 324.833488 -117.647212)
		(width 0.1143)
		(layer "In2.Cu")
		(net "P3E_CPU0_PE1_PCH_RXN<13>")
	)
	(segment
		(start 301.341028 -101.872288)
		(end 300.943772 -101.872288)
		(width 0.0889)
		(layer "In2.Cu")
		(net "P3E_CPU0_PE1_PCH_RXN<13>")
	)
	(segment
		(start 332.47965 -124.464826)
		(end 327.48855 -123.128786)
		(width 0.1143)
		(layer "In2.Cu")
		(net "P3E_CPU0_PE1_PCH_RXN<13>")
	)
	(segment
		(start 345.249246 -122.814842)
		(end 344.75928 -123.04776)
		(width 0.1143)
		(layer "In2.Cu")
		(net "P3E_CPU0_PE1_PCH_RXN<13>")
	)
	(arc
		(start 299.22597 -100.881434)
		(mid 299.03212 -100.825084)
		(end 298.890436 -100.681282)
		(width 0.0889)
		(layer "In2.Cu")
		(net "P3E_CPU0_PE1_PCH_RXN<13>")
	)
	(arc
		(start 300.9392 -101.872034)
		(mid 300.747558 -101.814868)
		(end 300.607476 -101.672136)
		(width 0.0889)
		(layer "In2.Cu")
		(net "P3E_CPU0_PE1_PCH_RXN<13>")
	)
	(arc
		(start 300.607476 -101.672136)
		(mid 300.396763 -101.459057)
		(end 300.10862 -101.376734)
		(width 0.0889)
		(layer "In2.Cu")
		(net "P3E_CPU0_PE1_PCH_RXN<13>")
	)
	(arc
		(start 300.08449 -101.376734)
		(mid 299.89064 -101.320384)
		(end 299.748956 -101.176582)
		(width 0.0889)
		(layer "In2.Cu")
		(net "P3E_CPU0_PE1_PCH_RXN<13>")
	)
	(arc
		(start 300.943772 -101.872288)
		(mid 300.941486 -101.872168)
		(end 300.9392 -101.872034)
		(width 0.0889)
		(layer "In2.Cu")
		(net "P3E_CPU0_PE1_PCH_RXN<13>")
	)
	(arc
		(start 298.890436 -100.681282)
		(mid 298.683432 -100.470418)
		(end 298.400216 -100.386134)
		(width 0.0889)
		(layer "In2.Cu")
		(net "P3E_CPU0_PE1_PCH_RXN<13>")
	)
	(arc
		(start 299.748956 -101.176582)
		(mid 299.541952 -100.965718)
		(end 299.258736 -100.881434)
		(width 0.0889)
		(layer "In2.Cu")
		(net "P3E_CPU0_PE1_PCH_RXN<13>")
	)
	(arc
		(start 297.502326 -99.890834)
		(mid 297.245504 -99.958135)
		(end 297.04411 -100.131118)
		(width 0.0889)
		(layer "In2.Cu")
		(net "P3E_CPU0_PE1_PCH_RXN<13>")
	)
	(arc
		(start 298.360592 -100.386134)
		(mid 298.170663 -100.328264)
		(end 298.031916 -100.186236)
		(width 0.0889)
		(layer "In2.Cu")
		(net "P3E_CPU0_PE1_PCH_RXN<13>")
	)
	(arc
		(start 298.031916 -100.186236)
		(mid 297.823308 -99.974304)
		(end 297.537886 -99.890834)
		(width 0.0889)
		(layer "In2.Cu")
		(net "P3E_CPU0_PE1_PCH_RXN<13>")
	)
	(segment
		(start 296.948606 -99.490784)
		(end 297.520106 -99.490784)
		(width 0.1143)
		(layer "F.Cu")
		(net "P3E_CPU0_PE1_PCH_RXN<12>")
	)
	(via
		(at 297.520106 -99.490784)
		(size 0.508)
		(drill 0.254)
		(layers "F.Cu" "B.Cu")
		(net "P3E_CPU0_PE1_PCH_RXN<12>")
	)
	(via
		(at 350.708214 -123.822206)
		(size 0.508)
		(drill 0.254)
		(layers "F.Cu" "B.Cu")
		(net "P3E_CPU0_PE1_PCH_RXN<12>")
	)
	(segment
		(start 353.654614 -123.564142)
		(end 353.654614 -123.780042)
		(width 0.1143)
		(layer "B.Cu")
		(net "P3E_CPU0_PE1_PCH_RXN<12>")
	)
	(segment
		(start 350.708214 -123.79833)
		(end 351.171002 -123.335542)
		(width 0.1143)
		(layer "B.Cu")
		(net "P3E_CPU0_PE1_PCH_RXN<12>")
	)
	(segment
		(start 351.171002 -123.335542)
		(end 353.426014 -123.335542)
		(width 0.1143)
		(layer "B.Cu")
		(net "P3E_CPU0_PE1_PCH_RXN<12>")
	)
	(segment
		(start 353.426014 -123.335542)
		(end 353.654614 -123.564142)
		(width 0.1143)
		(layer "B.Cu")
		(net "P3E_CPU0_PE1_PCH_RXN<12>")
	)
	(segment
		(start 350.708214 -123.822206)
		(end 350.708214 -123.79833)
		(width 0.1143)
		(layer "B.Cu")
		(net "P3E_CPU0_PE1_PCH_RXN<12>")
	)
	(segment
		(start 350.708214 -123.822206)
		(end 350.710246 -123.387866)
		(width 0.1143)
		(layer "In2.Cu")
		(net "P3E_CPU0_PE1_PCH_RXN<12>")
	)
	(segment
		(start 306.072286 -101.071934)
		(end 304.90795 -101.071934)
		(width 0.0889)
		(layer "In2.Cu")
		(net "P3E_CPU0_PE1_PCH_RXN<12>")
	)
	(segment
		(start 345.957652 -121.610374)
		(end 345.957652 -121.61012)
		(width 0.1143)
		(layer "In2.Cu")
		(net "P3E_CPU0_PE1_PCH_RXN<12>")
	)
	(segment
		(start 349.453708 -123.124976)
		(end 347.50756 -121.856754)
		(width 0.1143)
		(layer "In2.Cu")
		(net "P3E_CPU0_PE1_PCH_RXN<12>")
	)
	(segment
		(start 328.149204 -121.281952)
		(end 325.386192 -117.795548)
		(width 0.1143)
		(layer "In2.Cu")
		(net "P3E_CPU0_PE1_PCH_RXN<12>")
	)
	(segment
		(start 342.473026 -122.993912)
		(end 340.088728 -122.487944)
		(width 0.1143)
		(layer "In2.Cu")
		(net "P3E_CPU0_PE1_PCH_RXN<12>")
	)
	(segment
		(start 297.90263 -99.346004)
		(end 297.813222 -99.321874)
		(width 0.0889)
		(layer "In2.Cu")
		(net "P3E_CPU0_PE1_PCH_RXN<12>")
	)
	(segment
		(start 343.866978 -122.71502)
		(end 342.473026 -122.993912)
		(width 0.1143)
		(layer "In2.Cu")
		(net "P3E_CPU0_PE1_PCH_RXN<12>")
	)
	(segment
		(start 345.957652 -121.61012)
		(end 345.338908 -121.733818)
		(width 0.1143)
		(layer "In2.Cu")
		(net "P3E_CPU0_PE1_PCH_RXN<12>")
	)
	(segment
		(start 306.145184 -101.122734)
		(end 306.123086 -101.122734)
		(width 0.0889)
		(layer "In2.Cu")
		(net "P3E_CPU0_PE1_PCH_RXN<12>")
	)
	(segment
		(start 324.613524 -113.998756)
		(end 323.835522 -112.82299)
		(width 0.1143)
		(layer "In2.Cu")
		(net "P3E_CPU0_PE1_PCH_RXN<12>")
	)
	(segment
		(start 300.1137 -100.576888)
		(end 300.074076 -100.576888)
		(width 0.0889)
		(layer "In2.Cu")
		(net "P3E_CPU0_PE1_PCH_RXN<12>")
	)
	(segment
		(start 304.90795 -101.071934)
		(end 304.397664 -100.561648)
		(width 0.0889)
		(layer "In2.Cu")
		(net "P3E_CPU0_PE1_PCH_RXN<12>")
	)
	(segment
		(start 329.555094 -122.374152)
		(end 328.149204 -121.281952)
		(width 0.1143)
		(layer "In2.Cu")
		(net "P3E_CPU0_PE1_PCH_RXN<12>")
	)
	(segment
		(start 298.393612 -99.586288)
		(end 298.360846 -99.586288)
		(width 0.0889)
		(layer "In2.Cu")
		(net "P3E_CPU0_PE1_PCH_RXN<12>")
	)
	(segment
		(start 306.123086 -101.122734)
		(end 306.072286 -101.071934)
		(width 0.0889)
		(layer "In2.Cu")
		(net "P3E_CPU0_PE1_PCH_RXN<12>")
	)
	(segment
		(start 300.93666 -101.071934)
		(end 300.936406 -101.072188)
		(width 0.0889)
		(layer "In2.Cu")
		(net "P3E_CPU0_PE1_PCH_RXN<12>")
	)
	(segment
		(start 307.213 -101.122734)
		(end 306.145184 -101.122734)
		(width 0.1143)
		(layer "In2.Cu")
		(net "P3E_CPU0_PE1_PCH_RXN<12>")
	)
	(segment
		(start 340.088728 -122.487944)
		(end 334.175862 -123.743974)
		(width 0.1143)
		(layer "In2.Cu")
		(net "P3E_CPU0_PE1_PCH_RXN<12>")
	)
	(segment
		(start 346.57665 -121.486422)
		(end 345.957652 -121.610374)
		(width 0.1143)
		(layer "In2.Cu")
		(net "P3E_CPU0_PE1_PCH_RXN<12>")
	)
	(segment
		(start 334.175862 -123.743974)
		(end 329.555094 -122.374152)
		(width 0.1143)
		(layer "In2.Cu")
		(net "P3E_CPU0_PE1_PCH_RXN<12>")
	)
	(segment
		(start 347.50756 -121.856754)
		(end 346.57665 -121.486422)
		(width 0.1143)
		(layer "In2.Cu")
		(net "P3E_CPU0_PE1_PCH_RXN<12>")
	)
	(segment
		(start 303.748186 -100.561648)
		(end 303.2379 -101.071934)
		(width 0.0889)
		(layer "In2.Cu")
		(net "P3E_CPU0_PE1_PCH_RXN<12>")
	)
	(segment
		(start 320.2178 -110.427008)
		(end 307.213 -101.122734)
		(width 0.1143)
		(layer "In2.Cu")
		(net "P3E_CPU0_PE1_PCH_RXN<12>")
	)
	(segment
		(start 350.710246 -123.387866)
		(end 350.447356 -123.124976)
		(width 0.1143)
		(layer "In2.Cu")
		(net "P3E_CPU0_PE1_PCH_RXN<12>")
	)
	(segment
		(start 303.2379 -101.071934)
		(end 300.93666 -101.071934)
		(width 0.0889)
		(layer "In2.Cu")
		(net "P3E_CPU0_PE1_PCH_RXN<12>")
	)
	(segment
		(start 304.397664 -100.561648)
		(end 303.748186 -100.561648)
		(width 0.0889)
		(layer "In2.Cu")
		(net "P3E_CPU0_PE1_PCH_RXN<12>")
	)
	(segment
		(start 350.447356 -123.124976)
		(end 349.453708 -123.124976)
		(width 0.1143)
		(layer "In2.Cu")
		(net "P3E_CPU0_PE1_PCH_RXN<12>")
	)
	(segment
		(start 299.248322 -100.081588)
		(end 299.224192 -100.081588)
		(width 0.0889)
		(layer "In2.Cu")
		(net "P3E_CPU0_PE1_PCH_RXN<12>")
	)
	(segment
		(start 325.386192 -117.795548)
		(end 324.613524 -113.998756)
		(width 0.1143)
		(layer "In2.Cu")
		(net "P3E_CPU0_PE1_PCH_RXN<12>")
	)
	(segment
		(start 323.835522 -112.82299)
		(end 320.2178 -110.427008)
		(width 0.1143)
		(layer "In2.Cu")
		(net "P3E_CPU0_PE1_PCH_RXN<12>")
	)
	(segment
		(start 345.338908 -121.733818)
		(end 343.866978 -122.71502)
		(width 0.1143)
		(layer "In2.Cu")
		(net "P3E_CPU0_PE1_PCH_RXN<12>")
	)
	(segment
		(start 297.813222 -99.321874)
		(end 297.520106 -99.490784)
		(width 0.0889)
		(layer "In2.Cu")
		(net "P3E_CPU0_PE1_PCH_RXN<12>")
	)
	(arc
		(start 300.936406 -101.072188)
		(mid 300.650982 -100.988721)
		(end 300.442376 -100.776786)
		(width 0.0889)
		(layer "In2.Cu")
		(net "P3E_CPU0_PE1_PCH_RXN<12>")
	)
	(arc
		(start 298.360846 -99.586288)
		(mid 298.104024 -99.518987)
		(end 297.90263 -99.346004)
		(width 0.0889)
		(layer "In2.Cu")
		(net "P3E_CPU0_PE1_PCH_RXN<12>")
	)
	(arc
		(start 299.224192 -100.081588)
		(mid 298.936047 -99.999269)
		(end 298.725336 -99.786186)
		(width 0.0889)
		(layer "In2.Cu")
		(net "P3E_CPU0_PE1_PCH_RXN<12>")
	)
	(arc
		(start 300.442376 -100.776786)
		(mid 300.303632 -100.634753)
		(end 300.1137 -100.576888)
		(width 0.0889)
		(layer "In2.Cu")
		(net "P3E_CPU0_PE1_PCH_RXN<12>")
	)
	(arc
		(start 300.074076 -100.576888)
		(mid 299.790859 -100.492607)
		(end 299.583856 -100.28174)
		(width 0.0889)
		(layer "In2.Cu")
		(net "P3E_CPU0_PE1_PCH_RXN<12>")
	)
	(arc
		(start 299.583856 -100.28174)
		(mid 299.442173 -100.137936)
		(end 299.248322 -100.081588)
		(width 0.0889)
		(layer "In2.Cu")
		(net "P3E_CPU0_PE1_PCH_RXN<12>")
	)
	(arc
		(start 298.725336 -99.786186)
		(mid 298.585257 -99.64345)
		(end 298.393612 -99.586288)
		(width 0.0889)
		(layer "In2.Cu")
		(net "P3E_CPU0_PE1_PCH_RXN<12>")
	)
	(segment
		(start 296.948606 -98.500184)
		(end 297.520106 -98.500184)
		(width 0.1143)
		(layer "F.Cu")
		(net "P3E_CPU0_PE1_PCH_RXN<11>")
	)
	(via
		(at 358.951022 -122.563128)
		(size 0.508)
		(drill 0.254)
		(layers "F.Cu" "B.Cu")
		(net "P3E_CPU0_PE1_PCH_RXN<11>")
	)
	(via
		(at 297.520106 -98.500184)
		(size 0.508)
		(drill 0.254)
		(layers "F.Cu" "B.Cu")
		(net "P3E_CPU0_PE1_PCH_RXN<11>")
	)
	(segment
		(start 361.564682 -122.071892)
		(end 359.442258 -122.071892)
		(width 0.1143)
		(layer "B.Cu")
		(net "P3E_CPU0_PE1_PCH_RXN<11>")
	)
	(segment
		(start 361.826556 -122.333766)
		(end 361.564682 -122.071892)
		(width 0.1143)
		(layer "B.Cu")
		(net "P3E_CPU0_PE1_PCH_RXN<11>")
	)
	(segment
		(start 359.442258 -122.071892)
		(end 358.951022 -122.563128)
		(width 0.1143)
		(layer "B.Cu")
		(net "P3E_CPU0_PE1_PCH_RXN<11>")
	)
	(segment
		(start 361.826556 -122.510042)
		(end 361.826556 -122.333766)
		(width 0.1143)
		(layer "B.Cu")
		(net "P3E_CPU0_PE1_PCH_RXN<11>")
	)
	(segment
		(start 311.73039 -100.41128)
		(end 308.996588 -98.81362)
		(width 0.1143)
		(layer "In2.Cu")
		(net "P3E_CPU0_PE1_PCH_RXN<11>")
	)
	(segment
		(start 358.821736 -122.060208)
		(end 356.555548 -122.060208)
		(width 0.1143)
		(layer "In2.Cu")
		(net "P3E_CPU0_PE1_PCH_RXN<11>")
	)
	(segment
		(start 299.248322 -98.100134)
		(end 299.215556 -98.100134)
		(width 0.0889)
		(layer "In2.Cu")
		(net "P3E_CPU0_PE1_PCH_RXN<11>")
	)
	(segment
		(start 307.221636 -98.81362)
		(end 307.170836 -98.76282)
		(width 0.0889)
		(layer "In2.Cu")
		(net "P3E_CPU0_PE1_PCH_RXN<11>")
	)
	(segment
		(start 307.170836 -98.76282)
		(end 306.48656 -98.76282)
		(width 0.0889)
		(layer "In2.Cu")
		(net "P3E_CPU0_PE1_PCH_RXN<11>")
	)
	(segment
		(start 304.779172 -99.600512)
		(end 304.561494 -99.382834)
		(width 0.0889)
		(layer "In2.Cu")
		(net "P3E_CPU0_PE1_PCH_RXN<11>")
	)
	(segment
		(start 300.965362 -99.090734)
		(end 300.932596 -99.090734)
		(width 0.0889)
		(layer "In2.Cu")
		(net "P3E_CPU0_PE1_PCH_RXN<11>")
	)
	(segment
		(start 300.110652 -98.595688)
		(end 300.077886 -98.595688)
		(width 0.0889)
		(layer "In2.Cu")
		(net "P3E_CPU0_PE1_PCH_RXN<11>")
	)
	(segment
		(start 313.289188 -102.558596)
		(end 311.730136 -100.41128)
		(width 0.1143)
		(layer "In2.Cu")
		(net "P3E_CPU0_PE1_PCH_RXN<11>")
	)
	(segment
		(start 358.951022 -122.189494)
		(end 358.821736 -122.060208)
		(width 0.1143)
		(layer "In2.Cu")
		(net "P3E_CPU0_PE1_PCH_RXN<11>")
	)
	(segment
		(start 328.7014 -119.1006)
		(end 328.225912 -117.097048)
		(width 0.1143)
		(layer "In2.Cu")
		(net "P3E_CPU0_PE1_PCH_RXN<11>")
	)
	(segment
		(start 356.555548 -122.060208)
		(end 343.471754 -119.336312)
		(width 0.1143)
		(layer "In2.Cu")
		(net "P3E_CPU0_PE1_PCH_RXN<11>")
	)
	(segment
		(start 302.366172 -99.382834)
		(end 302.162718 -99.586288)
		(width 0.0889)
		(layer "In2.Cu")
		(net "P3E_CPU0_PE1_PCH_RXN<11>")
	)
	(segment
		(start 341.64016 -119.702326)
		(end 339.1662 -121.359168)
		(width 0.1143)
		(layer "In2.Cu")
		(net "P3E_CPU0_PE1_PCH_RXN<11>")
	)
	(segment
		(start 358.951022 -122.563128)
		(end 358.951022 -122.189494)
		(width 0.1143)
		(layer "In2.Cu")
		(net "P3E_CPU0_PE1_PCH_RXN<11>")
	)
	(segment
		(start 308.996588 -98.81362)
		(end 307.221636 -98.81362)
		(width 0.1143)
		(layer "In2.Cu")
		(net "P3E_CPU0_PE1_PCH_RXN<11>")
	)
	(segment
		(start 328.752708 -115.303554)
		(end 327.565004 -111.161576)
		(width 0.1143)
		(layer "In2.Cu")
		(net "P3E_CPU0_PE1_PCH_RXN<11>")
	)
	(segment
		(start 305.648868 -99.600512)
		(end 304.779172 -99.600512)
		(width 0.0889)
		(layer "In2.Cu")
		(net "P3E_CPU0_PE1_PCH_RXN<11>")
	)
	(segment
		(start 304.561494 -99.382834)
		(end 302.366172 -99.382834)
		(width 0.0889)
		(layer "In2.Cu")
		(net "P3E_CPU0_PE1_PCH_RXN<11>")
	)
	(segment
		(start 302.162718 -99.586288)
		(end 301.794926 -99.586288)
		(width 0.0889)
		(layer "In2.Cu")
		(net "P3E_CPU0_PE1_PCH_RXN<11>")
	)
	(segment
		(start 297.520106 -98.16211)
		(end 297.520106 -98.500184)
		(width 0.0889)
		(layer "In2.Cu")
		(net "P3E_CPU0_PE1_PCH_RXN<11>")
	)
	(segment
		(start 327.565004 -111.161576)
		(end 327.103232 -110.57509)
		(width 0.1143)
		(layer "In2.Cu")
		(net "P3E_CPU0_PE1_PCH_RXN<11>")
	)
	(segment
		(start 335.290922 -122.180858)
		(end 330.368656 -120.396254)
		(width 0.1143)
		(layer "In2.Cu")
		(net "P3E_CPU0_PE1_PCH_RXN<11>")
	)
	(segment
		(start 323.252846 -108.810044)
		(end 313.289188 -102.558596)
		(width 0.1143)
		(layer "In2.Cu")
		(net "P3E_CPU0_PE1_PCH_RXN<11>")
	)
	(segment
		(start 298.393612 -97.605088)
		(end 298.36364 -97.605088)
		(width 0.0889)
		(layer "In2.Cu")
		(net "P3E_CPU0_PE1_PCH_RXN<11>")
	)
	(segment
		(start 330.368656 -120.396254)
		(end 328.7014 -119.1006)
		(width 0.1143)
		(layer "In2.Cu")
		(net "P3E_CPU0_PE1_PCH_RXN<11>")
	)
	(segment
		(start 311.730136 -100.41128)
		(end 311.73039 -100.41128)
		(width 0.1143)
		(layer "In2.Cu")
		(net "P3E_CPU0_PE1_PCH_RXN<11>")
	)
	(segment
		(start 328.225912 -117.097048)
		(end 328.752454 -115.303554)
		(width 0.1143)
		(layer "In2.Cu")
		(net "P3E_CPU0_PE1_PCH_RXN<11>")
	)
	(segment
		(start 328.752454 -115.303554)
		(end 328.752708 -115.303554)
		(width 0.1143)
		(layer "In2.Cu")
		(net "P3E_CPU0_PE1_PCH_RXN<11>")
	)
	(segment
		(start 343.471754 -119.336312)
		(end 341.64016 -119.702326)
		(width 0.1143)
		(layer "In2.Cu")
		(net "P3E_CPU0_PE1_PCH_RXN<11>")
	)
	(segment
		(start 306.48656 -98.76282)
		(end 305.648868 -99.600512)
		(width 0.0889)
		(layer "In2.Cu")
		(net "P3E_CPU0_PE1_PCH_RXN<11>")
	)
	(segment
		(start 339.1662 -121.359168)
		(end 335.290922 -122.180858)
		(width 0.1143)
		(layer "In2.Cu")
		(net "P3E_CPU0_PE1_PCH_RXN<11>")
	)
	(segment
		(start 297.58513 -98.097086)
		(end 297.520106 -98.16211)
		(width 0.0889)
		(layer "In2.Cu")
		(net "P3E_CPU0_PE1_PCH_RXN<11>")
	)
	(segment
		(start 327.103232 -110.57509)
		(end 323.252846 -108.810044)
		(width 0.1143)
		(layer "In2.Cu")
		(net "P3E_CPU0_PE1_PCH_RXN<11>")
	)
	(arc
		(start 298.031916 -97.804986)
		(mid 297.843388 -98.004359)
		(end 297.58513 -98.097086)
		(width 0.0889)
		(layer "In2.Cu")
		(net "P3E_CPU0_PE1_PCH_RXN<11>")
	)
	(arc
		(start 299.215556 -98.100134)
		(mid 298.932339 -98.015853)
		(end 298.725336 -97.804986)
		(width 0.0889)
		(layer "In2.Cu")
		(net "P3E_CPU0_PE1_PCH_RXN<11>")
	)
	(arc
		(start 300.442376 -98.795586)
		(mid 300.302297 -98.65285)
		(end 300.110652 -98.595688)
		(width 0.0889)
		(layer "In2.Cu")
		(net "P3E_CPU0_PE1_PCH_RXN<11>")
	)
	(arc
		(start 300.932596 -99.090734)
		(mid 300.649379 -99.006453)
		(end 300.442376 -98.795586)
		(width 0.0889)
		(layer "In2.Cu")
		(net "P3E_CPU0_PE1_PCH_RXN<11>")
	)
	(arc
		(start 301.300896 -99.290886)
		(mid 301.159213 -99.147082)
		(end 300.965362 -99.090734)
		(width 0.0889)
		(layer "In2.Cu")
		(net "P3E_CPU0_PE1_PCH_RXN<11>")
	)
	(arc
		(start 299.583856 -98.300286)
		(mid 299.442173 -98.156482)
		(end 299.248322 -98.100134)
		(width 0.0889)
		(layer "In2.Cu")
		(net "P3E_CPU0_PE1_PCH_RXN<11>")
	)
	(arc
		(start 298.36364 -97.605088)
		(mid 298.171998 -97.662254)
		(end 298.031916 -97.804986)
		(width 0.0889)
		(layer "In2.Cu")
		(net "P3E_CPU0_PE1_PCH_RXN<11>")
	)
	(arc
		(start 298.725336 -97.804986)
		(mid 298.585257 -97.66225)
		(end 298.393612 -97.605088)
		(width 0.0889)
		(layer "In2.Cu")
		(net "P3E_CPU0_PE1_PCH_RXN<11>")
	)
	(arc
		(start 301.794926 -99.586288)
		(mid 301.509502 -99.502821)
		(end 301.300896 -99.290886)
		(width 0.0889)
		(layer "In2.Cu")
		(net "P3E_CPU0_PE1_PCH_RXN<11>")
	)
	(arc
		(start 300.077886 -98.595688)
		(mid 299.792462 -98.512221)
		(end 299.583856 -98.300286)
		(width 0.0889)
		(layer "In2.Cu")
		(net "P3E_CPU0_PE1_PCH_RXN<11>")
	)
	(segment
		(start 298.665646 -98.500184)
		(end 299.237146 -98.500184)
		(width 0.1143)
		(layer "F.Cu")
		(net "P3E_CPU0_PE1_PCH_RXN<10>")
	)
	(via
		(at 299.237146 -98.500184)
		(size 0.508)
		(drill 0.254)
		(layers "F.Cu" "B.Cu")
		(net "P3E_CPU0_PE1_PCH_RXN<10>")
	)
	(via
		(at 358.887014 -124.338842)
		(size 0.508)
		(drill 0.254)
		(layers "F.Cu" "B.Cu")
		(net "P3E_CPU0_PE1_PCH_RXN<10>")
	)
	(segment
		(start 361.556808 -124.864876)
		(end 359.413048 -124.864876)
		(width 0.1143)
		(layer "B.Cu")
		(net "P3E_CPU0_PE1_PCH_RXN<10>")
	)
	(segment
		(start 361.782614 -124.440442)
		(end 361.782614 -124.63907)
		(width 0.1143)
		(layer "B.Cu")
		(net "P3E_CPU0_PE1_PCH_RXN<10>")
	)
	(segment
		(start 359.413048 -124.864876)
		(end 358.887014 -124.338842)
		(width 0.1143)
		(layer "B.Cu")
		(net "P3E_CPU0_PE1_PCH_RXN<10>")
	)
	(segment
		(start 361.782614 -124.63907)
		(end 361.556808 -124.864876)
		(width 0.1143)
		(layer "B.Cu")
		(net "P3E_CPU0_PE1_PCH_RXN<10>")
	)
	(segment
		(start 308.74335 -99.2886)
		(end 308.299358 -99.2886)
		(width 0.1143)
		(layer "In2.Cu")
		(net "P3E_CPU0_PE1_PCH_RXN<10>")
	)
	(segment
		(start 352.772726 -121.75236)
		(end 346.799662 -120.484138)
		(width 0.1143)
		(layer "In2.Cu")
		(net "P3E_CPU0_PE1_PCH_RXN<10>")
	)
	(segment
		(start 304.098452 -99.748848)
		(end 304.009552 -99.837748)
		(width 0.0889)
		(layer "In2.Cu")
		(net "P3E_CPU0_PE1_PCH_RXN<10>")
	)
	(segment
		(start 328.814938 -120.424448)
		(end 326.476614 -117.098318)
		(width 0.1143)
		(layer "In2.Cu")
		(net "P3E_CPU0_PE1_PCH_RXN<10>")
	)
	(segment
		(start 305.258724 -100.07092)
		(end 304.979324 -100.07092)
		(width 0.0889)
		(layer "In2.Cu")
		(net "P3E_CPU0_PE1_PCH_RXN<10>")
	)
	(segment
		(start 306.262786 -99.860354)
		(end 306.05222 -100.07092)
		(width 0.0889)
		(layer "In2.Cu")
		(net "P3E_CPU0_PE1_PCH_RXN<10>")
	)
	(segment
		(start 355.809804 -123.999244)
		(end 352.772726 -121.75236)
		(width 0.1143)
		(layer "In2.Cu")
		(net "P3E_CPU0_PE1_PCH_RXN<10>")
	)
	(segment
		(start 306.05222 -100.07092)
		(end 305.715924 -100.07092)
		(width 0.0889)
		(layer "In2.Cu")
		(net "P3E_CPU0_PE1_PCH_RXN<10>")
	)
	(segment
		(start 306.460398 -99.537012)
		(end 306.262786 -99.734624)
		(width 0.0889)
		(layer "In2.Cu")
		(net "P3E_CPU0_PE1_PCH_RXN<10>")
	)
	(segment
		(start 307.06314 -99.3394)
		(end 306.78374 -99.3394)
		(width 0.0889)
		(layer "In2.Cu")
		(net "P3E_CPU0_PE1_PCH_RXN<10>")
	)
	(segment
		(start 307.52034 -99.3394)
		(end 307.43144 -99.2505)
		(width 0.0889)
		(layer "In2.Cu")
		(net "P3E_CPU0_PE1_PCH_RXN<10>")
	)
	(segment
		(start 306.78374 -99.3394)
		(end 306.586128 -99.537012)
		(width 0.0889)
		(layer "In2.Cu")
		(net "P3E_CPU0_PE1_PCH_RXN<10>")
	)
	(segment
		(start 341.224108 -121.609866)
		(end 340.876382 -121.535952)
		(width 0.1143)
		(layer "In2.Cu")
		(net "P3E_CPU0_PE1_PCH_RXN<10>")
	)
	(segment
		(start 307.15204 -99.2505)
		(end 307.06314 -99.3394)
		(width 0.0889)
		(layer "In2.Cu")
		(net "P3E_CPU0_PE1_PCH_RXN<10>")
	)
	(segment
		(start 304.746152 -99.837748)
		(end 304.466752 -99.837748)
		(width 0.0889)
		(layer "In2.Cu")
		(net "P3E_CPU0_PE1_PCH_RXN<10>")
	)
	(segment
		(start 340.680548 -121.663206)
		(end 340.079076 -121.535444)
		(width 0.1143)
		(layer "In2.Cu")
		(net "P3E_CPU0_PE1_PCH_RXN<10>")
	)
	(segment
		(start 308.22646 -99.3394)
		(end 307.52034 -99.3394)
		(width 0.0889)
		(layer "In2.Cu")
		(net "P3E_CPU0_PE1_PCH_RXN<10>")
	)
	(segment
		(start 299.0215 -98.375978)
		(end 299.237146 -98.500184)
		(width 0.0889)
		(layer "In2.Cu")
		(net "P3E_CPU0_PE1_PCH_RXN<10>")
	)
	(segment
		(start 306.586128 -99.537012)
		(end 306.460398 -99.537012)
		(width 0.0889)
		(layer "In2.Cu")
		(net "P3E_CPU0_PE1_PCH_RXN<10>")
	)
	(segment
		(start 346.799662 -120.484138)
		(end 345.000326 -120.84431)
		(width 0.1143)
		(layer "In2.Cu")
		(net "P3E_CPU0_PE1_PCH_RXN<10>")
	)
	(segment
		(start 334.770476 -122.663204)
		(end 329.937872 -121.296938)
		(width 0.1143)
		(layer "In2.Cu")
		(net "P3E_CPU0_PE1_PCH_RXN<10>")
	)
	(segment
		(start 326.476614 -117.098318)
		(end 324.710044 -110.338362)
		(width 0.1143)
		(layer "In2.Cu")
		(net "P3E_CPU0_PE1_PCH_RXN<10>")
	)
	(segment
		(start 302.641 -99.837748)
		(end 302.089312 -100.389436)
		(width 0.0889)
		(layer "In2.Cu")
		(net "P3E_CPU0_PE1_PCH_RXN<10>")
	)
	(segment
		(start 305.347624 -99.98202)
		(end 305.258724 -100.07092)
		(width 0.0889)
		(layer "In2.Cu")
		(net "P3E_CPU0_PE1_PCH_RXN<10>")
	)
	(segment
		(start 302.089312 -100.389436)
		(end 301.817786 -100.389436)
		(width 0.0889)
		(layer "In2.Cu")
		(net "P3E_CPU0_PE1_PCH_RXN<10>")
	)
	(segment
		(start 308.27726 -99.2886)
		(end 308.22646 -99.3394)
		(width 0.0889)
		(layer "In2.Cu")
		(net "P3E_CPU0_PE1_PCH_RXN<10>")
	)
	(segment
		(start 303.361852 -99.748848)
		(end 303.272952 -99.837748)
		(width 0.0889)
		(layer "In2.Cu")
		(net "P3E_CPU0_PE1_PCH_RXN<10>")
	)
	(segment
		(start 311.402476 -100.842826)
		(end 308.74335 -99.2886)
		(width 0.1143)
		(layer "In2.Cu")
		(net "P3E_CPU0_PE1_PCH_RXN<10>")
	)
	(segment
		(start 304.377852 -99.748848)
		(end 304.098452 -99.748848)
		(width 0.0889)
		(layer "In2.Cu")
		(net "P3E_CPU0_PE1_PCH_RXN<10>")
	)
	(segment
		(start 358.887014 -124.338842)
		(end 358.887014 -124.650754)
		(width 0.1143)
		(layer "In2.Cu")
		(net "P3E_CPU0_PE1_PCH_RXN<10>")
	)
	(segment
		(start 312.833766 -102.814628)
		(end 311.402476 -100.842826)
		(width 0.1143)
		(layer "In2.Cu")
		(net "P3E_CPU0_PE1_PCH_RXN<10>")
	)
	(segment
		(start 358.123236 -124.7775)
		(end 355.809804 -123.999244)
		(width 0.1143)
		(layer "In2.Cu")
		(net "P3E_CPU0_PE1_PCH_RXN<10>")
	)
	(segment
		(start 298.9834 -98.35388)
		(end 299.0215 -98.375978)
		(width 0.0889)
		(layer "In2.Cu")
		(net "P3E_CPU0_PE1_PCH_RXN<10>")
	)
	(segment
		(start 305.715924 -100.07092)
		(end 305.627024 -99.98202)
		(width 0.0889)
		(layer "In2.Cu")
		(net "P3E_CPU0_PE1_PCH_RXN<10>")
	)
	(segment
		(start 329.937872 -121.296938)
		(end 328.814938 -120.424448)
		(width 0.1143)
		(layer "In2.Cu")
		(net "P3E_CPU0_PE1_PCH_RXN<10>")
	)
	(segment
		(start 304.009552 -99.837748)
		(end 303.730152 -99.837748)
		(width 0.0889)
		(layer "In2.Cu")
		(net "P3E_CPU0_PE1_PCH_RXN<10>")
	)
	(segment
		(start 300.117256 -99.395788)
		(end 300.08449 -99.395788)
		(width 0.0889)
		(layer "In2.Cu")
		(net "P3E_CPU0_PE1_PCH_RXN<10>")
	)
	(segment
		(start 342.410796 -122.030998)
		(end 341.351362 -121.8057)
		(width 0.1143)
		(layer "In2.Cu")
		(net "P3E_CPU0_PE1_PCH_RXN<10>")
	)
	(segment
		(start 300.971966 -99.890834)
		(end 300.9392 -99.890834)
		(width 0.0889)
		(layer "In2.Cu")
		(net "P3E_CPU0_PE1_PCH_RXN<10>")
	)
	(segment
		(start 340.876382 -121.535952)
		(end 340.680548 -121.663206)
		(width 0.1143)
		(layer "In2.Cu")
		(net "P3E_CPU0_PE1_PCH_RXN<10>")
	)
	(segment
		(start 358.760268 -124.7775)
		(end 358.123236 -124.7775)
		(width 0.1143)
		(layer "In2.Cu")
		(net "P3E_CPU0_PE1_PCH_RXN<10>")
	)
	(segment
		(start 340.079076 -121.535444)
		(end 334.770476 -122.663204)
		(width 0.1143)
		(layer "In2.Cu")
		(net "P3E_CPU0_PE1_PCH_RXN<10>")
	)
	(segment
		(start 307.43144 -99.2505)
		(end 307.15204 -99.2505)
		(width 0.0889)
		(layer "In2.Cu")
		(net "P3E_CPU0_PE1_PCH_RXN<10>")
	)
	(segment
		(start 308.299358 -99.2886)
		(end 308.27726 -99.2886)
		(width 0.0889)
		(layer "In2.Cu")
		(net "P3E_CPU0_PE1_PCH_RXN<10>")
	)
	(segment
		(start 303.730152 -99.837748)
		(end 303.641252 -99.748848)
		(width 0.0889)
		(layer "In2.Cu")
		(net "P3E_CPU0_PE1_PCH_RXN<10>")
	)
	(segment
		(start 298.94403 -98.331274)
		(end 298.9834 -98.35388)
		(width 0.0889)
		(layer "In2.Cu")
		(net "P3E_CPU0_PE1_PCH_RXN<10>")
	)
	(segment
		(start 303.641252 -99.748848)
		(end 303.361852 -99.748848)
		(width 0.0889)
		(layer "In2.Cu")
		(net "P3E_CPU0_PE1_PCH_RXN<10>")
	)
	(segment
		(start 324.710044 -110.338362)
		(end 312.833766 -102.814628)
		(width 0.1143)
		(layer "In2.Cu")
		(net "P3E_CPU0_PE1_PCH_RXN<10>")
	)
	(segment
		(start 305.627024 -99.98202)
		(end 305.347624 -99.98202)
		(width 0.0889)
		(layer "In2.Cu")
		(net "P3E_CPU0_PE1_PCH_RXN<10>")
	)
	(segment
		(start 303.272952 -99.837748)
		(end 302.641 -99.837748)
		(width 0.0889)
		(layer "In2.Cu")
		(net "P3E_CPU0_PE1_PCH_RXN<10>")
	)
	(segment
		(start 345.000326 -120.84431)
		(end 343.567258 -121.799604)
		(width 0.1143)
		(layer "In2.Cu")
		(net "P3E_CPU0_PE1_PCH_RXN<10>")
	)
	(segment
		(start 298.86529 -98.35261)
		(end 298.94403 -98.331274)
		(width 0.0889)
		(layer "In2.Cu")
		(net "P3E_CPU0_PE1_PCH_RXN<10>")
	)
	(segment
		(start 358.887014 -124.650754)
		(end 358.760268 -124.7775)
		(width 0.1143)
		(layer "In2.Cu")
		(net "P3E_CPU0_PE1_PCH_RXN<10>")
	)
	(segment
		(start 304.979324 -100.07092)
		(end 304.746152 -99.837748)
		(width 0.0889)
		(layer "In2.Cu")
		(net "P3E_CPU0_PE1_PCH_RXN<10>")
	)
	(segment
		(start 299.254926 -98.900234)
		(end 299.22216 -98.900234)
		(width 0.0889)
		(layer "In2.Cu")
		(net "P3E_CPU0_PE1_PCH_RXN<10>")
	)
	(segment
		(start 343.567258 -121.799604)
		(end 342.410796 -122.030998)
		(width 0.1143)
		(layer "In2.Cu")
		(net "P3E_CPU0_PE1_PCH_RXN<10>")
	)
	(segment
		(start 341.351362 -121.8057)
		(end 341.224108 -121.609866)
		(width 0.1143)
		(layer "In2.Cu")
		(net "P3E_CPU0_PE1_PCH_RXN<10>")
	)
	(segment
		(start 304.466752 -99.837748)
		(end 304.377852 -99.748848)
		(width 0.0889)
		(layer "In2.Cu")
		(net "P3E_CPU0_PE1_PCH_RXN<10>")
	)
	(segment
		(start 306.262786 -99.734624)
		(end 306.262786 -99.860354)
		(width 0.0889)
		(layer "In2.Cu")
		(net "P3E_CPU0_PE1_PCH_RXN<10>")
	)
	(arc
		(start 299.748956 -99.195636)
		(mid 299.540348 -98.983704)
		(end 299.254926 -98.900234)
		(width 0.0889)
		(layer "In2.Cu")
		(net "P3E_CPU0_PE1_PCH_RXN<10>")
	)
	(arc
		(start 300.08449 -99.395788)
		(mid 299.89064 -99.339438)
		(end 299.748956 -99.195636)
		(width 0.0889)
		(layer "In2.Cu")
		(net "P3E_CPU0_PE1_PCH_RXN<10>")
	)
	(arc
		(start 301.465996 -100.186236)
		(mid 301.257388 -99.974304)
		(end 300.971966 -99.890834)
		(width 0.0889)
		(layer "In2.Cu")
		(net "P3E_CPU0_PE1_PCH_RXN<10>")
	)
	(arc
		(start 300.9392 -99.890834)
		(mid 300.747558 -99.833668)
		(end 300.607476 -99.690936)
		(width 0.0889)
		(layer "In2.Cu")
		(net "P3E_CPU0_PE1_PCH_RXN<10>")
	)
	(arc
		(start 301.817786 -100.389436)
		(mid 301.614653 -100.334988)
		(end 301.465996 -100.186236)
		(width 0.0889)
		(layer "In2.Cu")
		(net "P3E_CPU0_PE1_PCH_RXN<10>")
	)
	(arc
		(start 299.22216 -98.900234)
		(mid 298.902 -98.718769)
		(end 298.86529 -98.35261)
		(width 0.0889)
		(layer "In2.Cu")
		(net "P3E_CPU0_PE1_PCH_RXN<10>")
	)
	(arc
		(start 300.607476 -99.690936)
		(mid 300.400472 -99.480072)
		(end 300.117256 -99.395788)
		(width 0.0889)
		(layer "In2.Cu")
		(net "P3E_CPU0_PE1_PCH_RXN<10>")
	)
	(segment
		(start 378.32665 -116.72316)
		(end 378.82195 -116.953284)
		(width 0.1143)
		(layer "F.Cu")
		(net "P3E_CPU0_PE1_PCH_RXN<0>")
	)
	(via
		(at 378.82195 -116.953284)
		(size 0.508)
		(drill 0.254)
		(layers "F.Cu" "B.Cu")
		(net "P3E_CPU0_PE1_PCH_RXN<0>")
	)
	(via
		(at 335.088738 -67.74688)
		(size 0.508)
		(drill 0.254)
		(layers "F.Cu" "B.Cu")
		(net "P3E_CPU0_PE1_PCH_RXN<0>")
	)
	(via
		(at 335.85404 -71.81342)
		(size 0.508)
		(drill 0.254)
		(layers "F.Cu" "B.Cu")
		(net "P3E_CPU0_PE1_PCH_RXN<0>")
	)
	(segment
		(start 335.088738 -67.74688)
		(end 335.088738 -63.437516)
		(width 0.1143)
		(layer "B.Cu")
		(net "P3E_CPU0_PE1_PCH_RXN<0>")
	)
	(segment
		(start 335.52892 -71.4883)
		(end 335.52892 -70.817486)
		(width 0.1143)
		(layer "B.Cu")
		(net "P3E_CPU0_PE1_PCH_RXN<0>")
	)
	(segment
		(start 334.28686 -61.71438)
		(end 334.743806 -61.257434)
		(width 0.1143)
		(layer "B.Cu")
		(net "P3E_CPU0_PE1_PCH_RXN<0>")
	)
	(segment
		(start 335.52892 -70.817486)
		(end 335.088738 -70.377304)
		(width 0.1143)
		(layer "B.Cu")
		(net "P3E_CPU0_PE1_PCH_RXN<0>")
	)
	(segment
		(start 334.28686 -62.635638)
		(end 334.28686 -61.71438)
		(width 0.1143)
		(layer "B.Cu")
		(net "P3E_CPU0_PE1_PCH_RXN<0>")
	)
	(segment
		(start 335.088738 -63.437516)
		(end 334.28686 -62.635638)
		(width 0.1143)
		(layer "B.Cu")
		(net "P3E_CPU0_PE1_PCH_RXN<0>")
	)
	(segment
		(start 335.85404 -71.81342)
		(end 335.52892 -71.4883)
		(width 0.1143)
		(layer "B.Cu")
		(net "P3E_CPU0_PE1_PCH_RXN<0>")
	)
	(segment
		(start 335.088738 -70.377304)
		(end 335.088738 -67.74688)
		(width 0.1143)
		(layer "B.Cu")
		(net "P3E_CPU0_PE1_PCH_RXN<0>")
	)
	(segment
		(start 337.826096 -75.50277)
		(end 337.931506 -75.82916)
		(width 0.1143)
		(layer "In2.Cu")
		(net "P3E_CPU0_PE1_PCH_RXN<0>")
	)
	(segment
		(start 367.3856 -114.4016)
		(end 367.4364 -114.4524)
		(width 0.0889)
		(layer "In2.Cu")
		(net "P3E_CPU0_PE1_PCH_RXN<0>")
	)
	(segment
		(start 337.930744 -76.363322)
		(end 338.13877 -76.469494)
		(width 0.1143)
		(layer "In2.Cu")
		(net "P3E_CPU0_PE1_PCH_RXN<0>")
	)
	(segment
		(start 352.374962 -81.985358)
		(end 353.504754 -81.765648)
		(width 0.1143)
		(layer "In2.Cu")
		(net "P3E_CPU0_PE1_PCH_RXN<0>")
	)
	(segment
		(start 348.50451 -82.639916)
		(end 349.632016 -81.87944)
		(width 0.1143)
		(layer "In2.Cu")
		(net "P3E_CPU0_PE1_PCH_RXN<0>")
	)
	(segment
		(start 348.224602 -82.706464)
		(end 348.50451 -82.639916)
		(width 0.1143)
		(layer "In2.Cu")
		(net "P3E_CPU0_PE1_PCH_RXN<0>")
	)
	(segment
		(start 358.682036 -83.272884)
		(end 359.12806 -85.567266)
		(width 0.1143)
		(layer "In2.Cu")
		(net "P3E_CPU0_PE1_PCH_RXN<0>")
	)
	(segment
		(start 359.061766 -86.77275)
		(end 358.996234 -87.1093)
		(width 0.1143)
		(layer "In2.Cu")
		(net "P3E_CPU0_PE1_PCH_RXN<0>")
	)
	(segment
		(start 335.85404 -71.81342)
		(end 335.5086 -72.15886)
		(width 0.1143)
		(layer "In2.Cu")
		(net "P3E_CPU0_PE1_PCH_RXN<0>")
	)
	(segment
		(start 363.083602 -92.641674)
		(end 363.87913 -95.102934)
		(width 0.1143)
		(layer "In2.Cu")
		(net "P3E_CPU0_PE1_PCH_RXN<0>")
	)
	(segment
		(start 335.5086 -72.713342)
		(end 335.624678 -72.82942)
		(width 0.1143)
		(layer "In2.Cu")
		(net "P3E_CPU0_PE1_PCH_RXN<0>")
	)
	(segment
		(start 363.589062 -96.469962)
		(end 363.830362 -97.60966)
		(width 0.1143)
		(layer "In2.Cu")
		(net "P3E_CPU0_PE1_PCH_RXN<0>")
	)
	(segment
		(start 367.4364 -114.4524)
		(end 367.82756 -114.4524)
		(width 0.0889)
		(layer "In2.Cu")
		(net "P3E_CPU0_PE1_PCH_RXN<0>")
	)
	(segment
		(start 377.402852 -115.48999)
		(end 377.593098 -115.680236)
		(width 0.0889)
		(layer "In2.Cu")
		(net "P3E_CPU0_PE1_PCH_RXN<0>")
	)
	(segment
		(start 377.86437 -115.680236)
		(end 377.866148 -115.678458)
		(width 0.0889)
		(layer "In2.Cu")
		(net "P3E_CPU0_PE1_PCH_RXN<0>")
	)
	(segment
		(start 358.447848 -82.92592)
		(end 358.682036 -83.272884)
		(width 0.1143)
		(layer "In2.Cu")
		(net "P3E_CPU0_PE1_PCH_RXN<0>")
	)
	(segment
		(start 358.867964 -87.770208)
		(end 358.802432 -88.106758)
		(width 0.1143)
		(layer "In2.Cu")
		(net "P3E_CPU0_PE1_PCH_RXN<0>")
	)
	(segment
		(start 378.9172 -116.073174)
		(end 378.9172 -116.116354)
		(width 0.0889)
		(layer "In2.Cu")
		(net "P3E_CPU0_PE1_PCH_RXN<0>")
	)
	(segment
		(start 358.608884 -88.237314)
		(end 358.543352 -88.573864)
		(width 0.1143)
		(layer "In2.Cu")
		(net "P3E_CPU0_PE1_PCH_RXN<0>")
	)
	(segment
		(start 367.363502 -114.4016)
		(end 367.3856 -114.4016)
		(width 0.0889)
		(layer "In2.Cu")
		(net "P3E_CPU0_PE1_PCH_RXN<0>")
	)
	(segment
		(start 377.02617 -114.8207)
		(end 377.402852 -115.197382)
		(width 0.0889)
		(layer "In2.Cu")
		(net "P3E_CPU0_PE1_PCH_RXN<0>")
	)
	(segment
		(start 378.425964 -116.895372)
		(end 378.483876 -116.953284)
		(width 0.0889)
		(layer "In2.Cu")
		(net "P3E_CPU0_PE1_PCH_RXN<0>")
	)
	(segment
		(start 337.931506 -75.82916)
		(end 337.825334 -76.036932)
		(width 0.1143)
		(layer "In2.Cu")
		(net "P3E_CPU0_PE1_PCH_RXN<0>")
	)
	(segment
		(start 336.887312 -73.13676)
		(end 337.61807 -75.396598)
		(width 0.1143)
		(layer "In2.Cu")
		(net "P3E_CPU0_PE1_PCH_RXN<0>")
	)
	(segment
		(start 363.830362 -97.60966)
		(end 363.509814 -99.122992)
		(width 0.1143)
		(layer "In2.Cu")
		(net "P3E_CPU0_PE1_PCH_RXN<0>")
	)
	(segment
		(start 358.802686 -87.239856)
		(end 358.737408 -87.57666)
		(width 0.1143)
		(layer "In2.Cu")
		(net "P3E_CPU0_PE1_PCH_RXN<0>")
	)
	(segment
		(start 347.646244 -82.495898)
		(end 348.224602 -82.706464)
		(width 0.1143)
		(layer "In2.Cu")
		(net "P3E_CPU0_PE1_PCH_RXN<0>")
	)
	(segment
		(start 365.896906 -110.024926)
		(end 366.543336 -112.057942)
		(width 0.1143)
		(layer "In2.Cu")
		(net "P3E_CPU0_PE1_PCH_RXN<0>")
	)
	(segment
		(start 366.119664 -113.611914)
		(end 366.238028 -113.983516)
		(width 0.1143)
		(layer "In2.Cu")
		(net "P3E_CPU0_PE1_PCH_RXN<0>")
	)
	(segment
		(start 338.13877 -76.469494)
		(end 338.24418 -76.795884)
		(width 0.1143)
		(layer "In2.Cu")
		(net "P3E_CPU0_PE1_PCH_RXN<0>")
	)
	(segment
		(start 337.825334 -76.036932)
		(end 337.930744 -76.363322)
		(width 0.1143)
		(layer "In2.Cu")
		(net "P3E_CPU0_PE1_PCH_RXN<0>")
	)
	(segment
		(start 358.996234 -87.1093)
		(end 358.802686 -87.239856)
		(width 0.1143)
		(layer "In2.Cu")
		(net "P3E_CPU0_PE1_PCH_RXN<0>")
	)
	(segment
		(start 339.644482 -81.66354)
		(end 343.330784 -83.173062)
		(width 0.1143)
		(layer "In2.Cu")
		(net "P3E_CPU0_PE1_PCH_RXN<0>")
	)
	(segment
		(start 366.238028 -113.983516)
		(end 366.239298 -113.988088)
		(width 0.1143)
		(layer "In2.Cu")
		(net "P3E_CPU0_PE1_PCH_RXN<0>")
	)
	(segment
		(start 358.737408 -87.57666)
		(end 358.867964 -87.770208)
		(width 0.1143)
		(layer "In2.Cu")
		(net "P3E_CPU0_PE1_PCH_RXN<0>")
	)
	(segment
		(start 369.30838 -112.97158)
		(end 374.598946 -112.97158)
		(width 0.0889)
		(layer "In2.Cu")
		(net "P3E_CPU0_PE1_PCH_RXN<0>")
	)
	(segment
		(start 358.93121 -86.579202)
		(end 359.061766 -86.77275)
		(width 0.1143)
		(layer "In2.Cu")
		(net "P3E_CPU0_PE1_PCH_RXN<0>")
	)
	(segment
		(start 376.448066 -114.8207)
		(end 377.02617 -114.8207)
		(width 0.0889)
		(layer "In2.Cu")
		(net "P3E_CPU0_PE1_PCH_RXN<0>")
	)
	(segment
		(start 377.593098 -115.680236)
		(end 377.86437 -115.680236)
		(width 0.0889)
		(layer "In2.Cu")
		(net "P3E_CPU0_PE1_PCH_RXN<0>")
	)
	(segment
		(start 366.239298 -113.988088)
		(end 366.867694 -114.4016)
		(width 0.1143)
		(layer "In2.Cu")
		(net "P3E_CPU0_PE1_PCH_RXN<0>")
	)
	(segment
		(start 358.719882 -89.48166)
		(end 359.02138 -89.93378)
		(width 0.1143)
		(layer "In2.Cu")
		(net "P3E_CPU0_PE1_PCH_RXN<0>")
	)
	(segment
		(start 374.598946 -112.97158)
		(end 376.448066 -114.8207)
		(width 0.0889)
		(layer "In2.Cu")
		(net "P3E_CPU0_PE1_PCH_RXN<0>")
	)
	(segment
		(start 358.802432 -88.106758)
		(end 358.608884 -88.237314)
		(width 0.1143)
		(layer "In2.Cu")
		(net "P3E_CPU0_PE1_PCH_RXN<0>")
	)
	(segment
		(start 346.887292 -82.672936)
		(end 347.646244 -82.495898)
		(width 0.1143)
		(layer "In2.Cu")
		(net "P3E_CPU0_PE1_PCH_RXN<0>")
	)
	(segment
		(start 338.137754 -77.003656)
		(end 339.644482 -81.66354)
		(width 0.1143)
		(layer "In2.Cu")
		(net "P3E_CPU0_PE1_PCH_RXN<0>")
	)
	(segment
		(start 363.9693 -107.390946)
		(end 364.280704 -108.855256)
		(width 0.1143)
		(layer "In2.Cu")
		(net "P3E_CPU0_PE1_PCH_RXN<0>")
	)
	(segment
		(start 350.665288 -81.679288)
		(end 350.801178 -81.679288)
		(width 0.1143)
		(layer "In2.Cu")
		(net "P3E_CPU0_PE1_PCH_RXN<0>")
	)
	(segment
		(start 366.543336 -112.057942)
		(end 366.119664 -113.611914)
		(width 0.1143)
		(layer "In2.Cu")
		(net "P3E_CPU0_PE1_PCH_RXN<0>")
	)
	(segment
		(start 345.933268 -82.406998)
		(end 346.887292 -82.672936)
		(width 0.1143)
		(layer "In2.Cu")
		(net "P3E_CPU0_PE1_PCH_RXN<0>")
	)
	(segment
		(start 363.87913 -95.102934)
		(end 363.589062 -96.469962)
		(width 0.1143)
		(layer "In2.Cu")
		(net "P3E_CPU0_PE1_PCH_RXN<0>")
	)
	(segment
		(start 350.801178 -81.679288)
		(end 352.374962 -81.985358)
		(width 0.1143)
		(layer "In2.Cu")
		(net "P3E_CPU0_PE1_PCH_RXN<0>")
	)
	(segment
		(start 377.402852 -115.197382)
		(end 377.402852 -115.48999)
		(width 0.0889)
		(layer "In2.Cu")
		(net "P3E_CPU0_PE1_PCH_RXN<0>")
	)
	(segment
		(start 343.330784 -83.173062)
		(end 345.933268 -82.406998)
		(width 0.1143)
		(layer "In2.Cu")
		(net "P3E_CPU0_PE1_PCH_RXN<0>")
	)
	(segment
		(start 359.12806 -85.567266)
		(end 358.93121 -86.579202)
		(width 0.1143)
		(layer "In2.Cu")
		(net "P3E_CPU0_PE1_PCH_RXN<0>")
	)
	(segment
		(start 363.509814 -99.122992)
		(end 363.9693 -101.32314)
		(width 0.1143)
		(layer "In2.Cu")
		(net "P3E_CPU0_PE1_PCH_RXN<0>")
	)
	(segment
		(start 363.9693 -101.32314)
		(end 363.9693 -107.390946)
		(width 0.1143)
		(layer "In2.Cu")
		(net "P3E_CPU0_PE1_PCH_RXN<0>")
	)
	(segment
		(start 358.543352 -88.573864)
		(end 358.719882 -89.48166)
		(width 0.1143)
		(layer "In2.Cu")
		(net "P3E_CPU0_PE1_PCH_RXN<0>")
	)
	(segment
		(start 338.24418 -76.795884)
		(end 338.137754 -77.003656)
		(width 0.1143)
		(layer "In2.Cu")
		(net "P3E_CPU0_PE1_PCH_RXN<0>")
	)
	(segment
		(start 359.021888 -89.934288)
		(end 363.083602 -92.641674)
		(width 0.1143)
		(layer "In2.Cu")
		(net "P3E_CPU0_PE1_PCH_RXN<0>")
	)
	(segment
		(start 358.032304 -82.645758)
		(end 358.447848 -82.92592)
		(width 0.1143)
		(layer "In2.Cu")
		(net "P3E_CPU0_PE1_PCH_RXN<0>")
	)
	(segment
		(start 366.867694 -114.4016)
		(end 367.363502 -114.4016)
		(width 0.1143)
		(layer "In2.Cu")
		(net "P3E_CPU0_PE1_PCH_RXN<0>")
	)
	(segment
		(start 335.5086 -72.15886)
		(end 335.5086 -72.713342)
		(width 0.1143)
		(layer "In2.Cu")
		(net "P3E_CPU0_PE1_PCH_RXN<0>")
	)
	(segment
		(start 364.280704 -108.855256)
		(end 365.896906 -110.024926)
		(width 0.1143)
		(layer "In2.Cu")
		(net "P3E_CPU0_PE1_PCH_RXN<0>")
	)
	(segment
		(start 335.624678 -72.82942)
		(end 336.21726 -72.82942)
		(width 0.1143)
		(layer "In2.Cu")
		(net "P3E_CPU0_PE1_PCH_RXN<0>")
	)
	(segment
		(start 367.82756 -114.4524)
		(end 369.30838 -112.97158)
		(width 0.0889)
		(layer "In2.Cu")
		(net "P3E_CPU0_PE1_PCH_RXN<0>")
	)
	(segment
		(start 349.632016 -81.87944)
		(end 350.665288 -81.679288)
		(width 0.1143)
		(layer "In2.Cu")
		(net "P3E_CPU0_PE1_PCH_RXN<0>")
	)
	(segment
		(start 353.504754 -81.765648)
		(end 358.032304 -82.645758)
		(width 0.1143)
		(layer "In2.Cu")
		(net "P3E_CPU0_PE1_PCH_RXN<0>")
	)
	(segment
		(start 359.02138 -89.93378)
		(end 359.021888 -89.934288)
		(width 0.1143)
		(layer "In2.Cu")
		(net "P3E_CPU0_PE1_PCH_RXN<0>")
	)
	(segment
		(start 378.483876 -116.953284)
		(end 378.82195 -116.953284)
		(width 0.0889)
		(layer "In2.Cu")
		(net "P3E_CPU0_PE1_PCH_RXN<0>")
	)
	(segment
		(start 336.21726 -72.82942)
		(end 336.887312 -73.13676)
		(width 0.1143)
		(layer "In2.Cu")
		(net "P3E_CPU0_PE1_PCH_RXN<0>")
	)
	(segment
		(start 337.61807 -75.396598)
		(end 337.826096 -75.50277)
		(width 0.1143)
		(layer "In2.Cu")
		(net "P3E_CPU0_PE1_PCH_RXN<0>")
	)
	(segment
		(start 377.866148 -115.678458)
		(end 378.031248 -115.582954)
		(width 0.0889)
		(layer "In2.Cu")
		(net "P3E_CPU0_PE1_PCH_RXN<0>")
	)
	(arc
		(start 378.622052 -115.582954)
		(mid 378.832916 -115.789958)
		(end 378.9172 -116.073174)
		(width 0.0889)
		(layer "In2.Cu")
		(net "P3E_CPU0_PE1_PCH_RXN<0>")
	)
	(arc
		(start 378.9172 -116.116354)
		(mid 378.832919 -116.399571)
		(end 378.622052 -116.606574)
		(width 0.0889)
		(layer "In2.Cu")
		(net "P3E_CPU0_PE1_PCH_RXN<0>")
	)
	(arc
		(start 378.622052 -116.606574)
		(mid 378.490856 -116.728465)
		(end 378.425964 -116.895372)
		(width 0.0889)
		(layer "In2.Cu")
		(net "P3E_CPU0_PE1_PCH_RXN<0>")
	)
	(arc
		(start 378.031248 -115.582954)
		(mid 378.32665 -115.503823)
		(end 378.622052 -115.582954)
		(width 0.0889)
		(layer "In2.Cu")
		(net "P3E_CPU0_PE1_PCH_RXN<0>")
	)
	(segment
		(start 460.436722 -26.51633)
		(end 459.978252 -26.9748)
		(width 0.10795)
		(layer "F.Cu")
		(net "FM_BMC_FAULT_LED_N")
	)
	(segment
		(start 398.63395 -110.71352)
		(end 399.12925 -110.943644)
		(width 0.10795)
		(layer "F.Cu")
		(net "FM_BMC_FAULT_LED_N")
	)
	(segment
		(start 399.014442 -24.091646)
		(end 399.014442 -25.26665)
		(width 0.10795)
		(layer "F.Cu")
		(net "FM_BMC_FAULT_LED_N")
	)
	(segment
		(start 457.662026 -26.62682)
		(end 458.103986 -27.06878)
		(width 0.10795)
		(layer "F.Cu")
		(net "FM_BMC_FAULT_LED_N")
	)
	(segment
		(start 402.5646 -27.69362)
		(end 403.58822 -27.69362)
		(width 0.10795)
		(layer "F.Cu")
		(net "FM_BMC_FAULT_LED_N")
	)
	(segment
		(start 400.793712 -25.922732)
		(end 401.54606 -26.67508)
		(width 0.10795)
		(layer "F.Cu")
		(net "FM_BMC_FAULT_LED_N")
	)
	(segment
		(start 459.0796 -26.9748)
		(end 458.98562 -27.06878)
		(width 0.10795)
		(layer "F.Cu")
		(net "FM_BMC_FAULT_LED_N")
	)
	(segment
		(start 456.82154 -27.432)
		(end 456.82154 -26.73477)
		(width 0.10795)
		(layer "F.Cu")
		(net "FM_BMC_FAULT_LED_N")
	)
	(segment
		(start 458.103986 -27.06878)
		(end 458.39888 -27.06878)
		(width 0.10795)
		(layer "F.Cu")
		(net "FM_BMC_FAULT_LED_N")
	)
	(segment
		(start 459.978252 -26.9748)
		(end 459.0796 -26.9748)
		(width 0.10795)
		(layer "F.Cu")
		(net "FM_BMC_FAULT_LED_N")
	)
	(segment
		(start 399.670524 -25.922732)
		(end 400.793712 -25.922732)
		(width 0.10795)
		(layer "F.Cu")
		(net "FM_BMC_FAULT_LED_N")
	)
	(segment
		(start 456.82154 -26.73477)
		(end 456.92949 -26.62682)
		(width 0.10795)
		(layer "F.Cu")
		(net "FM_BMC_FAULT_LED_N")
	)
	(segment
		(start 406.937972 -28.782518)
		(end 407.090118 -28.934664)
		(width 0.10795)
		(layer "F.Cu")
		(net "FM_BMC_FAULT_LED_N")
	)
	(segment
		(start 404.677118 -28.782518)
		(end 406.937972 -28.782518)
		(width 0.10795)
		(layer "F.Cu")
		(net "FM_BMC_FAULT_LED_N")
	)
	(segment
		(start 456.92949 -26.62682)
		(end 457.662026 -26.62682)
		(width 0.10795)
		(layer "F.Cu")
		(net "FM_BMC_FAULT_LED_N")
	)
	(segment
		(start 399.014442 -25.26665)
		(end 399.670524 -25.922732)
		(width 0.10795)
		(layer "F.Cu")
		(net "FM_BMC_FAULT_LED_N")
	)
	(segment
		(start 458.98562 -27.06878)
		(end 458.39888 -27.06878)
		(width 0.10795)
		(layer "F.Cu")
		(net "FM_BMC_FAULT_LED_N")
	)
	(segment
		(start 399.99412 -23.111968)
		(end 399.014442 -24.091646)
		(width 0.10795)
		(layer "F.Cu")
		(net "FM_BMC_FAULT_LED_N")
	)
	(segment
		(start 403.58822 -27.69362)
		(end 404.677118 -28.782518)
		(width 0.10795)
		(layer "F.Cu")
		(net "FM_BMC_FAULT_LED_N")
	)
	(segment
		(start 401.54606 -26.67508)
		(end 402.5646 -27.69362)
		(width 0.10795)
		(layer "F.Cu")
		(net "FM_BMC_FAULT_LED_N")
	)
	(via
		(at 401.54606 -26.67508)
		(size 0.762)
		(drill 0.381)
		(layers "F.Cu" "B.Cu")
		(net "FM_BMC_FAULT_LED_N")
	)
	(via
		(at 399.12925 -110.943644)
		(size 0.508)
		(drill 0.254)
		(layers "F.Cu" "B.Cu")
		(net "FM_BMC_FAULT_LED_N")
	)
	(via
		(at 460.436722 -26.51633)
		(size 0.508)
		(drill 0.254)
		(layers "F.Cu" "B.Cu")
		(net "FM_BMC_FAULT_LED_N")
	)
	(via
		(at 374.166384 -30.733746)
		(size 0.508)
		(drill 0.254)
		(layers "F.Cu" "B.Cu")
		(net "FM_BMC_FAULT_LED_N")
	)
	(via
		(at 399.99412 -23.111968)
		(size 0.508)
		(drill 0.254)
		(layers "F.Cu" "B.Cu")
		(net "FM_BMC_FAULT_LED_N")
	)
	(segment
		(start 418.145722 -20.021296)
		(end 413.976058 -20.021296)
		(width 0.089408)
		(layer "In4.Cu")
		(net "FM_BMC_FAULT_LED_N")
	)
	(segment
		(start 404.515066 -23.368)
		(end 401.478242 -23.368)
		(width 0.089408)
		(layer "In4.Cu")
		(net "FM_BMC_FAULT_LED_N")
	)
	(segment
		(start 426.67428 -21.373592)
		(end 422.337738 -21.373592)
		(width 0.089408)
		(layer "In4.Cu")
		(net "FM_BMC_FAULT_LED_N")
	)
	(segment
		(start 401.478242 -23.368)
		(end 401.22221 -23.111968)
		(width 0.089408)
		(layer "In4.Cu")
		(net "FM_BMC_FAULT_LED_N")
	)
	(segment
		(start 392.573764 -22.04212)
		(end 394.946886 -22.04212)
		(width 0.089408)
		(layer "In4.Cu")
		(net "FM_BMC_FAULT_LED_N")
	)
	(segment
		(start 389.523732 -20.929854)
		(end 391.461498 -20.929854)
		(width 0.089408)
		(layer "In4.Cu")
		(net "FM_BMC_FAULT_LED_N")
	)
	(segment
		(start 374.166384 -30.733746)
		(end 375.38914 -29.51099)
		(width 0.089408)
		(layer "In4.Cu")
		(net "FM_BMC_FAULT_LED_N")
	)
	(segment
		(start 391.461498 -20.929854)
		(end 392.573764 -22.04212)
		(width 0.089408)
		(layer "In4.Cu")
		(net "FM_BMC_FAULT_LED_N")
	)
	(segment
		(start 413.976058 -20.021296)
		(end 413.025336 -20.972018)
		(width 0.089408)
		(layer "In4.Cu")
		(net "FM_BMC_FAULT_LED_N")
	)
	(segment
		(start 446.371726 -20.027392)
		(end 445.480694 -19.13636)
		(width 0.089408)
		(layer "In4.Cu")
		(net "FM_BMC_FAULT_LED_N")
	)
	(segment
		(start 400.817842 -21.99767)
		(end 399.99412 -22.821392)
		(width 0.089408)
		(layer "In4.Cu")
		(net "FM_BMC_FAULT_LED_N")
	)
	(segment
		(start 399.99412 -22.821392)
		(end 399.99412 -23.111968)
		(width 0.089408)
		(layer "In4.Cu")
		(net "FM_BMC_FAULT_LED_N")
	)
	(segment
		(start 407.023824 -22.926802)
		(end 406.258522 -23.692104)
		(width 0.089408)
		(layer "In4.Cu")
		(net "FM_BMC_FAULT_LED_N")
	)
	(segment
		(start 449.199 -22.462744)
		(end 449.199 -20.887944)
		(width 0.089408)
		(layer "In4.Cu")
		(net "FM_BMC_FAULT_LED_N")
	)
	(segment
		(start 440.873134 -19.13636)
		(end 439.690002 -20.319492)
		(width 0.089408)
		(layer "In4.Cu")
		(net "FM_BMC_FAULT_LED_N")
	)
	(segment
		(start 406.258522 -24.016462)
		(end 406.024334 -24.25065)
		(width 0.089408)
		(layer "In4.Cu")
		(net "FM_BMC_FAULT_LED_N")
	)
	(segment
		(start 396.053056 -20.93595)
		(end 400.601434 -20.93595)
		(width 0.089408)
		(layer "In4.Cu")
		(net "FM_BMC_FAULT_LED_N")
	)
	(segment
		(start 401.22221 -23.111968)
		(end 399.99412 -23.111968)
		(width 0.089408)
		(layer "In4.Cu")
		(net "FM_BMC_FAULT_LED_N")
	)
	(segment
		(start 445.480694 -19.13636)
		(end 440.873134 -19.13636)
		(width 0.089408)
		(layer "In4.Cu")
		(net "FM_BMC_FAULT_LED_N")
	)
	(segment
		(start 385.680458 -21.47189)
		(end 388.981696 -21.47189)
		(width 0.089408)
		(layer "In4.Cu")
		(net "FM_BMC_FAULT_LED_N")
	)
	(segment
		(start 384.782568 -20.574)
		(end 385.680458 -21.47189)
		(width 0.089408)
		(layer "In4.Cu")
		(net "FM_BMC_FAULT_LED_N")
	)
	(segment
		(start 448.338448 -20.027392)
		(end 446.371726 -20.027392)
		(width 0.089408)
		(layer "In4.Cu")
		(net "FM_BMC_FAULT_LED_N")
	)
	(segment
		(start 376.912124 -27.40533)
		(end 378.675392 -27.40533)
		(width 0.089408)
		(layer "In4.Cu")
		(net "FM_BMC_FAULT_LED_N")
	)
	(segment
		(start 411.719522 -21.924518)
		(end 409.56865 -21.924518)
		(width 0.089408)
		(layer "In4.Cu")
		(net "FM_BMC_FAULT_LED_N")
	)
	(segment
		(start 406.258522 -23.692104)
		(end 406.258522 -24.016462)
		(width 0.089408)
		(layer "In4.Cu")
		(net "FM_BMC_FAULT_LED_N")
	)
	(segment
		(start 453.888856 -27.1526)
		(end 449.199 -22.462744)
		(width 0.089408)
		(layer "In4.Cu")
		(net "FM_BMC_FAULT_LED_N")
	)
	(segment
		(start 379.202188 -25.394412)
		(end 384.0226 -20.574)
		(width 0.089408)
		(layer "In4.Cu")
		(net "FM_BMC_FAULT_LED_N")
	)
	(segment
		(start 375.38914 -29.51099)
		(end 375.38914 -28.928314)
		(width 0.089408)
		(layer "In4.Cu")
		(net "FM_BMC_FAULT_LED_N")
	)
	(segment
		(start 439.690002 -20.319492)
		(end 433.470558 -20.319492)
		(width 0.089408)
		(layer "In4.Cu")
		(net "FM_BMC_FAULT_LED_N")
	)
	(segment
		(start 394.946886 -22.04212)
		(end 396.053056 -20.93595)
		(width 0.089408)
		(layer "In4.Cu")
		(net "FM_BMC_FAULT_LED_N")
	)
	(segment
		(start 413.025336 -20.972018)
		(end 412.672022 -20.972018)
		(width 0.089408)
		(layer "In4.Cu")
		(net "FM_BMC_FAULT_LED_N")
	)
	(segment
		(start 460.436722 -26.51633)
		(end 459.800452 -27.1526)
		(width 0.089408)
		(layer "In4.Cu")
		(net "FM_BMC_FAULT_LED_N")
	)
	(segment
		(start 421.797226 -20.83308)
		(end 418.957506 -20.83308)
		(width 0.089408)
		(layer "In4.Cu")
		(net "FM_BMC_FAULT_LED_N")
	)
	(segment
		(start 384.0226 -20.574)
		(end 384.782568 -20.574)
		(width 0.089408)
		(layer "In4.Cu")
		(net "FM_BMC_FAULT_LED_N")
	)
	(segment
		(start 375.38914 -28.928314)
		(end 376.912124 -27.40533)
		(width 0.089408)
		(layer "In4.Cu")
		(net "FM_BMC_FAULT_LED_N")
	)
	(segment
		(start 405.397716 -24.25065)
		(end 404.515066 -23.368)
		(width 0.089408)
		(layer "In4.Cu")
		(net "FM_BMC_FAULT_LED_N")
	)
	(segment
		(start 406.024334 -24.25065)
		(end 405.397716 -24.25065)
		(width 0.089408)
		(layer "In4.Cu")
		(net "FM_BMC_FAULT_LED_N")
	)
	(segment
		(start 388.981696 -21.47189)
		(end 389.523732 -20.929854)
		(width 0.089408)
		(layer "In4.Cu")
		(net "FM_BMC_FAULT_LED_N")
	)
	(segment
		(start 449.199 -20.887944)
		(end 448.338448 -20.027392)
		(width 0.089408)
		(layer "In4.Cu")
		(net "FM_BMC_FAULT_LED_N")
	)
	(segment
		(start 408.566366 -22.926802)
		(end 407.023824 -22.926802)
		(width 0.089408)
		(layer "In4.Cu")
		(net "FM_BMC_FAULT_LED_N")
	)
	(segment
		(start 431.312066 -22.477984)
		(end 427.778672 -22.477984)
		(width 0.089408)
		(layer "In4.Cu")
		(net "FM_BMC_FAULT_LED_N")
	)
	(segment
		(start 433.470558 -20.319492)
		(end 431.312066 -22.477984)
		(width 0.089408)
		(layer "In4.Cu")
		(net "FM_BMC_FAULT_LED_N")
	)
	(segment
		(start 409.56865 -21.924518)
		(end 408.566366 -22.926802)
		(width 0.089408)
		(layer "In4.Cu")
		(net "FM_BMC_FAULT_LED_N")
	)
	(segment
		(start 427.778672 -22.477984)
		(end 426.67428 -21.373592)
		(width 0.089408)
		(layer "In4.Cu")
		(net "FM_BMC_FAULT_LED_N")
	)
	(segment
		(start 412.672022 -20.972018)
		(end 411.719522 -21.924518)
		(width 0.089408)
		(layer "In4.Cu")
		(net "FM_BMC_FAULT_LED_N")
	)
	(segment
		(start 379.202188 -26.878534)
		(end 379.202188 -25.394412)
		(width 0.089408)
		(layer "In4.Cu")
		(net "FM_BMC_FAULT_LED_N")
	)
	(segment
		(start 400.817842 -21.152358)
		(end 400.817842 -21.99767)
		(width 0.089408)
		(layer "In4.Cu")
		(net "FM_BMC_FAULT_LED_N")
	)
	(segment
		(start 400.601434 -20.93595)
		(end 400.817842 -21.152358)
		(width 0.089408)
		(layer "In4.Cu")
		(net "FM_BMC_FAULT_LED_N")
	)
	(segment
		(start 422.337738 -21.373592)
		(end 421.797226 -20.83308)
		(width 0.089408)
		(layer "In4.Cu")
		(net "FM_BMC_FAULT_LED_N")
	)
	(segment
		(start 459.800452 -27.1526)
		(end 453.888856 -27.1526)
		(width 0.089408)
		(layer "In4.Cu")
		(net "FM_BMC_FAULT_LED_N")
	)
	(segment
		(start 418.957506 -20.83308)
		(end 418.145722 -20.021296)
		(width 0.089408)
		(layer "In4.Cu")
		(net "FM_BMC_FAULT_LED_N")
	)
	(segment
		(start 378.675392 -27.40533)
		(end 379.202188 -26.878534)
		(width 0.089408)
		(layer "In4.Cu")
		(net "FM_BMC_FAULT_LED_N")
	)
	(segment
		(start 398.23517 -108.298742)
		(end 398.23517 -107.742482)
		(width 0.089408)
		(layer "In11.Cu")
		(net "FM_BMC_FAULT_LED_N")
	)
	(segment
		(start 399.12925 -110.943644)
		(end 398.23517 -110.049564)
		(width 0.089408)
		(layer "In11.Cu")
		(net "FM_BMC_FAULT_LED_N")
	)
	(segment
		(start 374.85447 -34.153094)
		(end 374.85447 -31.421832)
		(width 0.089408)
		(layer "In11.Cu")
		(net "FM_BMC_FAULT_LED_N")
	)
	(segment
		(start 398.673066 -104.998774)
		(end 399.550128 -104.121712)
		(width 0.089408)
		(layer "In11.Cu")
		(net "FM_BMC_FAULT_LED_N")
	)
	(segment
		(start 392.296904 -62.256162)
		(end 391.414508 -61.373766)
		(width 0.089408)
		(layer "In11.Cu")
		(net "FM_BMC_FAULT_LED_N")
	)
	(segment
		(start 377.809506 -45.511466)
		(end 377.825 -45.495972)
		(width 0.089408)
		(layer "In11.Cu")
		(net "FM_BMC_FAULT_LED_N")
	)
	(segment
		(start 378.043948 -46.077632)
		(end 377.809506 -45.84319)
		(width 0.089408)
		(layer "In11.Cu")
		(net "FM_BMC_FAULT_LED_N")
	)
	(segment
		(start 398.53743 -96.439736)
		(end 398.275556 -96.177862)
		(width 0.089408)
		(layer "In11.Cu")
		(net "FM_BMC_FAULT_LED_N")
	)
	(segment
		(start 398.53743 -101.955092)
		(end 398.53743 -101.732842)
		(width 0.089408)
		(layer "In11.Cu")
		(net "FM_BMC_FAULT_LED_N")
	)
	(segment
		(start 391.414508 -61.373766)
		(end 391.414508 -56.693816)
		(width 0.089408)
		(layer "In11.Cu")
		(net "FM_BMC_FAULT_LED_N")
	)
	(segment
		(start 391.414508 -56.693816)
		(end 387.25094 -52.530248)
		(width 0.089408)
		(layer "In11.Cu")
		(net "FM_BMC_FAULT_LED_N")
	)
	(segment
		(start 398.53743 -108.601002)
		(end 398.23517 -108.298742)
		(width 0.089408)
		(layer "In11.Cu")
		(net "FM_BMC_FAULT_LED_N")
	)
	(segment
		(start 386.13715 -49.548034)
		(end 385.037076 -48.44796)
		(width 0.089408)
		(layer "In11.Cu")
		(net "FM_BMC_FAULT_LED_N")
	)
	(segment
		(start 376.853704 -36.152328)
		(end 374.85447 -34.153094)
		(width 0.089408)
		(layer "In11.Cu")
		(net "FM_BMC_FAULT_LED_N")
	)
	(segment
		(start 395.521688 -79.360268)
		(end 395.521688 -71.501)
		(width 0.089408)
		(layer "In11.Cu")
		(net "FM_BMC_FAULT_LED_N")
	)
	(segment
		(start 383.20472 -48.448214)
		(end 382.803908 -48.448214)
		(width 0.089408)
		(layer "In11.Cu")
		(net "FM_BMC_FAULT_LED_N")
	)
	(segment
		(start 395.941804 -79.780384)
		(end 395.521688 -79.360268)
		(width 0.089408)
		(layer "In11.Cu")
		(net "FM_BMC_FAULT_LED_N")
	)
	(segment
		(start 376.853704 -41.97985)
		(end 376.853704 -36.152328)
		(width 0.089408)
		(layer "In11.Cu")
		(net "FM_BMC_FAULT_LED_N")
	)
	(segment
		(start 398.23517 -99.713542)
		(end 398.23517 -99.157282)
		(width 0.089408)
		(layer "In11.Cu")
		(net "FM_BMC_FAULT_LED_N")
	)
	(segment
		(start 382.692656 -48.44796)
		(end 381.787908 -47.543212)
		(width 0.089408)
		(layer "In11.Cu")
		(net "FM_BMC_FAULT_LED_N")
	)
	(segment
		(start 398.23517 -106.025442)
		(end 398.673066 -105.587546)
		(width 0.089408)
		(layer "In11.Cu")
		(net "FM_BMC_FAULT_LED_N")
	)
	(segment
		(start 398.53743 -106.883962)
		(end 398.23517 -106.581702)
		(width 0.089408)
		(layer "In11.Cu")
		(net "FM_BMC_FAULT_LED_N")
	)
	(segment
		(start 398.23517 -106.581702)
		(end 398.23517 -106.025442)
		(width 0.089408)
		(layer "In11.Cu")
		(net "FM_BMC_FAULT_LED_N")
	)
	(segment
		(start 398.275556 -95.686626)
		(end 397.468852 -94.879922)
		(width 0.089408)
		(layer "In11.Cu")
		(net "FM_BMC_FAULT_LED_N")
	)
	(segment
		(start 386.13715 -49.703228)
		(end 386.13715 -49.548034)
		(width 0.089408)
		(layer "In11.Cu")
		(net "FM_BMC_FAULT_LED_N")
	)
	(segment
		(start 374.85447 -31.421832)
		(end 374.166384 -30.733746)
		(width 0.089408)
		(layer "In11.Cu")
		(net "FM_BMC_FAULT_LED_N")
	)
	(segment
		(start 377.29668 -44.200826)
		(end 377.29668 -42.422826)
		(width 0.089408)
		(layer "In11.Cu")
		(net "FM_BMC_FAULT_LED_N")
	)
	(segment
		(start 398.275556 -96.177862)
		(end 398.275556 -95.686626)
		(width 0.089408)
		(layer "In11.Cu")
		(net "FM_BMC_FAULT_LED_N")
	)
	(segment
		(start 377.814078 -44.718224)
		(end 377.29668 -44.200826)
		(width 0.089408)
		(layer "In11.Cu")
		(net "FM_BMC_FAULT_LED_N")
	)
	(segment
		(start 398.23517 -109.459522)
		(end 398.53743 -109.157262)
		(width 0.089408)
		(layer "In11.Cu")
		(net "FM_BMC_FAULT_LED_N")
	)
	(segment
		(start 398.23517 -107.742482)
		(end 398.53743 -107.440222)
		(width 0.089408)
		(layer "In11.Cu")
		(net "FM_BMC_FAULT_LED_N")
	)
	(segment
		(start 394.973556 -91.57208)
		(end 397.161258 -89.384378)
		(width 0.089408)
		(layer "In11.Cu")
		(net "FM_BMC_FAULT_LED_N")
	)
	(segment
		(start 395.521688 -71.501)
		(end 394.913358 -70.89267)
		(width 0.089408)
		(layer "In11.Cu")
		(net "FM_BMC_FAULT_LED_N")
	)
	(segment
		(start 398.23517 -101.430582)
		(end 398.23517 -100.874322)
		(width 0.089408)
		(layer "In11.Cu")
		(net "FM_BMC_FAULT_LED_N")
	)
	(segment
		(start 398.53743 -98.298762)
		(end 398.454626 -98.215958)
		(width 0.089408)
		(layer "In11.Cu")
		(net "FM_BMC_FAULT_LED_N")
	)
	(segment
		(start 377.825 -44.718224)
		(end 377.814078 -44.718224)
		(width 0.089408)
		(layer "In11.Cu")
		(net "FM_BMC_FAULT_LED_N")
	)
	(segment
		(start 381.787908 -47.543212)
		(end 379.691646 -47.543212)
		(width 0.089408)
		(layer "In11.Cu")
		(net "FM_BMC_FAULT_LED_N")
	)
	(segment
		(start 398.23517 -100.874322)
		(end 398.53743 -100.572062)
		(width 0.089408)
		(layer "In11.Cu")
		(net "FM_BMC_FAULT_LED_N")
	)
	(segment
		(start 378.226066 -46.077632)
		(end 378.043948 -46.077632)
		(width 0.089408)
		(layer "In11.Cu")
		(net "FM_BMC_FAULT_LED_N")
	)
	(segment
		(start 392.296904 -63.518796)
		(end 392.296904 -62.256162)
		(width 0.089408)
		(layer "In11.Cu")
		(net "FM_BMC_FAULT_LED_N")
	)
	(segment
		(start 398.23517 -99.157282)
		(end 398.53743 -98.855022)
		(width 0.089408)
		(layer "In11.Cu")
		(net "FM_BMC_FAULT_LED_N")
	)
	(segment
		(start 379.691646 -47.543212)
		(end 378.226066 -46.077632)
		(width 0.089408)
		(layer "In11.Cu")
		(net "FM_BMC_FAULT_LED_N")
	)
	(segment
		(start 398.23517 -110.049564)
		(end 398.23517 -109.459522)
		(width 0.089408)
		(layer "In11.Cu")
		(net "FM_BMC_FAULT_LED_N")
	)
	(segment
		(start 382.803654 -48.44796)
		(end 382.692656 -48.44796)
		(width 0.089408)
		(layer "In11.Cu")
		(net "FM_BMC_FAULT_LED_N")
	)
	(segment
		(start 395.660118 -87.946484)
		(end 394.518896 -86.805262)
		(width 0.089408)
		(layer "In11.Cu")
		(net "FM_BMC_FAULT_LED_N")
	)
	(segment
		(start 385.037076 -48.44796)
		(end 383.204974 -48.44796)
		(width 0.089408)
		(layer "In11.Cu")
		(net "FM_BMC_FAULT_LED_N")
	)
	(segment
		(start 377.809506 -45.84319)
		(end 377.809506 -45.511466)
		(width 0.089408)
		(layer "In11.Cu")
		(net "FM_BMC_FAULT_LED_N")
	)
	(segment
		(start 398.53743 -100.015802)
		(end 398.23517 -99.713542)
		(width 0.089408)
		(layer "In11.Cu")
		(net "FM_BMC_FAULT_LED_N")
	)
	(segment
		(start 399.550128 -102.96779)
		(end 398.53743 -101.955092)
		(width 0.089408)
		(layer "In11.Cu")
		(net "FM_BMC_FAULT_LED_N")
	)
	(segment
		(start 398.53743 -109.157262)
		(end 398.53743 -108.601002)
		(width 0.089408)
		(layer "In11.Cu")
		(net "FM_BMC_FAULT_LED_N")
	)
	(segment
		(start 377.825 -45.495972)
		(end 377.825 -44.718224)
		(width 0.089408)
		(layer "In11.Cu")
		(net "FM_BMC_FAULT_LED_N")
	)
	(segment
		(start 398.454626 -98.215958)
		(end 398.454626 -97.220786)
		(width 0.089408)
		(layer "In11.Cu")
		(net "FM_BMC_FAULT_LED_N")
	)
	(segment
		(start 398.673066 -105.587546)
		(end 398.673066 -104.998774)
		(width 0.089408)
		(layer "In11.Cu")
		(net "FM_BMC_FAULT_LED_N")
	)
	(segment
		(start 394.973556 -93.010228)
		(end 394.973556 -91.57208)
		(width 0.089408)
		(layer "In11.Cu")
		(net "FM_BMC_FAULT_LED_N")
	)
	(segment
		(start 397.468852 -94.879922)
		(end 396.84325 -94.879922)
		(width 0.089408)
		(layer "In11.Cu")
		(net "FM_BMC_FAULT_LED_N")
	)
	(segment
		(start 396.84325 -94.879922)
		(end 394.973556 -93.010228)
		(width 0.089408)
		(layer "In11.Cu")
		(net "FM_BMC_FAULT_LED_N")
	)
	(segment
		(start 398.53743 -97.137982)
		(end 398.53743 -96.439736)
		(width 0.089408)
		(layer "In11.Cu")
		(net "FM_BMC_FAULT_LED_N")
	)
	(segment
		(start 394.913358 -66.13525)
		(end 392.296904 -63.518796)
		(width 0.089408)
		(layer "In11.Cu")
		(net "FM_BMC_FAULT_LED_N")
	)
	(segment
		(start 394.518896 -86.805262)
		(end 394.518896 -83.617816)
		(width 0.089408)
		(layer "In11.Cu")
		(net "FM_BMC_FAULT_LED_N")
	)
	(segment
		(start 395.941804 -82.194908)
		(end 395.941804 -79.780384)
		(width 0.089408)
		(layer "In11.Cu")
		(net "FM_BMC_FAULT_LED_N")
	)
	(segment
		(start 398.53743 -101.732842)
		(end 398.23517 -101.430582)
		(width 0.089408)
		(layer "In11.Cu")
		(net "FM_BMC_FAULT_LED_N")
	)
	(segment
		(start 394.518896 -83.617816)
		(end 395.941804 -82.194908)
		(width 0.089408)
		(layer "In11.Cu")
		(net "FM_BMC_FAULT_LED_N")
	)
	(segment
		(start 382.803908 -48.448214)
		(end 382.803654 -48.44796)
		(width 0.089408)
		(layer "In11.Cu")
		(net "FM_BMC_FAULT_LED_N")
	)
	(segment
		(start 397.161258 -88.5063)
		(end 396.601442 -87.946484)
		(width 0.089408)
		(layer "In11.Cu")
		(net "FM_BMC_FAULT_LED_N")
	)
	(segment
		(start 387.25094 -50.817018)
		(end 386.13715 -49.703228)
		(width 0.089408)
		(layer "In11.Cu")
		(net "FM_BMC_FAULT_LED_N")
	)
	(segment
		(start 387.25094 -52.530248)
		(end 387.25094 -50.817018)
		(width 0.089408)
		(layer "In11.Cu")
		(net "FM_BMC_FAULT_LED_N")
	)
	(segment
		(start 377.29668 -42.422826)
		(end 376.853704 -41.97985)
		(width 0.089408)
		(layer "In11.Cu")
		(net "FM_BMC_FAULT_LED_N")
	)
	(segment
		(start 394.913358 -70.89267)
		(end 394.913358 -66.13525)
		(width 0.089408)
		(layer "In11.Cu")
		(net "FM_BMC_FAULT_LED_N")
	)
	(segment
		(start 398.53743 -100.572062)
		(end 398.53743 -100.015802)
		(width 0.089408)
		(layer "In11.Cu")
		(net "FM_BMC_FAULT_LED_N")
	)
	(segment
		(start 383.204974 -48.44796)
		(end 383.20472 -48.448214)
		(width 0.089408)
		(layer "In11.Cu")
		(net "FM_BMC_FAULT_LED_N")
	)
	(segment
		(start 398.53743 -107.440222)
		(end 398.53743 -106.883962)
		(width 0.089408)
		(layer "In11.Cu")
		(net "FM_BMC_FAULT_LED_N")
	)
	(segment
		(start 398.454626 -97.220786)
		(end 398.53743 -97.137982)
		(width 0.089408)
		(layer "In11.Cu")
		(net "FM_BMC_FAULT_LED_N")
	)
	(segment
		(start 399.550128 -104.121712)
		(end 399.550128 -102.96779)
		(width 0.089408)
		(layer "In11.Cu")
		(net "FM_BMC_FAULT_LED_N")
	)
	(segment
		(start 398.53743 -98.855022)
		(end 398.53743 -98.298762)
		(width 0.089408)
		(layer "In11.Cu")
		(net "FM_BMC_FAULT_LED_N")
	)
	(segment
		(start 396.601442 -87.946484)
		(end 395.660118 -87.946484)
		(width 0.089408)
		(layer "In11.Cu")
		(net "FM_BMC_FAULT_LED_N")
	)
	(segment
		(start 397.161258 -89.384378)
		(end 397.161258 -88.5063)
		(width 0.089408)
		(layer "In11.Cu")
		(net "FM_BMC_FAULT_LED_N")
	)
	(segment
		(start 417.87572 -122.540014)
		(end 417.87572 -124.742702)
		(width 0.10795)
		(layer "F.Cu")
		(net "FM_XRC_PRESENT_N")
	)
	(segment
		(start 400.465036 -114.85499)
		(end 400.579844 -114.969798)
		(width 0.0889)
		(layer "F.Cu")
		(net "FM_XRC_PRESENT_N")
	)
	(segment
		(start 400.967702 -114.969798)
		(end 401.275804 -115.2779)
		(width 0.0889)
		(layer "F.Cu")
		(net "FM_XRC_PRESENT_N")
	)
	(segment
		(start 407.994358 -116.078254)
		(end 410.5148 -116.078254)
		(width 0.10795)
		(layer "F.Cu")
		(net "FM_XRC_PRESENT_N")
	)
	(segment
		(start 411.200346 -116.7638)
		(end 413.6898 -116.7638)
		(width 0.10795)
		(layer "F.Cu")
		(net "FM_XRC_PRESENT_N")
	)
	(segment
		(start 401.275804 -115.2779)
		(end 402.636482 -115.2779)
		(width 0.0889)
		(layer "F.Cu")
		(net "FM_XRC_PRESENT_N")
	)
	(segment
		(start 400.579844 -114.969798)
		(end 400.967702 -114.969798)
		(width 0.0889)
		(layer "F.Cu")
		(net "FM_XRC_PRESENT_N")
	)
	(segment
		(start 405.70023 -115.27155)
		(end 405.950166 -115.521486)
		(width 0.10795)
		(layer "F.Cu")
		(net "FM_XRC_PRESENT_N")
	)
	(segment
		(start 417.266882 -120.340882)
		(end 417.266882 -121.931176)
		(width 0.10795)
		(layer "F.Cu")
		(net "FM_XRC_PRESENT_N")
	)
	(segment
		(start 417.650422 -124.968)
		(end 416.594544 -124.968)
		(width 0.10795)
		(layer "F.Cu")
		(net "FM_XRC_PRESENT_N")
	)
	(segment
		(start 402.636482 -115.2779)
		(end 402.674582 -115.316)
		(width 0.0889)
		(layer "F.Cu")
		(net "FM_XRC_PRESENT_N")
	)
	(segment
		(start 407.839926 -115.521486)
		(end 407.839926 -115.923822)
		(width 0.10795)
		(layer "F.Cu")
		(net "FM_XRC_PRESENT_N")
	)
	(segment
		(start 405.950166 -115.521486)
		(end 407.839926 -115.521486)
		(width 0.10795)
		(layer "F.Cu")
		(net "FM_XRC_PRESENT_N")
	)
	(segment
		(start 407.839926 -115.923822)
		(end 407.994358 -116.078254)
		(width 0.10795)
		(layer "F.Cu")
		(net "FM_XRC_PRESENT_N")
	)
	(segment
		(start 403.413214 -115.27155)
		(end 405.70023 -115.27155)
		(width 0.10795)
		(layer "F.Cu")
		(net "FM_XRC_PRESENT_N")
	)
	(segment
		(start 403.368764 -115.316)
		(end 403.413214 -115.27155)
		(width 0.10795)
		(layer "F.Cu")
		(net "FM_XRC_PRESENT_N")
	)
	(segment
		(start 416.594544 -124.968)
		(end 416.374834 -124.74829)
		(width 0.10795)
		(layer "F.Cu")
		(net "FM_XRC_PRESENT_N")
	)
	(segment
		(start 402.674582 -115.316)
		(end 403.368764 -115.316)
		(width 0.0889)
		(layer "F.Cu")
		(net "FM_XRC_PRESENT_N")
	)
	(segment
		(start 413.6898 -116.7638)
		(end 417.266882 -120.340882)
		(width 0.10795)
		(layer "F.Cu")
		(net "FM_XRC_PRESENT_N")
	)
	(segment
		(start 417.266882 -121.931176)
		(end 417.87572 -122.540014)
		(width 0.10795)
		(layer "F.Cu")
		(net "FM_XRC_PRESENT_N")
	)
	(segment
		(start 423.090086 -28.934664)
		(end 423.478452 -28.546298)
		(width 0.10795)
		(layer "F.Cu")
		(net "FM_XRC_PRESENT_N")
	)
	(segment
		(start 417.87572 -124.742702)
		(end 417.650422 -124.968)
		(width 0.10795)
		(layer "F.Cu")
		(net "FM_XRC_PRESENT_N")
	)
	(segment
		(start 410.5148 -116.078254)
		(end 411.200346 -116.7638)
		(width 0.10795)
		(layer "F.Cu")
		(net "FM_XRC_PRESENT_N")
	)
	(via
		(at 486.283 -28.7782)
		(size 0.508)
		(drill 0.254)
		(layers "F.Cu" "B.Cu")
		(net "FM_XRC_PRESENT_N")
	)
	(via
		(at 423.658284 -104.898698)
		(size 0.508)
		(drill 0.254)
		(layers "F.Cu" "B.Cu")
		(net "FM_XRC_PRESENT_N")
	)
	(via
		(at 416.374834 -124.74829)
		(size 0.508)
		(drill 0.254)
		(layers "F.Cu" "B.Cu")
		(net "FM_XRC_PRESENT_N")
	)
	(via
		(at 431.6984 -146.8374)
		(size 0.508)
		(drill 0.254)
		(layers "F.Cu" "B.Cu")
		(net "FM_XRC_PRESENT_N")
	)
	(via
		(at 366.117886 -142.523718)
		(size 0.508)
		(drill 0.254)
		(layers "F.Cu" "B.Cu")
		(net "FM_XRC_PRESENT_N")
	)
	(via
		(at 485.22636 -56.068214)
		(size 0.508)
		(drill 0.254)
		(layers "F.Cu" "B.Cu")
		(net "FM_XRC_PRESENT_N")
	)
	(via
		(at 423.478452 -28.546298)
		(size 0.4572)
		(drill 0.2032)
		(layers "F.Cu" "B.Cu")
		(net "FM_XRC_PRESENT_N")
	)
	(segment
		(start 474.914976 -28.947364)
		(end 474.914976 -26.43378)
		(width 0.089408)
		(layer "In2.Cu")
		(net "FM_XRC_PRESENT_N")
	)
	(segment
		(start 435.695598 -23.881334)
		(end 436.6768 -23.881334)
		(width 0.089408)
		(layer "In2.Cu")
		(net "FM_XRC_PRESENT_N")
	)
	(segment
		(start 367.367058 -137.865358)
		(end 369.673378 -137.865358)
		(width 0.089408)
		(layer "In2.Cu")
		(net "FM_XRC_PRESENT_N")
	)
	(segment
		(start 462.44129 -32.906208)
		(end 462.984596 -33.449514)
		(width 0.089408)
		(layer "In2.Cu")
		(net "FM_XRC_PRESENT_N")
	)
	(segment
		(start 464.29549 -64.467232)
		(end 465.872322 -62.8904)
		(width 0.089408)
		(layer "In2.Cu")
		(net "FM_XRC_PRESENT_N")
	)
	(segment
		(start 406.1587 -157.861)
		(end 429.7934 -157.861)
		(width 0.089408)
		(layer "In2.Cu")
		(net "FM_XRC_PRESENT_N")
	)
	(segment
		(start 453.45223 -26.94432)
		(end 454.53935 -28.03144)
		(width 0.089408)
		(layer "In2.Cu")
		(net "FM_XRC_PRESENT_N")
	)
	(segment
		(start 469.5444 -61.6458)
		(end 469.5444 -59.2074)
		(width 0.089408)
		(layer "In2.Cu")
		(net "FM_XRC_PRESENT_N")
	)
	(segment
		(start 428.110142 -64.466978)
		(end 428.110396 -64.467232)
		(width 0.089408)
		(layer "In2.Cu")
		(net "FM_XRC_PRESENT_N")
	)
	(segment
		(start 423.174668 -68.027042)
		(end 423.174668 -67.89039)
		(width 0.089408)
		(layer "In2.Cu")
		(net "FM_XRC_PRESENT_N")
	)
	(segment
		(start 423.866056 -76.776072)
		(end 423.174922 -76.084938)
		(width 0.089408)
		(layer "In2.Cu")
		(net "FM_XRC_PRESENT_N")
	)
	(segment
		(start 485.181148 -56.113426)
		(end 485.22636 -56.068214)
		(width 0.089408)
		(layer "In2.Cu")
		(net "FM_XRC_PRESENT_N")
	)
	(segment
		(start 431.844704 -146.983704)
		(end 431.6984 -146.8374)
		(width 0.089408)
		(layer "In2.Cu")
		(net "FM_XRC_PRESENT_N")
	)
	(segment
		(start 424.782996 -26.613104)
		(end 426.477938 -26.613104)
		(width 0.089408)
		(layer "In2.Cu")
		(net "FM_XRC_PRESENT_N")
	)
	(segment
		(start 458.836014 -32.234378)
		(end 459.622652 -32.234378)
		(width 0.089408)
		(layer "In2.Cu")
		(net "FM_XRC_PRESENT_N")
	)
	(segment
		(start 458.305916 -31.70428)
		(end 458.836014 -32.234378)
		(width 0.089408)
		(layer "In2.Cu")
		(net "FM_XRC_PRESENT_N")
	)
	(segment
		(start 366.736376 -138.49604)
		(end 367.367058 -137.865358)
		(width 0.089408)
		(layer "In2.Cu")
		(net "FM_XRC_PRESENT_N")
	)
	(segment
		(start 431.844704 -152.26411)
		(end 431.844704 -146.983704)
		(width 0.089408)
		(layer "In2.Cu")
		(net "FM_XRC_PRESENT_N")
	)
	(segment
		(start 376.19432 -138.10488)
		(end 379.271276 -141.181836)
		(width 0.089408)
		(layer "In2.Cu")
		(net "FM_XRC_PRESENT_N")
	)
	(segment
		(start 369.9129 -138.10488)
		(end 376.19432 -138.10488)
		(width 0.089408)
		(layer "In2.Cu")
		(net "FM_XRC_PRESENT_N")
	)
	(segment
		(start 423.478452 -28.546298)
		(end 423.478452 -27.917648)
		(width 0.089408)
		(layer "In2.Cu")
		(net "FM_XRC_PRESENT_N")
	)
	(segment
		(start 468.742776 -33.449768)
		(end 471.351864 -30.84068)
		(width 0.089408)
		(layer "In2.Cu")
		(net "FM_XRC_PRESENT_N")
	)
	(segment
		(start 423.478452 -27.917648)
		(end 424.782996 -26.613104)
		(width 0.089408)
		(layer "In2.Cu")
		(net "FM_XRC_PRESENT_N")
	)
	(segment
		(start 468.584788 -33.449768)
		(end 468.742776 -33.449768)
		(width 0.089408)
		(layer "In2.Cu")
		(net "FM_XRC_PRESENT_N")
	)
	(segment
		(start 474.914976 -26.43378)
		(end 476.48368 -24.865076)
		(width 0.089408)
		(layer "In2.Cu")
		(net "FM_XRC_PRESENT_N")
	)
	(segment
		(start 379.271276 -141.181836)
		(end 390.247886 -141.181836)
		(width 0.089408)
		(layer "In2.Cu")
		(net "FM_XRC_PRESENT_N")
	)
	(segment
		(start 366.117886 -142.523718)
		(end 366.736376 -141.905228)
		(width 0.089408)
		(layer "In2.Cu")
		(net "FM_XRC_PRESENT_N")
	)
	(segment
		(start 480.156774 -56.073802)
		(end 480.196398 -56.113426)
		(width 0.089408)
		(layer "In2.Cu")
		(net "FM_XRC_PRESENT_N")
	)
	(segment
		(start 479.14433 -24.865076)
		(end 482.003354 -27.7241)
		(width 0.089408)
		(layer "In2.Cu")
		(net "FM_XRC_PRESENT_N")
	)
	(segment
		(start 444.024004 -23.00478)
		(end 447.963544 -26.94432)
		(width 0.089408)
		(layer "In2.Cu")
		(net "FM_XRC_PRESENT_N")
	)
	(segment
		(start 447.963544 -26.94432)
		(end 453.45223 -26.94432)
		(width 0.089408)
		(layer "In2.Cu")
		(net "FM_XRC_PRESENT_N")
	)
	(segment
		(start 423.174922 -76.084938)
		(end 423.174922 -68.027296)
		(width 0.089408)
		(layer "In2.Cu")
		(net "FM_XRC_PRESENT_N")
	)
	(segment
		(start 426.477938 -26.613104)
		(end 427.672246 -25.418796)
		(width 0.089408)
		(layer "In2.Cu")
		(net "FM_XRC_PRESENT_N")
	)
	(segment
		(start 468.2998 -62.8904)
		(end 469.5444 -61.6458)
		(width 0.089408)
		(layer "In2.Cu")
		(net "FM_XRC_PRESENT_N")
	)
	(segment
		(start 424.486578 -104.070404)
		(end 424.486578 -79.309976)
		(width 0.089408)
		(layer "In2.Cu")
		(net "FM_XRC_PRESENT_N")
	)
	(segment
		(start 454.53935 -28.03144)
		(end 455.199496 -28.03144)
		(width 0.089408)
		(layer "In2.Cu")
		(net "FM_XRC_PRESENT_N")
	)
	(segment
		(start 480.196398 -56.113426)
		(end 485.181148 -56.113426)
		(width 0.089408)
		(layer "In2.Cu")
		(net "FM_XRC_PRESENT_N")
	)
	(segment
		(start 423.866056 -78.689454)
		(end 423.866056 -76.776072)
		(width 0.089408)
		(layer "In2.Cu")
		(net "FM_XRC_PRESENT_N")
	)
	(segment
		(start 427.672246 -25.418796)
		(end 427.672246 -25.289764)
		(width 0.089408)
		(layer "In2.Cu")
		(net "FM_XRC_PRESENT_N")
	)
	(segment
		(start 404.469346 -149.225)
		(end 405.511 -150.266654)
		(width 0.089408)
		(layer "In2.Cu")
		(net "FM_XRC_PRESENT_N")
	)
	(segment
		(start 429.611028 -24.965914)
		(end 430.633378 -24.965914)
		(width 0.089408)
		(layer "In2.Cu")
		(net "FM_XRC_PRESENT_N")
	)
	(segment
		(start 471.351864 -30.84068)
		(end 473.021914 -30.84068)
		(width 0.089408)
		(layer "In2.Cu")
		(net "FM_XRC_PRESENT_N")
	)
	(segment
		(start 485.811068 -28.306268)
		(end 486.283 -28.7782)
		(width 0.089408)
		(layer "In2.Cu")
		(net "FM_XRC_PRESENT_N")
	)
	(segment
		(start 423.174922 -67.564762)
		(end 426.272706 -64.466978)
		(width 0.089408)
		(layer "In2.Cu")
		(net "FM_XRC_PRESENT_N")
	)
	(segment
		(start 465.872322 -62.8904)
		(end 468.2998 -62.8904)
		(width 0.089408)
		(layer "In2.Cu")
		(net "FM_XRC_PRESENT_N")
	)
	(segment
		(start 482.003354 -27.7241)
		(end 483.505764 -27.7241)
		(width 0.089408)
		(layer "In2.Cu")
		(net "FM_XRC_PRESENT_N")
	)
	(segment
		(start 428.110396 -64.467232)
		(end 464.29549 -64.467232)
		(width 0.089408)
		(layer "In2.Cu")
		(net "FM_XRC_PRESENT_N")
	)
	(segment
		(start 455.199496 -28.03144)
		(end 458.305916 -31.13786)
		(width 0.089408)
		(layer "In2.Cu")
		(net "FM_XRC_PRESENT_N")
	)
	(segment
		(start 423.658284 -104.898698)
		(end 424.486578 -104.070404)
		(width 0.089408)
		(layer "In2.Cu")
		(net "FM_XRC_PRESENT_N")
	)
	(segment
		(start 430.633378 -24.965914)
		(end 430.847754 -24.751538)
		(width 0.089408)
		(layer "In2.Cu")
		(net "FM_XRC_PRESENT_N")
	)
	(segment
		(start 437.553354 -23.00478)
		(end 444.024004 -23.00478)
		(width 0.089408)
		(layer "In2.Cu")
		(net "FM_XRC_PRESENT_N")
	)
	(segment
		(start 460.294482 -32.906208)
		(end 462.44129 -32.906208)
		(width 0.089408)
		(layer "In2.Cu")
		(net "FM_XRC_PRESENT_N")
	)
	(segment
		(start 366.736376 -141.905228)
		(end 366.736376 -138.49604)
		(width 0.089408)
		(layer "In2.Cu")
		(net "FM_XRC_PRESENT_N")
	)
	(segment
		(start 369.673378 -137.865358)
		(end 369.9129 -138.10488)
		(width 0.089408)
		(layer "In2.Cu")
		(net "FM_XRC_PRESENT_N")
	)
	(segment
		(start 423.174668 -67.89039)
		(end 423.174922 -67.890136)
		(width 0.089408)
		(layer "In2.Cu")
		(net "FM_XRC_PRESENT_N")
	)
	(segment
		(start 424.486578 -79.309976)
		(end 423.866056 -78.689454)
		(width 0.089408)
		(layer "In2.Cu")
		(net "FM_XRC_PRESENT_N")
	)
	(segment
		(start 431.6984 -155.956)
		(end 431.6984 -152.410414)
		(width 0.089408)
		(layer "In2.Cu")
		(net "FM_XRC_PRESENT_N")
	)
	(segment
		(start 426.272706 -64.466978)
		(end 428.110142 -64.466978)
		(width 0.089408)
		(layer "In2.Cu")
		(net "FM_XRC_PRESENT_N")
	)
	(segment
		(start 472.677998 -56.073802)
		(end 480.156774 -56.073802)
		(width 0.089408)
		(layer "In2.Cu")
		(net "FM_XRC_PRESENT_N")
	)
	(segment
		(start 484.087932 -28.306268)
		(end 485.811068 -28.306268)
		(width 0.089408)
		(layer "In2.Cu")
		(net "FM_XRC_PRESENT_N")
	)
	(segment
		(start 468.584534 -33.449514)
		(end 468.584788 -33.449768)
		(width 0.089408)
		(layer "In2.Cu")
		(net "FM_XRC_PRESENT_N")
	)
	(segment
		(start 405.511 -157.2133)
		(end 406.1587 -157.861)
		(width 0.089408)
		(layer "In2.Cu")
		(net "FM_XRC_PRESENT_N")
	)
	(segment
		(start 429.7934 -157.861)
		(end 431.6984 -155.956)
		(width 0.089408)
		(layer "In2.Cu")
		(net "FM_XRC_PRESENT_N")
	)
	(segment
		(start 395.158976 -146.979386)
		(end 396.480538 -148.300948)
		(width 0.089408)
		(layer "In2.Cu")
		(net "FM_XRC_PRESENT_N")
	)
	(segment
		(start 427.672246 -25.289764)
		(end 428.279814 -24.682196)
		(width 0.089408)
		(layer "In2.Cu")
		(net "FM_XRC_PRESENT_N")
	)
	(segment
		(start 459.622652 -32.234378)
		(end 460.294482 -32.906208)
		(width 0.089408)
		(layer "In2.Cu")
		(net "FM_XRC_PRESENT_N")
	)
	(segment
		(start 431.6984 -152.410414)
		(end 431.844704 -152.26411)
		(width 0.089408)
		(layer "In2.Cu")
		(net "FM_XRC_PRESENT_N")
	)
	(segment
		(start 396.480538 -148.300948)
		(end 398.67713 -148.300948)
		(width 0.089408)
		(layer "In2.Cu")
		(net "FM_XRC_PRESENT_N")
	)
	(segment
		(start 423.174922 -67.890136)
		(end 423.174922 -67.564762)
		(width 0.089408)
		(layer "In2.Cu")
		(net "FM_XRC_PRESENT_N")
	)
	(segment
		(start 430.847754 -24.751538)
		(end 434.825394 -24.751538)
		(width 0.089408)
		(layer "In2.Cu")
		(net "FM_XRC_PRESENT_N")
	)
	(segment
		(start 469.5444 -59.2074)
		(end 472.677998 -56.073802)
		(width 0.089408)
		(layer "In2.Cu")
		(net "FM_XRC_PRESENT_N")
	)
	(segment
		(start 405.511 -150.266654)
		(end 405.511 -157.2133)
		(width 0.089408)
		(layer "In2.Cu")
		(net "FM_XRC_PRESENT_N")
	)
	(segment
		(start 436.6768 -23.881334)
		(end 437.553354 -23.00478)
		(width 0.089408)
		(layer "In2.Cu")
		(net "FM_XRC_PRESENT_N")
	)
	(segment
		(start 458.305916 -31.13786)
		(end 458.305916 -31.70428)
		(width 0.089408)
		(layer "In2.Cu")
		(net "FM_XRC_PRESENT_N")
	)
	(segment
		(start 423.174922 -68.027296)
		(end 423.174668 -68.027042)
		(width 0.089408)
		(layer "In2.Cu")
		(net "FM_XRC_PRESENT_N")
	)
	(segment
		(start 390.247886 -141.181836)
		(end 391.358882 -142.292832)
		(width 0.089408)
		(layer "In2.Cu")
		(net "FM_XRC_PRESENT_N")
	)
	(segment
		(start 483.505764 -27.7241)
		(end 484.087932 -28.306268)
		(width 0.089408)
		(layer "In2.Cu")
		(net "FM_XRC_PRESENT_N")
	)
	(segment
		(start 395.158976 -142.893288)
		(end 395.158976 -146.979386)
		(width 0.089408)
		(layer "In2.Cu")
		(net "FM_XRC_PRESENT_N")
	)
	(segment
		(start 391.358882 -142.292832)
		(end 394.55852 -142.292832)
		(width 0.089408)
		(layer "In2.Cu")
		(net "FM_XRC_PRESENT_N")
	)
	(segment
		(start 398.67713 -148.300948)
		(end 399.601182 -149.225)
		(width 0.089408)
		(layer "In2.Cu")
		(net "FM_XRC_PRESENT_N")
	)
	(segment
		(start 399.601182 -149.225)
		(end 404.469346 -149.225)
		(width 0.089408)
		(layer "In2.Cu")
		(net "FM_XRC_PRESENT_N")
	)
	(segment
		(start 428.279814 -24.682196)
		(end 429.32731 -24.682196)
		(width 0.089408)
		(layer "In2.Cu")
		(net "FM_XRC_PRESENT_N")
	)
	(segment
		(start 429.32731 -24.682196)
		(end 429.611028 -24.965914)
		(width 0.089408)
		(layer "In2.Cu")
		(net "FM_XRC_PRESENT_N")
	)
	(segment
		(start 473.021914 -30.84068)
		(end 474.914976 -28.947364)
		(width 0.089408)
		(layer "In2.Cu")
		(net "FM_XRC_PRESENT_N")
	)
	(segment
		(start 462.984596 -33.449514)
		(end 468.584534 -33.449514)
		(width 0.089408)
		(layer "In2.Cu")
		(net "FM_XRC_PRESENT_N")
	)
	(segment
		(start 476.48368 -24.865076)
		(end 479.14433 -24.865076)
		(width 0.089408)
		(layer "In2.Cu")
		(net "FM_XRC_PRESENT_N")
	)
	(segment
		(start 394.55852 -142.292832)
		(end 395.158976 -142.893288)
		(width 0.089408)
		(layer "In2.Cu")
		(net "FM_XRC_PRESENT_N")
	)
	(segment
		(start 434.825394 -24.751538)
		(end 435.695598 -23.881334)
		(width 0.089408)
		(layer "In2.Cu")
		(net "FM_XRC_PRESENT_N")
	)
	(segment
		(start 419.14445 -121.705116)
		(end 419.14445 -109.02315)
		(width 0.089408)
		(layer "In4.Cu")
		(net "FM_XRC_PRESENT_N")
	)
	(segment
		(start 419.14445 -109.02315)
		(end 423.268902 -104.898698)
		(width 0.089408)
		(layer "In4.Cu")
		(net "FM_XRC_PRESENT_N")
	)
	(segment
		(start 416.85591 -123.399296)
		(end 417.801806 -122.4534)
		(width 0.089408)
		(layer "In4.Cu")
		(net "FM_XRC_PRESENT_N")
	)
	(segment
		(start 423.268902 -104.898698)
		(end 423.658284 -104.898698)
		(width 0.089408)
		(layer "In4.Cu")
		(net "FM_XRC_PRESENT_N")
	)
	(segment
		(start 416.673538 -123.399296)
		(end 416.85591 -123.399296)
		(width 0.089408)
		(layer "In4.Cu")
		(net "FM_XRC_PRESENT_N")
	)
	(segment
		(start 418.396166 -122.4534)
		(end 419.14445 -121.705116)
		(width 0.089408)
		(layer "In4.Cu")
		(net "FM_XRC_PRESENT_N")
	)
	(segment
		(start 416.207194 -123.86564)
		(end 416.673538 -123.399296)
		(width 0.089408)
		(layer "In4.Cu")
		(net "FM_XRC_PRESENT_N")
	)
	(segment
		(start 416.374834 -124.74829)
		(end 416.207194 -124.58065)
		(width 0.089408)
		(layer "In4.Cu")
		(net "FM_XRC_PRESENT_N")
	)
	(segment
		(start 417.801806 -122.4534)
		(end 418.396166 -122.4534)
		(width 0.089408)
		(layer "In4.Cu")
		(net "FM_XRC_PRESENT_N")
	)
	(segment
		(start 416.207194 -124.58065)
		(end 416.207194 -123.86564)
		(width 0.089408)
		(layer "In4.Cu")
		(net "FM_XRC_PRESENT_N")
	)
	(segment
		(start 344.502486 -141.560042)
		(end 348.35084 -141.560042)
		(width 0.089408)
		(layer "In9.Cu")
		(net "FM_XRC_PRESENT_N")
	)
	(segment
		(start 486.537 -49.35347)
		(end 486.523792 -49.340262)
		(width 0.089408)
		(layer "In9.Cu")
		(net "FM_XRC_PRESENT_N")
	)
	(segment
		(start 348.35084 -141.560042)
		(end 349.141796 -140.769086)
		(width 0.089408)
		(layer "In9.Cu")
		(net "FM_XRC_PRESENT_N")
	)
	(segment
		(start 16.725392 -120.30456)
		(end 17.547082 -121.12625)
		(width 0.089408)
		(layer "In9.Cu")
		(net "FM_XRC_PRESENT_N")
	)
	(segment
		(start 415.770568 -130.849878)
		(end 415.770568 -130.905504)
		(width 0.089408)
		(layer "In9.Cu")
		(net "FM_XRC_PRESENT_N")
	)
	(segment
		(start 351.771712 -140.981684)
		(end 355.096572 -144.306544)
		(width 0.089408)
		(layer "In9.Cu")
		(net "FM_XRC_PRESENT_N")
	)
	(segment
		(start 29.337 -154.432)
		(end 29.337 -155.321)
		(width 0.089408)
		(layer "In9.Cu")
		(net "FM_XRC_PRESENT_N")
	)
	(segment
		(start -5.089652 -116.757196)
		(end -1.856486 -119.990362)
		(width 0.089408)
		(layer "In9.Cu")
		(net "FM_XRC_PRESENT_N")
	)
	(segment
		(start 485.91343 -55.914544)
		(end 485.91343 -53.132482)
		(width 0.089408)
		(layer "In9.Cu")
		(net "FM_XRC_PRESENT_N")
	)
	(segment
		(start 29.337 -155.321)
		(end 30.353 -156.337)
		(width 0.089408)
		(layer "In9.Cu")
		(net "FM_XRC_PRESENT_N")
	)
	(segment
		(start 415.525966 -125.597158)
		(end 415.525966 -129.977642)
		(width 0.089408)
		(layer "In9.Cu")
		(net "FM_XRC_PRESENT_N")
	)
	(segment
		(start 487.0196 -35.7632)
		(end 487.0196 -28.967176)
		(width 0.089408)
		(layer "In9.Cu")
		(net "FM_XRC_PRESENT_N")
	)
	(segment
		(start 99.440746 -156.083)
		(end 157.29712 -156.083)
		(width 0.089408)
		(layer "In9.Cu")
		(net "FM_XRC_PRESENT_N")
	)
	(segment
		(start 349.141796 -140.769086)
		(end 350.202246 -140.769086)
		(width 0.089408)
		(layer "In9.Cu")
		(net "FM_XRC_PRESENT_N")
	)
	(segment
		(start 487.1466 -48.38573)
		(end 487.1466 -39.0398)
		(width 0.089408)
		(layer "In9.Cu")
		(net "FM_XRC_PRESENT_N")
	)
	(segment
		(start 488.1118 -38.0746)
		(end 488.1118 -36.8554)
		(width 0.089408)
		(layer "In9.Cu")
		(net "FM_XRC_PRESENT_N")
	)
	(segment
		(start 488.1118 -36.8554)
		(end 487.0196 -35.7632)
		(width 0.089408)
		(layer "In9.Cu")
		(net "FM_XRC_PRESENT_N")
	)
	(segment
		(start -1.856486 -119.990362)
		(end 7.592822 -119.990362)
		(width 0.089408)
		(layer "In9.Cu")
		(net "FM_XRC_PRESENT_N")
	)
	(segment
		(start 342.300052 -139.357608)
		(end 344.502486 -141.560042)
		(width 0.089408)
		(layer "In9.Cu")
		(net "FM_XRC_PRESENT_N")
	)
	(segment
		(start 415.534094 -129.98577)
		(end 415.534094 -130.613404)
		(width 0.089408)
		(layer "In9.Cu")
		(net "FM_XRC_PRESENT_N")
	)
	(segment
		(start 364.836456 -144.306544)
		(end 366.117886 -143.025114)
		(width 0.089408)
		(layer "In9.Cu")
		(net "FM_XRC_PRESENT_N")
	)
	(segment
		(start 350.202246 -140.769086)
		(end 350.414844 -140.981684)
		(width 0.089408)
		(layer "In9.Cu")
		(net "FM_XRC_PRESENT_N")
	)
	(segment
		(start 264.654792 -157.620208)
		(end 279.66416 -157.620208)
		(width 0.089408)
		(layer "In9.Cu")
		(net "FM_XRC_PRESENT_N")
	)
	(segment
		(start 16.823944 -129.139696)
		(end 18.503138 -130.81889)
		(width 0.089408)
		(layer "In9.Cu")
		(net "FM_XRC_PRESENT_N")
	)
	(segment
		(start 485.91343 -53.132482)
		(end 486.537 -52.508912)
		(width 0.089408)
		(layer "In9.Cu")
		(net "FM_XRC_PRESENT_N")
	)
	(segment
		(start -5.089652 -96.847406)
		(end -5.089652 -116.757196)
		(width 0.089408)
		(layer "In9.Cu")
		(net "FM_XRC_PRESENT_N")
	)
	(segment
		(start 487.1466 -39.0398)
		(end 488.1118 -38.0746)
		(width 0.089408)
		(layer "In9.Cu")
		(net "FM_XRC_PRESENT_N")
	)
	(segment
		(start 3.729482 -95.9993)
		(end -4.241546 -95.9993)
		(width 0.089408)
		(layer "In9.Cu")
		(net "FM_XRC_PRESENT_N")
	)
	(segment
		(start 330.036424 -158.151576)
		(end 331.597 -156.591)
		(width 0.089408)
		(layer "In9.Cu")
		(net "FM_XRC_PRESENT_N")
	)
	(segment
		(start 431.6984 -146.369024)
		(end 431.6984 -146.8374)
		(width 0.089408)
		(layer "In9.Cu")
		(net "FM_XRC_PRESENT_N")
	)
	(segment
		(start 485.75976 -56.068214)
		(end 485.91343 -55.914544)
		(width 0.089408)
		(layer "In9.Cu")
		(net "FM_XRC_PRESENT_N")
	)
	(segment
		(start 18.503138 -130.81889)
		(end 18.503138 -133.433058)
		(width 0.089408)
		(layer "In9.Cu")
		(net "FM_XRC_PRESENT_N")
	)
	(segment
		(start 180.073808 -154.26817)
		(end 182.224934 -156.419296)
		(width 0.089408)
		(layer "In9.Cu")
		(net "FM_XRC_PRESENT_N")
	)
	(segment
		(start 422.632632 -140.5382)
		(end 423.860214 -141.765782)
		(width 0.089408)
		(layer "In9.Cu")
		(net "FM_XRC_PRESENT_N")
	)
	(segment
		(start 16.819118 -129.139696)
		(end 16.823944 -129.139696)
		(width 0.089408)
		(layer "In9.Cu")
		(net "FM_XRC_PRESENT_N")
	)
	(segment
		(start 21.730462 -150.524718)
		(end 23.034752 -151.829008)
		(width 0.089408)
		(layer "In9.Cu")
		(net "FM_XRC_PRESENT_N")
	)
	(segment
		(start 167.827706 -150.178008)
		(end 176.91481 -150.178008)
		(width 0.089408)
		(layer "In9.Cu")
		(net "FM_XRC_PRESENT_N")
	)
	(segment
		(start 16.456152 -123.370848)
		(end 16.456152 -128.77673)
		(width 0.089408)
		(layer "In9.Cu")
		(net "FM_XRC_PRESENT_N")
	)
	(segment
		(start 430.851564 -141.765782)
		(end 431.787554 -142.701772)
		(width 0.089408)
		(layer "In9.Cu")
		(net "FM_XRC_PRESENT_N")
	)
	(segment
		(start 165.21303 -152.792684)
		(end 167.827706 -150.178008)
		(width 0.089408)
		(layer "In9.Cu")
		(net "FM_XRC_PRESENT_N")
	)
	(segment
		(start 187.70854 -157.91561)
		(end 264.35939 -157.91561)
		(width 0.089408)
		(layer "In9.Cu")
		(net "FM_XRC_PRESENT_N")
	)
	(segment
		(start 30.353 -156.337)
		(end 99.186746 -156.337)
		(width 0.089408)
		(layer "In9.Cu")
		(net "FM_XRC_PRESENT_N")
	)
	(segment
		(start 21.730208 -136.660128)
		(end 21.730208 -150.114)
		(width 0.089408)
		(layer "In9.Cu")
		(net "FM_XRC_PRESENT_N")
	)
	(segment
		(start 180.073808 -153.337006)
		(end 180.073808 -154.26817)
		(width 0.089408)
		(layer "In9.Cu")
		(net "FM_XRC_PRESENT_N")
	)
	(segment
		(start 416.374834 -124.74829)
		(end 415.525966 -125.597158)
		(width 0.089408)
		(layer "In9.Cu")
		(net "FM_XRC_PRESENT_N")
	)
	(segment
		(start 366.117886 -143.025114)
		(end 366.117886 -142.523718)
		(width 0.089408)
		(layer "In9.Cu")
		(net "FM_XRC_PRESENT_N")
	)
	(segment
		(start 486.830624 -28.7782)
		(end 486.283 -28.7782)
		(width 0.089408)
		(layer "In9.Cu")
		(net "FM_XRC_PRESENT_N")
	)
	(segment
		(start 421.269668 -140.5382)
		(end 422.632632 -140.5382)
		(width 0.089408)
		(layer "In9.Cu")
		(net "FM_XRC_PRESENT_N")
	)
	(segment
		(start 4.499864 -96.769936)
		(end 4.499864 -96.769682)
		(width 0.089408)
		(layer "In9.Cu")
		(net "FM_XRC_PRESENT_N")
	)
	(segment
		(start 431.787554 -142.701772)
		(end 431.787554 -146.27987)
		(width 0.089408)
		(layer "In9.Cu")
		(net "FM_XRC_PRESENT_N")
	)
	(segment
		(start 23.034752 -151.829008)
		(end 26.734008 -151.829008)
		(width 0.089408)
		(layer "In9.Cu")
		(net "FM_XRC_PRESENT_N")
	)
	(segment
		(start 280.195528 -158.151576)
		(end 330.036424 -158.151576)
		(width 0.089408)
		(layer "In9.Cu")
		(net "FM_XRC_PRESENT_N")
	)
	(segment
		(start 486.537 -52.508912)
		(end 486.537 -49.35347)
		(width 0.089408)
		(layer "In9.Cu")
		(net "FM_XRC_PRESENT_N")
	)
	(segment
		(start 331.597 -156.591)
		(end 337.058 -156.591)
		(width 0.089408)
		(layer "In9.Cu")
		(net "FM_XRC_PRESENT_N")
	)
	(segment
		(start 157.29712 -156.083)
		(end 160.587436 -152.792684)
		(width 0.089408)
		(layer "In9.Cu")
		(net "FM_XRC_PRESENT_N")
	)
	(segment
		(start 338.0486 -139.99845)
		(end 338.689442 -139.357608)
		(width 0.089408)
		(layer "In9.Cu")
		(net "FM_XRC_PRESENT_N")
	)
	(segment
		(start 18.503138 -133.433058)
		(end 21.730208 -136.660128)
		(width 0.089408)
		(layer "In9.Cu")
		(net "FM_XRC_PRESENT_N")
	)
	(segment
		(start 418.434774 -137.703306)
		(end 421.269668 -140.5382)
		(width 0.089408)
		(layer "In9.Cu")
		(net "FM_XRC_PRESENT_N")
	)
	(segment
		(start 21.730208 -150.114)
		(end 21.730462 -150.114)
		(width 0.089408)
		(layer "In9.Cu")
		(net "FM_XRC_PRESENT_N")
	)
	(segment
		(start 264.35939 -157.91561)
		(end 264.654792 -157.620208)
		(width 0.089408)
		(layer "In9.Cu")
		(net "FM_XRC_PRESENT_N")
	)
	(segment
		(start 176.91481 -150.178008)
		(end 180.073808 -153.337006)
		(width 0.089408)
		(layer "In9.Cu")
		(net "FM_XRC_PRESENT_N")
	)
	(segment
		(start 486.523792 -49.008538)
		(end 487.1466 -48.38573)
		(width 0.089408)
		(layer "In9.Cu")
		(net "FM_XRC_PRESENT_N")
	)
	(segment
		(start 415.525966 -129.977642)
		(end 415.534094 -129.98577)
		(width 0.089408)
		(layer "In9.Cu")
		(net "FM_XRC_PRESENT_N")
	)
	(segment
		(start 26.734008 -151.829008)
		(end 29.337 -154.432)
		(width 0.089408)
		(layer "In9.Cu")
		(net "FM_XRC_PRESENT_N")
	)
	(segment
		(start 350.414844 -140.981684)
		(end 351.771712 -140.981684)
		(width 0.089408)
		(layer "In9.Cu")
		(net "FM_XRC_PRESENT_N")
	)
	(segment
		(start -4.241546 -95.9993)
		(end -5.089652 -96.847406)
		(width 0.089408)
		(layer "In9.Cu")
		(net "FM_XRC_PRESENT_N")
	)
	(segment
		(start 186.212226 -156.419296)
		(end 187.70854 -157.91561)
		(width 0.089408)
		(layer "In9.Cu")
		(net "FM_XRC_PRESENT_N")
	)
	(segment
		(start 160.587436 -152.792684)
		(end 165.21303 -152.792684)
		(width 0.089408)
		(layer "In9.Cu")
		(net "FM_XRC_PRESENT_N")
	)
	(segment
		(start 7.592822 -119.990362)
		(end 7.90702 -120.30456)
		(width 0.089408)
		(layer "In9.Cu")
		(net "FM_XRC_PRESENT_N")
	)
	(segment
		(start 182.224934 -156.419296)
		(end 186.212226 -156.419296)
		(width 0.089408)
		(layer "In9.Cu")
		(net "FM_XRC_PRESENT_N")
	)
	(segment
		(start 16.456152 -128.77673)
		(end 16.819118 -129.139696)
		(width 0.089408)
		(layer "In9.Cu")
		(net "FM_XRC_PRESENT_N")
	)
	(segment
		(start 337.058 -156.591)
		(end 338.0486 -155.6004)
		(width 0.089408)
		(layer "In9.Cu")
		(net "FM_XRC_PRESENT_N")
	)
	(segment
		(start 418.434774 -133.56971)
		(end 418.434774 -137.703306)
		(width 0.089408)
		(layer "In9.Cu")
		(net "FM_XRC_PRESENT_N")
	)
	(segment
		(start 17.547082 -122.279918)
		(end 16.456152 -123.370848)
		(width 0.089408)
		(layer "In9.Cu")
		(net "FM_XRC_PRESENT_N")
	)
	(segment
		(start 338.689442 -139.357608)
		(end 342.300052 -139.357608)
		(width 0.089408)
		(layer "In9.Cu")
		(net "FM_XRC_PRESENT_N")
	)
	(segment
		(start 485.22636 -56.068214)
		(end 485.75976 -56.068214)
		(width 0.089408)
		(layer "In9.Cu")
		(net "FM_XRC_PRESENT_N")
	)
	(segment
		(start 99.186746 -156.337)
		(end 99.440746 -156.083)
		(width 0.089408)
		(layer "In9.Cu")
		(net "FM_XRC_PRESENT_N")
	)
	(segment
		(start 431.787554 -146.27987)
		(end 431.6984 -146.369024)
		(width 0.089408)
		(layer "In9.Cu")
		(net "FM_XRC_PRESENT_N")
	)
	(segment
		(start 17.547082 -121.12625)
		(end 17.547082 -122.279918)
		(width 0.089408)
		(layer "In9.Cu")
		(net "FM_XRC_PRESENT_N")
	)
	(segment
		(start 415.770568 -130.905504)
		(end 418.434774 -133.56971)
		(width 0.089408)
		(layer "In9.Cu")
		(net "FM_XRC_PRESENT_N")
	)
	(segment
		(start 487.0196 -28.967176)
		(end 486.830624 -28.7782)
		(width 0.089408)
		(layer "In9.Cu")
		(net "FM_XRC_PRESENT_N")
	)
	(segment
		(start 415.534094 -130.613404)
		(end 415.770568 -130.849878)
		(width 0.089408)
		(layer "In9.Cu")
		(net "FM_XRC_PRESENT_N")
	)
	(segment
		(start 279.66416 -157.620208)
		(end 280.195528 -158.151576)
		(width 0.089408)
		(layer "In9.Cu")
		(net "FM_XRC_PRESENT_N")
	)
	(segment
		(start 338.0486 -155.6004)
		(end 338.0486 -139.99845)
		(width 0.089408)
		(layer "In9.Cu")
		(net "FM_XRC_PRESENT_N")
	)
	(segment
		(start 7.90702 -120.30456)
		(end 16.725392 -120.30456)
		(width 0.089408)
		(layer "In9.Cu")
		(net "FM_XRC_PRESENT_N")
	)
	(segment
		(start 423.860214 -141.765782)
		(end 430.851564 -141.765782)
		(width 0.089408)
		(layer "In9.Cu")
		(net "FM_XRC_PRESENT_N")
	)
	(segment
		(start 21.730462 -150.114)
		(end 21.730462 -150.524718)
		(width 0.089408)
		(layer "In9.Cu")
		(net "FM_XRC_PRESENT_N")
	)
	(segment
		(start 355.096572 -144.306544)
		(end 364.836456 -144.306544)
		(width 0.089408)
		(layer "In9.Cu")
		(net "FM_XRC_PRESENT_N")
	)
	(segment
		(start 486.523792 -49.340262)
		(end 486.523792 -49.008538)
		(width 0.089408)
		(layer "In9.Cu")
		(net "FM_XRC_PRESENT_N")
	)
	(segment
		(start 4.499864 -96.769682)
		(end 3.729482 -95.9993)
		(width 0.089408)
		(layer "In9.Cu")
		(net "FM_XRC_PRESENT_N")
	)
	(segment
		(start 397.14805 -99.55276)
		(end 397.558768 -99.362006)
		(width 0.10795)
		(layer "F.Cu")
		(net "FM_UV_ADR_TRIGGER_EN")
	)
	(segment
		(start 369.545108 -73.495154)
		(end 369.944904 -73.89495)
		(width 0.1016)
		(layer "F.Cu")
		(net "FM_UV_ADR_TRIGGER_EN")
	)
	(segment
		(start 397.558768 -99.362006)
		(end 397.64335 -99.322636)
		(width 0.10795)
		(layer "F.Cu")
		(net "FM_UV_ADR_TRIGGER_EN")
	)
	(segment
		(start 408.690064 -38.534594)
		(end 408.290014 -38.934644)
		(width 0.10795)
		(layer "F.Cu")
		(net "FM_UV_ADR_TRIGGER_EN")
	)
	(via
		(at 369.545108 -73.495154)
		(size 0.4572)
		(drill 0.2032)
		(layers "F.Cu" "B.Cu")
		(net "FM_UV_ADR_TRIGGER_EN")
	)
	(via
		(at 397.64335 -99.322636)
		(size 0.508)
		(drill 0.254)
		(layers "F.Cu" "B.Cu")
		(net "FM_UV_ADR_TRIGGER_EN")
	)
	(via
		(at 408.290014 -38.934644)
		(size 0.4572)
		(drill 0.2032)
		(layers "F.Cu" "B.Cu")
		(net "FM_UV_ADR_TRIGGER_EN")
	)
	(via
		(at 396.113 -73.7362)
		(size 0.508)
		(drill 0.254)
		(layers "F.Cu" "B.Cu")
		(net "FM_UV_ADR_TRIGGER_EN")
	)
	(via
		(at 402.7424 -95.3008)
		(size 0.6604)
		(drill 0.3302)
		(layers "F.Cu" "B.Cu")
		(net "FM_UV_ADR_TRIGGER_EN")
	)
	(segment
		(start 397.730472 -98.295206)
		(end 397.64335 -98.382328)
		(width 0.10795)
		(layer "B.Cu")
		(net "FM_UV_ADR_TRIGGER_EN")
	)
	(segment
		(start 397.730472 -98.294952)
		(end 397.730472 -98.295206)
		(width 0.10795)
		(layer "B.Cu")
		(net "FM_UV_ADR_TRIGGER_EN")
	)
	(segment
		(start 401.737322 -95.54972)
		(end 399.231104 -98.055938)
		(width 0.10795)
		(layer "B.Cu")
		(net "FM_UV_ADR_TRIGGER_EN")
	)
	(segment
		(start 399.231104 -98.055938)
		(end 397.969486 -98.055938)
		(width 0.10795)
		(layer "B.Cu")
		(net "FM_UV_ADR_TRIGGER_EN")
	)
	(segment
		(start 397.64335 -98.382328)
		(end 397.64335 -99.322636)
		(width 0.10795)
		(layer "B.Cu")
		(net "FM_UV_ADR_TRIGGER_EN")
	)
	(segment
		(start 403.104096 -94.939104)
		(end 402.7424 -95.3008)
		(width 0.10795)
		(layer "B.Cu")
		(net "FM_UV_ADR_TRIGGER_EN")
	)
	(segment
		(start 402.7424 -95.3008)
		(end 402.49348 -95.54972)
		(width 0.10795)
		(layer "B.Cu")
		(net "FM_UV_ADR_TRIGGER_EN")
	)
	(segment
		(start 403.909022 -94.939104)
		(end 403.104096 -94.939104)
		(width 0.10795)
		(layer "B.Cu")
		(net "FM_UV_ADR_TRIGGER_EN")
	)
	(segment
		(start 402.49348 -95.54972)
		(end 401.737322 -95.54972)
		(width 0.10795)
		(layer "B.Cu")
		(net "FM_UV_ADR_TRIGGER_EN")
	)
	(segment
		(start 397.969486 -98.055938)
		(end 397.730472 -98.294952)
		(width 0.10795)
		(layer "B.Cu")
		(net "FM_UV_ADR_TRIGGER_EN")
	)
	(segment
		(start 404.330408 -94.517718)
		(end 403.909022 -94.939104)
		(width 0.10795)
		(layer "B.Cu")
		(net "FM_UV_ADR_TRIGGER_EN")
	)
	(segment
		(start 393.55268 -78.443328)
		(end 393.55268 -78.905862)
		(width 0.089408)
		(layer "In2.Cu")
		(net "FM_UV_ADR_TRIGGER_EN")
	)
	(segment
		(start 393.55268 -78.905862)
		(end 394.527024 -79.880206)
		(width 0.089408)
		(layer "In2.Cu")
		(net "FM_UV_ADR_TRIGGER_EN")
	)
	(segment
		(start 394.892784 -88.203024)
		(end 397.134588 -90.444828)
		(width 0.089408)
		(layer "In2.Cu")
		(net "FM_UV_ADR_TRIGGER_EN")
	)
	(segment
		(start 397.134842 -93.882464)
		(end 398.275556 -95.023178)
		(width 0.089408)
		(layer "In2.Cu")
		(net "FM_UV_ADR_TRIGGER_EN")
	)
	(segment
		(start 393.985496 -83.080352)
		(end 393.985496 -87.048848)
		(width 0.089408)
		(layer "In2.Cu")
		(net "FM_UV_ADR_TRIGGER_EN")
	)
	(segment
		(start 398.53743 -97.132648)
		(end 398.454626 -97.215452)
		(width 0.089408)
		(layer "In2.Cu")
		(net "FM_UV_ADR_TRIGGER_EN")
	)
	(segment
		(start 397.844264 -99.322636)
		(end 397.64335 -99.322636)
		(width 0.089408)
		(layer "In2.Cu")
		(net "FM_UV_ADR_TRIGGER_EN")
	)
	(segment
		(start 397.134842 -93.63329)
		(end 397.134842 -93.882464)
		(width 0.089408)
		(layer "In2.Cu")
		(net "FM_UV_ADR_TRIGGER_EN")
	)
	(segment
		(start 398.53743 -96.439736)
		(end 398.53743 -97.132648)
		(width 0.089408)
		(layer "In2.Cu")
		(net "FM_UV_ADR_TRIGGER_EN")
	)
	(segment
		(start 398.454626 -97.903792)
		(end 398.53743 -97.986596)
		(width 0.089408)
		(layer "In2.Cu")
		(net "FM_UV_ADR_TRIGGER_EN")
	)
	(segment
		(start 393.985496 -87.048848)
		(end 394.892784 -87.956136)
		(width 0.089408)
		(layer "In2.Cu")
		(net "FM_UV_ADR_TRIGGER_EN")
	)
	(segment
		(start 394.527024 -79.880206)
		(end 394.527024 -82.538824)
		(width 0.089408)
		(layer "In2.Cu")
		(net "FM_UV_ADR_TRIGGER_EN")
	)
	(segment
		(start 397.134588 -90.444828)
		(end 397.134588 -93.63329)
		(width 0.089408)
		(layer "In2.Cu")
		(net "FM_UV_ADR_TRIGGER_EN")
	)
	(segment
		(start 394.892784 -87.956136)
		(end 394.892784 -88.203024)
		(width 0.089408)
		(layer "In2.Cu")
		(net "FM_UV_ADR_TRIGGER_EN")
	)
	(segment
		(start 398.275556 -96.177862)
		(end 398.53743 -96.439736)
		(width 0.089408)
		(layer "In2.Cu")
		(net "FM_UV_ADR_TRIGGER_EN")
	)
	(segment
		(start 398.275556 -95.023178)
		(end 398.275556 -96.177862)
		(width 0.089408)
		(layer "In2.Cu")
		(net "FM_UV_ADR_TRIGGER_EN")
	)
	(segment
		(start 396.113 -75.883008)
		(end 393.55268 -78.443328)
		(width 0.089408)
		(layer "In2.Cu")
		(net "FM_UV_ADR_TRIGGER_EN")
	)
	(segment
		(start 398.53743 -98.62947)
		(end 397.844264 -99.322636)
		(width 0.089408)
		(layer "In2.Cu")
		(net "FM_UV_ADR_TRIGGER_EN")
	)
	(segment
		(start 398.53743 -97.986596)
		(end 398.53743 -98.62947)
		(width 0.089408)
		(layer "In2.Cu")
		(net "FM_UV_ADR_TRIGGER_EN")
	)
	(segment
		(start 398.454626 -97.215452)
		(end 398.454626 -97.903792)
		(width 0.089408)
		(layer "In2.Cu")
		(net "FM_UV_ADR_TRIGGER_EN")
	)
	(segment
		(start 397.134588 -93.63329)
		(end 397.134842 -93.63329)
		(width 0.089408)
		(layer "In2.Cu")
		(net "FM_UV_ADR_TRIGGER_EN")
	)
	(segment
		(start 394.527024 -82.538824)
		(end 393.985496 -83.080352)
		(width 0.089408)
		(layer "In2.Cu")
		(net "FM_UV_ADR_TRIGGER_EN")
	)
	(segment
		(start 396.113 -73.7362)
		(end 396.113 -75.883008)
		(width 0.089408)
		(layer "In2.Cu")
		(net "FM_UV_ADR_TRIGGER_EN")
	)
	(segment
		(start 391.742168 -74.803)
		(end 390.3472 -74.803)
		(width 0.089408)
		(layer "In4.Cu")
		(net "FM_UV_ADR_TRIGGER_EN")
	)
	(segment
		(start 395.993366 -73.526904)
		(end 395.743938 -73.526904)
		(width 0.089408)
		(layer "In4.Cu")
		(net "FM_UV_ADR_TRIGGER_EN")
	)
	(segment
		(start 388.075932 -73.605644)
		(end 386.210556 -73.605644)
		(width 0.089408)
		(layer "In4.Cu")
		(net "FM_UV_ADR_TRIGGER_EN")
	)
	(segment
		(start 390.144254 -74.600054)
		(end 389.070342 -74.600054)
		(width 0.089408)
		(layer "In4.Cu")
		(net "FM_UV_ADR_TRIGGER_EN")
	)
	(segment
		(start 378.1806 -74.257154)
		(end 370.307108 -74.257154)
		(width 0.089408)
		(layer "In4.Cu")
		(net "FM_UV_ADR_TRIGGER_EN")
	)
	(segment
		(start 381.8636 -73.9394)
		(end 381.6477 -74.1553)
		(width 0.089408)
		(layer "In4.Cu")
		(net "FM_UV_ADR_TRIGGER_EN")
	)
	(segment
		(start 395.55293 -73.335896)
		(end 393.67079 -73.335896)
		(width 0.089408)
		(layer "In4.Cu")
		(net "FM_UV_ADR_TRIGGER_EN")
	)
	(segment
		(start 386.210556 -73.605644)
		(end 385.8768 -73.9394)
		(width 0.089408)
		(layer "In4.Cu")
		(net "FM_UV_ADR_TRIGGER_EN")
	)
	(segment
		(start 393.12723 -73.879456)
		(end 392.665712 -73.879456)
		(width 0.089408)
		(layer "In4.Cu")
		(net "FM_UV_ADR_TRIGGER_EN")
	)
	(segment
		(start 389.070342 -74.600054)
		(end 388.075932 -73.605644)
		(width 0.089408)
		(layer "In4.Cu")
		(net "FM_UV_ADR_TRIGGER_EN")
	)
	(segment
		(start 390.3472 -74.803)
		(end 390.144254 -74.600054)
		(width 0.089408)
		(layer "In4.Cu")
		(net "FM_UV_ADR_TRIGGER_EN")
	)
	(segment
		(start 381.6477 -74.1553)
		(end 378.282454 -74.1553)
		(width 0.089408)
		(layer "In4.Cu")
		(net "FM_UV_ADR_TRIGGER_EN")
	)
	(segment
		(start 370.307108 -74.257154)
		(end 369.545108 -73.495154)
		(width 0.089408)
		(layer "In4.Cu")
		(net "FM_UV_ADR_TRIGGER_EN")
	)
	(segment
		(start 395.743938 -73.526904)
		(end 395.55293 -73.335896)
		(width 0.089408)
		(layer "In4.Cu")
		(net "FM_UV_ADR_TRIGGER_EN")
	)
	(segment
		(start 396.113 -73.7362)
		(end 396.113 -73.646538)
		(width 0.089408)
		(layer "In4.Cu")
		(net "FM_UV_ADR_TRIGGER_EN")
	)
	(segment
		(start 378.282454 -74.1553)
		(end 378.1806 -74.257154)
		(width 0.089408)
		(layer "In4.Cu")
		(net "FM_UV_ADR_TRIGGER_EN")
	)
	(segment
		(start 396.113 -73.646538)
		(end 395.993366 -73.526904)
		(width 0.089408)
		(layer "In4.Cu")
		(net "FM_UV_ADR_TRIGGER_EN")
	)
	(segment
		(start 392.665712 -73.879456)
		(end 391.742168 -74.803)
		(width 0.089408)
		(layer "In4.Cu")
		(net "FM_UV_ADR_TRIGGER_EN")
	)
	(segment
		(start 385.8768 -73.9394)
		(end 381.8636 -73.9394)
		(width 0.089408)
		(layer "In4.Cu")
		(net "FM_UV_ADR_TRIGGER_EN")
	)
	(segment
		(start 393.67079 -73.335896)
		(end 393.12723 -73.879456)
		(width 0.089408)
		(layer "In4.Cu")
		(net "FM_UV_ADR_TRIGGER_EN")
	)
	(segment
		(start 396.113 -73.188576)
		(end 396.113 -73.7362)
		(width 0.089408)
		(layer "In9.Cu")
		(net "FM_UV_ADR_TRIGGER_EN")
	)
	(segment
		(start 396.589504 -71.24319)
		(end 396.589504 -72.712072)
		(width 0.089408)
		(layer "In9.Cu")
		(net "FM_UV_ADR_TRIGGER_EN")
	)
	(segment
		(start 400.807174 -61.512704)
		(end 399.42516 -62.894718)
		(width 0.089408)
		(layer "In9.Cu")
		(net "FM_UV_ADR_TRIGGER_EN")
	)
	(segment
		(start 401.630642 -44.046648)
		(end 401.630642 -45.06214)
		(width 0.089408)
		(layer "In9.Cu")
		(net "FM_UV_ADR_TRIGGER_EN")
	)
	(segment
		(start 399.159984 -47.532798)
		(end 399.159984 -54.952392)
		(width 0.089408)
		(layer "In9.Cu")
		(net "FM_UV_ADR_TRIGGER_EN")
	)
	(segment
		(start 400.807174 -61.354716)
		(end 400.807174 -61.512704)
		(width 0.089408)
		(layer "In9.Cu")
		(net "FM_UV_ADR_TRIGGER_EN")
	)
	(segment
		(start 401.630642 -45.06214)
		(end 399.159984 -47.532798)
		(width 0.089408)
		(layer "In9.Cu")
		(net "FM_UV_ADR_TRIGGER_EN")
	)
	(segment
		(start 402.423884 -43.253406)
		(end 401.630642 -44.046648)
		(width 0.089408)
		(layer "In9.Cu")
		(net "FM_UV_ADR_TRIGGER_EN")
	)
	(segment
		(start 407.171652 -39.143178)
		(end 403.213062 -39.143178)
		(width 0.089408)
		(layer "In9.Cu")
		(net "FM_UV_ADR_TRIGGER_EN")
	)
	(segment
		(start 399.159984 -57.12714)
		(end 400.80692 -58.774076)
		(width 0.089408)
		(layer "In9.Cu")
		(net "FM_UV_ADR_TRIGGER_EN")
	)
	(segment
		(start 397.213328 -67.888358)
		(end 397.213328 -67.950334)
		(width 0.089408)
		(layer "In9.Cu")
		(net "FM_UV_ADR_TRIGGER_EN")
	)
	(segment
		(start 398.85112 -65.952878)
		(end 398.850612 -65.953386)
		(width 0.089408)
		(layer "In9.Cu")
		(net "FM_UV_ADR_TRIGGER_EN")
	)
	(segment
		(start 397.213074 -68.584064)
		(end 397.213328 -68.584318)
		(width 0.089408)
		(layer "In9.Cu")
		(net "FM_UV_ADR_TRIGGER_EN")
	)
	(segment
		(start 399.42516 -64.225678)
		(end 398.850612 -64.800226)
		(width 0.089408)
		(layer "In9.Cu")
		(net "FM_UV_ADR_TRIGGER_EN")
	)
	(segment
		(start 399.15973 -57.012586)
		(end 399.159984 -57.01284)
		(width 0.089408)
		(layer "In9.Cu")
		(net "FM_UV_ADR_TRIGGER_EN")
	)
	(segment
		(start 398.850612 -65.953386)
		(end 398.850612 -66.251074)
		(width 0.089408)
		(layer "In9.Cu")
		(net "FM_UV_ADR_TRIGGER_EN")
	)
	(segment
		(start 397.213328 -70.619366)
		(end 396.589504 -71.24319)
		(width 0.089408)
		(layer "In9.Cu")
		(net "FM_UV_ADR_TRIGGER_EN")
	)
	(segment
		(start 400.80692 -58.774076)
		(end 400.80692 -61.354462)
		(width 0.089408)
		(layer "In9.Cu")
		(net "FM_UV_ADR_TRIGGER_EN")
	)
	(segment
		(start 402.423884 -39.932356)
		(end 402.423884 -43.253406)
		(width 0.089408)
		(layer "In9.Cu")
		(net "FM_UV_ADR_TRIGGER_EN")
	)
	(segment
		(start 398.850612 -65.636394)
		(end 398.850866 -65.636648)
		(width 0.089408)
		(layer "In9.Cu")
		(net "FM_UV_ADR_TRIGGER_EN")
	)
	(segment
		(start 398.850612 -66.251074)
		(end 397.213328 -67.888358)
		(width 0.089408)
		(layer "In9.Cu")
		(net "FM_UV_ADR_TRIGGER_EN")
	)
	(segment
		(start 398.850866 -65.636648)
		(end 398.850866 -65.794636)
		(width 0.089408)
		(layer "In9.Cu")
		(net "FM_UV_ADR_TRIGGER_EN")
	)
	(segment
		(start 398.85112 -65.79489)
		(end 398.85112 -65.952878)
		(width 0.089408)
		(layer "In9.Cu")
		(net "FM_UV_ADR_TRIGGER_EN")
	)
	(segment
		(start 407.380186 -38.934644)
		(end 407.171652 -39.143178)
		(width 0.089408)
		(layer "In9.Cu")
		(net "FM_UV_ADR_TRIGGER_EN")
	)
	(segment
		(start 397.213074 -67.950588)
		(end 397.213074 -68.584064)
		(width 0.089408)
		(layer "In9.Cu")
		(net "FM_UV_ADR_TRIGGER_EN")
	)
	(segment
		(start 399.42516 -62.894718)
		(end 399.42516 -64.225678)
		(width 0.089408)
		(layer "In9.Cu")
		(net "FM_UV_ADR_TRIGGER_EN")
	)
	(segment
		(start 397.213328 -67.950334)
		(end 397.213074 -67.950588)
		(width 0.089408)
		(layer "In9.Cu")
		(net "FM_UV_ADR_TRIGGER_EN")
	)
	(segment
		(start 408.290014 -38.934644)
		(end 407.380186 -38.934644)
		(width 0.089408)
		(layer "In9.Cu")
		(net "FM_UV_ADR_TRIGGER_EN")
	)
	(segment
		(start 398.850612 -64.800226)
		(end 398.850612 -65.636394)
		(width 0.089408)
		(layer "In9.Cu")
		(net "FM_UV_ADR_TRIGGER_EN")
	)
	(segment
		(start 399.159984 -57.01284)
		(end 399.159984 -57.12714)
		(width 0.089408)
		(layer "In9.Cu")
		(net "FM_UV_ADR_TRIGGER_EN")
	)
	(segment
		(start 397.213328 -68.584318)
		(end 397.213328 -70.619366)
		(width 0.089408)
		(layer "In9.Cu")
		(net "FM_UV_ADR_TRIGGER_EN")
	)
	(segment
		(start 403.213062 -39.143178)
		(end 402.423884 -39.932356)
		(width 0.089408)
		(layer "In9.Cu")
		(net "FM_UV_ADR_TRIGGER_EN")
	)
	(segment
		(start 396.589504 -72.712072)
		(end 396.113 -73.188576)
		(width 0.089408)
		(layer "In9.Cu")
		(net "FM_UV_ADR_TRIGGER_EN")
	)
	(segment
		(start 398.850866 -65.794636)
		(end 398.85112 -65.79489)
		(width 0.089408)
		(layer "In9.Cu")
		(net "FM_UV_ADR_TRIGGER_EN")
	)
	(segment
		(start 400.80692 -61.354462)
		(end 400.807174 -61.354716)
		(width 0.089408)
		(layer "In9.Cu")
		(net "FM_UV_ADR_TRIGGER_EN")
	)
	(segment
		(start 399.15973 -54.952646)
		(end 399.15973 -57.012586)
		(width 0.089408)
		(layer "In9.Cu")
		(net "FM_UV_ADR_TRIGGER_EN")
	)
	(segment
		(start 399.159984 -54.952392)
		(end 399.15973 -54.952646)
		(width 0.089408)
		(layer "In9.Cu")
		(net "FM_UV_ADR_TRIGGER_EN")
	)
	(segment
		(start 474.8784 -35.1028)
		(end 474.609414 -35.1028)
		(width 0.10795)
		(layer "F.Cu")
		(net "CLK_50M_CKMNG_BMC_1_R")
	)
	(segment
		(start 474.0021 -33.457134)
		(end 474.0021 -32.778446)
		(width 0.10795)
		(layer "F.Cu")
		(net "CLK_50M_CKMNG_BMC_1_R")
	)
	(segment
		(start 474.0021 -32.778446)
		(end 474.169486 -32.61106)
		(width 0.10795)
		(layer "F.Cu")
		(net "CLK_50M_CKMNG_BMC_1_R")
	)
	(segment
		(start 473.899992 -33.559242)
		(end 474.0021 -33.457134)
		(width 0.10795)
		(layer "F.Cu")
		(net "CLK_50M_CKMNG_BMC_1_R")
	)
	(segment
		(start 473.899992 -33.569656)
		(end 473.899992 -33.559242)
		(width 0.10795)
		(layer "F.Cu")
		(net "CLK_50M_CKMNG_BMC_1_R")
	)
	(segment
		(start 473.837 -33.632648)
		(end 473.899992 -33.569656)
		(width 0.10795)
		(layer "F.Cu")
		(net "CLK_50M_CKMNG_BMC_1_R")
	)
	(segment
		(start 474.98 -35.2044)
		(end 474.8784 -35.1028)
		(width 0.10795)
		(layer "F.Cu")
		(net "CLK_50M_CKMNG_BMC_1_R")
	)
	(segment
		(start 474.281754 -35.1028)
		(end 473.837 -34.658046)
		(width 0.10795)
		(layer "F.Cu")
		(net "CLK_50M_CKMNG_BMC_1_R")
	)
	(segment
		(start 474.609414 -35.1028)
		(end 474.281754 -35.1028)
		(width 0.10795)
		(layer "F.Cu")
		(net "CLK_50M_CKMNG_BMC_1_R")
	)
	(segment
		(start 474.169486 -32.61106)
		(end 474.7895 -32.61106)
		(width 0.10795)
		(layer "F.Cu")
		(net "CLK_50M_CKMNG_BMC_1_R")
	)
	(segment
		(start 474.98 -35.7505)
		(end 474.98 -35.2044)
		(width 0.10795)
		(layer "F.Cu")
		(net "CLK_50M_CKMNG_BMC_1_R")
	)
	(segment
		(start 473.837 -34.658046)
		(end 473.837 -33.632648)
		(width 0.10795)
		(layer "F.Cu")
		(net "CLK_50M_CKMNG_BMC_1_R")
	)
	(via
		(at 474.609414 -35.1028)
		(size 0.508)
		(drill 0.254)
		(layers "F.Cu" "B.Cu")
		(net "CLK_50M_CKMNG_BMC_1_R")
	)
	(segment
		(start 394.8176 -66.6242)
		(end 394.677392 -66.6242)
		(width 0.1016)
		(layer "F.Cu")
		(net "VR_P5V_STBY_SS")
	)
	(segment
		(start 393.8905 -66.386202)
		(end 393.8905 -66.691002)
		(width 0.1016)
		(layer "F.Cu")
		(net "VR_P5V_STBY_SS")
	)
	(segment
		(start 394.023342 -66.25336)
		(end 393.8905 -66.386202)
		(width 0.1016)
		(layer "F.Cu")
		(net "VR_P5V_STBY_SS")
	)
	(segment
		(start 394.306552 -66.25336)
		(end 394.023342 -66.25336)
		(width 0.1016)
		(layer "F.Cu")
		(net "VR_P5V_STBY_SS")
	)
	(segment
		(start 394.677392 -66.6242)
		(end 394.306552 -66.25336)
		(width 0.1016)
		(layer "F.Cu")
		(net "VR_P5V_STBY_SS")
	)
	(segment
		(start 470.87663 -36.54552)
		(end 471.338402 -37.007292)
		(width 0.254)
		(layer "F.Cu")
		(net "VR_P1V2_BMC_STBY_FB")
	)
	(segment
		(start 471.338402 -37.007292)
		(end 470.577926 -37.767768)
		(width 0.254)
		(layer "F.Cu")
		(net "VR_P1V2_BMC_STBY_FB")
	)
	(segment
		(start 471.338402 -37.007292)
		(end 472.100402 -37.007292)
		(width 0.254)
		(layer "F.Cu")
		(net "VR_P1V2_BMC_STBY_FB")
	)
	(segment
		(start 470.37244 -36.54552)
		(end 470.87663 -36.54552)
		(width 0.254)
		(layer "F.Cu")
		(net "VR_P1V2_BMC_STBY_FB")
	)
	(segment
		(start 472.100402 -37.007292)
		(end 472.227402 -36.880292)
		(width 0.254)
		(layer "F.Cu")
		(net "VR_P1V2_BMC_STBY_FB")
	)
	(segment
		(start 470.577926 -37.767768)
		(end 470.577926 -38.188392)
		(width 0.254)
		(layer "F.Cu")
		(net "VR_P1V2_BMC_STBY_FB")
	)
	(via
		(at 470.37244 -36.54552)
		(size 0.762)
		(drill 0.381)
		(layers "F.Cu" "B.Cu")
		(net "VR_P1V2_BMC_STBY_FB")
	)
	(segment
		(start 391.715498 -63.046102)
		(end 392.2268 -62.5348)
		(width 0.254)
		(layer "F.Cu")
		(net "VR_P5V_STBY_VSENSE_R")
	)
	(segment
		(start 390.398 -63.6905)
		(end 390.398 -63.300102)
		(width 0.254)
		(layer "F.Cu")
		(net "VR_P5V_STBY_VSENSE_R")
	)
	(segment
		(start 390.652 -63.046102)
		(end 391.715498 -63.046102)
		(width 0.254)
		(layer "F.Cu")
		(net "VR_P5V_STBY_VSENSE_R")
	)
	(segment
		(start 392.2268 -61.9506)
		(end 393.059666 -61.117734)
		(width 0.254)
		(layer "F.Cu")
		(net "VR_P5V_STBY_VSENSE_R")
	)
	(segment
		(start 393.059666 -61.117734)
		(end 393.5984 -61.117734)
		(width 0.254)
		(layer "F.Cu")
		(net "VR_P5V_STBY_VSENSE_R")
	)
	(segment
		(start 393.916408 -61.435742)
		(end 393.916408 -61.773308)
		(width 0.254)
		(layer "F.Cu")
		(net "VR_P5V_STBY_VSENSE_R")
	)
	(segment
		(start 392.2268 -62.5348)
		(end 392.2268 -61.9506)
		(width 0.254)
		(layer "F.Cu")
		(net "VR_P5V_STBY_VSENSE_R")
	)
	(segment
		(start 393.5984 -61.117734)
		(end 393.916408 -61.435742)
		(width 0.254)
		(layer "F.Cu")
		(net "VR_P5V_STBY_VSENSE_R")
	)
	(segment
		(start 390.398 -63.300102)
		(end 390.652 -63.046102)
		(width 0.254)
		(layer "F.Cu")
		(net "VR_P5V_STBY_VSENSE_R")
	)
	(via
		(at 392.2268 -62.5348)
		(size 0.762)
		(drill 0.381)
		(layers "F.Cu" "B.Cu")
		(net "VR_P5V_STBY_VSENSE_R")
	)
	(segment
		(start 393.674346 -64.959738)
		(end 393.674346 -64.172338)
		(width 0.254)
		(layer "F.Cu")
		(net "VR_P5V_STBY_RC_COMP")
	)
	(segment
		(start 364.073948 -69.814948)
		(end 363.496606 -69.237606)
		(width 0.10795)
		(layer "F.Cu")
		(net "FM_P12V_MAIN_SW_EN")
	)
	(segment
		(start 365.625888 -79.494888)
		(end 366.745012 -79.494888)
		(width 0.10795)
		(layer "F.Cu")
		(net "FM_P12V_MAIN_SW_EN")
	)
	(segment
		(start 376.09145 -61.33592)
		(end 377.422918 -60.004452)
		(width 0.10795)
		(layer "F.Cu")
		(net "FM_P12V_MAIN_SW_EN")
	)
	(segment
		(start 366.2045 -60.1472)
		(end 366.7379 -60.1472)
		(width 0.10795)
		(layer "F.Cu")
		(net "FM_P12V_MAIN_SW_EN")
	)
	(segment
		(start 364.49 -75.4888)
		(end 364.49 -78.359)
		(width 0.10795)
		(layer "F.Cu")
		(net "FM_P12V_MAIN_SW_EN")
	)
	(segment
		(start 496.678204 -26.05532)
		(end 496.086384 -26.05532)
		(width 0.10795)
		(layer "F.Cu")
		(net "FM_P12V_MAIN_SW_EN")
	)
	(segment
		(start 377.422918 -60.004452)
		(end 381.642366 -60.004452)
		(width 0.10795)
		(layer "F.Cu")
		(net "FM_P12V_MAIN_SW_EN")
	)
	(segment
		(start 369.167918 -62.222126)
		(end 370.400326 -60.989718)
		(width 0.10795)
		(layer "F.Cu")
		(net "FM_P12V_MAIN_SW_EN")
	)
	(segment
		(start 368.812826 -62.222126)
		(end 369.167918 -62.222126)
		(width 0.10795)
		(layer "F.Cu")
		(net "FM_P12V_MAIN_SW_EN")
	)
	(segment
		(start 363.496606 -69.237606)
		(end 362.121704 -69.237606)
		(width 0.10795)
		(layer "F.Cu")
		(net "FM_P12V_MAIN_SW_EN")
	)
	(segment
		(start 496.086384 -26.05532)
		(end 495.992404 -26.1493)
		(width 0.10795)
		(layer "F.Cu")
		(net "FM_P12V_MAIN_SW_EN")
	)
	(segment
		(start 382.746504 -58.900314)
		(end 389.866632 -58.900314)
		(width 0.10795)
		(layer "F.Cu")
		(net "FM_P12V_MAIN_SW_EN")
	)
	(segment
		(start 366.7379 -60.1472)
		(end 368.812826 -62.222126)
		(width 0.10795)
		(layer "F.Cu")
		(net "FM_P12V_MAIN_SW_EN")
	)
	(segment
		(start 362.121704 -69.237606)
		(end 361.94873 -69.41058)
		(width 0.10795)
		(layer "F.Cu")
		(net "FM_P12V_MAIN_SW_EN")
	)
	(segment
		(start 381.642366 -60.004452)
		(end 382.746504 -58.900314)
		(width 0.10795)
		(layer "F.Cu")
		(net "FM_P12V_MAIN_SW_EN")
	)
	(segment
		(start 391.623296 -57.14365)
		(end 397.57731 -57.14365)
		(width 0.10795)
		(layer "F.Cu")
		(net "FM_P12V_MAIN_SW_EN")
	)
	(segment
		(start 374.673622 -60.989718)
		(end 375.019824 -61.33592)
		(width 0.10795)
		(layer "F.Cu")
		(net "FM_P12V_MAIN_SW_EN")
	)
	(segment
		(start 397.57731 -57.14365)
		(end 399.93824 -59.50458)
		(width 0.10795)
		(layer "F.Cu")
		(net "FM_P12V_MAIN_SW_EN")
	)
	(segment
		(start 361.94873 -69.41058)
		(end 361.94873 -72.94753)
		(width 0.10795)
		(layer "F.Cu")
		(net "FM_P12V_MAIN_SW_EN")
	)
	(segment
		(start 389.866632 -58.900314)
		(end 391.623296 -57.14365)
		(width 0.10795)
		(layer "F.Cu")
		(net "FM_P12V_MAIN_SW_EN")
	)
	(segment
		(start 370.400326 -60.989718)
		(end 374.673622 -60.989718)
		(width 0.10795)
		(layer "F.Cu")
		(net "FM_P12V_MAIN_SW_EN")
	)
	(segment
		(start 361.94873 -72.94753)
		(end 364.49 -75.4888)
		(width 0.10795)
		(layer "F.Cu")
		(net "FM_P12V_MAIN_SW_EN")
	)
	(segment
		(start 364.49 -78.359)
		(end 365.625888 -79.494888)
		(width 0.10795)
		(layer "F.Cu")
		(net "FM_P12V_MAIN_SW_EN")
	)
	(segment
		(start 364.073948 -70.673976)
		(end 364.073948 -69.814948)
		(width 0.10795)
		(layer "F.Cu")
		(net "FM_P12V_MAIN_SW_EN")
	)
	(segment
		(start 375.019824 -61.33592)
		(end 376.09145 -61.33592)
		(width 0.10795)
		(layer "F.Cu")
		(net "FM_P12V_MAIN_SW_EN")
	)
	(segment
		(start 399.93824 -59.50458)
		(end 399.93824 -60.36564)
		(width 0.10795)
		(layer "F.Cu")
		(net "FM_P12V_MAIN_SW_EN")
	)
	(via
		(at 366.2045 -60.1472)
		(size 0.508)
		(drill 0.254)
		(layers "F.Cu" "B.Cu")
		(net "FM_P12V_MAIN_SW_EN")
	)
	(via
		(at 401.2184 -59.7154)
		(size 0.6604)
		(drill 0.3302)
		(layers "F.Cu" "B.Cu")
		(net "FM_P12V_MAIN_SW_EN")
	)
	(via
		(at 465.862162 -44.709334)
		(size 0.508)
		(drill 0.254)
		(layers "F.Cu" "B.Cu")
		(net "FM_P12V_MAIN_SW_EN")
	)
	(via
		(at 364.073948 -70.673976)
		(size 0.508)
		(drill 0.254)
		(layers "F.Cu" "B.Cu")
		(net "FM_P12V_MAIN_SW_EN")
	)
	(via
		(at 495.992404 -26.1493)
		(size 0.508)
		(drill 0.254)
		(layers "F.Cu" "B.Cu")
		(net "FM_P12V_MAIN_SW_EN")
	)
	(via
		(at 399.93824 -60.36564)
		(size 0.508)
		(drill 0.254)
		(layers "F.Cu" "B.Cu")
		(net "FM_P12V_MAIN_SW_EN")
	)
	(segment
		(start 420.753794 -53.358796)
		(end 420.313612 -53.358796)
		(width 0.10795)
		(layer "B.Cu")
		(net "FM_P12V_MAIN_SW_EN")
	)
	(segment
		(start 411.2514 -58.8518)
		(end 405.41321 -58.8518)
		(width 0.10795)
		(layer "B.Cu")
		(net "FM_P12V_MAIN_SW_EN")
	)
	(segment
		(start 435.468522 -47.885604)
		(end 435.315106 -47.885604)
		(width 0.10795)
		(layer "B.Cu")
		(net "FM_P12V_MAIN_SW_EN")
	)
	(segment
		(start 403.283928 -58.8518)
		(end 402.5646 -58.8518)
		(width 0.10795)
		(layer "B.Cu")
		(net "FM_P12V_MAIN_SW_EN")
	)
	(segment
		(start 402.5646 -58.8518)
		(end 401.701 -59.7154)
		(width 0.10795)
		(layer "B.Cu")
		(net "FM_P12V_MAIN_SW_EN")
	)
	(segment
		(start 416.8775 -56.1975)
		(end 415.1884 -57.8866)
		(width 0.10795)
		(layer "B.Cu")
		(net "FM_P12V_MAIN_SW_EN")
	)
	(segment
		(start 399.93824 -60.36564)
		(end 400.58848 -59.7154)
		(width 0.10795)
		(layer "B.Cu")
		(net "FM_P12V_MAIN_SW_EN")
	)
	(segment
		(start 428.096172 -51.31689)
		(end 427.967648 -51.445414)
		(width 0.10795)
		(layer "B.Cu")
		(net "FM_P12V_MAIN_SW_EN")
	)
	(segment
		(start 427.967648 -51.445414)
		(end 427.228 -51.445414)
		(width 0.10795)
		(layer "B.Cu")
		(net "FM_P12V_MAIN_SW_EN")
	)
	(segment
		(start 463.352896 -47.2186)
		(end 436.135526 -47.2186)
		(width 0.10795)
		(layer "B.Cu")
		(net "FM_P12V_MAIN_SW_EN")
	)
	(segment
		(start 434.348128 -48.467518)
		(end 431.498756 -51.31689)
		(width 0.10795)
		(layer "B.Cu")
		(net "FM_P12V_MAIN_SW_EN")
	)
	(segment
		(start 420.313612 -53.358796)
		(end 417.474908 -56.1975)
		(width 0.10795)
		(layer "B.Cu")
		(net "FM_P12V_MAIN_SW_EN")
	)
	(segment
		(start 424.047412 -51.964082)
		(end 423.609262 -52.402232)
		(width 0.10795)
		(layer "B.Cu")
		(net "FM_P12V_MAIN_SW_EN")
	)
	(segment
		(start 405.404066 -58.842656)
		(end 403.293072 -58.842656)
		(width 0.10795)
		(layer "B.Cu")
		(net "FM_P12V_MAIN_SW_EN")
	)
	(segment
		(start 415.1884 -57.8866)
		(end 412.2166 -57.8866)
		(width 0.10795)
		(layer "B.Cu")
		(net "FM_P12V_MAIN_SW_EN")
	)
	(segment
		(start 431.498756 -51.31689)
		(end 428.096172 -51.31689)
		(width 0.10795)
		(layer "B.Cu")
		(net "FM_P12V_MAIN_SW_EN")
	)
	(segment
		(start 421.18026 -52.923948)
		(end 421.18026 -52.93233)
		(width 0.10795)
		(layer "B.Cu")
		(net "FM_P12V_MAIN_SW_EN")
	)
	(segment
		(start 436.135526 -47.2186)
		(end 435.468522 -47.885604)
		(width 0.10795)
		(layer "B.Cu")
		(net "FM_P12V_MAIN_SW_EN")
	)
	(segment
		(start 403.293072 -58.842656)
		(end 403.283928 -58.8518)
		(width 0.10795)
		(layer "B.Cu")
		(net "FM_P12V_MAIN_SW_EN")
	)
	(segment
		(start 426.162216 -51.31689)
		(end 425.51477 -51.964336)
		(width 0.10795)
		(layer "B.Cu")
		(net "FM_P12V_MAIN_SW_EN")
	)
	(segment
		(start 423.609262 -52.402232)
		(end 421.701976 -52.402232)
		(width 0.10795)
		(layer "B.Cu")
		(net "FM_P12V_MAIN_SW_EN")
	)
	(segment
		(start 405.41321 -58.8518)
		(end 405.404066 -58.842656)
		(width 0.10795)
		(layer "B.Cu")
		(net "FM_P12V_MAIN_SW_EN")
	)
	(segment
		(start 435.315106 -47.885604)
		(end 434.733192 -48.467518)
		(width 0.10795)
		(layer "B.Cu")
		(net "FM_P12V_MAIN_SW_EN")
	)
	(segment
		(start 434.733192 -48.467518)
		(end 434.348128 -48.467518)
		(width 0.10795)
		(layer "B.Cu")
		(net "FM_P12V_MAIN_SW_EN")
	)
	(segment
		(start 427.228 -51.445414)
		(end 427.099476 -51.31689)
		(width 0.10795)
		(layer "B.Cu")
		(net "FM_P12V_MAIN_SW_EN")
	)
	(segment
		(start 417.474908 -56.1975)
		(end 416.8775 -56.1975)
		(width 0.10795)
		(layer "B.Cu")
		(net "FM_P12V_MAIN_SW_EN")
	)
	(segment
		(start 412.2166 -57.8866)
		(end 411.2514 -58.8518)
		(width 0.10795)
		(layer "B.Cu")
		(net "FM_P12V_MAIN_SW_EN")
	)
	(segment
		(start 401.701 -59.7154)
		(end 401.2184 -59.7154)
		(width 0.10795)
		(layer "B.Cu")
		(net "FM_P12V_MAIN_SW_EN")
	)
	(segment
		(start 427.099476 -51.31689)
		(end 426.162216 -51.31689)
		(width 0.10795)
		(layer "B.Cu")
		(net "FM_P12V_MAIN_SW_EN")
	)
	(segment
		(start 400.58848 -59.7154)
		(end 401.2184 -59.7154)
		(width 0.10795)
		(layer "B.Cu")
		(net "FM_P12V_MAIN_SW_EN")
	)
	(segment
		(start 465.862162 -44.709334)
		(end 463.352896 -47.2186)
		(width 0.10795)
		(layer "B.Cu")
		(net "FM_P12V_MAIN_SW_EN")
	)
	(segment
		(start 425.51477 -51.964336)
		(end 425.157138 -51.964336)
		(width 0.10795)
		(layer "B.Cu")
		(net "FM_P12V_MAIN_SW_EN")
	)
	(segment
		(start 425.156884 -51.964082)
		(end 424.047412 -51.964082)
		(width 0.10795)
		(layer "B.Cu")
		(net "FM_P12V_MAIN_SW_EN")
	)
	(segment
		(start 421.701976 -52.402232)
		(end 421.18026 -52.923948)
		(width 0.10795)
		(layer "B.Cu")
		(net "FM_P12V_MAIN_SW_EN")
	)
	(segment
		(start 425.157138 -51.964336)
		(end 425.156884 -51.964082)
		(width 0.10795)
		(layer "B.Cu")
		(net "FM_P12V_MAIN_SW_EN")
	)
	(segment
		(start 421.18026 -52.93233)
		(end 420.753794 -53.358796)
		(width 0.10795)
		(layer "B.Cu")
		(net "FM_P12V_MAIN_SW_EN")
	)
	(segment
		(start 470.141808 -44.7294)
		(end 470.161874 -44.709334)
		(width 0.089408)
		(layer "In2.Cu")
		(net "FM_P12V_MAIN_SW_EN")
	)
	(segment
		(start 476.3516 -45.339)
		(end 478.910904 -42.779696)
		(width 0.089408)
		(layer "In2.Cu")
		(net "FM_P12V_MAIN_SW_EN")
	)
	(segment
		(start 492.747808 -32.001206)
		(end 492.747808 -28.917392)
		(width 0.089408)
		(layer "In2.Cu")
		(net "FM_P12V_MAIN_SW_EN")
	)
	(segment
		(start 470.161874 -44.709334)
		(end 470.210642 -44.709334)
		(width 0.089408)
		(layer "In2.Cu")
		(net "FM_P12V_MAIN_SW_EN")
	)
	(segment
		(start 465.862162 -44.709334)
		(end 465.882228 -44.7294)
		(width 0.089408)
		(layer "In2.Cu")
		(net "FM_P12V_MAIN_SW_EN")
	)
	(segment
		(start 495.992404 -26.516584)
		(end 495.992404 -26.1493)
		(width 0.089408)
		(layer "In2.Cu")
		(net "FM_P12V_MAIN_SW_EN")
	)
	(segment
		(start 474.091 -45.339)
		(end 476.3516 -45.339)
		(width 0.089408)
		(layer "In2.Cu")
		(net "FM_P12V_MAIN_SW_EN")
	)
	(segment
		(start 494.242852 -37.193982)
		(end 494.40084 -37.193982)
		(width 0.089408)
		(layer "In2.Cu")
		(net "FM_P12V_MAIN_SW_EN")
	)
	(segment
		(start 492.778288 -45.904912)
		(end 493.3442 -45.339)
		(width 0.089408)
		(layer "In2.Cu")
		(net "FM_P12V_MAIN_SW_EN")
	)
	(segment
		(start 495.36223 -34.615628)
		(end 492.747808 -32.001206)
		(width 0.089408)
		(layer "In2.Cu")
		(net "FM_P12V_MAIN_SW_EN")
	)
	(segment
		(start 495.36223 -35.414204)
		(end 495.36223 -34.615628)
		(width 0.089408)
		(layer "In2.Cu")
		(net "FM_P12V_MAIN_SW_EN")
	)
	(segment
		(start 478.910904 -42.779696)
		(end 479.405696 -42.779696)
		(width 0.089408)
		(layer "In2.Cu")
		(net "FM_P12V_MAIN_SW_EN")
	)
	(segment
		(start 465.882228 -44.7294)
		(end 470.141808 -44.7294)
		(width 0.089408)
		(layer "In2.Cu")
		(net "FM_P12V_MAIN_SW_EN")
	)
	(segment
		(start 472.590368 -44.366688)
		(end 473.118688 -44.366688)
		(width 0.089408)
		(layer "In2.Cu")
		(net "FM_P12V_MAIN_SW_EN")
	)
	(segment
		(start 479.99904 -43.37304)
		(end 485.808528 -43.37304)
		(width 0.089408)
		(layer "In2.Cu")
		(net "FM_P12V_MAIN_SW_EN")
	)
	(segment
		(start 494.242598 -37.193728)
		(end 494.242852 -37.193982)
		(width 0.089408)
		(layer "In2.Cu")
		(net "FM_P12V_MAIN_SW_EN")
	)
	(segment
		(start 493.6236 -44.196)
		(end 493.6236 -39.063422)
		(width 0.089408)
		(layer "In2.Cu")
		(net "FM_P12V_MAIN_SW_EN")
	)
	(segment
		(start 493.6236 -39.063422)
		(end 493.337088 -38.77691)
		(width 0.089408)
		(layer "In2.Cu")
		(net "FM_P12V_MAIN_SW_EN")
	)
	(segment
		(start 493.337088 -37.920168)
		(end 494.063528 -37.193728)
		(width 0.089408)
		(layer "In2.Cu")
		(net "FM_P12V_MAIN_SW_EN")
	)
	(segment
		(start 494.447576 -37.193728)
		(end 495.136932 -36.504372)
		(width 0.089408)
		(layer "In2.Cu")
		(net "FM_P12V_MAIN_SW_EN")
	)
	(segment
		(start 492.747808 -28.917392)
		(end 494.307114 -27.358086)
		(width 0.089408)
		(layer "In2.Cu")
		(net "FM_P12V_MAIN_SW_EN")
	)
	(segment
		(start 473.118688 -44.366688)
		(end 474.091 -45.339)
		(width 0.089408)
		(layer "In2.Cu")
		(net "FM_P12V_MAIN_SW_EN")
	)
	(segment
		(start 494.063528 -37.193728)
		(end 494.242598 -37.193728)
		(width 0.089408)
		(layer "In2.Cu")
		(net "FM_P12V_MAIN_SW_EN")
	)
	(segment
		(start 493.3442 -45.339)
		(end 493.3442 -44.4754)
		(width 0.089408)
		(layer "In2.Cu")
		(net "FM_P12V_MAIN_SW_EN")
	)
	(segment
		(start 495.136932 -36.504372)
		(end 495.136932 -35.639502)
		(width 0.089408)
		(layer "In2.Cu")
		(net "FM_P12V_MAIN_SW_EN")
	)
	(segment
		(start 493.337088 -38.77691)
		(end 493.337088 -37.920168)
		(width 0.089408)
		(layer "In2.Cu")
		(net "FM_P12V_MAIN_SW_EN")
	)
	(segment
		(start 495.150902 -27.358086)
		(end 495.992404 -26.516584)
		(width 0.089408)
		(layer "In2.Cu")
		(net "FM_P12V_MAIN_SW_EN")
	)
	(segment
		(start 493.3442 -44.4754)
		(end 493.6236 -44.196)
		(width 0.089408)
		(layer "In2.Cu")
		(net "FM_P12V_MAIN_SW_EN")
	)
	(segment
		(start 488.3404 -45.904912)
		(end 492.778288 -45.904912)
		(width 0.089408)
		(layer "In2.Cu")
		(net "FM_P12V_MAIN_SW_EN")
	)
	(segment
		(start 494.40084 -37.193982)
		(end 494.401094 -37.193728)
		(width 0.089408)
		(layer "In2.Cu")
		(net "FM_P12V_MAIN_SW_EN")
	)
	(segment
		(start 470.876376 -44.0436)
		(end 472.26728 -44.0436)
		(width 0.089408)
		(layer "In2.Cu")
		(net "FM_P12V_MAIN_SW_EN")
	)
	(segment
		(start 472.26728 -44.0436)
		(end 472.590368 -44.366688)
		(width 0.089408)
		(layer "In2.Cu")
		(net "FM_P12V_MAIN_SW_EN")
	)
	(segment
		(start 494.401094 -37.193728)
		(end 494.447576 -37.193728)
		(width 0.089408)
		(layer "In2.Cu")
		(net "FM_P12V_MAIN_SW_EN")
	)
	(segment
		(start 479.405696 -42.779696)
		(end 479.99904 -43.37304)
		(width 0.089408)
		(layer "In2.Cu")
		(net "FM_P12V_MAIN_SW_EN")
	)
	(segment
		(start 485.808528 -43.37304)
		(end 488.3404 -45.904912)
		(width 0.089408)
		(layer "In2.Cu")
		(net "FM_P12V_MAIN_SW_EN")
	)
	(segment
		(start 494.307114 -27.358086)
		(end 495.150902 -27.358086)
		(width 0.089408)
		(layer "In2.Cu")
		(net "FM_P12V_MAIN_SW_EN")
	)
	(segment
		(start 470.210642 -44.709334)
		(end 470.876376 -44.0436)
		(width 0.089408)
		(layer "In2.Cu")
		(net "FM_P12V_MAIN_SW_EN")
	)
	(segment
		(start 495.136932 -35.639502)
		(end 495.36223 -35.414204)
		(width 0.089408)
		(layer "In2.Cu")
		(net "FM_P12V_MAIN_SW_EN")
	)
	(segment
		(start 368.510312 -65.192656)
		(end 368.510312 -65.947544)
		(width 0.089408)
		(layer "In11.Cu")
		(net "FM_P12V_MAIN_SW_EN")
	)
	(segment
		(start 367.695988 -64.655192)
		(end 367.972848 -64.655192)
		(width 0.089408)
		(layer "In11.Cu")
		(net "FM_P12V_MAIN_SW_EN")
	)
	(segment
		(start 366.2045 -60.1472)
		(end 367.6142 -61.5569)
		(width 0.089408)
		(layer "In11.Cu")
		(net "FM_P12V_MAIN_SW_EN")
	)
	(segment
		(start 367.6142 -61.5569)
		(end 367.6142 -62.85738)
		(width 0.089408)
		(layer "In11.Cu")
		(net "FM_P12V_MAIN_SW_EN")
	)
	(segment
		(start 367.09604 -63.37554)
		(end 367.09604 -64.055244)
		(width 0.089408)
		(layer "In11.Cu")
		(net "FM_P12V_MAIN_SW_EN")
	)
	(segment
		(start 367.376456 -67.0814)
		(end 366.30229 -67.0814)
		(width 0.089408)
		(layer "In11.Cu")
		(net "FM_P12V_MAIN_SW_EN")
	)
	(segment
		(start 366.30229 -67.0814)
		(end 364.073948 -69.309742)
		(width 0.089408)
		(layer "In11.Cu")
		(net "FM_P12V_MAIN_SW_EN")
	)
	(segment
		(start 368.510312 -65.947544)
		(end 367.376456 -67.0814)
		(width 0.089408)
		(layer "In11.Cu")
		(net "FM_P12V_MAIN_SW_EN")
	)
	(segment
		(start 367.972848 -64.655192)
		(end 368.510312 -65.192656)
		(width 0.089408)
		(layer "In11.Cu")
		(net "FM_P12V_MAIN_SW_EN")
	)
	(segment
		(start 367.09604 -64.055244)
		(end 367.695988 -64.655192)
		(width 0.089408)
		(layer "In11.Cu")
		(net "FM_P12V_MAIN_SW_EN")
	)
	(segment
		(start 367.6142 -62.85738)
		(end 367.09604 -63.37554)
		(width 0.089408)
		(layer "In11.Cu")
		(net "FM_P12V_MAIN_SW_EN")
	)
	(segment
		(start 364.073948 -69.309742)
		(end 364.073948 -70.673976)
		(width 0.089408)
		(layer "In11.Cu")
		(net "FM_P12V_MAIN_SW_EN")
	)
	(segment
		(start 489.445808 -40.37838)
		(end 489.445808 -39.636446)
		(width 0.10795)
		(layer "F.Cu")
		(net "CLK_50M_CKMNG_SPRVLLE")
	)
	(segment
		(start 477.036384 -37.985192)
		(end 477.139 -37.882576)
		(width 0.10795)
		(layer "F.Cu")
		(net "CLK_50M_CKMNG_SPRVLLE")
	)
	(segment
		(start 488.6198 -40.71747)
		(end 489.106718 -40.71747)
		(width 0.10795)
		(layer "F.Cu")
		(net "CLK_50M_CKMNG_SPRVLLE")
	)
	(segment
		(start 477.139 -37.882576)
		(end 477.139 -37.5285)
		(width 0.10795)
		(layer "F.Cu")
		(net "CLK_50M_CKMNG_SPRVLLE")
	)
	(segment
		(start 477.036384 -38.822122)
		(end 477.036384 -37.985192)
		(width 0.10795)
		(layer "F.Cu")
		(net "CLK_50M_CKMNG_SPRVLLE")
	)
	(segment
		(start 489.106718 -40.71747)
		(end 489.445808 -40.37838)
		(width 0.10795)
		(layer "F.Cu")
		(net "CLK_50M_CKMNG_SPRVLLE")
	)
	(via
		(at 489.445808 -39.636446)
		(size 0.508)
		(drill 0.254)
		(layers "F.Cu" "B.Cu")
		(net "CLK_50M_CKMNG_SPRVLLE")
	)
	(via
		(at 477.036384 -38.822122)
		(size 0.508)
		(drill 0.254)
		(layers "F.Cu" "B.Cu")
		(net "CLK_50M_CKMNG_SPRVLLE")
	)
	(via
		(at 488.1626 -40.1574)
		(size 0.6604)
		(drill 0.3302)
		(layers "F.Cu" "B.Cu")
		(net "CLK_50M_CKMNG_SPRVLLE")
	)
	(segment
		(start 488.3531 -40.3479)
		(end 488.3531 -41.4274)
		(width 0.10795)
		(layer "B.Cu")
		(net "CLK_50M_CKMNG_SPRVLLE")
	)
	(segment
		(start 488.1626 -40.1574)
		(end 488.3531 -40.3479)
		(width 0.10795)
		(layer "B.Cu")
		(net "CLK_50M_CKMNG_SPRVLLE")
	)
	(segment
		(start 489.445808 -39.636446)
		(end 488.924854 -40.1574)
		(width 0.10795)
		(layer "B.Cu")
		(net "CLK_50M_CKMNG_SPRVLLE")
	)
	(segment
		(start 488.924854 -40.1574)
		(end 488.1626 -40.1574)
		(width 0.10795)
		(layer "B.Cu")
		(net "CLK_50M_CKMNG_SPRVLLE")
	)
	(segment
		(start 488.622848 -40.819832)
		(end 488.53344 -40.730424)
		(width 0.089408)
		(layer "In2.Cu")
		(net "CLK_50M_CKMNG_SPRVLLE")
	)
	(segment
		(start 480.980496 -40.260016)
		(end 488.69727 -40.260016)
		(width 0.089408)
		(layer "In2.Cu")
		(net "CLK_50M_CKMNG_SPRVLLE")
	)
	(segment
		(start 480.20732 -39.3192)
		(end 489.128562 -39.3192)
		(width 0.089408)
		(layer "In2.Cu")
		(net "CLK_50M_CKMNG_SPRVLLE")
	)
	(segment
		(start 480.891088 -40.349424)
		(end 480.980496 -40.260016)
		(width 0.089408)
		(layer "In2.Cu")
		(net "CLK_50M_CKMNG_SPRVLLE")
	)
	(segment
		(start 479.603308 -38.202108)
		(end 479.603308 -40.126412)
		(width 0.089408)
		(layer "In2.Cu")
		(net "CLK_50M_CKMNG_SPRVLLE")
	)
	(segment
		(start 480.980496 -40.730424)
		(end 480.891088 -40.641016)
		(width 0.089408)
		(layer "In2.Cu")
		(net "CLK_50M_CKMNG_SPRVLLE")
	)
	(segment
		(start 479.434144 -38.032944)
		(end 479.603308 -38.202108)
		(width 0.089408)
		(layer "In2.Cu")
		(net "CLK_50M_CKMNG_SPRVLLE")
	)
	(segment
		(start 479.603308 -40.126412)
		(end 480.677728 -41.200832)
		(width 0.089408)
		(layer "In2.Cu")
		(net "CLK_50M_CKMNG_SPRVLLE")
	)
	(segment
		(start 488.53344 -40.730424)
		(end 480.980496 -40.730424)
		(width 0.089408)
		(layer "In2.Cu")
		(net "CLK_50M_CKMNG_SPRVLLE")
	)
	(segment
		(start 480.117912 -39.688008)
		(end 480.117912 -39.408608)
		(width 0.089408)
		(layer "In2.Cu")
		(net "CLK_50M_CKMNG_SPRVLLE")
	)
	(segment
		(start 480.677728 -41.200832)
		(end 488.528614 -41.200832)
		(width 0.089408)
		(layer "In2.Cu")
		(net "CLK_50M_CKMNG_SPRVLLE")
	)
	(segment
		(start 488.707176 -39.789608)
		(end 480.219512 -39.789608)
		(width 0.089408)
		(layer "In2.Cu")
		(net "CLK_50M_CKMNG_SPRVLLE")
	)
	(segment
		(start 480.891088 -40.641016)
		(end 480.891088 -40.349424)
		(width 0.089408)
		(layer "In2.Cu")
		(net "CLK_50M_CKMNG_SPRVLLE")
	)
	(segment
		(start 477.036384 -38.822122)
		(end 477.014286 -38.800024)
		(width 0.089408)
		(layer "In2.Cu")
		(net "CLK_50M_CKMNG_SPRVLLE")
	)
	(segment
		(start 480.117912 -39.408608)
		(end 480.20732 -39.3192)
		(width 0.089408)
		(layer "In2.Cu")
		(net "CLK_50M_CKMNG_SPRVLLE")
	)
	(segment
		(start 488.796584 -39.879016)
		(end 488.707176 -39.789608)
		(width 0.089408)
		(layer "In2.Cu")
		(net "CLK_50M_CKMNG_SPRVLLE")
	)
	(segment
		(start 488.796584 -40.160702)
		(end 488.796584 -39.879016)
		(width 0.089408)
		(layer "In2.Cu")
		(net "CLK_50M_CKMNG_SPRVLLE")
	)
	(segment
		(start 488.69727 -40.260016)
		(end 488.796584 -40.160702)
		(width 0.089408)
		(layer "In2.Cu")
		(net "CLK_50M_CKMNG_SPRVLLE")
	)
	(segment
		(start 488.622848 -41.106598)
		(end 488.622848 -40.819832)
		(width 0.089408)
		(layer "In2.Cu")
		(net "CLK_50M_CKMNG_SPRVLLE")
	)
	(segment
		(start 477.222058 -38.032944)
		(end 479.434144 -38.032944)
		(width 0.089408)
		(layer "In2.Cu")
		(net "CLK_50M_CKMNG_SPRVLLE")
	)
	(segment
		(start 489.128562 -39.3192)
		(end 489.445808 -39.636446)
		(width 0.089408)
		(layer "In2.Cu")
		(net "CLK_50M_CKMNG_SPRVLLE")
	)
	(segment
		(start 477.014286 -38.800024)
		(end 477.014286 -38.240716)
		(width 0.089408)
		(layer "In2.Cu")
		(net "CLK_50M_CKMNG_SPRVLLE")
	)
	(segment
		(start 477.014286 -38.240716)
		(end 477.222058 -38.032944)
		(width 0.089408)
		(layer "In2.Cu")
		(net "CLK_50M_CKMNG_SPRVLLE")
	)
	(segment
		(start 480.219512 -39.789608)
		(end 480.117912 -39.688008)
		(width 0.089408)
		(layer "In2.Cu")
		(net "CLK_50M_CKMNG_SPRVLLE")
	)
	(segment
		(start 488.528614 -41.200832)
		(end 488.622848 -41.106598)
		(width 0.089408)
		(layer "In2.Cu")
		(net "CLK_50M_CKMNG_SPRVLLE")
	)
	(segment
		(start 476.601028 -117.20957)
		(end 476.600774 -117.209824)
		(width 0.10795)
		(layer "F.Cu")
		(net "CLK_50M_CKMNG_OCP")
	)
	(segment
		(start 474.4974 -38.0238)
		(end 474.091 -37.6174)
		(width 0.10795)
		(layer "F.Cu")
		(net "CLK_50M_CKMNG_OCP")
	)
	(segment
		(start 474.9038 -38.4302)
		(end 474.4974 -38.0238)
		(width 0.10795)
		(layer "F.Cu")
		(net "CLK_50M_CKMNG_OCP")
	)
	(segment
		(start 476.600774 -117.209824)
		(end 476.609156 -119.57939)
		(width 0.10795)
		(layer "F.Cu")
		(net "CLK_50M_CKMNG_OCP")
	)
	(segment
		(start 475.366334 -39.012622)
		(end 474.9038 -38.550088)
		(width 0.10795)
		(layer "F.Cu")
		(net "CLK_50M_CKMNG_OCP")
	)
	(segment
		(start 474.9038 -38.550088)
		(end 474.9038 -38.4302)
		(width 0.10795)
		(layer "F.Cu")
		(net "CLK_50M_CKMNG_OCP")
	)
	(segment
		(start 476.609156 -119.57939)
		(end 476.74403 -119.714264)
		(width 0.10795)
		(layer "F.Cu")
		(net "CLK_50M_CKMNG_OCP")
	)
	(segment
		(start 474.091 -37.6174)
		(end 474.091 -36.6395)
		(width 0.10795)
		(layer "F.Cu")
		(net "CLK_50M_CKMNG_OCP")
	)
	(segment
		(start 476.601028 -116.993162)
		(end 476.601028 -117.20957)
		(width 0.10795)
		(layer "F.Cu")
		(net "CLK_50M_CKMNG_OCP")
	)
	(via
		(at 476.74403 -119.714264)
		(size 0.508)
		(drill 0.254)
		(layers "F.Cu" "B.Cu")
		(net "CLK_50M_CKMNG_OCP")
	)
	(via
		(at 475.366334 -39.012622)
		(size 0.508)
		(drill 0.254)
		(layers "F.Cu" "B.Cu")
		(net "CLK_50M_CKMNG_OCP")
	)
	(via
		(at 474.4974 -38.0238)
		(size 0.762)
		(drill 0.381)
		(layers "F.Cu" "B.Cu")
		(net "CLK_50M_CKMNG_OCP")
	)
	(segment
		(start 475.588076 -56.238648)
		(end 472.894152 -56.238648)
		(width 0.089408)
		(layer "In11.Cu")
		(net "CLK_50M_CKMNG_OCP")
	)
	(segment
		(start 469.786462 -61.218572)
		(end 469.786208 -61.218826)
		(width 0.089408)
		(layer "In11.Cu")
		(net "CLK_50M_CKMNG_OCP")
	)
	(segment
		(start 472.758516 -39.782496)
		(end 472.598496 -39.942516)
		(width 0.089408)
		(layer "In11.Cu")
		(net "CLK_50M_CKMNG_OCP")
	)
	(segment
		(start 476.569024 -48.422814)
		(end 476.569024 -51.99253)
		(width 0.089408)
		(layer "In11.Cu")
		(net "CLK_50M_CKMNG_OCP")
	)
	(segment
		(start 474.047566 -44.0944)
		(end 474.4974 -44.0944)
		(width 0.089408)
		(layer "In11.Cu")
		(net "CLK_50M_CKMNG_OCP")
	)
	(segment
		(start 474.680788 -46.534578)
		(end 476.569024 -48.422814)
		(width 0.089408)
		(layer "In11.Cu")
		(net "CLK_50M_CKMNG_OCP")
	)
	(segment
		(start 475.366334 -39.012622)
		(end 475.4372 -39.083488)
		(width 0.089408)
		(layer "In11.Cu")
		(net "CLK_50M_CKMNG_OCP")
	)
	(segment
		(start 478.123504 -55.859172)
		(end 481.301806 -55.859172)
		(width 0.089408)
		(layer "In11.Cu")
		(net "CLK_50M_CKMNG_OCP")
	)
	(segment
		(start 476.931228 -57.5818)
		(end 475.588076 -56.238648)
		(width 0.089408)
		(layer "In11.Cu")
		(net "CLK_50M_CKMNG_OCP")
	)
	(segment
		(start 474.680788 -44.277788)
		(end 474.680788 -46.534578)
		(width 0.089408)
		(layer "In11.Cu")
		(net "CLK_50M_CKMNG_OCP")
	)
	(segment
		(start 476.569024 -51.99253)
		(end 477.6724 -53.095906)
		(width 0.089408)
		(layer "In11.Cu")
		(net "CLK_50M_CKMNG_OCP")
	)
	(segment
		(start 426.708062 -78.176628)
		(end 426.708062 -109.534452)
		(width 0.089408)
		(layer "In11.Cu")
		(net "CLK_50M_CKMNG_OCP")
	)
	(segment
		(start 484.1875 -59.212734)
		(end 483.92461 -59.475624)
		(width 0.089408)
		(layer "In11.Cu")
		(net "CLK_50M_CKMNG_OCP")
	)
	(segment
		(start 477.539304 -116.696744)
		(end 476.74403 -117.492018)
		(width 0.089408)
		(layer "In11.Cu")
		(net "CLK_50M_CKMNG_OCP")
	)
	(segment
		(start 427.808136 -66.692526)
		(end 426.173392 -68.32727)
		(width 0.089408)
		(layer "In11.Cu")
		(net "CLK_50M_CKMNG_OCP")
	)
	(segment
		(start 473.61348 -43.66768)
		(end 473.893896 -43.948096)
		(width 0.089408)
		(layer "In11.Cu")
		(net "CLK_50M_CKMNG_OCP")
	)
	(segment
		(start 476.74403 -117.492018)
		(end 476.74403 -119.714264)
		(width 0.089408)
		(layer "In11.Cu")
		(net "CLK_50M_CKMNG_OCP")
	)
	(segment
		(start 427.63948 -110.46587)
		(end 474.657928 -110.46587)
		(width 0.089408)
		(layer "In11.Cu")
		(net "CLK_50M_CKMNG_OCP")
	)
	(segment
		(start 469.786208 -59.346592)
		(end 469.786208 -60.955174)
		(width 0.089408)
		(layer "In11.Cu")
		(net "CLK_50M_CKMNG_OCP")
	)
	(segment
		(start 472.845892 -43.66768)
		(end 473.61348 -43.66768)
		(width 0.089408)
		(layer "In11.Cu")
		(net "CLK_50M_CKMNG_OCP")
	)
	(segment
		(start 477.539304 -113.347246)
		(end 477.539304 -116.696744)
		(width 0.089408)
		(layer "In11.Cu")
		(net "CLK_50M_CKMNG_OCP")
	)
	(segment
		(start 477.451166 -57.5818)
		(end 476.931228 -57.5818)
		(width 0.089408)
		(layer "In11.Cu")
		(net "CLK_50M_CKMNG_OCP")
	)
	(segment
		(start 472.598496 -43.420284)
		(end 472.845892 -43.66768)
		(width 0.089408)
		(layer "In11.Cu")
		(net "CLK_50M_CKMNG_OCP")
	)
	(segment
		(start 484.1875 -56.2737)
		(end 484.1875 -59.212734)
		(width 0.089408)
		(layer "In11.Cu")
		(net "CLK_50M_CKMNG_OCP")
	)
	(segment
		(start 473.893896 -43.948096)
		(end 473.901262 -43.948096)
		(width 0.089408)
		(layer "In11.Cu")
		(net "CLK_50M_CKMNG_OCP")
	)
	(segment
		(start 475.4372 -39.083488)
		(end 475.4372 -39.497)
		(width 0.089408)
		(layer "In11.Cu")
		(net "CLK_50M_CKMNG_OCP")
	)
	(segment
		(start 482.95306 -59.475624)
		(end 482.505004 -59.027568)
		(width 0.089408)
		(layer "In11.Cu")
		(net "CLK_50M_CKMNG_OCP")
	)
	(segment
		(start 473.901262 -43.948096)
		(end 474.047566 -44.0944)
		(width 0.089408)
		(layer "In11.Cu")
		(net "CLK_50M_CKMNG_OCP")
	)
	(segment
		(start 464.729576 -66.692526)
		(end 427.808136 -66.692526)
		(width 0.089408)
		(layer "In11.Cu")
		(net "CLK_50M_CKMNG_OCP")
	)
	(segment
		(start 426.066712 -77.535278)
		(end 426.708062 -78.176628)
		(width 0.089408)
		(layer "In11.Cu")
		(net "CLK_50M_CKMNG_OCP")
	)
	(segment
		(start 426.066712 -68.634864)
		(end 426.066712 -77.535278)
		(width 0.089408)
		(layer "In11.Cu")
		(net "CLK_50M_CKMNG_OCP")
	)
	(segment
		(start 477.6724 -53.095906)
		(end 477.6724 -55.408068)
		(width 0.089408)
		(layer "In11.Cu")
		(net "CLK_50M_CKMNG_OCP")
	)
	(segment
		(start 483.92461 -59.475624)
		(end 482.95306 -59.475624)
		(width 0.089408)
		(layer "In11.Cu")
		(net "CLK_50M_CKMNG_OCP")
	)
	(segment
		(start 482.505004 -59.027568)
		(end 478.896934 -59.027568)
		(width 0.089408)
		(layer "In11.Cu")
		(net "CLK_50M_CKMNG_OCP")
	)
	(segment
		(start 426.708062 -109.534452)
		(end 427.63948 -110.46587)
		(width 0.089408)
		(layer "In11.Cu")
		(net "CLK_50M_CKMNG_OCP")
	)
	(segment
		(start 469.786208 -61.218826)
		(end 469.786208 -61.635894)
		(width 0.089408)
		(layer "In11.Cu")
		(net "CLK_50M_CKMNG_OCP")
	)
	(segment
		(start 472.598496 -39.942516)
		(end 472.598496 -43.420284)
		(width 0.089408)
		(layer "In11.Cu")
		(net "CLK_50M_CKMNG_OCP")
	)
	(segment
		(start 472.894152 -56.238648)
		(end 469.786208 -59.346592)
		(width 0.089408)
		(layer "In11.Cu")
		(net "CLK_50M_CKMNG_OCP")
	)
	(segment
		(start 474.657928 -110.46587)
		(end 477.539304 -113.347246)
		(width 0.089408)
		(layer "In11.Cu")
		(net "CLK_50M_CKMNG_OCP")
	)
	(segment
		(start 426.173392 -68.32727)
		(end 426.173392 -68.528184)
		(width 0.089408)
		(layer "In11.Cu")
		(net "CLK_50M_CKMNG_OCP")
	)
	(segment
		(start 481.301806 -55.859172)
		(end 481.348034 -55.9054)
		(width 0.089408)
		(layer "In11.Cu")
		(net "CLK_50M_CKMNG_OCP")
	)
	(segment
		(start 426.173392 -68.528184)
		(end 426.066712 -68.634864)
		(width 0.089408)
		(layer "In11.Cu")
		(net "CLK_50M_CKMNG_OCP")
	)
	(segment
		(start 478.896934 -59.027568)
		(end 477.451166 -57.5818)
		(width 0.089408)
		(layer "In11.Cu")
		(net "CLK_50M_CKMNG_OCP")
	)
	(segment
		(start 469.786462 -60.955428)
		(end 469.786462 -61.218572)
		(width 0.089408)
		(layer "In11.Cu")
		(net "CLK_50M_CKMNG_OCP")
	)
	(segment
		(start 469.786208 -60.955174)
		(end 469.786462 -60.955428)
		(width 0.089408)
		(layer "In11.Cu")
		(net "CLK_50M_CKMNG_OCP")
	)
	(segment
		(start 481.348034 -55.9054)
		(end 483.8192 -55.9054)
		(width 0.089408)
		(layer "In11.Cu")
		(net "CLK_50M_CKMNG_OCP")
	)
	(segment
		(start 474.4974 -44.0944)
		(end 474.680788 -44.277788)
		(width 0.089408)
		(layer "In11.Cu")
		(net "CLK_50M_CKMNG_OCP")
	)
	(segment
		(start 475.4372 -39.497)
		(end 475.151704 -39.782496)
		(width 0.089408)
		(layer "In11.Cu")
		(net "CLK_50M_CKMNG_OCP")
	)
	(segment
		(start 469.786208 -61.635894)
		(end 464.729576 -66.692526)
		(width 0.089408)
		(layer "In11.Cu")
		(net "CLK_50M_CKMNG_OCP")
	)
	(segment
		(start 477.6724 -55.408068)
		(end 478.123504 -55.859172)
		(width 0.089408)
		(layer "In11.Cu")
		(net "CLK_50M_CKMNG_OCP")
	)
	(segment
		(start 483.8192 -55.9054)
		(end 484.1875 -56.2737)
		(width 0.089408)
		(layer "In11.Cu")
		(net "CLK_50M_CKMNG_OCP")
	)
	(segment
		(start 475.151704 -39.782496)
		(end 472.758516 -39.782496)
		(width 0.089408)
		(layer "In11.Cu")
		(net "CLK_50M_CKMNG_OCP")
	)
	(segment
		(start 405.70531 -28.554172)
		(end 407.509726 -28.554172)
		(width 0.10795)
		(layer "F.Cu")
		(net "CLK_50M_CKMNG_BMC_1")
	)
	(segment
		(start 474.98 -36.6395)
		(end 475.495874 -36.6395)
		(width 0.10795)
		(layer "F.Cu")
		(net "CLK_50M_CKMNG_BMC_1")
	)
	(segment
		(start 404.990808 -28.289758)
		(end 405.440896 -28.289758)
		(width 0.10795)
		(layer "F.Cu")
		(net "CLK_50M_CKMNG_BMC_1")
	)
	(segment
		(start 407.509726 -28.554172)
		(end 407.890218 -28.934664)
		(width 0.10795)
		(layer "F.Cu")
		(net "CLK_50M_CKMNG_BMC_1")
	)
	(segment
		(start 475.495874 -36.6395)
		(end 475.5896 -36.733226)
		(width 0.10795)
		(layer "F.Cu")
		(net "CLK_50M_CKMNG_BMC_1")
	)
	(segment
		(start 405.440896 -28.289758)
		(end 405.70531 -28.554172)
		(width 0.10795)
		(layer "F.Cu")
		(net "CLK_50M_CKMNG_BMC_1")
	)
	(via
		(at 404.990808 -28.289758)
		(size 0.508)
		(drill 0.254)
		(layers "F.Cu" "B.Cu")
		(net "CLK_50M_CKMNG_BMC_1")
	)
	(via
		(at 475.5896 -36.733226)
		(size 0.508)
		(drill 0.254)
		(layers "F.Cu" "B.Cu")
		(net "CLK_50M_CKMNG_BMC_1")
	)
	(segment
		(start 459.1558 -29.723842)
		(end 459.835758 -30.4038)
		(width 0.089408)
		(layer "In4.Cu")
		(net "CLK_50M_CKMNG_BMC_1")
	)
	(segment
		(start 431.824892 -24.56942)
		(end 432.778408 -24.56942)
		(width 0.089408)
		(layer "In4.Cu")
		(net "CLK_50M_CKMNG_BMC_1")
	)
	(segment
		(start 452.685912 -28.92044)
		(end 456.997562 -28.92044)
		(width 0.089408)
		(layer "In4.Cu")
		(net "CLK_50M_CKMNG_BMC_1")
	)
	(segment
		(start 473.263722 -36.209224)
		(end 473.26677 -36.212272)
		(width 0.089408)
		(layer "In4.Cu")
		(net "CLK_50M_CKMNG_BMC_1")
	)
	(segment
		(start 406.814528 -27.340052)
		(end 408.12085 -26.03373)
		(width 0.089408)
		(layer "In4.Cu")
		(net "CLK_50M_CKMNG_BMC_1")
	)
	(segment
		(start 415.929826 -24.11095)
		(end 420.674038 -24.11095)
		(width 0.089408)
		(layer "In4.Cu")
		(net "CLK_50M_CKMNG_BMC_1")
	)
	(segment
		(start 429.4759 -24.872442)
		(end 430.150778 -24.872442)
		(width 0.089408)
		(layer "In4.Cu")
		(net "CLK_50M_CKMNG_BMC_1")
	)
	(segment
		(start 428.841662 -24.238204)
		(end 429.4759 -24.872442)
		(width 0.089408)
		(layer "In4.Cu")
		(net "CLK_50M_CKMNG_BMC_1")
	)
	(segment
		(start 447.24066 -24.446484)
		(end 448.518026 -25.72385)
		(width 0.089408)
		(layer "In4.Cu")
		(net "CLK_50M_CKMNG_BMC_1")
	)
	(segment
		(start 473.598494 -36.212272)
		(end 473.601542 -36.209224)
		(width 0.089408)
		(layer "In4.Cu")
		(net "CLK_50M_CKMNG_BMC_1")
	)
	(segment
		(start 449.489322 -25.72385)
		(end 452.685912 -28.92044)
		(width 0.089408)
		(layer "In4.Cu")
		(net "CLK_50M_CKMNG_BMC_1")
	)
	(segment
		(start 408.12085 -26.03373)
		(end 408.78633 -26.03373)
		(width 0.089408)
		(layer "In4.Cu")
		(net "CLK_50M_CKMNG_BMC_1")
	)
	(segment
		(start 456.997562 -28.92044)
		(end 457.800964 -29.723842)
		(width 0.089408)
		(layer "In4.Cu")
		(net "CLK_50M_CKMNG_BMC_1")
	)
	(segment
		(start 405.375364 -27.340052)
		(end 406.814528 -27.340052)
		(width 0.089408)
		(layer "In4.Cu")
		(net "CLK_50M_CKMNG_BMC_1")
	)
	(segment
		(start 426.654214 -24.238204)
		(end 428.841662 -24.238204)
		(width 0.089408)
		(layer "In4.Cu")
		(net "CLK_50M_CKMNG_BMC_1")
	)
	(segment
		(start 404.990808 -28.289758)
		(end 404.990808 -27.724608)
		(width 0.089408)
		(layer "In4.Cu")
		(net "CLK_50M_CKMNG_BMC_1")
	)
	(segment
		(start 473.26677 -36.212272)
		(end 473.598494 -36.212272)
		(width 0.089408)
		(layer "In4.Cu")
		(net "CLK_50M_CKMNG_BMC_1")
	)
	(segment
		(start 457.800964 -29.723842)
		(end 459.1558 -29.723842)
		(width 0.089408)
		(layer "In4.Cu")
		(net "CLK_50M_CKMNG_BMC_1")
	)
	(segment
		(start 408.78633 -26.03373)
		(end 409.52801 -25.29205)
		(width 0.089408)
		(layer "In4.Cu")
		(net "CLK_50M_CKMNG_BMC_1")
	)
	(segment
		(start 430.150778 -24.872442)
		(end 430.566068 -24.457152)
		(width 0.089408)
		(layer "In4.Cu")
		(net "CLK_50M_CKMNG_BMC_1")
	)
	(segment
		(start 430.566068 -24.457152)
		(end 430.772062 -24.457152)
		(width 0.089408)
		(layer "In4.Cu")
		(net "CLK_50M_CKMNG_BMC_1")
	)
	(segment
		(start 404.990808 -27.724608)
		(end 405.375364 -27.340052)
		(width 0.089408)
		(layer "In4.Cu")
		(net "CLK_50M_CKMNG_BMC_1")
	)
	(segment
		(start 464.499452 -33.424622)
		(end 466.145626 -33.424622)
		(width 0.089408)
		(layer "In4.Cu")
		(net "CLK_50M_CKMNG_BMC_1")
	)
	(segment
		(start 432.778408 -24.56942)
		(end 434.612288 -22.73554)
		(width 0.089408)
		(layer "In4.Cu")
		(net "CLK_50M_CKMNG_BMC_1")
	)
	(segment
		(start 473.601542 -36.209224)
		(end 475.065598 -36.209224)
		(width 0.089408)
		(layer "In4.Cu")
		(net "CLK_50M_CKMNG_BMC_1")
	)
	(segment
		(start 426.32376 -24.568658)
		(end 426.654214 -24.238204)
		(width 0.089408)
		(layer "In4.Cu")
		(net "CLK_50M_CKMNG_BMC_1")
	)
	(segment
		(start 475.065598 -36.209224)
		(end 475.5896 -36.733226)
		(width 0.089408)
		(layer "In4.Cu")
		(net "CLK_50M_CKMNG_BMC_1")
	)
	(segment
		(start 431.690526 -24.435054)
		(end 431.824892 -24.56942)
		(width 0.089408)
		(layer "In4.Cu")
		(net "CLK_50M_CKMNG_BMC_1")
	)
	(segment
		(start 444.598298 -21.608288)
		(end 447.24066 -24.25065)
		(width 0.089408)
		(layer "In4.Cu")
		(net "CLK_50M_CKMNG_BMC_1")
	)
	(segment
		(start 461.47863 -30.4038)
		(end 464.499452 -33.424622)
		(width 0.089408)
		(layer "In4.Cu")
		(net "CLK_50M_CKMNG_BMC_1")
	)
	(segment
		(start 434.612288 -22.73554)
		(end 434.612288 -22.028912)
		(width 0.089408)
		(layer "In4.Cu")
		(net "CLK_50M_CKMNG_BMC_1")
	)
	(segment
		(start 471.30843 -36.209224)
		(end 473.263722 -36.209224)
		(width 0.089408)
		(layer "In4.Cu")
		(net "CLK_50M_CKMNG_BMC_1")
	)
	(segment
		(start 430.79416 -24.435054)
		(end 431.690526 -24.435054)
		(width 0.089408)
		(layer "In4.Cu")
		(net "CLK_50M_CKMNG_BMC_1")
	)
	(segment
		(start 466.145626 -33.424622)
		(end 467.674198 -34.953194)
		(width 0.089408)
		(layer "In4.Cu")
		(net "CLK_50M_CKMNG_BMC_1")
	)
	(segment
		(start 421.131746 -24.568658)
		(end 426.32376 -24.568658)
		(width 0.089408)
		(layer "In4.Cu")
		(net "CLK_50M_CKMNG_BMC_1")
	)
	(segment
		(start 459.835758 -30.4038)
		(end 461.47863 -30.4038)
		(width 0.089408)
		(layer "In4.Cu")
		(net "CLK_50M_CKMNG_BMC_1")
	)
	(segment
		(start 430.772062 -24.457152)
		(end 430.79416 -24.435054)
		(width 0.089408)
		(layer "In4.Cu")
		(net "CLK_50M_CKMNG_BMC_1")
	)
	(segment
		(start 420.674038 -24.11095)
		(end 421.131746 -24.568658)
		(width 0.089408)
		(layer "In4.Cu")
		(net "CLK_50M_CKMNG_BMC_1")
	)
	(segment
		(start 470.0524 -34.953194)
		(end 471.30843 -36.209224)
		(width 0.089408)
		(layer "In4.Cu")
		(net "CLK_50M_CKMNG_BMC_1")
	)
	(segment
		(start 434.612288 -22.028912)
		(end 435.032912 -21.608288)
		(width 0.089408)
		(layer "In4.Cu")
		(net "CLK_50M_CKMNG_BMC_1")
	)
	(segment
		(start 467.674198 -34.953194)
		(end 470.0524 -34.953194)
		(width 0.089408)
		(layer "In4.Cu")
		(net "CLK_50M_CKMNG_BMC_1")
	)
	(segment
		(start 448.518026 -25.72385)
		(end 449.489322 -25.72385)
		(width 0.089408)
		(layer "In4.Cu")
		(net "CLK_50M_CKMNG_BMC_1")
	)
	(segment
		(start 447.24066 -24.25065)
		(end 447.24066 -24.446484)
		(width 0.089408)
		(layer "In4.Cu")
		(net "CLK_50M_CKMNG_BMC_1")
	)
	(segment
		(start 409.52801 -25.29205)
		(end 414.748726 -25.29205)
		(width 0.089408)
		(layer "In4.Cu")
		(net "CLK_50M_CKMNG_BMC_1")
	)
	(segment
		(start 414.748726 -25.29205)
		(end 415.929826 -24.11095)
		(width 0.089408)
		(layer "In4.Cu")
		(net "CLK_50M_CKMNG_BMC_1")
	)
	(segment
		(start 435.032912 -21.608288)
		(end 444.598298 -21.608288)
		(width 0.089408)
		(layer "In4.Cu")
		(net "CLK_50M_CKMNG_BMC_1")
	)
	(segment
		(start 393.685014 -112.441736)
		(end 394.165074 -112.664748)
		(width 0.254)
		(layer "F.Cu")
		(net "A_KR1_RBIAS")
	)
	(segment
		(start 393.68095 -112.43056)
		(end 393.685014 -112.441736)
		(width 0.254)
		(layer "F.Cu")
		(net "A_KR1_RBIAS")
	)
	(segment
		(start 394.165074 -112.664748)
		(end 394.17625 -112.660684)
		(width 0.254)
		(layer "F.Cu")
		(net "A_KR1_RBIAS")
	)
	(via
		(at 394.17625 -112.660684)
		(size 0.508)
		(drill 0.254)
		(layers "F.Cu" "B.Cu")
		(net "A_KR1_RBIAS")
	)
	(segment
		(start 394.17625 -112.660684)
		(end 393.81557 -112.660684)
		(width 0.254)
		(layer "B.Cu")
		(net "A_KR1_RBIAS")
	)
	(segment
		(start 393.81557 -112.660684)
		(end 393.396216 -113.080038)
		(width 0.254)
		(layer "B.Cu")
		(net "A_KR1_RBIAS")
	)
	(segment
		(start 393.396216 -113.080038)
		(end 392.835384 -113.080038)
		(width 0.254)
		(layer "B.Cu")
		(net "A_KR1_RBIAS")
	)
	(segment
		(start 393.24788 -105.89514)
		(end 392.938 -105.8545)
		(width 0.254)
		(layer "F.Cu")
		(net "A_KR0_RBIAS")
	)
	(segment
		(start 393.41806 -106.06786)
		(end 393.24788 -105.89514)
		(width 0.254)
		(layer "F.Cu")
		(net "A_KR0_RBIAS")
	)
	(segment
		(start 393.215368 -106.402378)
		(end 393.37996 -106.299)
		(width 0.254)
		(layer "F.Cu")
		(net "A_KR0_RBIAS")
	)
	(segment
		(start 393.37996 -106.299)
		(end 393.41806 -106.06786)
		(width 0.254)
		(layer "F.Cu")
		(net "A_KR0_RBIAS")
	)
	(segment
		(start 393.18565 -106.42092)
		(end 393.215368 -106.402378)
		(width 0.254)
		(layer "F.Cu")
		(net "A_KR0_RBIAS")
	)
	(via
		(at 392.938 -105.8545)
		(size 0.508)
		(drill 0.254)
		(layers "F.Cu" "B.Cu")
		(net "A_KR0_RBIAS")
	)
	(segment
		(start 392.938 -105.8545)
		(end 392.498834 -106.293666)
		(width 0.254)
		(layer "B.Cu")
		(net "A_KR0_RBIAS")
	)
	(segment
		(start 392.498834 -106.293666)
		(end 392.498834 -106.467148)
		(width 0.254)
		(layer "B.Cu")
		(net "A_KR0_RBIAS")
	)
	(segment
		(start 392.928602 -154.796998)
		(end 393.3317 -154.796998)
		(width 0.1778)
		(layer "F.Cu")
		(net "VR_PVNN_PCH_XADDR2")
	)
	(segment
		(start 392.6586 -155.067)
		(end 392.928602 -154.796998)
		(width 0.1778)
		(layer "F.Cu")
		(net "VR_PVNN_PCH_XADDR2")
	)
	(segment
		(start 391.795 -155.067)
		(end 392.6586 -155.067)
		(width 0.1778)
		(layer "F.Cu")
		(net "VR_PVNN_PCH_XADDR2")
	)
	(segment
		(start 174.128684 -63.232792)
		(end 173.736 -63.625476)
		(width 0.2032)
		(layer "F.Cu")
		(net "VR_PVCCIO_CPU1_XADDR2")
	)
	(segment
		(start 173.736 -63.831978)
		(end 173.246542 -63.831978)
		(width 0.2032)
		(layer "F.Cu")
		(net "VR_PVCCIO_CPU1_XADDR2")
	)
	(segment
		(start 176.156366 -63.547752)
		(end 175.841406 -63.232792)
		(width 0.2032)
		(layer "F.Cu")
		(net "VR_PVCCIO_CPU1_XADDR2")
	)
	(segment
		(start 173.246542 -63.831978)
		(end 172.70222 -64.3763)
		(width 0.2032)
		(layer "F.Cu")
		(net "VR_PVCCIO_CPU1_XADDR2")
	)
	(segment
		(start 175.841406 -63.232792)
		(end 174.128684 -63.232792)
		(width 0.2032)
		(layer "F.Cu")
		(net "VR_PVCCIO_CPU1_XADDR2")
	)
	(segment
		(start 173.736 -63.625476)
		(end 173.736 -63.831978)
		(width 0.2032)
		(layer "F.Cu")
		(net "VR_PVCCIO_CPU1_XADDR2")
	)
	(segment
		(start 172.020738 -65.802002)
		(end 171.6405 -65.802002)
		(width 0.2032)
		(layer "F.Cu")
		(net "VR_PVCCIO_CPU1_XADDR2")
	)
	(segment
		(start 172.70222 -64.3763)
		(end 172.70222 -65.12052)
		(width 0.2032)
		(layer "F.Cu")
		(net "VR_PVCCIO_CPU1_XADDR2")
	)
	(segment
		(start 172.70222 -65.12052)
		(end 172.020738 -65.802002)
		(width 0.2032)
		(layer "F.Cu")
		(net "VR_PVCCIO_CPU1_XADDR2")
	)
	(via
		(at 176.156366 -63.547752)
		(size 0.762)
		(drill 0.381)
		(layers "F.Cu" "B.Cu")
		(net "VR_PVCCIO_CPU1_XADDR2")
	)
	(via
		(at 350.23552 -89.50198)
		(size 0.6604)
		(drill 0.3302)
		(layers "F.Cu" "B.Cu")
		(net "VR_PVCCIO_CPU0_XADDR2")
	)
	(segment
		(start 349.889826 -89.156286)
		(end 349.889826 -89.026238)
		(width 0.1143)
		(layer "B.Cu")
		(net "VR_PVCCIO_CPU0_XADDR2")
	)
	(segment
		(start 351.1296 -89.865962)
		(end 350.599502 -89.865962)
		(width 0.1143)
		(layer "B.Cu")
		(net "VR_PVCCIO_CPU0_XADDR2")
	)
	(segment
		(start 350.23552 -89.50198)
		(end 349.889826 -89.156286)
		(width 0.1143)
		(layer "B.Cu")
		(net "VR_PVCCIO_CPU0_XADDR2")
	)
	(segment
		(start 349.315786 -88.452198)
		(end 348.9833 -88.452198)
		(width 0.1143)
		(layer "B.Cu")
		(net "VR_PVCCIO_CPU0_XADDR2")
	)
	(segment
		(start 350.599502 -89.865962)
		(end 350.23552 -89.50198)
		(width 0.1143)
		(layer "B.Cu")
		(net "VR_PVCCIO_CPU0_XADDR2")
	)
	(segment
		(start 349.889826 -89.026238)
		(end 349.315786 -88.452198)
		(width 0.1143)
		(layer "B.Cu")
		(net "VR_PVCCIO_CPU0_XADDR2")
	)
	(segment
		(start 406.290018 -30.004004)
		(end 406.370028 -30.084014)
		(width 0.1143)
		(layer "F.Cu")
		(net "USB2_PCH_BMC_P5_DP")
	)
	(segment
		(start 409.208478 -119.051832)
		(end 409.519882 -118.740428)
		(width 0.1143)
		(layer "F.Cu")
		(net "USB2_PCH_BMC_P5_DP")
	)
	(segment
		(start 399.81759 -28.69565)
		(end 400.341592 -29.219652)
		(width 0.1143)
		(layer "F.Cu")
		(net "USB2_PCH_BMC_P5_DP")
	)
	(segment
		(start 395.766544 -25.622758)
		(end 395.648688 -25.622758)
		(width 0.1143)
		(layer "F.Cu")
		(net "USB2_PCH_BMC_P5_DP")
	)
	(segment
		(start 410.193998 -118.491508)
		(end 412.077408 -118.491508)
		(width 0.1143)
		(layer "F.Cu")
		(net "USB2_PCH_BMC_P5_DP")
	)
	(segment
		(start 406.370028 -30.084014)
		(end 407.439622 -30.084014)
		(width 0.1143)
		(layer "F.Cu")
		(net "USB2_PCH_BMC_P5_DP")
	)
	(segment
		(start 395.49705 -25.774396)
		(end 395.49705 -26.05405)
		(width 0.1143)
		(layer "F.Cu")
		(net "USB2_PCH_BMC_P5_DP")
	)
	(segment
		(start 395.49705 -26.05405)
		(end 395.93012 -26.48712)
		(width 0.1143)
		(layer "F.Cu")
		(net "USB2_PCH_BMC_P5_DP")
	)
	(segment
		(start 412.077408 -118.491508)
		(end 412.42107 -118.83517)
		(width 0.1143)
		(layer "F.Cu")
		(net "USB2_PCH_BMC_P5_DP")
	)
	(segment
		(start 395.93012 -26.48712)
		(end 396.84452 -26.48712)
		(width 0.1143)
		(layer "F.Cu")
		(net "USB2_PCH_BMC_P5_DP")
	)
	(segment
		(start 409.519882 -118.740428)
		(end 409.945078 -118.740428)
		(width 0.1143)
		(layer "F.Cu")
		(net "USB2_PCH_BMC_P5_DP")
	)
	(segment
		(start 399.05305 -28.69565)
		(end 399.81759 -28.69565)
		(width 0.1143)
		(layer "F.Cu")
		(net "USB2_PCH_BMC_P5_DP")
	)
	(segment
		(start 407.439622 -30.084014)
		(end 407.890218 -30.53461)
		(width 0.1143)
		(layer "F.Cu")
		(net "USB2_PCH_BMC_P5_DP")
	)
	(segment
		(start 400.341592 -29.219652)
		(end 401.125944 -30.004004)
		(width 0.1143)
		(layer "F.Cu")
		(net "USB2_PCH_BMC_P5_DP")
	)
	(segment
		(start 409.945078 -118.740428)
		(end 410.193998 -118.491508)
		(width 0.1143)
		(layer "F.Cu")
		(net "USB2_PCH_BMC_P5_DP")
	)
	(segment
		(start 401.125944 -30.004004)
		(end 406.290018 -30.004004)
		(width 0.1143)
		(layer "F.Cu")
		(net "USB2_PCH_BMC_P5_DP")
	)
	(segment
		(start 396.84452 -26.48712)
		(end 399.05305 -28.69565)
		(width 0.1143)
		(layer "F.Cu")
		(net "USB2_PCH_BMC_P5_DP")
	)
	(segment
		(start 395.648688 -25.622758)
		(end 395.49705 -25.774396)
		(width 0.1143)
		(layer "F.Cu")
		(net "USB2_PCH_BMC_P5_DP")
	)
	(via
		(at 412.42107 -118.83517)
		(size 0.508)
		(drill 0.254)
		(layers "F.Cu" "B.Cu")
		(net "USB2_PCH_BMC_P5_DP")
	)
	(via
		(at 395.766544 -25.622758)
		(size 0.508)
		(drill 0.254)
		(layers "F.Cu" "B.Cu")
		(net "USB2_PCH_BMC_P5_DP")
	)
	(via
		(at 400.341592 -29.219652)
		(size 0.508)
		(drill 0.254)
		(layers "F.Cu" "B.Cu")
		(net "USB2_PCH_BMC_P5_DP")
	)
	(segment
		(start 395.4653 -26.4287)
		(end 395.4653 -25.924002)
		(width 0.1143)
		(layer "In11.Cu")
		(net "USB2_PCH_BMC_P5_DP")
	)
	(segment
		(start 417.31565 -94.383352)
		(end 417.855654 -93.842332)
		(width 0.1143)
		(layer "In11.Cu")
		(net "USB2_PCH_BMC_P5_DP")
	)
	(segment
		(start 401.3073 -49.00803)
		(end 401.3073 -45.633132)
		(width 0.1143)
		(layer "In11.Cu")
		(net "USB2_PCH_BMC_P5_DP")
	)
	(segment
		(start 417.31565 -94.547436)
		(end 417.31565 -94.383352)
		(width 0.1143)
		(layer "In11.Cu")
		(net "USB2_PCH_BMC_P5_DP")
	)
	(segment
		(start 412.731966 -55.732934)
		(end 412.731966 -55.224934)
		(width 0.1143)
		(layer "In11.Cu")
		(net "USB2_PCH_BMC_P5_DP")
	)
	(segment
		(start 418.25545 -86.83371)
		(end 417.734242 -86.312502)
		(width 0.1143)
		(layer "In11.Cu")
		(net "USB2_PCH_BMC_P5_DP")
	)
	(segment
		(start 396.565882 -34.522918)
		(end 396.565882 -31.223204)
		(width 0.1143)
		(layer "In11.Cu")
		(net "USB2_PCH_BMC_P5_DP")
	)
	(segment
		(start 417.5252 -70.434454)
		(end 417.5252 -63.373)
		(width 0.1143)
		(layer "In11.Cu")
		(net "USB2_PCH_BMC_P5_DP")
	)
	(segment
		(start 418.25545 -89.636854)
		(end 418.25545 -86.83371)
		(width 0.1143)
		(layer "In11.Cu")
		(net "USB2_PCH_BMC_P5_DP")
	)
	(segment
		(start 412.572454 -118.481602)
		(end 412.837376 -118.481602)
		(width 0.1143)
		(layer "In11.Cu")
		(net "USB2_PCH_BMC_P5_DP")
	)
	(segment
		(start 418.134038 -71.043292)
		(end 417.5252 -70.434454)
		(width 0.1143)
		(layer "In11.Cu")
		(net "USB2_PCH_BMC_P5_DP")
	)
	(segment
		(start 397.754602 -42.080434)
		(end 397.754602 -40.554402)
		(width 0.1143)
		(layer "In11.Cu")
		(net "USB2_PCH_BMC_P5_DP")
	)
	(segment
		(start 416.9791 -62.8269)
		(end 416.9791 -60.972954)
		(width 0.1143)
		(layer "In11.Cu")
		(net "USB2_PCH_BMC_P5_DP")
	)
	(segment
		(start 414.805622 -56.2356)
		(end 413.234632 -56.2356)
		(width 0.1143)
		(layer "In11.Cu")
		(net "USB2_PCH_BMC_P5_DP")
	)
	(segment
		(start 415.69005 -109.284008)
		(end 417.0172 -107.956858)
		(width 0.1143)
		(layer "In11.Cu")
		(net "USB2_PCH_BMC_P5_DP")
	)
	(segment
		(start 412.42107 -118.83517)
		(end 412.42107 -118.632986)
		(width 0.1143)
		(layer "In11.Cu")
		(net "USB2_PCH_BMC_P5_DP")
	)
	(segment
		(start 418.134038 -80.996028)
		(end 418.134038 -71.043292)
		(width 0.1143)
		(layer "In11.Cu")
		(net "USB2_PCH_BMC_P5_DP")
	)
	(segment
		(start 395.1097 -26.7843)
		(end 395.4653 -26.4287)
		(width 0.1143)
		(layer "In11.Cu")
		(net "USB2_PCH_BMC_P5_DP")
	)
	(segment
		(start 416.9791 -60.972954)
		(end 416.2552 -60.249054)
		(width 0.1143)
		(layer "In11.Cu")
		(net "USB2_PCH_BMC_P5_DP")
	)
	(segment
		(start 416.2552 -57.685178)
		(end 414.805622 -56.2356)
		(width 0.1143)
		(layer "In11.Cu")
		(net "USB2_PCH_BMC_P5_DP")
	)
	(segment
		(start 417.855654 -93.842332)
		(end 417.855654 -90.03665)
		(width 0.1143)
		(layer "In11.Cu")
		(net "USB2_PCH_BMC_P5_DP")
	)
	(segment
		(start 412.731966 -55.224934)
		(end 409.818586 -52.3113)
		(width 0.1143)
		(layer "In11.Cu")
		(net "USB2_PCH_BMC_P5_DP")
	)
	(segment
		(start 417.734242 -81.395824)
		(end 418.134038 -80.996028)
		(width 0.1143)
		(layer "In11.Cu")
		(net "USB2_PCH_BMC_P5_DP")
	)
	(segment
		(start 396.565882 -31.223204)
		(end 396.61465 -31.174436)
		(width 0.1143)
		(layer "In11.Cu")
		(net "USB2_PCH_BMC_P5_DP")
	)
	(segment
		(start 395.4653 -25.924002)
		(end 395.766544 -25.622758)
		(width 0.1143)
		(layer "In11.Cu")
		(net "USB2_PCH_BMC_P5_DP")
	)
	(segment
		(start 414.613852 -117.2337)
		(end 415.2011 -116.646452)
		(width 0.1143)
		(layer "In11.Cu")
		(net "USB2_PCH_BMC_P5_DP")
	)
	(segment
		(start 417.0172 -107.956858)
		(end 417.0172 -94.845886)
		(width 0.1143)
		(layer "In11.Cu")
		(net "USB2_PCH_BMC_P5_DP")
	)
	(segment
		(start 414.085278 -117.2337)
		(end 414.613852 -117.2337)
		(width 0.1143)
		(layer "In11.Cu")
		(net "USB2_PCH_BMC_P5_DP")
	)
	(segment
		(start 417.5252 -63.373)
		(end 416.9791 -62.8269)
		(width 0.1143)
		(layer "In11.Cu")
		(net "USB2_PCH_BMC_P5_DP")
	)
	(segment
		(start 415.2011 -116.646452)
		(end 415.2011 -111.5949)
		(width 0.1143)
		(layer "In11.Cu")
		(net "USB2_PCH_BMC_P5_DP")
	)
	(segment
		(start 403.455886 -51.156616)
		(end 401.3073 -49.00803)
		(width 0.1143)
		(layer "In11.Cu")
		(net "USB2_PCH_BMC_P5_DP")
	)
	(segment
		(start 396.024862 -30.10535)
		(end 395.1097 -29.190188)
		(width 0.1143)
		(layer "In11.Cu")
		(net "USB2_PCH_BMC_P5_DP")
	)
	(segment
		(start 405.84882 -51.156616)
		(end 403.455886 -51.156616)
		(width 0.1143)
		(layer "In11.Cu")
		(net "USB2_PCH_BMC_P5_DP")
	)
	(segment
		(start 397.754602 -40.554402)
		(end 396.667482 -39.467282)
		(width 0.1143)
		(layer "In11.Cu")
		(net "USB2_PCH_BMC_P5_DP")
	)
	(segment
		(start 409.818586 -52.3113)
		(end 407.003504 -52.3113)
		(width 0.1143)
		(layer "In11.Cu")
		(net "USB2_PCH_BMC_P5_DP")
	)
	(segment
		(start 415.69005 -111.10595)
		(end 415.69005 -109.284008)
		(width 0.1143)
		(layer "In11.Cu")
		(net "USB2_PCH_BMC_P5_DP")
	)
	(segment
		(start 417.0172 -94.845886)
		(end 417.31565 -94.547436)
		(width 0.1143)
		(layer "In11.Cu")
		(net "USB2_PCH_BMC_P5_DP")
	)
	(segment
		(start 417.734242 -86.312502)
		(end 417.734242 -81.395824)
		(width 0.1143)
		(layer "In11.Cu")
		(net "USB2_PCH_BMC_P5_DP")
	)
	(segment
		(start 401.3073 -45.633132)
		(end 397.754602 -42.080434)
		(width 0.1143)
		(layer "In11.Cu")
		(net "USB2_PCH_BMC_P5_DP")
	)
	(segment
		(start 417.855654 -90.03665)
		(end 418.25545 -89.636854)
		(width 0.1143)
		(layer "In11.Cu")
		(net "USB2_PCH_BMC_P5_DP")
	)
	(segment
		(start 395.1097 -29.190188)
		(end 395.1097 -26.7843)
		(width 0.1143)
		(layer "In11.Cu")
		(net "USB2_PCH_BMC_P5_DP")
	)
	(segment
		(start 396.667482 -34.624518)
		(end 396.565882 -34.522918)
		(width 0.1143)
		(layer "In11.Cu")
		(net "USB2_PCH_BMC_P5_DP")
	)
	(segment
		(start 396.61465 -30.547564)
		(end 396.172436 -30.10535)
		(width 0.1143)
		(layer "In11.Cu")
		(net "USB2_PCH_BMC_P5_DP")
	)
	(segment
		(start 412.42107 -118.632986)
		(end 412.572454 -118.481602)
		(width 0.1143)
		(layer "In11.Cu")
		(net "USB2_PCH_BMC_P5_DP")
	)
	(segment
		(start 413.234632 -56.2356)
		(end 412.731966 -55.732934)
		(width 0.1143)
		(layer "In11.Cu")
		(net "USB2_PCH_BMC_P5_DP")
	)
	(segment
		(start 412.837376 -118.481602)
		(end 414.085278 -117.2337)
		(width 0.1143)
		(layer "In11.Cu")
		(net "USB2_PCH_BMC_P5_DP")
	)
	(segment
		(start 396.172436 -30.10535)
		(end 396.024862 -30.10535)
		(width 0.1143)
		(layer "In11.Cu")
		(net "USB2_PCH_BMC_P5_DP")
	)
	(segment
		(start 396.667482 -39.467282)
		(end 396.667482 -34.624518)
		(width 0.1143)
		(layer "In11.Cu")
		(net "USB2_PCH_BMC_P5_DP")
	)
	(segment
		(start 416.2552 -60.249054)
		(end 416.2552 -57.685178)
		(width 0.1143)
		(layer "In11.Cu")
		(net "USB2_PCH_BMC_P5_DP")
	)
	(segment
		(start 407.003504 -52.3113)
		(end 405.84882 -51.156616)
		(width 0.1143)
		(layer "In11.Cu")
		(net "USB2_PCH_BMC_P5_DP")
	)
	(segment
		(start 396.61465 -31.174436)
		(end 396.61465 -30.547564)
		(width 0.1143)
		(layer "In11.Cu")
		(net "USB2_PCH_BMC_P5_DP")
	)
	(segment
		(start 415.2011 -111.5949)
		(end 415.69005 -111.10595)
		(width 0.1143)
		(layer "In11.Cu")
		(net "USB2_PCH_BMC_P5_DP")
	)
	(segment
		(start 395.2367 -26.135076)
		(end 395.830044 -26.72842)
		(width 0.1143)
		(layer "F.Cu")
		(net "USB2_PCH_BMC_P5_DN")
	)
	(segment
		(start 402.587968 -30.359604)
		(end 402.930868 -30.359604)
		(width 0.1143)
		(layer "F.Cu")
		(net "USB2_PCH_BMC_P5_DN")
	)
	(segment
		(start 403.845268 -30.359604)
		(end 403.959568 -30.245304)
		(width 0.1143)
		(layer "F.Cu")
		(net "USB2_PCH_BMC_P5_DN")
	)
	(segment
		(start 402.473668 -30.245304)
		(end 402.587968 -30.359604)
		(width 0.1143)
		(layer "F.Cu")
		(net "USB2_PCH_BMC_P5_DN")
	)
	(segment
		(start 409.845002 -118.499128)
		(end 410.093922 -118.250208)
		(width 0.1143)
		(layer "F.Cu")
		(net "USB2_PCH_BMC_P5_DN")
	)
	(segment
		(start 405.788368 -30.245304)
		(end 406.189942 -30.245304)
		(width 0.1143)
		(layer "F.Cu")
		(net "USB2_PCH_BMC_P5_DN")
	)
	(segment
		(start 404.302468 -30.245304)
		(end 404.416768 -30.359604)
		(width 0.1143)
		(layer "F.Cu")
		(net "USB2_PCH_BMC_P5_DN")
	)
	(segment
		(start 404.873968 -30.245304)
		(end 405.216868 -30.245304)
		(width 0.1143)
		(layer "F.Cu")
		(net "USB2_PCH_BMC_P5_DN")
	)
	(segment
		(start 410.093922 -118.250208)
		(end 412.09214 -118.250208)
		(width 0.1143)
		(layer "F.Cu")
		(net "USB2_PCH_BMC_P5_DN")
	)
	(segment
		(start 406.883108 -30.3276)
		(end 407.090118 -30.53461)
		(width 0.1143)
		(layer "F.Cu")
		(net "USB2_PCH_BMC_P5_DN")
	)
	(segment
		(start 404.416768 -30.359604)
		(end 404.759668 -30.359604)
		(width 0.1143)
		(layer "F.Cu")
		(net "USB2_PCH_BMC_P5_DN")
	)
	(segment
		(start 404.759668 -30.359604)
		(end 404.873968 -30.245304)
		(width 0.1143)
		(layer "F.Cu")
		(net "USB2_PCH_BMC_P5_DN")
	)
	(segment
		(start 403.502368 -30.359604)
		(end 403.845268 -30.359604)
		(width 0.1143)
		(layer "F.Cu")
		(net "USB2_PCH_BMC_P5_DN")
	)
	(segment
		(start 395.830044 -26.72842)
		(end 396.744444 -26.72842)
		(width 0.1143)
		(layer "F.Cu")
		(net "USB2_PCH_BMC_P5_DN")
	)
	(segment
		(start 406.272238 -30.3276)
		(end 406.883108 -30.3276)
		(width 0.1143)
		(layer "F.Cu")
		(net "USB2_PCH_BMC_P5_DN")
	)
	(segment
		(start 409.208478 -118.239032)
		(end 409.468574 -118.499128)
		(width 0.1143)
		(layer "F.Cu")
		(net "USB2_PCH_BMC_P5_DN")
	)
	(segment
		(start 409.468574 -118.499128)
		(end 409.845002 -118.499128)
		(width 0.1143)
		(layer "F.Cu")
		(net "USB2_PCH_BMC_P5_DN")
	)
	(segment
		(start 394.875258 -25.622758)
		(end 395.040358 -25.622758)
		(width 0.1143)
		(layer "F.Cu")
		(net "USB2_PCH_BMC_P5_DN")
	)
	(segment
		(start 401.025868 -30.245304)
		(end 402.473668 -30.245304)
		(width 0.1143)
		(layer "F.Cu")
		(net "USB2_PCH_BMC_P5_DN")
	)
	(segment
		(start 402.930868 -30.359604)
		(end 403.045168 -30.245304)
		(width 0.1143)
		(layer "F.Cu")
		(net "USB2_PCH_BMC_P5_DN")
	)
	(segment
		(start 405.674068 -30.359604)
		(end 405.788368 -30.245304)
		(width 0.1143)
		(layer "F.Cu")
		(net "USB2_PCH_BMC_P5_DN")
	)
	(segment
		(start 397.786098 -27.931872)
		(end 397.947896 -27.931872)
		(width 0.1143)
		(layer "F.Cu")
		(net "USB2_PCH_BMC_P5_DN")
	)
	(segment
		(start 406.189942 -30.245304)
		(end 406.272238 -30.3276)
		(width 0.1143)
		(layer "F.Cu")
		(net "USB2_PCH_BMC_P5_DN")
	)
	(segment
		(start 399.717514 -28.93695)
		(end 401.025868 -30.245304)
		(width 0.1143)
		(layer "F.Cu")
		(net "USB2_PCH_BMC_P5_DN")
	)
	(segment
		(start 405.216868 -30.245304)
		(end 405.331168 -30.359604)
		(width 0.1143)
		(layer "F.Cu")
		(net "USB2_PCH_BMC_P5_DN")
	)
	(segment
		(start 403.959568 -30.245304)
		(end 404.302468 -30.245304)
		(width 0.1143)
		(layer "F.Cu")
		(net "USB2_PCH_BMC_P5_DN")
	)
	(segment
		(start 412.09214 -118.250208)
		(end 412.432246 -117.910102)
		(width 0.1143)
		(layer "F.Cu")
		(net "USB2_PCH_BMC_P5_DN")
	)
	(segment
		(start 397.947896 -27.931872)
		(end 398.952974 -28.93695)
		(width 0.1143)
		(layer "F.Cu")
		(net "USB2_PCH_BMC_P5_DN")
	)
	(segment
		(start 403.045168 -30.245304)
		(end 403.388068 -30.245304)
		(width 0.1143)
		(layer "F.Cu")
		(net "USB2_PCH_BMC_P5_DN")
	)
	(segment
		(start 395.040358 -25.622758)
		(end 395.2367 -25.8191)
		(width 0.1143)
		(layer "F.Cu")
		(net "USB2_PCH_BMC_P5_DN")
	)
	(segment
		(start 395.2367 -25.8191)
		(end 395.2367 -26.135076)
		(width 0.1143)
		(layer "F.Cu")
		(net "USB2_PCH_BMC_P5_DN")
	)
	(segment
		(start 397.010128 -26.994104)
		(end 397.543782 -27.527758)
		(width 0.1143)
		(layer "F.Cu")
		(net "USB2_PCH_BMC_P5_DN")
	)
	(segment
		(start 405.331168 -30.359604)
		(end 405.674068 -30.359604)
		(width 0.1143)
		(layer "F.Cu")
		(net "USB2_PCH_BMC_P5_DN")
	)
	(segment
		(start 403.388068 -30.245304)
		(end 403.502368 -30.359604)
		(width 0.1143)
		(layer "F.Cu")
		(net "USB2_PCH_BMC_P5_DN")
	)
	(segment
		(start 396.744444 -26.72842)
		(end 397.010128 -26.994104)
		(width 0.1143)
		(layer "F.Cu")
		(net "USB2_PCH_BMC_P5_DN")
	)
	(segment
		(start 398.952974 -28.93695)
		(end 399.717514 -28.93695)
		(width 0.1143)
		(layer "F.Cu")
		(net "USB2_PCH_BMC_P5_DN")
	)
	(segment
		(start 397.543782 -27.527758)
		(end 397.543782 -27.689302)
		(width 0.1143)
		(layer "F.Cu")
		(net "USB2_PCH_BMC_P5_DN")
	)
	(segment
		(start 397.543782 -27.689302)
		(end 397.786098 -27.931872)
		(width 0.1143)
		(layer "F.Cu")
		(net "USB2_PCH_BMC_P5_DN")
	)
	(via
		(at 412.432246 -117.910102)
		(size 0.508)
		(drill 0.254)
		(layers "F.Cu" "B.Cu")
		(net "USB2_PCH_BMC_P5_DN")
	)
	(via
		(at 394.875258 -25.622758)
		(size 0.508)
		(drill 0.254)
		(layers "F.Cu" "B.Cu")
		(net "USB2_PCH_BMC_P5_DN")
	)
	(via
		(at 397.010128 -26.994104)
		(size 0.508)
		(drill 0.254)
		(layers "F.Cu" "B.Cu")
		(net "USB2_PCH_BMC_P5_DN")
	)
	(segment
		(start 396.32255 -30.668722)
		(end 396.051278 -30.39745)
		(width 0.1143)
		(layer "In11.Cu")
		(net "USB2_PCH_BMC_P5_DN")
	)
	(segment
		(start 415.9631 -57.806336)
		(end 414.684464 -56.5277)
		(width 0.1143)
		(layer "In11.Cu")
		(net "USB2_PCH_BMC_P5_DN")
	)
	(segment
		(start 397.462502 -40.67556)
		(end 396.375382 -39.58844)
		(width 0.1143)
		(layer "In11.Cu")
		(net "USB2_PCH_BMC_P5_DN")
	)
	(segment
		(start 416.7251 -94.724728)
		(end 417.02355 -94.426278)
		(width 0.1143)
		(layer "In11.Cu")
		(net "USB2_PCH_BMC_P5_DN")
	)
	(segment
		(start 417.563554 -93.721428)
		(end 417.563554 -89.915492)
		(width 0.1143)
		(layer "In11.Cu")
		(net "USB2_PCH_BMC_P5_DN")
	)
	(segment
		(start 395.903704 -30.39745)
		(end 394.8176 -29.311346)
		(width 0.1143)
		(layer "In11.Cu")
		(net "USB2_PCH_BMC_P5_DN")
	)
	(segment
		(start 397.462502 -42.201592)
		(end 397.462502 -40.67556)
		(width 0.1143)
		(layer "In11.Cu")
		(net "USB2_PCH_BMC_P5_DN")
	)
	(segment
		(start 413.113474 -56.5277)
		(end 412.439866 -55.854092)
		(width 0.1143)
		(layer "In11.Cu")
		(net "USB2_PCH_BMC_P5_DN")
	)
	(segment
		(start 396.273782 -34.644076)
		(end 396.273782 -31.102046)
		(width 0.1143)
		(layer "In11.Cu")
		(net "USB2_PCH_BMC_P5_DN")
	)
	(segment
		(start 405.727662 -51.448716)
		(end 403.334728 -51.448716)
		(width 0.1143)
		(layer "In11.Cu")
		(net "USB2_PCH_BMC_P5_DN")
	)
	(segment
		(start 406.882346 -52.6034)
		(end 405.727662 -51.448716)
		(width 0.1143)
		(layer "In11.Cu")
		(net "USB2_PCH_BMC_P5_DN")
	)
	(segment
		(start 395.1732 -26.307542)
		(end 395.1732 -25.9207)
		(width 0.1143)
		(layer "In11.Cu")
		(net "USB2_PCH_BMC_P5_DN")
	)
	(segment
		(start 396.375382 -34.745676)
		(end 396.273782 -34.644076)
		(width 0.1143)
		(layer "In11.Cu")
		(net "USB2_PCH_BMC_P5_DN")
	)
	(segment
		(start 394.6525 -27.171142)
		(end 394.8176 -27.006042)
		(width 0.1143)
		(layer "In11.Cu")
		(net "USB2_PCH_BMC_P5_DN")
	)
	(segment
		(start 396.210282 -37.30498)
		(end 396.375382 -37.13988)
		(width 0.1143)
		(layer "In11.Cu")
		(net "USB2_PCH_BMC_P5_DN")
	)
	(segment
		(start 396.210282 -36.63188)
		(end 396.210282 -36.28898)
		(width 0.1143)
		(layer "In11.Cu")
		(net "USB2_PCH_BMC_P5_DN")
	)
	(segment
		(start 412.439866 -55.346092)
		(end 409.697428 -52.6034)
		(width 0.1143)
		(layer "In11.Cu")
		(net "USB2_PCH_BMC_P5_DN")
	)
	(segment
		(start 394.6525 -28.530042)
		(end 394.6525 -28.187142)
		(width 0.1143)
		(layer "In11.Cu")
		(net "USB2_PCH_BMC_P5_DN")
	)
	(segment
		(start 394.8176 -29.311346)
		(end 394.8176 -28.695142)
		(width 0.1143)
		(layer "In11.Cu")
		(net "USB2_PCH_BMC_P5_DN")
	)
	(segment
		(start 417.841938 -71.16445)
		(end 417.2331 -70.555612)
		(width 0.1143)
		(layer "In11.Cu")
		(net "USB2_PCH_BMC_P5_DN")
	)
	(segment
		(start 415.9631 -60.370212)
		(end 415.9631 -57.806336)
		(width 0.1143)
		(layer "In11.Cu")
		(net "USB2_PCH_BMC_P5_DN")
	)
	(segment
		(start 416.687 -61.094112)
		(end 415.9631 -60.370212)
		(width 0.1143)
		(layer "In11.Cu")
		(net "USB2_PCH_BMC_P5_DN")
	)
	(segment
		(start 417.02355 -94.262448)
		(end 417.563554 -93.721428)
		(width 0.1143)
		(layer "In11.Cu")
		(net "USB2_PCH_BMC_P5_DN")
	)
	(segment
		(start 416.7251 -107.8357)
		(end 416.7251 -94.724728)
		(width 0.1143)
		(layer "In11.Cu")
		(net "USB2_PCH_BMC_P5_DN")
	)
	(segment
		(start 417.841938 -80.87487)
		(end 417.841938 -71.16445)
		(width 0.1143)
		(layer "In11.Cu")
		(net "USB2_PCH_BMC_P5_DN")
	)
	(segment
		(start 417.563554 -89.915492)
		(end 417.96335 -89.515696)
		(width 0.1143)
		(layer "In11.Cu")
		(net "USB2_PCH_BMC_P5_DN")
	)
	(segment
		(start 416.687 -62.948058)
		(end 416.687 -61.094112)
		(width 0.1143)
		(layer "In11.Cu")
		(net "USB2_PCH_BMC_P5_DN")
	)
	(segment
		(start 394.8176 -27.679142)
		(end 394.6525 -27.514042)
		(width 0.1143)
		(layer "In11.Cu")
		(net "USB2_PCH_BMC_P5_DN")
	)
	(segment
		(start 414.909 -116.525294)
		(end 414.909 -111.473742)
		(width 0.1143)
		(layer "In11.Cu")
		(net "USB2_PCH_BMC_P5_DN")
	)
	(segment
		(start 412.716218 -118.189502)
		(end 413.96412 -116.9416)
		(width 0.1143)
		(layer "In11.Cu")
		(net "USB2_PCH_BMC_P5_DN")
	)
	(segment
		(start 417.96335 -86.954868)
		(end 417.442142 -86.43366)
		(width 0.1143)
		(layer "In11.Cu")
		(net "USB2_PCH_BMC_P5_DN")
	)
	(segment
		(start 396.375382 -36.79698)
		(end 396.210282 -36.63188)
		(width 0.1143)
		(layer "In11.Cu")
		(net "USB2_PCH_BMC_P5_DN")
	)
	(segment
		(start 417.2331 -70.555612)
		(end 417.2331 -63.494158)
		(width 0.1143)
		(layer "In11.Cu")
		(net "USB2_PCH_BMC_P5_DN")
	)
	(segment
		(start 417.442142 -86.43366)
		(end 417.442142 -81.274666)
		(width 0.1143)
		(layer "In11.Cu")
		(net "USB2_PCH_BMC_P5_DN")
	)
	(segment
		(start 415.39795 -110.984792)
		(end 415.39795 -109.16285)
		(width 0.1143)
		(layer "In11.Cu")
		(net "USB2_PCH_BMC_P5_DN")
	)
	(segment
		(start 413.96412 -116.9416)
		(end 414.492694 -116.9416)
		(width 0.1143)
		(layer "In11.Cu")
		(net "USB2_PCH_BMC_P5_DN")
	)
	(segment
		(start 394.8176 -28.022042)
		(end 394.8176 -27.679142)
		(width 0.1143)
		(layer "In11.Cu")
		(net "USB2_PCH_BMC_P5_DN")
	)
	(segment
		(start 415.39795 -109.16285)
		(end 416.7251 -107.8357)
		(width 0.1143)
		(layer "In11.Cu")
		(net "USB2_PCH_BMC_P5_DN")
	)
	(segment
		(start 396.210282 -37.64788)
		(end 396.210282 -37.30498)
		(width 0.1143)
		(layer "In11.Cu")
		(net "USB2_PCH_BMC_P5_DN")
	)
	(segment
		(start 414.684464 -56.5277)
		(end 413.113474 -56.5277)
		(width 0.1143)
		(layer "In11.Cu")
		(net "USB2_PCH_BMC_P5_DN")
	)
	(segment
		(start 409.697428 -52.6034)
		(end 406.882346 -52.6034)
		(width 0.1143)
		(layer "In11.Cu")
		(net "USB2_PCH_BMC_P5_DN")
	)
	(segment
		(start 394.6525 -27.514042)
		(end 394.6525 -27.171142)
		(width 0.1143)
		(layer "In11.Cu")
		(net "USB2_PCH_BMC_P5_DN")
	)
	(segment
		(start 414.909 -111.473742)
		(end 415.39795 -110.984792)
		(width 0.1143)
		(layer "In11.Cu")
		(net "USB2_PCH_BMC_P5_DN")
	)
	(segment
		(start 394.8176 -28.695142)
		(end 394.6525 -28.530042)
		(width 0.1143)
		(layer "In11.Cu")
		(net "USB2_PCH_BMC_P5_DN")
	)
	(segment
		(start 396.32255 -31.053278)
		(end 396.32255 -30.668722)
		(width 0.1143)
		(layer "In11.Cu")
		(net "USB2_PCH_BMC_P5_DN")
	)
	(segment
		(start 396.375382 -36.12388)
		(end 396.375382 -34.745676)
		(width 0.1143)
		(layer "In11.Cu")
		(net "USB2_PCH_BMC_P5_DN")
	)
	(segment
		(start 403.334728 -51.448716)
		(end 401.0152 -49.129188)
		(width 0.1143)
		(layer "In11.Cu")
		(net "USB2_PCH_BMC_P5_DN")
	)
	(segment
		(start 414.492694 -116.9416)
		(end 414.909 -116.525294)
		(width 0.1143)
		(layer "In11.Cu")
		(net "USB2_PCH_BMC_P5_DN")
	)
	(segment
		(start 394.8176 -26.663142)
		(end 395.1732 -26.307542)
		(width 0.1143)
		(layer "In11.Cu")
		(net "USB2_PCH_BMC_P5_DN")
	)
	(segment
		(start 401.0152 -45.75429)
		(end 397.462502 -42.201592)
		(width 0.1143)
		(layer "In11.Cu")
		(net "USB2_PCH_BMC_P5_DN")
	)
	(segment
		(start 417.442142 -81.274666)
		(end 417.841938 -80.87487)
		(width 0.1143)
		(layer "In11.Cu")
		(net "USB2_PCH_BMC_P5_DN")
	)
	(segment
		(start 412.432246 -117.910102)
		(end 412.432246 -118.085108)
		(width 0.1143)
		(layer "In11.Cu")
		(net "USB2_PCH_BMC_P5_DN")
	)
	(segment
		(start 394.8176 -27.006042)
		(end 394.8176 -26.663142)
		(width 0.1143)
		(layer "In11.Cu")
		(net "USB2_PCH_BMC_P5_DN")
	)
	(segment
		(start 412.53664 -118.189502)
		(end 412.716218 -118.189502)
		(width 0.1143)
		(layer "In11.Cu")
		(net "USB2_PCH_BMC_P5_DN")
	)
	(segment
		(start 396.375382 -39.58844)
		(end 396.375382 -37.81298)
		(width 0.1143)
		(layer "In11.Cu")
		(net "USB2_PCH_BMC_P5_DN")
	)
	(segment
		(start 395.1732 -25.9207)
		(end 394.875258 -25.622758)
		(width 0.1143)
		(layer "In11.Cu")
		(net "USB2_PCH_BMC_P5_DN")
	)
	(segment
		(start 396.375382 -37.81298)
		(end 396.210282 -37.64788)
		(width 0.1143)
		(layer "In11.Cu")
		(net "USB2_PCH_BMC_P5_DN")
	)
	(segment
		(start 396.210282 -36.28898)
		(end 396.375382 -36.12388)
		(width 0.1143)
		(layer "In11.Cu")
		(net "USB2_PCH_BMC_P5_DN")
	)
	(segment
		(start 396.375382 -37.13988)
		(end 396.375382 -36.79698)
		(width 0.1143)
		(layer "In11.Cu")
		(net "USB2_PCH_BMC_P5_DN")
	)
	(segment
		(start 412.432246 -118.085108)
		(end 412.53664 -118.189502)
		(width 0.1143)
		(layer "In11.Cu")
		(net "USB2_PCH_BMC_P5_DN")
	)
	(segment
		(start 396.051278 -30.39745)
		(end 395.903704 -30.39745)
		(width 0.1143)
		(layer "In11.Cu")
		(net "USB2_PCH_BMC_P5_DN")
	)
	(segment
		(start 401.0152 -49.129188)
		(end 401.0152 -45.75429)
		(width 0.1143)
		(layer "In11.Cu")
		(net "USB2_PCH_BMC_P5_DN")
	)
	(segment
		(start 396.273782 -31.102046)
		(end 396.32255 -31.053278)
		(width 0.1143)
		(layer "In11.Cu")
		(net "USB2_PCH_BMC_P5_DN")
	)
	(segment
		(start 394.6525 -28.187142)
		(end 394.8176 -28.022042)
		(width 0.1143)
		(layer "In11.Cu")
		(net "USB2_PCH_BMC_P5_DN")
	)
	(segment
		(start 417.02355 -94.426278)
		(end 417.02355 -94.262448)
		(width 0.1143)
		(layer "In11.Cu")
		(net "USB2_PCH_BMC_P5_DN")
	)
	(segment
		(start 412.439866 -55.854092)
		(end 412.439866 -55.346092)
		(width 0.1143)
		(layer "In11.Cu")
		(net "USB2_PCH_BMC_P5_DN")
	)
	(segment
		(start 417.2331 -63.494158)
		(end 416.687 -62.948058)
		(width 0.1143)
		(layer "In11.Cu")
		(net "USB2_PCH_BMC_P5_DN")
	)
	(segment
		(start 417.96335 -89.515696)
		(end 417.96335 -86.954868)
		(width 0.1143)
		(layer "In11.Cu")
		(net "USB2_PCH_BMC_P5_DN")
	)
	(segment
		(start 399.208752 -31.375604)
		(end 403.067266 -31.375604)
		(width 0.1143)
		(layer "F.Cu")
		(net "USB_PCH_BMC_P4_DP")
	)
	(segment
		(start 396.80515 -32.61995)
		(end 396.2654 -32.0802)
		(width 0.1143)
		(layer "F.Cu")
		(net "USB_PCH_BMC_P4_DP")
	)
	(segment
		(start 410.5275 -121.204482)
		(end 410.456634 -121.133616)
		(width 0.1143)
		(layer "F.Cu")
		(net "USB_PCH_BMC_P4_DP")
	)
	(segment
		(start 408.924252 -122.296936)
		(end 409.193746 -122.296936)
		(width 0.1143)
		(layer "F.Cu")
		(net "USB_PCH_BMC_P4_DP")
	)
	(segment
		(start 406.814528 -31.6103)
		(end 407.090118 -31.33471)
		(width 0.1143)
		(layer "F.Cu")
		(net "USB_PCH_BMC_P4_DP")
	)
	(segment
		(start 398.650968 -31.933388)
		(end 397.964406 -32.61995)
		(width 0.1143)
		(layer "F.Cu")
		(net "USB_PCH_BMC_P4_DP")
	)
	(segment
		(start 395.7574 -31.7881)
		(end 395.7574 -31.604458)
		(width 0.1143)
		(layer "F.Cu")
		(net "USB_PCH_BMC_P4_DP")
	)
	(segment
		(start 410.064204 -121.09196)
		(end 409.956 -120.97131)
		(width 0.1143)
		(layer "F.Cu")
		(net "USB_PCH_BMC_P4_DP")
	)
	(segment
		(start 409.934664 -121.556018)
		(end 410.4132 -121.556018)
		(width 0.1143)
		(layer "F.Cu")
		(net "USB_PCH_BMC_P4_DP")
	)
	(segment
		(start 409.37307 -122.117612)
		(end 409.37307 -121.955814)
		(width 0.1143)
		(layer "F.Cu")
		(net "USB_PCH_BMC_P4_DP")
	)
	(segment
		(start 398.650968 -31.933388)
		(end 399.208752 -31.375604)
		(width 0.1143)
		(layer "F.Cu")
		(net "USB_PCH_BMC_P4_DP")
	)
	(segment
		(start 396.2654 -32.0802)
		(end 396.0495 -32.0802)
		(width 0.1143)
		(layer "F.Cu")
		(net "USB_PCH_BMC_P4_DP")
	)
	(segment
		(start 396.0495 -32.0802)
		(end 395.7574 -31.7881)
		(width 0.1143)
		(layer "F.Cu")
		(net "USB_PCH_BMC_P4_DP")
	)
	(segment
		(start 405.06142 -31.477204)
		(end 406.34285 -31.477204)
		(width 0.1143)
		(layer "F.Cu")
		(net "USB_PCH_BMC_P4_DP")
	)
	(segment
		(start 406.475946 -31.6103)
		(end 406.814528 -31.6103)
		(width 0.1143)
		(layer "F.Cu")
		(net "USB_PCH_BMC_P4_DP")
	)
	(segment
		(start 403.499828 -31.808166)
		(end 404.730458 -31.808166)
		(width 0.1143)
		(layer "F.Cu")
		(net "USB_PCH_BMC_P4_DP")
	)
	(segment
		(start 410.5275 -121.441718)
		(end 410.5275 -121.204482)
		(width 0.1143)
		(layer "F.Cu")
		(net "USB_PCH_BMC_P4_DP")
	)
	(segment
		(start 397.964406 -32.61995)
		(end 396.80515 -32.61995)
		(width 0.1143)
		(layer "F.Cu")
		(net "USB_PCH_BMC_P4_DP")
	)
	(segment
		(start 409.193746 -122.296936)
		(end 409.37307 -122.117612)
		(width 0.1143)
		(layer "F.Cu")
		(net "USB_PCH_BMC_P4_DP")
	)
	(segment
		(start 409.777184 -121.713498)
		(end 409.934664 -121.556018)
		(width 0.1143)
		(layer "F.Cu")
		(net "USB_PCH_BMC_P4_DP")
	)
	(segment
		(start 403.067266 -31.375604)
		(end 403.499828 -31.808166)
		(width 0.1143)
		(layer "F.Cu")
		(net "USB_PCH_BMC_P4_DP")
	)
	(segment
		(start 408.638502 -122.011186)
		(end 408.924252 -122.296936)
		(width 0.1143)
		(layer "F.Cu")
		(net "USB_PCH_BMC_P4_DP")
	)
	(segment
		(start 404.730458 -31.808166)
		(end 405.06142 -31.477204)
		(width 0.1143)
		(layer "F.Cu")
		(net "USB_PCH_BMC_P4_DP")
	)
	(segment
		(start 406.34285 -31.477204)
		(end 406.475946 -31.6103)
		(width 0.1143)
		(layer "F.Cu")
		(net "USB_PCH_BMC_P4_DP")
	)
	(segment
		(start 410.4132 -121.556018)
		(end 410.5275 -121.441718)
		(width 0.1143)
		(layer "F.Cu")
		(net "USB_PCH_BMC_P4_DP")
	)
	(segment
		(start 410.456634 -121.133616)
		(end 410.064204 -121.09196)
		(width 0.1143)
		(layer "F.Cu")
		(net "USB_PCH_BMC_P4_DP")
	)
	(segment
		(start 409.956 -120.97131)
		(end 409.956 -120.89638)
		(width 0.1143)
		(layer "F.Cu")
		(net "USB_PCH_BMC_P4_DP")
	)
	(segment
		(start 409.615386 -121.713498)
		(end 409.777184 -121.713498)
		(width 0.1143)
		(layer "F.Cu")
		(net "USB_PCH_BMC_P4_DP")
	)
	(segment
		(start 409.37307 -121.955814)
		(end 409.615386 -121.713498)
		(width 0.1143)
		(layer "F.Cu")
		(net "USB_PCH_BMC_P4_DP")
	)
	(via
		(at 409.956 -120.89638)
		(size 0.508)
		(drill 0.254)
		(layers "F.Cu" "B.Cu")
		(net "USB_PCH_BMC_P4_DP")
	)
	(via
		(at 398.650968 -31.933388)
		(size 0.508)
		(drill 0.254)
		(layers "F.Cu" "B.Cu")
		(net "USB_PCH_BMC_P4_DP")
	)
	(via
		(at 395.7574 -31.604458)
		(size 0.508)
		(drill 0.254)
		(layers "F.Cu" "B.Cu")
		(net "USB_PCH_BMC_P4_DP")
	)
	(segment
		(start 401.889722 -53.45938)
		(end 402.833078 -53.45938)
		(width 0.1143)
		(layer "In11.Cu")
		(net "USB_PCH_BMC_P4_DP")
	)
	(segment
		(start 403.255988 -53.03647)
		(end 405.05507 -53.03647)
		(width 0.1143)
		(layer "In11.Cu")
		(net "USB_PCH_BMC_P4_DP")
	)
	(segment
		(start 414.755584 -83.056984)
		(end 414.755584 -83.816698)
		(width 0.1143)
		(layer "In11.Cu")
		(net "USB_PCH_BMC_P4_DP")
	)
	(segment
		(start 409.5115 -116.3574)
		(end 408.912568 -116.3574)
		(width 0.1143)
		(layer "In11.Cu")
		(net "USB_PCH_BMC_P4_DP")
	)
	(segment
		(start 393.898882 -37.216842)
		(end 393.898882 -39.109904)
		(width 0.1143)
		(layer "In11.Cu")
		(net "USB_PCH_BMC_P4_DP")
	)
	(segment
		(start 412.845504 -87.987886)
		(end 414.726882 -89.869264)
		(width 0.1143)
		(layer "In11.Cu")
		(net "USB_PCH_BMC_P4_DP")
	)
	(segment
		(start 408.912568 -116.3574)
		(end 408.087576 -117.182392)
		(width 0.1143)
		(layer "In11.Cu")
		(net "USB_PCH_BMC_P4_DP")
	)
	(segment
		(start 410.2354 -115.6335)
		(end 409.5115 -116.3574)
		(width 0.1143)
		(layer "In11.Cu")
		(net "USB_PCH_BMC_P4_DP")
	)
	(segment
		(start 398.399254 -45.728636)
		(end 398.399254 -46.412658)
		(width 0.1143)
		(layer "In11.Cu")
		(net "USB_PCH_BMC_P4_DP")
	)
	(segment
		(start 413.29483 -104.395016)
		(end 413.29483 -109.405166)
		(width 0.1143)
		(layer "In11.Cu")
		(net "USB_PCH_BMC_P4_DP")
	)
	(segment
		(start 412.328868 -110.371128)
		(end 412.328868 -114.873278)
		(width 0.1143)
		(layer "In11.Cu")
		(net "USB_PCH_BMC_P4_DP")
	)
	(segment
		(start 414.3248 -60.0456)
		(end 414.3248 -66.0654)
		(width 0.1143)
		(layer "In11.Cu")
		(net "USB_PCH_BMC_P4_DP")
	)
	(segment
		(start 415.56051 -80.55229)
		(end 414.6042 -81.5086)
		(width 0.1143)
		(layer "In11.Cu")
		(net "USB_PCH_BMC_P4_DP")
	)
	(segment
		(start 397.539972 -45.314362)
		(end 397.98498 -45.314362)
		(width 0.1143)
		(layer "In11.Cu")
		(net "USB_PCH_BMC_P4_DP")
	)
	(segment
		(start 416.267138 -77.680058)
		(end 415.56051 -78.386686)
		(width 0.1143)
		(layer "In11.Cu")
		(net "USB_PCH_BMC_P4_DP")
	)
	(segment
		(start 399.4404 -51.010058)
		(end 401.889722 -53.45938)
		(width 0.1143)
		(layer "In11.Cu")
		(net "USB_PCH_BMC_P4_DP")
	)
	(segment
		(start 392.783314 -36.101274)
		(end 393.898882 -37.216842)
		(width 0.1143)
		(layer "In11.Cu")
		(net "USB_PCH_BMC_P4_DP")
	)
	(segment
		(start 408.087576 -117.182392)
		(end 408.087576 -119.086376)
		(width 0.1143)
		(layer "In11.Cu")
		(net "USB_PCH_BMC_P4_DP")
	)
	(segment
		(start 397.98498 -45.314362)
		(end 398.399254 -45.728636)
		(width 0.1143)
		(layer "In11.Cu")
		(net "USB_PCH_BMC_P4_DP")
	)
	(segment
		(start 415.56051 -78.386686)
		(end 415.56051 -80.55229)
		(width 0.1143)
		(layer "In11.Cu")
		(net "USB_PCH_BMC_P4_DP")
	)
	(segment
		(start 412.845504 -85.726778)
		(end 412.845504 -87.987886)
		(width 0.1143)
		(layer "In11.Cu")
		(net "USB_PCH_BMC_P4_DP")
	)
	(segment
		(start 402.833078 -53.45938)
		(end 403.255988 -53.03647)
		(width 0.1143)
		(layer "In11.Cu")
		(net "USB_PCH_BMC_P4_DP")
	)
	(segment
		(start 413.5755 -59.2963)
		(end 414.3248 -60.0456)
		(width 0.1143)
		(layer "In11.Cu")
		(net "USB_PCH_BMC_P4_DP")
	)
	(segment
		(start 394.75664 -43.252898)
		(end 396.280132 -43.252898)
		(width 0.1143)
		(layer "In11.Cu")
		(net "USB_PCH_BMC_P4_DP")
	)
	(segment
		(start 412.328868 -114.873278)
		(end 411.568646 -115.6335)
		(width 0.1143)
		(layer "In11.Cu")
		(net "USB_PCH_BMC_P4_DP")
	)
	(segment
		(start 392.783314 -32.916876)
		(end 392.783314 -36.101274)
		(width 0.1143)
		(layer "In11.Cu")
		(net "USB_PCH_BMC_P4_DP")
	)
	(segment
		(start 415.308542 -72.677274)
		(end 415.987992 -72.677274)
		(width 0.1143)
		(layer "In11.Cu")
		(net "USB_PCH_BMC_P4_DP")
	)
	(segment
		(start 416.267138 -72.95642)
		(end 416.267138 -77.680058)
		(width 0.1143)
		(layer "In11.Cu")
		(net "USB_PCH_BMC_P4_DP")
	)
	(segment
		(start 414.9217 -66.6623)
		(end 414.9217 -72.290432)
		(width 0.1143)
		(layer "In11.Cu")
		(net "USB_PCH_BMC_P4_DP")
	)
	(segment
		(start 393.739116 -42.235374)
		(end 394.75664 -43.252898)
		(width 0.1143)
		(layer "In11.Cu")
		(net "USB_PCH_BMC_P4_DP")
	)
	(segment
		(start 409.062428 -120.061228)
		(end 410.122624 -120.061228)
		(width 0.1143)
		(layer "In11.Cu")
		(net "USB_PCH_BMC_P4_DP")
	)
	(segment
		(start 395.7574 -31.604458)
		(end 395.326108 -32.03575)
		(width 0.1143)
		(layer "In11.Cu")
		(net "USB_PCH_BMC_P4_DP")
	)
	(segment
		(start 396.280132 -43.252898)
		(end 397.177006 -44.149772)
		(width 0.1143)
		(layer "In11.Cu")
		(net "USB_PCH_BMC_P4_DP")
	)
	(segment
		(start 408.087576 -119.086376)
		(end 409.062428 -120.061228)
		(width 0.1143)
		(layer "In11.Cu")
		(net "USB_PCH_BMC_P4_DP")
	)
	(segment
		(start 414.755584 -83.816698)
		(end 412.845504 -85.726778)
		(width 0.1143)
		(layer "In11.Cu")
		(net "USB_PCH_BMC_P4_DP")
	)
	(segment
		(start 405.05507 -53.03647)
		(end 411.3149 -59.2963)
		(width 0.1143)
		(layer "In11.Cu")
		(net "USB_PCH_BMC_P4_DP")
	)
	(segment
		(start 414.726882 -102.962964)
		(end 413.29483 -104.395016)
		(width 0.1143)
		(layer "In11.Cu")
		(net "USB_PCH_BMC_P4_DP")
	)
	(segment
		(start 397.177006 -44.149772)
		(end 397.177006 -44.951396)
		(width 0.1143)
		(layer "In11.Cu")
		(net "USB_PCH_BMC_P4_DP")
	)
	(segment
		(start 410.268928 -120.583452)
		(end 409.956 -120.89638)
		(width 0.1143)
		(layer "In11.Cu")
		(net "USB_PCH_BMC_P4_DP")
	)
	(segment
		(start 399.4404 -47.453804)
		(end 399.4404 -51.010058)
		(width 0.1143)
		(layer "In11.Cu")
		(net "USB_PCH_BMC_P4_DP")
	)
	(segment
		(start 410.268928 -120.207532)
		(end 410.268928 -120.583452)
		(width 0.1143)
		(layer "In11.Cu")
		(net "USB_PCH_BMC_P4_DP")
	)
	(segment
		(start 414.9217 -72.290432)
		(end 415.308542 -72.677274)
		(width 0.1143)
		(layer "In11.Cu")
		(net "USB_PCH_BMC_P4_DP")
	)
	(segment
		(start 414.3248 -66.0654)
		(end 414.9217 -66.6623)
		(width 0.1143)
		(layer "In11.Cu")
		(net "USB_PCH_BMC_P4_DP")
	)
	(segment
		(start 393.898882 -39.109904)
		(end 393.739116 -39.26967)
		(width 0.1143)
		(layer "In11.Cu")
		(net "USB_PCH_BMC_P4_DP")
	)
	(segment
		(start 415.987992 -72.677274)
		(end 416.267138 -72.95642)
		(width 0.1143)
		(layer "In11.Cu")
		(net "USB_PCH_BMC_P4_DP")
	)
	(segment
		(start 413.29483 -109.405166)
		(end 412.328868 -110.371128)
		(width 0.1143)
		(layer "In11.Cu")
		(net "USB_PCH_BMC_P4_DP")
	)
	(segment
		(start 414.6042 -82.9056)
		(end 414.755584 -83.056984)
		(width 0.1143)
		(layer "In11.Cu")
		(net "USB_PCH_BMC_P4_DP")
	)
	(segment
		(start 393.66444 -32.03575)
		(end 392.783314 -32.916876)
		(width 0.1143)
		(layer "In11.Cu")
		(net "USB_PCH_BMC_P4_DP")
	)
	(segment
		(start 397.177006 -44.951396)
		(end 397.539972 -45.314362)
		(width 0.1143)
		(layer "In11.Cu")
		(net "USB_PCH_BMC_P4_DP")
	)
	(segment
		(start 411.3149 -59.2963)
		(end 413.5755 -59.2963)
		(width 0.1143)
		(layer "In11.Cu")
		(net "USB_PCH_BMC_P4_DP")
	)
	(segment
		(start 411.568646 -115.6335)
		(end 410.2354 -115.6335)
		(width 0.1143)
		(layer "In11.Cu")
		(net "USB_PCH_BMC_P4_DP")
	)
	(segment
		(start 414.6042 -81.5086)
		(end 414.6042 -82.9056)
		(width 0.1143)
		(layer "In11.Cu")
		(net "USB_PCH_BMC_P4_DP")
	)
	(segment
		(start 393.739116 -39.26967)
		(end 393.739116 -42.235374)
		(width 0.1143)
		(layer "In11.Cu")
		(net "USB_PCH_BMC_P4_DP")
	)
	(segment
		(start 395.326108 -32.03575)
		(end 393.66444 -32.03575)
		(width 0.1143)
		(layer "In11.Cu")
		(net "USB_PCH_BMC_P4_DP")
	)
	(segment
		(start 410.122624 -120.061228)
		(end 410.268928 -120.207532)
		(width 0.1143)
		(layer "In11.Cu")
		(net "USB_PCH_BMC_P4_DP")
	)
	(segment
		(start 398.399254 -46.412658)
		(end 399.4404 -47.453804)
		(width 0.1143)
		(layer "In11.Cu")
		(net "USB_PCH_BMC_P4_DP")
	)
	(segment
		(start 414.726882 -89.869264)
		(end 414.726882 -102.962964)
		(width 0.1143)
		(layer "In11.Cu")
		(net "USB_PCH_BMC_P4_DP")
	)
	(segment
		(start 406.37587 -31.8516)
		(end 406.242774 -31.718504)
		(width 0.1143)
		(layer "F.Cu")
		(net "USB_PCH_BMC_P4_DN")
	)
	(segment
		(start 408.924252 -122.538236)
		(end 409.293822 -122.538236)
		(width 0.1143)
		(layer "F.Cu")
		(net "USB_PCH_BMC_P4_DN")
	)
	(segment
		(start 402.96719 -31.616904)
		(end 399.308828 -31.616904)
		(width 0.1143)
		(layer "F.Cu")
		(net "USB_PCH_BMC_P4_DN")
	)
	(segment
		(start 406.807162 -31.8516)
		(end 406.37587 -31.8516)
		(width 0.1143)
		(layer "F.Cu")
		(net "USB_PCH_BMC_P4_DN")
	)
	(segment
		(start 410.513276 -121.797318)
		(end 410.8958 -121.414794)
		(width 0.1143)
		(layer "F.Cu")
		(net "USB_PCH_BMC_P4_DN")
	)
	(segment
		(start 410.03474 -121.797318)
		(end 410.513276 -121.797318)
		(width 0.1143)
		(layer "F.Cu")
		(net "USB_PCH_BMC_P4_DN")
	)
	(segment
		(start 406.242774 -31.718504)
		(end 405.161496 -31.718504)
		(width 0.1143)
		(layer "F.Cu")
		(net "USB_PCH_BMC_P4_DN")
	)
	(segment
		(start 405.161496 -31.718504)
		(end 404.830534 -32.049466)
		(width 0.1143)
		(layer "F.Cu")
		(net "USB_PCH_BMC_P4_DN")
	)
	(segment
		(start 399.308828 -31.616904)
		(end 398.064482 -32.86125)
		(width 0.1143)
		(layer "F.Cu")
		(net "USB_PCH_BMC_P4_DN")
	)
	(segment
		(start 404.830534 -32.049466)
		(end 403.399752 -32.049466)
		(width 0.1143)
		(layer "F.Cu")
		(net "USB_PCH_BMC_P4_DN")
	)
	(segment
		(start 395.7574 -32.513524)
		(end 395.949424 -32.3215)
		(width 0.1143)
		(layer "F.Cu")
		(net "USB_PCH_BMC_P4_DN")
	)
	(segment
		(start 409.293822 -122.538236)
		(end 410.03474 -121.797318)
		(width 0.1143)
		(layer "F.Cu")
		(net "USB_PCH_BMC_P4_DN")
	)
	(segment
		(start 396.705074 -32.86125)
		(end 397.530066 -32.86125)
		(width 0.1143)
		(layer "F.Cu")
		(net "USB_PCH_BMC_P4_DN")
	)
	(segment
		(start 395.7574 -32.747204)
		(end 395.7574 -32.513524)
		(width 0.1143)
		(layer "F.Cu")
		(net "USB_PCH_BMC_P4_DN")
	)
	(segment
		(start 407.090118 -32.134556)
		(end 406.807162 -31.8516)
		(width 0.1143)
		(layer "F.Cu")
		(net "USB_PCH_BMC_P4_DN")
	)
	(segment
		(start 408.638502 -122.823986)
		(end 408.924252 -122.538236)
		(width 0.1143)
		(layer "F.Cu")
		(net "USB_PCH_BMC_P4_DN")
	)
	(segment
		(start 396.165324 -32.3215)
		(end 396.705074 -32.86125)
		(width 0.1143)
		(layer "F.Cu")
		(net "USB_PCH_BMC_P4_DN")
	)
	(segment
		(start 410.8958 -121.414794)
		(end 410.8958 -120.893078)
		(width 0.1143)
		(layer "F.Cu")
		(net "USB_PCH_BMC_P4_DN")
	)
	(segment
		(start 395.949424 -32.3215)
		(end 396.165324 -32.3215)
		(width 0.1143)
		(layer "F.Cu")
		(net "USB_PCH_BMC_P4_DN")
	)
	(segment
		(start 398.064482 -32.86125)
		(end 397.530066 -32.86125)
		(width 0.1143)
		(layer "F.Cu")
		(net "USB_PCH_BMC_P4_DN")
	)
	(segment
		(start 403.399752 -32.049466)
		(end 402.96719 -31.616904)
		(width 0.1143)
		(layer "F.Cu")
		(net "USB_PCH_BMC_P4_DN")
	)
	(via
		(at 395.7574 -32.747204)
		(size 0.508)
		(drill 0.254)
		(layers "F.Cu" "B.Cu")
		(net "USB_PCH_BMC_P4_DN")
	)
	(via
		(at 397.530066 -32.86125)
		(size 0.508)
		(drill 0.254)
		(layers "F.Cu" "B.Cu")
		(net "USB_PCH_BMC_P4_DN")
	)
	(via
		(at 410.8958 -120.893078)
		(size 0.508)
		(drill 0.254)
		(layers "F.Cu" "B.Cu")
		(net "USB_PCH_BMC_P4_DN")
	)
	(segment
		(start 393.785598 -32.32785)
		(end 393.075414 -33.038034)
		(width 0.1143)
		(layer "In11.Cu")
		(net "USB_PCH_BMC_P4_DN")
	)
	(segment
		(start 415.018982 -103.084122)
		(end 413.58693 -104.516174)
		(width 0.1143)
		(layer "In11.Cu")
		(net "USB_PCH_BMC_P4_DN")
	)
	(segment
		(start 414.6169 -64.837818)
		(end 414.782 -65.002918)
		(width 0.1143)
		(layer "In11.Cu")
		(net "USB_PCH_BMC_P4_DN")
	)
	(segment
		(start 398.106138 -45.022262)
		(end 398.691354 -45.607478)
		(width 0.1143)
		(layer "In11.Cu")
		(net "USB_PCH_BMC_P4_DN")
	)
	(segment
		(start 415.85261 -78.507844)
		(end 415.85261 -80.673448)
		(width 0.1143)
		(layer "In11.Cu")
		(net "USB_PCH_BMC_P4_DN")
	)
	(segment
		(start 415.018982 -89.748106)
		(end 415.018982 -103.084122)
		(width 0.1143)
		(layer "In11.Cu")
		(net "USB_PCH_BMC_P4_DN")
	)
	(segment
		(start 409.632658 -116.6495)
		(end 409.033726 -116.6495)
		(width 0.1143)
		(layer "In11.Cu")
		(net "USB_PCH_BMC_P4_DN")
	)
	(segment
		(start 397.469106 -44.028614)
		(end 397.469106 -44.830238)
		(width 0.1143)
		(layer "In11.Cu")
		(net "USB_PCH_BMC_P4_DN")
	)
	(segment
		(start 395.7574 -32.747204)
		(end 395.338046 -32.32785)
		(width 0.1143)
		(layer "In11.Cu")
		(net "USB_PCH_BMC_P4_DN")
	)
	(segment
		(start 396.40129 -42.960798)
		(end 397.469106 -44.028614)
		(width 0.1143)
		(layer "In11.Cu")
		(net "USB_PCH_BMC_P4_DN")
	)
	(segment
		(start 397.469106 -44.830238)
		(end 397.66113 -45.022262)
		(width 0.1143)
		(layer "In11.Cu")
		(net "USB_PCH_BMC_P4_DN")
	)
	(segment
		(start 408.379676 -117.30355)
		(end 408.379676 -117.949218)
		(width 0.1143)
		(layer "In11.Cu")
		(net "USB_PCH_BMC_P4_DN")
	)
	(segment
		(start 399.7325 -50.8889)
		(end 400.08683 -51.24323)
		(width 0.1143)
		(layer "In11.Cu")
		(net "USB_PCH_BMC_P4_DN")
	)
	(segment
		(start 394.877798 -42.960798)
		(end 396.40129 -42.960798)
		(width 0.1143)
		(layer "In11.Cu")
		(net "USB_PCH_BMC_P4_DN")
	)
	(segment
		(start 415.047684 -82.935826)
		(end 415.047684 -83.937856)
		(width 0.1143)
		(layer "In11.Cu")
		(net "USB_PCH_BMC_P4_DN")
	)
	(segment
		(start 402.01088 -53.16728)
		(end 402.71192 -53.16728)
		(width 0.1143)
		(layer "In11.Cu")
		(net "USB_PCH_BMC_P4_DN")
	)
	(segment
		(start 401.280884 -52.203858)
		(end 401.280884 -52.437284)
		(width 0.1143)
		(layer "In11.Cu")
		(net "USB_PCH_BMC_P4_DN")
	)
	(segment
		(start 405.176228 -52.74437)
		(end 411.436058 -59.0042)
		(width 0.1143)
		(layer "In11.Cu")
		(net "USB_PCH_BMC_P4_DN")
	)
	(segment
		(start 416.10915 -72.385174)
		(end 416.559238 -72.835262)
		(width 0.1143)
		(layer "In11.Cu")
		(net "USB_PCH_BMC_P4_DN")
	)
	(segment
		(start 415.2138 -72.169274)
		(end 415.4297 -72.385174)
		(width 0.1143)
		(layer "In11.Cu")
		(net "USB_PCH_BMC_P4_DN")
	)
	(segment
		(start 393.075414 -33.038034)
		(end 393.075414 -35.980116)
		(width 0.1143)
		(layer "In11.Cu")
		(net "USB_PCH_BMC_P4_DN")
	)
	(segment
		(start 414.6169 -59.924442)
		(end 414.6169 -64.837818)
		(width 0.1143)
		(layer "In11.Cu")
		(net "USB_PCH_BMC_P4_DN")
	)
	(segment
		(start 408.544776 -118.457218)
		(end 408.379676 -118.622318)
		(width 0.1143)
		(layer "In11.Cu")
		(net "USB_PCH_BMC_P4_DN")
	)
	(segment
		(start 415.4297 -72.385174)
		(end 416.10915 -72.385174)
		(width 0.1143)
		(layer "In11.Cu")
		(net "USB_PCH_BMC_P4_DN")
	)
	(segment
		(start 395.338046 -32.32785)
		(end 393.785598 -32.32785)
		(width 0.1143)
		(layer "In11.Cu")
		(net "USB_PCH_BMC_P4_DN")
	)
	(segment
		(start 414.6169 -65.510918)
		(end 414.6169 -65.944242)
		(width 0.1143)
		(layer "In11.Cu")
		(net "USB_PCH_BMC_P4_DN")
	)
	(segment
		(start 401.038568 -51.961542)
		(end 401.280884 -52.203858)
		(width 0.1143)
		(layer "In11.Cu")
		(net "USB_PCH_BMC_P4_DN")
	)
	(segment
		(start 410.243782 -119.769128)
		(end 410.561028 -120.086374)
		(width 0.1143)
		(layer "In11.Cu")
		(net "USB_PCH_BMC_P4_DN")
	)
	(segment
		(start 394.031216 -42.114216)
		(end 394.877798 -42.960798)
		(width 0.1143)
		(layer "In11.Cu")
		(net "USB_PCH_BMC_P4_DN")
	)
	(segment
		(start 394.031216 -39.390828)
		(end 394.031216 -42.114216)
		(width 0.1143)
		(layer "In11.Cu")
		(net "USB_PCH_BMC_P4_DN")
	)
	(segment
		(start 400.08683 -51.24323)
		(end 400.320256 -51.24323)
		(width 0.1143)
		(layer "In11.Cu")
		(net "USB_PCH_BMC_P4_DN")
	)
	(segment
		(start 412.620968 -110.492286)
		(end 412.620968 -114.994436)
		(width 0.1143)
		(layer "In11.Cu")
		(net "USB_PCH_BMC_P4_DN")
	)
	(segment
		(start 411.436058 -59.0042)
		(end 413.696658 -59.0042)
		(width 0.1143)
		(layer "In11.Cu")
		(net "USB_PCH_BMC_P4_DN")
	)
	(segment
		(start 415.047684 -83.937856)
		(end 413.137604 -85.847936)
		(width 0.1143)
		(layer "In11.Cu")
		(net "USB_PCH_BMC_P4_DN")
	)
	(segment
		(start 416.559238 -72.835262)
		(end 416.559238 -77.801216)
		(width 0.1143)
		(layer "In11.Cu")
		(net "USB_PCH_BMC_P4_DN")
	)
	(segment
		(start 413.137604 -87.866728)
		(end 415.018982 -89.748106)
		(width 0.1143)
		(layer "In11.Cu")
		(net "USB_PCH_BMC_P4_DN")
	)
	(segment
		(start 400.320256 -51.24323)
		(end 400.562572 -51.485546)
		(width 0.1143)
		(layer "In11.Cu")
		(net "USB_PCH_BMC_P4_DN")
	)
	(segment
		(start 402.71192 -53.16728)
		(end 403.13483 -52.74437)
		(width 0.1143)
		(layer "In11.Cu")
		(net "USB_PCH_BMC_P4_DN")
	)
	(segment
		(start 401.280884 -52.437284)
		(end 402.01088 -53.16728)
		(width 0.1143)
		(layer "In11.Cu")
		(net "USB_PCH_BMC_P4_DN")
	)
	(segment
		(start 403.13483 -52.74437)
		(end 405.176228 -52.74437)
		(width 0.1143)
		(layer "In11.Cu")
		(net "USB_PCH_BMC_P4_DN")
	)
	(segment
		(start 400.562572 -51.485546)
		(end 400.562572 -51.718972)
		(width 0.1143)
		(layer "In11.Cu")
		(net "USB_PCH_BMC_P4_DN")
	)
	(segment
		(start 410.561028 -120.086374)
		(end 410.561028 -120.558306)
		(width 0.1143)
		(layer "In11.Cu")
		(net "USB_PCH_BMC_P4_DN")
	)
	(segment
		(start 413.58693 -109.526324)
		(end 412.620968 -110.492286)
		(width 0.1143)
		(layer "In11.Cu")
		(net "USB_PCH_BMC_P4_DN")
	)
	(segment
		(start 399.7325 -47.332646)
		(end 399.7325 -50.8889)
		(width 0.1143)
		(layer "In11.Cu")
		(net "USB_PCH_BMC_P4_DN")
	)
	(segment
		(start 394.190982 -37.095684)
		(end 394.190982 -39.231062)
		(width 0.1143)
		(layer "In11.Cu")
		(net "USB_PCH_BMC_P4_DN")
	)
	(segment
		(start 416.559238 -77.801216)
		(end 415.85261 -78.507844)
		(width 0.1143)
		(layer "In11.Cu")
		(net "USB_PCH_BMC_P4_DN")
	)
	(segment
		(start 414.8963 -82.784442)
		(end 415.047684 -82.935826)
		(width 0.1143)
		(layer "In11.Cu")
		(net "USB_PCH_BMC_P4_DN")
	)
	(segment
		(start 408.379676 -118.622318)
		(end 408.379676 -118.965218)
		(width 0.1143)
		(layer "In11.Cu")
		(net "USB_PCH_BMC_P4_DN")
	)
	(segment
		(start 410.561028 -120.558306)
		(end 410.8958 -120.893078)
		(width 0.1143)
		(layer "In11.Cu")
		(net "USB_PCH_BMC_P4_DN")
	)
	(segment
		(start 400.562572 -51.718972)
		(end 400.805142 -51.961542)
		(width 0.1143)
		(layer "In11.Cu")
		(net "USB_PCH_BMC_P4_DN")
	)
	(segment
		(start 410.356558 -115.9256)
		(end 409.632658 -116.6495)
		(width 0.1143)
		(layer "In11.Cu")
		(net "USB_PCH_BMC_P4_DN")
	)
	(segment
		(start 393.075414 -35.980116)
		(end 394.190982 -37.095684)
		(width 0.1143)
		(layer "In11.Cu")
		(net "USB_PCH_BMC_P4_DN")
	)
	(segment
		(start 408.379676 -117.949218)
		(end 408.544776 -118.114318)
		(width 0.1143)
		(layer "In11.Cu")
		(net "USB_PCH_BMC_P4_DN")
	)
	(segment
		(start 409.033726 -116.6495)
		(end 408.379676 -117.30355)
		(width 0.1143)
		(layer "In11.Cu")
		(net "USB_PCH_BMC_P4_DN")
	)
	(segment
		(start 415.85261 -80.673448)
		(end 414.8963 -81.629758)
		(width 0.1143)
		(layer "In11.Cu")
		(net "USB_PCH_BMC_P4_DN")
	)
	(segment
		(start 413.137604 -85.847936)
		(end 413.137604 -87.866728)
		(width 0.1143)
		(layer "In11.Cu")
		(net "USB_PCH_BMC_P4_DN")
	)
	(segment
		(start 414.8963 -81.629758)
		(end 414.8963 -82.784442)
		(width 0.1143)
		(layer "In11.Cu")
		(net "USB_PCH_BMC_P4_DN")
	)
	(segment
		(start 415.2138 -66.541142)
		(end 415.2138 -72.169274)
		(width 0.1143)
		(layer "In11.Cu")
		(net "USB_PCH_BMC_P4_DN")
	)
	(segment
		(start 413.58693 -104.516174)
		(end 413.58693 -109.526324)
		(width 0.1143)
		(layer "In11.Cu")
		(net "USB_PCH_BMC_P4_DN")
	)
	(segment
		(start 412.620968 -114.994436)
		(end 411.689804 -115.9256)
		(width 0.1143)
		(layer "In11.Cu")
		(net "USB_PCH_BMC_P4_DN")
	)
	(segment
		(start 409.183586 -119.769128)
		(end 410.243782 -119.769128)
		(width 0.1143)
		(layer "In11.Cu")
		(net "USB_PCH_BMC_P4_DN")
	)
	(segment
		(start 413.696658 -59.0042)
		(end 414.6169 -59.924442)
		(width 0.1143)
		(layer "In11.Cu")
		(net "USB_PCH_BMC_P4_DN")
	)
	(segment
		(start 398.691354 -46.2915)
		(end 399.7325 -47.332646)
		(width 0.1143)
		(layer "In11.Cu")
		(net "USB_PCH_BMC_P4_DN")
	)
	(segment
		(start 398.691354 -45.607478)
		(end 398.691354 -46.2915)
		(width 0.1143)
		(layer "In11.Cu")
		(net "USB_PCH_BMC_P4_DN")
	)
	(segment
		(start 400.805142 -51.961542)
		(end 401.038568 -51.961542)
		(width 0.1143)
		(layer "In11.Cu")
		(net "USB_PCH_BMC_P4_DN")
	)
	(segment
		(start 408.379676 -118.965218)
		(end 409.183586 -119.769128)
		(width 0.1143)
		(layer "In11.Cu")
		(net "USB_PCH_BMC_P4_DN")
	)
	(segment
		(start 397.66113 -45.022262)
		(end 398.106138 -45.022262)
		(width 0.1143)
		(layer "In11.Cu")
		(net "USB_PCH_BMC_P4_DN")
	)
	(segment
		(start 414.782 -65.345818)
		(end 414.6169 -65.510918)
		(width 0.1143)
		(layer "In11.Cu")
		(net "USB_PCH_BMC_P4_DN")
	)
	(segment
		(start 408.544776 -118.114318)
		(end 408.544776 -118.457218)
		(width 0.1143)
		(layer "In11.Cu")
		(net "USB_PCH_BMC_P4_DN")
	)
	(segment
		(start 411.689804 -115.9256)
		(end 410.356558 -115.9256)
		(width 0.1143)
		(layer "In11.Cu")
		(net "USB_PCH_BMC_P4_DN")
	)
	(segment
		(start 414.6169 -65.944242)
		(end 415.2138 -66.541142)
		(width 0.1143)
		(layer "In11.Cu")
		(net "USB_PCH_BMC_P4_DN")
	)
	(segment
		(start 414.782 -65.002918)
		(end 414.782 -65.345818)
		(width 0.1143)
		(layer "In11.Cu")
		(net "USB_PCH_BMC_P4_DN")
	)
	(segment
		(start 394.190982 -39.231062)
		(end 394.031216 -39.390828)
		(width 0.1143)
		(layer "In11.Cu")
		(net "USB_PCH_BMC_P4_DN")
	)
	(segment
		(start 125.938788 -69.277738)
		(end 126.510288 -69.277738)
		(width 0.10795)
		(layer "F.Cu")
		(net "TP_CPU1_SOCKET_ID_2")
	)
	(via
		(at 126.510288 -69.277738)
		(size 0.508)
		(drill 0.254)
		(layers "F.Cu" "B.Cu")
		(net "TP_CPU1_SOCKET_ID_2")
	)
	(segment
		(start 290.93922 -69.277738)
		(end 291.51072 -69.277738)
		(width 0.10795)
		(layer "F.Cu")
		(net "TP_CPU0_SOCKET_ID_2")
	)
	(via
		(at 291.51072 -69.277738)
		(size 0.508)
		(drill 0.254)
		(layers "F.Cu" "B.Cu")
		(net "TP_CPU0_SOCKET_ID_2")
	)
	(segment
		(start 293.51478 -61.847984)
		(end 294.08628 -61.847984)
		(width 0.10795)
		(layer "F.Cu")
		(net "TP_CPU0_PROCDIS_G_N")
	)
	(via
		(at 294.08628 -61.847984)
		(size 0.508)
		(drill 0.254)
		(layers "F.Cu" "B.Cu")
		(net "TP_CPU0_PROCDIS_G_N")
	)
	(segment
		(start 411.54985 -16.886936)
		(end 411.249622 -17.187164)
		(width 0.254)
		(layer "F.Cu")
		(net "A_PVNN_STBY_PCH_SENSOR")
	)
	(segment
		(start 409.51023 -24.40813)
		(end 410.718 -25.6159)
		(width 0.127)
		(layer "F.Cu")
		(net "A_PVNN_STBY_PCH_SENSOR")
	)
	(segment
		(start 411.249622 -18.059654)
		(end 411.666182 -18.476214)
		(width 0.254)
		(layer "F.Cu")
		(net "A_PVNN_STBY_PCH_SENSOR")
	)
	(segment
		(start 411.666182 -19.011138)
		(end 410.873956 -19.011138)
		(width 0.254)
		(layer "F.Cu")
		(net "A_PVNN_STBY_PCH_SENSOR")
	)
	(segment
		(start 410.171138 -20.449794)
		(end 409.504134 -21.116798)
		(width 0.254)
		(layer "F.Cu")
		(net "A_PVNN_STBY_PCH_SENSOR")
	)
	(segment
		(start 410.718 -25.6159)
		(end 410.718 -27.762454)
		(width 0.127)
		(layer "F.Cu")
		(net "A_PVNN_STBY_PCH_SENSOR")
	)
	(segment
		(start 412.241746 -16.886936)
		(end 411.82925 -16.886936)
		(width 0.254)
		(layer "F.Cu")
		(net "A_PVNN_STBY_PCH_SENSOR")
	)
	(segment
		(start 410.873956 -19.011138)
		(end 410.171138 -19.713956)
		(width 0.254)
		(layer "F.Cu")
		(net "A_PVNN_STBY_PCH_SENSOR")
	)
	(segment
		(start 409.504134 -24.242268)
		(end 409.51023 -24.248364)
		(width 0.254)
		(layer "F.Cu")
		(net "A_PVNN_STBY_PCH_SENSOR")
	)
	(segment
		(start 412.496 -18.415)
		(end 412.496 -17.14119)
		(width 0.254)
		(layer "F.Cu")
		(net "A_PVNN_STBY_PCH_SENSOR")
	)
	(segment
		(start 411.82925 -16.886936)
		(end 411.54985 -16.886936)
		(width 0.254)
		(layer "F.Cu")
		(net "A_PVNN_STBY_PCH_SENSOR")
	)
	(segment
		(start 411.666182 -18.476214)
		(end 411.666182 -19.011138)
		(width 0.254)
		(layer "F.Cu")
		(net "A_PVNN_STBY_PCH_SENSOR")
	)
	(segment
		(start 412.496 -17.14119)
		(end 412.241746 -16.886936)
		(width 0.254)
		(layer "F.Cu")
		(net "A_PVNN_STBY_PCH_SENSOR")
	)
	(segment
		(start 410.718 -27.762454)
		(end 411.09011 -28.134564)
		(width 0.127)
		(layer "F.Cu")
		(net "A_PVNN_STBY_PCH_SENSOR")
	)
	(segment
		(start 409.504134 -21.116798)
		(end 409.504134 -24.242268)
		(width 0.254)
		(layer "F.Cu")
		(net "A_PVNN_STBY_PCH_SENSOR")
	)
	(segment
		(start 411.249622 -17.187164)
		(end 411.249622 -18.059654)
		(width 0.254)
		(layer "F.Cu")
		(net "A_PVNN_STBY_PCH_SENSOR")
	)
	(segment
		(start 409.51023 -24.248364)
		(end 409.51023 -24.40813)
		(width 0.127)
		(layer "F.Cu")
		(net "A_PVNN_STBY_PCH_SENSOR")
	)
	(segment
		(start 410.171138 -19.713956)
		(end 410.171138 -20.449794)
		(width 0.254)
		(layer "F.Cu")
		(net "A_PVNN_STBY_PCH_SENSOR")
	)
	(via
		(at 411.666182 -19.011138)
		(size 0.508)
		(drill 0.254)
		(layers "F.Cu" "B.Cu")
		(net "A_PVNN_STBY_PCH_SENSOR")
	)
	(via
		(at 411.82925 -16.886936)
		(size 0.762)
		(drill 0.381)
		(layers "F.Cu" "B.Cu")
		(net "A_PVNN_STBY_PCH_SENSOR")
	)
	(segment
		(start 408.045412 -19.205956)
		(end 407.465022 -18.625566)
		(width 0.254)
		(layer "B.Cu")
		(net "A_PVNN_STBY_PCH_SENSOR")
	)
	(segment
		(start 409.69565 -18.8214)
		(end 409.311094 -19.205956)
		(width 0.254)
		(layer "B.Cu")
		(net "A_PVNN_STBY_PCH_SENSOR")
	)
	(segment
		(start 411.666182 -19.011138)
		(end 411.314138 -19.011138)
		(width 0.254)
		(layer "B.Cu")
		(net "A_PVNN_STBY_PCH_SENSOR")
	)
	(segment
		(start 411.314138 -19.011138)
		(end 411.1244 -18.8214)
		(width 0.254)
		(layer "B.Cu")
		(net "A_PVNN_STBY_PCH_SENSOR")
	)
	(segment
		(start 407.465022 -18.625566)
		(end 407.465022 -17.838166)
		(width 0.254)
		(layer "B.Cu")
		(net "A_PVNN_STBY_PCH_SENSOR")
	)
	(segment
		(start 411.1244 -18.8214)
		(end 409.69565 -18.8214)
		(width 0.254)
		(layer "B.Cu")
		(net "A_PVNN_STBY_PCH_SENSOR")
	)
	(segment
		(start 409.311094 -19.205956)
		(end 408.045412 -19.205956)
		(width 0.254)
		(layer "B.Cu")
		(net "A_PVNN_STBY_PCH_SENSOR")
	)
	(segment
		(start 382.590548 -93.199966)
		(end 382.485138 -93.305376)
		(width 0.0889)
		(layer "F.Cu")
		(net "LPC_LAD2_IO2")
	)
	(segment
		(start 382.590548 -92.580968)
		(end 382.590548 -93.199966)
		(width 0.0889)
		(layer "F.Cu")
		(net "LPC_LAD2_IO2")
	)
	(segment
		(start 382.485138 -93.95968)
		(end 382.484884 -93.959934)
		(width 0.0889)
		(layer "F.Cu")
		(net "LPC_LAD2_IO2")
	)
	(segment
		(start 382.145286 -91.721686)
		(end 382.435354 -92.011754)
		(width 0.0889)
		(layer "F.Cu")
		(net "LPC_LAD2_IO2")
	)
	(segment
		(start 382.4478 -92.43822)
		(end 382.590548 -92.580968)
		(width 0.0889)
		(layer "F.Cu")
		(net "LPC_LAD2_IO2")
	)
	(segment
		(start 381.4826 -91.059)
		(end 382.145286 -91.721686)
		(width 0.10795)
		(layer "F.Cu")
		(net "LPC_LAD2_IO2")
	)
	(segment
		(start 379.984 -88.2015)
		(end 381.04191 -89.25941)
		(width 0.10795)
		(layer "F.Cu")
		(net "LPC_LAD2_IO2")
	)
	(segment
		(start 382.4478 -92.423996)
		(end 382.4478 -92.43822)
		(width 0.0889)
		(layer "F.Cu")
		(net "LPC_LAD2_IO2")
	)
	(segment
		(start 381.4826 -90.6145)
		(end 381.4826 -91.059)
		(width 0.10795)
		(layer "F.Cu")
		(net "LPC_LAD2_IO2")
	)
	(segment
		(start 381.04191 -90.17381)
		(end 381.4826 -90.6145)
		(width 0.10795)
		(layer "F.Cu")
		(net "LPC_LAD2_IO2")
	)
	(segment
		(start 382.435354 -92.011754)
		(end 382.435354 -92.41155)
		(width 0.0889)
		(layer "F.Cu")
		(net "LPC_LAD2_IO2")
	)
	(segment
		(start 381.04191 -89.25941)
		(end 381.04191 -90.17381)
		(width 0.10795)
		(layer "F.Cu")
		(net "LPC_LAD2_IO2")
	)
	(segment
		(start 382.485138 -93.305376)
		(end 382.485138 -93.95968)
		(width 0.0889)
		(layer "F.Cu")
		(net "LPC_LAD2_IO2")
	)
	(segment
		(start 382.435354 -92.41155)
		(end 382.4478 -92.423996)
		(width 0.0889)
		(layer "F.Cu")
		(net "LPC_LAD2_IO2")
	)
	(segment
		(start 379.222 -90.82913)
		(end 379.642624 -91.249754)
		(width 0.10795)
		(layer "F.Cu")
		(net "LPC_LAD1_IO1")
	)
	(segment
		(start 379.222 -88.2015)
		(end 379.222 -90.82913)
		(width 0.10795)
		(layer "F.Cu")
		(net "LPC_LAD1_IO1")
	)
	(segment
		(start 379.642624 -93.202506)
		(end 379.985016 -93.544898)
		(width 0.0889)
		(layer "F.Cu")
		(net "LPC_LAD1_IO1")
	)
	(segment
		(start 379.642624 -92.826078)
		(end 379.642624 -93.202506)
		(width 0.0889)
		(layer "F.Cu")
		(net "LPC_LAD1_IO1")
	)
	(segment
		(start 379.642624 -91.249754)
		(end 379.642624 -92.826078)
		(width 0.10795)
		(layer "F.Cu")
		(net "LPC_LAD1_IO1")
	)
	(segment
		(start 408.2034 -64.897)
		(end 407.8351 -64.897)
		(width 0.10795)
		(layer "F.Cu")
		(net "SPI_PCH_TPM_MOSI_R")
	)
	(segment
		(start 409.43403 -64.52997)
		(end 408.9654 -64.9986)
		(width 0.10795)
		(layer "F.Cu")
		(net "SPI_PCH_TPM_MOSI_R")
	)
	(segment
		(start 408.305 -64.9986)
		(end 408.2034 -64.897)
		(width 0.10795)
		(layer "F.Cu")
		(net "SPI_PCH_TPM_MOSI_R")
	)
	(segment
		(start 408.9654 -64.9986)
		(end 408.305 -64.9986)
		(width 0.10795)
		(layer "F.Cu")
		(net "SPI_PCH_TPM_MOSI_R")
	)
	(segment
		(start 410.340048 -64.52997)
		(end 409.43403 -64.52997)
		(width 0.10795)
		(layer "F.Cu")
		(net "SPI_PCH_TPM_MOSI_R")
	)
	(segment
		(start 383.27076 -92.13596)
		(end 383.27076 -93.711776)
		(width 0.0889)
		(layer "F.Cu")
		(net "LPC_LAD0_IO0")
	)
	(segment
		(start 383.27076 -93.711776)
		(end 382.98501 -93.997526)
		(width 0.0889)
		(layer "F.Cu")
		(net "LPC_LAD0_IO0")
	)
	(segment
		(start 382.3716 -91.2368)
		(end 383.27076 -92.13596)
		(width 0.0889)
		(layer "F.Cu")
		(net "LPC_LAD0_IO0")
	)
	(segment
		(start 382.98501 -93.997526)
		(end 382.98501 -94.37497)
		(width 0.0889)
		(layer "F.Cu")
		(net "LPC_LAD0_IO0")
	)
	(segment
		(start 381.508 -88.2015)
		(end 381.524002 -88.2015)
		(width 0.10795)
		(layer "F.Cu")
		(net "LPC_LAD0_IO0")
	)
	(segment
		(start 382.3716 -89.049098)
		(end 382.3716 -90.863928)
		(width 0.10795)
		(layer "F.Cu")
		(net "LPC_LAD0_IO0")
	)
	(segment
		(start 382.3716 -90.863928)
		(end 382.3716 -91.2368)
		(width 0.0889)
		(layer "F.Cu")
		(net "LPC_LAD0_IO0")
	)
	(segment
		(start 381.524002 -88.2015)
		(end 382.3716 -89.049098)
		(width 0.10795)
		(layer "F.Cu")
		(net "LPC_LAD0_IO0")
	)
	(segment
		(start 170.942 -126.4158)
		(end 171.8564 -127.3302)
		(width 0.10795)
		(layer "F.Cu")
		(net "JTAG_MCP_CPU1_TDO")
	)
	(segment
		(start 170.2816 -126.4158)
		(end 170.942 -126.4158)
		(width 0.10795)
		(layer "F.Cu")
		(net "JTAG_MCP_CPU1_TDO")
	)
	(segment
		(start 124.221748 -82.155284)
		(end 124.793248 -82.155284)
		(width 0.1016)
		(layer "F.Cu")
		(net "JTAG_MCP_CPU1_TDO")
	)
	(via
		(at 496.977924 -133.774434)
		(size 0.508)
		(drill 0.254)
		(layers "F.Cu" "B.Cu")
		(net "JTAG_MCP_CPU1_TDO")
	)
	(via
		(at 412.07182 -150.45055)
		(size 0.508)
		(drill 0.254)
		(layers "F.Cu" "B.Cu")
		(net "JTAG_MCP_CPU1_TDO")
	)
	(via
		(at 471.43416 -149.530816)
		(size 0.508)
		(drill 0.254)
		(layers "F.Cu" "B.Cu")
		(net "JTAG_MCP_CPU1_TDO")
	)
	(via
		(at 171.8564 -127.3302)
		(size 0.508)
		(drill 0.254)
		(layers "F.Cu" "B.Cu")
		(net "JTAG_MCP_CPU1_TDO")
	)
	(via
		(at 170.2816 -126.4158)
		(size 0.762)
		(drill 0.381)
		(layers "F.Cu" "B.Cu")
		(net "JTAG_MCP_CPU1_TDO")
	)
	(via
		(at 124.793248 -82.155284)
		(size 0.508)
		(drill 0.254)
		(layers "F.Cu" "B.Cu")
		(net "JTAG_MCP_CPU1_TDO")
	)
	(segment
		(start 496.87099 -133.6675)
		(end 496.977924 -133.774434)
		(width 0.10795)
		(layer "B.Cu")
		(net "JTAG_MCP_CPU1_TDO")
	)
	(segment
		(start 496.315492 -133.6675)
		(end 496.87099 -133.6675)
		(width 0.10795)
		(layer "B.Cu")
		(net "JTAG_MCP_CPU1_TDO")
	)
	(segment
		(start 183.405018 -128.88214)
		(end 183.859932 -129.337054)
		(width 0.089408)
		(layer "In2.Cu")
		(net "JTAG_MCP_CPU1_TDO")
	)
	(segment
		(start 329.5015 -148.083778)
		(end 329.5015 -142.15491)
		(width 0.089408)
		(layer "In2.Cu")
		(net "JTAG_MCP_CPU1_TDO")
	)
	(segment
		(start 408.578812 -149.027388)
		(end 409.6512 -147.955)
		(width 0.089408)
		(layer "In2.Cu")
		(net "JTAG_MCP_CPU1_TDO")
	)
	(segment
		(start 396.578328 -148.0566)
		(end 399.567146 -148.0566)
		(width 0.089408)
		(layer "In2.Cu")
		(net "JTAG_MCP_CPU1_TDO")
	)
	(segment
		(start 376.32894 -137.85342)
		(end 379.415548 -140.940028)
		(width 0.089408)
		(layer "In2.Cu")
		(net "JTAG_MCP_CPU1_TDO")
	)
	(segment
		(start 359.349294 -132.9944)
		(end 359.69194 -132.9944)
		(width 0.089408)
		(layer "In2.Cu")
		(net "JTAG_MCP_CPU1_TDO")
	)
	(segment
		(start 182.913274 -128.88214)
		(end 183.405018 -128.88214)
		(width 0.089408)
		(layer "In2.Cu")
		(net "JTAG_MCP_CPU1_TDO")
	)
	(segment
		(start 399.719546 -148.209)
		(end 404.7998 -148.209)
		(width 0.089408)
		(layer "In2.Cu")
		(net "JTAG_MCP_CPU1_TDO")
	)
	(segment
		(start 265.189208 -157.893766)
		(end 265.488928 -157.594046)
		(width 0.089408)
		(layer "In2.Cu")
		(net "JTAG_MCP_CPU1_TDO")
	)
	(segment
		(start 188.067188 -137.807192)
		(end 186.802522 -139.071858)
		(width 0.089408)
		(layer "In2.Cu")
		(net "JTAG_MCP_CPU1_TDO")
	)
	(segment
		(start 331.728064 -157.49016)
		(end 331.728064 -156.45003)
		(width 0.089408)
		(layer "In2.Cu")
		(net "JTAG_MCP_CPU1_TDO")
	)
	(segment
		(start 331.728064 -156.45003)
		(end 330.383896 -155.105862)
		(width 0.089408)
		(layer "In2.Cu")
		(net "JTAG_MCP_CPU1_TDO")
	)
	(segment
		(start 278.62276 -156.8958)
		(end 323.488304 -156.8958)
		(width 0.089408)
		(layer "In2.Cu")
		(net "JTAG_MCP_CPU1_TDO")
	)
	(segment
		(start 363.982 -138.101324)
		(end 365.078772 -139.198096)
		(width 0.089408)
		(layer "In2.Cu")
		(net "JTAG_MCP_CPU1_TDO")
	)
	(segment
		(start 365.078772 -139.198096)
		(end 365.478822 -139.198096)
		(width 0.089408)
		(layer "In2.Cu")
		(net "JTAG_MCP_CPU1_TDO")
	)
	(segment
		(start 369.863878 -137.62355)
		(end 370.093748 -137.85342)
		(width 0.089408)
		(layer "In2.Cu")
		(net "JTAG_MCP_CPU1_TDO")
	)
	(segment
		(start 347.748098 -138.172698)
		(end 349.14078 -139.56538)
		(width 0.089408)
		(layer "In2.Cu")
		(net "JTAG_MCP_CPU1_TDO")
	)
	(segment
		(start 185.071512 -131.97967)
		(end 186.471814 -131.97967)
		(width 0.089408)
		(layer "In2.Cu")
		(net "JTAG_MCP_CPU1_TDO")
	)
	(segment
		(start 183.859932 -130.76809)
		(end 185.071512 -131.97967)
		(width 0.089408)
		(layer "In2.Cu")
		(net "JTAG_MCP_CPU1_TDO")
	)
	(segment
		(start 363.982 -137.67054)
		(end 363.982 -138.101324)
		(width 0.089408)
		(layer "In2.Cu")
		(net "JTAG_MCP_CPU1_TDO")
	)
	(segment
		(start 379.415548 -140.940028)
		(end 390.348216 -140.940028)
		(width 0.089408)
		(layer "In2.Cu")
		(net "JTAG_MCP_CPU1_TDO")
	)
	(segment
		(start 324.771258 -158.178754)
		(end 331.03947 -158.178754)
		(width 0.089408)
		(layer "In2.Cu")
		(net "JTAG_MCP_CPU1_TDO")
	)
	(segment
		(start 190.818516 -134.558786)
		(end 190.818516 -136.107424)
		(width 0.089408)
		(layer "In2.Cu")
		(net "JTAG_MCP_CPU1_TDO")
	)
	(segment
		(start 328.91222 -152.131522)
		(end 328.91222 -148.673058)
		(width 0.089408)
		(layer "In2.Cu")
		(net "JTAG_MCP_CPU1_TDO")
	)
	(segment
		(start 390.348216 -140.940028)
		(end 391.459212 -142.051024)
		(width 0.089408)
		(layer "In2.Cu")
		(net "JTAG_MCP_CPU1_TDO")
	)
	(segment
		(start 329.47356 -139.4079)
		(end 329.81138 -139.07008)
		(width 0.089408)
		(layer "In2.Cu")
		(net "JTAG_MCP_CPU1_TDO")
	)
	(segment
		(start 330.383896 -155.105862)
		(end 330.383896 -153.866596)
		(width 0.089408)
		(layer "In2.Cu")
		(net "JTAG_MCP_CPU1_TDO")
	)
	(segment
		(start 349.14078 -139.56538)
		(end 352.608896 -139.56538)
		(width 0.089408)
		(layer "In2.Cu")
		(net "JTAG_MCP_CPU1_TDO")
	)
	(segment
		(start 265.050778 -157.893766)
		(end 265.189208 -157.893766)
		(width 0.089408)
		(layer "In2.Cu")
		(net "JTAG_MCP_CPU1_TDO")
	)
	(segment
		(start 362.077 -135.37946)
		(end 362.077 -135.76554)
		(width 0.089408)
		(layer "In2.Cu")
		(net "JTAG_MCP_CPU1_TDO")
	)
	(segment
		(start 365.478822 -139.198096)
		(end 367.053368 -137.62355)
		(width 0.089408)
		(layer "In2.Cu")
		(net "JTAG_MCP_CPU1_TDO")
	)
	(segment
		(start 357.423974 -132.588254)
		(end 358.943148 -132.588254)
		(width 0.089408)
		(layer "In2.Cu")
		(net "JTAG_MCP_CPU1_TDO")
	)
	(segment
		(start 329.05954 -152.54224)
		(end 329.05954 -152.521666)
		(width 0.089408)
		(layer "In2.Cu")
		(net "JTAG_MCP_CPU1_TDO")
	)
	(segment
		(start 265.04646 -157.898084)
		(end 265.050778 -157.893766)
		(width 0.089408)
		(layer "In2.Cu")
		(net "JTAG_MCP_CPU1_TDO")
	)
	(segment
		(start 189.118748 -137.807192)
		(end 188.067188 -137.807192)
		(width 0.089408)
		(layer "In2.Cu")
		(net "JTAG_MCP_CPU1_TDO")
	)
	(segment
		(start 174.758604 -127.9652)
		(end 181.996334 -127.9652)
		(width 0.089408)
		(layer "In2.Cu")
		(net "JTAG_MCP_CPU1_TDO")
	)
	(segment
		(start 329.473306 -141.8844)
		(end 329.47356 -141.884146)
		(width 0.089408)
		(layer "In2.Cu")
		(net "JTAG_MCP_CPU1_TDO")
	)
	(segment
		(start 189.049914 -157.893766)
		(end 191.21247 -157.893766)
		(width 0.089408)
		(layer "In2.Cu")
		(net "JTAG_MCP_CPU1_TDO")
	)
	(segment
		(start 190.818516 -136.107424)
		(end 189.118748 -137.807192)
		(width 0.089408)
		(layer "In2.Cu")
		(net "JTAG_MCP_CPU1_TDO")
	)
	(segment
		(start 186.802522 -139.071858)
		(end 186.802522 -153.062432)
		(width 0.089408)
		(layer "In2.Cu")
		(net "JTAG_MCP_CPU1_TDO")
	)
	(segment
		(start 191.216788 -157.898084)
		(end 265.04646 -157.898084)
		(width 0.089408)
		(layer "In2.Cu")
		(net "JTAG_MCP_CPU1_TDO")
	)
	(segment
		(start 189.872874 -133.613144)
		(end 190.818516 -134.558786)
		(width 0.089408)
		(layer "In2.Cu")
		(net "JTAG_MCP_CPU1_TDO")
	)
	(segment
		(start 181.996334 -127.9652)
		(end 182.913274 -128.88214)
		(width 0.089408)
		(layer "In2.Cu")
		(net "JTAG_MCP_CPU1_TDO")
	)
	(segment
		(start 191.21247 -157.893766)
		(end 191.216788 -157.898084)
		(width 0.089408)
		(layer "In2.Cu")
		(net "JTAG_MCP_CPU1_TDO")
	)
	(segment
		(start 277.924514 -157.594046)
		(end 278.62276 -156.8958)
		(width 0.089408)
		(layer "In2.Cu")
		(net "JTAG_MCP_CPU1_TDO")
	)
	(segment
		(start 188.105288 -133.613144)
		(end 189.872874 -133.613144)
		(width 0.089408)
		(layer "In2.Cu")
		(net "JTAG_MCP_CPU1_TDO")
	)
	(segment
		(start 329.473306 -142.126716)
		(end 329.473306 -141.8844)
		(width 0.089408)
		(layer "In2.Cu")
		(net "JTAG_MCP_CPU1_TDO")
	)
	(segment
		(start 358.943148 -132.588254)
		(end 359.349294 -132.9944)
		(width 0.089408)
		(layer "In2.Cu")
		(net "JTAG_MCP_CPU1_TDO")
	)
	(segment
		(start 186.471814 -131.97967)
		(end 188.105288 -133.613144)
		(width 0.089408)
		(layer "In2.Cu")
		(net "JTAG_MCP_CPU1_TDO")
	)
	(segment
		(start 359.69194 -132.9944)
		(end 362.077 -135.37946)
		(width 0.089408)
		(layer "In2.Cu")
		(net "JTAG_MCP_CPU1_TDO")
	)
	(segment
		(start 172.2628 -126.9238)
		(end 173.717204 -126.9238)
		(width 0.089408)
		(layer "In2.Cu")
		(net "JTAG_MCP_CPU1_TDO")
	)
	(segment
		(start 187.010294 -153.270204)
		(end 187.010294 -155.854146)
		(width 0.089408)
		(layer "In2.Cu")
		(net "JTAG_MCP_CPU1_TDO")
	)
	(segment
		(start 352.608896 -139.56538)
		(end 354.17506 -137.999216)
		(width 0.089408)
		(layer "In2.Cu")
		(net "JTAG_MCP_CPU1_TDO")
	)
	(segment
		(start 328.911966 -152.374092)
		(end 328.911966 -152.131776)
		(width 0.089408)
		(layer "In2.Cu")
		(net "JTAG_MCP_CPU1_TDO")
	)
	(segment
		(start 329.47356 -141.884146)
		(end 329.47356 -139.4079)
		(width 0.089408)
		(layer "In2.Cu")
		(net "JTAG_MCP_CPU1_TDO")
	)
	(segment
		(start 329.5015 -142.15491)
		(end 329.473306 -142.126716)
		(width 0.089408)
		(layer "In2.Cu")
		(net "JTAG_MCP_CPU1_TDO")
	)
	(segment
		(start 409.6512 -147.955)
		(end 410.6672 -147.955)
		(width 0.089408)
		(layer "In2.Cu")
		(net "JTAG_MCP_CPU1_TDO")
	)
	(segment
		(start 370.093748 -137.85342)
		(end 376.32894 -137.85342)
		(width 0.089408)
		(layer "In2.Cu")
		(net "JTAG_MCP_CPU1_TDO")
	)
	(segment
		(start 265.488928 -157.594046)
		(end 277.924514 -157.594046)
		(width 0.089408)
		(layer "In2.Cu")
		(net "JTAG_MCP_CPU1_TDO")
	)
	(segment
		(start 171.8564 -127.3302)
		(end 172.2628 -126.9238)
		(width 0.089408)
		(layer "In2.Cu")
		(net "JTAG_MCP_CPU1_TDO")
	)
	(segment
		(start 329.81138 -139.07008)
		(end 337.459574 -139.07008)
		(width 0.089408)
		(layer "In2.Cu")
		(net "JTAG_MCP_CPU1_TDO")
	)
	(segment
		(start 187.010294 -155.854146)
		(end 189.049914 -157.893766)
		(width 0.089408)
		(layer "In2.Cu")
		(net "JTAG_MCP_CPU1_TDO")
	)
	(segment
		(start 357.181404 -132.588)
		(end 357.42372 -132.588)
		(width 0.089408)
		(layer "In2.Cu")
		(net "JTAG_MCP_CPU1_TDO")
	)
	(segment
		(start 412.07182 -149.35962)
		(end 412.07182 -150.45055)
		(width 0.089408)
		(layer "In2.Cu")
		(net "JTAG_MCP_CPU1_TDO")
	)
	(segment
		(start 391.459212 -142.051024)
		(end 394.65885 -142.051024)
		(width 0.089408)
		(layer "In2.Cu")
		(net "JTAG_MCP_CPU1_TDO")
	)
	(segment
		(start 354.17506 -135.594344)
		(end 357.181404 -132.588)
		(width 0.089408)
		(layer "In2.Cu")
		(net "JTAG_MCP_CPU1_TDO")
	)
	(segment
		(start 328.911966 -152.131776)
		(end 328.91222 -152.131522)
		(width 0.089408)
		(layer "In2.Cu")
		(net "JTAG_MCP_CPU1_TDO")
	)
	(segment
		(start 410.6672 -147.955)
		(end 412.07182 -149.35962)
		(width 0.089408)
		(layer "In2.Cu")
		(net "JTAG_MCP_CPU1_TDO")
	)
	(segment
		(start 395.400784 -146.879056)
		(end 396.578328 -148.0566)
		(width 0.089408)
		(layer "In2.Cu")
		(net "JTAG_MCP_CPU1_TDO")
	)
	(segment
		(start 405.618188 -149.027388)
		(end 408.578812 -149.027388)
		(width 0.089408)
		(layer "In2.Cu")
		(net "JTAG_MCP_CPU1_TDO")
	)
	(segment
		(start 330.383896 -153.866596)
		(end 329.05954 -152.54224)
		(width 0.089408)
		(layer "In2.Cu")
		(net "JTAG_MCP_CPU1_TDO")
	)
	(segment
		(start 354.17506 -137.999216)
		(end 354.17506 -135.594344)
		(width 0.089408)
		(layer "In2.Cu")
		(net "JTAG_MCP_CPU1_TDO")
	)
	(segment
		(start 394.65885 -142.051024)
		(end 395.400784 -142.792958)
		(width 0.089408)
		(layer "In2.Cu")
		(net "JTAG_MCP_CPU1_TDO")
	)
	(segment
		(start 395.400784 -142.792958)
		(end 395.400784 -146.879056)
		(width 0.089408)
		(layer "In2.Cu")
		(net "JTAG_MCP_CPU1_TDO")
	)
	(segment
		(start 323.488304 -156.8958)
		(end 324.771258 -158.178754)
		(width 0.089408)
		(layer "In2.Cu")
		(net "JTAG_MCP_CPU1_TDO")
	)
	(segment
		(start 338.356956 -138.172698)
		(end 347.748098 -138.172698)
		(width 0.089408)
		(layer "In2.Cu")
		(net "JTAG_MCP_CPU1_TDO")
	)
	(segment
		(start 337.459574 -139.07008)
		(end 338.356956 -138.172698)
		(width 0.089408)
		(layer "In2.Cu")
		(net "JTAG_MCP_CPU1_TDO")
	)
	(segment
		(start 328.91222 -148.673058)
		(end 329.5015 -148.083778)
		(width 0.089408)
		(layer "In2.Cu")
		(net "JTAG_MCP_CPU1_TDO")
	)
	(segment
		(start 357.42372 -132.588)
		(end 357.423974 -132.588254)
		(width 0.089408)
		(layer "In2.Cu")
		(net "JTAG_MCP_CPU1_TDO")
	)
	(segment
		(start 367.053368 -137.62355)
		(end 369.863878 -137.62355)
		(width 0.089408)
		(layer "In2.Cu")
		(net "JTAG_MCP_CPU1_TDO")
	)
	(segment
		(start 173.717204 -126.9238)
		(end 174.758604 -127.9652)
		(width 0.089408)
		(layer "In2.Cu")
		(net "JTAG_MCP_CPU1_TDO")
	)
	(segment
		(start 331.03947 -158.178754)
		(end 331.728064 -157.49016)
		(width 0.089408)
		(layer "In2.Cu")
		(net "JTAG_MCP_CPU1_TDO")
	)
	(segment
		(start 183.859932 -129.337054)
		(end 183.859932 -130.76809)
		(width 0.089408)
		(layer "In2.Cu")
		(net "JTAG_MCP_CPU1_TDO")
	)
	(segment
		(start 186.802522 -153.062432)
		(end 187.010294 -153.270204)
		(width 0.089408)
		(layer "In2.Cu")
		(net "JTAG_MCP_CPU1_TDO")
	)
	(segment
		(start 362.077 -135.76554)
		(end 363.982 -137.67054)
		(width 0.089408)
		(layer "In2.Cu")
		(net "JTAG_MCP_CPU1_TDO")
	)
	(segment
		(start 399.567146 -148.0566)
		(end 399.719546 -148.209)
		(width 0.089408)
		(layer "In2.Cu")
		(net "JTAG_MCP_CPU1_TDO")
	)
	(segment
		(start 329.05954 -152.521666)
		(end 328.911966 -152.374092)
		(width 0.089408)
		(layer "In2.Cu")
		(net "JTAG_MCP_CPU1_TDO")
	)
	(segment
		(start 404.7998 -148.209)
		(end 405.618188 -149.027388)
		(width 0.089408)
		(layer "In2.Cu")
		(net "JTAG_MCP_CPU1_TDO")
	)
	(segment
		(start 487.687112 -143.424148)
		(end 487.687366 -143.423894)
		(width 0.089408)
		(layer "In9.Cu")
		(net "JTAG_MCP_CPU1_TDO")
	)
	(segment
		(start 487.444542 -143.423894)
		(end 487.444796 -143.424148)
		(width 0.089408)
		(layer "In9.Cu")
		(net "JTAG_MCP_CPU1_TDO")
	)
	(segment
		(start 495.412776 -135.2042)
		(end 496.842542 -133.774434)
		(width 0.089408)
		(layer "In9.Cu")
		(net "JTAG_MCP_CPU1_TDO")
	)
	(segment
		(start 488.597702 -142.547086)
		(end 489.48848 -142.547086)
		(width 0.089408)
		(layer "In9.Cu")
		(net "JTAG_MCP_CPU1_TDO")
	)
	(segment
		(start 482.3206 -143.995902)
		(end 482.892608 -143.423894)
		(width 0.089408)
		(layer "In9.Cu")
		(net "JTAG_MCP_CPU1_TDO")
	)
	(segment
		(start 487.720894 -143.423894)
		(end 488.597702 -142.547086)
		(width 0.089408)
		(layer "In9.Cu")
		(net "JTAG_MCP_CPU1_TDO")
	)
	(segment
		(start 489.905548 -142.130018)
		(end 489.905548 -138.260836)
		(width 0.089408)
		(layer "In9.Cu")
		(net "JTAG_MCP_CPU1_TDO")
	)
	(segment
		(start 492.962184 -135.2042)
		(end 495.412776 -135.2042)
		(width 0.089408)
		(layer "In9.Cu")
		(net "JTAG_MCP_CPU1_TDO")
	)
	(segment
		(start 482.892608 -143.423894)
		(end 487.444542 -143.423894)
		(width 0.089408)
		(layer "In9.Cu")
		(net "JTAG_MCP_CPU1_TDO")
	)
	(segment
		(start 482.3206 -146.8374)
		(end 482.3206 -143.995902)
		(width 0.089408)
		(layer "In9.Cu")
		(net "JTAG_MCP_CPU1_TDO")
	)
	(segment
		(start 487.687366 -143.423894)
		(end 487.720894 -143.423894)
		(width 0.089408)
		(layer "In9.Cu")
		(net "JTAG_MCP_CPU1_TDO")
	)
	(segment
		(start 473.38488 -149.53488)
		(end 474.089476 -148.830284)
		(width 0.089408)
		(layer "In9.Cu")
		(net "JTAG_MCP_CPU1_TDO")
	)
	(segment
		(start 487.444796 -143.424148)
		(end 487.687112 -143.424148)
		(width 0.089408)
		(layer "In9.Cu")
		(net "JTAG_MCP_CPU1_TDO")
	)
	(segment
		(start 471.43416 -149.530816)
		(end 471.43416 -149.53488)
		(width 0.089408)
		(layer "In9.Cu")
		(net "JTAG_MCP_CPU1_TDO")
	)
	(segment
		(start 496.842542 -133.774434)
		(end 496.977924 -133.774434)
		(width 0.089408)
		(layer "In9.Cu")
		(net "JTAG_MCP_CPU1_TDO")
	)
	(segment
		(start 489.905548 -138.260836)
		(end 492.962184 -135.2042)
		(width 0.089408)
		(layer "In9.Cu")
		(net "JTAG_MCP_CPU1_TDO")
	)
	(segment
		(start 474.089476 -148.830284)
		(end 480.327716 -148.830284)
		(width 0.089408)
		(layer "In9.Cu")
		(net "JTAG_MCP_CPU1_TDO")
	)
	(segment
		(start 471.43416 -149.53488)
		(end 473.38488 -149.53488)
		(width 0.089408)
		(layer "In9.Cu")
		(net "JTAG_MCP_CPU1_TDO")
	)
	(segment
		(start 489.48848 -142.547086)
		(end 489.905548 -142.130018)
		(width 0.089408)
		(layer "In9.Cu")
		(net "JTAG_MCP_CPU1_TDO")
	)
	(segment
		(start 480.327716 -148.830284)
		(end 482.3206 -146.8374)
		(width 0.089408)
		(layer "In9.Cu")
		(net "JTAG_MCP_CPU1_TDO")
	)
	(segment
		(start 419.38321 -156.810964)
		(end 417.73602 -155.163774)
		(width 0.089408)
		(layer "In11.Cu")
		(net "JTAG_MCP_CPU1_TDO")
	)
	(segment
		(start 462.372202 -152.146)
		(end 456.7174 -152.146)
		(width 0.089408)
		(layer "In11.Cu")
		(net "JTAG_MCP_CPU1_TDO")
	)
	(segment
		(start 132.173218 -87.803482)
		(end 132.17652 -87.809324)
		(width 0.0889)
		(layer "In11.Cu")
		(net "JTAG_MCP_CPU1_TDO")
	)
	(segment
		(start 131.650232 -87.508588)
		(end 131.6863 -87.508588)
		(width 0.0889)
		(layer "In11.Cu")
		(net "JTAG_MCP_CPU1_TDO")
	)
	(segment
		(start 125.636782 -84.041234)
		(end 125.669548 -84.041234)
		(width 0.0889)
		(layer "In11.Cu")
		(net "JTAG_MCP_CPU1_TDO")
	)
	(segment
		(start 135.938768 -89.984834)
		(end 135.971534 -89.984834)
		(width 0.0889)
		(layer "In11.Cu")
		(net "JTAG_MCP_CPU1_TDO")
	)
	(segment
		(start 132.519674 -88.003634)
		(end 132.537454 -88.003634)
		(width 0.0889)
		(layer "In11.Cu")
		(net "JTAG_MCP_CPU1_TDO")
	)
	(segment
		(start 417.73602 -154.60218)
		(end 418.244528 -154.093672)
		(width 0.089408)
		(layer "In11.Cu")
		(net "JTAG_MCP_CPU1_TDO")
	)
	(segment
		(start 424.588686 -154.051)
		(end 421.828722 -156.810964)
		(width 0.089408)
		(layer "In11.Cu")
		(net "JTAG_MCP_CPU1_TDO")
	)
	(segment
		(start 140.235178 -92.461588)
		(end 140.8176 -92.461588)
		(width 0.0889)
		(layer "In11.Cu")
		(net "JTAG_MCP_CPU1_TDO")
	)
	(segment
		(start 417.73602 -155.163774)
		(end 417.73602 -154.60218)
		(width 0.089408)
		(layer "In11.Cu")
		(net "JTAG_MCP_CPU1_TDO")
	)
	(segment
		(start 421.828722 -156.810964)
		(end 419.38321 -156.810964)
		(width 0.089408)
		(layer "In11.Cu")
		(net "JTAG_MCP_CPU1_TDO")
	)
	(segment
		(start 416.147504 -153.181812)
		(end 412.760414 -153.181812)
		(width 0.089408)
		(layer "In11.Cu")
		(net "JTAG_MCP_CPU1_TDO")
	)
	(segment
		(start 418.244528 -153.465276)
		(end 417.891976 -153.112724)
		(width 0.089408)
		(layer "In11.Cu")
		(net "JTAG_MCP_CPU1_TDO")
	)
	(segment
		(start 418.244528 -154.093672)
		(end 418.244528 -153.465276)
		(width 0.089408)
		(layer "In11.Cu")
		(net "JTAG_MCP_CPU1_TDO")
	)
	(segment
		(start 417.16833 -152.9461)
		(end 416.383216 -152.9461)
		(width 0.089408)
		(layer "In11.Cu")
		(net "JTAG_MCP_CPU1_TDO")
	)
	(segment
		(start 470.581736 -150.28291)
		(end 467.395306 -153.46934)
		(width 0.089408)
		(layer "In11.Cu")
		(net "JTAG_MCP_CPU1_TDO")
	)
	(segment
		(start 436.484776 -154.051)
		(end 424.588686 -154.051)
		(width 0.089408)
		(layer "In11.Cu")
		(net "JTAG_MCP_CPU1_TDO")
	)
	(segment
		(start 142.016988 -92.461588)
		(end 143.51 -93.9546)
		(width 0.089408)
		(layer "In11.Cu")
		(net "JTAG_MCP_CPU1_TDO")
	)
	(segment
		(start 143.839184 -99.58578)
		(end 154.89428 -110.640876)
		(width 0.089408)
		(layer "In11.Cu")
		(net "JTAG_MCP_CPU1_TDO")
	)
	(segment
		(start 127.353822 -85.031834)
		(end 127.386588 -85.031834)
		(width 0.0889)
		(layer "In11.Cu")
		(net "JTAG_MCP_CPU1_TDO")
	)
	(segment
		(start 123.588018 -82.450686)
		(end 123.583192 -82.459322)
		(width 0.0889)
		(layer "In11.Cu")
		(net "JTAG_MCP_CPU1_TDO")
	)
	(segment
		(start 416.383216 -152.9461)
		(end 416.147504 -153.181812)
		(width 0.089408)
		(layer "In11.Cu")
		(net "JTAG_MCP_CPU1_TDO")
	)
	(segment
		(start 126.499112 -84.536788)
		(end 126.531878 -84.536788)
		(width 0.0889)
		(layer "In11.Cu")
		(net "JTAG_MCP_CPU1_TDO")
	)
	(segment
		(start 154.89428 -110.640876)
		(end 155.337764 -110.640876)
		(width 0.089408)
		(layer "In11.Cu")
		(net "JTAG_MCP_CPU1_TDO")
	)
	(segment
		(start 171.8564 -127.324104)
		(end 171.8564 -127.3302)
		(width 0.089408)
		(layer "In11.Cu")
		(net "JTAG_MCP_CPU1_TDO")
	)
	(segment
		(start 134.221728 -88.994234)
		(end 134.254494 -88.994234)
		(width 0.0889)
		(layer "In11.Cu")
		(net "JTAG_MCP_CPU1_TDO")
	)
	(segment
		(start 130.787902 -87.013034)
		(end 130.820668 -87.013034)
		(width 0.0889)
		(layer "In11.Cu")
		(net "JTAG_MCP_CPU1_TDO")
	)
	(segment
		(start 133.367018 -88.499188)
		(end 133.399784 -88.499188)
		(width 0.0889)
		(layer "In11.Cu")
		(net "JTAG_MCP_CPU1_TDO")
	)
	(segment
		(start 412.760414 -153.181812)
		(end 411.710632 -152.13203)
		(width 0.089408)
		(layer "In11.Cu")
		(net "JTAG_MCP_CPU1_TDO")
	)
	(segment
		(start 412.07182 -150.4823)
		(end 412.07182 -150.45055)
		(width 0.089408)
		(layer "In11.Cu")
		(net "JTAG_MCP_CPU1_TDO")
	)
	(segment
		(start 168.8719 -124.339604)
		(end 171.8564 -127.324104)
		(width 0.089408)
		(layer "In11.Cu")
		(net "JTAG_MCP_CPU1_TDO")
	)
	(segment
		(start 168.8719 -122.89536)
		(end 168.8719 -124.339604)
		(width 0.089408)
		(layer "In11.Cu")
		(net "JTAG_MCP_CPU1_TDO")
	)
	(segment
		(start 139.372848 -91.966034)
		(end 139.405614 -91.966034)
		(width 0.0889)
		(layer "In11.Cu")
		(net "JTAG_MCP_CPU1_TDO")
	)
	(segment
		(start 143.51 -93.9546)
		(end 143.51 -98.813112)
		(width 0.089408)
		(layer "In11.Cu")
		(net "JTAG_MCP_CPU1_TDO")
	)
	(segment
		(start 447.959734 -154.566366)
		(end 437.000142 -154.566366)
		(width 0.089408)
		(layer "In11.Cu")
		(net "JTAG_MCP_CPU1_TDO")
	)
	(segment
		(start 411.710632 -152.13203)
		(end 411.710632 -150.843488)
		(width 0.089408)
		(layer "In11.Cu")
		(net "JTAG_MCP_CPU1_TDO")
	)
	(segment
		(start 463.695542 -153.46934)
		(end 462.372202 -152.146)
		(width 0.089408)
		(layer "In11.Cu")
		(net "JTAG_MCP_CPU1_TDO")
	)
	(segment
		(start 161.850324 -117.153436)
		(end 166.3192 -117.153436)
		(width 0.089408)
		(layer "In11.Cu")
		(net "JTAG_MCP_CPU1_TDO")
	)
	(segment
		(start 467.395306 -153.46934)
		(end 463.695542 -153.46934)
		(width 0.089408)
		(layer "In11.Cu")
		(net "JTAG_MCP_CPU1_TDO")
	)
	(segment
		(start 448.9831 -153.543)
		(end 447.959734 -154.566366)
		(width 0.089408)
		(layer "In11.Cu")
		(net "JTAG_MCP_CPU1_TDO")
	)
	(segment
		(start 456.7174 -152.146)
		(end 455.3204 -153.543)
		(width 0.089408)
		(layer "In11.Cu")
		(net "JTAG_MCP_CPU1_TDO")
	)
	(segment
		(start 417.334954 -153.112724)
		(end 417.16833 -152.9461)
		(width 0.089408)
		(layer "In11.Cu")
		(net "JTAG_MCP_CPU1_TDO")
	)
	(segment
		(start 155.337764 -110.640876)
		(end 161.850324 -117.153436)
		(width 0.089408)
		(layer "In11.Cu")
		(net "JTAG_MCP_CPU1_TDO")
	)
	(segment
		(start 140.8176 -92.461588)
		(end 142.016988 -92.461588)
		(width 0.089408)
		(layer "In11.Cu")
		(net "JTAG_MCP_CPU1_TDO")
	)
	(segment
		(start 129.070862 -86.022434)
		(end 129.103628 -86.022434)
		(width 0.0889)
		(layer "In11.Cu")
		(net "JTAG_MCP_CPU1_TDO")
	)
	(segment
		(start 135.084058 -89.489788)
		(end 135.116824 -89.489788)
		(width 0.0889)
		(layer "In11.Cu")
		(net "JTAG_MCP_CPU1_TDO")
	)
	(segment
		(start 470.68613 -150.28291)
		(end 470.581736 -150.28291)
		(width 0.089408)
		(layer "In11.Cu")
		(net "JTAG_MCP_CPU1_TDO")
	)
	(segment
		(start 169.641774 -120.47601)
		(end 169.641774 -122.125486)
		(width 0.089408)
		(layer "In11.Cu")
		(net "JTAG_MCP_CPU1_TDO")
	)
	(segment
		(start 437.000142 -154.566366)
		(end 436.484776 -154.051)
		(width 0.089408)
		(layer "In11.Cu")
		(net "JTAG_MCP_CPU1_TDO")
	)
	(segment
		(start 137.655808 -90.975434)
		(end 137.688574 -90.975434)
		(width 0.0889)
		(layer "In11.Cu")
		(net "JTAG_MCP_CPU1_TDO")
	)
	(segment
		(start 471.43416 -149.530816)
		(end 471.43416 -149.53488)
		(width 0.089408)
		(layer "In11.Cu")
		(net "JTAG_MCP_CPU1_TDO")
	)
	(segment
		(start 124.782072 -83.546188)
		(end 124.814838 -83.546188)
		(width 0.0889)
		(layer "In11.Cu")
		(net "JTAG_MCP_CPU1_TDO")
	)
	(segment
		(start 129.933192 -86.517988)
		(end 129.965958 -86.517988)
		(width 0.0889)
		(layer "In11.Cu")
		(net "JTAG_MCP_CPU1_TDO")
	)
	(segment
		(start 455.3204 -153.543)
		(end 448.9831 -153.543)
		(width 0.089408)
		(layer "In11.Cu")
		(net "JTAG_MCP_CPU1_TDO")
	)
	(segment
		(start 417.891976 -153.112724)
		(end 417.334954 -153.112724)
		(width 0.089408)
		(layer "In11.Cu")
		(net "JTAG_MCP_CPU1_TDO")
	)
	(segment
		(start 136.801098 -90.480388)
		(end 136.833864 -90.480388)
		(width 0.0889)
		(layer "In11.Cu")
		(net "JTAG_MCP_CPU1_TDO")
	)
	(segment
		(start 169.641774 -122.125486)
		(end 168.8719 -122.89536)
		(width 0.089408)
		(layer "In11.Cu")
		(net "JTAG_MCP_CPU1_TDO")
	)
	(segment
		(start 143.51 -98.813112)
		(end 143.839184 -99.142296)
		(width 0.089408)
		(layer "In11.Cu")
		(net "JTAG_MCP_CPU1_TDO")
	)
	(segment
		(start 143.839184 -99.142296)
		(end 143.839184 -99.58578)
		(width 0.089408)
		(layer "In11.Cu")
		(net "JTAG_MCP_CPU1_TDO")
	)
	(segment
		(start 411.710632 -150.843488)
		(end 412.07182 -150.4823)
		(width 0.089408)
		(layer "In11.Cu")
		(net "JTAG_MCP_CPU1_TDO")
	)
	(segment
		(start 138.518138 -91.470988)
		(end 138.550904 -91.470988)
		(width 0.0889)
		(layer "In11.Cu")
		(net "JTAG_MCP_CPU1_TDO")
	)
	(segment
		(start 123.919742 -83.050634)
		(end 123.952508 -83.050634)
		(width 0.0889)
		(layer "In11.Cu")
		(net "JTAG_MCP_CPU1_TDO")
	)
	(segment
		(start 166.3192 -117.153436)
		(end 169.641774 -120.47601)
		(width 0.089408)
		(layer "In11.Cu")
		(net "JTAG_MCP_CPU1_TDO")
	)
	(segment
		(start 128.216152 -85.527388)
		(end 128.248918 -85.527388)
		(width 0.0889)
		(layer "In11.Cu")
		(net "JTAG_MCP_CPU1_TDO")
	)
	(segment
		(start 471.43416 -149.53488)
		(end 470.68613 -150.28291)
		(width 0.089408)
		(layer "In11.Cu")
		(net "JTAG_MCP_CPU1_TDO")
	)
	(arc
		(start 123.952508 -83.050634)
		(mid 124.237932 -83.134101)
		(end 124.446538 -83.346036)
		(width 0.0889)
		(layer "In11.Cu")
		(net "JTAG_MCP_CPU1_TDO")
	)
	(arc
		(start 133.031484 -88.299036)
		(mid 133.173167 -88.44284)
		(end 133.367018 -88.499188)
		(width 0.0889)
		(layer "In11.Cu")
		(net "JTAG_MCP_CPU1_TDO")
	)
	(arc
		(start 127.386588 -85.031834)
		(mid 127.672012 -85.115301)
		(end 127.880618 -85.327236)
		(width 0.0889)
		(layer "In11.Cu")
		(net "JTAG_MCP_CPU1_TDO")
	)
	(arc
		(start 137.324084 -90.775536)
		(mid 137.464163 -90.918272)
		(end 137.655808 -90.975434)
		(width 0.0889)
		(layer "In11.Cu")
		(net "JTAG_MCP_CPU1_TDO")
	)
	(arc
		(start 128.739138 -85.822536)
		(mid 128.879217 -85.965272)
		(end 129.070862 -86.022434)
		(width 0.0889)
		(layer "In11.Cu")
		(net "JTAG_MCP_CPU1_TDO")
	)
	(arc
		(start 133.890004 -88.794336)
		(mid 134.030083 -88.937072)
		(end 134.221728 -88.994234)
		(width 0.0889)
		(layer "In11.Cu")
		(net "JTAG_MCP_CPU1_TDO")
	)
	(arc
		(start 129.103628 -86.022434)
		(mid 129.389052 -86.105901)
		(end 129.597658 -86.317836)
		(width 0.0889)
		(layer "In11.Cu")
		(net "JTAG_MCP_CPU1_TDO")
	)
	(arc
		(start 135.971534 -89.984834)
		(mid 136.256958 -90.068301)
		(end 136.465564 -90.280236)
		(width 0.0889)
		(layer "In11.Cu")
		(net "JTAG_MCP_CPU1_TDO")
	)
	(arc
		(start 131.6863 -87.508588)
		(mid 131.9676 -87.593554)
		(end 132.173218 -87.803482)
		(width 0.0889)
		(layer "In11.Cu")
		(net "JTAG_MCP_CPU1_TDO")
	)
	(arc
		(start 132.17652 -87.809324)
		(mid 132.322486 -87.951723)
		(end 132.519674 -88.003634)
		(width 0.0889)
		(layer "In11.Cu")
		(net "JTAG_MCP_CPU1_TDO")
	)
	(arc
		(start 136.833864 -90.480388)
		(mid 137.117081 -90.564669)
		(end 137.324084 -90.775536)
		(width 0.0889)
		(layer "In11.Cu")
		(net "JTAG_MCP_CPU1_TDO")
	)
	(arc
		(start 132.537454 -88.003634)
		(mid 132.822878 -88.087101)
		(end 133.031484 -88.299036)
		(width 0.0889)
		(layer "In11.Cu")
		(net "JTAG_MCP_CPU1_TDO")
	)
	(arc
		(start 128.248918 -85.527388)
		(mid 128.532135 -85.611669)
		(end 128.739138 -85.822536)
		(width 0.0889)
		(layer "In11.Cu")
		(net "JTAG_MCP_CPU1_TDO")
	)
	(arc
		(start 124.793248 -82.155284)
		(mid 124.361 -82.226651)
		(end 123.923552 -82.250534)
		(width 0.0889)
		(layer "In11.Cu")
		(net "JTAG_MCP_CPU1_TDO")
	)
	(arc
		(start 129.597658 -86.317836)
		(mid 129.739341 -86.46164)
		(end 129.933192 -86.517988)
		(width 0.0889)
		(layer "In11.Cu")
		(net "JTAG_MCP_CPU1_TDO")
	)
	(arc
		(start 134.748524 -89.289636)
		(mid 134.890207 -89.43344)
		(end 135.084058 -89.489788)
		(width 0.0889)
		(layer "In11.Cu")
		(net "JTAG_MCP_CPU1_TDO")
	)
	(arc
		(start 126.531878 -84.536788)
		(mid 126.815095 -84.621069)
		(end 127.022098 -84.831936)
		(width 0.0889)
		(layer "In11.Cu")
		(net "JTAG_MCP_CPU1_TDO")
	)
	(arc
		(start 139.899644 -92.261436)
		(mid 140.041327 -92.40524)
		(end 140.235178 -92.461588)
		(width 0.0889)
		(layer "In11.Cu")
		(net "JTAG_MCP_CPU1_TDO")
	)
	(arc
		(start 135.607044 -89.784936)
		(mid 135.747123 -89.927672)
		(end 135.938768 -89.984834)
		(width 0.0889)
		(layer "In11.Cu")
		(net "JTAG_MCP_CPU1_TDO")
	)
	(arc
		(start 123.583192 -82.459322)
		(mid 123.534437 -82.655674)
		(end 123.588018 -82.850736)
		(width 0.0889)
		(layer "In11.Cu")
		(net "JTAG_MCP_CPU1_TDO")
	)
	(arc
		(start 135.116824 -89.489788)
		(mid 135.400041 -89.574069)
		(end 135.607044 -89.784936)
		(width 0.0889)
		(layer "In11.Cu")
		(net "JTAG_MCP_CPU1_TDO")
	)
	(arc
		(start 127.022098 -84.831936)
		(mid 127.162177 -84.974672)
		(end 127.353822 -85.031834)
		(width 0.0889)
		(layer "In11.Cu")
		(net "JTAG_MCP_CPU1_TDO")
	)
	(arc
		(start 125.305058 -83.841336)
		(mid 125.445137 -83.984072)
		(end 125.636782 -84.041234)
		(width 0.0889)
		(layer "In11.Cu")
		(net "JTAG_MCP_CPU1_TDO")
	)
	(arc
		(start 126.163578 -84.336636)
		(mid 126.305261 -84.48044)
		(end 126.499112 -84.536788)
		(width 0.0889)
		(layer "In11.Cu")
		(net "JTAG_MCP_CPU1_TDO")
	)
	(arc
		(start 123.588018 -82.850736)
		(mid 123.728097 -82.993472)
		(end 123.919742 -83.050634)
		(width 0.0889)
		(layer "In11.Cu")
		(net "JTAG_MCP_CPU1_TDO")
	)
	(arc
		(start 124.446538 -83.346036)
		(mid 124.588221 -83.48984)
		(end 124.782072 -83.546188)
		(width 0.0889)
		(layer "In11.Cu")
		(net "JTAG_MCP_CPU1_TDO")
	)
	(arc
		(start 139.041124 -91.766136)
		(mid 139.181203 -91.908872)
		(end 139.372848 -91.966034)
		(width 0.0889)
		(layer "In11.Cu")
		(net "JTAG_MCP_CPU1_TDO")
	)
	(arc
		(start 123.923552 -82.250534)
		(mid 123.729702 -82.306884)
		(end 123.588018 -82.450686)
		(width 0.0889)
		(layer "In11.Cu")
		(net "JTAG_MCP_CPU1_TDO")
	)
	(arc
		(start 124.814838 -83.546188)
		(mid 125.098055 -83.630469)
		(end 125.305058 -83.841336)
		(width 0.0889)
		(layer "In11.Cu")
		(net "JTAG_MCP_CPU1_TDO")
	)
	(arc
		(start 139.405614 -91.966034)
		(mid 139.691038 -92.049501)
		(end 139.899644 -92.261436)
		(width 0.0889)
		(layer "In11.Cu")
		(net "JTAG_MCP_CPU1_TDO")
	)
	(arc
		(start 138.182604 -91.270836)
		(mid 138.324287 -91.41464)
		(end 138.518138 -91.470988)
		(width 0.0889)
		(layer "In11.Cu")
		(net "JTAG_MCP_CPU1_TDO")
	)
	(arc
		(start 131.314698 -87.308436)
		(mid 131.456381 -87.45224)
		(end 131.650232 -87.508588)
		(width 0.0889)
		(layer "In11.Cu")
		(net "JTAG_MCP_CPU1_TDO")
	)
	(arc
		(start 130.820668 -87.013034)
		(mid 131.106092 -87.096501)
		(end 131.314698 -87.308436)
		(width 0.0889)
		(layer "In11.Cu")
		(net "JTAG_MCP_CPU1_TDO")
	)
	(arc
		(start 138.550904 -91.470988)
		(mid 138.834121 -91.555269)
		(end 139.041124 -91.766136)
		(width 0.0889)
		(layer "In11.Cu")
		(net "JTAG_MCP_CPU1_TDO")
	)
	(arc
		(start 125.669548 -84.041234)
		(mid 125.954972 -84.124701)
		(end 126.163578 -84.336636)
		(width 0.0889)
		(layer "In11.Cu")
		(net "JTAG_MCP_CPU1_TDO")
	)
	(arc
		(start 136.465564 -90.280236)
		(mid 136.607247 -90.42404)
		(end 136.801098 -90.480388)
		(width 0.0889)
		(layer "In11.Cu")
		(net "JTAG_MCP_CPU1_TDO")
	)
	(arc
		(start 127.880618 -85.327236)
		(mid 128.022301 -85.47104)
		(end 128.216152 -85.527388)
		(width 0.0889)
		(layer "In11.Cu")
		(net "JTAG_MCP_CPU1_TDO")
	)
	(arc
		(start 129.965958 -86.517988)
		(mid 130.249175 -86.602269)
		(end 130.456178 -86.813136)
		(width 0.0889)
		(layer "In11.Cu")
		(net "JTAG_MCP_CPU1_TDO")
	)
	(arc
		(start 134.254494 -88.994234)
		(mid 134.539918 -89.077701)
		(end 134.748524 -89.289636)
		(width 0.0889)
		(layer "In11.Cu")
		(net "JTAG_MCP_CPU1_TDO")
	)
	(arc
		(start 130.456178 -86.813136)
		(mid 130.596257 -86.955872)
		(end 130.787902 -87.013034)
		(width 0.0889)
		(layer "In11.Cu")
		(net "JTAG_MCP_CPU1_TDO")
	)
	(arc
		(start 137.688574 -90.975434)
		(mid 137.973998 -91.058901)
		(end 138.182604 -91.270836)
		(width 0.0889)
		(layer "In11.Cu")
		(net "JTAG_MCP_CPU1_TDO")
	)
	(arc
		(start 133.399784 -88.499188)
		(mid 133.683001 -88.583469)
		(end 133.890004 -88.794336)
		(width 0.0889)
		(layer "In11.Cu")
		(net "JTAG_MCP_CPU1_TDO")
	)
	(segment
		(start 289.22218 -82.155284)
		(end 289.79368 -82.155284)
		(width 0.1016)
		(layer "F.Cu")
		(net "JTAG_MCP_CPU0_TDO")
	)
	(via
		(at 428.625 -122.936)
		(size 0.508)
		(drill 0.254)
		(layers "F.Cu" "B.Cu")
		(net "JTAG_MCP_CPU0_TDO")
	)
	(via
		(at 324.5612 -126.265432)
		(size 0.508)
		(drill 0.254)
		(layers "F.Cu" "B.Cu")
		(net "JTAG_MCP_CPU0_TDO")
	)
	(via
		(at 498.92458 -129.89814)
		(size 0.508)
		(drill 0.254)
		(layers "F.Cu" "B.Cu")
		(net "JTAG_MCP_CPU0_TDO")
	)
	(via
		(at 475.902528 -127.229616)
		(size 0.508)
		(drill 0.254)
		(layers "F.Cu" "B.Cu")
		(net "JTAG_MCP_CPU0_TDO")
	)
	(via
		(at 342.276684 -121.131838)
		(size 0.508)
		(drill 0.254)
		(layers "F.Cu" "B.Cu")
		(net "JTAG_MCP_CPU0_TDO")
	)
	(via
		(at 498.0178 -135.0264)
		(size 0.6604)
		(drill 0.3302)
		(layers "F.Cu" "B.Cu")
		(net "JTAG_MCP_CPU0_TDO")
	)
	(via
		(at 289.79368 -82.155284)
		(size 0.508)
		(drill 0.254)
		(layers "F.Cu" "B.Cu")
		(net "JTAG_MCP_CPU0_TDO")
	)
	(segment
		(start 498.221 -134.8232)
		(end 498.221 -133.161024)
		(width 0.10795)
		(layer "B.Cu")
		(net "JTAG_MCP_CPU0_TDO")
	)
	(segment
		(start 498.485414 -129.458974)
		(end 498.92458 -129.89814)
		(width 0.10795)
		(layer "B.Cu")
		(net "JTAG_MCP_CPU0_TDO")
	)
	(segment
		(start 498.978174 -129.2225)
		(end 498.92458 -129.276094)
		(width 0.10795)
		(layer "B.Cu")
		(net "JTAG_MCP_CPU0_TDO")
	)
	(segment
		(start 498.073426 -129.458974)
		(end 498.485414 -129.458974)
		(width 0.10795)
		(layer "B.Cu")
		(net "JTAG_MCP_CPU0_TDO")
	)
	(segment
		(start 497.1542 -132.094224)
		(end 497.1542 -131.4704)
		(width 0.10795)
		(layer "B.Cu")
		(net "JTAG_MCP_CPU0_TDO")
	)
	(segment
		(start 497.1542 -131.4704)
		(end 497.6114 -131.0132)
		(width 0.10795)
		(layer "B.Cu")
		(net "JTAG_MCP_CPU0_TDO")
	)
	(segment
		(start 498.92458 -129.276094)
		(end 498.92458 -129.89814)
		(width 0.10795)
		(layer "B.Cu")
		(net "JTAG_MCP_CPU0_TDO")
	)
	(segment
		(start 496.1763 -135.0899)
		(end 496.3922 -135.3058)
		(width 0.10795)
		(layer "B.Cu")
		(net "JTAG_MCP_CPU0_TDO")
	)
	(segment
		(start 498.221 -133.161024)
		(end 497.1542 -132.094224)
		(width 0.10795)
		(layer "B.Cu")
		(net "JTAG_MCP_CPU0_TDO")
	)
	(segment
		(start 496.3922 -135.3058)
		(end 497.7384 -135.3058)
		(width 0.10795)
		(layer "B.Cu")
		(net "JTAG_MCP_CPU0_TDO")
	)
	(segment
		(start 497.7384 -135.3058)
		(end 498.0178 -135.0264)
		(width 0.10795)
		(layer "B.Cu")
		(net "JTAG_MCP_CPU0_TDO")
	)
	(segment
		(start 495.01552 -134.13994)
		(end 495.96548 -135.0899)
		(width 0.10795)
		(layer "B.Cu")
		(net "JTAG_MCP_CPU0_TDO")
	)
	(segment
		(start 495.01552 -133.6675)
		(end 495.01552 -134.13994)
		(width 0.10795)
		(layer "B.Cu")
		(net "JTAG_MCP_CPU0_TDO")
	)
	(segment
		(start 497.6114 -129.921)
		(end 498.073426 -129.458974)
		(width 0.10795)
		(layer "B.Cu")
		(net "JTAG_MCP_CPU0_TDO")
	)
	(segment
		(start 497.6114 -131.0132)
		(end 497.6114 -129.921)
		(width 0.10795)
		(layer "B.Cu")
		(net "JTAG_MCP_CPU0_TDO")
	)
	(segment
		(start 498.978174 -128.52654)
		(end 498.978174 -129.2225)
		(width 0.10795)
		(layer "B.Cu")
		(net "JTAG_MCP_CPU0_TDO")
	)
	(segment
		(start 495.96548 -135.0899)
		(end 496.1763 -135.0899)
		(width 0.10795)
		(layer "B.Cu")
		(net "JTAG_MCP_CPU0_TDO")
	)
	(segment
		(start 498.0178 -135.0264)
		(end 498.221 -134.8232)
		(width 0.10795)
		(layer "B.Cu")
		(net "JTAG_MCP_CPU0_TDO")
	)
	(segment
		(start 475.902528 -127.229616)
		(end 475.89694 -127.229616)
		(width 0.089408)
		(layer "In2.Cu")
		(net "JTAG_MCP_CPU0_TDO")
	)
	(segment
		(start 470.393268 -122.248168)
		(end 467.201504 -122.248168)
		(width 0.089408)
		(layer "In2.Cu")
		(net "JTAG_MCP_CPU0_TDO")
	)
	(segment
		(start 475.89694 -127.2286)
		(end 475.3737 -127.2286)
		(width 0.089408)
		(layer "In2.Cu")
		(net "JTAG_MCP_CPU0_TDO")
	)
	(segment
		(start 434.428138 -122.421142)
		(end 433.326794 -123.522486)
		(width 0.089408)
		(layer "In2.Cu")
		(net "JTAG_MCP_CPU0_TDO")
	)
	(segment
		(start 428.778924 -122.782076)
		(end 428.625 -122.936)
		(width 0.089408)
		(layer "In2.Cu")
		(net "JTAG_MCP_CPU0_TDO")
	)
	(segment
		(start 456.11161 -125.410976)
		(end 455.59472 -124.894086)
		(width 0.089408)
		(layer "In2.Cu")
		(net "JTAG_MCP_CPU0_TDO")
	)
	(segment
		(start 431.808636 -123.522486)
		(end 431.068226 -122.782076)
		(width 0.089408)
		(layer "In2.Cu")
		(net "JTAG_MCP_CPU0_TDO")
	)
	(segment
		(start 467.201504 -122.248168)
		(end 464.038696 -125.410976)
		(width 0.089408)
		(layer "In2.Cu")
		(net "JTAG_MCP_CPU0_TDO")
	)
	(segment
		(start 464.038696 -125.410976)
		(end 456.11161 -125.410976)
		(width 0.089408)
		(layer "In2.Cu")
		(net "JTAG_MCP_CPU0_TDO")
	)
	(segment
		(start 440.026044 -121.99112)
		(end 439.596022 -122.421142)
		(width 0.089408)
		(layer "In2.Cu")
		(net "JTAG_MCP_CPU0_TDO")
	)
	(segment
		(start 455.59472 -124.894086)
		(end 455.59472 -123.858782)
		(width 0.089408)
		(layer "In2.Cu")
		(net "JTAG_MCP_CPU0_TDO")
	)
	(segment
		(start 453.352662 -123.0376)
		(end 453.056498 -123.0376)
		(width 0.089408)
		(layer "In2.Cu")
		(net "JTAG_MCP_CPU0_TDO")
	)
	(segment
		(start 453.352916 -123.037854)
		(end 453.352662 -123.0376)
		(width 0.089408)
		(layer "In2.Cu")
		(net "JTAG_MCP_CPU0_TDO")
	)
	(segment
		(start 454.773538 -123.0376)
		(end 453.553322 -123.0376)
		(width 0.089408)
		(layer "In2.Cu")
		(net "JTAG_MCP_CPU0_TDO")
	)
	(segment
		(start 453.553322 -123.0376)
		(end 453.553068 -123.037854)
		(width 0.089408)
		(layer "In2.Cu")
		(net "JTAG_MCP_CPU0_TDO")
	)
	(segment
		(start 475.3737 -127.2286)
		(end 470.393268 -122.248168)
		(width 0.089408)
		(layer "In2.Cu")
		(net "JTAG_MCP_CPU0_TDO")
	)
	(segment
		(start 453.553068 -123.037854)
		(end 453.352916 -123.037854)
		(width 0.089408)
		(layer "In2.Cu")
		(net "JTAG_MCP_CPU0_TDO")
	)
	(segment
		(start 439.596022 -122.421142)
		(end 434.428138 -122.421142)
		(width 0.089408)
		(layer "In2.Cu")
		(net "JTAG_MCP_CPU0_TDO")
	)
	(segment
		(start 452.010018 -121.99112)
		(end 440.026044 -121.99112)
		(width 0.089408)
		(layer "In2.Cu")
		(net "JTAG_MCP_CPU0_TDO")
	)
	(segment
		(start 433.326794 -123.522486)
		(end 431.808636 -123.522486)
		(width 0.089408)
		(layer "In2.Cu")
		(net "JTAG_MCP_CPU0_TDO")
	)
	(segment
		(start 455.59472 -123.858782)
		(end 454.773538 -123.0376)
		(width 0.089408)
		(layer "In2.Cu")
		(net "JTAG_MCP_CPU0_TDO")
	)
	(segment
		(start 475.89694 -127.229616)
		(end 475.89694 -127.2286)
		(width 0.089408)
		(layer "In2.Cu")
		(net "JTAG_MCP_CPU0_TDO")
	)
	(segment
		(start 453.056498 -123.0376)
		(end 452.010018 -121.99112)
		(width 0.089408)
		(layer "In2.Cu")
		(net "JTAG_MCP_CPU0_TDO")
	)
	(segment
		(start 431.068226 -122.782076)
		(end 428.778924 -122.782076)
		(width 0.089408)
		(layer "In2.Cu")
		(net "JTAG_MCP_CPU0_TDO")
	)
	(segment
		(start 496.647216 -129.642108)
		(end 498.668548 -129.642108)
		(width 0.089408)
		(layer "In9.Cu")
		(net "JTAG_MCP_CPU0_TDO")
	)
	(segment
		(start 331.146912 -123.767088)
		(end 330.566776 -124.347224)
		(width 0.089408)
		(layer "In9.Cu")
		(net "JTAG_MCP_CPU0_TDO")
	)
	(segment
		(start 498.668548 -129.642108)
		(end 498.92458 -129.89814)
		(width 0.089408)
		(layer "In9.Cu")
		(net "JTAG_MCP_CPU0_TDO")
	)
	(segment
		(start 482.0666 -128.1176)
		(end 483.235 -129.286)
		(width 0.089408)
		(layer "In9.Cu")
		(net "JTAG_MCP_CPU0_TDO")
	)
	(segment
		(start 490.36478 -132.461)
		(end 493.828324 -132.461)
		(width 0.089408)
		(layer "In9.Cu")
		(net "JTAG_MCP_CPU0_TDO")
	)
	(segment
		(start 483.235 -129.286)
		(end 486.283 -129.286)
		(width 0.089408)
		(layer "In9.Cu")
		(net "JTAG_MCP_CPU0_TDO")
	)
	(segment
		(start 324.809358 -126.51359)
		(end 324.5612 -126.265432)
		(width 0.089408)
		(layer "In9.Cu")
		(net "JTAG_MCP_CPU0_TDO")
	)
	(segment
		(start 493.828324 -132.461)
		(end 496.647216 -129.642108)
		(width 0.089408)
		(layer "In9.Cu")
		(net "JTAG_MCP_CPU0_TDO")
	)
	(segment
		(start 325.514716 -126.51359)
		(end 324.809358 -126.51359)
		(width 0.089408)
		(layer "In9.Cu")
		(net "JTAG_MCP_CPU0_TDO")
	)
	(segment
		(start 328.81951 -124.565156)
		(end 327.46315 -124.565156)
		(width 0.089408)
		(layer "In9.Cu")
		(net "JTAG_MCP_CPU0_TDO")
	)
	(segment
		(start 338.889848 -123.767088)
		(end 331.146912 -123.767088)
		(width 0.089408)
		(layer "In9.Cu")
		(net "JTAG_MCP_CPU0_TDO")
	)
	(segment
		(start 488.7468 -130.84302)
		(end 490.36478 -132.461)
		(width 0.089408)
		(layer "In9.Cu")
		(net "JTAG_MCP_CPU0_TDO")
	)
	(segment
		(start 330.566776 -124.347224)
		(end 329.037442 -124.347224)
		(width 0.089408)
		(layer "In9.Cu")
		(net "JTAG_MCP_CPU0_TDO")
	)
	(segment
		(start 329.037442 -124.347224)
		(end 328.81951 -124.565156)
		(width 0.089408)
		(layer "In9.Cu")
		(net "JTAG_MCP_CPU0_TDO")
	)
	(segment
		(start 486.283 -129.286)
		(end 487.84002 -130.84302)
		(width 0.089408)
		(layer "In9.Cu")
		(net "JTAG_MCP_CPU0_TDO")
	)
	(segment
		(start 475.902528 -127.406908)
		(end 476.61322 -128.1176)
		(width 0.089408)
		(layer "In9.Cu")
		(net "JTAG_MCP_CPU0_TDO")
	)
	(segment
		(start 342.276684 -121.131838)
		(end 341.525098 -121.131838)
		(width 0.089408)
		(layer "In9.Cu")
		(net "JTAG_MCP_CPU0_TDO")
	)
	(segment
		(start 475.902528 -127.229616)
		(end 475.902528 -127.406908)
		(width 0.089408)
		(layer "In9.Cu")
		(net "JTAG_MCP_CPU0_TDO")
	)
	(segment
		(start 327.46315 -124.565156)
		(end 325.514716 -126.51359)
		(width 0.089408)
		(layer "In9.Cu")
		(net "JTAG_MCP_CPU0_TDO")
	)
	(segment
		(start 476.61322 -128.1176)
		(end 482.0666 -128.1176)
		(width 0.089408)
		(layer "In9.Cu")
		(net "JTAG_MCP_CPU0_TDO")
	)
	(segment
		(start 487.84002 -130.84302)
		(end 488.7468 -130.84302)
		(width 0.089408)
		(layer "In9.Cu")
		(net "JTAG_MCP_CPU0_TDO")
	)
	(segment
		(start 341.525098 -121.131838)
		(end 338.889848 -123.767088)
		(width 0.089408)
		(layer "In9.Cu")
		(net "JTAG_MCP_CPU0_TDO")
	)
	(segment
		(start 412.60776 -135.218678)
		(end 414.894014 -135.218678)
		(width 0.089408)
		(layer "In11.Cu")
		(net "JTAG_MCP_CPU0_TDO")
	)
	(segment
		(start 372.056406 -128.35255)
		(end 373.627396 -128.35255)
		(width 0.089408)
		(layer "In11.Cu")
		(net "JTAG_MCP_CPU0_TDO")
	)
	(segment
		(start 373.973852 -128.699006)
		(end 374.324118 -128.699006)
		(width 0.089408)
		(layer "In11.Cu")
		(net "JTAG_MCP_CPU0_TDO")
	)
	(segment
		(start 426.489114 -125.071886)
		(end 428.625 -122.936)
		(width 0.089408)
		(layer "In11.Cu")
		(net "JTAG_MCP_CPU0_TDO")
	)
	(segment
		(start 292.876478 -94.842076)
		(end 292.881304 -94.83344)
		(width 0.089408)
		(layer "In11.Cu")
		(net "JTAG_MCP_CPU0_TDO")
	)
	(segment
		(start 344.934286 -120.03151)
		(end 345.074748 -120.171972)
		(width 0.089408)
		(layer "In11.Cu")
		(net "JTAG_MCP_CPU0_TDO")
	)
	(segment
		(start 289.453574 -87.31885)
		(end 289.447224 -87.308182)
		(width 0.089408)
		(layer "In11.Cu")
		(net "JTAG_MCP_CPU0_TDO")
	)
	(segment
		(start 292.881304 -96.223582)
		(end 292.876478 -96.214946)
		(width 0.089408)
		(layer "In11.Cu")
		(net "JTAG_MCP_CPU0_TDO")
	)
	(segment
		(start 296.23258 -103.19258)
		(end 296.23258 -102.710234)
		(width 0.089408)
		(layer "In11.Cu")
		(net "JTAG_MCP_CPU0_TDO")
	)
	(segment
		(start 289.453574 -86.32825)
		(end 289.447224 -86.317582)
		(width 0.089408)
		(layer "In11.Cu")
		(net "JTAG_MCP_CPU0_TDO")
	)
	(segment
		(start 289.81781 -90.480134)
		(end 289.786568 -90.480134)
		(width 0.089408)
		(layer "In11.Cu")
		(net "JTAG_MCP_CPU0_TDO")
	)
	(segment
		(start 375.570496 -129.945384)
		(end 378.360432 -129.945384)
		(width 0.089408)
		(layer "In11.Cu")
		(net "JTAG_MCP_CPU0_TDO")
	)
	(segment
		(start 293.739824 -100.681282)
		(end 293.734998 -100.672646)
		(width 0.089408)
		(layer "In11.Cu")
		(net "JTAG_MCP_CPU0_TDO")
	)
	(segment
		(start 292.887654 -96.23425)
		(end 292.881304 -96.223582)
		(width 0.089408)
		(layer "In11.Cu")
		(net "JTAG_MCP_CPU0_TDO")
	)
	(segment
		(start 400.63166 -135.498078)
		(end 404.31212 -135.498078)
		(width 0.089408)
		(layer "In11.Cu")
		(net "JTAG_MCP_CPU0_TDO")
	)
	(segment
		(start 320.775838 -124.097796)
		(end 320.775838 -123.113038)
		(width 0.089408)
		(layer "In11.Cu")
		(net "JTAG_MCP_CPU0_TDO")
	)
	(segment
		(start 409.695904 -135.080756)
		(end 412.469838 -135.080756)
		(width 0.089408)
		(layer "In11.Cu")
		(net "JTAG_MCP_CPU0_TDO")
	)
	(segment
		(start 343.867486 -120.03151)
		(end 344.934286 -120.03151)
		(width 0.089408)
		(layer "In11.Cu")
		(net "JTAG_MCP_CPU0_TDO")
	)
	(segment
		(start 297.859704 -103.378)
		(end 296.418 -103.378)
		(width 0.089408)
		(layer "In11.Cu")
		(net "JTAG_MCP_CPU0_TDO")
	)
	(segment
		(start 412.469838 -135.080756)
		(end 412.60776 -135.218678)
		(width 0.089408)
		(layer "In11.Cu")
		(net "JTAG_MCP_CPU0_TDO")
	)
	(segment
		(start 415.234628 -134.878064)
		(end 417.304474 -134.878064)
		(width 0.089408)
		(layer "In11.Cu")
		(net "JTAG_MCP_CPU0_TDO")
	)
	(segment
		(start 426.251116 -127.176784)
		(end 426.260768 -127.176784)
		(width 0.089408)
		(layer "In11.Cu")
		(net "JTAG_MCP_CPU0_TDO")
	)
	(segment
		(start 292.881304 -97.214182)
		(end 292.876478 -97.205546)
		(width 0.089408)
		(layer "In11.Cu")
		(net "JTAG_MCP_CPU0_TDO")
	)
	(segment
		(start 369.27663 -125.572774)
		(end 372.056406 -128.35255)
		(width 0.089408)
		(layer "In11.Cu")
		(net "JTAG_MCP_CPU0_TDO")
	)
	(segment
		(start 289.453574 -89.30005)
		(end 289.447224 -89.289382)
		(width 0.089408)
		(layer "In11.Cu")
		(net "JTAG_MCP_CPU0_TDO")
	)
	(segment
		(start 289.447224 -84.336382)
		(end 289.442398 -84.327746)
		(width 0.089408)
		(layer "In11.Cu")
		(net "JTAG_MCP_CPU0_TDO")
	)
	(segment
		(start 383.150364 -132.588508)
		(end 385.374642 -132.588508)
		(width 0.089408)
		(layer "In11.Cu")
		(net "JTAG_MCP_CPU0_TDO")
	)
	(segment
		(start 345.074748 -120.171972)
		(end 366.733328 -120.171972)
		(width 0.089408)
		(layer "In11.Cu")
		(net "JTAG_MCP_CPU0_TDO")
	)
	(segment
		(start 385.374642 -132.588508)
		(end 389.026654 -136.24052)
		(width 0.089408)
		(layer "In11.Cu")
		(net "JTAG_MCP_CPU0_TDO")
	)
	(segment
		(start 289.447224 -86.317582)
		(end 289.442398 -86.308946)
		(width 0.089408)
		(layer "In11.Cu")
		(net "JTAG_MCP_CPU0_TDO")
	)
	(segment
		(start 292.887654 -93.26245)
		(end 292.881304 -93.251782)
		(width 0.089408)
		(layer "In11.Cu")
		(net "JTAG_MCP_CPU0_TDO")
	)
	(segment
		(start 301.700438 -107.218734)
		(end 297.859704 -103.378)
		(width 0.089408)
		(layer "In11.Cu")
		(net "JTAG_MCP_CPU0_TDO")
	)
	(segment
		(start 417.304474 -134.878064)
		(end 424.057826 -128.124712)
		(width 0.089408)
		(layer "In11.Cu")
		(net "JTAG_MCP_CPU0_TDO")
	)
	(segment
		(start 292.881304 -93.251782)
		(end 292.876478 -93.243146)
		(width 0.089408)
		(layer "In11.Cu")
		(net "JTAG_MCP_CPU0_TDO")
	)
	(segment
		(start 289.447224 -83.345782)
		(end 289.442398 -83.337146)
		(width 0.089408)
		(layer "In11.Cu")
		(net "JTAG_MCP_CPU0_TDO")
	)
	(segment
		(start 295.29151 -101.76764)
		(end 295.109392 -101.452426)
		(width 0.089408)
		(layer "In11.Cu")
		(net "JTAG_MCP_CPU0_TDO")
	)
	(segment
		(start 366.733328 -120.171972)
		(end 369.27663 -122.715274)
		(width 0.089408)
		(layer "In11.Cu")
		(net "JTAG_MCP_CPU0_TDO")
	)
	(segment
		(start 373.627396 -128.35255)
		(end 373.973852 -128.699006)
		(width 0.089408)
		(layer "In11.Cu")
		(net "JTAG_MCP_CPU0_TDO")
	)
	(segment
		(start 296.418 -103.378)
		(end 296.23258 -103.19258)
		(width 0.089408)
		(layer "In11.Cu")
		(net "JTAG_MCP_CPU0_TDO")
	)
	(segment
		(start 342.276684 -121.131838)
		(end 343.136728 -121.131838)
		(width 0.089408)
		(layer "In11.Cu")
		(net "JTAG_MCP_CPU0_TDO")
	)
	(segment
		(start 426.489114 -126.948438)
		(end 426.489114 -125.071886)
		(width 0.089408)
		(layer "In11.Cu")
		(net "JTAG_MCP_CPU0_TDO")
	)
	(segment
		(start 289.453574 -83.35645)
		(end 289.447224 -83.345782)
		(width 0.089408)
		(layer "In11.Cu")
		(net "JTAG_MCP_CPU0_TDO")
	)
	(segment
		(start 292.887654 -97.22485)
		(end 292.881304 -97.214182)
		(width 0.089408)
		(layer "In11.Cu")
		(net "JTAG_MCP_CPU0_TDO")
	)
	(segment
		(start 343.515696 -120.75287)
		(end 343.515696 -120.3833)
		(width 0.089408)
		(layer "In11.Cu")
		(net "JTAG_MCP_CPU0_TDO")
	)
	(segment
		(start 293.739824 -100.28174)
		(end 293.746174 -100.271072)
		(width 0.089408)
		(layer "In11.Cu")
		(net "JTAG_MCP_CPU0_TDO")
	)
	(segment
		(start 295.814496 -102.062534)
		(end 295.778428 -102.062534)
		(width 0.089408)
		(layer "In11.Cu")
		(net "JTAG_MCP_CPU0_TDO")
	)
	(segment
		(start 289.453574 -84.34705)
		(end 289.447224 -84.336382)
		(width 0.089408)
		(layer "In11.Cu")
		(net "JTAG_MCP_CPU0_TDO")
	)
	(segment
		(start 322.222876 -125.121162)
		(end 321.799204 -125.121162)
		(width 0.089408)
		(layer "In11.Cu")
		(net "JTAG_MCP_CPU0_TDO")
	)
	(segment
		(start 319.697862 -122.035062)
		(end 317.422276 -122.035062)
		(width 0.089408)
		(layer "In11.Cu")
		(net "JTAG_MCP_CPU0_TDO")
	)
	(segment
		(start 293.25189 -99.395534)
		(end 293.220648 -99.395534)
		(width 0.089408)
		(layer "In11.Cu")
		(net "JTAG_MCP_CPU0_TDO")
	)
	(segment
		(start 369.27663 -122.715274)
		(end 369.27663 -125.572774)
		(width 0.089408)
		(layer "In11.Cu")
		(net "JTAG_MCP_CPU0_TDO")
	)
	(segment
		(start 321.799204 -125.121162)
		(end 320.775838 -124.097796)
		(width 0.089408)
		(layer "In11.Cu")
		(net "JTAG_MCP_CPU0_TDO")
	)
	(segment
		(start 323.60489 -125.309122)
		(end 322.410836 -125.309122)
		(width 0.089408)
		(layer "In11.Cu")
		(net "JTAG_MCP_CPU0_TDO")
	)
	(segment
		(start 389.026654 -136.24052)
		(end 399.889218 -136.24052)
		(width 0.089408)
		(layer "In11.Cu")
		(net "JTAG_MCP_CPU0_TDO")
	)
	(segment
		(start 414.894014 -135.218678)
		(end 415.234628 -134.878064)
		(width 0.089408)
		(layer "In11.Cu")
		(net "JTAG_MCP_CPU0_TDO")
	)
	(segment
		(start 289.463734 -82.918046)
		(end 289.79368 -82.155284)
		(width 0.089408)
		(layer "In11.Cu")
		(net "JTAG_MCP_CPU0_TDO")
	)
	(segment
		(start 424.057826 -128.124712)
		(end 425.303188 -128.124712)
		(width 0.089408)
		(layer "In11.Cu")
		(net "JTAG_MCP_CPU0_TDO")
	)
	(segment
		(start 382.352804 -131.790948)
		(end 383.150364 -132.588508)
		(width 0.089408)
		(layer "In11.Cu")
		(net "JTAG_MCP_CPU0_TDO")
	)
	(segment
		(start 378.360432 -129.945384)
		(end 380.205996 -131.790948)
		(width 0.089408)
		(layer "In11.Cu")
		(net "JTAG_MCP_CPU0_TDO")
	)
	(segment
		(start 343.136728 -121.131838)
		(end 343.515696 -120.75287)
		(width 0.089408)
		(layer "In11.Cu")
		(net "JTAG_MCP_CPU0_TDO")
	)
	(segment
		(start 289.447224 -88.298782)
		(end 289.442398 -88.290146)
		(width 0.089408)
		(layer "In11.Cu")
		(net "JTAG_MCP_CPU0_TDO")
	)
	(segment
		(start 317.422276 -122.035062)
		(end 302.605948 -107.218734)
		(width 0.089408)
		(layer "In11.Cu")
		(net "JTAG_MCP_CPU0_TDO")
	)
	(segment
		(start 289.447224 -85.326982)
		(end 289.442398 -85.318346)
		(width 0.089408)
		(layer "In11.Cu")
		(net "JTAG_MCP_CPU0_TDO")
	)
	(segment
		(start 296.23258 -102.406196)
		(end 296.15003 -102.262686)
		(width 0.089408)
		(layer "In11.Cu")
		(net "JTAG_MCP_CPU0_TDO")
	)
	(segment
		(start 295.109392 -101.452426)
		(end 294.854122 -101.395784)
		(width 0.089408)
		(layer "In11.Cu")
		(net "JTAG_MCP_CPU0_TDO")
	)
	(segment
		(start 292.887654 -98.21545)
		(end 292.881304 -98.204782)
		(width 0.089408)
		(layer "In11.Cu")
		(net "JTAG_MCP_CPU0_TDO")
	)
	(segment
		(start 426.260768 -127.176784)
		(end 426.489114 -126.948438)
		(width 0.089408)
		(layer "In11.Cu")
		(net "JTAG_MCP_CPU0_TDO")
	)
	(segment
		(start 292.887654 -95.24365)
		(end 292.881304 -95.232982)
		(width 0.089408)
		(layer "In11.Cu")
		(net "JTAG_MCP_CPU0_TDO")
	)
	(segment
		(start 292.881304 -98.204782)
		(end 292.876478 -98.196146)
		(width 0.089408)
		(layer "In11.Cu")
		(net "JTAG_MCP_CPU0_TDO")
	)
	(segment
		(start 291.53485 -91.470734)
		(end 291.503608 -91.470734)
		(width 0.089408)
		(layer "In11.Cu")
		(net "JTAG_MCP_CPU0_TDO")
	)
	(segment
		(start 322.410836 -125.309122)
		(end 322.222876 -125.121162)
		(width 0.089408)
		(layer "In11.Cu")
		(net "JTAG_MCP_CPU0_TDO")
	)
	(segment
		(start 292.389814 -91.96578)
		(end 292.357048 -91.96578)
		(width 0.089408)
		(layer "In11.Cu")
		(net "JTAG_MCP_CPU0_TDO")
	)
	(segment
		(start 374.324118 -128.699006)
		(end 375.570496 -129.945384)
		(width 0.089408)
		(layer "In11.Cu")
		(net "JTAG_MCP_CPU0_TDO")
	)
	(segment
		(start 320.775838 -123.113038)
		(end 319.697862 -122.035062)
		(width 0.089408)
		(layer "In11.Cu")
		(net "JTAG_MCP_CPU0_TDO")
	)
	(segment
		(start 380.205996 -131.790948)
		(end 382.352804 -131.790948)
		(width 0.089408)
		(layer "In11.Cu")
		(net "JTAG_MCP_CPU0_TDO")
	)
	(segment
		(start 324.5612 -126.265432)
		(end 323.60489 -125.309122)
		(width 0.089408)
		(layer "In11.Cu")
		(net "JTAG_MCP_CPU0_TDO")
	)
	(segment
		(start 289.447224 -89.289382)
		(end 289.442398 -89.280746)
		(width 0.089408)
		(layer "In11.Cu")
		(net "JTAG_MCP_CPU0_TDO")
	)
	(segment
		(start 406.98674 -136.249156)
		(end 409.695904 -135.080756)
		(width 0.089408)
		(layer "In11.Cu")
		(net "JTAG_MCP_CPU0_TDO")
	)
	(segment
		(start 302.605948 -107.218734)
		(end 301.700438 -107.218734)
		(width 0.089408)
		(layer "In11.Cu")
		(net "JTAG_MCP_CPU0_TDO")
	)
	(segment
		(start 425.303188 -128.124712)
		(end 426.251116 -127.176784)
		(width 0.089408)
		(layer "In11.Cu")
		(net "JTAG_MCP_CPU0_TDO")
	)
	(segment
		(start 289.447224 -87.308182)
		(end 289.442398 -87.299546)
		(width 0.089408)
		(layer "In11.Cu")
		(net "JTAG_MCP_CPU0_TDO")
	)
	(segment
		(start 289.453574 -85.33765)
		(end 289.447224 -85.326982)
		(width 0.089408)
		(layer "In11.Cu")
		(net "JTAG_MCP_CPU0_TDO")
	)
	(segment
		(start 343.515696 -120.3833)
		(end 343.867486 -120.03151)
		(width 0.089408)
		(layer "In11.Cu")
		(net "JTAG_MCP_CPU0_TDO")
	)
	(segment
		(start 289.447224 -82.94624)
		(end 289.463734 -82.918046)
		(width 0.089408)
		(layer "In11.Cu")
		(net "JTAG_MCP_CPU0_TDO")
	)
	(segment
		(start 290.672774 -90.97518)
		(end 290.640008 -90.97518)
		(width 0.089408)
		(layer "In11.Cu")
		(net "JTAG_MCP_CPU0_TDO")
	)
	(segment
		(start 404.31212 -135.498078)
		(end 405.063198 -136.249156)
		(width 0.089408)
		(layer "In11.Cu")
		(net "JTAG_MCP_CPU0_TDO")
	)
	(segment
		(start 399.889218 -136.24052)
		(end 400.63166 -135.498078)
		(width 0.089408)
		(layer "In11.Cu")
		(net "JTAG_MCP_CPU0_TDO")
	)
	(segment
		(start 405.063198 -136.249156)
		(end 406.98674 -136.249156)
		(width 0.089408)
		(layer "In11.Cu")
		(net "JTAG_MCP_CPU0_TDO")
	)
	(segment
		(start 289.453574 -88.30945)
		(end 289.447224 -88.298782)
		(width 0.089408)
		(layer "In11.Cu")
		(net "JTAG_MCP_CPU0_TDO")
	)
	(arc
		(start 289.447224 -89.88044)
		(mid 289.526539 -89.591068)
		(end 289.453574 -89.30005)
		(width 0.089408)
		(layer "In11.Cu")
		(net "JTAG_MCP_CPU0_TDO")
	)
	(arc
		(start 293.746174 -100.271072)
		(mid 293.742837 -99.695611)
		(end 293.25189 -99.395534)
		(width 0.089408)
		(layer "In11.Cu")
		(net "JTAG_MCP_CPU0_TDO")
	)
	(arc
		(start 289.786568 -90.480134)
		(mid 289.445655 -90.277228)
		(end 289.447224 -89.88044)
		(width 0.089408)
		(layer "In11.Cu")
		(net "JTAG_MCP_CPU0_TDO")
	)
	(arc
		(start 294.148764 -100.89642)
		(mid 293.912382 -100.849507)
		(end 293.739824 -100.681282)
		(width 0.089408)
		(layer "In11.Cu")
		(net "JTAG_MCP_CPU0_TDO")
	)
	(arc
		(start 289.447224 -84.92744)
		(mid 289.526539 -84.638068)
		(end 289.453574 -84.34705)
		(width 0.089408)
		(layer "In11.Cu")
		(net "JTAG_MCP_CPU0_TDO")
	)
	(arc
		(start 289.447224 -87.89924)
		(mid 289.526539 -87.609868)
		(end 289.453574 -87.31885)
		(width 0.089408)
		(layer "In11.Cu")
		(net "JTAG_MCP_CPU0_TDO")
	)
	(arc
		(start 289.447224 -83.93684)
		(mid 289.526539 -83.647468)
		(end 289.453574 -83.35645)
		(width 0.089408)
		(layer "In11.Cu")
		(net "JTAG_MCP_CPU0_TDO")
	)
	(arc
		(start 292.881304 -95.232982)
		(mid 292.827927 -95.038173)
		(end 292.876478 -94.842076)
		(width 0.089408)
		(layer "In11.Cu")
		(net "JTAG_MCP_CPU0_TDO")
	)
	(arc
		(start 292.881304 -95.82404)
		(mid 292.960619 -95.534668)
		(end 292.887654 -95.24365)
		(width 0.089408)
		(layer "In11.Cu")
		(net "JTAG_MCP_CPU0_TDO")
	)
	(arc
		(start 292.876478 -97.205546)
		(mid 292.827814 -97.009448)
		(end 292.881304 -96.81464)
		(width 0.089408)
		(layer "In11.Cu")
		(net "JTAG_MCP_CPU0_TDO")
	)
	(arc
		(start 292.881304 -94.242636)
		(mid 292.827771 -94.042738)
		(end 292.881304 -93.84284)
		(width 0.089408)
		(layer "In11.Cu")
		(net "JTAG_MCP_CPU0_TDO")
	)
	(arc
		(start 292.876478 -98.196146)
		(mid 292.827814 -98.000048)
		(end 292.881304 -97.80524)
		(width 0.089408)
		(layer "In11.Cu")
		(net "JTAG_MCP_CPU0_TDO")
	)
	(arc
		(start 292.876478 -96.214946)
		(mid 292.827814 -96.018848)
		(end 292.881304 -95.82404)
		(width 0.089408)
		(layer "In11.Cu")
		(net "JTAG_MCP_CPU0_TDO")
	)
	(arc
		(start 292.881304 -93.84284)
		(mid 292.960619 -93.553468)
		(end 292.887654 -93.26245)
		(width 0.089408)
		(layer "In11.Cu")
		(net "JTAG_MCP_CPU0_TDO")
	)
	(arc
		(start 296.23258 -102.710234)
		(mid 296.273237 -102.558232)
		(end 296.23258 -102.406196)
		(width 0.089408)
		(layer "In11.Cu")
		(net "JTAG_MCP_CPU0_TDO")
	)
	(arc
		(start 289.442398 -87.299546)
		(mid 289.393734 -87.103448)
		(end 289.447224 -86.90864)
		(width 0.089408)
		(layer "In11.Cu")
		(net "JTAG_MCP_CPU0_TDO")
	)
	(arc
		(start 293.220648 -99.395534)
		(mid 292.879735 -99.192628)
		(end 292.881304 -98.79584)
		(width 0.089408)
		(layer "In11.Cu")
		(net "JTAG_MCP_CPU0_TDO")
	)
	(arc
		(start 289.442398 -83.337146)
		(mid 289.393734 -83.141048)
		(end 289.447224 -82.94624)
		(width 0.089408)
		(layer "In11.Cu")
		(net "JTAG_MCP_CPU0_TDO")
	)
	(arc
		(start 289.447224 -86.90864)
		(mid 289.526539 -86.619268)
		(end 289.453574 -86.32825)
		(width 0.089408)
		(layer "In11.Cu")
		(net "JTAG_MCP_CPU0_TDO")
	)
	(arc
		(start 291.164264 -91.270582)
		(mid 290.956735 -91.059298)
		(end 290.672774 -90.97518)
		(width 0.089408)
		(layer "In11.Cu")
		(net "JTAG_MCP_CPU0_TDO")
	)
	(arc
		(start 289.442398 -85.318346)
		(mid 289.393734 -85.122248)
		(end 289.447224 -84.92744)
		(width 0.089408)
		(layer "In11.Cu")
		(net "JTAG_MCP_CPU0_TDO")
	)
	(arc
		(start 289.442398 -84.327746)
		(mid 289.393734 -84.131648)
		(end 289.447224 -83.93684)
		(width 0.089408)
		(layer "In11.Cu")
		(net "JTAG_MCP_CPU0_TDO")
	)
	(arc
		(start 295.778428 -102.062534)
		(mid 295.497128 -101.977568)
		(end 295.29151 -101.76764)
		(width 0.089408)
		(layer "In11.Cu")
		(net "JTAG_MCP_CPU0_TDO")
	)
	(arc
		(start 292.881304 -98.79584)
		(mid 292.960619 -98.506468)
		(end 292.887654 -98.21545)
		(width 0.089408)
		(layer "In11.Cu")
		(net "JTAG_MCP_CPU0_TDO")
	)
	(arc
		(start 292.881304 -97.80524)
		(mid 292.960619 -97.515868)
		(end 292.887654 -97.22485)
		(width 0.089408)
		(layer "In11.Cu")
		(net "JTAG_MCP_CPU0_TDO")
	)
	(arc
		(start 292.357048 -91.96578)
		(mid 292.163945 -91.909261)
		(end 292.022784 -91.765882)
		(width 0.089408)
		(layer "In11.Cu")
		(net "JTAG_MCP_CPU0_TDO")
	)
	(arc
		(start 294.854122 -101.395784)
		(mid 294.670874 -101.305242)
		(end 294.550592 -101.140006)
		(width 0.089408)
		(layer "In11.Cu")
		(net "JTAG_MCP_CPU0_TDO")
	)
	(arc
		(start 289.442398 -88.290146)
		(mid 289.393734 -88.094048)
		(end 289.447224 -87.89924)
		(width 0.089408)
		(layer "In11.Cu")
		(net "JTAG_MCP_CPU0_TDO")
	)
	(arc
		(start 290.305744 -90.775282)
		(mid 290.099707 -90.565004)
		(end 289.81781 -90.480134)
		(width 0.089408)
		(layer "In11.Cu")
		(net "JTAG_MCP_CPU0_TDO")
	)
	(arc
		(start 296.15003 -102.262686)
		(mid 296.008347 -102.118882)
		(end 295.814496 -102.062534)
		(width 0.089408)
		(layer "In11.Cu")
		(net "JTAG_MCP_CPU0_TDO")
	)
	(arc
		(start 289.447224 -85.91804)
		(mid 289.526539 -85.628668)
		(end 289.453574 -85.33765)
		(width 0.089408)
		(layer "In11.Cu")
		(net "JTAG_MCP_CPU0_TDO")
	)
	(arc
		(start 291.503608 -91.470734)
		(mid 291.307576 -91.41535)
		(end 291.164264 -91.270582)
		(width 0.089408)
		(layer "In11.Cu")
		(net "JTAG_MCP_CPU0_TDO")
	)
	(arc
		(start 294.550592 -101.140006)
		(mid 294.389858 -100.951907)
		(end 294.148764 -100.89642)
		(width 0.089408)
		(layer "In11.Cu")
		(net "JTAG_MCP_CPU0_TDO")
	)
	(arc
		(start 289.442398 -86.308946)
		(mid 289.393734 -86.112848)
		(end 289.447224 -85.91804)
		(width 0.089408)
		(layer "In11.Cu")
		(net "JTAG_MCP_CPU0_TDO")
	)
	(arc
		(start 292.881304 -96.81464)
		(mid 292.960619 -96.525268)
		(end 292.887654 -96.23425)
		(width 0.089408)
		(layer "In11.Cu")
		(net "JTAG_MCP_CPU0_TDO")
	)
	(arc
		(start 292.876478 -93.243146)
		(mid 292.827814 -93.047048)
		(end 292.881304 -92.85224)
		(width 0.089408)
		(layer "In11.Cu")
		(net "JTAG_MCP_CPU0_TDO")
	)
	(arc
		(start 292.022784 -91.765882)
		(mid 291.816747 -91.555604)
		(end 291.53485 -91.470734)
		(width 0.089408)
		(layer "In11.Cu")
		(net "JTAG_MCP_CPU0_TDO")
	)
	(arc
		(start 292.881304 -94.83344)
		(mid 292.960401 -94.538038)
		(end 292.881304 -94.242636)
		(width 0.089408)
		(layer "In11.Cu")
		(net "JTAG_MCP_CPU0_TDO")
	)
	(arc
		(start 289.442398 -89.280746)
		(mid 289.393734 -89.084648)
		(end 289.447224 -88.88984)
		(width 0.089408)
		(layer "In11.Cu")
		(net "JTAG_MCP_CPU0_TDO")
	)
	(arc
		(start 289.447224 -88.88984)
		(mid 289.526539 -88.600468)
		(end 289.453574 -88.30945)
		(width 0.089408)
		(layer "In11.Cu")
		(net "JTAG_MCP_CPU0_TDO")
	)
	(arc
		(start 293.734998 -100.672646)
		(mid 293.686334 -100.476548)
		(end 293.739824 -100.28174)
		(width 0.089408)
		(layer "In11.Cu")
		(net "JTAG_MCP_CPU0_TDO")
	)
	(arc
		(start 292.881304 -92.85224)
		(mid 292.886382 -92.269903)
		(end 292.389814 -91.96578)
		(width 0.089408)
		(layer "In11.Cu")
		(net "JTAG_MCP_CPU0_TDO")
	)
	(arc
		(start 290.640008 -90.97518)
		(mid 290.446905 -90.918661)
		(end 290.305744 -90.775282)
		(width 0.089408)
		(layer "In11.Cu")
		(net "JTAG_MCP_CPU0_TDO")
	)
	(segment
		(start 401.814538 2.678938)
		(end 402.336 3.2004)
		(width 0.10795)
		(layer "F.Cu")
		(net "JTAG_PLD_TMS")
	)
	(segment
		(start 401.814538 1.702308)
		(end 401.814538 2.678938)
		(width 0.10795)
		(layer "F.Cu")
		(net "JTAG_PLD_TMS")
	)
	(segment
		(start 402.336 3.2004)
		(end 403.606 3.2004)
		(width 0.10795)
		(layer "F.Cu")
		(net "JTAG_PLD_TMS")
	)
	(segment
		(start 373.544846 -68.695316)
		(end 373.14505 -69.095112)
		(width 0.1016)
		(layer "F.Cu")
		(net "JTAG_PLD_TMS")
	)
	(via
		(at 453.482964 -2.0574)
		(size 0.508)
		(drill 0.254)
		(layers "F.Cu" "B.Cu")
		(net "JTAG_PLD_TMS")
	)
	(via
		(at 373.544846 -68.695316)
		(size 0.4572)
		(drill 0.2032)
		(layers "F.Cu" "B.Cu")
		(net "JTAG_PLD_TMS")
	)
	(via
		(at 401.814538 1.702308)
		(size 0.508)
		(drill 0.254)
		(layers "F.Cu" "B.Cu")
		(net "JTAG_PLD_TMS")
	)
	(via
		(at 381.54991 -63.8048)
		(size 0.508)
		(drill 0.254)
		(layers "F.Cu" "B.Cu")
		(net "JTAG_PLD_TMS")
	)
	(segment
		(start 380.586996 -66.877184)
		(end 380.383542 -66.877184)
		(width 0.089408)
		(layer "In2.Cu")
		(net "JTAG_PLD_TMS")
	)
	(segment
		(start 373.961914 -68.278248)
		(end 373.544846 -68.695316)
		(width 0.089408)
		(layer "In2.Cu")
		(net "JTAG_PLD_TMS")
	)
	(segment
		(start 379.258576 -66.877184)
		(end 377.857512 -68.278248)
		(width 0.089408)
		(layer "In2.Cu")
		(net "JTAG_PLD_TMS")
	)
	(segment
		(start 381.54991 -63.8048)
		(end 381.54991 -65.91427)
		(width 0.089408)
		(layer "In2.Cu")
		(net "JTAG_PLD_TMS")
	)
	(segment
		(start 377.857512 -68.278248)
		(end 373.961914 -68.278248)
		(width 0.089408)
		(layer "In2.Cu")
		(net "JTAG_PLD_TMS")
	)
	(segment
		(start 380.383034 -66.876676)
		(end 380.182882 -66.876676)
		(width 0.089408)
		(layer "In2.Cu")
		(net "JTAG_PLD_TMS")
	)
	(segment
		(start 379.940312 -66.87693)
		(end 379.940058 -66.877184)
		(width 0.089408)
		(layer "In2.Cu")
		(net "JTAG_PLD_TMS")
	)
	(segment
		(start 380.182628 -66.87693)
		(end 379.940312 -66.87693)
		(width 0.089408)
		(layer "In2.Cu")
		(net "JTAG_PLD_TMS")
	)
	(segment
		(start 379.940058 -66.877184)
		(end 379.258576 -66.877184)
		(width 0.089408)
		(layer "In2.Cu")
		(net "JTAG_PLD_TMS")
	)
	(segment
		(start 380.182882 -66.876676)
		(end 380.182628 -66.87693)
		(width 0.089408)
		(layer "In2.Cu")
		(net "JTAG_PLD_TMS")
	)
	(segment
		(start 381.54991 -65.91427)
		(end 380.586996 -66.877184)
		(width 0.089408)
		(layer "In2.Cu")
		(net "JTAG_PLD_TMS")
	)
	(segment
		(start 380.383542 -66.877184)
		(end 380.383034 -66.876676)
		(width 0.089408)
		(layer "In2.Cu")
		(net "JTAG_PLD_TMS")
	)
	(segment
		(start 405.131524 2.298192)
		(end 411.953456 2.298192)
		(width 0.089408)
		(layer "In4.Cu")
		(net "JTAG_PLD_TMS")
	)
	(segment
		(start 422.600628 1.519682)
		(end 430.271428 1.519682)
		(width 0.089408)
		(layer "In4.Cu")
		(net "JTAG_PLD_TMS")
	)
	(segment
		(start 431.989738 -0.198628)
		(end 451.624192 -0.198628)
		(width 0.089408)
		(layer "In4.Cu")
		(net "JTAG_PLD_TMS")
	)
	(segment
		(start 402.214842 1.302004)
		(end 404.135336 1.302004)
		(width 0.089408)
		(layer "In4.Cu")
		(net "JTAG_PLD_TMS")
	)
	(segment
		(start 430.271428 1.519682)
		(end 431.989738 -0.198628)
		(width 0.089408)
		(layer "In4.Cu")
		(net "JTAG_PLD_TMS")
	)
	(segment
		(start 401.814538 1.702308)
		(end 402.214842 1.302004)
		(width 0.089408)
		(layer "In4.Cu")
		(net "JTAG_PLD_TMS")
	)
	(segment
		(start 451.624192 -0.198628)
		(end 453.482964 -2.0574)
		(width 0.089408)
		(layer "In4.Cu")
		(net "JTAG_PLD_TMS")
	)
	(segment
		(start 411.953456 2.298192)
		(end 412.526988 1.72466)
		(width 0.089408)
		(layer "In4.Cu")
		(net "JTAG_PLD_TMS")
	)
	(segment
		(start 404.135336 1.302004)
		(end 405.131524 2.298192)
		(width 0.089408)
		(layer "In4.Cu")
		(net "JTAG_PLD_TMS")
	)
	(segment
		(start 415.572702 3.026918)
		(end 421.093392 3.026918)
		(width 0.089408)
		(layer "In4.Cu")
		(net "JTAG_PLD_TMS")
	)
	(segment
		(start 414.270444 1.72466)
		(end 415.572702 3.026918)
		(width 0.089408)
		(layer "In4.Cu")
		(net "JTAG_PLD_TMS")
	)
	(segment
		(start 421.093392 3.026918)
		(end 422.600628 1.519682)
		(width 0.089408)
		(layer "In4.Cu")
		(net "JTAG_PLD_TMS")
	)
	(segment
		(start 412.526988 1.72466)
		(end 414.270444 1.72466)
		(width 0.089408)
		(layer "In4.Cu")
		(net "JTAG_PLD_TMS")
	)
	(segment
		(start 405.101298 -10.073894)
		(end 407.993088 -7.182104)
		(width 0.089408)
		(layer "In11.Cu")
		(net "JTAG_PLD_TMS")
	)
	(segment
		(start 382.312672 -59.830208)
		(end 382.312672 -56.49849)
		(width 0.089408)
		(layer "In11.Cu")
		(net "JTAG_PLD_TMS")
	)
	(segment
		(start 449.525644 -6.99135)
		(end 450.2658 -6.251194)
		(width 0.089408)
		(layer "In11.Cu")
		(net "JTAG_PLD_TMS")
	)
	(segment
		(start 371.333776 -26.6192)
		(end 371.333776 -21.531072)
		(width 0.089408)
		(layer "In11.Cu")
		(net "JTAG_PLD_TMS")
	)
	(segment
		(start 445.790066 -6.647688)
		(end 446.864232 -6.647688)
		(width 0.089408)
		(layer "In11.Cu")
		(net "JTAG_PLD_TMS")
	)
	(segment
		(start 371.889528 -47.557182)
		(end 371.889528 -46.90237)
		(width 0.089408)
		(layer "In11.Cu")
		(net "JTAG_PLD_TMS")
	)
	(segment
		(start 381.830072 -55.291482)
		(end 379.572774 -53.034184)
		(width 0.089408)
		(layer "In11.Cu")
		(net "JTAG_PLD_TMS")
	)
	(segment
		(start 401.168108 -10.233152)
		(end 404.94204 -10.233152)
		(width 0.089408)
		(layer "In11.Cu")
		(net "JTAG_PLD_TMS")
	)
	(segment
		(start 399.514568 -11.886692)
		(end 401.168108 -10.233152)
		(width 0.089408)
		(layer "In11.Cu")
		(net "JTAG_PLD_TMS")
	)
	(segment
		(start 369.89766 -28.055316)
		(end 371.333776 -26.6192)
		(width 0.089408)
		(layer "In11.Cu")
		(net "JTAG_PLD_TMS")
	)
	(segment
		(start 370.293646 -34.636202)
		(end 369.89766 -34.240216)
		(width 0.089408)
		(layer "In11.Cu")
		(net "JTAG_PLD_TMS")
	)
	(segment
		(start 373.26824 -48.935894)
		(end 371.889528 -47.557182)
		(width 0.089408)
		(layer "In11.Cu")
		(net "JTAG_PLD_TMS")
	)
	(segment
		(start 381.830072 -55.61457)
		(end 381.830072 -55.291482)
		(width 0.089408)
		(layer "In11.Cu")
		(net "JTAG_PLD_TMS")
	)
	(segment
		(start 371.333776 -21.531072)
		(end 380.978156 -11.886692)
		(width 0.089408)
		(layer "In11.Cu")
		(net "JTAG_PLD_TMS")
	)
	(segment
		(start 450.2658 -6.251194)
		(end 450.2658 -5.35559)
		(width 0.089408)
		(layer "In11.Cu")
		(net "JTAG_PLD_TMS")
	)
	(segment
		(start 381.829818 -56.015636)
		(end 381.829818 -55.614824)
		(width 0.089408)
		(layer "In11.Cu")
		(net "JTAG_PLD_TMS")
	)
	(segment
		(start 373.923052 -48.935894)
		(end 373.26824 -48.935894)
		(width 0.089408)
		(layer "In11.Cu")
		(net "JTAG_PLD_TMS")
	)
	(segment
		(start 408.19324 -7.182104)
		(end 408.193494 -7.182358)
		(width 0.089408)
		(layer "In11.Cu")
		(net "JTAG_PLD_TMS")
	)
	(segment
		(start 381.54991 -63.598552)
		(end 381.508 -63.556642)
		(width 0.089408)
		(layer "In11.Cu")
		(net "JTAG_PLD_TMS")
	)
	(segment
		(start 445.255396 -7.182358)
		(end 445.790066 -6.647688)
		(width 0.089408)
		(layer "In11.Cu")
		(net "JTAG_PLD_TMS")
	)
	(segment
		(start 382.312672 -56.49849)
		(end 381.829818 -56.015636)
		(width 0.089408)
		(layer "In11.Cu")
		(net "JTAG_PLD_TMS")
	)
	(segment
		(start 380.978156 -11.886692)
		(end 399.514568 -11.886692)
		(width 0.089408)
		(layer "In11.Cu")
		(net "JTAG_PLD_TMS")
	)
	(segment
		(start 404.94204 -10.233152)
		(end 405.101298 -10.073894)
		(width 0.0889)
		(layer "In11.Cu")
		(net "JTAG_PLD_TMS")
	)
	(segment
		(start 378.021342 -53.034184)
		(end 373.923052 -48.935894)
		(width 0.089408)
		(layer "In11.Cu")
		(net "JTAG_PLD_TMS")
	)
	(segment
		(start 381.54991 -63.8048)
		(end 381.54991 -63.598552)
		(width 0.089408)
		(layer "In11.Cu")
		(net "JTAG_PLD_TMS")
	)
	(segment
		(start 381.508 -60.63488)
		(end 382.312672 -59.830208)
		(width 0.089408)
		(layer "In11.Cu")
		(net "JTAG_PLD_TMS")
	)
	(segment
		(start 446.864232 -6.647688)
		(end 447.207894 -6.99135)
		(width 0.089408)
		(layer "In11.Cu")
		(net "JTAG_PLD_TMS")
	)
	(segment
		(start 447.207894 -6.99135)
		(end 449.525644 -6.99135)
		(width 0.089408)
		(layer "In11.Cu")
		(net "JTAG_PLD_TMS")
	)
	(segment
		(start 408.193494 -7.182358)
		(end 445.255396 -7.182358)
		(width 0.089408)
		(layer "In11.Cu")
		(net "JTAG_PLD_TMS")
	)
	(segment
		(start 370.293646 -45.306488)
		(end 370.293646 -34.636202)
		(width 0.089408)
		(layer "In11.Cu")
		(net "JTAG_PLD_TMS")
	)
	(segment
		(start 453.482964 -2.138426)
		(end 453.482964 -2.0574)
		(width 0.089408)
		(layer "In11.Cu")
		(net "JTAG_PLD_TMS")
	)
	(segment
		(start 381.508 -63.556642)
		(end 381.508 -60.63488)
		(width 0.089408)
		(layer "In11.Cu")
		(net "JTAG_PLD_TMS")
	)
	(segment
		(start 407.993088 -7.182104)
		(end 408.19324 -7.182104)
		(width 0.089408)
		(layer "In11.Cu")
		(net "JTAG_PLD_TMS")
	)
	(segment
		(start 371.889528 -46.90237)
		(end 370.293646 -45.306488)
		(width 0.089408)
		(layer "In11.Cu")
		(net "JTAG_PLD_TMS")
	)
	(segment
		(start 381.829818 -55.614824)
		(end 381.830072 -55.61457)
		(width 0.089408)
		(layer "In11.Cu")
		(net "JTAG_PLD_TMS")
	)
	(segment
		(start 379.572774 -53.034184)
		(end 378.021342 -53.034184)
		(width 0.089408)
		(layer "In11.Cu")
		(net "JTAG_PLD_TMS")
	)
	(segment
		(start 450.2658 -5.35559)
		(end 453.482964 -2.138426)
		(width 0.089408)
		(layer "In11.Cu")
		(net "JTAG_PLD_TMS")
	)
	(segment
		(start 369.89766 -34.240216)
		(end 369.89766 -28.055316)
		(width 0.089408)
		(layer "In11.Cu")
		(net "JTAG_PLD_TMS")
	)
	(segment
		(start 375.144792 -69.495162)
		(end 374.744996 -69.894958)
		(width 0.10795)
		(layer "F.Cu")
		(net "JTAG_PLD_TDO")
	)
	(via
		(at 464.791552 -2.72669)
		(size 0.508)
		(drill 0.254)
		(layers "F.Cu" "B.Cu")
		(net "JTAG_PLD_TDO")
	)
	(via
		(at 384.6576 -0.889)
		(size 0.508)
		(drill 0.254)
		(layers "F.Cu" "B.Cu")
		(net "JTAG_PLD_TDO")
	)
	(via
		(at 375.144792 -69.495162)
		(size 0.4572)
		(drill 0.2032)
		(layers "F.Cu" "B.Cu")
		(net "JTAG_PLD_TDO")
	)
	(via
		(at 382.212088 -65.844166)
		(size 0.508)
		(drill 0.254)
		(layers "F.Cu" "B.Cu")
		(net "JTAG_PLD_TDO")
	)
	(segment
		(start 389.6106 -1.47955)
		(end 389.47725 -1.3462)
		(width 0.10795)
		(layer "B.Cu")
		(net "JTAG_PLD_TDO")
	)
	(segment
		(start 386.63753 -2.66827)
		(end 388.106666 -2.66827)
		(width 0.10795)
		(layer "B.Cu")
		(net "JTAG_PLD_TDO")
	)
	(segment
		(start 385.3688 -3.0988)
		(end 386.207 -3.0988)
		(width 0.10795)
		(layer "B.Cu")
		(net "JTAG_PLD_TDO")
	)
	(segment
		(start 385.1148 -1.3462)
		(end 384.6576 -0.889)
		(width 0.10795)
		(layer "B.Cu")
		(net "JTAG_PLD_TDO")
	)
	(segment
		(start 386.207 -3.0988)
		(end 386.63753 -2.66827)
		(width 0.10795)
		(layer "B.Cu")
		(net "JTAG_PLD_TDO")
	)
	(segment
		(start 388.32155 -2.453386)
		(end 388.9248 -2.453386)
		(width 0.10795)
		(layer "B.Cu")
		(net "JTAG_PLD_TDO")
	)
	(segment
		(start 389.47725 -1.3462)
		(end 385.1148 -1.3462)
		(width 0.10795)
		(layer "B.Cu")
		(net "JTAG_PLD_TDO")
	)
	(segment
		(start 388.106666 -2.66827)
		(end 388.32155 -2.453386)
		(width 0.10795)
		(layer "B.Cu")
		(net "JTAG_PLD_TDO")
	)
	(segment
		(start 388.9248 -2.453386)
		(end 389.45693 -2.453386)
		(width 0.10795)
		(layer "B.Cu")
		(net "JTAG_PLD_TDO")
	)
	(segment
		(start 389.6106 -2.299716)
		(end 389.6106 -1.47955)
		(width 0.10795)
		(layer "B.Cu")
		(net "JTAG_PLD_TDO")
	)
	(segment
		(start 389.45693 -2.453386)
		(end 389.6106 -2.299716)
		(width 0.10795)
		(layer "B.Cu")
		(net "JTAG_PLD_TDO")
	)
	(segment
		(start 405.629618 2.465832)
		(end 406.010618 2.465832)
		(width 0.089408)
		(layer "In2.Cu")
		(net "JTAG_PLD_TDO")
	)
	(segment
		(start 464.7946 -2.616454)
		(end 464.7946 -2.72669)
		(width 0.089408)
		(layer "In2.Cu")
		(net "JTAG_PLD_TDO")
	)
	(segment
		(start 398.202912 0.423672)
		(end 399.063464 1.284224)
		(width 0.089408)
		(layer "In2.Cu")
		(net "JTAG_PLD_TDO")
	)
	(segment
		(start 427.24451 2.286)
		(end 463.220054 2.286)
		(width 0.089408)
		(layer "In2.Cu")
		(net "JTAG_PLD_TDO")
	)
	(segment
		(start 375.539 -69.100954)
		(end 377.74245 -69.100954)
		(width 0.089408)
		(layer "In2.Cu")
		(net "JTAG_PLD_TDO")
	)
	(segment
		(start 406.211278 2.465832)
		(end 420.950898 2.465832)
		(width 0.089408)
		(layer "In2.Cu")
		(net "JTAG_PLD_TDO")
	)
	(segment
		(start 420.950898 2.465832)
		(end 422.494202 0.922528)
		(width 0.089408)
		(layer "In2.Cu")
		(net "JTAG_PLD_TDO")
	)
	(segment
		(start 464.590384 0.12954)
		(end 464.934808 -0.214884)
		(width 0.089408)
		(layer "In2.Cu")
		(net "JTAG_PLD_TDO")
	)
	(segment
		(start 406.211024 2.466086)
		(end 406.211278 2.465832)
		(width 0.089408)
		(layer "In2.Cu")
		(net "JTAG_PLD_TDO")
	)
	(segment
		(start 379.104906 -67.372992)
		(end 379.358906 -67.118992)
		(width 0.089408)
		(layer "In2.Cu")
		(net "JTAG_PLD_TDO")
	)
	(segment
		(start 382.034288 -65.844166)
		(end 382.212088 -65.844166)
		(width 0.089408)
		(layer "In2.Cu")
		(net "JTAG_PLD_TDO")
	)
	(segment
		(start 385.970272 0.423672)
		(end 398.202912 0.423672)
		(width 0.089408)
		(layer "In2.Cu")
		(net "JTAG_PLD_TDO")
	)
	(segment
		(start 406.010618 2.465832)
		(end 406.010872 2.466086)
		(width 0.089408)
		(layer "In2.Cu")
		(net "JTAG_PLD_TDO")
	)
	(segment
		(start 422.494202 0.922528)
		(end 425.881038 0.922528)
		(width 0.089408)
		(layer "In2.Cu")
		(net "JTAG_PLD_TDO")
	)
	(segment
		(start 377.923552 -68.919852)
		(end 377.923552 -68.50634)
		(width 0.089408)
		(layer "In2.Cu")
		(net "JTAG_PLD_TDO")
	)
	(segment
		(start 464.590384 0.91567)
		(end 464.590384 0.12954)
		(width 0.089408)
		(layer "In2.Cu")
		(net "JTAG_PLD_TDO")
	)
	(segment
		(start 404.44801 1.284224)
		(end 405.629618 2.465832)
		(width 0.089408)
		(layer "In2.Cu")
		(net "JTAG_PLD_TDO")
	)
	(segment
		(start 464.934808 -0.214884)
		(end 464.934808 -2.476246)
		(width 0.089408)
		(layer "In2.Cu")
		(net "JTAG_PLD_TDO")
	)
	(segment
		(start 384.6576 -0.889)
		(end 385.970272 0.423672)
		(width 0.089408)
		(layer "In2.Cu")
		(net "JTAG_PLD_TDO")
	)
	(segment
		(start 406.010872 2.466086)
		(end 406.211024 2.466086)
		(width 0.089408)
		(layer "In2.Cu")
		(net "JTAG_PLD_TDO")
	)
	(segment
		(start 377.74245 -69.100954)
		(end 377.923552 -68.919852)
		(width 0.089408)
		(layer "In2.Cu")
		(net "JTAG_PLD_TDO")
	)
	(segment
		(start 379.0569 -67.372992)
		(end 379.104906 -67.372992)
		(width 0.089408)
		(layer "In2.Cu")
		(net "JTAG_PLD_TDO")
	)
	(segment
		(start 463.220054 2.286)
		(end 464.590384 0.91567)
		(width 0.089408)
		(layer "In2.Cu")
		(net "JTAG_PLD_TDO")
	)
	(segment
		(start 464.934808 -2.476246)
		(end 464.7946 -2.616454)
		(width 0.089408)
		(layer "In2.Cu")
		(net "JTAG_PLD_TDO")
	)
	(segment
		(start 399.063464 1.284224)
		(end 404.44801 1.284224)
		(width 0.089408)
		(layer "In2.Cu")
		(net "JTAG_PLD_TDO")
	)
	(segment
		(start 377.923552 -68.50634)
		(end 379.0569 -67.372992)
		(width 0.089408)
		(layer "In2.Cu")
		(net "JTAG_PLD_TDO")
	)
	(segment
		(start 464.7946 -2.72669)
		(end 464.791552 -2.72669)
		(width 0.089408)
		(layer "In2.Cu")
		(net "JTAG_PLD_TDO")
	)
	(segment
		(start 425.881038 0.922528)
		(end 427.24451 2.286)
		(width 0.089408)
		(layer "In2.Cu")
		(net "JTAG_PLD_TDO")
	)
	(segment
		(start 380.759462 -67.118992)
		(end 382.034288 -65.844166)
		(width 0.089408)
		(layer "In2.Cu")
		(net "JTAG_PLD_TDO")
	)
	(segment
		(start 375.144792 -69.495162)
		(end 375.539 -69.100954)
		(width 0.089408)
		(layer "In2.Cu")
		(net "JTAG_PLD_TDO")
	)
	(segment
		(start 379.358906 -67.118992)
		(end 380.759462 -67.118992)
		(width 0.089408)
		(layer "In2.Cu")
		(net "JTAG_PLD_TDO")
	)
	(segment
		(start 372.373144 -47.350426)
		(end 372.373144 -46.70171)
		(width 0.089408)
		(layer "In11.Cu")
		(net "JTAG_PLD_TDO")
	)
	(segment
		(start 462.5848 -2.278634)
		(end 463.034634 -1.8288)
		(width 0.089408)
		(layer "In11.Cu")
		(net "JTAG_PLD_TDO")
	)
	(segment
		(start 379.773434 -52.550568)
		(end 378.323348 -52.550568)
		(width 0.089408)
		(layer "In11.Cu")
		(net "JTAG_PLD_TDO")
	)
	(segment
		(start 463.034634 -1.8288)
		(end 463.8294 -1.8288)
		(width 0.089408)
		(layer "In11.Cu")
		(net "JTAG_PLD_TDO")
	)
	(segment
		(start 405.1427 -10.716768)
		(end 408.193494 -7.665974)
		(width 0.089408)
		(layer "In11.Cu")
		(net "JTAG_PLD_TDO")
	)
	(segment
		(start 445.456056 -7.665974)
		(end 445.990726 -7.131304)
		(width 0.089408)
		(layer "In11.Cu")
		(net "JTAG_PLD_TDO")
	)
	(segment
		(start 463.8294 -1.8288)
		(end 464.72729 -2.72669)
		(width 0.089408)
		(layer "In11.Cu")
		(net "JTAG_PLD_TDO")
	)
	(segment
		(start 382.410716 -63.613284)
		(end 382.410716 -60.41644)
		(width 0.089408)
		(layer "In11.Cu")
		(net "JTAG_PLD_TDO")
	)
	(segment
		(start 445.990726 -7.131304)
		(end 446.663572 -7.131304)
		(width 0.089408)
		(layer "In11.Cu")
		(net "JTAG_PLD_TDO")
	)
	(segment
		(start 372.373144 -46.70171)
		(end 370.777262 -45.105828)
		(width 0.089408)
		(layer "In11.Cu")
		(net "JTAG_PLD_TDO")
	)
	(segment
		(start 382.313688 -55.81523)
		(end 382.313688 -55.320946)
		(width 0.089408)
		(layer "In11.Cu")
		(net "JTAG_PLD_TDO")
	)
	(segment
		(start 370.777262 -45.105828)
		(end 370.777262 -34.435542)
		(width 0.089408)
		(layer "In11.Cu")
		(net "JTAG_PLD_TDO")
	)
	(segment
		(start 464.72729 -2.72669)
		(end 464.791552 -2.72669)
		(width 0.089408)
		(layer "In11.Cu")
		(net "JTAG_PLD_TDO")
	)
	(segment
		(start 371.817392 -26.81986)
		(end 371.817392 -21.731732)
		(width 0.089408)
		(layer "In11.Cu")
		(net "JTAG_PLD_TDO")
	)
	(segment
		(start 370.777262 -34.435542)
		(end 370.487448 -34.145728)
		(width 0.089408)
		(layer "In11.Cu")
		(net "JTAG_PLD_TDO")
	)
	(segment
		(start 453.324214 -3.877056)
		(end 460.721964 -3.877056)
		(width 0.089408)
		(layer "In11.Cu")
		(net "JTAG_PLD_TDO")
	)
	(segment
		(start 408.193494 -7.665974)
		(end 445.456056 -7.665974)
		(width 0.089408)
		(layer "In11.Cu")
		(net "JTAG_PLD_TDO")
	)
	(segment
		(start 382.796288 -56.29783)
		(end 382.313688 -55.81523)
		(width 0.089408)
		(layer "In11.Cu")
		(net "JTAG_PLD_TDO")
	)
	(segment
		(start 462.5848 -3.37566)
		(end 462.5848 -2.278634)
		(width 0.089408)
		(layer "In11.Cu")
		(net "JTAG_PLD_TDO")
	)
	(segment
		(start 460.721964 -3.877056)
		(end 460.934308 -4.0894)
		(width 0.089408)
		(layer "In11.Cu")
		(net "JTAG_PLD_TDO")
	)
	(segment
		(start 382.796288 -60.030868)
		(end 382.796288 -56.29783)
		(width 0.089408)
		(layer "In11.Cu")
		(net "JTAG_PLD_TDO")
	)
	(segment
		(start 381.178816 -12.370308)
		(end 399.715228 -12.370308)
		(width 0.089408)
		(layer "In11.Cu")
		(net "JTAG_PLD_TDO")
	)
	(segment
		(start 401.368768 -10.716768)
		(end 405.1427 -10.716768)
		(width 0.089408)
		(layer "In11.Cu")
		(net "JTAG_PLD_TDO")
	)
	(segment
		(start 382.313942 -55.320692)
		(end 382.313942 -55.091076)
		(width 0.089408)
		(layer "In11.Cu")
		(net "JTAG_PLD_TDO")
	)
	(segment
		(start 370.487448 -34.145728)
		(end 370.487448 -28.149804)
		(width 0.089408)
		(layer "In11.Cu")
		(net "JTAG_PLD_TDO")
	)
	(segment
		(start 382.410716 -60.41644)
		(end 382.796288 -60.030868)
		(width 0.089408)
		(layer "In11.Cu")
		(net "JTAG_PLD_TDO")
	)
	(segment
		(start 399.715228 -12.370308)
		(end 401.368768 -10.716768)
		(width 0.089408)
		(layer "In11.Cu")
		(net "JTAG_PLD_TDO")
	)
	(segment
		(start 373.3419 -48.319182)
		(end 372.373144 -47.350426)
		(width 0.089408)
		(layer "In11.Cu")
		(net "JTAG_PLD_TDO")
	)
	(segment
		(start 371.817392 -21.731732)
		(end 381.178816 -12.370308)
		(width 0.089408)
		(layer "In11.Cu")
		(net "JTAG_PLD_TDO")
	)
	(segment
		(start 378.323348 -52.550568)
		(end 374.091962 -48.319182)
		(width 0.089408)
		(layer "In11.Cu")
		(net "JTAG_PLD_TDO")
	)
	(segment
		(start 461.87106 -4.0894)
		(end 462.5848 -3.37566)
		(width 0.089408)
		(layer "In11.Cu")
		(net "JTAG_PLD_TDO")
	)
	(segment
		(start 382.065784 -64.731138)
		(end 382.07061 -64.726312)
		(width 0.089408)
		(layer "In11.Cu")
		(net "JTAG_PLD_TDO")
	)
	(segment
		(start 446.663572 -7.131304)
		(end 447.050668 -7.5184)
		(width 0.089408)
		(layer "In11.Cu")
		(net "JTAG_PLD_TDO")
	)
	(segment
		(start 382.07061 -64.726312)
		(end 382.07061 -63.95339)
		(width 0.089408)
		(layer "In11.Cu")
		(net "JTAG_PLD_TDO")
	)
	(segment
		(start 382.313942 -55.091076)
		(end 379.773434 -52.550568)
		(width 0.089408)
		(layer "In11.Cu")
		(net "JTAG_PLD_TDO")
	)
	(segment
		(start 382.212088 -65.844166)
		(end 382.065784 -65.697862)
		(width 0.089408)
		(layer "In11.Cu")
		(net "JTAG_PLD_TDO")
	)
	(segment
		(start 382.065784 -65.697862)
		(end 382.065784 -64.731138)
		(width 0.089408)
		(layer "In11.Cu")
		(net "JTAG_PLD_TDO")
	)
	(segment
		(start 370.487448 -28.149804)
		(end 371.817392 -26.81986)
		(width 0.089408)
		(layer "In11.Cu")
		(net "JTAG_PLD_TDO")
	)
	(segment
		(start 460.934308 -4.0894)
		(end 461.87106 -4.0894)
		(width 0.089408)
		(layer "In11.Cu")
		(net "JTAG_PLD_TDO")
	)
	(segment
		(start 374.091962 -48.319182)
		(end 373.3419 -48.319182)
		(width 0.089408)
		(layer "In11.Cu")
		(net "JTAG_PLD_TDO")
	)
	(segment
		(start 449.68287 -7.5184)
		(end 453.324214 -3.877056)
		(width 0.089408)
		(layer "In11.Cu")
		(net "JTAG_PLD_TDO")
	)
	(segment
		(start 447.050668 -7.5184)
		(end 449.68287 -7.5184)
		(width 0.089408)
		(layer "In11.Cu")
		(net "JTAG_PLD_TDO")
	)
	(segment
		(start 382.313688 -55.320946)
		(end 382.313942 -55.320692)
		(width 0.089408)
		(layer "In11.Cu")
		(net "JTAG_PLD_TDO")
	)
	(segment
		(start 382.07061 -63.95339)
		(end 382.410716 -63.613284)
		(width 0.089408)
		(layer "In11.Cu")
		(net "JTAG_PLD_TDO")
	)
	(segment
		(start 379.69952 -67.4624)
		(end 374.852946 -67.4624)
		(width 0.10795)
		(layer "F.Cu")
		(net "JTAG_PLD_TDI")
	)
	(segment
		(start 381.975868 -62.402212)
		(end 382.110996 -62.53734)
		(width 0.10795)
		(layer "F.Cu")
		(net "JTAG_PLD_TDI")
	)
	(segment
		(start 403.606 4.0894)
		(end 402.971 4.0894)
		(width 0.10795)
		(layer "F.Cu")
		(net "JTAG_PLD_TDI")
	)
	(segment
		(start 381.919226 -65.242694)
		(end 379.69952 -67.4624)
		(width 0.10795)
		(layer "F.Cu")
		(net "JTAG_PLD_TDI")
	)
	(segment
		(start 381.919226 -64.545718)
		(end 381.919226 -65.242694)
		(width 0.10795)
		(layer "F.Cu")
		(net "JTAG_PLD_TDI")
	)
	(segment
		(start 382.110996 -62.53734)
		(end 382.110996 -64.353948)
		(width 0.10795)
		(layer "F.Cu")
		(net "JTAG_PLD_TDI")
	)
	(segment
		(start 374.852946 -67.4624)
		(end 374.744996 -67.57035)
		(width 0.10795)
		(layer "F.Cu")
		(net "JTAG_PLD_TDI")
	)
	(segment
		(start 382.110996 -64.353948)
		(end 381.919226 -64.545718)
		(width 0.10795)
		(layer "F.Cu")
		(net "JTAG_PLD_TDI")
	)
	(segment
		(start 374.744996 -67.57035)
		(end 374.744996 -68.295012)
		(width 0.10795)
		(layer "F.Cu")
		(net "JTAG_PLD_TDI")
	)
	(via
		(at 382.558798 -63.038228)
		(size 0.6604)
		(drill 0.3302)
		(layers "F.Cu" "B.Cu")
		(net "JTAG_PLD_TDI")
	)
	(via
		(at 402.971 4.0894)
		(size 0.508)
		(drill 0.254)
		(layers "F.Cu" "B.Cu")
		(net "JTAG_PLD_TDI")
	)
	(via
		(at 381.975868 -62.402212)
		(size 0.508)
		(drill 0.254)
		(layers "F.Cu" "B.Cu")
		(net "JTAG_PLD_TDI")
	)
	(via
		(at 465.5566 -2.6162)
		(size 0.508)
		(drill 0.254)
		(layers "F.Cu" "B.Cu")
		(net "JTAG_PLD_TDI")
	)
	(segment
		(start 381.975868 -62.455298)
		(end 382.558798 -63.038228)
		(width 0.10795)
		(layer "B.Cu")
		(net "JTAG_PLD_TDI")
	)
	(segment
		(start 381.975868 -62.402212)
		(end 381.975868 -62.455298)
		(width 0.10795)
		(layer "B.Cu")
		(net "JTAG_PLD_TDI")
	)
	(segment
		(start 462.85912 2.527046)
		(end 464.204304 1.181862)
		(width 0.089408)
		(layer "In4.Cu")
		(net "JTAG_PLD_TDI")
	)
	(segment
		(start 426.79493 2.577592)
		(end 426.92193 2.577592)
		(width 0.089408)
		(layer "In4.Cu")
		(net "JTAG_PLD_TDI")
	)
	(segment
		(start 411.371288 4.325112)
		(end 413.004 2.6924)
		(width 0.089408)
		(layer "In4.Cu")
		(net "JTAG_PLD_TDI")
	)
	(segment
		(start 426.594524 2.577338)
		(end 426.794676 2.577338)
		(width 0.089408)
		(layer "In4.Cu")
		(net "JTAG_PLD_TDI")
	)
	(segment
		(start 431.058574 2.583688)
		(end 431.115216 2.527046)
		(width 0.089408)
		(layer "In4.Cu")
		(net "JTAG_PLD_TDI")
	)
	(segment
		(start 418.55263 4.087368)
		(end 421.401494 4.087368)
		(width 0.089408)
		(layer "In4.Cu")
		(net "JTAG_PLD_TDI")
	)
	(segment
		(start 464.204304 1.181862)
		(end 464.204304 0.0762)
		(width 0.089408)
		(layer "In4.Cu")
		(net "JTAG_PLD_TDI")
	)
	(segment
		(start 426.794676 2.577338)
		(end 426.79493 2.577592)
		(width 0.089408)
		(layer "In4.Cu")
		(net "JTAG_PLD_TDI")
	)
	(segment
		(start 416.54603 4.087368)
		(end 416.546284 4.087622)
		(width 0.089408)
		(layer "In4.Cu")
		(net "JTAG_PLD_TDI")
	)
	(segment
		(start 423.111676 2.577338)
		(end 423.11193 2.577592)
		(width 0.089408)
		(layer "In4.Cu")
		(net "JTAG_PLD_TDI")
	)
	(segment
		(start 418.552376 4.087622)
		(end 418.55263 4.087368)
		(width 0.089408)
		(layer "In4.Cu")
		(net "JTAG_PLD_TDI")
	)
	(segment
		(start 404.6728 4.0894)
		(end 405.0284 3.7338)
		(width 0.089408)
		(layer "In4.Cu")
		(net "JTAG_PLD_TDI")
	)
	(segment
		(start 409.512262 3.7338)
		(end 410.103574 4.325112)
		(width 0.089408)
		(layer "In4.Cu")
		(net "JTAG_PLD_TDI")
	)
	(segment
		(start 465.0105 -2.0701)
		(end 465.5566 -2.6162)
		(width 0.089408)
		(layer "In4.Cu")
		(net "JTAG_PLD_TDI")
	)
	(segment
		(start 415.2646 4.087368)
		(end 416.54603 4.087368)
		(width 0.089408)
		(layer "In4.Cu")
		(net "JTAG_PLD_TDI")
	)
	(segment
		(start 426.59427 2.577592)
		(end 426.594524 2.577338)
		(width 0.089408)
		(layer "In4.Cu")
		(net "JTAG_PLD_TDI")
	)
	(segment
		(start 413.869632 2.6924)
		(end 415.2646 4.087368)
		(width 0.089408)
		(layer "In4.Cu")
		(net "JTAG_PLD_TDI")
	)
	(segment
		(start 464.204304 0.0762)
		(end 465.0105 -0.729996)
		(width 0.089408)
		(layer "In4.Cu")
		(net "JTAG_PLD_TDI")
	)
	(segment
		(start 413.004 2.6924)
		(end 413.869632 2.6924)
		(width 0.089408)
		(layer "In4.Cu")
		(net "JTAG_PLD_TDI")
	)
	(segment
		(start 423.11193 2.577592)
		(end 426.59427 2.577592)
		(width 0.089408)
		(layer "In4.Cu")
		(net "JTAG_PLD_TDI")
	)
	(segment
		(start 402.971 4.0894)
		(end 404.6728 4.0894)
		(width 0.089408)
		(layer "In4.Cu")
		(net "JTAG_PLD_TDI")
	)
	(segment
		(start 426.928026 2.583688)
		(end 431.058574 2.583688)
		(width 0.089408)
		(layer "In4.Cu")
		(net "JTAG_PLD_TDI")
	)
	(segment
		(start 410.103574 4.325112)
		(end 411.371288 4.325112)
		(width 0.089408)
		(layer "In4.Cu")
		(net "JTAG_PLD_TDI")
	)
	(segment
		(start 431.115216 2.527046)
		(end 462.85912 2.527046)
		(width 0.089408)
		(layer "In4.Cu")
		(net "JTAG_PLD_TDI")
	)
	(segment
		(start 405.0284 3.7338)
		(end 409.512262 3.7338)
		(width 0.089408)
		(layer "In4.Cu")
		(net "JTAG_PLD_TDI")
	)
	(segment
		(start 421.401494 4.087368)
		(end 422.911524 2.577338)
		(width 0.089408)
		(layer "In4.Cu")
		(net "JTAG_PLD_TDI")
	)
	(segment
		(start 465.0105 -0.729996)
		(end 465.0105 -2.0701)
		(width 0.089408)
		(layer "In4.Cu")
		(net "JTAG_PLD_TDI")
	)
	(segment
		(start 422.911524 2.577338)
		(end 423.111676 2.577338)
		(width 0.089408)
		(layer "In4.Cu")
		(net "JTAG_PLD_TDI")
	)
	(segment
		(start 416.546284 4.087622)
		(end 418.552376 4.087622)
		(width 0.089408)
		(layer "In4.Cu")
		(net "JTAG_PLD_TDI")
	)
	(segment
		(start 426.92193 2.577592)
		(end 426.928026 2.583688)
		(width 0.089408)
		(layer "In4.Cu")
		(net "JTAG_PLD_TDI")
	)
	(segment
		(start 382.071626 -55.915306)
		(end 382.071626 -55.715154)
		(width 0.089408)
		(layer "In11.Cu")
		(net "JTAG_PLD_TDI")
	)
	(segment
		(start 462.164938 -3.366262)
		(end 462.164938 -2.236724)
		(width 0.089408)
		(layer "In11.Cu")
		(net "JTAG_PLD_TDI")
	)
	(segment
		(start 370.535454 -45.206158)
		(end 370.535454 -34.535872)
		(width 0.089408)
		(layer "In11.Cu")
		(net "JTAG_PLD_TDI")
	)
	(segment
		(start 370.24564 -28.049474)
		(end 371.575584 -26.71953)
		(width 0.089408)
		(layer "In11.Cu")
		(net "JTAG_PLD_TDI")
	)
	(segment
		(start 378.121672 -52.792376)
		(end 373.890286 -48.56099)
		(width 0.089408)
		(layer "In11.Cu")
		(net "JTAG_PLD_TDI")
	)
	(segment
		(start 449.625974 -7.233158)
		(end 453.08012 -3.779012)
		(width 0.089408)
		(layer "In11.Cu")
		(net "JTAG_PLD_TDI")
	)
	(segment
		(start 453.08012 -3.77698)
		(end 453.22236 -3.63474)
		(width 0.089408)
		(layer "In11.Cu")
		(net "JTAG_PLD_TDI")
	)
	(segment
		(start 371.575584 -26.71953)
		(end 371.575584 -21.631402)
		(width 0.089408)
		(layer "In11.Cu")
		(net "JTAG_PLD_TDI")
	)
	(segment
		(start 399.614898 -12.1285)
		(end 401.268438 -10.47496)
		(width 0.089408)
		(layer "In11.Cu")
		(net "JTAG_PLD_TDI")
	)
	(segment
		(start 382.55448 -59.930538)
		(end 382.55448 -56.39816)
		(width 0.089408)
		(layer "In11.Cu")
		(net "JTAG_PLD_TDI")
	)
	(segment
		(start 460.82204 -3.63474)
		(end 460.973678 -3.786378)
		(width 0.089408)
		(layer "In11.Cu")
		(net "JTAG_PLD_TDI")
	)
	(segment
		(start 453.08012 -3.779012)
		(end 453.08012 -3.77698)
		(width 0.089408)
		(layer "In11.Cu")
		(net "JTAG_PLD_TDI")
	)
	(segment
		(start 445.355726 -7.424166)
		(end 445.890396 -6.889496)
		(width 0.089408)
		(layer "In11.Cu")
		(net "JTAG_PLD_TDI")
	)
	(segment
		(start 460.973678 -3.786378)
		(end 461.744822 -3.786378)
		(width 0.089408)
		(layer "In11.Cu")
		(net "JTAG_PLD_TDI")
	)
	(segment
		(start 447.107564 -7.233158)
		(end 449.625974 -7.233158)
		(width 0.089408)
		(layer "In11.Cu")
		(net "JTAG_PLD_TDI")
	)
	(segment
		(start 462.826862 -1.5748)
		(end 464.0834 -1.5748)
		(width 0.089408)
		(layer "In11.Cu")
		(net "JTAG_PLD_TDI")
	)
	(segment
		(start 372.131336 -46.80204)
		(end 370.535454 -45.206158)
		(width 0.089408)
		(layer "In11.Cu")
		(net "JTAG_PLD_TDI")
	)
	(segment
		(start 465.1756 -2.2352)
		(end 465.5566 -2.6162)
		(width 0.089408)
		(layer "In11.Cu")
		(net "JTAG_PLD_TDI")
	)
	(segment
		(start 445.890396 -6.889496)
		(end 446.763902 -6.889496)
		(width 0.089408)
		(layer "In11.Cu")
		(net "JTAG_PLD_TDI")
	)
	(segment
		(start 372.131336 -47.450756)
		(end 372.131336 -46.80204)
		(width 0.089408)
		(layer "In11.Cu")
		(net "JTAG_PLD_TDI")
	)
	(segment
		(start 382.071626 -55.715154)
		(end 382.07188 -55.7149)
		(width 0.089408)
		(layer "In11.Cu")
		(net "JTAG_PLD_TDI")
	)
	(segment
		(start 381.078486 -12.1285)
		(end 399.614898 -12.1285)
		(width 0.089408)
		(layer "In11.Cu")
		(net "JTAG_PLD_TDI")
	)
	(segment
		(start 408.093164 -7.424166)
		(end 445.355726 -7.424166)
		(width 0.089408)
		(layer "In11.Cu")
		(net "JTAG_PLD_TDI")
	)
	(segment
		(start 401.268438 -10.47496)
		(end 405.04237 -10.47496)
		(width 0.089408)
		(layer "In11.Cu")
		(net "JTAG_PLD_TDI")
	)
	(segment
		(start 382.07188 -55.191152)
		(end 379.673104 -52.792376)
		(width 0.089408)
		(layer "In11.Cu")
		(net "JTAG_PLD_TDI")
	)
	(segment
		(start 464.7438 -2.2352)
		(end 465.1756 -2.2352)
		(width 0.089408)
		(layer "In11.Cu")
		(net "JTAG_PLD_TDI")
	)
	(segment
		(start 382.55448 -56.39816)
		(end 382.071626 -55.915306)
		(width 0.089408)
		(layer "In11.Cu")
		(net "JTAG_PLD_TDI")
	)
	(segment
		(start 370.535454 -34.535872)
		(end 370.24564 -34.246058)
		(width 0.089408)
		(layer "In11.Cu")
		(net "JTAG_PLD_TDI")
	)
	(segment
		(start 373.890286 -48.56099)
		(end 373.24157 -48.56099)
		(width 0.089408)
		(layer "In11.Cu")
		(net "JTAG_PLD_TDI")
	)
	(segment
		(start 382.028192 -62.349888)
		(end 382.028192 -60.456826)
		(width 0.089408)
		(layer "In11.Cu")
		(net "JTAG_PLD_TDI")
	)
	(segment
		(start 382.028192 -60.456826)
		(end 382.55448 -59.930538)
		(width 0.089408)
		(layer "In11.Cu")
		(net "JTAG_PLD_TDI")
	)
	(segment
		(start 462.164938 -2.236724)
		(end 462.826862 -1.5748)
		(width 0.089408)
		(layer "In11.Cu")
		(net "JTAG_PLD_TDI")
	)
	(segment
		(start 381.975868 -62.402212)
		(end 382.028192 -62.349888)
		(width 0.089408)
		(layer "In11.Cu")
		(net "JTAG_PLD_TDI")
	)
	(segment
		(start 461.744822 -3.786378)
		(end 462.164938 -3.366262)
		(width 0.089408)
		(layer "In11.Cu")
		(net "JTAG_PLD_TDI")
	)
	(segment
		(start 379.673104 -52.792376)
		(end 378.121672 -52.792376)
		(width 0.089408)
		(layer "In11.Cu")
		(net "JTAG_PLD_TDI")
	)
	(segment
		(start 464.0834 -1.5748)
		(end 464.7438 -2.2352)
		(width 0.089408)
		(layer "In11.Cu")
		(net "JTAG_PLD_TDI")
	)
	(segment
		(start 453.22236 -3.63474)
		(end 460.82204 -3.63474)
		(width 0.089408)
		(layer "In11.Cu")
		(net "JTAG_PLD_TDI")
	)
	(segment
		(start 370.24564 -34.246058)
		(end 370.24564 -28.049474)
		(width 0.089408)
		(layer "In11.Cu")
		(net "JTAG_PLD_TDI")
	)
	(segment
		(start 371.575584 -21.631402)
		(end 381.078486 -12.1285)
		(width 0.089408)
		(layer "In11.Cu")
		(net "JTAG_PLD_TDI")
	)
	(segment
		(start 405.04237 -10.47496)
		(end 408.093164 -7.424166)
		(width 0.089408)
		(layer "In11.Cu")
		(net "JTAG_PLD_TDI")
	)
	(segment
		(start 382.07188 -55.7149)
		(end 382.07188 -55.191152)
		(width 0.089408)
		(layer "In11.Cu")
		(net "JTAG_PLD_TDI")
	)
	(segment
		(start 373.24157 -48.56099)
		(end 372.131336 -47.450756)
		(width 0.089408)
		(layer "In11.Cu")
		(net "JTAG_PLD_TDI")
	)
	(segment
		(start 446.763902 -6.889496)
		(end 447.107564 -7.233158)
		(width 0.089408)
		(layer "In11.Cu")
		(net "JTAG_PLD_TDI")
	)
	(segment
		(start 398.785842 -26.459688)
		(end 399.38833 -27.062176)
		(width 0.10795)
		(layer "F.Cu")
		(net "JTAG_PLD_TCK")
	)
	(segment
		(start 401.867878 -20.964144)
		(end 401.529042 -20.964144)
		(width 0.10795)
		(layer "F.Cu")
		(net "JTAG_PLD_TCK")
	)
	(segment
		(start 397.8402 0.1778)
		(end 397.8402 -0.7874)
		(width 0.10795)
		(layer "F.Cu")
		(net "JTAG_PLD_TCK")
	)
	(segment
		(start 380.865888 -63.59398)
		(end 380.865888 -64.216026)
		(width 0.10795)
		(layer "F.Cu")
		(net "JTAG_PLD_TCK")
	)
	(segment
		(start 380.865888 -64.216026)
		(end 381.30734 -64.657478)
		(width 0.10795)
		(layer "F.Cu")
		(net "JTAG_PLD_TCK")
	)
	(segment
		(start 401.529042 -20.964144)
		(end 399.536412 -22.956774)
		(width 0.10795)
		(layer "F.Cu")
		(net "JTAG_PLD_TCK")
	)
	(segment
		(start 399.38833 -27.062176)
		(end 399.38833 -28.131516)
		(width 0.10795)
		(layer "F.Cu")
		(net "JTAG_PLD_TCK")
	)
	(segment
		(start 398.450308 -24.248364)
		(end 398.450308 -26.124154)
		(width 0.10795)
		(layer "F.Cu")
		(net "JTAG_PLD_TCK")
	)
	(segment
		(start 381.30734 -64.657478)
		(end 381.30734 -65.459356)
		(width 0.10795)
		(layer "F.Cu")
		(net "JTAG_PLD_TCK")
	)
	(segment
		(start 381.30734 -65.459356)
		(end 379.826012 -66.940684)
		(width 0.10795)
		(layer "F.Cu")
		(net "JTAG_PLD_TCK")
	)
	(segment
		(start 397.8402 -0.7874)
		(end 397.764 -0.8636)
		(width 0.10795)
		(layer "F.Cu")
		(net "JTAG_PLD_TCK")
	)
	(segment
		(start 399.536412 -22.956774)
		(end 399.536412 -23.16226)
		(width 0.10795)
		(layer "F.Cu")
		(net "JTAG_PLD_TCK")
	)
	(segment
		(start 398.441926 0.779526)
		(end 397.8402 0.1778)
		(width 0.10795)
		(layer "F.Cu")
		(net "JTAG_PLD_TCK")
	)
	(segment
		(start 398.450308 -26.124154)
		(end 398.785842 -26.459688)
		(width 0.10795)
		(layer "F.Cu")
		(net "JTAG_PLD_TCK")
	)
	(segment
		(start 379.826012 -66.940684)
		(end 374.687084 -66.940684)
		(width 0.10795)
		(layer "F.Cu")
		(net "JTAG_PLD_TCK")
	)
	(segment
		(start 402.176996 -20.655026)
		(end 401.867878 -20.964144)
		(width 0.10795)
		(layer "F.Cu")
		(net "JTAG_PLD_TCK")
	)
	(segment
		(start 373.944896 -67.682872)
		(end 373.944896 -68.295012)
		(width 0.10795)
		(layer "F.Cu")
		(net "JTAG_PLD_TCK")
	)
	(segment
		(start 399.770092 0.779526)
		(end 398.441926 0.779526)
		(width 0.10795)
		(layer "F.Cu")
		(net "JTAG_PLD_TCK")
	)
	(segment
		(start 374.687084 -66.940684)
		(end 373.944896 -67.682872)
		(width 0.10795)
		(layer "F.Cu")
		(net "JTAG_PLD_TCK")
	)
	(segment
		(start 399.536412 -23.16226)
		(end 398.450308 -24.248364)
		(width 0.10795)
		(layer "F.Cu")
		(net "JTAG_PLD_TCK")
	)
	(via
		(at 398.785842 -26.459688)
		(size 0.6604)
		(drill 0.3302)
		(layers "F.Cu" "B.Cu")
		(net "JTAG_PLD_TCK")
	)
	(via
		(at 402.176996 -20.655026)
		(size 0.508)
		(drill 0.254)
		(layers "F.Cu" "B.Cu")
		(net "JTAG_PLD_TCK")
	)
	(via
		(at 380.865888 -63.59398)
		(size 0.508)
		(drill 0.254)
		(layers "F.Cu" "B.Cu")
		(net "JTAG_PLD_TCK")
	)
	(via
		(at 399.38833 -28.131516)
		(size 0.508)
		(drill 0.254)
		(layers "F.Cu" "B.Cu")
		(net "JTAG_PLD_TCK")
	)
	(via
		(at 397.764 -0.8636)
		(size 0.508)
		(drill 0.254)
		(layers "F.Cu" "B.Cu")
		(net "JTAG_PLD_TCK")
	)
	(segment
		(start 400.668998 -17.701006)
		(end 400.812 -17.844008)
		(width 0.10795)
		(layer "B.Cu")
		(net "JTAG_PLD_TCK")
	)
	(segment
		(start 400.812 -19.430492)
		(end 402.036534 -20.655026)
		(width 0.10795)
		(layer "B.Cu")
		(net "JTAG_PLD_TCK")
	)
	(segment
		(start 390.306814 -2.834386)
		(end 390.306814 -3.47853)
		(width 0.10795)
		(layer "B.Cu")
		(net "JTAG_PLD_TCK")
	)
	(segment
		(start 402.7932 -14.5034)
		(end 400.668998 -16.627602)
		(width 0.10795)
		(layer "B.Cu")
		(net "JTAG_PLD_TCK")
	)
	(segment
		(start 402.036534 -20.655026)
		(end 402.176996 -20.655026)
		(width 0.10795)
		(layer "B.Cu")
		(net "JTAG_PLD_TCK")
	)
	(segment
		(start 390.306814 -3.47853)
		(end 391.247884 -4.4196)
		(width 0.10795)
		(layer "B.Cu")
		(net "JTAG_PLD_TCK")
	)
	(segment
		(start 390.9314 -2.2098)
		(end 390.306814 -2.834386)
		(width 0.10795)
		(layer "B.Cu")
		(net "JTAG_PLD_TCK")
	)
	(segment
		(start 400.812 -17.844008)
		(end 400.812 -19.430492)
		(width 0.10795)
		(layer "B.Cu")
		(net "JTAG_PLD_TCK")
	)
	(segment
		(start 402.7932 -6.942074)
		(end 402.7932 -14.5034)
		(width 0.10795)
		(layer "B.Cu")
		(net "JTAG_PLD_TCK")
	)
	(segment
		(start 391.247884 -4.4196)
		(end 400.270726 -4.4196)
		(width 0.10795)
		(layer "B.Cu")
		(net "JTAG_PLD_TCK")
	)
	(segment
		(start 396.4178 -2.2098)
		(end 390.9314 -2.2098)
		(width 0.10795)
		(layer "B.Cu")
		(net "JTAG_PLD_TCK")
	)
	(segment
		(start 400.668998 -16.627602)
		(end 400.668998 -17.701006)
		(width 0.10795)
		(layer "B.Cu")
		(net "JTAG_PLD_TCK")
	)
	(segment
		(start 397.764 -0.8636)
		(end 396.4178 -2.2098)
		(width 0.10795)
		(layer "B.Cu")
		(net "JTAG_PLD_TCK")
	)
	(segment
		(start 400.270726 -4.4196)
		(end 402.7932 -6.942074)
		(width 0.10795)
		(layer "B.Cu")
		(net "JTAG_PLD_TCK")
	)
	(segment
		(start 388.326376 -31.92399)
		(end 388.326376 -31.160466)
		(width 0.089408)
		(layer "In2.Cu")
		(net "JTAG_PLD_TCK")
	)
	(segment
		(start 380.873 -59.944)
		(end 381.545592 -59.271408)
		(width 0.089408)
		(layer "In2.Cu")
		(net "JTAG_PLD_TCK")
	)
	(segment
		(start 397.020796 -28.28417)
		(end 397.286226 -28.01874)
		(width 0.089408)
		(layer "In2.Cu")
		(net "JTAG_PLD_TCK")
	)
	(segment
		(start 386.17398 -35.803586)
		(end 386.17398 -34.076386)
		(width 0.089408)
		(layer "In2.Cu")
		(net "JTAG_PLD_TCK")
	)
	(segment
		(start 381.390144 -56.551322)
		(end 381.390144 -51.20005)
		(width 0.089408)
		(layer "In2.Cu")
		(net "JTAG_PLD_TCK")
	)
	(segment
		(start 381.54991 -56.711088)
		(end 381.390144 -56.551322)
		(width 0.089408)
		(layer "In2.Cu")
		(net "JTAG_PLD_TCK")
	)
	(segment
		(start 381.545592 -59.271408)
		(end 381.545592 -57.44845)
		(width 0.089408)
		(layer "In2.Cu")
		(net "JTAG_PLD_TCK")
	)
	(segment
		(start 386.17398 -34.076386)
		(end 388.326376 -31.92399)
		(width 0.089408)
		(layer "In2.Cu")
		(net "JTAG_PLD_TCK")
	)
	(segment
		(start 383.159 -44.689776)
		(end 383.159 -42.434256)
		(width 0.089408)
		(layer "In2.Cu")
		(net "JTAG_PLD_TCK")
	)
	(segment
		(start 380.873 -63.586868)
		(end 380.873 -59.944)
		(width 0.089408)
		(layer "In2.Cu")
		(net "JTAG_PLD_TCK")
	)
	(segment
		(start 383.270252 -42.323004)
		(end 383.270252 -40.927274)
		(width 0.089408)
		(layer "In2.Cu")
		(net "JTAG_PLD_TCK")
	)
	(segment
		(start 381.545592 -57.44845)
		(end 381.54991 -57.444132)
		(width 0.089408)
		(layer "In2.Cu")
		(net "JTAG_PLD_TCK")
	)
	(segment
		(start 389.934196 -29.552646)
		(end 391.785094 -29.552646)
		(width 0.089408)
		(layer "In2.Cu")
		(net "JTAG_PLD_TCK")
	)
	(segment
		(start 381.390144 -51.20005)
		(end 381.559308 -51.030886)
		(width 0.089408)
		(layer "In2.Cu")
		(net "JTAG_PLD_TCK")
	)
	(segment
		(start 388.326376 -31.160466)
		(end 389.934196 -29.552646)
		(width 0.089408)
		(layer "In2.Cu")
		(net "JTAG_PLD_TCK")
	)
	(segment
		(start 383.159 -42.434256)
		(end 383.270252 -42.323004)
		(width 0.089408)
		(layer "In2.Cu")
		(net "JTAG_PLD_TCK")
	)
	(segment
		(start 381.54991 -57.444132)
		(end 381.54991 -56.711088)
		(width 0.089408)
		(layer "In2.Cu")
		(net "JTAG_PLD_TCK")
	)
	(segment
		(start 381.559308 -46.289468)
		(end 383.159 -44.689776)
		(width 0.089408)
		(layer "In2.Cu")
		(net "JTAG_PLD_TCK")
	)
	(segment
		(start 382.962912 -40.619934)
		(end 382.962912 -38.972236)
		(width 0.089408)
		(layer "In2.Cu")
		(net "JTAG_PLD_TCK")
	)
	(segment
		(start 393.052046 -28.28417)
		(end 397.020796 -28.28417)
		(width 0.089408)
		(layer "In2.Cu")
		(net "JTAG_PLD_TCK")
	)
	(segment
		(start 381.559308 -51.030886)
		(end 381.559308 -46.289468)
		(width 0.089408)
		(layer "In2.Cu")
		(net "JTAG_PLD_TCK")
	)
	(segment
		(start 383.093468 -38.84168)
		(end 386.17398 -35.803586)
		(width 0.089408)
		(layer "In2.Cu")
		(net "JTAG_PLD_TCK")
	)
	(segment
		(start 392.851132 -28.486608)
		(end 393.052046 -28.28417)
		(width 0.089408)
		(layer "In2.Cu")
		(net "JTAG_PLD_TCK")
	)
	(segment
		(start 382.962912 -38.972236)
		(end 383.093468 -38.84168)
		(width 0.089408)
		(layer "In2.Cu")
		(net "JTAG_PLD_TCK")
	)
	(segment
		(start 380.865888 -63.59398)
		(end 380.873 -63.586868)
		(width 0.089408)
		(layer "In2.Cu")
		(net "JTAG_PLD_TCK")
	)
	(segment
		(start 391.785094 -29.552646)
		(end 392.851132 -28.486608)
		(width 0.089408)
		(layer "In2.Cu")
		(net "JTAG_PLD_TCK")
	)
	(segment
		(start 397.286226 -28.01874)
		(end 399.275554 -28.01874)
		(width 0.089408)
		(layer "In2.Cu")
		(net "JTAG_PLD_TCK")
	)
	(segment
		(start 399.275554 -28.01874)
		(end 399.38833 -28.131516)
		(width 0.089408)
		(layer "In2.Cu")
		(net "JTAG_PLD_TCK")
	)
	(segment
		(start 383.270252 -40.927274)
		(end 382.962912 -40.619934)
		(width 0.089408)
		(layer "In2.Cu")
		(net "JTAG_PLD_TCK")
	)
	(segment
		(start 401.295108 -103.855012)
		(end 402.613368 -103.855012)
		(width 0.0889)
		(layer "F.Cu")
		(net "JTAG_PCH_GBE_TRST_N")
	)
	(segment
		(start 402.613368 -103.855012)
		(end 403.001734 -104.243378)
		(width 0.0889)
		(layer "F.Cu")
		(net "JTAG_PCH_GBE_TRST_N")
	)
	(segment
		(start 391.16 -0.254)
		(end 391.16 -0.8636)
		(width 0.10795)
		(layer "F.Cu")
		(net "JTAG_PCH_GBE_TRST_N")
	)
	(segment
		(start 403.70379 -104.65689)
		(end 403.733 -104.65689)
		(width 0.0889)
		(layer "F.Cu")
		(net "JTAG_PCH_GBE_TRST_N")
	)
	(segment
		(start 403.293834 -104.246934)
		(end 403.70379 -104.65689)
		(width 0.0889)
		(layer "F.Cu")
		(net "JTAG_PCH_GBE_TRST_N")
	)
	(segment
		(start 403.001734 -104.243378)
		(end 403.2631 -104.243378)
		(width 0.0889)
		(layer "F.Cu")
		(net "JTAG_PCH_GBE_TRST_N")
	)
	(segment
		(start 403.266656 -104.246934)
		(end 403.293834 -104.246934)
		(width 0.0889)
		(layer "F.Cu")
		(net "JTAG_PCH_GBE_TRST_N")
	)
	(segment
		(start 403.2631 -104.243378)
		(end 403.266656 -104.246934)
		(width 0.0889)
		(layer "F.Cu")
		(net "JTAG_PCH_GBE_TRST_N")
	)
	(via
		(at 391.16 -0.8636)
		(size 0.508)
		(drill 0.254)
		(layers "F.Cu" "B.Cu")
		(net "JTAG_PCH_GBE_TRST_N")
	)
	(via
		(at 459.2574 -5.5372)
		(size 0.508)
		(drill 0.254)
		(layers "F.Cu" "B.Cu")
		(net "JTAG_PCH_GBE_TRST_N")
	)
	(via
		(at 403.733 -104.65689)
		(size 0.508)
		(drill 0.254)
		(layers "F.Cu" "B.Cu")
		(net "JTAG_PCH_GBE_TRST_N")
	)
	(segment
		(start 415.46526 3.603752)
		(end 414.070292 2.208784)
		(width 0.089408)
		(layer "In4.Cu")
		(net "JTAG_PCH_GBE_TRST_N")
	)
	(segment
		(start 458.597 -1.524)
		(end 456.553824 -1.524)
		(width 0.089408)
		(layer "In4.Cu")
		(net "JTAG_PCH_GBE_TRST_N")
	)
	(segment
		(start 459.008734 -5.288534)
		(end 459.008734 -2.76733)
		(width 0.089408)
		(layer "In4.Cu")
		(net "JTAG_PCH_GBE_TRST_N")
	)
	(segment
		(start 413.12846 2.208784)
		(end 413.127952 2.208276)
		(width 0.089408)
		(layer "In4.Cu")
		(net "JTAG_PCH_GBE_TRST_N")
	)
	(segment
		(start 400.351498 2.232152)
		(end 394.880592 2.232152)
		(width 0.089408)
		(layer "In4.Cu")
		(net "JTAG_PCH_GBE_TRST_N")
	)
	(segment
		(start 392.185144 -0.463296)
		(end 391.560304 -0.463296)
		(width 0.089408)
		(layer "In4.Cu")
		(net "JTAG_PCH_GBE_TRST_N")
	)
	(segment
		(start 458.984604 -1.911604)
		(end 458.597 -1.524)
		(width 0.089408)
		(layer "In4.Cu")
		(net "JTAG_PCH_GBE_TRST_N")
	)
	(segment
		(start 416.746944 3.604006)
		(end 416.74669 3.603752)
		(width 0.089408)
		(layer "In4.Cu")
		(net "JTAG_PCH_GBE_TRST_N")
	)
	(segment
		(start 412.927546 2.20853)
		(end 412.727394 2.20853)
		(width 0.089408)
		(layer "In4.Cu")
		(net "JTAG_PCH_GBE_TRST_N")
	)
	(segment
		(start 427.122336 2.093722)
		(end 426.393864 2.093722)
		(width 0.089408)
		(layer "In4.Cu")
		(net "JTAG_PCH_GBE_TRST_N")
	)
	(segment
		(start 421.200834 3.603752)
		(end 418.35197 3.603752)
		(width 0.089408)
		(layer "In4.Cu")
		(net "JTAG_PCH_GBE_TRST_N")
	)
	(segment
		(start 423.312082 2.093468)
		(end 422.91127 2.093468)
		(width 0.089408)
		(layer "In4.Cu")
		(net "JTAG_PCH_GBE_TRST_N")
	)
	(segment
		(start 426.393864 2.093722)
		(end 426.39361 2.093976)
		(width 0.089408)
		(layer "In4.Cu")
		(net "JTAG_PCH_GBE_TRST_N")
	)
	(segment
		(start 456.553824 -1.524)
		(end 454.744582 0.285242)
		(width 0.089408)
		(layer "In4.Cu")
		(net "JTAG_PCH_GBE_TRST_N")
	)
	(segment
		(start 454.744582 0.285242)
		(end 432.190144 0.285242)
		(width 0.089408)
		(layer "In4.Cu")
		(net "JTAG_PCH_GBE_TRST_N")
	)
	(segment
		(start 427.128686 2.100072)
		(end 427.122336 2.093722)
		(width 0.089408)
		(layer "In4.Cu")
		(net "JTAG_PCH_GBE_TRST_N")
	)
	(segment
		(start 422.91127 2.093468)
		(end 422.911016 2.093722)
		(width 0.089408)
		(layer "In4.Cu")
		(net "JTAG_PCH_GBE_TRST_N")
	)
	(segment
		(start 413.127952 2.208276)
		(end 412.9278 2.208276)
		(width 0.089408)
		(layer "In4.Cu")
		(net "JTAG_PCH_GBE_TRST_N")
	)
	(segment
		(start 423.31259 2.093976)
		(end 423.312082 2.093468)
		(width 0.089408)
		(layer "In4.Cu")
		(net "JTAG_PCH_GBE_TRST_N")
	)
	(segment
		(start 412.9278 2.208276)
		(end 412.927546 2.20853)
		(width 0.089408)
		(layer "In4.Cu")
		(net "JTAG_PCH_GBE_TRST_N")
	)
	(segment
		(start 459.008734 -2.76733)
		(end 458.984604 -2.7432)
		(width 0.089408)
		(layer "In4.Cu")
		(net "JTAG_PCH_GBE_TRST_N")
	)
	(segment
		(start 430.375314 2.100072)
		(end 427.128686 2.100072)
		(width 0.089408)
		(layer "In4.Cu")
		(net "JTAG_PCH_GBE_TRST_N")
	)
	(segment
		(start 412.727394 2.20853)
		(end 412.091124 2.8448)
		(width 0.089408)
		(layer "In4.Cu")
		(net "JTAG_PCH_GBE_TRST_N")
	)
	(segment
		(start 426.39361 2.093976)
		(end 423.31259 2.093976)
		(width 0.089408)
		(layer "In4.Cu")
		(net "JTAG_PCH_GBE_TRST_N")
	)
	(segment
		(start 459.2574 -5.5372)
		(end 459.008734 -5.288534)
		(width 0.089408)
		(layer "In4.Cu")
		(net "JTAG_PCH_GBE_TRST_N")
	)
	(segment
		(start 422.911016 2.093722)
		(end 422.710864 2.093722)
		(width 0.089408)
		(layer "In4.Cu")
		(net "JTAG_PCH_GBE_TRST_N")
	)
	(segment
		(start 418.351716 3.604006)
		(end 416.746944 3.604006)
		(width 0.089408)
		(layer "In4.Cu")
		(net "JTAG_PCH_GBE_TRST_N")
	)
	(segment
		(start 458.984604 -2.7432)
		(end 458.984604 -1.911604)
		(width 0.089408)
		(layer "In4.Cu")
		(net "JTAG_PCH_GBE_TRST_N")
	)
	(segment
		(start 422.710864 2.093722)
		(end 421.200834 3.603752)
		(width 0.089408)
		(layer "In4.Cu")
		(net "JTAG_PCH_GBE_TRST_N")
	)
	(segment
		(start 391.560304 -0.463296)
		(end 391.16 -0.8636)
		(width 0.089408)
		(layer "In4.Cu")
		(net "JTAG_PCH_GBE_TRST_N")
	)
	(segment
		(start 432.190144 0.285242)
		(end 430.375314 2.100072)
		(width 0.089408)
		(layer "In4.Cu")
		(net "JTAG_PCH_GBE_TRST_N")
	)
	(segment
		(start 418.35197 3.603752)
		(end 418.351716 3.604006)
		(width 0.089408)
		(layer "In4.Cu")
		(net "JTAG_PCH_GBE_TRST_N")
	)
	(segment
		(start 416.74669 3.603752)
		(end 415.46526 3.603752)
		(width 0.089408)
		(layer "In4.Cu")
		(net "JTAG_PCH_GBE_TRST_N")
	)
	(segment
		(start 400.964146 2.8448)
		(end 400.351498 2.232152)
		(width 0.089408)
		(layer "In4.Cu")
		(net "JTAG_PCH_GBE_TRST_N")
	)
	(segment
		(start 394.880592 2.232152)
		(end 392.185144 -0.463296)
		(width 0.089408)
		(layer "In4.Cu")
		(net "JTAG_PCH_GBE_TRST_N")
	)
	(segment
		(start 412.091124 2.8448)
		(end 400.964146 2.8448)
		(width 0.089408)
		(layer "In4.Cu")
		(net "JTAG_PCH_GBE_TRST_N")
	)
	(segment
		(start 414.070292 2.208784)
		(end 413.12846 2.208784)
		(width 0.089408)
		(layer "In4.Cu")
		(net "JTAG_PCH_GBE_TRST_N")
	)
	(segment
		(start 399.296636 -79.840074)
		(end 398.986502 -80.150208)
		(width 0.089408)
		(layer "In11.Cu")
		(net "JTAG_PCH_GBE_TRST_N")
	)
	(segment
		(start 398.986502 -83.296252)
		(end 399.514314 -83.824064)
		(width 0.089408)
		(layer "In11.Cu")
		(net "JTAG_PCH_GBE_TRST_N")
	)
	(segment
		(start 398.986502 -80.150208)
		(end 398.986502 -83.296252)
		(width 0.089408)
		(layer "In11.Cu")
		(net "JTAG_PCH_GBE_TRST_N")
	)
	(segment
		(start 459.2574 -5.5372)
		(end 459.244192 -5.550408)
		(width 0.089408)
		(layer "In11.Cu")
		(net "JTAG_PCH_GBE_TRST_N")
	)
	(segment
		(start 382.752854 -14.812772)
		(end 379.447552 -18.118074)
		(width 0.089408)
		(layer "In11.Cu")
		(net "JTAG_PCH_GBE_TRST_N")
	)
	(segment
		(start 377.579128 -35.851338)
		(end 377.579128 -41.574974)
		(width 0.089408)
		(layer "In11.Cu")
		(net "JTAG_PCH_GBE_TRST_N")
	)
	(segment
		(start 378.953776 -44.249848)
		(end 379.2855 -44.249848)
		(width 0.089408)
		(layer "In11.Cu")
		(net "JTAG_PCH_GBE_TRST_N")
	)
	(segment
		(start 380.330964 -44.012358)
		(end 380.8984 -44.579794)
		(width 0.089408)
		(layer "In11.Cu")
		(net "JTAG_PCH_GBE_TRST_N")
	)
	(segment
		(start 399.514314 -85.00618)
		(end 400.183604 -85.67547)
		(width 0.089408)
		(layer "In11.Cu")
		(net "JTAG_PCH_GBE_TRST_N")
	)
	(segment
		(start 439.79465 -13.818108)
		(end 438.26303 -15.349728)
		(width 0.089408)
		(layer "In11.Cu")
		(net "JTAG_PCH_GBE_TRST_N")
	)
	(segment
		(start 387.976618 -50.516282)
		(end 387.976618 -52.229512)
		(width 0.089408)
		(layer "In11.Cu")
		(net "JTAG_PCH_GBE_TRST_N")
	)
	(segment
		(start 455.831194 -7.0612)
		(end 455.206862 -6.436868)
		(width 0.089408)
		(layer "In11.Cu")
		(net "JTAG_PCH_GBE_TRST_N")
	)
	(segment
		(start 445.805814 -13.818108)
		(end 439.79465 -13.818108)
		(width 0.089408)
		(layer "In11.Cu")
		(net "JTAG_PCH_GBE_TRST_N")
	)
	(segment
		(start 417.798758 -13.108432)
		(end 402.383244 -13.108432)
		(width 0.089408)
		(layer "In11.Cu")
		(net "JTAG_PCH_GBE_TRST_N")
	)
	(segment
		(start 397.10995 -72.263)
		(end 397.109696 -72.263254)
		(width 0.089408)
		(layer "In11.Cu")
		(net "JTAG_PCH_GBE_TRST_N")
	)
	(segment
		(start 394.146278 -64.341756)
		(end 395.648434 -65.843912)
		(width 0.089408)
		(layer "In11.Cu")
		(net "JTAG_PCH_GBE_TRST_N")
	)
	(segment
		(start 399.2372 -78.986634)
		(end 399.296636 -79.04607)
		(width 0.089408)
		(layer "In11.Cu")
		(net "JTAG_PCH_GBE_TRST_N")
	)
	(segment
		(start 399.2372 -77.75956)
		(end 399.2372 -78.986634)
		(width 0.089408)
		(layer "In11.Cu")
		(net "JTAG_PCH_GBE_TRST_N")
	)
	(segment
		(start 458.667612 -5.550408)
		(end 458.327252 -5.890768)
		(width 0.089408)
		(layer "In11.Cu")
		(net "JTAG_PCH_GBE_TRST_N")
	)
	(segment
		(start 399.514314 -83.824064)
		(end 399.514314 -85.00618)
		(width 0.089408)
		(layer "In11.Cu")
		(net "JTAG_PCH_GBE_TRST_N")
	)
	(segment
		(start 420.228268 -15.537942)
		(end 417.798758 -13.108432)
		(width 0.089408)
		(layer "In11.Cu")
		(net "JTAG_PCH_GBE_TRST_N")
	)
	(segment
		(start 400.077178 -14.813026)
		(end 400.076924 -14.812772)
		(width 0.089408)
		(layer "In11.Cu")
		(net "JTAG_PCH_GBE_TRST_N")
	)
	(segment
		(start 398.860518 -77.382878)
		(end 399.2372 -77.75956)
		(width 0.089408)
		(layer "In11.Cu")
		(net "JTAG_PCH_GBE_TRST_N")
	)
	(segment
		(start 397.109696 -72.263254)
		(end 397.109696 -74.654918)
		(width 0.089408)
		(layer "In11.Cu")
		(net "JTAG_PCH_GBE_TRST_N")
	)
	(segment
		(start 380.8984 -44.579794)
		(end 380.8984 -44.959016)
		(width 0.089408)
		(layer "In11.Cu")
		(net "JTAG_PCH_GBE_TRST_N")
	)
	(segment
		(start 402.383244 -13.108432)
		(end 400.67865 -14.813026)
		(width 0.089408)
		(layer "In11.Cu")
		(net "JTAG_PCH_GBE_TRST_N")
	)
	(segment
		(start 401.42922 -93.946726)
		(end 401.42922 -102.713536)
		(width 0.089408)
		(layer "In11.Cu")
		(net "JTAG_PCH_GBE_TRST_N")
	)
	(segment
		(start 402.65731 -103.5812)
		(end 403.733 -104.65689)
		(width 0.089408)
		(layer "In11.Cu")
		(net "JTAG_PCH_GBE_TRST_N")
	)
	(segment
		(start 459.244192 -5.550408)
		(end 458.667612 -5.550408)
		(width 0.089408)
		(layer "In11.Cu")
		(net "JTAG_PCH_GBE_TRST_N")
	)
	(segment
		(start 399.871692 -90.69578)
		(end 399.871692 -92.389198)
		(width 0.089408)
		(layer "In11.Cu")
		(net "JTAG_PCH_GBE_TRST_N")
	)
	(segment
		(start 395.648434 -65.843912)
		(end 395.648434 -70.601332)
		(width 0.089408)
		(layer "In11.Cu")
		(net "JTAG_PCH_GBE_TRST_N")
	)
	(segment
		(start 379.2855 -44.249848)
		(end 379.52299 -44.012358)
		(width 0.089408)
		(layer "In11.Cu")
		(net "JTAG_PCH_GBE_TRST_N")
	)
	(segment
		(start 431.95621 -15.349728)
		(end 431.767996 -15.537942)
		(width 0.089408)
		(layer "In11.Cu")
		(net "JTAG_PCH_GBE_TRST_N")
	)
	(segment
		(start 400.183604 -90.383868)
		(end 399.871692 -90.69578)
		(width 0.089408)
		(layer "In11.Cu")
		(net "JTAG_PCH_GBE_TRST_N")
	)
	(segment
		(start 457.313792 -7.0612)
		(end 455.831194 -7.0612)
		(width 0.089408)
		(layer "In11.Cu")
		(net "JTAG_PCH_GBE_TRST_N")
	)
	(segment
		(start 379.447552 -18.657316)
		(end 375.579894 -22.524974)
		(width 0.089408)
		(layer "In11.Cu")
		(net "JTAG_PCH_GBE_TRST_N")
	)
	(segment
		(start 378.719334 -44.015406)
		(end 378.953776 -44.249848)
		(width 0.089408)
		(layer "In11.Cu")
		(net "JTAG_PCH_GBE_TRST_N")
	)
	(segment
		(start 400.076924 -14.812772)
		(end 382.752854 -14.812772)
		(width 0.089408)
		(layer "In11.Cu")
		(net "JTAG_PCH_GBE_TRST_N")
	)
	(segment
		(start 397.109696 -74.654918)
		(end 398.860518 -76.40574)
		(width 0.089408)
		(layer "In11.Cu")
		(net "JTAG_PCH_GBE_TRST_N")
	)
	(segment
		(start 377.579128 -41.574974)
		(end 378.719334 -42.71518)
		(width 0.089408)
		(layer "In11.Cu")
		(net "JTAG_PCH_GBE_TRST_N")
	)
	(segment
		(start 398.860518 -76.40574)
		(end 398.860518 -77.382878)
		(width 0.089408)
		(layer "In11.Cu")
		(net "JTAG_PCH_GBE_TRST_N")
	)
	(segment
		(start 386.862828 -48.397922)
		(end 386.862828 -49.402492)
		(width 0.089408)
		(layer "In11.Cu")
		(net "JTAG_PCH_GBE_TRST_N")
	)
	(segment
		(start 380.8984 -44.959016)
		(end 383.66192 -47.722536)
		(width 0.089408)
		(layer "In11.Cu")
		(net "JTAG_PCH_GBE_TRST_N")
	)
	(segment
		(start 399.296636 -79.04607)
		(end 399.296636 -79.840074)
		(width 0.089408)
		(layer "In11.Cu")
		(net "JTAG_PCH_GBE_TRST_N")
	)
	(segment
		(start 458.327252 -5.890768)
		(end 458.327252 -6.04774)
		(width 0.089408)
		(layer "In11.Cu")
		(net "JTAG_PCH_GBE_TRST_N")
	)
	(segment
		(start 375.579894 -33.852104)
		(end 377.579128 -35.851338)
		(width 0.089408)
		(layer "In11.Cu")
		(net "JTAG_PCH_GBE_TRST_N")
	)
	(segment
		(start 386.187442 -47.722536)
		(end 386.862828 -48.397922)
		(width 0.089408)
		(layer "In11.Cu")
		(net "JTAG_PCH_GBE_TRST_N")
	)
	(segment
		(start 400.183604 -85.67547)
		(end 400.183604 -90.383868)
		(width 0.089408)
		(layer "In11.Cu")
		(net "JTAG_PCH_GBE_TRST_N")
	)
	(segment
		(start 401.42922 -102.713536)
		(end 402.296884 -103.5812)
		(width 0.089408)
		(layer "In11.Cu")
		(net "JTAG_PCH_GBE_TRST_N")
	)
	(segment
		(start 379.447552 -18.118074)
		(end 379.447552 -18.657316)
		(width 0.089408)
		(layer "In11.Cu")
		(net "JTAG_PCH_GBE_TRST_N")
	)
	(segment
		(start 386.862828 -49.402492)
		(end 387.976618 -50.516282)
		(width 0.089408)
		(layer "In11.Cu")
		(net "JTAG_PCH_GBE_TRST_N")
	)
	(segment
		(start 452.62165 -8.61187)
		(end 451.012052 -8.61187)
		(width 0.089408)
		(layer "In11.Cu")
		(net "JTAG_PCH_GBE_TRST_N")
	)
	(segment
		(start 378.719334 -42.71518)
		(end 378.719334 -44.015406)
		(width 0.089408)
		(layer "In11.Cu")
		(net "JTAG_PCH_GBE_TRST_N")
	)
	(segment
		(start 400.67865 -14.813026)
		(end 400.077178 -14.813026)
		(width 0.089408)
		(layer "In11.Cu")
		(net "JTAG_PCH_GBE_TRST_N")
	)
	(segment
		(start 451.012052 -8.61187)
		(end 445.805814 -13.818108)
		(width 0.089408)
		(layer "In11.Cu")
		(net "JTAG_PCH_GBE_TRST_N")
	)
	(segment
		(start 379.52299 -44.012358)
		(end 380.330964 -44.012358)
		(width 0.089408)
		(layer "In11.Cu")
		(net "JTAG_PCH_GBE_TRST_N")
	)
	(segment
		(start 383.66192 -47.722536)
		(end 386.187442 -47.722536)
		(width 0.089408)
		(layer "In11.Cu")
		(net "JTAG_PCH_GBE_TRST_N")
	)
	(segment
		(start 455.206862 -6.436868)
		(end 455.204068 -6.436868)
		(width 0.089408)
		(layer "In11.Cu")
		(net "JTAG_PCH_GBE_TRST_N")
	)
	(segment
		(start 399.871692 -92.389198)
		(end 401.42922 -93.946726)
		(width 0.089408)
		(layer "In11.Cu")
		(net "JTAG_PCH_GBE_TRST_N")
	)
	(segment
		(start 402.296884 -103.5812)
		(end 402.65731 -103.5812)
		(width 0.089408)
		(layer "In11.Cu")
		(net "JTAG_PCH_GBE_TRST_N")
	)
	(segment
		(start 395.648434 -70.601332)
		(end 397.10995 -72.062848)
		(width 0.089408)
		(layer "In11.Cu")
		(net "JTAG_PCH_GBE_TRST_N")
	)
	(segment
		(start 458.327252 -6.04774)
		(end 457.313792 -7.0612)
		(width 0.089408)
		(layer "In11.Cu")
		(net "JTAG_PCH_GBE_TRST_N")
	)
	(segment
		(start 394.146278 -58.399172)
		(end 394.146278 -64.341756)
		(width 0.089408)
		(layer "In11.Cu")
		(net "JTAG_PCH_GBE_TRST_N")
	)
	(segment
		(start 455.204068 -6.436868)
		(end 455.155808 -6.388608)
		(width 0.089408)
		(layer "In11.Cu")
		(net "JTAG_PCH_GBE_TRST_N")
	)
	(segment
		(start 387.976618 -52.229512)
		(end 394.146278 -58.399172)
		(width 0.089408)
		(layer "In11.Cu")
		(net "JTAG_PCH_GBE_TRST_N")
	)
	(segment
		(start 397.10995 -72.062848)
		(end 397.10995 -72.263)
		(width 0.089408)
		(layer "In11.Cu")
		(net "JTAG_PCH_GBE_TRST_N")
	)
	(segment
		(start 455.155808 -6.388608)
		(end 454.844912 -6.388608)
		(width 0.089408)
		(layer "In11.Cu")
		(net "JTAG_PCH_GBE_TRST_N")
	)
	(segment
		(start 438.26303 -15.349728)
		(end 431.95621 -15.349728)
		(width 0.089408)
		(layer "In11.Cu")
		(net "JTAG_PCH_GBE_TRST_N")
	)
	(segment
		(start 431.767996 -15.537942)
		(end 420.228268 -15.537942)
		(width 0.089408)
		(layer "In11.Cu")
		(net "JTAG_PCH_GBE_TRST_N")
	)
	(segment
		(start 375.579894 -22.524974)
		(end 375.579894 -33.852104)
		(width 0.089408)
		(layer "In11.Cu")
		(net "JTAG_PCH_GBE_TRST_N")
	)
	(segment
		(start 454.844912 -6.388608)
		(end 452.62165 -8.61187)
		(width 0.089408)
		(layer "In11.Cu")
		(net "JTAG_PCH_GBE_TRST_N")
	)
	(segment
		(start 428.987712 -66.489834)
		(end 427.269656 -66.489834)
		(width 0.10795)
		(layer "F.Cu")
		(net "JTAG_BMC_TRST_N")
	)
	(segment
		(start 427.269656 -66.489834)
		(end 425.7802 -67.97929)
		(width 0.10795)
		(layer "F.Cu")
		(net "JTAG_BMC_TRST_N")
	)
	(segment
		(start 468.814404 -62.226444)
		(end 467.349078 -63.69177)
		(width 0.10795)
		(layer "F.Cu")
		(net "JTAG_BMC_TRST_N")
	)
	(segment
		(start 422.775634 -75.851004)
		(end 422.775634 -78.368906)
		(width 0.10795)
		(layer "F.Cu")
		(net "JTAG_BMC_TRST_N")
	)
	(segment
		(start 467.349078 -64.654938)
		(end 465.557616 -66.4464)
		(width 0.10795)
		(layer "F.Cu")
		(net "JTAG_BMC_TRST_N")
	)
	(segment
		(start 434.840126 -153.454608)
		(end 434.840126 -147.159218)
		(width 0.10795)
		(layer "F.Cu")
		(net "JTAG_BMC_TRST_N")
	)
	(segment
		(start 422.775634 -78.368906)
		(end 422.771062 -78.373478)
		(width 0.10795)
		(layer "F.Cu")
		(net "JTAG_BMC_TRST_N")
	)
	(segment
		(start 429.031146 -66.4464)
		(end 428.987712 -66.489834)
		(width 0.10795)
		(layer "F.Cu")
		(net "JTAG_BMC_TRST_N")
	)
	(segment
		(start 468.488776 -56.90489)
		(end 468.814404 -57.230518)
		(width 0.10795)
		(layer "F.Cu")
		(net "JTAG_BMC_TRST_N")
	)
	(segment
		(start 467.349078 -63.69177)
		(end 467.349078 -64.654938)
		(width 0.10795)
		(layer "F.Cu")
		(net "JTAG_BMC_TRST_N")
	)
	(segment
		(start 438.183782 -156.183584)
		(end 436.116222 -154.116024)
		(width 0.10795)
		(layer "F.Cu")
		(net "JTAG_BMC_TRST_N")
	)
	(segment
		(start 392.049 -0.254)
		(end 392.049 -0.8636)
		(width 0.10795)
		(layer "F.Cu")
		(net "JTAG_BMC_TRST_N")
	)
	(segment
		(start 436.116222 -154.116024)
		(end 435.501542 -154.116024)
		(width 0.10795)
		(layer "F.Cu")
		(net "JTAG_BMC_TRST_N")
	)
	(segment
		(start 434.840126 -147.159218)
		(end 434.438806 -146.757898)
		(width 0.10795)
		(layer "F.Cu")
		(net "JTAG_BMC_TRST_N")
	)
	(segment
		(start 425.7802 -67.97929)
		(end 425.7802 -72.846438)
		(width 0.10795)
		(layer "F.Cu")
		(net "JTAG_BMC_TRST_N")
	)
	(segment
		(start 435.501542 -154.116024)
		(end 434.840126 -153.454608)
		(width 0.10795)
		(layer "F.Cu")
		(net "JTAG_BMC_TRST_N")
	)
	(segment
		(start 465.557616 -66.4464)
		(end 429.031146 -66.4464)
		(width 0.10795)
		(layer "F.Cu")
		(net "JTAG_BMC_TRST_N")
	)
	(segment
		(start 468.814404 -57.230518)
		(end 468.814404 -62.226444)
		(width 0.10795)
		(layer "F.Cu")
		(net "JTAG_BMC_TRST_N")
	)
	(segment
		(start 410.290264 -34.534602)
		(end 409.890214 -34.934652)
		(width 0.10795)
		(layer "F.Cu")
		(net "JTAG_BMC_TRST_N")
	)
	(segment
		(start 425.7802 -72.846438)
		(end 422.775634 -75.851004)
		(width 0.10795)
		(layer "F.Cu")
		(net "JTAG_BMC_TRST_N")
	)
	(via
		(at 427.101 -122.428)
		(size 0.508)
		(drill 0.254)
		(layers "F.Cu" "B.Cu")
		(net "JTAG_BMC_TRST_N")
	)
	(via
		(at 355.6254 -2.54)
		(size 0.508)
		(drill 0.254)
		(layers "F.Cu" "B.Cu")
		(net "JTAG_BMC_TRST_N")
	)
	(via
		(at 422.771062 -78.373478)
		(size 0.508)
		(drill 0.254)
		(layers "F.Cu" "B.Cu")
		(net "JTAG_BMC_TRST_N")
	)
	(via
		(at 409.890214 -34.934652)
		(size 0.4572)
		(drill 0.2032)
		(layers "F.Cu" "B.Cu")
		(net "JTAG_BMC_TRST_N")
	)
	(via
		(at 467.275418 -38.606476)
		(size 0.508)
		(drill 0.254)
		(layers "F.Cu" "B.Cu")
		(net "JTAG_BMC_TRST_N")
	)
	(via
		(at 468.488776 -56.90489)
		(size 0.508)
		(drill 0.254)
		(layers "F.Cu" "B.Cu")
		(net "JTAG_BMC_TRST_N")
	)
	(via
		(at 475.552516 -35.208972)
		(size 0.508)
		(drill 0.254)
		(layers "F.Cu" "B.Cu")
		(net "JTAG_BMC_TRST_N")
	)
	(via
		(at 392.049 -0.8636)
		(size 0.508)
		(drill 0.254)
		(layers "F.Cu" "B.Cu")
		(net "JTAG_BMC_TRST_N")
	)
	(via
		(at 438.183782 -156.183584)
		(size 0.508)
		(drill 0.254)
		(layers "F.Cu" "B.Cu")
		(net "JTAG_BMC_TRST_N")
	)
	(via
		(at 418.076126 -130.77698)
		(size 0.508)
		(drill 0.254)
		(layers "F.Cu" "B.Cu")
		(net "JTAG_BMC_TRST_N")
	)
	(via
		(at 434.438806 -146.757898)
		(size 0.508)
		(drill 0.254)
		(layers "F.Cu" "B.Cu")
		(net "JTAG_BMC_TRST_N")
	)
	(via
		(at 423.945304 -111.323374)
		(size 0.508)
		(drill 0.254)
		(layers "F.Cu" "B.Cu")
		(net "JTAG_BMC_TRST_N")
	)
	(via
		(at 487.47553 -34.136584)
		(size 0.508)
		(drill 0.254)
		(layers "F.Cu" "B.Cu")
		(net "JTAG_BMC_TRST_N")
	)
	(segment
		(start 356.0572 -2.1082)
		(end 357.098346 -2.1082)
		(width 0.10795)
		(layer "B.Cu")
		(net "JTAG_BMC_TRST_N")
	)
	(segment
		(start 422.859962 -110.238032)
		(end 423.945304 -111.323374)
		(width 0.10795)
		(layer "B.Cu")
		(net "JTAG_BMC_TRST_N")
	)
	(segment
		(start 441.324492 -156.666692)
		(end 441.8076 -157.1498)
		(width 0.10795)
		(layer "B.Cu")
		(net "JTAG_BMC_TRST_N")
	)
	(segment
		(start 441.8076 -157.1498)
		(end 442.468 -157.1498)
		(width 0.10795)
		(layer "B.Cu")
		(net "JTAG_BMC_TRST_N")
	)
	(segment
		(start 357.3526 -2.362454)
		(end 357.3526 -2.7686)
		(width 0.10795)
		(layer "B.Cu")
		(net "JTAG_BMC_TRST_N")
	)
	(segment
		(start 356.9716 -4.1656)
		(end 357.9368 -5.1308)
		(width 0.10795)
		(layer "B.Cu")
		(net "JTAG_BMC_TRST_N")
	)
	(segment
		(start 422.859962 -104.008682)
		(end 422.859962 -110.238032)
		(width 0.10795)
		(layer "B.Cu")
		(net "JTAG_BMC_TRST_N")
	)
	(segment
		(start 357.3526 -2.7686)
		(end 356.9716 -3.1496)
		(width 0.10795)
		(layer "B.Cu")
		(net "JTAG_BMC_TRST_N")
	)
	(segment
		(start 356.9716 -3.1496)
		(end 356.9716 -4.1656)
		(width 0.10795)
		(layer "B.Cu")
		(net "JTAG_BMC_TRST_N")
	)
	(segment
		(start 438.183782 -156.183584)
		(end 438.66689 -156.666692)
		(width 0.10795)
		(layer "B.Cu")
		(net "JTAG_BMC_TRST_N")
	)
	(segment
		(start 422.771062 -78.373478)
		(end 423.008552 -78.610968)
		(width 0.10795)
		(layer "B.Cu")
		(net "JTAG_BMC_TRST_N")
	)
	(segment
		(start 357.9368 -5.1308)
		(end 358.3432 -5.1308)
		(width 0.10795)
		(layer "B.Cu")
		(net "JTAG_BMC_TRST_N")
	)
	(segment
		(start 355.6254 -2.54)
		(end 356.0572 -2.1082)
		(width 0.10795)
		(layer "B.Cu")
		(net "JTAG_BMC_TRST_N")
	)
	(segment
		(start 438.66689 -156.666692)
		(end 441.324492 -156.666692)
		(width 0.10795)
		(layer "B.Cu")
		(net "JTAG_BMC_TRST_N")
	)
	(segment
		(start 423.321734 -100.823268)
		(end 423.328338 -100.829872)
		(width 0.10795)
		(layer "B.Cu")
		(net "JTAG_BMC_TRST_N")
	)
	(segment
		(start 422.837864 -91.446096)
		(end 423.321734 -91.929966)
		(width 0.10795)
		(layer "B.Cu")
		(net "JTAG_BMC_TRST_N")
	)
	(segment
		(start 423.328338 -100.829872)
		(end 423.328338 -103.540306)
		(width 0.10795)
		(layer "B.Cu")
		(net "JTAG_BMC_TRST_N")
	)
	(segment
		(start 423.328338 -103.540306)
		(end 422.859962 -104.008682)
		(width 0.10795)
		(layer "B.Cu")
		(net "JTAG_BMC_TRST_N")
	)
	(segment
		(start 423.008552 -86.741)
		(end 422.837864 -86.911688)
		(width 0.10795)
		(layer "B.Cu")
		(net "JTAG_BMC_TRST_N")
	)
	(segment
		(start 357.098346 -2.1082)
		(end 357.3526 -2.362454)
		(width 0.10795)
		(layer "B.Cu")
		(net "JTAG_BMC_TRST_N")
	)
	(segment
		(start 423.321734 -91.929966)
		(end 423.321734 -100.823268)
		(width 0.10795)
		(layer "B.Cu")
		(net "JTAG_BMC_TRST_N")
	)
	(segment
		(start 423.008552 -78.610968)
		(end 423.008552 -86.741)
		(width 0.10795)
		(layer "B.Cu")
		(net "JTAG_BMC_TRST_N")
	)
	(segment
		(start 422.837864 -86.911688)
		(end 422.837864 -91.446096)
		(width 0.10795)
		(layer "B.Cu")
		(net "JTAG_BMC_TRST_N")
	)
	(segment
		(start 468.92083 -38.375844)
		(end 470.506298 -38.375844)
		(width 0.089408)
		(layer "In2.Cu")
		(net "JTAG_BMC_TRST_N")
	)
	(segment
		(start 475.882208 -35.208972)
		(end 475.552516 -35.208972)
		(width 0.089408)
		(layer "In2.Cu")
		(net "JTAG_BMC_TRST_N")
	)
	(segment
		(start 485.78008 -36.737036)
		(end 483.40137 -36.737036)
		(width 0.089408)
		(layer "In2.Cu")
		(net "JTAG_BMC_TRST_N")
	)
	(segment
		(start 486.223818 -36.293298)
		(end 485.78008 -36.737036)
		(width 0.089408)
		(layer "In2.Cu")
		(net "JTAG_BMC_TRST_N")
	)
	(segment
		(start 472.237562 -36.64458)
		(end 474.116908 -36.64458)
		(width 0.089408)
		(layer "In2.Cu")
		(net "JTAG_BMC_TRST_N")
	)
	(segment
		(start 487.47553 -34.136584)
		(end 487.47553 -34.91357)
		(width 0.089408)
		(layer "In2.Cu")
		(net "JTAG_BMC_TRST_N")
	)
	(segment
		(start 486.223818 -36.165282)
		(end 486.223818 -36.293298)
		(width 0.089408)
		(layer "In2.Cu")
		(net "JTAG_BMC_TRST_N")
	)
	(segment
		(start 476.734886 -36.06165)
		(end 475.882208 -35.208972)
		(width 0.089408)
		(layer "In2.Cu")
		(net "JTAG_BMC_TRST_N")
	)
	(segment
		(start 478.487994 -34.976562)
		(end 477.402906 -36.06165)
		(width 0.089408)
		(layer "In2.Cu")
		(net "JTAG_BMC_TRST_N")
	)
	(segment
		(start 482.983794 -36.31946)
		(end 482.983794 -35.744404)
		(width 0.089408)
		(layer "In2.Cu")
		(net "JTAG_BMC_TRST_N")
	)
	(segment
		(start 470.506298 -38.375844)
		(end 472.237562 -36.64458)
		(width 0.089408)
		(layer "In2.Cu")
		(net "JTAG_BMC_TRST_N")
	)
	(segment
		(start 481.961952 -34.976562)
		(end 478.487994 -34.976562)
		(width 0.089408)
		(layer "In2.Cu")
		(net "JTAG_BMC_TRST_N")
	)
	(segment
		(start 487.47553 -34.91357)
		(end 486.223818 -36.165282)
		(width 0.089408)
		(layer "In2.Cu")
		(net "JTAG_BMC_TRST_N")
	)
	(segment
		(start 482.983794 -35.744404)
		(end 482.83749 -35.5981)
		(width 0.089408)
		(layer "In2.Cu")
		(net "JTAG_BMC_TRST_N")
	)
	(segment
		(start 482.58349 -35.5981)
		(end 481.961952 -34.976562)
		(width 0.089408)
		(layer "In2.Cu")
		(net "JTAG_BMC_TRST_N")
	)
	(segment
		(start 482.83749 -35.5981)
		(end 482.58349 -35.5981)
		(width 0.089408)
		(layer "In2.Cu")
		(net "JTAG_BMC_TRST_N")
	)
	(segment
		(start 474.116908 -36.64458)
		(end 475.552516 -35.208972)
		(width 0.089408)
		(layer "In2.Cu")
		(net "JTAG_BMC_TRST_N")
	)
	(segment
		(start 468.690198 -38.606476)
		(end 468.92083 -38.375844)
		(width 0.089408)
		(layer "In2.Cu")
		(net "JTAG_BMC_TRST_N")
	)
	(segment
		(start 467.275418 -38.606476)
		(end 468.690198 -38.606476)
		(width 0.089408)
		(layer "In2.Cu")
		(net "JTAG_BMC_TRST_N")
	)
	(segment
		(start 483.40137 -36.737036)
		(end 482.983794 -36.31946)
		(width 0.089408)
		(layer "In2.Cu")
		(net "JTAG_BMC_TRST_N")
	)
	(segment
		(start 477.402906 -36.06165)
		(end 476.734886 -36.06165)
		(width 0.089408)
		(layer "In2.Cu")
		(net "JTAG_BMC_TRST_N")
	)
	(segment
		(start 416.84702 3.361944)
		(end 416.847274 3.362198)
		(width 0.089408)
		(layer "In4.Cu")
		(net "JTAG_BMC_TRST_N")
	)
	(segment
		(start 472.751912 -63.011812)
		(end 475.300294 -63.011812)
		(width 0.089408)
		(layer "In4.Cu")
		(net "JTAG_BMC_TRST_N")
	)
	(segment
		(start 487.721656 -34.136584)
		(end 487.47553 -34.136584)
		(width 0.089408)
		(layer "In4.Cu")
		(net "JTAG_BMC_TRST_N")
	)
	(segment
		(start 412.627064 1.966722)
		(end 412.827216 1.966722)
		(width 0.089408)
		(layer "In4.Cu")
		(net "JTAG_BMC_TRST_N")
	)
	(segment
		(start 418.25164 3.361944)
		(end 421.100504 3.361944)
		(width 0.089408)
		(layer "In4.Cu")
		(net "JTAG_BMC_TRST_N")
	)
	(segment
		(start 479.49866 -48.35144)
		(end 480.327462 -47.522638)
		(width 0.089408)
		(layer "In4.Cu")
		(net "JTAG_BMC_TRST_N")
	)
	(segment
		(start 471.715338 -12.409932)
		(end 476.931482 -17.626076)
		(width 0.089408)
		(layer "In4.Cu")
		(net "JTAG_BMC_TRST_N")
	)
	(segment
		(start 400.451828 1.990344)
		(end 401.052284 2.5908)
		(width 0.089408)
		(layer "In4.Cu")
		(net "JTAG_BMC_TRST_N")
	)
	(segment
		(start 416.847274 3.362198)
		(end 418.251386 3.362198)
		(width 0.089408)
		(layer "In4.Cu")
		(net "JTAG_BMC_TRST_N")
	)
	(segment
		(start 469.022938 -59.282838)
		(end 472.751912 -63.011812)
		(width 0.089408)
		(layer "In4.Cu")
		(net "JTAG_BMC_TRST_N")
	)
	(segment
		(start 479.307652 -19.137122)
		(end 480.245166 -19.137122)
		(width 0.089408)
		(layer "In4.Cu")
		(net "JTAG_BMC_TRST_N")
	)
	(segment
		(start 483.936294 -27.170634)
		(end 484.10241 -27.33675)
		(width 0.089408)
		(layer "In4.Cu")
		(net "JTAG_BMC_TRST_N")
	)
	(segment
		(start 476.764858 -54.600094)
		(end 476.764858 -53.646578)
		(width 0.089408)
		(layer "In4.Cu")
		(net "JTAG_BMC_TRST_N")
	)
	(segment
		(start 478.60458 -52.40782)
		(end 479.49866 -51.51374)
		(width 0.089408)
		(layer "In4.Cu")
		(net "JTAG_BMC_TRST_N")
	)
	(segment
		(start 483.936294 -26.712926)
		(end 483.936294 -27.170634)
		(width 0.089408)
		(layer "In4.Cu")
		(net "JTAG_BMC_TRST_N")
	)
	(segment
		(start 422.81094 1.85166)
		(end 423.412412 1.85166)
		(width 0.089408)
		(layer "In4.Cu")
		(net "JTAG_BMC_TRST_N")
	)
	(segment
		(start 432.29022 0.04318)
		(end 432.290474 0.043434)
		(width 0.089408)
		(layer "In4.Cu")
		(net "JTAG_BMC_TRST_N")
	)
	(segment
		(start 430.274984 1.858264)
		(end 432.090068 0.04318)
		(width 0.089408)
		(layer "In4.Cu")
		(net "JTAG_BMC_TRST_N")
	)
	(segment
		(start 485.51973 -27.33675)
		(end 487.597958 -29.414978)
		(width 0.089408)
		(layer "In4.Cu")
		(net "JTAG_BMC_TRST_N")
	)
	(segment
		(start 421.100504 3.361944)
		(end 422.610534 1.851914)
		(width 0.089408)
		(layer "In4.Cu")
		(net "JTAG_BMC_TRST_N")
	)
	(segment
		(start 487.597958 -29.414978)
		(end 487.597958 -31.281116)
		(width 0.089408)
		(layer "In4.Cu")
		(net "JTAG_BMC_TRST_N")
	)
	(segment
		(start 414.170622 1.966976)
		(end 415.56559 3.361944)
		(width 0.089408)
		(layer "In4.Cu")
		(net "JTAG_BMC_TRST_N")
	)
	(segment
		(start 426.293534 1.851914)
		(end 427.222666 1.851914)
		(width 0.089408)
		(layer "In4.Cu")
		(net "JTAG_BMC_TRST_N")
	)
	(segment
		(start 476.764858 -53.646578)
		(end 478.003616 -52.40782)
		(width 0.089408)
		(layer "In4.Cu")
		(net "JTAG_BMC_TRST_N")
	)
	(segment
		(start 426.29328 1.852168)
		(end 426.293534 1.851914)
		(width 0.089408)
		(layer "In4.Cu")
		(net "JTAG_BMC_TRST_N")
	)
	(segment
		(start 469.327738 -11.126978)
		(end 470.610692 -12.409932)
		(width 0.089408)
		(layer "In4.Cu")
		(net "JTAG_BMC_TRST_N")
	)
	(segment
		(start 459.848204 -9.66597)
		(end 461.199992 -11.017758)
		(width 0.089408)
		(layer "In4.Cu")
		(net "JTAG_BMC_TRST_N")
	)
	(segment
		(start 480.245166 -19.137122)
		(end 483.085394 -21.97735)
		(width 0.089408)
		(layer "In4.Cu")
		(net "JTAG_BMC_TRST_N")
	)
	(segment
		(start 413.22879 1.966976)
		(end 414.170622 1.966976)
		(width 0.089408)
		(layer "In4.Cu")
		(net "JTAG_BMC_TRST_N")
	)
	(segment
		(start 468.488776 -56.90489)
		(end 469.022938 -57.439052)
		(width 0.089408)
		(layer "In4.Cu")
		(net "JTAG_BMC_TRST_N")
	)
	(segment
		(start 476.931482 -17.626076)
		(end 477.796606 -17.626076)
		(width 0.089408)
		(layer "In4.Cu")
		(net "JTAG_BMC_TRST_N")
	)
	(segment
		(start 418.251386 3.362198)
		(end 418.25164 3.361944)
		(width 0.089408)
		(layer "In4.Cu")
		(net "JTAG_BMC_TRST_N")
	)
	(segment
		(start 454.639172 0.043434)
		(end 456.462892 -1.780286)
		(width 0.089408)
		(layer "In4.Cu")
		(net "JTAG_BMC_TRST_N")
	)
	(segment
		(start 480.327462 -47.522638)
		(end 480.327462 -36.981638)
		(width 0.089408)
		(layer "In4.Cu")
		(net "JTAG_BMC_TRST_N")
	)
	(segment
		(start 475.300294 -63.011812)
		(end 476.674688 -61.637418)
		(width 0.089408)
		(layer "In4.Cu")
		(net "JTAG_BMC_TRST_N")
	)
	(segment
		(start 413.228282 1.966468)
		(end 413.22879 1.966976)
		(width 0.089408)
		(layer "In4.Cu")
		(net "JTAG_BMC_TRST_N")
	)
	(segment
		(start 458.736192 -2.836926)
		(end 458.766926 -2.86766)
		(width 0.089408)
		(layer "In4.Cu")
		(net "JTAG_BMC_TRST_N")
	)
	(segment
		(start 412.827216 1.966722)
		(end 412.82747 1.966468)
		(width 0.089408)
		(layer "In4.Cu")
		(net "JTAG_BMC_TRST_N")
	)
	(segment
		(start 470.610692 -12.409932)
		(end 471.715338 -12.409932)
		(width 0.089408)
		(layer "In4.Cu")
		(net "JTAG_BMC_TRST_N")
	)
	(segment
		(start 488.004612 -33.853628)
		(end 487.721656 -34.136584)
		(width 0.089408)
		(layer "In4.Cu")
		(net "JTAG_BMC_TRST_N")
	)
	(segment
		(start 477.796606 -17.626076)
		(end 479.307652 -19.137122)
		(width 0.089408)
		(layer "In4.Cu")
		(net "JTAG_BMC_TRST_N")
	)
	(segment
		(start 459.848204 -9.031732)
		(end 459.848204 -9.66597)
		(width 0.089408)
		(layer "In4.Cu")
		(net "JTAG_BMC_TRST_N")
	)
	(segment
		(start 422.810686 1.851914)
		(end 422.81094 1.85166)
		(width 0.089408)
		(layer "In4.Cu")
		(net "JTAG_BMC_TRST_N")
	)
	(segment
		(start 469.022938 -57.439052)
		(end 469.022938 -59.282838)
		(width 0.089408)
		(layer "In4.Cu")
		(net "JTAG_BMC_TRST_N")
	)
	(segment
		(start 427.229016 1.858264)
		(end 430.274984 1.858264)
		(width 0.089408)
		(layer "In4.Cu")
		(net "JTAG_BMC_TRST_N")
	)
	(segment
		(start 415.56559 3.361944)
		(end 416.84702 3.361944)
		(width 0.089408)
		(layer "In4.Cu")
		(net "JTAG_BMC_TRST_N")
	)
	(segment
		(start 458.766926 -5.057394)
		(end 457.6572 -6.16712)
		(width 0.089408)
		(layer "In4.Cu")
		(net "JTAG_BMC_TRST_N")
	)
	(segment
		(start 457.6572 -6.840728)
		(end 459.848204 -9.031732)
		(width 0.089408)
		(layer "In4.Cu")
		(net "JTAG_BMC_TRST_N")
	)
	(segment
		(start 476.430086 -34.331402)
		(end 475.552516 -35.208972)
		(width 0.089408)
		(layer "In4.Cu")
		(net "JTAG_BMC_TRST_N")
	)
	(segment
		(start 461.199992 -11.017758)
		(end 464.85302 -11.017758)
		(width 0.089408)
		(layer "In4.Cu")
		(net "JTAG_BMC_TRST_N")
	)
	(segment
		(start 476.674688 -61.637418)
		(end 476.674688 -61.395102)
		(width 0.089408)
		(layer "In4.Cu")
		(net "JTAG_BMC_TRST_N")
	)
	(segment
		(start 476.674688 -61.395102)
		(end 476.674434 -61.394848)
		(width 0.089408)
		(layer "In4.Cu")
		(net "JTAG_BMC_TRST_N")
	)
	(segment
		(start 483.085394 -21.97735)
		(end 483.085394 -25.862026)
		(width 0.089408)
		(layer "In4.Cu")
		(net "JTAG_BMC_TRST_N")
	)
	(segment
		(start 432.090068 0.04318)
		(end 432.29022 0.04318)
		(width 0.089408)
		(layer "In4.Cu")
		(net "JTAG_BMC_TRST_N")
	)
	(segment
		(start 480.327462 -36.981638)
		(end 479.690176 -36.344352)
		(width 0.089408)
		(layer "In4.Cu")
		(net "JTAG_BMC_TRST_N")
	)
	(segment
		(start 412.002986 2.5908)
		(end 412.627064 1.966722)
		(width 0.089408)
		(layer "In4.Cu")
		(net "JTAG_BMC_TRST_N")
	)
	(segment
		(start 488.004612 -31.68777)
		(end 488.004612 -33.853628)
		(width 0.089408)
		(layer "In4.Cu")
		(net "JTAG_BMC_TRST_N")
	)
	(segment
		(start 458.736192 -2.026412)
		(end 458.736192 -2.836926)
		(width 0.089408)
		(layer "In4.Cu")
		(net "JTAG_BMC_TRST_N")
	)
	(segment
		(start 394.980922 1.990344)
		(end 400.451828 1.990344)
		(width 0.089408)
		(layer "In4.Cu")
		(net "JTAG_BMC_TRST_N")
	)
	(segment
		(start 487.597958 -31.281116)
		(end 488.004612 -31.68777)
		(width 0.089408)
		(layer "In4.Cu")
		(net "JTAG_BMC_TRST_N")
	)
	(segment
		(start 478.68967 -34.331402)
		(end 476.430086 -34.331402)
		(width 0.089408)
		(layer "In4.Cu")
		(net "JTAG_BMC_TRST_N")
	)
	(segment
		(start 476.674434 -56.150002)
		(end 477.289622 -55.534814)
		(width 0.089408)
		(layer "In4.Cu")
		(net "JTAG_BMC_TRST_N")
	)
	(segment
		(start 476.674434 -61.394848)
		(end 476.674434 -56.150002)
		(width 0.089408)
		(layer "In4.Cu")
		(net "JTAG_BMC_TRST_N")
	)
	(segment
		(start 464.96224 -11.126978)
		(end 469.327738 -11.126978)
		(width 0.089408)
		(layer "In4.Cu")
		(net "JTAG_BMC_TRST_N")
	)
	(segment
		(start 423.41292 1.852168)
		(end 426.29328 1.852168)
		(width 0.089408)
		(layer "In4.Cu")
		(net "JTAG_BMC_TRST_N")
	)
	(segment
		(start 392.049 -0.8636)
		(end 392.126978 -0.8636)
		(width 0.089408)
		(layer "In4.Cu")
		(net "JTAG_BMC_TRST_N")
	)
	(segment
		(start 422.610534 1.851914)
		(end 422.810686 1.851914)
		(width 0.089408)
		(layer "In4.Cu")
		(net "JTAG_BMC_TRST_N")
	)
	(segment
		(start 458.490066 -1.780286)
		(end 458.736192 -2.026412)
		(width 0.089408)
		(layer "In4.Cu")
		(net "JTAG_BMC_TRST_N")
	)
	(segment
		(start 464.85302 -11.017758)
		(end 464.96224 -11.126978)
		(width 0.089408)
		(layer "In4.Cu")
		(net "JTAG_BMC_TRST_N")
	)
	(segment
		(start 483.085394 -25.862026)
		(end 483.936294 -26.712926)
		(width 0.089408)
		(layer "In4.Cu")
		(net "JTAG_BMC_TRST_N")
	)
	(segment
		(start 478.003616 -52.40782)
		(end 478.60458 -52.40782)
		(width 0.089408)
		(layer "In4.Cu")
		(net "JTAG_BMC_TRST_N")
	)
	(segment
		(start 458.766926 -2.86766)
		(end 458.766926 -5.057394)
		(width 0.089408)
		(layer "In4.Cu")
		(net "JTAG_BMC_TRST_N")
	)
	(segment
		(start 432.290474 0.043434)
		(end 454.639172 0.043434)
		(width 0.089408)
		(layer "In4.Cu")
		(net "JTAG_BMC_TRST_N")
	)
	(segment
		(start 401.052284 2.5908)
		(end 412.002986 2.5908)
		(width 0.089408)
		(layer "In4.Cu")
		(net "JTAG_BMC_TRST_N")
	)
	(segment
		(start 479.690176 -36.344352)
		(end 479.690176 -35.331908)
		(width 0.089408)
		(layer "In4.Cu")
		(net "JTAG_BMC_TRST_N")
	)
	(segment
		(start 479.690176 -35.331908)
		(end 478.68967 -34.331402)
		(width 0.089408)
		(layer "In4.Cu")
		(net "JTAG_BMC_TRST_N")
	)
	(segment
		(start 392.126978 -0.8636)
		(end 394.980922 1.990344)
		(width 0.089408)
		(layer "In4.Cu")
		(net "JTAG_BMC_TRST_N")
	)
	(segment
		(start 456.462892 -1.780286)
		(end 458.490066 -1.780286)
		(width 0.089408)
		(layer "In4.Cu")
		(net "JTAG_BMC_TRST_N")
	)
	(segment
		(start 457.6572 -6.16712)
		(end 457.6572 -6.840728)
		(width 0.089408)
		(layer "In4.Cu")
		(net "JTAG_BMC_TRST_N")
	)
	(segment
		(start 477.289622 -55.534814)
		(end 477.289622 -55.124858)
		(width 0.089408)
		(layer "In4.Cu")
		(net "JTAG_BMC_TRST_N")
	)
	(segment
		(start 479.49866 -51.51374)
		(end 479.49866 -48.35144)
		(width 0.089408)
		(layer "In4.Cu")
		(net "JTAG_BMC_TRST_N")
	)
	(segment
		(start 484.10241 -27.33675)
		(end 485.51973 -27.33675)
		(width 0.089408)
		(layer "In4.Cu")
		(net "JTAG_BMC_TRST_N")
	)
	(segment
		(start 423.412412 1.85166)
		(end 423.41292 1.852168)
		(width 0.089408)
		(layer "In4.Cu")
		(net "JTAG_BMC_TRST_N")
	)
	(segment
		(start 412.82747 1.966468)
		(end 413.228282 1.966468)
		(width 0.089408)
		(layer "In4.Cu")
		(net "JTAG_BMC_TRST_N")
	)
	(segment
		(start 477.289622 -55.124858)
		(end 476.764858 -54.600094)
		(width 0.089408)
		(layer "In4.Cu")
		(net "JTAG_BMC_TRST_N")
	)
	(segment
		(start 427.222666 1.851914)
		(end 427.229016 1.858264)
		(width 0.089408)
		(layer "In4.Cu")
		(net "JTAG_BMC_TRST_N")
	)
	(segment
		(start 426.18152 -115.158774)
		(end 426.18152 -112.978438)
		(width 0.089408)
		(layer "In9.Cu")
		(net "JTAG_BMC_TRST_N")
	)
	(segment
		(start 431.795682 -140.393674)
		(end 431.067718 -140.393674)
		(width 0.089408)
		(layer "In9.Cu")
		(net "JTAG_BMC_TRST_N")
	)
	(segment
		(start 433.413916 -140.39342)
		(end 431.795936 -140.39342)
		(width 0.089408)
		(layer "In9.Cu")
		(net "JTAG_BMC_TRST_N")
	)
	(segment
		(start 435.72684 -145.469864)
		(end 435.72684 -142.706344)
		(width 0.089408)
		(layer "In9.Cu")
		(net "JTAG_BMC_TRST_N")
	)
	(segment
		(start 427.320456 -120.844564)
		(end 427.320456 -120.109996)
		(width 0.089408)
		(layer "In9.Cu")
		(net "JTAG_BMC_TRST_N")
	)
	(segment
		(start 418.076126 -131.3307)
		(end 418.076126 -130.77698)
		(width 0.089408)
		(layer "In9.Cu")
		(net "JTAG_BMC_TRST_N")
	)
	(segment
		(start 426.18152 -112.978438)
		(end 424.526456 -111.323374)
		(width 0.089408)
		(layer "In9.Cu")
		(net "JTAG_BMC_TRST_N")
	)
	(segment
		(start 427.067726 -121.097294)
		(end 427.320456 -120.844564)
		(width 0.089408)
		(layer "In9.Cu")
		(net "JTAG_BMC_TRST_N")
	)
	(segment
		(start 435.72684 -142.706344)
		(end 433.413916 -140.39342)
		(width 0.089408)
		(layer "In9.Cu")
		(net "JTAG_BMC_TRST_N")
	)
	(segment
		(start 431.795936 -140.39342)
		(end 431.795682 -140.393674)
		(width 0.089408)
		(layer "In9.Cu")
		(net "JTAG_BMC_TRST_N")
	)
	(segment
		(start 428.969678 -138.295634)
		(end 427.469046 -138.295634)
		(width 0.089408)
		(layer "In9.Cu")
		(net "JTAG_BMC_TRST_N")
	)
	(segment
		(start 426.105066 -136.931654)
		(end 423.67708 -136.931654)
		(width 0.089408)
		(layer "In9.Cu")
		(net "JTAG_BMC_TRST_N")
	)
	(segment
		(start 434.438806 -146.757898)
		(end 435.72684 -145.469864)
		(width 0.089408)
		(layer "In9.Cu")
		(net "JTAG_BMC_TRST_N")
	)
	(segment
		(start 427.067726 -122.394726)
		(end 427.067726 -121.097294)
		(width 0.089408)
		(layer "In9.Cu")
		(net "JTAG_BMC_TRST_N")
	)
	(segment
		(start 431.067718 -140.393674)
		(end 428.969678 -138.295634)
		(width 0.089408)
		(layer "In9.Cu")
		(net "JTAG_BMC_TRST_N")
	)
	(segment
		(start 426.903134 -119.692674)
		(end 426.903134 -115.880388)
		(width 0.089408)
		(layer "In9.Cu")
		(net "JTAG_BMC_TRST_N")
	)
	(segment
		(start 427.101 -122.428)
		(end 427.067726 -122.394726)
		(width 0.089408)
		(layer "In9.Cu")
		(net "JTAG_BMC_TRST_N")
	)
	(segment
		(start 424.526456 -111.323374)
		(end 423.945304 -111.323374)
		(width 0.089408)
		(layer "In9.Cu")
		(net "JTAG_BMC_TRST_N")
	)
	(segment
		(start 423.67708 -136.931654)
		(end 418.076126 -131.3307)
		(width 0.089408)
		(layer "In9.Cu")
		(net "JTAG_BMC_TRST_N")
	)
	(segment
		(start 427.469046 -138.295634)
		(end 426.105066 -136.931654)
		(width 0.089408)
		(layer "In9.Cu")
		(net "JTAG_BMC_TRST_N")
	)
	(segment
		(start 427.320456 -120.109996)
		(end 426.903134 -119.692674)
		(width 0.089408)
		(layer "In9.Cu")
		(net "JTAG_BMC_TRST_N")
	)
	(segment
		(start 426.903134 -115.880388)
		(end 426.18152 -115.158774)
		(width 0.089408)
		(layer "In9.Cu")
		(net "JTAG_BMC_TRST_N")
	)
	(segment
		(start 424.894248 -125.886972)
		(end 424.562524 -125.886972)
		(width 0.089408)
		(layer "In11.Cu")
		(net "JTAG_BMC_TRST_N")
	)
	(segment
		(start 414.01111 -35.688016)
		(end 418.683948 -35.688016)
		(width 0.089408)
		(layer "In11.Cu")
		(net "JTAG_BMC_TRST_N")
	)
	(segment
		(start 446.221866 -38.69436)
		(end 447.979546 -36.93668)
		(width 0.089408)
		(layer "In11.Cu")
		(net "JTAG_BMC_TRST_N")
	)
	(segment
		(start 377.874022 -2.795016)
		(end 379.9078 -2.795016)
		(width 0.089408)
		(layer "In11.Cu")
		(net "JTAG_BMC_TRST_N")
	)
	(segment
		(start 424.297856 -35.331654)
		(end 427.272196 -38.305994)
		(width 0.089408)
		(layer "In11.Cu")
		(net "JTAG_BMC_TRST_N")
	)
	(segment
		(start 409.890214 -34.934652)
		(end 413.257746 -34.934652)
		(width 0.089408)
		(layer "In11.Cu")
		(net "JTAG_BMC_TRST_N")
	)
	(segment
		(start 427.272196 -38.305994)
		(end 429.77689 -38.305994)
		(width 0.089408)
		(layer "In11.Cu")
		(net "JTAG_BMC_TRST_N")
	)
	(segment
		(start 424.558206 -125.882654)
		(end 424.509438 -125.882654)
		(width 0.089408)
		(layer "In11.Cu")
		(net "JTAG_BMC_TRST_N")
	)
	(segment
		(start 391.542016 -0.356616)
		(end 392.049 -0.8636)
		(width 0.089408)
		(layer "In11.Cu")
		(net "JTAG_BMC_TRST_N")
	)
	(segment
		(start 429.77689 -38.305994)
		(end 430.25441 -37.828474)
		(width 0.089408)
		(layer "In11.Cu")
		(net "JTAG_BMC_TRST_N")
	)
	(segment
		(start 356.932484 -4.54787)
		(end 357.132636 -4.54787)
		(width 0.089408)
		(layer "In11.Cu")
		(net "JTAG_BMC_TRST_N")
	)
	(segment
		(start 458.46238 -36.797742)
		(end 459.69428 -36.797742)
		(width 0.089408)
		(layer "In11.Cu")
		(net "JTAG_BMC_TRST_N")
	)
	(segment
		(start 355.6254 -2.54)
		(end 356.462584 -3.377184)
		(width 0.089408)
		(layer "In11.Cu")
		(net "JTAG_BMC_TRST_N")
	)
	(segment
		(start 363.551978 -4.547616)
		(end 365.710978 -2.388616)
		(width 0.089408)
		(layer "In11.Cu")
		(net "JTAG_BMC_TRST_N")
	)
	(segment
		(start 460.10195 -37.205412)
		(end 464.473798 -37.205412)
		(width 0.089408)
		(layer "In11.Cu")
		(net "JTAG_BMC_TRST_N")
	)
	(segment
		(start 425.29633 -122.600212)
		(end 425.29633 -125.532388)
		(width 0.089408)
		(layer "In11.Cu")
		(net "JTAG_BMC_TRST_N")
	)
	(segment
		(start 413.257746 -34.934652)
		(end 414.01111 -35.688016)
		(width 0.089408)
		(layer "In11.Cu")
		(net "JTAG_BMC_TRST_N")
	)
	(segment
		(start 433.761134 -37.828474)
		(end 434.960776 -39.028116)
		(width 0.089408)
		(layer "In11.Cu")
		(net "JTAG_BMC_TRST_N")
	)
	(segment
		(start 357.13289 -4.547616)
		(end 363.551978 -4.547616)
		(width 0.089408)
		(layer "In11.Cu")
		(net "JTAG_BMC_TRST_N")
	)
	(segment
		(start 427.101 -122.428)
		(end 426.499528 -122.428)
		(width 0.089408)
		(layer "In11.Cu")
		(net "JTAG_BMC_TRST_N")
	)
	(segment
		(start 430.25441 -37.828474)
		(end 433.761134 -37.828474)
		(width 0.089408)
		(layer "In11.Cu")
		(net "JTAG_BMC_TRST_N")
	)
	(segment
		(start 459.69428 -36.797742)
		(end 460.10195 -37.205412)
		(width 0.089408)
		(layer "In11.Cu")
		(net "JTAG_BMC_TRST_N")
	)
	(segment
		(start 382.3462 -0.356616)
		(end 391.542016 -0.356616)
		(width 0.089408)
		(layer "In11.Cu")
		(net "JTAG_BMC_TRST_N")
	)
	(segment
		(start 424.562524 -125.886972)
		(end 424.558206 -125.882654)
		(width 0.089408)
		(layer "In11.Cu")
		(net "JTAG_BMC_TRST_N")
	)
	(segment
		(start 458.261974 -36.797488)
		(end 458.462126 -36.797488)
		(width 0.089408)
		(layer "In11.Cu")
		(net "JTAG_BMC_TRST_N")
	)
	(segment
		(start 418.076126 -130.711702)
		(end 418.076126 -130.77698)
		(width 0.089408)
		(layer "In11.Cu")
		(net "JTAG_BMC_TRST_N")
	)
	(segment
		(start 425.29633 -125.532388)
		(end 424.946064 -125.882654)
		(width 0.089408)
		(layer "In11.Cu")
		(net "JTAG_BMC_TRST_N")
	)
	(segment
		(start 442.571886 -39.028116)
		(end 443.053216 -38.546786)
		(width 0.089408)
		(layer "In11.Cu")
		(net "JTAG_BMC_TRST_N")
	)
	(segment
		(start 365.710978 -2.388616)
		(end 377.467622 -2.388616)
		(width 0.089408)
		(layer "In11.Cu")
		(net "JTAG_BMC_TRST_N")
	)
	(segment
		(start 443.053216 -38.546786)
		(end 445.38265 -38.546786)
		(width 0.089408)
		(layer "In11.Cu")
		(net "JTAG_BMC_TRST_N")
	)
	(segment
		(start 426.37329 -122.301762)
		(end 425.59478 -122.301762)
		(width 0.089408)
		(layer "In11.Cu")
		(net "JTAG_BMC_TRST_N")
	)
	(segment
		(start 356.462584 -4.07797)
		(end 356.932484 -4.54787)
		(width 0.089408)
		(layer "In11.Cu")
		(net "JTAG_BMC_TRST_N")
	)
	(segment
		(start 445.38265 -38.546786)
		(end 445.530224 -38.69436)
		(width 0.089408)
		(layer "In11.Cu")
		(net "JTAG_BMC_TRST_N")
	)
	(segment
		(start 424.898566 -125.882654)
		(end 424.894248 -125.886972)
		(width 0.089408)
		(layer "In11.Cu")
		(net "JTAG_BMC_TRST_N")
	)
	(segment
		(start 424.946064 -125.882654)
		(end 424.898566 -125.882654)
		(width 0.089408)
		(layer "In11.Cu")
		(net "JTAG_BMC_TRST_N")
	)
	(segment
		(start 434.960776 -39.028116)
		(end 442.571886 -39.028116)
		(width 0.089408)
		(layer "In11.Cu")
		(net "JTAG_BMC_TRST_N")
	)
	(segment
		(start 445.530224 -38.69436)
		(end 446.221866 -38.69436)
		(width 0.089408)
		(layer "In11.Cu")
		(net "JTAG_BMC_TRST_N")
	)
	(segment
		(start 447.979546 -36.93668)
		(end 458.122782 -36.93668)
		(width 0.089408)
		(layer "In11.Cu")
		(net "JTAG_BMC_TRST_N")
	)
	(segment
		(start 420.024814 -130.367278)
		(end 418.42055 -130.367278)
		(width 0.089408)
		(layer "In11.Cu")
		(net "JTAG_BMC_TRST_N")
	)
	(segment
		(start 356.462584 -3.377184)
		(end 356.462584 -4.07797)
		(width 0.089408)
		(layer "In11.Cu")
		(net "JTAG_BMC_TRST_N")
	)
	(segment
		(start 464.75269 -37.484304)
		(end 466.751924 -37.484304)
		(width 0.089408)
		(layer "In11.Cu")
		(net "JTAG_BMC_TRST_N")
	)
	(segment
		(start 458.122782 -36.93668)
		(end 458.261974 -36.797488)
		(width 0.089408)
		(layer "In11.Cu")
		(net "JTAG_BMC_TRST_N")
	)
	(segment
		(start 357.132636 -4.54787)
		(end 357.13289 -4.547616)
		(width 0.089408)
		(layer "In11.Cu")
		(net "JTAG_BMC_TRST_N")
	)
	(segment
		(start 466.751924 -37.484304)
		(end 467.275418 -38.007798)
		(width 0.089408)
		(layer "In11.Cu")
		(net "JTAG_BMC_TRST_N")
	)
	(segment
		(start 426.499528 -122.428)
		(end 426.37329 -122.301762)
		(width 0.089408)
		(layer "In11.Cu")
		(net "JTAG_BMC_TRST_N")
	)
	(segment
		(start 418.42055 -130.367278)
		(end 418.076126 -130.711702)
		(width 0.089408)
		(layer "In11.Cu")
		(net "JTAG_BMC_TRST_N")
	)
	(segment
		(start 419.04031 -35.331654)
		(end 424.297856 -35.331654)
		(width 0.089408)
		(layer "In11.Cu")
		(net "JTAG_BMC_TRST_N")
	)
	(segment
		(start 458.462126 -36.797488)
		(end 458.46238 -36.797742)
		(width 0.089408)
		(layer "In11.Cu")
		(net "JTAG_BMC_TRST_N")
	)
	(segment
		(start 464.473798 -37.205412)
		(end 464.75269 -37.484304)
		(width 0.089408)
		(layer "In11.Cu")
		(net "JTAG_BMC_TRST_N")
	)
	(segment
		(start 467.275418 -38.007798)
		(end 467.275418 -38.606476)
		(width 0.089408)
		(layer "In11.Cu")
		(net "JTAG_BMC_TRST_N")
	)
	(segment
		(start 425.59478 -122.301762)
		(end 425.29633 -122.600212)
		(width 0.089408)
		(layer "In11.Cu")
		(net "JTAG_BMC_TRST_N")
	)
	(segment
		(start 377.467622 -2.388616)
		(end 377.874022 -2.795016)
		(width 0.089408)
		(layer "In11.Cu")
		(net "JTAG_BMC_TRST_N")
	)
	(segment
		(start 379.9078 -2.795016)
		(end 382.3462 -0.356616)
		(width 0.089408)
		(layer "In11.Cu")
		(net "JTAG_BMC_TRST_N")
	)
	(segment
		(start 418.683948 -35.688016)
		(end 419.04031 -35.331654)
		(width 0.089408)
		(layer "In11.Cu")
		(net "JTAG_BMC_TRST_N")
	)
	(segment
		(start 424.509438 -125.882654)
		(end 420.024814 -130.367278)
		(width 0.089408)
		(layer "In11.Cu")
		(net "JTAG_BMC_TRST_N")
	)
	(segment
		(start 131.089908 -68.287138)
		(end 131.661408 -68.287138)
		(width 0.1016)
		(layer "F.Cu")
		(net "H_PM_SYNC_GTL_R2")
	)
	(via
		(at 131.661408 -68.287138)
		(size 0.508)
		(drill 0.254)
		(layers "F.Cu" "B.Cu")
		(net "H_PM_SYNC_GTL_R2")
	)
	(segment
		(start 130.8354 -68.287138)
		(end 131.661408 -68.287138)
		(width 0.10795)
		(layer "B.Cu")
		(net "H_PM_SYNC_GTL_R2")
	)
	(segment
		(start 130.61188 -67.764914)
		(end 130.61188 -68.063618)
		(width 0.10795)
		(layer "B.Cu")
		(net "H_PM_SYNC_GTL_R2")
	)
	(segment
		(start 130.61188 -68.063618)
		(end 130.8354 -68.287138)
		(width 0.10795)
		(layer "B.Cu")
		(net "H_PM_SYNC_GTL_R2")
	)
	(segment
		(start 296.66184 -68.287138)
		(end 296.09034 -68.287138)
		(width 0.1016)
		(layer "F.Cu")
		(net "H_PM_SYNC_GTL_R1")
	)
	(via
		(at 296.66184 -68.287138)
		(size 0.508)
		(drill 0.254)
		(layers "F.Cu" "B.Cu")
		(net "H_PM_SYNC_GTL_R1")
	)
	(segment
		(start 296.529506 -68.154804)
		(end 295.8846 -68.154804)
		(width 0.10795)
		(layer "B.Cu")
		(net "H_PM_SYNC_GTL_R1")
	)
	(segment
		(start 296.66184 -68.287138)
		(end 296.529506 -68.154804)
		(width 0.10795)
		(layer "B.Cu")
		(net "H_PM_SYNC_GTL_R1")
	)
	(segment
		(start 409.283408 -66.529966)
		(end 410.340048 -66.529966)
		(width 0.10795)
		(layer "F.Cu")
		(net "SPI_PCH_TPM_CLK_R")
	)
	(segment
		(start 407.878026 -65.869566)
		(end 408.623008 -65.869566)
		(width 0.10795)
		(layer "F.Cu")
		(net "SPI_PCH_TPM_CLK_R")
	)
	(segment
		(start 408.623008 -65.869566)
		(end 409.283408 -66.529966)
		(width 0.10795)
		(layer "F.Cu")
		(net "SPI_PCH_TPM_CLK_R")
	)
	(segment
		(start 489.24718 -42.45102)
		(end 488.980734 -42.717466)
		(width 0.10795)
		(layer "F.Cu")
		(net "RMII_SPRNGVLLE_BMC_PCH_RXD0_R")
	)
	(segment
		(start 488.980734 -42.717466)
		(end 488.6198 -42.717466)
		(width 0.10795)
		(layer "F.Cu")
		(net "RMII_SPRNGVLLE_BMC_PCH_RXD0_R")
	)
	(segment
		(start 490.41812 -42.45102)
		(end 490.051344 -42.45102)
		(width 0.10795)
		(layer "F.Cu")
		(net "RMII_SPRNGVLLE_BMC_PCH_RXD0_R")
	)
	(segment
		(start 491.0455 -43.0784)
		(end 490.41812 -42.45102)
		(width 0.10795)
		(layer "F.Cu")
		(net "RMII_SPRNGVLLE_BMC_PCH_RXD0_R")
	)
	(segment
		(start 490.051344 -42.45102)
		(end 489.24718 -42.45102)
		(width 0.10795)
		(layer "F.Cu")
		(net "RMII_SPRNGVLLE_BMC_PCH_RXD0_R")
	)
	(via
		(at 490.051344 -42.45102)
		(size 0.508)
		(drill 0.254)
		(layers "F.Cu" "B.Cu")
		(net "RMII_SPRNGVLLE_BMC_PCH_RXD0_R")
	)
	(segment
		(start 398.13865 -97.83572)
		(end 398.853406 -97.629472)
		(width 0.10795)
		(layer "F.Cu")
		(net "FP_NMI_BTN_N")
	)
	(segment
		(start 410.290264 -40.13454)
		(end 409.890214 -40.53459)
		(width 0.089408)
		(layer "F.Cu")
		(net "FP_NMI_BTN_N")
	)
	(via
		(at 412.2928 -19.2532)
		(size 0.508)
		(drill 0.254)
		(layers "F.Cu" "B.Cu")
		(net "FP_NMI_BTN_N")
	)
	(via
		(at 398.853406 -97.629472)
		(size 0.508)
		(drill 0.254)
		(layers "F.Cu" "B.Cu")
		(net "FP_NMI_BTN_N")
	)
	(via
		(at 407.162 -16.002)
		(size 0.6604)
		(drill 0.3302)
		(layers "F.Cu" "B.Cu")
		(net "FP_NMI_BTN_N")
	)
	(via
		(at 409.890214 -40.53459)
		(size 0.4572)
		(drill 0.2032)
		(layers "F.Cu" "B.Cu")
		(net "FP_NMI_BTN_N")
	)
	(via
		(at 405.893524 -48.874934)
		(size 0.508)
		(drill 0.254)
		(layers "F.Cu" "B.Cu")
		(net "FP_NMI_BTN_N")
	)
	(segment
		(start 408.931618 -42.518838)
		(end 408.85618 -42.4434)
		(width 0.10795)
		(layer "B.Cu")
		(net "FP_NMI_BTN_N")
	)
	(segment
		(start 412.2928 -19.2532)
		(end 412.2928 -19.031712)
		(width 0.10795)
		(layer "B.Cu")
		(net "FP_NMI_BTN_N")
	)
	(segment
		(start 409.4988 -41.858692)
		(end 409.4988 -42.291)
		(width 0.10795)
		(layer "B.Cu")
		(net "FP_NMI_BTN_N")
	)
	(segment
		(start 407.162 -15.283688)
		(end 407.3017 -15.143988)
		(width 0.10795)
		(layer "B.Cu")
		(net "FP_NMI_BTN_N")
	)
	(segment
		(start 408.059382 -18.307304)
		(end 408.077924 -18.288762)
		(width 0.10795)
		(layer "B.Cu")
		(net "FP_NMI_BTN_N")
	)
	(segment
		(start 409.730702 -41.750742)
		(end 409.60675 -41.750742)
		(width 0.10795)
		(layer "B.Cu")
		(net "FP_NMI_BTN_N")
	)
	(segment
		(start 407.725626 -45.347128)
		(end 407.725626 -47.465234)
		(width 0.10795)
		(layer "B.Cu")
		(net "FP_NMI_BTN_N")
	)
	(segment
		(start 411.764988 -18.5039)
		(end 409.6131 -18.5039)
		(width 0.10795)
		(layer "B.Cu")
		(net "FP_NMI_BTN_N")
	)
	(segment
		(start 407.3652 -13.9573)
		(end 407.3652 -14.351)
		(width 0.10795)
		(layer "B.Cu")
		(net "FP_NMI_BTN_N")
	)
	(segment
		(start 409.194 -18.923)
		(end 408.28595 -18.923)
		(width 0.10795)
		(layer "B.Cu")
		(net "FP_NMI_BTN_N")
	)
	(segment
		(start 410.849318 -40.950388)
		(end 411.096968 -41.198038)
		(width 0.10795)
		(layer "B.Cu")
		(net "FP_NMI_BTN_N")
	)
	(segment
		(start 409.6131 -18.5039)
		(end 409.194 -18.923)
		(width 0.10795)
		(layer "B.Cu")
		(net "FP_NMI_BTN_N")
	)
	(segment
		(start 407.3017 -14.4145)
		(end 407.3017 -14.7828)
		(width 0.10795)
		(layer "B.Cu")
		(net "FP_NMI_BTN_N")
	)
	(segment
		(start 409.270962 -42.518838)
		(end 408.931618 -42.518838)
		(width 0.10795)
		(layer "B.Cu")
		(net "FP_NMI_BTN_N")
	)
	(segment
		(start 407.57475 -45.196252)
		(end 407.725626 -45.347128)
		(width 0.10795)
		(layer "B.Cu")
		(net "FP_NMI_BTN_N")
	)
	(segment
		(start 408.178 -17.199864)
		(end 407.665936 -16.6878)
		(width 0.10795)
		(layer "B.Cu")
		(net "FP_NMI_BTN_N")
	)
	(segment
		(start 412.2928 -19.031712)
		(end 411.764988 -18.5039)
		(width 0.10795)
		(layer "B.Cu")
		(net "FP_NMI_BTN_N")
	)
	(segment
		(start 408.077924 -18.288762)
		(end 408.077924 -18.269204)
		(width 0.10795)
		(layer "B.Cu")
		(net "FP_NMI_BTN_N")
	)
	(segment
		(start 407.3652 -14.351)
		(end 407.3017 -14.4145)
		(width 0.10795)
		(layer "B.Cu")
		(net "FP_NMI_BTN_N")
	)
	(segment
		(start 410.049726 -41.750742)
		(end 410.049472 -41.750488)
		(width 0.10795)
		(layer "B.Cu")
		(net "FP_NMI_BTN_N")
	)
	(segment
		(start 410.530802 -41.750742)
		(end 410.049726 -41.750742)
		(width 0.10795)
		(layer "B.Cu")
		(net "FP_NMI_BTN_N")
	)
	(segment
		(start 408.059382 -18.696432)
		(end 408.059382 -18.307304)
		(width 0.10795)
		(layer "B.Cu")
		(net "FP_NMI_BTN_N")
	)
	(segment
		(start 410.843222 -40.9448)
		(end 410.84881 -40.950388)
		(width 0.10795)
		(layer "B.Cu")
		(net "FP_NMI_BTN_N")
	)
	(segment
		(start 407.665936 -16.505936)
		(end 407.162 -16.002)
		(width 0.10795)
		(layer "B.Cu")
		(net "FP_NMI_BTN_N")
	)
	(segment
		(start 408.077924 -18.269204)
		(end 408.178 -18.169128)
		(width 0.10795)
		(layer "B.Cu")
		(net "FP_NMI_BTN_N")
	)
	(segment
		(start 408.28595 -18.923)
		(end 408.059382 -18.696432)
		(width 0.10795)
		(layer "B.Cu")
		(net "FP_NMI_BTN_N")
	)
	(segment
		(start 411.096968 -41.498266)
		(end 410.844746 -41.750488)
		(width 0.10795)
		(layer "B.Cu")
		(net "FP_NMI_BTN_N")
	)
	(segment
		(start 410.464 -40.9448)
		(end 410.843222 -40.9448)
		(width 0.10795)
		(layer "B.Cu")
		(net "FP_NMI_BTN_N")
	)
	(segment
		(start 406.315926 -48.874934)
		(end 405.893524 -48.874934)
		(width 0.10795)
		(layer "B.Cu")
		(net "FP_NMI_BTN_N")
	)
	(segment
		(start 410.049472 -41.750488)
		(end 409.730956 -41.750488)
		(width 0.10795)
		(layer "B.Cu")
		(net "FP_NMI_BTN_N")
	)
	(segment
		(start 409.890214 -40.53459)
		(end 410.05379 -40.53459)
		(width 0.10795)
		(layer "B.Cu")
		(net "FP_NMI_BTN_N")
	)
	(segment
		(start 408.400758 -42.4434)
		(end 407.57475 -43.269408)
		(width 0.10795)
		(layer "B.Cu")
		(net "FP_NMI_BTN_N")
	)
	(segment
		(start 407.725626 -47.465234)
		(end 406.315926 -48.874934)
		(width 0.10795)
		(layer "B.Cu")
		(net "FP_NMI_BTN_N")
	)
	(segment
		(start 407.665936 -16.6878)
		(end 407.665936 -16.505936)
		(width 0.10795)
		(layer "B.Cu")
		(net "FP_NMI_BTN_N")
	)
	(segment
		(start 410.84881 -40.950388)
		(end 410.849318 -40.950388)
		(width 0.10795)
		(layer "B.Cu")
		(net "FP_NMI_BTN_N")
	)
	(segment
		(start 409.60675 -41.750742)
		(end 409.4988 -41.858692)
		(width 0.10795)
		(layer "B.Cu")
		(net "FP_NMI_BTN_N")
	)
	(segment
		(start 410.531056 -41.750488)
		(end 410.530802 -41.750742)
		(width 0.10795)
		(layer "B.Cu")
		(net "FP_NMI_BTN_N")
	)
	(segment
		(start 407.57475 -43.269408)
		(end 407.57475 -45.196252)
		(width 0.10795)
		(layer "B.Cu")
		(net "FP_NMI_BTN_N")
	)
	(segment
		(start 410.05379 -40.53459)
		(end 410.464 -40.9448)
		(width 0.10795)
		(layer "B.Cu")
		(net "FP_NMI_BTN_N")
	)
	(segment
		(start 407.3017 -15.143988)
		(end 407.3017 -14.7828)
		(width 0.10795)
		(layer "B.Cu")
		(net "FP_NMI_BTN_N")
	)
	(segment
		(start 411.096968 -41.198038)
		(end 411.096968 -41.498266)
		(width 0.10795)
		(layer "B.Cu")
		(net "FP_NMI_BTN_N")
	)
	(segment
		(start 409.730956 -41.750488)
		(end 409.730702 -41.750742)
		(width 0.10795)
		(layer "B.Cu")
		(net "FP_NMI_BTN_N")
	)
	(segment
		(start 408.85618 -42.4434)
		(end 408.400758 -42.4434)
		(width 0.10795)
		(layer "B.Cu")
		(net "FP_NMI_BTN_N")
	)
	(segment
		(start 408.178 -18.169128)
		(end 408.178 -17.199864)
		(width 0.10795)
		(layer "B.Cu")
		(net "FP_NMI_BTN_N")
	)
	(segment
		(start 409.4988 -42.291)
		(end 409.270962 -42.518838)
		(width 0.10795)
		(layer "B.Cu")
		(net "FP_NMI_BTN_N")
	)
	(segment
		(start 407.162 -16.002)
		(end 407.162 -15.283688)
		(width 0.10795)
		(layer "B.Cu")
		(net "FP_NMI_BTN_N")
	)
	(segment
		(start 410.844746 -41.750488)
		(end 410.531056 -41.750488)
		(width 0.10795)
		(layer "B.Cu")
		(net "FP_NMI_BTN_N")
	)
	(segment
		(start 398.853406 -97.629472)
		(end 399.203672 -97.629472)
		(width 0.089408)
		(layer "In2.Cu")
		(net "FP_NMI_BTN_N")
	)
	(segment
		(start 396.5702 -64.1096)
		(end 396.5702 -62.854078)
		(width 0.089408)
		(layer "In2.Cu")
		(net "FP_NMI_BTN_N")
	)
	(segment
		(start 396.578328 -75.687936)
		(end 396.578328 -73.635362)
		(width 0.089408)
		(layer "In2.Cu")
		(net "FP_NMI_BTN_N")
	)
	(segment
		(start 395.96568 -79.658464)
		(end 395.54531 -79.238094)
		(width 0.089408)
		(layer "In2.Cu")
		(net "FP_NMI_BTN_N")
	)
	(segment
		(start 394.623544 -71.070216)
		(end 394.623544 -66.056256)
		(width 0.089408)
		(layer "In2.Cu")
		(net "FP_NMI_BTN_N")
	)
	(segment
		(start 399.58137 -97.251774)
		(end 399.58137 -96.05899)
		(width 0.089408)
		(layer "In2.Cu")
		(net "FP_NMI_BTN_N")
	)
	(segment
		(start 405.893524 -49.881028)
		(end 405.893524 -48.874934)
		(width 0.089408)
		(layer "In2.Cu")
		(net "FP_NMI_BTN_N")
	)
	(segment
		(start 396.578328 -73.635362)
		(end 396.278862 -73.335896)
		(width 0.089408)
		(layer "In2.Cu")
		(net "FP_NMI_BTN_N")
	)
	(segment
		(start 394.623544 -66.056256)
		(end 396.5702 -64.1096)
		(width 0.089408)
		(layer "In2.Cu")
		(net "FP_NMI_BTN_N")
	)
	(segment
		(start 394.86332 -71.309992)
		(end 394.623544 -71.070216)
		(width 0.089408)
		(layer "In2.Cu")
		(net "FP_NMI_BTN_N")
	)
	(segment
		(start 399.203672 -97.629472)
		(end 399.58137 -97.251774)
		(width 0.089408)
		(layer "In2.Cu")
		(net "FP_NMI_BTN_N")
	)
	(segment
		(start 395.157198 -83.880198)
		(end 395.157198 -83.041998)
		(width 0.089408)
		(layer "In2.Cu")
		(net "FP_NMI_BTN_N")
	)
	(segment
		(start 395.54531 -76.720954)
		(end 396.578328 -75.687936)
		(width 0.089408)
		(layer "In2.Cu")
		(net "FP_NMI_BTN_N")
	)
	(segment
		(start 394.86332 -72.264016)
		(end 394.86332 -71.309992)
		(width 0.089408)
		(layer "In2.Cu")
		(net "FP_NMI_BTN_N")
	)
	(segment
		(start 395.9352 -73.335896)
		(end 394.86332 -72.264016)
		(width 0.089408)
		(layer "In2.Cu")
		(net "FP_NMI_BTN_N")
	)
	(segment
		(start 396.278862 -73.335896)
		(end 395.9352 -73.335896)
		(width 0.089408)
		(layer "In2.Cu")
		(net "FP_NMI_BTN_N")
	)
	(segment
		(start 396.1892 -84.9122)
		(end 395.157198 -83.880198)
		(width 0.089408)
		(layer "In2.Cu")
		(net "FP_NMI_BTN_N")
	)
	(segment
		(start 397.847312 -61.576966)
		(end 397.847312 -57.92724)
		(width 0.089408)
		(layer "In2.Cu")
		(net "FP_NMI_BTN_N")
	)
	(segment
		(start 395.157198 -83.041998)
		(end 395.96568 -82.233516)
		(width 0.089408)
		(layer "In2.Cu")
		(net "FP_NMI_BTN_N")
	)
	(segment
		(start 397.325596 -93.803216)
		(end 397.325596 -89.29243)
		(width 0.089408)
		(layer "In2.Cu")
		(net "FP_NMI_BTN_N")
	)
	(segment
		(start 397.847312 -57.92724)
		(end 405.893524 -49.881028)
		(width 0.089408)
		(layer "In2.Cu")
		(net "FP_NMI_BTN_N")
	)
	(segment
		(start 396.5702 -62.854078)
		(end 397.847312 -61.576966)
		(width 0.089408)
		(layer "In2.Cu")
		(net "FP_NMI_BTN_N")
	)
	(segment
		(start 395.54531 -79.238094)
		(end 395.54531 -76.720954)
		(width 0.089408)
		(layer "In2.Cu")
		(net "FP_NMI_BTN_N")
	)
	(segment
		(start 399.58137 -96.05899)
		(end 397.325596 -93.803216)
		(width 0.089408)
		(layer "In2.Cu")
		(net "FP_NMI_BTN_N")
	)
	(segment
		(start 395.96568 -82.233516)
		(end 395.96568 -79.658464)
		(width 0.089408)
		(layer "In2.Cu")
		(net "FP_NMI_BTN_N")
	)
	(segment
		(start 397.325596 -89.29243)
		(end 396.1892 -88.156034)
		(width 0.089408)
		(layer "In2.Cu")
		(net "FP_NMI_BTN_N")
	)
	(segment
		(start 396.1892 -88.156034)
		(end 396.1892 -84.9122)
		(width 0.089408)
		(layer "In2.Cu")
		(net "FP_NMI_BTN_N")
	)
	(segment
		(start 408.134566 -33.760156)
		(end 408.403552 -33.760156)
		(width 0.089408)
		(layer "In11.Cu")
		(net "FP_NMI_BTN_N")
	)
	(segment
		(start 408.664918 -36.256214)
		(end 408.268424 -35.85972)
		(width 0.089408)
		(layer "In11.Cu")
		(net "FP_NMI_BTN_N")
	)
	(segment
		(start 409.725368 -31.372556)
		(end 409.753816 -31.344108)
		(width 0.089408)
		(layer "In11.Cu")
		(net "FP_NMI_BTN_N")
	)
	(segment
		(start 409.734766 -29.709618)
		(end 409.465018 -29.43987)
		(width 0.089408)
		(layer "In11.Cu")
		(net "FP_NMI_BTN_N")
	)
	(segment
		(start 408.664918 -39.071296)
		(end 408.664918 -38.784276)
		(width 0.089408)
		(layer "In11.Cu")
		(net "FP_NMI_BTN_N")
	)
	(segment
		(start 408.131772 -33.76295)
		(end 408.134566 -33.760156)
		(width 0.089408)
		(layer "In11.Cu")
		(net "FP_NMI_BTN_N")
	)
	(segment
		(start 410.264864 -31.123128)
		(end 410.264864 -31.090362)
		(width 0.089408)
		(layer "In11.Cu")
		(net "FP_NMI_BTN_N")
	)
	(segment
		(start 409.502356 -31.592012)
		(end 409.721812 -31.372556)
		(width 0.089408)
		(layer "In11.Cu")
		(net "FP_NMI_BTN_N")
	)
	(segment
		(start 407.887932 -33.856168)
		(end 407.98115 -33.76295)
		(width 0.089408)
		(layer "In11.Cu")
		(net "FP_NMI_BTN_N")
	)
	(segment
		(start 408.916124 -32.109156)
		(end 408.934412 -32.109156)
		(width 0.089408)
		(layer "In11.Cu")
		(net "FP_NMI_BTN_N")
	)
	(segment
		(start 408.676094 -32.349186)
		(end 408.916124 -32.109156)
		(width 0.089408)
		(layer "In11.Cu")
		(net "FP_NMI_BTN_N")
	)
	(segment
		(start 409.995624 -29.709618)
		(end 409.734766 -29.709618)
		(width 0.089408)
		(layer "In11.Cu")
		(net "FP_NMI_BTN_N")
	)
	(segment
		(start 408.953716 -39.360094)
		(end 408.664918 -39.071296)
		(width 0.089408)
		(layer "In11.Cu")
		(net "FP_NMI_BTN_N")
	)
	(segment
		(start 408.715464 -26.99385)
		(end 409.089352 -26.619962)
		(width 0.089408)
		(layer "In11.Cu")
		(net "FP_NMI_BTN_N")
	)
	(segment
		(start 410.043884 -31.344108)
		(end 410.264864 -31.123128)
		(width 0.089408)
		(layer "In11.Cu")
		(net "FP_NMI_BTN_N")
	)
	(segment
		(start 409.47848 -39.474902)
		(end 409.377388 -39.37381)
		(width 0.089408)
		(layer "In11.Cu")
		(net "FP_NMI_BTN_N")
	)
	(segment
		(start 409.465018 -29.43987)
		(end 409.465018 -28.379166)
		(width 0.089408)
		(layer "In11.Cu")
		(net "FP_NMI_BTN_N")
	)
	(segment
		(start 408.664918 -37.564314)
		(end 408.664918 -36.256214)
		(width 0.089408)
		(layer "In11.Cu")
		(net "FP_NMI_BTN_N")
	)
	(segment
		(start 409.753816 -31.344108)
		(end 410.043884 -31.344108)
		(width 0.089408)
		(layer "In11.Cu")
		(net "FP_NMI_BTN_N")
	)
	(segment
		(start 409.245562 -32.10941)
		(end 409.502356 -31.852616)
		(width 0.089408)
		(layer "In11.Cu")
		(net "FP_NMI_BTN_N")
	)
	(segment
		(start 409.721812 -31.372556)
		(end 409.725368 -31.372556)
		(width 0.089408)
		(layer "In11.Cu")
		(net "FP_NMI_BTN_N")
	)
	(segment
		(start 408.369516 -38.484048)
		(end 408.369516 -37.859716)
		(width 0.089408)
		(layer "In11.Cu")
		(net "FP_NMI_BTN_N")
	)
	(segment
		(start 409.194508 -28.109164)
		(end 408.93492 -28.109164)
		(width 0.089408)
		(layer "In11.Cu")
		(net "FP_NMI_BTN_N")
	)
	(segment
		(start 408.715464 -27.889708)
		(end 408.715464 -26.99385)
		(width 0.089408)
		(layer "In11.Cu")
		(net "FP_NMI_BTN_N")
	)
	(segment
		(start 408.664664 -38.779196)
		(end 408.369516 -38.484048)
		(width 0.089408)
		(layer "In11.Cu")
		(net "FP_NMI_BTN_N")
	)
	(segment
		(start 410.265118 -31.090108)
		(end 410.265118 -29.979112)
		(width 0.089408)
		(layer "In11.Cu")
		(net "FP_NMI_BTN_N")
	)
	(segment
		(start 408.664664 -38.784022)
		(end 408.664664 -38.779196)
		(width 0.089408)
		(layer "In11.Cu")
		(net "FP_NMI_BTN_N")
	)
	(segment
		(start 411.829504 -19.716496)
		(end 412.2928 -19.2532)
		(width 0.089408)
		(layer "In11.Cu")
		(net "FP_NMI_BTN_N")
	)
	(segment
		(start 409.465018 -28.379166)
		(end 409.245562 -28.15971)
		(width 0.089408)
		(layer "In11.Cu")
		(net "FP_NMI_BTN_N")
	)
	(segment
		(start 407.887932 -35.199828)
		(end 407.887932 -33.856168)
		(width 0.089408)
		(layer "In11.Cu")
		(net "FP_NMI_BTN_N")
	)
	(segment
		(start 409.245054 -28.15971)
		(end 409.194508 -28.109164)
		(width 0.089408)
		(layer "In11.Cu")
		(net "FP_NMI_BTN_N")
	)
	(segment
		(start 408.403552 -33.760156)
		(end 408.664918 -33.49879)
		(width 0.089408)
		(layer "In11.Cu")
		(net "FP_NMI_BTN_N")
	)
	(segment
		(start 409.890214 -40.53459)
		(end 409.890214 -40.31615)
		(width 0.089408)
		(layer "In11.Cu")
		(net "FP_NMI_BTN_N")
	)
	(segment
		(start 408.676094 -32.781494)
		(end 408.676094 -32.349186)
		(width 0.089408)
		(layer "In11.Cu")
		(net "FP_NMI_BTN_N")
	)
	(segment
		(start 408.934666 -32.10941)
		(end 409.245562 -32.10941)
		(width 0.089408)
		(layer "In11.Cu")
		(net "FP_NMI_BTN_N")
	)
	(segment
		(start 407.98115 -33.76295)
		(end 408.131772 -33.76295)
		(width 0.089408)
		(layer "In11.Cu")
		(net "FP_NMI_BTN_N")
	)
	(segment
		(start 409.259278 -39.37381)
		(end 409.245562 -39.360094)
		(width 0.089408)
		(layer "In11.Cu")
		(net "FP_NMI_BTN_N")
	)
	(segment
		(start 409.47848 -39.904416)
		(end 409.47848 -39.474902)
		(width 0.089408)
		(layer "In11.Cu")
		(net "FP_NMI_BTN_N")
	)
	(segment
		(start 409.502356 -31.852616)
		(end 409.502356 -31.592012)
		(width 0.089408)
		(layer "In11.Cu")
		(net "FP_NMI_BTN_N")
	)
	(segment
		(start 408.268424 -35.85972)
		(end 408.268424 -35.58032)
		(width 0.089408)
		(layer "In11.Cu")
		(net "FP_NMI_BTN_N")
	)
	(segment
		(start 409.089352 -20.506182)
		(end 409.879038 -19.716496)
		(width 0.089408)
		(layer "In11.Cu")
		(net "FP_NMI_BTN_N")
	)
	(segment
		(start 408.664918 -33.49879)
		(end 408.664918 -32.79267)
		(width 0.089408)
		(layer "In11.Cu")
		(net "FP_NMI_BTN_N")
	)
	(segment
		(start 408.268424 -35.58032)
		(end 407.887932 -35.199828)
		(width 0.089408)
		(layer "In11.Cu")
		(net "FP_NMI_BTN_N")
	)
	(segment
		(start 409.245562 -28.15971)
		(end 409.245054 -28.15971)
		(width 0.089408)
		(layer "In11.Cu")
		(net "FP_NMI_BTN_N")
	)
	(segment
		(start 410.265118 -29.979112)
		(end 409.995624 -29.709618)
		(width 0.089408)
		(layer "In11.Cu")
		(net "FP_NMI_BTN_N")
	)
	(segment
		(start 409.245562 -39.360094)
		(end 408.953716 -39.360094)
		(width 0.089408)
		(layer "In11.Cu")
		(net "FP_NMI_BTN_N")
	)
	(segment
		(start 409.089352 -26.619962)
		(end 409.089352 -20.506182)
		(width 0.089408)
		(layer "In11.Cu")
		(net "FP_NMI_BTN_N")
	)
	(segment
		(start 410.264864 -31.090362)
		(end 410.265118 -31.090108)
		(width 0.089408)
		(layer "In11.Cu")
		(net "FP_NMI_BTN_N")
	)
	(segment
		(start 408.664918 -38.784276)
		(end 408.664664 -38.784022)
		(width 0.089408)
		(layer "In11.Cu")
		(net "FP_NMI_BTN_N")
	)
	(segment
		(start 409.377388 -39.37381)
		(end 409.259278 -39.37381)
		(width 0.089408)
		(layer "In11.Cu")
		(net "FP_NMI_BTN_N")
	)
	(segment
		(start 408.369516 -37.859716)
		(end 408.664918 -37.564314)
		(width 0.089408)
		(layer "In11.Cu")
		(net "FP_NMI_BTN_N")
	)
	(segment
		(start 408.934412 -32.109156)
		(end 408.934666 -32.10941)
		(width 0.089408)
		(layer "In11.Cu")
		(net "FP_NMI_BTN_N")
	)
	(segment
		(start 408.93492 -28.109164)
		(end 408.715464 -27.889708)
		(width 0.089408)
		(layer "In11.Cu")
		(net "FP_NMI_BTN_N")
	)
	(segment
		(start 409.879038 -19.716496)
		(end 411.829504 -19.716496)
		(width 0.089408)
		(layer "In11.Cu")
		(net "FP_NMI_BTN_N")
	)
	(segment
		(start 408.664918 -32.79267)
		(end 408.676094 -32.781494)
		(width 0.089408)
		(layer "In11.Cu")
		(net "FP_NMI_BTN_N")
	)
	(segment
		(start 409.890214 -40.31615)
		(end 409.47848 -39.904416)
		(width 0.089408)
		(layer "In11.Cu")
		(net "FP_NMI_BTN_N")
	)
	(segment
		(start 401.13839 -114.140742)
		(end 400.971258 -113.97361)
		(width 0.0889)
		(layer "F.Cu")
		(net "IRQ_MEZZ_LAN_ALERT_N")
	)
	(segment
		(start 476.4786 -115.2144)
		(end 476.4786 -114.312192)
		(width 0.10795)
		(layer "F.Cu")
		(net "IRQ_MEZZ_LAN_ALERT_N")
	)
	(segment
		(start 401.451826 -114.140742)
		(end 401.13839 -114.140742)
		(width 0.0889)
		(layer "F.Cu")
		(net "IRQ_MEZZ_LAN_ALERT_N")
	)
	(segment
		(start 476.862394 -113.928398)
		(end 477.180402 -113.928398)
		(width 0.10795)
		(layer "F.Cu")
		(net "IRQ_MEZZ_LAN_ALERT_N")
	)
	(segment
		(start 400.971258 -113.97361)
		(end 400.971258 -113.973356)
		(width 0.0889)
		(layer "F.Cu")
		(net "IRQ_MEZZ_LAN_ALERT_N")
	)
	(segment
		(start 404.201376 -114.842036)
		(end 403.62886 -114.26952)
		(width 0.0889)
		(layer "F.Cu")
		(net "IRQ_MEZZ_LAN_ALERT_N")
	)
	(segment
		(start 401.537678 -114.05489)
		(end 401.451826 -114.140742)
		(width 0.0889)
		(layer "F.Cu")
		(net "IRQ_MEZZ_LAN_ALERT_N")
	)
	(segment
		(start 403.62886 -114.26952)
		(end 402.819616 -114.26952)
		(width 0.0889)
		(layer "F.Cu")
		(net "IRQ_MEZZ_LAN_ALERT_N")
	)
	(segment
		(start 477.180402 -113.928398)
		(end 477.400874 -113.707926)
		(width 0.10795)
		(layer "F.Cu")
		(net "IRQ_MEZZ_LAN_ALERT_N")
	)
	(segment
		(start 477.400874 -113.707926)
		(end 477.400874 -112.205516)
		(width 0.10795)
		(layer "F.Cu")
		(net "IRQ_MEZZ_LAN_ALERT_N")
	)
	(segment
		(start 400.852894 -113.854992)
		(end 400.465036 -113.854992)
		(width 0.0889)
		(layer "F.Cu")
		(net "IRQ_MEZZ_LAN_ALERT_N")
	)
	(segment
		(start 402.604986 -114.05489)
		(end 401.537678 -114.05489)
		(width 0.0889)
		(layer "F.Cu")
		(net "IRQ_MEZZ_LAN_ALERT_N")
	)
	(segment
		(start 402.819616 -114.26952)
		(end 402.604986 -114.05489)
		(width 0.0889)
		(layer "F.Cu")
		(net "IRQ_MEZZ_LAN_ALERT_N")
	)
	(segment
		(start 400.971258 -113.973356)
		(end 400.852894 -113.854992)
		(width 0.0889)
		(layer "F.Cu")
		(net "IRQ_MEZZ_LAN_ALERT_N")
	)
	(segment
		(start 476.4786 -114.312192)
		(end 476.862394 -113.928398)
		(width 0.10795)
		(layer "F.Cu")
		(net "IRQ_MEZZ_LAN_ALERT_N")
	)
	(segment
		(start 409.490164 -37.734748)
		(end 409.090114 -38.134798)
		(width 0.10795)
		(layer "F.Cu")
		(net "IRQ_MEZZ_LAN_ALERT_N")
	)
	(via
		(at 404.201376 -114.842036)
		(size 0.508)
		(drill 0.254)
		(layers "F.Cu" "B.Cu")
		(net "IRQ_MEZZ_LAN_ALERT_N")
	)
	(via
		(at 471.155268 -46.14037)
		(size 0.508)
		(drill 0.254)
		(layers "F.Cu" "B.Cu")
		(net "IRQ_MEZZ_LAN_ALERT_N")
	)
	(via
		(at 403.554946 -41.360852)
		(size 0.6604)
		(drill 0.3302)
		(layers "F.Cu" "B.Cu")
		(net "IRQ_MEZZ_LAN_ALERT_N")
	)
	(via
		(at 409.090114 -38.134798)
		(size 0.4572)
		(drill 0.2032)
		(layers "F.Cu" "B.Cu")
		(net "IRQ_MEZZ_LAN_ALERT_N")
	)
	(via
		(at 476.4786 -115.2144)
		(size 0.508)
		(drill 0.254)
		(layers "F.Cu" "B.Cu")
		(net "IRQ_MEZZ_LAN_ALERT_N")
	)
	(via
		(at 400.432524 -36.427664)
		(size 0.508)
		(drill 0.254)
		(layers "F.Cu" "B.Cu")
		(net "IRQ_MEZZ_LAN_ALERT_N")
	)
	(via
		(at 416.502596 -111.629444)
		(size 0.508)
		(drill 0.254)
		(layers "F.Cu" "B.Cu")
		(net "IRQ_MEZZ_LAN_ALERT_N")
	)
	(segment
		(start 397.935196 -25.632664)
		(end 397.935196 -21.169376)
		(width 0.10795)
		(layer "B.Cu")
		(net "IRQ_MEZZ_LAN_ALERT_N")
	)
	(segment
		(start 394.9446 -18.523966)
		(end 394.9446 -15.923006)
		(width 0.10795)
		(layer "B.Cu")
		(net "IRQ_MEZZ_LAN_ALERT_N")
	)
	(segment
		(start 405.730456 -39.2938)
		(end 405.0792 -39.945056)
		(width 0.10795)
		(layer "B.Cu")
		(net "IRQ_MEZZ_LAN_ALERT_N")
	)
	(segment
		(start 405.0792 -40.591232)
		(end 404.30958 -41.360852)
		(width 0.10795)
		(layer "B.Cu")
		(net "IRQ_MEZZ_LAN_ALERT_N")
	)
	(segment
		(start 399.883376 -28.001722)
		(end 399.231358 -27.349704)
		(width 0.10795)
		(layer "B.Cu")
		(net "IRQ_MEZZ_LAN_ALERT_N")
	)
	(segment
		(start 408.509216 -38.134798)
		(end 407.350214 -39.2938)
		(width 0.10795)
		(layer "B.Cu")
		(net "IRQ_MEZZ_LAN_ALERT_N")
	)
	(segment
		(start 399.16989 -33.255204)
		(end 399.16989 -31.839154)
		(width 0.10795)
		(layer "B.Cu")
		(net "IRQ_MEZZ_LAN_ALERT_N")
	)
	(segment
		(start 389.217662 -13.514832)
		(end 389.217662 -14.528292)
		(width 0.10795)
		(layer "B.Cu")
		(net "IRQ_MEZZ_LAN_ALERT_N")
	)
	(segment
		(start 399.300446 -33.38576)
		(end 399.16989 -33.255204)
		(width 0.10795)
		(layer "B.Cu")
		(net "IRQ_MEZZ_LAN_ALERT_N")
	)
	(segment
		(start 399.883376 -28.29052)
		(end 399.883376 -28.001722)
		(width 0.10795)
		(layer "B.Cu")
		(net "IRQ_MEZZ_LAN_ALERT_N")
	)
	(segment
		(start 399.194782 -28.979114)
		(end 399.883376 -28.29052)
		(width 0.10795)
		(layer "B.Cu")
		(net "IRQ_MEZZ_LAN_ALERT_N")
	)
	(segment
		(start 399.300446 -35.295586)
		(end 399.300446 -33.38576)
		(width 0.10795)
		(layer "B.Cu")
		(net "IRQ_MEZZ_LAN_ALERT_N")
	)
	(segment
		(start 403.554946 -41.360852)
		(end 402.361146 -41.360852)
		(width 0.10795)
		(layer "B.Cu")
		(net "IRQ_MEZZ_LAN_ALERT_N")
	)
	(segment
		(start 399.231358 -26.928826)
		(end 397.935196 -25.632664)
		(width 0.10795)
		(layer "B.Cu")
		(net "IRQ_MEZZ_LAN_ALERT_N")
	)
	(segment
		(start 395.64056 -18.87474)
		(end 395.295374 -18.87474)
		(width 0.10795)
		(layer "B.Cu")
		(net "IRQ_MEZZ_LAN_ALERT_N")
	)
	(segment
		(start 391.452862 -14.360144)
		(end 390.487408 -13.39469)
		(width 0.10795)
		(layer "B.Cu")
		(net "IRQ_MEZZ_LAN_ALERT_N")
	)
	(segment
		(start 407.350214 -39.2938)
		(end 405.730456 -39.2938)
		(width 0.10795)
		(layer "B.Cu")
		(net "IRQ_MEZZ_LAN_ALERT_N")
	)
	(segment
		(start 395.295374 -18.87474)
		(end 394.9446 -18.523966)
		(width 0.10795)
		(layer "B.Cu")
		(net "IRQ_MEZZ_LAN_ALERT_N")
	)
	(segment
		(start 399.16989 -31.839154)
		(end 398.596358 -31.265622)
		(width 0.10795)
		(layer "B.Cu")
		(net "IRQ_MEZZ_LAN_ALERT_N")
	)
	(segment
		(start 404.30958 -41.360852)
		(end 403.554946 -41.360852)
		(width 0.10795)
		(layer "B.Cu")
		(net "IRQ_MEZZ_LAN_ALERT_N")
	)
	(segment
		(start 389.337804 -13.39469)
		(end 389.217662 -13.514832)
		(width 0.10795)
		(layer "B.Cu")
		(net "IRQ_MEZZ_LAN_ALERT_N")
	)
	(segment
		(start 398.596358 -31.265622)
		(end 398.596358 -30.30601)
		(width 0.10795)
		(layer "B.Cu")
		(net "IRQ_MEZZ_LAN_ALERT_N")
	)
	(segment
		(start 394.9446 -15.923006)
		(end 393.381738 -14.360144)
		(width 0.10795)
		(layer "B.Cu")
		(net "IRQ_MEZZ_LAN_ALERT_N")
	)
	(segment
		(start 399.194782 -29.707586)
		(end 399.194782 -28.979114)
		(width 0.10795)
		(layer "B.Cu")
		(net "IRQ_MEZZ_LAN_ALERT_N")
	)
	(segment
		(start 393.381738 -14.360144)
		(end 391.452862 -14.360144)
		(width 0.10795)
		(layer "B.Cu")
		(net "IRQ_MEZZ_LAN_ALERT_N")
	)
	(segment
		(start 398.596358 -30.30601)
		(end 399.194782 -29.707586)
		(width 0.10795)
		(layer "B.Cu")
		(net "IRQ_MEZZ_LAN_ALERT_N")
	)
	(segment
		(start 400.432524 -36.427664)
		(end 399.300446 -35.295586)
		(width 0.10795)
		(layer "B.Cu")
		(net "IRQ_MEZZ_LAN_ALERT_N")
	)
	(segment
		(start 409.090114 -38.134798)
		(end 408.509216 -38.134798)
		(width 0.10795)
		(layer "B.Cu")
		(net "IRQ_MEZZ_LAN_ALERT_N")
	)
	(segment
		(start 399.231358 -27.349704)
		(end 399.231358 -26.928826)
		(width 0.10795)
		(layer "B.Cu")
		(net "IRQ_MEZZ_LAN_ALERT_N")
	)
	(segment
		(start 397.935196 -21.169376)
		(end 395.64056 -18.87474)
		(width 0.10795)
		(layer "B.Cu")
		(net "IRQ_MEZZ_LAN_ALERT_N")
	)
	(segment
		(start 390.487408 -13.39469)
		(end 389.337804 -13.39469)
		(width 0.10795)
		(layer "B.Cu")
		(net "IRQ_MEZZ_LAN_ALERT_N")
	)
	(segment
		(start 405.0792 -39.945056)
		(end 405.0792 -40.591232)
		(width 0.10795)
		(layer "B.Cu")
		(net "IRQ_MEZZ_LAN_ALERT_N")
	)
	(segment
		(start 427.361604 -117.136926)
		(end 427.01464 -116.789962)
		(width 0.089408)
		(layer "In2.Cu")
		(net "IRQ_MEZZ_LAN_ALERT_N")
	)
	(segment
		(start 430.578514 -118.493032)
		(end 429.222408 -117.136926)
		(width 0.089408)
		(layer "In2.Cu")
		(net "IRQ_MEZZ_LAN_ALERT_N")
	)
	(segment
		(start 476.4786 -115.2144)
		(end 476.172784 -114.908584)
		(width 0.089408)
		(layer "In2.Cu")
		(net "IRQ_MEZZ_LAN_ALERT_N")
	)
	(segment
		(start 424.86326 -116.271548)
		(end 423.019728 -116.271548)
		(width 0.089408)
		(layer "In2.Cu")
		(net "IRQ_MEZZ_LAN_ALERT_N")
	)
	(segment
		(start 427.01464 -116.789962)
		(end 426.109384 -116.789962)
		(width 0.089408)
		(layer "In2.Cu")
		(net "IRQ_MEZZ_LAN_ALERT_N")
	)
	(segment
		(start 425.548552 -116.95684)
		(end 424.86326 -116.271548)
		(width 0.089408)
		(layer "In2.Cu")
		(net "IRQ_MEZZ_LAN_ALERT_N")
	)
	(segment
		(start 418.727382 -117.037866)
		(end 417.225226 -115.53571)
		(width 0.089408)
		(layer "In2.Cu")
		(net "IRQ_MEZZ_LAN_ALERT_N")
	)
	(segment
		(start 417.225226 -115.53571)
		(end 417.225226 -112.352074)
		(width 0.089408)
		(layer "In2.Cu")
		(net "IRQ_MEZZ_LAN_ALERT_N")
	)
	(segment
		(start 476.172784 -114.908584)
		(end 476.172784 -113.613946)
		(width 0.089408)
		(layer "In2.Cu")
		(net "IRQ_MEZZ_LAN_ALERT_N")
	)
	(segment
		(start 426.109384 -116.789962)
		(end 425.942506 -116.95684)
		(width 0.089408)
		(layer "In2.Cu")
		(net "IRQ_MEZZ_LAN_ALERT_N")
	)
	(segment
		(start 425.942506 -116.95684)
		(end 425.548552 -116.95684)
		(width 0.089408)
		(layer "In2.Cu")
		(net "IRQ_MEZZ_LAN_ALERT_N")
	)
	(segment
		(start 432.858164 -118.493032)
		(end 430.578514 -118.493032)
		(width 0.089408)
		(layer "In2.Cu")
		(net "IRQ_MEZZ_LAN_ALERT_N")
	)
	(segment
		(start 437.599582 -113.751614)
		(end 432.858164 -118.493032)
		(width 0.089408)
		(layer "In2.Cu")
		(net "IRQ_MEZZ_LAN_ALERT_N")
	)
	(segment
		(start 440.533536 -112.957864)
		(end 439.739786 -113.751614)
		(width 0.089408)
		(layer "In2.Cu")
		(net "IRQ_MEZZ_LAN_ALERT_N")
	)
	(segment
		(start 476.172784 -113.613946)
		(end 475.516702 -112.957864)
		(width 0.089408)
		(layer "In2.Cu")
		(net "IRQ_MEZZ_LAN_ALERT_N")
	)
	(segment
		(start 417.225226 -112.352074)
		(end 416.502596 -111.629444)
		(width 0.089408)
		(layer "In2.Cu")
		(net "IRQ_MEZZ_LAN_ALERT_N")
	)
	(segment
		(start 475.516702 -112.957864)
		(end 440.533536 -112.957864)
		(width 0.089408)
		(layer "In2.Cu")
		(net "IRQ_MEZZ_LAN_ALERT_N")
	)
	(segment
		(start 423.019728 -116.271548)
		(end 422.25341 -117.037866)
		(width 0.089408)
		(layer "In2.Cu")
		(net "IRQ_MEZZ_LAN_ALERT_N")
	)
	(segment
		(start 422.25341 -117.037866)
		(end 418.727382 -117.037866)
		(width 0.089408)
		(layer "In2.Cu")
		(net "IRQ_MEZZ_LAN_ALERT_N")
	)
	(segment
		(start 429.222408 -117.136926)
		(end 427.361604 -117.136926)
		(width 0.089408)
		(layer "In2.Cu")
		(net "IRQ_MEZZ_LAN_ALERT_N")
	)
	(segment
		(start 439.739786 -113.751614)
		(end 437.599582 -113.751614)
		(width 0.089408)
		(layer "In2.Cu")
		(net "IRQ_MEZZ_LAN_ALERT_N")
	)
	(segment
		(start 408.52598 -38.134798)
		(end 409.090114 -38.134798)
		(width 0.089408)
		(layer "In4.Cu")
		(net "IRQ_MEZZ_LAN_ALERT_N")
	)
	(segment
		(start 404.5966 -38.1762)
		(end 405.478234 -38.1762)
		(width 0.089408)
		(layer "In4.Cu")
		(net "IRQ_MEZZ_LAN_ALERT_N")
	)
	(segment
		(start 405.478234 -38.1762)
		(end 406.319228 -39.017194)
		(width 0.089408)
		(layer "In4.Cu")
		(net "IRQ_MEZZ_LAN_ALERT_N")
	)
	(segment
		(start 402.848064 -36.427664)
		(end 404.5966 -38.1762)
		(width 0.089408)
		(layer "In4.Cu")
		(net "IRQ_MEZZ_LAN_ALERT_N")
	)
	(segment
		(start 406.319228 -39.017194)
		(end 407.643584 -39.017194)
		(width 0.089408)
		(layer "In4.Cu")
		(net "IRQ_MEZZ_LAN_ALERT_N")
	)
	(segment
		(start 407.643584 -39.017194)
		(end 408.52598 -38.134798)
		(width 0.089408)
		(layer "In4.Cu")
		(net "IRQ_MEZZ_LAN_ALERT_N")
	)
	(segment
		(start 400.432524 -36.427664)
		(end 402.848064 -36.427664)
		(width 0.089408)
		(layer "In4.Cu")
		(net "IRQ_MEZZ_LAN_ALERT_N")
	)
	(segment
		(start 436.291736 -63.654432)
		(end 435.795674 -63.15837)
		(width 0.089408)
		(layer "In9.Cu")
		(net "IRQ_MEZZ_LAN_ALERT_N")
	)
	(segment
		(start 416.896804 -113.353596)
		(end 416.698684 -113.551716)
		(width 0.089408)
		(layer "In9.Cu")
		(net "IRQ_MEZZ_LAN_ALERT_N")
	)
	(segment
		(start 426.852842 -60.095638)
		(end 426.496988 -60.451492)
		(width 0.089408)
		(layer "In9.Cu")
		(net "IRQ_MEZZ_LAN_ALERT_N")
	)
	(segment
		(start 471.006424 -53.58257)
		(end 471.006424 -54.550818)
		(width 0.089408)
		(layer "In9.Cu")
		(net "IRQ_MEZZ_LAN_ALERT_N")
	)
	(segment
		(start 410.085794 -113.600738)
		(end 409.620466 -114.066066)
		(width 0.089408)
		(layer "In9.Cu")
		(net "IRQ_MEZZ_LAN_ALERT_N")
	)
	(segment
		(start 423.242486 -60.451492)
		(end 421.372792 -62.321186)
		(width 0.089408)
		(layer "In9.Cu")
		(net "IRQ_MEZZ_LAN_ALERT_N")
	)
	(segment
		(start 410.085794 -112.738154)
		(end 410.085794 -113.600738)
		(width 0.089408)
		(layer "In9.Cu")
		(net "IRQ_MEZZ_LAN_ALERT_N")
	)
	(segment
		(start 430.792636 -63.148718)
		(end 427.739556 -60.095638)
		(width 0.089408)
		(layer "In9.Cu")
		(net "IRQ_MEZZ_LAN_ALERT_N")
	)
	(segment
		(start 470.154 -49.15789)
		(end 470.154 -52.730146)
		(width 0.089408)
		(layer "In9.Cu")
		(net "IRQ_MEZZ_LAN_ALERT_N")
	)
	(segment
		(start 416.502596 -111.629444)
		(end 416.896804 -112.023652)
		(width 0.089408)
		(layer "In9.Cu")
		(net "IRQ_MEZZ_LAN_ALERT_N")
	)
	(segment
		(start 462.538064 -64.09944)
		(end 440.509914 -64.09944)
		(width 0.089408)
		(layer "In9.Cu")
		(net "IRQ_MEZZ_LAN_ALERT_N")
	)
	(segment
		(start 463.569812 -62.484254)
		(end 462.751678 -63.302388)
		(width 0.089408)
		(layer "In9.Cu")
		(net "IRQ_MEZZ_LAN_ALERT_N")
	)
	(segment
		(start 416.896804 -112.023652)
		(end 416.896804 -113.353596)
		(width 0.089408)
		(layer "In9.Cu")
		(net "IRQ_MEZZ_LAN_ALERT_N")
	)
	(segment
		(start 435.742842 -63.15837)
		(end 435.73319 -63.148718)
		(width 0.089408)
		(layer "In9.Cu")
		(net "IRQ_MEZZ_LAN_ALERT_N")
	)
	(segment
		(start 421.372792 -62.321186)
		(end 421.372792 -63.603378)
		(width 0.089408)
		(layer "In9.Cu")
		(net "IRQ_MEZZ_LAN_ALERT_N")
	)
	(segment
		(start 437.057546 -63.403226)
		(end 436.80634 -63.654432)
		(width 0.089408)
		(layer "In9.Cu")
		(net "IRQ_MEZZ_LAN_ALERT_N")
	)
	(segment
		(start 471.155268 -46.25467)
		(end 470.535 -46.874938)
		(width 0.089408)
		(layer "In9.Cu")
		(net "IRQ_MEZZ_LAN_ALERT_N")
	)
	(segment
		(start 409.620466 -114.066066)
		(end 404.977346 -114.066066)
		(width 0.089408)
		(layer "In9.Cu")
		(net "IRQ_MEZZ_LAN_ALERT_N")
	)
	(segment
		(start 417.161472 -110.970568)
		(end 416.502596 -111.629444)
		(width 0.089408)
		(layer "In9.Cu")
		(net "IRQ_MEZZ_LAN_ALERT_N")
	)
	(segment
		(start 435.73319 -63.148718)
		(end 430.792636 -63.148718)
		(width 0.089408)
		(layer "In9.Cu")
		(net "IRQ_MEZZ_LAN_ALERT_N")
	)
	(segment
		(start 462.751678 -63.302388)
		(end 462.751678 -63.885826)
		(width 0.089408)
		(layer "In9.Cu")
		(net "IRQ_MEZZ_LAN_ALERT_N")
	)
	(segment
		(start 420.778432 -78.177644)
		(end 420.778432 -78.335632)
		(width 0.089408)
		(layer "In9.Cu")
		(net "IRQ_MEZZ_LAN_ALERT_N")
	)
	(segment
		(start 436.80634 -63.654432)
		(end 436.291736 -63.654432)
		(width 0.089408)
		(layer "In9.Cu")
		(net "IRQ_MEZZ_LAN_ALERT_N")
	)
	(segment
		(start 414.054036 -111.486696)
		(end 411.337252 -111.486696)
		(width 0.089408)
		(layer "In9.Cu")
		(net "IRQ_MEZZ_LAN_ALERT_N")
	)
	(segment
		(start 467.79815 -61.698378)
		(end 467.79815 -62.249812)
		(width 0.089408)
		(layer "In9.Cu")
		(net "IRQ_MEZZ_LAN_ALERT_N")
	)
	(segment
		(start 470.877138 -58.989214)
		(end 468.54999 -61.316362)
		(width 0.089408)
		(layer "In9.Cu")
		(net "IRQ_MEZZ_LAN_ALERT_N")
	)
	(segment
		(start 418.40277 -95.692976)
		(end 417.874958 -95.692976)
		(width 0.089408)
		(layer "In9.Cu")
		(net "IRQ_MEZZ_LAN_ALERT_N")
	)
	(segment
		(start 420.778686 -93.31706)
		(end 418.40277 -95.692976)
		(width 0.089408)
		(layer "In9.Cu")
		(net "IRQ_MEZZ_LAN_ALERT_N")
	)
	(segment
		(start 417.874958 -95.692976)
		(end 415.806636 -97.761298)
		(width 0.089408)
		(layer "In9.Cu")
		(net "IRQ_MEZZ_LAN_ALERT_N")
	)
	(segment
		(start 421.64127 -77.314806)
		(end 420.778432 -78.177644)
		(width 0.089408)
		(layer "In9.Cu")
		(net "IRQ_MEZZ_LAN_ALERT_N")
	)
	(segment
		(start 415.806636 -106.957114)
		(end 417.161472 -108.31195)
		(width 0.089408)
		(layer "In9.Cu")
		(net "IRQ_MEZZ_LAN_ALERT_N")
	)
	(segment
		(start 437.306974 -63.154306)
		(end 437.058054 -63.403226)
		(width 0.089408)
		(layer "In9.Cu")
		(net "IRQ_MEZZ_LAN_ALERT_N")
	)
	(segment
		(start 420.778432 -78.335632)
		(end 420.778686 -78.335886)
		(width 0.089408)
		(layer "In9.Cu")
		(net "IRQ_MEZZ_LAN_ALERT_N")
	)
	(segment
		(start 420.778686 -78.335886)
		(end 420.778686 -93.31706)
		(width 0.089408)
		(layer "In9.Cu")
		(net "IRQ_MEZZ_LAN_ALERT_N")
	)
	(segment
		(start 440.509914 -64.09944)
		(end 439.56478 -63.154306)
		(width 0.089408)
		(layer "In9.Cu")
		(net "IRQ_MEZZ_LAN_ALERT_N")
	)
	(segment
		(start 470.535 -46.874938)
		(end 470.535 -48.77689)
		(width 0.089408)
		(layer "In9.Cu")
		(net "IRQ_MEZZ_LAN_ALERT_N")
	)
	(segment
		(start 470.877138 -54.680104)
		(end 470.877138 -58.989214)
		(width 0.089408)
		(layer "In9.Cu")
		(net "IRQ_MEZZ_LAN_ALERT_N")
	)
	(segment
		(start 404.977346 -114.066066)
		(end 404.201376 -114.842036)
		(width 0.089408)
		(layer "In9.Cu")
		(net "IRQ_MEZZ_LAN_ALERT_N")
	)
	(segment
		(start 471.006424 -54.550818)
		(end 470.877138 -54.680104)
		(width 0.089408)
		(layer "In9.Cu")
		(net "IRQ_MEZZ_LAN_ALERT_N")
	)
	(segment
		(start 439.56478 -63.154306)
		(end 437.306974 -63.154306)
		(width 0.089408)
		(layer "In9.Cu")
		(net "IRQ_MEZZ_LAN_ALERT_N")
	)
	(segment
		(start 426.496988 -60.451492)
		(end 423.242486 -60.451492)
		(width 0.089408)
		(layer "In9.Cu")
		(net "IRQ_MEZZ_LAN_ALERT_N")
	)
	(segment
		(start 427.739556 -60.095638)
		(end 426.852842 -60.095638)
		(width 0.089408)
		(layer "In9.Cu")
		(net "IRQ_MEZZ_LAN_ALERT_N")
	)
	(segment
		(start 470.154 -52.730146)
		(end 471.006424 -53.58257)
		(width 0.089408)
		(layer "In9.Cu")
		(net "IRQ_MEZZ_LAN_ALERT_N")
	)
	(segment
		(start 467.79815 -62.249812)
		(end 467.563708 -62.484254)
		(width 0.089408)
		(layer "In9.Cu")
		(net "IRQ_MEZZ_LAN_ALERT_N")
	)
	(segment
		(start 471.155268 -46.14037)
		(end 471.155268 -46.25467)
		(width 0.089408)
		(layer "In9.Cu")
		(net "IRQ_MEZZ_LAN_ALERT_N")
	)
	(segment
		(start 462.751678 -63.885826)
		(end 462.538064 -64.09944)
		(width 0.089408)
		(layer "In9.Cu")
		(net "IRQ_MEZZ_LAN_ALERT_N")
	)
	(segment
		(start 468.180166 -61.316362)
		(end 467.79815 -61.698378)
		(width 0.089408)
		(layer "In9.Cu")
		(net "IRQ_MEZZ_LAN_ALERT_N")
	)
	(segment
		(start 467.563708 -62.484254)
		(end 463.569812 -62.484254)
		(width 0.089408)
		(layer "In9.Cu")
		(net "IRQ_MEZZ_LAN_ALERT_N")
	)
	(segment
		(start 470.535 -48.77689)
		(end 470.154 -49.15789)
		(width 0.089408)
		(layer "In9.Cu")
		(net "IRQ_MEZZ_LAN_ALERT_N")
	)
	(segment
		(start 416.698684 -113.551716)
		(end 416.119056 -113.551716)
		(width 0.089408)
		(layer "In9.Cu")
		(net "IRQ_MEZZ_LAN_ALERT_N")
	)
	(segment
		(start 435.795674 -63.15837)
		(end 435.742842 -63.15837)
		(width 0.089408)
		(layer "In9.Cu")
		(net "IRQ_MEZZ_LAN_ALERT_N")
	)
	(segment
		(start 468.54999 -61.316362)
		(end 468.180166 -61.316362)
		(width 0.089408)
		(layer "In9.Cu")
		(net "IRQ_MEZZ_LAN_ALERT_N")
	)
	(segment
		(start 421.372792 -63.603378)
		(end 421.64127 -63.871856)
		(width 0.089408)
		(layer "In9.Cu")
		(net "IRQ_MEZZ_LAN_ALERT_N")
	)
	(segment
		(start 421.64127 -63.871856)
		(end 421.64127 -77.314806)
		(width 0.089408)
		(layer "In9.Cu")
		(net "IRQ_MEZZ_LAN_ALERT_N")
	)
	(segment
		(start 417.161472 -108.31195)
		(end 417.161472 -110.970568)
		(width 0.089408)
		(layer "In9.Cu")
		(net "IRQ_MEZZ_LAN_ALERT_N")
	)
	(segment
		(start 416.119056 -113.551716)
		(end 414.054036 -111.486696)
		(width 0.089408)
		(layer "In9.Cu")
		(net "IRQ_MEZZ_LAN_ALERT_N")
	)
	(segment
		(start 437.058054 -63.403226)
		(end 437.057546 -63.403226)
		(width 0.089408)
		(layer "In9.Cu")
		(net "IRQ_MEZZ_LAN_ALERT_N")
	)
	(segment
		(start 411.337252 -111.486696)
		(end 410.085794 -112.738154)
		(width 0.089408)
		(layer "In9.Cu")
		(net "IRQ_MEZZ_LAN_ALERT_N")
	)
	(segment
		(start 415.806636 -97.761298)
		(end 415.806636 -106.957114)
		(width 0.089408)
		(layer "In9.Cu")
		(net "IRQ_MEZZ_LAN_ALERT_N")
	)
	(segment
		(start 409.313634 -38.134798)
		(end 409.090114 -38.134798)
		(width 0.089408)
		(layer "In11.Cu")
		(net "IRQ_MEZZ_LAN_ALERT_N")
	)
	(segment
		(start 448.759834 -37.895784)
		(end 447.090038 -39.56558)
		(width 0.089408)
		(layer "In11.Cu")
		(net "IRQ_MEZZ_LAN_ALERT_N")
	)
	(segment
		(start 447.090038 -39.56558)
		(end 444.663322 -39.56558)
		(width 0.089408)
		(layer "In11.Cu")
		(net "IRQ_MEZZ_LAN_ALERT_N")
	)
	(segment
		(start 444.15329 -39.813738)
		(end 444.142622 -39.824406)
		(width 0.089408)
		(layer "In11.Cu")
		(net "IRQ_MEZZ_LAN_ALERT_N")
	)
	(segment
		(start 464.27644 -40.10152)
		(end 462.900776 -38.725856)
		(width 0.089408)
		(layer "In11.Cu")
		(net "IRQ_MEZZ_LAN_ALERT_N")
	)
	(segment
		(start 471.155268 -46.14037)
		(end 470.489534 -46.14037)
		(width 0.089408)
		(layer "In11.Cu")
		(net "IRQ_MEZZ_LAN_ALERT_N")
	)
	(segment
		(start 434.406548 -39.724838)
		(end 430.358296 -39.724838)
		(width 0.089408)
		(layer "In11.Cu")
		(net "IRQ_MEZZ_LAN_ALERT_N")
	)
	(segment
		(start 467.683342 -43.334178)
		(end 467.683342 -41.882314)
		(width 0.089408)
		(layer "In11.Cu")
		(net "IRQ_MEZZ_LAN_ALERT_N")
	)
	(segment
		(start 444.485268 -39.743634)
		(end 444.223648 -39.743634)
		(width 0.089408)
		(layer "In11.Cu")
		(net "IRQ_MEZZ_LAN_ALERT_N")
	)
	(segment
		(start 419.241986 -37.75456)
		(end 419.071044 -37.583618)
		(width 0.089408)
		(layer "In11.Cu")
		(net "IRQ_MEZZ_LAN_ALERT_N")
	)
	(segment
		(start 462.118456 -38.725856)
		(end 461.678528 -38.725856)
		(width 0.089408)
		(layer "In11.Cu")
		(net "IRQ_MEZZ_LAN_ALERT_N")
	)
	(segment
		(start 444.223648 -39.743634)
		(end 444.153544 -39.813738)
		(width 0.089408)
		(layer "In11.Cu")
		(net "IRQ_MEZZ_LAN_ALERT_N")
	)
	(segment
		(start 456.566016 -39.30777)
		(end 455.15403 -37.895784)
		(width 0.089408)
		(layer "In11.Cu")
		(net "IRQ_MEZZ_LAN_ALERT_N")
	)
	(segment
		(start 444.142622 -39.824406)
		(end 434.506116 -39.824406)
		(width 0.089408)
		(layer "In11.Cu")
		(net "IRQ_MEZZ_LAN_ALERT_N")
	)
	(segment
		(start 458.011022 -39.30777)
		(end 456.566016 -39.30777)
		(width 0.089408)
		(layer "In11.Cu")
		(net "IRQ_MEZZ_LAN_ALERT_N")
	)
	(segment
		(start 426.657516 -39.37127)
		(end 426.648372 -39.362126)
		(width 0.089408)
		(layer "In11.Cu")
		(net "IRQ_MEZZ_LAN_ALERT_N")
	)
	(segment
		(start 419.071044 -37.583618)
		(end 415.638488 -37.583618)
		(width 0.089408)
		(layer "In11.Cu")
		(net "IRQ_MEZZ_LAN_ALERT_N")
	)
	(segment
		(start 444.663322 -39.56558)
		(end 444.485268 -39.743634)
		(width 0.089408)
		(layer "In11.Cu")
		(net "IRQ_MEZZ_LAN_ALERT_N")
	)
	(segment
		(start 466.519514 -40.718486)
		(end 466.517228 -40.718486)
		(width 0.089408)
		(layer "In11.Cu")
		(net "IRQ_MEZZ_LAN_ALERT_N")
	)
	(segment
		(start 409.697682 -37.75075)
		(end 409.313634 -38.134798)
		(width 0.089408)
		(layer "In11.Cu")
		(net "IRQ_MEZZ_LAN_ALERT_N")
	)
	(segment
		(start 462.120234 -38.724078)
		(end 462.118456 -38.725856)
		(width 0.089408)
		(layer "In11.Cu")
		(net "IRQ_MEZZ_LAN_ALERT_N")
	)
	(segment
		(start 455.15403 -37.895784)
		(end 448.759834 -37.895784)
		(width 0.089408)
		(layer "In11.Cu")
		(net "IRQ_MEZZ_LAN_ALERT_N")
	)
	(segment
		(start 461.67675 -38.724078)
		(end 461.028034 -38.724078)
		(width 0.089408)
		(layer "In11.Cu")
		(net "IRQ_MEZZ_LAN_ALERT_N")
	)
	(segment
		(start 458.592936 -38.725856)
		(end 458.011022 -39.30777)
		(width 0.089408)
		(layer "In11.Cu")
		(net "IRQ_MEZZ_LAN_ALERT_N")
	)
	(segment
		(start 462.76895 -38.724078)
		(end 462.120234 -38.724078)
		(width 0.089408)
		(layer "In11.Cu")
		(net "IRQ_MEZZ_LAN_ALERT_N")
	)
	(segment
		(start 461.026256 -38.725856)
		(end 458.592936 -38.725856)
		(width 0.089408)
		(layer "In11.Cu")
		(net "IRQ_MEZZ_LAN_ALERT_N")
	)
	(segment
		(start 466.517228 -40.718486)
		(end 465.900262 -40.10152)
		(width 0.089408)
		(layer "In11.Cu")
		(net "IRQ_MEZZ_LAN_ALERT_N")
	)
	(segment
		(start 461.678528 -38.725856)
		(end 461.67675 -38.724078)
		(width 0.089408)
		(layer "In11.Cu")
		(net "IRQ_MEZZ_LAN_ALERT_N")
	)
	(segment
		(start 430.004728 -39.37127)
		(end 426.657516 -39.37127)
		(width 0.089408)
		(layer "In11.Cu")
		(net "IRQ_MEZZ_LAN_ALERT_N")
	)
	(segment
		(start 426.648372 -39.362126)
		(end 426.573442 -39.362126)
		(width 0.089408)
		(layer "In11.Cu")
		(net "IRQ_MEZZ_LAN_ALERT_N")
	)
	(segment
		(start 461.028034 -38.724078)
		(end 461.026256 -38.725856)
		(width 0.089408)
		(layer "In11.Cu")
		(net "IRQ_MEZZ_LAN_ALERT_N")
	)
	(segment
		(start 424.965876 -37.75456)
		(end 419.241986 -37.75456)
		(width 0.089408)
		(layer "In11.Cu")
		(net "IRQ_MEZZ_LAN_ALERT_N")
	)
	(segment
		(start 444.153544 -39.813738)
		(end 444.15329 -39.813738)
		(width 0.089408)
		(layer "In11.Cu")
		(net "IRQ_MEZZ_LAN_ALERT_N")
	)
	(segment
		(start 462.900776 -38.725856)
		(end 462.770728 -38.725856)
		(width 0.089408)
		(layer "In11.Cu")
		(net "IRQ_MEZZ_LAN_ALERT_N")
	)
	(segment
		(start 430.358296 -39.724838)
		(end 430.004728 -39.37127)
		(width 0.089408)
		(layer "In11.Cu")
		(net "IRQ_MEZZ_LAN_ALERT_N")
	)
	(segment
		(start 470.489534 -46.14037)
		(end 467.683342 -43.334178)
		(width 0.089408)
		(layer "In11.Cu")
		(net "IRQ_MEZZ_LAN_ALERT_N")
	)
	(segment
		(start 462.770728 -38.725856)
		(end 462.76895 -38.724078)
		(width 0.089408)
		(layer "In11.Cu")
		(net "IRQ_MEZZ_LAN_ALERT_N")
	)
	(segment
		(start 426.573442 -39.362126)
		(end 424.965876 -37.75456)
		(width 0.089408)
		(layer "In11.Cu")
		(net "IRQ_MEZZ_LAN_ALERT_N")
	)
	(segment
		(start 465.900262 -40.10152)
		(end 464.27644 -40.10152)
		(width 0.089408)
		(layer "In11.Cu")
		(net "IRQ_MEZZ_LAN_ALERT_N")
	)
	(segment
		(start 434.506116 -39.824406)
		(end 434.406548 -39.724838)
		(width 0.089408)
		(layer "In11.Cu")
		(net "IRQ_MEZZ_LAN_ALERT_N")
	)
	(segment
		(start 415.471356 -37.75075)
		(end 409.697682 -37.75075)
		(width 0.089408)
		(layer "In11.Cu")
		(net "IRQ_MEZZ_LAN_ALERT_N")
	)
	(segment
		(start 415.638488 -37.583618)
		(end 415.471356 -37.75075)
		(width 0.089408)
		(layer "In11.Cu")
		(net "IRQ_MEZZ_LAN_ALERT_N")
	)
	(segment
		(start 467.683342 -41.882314)
		(end 466.519514 -40.718486)
		(width 0.089408)
		(layer "In11.Cu")
		(net "IRQ_MEZZ_LAN_ALERT_N")
	)
	(via
		(at 329.44054 -5.46354)
		(size 0.6604)
		(drill 0.3302)
		(layers "F.Cu" "B.Cu")
		(net "FM_DIMM_EVENT_FET")
	)
	(segment
		(start 329.770486 -5.46354)
		(end 329.44054 -5.46354)
		(width 0.10795)
		(layer "B.Cu")
		(net "FM_DIMM_EVENT_FET")
	)
	(segment
		(start 329.44054 -5.46354)
		(end 329.41514 -5.48894)
		(width 0.10795)
		(layer "B.Cu")
		(net "FM_DIMM_EVENT_FET")
	)
	(segment
		(start 329.41514 -5.48894)
		(end 329.41514 -7.47014)
		(width 0.10795)
		(layer "B.Cu")
		(net "FM_DIMM_EVENT_FET")
	)
	(segment
		(start 330.581 -5.969)
		(end 330.275946 -5.969)
		(width 0.10795)
		(layer "B.Cu")
		(net "FM_DIMM_EVENT_FET")
	)
	(segment
		(start 330.3524 -7.493)
		(end 329.438 -7.493)
		(width 0.10795)
		(layer "B.Cu")
		(net "FM_DIMM_EVENT_FET")
	)
	(segment
		(start 331.15504 -7.3406)
		(end 330.5048 -7.3406)
		(width 0.10795)
		(layer "B.Cu")
		(net "FM_DIMM_EVENT_FET")
	)
	(segment
		(start 329.41514 -7.47014)
		(end 329.438 -7.493)
		(width 0.10795)
		(layer "B.Cu")
		(net "FM_DIMM_EVENT_FET")
	)
	(segment
		(start 330.275946 -5.969)
		(end 329.770486 -5.46354)
		(width 0.10795)
		(layer "B.Cu")
		(net "FM_DIMM_EVENT_FET")
	)
	(segment
		(start 330.5048 -7.3406)
		(end 330.3524 -7.493)
		(width 0.10795)
		(layer "B.Cu")
		(net "FM_DIMM_EVENT_FET")
	)
	(segment
		(start 153.664158 -27.9908)
		(end 154.305 -27.9908)
		(width 0.127)
		(layer "F.Cu")
		(net "CLK_322M_OSC_CPU1_RC_DP")
	)
	(segment
		(start 119.929402 -65.810384)
		(end 119.357902 -65.810384)
		(width 0.127)
		(layer "F.Cu")
		(net "CLK_322M_OSC_CPU1_RC_DP")
	)
	(via
		(at 119.357902 -65.810384)
		(size 0.508)
		(drill 0.254)
		(layers "F.Cu" "B.Cu")
		(net "CLK_322M_OSC_CPU1_RC_DP")
	)
	(via
		(at 153.664158 -27.9908)
		(size 0.508)
		(drill 0.254)
		(layers "F.Cu" "B.Cu")
		(net "CLK_322M_OSC_CPU1_RC_DP")
	)
	(segment
		(start 127.383794 -62.248034)
		(end 127.351028 -62.248034)
		(width 0.0889)
		(layer "In2.Cu")
		(net "CLK_322M_OSC_CPU1_RC_DP")
	)
	(segment
		(start 153.664158 -27.9908)
		(end 153.664158 -28.707842)
		(width 0.1143)
		(layer "In2.Cu")
		(net "CLK_322M_OSC_CPU1_RC_DP")
	)
	(segment
		(start 131.149598 -56.695086)
		(end 131.154424 -56.703722)
		(width 0.0889)
		(layer "In2.Cu")
		(net "CLK_322M_OSC_CPU1_RC_DP")
	)
	(segment
		(start 129.955544 -60.762388)
		(end 129.922778 -60.762388)
		(width 0.0889)
		(layer "In2.Cu")
		(net "CLK_322M_OSC_CPU1_RC_DP")
	)
	(segment
		(start 131.661408 -55.809388)
		(end 131.639818 -55.809388)
		(width 0.0889)
		(layer "In2.Cu")
		(net "CLK_322M_OSC_CPU1_RC_DP")
	)
	(segment
		(start 120.227344 -65.715388)
		(end 120.191276 -65.715388)
		(width 0.0889)
		(layer "In2.Cu")
		(net "CLK_322M_OSC_CPU1_RC_DP")
	)
	(segment
		(start 124.975366 -63.238634)
		(end 124.4092 -63.8048)
		(width 0.0889)
		(layer "In2.Cu")
		(net "CLK_322M_OSC_CPU1_RC_DP")
	)
	(segment
		(start 121.092468 -65.219834)
		(end 121.056908 -65.219834)
		(width 0.0889)
		(layer "In2.Cu")
		(net "CLK_322M_OSC_CPU1_RC_DP")
	)
	(segment
		(start 139.822174 -51.572922)
		(end 139.52982 -51.572922)
		(width 0.1143)
		(layer "In2.Cu")
		(net "CLK_322M_OSC_CPU1_RC_DP")
	)
	(segment
		(start 131.149598 -57.685686)
		(end 131.154424 -57.694322)
		(width 0.0889)
		(layer "In2.Cu")
		(net "CLK_322M_OSC_CPU1_RC_DP")
	)
	(segment
		(start 119.740172 -65.955164)
		(end 119.650764 -65.979294)
		(width 0.0889)
		(layer "In2.Cu")
		(net "CLK_322M_OSC_CPU1_RC_DP")
	)
	(segment
		(start 135.11022 -53.827934)
		(end 135.077454 -53.827934)
		(width 0.0889)
		(layer "In2.Cu")
		(net "CLK_322M_OSC_CPU1_RC_DP")
	)
	(segment
		(start 133.39318 -54.818534)
		(end 133.360414 -54.818534)
		(width 0.0889)
		(layer "In2.Cu")
		(net "CLK_322M_OSC_CPU1_RC_DP")
	)
	(segment
		(start 119.650764 -65.979294)
		(end 119.357902 -65.810384)
		(width 0.0889)
		(layer "In2.Cu")
		(net "CLK_322M_OSC_CPU1_RC_DP")
	)
	(segment
		(start 131.149598 -59.666886)
		(end 131.154424 -59.675522)
		(width 0.0889)
		(layer "In2.Cu")
		(net "CLK_322M_OSC_CPU1_RC_DP")
	)
	(segment
		(start 138.047222 -51.623722)
		(end 137.330434 -52.340002)
		(width 0.0889)
		(layer "In2.Cu")
		(net "CLK_322M_OSC_CPU1_RC_DP")
	)
	(segment
		(start 139.507722 -51.572922)
		(end 139.456922 -51.623722)
		(width 0.0889)
		(layer "In2.Cu")
		(net "CLK_322M_OSC_CPU1_RC_DP")
	)
	(segment
		(start 134.24789 -54.323488)
		(end 134.215124 -54.323488)
		(width 0.0889)
		(layer "In2.Cu")
		(net "CLK_322M_OSC_CPU1_RC_DP")
	)
	(segment
		(start 131.143248 -56.684418)
		(end 131.149598 -56.695086)
		(width 0.0889)
		(layer "In2.Cu")
		(net "CLK_322M_OSC_CPU1_RC_DP")
	)
	(segment
		(start 124.4092 -64.2874)
		(end 123.971812 -64.724788)
		(width 0.0889)
		(layer "In2.Cu")
		(net "CLK_322M_OSC_CPU1_RC_DP")
	)
	(segment
		(start 135.96493 -53.332634)
		(end 135.9408 -53.332634)
		(width 0.0889)
		(layer "In2.Cu")
		(net "CLK_322M_OSC_CPU1_RC_DP")
	)
	(segment
		(start 126.521464 -62.743588)
		(end 126.488698 -62.743588)
		(width 0.0889)
		(layer "In2.Cu")
		(net "CLK_322M_OSC_CPU1_RC_DP")
	)
	(segment
		(start 131.143248 -57.675018)
		(end 131.149598 -57.685686)
		(width 0.0889)
		(layer "In2.Cu")
		(net "CLK_322M_OSC_CPU1_RC_DP")
	)
	(segment
		(start 137.330434 -52.340002)
		(end 137.158984 -52.637436)
		(width 0.0889)
		(layer "In2.Cu")
		(net "CLK_322M_OSC_CPU1_RC_DP")
	)
	(segment
		(start 139.52982 -51.572922)
		(end 139.507722 -51.572922)
		(width 0.0889)
		(layer "In2.Cu")
		(net "CLK_322M_OSC_CPU1_RC_DP")
	)
	(segment
		(start 153.233628 -29.138372)
		(end 152.7175 -29.138372)
		(width 0.1143)
		(layer "In2.Cu")
		(net "CLK_322M_OSC_CPU1_RC_DP")
	)
	(segment
		(start 132.53466 -55.313834)
		(end 132.501894 -55.313834)
		(width 0.0889)
		(layer "In2.Cu")
		(net "CLK_322M_OSC_CPU1_RC_DP")
	)
	(segment
		(start 125.666754 -63.238634)
		(end 124.975366 -63.238634)
		(width 0.0889)
		(layer "In2.Cu")
		(net "CLK_322M_OSC_CPU1_RC_DP")
	)
	(segment
		(start 139.456922 -51.623722)
		(end 138.047222 -51.623722)
		(width 0.0889)
		(layer "In2.Cu")
		(net "CLK_322M_OSC_CPU1_RC_DP")
	)
	(segment
		(start 136.830308 -52.837334)
		(end 136.790684 -52.837334)
		(width 0.0889)
		(layer "In2.Cu")
		(net "CLK_322M_OSC_CPU1_RC_DP")
	)
	(segment
		(start 122.806714 -65.219834)
		(end 122.773948 -65.219834)
		(width 0.0889)
		(layer "In2.Cu")
		(net "CLK_322M_OSC_CPU1_RC_DP")
	)
	(segment
		(start 129.100834 -61.257434)
		(end 129.068068 -61.257434)
		(width 0.0889)
		(layer "In2.Cu")
		(net "CLK_322M_OSC_CPU1_RC_DP")
	)
	(segment
		(start 131.149598 -59.076336)
		(end 131.143248 -59.087004)
		(width 0.0889)
		(layer "In2.Cu")
		(net "CLK_322M_OSC_CPU1_RC_DP")
	)
	(segment
		(start 132.007864 -55.609236)
		(end 132.004562 -55.615078)
		(width 0.0889)
		(layer "In2.Cu")
		(net "CLK_322M_OSC_CPU1_RC_DP")
	)
	(segment
		(start 123.971812 -64.724788)
		(end 123.628658 -64.724788)
		(width 0.0889)
		(layer "In2.Cu")
		(net "CLK_322M_OSC_CPU1_RC_DP")
	)
	(segment
		(start 152.23744 -29.618432)
		(end 152.23744 -39.157656)
		(width 0.1143)
		(layer "In2.Cu")
		(net "CLK_322M_OSC_CPU1_RC_DP")
	)
	(segment
		(start 152.23744 -39.157656)
		(end 139.822174 -51.572922)
		(width 0.1143)
		(layer "In2.Cu")
		(net "CLK_322M_OSC_CPU1_RC_DP")
	)
	(segment
		(start 152.7175 -29.138372)
		(end 152.23744 -29.618432)
		(width 0.1143)
		(layer "In2.Cu")
		(net "CLK_322M_OSC_CPU1_RC_DP")
	)
	(segment
		(start 128.238504 -61.752988)
		(end 128.205738 -61.752988)
		(width 0.0889)
		(layer "In2.Cu")
		(net "CLK_322M_OSC_CPU1_RC_DP")
	)
	(segment
		(start 124.4092 -63.8048)
		(end 124.4092 -64.2874)
		(width 0.0889)
		(layer "In2.Cu")
		(net "CLK_322M_OSC_CPU1_RC_DP")
	)
	(segment
		(start 130.817874 -60.266834)
		(end 130.785108 -60.266834)
		(width 0.0889)
		(layer "In2.Cu")
		(net "CLK_322M_OSC_CPU1_RC_DP")
	)
	(segment
		(start 153.664158 -28.707842)
		(end 153.233628 -29.138372)
		(width 0.1143)
		(layer "In2.Cu")
		(net "CLK_322M_OSC_CPU1_RC_DP")
	)
	(arc
		(start 126.856998 -62.543436)
		(mid 126.715315 -62.68724)
		(end 126.521464 -62.743588)
		(width 0.0889)
		(layer "In2.Cu")
		(net "CLK_322M_OSC_CPU1_RC_DP")
	)
	(arc
		(start 122.773948 -65.219834)
		(mid 122.488524 -65.303301)
		(end 122.279918 -65.515236)
		(width 0.0889)
		(layer "In2.Cu")
		(net "CLK_322M_OSC_CPU1_RC_DP")
	)
	(arc
		(start 121.056908 -65.219834)
		(mid 120.771484 -65.303301)
		(end 120.562878 -65.515236)
		(width 0.0889)
		(layer "In2.Cu")
		(net "CLK_322M_OSC_CPU1_RC_DP")
	)
	(arc
		(start 122.279918 -65.515236)
		(mid 122.138562 -65.658845)
		(end 121.945146 -65.715388)
		(width 0.0889)
		(layer "In2.Cu")
		(net "CLK_322M_OSC_CPU1_RC_DP")
	)
	(arc
		(start 131.639818 -55.809388)
		(mid 131.147428 -56.108321)
		(end 131.143248 -56.684418)
		(width 0.0889)
		(layer "In2.Cu")
		(net "CLK_322M_OSC_CPU1_RC_DP")
	)
	(arc
		(start 127.715518 -62.048136)
		(mid 127.575439 -62.190872)
		(end 127.383794 -62.248034)
		(width 0.0889)
		(layer "In2.Cu")
		(net "CLK_322M_OSC_CPU1_RC_DP")
	)
	(arc
		(start 131.154424 -57.694322)
		(mid 131.203179 -57.890674)
		(end 131.149598 -58.085736)
		(width 0.0889)
		(layer "In2.Cu")
		(net "CLK_322M_OSC_CPU1_RC_DP")
	)
	(arc
		(start 132.004562 -55.615078)
		(mid 131.858596 -55.757477)
		(end 131.661408 -55.809388)
		(width 0.0889)
		(layer "In2.Cu")
		(net "CLK_322M_OSC_CPU1_RC_DP")
	)
	(arc
		(start 129.432558 -61.057536)
		(mid 129.292479 -61.200272)
		(end 129.100834 -61.257434)
		(width 0.0889)
		(layer "In2.Cu")
		(net "CLK_322M_OSC_CPU1_RC_DP")
	)
	(arc
		(start 130.785108 -60.266834)
		(mid 130.499684 -60.350301)
		(end 130.291078 -60.562236)
		(width 0.0889)
		(layer "In2.Cu")
		(net "CLK_322M_OSC_CPU1_RC_DP")
	)
	(arc
		(start 134.583424 -54.123336)
		(mid 134.441741 -54.26714)
		(end 134.24789 -54.323488)
		(width 0.0889)
		(layer "In2.Cu")
		(net "CLK_322M_OSC_CPU1_RC_DP")
	)
	(arc
		(start 132.866384 -55.113936)
		(mid 132.726305 -55.256672)
		(end 132.53466 -55.313834)
		(width 0.0889)
		(layer "In2.Cu")
		(net "CLK_322M_OSC_CPU1_RC_DP")
	)
	(arc
		(start 129.922778 -60.762388)
		(mid 129.639561 -60.846669)
		(end 129.432558 -61.057536)
		(width 0.0889)
		(layer "In2.Cu")
		(net "CLK_322M_OSC_CPU1_RC_DP")
	)
	(arc
		(start 121.586498 -65.515236)
		(mid 121.37789 -65.303304)
		(end 121.092468 -65.219834)
		(width 0.0889)
		(layer "In2.Cu")
		(net "CLK_322M_OSC_CPU1_RC_DP")
	)
	(arc
		(start 123.628658 -64.724788)
		(mid 123.345441 -64.809069)
		(end 123.138438 -65.019936)
		(width 0.0889)
		(layer "In2.Cu")
		(net "CLK_322M_OSC_CPU1_RC_DP")
	)
	(arc
		(start 135.9408 -53.332634)
		(mid 135.652655 -53.414953)
		(end 135.441944 -53.628036)
		(width 0.0889)
		(layer "In2.Cu")
		(net "CLK_322M_OSC_CPU1_RC_DP")
	)
	(arc
		(start 123.138438 -65.019936)
		(mid 122.998359 -65.162672)
		(end 122.806714 -65.219834)
		(width 0.0889)
		(layer "In2.Cu")
		(net "CLK_322M_OSC_CPU1_RC_DP")
	)
	(arc
		(start 132.501894 -55.313834)
		(mid 132.21647 -55.397301)
		(end 132.007864 -55.609236)
		(width 0.0889)
		(layer "In2.Cu")
		(net "CLK_322M_OSC_CPU1_RC_DP")
	)
	(arc
		(start 128.205738 -61.752988)
		(mid 127.922521 -61.837269)
		(end 127.715518 -62.048136)
		(width 0.0889)
		(layer "In2.Cu")
		(net "CLK_322M_OSC_CPU1_RC_DP")
	)
	(arc
		(start 131.149598 -58.085736)
		(mid 131.070467 -58.381138)
		(end 131.149598 -58.67654)
		(width 0.0889)
		(layer "In2.Cu")
		(net "CLK_322M_OSC_CPU1_RC_DP")
	)
	(arc
		(start 120.562878 -65.515236)
		(mid 120.421195 -65.65904)
		(end 120.227344 -65.715388)
		(width 0.0889)
		(layer "In2.Cu")
		(net "CLK_322M_OSC_CPU1_RC_DP")
	)
	(arc
		(start 125.998478 -63.038736)
		(mid 125.858399 -63.181472)
		(end 125.666754 -63.238634)
		(width 0.0889)
		(layer "In2.Cu")
		(net "CLK_322M_OSC_CPU1_RC_DP")
	)
	(arc
		(start 126.488698 -62.743588)
		(mid 126.205481 -62.827869)
		(end 125.998478 -63.038736)
		(width 0.0889)
		(layer "In2.Cu")
		(net "CLK_322M_OSC_CPU1_RC_DP")
	)
	(arc
		(start 131.154424 -59.675522)
		(mid 131.150677 -60.064778)
		(end 130.817874 -60.266834)
		(width 0.0889)
		(layer "In2.Cu")
		(net "CLK_322M_OSC_CPU1_RC_DP")
	)
	(arc
		(start 120.191276 -65.715388)
		(mid 119.938486 -65.784028)
		(end 119.740172 -65.955164)
		(width 0.0889)
		(layer "In2.Cu")
		(net "CLK_322M_OSC_CPU1_RC_DP")
	)
	(arc
		(start 135.441944 -53.628036)
		(mid 135.301865 -53.770772)
		(end 135.11022 -53.827934)
		(width 0.0889)
		(layer "In2.Cu")
		(net "CLK_322M_OSC_CPU1_RC_DP")
	)
	(arc
		(start 135.077454 -53.827934)
		(mid 134.79203 -53.911401)
		(end 134.583424 -54.123336)
		(width 0.0889)
		(layer "In2.Cu")
		(net "CLK_322M_OSC_CPU1_RC_DP")
	)
	(arc
		(start 131.154424 -56.703722)
		(mid 131.203179 -56.900074)
		(end 131.149598 -57.095136)
		(width 0.0889)
		(layer "In2.Cu")
		(net "CLK_322M_OSC_CPU1_RC_DP")
	)
	(arc
		(start 127.351028 -62.248034)
		(mid 127.065604 -62.331501)
		(end 126.856998 -62.543436)
		(width 0.0889)
		(layer "In2.Cu")
		(net "CLK_322M_OSC_CPU1_RC_DP")
	)
	(arc
		(start 134.215124 -54.323488)
		(mid 133.931907 -54.407769)
		(end 133.724904 -54.618636)
		(width 0.0889)
		(layer "In2.Cu")
		(net "CLK_322M_OSC_CPU1_RC_DP")
	)
	(arc
		(start 131.143248 -59.087004)
		(mid 131.07045 -59.377767)
		(end 131.149598 -59.666886)
		(width 0.0889)
		(layer "In2.Cu")
		(net "CLK_322M_OSC_CPU1_RC_DP")
	)
	(arc
		(start 131.149598 -57.095136)
		(mid 131.070376 -57.384254)
		(end 131.143248 -57.675018)
		(width 0.0889)
		(layer "In2.Cu")
		(net "CLK_322M_OSC_CPU1_RC_DP")
	)
	(arc
		(start 136.300464 -53.132482)
		(mid 136.158781 -53.276286)
		(end 135.96493 -53.332634)
		(width 0.0889)
		(layer "In2.Cu")
		(net "CLK_322M_OSC_CPU1_RC_DP")
	)
	(arc
		(start 128.574038 -61.552836)
		(mid 128.432355 -61.69664)
		(end 128.238504 -61.752988)
		(width 0.0889)
		(layer "In2.Cu")
		(net "CLK_322M_OSC_CPU1_RC_DP")
	)
	(arc
		(start 133.724904 -54.618636)
		(mid 133.584825 -54.761372)
		(end 133.39318 -54.818534)
		(width 0.0889)
		(layer "In2.Cu")
		(net "CLK_322M_OSC_CPU1_RC_DP")
	)
	(arc
		(start 133.360414 -54.818534)
		(mid 133.07499 -54.902001)
		(end 132.866384 -55.113936)
		(width 0.0889)
		(layer "In2.Cu")
		(net "CLK_322M_OSC_CPU1_RC_DP")
	)
	(arc
		(start 129.068068 -61.257434)
		(mid 128.782644 -61.340901)
		(end 128.574038 -61.552836)
		(width 0.0889)
		(layer "In2.Cu")
		(net "CLK_322M_OSC_CPU1_RC_DP")
	)
	(arc
		(start 130.291078 -60.562236)
		(mid 130.149395 -60.70604)
		(end 129.955544 -60.762388)
		(width 0.0889)
		(layer "In2.Cu")
		(net "CLK_322M_OSC_CPU1_RC_DP")
	)
	(arc
		(start 137.158984 -52.637436)
		(mid 137.02024 -52.779469)
		(end 136.830308 -52.837334)
		(width 0.0889)
		(layer "In2.Cu")
		(net "CLK_322M_OSC_CPU1_RC_DP")
	)
	(arc
		(start 131.149598 -58.67654)
		(mid 131.203097 -58.876438)
		(end 131.149598 -59.076336)
		(width 0.0889)
		(layer "In2.Cu")
		(net "CLK_322M_OSC_CPU1_RC_DP")
	)
	(arc
		(start 121.945146 -65.715388)
		(mid 121.933208 -65.715566)
		(end 121.92127 -65.715388)
		(width 0.0889)
		(layer "In2.Cu")
		(net "CLK_322M_OSC_CPU1_RC_DP")
	)
	(arc
		(start 136.790684 -52.837334)
		(mid 136.507467 -52.921615)
		(end 136.300464 -53.132482)
		(width 0.0889)
		(layer "In2.Cu")
		(net "CLK_322M_OSC_CPU1_RC_DP")
	)
	(arc
		(start 121.92127 -65.715388)
		(mid 121.727844 -65.658861)
		(end 121.586498 -65.515236)
		(width 0.0889)
		(layer "In2.Cu")
		(net "CLK_322M_OSC_CPU1_RC_DP")
	)
	(segment
		(start 153.981912 -30.5308)
		(end 154.305 -30.5308)
		(width 0.127)
		(layer "F.Cu")
		(net "CLK_322M_OSC_CPU1_RC_DN")
	)
	(segment
		(start 120.787668 -66.305938)
		(end 120.216168 -66.305938)
		(width 0.127)
		(layer "F.Cu")
		(net "CLK_322M_OSC_CPU1_RC_DN")
	)
	(segment
		(start 153.677112 -30.226)
		(end 153.981912 -30.5308)
		(width 0.127)
		(layer "F.Cu")
		(net "CLK_322M_OSC_CPU1_RC_DN")
	)
	(via
		(at 120.216168 -66.305938)
		(size 0.508)
		(drill 0.254)
		(layers "F.Cu" "B.Cu")
		(net "CLK_322M_OSC_CPU1_RC_DN")
	)
	(via
		(at 153.677112 -30.226)
		(size 0.508)
		(drill 0.254)
		(layers "F.Cu" "B.Cu")
		(net "CLK_322M_OSC_CPU1_RC_DN")
	)
	(segment
		(start 137.96137 -52.078636)
		(end 137.96137 -51.979068)
		(width 0.0889)
		(layer "In2.Cu")
		(net "CLK_322M_OSC_CPU1_RC_DN")
	)
	(segment
		(start 134.221728 -54.513988)
		(end 134.254494 -54.513988)
		(width 0.0889)
		(layer "In2.Cu")
		(net "CLK_322M_OSC_CPU1_RC_DN")
	)
	(segment
		(start 131.321048 -56.610504)
		(end 131.314698 -56.599836)
		(width 0.0889)
		(layer "In2.Cu")
		(net "CLK_322M_OSC_CPU1_RC_DN")
	)
	(segment
		(start 152.52954 -32.816038)
		(end 152.52954 -32.55645)
		(width 0.1143)
		(layer "In2.Cu")
		(net "CLK_322M_OSC_CPU1_RC_DN")
	)
	(segment
		(start 137.60958 -52.330858)
		(end 137.736072 -52.204366)
		(width 0.0889)
		(layer "In2.Cu")
		(net "CLK_322M_OSC_CPU1_RC_DN")
	)
	(segment
		(start 152.52954 -33.52419)
		(end 152.52954 -33.29559)
		(width 0.1143)
		(layer "In2.Cu")
		(net "CLK_322M_OSC_CPU1_RC_DN")
	)
	(segment
		(start 135.938768 -53.523388)
		(end 135.966708 -53.523388)
		(width 0.0889)
		(layer "In2.Cu")
		(net "CLK_322M_OSC_CPU1_RC_DN")
	)
	(segment
		(start 139.943332 -51.865022)
		(end 152.52954 -39.278814)
		(width 0.1143)
		(layer "In2.Cu")
		(net "CLK_322M_OSC_CPU1_RC_DN")
	)
	(segment
		(start 152.52954 -39.278814)
		(end 152.52954 -34.711894)
		(width 0.1143)
		(layer "In2.Cu")
		(net "CLK_322M_OSC_CPU1_RC_DN")
	)
	(segment
		(start 130.791712 -60.457334)
		(end 130.824478 -60.457334)
		(width 0.0889)
		(layer "In2.Cu")
		(net "CLK_322M_OSC_CPU1_RC_DN")
	)
	(segment
		(start 152.655016 -33.170114)
		(end 152.655016 -32.941514)
		(width 0.1143)
		(layer "In2.Cu")
		(net "CLK_322M_OSC_CPU1_RC_DN")
	)
	(segment
		(start 152.52954 -29.73959)
		(end 152.838658 -29.430472)
		(width 0.1143)
		(layer "In2.Cu")
		(net "CLK_322M_OSC_CPU1_RC_DN")
	)
	(segment
		(start 120.216168 -66.305938)
		(end 119.923306 -66.137028)
		(width 0.0889)
		(layer "In2.Cu")
		(net "CLK_322M_OSC_CPU1_RC_DN")
	)
	(segment
		(start 152.655016 -34.357818)
		(end 152.52954 -34.232342)
		(width 0.1143)
		(layer "In2.Cu")
		(net "CLK_322M_OSC_CPU1_RC_DN")
	)
	(segment
		(start 152.655016 -33.649666)
		(end 152.52954 -33.52419)
		(width 0.1143)
		(layer "In2.Cu")
		(net "CLK_322M_OSC_CPU1_RC_DN")
	)
	(segment
		(start 138.037062 -51.903376)
		(end 138.037062 -51.903884)
		(width 0.0889)
		(layer "In2.Cu")
		(net "CLK_322M_OSC_CPU1_RC_DN")
	)
	(segment
		(start 137.96137 -51.979068)
		(end 138.037062 -51.903376)
		(width 0.0889)
		(layer "In2.Cu")
		(net "CLK_322M_OSC_CPU1_RC_DN")
	)
	(segment
		(start 139.507722 -51.865022)
		(end 139.52982 -51.865022)
		(width 0.0889)
		(layer "In2.Cu")
		(net "CLK_322M_OSC_CPU1_RC_DN")
	)
	(segment
		(start 152.52954 -33.29559)
		(end 152.655016 -33.170114)
		(width 0.1143)
		(layer "In2.Cu")
		(net "CLK_322M_OSC_CPU1_RC_DN")
	)
	(segment
		(start 137.324084 -52.732686)
		(end 137.483088 -52.457096)
		(width 0.0889)
		(layer "In2.Cu")
		(net "CLK_322M_OSC_CPU1_RC_DN")
	)
	(segment
		(start 123.635262 -64.915288)
		(end 124.050806 -64.915288)
		(width 0.0889)
		(layer "In2.Cu")
		(net "CLK_322M_OSC_CPU1_RC_DN")
	)
	(segment
		(start 152.621488 -32.235902)
		(end 152.52954 -32.143954)
		(width 0.1143)
		(layer "In2.Cu")
		(net "CLK_322M_OSC_CPU1_RC_DN")
	)
	(segment
		(start 152.655016 -33.878266)
		(end 152.655016 -33.649666)
		(width 0.1143)
		(layer "In2.Cu")
		(net "CLK_322M_OSC_CPU1_RC_DN")
	)
	(segment
		(start 124.599446 -63.884048)
		(end 125.05436 -63.429134)
		(width 0.0889)
		(layer "In2.Cu")
		(net "CLK_322M_OSC_CPU1_RC_DN")
	)
	(segment
		(start 152.52954 -32.55645)
		(end 152.621488 -32.464502)
		(width 0.1143)
		(layer "In2.Cu")
		(net "CLK_322M_OSC_CPU1_RC_DN")
	)
	(segment
		(start 124.599446 -64.366648)
		(end 124.599446 -63.884048)
		(width 0.0889)
		(layer "In2.Cu")
		(net "CLK_322M_OSC_CPU1_RC_DN")
	)
	(segment
		(start 124.050806 -64.915288)
		(end 124.599446 -64.366648)
		(width 0.0889)
		(layer "In2.Cu")
		(net "CLK_322M_OSC_CPU1_RC_DN")
	)
	(segment
		(start 132.173218 -55.704486)
		(end 132.17652 -55.698644)
		(width 0.0889)
		(layer "In2.Cu")
		(net "CLK_322M_OSC_CPU1_RC_DN")
	)
	(segment
		(start 135.084058 -54.018434)
		(end 135.116824 -54.018434)
		(width 0.0889)
		(layer "In2.Cu")
		(net "CLK_322M_OSC_CPU1_RC_DN")
	)
	(segment
		(start 153.677112 -29.681424)
		(end 153.677112 -30.226)
		(width 0.1143)
		(layer "In2.Cu")
		(net "CLK_322M_OSC_CPU1_RC_DN")
	)
	(segment
		(start 131.646422 -55.999888)
		(end 131.679188 -55.999888)
		(width 0.0889)
		(layer "In2.Cu")
		(net "CLK_322M_OSC_CPU1_RC_DN")
	)
	(segment
		(start 153.42616 -29.430472)
		(end 153.677112 -29.681424)
		(width 0.1143)
		(layer "In2.Cu")
		(net "CLK_322M_OSC_CPU1_RC_DN")
	)
	(segment
		(start 152.621488 -32.464502)
		(end 152.621488 -32.235902)
		(width 0.1143)
		(layer "In2.Cu")
		(net "CLK_322M_OSC_CPU1_RC_DN")
	)
	(segment
		(start 152.655016 -34.586418)
		(end 152.655016 -34.357818)
		(width 0.1143)
		(layer "In2.Cu")
		(net "CLK_322M_OSC_CPU1_RC_DN")
	)
	(segment
		(start 129.929382 -60.952888)
		(end 129.962148 -60.952888)
		(width 0.0889)
		(layer "In2.Cu")
		(net "CLK_322M_OSC_CPU1_RC_DN")
	)
	(segment
		(start 137.736072 -52.204366)
		(end 137.83564 -52.204366)
		(width 0.0889)
		(layer "In2.Cu")
		(net "CLK_322M_OSC_CPU1_RC_DN")
	)
	(segment
		(start 126.495302 -62.934088)
		(end 126.528068 -62.934088)
		(width 0.0889)
		(layer "In2.Cu")
		(net "CLK_322M_OSC_CPU1_RC_DN")
	)
	(segment
		(start 152.838658 -29.430472)
		(end 153.42616 -29.430472)
		(width 0.1143)
		(layer "In2.Cu")
		(net "CLK_322M_OSC_CPU1_RC_DN")
	)
	(segment
		(start 131.314698 -56.599836)
		(end 131.309872 -56.5912)
		(width 0.0889)
		(layer "In2.Cu")
		(net "CLK_322M_OSC_CPU1_RC_DN")
	)
	(segment
		(start 152.52954 -32.143954)
		(end 152.52954 -29.73959)
		(width 0.1143)
		(layer "In2.Cu")
		(net "CLK_322M_OSC_CPU1_RC_DN")
	)
	(segment
		(start 152.52954 -34.003742)
		(end 152.655016 -33.878266)
		(width 0.1143)
		(layer "In2.Cu")
		(net "CLK_322M_OSC_CPU1_RC_DN")
	)
	(segment
		(start 121.915428 -65.905888)
		(end 121.950988 -65.905888)
		(width 0.0889)
		(layer "In2.Cu")
		(net "CLK_322M_OSC_CPU1_RC_DN")
	)
	(segment
		(start 152.52954 -34.232342)
		(end 152.52954 -34.003742)
		(width 0.1143)
		(layer "In2.Cu")
		(net "CLK_322M_OSC_CPU1_RC_DN")
	)
	(segment
		(start 137.60958 -52.330604)
		(end 137.60958 -52.330858)
		(width 0.0889)
		(layer "In2.Cu")
		(net "CLK_322M_OSC_CPU1_RC_DN")
	)
	(segment
		(start 131.314698 -59.171586)
		(end 131.321048 -59.160918)
		(width 0.0889)
		(layer "In2.Cu")
		(net "CLK_322M_OSC_CPU1_RC_DN")
	)
	(segment
		(start 119.923306 -66.137028)
		(end 119.902224 -66.058288)
		(width 0.0889)
		(layer "In2.Cu")
		(net "CLK_322M_OSC_CPU1_RC_DN")
	)
	(segment
		(start 132.519674 -55.504334)
		(end 132.541264 -55.504334)
		(width 0.0889)
		(layer "In2.Cu")
		(net "CLK_322M_OSC_CPU1_RC_DN")
	)
	(segment
		(start 136.79424 -53.028088)
		(end 136.799828 -53.027834)
		(width 0.0889)
		(layer "In2.Cu")
		(net "CLK_322M_OSC_CPU1_RC_DN")
	)
	(segment
		(start 125.05436 -63.429134)
		(end 125.673358 -63.429134)
		(width 0.0889)
		(layer "In2.Cu")
		(net "CLK_322M_OSC_CPU1_RC_DN")
	)
	(segment
		(start 139.456922 -51.814222)
		(end 139.507722 -51.865022)
		(width 0.0889)
		(layer "In2.Cu")
		(net "CLK_322M_OSC_CPU1_RC_DN")
	)
	(segment
		(start 131.314698 -57.590436)
		(end 131.309872 -57.5818)
		(width 0.0889)
		(layer "In2.Cu")
		(net "CLK_322M_OSC_CPU1_RC_DN")
	)
	(segment
		(start 129.074672 -61.447934)
		(end 129.107438 -61.447934)
		(width 0.0889)
		(layer "In2.Cu")
		(net "CLK_322M_OSC_CPU1_RC_DN")
	)
	(segment
		(start 120.216168 -65.905888)
		(end 120.233948 -65.905888)
		(width 0.0889)
		(layer "In2.Cu")
		(net "CLK_322M_OSC_CPU1_RC_DN")
	)
	(segment
		(start 152.655016 -32.941514)
		(end 152.52954 -32.816038)
		(width 0.1143)
		(layer "In2.Cu")
		(net "CLK_322M_OSC_CPU1_RC_DN")
	)
	(segment
		(start 152.52954 -34.711894)
		(end 152.655016 -34.586418)
		(width 0.1143)
		(layer "In2.Cu")
		(net "CLK_322M_OSC_CPU1_RC_DN")
	)
	(segment
		(start 128.212342 -61.943488)
		(end 128.245108 -61.943488)
		(width 0.0889)
		(layer "In2.Cu")
		(net "CLK_322M_OSC_CPU1_RC_DN")
	)
	(segment
		(start 122.780552 -65.410334)
		(end 122.813318 -65.410334)
		(width 0.0889)
		(layer "In2.Cu")
		(net "CLK_322M_OSC_CPU1_RC_DN")
	)
	(segment
		(start 136.799828 -53.027834)
		(end 136.834372 -53.027834)
		(width 0.0889)
		(layer "In2.Cu")
		(net "CLK_322M_OSC_CPU1_RC_DN")
	)
	(segment
		(start 137.83564 -52.204366)
		(end 137.96137 -52.078636)
		(width 0.0889)
		(layer "In2.Cu")
		(net "CLK_322M_OSC_CPU1_RC_DN")
	)
	(segment
		(start 139.52982 -51.865022)
		(end 139.943332 -51.865022)
		(width 0.1143)
		(layer "In2.Cu")
		(net "CLK_322M_OSC_CPU1_RC_DN")
	)
	(segment
		(start 137.483088 -52.457096)
		(end 137.60958 -52.330604)
		(width 0.0889)
		(layer "In2.Cu")
		(net "CLK_322M_OSC_CPU1_RC_DN")
	)
	(segment
		(start 131.314698 -58.581036)
		(end 131.309872 -58.5724)
		(width 0.0889)
		(layer "In2.Cu")
		(net "CLK_322M_OSC_CPU1_RC_DN")
	)
	(segment
		(start 127.357632 -62.438534)
		(end 127.390398 -62.438534)
		(width 0.0889)
		(layer "In2.Cu")
		(net "CLK_322M_OSC_CPU1_RC_DN")
	)
	(segment
		(start 133.367018 -55.009034)
		(end 133.399784 -55.009034)
		(width 0.0889)
		(layer "In2.Cu")
		(net "CLK_322M_OSC_CPU1_RC_DN")
	)
	(segment
		(start 131.321048 -57.601104)
		(end 131.314698 -57.590436)
		(width 0.0889)
		(layer "In2.Cu")
		(net "CLK_322M_OSC_CPU1_RC_DN")
	)
	(segment
		(start 138.126724 -51.814222)
		(end 139.456922 -51.814222)
		(width 0.0889)
		(layer "In2.Cu")
		(net "CLK_322M_OSC_CPU1_RC_DN")
	)
	(segment
		(start 138.037062 -51.903884)
		(end 138.126724 -51.814222)
		(width 0.0889)
		(layer "In2.Cu")
		(net "CLK_322M_OSC_CPU1_RC_DN")
	)
	(arc
		(start 135.116824 -54.018434)
		(mid 135.400041 -53.934153)
		(end 135.607044 -53.723286)
		(width 0.0889)
		(layer "In2.Cu")
		(net "CLK_322M_OSC_CPU1_RC_DN")
	)
	(arc
		(start 131.314698 -58.180986)
		(mid 131.39392 -57.891868)
		(end 131.321048 -57.601104)
		(width 0.0889)
		(layer "In2.Cu")
		(net "CLK_322M_OSC_CPU1_RC_DN")
	)
	(arc
		(start 128.245108 -61.943488)
		(mid 128.530532 -61.860021)
		(end 128.739138 -61.648086)
		(width 0.0889)
		(layer "In2.Cu")
		(net "CLK_322M_OSC_CPU1_RC_DN")
	)
	(arc
		(start 131.321048 -59.160918)
		(mid 131.393846 -58.870155)
		(end 131.314698 -58.581036)
		(width 0.0889)
		(layer "In2.Cu")
		(net "CLK_322M_OSC_CPU1_RC_DN")
	)
	(arc
		(start 136.465564 -53.227986)
		(mid 136.604308 -53.085953)
		(end 136.79424 -53.028088)
		(width 0.0889)
		(layer "In2.Cu")
		(net "CLK_322M_OSC_CPU1_RC_DN")
	)
	(arc
		(start 131.314698 -59.571382)
		(mid 131.261199 -59.371484)
		(end 131.314698 -59.171586)
		(width 0.0889)
		(layer "In2.Cu")
		(net "CLK_322M_OSC_CPU1_RC_DN")
	)
	(arc
		(start 120.727978 -65.610486)
		(mid 120.869334 -65.466877)
		(end 121.06275 -65.410334)
		(width 0.0889)
		(layer "In2.Cu")
		(net "CLK_322M_OSC_CPU1_RC_DN")
	)
	(arc
		(start 121.950988 -65.905888)
		(mid 122.236412 -65.822421)
		(end 122.445018 -65.610486)
		(width 0.0889)
		(layer "In2.Cu")
		(net "CLK_322M_OSC_CPU1_RC_DN")
	)
	(arc
		(start 121.086626 -65.410334)
		(mid 121.280052 -65.466861)
		(end 121.421398 -65.610486)
		(width 0.0889)
		(layer "In2.Cu")
		(net "CLK_322M_OSC_CPU1_RC_DN")
	)
	(arc
		(start 131.679188 -55.999888)
		(mid 131.964612 -55.916421)
		(end 132.173218 -55.704486)
		(width 0.0889)
		(layer "In2.Cu")
		(net "CLK_322M_OSC_CPU1_RC_DN")
	)
	(arc
		(start 126.528068 -62.934088)
		(mid 126.813492 -62.850621)
		(end 127.022098 -62.638686)
		(width 0.0889)
		(layer "In2.Cu")
		(net "CLK_322M_OSC_CPU1_RC_DN")
	)
	(arc
		(start 131.309872 -56.5912)
		(mid 131.313619 -56.201944)
		(end 131.646422 -55.999888)
		(width 0.0889)
		(layer "In2.Cu")
		(net "CLK_322M_OSC_CPU1_RC_DN")
	)
	(arc
		(start 131.309872 -57.5818)
		(mid 131.261117 -57.385448)
		(end 131.314698 -57.190386)
		(width 0.0889)
		(layer "In2.Cu")
		(net "CLK_322M_OSC_CPU1_RC_DN")
	)
	(arc
		(start 122.445018 -65.610486)
		(mid 122.586701 -65.466682)
		(end 122.780552 -65.410334)
		(width 0.0889)
		(layer "In2.Cu")
		(net "CLK_322M_OSC_CPU1_RC_DN")
	)
	(arc
		(start 122.813318 -65.410334)
		(mid 123.096535 -65.326053)
		(end 123.303538 -65.115186)
		(width 0.0889)
		(layer "In2.Cu")
		(net "CLK_322M_OSC_CPU1_RC_DN")
	)
	(arc
		(start 127.880618 -62.143386)
		(mid 128.020697 -62.00065)
		(end 128.212342 -61.943488)
		(width 0.0889)
		(layer "In2.Cu")
		(net "CLK_322M_OSC_CPU1_RC_DN")
	)
	(arc
		(start 128.739138 -61.648086)
		(mid 128.880821 -61.504282)
		(end 129.074672 -61.447934)
		(width 0.0889)
		(layer "In2.Cu")
		(net "CLK_322M_OSC_CPU1_RC_DN")
	)
	(arc
		(start 121.06275 -65.410334)
		(mid 121.074688 -65.410156)
		(end 121.086626 -65.410334)
		(width 0.0889)
		(layer "In2.Cu")
		(net "CLK_322M_OSC_CPU1_RC_DN")
	)
	(arc
		(start 135.966708 -53.523388)
		(mid 136.254853 -53.441069)
		(end 136.465564 -53.227986)
		(width 0.0889)
		(layer "In2.Cu")
		(net "CLK_322M_OSC_CPU1_RC_DN")
	)
	(arc
		(start 129.597658 -61.152786)
		(mid 129.737737 -61.01005)
		(end 129.929382 -60.952888)
		(width 0.0889)
		(layer "In2.Cu")
		(net "CLK_322M_OSC_CPU1_RC_DN")
	)
	(arc
		(start 134.748524 -54.218586)
		(mid 134.890207 -54.074782)
		(end 135.084058 -54.018434)
		(width 0.0889)
		(layer "In2.Cu")
		(net "CLK_322M_OSC_CPU1_RC_DN")
	)
	(arc
		(start 135.607044 -53.723286)
		(mid 135.747123 -53.58055)
		(end 135.938768 -53.523388)
		(width 0.0889)
		(layer "In2.Cu")
		(net "CLK_322M_OSC_CPU1_RC_DN")
	)
	(arc
		(start 120.233948 -65.905888)
		(mid 120.519372 -65.822421)
		(end 120.727978 -65.610486)
		(width 0.0889)
		(layer "In2.Cu")
		(net "CLK_322M_OSC_CPU1_RC_DN")
	)
	(arc
		(start 130.456178 -60.657486)
		(mid 130.597861 -60.513682)
		(end 130.791712 -60.457334)
		(width 0.0889)
		(layer "In2.Cu")
		(net "CLK_322M_OSC_CPU1_RC_DN")
	)
	(arc
		(start 133.031484 -55.209186)
		(mid 133.173167 -55.065382)
		(end 133.367018 -55.009034)
		(width 0.0889)
		(layer "In2.Cu")
		(net "CLK_322M_OSC_CPU1_RC_DN")
	)
	(arc
		(start 131.309872 -58.5724)
		(mid 131.261117 -58.376048)
		(end 131.314698 -58.180986)
		(width 0.0889)
		(layer "In2.Cu")
		(net "CLK_322M_OSC_CPU1_RC_DN")
	)
	(arc
		(start 134.254494 -54.513988)
		(mid 134.539918 -54.430521)
		(end 134.748524 -54.218586)
		(width 0.0889)
		(layer "In2.Cu")
		(net "CLK_322M_OSC_CPU1_RC_DN")
	)
	(arc
		(start 121.421398 -65.610486)
		(mid 121.630006 -65.822418)
		(end 121.915428 -65.905888)
		(width 0.0889)
		(layer "In2.Cu")
		(net "CLK_322M_OSC_CPU1_RC_DN")
	)
	(arc
		(start 130.824478 -60.457334)
		(mid 131.319955 -60.152891)
		(end 131.314698 -59.571382)
		(width 0.0889)
		(layer "In2.Cu")
		(net "CLK_322M_OSC_CPU1_RC_DN")
	)
	(arc
		(start 133.399784 -55.009034)
		(mid 133.683001 -54.924753)
		(end 133.890004 -54.713886)
		(width 0.0889)
		(layer "In2.Cu")
		(net "CLK_322M_OSC_CPU1_RC_DN")
	)
	(arc
		(start 132.541264 -55.504334)
		(mid 132.824481 -55.420053)
		(end 133.031484 -55.209186)
		(width 0.0889)
		(layer "In2.Cu")
		(net "CLK_322M_OSC_CPU1_RC_DN")
	)
	(arc
		(start 127.390398 -62.438534)
		(mid 127.673615 -62.354253)
		(end 127.880618 -62.143386)
		(width 0.0889)
		(layer "In2.Cu")
		(net "CLK_322M_OSC_CPU1_RC_DN")
	)
	(arc
		(start 129.107438 -61.447934)
		(mid 129.390655 -61.363653)
		(end 129.597658 -61.152786)
		(width 0.0889)
		(layer "In2.Cu")
		(net "CLK_322M_OSC_CPU1_RC_DN")
	)
	(arc
		(start 127.022098 -62.638686)
		(mid 127.163781 -62.494882)
		(end 127.357632 -62.438534)
		(width 0.0889)
		(layer "In2.Cu")
		(net "CLK_322M_OSC_CPU1_RC_DN")
	)
	(arc
		(start 123.303538 -65.115186)
		(mid 123.443617 -64.97245)
		(end 123.635262 -64.915288)
		(width 0.0889)
		(layer "In2.Cu")
		(net "CLK_322M_OSC_CPU1_RC_DN")
	)
	(arc
		(start 136.834372 -53.027834)
		(mid 137.117276 -52.943415)
		(end 137.324084 -52.732686)
		(width 0.0889)
		(layer "In2.Cu")
		(net "CLK_322M_OSC_CPU1_RC_DN")
	)
	(arc
		(start 119.902224 -66.058288)
		(mid 120.041701 -65.946044)
		(end 120.216168 -65.905888)
		(width 0.0889)
		(layer "In2.Cu")
		(net "CLK_322M_OSC_CPU1_RC_DN")
	)
	(arc
		(start 126.163578 -63.133986)
		(mid 126.303657 -62.99125)
		(end 126.495302 -62.934088)
		(width 0.0889)
		(layer "In2.Cu")
		(net "CLK_322M_OSC_CPU1_RC_DN")
	)
	(arc
		(start 129.962148 -60.952888)
		(mid 130.247572 -60.869421)
		(end 130.456178 -60.657486)
		(width 0.0889)
		(layer "In2.Cu")
		(net "CLK_322M_OSC_CPU1_RC_DN")
	)
	(arc
		(start 132.17652 -55.698644)
		(mid 132.322486 -55.556245)
		(end 132.519674 -55.504334)
		(width 0.0889)
		(layer "In2.Cu")
		(net "CLK_322M_OSC_CPU1_RC_DN")
	)
	(arc
		(start 131.314698 -57.190386)
		(mid 131.39392 -56.901268)
		(end 131.321048 -56.610504)
		(width 0.0889)
		(layer "In2.Cu")
		(net "CLK_322M_OSC_CPU1_RC_DN")
	)
	(arc
		(start 133.890004 -54.713886)
		(mid 134.030083 -54.57115)
		(end 134.221728 -54.513988)
		(width 0.0889)
		(layer "In2.Cu")
		(net "CLK_322M_OSC_CPU1_RC_DN")
	)
	(arc
		(start 125.673358 -63.429134)
		(mid 125.956575 -63.344853)
		(end 126.163578 -63.133986)
		(width 0.0889)
		(layer "In2.Cu")
		(net "CLK_322M_OSC_CPU1_RC_DN")
	)
	(segment
		(start 157.390084 -28.980384)
		(end 157.0355 -28.6258)
		(width 0.127)
		(layer "F.Cu")
		(net "CLK_156M_OSC_CPU1_HFI_DP")
	)
	(segment
		(start 155.890722 -29.031438)
		(end 155.345638 -29.031438)
		(width 0.127)
		(layer "F.Cu")
		(net "CLK_156M_OSC_CPU1_HFI_DP")
	)
	(segment
		(start 157.493716 -28.980384)
		(end 157.390084 -28.980384)
		(width 0.127)
		(layer "F.Cu")
		(net "CLK_156M_OSC_CPU1_HFI_DP")
	)
	(segment
		(start 129.372868 -74.230738)
		(end 129.94386 -74.230738)
		(width 0.127)
		(layer "F.Cu")
		(net "CLK_156M_OSC_CPU1_HFI_DP")
	)
	(segment
		(start 157.0355 -28.6258)
		(end 156.29636 -28.6258)
		(width 0.127)
		(layer "F.Cu")
		(net "CLK_156M_OSC_CPU1_HFI_DP")
	)
	(segment
		(start 129.94386 -74.230738)
		(end 129.944368 -74.23023)
		(width 0.127)
		(layer "F.Cu")
		(net "CLK_156M_OSC_CPU1_HFI_DP")
	)
	(segment
		(start 155.345638 -29.031438)
		(end 155.194 -28.8798)
		(width 0.127)
		(layer "F.Cu")
		(net "CLK_156M_OSC_CPU1_HFI_DP")
	)
	(segment
		(start 156.29636 -28.6258)
		(end 155.890722 -29.031438)
		(width 0.127)
		(layer "F.Cu")
		(net "CLK_156M_OSC_CPU1_HFI_DP")
	)
	(via
		(at 157.493716 -28.980384)
		(size 0.508)
		(drill 0.254)
		(layers "F.Cu" "B.Cu")
		(net "CLK_156M_OSC_CPU1_HFI_DP")
	)
	(via
		(at 129.944368 -74.23023)
		(size 0.508)
		(drill 0.254)
		(layers "F.Cu" "B.Cu")
		(net "CLK_156M_OSC_CPU1_HFI_DP")
	)
	(segment
		(start 132.173218 -71.554086)
		(end 132.182108 -71.538846)
		(width 0.0889)
		(layer "In2.Cu")
		(net "CLK_156M_OSC_CPU1_HFI_DP")
	)
	(segment
		(start 131.646422 -72.840088)
		(end 131.679188 -72.840088)
		(width 0.0889)
		(layer "In2.Cu")
		(net "CLK_156M_OSC_CPU1_HFI_DP")
	)
	(segment
		(start 132.173218 -63.629286)
		(end 132.182108 -63.614046)
		(width 0.0889)
		(layer "In2.Cu")
		(net "CLK_156M_OSC_CPU1_HFI_DP")
	)
	(segment
		(start 137.655808 -54.513988)
		(end 137.688574 -54.513988)
		(width 0.0889)
		(layer "In2.Cu")
		(net "CLK_156M_OSC_CPU1_HFI_DP")
	)
	(segment
		(start 132.173218 -68.582286)
		(end 132.182108 -68.567046)
		(width 0.0889)
		(layer "In2.Cu")
		(net "CLK_156M_OSC_CPU1_HFI_DP")
	)
	(segment
		(start 140.639546 -52.7558)
		(end 157.244542 -36.150804)
		(width 0.1143)
		(layer "In2.Cu")
		(net "CLK_156M_OSC_CPU1_HFI_DP")
	)
	(segment
		(start 133.363208 -55.999888)
		(end 133.395974 -55.999888)
		(width 0.0889)
		(layer "In2.Cu")
		(net "CLK_156M_OSC_CPU1_HFI_DP")
	)
	(segment
		(start 139.137644 -53.556154)
		(end 139.417044 -53.2765)
		(width 0.0889)
		(layer "In2.Cu")
		(net "CLK_156M_OSC_CPU1_HFI_DP")
	)
	(segment
		(start 132.173218 -62.638686)
		(end 132.182108 -62.623446)
		(width 0.0889)
		(layer "In2.Cu")
		(net "CLK_156M_OSC_CPU1_HFI_DP")
	)
	(segment
		(start 135.080248 -55.009288)
		(end 135.11022 -55.009288)
		(width 0.0889)
		(layer "In2.Cu")
		(net "CLK_156M_OSC_CPU1_HFI_DP")
	)
	(segment
		(start 132.173218 -69.572886)
		(end 132.182108 -69.557646)
		(width 0.0889)
		(layer "In2.Cu")
		(net "CLK_156M_OSC_CPU1_HFI_DP")
	)
	(segment
		(start 132.179568 -59.087004)
		(end 132.173218 -59.076336)
		(width 0.0889)
		(layer "In2.Cu")
		(net "CLK_156M_OSC_CPU1_HFI_DP")
	)
	(segment
		(start 134.225538 -55.504334)
		(end 134.258304 -55.504334)
		(width 0.0889)
		(layer "In2.Cu")
		(net "CLK_156M_OSC_CPU1_HFI_DP")
	)
	(segment
		(start 129.944368 -73.892156)
		(end 130.008884 -73.82764)
		(width 0.0889)
		(layer "In2.Cu")
		(net "CLK_156M_OSC_CPU1_HFI_DP")
	)
	(segment
		(start 133.037834 -56.610504)
		(end 133.031484 -56.599836)
		(width 0.0889)
		(layer "In2.Cu")
		(net "CLK_156M_OSC_CPU1_HFI_DP")
	)
	(segment
		(start 132.173218 -60.657486)
		(end 132.182108 -60.642246)
		(width 0.0889)
		(layer "In2.Cu")
		(net "CLK_156M_OSC_CPU1_HFI_DP")
	)
	(segment
		(start 157.582108 -29.50845)
		(end 157.35046 -29.276802)
		(width 0.1143)
		(layer "In2.Cu")
		(net "CLK_156M_OSC_CPU1_HFI_DP")
	)
	(segment
		(start 138.518138 -54.018434)
		(end 138.550904 -54.018434)
		(width 0.0889)
		(layer "In2.Cu")
		(net "CLK_156M_OSC_CPU1_HFI_DP")
	)
	(segment
		(start 132.173218 -64.619886)
		(end 132.182108 -64.604646)
		(width 0.0889)
		(layer "In2.Cu")
		(net "CLK_156M_OSC_CPU1_HFI_DP")
	)
	(segment
		(start 140.047472 -53.2765)
		(end 140.552932 -52.77104)
		(width 0.0889)
		(layer "In2.Cu")
		(net "CLK_156M_OSC_CPU1_HFI_DP")
	)
	(segment
		(start 157.244542 -36.150804)
		(end 157.244542 -31.007558)
		(width 0.1143)
		(layer "In2.Cu")
		(net "CLK_156M_OSC_CPU1_HFI_DP")
	)
	(segment
		(start 132.173218 -58.67654)
		(end 132.179568 -58.665872)
		(width 0.0889)
		(layer "In2.Cu")
		(net "CLK_156M_OSC_CPU1_HFI_DP")
	)
	(segment
		(start 132.173218 -61.648086)
		(end 132.182108 -61.632846)
		(width 0.0889)
		(layer "In2.Cu")
		(net "CLK_156M_OSC_CPU1_HFI_DP")
	)
	(segment
		(start 135.932164 -55.504334)
		(end 135.975344 -55.504334)
		(width 0.0889)
		(layer "In2.Cu")
		(net "CLK_156M_OSC_CPU1_HFI_DP")
	)
	(segment
		(start 132.173218 -67.591686)
		(end 132.182108 -67.576446)
		(width 0.0889)
		(layer "In2.Cu")
		(net "CLK_156M_OSC_CPU1_HFI_DP")
	)
	(segment
		(start 157.244542 -31.007558)
		(end 157.582108 -30.669992)
		(width 0.1143)
		(layer "In2.Cu")
		(net "CLK_156M_OSC_CPU1_HFI_DP")
	)
	(segment
		(start 132.519674 -57.485534)
		(end 132.541264 -57.485534)
		(width 0.0889)
		(layer "In2.Cu")
		(net "CLK_156M_OSC_CPU1_HFI_DP")
	)
	(segment
		(start 157.35046 -29.276802)
		(end 157.35046 -29.12364)
		(width 0.1143)
		(layer "In2.Cu")
		(net "CLK_156M_OSC_CPU1_HFI_DP")
	)
	(segment
		(start 140.552932 -52.77104)
		(end 140.624052 -52.771294)
		(width 0.0889)
		(layer "In2.Cu")
		(net "CLK_156M_OSC_CPU1_HFI_DP")
	)
	(segment
		(start 132.173218 -57.685686)
		(end 132.17652 -57.679844)
		(width 0.0889)
		(layer "In2.Cu")
		(net "CLK_156M_OSC_CPU1_HFI_DP")
	)
	(segment
		(start 157.582108 -30.669992)
		(end 157.582108 -29.50845)
		(width 0.1143)
		(layer "In2.Cu")
		(net "CLK_156M_OSC_CPU1_HFI_DP")
	)
	(segment
		(start 139.417044 -53.2765)
		(end 140.047472 -53.2765)
		(width 0.0889)
		(layer "In2.Cu")
		(net "CLK_156M_OSC_CPU1_HFI_DP")
	)
	(segment
		(start 130.791712 -73.335134)
		(end 130.824478 -73.335134)
		(width 0.0889)
		(layer "In2.Cu")
		(net "CLK_156M_OSC_CPU1_HFI_DP")
	)
	(segment
		(start 132.173218 -66.601086)
		(end 132.182108 -66.585846)
		(width 0.0889)
		(layer "In2.Cu")
		(net "CLK_156M_OSC_CPU1_HFI_DP")
	)
	(segment
		(start 133.031484 -56.599836)
		(end 133.026658 -56.5912)
		(width 0.0889)
		(layer "In2.Cu")
		(net "CLK_156M_OSC_CPU1_HFI_DP")
	)
	(segment
		(start 129.944368 -74.23023)
		(end 129.944368 -73.892156)
		(width 0.0889)
		(layer "In2.Cu")
		(net "CLK_156M_OSC_CPU1_HFI_DP")
	)
	(segment
		(start 157.35046 -29.12364)
		(end 157.493716 -28.980384)
		(width 0.1143)
		(layer "In2.Cu")
		(net "CLK_156M_OSC_CPU1_HFI_DP")
	)
	(segment
		(start 139.041124 -53.723286)
		(end 139.137644 -53.556154)
		(width 0.0889)
		(layer "In2.Cu")
		(net "CLK_156M_OSC_CPU1_HFI_DP")
	)
	(segment
		(start 136.801098 -55.009034)
		(end 136.833864 -55.009034)
		(width 0.0889)
		(layer "In2.Cu")
		(net "CLK_156M_OSC_CPU1_HFI_DP")
	)
	(segment
		(start 132.173218 -65.610486)
		(end 132.182108 -65.595246)
		(width 0.0889)
		(layer "In2.Cu")
		(net "CLK_156M_OSC_CPU1_HFI_DP")
	)
	(segment
		(start 132.173218 -72.544686)
		(end 132.182108 -72.529446)
		(width 0.0889)
		(layer "In2.Cu")
		(net "CLK_156M_OSC_CPU1_HFI_DP")
	)
	(segment
		(start 140.624052 -52.771294)
		(end 140.639546 -52.7558)
		(width 0.0889)
		(layer "In2.Cu")
		(net "CLK_156M_OSC_CPU1_HFI_DP")
	)
	(arc
		(start 138.550904 -54.018434)
		(mid 138.834121 -53.934153)
		(end 139.041124 -53.723286)
		(width 0.0889)
		(layer "In2.Cu")
		(net "CLK_156M_OSC_CPU1_HFI_DP")
	)
	(arc
		(start 135.441944 -55.209186)
		(mid 135.648948 -55.42005)
		(end 135.932164 -55.504334)
		(width 0.0889)
		(layer "In2.Cu")
		(net "CLK_156M_OSC_CPU1_HFI_DP")
	)
	(arc
		(start 133.395974 -55.999888)
		(mid 133.681398 -55.916421)
		(end 133.890004 -55.704486)
		(width 0.0889)
		(layer "In2.Cu")
		(net "CLK_156M_OSC_CPU1_HFI_DP")
	)
	(arc
		(start 132.173218 -70.563486)
		(mid 132.252349 -70.268084)
		(end 132.173218 -69.972682)
		(width 0.0889)
		(layer "In2.Cu")
		(net "CLK_156M_OSC_CPU1_HFI_DP")
	)
	(arc
		(start 137.688574 -54.513988)
		(mid 137.973998 -54.430521)
		(end 138.182604 -54.218586)
		(width 0.0889)
		(layer "In2.Cu")
		(net "CLK_156M_OSC_CPU1_HFI_DP")
	)
	(arc
		(start 132.173218 -68.982082)
		(mid 132.119685 -68.782184)
		(end 132.173218 -68.582286)
		(width 0.0889)
		(layer "In2.Cu")
		(net "CLK_156M_OSC_CPU1_HFI_DP")
	)
	(arc
		(start 132.173218 -64.029082)
		(mid 132.119685 -63.829184)
		(end 132.173218 -63.629286)
		(width 0.0889)
		(layer "In2.Cu")
		(net "CLK_156M_OSC_CPU1_HFI_DP")
	)
	(arc
		(start 136.465564 -55.209186)
		(mid 136.607247 -55.065382)
		(end 136.801098 -55.009034)
		(width 0.0889)
		(layer "In2.Cu")
		(net "CLK_156M_OSC_CPU1_HFI_DP")
	)
	(arc
		(start 132.182108 -60.642246)
		(mid 132.252505 -60.353295)
		(end 132.173218 -60.066682)
		(width 0.0889)
		(layer "In2.Cu")
		(net "CLK_156M_OSC_CPU1_HFI_DP")
	)
	(arc
		(start 134.748524 -55.209186)
		(mid 134.888603 -55.06645)
		(end 135.080248 -55.009288)
		(width 0.0889)
		(layer "In2.Cu")
		(net "CLK_156M_OSC_CPU1_HFI_DP")
	)
	(arc
		(start 133.031484 -56.199786)
		(mid 133.171563 -56.05705)
		(end 133.363208 -55.999888)
		(width 0.0889)
		(layer "In2.Cu")
		(net "CLK_156M_OSC_CPU1_HFI_DP")
	)
	(arc
		(start 132.173218 -71.953882)
		(mid 132.119685 -71.753984)
		(end 132.173218 -71.554086)
		(width 0.0889)
		(layer "In2.Cu")
		(net "CLK_156M_OSC_CPU1_HFI_DP")
	)
	(arc
		(start 132.173218 -63.038482)
		(mid 132.119685 -62.838584)
		(end 132.173218 -62.638686)
		(width 0.0889)
		(layer "In2.Cu")
		(net "CLK_156M_OSC_CPU1_HFI_DP")
	)
	(arc
		(start 132.173218 -67.000882)
		(mid 132.119685 -66.800984)
		(end 132.173218 -66.601086)
		(width 0.0889)
		(layer "In2.Cu")
		(net "CLK_156M_OSC_CPU1_HFI_DP")
	)
	(arc
		(start 132.182108 -63.614046)
		(mid 132.252505 -63.325095)
		(end 132.173218 -63.038482)
		(width 0.0889)
		(layer "In2.Cu")
		(net "CLK_156M_OSC_CPU1_HFI_DP")
	)
	(arc
		(start 130.029966 -73.824846)
		(mid 130.27631 -73.72899)
		(end 130.456178 -73.535286)
		(width 0.0889)
		(layer "In2.Cu")
		(net "CLK_156M_OSC_CPU1_HFI_DP")
	)
	(arc
		(start 132.173218 -70.963282)
		(mid 132.119685 -70.763384)
		(end 132.173218 -70.563486)
		(width 0.0889)
		(layer "In2.Cu")
		(net "CLK_156M_OSC_CPU1_HFI_DP")
	)
	(arc
		(start 132.173218 -62.047882)
		(mid 132.119685 -61.847984)
		(end 132.173218 -61.648086)
		(width 0.0889)
		(layer "In2.Cu")
		(net "CLK_156M_OSC_CPU1_HFI_DP")
	)
	(arc
		(start 132.173218 -58.085482)
		(mid 132.119685 -57.885584)
		(end 132.173218 -57.685686)
		(width 0.0889)
		(layer "In2.Cu")
		(net "CLK_156M_OSC_CPU1_HFI_DP")
	)
	(arc
		(start 132.173218 -60.066682)
		(mid 132.119685 -59.866784)
		(end 132.173218 -59.666886)
		(width 0.0889)
		(layer "In2.Cu")
		(net "CLK_156M_OSC_CPU1_HFI_DP")
	)
	(arc
		(start 138.182604 -54.218586)
		(mid 138.324287 -54.074782)
		(end 138.518138 -54.018434)
		(width 0.0889)
		(layer "In2.Cu")
		(net "CLK_156M_OSC_CPU1_HFI_DP")
	)
	(arc
		(start 132.182108 -67.576446)
		(mid 132.252505 -67.287495)
		(end 132.173218 -67.000882)
		(width 0.0889)
		(layer "In2.Cu")
		(net "CLK_156M_OSC_CPU1_HFI_DP")
	)
	(arc
		(start 135.975344 -55.504334)
		(mid 136.258561 -55.420053)
		(end 136.465564 -55.209186)
		(width 0.0889)
		(layer "In2.Cu")
		(net "CLK_156M_OSC_CPU1_HFI_DP")
	)
	(arc
		(start 132.182108 -69.557646)
		(mid 132.252505 -69.268695)
		(end 132.173218 -68.982082)
		(width 0.0889)
		(layer "In2.Cu")
		(net "CLK_156M_OSC_CPU1_HFI_DP")
	)
	(arc
		(start 132.17652 -57.679844)
		(mid 132.322486 -57.537445)
		(end 132.519674 -57.485534)
		(width 0.0889)
		(layer "In2.Cu")
		(net "CLK_156M_OSC_CPU1_HFI_DP")
	)
	(arc
		(start 130.456178 -73.535286)
		(mid 130.597861 -73.391482)
		(end 130.791712 -73.335134)
		(width 0.0889)
		(layer "In2.Cu")
		(net "CLK_156M_OSC_CPU1_HFI_DP")
	)
	(arc
		(start 132.173218 -65.019682)
		(mid 132.119685 -64.819784)
		(end 132.173218 -64.619886)
		(width 0.0889)
		(layer "In2.Cu")
		(net "CLK_156M_OSC_CPU1_HFI_DP")
	)
	(arc
		(start 132.173218 -59.666886)
		(mid 132.25244 -59.377768)
		(end 132.179568 -59.087004)
		(width 0.0889)
		(layer "In2.Cu")
		(net "CLK_156M_OSC_CPU1_HFI_DP")
	)
	(arc
		(start 133.890004 -55.704486)
		(mid 134.031687 -55.560682)
		(end 134.225538 -55.504334)
		(width 0.0889)
		(layer "In2.Cu")
		(net "CLK_156M_OSC_CPU1_HFI_DP")
	)
	(arc
		(start 132.173218 -59.076336)
		(mid 132.119685 -58.876438)
		(end 132.173218 -58.67654)
		(width 0.0889)
		(layer "In2.Cu")
		(net "CLK_156M_OSC_CPU1_HFI_DP")
	)
	(arc
		(start 132.173218 -61.057282)
		(mid 132.119685 -60.857384)
		(end 132.173218 -60.657486)
		(width 0.0889)
		(layer "In2.Cu")
		(net "CLK_156M_OSC_CPU1_HFI_DP")
	)
	(arc
		(start 132.173218 -67.991482)
		(mid 132.119685 -67.791584)
		(end 132.173218 -67.591686)
		(width 0.0889)
		(layer "In2.Cu")
		(net "CLK_156M_OSC_CPU1_HFI_DP")
	)
	(arc
		(start 132.173218 -66.010282)
		(mid 132.119685 -65.810384)
		(end 132.173218 -65.610486)
		(width 0.0889)
		(layer "In2.Cu")
		(net "CLK_156M_OSC_CPU1_HFI_DP")
	)
	(arc
		(start 132.182108 -68.567046)
		(mid 132.252505 -68.278095)
		(end 132.173218 -67.991482)
		(width 0.0889)
		(layer "In2.Cu")
		(net "CLK_156M_OSC_CPU1_HFI_DP")
	)
	(arc
		(start 132.182108 -72.529446)
		(mid 132.252505 -72.240495)
		(end 132.173218 -71.953882)
		(width 0.0889)
		(layer "In2.Cu")
		(net "CLK_156M_OSC_CPU1_HFI_DP")
	)
	(arc
		(start 132.182108 -71.538846)
		(mid 132.252505 -71.249895)
		(end 132.173218 -70.963282)
		(width 0.0889)
		(layer "In2.Cu")
		(net "CLK_156M_OSC_CPU1_HFI_DP")
	)
	(arc
		(start 132.179568 -58.665872)
		(mid 132.252488 -58.374855)
		(end 132.173218 -58.085482)
		(width 0.0889)
		(layer "In2.Cu")
		(net "CLK_156M_OSC_CPU1_HFI_DP")
	)
	(arc
		(start 131.314698 -73.039986)
		(mid 131.454777 -72.89725)
		(end 131.646422 -72.840088)
		(width 0.0889)
		(layer "In2.Cu")
		(net "CLK_156M_OSC_CPU1_HFI_DP")
	)
	(arc
		(start 133.031484 -57.190386)
		(mid 133.110706 -56.901268)
		(end 133.037834 -56.610504)
		(width 0.0889)
		(layer "In2.Cu")
		(net "CLK_156M_OSC_CPU1_HFI_DP")
	)
	(arc
		(start 132.173218 -69.972682)
		(mid 132.119685 -69.772784)
		(end 132.173218 -69.572886)
		(width 0.0889)
		(layer "In2.Cu")
		(net "CLK_156M_OSC_CPU1_HFI_DP")
	)
	(arc
		(start 130.008884 -73.82764)
		(mid 130.019438 -73.826338)
		(end 130.029966 -73.824846)
		(width 0.0889)
		(layer "In2.Cu")
		(net "CLK_156M_OSC_CPU1_HFI_DP")
	)
	(arc
		(start 132.182108 -62.623446)
		(mid 132.252505 -62.334495)
		(end 132.173218 -62.047882)
		(width 0.0889)
		(layer "In2.Cu")
		(net "CLK_156M_OSC_CPU1_HFI_DP")
	)
	(arc
		(start 134.258304 -55.504334)
		(mid 134.541521 -55.420053)
		(end 134.748524 -55.209186)
		(width 0.0889)
		(layer "In2.Cu")
		(net "CLK_156M_OSC_CPU1_HFI_DP")
	)
	(arc
		(start 136.833864 -55.009034)
		(mid 137.117081 -54.924753)
		(end 137.324084 -54.713886)
		(width 0.0889)
		(layer "In2.Cu")
		(net "CLK_156M_OSC_CPU1_HFI_DP")
	)
	(arc
		(start 132.182108 -66.585846)
		(mid 132.252505 -66.296895)
		(end 132.173218 -66.010282)
		(width 0.0889)
		(layer "In2.Cu")
		(net "CLK_156M_OSC_CPU1_HFI_DP")
	)
	(arc
		(start 132.182108 -61.632846)
		(mid 132.252505 -61.343895)
		(end 132.173218 -61.057282)
		(width 0.0889)
		(layer "In2.Cu")
		(net "CLK_156M_OSC_CPU1_HFI_DP")
	)
	(arc
		(start 132.182108 -64.604646)
		(mid 132.252505 -64.315695)
		(end 132.173218 -64.029082)
		(width 0.0889)
		(layer "In2.Cu")
		(net "CLK_156M_OSC_CPU1_HFI_DP")
	)
	(arc
		(start 137.324084 -54.713886)
		(mid 137.464163 -54.57115)
		(end 137.655808 -54.513988)
		(width 0.0889)
		(layer "In2.Cu")
		(net "CLK_156M_OSC_CPU1_HFI_DP")
	)
	(arc
		(start 135.11022 -55.009288)
		(mid 135.301862 -55.066454)
		(end 135.441944 -55.209186)
		(width 0.0889)
		(layer "In2.Cu")
		(net "CLK_156M_OSC_CPU1_HFI_DP")
	)
	(arc
		(start 133.026658 -56.5912)
		(mid 132.977903 -56.394848)
		(end 133.031484 -56.199786)
		(width 0.0889)
		(layer "In2.Cu")
		(net "CLK_156M_OSC_CPU1_HFI_DP")
	)
	(arc
		(start 131.679188 -72.840088)
		(mid 131.964612 -72.756621)
		(end 132.173218 -72.544686)
		(width 0.0889)
		(layer "In2.Cu")
		(net "CLK_156M_OSC_CPU1_HFI_DP")
	)
	(arc
		(start 132.541264 -57.485534)
		(mid 132.824481 -57.401253)
		(end 133.031484 -57.190386)
		(width 0.0889)
		(layer "In2.Cu")
		(net "CLK_156M_OSC_CPU1_HFI_DP")
	)
	(arc
		(start 132.182108 -65.595246)
		(mid 132.252505 -65.306295)
		(end 132.173218 -65.019682)
		(width 0.0889)
		(layer "In2.Cu")
		(net "CLK_156M_OSC_CPU1_HFI_DP")
	)
	(arc
		(start 130.824478 -73.335134)
		(mid 131.107695 -73.250853)
		(end 131.314698 -73.039986)
		(width 0.0889)
		(layer "In2.Cu")
		(net "CLK_156M_OSC_CPU1_HFI_DP")
	)
	(segment
		(start 156.8196 -29.4132)
		(end 156.945838 -29.286962)
		(width 0.127)
		(layer "F.Cu")
		(net "CLK_156M_OSC_CPU1_HFI_DN")
	)
	(segment
		(start 156.422852 -28.9306)
		(end 156.017214 -29.336238)
		(width 0.127)
		(layer "F.Cu")
		(net "CLK_156M_OSC_CPU1_HFI_DN")
	)
	(segment
		(start 155.194 -29.463492)
		(end 155.194 -29.6418)
		(width 0.127)
		(layer "F.Cu")
		(net "CLK_156M_OSC_CPU1_HFI_DN")
	)
	(segment
		(start 156.017214 -29.336238)
		(end 155.321254 -29.336238)
		(width 0.127)
		(layer "F.Cu")
		(net "CLK_156M_OSC_CPU1_HFI_DN")
	)
	(segment
		(start 156.945838 -29.05633)
		(end 156.820108 -28.9306)
		(width 0.127)
		(layer "F.Cu")
		(net "CLK_156M_OSC_CPU1_HFI_DN")
	)
	(segment
		(start 156.945838 -29.286962)
		(end 156.945838 -29.05633)
		(width 0.127)
		(layer "F.Cu")
		(net "CLK_156M_OSC_CPU1_HFI_DN")
	)
	(segment
		(start 129.944368 -73.240138)
		(end 129.372868 -73.240138)
		(width 0.127)
		(layer "F.Cu")
		(net "CLK_156M_OSC_CPU1_HFI_DN")
	)
	(segment
		(start 156.820108 -28.9306)
		(end 156.422852 -28.9306)
		(width 0.127)
		(layer "F.Cu")
		(net "CLK_156M_OSC_CPU1_HFI_DN")
	)
	(segment
		(start 155.321254 -29.336238)
		(end 155.194 -29.463492)
		(width 0.127)
		(layer "F.Cu")
		(net "CLK_156M_OSC_CPU1_HFI_DN")
	)
	(via
		(at 156.8196 -29.4132)
		(size 0.508)
		(drill 0.254)
		(layers "F.Cu" "B.Cu")
		(net "CLK_156M_OSC_CPU1_HFI_DN")
	)
	(via
		(at 129.944368 -73.240138)
		(size 0.508)
		(drill 0.254)
		(layers "F.Cu" "B.Cu")
		(net "CLK_156M_OSC_CPU1_HFI_DN")
	)
	(segment
		(start 156.952442 -33.782)
		(end 156.952442 -34.1249)
		(width 0.1143)
		(layer "In2.Cu")
		(net "CLK_156M_OSC_CPU1_HFI_DN")
	)
	(segment
		(start 132.007864 -72.449436)
		(end 132.004562 -72.455278)
		(width 0.0889)
		(layer "In2.Cu")
		(net "CLK_156M_OSC_CPU1_HFI_DN")
	)
	(segment
		(start 139.33805 -53.086)
		(end 138.98499 -53.43906)
		(width 0.0889)
		(layer "In2.Cu")
		(net "CLK_156M_OSC_CPU1_HFI_DN")
	)
	(segment
		(start 138.98499 -53.43906)
		(end 138.876024 -53.628036)
		(width 0.0889)
		(layer "In2.Cu")
		(net "CLK_156M_OSC_CPU1_HFI_DN")
	)
	(segment
		(start 156.800042 -31.6992)
		(end 156.952442 -31.8516)
		(width 0.1143)
		(layer "In2.Cu")
		(net "CLK_156M_OSC_CPU1_HFI_DN")
	)
	(segment
		(start 140.433044 -52.549044)
		(end 140.41755 -52.564538)
		(width 0.0889)
		(layer "In2.Cu")
		(net "CLK_156M_OSC_CPU1_HFI_DN")
	)
	(segment
		(start 132.007864 -67.496436)
		(end 131.998974 -67.511676)
		(width 0.0889)
		(layer "In2.Cu")
		(net "CLK_156M_OSC_CPU1_HFI_DN")
	)
	(segment
		(start 156.800042 -32.3088)
		(end 156.800042 -32.6136)
		(width 0.1143)
		(layer "In2.Cu")
		(net "CLK_156M_OSC_CPU1_HFI_DN")
	)
	(segment
		(start 132.860034 -56.684418)
		(end 132.866384 -56.695086)
		(width 0.0889)
		(layer "In2.Cu")
		(net "CLK_156M_OSC_CPU1_HFI_DN")
	)
	(segment
		(start 130.817874 -73.144634)
		(end 130.785108 -73.144634)
		(width 0.0889)
		(layer "In2.Cu")
		(net "CLK_156M_OSC_CPU1_HFI_DN")
	)
	(segment
		(start 156.8196 -29.4132)
		(end 157.0736 -29.4132)
		(width 0.1143)
		(layer "In2.Cu")
		(net "CLK_156M_OSC_CPU1_HFI_DN")
	)
	(segment
		(start 157.290008 -30.548834)
		(end 156.952442 -30.8864)
		(width 0.1143)
		(layer "In2.Cu")
		(net "CLK_156M_OSC_CPU1_HFI_DN")
	)
	(segment
		(start 132.007864 -60.562236)
		(end 131.998974 -60.577476)
		(width 0.0889)
		(layer "In2.Cu")
		(net "CLK_156M_OSC_CPU1_HFI_DN")
	)
	(segment
		(start 156.952442 -32.766)
		(end 156.952442 -33.1089)
		(width 0.1143)
		(layer "In2.Cu")
		(net "CLK_156M_OSC_CPU1_HFI_DN")
	)
	(segment
		(start 132.007864 -65.515236)
		(end 131.998974 -65.530476)
		(width 0.0889)
		(layer "In2.Cu")
		(net "CLK_156M_OSC_CPU1_HFI_DN")
	)
	(segment
		(start 157.0736 -29.4132)
		(end 157.290008 -29.629608)
		(width 0.1143)
		(layer "In2.Cu")
		(net "CLK_156M_OSC_CPU1_HFI_DN")
	)
	(segment
		(start 156.952442 -32.1564)
		(end 156.800042 -32.3088)
		(width 0.1143)
		(layer "In2.Cu")
		(net "CLK_156M_OSC_CPU1_HFI_DN")
	)
	(segment
		(start 132.007864 -61.552836)
		(end 131.998974 -61.568076)
		(width 0.0889)
		(layer "In2.Cu")
		(net "CLK_156M_OSC_CPU1_HFI_DN")
	)
	(segment
		(start 130.00228 -73.636124)
		(end 129.944368 -73.578212)
		(width 0.0889)
		(layer "In2.Cu")
		(net "CLK_156M_OSC_CPU1_HFI_DN")
	)
	(segment
		(start 132.007864 -69.477636)
		(end 132.001514 -69.488304)
		(width 0.0889)
		(layer "In2.Cu")
		(net "CLK_156M_OSC_CPU1_HFI_DN")
	)
	(segment
		(start 131.661408 -72.649588)
		(end 131.639818 -72.649588)
		(width 0.0889)
		(layer "In2.Cu")
		(net "CLK_156M_OSC_CPU1_HFI_DN")
	)
	(segment
		(start 156.787342 -34.6329)
		(end 156.952442 -34.798)
		(width 0.1143)
		(layer "In2.Cu")
		(net "CLK_156M_OSC_CPU1_HFI_DN")
	)
	(segment
		(start 156.952442 -36.029646)
		(end 140.433044 -52.549044)
		(width 0.1143)
		(layer "In2.Cu")
		(net "CLK_156M_OSC_CPU1_HFI_DN")
	)
	(segment
		(start 132.007864 -63.534036)
		(end 131.998974 -63.549276)
		(width 0.0889)
		(layer "In2.Cu")
		(net "CLK_156M_OSC_CPU1_HFI_DN")
	)
	(segment
		(start 139.968224 -53.086)
		(end 139.33805 -53.086)
		(width 0.0889)
		(layer "In2.Cu")
		(net "CLK_156M_OSC_CPU1_HFI_DN")
	)
	(segment
		(start 132.007864 -57.590436)
		(end 131.998974 -57.605676)
		(width 0.0889)
		(layer "In2.Cu")
		(net "CLK_156M_OSC_CPU1_HFI_DN")
	)
	(segment
		(start 132.007864 -59.571382)
		(end 132.001514 -59.58205)
		(width 0.0889)
		(layer "In2.Cu")
		(net "CLK_156M_OSC_CPU1_HFI_DN")
	)
	(segment
		(start 133.38937 -55.809388)
		(end 133.356604 -55.809388)
		(width 0.0889)
		(layer "In2.Cu")
		(net "CLK_156M_OSC_CPU1_HFI_DN")
	)
	(segment
		(start 156.952442 -31.242)
		(end 156.800042 -31.3944)
		(width 0.1143)
		(layer "In2.Cu")
		(net "CLK_156M_OSC_CPU1_HFI_DN")
	)
	(segment
		(start 156.800042 -31.3944)
		(end 156.800042 -31.6992)
		(width 0.1143)
		(layer "In2.Cu")
		(net "CLK_156M_OSC_CPU1_HFI_DN")
	)
	(segment
		(start 135.116824 -54.818788)
		(end 135.073644 -54.818788)
		(width 0.0889)
		(layer "In2.Cu")
		(net "CLK_156M_OSC_CPU1_HFI_DN")
	)
	(segment
		(start 157.290008 -29.629608)
		(end 157.290008 -30.548834)
		(width 0.1143)
		(layer "In2.Cu")
		(net "CLK_156M_OSC_CPU1_HFI_DN")
	)
	(segment
		(start 156.787342 -33.274)
		(end 156.787342 -33.6169)
		(width 0.1143)
		(layer "In2.Cu")
		(net "CLK_156M_OSC_CPU1_HFI_DN")
	)
	(segment
		(start 132.007864 -62.543436)
		(end 131.998974 -62.558676)
		(width 0.0889)
		(layer "In2.Cu")
		(net "CLK_156M_OSC_CPU1_HFI_DN")
	)
	(segment
		(start 156.952442 -30.8864)
		(end 156.952442 -31.242)
		(width 0.1143)
		(layer "In2.Cu")
		(net "CLK_156M_OSC_CPU1_HFI_DN")
	)
	(segment
		(start 132.001514 -59.160918)
		(end 132.007864 -59.171586)
		(width 0.0889)
		(layer "In2.Cu")
		(net "CLK_156M_OSC_CPU1_HFI_DN")
	)
	(segment
		(start 156.952442 -33.1089)
		(end 156.787342 -33.274)
		(width 0.1143)
		(layer "In2.Cu")
		(net "CLK_156M_OSC_CPU1_HFI_DN")
	)
	(segment
		(start 156.952442 -31.8516)
		(end 156.952442 -32.1564)
		(width 0.1143)
		(layer "In2.Cu")
		(net "CLK_156M_OSC_CPU1_HFI_DN")
	)
	(segment
		(start 132.007864 -71.458836)
		(end 131.998974 -71.474076)
		(width 0.0889)
		(layer "In2.Cu")
		(net "CLK_156M_OSC_CPU1_HFI_DN")
	)
	(segment
		(start 138.54684 -53.827934)
		(end 138.511534 -53.827934)
		(width 0.0889)
		(layer "In2.Cu")
		(net "CLK_156M_OSC_CPU1_HFI_DN")
	)
	(segment
		(start 156.952442 -34.798)
		(end 156.952442 -36.029646)
		(width 0.1143)
		(layer "In2.Cu")
		(net "CLK_156M_OSC_CPU1_HFI_DN")
	)
	(segment
		(start 134.2517 -55.313834)
		(end 134.218934 -55.313834)
		(width 0.0889)
		(layer "In2.Cu")
		(net "CLK_156M_OSC_CPU1_HFI_DN")
	)
	(segment
		(start 135.96874 -55.313834)
		(end 135.938768 -55.313834)
		(width 0.0889)
		(layer "In2.Cu")
		(net "CLK_156M_OSC_CPU1_HFI_DN")
	)
	(segment
		(start 136.82726 -54.818534)
		(end 136.794494 -54.818534)
		(width 0.0889)
		(layer "In2.Cu")
		(net "CLK_156M_OSC_CPU1_HFI_DN")
	)
	(segment
		(start 129.944368 -73.578212)
		(end 129.944368 -73.240138)
		(width 0.0889)
		(layer "In2.Cu")
		(net "CLK_156M_OSC_CPU1_HFI_DN")
	)
	(segment
		(start 132.007864 -68.487036)
		(end 131.998974 -68.502276)
		(width 0.0889)
		(layer "In2.Cu")
		(net "CLK_156M_OSC_CPU1_HFI_DN")
	)
	(segment
		(start 132.53466 -57.295034)
		(end 132.501894 -57.295034)
		(width 0.0889)
		(layer "In2.Cu")
		(net "CLK_156M_OSC_CPU1_HFI_DN")
	)
	(segment
		(start 132.866384 -56.695086)
		(end 132.87121 -56.703722)
		(width 0.0889)
		(layer "In2.Cu")
		(net "CLK_156M_OSC_CPU1_HFI_DN")
	)
	(segment
		(start 140.41755 -52.564538)
		(end 140.41755 -52.636674)
		(width 0.0889)
		(layer "In2.Cu")
		(net "CLK_156M_OSC_CPU1_HFI_DN")
	)
	(segment
		(start 132.007864 -64.524636)
		(end 131.998974 -64.539876)
		(width 0.0889)
		(layer "In2.Cu")
		(net "CLK_156M_OSC_CPU1_HFI_DN")
	)
	(segment
		(start 140.41755 -52.636674)
		(end 139.968224 -53.086)
		(width 0.0889)
		(layer "In2.Cu")
		(net "CLK_156M_OSC_CPU1_HFI_DN")
	)
	(segment
		(start 156.800042 -32.6136)
		(end 156.952442 -32.766)
		(width 0.1143)
		(layer "In2.Cu")
		(net "CLK_156M_OSC_CPU1_HFI_DN")
	)
	(segment
		(start 132.007864 -70.467982)
		(end 132.001514 -70.47865)
		(width 0.0889)
		(layer "In2.Cu")
		(net "CLK_156M_OSC_CPU1_HFI_DN")
	)
	(segment
		(start 137.68197 -54.323488)
		(end 137.649204 -54.323488)
		(width 0.0889)
		(layer "In2.Cu")
		(net "CLK_156M_OSC_CPU1_HFI_DN")
	)
	(segment
		(start 156.787342 -34.29)
		(end 156.787342 -34.6329)
		(width 0.1143)
		(layer "In2.Cu")
		(net "CLK_156M_OSC_CPU1_HFI_DN")
	)
	(segment
		(start 156.787342 -33.6169)
		(end 156.952442 -33.782)
		(width 0.1143)
		(layer "In2.Cu")
		(net "CLK_156M_OSC_CPU1_HFI_DN")
	)
	(segment
		(start 156.952442 -34.1249)
		(end 156.787342 -34.29)
		(width 0.1143)
		(layer "In2.Cu")
		(net "CLK_156M_OSC_CPU1_HFI_DN")
	)
	(segment
		(start 132.007864 -66.505836)
		(end 131.998974 -66.521076)
		(width 0.0889)
		(layer "In2.Cu")
		(net "CLK_156M_OSC_CPU1_HFI_DN")
	)
	(arc
		(start 134.218934 -55.313834)
		(mid 133.93351 -55.397301)
		(end 133.724904 -55.609236)
		(width 0.0889)
		(layer "In2.Cu")
		(net "CLK_156M_OSC_CPU1_HFI_DN")
	)
	(arc
		(start 131.149598 -72.944736)
		(mid 131.009519 -73.087472)
		(end 130.817874 -73.144634)
		(width 0.0889)
		(layer "In2.Cu")
		(net "CLK_156M_OSC_CPU1_HFI_DN")
	)
	(arc
		(start 132.001514 -59.58205)
		(mid 131.928594 -59.873067)
		(end 132.007864 -60.16244)
		(width 0.0889)
		(layer "In2.Cu")
		(net "CLK_156M_OSC_CPU1_HFI_DN")
	)
	(arc
		(start 131.998974 -71.474076)
		(mid 131.928577 -71.763027)
		(end 132.007864 -72.04964)
		(width 0.0889)
		(layer "In2.Cu")
		(net "CLK_156M_OSC_CPU1_HFI_DN")
	)
	(arc
		(start 136.300464 -55.113936)
		(mid 136.160385 -55.256672)
		(end 135.96874 -55.313834)
		(width 0.0889)
		(layer "In2.Cu")
		(net "CLK_156M_OSC_CPU1_HFI_DN")
	)
	(arc
		(start 132.007864 -72.04964)
		(mid 132.061397 -72.249538)
		(end 132.007864 -72.449436)
		(width 0.0889)
		(layer "In2.Cu")
		(net "CLK_156M_OSC_CPU1_HFI_DN")
	)
	(arc
		(start 132.007864 -64.12484)
		(mid 132.061397 -64.324738)
		(end 132.007864 -64.524636)
		(width 0.0889)
		(layer "In2.Cu")
		(net "CLK_156M_OSC_CPU1_HFI_DN")
	)
	(arc
		(start 131.998974 -66.521076)
		(mid 131.928577 -66.810027)
		(end 132.007864 -67.09664)
		(width 0.0889)
		(layer "In2.Cu")
		(net "CLK_156M_OSC_CPU1_HFI_DN")
	)
	(arc
		(start 132.007864 -63.13424)
		(mid 132.061397 -63.334138)
		(end 132.007864 -63.534036)
		(width 0.0889)
		(layer "In2.Cu")
		(net "CLK_156M_OSC_CPU1_HFI_DN")
	)
	(arc
		(start 132.007864 -61.15304)
		(mid 132.061397 -61.352938)
		(end 132.007864 -61.552836)
		(width 0.0889)
		(layer "In2.Cu")
		(net "CLK_156M_OSC_CPU1_HFI_DN")
	)
	(arc
		(start 131.998974 -62.558676)
		(mid 131.928577 -62.847627)
		(end 132.007864 -63.13424)
		(width 0.0889)
		(layer "In2.Cu")
		(net "CLK_156M_OSC_CPU1_HFI_DN")
	)
	(arc
		(start 132.87121 -56.703722)
		(mid 132.919965 -56.900074)
		(end 132.866384 -57.095136)
		(width 0.0889)
		(layer "In2.Cu")
		(net "CLK_156M_OSC_CPU1_HFI_DN")
	)
	(arc
		(start 132.001514 -70.47865)
		(mid 131.928594 -70.769667)
		(end 132.007864 -71.05904)
		(width 0.0889)
		(layer "In2.Cu")
		(net "CLK_156M_OSC_CPU1_HFI_DN")
	)
	(arc
		(start 137.158984 -54.618636)
		(mid 137.018905 -54.761372)
		(end 136.82726 -54.818534)
		(width 0.0889)
		(layer "In2.Cu")
		(net "CLK_156M_OSC_CPU1_HFI_DN")
	)
	(arc
		(start 131.639818 -72.649588)
		(mid 131.356601 -72.733869)
		(end 131.149598 -72.944736)
		(width 0.0889)
		(layer "In2.Cu")
		(net "CLK_156M_OSC_CPU1_HFI_DN")
	)
	(arc
		(start 132.004562 -72.455278)
		(mid 131.858596 -72.597677)
		(end 131.661408 -72.649588)
		(width 0.0889)
		(layer "In2.Cu")
		(net "CLK_156M_OSC_CPU1_HFI_DN")
	)
	(arc
		(start 132.007864 -69.07784)
		(mid 132.061397 -69.277738)
		(end 132.007864 -69.477636)
		(width 0.0889)
		(layer "In2.Cu")
		(net "CLK_156M_OSC_CPU1_HFI_DN")
	)
	(arc
		(start 132.001514 -69.488304)
		(mid 131.928716 -69.779067)
		(end 132.007864 -70.068186)
		(width 0.0889)
		(layer "In2.Cu")
		(net "CLK_156M_OSC_CPU1_HFI_DN")
	)
	(arc
		(start 132.007864 -60.16244)
		(mid 132.061397 -60.362338)
		(end 132.007864 -60.562236)
		(width 0.0889)
		(layer "In2.Cu")
		(net "CLK_156M_OSC_CPU1_HFI_DN")
	)
	(arc
		(start 138.511534 -53.827934)
		(mid 138.22611 -53.911401)
		(end 138.017504 -54.123336)
		(width 0.0889)
		(layer "In2.Cu")
		(net "CLK_156M_OSC_CPU1_HFI_DN")
	)
	(arc
		(start 133.724904 -55.609236)
		(mid 133.583221 -55.75304)
		(end 133.38937 -55.809388)
		(width 0.0889)
		(layer "In2.Cu")
		(net "CLK_156M_OSC_CPU1_HFI_DN")
	)
	(arc
		(start 131.998974 -68.502276)
		(mid 131.928577 -68.791227)
		(end 132.007864 -69.07784)
		(width 0.0889)
		(layer "In2.Cu")
		(net "CLK_156M_OSC_CPU1_HFI_DN")
	)
	(arc
		(start 131.998974 -63.549276)
		(mid 131.928577 -63.838227)
		(end 132.007864 -64.12484)
		(width 0.0889)
		(layer "In2.Cu")
		(net "CLK_156M_OSC_CPU1_HFI_DN")
	)
	(arc
		(start 135.938768 -55.313834)
		(mid 135.747126 -55.256668)
		(end 135.607044 -55.113936)
		(width 0.0889)
		(layer "In2.Cu")
		(net "CLK_156M_OSC_CPU1_HFI_DN")
	)
	(arc
		(start 131.998974 -67.511676)
		(mid 131.928577 -67.800627)
		(end 132.007864 -68.08724)
		(width 0.0889)
		(layer "In2.Cu")
		(net "CLK_156M_OSC_CPU1_HFI_DN")
	)
	(arc
		(start 132.007864 -71.05904)
		(mid 132.061397 -71.258938)
		(end 132.007864 -71.458836)
		(width 0.0889)
		(layer "In2.Cu")
		(net "CLK_156M_OSC_CPU1_HFI_DN")
	)
	(arc
		(start 132.007864 -65.11544)
		(mid 132.061397 -65.315338)
		(end 132.007864 -65.515236)
		(width 0.0889)
		(layer "In2.Cu")
		(net "CLK_156M_OSC_CPU1_HFI_DN")
	)
	(arc
		(start 138.876024 -53.628036)
		(mid 138.737031 -53.770116)
		(end 138.54684 -53.827934)
		(width 0.0889)
		(layer "In2.Cu")
		(net "CLK_156M_OSC_CPU1_HFI_DN")
	)
	(arc
		(start 135.607044 -55.113936)
		(mid 135.40004 -54.903072)
		(end 135.116824 -54.818788)
		(width 0.0889)
		(layer "In2.Cu")
		(net "CLK_156M_OSC_CPU1_HFI_DN")
	)
	(arc
		(start 131.998974 -57.605676)
		(mid 131.928577 -57.894627)
		(end 132.007864 -58.18124)
		(width 0.0889)
		(layer "In2.Cu")
		(net "CLK_156M_OSC_CPU1_HFI_DN")
	)
	(arc
		(start 133.356604 -55.809388)
		(mid 133.073387 -55.893669)
		(end 132.866384 -56.104536)
		(width 0.0889)
		(layer "In2.Cu")
		(net "CLK_156M_OSC_CPU1_HFI_DN")
	)
	(arc
		(start 131.998974 -65.530476)
		(mid 131.928577 -65.819427)
		(end 132.007864 -66.10604)
		(width 0.0889)
		(layer "In2.Cu")
		(net "CLK_156M_OSC_CPU1_HFI_DN")
	)
	(arc
		(start 132.501894 -57.295034)
		(mid 132.21647 -57.378501)
		(end 132.007864 -57.590436)
		(width 0.0889)
		(layer "In2.Cu")
		(net "CLK_156M_OSC_CPU1_HFI_DN")
	)
	(arc
		(start 132.007864 -67.09664)
		(mid 132.061397 -67.296538)
		(end 132.007864 -67.496436)
		(width 0.0889)
		(layer "In2.Cu")
		(net "CLK_156M_OSC_CPU1_HFI_DN")
	)
	(arc
		(start 134.583424 -55.113936)
		(mid 134.443345 -55.256672)
		(end 134.2517 -55.313834)
		(width 0.0889)
		(layer "In2.Cu")
		(net "CLK_156M_OSC_CPU1_HFI_DN")
	)
	(arc
		(start 130.291078 -73.440036)
		(mid 130.169187 -73.571232)
		(end 130.00228 -73.636124)
		(width 0.0889)
		(layer "In2.Cu")
		(net "CLK_156M_OSC_CPU1_HFI_DN")
	)
	(arc
		(start 132.007864 -70.068186)
		(mid 132.061397 -70.268084)
		(end 132.007864 -70.467982)
		(width 0.0889)
		(layer "In2.Cu")
		(net "CLK_156M_OSC_CPU1_HFI_DN")
	)
	(arc
		(start 131.998974 -60.577476)
		(mid 131.928577 -60.866427)
		(end 132.007864 -61.15304)
		(width 0.0889)
		(layer "In2.Cu")
		(net "CLK_156M_OSC_CPU1_HFI_DN")
	)
	(arc
		(start 137.649204 -54.323488)
		(mid 137.365987 -54.407769)
		(end 137.158984 -54.618636)
		(width 0.0889)
		(layer "In2.Cu")
		(net "CLK_156M_OSC_CPU1_HFI_DN")
	)
	(arc
		(start 132.007864 -58.18124)
		(mid 132.061397 -58.381138)
		(end 132.007864 -58.581036)
		(width 0.0889)
		(layer "In2.Cu")
		(net "CLK_156M_OSC_CPU1_HFI_DN")
	)
	(arc
		(start 131.998974 -61.568076)
		(mid 131.928577 -61.857027)
		(end 132.007864 -62.14364)
		(width 0.0889)
		(layer "In2.Cu")
		(net "CLK_156M_OSC_CPU1_HFI_DN")
	)
	(arc
		(start 132.007864 -68.08724)
		(mid 132.061397 -68.287138)
		(end 132.007864 -68.487036)
		(width 0.0889)
		(layer "In2.Cu")
		(net "CLK_156M_OSC_CPU1_HFI_DN")
	)
	(arc
		(start 132.866384 -56.104536)
		(mid 132.787162 -56.393654)
		(end 132.860034 -56.684418)
		(width 0.0889)
		(layer "In2.Cu")
		(net "CLK_156M_OSC_CPU1_HFI_DN")
	)
	(arc
		(start 132.007864 -66.10604)
		(mid 132.061397 -66.305938)
		(end 132.007864 -66.505836)
		(width 0.0889)
		(layer "In2.Cu")
		(net "CLK_156M_OSC_CPU1_HFI_DN")
	)
	(arc
		(start 135.073644 -54.818788)
		(mid 134.790427 -54.903069)
		(end 134.583424 -55.113936)
		(width 0.0889)
		(layer "In2.Cu")
		(net "CLK_156M_OSC_CPU1_HFI_DN")
	)
	(arc
		(start 132.866384 -57.095136)
		(mid 132.726305 -57.237872)
		(end 132.53466 -57.295034)
		(width 0.0889)
		(layer "In2.Cu")
		(net "CLK_156M_OSC_CPU1_HFI_DN")
	)
	(arc
		(start 138.017504 -54.123336)
		(mid 137.875821 -54.26714)
		(end 137.68197 -54.323488)
		(width 0.0889)
		(layer "In2.Cu")
		(net "CLK_156M_OSC_CPU1_HFI_DN")
	)
	(arc
		(start 132.007864 -62.14364)
		(mid 132.061397 -62.343538)
		(end 132.007864 -62.543436)
		(width 0.0889)
		(layer "In2.Cu")
		(net "CLK_156M_OSC_CPU1_HFI_DN")
	)
	(arc
		(start 131.998974 -64.539876)
		(mid 131.928577 -64.828827)
		(end 132.007864 -65.11544)
		(width 0.0889)
		(layer "In2.Cu")
		(net "CLK_156M_OSC_CPU1_HFI_DN")
	)
	(arc
		(start 132.007864 -58.581036)
		(mid 131.928642 -58.870154)
		(end 132.001514 -59.160918)
		(width 0.0889)
		(layer "In2.Cu")
		(net "CLK_156M_OSC_CPU1_HFI_DN")
	)
	(arc
		(start 130.785108 -73.144634)
		(mid 130.499684 -73.228101)
		(end 130.291078 -73.440036)
		(width 0.0889)
		(layer "In2.Cu")
		(net "CLK_156M_OSC_CPU1_HFI_DN")
	)
	(arc
		(start 132.007864 -59.171586)
		(mid 132.061397 -59.371484)
		(end 132.007864 -59.571382)
		(width 0.0889)
		(layer "In2.Cu")
		(net "CLK_156M_OSC_CPU1_HFI_DN")
	)
	(arc
		(start 136.794494 -54.818534)
		(mid 136.50907 -54.902001)
		(end 136.300464 -55.113936)
		(width 0.0889)
		(layer "In2.Cu")
		(net "CLK_156M_OSC_CPU1_HFI_DN")
	)
	(segment
		(start 319.4939 -28.9179)
		(end 319.476882 -28.934918)
		(width 0.127)
		(layer "F.Cu")
		(net "CLK_156M_OSC_CPU0_HFI_DP")
	)
	(segment
		(start 319.476882 -28.934918)
		(end 318.8716 -28.934918)
		(width 0.127)
		(layer "F.Cu")
		(net "CLK_156M_OSC_CPU0_HFI_DP")
	)
	(segment
		(start 294.3733 -74.230738)
		(end 294.9448 -74.230738)
		(width 0.127)
		(layer "F.Cu")
		(net "CLK_156M_OSC_CPU0_HFI_DP")
	)
	(via
		(at 294.9448 -74.230738)
		(size 0.508)
		(drill 0.254)
		(layers "F.Cu" "B.Cu")
		(net "CLK_156M_OSC_CPU0_HFI_DP")
	)
	(via
		(at 319.4939 -28.9179)
		(size 0.508)
		(drill 0.254)
		(layers "F.Cu" "B.Cu")
		(net "CLK_156M_OSC_CPU0_HFI_DP")
	)
	(segment
		(start 322.2244 -32.82569)
		(end 321.0433 -31.64459)
		(width 0.1143)
		(layer "In4.Cu")
		(net "CLK_156M_OSC_CPU0_HFI_DP")
	)
	(segment
		(start 295.45661 -69.572886)
		(end 295.46296 -69.562218)
		(width 0.0889)
		(layer "In4.Cu")
		(net "CLK_156M_OSC_CPU0_HFI_DP")
	)
	(segment
		(start 321.4751 -34.7853)
		(end 322.2244 -34.036)
		(width 0.1143)
		(layer "In4.Cu")
		(net "CLK_156M_OSC_CPU0_HFI_DP")
	)
	(segment
		(start 296.31513 -63.534036)
		(end 296.310304 -63.5254)
		(width 0.0889)
		(layer "In4.Cu")
		(net "CLK_156M_OSC_CPU0_HFI_DP")
	)
	(segment
		(start 296.31513 -56.599836)
		(end 296.310304 -56.5912)
		(width 0.0889)
		(layer "In4.Cu")
		(net "CLK_156M_OSC_CPU0_HFI_DP")
	)
	(segment
		(start 296.31513 -57.590436)
		(end 296.310304 -57.5818)
		(width 0.0889)
		(layer "In4.Cu")
		(net "CLK_156M_OSC_CPU0_HFI_DP")
	)
	(segment
		(start 300.686978 -51.643026)
		(end 300.997366 -51.138582)
		(width 0.0889)
		(layer "In4.Cu")
		(net "CLK_156M_OSC_CPU0_HFI_DP")
	)
	(segment
		(start 296.32148 -61.563504)
		(end 296.31513 -61.552836)
		(width 0.0889)
		(layer "In4.Cu")
		(net "CLK_156M_OSC_CPU0_HFI_DP")
	)
	(segment
		(start 296.32148 -60.572904)
		(end 296.31513 -60.562236)
		(width 0.0889)
		(layer "In4.Cu")
		(net "CLK_156M_OSC_CPU0_HFI_DP")
	)
	(segment
		(start 295.451784 -68.590922)
		(end 295.45661 -68.582286)
		(width 0.0889)
		(layer "In4.Cu")
		(net "CLK_156M_OSC_CPU0_HFI_DP")
	)
	(segment
		(start 303.9364 -49.2506)
		(end 306.197 -46.99)
		(width 0.1143)
		(layer "In4.Cu")
		(net "CLK_156M_OSC_CPU0_HFI_DP")
	)
	(segment
		(start 317.951358 -36.3601)
		(end 318.401446 -36.3601)
		(width 0.1143)
		(layer "In4.Cu")
		(net "CLK_156M_OSC_CPU0_HFI_DP")
	)
	(segment
		(start 295.820592 -65.972436)
		(end 296.315384 -65.115186)
		(width 0.0889)
		(layer "In4.Cu")
		(net "CLK_156M_OSC_CPU0_HFI_DP")
	)
	(segment
		(start 303.60874 -49.578514)
		(end 303.9364 -49.250854)
		(width 0.1143)
		(layer "In4.Cu")
		(net "CLK_156M_OSC_CPU0_HFI_DP")
	)
	(segment
		(start 296.32148 -64.536066)
		(end 296.319194 -64.531748)
		(width 0.0889)
		(layer "In4.Cu")
		(net "CLK_156M_OSC_CPU0_HFI_DP")
	)
	(segment
		(start 301.366174 -50.92954)
		(end 302.18507 -50.92954)
		(width 0.0889)
		(layer "In4.Cu")
		(net "CLK_156M_OSC_CPU0_HFI_DP")
	)
	(segment
		(start 295.451784 -71.562722)
		(end 295.45661 -71.554086)
		(width 0.0889)
		(layer "In4.Cu")
		(net "CLK_156M_OSC_CPU0_HFI_DP")
	)
	(segment
		(start 296.31513 -62.543436)
		(end 296.310304 -62.5348)
		(width 0.0889)
		(layer "In4.Cu")
		(net "CLK_156M_OSC_CPU0_HFI_DP")
	)
	(segment
		(start 298.360592 -53.028088)
		(end 298.400216 -53.028088)
		(width 0.0889)
		(layer "In4.Cu")
		(net "CLK_156M_OSC_CPU0_HFI_DP")
	)
	(segment
		(start 300.08068 -52.037488)
		(end 300.113446 -52.037488)
		(width 0.0889)
		(layer "In4.Cu")
		(net "CLK_156M_OSC_CPU0_HFI_DP")
	)
	(segment
		(start 296.319194 -64.531748)
		(end 296.310304 -64.516)
		(width 0.0889)
		(layer "In4.Cu")
		(net "CLK_156M_OSC_CPU0_HFI_DP")
	)
	(segment
		(start 295.535604 -67.854322)
		(end 295.820592 -67.569334)
		(width 0.0889)
		(layer "In4.Cu")
		(net "CLK_156M_OSC_CPU0_HFI_DP")
	)
	(segment
		(start 306.197 -46.99)
		(end 306.197 -46.0502)
		(width 0.1143)
		(layer "In4.Cu")
		(net "CLK_156M_OSC_CPU0_HFI_DP")
	)
	(segment
		(start 303.9364 -49.250854)
		(end 303.9364 -49.2506)
		(width 0.1143)
		(layer "In4.Cu")
		(net "CLK_156M_OSC_CPU0_HFI_DP")
	)
	(segment
		(start 296.32148 -54.629304)
		(end 296.31513 -54.618636)
		(width 0.0889)
		(layer "In4.Cu")
		(net "CLK_156M_OSC_CPU0_HFI_DP")
	)
	(segment
		(start 322.2244 -34.036)
		(end 322.2244 -32.82569)
		(width 0.1143)
		(layer "In4.Cu")
		(net "CLK_156M_OSC_CPU0_HFI_DP")
	)
	(segment
		(start 306.197 -46.0502)
		(end 313.817 -38.4302)
		(width 0.1143)
		(layer "In4.Cu")
		(net "CLK_156M_OSC_CPU0_HFI_DP")
	)
	(segment
		(start 299.22597 -52.532788)
		(end 299.2501 -52.532788)
		(width 0.0889)
		(layer "In4.Cu")
		(net "CLK_156M_OSC_CPU0_HFI_DP")
	)
	(segment
		(start 318.401446 -36.3601)
		(end 319.976246 -34.7853)
		(width 0.1143)
		(layer "In4.Cu")
		(net "CLK_156M_OSC_CPU0_HFI_DP")
	)
	(segment
		(start 296.32148 -62.554104)
		(end 296.31513 -62.543436)
		(width 0.0889)
		(layer "In4.Cu")
		(net "CLK_156M_OSC_CPU0_HFI_DP")
	)
	(segment
		(start 295.451784 -70.572122)
		(end 295.45661 -70.563486)
		(width 0.0889)
		(layer "In4.Cu")
		(net "CLK_156M_OSC_CPU0_HFI_DP")
	)
	(segment
		(start 296.32148 -63.544704)
		(end 296.31513 -63.534036)
		(width 0.0889)
		(layer "In4.Cu")
		(net "CLK_156M_OSC_CPU0_HFI_DP")
	)
	(segment
		(start 302.18507 -50.92954)
		(end 302.934116 -50.180494)
		(width 0.0889)
		(layer "In4.Cu")
		(net "CLK_156M_OSC_CPU0_HFI_DP")
	)
	(segment
		(start 300.997366 -51.138582)
		(end 301.366174 -50.92954)
		(width 0.0889)
		(layer "In4.Cu")
		(net "CLK_156M_OSC_CPU0_HFI_DP")
	)
	(segment
		(start 295.820592 -67.569334)
		(end 295.820592 -65.972436)
		(width 0.0889)
		(layer "In4.Cu")
		(net "CLK_156M_OSC_CPU0_HFI_DP")
	)
	(segment
		(start 296.31513 -58.581036)
		(end 296.310304 -58.5724)
		(width 0.0889)
		(layer "In4.Cu")
		(net "CLK_156M_OSC_CPU0_HFI_DP")
	)
	(segment
		(start 313.817 -38.4302)
		(end 315.881258 -38.4302)
		(width 0.1143)
		(layer "In4.Cu")
		(net "CLK_156M_OSC_CPU0_HFI_DP")
	)
	(segment
		(start 297.507914 -53.523388)
		(end 297.537886 -53.523388)
		(width 0.0889)
		(layer "In4.Cu")
		(net "CLK_156M_OSC_CPU0_HFI_DP")
	)
	(segment
		(start 320.583306 -29.136848)
		(end 319.712848 -29.136848)
		(width 0.1143)
		(layer "In4.Cu")
		(net "CLK_156M_OSC_CPU0_HFI_DP")
	)
	(segment
		(start 296.32148 -55.619904)
		(end 296.31513 -55.609236)
		(width 0.0889)
		(layer "In4.Cu")
		(net "CLK_156M_OSC_CPU0_HFI_DP")
	)
	(segment
		(start 319.976246 -34.7853)
		(end 321.4751 -34.7853)
		(width 0.1143)
		(layer "In4.Cu")
		(net "CLK_156M_OSC_CPU0_HFI_DP")
	)
	(segment
		(start 296.32148 -57.601104)
		(end 296.31513 -57.590436)
		(width 0.0889)
		(layer "In4.Cu")
		(net "CLK_156M_OSC_CPU0_HFI_DP")
	)
	(segment
		(start 295.45661 -73.535286)
		(end 295.46296 -73.524618)
		(width 0.0889)
		(layer "In4.Cu")
		(net "CLK_156M_OSC_CPU0_HFI_DP")
	)
	(segment
		(start 302.934116 -50.180494)
		(end 303.006506 -50.180494)
		(width 0.0889)
		(layer "In4.Cu")
		(net "CLK_156M_OSC_CPU0_HFI_DP")
	)
	(segment
		(start 295.535604 -68.287138)
		(end 295.535604 -67.854322)
		(width 0.0889)
		(layer "In4.Cu")
		(net "CLK_156M_OSC_CPU0_HFI_DP")
	)
	(segment
		(start 303.022 -50.165)
		(end 303.60874 -49.578514)
		(width 0.1143)
		(layer "In4.Cu")
		(net "CLK_156M_OSC_CPU0_HFI_DP")
	)
	(segment
		(start 296.31513 -60.562236)
		(end 296.310304 -60.5536)
		(width 0.0889)
		(layer "In4.Cu")
		(net "CLK_156M_OSC_CPU0_HFI_DP")
	)
	(segment
		(start 296.322242 -64.537336)
		(end 296.32148 -64.536066)
		(width 0.0889)
		(layer "In4.Cu")
		(net "CLK_156M_OSC_CPU0_HFI_DP")
	)
	(segment
		(start 294.9448 -74.230738)
		(end 294.9448 -73.892664)
		(width 0.0889)
		(layer "In4.Cu")
		(net "CLK_156M_OSC_CPU0_HFI_DP")
	)
	(segment
		(start 296.31513 -59.171586)
		(end 296.32148 -59.160918)
		(width 0.0889)
		(layer "In4.Cu")
		(net "CLK_156M_OSC_CPU0_HFI_DP")
	)
	(segment
		(start 321.0433 -31.64459)
		(end 321.0433 -29.596842)
		(width 0.1143)
		(layer "In4.Cu")
		(net "CLK_156M_OSC_CPU0_HFI_DP")
	)
	(segment
		(start 296.31513 -54.618636)
		(end 296.310304 -54.61)
		(width 0.0889)
		(layer "In4.Cu")
		(net "CLK_156M_OSC_CPU0_HFI_DP")
	)
	(segment
		(start 315.881258 -38.4302)
		(end 317.951358 -36.3601)
		(width 0.1143)
		(layer "In4.Cu")
		(net "CLK_156M_OSC_CPU0_HFI_DP")
	)
	(segment
		(start 296.32148 -56.610504)
		(end 296.31513 -56.599836)
		(width 0.0889)
		(layer "In4.Cu")
		(net "CLK_156M_OSC_CPU0_HFI_DP")
	)
	(segment
		(start 321.0433 -29.596842)
		(end 320.583306 -29.136848)
		(width 0.1143)
		(layer "In4.Cu")
		(net "CLK_156M_OSC_CPU0_HFI_DP")
	)
	(segment
		(start 295.45661 -71.554086)
		(end 295.46296 -71.543418)
		(width 0.0889)
		(layer "In4.Cu")
		(net "CLK_156M_OSC_CPU0_HFI_DP")
	)
	(segment
		(start 303.006506 -50.180494)
		(end 303.022 -50.165)
		(width 0.0889)
		(layer "In4.Cu")
		(net "CLK_156M_OSC_CPU0_HFI_DP")
	)
	(segment
		(start 295.45661 -72.544686)
		(end 295.46296 -72.534018)
		(width 0.0889)
		(layer "In4.Cu")
		(net "CLK_156M_OSC_CPU0_HFI_DP")
	)
	(segment
		(start 296.646854 -54.018688)
		(end 296.674794 -54.018688)
		(width 0.0889)
		(layer "In4.Cu")
		(net "CLK_156M_OSC_CPU0_HFI_DP")
	)
	(segment
		(start 296.31513 -61.552836)
		(end 296.310304 -61.5442)
		(width 0.0889)
		(layer "In4.Cu")
		(net "CLK_156M_OSC_CPU0_HFI_DP")
	)
	(segment
		(start 295.451784 -72.553322)
		(end 295.45661 -72.544686)
		(width 0.0889)
		(layer "In4.Cu")
		(net "CLK_156M_OSC_CPU0_HFI_DP")
	)
	(segment
		(start 294.9448 -73.892664)
		(end 295.010078 -73.827386)
		(width 0.0889)
		(layer "In4.Cu")
		(net "CLK_156M_OSC_CPU0_HFI_DP")
	)
	(segment
		(start 300.67123 -51.658774)
		(end 300.686978 -51.643026)
		(width 0.0889)
		(layer "In4.Cu")
		(net "CLK_156M_OSC_CPU0_HFI_DP")
	)
	(segment
		(start 296.31513 -55.609236)
		(end 296.310304 -55.6006)
		(width 0.0889)
		(layer "In4.Cu")
		(net "CLK_156M_OSC_CPU0_HFI_DP")
	)
	(segment
		(start 319.712848 -29.136848)
		(end 319.4939 -28.9179)
		(width 0.1143)
		(layer "In4.Cu")
		(net "CLK_156M_OSC_CPU0_HFI_DP")
	)
	(arc
		(start 296.31513 -58.180986)
		(mid 296.394352 -57.891868)
		(end 296.32148 -57.601104)
		(width 0.0889)
		(layer "In4.Cu")
		(net "CLK_156M_OSC_CPU0_HFI_DP")
	)
	(arc
		(start 295.45661 -68.982336)
		(mid 295.40314 -68.787273)
		(end 295.451784 -68.590922)
		(width 0.0889)
		(layer "In4.Cu")
		(net "CLK_156M_OSC_CPU0_HFI_DP")
	)
	(arc
		(start 295.45661 -69.972682)
		(mid 295.403111 -69.772784)
		(end 295.45661 -69.572886)
		(width 0.0889)
		(layer "In4.Cu")
		(net "CLK_156M_OSC_CPU0_HFI_DP")
	)
	(arc
		(start 296.32148 -59.160918)
		(mid 296.394278 -58.870155)
		(end 296.31513 -58.581036)
		(width 0.0889)
		(layer "In4.Cu")
		(net "CLK_156M_OSC_CPU0_HFI_DP")
	)
	(arc
		(start 295.45661 -71.954136)
		(mid 295.40314 -71.759073)
		(end 295.451784 -71.562722)
		(width 0.0889)
		(layer "In4.Cu")
		(net "CLK_156M_OSC_CPU0_HFI_DP")
	)
	(arc
		(start 295.46296 -69.562218)
		(mid 295.535758 -69.271455)
		(end 295.45661 -68.982336)
		(width 0.0889)
		(layer "In4.Cu")
		(net "CLK_156M_OSC_CPU0_HFI_DP")
	)
	(arc
		(start 296.310304 -63.5254)
		(mid 296.261549 -63.329048)
		(end 296.31513 -63.133986)
		(width 0.0889)
		(layer "In4.Cu")
		(net "CLK_156M_OSC_CPU0_HFI_DP")
	)
	(arc
		(start 295.46296 -73.524618)
		(mid 295.535758 -73.233855)
		(end 295.45661 -72.944736)
		(width 0.0889)
		(layer "In4.Cu")
		(net "CLK_156M_OSC_CPU0_HFI_DP")
	)
	(arc
		(start 299.748956 -52.237386)
		(mid 299.889035 -52.09465)
		(end 300.08068 -52.037488)
		(width 0.0889)
		(layer "In4.Cu")
		(net "CLK_156M_OSC_CPU0_HFI_DP")
	)
	(arc
		(start 296.310304 -61.5442)
		(mid 296.261549 -61.347848)
		(end 296.31513 -61.152786)
		(width 0.0889)
		(layer "In4.Cu")
		(net "CLK_156M_OSC_CPU0_HFI_DP")
	)
	(arc
		(start 296.31513 -55.209186)
		(mid 296.394352 -54.920068)
		(end 296.32148 -54.629304)
		(width 0.0889)
		(layer "In4.Cu")
		(net "CLK_156M_OSC_CPU0_HFI_DP")
	)
	(arc
		(start 296.310304 -60.5536)
		(mid 296.261549 -60.357248)
		(end 296.31513 -60.162186)
		(width 0.0889)
		(layer "In4.Cu")
		(net "CLK_156M_OSC_CPU0_HFI_DP")
	)
	(arc
		(start 298.031916 -53.227986)
		(mid 298.17066 -53.085953)
		(end 298.360592 -53.028088)
		(width 0.0889)
		(layer "In4.Cu")
		(net "CLK_156M_OSC_CPU0_HFI_DP")
	)
	(arc
		(start 296.310304 -54.61)
		(mid 296.261549 -54.413648)
		(end 296.31513 -54.218586)
		(width 0.0889)
		(layer "In4.Cu")
		(net "CLK_156M_OSC_CPU0_HFI_DP")
	)
	(arc
		(start 296.31513 -54.218586)
		(mid 296.455209 -54.07585)
		(end 296.646854 -54.018688)
		(width 0.0889)
		(layer "In4.Cu")
		(net "CLK_156M_OSC_CPU0_HFI_DP")
	)
	(arc
		(start 295.45661 -70.963536)
		(mid 295.40314 -70.768473)
		(end 295.451784 -70.572122)
		(width 0.0889)
		(layer "In4.Cu")
		(net "CLK_156M_OSC_CPU0_HFI_DP")
	)
	(arc
		(start 296.310304 -58.5724)
		(mid 296.261549 -58.376048)
		(end 296.31513 -58.180986)
		(width 0.0889)
		(layer "In4.Cu")
		(net "CLK_156M_OSC_CPU0_HFI_DP")
	)
	(arc
		(start 295.46296 -71.543418)
		(mid 295.535758 -71.252655)
		(end 295.45661 -70.963536)
		(width 0.0889)
		(layer "In4.Cu")
		(net "CLK_156M_OSC_CPU0_HFI_DP")
	)
	(arc
		(start 298.890436 -52.73294)
		(mid 299.032119 -52.589136)
		(end 299.22597 -52.532788)
		(width 0.0889)
		(layer "In4.Cu")
		(net "CLK_156M_OSC_CPU0_HFI_DP")
	)
	(arc
		(start 296.31513 -64.124586)
		(mid 296.394352 -63.835468)
		(end 296.32148 -63.544704)
		(width 0.0889)
		(layer "In4.Cu")
		(net "CLK_156M_OSC_CPU0_HFI_DP")
	)
	(arc
		(start 296.31513 -59.571382)
		(mid 296.261631 -59.371484)
		(end 296.31513 -59.171586)
		(width 0.0889)
		(layer "In4.Cu")
		(net "CLK_156M_OSC_CPU0_HFI_DP")
	)
	(arc
		(start 296.31513 -56.199786)
		(mid 296.394352 -55.910668)
		(end 296.32148 -55.619904)
		(width 0.0889)
		(layer "In4.Cu")
		(net "CLK_156M_OSC_CPU0_HFI_DP")
	)
	(arc
		(start 295.46296 -72.534018)
		(mid 295.535758 -72.243255)
		(end 295.45661 -71.954136)
		(width 0.0889)
		(layer "In4.Cu")
		(net "CLK_156M_OSC_CPU0_HFI_DP")
	)
	(arc
		(start 296.315384 -65.115186)
		(mid 296.394312 -64.827144)
		(end 296.322242 -64.537336)
		(width 0.0889)
		(layer "In4.Cu")
		(net "CLK_156M_OSC_CPU0_HFI_DP")
	)
	(arc
		(start 296.310304 -64.516)
		(mid 296.261549 -64.319648)
		(end 296.31513 -64.124586)
		(width 0.0889)
		(layer "In4.Cu")
		(net "CLK_156M_OSC_CPU0_HFI_DP")
	)
	(arc
		(start 299.2501 -52.532788)
		(mid 299.538245 -52.450469)
		(end 299.748956 -52.237386)
		(width 0.0889)
		(layer "In4.Cu")
		(net "CLK_156M_OSC_CPU0_HFI_DP")
	)
	(arc
		(start 300.113446 -52.037488)
		(mid 300.39887 -51.954021)
		(end 300.607476 -51.742086)
		(width 0.0889)
		(layer "In4.Cu")
		(net "CLK_156M_OSC_CPU0_HFI_DP")
	)
	(arc
		(start 296.310304 -55.6006)
		(mid 296.261549 -55.404248)
		(end 296.31513 -55.209186)
		(width 0.0889)
		(layer "In4.Cu")
		(net "CLK_156M_OSC_CPU0_HFI_DP")
	)
	(arc
		(start 296.674794 -54.018688)
		(mid 296.962939 -53.936369)
		(end 297.17365 -53.723286)
		(width 0.0889)
		(layer "In4.Cu")
		(net "CLK_156M_OSC_CPU0_HFI_DP")
	)
	(arc
		(start 296.31513 -60.162186)
		(mid 296.394261 -59.866784)
		(end 296.31513 -59.571382)
		(width 0.0889)
		(layer "In4.Cu")
		(net "CLK_156M_OSC_CPU0_HFI_DP")
	)
	(arc
		(start 295.010078 -73.827386)
		(mid 295.268215 -73.734632)
		(end 295.45661 -73.535286)
		(width 0.0889)
		(layer "In4.Cu")
		(net "CLK_156M_OSC_CPU0_HFI_DP")
	)
	(arc
		(start 295.45661 -68.582286)
		(mid 295.515522 -68.439907)
		(end 295.535604 -68.287138)
		(width 0.0889)
		(layer "In4.Cu")
		(net "CLK_156M_OSC_CPU0_HFI_DP")
	)
	(arc
		(start 295.45661 -70.563486)
		(mid 295.535741 -70.268084)
		(end 295.45661 -69.972682)
		(width 0.0889)
		(layer "In4.Cu")
		(net "CLK_156M_OSC_CPU0_HFI_DP")
	)
	(arc
		(start 296.31513 -63.133986)
		(mid 296.394352 -62.844868)
		(end 296.32148 -62.554104)
		(width 0.0889)
		(layer "In4.Cu")
		(net "CLK_156M_OSC_CPU0_HFI_DP")
	)
	(arc
		(start 297.537886 -53.523388)
		(mid 297.82331 -53.439921)
		(end 298.031916 -53.227986)
		(width 0.0889)
		(layer "In4.Cu")
		(net "CLK_156M_OSC_CPU0_HFI_DP")
	)
	(arc
		(start 296.310304 -62.5348)
		(mid 296.261549 -62.338448)
		(end 296.31513 -62.143386)
		(width 0.0889)
		(layer "In4.Cu")
		(net "CLK_156M_OSC_CPU0_HFI_DP")
	)
	(arc
		(start 297.17365 -53.723286)
		(mid 297.314807 -53.579901)
		(end 297.507914 -53.523388)
		(width 0.0889)
		(layer "In4.Cu")
		(net "CLK_156M_OSC_CPU0_HFI_DP")
	)
	(arc
		(start 298.400216 -53.028088)
		(mid 298.683433 -52.943807)
		(end 298.890436 -52.73294)
		(width 0.0889)
		(layer "In4.Cu")
		(net "CLK_156M_OSC_CPU0_HFI_DP")
	)
	(arc
		(start 296.310304 -56.5912)
		(mid 296.261549 -56.394848)
		(end 296.31513 -56.199786)
		(width 0.0889)
		(layer "In4.Cu")
		(net "CLK_156M_OSC_CPU0_HFI_DP")
	)
	(arc
		(start 300.645068 -51.687984)
		(mid 300.657787 -51.673054)
		(end 300.67123 -51.658774)
		(width 0.0889)
		(layer "In4.Cu")
		(net "CLK_156M_OSC_CPU0_HFI_DP")
	)
	(arc
		(start 300.607476 -51.742086)
		(mid 300.625154 -51.714258)
		(end 300.645068 -51.687984)
		(width 0.0889)
		(layer "In4.Cu")
		(net "CLK_156M_OSC_CPU0_HFI_DP")
	)
	(arc
		(start 296.31513 -57.190386)
		(mid 296.394352 -56.901268)
		(end 296.32148 -56.610504)
		(width 0.0889)
		(layer "In4.Cu")
		(net "CLK_156M_OSC_CPU0_HFI_DP")
	)
	(arc
		(start 296.310304 -57.5818)
		(mid 296.261549 -57.385448)
		(end 296.31513 -57.190386)
		(width 0.0889)
		(layer "In4.Cu")
		(net "CLK_156M_OSC_CPU0_HFI_DP")
	)
	(arc
		(start 296.31513 -62.143386)
		(mid 296.394352 -61.854268)
		(end 296.32148 -61.563504)
		(width 0.0889)
		(layer "In4.Cu")
		(net "CLK_156M_OSC_CPU0_HFI_DP")
	)
	(arc
		(start 295.45661 -72.944736)
		(mid 295.40314 -72.749673)
		(end 295.451784 -72.553322)
		(width 0.0889)
		(layer "In4.Cu")
		(net "CLK_156M_OSC_CPU0_HFI_DP")
	)
	(arc
		(start 296.31513 -61.152786)
		(mid 296.394352 -60.863668)
		(end 296.32148 -60.572904)
		(width 0.0889)
		(layer "In4.Cu")
		(net "CLK_156M_OSC_CPU0_HFI_DP")
	)
	(segment
		(start 318.8716 -29.696918)
		(end 319.485518 -29.696918)
		(width 0.127)
		(layer "F.Cu")
		(net "CLK_156M_OSC_CPU0_HFI_DN")
	)
	(segment
		(start 319.485518 -29.696918)
		(end 319.4939 -29.7053)
		(width 0.127)
		(layer "F.Cu")
		(net "CLK_156M_OSC_CPU0_HFI_DN")
	)
	(segment
		(start 294.3733 -73.240138)
		(end 294.9448 -73.240138)
		(width 0.127)
		(layer "F.Cu")
		(net "CLK_156M_OSC_CPU0_HFI_DN")
	)
	(via
		(at 319.4939 -29.7053)
		(size 0.508)
		(drill 0.254)
		(layers "F.Cu" "B.Cu")
		(net "CLK_156M_OSC_CPU0_HFI_DN")
	)
	(via
		(at 294.9448 -73.240138)
		(size 0.508)
		(drill 0.254)
		(layers "F.Cu" "B.Cu")
		(net "CLK_156M_OSC_CPU0_HFI_DN")
	)
	(segment
		(start 295.630092 -67.49034)
		(end 295.630092 -65.921382)
		(width 0.0889)
		(layer "In4.Cu")
		(net "CLK_156M_OSC_CPU0_HFI_DN")
	)
	(segment
		(start 296.15003 -60.657486)
		(end 296.14368 -60.646818)
		(width 0.0889)
		(layer "In4.Cu")
		(net "CLK_156M_OSC_CPU0_HFI_DN")
	)
	(segment
		(start 296.154856 -55.713122)
		(end 296.15003 -55.704486)
		(width 0.0889)
		(layer "In4.Cu")
		(net "CLK_156M_OSC_CPU0_HFI_DN")
	)
	(segment
		(start 301.315882 -50.73904)
		(end 302.106076 -50.73904)
		(width 0.0889)
		(layer "In4.Cu")
		(net "CLK_156M_OSC_CPU0_HFI_DN")
	)
	(segment
		(start 320.7512 -29.718)
		(end 320.462148 -29.428948)
		(width 0.1143)
		(layer "In4.Cu")
		(net "CLK_156M_OSC_CPU0_HFI_DN")
	)
	(segment
		(start 302.608996 -50.23612)
		(end 302.800004 -50.045112)
		(width 0.0889)
		(layer "In4.Cu")
		(net "CLK_156M_OSC_CPU0_HFI_DN")
	)
	(segment
		(start 296.648886 -53.827934)
		(end 296.66184 -53.827934)
		(width 0.0889)
		(layer "In4.Cu")
		(net "CLK_156M_OSC_CPU0_HFI_DN")
	)
	(segment
		(start 295.29151 -72.449436)
		(end 295.296336 -72.4408)
		(width 0.0889)
		(layer "In4.Cu")
		(net "CLK_156M_OSC_CPU0_HFI_DN")
	)
	(segment
		(start 318.280288 -36.068)
		(end 319.136776 -35.211512)
		(width 0.1143)
		(layer "In4.Cu")
		(net "CLK_156M_OSC_CPU0_HFI_DN")
	)
	(segment
		(start 296.15003 -63.629286)
		(end 296.14368 -63.618618)
		(width 0.0889)
		(layer "In4.Cu")
		(net "CLK_156M_OSC_CPU0_HFI_DN")
	)
	(segment
		(start 296.15003 -55.704486)
		(end 296.14368 -55.693818)
		(width 0.0889)
		(layer "In4.Cu")
		(net "CLK_156M_OSC_CPU0_HFI_DN")
	)
	(segment
		(start 295.630092 -65.921382)
		(end 296.150284 -65.019936)
		(width 0.0889)
		(layer "In4.Cu")
		(net "CLK_156M_OSC_CPU0_HFI_DN")
	)
	(segment
		(start 295.289224 -68.490846)
		(end 295.290748 -68.488052)
		(width 0.0889)
		(layer "In4.Cu")
		(net "CLK_156M_OSC_CPU0_HFI_DN")
	)
	(segment
		(start 295.29151 -73.440036)
		(end 295.296336 -73.4314)
		(width 0.0889)
		(layer "In4.Cu")
		(net "CLK_156M_OSC_CPU0_HFI_DN")
	)
	(segment
		(start 320.966592 -32.196786)
		(end 320.966592 -31.98114)
		(width 0.1143)
		(layer "In4.Cu")
		(net "CLK_156M_OSC_CPU0_HFI_DN")
	)
	(segment
		(start 296.156634 -64.632078)
		(end 296.15003 -64.619886)
		(width 0.0889)
		(layer "In4.Cu")
		(net "CLK_156M_OSC_CPU0_HFI_DN")
	)
	(segment
		(start 321.9323 -33.914842)
		(end 321.9323 -32.946848)
		(width 0.1143)
		(layer "In4.Cu")
		(net "CLK_156M_OSC_CPU0_HFI_DN")
	)
	(segment
		(start 313.453272 -38.38067)
		(end 313.695842 -38.1381)
		(width 0.1143)
		(layer "In4.Cu")
		(net "CLK_156M_OSC_CPU0_HFI_DN")
	)
	(segment
		(start 302.106076 -50.73904)
		(end 302.294544 -50.550572)
		(width 0.0889)
		(layer "In4.Cu")
		(net "CLK_156M_OSC_CPU0_HFI_DN")
	)
	(segment
		(start 302.483266 -50.23612)
		(end 302.608996 -50.23612)
		(width 0.0889)
		(layer "In4.Cu")
		(net "CLK_156M_OSC_CPU0_HFI_DN")
	)
	(segment
		(start 321.353942 -34.4932)
		(end 321.9323 -33.914842)
		(width 0.1143)
		(layer "In4.Cu")
		(net "CLK_156M_OSC_CPU0_HFI_DN")
	)
	(segment
		(start 320.7512 -30.9372)
		(end 320.5988 -30.7848)
		(width 0.1143)
		(layer "In4.Cu")
		(net "CLK_156M_OSC_CPU0_HFI_DN")
	)
	(segment
		(start 302.815244 -49.958498)
		(end 305.9049 -46.868842)
		(width 0.1143)
		(layer "In4.Cu")
		(net "CLK_156M_OSC_CPU0_HFI_DN")
	)
	(segment
		(start 313.219846 -38.38067)
		(end 313.453272 -38.38067)
		(width 0.1143)
		(layer "In4.Cu")
		(net "CLK_156M_OSC_CPU0_HFI_DN")
	)
	(segment
		(start 296.154856 -60.666122)
		(end 296.15003 -60.657486)
		(width 0.0889)
		(layer "In4.Cu")
		(net "CLK_156M_OSC_CPU0_HFI_DN")
	)
	(segment
		(start 312.97753 -38.622986)
		(end 313.219846 -38.38067)
		(width 0.1143)
		(layer "In4.Cu")
		(net "CLK_156M_OSC_CPU0_HFI_DN")
	)
	(segment
		(start 295.29151 -71.458836)
		(end 295.296336 -71.4502)
		(width 0.0889)
		(layer "In4.Cu")
		(net "CLK_156M_OSC_CPU0_HFI_DN")
	)
	(segment
		(start 320.7512 -30.3276)
		(end 320.7512 -29.718)
		(width 0.1143)
		(layer "In4.Cu")
		(net "CLK_156M_OSC_CPU0_HFI_DN")
	)
	(segment
		(start 305.9049 -46.868842)
		(end 305.9049 -45.929042)
		(width 0.1143)
		(layer "In4.Cu")
		(net "CLK_156M_OSC_CPU0_HFI_DN")
	)
	(segment
		(start 296.15003 -61.648086)
		(end 296.14368 -61.637418)
		(width 0.0889)
		(layer "In4.Cu")
		(net "CLK_156M_OSC_CPU0_HFI_DN")
	)
	(segment
		(start 312.258964 -39.574978)
		(end 312.258964 -39.341552)
		(width 0.1143)
		(layer "In4.Cu")
		(net "CLK_156M_OSC_CPU0_HFI_DN")
	)
	(segment
		(start 320.5988 -30.48)
		(end 320.7512 -30.3276)
		(width 0.1143)
		(layer "In4.Cu")
		(net "CLK_156M_OSC_CPU0_HFI_DN")
	)
	(segment
		(start 295.345104 -68.287138)
		(end 295.345104 -67.775328)
		(width 0.0889)
		(layer "In4.Cu")
		(net "CLK_156M_OSC_CPU0_HFI_DN")
	)
	(segment
		(start 320.462148 -29.428948)
		(end 319.744852 -29.428948)
		(width 0.1143)
		(layer "In4.Cu")
		(net "CLK_156M_OSC_CPU0_HFI_DN")
	)
	(segment
		(start 296.15003 -57.685686)
		(end 296.14368 -57.675018)
		(width 0.0889)
		(layer "In4.Cu")
		(net "CLK_156M_OSC_CPU0_HFI_DN")
	)
	(segment
		(start 295.28516 -72.460104)
		(end 295.29151 -72.449436)
		(width 0.0889)
		(layer "In4.Cu")
		(net "CLK_156M_OSC_CPU0_HFI_DN")
	)
	(segment
		(start 295.28516 -68.497704)
		(end 295.289224 -68.490846)
		(width 0.0889)
		(layer "In4.Cu")
		(net "CLK_156M_OSC_CPU0_HFI_DN")
	)
	(segment
		(start 300.074076 -51.846988)
		(end 300.106842 -51.846988)
		(width 0.0889)
		(layer "In4.Cu")
		(net "CLK_156M_OSC_CPU0_HFI_DN")
	)
	(segment
		(start 319.612518 -34.73577)
		(end 319.855088 -34.4932)
		(width 0.1143)
		(layer "In4.Cu")
		(net "CLK_156M_OSC_CPU0_HFI_DN")
	)
	(segment
		(start 296.15003 -56.695086)
		(end 296.14368 -56.684418)
		(width 0.0889)
		(layer "In4.Cu")
		(net "CLK_156M_OSC_CPU0_HFI_DN")
	)
	(segment
		(start 298.360846 -52.837334)
		(end 298.39666 -52.837334)
		(width 0.0889)
		(layer "In4.Cu")
		(net "CLK_156M_OSC_CPU0_HFI_DN")
	)
	(segment
		(start 296.154856 -56.703722)
		(end 296.15003 -56.695086)
		(width 0.0889)
		(layer "In4.Cu")
		(net "CLK_156M_OSC_CPU0_HFI_DN")
	)
	(segment
		(start 305.9049 -45.929042)
		(end 312.258964 -39.574978)
		(width 0.1143)
		(layer "In4.Cu")
		(net "CLK_156M_OSC_CPU0_HFI_DN")
	)
	(segment
		(start 321.182238 -32.412432)
		(end 320.966592 -32.196786)
		(width 0.1143)
		(layer "In4.Cu")
		(net "CLK_156M_OSC_CPU0_HFI_DN")
	)
	(segment
		(start 295.290748 -68.488052)
		(end 295.29151 -68.487036)
		(width 0.0889)
		(layer "In4.Cu")
		(net "CLK_156M_OSC_CPU0_HFI_DN")
	)
	(segment
		(start 317.8302 -36.068)
		(end 318.280288 -36.068)
		(width 0.1143)
		(layer "In4.Cu")
		(net "CLK_156M_OSC_CPU0_HFI_DN")
	)
	(segment
		(start 296.154856 -62.647322)
		(end 296.15003 -62.638686)
		(width 0.0889)
		(layer "In4.Cu")
		(net "CLK_156M_OSC_CPU0_HFI_DN")
	)
	(segment
		(start 319.855088 -34.4932)
		(end 321.353942 -34.4932)
		(width 0.1143)
		(layer "In4.Cu")
		(net "CLK_156M_OSC_CPU0_HFI_DN")
	)
	(segment
		(start 297.498516 -53.332634)
		(end 297.53814 -53.332634)
		(width 0.0889)
		(layer "In4.Cu")
		(net "CLK_156M_OSC_CPU0_HFI_DN")
	)
	(segment
		(start 313.695842 -38.1381)
		(end 315.7601 -38.1381)
		(width 0.1143)
		(layer "In4.Cu")
		(net "CLK_156M_OSC_CPU0_HFI_DN")
	)
	(segment
		(start 321.397884 -32.412432)
		(end 321.182238 -32.412432)
		(width 0.1143)
		(layer "In4.Cu")
		(net "CLK_156M_OSC_CPU0_HFI_DN")
	)
	(segment
		(start 294.9448 -73.578212)
		(end 295.002712 -73.636124)
		(width 0.0889)
		(layer "In4.Cu")
		(net "CLK_156M_OSC_CPU0_HFI_DN")
	)
	(segment
		(start 296.154856 -57.694322)
		(end 296.15003 -57.685686)
		(width 0.0889)
		(layer "In4.Cu")
		(net "CLK_156M_OSC_CPU0_HFI_DN")
	)
	(segment
		(start 296.154856 -54.722522)
		(end 296.15003 -54.713886)
		(width 0.0889)
		(layer "In4.Cu")
		(net "CLK_156M_OSC_CPU0_HFI_DN")
	)
	(segment
		(start 296.15003 -62.638686)
		(end 296.14368 -62.628018)
		(width 0.0889)
		(layer "In4.Cu")
		(net "CLK_156M_OSC_CPU0_HFI_DN")
	)
	(segment
		(start 296.15003 -54.713886)
		(end 296.14368 -54.703218)
		(width 0.0889)
		(layer "In4.Cu")
		(net "CLK_156M_OSC_CPU0_HFI_DN")
	)
	(segment
		(start 297.004994 -53.633624)
		(end 297.008296 -53.627782)
		(width 0.0889)
		(layer "In4.Cu")
		(net "CLK_156M_OSC_CPU0_HFI_DN")
	)
	(segment
		(start 299.224192 -52.342034)
		(end 299.252132 -52.342034)
		(width 0.0889)
		(layer "In4.Cu")
		(net "CLK_156M_OSC_CPU0_HFI_DN")
	)
	(segment
		(start 302.294544 -50.550572)
		(end 302.294544 -50.424842)
		(width 0.0889)
		(layer "In4.Cu")
		(net "CLK_156M_OSC_CPU0_HFI_DN")
	)
	(segment
		(start 296.14368 -59.087004)
		(end 296.15003 -59.076336)
		(width 0.0889)
		(layer "In4.Cu")
		(net "CLK_156M_OSC_CPU0_HFI_DN")
	)
	(segment
		(start 321.9323 -32.946848)
		(end 321.397884 -32.412432)
		(width 0.1143)
		(layer "In4.Cu")
		(net "CLK_156M_OSC_CPU0_HFI_DN")
	)
	(segment
		(start 319.379092 -34.73577)
		(end 319.612518 -34.73577)
		(width 0.1143)
		(layer "In4.Cu")
		(net "CLK_156M_OSC_CPU0_HFI_DN")
	)
	(segment
		(start 319.136776 -34.978086)
		(end 319.379092 -34.73577)
		(width 0.1143)
		(layer "In4.Cu")
		(net "CLK_156M_OSC_CPU0_HFI_DN")
	)
	(segment
		(start 294.9448 -73.240138)
		(end 294.9448 -73.578212)
		(width 0.0889)
		(layer "In4.Cu")
		(net "CLK_156M_OSC_CPU0_HFI_DN")
	)
	(segment
		(start 302.79975 -49.973992)
		(end 302.815244 -49.958498)
		(width 0.0889)
		(layer "In4.Cu")
		(net "CLK_156M_OSC_CPU0_HFI_DN")
	)
	(segment
		(start 296.154856 -61.656722)
		(end 296.15003 -61.648086)
		(width 0.0889)
		(layer "In4.Cu")
		(net "CLK_156M_OSC_CPU0_HFI_DN")
	)
	(segment
		(start 295.345104 -67.775328)
		(end 295.630092 -67.49034)
		(width 0.0889)
		(layer "In4.Cu")
		(net "CLK_156M_OSC_CPU0_HFI_DN")
	)
	(segment
		(start 319.744852 -29.428948)
		(end 319.4939 -29.6799)
		(width 0.1143)
		(layer "In4.Cu")
		(net "CLK_156M_OSC_CPU0_HFI_DN")
	)
	(segment
		(start 302.294544 -50.424842)
		(end 302.483266 -50.23612)
		(width 0.0889)
		(layer "In4.Cu")
		(net "CLK_156M_OSC_CPU0_HFI_DN")
	)
	(segment
		(start 315.7601 -38.1381)
		(end 317.8302 -36.068)
		(width 0.1143)
		(layer "In4.Cu")
		(net "CLK_156M_OSC_CPU0_HFI_DN")
	)
	(segment
		(start 320.7512 -31.765748)
		(end 320.7512 -30.9372)
		(width 0.1143)
		(layer "In4.Cu")
		(net "CLK_156M_OSC_CPU0_HFI_DN")
	)
	(segment
		(start 296.154856 -63.637922)
		(end 296.15003 -63.629286)
		(width 0.0889)
		(layer "In4.Cu")
		(net "CLK_156M_OSC_CPU0_HFI_DN")
	)
	(segment
		(start 312.501534 -39.098982)
		(end 312.73496 -39.098982)
		(width 0.1143)
		(layer "In4.Cu")
		(net "CLK_156M_OSC_CPU0_HFI_DN")
	)
	(segment
		(start 300.536356 -51.524154)
		(end 300.860714 -50.99685)
		(width 0.0889)
		(layer "In4.Cu")
		(net "CLK_156M_OSC_CPU0_HFI_DN")
	)
	(segment
		(start 295.28516 -69.488304)
		(end 295.29151 -69.477636)
		(width 0.0889)
		(layer "In4.Cu")
		(net "CLK_156M_OSC_CPU0_HFI_DN")
	)
	(segment
		(start 319.4939 -29.6799)
		(end 319.4939 -29.7053)
		(width 0.1143)
		(layer "In4.Cu")
		(net "CLK_156M_OSC_CPU0_HFI_DN")
	)
	(segment
		(start 312.258964 -39.341552)
		(end 312.501534 -39.098982)
		(width 0.1143)
		(layer "In4.Cu")
		(net "CLK_156M_OSC_CPU0_HFI_DN")
	)
	(segment
		(start 320.5988 -30.7848)
		(end 320.5988 -30.48)
		(width 0.1143)
		(layer "In4.Cu")
		(net "CLK_156M_OSC_CPU0_HFI_DN")
	)
	(segment
		(start 302.800004 -50.045112)
		(end 302.79975 -49.973992)
		(width 0.0889)
		(layer "In4.Cu")
		(net "CLK_156M_OSC_CPU0_HFI_DN")
	)
	(segment
		(start 295.29151 -69.477636)
		(end 295.296336 -69.469)
		(width 0.0889)
		(layer "In4.Cu")
		(net "CLK_156M_OSC_CPU0_HFI_DN")
	)
	(segment
		(start 295.28516 -71.469504)
		(end 295.29151 -71.458836)
		(width 0.0889)
		(layer "In4.Cu")
		(net "CLK_156M_OSC_CPU0_HFI_DN")
	)
	(segment
		(start 319.136776 -35.211512)
		(end 319.136776 -34.978086)
		(width 0.1143)
		(layer "In4.Cu")
		(net "CLK_156M_OSC_CPU0_HFI_DN")
	)
	(segment
		(start 312.97753 -38.856412)
		(end 312.97753 -38.622986)
		(width 0.1143)
		(layer "In4.Cu")
		(net "CLK_156M_OSC_CPU0_HFI_DN")
	)
	(segment
		(start 300.860714 -50.99685)
		(end 301.315882 -50.73904)
		(width 0.0889)
		(layer "In4.Cu")
		(net "CLK_156M_OSC_CPU0_HFI_DN")
	)
	(segment
		(start 320.966592 -31.98114)
		(end 320.7512 -31.765748)
		(width 0.1143)
		(layer "In4.Cu")
		(net "CLK_156M_OSC_CPU0_HFI_DN")
	)
	(segment
		(start 312.73496 -39.098982)
		(end 312.97753 -38.856412)
		(width 0.1143)
		(layer "In4.Cu")
		(net "CLK_156M_OSC_CPU0_HFI_DN")
	)
	(segment
		(start 296.154856 -59.675522)
		(end 296.15003 -59.666886)
		(width 0.0889)
		(layer "In4.Cu")
		(net "CLK_156M_OSC_CPU0_HFI_DN")
	)
	(segment
		(start 296.15003 -64.619886)
		(end 296.14368 -64.609218)
		(width 0.0889)
		(layer "In4.Cu")
		(net "CLK_156M_OSC_CPU0_HFI_DN")
	)
	(arc
		(start 296.14368 -60.646818)
		(mid 296.070882 -60.356055)
		(end 296.15003 -60.066936)
		(width 0.0889)
		(layer "In4.Cu")
		(net "CLK_156M_OSC_CPU0_HFI_DN")
	)
	(arc
		(start 296.14368 -56.684418)
		(mid 296.070882 -56.393655)
		(end 296.15003 -56.104536)
		(width 0.0889)
		(layer "In4.Cu")
		(net "CLK_156M_OSC_CPU0_HFI_DN")
	)
	(arc
		(start 296.15003 -63.038736)
		(mid 296.2035 -62.843673)
		(end 296.154856 -62.647322)
		(width 0.0889)
		(layer "In4.Cu")
		(net "CLK_156M_OSC_CPU0_HFI_DN")
	)
	(arc
		(start 300.106842 -51.846988)
		(mid 300.300692 -51.790638)
		(end 300.442376 -51.646836)
		(width 0.0889)
		(layer "In4.Cu")
		(net "CLK_156M_OSC_CPU0_HFI_DN")
	)
	(arc
		(start 296.15003 -61.057536)
		(mid 296.2035 -60.862473)
		(end 296.154856 -60.666122)
		(width 0.0889)
		(layer "In4.Cu")
		(net "CLK_156M_OSC_CPU0_HFI_DN")
	)
	(arc
		(start 295.29151 -70.068186)
		(mid 295.212288 -69.779068)
		(end 295.28516 -69.488304)
		(width 0.0889)
		(layer "In4.Cu")
		(net "CLK_156M_OSC_CPU0_HFI_DN")
	)
	(arc
		(start 296.15003 -58.67654)
		(mid 296.070899 -58.381138)
		(end 296.15003 -58.085736)
		(width 0.0889)
		(layer "In4.Cu")
		(net "CLK_156M_OSC_CPU0_HFI_DN")
	)
	(arc
		(start 295.29151 -69.077586)
		(mid 295.212288 -68.788468)
		(end 295.28516 -68.497704)
		(width 0.0889)
		(layer "In4.Cu")
		(net "CLK_156M_OSC_CPU0_HFI_DN")
	)
	(arc
		(start 296.66184 -53.827934)
		(mid 296.859001 -53.775975)
		(end 297.004994 -53.633624)
		(width 0.0889)
		(layer "In4.Cu")
		(net "CLK_156M_OSC_CPU0_HFI_DN")
	)
	(arc
		(start 295.296336 -73.4314)
		(mid 295.345091 -73.235048)
		(end 295.29151 -73.039986)
		(width 0.0889)
		(layer "In4.Cu")
		(net "CLK_156M_OSC_CPU0_HFI_DN")
	)
	(arc
		(start 299.583856 -52.142136)
		(mid 299.79086 -51.931272)
		(end 300.074076 -51.846988)
		(width 0.0889)
		(layer "In4.Cu")
		(net "CLK_156M_OSC_CPU0_HFI_DN")
	)
	(arc
		(start 295.29151 -71.058786)
		(mid 295.212379 -70.763384)
		(end 295.29151 -70.467982)
		(width 0.0889)
		(layer "In4.Cu")
		(net "CLK_156M_OSC_CPU0_HFI_DN")
	)
	(arc
		(start 295.29151 -70.467982)
		(mid 295.345009 -70.268084)
		(end 295.29151 -70.068186)
		(width 0.0889)
		(layer "In4.Cu")
		(net "CLK_156M_OSC_CPU0_HFI_DN")
	)
	(arc
		(start 296.14368 -64.609218)
		(mid 296.070882 -64.318455)
		(end 296.15003 -64.029336)
		(width 0.0889)
		(layer "In4.Cu")
		(net "CLK_156M_OSC_CPU0_HFI_DN")
	)
	(arc
		(start 296.15003 -59.666886)
		(mid 296.070808 -59.377768)
		(end 296.14368 -59.087004)
		(width 0.0889)
		(layer "In4.Cu")
		(net "CLK_156M_OSC_CPU0_HFI_DN")
	)
	(arc
		(start 296.14368 -63.618618)
		(mid 296.070882 -63.327855)
		(end 296.15003 -63.038736)
		(width 0.0889)
		(layer "In4.Cu")
		(net "CLK_156M_OSC_CPU0_HFI_DN")
	)
	(arc
		(start 300.442376 -51.646836)
		(mid 300.485335 -51.582407)
		(end 300.536356 -51.524154)
		(width 0.0889)
		(layer "In4.Cu")
		(net "CLK_156M_OSC_CPU0_HFI_DN")
	)
	(arc
		(start 296.15003 -64.029336)
		(mid 296.2035 -63.834273)
		(end 296.154856 -63.637922)
		(width 0.0889)
		(layer "In4.Cu")
		(net "CLK_156M_OSC_CPU0_HFI_DN")
	)
	(arc
		(start 296.150284 -65.019936)
		(mid 296.203569 -64.82683)
		(end 296.156634 -64.632078)
		(width 0.0889)
		(layer "In4.Cu")
		(net "CLK_156M_OSC_CPU0_HFI_DN")
	)
	(arc
		(start 297.866816 -53.132736)
		(mid 298.075424 -52.920804)
		(end 298.360846 -52.837334)
		(width 0.0889)
		(layer "In4.Cu")
		(net "CLK_156M_OSC_CPU0_HFI_DN")
	)
	(arc
		(start 295.29151 -73.039986)
		(mid 295.212288 -72.750868)
		(end 295.28516 -72.460104)
		(width 0.0889)
		(layer "In4.Cu")
		(net "CLK_156M_OSC_CPU0_HFI_DN")
	)
	(arc
		(start 297.008296 -53.627782)
		(mid 297.2153 -53.416918)
		(end 297.498516 -53.332634)
		(width 0.0889)
		(layer "In4.Cu")
		(net "CLK_156M_OSC_CPU0_HFI_DN")
	)
	(arc
		(start 296.15003 -59.076336)
		(mid 296.203529 -58.876438)
		(end 296.15003 -58.67654)
		(width 0.0889)
		(layer "In4.Cu")
		(net "CLK_156M_OSC_CPU0_HFI_DN")
	)
	(arc
		(start 296.15003 -58.085736)
		(mid 296.2035 -57.890673)
		(end 296.154856 -57.694322)
		(width 0.0889)
		(layer "In4.Cu")
		(net "CLK_156M_OSC_CPU0_HFI_DN")
	)
	(arc
		(start 298.39666 -52.837334)
		(mid 298.586589 -52.779464)
		(end 298.725336 -52.637436)
		(width 0.0889)
		(layer "In4.Cu")
		(net "CLK_156M_OSC_CPU0_HFI_DN")
	)
	(arc
		(start 296.14368 -57.675018)
		(mid 296.070882 -57.384255)
		(end 296.15003 -57.095136)
		(width 0.0889)
		(layer "In4.Cu")
		(net "CLK_156M_OSC_CPU0_HFI_DN")
	)
	(arc
		(start 295.29151 -68.487036)
		(mid 295.331464 -68.390612)
		(end 295.345104 -68.287138)
		(width 0.0889)
		(layer "In4.Cu")
		(net "CLK_156M_OSC_CPU0_HFI_DN")
	)
	(arc
		(start 296.15003 -55.113936)
		(mid 296.2035 -54.918873)
		(end 296.154856 -54.722522)
		(width 0.0889)
		(layer "In4.Cu")
		(net "CLK_156M_OSC_CPU0_HFI_DN")
	)
	(arc
		(start 296.14368 -62.628018)
		(mid 296.070882 -62.337255)
		(end 296.15003 -62.048136)
		(width 0.0889)
		(layer "In4.Cu")
		(net "CLK_156M_OSC_CPU0_HFI_DN")
	)
	(arc
		(start 299.252132 -52.342034)
		(mid 299.443774 -52.284868)
		(end 299.583856 -52.142136)
		(width 0.0889)
		(layer "In4.Cu")
		(net "CLK_156M_OSC_CPU0_HFI_DN")
	)
	(arc
		(start 295.296336 -69.469)
		(mid 295.345091 -69.272648)
		(end 295.29151 -69.077586)
		(width 0.0889)
		(layer "In4.Cu")
		(net "CLK_156M_OSC_CPU0_HFI_DN")
	)
	(arc
		(start 295.29151 -72.049386)
		(mid 295.212288 -71.760268)
		(end 295.28516 -71.469504)
		(width 0.0889)
		(layer "In4.Cu")
		(net "CLK_156M_OSC_CPU0_HFI_DN")
	)
	(arc
		(start 295.296336 -71.4502)
		(mid 295.345091 -71.253848)
		(end 295.29151 -71.058786)
		(width 0.0889)
		(layer "In4.Cu")
		(net "CLK_156M_OSC_CPU0_HFI_DN")
	)
	(arc
		(start 296.14368 -55.693818)
		(mid 296.070882 -55.403055)
		(end 296.15003 -55.113936)
		(width 0.0889)
		(layer "In4.Cu")
		(net "CLK_156M_OSC_CPU0_HFI_DN")
	)
	(arc
		(start 296.15003 -54.123336)
		(mid 296.360743 -53.910257)
		(end 296.648886 -53.827934)
		(width 0.0889)
		(layer "In4.Cu")
		(net "CLK_156M_OSC_CPU0_HFI_DN")
	)
	(arc
		(start 296.15003 -56.104536)
		(mid 296.2035 -55.909473)
		(end 296.154856 -55.713122)
		(width 0.0889)
		(layer "In4.Cu")
		(net "CLK_156M_OSC_CPU0_HFI_DN")
	)
	(arc
		(start 296.14368 -54.703218)
		(mid 296.070882 -54.412455)
		(end 296.15003 -54.123336)
		(width 0.0889)
		(layer "In4.Cu")
		(net "CLK_156M_OSC_CPU0_HFI_DN")
	)
	(arc
		(start 295.296336 -72.4408)
		(mid 295.345091 -72.244448)
		(end 295.29151 -72.049386)
		(width 0.0889)
		(layer "In4.Cu")
		(net "CLK_156M_OSC_CPU0_HFI_DN")
	)
	(arc
		(start 295.002712 -73.636124)
		(mid 295.169613 -73.571224)
		(end 295.29151 -73.440036)
		(width 0.0889)
		(layer "In4.Cu")
		(net "CLK_156M_OSC_CPU0_HFI_DN")
	)
	(arc
		(start 297.53814 -53.332634)
		(mid 297.728069 -53.274764)
		(end 297.866816 -53.132736)
		(width 0.0889)
		(layer "In4.Cu")
		(net "CLK_156M_OSC_CPU0_HFI_DN")
	)
	(arc
		(start 296.14368 -61.637418)
		(mid 296.070882 -61.346655)
		(end 296.15003 -61.057536)
		(width 0.0889)
		(layer "In4.Cu")
		(net "CLK_156M_OSC_CPU0_HFI_DN")
	)
	(arc
		(start 296.15003 -60.066936)
		(mid 296.2035 -59.871873)
		(end 296.154856 -59.675522)
		(width 0.0889)
		(layer "In4.Cu")
		(net "CLK_156M_OSC_CPU0_HFI_DN")
	)
	(arc
		(start 296.15003 -57.095136)
		(mid 296.2035 -56.900073)
		(end 296.154856 -56.703722)
		(width 0.0889)
		(layer "In4.Cu")
		(net "CLK_156M_OSC_CPU0_HFI_DN")
	)
	(arc
		(start 296.15003 -62.048136)
		(mid 296.2035 -61.853073)
		(end 296.154856 -61.656722)
		(width 0.0889)
		(layer "In4.Cu")
		(net "CLK_156M_OSC_CPU0_HFI_DN")
	)
	(arc
		(start 298.725336 -52.637436)
		(mid 298.936049 -52.424357)
		(end 299.224192 -52.342034)
		(width 0.0889)
		(layer "In4.Cu")
		(net "CLK_156M_OSC_CPU0_HFI_DN")
	)
	(segment
		(start 147.2946 -29.8958)
		(end 149.7711 -29.8958)
		(width 0.1016)
		(layer "F.Cu")
		(net "NC_CLK_156M_CPU1_OSC")
	)
	(via
		(at 147.2946 -29.8958)
		(size 0.762)
		(drill 0.381)
		(layers "F.Cu" "B.Cu")
		(net "NC_CLK_156M_CPU1_OSC")
	)
	(segment
		(start 398.624044 -151.996902)
		(end 398.728946 -151.892)
		(width 0.10795)
		(layer "F.Cu")
		(net "IRQ_PVNN_PCH_VRHOT_N")
	)
	(segment
		(start 399.41373 -151.892)
		(end 399.7706 -151.892)
		(width 0.10795)
		(layer "F.Cu")
		(net "IRQ_PVNN_PCH_VRHOT_N")
	)
	(segment
		(start 399.93824 -151.72436)
		(end 400.25066 -151.72436)
		(width 0.10795)
		(layer "F.Cu")
		(net "IRQ_PVNN_PCH_VRHOT_N")
	)
	(segment
		(start 398.2339 -151.996902)
		(end 398.624044 -151.996902)
		(width 0.10795)
		(layer "F.Cu")
		(net "IRQ_PVNN_PCH_VRHOT_N")
	)
	(segment
		(start 399.7706 -151.892)
		(end 399.93824 -151.72436)
		(width 0.10795)
		(layer "F.Cu")
		(net "IRQ_PVNN_PCH_VRHOT_N")
	)
	(segment
		(start 398.728946 -151.892)
		(end 399.41373 -151.892)
		(width 0.10795)
		(layer "F.Cu")
		(net "IRQ_PVNN_PCH_VRHOT_N")
	)
	(via
		(at 399.41373 -151.892)
		(size 0.508)
		(drill 0.254)
		(layers "F.Cu" "B.Cu")
		(net "IRQ_PVNN_PCH_VRHOT_N")
	)
	(segment
		(start 165.7858 -70.0024)
		(end 166.116 -70.0024)
		(width 0.10795)
		(layer "F.Cu")
		(net "IRQ_PVCCIO_CPU1_VRHOT_N")
	)
	(segment
		(start 165.3286 -69.9262)
		(end 165.4048 -70.0024)
		(width 0.10795)
		(layer "F.Cu")
		(net "IRQ_PVCCIO_CPU1_VRHOT_N")
	)
	(segment
		(start 166.226998 -69.891402)
		(end 166.226998 -69.535802)
		(width 0.10795)
		(layer "F.Cu")
		(net "IRQ_PVCCIO_CPU1_VRHOT_N")
	)
	(segment
		(start 166.7383 -69.0245)
		(end 166.7383 -68.602098)
		(width 0.10795)
		(layer "F.Cu")
		(net "IRQ_PVCCIO_CPU1_VRHOT_N")
	)
	(segment
		(start 166.226998 -69.535802)
		(end 166.7383 -69.0245)
		(width 0.10795)
		(layer "F.Cu")
		(net "IRQ_PVCCIO_CPU1_VRHOT_N")
	)
	(segment
		(start 164.973 -69.9262)
		(end 165.3286 -69.9262)
		(width 0.10795)
		(layer "F.Cu")
		(net "IRQ_PVCCIO_CPU1_VRHOT_N")
	)
	(segment
		(start 165.4048 -70.0024)
		(end 165.7858 -70.0024)
		(width 0.10795)
		(layer "F.Cu")
		(net "IRQ_PVCCIO_CPU1_VRHOT_N")
	)
	(segment
		(start 166.116 -70.0024)
		(end 166.226998 -69.891402)
		(width 0.10795)
		(layer "F.Cu")
		(net "IRQ_PVCCIO_CPU1_VRHOT_N")
	)
	(via
		(at 165.7858 -70.0024)
		(size 0.1016)
		(drill 0.0508)
		(layers "F.Cu" "B.Cu")
		(net "IRQ_PVCCIO_CPU1_VRHOT_N")
	)
	(via
		(at 342.9508 -84.5058)
		(size 0.6604)
		(drill 0.3302)
		(layers "F.Cu" "B.Cu")
		(net "IRQ_PVCCIO_CPU0_VRHOT_N")
	)
	(segment
		(start 341.63 -84.5058)
		(end 342.9508 -84.5058)
		(width 0.10795)
		(layer "B.Cu")
		(net "IRQ_PVCCIO_CPU0_VRHOT_N")
	)
	(segment
		(start 343.5604 -85.1027)
		(end 342.9635 -84.5058)
		(width 0.10795)
		(layer "B.Cu")
		(net "IRQ_PVCCIO_CPU0_VRHOT_N")
	)
	(segment
		(start 342.9635 -84.5058)
		(end 342.9508 -84.5058)
		(width 0.10795)
		(layer "B.Cu")
		(net "IRQ_PVCCIO_CPU0_VRHOT_N")
	)
	(segment
		(start 343.5604 -85.471)
		(end 343.5604 -85.1027)
		(width 0.10795)
		(layer "B.Cu")
		(net "IRQ_PVCCIO_CPU0_VRHOT_N")
	)
	(segment
		(start 343.741502 -85.652102)
		(end 343.5604 -85.471)
		(width 0.10795)
		(layer "B.Cu")
		(net "IRQ_PVCCIO_CPU0_VRHOT_N")
	)
	(segment
		(start 344.0811 -85.652102)
		(end 343.741502 -85.652102)
		(width 0.10795)
		(layer "B.Cu")
		(net "IRQ_PVCCIO_CPU0_VRHOT_N")
	)
	(segment
		(start 397.470376 -115.15598)
		(end 397.558768 -115.196874)
		(width 0.10795)
		(layer "F.Cu")
		(net "FM_OC0_USB_N")
	)
	(segment
		(start 397.14805 -115.00612)
		(end 397.470376 -115.15598)
		(width 0.10795)
		(layer "F.Cu")
		(net "FM_OC0_USB_N")
	)
	(segment
		(start 374.344692 -76.694792)
		(end 373.944896 -76.294996)
		(width 0.10795)
		(layer "F.Cu")
		(net "FM_OC0_USB_N")
	)
	(segment
		(start 397.558768 -115.196874)
		(end 397.64335 -115.236244)
		(width 0.10795)
		(layer "F.Cu")
		(net "FM_OC0_USB_N")
	)
	(via
		(at 395.9733 -92.2147)
		(size 0.508)
		(drill 0.254)
		(layers "F.Cu" "B.Cu")
		(net "FM_OC0_USB_N")
	)
	(via
		(at 458.1906 -124.841)
		(size 0.508)
		(drill 0.254)
		(layers "F.Cu" "B.Cu")
		(net "FM_OC0_USB_N")
	)
	(via
		(at 397.64335 -115.236244)
		(size 0.508)
		(drill 0.254)
		(layers "F.Cu" "B.Cu")
		(net "FM_OC0_USB_N")
	)
	(via
		(at 459.266036 -125.916436)
		(size 0.6604)
		(drill 0.3302)
		(layers "F.Cu" "B.Cu")
		(net "FM_OC0_USB_N")
	)
	(via
		(at 374.344692 -76.694792)
		(size 0.4572)
		(drill 0.2032)
		(layers "F.Cu" "B.Cu")
		(net "FM_OC0_USB_N")
	)
	(segment
		(start 464.2104 -128.8288)
		(end 463.55 -128.8288)
		(width 0.10795)
		(layer "B.Cu")
		(net "FM_OC0_USB_N")
	)
	(segment
		(start 459.87335 -126.52375)
		(end 459.87335 -128.358392)
		(width 0.10795)
		(layer "B.Cu")
		(net "FM_OC0_USB_N")
	)
	(segment
		(start 466.92312 -129.48412)
		(end 466.4456 -129.0066)
		(width 0.10795)
		(layer "B.Cu")
		(net "FM_OC0_USB_N")
	)
	(segment
		(start 461.432148 -128.654048)
		(end 461.6069 -128.8288)
		(width 0.10795)
		(layer "B.Cu")
		(net "FM_OC0_USB_N")
	)
	(segment
		(start 459.266036 -125.916436)
		(end 459.87335 -126.52375)
		(width 0.10795)
		(layer "B.Cu")
		(net "FM_OC0_USB_N")
	)
	(segment
		(start 458.1906 -124.841)
		(end 459.266036 -125.916436)
		(width 0.10795)
		(layer "B.Cu")
		(net "FM_OC0_USB_N")
	)
	(segment
		(start 459.87335 -128.358392)
		(end 460.169006 -128.654048)
		(width 0.10795)
		(layer "B.Cu")
		(net "FM_OC0_USB_N")
	)
	(segment
		(start 466.4456 -129.0066)
		(end 464.3882 -129.0066)
		(width 0.10795)
		(layer "B.Cu")
		(net "FM_OC0_USB_N")
	)
	(segment
		(start 461.6069 -128.8288)
		(end 463.55 -128.8288)
		(width 0.10795)
		(layer "B.Cu")
		(net "FM_OC0_USB_N")
	)
	(segment
		(start 460.169006 -128.654048)
		(end 461.432148 -128.654048)
		(width 0.10795)
		(layer "B.Cu")
		(net "FM_OC0_USB_N")
	)
	(segment
		(start 466.92312 -130.5052)
		(end 466.92312 -129.48412)
		(width 0.10795)
		(layer "B.Cu")
		(net "FM_OC0_USB_N")
	)
	(segment
		(start 464.3882 -129.0066)
		(end 464.2104 -128.8288)
		(width 0.10795)
		(layer "B.Cu")
		(net "FM_OC0_USB_N")
	)
	(segment
		(start 399.275046 -115.14455)
		(end 398.833848 -114.889534)
		(width 0.0889)
		(layer "In2.Cu")
		(net "FM_OC0_USB_N")
	)
	(segment
		(start 439.495692 -122.179334)
		(end 434.320442 -122.179334)
		(width 0.089408)
		(layer "In2.Cu")
		(net "FM_OC0_USB_N")
	)
	(segment
		(start 397.558768 -115.089432)
		(end 397.64335 -115.236244)
		(width 0.0889)
		(layer "In2.Cu")
		(net "FM_OC0_USB_N")
	)
	(segment
		(start 378.3965 -93.7641)
		(end 377.492006 -92.859606)
		(width 0.089408)
		(layer "In2.Cu")
		(net "FM_OC0_USB_N")
	)
	(segment
		(start 432.014884 -123.152154)
		(end 431.37709 -122.51436)
		(width 0.089408)
		(layer "In2.Cu")
		(net "FM_OC0_USB_N")
	)
	(segment
		(start 431.37709 -122.51436)
		(end 428.480474 -122.51436)
		(width 0.089408)
		(layer "In2.Cu")
		(net "FM_OC0_USB_N")
	)
	(segment
		(start 377.793504 -79.521304)
		(end 377.390152 -79.521304)
		(width 0.089408)
		(layer "In2.Cu")
		(net "FM_OC0_USB_N")
	)
	(segment
		(start 374.471692 -76.694792)
		(end 374.344692 -76.694792)
		(width 0.089408)
		(layer "In2.Cu")
		(net "FM_OC0_USB_N")
	)
	(segment
		(start 453.156828 -122.795792)
		(end 452.110348 -121.749312)
		(width 0.089408)
		(layer "In2.Cu")
		(net "FM_OC0_USB_N")
	)
	(segment
		(start 395.586204 -92.754196)
		(end 394.5763 -93.7641)
		(width 0.089408)
		(layer "In2.Cu")
		(net "FM_OC0_USB_N")
	)
	(segment
		(start 405.94915 -119.260874)
		(end 402.354542 -119.260874)
		(width 0.089408)
		(layer "In2.Cu")
		(net "FM_OC0_USB_N")
	)
	(segment
		(start 395.9733 -92.2147)
		(end 395.9733 -92.365068)
		(width 0.089408)
		(layer "In2.Cu")
		(net "FM_OC0_USB_N")
	)
	(segment
		(start 377.171458 -80.003142)
		(end 376.8852 -80.2894)
		(width 0.089408)
		(layer "In2.Cu")
		(net "FM_OC0_USB_N")
	)
	(segment
		(start 378.53366 -83.620356)
		(end 377.9647 -83.051396)
		(width 0.089408)
		(layer "In2.Cu")
		(net "FM_OC0_USB_N")
	)
	(segment
		(start 399.5801 -116.486432)
		(end 399.5801 -115.449604)
		(width 0.089408)
		(layer "In2.Cu")
		(net "FM_OC0_USB_N")
	)
	(segment
		(start 433.347622 -123.152154)
		(end 432.014884 -123.152154)
		(width 0.089408)
		(layer "In2.Cu")
		(net "FM_OC0_USB_N")
	)
	(segment
		(start 458.1906 -124.003562)
		(end 456.98283 -122.795792)
		(width 0.089408)
		(layer "In2.Cu")
		(net "FM_OC0_USB_N")
	)
	(segment
		(start 434.320442 -122.179334)
		(end 433.347622 -123.152154)
		(width 0.089408)
		(layer "In2.Cu")
		(net "FM_OC0_USB_N")
	)
	(segment
		(start 425.096178 -125.898656)
		(end 424.043856 -125.898656)
		(width 0.089408)
		(layer "In2.Cu")
		(net "FM_OC0_USB_N")
	)
	(segment
		(start 378.53366 -86.79434)
		(end 378.53366 -83.620356)
		(width 0.089408)
		(layer "In2.Cu")
		(net "FM_OC0_USB_N")
	)
	(segment
		(start 399.5801 -115.449604)
		(end 399.275046 -115.14455)
		(width 0.089408)
		(layer "In2.Cu")
		(net "FM_OC0_USB_N")
	)
	(segment
		(start 407.373582 -120.685306)
		(end 405.94915 -119.260874)
		(width 0.089408)
		(layer "In2.Cu")
		(net "FM_OC0_USB_N")
	)
	(segment
		(start 376.8852 -80.2894)
		(end 375.7803 -80.2894)
		(width 0.089408)
		(layer "In2.Cu")
		(net "FM_OC0_USB_N")
	)
	(segment
		(start 417.152074 -123.059952)
		(end 412.265876 -123.059952)
		(width 0.089408)
		(layer "In2.Cu")
		(net "FM_OC0_USB_N")
	)
	(segment
		(start 397.495776 -114.864388)
		(end 397.47444 -114.943128)
		(width 0.0889)
		(layer "In2.Cu")
		(net "FM_OC0_USB_N")
	)
	(segment
		(start 458.1906 -124.841)
		(end 458.1906 -124.003562)
		(width 0.089408)
		(layer "In2.Cu")
		(net "FM_OC0_USB_N")
	)
	(segment
		(start 377.9647 -83.051396)
		(end 377.9647 -79.6925)
		(width 0.089408)
		(layer "In2.Cu")
		(net "FM_OC0_USB_N")
	)
	(segment
		(start 374.7389 -79.248)
		(end 374.7389 -76.962)
		(width 0.089408)
		(layer "In2.Cu")
		(net "FM_OC0_USB_N")
	)
	(segment
		(start 418.940488 -124.848366)
		(end 417.152074 -123.059952)
		(width 0.089408)
		(layer "In2.Cu")
		(net "FM_OC0_USB_N")
	)
	(segment
		(start 377.492006 -90.56624)
		(end 377.125992 -90.200226)
		(width 0.089408)
		(layer "In2.Cu")
		(net "FM_OC0_USB_N")
	)
	(segment
		(start 377.390152 -79.521304)
		(end 377.171458 -79.739998)
		(width 0.089408)
		(layer "In2.Cu")
		(net "FM_OC0_USB_N")
	)
	(segment
		(start 439.925714 -121.749312)
		(end 439.495692 -122.179334)
		(width 0.089408)
		(layer "In2.Cu")
		(net "FM_OC0_USB_N")
	)
	(segment
		(start 375.7803 -80.2894)
		(end 374.7389 -79.248)
		(width 0.089408)
		(layer "In2.Cu")
		(net "FM_OC0_USB_N")
	)
	(segment
		(start 377.125992 -88.202008)
		(end 378.53366 -86.79434)
		(width 0.089408)
		(layer "In2.Cu")
		(net "FM_OC0_USB_N")
	)
	(segment
		(start 377.125992 -90.200226)
		(end 377.125992 -88.202008)
		(width 0.089408)
		(layer "In2.Cu")
		(net "FM_OC0_USB_N")
	)
	(segment
		(start 394.5763 -93.7641)
		(end 378.3965 -93.7641)
		(width 0.089408)
		(layer "In2.Cu")
		(net "FM_OC0_USB_N")
	)
	(segment
		(start 374.7389 -76.962)
		(end 374.471692 -76.694792)
		(width 0.089408)
		(layer "In2.Cu")
		(net "FM_OC0_USB_N")
	)
	(segment
		(start 377.9647 -79.6925)
		(end 377.793504 -79.521304)
		(width 0.089408)
		(layer "In2.Cu")
		(net "FM_OC0_USB_N")
	)
	(segment
		(start 409.690062 -123.716796)
		(end 407.373582 -121.400316)
		(width 0.089408)
		(layer "In2.Cu")
		(net "FM_OC0_USB_N")
	)
	(segment
		(start 397.47444 -114.943128)
		(end 397.558768 -115.089432)
		(width 0.0889)
		(layer "In2.Cu")
		(net "FM_OC0_USB_N")
	)
	(segment
		(start 395.586204 -92.752164)
		(end 395.586204 -92.754196)
		(width 0.089408)
		(layer "In2.Cu")
		(net "FM_OC0_USB_N")
	)
	(segment
		(start 411.609032 -123.716796)
		(end 409.690062 -123.716796)
		(width 0.089408)
		(layer "In2.Cu")
		(net "FM_OC0_USB_N")
	)
	(segment
		(start 428.480474 -122.51436)
		(end 425.096178 -125.898656)
		(width 0.089408)
		(layer "In2.Cu")
		(net "FM_OC0_USB_N")
	)
	(segment
		(start 452.110348 -121.749312)
		(end 439.925714 -121.749312)
		(width 0.089408)
		(layer "In2.Cu")
		(net "FM_OC0_USB_N")
	)
	(segment
		(start 456.98283 -122.795792)
		(end 453.156828 -122.795792)
		(width 0.089408)
		(layer "In2.Cu")
		(net "FM_OC0_USB_N")
	)
	(segment
		(start 422.993566 -124.848366)
		(end 418.940488 -124.848366)
		(width 0.089408)
		(layer "In2.Cu")
		(net "FM_OC0_USB_N")
	)
	(segment
		(start 395.9733 -92.365068)
		(end 395.586204 -92.752164)
		(width 0.089408)
		(layer "In2.Cu")
		(net "FM_OC0_USB_N")
	)
	(segment
		(start 412.265876 -123.059952)
		(end 411.609032 -123.716796)
		(width 0.089408)
		(layer "In2.Cu")
		(net "FM_OC0_USB_N")
	)
	(segment
		(start 402.354542 -119.260874)
		(end 399.5801 -116.486432)
		(width 0.089408)
		(layer "In2.Cu")
		(net "FM_OC0_USB_N")
	)
	(segment
		(start 377.492006 -92.859606)
		(end 377.492006 -90.56624)
		(width 0.089408)
		(layer "In2.Cu")
		(net "FM_OC0_USB_N")
	)
	(segment
		(start 407.373582 -121.400316)
		(end 407.373582 -120.685306)
		(width 0.089408)
		(layer "In2.Cu")
		(net "FM_OC0_USB_N")
	)
	(segment
		(start 377.171458 -79.739998)
		(end 377.171458 -80.003142)
		(width 0.089408)
		(layer "In2.Cu")
		(net "FM_OC0_USB_N")
	)
	(segment
		(start 424.043856 -125.898656)
		(end 422.993566 -124.848366)
		(width 0.089408)
		(layer "In2.Cu")
		(net "FM_OC0_USB_N")
	)
	(arc
		(start 398.833848 -114.889534)
		(mid 398.63395 -114.836035)
		(end 398.434052 -114.889534)
		(width 0.0889)
		(layer "In2.Cu")
		(net "FM_OC0_USB_N")
	)
	(arc
		(start 398.434052 -114.889534)
		(mid 398.13865 -114.968665)
		(end 397.843248 -114.889534)
		(width 0.0889)
		(layer "In2.Cu")
		(net "FM_OC0_USB_N")
	)
	(arc
		(start 397.843248 -114.889534)
		(mid 397.672399 -114.8372)
		(end 397.495776 -114.864388)
		(width 0.0889)
		(layer "In2.Cu")
		(net "FM_OC0_USB_N")
	)
	(segment
		(start 398.04213 -113.128298)
		(end 398.04213 -113.91011)
		(width 0.089408)
		(layer "In11.Cu")
		(net "FM_OC0_USB_N")
	)
	(segment
		(start 398.04213 -113.91011)
		(end 397.64335 -114.30889)
		(width 0.089408)
		(layer "In11.Cu")
		(net "FM_OC0_USB_N")
	)
	(segment
		(start 397.999966 -94.234)
		(end 400.131534 -96.365568)
		(width 0.089408)
		(layer "In11.Cu")
		(net "FM_OC0_USB_N")
	)
	(segment
		(start 400.131534 -111.045498)
		(end 398.915128 -112.261904)
		(width 0.089408)
		(layer "In11.Cu")
		(net "FM_OC0_USB_N")
	)
	(segment
		(start 398.915128 -112.261904)
		(end 397.973296 -112.261904)
		(width 0.089408)
		(layer "In11.Cu")
		(net "FM_OC0_USB_N")
	)
	(segment
		(start 397.874998 -94.234)
		(end 397.999966 -94.234)
		(width 0.089408)
		(layer "In11.Cu")
		(net "FM_OC0_USB_N")
	)
	(segment
		(start 396.44574 -92.804742)
		(end 397.874998 -94.234)
		(width 0.089408)
		(layer "In11.Cu")
		(net "FM_OC0_USB_N")
	)
	(segment
		(start 400.131534 -96.365568)
		(end 400.131534 -111.045498)
		(width 0.089408)
		(layer "In11.Cu")
		(net "FM_OC0_USB_N")
	)
	(segment
		(start 396.44574 -92.68714)
		(end 396.44574 -92.804742)
		(width 0.089408)
		(layer "In11.Cu")
		(net "FM_OC0_USB_N")
	)
	(segment
		(start 397.73987 -112.826038)
		(end 398.04213 -113.128298)
		(width 0.089408)
		(layer "In11.Cu")
		(net "FM_OC0_USB_N")
	)
	(segment
		(start 397.973296 -112.261904)
		(end 397.73987 -112.49533)
		(width 0.089408)
		(layer "In11.Cu")
		(net "FM_OC0_USB_N")
	)
	(segment
		(start 397.64335 -114.30889)
		(end 397.64335 -115.236244)
		(width 0.089408)
		(layer "In11.Cu")
		(net "FM_OC0_USB_N")
	)
	(segment
		(start 395.9733 -92.2147)
		(end 396.44574 -92.68714)
		(width 0.089408)
		(layer "In11.Cu")
		(net "FM_OC0_USB_N")
	)
	(segment
		(start 397.73987 -112.49533)
		(end 397.73987 -112.826038)
		(width 0.089408)
		(layer "In11.Cu")
		(net "FM_OC0_USB_N")
	)
	(segment
		(start 317.9826 -27.18816)
		(end 318.00292 -27.16784)
		(width 0.127)
		(layer "F.Cu")
		(net "CLK_322M_OSC_CPU0_RC_DP")
	)
	(segment
		(start 284.358334 -65.810384)
		(end 284.929834 -65.810384)
		(width 0.127)
		(layer "F.Cu")
		(net "CLK_322M_OSC_CPU0_RC_DP")
	)
	(segment
		(start 317.9826 -28.045918)
		(end 317.9826 -27.18816)
		(width 0.127)
		(layer "F.Cu")
		(net "CLK_322M_OSC_CPU0_RC_DP")
	)
	(via
		(at 284.358334 -65.810384)
		(size 0.508)
		(drill 0.254)
		(layers "F.Cu" "B.Cu")
		(net "CLK_322M_OSC_CPU0_RC_DP")
	)
	(via
		(at 318.00292 -27.16784)
		(size 0.508)
		(drill 0.254)
		(layers "F.Cu" "B.Cu")
		(net "CLK_322M_OSC_CPU0_RC_DP")
	)
	(segment
		(start 319.5066 -33.001712)
		(end 317.646812 -34.8615)
		(width 0.1143)
		(layer "In4.Cu")
		(net "CLK_322M_OSC_CPU0_RC_DP")
	)
	(segment
		(start 299.132498 -50.861976)
		(end 297.942508 -50.861976)
		(width 0.1143)
		(layer "In4.Cu")
		(net "CLK_322M_OSC_CPU0_RC_DP")
	)
	(segment
		(start 285.23438 -66.896488)
		(end 285.19882 -66.896488)
		(width 0.0889)
		(layer "In4.Cu")
		(net "CLK_322M_OSC_CPU0_RC_DP")
	)
	(segment
		(start 315.132974 -34.8615)
		(end 299.132498 -50.861976)
		(width 0.1143)
		(layer "In4.Cu")
		(net "CLK_322M_OSC_CPU0_RC_DP")
	)
	(segment
		(start 284.62732 -66.257678)
		(end 284.358334 -65.810384)
		(width 0.0889)
		(layer "In4.Cu")
		(net "CLK_322M_OSC_CPU0_RC_DP")
	)
	(segment
		(start 286.95142 -64.915288)
		(end 286.918654 -64.915288)
		(width 0.0889)
		(layer "In4.Cu")
		(net "CLK_322M_OSC_CPU0_RC_DP")
	)
	(segment
		(start 286.09671 -66.400934)
		(end 286.063944 -66.400934)
		(width 0.0889)
		(layer "In4.Cu")
		(net "CLK_322M_OSC_CPU0_RC_DP")
	)
	(segment
		(start 293.24554 -55.009288)
		(end 293.212774 -55.009288)
		(width 0.0889)
		(layer "In4.Cu")
		(net "CLK_322M_OSC_CPU0_RC_DP")
	)
	(segment
		(start 318.5922 -29.591)
		(end 318.5922 -30.505146)
		(width 0.1143)
		(layer "In4.Cu")
		(net "CLK_322M_OSC_CPU0_RC_DP")
	)
	(segment
		(start 318.00292 -27.16784)
		(end 318.00292 -29.00172)
		(width 0.1143)
		(layer "In4.Cu")
		(net "CLK_322M_OSC_CPU0_RC_DP")
	)
	(segment
		(start 287.81375 -64.419734)
		(end 287.780984 -64.419734)
		(width 0.0889)
		(layer "In4.Cu")
		(net "CLK_322M_OSC_CPU0_RC_DP")
	)
	(segment
		(start 294.3733 -52.523898)
		(end 294.3733 -52.959)
		(width 0.0889)
		(layer "In4.Cu")
		(net "CLK_322M_OSC_CPU0_RC_DP")
	)
	(segment
		(start 294.458898 -53.386736)
		(end 294.602916 -53.63591)
		(width 0.0889)
		(layer "In4.Cu")
		(net "CLK_322M_OSC_CPU0_RC_DP")
	)
	(segment
		(start 286.582104 -65.5066)
		(end 286.58693 -65.515236)
		(width 0.0889)
		(layer "In4.Cu")
		(net "CLK_322M_OSC_CPU0_RC_DP")
	)
	(segment
		(start 294.10787 -54.513734)
		(end 294.075104 -54.513734)
		(width 0.0889)
		(layer "In4.Cu")
		(net "CLK_322M_OSC_CPU0_RC_DP")
	)
	(segment
		(start 294.875458 -51.7144)
		(end 294.4241 -52.165758)
		(width 0.1143)
		(layer "In4.Cu")
		(net "CLK_322M_OSC_CPU0_RC_DP")
	)
	(segment
		(start 292.39083 -55.504334)
		(end 292.358064 -55.504334)
		(width 0.0889)
		(layer "In4.Cu")
		(net "CLK_322M_OSC_CPU0_RC_DP")
	)
	(segment
		(start 318.5922 -30.505146)
		(end 319.5066 -31.419546)
		(width 0.1143)
		(layer "In4.Cu")
		(net "CLK_322M_OSC_CPU0_RC_DP")
	)
	(segment
		(start 294.4241 -52.451)
		(end 294.4241 -52.473098)
		(width 0.0889)
		(layer "In4.Cu")
		(net "CLK_322M_OSC_CPU0_RC_DP")
	)
	(segment
		(start 297.090084 -51.7144)
		(end 294.875458 -51.7144)
		(width 0.1143)
		(layer "In4.Cu")
		(net "CLK_322M_OSC_CPU0_RC_DP")
	)
	(segment
		(start 294.37076 -53.043074)
		(end 294.458898 -53.386736)
		(width 0.0889)
		(layer "In4.Cu")
		(net "CLK_322M_OSC_CPU0_RC_DP")
	)
	(segment
		(start 297.942508 -50.861976)
		(end 297.090084 -51.7144)
		(width 0.1143)
		(layer "In4.Cu")
		(net "CLK_322M_OSC_CPU0_RC_DP")
	)
	(segment
		(start 289.260026 -63.924688)
		(end 288.635694 -63.924688)
		(width 0.0889)
		(layer "In4.Cu")
		(net "CLK_322M_OSC_CPU0_RC_DP")
	)
	(segment
		(start 318.00292 -29.00172)
		(end 318.5922 -29.591)
		(width 0.1143)
		(layer "In4.Cu")
		(net "CLK_322M_OSC_CPU0_RC_DP")
	)
	(segment
		(start 294.4241 -52.165758)
		(end 294.4241 -52.451)
		(width 0.1143)
		(layer "In4.Cu")
		(net "CLK_322M_OSC_CPU0_RC_DP")
	)
	(segment
		(start 294.3733 -52.959)
		(end 294.37076 -53.043074)
		(width 0.0889)
		(layer "In4.Cu")
		(net "CLK_322M_OSC_CPU0_RC_DP")
	)
	(segment
		(start 317.646812 -34.8615)
		(end 315.132974 -34.8615)
		(width 0.1143)
		(layer "In4.Cu")
		(net "CLK_322M_OSC_CPU0_RC_DP")
	)
	(segment
		(start 290.653724 -56.49468)
		(end 290.387278 -56.49468)
		(width 0.0889)
		(layer "In4.Cu")
		(net "CLK_322M_OSC_CPU0_RC_DP")
	)
	(segment
		(start 291.5285 -55.999888)
		(end 291.493194 -55.999888)
		(width 0.0889)
		(layer "In4.Cu")
		(net "CLK_322M_OSC_CPU0_RC_DP")
	)
	(segment
		(start 319.5066 -31.419546)
		(end 319.5066 -33.001712)
		(width 0.1143)
		(layer "In4.Cu")
		(net "CLK_322M_OSC_CPU0_RC_DP")
	)
	(segment
		(start 286.58693 -65.515236)
		(end 286.59328 -65.525904)
		(width 0.0889)
		(layer "In4.Cu")
		(net "CLK_322M_OSC_CPU0_RC_DP")
	)
	(segment
		(start 290.108386 -63.076328)
		(end 289.260026 -63.924688)
		(width 0.0889)
		(layer "In4.Cu")
		(net "CLK_322M_OSC_CPU0_RC_DP")
	)
	(segment
		(start 294.4241 -52.473098)
		(end 294.3733 -52.523898)
		(width 0.0889)
		(layer "In4.Cu")
		(net "CLK_322M_OSC_CPU0_RC_DP")
	)
	(segment
		(start 284.70479 -66.601086)
		(end 284.6959 -66.585846)
		(width 0.0889)
		(layer "In4.Cu")
		(net "CLK_322M_OSC_CPU0_RC_DP")
	)
	(segment
		(start 290.108386 -56.773572)
		(end 290.108386 -63.076328)
		(width 0.0889)
		(layer "In4.Cu")
		(net "CLK_322M_OSC_CPU0_RC_DP")
	)
	(segment
		(start 290.387278 -56.49468)
		(end 290.108386 -56.773572)
		(width 0.0889)
		(layer "In4.Cu")
		(net "CLK_322M_OSC_CPU0_RC_DP")
	)
	(arc
		(start 292.88105 -55.209186)
		(mid 292.674046 -55.42005)
		(end 292.39083 -55.504334)
		(width 0.0889)
		(layer "In4.Cu")
		(net "CLK_322M_OSC_CPU0_RC_DP")
	)
	(arc
		(start 284.6959 -66.585846)
		(mid 284.63788 -66.426725)
		(end 284.62732 -66.257678)
		(width 0.0889)
		(layer "In4.Cu")
		(net "CLK_322M_OSC_CPU0_RC_DP")
	)
	(arc
		(start 286.918654 -64.915288)
		(mid 286.585736 -65.117279)
		(end 286.582104 -65.5066)
		(width 0.0889)
		(layer "In4.Cu")
		(net "CLK_322M_OSC_CPU0_RC_DP")
	)
	(arc
		(start 292.358064 -55.504334)
		(mid 292.164214 -55.560684)
		(end 292.02253 -55.704486)
		(width 0.0889)
		(layer "In4.Cu")
		(net "CLK_322M_OSC_CPU0_RC_DP")
	)
	(arc
		(start 294.075104 -54.513734)
		(mid 293.881254 -54.570084)
		(end 293.73957 -54.713886)
		(width 0.0889)
		(layer "In4.Cu")
		(net "CLK_322M_OSC_CPU0_RC_DP")
	)
	(arc
		(start 287.44545 -64.619886)
		(mid 287.236842 -64.831818)
		(end 286.95142 -64.915288)
		(width 0.0889)
		(layer "In4.Cu")
		(net "CLK_322M_OSC_CPU0_RC_DP")
	)
	(arc
		(start 285.19882 -66.896488)
		(mid 284.913396 -66.813021)
		(end 284.70479 -66.601086)
		(width 0.0889)
		(layer "In4.Cu")
		(net "CLK_322M_OSC_CPU0_RC_DP")
	)
	(arc
		(start 288.30397 -64.124586)
		(mid 288.096966 -64.33545)
		(end 287.81375 -64.419734)
		(width 0.0889)
		(layer "In4.Cu")
		(net "CLK_322M_OSC_CPU0_RC_DP")
	)
	(arc
		(start 286.063944 -66.400934)
		(mid 285.870094 -66.457284)
		(end 285.72841 -66.601086)
		(width 0.0889)
		(layer "In4.Cu")
		(net "CLK_322M_OSC_CPU0_RC_DP")
	)
	(arc
		(start 285.72841 -66.601086)
		(mid 285.519802 -66.813018)
		(end 285.23438 -66.896488)
		(width 0.0889)
		(layer "In4.Cu")
		(net "CLK_322M_OSC_CPU0_RC_DP")
	)
	(arc
		(start 286.59328 -65.525904)
		(mid 286.589249 -66.102086)
		(end 286.09671 -66.400934)
		(width 0.0889)
		(layer "In4.Cu")
		(net "CLK_322M_OSC_CPU0_RC_DP")
	)
	(arc
		(start 288.635694 -63.924688)
		(mid 288.444052 -63.981854)
		(end 288.30397 -64.124586)
		(width 0.0889)
		(layer "In4.Cu")
		(net "CLK_322M_OSC_CPU0_RC_DP")
	)
	(arc
		(start 293.73957 -54.713886)
		(mid 293.530962 -54.925818)
		(end 293.24554 -55.009288)
		(width 0.0889)
		(layer "In4.Cu")
		(net "CLK_322M_OSC_CPU0_RC_DP")
	)
	(arc
		(start 292.02253 -55.704486)
		(mid 291.813922 -55.916418)
		(end 291.5285 -55.999888)
		(width 0.0889)
		(layer "In4.Cu")
		(net "CLK_322M_OSC_CPU0_RC_DP")
	)
	(arc
		(start 291.493194 -55.999888)
		(mid 291.302952 -56.057623)
		(end 291.16401 -56.199786)
		(width 0.0889)
		(layer "In4.Cu")
		(net "CLK_322M_OSC_CPU0_RC_DP")
	)
	(arc
		(start 293.212774 -55.009288)
		(mid 293.021132 -55.066454)
		(end 292.88105 -55.209186)
		(width 0.0889)
		(layer "In4.Cu")
		(net "CLK_322M_OSC_CPU0_RC_DP")
	)
	(arc
		(start 291.16401 -56.199786)
		(mid 290.948387 -56.415633)
		(end 290.653724 -56.49468)
		(width 0.0889)
		(layer "In4.Cu")
		(net "CLK_322M_OSC_CPU0_RC_DP")
	)
	(arc
		(start 294.602916 -53.63591)
		(mid 294.601208 -54.213509)
		(end 294.10787 -54.513734)
		(width 0.0889)
		(layer "In4.Cu")
		(net "CLK_322M_OSC_CPU0_RC_DP")
	)
	(arc
		(start 287.780984 -64.419734)
		(mid 287.587134 -64.476084)
		(end 287.44545 -64.619886)
		(width 0.0889)
		(layer "In4.Cu")
		(net "CLK_322M_OSC_CPU0_RC_DP")
	)
	(segment
		(start 317.5508 -31.2166)
		(end 317.5508 -30.79242)
		(width 0.127)
		(layer "F.Cu")
		(net "CLK_322M_OSC_CPU0_RC_DN")
	)
	(segment
		(start 317.5508 -30.79242)
		(end 317.757302 -30.585918)
		(width 0.127)
		(layer "F.Cu")
		(net "CLK_322M_OSC_CPU0_RC_DN")
	)
	(segment
		(start 285.2166 -66.305938)
		(end 285.7881 -66.305938)
		(width 0.127)
		(layer "F.Cu")
		(net "CLK_322M_OSC_CPU0_RC_DN")
	)
	(segment
		(start 317.757302 -30.585918)
		(end 317.9826 -30.585918)
		(width 0.127)
		(layer "F.Cu")
		(net "CLK_322M_OSC_CPU0_RC_DN")
	)
	(via
		(at 285.2166 -66.305938)
		(size 0.508)
		(drill 0.254)
		(layers "F.Cu" "B.Cu")
		(net "CLK_322M_OSC_CPU0_RC_DN")
	)
	(via
		(at 317.5508 -31.2166)
		(size 0.508)
		(drill 0.254)
		(layers "F.Cu" "B.Cu")
		(net "CLK_322M_OSC_CPU0_RC_DN")
	)
	(segment
		(start 289.917886 -59.631834)
		(end 289.917886 -59.936634)
		(width 0.0889)
		(layer "In4.Cu")
		(net "CLK_322M_OSC_CPU0_RC_DN")
	)
	(segment
		(start 289.917886 -58.869834)
		(end 289.917886 -59.174634)
		(width 0.0889)
		(layer "In4.Cu")
		(net "CLK_322M_OSC_CPU0_RC_DN")
	)
	(segment
		(start 289.841686 -61.536834)
		(end 289.841686 -61.841634)
		(width 0.0889)
		(layer "In4.Cu")
		(net "CLK_322M_OSC_CPU0_RC_DN")
	)
	(segment
		(start 286.41548 -65.599818)
		(end 286.42183 -65.610486)
		(width 0.0889)
		(layer "In4.Cu")
		(net "CLK_322M_OSC_CPU0_RC_DN")
	)
	(segment
		(start 319.0621 -31.997904)
		(end 319.0621 -32.302704)
		(width 0.1143)
		(layer "In4.Cu")
		(net "CLK_322M_OSC_CPU0_RC_DN")
	)
	(segment
		(start 318.3001 -29.712158)
		(end 318.3001 -30.626304)
		(width 0.1143)
		(layer "In4.Cu")
		(net "CLK_322M_OSC_CPU0_RC_DN")
	)
	(segment
		(start 289.841686 -58.031634)
		(end 289.917886 -58.107834)
		(width 0.0889)
		(layer "In4.Cu")
		(net "CLK_322M_OSC_CPU0_RC_DN")
	)
	(segment
		(start 291.521896 -55.809388)
		(end 291.48913 -55.809388)
		(width 0.0889)
		(layer "In4.Cu")
		(net "CLK_322M_OSC_CPU0_RC_DN")
	)
	(segment
		(start 319.2145 -31.845504)
		(end 319.0621 -31.997904)
		(width 0.1143)
		(layer "In4.Cu")
		(net "CLK_322M_OSC_CPU0_RC_DN")
	)
	(segment
		(start 289.917886 -62.222634)
		(end 289.841686 -62.298834)
		(width 0.0889)
		(layer "In4.Cu")
		(net "CLK_322M_OSC_CPU0_RC_DN")
	)
	(segment
		(start 317.970662 -29.38272)
		(end 318.3001 -29.712158)
		(width 0.1143)
		(layer "In4.Cu")
		(net "CLK_322M_OSC_CPU0_RC_DN")
	)
	(segment
		(start 289.917886 -61.917834)
		(end 289.917886 -62.222634)
		(width 0.0889)
		(layer "In4.Cu")
		(net "CLK_322M_OSC_CPU0_RC_DN")
	)
	(segment
		(start 317.525654 -34.5694)
		(end 315.011816 -34.5694)
		(width 0.1143)
		(layer "In4.Cu")
		(net "CLK_322M_OSC_CPU0_RC_DN")
	)
	(segment
		(start 297.82135 -50.569876)
		(end 296.968926 -51.4223)
		(width 0.1143)
		(layer "In4.Cu")
		(net "CLK_322M_OSC_CPU0_RC_DN")
	)
	(segment
		(start 294.101266 -54.323234)
		(end 294.0685 -54.323234)
		(width 0.0889)
		(layer "In4.Cu")
		(net "CLK_322M_OSC_CPU0_RC_DN")
	)
	(segment
		(start 289.841686 -62.298834)
		(end 289.841686 -62.603634)
		(width 0.0889)
		(layer "In4.Cu")
		(net "CLK_322M_OSC_CPU0_RC_DN")
	)
	(segment
		(start 294.132 -52.0446)
		(end 294.132 -52.451)
		(width 0.1143)
		(layer "In4.Cu")
		(net "CLK_322M_OSC_CPU0_RC_DN")
	)
	(segment
		(start 284.844998 -66.158364)
		(end 284.923738 -66.137028)
		(width 0.0889)
		(layer "In4.Cu")
		(net "CLK_322M_OSC_CPU0_RC_DN")
	)
	(segment
		(start 317.69558 -29.38272)
		(end 317.970662 -29.38272)
		(width 0.1143)
		(layer "In4.Cu")
		(net "CLK_322M_OSC_CPU0_RC_DN")
	)
	(segment
		(start 289.917886 -59.936634)
		(end 289.841686 -60.012834)
		(width 0.0889)
		(layer "In4.Cu")
		(net "CLK_322M_OSC_CPU0_RC_DN")
	)
	(segment
		(start 289.3695 -63.54572)
		(end 289.181032 -63.734188)
		(width 0.0889)
		(layer "In4.Cu")
		(net "CLK_322M_OSC_CPU0_RC_DN")
	)
	(segment
		(start 289.841686 -59.555634)
		(end 289.917886 -59.631834)
		(width 0.0889)
		(layer "In4.Cu")
		(net "CLK_322M_OSC_CPU0_RC_DN")
	)
	(segment
		(start 318.3001 -30.626304)
		(end 319.2145 -31.540704)
		(width 0.1143)
		(layer "In4.Cu")
		(net "CLK_322M_OSC_CPU0_RC_DN")
	)
	(segment
		(start 290.308284 -56.30418)
		(end 289.917886 -56.694578)
		(width 0.0889)
		(layer "In4.Cu")
		(net "CLK_322M_OSC_CPU0_RC_DN")
	)
	(segment
		(start 289.841686 -58.488834)
		(end 289.841686 -58.793634)
		(width 0.0889)
		(layer "In4.Cu")
		(net "CLK_322M_OSC_CPU0_RC_DN")
	)
	(segment
		(start 294.1828 -52.523898)
		(end 294.1828 -52.955952)
		(width 0.0889)
		(layer "In4.Cu")
		(net "CLK_322M_OSC_CPU0_RC_DN")
	)
	(segment
		(start 287.807146 -64.229234)
		(end 287.77438 -64.229234)
		(width 0.0889)
		(layer "In4.Cu")
		(net "CLK_322M_OSC_CPU0_RC_DN")
	)
	(segment
		(start 289.917886 -62.679834)
		(end 289.917886 -62.997334)
		(width 0.0889)
		(layer "In4.Cu")
		(net "CLK_322M_OSC_CPU0_RC_DN")
	)
	(segment
		(start 294.7543 -51.4223)
		(end 294.132 -52.0446)
		(width 0.1143)
		(layer "In4.Cu")
		(net "CLK_322M_OSC_CPU0_RC_DN")
	)
	(segment
		(start 289.181032 -63.734188)
		(end 288.632392 -63.734188)
		(width 0.0889)
		(layer "In4.Cu")
		(net "CLK_322M_OSC_CPU0_RC_DN")
	)
	(segment
		(start 292.384226 -55.313834)
		(end 292.35146 -55.313834)
		(width 0.0889)
		(layer "In4.Cu")
		(net "CLK_322M_OSC_CPU0_RC_DN")
	)
	(segment
		(start 289.917886 -56.694578)
		(end 289.917886 -57.650634)
		(width 0.0889)
		(layer "In4.Cu")
		(net "CLK_322M_OSC_CPU0_RC_DN")
	)
	(segment
		(start 289.917886 -60.698634)
		(end 289.841686 -60.774834)
		(width 0.0889)
		(layer "In4.Cu")
		(net "CLK_322M_OSC_CPU0_RC_DN")
	)
	(segment
		(start 296.968926 -51.4223)
		(end 294.7543 -51.4223)
		(width 0.1143)
		(layer "In4.Cu")
		(net "CLK_322M_OSC_CPU0_RC_DN")
	)
	(segment
		(start 286.42183 -65.610486)
		(end 286.426656 -65.619122)
		(width 0.0889)
		(layer "In4.Cu")
		(net "CLK_322M_OSC_CPU0_RC_DN")
	)
	(segment
		(start 319.2145 -32.880554)
		(end 317.525654 -34.5694)
		(width 0.1143)
		(layer "In4.Cu")
		(net "CLK_322M_OSC_CPU0_RC_DN")
	)
	(segment
		(start 319.2145 -32.455104)
		(end 319.2145 -32.880554)
		(width 0.1143)
		(layer "In4.Cu")
		(net "CLK_322M_OSC_CPU0_RC_DN")
	)
	(segment
		(start 289.841686 -59.250834)
		(end 289.841686 -59.555634)
		(width 0.0889)
		(layer "In4.Cu")
		(net "CLK_322M_OSC_CPU0_RC_DN")
	)
	(segment
		(start 315.011816 -34.5694)
		(end 299.01134 -50.569876)
		(width 0.1143)
		(layer "In4.Cu")
		(net "CLK_322M_OSC_CPU0_RC_DN")
	)
	(segment
		(start 289.841686 -61.841634)
		(end 289.917886 -61.917834)
		(width 0.0889)
		(layer "In4.Cu")
		(net "CLK_322M_OSC_CPU0_RC_DN")
	)
	(segment
		(start 289.3695 -63.41999)
		(end 289.3695 -63.54572)
		(width 0.0889)
		(layer "In4.Cu")
		(net "CLK_322M_OSC_CPU0_RC_DN")
	)
	(segment
		(start 293.238936 -54.818788)
		(end 293.20617 -54.818788)
		(width 0.0889)
		(layer "In4.Cu")
		(net "CLK_322M_OSC_CPU0_RC_DN")
	)
	(segment
		(start 319.0621 -32.302704)
		(end 319.2145 -32.455104)
		(width 0.1143)
		(layer "In4.Cu")
		(net "CLK_322M_OSC_CPU0_RC_DN")
	)
	(segment
		(start 289.683952 -63.231268)
		(end 289.558222 -63.231268)
		(width 0.0889)
		(layer "In4.Cu")
		(net "CLK_322M_OSC_CPU0_RC_DN")
	)
	(segment
		(start 286.944816 -64.724788)
		(end 286.91205 -64.724788)
		(width 0.0889)
		(layer "In4.Cu")
		(net "CLK_322M_OSC_CPU0_RC_DN")
	)
	(segment
		(start 294.280844 -53.45938)
		(end 294.433244 -53.723032)
		(width 0.0889)
		(layer "In4.Cu")
		(net "CLK_322M_OSC_CPU0_RC_DN")
	)
	(segment
		(start 289.841686 -61.079634)
		(end 289.917886 -61.155834)
		(width 0.0889)
		(layer "In4.Cu")
		(net "CLK_322M_OSC_CPU0_RC_DN")
	)
	(segment
		(start 290.65347 -56.30418)
		(end 290.308284 -56.30418)
		(width 0.0889)
		(layer "In4.Cu")
		(net "CLK_322M_OSC_CPU0_RC_DN")
	)
	(segment
		(start 317.5508 -31.2166)
		(end 317.5508 -29.5275)
		(width 0.1143)
		(layer "In4.Cu")
		(net "CLK_322M_OSC_CPU0_RC_DN")
	)
	(segment
		(start 289.917886 -58.107834)
		(end 289.917886 -58.412634)
		(width 0.0889)
		(layer "In4.Cu")
		(net "CLK_322M_OSC_CPU0_RC_DN")
	)
	(segment
		(start 289.917886 -60.393834)
		(end 289.917886 -60.698634)
		(width 0.0889)
		(layer "In4.Cu")
		(net "CLK_322M_OSC_CPU0_RC_DN")
	)
	(segment
		(start 294.179498 -53.064156)
		(end 294.280844 -53.45938)
		(width 0.0889)
		(layer "In4.Cu")
		(net "CLK_322M_OSC_CPU0_RC_DN")
	)
	(segment
		(start 289.558222 -63.231268)
		(end 289.3695 -63.41999)
		(width 0.0889)
		(layer "In4.Cu")
		(net "CLK_322M_OSC_CPU0_RC_DN")
	)
	(segment
		(start 289.917886 -62.997334)
		(end 289.683952 -63.231268)
		(width 0.0889)
		(layer "In4.Cu")
		(net "CLK_322M_OSC_CPU0_RC_DN")
	)
	(segment
		(start 294.132 -52.473098)
		(end 294.1828 -52.523898)
		(width 0.0889)
		(layer "In4.Cu")
		(net "CLK_322M_OSC_CPU0_RC_DN")
	)
	(segment
		(start 286.090106 -66.210434)
		(end 286.05734 -66.210434)
		(width 0.0889)
		(layer "In4.Cu")
		(net "CLK_322M_OSC_CPU0_RC_DN")
	)
	(segment
		(start 289.841686 -60.317634)
		(end 289.917886 -60.393834)
		(width 0.0889)
		(layer "In4.Cu")
		(net "CLK_322M_OSC_CPU0_RC_DN")
	)
	(segment
		(start 289.841686 -62.603634)
		(end 289.917886 -62.679834)
		(width 0.0889)
		(layer "In4.Cu")
		(net "CLK_322M_OSC_CPU0_RC_DN")
	)
	(segment
		(start 299.01134 -50.569876)
		(end 297.82135 -50.569876)
		(width 0.1143)
		(layer "In4.Cu")
		(net "CLK_322M_OSC_CPU0_RC_DN")
	)
	(segment
		(start 289.841686 -58.793634)
		(end 289.917886 -58.869834)
		(width 0.0889)
		(layer "In4.Cu")
		(net "CLK_322M_OSC_CPU0_RC_DN")
	)
	(segment
		(start 284.923738 -66.137028)
		(end 285.2166 -66.305938)
		(width 0.0889)
		(layer "In4.Cu")
		(net "CLK_322M_OSC_CPU0_RC_DN")
	)
	(segment
		(start 289.917886 -58.412634)
		(end 289.841686 -58.488834)
		(width 0.0889)
		(layer "In4.Cu")
		(net "CLK_322M_OSC_CPU0_RC_DN")
	)
	(segment
		(start 289.841686 -57.726834)
		(end 289.841686 -58.031634)
		(width 0.0889)
		(layer "In4.Cu")
		(net "CLK_322M_OSC_CPU0_RC_DN")
	)
	(segment
		(start 289.841686 -60.774834)
		(end 289.841686 -61.079634)
		(width 0.0889)
		(layer "In4.Cu")
		(net "CLK_322M_OSC_CPU0_RC_DN")
	)
	(segment
		(start 294.1828 -52.955952)
		(end 294.179498 -53.064156)
		(width 0.0889)
		(layer "In4.Cu")
		(net "CLK_322M_OSC_CPU0_RC_DN")
	)
	(segment
		(start 289.917886 -61.460634)
		(end 289.841686 -61.536834)
		(width 0.0889)
		(layer "In4.Cu")
		(net "CLK_322M_OSC_CPU0_RC_DN")
	)
	(segment
		(start 319.2145 -31.540704)
		(end 319.2145 -31.845504)
		(width 0.1143)
		(layer "In4.Cu")
		(net "CLK_322M_OSC_CPU0_RC_DN")
	)
	(segment
		(start 289.841686 -60.012834)
		(end 289.841686 -60.317634)
		(width 0.0889)
		(layer "In4.Cu")
		(net "CLK_322M_OSC_CPU0_RC_DN")
	)
	(segment
		(start 289.917886 -59.174634)
		(end 289.841686 -59.250834)
		(width 0.0889)
		(layer "In4.Cu")
		(net "CLK_322M_OSC_CPU0_RC_DN")
	)
	(segment
		(start 294.433244 -53.723032)
		(end 294.437816 -53.731922)
		(width 0.0889)
		(layer "In4.Cu")
		(net "CLK_322M_OSC_CPU0_RC_DN")
	)
	(segment
		(start 294.132 -52.451)
		(end 294.132 -52.473098)
		(width 0.0889)
		(layer "In4.Cu")
		(net "CLK_322M_OSC_CPU0_RC_DN")
	)
	(segment
		(start 289.917886 -61.155834)
		(end 289.917886 -61.460634)
		(width 0.0889)
		(layer "In4.Cu")
		(net "CLK_322M_OSC_CPU0_RC_DN")
	)
	(segment
		(start 289.917886 -57.650634)
		(end 289.841686 -57.726834)
		(width 0.0889)
		(layer "In4.Cu")
		(net "CLK_322M_OSC_CPU0_RC_DN")
	)
	(segment
		(start 317.5508 -29.5275)
		(end 317.69558 -29.38272)
		(width 0.1143)
		(layer "In4.Cu")
		(net "CLK_322M_OSC_CPU0_RC_DN")
	)
	(arc
		(start 293.20617 -54.818788)
		(mid 292.922953 -54.903069)
		(end 292.71595 -55.113936)
		(width 0.0889)
		(layer "In4.Cu")
		(net "CLK_322M_OSC_CPU0_RC_DN")
	)
	(arc
		(start 292.35146 -55.313834)
		(mid 292.066036 -55.397301)
		(end 291.85743 -55.609236)
		(width 0.0889)
		(layer "In4.Cu")
		(net "CLK_322M_OSC_CPU0_RC_DN")
	)
	(arc
		(start 294.437816 -53.731922)
		(mid 294.434069 -54.121178)
		(end 294.101266 -54.323234)
		(width 0.0889)
		(layer "In4.Cu")
		(net "CLK_322M_OSC_CPU0_RC_DN")
	)
	(arc
		(start 287.77438 -64.229234)
		(mid 287.488956 -64.312701)
		(end 287.28035 -64.524636)
		(width 0.0889)
		(layer "In4.Cu")
		(net "CLK_322M_OSC_CPU0_RC_DN")
	)
	(arc
		(start 293.57447 -54.618636)
		(mid 293.432787 -54.76244)
		(end 293.238936 -54.818788)
		(width 0.0889)
		(layer "In4.Cu")
		(net "CLK_322M_OSC_CPU0_RC_DN")
	)
	(arc
		(start 288.13887 -64.029336)
		(mid 287.998791 -64.172072)
		(end 287.807146 -64.229234)
		(width 0.0889)
		(layer "In4.Cu")
		(net "CLK_322M_OSC_CPU0_RC_DN")
	)
	(arc
		(start 287.28035 -64.524636)
		(mid 287.138667 -64.66844)
		(end 286.944816 -64.724788)
		(width 0.0889)
		(layer "In4.Cu")
		(net "CLK_322M_OSC_CPU0_RC_DN")
	)
	(arc
		(start 290.99891 -56.104536)
		(mid 290.852948 -56.250643)
		(end 290.65347 -56.30418)
		(width 0.0889)
		(layer "In4.Cu")
		(net "CLK_322M_OSC_CPU0_RC_DN")
	)
	(arc
		(start 292.71595 -55.113936)
		(mid 292.575871 -55.256672)
		(end 292.384226 -55.313834)
		(width 0.0889)
		(layer "In4.Cu")
		(net "CLK_322M_OSC_CPU0_RC_DN")
	)
	(arc
		(start 286.426656 -65.619122)
		(mid 286.422909 -66.008378)
		(end 286.090106 -66.210434)
		(width 0.0889)
		(layer "In4.Cu")
		(net "CLK_322M_OSC_CPU0_RC_DN")
	)
	(arc
		(start 285.56331 -66.505836)
		(mid 285.422096 -66.649466)
		(end 285.228792 -66.705988)
		(width 0.0889)
		(layer "In4.Cu")
		(net "CLK_322M_OSC_CPU0_RC_DN")
	)
	(arc
		(start 291.85743 -55.609236)
		(mid 291.715747 -55.75304)
		(end 291.521896 -55.809388)
		(width 0.0889)
		(layer "In4.Cu")
		(net "CLK_322M_OSC_CPU0_RC_DN")
	)
	(arc
		(start 286.05734 -66.210434)
		(mid 285.771916 -66.293901)
		(end 285.56331 -66.505836)
		(width 0.0889)
		(layer "In4.Cu")
		(net "CLK_322M_OSC_CPU0_RC_DN")
	)
	(arc
		(start 285.228792 -66.705988)
		(mid 285.216727 -66.706166)
		(end 285.204662 -66.705988)
		(width 0.0889)
		(layer "In4.Cu")
		(net "CLK_322M_OSC_CPU0_RC_DN")
	)
	(arc
		(start 284.818074 -66.273426)
		(mid 284.827248 -66.21489)
		(end 284.844998 -66.158364)
		(width 0.0889)
		(layer "In4.Cu")
		(net "CLK_322M_OSC_CPU0_RC_DN")
	)
	(arc
		(start 284.864302 -66.495422)
		(mid 284.825107 -66.38777)
		(end 284.818074 -66.273426)
		(width 0.0889)
		(layer "In4.Cu")
		(net "CLK_322M_OSC_CPU0_RC_DN")
	)
	(arc
		(start 285.204662 -66.705988)
		(mid 285.006221 -66.646368)
		(end 284.864302 -66.495422)
		(width 0.0889)
		(layer "In4.Cu")
		(net "CLK_322M_OSC_CPU0_RC_DN")
	)
	(arc
		(start 288.632392 -63.734188)
		(mid 288.347345 -63.817716)
		(end 288.13887 -64.029336)
		(width 0.0889)
		(layer "In4.Cu")
		(net "CLK_322M_OSC_CPU0_RC_DN")
	)
	(arc
		(start 291.48913 -55.809388)
		(mid 291.205913 -55.893669)
		(end 290.99891 -56.104536)
		(width 0.0889)
		(layer "In4.Cu")
		(net "CLK_322M_OSC_CPU0_RC_DN")
	)
	(arc
		(start 286.91205 -64.724788)
		(mid 286.41966 -65.023721)
		(end 286.41548 -65.599818)
		(width 0.0889)
		(layer "In4.Cu")
		(net "CLK_322M_OSC_CPU0_RC_DN")
	)
	(arc
		(start 294.0685 -54.323234)
		(mid 293.783076 -54.406701)
		(end 293.57447 -54.618636)
		(width 0.0889)
		(layer "In4.Cu")
		(net "CLK_322M_OSC_CPU0_RC_DN")
	)
	(segment
		(start 489.5469 -41.9862)
		(end 490.9693 -41.9862)
		(width 0.10795)
		(layer "F.Cu")
		(net "RMII_SPRNGVLLE_BMC_PCH_RXD1_R")
	)
	(segment
		(start 490.9693 -41.9862)
		(end 491.0455 -42.0624)
		(width 0.10795)
		(layer "F.Cu")
		(net "RMII_SPRNGVLLE_BMC_PCH_RXD1_R")
	)
	(segment
		(start 491.0455 -42.158158)
		(end 491.404148 -42.516806)
		(width 0.10795)
		(layer "F.Cu")
		(net "RMII_SPRNGVLLE_BMC_PCH_RXD1_R")
	)
	(segment
		(start 491.404148 -42.516806)
		(end 493.67186 -42.516806)
		(width 0.10795)
		(layer "F.Cu")
		(net "RMII_SPRNGVLLE_BMC_PCH_RXD1_R")
	)
	(segment
		(start 493.67186 -42.516806)
		(end 493.725962 -42.462704)
		(width 0.10795)
		(layer "F.Cu")
		(net "RMII_SPRNGVLLE_BMC_PCH_RXD1_R")
	)
	(segment
		(start 488.6198 -42.21734)
		(end 489.31576 -42.21734)
		(width 0.10795)
		(layer "F.Cu")
		(net "RMII_SPRNGVLLE_BMC_PCH_RXD1_R")
	)
	(segment
		(start 491.0455 -42.0624)
		(end 491.0455 -42.158158)
		(width 0.10795)
		(layer "F.Cu")
		(net "RMII_SPRNGVLLE_BMC_PCH_RXD1_R")
	)
	(segment
		(start 489.31576 -42.21734)
		(end 489.5469 -41.9862)
		(width 0.10795)
		(layer "F.Cu")
		(net "RMII_SPRNGVLLE_BMC_PCH_RXD1_R")
	)
	(via
		(at 493.725962 -42.462704)
		(size 0.762)
		(drill 0.381)
		(layers "F.Cu" "B.Cu")
		(net "RMII_SPRNGVLLE_BMC_PCH_RXD1_R")
	)
	(segment
		(start 489.174282 -41.217342)
		(end 488.6198 -41.217342)
		(width 0.10795)
		(layer "F.Cu")
		(net "RMII_BMC_PCH_SPRNGVLLE_CRSDV_R")
	)
	(segment
		(start 491.0455 -40.0304)
		(end 490.22 -40.0304)
		(width 0.10795)
		(layer "F.Cu")
		(net "RMII_BMC_PCH_SPRNGVLLE_CRSDV_R")
	)
	(segment
		(start 490.22 -40.0304)
		(end 489.966 -40.2844)
		(width 0.10795)
		(layer "F.Cu")
		(net "RMII_BMC_PCH_SPRNGVLLE_CRSDV_R")
	)
	(segment
		(start 489.966 -40.425624)
		(end 489.174282 -41.217342)
		(width 0.10795)
		(layer "F.Cu")
		(net "RMII_BMC_PCH_SPRNGVLLE_CRSDV_R")
	)
	(segment
		(start 489.966 -40.2844)
		(end 489.966 -40.425624)
		(width 0.10795)
		(layer "F.Cu")
		(net "RMII_BMC_PCH_SPRNGVLLE_CRSDV_R")
	)
	(via
		(at 489.966 -40.2844)
		(size 0.508)
		(drill 0.254)
		(layers "F.Cu" "B.Cu")
		(net "RMII_BMC_PCH_SPRNGVLLE_CRSDV_R")
	)
	(via
		(at 16.44015 -100.74783)
		(size 0.508)
		(drill 0.254)
		(layers "F.Cu" "B.Cu")
		(net "P3E_CPU1_PE3_MP_C_TXP<9>")
	)
	(segment
		(start 17.480788 -100.246688)
		(end 16.941292 -100.246688)
		(width 0.1143)
		(layer "B.Cu")
		(net "P3E_CPU1_PE3_MP_C_TXP<9>")
	)
	(segment
		(start 16.941292 -100.246688)
		(end 16.44015 -100.74783)
		(width 0.1143)
		(layer "B.Cu")
		(net "P3E_CPU1_PE3_MP_C_TXP<9>")
	)
	(segment
		(start 17.83842 -100.60432)
		(end 17.480788 -100.246688)
		(width 0.1143)
		(layer "B.Cu")
		(net "P3E_CPU1_PE3_MP_C_TXP<9>")
	)
	(segment
		(start 2.555494 -90.769948)
		(end 2.446274 -90.660728)
		(width 0.1143)
		(layer "In4.Cu")
		(net "P3E_CPU1_PE3_MP_C_TXP<9>")
	)
	(segment
		(start 16.22552 -100.31222)
		(end 16.32585 -100.31222)
		(width 0.1143)
		(layer "In4.Cu")
		(net "P3E_CPU1_PE3_MP_C_TXP<9>")
	)
	(segment
		(start 7.063486 -89.585546)
		(end 7.406386 -89.585546)
		(width 0.1143)
		(layer "In4.Cu")
		(net "P3E_CPU1_PE3_MP_C_TXP<9>")
	)
	(segment
		(start 7.914386 -89.420446)
		(end 8.079486 -89.585546)
		(width 0.1143)
		(layer "In4.Cu")
		(net "P3E_CPU1_PE3_MP_C_TXP<9>")
	)
	(segment
		(start 6.390386 -89.585546)
		(end 6.555486 -89.420446)
		(width 0.1143)
		(layer "In4.Cu")
		(net "P3E_CPU1_PE3_MP_C_TXP<9>")
	)
	(segment
		(start 8.930386 -89.420446)
		(end 11.054334 -91.544394)
		(width 0.1143)
		(layer "In4.Cu")
		(net "P3E_CPU1_PE3_MP_C_TXP<9>")
	)
	(segment
		(start 2.446274 -90.660728)
		(end 2.446274 -89.918032)
		(width 0.1143)
		(layer "In4.Cu")
		(net "P3E_CPU1_PE3_MP_C_TXP<9>")
	)
	(segment
		(start 11.054334 -93.901006)
		(end 13.113512 -99.397058)
		(width 0.1143)
		(layer "In4.Cu")
		(net "P3E_CPU1_PE3_MP_C_TXP<9>")
	)
	(segment
		(start 16.44015 -100.42652)
		(end 16.44015 -100.74783)
		(width 0.1143)
		(layer "In4.Cu")
		(net "P3E_CPU1_PE3_MP_C_TXP<9>")
	)
	(segment
		(start 10.919206 -92.559632)
		(end 11.054334 -92.69476)
		(width 0.1143)
		(layer "In4.Cu")
		(net "P3E_CPU1_PE3_MP_C_TXP<9>")
	)
	(segment
		(start 7.406386 -89.585546)
		(end 7.571486 -89.420446)
		(width 0.1143)
		(layer "In4.Cu")
		(net "P3E_CPU1_PE3_MP_C_TXP<9>")
	)
	(segment
		(start 6.047486 -89.585546)
		(end 6.390386 -89.585546)
		(width 0.1143)
		(layer "In4.Cu")
		(net "P3E_CPU1_PE3_MP_C_TXP<9>")
	)
	(segment
		(start 13.113512 -99.397058)
		(end 14.033754 -100.3173)
		(width 0.1143)
		(layer "In4.Cu")
		(net "P3E_CPU1_PE3_MP_C_TXP<9>")
	)
	(segment
		(start 2.94386 -89.420446)
		(end 5.882386 -89.420446)
		(width 0.1143)
		(layer "In4.Cu")
		(net "P3E_CPU1_PE3_MP_C_TXP<9>")
	)
	(segment
		(start 2.999994 -90.769948)
		(end 2.555494 -90.769948)
		(width 0.1143)
		(layer "In4.Cu")
		(net "P3E_CPU1_PE3_MP_C_TXP<9>")
	)
	(segment
		(start 11.054334 -92.69476)
		(end 11.054334 -93.901006)
		(width 0.1143)
		(layer "In4.Cu")
		(net "P3E_CPU1_PE3_MP_C_TXP<9>")
	)
	(segment
		(start 11.054334 -92.081604)
		(end 10.919206 -92.216732)
		(width 0.1143)
		(layer "In4.Cu")
		(net "P3E_CPU1_PE3_MP_C_TXP<9>")
	)
	(segment
		(start 2.446274 -89.918032)
		(end 2.94386 -89.420446)
		(width 0.1143)
		(layer "In4.Cu")
		(net "P3E_CPU1_PE3_MP_C_TXP<9>")
	)
	(segment
		(start 6.555486 -89.420446)
		(end 6.898386 -89.420446)
		(width 0.1143)
		(layer "In4.Cu")
		(net "P3E_CPU1_PE3_MP_C_TXP<9>")
	)
	(segment
		(start 7.571486 -89.420446)
		(end 7.914386 -89.420446)
		(width 0.1143)
		(layer "In4.Cu")
		(net "P3E_CPU1_PE3_MP_C_TXP<9>")
	)
	(segment
		(start 10.919206 -92.216732)
		(end 10.919206 -92.559632)
		(width 0.1143)
		(layer "In4.Cu")
		(net "P3E_CPU1_PE3_MP_C_TXP<9>")
	)
	(segment
		(start 8.422386 -89.585546)
		(end 8.587486 -89.420446)
		(width 0.1143)
		(layer "In4.Cu")
		(net "P3E_CPU1_PE3_MP_C_TXP<9>")
	)
	(segment
		(start 14.033754 -100.3173)
		(end 16.22044 -100.3173)
		(width 0.1143)
		(layer "In4.Cu")
		(net "P3E_CPU1_PE3_MP_C_TXP<9>")
	)
	(segment
		(start 8.587486 -89.420446)
		(end 8.930386 -89.420446)
		(width 0.1143)
		(layer "In4.Cu")
		(net "P3E_CPU1_PE3_MP_C_TXP<9>")
	)
	(segment
		(start 6.898386 -89.420446)
		(end 7.063486 -89.585546)
		(width 0.1143)
		(layer "In4.Cu")
		(net "P3E_CPU1_PE3_MP_C_TXP<9>")
	)
	(segment
		(start 8.079486 -89.585546)
		(end 8.422386 -89.585546)
		(width 0.1143)
		(layer "In4.Cu")
		(net "P3E_CPU1_PE3_MP_C_TXP<9>")
	)
	(segment
		(start 16.22044 -100.3173)
		(end 16.22552 -100.31222)
		(width 0.1143)
		(layer "In4.Cu")
		(net "P3E_CPU1_PE3_MP_C_TXP<9>")
	)
	(segment
		(start 11.054334 -91.544394)
		(end 11.054334 -92.081604)
		(width 0.1143)
		(layer "In4.Cu")
		(net "P3E_CPU1_PE3_MP_C_TXP<9>")
	)
	(segment
		(start 16.32585 -100.31222)
		(end 16.44015 -100.42652)
		(width 0.1143)
		(layer "In4.Cu")
		(net "P3E_CPU1_PE3_MP_C_TXP<9>")
	)
	(segment
		(start 5.882386 -89.420446)
		(end 6.047486 -89.585546)
		(width 0.1143)
		(layer "In4.Cu")
		(net "P3E_CPU1_PE3_MP_C_TXP<9>")
	)
	(segment
		(start 10.881106 -93.80855)
		(end 10.819384 -93.957902)
		(width 0.1143)
		(layer "B.Cu")
		(net "P3E_CPU1_PE3_MP_C_TXP<8>")
	)
	(segment
		(start 8.217916 -89.81948)
		(end 8.564626 -89.81948)
		(width 0.1143)
		(layer "B.Cu")
		(net "P3E_CPU1_PE3_MP_C_TXP<8>")
	)
	(segment
		(start 11.533632 -96.084136)
		(end 11.667998 -96.174052)
		(width 0.1143)
		(layer "B.Cu")
		(net "P3E_CPU1_PE3_MP_C_TXP<8>")
	)
	(segment
		(start 10.250424 -92.585286)
		(end 10.399776 -92.647262)
		(width 0.1143)
		(layer "B.Cu")
		(net "P3E_CPU1_PE3_MP_C_TXP<8>")
	)
	(segment
		(start 7.303516 -89.81948)
		(end 7.646416 -89.81948)
		(width 0.1143)
		(layer "B.Cu")
		(net "P3E_CPU1_PE3_MP_C_TXP<8>")
	)
	(segment
		(start -1.20015 -90.769948)
		(end -1.43129 -90.769948)
		(width 0.1143)
		(layer "B.Cu")
		(net "P3E_CPU1_PE3_MP_C_TXP<8>")
	)
	(segment
		(start 10.119106 -92.268548)
		(end 10.250424 -92.585286)
		(width 0.1143)
		(layer "B.Cu")
		(net "P3E_CPU1_PE3_MP_C_TXP<8>")
	)
	(segment
		(start 9.900412 -91.740482)
		(end 10.049764 -91.802458)
		(width 0.1143)
		(layer "B.Cu")
		(net "P3E_CPU1_PE3_MP_C_TXP<8>")
	)
	(segment
		(start -1.43129 -90.769948)
		(end -1.66624 -90.534998)
		(width 0.1143)
		(layer "B.Cu")
		(net "P3E_CPU1_PE3_MP_C_TXP<8>")
	)
	(segment
		(start 10.749788 -93.491812)
		(end 10.881106 -93.80855)
		(width 0.1143)
		(layer "B.Cu")
		(net "P3E_CPU1_PE3_MP_C_TXP<8>")
	)
	(segment
		(start 10.469118 -93.113352)
		(end 10.600436 -93.43009)
		(width 0.1143)
		(layer "B.Cu")
		(net "P3E_CPU1_PE3_MP_C_TXP<8>")
	)
	(segment
		(start 10.531094 -92.964)
		(end 10.469118 -93.113352)
		(width 0.1143)
		(layer "B.Cu")
		(net "P3E_CPU1_PE3_MP_C_TXP<8>")
	)
	(segment
		(start 9.83107 -91.274392)
		(end 9.769094 -91.423744)
		(width 0.1143)
		(layer "B.Cu")
		(net "P3E_CPU1_PE3_MP_C_TXP<8>")
	)
	(segment
		(start 12.388088 -97.681288)
		(end 12.790424 -97.678748)
		(width 0.1143)
		(layer "B.Cu")
		(net "P3E_CPU1_PE3_MP_C_TXP<8>")
	)
	(segment
		(start 11.46683 -95.74784)
		(end 11.533632 -96.084136)
		(width 0.1143)
		(layer "B.Cu")
		(net "P3E_CPU1_PE3_MP_C_TXP<8>")
	)
	(segment
		(start 9.769094 -91.423744)
		(end 9.900412 -91.740482)
		(width 0.1143)
		(layer "B.Cu")
		(net "P3E_CPU1_PE3_MP_C_TXP<8>")
	)
	(segment
		(start 7.189216 -89.93378)
		(end 7.303516 -89.81948)
		(width 0.1143)
		(layer "B.Cu")
		(net "P3E_CPU1_PE3_MP_C_TXP<8>")
	)
	(segment
		(start 11.863324 -97.156524)
		(end 12.388088 -97.681288)
		(width 0.1143)
		(layer "B.Cu")
		(net "P3E_CPU1_PE3_MP_C_TXP<8>")
	)
	(segment
		(start 10.950448 -94.274894)
		(end 11.0998 -94.336616)
		(width 0.1143)
		(layer "B.Cu")
		(net "P3E_CPU1_PE3_MP_C_TXP<8>")
	)
	(segment
		(start 7.760716 -89.93378)
		(end 8.103616 -89.93378)
		(width 0.1143)
		(layer "B.Cu")
		(net "P3E_CPU1_PE3_MP_C_TXP<8>")
	)
	(segment
		(start -1.66624 -90.534998)
		(end -1.66624 -90.163396)
		(width 0.1143)
		(layer "B.Cu")
		(net "P3E_CPU1_PE3_MP_C_TXP<8>")
	)
	(segment
		(start -1.322324 -89.81948)
		(end 6.732016 -89.81948)
		(width 0.1143)
		(layer "B.Cu")
		(net "P3E_CPU1_PE3_MP_C_TXP<8>")
	)
	(segment
		(start 10.600436 -93.43009)
		(end 10.749788 -93.491812)
		(width 0.1143)
		(layer "B.Cu")
		(net "P3E_CPU1_PE3_MP_C_TXP<8>")
	)
	(segment
		(start 8.564626 -89.81948)
		(end 9.697466 -90.95232)
		(width 0.1143)
		(layer "B.Cu")
		(net "P3E_CPU1_PE3_MP_C_TXP<8>")
	)
	(segment
		(start 6.732016 -89.81948)
		(end 6.846316 -89.93378)
		(width 0.1143)
		(layer "B.Cu")
		(net "P3E_CPU1_PE3_MP_C_TXP<8>")
	)
	(segment
		(start 11.556492 -95.613474)
		(end 11.46683 -95.74784)
		(width 0.1143)
		(layer "B.Cu")
		(net "P3E_CPU1_PE3_MP_C_TXP<8>")
	)
	(segment
		(start -1.66624 -90.163396)
		(end -1.322324 -89.81948)
		(width 0.1143)
		(layer "B.Cu")
		(net "P3E_CPU1_PE3_MP_C_TXP<8>")
	)
	(segment
		(start 10.819384 -93.957902)
		(end 10.950448 -94.274894)
		(width 0.1143)
		(layer "B.Cu")
		(net "P3E_CPU1_PE3_MP_C_TXP<8>")
	)
	(segment
		(start 10.181082 -92.119196)
		(end 10.119106 -92.268548)
		(width 0.1143)
		(layer "B.Cu")
		(net "P3E_CPU1_PE3_MP_C_TXP<8>")
	)
	(segment
		(start 7.646416 -89.81948)
		(end 7.760716 -89.93378)
		(width 0.1143)
		(layer "B.Cu")
		(net "P3E_CPU1_PE3_MP_C_TXP<8>")
	)
	(segment
		(start 12.790424 -97.678748)
		(end 13.11402 -97.99828)
		(width 0.1143)
		(layer "B.Cu")
		(net "P3E_CPU1_PE3_MP_C_TXP<8>")
	)
	(segment
		(start 10.399776 -92.647262)
		(end 10.531094 -92.964)
		(width 0.1143)
		(layer "B.Cu")
		(net "P3E_CPU1_PE3_MP_C_TXP<8>")
	)
	(segment
		(start 11.0998 -94.336616)
		(end 11.48969 -95.277178)
		(width 0.1143)
		(layer "B.Cu")
		(net "P3E_CPU1_PE3_MP_C_TXP<8>")
	)
	(segment
		(start 6.846316 -89.93378)
		(end 7.189216 -89.93378)
		(width 0.1143)
		(layer "B.Cu")
		(net "P3E_CPU1_PE3_MP_C_TXP<8>")
	)
	(segment
		(start 10.049764 -91.802458)
		(end 10.181082 -92.119196)
		(width 0.1143)
		(layer "B.Cu")
		(net "P3E_CPU1_PE3_MP_C_TXP<8>")
	)
	(segment
		(start 9.697466 -90.95232)
		(end 9.83107 -91.274392)
		(width 0.1143)
		(layer "B.Cu")
		(net "P3E_CPU1_PE3_MP_C_TXP<8>")
	)
	(segment
		(start 11.48969 -95.277178)
		(end 11.556492 -95.613474)
		(width 0.1143)
		(layer "B.Cu")
		(net "P3E_CPU1_PE3_MP_C_TXP<8>")
	)
	(segment
		(start 8.103616 -89.93378)
		(end 8.217916 -89.81948)
		(width 0.1143)
		(layer "B.Cu")
		(net "P3E_CPU1_PE3_MP_C_TXP<8>")
	)
	(segment
		(start 11.667998 -96.174052)
		(end 11.863324 -97.156524)
		(width 0.1143)
		(layer "B.Cu")
		(net "P3E_CPU1_PE3_MP_C_TXP<8>")
	)
	(via
		(at 16.607536 -102.427532)
		(size 0.508)
		(drill 0.254)
		(layers "F.Cu" "B.Cu")
		(net "P3E_CPU1_PE3_MP_C_TXN<15>")
	)
	(segment
		(start 17.83842 -102.611936)
		(end 17.83842 -102.45852)
		(width 0.1143)
		(layer "B.Cu")
		(net "P3E_CPU1_PE3_MP_C_TXN<15>")
	)
	(segment
		(start 17.547082 -102.903274)
		(end 17.83842 -102.611936)
		(width 0.1143)
		(layer "B.Cu")
		(net "P3E_CPU1_PE3_MP_C_TXN<15>")
	)
	(segment
		(start 16.715486 -102.973632)
		(end 17.208246 -102.973632)
		(width 0.1143)
		(layer "B.Cu")
		(net "P3E_CPU1_PE3_MP_C_TXN<15>")
	)
	(segment
		(start 17.278604 -102.903274)
		(end 17.547082 -102.903274)
		(width 0.1143)
		(layer "B.Cu")
		(net "P3E_CPU1_PE3_MP_C_TXN<15>")
	)
	(segment
		(start 16.607536 -102.865682)
		(end 16.715486 -102.973632)
		(width 0.1143)
		(layer "B.Cu")
		(net "P3E_CPU1_PE3_MP_C_TXN<15>")
	)
	(segment
		(start 17.208246 -102.973632)
		(end 17.278604 -102.903274)
		(width 0.1143)
		(layer "B.Cu")
		(net "P3E_CPU1_PE3_MP_C_TXN<15>")
	)
	(segment
		(start 16.607536 -102.427532)
		(end 16.607536 -102.865682)
		(width 0.1143)
		(layer "B.Cu")
		(net "P3E_CPU1_PE3_MP_C_TXN<15>")
	)
	(segment
		(start 6.37286 -95.485458)
		(end 6.704076 -95.816674)
		(width 0.1143)
		(layer "In4.Cu")
		(net "P3E_CPU1_PE3_MP_C_TXN<15>")
	)
	(segment
		(start 11.45413 -101.400864)
		(end 11.45413 -103.817928)
		(width 0.1143)
		(layer "In4.Cu")
		(net "P3E_CPU1_PE3_MP_C_TXN<15>")
	)
	(segment
		(start 17.037812 -103.106474)
		(end 16.607536 -102.676198)
		(width 0.1143)
		(layer "In4.Cu")
		(net "P3E_CPU1_PE3_MP_C_TXN<15>")
	)
	(segment
		(start 12.845542 -105.20934)
		(end 15.838932 -105.20934)
		(width 0.1143)
		(layer "In4.Cu")
		(net "P3E_CPU1_PE3_MP_C_TXN<15>")
	)
	(segment
		(start 5.80009 -94.76994)
		(end 6.116066 -94.76994)
		(width 0.1143)
		(layer "In4.Cu")
		(net "P3E_CPU1_PE3_MP_C_TXN<15>")
	)
	(segment
		(start 7.604506 -95.816674)
		(end 10.24509 -98.482658)
		(width 0.1143)
		(layer "In4.Cu")
		(net "P3E_CPU1_PE3_MP_C_TXN<15>")
	)
	(segment
		(start 6.37286 -95.026734)
		(end 6.37286 -95.485458)
		(width 0.1143)
		(layer "In4.Cu")
		(net "P3E_CPU1_PE3_MP_C_TXN<15>")
	)
	(segment
		(start 17.037812 -104.01046)
		(end 17.037812 -103.106474)
		(width 0.1143)
		(layer "In4.Cu")
		(net "P3E_CPU1_PE3_MP_C_TXN<15>")
	)
	(segment
		(start 16.607536 -102.676198)
		(end 16.607536 -102.427532)
		(width 0.1143)
		(layer "In4.Cu")
		(net "P3E_CPU1_PE3_MP_C_TXN<15>")
	)
	(segment
		(start 10.24509 -98.482658)
		(end 11.45413 -101.400864)
		(width 0.1143)
		(layer "In4.Cu")
		(net "P3E_CPU1_PE3_MP_C_TXN<15>")
	)
	(segment
		(start 6.704076 -95.816674)
		(end 7.604506 -95.816674)
		(width 0.1143)
		(layer "In4.Cu")
		(net "P3E_CPU1_PE3_MP_C_TXN<15>")
	)
	(segment
		(start 15.838932 -105.20934)
		(end 17.037812 -104.01046)
		(width 0.1143)
		(layer "In4.Cu")
		(net "P3E_CPU1_PE3_MP_C_TXN<15>")
	)
	(segment
		(start 11.45413 -103.817928)
		(end 12.845542 -105.20934)
		(width 0.1143)
		(layer "In4.Cu")
		(net "P3E_CPU1_PE3_MP_C_TXN<15>")
	)
	(segment
		(start 6.116066 -94.76994)
		(end 6.37286 -95.026734)
		(width 0.1143)
		(layer "In4.Cu")
		(net "P3E_CPU1_PE3_MP_C_TXN<15>")
	)
	(segment
		(start 9.342628 -97.155)
		(end 9.584944 -97.39757)
		(width 0.1143)
		(layer "B.Cu")
		(net "P3E_CPU1_PE3_MP_C_TXP<14>")
	)
	(segment
		(start 2.999994 -94.76994)
		(end 2.54 -94.76994)
		(width 0.1143)
		(layer "B.Cu")
		(net "P3E_CPU1_PE3_MP_C_TXP<14>")
	)
	(segment
		(start 10.384282 -98.829368)
		(end 10.515346 -99.146106)
		(width 0.1143)
		(layer "B.Cu")
		(net "P3E_CPU1_PE3_MP_C_TXP<14>")
	)
	(segment
		(start 7.679944 -95.654368)
		(end 8.534146 -96.50857)
		(width 0.1143)
		(layer "B.Cu")
		(net "P3E_CPU1_PE3_MP_C_TXP<14>")
	)
	(segment
		(start 11.153394 -100.985066)
		(end 11.284712 -101.301804)
		(width 0.1143)
		(layer "B.Cu")
		(net "P3E_CPU1_PE3_MP_C_TXP<14>")
	)
	(segment
		(start 2.42062 -95.33382)
		(end 2.741168 -95.654368)
		(width 0.1143)
		(layer "B.Cu")
		(net "P3E_CPU1_PE3_MP_C_TXP<14>")
	)
	(segment
		(start 8.534146 -96.50857)
		(end 8.695944 -96.50857)
		(width 0.1143)
		(layer "B.Cu")
		(net "P3E_CPU1_PE3_MP_C_TXP<14>")
	)
	(segment
		(start 2.741168 -95.654368)
		(end 7.679944 -95.654368)
		(width 0.1143)
		(layer "B.Cu")
		(net "P3E_CPU1_PE3_MP_C_TXP<14>")
	)
	(segment
		(start 11.084052 -100.518976)
		(end 11.21537 -100.835714)
		(width 0.1143)
		(layer "B.Cu")
		(net "P3E_CPU1_PE3_MP_C_TXP<14>")
	)
	(segment
		(start 10.453624 -99.295458)
		(end 10.584688 -99.612196)
		(width 0.1143)
		(layer "B.Cu")
		(net "P3E_CPU1_PE3_MP_C_TXP<14>")
	)
	(segment
		(start 10.23493 -98.767392)
		(end 10.384282 -98.829368)
		(width 0.1143)
		(layer "B.Cu")
		(net "P3E_CPU1_PE3_MP_C_TXP<14>")
	)
	(segment
		(start 2.42062 -94.88932)
		(end 2.42062 -95.33382)
		(width 0.1143)
		(layer "B.Cu")
		(net "P3E_CPU1_PE3_MP_C_TXP<14>")
	)
	(segment
		(start 8.938514 -96.912684)
		(end 9.18083 -97.155)
		(width 0.1143)
		(layer "B.Cu")
		(net "P3E_CPU1_PE3_MP_C_TXP<14>")
	)
	(segment
		(start 10.584688 -99.612196)
		(end 10.73404 -99.674172)
		(width 0.1143)
		(layer "B.Cu")
		(net "P3E_CPU1_PE3_MP_C_TXP<14>")
	)
	(segment
		(start 2.54 -94.76994)
		(end 2.42062 -94.88932)
		(width 0.1143)
		(layer "B.Cu")
		(net "P3E_CPU1_PE3_MP_C_TXP<14>")
	)
	(segment
		(start 8.93826 -96.750886)
		(end 8.938514 -96.912684)
		(width 0.1143)
		(layer "B.Cu")
		(net "P3E_CPU1_PE3_MP_C_TXP<14>")
	)
	(segment
		(start 11.88593 -101.90353)
		(end 12.07897 -101.90353)
		(width 0.1143)
		(layer "B.Cu")
		(net "P3E_CPU1_PE3_MP_C_TXP<14>")
	)
	(segment
		(start 10.865358 -99.99091)
		(end 10.803636 -100.140262)
		(width 0.1143)
		(layer "B.Cu")
		(net "P3E_CPU1_PE3_MP_C_TXP<14>")
	)
	(segment
		(start 9.83996 -97.81413)
		(end 10.23493 -98.767392)
		(width 0.1143)
		(layer "B.Cu")
		(net "P3E_CPU1_PE3_MP_C_TXP<14>")
	)
	(segment
		(start 10.73404 -99.674172)
		(end 10.865358 -99.99091)
		(width 0.1143)
		(layer "B.Cu")
		(net "P3E_CPU1_PE3_MP_C_TXP<14>")
	)
	(segment
		(start 12.07897 -101.90353)
		(end 12.40282 -101.57968)
		(width 0.1143)
		(layer "B.Cu")
		(net "P3E_CPU1_PE3_MP_C_TXP<14>")
	)
	(segment
		(start 10.515346 -99.146106)
		(end 10.453624 -99.295458)
		(width 0.1143)
		(layer "B.Cu")
		(net "P3E_CPU1_PE3_MP_C_TXP<14>")
	)
	(segment
		(start 9.18083 -97.155)
		(end 9.342628 -97.155)
		(width 0.1143)
		(layer "B.Cu")
		(net "P3E_CPU1_PE3_MP_C_TXP<14>")
	)
	(segment
		(start 11.284712 -101.301804)
		(end 11.88593 -101.90353)
		(width 0.1143)
		(layer "B.Cu")
		(net "P3E_CPU1_PE3_MP_C_TXP<14>")
	)
	(segment
		(start 11.21537 -100.835714)
		(end 11.153394 -100.985066)
		(width 0.1143)
		(layer "B.Cu")
		(net "P3E_CPU1_PE3_MP_C_TXP<14>")
	)
	(segment
		(start 9.584944 -97.39757)
		(end 9.584944 -97.559114)
		(width 0.1143)
		(layer "B.Cu")
		(net "P3E_CPU1_PE3_MP_C_TXP<14>")
	)
	(segment
		(start 10.9347 -100.457)
		(end 11.084052 -100.518976)
		(width 0.1143)
		(layer "B.Cu")
		(net "P3E_CPU1_PE3_MP_C_TXP<14>")
	)
	(segment
		(start 9.584944 -97.559114)
		(end 9.83996 -97.81413)
		(width 0.1143)
		(layer "B.Cu")
		(net "P3E_CPU1_PE3_MP_C_TXP<14>")
	)
	(segment
		(start 8.695944 -96.50857)
		(end 8.93826 -96.750886)
		(width 0.1143)
		(layer "B.Cu")
		(net "P3E_CPU1_PE3_MP_C_TXP<14>")
	)
	(segment
		(start 10.803636 -100.140262)
		(end 10.9347 -100.457)
		(width 0.1143)
		(layer "B.Cu")
		(net "P3E_CPU1_PE3_MP_C_TXP<14>")
	)
	(via
		(at 15.310866 -105.52557)
		(size 0.508)
		(drill 0.254)
		(layers "F.Cu" "B.Cu")
		(net "P3E_CPU1_PE3_MP_C_TXN<13>")
	)
	(via
		(at 14.321282 -103.673402)
		(size 0.508)
		(drill 0.254)
		(layers "F.Cu" "B.Cu")
		(net "P3E_CPU1_PE3_MP_C_TXN<13>")
	)
	(segment
		(start 14.235176 -104.81056)
		(end 14.235176 -104.634538)
		(width 0.1143)
		(layer "B.Cu")
		(net "P3E_CPU1_PE3_MP_C_TXN<13>")
	)
	(segment
		(start 14.950186 -105.52557)
		(end 14.770608 -105.345992)
		(width 0.1143)
		(layer "B.Cu")
		(net "P3E_CPU1_PE3_MP_C_TXN<13>")
	)
	(segment
		(start 13.950696 -103.54056)
		(end 14.18844 -103.54056)
		(width 0.1143)
		(layer "B.Cu")
		(net "P3E_CPU1_PE3_MP_C_TXN<13>")
	)
	(segment
		(start 17.83842 -105.20172)
		(end 17.83842 -105.40746)
		(width 0.1143)
		(layer "B.Cu")
		(net "P3E_CPU1_PE3_MP_C_TXN<13>")
	)
	(segment
		(start 14.770608 -105.345992)
		(end 14.770608 -105.16997)
		(width 0.1143)
		(layer "B.Cu")
		(net "P3E_CPU1_PE3_MP_C_TXN<13>")
	)
	(segment
		(start 14.770608 -105.16997)
		(end 14.590776 -104.990138)
		(width 0.1143)
		(layer "B.Cu")
		(net "P3E_CPU1_PE3_MP_C_TXN<13>")
	)
	(segment
		(start 16.86814 -105.40111)
		(end 16.61414 -105.40111)
		(width 0.1143)
		(layer "B.Cu")
		(net "P3E_CPU1_PE3_MP_C_TXN<13>")
	)
	(segment
		(start 16.61414 -105.40111)
		(end 16.48968 -105.52557)
		(width 0.1143)
		(layer "B.Cu")
		(net "P3E_CPU1_PE3_MP_C_TXN<13>")
	)
	(segment
		(start 15.310866 -105.52557)
		(end 14.950186 -105.52557)
		(width 0.1143)
		(layer "B.Cu")
		(net "P3E_CPU1_PE3_MP_C_TXN<13>")
	)
	(segment
		(start 13.65504 -103.836216)
		(end 13.950696 -103.54056)
		(width 0.1143)
		(layer "B.Cu")
		(net "P3E_CPU1_PE3_MP_C_TXN<13>")
	)
	(segment
		(start 14.414754 -104.990138)
		(end 14.235176 -104.81056)
		(width 0.1143)
		(layer "B.Cu")
		(net "P3E_CPU1_PE3_MP_C_TXN<13>")
	)
	(segment
		(start 14.055344 -104.454706)
		(end 13.879322 -104.454706)
		(width 0.1143)
		(layer "B.Cu")
		(net "P3E_CPU1_PE3_MP_C_TXN<13>")
	)
	(segment
		(start 16.48968 -105.52557)
		(end 16.23568 -105.52557)
		(width 0.1143)
		(layer "B.Cu")
		(net "P3E_CPU1_PE3_MP_C_TXN<13>")
	)
	(segment
		(start 16.23568 -105.52557)
		(end 16.11122 -105.40111)
		(width 0.1143)
		(layer "B.Cu")
		(net "P3E_CPU1_PE3_MP_C_TXN<13>")
	)
	(segment
		(start 17.83842 -105.40746)
		(end 17.72031 -105.52557)
		(width 0.1143)
		(layer "B.Cu")
		(net "P3E_CPU1_PE3_MP_C_TXN<13>")
	)
	(segment
		(start 13.879322 -104.454706)
		(end 13.65504 -104.230424)
		(width 0.1143)
		(layer "B.Cu")
		(net "P3E_CPU1_PE3_MP_C_TXN<13>")
	)
	(segment
		(start 15.73276 -105.52557)
		(end 15.310866 -105.52557)
		(width 0.1143)
		(layer "B.Cu")
		(net "P3E_CPU1_PE3_MP_C_TXN<13>")
	)
	(segment
		(start 14.590776 -104.990138)
		(end 14.414754 -104.990138)
		(width 0.1143)
		(layer "B.Cu")
		(net "P3E_CPU1_PE3_MP_C_TXN<13>")
	)
	(segment
		(start 17.72031 -105.52557)
		(end 16.9926 -105.52557)
		(width 0.1143)
		(layer "B.Cu")
		(net "P3E_CPU1_PE3_MP_C_TXN<13>")
	)
	(segment
		(start 15.85722 -105.40111)
		(end 15.73276 -105.52557)
		(width 0.1143)
		(layer "B.Cu")
		(net "P3E_CPU1_PE3_MP_C_TXN<13>")
	)
	(segment
		(start 13.65504 -104.230424)
		(end 13.65504 -103.836216)
		(width 0.1143)
		(layer "B.Cu")
		(net "P3E_CPU1_PE3_MP_C_TXN<13>")
	)
	(segment
		(start 16.11122 -105.40111)
		(end 15.85722 -105.40111)
		(width 0.1143)
		(layer "B.Cu")
		(net "P3E_CPU1_PE3_MP_C_TXN<13>")
	)
	(segment
		(start 16.9926 -105.52557)
		(end 16.86814 -105.40111)
		(width 0.1143)
		(layer "B.Cu")
		(net "P3E_CPU1_PE3_MP_C_TXN<13>")
	)
	(segment
		(start 14.235176 -104.634538)
		(end 14.055344 -104.454706)
		(width 0.1143)
		(layer "B.Cu")
		(net "P3E_CPU1_PE3_MP_C_TXN<13>")
	)
	(segment
		(start 14.18844 -103.54056)
		(end 14.321282 -103.673402)
		(width 0.1143)
		(layer "B.Cu")
		(net "P3E_CPU1_PE3_MP_C_TXN<13>")
	)
	(segment
		(start 13.631926 -103.8733)
		(end 13.831824 -103.673402)
		(width 0.1143)
		(layer "In4.Cu")
		(net "P3E_CPU1_PE3_MP_C_TXN<13>")
	)
	(segment
		(start 12.2174 -100.888292)
		(end 12.2174 -103.340154)
		(width 0.1143)
		(layer "In4.Cu")
		(net "P3E_CPU1_PE3_MP_C_TXN<13>")
	)
	(segment
		(start 5.054092 -93.564456)
		(end 5.484876 -93.99524)
		(width 0.1143)
		(layer "In4.Cu")
		(net "P3E_CPU1_PE3_MP_C_TXN<13>")
	)
	(segment
		(start 13.831824 -103.673402)
		(end 14.321282 -103.673402)
		(width 0.1143)
		(layer "In4.Cu")
		(net "P3E_CPU1_PE3_MP_C_TXN<13>")
	)
	(segment
		(start 12.750546 -103.8733)
		(end 13.631926 -103.8733)
		(width 0.1143)
		(layer "In4.Cu")
		(net "P3E_CPU1_PE3_MP_C_TXN<13>")
	)
	(segment
		(start 4.499864 -92.769944)
		(end 5.054092 -93.324172)
		(width 0.1143)
		(layer "In4.Cu")
		(net "P3E_CPU1_PE3_MP_C_TXN<13>")
	)
	(segment
		(start 8.746236 -93.99524)
		(end 9.798558 -95.047816)
		(width 0.1143)
		(layer "In4.Cu")
		(net "P3E_CPU1_PE3_MP_C_TXN<13>")
	)
	(segment
		(start 5.054092 -93.324172)
		(end 5.054092 -93.564456)
		(width 0.1143)
		(layer "In4.Cu")
		(net "P3E_CPU1_PE3_MP_C_TXN<13>")
	)
	(segment
		(start 9.798558 -95.047816)
		(end 12.2174 -100.888292)
		(width 0.1143)
		(layer "In4.Cu")
		(net "P3E_CPU1_PE3_MP_C_TXN<13>")
	)
	(segment
		(start 5.484876 -93.99524)
		(end 8.746236 -93.99524)
		(width 0.1143)
		(layer "In4.Cu")
		(net "P3E_CPU1_PE3_MP_C_TXN<13>")
	)
	(segment
		(start 12.2174 -103.340154)
		(end 12.750546 -103.8733)
		(width 0.1143)
		(layer "In4.Cu")
		(net "P3E_CPU1_PE3_MP_C_TXN<13>")
	)
	(segment
		(start 11.246866 -98.54565)
		(end 11.185144 -98.695002)
		(width 0.1143)
		(layer "B.Cu")
		(net "P3E_CPU1_PE3_MP_C_TXP<12>")
	)
	(segment
		(start 10.96645 -98.166936)
		(end 11.115802 -98.228912)
		(width 0.1143)
		(layer "B.Cu")
		(net "P3E_CPU1_PE3_MP_C_TXP<12>")
	)
	(segment
		(start 10.76579 -97.384108)
		(end 10.896854 -97.700846)
		(width 0.1143)
		(layer "B.Cu")
		(net "P3E_CPU1_PE3_MP_C_TXP<12>")
	)
	(segment
		(start 1.380998 -92.769944)
		(end 1.078738 -92.467684)
		(width 0.1143)
		(layer "B.Cu")
		(net "P3E_CPU1_PE3_MP_C_TXP<12>")
	)
	(segment
		(start 12.344908 -100.13823)
		(end 12.79017 -100.13823)
		(width 0.1143)
		(layer "B.Cu")
		(net "P3E_CPU1_PE3_MP_C_TXP<12>")
	)
	(segment
		(start 11.596878 -99.390454)
		(end 12.344908 -100.13823)
		(width 0.1143)
		(layer "B.Cu")
		(net "P3E_CPU1_PE3_MP_C_TXP<12>")
	)
	(segment
		(start 1.277112 -91.895676)
		(end 7.4549 -91.895676)
		(width 0.1143)
		(layer "B.Cu")
		(net "P3E_CPU1_PE3_MP_C_TXP<12>")
	)
	(segment
		(start 10.547096 -96.856042)
		(end 10.48512 -97.005394)
		(width 0.1143)
		(layer "B.Cu")
		(net "P3E_CPU1_PE3_MP_C_TXP<12>")
	)
	(segment
		(start 1.078738 -92.09405)
		(end 1.277112 -91.895676)
		(width 0.1143)
		(layer "B.Cu")
		(net "P3E_CPU1_PE3_MP_C_TXP<12>")
	)
	(segment
		(start 10.135108 -96.16059)
		(end 10.266426 -96.477582)
		(width 0.1143)
		(layer "B.Cu")
		(net "P3E_CPU1_PE3_MP_C_TXP<12>")
	)
	(segment
		(start 11.115802 -98.228912)
		(end 11.246866 -98.54565)
		(width 0.1143)
		(layer "B.Cu")
		(net "P3E_CPU1_PE3_MP_C_TXP<12>")
	)
	(segment
		(start 11.185144 -98.695002)
		(end 11.316208 -99.01174)
		(width 0.1143)
		(layer "B.Cu")
		(net "P3E_CPU1_PE3_MP_C_TXP<12>")
	)
	(segment
		(start 10.616438 -97.322132)
		(end 10.76579 -97.384108)
		(width 0.1143)
		(layer "B.Cu")
		(net "P3E_CPU1_PE3_MP_C_TXP<12>")
	)
	(segment
		(start 10.48512 -97.005394)
		(end 10.616438 -97.322132)
		(width 0.1143)
		(layer "B.Cu")
		(net "P3E_CPU1_PE3_MP_C_TXP<12>")
	)
	(segment
		(start 10.835132 -97.850198)
		(end 10.96645 -98.166936)
		(width 0.1143)
		(layer "B.Cu")
		(net "P3E_CPU1_PE3_MP_C_TXP<12>")
	)
	(segment
		(start 10.266426 -96.477582)
		(end 10.415778 -96.539304)
		(width 0.1143)
		(layer "B.Cu")
		(net "P3E_CPU1_PE3_MP_C_TXP<12>")
	)
	(segment
		(start 10.896854 -97.700846)
		(end 10.835132 -97.850198)
		(width 0.1143)
		(layer "B.Cu")
		(net "P3E_CPU1_PE3_MP_C_TXP<12>")
	)
	(segment
		(start 10.197084 -96.011238)
		(end 10.135108 -96.16059)
		(width 0.1143)
		(layer "B.Cu")
		(net "P3E_CPU1_PE3_MP_C_TXP<12>")
	)
	(segment
		(start 9.225788 -93.666818)
		(end 10.197084 -96.011238)
		(width 0.1143)
		(layer "B.Cu")
		(net "P3E_CPU1_PE3_MP_C_TXP<12>")
	)
	(segment
		(start 7.4549 -91.895676)
		(end 9.225788 -93.666818)
		(width 0.1143)
		(layer "B.Cu")
		(net "P3E_CPU1_PE3_MP_C_TXP<12>")
	)
	(segment
		(start 1.700022 -92.769944)
		(end 1.380998 -92.769944)
		(width 0.1143)
		(layer "B.Cu")
		(net "P3E_CPU1_PE3_MP_C_TXP<12>")
	)
	(segment
		(start 11.316208 -99.01174)
		(end 11.46556 -99.073716)
		(width 0.1143)
		(layer "B.Cu")
		(net "P3E_CPU1_PE3_MP_C_TXP<12>")
	)
	(segment
		(start 12.79017 -100.13823)
		(end 13.11402 -100.46208)
		(width 0.1143)
		(layer "B.Cu")
		(net "P3E_CPU1_PE3_MP_C_TXP<12>")
	)
	(segment
		(start 1.078738 -92.467684)
		(end 1.078738 -92.09405)
		(width 0.1143)
		(layer "B.Cu")
		(net "P3E_CPU1_PE3_MP_C_TXP<12>")
	)
	(segment
		(start 10.415778 -96.539304)
		(end 10.547096 -96.856042)
		(width 0.1143)
		(layer "B.Cu")
		(net "P3E_CPU1_PE3_MP_C_TXP<12>")
	)
	(segment
		(start 11.46556 -99.073716)
		(end 11.596878 -99.390454)
		(width 0.1143)
		(layer "B.Cu")
		(net "P3E_CPU1_PE3_MP_C_TXP<12>")
	)
	(via
		(at 12.51331 -106.42473)
		(size 0.508)
		(drill 0.254)
		(layers "F.Cu" "B.Cu")
		(net "P3E_CPU1_PE3_MP_C_TXP<11>")
	)
	(segment
		(start 13.49756 -106.93908)
		(end 13.84046 -106.59618)
		(width 0.1143)
		(layer "B.Cu")
		(net "P3E_CPU1_PE3_MP_C_TXP<11>")
	)
	(segment
		(start 12.73048 -106.93908)
		(end 13.49756 -106.93908)
		(width 0.1143)
		(layer "B.Cu")
		(net "P3E_CPU1_PE3_MP_C_TXP<11>")
	)
	(segment
		(start 12.51331 -106.42473)
		(end 12.51331 -106.72191)
		(width 0.1143)
		(layer "B.Cu")
		(net "P3E_CPU1_PE3_MP_C_TXP<11>")
	)
	(segment
		(start 12.51331 -106.72191)
		(end 12.73048 -106.93908)
		(width 0.1143)
		(layer "B.Cu")
		(net "P3E_CPU1_PE3_MP_C_TXP<11>")
	)
	(segment
		(start -4.8895 -94.767654)
		(end -4.7244 -94.932754)
		(width 0.1143)
		(layer "In4.Cu")
		(net "P3E_CPU1_PE3_MP_C_TXP<11>")
	)
	(segment
		(start 9.774174 -98.61042)
		(end 10.986008 -101.5365)
		(width 0.1143)
		(layer "In4.Cu")
		(net "P3E_CPU1_PE3_MP_C_TXP<11>")
	)
	(segment
		(start -2.500122 -92.769944)
		(end -2.849372 -92.769944)
		(width 0.1143)
		(layer "In4.Cu")
		(net "P3E_CPU1_PE3_MP_C_TXP<11>")
	)
	(segment
		(start -4.8895 -94.201234)
		(end -4.8895 -94.767654)
		(width 0.1143)
		(layer "In4.Cu")
		(net "P3E_CPU1_PE3_MP_C_TXP<11>")
	)
	(segment
		(start -3.60299 -97.59188)
		(end -3.26009 -97.59188)
		(width 0.1143)
		(layer "In4.Cu")
		(net "P3E_CPU1_PE3_MP_C_TXP<11>")
	)
	(segment
		(start -3.07848 -93.334586)
		(end -3.487674 -93.74378)
		(width 0.1143)
		(layer "In4.Cu")
		(net "P3E_CPU1_PE3_MP_C_TXP<11>")
	)
	(segment
		(start -4.7244 -95.948754)
		(end -4.7244 -96.291654)
		(width 0.1143)
		(layer "In4.Cu")
		(net "P3E_CPU1_PE3_MP_C_TXP<11>")
	)
	(segment
		(start 8.92048 -97.75698)
		(end 9.774174 -98.61042)
		(width 0.1143)
		(layer "In4.Cu")
		(net "P3E_CPU1_PE3_MP_C_TXP<11>")
	)
	(segment
		(start -3.26009 -97.59188)
		(end -3.09499 -97.75698)
		(width 0.1143)
		(layer "In4.Cu")
		(net "P3E_CPU1_PE3_MP_C_TXP<11>")
	)
	(segment
		(start 11.51128 -106.91368)
		(end 12.39901 -106.91368)
		(width 0.1143)
		(layer "In4.Cu")
		(net "P3E_CPU1_PE3_MP_C_TXP<11>")
	)
	(segment
		(start -4.8895 -95.440754)
		(end -4.8895 -95.783654)
		(width 0.1143)
		(layer "In4.Cu")
		(net "P3E_CPU1_PE3_MP_C_TXP<11>")
	)
	(segment
		(start -4.432046 -93.74378)
		(end -4.8895 -94.201234)
		(width 0.1143)
		(layer "In4.Cu")
		(net "P3E_CPU1_PE3_MP_C_TXP<11>")
	)
	(segment
		(start -3.09499 -97.75698)
		(end 8.92048 -97.75698)
		(width 0.1143)
		(layer "In4.Cu")
		(net "P3E_CPU1_PE3_MP_C_TXP<11>")
	)
	(segment
		(start 12.39901 -106.91368)
		(end 12.51331 -106.79938)
		(width 0.1143)
		(layer "In4.Cu")
		(net "P3E_CPU1_PE3_MP_C_TXP<11>")
	)
	(segment
		(start -4.8895 -95.783654)
		(end -4.7244 -95.948754)
		(width 0.1143)
		(layer "In4.Cu")
		(net "P3E_CPU1_PE3_MP_C_TXP<11>")
	)
	(segment
		(start -4.8895 -96.456754)
		(end -4.8895 -97.360486)
		(width 0.1143)
		(layer "In4.Cu")
		(net "P3E_CPU1_PE3_MP_C_TXP<11>")
	)
	(segment
		(start 10.986008 -106.388408)
		(end 11.51128 -106.91368)
		(width 0.1143)
		(layer "In4.Cu")
		(net "P3E_CPU1_PE3_MP_C_TXP<11>")
	)
	(segment
		(start -4.7244 -95.275654)
		(end -4.8895 -95.440754)
		(width 0.1143)
		(layer "In4.Cu")
		(net "P3E_CPU1_PE3_MP_C_TXP<11>")
	)
	(segment
		(start -3.487674 -93.74378)
		(end -4.432046 -93.74378)
		(width 0.1143)
		(layer "In4.Cu")
		(net "P3E_CPU1_PE3_MP_C_TXP<11>")
	)
	(segment
		(start -4.493006 -97.75698)
		(end -3.76809 -97.75698)
		(width 0.1143)
		(layer "In4.Cu")
		(net "P3E_CPU1_PE3_MP_C_TXP<11>")
	)
	(segment
		(start -4.7244 -94.932754)
		(end -4.7244 -95.275654)
		(width 0.1143)
		(layer "In4.Cu")
		(net "P3E_CPU1_PE3_MP_C_TXP<11>")
	)
	(segment
		(start -3.76809 -97.75698)
		(end -3.60299 -97.59188)
		(width 0.1143)
		(layer "In4.Cu")
		(net "P3E_CPU1_PE3_MP_C_TXP<11>")
	)
	(segment
		(start -3.07848 -92.999052)
		(end -3.07848 -93.334586)
		(width 0.1143)
		(layer "In4.Cu")
		(net "P3E_CPU1_PE3_MP_C_TXP<11>")
	)
	(segment
		(start -4.7244 -96.291654)
		(end -4.8895 -96.456754)
		(width 0.1143)
		(layer "In4.Cu")
		(net "P3E_CPU1_PE3_MP_C_TXP<11>")
	)
	(segment
		(start -4.8895 -97.360486)
		(end -4.493006 -97.75698)
		(width 0.1143)
		(layer "In4.Cu")
		(net "P3E_CPU1_PE3_MP_C_TXP<11>")
	)
	(segment
		(start 10.986008 -101.5365)
		(end 10.986008 -106.388408)
		(width 0.1143)
		(layer "In4.Cu")
		(net "P3E_CPU1_PE3_MP_C_TXP<11>")
	)
	(segment
		(start -2.849372 -92.769944)
		(end -3.07848 -92.999052)
		(width 0.1143)
		(layer "In4.Cu")
		(net "P3E_CPU1_PE3_MP_C_TXP<11>")
	)
	(segment
		(start 12.51331 -106.79938)
		(end 12.51331 -106.42473)
		(width 0.1143)
		(layer "In4.Cu")
		(net "P3E_CPU1_PE3_MP_C_TXP<11>")
	)
	(via
		(at 15.49527 -107.77347)
		(size 0.508)
		(drill 0.254)
		(layers "F.Cu" "B.Cu")
		(net "P3E_CPU1_PE3_MP_C_TXN<10>")
	)
	(segment
		(start 16.82242 -107.94492)
		(end 16.47952 -108.28782)
		(width 0.1143)
		(layer "B.Cu")
		(net "P3E_CPU1_PE3_MP_C_TXN<10>")
	)
	(segment
		(start 15.73022 -108.28782)
		(end 15.49527 -108.05287)
		(width 0.1143)
		(layer "B.Cu")
		(net "P3E_CPU1_PE3_MP_C_TXN<10>")
	)
	(segment
		(start 16.47952 -108.28782)
		(end 15.73022 -108.28782)
		(width 0.1143)
		(layer "B.Cu")
		(net "P3E_CPU1_PE3_MP_C_TXN<10>")
	)
	(segment
		(start 15.49527 -108.05287)
		(end 15.49527 -107.77347)
		(width 0.1143)
		(layer "B.Cu")
		(net "P3E_CPU1_PE3_MP_C_TXN<10>")
	)
	(segment
		(start 16.60398 -105.91165)
		(end 16.36141 -106.15422)
		(width 0.1143)
		(layer "In4.Cu")
		(net "P3E_CPU1_PE3_MP_C_TXN<10>")
	)
	(segment
		(start 14.9352 -107.93095)
		(end 15.26667 -108.26242)
		(width 0.1143)
		(layer "In4.Cu")
		(net "P3E_CPU1_PE3_MP_C_TXN<10>")
	)
	(segment
		(start 13.777722 -100.637848)
		(end 15.639542 -101.4095)
		(width 0.1143)
		(layer "In4.Cu")
		(net "P3E_CPU1_PE3_MP_C_TXN<10>")
	)
	(segment
		(start 16.127984 -106.15422)
		(end 15.885414 -106.39679)
		(width 0.1143)
		(layer "In4.Cu")
		(net "P3E_CPU1_PE3_MP_C_TXN<10>")
	)
	(segment
		(start 15.885414 -106.39679)
		(end 15.885414 -106.630216)
		(width 0.1143)
		(layer "In4.Cu")
		(net "P3E_CPU1_PE3_MP_C_TXN<10>")
	)
	(segment
		(start 18.034 -104.248204)
		(end 17.322546 -104.959658)
		(width 0.1143)
		(layer "In4.Cu")
		(net "P3E_CPU1_PE3_MP_C_TXN<10>")
	)
	(segment
		(start 15.409672 -106.872532)
		(end 14.9352 -107.347004)
		(width 0.1143)
		(layer "In4.Cu")
		(net "P3E_CPU1_PE3_MP_C_TXN<10>")
	)
	(segment
		(start 6.646164 -91.443302)
		(end 6.831838 -91.628976)
		(width 0.1143)
		(layer "In4.Cu")
		(net "P3E_CPU1_PE3_MP_C_TXN<10>")
	)
	(segment
		(start 6.760464 -90.769948)
		(end 6.646164 -90.884248)
		(width 0.1143)
		(layer "In4.Cu")
		(net "P3E_CPU1_PE3_MP_C_TXN<10>")
	)
	(segment
		(start 15.26667 -108.26242)
		(end 15.38097 -108.26242)
		(width 0.1143)
		(layer "In4.Cu")
		(net "P3E_CPU1_PE3_MP_C_TXN<10>")
	)
	(segment
		(start 6.831838 -91.628976)
		(end 8.011922 -91.628976)
		(width 0.1143)
		(layer "In4.Cu")
		(net "P3E_CPU1_PE3_MP_C_TXN<10>")
	)
	(segment
		(start 15.49527 -108.14812)
		(end 15.49527 -107.77347)
		(width 0.1143)
		(layer "In4.Cu")
		(net "P3E_CPU1_PE3_MP_C_TXN<10>")
	)
	(segment
		(start 16.84655 -105.435654)
		(end 16.60398 -105.678224)
		(width 0.1143)
		(layer "In4.Cu")
		(net "P3E_CPU1_PE3_MP_C_TXN<10>")
	)
	(segment
		(start 15.885414 -106.630216)
		(end 15.643098 -106.872532)
		(width 0.1143)
		(layer "In4.Cu")
		(net "P3E_CPU1_PE3_MP_C_TXN<10>")
	)
	(segment
		(start 10.425684 -94.042484)
		(end 12.72032 -99.580446)
		(width 0.1143)
		(layer "In4.Cu")
		(net "P3E_CPU1_PE3_MP_C_TXN<10>")
	)
	(segment
		(start 16.60398 -105.678224)
		(end 16.60398 -105.91165)
		(width 0.1143)
		(layer "In4.Cu")
		(net "P3E_CPU1_PE3_MP_C_TXN<10>")
	)
	(segment
		(start 16.36141 -106.15422)
		(end 16.127984 -106.15422)
		(width 0.1143)
		(layer "In4.Cu")
		(net "P3E_CPU1_PE3_MP_C_TXN<10>")
	)
	(segment
		(start 6.646164 -90.884248)
		(end 6.646164 -91.443302)
		(width 0.1143)
		(layer "In4.Cu")
		(net "P3E_CPU1_PE3_MP_C_TXN<10>")
	)
	(segment
		(start 17.079976 -105.435654)
		(end 16.84655 -105.435654)
		(width 0.1143)
		(layer "In4.Cu")
		(net "P3E_CPU1_PE3_MP_C_TXN<10>")
	)
	(segment
		(start 17.322546 -105.193084)
		(end 17.079976 -105.435654)
		(width 0.1143)
		(layer "In4.Cu")
		(net "P3E_CPU1_PE3_MP_C_TXN<10>")
	)
	(segment
		(start 7.199884 -90.769948)
		(end 6.760464 -90.769948)
		(width 0.1143)
		(layer "In4.Cu")
		(net "P3E_CPU1_PE3_MP_C_TXN<10>")
	)
	(segment
		(start 14.9352 -107.347004)
		(end 14.9352 -107.93095)
		(width 0.1143)
		(layer "In4.Cu")
		(net "P3E_CPU1_PE3_MP_C_TXN<10>")
	)
	(segment
		(start 15.643098 -106.872532)
		(end 15.409672 -106.872532)
		(width 0.1143)
		(layer "In4.Cu")
		(net "P3E_CPU1_PE3_MP_C_TXN<10>")
	)
	(segment
		(start 8.011922 -91.628976)
		(end 10.425684 -94.042484)
		(width 0.1143)
		(layer "In4.Cu")
		(net "P3E_CPU1_PE3_MP_C_TXN<10>")
	)
	(segment
		(start 12.72032 -99.580446)
		(end 13.777722 -100.637848)
		(width 0.1143)
		(layer "In4.Cu")
		(net "P3E_CPU1_PE3_MP_C_TXN<10>")
	)
	(segment
		(start 17.322546 -104.959658)
		(end 17.322546 -105.193084)
		(width 0.1143)
		(layer "In4.Cu")
		(net "P3E_CPU1_PE3_MP_C_TXN<10>")
	)
	(segment
		(start 18.034 -101.933248)
		(end 18.034 -104.248204)
		(width 0.1143)
		(layer "In4.Cu")
		(net "P3E_CPU1_PE3_MP_C_TXN<10>")
	)
	(segment
		(start 15.38097 -108.26242)
		(end 15.49527 -108.14812)
		(width 0.1143)
		(layer "In4.Cu")
		(net "P3E_CPU1_PE3_MP_C_TXN<10>")
	)
	(segment
		(start 17.510252 -101.4095)
		(end 18.034 -101.933248)
		(width 0.1143)
		(layer "In4.Cu")
		(net "P3E_CPU1_PE3_MP_C_TXN<10>")
	)
	(segment
		(start 15.639542 -101.4095)
		(end 17.510252 -101.4095)
		(width 0.1143)
		(layer "In4.Cu")
		(net "P3E_CPU1_PE3_MP_C_TXN<10>")
	)
	(via
		(at 16.44015 -99.47783)
		(size 0.508)
		(drill 0.254)
		(layers "F.Cu" "B.Cu")
		(net "P3E_CPU1_PE3_MP_C_TXN<9>")
	)
	(segment
		(start 16.44015 -99.54895)
		(end 16.44015 -99.47783)
		(width 0.1143)
		(layer "B.Cu")
		(net "P3E_CPU1_PE3_MP_C_TXN<9>")
	)
	(segment
		(start 17.548352 -100.005388)
		(end 16.896588 -100.005388)
		(width 0.1143)
		(layer "B.Cu")
		(net "P3E_CPU1_PE3_MP_C_TXN<9>")
	)
	(segment
		(start 16.896588 -100.005388)
		(end 16.44015 -99.54895)
		(width 0.1143)
		(layer "B.Cu")
		(net "P3E_CPU1_PE3_MP_C_TXN<9>")
	)
	(segment
		(start 17.83842 -99.71532)
		(end 17.548352 -100.005388)
		(width 0.1143)
		(layer "B.Cu")
		(net "P3E_CPU1_PE3_MP_C_TXN<9>")
	)
	(segment
		(start 2.044954 -90.769948)
		(end 2.154174 -90.660728)
		(width 0.1143)
		(layer "In4.Cu")
		(net "P3E_CPU1_PE3_MP_C_TXN<9>")
	)
	(segment
		(start 1.599946 -90.769948)
		(end 2.044954 -90.769948)
		(width 0.1143)
		(layer "In4.Cu")
		(net "P3E_CPU1_PE3_MP_C_TXN<9>")
	)
	(segment
		(start 2.154174 -89.796874)
		(end 2.822702 -89.128346)
		(width 0.1143)
		(layer "In4.Cu")
		(net "P3E_CPU1_PE3_MP_C_TXN<9>")
	)
	(segment
		(start 11.346434 -93.84792)
		(end 13.364972 -99.23526)
		(width 0.1143)
		(layer "In4.Cu")
		(net "P3E_CPU1_PE3_MP_C_TXN<9>")
	)
	(segment
		(start 16.22044 -100.0252)
		(end 16.44015 -99.80549)
		(width 0.1143)
		(layer "In4.Cu")
		(net "P3E_CPU1_PE3_MP_C_TXN<9>")
	)
	(segment
		(start 2.154174 -90.660728)
		(end 2.154174 -89.796874)
		(width 0.1143)
		(layer "In4.Cu")
		(net "P3E_CPU1_PE3_MP_C_TXN<9>")
	)
	(segment
		(start 13.364972 -99.23526)
		(end 14.154912 -100.0252)
		(width 0.1143)
		(layer "In4.Cu")
		(net "P3E_CPU1_PE3_MP_C_TXN<9>")
	)
	(segment
		(start 14.154912 -100.0252)
		(end 16.22044 -100.0252)
		(width 0.1143)
		(layer "In4.Cu")
		(net "P3E_CPU1_PE3_MP_C_TXN<9>")
	)
	(segment
		(start 9.051544 -89.128346)
		(end 11.346434 -91.423236)
		(width 0.1143)
		(layer "In4.Cu")
		(net "P3E_CPU1_PE3_MP_C_TXN<9>")
	)
	(segment
		(start 16.44015 -99.80549)
		(end 16.44015 -99.47783)
		(width 0.1143)
		(layer "In4.Cu")
		(net "P3E_CPU1_PE3_MP_C_TXN<9>")
	)
	(segment
		(start 2.822702 -89.128346)
		(end 9.051544 -89.128346)
		(width 0.1143)
		(layer "In4.Cu")
		(net "P3E_CPU1_PE3_MP_C_TXN<9>")
	)
	(segment
		(start 11.346434 -91.423236)
		(end 11.346434 -93.84792)
		(width 0.1143)
		(layer "In4.Cu")
		(net "P3E_CPU1_PE3_MP_C_TXN<9>")
	)
	(segment
		(start 12.487402 -97.439226)
		(end 12.789154 -97.437448)
		(width 0.1143)
		(layer "B.Cu")
		(net "P3E_CPU1_PE3_MP_C_TXN<8>")
	)
	(segment
		(start 12.789916 -97.437448)
		(end 13.10894 -97.11436)
		(width 0.1143)
		(layer "B.Cu")
		(net "P3E_CPU1_PE3_MP_C_TXN<8>")
	)
	(segment
		(start -1.4224 -89.57818)
		(end 8.664702 -89.57818)
		(width 0.1143)
		(layer "B.Cu")
		(net "P3E_CPU1_PE3_MP_C_TXN<8>")
	)
	(segment
		(start -2.599944 -90.769948)
		(end -2.169414 -90.769948)
		(width 0.1143)
		(layer "B.Cu")
		(net "P3E_CPU1_PE3_MP_C_TXN<8>")
	)
	(segment
		(start 12.085828 -97.037652)
		(end 12.487402 -97.439226)
		(width 0.1143)
		(layer "B.Cu")
		(net "P3E_CPU1_PE3_MP_C_TXN<8>")
	)
	(segment
		(start 12.789154 -97.437448)
		(end 12.789916 -97.437448)
		(width 0.1143)
		(layer "B.Cu")
		(net "P3E_CPU1_PE3_MP_C_TXN<8>")
	)
	(segment
		(start -1.90754 -90.508074)
		(end -1.90754 -90.06332)
		(width 0.1143)
		(layer "B.Cu")
		(net "P3E_CPU1_PE3_MP_C_TXN<8>")
	)
	(segment
		(start -1.90754 -90.06332)
		(end -1.4224 -89.57818)
		(width 0.1143)
		(layer "B.Cu")
		(net "P3E_CPU1_PE3_MP_C_TXN<8>")
	)
	(segment
		(start 9.90219 -90.815414)
		(end 11.721846 -95.20682)
		(width 0.1143)
		(layer "B.Cu")
		(net "P3E_CPU1_PE3_MP_C_TXN<8>")
	)
	(segment
		(start 11.721846 -95.20682)
		(end 12.085828 -97.037652)
		(width 0.1143)
		(layer "B.Cu")
		(net "P3E_CPU1_PE3_MP_C_TXN<8>")
	)
	(segment
		(start 8.664702 -89.57818)
		(end 9.90219 -90.815414)
		(width 0.1143)
		(layer "B.Cu")
		(net "P3E_CPU1_PE3_MP_C_TXN<8>")
	)
	(segment
		(start -2.169414 -90.769948)
		(end -1.90754 -90.508074)
		(width 0.1143)
		(layer "B.Cu")
		(net "P3E_CPU1_PE3_MP_C_TXN<8>")
	)
	(via
		(at 16.008096 -103.031544)
		(size 0.508)
		(drill 0.254)
		(layers "F.Cu" "B.Cu")
		(net "P3E_CPU1_PE3_MP_C_TXP<15>")
	)
	(segment
		(start 16.008096 -103.031544)
		(end 16.432022 -103.031544)
		(width 0.1143)
		(layer "B.Cu")
		(net "P3E_CPU1_PE3_MP_C_TXP<15>")
	)
	(segment
		(start 17.37868 -103.144574)
		(end 17.635474 -103.144574)
		(width 0.1143)
		(layer "B.Cu")
		(net "P3E_CPU1_PE3_MP_C_TXP<15>")
	)
	(segment
		(start 17.308322 -103.214932)
		(end 17.37868 -103.144574)
		(width 0.1143)
		(layer "B.Cu")
		(net "P3E_CPU1_PE3_MP_C_TXP<15>")
	)
	(segment
		(start 16.432022 -103.031544)
		(end 16.61541 -103.214932)
		(width 0.1143)
		(layer "B.Cu")
		(net "P3E_CPU1_PE3_MP_C_TXP<15>")
	)
	(segment
		(start 17.635474 -103.144574)
		(end 17.83842 -103.34752)
		(width 0.1143)
		(layer "B.Cu")
		(net "P3E_CPU1_PE3_MP_C_TXP<15>")
	)
	(segment
		(start 16.61541 -103.214932)
		(end 17.308322 -103.214932)
		(width 0.1143)
		(layer "B.Cu")
		(net "P3E_CPU1_PE3_MP_C_TXP<15>")
	)
	(segment
		(start 12.481814 -104.198928)
		(end 12.248388 -104.198928)
		(width 0.1143)
		(layer "In4.Cu")
		(net "P3E_CPU1_PE3_MP_C_TXP<15>")
	)
	(segment
		(start 6.66496 -95.06966)
		(end 6.96468 -94.76994)
		(width 0.1143)
		(layer "In4.Cu")
		(net "P3E_CPU1_PE3_MP_C_TXP<15>")
	)
	(segment
		(start 14.866874 -104.75214)
		(end 14.701774 -104.91724)
		(width 0.1143)
		(layer "In4.Cu")
		(net "P3E_CPU1_PE3_MP_C_TXP<15>")
	)
	(segment
		(start 9.397746 -97.211896)
		(end 9.156446 -96.96831)
		(width 0.1143)
		(layer "In4.Cu")
		(net "P3E_CPU1_PE3_MP_C_TXP<15>")
	)
	(segment
		(start 8.916162 -96.491298)
		(end 8.682736 -96.490028)
		(width 0.1143)
		(layer "In4.Cu")
		(net "P3E_CPU1_PE3_MP_C_TXP<15>")
	)
	(segment
		(start 13.9827 -104.91724)
		(end 13.8176 -104.75214)
		(width 0.1143)
		(layer "In4.Cu")
		(net "P3E_CPU1_PE3_MP_C_TXP<15>")
	)
	(segment
		(start 12.9667 -104.91724)
		(end 12.72413 -104.67467)
		(width 0.1143)
		(layer "In4.Cu")
		(net "P3E_CPU1_PE3_MP_C_TXP<15>")
	)
	(segment
		(start 6.66496 -95.3643)
		(end 6.66496 -95.06966)
		(width 0.1143)
		(layer "In4.Cu")
		(net "P3E_CPU1_PE3_MP_C_TXP<15>")
	)
	(segment
		(start 9.156446 -96.96831)
		(end 9.157462 -96.734884)
		(width 0.1143)
		(layer "In4.Cu")
		(net "P3E_CPU1_PE3_MP_C_TXP<15>")
	)
	(segment
		(start 16.436086 -104.198928)
		(end 16.20266 -104.198928)
		(width 0.1143)
		(layer "In4.Cu")
		(net "P3E_CPU1_PE3_MP_C_TXP<15>")
	)
	(segment
		(start 16.745712 -103.227632)
		(end 16.745712 -103.889302)
		(width 0.1143)
		(layer "In4.Cu")
		(net "P3E_CPU1_PE3_MP_C_TXP<15>")
	)
	(segment
		(start 12.72413 -104.67467)
		(end 12.72413 -104.441244)
		(width 0.1143)
		(layer "In4.Cu")
		(net "P3E_CPU1_PE3_MP_C_TXP<15>")
	)
	(segment
		(start 8.441436 -96.246442)
		(end 8.442452 -96.013016)
		(width 0.1143)
		(layer "In4.Cu")
		(net "P3E_CPU1_PE3_MP_C_TXP<15>")
	)
	(segment
		(start 12.248388 -104.198928)
		(end 11.74623 -103.69677)
		(width 0.1143)
		(layer "In4.Cu")
		(net "P3E_CPU1_PE3_MP_C_TXP<15>")
	)
	(segment
		(start 11.74623 -103.69677)
		(end 11.74623 -101.342698)
		(width 0.1143)
		(layer "In4.Cu")
		(net "P3E_CPU1_PE3_MP_C_TXP<15>")
	)
	(segment
		(start 11.74623 -101.342698)
		(end 10.882122 -99.256596)
		(width 0.1143)
		(layer "In4.Cu")
		(net "P3E_CPU1_PE3_MP_C_TXP<15>")
	)
	(segment
		(start 10.882122 -99.256596)
		(end 10.97153 -99.04095)
		(width 0.1143)
		(layer "In4.Cu")
		(net "P3E_CPU1_PE3_MP_C_TXP<15>")
	)
	(segment
		(start 13.3096 -104.91724)
		(end 12.9667 -104.91724)
		(width 0.1143)
		(layer "In4.Cu")
		(net "P3E_CPU1_PE3_MP_C_TXP<15>")
	)
	(segment
		(start 14.701774 -104.91724)
		(end 13.9827 -104.91724)
		(width 0.1143)
		(layer "In4.Cu")
		(net "P3E_CPU1_PE3_MP_C_TXP<15>")
	)
	(segment
		(start 12.72413 -104.441244)
		(end 12.481814 -104.198928)
		(width 0.1143)
		(layer "In4.Cu")
		(net "P3E_CPU1_PE3_MP_C_TXP<15>")
	)
	(segment
		(start 13.8176 -104.75214)
		(end 13.4747 -104.75214)
		(width 0.1143)
		(layer "In4.Cu")
		(net "P3E_CPU1_PE3_MP_C_TXP<15>")
	)
	(segment
		(start 8.201152 -95.76943)
		(end 7.967726 -95.76816)
		(width 0.1143)
		(layer "In4.Cu")
		(net "P3E_CPU1_PE3_MP_C_TXP<15>")
	)
	(segment
		(start 15.717774 -104.91724)
		(end 15.374874 -104.91724)
		(width 0.1143)
		(layer "In4.Cu")
		(net "P3E_CPU1_PE3_MP_C_TXP<15>")
	)
	(segment
		(start 10.493248 -98.318066)
		(end 9.871456 -97.690178)
		(width 0.1143)
		(layer "In4.Cu")
		(net "P3E_CPU1_PE3_MP_C_TXP<15>")
	)
	(segment
		(start 6.82498 -95.52432)
		(end 6.66496 -95.3643)
		(width 0.1143)
		(layer "In4.Cu")
		(net "P3E_CPU1_PE3_MP_C_TXP<15>")
	)
	(segment
		(start 15.374874 -104.91724)
		(end 15.209774 -104.75214)
		(width 0.1143)
		(layer "In4.Cu")
		(net "P3E_CPU1_PE3_MP_C_TXP<15>")
	)
	(segment
		(start 15.960344 -104.441244)
		(end 15.960344 -104.67467)
		(width 0.1143)
		(layer "In4.Cu")
		(net "P3E_CPU1_PE3_MP_C_TXP<15>")
	)
	(segment
		(start 7.967726 -95.76816)
		(end 7.726426 -95.524574)
		(width 0.1143)
		(layer "In4.Cu")
		(net "P3E_CPU1_PE3_MP_C_TXP<15>")
	)
	(segment
		(start 10.840212 -98.724212)
		(end 10.624566 -98.634804)
		(width 0.1143)
		(layer "In4.Cu")
		(net "P3E_CPU1_PE3_MP_C_TXP<15>")
	)
	(segment
		(start 16.745712 -103.889302)
		(end 16.436086 -104.198928)
		(width 0.1143)
		(layer "In4.Cu")
		(net "P3E_CPU1_PE3_MP_C_TXP<15>")
	)
	(segment
		(start 7.726426 -95.524574)
		(end 6.82498 -95.52432)
		(width 0.1143)
		(layer "In4.Cu")
		(net "P3E_CPU1_PE3_MP_C_TXP<15>")
	)
	(segment
		(start 6.96468 -94.76994)
		(end 7.199884 -94.76994)
		(width 0.1143)
		(layer "In4.Cu")
		(net "P3E_CPU1_PE3_MP_C_TXP<15>")
	)
	(segment
		(start 9.872472 -97.456752)
		(end 9.631172 -97.213166)
		(width 0.1143)
		(layer "In4.Cu")
		(net "P3E_CPU1_PE3_MP_C_TXP<15>")
	)
	(segment
		(start 8.682736 -96.490028)
		(end 8.441436 -96.246442)
		(width 0.1143)
		(layer "In4.Cu")
		(net "P3E_CPU1_PE3_MP_C_TXP<15>")
	)
	(segment
		(start 16.20266 -104.198928)
		(end 15.960344 -104.441244)
		(width 0.1143)
		(layer "In4.Cu")
		(net "P3E_CPU1_PE3_MP_C_TXP<15>")
	)
	(segment
		(start 16.008096 -103.031544)
		(end 16.549624 -103.031544)
		(width 0.1143)
		(layer "In4.Cu")
		(net "P3E_CPU1_PE3_MP_C_TXP<15>")
	)
	(segment
		(start 9.157462 -96.734884)
		(end 8.916162 -96.491298)
		(width 0.1143)
		(layer "In4.Cu")
		(net "P3E_CPU1_PE3_MP_C_TXP<15>")
	)
	(segment
		(start 9.631172 -97.213166)
		(end 9.397746 -97.211896)
		(width 0.1143)
		(layer "In4.Cu")
		(net "P3E_CPU1_PE3_MP_C_TXP<15>")
	)
	(segment
		(start 15.960344 -104.67467)
		(end 15.717774 -104.91724)
		(width 0.1143)
		(layer "In4.Cu")
		(net "P3E_CPU1_PE3_MP_C_TXP<15>")
	)
	(segment
		(start 8.442452 -96.013016)
		(end 8.201152 -95.76943)
		(width 0.1143)
		(layer "In4.Cu")
		(net "P3E_CPU1_PE3_MP_C_TXP<15>")
	)
	(segment
		(start 16.549624 -103.031544)
		(end 16.745712 -103.227632)
		(width 0.1143)
		(layer "In4.Cu")
		(net "P3E_CPU1_PE3_MP_C_TXP<15>")
	)
	(segment
		(start 10.624566 -98.634804)
		(end 10.493248 -98.318066)
		(width 0.1143)
		(layer "In4.Cu")
		(net "P3E_CPU1_PE3_MP_C_TXP<15>")
	)
	(segment
		(start 9.871456 -97.690178)
		(end 9.872472 -97.456752)
		(width 0.1143)
		(layer "In4.Cu")
		(net "P3E_CPU1_PE3_MP_C_TXP<15>")
	)
	(segment
		(start 15.209774 -104.75214)
		(end 14.866874 -104.75214)
		(width 0.1143)
		(layer "In4.Cu")
		(net "P3E_CPU1_PE3_MP_C_TXP<15>")
	)
	(segment
		(start 10.97153 -99.04095)
		(end 10.840212 -98.724212)
		(width 0.1143)
		(layer "In4.Cu")
		(net "P3E_CPU1_PE3_MP_C_TXP<15>")
	)
	(segment
		(start 13.4747 -104.75214)
		(end 13.3096 -104.91724)
		(width 0.1143)
		(layer "In4.Cu")
		(net "P3E_CPU1_PE3_MP_C_TXP<15>")
	)
	(segment
		(start 2.05994 -94.76994)
		(end 2.17932 -94.88932)
		(width 0.1143)
		(layer "B.Cu")
		(net "P3E_CPU1_PE3_MP_C_TXN<14>")
	)
	(segment
		(start 1.599946 -94.76994)
		(end 2.05994 -94.76994)
		(width 0.1143)
		(layer "B.Cu")
		(net "P3E_CPU1_PE3_MP_C_TXN<14>")
	)
	(segment
		(start 12.07897 -102.14483)
		(end 12.40282 -102.46868)
		(width 0.1143)
		(layer "B.Cu")
		(net "P3E_CPU1_PE3_MP_C_TXN<14>")
	)
	(segment
		(start 9.635236 -97.951036)
		(end 11.079988 -101.43871)
		(width 0.1143)
		(layer "B.Cu")
		(net "P3E_CPU1_PE3_MP_C_TXN<14>")
	)
	(segment
		(start 11.785854 -102.14483)
		(end 12.07897 -102.14483)
		(width 0.1143)
		(layer "B.Cu")
		(net "P3E_CPU1_PE3_MP_C_TXN<14>")
	)
	(segment
		(start 2.641092 -95.895668)
		(end 7.579868 -95.895668)
		(width 0.1143)
		(layer "B.Cu")
		(net "P3E_CPU1_PE3_MP_C_TXN<14>")
	)
	(segment
		(start 2.17932 -95.433896)
		(end 2.641092 -95.895668)
		(width 0.1143)
		(layer "B.Cu")
		(net "P3E_CPU1_PE3_MP_C_TXN<14>")
	)
	(segment
		(start 2.17932 -94.88932)
		(end 2.17932 -95.433896)
		(width 0.1143)
		(layer "B.Cu")
		(net "P3E_CPU1_PE3_MP_C_TXN<14>")
	)
	(segment
		(start 7.579868 -95.895668)
		(end 9.635236 -97.951036)
		(width 0.1143)
		(layer "B.Cu")
		(net "P3E_CPU1_PE3_MP_C_TXN<14>")
	)
	(segment
		(start 11.079988 -101.43871)
		(end 11.785854 -102.14483)
		(width 0.1143)
		(layer "B.Cu")
		(net "P3E_CPU1_PE3_MP_C_TXN<14>")
	)
	(via
		(at 13.777976 -103.028496)
		(size 0.508)
		(drill 0.254)
		(layers "F.Cu" "B.Cu")
		(net "P3E_CPU1_PE3_MP_C_TXP<13>")
	)
	(via
		(at 16.969486 -105.76687)
		(size 0.508)
		(drill 0.254)
		(layers "F.Cu" "B.Cu")
		(net "P3E_CPU1_PE3_MP_C_TXP<13>")
	)
	(segment
		(start 13.777976 -103.371904)
		(end 13.777976 -103.028496)
		(width 0.1143)
		(layer "B.Cu")
		(net "P3E_CPU1_PE3_MP_C_TXP<13>")
	)
	(segment
		(start 16.969486 -105.76687)
		(end 14.85011 -105.76687)
		(width 0.1143)
		(layer "B.Cu")
		(net "P3E_CPU1_PE3_MP_C_TXP<13>")
	)
	(segment
		(start 17.51457 -105.76687)
		(end 16.969486 -105.76687)
		(width 0.1143)
		(layer "B.Cu")
		(net "P3E_CPU1_PE3_MP_C_TXP<13>")
	)
	(segment
		(start 17.83842 -106.09072)
		(end 17.51457 -105.76687)
		(width 0.1143)
		(layer "B.Cu")
		(net "P3E_CPU1_PE3_MP_C_TXP<13>")
	)
	(segment
		(start 13.41374 -103.73614)
		(end 13.777976 -103.371904)
		(width 0.1143)
		(layer "B.Cu")
		(net "P3E_CPU1_PE3_MP_C_TXP<13>")
	)
	(segment
		(start 13.41374 -104.3305)
		(end 13.41374 -103.73614)
		(width 0.1143)
		(layer "B.Cu")
		(net "P3E_CPU1_PE3_MP_C_TXP<13>")
	)
	(segment
		(start 14.85011 -105.76687)
		(end 13.41374 -104.3305)
		(width 0.1143)
		(layer "B.Cu")
		(net "P3E_CPU1_PE3_MP_C_TXP<13>")
	)
	(segment
		(start 13.510768 -103.5812)
		(end 13.777976 -103.313992)
		(width 0.1143)
		(layer "In4.Cu")
		(net "P3E_CPU1_PE3_MP_C_TXP<13>")
	)
	(segment
		(start 12.68476 -102.1588)
		(end 12.5095 -102.33406)
		(width 0.1143)
		(layer "In4.Cu")
		(net "P3E_CPU1_PE3_MP_C_TXP<13>")
	)
	(segment
		(start 10.046462 -94.882208)
		(end 12.5095 -100.830126)
		(width 0.1143)
		(layer "In4.Cu")
		(net "P3E_CPU1_PE3_MP_C_TXP<13>")
	)
	(segment
		(start 12.5095 -103.218996)
		(end 12.871704 -103.5812)
		(width 0.1143)
		(layer "In4.Cu")
		(net "P3E_CPU1_PE3_MP_C_TXP<13>")
	)
	(segment
		(start 7.435088 -93.70314)
		(end 7.777988 -93.70314)
		(width 0.1143)
		(layer "In4.Cu")
		(net "P3E_CPU1_PE3_MP_C_TXP<13>")
	)
	(segment
		(start 8.867394 -93.70314)
		(end 10.046462 -94.882208)
		(width 0.1143)
		(layer "In4.Cu")
		(net "P3E_CPU1_PE3_MP_C_TXP<13>")
	)
	(segment
		(start 12.5095 -100.830126)
		(end 12.5095 -101.67874)
		(width 0.1143)
		(layer "In4.Cu")
		(net "P3E_CPU1_PE3_MP_C_TXP<13>")
	)
	(segment
		(start 5.51561 -92.769944)
		(end 5.346192 -92.939362)
		(width 0.1143)
		(layer "In4.Cu")
		(net "P3E_CPU1_PE3_MP_C_TXP<13>")
	)
	(segment
		(start 5.899912 -92.769944)
		(end 5.51561 -92.769944)
		(width 0.1143)
		(layer "In4.Cu")
		(net "P3E_CPU1_PE3_MP_C_TXP<13>")
	)
	(segment
		(start 13.777976 -103.313992)
		(end 13.777976 -103.028496)
		(width 0.1143)
		(layer "In4.Cu")
		(net "P3E_CPU1_PE3_MP_C_TXP<13>")
	)
	(segment
		(start 7.777988 -93.70314)
		(end 7.953248 -93.52788)
		(width 0.1143)
		(layer "In4.Cu")
		(net "P3E_CPU1_PE3_MP_C_TXP<13>")
	)
	(segment
		(start 8.433308 -93.70314)
		(end 8.867394 -93.70314)
		(width 0.1143)
		(layer "In4.Cu")
		(net "P3E_CPU1_PE3_MP_C_TXP<13>")
	)
	(segment
		(start 12.871704 -103.5812)
		(end 13.510768 -103.5812)
		(width 0.1143)
		(layer "In4.Cu")
		(net "P3E_CPU1_PE3_MP_C_TXP<13>")
	)
	(segment
		(start 5.606034 -93.70314)
		(end 6.761988 -93.70314)
		(width 0.1143)
		(layer "In4.Cu")
		(net "P3E_CPU1_PE3_MP_C_TXP<13>")
	)
	(segment
		(start 7.953248 -93.52788)
		(end 8.258048 -93.52788)
		(width 0.1143)
		(layer "In4.Cu")
		(net "P3E_CPU1_PE3_MP_C_TXP<13>")
	)
	(segment
		(start 12.68476 -101.854)
		(end 12.68476 -102.1588)
		(width 0.1143)
		(layer "In4.Cu")
		(net "P3E_CPU1_PE3_MP_C_TXP<13>")
	)
	(segment
		(start 6.927088 -93.53804)
		(end 7.269988 -93.53804)
		(width 0.1143)
		(layer "In4.Cu")
		(net "P3E_CPU1_PE3_MP_C_TXP<13>")
	)
	(segment
		(start 5.346192 -93.443298)
		(end 5.606034 -93.70314)
		(width 0.1143)
		(layer "In4.Cu")
		(net "P3E_CPU1_PE3_MP_C_TXP<13>")
	)
	(segment
		(start 8.258048 -93.52788)
		(end 8.433308 -93.70314)
		(width 0.1143)
		(layer "In4.Cu")
		(net "P3E_CPU1_PE3_MP_C_TXP<13>")
	)
	(segment
		(start 5.346192 -92.939362)
		(end 5.346192 -93.443298)
		(width 0.1143)
		(layer "In4.Cu")
		(net "P3E_CPU1_PE3_MP_C_TXP<13>")
	)
	(segment
		(start 7.269988 -93.53804)
		(end 7.435088 -93.70314)
		(width 0.1143)
		(layer "In4.Cu")
		(net "P3E_CPU1_PE3_MP_C_TXP<13>")
	)
	(segment
		(start 6.761988 -93.70314)
		(end 6.927088 -93.53804)
		(width 0.1143)
		(layer "In4.Cu")
		(net "P3E_CPU1_PE3_MP_C_TXP<13>")
	)
	(segment
		(start 12.5095 -101.67874)
		(end 12.68476 -101.854)
		(width 0.1143)
		(layer "In4.Cu")
		(net "P3E_CPU1_PE3_MP_C_TXP<13>")
	)
	(segment
		(start 12.5095 -102.33406)
		(end 12.5095 -103.218996)
		(width 0.1143)
		(layer "In4.Cu")
		(net "P3E_CPU1_PE3_MP_C_TXP<13>")
	)
	(segment
		(start 1.177036 -91.654376)
		(end 7.554976 -91.654376)
		(width 0.1143)
		(layer "B.Cu")
		(net "P3E_CPU1_PE3_MP_C_TXN<12>")
	)
	(segment
		(start 11.801602 -99.253548)
		(end 12.444984 -99.89693)
		(width 0.1143)
		(layer "B.Cu")
		(net "P3E_CPU1_PE3_MP_C_TXN<12>")
	)
	(segment
		(start 0.299974 -92.769944)
		(end 0.591566 -92.769944)
		(width 0.1143)
		(layer "B.Cu")
		(net "P3E_CPU1_PE3_MP_C_TXN<12>")
	)
	(segment
		(start 7.554976 -91.654376)
		(end 9.430512 -93.529912)
		(width 0.1143)
		(layer "B.Cu")
		(net "P3E_CPU1_PE3_MP_C_TXN<12>")
	)
	(segment
		(start 9.430512 -93.529912)
		(end 11.801602 -99.253548)
		(width 0.1143)
		(layer "B.Cu")
		(net "P3E_CPU1_PE3_MP_C_TXN<12>")
	)
	(segment
		(start 0.837438 -92.524072)
		(end 0.837438 -91.993974)
		(width 0.1143)
		(layer "B.Cu")
		(net "P3E_CPU1_PE3_MP_C_TXN<12>")
	)
	(segment
		(start 12.444984 -99.89693)
		(end 12.79017 -99.89693)
		(width 0.1143)
		(layer "B.Cu")
		(net "P3E_CPU1_PE3_MP_C_TXN<12>")
	)
	(segment
		(start 0.591566 -92.769944)
		(end 0.837438 -92.524072)
		(width 0.1143)
		(layer "B.Cu")
		(net "P3E_CPU1_PE3_MP_C_TXN<12>")
	)
	(segment
		(start 0.837438 -91.993974)
		(end 1.177036 -91.654376)
		(width 0.1143)
		(layer "B.Cu")
		(net "P3E_CPU1_PE3_MP_C_TXN<12>")
	)
	(segment
		(start 12.79017 -99.89693)
		(end 13.11402 -99.57308)
		(width 0.1143)
		(layer "B.Cu")
		(net "P3E_CPU1_PE3_MP_C_TXN<12>")
	)
	(via
		(at 12.51331 -107.69473)
		(size 0.508)
		(drill 0.254)
		(layers "F.Cu" "B.Cu")
		(net "P3E_CPU1_PE3_MP_C_TXN<11>")
	)
	(segment
		(start 12.70762 -107.18038)
		(end 13.53566 -107.18038)
		(width 0.1143)
		(layer "B.Cu")
		(net "P3E_CPU1_PE3_MP_C_TXN<11>")
	)
	(segment
		(start 12.51331 -107.37469)
		(end 12.70762 -107.18038)
		(width 0.1143)
		(layer "B.Cu")
		(net "P3E_CPU1_PE3_MP_C_TXN<11>")
	)
	(segment
		(start 12.51331 -107.69473)
		(end 12.51331 -107.37469)
		(width 0.1143)
		(layer "B.Cu")
		(net "P3E_CPU1_PE3_MP_C_TXN<11>")
	)
	(segment
		(start 13.53566 -107.18038)
		(end 13.84046 -107.48518)
		(width 0.1143)
		(layer "B.Cu")
		(net "P3E_CPU1_PE3_MP_C_TXN<11>")
	)
	(segment
		(start -3.529076 -92.769944)
		(end -3.37058 -92.92844)
		(width 0.1143)
		(layer "In4.Cu")
		(net "P3E_CPU1_PE3_MP_C_TXN<11>")
	)
	(segment
		(start -5.1816 -97.481644)
		(end -4.614164 -98.04908)
		(width 0.1143)
		(layer "In4.Cu")
		(net "P3E_CPU1_PE3_MP_C_TXN<11>")
	)
	(segment
		(start -3.608832 -93.45168)
		(end -4.553204 -93.45168)
		(width 0.1143)
		(layer "In4.Cu")
		(net "P3E_CPU1_PE3_MP_C_TXN<11>")
	)
	(segment
		(start -3.37058 -92.92844)
		(end -3.37058 -93.213428)
		(width 0.1143)
		(layer "In4.Cu")
		(net "P3E_CPU1_PE3_MP_C_TXN<11>")
	)
	(segment
		(start -3.899916 -92.769944)
		(end -3.529076 -92.769944)
		(width 0.1143)
		(layer "In4.Cu")
		(net "P3E_CPU1_PE3_MP_C_TXN<11>")
	)
	(segment
		(start -3.37058 -93.213428)
		(end -3.608832 -93.45168)
		(width 0.1143)
		(layer "In4.Cu")
		(net "P3E_CPU1_PE3_MP_C_TXN<11>")
	)
	(segment
		(start -5.1816 -94.080076)
		(end -5.1816 -97.481644)
		(width 0.1143)
		(layer "In4.Cu")
		(net "P3E_CPU1_PE3_MP_C_TXN<11>")
	)
	(segment
		(start 8.799322 -98.04908)
		(end 9.52627 -98.776028)
		(width 0.1143)
		(layer "In4.Cu")
		(net "P3E_CPU1_PE3_MP_C_TXN<11>")
	)
	(segment
		(start 10.693908 -101.594666)
		(end 10.693908 -106.509566)
		(width 0.1143)
		(layer "In4.Cu")
		(net "P3E_CPU1_PE3_MP_C_TXN<11>")
	)
	(segment
		(start -4.553204 -93.45168)
		(end -5.1816 -94.080076)
		(width 0.1143)
		(layer "In4.Cu")
		(net "P3E_CPU1_PE3_MP_C_TXN<11>")
	)
	(segment
		(start -4.614164 -98.04908)
		(end 8.799322 -98.04908)
		(width 0.1143)
		(layer "In4.Cu")
		(net "P3E_CPU1_PE3_MP_C_TXN<11>")
	)
	(segment
		(start 10.693908 -106.509566)
		(end 11.390122 -107.20578)
		(width 0.1143)
		(layer "In4.Cu")
		(net "P3E_CPU1_PE3_MP_C_TXN<11>")
	)
	(segment
		(start 12.51331 -107.32008)
		(end 12.51331 -107.69473)
		(width 0.1143)
		(layer "In4.Cu")
		(net "P3E_CPU1_PE3_MP_C_TXN<11>")
	)
	(segment
		(start 12.39901 -107.20578)
		(end 12.51331 -107.32008)
		(width 0.1143)
		(layer "In4.Cu")
		(net "P3E_CPU1_PE3_MP_C_TXN<11>")
	)
	(segment
		(start 9.52627 -98.776028)
		(end 10.693908 -101.594666)
		(width 0.1143)
		(layer "In4.Cu")
		(net "P3E_CPU1_PE3_MP_C_TXN<11>")
	)
	(segment
		(start 11.390122 -107.20578)
		(end 12.39901 -107.20578)
		(width 0.1143)
		(layer "In4.Cu")
		(net "P3E_CPU1_PE3_MP_C_TXN<11>")
	)
	(via
		(at 15.49527 -109.04347)
		(size 0.508)
		(drill 0.254)
		(layers "F.Cu" "B.Cu")
		(net "P3E_CPU1_PE3_MP_C_TXP<10>")
	)
	(segment
		(start 15.49527 -108.76153)
		(end 15.49527 -109.04347)
		(width 0.1143)
		(layer "B.Cu")
		(net "P3E_CPU1_PE3_MP_C_TXP<10>")
	)
	(segment
		(start 16.51762 -108.52912)
		(end 15.72768 -108.52912)
		(width 0.1143)
		(layer "B.Cu")
		(net "P3E_CPU1_PE3_MP_C_TXP<10>")
	)
	(segment
		(start 15.72768 -108.52912)
		(end 15.49527 -108.76153)
		(width 0.1143)
		(layer "B.Cu")
		(net "P3E_CPU1_PE3_MP_C_TXP<10>")
	)
	(segment
		(start 16.82242 -108.83392)
		(end 16.51762 -108.52912)
		(width 0.1143)
		(layer "B.Cu")
		(net "P3E_CPU1_PE3_MP_C_TXP<10>")
	)
	(segment
		(start 10.17778 -94.208092)
		(end 12.472416 -99.746054)
		(width 0.1143)
		(layer "In4.Cu")
		(net "P3E_CPU1_PE3_MP_C_TXP<10>")
	)
	(segment
		(start 5.80009 -90.769948)
		(end 6.239764 -90.769948)
		(width 0.1143)
		(layer "In4.Cu")
		(net "P3E_CPU1_PE3_MP_C_TXP<10>")
	)
	(segment
		(start 17.7419 -104.127046)
		(end 14.6431 -107.225846)
		(width 0.1143)
		(layer "In4.Cu")
		(net "P3E_CPU1_PE3_MP_C_TXP<10>")
	)
	(segment
		(start 13.612114 -100.885752)
		(end 15.581376 -101.7016)
		(width 0.1143)
		(layer "In4.Cu")
		(net "P3E_CPU1_PE3_MP_C_TXP<10>")
	)
	(segment
		(start 15.145512 -108.55452)
		(end 15.38097 -108.55452)
		(width 0.1143)
		(layer "In4.Cu")
		(net "P3E_CPU1_PE3_MP_C_TXP<10>")
	)
	(segment
		(start 15.49527 -108.66882)
		(end 15.49527 -109.04347)
		(width 0.1143)
		(layer "In4.Cu")
		(net "P3E_CPU1_PE3_MP_C_TXP<10>")
	)
	(segment
		(start 6.354064 -91.56446)
		(end 6.71068 -91.921076)
		(width 0.1143)
		(layer "In4.Cu")
		(net "P3E_CPU1_PE3_MP_C_TXP<10>")
	)
	(segment
		(start 12.472416 -99.746054)
		(end 13.612114 -100.885752)
		(width 0.1143)
		(layer "In4.Cu")
		(net "P3E_CPU1_PE3_MP_C_TXP<10>")
	)
	(segment
		(start 6.354064 -90.884248)
		(end 6.354064 -91.56446)
		(width 0.1143)
		(layer "In4.Cu")
		(net "P3E_CPU1_PE3_MP_C_TXP<10>")
	)
	(segment
		(start 17.389094 -101.7016)
		(end 17.7419 -102.054406)
		(width 0.1143)
		(layer "In4.Cu")
		(net "P3E_CPU1_PE3_MP_C_TXP<10>")
	)
	(segment
		(start 7.890764 -91.921076)
		(end 10.17778 -94.208092)
		(width 0.1143)
		(layer "In4.Cu")
		(net "P3E_CPU1_PE3_MP_C_TXP<10>")
	)
	(segment
		(start 17.7419 -102.054406)
		(end 17.7419 -104.127046)
		(width 0.1143)
		(layer "In4.Cu")
		(net "P3E_CPU1_PE3_MP_C_TXP<10>")
	)
	(segment
		(start 15.38097 -108.55452)
		(end 15.49527 -108.66882)
		(width 0.1143)
		(layer "In4.Cu")
		(net "P3E_CPU1_PE3_MP_C_TXP<10>")
	)
	(segment
		(start 6.239764 -90.769948)
		(end 6.354064 -90.884248)
		(width 0.1143)
		(layer "In4.Cu")
		(net "P3E_CPU1_PE3_MP_C_TXP<10>")
	)
	(segment
		(start 15.581376 -101.7016)
		(end 17.389094 -101.7016)
		(width 0.1143)
		(layer "In4.Cu")
		(net "P3E_CPU1_PE3_MP_C_TXP<10>")
	)
	(segment
		(start 14.6431 -107.225846)
		(end 14.6431 -108.052108)
		(width 0.1143)
		(layer "In4.Cu")
		(net "P3E_CPU1_PE3_MP_C_TXP<10>")
	)
	(segment
		(start 14.6431 -108.052108)
		(end 15.145512 -108.55452)
		(width 0.1143)
		(layer "In4.Cu")
		(net "P3E_CPU1_PE3_MP_C_TXP<10>")
	)
	(segment
		(start 6.71068 -91.921076)
		(end 7.890764 -91.921076)
		(width 0.1143)
		(layer "In4.Cu")
		(net "P3E_CPU1_PE3_MP_C_TXP<10>")
	)
	(segment
		(start 380.746 -87.3125)
		(end 380.746 -86.888066)
		(width 0.10795)
		(layer "F.Cu")
		(net "LPC_LAD3_IO3_R")
	)
	(segment
		(start 409.8671 -44.1325)
		(end 409.8671 -43.75785)
		(width 0.10795)
		(layer "F.Cu")
		(net "LPC_LAD3_IO3_R")
	)
	(segment
		(start 380.746 -86.888066)
		(end 380.956566 -86.6775)
		(width 0.10795)
		(layer "F.Cu")
		(net "LPC_LAD3_IO3_R")
	)
	(segment
		(start 409.8671 -43.75785)
		(end 410.290264 -43.334686)
		(width 0.10795)
		(layer "F.Cu")
		(net "LPC_LAD3_IO3_R")
	)
	(via
		(at 388.199884 -37.48913)
		(size 0.6604)
		(drill 0.3302)
		(layers "F.Cu" "B.Cu")
		(net "LPC_LAD3_IO3_R")
	)
	(via
		(at 389.12419 -37.338)
		(size 0.508)
		(drill 0.254)
		(layers "F.Cu" "B.Cu")
		(net "LPC_LAD3_IO3_R")
	)
	(via
		(at 409.8671 -44.1325)
		(size 0.4572)
		(drill 0.2032)
		(layers "F.Cu" "B.Cu")
		(net "LPC_LAD3_IO3_R")
	)
	(via
		(at 380.956566 -86.6775)
		(size 0.508)
		(drill 0.254)
		(layers "F.Cu" "B.Cu")
		(net "LPC_LAD3_IO3_R")
	)
	(segment
		(start 388.97306 -37.48913)
		(end 389.12419 -37.338)
		(width 0.10795)
		(layer "B.Cu")
		(net "LPC_LAD3_IO3_R")
	)
	(segment
		(start 388.199884 -37.48913)
		(end 388.97306 -37.48913)
		(width 0.10795)
		(layer "B.Cu")
		(net "LPC_LAD3_IO3_R")
	)
	(segment
		(start 401.499578 -41.580308)
		(end 402.641816 -42.722546)
		(width 0.089408)
		(layer "In4.Cu")
		(net "LPC_LAD3_IO3_R")
	)
	(segment
		(start 392.594592 -37.439346)
		(end 394.070332 -38.915086)
		(width 0.089408)
		(layer "In4.Cu")
		(net "LPC_LAD3_IO3_R")
	)
	(segment
		(start 400.44243 -41.580308)
		(end 401.499578 -41.580308)
		(width 0.089408)
		(layer "In4.Cu")
		(net "LPC_LAD3_IO3_R")
	)
	(segment
		(start 407.064718 -42.914062)
		(end 407.074116 -42.914062)
		(width 0.089408)
		(layer "In4.Cu")
		(net "LPC_LAD3_IO3_R")
	)
	(segment
		(start 389.225536 -37.439346)
		(end 392.594592 -37.439346)
		(width 0.089408)
		(layer "In4.Cu")
		(net "LPC_LAD3_IO3_R")
	)
	(segment
		(start 389.12419 -37.338)
		(end 389.225536 -37.439346)
		(width 0.089408)
		(layer "In4.Cu")
		(net "LPC_LAD3_IO3_R")
	)
	(segment
		(start 406.369012 -42.90949)
		(end 406.369266 -42.90949)
		(width 0.089408)
		(layer "In4.Cu")
		(net "LPC_LAD3_IO3_R")
	)
	(segment
		(start 407.074116 -42.914062)
		(end 408.635454 -44.4754)
		(width 0.089408)
		(layer "In4.Cu")
		(net "LPC_LAD3_IO3_R")
	)
	(segment
		(start 406.369266 -42.90949)
		(end 406.372568 -42.912792)
		(width 0.089408)
		(layer "In4.Cu")
		(net "LPC_LAD3_IO3_R")
	)
	(segment
		(start 406.372568 -42.912792)
		(end 407.063448 -42.912792)
		(width 0.089408)
		(layer "In4.Cu")
		(net "LPC_LAD3_IO3_R")
	)
	(segment
		(start 407.063448 -42.912792)
		(end 407.064718 -42.914062)
		(width 0.089408)
		(layer "In4.Cu")
		(net "LPC_LAD3_IO3_R")
	)
	(segment
		(start 397.777208 -38.915086)
		(end 400.44243 -41.580308)
		(width 0.089408)
		(layer "In4.Cu")
		(net "LPC_LAD3_IO3_R")
	)
	(segment
		(start 394.070332 -38.915086)
		(end 397.777208 -38.915086)
		(width 0.089408)
		(layer "In4.Cu")
		(net "LPC_LAD3_IO3_R")
	)
	(segment
		(start 408.635454 -44.4754)
		(end 409.5242 -44.4754)
		(width 0.089408)
		(layer "In4.Cu")
		(net "LPC_LAD3_IO3_R")
	)
	(segment
		(start 402.641816 -42.722546)
		(end 406.182068 -42.722546)
		(width 0.089408)
		(layer "In4.Cu")
		(net "LPC_LAD3_IO3_R")
	)
	(segment
		(start 409.5242 -44.4754)
		(end 409.8671 -44.1325)
		(width 0.089408)
		(layer "In4.Cu")
		(net "LPC_LAD3_IO3_R")
	)
	(segment
		(start 406.182068 -42.722546)
		(end 406.369012 -42.90949)
		(width 0.089408)
		(layer "In4.Cu")
		(net "LPC_LAD3_IO3_R")
	)
	(segment
		(start 387.017514 -72.011286)
		(end 387.017514 -73.183496)
		(width 0.089408)
		(layer "In9.Cu")
		(net "LPC_LAD3_IO3_R")
	)
	(segment
		(start 388.942072 -51.706018)
		(end 389.197088 -51.961034)
		(width 0.089408)
		(layer "In9.Cu")
		(net "LPC_LAD3_IO3_R")
	)
	(segment
		(start 387.017514 -73.183496)
		(end 386.462524 -73.738486)
		(width 0.089408)
		(layer "In9.Cu")
		(net "LPC_LAD3_IO3_R")
	)
	(segment
		(start 384.10388 -84.30514)
		(end 383.9464 -84.46262)
		(width 0.089408)
		(layer "In9.Cu")
		(net "LPC_LAD3_IO3_R")
	)
	(segment
		(start 383.9464 -84.46262)
		(end 383.0828 -84.46262)
		(width 0.089408)
		(layer "In9.Cu")
		(net "LPC_LAD3_IO3_R")
	)
	(segment
		(start 381.802386 -86.393528)
		(end 381.518414 -86.6775)
		(width 0.089408)
		(layer "In9.Cu")
		(net "LPC_LAD3_IO3_R")
	)
	(segment
		(start 389.197088 -52.916074)
		(end 390.37641 -54.095396)
		(width 0.089408)
		(layer "In9.Cu")
		(net "LPC_LAD3_IO3_R")
	)
	(segment
		(start 390.37641 -58.8518)
		(end 389.655304 -59.572906)
		(width 0.089408)
		(layer "In9.Cu")
		(net "LPC_LAD3_IO3_R")
	)
	(segment
		(start 389.675624 -41.34104)
		(end 389.417814 -41.59885)
		(width 0.089408)
		(layer "In9.Cu")
		(net "LPC_LAD3_IO3_R")
	)
	(segment
		(start 389.197088 -51.961034)
		(end 389.197088 -52.916074)
		(width 0.089408)
		(layer "In9.Cu")
		(net "LPC_LAD3_IO3_R")
	)
	(segment
		(start 389.417814 -45.033692)
		(end 388.942072 -45.509434)
		(width 0.089408)
		(layer "In9.Cu")
		(net "LPC_LAD3_IO3_R")
	)
	(segment
		(start 389.675624 -41.112186)
		(end 389.675624 -41.34104)
		(width 0.089408)
		(layer "In9.Cu")
		(net "LPC_LAD3_IO3_R")
	)
	(segment
		(start 388.942072 -45.509434)
		(end 388.942072 -51.706018)
		(width 0.089408)
		(layer "In9.Cu")
		(net "LPC_LAD3_IO3_R")
	)
	(segment
		(start 390.37641 -54.095396)
		(end 390.37641 -58.8518)
		(width 0.089408)
		(layer "In9.Cu")
		(net "LPC_LAD3_IO3_R")
	)
	(segment
		(start 389.655304 -59.572906)
		(end 389.655304 -63.5762)
		(width 0.089408)
		(layer "In9.Cu")
		(net "LPC_LAD3_IO3_R")
	)
	(segment
		(start 387.873748 -65.357756)
		(end 387.873748 -70.13829)
		(width 0.089408)
		(layer "In9.Cu")
		(net "LPC_LAD3_IO3_R")
	)
	(segment
		(start 387.624574 -71.404226)
		(end 387.017514 -72.011286)
		(width 0.089408)
		(layer "In9.Cu")
		(net "LPC_LAD3_IO3_R")
	)
	(segment
		(start 381.518414 -86.6775)
		(end 380.956566 -86.6775)
		(width 0.089408)
		(layer "In9.Cu")
		(net "LPC_LAD3_IO3_R")
	)
	(segment
		(start 384.990594 -81.988406)
		(end 384.10388 -82.87512)
		(width 0.089408)
		(layer "In9.Cu")
		(net "LPC_LAD3_IO3_R")
	)
	(segment
		(start 389.12419 -37.338)
		(end 390.24814 -38.46195)
		(width 0.089408)
		(layer "In9.Cu")
		(net "LPC_LAD3_IO3_R")
	)
	(segment
		(start 381.802386 -85.743034)
		(end 381.802386 -86.393528)
		(width 0.089408)
		(layer "In9.Cu")
		(net "LPC_LAD3_IO3_R")
	)
	(segment
		(start 386.462524 -73.738486)
		(end 386.462524 -75.865736)
		(width 0.089408)
		(layer "In9.Cu")
		(net "LPC_LAD3_IO3_R")
	)
	(segment
		(start 387.873748 -70.13829)
		(end 387.624574 -70.387464)
		(width 0.089408)
		(layer "In9.Cu")
		(net "LPC_LAD3_IO3_R")
	)
	(segment
		(start 383.0828 -84.46262)
		(end 381.802386 -85.743034)
		(width 0.089408)
		(layer "In9.Cu")
		(net "LPC_LAD3_IO3_R")
	)
	(segment
		(start 390.24814 -38.46195)
		(end 390.24814 -40.53967)
		(width 0.089408)
		(layer "In9.Cu")
		(net "LPC_LAD3_IO3_R")
	)
	(segment
		(start 384.45694 -79.464916)
		(end 384.990594 -79.99857)
		(width 0.089408)
		(layer "In9.Cu")
		(net "LPC_LAD3_IO3_R")
	)
	(segment
		(start 389.655304 -63.5762)
		(end 387.873748 -65.357756)
		(width 0.089408)
		(layer "In9.Cu")
		(net "LPC_LAD3_IO3_R")
	)
	(segment
		(start 384.10388 -82.87512)
		(end 384.10388 -84.30514)
		(width 0.089408)
		(layer "In9.Cu")
		(net "LPC_LAD3_IO3_R")
	)
	(segment
		(start 384.990594 -79.99857)
		(end 384.990594 -81.988406)
		(width 0.089408)
		(layer "In9.Cu")
		(net "LPC_LAD3_IO3_R")
	)
	(segment
		(start 386.462524 -75.865736)
		(end 384.45694 -77.871574)
		(width 0.089408)
		(layer "In9.Cu")
		(net "LPC_LAD3_IO3_R")
	)
	(segment
		(start 390.24814 -40.53967)
		(end 389.675624 -41.112186)
		(width 0.089408)
		(layer "In9.Cu")
		(net "LPC_LAD3_IO3_R")
	)
	(segment
		(start 384.45694 -77.871574)
		(end 384.45694 -79.464916)
		(width 0.089408)
		(layer "In9.Cu")
		(net "LPC_LAD3_IO3_R")
	)
	(segment
		(start 387.624574 -70.387464)
		(end 387.624574 -71.404226)
		(width 0.089408)
		(layer "In9.Cu")
		(net "LPC_LAD3_IO3_R")
	)
	(segment
		(start 389.417814 -41.59885)
		(end 389.417814 -45.033692)
		(width 0.089408)
		(layer "In9.Cu")
		(net "LPC_LAD3_IO3_R")
	)
	(segment
		(start 408.742388 -44.040806)
		(end 408.742388 -43.807888)
		(width 0.10795)
		(layer "F.Cu")
		(net "LPC_LAD2_IO2_R")
	)
	(segment
		(start 409.02128 -43.528996)
		(end 409.490164 -43.334686)
		(width 0.10795)
		(layer "F.Cu")
		(net "LPC_LAD2_IO2_R")
	)
	(segment
		(start 379.673104 -86.035896)
		(end 379.39472 -86.31428)
		(width 0.10795)
		(layer "F.Cu")
		(net "LPC_LAD2_IO2_R")
	)
	(segment
		(start 379.84303 -86.035896)
		(end 379.673104 -86.035896)
		(width 0.10795)
		(layer "F.Cu")
		(net "LPC_LAD2_IO2_R")
	)
	(segment
		(start 379.39472 -86.72322)
		(end 379.984 -87.3125)
		(width 0.10795)
		(layer "F.Cu")
		(net "LPC_LAD2_IO2_R")
	)
	(segment
		(start 379.39472 -86.31428)
		(end 379.39472 -86.72322)
		(width 0.10795)
		(layer "F.Cu")
		(net "LPC_LAD2_IO2_R")
	)
	(segment
		(start 408.742388 -43.807888)
		(end 409.02128 -43.528996)
		(width 0.10795)
		(layer "F.Cu")
		(net "LPC_LAD2_IO2_R")
	)
	(via
		(at 408.715464 -43.181524)
		(size 0.6604)
		(drill 0.3302)
		(layers "F.Cu" "B.Cu")
		(net "LPC_LAD2_IO2_R")
	)
	(via
		(at 379.84303 -86.035896)
		(size 0.508)
		(drill 0.254)
		(layers "F.Cu" "B.Cu")
		(net "LPC_LAD2_IO2_R")
	)
	(via
		(at 389.362442 -36.707572)
		(size 0.508)
		(drill 0.254)
		(layers "F.Cu" "B.Cu")
		(net "LPC_LAD2_IO2_R")
	)
	(via
		(at 408.742388 -44.040806)
		(size 0.4572)
		(drill 0.2032)
		(layers "F.Cu" "B.Cu")
		(net "LPC_LAD2_IO2_R")
	)
	(segment
		(start 408.715464 -44.013882)
		(end 408.715464 -43.181524)
		(width 0.089408)
		(layer "B.Cu")
		(net "LPC_LAD2_IO2_R")
	)
	(segment
		(start 408.742388 -44.040806)
		(end 408.715464 -44.013882)
		(width 0.089408)
		(layer "B.Cu")
		(net "LPC_LAD2_IO2_R")
	)
	(segment
		(start 389.661908 -37.007038)
		(end 392.773662 -37.007038)
		(width 0.089408)
		(layer "In4.Cu")
		(net "LPC_LAD2_IO2_R")
	)
	(segment
		(start 405.012906 -41.75506)
		(end 406.404064 -41.75506)
		(width 0.089408)
		(layer "In4.Cu")
		(net "LPC_LAD2_IO2_R")
	)
	(segment
		(start 404.483062 -42.284904)
		(end 405.012906 -41.75506)
		(width 0.089408)
		(layer "In4.Cu")
		(net "LPC_LAD2_IO2_R")
	)
	(segment
		(start 401.678648 -41.148)
		(end 402.815552 -42.284904)
		(width 0.089408)
		(layer "In4.Cu")
		(net "LPC_LAD2_IO2_R")
	)
	(segment
		(start 402.815552 -42.284904)
		(end 404.483062 -42.284904)
		(width 0.089408)
		(layer "In4.Cu")
		(net "LPC_LAD2_IO2_R")
	)
	(segment
		(start 400.6215 -41.148)
		(end 401.678648 -41.148)
		(width 0.089408)
		(layer "In4.Cu")
		(net "LPC_LAD2_IO2_R")
	)
	(segment
		(start 408.68981 -44.040806)
		(end 408.742388 -44.040806)
		(width 0.089408)
		(layer "In4.Cu")
		(net "LPC_LAD2_IO2_R")
	)
	(segment
		(start 397.947896 -38.474396)
		(end 400.6215 -41.148)
		(width 0.089408)
		(layer "In4.Cu")
		(net "LPC_LAD2_IO2_R")
	)
	(segment
		(start 406.404064 -41.75506)
		(end 408.68981 -44.040806)
		(width 0.089408)
		(layer "In4.Cu")
		(net "LPC_LAD2_IO2_R")
	)
	(segment
		(start 394.24102 -38.474396)
		(end 397.947896 -38.474396)
		(width 0.089408)
		(layer "In4.Cu")
		(net "LPC_LAD2_IO2_R")
	)
	(segment
		(start 389.362442 -36.707572)
		(end 389.661908 -37.007038)
		(width 0.089408)
		(layer "In4.Cu")
		(net "LPC_LAD2_IO2_R")
	)
	(segment
		(start 392.773662 -37.007038)
		(end 394.24102 -38.474396)
		(width 0.089408)
		(layer "In4.Cu")
		(net "LPC_LAD2_IO2_R")
	)
	(segment
		(start 386.030216 -75.665076)
		(end 386.030216 -73.559416)
		(width 0.089408)
		(layer "In9.Cu")
		(net "LPC_LAD2_IO2_R")
	)
	(segment
		(start 389.944102 -58.672476)
		(end 389.944102 -54.274466)
		(width 0.089408)
		(layer "In9.Cu")
		(net "LPC_LAD2_IO2_R")
	)
	(segment
		(start 387.44144 -69.95922)
		(end 387.44144 -65.178686)
		(width 0.089408)
		(layer "In9.Cu")
		(net "LPC_LAD2_IO2_R")
	)
	(segment
		(start 387.192266 -71.125334)
		(end 387.192266 -70.208394)
		(width 0.089408)
		(layer "In9.Cu")
		(net "LPC_LAD2_IO2_R")
	)
	(segment
		(start 382.54686 -83.343242)
		(end 384.024632 -81.86547)
		(width 0.089408)
		(layer "In9.Cu")
		(net "LPC_LAD2_IO2_R")
	)
	(segment
		(start 388.76478 -53.095144)
		(end 388.76478 -52.164234)
		(width 0.089408)
		(layer "In9.Cu")
		(net "LPC_LAD2_IO2_R")
	)
	(segment
		(start 389.200898 -62.318138)
		(end 389.200898 -59.41568)
		(width 0.089408)
		(layer "In9.Cu")
		(net "LPC_LAD2_IO2_R")
	)
	(segment
		(start 388.76478 -52.164234)
		(end 388.504684 -51.904138)
		(width 0.089408)
		(layer "In9.Cu")
		(net "LPC_LAD2_IO2_R")
	)
	(segment
		(start 389.200898 -59.41568)
		(end 389.944102 -58.672476)
		(width 0.089408)
		(layer "In9.Cu")
		(net "LPC_LAD2_IO2_R")
	)
	(segment
		(start 388.723886 -36.903914)
		(end 388.920228 -36.707572)
		(width 0.089408)
		(layer "In9.Cu")
		(net "LPC_LAD2_IO2_R")
	)
	(segment
		(start 389.243316 -40.933116)
		(end 389.815832 -40.3606)
		(width 0.089408)
		(layer "In9.Cu")
		(net "LPC_LAD2_IO2_R")
	)
	(segment
		(start 388.548626 -64.0715)
		(end 388.548626 -62.97041)
		(width 0.089408)
		(layer "In9.Cu")
		(net "LPC_LAD2_IO2_R")
	)
	(segment
		(start 386.585206 -73.004426)
		(end 386.585206 -71.732394)
		(width 0.089408)
		(layer "In9.Cu")
		(net "LPC_LAD2_IO2_R")
	)
	(segment
		(start 386.030216 -73.559416)
		(end 386.585206 -73.004426)
		(width 0.089408)
		(layer "In9.Cu")
		(net "LPC_LAD2_IO2_R")
	)
	(segment
		(start 387.44144 -65.178686)
		(end 388.548626 -64.0715)
		(width 0.089408)
		(layer "In9.Cu")
		(net "LPC_LAD2_IO2_R")
	)
	(segment
		(start 380.642368 -86.40572)
		(end 381.035814 -86.012274)
		(width 0.089408)
		(layer "In9.Cu")
		(net "LPC_LAD2_IO2_R")
	)
	(segment
		(start 381.035814 -86.012274)
		(end 381.035814 -85.894926)
		(width 0.089408)
		(layer "In9.Cu")
		(net "LPC_LAD2_IO2_R")
	)
	(segment
		(start 380.28372 -86.40572)
		(end 380.642368 -86.40572)
		(width 0.089408)
		(layer "In9.Cu")
		(net "LPC_LAD2_IO2_R")
	)
	(segment
		(start 389.815832 -40.3606)
		(end 389.815832 -38.74008)
		(width 0.089408)
		(layer "In9.Cu")
		(net "LPC_LAD2_IO2_R")
	)
	(segment
		(start 388.920228 -36.707572)
		(end 389.362442 -36.707572)
		(width 0.089408)
		(layer "In9.Cu")
		(net "LPC_LAD2_IO2_R")
	)
	(segment
		(start 384.024378 -77.671422)
		(end 386.030216 -75.665076)
		(width 0.089408)
		(layer "In9.Cu")
		(net "LPC_LAD2_IO2_R")
	)
	(segment
		(start 387.192266 -70.208394)
		(end 387.44144 -69.95922)
		(width 0.089408)
		(layer "In9.Cu")
		(net "LPC_LAD2_IO2_R")
	)
	(segment
		(start 389.243316 -41.16197)
		(end 389.243316 -40.933116)
		(width 0.089408)
		(layer "In9.Cu")
		(net "LPC_LAD2_IO2_R")
	)
	(segment
		(start 388.504684 -41.900602)
		(end 389.243316 -41.16197)
		(width 0.089408)
		(layer "In9.Cu")
		(net "LPC_LAD2_IO2_R")
	)
	(segment
		(start 384.024632 -81.86547)
		(end 384.024632 -78.050644)
		(width 0.089408)
		(layer "In9.Cu")
		(net "LPC_LAD2_IO2_R")
	)
	(segment
		(start 379.84303 -86.035896)
		(end 379.913896 -86.035896)
		(width 0.089408)
		(layer "In9.Cu")
		(net "LPC_LAD2_IO2_R")
	)
	(segment
		(start 388.548626 -62.97041)
		(end 389.200898 -62.318138)
		(width 0.089408)
		(layer "In9.Cu")
		(net "LPC_LAD2_IO2_R")
	)
	(segment
		(start 384.024378 -78.05039)
		(end 384.024378 -77.671422)
		(width 0.089408)
		(layer "In9.Cu")
		(net "LPC_LAD2_IO2_R")
	)
	(segment
		(start 381.035814 -85.894926)
		(end 382.54686 -84.38388)
		(width 0.089408)
		(layer "In9.Cu")
		(net "LPC_LAD2_IO2_R")
	)
	(segment
		(start 386.585206 -71.732394)
		(end 387.192266 -71.125334)
		(width 0.089408)
		(layer "In9.Cu")
		(net "LPC_LAD2_IO2_R")
	)
	(segment
		(start 382.54686 -84.38388)
		(end 382.54686 -83.343242)
		(width 0.089408)
		(layer "In9.Cu")
		(net "LPC_LAD2_IO2_R")
	)
	(segment
		(start 379.913896 -86.035896)
		(end 380.28372 -86.40572)
		(width 0.089408)
		(layer "In9.Cu")
		(net "LPC_LAD2_IO2_R")
	)
	(segment
		(start 389.944102 -54.274466)
		(end 388.76478 -53.095144)
		(width 0.089408)
		(layer "In9.Cu")
		(net "LPC_LAD2_IO2_R")
	)
	(segment
		(start 384.024632 -78.050644)
		(end 384.024378 -78.05039)
		(width 0.089408)
		(layer "In9.Cu")
		(net "LPC_LAD2_IO2_R")
	)
	(segment
		(start 389.815832 -38.74008)
		(end 388.723886 -37.648134)
		(width 0.089408)
		(layer "In9.Cu")
		(net "LPC_LAD2_IO2_R")
	)
	(segment
		(start 388.504684 -51.904138)
		(end 388.504684 -41.900602)
		(width 0.089408)
		(layer "In9.Cu")
		(net "LPC_LAD2_IO2_R")
	)
	(segment
		(start 388.723886 -37.648134)
		(end 388.723886 -36.903914)
		(width 0.089408)
		(layer "In9.Cu")
		(net "LPC_LAD2_IO2_R")
	)
	(segment
		(start 378.95784 -85.701886)
		(end 378.95784 -87.04834)
		(width 0.10795)
		(layer "F.Cu")
		(net "LPC_LAD1_IO1_R")
	)
	(segment
		(start 379.220222 -85.439504)
		(end 378.95784 -85.701886)
		(width 0.10795)
		(layer "F.Cu")
		(net "LPC_LAD1_IO1_R")
	)
	(segment
		(start 411.89021 -41.73474)
		(end 411.89021 -41.734994)
		(width 0.10795)
		(layer "F.Cu")
		(net "LPC_LAD1_IO1_R")
	)
	(segment
		(start 378.95784 -87.04834)
		(end 379.222 -87.3125)
		(width 0.10795)
		(layer "F.Cu")
		(net "LPC_LAD1_IO1_R")
	)
	(segment
		(start 411.89021 -41.734994)
		(end 411.490414 -42.13479)
		(width 0.10795)
		(layer "F.Cu")
		(net "LPC_LAD1_IO1_R")
	)
	(segment
		(start 380.0856 -85.439504)
		(end 379.220222 -85.439504)
		(width 0.10795)
		(layer "F.Cu")
		(net "LPC_LAD1_IO1_R")
	)
	(via
		(at 380.0856 -85.439504)
		(size 0.508)
		(drill 0.254)
		(layers "F.Cu" "B.Cu")
		(net "LPC_LAD1_IO1_R")
	)
	(via
		(at 411.490414 -42.13479)
		(size 0.4572)
		(drill 0.2032)
		(layers "F.Cu" "B.Cu")
		(net "LPC_LAD1_IO1_R")
	)
	(via
		(at 387.68274 -36.11626)
		(size 0.508)
		(drill 0.254)
		(layers "F.Cu" "B.Cu")
		(net "LPC_LAD1_IO1_R")
	)
	(segment
		(start 389.70585 -36.11626)
		(end 387.68274 -36.11626)
		(width 0.089408)
		(layer "In4.Cu")
		(net "LPC_LAD1_IO1_R")
	)
	(segment
		(start 405.3459 -40.524684)
		(end 404.572216 -39.751)
		(width 0.089408)
		(layer "In4.Cu")
		(net "LPC_LAD1_IO1_R")
	)
	(segment
		(start 411.490414 -42.13479)
		(end 411.115764 -42.50944)
		(width 0.089408)
		(layer "In4.Cu")
		(net "LPC_LAD1_IO1_R")
	)
	(segment
		(start 394.396722 -38.01872)
		(end 392.952732 -36.57473)
		(width 0.089408)
		(layer "In4.Cu")
		(net "LPC_LAD1_IO1_R")
	)
	(segment
		(start 406.666954 -40.524684)
		(end 405.3459 -40.524684)
		(width 0.089408)
		(layer "In4.Cu")
		(net "LPC_LAD1_IO1_R")
	)
	(segment
		(start 408.65171 -42.50944)
		(end 406.666954 -40.524684)
		(width 0.089408)
		(layer "In4.Cu")
		(net "LPC_LAD1_IO1_R")
	)
	(segment
		(start 404.377652 -39.751)
		(end 402.199348 -37.572696)
		(width 0.089408)
		(layer "In4.Cu")
		(net "LPC_LAD1_IO1_R")
	)
	(segment
		(start 399.112232 -38.01872)
		(end 394.396722 -38.01872)
		(width 0.089408)
		(layer "In4.Cu")
		(net "LPC_LAD1_IO1_R")
	)
	(segment
		(start 411.115764 -42.50944)
		(end 408.65171 -42.50944)
		(width 0.089408)
		(layer "In4.Cu")
		(net "LPC_LAD1_IO1_R")
	)
	(segment
		(start 392.952732 -36.57473)
		(end 390.16432 -36.57473)
		(width 0.089408)
		(layer "In4.Cu")
		(net "LPC_LAD1_IO1_R")
	)
	(segment
		(start 402.199348 -37.572696)
		(end 399.558256 -37.572696)
		(width 0.089408)
		(layer "In4.Cu")
		(net "LPC_LAD1_IO1_R")
	)
	(segment
		(start 404.572216 -39.751)
		(end 404.377652 -39.751)
		(width 0.089408)
		(layer "In4.Cu")
		(net "LPC_LAD1_IO1_R")
	)
	(segment
		(start 399.558256 -37.572696)
		(end 399.112232 -38.01872)
		(width 0.089408)
		(layer "In4.Cu")
		(net "LPC_LAD1_IO1_R")
	)
	(segment
		(start 390.16432 -36.57473)
		(end 389.70585 -36.11626)
		(width 0.089408)
		(layer "In4.Cu")
		(net "LPC_LAD1_IO1_R")
	)
	(segment
		(start 386.772658 -39.045642)
		(end 386.772658 -44.496482)
		(width 0.089408)
		(layer "In9.Cu")
		(net "LPC_LAD1_IO1_R")
	)
	(segment
		(start 388.116318 -63.89243)
		(end 387.009132 -64.999616)
		(width 0.089408)
		(layer "In9.Cu")
		(net "LPC_LAD1_IO1_R")
	)
	(segment
		(start 385.597908 -75.486006)
		(end 383.59207 -77.492352)
		(width 0.089408)
		(layer "In9.Cu")
		(net "LPC_LAD1_IO1_R")
	)
	(segment
		(start 387.68274 -36.11626)
		(end 387.68274 -38.13556)
		(width 0.089408)
		(layer "In9.Cu")
		(net "LPC_LAD1_IO1_R")
	)
	(segment
		(start 388.332472 -53.274214)
		(end 389.511794 -54.453536)
		(width 0.089408)
		(layer "In9.Cu")
		(net "LPC_LAD1_IO1_R")
	)
	(segment
		(start 388.76859 -62.138814)
		(end 388.116318 -62.791086)
		(width 0.089408)
		(layer "In9.Cu")
		(net "LPC_LAD1_IO1_R")
	)
	(segment
		(start 389.511794 -58.493406)
		(end 388.76859 -59.23661)
		(width 0.089408)
		(layer "In9.Cu")
		(net "LPC_LAD1_IO1_R")
	)
	(segment
		(start 383.59207 -77.492352)
		(end 383.59207 -78.229714)
		(width 0.089408)
		(layer "In9.Cu")
		(net "LPC_LAD1_IO1_R")
	)
	(segment
		(start 386.152898 -72.825102)
		(end 385.597908 -73.380092)
		(width 0.089408)
		(layer "In9.Cu")
		(net "LPC_LAD1_IO1_R")
	)
	(segment
		(start 386.772658 -44.496482)
		(end 388.072376 -45.7962)
		(width 0.089408)
		(layer "In9.Cu")
		(net "LPC_LAD1_IO1_R")
	)
	(segment
		(start 389.511794 -54.453536)
		(end 389.511794 -58.493406)
		(width 0.089408)
		(layer "In9.Cu")
		(net "LPC_LAD1_IO1_R")
	)
	(segment
		(start 387.68274 -38.13556)
		(end 386.772658 -39.045642)
		(width 0.089408)
		(layer "In9.Cu")
		(net "LPC_LAD1_IO1_R")
	)
	(segment
		(start 386.152898 -70.636384)
		(end 386.152898 -72.825102)
		(width 0.089408)
		(layer "In9.Cu")
		(net "LPC_LAD1_IO1_R")
	)
	(segment
		(start 383.592324 -81.6864)
		(end 381.5969 -83.681824)
		(width 0.089408)
		(layer "In9.Cu")
		(net "LPC_LAD1_IO1_R")
	)
	(segment
		(start 388.072376 -45.7962)
		(end 388.072376 -52.083208)
		(width 0.089408)
		(layer "In9.Cu")
		(net "LPC_LAD1_IO1_R")
	)
	(segment
		(start 380.228856 -85.58276)
		(end 380.0856 -85.439504)
		(width 0.089408)
		(layer "In9.Cu")
		(net "LPC_LAD1_IO1_R")
	)
	(segment
		(start 388.072376 -52.083208)
		(end 388.332472 -52.343304)
		(width 0.089408)
		(layer "In9.Cu")
		(net "LPC_LAD1_IO1_R")
	)
	(segment
		(start 388.332472 -52.343304)
		(end 388.332472 -53.274214)
		(width 0.089408)
		(layer "In9.Cu")
		(net "LPC_LAD1_IO1_R")
	)
	(segment
		(start 388.116318 -62.791086)
		(end 388.116318 -63.89243)
		(width 0.089408)
		(layer "In9.Cu")
		(net "LPC_LAD1_IO1_R")
	)
	(segment
		(start 380.72314 -85.58276)
		(end 380.228856 -85.58276)
		(width 0.089408)
		(layer "In9.Cu")
		(net "LPC_LAD1_IO1_R")
	)
	(segment
		(start 383.59207 -78.229714)
		(end 383.592324 -78.229968)
		(width 0.089408)
		(layer "In9.Cu")
		(net "LPC_LAD1_IO1_R")
	)
	(segment
		(start 381.5969 -84.709)
		(end 380.72314 -85.58276)
		(width 0.089408)
		(layer "In9.Cu")
		(net "LPC_LAD1_IO1_R")
	)
	(segment
		(start 381.5969 -83.681824)
		(end 381.5969 -84.709)
		(width 0.089408)
		(layer "In9.Cu")
		(net "LPC_LAD1_IO1_R")
	)
	(segment
		(start 388.76859 -59.23661)
		(end 388.76859 -62.138814)
		(width 0.089408)
		(layer "In9.Cu")
		(net "LPC_LAD1_IO1_R")
	)
	(segment
		(start 387.009132 -64.999616)
		(end 387.009132 -69.78015)
		(width 0.089408)
		(layer "In9.Cu")
		(net "LPC_LAD1_IO1_R")
	)
	(segment
		(start 387.009132 -69.78015)
		(end 386.152898 -70.636384)
		(width 0.089408)
		(layer "In9.Cu")
		(net "LPC_LAD1_IO1_R")
	)
	(segment
		(start 385.597908 -73.380092)
		(end 385.597908 -75.486006)
		(width 0.089408)
		(layer "In9.Cu")
		(net "LPC_LAD1_IO1_R")
	)
	(segment
		(start 383.592324 -78.229968)
		(end 383.592324 -81.6864)
		(width 0.089408)
		(layer "In9.Cu")
		(net "LPC_LAD1_IO1_R")
	)
	(segment
		(start 411.509972 -42.914824)
		(end 411.481524 -42.914824)
		(width 0.089408)
		(layer "F.Cu")
		(net "LPC_LAD0_IO0_R")
	)
	(segment
		(start 381.544068 -85.718396)
		(end 381.323596 -85.718396)
		(width 0.10795)
		(layer "F.Cu")
		(net "LPC_LAD0_IO0_R")
	)
	(segment
		(start 381.508 -87.3125)
		(end 381.508 -86.70036)
		(width 0.10795)
		(layer "F.Cu")
		(net "LPC_LAD0_IO0_R")
	)
	(segment
		(start 411.89021 -42.534586)
		(end 411.509972 -42.914824)
		(width 0.089408)
		(layer "F.Cu")
		(net "LPC_LAD0_IO0_R")
	)
	(segment
		(start 381.824484 -85.998812)
		(end 381.544068 -85.718396)
		(width 0.10795)
		(layer "F.Cu")
		(net "LPC_LAD0_IO0_R")
	)
	(segment
		(start 381.508 -86.70036)
		(end 381.824484 -86.383876)
		(width 0.10795)
		(layer "F.Cu")
		(net "LPC_LAD0_IO0_R")
	)
	(segment
		(start 381.323596 -85.718396)
		(end 380.6444 -85.0392)
		(width 0.10795)
		(layer "F.Cu")
		(net "LPC_LAD0_IO0_R")
	)
	(segment
		(start 381.824484 -86.383876)
		(end 381.824484 -85.998812)
		(width 0.10795)
		(layer "F.Cu")
		(net "LPC_LAD0_IO0_R")
	)
	(via
		(at 387.3246 -35.3314)
		(size 0.508)
		(drill 0.254)
		(layers "F.Cu" "B.Cu")
		(net "LPC_LAD0_IO0_R")
	)
	(via
		(at 411.481524 -42.914824)
		(size 0.4572)
		(drill 0.2032)
		(layers "F.Cu" "B.Cu")
		(net "LPC_LAD0_IO0_R")
	)
	(via
		(at 380.6444 -85.0392)
		(size 0.508)
		(drill 0.254)
		(layers "F.Cu" "B.Cu")
		(net "LPC_LAD0_IO0_R")
	)
	(segment
		(start 387.734302 -35.3314)
		(end 388.086854 -35.683952)
		(width 0.089408)
		(layer "In4.Cu")
		(net "LPC_LAD0_IO0_R")
	)
	(segment
		(start 389.91413 -35.712908)
		(end 390.343644 -36.142422)
		(width 0.089408)
		(layer "In4.Cu")
		(net "LPC_LAD0_IO0_R")
	)
	(segment
		(start 407.729182 -41.303702)
		(end 408.162506 -41.737026)
		(width 0.089408)
		(layer "In4.Cu")
		(net "LPC_LAD0_IO0_R")
	)
	(segment
		(start 388.086854 -35.683952)
		(end 389.88492 -35.683952)
		(width 0.089408)
		(layer "In4.Cu")
		(net "LPC_LAD0_IO0_R")
	)
	(segment
		(start 397.040862 -37.56025)
		(end 397.281146 -37.319966)
		(width 0.089408)
		(layer "In4.Cu")
		(net "LPC_LAD0_IO0_R")
	)
	(segment
		(start 411.622494 -41.737026)
		(end 411.645354 -41.759886)
		(width 0.089408)
		(layer "In4.Cu")
		(net "LPC_LAD0_IO0_R")
	)
	(segment
		(start 393.218162 -36.228528)
		(end 394.549884 -37.56025)
		(width 0.089408)
		(layer "In4.Cu")
		(net "LPC_LAD0_IO0_R")
	)
	(segment
		(start 406.47874 -39.5478)
		(end 407.729182 -40.798242)
		(width 0.089408)
		(layer "In4.Cu")
		(net "LPC_LAD0_IO0_R")
	)
	(segment
		(start 389.88492 -35.683952)
		(end 389.913876 -35.712908)
		(width 0.089408)
		(layer "In4.Cu")
		(net "LPC_LAD0_IO0_R")
	)
	(segment
		(start 399.199608 -37.319966)
		(end 399.379186 -37.140388)
		(width 0.089408)
		(layer "In4.Cu")
		(net "LPC_LAD0_IO0_R")
	)
	(segment
		(start 411.865318 -42.53103)
		(end 411.481524 -42.914824)
		(width 0.089408)
		(layer "In4.Cu")
		(net "LPC_LAD0_IO0_R")
	)
	(segment
		(start 403.009862 -37.140388)
		(end 405.417274 -39.5478)
		(width 0.089408)
		(layer "In4.Cu")
		(net "LPC_LAD0_IO0_R")
	)
	(segment
		(start 389.913876 -35.712908)
		(end 389.91413 -35.712908)
		(width 0.089408)
		(layer "In4.Cu")
		(net "LPC_LAD0_IO0_R")
	)
	(segment
		(start 411.645862 -41.759886)
		(end 411.865318 -41.979342)
		(width 0.089408)
		(layer "In4.Cu")
		(net "LPC_LAD0_IO0_R")
	)
	(segment
		(start 399.379186 -37.140388)
		(end 403.009862 -37.140388)
		(width 0.089408)
		(layer "In4.Cu")
		(net "LPC_LAD0_IO0_R")
	)
	(segment
		(start 393.131802 -36.142422)
		(end 393.217908 -36.228528)
		(width 0.089408)
		(layer "In4.Cu")
		(net "LPC_LAD0_IO0_R")
	)
	(segment
		(start 394.549884 -37.56025)
		(end 397.040862 -37.56025)
		(width 0.089408)
		(layer "In4.Cu")
		(net "LPC_LAD0_IO0_R")
	)
	(segment
		(start 411.645354 -41.759886)
		(end 411.645862 -41.759886)
		(width 0.089408)
		(layer "In4.Cu")
		(net "LPC_LAD0_IO0_R")
	)
	(segment
		(start 411.865318 -41.979342)
		(end 411.865318 -42.53103)
		(width 0.089408)
		(layer "In4.Cu")
		(net "LPC_LAD0_IO0_R")
	)
	(segment
		(start 408.162506 -41.737026)
		(end 411.622494 -41.737026)
		(width 0.089408)
		(layer "In4.Cu")
		(net "LPC_LAD0_IO0_R")
	)
	(segment
		(start 405.417274 -39.5478)
		(end 406.47874 -39.5478)
		(width 0.089408)
		(layer "In4.Cu")
		(net "LPC_LAD0_IO0_R")
	)
	(segment
		(start 387.3246 -35.3314)
		(end 387.734302 -35.3314)
		(width 0.089408)
		(layer "In4.Cu")
		(net "LPC_LAD0_IO0_R")
	)
	(segment
		(start 407.729182 -40.798242)
		(end 407.729182 -41.303702)
		(width 0.089408)
		(layer "In4.Cu")
		(net "LPC_LAD0_IO0_R")
	)
	(segment
		(start 393.217908 -36.228528)
		(end 393.218162 -36.228528)
		(width 0.089408)
		(layer "In4.Cu")
		(net "LPC_LAD0_IO0_R")
	)
	(segment
		(start 397.281146 -37.319966)
		(end 399.199608 -37.319966)
		(width 0.089408)
		(layer "In4.Cu")
		(net "LPC_LAD0_IO0_R")
	)
	(segment
		(start 390.343644 -36.142422)
		(end 393.131802 -36.142422)
		(width 0.089408)
		(layer "In4.Cu")
		(net "LPC_LAD0_IO0_R")
	)
	(segment
		(start 385.139692 -75.332844)
		(end 383.150872 -77.322172)
		(width 0.089408)
		(layer "In9.Cu")
		(net "LPC_LAD0_IO0_R")
	)
	(segment
		(start 387.640068 -46.092364)
		(end 387.640068 -52.262278)
		(width 0.089408)
		(layer "In9.Cu")
		(net "LPC_LAD0_IO0_R")
	)
	(segment
		(start 387.900164 -52.522374)
		(end 387.900164 -53.453284)
		(width 0.089408)
		(layer "In9.Cu")
		(net "LPC_LAD0_IO0_R")
	)
	(segment
		(start 382.715516 -79.31658)
		(end 382.715516 -79.74838)
		(width 0.089408)
		(layer "In9.Cu")
		(net "LPC_LAD0_IO0_R")
	)
	(segment
		(start 387.833616 -61.97473)
		(end 386.576824 -63.231522)
		(width 0.089408)
		(layer "In9.Cu")
		(net "LPC_LAD0_IO0_R")
	)
	(segment
		(start 381.1016 -84.582)
		(end 380.6444 -85.0392)
		(width 0.089408)
		(layer "In9.Cu")
		(net "LPC_LAD0_IO0_R")
	)
	(segment
		(start 386.33527 -36.32073)
		(end 386.33527 -44.787566)
		(width 0.089408)
		(layer "In9.Cu")
		(net "LPC_LAD0_IO0_R")
	)
	(segment
		(start 385.72059 -70.457314)
		(end 385.72059 -71.800466)
		(width 0.089408)
		(layer "In9.Cu")
		(net "LPC_LAD0_IO0_R")
	)
	(segment
		(start 386.33527 -44.787566)
		(end 387.640068 -46.092364)
		(width 0.089408)
		(layer "In9.Cu")
		(net "LPC_LAD0_IO0_R")
	)
	(segment
		(start 383.14884 -80.181704)
		(end 383.14884 -81.518506)
		(width 0.089408)
		(layer "In9.Cu")
		(net "LPC_LAD0_IO0_R")
	)
	(segment
		(start 387.833616 -61.238638)
		(end 387.833616 -61.97473)
		(width 0.089408)
		(layer "In9.Cu")
		(net "LPC_LAD0_IO0_R")
	)
	(segment
		(start 386.576824 -63.231522)
		(end 386.576824 -69.60108)
		(width 0.089408)
		(layer "In9.Cu")
		(net "LPC_LAD0_IO0_R")
	)
	(segment
		(start 388.69239 -54.24551)
		(end 388.69239 -58.344054)
		(width 0.089408)
		(layer "In9.Cu")
		(net "LPC_LAD0_IO0_R")
	)
	(segment
		(start 387.900164 -53.453284)
		(end 388.69239 -54.24551)
		(width 0.089408)
		(layer "In9.Cu")
		(net "LPC_LAD0_IO0_R")
	)
	(segment
		(start 388.69239 -58.344054)
		(end 388.336282 -58.700162)
		(width 0.089408)
		(layer "In9.Cu")
		(net "LPC_LAD0_IO0_R")
	)
	(segment
		(start 388.336282 -58.700162)
		(end 388.336282 -60.735972)
		(width 0.089408)
		(layer "In9.Cu")
		(net "LPC_LAD0_IO0_R")
	)
	(segment
		(start 382.715516 -79.74838)
		(end 383.14884 -80.181704)
		(width 0.089408)
		(layer "In9.Cu")
		(net "LPC_LAD0_IO0_R")
	)
	(segment
		(start 385.72059 -71.800466)
		(end 385.139692 -72.381364)
		(width 0.089408)
		(layer "In9.Cu")
		(net "LPC_LAD0_IO0_R")
	)
	(segment
		(start 388.336282 -60.735972)
		(end 387.833616 -61.238638)
		(width 0.089408)
		(layer "In9.Cu")
		(net "LPC_LAD0_IO0_R")
	)
	(segment
		(start 383.14884 -81.518506)
		(end 381.1016 -83.565746)
		(width 0.089408)
		(layer "In9.Cu")
		(net "LPC_LAD0_IO0_R")
	)
	(segment
		(start 383.150872 -78.881224)
		(end 382.715516 -79.31658)
		(width 0.089408)
		(layer "In9.Cu")
		(net "LPC_LAD0_IO0_R")
	)
	(segment
		(start 387.640068 -52.262278)
		(end 387.900164 -52.522374)
		(width 0.089408)
		(layer "In9.Cu")
		(net "LPC_LAD0_IO0_R")
	)
	(segment
		(start 387.3246 -35.3314)
		(end 386.33527 -36.32073)
		(width 0.089408)
		(layer "In9.Cu")
		(net "LPC_LAD0_IO0_R")
	)
	(segment
		(start 381.1016 -83.565746)
		(end 381.1016 -84.582)
		(width 0.089408)
		(layer "In9.Cu")
		(net "LPC_LAD0_IO0_R")
	)
	(segment
		(start 383.150872 -77.322172)
		(end 383.150872 -78.881224)
		(width 0.089408)
		(layer "In9.Cu")
		(net "LPC_LAD0_IO0_R")
	)
	(segment
		(start 385.139692 -72.381364)
		(end 385.139692 -75.332844)
		(width 0.089408)
		(layer "In9.Cu")
		(net "LPC_LAD0_IO0_R")
	)
	(segment
		(start 386.576824 -69.60108)
		(end 385.72059 -70.457314)
		(width 0.089408)
		(layer "In9.Cu")
		(net "LPC_LAD0_IO0_R")
	)
	(segment
		(start 366.235234 -104.221026)
		(end 366.513364 -104.499156)
		(width 0.1143)
		(layer "F.Cu")
		(net "CLK_100M_BMC_PE_R_DP")
	)
	(segment
		(start 368.845592 -104.635046)
		(end 369.007644 -104.635046)
		(width 0.1143)
		(layer "F.Cu")
		(net "CLK_100M_BMC_PE_R_DP")
	)
	(segment
		(start 411.503622 -46.825154)
		(end 411.503622 -46.626018)
		(width 0.1143)
		(layer "F.Cu")
		(net "CLK_100M_BMC_PE_R_DP")
	)
	(segment
		(start 365.94034 -104.221026)
		(end 366.235234 -104.221026)
		(width 0.1143)
		(layer "F.Cu")
		(net "CLK_100M_BMC_PE_R_DP")
	)
	(segment
		(start 411.434026 -47.056802)
		(end 411.353 -46.975776)
		(width 0.1143)
		(layer "F.Cu")
		(net "CLK_100M_BMC_PE_R_DP")
	)
	(segment
		(start 411.137354 -47.682404)
		(end 411.434026 -47.385732)
		(width 0.1143)
		(layer "F.Cu")
		(net "CLK_100M_BMC_PE_R_DP")
	)
	(segment
		(start 413.898842 -43.316906)
		(end 414.290256 -42.534586)
		(width 0.1143)
		(layer "F.Cu")
		(net "CLK_100M_BMC_PE_R_DP")
	)
	(segment
		(start 368.1349 -104.499156)
		(end 368.709702 -104.499156)
		(width 0.1143)
		(layer "F.Cu")
		(net "CLK_100M_BMC_PE_R_DP")
	)
	(segment
		(start 365.712502 -103.993188)
		(end 365.94034 -104.221026)
		(width 0.1143)
		(layer "F.Cu")
		(net "CLK_100M_BMC_PE_R_DP")
	)
	(segment
		(start 413.898842 -44.230798)
		(end 413.898842 -43.316906)
		(width 0.1143)
		(layer "F.Cu")
		(net "CLK_100M_BMC_PE_R_DP")
	)
	(segment
		(start 411.503622 -46.626018)
		(end 413.898842 -44.230798)
		(width 0.1143)
		(layer "F.Cu")
		(net "CLK_100M_BMC_PE_R_DP")
	)
	(segment
		(start 366.513364 -104.499156)
		(end 368.1349 -104.499156)
		(width 0.1143)
		(layer "F.Cu")
		(net "CLK_100M_BMC_PE_R_DP")
	)
	(segment
		(start 368.709702 -104.499156)
		(end 368.845592 -104.635046)
		(width 0.1143)
		(layer "F.Cu")
		(net "CLK_100M_BMC_PE_R_DP")
	)
	(segment
		(start 411.353 -46.975776)
		(end 411.503622 -46.825154)
		(width 0.1143)
		(layer "F.Cu")
		(net "CLK_100M_BMC_PE_R_DP")
	)
	(segment
		(start 411.434026 -47.385732)
		(end 411.434026 -47.056802)
		(width 0.1143)
		(layer "F.Cu")
		(net "CLK_100M_BMC_PE_R_DP")
	)
	(segment
		(start 411.130242 -47.682404)
		(end 411.137354 -47.682404)
		(width 0.1143)
		(layer "F.Cu")
		(net "CLK_100M_BMC_PE_R_DP")
	)
	(segment
		(start 369.007644 -104.635046)
		(end 369.333526 -104.309164)
		(width 0.1143)
		(layer "F.Cu")
		(net "CLK_100M_BMC_PE_R_DP")
	)
	(via
		(at 368.1349 -104.499156)
		(size 0.508)
		(drill 0.254)
		(layers "F.Cu" "B.Cu")
		(net "CLK_100M_BMC_PE_R_DP")
	)
	(via
		(at 411.353 -46.975776)
		(size 0.508)
		(drill 0.254)
		(layers "F.Cu" "B.Cu")
		(net "CLK_100M_BMC_PE_R_DP")
	)
	(via
		(at 408.126438 -16.497046)
		(size 0.508)
		(drill 0.254)
		(layers "F.Cu" "B.Cu")
		(net "CLK_100M_BMC_PE_R_DP")
	)
	(via
		(at 365.712502 -103.993188)
		(size 0.508)
		(drill 0.254)
		(layers "F.Cu" "B.Cu")
		(net "CLK_100M_BMC_PE_R_DP")
	)
	(segment
		(start 403.36851 -15.8369)
		(end 401.593304 -16.198088)
		(width 0.1143)
		(layer "In2.Cu")
		(net "CLK_100M_BMC_PE_R_DP")
	)
	(segment
		(start 398.676368 -16.547592)
		(end 395.013688 -15.769844)
		(width 0.1143)
		(layer "In2.Cu")
		(net "CLK_100M_BMC_PE_R_DP")
	)
	(segment
		(start 408.126438 -16.497046)
		(end 407.895552 -16.26616)
		(width 0.1143)
		(layer "In2.Cu")
		(net "CLK_100M_BMC_PE_R_DP")
	)
	(segment
		(start 375.245884 -19.717512)
		(end 374.956578 -19.924522)
		(width 0.1143)
		(layer "In2.Cu")
		(net "CLK_100M_BMC_PE_R_DP")
	)
	(segment
		(start 393.221972 -16.3195)
		(end 393.026138 -16.192246)
		(width 0.1143)
		(layer "In2.Cu")
		(net "CLK_100M_BMC_PE_R_DP")
	)
	(segment
		(start 360.855768 -85.60181)
		(end 360.985054 -85.79612)
		(width 0.1143)
		(layer "In2.Cu")
		(net "CLK_100M_BMC_PE_R_DP")
	)
	(segment
		(start 365.482632 -104.223058)
		(end 365.712502 -103.993188)
		(width 0.1143)
		(layer "In2.Cu")
		(net "CLK_100M_BMC_PE_R_DP")
	)
	(segment
		(start 388.85495 -15.97406)
		(end 376.939556 -18.505424)
		(width 0.1143)
		(layer "In2.Cu")
		(net "CLK_100M_BMC_PE_R_DP")
	)
	(segment
		(start 375.476262 -19.755866)
		(end 375.245884 -19.717512)
		(width 0.1143)
		(layer "In2.Cu")
		(net "CLK_100M_BMC_PE_R_DP")
	)
	(segment
		(start 406.818846 -16.4465)
		(end 406.364948 -16.4465)
		(width 0.1143)
		(layer "In2.Cu")
		(net "CLK_100M_BMC_PE_R_DP")
	)
	(segment
		(start 364.7567 -103.873554)
		(end 365.106204 -104.223058)
		(width 0.1143)
		(layer "In2.Cu")
		(net "CLK_100M_BMC_PE_R_DP")
	)
	(segment
		(start 365.469424 -47.627286)
		(end 364.856014 -50.694082)
		(width 0.1143)
		(layer "In2.Cu")
		(net "CLK_100M_BMC_PE_R_DP")
	)
	(segment
		(start 361.3023 -79.009494)
		(end 361.08386 -80.03921)
		(width 0.1143)
		(layer "In2.Cu")
		(net "CLK_100M_BMC_PE_R_DP")
	)
	(segment
		(start 361.509818 -64.872108)
		(end 360.167174 -65.850262)
		(width 0.1143)
		(layer "In2.Cu")
		(net "CLK_100M_BMC_PE_R_DP")
	)
	(segment
		(start 376.61215 -18.942812)
		(end 376.323098 -19.149568)
		(width 0.1143)
		(layer "In2.Cu")
		(net "CLK_100M_BMC_PE_R_DP")
	)
	(segment
		(start 395.013688 -15.769844)
		(end 393.684506 -16.052292)
		(width 0.1143)
		(layer "In2.Cu")
		(net "CLK_100M_BMC_PE_R_DP")
	)
	(segment
		(start 362.508038 -60.16117)
		(end 361.509818 -64.872108)
		(width 0.1143)
		(layer "In2.Cu")
		(net "CLK_100M_BMC_PE_R_DP")
	)
	(segment
		(start 392.690604 -16.26362)
		(end 392.563604 -16.459454)
		(width 0.1143)
		(layer "In2.Cu")
		(net "CLK_100M_BMC_PE_R_DP")
	)
	(segment
		(start 376.323098 -19.149568)
		(end 376.09272 -19.111468)
		(width 0.1143)
		(layer "In2.Cu")
		(net "CLK_100M_BMC_PE_R_DP")
	)
	(segment
		(start 407.895552 -16.26616)
		(end 406.999186 -16.26616)
		(width 0.1143)
		(layer "In2.Cu")
		(net "CLK_100M_BMC_PE_R_DP")
	)
	(segment
		(start 360.829352 -89.454482)
		(end 361.71124 -90.776552)
		(width 0.1143)
		(layer "In2.Cu")
		(net "CLK_100M_BMC_PE_R_DP")
	)
	(segment
		(start 393.684506 -16.052292)
		(end 393.557252 -16.248126)
		(width 0.1143)
		(layer "In2.Cu")
		(net "CLK_100M_BMC_PE_R_DP")
	)
	(segment
		(start 361.254294 -83.609434)
		(end 361.38358 -83.803744)
		(width 0.1143)
		(layer "In2.Cu")
		(net "CLK_100M_BMC_PE_R_DP")
	)
	(segment
		(start 406.364948 -16.4465)
		(end 403.36851 -15.8369)
		(width 0.1143)
		(layer "In2.Cu")
		(net "CLK_100M_BMC_PE_R_DP")
	)
	(segment
		(start 376.650504 -18.712434)
		(end 376.61215 -18.942812)
		(width 0.1143)
		(layer "In2.Cu")
		(net "CLK_100M_BMC_PE_R_DP")
	)
	(segment
		(start 360.985054 -85.79612)
		(end 360.917998 -86.132162)
		(width 0.1143)
		(layer "In2.Cu")
		(net "CLK_100M_BMC_PE_R_DP")
	)
	(segment
		(start 364.7567 -100.978716)
		(end 364.7567 -103.873554)
		(width 0.1143)
		(layer "In2.Cu")
		(net "CLK_100M_BMC_PE_R_DP")
	)
	(segment
		(start 361.054904 -84.605622)
		(end 361.184444 -84.799932)
		(width 0.1143)
		(layer "In2.Cu")
		(net "CLK_100M_BMC_PE_R_DP")
	)
	(segment
		(start 364.918244 -51.224434)
		(end 364.723934 -51.353974)
		(width 0.1143)
		(layer "In2.Cu")
		(net "CLK_100M_BMC_PE_R_DP")
	)
	(segment
		(start 361.71124 -90.776552)
		(end 363.814868 -92.179902)
		(width 0.1143)
		(layer "In2.Cu")
		(net "CLK_100M_BMC_PE_R_DP")
	)
	(segment
		(start 363.814868 -92.179902)
		(end 364.737904 -95.037656)
		(width 0.1143)
		(layer "In2.Cu")
		(net "CLK_100M_BMC_PE_R_DP")
	)
	(segment
		(start 360.524552 -87.25789)
		(end 360.457242 -87.594186)
		(width 0.1143)
		(layer "In2.Cu")
		(net "CLK_100M_BMC_PE_R_DP")
	)
	(segment
		(start 364.968282 -53.24983)
		(end 365.190786 -53.584348)
		(width 0.1143)
		(layer "In2.Cu")
		(net "CLK_100M_BMC_PE_R_DP")
	)
	(segment
		(start 364.985554 -50.888392)
		(end 364.918244 -51.224434)
		(width 0.1143)
		(layer "In2.Cu")
		(net "CLK_100M_BMC_PE_R_DP")
	)
	(segment
		(start 376.09272 -19.111468)
		(end 375.803414 -19.318478)
		(width 0.1143)
		(layer "In2.Cu")
		(net "CLK_100M_BMC_PE_R_DP")
	)
	(segment
		(start 361.53344 -82.21345)
		(end 361.254294 -83.609434)
		(width 0.1143)
		(layer "In2.Cu")
		(net "CLK_100M_BMC_PE_R_DP")
	)
	(segment
		(start 361.184444 -84.799932)
		(end 361.117388 -85.135974)
		(width 0.1143)
		(layer "In2.Cu")
		(net "CLK_100M_BMC_PE_R_DP")
	)
	(segment
		(start 364.961424 -46.015656)
		(end 365.469424 -47.627286)
		(width 0.1143)
		(layer "In2.Cu")
		(net "CLK_100M_BMC_PE_R_DP")
	)
	(segment
		(start 360.457242 -87.594186)
		(end 360.524552 -87.930482)
		(width 0.1143)
		(layer "In2.Cu")
		(net "CLK_100M_BMC_PE_R_DP")
	)
	(segment
		(start 364.737904 -95.037656)
		(end 364.449868 -96.393508)
		(width 0.1143)
		(layer "In2.Cu")
		(net "CLK_100M_BMC_PE_R_DP")
	)
	(segment
		(start 368.823748 -31.830264)
		(end 368.030252 -32.408876)
		(width 0.1143)
		(layer "In2.Cu")
		(net "CLK_100M_BMC_PE_R_DP")
	)
	(segment
		(start 360.785918 -86.792308)
		(end 360.718862 -87.12835)
		(width 0.1143)
		(layer "In2.Cu")
		(net "CLK_100M_BMC_PE_R_DP")
	)
	(segment
		(start 364.723934 -51.353974)
		(end 364.656624 -51.69027)
		(width 0.1143)
		(layer "In2.Cu")
		(net "CLK_100M_BMC_PE_R_DP")
	)
	(segment
		(start 361.38358 -83.803744)
		(end 361.316524 -84.139786)
		(width 0.1143)
		(layer "In2.Cu")
		(net "CLK_100M_BMC_PE_R_DP")
	)
	(segment
		(start 364.856014 -50.694082)
		(end 364.985554 -50.888392)
		(width 0.1143)
		(layer "In2.Cu")
		(net "CLK_100M_BMC_PE_R_DP")
	)
	(segment
		(start 360.923078 -85.265514)
		(end 360.855768 -85.60181)
		(width 0.1143)
		(layer "In2.Cu")
		(net "CLK_100M_BMC_PE_R_DP")
	)
	(segment
		(start 375.803414 -19.318478)
		(end 375.765314 -19.548856)
		(width 0.1143)
		(layer "In2.Cu")
		(net "CLK_100M_BMC_PE_R_DP")
	)
	(segment
		(start 369.652296 -27.93365)
		(end 368.823748 -31.830264)
		(width 0.1143)
		(layer "In2.Cu")
		(net "CLK_100M_BMC_PE_R_DP")
	)
	(segment
		(start 367.093754 -36.812474)
		(end 367.371884 -37.878004)
		(width 0.1143)
		(layer "In2.Cu")
		(net "CLK_100M_BMC_PE_R_DP")
	)
	(segment
		(start 392.563604 -16.459454)
		(end 392.22807 -16.530574)
		(width 0.1143)
		(layer "In2.Cu")
		(net "CLK_100M_BMC_PE_R_DP")
	)
	(segment
		(start 364.968028 -53.24983)
		(end 364.968282 -53.24983)
		(width 0.1143)
		(layer "In2.Cu")
		(net "CLK_100M_BMC_PE_R_DP")
	)
	(segment
		(start 401.593304 -16.198088)
		(end 400.958812 -16.062706)
		(width 0.1143)
		(layer "In2.Cu")
		(net "CLK_100M_BMC_PE_R_DP")
	)
	(segment
		(start 361.117388 -85.135974)
		(end 360.923078 -85.265514)
		(width 0.1143)
		(layer "In2.Cu")
		(net "CLK_100M_BMC_PE_R_DP")
	)
	(segment
		(start 368.030252 -32.408876)
		(end 367.093754 -36.812474)
		(width 0.1143)
		(layer "In2.Cu")
		(net "CLK_100M_BMC_PE_R_DP")
	)
	(segment
		(start 360.656378 -86.597998)
		(end 360.785918 -86.792308)
		(width 0.1143)
		(layer "In2.Cu")
		(net "CLK_100M_BMC_PE_R_DP")
	)
	(segment
		(start 364.449868 -96.393508)
		(end 364.740698 -97.76333)
		(width 0.1143)
		(layer "In2.Cu")
		(net "CLK_100M_BMC_PE_R_DP")
	)
	(segment
		(start 360.718862 -88.060022)
		(end 360.785918 -88.396064)
		(width 0.1143)
		(layer "In2.Cu")
		(net "CLK_100M_BMC_PE_R_DP")
	)
	(segment
		(start 392.22807 -16.530574)
		(end 392.032236 -16.403574)
		(width 0.1143)
		(layer "In2.Cu")
		(net "CLK_100M_BMC_PE_R_DP")
	)
	(segment
		(start 375.765314 -19.548856)
		(end 375.476262 -19.755866)
		(width 0.1143)
		(layer "In2.Cu")
		(net "CLK_100M_BMC_PE_R_DP")
	)
	(segment
		(start 360.917998 -86.132162)
		(end 360.723688 -86.261702)
		(width 0.1143)
		(layer "In2.Cu")
		(net "CLK_100M_BMC_PE_R_DP")
	)
	(segment
		(start 360.718862 -87.12835)
		(end 360.524552 -87.25789)
		(width 0.1143)
		(layer "In2.Cu")
		(net "CLK_100M_BMC_PE_R_DP")
	)
	(segment
		(start 360.524552 -87.930482)
		(end 360.718862 -88.060022)
		(width 0.1143)
		(layer "In2.Cu")
		(net "CLK_100M_BMC_PE_R_DP")
	)
	(segment
		(start 360.167174 -65.850262)
		(end 359.526332 -68.51777)
		(width 0.1143)
		(layer "In2.Cu")
		(net "CLK_100M_BMC_PE_R_DP")
	)
	(segment
		(start 361.122214 -84.269326)
		(end 361.054904 -84.605622)
		(width 0.1143)
		(layer "In2.Cu")
		(net "CLK_100M_BMC_PE_R_DP")
	)
	(segment
		(start 365.581692 -55.5498)
		(end 362.508038 -60.16117)
		(width 0.1143)
		(layer "In2.Cu")
		(net "CLK_100M_BMC_PE_R_DP")
	)
	(segment
		(start 391.454894 -16.526256)
		(end 388.85495 -15.97406)
		(width 0.1143)
		(layer "In2.Cu")
		(net "CLK_100M_BMC_PE_R_DP")
	)
	(segment
		(start 376.939556 -18.505424)
		(end 376.650504 -18.712434)
		(width 0.1143)
		(layer "In2.Cu")
		(net "CLK_100M_BMC_PE_R_DP")
	)
	(segment
		(start 364.656624 -51.69027)
		(end 364.968028 -53.24983)
		(width 0.1143)
		(layer "In2.Cu")
		(net "CLK_100M_BMC_PE_R_DP")
	)
	(segment
		(start 361.3023 -76.898754)
		(end 361.3023 -79.009494)
		(width 0.1143)
		(layer "In2.Cu")
		(net "CLK_100M_BMC_PE_R_DP")
	)
	(segment
		(start 364.740698 -97.76333)
		(end 364.406942 -99.336352)
		(width 0.1143)
		(layer "In2.Cu")
		(net "CLK_100M_BMC_PE_R_DP")
	)
	(segment
		(start 392.032236 -16.403574)
		(end 391.454894 -16.526256)
		(width 0.1143)
		(layer "In2.Cu")
		(net "CLK_100M_BMC_PE_R_DP")
	)
	(segment
		(start 361.08386 -80.03921)
		(end 361.53344 -82.21345)
		(width 0.1143)
		(layer "In2.Cu")
		(net "CLK_100M_BMC_PE_R_DP")
	)
	(segment
		(start 360.785918 -88.396064)
		(end 360.656632 -88.590374)
		(width 0.1143)
		(layer "In2.Cu")
		(net "CLK_100M_BMC_PE_R_DP")
	)
	(segment
		(start 365.190786 -53.584348)
		(end 365.581692 -55.5498)
		(width 0.1143)
		(layer "In2.Cu")
		(net "CLK_100M_BMC_PE_R_DP")
	)
	(segment
		(start 360.723688 -86.261702)
		(end 360.656378 -86.597998)
		(width 0.1143)
		(layer "In2.Cu")
		(net "CLK_100M_BMC_PE_R_DP")
	)
	(segment
		(start 373.467884 -20.990052)
		(end 372.92153 -23.560024)
		(width 0.1143)
		(layer "In2.Cu")
		(net "CLK_100M_BMC_PE_R_DP")
	)
	(segment
		(start 365.273844 -44.45508)
		(end 364.961424 -46.015656)
		(width 0.1143)
		(layer "In2.Cu")
		(net "CLK_100M_BMC_PE_R_DP")
	)
	(segment
		(start 367.371884 -37.878004)
		(end 366.51565 -42.592498)
		(width 0.1143)
		(layer "In2.Cu")
		(net "CLK_100M_BMC_PE_R_DP")
	)
	(segment
		(start 374.918478 -20.1549)
		(end 374.629426 -20.36191)
		(width 0.1143)
		(layer "In2.Cu")
		(net "CLK_100M_BMC_PE_R_DP")
	)
	(segment
		(start 359.526332 -68.51777)
		(end 361.3023 -76.898754)
		(width 0.1143)
		(layer "In2.Cu")
		(net "CLK_100M_BMC_PE_R_DP")
	)
	(segment
		(start 366.51565 -42.592498)
		(end 365.273844 -44.45508)
		(width 0.1143)
		(layer "In2.Cu")
		(net "CLK_100M_BMC_PE_R_DP")
	)
	(segment
		(start 374.399048 -20.32381)
		(end 373.467884 -20.990052)
		(width 0.1143)
		(layer "In2.Cu")
		(net "CLK_100M_BMC_PE_R_DP")
	)
	(segment
		(start 374.956578 -19.924522)
		(end 374.918478 -20.1549)
		(width 0.1143)
		(layer "In2.Cu")
		(net "CLK_100M_BMC_PE_R_DP")
	)
	(segment
		(start 374.629426 -20.36191)
		(end 374.399048 -20.32381)
		(width 0.1143)
		(layer "In2.Cu")
		(net "CLK_100M_BMC_PE_R_DP")
	)
	(segment
		(start 393.557252 -16.248126)
		(end 393.221972 -16.3195)
		(width 0.1143)
		(layer "In2.Cu")
		(net "CLK_100M_BMC_PE_R_DP")
	)
	(segment
		(start 406.999186 -16.26616)
		(end 406.818846 -16.4465)
		(width 0.1143)
		(layer "In2.Cu")
		(net "CLK_100M_BMC_PE_R_DP")
	)
	(segment
		(start 360.656632 -88.590374)
		(end 360.829352 -89.454482)
		(width 0.1143)
		(layer "In2.Cu")
		(net "CLK_100M_BMC_PE_R_DP")
	)
	(segment
		(start 361.316524 -84.139786)
		(end 361.122214 -84.269326)
		(width 0.1143)
		(layer "In2.Cu")
		(net "CLK_100M_BMC_PE_R_DP")
	)
	(segment
		(start 364.406942 -99.336352)
		(end 364.7567 -100.978716)
		(width 0.1143)
		(layer "In2.Cu")
		(net "CLK_100M_BMC_PE_R_DP")
	)
	(segment
		(start 393.026138 -16.192246)
		(end 392.690604 -16.26362)
		(width 0.1143)
		(layer "In2.Cu")
		(net "CLK_100M_BMC_PE_R_DP")
	)
	(segment
		(start 400.958812 -16.062706)
		(end 398.676368 -16.547592)
		(width 0.1143)
		(layer "In2.Cu")
		(net "CLK_100M_BMC_PE_R_DP")
	)
	(segment
		(start 372.92153 -23.560024)
		(end 369.652296 -27.93365)
		(width 0.1143)
		(layer "In2.Cu")
		(net "CLK_100M_BMC_PE_R_DP")
	)
	(segment
		(start 365.106204 -104.223058)
		(end 365.482632 -104.223058)
		(width 0.1143)
		(layer "In2.Cu")
		(net "CLK_100M_BMC_PE_R_DP")
	)
	(segment
		(start 402.63699 -36.400232)
		(end 402.63699 -36.044632)
		(width 0.1143)
		(layer "In11.Cu")
		(net "CLK_100M_BMC_PE_R_DP")
	)
	(segment
		(start 402.47189 -30.598872)
		(end 402.47189 -30.255972)
		(width 0.1143)
		(layer "In11.Cu")
		(net "CLK_100M_BMC_PE_R_DP")
	)
	(segment
		(start 402.63699 -37.086032)
		(end 402.47189 -36.920932)
		(width 0.1143)
		(layer "In11.Cu")
		(net "CLK_100M_BMC_PE_R_DP")
	)
	(segment
		(start 407.79192 -46.425866)
		(end 407.79192 -45.52569)
		(width 0.1143)
		(layer "In11.Cu")
		(net "CLK_100M_BMC_PE_R_DP")
	)
	(segment
		(start 402.47189 -31.614872)
		(end 402.47189 -31.271972)
		(width 0.1143)
		(layer "In11.Cu")
		(net "CLK_100M_BMC_PE_R_DP")
	)
	(segment
		(start 402.3106 -23.7617)
		(end 402.1455 -23.5966)
		(width 0.1143)
		(layer "In11.Cu")
		(net "CLK_100M_BMC_PE_R_DP")
	)
	(segment
		(start 411.426406 -47.546006)
		(end 408.401266 -47.546006)
		(width 0.1143)
		(layer "In11.Cu")
		(net "CLK_100M_BMC_PE_R_DP")
	)
	(segment
		(start 403.5679 -42.709846)
		(end 403.5679 -41.725596)
		(width 0.1143)
		(layer "In11.Cu")
		(net "CLK_100M_BMC_PE_R_DP")
	)
	(segment
		(start 401.447 -28.168346)
		(end 401.447 -27.610054)
		(width 0.1143)
		(layer "In11.Cu")
		(net "CLK_100M_BMC_PE_R_DP")
	)
	(segment
		(start 402.47189 -36.920932)
		(end 402.47189 -36.565332)
		(width 0.1143)
		(layer "In11.Cu")
		(net "CLK_100M_BMC_PE_R_DP")
	)
	(segment
		(start 407.96972 -47.11446)
		(end 407.96972 -46.603666)
		(width 0.1143)
		(layer "In11.Cu")
		(net "CLK_100M_BMC_PE_R_DP")
	)
	(segment
		(start 411.534356 -47.157132)
		(end 411.534356 -47.438056)
		(width 0.1143)
		(layer "In11.Cu")
		(net "CLK_100M_BMC_PE_R_DP")
	)
	(segment
		(start 402.3106 -24.7777)
		(end 402.1455 -24.6126)
		(width 0.1143)
		(layer "In11.Cu")
		(net "CLK_100M_BMC_PE_R_DP")
	)
	(segment
		(start 401.447 -27.610054)
		(end 402.1455 -26.911554)
		(width 0.1143)
		(layer "In11.Cu")
		(net "CLK_100M_BMC_PE_R_DP")
	)
	(segment
		(start 402.934678 -20.32762)
		(end 402.71319 -20.106132)
		(width 0.1143)
		(layer "In11.Cu")
		(net "CLK_100M_BMC_PE_R_DP")
	)
	(segment
		(start 402.947886 -17.10436)
		(end 403.303486 -17.10436)
		(width 0.1143)
		(layer "In11.Cu")
		(net "CLK_100M_BMC_PE_R_DP")
	)
	(segment
		(start 403.5679 -41.725596)
		(end 402.47189 -40.629586)
		(width 0.1143)
		(layer "In11.Cu")
		(net "CLK_100M_BMC_PE_R_DP")
	)
	(segment
		(start 403.468586 -16.93926)
		(end 403.824186 -16.93926)
		(width 0.1143)
		(layer "In11.Cu")
		(net "CLK_100M_BMC_PE_R_DP")
	)
	(segment
		(start 407.79192 -45.52569)
		(end 406.89403 -44.6278)
		(width 0.1143)
		(layer "In11.Cu")
		(net "CLK_100M_BMC_PE_R_DP")
	)
	(segment
		(start 411.534356 -47.438056)
		(end 411.426406 -47.546006)
		(width 0.1143)
		(layer "In11.Cu")
		(net "CLK_100M_BMC_PE_R_DP")
	)
	(segment
		(start 402.045678 -18.20291)
		(end 402.045678 -17.383252)
		(width 0.1143)
		(layer "In11.Cu")
		(net "CLK_100M_BMC_PE_R_DP")
	)
	(segment
		(start 403.824186 -16.93926)
		(end 403.989286 -17.10436)
		(width 0.1143)
		(layer "In11.Cu")
		(net "CLK_100M_BMC_PE_R_DP")
	)
	(segment
		(start 402.63699 -33.138872)
		(end 402.63699 -32.795972)
		(width 0.1143)
		(layer "In11.Cu")
		(net "CLK_100M_BMC_PE_R_DP")
	)
	(segment
		(start 406.89403 -44.6278)
		(end 405.485854 -44.6278)
		(width 0.1143)
		(layer "In11.Cu")
		(net "CLK_100M_BMC_PE_R_DP")
	)
	(segment
		(start 402.47189 -29.582872)
		(end 402.47189 -29.193236)
		(width 0.1143)
		(layer "In11.Cu")
		(net "CLK_100M_BMC_PE_R_DP")
	)
	(segment
		(start 406.609296 -16.26616)
		(end 407.895552 -16.26616)
		(width 0.1143)
		(layer "In11.Cu")
		(net "CLK_100M_BMC_PE_R_DP")
	)
	(segment
		(start 402.47189 -32.287972)
		(end 402.63699 -32.122872)
		(width 0.1143)
		(layer "In11.Cu")
		(net "CLK_100M_BMC_PE_R_DP")
	)
	(segment
		(start 404.344886 -17.10436)
		(end 404.509986 -16.93926)
		(width 0.1143)
		(layer "In11.Cu")
		(net "CLK_100M_BMC_PE_R_DP")
	)
	(segment
		(start 402.63699 -30.090872)
		(end 402.63699 -29.747972)
		(width 0.1143)
		(layer "In11.Cu")
		(net "CLK_100M_BMC_PE_R_DP")
	)
	(segment
		(start 402.47189 -32.630872)
		(end 402.47189 -32.287972)
		(width 0.1143)
		(layer "In11.Cu")
		(net "CLK_100M_BMC_PE_R_DP")
	)
	(segment
		(start 402.47189 -40.629586)
		(end 402.47189 -37.606732)
		(width 0.1143)
		(layer "In11.Cu")
		(net "CLK_100M_BMC_PE_R_DP")
	)
	(segment
		(start 403.989286 -17.10436)
		(end 404.344886 -17.10436)
		(width 0.1143)
		(layer "In11.Cu")
		(net "CLK_100M_BMC_PE_R_DP")
	)
	(segment
		(start 402.71319 -18.870422)
		(end 402.045678 -18.20291)
		(width 0.1143)
		(layer "In11.Cu")
		(net "CLK_100M_BMC_PE_R_DP")
	)
	(segment
		(start 402.63699 -32.795972)
		(end 402.47189 -32.630872)
		(width 0.1143)
		(layer "In11.Cu")
		(net "CLK_100M_BMC_PE_R_DP")
	)
	(segment
		(start 402.1455 -24.2697)
		(end 402.3106 -24.1046)
		(width 0.1143)
		(layer "In11.Cu")
		(net "CLK_100M_BMC_PE_R_DP")
	)
	(segment
		(start 402.63699 -31.106872)
		(end 402.63699 -30.763972)
		(width 0.1143)
		(layer "In11.Cu")
		(net "CLK_100M_BMC_PE_R_DP")
	)
	(segment
		(start 401.772374 -21.956014)
		(end 402.223224 -21.505164)
		(width 0.1143)
		(layer "In11.Cu")
		(net "CLK_100M_BMC_PE_R_DP")
	)
	(segment
		(start 402.63699 -30.763972)
		(end 402.47189 -30.598872)
		(width 0.1143)
		(layer "In11.Cu")
		(net "CLK_100M_BMC_PE_R_DP")
	)
	(segment
		(start 402.045678 -17.383252)
		(end 402.48967 -16.93926)
		(width 0.1143)
		(layer "In11.Cu")
		(net "CLK_100M_BMC_PE_R_DP")
	)
	(segment
		(start 402.47189 -35.879532)
		(end 402.47189 -35.523932)
		(width 0.1143)
		(layer "In11.Cu")
		(net "CLK_100M_BMC_PE_R_DP")
	)
	(segment
		(start 402.63699 -35.003232)
		(end 402.47189 -34.838132)
		(width 0.1143)
		(layer "In11.Cu")
		(net "CLK_100M_BMC_PE_R_DP")
	)
	(segment
		(start 402.48967 -16.93926)
		(end 402.782786 -16.93926)
		(width 0.1143)
		(layer "In11.Cu")
		(net "CLK_100M_BMC_PE_R_DP")
	)
	(segment
		(start 402.71319 -20.106132)
		(end 402.71319 -18.870422)
		(width 0.1143)
		(layer "In11.Cu")
		(net "CLK_100M_BMC_PE_R_DP")
	)
	(segment
		(start 401.772374 -22.880574)
		(end 401.772374 -21.956014)
		(width 0.1143)
		(layer "In11.Cu")
		(net "CLK_100M_BMC_PE_R_DP")
	)
	(segment
		(start 402.47189 -33.303972)
		(end 402.63699 -33.138872)
		(width 0.1143)
		(layer "In11.Cu")
		(net "CLK_100M_BMC_PE_R_DP")
	)
	(segment
		(start 402.47189 -35.523932)
		(end 402.63699 -35.358832)
		(width 0.1143)
		(layer "In11.Cu")
		(net "CLK_100M_BMC_PE_R_DP")
	)
	(segment
		(start 402.63699 -37.441632)
		(end 402.63699 -37.086032)
		(width 0.1143)
		(layer "In11.Cu")
		(net "CLK_100M_BMC_PE_R_DP")
	)
	(segment
		(start 402.1455 -25.2857)
		(end 402.3106 -25.1206)
		(width 0.1143)
		(layer "In11.Cu")
		(net "CLK_100M_BMC_PE_R_DP")
	)
	(segment
		(start 402.47189 -37.606732)
		(end 402.63699 -37.441632)
		(width 0.1143)
		(layer "In11.Cu")
		(net "CLK_100M_BMC_PE_R_DP")
	)
	(segment
		(start 402.1455 -24.6126)
		(end 402.1455 -24.2697)
		(width 0.1143)
		(layer "In11.Cu")
		(net "CLK_100M_BMC_PE_R_DP")
	)
	(segment
		(start 402.1455 -23.5966)
		(end 402.1455 -23.2537)
		(width 0.1143)
		(layer "In11.Cu")
		(net "CLK_100M_BMC_PE_R_DP")
	)
	(segment
		(start 408.401266 -47.546006)
		(end 407.96972 -47.11446)
		(width 0.1143)
		(layer "In11.Cu")
		(net "CLK_100M_BMC_PE_R_DP")
	)
	(segment
		(start 402.63699 -36.044632)
		(end 402.47189 -35.879532)
		(width 0.1143)
		(layer "In11.Cu")
		(net "CLK_100M_BMC_PE_R_DP")
	)
	(segment
		(start 402.63699 -31.779972)
		(end 402.47189 -31.614872)
		(width 0.1143)
		(layer "In11.Cu")
		(net "CLK_100M_BMC_PE_R_DP")
	)
	(segment
		(start 402.47189 -29.193236)
		(end 401.447 -28.168346)
		(width 0.1143)
		(layer "In11.Cu")
		(net "CLK_100M_BMC_PE_R_DP")
	)
	(segment
		(start 402.47189 -36.565332)
		(end 402.63699 -36.400232)
		(width 0.1143)
		(layer "In11.Cu")
		(net "CLK_100M_BMC_PE_R_DP")
	)
	(segment
		(start 402.47189 -30.255972)
		(end 402.63699 -30.090872)
		(width 0.1143)
		(layer "In11.Cu")
		(net "CLK_100M_BMC_PE_R_DP")
	)
	(segment
		(start 402.63699 -35.358832)
		(end 402.63699 -35.003232)
		(width 0.1143)
		(layer "In11.Cu")
		(net "CLK_100M_BMC_PE_R_DP")
	)
	(segment
		(start 402.1455 -23.2537)
		(end 401.772374 -22.880574)
		(width 0.1143)
		(layer "In11.Cu")
		(net "CLK_100M_BMC_PE_R_DP")
	)
	(segment
		(start 402.934678 -20.967954)
		(end 402.934678 -20.32762)
		(width 0.1143)
		(layer "In11.Cu")
		(net "CLK_100M_BMC_PE_R_DP")
	)
	(segment
		(start 402.63699 -29.747972)
		(end 402.47189 -29.582872)
		(width 0.1143)
		(layer "In11.Cu")
		(net "CLK_100M_BMC_PE_R_DP")
	)
	(segment
		(start 407.895552 -16.26616)
		(end 408.126438 -16.497046)
		(width 0.1143)
		(layer "In11.Cu")
		(net "CLK_100M_BMC_PE_R_DP")
	)
	(segment
		(start 402.782786 -16.93926)
		(end 402.947886 -17.10436)
		(width 0.1143)
		(layer "In11.Cu")
		(net "CLK_100M_BMC_PE_R_DP")
	)
	(segment
		(start 402.63699 -32.122872)
		(end 402.63699 -31.779972)
		(width 0.1143)
		(layer "In11.Cu")
		(net "CLK_100M_BMC_PE_R_DP")
	)
	(segment
		(start 402.3106 -24.1046)
		(end 402.3106 -23.7617)
		(width 0.1143)
		(layer "In11.Cu")
		(net "CLK_100M_BMC_PE_R_DP")
	)
	(segment
		(start 402.47189 -34.838132)
		(end 402.47189 -33.303972)
		(width 0.1143)
		(layer "In11.Cu")
		(net "CLK_100M_BMC_PE_R_DP")
	)
	(segment
		(start 402.397468 -21.505164)
		(end 402.934678 -20.967954)
		(width 0.1143)
		(layer "In11.Cu")
		(net "CLK_100M_BMC_PE_R_DP")
	)
	(segment
		(start 402.47189 -31.271972)
		(end 402.63699 -31.106872)
		(width 0.1143)
		(layer "In11.Cu")
		(net "CLK_100M_BMC_PE_R_DP")
	)
	(segment
		(start 405.485854 -44.6278)
		(end 403.5679 -42.709846)
		(width 0.1143)
		(layer "In11.Cu")
		(net "CLK_100M_BMC_PE_R_DP")
	)
	(segment
		(start 403.303486 -17.10436)
		(end 403.468586 -16.93926)
		(width 0.1143)
		(layer "In11.Cu")
		(net "CLK_100M_BMC_PE_R_DP")
	)
	(segment
		(start 411.353 -46.975776)
		(end 411.534356 -47.157132)
		(width 0.1143)
		(layer "In11.Cu")
		(net "CLK_100M_BMC_PE_R_DP")
	)
	(segment
		(start 405.936196 -16.93926)
		(end 406.609296 -16.26616)
		(width 0.1143)
		(layer "In11.Cu")
		(net "CLK_100M_BMC_PE_R_DP")
	)
	(segment
		(start 402.3106 -25.1206)
		(end 402.3106 -24.7777)
		(width 0.1143)
		(layer "In11.Cu")
		(net "CLK_100M_BMC_PE_R_DP")
	)
	(segment
		(start 402.223224 -21.505164)
		(end 402.397468 -21.505164)
		(width 0.1143)
		(layer "In11.Cu")
		(net "CLK_100M_BMC_PE_R_DP")
	)
	(segment
		(start 407.96972 -46.603666)
		(end 407.79192 -46.425866)
		(width 0.1143)
		(layer "In11.Cu")
		(net "CLK_100M_BMC_PE_R_DP")
	)
	(segment
		(start 402.1455 -26.911554)
		(end 402.1455 -25.2857)
		(width 0.1143)
		(layer "In11.Cu")
		(net "CLK_100M_BMC_PE_R_DP")
	)
	(segment
		(start 404.509986 -16.93926)
		(end 405.936196 -16.93926)
		(width 0.1143)
		(layer "In11.Cu")
		(net "CLK_100M_BMC_PE_R_DP")
	)
	(segment
		(start 413.250126 -45.22089)
		(end 413.41167 -45.059346)
		(width 0.1143)
		(layer "F.Cu")
		(net "CLK_100M_BMC_PE_R_DN")
	)
	(segment
		(start 411.9118 -47.00524)
		(end 411.744922 -46.838362)
		(width 0.1143)
		(layer "F.Cu")
		(net "CLK_100M_BMC_PE_R_DN")
	)
	(segment
		(start 412.0896 -46.557438)
		(end 412.251398 -46.39564)
		(width 0.1143)
		(layer "F.Cu")
		(net "CLK_100M_BMC_PE_R_DN")
	)
	(segment
		(start 413.74949 -44.897548)
		(end 413.74949 -44.721526)
		(width 0.1143)
		(layer "F.Cu")
		(net "CLK_100M_BMC_PE_R_DN")
	)
	(segment
		(start 366.413288 -104.740456)
		(end 366.9157 -104.740456)
		(width 0.1143)
		(layer "F.Cu")
		(net "CLK_100M_BMC_PE_R_DN")
	)
	(segment
		(start 412.750762 -45.720254)
		(end 412.912306 -45.55871)
		(width 0.1143)
		(layer "F.Cu")
		(net "CLK_100M_BMC_PE_R_DN")
	)
	(segment
		(start 412.912306 -45.55871)
		(end 413.088328 -45.55871)
		(width 0.1143)
		(layer "F.Cu")
		(net "CLK_100M_BMC_PE_R_DN")
	)
	(segment
		(start 414.140142 -43.404536)
		(end 414.209992 -43.334686)
		(width 0.1143)
		(layer "F.Cu")
		(net "CLK_100M_BMC_PE_R_DN")
	)
	(segment
		(start 413.088328 -45.55871)
		(end 413.250126 -45.396912)
		(width 0.1143)
		(layer "F.Cu")
		(net "CLK_100M_BMC_PE_R_DN")
	)
	(segment
		(start 414.264602 -43.776646)
		(end 414.140142 -43.652186)
		(width 0.1143)
		(layer "F.Cu")
		(net "CLK_100M_BMC_PE_R_DN")
	)
	(segment
		(start 414.140142 -43.652186)
		(end 414.140142 -43.404536)
		(width 0.1143)
		(layer "F.Cu")
		(net "CLK_100M_BMC_PE_R_DN")
	)
	(segment
		(start 413.74949 -44.721526)
		(end 414.140142 -44.330874)
		(width 0.1143)
		(layer "F.Cu")
		(net "CLK_100M_BMC_PE_R_DN")
	)
	(segment
		(start 413.587692 -45.059346)
		(end 413.74949 -44.897548)
		(width 0.1143)
		(layer "F.Cu")
		(net "CLK_100M_BMC_PE_R_DN")
	)
	(segment
		(start 413.41167 -45.059346)
		(end 413.587692 -45.059346)
		(width 0.1143)
		(layer "F.Cu")
		(net "CLK_100M_BMC_PE_R_DN")
	)
	(segment
		(start 411.744922 -46.838362)
		(end 411.744922 -46.726094)
		(width 0.1143)
		(layer "F.Cu")
		(net "CLK_100M_BMC_PE_R_DN")
	)
	(segment
		(start 412.251398 -46.39564)
		(end 412.251398 -46.219618)
		(width 0.1143)
		(layer "F.Cu")
		(net "CLK_100M_BMC_PE_R_DN")
	)
	(segment
		(start 366.135158 -104.462326)
		(end 366.413288 -104.740456)
		(width 0.1143)
		(layer "F.Cu")
		(net "CLK_100M_BMC_PE_R_DN")
	)
	(segment
		(start 411.913578 -46.557438)
		(end 412.0896 -46.557438)
		(width 0.1143)
		(layer "F.Cu")
		(net "CLK_100M_BMC_PE_R_DN")
	)
	(segment
		(start 412.588964 -46.058074)
		(end 412.750762 -45.896276)
		(width 0.1143)
		(layer "F.Cu")
		(net "CLK_100M_BMC_PE_R_DN")
	)
	(segment
		(start 414.140142 -44.12996)
		(end 414.264602 -44.0055)
		(width 0.1143)
		(layer "F.Cu")
		(net "CLK_100M_BMC_PE_R_DN")
	)
	(segment
		(start 368.745516 -104.876346)
		(end 369.011708 -104.876346)
		(width 0.1143)
		(layer "F.Cu")
		(net "CLK_100M_BMC_PE_R_DN")
	)
	(segment
		(start 365.671354 -104.766364)
		(end 365.975392 -104.462326)
		(width 0.1143)
		(layer "F.Cu")
		(net "CLK_100M_BMC_PE_R_DN")
	)
	(segment
		(start 368.609626 -104.740456)
		(end 368.745516 -104.876346)
		(width 0.1143)
		(layer "F.Cu")
		(net "CLK_100M_BMC_PE_R_DN")
	)
	(segment
		(start 365.975392 -104.462326)
		(end 366.135158 -104.462326)
		(width 0.1143)
		(layer "F.Cu")
		(net "CLK_100M_BMC_PE_R_DN")
	)
	(segment
		(start 412.750762 -45.896276)
		(end 412.750762 -45.720254)
		(width 0.1143)
		(layer "F.Cu")
		(net "CLK_100M_BMC_PE_R_DN")
	)
	(segment
		(start 413.250126 -45.396912)
		(end 413.250126 -45.22089)
		(width 0.1143)
		(layer "F.Cu")
		(net "CLK_100M_BMC_PE_R_DN")
	)
	(segment
		(start 411.713934 -47.504096)
		(end 411.713934 -47.342298)
		(width 0.1143)
		(layer "F.Cu")
		(net "CLK_100M_BMC_PE_R_DN")
	)
	(segment
		(start 414.264602 -44.0055)
		(end 414.264602 -43.776646)
		(width 0.1143)
		(layer "F.Cu")
		(net "CLK_100M_BMC_PE_R_DN")
	)
	(segment
		(start 366.9157 -104.740456)
		(end 368.609626 -104.740456)
		(width 0.1143)
		(layer "F.Cu")
		(net "CLK_100M_BMC_PE_R_DN")
	)
	(segment
		(start 411.744922 -46.726094)
		(end 411.913578 -46.557438)
		(width 0.1143)
		(layer "F.Cu")
		(net "CLK_100M_BMC_PE_R_DN")
	)
	(segment
		(start 412.050992 -47.00524)
		(end 411.9118 -47.00524)
		(width 0.1143)
		(layer "F.Cu")
		(net "CLK_100M_BMC_PE_R_DN")
	)
	(segment
		(start 412.412942 -46.058074)
		(end 412.588964 -46.058074)
		(width 0.1143)
		(layer "F.Cu")
		(net "CLK_100M_BMC_PE_R_DN")
	)
	(segment
		(start 369.011708 -104.876346)
		(end 369.333526 -105.198164)
		(width 0.1143)
		(layer "F.Cu")
		(net "CLK_100M_BMC_PE_R_DN")
	)
	(segment
		(start 411.892242 -47.682404)
		(end 411.713934 -47.504096)
		(width 0.1143)
		(layer "F.Cu")
		(net "CLK_100M_BMC_PE_R_DN")
	)
	(segment
		(start 414.140142 -44.330874)
		(end 414.140142 -44.12996)
		(width 0.1143)
		(layer "F.Cu")
		(net "CLK_100M_BMC_PE_R_DN")
	)
	(segment
		(start 412.251398 -46.219618)
		(end 412.412942 -46.058074)
		(width 0.1143)
		(layer "F.Cu")
		(net "CLK_100M_BMC_PE_R_DN")
	)
	(segment
		(start 414.209992 -43.334686)
		(end 414.290256 -43.334686)
		(width 0.1143)
		(layer "F.Cu")
		(net "CLK_100M_BMC_PE_R_DN")
	)
	(segment
		(start 411.713934 -47.342298)
		(end 412.050992 -47.00524)
		(width 0.1143)
		(layer "F.Cu")
		(net "CLK_100M_BMC_PE_R_DN")
	)
	(via
		(at 366.9157 -104.740456)
		(size 0.508)
		(drill 0.254)
		(layers "F.Cu" "B.Cu")
		(net "CLK_100M_BMC_PE_R_DN")
	)
	(via
		(at 412.050992 -47.00524)
		(size 0.508)
		(drill 0.254)
		(layers "F.Cu" "B.Cu")
		(net "CLK_100M_BMC_PE_R_DN")
	)
	(via
		(at 408.546808 -15.97406)
		(size 0.508)
		(drill 0.254)
		(layers "F.Cu" "B.Cu")
		(net "CLK_100M_BMC_PE_R_DN")
	)
	(via
		(at 365.671354 -104.766364)
		(size 0.508)
		(drill 0.254)
		(layers "F.Cu" "B.Cu")
		(net "CLK_100M_BMC_PE_R_DN")
	)
	(segment
		(start 364.358682 -51.69027)
		(end 365.16818 -47.643542)
		(width 0.1143)
		(layer "In2.Cu")
		(net "CLK_100M_BMC_PE_R_DN")
	)
	(segment
		(start 360.1593 -87.594186)
		(end 361.235244 -82.214466)
		(width 0.1143)
		(layer "In2.Cu")
		(net "CLK_100M_BMC_PE_R_DN")
	)
	(segment
		(start 365.671354 -104.766364)
		(end 365.420148 -104.515158)
		(width 0.1143)
		(layer "In2.Cu")
		(net "CLK_100M_BMC_PE_R_DN")
	)
	(segment
		(start 364.998762 -44.341034)
		(end 366.239044 -42.480738)
		(width 0.1143)
		(layer "In2.Cu")
		(net "CLK_100M_BMC_PE_R_DN")
	)
	(segment
		(start 391.454894 -16.227552)
		(end 395.013688 -15.47114)
		(width 0.1143)
		(layer "In2.Cu")
		(net "CLK_100M_BMC_PE_R_DN")
	)
	(segment
		(start 365.271558 -55.488332)
		(end 364.91545 -53.69814)
		(width 0.1143)
		(layer "In2.Cu")
		(net "CLK_100M_BMC_PE_R_DN")
	)
	(segment
		(start 368.561112 -31.660084)
		(end 369.379754 -27.809952)
		(width 0.1143)
		(layer "In2.Cu")
		(net "CLK_100M_BMC_PE_R_DN")
	)
	(segment
		(start 361.235244 -82.214466)
		(end 360.78541 -80.038448)
		(width 0.1143)
		(layer "In2.Cu")
		(net "CLK_100M_BMC_PE_R_DN")
	)
	(segment
		(start 376.818906 -18.232374)
		(end 388.85495 -15.675356)
		(width 0.1143)
		(layer "In2.Cu")
		(net "CLK_100M_BMC_PE_R_DN")
	)
	(segment
		(start 406.878028 -15.97406)
		(end 408.546808 -15.97406)
		(width 0.1143)
		(layer "In2.Cu")
		(net "CLK_100M_BMC_PE_R_DN")
	)
	(segment
		(start 395.013688 -15.47114)
		(end 398.676368 -16.248888)
		(width 0.1143)
		(layer "In2.Cu")
		(net "CLK_100M_BMC_PE_R_DN")
	)
	(segment
		(start 367.767616 -32.238696)
		(end 368.561112 -31.660084)
		(width 0.1143)
		(layer "In2.Cu")
		(net "CLK_100M_BMC_PE_R_DN")
	)
	(segment
		(start 364.985046 -104.515158)
		(end 364.4646 -103.994712)
		(width 0.1143)
		(layer "In2.Cu")
		(net "CLK_100M_BMC_PE_R_DN")
	)
	(segment
		(start 364.151164 -96.393508)
		(end 364.435898 -95.05315)
		(width 0.1143)
		(layer "In2.Cu")
		(net "CLK_100M_BMC_PE_R_DN")
	)
	(segment
		(start 366.793526 -36.819332)
		(end 367.767616 -32.238696)
		(width 0.1143)
		(layer "In2.Cu")
		(net "CLK_100M_BMC_PE_R_DN")
	)
	(segment
		(start 401.594828 -15.899638)
		(end 403.36851 -15.538704)
		(width 0.1143)
		(layer "In2.Cu")
		(net "CLK_100M_BMC_PE_R_DN")
	)
	(segment
		(start 364.435898 -95.05315)
		(end 363.56798 -92.366592)
		(width 0.1143)
		(layer "In2.Cu")
		(net "CLK_100M_BMC_PE_R_DN")
	)
	(segment
		(start 364.108238 -99.336352)
		(end 364.441994 -97.76333)
		(width 0.1143)
		(layer "In2.Cu")
		(net "CLK_100M_BMC_PE_R_DN")
	)
	(segment
		(start 398.676368 -16.248888)
		(end 400.959066 -15.764002)
		(width 0.1143)
		(layer "In2.Cu")
		(net "CLK_100M_BMC_PE_R_DN")
	)
	(segment
		(start 373.205756 -20.818094)
		(end 376.818906 -18.232374)
		(width 0.1143)
		(layer "In2.Cu")
		(net "CLK_100M_BMC_PE_R_DN")
	)
	(segment
		(start 365.16818 -47.643542)
		(end 364.66018 -46.031912)
		(width 0.1143)
		(layer "In2.Cu")
		(net "CLK_100M_BMC_PE_R_DN")
	)
	(segment
		(start 364.91545 -53.69814)
		(end 364.692946 -53.364384)
		(width 0.1143)
		(layer "In2.Cu")
		(net "CLK_100M_BMC_PE_R_DN")
	)
	(segment
		(start 369.379754 -27.809952)
		(end 372.649242 -23.436072)
		(width 0.1143)
		(layer "In2.Cu")
		(net "CLK_100M_BMC_PE_R_DN")
	)
	(segment
		(start 360.55427 -89.568528)
		(end 360.1593 -87.594186)
		(width 0.1143)
		(layer "In2.Cu")
		(net "CLK_100M_BMC_PE_R_DN")
	)
	(segment
		(start 365.420148 -104.515158)
		(end 364.985046 -104.515158)
		(width 0.1143)
		(layer "In2.Cu")
		(net "CLK_100M_BMC_PE_R_DN")
	)
	(segment
		(start 406.697688 -16.1544)
		(end 406.878028 -15.97406)
		(width 0.1143)
		(layer "In2.Cu")
		(net "CLK_100M_BMC_PE_R_DN")
	)
	(segment
		(start 360.78541 -80.038448)
		(end 361.0102 -78.97876)
		(width 0.1143)
		(layer "In2.Cu")
		(net "CLK_100M_BMC_PE_R_DN")
	)
	(segment
		(start 366.239044 -42.480738)
		(end 367.072672 -37.889434)
		(width 0.1143)
		(layer "In2.Cu")
		(net "CLK_100M_BMC_PE_R_DN")
	)
	(segment
		(start 403.36851 -15.538704)
		(end 406.394412 -16.1544)
		(width 0.1143)
		(layer "In2.Cu")
		(net "CLK_100M_BMC_PE_R_DN")
	)
	(segment
		(start 364.66018 -46.031912)
		(end 364.998762 -44.341034)
		(width 0.1143)
		(layer "In2.Cu")
		(net "CLK_100M_BMC_PE_R_DN")
	)
	(segment
		(start 361.247182 -64.701928)
		(end 362.233718 -60.0456)
		(width 0.1143)
		(layer "In2.Cu")
		(net "CLK_100M_BMC_PE_R_DN")
	)
	(segment
		(start 364.4646 -103.994712)
		(end 364.4646 -101.009704)
		(width 0.1143)
		(layer "In2.Cu")
		(net "CLK_100M_BMC_PE_R_DN")
	)
	(segment
		(start 364.692946 -53.364384)
		(end 364.358682 -51.69027)
		(width 0.1143)
		(layer "In2.Cu")
		(net "CLK_100M_BMC_PE_R_DN")
	)
	(segment
		(start 359.908094 -65.677288)
		(end 361.247182 -64.701928)
		(width 0.1143)
		(layer "In2.Cu")
		(net "CLK_100M_BMC_PE_R_DN")
	)
	(segment
		(start 359.226866 -68.513706)
		(end 359.908094 -65.677288)
		(width 0.1143)
		(layer "In2.Cu")
		(net "CLK_100M_BMC_PE_R_DN")
	)
	(segment
		(start 367.072672 -37.889434)
		(end 366.793526 -36.819332)
		(width 0.1143)
		(layer "In2.Cu")
		(net "CLK_100M_BMC_PE_R_DN")
	)
	(segment
		(start 388.85495 -15.675356)
		(end 391.454894 -16.227552)
		(width 0.1143)
		(layer "In2.Cu")
		(net "CLK_100M_BMC_PE_R_DN")
	)
	(segment
		(start 362.233718 -60.0456)
		(end 365.271558 -55.488332)
		(width 0.1143)
		(layer "In2.Cu")
		(net "CLK_100M_BMC_PE_R_DN")
	)
	(segment
		(start 364.4646 -101.009704)
		(end 364.108238 -99.336352)
		(width 0.1143)
		(layer "In2.Cu")
		(net "CLK_100M_BMC_PE_R_DN")
	)
	(segment
		(start 361.50042 -90.987372)
		(end 360.55427 -89.568528)
		(width 0.1143)
		(layer "In2.Cu")
		(net "CLK_100M_BMC_PE_R_DN")
	)
	(segment
		(start 406.394412 -16.1544)
		(end 406.697688 -16.1544)
		(width 0.1143)
		(layer "In2.Cu")
		(net "CLK_100M_BMC_PE_R_DN")
	)
	(segment
		(start 361.0102 -78.97876)
		(end 361.0102 -76.929488)
		(width 0.1143)
		(layer "In2.Cu")
		(net "CLK_100M_BMC_PE_R_DN")
	)
	(segment
		(start 361.0102 -76.929488)
		(end 359.226866 -68.513706)
		(width 0.1143)
		(layer "In2.Cu")
		(net "CLK_100M_BMC_PE_R_DN")
	)
	(segment
		(start 400.959066 -15.764002)
		(end 401.594828 -15.899638)
		(width 0.1143)
		(layer "In2.Cu")
		(net "CLK_100M_BMC_PE_R_DN")
	)
	(segment
		(start 372.649242 -23.436072)
		(end 373.205756 -20.818094)
		(width 0.1143)
		(layer "In2.Cu")
		(net "CLK_100M_BMC_PE_R_DN")
	)
	(segment
		(start 363.56798 -92.366592)
		(end 361.50042 -90.987372)
		(width 0.1143)
		(layer "In2.Cu")
		(net "CLK_100M_BMC_PE_R_DN")
	)
	(segment
		(start 364.441994 -97.76333)
		(end 364.151164 -96.393508)
		(width 0.1143)
		(layer "In2.Cu")
		(net "CLK_100M_BMC_PE_R_DN")
	)
	(segment
		(start 402.42109 -18.99158)
		(end 401.753578 -18.324068)
		(width 0.1143)
		(layer "In11.Cu")
		(net "CLK_100M_BMC_PE_R_DN")
	)
	(segment
		(start 402.102066 -21.213064)
		(end 402.27631 -21.213064)
		(width 0.1143)
		(layer "In11.Cu")
		(net "CLK_100M_BMC_PE_R_DN")
	)
	(segment
		(start 408.280108 -47.838106)
		(end 407.67762 -47.235618)
		(width 0.1143)
		(layer "In11.Cu")
		(net "CLK_100M_BMC_PE_R_DN")
	)
	(segment
		(start 412.050992 -47.00524)
		(end 411.826456 -47.229776)
		(width 0.1143)
		(layer "In11.Cu")
		(net "CLK_100M_BMC_PE_R_DN")
	)
	(segment
		(start 411.826456 -47.559214)
		(end 411.547564 -47.838106)
		(width 0.1143)
		(layer "In11.Cu")
		(net "CLK_100M_BMC_PE_R_DN")
	)
	(segment
		(start 401.480274 -23.001732)
		(end 401.480274 -21.834856)
		(width 0.1143)
		(layer "In11.Cu")
		(net "CLK_100M_BMC_PE_R_DN")
	)
	(segment
		(start 406.488138 -15.97406)
		(end 408.546808 -15.97406)
		(width 0.1143)
		(layer "In11.Cu")
		(net "CLK_100M_BMC_PE_R_DN")
	)
	(segment
		(start 402.368512 -16.64716)
		(end 405.815038 -16.64716)
		(width 0.1143)
		(layer "In11.Cu")
		(net "CLK_100M_BMC_PE_R_DN")
	)
	(segment
		(start 401.753578 -17.262094)
		(end 402.368512 -16.64716)
		(width 0.1143)
		(layer "In11.Cu")
		(net "CLK_100M_BMC_PE_R_DN")
	)
	(segment
		(start 402.642578 -20.448778)
		(end 402.42109 -20.22729)
		(width 0.1143)
		(layer "In11.Cu")
		(net "CLK_100M_BMC_PE_R_DN")
	)
	(segment
		(start 407.49982 -45.646848)
		(end 406.772872 -44.9199)
		(width 0.1143)
		(layer "In11.Cu")
		(net "CLK_100M_BMC_PE_R_DN")
	)
	(segment
		(start 401.753578 -18.324068)
		(end 401.753578 -17.262094)
		(width 0.1143)
		(layer "In11.Cu")
		(net "CLK_100M_BMC_PE_R_DN")
	)
	(segment
		(start 403.2758 -41.846754)
		(end 402.17979 -40.750744)
		(width 0.1143)
		(layer "In11.Cu")
		(net "CLK_100M_BMC_PE_R_DN")
	)
	(segment
		(start 402.642578 -20.846796)
		(end 402.642578 -20.448778)
		(width 0.1143)
		(layer "In11.Cu")
		(net "CLK_100M_BMC_PE_R_DN")
	)
	(segment
		(start 407.67762 -46.724824)
		(end 407.49982 -46.547024)
		(width 0.1143)
		(layer "In11.Cu")
		(net "CLK_100M_BMC_PE_R_DN")
	)
	(segment
		(start 407.49982 -46.547024)
		(end 407.49982 -45.646848)
		(width 0.1143)
		(layer "In11.Cu")
		(net "CLK_100M_BMC_PE_R_DN")
	)
	(segment
		(start 411.826456 -47.229776)
		(end 411.826456 -47.559214)
		(width 0.1143)
		(layer "In11.Cu")
		(net "CLK_100M_BMC_PE_R_DN")
	)
	(segment
		(start 401.1549 -27.488896)
		(end 401.8534 -26.790396)
		(width 0.1143)
		(layer "In11.Cu")
		(net "CLK_100M_BMC_PE_R_DN")
	)
	(segment
		(start 402.42109 -20.22729)
		(end 402.42109 -18.99158)
		(width 0.1143)
		(layer "In11.Cu")
		(net "CLK_100M_BMC_PE_R_DN")
	)
	(segment
		(start 405.364696 -44.9199)
		(end 403.2758 -42.831004)
		(width 0.1143)
		(layer "In11.Cu")
		(net "CLK_100M_BMC_PE_R_DN")
	)
	(segment
		(start 401.1549 -28.289504)
		(end 401.1549 -27.488896)
		(width 0.1143)
		(layer "In11.Cu")
		(net "CLK_100M_BMC_PE_R_DN")
	)
	(segment
		(start 407.67762 -47.235618)
		(end 407.67762 -46.724824)
		(width 0.1143)
		(layer "In11.Cu")
		(net "CLK_100M_BMC_PE_R_DN")
	)
	(segment
		(start 401.480274 -21.834856)
		(end 402.102066 -21.213064)
		(width 0.1143)
		(layer "In11.Cu")
		(net "CLK_100M_BMC_PE_R_DN")
	)
	(segment
		(start 405.815038 -16.64716)
		(end 406.488138 -15.97406)
		(width 0.1143)
		(layer "In11.Cu")
		(net "CLK_100M_BMC_PE_R_DN")
	)
	(segment
		(start 411.547564 -47.838106)
		(end 408.280108 -47.838106)
		(width 0.1143)
		(layer "In11.Cu")
		(net "CLK_100M_BMC_PE_R_DN")
	)
	(segment
		(start 402.17979 -40.750744)
		(end 402.17979 -29.314394)
		(width 0.1143)
		(layer "In11.Cu")
		(net "CLK_100M_BMC_PE_R_DN")
	)
	(segment
		(start 401.8534 -23.374858)
		(end 401.480274 -23.001732)
		(width 0.1143)
		(layer "In11.Cu")
		(net "CLK_100M_BMC_PE_R_DN")
	)
	(segment
		(start 401.8534 -26.790396)
		(end 401.8534 -23.374858)
		(width 0.1143)
		(layer "In11.Cu")
		(net "CLK_100M_BMC_PE_R_DN")
	)
	(segment
		(start 402.17979 -29.314394)
		(end 401.1549 -28.289504)
		(width 0.1143)
		(layer "In11.Cu")
		(net "CLK_100M_BMC_PE_R_DN")
	)
	(segment
		(start 403.2758 -42.831004)
		(end 403.2758 -41.846754)
		(width 0.1143)
		(layer "In11.Cu")
		(net "CLK_100M_BMC_PE_R_DN")
	)
	(segment
		(start 402.27631 -21.213064)
		(end 402.642578 -20.846796)
		(width 0.1143)
		(layer "In11.Cu")
		(net "CLK_100M_BMC_PE_R_DN")
	)
	(segment
		(start 406.772872 -44.9199)
		(end 405.364696 -44.9199)
		(width 0.1143)
		(layer "In11.Cu")
		(net "CLK_100M_BMC_PE_R_DN")
	)
	(segment
		(start 401.009104 -120.043956)
		(end 401.110958 -120.14581)
		(width 0.0889)
		(layer "F.Cu")
		(net "USB2_P01_DP")
	)
	(segment
		(start 401.927822 -120.14581)
		(end 402.326602 -120.54459)
		(width 0.0889)
		(layer "F.Cu")
		(net "USB2_P01_DP")
	)
	(segment
		(start 404.2029 -120.367806)
		(end 404.2029 -120.17756)
		(width 0.0889)
		(layer "F.Cu")
		(net "USB2_P01_DP")
	)
	(segment
		(start 401.110958 -120.14581)
		(end 401.927822 -120.14581)
		(width 0.0889)
		(layer "F.Cu")
		(net "USB2_P01_DP")
	)
	(segment
		(start 400.649948 -120.126252)
		(end 400.732244 -120.043956)
		(width 0.0889)
		(layer "F.Cu")
		(net "USB2_P01_DP")
	)
	(segment
		(start 400.732244 -120.043956)
		(end 401.009104 -120.043956)
		(width 0.0889)
		(layer "F.Cu")
		(net "USB2_P01_DP")
	)
	(segment
		(start 404.026116 -120.54459)
		(end 404.2029 -120.367806)
		(width 0.0889)
		(layer "F.Cu")
		(net "USB2_P01_DP")
	)
	(segment
		(start 402.326602 -120.54459)
		(end 404.026116 -120.54459)
		(width 0.0889)
		(layer "F.Cu")
		(net "USB2_P01_DP")
	)
	(segment
		(start 400.05 -120.355106)
		(end 400.649948 -120.126252)
		(width 0.0889)
		(layer "F.Cu")
		(net "USB2_P01_DP")
	)
	(segment
		(start 404.2029 -120.17756)
		(end 404.00732 -119.98198)
		(width 0.0889)
		(layer "F.Cu")
		(net "USB2_P01_DP")
	)
	(via
		(at 404.00732 -119.98198)
		(size 0.508)
		(drill 0.254)
		(layers "F.Cu" "B.Cu")
		(net "USB2_P01_DP")
	)
	(via
		(at 470.590626 -125.11405)
		(size 0.508)
		(drill 0.254)
		(layers "F.Cu" "B.Cu")
		(net "USB2_P01_DP")
	)
	(segment
		(start 470.590626 -124.714)
		(end 470.590626 -125.11405)
		(width 0.1143)
		(layer "B.Cu")
		(net "USB2_P01_DP")
	)
	(segment
		(start 471.182446 -124.8791)
		(end 470.903046 -124.5997)
		(width 0.1143)
		(layer "B.Cu")
		(net "USB2_P01_DP")
	)
	(segment
		(start 471.6653 -124.8791)
		(end 471.182446 -124.8791)
		(width 0.1143)
		(layer "B.Cu")
		(net "USB2_P01_DP")
	)
	(segment
		(start 470.704926 -124.5997)
		(end 470.590626 -124.714)
		(width 0.1143)
		(layer "B.Cu")
		(net "USB2_P01_DP")
	)
	(segment
		(start 470.903046 -124.5997)
		(end 470.704926 -124.5997)
		(width 0.1143)
		(layer "B.Cu")
		(net "USB2_P01_DP")
	)
	(segment
		(start 435.735222 -124.779278)
		(end 446.84442 -124.779278)
		(width 0.1143)
		(layer "In2.Cu")
		(net "USB2_P01_DP")
	)
	(segment
		(start 424.163744 -128.181608)
		(end 425.425108 -128.181608)
		(width 0.1143)
		(layer "In2.Cu")
		(net "USB2_P01_DP")
	)
	(segment
		(start 404.00732 -119.98198)
		(end 404.322788 -120.297448)
		(width 0.1143)
		(layer "In2.Cu")
		(net "USB2_P01_DP")
	)
	(segment
		(start 425.425108 -128.181608)
		(end 428.0662 -125.540516)
		(width 0.1143)
		(layer "In2.Cu")
		(net "USB2_P01_DP")
	)
	(segment
		(start 419.229794 -126.80442)
		(end 422.786556 -126.80442)
		(width 0.1143)
		(layer "In2.Cu")
		(net "USB2_P01_DP")
	)
	(segment
		(start 470.3572 -124.6759)
		(end 470.590626 -124.909326)
		(width 0.1143)
		(layer "In2.Cu")
		(net "USB2_P01_DP")
	)
	(segment
		(start 414.274254 -124.333)
		(end 415.445194 -125.50394)
		(width 0.1143)
		(layer "In2.Cu")
		(net "USB2_P01_DP")
	)
	(segment
		(start 412.25724 -125.2855)
		(end 413.20974 -124.333)
		(width 0.1143)
		(layer "In2.Cu")
		(net "USB2_P01_DP")
	)
	(segment
		(start 428.0662 -125.540516)
		(end 434.973984 -125.540516)
		(width 0.1143)
		(layer "In2.Cu")
		(net "USB2_P01_DP")
	)
	(segment
		(start 468.50935 -127.62865)
		(end 469.3285 -126.809246)
		(width 0.1143)
		(layer "In2.Cu")
		(net "USB2_P01_DP")
	)
	(segment
		(start 466.738208 -128.13665)
		(end 467.246208 -127.62865)
		(width 0.1143)
		(layer "In2.Cu")
		(net "USB2_P01_DP")
	)
	(segment
		(start 470.590626 -124.909326)
		(end 470.590626 -125.11405)
		(width 0.1143)
		(layer "In2.Cu")
		(net "USB2_P01_DP")
	)
	(segment
		(start 415.445194 -125.50394)
		(end 417.929314 -125.50394)
		(width 0.1143)
		(layer "In2.Cu")
		(net "USB2_P01_DP")
	)
	(segment
		(start 405.923242 -125.2855)
		(end 412.25724 -125.2855)
		(width 0.1143)
		(layer "In2.Cu")
		(net "USB2_P01_DP")
	)
	(segment
		(start 469.716612 -124.6759)
		(end 470.3572 -124.6759)
		(width 0.1143)
		(layer "In2.Cu")
		(net "USB2_P01_DP")
	)
	(segment
		(start 469.3285 -125.064012)
		(end 469.716612 -124.6759)
		(width 0.1143)
		(layer "In2.Cu")
		(net "USB2_P01_DP")
	)
	(segment
		(start 422.786556 -126.80442)
		(end 424.163744 -128.181608)
		(width 0.1143)
		(layer "In2.Cu")
		(net "USB2_P01_DP")
	)
	(segment
		(start 446.84442 -124.779278)
		(end 450.201792 -128.13665)
		(width 0.1143)
		(layer "In2.Cu")
		(net "USB2_P01_DP")
	)
	(segment
		(start 404.322788 -123.685046)
		(end 405.923242 -125.2855)
		(width 0.1143)
		(layer "In2.Cu")
		(net "USB2_P01_DP")
	)
	(segment
		(start 413.20974 -124.333)
		(end 414.274254 -124.333)
		(width 0.1143)
		(layer "In2.Cu")
		(net "USB2_P01_DP")
	)
	(segment
		(start 467.246208 -127.62865)
		(end 468.50935 -127.62865)
		(width 0.1143)
		(layer "In2.Cu")
		(net "USB2_P01_DP")
	)
	(segment
		(start 417.929314 -125.50394)
		(end 419.229794 -126.80442)
		(width 0.1143)
		(layer "In2.Cu")
		(net "USB2_P01_DP")
	)
	(segment
		(start 469.3285 -126.809246)
		(end 469.3285 -125.064012)
		(width 0.1143)
		(layer "In2.Cu")
		(net "USB2_P01_DP")
	)
	(segment
		(start 404.322788 -120.297448)
		(end 404.322788 -123.685046)
		(width 0.1143)
		(layer "In2.Cu")
		(net "USB2_P01_DP")
	)
	(segment
		(start 434.973984 -125.540516)
		(end 435.735222 -124.779278)
		(width 0.1143)
		(layer "In2.Cu")
		(net "USB2_P01_DP")
	)
	(segment
		(start 450.201792 -128.13665)
		(end 466.738208 -128.13665)
		(width 0.1143)
		(layer "In2.Cu")
		(net "USB2_P01_DP")
	)
	(segment
		(start 404.10511 -120.73509)
		(end 404.3934 -120.4468)
		(width 0.0889)
		(layer "F.Cu")
		(net "USB2_P01_DN")
	)
	(segment
		(start 403.269958 -120.73509)
		(end 403.358858 -120.82399)
		(width 0.0889)
		(layer "F.Cu")
		(net "USB2_P01_DN")
	)
	(segment
		(start 403.003258 -120.73509)
		(end 403.269958 -120.73509)
		(width 0.0889)
		(layer "F.Cu")
		(net "USB2_P01_DN")
	)
	(segment
		(start 402.247608 -120.73509)
		(end 402.558758 -120.73509)
		(width 0.0889)
		(layer "F.Cu")
		(net "USB2_P01_DN")
	)
	(segment
		(start 400.898868 -120.33631)
		(end 401.848828 -120.33631)
		(width 0.0889)
		(layer "F.Cu")
		(net "USB2_P01_DN")
	)
	(segment
		(start 402.914358 -120.82399)
		(end 403.003258 -120.73509)
		(width 0.0889)
		(layer "F.Cu")
		(net "USB2_P01_DN")
	)
	(segment
		(start 404.3934 -120.0912)
		(end 404.50262 -119.98198)
		(width 0.0889)
		(layer "F.Cu")
		(net "USB2_P01_DN")
	)
	(segment
		(start 401.848828 -120.33631)
		(end 402.247608 -120.73509)
		(width 0.0889)
		(layer "F.Cu")
		(net "USB2_P01_DN")
	)
	(segment
		(start 400.880072 -120.355106)
		(end 400.898868 -120.33631)
		(width 0.0889)
		(layer "F.Cu")
		(net "USB2_P01_DN")
	)
	(segment
		(start 402.647658 -120.82399)
		(end 402.914358 -120.82399)
		(width 0.0889)
		(layer "F.Cu")
		(net "USB2_P01_DN")
	)
	(segment
		(start 403.625558 -120.82399)
		(end 403.714458 -120.73509)
		(width 0.0889)
		(layer "F.Cu")
		(net "USB2_P01_DN")
	)
	(segment
		(start 402.558758 -120.73509)
		(end 402.647658 -120.82399)
		(width 0.0889)
		(layer "F.Cu")
		(net "USB2_P01_DN")
	)
	(segment
		(start 403.358858 -120.82399)
		(end 403.625558 -120.82399)
		(width 0.0889)
		(layer "F.Cu")
		(net "USB2_P01_DN")
	)
	(segment
		(start 404.3934 -120.4468)
		(end 404.3934 -120.0912)
		(width 0.0889)
		(layer "F.Cu")
		(net "USB2_P01_DN")
	)
	(segment
		(start 403.714458 -120.73509)
		(end 404.10511 -120.73509)
		(width 0.0889)
		(layer "F.Cu")
		(net "USB2_P01_DN")
	)
	(segment
		(start 404.50262 -119.98198)
		(end 404.94712 -119.98198)
		(width 0.0889)
		(layer "F.Cu")
		(net "USB2_P01_DN")
	)
	(via
		(at 470.590626 -123.84405)
		(size 0.508)
		(drill 0.254)
		(layers "F.Cu" "B.Cu")
		(net "USB2_P01_DN")
	)
	(via
		(at 404.94712 -119.98198)
		(size 0.508)
		(drill 0.254)
		(layers "F.Cu" "B.Cu")
		(net "USB2_P01_DN")
	)
	(segment
		(start 471.6653 -124.079)
		(end 471.195146 -124.079)
		(width 0.1143)
		(layer "B.Cu")
		(net "USB2_P01_DN")
	)
	(segment
		(start 470.704926 -124.3584)
		(end 470.590626 -124.2441)
		(width 0.1143)
		(layer "B.Cu")
		(net "USB2_P01_DN")
	)
	(segment
		(start 470.590626 -124.2441)
		(end 470.590626 -123.84405)
		(width 0.1143)
		(layer "B.Cu")
		(net "USB2_P01_DN")
	)
	(segment
		(start 470.915746 -124.3584)
		(end 470.704926 -124.3584)
		(width 0.1143)
		(layer "B.Cu")
		(net "USB2_P01_DN")
	)
	(segment
		(start 471.195146 -124.079)
		(end 470.915746 -124.3584)
		(width 0.1143)
		(layer "B.Cu")
		(net "USB2_P01_DN")
	)
	(segment
		(start 464.204558 -127.67945)
		(end 464.369658 -127.84455)
		(width 0.1143)
		(layer "In2.Cu")
		(net "USB2_P01_DN")
	)
	(segment
		(start 450.32295 -127.84455)
		(end 463.696558 -127.84455)
		(width 0.1143)
		(layer "In2.Cu")
		(net "USB2_P01_DN")
	)
	(segment
		(start 404.614888 -120.314212)
		(end 404.614888 -123.563888)
		(width 0.1143)
		(layer "In2.Cu")
		(net "USB2_P01_DN")
	)
	(segment
		(start 414.395412 -124.0409)
		(end 415.566352 -125.21184)
		(width 0.1143)
		(layer "In2.Cu")
		(net "USB2_P01_DN")
	)
	(segment
		(start 469.595454 -124.3838)
		(end 470.35466 -124.3838)
		(width 0.1143)
		(layer "In2.Cu")
		(net "USB2_P01_DN")
	)
	(segment
		(start 468.388192 -127.33655)
		(end 469.0364 -126.688088)
		(width 0.1143)
		(layer "In2.Cu")
		(net "USB2_P01_DN")
	)
	(segment
		(start 419.858952 -126.34722)
		(end 420.201852 -126.34722)
		(width 0.1143)
		(layer "In2.Cu")
		(net "USB2_P01_DN")
	)
	(segment
		(start 412.136082 -124.9934)
		(end 413.088582 -124.0409)
		(width 0.1143)
		(layer "In2.Cu")
		(net "USB2_P01_DN")
	)
	(segment
		(start 425.30395 -127.889508)
		(end 427.945042 -125.248416)
		(width 0.1143)
		(layer "In2.Cu")
		(net "USB2_P01_DN")
	)
	(segment
		(start 469.0364 -126.688088)
		(end 469.0364 -124.942854)
		(width 0.1143)
		(layer "In2.Cu")
		(net "USB2_P01_DN")
	)
	(segment
		(start 463.696558 -127.84455)
		(end 463.861658 -127.67945)
		(width 0.1143)
		(layer "In2.Cu")
		(net "USB2_P01_DN")
	)
	(segment
		(start 415.566352 -125.21184)
		(end 418.050472 -125.21184)
		(width 0.1143)
		(layer "In2.Cu")
		(net "USB2_P01_DN")
	)
	(segment
		(start 470.590626 -124.147834)
		(end 470.590626 -123.84405)
		(width 0.1143)
		(layer "In2.Cu")
		(net "USB2_P01_DN")
	)
	(segment
		(start 464.877658 -127.67945)
		(end 465.220558 -127.67945)
		(width 0.1143)
		(layer "In2.Cu")
		(net "USB2_P01_DN")
	)
	(segment
		(start 419.693852 -126.51232)
		(end 419.858952 -126.34722)
		(width 0.1143)
		(layer "In2.Cu")
		(net "USB2_P01_DN")
	)
	(segment
		(start 427.945042 -125.248416)
		(end 434.852826 -125.248416)
		(width 0.1143)
		(layer "In2.Cu")
		(net "USB2_P01_DN")
	)
	(segment
		(start 420.201852 -126.34722)
		(end 420.366952 -126.51232)
		(width 0.1143)
		(layer "In2.Cu")
		(net "USB2_P01_DN")
	)
	(segment
		(start 422.907714 -126.51232)
		(end 424.284902 -127.889508)
		(width 0.1143)
		(layer "In2.Cu")
		(net "USB2_P01_DN")
	)
	(segment
		(start 467.12505 -127.33655)
		(end 468.388192 -127.33655)
		(width 0.1143)
		(layer "In2.Cu")
		(net "USB2_P01_DN")
	)
	(segment
		(start 404.614888 -123.563888)
		(end 406.0444 -124.9934)
		(width 0.1143)
		(layer "In2.Cu")
		(net "USB2_P01_DN")
	)
	(segment
		(start 404.94712 -119.98198)
		(end 404.614888 -120.314212)
		(width 0.1143)
		(layer "In2.Cu")
		(net "USB2_P01_DN")
	)
	(segment
		(start 406.0444 -124.9934)
		(end 412.136082 -124.9934)
		(width 0.1143)
		(layer "In2.Cu")
		(net "USB2_P01_DN")
	)
	(segment
		(start 465.385658 -127.84455)
		(end 466.61705 -127.84455)
		(width 0.1143)
		(layer "In2.Cu")
		(net "USB2_P01_DN")
	)
	(segment
		(start 435.614064 -124.487178)
		(end 446.965578 -124.487178)
		(width 0.1143)
		(layer "In2.Cu")
		(net "USB2_P01_DN")
	)
	(segment
		(start 463.861658 -127.67945)
		(end 464.204558 -127.67945)
		(width 0.1143)
		(layer "In2.Cu")
		(net "USB2_P01_DN")
	)
	(segment
		(start 470.35466 -124.3838)
		(end 470.590626 -124.147834)
		(width 0.1143)
		(layer "In2.Cu")
		(net "USB2_P01_DN")
	)
	(segment
		(start 464.369658 -127.84455)
		(end 464.712558 -127.84455)
		(width 0.1143)
		(layer "In2.Cu")
		(net "USB2_P01_DN")
	)
	(segment
		(start 434.852826 -125.248416)
		(end 435.614064 -124.487178)
		(width 0.1143)
		(layer "In2.Cu")
		(net "USB2_P01_DN")
	)
	(segment
		(start 466.61705 -127.84455)
		(end 467.12505 -127.33655)
		(width 0.1143)
		(layer "In2.Cu")
		(net "USB2_P01_DN")
	)
	(segment
		(start 419.350952 -126.51232)
		(end 419.693852 -126.51232)
		(width 0.1143)
		(layer "In2.Cu")
		(net "USB2_P01_DN")
	)
	(segment
		(start 469.0364 -124.942854)
		(end 469.595454 -124.3838)
		(width 0.1143)
		(layer "In2.Cu")
		(net "USB2_P01_DN")
	)
	(segment
		(start 420.366952 -126.51232)
		(end 422.907714 -126.51232)
		(width 0.1143)
		(layer "In2.Cu")
		(net "USB2_P01_DN")
	)
	(segment
		(start 418.050472 -125.21184)
		(end 419.350952 -126.51232)
		(width 0.1143)
		(layer "In2.Cu")
		(net "USB2_P01_DN")
	)
	(segment
		(start 413.088582 -124.0409)
		(end 414.395412 -124.0409)
		(width 0.1143)
		(layer "In2.Cu")
		(net "USB2_P01_DN")
	)
	(segment
		(start 465.220558 -127.67945)
		(end 465.385658 -127.84455)
		(width 0.1143)
		(layer "In2.Cu")
		(net "USB2_P01_DN")
	)
	(segment
		(start 424.284902 -127.889508)
		(end 425.30395 -127.889508)
		(width 0.1143)
		(layer "In2.Cu")
		(net "USB2_P01_DN")
	)
	(segment
		(start 464.712558 -127.84455)
		(end 464.877658 -127.67945)
		(width 0.1143)
		(layer "In2.Cu")
		(net "USB2_P01_DN")
	)
	(segment
		(start 446.965578 -124.487178)
		(end 450.32295 -127.84455)
		(width 0.1143)
		(layer "In2.Cu")
		(net "USB2_P01_DN")
	)
	(segment
		(start 380.30785 -115.00612)
		(end 380.80315 -115.236244)
		(width 0.10795)
		(layer "F.Cu")
		(net "TP_PCH_RSVD25")
	)
	(via
		(at 380.80315 -115.236244)
		(size 0.508)
		(drill 0.254)
		(layers "F.Cu" "B.Cu")
		(net "TP_PCH_RSVD25")
	)
	(segment
		(start 380.30785 -113.28908)
		(end 380.80315 -113.519204)
		(width 0.10795)
		(layer "F.Cu")
		(net "TP_PCH_RSVD24")
	)
	(via
		(at 380.80315 -113.519204)
		(size 0.508)
		(drill 0.254)
		(layers "F.Cu" "B.Cu")
		(net "TP_PCH_RSVD24")
	)
	(segment
		(start 138.816334 -96.518984)
		(end 139.387834 -96.518984)
		(width 0.1143)
		(layer "F.Cu")
		(net "P3E_CPU1_PE3_MP_TXP<9>")
	)
	(via
		(at 33.5534 -111.418116)
		(size 0.508)
		(drill 0.254)
		(layers "F.Cu" "B.Cu")
		(net "P3E_CPU1_PE3_MP_TXP<9>")
	)
	(via
		(at 139.387834 -96.518984)
		(size 0.508)
		(drill 0.254)
		(layers "F.Cu" "B.Cu")
		(net "P3E_CPU1_PE3_MP_TXP<9>")
	)
	(segment
		(start 124.446538 -92.261436)
		(end 124.441712 -92.2528)
		(width 0.0889)
		(layer "B.Cu")
		(net "P3E_CPU1_PE3_MP_TXP<9>")
	)
	(segment
		(start 120.785382 -104.39527)
		(end 120.785128 -104.374696)
		(width 0.0889)
		(layer "B.Cu")
		(net "P3E_CPU1_PE3_MP_TXP<9>")
	)
	(segment
		(start 124.446538 -91.270836)
		(end 124.441712 -91.2622)
		(width 0.0889)
		(layer "B.Cu")
		(net "P3E_CPU1_PE3_MP_TXP<9>")
	)
	(segment
		(start 141.482826 -94.323916)
		(end 141.482572 -94.32417)
		(width 0.0889)
		(layer "B.Cu")
		(net "P3E_CPU1_PE3_MP_TXP<9>")
	)
	(segment
		(start 141.37259 -91.438476)
		(end 141.28623 -91.524836)
		(width 0.0889)
		(layer "B.Cu")
		(net "P3E_CPU1_PE3_MP_TXP<9>")
	)
	(segment
		(start 126.495302 -87.699088)
		(end 126.528068 -87.699088)
		(width 0.0889)
		(layer "B.Cu")
		(net "P3E_CPU1_PE3_MP_TXP<9>")
	)
	(segment
		(start 124.452888 -91.281504)
		(end 124.446538 -91.270836)
		(width 0.0889)
		(layer "B.Cu")
		(net "P3E_CPU1_PE3_MP_TXP<9>")
	)
	(segment
		(start 123.00839 -102.294436)
		(end 123.00839 -102.151434)
		(width 0.0889)
		(layer "B.Cu")
		(net "P3E_CPU1_PE3_MP_TXP<9>")
	)
	(segment
		(start 132.173218 -84.431886)
		(end 132.17652 -84.426044)
		(width 0.0889)
		(layer "B.Cu")
		(net "P3E_CPU1_PE3_MP_TXP<9>")
	)
	(segment
		(start 124.452888 -92.272104)
		(end 124.446538 -92.261436)
		(width 0.0889)
		(layer "B.Cu")
		(net "P3E_CPU1_PE3_MP_TXP<9>")
	)
	(segment
		(start 68.680838 -106.646472)
		(end 68.680838 -106.646218)
		(width 0.1143)
		(layer "B.Cu")
		(net "P3E_CPU1_PE3_MP_TXP<9>")
	)
	(segment
		(start 141.37259 -91.966796)
		(end 141.28623 -92.053156)
		(width 0.0889)
		(layer "B.Cu")
		(net "P3E_CPU1_PE3_MP_TXP<9>")
	)
	(segment
		(start 141.45641 -89.7763)
		(end 141.451584 -89.784682)
		(width 0.0889)
		(layer "B.Cu")
		(net "P3E_CPU1_PE3_MP_TXP<9>")
	)
	(segment
		(start 130.791712 -85.222334)
		(end 130.824478 -85.222334)
		(width 0.0889)
		(layer "B.Cu")
		(net "P3E_CPU1_PE3_MP_TXP<9>")
	)
	(segment
		(start 125.640592 -88.194134)
		(end 125.673358 -88.194134)
		(width 0.0889)
		(layer "B.Cu")
		(net "P3E_CPU1_PE3_MP_TXP<9>")
	)
	(segment
		(start 124.452888 -97.225104)
		(end 124.446538 -97.214436)
		(width 0.0889)
		(layer "B.Cu")
		(net "P3E_CPU1_PE3_MP_TXP<9>")
	)
	(segment
		(start 123.133866 -102.025704)
		(end 123.277122 -102.025704)
		(width 0.0889)
		(layer "B.Cu")
		(net "P3E_CPU1_PE3_MP_TXP<9>")
	)
	(segment
		(start 124.446538 -99.195636)
		(end 124.441712 -99.187)
		(width 0.0889)
		(layer "B.Cu")
		(net "P3E_CPU1_PE3_MP_TXP<9>")
	)
	(segment
		(start 139.445746 -96.91497)
		(end 139.387834 -96.857058)
		(width 0.0889)
		(layer "B.Cu")
		(net "P3E_CPU1_PE3_MP_TXP<9>")
	)
	(segment
		(start 139.387834 -96.857058)
		(end 139.387834 -96.518984)
		(width 0.0889)
		(layer "B.Cu")
		(net "P3E_CPU1_PE3_MP_TXP<9>")
	)
	(segment
		(start 141.28623 -92.759276)
		(end 141.37259 -92.845636)
		(width 0.0889)
		(layer "B.Cu")
		(net "P3E_CPU1_PE3_MP_TXP<9>")
	)
	(segment
		(start 136.794494 -83.736688)
		(end 136.82726 -83.736688)
		(width 0.0889)
		(layer "B.Cu")
		(net "P3E_CPU1_PE3_MP_TXP<9>")
	)
	(segment
		(start 137.649204 -84.231734)
		(end 137.68197 -84.231734)
		(width 0.0889)
		(layer "B.Cu")
		(net "P3E_CPU1_PE3_MP_TXP<9>")
	)
	(segment
		(start 124.446538 -97.214436)
		(end 124.441712 -97.2058)
		(width 0.0889)
		(layer "B.Cu")
		(net "P3E_CPU1_PE3_MP_TXP<9>")
	)
	(segment
		(start 53.474112 -109.68609)
		(end 68.680838 -106.646472)
		(width 0.1143)
		(layer "B.Cu")
		(net "P3E_CPU1_PE3_MP_TXP<9>")
	)
	(segment
		(start 141.37259 -92.495116)
		(end 141.28623 -92.581476)
		(width 0.0889)
		(layer "B.Cu")
		(net "P3E_CPU1_PE3_MP_TXP<9>")
	)
	(segment
		(start 141.37259 -91.260676)
		(end 141.37259 -91.438476)
		(width 0.0889)
		(layer "B.Cu")
		(net "P3E_CPU1_PE3_MP_TXP<9>")
	)
	(segment
		(start 124.452888 -93.262704)
		(end 124.446538 -93.252036)
		(width 0.0889)
		(layer "B.Cu")
		(net "P3E_CPU1_PE3_MP_TXP<9>")
	)
	(segment
		(start 89.913714 -105.508552)
		(end 97.281746 -106.981752)
		(width 0.1143)
		(layer "B.Cu")
		(net "P3E_CPU1_PE3_MP_TXP<9>")
	)
	(segment
		(start 141.482572 -94.32417)
		(end 141.482318 -94.32417)
		(width 0.0889)
		(layer "B.Cu")
		(net "P3E_CPU1_PE3_MP_TXP<9>")
	)
	(segment
		(start 124.446538 -100.186236)
		(end 124.441712 -100.1776)
		(width 0.0889)
		(layer "B.Cu")
		(net "P3E_CPU1_PE3_MP_TXP<9>")
	)
	(segment
		(start 141.37259 -94.080076)
		(end 141.482826 -94.323916)
		(width 0.0889)
		(layer "B.Cu")
		(net "P3E_CPU1_PE3_MP_TXP<9>")
	)
	(segment
		(start 109.155484 -106.055414)
		(end 112.843564 -106.79303)
		(width 0.1143)
		(layer "B.Cu")
		(net "P3E_CPU1_PE3_MP_TXP<9>")
	)
	(segment
		(start 141.37259 -90.390218)
		(end 141.294612 -90.468196)
		(width 0.0889)
		(layer "B.Cu")
		(net "P3E_CPU1_PE3_MP_TXP<9>")
	)
	(segment
		(start 124.452888 -98.215704)
		(end 124.446538 -98.205036)
		(width 0.0889)
		(layer "B.Cu")
		(net "P3E_CPU1_PE3_MP_TXP<9>")
	)
	(segment
		(start 124.446538 -98.205036)
		(end 124.441712 -98.1964)
		(width 0.0889)
		(layer "B.Cu")
		(net "P3E_CPU1_PE3_MP_TXP<9>")
	)
	(segment
		(start 141.28623 -92.053156)
		(end 141.28623 -92.230956)
		(width 0.0889)
		(layer "B.Cu")
		(net "P3E_CPU1_PE3_MP_TXP<9>")
	)
	(segment
		(start 141.271752 -95.928434)
		(end 141.087094 -95.928434)
		(width 0.0889)
		(layer "B.Cu")
		(net "P3E_CPU1_PE3_MP_TXP<9>")
	)
	(segment
		(start 141.28623 -92.581476)
		(end 141.28623 -92.759276)
		(width 0.0889)
		(layer "B.Cu")
		(net "P3E_CPU1_PE3_MP_TXP<9>")
	)
	(segment
		(start 141.451584 -87.403686)
		(end 141.45641 -87.412322)
		(width 0.0889)
		(layer "B.Cu")
		(net "P3E_CPU1_PE3_MP_TXP<9>")
	)
	(segment
		(start 122.093736 -103.20909)
		(end 122.219466 -103.08336)
		(width 0.0889)
		(layer "B.Cu")
		(net "P3E_CPU1_PE3_MP_TXP<9>")
	)
	(segment
		(start 22.421088 -101.897942)
		(end 22.421342 -101.89845)
		(width 0.1143)
		(layer "B.Cu")
		(net "P3E_CPU1_PE3_MP_TXP<9>")
	)
	(segment
		(start 141.28623 -93.287596)
		(end 141.37259 -93.373956)
		(width 0.0889)
		(layer "B.Cu")
		(net "P3E_CPU1_PE3_MP_TXP<9>")
	)
	(segment
		(start 27.530298 -109.32922)
		(end 30.269434 -109.89818)
		(width 0.1143)
		(layer "B.Cu")
		(net "P3E_CPU1_PE3_MP_TXP<9>")
	)
	(segment
		(start 122.219466 -102.940358)
		(end 122.344942 -102.814628)
		(width 0.0889)
		(layer "B.Cu")
		(net "P3E_CPU1_PE3_MP_TXP<9>")
	)
	(segment
		(start 121.95048 -103.20909)
		(end 122.093736 -103.20909)
		(width 0.0889)
		(layer "B.Cu")
		(net "P3E_CPU1_PE3_MP_TXP<9>")
	)
	(segment
		(start 141.28623 -91.524836)
		(end 141.28623 -91.702636)
		(width 0.0889)
		(layer "B.Cu")
		(net "P3E_CPU1_PE3_MP_TXP<9>")
	)
	(segment
		(start 122.739404 -102.420166)
		(end 122.88266 -102.420166)
		(width 0.0889)
		(layer "B.Cu")
		(net "P3E_CPU1_PE3_MP_TXP<9>")
	)
	(segment
		(start 141.28623 -92.230956)
		(end 141.37259 -92.317316)
		(width 0.0889)
		(layer "B.Cu")
		(net "P3E_CPU1_PE3_MP_TXP<9>")
	)
	(segment
		(start 141.294612 -90.645996)
		(end 141.37259 -90.723974)
		(width 0.0889)
		(layer "B.Cu")
		(net "P3E_CPU1_PE3_MP_TXP<9>")
	)
	(segment
		(start 134.225538 -83.241134)
		(end 134.258304 -83.241134)
		(width 0.0889)
		(layer "B.Cu")
		(net "P3E_CPU1_PE3_MP_TXP<9>")
	)
	(segment
		(start 120.777254 -104.418638)
		(end 120.785382 -104.41051)
		(width 0.0889)
		(layer "B.Cu")
		(net "P3E_CPU1_PE3_MP_TXP<9>")
	)
	(segment
		(start 141.28623 -93.109796)
		(end 141.28623 -93.287596)
		(width 0.0889)
		(layer "B.Cu")
		(net "P3E_CPU1_PE3_MP_TXP<9>")
	)
	(segment
		(start 141.28623 -91.702636)
		(end 141.37259 -91.788996)
		(width 0.0889)
		(layer "B.Cu")
		(net "P3E_CPU1_PE3_MP_TXP<9>")
	)
	(segment
		(start 129.929382 -85.717888)
		(end 129.962148 -85.717888)
		(width 0.0889)
		(layer "B.Cu")
		(net "P3E_CPU1_PE3_MP_TXP<9>")
	)
	(segment
		(start 68.680838 -106.646218)
		(end 83.888072 -103.606092)
		(width 0.1143)
		(layer "B.Cu")
		(net "P3E_CPU1_PE3_MP_TXP<9>")
	)
	(segment
		(start 123.402852 -101.899974)
		(end 123.402852 -101.756718)
		(width 0.0889)
		(layer "B.Cu")
		(net "P3E_CPU1_PE3_MP_TXP<9>")
	)
	(segment
		(start 123.528328 -101.631242)
		(end 123.528328 -101.300788)
		(width 0.0889)
		(layer "B.Cu")
		(net "P3E_CPU1_PE3_MP_TXP<9>")
	)
	(segment
		(start 124.446538 -89.289636)
		(end 124.441712 -89.281)
		(width 0.0889)
		(layer "B.Cu")
		(net "P3E_CPU1_PE3_MP_TXP<9>")
	)
	(segment
		(start 135.932164 -83.241134)
		(end 135.96493 -83.241134)
		(width 0.0889)
		(layer "B.Cu")
		(net "P3E_CPU1_PE3_MP_TXP<9>")
	)
	(segment
		(start 128.212342 -86.708488)
		(end 128.245108 -86.708488)
		(width 0.0889)
		(layer "B.Cu")
		(net "P3E_CPU1_PE3_MP_TXP<9>")
	)
	(segment
		(start 140.228574 -85.717888)
		(end 140.26134 -85.717888)
		(width 0.0889)
		(layer "B.Cu")
		(net "P3E_CPU1_PE3_MP_TXP<9>")
	)
	(segment
		(start 124.452888 -96.234504)
		(end 124.446538 -96.223836)
		(width 0.0889)
		(layer "B.Cu")
		(net "P3E_CPU1_PE3_MP_TXP<9>")
	)
	(segment
		(start 88.418924 -104.511856)
		(end 89.913714 -105.508552)
		(width 0.1143)
		(layer "B.Cu")
		(net "P3E_CPU1_PE3_MP_TXP<9>")
	)
	(segment
		(start 133.363208 -83.736688)
		(end 133.395974 -83.736688)
		(width 0.0889)
		(layer "B.Cu")
		(net "P3E_CPU1_PE3_MP_TXP<9>")
	)
	(segment
		(start 141.37259 -92.317316)
		(end 141.37259 -92.495116)
		(width 0.0889)
		(layer "B.Cu")
		(net "P3E_CPU1_PE3_MP_TXP<9>")
	)
	(segment
		(start 123.756928 -101.072188)
		(end 123.952508 -101.072188)
		(width 0.0889)
		(layer "B.Cu")
		(net "P3E_CPU1_PE3_MP_TXP<9>")
	)
	(segment
		(start 131.646422 -84.727288)
		(end 131.679188 -84.727288)
		(width 0.0889)
		(layer "B.Cu")
		(net "P3E_CPU1_PE3_MP_TXP<9>")
	)
	(segment
		(start 25.024334 -106.111548)
		(end 25.024334 -106.111802)
		(width 0.1143)
		(layer "B.Cu")
		(net "P3E_CPU1_PE3_MP_TXP<9>")
	)
	(segment
		(start 20.821396 -100.29825)
		(end 22.421088 -101.897942)
		(width 0.1143)
		(layer "B.Cu")
		(net "P3E_CPU1_PE3_MP_TXP<9>")
	)
	(segment
		(start 122.88266 -102.420166)
		(end 123.00839 -102.294436)
		(width 0.0889)
		(layer "B.Cu")
		(net "P3E_CPU1_PE3_MP_TXP<9>")
	)
	(segment
		(start 33.5534 -111.418116)
		(end 35.888422 -111.418116)
		(width 0.1143)
		(layer "B.Cu")
		(net "P3E_CPU1_PE3_MP_TXP<9>")
	)
	(segment
		(start 124.446538 -90.280236)
		(end 124.441712 -90.2716)
		(width 0.0889)
		(layer "B.Cu")
		(net "P3E_CPU1_PE3_MP_TXP<9>")
	)
	(segment
		(start 124.446538 -96.223836)
		(end 124.441712 -96.2152)
		(width 0.0889)
		(layer "B.Cu")
		(net "P3E_CPU1_PE3_MP_TXP<9>")
	)
	(segment
		(start 123.528328 -101.300788)
		(end 123.756928 -101.072188)
		(width 0.0889)
		(layer "B.Cu")
		(net "P3E_CPU1_PE3_MP_TXP<9>")
	)
	(segment
		(start 102.211378 -105.995978)
		(end 105.831132 -106.719878)
		(width 0.1143)
		(layer "B.Cu")
		(net "P3E_CPU1_PE3_MP_TXP<9>")
	)
	(segment
		(start 25.024334 -106.111802)
		(end 25.395936 -106.483404)
		(width 0.1143)
		(layer "B.Cu")
		(net "P3E_CPU1_PE3_MP_TXP<9>")
	)
	(segment
		(start 124.446538 -93.252036)
		(end 124.441712 -93.2434)
		(width 0.0889)
		(layer "B.Cu")
		(net "P3E_CPU1_PE3_MP_TXP<9>")
	)
	(segment
		(start 22.421342 -101.89845)
		(end 23.559516 -104.646984)
		(width 0.1143)
		(layer "B.Cu")
		(net "P3E_CPU1_PE3_MP_TXP<9>")
	)
	(segment
		(start 135.080248 -82.746088)
		(end 135.11022 -82.746088)
		(width 0.0889)
		(layer "B.Cu")
		(net "P3E_CPU1_PE3_MP_TXP<9>")
	)
	(segment
		(start 132.519674 -84.231734)
		(end 132.541264 -84.231734)
		(width 0.0889)
		(layer "B.Cu")
		(net "P3E_CPU1_PE3_MP_TXP<9>")
	)
	(segment
		(start 141.37259 -90.910156)
		(end 141.28623 -90.996516)
		(width 0.0889)
		(layer "B.Cu")
		(net "P3E_CPU1_PE3_MP_TXP<9>")
	)
	(segment
		(start 141.28623 -90.996516)
		(end 141.28623 -91.174316)
		(width 0.0889)
		(layer "B.Cu")
		(net "P3E_CPU1_PE3_MP_TXP<9>")
	)
	(segment
		(start 124.452888 -90.290904)
		(end 124.446538 -90.280236)
		(width 0.0889)
		(layer "B.Cu")
		(net "P3E_CPU1_PE3_MP_TXP<9>")
	)
	(segment
		(start 122.344942 -102.814628)
		(end 122.488198 -102.814628)
		(width 0.0889)
		(layer "B.Cu")
		(net "P3E_CPU1_PE3_MP_TXP<9>")
	)
	(segment
		(start 141.37259 -91.788996)
		(end 141.37259 -91.966796)
		(width 0.0889)
		(layer "B.Cu")
		(net "P3E_CPU1_PE3_MP_TXP<9>")
	)
	(segment
		(start 32.795718 -111.418116)
		(end 33.5534 -111.418116)
		(width 0.1143)
		(layer "B.Cu")
		(net "P3E_CPU1_PE3_MP_TXP<9>")
	)
	(segment
		(start 124.778262 -88.689688)
		(end 124.811028 -88.689688)
		(width 0.0889)
		(layer "B.Cu")
		(net "P3E_CPU1_PE3_MP_TXP<9>")
	)
	(segment
		(start 112.843564 -106.79303)
		(end 119.791988 -105.403904)
		(width 0.1143)
		(layer "B.Cu")
		(net "P3E_CPU1_PE3_MP_TXP<9>")
	)
	(segment
		(start 23.559516 -104.646984)
		(end 25.024334 -106.111548)
		(width 0.1143)
		(layer "B.Cu")
		(net "P3E_CPU1_PE3_MP_TXP<9>")
	)
	(segment
		(start 138.511534 -84.727288)
		(end 138.5443 -84.727288)
		(width 0.0889)
		(layer "B.Cu")
		(net "P3E_CPU1_PE3_MP_TXP<9>")
	)
	(segment
		(start 127.357632 -87.203534)
		(end 127.390398 -87.203534)
		(width 0.0889)
		(layer "B.Cu")
		(net "P3E_CPU1_PE3_MP_TXP<9>")
	)
	(segment
		(start 141.482318 -94.32417)
		(end 141.48816 -94.335092)
		(width 0.0889)
		(layer "B.Cu")
		(net "P3E_CPU1_PE3_MP_TXP<9>")
	)
	(segment
		(start 124.452888 -89.300304)
		(end 124.446538 -89.289636)
		(width 0.0889)
		(layer "B.Cu")
		(net "P3E_CPU1_PE3_MP_TXP<9>")
	)
	(segment
		(start 141.37259 -93.373956)
		(end 141.37259 -94.080076)
		(width 0.0889)
		(layer "B.Cu")
		(net "P3E_CPU1_PE3_MP_TXP<9>")
	)
	(segment
		(start 122.219466 -103.08336)
		(end 122.219466 -102.940358)
		(width 0.0889)
		(layer "B.Cu")
		(net "P3E_CPU1_PE3_MP_TXP<9>")
	)
	(segment
		(start 25.395936 -107.195366)
		(end 27.530298 -109.32922)
		(width 0.1143)
		(layer "B.Cu")
		(net "P3E_CPU1_PE3_MP_TXP<9>")
	)
	(segment
		(start 123.00839 -102.151434)
		(end 123.133866 -102.025704)
		(width 0.0889)
		(layer "B.Cu")
		(net "P3E_CPU1_PE3_MP_TXP<9>")
	)
	(segment
		(start 124.452888 -99.206304)
		(end 124.446538 -99.195636)
		(width 0.0889)
		(layer "B.Cu")
		(net "P3E_CPU1_PE3_MP_TXP<9>")
	)
	(segment
		(start 31.077408 -110.706154)
		(end 32.795718 -111.418116)
		(width 0.1143)
		(layer "B.Cu")
		(net "P3E_CPU1_PE3_MP_TXP<9>")
	)
	(segment
		(start 35.888422 -111.418116)
		(end 53.474112 -109.68609)
		(width 0.1143)
		(layer "B.Cu")
		(net "P3E_CPU1_PE3_MP_TXP<9>")
	)
	(segment
		(start 141.445234 -89.374218)
		(end 141.451584 -89.384886)
		(width 0.0889)
		(layer "B.Cu")
		(net "P3E_CPU1_PE3_MP_TXP<9>")
	)
	(segment
		(start 83.888072 -103.606092)
		(end 88.418924 -104.511856)
		(width 0.1143)
		(layer "B.Cu")
		(net "P3E_CPU1_PE3_MP_TXP<9>")
	)
	(segment
		(start 141.451584 -88.394286)
		(end 141.45641 -88.402922)
		(width 0.0889)
		(layer "B.Cu")
		(net "P3E_CPU1_PE3_MP_TXP<9>")
	)
	(segment
		(start 141.37259 -93.023436)
		(end 141.28623 -93.109796)
		(width 0.0889)
		(layer "B.Cu")
		(net "P3E_CPU1_PE3_MP_TXP<9>")
	)
	(segment
		(start 123.402852 -101.756718)
		(end 123.528328 -101.631242)
		(width 0.0889)
		(layer "B.Cu")
		(net "P3E_CPU1_PE3_MP_TXP<9>")
	)
	(segment
		(start 120.785382 -104.41051)
		(end 120.785382 -104.39527)
		(width 0.0889)
		(layer "B.Cu")
		(net "P3E_CPU1_PE3_MP_TXP<9>")
	)
	(segment
		(start 141.48816 -94.740984)
		(end 141.482318 -94.751906)
		(width 0.0889)
		(layer "B.Cu")
		(net "P3E_CPU1_PE3_MP_TXP<9>")
	)
	(segment
		(start 141.445234 -88.383618)
		(end 141.451584 -88.394286)
		(width 0.0889)
		(layer "B.Cu")
		(net "P3E_CPU1_PE3_MP_TXP<9>")
	)
	(segment
		(start 122.613928 -102.545896)
		(end 122.739404 -102.420166)
		(width 0.0889)
		(layer "B.Cu")
		(net "P3E_CPU1_PE3_MP_TXP<9>")
	)
	(segment
		(start 19.03349 -100.29825)
		(end 20.821396 -100.29825)
		(width 0.1143)
		(layer "B.Cu")
		(net "P3E_CPU1_PE3_MP_TXP<9>")
	)
	(segment
		(start 141.445234 -87.393018)
		(end 141.451584 -87.403686)
		(width 0.0889)
		(layer "B.Cu")
		(net "P3E_CPU1_PE3_MP_TXP<9>")
	)
	(segment
		(start 141.37259 -90.08999)
		(end 141.37259 -90.390218)
		(width 0.0889)
		(layer "B.Cu")
		(net "P3E_CPU1_PE3_MP_TXP<9>")
	)
	(segment
		(start 141.37259 -90.723974)
		(end 141.37259 -90.910156)
		(width 0.0889)
		(layer "B.Cu")
		(net "P3E_CPU1_PE3_MP_TXP<9>")
	)
	(segment
		(start 97.281746 -106.981752)
		(end 102.211378 -105.995978)
		(width 0.1143)
		(layer "B.Cu")
		(net "P3E_CPU1_PE3_MP_TXP<9>")
	)
	(segment
		(start 140.25753 -96.423988)
		(end 140.224764 -96.423988)
		(width 0.0889)
		(layer "B.Cu")
		(net "P3E_CPU1_PE3_MP_TXP<9>")
	)
	(segment
		(start 141.37259 -92.845636)
		(end 141.37259 -93.023436)
		(width 0.0889)
		(layer "B.Cu")
		(net "P3E_CPU1_PE3_MP_TXP<9>")
	)
	(segment
		(start 120.785128 -104.374696)
		(end 121.95048 -103.20909)
		(width 0.0889)
		(layer "B.Cu")
		(net "P3E_CPU1_PE3_MP_TXP<9>")
	)
	(segment
		(start 30.269434 -109.89818)
		(end 31.077408 -110.706154)
		(width 0.1143)
		(layer "B.Cu")
		(net "P3E_CPU1_PE3_MP_TXP<9>")
	)
	(segment
		(start 141.083284 -86.212934)
		(end 141.11605 -86.212934)
		(width 0.0889)
		(layer "B.Cu")
		(net "P3E_CPU1_PE3_MP_TXP<9>")
	)
	(segment
		(start 124.446538 -94.833186)
		(end 124.452888 -94.822518)
		(width 0.0889)
		(layer "B.Cu")
		(net "P3E_CPU1_PE3_MP_TXP<9>")
	)
	(segment
		(start 141.28623 -91.174316)
		(end 141.37259 -91.260676)
		(width 0.0889)
		(layer "B.Cu")
		(net "P3E_CPU1_PE3_MP_TXP<9>")
	)
	(segment
		(start 25.395936 -106.483404)
		(end 25.395936 -107.195366)
		(width 0.1143)
		(layer "B.Cu")
		(net "P3E_CPU1_PE3_MP_TXP<9>")
	)
	(segment
		(start 105.831132 -106.719878)
		(end 109.155484 -106.055414)
		(width 0.1143)
		(layer "B.Cu")
		(net "P3E_CPU1_PE3_MP_TXP<9>")
	)
	(segment
		(start 122.488198 -102.814628)
		(end 122.613928 -102.688898)
		(width 0.0889)
		(layer "B.Cu")
		(net "P3E_CPU1_PE3_MP_TXP<9>")
	)
	(segment
		(start 139.366244 -85.222334)
		(end 139.39901 -85.222334)
		(width 0.0889)
		(layer "B.Cu")
		(net "P3E_CPU1_PE3_MP_TXP<9>")
	)
	(segment
		(start 141.294612 -90.468196)
		(end 141.294612 -90.645996)
		(width 0.0889)
		(layer "B.Cu")
		(net "P3E_CPU1_PE3_MP_TXP<9>")
	)
	(segment
		(start 129.074672 -86.212934)
		(end 129.107438 -86.212934)
		(width 0.0889)
		(layer "B.Cu")
		(net "P3E_CPU1_PE3_MP_TXP<9>")
	)
	(segment
		(start 119.791988 -105.403904)
		(end 120.777254 -104.418638)
		(width 0.1143)
		(layer "B.Cu")
		(net "P3E_CPU1_PE3_MP_TXP<9>")
	)
	(segment
		(start 123.277122 -102.025704)
		(end 123.402852 -101.899974)
		(width 0.0889)
		(layer "B.Cu")
		(net "P3E_CPU1_PE3_MP_TXP<9>")
	)
	(segment
		(start 18.72742 -100.60432)
		(end 19.03349 -100.29825)
		(width 0.1143)
		(layer "B.Cu")
		(net "P3E_CPU1_PE3_MP_TXP<9>")
	)
	(segment
		(start 124.446538 -94.242636)
		(end 124.441712 -94.234)
		(width 0.0889)
		(layer "B.Cu")
		(net "P3E_CPU1_PE3_MP_TXP<9>")
	)
	(segment
		(start 122.613928 -102.688898)
		(end 122.613928 -102.545896)
		(width 0.0889)
		(layer "B.Cu")
		(net "P3E_CPU1_PE3_MP_TXP<9>")
	)
	(arc
		(start 139.734544 -85.422486)
		(mid 139.943152 -85.634418)
		(end 140.228574 -85.717888)
		(width 0.0889)
		(layer "B.Cu")
		(net "P3E_CPU1_PE3_MP_TXP<9>")
	)
	(arc
		(start 127.022098 -87.403686)
		(mid 127.163781 -87.259882)
		(end 127.357632 -87.203534)
		(width 0.0889)
		(layer "B.Cu")
		(net "P3E_CPU1_PE3_MP_TXP<9>")
	)
	(arc
		(start 124.446538 -96.814386)
		(mid 124.52576 -96.525268)
		(end 124.452888 -96.234504)
		(width 0.0889)
		(layer "B.Cu")
		(net "P3E_CPU1_PE3_MP_TXP<9>")
	)
	(arc
		(start 141.451584 -89.784682)
		(mid 141.391316 -89.931966)
		(end 141.37259 -90.08999)
		(width 0.0889)
		(layer "B.Cu")
		(net "P3E_CPU1_PE3_MP_TXP<9>")
	)
	(arc
		(start 130.824478 -85.222334)
		(mid 131.107695 -85.138053)
		(end 131.314698 -84.927186)
		(width 0.0889)
		(layer "B.Cu")
		(net "P3E_CPU1_PE3_MP_TXP<9>")
	)
	(arc
		(start 139.734544 -96.719136)
		(mid 139.612599 -96.850168)
		(end 139.445746 -96.91497)
		(width 0.0889)
		(layer "B.Cu")
		(net "P3E_CPU1_PE3_MP_TXP<9>")
	)
	(arc
		(start 140.593064 -85.917786)
		(mid 140.800068 -86.12865)
		(end 141.083284 -86.212934)
		(width 0.0889)
		(layer "B.Cu")
		(net "P3E_CPU1_PE3_MP_TXP<9>")
	)
	(arc
		(start 141.45641 -88.402922)
		(mid 141.505165 -88.599274)
		(end 141.451584 -88.794336)
		(width 0.0889)
		(layer "B.Cu")
		(net "P3E_CPU1_PE3_MP_TXP<9>")
	)
	(arc
		(start 141.451584 -88.794336)
		(mid 141.372362 -89.083454)
		(end 141.445234 -89.374218)
		(width 0.0889)
		(layer "B.Cu")
		(net "P3E_CPU1_PE3_MP_TXP<9>")
	)
	(arc
		(start 124.441712 -91.2622)
		(mid 124.392957 -91.065848)
		(end 124.446538 -90.870786)
		(width 0.0889)
		(layer "B.Cu")
		(net "P3E_CPU1_PE3_MP_TXP<9>")
	)
	(arc
		(start 124.452888 -94.822518)
		(mid 124.525686 -94.531755)
		(end 124.446538 -94.242636)
		(width 0.0889)
		(layer "B.Cu")
		(net "P3E_CPU1_PE3_MP_TXP<9>")
	)
	(arc
		(start 124.441712 -97.2058)
		(mid 124.392957 -97.009448)
		(end 124.446538 -96.814386)
		(width 0.0889)
		(layer "B.Cu")
		(net "P3E_CPU1_PE3_MP_TXP<9>")
	)
	(arc
		(start 134.258304 -83.241134)
		(mid 134.541521 -83.156853)
		(end 134.748524 -82.945986)
		(width 0.0889)
		(layer "B.Cu")
		(net "P3E_CPU1_PE3_MP_TXP<9>")
	)
	(arc
		(start 124.811028 -88.689688)
		(mid 125.096452 -88.606221)
		(end 125.305058 -88.394286)
		(width 0.0889)
		(layer "B.Cu")
		(net "P3E_CPU1_PE3_MP_TXP<9>")
	)
	(arc
		(start 124.446538 -90.870786)
		(mid 124.52576 -90.581668)
		(end 124.452888 -90.290904)
		(width 0.0889)
		(layer "B.Cu")
		(net "P3E_CPU1_PE3_MP_TXP<9>")
	)
	(arc
		(start 124.441712 -99.187)
		(mid 124.392957 -98.990648)
		(end 124.446538 -98.795586)
		(width 0.0889)
		(layer "B.Cu")
		(net "P3E_CPU1_PE3_MP_TXP<9>")
	)
	(arc
		(start 124.446538 -89.880186)
		(mid 124.52576 -89.591068)
		(end 124.452888 -89.300304)
		(width 0.0889)
		(layer "B.Cu")
		(net "P3E_CPU1_PE3_MP_TXP<9>")
	)
	(arc
		(start 124.441712 -100.1776)
		(mid 124.392957 -99.981248)
		(end 124.446538 -99.786186)
		(width 0.0889)
		(layer "B.Cu")
		(net "P3E_CPU1_PE3_MP_TXP<9>")
	)
	(arc
		(start 141.482318 -94.751906)
		(mid 141.415459 -95.03939)
		(end 141.48816 -95.325438)
		(width 0.0889)
		(layer "B.Cu")
		(net "P3E_CPU1_PE3_MP_TXP<9>")
	)
	(arc
		(start 124.441712 -96.2152)
		(mid 124.392957 -96.018848)
		(end 124.446538 -95.823786)
		(width 0.0889)
		(layer "B.Cu")
		(net "P3E_CPU1_PE3_MP_TXP<9>")
	)
	(arc
		(start 138.017504 -84.431886)
		(mid 138.226112 -84.643818)
		(end 138.511534 -84.727288)
		(width 0.0889)
		(layer "B.Cu")
		(net "P3E_CPU1_PE3_MP_TXP<9>")
	)
	(arc
		(start 131.679188 -84.727288)
		(mid 131.964612 -84.643821)
		(end 132.173218 -84.431886)
		(width 0.0889)
		(layer "B.Cu")
		(net "P3E_CPU1_PE3_MP_TXP<9>")
	)
	(arc
		(start 132.17652 -84.426044)
		(mid 132.322486 -84.283645)
		(end 132.519674 -84.231734)
		(width 0.0889)
		(layer "B.Cu")
		(net "P3E_CPU1_PE3_MP_TXP<9>")
	)
	(arc
		(start 128.245108 -86.708488)
		(mid 128.530532 -86.625021)
		(end 128.739138 -86.413086)
		(width 0.0889)
		(layer "B.Cu")
		(net "P3E_CPU1_PE3_MP_TXP<9>")
	)
	(arc
		(start 141.11605 -86.212934)
		(mid 141.454219 -86.417732)
		(end 141.451584 -86.813136)
		(width 0.0889)
		(layer "B.Cu")
		(net "P3E_CPU1_PE3_MP_TXP<9>")
	)
	(arc
		(start 125.305058 -88.394286)
		(mid 125.446741 -88.250482)
		(end 125.640592 -88.194134)
		(width 0.0889)
		(layer "B.Cu")
		(net "P3E_CPU1_PE3_MP_TXP<9>")
	)
	(arc
		(start 124.446538 -97.804986)
		(mid 124.52576 -97.515868)
		(end 124.452888 -97.225104)
		(width 0.0889)
		(layer "B.Cu")
		(net "P3E_CPU1_PE3_MP_TXP<9>")
	)
	(arc
		(start 135.96493 -83.241134)
		(mid 136.15878 -83.297484)
		(end 136.300464 -83.441286)
		(width 0.0889)
		(layer "B.Cu")
		(net "P3E_CPU1_PE3_MP_TXP<9>")
	)
	(arc
		(start 141.451584 -86.813136)
		(mid 141.372362 -87.102254)
		(end 141.445234 -87.393018)
		(width 0.0889)
		(layer "B.Cu")
		(net "P3E_CPU1_PE3_MP_TXP<9>")
	)
	(arc
		(start 141.45641 -87.412322)
		(mid 141.505165 -87.608674)
		(end 141.451584 -87.803736)
		(width 0.0889)
		(layer "B.Cu")
		(net "P3E_CPU1_PE3_MP_TXP<9>")
	)
	(arc
		(start 133.890004 -83.441286)
		(mid 134.031687 -83.297482)
		(end 134.225538 -83.241134)
		(width 0.0889)
		(layer "B.Cu")
		(net "P3E_CPU1_PE3_MP_TXP<9>")
	)
	(arc
		(start 133.395974 -83.736688)
		(mid 133.681398 -83.653221)
		(end 133.890004 -83.441286)
		(width 0.0889)
		(layer "B.Cu")
		(net "P3E_CPU1_PE3_MP_TXP<9>")
	)
	(arc
		(start 139.39901 -85.222334)
		(mid 139.59286 -85.278684)
		(end 139.734544 -85.422486)
		(width 0.0889)
		(layer "B.Cu")
		(net "P3E_CPU1_PE3_MP_TXP<9>")
	)
	(arc
		(start 131.314698 -84.927186)
		(mid 131.454777 -84.78445)
		(end 131.646422 -84.727288)
		(width 0.0889)
		(layer "B.Cu")
		(net "P3E_CPU1_PE3_MP_TXP<9>")
	)
	(arc
		(start 129.107438 -86.212934)
		(mid 129.390655 -86.128653)
		(end 129.597658 -85.917786)
		(width 0.0889)
		(layer "B.Cu")
		(net "P3E_CPU1_PE3_MP_TXP<9>")
	)
	(arc
		(start 129.597658 -85.917786)
		(mid 129.737737 -85.77505)
		(end 129.929382 -85.717888)
		(width 0.0889)
		(layer "B.Cu")
		(net "P3E_CPU1_PE3_MP_TXP<9>")
	)
	(arc
		(start 124.446538 -91.861386)
		(mid 124.52576 -91.572268)
		(end 124.452888 -91.281504)
		(width 0.0889)
		(layer "B.Cu")
		(net "P3E_CPU1_PE3_MP_TXP<9>")
	)
	(arc
		(start 141.451584 -87.803736)
		(mid 141.372362 -88.092854)
		(end 141.445234 -88.383618)
		(width 0.0889)
		(layer "B.Cu")
		(net "P3E_CPU1_PE3_MP_TXP<9>")
	)
	(arc
		(start 135.11022 -82.746088)
		(mid 135.301862 -82.803254)
		(end 135.441944 -82.945986)
		(width 0.0889)
		(layer "B.Cu")
		(net "P3E_CPU1_PE3_MP_TXP<9>")
	)
	(arc
		(start 124.441712 -98.1964)
		(mid 124.392957 -98.000048)
		(end 124.446538 -97.804986)
		(width 0.0889)
		(layer "B.Cu")
		(net "P3E_CPU1_PE3_MP_TXP<9>")
	)
	(arc
		(start 134.748524 -82.945986)
		(mid 134.888603 -82.80325)
		(end 135.080248 -82.746088)
		(width 0.0889)
		(layer "B.Cu")
		(net "P3E_CPU1_PE3_MP_TXP<9>")
	)
	(arc
		(start 124.446538 -92.851986)
		(mid 124.52576 -92.562868)
		(end 124.452888 -92.272104)
		(width 0.0889)
		(layer "B.Cu")
		(net "P3E_CPU1_PE3_MP_TXP<9>")
	)
	(arc
		(start 124.446538 -98.795586)
		(mid 124.52576 -98.506468)
		(end 124.452888 -98.215704)
		(width 0.0889)
		(layer "B.Cu")
		(net "P3E_CPU1_PE3_MP_TXP<9>")
	)
	(arc
		(start 123.952508 -101.072188)
		(mid 124.450759 -100.769348)
		(end 124.446538 -100.186236)
		(width 0.0889)
		(layer "B.Cu")
		(net "P3E_CPU1_PE3_MP_TXP<9>")
	)
	(arc
		(start 137.68197 -84.231734)
		(mid 137.87582 -84.288084)
		(end 138.017504 -84.431886)
		(width 0.0889)
		(layer "B.Cu")
		(net "P3E_CPU1_PE3_MP_TXP<9>")
	)
	(arc
		(start 135.441944 -82.945986)
		(mid 135.648948 -83.15685)
		(end 135.932164 -83.241134)
		(width 0.0889)
		(layer "B.Cu")
		(net "P3E_CPU1_PE3_MP_TXP<9>")
	)
	(arc
		(start 138.5443 -84.727288)
		(mid 138.735942 -84.784454)
		(end 138.876024 -84.927186)
		(width 0.0889)
		(layer "B.Cu")
		(net "P3E_CPU1_PE3_MP_TXP<9>")
	)
	(arc
		(start 126.163578 -87.898986)
		(mid 126.303657 -87.75625)
		(end 126.495302 -87.699088)
		(width 0.0889)
		(layer "B.Cu")
		(net "P3E_CPU1_PE3_MP_TXP<9>")
	)
	(arc
		(start 133.031484 -83.936586)
		(mid 133.171563 -83.79385)
		(end 133.363208 -83.736688)
		(width 0.0889)
		(layer "B.Cu")
		(net "P3E_CPU1_PE3_MP_TXP<9>")
	)
	(arc
		(start 124.446538 -93.842586)
		(mid 124.52576 -93.553468)
		(end 124.452888 -93.262704)
		(width 0.0889)
		(layer "B.Cu")
		(net "P3E_CPU1_PE3_MP_TXP<9>")
	)
	(arc
		(start 124.441712 -93.2434)
		(mid 124.392957 -93.047048)
		(end 124.446538 -92.851986)
		(width 0.0889)
		(layer "B.Cu")
		(net "P3E_CPU1_PE3_MP_TXP<9>")
	)
	(arc
		(start 124.441712 -94.234)
		(mid 124.392957 -94.037648)
		(end 124.446538 -93.842586)
		(width 0.0889)
		(layer "B.Cu")
		(net "P3E_CPU1_PE3_MP_TXP<9>")
	)
	(arc
		(start 124.446538 -95.823786)
		(mid 124.525669 -95.528384)
		(end 124.446538 -95.232982)
		(width 0.0889)
		(layer "B.Cu")
		(net "P3E_CPU1_PE3_MP_TXP<9>")
	)
	(arc
		(start 140.26134 -85.717888)
		(mid 140.452982 -85.775054)
		(end 140.593064 -85.917786)
		(width 0.0889)
		(layer "B.Cu")
		(net "P3E_CPU1_PE3_MP_TXP<9>")
	)
	(arc
		(start 124.446538 -95.232982)
		(mid 124.393039 -95.033084)
		(end 124.446538 -94.833186)
		(width 0.0889)
		(layer "B.Cu")
		(net "P3E_CPU1_PE3_MP_TXP<9>")
	)
	(arc
		(start 140.224764 -96.423988)
		(mid 139.941547 -96.508269)
		(end 139.734544 -96.719136)
		(width 0.0889)
		(layer "B.Cu")
		(net "P3E_CPU1_PE3_MP_TXP<9>")
	)
	(arc
		(start 132.541264 -84.231734)
		(mid 132.824481 -84.147453)
		(end 133.031484 -83.936586)
		(width 0.0889)
		(layer "B.Cu")
		(net "P3E_CPU1_PE3_MP_TXP<9>")
	)
	(arc
		(start 127.880618 -86.908386)
		(mid 128.020697 -86.76565)
		(end 128.212342 -86.708488)
		(width 0.0889)
		(layer "B.Cu")
		(net "P3E_CPU1_PE3_MP_TXP<9>")
	)
	(arc
		(start 126.528068 -87.699088)
		(mid 126.813492 -87.615621)
		(end 127.022098 -87.403686)
		(width 0.0889)
		(layer "B.Cu")
		(net "P3E_CPU1_PE3_MP_TXP<9>")
	)
	(arc
		(start 136.300464 -83.441286)
		(mid 136.509072 -83.653218)
		(end 136.794494 -83.736688)
		(width 0.0889)
		(layer "B.Cu")
		(net "P3E_CPU1_PE3_MP_TXP<9>")
	)
	(arc
		(start 136.82726 -83.736688)
		(mid 137.018902 -83.793854)
		(end 137.158984 -83.936586)
		(width 0.0889)
		(layer "B.Cu")
		(net "P3E_CPU1_PE3_MP_TXP<9>")
	)
	(arc
		(start 128.739138 -86.413086)
		(mid 128.880821 -86.269282)
		(end 129.074672 -86.212934)
		(width 0.0889)
		(layer "B.Cu")
		(net "P3E_CPU1_PE3_MP_TXP<9>")
	)
	(arc
		(start 130.456178 -85.422486)
		(mid 130.597861 -85.278682)
		(end 130.791712 -85.222334)
		(width 0.0889)
		(layer "B.Cu")
		(net "P3E_CPU1_PE3_MP_TXP<9>")
	)
	(arc
		(start 124.441712 -90.2716)
		(mid 124.392957 -90.075248)
		(end 124.446538 -89.880186)
		(width 0.0889)
		(layer "B.Cu")
		(net "P3E_CPU1_PE3_MP_TXP<9>")
	)
	(arc
		(start 125.673358 -88.194134)
		(mid 125.956575 -88.109853)
		(end 126.163578 -87.898986)
		(width 0.0889)
		(layer "B.Cu")
		(net "P3E_CPU1_PE3_MP_TXP<9>")
	)
	(arc
		(start 124.441712 -92.2528)
		(mid 124.392957 -92.056448)
		(end 124.446538 -91.861386)
		(width 0.0889)
		(layer "B.Cu")
		(net "P3E_CPU1_PE3_MP_TXP<9>")
	)
	(arc
		(start 141.087094 -95.928434)
		(mid 140.80167 -96.011901)
		(end 140.593064 -96.223836)
		(width 0.0889)
		(layer "B.Cu")
		(net "P3E_CPU1_PE3_MP_TXP<9>")
	)
	(arc
		(start 138.876024 -84.927186)
		(mid 139.083028 -85.13805)
		(end 139.366244 -85.222334)
		(width 0.0889)
		(layer "B.Cu")
		(net "P3E_CPU1_PE3_MP_TXP<9>")
	)
	(arc
		(start 127.390398 -87.203534)
		(mid 127.673615 -87.119253)
		(end 127.880618 -86.908386)
		(width 0.0889)
		(layer "B.Cu")
		(net "P3E_CPU1_PE3_MP_TXP<9>")
	)
	(arc
		(start 141.48816 -95.325438)
		(mid 141.512951 -95.67464)
		(end 141.271752 -95.928434)
		(width 0.0889)
		(layer "B.Cu")
		(net "P3E_CPU1_PE3_MP_TXP<9>")
	)
	(arc
		(start 124.441712 -89.281)
		(mid 124.445459 -88.891744)
		(end 124.778262 -88.689688)
		(width 0.0889)
		(layer "B.Cu")
		(net "P3E_CPU1_PE3_MP_TXP<9>")
	)
	(arc
		(start 129.962148 -85.717888)
		(mid 130.247572 -85.634421)
		(end 130.456178 -85.422486)
		(width 0.0889)
		(layer "B.Cu")
		(net "P3E_CPU1_PE3_MP_TXP<9>")
	)
	(arc
		(start 141.451584 -89.384886)
		(mid 141.505054 -89.579949)
		(end 141.45641 -89.7763)
		(width 0.0889)
		(layer "B.Cu")
		(net "P3E_CPU1_PE3_MP_TXP<9>")
	)
	(arc
		(start 124.446538 -99.786186)
		(mid 124.52576 -99.497068)
		(end 124.452888 -99.206304)
		(width 0.0889)
		(layer "B.Cu")
		(net "P3E_CPU1_PE3_MP_TXP<9>")
	)
	(arc
		(start 140.593064 -96.223836)
		(mid 140.451381 -96.36764)
		(end 140.25753 -96.423988)
		(width 0.0889)
		(layer "B.Cu")
		(net "P3E_CPU1_PE3_MP_TXP<9>")
	)
	(arc
		(start 141.48816 -94.335092)
		(mid 141.538573 -94.538038)
		(end 141.48816 -94.740984)
		(width 0.0889)
		(layer "B.Cu")
		(net "P3E_CPU1_PE3_MP_TXP<9>")
	)
	(arc
		(start 137.158984 -83.936586)
		(mid 137.365988 -84.14745)
		(end 137.649204 -84.231734)
		(width 0.0889)
		(layer "B.Cu")
		(net "P3E_CPU1_PE3_MP_TXP<9>")
	)
	(segment
		(start 137.957814 -97.014538)
		(end 138.529314 -97.014538)
		(width 0.1143)
		(layer "F.Cu")
		(net "P3E_CPU1_PE3_MP_TXP<8>")
	)
	(via
		(at 17.653 -98.5647)
		(size 0.508)
		(drill 0.254)
		(layers "F.Cu" "B.Cu")
		(net "P3E_CPU1_PE3_MP_TXP<8>")
	)
	(via
		(at 138.529314 -97.014538)
		(size 0.508)
		(drill 0.254)
		(layers "F.Cu" "B.Cu")
		(net "P3E_CPU1_PE3_MP_TXP<8>")
	)
	(segment
		(start 121.444512 -102.474776)
		(end 121.322338 -102.474776)
		(width 0.0889)
		(layer "B.Cu")
		(net "P3E_CPU1_PE3_MP_TXP<8>")
	)
	(segment
		(start 121.322338 -102.474776)
		(end 121.196862 -102.600252)
		(width 0.0889)
		(layer "B.Cu")
		(net "P3E_CPU1_PE3_MP_TXP<8>")
	)
	(segment
		(start 141.087094 -96.919034)
		(end 141.273022 -96.919034)
		(width 0.0889)
		(layer "B.Cu")
		(net "P3E_CPU1_PE3_MP_TXP<8>")
	)
	(segment
		(start 142.4432 -93.46946)
		(end 142.4432 -92.76334)
		(width 0.0889)
		(layer "B.Cu")
		(net "P3E_CPU1_PE3_MP_TXP<8>")
	)
	(segment
		(start 123.588018 -97.309686)
		(end 123.583192 -97.318322)
		(width 0.0889)
		(layer "B.Cu")
		(net "P3E_CPU1_PE3_MP_TXP<8>")
	)
	(segment
		(start 121.839228 -102.101142)
		(end 121.695972 -102.101142)
		(width 0.0889)
		(layer "B.Cu")
		(net "P3E_CPU1_PE3_MP_TXP<8>")
	)
	(segment
		(start 123.515374 -100.408486)
		(end 123.236736 -100.700586)
		(width 0.0889)
		(layer "B.Cu")
		(net "P3E_CPU1_PE3_MP_TXP<8>")
	)
	(segment
		(start 126.528068 -86.708488)
		(end 126.495302 -86.708488)
		(width 0.0889)
		(layer "B.Cu")
		(net "P3E_CPU1_PE3_MP_TXP<8>")
	)
	(segment
		(start 123.594368 -92.346018)
		(end 123.588018 -92.356686)
		(width 0.0889)
		(layer "B.Cu")
		(net "P3E_CPU1_PE3_MP_TXP<8>")
	)
	(segment
		(start 88.933782 -103.565706)
		(end 83.99145 -102.577392)
		(width 0.1143)
		(layer "B.Cu")
		(net "P3E_CPU1_PE3_MP_TXP<8>")
	)
	(segment
		(start 122.893074 -100.90404)
		(end 122.753882 -101.043232)
		(width 0.0889)
		(layer "B.Cu")
		(net "P3E_CPU1_PE3_MP_TXP<8>")
	)
	(segment
		(start 122.753882 -101.043232)
		(end 122.753882 -101.186488)
		(width 0.0889)
		(layer "B.Cu")
		(net "P3E_CPU1_PE3_MP_TXP<8>")
	)
	(segment
		(start 16.809212 -98.5647)
		(end 17.653 -98.5647)
		(width 0.1143)
		(layer "B.Cu")
		(net "P3E_CPU1_PE3_MP_TXP<8>")
	)
	(segment
		(start 121.196862 -102.600252)
		(end 121.196862 -102.722426)
		(width 0.0889)
		(layer "B.Cu")
		(net "P3E_CPU1_PE3_MP_TXP<8>")
	)
	(segment
		(start 142.4432 -95.497904)
		(end 142.4432 -94.77375)
		(width 0.0889)
		(layer "B.Cu")
		(net "P3E_CPU1_PE3_MP_TXP<8>")
	)
	(segment
		(start 130.824478 -84.231734)
		(end 130.791712 -84.231734)
		(width 0.0889)
		(layer "B.Cu")
		(net "P3E_CPU1_PE3_MP_TXP<8>")
	)
	(segment
		(start 122.628152 -101.312218)
		(end 122.484896 -101.312218)
		(width 0.0889)
		(layer "B.Cu")
		(net "P3E_CPU1_PE3_MP_TXP<8>")
	)
	(segment
		(start 105.627424 -105.659428)
		(end 102.13086 -104.959912)
		(width 0.1143)
		(layer "B.Cu")
		(net "P3E_CPU1_PE3_MP_TXP<8>")
	)
	(segment
		(start 142.35684 -91.09202)
		(end 142.35684 -90.91422)
		(width 0.0889)
		(layer "B.Cu")
		(net "P3E_CPU1_PE3_MP_TXP<8>")
	)
	(segment
		(start 142.35684 -93.55582)
		(end 142.4432 -93.46946)
		(width 0.0889)
		(layer "B.Cu")
		(net "P3E_CPU1_PE3_MP_TXP<8>")
	)
	(segment
		(start 120.823228 -103.09606)
		(end 120.697244 -103.222044)
		(width 0.0889)
		(layer "B.Cu")
		(net "P3E_CPU1_PE3_MP_TXP<8>")
	)
	(segment
		(start 34.71164 -110.452154)
		(end 33.062926 -110.452154)
		(width 0.1143)
		(layer "B.Cu")
		(net "P3E_CPU1_PE3_MP_TXP<8>")
	)
	(segment
		(start 123.588018 -99.290886)
		(end 123.583192 -99.299522)
		(width 0.0889)
		(layer "B.Cu")
		(net "P3E_CPU1_PE3_MP_TXP<8>")
	)
	(segment
		(start 142.4432 -90.10269)
		(end 142.30985 -89.872058)
		(width 0.0889)
		(layer "B.Cu")
		(net "P3E_CPU1_PE3_MP_TXP<8>")
	)
	(segment
		(start 142.35684 -90.91422)
		(end 142.4432 -90.82786)
		(width 0.0889)
		(layer "B.Cu")
		(net "P3E_CPU1_PE3_MP_TXP<8>")
	)
	(segment
		(start 123.588018 -98.300286)
		(end 123.583192 -98.308922)
		(width 0.0889)
		(layer "B.Cu")
		(net "P3E_CPU1_PE3_MP_TXP<8>")
	)
	(segment
		(start 118.62562 -104.47909)
		(end 112.417098 -105.68432)
		(width 0.1143)
		(layer "B.Cu")
		(net "P3E_CPU1_PE3_MP_TXP<8>")
	)
	(segment
		(start 123.594368 -96.308418)
		(end 123.588018 -96.319086)
		(width 0.0889)
		(layer "B.Cu")
		(net "P3E_CPU1_PE3_MP_TXP<8>")
	)
	(segment
		(start 142.303754 -87.319104)
		(end 142.310104 -87.308436)
		(width 0.0889)
		(layer "B.Cu")
		(net "P3E_CPU1_PE3_MP_TXP<8>")
	)
	(segment
		(start 26.367232 -106.794808)
		(end 26.367232 -106.077766)
		(width 0.1143)
		(layer "B.Cu")
		(net "P3E_CPU1_PE3_MP_TXP<8>")
	)
	(segment
		(start 142.303754 -86.328504)
		(end 142.310104 -86.317836)
		(width 0.0889)
		(layer "B.Cu")
		(net "P3E_CPU1_PE3_MP_TXP<8>")
	)
	(segment
		(start 121.070878 -102.84841)
		(end 120.948704 -102.84841)
		(width 0.0889)
		(layer "B.Cu")
		(net "P3E_CPU1_PE3_MP_TXP<8>")
	)
	(segment
		(start 121.964958 -101.832156)
		(end 121.964958 -101.975412)
		(width 0.0889)
		(layer "B.Cu")
		(net "P3E_CPU1_PE3_MP_TXP<8>")
	)
	(segment
		(start 14.678914 -97.682558)
		(end 16.809212 -98.5647)
		(width 0.1143)
		(layer "B.Cu")
		(net "P3E_CPU1_PE3_MP_TXP<8>")
	)
	(segment
		(start 119.577104 -104.22001)
		(end 118.85422 -104.408986)
		(width 0.0889)
		(layer "B.Cu")
		(net "P3E_CPU1_PE3_MP_TXP<8>")
	)
	(segment
		(start 120.32361 -103.595678)
		(end 120.201436 -103.595678)
		(width 0.0889)
		(layer "B.Cu")
		(net "P3E_CPU1_PE3_MP_TXP<8>")
	)
	(segment
		(start 122.35942 -101.58095)
		(end 122.23369 -101.70668)
		(width 0.0889)
		(layer "B.Cu")
		(net "P3E_CPU1_PE3_MP_TXP<8>")
	)
	(segment
		(start 142.35684 -92.49918)
		(end 142.4432 -92.41282)
		(width 0.0889)
		(layer "B.Cu")
		(net "P3E_CPU1_PE3_MP_TXP<8>")
	)
	(segment
		(start 142.342108 -95.776796)
		(end 142.342108 -95.598996)
		(width 0.0889)
		(layer "B.Cu")
		(net "P3E_CPU1_PE3_MP_TXP<8>")
	)
	(segment
		(start 137.68197 -83.241134)
		(end 137.649204 -83.241134)
		(width 0.0889)
		(layer "B.Cu")
		(net "P3E_CPU1_PE3_MP_TXP<8>")
	)
	(segment
		(start 97.209102 -105.944162)
		(end 90.484706 -104.599486)
		(width 0.1143)
		(layer "B.Cu")
		(net "P3E_CPU1_PE3_MP_TXP<8>")
	)
	(segment
		(start 142.310104 -88.88984)
		(end 142.303754 -88.879172)
		(width 0.0889)
		(layer "B.Cu")
		(net "P3E_CPU1_PE3_MP_TXP<8>")
	)
	(segment
		(start 120.823228 -102.973886)
		(end 120.823228 -103.09606)
		(width 0.0889)
		(layer "B.Cu")
		(net "P3E_CPU1_PE3_MP_TXP<8>")
	)
	(segment
		(start 138.236198 -96.845374)
		(end 138.157458 -96.86671)
		(width 0.0889)
		(layer "B.Cu")
		(net "P3E_CPU1_PE3_MP_TXP<8>")
	)
	(segment
		(start 122.23369 -101.70668)
		(end 122.090434 -101.70668)
		(width 0.0889)
		(layer "B.Cu")
		(net "P3E_CPU1_PE3_MP_TXP<8>")
	)
	(segment
		(start 23.151592 -101.078792)
		(end 20.637754 -98.5647)
		(width 0.1143)
		(layer "B.Cu")
		(net "P3E_CPU1_PE3_MP_TXP<8>")
	)
	(segment
		(start 122.484896 -101.312218)
		(end 122.35942 -101.437694)
		(width 0.0889)
		(layer "B.Cu")
		(net "P3E_CPU1_PE3_MP_TXP<8>")
	)
	(segment
		(start 123.956318 -88.194134)
		(end 123.923552 -88.194134)
		(width 0.0889)
		(layer "B.Cu")
		(net "P3E_CPU1_PE3_MP_TXP<8>")
	)
	(segment
		(start 141.97838 -85.717888)
		(end 141.945614 -85.717888)
		(width 0.0889)
		(layer "B.Cu")
		(net "P3E_CPU1_PE3_MP_TXP<8>")
	)
	(segment
		(start 142.35684 -94.68739)
		(end 142.35684 -94.50959)
		(width 0.0889)
		(layer "B.Cu")
		(net "P3E_CPU1_PE3_MP_TXP<8>")
	)
	(segment
		(start 127.390398 -86.212934)
		(end 127.357632 -86.212934)
		(width 0.0889)
		(layer "B.Cu")
		(net "P3E_CPU1_PE3_MP_TXP<8>")
	)
	(segment
		(start 121.570496 -102.226618)
		(end 121.570496 -102.348792)
		(width 0.0889)
		(layer "B.Cu")
		(net "P3E_CPU1_PE3_MP_TXP<8>")
	)
	(segment
		(start 142.4432 -92.76334)
		(end 142.35684 -92.67698)
		(width 0.0889)
		(layer "B.Cu")
		(net "P3E_CPU1_PE3_MP_TXP<8>")
	)
	(segment
		(start 122.753882 -101.186488)
		(end 122.628152 -101.312218)
		(width 0.0889)
		(layer "B.Cu")
		(net "P3E_CPU1_PE3_MP_TXP<8>")
	)
	(segment
		(start 131.679188 -83.736688)
		(end 131.646422 -83.736688)
		(width 0.0889)
		(layer "B.Cu")
		(net "P3E_CPU1_PE3_MP_TXP<8>")
	)
	(segment
		(start 102.13086 -104.959912)
		(end 97.209102 -105.944162)
		(width 0.1143)
		(layer "B.Cu")
		(net "P3E_CPU1_PE3_MP_TXP<8>")
	)
	(segment
		(start 129.962148 -84.727288)
		(end 129.929382 -84.727288)
		(width 0.0889)
		(layer "B.Cu")
		(net "P3E_CPU1_PE3_MP_TXP<8>")
	)
	(segment
		(start 54.195472 -108.53293)
		(end 34.71164 -110.452154)
		(width 0.1143)
		(layer "B.Cu")
		(net "P3E_CPU1_PE3_MP_TXP<8>")
	)
	(segment
		(start 139.39901 -84.231734)
		(end 139.366244 -84.231734)
		(width 0.0889)
		(layer "B.Cu")
		(net "P3E_CPU1_PE3_MP_TXP<8>")
	)
	(segment
		(start 133.391148 -82.746088)
		(end 133.363208 -82.746088)
		(width 0.0889)
		(layer "B.Cu")
		(net "P3E_CPU1_PE3_MP_TXP<8>")
	)
	(segment
		(start 20.637754 -98.5647)
		(end 17.653 -98.5647)
		(width 0.1143)
		(layer "B.Cu")
		(net "P3E_CPU1_PE3_MP_TXP<8>")
	)
	(segment
		(start 123.588018 -100.28174)
		(end 123.515374 -100.408486)
		(width 0.0889)
		(layer "B.Cu")
		(net "P3E_CPU1_PE3_MP_TXP<8>")
	)
	(segment
		(start 142.35684 -92.67698)
		(end 142.35684 -92.49918)
		(width 0.0889)
		(layer "B.Cu")
		(net "P3E_CPU1_PE3_MP_TXP<8>")
	)
	(segment
		(start 134.258304 -82.250534)
		(end 134.225538 -82.250534)
		(width 0.0889)
		(layer "B.Cu")
		(net "P3E_CPU1_PE3_MP_TXP<8>")
	)
	(segment
		(start 123.594368 -97.299018)
		(end 123.588018 -97.309686)
		(width 0.0889)
		(layer "B.Cu")
		(net "P3E_CPU1_PE3_MP_TXP<8>")
	)
	(segment
		(start 120.948704 -102.84841)
		(end 120.823228 -102.973886)
		(width 0.0889)
		(layer "B.Cu")
		(net "P3E_CPU1_PE3_MP_TXP<8>")
	)
	(segment
		(start 28.015438 -108.443014)
		(end 26.367232 -106.794808)
		(width 0.1143)
		(layer "B.Cu")
		(net "P3E_CPU1_PE3_MP_TXP<8>")
	)
	(segment
		(start 14.318742 -97.682558)
		(end 14.678914 -97.682558)
		(width 0.1143)
		(layer "B.Cu")
		(net "P3E_CPU1_PE3_MP_TXP<8>")
	)
	(segment
		(start 142.31493 -88.898476)
		(end 142.310104 -88.88984)
		(width 0.0889)
		(layer "B.Cu")
		(net "P3E_CPU1_PE3_MP_TXP<8>")
	)
	(segment
		(start 142.35684 -92.14866)
		(end 142.35684 -91.97086)
		(width 0.0889)
		(layer "B.Cu")
		(net "P3E_CPU1_PE3_MP_TXP<8>")
	)
	(segment
		(start 142.4432 -94.77375)
		(end 142.35684 -94.68739)
		(width 0.0889)
		(layer "B.Cu")
		(net "P3E_CPU1_PE3_MP_TXP<8>")
	)
	(segment
		(start 142.310104 -87.308436)
		(end 142.31493 -87.2998)
		(width 0.0889)
		(layer "B.Cu")
		(net "P3E_CPU1_PE3_MP_TXP<8>")
	)
	(segment
		(start 120.449594 -103.34752)
		(end 120.449594 -103.469694)
		(width 0.0889)
		(layer "B.Cu")
		(net "P3E_CPU1_PE3_MP_TXP<8>")
	)
	(segment
		(start 142.4432 -96.278446)
		(end 142.4432 -95.877888)
		(width 0.0889)
		(layer "B.Cu")
		(net "P3E_CPU1_PE3_MP_TXP<8>")
	)
	(segment
		(start 142.35684 -91.44254)
		(end 142.4432 -91.35618)
		(width 0.0889)
		(layer "B.Cu")
		(net "P3E_CPU1_PE3_MP_TXP<8>")
	)
	(segment
		(start 132.541264 -83.241134)
		(end 132.519674 -83.241134)
		(width 0.0889)
		(layer "B.Cu")
		(net "P3E_CPU1_PE3_MP_TXP<8>")
	)
	(segment
		(start 120.449594 -103.469694)
		(end 120.32361 -103.595678)
		(width 0.0889)
		(layer "B.Cu")
		(net "P3E_CPU1_PE3_MP_TXP<8>")
	)
	(segment
		(start 142.342108 -95.598996)
		(end 142.4432 -95.497904)
		(width 0.0889)
		(layer "B.Cu")
		(net "P3E_CPU1_PE3_MP_TXP<8>")
	)
	(segment
		(start 118.64721 -104.475026)
		(end 118.62562 -104.47909)
		(width 0.0889)
		(layer "B.Cu")
		(net "P3E_CPU1_PE3_MP_TXP<8>")
	)
	(segment
		(start 123.594368 -99.280218)
		(end 123.588018 -99.290886)
		(width 0.0889)
		(layer "B.Cu")
		(net "P3E_CPU1_PE3_MP_TXP<8>")
	)
	(segment
		(start 121.570496 -102.348792)
		(end 121.444512 -102.474776)
		(width 0.0889)
		(layer "B.Cu")
		(net "P3E_CPU1_PE3_MP_TXP<8>")
	)
	(segment
		(start 142.4432 -91.7067)
		(end 142.35684 -91.62034)
		(width 0.0889)
		(layer "B.Cu")
		(net "P3E_CPU1_PE3_MP_TXP<8>")
	)
	(segment
		(start 123.594368 -90.364818)
		(end 123.588018 -90.375486)
		(width 0.0889)
		(layer "B.Cu")
		(net "P3E_CPU1_PE3_MP_TXP<8>")
	)
	(segment
		(start 31.586678 -109.840522)
		(end 30.757876 -109.01172)
		(width 0.1143)
		(layer "B.Cu")
		(net "P3E_CPU1_PE3_MP_TXP<8>")
	)
	(segment
		(start 142.35684 -91.97086)
		(end 142.4432 -91.8845)
		(width 0.0889)
		(layer "B.Cu")
		(net "P3E_CPU1_PE3_MP_TXP<8>")
	)
	(segment
		(start 121.964958 -101.975412)
		(end 121.839228 -102.101142)
		(width 0.0889)
		(layer "B.Cu")
		(net "P3E_CPU1_PE3_MP_TXP<8>")
	)
	(segment
		(start 142.35684 -93.73362)
		(end 142.35684 -93.55582)
		(width 0.0889)
		(layer "B.Cu")
		(net "P3E_CPU1_PE3_MP_TXP<8>")
	)
	(segment
		(start 138.529314 -97.014538)
		(end 138.236198 -96.845374)
		(width 0.0889)
		(layer "B.Cu")
		(net "P3E_CPU1_PE3_MP_TXP<8>")
	)
	(segment
		(start 24.412194 -104.122982)
		(end 23.151592 -101.078792)
		(width 0.1143)
		(layer "B.Cu")
		(net "P3E_CPU1_PE3_MP_TXP<8>")
	)
	(segment
		(start 14.00302 -97.99828)
		(end 14.318742 -97.682558)
		(width 0.1143)
		(layer "B.Cu")
		(net "P3E_CPU1_PE3_MP_TXP<8>")
	)
	(segment
		(start 142.4432 -95.877888)
		(end 142.342108 -95.776796)
		(width 0.0889)
		(layer "B.Cu")
		(net "P3E_CPU1_PE3_MP_TXP<8>")
	)
	(segment
		(start 132.17652 -83.435444)
		(end 132.173218 -83.441286)
		(width 0.0889)
		(layer "B.Cu")
		(net "P3E_CPU1_PE3_MP_TXP<8>")
	)
	(segment
		(start 135.96493 -82.250534)
		(end 135.932164 -82.250534)
		(width 0.0889)
		(layer "B.Cu")
		(net "P3E_CPU1_PE3_MP_TXP<8>")
	)
	(segment
		(start 121.695972 -102.101142)
		(end 121.570496 -102.226618)
		(width 0.0889)
		(layer "B.Cu")
		(net "P3E_CPU1_PE3_MP_TXP<8>")
	)
	(segment
		(start 142.35684 -91.62034)
		(end 142.35684 -91.44254)
		(width 0.0889)
		(layer "B.Cu")
		(net "P3E_CPU1_PE3_MP_TXP<8>")
	)
	(segment
		(start 125.673358 -87.203534)
		(end 125.640592 -87.203534)
		(width 0.0889)
		(layer "B.Cu")
		(net "P3E_CPU1_PE3_MP_TXP<8>")
	)
	(segment
		(start 112.417098 -105.68432)
		(end 108.95965 -104.992932)
		(width 0.1143)
		(layer "B.Cu")
		(net "P3E_CPU1_PE3_MP_TXP<8>")
	)
	(segment
		(start 123.588018 -95.328486)
		(end 123.583192 -95.337122)
		(width 0.0889)
		(layer "B.Cu")
		(net "P3E_CPU1_PE3_MP_TXP<8>")
	)
	(segment
		(start 142.4432 -92.23502)
		(end 142.35684 -92.14866)
		(width 0.0889)
		(layer "B.Cu")
		(net "P3E_CPU1_PE3_MP_TXP<8>")
	)
	(segment
		(start 123.588018 -96.319086)
		(end 123.583192 -96.327722)
		(width 0.0889)
		(layer "B.Cu")
		(net "P3E_CPU1_PE3_MP_TXP<8>")
	)
	(segment
		(start 142.4432 -94.42323)
		(end 142.4432 -93.81998)
		(width 0.0889)
		(layer "B.Cu")
		(net "P3E_CPU1_PE3_MP_TXP<8>")
	)
	(segment
		(start 118.667276 -104.445308)
		(end 118.64721 -104.475026)
		(width 0.0889)
		(layer "B.Cu")
		(net "P3E_CPU1_PE3_MP_TXP<8>")
	)
	(segment
		(start 120.201436 -103.595678)
		(end 119.577104 -104.22001)
		(width 0.0889)
		(layer "B.Cu")
		(net "P3E_CPU1_PE3_MP_TXP<8>")
	)
	(segment
		(start 30.757876 -109.01172)
		(end 28.015438 -108.443014)
		(width 0.1143)
		(layer "B.Cu")
		(net "P3E_CPU1_PE3_MP_TXP<8>")
	)
	(segment
		(start 142.310104 -86.317836)
		(end 142.31493 -86.3092)
		(width 0.0889)
		(layer "B.Cu")
		(net "P3E_CPU1_PE3_MP_TXP<8>")
	)
	(segment
		(start 123.588018 -89.384886)
		(end 123.583192 -89.393522)
		(width 0.0889)
		(layer "B.Cu")
		(net "P3E_CPU1_PE3_MP_TXP<8>")
	)
	(segment
		(start 33.062926 -110.452154)
		(end 31.586678 -109.840522)
		(width 0.1143)
		(layer "B.Cu")
		(net "P3E_CPU1_PE3_MP_TXP<8>")
	)
	(segment
		(start 123.594368 -89.374218)
		(end 123.588018 -89.384886)
		(width 0.0889)
		(layer "B.Cu")
		(net "P3E_CPU1_PE3_MP_TXP<8>")
	)
	(segment
		(start 120.697244 -103.222044)
		(end 120.57507 -103.222044)
		(width 0.0889)
		(layer "B.Cu")
		(net "P3E_CPU1_PE3_MP_TXP<8>")
	)
	(segment
		(start 141.11605 -85.222334)
		(end 141.083284 -85.222334)
		(width 0.0889)
		(layer "B.Cu")
		(net "P3E_CPU1_PE3_MP_TXP<8>")
	)
	(segment
		(start 124.811028 -87.699088)
		(end 124.778262 -87.699088)
		(width 0.0889)
		(layer "B.Cu")
		(net "P3E_CPU1_PE3_MP_TXP<8>")
	)
	(segment
		(start 129.107438 -85.222334)
		(end 129.074672 -85.222334)
		(width 0.0889)
		(layer "B.Cu")
		(net "P3E_CPU1_PE3_MP_TXP<8>")
	)
	(segment
		(start 123.594368 -98.289618)
		(end 123.588018 -98.300286)
		(width 0.0889)
		(layer "B.Cu")
		(net "P3E_CPU1_PE3_MP_TXP<8>")
	)
	(segment
		(start 139.372848 -97.909634)
		(end 139.40282 -97.909634)
		(width 0.0889)
		(layer "B.Cu")
		(net "P3E_CPU1_PE3_MP_TXP<8>")
	)
	(segment
		(start 142.308072 -96.413574)
		(end 142.4432 -96.278446)
		(width 0.0889)
		(layer "B.Cu")
		(net "P3E_CPU1_PE3_MP_TXP<8>")
	)
	(segment
		(start 123.588018 -94.737936)
		(end 123.594368 -94.748604)
		(width 0.0889)
		(layer "B.Cu")
		(net "P3E_CPU1_PE3_MP_TXP<8>")
	)
	(segment
		(start 123.588018 -91.366086)
		(end 123.583192 -91.374722)
		(width 0.0889)
		(layer "B.Cu")
		(net "P3E_CPU1_PE3_MP_TXP<8>")
	)
	(segment
		(start 142.4432 -91.17838)
		(end 142.35684 -91.09202)
		(width 0.0889)
		(layer "B.Cu")
		(net "P3E_CPU1_PE3_MP_TXP<8>")
	)
	(segment
		(start 142.4432 -91.35618)
		(end 142.4432 -91.17838)
		(width 0.0889)
		(layer "B.Cu")
		(net "P3E_CPU1_PE3_MP_TXP<8>")
	)
	(segment
		(start 140.26134 -84.727288)
		(end 140.228574 -84.727288)
		(width 0.0889)
		(layer "B.Cu")
		(net "P3E_CPU1_PE3_MP_TXP<8>")
	)
	(segment
		(start 123.594368 -93.336618)
		(end 123.588018 -93.347286)
		(width 0.0889)
		(layer "B.Cu")
		(net "P3E_CPU1_PE3_MP_TXP<8>")
	)
	(segment
		(start 120.57507 -103.222044)
		(end 120.449594 -103.34752)
		(width 0.0889)
		(layer "B.Cu")
		(net "P3E_CPU1_PE3_MP_TXP<8>")
	)
	(segment
		(start 142.4432 -90.82786)
		(end 142.4432 -90.10269)
		(width 0.0889)
		(layer "B.Cu")
		(net "P3E_CPU1_PE3_MP_TXP<8>")
	)
	(segment
		(start 136.82726 -82.746088)
		(end 136.79932 -82.746088)
		(width 0.0889)
		(layer "B.Cu")
		(net "P3E_CPU1_PE3_MP_TXP<8>")
	)
	(segment
		(start 123.236736 -100.700586)
		(end 122.893074 -100.90404)
		(width 0.0889)
		(layer "B.Cu")
		(net "P3E_CPU1_PE3_MP_TXP<8>")
	)
	(segment
		(start 140.224764 -97.414588)
		(end 140.25753 -97.414588)
		(width 0.0889)
		(layer "B.Cu")
		(net "P3E_CPU1_PE3_MP_TXP<8>")
	)
	(segment
		(start 123.588018 -90.375486)
		(end 123.583192 -90.384122)
		(width 0.0889)
		(layer "B.Cu")
		(net "P3E_CPU1_PE3_MP_TXP<8>")
	)
	(segment
		(start 123.594368 -91.355418)
		(end 123.588018 -91.366086)
		(width 0.0889)
		(layer "B.Cu")
		(net "P3E_CPU1_PE3_MP_TXP<8>")
	)
	(segment
		(start 142.000986 -96.413574)
		(end 142.308072 -96.413574)
		(width 0.0889)
		(layer "B.Cu")
		(net "P3E_CPU1_PE3_MP_TXP<8>")
	)
	(segment
		(start 108.95965 -104.992932)
		(end 105.627424 -105.659428)
		(width 0.1143)
		(layer "B.Cu")
		(net "P3E_CPU1_PE3_MP_TXP<8>")
	)
	(segment
		(start 142.4432 -92.41282)
		(end 142.4432 -92.23502)
		(width 0.0889)
		(layer "B.Cu")
		(net "P3E_CPU1_PE3_MP_TXP<8>")
	)
	(segment
		(start 142.4432 -91.8845)
		(end 142.4432 -91.7067)
		(width 0.0889)
		(layer "B.Cu")
		(net "P3E_CPU1_PE3_MP_TXP<8>")
	)
	(segment
		(start 26.367232 -106.077766)
		(end 24.412194 -104.122982)
		(width 0.1143)
		(layer "B.Cu")
		(net "P3E_CPU1_PE3_MP_TXP<8>")
	)
	(segment
		(start 121.196862 -102.722426)
		(end 121.070878 -102.84841)
		(width 0.0889)
		(layer "B.Cu")
		(net "P3E_CPU1_PE3_MP_TXP<8>")
	)
	(segment
		(start 138.518138 -97.414588)
		(end 138.550904 -97.414588)
		(width 0.0889)
		(layer "B.Cu")
		(net "P3E_CPU1_PE3_MP_TXP<8>")
	)
	(segment
		(start 135.113268 -81.755488)
		(end 135.0772 -81.755488)
		(width 0.0889)
		(layer "B.Cu")
		(net "P3E_CPU1_PE3_MP_TXP<8>")
	)
	(segment
		(start 128.245108 -85.717888)
		(end 128.212342 -85.717888)
		(width 0.0889)
		(layer "B.Cu")
		(net "P3E_CPU1_PE3_MP_TXP<8>")
	)
	(segment
		(start 118.85422 -104.408986)
		(end 118.667276 -104.445308)
		(width 0.0889)
		(layer "B.Cu")
		(net "P3E_CPU1_PE3_MP_TXP<8>")
	)
	(segment
		(start 122.090434 -101.70668)
		(end 121.964958 -101.832156)
		(width 0.0889)
		(layer "B.Cu")
		(net "P3E_CPU1_PE3_MP_TXP<8>")
	)
	(segment
		(start 142.35684 -94.50959)
		(end 142.4432 -94.42323)
		(width 0.0889)
		(layer "B.Cu")
		(net "P3E_CPU1_PE3_MP_TXP<8>")
	)
	(segment
		(start 123.588018 -93.347286)
		(end 123.583192 -93.355922)
		(width 0.0889)
		(layer "B.Cu")
		(net "P3E_CPU1_PE3_MP_TXP<8>")
	)
	(segment
		(start 90.484706 -104.599486)
		(end 88.933782 -103.565706)
		(width 0.1143)
		(layer "B.Cu")
		(net "P3E_CPU1_PE3_MP_TXP<8>")
	)
	(segment
		(start 122.35942 -101.437694)
		(end 122.35942 -101.58095)
		(width 0.0889)
		(layer "B.Cu")
		(net "P3E_CPU1_PE3_MP_TXP<8>")
	)
	(segment
		(start 138.5443 -83.736688)
		(end 138.511534 -83.736688)
		(width 0.0889)
		(layer "B.Cu")
		(net "P3E_CPU1_PE3_MP_TXP<8>")
	)
	(segment
		(start 83.99145 -102.577392)
		(end 54.195472 -108.53293)
		(width 0.1143)
		(layer "B.Cu")
		(net "P3E_CPU1_PE3_MP_TXP<8>")
	)
	(segment
		(start 142.4432 -93.81998)
		(end 142.35684 -93.73362)
		(width 0.0889)
		(layer "B.Cu")
		(net "P3E_CPU1_PE3_MP_TXP<8>")
	)
	(segment
		(start 123.588018 -92.356686)
		(end 123.583192 -92.365322)
		(width 0.0889)
		(layer "B.Cu")
		(net "P3E_CPU1_PE3_MP_TXP<8>")
	)
	(arc
		(start 129.597658 -84.927186)
		(mid 129.390654 -85.13805)
		(end 129.107438 -85.222334)
		(width 0.0889)
		(layer "B.Cu")
		(net "P3E_CPU1_PE3_MP_TXP<8>")
	)
	(arc
		(start 126.163578 -86.908386)
		(mid 125.956574 -87.11925)
		(end 125.673358 -87.203534)
		(width 0.0889)
		(layer "B.Cu")
		(net "P3E_CPU1_PE3_MP_TXP<8>")
	)
	(arc
		(start 137.158984 -82.945986)
		(mid 137.018905 -82.80325)
		(end 136.82726 -82.746088)
		(width 0.0889)
		(layer "B.Cu")
		(net "P3E_CPU1_PE3_MP_TXP<8>")
	)
	(arc
		(start 135.0772 -81.755488)
		(mid 134.887271 -81.813358)
		(end 134.748524 -81.955386)
		(width 0.0889)
		(layer "B.Cu")
		(net "P3E_CPU1_PE3_MP_TXP<8>")
	)
	(arc
		(start 123.588018 -96.719136)
		(mid 123.66724 -97.008254)
		(end 123.594368 -97.299018)
		(width 0.0889)
		(layer "B.Cu")
		(net "P3E_CPU1_PE3_MP_TXP<8>")
	)
	(arc
		(start 134.748524 -81.955386)
		(mid 134.54152 -82.16625)
		(end 134.258304 -82.250534)
		(width 0.0889)
		(layer "B.Cu")
		(net "P3E_CPU1_PE3_MP_TXP<8>")
	)
	(arc
		(start 123.588018 -98.700336)
		(mid 123.66724 -98.989454)
		(end 123.594368 -99.280218)
		(width 0.0889)
		(layer "B.Cu")
		(net "P3E_CPU1_PE3_MP_TXP<8>")
	)
	(arc
		(start 126.495302 -86.708488)
		(mid 126.30366 -86.765654)
		(end 126.163578 -86.908386)
		(width 0.0889)
		(layer "B.Cu")
		(net "P3E_CPU1_PE3_MP_TXP<8>")
	)
	(arc
		(start 137.649204 -83.241134)
		(mid 137.365987 -83.156853)
		(end 137.158984 -82.945986)
		(width 0.0889)
		(layer "B.Cu")
		(net "P3E_CPU1_PE3_MP_TXP<8>")
	)
	(arc
		(start 123.588018 -97.709736)
		(mid 123.66724 -97.998854)
		(end 123.594368 -98.289618)
		(width 0.0889)
		(layer "B.Cu")
		(net "P3E_CPU1_PE3_MP_TXP<8>")
	)
	(arc
		(start 136.300464 -82.450686)
		(mid 136.158781 -82.306882)
		(end 135.96493 -82.250534)
		(width 0.0889)
		(layer "B.Cu")
		(net "P3E_CPU1_PE3_MP_TXP<8>")
	)
	(arc
		(start 123.583192 -98.308922)
		(mid 123.534437 -98.505274)
		(end 123.588018 -98.700336)
		(width 0.0889)
		(layer "B.Cu")
		(net "P3E_CPU1_PE3_MP_TXP<8>")
	)
	(arc
		(start 142.310104 -89.28989)
		(mid 142.363574 -89.094827)
		(end 142.31493 -88.898476)
		(width 0.0889)
		(layer "B.Cu")
		(net "P3E_CPU1_PE3_MP_TXP<8>")
	)
	(arc
		(start 140.593064 -84.927186)
		(mid 140.452985 -84.78445)
		(end 140.26134 -84.727288)
		(width 0.0889)
		(layer "B.Cu")
		(net "P3E_CPU1_PE3_MP_TXP<8>")
	)
	(arc
		(start 133.363208 -82.746088)
		(mid 133.171566 -82.803254)
		(end 133.031484 -82.945986)
		(width 0.0889)
		(layer "B.Cu")
		(net "P3E_CPU1_PE3_MP_TXP<8>")
	)
	(arc
		(start 129.929382 -84.727288)
		(mid 129.73774 -84.784454)
		(end 129.597658 -84.927186)
		(width 0.0889)
		(layer "B.Cu")
		(net "P3E_CPU1_PE3_MP_TXP<8>")
	)
	(arc
		(start 131.314698 -83.936586)
		(mid 131.107694 -84.14745)
		(end 130.824478 -84.231734)
		(width 0.0889)
		(layer "B.Cu")
		(net "P3E_CPU1_PE3_MP_TXP<8>")
	)
	(arc
		(start 123.588018 -90.775536)
		(mid 123.66724 -91.064654)
		(end 123.594368 -91.355418)
		(width 0.0889)
		(layer "B.Cu")
		(net "P3E_CPU1_PE3_MP_TXP<8>")
	)
	(arc
		(start 139.366244 -84.231734)
		(mid 139.083027 -84.147453)
		(end 138.876024 -83.936586)
		(width 0.0889)
		(layer "B.Cu")
		(net "P3E_CPU1_PE3_MP_TXP<8>")
	)
	(arc
		(start 139.041124 -97.709736)
		(mid 139.181203 -97.852472)
		(end 139.372848 -97.909634)
		(width 0.0889)
		(layer "B.Cu")
		(net "P3E_CPU1_PE3_MP_TXP<8>")
	)
	(arc
		(start 142.31493 -87.2998)
		(mid 142.363685 -87.103448)
		(end 142.310104 -86.908386)
		(width 0.0889)
		(layer "B.Cu")
		(net "P3E_CPU1_PE3_MP_TXP<8>")
	)
	(arc
		(start 133.031484 -82.945986)
		(mid 132.82448 -83.15685)
		(end 132.541264 -83.241134)
		(width 0.0889)
		(layer "B.Cu")
		(net "P3E_CPU1_PE3_MP_TXP<8>")
	)
	(arc
		(start 141.083284 -85.222334)
		(mid 140.800067 -85.138053)
		(end 140.593064 -84.927186)
		(width 0.0889)
		(layer "B.Cu")
		(net "P3E_CPU1_PE3_MP_TXP<8>")
	)
	(arc
		(start 128.212342 -85.717888)
		(mid 128.0207 -85.775054)
		(end 127.880618 -85.917786)
		(width 0.0889)
		(layer "B.Cu")
		(net "P3E_CPU1_PE3_MP_TXP<8>")
	)
	(arc
		(start 142.31493 -86.3092)
		(mid 142.311183 -85.919944)
		(end 141.97838 -85.717888)
		(width 0.0889)
		(layer "B.Cu")
		(net "P3E_CPU1_PE3_MP_TXP<8>")
	)
	(arc
		(start 135.441944 -81.955386)
		(mid 135.3032 -81.813353)
		(end 135.113268 -81.755488)
		(width 0.0889)
		(layer "B.Cu")
		(net "P3E_CPU1_PE3_MP_TXP<8>")
	)
	(arc
		(start 123.583192 -92.365322)
		(mid 123.534437 -92.561674)
		(end 123.588018 -92.756736)
		(width 0.0889)
		(layer "B.Cu")
		(net "P3E_CPU1_PE3_MP_TXP<8>")
	)
	(arc
		(start 130.456178 -84.431886)
		(mid 130.24757 -84.643818)
		(end 129.962148 -84.727288)
		(width 0.0889)
		(layer "B.Cu")
		(net "P3E_CPU1_PE3_MP_TXP<8>")
	)
	(arc
		(start 141.273022 -96.919034)
		(mid 141.39762 -96.839219)
		(end 141.48816 -96.722184)
		(width 0.0889)
		(layer "B.Cu")
		(net "P3E_CPU1_PE3_MP_TXP<8>")
	)
	(arc
		(start 132.173218 -83.441286)
		(mid 131.96461 -83.653218)
		(end 131.679188 -83.736688)
		(width 0.0889)
		(layer "B.Cu")
		(net "P3E_CPU1_PE3_MP_TXP<8>")
	)
	(arc
		(start 123.588018 -93.747336)
		(mid 123.667149 -94.042738)
		(end 123.588018 -94.33814)
		(width 0.0889)
		(layer "B.Cu")
		(net "P3E_CPU1_PE3_MP_TXP<8>")
	)
	(arc
		(start 123.583192 -93.355922)
		(mid 123.534437 -93.552274)
		(end 123.588018 -93.747336)
		(width 0.0889)
		(layer "B.Cu")
		(net "P3E_CPU1_PE3_MP_TXP<8>")
	)
	(arc
		(start 142.310104 -87.898986)
		(mid 142.230882 -87.609868)
		(end 142.303754 -87.319104)
		(width 0.0889)
		(layer "B.Cu")
		(net "P3E_CPU1_PE3_MP_TXP<8>")
	)
	(arc
		(start 141.945614 -85.717888)
		(mid 141.66019 -85.634421)
		(end 141.451584 -85.422486)
		(width 0.0889)
		(layer "B.Cu")
		(net "P3E_CPU1_PE3_MP_TXP<8>")
	)
	(arc
		(start 138.157458 -96.86671)
		(mid 138.195098 -97.234649)
		(end 138.518138 -97.414588)
		(width 0.0889)
		(layer "B.Cu")
		(net "P3E_CPU1_PE3_MP_TXP<8>")
	)
	(arc
		(start 123.588018 -88.794336)
		(mid 123.66724 -89.083454)
		(end 123.594368 -89.374218)
		(width 0.0889)
		(layer "B.Cu")
		(net "P3E_CPU1_PE3_MP_TXP<8>")
	)
	(arc
		(start 125.305058 -87.403686)
		(mid 125.09645 -87.615618)
		(end 124.811028 -87.699088)
		(width 0.0889)
		(layer "B.Cu")
		(net "P3E_CPU1_PE3_MP_TXP<8>")
	)
	(arc
		(start 123.583192 -99.299522)
		(mid 123.534437 -99.495874)
		(end 123.588018 -99.690936)
		(width 0.0889)
		(layer "B.Cu")
		(net "P3E_CPU1_PE3_MP_TXP<8>")
	)
	(arc
		(start 131.646422 -83.736688)
		(mid 131.45478 -83.793854)
		(end 131.314698 -83.936586)
		(width 0.0889)
		(layer "B.Cu")
		(net "P3E_CPU1_PE3_MP_TXP<8>")
	)
	(arc
		(start 139.734544 -97.709736)
		(mid 139.941548 -97.498872)
		(end 140.224764 -97.414588)
		(width 0.0889)
		(layer "B.Cu")
		(net "P3E_CPU1_PE3_MP_TXP<8>")
	)
	(arc
		(start 123.588018 -99.690936)
		(mid 123.667149 -99.986338)
		(end 123.588018 -100.28174)
		(width 0.0889)
		(layer "B.Cu")
		(net "P3E_CPU1_PE3_MP_TXP<8>")
	)
	(arc
		(start 123.588018 -95.728536)
		(mid 123.66724 -96.017654)
		(end 123.594368 -96.308418)
		(width 0.0889)
		(layer "B.Cu")
		(net "P3E_CPU1_PE3_MP_TXP<8>")
	)
	(arc
		(start 138.876024 -83.936586)
		(mid 138.735945 -83.79385)
		(end 138.5443 -83.736688)
		(width 0.0889)
		(layer "B.Cu")
		(net "P3E_CPU1_PE3_MP_TXP<8>")
	)
	(arc
		(start 140.228574 -84.727288)
		(mid 139.94315 -84.643821)
		(end 139.734544 -84.431886)
		(width 0.0889)
		(layer "B.Cu")
		(net "P3E_CPU1_PE3_MP_TXP<8>")
	)
	(arc
		(start 140.593064 -97.214436)
		(mid 140.801672 -97.002504)
		(end 141.087094 -96.919034)
		(width 0.0889)
		(layer "B.Cu")
		(net "P3E_CPU1_PE3_MP_TXP<8>")
	)
	(arc
		(start 127.357632 -86.212934)
		(mid 127.163782 -86.269284)
		(end 127.022098 -86.413086)
		(width 0.0889)
		(layer "B.Cu")
		(net "P3E_CPU1_PE3_MP_TXP<8>")
	)
	(arc
		(start 138.511534 -83.736688)
		(mid 138.22611 -83.653221)
		(end 138.017504 -83.441286)
		(width 0.0889)
		(layer "B.Cu")
		(net "P3E_CPU1_PE3_MP_TXP<8>")
	)
	(arc
		(start 123.583192 -96.327722)
		(mid 123.534437 -96.524074)
		(end 123.588018 -96.719136)
		(width 0.0889)
		(layer "B.Cu")
		(net "P3E_CPU1_PE3_MP_TXP<8>")
	)
	(arc
		(start 138.550904 -97.414588)
		(mid 138.834121 -97.498869)
		(end 139.041124 -97.709736)
		(width 0.0889)
		(layer "B.Cu")
		(net "P3E_CPU1_PE3_MP_TXP<8>")
	)
	(arc
		(start 129.074672 -85.222334)
		(mid 128.880822 -85.278684)
		(end 128.739138 -85.422486)
		(width 0.0889)
		(layer "B.Cu")
		(net "P3E_CPU1_PE3_MP_TXP<8>")
	)
	(arc
		(start 123.583192 -89.393522)
		(mid 123.534437 -89.589874)
		(end 123.588018 -89.784936)
		(width 0.0889)
		(layer "B.Cu")
		(net "P3E_CPU1_PE3_MP_TXP<8>")
	)
	(arc
		(start 123.588018 -89.784936)
		(mid 123.66724 -90.074054)
		(end 123.594368 -90.364818)
		(width 0.0889)
		(layer "B.Cu")
		(net "P3E_CPU1_PE3_MP_TXP<8>")
	)
	(arc
		(start 139.40282 -97.909634)
		(mid 139.594462 -97.852468)
		(end 139.734544 -97.709736)
		(width 0.0889)
		(layer "B.Cu")
		(net "P3E_CPU1_PE3_MP_TXP<8>")
	)
	(arc
		(start 128.739138 -85.422486)
		(mid 128.53053 -85.634418)
		(end 128.245108 -85.717888)
		(width 0.0889)
		(layer "B.Cu")
		(net "P3E_CPU1_PE3_MP_TXP<8>")
	)
	(arc
		(start 142.30985 -89.872058)
		(mid 142.231848 -89.580945)
		(end 142.310104 -89.28989)
		(width 0.0889)
		(layer "B.Cu")
		(net "P3E_CPU1_PE3_MP_TXP<8>")
	)
	(arc
		(start 123.923552 -88.194134)
		(mid 123.585383 -88.398932)
		(end 123.588018 -88.794336)
		(width 0.0889)
		(layer "B.Cu")
		(net "P3E_CPU1_PE3_MP_TXP<8>")
	)
	(arc
		(start 123.588018 -92.756736)
		(mid 123.66724 -93.045854)
		(end 123.594368 -93.336618)
		(width 0.0889)
		(layer "B.Cu")
		(net "P3E_CPU1_PE3_MP_TXP<8>")
	)
	(arc
		(start 141.48816 -96.722184)
		(mid 141.701737 -96.496673)
		(end 142.000986 -96.413574)
		(width 0.0889)
		(layer "B.Cu")
		(net "P3E_CPU1_PE3_MP_TXP<8>")
	)
	(arc
		(start 124.446538 -87.898986)
		(mid 124.239534 -88.10985)
		(end 123.956318 -88.194134)
		(width 0.0889)
		(layer "B.Cu")
		(net "P3E_CPU1_PE3_MP_TXP<8>")
	)
	(arc
		(start 127.022098 -86.413086)
		(mid 126.81349 -86.625018)
		(end 126.528068 -86.708488)
		(width 0.0889)
		(layer "B.Cu")
		(net "P3E_CPU1_PE3_MP_TXP<8>")
	)
	(arc
		(start 132.519674 -83.241134)
		(mid 132.322513 -83.293093)
		(end 132.17652 -83.435444)
		(width 0.0889)
		(layer "B.Cu")
		(net "P3E_CPU1_PE3_MP_TXP<8>")
	)
	(arc
		(start 135.932164 -82.250534)
		(mid 135.648947 -82.166253)
		(end 135.441944 -81.955386)
		(width 0.0889)
		(layer "B.Cu")
		(net "P3E_CPU1_PE3_MP_TXP<8>")
	)
	(arc
		(start 142.310104 -88.29929)
		(mid 142.363764 -88.099138)
		(end 142.310104 -87.898986)
		(width 0.0889)
		(layer "B.Cu")
		(net "P3E_CPU1_PE3_MP_TXP<8>")
	)
	(arc
		(start 141.451584 -85.422486)
		(mid 141.309901 -85.278682)
		(end 141.11605 -85.222334)
		(width 0.0889)
		(layer "B.Cu")
		(net "P3E_CPU1_PE3_MP_TXP<8>")
	)
	(arc
		(start 133.890004 -82.450686)
		(mid 133.679291 -82.663765)
		(end 133.391148 -82.746088)
		(width 0.0889)
		(layer "B.Cu")
		(net "P3E_CPU1_PE3_MP_TXP<8>")
	)
	(arc
		(start 124.778262 -87.699088)
		(mid 124.58662 -87.756254)
		(end 124.446538 -87.898986)
		(width 0.0889)
		(layer "B.Cu")
		(net "P3E_CPU1_PE3_MP_TXP<8>")
	)
	(arc
		(start 142.310104 -86.908386)
		(mid 142.230882 -86.619268)
		(end 142.303754 -86.328504)
		(width 0.0889)
		(layer "B.Cu")
		(net "P3E_CPU1_PE3_MP_TXP<8>")
	)
	(arc
		(start 134.225538 -82.250534)
		(mid 134.031688 -82.306884)
		(end 133.890004 -82.450686)
		(width 0.0889)
		(layer "B.Cu")
		(net "P3E_CPU1_PE3_MP_TXP<8>")
	)
	(arc
		(start 123.583192 -91.374722)
		(mid 123.534437 -91.571074)
		(end 123.588018 -91.766136)
		(width 0.0889)
		(layer "B.Cu")
		(net "P3E_CPU1_PE3_MP_TXP<8>")
	)
	(arc
		(start 123.583192 -90.384122)
		(mid 123.534437 -90.580474)
		(end 123.588018 -90.775536)
		(width 0.0889)
		(layer "B.Cu")
		(net "P3E_CPU1_PE3_MP_TXP<8>")
	)
	(arc
		(start 123.588018 -91.766136)
		(mid 123.66724 -92.055254)
		(end 123.594368 -92.346018)
		(width 0.0889)
		(layer "B.Cu")
		(net "P3E_CPU1_PE3_MP_TXP<8>")
	)
	(arc
		(start 127.880618 -85.917786)
		(mid 127.673614 -86.12865)
		(end 127.390398 -86.212934)
		(width 0.0889)
		(layer "B.Cu")
		(net "P3E_CPU1_PE3_MP_TXP<8>")
	)
	(arc
		(start 123.583192 -95.337122)
		(mid 123.534437 -95.533474)
		(end 123.588018 -95.728536)
		(width 0.0889)
		(layer "B.Cu")
		(net "P3E_CPU1_PE3_MP_TXP<8>")
	)
	(arc
		(start 123.588018 -94.33814)
		(mid 123.534519 -94.538038)
		(end 123.588018 -94.737936)
		(width 0.0889)
		(layer "B.Cu")
		(net "P3E_CPU1_PE3_MP_TXP<8>")
	)
	(arc
		(start 140.25753 -97.414588)
		(mid 140.45138 -97.358238)
		(end 140.593064 -97.214436)
		(width 0.0889)
		(layer "B.Cu")
		(net "P3E_CPU1_PE3_MP_TXP<8>")
	)
	(arc
		(start 123.594368 -94.748604)
		(mid 123.667166 -95.039367)
		(end 123.588018 -95.328486)
		(width 0.0889)
		(layer "B.Cu")
		(net "P3E_CPU1_PE3_MP_TXP<8>")
	)
	(arc
		(start 130.791712 -84.231734)
		(mid 130.597862 -84.288084)
		(end 130.456178 -84.431886)
		(width 0.0889)
		(layer "B.Cu")
		(net "P3E_CPU1_PE3_MP_TXP<8>")
	)
	(arc
		(start 138.017504 -83.441286)
		(mid 137.875821 -83.297482)
		(end 137.68197 -83.241134)
		(width 0.0889)
		(layer "B.Cu")
		(net "P3E_CPU1_PE3_MP_TXP<8>")
	)
	(arc
		(start 139.734544 -84.431886)
		(mid 139.592861 -84.288082)
		(end 139.39901 -84.231734)
		(width 0.0889)
		(layer "B.Cu")
		(net "P3E_CPU1_PE3_MP_TXP<8>")
	)
	(arc
		(start 142.303754 -88.879172)
		(mid 142.230956 -88.588409)
		(end 142.310104 -88.29929)
		(width 0.0889)
		(layer "B.Cu")
		(net "P3E_CPU1_PE3_MP_TXP<8>")
	)
	(arc
		(start 136.79932 -82.746088)
		(mid 136.511175 -82.663769)
		(end 136.300464 -82.450686)
		(width 0.0889)
		(layer "B.Cu")
		(net "P3E_CPU1_PE3_MP_TXP<8>")
	)
	(arc
		(start 123.583192 -97.318322)
		(mid 123.534437 -97.514674)
		(end 123.588018 -97.709736)
		(width 0.0889)
		(layer "B.Cu")
		(net "P3E_CPU1_PE3_MP_TXP<8>")
	)
	(arc
		(start 125.640592 -87.203534)
		(mid 125.446742 -87.259884)
		(end 125.305058 -87.403686)
		(width 0.0889)
		(layer "B.Cu")
		(net "P3E_CPU1_PE3_MP_TXP<8>")
	)
	(segment
		(start 138.816334 -89.584784)
		(end 139.387834 -89.584784)
		(width 0.1143)
		(layer "F.Cu")
		(net "P3E_CPU1_PE3_MP_TXP<15>")
	)
	(via
		(at 139.387834 -89.584784)
		(size 0.508)
		(drill 0.254)
		(layers "F.Cu" "B.Cu")
		(net "P3E_CPU1_PE3_MP_TXP<15>")
	)
	(via
		(at 33.02 -113.4364)
		(size 0.508)
		(drill 0.254)
		(layers "F.Cu" "B.Cu")
		(net "P3E_CPU1_PE3_MP_TXP<15>")
	)
	(segment
		(start 26.582116 -111.149384)
		(end 28.95727 -111.642398)
		(width 0.1143)
		(layer "B.Cu")
		(net "P3E_CPU1_PE3_MP_TXP<15>")
	)
	(segment
		(start 102.5779 -108.09732)
		(end 105.717594 -108.725208)
		(width 0.1143)
		(layer "B.Cu")
		(net "P3E_CPU1_PE3_MP_TXP<15>")
	)
	(segment
		(start 124.202698 -104.462326)
		(end 124.202698 -104.321864)
		(width 0.0889)
		(layer "B.Cu")
		(net "P3E_CPU1_PE3_MP_TXP<15>")
	)
	(segment
		(start 129.074672 -88.194134)
		(end 129.107438 -88.194134)
		(width 0.0889)
		(layer "B.Cu")
		(net "P3E_CPU1_PE3_MP_TXP<15>")
	)
	(segment
		(start 123.6853 -104.979724)
		(end 123.81103 -104.853994)
		(width 0.0889)
		(layer "B.Cu")
		(net "P3E_CPU1_PE3_MP_TXP<15>")
	)
	(segment
		(start 126.169928 -99.206304)
		(end 126.163578 -99.195636)
		(width 0.0889)
		(layer "B.Cu")
		(net "P3E_CPU1_PE3_MP_TXP<15>")
	)
	(segment
		(start 139.728194 -89.374218)
		(end 139.734544 -89.384886)
		(width 0.0889)
		(layer "B.Cu")
		(net "P3E_CPU1_PE3_MP_TXP<15>")
	)
	(segment
		(start 126.495302 -89.680288)
		(end 126.528068 -89.680288)
		(width 0.0889)
		(layer "B.Cu")
		(net "P3E_CPU1_PE3_MP_TXP<15>")
	)
	(segment
		(start 126.163578 -100.186236)
		(end 126.158752 -100.1776)
		(width 0.0889)
		(layer "B.Cu")
		(net "P3E_CPU1_PE3_MP_TXP<15>")
	)
	(segment
		(start 30.290262 -112.533176)
		(end 32.47009 -113.4364)
		(width 0.1143)
		(layer "B.Cu")
		(net "P3E_CPU1_PE3_MP_TXP<15>")
	)
	(segment
		(start 113.112804 -108.994702)
		(end 121.16816 -107.39247)
		(width 0.1143)
		(layer "B.Cu")
		(net "P3E_CPU1_PE3_MP_TXP<15>")
	)
	(segment
		(start 123.027694 -105.63733)
		(end 123.027694 -105.496868)
		(width 0.0889)
		(layer "B.Cu")
		(net "P3E_CPU1_PE3_MP_TXP<15>")
	)
	(segment
		(start 125.894846 -102.629716)
		(end 126.035308 -102.629716)
		(width 0.0889)
		(layer "B.Cu")
		(net "P3E_CPU1_PE3_MP_TXP<15>")
	)
	(segment
		(start 123.936506 -104.588056)
		(end 124.076968 -104.588056)
		(width 0.0889)
		(layer "B.Cu")
		(net "P3E_CPU1_PE3_MP_TXP<15>")
	)
	(segment
		(start 132.519674 -86.212934)
		(end 132.541264 -86.212934)
		(width 0.0889)
		(layer "B.Cu")
		(net "P3E_CPU1_PE3_MP_TXP<15>")
	)
	(segment
		(start 135.080248 -84.727288)
		(end 135.11022 -84.727288)
		(width 0.0889)
		(layer "B.Cu")
		(net "P3E_CPU1_PE3_MP_TXP<15>")
	)
	(segment
		(start 123.544838 -104.979724)
		(end 123.6853 -104.979724)
		(width 0.0889)
		(layer "B.Cu")
		(net "P3E_CPU1_PE3_MP_TXP<15>")
	)
	(segment
		(start 123.81103 -104.853994)
		(end 123.81103 -104.713532)
		(width 0.0889)
		(layer "B.Cu")
		(net "P3E_CPU1_PE3_MP_TXP<15>")
	)
	(segment
		(start 121.760742 -106.799888)
		(end 121.760742 -106.76382)
		(width 0.0889)
		(layer "B.Cu")
		(net "P3E_CPU1_PE3_MP_TXP<15>")
	)
	(segment
		(start 126.169928 -96.234504)
		(end 126.163578 -96.223836)
		(width 0.0889)
		(layer "B.Cu")
		(net "P3E_CPU1_PE3_MP_TXP<15>")
	)
	(segment
		(start 124.076968 -104.588056)
		(end 124.202698 -104.462326)
		(width 0.0889)
		(layer "B.Cu")
		(net "P3E_CPU1_PE3_MP_TXP<15>")
	)
	(segment
		(start 83.801204 -105.611422)
		(end 87.006684 -106.253026)
		(width 0.1143)
		(layer "B.Cu")
		(net "P3E_CPU1_PE3_MP_TXP<15>")
	)
	(segment
		(start 121.745248 -106.815382)
		(end 121.760742 -106.799888)
		(width 0.0889)
		(layer "B.Cu")
		(net "P3E_CPU1_PE3_MP_TXP<15>")
	)
	(segment
		(start 21.905214 -105.751376)
		(end 23.339806 -107.185714)
		(width 0.1143)
		(layer "B.Cu")
		(net "P3E_CPU1_PE3_MP_TXP<15>")
	)
	(segment
		(start 134.225538 -85.222334)
		(end 134.258304 -85.222334)
		(width 0.0889)
		(layer "B.Cu")
		(net "P3E_CPU1_PE3_MP_TXP<15>")
	)
	(segment
		(start 123.419362 -105.1052)
		(end 123.544838 -104.979724)
		(width 0.0889)
		(layer "B.Cu")
		(net "P3E_CPU1_PE3_MP_TXP<15>")
	)
	(segment
		(start 125.251972 -103.413052)
		(end 125.377702 -103.287322)
		(width 0.0889)
		(layer "B.Cu")
		(net "P3E_CPU1_PE3_MP_TXP<15>")
	)
	(segment
		(start 126.163578 -99.195636)
		(end 126.158752 -99.187)
		(width 0.0889)
		(layer "B.Cu")
		(net "P3E_CPU1_PE3_MP_TXP<15>")
	)
	(segment
		(start 130.791712 -87.203534)
		(end 130.824478 -87.203534)
		(width 0.0889)
		(layer "B.Cu")
		(net "P3E_CPU1_PE3_MP_TXP<15>")
	)
	(segment
		(start 21.25853 -104.1908)
		(end 21.905214 -105.751376)
		(width 0.1143)
		(layer "B.Cu")
		(net "P3E_CPU1_PE3_MP_TXP<15>")
	)
	(segment
		(start 19.085052 -102.989888)
		(end 20.059142 -102.989888)
		(width 0.1143)
		(layer "B.Cu")
		(net "P3E_CPU1_PE3_MP_TXP<15>")
	)
	(segment
		(start 35.658552 -113.4364)
		(end 53.38953 -111.69015)
		(width 0.1143)
		(layer "B.Cu")
		(net "P3E_CPU1_PE3_MP_TXP<15>")
	)
	(segment
		(start 123.419362 -105.245662)
		(end 123.419362 -105.1052)
		(width 0.0889)
		(layer "B.Cu")
		(net "P3E_CPU1_PE3_MP_TXP<15>")
	)
	(segment
		(start 126.163578 -94.242636)
		(end 126.158752 -94.234)
		(width 0.0889)
		(layer "B.Cu")
		(net "P3E_CPU1_PE3_MP_TXP<15>")
	)
	(segment
		(start 124.468636 -104.196388)
		(end 124.594366 -104.070658)
		(width 0.0889)
		(layer "B.Cu")
		(net "P3E_CPU1_PE3_MP_TXP<15>")
	)
	(segment
		(start 126.286514 -102.238048)
		(end 126.286514 -101.390196)
		(width 0.0889)
		(layer "B.Cu")
		(net "P3E_CPU1_PE3_MP_TXP<15>")
	)
	(segment
		(start 137.649204 -86.212934)
		(end 137.68197 -86.212934)
		(width 0.0889)
		(layer "B.Cu")
		(net "P3E_CPU1_PE3_MP_TXP<15>")
	)
	(segment
		(start 97.322132 -109.148372)
		(end 102.5779 -108.09732)
		(width 0.1143)
		(layer "B.Cu")
		(net "P3E_CPU1_PE3_MP_TXP<15>")
	)
	(segment
		(start 129.929382 -87.699088)
		(end 129.962148 -87.699088)
		(width 0.0889)
		(layer "B.Cu")
		(net "P3E_CPU1_PE3_MP_TXP<15>")
	)
	(segment
		(start 88.789256 -107.442)
		(end 97.322132 -109.148372)
		(width 0.1143)
		(layer "B.Cu")
		(net "P3E_CPU1_PE3_MP_TXP<15>")
	)
	(segment
		(start 139.387834 -89.922858)
		(end 139.387834 -89.584784)
		(width 0.0889)
		(layer "B.Cu")
		(net "P3E_CPU1_PE3_MP_TXP<15>")
	)
	(segment
		(start 124.202698 -104.321864)
		(end 124.328174 -104.196388)
		(width 0.0889)
		(layer "B.Cu")
		(net "P3E_CPU1_PE3_MP_TXP<15>")
	)
	(segment
		(start 122.761502 -105.76306)
		(end 122.901964 -105.76306)
		(width 0.0889)
		(layer "B.Cu")
		(net "P3E_CPU1_PE3_MP_TXP<15>")
	)
	(segment
		(start 23.339806 -107.185714)
		(end 23.339806 -107.908344)
		(width 0.1143)
		(layer "B.Cu")
		(net "P3E_CPU1_PE3_MP_TXP<15>")
	)
	(segment
		(start 126.169928 -93.262704)
		(end 126.163578 -93.252036)
		(width 0.0889)
		(layer "B.Cu")
		(net "P3E_CPU1_PE3_MP_TXP<15>")
	)
	(segment
		(start 105.717594 -108.725208)
		(end 108.742988 -108.120942)
		(width 0.1143)
		(layer "B.Cu")
		(net "P3E_CPU1_PE3_MP_TXP<15>")
	)
	(segment
		(start 18.72742 -103.34752)
		(end 19.085052 -102.989888)
		(width 0.1143)
		(layer "B.Cu")
		(net "P3E_CPU1_PE3_MP_TXP<15>")
	)
	(segment
		(start 121.16816 -107.39247)
		(end 121.745248 -106.815382)
		(width 0.1143)
		(layer "B.Cu")
		(net "P3E_CPU1_PE3_MP_TXP<15>")
	)
	(segment
		(start 20.059142 -102.989888)
		(end 21.25853 -104.1908)
		(width 0.1143)
		(layer "B.Cu")
		(net "P3E_CPU1_PE3_MP_TXP<15>")
	)
	(segment
		(start 126.163578 -94.833186)
		(end 126.169928 -94.822518)
		(width 0.0889)
		(layer "B.Cu")
		(net "P3E_CPU1_PE3_MP_TXP<15>")
	)
	(segment
		(start 125.377702 -103.14686)
		(end 125.503178 -103.021384)
		(width 0.0889)
		(layer "B.Cu")
		(net "P3E_CPU1_PE3_MP_TXP<15>")
	)
	(segment
		(start 126.161038 -102.363524)
		(end 126.286514 -102.238048)
		(width 0.0889)
		(layer "B.Cu")
		(net "P3E_CPU1_PE3_MP_TXP<15>")
	)
	(segment
		(start 126.169928 -92.272104)
		(end 126.163578 -92.261436)
		(width 0.0889)
		(layer "B.Cu")
		(net "P3E_CPU1_PE3_MP_TXP<15>")
	)
	(segment
		(start 28.95727 -111.642398)
		(end 30.290262 -112.533176)
		(width 0.1143)
		(layer "B.Cu")
		(net "P3E_CPU1_PE3_MP_TXP<15>")
	)
	(segment
		(start 126.163578 -98.205036)
		(end 126.158752 -98.1964)
		(width 0.0889)
		(layer "B.Cu")
		(net "P3E_CPU1_PE3_MP_TXP<15>")
	)
	(segment
		(start 124.719842 -103.80472)
		(end 124.860304 -103.80472)
		(width 0.0889)
		(layer "B.Cu")
		(net "P3E_CPU1_PE3_MP_TXP<15>")
	)
	(segment
		(start 126.163578 -92.261436)
		(end 126.158752 -92.2528)
		(width 0.0889)
		(layer "B.Cu")
		(net "P3E_CPU1_PE3_MP_TXP<15>")
	)
	(segment
		(start 122.901964 -105.76306)
		(end 123.027694 -105.63733)
		(width 0.0889)
		(layer "B.Cu")
		(net "P3E_CPU1_PE3_MP_TXP<15>")
	)
	(segment
		(start 136.794494 -85.717888)
		(end 136.82726 -85.717888)
		(width 0.0889)
		(layer "B.Cu")
		(net "P3E_CPU1_PE3_MP_TXP<15>")
	)
	(segment
		(start 126.163578 -90.280236)
		(end 126.158752 -90.2716)
		(width 0.0889)
		(layer "B.Cu")
		(net "P3E_CPU1_PE3_MP_TXP<15>")
	)
	(segment
		(start 125.76937 -102.755192)
		(end 125.894846 -102.629716)
		(width 0.0889)
		(layer "B.Cu")
		(net "P3E_CPU1_PE3_MP_TXP<15>")
	)
	(segment
		(start 124.986034 -103.67899)
		(end 124.986034 -103.538528)
		(width 0.0889)
		(layer "B.Cu")
		(net "P3E_CPU1_PE3_MP_TXP<15>")
	)
	(segment
		(start 87.006684 -106.253026)
		(end 88.789256 -107.442)
		(width 0.1143)
		(layer "B.Cu")
		(net "P3E_CPU1_PE3_MP_TXP<15>")
	)
	(segment
		(start 33.02 -113.4364)
		(end 35.658552 -113.4364)
		(width 0.1143)
		(layer "B.Cu")
		(net "P3E_CPU1_PE3_MP_TXP<15>")
	)
	(segment
		(start 23.339806 -107.908344)
		(end 26.582116 -111.149384)
		(width 0.1143)
		(layer "B.Cu")
		(net "P3E_CPU1_PE3_MP_TXP<15>")
	)
	(segment
		(start 133.363208 -85.717888)
		(end 133.395974 -85.717888)
		(width 0.0889)
		(layer "B.Cu")
		(net "P3E_CPU1_PE3_MP_TXP<15>")
	)
	(segment
		(start 131.646422 -86.708488)
		(end 131.679188 -86.708488)
		(width 0.0889)
		(layer "B.Cu")
		(net "P3E_CPU1_PE3_MP_TXP<15>")
	)
	(segment
		(start 126.286514 -101.390196)
		(end 126.163578 -101.176582)
		(width 0.0889)
		(layer "B.Cu")
		(net "P3E_CPU1_PE3_MP_TXP<15>")
	)
	(segment
		(start 126.169928 -91.281504)
		(end 126.163578 -91.270836)
		(width 0.0889)
		(layer "B.Cu")
		(net "P3E_CPU1_PE3_MP_TXP<15>")
	)
	(segment
		(start 139.734544 -89.384886)
		(end 139.73937 -89.393522)
		(width 0.0889)
		(layer "B.Cu")
		(net "P3E_CPU1_PE3_MP_TXP<15>")
	)
	(segment
		(start 135.932164 -85.222334)
		(end 135.96493 -85.222334)
		(width 0.0889)
		(layer "B.Cu")
		(net "P3E_CPU1_PE3_MP_TXP<15>")
	)
	(segment
		(start 126.163578 -91.270836)
		(end 126.158752 -91.2622)
		(width 0.0889)
		(layer "B.Cu")
		(net "P3E_CPU1_PE3_MP_TXP<15>")
	)
	(segment
		(start 121.760742 -106.76382)
		(end 122.761502 -105.76306)
		(width 0.0889)
		(layer "B.Cu")
		(net "P3E_CPU1_PE3_MP_TXP<15>")
	)
	(segment
		(start 53.38953 -111.69015)
		(end 83.801204 -105.611422)
		(width 0.1143)
		(layer "B.Cu")
		(net "P3E_CPU1_PE3_MP_TXP<15>")
	)
	(segment
		(start 125.11151 -103.413052)
		(end 125.251972 -103.413052)
		(width 0.0889)
		(layer "B.Cu")
		(net "P3E_CPU1_PE3_MP_TXP<15>")
	)
	(segment
		(start 125.377702 -103.287322)
		(end 125.377702 -103.14686)
		(width 0.0889)
		(layer "B.Cu")
		(net "P3E_CPU1_PE3_MP_TXP<15>")
	)
	(segment
		(start 123.293632 -105.371392)
		(end 123.419362 -105.245662)
		(width 0.0889)
		(layer "B.Cu")
		(net "P3E_CPU1_PE3_MP_TXP<15>")
	)
	(segment
		(start 124.328174 -104.196388)
		(end 124.468636 -104.196388)
		(width 0.0889)
		(layer "B.Cu")
		(net "P3E_CPU1_PE3_MP_TXP<15>")
	)
	(segment
		(start 126.035308 -102.629716)
		(end 126.161038 -102.503986)
		(width 0.0889)
		(layer "B.Cu")
		(net "P3E_CPU1_PE3_MP_TXP<15>")
	)
	(segment
		(start 124.986034 -103.538528)
		(end 125.11151 -103.413052)
		(width 0.0889)
		(layer "B.Cu")
		(net "P3E_CPU1_PE3_MP_TXP<15>")
	)
	(segment
		(start 126.169928 -98.215704)
		(end 126.163578 -98.205036)
		(width 0.0889)
		(layer "B.Cu")
		(net "P3E_CPU1_PE3_MP_TXP<15>")
	)
	(segment
		(start 126.163578 -100.776786)
		(end 126.169928 -100.766118)
		(width 0.0889)
		(layer "B.Cu")
		(net "P3E_CPU1_PE3_MP_TXP<15>")
	)
	(segment
		(start 126.161038 -102.503986)
		(end 126.161038 -102.363524)
		(width 0.0889)
		(layer "B.Cu")
		(net "P3E_CPU1_PE3_MP_TXP<15>")
	)
	(segment
		(start 123.027694 -105.496868)
		(end 123.15317 -105.371392)
		(width 0.0889)
		(layer "B.Cu")
		(net "P3E_CPU1_PE3_MP_TXP<15>")
	)
	(segment
		(start 124.594366 -103.930196)
		(end 124.719842 -103.80472)
		(width 0.0889)
		(layer "B.Cu")
		(net "P3E_CPU1_PE3_MP_TXP<15>")
	)
	(segment
		(start 128.212342 -88.689688)
		(end 128.245108 -88.689688)
		(width 0.0889)
		(layer "B.Cu")
		(net "P3E_CPU1_PE3_MP_TXP<15>")
	)
	(segment
		(start 123.81103 -104.713532)
		(end 123.936506 -104.588056)
		(width 0.0889)
		(layer "B.Cu")
		(net "P3E_CPU1_PE3_MP_TXP<15>")
	)
	(segment
		(start 138.511534 -86.708488)
		(end 138.5443 -86.708488)
		(width 0.0889)
		(layer "B.Cu")
		(net "P3E_CPU1_PE3_MP_TXP<15>")
	)
	(segment
		(start 124.594366 -104.070658)
		(end 124.594366 -103.930196)
		(width 0.0889)
		(layer "B.Cu")
		(net "P3E_CPU1_PE3_MP_TXP<15>")
	)
	(segment
		(start 139.366244 -87.203534)
		(end 139.39901 -87.203534)
		(width 0.0889)
		(layer "B.Cu")
		(net "P3E_CPU1_PE3_MP_TXP<15>")
	)
	(segment
		(start 125.503178 -103.021384)
		(end 125.64364 -103.021384)
		(width 0.0889)
		(layer "B.Cu")
		(net "P3E_CPU1_PE3_MP_TXP<15>")
	)
	(segment
		(start 126.163578 -93.252036)
		(end 126.158752 -93.2434)
		(width 0.0889)
		(layer "B.Cu")
		(net "P3E_CPU1_PE3_MP_TXP<15>")
	)
	(segment
		(start 126.169928 -97.225104)
		(end 126.163578 -97.214436)
		(width 0.0889)
		(layer "B.Cu")
		(net "P3E_CPU1_PE3_MP_TXP<15>")
	)
	(segment
		(start 132.173218 -86.413086)
		(end 132.17652 -86.407244)
		(width 0.0889)
		(layer "B.Cu")
		(net "P3E_CPU1_PE3_MP_TXP<15>")
	)
	(segment
		(start 124.860304 -103.80472)
		(end 124.986034 -103.67899)
		(width 0.0889)
		(layer "B.Cu")
		(net "P3E_CPU1_PE3_MP_TXP<15>")
	)
	(segment
		(start 127.357632 -89.184734)
		(end 127.390398 -89.184734)
		(width 0.0889)
		(layer "B.Cu")
		(net "P3E_CPU1_PE3_MP_TXP<15>")
	)
	(segment
		(start 126.163578 -97.214436)
		(end 126.158752 -97.2058)
		(width 0.0889)
		(layer "B.Cu")
		(net "P3E_CPU1_PE3_MP_TXP<15>")
	)
	(segment
		(start 32.47009 -113.4364)
		(end 33.02 -113.4364)
		(width 0.1143)
		(layer "B.Cu")
		(net "P3E_CPU1_PE3_MP_TXP<15>")
	)
	(segment
		(start 139.445746 -89.98077)
		(end 139.387834 -89.922858)
		(width 0.0889)
		(layer "B.Cu")
		(net "P3E_CPU1_PE3_MP_TXP<15>")
	)
	(segment
		(start 108.742988 -108.120942)
		(end 113.112804 -108.994702)
		(width 0.1143)
		(layer "B.Cu")
		(net "P3E_CPU1_PE3_MP_TXP<15>")
	)
	(segment
		(start 126.169928 -90.290904)
		(end 126.163578 -90.280236)
		(width 0.0889)
		(layer "B.Cu")
		(net "P3E_CPU1_PE3_MP_TXP<15>")
	)
	(segment
		(start 125.76937 -102.895654)
		(end 125.76937 -102.755192)
		(width 0.0889)
		(layer "B.Cu")
		(net "P3E_CPU1_PE3_MP_TXP<15>")
	)
	(segment
		(start 126.163578 -96.223836)
		(end 126.158752 -96.2152)
		(width 0.0889)
		(layer "B.Cu")
		(net "P3E_CPU1_PE3_MP_TXP<15>")
	)
	(segment
		(start 125.64364 -103.021384)
		(end 125.76937 -102.895654)
		(width 0.0889)
		(layer "B.Cu")
		(net "P3E_CPU1_PE3_MP_TXP<15>")
	)
	(segment
		(start 123.15317 -105.371392)
		(end 123.293632 -105.371392)
		(width 0.0889)
		(layer "B.Cu")
		(net "P3E_CPU1_PE3_MP_TXP<15>")
	)
	(arc
		(start 126.158752 -94.234)
		(mid 126.109997 -94.037648)
		(end 126.163578 -93.842586)
		(width 0.0889)
		(layer "B.Cu")
		(net "P3E_CPU1_PE3_MP_TXP<15>")
	)
	(arc
		(start 129.107438 -88.194134)
		(mid 129.390655 -88.109853)
		(end 129.597658 -87.898986)
		(width 0.0889)
		(layer "B.Cu")
		(net "P3E_CPU1_PE3_MP_TXP<15>")
	)
	(arc
		(start 136.300464 -85.422486)
		(mid 136.509072 -85.634418)
		(end 136.794494 -85.717888)
		(width 0.0889)
		(layer "B.Cu")
		(net "P3E_CPU1_PE3_MP_TXP<15>")
	)
	(arc
		(start 132.17652 -86.407244)
		(mid 132.322486 -86.264845)
		(end 132.519674 -86.212934)
		(width 0.0889)
		(layer "B.Cu")
		(net "P3E_CPU1_PE3_MP_TXP<15>")
	)
	(arc
		(start 126.163578 -93.842586)
		(mid 126.2428 -93.553468)
		(end 126.169928 -93.262704)
		(width 0.0889)
		(layer "B.Cu")
		(net "P3E_CPU1_PE3_MP_TXP<15>")
	)
	(arc
		(start 135.11022 -84.727288)
		(mid 135.301862 -84.784454)
		(end 135.441944 -84.927186)
		(width 0.0889)
		(layer "B.Cu")
		(net "P3E_CPU1_PE3_MP_TXP<15>")
	)
	(arc
		(start 126.163578 -95.232982)
		(mid 126.110079 -95.033084)
		(end 126.163578 -94.833186)
		(width 0.0889)
		(layer "B.Cu")
		(net "P3E_CPU1_PE3_MP_TXP<15>")
	)
	(arc
		(start 130.456178 -87.403686)
		(mid 130.597861 -87.259882)
		(end 130.791712 -87.203534)
		(width 0.0889)
		(layer "B.Cu")
		(net "P3E_CPU1_PE3_MP_TXP<15>")
	)
	(arc
		(start 126.169928 -94.822518)
		(mid 126.242726 -94.531755)
		(end 126.163578 -94.242636)
		(width 0.0889)
		(layer "B.Cu")
		(net "P3E_CPU1_PE3_MP_TXP<15>")
	)
	(arc
		(start 134.258304 -85.222334)
		(mid 134.541521 -85.138053)
		(end 134.748524 -84.927186)
		(width 0.0889)
		(layer "B.Cu")
		(net "P3E_CPU1_PE3_MP_TXP<15>")
	)
	(arc
		(start 126.158752 -93.2434)
		(mid 126.109997 -93.047048)
		(end 126.163578 -92.851986)
		(width 0.0889)
		(layer "B.Cu")
		(net "P3E_CPU1_PE3_MP_TXP<15>")
	)
	(arc
		(start 133.890004 -85.422486)
		(mid 134.031687 -85.278682)
		(end 134.225538 -85.222334)
		(width 0.0889)
		(layer "B.Cu")
		(net "P3E_CPU1_PE3_MP_TXP<15>")
	)
	(arc
		(start 126.163578 -90.870786)
		(mid 126.2428 -90.581668)
		(end 126.169928 -90.290904)
		(width 0.0889)
		(layer "B.Cu")
		(net "P3E_CPU1_PE3_MP_TXP<15>")
	)
	(arc
		(start 126.158752 -98.1964)
		(mid 126.109997 -98.000048)
		(end 126.163578 -97.804986)
		(width 0.0889)
		(layer "B.Cu")
		(net "P3E_CPU1_PE3_MP_TXP<15>")
	)
	(arc
		(start 139.734544 -87.803736)
		(mid 139.655322 -88.092854)
		(end 139.728194 -88.383618)
		(width 0.0889)
		(layer "B.Cu")
		(net "P3E_CPU1_PE3_MP_TXP<15>")
	)
	(arc
		(start 134.748524 -84.927186)
		(mid 134.888603 -84.78445)
		(end 135.080248 -84.727288)
		(width 0.0889)
		(layer "B.Cu")
		(net "P3E_CPU1_PE3_MP_TXP<15>")
	)
	(arc
		(start 139.73937 -89.393522)
		(mid 139.745782 -89.763758)
		(end 139.445746 -89.98077)
		(width 0.0889)
		(layer "B.Cu")
		(net "P3E_CPU1_PE3_MP_TXP<15>")
	)
	(arc
		(start 135.441944 -84.927186)
		(mid 135.648948 -85.13805)
		(end 135.932164 -85.222334)
		(width 0.0889)
		(layer "B.Cu")
		(net "P3E_CPU1_PE3_MP_TXP<15>")
	)
	(arc
		(start 128.739138 -88.394286)
		(mid 128.880821 -88.250482)
		(end 129.074672 -88.194134)
		(width 0.0889)
		(layer "B.Cu")
		(net "P3E_CPU1_PE3_MP_TXP<15>")
	)
	(arc
		(start 126.163578 -99.786186)
		(mid 126.2428 -99.497068)
		(end 126.169928 -99.206304)
		(width 0.0889)
		(layer "B.Cu")
		(net "P3E_CPU1_PE3_MP_TXP<15>")
	)
	(arc
		(start 126.163578 -101.176582)
		(mid 126.110079 -100.976684)
		(end 126.163578 -100.776786)
		(width 0.0889)
		(layer "B.Cu")
		(net "P3E_CPU1_PE3_MP_TXP<15>")
	)
	(arc
		(start 126.163578 -96.814386)
		(mid 126.2428 -96.525268)
		(end 126.169928 -96.234504)
		(width 0.0889)
		(layer "B.Cu")
		(net "P3E_CPU1_PE3_MP_TXP<15>")
	)
	(arc
		(start 139.734544 -88.794336)
		(mid 139.655322 -89.083454)
		(end 139.728194 -89.374218)
		(width 0.0889)
		(layer "B.Cu")
		(net "P3E_CPU1_PE3_MP_TXP<15>")
	)
	(arc
		(start 126.158752 -91.2622)
		(mid 126.109997 -91.065848)
		(end 126.163578 -90.870786)
		(width 0.0889)
		(layer "B.Cu")
		(net "P3E_CPU1_PE3_MP_TXP<15>")
	)
	(arc
		(start 126.163578 -95.823786)
		(mid 126.242709 -95.528384)
		(end 126.163578 -95.232982)
		(width 0.0889)
		(layer "B.Cu")
		(net "P3E_CPU1_PE3_MP_TXP<15>")
	)
	(arc
		(start 128.245108 -88.689688)
		(mid 128.530532 -88.606221)
		(end 128.739138 -88.394286)
		(width 0.0889)
		(layer "B.Cu")
		(net "P3E_CPU1_PE3_MP_TXP<15>")
	)
	(arc
		(start 126.158752 -96.2152)
		(mid 126.109997 -96.018848)
		(end 126.163578 -95.823786)
		(width 0.0889)
		(layer "B.Cu")
		(net "P3E_CPU1_PE3_MP_TXP<15>")
	)
	(arc
		(start 138.5443 -86.708488)
		(mid 138.735942 -86.765654)
		(end 138.876024 -86.908386)
		(width 0.0889)
		(layer "B.Cu")
		(net "P3E_CPU1_PE3_MP_TXP<15>")
	)
	(arc
		(start 139.728194 -88.383618)
		(mid 139.733904 -88.393199)
		(end 139.73937 -88.402922)
		(width 0.0889)
		(layer "B.Cu")
		(net "P3E_CPU1_PE3_MP_TXP<15>")
	)
	(arc
		(start 133.395974 -85.717888)
		(mid 133.681398 -85.634421)
		(end 133.890004 -85.422486)
		(width 0.0889)
		(layer "B.Cu")
		(net "P3E_CPU1_PE3_MP_TXP<15>")
	)
	(arc
		(start 137.158984 -85.917786)
		(mid 137.365988 -86.12865)
		(end 137.649204 -86.212934)
		(width 0.0889)
		(layer "B.Cu")
		(net "P3E_CPU1_PE3_MP_TXP<15>")
	)
	(arc
		(start 126.158752 -99.187)
		(mid 126.109997 -98.990648)
		(end 126.163578 -98.795586)
		(width 0.0889)
		(layer "B.Cu")
		(net "P3E_CPU1_PE3_MP_TXP<15>")
	)
	(arc
		(start 127.022098 -89.384886)
		(mid 127.163781 -89.241082)
		(end 127.357632 -89.184734)
		(width 0.0889)
		(layer "B.Cu")
		(net "P3E_CPU1_PE3_MP_TXP<15>")
	)
	(arc
		(start 129.962148 -87.699088)
		(mid 130.247572 -87.615621)
		(end 130.456178 -87.403686)
		(width 0.0889)
		(layer "B.Cu")
		(net "P3E_CPU1_PE3_MP_TXP<15>")
	)
	(arc
		(start 130.824478 -87.203534)
		(mid 131.107695 -87.119253)
		(end 131.314698 -86.908386)
		(width 0.0889)
		(layer "B.Cu")
		(net "P3E_CPU1_PE3_MP_TXP<15>")
	)
	(arc
		(start 126.163578 -92.851986)
		(mid 126.2428 -92.562868)
		(end 126.169928 -92.272104)
		(width 0.0889)
		(layer "B.Cu")
		(net "P3E_CPU1_PE3_MP_TXP<15>")
	)
	(arc
		(start 138.017504 -86.413086)
		(mid 138.226112 -86.625018)
		(end 138.511534 -86.708488)
		(width 0.0889)
		(layer "B.Cu")
		(net "P3E_CPU1_PE3_MP_TXP<15>")
	)
	(arc
		(start 126.169928 -100.766118)
		(mid 126.242726 -100.475355)
		(end 126.163578 -100.186236)
		(width 0.0889)
		(layer "B.Cu")
		(net "P3E_CPU1_PE3_MP_TXP<15>")
	)
	(arc
		(start 126.163578 -91.861386)
		(mid 126.2428 -91.572268)
		(end 126.169928 -91.281504)
		(width 0.0889)
		(layer "B.Cu")
		(net "P3E_CPU1_PE3_MP_TXP<15>")
	)
	(arc
		(start 139.39901 -87.203534)
		(mid 139.737179 -87.408332)
		(end 139.734544 -87.803736)
		(width 0.0889)
		(layer "B.Cu")
		(net "P3E_CPU1_PE3_MP_TXP<15>")
	)
	(arc
		(start 129.597658 -87.898986)
		(mid 129.737737 -87.75625)
		(end 129.929382 -87.699088)
		(width 0.0889)
		(layer "B.Cu")
		(net "P3E_CPU1_PE3_MP_TXP<15>")
	)
	(arc
		(start 126.158752 -90.2716)
		(mid 126.162499 -89.882344)
		(end 126.495302 -89.680288)
		(width 0.0889)
		(layer "B.Cu")
		(net "P3E_CPU1_PE3_MP_TXP<15>")
	)
	(arc
		(start 126.528068 -89.680288)
		(mid 126.813492 -89.596821)
		(end 127.022098 -89.384886)
		(width 0.0889)
		(layer "B.Cu")
		(net "P3E_CPU1_PE3_MP_TXP<15>")
	)
	(arc
		(start 139.73937 -88.402922)
		(mid 139.788125 -88.599274)
		(end 139.734544 -88.794336)
		(width 0.0889)
		(layer "B.Cu")
		(net "P3E_CPU1_PE3_MP_TXP<15>")
	)
	(arc
		(start 126.158752 -92.2528)
		(mid 126.109997 -92.056448)
		(end 126.163578 -91.861386)
		(width 0.0889)
		(layer "B.Cu")
		(net "P3E_CPU1_PE3_MP_TXP<15>")
	)
	(arc
		(start 127.880618 -88.889586)
		(mid 128.020697 -88.74685)
		(end 128.212342 -88.689688)
		(width 0.0889)
		(layer "B.Cu")
		(net "P3E_CPU1_PE3_MP_TXP<15>")
	)
	(arc
		(start 127.390398 -89.184734)
		(mid 127.673615 -89.100453)
		(end 127.880618 -88.889586)
		(width 0.0889)
		(layer "B.Cu")
		(net "P3E_CPU1_PE3_MP_TXP<15>")
	)
	(arc
		(start 131.314698 -86.908386)
		(mid 131.454777 -86.76565)
		(end 131.646422 -86.708488)
		(width 0.0889)
		(layer "B.Cu")
		(net "P3E_CPU1_PE3_MP_TXP<15>")
	)
	(arc
		(start 126.158752 -100.1776)
		(mid 126.109997 -99.981248)
		(end 126.163578 -99.786186)
		(width 0.0889)
		(layer "B.Cu")
		(net "P3E_CPU1_PE3_MP_TXP<15>")
	)
	(arc
		(start 133.031484 -85.917786)
		(mid 133.171563 -85.77505)
		(end 133.363208 -85.717888)
		(width 0.0889)
		(layer "B.Cu")
		(net "P3E_CPU1_PE3_MP_TXP<15>")
	)
	(arc
		(start 126.163578 -97.804986)
		(mid 126.2428 -97.515868)
		(end 126.169928 -97.225104)
		(width 0.0889)
		(layer "B.Cu")
		(net "P3E_CPU1_PE3_MP_TXP<15>")
	)
	(arc
		(start 136.82726 -85.717888)
		(mid 137.018902 -85.775054)
		(end 137.158984 -85.917786)
		(width 0.0889)
		(layer "B.Cu")
		(net "P3E_CPU1_PE3_MP_TXP<15>")
	)
	(arc
		(start 131.679188 -86.708488)
		(mid 131.964612 -86.625021)
		(end 132.173218 -86.413086)
		(width 0.0889)
		(layer "B.Cu")
		(net "P3E_CPU1_PE3_MP_TXP<15>")
	)
	(arc
		(start 137.68197 -86.212934)
		(mid 137.87582 -86.269284)
		(end 138.017504 -86.413086)
		(width 0.0889)
		(layer "B.Cu")
		(net "P3E_CPU1_PE3_MP_TXP<15>")
	)
	(arc
		(start 126.163578 -98.795586)
		(mid 126.2428 -98.506468)
		(end 126.169928 -98.215704)
		(width 0.0889)
		(layer "B.Cu")
		(net "P3E_CPU1_PE3_MP_TXP<15>")
	)
	(arc
		(start 135.96493 -85.222334)
		(mid 136.15878 -85.278684)
		(end 136.300464 -85.422486)
		(width 0.0889)
		(layer "B.Cu")
		(net "P3E_CPU1_PE3_MP_TXP<15>")
	)
	(arc
		(start 126.158752 -97.2058)
		(mid 126.109997 -97.009448)
		(end 126.163578 -96.814386)
		(width 0.0889)
		(layer "B.Cu")
		(net "P3E_CPU1_PE3_MP_TXP<15>")
	)
	(arc
		(start 138.876024 -86.908386)
		(mid 139.083028 -87.11925)
		(end 139.366244 -87.203534)
		(width 0.0889)
		(layer "B.Cu")
		(net "P3E_CPU1_PE3_MP_TXP<15>")
	)
	(arc
		(start 132.541264 -86.212934)
		(mid 132.824481 -86.128653)
		(end 133.031484 -85.917786)
		(width 0.0889)
		(layer "B.Cu")
		(net "P3E_CPU1_PE3_MP_TXP<15>")
	)
	(segment
		(start 139.674854 -91.070938)
		(end 140.246354 -91.070938)
		(width 0.1143)
		(layer "F.Cu")
		(net "P3E_CPU1_PE3_MP_TXP<14>")
	)
	(via
		(at 23.3426 -108.991654)
		(size 0.508)
		(drill 0.254)
		(layers "F.Cu" "B.Cu")
		(net "P3E_CPU1_PE3_MP_TXP<14>")
	)
	(via
		(at 140.246354 -91.070938)
		(size 0.508)
		(drill 0.254)
		(layers "F.Cu" "B.Cu")
		(net "P3E_CPU1_PE3_MP_TXP<14>")
	)
	(segment
		(start 126.856998 -94.833186)
		(end 126.850648 -94.822518)
		(width 0.0889)
		(layer "B.Cu")
		(net "P3E_CPU1_PE3_MP_TXP<14>")
	)
	(segment
		(start 139.86383 -91.215718)
		(end 139.953238 -91.239848)
		(width 0.0889)
		(layer "B.Cu")
		(net "P3E_CPU1_PE3_MP_TXP<14>")
	)
	(segment
		(start 139.041378 -89.384378)
		(end 139.041124 -89.384886)
		(width 0.0889)
		(layer "B.Cu")
		(net "P3E_CPU1_PE3_MP_TXP<14>")
	)
	(segment
		(start 83.587336 -106.41457)
		(end 86.675722 -107.032298)
		(width 0.1143)
		(layer "B.Cu")
		(net "P3E_CPU1_PE3_MP_TXP<14>")
	)
	(segment
		(start 126.920752 -100.88753)
		(end 126.850648 -100.766118)
		(width 0.0889)
		(layer "B.Cu")
		(net "P3E_CPU1_PE3_MP_TXP<14>")
	)
	(segment
		(start 126.856998 -99.195636)
		(end 126.861824 -99.187)
		(width 0.0889)
		(layer "B.Cu")
		(net "P3E_CPU1_PE3_MP_TXP<14>")
	)
	(segment
		(start 126.850648 -99.206304)
		(end 126.856998 -99.195636)
		(width 0.0889)
		(layer "B.Cu")
		(net "P3E_CPU1_PE3_MP_TXP<14>")
	)
	(segment
		(start 126.770892 -101.34473)
		(end 126.8603 -101.21011)
		(width 0.0889)
		(layer "B.Cu")
		(net "P3E_CPU1_PE3_MP_TXP<14>")
	)
	(segment
		(start 105.725214 -109.528102)
		(end 108.89107 -108.89488)
		(width 0.1143)
		(layer "B.Cu")
		(net "P3E_CPU1_PE3_MP_TXP<14>")
	)
	(segment
		(start 52.916074 -112.54613)
		(end 83.587336 -106.41457)
		(width 0.1143)
		(layer "B.Cu")
		(net "P3E_CPU1_PE3_MP_TXP<14>")
	)
	(segment
		(start 15.151354 -102.643178)
		(end 15.583662 -103.687372)
		(width 0.1143)
		(layer "B.Cu")
		(net "P3E_CPU1_PE3_MP_TXP<14>")
	)
	(segment
		(start 137.655808 -87.013034)
		(end 137.688574 -87.013034)
		(width 0.0889)
		(layer "B.Cu")
		(net "P3E_CPU1_PE3_MP_TXP<14>")
	)
	(segment
		(start 126.856998 -92.261436)
		(end 126.861824 -92.2528)
		(width 0.0889)
		(layer "B.Cu")
		(net "P3E_CPU1_PE3_MP_TXP<14>")
	)
	(segment
		(start 126.627128 -103.0478)
		(end 126.770892 -102.904036)
		(width 0.0889)
		(layer "B.Cu")
		(net "P3E_CPU1_PE3_MP_TXP<14>")
	)
	(segment
		(start 126.856998 -93.252036)
		(end 126.861824 -93.2434)
		(width 0.0889)
		(layer "B.Cu")
		(net "P3E_CPU1_PE3_MP_TXP<14>")
	)
	(segment
		(start 126.856998 -94.242636)
		(end 126.861824 -94.234)
		(width 0.0889)
		(layer "B.Cu")
		(net "P3E_CPU1_PE3_MP_TXP<14>")
	)
	(segment
		(start 126.850648 -93.262704)
		(end 126.856998 -93.252036)
		(width 0.0889)
		(layer "B.Cu")
		(net "P3E_CPU1_PE3_MP_TXP<14>")
	)
	(segment
		(start 139.372848 -90.975434)
		(end 139.405614 -90.975434)
		(width 0.0889)
		(layer "B.Cu")
		(net "P3E_CPU1_PE3_MP_TXP<14>")
	)
	(segment
		(start 32.372554 -114.185446)
		(end 36.27501 -114.185446)
		(width 0.1143)
		(layer "B.Cu")
		(net "P3E_CPU1_PE3_MP_TXP<14>")
	)
	(segment
		(start 126.850648 -91.281504)
		(end 126.856998 -91.270836)
		(width 0.0889)
		(layer "B.Cu")
		(net "P3E_CPU1_PE3_MP_TXP<14>")
	)
	(segment
		(start 139.041378 -88.393778)
		(end 139.041124 -88.394286)
		(width 0.0889)
		(layer "B.Cu")
		(net "P3E_CPU1_PE3_MP_TXP<14>")
	)
	(segment
		(start 126.856998 -100.186236)
		(end 126.861824 -100.1776)
		(width 0.0889)
		(layer "B.Cu")
		(net "P3E_CPU1_PE3_MP_TXP<14>")
	)
	(segment
		(start 36.275264 -114.185446)
		(end 52.916074 -112.54613)
		(width 0.1143)
		(layer "B.Cu")
		(net "P3E_CPU1_PE3_MP_TXP<14>")
	)
	(segment
		(start 97.27184 -110.021878)
		(end 102.732586 -108.929678)
		(width 0.1143)
		(layer "B.Cu")
		(net "P3E_CPU1_PE3_MP_TXP<14>")
	)
	(segment
		(start 139.047474 -88.383618)
		(end 139.041378 -88.393778)
		(width 0.0889)
		(layer "B.Cu")
		(net "P3E_CPU1_PE3_MP_TXP<14>")
	)
	(segment
		(start 13.29182 -101.57968)
		(end 13.53693 -101.82479)
		(width 0.1143)
		(layer "B.Cu")
		(net "P3E_CPU1_PE3_MP_TXP<14>")
	)
	(segment
		(start 23.3426 -108.991654)
		(end 26.21788 -111.866934)
		(width 0.1143)
		(layer "B.Cu")
		(net "P3E_CPU1_PE3_MP_TXP<14>")
	)
	(segment
		(start 123.29414 -106.380534)
		(end 126.626874 -103.0478)
		(width 0.0889)
		(layer "B.Cu")
		(net "P3E_CPU1_PE3_MP_TXP<14>")
	)
	(segment
		(start 126.850648 -97.225104)
		(end 126.856998 -97.214436)
		(width 0.0889)
		(layer "B.Cu")
		(net "P3E_CPU1_PE3_MP_TXP<14>")
	)
	(segment
		(start 28.61437 -112.332516)
		(end 29.769816 -113.107216)
		(width 0.1143)
		(layer "B.Cu")
		(net "P3E_CPU1_PE3_MP_TXP<14>")
	)
	(segment
		(start 86.675722 -107.032298)
		(end 88.54059 -108.275628)
		(width 0.1143)
		(layer "B.Cu")
		(net "P3E_CPU1_PE3_MP_TXP<14>")
	)
	(segment
		(start 36.275264 -114.185192)
		(end 36.275264 -114.185446)
		(width 0.1143)
		(layer "B.Cu")
		(net "P3E_CPU1_PE3_MP_TXP<14>")
	)
	(segment
		(start 14.332966 -101.82479)
		(end 15.151354 -102.643178)
		(width 0.1143)
		(layer "B.Cu")
		(net "P3E_CPU1_PE3_MP_TXP<14>")
	)
	(segment
		(start 15.932912 -104.123998)
		(end 16.05026 -104.17302)
		(width 0.1143)
		(layer "B.Cu")
		(net "P3E_CPU1_PE3_MP_TXP<14>")
	)
	(segment
		(start 139.041378 -90.374978)
		(end 139.041124 -90.375486)
		(width 0.0889)
		(layer "B.Cu")
		(net "P3E_CPU1_PE3_MP_TXP<14>")
	)
	(segment
		(start 129.068068 -88.994234)
		(end 129.100834 -88.994234)
		(width 0.0889)
		(layer "B.Cu")
		(net "P3E_CPU1_PE3_MP_TXP<14>")
	)
	(segment
		(start 135.938768 -86.022434)
		(end 135.971534 -86.022434)
		(width 0.0889)
		(layer "B.Cu")
		(net "P3E_CPU1_PE3_MP_TXP<14>")
	)
	(segment
		(start 138.518138 -87.508588)
		(end 138.550904 -87.508588)
		(width 0.0889)
		(layer "B.Cu")
		(net "P3E_CPU1_PE3_MP_TXP<14>")
	)
	(segment
		(start 126.626874 -103.0478)
		(end 126.627128 -103.0478)
		(width 0.0889)
		(layer "B.Cu")
		(net "P3E_CPU1_PE3_MP_TXP<14>")
	)
	(segment
		(start 113.102644 -109.737398)
		(end 121.590308 -108.048806)
		(width 0.1143)
		(layer "B.Cu")
		(net "P3E_CPU1_PE3_MP_TXP<14>")
	)
	(segment
		(start 88.54059 -108.275628)
		(end 97.27184 -110.021878)
		(width 0.1143)
		(layer "B.Cu")
		(net "P3E_CPU1_PE3_MP_TXP<14>")
	)
	(segment
		(start 126.856998 -97.214436)
		(end 126.861824 -97.2058)
		(width 0.0889)
		(layer "B.Cu")
		(net "P3E_CPU1_PE3_MP_TXP<14>")
	)
	(segment
		(start 139.041124 -90.375486)
		(end 139.036298 -90.384122)
		(width 0.0889)
		(layer "B.Cu")
		(net "P3E_CPU1_PE3_MP_TXP<14>")
	)
	(segment
		(start 26.21788 -111.866934)
		(end 28.61437 -112.332516)
		(width 0.1143)
		(layer "B.Cu")
		(net "P3E_CPU1_PE3_MP_TXP<14>")
	)
	(segment
		(start 126.8603 -101.21011)
		(end 126.8603 -101.209856)
		(width 0.0889)
		(layer "B.Cu")
		(net "P3E_CPU1_PE3_MP_TXP<14>")
	)
	(segment
		(start 139.047474 -89.374218)
		(end 139.041378 -89.384378)
		(width 0.0889)
		(layer "B.Cu")
		(net "P3E_CPU1_PE3_MP_TXP<14>")
	)
	(segment
		(start 126.850648 -92.272104)
		(end 126.856998 -92.261436)
		(width 0.0889)
		(layer "B.Cu")
		(net "P3E_CPU1_PE3_MP_TXP<14>")
	)
	(segment
		(start 126.850648 -96.234504)
		(end 126.856998 -96.223836)
		(width 0.0889)
		(layer "B.Cu")
		(net "P3E_CPU1_PE3_MP_TXP<14>")
	)
	(segment
		(start 131.639818 -87.508588)
		(end 131.661408 -87.508588)
		(width 0.0889)
		(layer "B.Cu")
		(net "P3E_CPU1_PE3_MP_TXP<14>")
	)
	(segment
		(start 133.356604 -86.517988)
		(end 133.38937 -86.517988)
		(width 0.0889)
		(layer "B.Cu")
		(net "P3E_CPU1_PE3_MP_TXP<14>")
	)
	(segment
		(start 132.501894 -87.013034)
		(end 132.53466 -87.013034)
		(width 0.0889)
		(layer "B.Cu")
		(net "P3E_CPU1_PE3_MP_TXP<14>")
	)
	(segment
		(start 15.671292 -103.862886)
		(end 15.932912 -104.123998)
		(width 0.1143)
		(layer "B.Cu")
		(net "P3E_CPU1_PE3_MP_TXP<14>")
	)
	(segment
		(start 19.246596 -104.17302)
		(end 22.595586 -107.52201)
		(width 0.1143)
		(layer "B.Cu")
		(net "P3E_CPU1_PE3_MP_TXP<14>")
	)
	(segment
		(start 22.595586 -107.52201)
		(end 22.595586 -108.24464)
		(width 0.1143)
		(layer "B.Cu")
		(net "P3E_CPU1_PE3_MP_TXP<14>")
	)
	(segment
		(start 132.004562 -87.314278)
		(end 132.007864 -87.308436)
		(width 0.0889)
		(layer "B.Cu")
		(net "P3E_CPU1_PE3_MP_TXP<14>")
	)
	(segment
		(start 102.732586 -108.929678)
		(end 105.725214 -109.528102)
		(width 0.1143)
		(layer "B.Cu")
		(net "P3E_CPU1_PE3_MP_TXP<14>")
	)
	(segment
		(start 36.27501 -114.185446)
		(end 36.275264 -114.185192)
		(width 0.1143)
		(layer "B.Cu")
		(net "P3E_CPU1_PE3_MP_TXP<14>")
	)
	(segment
		(start 139.041124 -89.384886)
		(end 139.036298 -89.393522)
		(width 0.0889)
		(layer "B.Cu")
		(net "P3E_CPU1_PE3_MP_TXP<14>")
	)
	(segment
		(start 134.218934 -86.022434)
		(end 134.2517 -86.022434)
		(width 0.0889)
		(layer "B.Cu")
		(net "P3E_CPU1_PE3_MP_TXP<14>")
	)
	(segment
		(start 29.769816 -113.107216)
		(end 32.372554 -114.185446)
		(width 0.1143)
		(layer "B.Cu")
		(net "P3E_CPU1_PE3_MP_TXP<14>")
	)
	(segment
		(start 126.856998 -91.270836)
		(end 126.861824 -91.2622)
		(width 0.0889)
		(layer "B.Cu")
		(net "P3E_CPU1_PE3_MP_TXP<14>")
	)
	(segment
		(start 108.89107 -108.89488)
		(end 113.102644 -109.737398)
		(width 0.1143)
		(layer "B.Cu")
		(net "P3E_CPU1_PE3_MP_TXP<14>")
	)
	(segment
		(start 123.243086 -106.396028)
		(end 123.25858 -106.380534)
		(width 0.0889)
		(layer "B.Cu")
		(net "P3E_CPU1_PE3_MP_TXP<14>")
	)
	(segment
		(start 13.53693 -101.82479)
		(end 14.332966 -101.82479)
		(width 0.1143)
		(layer "B.Cu")
		(net "P3E_CPU1_PE3_MP_TXP<14>")
	)
	(segment
		(start 139.047474 -90.364818)
		(end 139.041378 -90.374978)
		(width 0.0889)
		(layer "B.Cu")
		(net "P3E_CPU1_PE3_MP_TXP<14>")
	)
	(segment
		(start 139.041124 -88.394286)
		(end 139.036298 -88.402922)
		(width 0.0889)
		(layer "B.Cu")
		(net "P3E_CPU1_PE3_MP_TXP<14>")
	)
	(segment
		(start 22.595586 -108.24464)
		(end 23.3426 -108.991654)
		(width 0.1143)
		(layer "B.Cu")
		(net "P3E_CPU1_PE3_MP_TXP<14>")
	)
	(segment
		(start 129.922778 -88.499188)
		(end 129.955544 -88.499188)
		(width 0.0889)
		(layer "B.Cu")
		(net "P3E_CPU1_PE3_MP_TXP<14>")
	)
	(segment
		(start 15.583662 -103.687372)
		(end 15.671292 -103.862886)
		(width 0.1143)
		(layer "B.Cu")
		(net "P3E_CPU1_PE3_MP_TXP<14>")
	)
	(segment
		(start 126.921768 -100.889054)
		(end 126.920752 -100.88753)
		(width 0.0889)
		(layer "B.Cu")
		(net "P3E_CPU1_PE3_MP_TXP<14>")
	)
	(segment
		(start 127.351028 -89.984834)
		(end 127.383794 -89.984834)
		(width 0.0889)
		(layer "B.Cu")
		(net "P3E_CPU1_PE3_MP_TXP<14>")
	)
	(segment
		(start 121.590308 -108.048806)
		(end 123.243086 -106.396028)
		(width 0.1143)
		(layer "B.Cu")
		(net "P3E_CPU1_PE3_MP_TXP<14>")
	)
	(segment
		(start 128.205738 -89.489788)
		(end 128.238504 -89.489788)
		(width 0.0889)
		(layer "B.Cu")
		(net "P3E_CPU1_PE3_MP_TXP<14>")
	)
	(segment
		(start 135.073644 -85.527388)
		(end 135.116824 -85.527388)
		(width 0.0889)
		(layer "B.Cu")
		(net "P3E_CPU1_PE3_MP_TXP<14>")
	)
	(segment
		(start 126.856998 -96.223836)
		(end 126.861824 -96.2152)
		(width 0.0889)
		(layer "B.Cu")
		(net "P3E_CPU1_PE3_MP_TXP<14>")
	)
	(segment
		(start 126.856998 -98.205036)
		(end 126.861824 -98.1964)
		(width 0.0889)
		(layer "B.Cu")
		(net "P3E_CPU1_PE3_MP_TXP<14>")
	)
	(segment
		(start 16.05026 -104.17302)
		(end 19.246596 -104.17302)
		(width 0.1143)
		(layer "B.Cu")
		(net "P3E_CPU1_PE3_MP_TXP<14>")
	)
	(segment
		(start 126.770892 -102.904036)
		(end 126.770892 -101.34473)
		(width 0.0889)
		(layer "B.Cu")
		(net "P3E_CPU1_PE3_MP_TXP<14>")
	)
	(segment
		(start 123.25858 -106.380534)
		(end 123.29414 -106.380534)
		(width 0.0889)
		(layer "B.Cu")
		(net "P3E_CPU1_PE3_MP_TXP<14>")
	)
	(segment
		(start 126.850648 -98.215704)
		(end 126.856998 -98.205036)
		(width 0.0889)
		(layer "B.Cu")
		(net "P3E_CPU1_PE3_MP_TXP<14>")
	)
	(segment
		(start 139.953238 -91.239848)
		(end 140.246354 -91.070938)
		(width 0.0889)
		(layer "B.Cu")
		(net "P3E_CPU1_PE3_MP_TXP<14>")
	)
	(segment
		(start 130.785108 -88.003634)
		(end 130.817874 -88.003634)
		(width 0.0889)
		(layer "B.Cu")
		(net "P3E_CPU1_PE3_MP_TXP<14>")
	)
	(segment
		(start 136.801098 -86.517988)
		(end 136.833864 -86.517988)
		(width 0.0889)
		(layer "B.Cu")
		(net "P3E_CPU1_PE3_MP_TXP<14>")
	)
	(arc
		(start 129.432558 -88.794336)
		(mid 129.639562 -88.583472)
		(end 129.922778 -88.499188)
		(width 0.0889)
		(layer "B.Cu")
		(net "P3E_CPU1_PE3_MP_TXP<14>")
	)
	(arc
		(start 133.724904 -86.317836)
		(mid 133.933512 -86.105904)
		(end 134.218934 -86.022434)
		(width 0.0889)
		(layer "B.Cu")
		(net "P3E_CPU1_PE3_MP_TXP<14>")
	)
	(arc
		(start 126.861824 -100.1776)
		(mid 126.910579 -99.981248)
		(end 126.856998 -99.786186)
		(width 0.0889)
		(layer "B.Cu")
		(net "P3E_CPU1_PE3_MP_TXP<14>")
	)
	(arc
		(start 130.817874 -88.003634)
		(mid 131.009516 -87.946468)
		(end 131.149598 -87.803736)
		(width 0.0889)
		(layer "B.Cu")
		(net "P3E_CPU1_PE3_MP_TXP<14>")
	)
	(arc
		(start 139.405614 -90.975434)
		(mid 139.662436 -91.042735)
		(end 139.86383 -91.215718)
		(width 0.0889)
		(layer "B.Cu")
		(net "P3E_CPU1_PE3_MP_TXP<14>")
	)
	(arc
		(start 126.861824 -91.2622)
		(mid 126.910579 -91.065848)
		(end 126.856998 -90.870786)
		(width 0.0889)
		(layer "B.Cu")
		(net "P3E_CPU1_PE3_MP_TXP<14>")
	)
	(arc
		(start 128.574038 -89.289636)
		(mid 128.782646 -89.077704)
		(end 129.068068 -88.994234)
		(width 0.0889)
		(layer "B.Cu")
		(net "P3E_CPU1_PE3_MP_TXP<14>")
	)
	(arc
		(start 126.861824 -97.2058)
		(mid 126.910579 -97.009448)
		(end 126.856998 -96.814386)
		(width 0.0889)
		(layer "B.Cu")
		(net "P3E_CPU1_PE3_MP_TXP<14>")
	)
	(arc
		(start 137.688574 -87.013034)
		(mid 137.973998 -87.096501)
		(end 138.182604 -87.308436)
		(width 0.0889)
		(layer "B.Cu")
		(net "P3E_CPU1_PE3_MP_TXP<14>")
	)
	(arc
		(start 126.856998 -91.861386)
		(mid 126.777776 -91.572268)
		(end 126.850648 -91.281504)
		(width 0.0889)
		(layer "B.Cu")
		(net "P3E_CPU1_PE3_MP_TXP<14>")
	)
	(arc
		(start 126.856998 -93.842586)
		(mid 126.777776 -93.553468)
		(end 126.850648 -93.262704)
		(width 0.0889)
		(layer "B.Cu")
		(net "P3E_CPU1_PE3_MP_TXP<14>")
	)
	(arc
		(start 139.036298 -88.402922)
		(mid 138.987543 -88.599274)
		(end 139.041124 -88.794336)
		(width 0.0889)
		(layer "B.Cu")
		(net "P3E_CPU1_PE3_MP_TXP<14>")
	)
	(arc
		(start 135.971534 -86.022434)
		(mid 136.256958 -86.105901)
		(end 136.465564 -86.317836)
		(width 0.0889)
		(layer "B.Cu")
		(net "P3E_CPU1_PE3_MP_TXP<14>")
	)
	(arc
		(start 126.861824 -94.234)
		(mid 126.910579 -94.037648)
		(end 126.856998 -93.842586)
		(width 0.0889)
		(layer "B.Cu")
		(net "P3E_CPU1_PE3_MP_TXP<14>")
	)
	(arc
		(start 139.041124 -88.794336)
		(mid 139.120346 -89.083454)
		(end 139.047474 -89.374218)
		(width 0.0889)
		(layer "B.Cu")
		(net "P3E_CPU1_PE3_MP_TXP<14>")
	)
	(arc
		(start 126.856998 -95.232982)
		(mid 126.910497 -95.033084)
		(end 126.856998 -94.833186)
		(width 0.0889)
		(layer "B.Cu")
		(net "P3E_CPU1_PE3_MP_TXP<14>")
	)
	(arc
		(start 126.856998 -90.870786)
		(mid 126.852669 -90.287614)
		(end 127.351028 -89.984834)
		(width 0.0889)
		(layer "B.Cu")
		(net "P3E_CPU1_PE3_MP_TXP<14>")
	)
	(arc
		(start 137.324084 -86.813136)
		(mid 137.464163 -86.955872)
		(end 137.655808 -87.013034)
		(width 0.0889)
		(layer "B.Cu")
		(net "P3E_CPU1_PE3_MP_TXP<14>")
	)
	(arc
		(start 126.861824 -99.187)
		(mid 126.910579 -98.990648)
		(end 126.856998 -98.795586)
		(width 0.0889)
		(layer "B.Cu")
		(net "P3E_CPU1_PE3_MP_TXP<14>")
	)
	(arc
		(start 131.149598 -87.803736)
		(mid 131.356602 -87.592872)
		(end 131.639818 -87.508588)
		(width 0.0889)
		(layer "B.Cu")
		(net "P3E_CPU1_PE3_MP_TXP<14>")
	)
	(arc
		(start 126.8603 -101.209856)
		(mid 126.923468 -101.055664)
		(end 126.921768 -100.889054)
		(width 0.0889)
		(layer "B.Cu")
		(net "P3E_CPU1_PE3_MP_TXP<14>")
	)
	(arc
		(start 126.856998 -92.851986)
		(mid 126.777776 -92.562868)
		(end 126.850648 -92.272104)
		(width 0.0889)
		(layer "B.Cu")
		(net "P3E_CPU1_PE3_MP_TXP<14>")
	)
	(arc
		(start 127.383794 -89.984834)
		(mid 127.575436 -89.927668)
		(end 127.715518 -89.784936)
		(width 0.0889)
		(layer "B.Cu")
		(net "P3E_CPU1_PE3_MP_TXP<14>")
	)
	(arc
		(start 126.850648 -94.822518)
		(mid 126.77785 -94.531755)
		(end 126.856998 -94.242636)
		(width 0.0889)
		(layer "B.Cu")
		(net "P3E_CPU1_PE3_MP_TXP<14>")
	)
	(arc
		(start 130.291078 -88.299036)
		(mid 130.499686 -88.087104)
		(end 130.785108 -88.003634)
		(width 0.0889)
		(layer "B.Cu")
		(net "P3E_CPU1_PE3_MP_TXP<14>")
	)
	(arc
		(start 138.182604 -87.308436)
		(mid 138.324287 -87.45224)
		(end 138.518138 -87.508588)
		(width 0.0889)
		(layer "B.Cu")
		(net "P3E_CPU1_PE3_MP_TXP<14>")
	)
	(arc
		(start 132.53466 -87.013034)
		(mid 132.726302 -86.955868)
		(end 132.866384 -86.813136)
		(width 0.0889)
		(layer "B.Cu")
		(net "P3E_CPU1_PE3_MP_TXP<14>")
	)
	(arc
		(start 139.036298 -90.384122)
		(mid 139.040045 -90.773378)
		(end 139.372848 -90.975434)
		(width 0.0889)
		(layer "B.Cu")
		(net "P3E_CPU1_PE3_MP_TXP<14>")
	)
	(arc
		(start 126.856998 -96.814386)
		(mid 126.777776 -96.525268)
		(end 126.850648 -96.234504)
		(width 0.0889)
		(layer "B.Cu")
		(net "P3E_CPU1_PE3_MP_TXP<14>")
	)
	(arc
		(start 126.861824 -96.2152)
		(mid 126.910579 -96.018848)
		(end 126.856998 -95.823786)
		(width 0.0889)
		(layer "B.Cu")
		(net "P3E_CPU1_PE3_MP_TXP<14>")
	)
	(arc
		(start 126.861824 -98.1964)
		(mid 126.910579 -98.000048)
		(end 126.856998 -97.804986)
		(width 0.0889)
		(layer "B.Cu")
		(net "P3E_CPU1_PE3_MP_TXP<14>")
	)
	(arc
		(start 129.100834 -88.994234)
		(mid 129.292476 -88.937068)
		(end 129.432558 -88.794336)
		(width 0.0889)
		(layer "B.Cu")
		(net "P3E_CPU1_PE3_MP_TXP<14>")
	)
	(arc
		(start 138.550904 -87.508588)
		(mid 139.043294 -87.807521)
		(end 139.047474 -88.383618)
		(width 0.0889)
		(layer "B.Cu")
		(net "P3E_CPU1_PE3_MP_TXP<14>")
	)
	(arc
		(start 133.38937 -86.517988)
		(mid 133.58322 -86.461638)
		(end 133.724904 -86.317836)
		(width 0.0889)
		(layer "B.Cu")
		(net "P3E_CPU1_PE3_MP_TXP<14>")
	)
	(arc
		(start 136.833864 -86.517988)
		(mid 137.117081 -86.602269)
		(end 137.324084 -86.813136)
		(width 0.0889)
		(layer "B.Cu")
		(net "P3E_CPU1_PE3_MP_TXP<14>")
	)
	(arc
		(start 128.238504 -89.489788)
		(mid 128.432354 -89.433438)
		(end 128.574038 -89.289636)
		(width 0.0889)
		(layer "B.Cu")
		(net "P3E_CPU1_PE3_MP_TXP<14>")
	)
	(arc
		(start 135.116824 -85.527388)
		(mid 135.400041 -85.611669)
		(end 135.607044 -85.822536)
		(width 0.0889)
		(layer "B.Cu")
		(net "P3E_CPU1_PE3_MP_TXP<14>")
	)
	(arc
		(start 135.607044 -85.822536)
		(mid 135.747123 -85.965272)
		(end 135.938768 -86.022434)
		(width 0.0889)
		(layer "B.Cu")
		(net "P3E_CPU1_PE3_MP_TXP<14>")
	)
	(arc
		(start 126.856998 -99.786186)
		(mid 126.777776 -99.497068)
		(end 126.850648 -99.206304)
		(width 0.0889)
		(layer "B.Cu")
		(net "P3E_CPU1_PE3_MP_TXP<14>")
	)
	(arc
		(start 126.856998 -95.823786)
		(mid 126.777867 -95.528384)
		(end 126.856998 -95.232982)
		(width 0.0889)
		(layer "B.Cu")
		(net "P3E_CPU1_PE3_MP_TXP<14>")
	)
	(arc
		(start 134.2517 -86.022434)
		(mid 134.443342 -85.965268)
		(end 134.583424 -85.822536)
		(width 0.0889)
		(layer "B.Cu")
		(net "P3E_CPU1_PE3_MP_TXP<14>")
	)
	(arc
		(start 126.856998 -98.795586)
		(mid 126.777776 -98.506468)
		(end 126.850648 -98.215704)
		(width 0.0889)
		(layer "B.Cu")
		(net "P3E_CPU1_PE3_MP_TXP<14>")
	)
	(arc
		(start 129.955544 -88.499188)
		(mid 130.149394 -88.442838)
		(end 130.291078 -88.299036)
		(width 0.0889)
		(layer "B.Cu")
		(net "P3E_CPU1_PE3_MP_TXP<14>")
	)
	(arc
		(start 127.715518 -89.784936)
		(mid 127.922522 -89.574072)
		(end 128.205738 -89.489788)
		(width 0.0889)
		(layer "B.Cu")
		(net "P3E_CPU1_PE3_MP_TXP<14>")
	)
	(arc
		(start 139.041124 -89.784936)
		(mid 139.120346 -90.074054)
		(end 139.047474 -90.364818)
		(width 0.0889)
		(layer "B.Cu")
		(net "P3E_CPU1_PE3_MP_TXP<14>")
	)
	(arc
		(start 139.036298 -89.393522)
		(mid 138.987543 -89.589874)
		(end 139.041124 -89.784936)
		(width 0.0889)
		(layer "B.Cu")
		(net "P3E_CPU1_PE3_MP_TXP<14>")
	)
	(arc
		(start 126.861824 -92.2528)
		(mid 126.910579 -92.056448)
		(end 126.856998 -91.861386)
		(width 0.0889)
		(layer "B.Cu")
		(net "P3E_CPU1_PE3_MP_TXP<14>")
	)
	(arc
		(start 132.007864 -87.308436)
		(mid 132.216472 -87.096504)
		(end 132.501894 -87.013034)
		(width 0.0889)
		(layer "B.Cu")
		(net "P3E_CPU1_PE3_MP_TXP<14>")
	)
	(arc
		(start 131.661408 -87.508588)
		(mid 131.858569 -87.456629)
		(end 132.004562 -87.314278)
		(width 0.0889)
		(layer "B.Cu")
		(net "P3E_CPU1_PE3_MP_TXP<14>")
	)
	(arc
		(start 132.866384 -86.813136)
		(mid 133.073388 -86.602272)
		(end 133.356604 -86.517988)
		(width 0.0889)
		(layer "B.Cu")
		(net "P3E_CPU1_PE3_MP_TXP<14>")
	)
	(arc
		(start 126.861824 -93.2434)
		(mid 126.910579 -93.047048)
		(end 126.856998 -92.851986)
		(width 0.0889)
		(layer "B.Cu")
		(net "P3E_CPU1_PE3_MP_TXP<14>")
	)
	(arc
		(start 136.465564 -86.317836)
		(mid 136.607247 -86.46164)
		(end 136.801098 -86.517988)
		(width 0.0889)
		(layer "B.Cu")
		(net "P3E_CPU1_PE3_MP_TXP<14>")
	)
	(arc
		(start 126.850648 -100.766118)
		(mid 126.77785 -100.475355)
		(end 126.856998 -100.186236)
		(width 0.0889)
		(layer "B.Cu")
		(net "P3E_CPU1_PE3_MP_TXP<14>")
	)
	(arc
		(start 134.583424 -85.822536)
		(mid 134.790428 -85.611672)
		(end 135.073644 -85.527388)
		(width 0.0889)
		(layer "B.Cu")
		(net "P3E_CPU1_PE3_MP_TXP<14>")
	)
	(arc
		(start 126.856998 -97.804986)
		(mid 126.777776 -97.515868)
		(end 126.850648 -97.225104)
		(width 0.0889)
		(layer "B.Cu")
		(net "P3E_CPU1_PE3_MP_TXP<14>")
	)
	(segment
		(start 137.957814 -92.061538)
		(end 138.529314 -92.061538)
		(width 0.1143)
		(layer "F.Cu")
		(net "P3E_CPU1_PE3_MP_TXP<13>")
	)
	(via
		(at 138.529314 -92.061538)
		(size 0.508)
		(drill 0.254)
		(layers "F.Cu" "B.Cu")
		(net "P3E_CPU1_PE3_MP_TXP<13>")
	)
	(via
		(at 32.1818 -115.4176)
		(size 0.508)
		(drill 0.254)
		(layers "F.Cu" "B.Cu")
		(net "P3E_CPU1_PE3_MP_TXP<13>")
	)
	(segment
		(start 125.843538 -105.651808)
		(end 125.969268 -105.526078)
		(width 0.0889)
		(layer "B.Cu")
		(net "P3E_CPU1_PE3_MP_TXP<13>")
	)
	(segment
		(start 108.621322 -110.20298)
		(end 113.196624 -111.118142)
		(width 0.1143)
		(layer "B.Cu")
		(net "P3E_CPU1_PE3_MP_TXP<13>")
	)
	(segment
		(start 113.196624 -111.118142)
		(end 122.029982 -109.36097)
		(width 0.1143)
		(layer "B.Cu")
		(net "P3E_CPU1_PE3_MP_TXP<13>")
	)
	(segment
		(start 126.486412 -104.868472)
		(end 126.626874 -104.868472)
		(width 0.0889)
		(layer "B.Cu")
		(net "P3E_CPU1_PE3_MP_TXP<13>")
	)
	(segment
		(start 138.511534 -91.661488)
		(end 138.5443 -91.661488)
		(width 0.0889)
		(layer "B.Cu")
		(net "P3E_CPU1_PE3_MP_TXP<13>")
	)
	(segment
		(start 129.929382 -89.680288)
		(end 129.962148 -89.680288)
		(width 0.0889)
		(layer "B.Cu")
		(net "P3E_CPU1_PE3_MP_TXP<13>")
	)
	(segment
		(start 122.029982 -109.36097)
		(end 125.04674 -106.344212)
		(width 0.1143)
		(layer "B.Cu")
		(net "P3E_CPU1_PE3_MP_TXP<13>")
	)
	(segment
		(start 83.638644 -107.673394)
		(end 85.938868 -108.133134)
		(width 0.1143)
		(layer "B.Cu")
		(net "P3E_CPU1_PE3_MP_TXP<13>")
	)
	(segment
		(start 126.752604 -104.742742)
		(end 126.752604 -104.60228)
		(width 0.0889)
		(layer "B.Cu")
		(net "P3E_CPU1_PE3_MP_TXP<13>")
	)
	(segment
		(start 127.886968 -93.262704)
		(end 127.880618 -93.252036)
		(width 0.0889)
		(layer "B.Cu")
		(net "P3E_CPU1_PE3_MP_TXP<13>")
	)
	(segment
		(start 127.886968 -98.215704)
		(end 127.880618 -98.205036)
		(width 0.0889)
		(layer "B.Cu")
		(net "P3E_CPU1_PE3_MP_TXP<13>")
	)
	(segment
		(start 126.235206 -105.26014)
		(end 126.360936 -105.13441)
		(width 0.0889)
		(layer "B.Cu")
		(net "P3E_CPU1_PE3_MP_TXP<13>")
	)
	(segment
		(start 36.412932 -115.4176)
		(end 53.13045 -113.771172)
		(width 0.1143)
		(layer "B.Cu")
		(net "P3E_CPU1_PE3_MP_TXP<13>")
	)
	(segment
		(start 125.311408 -106.043476)
		(end 125.45187 -106.043476)
		(width 0.0889)
		(layer "B.Cu")
		(net "P3E_CPU1_PE3_MP_TXP<13>")
	)
	(segment
		(start 132.519674 -88.194134)
		(end 132.541264 -88.194134)
		(width 0.0889)
		(layer "B.Cu")
		(net "P3E_CPU1_PE3_MP_TXP<13>")
	)
	(segment
		(start 125.703076 -105.651808)
		(end 125.843538 -105.651808)
		(width 0.0889)
		(layer "B.Cu")
		(net "P3E_CPU1_PE3_MP_TXP<13>")
	)
	(segment
		(start 53.13045 -113.771172)
		(end 83.638644 -107.673394)
		(width 0.1143)
		(layer "B.Cu")
		(net "P3E_CPU1_PE3_MP_TXP<13>")
	)
	(segment
		(start 125.45187 -106.043476)
		(end 125.5776 -105.917746)
		(width 0.0889)
		(layer "B.Cu")
		(net "P3E_CPU1_PE3_MP_TXP<13>")
	)
	(segment
		(start 125.5776 -105.917746)
		(end 125.5776 -105.777284)
		(width 0.0889)
		(layer "B.Cu")
		(net "P3E_CPU1_PE3_MP_TXP<13>")
	)
	(segment
		(start 18.72742 -106.09072)
		(end 19.007582 -105.810558)
		(width 0.1143)
		(layer "B.Cu")
		(net "P3E_CPU1_PE3_MP_TXP<13>")
	)
	(segment
		(start 127.886968 -99.206304)
		(end 127.880618 -99.195636)
		(width 0.0889)
		(layer "B.Cu")
		(net "P3E_CPU1_PE3_MP_TXP<13>")
	)
	(segment
		(start 102.694994 -110.297976)
		(end 105.419144 -110.84306)
		(width 0.1143)
		(layer "B.Cu")
		(net "P3E_CPU1_PE3_MP_TXP<13>")
	)
	(segment
		(start 125.5776 -105.777284)
		(end 125.703076 -105.651808)
		(width 0.0889)
		(layer "B.Cu")
		(net "P3E_CPU1_PE3_MP_TXP<13>")
	)
	(segment
		(start 21.36267 -108.72978)
		(end 25.916382 -113.283746)
		(width 0.1143)
		(layer "B.Cu")
		(net "P3E_CPU1_PE3_MP_TXP<13>")
	)
	(segment
		(start 127.880618 -98.205036)
		(end 127.875792 -98.1964)
		(width 0.0889)
		(layer "B.Cu")
		(net "P3E_CPU1_PE3_MP_TXP<13>")
	)
	(segment
		(start 127.926084 -102.247192)
		(end 127.89154 -102.187248)
		(width 0.0889)
		(layer "B.Cu")
		(net "P3E_CPU1_PE3_MP_TXP<13>")
	)
	(segment
		(start 138.011154 -90.364818)
		(end 138.017504 -90.375486)
		(width 0.0889)
		(layer "B.Cu")
		(net "P3E_CPU1_PE3_MP_TXP<13>")
	)
	(segment
		(start 127.886968 -97.225104)
		(end 127.880618 -97.214436)
		(width 0.0889)
		(layer "B.Cu")
		(net "P3E_CPU1_PE3_MP_TXP<13>")
	)
	(segment
		(start 127.880618 -96.223836)
		(end 127.875792 -96.2152)
		(width 0.0889)
		(layer "B.Cu")
		(net "P3E_CPU1_PE3_MP_TXP<13>")
	)
	(segment
		(start 127.269748 -104.085136)
		(end 127.41021 -104.085136)
		(width 0.0889)
		(layer "B.Cu")
		(net "P3E_CPU1_PE3_MP_TXP<13>")
	)
	(segment
		(start 32.1818 -115.4176)
		(end 36.412932 -115.4176)
		(width 0.1143)
		(layer "B.Cu")
		(net "P3E_CPU1_PE3_MP_TXP<13>")
	)
	(segment
		(start 135.932164 -87.203534)
		(end 135.96493 -87.203534)
		(width 0.0889)
		(layer "B.Cu")
		(net "P3E_CPU1_PE3_MP_TXP<13>")
	)
	(segment
		(start 126.752604 -104.60228)
		(end 126.87808 -104.476804)
		(width 0.0889)
		(layer "B.Cu")
		(net "P3E_CPU1_PE3_MP_TXP<13>")
	)
	(segment
		(start 125.969268 -105.526078)
		(end 125.969268 -105.385616)
		(width 0.0889)
		(layer "B.Cu")
		(net "P3E_CPU1_PE3_MP_TXP<13>")
	)
	(segment
		(start 127.880618 -93.252036)
		(end 127.875792 -93.2434)
		(width 0.0889)
		(layer "B.Cu")
		(net "P3E_CPU1_PE3_MP_TXP<13>")
	)
	(segment
		(start 127.41021 -104.085136)
		(end 127.53594 -103.959406)
		(width 0.0889)
		(layer "B.Cu")
		(net "P3E_CPU1_PE3_MP_TXP<13>")
	)
	(segment
		(start 87.9475 -109.472222)
		(end 97.386394 -111.359696)
		(width 0.1143)
		(layer "B.Cu")
		(net "P3E_CPU1_PE3_MP_TXP<13>")
	)
	(segment
		(start 127.880618 -91.270836)
		(end 127.875792 -91.2622)
		(width 0.0889)
		(layer "B.Cu")
		(net "P3E_CPU1_PE3_MP_TXP<13>")
	)
	(segment
		(start 138.011154 -89.374218)
		(end 138.017504 -89.384886)
		(width 0.0889)
		(layer "B.Cu")
		(net "P3E_CPU1_PE3_MP_TXP<13>")
	)
	(segment
		(start 21.36267 -108.003594)
		(end 21.36267 -108.72978)
		(width 0.1143)
		(layer "B.Cu")
		(net "P3E_CPU1_PE3_MP_TXP<13>")
	)
	(segment
		(start 131.646422 -88.689688)
		(end 131.679188 -88.689688)
		(width 0.0889)
		(layer "B.Cu")
		(net "P3E_CPU1_PE3_MP_TXP<13>")
	)
	(segment
		(start 127.875792 -100.785422)
		(end 127.886968 -100.766118)
		(width 0.0889)
		(layer "B.Cu")
		(net "P3E_CPU1_PE3_MP_TXP<13>")
	)
	(segment
		(start 127.880618 -99.195636)
		(end 127.875792 -99.187)
		(width 0.0889)
		(layer "B.Cu")
		(net "P3E_CPU1_PE3_MP_TXP<13>")
	)
	(segment
		(start 134.225538 -87.203534)
		(end 134.258304 -87.203534)
		(width 0.0889)
		(layer "B.Cu")
		(net "P3E_CPU1_PE3_MP_TXP<13>")
	)
	(segment
		(start 128.212342 -90.670888)
		(end 128.245108 -90.670888)
		(width 0.0889)
		(layer "B.Cu")
		(net "P3E_CPU1_PE3_MP_TXP<13>")
	)
	(segment
		(start 127.886968 -91.281504)
		(end 127.880618 -91.270836)
		(width 0.0889)
		(layer "B.Cu")
		(net "P3E_CPU1_PE3_MP_TXP<13>")
	)
	(segment
		(start 125.969268 -105.385616)
		(end 126.094744 -105.26014)
		(width 0.0889)
		(layer "B.Cu")
		(net "P3E_CPU1_PE3_MP_TXP<13>")
	)
	(segment
		(start 137.649204 -88.194134)
		(end 137.68197 -88.194134)
		(width 0.0889)
		(layer "B.Cu")
		(net "P3E_CPU1_PE3_MP_TXP<13>")
	)
	(segment
		(start 127.886968 -92.272104)
		(end 127.880618 -92.261436)
		(width 0.0889)
		(layer "B.Cu")
		(net "P3E_CPU1_PE3_MP_TXP<13>")
	)
	(segment
		(start 127.880618 -92.261436)
		(end 127.875792 -92.2528)
		(width 0.0889)
		(layer "B.Cu")
		(net "P3E_CPU1_PE3_MP_TXP<13>")
	)
	(segment
		(start 136.794494 -87.699088)
		(end 136.82726 -87.699088)
		(width 0.0889)
		(layer "B.Cu")
		(net "P3E_CPU1_PE3_MP_TXP<13>")
	)
	(segment
		(start 127.53594 -103.959406)
		(end 127.53594 -103.818944)
		(width 0.0889)
		(layer "B.Cu")
		(net "P3E_CPU1_PE3_MP_TXP<13>")
	)
	(segment
		(start 138.017504 -89.384886)
		(end 138.02233 -89.393522)
		(width 0.0889)
		(layer "B.Cu")
		(net "P3E_CPU1_PE3_MP_TXP<13>")
	)
	(segment
		(start 97.386394 -111.359696)
		(end 102.694994 -110.297976)
		(width 0.1143)
		(layer "B.Cu")
		(net "P3E_CPU1_PE3_MP_TXP<13>")
	)
	(segment
		(start 127.880618 -94.242636)
		(end 127.875792 -94.234)
		(width 0.0889)
		(layer "B.Cu")
		(net "P3E_CPU1_PE3_MP_TXP<13>")
	)
	(segment
		(start 138.017504 -90.375486)
		(end 138.02233 -90.384122)
		(width 0.0889)
		(layer "B.Cu")
		(net "P3E_CPU1_PE3_MP_TXP<13>")
	)
	(segment
		(start 19.007582 -105.810558)
		(end 19.169634 -105.810558)
		(width 0.1143)
		(layer "B.Cu")
		(net "P3E_CPU1_PE3_MP_TXP<13>")
	)
	(segment
		(start 125.062234 -106.29265)
		(end 125.311408 -106.043476)
		(width 0.0889)
		(layer "B.Cu")
		(net "P3E_CPU1_PE3_MP_TXP<13>")
	)
	(segment
		(start 105.419144 -110.84306)
		(end 108.621322 -110.20298)
		(width 0.1143)
		(layer "B.Cu")
		(net "P3E_CPU1_PE3_MP_TXP<13>")
	)
	(segment
		(start 138.90117 -92.209112)
		(end 138.82243 -92.230448)
		(width 0.0889)
		(layer "B.Cu")
		(net "P3E_CPU1_PE3_MP_TXP<13>")
	)
	(segment
		(start 132.173218 -88.394286)
		(end 132.17652 -88.388444)
		(width 0.0889)
		(layer "B.Cu")
		(net "P3E_CPU1_PE3_MP_TXP<13>")
	)
	(segment
		(start 25.916382 -113.283746)
		(end 31.068264 -115.4176)
		(width 0.1143)
		(layer "B.Cu")
		(net "P3E_CPU1_PE3_MP_TXP<13>")
	)
	(segment
		(start 126.360936 -105.13441)
		(end 126.360936 -104.993948)
		(width 0.0889)
		(layer "B.Cu")
		(net "P3E_CPU1_PE3_MP_TXP<13>")
	)
	(segment
		(start 127.880618 -97.214436)
		(end 127.875792 -97.2058)
		(width 0.0889)
		(layer "B.Cu")
		(net "P3E_CPU1_PE3_MP_TXP<13>")
	)
	(segment
		(start 127.144272 -104.351074)
		(end 127.144272 -104.210612)
		(width 0.0889)
		(layer "B.Cu")
		(net "P3E_CPU1_PE3_MP_TXP<13>")
	)
	(segment
		(start 127.880618 -94.833186)
		(end 127.886968 -94.822518)
		(width 0.0889)
		(layer "B.Cu")
		(net "P3E_CPU1_PE3_MP_TXP<13>")
	)
	(segment
		(start 129.074672 -90.175334)
		(end 129.107438 -90.175334)
		(width 0.0889)
		(layer "B.Cu")
		(net "P3E_CPU1_PE3_MP_TXP<13>")
	)
	(segment
		(start 130.791712 -89.184734)
		(end 130.824478 -89.184734)
		(width 0.0889)
		(layer "B.Cu")
		(net "P3E_CPU1_PE3_MP_TXP<13>")
	)
	(segment
		(start 127.880618 -100.186236)
		(end 127.875792 -100.1776)
		(width 0.0889)
		(layer "B.Cu")
		(net "P3E_CPU1_PE3_MP_TXP<13>")
	)
	(segment
		(start 138.82243 -92.230448)
		(end 138.529314 -92.061538)
		(width 0.0889)
		(layer "B.Cu")
		(net "P3E_CPU1_PE3_MP_TXP<13>")
	)
	(segment
		(start 31.068264 -115.4176)
		(end 32.1818 -115.4176)
		(width 0.1143)
		(layer "B.Cu")
		(net "P3E_CPU1_PE3_MP_TXP<13>")
	)
	(segment
		(start 127.53594 -103.818944)
		(end 127.926084 -103.4288)
		(width 0.0889)
		(layer "B.Cu")
		(net "P3E_CPU1_PE3_MP_TXP<13>")
	)
	(segment
		(start 133.363208 -87.699088)
		(end 133.395974 -87.699088)
		(width 0.0889)
		(layer "B.Cu")
		(net "P3E_CPU1_PE3_MP_TXP<13>")
	)
	(segment
		(start 126.094744 -105.26014)
		(end 126.235206 -105.26014)
		(width 0.0889)
		(layer "B.Cu")
		(net "P3E_CPU1_PE3_MP_TXP<13>")
	)
	(segment
		(start 125.062234 -106.328718)
		(end 125.062234 -106.29265)
		(width 0.0889)
		(layer "B.Cu")
		(net "P3E_CPU1_PE3_MP_TXP<13>")
	)
	(segment
		(start 126.87808 -104.476804)
		(end 127.018542 -104.476804)
		(width 0.0889)
		(layer "B.Cu")
		(net "P3E_CPU1_PE3_MP_TXP<13>")
	)
	(segment
		(start 127.926084 -103.4288)
		(end 127.926084 -102.247192)
		(width 0.0889)
		(layer "B.Cu")
		(net "P3E_CPU1_PE3_MP_TXP<13>")
	)
	(segment
		(start 85.938868 -108.133134)
		(end 87.9475 -109.472222)
		(width 0.1143)
		(layer "B.Cu")
		(net "P3E_CPU1_PE3_MP_TXP<13>")
	)
	(segment
		(start 127.018542 -104.476804)
		(end 127.144272 -104.351074)
		(width 0.0889)
		(layer "B.Cu")
		(net "P3E_CPU1_PE3_MP_TXP<13>")
	)
	(segment
		(start 19.169634 -105.810558)
		(end 21.36267 -108.003594)
		(width 0.1143)
		(layer "B.Cu")
		(net "P3E_CPU1_PE3_MP_TXP<13>")
	)
	(segment
		(start 126.360936 -104.993948)
		(end 126.486412 -104.868472)
		(width 0.0889)
		(layer "B.Cu")
		(net "P3E_CPU1_PE3_MP_TXP<13>")
	)
	(segment
		(start 125.04674 -106.344212)
		(end 125.062234 -106.328718)
		(width 0.0889)
		(layer "B.Cu")
		(net "P3E_CPU1_PE3_MP_TXP<13>")
	)
	(segment
		(start 127.144272 -104.210612)
		(end 127.269748 -104.085136)
		(width 0.0889)
		(layer "B.Cu")
		(net "P3E_CPU1_PE3_MP_TXP<13>")
	)
	(segment
		(start 135.080248 -86.708488)
		(end 135.11022 -86.708488)
		(width 0.0889)
		(layer "B.Cu")
		(net "P3E_CPU1_PE3_MP_TXP<13>")
	)
	(segment
		(start 127.886968 -96.234504)
		(end 127.880618 -96.223836)
		(width 0.0889)
		(layer "B.Cu")
		(net "P3E_CPU1_PE3_MP_TXP<13>")
	)
	(segment
		(start 126.626874 -104.868472)
		(end 126.752604 -104.742742)
		(width 0.0889)
		(layer "B.Cu")
		(net "P3E_CPU1_PE3_MP_TXP<13>")
	)
	(arc
		(start 136.82726 -87.699088)
		(mid 137.018902 -87.756254)
		(end 137.158984 -87.898986)
		(width 0.0889)
		(layer "B.Cu")
		(net "P3E_CPU1_PE3_MP_TXP<13>")
	)
	(arc
		(start 127.880618 -98.795586)
		(mid 127.95984 -98.506468)
		(end 127.886968 -98.215704)
		(width 0.0889)
		(layer "B.Cu")
		(net "P3E_CPU1_PE3_MP_TXP<13>")
	)
	(arc
		(start 131.679188 -88.689688)
		(mid 131.964612 -88.606221)
		(end 132.173218 -88.394286)
		(width 0.0889)
		(layer "B.Cu")
		(net "P3E_CPU1_PE3_MP_TXP<13>")
	)
	(arc
		(start 138.017504 -88.794336)
		(mid 137.938282 -89.083454)
		(end 138.011154 -89.374218)
		(width 0.0889)
		(layer "B.Cu")
		(net "P3E_CPU1_PE3_MP_TXP<13>")
	)
	(arc
		(start 135.441944 -86.908386)
		(mid 135.648948 -87.11925)
		(end 135.932164 -87.203534)
		(width 0.0889)
		(layer "B.Cu")
		(net "P3E_CPU1_PE3_MP_TXP<13>")
	)
	(arc
		(start 138.017504 -90.775536)
		(mid 138.013175 -91.358708)
		(end 138.511534 -91.661488)
		(width 0.0889)
		(layer "B.Cu")
		(net "P3E_CPU1_PE3_MP_TXP<13>")
	)
	(arc
		(start 127.875792 -92.2528)
		(mid 127.827037 -92.056448)
		(end 127.880618 -91.861386)
		(width 0.0889)
		(layer "B.Cu")
		(net "P3E_CPU1_PE3_MP_TXP<13>")
	)
	(arc
		(start 137.68197 -88.194134)
		(mid 138.020139 -88.398932)
		(end 138.017504 -88.794336)
		(width 0.0889)
		(layer "B.Cu")
		(net "P3E_CPU1_PE3_MP_TXP<13>")
	)
	(arc
		(start 127.880618 -95.232982)
		(mid 127.827119 -95.033084)
		(end 127.880618 -94.833186)
		(width 0.0889)
		(layer "B.Cu")
		(net "P3E_CPU1_PE3_MP_TXP<13>")
	)
	(arc
		(start 127.875792 -91.2622)
		(mid 127.879539 -90.872944)
		(end 128.212342 -90.670888)
		(width 0.0889)
		(layer "B.Cu")
		(net "P3E_CPU1_PE3_MP_TXP<13>")
	)
	(arc
		(start 127.880618 -99.786186)
		(mid 127.95984 -99.497068)
		(end 127.886968 -99.206304)
		(width 0.0889)
		(layer "B.Cu")
		(net "P3E_CPU1_PE3_MP_TXP<13>")
	)
	(arc
		(start 127.880618 -91.861386)
		(mid 127.95984 -91.572268)
		(end 127.886968 -91.281504)
		(width 0.0889)
		(layer "B.Cu")
		(net "P3E_CPU1_PE3_MP_TXP<13>")
	)
	(arc
		(start 130.824478 -89.184734)
		(mid 131.107695 -89.100453)
		(end 131.314698 -88.889586)
		(width 0.0889)
		(layer "B.Cu")
		(net "P3E_CPU1_PE3_MP_TXP<13>")
	)
	(arc
		(start 127.880618 -96.814386)
		(mid 127.95984 -96.525268)
		(end 127.886968 -96.234504)
		(width 0.0889)
		(layer "B.Cu")
		(net "P3E_CPU1_PE3_MP_TXP<13>")
	)
	(arc
		(start 138.017504 -89.784936)
		(mid 137.938282 -90.074054)
		(end 138.011154 -90.364818)
		(width 0.0889)
		(layer "B.Cu")
		(net "P3E_CPU1_PE3_MP_TXP<13>")
	)
	(arc
		(start 127.89154 -102.187248)
		(mid 127.700122 -101.488385)
		(end 127.875792 -100.785422)
		(width 0.0889)
		(layer "B.Cu")
		(net "P3E_CPU1_PE3_MP_TXP<13>")
	)
	(arc
		(start 127.886968 -94.822518)
		(mid 127.959766 -94.531755)
		(end 127.880618 -94.242636)
		(width 0.0889)
		(layer "B.Cu")
		(net "P3E_CPU1_PE3_MP_TXP<13>")
	)
	(arc
		(start 134.748524 -86.908386)
		(mid 134.888603 -86.76565)
		(end 135.080248 -86.708488)
		(width 0.0889)
		(layer "B.Cu")
		(net "P3E_CPU1_PE3_MP_TXP<13>")
	)
	(arc
		(start 127.880618 -93.842586)
		(mid 127.95984 -93.553468)
		(end 127.886968 -93.262704)
		(width 0.0889)
		(layer "B.Cu")
		(net "P3E_CPU1_PE3_MP_TXP<13>")
	)
	(arc
		(start 127.875792 -96.2152)
		(mid 127.827037 -96.018848)
		(end 127.880618 -95.823786)
		(width 0.0889)
		(layer "B.Cu")
		(net "P3E_CPU1_PE3_MP_TXP<13>")
	)
	(arc
		(start 127.886968 -100.766118)
		(mid 127.959766 -100.475355)
		(end 127.880618 -100.186236)
		(width 0.0889)
		(layer "B.Cu")
		(net "P3E_CPU1_PE3_MP_TXP<13>")
	)
	(arc
		(start 133.031484 -87.898986)
		(mid 133.171563 -87.75625)
		(end 133.363208 -87.699088)
		(width 0.0889)
		(layer "B.Cu")
		(net "P3E_CPU1_PE3_MP_TXP<13>")
	)
	(arc
		(start 127.875792 -94.234)
		(mid 127.827037 -94.037648)
		(end 127.880618 -93.842586)
		(width 0.0889)
		(layer "B.Cu")
		(net "P3E_CPU1_PE3_MP_TXP<13>")
	)
	(arc
		(start 132.17652 -88.388444)
		(mid 132.322486 -88.246045)
		(end 132.519674 -88.194134)
		(width 0.0889)
		(layer "B.Cu")
		(net "P3E_CPU1_PE3_MP_TXP<13>")
	)
	(arc
		(start 132.541264 -88.194134)
		(mid 132.824481 -88.109853)
		(end 133.031484 -87.898986)
		(width 0.0889)
		(layer "B.Cu")
		(net "P3E_CPU1_PE3_MP_TXP<13>")
	)
	(arc
		(start 137.158984 -87.898986)
		(mid 137.365988 -88.10985)
		(end 137.649204 -88.194134)
		(width 0.0889)
		(layer "B.Cu")
		(net "P3E_CPU1_PE3_MP_TXP<13>")
	)
	(arc
		(start 138.02233 -90.384122)
		(mid 138.071085 -90.580474)
		(end 138.017504 -90.775536)
		(width 0.0889)
		(layer "B.Cu")
		(net "P3E_CPU1_PE3_MP_TXP<13>")
	)
	(arc
		(start 128.739138 -90.375486)
		(mid 128.880821 -90.231682)
		(end 129.074672 -90.175334)
		(width 0.0889)
		(layer "B.Cu")
		(net "P3E_CPU1_PE3_MP_TXP<13>")
	)
	(arc
		(start 130.456178 -89.384886)
		(mid 130.597861 -89.241082)
		(end 130.791712 -89.184734)
		(width 0.0889)
		(layer "B.Cu")
		(net "P3E_CPU1_PE3_MP_TXP<13>")
	)
	(arc
		(start 134.258304 -87.203534)
		(mid 134.541521 -87.119253)
		(end 134.748524 -86.908386)
		(width 0.0889)
		(layer "B.Cu")
		(net "P3E_CPU1_PE3_MP_TXP<13>")
	)
	(arc
		(start 127.875792 -99.187)
		(mid 127.827037 -98.990648)
		(end 127.880618 -98.795586)
		(width 0.0889)
		(layer "B.Cu")
		(net "P3E_CPU1_PE3_MP_TXP<13>")
	)
	(arc
		(start 133.890004 -87.403686)
		(mid 134.031687 -87.259882)
		(end 134.225538 -87.203534)
		(width 0.0889)
		(layer "B.Cu")
		(net "P3E_CPU1_PE3_MP_TXP<13>")
	)
	(arc
		(start 129.962148 -89.680288)
		(mid 130.247572 -89.596821)
		(end 130.456178 -89.384886)
		(width 0.0889)
		(layer "B.Cu")
		(net "P3E_CPU1_PE3_MP_TXP<13>")
	)
	(arc
		(start 131.314698 -88.889586)
		(mid 131.454777 -88.74685)
		(end 131.646422 -88.689688)
		(width 0.0889)
		(layer "B.Cu")
		(net "P3E_CPU1_PE3_MP_TXP<13>")
	)
	(arc
		(start 138.5443 -91.661488)
		(mid 138.86446 -91.842953)
		(end 138.90117 -92.209112)
		(width 0.0889)
		(layer "B.Cu")
		(net "P3E_CPU1_PE3_MP_TXP<13>")
	)
	(arc
		(start 129.597658 -89.880186)
		(mid 129.737737 -89.73745)
		(end 129.929382 -89.680288)
		(width 0.0889)
		(layer "B.Cu")
		(net "P3E_CPU1_PE3_MP_TXP<13>")
	)
	(arc
		(start 135.96493 -87.203534)
		(mid 136.15878 -87.259884)
		(end 136.300464 -87.403686)
		(width 0.0889)
		(layer "B.Cu")
		(net "P3E_CPU1_PE3_MP_TXP<13>")
	)
	(arc
		(start 136.300464 -87.403686)
		(mid 136.509072 -87.615618)
		(end 136.794494 -87.699088)
		(width 0.0889)
		(layer "B.Cu")
		(net "P3E_CPU1_PE3_MP_TXP<13>")
	)
	(arc
		(start 135.11022 -86.708488)
		(mid 135.301862 -86.765654)
		(end 135.441944 -86.908386)
		(width 0.0889)
		(layer "B.Cu")
		(net "P3E_CPU1_PE3_MP_TXP<13>")
	)
	(arc
		(start 127.880618 -92.851986)
		(mid 127.95984 -92.562868)
		(end 127.886968 -92.272104)
		(width 0.0889)
		(layer "B.Cu")
		(net "P3E_CPU1_PE3_MP_TXP<13>")
	)
	(arc
		(start 127.875792 -100.1776)
		(mid 127.827037 -99.981248)
		(end 127.880618 -99.786186)
		(width 0.0889)
		(layer "B.Cu")
		(net "P3E_CPU1_PE3_MP_TXP<13>")
	)
	(arc
		(start 129.107438 -90.175334)
		(mid 129.390655 -90.091053)
		(end 129.597658 -89.880186)
		(width 0.0889)
		(layer "B.Cu")
		(net "P3E_CPU1_PE3_MP_TXP<13>")
	)
	(arc
		(start 127.875792 -98.1964)
		(mid 127.827037 -98.000048)
		(end 127.880618 -97.804986)
		(width 0.0889)
		(layer "B.Cu")
		(net "P3E_CPU1_PE3_MP_TXP<13>")
	)
	(arc
		(start 127.875792 -97.2058)
		(mid 127.827037 -97.009448)
		(end 127.880618 -96.814386)
		(width 0.0889)
		(layer "B.Cu")
		(net "P3E_CPU1_PE3_MP_TXP<13>")
	)
	(arc
		(start 138.02233 -89.393522)
		(mid 138.071085 -89.589874)
		(end 138.017504 -89.784936)
		(width 0.0889)
		(layer "B.Cu")
		(net "P3E_CPU1_PE3_MP_TXP<13>")
	)
	(arc
		(start 127.880618 -97.804986)
		(mid 127.95984 -97.515868)
		(end 127.886968 -97.225104)
		(width 0.0889)
		(layer "B.Cu")
		(net "P3E_CPU1_PE3_MP_TXP<13>")
	)
	(arc
		(start 127.875792 -93.2434)
		(mid 127.827037 -93.047048)
		(end 127.880618 -92.851986)
		(width 0.0889)
		(layer "B.Cu")
		(net "P3E_CPU1_PE3_MP_TXP<13>")
	)
	(arc
		(start 128.245108 -90.670888)
		(mid 128.530532 -90.587421)
		(end 128.739138 -90.375486)
		(width 0.0889)
		(layer "B.Cu")
		(net "P3E_CPU1_PE3_MP_TXP<13>")
	)
	(arc
		(start 127.880618 -95.823786)
		(mid 127.959749 -95.528384)
		(end 127.880618 -95.232982)
		(width 0.0889)
		(layer "B.Cu")
		(net "P3E_CPU1_PE3_MP_TXP<13>")
	)
	(arc
		(start 133.395974 -87.699088)
		(mid 133.681398 -87.615621)
		(end 133.890004 -87.403686)
		(width 0.0889)
		(layer "B.Cu")
		(net "P3E_CPU1_PE3_MP_TXP<13>")
	)
	(segment
		(start 137.957814 -94.042738)
		(end 138.529314 -94.042738)
		(width 0.1143)
		(layer "F.Cu")
		(net "P3E_CPU1_PE3_MP_TXP<12>")
	)
	(via
		(at 26.364946 -109.560868)
		(size 0.508)
		(drill 0.254)
		(layers "F.Cu" "B.Cu")
		(net "P3E_CPU1_PE3_MP_TXP<12>")
	)
	(via
		(at 138.529314 -94.042738)
		(size 0.508)
		(drill 0.254)
		(layers "F.Cu" "B.Cu")
		(net "P3E_CPU1_PE3_MP_TXP<12>")
	)
	(segment
		(start 125.382274 -101.806248)
		(end 125.305058 -101.672136)
		(width 0.0889)
		(layer "B.Cu")
		(net "P3E_CPU1_PE3_MP_TXP<12>")
	)
	(segment
		(start 22.102064 -103.661718)
		(end 20.371054 -101.9302)
		(width 0.1143)
		(layer "B.Cu")
		(net "P3E_CPU1_PE3_MP_TXP<12>")
	)
	(segment
		(start 122.666506 -104.33685)
		(end 122.78868 -104.33685)
		(width 0.0889)
		(layer "B.Cu")
		(net "P3E_CPU1_PE3_MP_TXP<12>")
	)
	(segment
		(start 121.752106 -105.251504)
		(end 121.877582 -105.125774)
		(width 0.0889)
		(layer "B.Cu")
		(net "P3E_CPU1_PE3_MP_TXP<12>")
	)
	(segment
		(start 120.30837 -106.384344)
		(end 120.696228 -106.307382)
		(width 0.0889)
		(layer "B.Cu")
		(net "P3E_CPU1_PE3_MP_TXP<12>")
	)
	(segment
		(start 105.743756 -107.729782)
		(end 109.125258 -107.053126)
		(width 0.1143)
		(layer "B.Cu")
		(net "P3E_CPU1_PE3_MP_TXP<12>")
	)
	(segment
		(start 120.696228 -106.307382)
		(end 121.109486 -105.894124)
		(width 0.0889)
		(layer "B.Cu")
		(net "P3E_CPU1_PE3_MP_TXP<12>")
	)
	(segment
		(start 124.447554 -103.197914)
		(end 125.382274 -102.263194)
		(width 0.0889)
		(layer "B.Cu")
		(net "P3E_CPU1_PE3_MP_TXP<12>")
	)
	(segment
		(start 134.225538 -84.231734)
		(end 134.258304 -84.231734)
		(width 0.0889)
		(layer "B.Cu")
		(net "P3E_CPU1_PE3_MP_TXP<12>")
	)
	(segment
		(start 139.40282 -93.947234)
		(end 139.37488 -93.947234)
		(width 0.0889)
		(layer "B.Cu")
		(net "P3E_CPU1_PE3_MP_TXP<12>")
	)
	(segment
		(start 125.300232 -90.384122)
		(end 125.305058 -90.375486)
		(width 0.0889)
		(layer "B.Cu")
		(net "P3E_CPU1_PE3_MP_TXP<12>")
	)
	(segment
		(start 20.371054 -101.9302)
		(end 19.267424 -101.9302)
		(width 0.1143)
		(layer "B.Cu")
		(net "P3E_CPU1_PE3_MP_TXP<12>")
	)
	(segment
		(start 29.689298 -110.7948)
		(end 30.602936 -111.571532)
		(width 0.1143)
		(layer "B.Cu")
		(net "P3E_CPU1_PE3_MP_TXP<12>")
	)
	(segment
		(start 125.305058 -98.300286)
		(end 125.311408 -98.289618)
		(width 0.0889)
		(layer "B.Cu")
		(net "P3E_CPU1_PE3_MP_TXP<12>")
	)
	(segment
		(start 30.602936 -111.571532)
		(end 30.602682 -111.571532)
		(width 0.1143)
		(layer "B.Cu")
		(net "P3E_CPU1_PE3_MP_TXP<12>")
	)
	(segment
		(start 121.877582 -105.125774)
		(end 122.020838 -105.125774)
		(width 0.0889)
		(layer "B.Cu")
		(net "P3E_CPU1_PE3_MP_TXP<12>")
	)
	(segment
		(start 139.366244 -86.212934)
		(end 139.39901 -86.212934)
		(width 0.0889)
		(layer "B.Cu")
		(net "P3E_CPU1_PE3_MP_TXP<12>")
	)
	(segment
		(start 121.626376 -105.520236)
		(end 121.752106 -105.394506)
		(width 0.0889)
		(layer "B.Cu")
		(net "P3E_CPU1_PE3_MP_TXP<12>")
	)
	(segment
		(start 122.4153 -104.731312)
		(end 122.54103 -104.605582)
		(width 0.0889)
		(layer "B.Cu")
		(net "P3E_CPU1_PE3_MP_TXP<12>")
	)
	(segment
		(start 125.305058 -90.375486)
		(end 125.311408 -90.364818)
		(width 0.0889)
		(layer "B.Cu")
		(net "P3E_CPU1_PE3_MP_TXP<12>")
	)
	(segment
		(start 19.267424 -101.9302)
		(end 19.021044 -101.68382)
		(width 0.1143)
		(layer "B.Cu")
		(net "P3E_CPU1_PE3_MP_TXP<12>")
	)
	(segment
		(start 133.363208 -84.727288)
		(end 133.395974 -84.727288)
		(width 0.0889)
		(layer "B.Cu")
		(net "P3E_CPU1_PE3_MP_TXP<12>")
	)
	(segment
		(start 125.305058 -97.309686)
		(end 125.311408 -97.299018)
		(width 0.0889)
		(layer "B.Cu")
		(net "P3E_CPU1_PE3_MP_TXP<12>")
	)
	(segment
		(start 125.311408 -100.692204)
		(end 125.305058 -100.681536)
		(width 0.0889)
		(layer "B.Cu")
		(net "P3E_CPU1_PE3_MP_TXP<12>")
	)
	(segment
		(start 122.146568 -105.000044)
		(end 122.146568 -104.857042)
		(width 0.0889)
		(layer "B.Cu")
		(net "P3E_CPU1_PE3_MP_TXP<12>")
	)
	(segment
		(start 53.281834 -110.719616)
		(end 83.880452 -104.604058)
		(width 0.1143)
		(layer "B.Cu")
		(net "P3E_CPU1_PE3_MP_TXP<12>")
	)
	(segment
		(start 140.649198 -90.135202)
		(end 140.649198 -92.052394)
		(width 0.0889)
		(layer "B.Cu")
		(net "P3E_CPU1_PE3_MP_TXP<12>")
	)
	(segment
		(start 138.511534 -85.717888)
		(end 138.5443 -85.717888)
		(width 0.0889)
		(layer "B.Cu")
		(net "P3E_CPU1_PE3_MP_TXP<12>")
	)
	(segment
		(start 122.020838 -105.125774)
		(end 122.146568 -105.000044)
		(width 0.0889)
		(layer "B.Cu")
		(net "P3E_CPU1_PE3_MP_TXP<12>")
	)
	(segment
		(start 140.585952 -92.839286)
		(end 140.586714 -92.841318)
		(width 0.0889)
		(layer "B.Cu")
		(net "P3E_CPU1_PE3_MP_TXP<12>")
	)
	(segment
		(start 122.914664 -104.088946)
		(end 123.04014 -103.963216)
		(width 0.0889)
		(layer "B.Cu")
		(net "P3E_CPU1_PE3_MP_TXP<12>")
	)
	(segment
		(start 113.09096 -107.846114)
		(end 120.26646 -106.418888)
		(width 0.1143)
		(layer "B.Cu")
		(net "P3E_CPU1_PE3_MP_TXP<12>")
	)
	(segment
		(start 137.649204 -85.222334)
		(end 137.68197 -85.222334)
		(width 0.0889)
		(layer "B.Cu")
		(net "P3E_CPU1_PE3_MP_TXP<12>")
	)
	(segment
		(start 123.413774 -103.589582)
		(end 123.535948 -103.589582)
		(width 0.0889)
		(layer "B.Cu")
		(net "P3E_CPU1_PE3_MP_TXP<12>")
	)
	(segment
		(start 121.752106 -105.394506)
		(end 121.752106 -105.251504)
		(width 0.0889)
		(layer "B.Cu")
		(net "P3E_CPU1_PE3_MP_TXP<12>")
	)
	(segment
		(start 125.305058 -99.290886)
		(end 125.311408 -99.280218)
		(width 0.0889)
		(layer "B.Cu")
		(net "P3E_CPU1_PE3_MP_TXP<12>")
	)
	(segment
		(start 125.640592 -89.184734)
		(end 125.673358 -89.184734)
		(width 0.0889)
		(layer "B.Cu")
		(net "P3E_CPU1_PE3_MP_TXP<12>")
	)
	(segment
		(start 24.321008 -107.517692)
		(end 24.321008 -106.77525)
		(width 0.1143)
		(layer "B.Cu")
		(net "P3E_CPU1_PE3_MP_TXP<12>")
	)
	(segment
		(start 140.593064 -88.299036)
		(end 140.586714 -88.309704)
		(width 0.0889)
		(layer "B.Cu")
		(net "P3E_CPU1_PE3_MP_TXP<12>")
	)
	(segment
		(start 122.914664 -104.210866)
		(end 122.914664 -104.088946)
		(width 0.0889)
		(layer "B.Cu")
		(net "P3E_CPU1_PE3_MP_TXP<12>")
	)
	(segment
		(start 121.357644 -105.645966)
		(end 121.48312 -105.520236)
		(width 0.0889)
		(layer "B.Cu")
		(net "P3E_CPU1_PE3_MP_TXP<12>")
	)
	(segment
		(start 128.212342 -87.699088)
		(end 128.245108 -87.699088)
		(width 0.0889)
		(layer "B.Cu")
		(net "P3E_CPU1_PE3_MP_TXP<12>")
	)
	(segment
		(start 109.125258 -107.053126)
		(end 113.09096 -107.846114)
		(width 0.1143)
		(layer "B.Cu")
		(net "P3E_CPU1_PE3_MP_TXP<12>")
	)
	(segment
		(start 125.305058 -92.356686)
		(end 125.311408 -92.346018)
		(width 0.0889)
		(layer "B.Cu")
		(net "P3E_CPU1_PE3_MP_TXP<12>")
	)
	(segment
		(start 122.54103 -104.46258)
		(end 122.666506 -104.33685)
		(width 0.0889)
		(layer "B.Cu")
		(net "P3E_CPU1_PE3_MP_TXP<12>")
	)
	(segment
		(start 135.932164 -84.231734)
		(end 135.96493 -84.231734)
		(width 0.0889)
		(layer "B.Cu")
		(net "P3E_CPU1_PE3_MP_TXP<12>")
	)
	(segment
		(start 123.805442 -103.197914)
		(end 124.447554 -103.197914)
		(width 0.0889)
		(layer "B.Cu")
		(net "P3E_CPU1_PE3_MP_TXP<12>")
	)
	(segment
		(start 132.519674 -85.222334)
		(end 132.541264 -85.222334)
		(width 0.0889)
		(layer "B.Cu")
		(net "P3E_CPU1_PE3_MP_TXP<12>")
	)
	(segment
		(start 140.228574 -86.708488)
		(end 140.26134 -86.708488)
		(width 0.0889)
		(layer "B.Cu")
		(net "P3E_CPU1_PE3_MP_TXP<12>")
	)
	(segment
		(start 121.48312 -105.520236)
		(end 121.626376 -105.520236)
		(width 0.0889)
		(layer "B.Cu")
		(net "P3E_CPU1_PE3_MP_TXP<12>")
	)
	(segment
		(start 97.78492 -108.067856)
		(end 102.610158 -107.10291)
		(width 0.1143)
		(layer "B.Cu")
		(net "P3E_CPU1_PE3_MP_TXP<12>")
	)
	(segment
		(start 16.023844 -101.68382)
		(end 15.5067 -101.166676)
		(width 0.1143)
		(layer "B.Cu")
		(net "P3E_CPU1_PE3_MP_TXP<12>")
	)
	(segment
		(start 125.300232 -98.308922)
		(end 125.305058 -98.300286)
		(width 0.0889)
		(layer "B.Cu")
		(net "P3E_CPU1_PE3_MP_TXP<12>")
	)
	(segment
		(start 30.602682 -111.571532)
		(end 30.631638 -111.59617)
		(width 0.1143)
		(layer "B.Cu")
		(net "P3E_CPU1_PE3_MP_TXP<12>")
	)
	(segment
		(start 129.929382 -86.708488)
		(end 129.962148 -86.708488)
		(width 0.0889)
		(layer "B.Cu")
		(net "P3E_CPU1_PE3_MP_TXP<12>")
	)
	(segment
		(start 36.366196 -112.385856)
		(end 53.281834 -110.719616)
		(width 0.1143)
		(layer "B.Cu")
		(net "P3E_CPU1_PE3_MP_TXP<12>")
	)
	(segment
		(start 138.587226 -94.438724)
		(end 138.529314 -94.380812)
		(width 0.0889)
		(layer "B.Cu")
		(net "P3E_CPU1_PE3_MP_TXP<12>")
	)
	(segment
		(start 125.382274 -102.263194)
		(end 125.382274 -101.806248)
		(width 0.0889)
		(layer "B.Cu")
		(net "P3E_CPU1_PE3_MP_TXP<12>")
	)
	(segment
		(start 30.682946 -111.617506)
		(end 30.686248 -111.618776)
		(width 0.1143)
		(layer "B.Cu")
		(net "P3E_CPU1_PE3_MP_TXP<12>")
	)
	(segment
		(start 136.794494 -84.727288)
		(end 136.82726 -84.727288)
		(width 0.0889)
		(layer "B.Cu")
		(net "P3E_CPU1_PE3_MP_TXP<12>")
	)
	(segment
		(start 123.04014 -103.963216)
		(end 123.162314 -103.963216)
		(width 0.0889)
		(layer "B.Cu")
		(net "P3E_CPU1_PE3_MP_TXP<12>")
	)
	(segment
		(start 120.28805 -106.41457)
		(end 120.308116 -106.384598)
		(width 0.0889)
		(layer "B.Cu")
		(net "P3E_CPU1_PE3_MP_TXP<12>")
	)
	(segment
		(start 140.59789 -88.2904)
		(end 140.593064 -88.299036)
		(width 0.0889)
		(layer "B.Cu")
		(net "P3E_CPU1_PE3_MP_TXP<12>")
	)
	(segment
		(start 125.311408 -94.748604)
		(end 125.305058 -94.737936)
		(width 0.0889)
		(layer "B.Cu")
		(net "P3E_CPU1_PE3_MP_TXP<12>")
	)
	(segment
		(start 121.357644 -105.767886)
		(end 121.357644 -105.645966)
		(width 0.0889)
		(layer "B.Cu")
		(net "P3E_CPU1_PE3_MP_TXP<12>")
	)
	(segment
		(start 140.602716 -89.897458)
		(end 140.602716 -89.897204)
		(width 0.0889)
		(layer "B.Cu")
		(net "P3E_CPU1_PE3_MP_TXP<12>")
	)
	(segment
		(start 26.364946 -109.560868)
		(end 24.321008 -107.517692)
		(width 0.1143)
		(layer "B.Cu")
		(net "P3E_CPU1_PE3_MP_TXP<12>")
	)
	(segment
		(start 19.021044 -101.68382)
		(end 16.023844 -101.68382)
		(width 0.1143)
		(layer "B.Cu")
		(net "P3E_CPU1_PE3_MP_TXP<12>")
	)
	(segment
		(start 123.288298 -103.837232)
		(end 123.288298 -103.715058)
		(width 0.0889)
		(layer "B.Cu")
		(net "P3E_CPU1_PE3_MP_TXP<12>")
	)
	(segment
		(start 140.64996 -90.126312)
		(end 140.649198 -90.135202)
		(width 0.0889)
		(layer "B.Cu")
		(net "P3E_CPU1_PE3_MP_TXP<12>")
	)
	(segment
		(start 122.146568 -104.857042)
		(end 122.272044 -104.731312)
		(width 0.0889)
		(layer "B.Cu")
		(net "P3E_CPU1_PE3_MP_TXP<12>")
	)
	(segment
		(start 132.173218 -85.422486)
		(end 132.17652 -85.416644)
		(width 0.0889)
		(layer "B.Cu")
		(net "P3E_CPU1_PE3_MP_TXP<12>")
	)
	(segment
		(start 131.646422 -85.717888)
		(end 131.679188 -85.717888)
		(width 0.0889)
		(layer "B.Cu")
		(net "P3E_CPU1_PE3_MP_TXP<12>")
	)
	(segment
		(start 125.300232 -97.318322)
		(end 125.305058 -97.309686)
		(width 0.0889)
		(layer "B.Cu")
		(net "P3E_CPU1_PE3_MP_TXP<12>")
	)
	(segment
		(start 138.529314 -94.380812)
		(end 138.529314 -94.042738)
		(width 0.0889)
		(layer "B.Cu")
		(net "P3E_CPU1_PE3_MP_TXP<12>")
	)
	(segment
		(start 24.321008 -106.77525)
		(end 22.735286 -105.189782)
		(width 0.1143)
		(layer "B.Cu")
		(net "P3E_CPU1_PE3_MP_TXP<12>")
	)
	(segment
		(start 15.082266 -100.183442)
		(end 14.281658 -100.183442)
		(width 0.1143)
		(layer "B.Cu")
		(net "P3E_CPU1_PE3_MP_TXP<12>")
	)
	(segment
		(start 123.535948 -103.589582)
		(end 123.661932 -103.463598)
		(width 0.0889)
		(layer "B.Cu")
		(net "P3E_CPU1_PE3_MP_TXP<12>")
	)
	(segment
		(start 30.631638 -111.59617)
		(end 30.680152 -111.61649)
		(width 0.1143)
		(layer "B.Cu")
		(net "P3E_CPU1_PE3_MP_TXP<12>")
	)
	(segment
		(start 27.051762 -110.24743)
		(end 29.689298 -110.7948)
		(width 0.1143)
		(layer "B.Cu")
		(net "P3E_CPU1_PE3_MP_TXP<12>")
	)
	(segment
		(start 125.305058 -91.366086)
		(end 125.311408 -91.355418)
		(width 0.0889)
		(layer "B.Cu")
		(net "P3E_CPU1_PE3_MP_TXP<12>")
	)
	(segment
		(start 122.78868 -104.33685)
		(end 122.914664 -104.210866)
		(width 0.0889)
		(layer "B.Cu")
		(net "P3E_CPU1_PE3_MP_TXP<12>")
	)
	(segment
		(start 14.281658 -100.183442)
		(end 14.00302 -100.46208)
		(width 0.1143)
		(layer "B.Cu")
		(net "P3E_CPU1_PE3_MP_TXP<12>")
	)
	(segment
		(start 126.495302 -88.689688)
		(end 126.528068 -88.689688)
		(width 0.0889)
		(layer "B.Cu")
		(net "P3E_CPU1_PE3_MP_TXP<12>")
	)
	(segment
		(start 15.5067 -101.166676)
		(end 15.5067 -100.607876)
		(width 0.1143)
		(layer "B.Cu")
		(net "P3E_CPU1_PE3_MP_TXP<12>")
	)
	(segment
		(start 123.661932 -103.463598)
		(end 123.661932 -103.341424)
		(width 0.0889)
		(layer "B.Cu")
		(net "P3E_CPU1_PE3_MP_TXP<12>")
	)
	(segment
		(start 125.300232 -96.327722)
		(end 125.305058 -96.319086)
		(width 0.0889)
		(layer "B.Cu")
		(net "P3E_CPU1_PE3_MP_TXP<12>")
	)
	(segment
		(start 140.25753 -93.452188)
		(end 140.224764 -93.452188)
		(width 0.0889)
		(layer "B.Cu")
		(net "P3E_CPU1_PE3_MP_TXP<12>")
	)
	(segment
		(start 140.59789 -87.2998)
		(end 140.593064 -87.308436)
		(width 0.0889)
		(layer "B.Cu")
		(net "P3E_CPU1_PE3_MP_TXP<12>")
	)
	(segment
		(start 125.305058 -93.347286)
		(end 125.311408 -93.336618)
		(width 0.0889)
		(layer "B.Cu")
		(net "P3E_CPU1_PE3_MP_TXP<12>")
	)
	(segment
		(start 125.300232 -93.355922)
		(end 125.305058 -93.347286)
		(width 0.0889)
		(layer "B.Cu")
		(net "P3E_CPU1_PE3_MP_TXP<12>")
	)
	(segment
		(start 125.305058 -96.319086)
		(end 125.311408 -96.308418)
		(width 0.0889)
		(layer "B.Cu")
		(net "P3E_CPU1_PE3_MP_TXP<12>")
	)
	(segment
		(start 125.300232 -95.337122)
		(end 125.305058 -95.328486)
		(width 0.0889)
		(layer "B.Cu")
		(net "P3E_CPU1_PE3_MP_TXP<12>")
	)
	(segment
		(start 30.686248 -111.618776)
		(end 32.537908 -112.385856)
		(width 0.1143)
		(layer "B.Cu")
		(net "P3E_CPU1_PE3_MP_TXP<12>")
	)
	(segment
		(start 123.288298 -103.715058)
		(end 123.413774 -103.589582)
		(width 0.0889)
		(layer "B.Cu")
		(net "P3E_CPU1_PE3_MP_TXP<12>")
	)
	(segment
		(start 120.26646 -106.418888)
		(end 120.28805 -106.41457)
		(width 0.0889)
		(layer "B.Cu")
		(net "P3E_CPU1_PE3_MP_TXP<12>")
	)
	(segment
		(start 121.23166 -105.89387)
		(end 121.357644 -105.767886)
		(width 0.0889)
		(layer "B.Cu")
		(net "P3E_CPU1_PE3_MP_TXP<12>")
	)
	(segment
		(start 125.300232 -91.374722)
		(end 125.305058 -91.366086)
		(width 0.0889)
		(layer "B.Cu")
		(net "P3E_CPU1_PE3_MP_TXP<12>")
	)
	(segment
		(start 22.735286 -105.189782)
		(end 22.102064 -103.661718)
		(width 0.1143)
		(layer "B.Cu")
		(net "P3E_CPU1_PE3_MP_TXP<12>")
	)
	(segment
		(start 125.300232 -99.299522)
		(end 125.305058 -99.290886)
		(width 0.0889)
		(layer "B.Cu")
		(net "P3E_CPU1_PE3_MP_TXP<12>")
	)
	(segment
		(start 122.54103 -104.605582)
		(end 122.54103 -104.46258)
		(width 0.0889)
		(layer "B.Cu")
		(net "P3E_CPU1_PE3_MP_TXP<12>")
	)
	(segment
		(start 87.644732 -105.358692)
		(end 89.104724 -106.332274)
		(width 0.1143)
		(layer "B.Cu")
		(net "P3E_CPU1_PE3_MP_TXP<12>")
	)
	(segment
		(start 127.357632 -88.194134)
		(end 127.390398 -88.194134)
		(width 0.0889)
		(layer "B.Cu")
		(net "P3E_CPU1_PE3_MP_TXP<12>")
	)
	(segment
		(start 135.080248 -83.736688)
		(end 135.11022 -83.736688)
		(width 0.0889)
		(layer "B.Cu")
		(net "P3E_CPU1_PE3_MP_TXP<12>")
	)
	(segment
		(start 30.680914 -111.616744)
		(end 30.682946 -111.617506)
		(width 0.1143)
		(layer "B.Cu")
		(net "P3E_CPU1_PE3_MP_TXP<12>")
	)
	(segment
		(start 120.308116 -106.384598)
		(end 120.30837 -106.384344)
		(width 0.0889)
		(layer "B.Cu")
		(net "P3E_CPU1_PE3_MP_TXP<12>")
	)
	(segment
		(start 30.680152 -111.61649)
		(end 30.680914 -111.616744)
		(width 0.1143)
		(layer "B.Cu")
		(net "P3E_CPU1_PE3_MP_TXP<12>")
	)
	(segment
		(start 83.880452 -104.604058)
		(end 87.644732 -105.358692)
		(width 0.1143)
		(layer "B.Cu")
		(net "P3E_CPU1_PE3_MP_TXP<12>")
	)
	(segment
		(start 32.537908 -112.385856)
		(end 36.366196 -112.385856)
		(width 0.1143)
		(layer "B.Cu")
		(net "P3E_CPU1_PE3_MP_TXP<12>")
	)
	(segment
		(start 121.109486 -105.894124)
		(end 121.23166 -105.89387)
		(width 0.0889)
		(layer "B.Cu")
		(net "P3E_CPU1_PE3_MP_TXP<12>")
	)
	(segment
		(start 130.791712 -86.212934)
		(end 130.824478 -86.212934)
		(width 0.0889)
		(layer "B.Cu")
		(net "P3E_CPU1_PE3_MP_TXP<12>")
	)
	(segment
		(start 140.59789 -89.281)
		(end 140.593064 -89.289636)
		(width 0.0889)
		(layer "B.Cu")
		(net "P3E_CPU1_PE3_MP_TXP<12>")
	)
	(segment
		(start 129.074672 -87.203534)
		(end 129.107438 -87.203534)
		(width 0.0889)
		(layer "B.Cu")
		(net "P3E_CPU1_PE3_MP_TXP<12>")
	)
	(segment
		(start 89.104724 -106.332274)
		(end 97.78492 -108.067856)
		(width 0.1143)
		(layer "B.Cu")
		(net "P3E_CPU1_PE3_MP_TXP<12>")
	)
	(segment
		(start 102.610158 -107.10291)
		(end 105.743756 -107.729782)
		(width 0.1143)
		(layer "B.Cu")
		(net "P3E_CPU1_PE3_MP_TXP<12>")
	)
	(segment
		(start 123.162314 -103.963216)
		(end 123.288298 -103.837232)
		(width 0.0889)
		(layer "B.Cu")
		(net "P3E_CPU1_PE3_MP_TXP<12>")
	)
	(segment
		(start 140.593064 -87.308436)
		(end 140.586714 -87.319104)
		(width 0.0889)
		(layer "B.Cu")
		(net "P3E_CPU1_PE3_MP_TXP<12>")
	)
	(segment
		(start 26.364946 -109.560868)
		(end 27.051762 -110.24743)
		(width 0.1143)
		(layer "B.Cu")
		(net "P3E_CPU1_PE3_MP_TXP<12>")
	)
	(segment
		(start 15.5067 -100.607876)
		(end 15.082266 -100.183442)
		(width 0.1143)
		(layer "B.Cu")
		(net "P3E_CPU1_PE3_MP_TXP<12>")
	)
	(segment
		(start 125.300232 -92.365322)
		(end 125.305058 -92.356686)
		(width 0.0889)
		(layer "B.Cu")
		(net "P3E_CPU1_PE3_MP_TXP<12>")
	)
	(segment
		(start 122.272044 -104.731312)
		(end 122.4153 -104.731312)
		(width 0.0889)
		(layer "B.Cu")
		(net "P3E_CPU1_PE3_MP_TXP<12>")
	)
	(segment
		(start 123.661932 -103.341424)
		(end 123.805442 -103.197914)
		(width 0.0889)
		(layer "B.Cu")
		(net "P3E_CPU1_PE3_MP_TXP<12>")
	)
	(arc
		(start 140.593064 -89.289636)
		(mid 140.513933 -89.585038)
		(end 140.593064 -89.88044)
		(width 0.0889)
		(layer "B.Cu")
		(net "P3E_CPU1_PE3_MP_TXP<12>")
	)
	(arc
		(start 140.593064 -88.889586)
		(mid 140.646534 -89.084649)
		(end 140.59789 -89.281)
		(width 0.0889)
		(layer "B.Cu")
		(net "P3E_CPU1_PE3_MP_TXP<12>")
	)
	(arc
		(start 129.962148 -86.708488)
		(mid 130.247572 -86.625021)
		(end 130.456178 -86.413086)
		(width 0.0889)
		(layer "B.Cu")
		(net "P3E_CPU1_PE3_MP_TXP<12>")
	)
	(arc
		(start 137.68197 -85.222334)
		(mid 137.87582 -85.278684)
		(end 138.017504 -85.422486)
		(width 0.0889)
		(layer "B.Cu")
		(net "P3E_CPU1_PE3_MP_TXP<12>")
	)
	(arc
		(start 135.96493 -84.231734)
		(mid 136.15878 -84.288084)
		(end 136.300464 -84.431886)
		(width 0.0889)
		(layer "B.Cu")
		(net "P3E_CPU1_PE3_MP_TXP<12>")
	)
	(arc
		(start 125.305058 -89.784936)
		(mid 125.30231 -89.389469)
		(end 125.640592 -89.184734)
		(width 0.0889)
		(layer "B.Cu")
		(net "P3E_CPU1_PE3_MP_TXP<12>")
	)
	(arc
		(start 125.305058 -95.328486)
		(mid 125.38428 -95.039368)
		(end 125.311408 -94.748604)
		(width 0.0889)
		(layer "B.Cu")
		(net "P3E_CPU1_PE3_MP_TXP<12>")
	)
	(arc
		(start 125.673358 -89.184734)
		(mid 125.956575 -89.100453)
		(end 126.163578 -88.889586)
		(width 0.0889)
		(layer "B.Cu")
		(net "P3E_CPU1_PE3_MP_TXP<12>")
	)
	(arc
		(start 140.586714 -92.841318)
		(mid 140.589925 -92.846631)
		(end 140.593064 -92.851986)
		(width 0.0889)
		(layer "B.Cu")
		(net "P3E_CPU1_PE3_MP_TXP<12>")
	)
	(arc
		(start 132.17652 -85.416644)
		(mid 132.322486 -85.274245)
		(end 132.519674 -85.222334)
		(width 0.0889)
		(layer "B.Cu")
		(net "P3E_CPU1_PE3_MP_TXP<12>")
	)
	(arc
		(start 138.876024 -94.242636)
		(mid 138.816373 -94.321672)
		(end 138.739118 -94.383606)
		(width 0.0889)
		(layer "B.Cu")
		(net "P3E_CPU1_PE3_MP_TXP<12>")
	)
	(arc
		(start 133.890004 -84.431886)
		(mid 134.031687 -84.288082)
		(end 134.225538 -84.231734)
		(width 0.0889)
		(layer "B.Cu")
		(net "P3E_CPU1_PE3_MP_TXP<12>")
	)
	(arc
		(start 139.734544 -86.413086)
		(mid 139.943152 -86.625018)
		(end 140.228574 -86.708488)
		(width 0.0889)
		(layer "B.Cu")
		(net "P3E_CPU1_PE3_MP_TXP<12>")
	)
	(arc
		(start 126.163578 -88.889586)
		(mid 126.303657 -88.74685)
		(end 126.495302 -88.689688)
		(width 0.0889)
		(layer "B.Cu")
		(net "P3E_CPU1_PE3_MP_TXP<12>")
	)
	(arc
		(start 139.39901 -86.212934)
		(mid 139.59286 -86.269284)
		(end 139.734544 -86.413086)
		(width 0.0889)
		(layer "B.Cu")
		(net "P3E_CPU1_PE3_MP_TXP<12>")
	)
	(arc
		(start 140.593064 -92.261436)
		(mid 140.514103 -92.549418)
		(end 140.585952 -92.839286)
		(width 0.0889)
		(layer "B.Cu")
		(net "P3E_CPU1_PE3_MP_TXP<12>")
	)
	(arc
		(start 125.305058 -91.766136)
		(mid 125.251588 -91.571073)
		(end 125.300232 -91.374722)
		(width 0.0889)
		(layer "B.Cu")
		(net "P3E_CPU1_PE3_MP_TXP<12>")
	)
	(arc
		(start 140.602716 -89.897204)
		(mid 140.640065 -89.993724)
		(end 140.651484 -90.096594)
		(width 0.0889)
		(layer "B.Cu")
		(net "P3E_CPU1_PE3_MP_TXP<12>")
	)
	(arc
		(start 125.305058 -92.756736)
		(mid 125.251588 -92.561673)
		(end 125.300232 -92.365322)
		(width 0.0889)
		(layer "B.Cu")
		(net "P3E_CPU1_PE3_MP_TXP<12>")
	)
	(arc
		(start 128.245108 -87.699088)
		(mid 128.530532 -87.615621)
		(end 128.739138 -87.403686)
		(width 0.0889)
		(layer "B.Cu")
		(net "P3E_CPU1_PE3_MP_TXP<12>")
	)
	(arc
		(start 125.305058 -95.728536)
		(mid 125.251588 -95.533473)
		(end 125.300232 -95.337122)
		(width 0.0889)
		(layer "B.Cu")
		(net "P3E_CPU1_PE3_MP_TXP<12>")
	)
	(arc
		(start 125.311408 -97.299018)
		(mid 125.384206 -97.008255)
		(end 125.305058 -96.719136)
		(width 0.0889)
		(layer "B.Cu")
		(net "P3E_CPU1_PE3_MP_TXP<12>")
	)
	(arc
		(start 130.824478 -86.212934)
		(mid 131.107695 -86.128653)
		(end 131.314698 -85.917786)
		(width 0.0889)
		(layer "B.Cu")
		(net "P3E_CPU1_PE3_MP_TXP<12>")
	)
	(arc
		(start 133.395974 -84.727288)
		(mid 133.681398 -84.643821)
		(end 133.890004 -84.431886)
		(width 0.0889)
		(layer "B.Cu")
		(net "P3E_CPU1_PE3_MP_TXP<12>")
	)
	(arc
		(start 137.158984 -84.927186)
		(mid 137.365988 -85.13805)
		(end 137.649204 -85.222334)
		(width 0.0889)
		(layer "B.Cu")
		(net "P3E_CPU1_PE3_MP_TXP<12>")
	)
	(arc
		(start 129.107438 -87.203534)
		(mid 129.390655 -87.119253)
		(end 129.597658 -86.908386)
		(width 0.0889)
		(layer "B.Cu")
		(net "P3E_CPU1_PE3_MP_TXP<12>")
	)
	(arc
		(start 125.311408 -91.355418)
		(mid 125.384206 -91.064655)
		(end 125.305058 -90.775536)
		(width 0.0889)
		(layer "B.Cu")
		(net "P3E_CPU1_PE3_MP_TXP<12>")
	)
	(arc
		(start 125.311408 -92.346018)
		(mid 125.384206 -92.055255)
		(end 125.305058 -91.766136)
		(width 0.0889)
		(layer "B.Cu")
		(net "P3E_CPU1_PE3_MP_TXP<12>")
	)
	(arc
		(start 125.305058 -100.28174)
		(mid 125.384189 -99.986338)
		(end 125.305058 -99.690936)
		(width 0.0889)
		(layer "B.Cu")
		(net "P3E_CPU1_PE3_MP_TXP<12>")
	)
	(arc
		(start 136.82726 -84.727288)
		(mid 137.018902 -84.784454)
		(end 137.158984 -84.927186)
		(width 0.0889)
		(layer "B.Cu")
		(net "P3E_CPU1_PE3_MP_TXP<12>")
	)
	(arc
		(start 125.311408 -96.308418)
		(mid 125.384206 -96.017655)
		(end 125.305058 -95.728536)
		(width 0.0889)
		(layer "B.Cu")
		(net "P3E_CPU1_PE3_MP_TXP<12>")
	)
	(arc
		(start 125.305058 -98.700336)
		(mid 125.251588 -98.505273)
		(end 125.300232 -98.308922)
		(width 0.0889)
		(layer "B.Cu")
		(net "P3E_CPU1_PE3_MP_TXP<12>")
	)
	(arc
		(start 125.305058 -101.272086)
		(mid 125.38428 -100.982968)
		(end 125.311408 -100.692204)
		(width 0.0889)
		(layer "B.Cu")
		(net "P3E_CPU1_PE3_MP_TXP<12>")
	)
	(arc
		(start 140.586714 -88.309704)
		(mid 140.513916 -88.600467)
		(end 140.593064 -88.889586)
		(width 0.0889)
		(layer "B.Cu")
		(net "P3E_CPU1_PE3_MP_TXP<12>")
	)
	(arc
		(start 138.017504 -85.422486)
		(mid 138.226112 -85.634418)
		(end 138.511534 -85.717888)
		(width 0.0889)
		(layer "B.Cu")
		(net "P3E_CPU1_PE3_MP_TXP<12>")
	)
	(arc
		(start 132.541264 -85.222334)
		(mid 132.824481 -85.138053)
		(end 133.031484 -84.927186)
		(width 0.0889)
		(layer "B.Cu")
		(net "P3E_CPU1_PE3_MP_TXP<12>")
	)
	(arc
		(start 125.305058 -96.719136)
		(mid 125.251588 -96.524073)
		(end 125.300232 -96.327722)
		(width 0.0889)
		(layer "B.Cu")
		(net "P3E_CPU1_PE3_MP_TXP<12>")
	)
	(arc
		(start 140.593064 -92.851986)
		(mid 140.595812 -93.247453)
		(end 140.25753 -93.452188)
		(width 0.0889)
		(layer "B.Cu")
		(net "P3E_CPU1_PE3_MP_TXP<12>")
	)
	(arc
		(start 140.593064 -87.898986)
		(mid 140.646534 -88.094049)
		(end 140.59789 -88.2904)
		(width 0.0889)
		(layer "B.Cu")
		(net "P3E_CPU1_PE3_MP_TXP<12>")
	)
	(arc
		(start 136.300464 -84.431886)
		(mid 136.509072 -84.643818)
		(end 136.794494 -84.727288)
		(width 0.0889)
		(layer "B.Cu")
		(net "P3E_CPU1_PE3_MP_TXP<12>")
	)
	(arc
		(start 125.311408 -93.336618)
		(mid 125.384206 -93.045855)
		(end 125.305058 -92.756736)
		(width 0.0889)
		(layer "B.Cu")
		(net "P3E_CPU1_PE3_MP_TXP<12>")
	)
	(arc
		(start 140.593064 -89.88044)
		(mid 140.597923 -89.88893)
		(end 140.602716 -89.897458)
		(width 0.0889)
		(layer "B.Cu")
		(net "P3E_CPU1_PE3_MP_TXP<12>")
	)
	(arc
		(start 125.305058 -90.775536)
		(mid 125.251588 -90.580473)
		(end 125.300232 -90.384122)
		(width 0.0889)
		(layer "B.Cu")
		(net "P3E_CPU1_PE3_MP_TXP<12>")
	)
	(arc
		(start 134.748524 -83.936586)
		(mid 134.888603 -83.79385)
		(end 135.080248 -83.736688)
		(width 0.0889)
		(layer "B.Cu")
		(net "P3E_CPU1_PE3_MP_TXP<12>")
	)
	(arc
		(start 133.031484 -84.927186)
		(mid 133.171563 -84.78445)
		(end 133.363208 -84.727288)
		(width 0.0889)
		(layer "B.Cu")
		(net "P3E_CPU1_PE3_MP_TXP<12>")
	)
	(arc
		(start 135.11022 -83.736688)
		(mid 135.301862 -83.793854)
		(end 135.441944 -83.936586)
		(width 0.0889)
		(layer "B.Cu")
		(net "P3E_CPU1_PE3_MP_TXP<12>")
	)
	(arc
		(start 131.314698 -85.917786)
		(mid 131.454777 -85.77505)
		(end 131.646422 -85.717888)
		(width 0.0889)
		(layer "B.Cu")
		(net "P3E_CPU1_PE3_MP_TXP<12>")
	)
	(arc
		(start 125.305058 -99.690936)
		(mid 125.251588 -99.495873)
		(end 125.300232 -99.299522)
		(width 0.0889)
		(layer "B.Cu")
		(net "P3E_CPU1_PE3_MP_TXP<12>")
	)
	(arc
		(start 130.456178 -86.413086)
		(mid 130.597861 -86.269282)
		(end 130.791712 -86.212934)
		(width 0.0889)
		(layer "B.Cu")
		(net "P3E_CPU1_PE3_MP_TXP<12>")
	)
	(arc
		(start 128.739138 -87.403686)
		(mid 128.880821 -87.259882)
		(end 129.074672 -87.203534)
		(width 0.0889)
		(layer "B.Cu")
		(net "P3E_CPU1_PE3_MP_TXP<12>")
	)
	(arc
		(start 135.441944 -83.936586)
		(mid 135.648948 -84.14745)
		(end 135.932164 -84.231734)
		(width 0.0889)
		(layer "B.Cu")
		(net "P3E_CPU1_PE3_MP_TXP<12>")
	)
	(arc
		(start 134.258304 -84.231734)
		(mid 134.541521 -84.147453)
		(end 134.748524 -83.936586)
		(width 0.0889)
		(layer "B.Cu")
		(net "P3E_CPU1_PE3_MP_TXP<12>")
	)
	(arc
		(start 140.224764 -93.452188)
		(mid 139.941547 -93.536469)
		(end 139.734544 -93.747336)
		(width 0.0889)
		(layer "B.Cu")
		(net "P3E_CPU1_PE3_MP_TXP<12>")
	)
	(arc
		(start 125.305058 -101.672136)
		(mid 125.251559 -101.472128)
		(end 125.305058 -101.272086)
		(width 0.0889)
		(layer "B.Cu")
		(net "P3E_CPU1_PE3_MP_TXP<12>")
	)
	(arc
		(start 125.311408 -98.289618)
		(mid 125.384206 -97.998855)
		(end 125.305058 -97.709736)
		(width 0.0889)
		(layer "B.Cu")
		(net "P3E_CPU1_PE3_MP_TXP<12>")
	)
	(arc
		(start 129.597658 -86.908386)
		(mid 129.737737 -86.76565)
		(end 129.929382 -86.708488)
		(width 0.0889)
		(layer "B.Cu")
		(net "P3E_CPU1_PE3_MP_TXP<12>")
	)
	(arc
		(start 125.311408 -99.280218)
		(mid 125.384206 -98.989455)
		(end 125.305058 -98.700336)
		(width 0.0889)
		(layer "B.Cu")
		(net "P3E_CPU1_PE3_MP_TXP<12>")
	)
	(arc
		(start 126.528068 -88.689688)
		(mid 126.813492 -88.606221)
		(end 127.022098 -88.394286)
		(width 0.0889)
		(layer "B.Cu")
		(net "P3E_CPU1_PE3_MP_TXP<12>")
	)
	(arc
		(start 127.880618 -87.898986)
		(mid 128.020697 -87.75625)
		(end 128.212342 -87.699088)
		(width 0.0889)
		(layer "B.Cu")
		(net "P3E_CPU1_PE3_MP_TXP<12>")
	)
	(arc
		(start 140.586714 -87.319104)
		(mid 140.513916 -87.609867)
		(end 140.593064 -87.898986)
		(width 0.0889)
		(layer "B.Cu")
		(net "P3E_CPU1_PE3_MP_TXP<12>")
	)
	(arc
		(start 127.022098 -88.394286)
		(mid 127.163781 -88.250482)
		(end 127.357632 -88.194134)
		(width 0.0889)
		(layer "B.Cu")
		(net "P3E_CPU1_PE3_MP_TXP<12>")
	)
	(arc
		(start 139.734544 -93.747336)
		(mid 139.594465 -93.890072)
		(end 139.40282 -93.947234)
		(width 0.0889)
		(layer "B.Cu")
		(net "P3E_CPU1_PE3_MP_TXP<12>")
	)
	(arc
		(start 127.390398 -88.194134)
		(mid 127.673615 -88.109853)
		(end 127.880618 -87.898986)
		(width 0.0889)
		(layer "B.Cu")
		(net "P3E_CPU1_PE3_MP_TXP<12>")
	)
	(arc
		(start 140.26134 -86.708488)
		(mid 140.594258 -86.910479)
		(end 140.59789 -87.2998)
		(width 0.0889)
		(layer "B.Cu")
		(net "P3E_CPU1_PE3_MP_TXP<12>")
	)
	(arc
		(start 140.649198 -92.052394)
		(mid 140.634929 -92.160623)
		(end 140.593064 -92.261436)
		(width 0.0889)
		(layer "B.Cu")
		(net "P3E_CPU1_PE3_MP_TXP<12>")
	)
	(arc
		(start 138.5443 -85.717888)
		(mid 138.735942 -85.775054)
		(end 138.876024 -85.917786)
		(width 0.0889)
		(layer "B.Cu")
		(net "P3E_CPU1_PE3_MP_TXP<12>")
	)
	(arc
		(start 125.305058 -94.737936)
		(mid 125.251559 -94.538038)
		(end 125.305058 -94.33814)
		(width 0.0889)
		(layer "B.Cu")
		(net "P3E_CPU1_PE3_MP_TXP<12>")
	)
	(arc
		(start 139.37488 -93.947234)
		(mid 139.086735 -94.029553)
		(end 138.876024 -94.242636)
		(width 0.0889)
		(layer "B.Cu")
		(net "P3E_CPU1_PE3_MP_TXP<12>")
	)
	(arc
		(start 125.311408 -90.364818)
		(mid 125.384206 -90.074055)
		(end 125.305058 -89.784936)
		(width 0.0889)
		(layer "B.Cu")
		(net "P3E_CPU1_PE3_MP_TXP<12>")
	)
	(arc
		(start 138.739118 -94.383606)
		(mid 138.665979 -94.418895)
		(end 138.587226 -94.438724)
		(width 0.0889)
		(layer "B.Cu")
		(net "P3E_CPU1_PE3_MP_TXP<12>")
	)
	(arc
		(start 125.305058 -97.709736)
		(mid 125.251588 -97.514673)
		(end 125.300232 -97.318322)
		(width 0.0889)
		(layer "B.Cu")
		(net "P3E_CPU1_PE3_MP_TXP<12>")
	)
	(arc
		(start 125.305058 -100.681536)
		(mid 125.251559 -100.481638)
		(end 125.305058 -100.28174)
		(width 0.0889)
		(layer "B.Cu")
		(net "P3E_CPU1_PE3_MP_TXP<12>")
	)
	(arc
		(start 131.679188 -85.717888)
		(mid 131.964612 -85.634421)
		(end 132.173218 -85.422486)
		(width 0.0889)
		(layer "B.Cu")
		(net "P3E_CPU1_PE3_MP_TXP<12>")
	)
	(arc
		(start 140.651484 -90.096594)
		(mid 140.651 -90.111467)
		(end 140.64996 -90.126312)
		(width 0.0889)
		(layer "B.Cu")
		(net "P3E_CPU1_PE3_MP_TXP<12>")
	)
	(arc
		(start 125.305058 -93.747336)
		(mid 125.251588 -93.552273)
		(end 125.300232 -93.355922)
		(width 0.0889)
		(layer "B.Cu")
		(net "P3E_CPU1_PE3_MP_TXP<12>")
	)
	(arc
		(start 138.876024 -85.917786)
		(mid 139.083028 -86.12865)
		(end 139.366244 -86.212934)
		(width 0.0889)
		(layer "B.Cu")
		(net "P3E_CPU1_PE3_MP_TXP<12>")
	)
	(arc
		(start 125.305058 -94.33814)
		(mid 125.384189 -94.042738)
		(end 125.305058 -93.747336)
		(width 0.0889)
		(layer "B.Cu")
		(net "P3E_CPU1_PE3_MP_TXP<12>")
	)
	(segment
		(start 138.816588 -94.537784)
		(end 139.387834 -94.537784)
		(width 0.1143)
		(layer "F.Cu")
		(net "P3E_CPU1_PE3_MP_TXP<11>")
	)
	(segment
		(start 138.816334 -94.538038)
		(end 138.816588 -94.537784)
		(width 0.1143)
		(layer "F.Cu")
		(net "P3E_CPU1_PE3_MP_TXP<11>")
	)
	(via
		(at 139.387834 -94.537784)
		(size 0.508)
		(drill 0.254)
		(layers "F.Cu" "B.Cu")
		(net "P3E_CPU1_PE3_MP_TXP<11>")
	)
	(via
		(at 20.672298 -110.245144)
		(size 0.508)
		(drill 0.254)
		(layers "F.Cu" "B.Cu")
		(net "P3E_CPU1_PE3_MP_TXP<11>")
	)
	(segment
		(start 137.330434 -90.364818)
		(end 137.324084 -90.375486)
		(width 0.0889)
		(layer "B.Cu")
		(net "P3E_CPU1_PE3_MP_TXP<11>")
	)
	(segment
		(start 83.442302 -108.472478)
		(end 85.198966 -108.82376)
		(width 0.1143)
		(layer "B.Cu")
		(net "P3E_CPU1_PE3_MP_TXP<11>")
	)
	(segment
		(start 138.188954 -94.822518)
		(end 138.182604 -94.833186)
		(width 0.0889)
		(layer "B.Cu")
		(net "P3E_CPU1_PE3_MP_TXP<11>")
	)
	(segment
		(start 128.627632 -103.863394)
		(end 128.627632 -100.976684)
		(width 0.0889)
		(layer "B.Cu")
		(net "P3E_CPU1_PE3_MP_TXP<11>")
	)
	(segment
		(start 53.246274 -114.50701)
		(end 83.442302 -108.472478)
		(width 0.1143)
		(layer "B.Cu")
		(net "P3E_CPU1_PE3_MP_TXP<11>")
	)
	(segment
		(start 17.798542 -106.90098)
		(end 18.804382 -107.317794)
		(width 0.1143)
		(layer "B.Cu")
		(net "P3E_CPU1_PE3_MP_TXP<11>")
	)
	(segment
		(start 128.574038 -96.223836)
		(end 128.578864 -96.2152)
		(width 0.0889)
		(layer "B.Cu")
		(net "P3E_CPU1_PE3_MP_TXP<11>")
	)
	(segment
		(start 128.567688 -97.225104)
		(end 128.574038 -97.214436)
		(width 0.0889)
		(layer "B.Cu")
		(net "P3E_CPU1_PE3_MP_TXP<11>")
	)
	(segment
		(start 122.197622 -110.257336)
		(end 127.780542 -104.674416)
		(width 0.1143)
		(layer "B.Cu")
		(net "P3E_CPU1_PE3_MP_TXP<11>")
	)
	(segment
		(start 102.469188 -111.260636)
		(end 105.162858 -111.799116)
		(width 0.1143)
		(layer "B.Cu")
		(net "P3E_CPU1_PE3_MP_TXP<11>")
	)
	(segment
		(start 131.639818 -89.489788)
		(end 131.661408 -89.489788)
		(width 0.0889)
		(layer "B.Cu")
		(net "P3E_CPU1_PE3_MP_TXP<11>")
	)
	(segment
		(start 138.177778 -94.234)
		(end 138.182604 -94.242636)
		(width 0.0889)
		(layer "B.Cu")
		(net "P3E_CPU1_PE3_MP_TXP<11>")
	)
	(segment
		(start 36.134802 -116.1923)
		(end 53.246274 -114.50701)
		(width 0.1143)
		(layer "B.Cu")
		(net "P3E_CPU1_PE3_MP_TXP<11>")
	)
	(segment
		(start 20.672298 -110.245144)
		(end 23.747476 -113.32083)
		(width 0.1143)
		(layer "B.Cu")
		(net "P3E_CPU1_PE3_MP_TXP<11>")
	)
	(segment
		(start 128.567688 -92.272104)
		(end 128.574038 -92.261436)
		(width 0.0889)
		(layer "B.Cu")
		(net "P3E_CPU1_PE3_MP_TXP<11>")
	)
	(segment
		(start 128.567688 -99.206304)
		(end 128.574038 -99.195636)
		(width 0.0889)
		(layer "B.Cu")
		(net "P3E_CPU1_PE3_MP_TXP<11>")
	)
	(segment
		(start 135.938768 -88.003634)
		(end 135.971534 -88.003634)
		(width 0.0889)
		(layer "B.Cu")
		(net "P3E_CPU1_PE3_MP_TXP<11>")
	)
	(segment
		(start 135.073644 -87.508588)
		(end 135.116824 -87.508588)
		(width 0.0889)
		(layer "B.Cu")
		(net "P3E_CPU1_PE3_MP_TXP<11>")
	)
	(segment
		(start 128.574038 -94.242636)
		(end 128.578864 -94.234)
		(width 0.0889)
		(layer "B.Cu")
		(net "P3E_CPU1_PE3_MP_TXP<11>")
	)
	(segment
		(start 85.198966 -108.82376)
		(end 87.505286 -110.361476)
		(width 0.1143)
		(layer "B.Cu")
		(net "P3E_CPU1_PE3_MP_TXP<11>")
	)
	(segment
		(start 132.501894 -88.994234)
		(end 132.53466 -88.994234)
		(width 0.0889)
		(layer "B.Cu")
		(net "P3E_CPU1_PE3_MP_TXP<11>")
	)
	(segment
		(start 105.162858 -111.799116)
		(end 108.98251 -111.035084)
		(width 0.1143)
		(layer "B.Cu")
		(net "P3E_CPU1_PE3_MP_TXP<11>")
	)
	(segment
		(start 137.330434 -91.355418)
		(end 137.324084 -91.366086)
		(width 0.0889)
		(layer "B.Cu")
		(net "P3E_CPU1_PE3_MP_TXP<11>")
	)
	(segment
		(start 133.356604 -88.499188)
		(end 133.38937 -88.499188)
		(width 0.0889)
		(layer "B.Cu")
		(net "P3E_CPU1_PE3_MP_TXP<11>")
	)
	(segment
		(start 134.218934 -88.003634)
		(end 134.2517 -88.003634)
		(width 0.0889)
		(layer "B.Cu")
		(net "P3E_CPU1_PE3_MP_TXP<11>")
	)
	(segment
		(start 137.324084 -89.384886)
		(end 137.319258 -89.393522)
		(width 0.0889)
		(layer "B.Cu")
		(net "P3E_CPU1_PE3_MP_TXP<11>")
	)
	(segment
		(start 128.567688 -98.215704)
		(end 128.574038 -98.205036)
		(width 0.0889)
		(layer "B.Cu")
		(net "P3E_CPU1_PE3_MP_TXP<11>")
	)
	(segment
		(start 128.574038 -100.186236)
		(end 128.578864 -100.1776)
		(width 0.0889)
		(layer "B.Cu")
		(net "P3E_CPU1_PE3_MP_TXP<11>")
	)
	(segment
		(start 138.177778 -93.2434)
		(end 138.182604 -93.252036)
		(width 0.0889)
		(layer "B.Cu")
		(net "P3E_CPU1_PE3_MP_TXP<11>")
	)
	(segment
		(start 138.182604 -93.252036)
		(end 138.188954 -93.262704)
		(width 0.0889)
		(layer "B.Cu")
		(net "P3E_CPU1_PE3_MP_TXP<11>")
	)
	(segment
		(start 108.98251 -111.035084)
		(end 113.608612 -111.965486)
		(width 0.1143)
		(layer "B.Cu")
		(net "P3E_CPU1_PE3_MP_TXP<11>")
	)
	(segment
		(start 127.780542 -104.674416)
		(end 127.81661 -104.674416)
		(width 0.0889)
		(layer "B.Cu")
		(net "P3E_CPU1_PE3_MP_TXP<11>")
	)
	(segment
		(start 18.804382 -107.317794)
		(end 19.7993 -108.312966)
		(width 0.1143)
		(layer "B.Cu")
		(net "P3E_CPU1_PE3_MP_TXP<11>")
	)
	(segment
		(start 137.655808 -91.966034)
		(end 137.688574 -91.966034)
		(width 0.0889)
		(layer "B.Cu")
		(net "P3E_CPU1_PE3_MP_TXP<11>")
	)
	(segment
		(start 97.234248 -112.307624)
		(end 102.469188 -111.260636)
		(width 0.1143)
		(layer "B.Cu")
		(net "P3E_CPU1_PE3_MP_TXP<11>")
	)
	(segment
		(start 137.324084 -91.366086)
		(end 137.319258 -91.374722)
		(width 0.0889)
		(layer "B.Cu")
		(net "P3E_CPU1_PE3_MP_TXP<11>")
	)
	(segment
		(start 19.7993 -109.372146)
		(end 20.672298 -110.245144)
		(width 0.1143)
		(layer "B.Cu")
		(net "P3E_CPU1_PE3_MP_TXP<11>")
	)
	(segment
		(start 30.67939 -116.1923)
		(end 36.134802 -116.1923)
		(width 0.1143)
		(layer "B.Cu")
		(net "P3E_CPU1_PE3_MP_TXP<11>")
	)
	(segment
		(start 129.922778 -90.480388)
		(end 129.955544 -90.480388)
		(width 0.0889)
		(layer "B.Cu")
		(net "P3E_CPU1_PE3_MP_TXP<11>")
	)
	(segment
		(start 15.03426 -106.90098)
		(end 17.798542 -106.90098)
		(width 0.1143)
		(layer "B.Cu")
		(net "P3E_CPU1_PE3_MP_TXP<11>")
	)
	(segment
		(start 137.330434 -89.374218)
		(end 137.324084 -89.384886)
		(width 0.0889)
		(layer "B.Cu")
		(net "P3E_CPU1_PE3_MP_TXP<11>")
	)
	(segment
		(start 113.608612 -111.965486)
		(end 122.197622 -110.257336)
		(width 0.1143)
		(layer "B.Cu")
		(net "P3E_CPU1_PE3_MP_TXP<11>")
	)
	(segment
		(start 137.324084 -90.375486)
		(end 137.319258 -90.384122)
		(width 0.0889)
		(layer "B.Cu")
		(net "P3E_CPU1_PE3_MP_TXP<11>")
	)
	(segment
		(start 130.785108 -89.984834)
		(end 130.817874 -89.984834)
		(width 0.0889)
		(layer "B.Cu")
		(net "P3E_CPU1_PE3_MP_TXP<11>")
	)
	(segment
		(start 129.068068 -90.975434)
		(end 129.100834 -90.975434)
		(width 0.0889)
		(layer "B.Cu")
		(net "P3E_CPU1_PE3_MP_TXP<11>")
	)
	(segment
		(start 128.574038 -98.205036)
		(end 128.578864 -98.1964)
		(width 0.0889)
		(layer "B.Cu")
		(net "P3E_CPU1_PE3_MP_TXP<11>")
	)
	(segment
		(start 128.574038 -99.195636)
		(end 128.578864 -99.187)
		(width 0.0889)
		(layer "B.Cu")
		(net "P3E_CPU1_PE3_MP_TXP<11>")
	)
	(segment
		(start 128.567688 -96.234504)
		(end 128.574038 -96.223836)
		(width 0.0889)
		(layer "B.Cu")
		(net "P3E_CPU1_PE3_MP_TXP<11>")
	)
	(segment
		(start 127.81661 -104.674416)
		(end 128.627632 -103.863394)
		(width 0.0889)
		(layer "B.Cu")
		(net "P3E_CPU1_PE3_MP_TXP<11>")
	)
	(segment
		(start 128.567688 -93.262704)
		(end 128.574038 -93.252036)
		(width 0.0889)
		(layer "B.Cu")
		(net "P3E_CPU1_PE3_MP_TXP<11>")
	)
	(segment
		(start 128.574038 -94.833186)
		(end 128.567688 -94.822518)
		(width 0.0889)
		(layer "B.Cu")
		(net "P3E_CPU1_PE3_MP_TXP<11>")
	)
	(segment
		(start 128.574038 -93.252036)
		(end 128.578864 -93.2434)
		(width 0.0889)
		(layer "B.Cu")
		(net "P3E_CPU1_PE3_MP_TXP<11>")
	)
	(segment
		(start 132.004562 -89.295478)
		(end 132.007864 -89.289636)
		(width 0.0889)
		(layer "B.Cu")
		(net "P3E_CPU1_PE3_MP_TXP<11>")
	)
	(segment
		(start 128.574038 -100.776786)
		(end 128.567688 -100.766118)
		(width 0.0889)
		(layer "B.Cu")
		(net "P3E_CPU1_PE3_MP_TXP<11>")
	)
	(segment
		(start 23.747476 -113.32083)
		(end 30.67939 -116.1923)
		(width 0.1143)
		(layer "B.Cu")
		(net "P3E_CPU1_PE3_MP_TXP<11>")
	)
	(segment
		(start 128.574038 -92.261436)
		(end 128.578864 -92.2528)
		(width 0.0889)
		(layer "B.Cu")
		(net "P3E_CPU1_PE3_MP_TXP<11>")
	)
	(segment
		(start 14.72946 -106.59618)
		(end 15.03426 -106.90098)
		(width 0.1143)
		(layer "B.Cu")
		(net "P3E_CPU1_PE3_MP_TXP<11>")
	)
	(segment
		(start 136.801098 -88.499188)
		(end 136.833864 -88.499188)
		(width 0.0889)
		(layer "B.Cu")
		(net "P3E_CPU1_PE3_MP_TXP<11>")
	)
	(segment
		(start 19.7993 -108.312966)
		(end 19.7993 -109.372146)
		(width 0.1143)
		(layer "B.Cu")
		(net "P3E_CPU1_PE3_MP_TXP<11>")
	)
	(segment
		(start 128.574038 -97.214436)
		(end 128.578864 -97.2058)
		(width 0.0889)
		(layer "B.Cu")
		(net "P3E_CPU1_PE3_MP_TXP<11>")
	)
	(segment
		(start 87.505286 -110.361476)
		(end 97.234248 -112.307624)
		(width 0.1143)
		(layer "B.Cu")
		(net "P3E_CPU1_PE3_MP_TXP<11>")
	)
	(arc
		(start 131.661408 -89.489788)
		(mid 131.858569 -89.437829)
		(end 132.004562 -89.295478)
		(width 0.0889)
		(layer "B.Cu")
		(net "P3E_CPU1_PE3_MP_TXP<11>")
	)
	(arc
		(start 128.578864 -100.1776)
		(mid 128.627619 -99.981248)
		(end 128.574038 -99.786186)
		(width 0.0889)
		(layer "B.Cu")
		(net "P3E_CPU1_PE3_MP_TXP<11>")
	)
	(arc
		(start 132.866384 -88.794336)
		(mid 133.073388 -88.583472)
		(end 133.356604 -88.499188)
		(width 0.0889)
		(layer "B.Cu")
		(net "P3E_CPU1_PE3_MP_TXP<11>")
	)
	(arc
		(start 128.578864 -98.1964)
		(mid 128.627619 -98.000048)
		(end 128.574038 -97.804986)
		(width 0.0889)
		(layer "B.Cu")
		(net "P3E_CPU1_PE3_MP_TXP<11>")
	)
	(arc
		(start 136.833864 -88.499188)
		(mid 137.326254 -88.798121)
		(end 137.330434 -89.374218)
		(width 0.0889)
		(layer "B.Cu")
		(net "P3E_CPU1_PE3_MP_TXP<11>")
	)
	(arc
		(start 134.583424 -87.803736)
		(mid 134.790428 -87.592872)
		(end 135.073644 -87.508588)
		(width 0.0889)
		(layer "B.Cu")
		(net "P3E_CPU1_PE3_MP_TXP<11>")
	)
	(arc
		(start 138.182604 -93.842586)
		(mid 138.129134 -94.037649)
		(end 138.177778 -94.234)
		(width 0.0889)
		(layer "B.Cu")
		(net "P3E_CPU1_PE3_MP_TXP<11>")
	)
	(arc
		(start 137.319258 -90.384122)
		(mid 137.270503 -90.580474)
		(end 137.324084 -90.775536)
		(width 0.0889)
		(layer "B.Cu")
		(net "P3E_CPU1_PE3_MP_TXP<11>")
	)
	(arc
		(start 133.724904 -88.299036)
		(mid 133.933512 -88.087104)
		(end 134.218934 -88.003634)
		(width 0.0889)
		(layer "B.Cu")
		(net "P3E_CPU1_PE3_MP_TXP<11>")
	)
	(arc
		(start 138.182604 -94.242636)
		(mid 138.261826 -94.531754)
		(end 138.188954 -94.822518)
		(width 0.0889)
		(layer "B.Cu")
		(net "P3E_CPU1_PE3_MP_TXP<11>")
	)
	(arc
		(start 132.007864 -89.289636)
		(mid 132.216472 -89.077704)
		(end 132.501894 -88.994234)
		(width 0.0889)
		(layer "B.Cu")
		(net "P3E_CPU1_PE3_MP_TXP<11>")
	)
	(arc
		(start 128.578864 -94.234)
		(mid 128.627619 -94.037648)
		(end 128.574038 -93.842586)
		(width 0.0889)
		(layer "B.Cu")
		(net "P3E_CPU1_PE3_MP_TXP<11>")
	)
	(arc
		(start 130.817874 -89.984834)
		(mid 131.009516 -89.927668)
		(end 131.149598 -89.784936)
		(width 0.0889)
		(layer "B.Cu")
		(net "P3E_CPU1_PE3_MP_TXP<11>")
	)
	(arc
		(start 131.149598 -89.784936)
		(mid 131.356602 -89.574072)
		(end 131.639818 -89.489788)
		(width 0.0889)
		(layer "B.Cu")
		(net "P3E_CPU1_PE3_MP_TXP<11>")
	)
	(arc
		(start 128.578864 -96.2152)
		(mid 128.627619 -96.018848)
		(end 128.574038 -95.823786)
		(width 0.0889)
		(layer "B.Cu")
		(net "P3E_CPU1_PE3_MP_TXP<11>")
	)
	(arc
		(start 128.574038 -96.814386)
		(mid 128.494816 -96.525268)
		(end 128.567688 -96.234504)
		(width 0.0889)
		(layer "B.Cu")
		(net "P3E_CPU1_PE3_MP_TXP<11>")
	)
	(arc
		(start 138.182604 -94.833186)
		(mid 138.329416 -95.379794)
		(end 138.876024 -95.232982)
		(width 0.0889)
		(layer "B.Cu")
		(net "P3E_CPU1_PE3_MP_TXP<11>")
	)
	(arc
		(start 138.182604 -92.851986)
		(mid 138.129134 -93.047049)
		(end 138.177778 -93.2434)
		(width 0.0889)
		(layer "B.Cu")
		(net "P3E_CPU1_PE3_MP_TXP<11>")
	)
	(arc
		(start 129.100834 -90.975434)
		(mid 129.292476 -90.918268)
		(end 129.432558 -90.775536)
		(width 0.0889)
		(layer "B.Cu")
		(net "P3E_CPU1_PE3_MP_TXP<11>")
	)
	(arc
		(start 137.319258 -89.393522)
		(mid 137.270503 -89.589874)
		(end 137.324084 -89.784936)
		(width 0.0889)
		(layer "B.Cu")
		(net "P3E_CPU1_PE3_MP_TXP<11>")
	)
	(arc
		(start 128.574038 -92.851986)
		(mid 128.494816 -92.562868)
		(end 128.567688 -92.272104)
		(width 0.0889)
		(layer "B.Cu")
		(net "P3E_CPU1_PE3_MP_TXP<11>")
	)
	(arc
		(start 136.465564 -88.299036)
		(mid 136.607247 -88.44284)
		(end 136.801098 -88.499188)
		(width 0.0889)
		(layer "B.Cu")
		(net "P3E_CPU1_PE3_MP_TXP<11>")
	)
	(arc
		(start 139.366244 -94.937834)
		(mid 139.465293 -94.907497)
		(end 139.53617 -94.831916)
		(width 0.0889)
		(layer "B.Cu")
		(net "P3E_CPU1_PE3_MP_TXP<11>")
	)
	(arc
		(start 128.567688 -94.822518)
		(mid 128.49489 -94.531755)
		(end 128.574038 -94.242636)
		(width 0.0889)
		(layer "B.Cu")
		(net "P3E_CPU1_PE3_MP_TXP<11>")
	)
	(arc
		(start 128.578864 -93.2434)
		(mid 128.627619 -93.047048)
		(end 128.574038 -92.851986)
		(width 0.0889)
		(layer "B.Cu")
		(net "P3E_CPU1_PE3_MP_TXP<11>")
	)
	(arc
		(start 130.291078 -90.280236)
		(mid 130.499686 -90.068304)
		(end 130.785108 -89.984834)
		(width 0.0889)
		(layer "B.Cu")
		(net "P3E_CPU1_PE3_MP_TXP<11>")
	)
	(arc
		(start 133.38937 -88.499188)
		(mid 133.58322 -88.442838)
		(end 133.724904 -88.299036)
		(width 0.0889)
		(layer "B.Cu")
		(net "P3E_CPU1_PE3_MP_TXP<11>")
	)
	(arc
		(start 128.574038 -98.795586)
		(mid 128.494816 -98.506468)
		(end 128.567688 -98.215704)
		(width 0.0889)
		(layer "B.Cu")
		(net "P3E_CPU1_PE3_MP_TXP<11>")
	)
	(arc
		(start 138.876024 -95.232982)
		(mid 139.083028 -95.022118)
		(end 139.366244 -94.937834)
		(width 0.0889)
		(layer "B.Cu")
		(net "P3E_CPU1_PE3_MP_TXP<11>")
	)
	(arc
		(start 137.324084 -90.775536)
		(mid 137.403306 -91.064654)
		(end 137.330434 -91.355418)
		(width 0.0889)
		(layer "B.Cu")
		(net "P3E_CPU1_PE3_MP_TXP<11>")
	)
	(arc
		(start 135.607044 -87.803736)
		(mid 135.747123 -87.946472)
		(end 135.938768 -88.003634)
		(width 0.0889)
		(layer "B.Cu")
		(net "P3E_CPU1_PE3_MP_TXP<11>")
	)
	(arc
		(start 128.567688 -100.766118)
		(mid 128.49489 -100.475355)
		(end 128.574038 -100.186236)
		(width 0.0889)
		(layer "B.Cu")
		(net "P3E_CPU1_PE3_MP_TXP<11>")
	)
	(arc
		(start 135.971534 -88.003634)
		(mid 136.256958 -88.087101)
		(end 136.465564 -88.299036)
		(width 0.0889)
		(layer "B.Cu")
		(net "P3E_CPU1_PE3_MP_TXP<11>")
	)
	(arc
		(start 128.627632 -100.976684)
		(mid 128.613962 -100.873218)
		(end 128.574038 -100.776786)
		(width 0.0889)
		(layer "B.Cu")
		(net "P3E_CPU1_PE3_MP_TXP<11>")
	)
	(arc
		(start 128.578864 -97.2058)
		(mid 128.627619 -97.009448)
		(end 128.574038 -96.814386)
		(width 0.0889)
		(layer "B.Cu")
		(net "P3E_CPU1_PE3_MP_TXP<11>")
	)
	(arc
		(start 135.116824 -87.508588)
		(mid 135.400041 -87.592869)
		(end 135.607044 -87.803736)
		(width 0.0889)
		(layer "B.Cu")
		(net "P3E_CPU1_PE3_MP_TXP<11>")
	)
	(arc
		(start 137.324084 -89.784936)
		(mid 137.403306 -90.074054)
		(end 137.330434 -90.364818)
		(width 0.0889)
		(layer "B.Cu")
		(net "P3E_CPU1_PE3_MP_TXP<11>")
	)
	(arc
		(start 132.53466 -88.994234)
		(mid 132.726302 -88.937068)
		(end 132.866384 -88.794336)
		(width 0.0889)
		(layer "B.Cu")
		(net "P3E_CPU1_PE3_MP_TXP<11>")
	)
	(arc
		(start 137.688574 -91.966034)
		(mid 138.186825 -92.268874)
		(end 138.182604 -92.851986)
		(width 0.0889)
		(layer "B.Cu")
		(net "P3E_CPU1_PE3_MP_TXP<11>")
	)
	(arc
		(start 134.2517 -88.003634)
		(mid 134.443342 -87.946468)
		(end 134.583424 -87.803736)
		(width 0.0889)
		(layer "B.Cu")
		(net "P3E_CPU1_PE3_MP_TXP<11>")
	)
	(arc
		(start 128.574038 -95.823786)
		(mid 128.494907 -95.528384)
		(end 128.574038 -95.232982)
		(width 0.0889)
		(layer "B.Cu")
		(net "P3E_CPU1_PE3_MP_TXP<11>")
	)
	(arc
		(start 139.53617 -94.831916)
		(mid 139.538456 -94.64632)
		(end 139.387834 -94.537784)
		(width 0.0889)
		(layer "B.Cu")
		(net "P3E_CPU1_PE3_MP_TXP<11>")
	)
	(arc
		(start 128.574038 -97.804986)
		(mid 128.494816 -97.515868)
		(end 128.567688 -97.225104)
		(width 0.0889)
		(layer "B.Cu")
		(net "P3E_CPU1_PE3_MP_TXP<11>")
	)
	(arc
		(start 138.188954 -93.262704)
		(mid 138.261752 -93.553467)
		(end 138.182604 -93.842586)
		(width 0.0889)
		(layer "B.Cu")
		(net "P3E_CPU1_PE3_MP_TXP<11>")
	)
	(arc
		(start 128.578864 -92.2528)
		(mid 128.627619 -92.056448)
		(end 128.574038 -91.861386)
		(width 0.0889)
		(layer "B.Cu")
		(net "P3E_CPU1_PE3_MP_TXP<11>")
	)
	(arc
		(start 129.955544 -90.480388)
		(mid 130.149394 -90.424038)
		(end 130.291078 -90.280236)
		(width 0.0889)
		(layer "B.Cu")
		(net "P3E_CPU1_PE3_MP_TXP<11>")
	)
	(arc
		(start 128.574038 -99.786186)
		(mid 128.494816 -99.497068)
		(end 128.567688 -99.206304)
		(width 0.0889)
		(layer "B.Cu")
		(net "P3E_CPU1_PE3_MP_TXP<11>")
	)
	(arc
		(start 129.432558 -90.775536)
		(mid 129.639562 -90.564672)
		(end 129.922778 -90.480388)
		(width 0.0889)
		(layer "B.Cu")
		(net "P3E_CPU1_PE3_MP_TXP<11>")
	)
	(arc
		(start 128.578864 -99.187)
		(mid 128.627619 -98.990648)
		(end 128.574038 -98.795586)
		(width 0.0889)
		(layer "B.Cu")
		(net "P3E_CPU1_PE3_MP_TXP<11>")
	)
	(arc
		(start 128.574038 -93.842586)
		(mid 128.494816 -93.553468)
		(end 128.567688 -93.262704)
		(width 0.0889)
		(layer "B.Cu")
		(net "P3E_CPU1_PE3_MP_TXP<11>")
	)
	(arc
		(start 128.574038 -95.232982)
		(mid 128.627537 -95.033084)
		(end 128.574038 -94.833186)
		(width 0.0889)
		(layer "B.Cu")
		(net "P3E_CPU1_PE3_MP_TXP<11>")
	)
	(arc
		(start 137.319258 -91.374722)
		(mid 137.323005 -91.763978)
		(end 137.655808 -91.966034)
		(width 0.0889)
		(layer "B.Cu")
		(net "P3E_CPU1_PE3_MP_TXP<11>")
	)
	(arc
		(start 128.574038 -91.861386)
		(mid 128.569709 -91.278214)
		(end 129.068068 -90.975434)
		(width 0.0889)
		(layer "B.Cu")
		(net "P3E_CPU1_PE3_MP_TXP<11>")
	)
	(segment
		(start 138.816334 -95.528384)
		(end 139.387834 -95.528384)
		(width 0.1143)
		(layer "F.Cu")
		(net "P3E_CPU1_PE3_MP_TXP<10>")
	)
	(via
		(at 139.387834 -95.528384)
		(size 0.508)
		(drill 0.254)
		(layers "F.Cu" "B.Cu")
		(net "P3E_CPU1_PE3_MP_TXP<10>")
	)
	(via
		(at 30.9372 -117.4242)
		(size 0.508)
		(drill 0.254)
		(layers "F.Cu" "B.Cu")
		(net "P3E_CPU1_PE3_MP_TXP<10>")
	)
	(segment
		(start 111.926878 -112.98428)
		(end 111.792258 -113.073942)
		(width 0.1143)
		(layer "B.Cu")
		(net "P3E_CPU1_PE3_MP_TXP<10>")
	)
	(segment
		(start 129.550668 -104.418384)
		(end 129.550668 -104.798114)
		(width 0.1143)
		(layer "B.Cu")
		(net "P3E_CPU1_PE3_MP_TXP<10>")
	)
	(segment
		(start 111.3663 -112.872266)
		(end 108.706666 -112.34039)
		(width 0.1143)
		(layer "B.Cu")
		(net "P3E_CPU1_PE3_MP_TXP<10>")
	)
	(segment
		(start 136.30529 -91.374722)
		(end 136.300464 -91.366086)
		(width 0.0889)
		(layer "B.Cu")
		(net "P3E_CPU1_PE3_MP_TXP<10>")
	)
	(segment
		(start 129.592832 -94.234)
		(end 129.597658 -94.242636)
		(width 0.0889)
		(layer "B.Cu")
		(net "P3E_CPU1_PE3_MP_TXP<10>")
	)
	(segment
		(start 133.395974 -89.680288)
		(end 133.363208 -89.680288)
		(width 0.0889)
		(layer "B.Cu")
		(net "P3E_CPU1_PE3_MP_TXP<10>")
	)
	(segment
		(start 135.11022 -88.689688)
		(end 135.080248 -88.689688)
		(width 0.0889)
		(layer "B.Cu")
		(net "P3E_CPU1_PE3_MP_TXP<10>")
	)
	(segment
		(start 132.17652 -90.369644)
		(end 132.173218 -90.375486)
		(width 0.0889)
		(layer "B.Cu")
		(net "P3E_CPU1_PE3_MP_TXP<10>")
	)
	(segment
		(start 111.456216 -113.006886)
		(end 111.366554 -112.872266)
		(width 0.1143)
		(layer "B.Cu")
		(net "P3E_CPU1_PE3_MP_TXP<10>")
	)
	(segment
		(start 120.137682 -112.015016)
		(end 119.801386 -112.081818)
		(width 0.1143)
		(layer "B.Cu")
		(net "P3E_CPU1_PE3_MP_TXP<10>")
	)
	(segment
		(start 129.962148 -91.661488)
		(end 129.929382 -91.661488)
		(width 0.0889)
		(layer "B.Cu")
		(net "P3E_CPU1_PE3_MP_TXP<10>")
	)
	(segment
		(start 121.124472 -111.702342)
		(end 121.034556 -111.836708)
		(width 0.1143)
		(layer "B.Cu")
		(net "P3E_CPU1_PE3_MP_TXP<10>")
	)
	(segment
		(start 118.904512 -112.260126)
		(end 118.770146 -112.170464)
		(width 0.1143)
		(layer "B.Cu")
		(net "P3E_CPU1_PE3_MP_TXP<10>")
	)
	(segment
		(start 136.300464 -91.366086)
		(end 136.294114 -91.355418)
		(width 0.0889)
		(layer "B.Cu")
		(net "P3E_CPU1_PE3_MP_TXP<10>")
	)
	(segment
		(start 129.550668 -104.798114)
		(end 123.024646 -111.32439)
		(width 0.1143)
		(layer "B.Cu")
		(net "P3E_CPU1_PE3_MP_TXP<10>")
	)
	(segment
		(start 129.604008 -100.766118)
		(end 129.525268 -100.902516)
		(width 0.0889)
		(layer "B.Cu")
		(net "P3E_CPU1_PE3_MP_TXP<10>")
	)
	(segment
		(start 129.597658 -98.205036)
		(end 129.604008 -98.215704)
		(width 0.0889)
		(layer "B.Cu")
		(net "P3E_CPU1_PE3_MP_TXP<10>")
	)
	(segment
		(start 102.780084 -112.58169)
		(end 96.363282 -113.865152)
		(width 0.1143)
		(layer "B.Cu")
		(net "P3E_CPU1_PE3_MP_TXP<10>")
	)
	(segment
		(start 137.158984 -94.833186)
		(end 137.152634 -94.822518)
		(width 0.0889)
		(layer "B.Cu")
		(net "P3E_CPU1_PE3_MP_TXP<10>")
	)
	(segment
		(start 112.688878 -113.253266)
		(end 112.352836 -113.18621)
		(width 0.1143)
		(layer "B.Cu")
		(net "P3E_CPU1_PE3_MP_TXP<10>")
	)
	(segment
		(start 91.417394 -112.876076)
		(end 82.333846 -114.692938)
		(width 0.1143)
		(layer "B.Cu")
		(net "P3E_CPU1_PE3_MP_TXP<10>")
	)
	(segment
		(start 136.300464 -90.375486)
		(end 136.294114 -90.364818)
		(width 0.0889)
		(layer "B.Cu")
		(net "P3E_CPU1_PE3_MP_TXP<10>")
	)
	(segment
		(start 70.602602 -112.346232)
		(end 53.421534 -115.744498)
		(width 0.1143)
		(layer "B.Cu")
		(net "P3E_CPU1_PE3_MP_TXP<10>")
	)
	(segment
		(start 30.491938 -117.4242)
		(end 30.9372 -117.4242)
		(width 0.1143)
		(layer "B.Cu")
		(net "P3E_CPU1_PE3_MP_TXP<10>")
	)
	(segment
		(start 53.421534 -115.744498)
		(end 36.36772 -117.4242)
		(width 0.1143)
		(layer "B.Cu")
		(net "P3E_CPU1_PE3_MP_TXP<10>")
	)
	(segment
		(start 120.227598 -111.88065)
		(end 120.137682 -112.015016)
		(width 0.1143)
		(layer "B.Cu")
		(net "P3E_CPU1_PE3_MP_TXP<10>")
	)
	(segment
		(start 135.96493 -89.184734)
		(end 135.932164 -89.184734)
		(width 0.0889)
		(layer "B.Cu")
		(net "P3E_CPU1_PE3_MP_TXP<10>")
	)
	(segment
		(start 123.024646 -111.32439)
		(end 121.124472 -111.702342)
		(width 0.1143)
		(layer "B.Cu")
		(net "P3E_CPU1_PE3_MP_TXP<10>")
	)
	(segment
		(start 120.563894 -111.813848)
		(end 120.227598 -111.88065)
		(width 0.1143)
		(layer "B.Cu")
		(net "P3E_CPU1_PE3_MP_TXP<10>")
	)
	(segment
		(start 17.71142 -108.83392)
		(end 17.71142 -108.72978)
		(width 0.1143)
		(layer "B.Cu")
		(net "P3E_CPU1_PE3_MP_TXP<10>")
	)
	(segment
		(start 139.387834 -95.528384)
		(end 139.094718 -95.697548)
		(width 0.0889)
		(layer "B.Cu")
		(net "P3E_CPU1_PE3_MP_TXP<10>")
	)
	(segment
		(start 18.306288 -109.591348)
		(end 23.060914 -114.345974)
		(width 0.1143)
		(layer "B.Cu")
		(net "P3E_CPU1_PE3_MP_TXP<10>")
	)
	(segment
		(start 119.241062 -112.193324)
		(end 118.904512 -112.260126)
		(width 0.1143)
		(layer "B.Cu")
		(net "P3E_CPU1_PE3_MP_TXP<10>")
	)
	(segment
		(start 129.592832 -97.2058)
		(end 129.597658 -97.214436)
		(width 0.0889)
		(layer "B.Cu")
		(net "P3E_CPU1_PE3_MP_TXP<10>")
	)
	(segment
		(start 17.9705 -108.4707)
		(end 18.099024 -108.4707)
		(width 0.1143)
		(layer "B.Cu")
		(net "P3E_CPU1_PE3_MP_TXP<10>")
	)
	(segment
		(start 131.679188 -90.670888)
		(end 131.646422 -90.670888)
		(width 0.0889)
		(layer "B.Cu")
		(net "P3E_CPU1_PE3_MP_TXP<10>")
	)
	(segment
		(start 112.352836 -113.18621)
		(end 112.263174 -113.05159)
		(width 0.1143)
		(layer "B.Cu")
		(net "P3E_CPU1_PE3_MP_TXP<10>")
	)
	(segment
		(start 36.36772 -117.4242)
		(end 30.9372 -117.4242)
		(width 0.1143)
		(layer "B.Cu")
		(net "P3E_CPU1_PE3_MP_TXP<10>")
	)
	(segment
		(start 129.604008 -94.822518)
		(end 129.597658 -94.833186)
		(width 0.0889)
		(layer "B.Cu")
		(net "P3E_CPU1_PE3_MP_TXP<10>")
	)
	(segment
		(start 112.823498 -113.163604)
		(end 112.688878 -113.253266)
		(width 0.1143)
		(layer "B.Cu")
		(net "P3E_CPU1_PE3_MP_TXP<10>")
	)
	(segment
		(start 121.034556 -111.836708)
		(end 120.69826 -111.90351)
		(width 0.1143)
		(layer "B.Cu")
		(net "P3E_CPU1_PE3_MP_TXP<10>")
	)
	(segment
		(start 129.597658 -92.261436)
		(end 129.604008 -92.272104)
		(width 0.0889)
		(layer "B.Cu")
		(net "P3E_CPU1_PE3_MP_TXP<10>")
	)
	(segment
		(start 136.30529 -90.384122)
		(end 136.300464 -90.375486)
		(width 0.0889)
		(layer "B.Cu")
		(net "P3E_CPU1_PE3_MP_TXP<10>")
	)
	(segment
		(start 129.550668 -104.396286)
		(end 129.550668 -104.418384)
		(width 0.0889)
		(layer "B.Cu")
		(net "P3E_CPU1_PE3_MP_TXP<10>")
	)
	(segment
		(start 129.597658 -93.252036)
		(end 129.604008 -93.262704)
		(width 0.0889)
		(layer "B.Cu")
		(net "P3E_CPU1_PE3_MP_TXP<10>")
	)
	(segment
		(start 137.68197 -96.118934)
		(end 137.649204 -96.118934)
		(width 0.0889)
		(layer "B.Cu")
		(net "P3E_CPU1_PE3_MP_TXP<10>")
	)
	(segment
		(start 129.597658 -99.195636)
		(end 129.604008 -99.206304)
		(width 0.0889)
		(layer "B.Cu")
		(net "P3E_CPU1_PE3_MP_TXP<10>")
	)
	(segment
		(start 132.541264 -90.175334)
		(end 132.519674 -90.175334)
		(width 0.0889)
		(layer "B.Cu")
		(net "P3E_CPU1_PE3_MP_TXP<10>")
	)
	(segment
		(start 23.060914 -114.345974)
		(end 30.491938 -117.4242)
		(width 0.1143)
		(layer "B.Cu")
		(net "P3E_CPU1_PE3_MP_TXP<10>")
	)
	(segment
		(start 96.363282 -113.865152)
		(end 91.417394 -112.876076)
		(width 0.1143)
		(layer "B.Cu")
		(net "P3E_CPU1_PE3_MP_TXP<10>")
	)
	(segment
		(start 130.824478 -91.165934)
		(end 130.791712 -91.165934)
		(width 0.0889)
		(layer "B.Cu")
		(net "P3E_CPU1_PE3_MP_TXP<10>")
	)
	(segment
		(start 118.770146 -112.170464)
		(end 113.298224 -113.2586)
		(width 0.1143)
		(layer "B.Cu")
		(net "P3E_CPU1_PE3_MP_TXP<10>")
	)
	(segment
		(start 18.306288 -108.677964)
		(end 18.306288 -109.591348)
		(width 0.1143)
		(layer "B.Cu")
		(net "P3E_CPU1_PE3_MP_TXP<10>")
	)
	(segment
		(start 120.69826 -111.90351)
		(end 120.563894 -111.813848)
		(width 0.1143)
		(layer "B.Cu")
		(net "P3E_CPU1_PE3_MP_TXP<10>")
	)
	(segment
		(start 129.592832 -99.187)
		(end 129.597658 -99.195636)
		(width 0.0889)
		(layer "B.Cu")
		(net "P3E_CPU1_PE3_MP_TXP<10>")
	)
	(segment
		(start 108.706666 -112.34039)
		(end 105.139744 -113.053622)
		(width 0.1143)
		(layer "B.Cu")
		(net "P3E_CPU1_PE3_MP_TXP<10>")
	)
	(segment
		(start 112.263174 -113.05159)
		(end 111.926878 -112.98428)
		(width 0.1143)
		(layer "B.Cu")
		(net "P3E_CPU1_PE3_MP_TXP<10>")
	)
	(segment
		(start 137.152634 -93.262704)
		(end 137.158984 -93.252036)
		(width 0.0889)
		(layer "B.Cu")
		(net "P3E_CPU1_PE3_MP_TXP<10>")
	)
	(segment
		(start 139.094718 -95.697548)
		(end 139.070842 -95.786956)
		(width 0.0889)
		(layer "B.Cu")
		(net "P3E_CPU1_PE3_MP_TXP<10>")
	)
	(segment
		(start 129.592832 -93.2434)
		(end 129.597658 -93.252036)
		(width 0.0889)
		(layer "B.Cu")
		(net "P3E_CPU1_PE3_MP_TXP<10>")
	)
	(segment
		(start 111.792258 -113.073942)
		(end 111.456216 -113.006886)
		(width 0.1143)
		(layer "B.Cu")
		(net "P3E_CPU1_PE3_MP_TXP<10>")
	)
	(segment
		(start 129.525268 -100.902516)
		(end 129.525268 -104.370886)
		(width 0.0889)
		(layer "B.Cu")
		(net "P3E_CPU1_PE3_MP_TXP<10>")
	)
	(segment
		(start 137.158984 -93.252036)
		(end 137.16381 -93.2434)
		(width 0.0889)
		(layer "B.Cu")
		(net "P3E_CPU1_PE3_MP_TXP<10>")
	)
	(segment
		(start 113.298224 -113.2586)
		(end 112.823498 -113.163604)
		(width 0.1143)
		(layer "B.Cu")
		(net "P3E_CPU1_PE3_MP_TXP<10>")
	)
	(segment
		(start 119.66702 -111.992156)
		(end 119.330724 -112.058958)
		(width 0.1143)
		(layer "B.Cu")
		(net "P3E_CPU1_PE3_MP_TXP<10>")
	)
	(segment
		(start 119.330724 -112.058958)
		(end 119.241062 -112.193324)
		(width 0.1143)
		(layer "B.Cu")
		(net "P3E_CPU1_PE3_MP_TXP<10>")
	)
	(segment
		(start 129.597658 -96.223836)
		(end 129.604008 -96.234504)
		(width 0.0889)
		(layer "B.Cu")
		(net "P3E_CPU1_PE3_MP_TXP<10>")
	)
	(segment
		(start 129.592832 -100.1776)
		(end 129.597658 -100.186236)
		(width 0.0889)
		(layer "B.Cu")
		(net "P3E_CPU1_PE3_MP_TXP<10>")
	)
	(segment
		(start 129.592832 -98.1964)
		(end 129.597658 -98.205036)
		(width 0.0889)
		(layer "B.Cu")
		(net "P3E_CPU1_PE3_MP_TXP<10>")
	)
	(segment
		(start 105.139744 -113.053622)
		(end 102.780084 -112.58169)
		(width 0.1143)
		(layer "B.Cu")
		(net "P3E_CPU1_PE3_MP_TXP<10>")
	)
	(segment
		(start 18.099024 -108.4707)
		(end 18.306288 -108.677964)
		(width 0.1143)
		(layer "B.Cu")
		(net "P3E_CPU1_PE3_MP_TXP<10>")
	)
	(segment
		(start 129.597658 -97.214436)
		(end 129.604008 -97.225104)
		(width 0.0889)
		(layer "B.Cu")
		(net "P3E_CPU1_PE3_MP_TXP<10>")
	)
	(segment
		(start 119.801386 -112.081818)
		(end 119.66702 -111.992156)
		(width 0.1143)
		(layer "B.Cu")
		(net "P3E_CPU1_PE3_MP_TXP<10>")
	)
	(segment
		(start 129.592832 -92.2528)
		(end 129.597658 -92.261436)
		(width 0.0889)
		(layer "B.Cu")
		(net "P3E_CPU1_PE3_MP_TXP<10>")
	)
	(segment
		(start 137.158984 -94.242636)
		(end 137.16381 -94.234)
		(width 0.0889)
		(layer "B.Cu")
		(net "P3E_CPU1_PE3_MP_TXP<10>")
	)
	(segment
		(start 134.258304 -89.184734)
		(end 134.225538 -89.184734)
		(width 0.0889)
		(layer "B.Cu")
		(net "P3E_CPU1_PE3_MP_TXP<10>")
	)
	(segment
		(start 82.333846 -114.692938)
		(end 70.602602 -112.346232)
		(width 0.1143)
		(layer "B.Cu")
		(net "P3E_CPU1_PE3_MP_TXP<10>")
	)
	(segment
		(start 129.592832 -96.2152)
		(end 129.597658 -96.223836)
		(width 0.0889)
		(layer "B.Cu")
		(net "P3E_CPU1_PE3_MP_TXP<10>")
	)
	(segment
		(start 129.525268 -104.370886)
		(end 129.550668 -104.396286)
		(width 0.0889)
		(layer "B.Cu")
		(net "P3E_CPU1_PE3_MP_TXP<10>")
	)
	(segment
		(start 136.82726 -92.652088)
		(end 136.794494 -92.652088)
		(width 0.0889)
		(layer "B.Cu")
		(net "P3E_CPU1_PE3_MP_TXP<10>")
	)
	(segment
		(start 17.71142 -108.72978)
		(end 17.9705 -108.4707)
		(width 0.1143)
		(layer "B.Cu")
		(net "P3E_CPU1_PE3_MP_TXP<10>")
	)
	(segment
		(start 111.366554 -112.872266)
		(end 111.3663 -112.872266)
		(width 0.1143)
		(layer "B.Cu")
		(net "P3E_CPU1_PE3_MP_TXP<10>")
	)
	(arc
		(start 129.929382 -91.661488)
		(mid 129.596464 -91.863479)
		(end 129.592832 -92.2528)
		(width 0.0889)
		(layer "B.Cu")
		(net "P3E_CPU1_PE3_MP_TXP<10>")
	)
	(arc
		(start 129.597658 -95.823786)
		(mid 129.544188 -96.018849)
		(end 129.592832 -96.2152)
		(width 0.0889)
		(layer "B.Cu")
		(net "P3E_CPU1_PE3_MP_TXP<10>")
	)
	(arc
		(start 129.597658 -97.804986)
		(mid 129.544188 -98.000049)
		(end 129.592832 -98.1964)
		(width 0.0889)
		(layer "B.Cu")
		(net "P3E_CPU1_PE3_MP_TXP<10>")
	)
	(arc
		(start 129.604008 -96.234504)
		(mid 129.676806 -96.525267)
		(end 129.597658 -96.814386)
		(width 0.0889)
		(layer "B.Cu")
		(net "P3E_CPU1_PE3_MP_TXP<10>")
	)
	(arc
		(start 134.225538 -89.184734)
		(mid 134.031688 -89.241084)
		(end 133.890004 -89.384886)
		(width 0.0889)
		(layer "B.Cu")
		(net "P3E_CPU1_PE3_MP_TXP<10>")
	)
	(arc
		(start 137.16381 -93.2434)
		(mid 137.160063 -92.854144)
		(end 136.82726 -92.652088)
		(width 0.0889)
		(layer "B.Cu")
		(net "P3E_CPU1_PE3_MP_TXP<10>")
	)
	(arc
		(start 134.748524 -88.889586)
		(mid 134.54152 -89.10045)
		(end 134.258304 -89.184734)
		(width 0.0889)
		(layer "B.Cu")
		(net "P3E_CPU1_PE3_MP_TXP<10>")
	)
	(arc
		(start 129.597658 -94.242636)
		(mid 129.67688 -94.531754)
		(end 129.604008 -94.822518)
		(width 0.0889)
		(layer "B.Cu")
		(net "P3E_CPU1_PE3_MP_TXP<10>")
	)
	(arc
		(start 137.158984 -95.232982)
		(mid 137.212483 -95.033084)
		(end 137.158984 -94.833186)
		(width 0.0889)
		(layer "B.Cu")
		(net "P3E_CPU1_PE3_MP_TXP<10>")
	)
	(arc
		(start 137.152634 -94.822518)
		(mid 137.079836 -94.531755)
		(end 137.158984 -94.242636)
		(width 0.0889)
		(layer "B.Cu")
		(net "P3E_CPU1_PE3_MP_TXP<10>")
	)
	(arc
		(start 129.604008 -99.206304)
		(mid 129.676806 -99.497067)
		(end 129.597658 -99.786186)
		(width 0.0889)
		(layer "B.Cu")
		(net "P3E_CPU1_PE3_MP_TXP<10>")
	)
	(arc
		(start 136.794494 -92.652088)
		(mid 136.296243 -92.349248)
		(end 136.300464 -91.766136)
		(width 0.0889)
		(layer "B.Cu")
		(net "P3E_CPU1_PE3_MP_TXP<10>")
	)
	(arc
		(start 137.649204 -96.118934)
		(mid 137.153727 -95.814491)
		(end 137.158984 -95.232982)
		(width 0.0889)
		(layer "B.Cu")
		(net "P3E_CPU1_PE3_MP_TXP<10>")
	)
	(arc
		(start 129.604008 -93.262704)
		(mid 129.676806 -93.553467)
		(end 129.597658 -93.842586)
		(width 0.0889)
		(layer "B.Cu")
		(net "P3E_CPU1_PE3_MP_TXP<10>")
	)
	(arc
		(start 129.597658 -98.795586)
		(mid 129.544188 -98.990649)
		(end 129.592832 -99.187)
		(width 0.0889)
		(layer "B.Cu")
		(net "P3E_CPU1_PE3_MP_TXP<10>")
	)
	(arc
		(start 129.604008 -97.225104)
		(mid 129.676806 -97.515867)
		(end 129.597658 -97.804986)
		(width 0.0889)
		(layer "B.Cu")
		(net "P3E_CPU1_PE3_MP_TXP<10>")
	)
	(arc
		(start 129.597658 -94.833186)
		(mid 129.544159 -95.033084)
		(end 129.597658 -95.232982)
		(width 0.0889)
		(layer "B.Cu")
		(net "P3E_CPU1_PE3_MP_TXP<10>")
	)
	(arc
		(start 129.597658 -99.786186)
		(mid 129.544188 -99.981249)
		(end 129.592832 -100.1776)
		(width 0.0889)
		(layer "B.Cu")
		(net "P3E_CPU1_PE3_MP_TXP<10>")
	)
	(arc
		(start 135.080248 -88.689688)
		(mid 134.888606 -88.746854)
		(end 134.748524 -88.889586)
		(width 0.0889)
		(layer "B.Cu")
		(net "P3E_CPU1_PE3_MP_TXP<10>")
	)
	(arc
		(start 138.017504 -96.319086)
		(mid 137.875821 -96.175282)
		(end 137.68197 -96.118934)
		(width 0.0889)
		(layer "B.Cu")
		(net "P3E_CPU1_PE3_MP_TXP<10>")
	)
	(arc
		(start 132.173218 -90.375486)
		(mid 131.96461 -90.587418)
		(end 131.679188 -90.670888)
		(width 0.0889)
		(layer "B.Cu")
		(net "P3E_CPU1_PE3_MP_TXP<10>")
	)
	(arc
		(start 129.597658 -95.232982)
		(mid 129.676789 -95.528384)
		(end 129.597658 -95.823786)
		(width 0.0889)
		(layer "B.Cu")
		(net "P3E_CPU1_PE3_MP_TXP<10>")
	)
	(arc
		(start 129.604008 -92.272104)
		(mid 129.676806 -92.562867)
		(end 129.597658 -92.851986)
		(width 0.0889)
		(layer "B.Cu")
		(net "P3E_CPU1_PE3_MP_TXP<10>")
	)
	(arc
		(start 136.294114 -91.355418)
		(mid 136.221316 -91.064655)
		(end 136.300464 -90.775536)
		(width 0.0889)
		(layer "B.Cu")
		(net "P3E_CPU1_PE3_MP_TXP<10>")
	)
	(arc
		(start 133.363208 -89.680288)
		(mid 133.171566 -89.737454)
		(end 133.031484 -89.880186)
		(width 0.0889)
		(layer "B.Cu")
		(net "P3E_CPU1_PE3_MP_TXP<10>")
	)
	(arc
		(start 136.300464 -91.766136)
		(mid 136.353934 -91.571073)
		(end 136.30529 -91.374722)
		(width 0.0889)
		(layer "B.Cu")
		(net "P3E_CPU1_PE3_MP_TXP<10>")
	)
	(arc
		(start 129.597658 -100.186236)
		(mid 129.67688 -100.475354)
		(end 129.604008 -100.766118)
		(width 0.0889)
		(layer "B.Cu")
		(net "P3E_CPU1_PE3_MP_TXP<10>")
	)
	(arc
		(start 136.294114 -90.364818)
		(mid 136.221316 -90.074055)
		(end 136.300464 -89.784936)
		(width 0.0889)
		(layer "B.Cu")
		(net "P3E_CPU1_PE3_MP_TXP<10>")
	)
	(arc
		(start 131.646422 -90.670888)
		(mid 131.45478 -90.728054)
		(end 131.314698 -90.870786)
		(width 0.0889)
		(layer "B.Cu")
		(net "P3E_CPU1_PE3_MP_TXP<10>")
	)
	(arc
		(start 133.890004 -89.384886)
		(mid 133.681396 -89.596818)
		(end 133.395974 -89.680288)
		(width 0.0889)
		(layer "B.Cu")
		(net "P3E_CPU1_PE3_MP_TXP<10>")
	)
	(arc
		(start 131.314698 -90.870786)
		(mid 131.107694 -91.08165)
		(end 130.824478 -91.165934)
		(width 0.0889)
		(layer "B.Cu")
		(net "P3E_CPU1_PE3_MP_TXP<10>")
	)
	(arc
		(start 129.597658 -92.851986)
		(mid 129.544188 -93.047049)
		(end 129.592832 -93.2434)
		(width 0.0889)
		(layer "B.Cu")
		(net "P3E_CPU1_PE3_MP_TXP<10>")
	)
	(arc
		(start 137.158984 -93.842586)
		(mid 137.079762 -93.553468)
		(end 137.152634 -93.262704)
		(width 0.0889)
		(layer "B.Cu")
		(net "P3E_CPU1_PE3_MP_TXP<10>")
	)
	(arc
		(start 129.597658 -96.814386)
		(mid 129.544188 -97.009449)
		(end 129.592832 -97.2058)
		(width 0.0889)
		(layer "B.Cu")
		(net "P3E_CPU1_PE3_MP_TXP<10>")
	)
	(arc
		(start 133.031484 -89.880186)
		(mid 132.82448 -90.09105)
		(end 132.541264 -90.175334)
		(width 0.0889)
		(layer "B.Cu")
		(net "P3E_CPU1_PE3_MP_TXP<10>")
	)
	(arc
		(start 135.932164 -89.184734)
		(mid 135.648947 -89.100453)
		(end 135.441944 -88.889586)
		(width 0.0889)
		(layer "B.Cu")
		(net "P3E_CPU1_PE3_MP_TXP<10>")
	)
	(arc
		(start 129.597658 -93.842586)
		(mid 129.544188 -94.037649)
		(end 129.592832 -94.234)
		(width 0.0889)
		(layer "B.Cu")
		(net "P3E_CPU1_PE3_MP_TXP<10>")
	)
	(arc
		(start 137.16381 -94.234)
		(mid 137.212565 -94.037648)
		(end 137.158984 -93.842586)
		(width 0.0889)
		(layer "B.Cu")
		(net "P3E_CPU1_PE3_MP_TXP<10>")
	)
	(arc
		(start 136.300464 -89.784936)
		(mid 136.303212 -89.389469)
		(end 135.96493 -89.184734)
		(width 0.0889)
		(layer "B.Cu")
		(net "P3E_CPU1_PE3_MP_TXP<10>")
	)
	(arc
		(start 135.441944 -88.889586)
		(mid 135.301865 -88.74685)
		(end 135.11022 -88.689688)
		(width 0.0889)
		(layer "B.Cu")
		(net "P3E_CPU1_PE3_MP_TXP<10>")
	)
	(arc
		(start 139.070842 -95.786956)
		(mid 139.019057 -96.354904)
		(end 138.51128 -96.614488)
		(width 0.0889)
		(layer "B.Cu")
		(net "P3E_CPU1_PE3_MP_TXP<10>")
	)
	(arc
		(start 138.51128 -96.614488)
		(mid 138.225997 -96.530962)
		(end 138.017504 -96.319086)
		(width 0.0889)
		(layer "B.Cu")
		(net "P3E_CPU1_PE3_MP_TXP<10>")
	)
	(arc
		(start 132.519674 -90.175334)
		(mid 132.322513 -90.227293)
		(end 132.17652 -90.369644)
		(width 0.0889)
		(layer "B.Cu")
		(net "P3E_CPU1_PE3_MP_TXP<10>")
	)
	(arc
		(start 130.456178 -91.366086)
		(mid 130.24757 -91.578018)
		(end 129.962148 -91.661488)
		(width 0.0889)
		(layer "B.Cu")
		(net "P3E_CPU1_PE3_MP_TXP<10>")
	)
	(arc
		(start 129.604008 -98.215704)
		(mid 129.676806 -98.506467)
		(end 129.597658 -98.795586)
		(width 0.0889)
		(layer "B.Cu")
		(net "P3E_CPU1_PE3_MP_TXP<10>")
	)
	(arc
		(start 130.791712 -91.165934)
		(mid 130.597862 -91.222284)
		(end 130.456178 -91.366086)
		(width 0.0889)
		(layer "B.Cu")
		(net "P3E_CPU1_PE3_MP_TXP<10>")
	)
	(arc
		(start 136.300464 -90.775536)
		(mid 136.353934 -90.580473)
		(end 136.30529 -90.384122)
		(width 0.0889)
		(layer "B.Cu")
		(net "P3E_CPU1_PE3_MP_TXP<10>")
	)
	(segment
		(start 138.816334 -97.509584)
		(end 139.387834 -97.509584)
		(width 0.1143)
		(layer "F.Cu")
		(net "P3E_CPU1_PE3_MP_TXN<9>")
	)
	(via
		(at 139.387834 -97.509584)
		(size 0.508)
		(drill 0.254)
		(layers "F.Cu" "B.Cu")
		(net "P3E_CPU1_PE3_MP_TXN<9>")
	)
	(via
		(at 35.503104 -111.176816)
		(size 0.508)
		(drill 0.254)
		(layers "F.Cu" "B.Cu")
		(net "P3E_CPU1_PE3_MP_TXN<9>")
	)
	(segment
		(start 129.922778 -85.527388)
		(end 129.955544 -85.527388)
		(width 0.0889)
		(layer "B.Cu")
		(net "P3E_CPU1_PE3_MP_TXN<9>")
	)
	(segment
		(start 124.286264 -89.393522)
		(end 124.281438 -89.384886)
		(width 0.0889)
		(layer "B.Cu")
		(net "P3E_CPU1_PE3_MP_TXN<9>")
	)
	(segment
		(start 22.626066 -101.761544)
		(end 23.76424 -104.510078)
		(width 0.1143)
		(layer "B.Cu")
		(net "P3E_CPU1_PE3_MP_TXN<9>")
	)
	(segment
		(start 120.606566 -104.24795)
		(end 120.62206 -104.232456)
		(width 0.0889)
		(layer "B.Cu")
		(net "P3E_CPU1_PE3_MP_TXN<9>")
	)
	(segment
		(start 130.785108 -85.031834)
		(end 130.817874 -85.031834)
		(width 0.0889)
		(layer "B.Cu")
		(net "P3E_CPU1_PE3_MP_TXN<9>")
	)
	(segment
		(start 20.921472 -100.05695)
		(end 22.626066 -101.761544)
		(width 0.1143)
		(layer "B.Cu")
		(net "P3E_CPU1_PE3_MP_TXN<9>")
	)
	(segment
		(start 119.672862 -105.1814)
		(end 119.688102 -105.16616)
		(width 0.1143)
		(layer "B.Cu")
		(net "P3E_CPU1_PE3_MP_TXN<9>")
	)
	(segment
		(start 124.281438 -89.384886)
		(end 124.275088 -89.374218)
		(width 0.0889)
		(layer "B.Cu")
		(net "P3E_CPU1_PE3_MP_TXN<9>")
	)
	(segment
		(start 113.605818 -106.277918)
		(end 113.740184 -106.36758)
		(width 0.1143)
		(layer "B.Cu")
		(net "P3E_CPU1_PE3_MP_TXN<9>")
	)
	(segment
		(start 123.677934 -100.881688)
		(end 123.949206 -100.881688)
		(width 0.0889)
		(layer "B.Cu")
		(net "P3E_CPU1_PE3_MP_TXN<9>")
	)
	(segment
		(start 35.876484 -111.176816)
		(end 53.438552 -109.447076)
		(width 0.1143)
		(layer "B.Cu")
		(net "P3E_CPU1_PE3_MP_TXN<9>")
	)
	(segment
		(start 25.195022 -105.94086)
		(end 25.195022 -105.941114)
		(width 0.1143)
		(layer "B.Cu")
		(net "P3E_CPU1_PE3_MP_TXN<9>")
	)
	(segment
		(start 138.518138 -84.536788)
		(end 138.550904 -84.536788)
		(width 0.0889)
		(layer "B.Cu")
		(net "P3E_CPU1_PE3_MP_TXN<9>")
	)
	(segment
		(start 117.543326 -105.607104)
		(end 117.879622 -105.540048)
		(width 0.1143)
		(layer "B.Cu")
		(net "P3E_CPU1_PE3_MP_TXN<9>")
	)
	(segment
		(start 124.286264 -93.355922)
		(end 124.281438 -93.347286)
		(width 0.0889)
		(layer "B.Cu")
		(net "P3E_CPU1_PE3_MP_TXN<9>")
	)
	(segment
		(start 126.488698 -87.508588)
		(end 126.521464 -87.508588)
		(width 0.0889)
		(layer "B.Cu")
		(net "P3E_CPU1_PE3_MP_TXN<9>")
	)
	(segment
		(start 124.771658 -88.499188)
		(end 124.804424 -88.499188)
		(width 0.0889)
		(layer "B.Cu")
		(net "P3E_CPU1_PE3_MP_TXN<9>")
	)
	(segment
		(start 120.62206 -104.232456)
		(end 120.65762 -104.232456)
		(width 0.0889)
		(layer "B.Cu")
		(net "P3E_CPU1_PE3_MP_TXN<9>")
	)
	(segment
		(start 133.356604 -83.546188)
		(end 133.38937 -83.546188)
		(width 0.0889)
		(layer "B.Cu")
		(net "P3E_CPU1_PE3_MP_TXN<9>")
	)
	(segment
		(start 124.281438 -92.356686)
		(end 124.275088 -92.346018)
		(width 0.0889)
		(layer "B.Cu")
		(net "P3E_CPU1_PE3_MP_TXN<9>")
	)
	(segment
		(start 124.286264 -97.318322)
		(end 124.281438 -97.309686)
		(width 0.0889)
		(layer "B.Cu")
		(net "P3E_CPU1_PE3_MP_TXN<9>")
	)
	(segment
		(start 113.269522 -106.345228)
		(end 113.605818 -106.277918)
		(width 0.1143)
		(layer "B.Cu")
		(net "P3E_CPU1_PE3_MP_TXN<9>")
	)
	(segment
		(start 18.72742 -99.71532)
		(end 19.06905 -100.05695)
		(width 0.1143)
		(layer "B.Cu")
		(net "P3E_CPU1_PE3_MP_TXN<9>")
	)
	(segment
		(start 123.337828 -101.552248)
		(end 123.337828 -101.221794)
		(width 0.0889)
		(layer "B.Cu")
		(net "P3E_CPU1_PE3_MP_TXN<9>")
	)
	(segment
		(start 124.281438 -97.309686)
		(end 124.275088 -97.299018)
		(width 0.0889)
		(layer "B.Cu")
		(net "P3E_CPU1_PE3_MP_TXN<9>")
	)
	(segment
		(start 139.387834 -97.17151)
		(end 139.387834 -97.509584)
		(width 0.0889)
		(layer "B.Cu")
		(net "P3E_CPU1_PE3_MP_TXN<9>")
	)
	(segment
		(start 131.639818 -84.536788)
		(end 131.661408 -84.536788)
		(width 0.0889)
		(layer "B.Cu")
		(net "P3E_CPU1_PE3_MP_TXN<9>")
	)
	(segment
		(start 141.611858 -89.281)
		(end 141.616684 -89.289636)
		(width 0.0889)
		(layer "B.Cu")
		(net "P3E_CPU1_PE3_MP_TXN<9>")
	)
	(segment
		(start 119.688356 -105.16616)
		(end 120.606566 -104.24795)
		(width 0.1143)
		(layer "B.Cu")
		(net "P3E_CPU1_PE3_MP_TXN<9>")
	)
	(segment
		(start 124.286264 -90.384122)
		(end 124.281438 -90.375486)
		(width 0.0889)
		(layer "B.Cu")
		(net "P3E_CPU1_PE3_MP_TXN<9>")
	)
	(segment
		(start 88.513158 -104.284526)
		(end 90.007948 -105.281222)
		(width 0.1143)
		(layer "B.Cu")
		(net "P3E_CPU1_PE3_MP_TXN<9>")
	)
	(segment
		(start 120.65762 -104.232456)
		(end 123.337828 -101.552248)
		(width 0.0889)
		(layer "B.Cu")
		(net "P3E_CPU1_PE3_MP_TXN<9>")
	)
	(segment
		(start 116.646706 -105.786428)
		(end 116.983002 -105.719372)
		(width 0.1143)
		(layer "B.Cu")
		(net "P3E_CPU1_PE3_MP_TXN<9>")
	)
	(segment
		(start 124.281438 -99.290886)
		(end 124.275088 -99.280218)
		(width 0.0889)
		(layer "B.Cu")
		(net "P3E_CPU1_PE3_MP_TXN<9>")
	)
	(segment
		(start 141.56309 -94.038928)
		(end 141.656562 -94.245684)
		(width 0.0889)
		(layer "B.Cu")
		(net "P3E_CPU1_PE3_MP_TXN<9>")
	)
	(segment
		(start 141.308074 -96.118934)
		(end 141.093698 -96.118934)
		(width 0.0889)
		(layer "B.Cu")
		(net "P3E_CPU1_PE3_MP_TXN<9>")
	)
	(segment
		(start 117.408706 -105.517442)
		(end 117.543326 -105.607104)
		(width 0.1143)
		(layer "B.Cu")
		(net "P3E_CPU1_PE3_MP_TXN<9>")
	)
	(segment
		(start 127.351028 -87.013034)
		(end 127.383794 -87.013034)
		(width 0.0889)
		(layer "B.Cu")
		(net "P3E_CPU1_PE3_MP_TXN<9>")
	)
	(segment
		(start 25.637236 -106.383328)
		(end 25.637236 -107.09529)
		(width 0.1143)
		(layer "B.Cu")
		(net "P3E_CPU1_PE3_MP_TXN<9>")
	)
	(segment
		(start 30.389322 -109.676438)
		(end 31.214314 -110.50143)
		(width 0.1143)
		(layer "B.Cu")
		(net "P3E_CPU1_PE3_MP_TXN<9>")
	)
	(segment
		(start 141.616684 -89.88044)
		(end 141.616684 -89.880186)
		(width 0.0889)
		(layer "B.Cu")
		(net "P3E_CPU1_PE3_MP_TXN<9>")
	)
	(segment
		(start 141.611858 -88.2904)
		(end 141.616684 -88.299036)
		(width 0.0889)
		(layer "B.Cu")
		(net "P3E_CPU1_PE3_MP_TXN<9>")
	)
	(segment
		(start 116.086128 -105.898442)
		(end 116.176044 -105.764076)
		(width 0.1143)
		(layer "B.Cu")
		(net "P3E_CPU1_PE3_MP_TXN<9>")
	)
	(segment
		(start 118.865904 -105.226104)
		(end 119.2022 -105.159048)
		(width 0.1143)
		(layer "B.Cu")
		(net "P3E_CPU1_PE3_MP_TXN<9>")
	)
	(segment
		(start 116.512086 -105.696766)
		(end 116.646706 -105.786428)
		(width 0.1143)
		(layer "B.Cu")
		(net "P3E_CPU1_PE3_MP_TXN<9>")
	)
	(segment
		(start 27.649932 -109.107478)
		(end 30.389322 -109.676438)
		(width 0.1143)
		(layer "B.Cu")
		(net "P3E_CPU1_PE3_MP_TXN<9>")
	)
	(segment
		(start 118.776242 -105.360724)
		(end 118.865904 -105.226104)
		(width 0.1143)
		(layer "B.Cu")
		(net "P3E_CPU1_PE3_MP_TXN<9>")
	)
	(segment
		(start 114.502438 -106.098594)
		(end 114.636804 -106.188256)
		(width 0.1143)
		(layer "B.Cu")
		(net "P3E_CPU1_PE3_MP_TXN<9>")
	)
	(segment
		(start 113.740184 -106.36758)
		(end 114.07648 -106.30027)
		(width 0.1143)
		(layer "B.Cu")
		(net "P3E_CPU1_PE3_MP_TXN<9>")
	)
	(segment
		(start 109.155484 -105.809288)
		(end 112.843564 -106.546904)
		(width 0.1143)
		(layer "B.Cu")
		(net "P3E_CPU1_PE3_MP_TXN<9>")
	)
	(segment
		(start 135.938768 -83.050634)
		(end 135.971534 -83.050634)
		(width 0.0889)
		(layer "B.Cu")
		(net "P3E_CPU1_PE3_MP_TXN<9>")
	)
	(segment
		(start 124.281438 -90.375486)
		(end 124.275088 -90.364818)
		(width 0.0889)
		(layer "B.Cu")
		(net "P3E_CPU1_PE3_MP_TXN<9>")
	)
	(segment
		(start 141.662404 -94.819216)
		(end 141.656562 -94.830138)
		(width 0.0889)
		(layer "B.Cu")
		(net "P3E_CPU1_PE3_MP_TXN<9>")
	)
	(segment
		(start 124.286264 -99.299522)
		(end 124.281438 -99.290886)
		(width 0.0889)
		(layer "B.Cu")
		(net "P3E_CPU1_PE3_MP_TXN<9>")
	)
	(segment
		(start 116.983002 -105.719372)
		(end 117.072664 -105.584752)
		(width 0.1143)
		(layer "B.Cu")
		(net "P3E_CPU1_PE3_MP_TXN<9>")
	)
	(segment
		(start 124.281438 -96.319086)
		(end 124.275088 -96.308418)
		(width 0.0889)
		(layer "B.Cu")
		(net "P3E_CPU1_PE3_MP_TXN<9>")
	)
	(segment
		(start 119.336566 -105.24871)
		(end 119.672862 -105.1814)
		(width 0.1143)
		(layer "B.Cu")
		(net "P3E_CPU1_PE3_MP_TXN<9>")
	)
	(segment
		(start 124.286264 -98.308922)
		(end 124.281438 -98.300286)
		(width 0.0889)
		(layer "B.Cu")
		(net "P3E_CPU1_PE3_MP_TXN<9>")
	)
	(segment
		(start 35.503104 -111.176816)
		(end 35.876484 -111.176816)
		(width 0.1143)
		(layer "B.Cu")
		(net "P3E_CPU1_PE3_MP_TXN<9>")
	)
	(segment
		(start 132.004562 -84.342478)
		(end 132.007864 -84.336636)
		(width 0.0889)
		(layer "B.Cu")
		(net "P3E_CPU1_PE3_MP_TXN<9>")
	)
	(segment
		(start 114.07648 -106.30027)
		(end 114.166142 -106.165904)
		(width 0.1143)
		(layer "B.Cu")
		(net "P3E_CPU1_PE3_MP_TXN<9>")
	)
	(segment
		(start 53.438552 -109.447076)
		(end 83.888072 -103.359966)
		(width 0.1143)
		(layer "B.Cu")
		(net "P3E_CPU1_PE3_MP_TXN<9>")
	)
	(segment
		(start 124.286264 -96.327722)
		(end 124.281438 -96.319086)
		(width 0.0889)
		(layer "B.Cu")
		(net "P3E_CPU1_PE3_MP_TXN<9>")
	)
	(segment
		(start 140.264134 -96.614488)
		(end 140.231368 -96.614488)
		(width 0.0889)
		(layer "B.Cu")
		(net "P3E_CPU1_PE3_MP_TXN<9>")
	)
	(segment
		(start 141.611858 -87.2998)
		(end 141.616684 -87.308436)
		(width 0.0889)
		(layer "B.Cu")
		(net "P3E_CPU1_PE3_MP_TXN<9>")
	)
	(segment
		(start 124.286264 -92.365322)
		(end 124.281438 -92.356686)
		(width 0.0889)
		(layer "B.Cu")
		(net "P3E_CPU1_PE3_MP_TXN<9>")
	)
	(segment
		(start 124.281438 -93.347286)
		(end 124.275088 -93.336618)
		(width 0.0889)
		(layer "B.Cu")
		(net "P3E_CPU1_PE3_MP_TXN<9>")
	)
	(segment
		(start 140.235178 -85.527388)
		(end 140.267944 -85.527388)
		(width 0.0889)
		(layer "B.Cu")
		(net "P3E_CPU1_PE3_MP_TXN<9>")
	)
	(segment
		(start 83.888072 -103.359966)
		(end 88.513158 -104.284526)
		(width 0.1143)
		(layer "B.Cu")
		(net "P3E_CPU1_PE3_MP_TXN<9>")
	)
	(segment
		(start 141.56309 -90.086688)
		(end 141.56309 -94.038928)
		(width 0.0889)
		(layer "B.Cu")
		(net "P3E_CPU1_PE3_MP_TXN<9>")
	)
	(segment
		(start 124.286264 -91.374722)
		(end 124.281438 -91.366086)
		(width 0.0889)
		(layer "B.Cu")
		(net "P3E_CPU1_PE3_MP_TXN<9>")
	)
	(segment
		(start 118.439946 -105.428034)
		(end 118.776242 -105.360724)
		(width 0.1143)
		(layer "B.Cu")
		(net "P3E_CPU1_PE3_MP_TXN<9>")
	)
	(segment
		(start 136.801098 -83.546188)
		(end 136.833864 -83.546188)
		(width 0.0889)
		(layer "B.Cu")
		(net "P3E_CPU1_PE3_MP_TXN<9>")
	)
	(segment
		(start 141.089888 -86.022434)
		(end 141.122654 -86.022434)
		(width 0.0889)
		(layer "B.Cu")
		(net "P3E_CPU1_PE3_MP_TXN<9>")
	)
	(segment
		(start 118.30558 -105.338118)
		(end 118.439946 -105.428034)
		(width 0.1143)
		(layer "B.Cu")
		(net "P3E_CPU1_PE3_MP_TXN<9>")
	)
	(segment
		(start 141.616684 -88.299036)
		(end 141.623034 -88.309704)
		(width 0.0889)
		(layer "B.Cu")
		(net "P3E_CPU1_PE3_MP_TXN<9>")
	)
	(segment
		(start 19.06905 -100.05695)
		(end 20.921472 -100.05695)
		(width 0.1143)
		(layer "B.Cu")
		(net "P3E_CPU1_PE3_MP_TXN<9>")
	)
	(segment
		(start 117.969284 -105.405428)
		(end 118.30558 -105.338118)
		(width 0.1143)
		(layer "B.Cu")
		(net "P3E_CPU1_PE3_MP_TXN<9>")
	)
	(segment
		(start 128.205738 -86.517988)
		(end 128.238504 -86.517988)
		(width 0.0889)
		(layer "B.Cu")
		(net "P3E_CPU1_PE3_MP_TXN<9>")
	)
	(segment
		(start 25.637236 -107.09529)
		(end 27.649932 -109.107478)
		(width 0.1143)
		(layer "B.Cu")
		(net "P3E_CPU1_PE3_MP_TXN<9>")
	)
	(segment
		(start 132.501894 -84.041234)
		(end 132.53466 -84.041234)
		(width 0.0889)
		(layer "B.Cu")
		(net "P3E_CPU1_PE3_MP_TXN<9>")
	)
	(segment
		(start 119.688102 -105.16616)
		(end 119.688356 -105.16616)
		(width 0.1143)
		(layer "B.Cu")
		(net "P3E_CPU1_PE3_MP_TXN<9>")
	)
	(segment
		(start 113.17986 -106.479594)
		(end 113.269522 -106.345228)
		(width 0.1143)
		(layer "B.Cu")
		(net "P3E_CPU1_PE3_MP_TXN<9>")
	)
	(segment
		(start 139.372848 -85.031834)
		(end 139.405614 -85.031834)
		(width 0.0889)
		(layer "B.Cu")
		(net "P3E_CPU1_PE3_MP_TXN<9>")
	)
	(segment
		(start 117.072664 -105.584752)
		(end 117.408706 -105.517442)
		(width 0.1143)
		(layer "B.Cu")
		(net "P3E_CPU1_PE3_MP_TXN<9>")
	)
	(segment
		(start 105.831132 -106.473752)
		(end 109.155484 -105.809288)
		(width 0.1143)
		(layer "B.Cu")
		(net "P3E_CPU1_PE3_MP_TXN<9>")
	)
	(segment
		(start 25.195022 -105.941114)
		(end 25.637236 -106.383328)
		(width 0.1143)
		(layer "B.Cu")
		(net "P3E_CPU1_PE3_MP_TXN<9>")
	)
	(segment
		(start 123.337828 -101.221794)
		(end 123.677934 -100.881688)
		(width 0.0889)
		(layer "B.Cu")
		(net "P3E_CPU1_PE3_MP_TXN<9>")
	)
	(segment
		(start 141.656562 -95.23603)
		(end 141.662404 -95.246952)
		(width 0.0889)
		(layer "B.Cu")
		(net "P3E_CPU1_PE3_MP_TXN<9>")
	)
	(segment
		(start 117.879622 -105.540048)
		(end 117.969284 -105.405428)
		(width 0.1143)
		(layer "B.Cu")
		(net "P3E_CPU1_PE3_MP_TXN<9>")
	)
	(segment
		(start 32.843978 -111.176816)
		(end 35.503104 -111.176816)
		(width 0.1143)
		(layer "B.Cu")
		(net "P3E_CPU1_PE3_MP_TXN<9>")
	)
	(segment
		(start 102.211378 -105.749852)
		(end 105.831132 -106.473752)
		(width 0.1143)
		(layer "B.Cu")
		(net "P3E_CPU1_PE3_MP_TXN<9>")
	)
	(segment
		(start 124.275088 -94.748604)
		(end 124.281438 -94.737936)
		(width 0.0889)
		(layer "B.Cu")
		(net "P3E_CPU1_PE3_MP_TXN<9>")
	)
	(segment
		(start 125.633988 -88.003634)
		(end 125.666754 -88.003634)
		(width 0.0889)
		(layer "B.Cu")
		(net "P3E_CPU1_PE3_MP_TXN<9>")
	)
	(segment
		(start 139.452858 -97.106486)
		(end 139.387834 -97.17151)
		(width 0.0889)
		(layer "B.Cu")
		(net "P3E_CPU1_PE3_MP_TXN<9>")
	)
	(segment
		(start 141.616684 -87.308436)
		(end 141.623034 -87.319104)
		(width 0.0889)
		(layer "B.Cu")
		(net "P3E_CPU1_PE3_MP_TXN<9>")
	)
	(segment
		(start 23.76424 -104.510078)
		(end 25.195022 -105.94086)
		(width 0.1143)
		(layer "B.Cu")
		(net "P3E_CPU1_PE3_MP_TXN<9>")
	)
	(segment
		(start 134.218934 -83.050634)
		(end 134.2517 -83.050634)
		(width 0.0889)
		(layer "B.Cu")
		(net "P3E_CPU1_PE3_MP_TXN<9>")
	)
	(segment
		(start 31.214314 -110.50143)
		(end 32.843978 -111.176816)
		(width 0.1143)
		(layer "B.Cu")
		(net "P3E_CPU1_PE3_MP_TXN<9>")
	)
	(segment
		(start 90.007948 -105.281222)
		(end 97.281746 -106.735626)
		(width 0.1143)
		(layer "B.Cu")
		(net "P3E_CPU1_PE3_MP_TXN<9>")
	)
	(segment
		(start 124.286264 -95.337122)
		(end 124.281438 -95.328486)
		(width 0.0889)
		(layer "B.Cu")
		(net "P3E_CPU1_PE3_MP_TXN<9>")
	)
	(segment
		(start 97.281746 -106.735626)
		(end 102.211378 -105.749852)
		(width 0.1143)
		(layer "B.Cu")
		(net "P3E_CPU1_PE3_MP_TXN<9>")
	)
	(segment
		(start 116.176044 -105.764076)
		(end 116.512086 -105.696766)
		(width 0.1143)
		(layer "B.Cu")
		(net "P3E_CPU1_PE3_MP_TXN<9>")
	)
	(segment
		(start 114.166142 -106.165904)
		(end 114.502438 -106.098594)
		(width 0.1143)
		(layer "B.Cu")
		(net "P3E_CPU1_PE3_MP_TXN<9>")
	)
	(segment
		(start 124.281438 -91.366086)
		(end 124.275088 -91.355418)
		(width 0.0889)
		(layer "B.Cu")
		(net "P3E_CPU1_PE3_MP_TXN<9>")
	)
	(segment
		(start 114.636804 -106.188256)
		(end 116.086128 -105.898442)
		(width 0.1143)
		(layer "B.Cu")
		(net "P3E_CPU1_PE3_MP_TXN<9>")
	)
	(segment
		(start 124.281438 -98.300286)
		(end 124.275088 -98.289618)
		(width 0.0889)
		(layer "B.Cu")
		(net "P3E_CPU1_PE3_MP_TXN<9>")
	)
	(segment
		(start 137.655808 -84.041234)
		(end 137.688574 -84.041234)
		(width 0.0889)
		(layer "B.Cu")
		(net "P3E_CPU1_PE3_MP_TXN<9>")
	)
	(segment
		(start 129.068068 -86.022434)
		(end 129.100834 -86.022434)
		(width 0.0889)
		(layer "B.Cu")
		(net "P3E_CPU1_PE3_MP_TXN<9>")
	)
	(segment
		(start 112.843564 -106.546904)
		(end 113.17986 -106.479594)
		(width 0.1143)
		(layer "B.Cu")
		(net "P3E_CPU1_PE3_MP_TXN<9>")
	)
	(segment
		(start 119.2022 -105.159048)
		(end 119.336566 -105.24871)
		(width 0.1143)
		(layer "B.Cu")
		(net "P3E_CPU1_PE3_MP_TXN<9>")
	)
	(arc
		(start 124.281438 -90.775536)
		(mid 124.334908 -90.580473)
		(end 124.286264 -90.384122)
		(width 0.0889)
		(layer "B.Cu")
		(net "P3E_CPU1_PE3_MP_TXN<9>")
	)
	(arc
		(start 141.623034 -87.319104)
		(mid 141.695832 -87.609867)
		(end 141.616684 -87.898986)
		(width 0.0889)
		(layer "B.Cu")
		(net "P3E_CPU1_PE3_MP_TXN<9>")
	)
	(arc
		(start 126.521464 -87.508588)
		(mid 126.715314 -87.452238)
		(end 126.856998 -87.308436)
		(width 0.0889)
		(layer "B.Cu")
		(net "P3E_CPU1_PE3_MP_TXN<9>")
	)
	(arc
		(start 124.281438 -95.728536)
		(mid 124.334908 -95.533473)
		(end 124.286264 -95.337122)
		(width 0.0889)
		(layer "B.Cu")
		(net "P3E_CPU1_PE3_MP_TXN<9>")
	)
	(arc
		(start 124.275088 -92.346018)
		(mid 124.20229 -92.055255)
		(end 124.281438 -91.766136)
		(width 0.0889)
		(layer "B.Cu")
		(net "P3E_CPU1_PE3_MP_TXN<9>")
	)
	(arc
		(start 124.275088 -99.280218)
		(mid 124.20229 -98.989455)
		(end 124.281438 -98.700336)
		(width 0.0889)
		(layer "B.Cu")
		(net "P3E_CPU1_PE3_MP_TXN<9>")
	)
	(arc
		(start 124.281438 -89.784936)
		(mid 124.334908 -89.589873)
		(end 124.286264 -89.393522)
		(width 0.0889)
		(layer "B.Cu")
		(net "P3E_CPU1_PE3_MP_TXN<9>")
	)
	(arc
		(start 124.281438 -97.709736)
		(mid 124.334908 -97.514673)
		(end 124.286264 -97.318322)
		(width 0.0889)
		(layer "B.Cu")
		(net "P3E_CPU1_PE3_MP_TXN<9>")
	)
	(arc
		(start 128.574038 -86.317836)
		(mid 128.782646 -86.105904)
		(end 129.068068 -86.022434)
		(width 0.0889)
		(layer "B.Cu")
		(net "P3E_CPU1_PE3_MP_TXN<9>")
	)
	(arc
		(start 141.093698 -96.118934)
		(mid 140.899848 -96.175284)
		(end 140.758164 -96.319086)
		(width 0.0889)
		(layer "B.Cu")
		(net "P3E_CPU1_PE3_MP_TXN<9>")
	)
	(arc
		(start 136.465564 -83.346036)
		(mid 136.607247 -83.48984)
		(end 136.801098 -83.546188)
		(width 0.0889)
		(layer "B.Cu")
		(net "P3E_CPU1_PE3_MP_TXN<9>")
	)
	(arc
		(start 123.949206 -100.881688)
		(mid 123.950984 -100.881565)
		(end 123.952762 -100.881434)
		(width 0.0889)
		(layer "B.Cu")
		(net "P3E_CPU1_PE3_MP_TXN<9>")
	)
	(arc
		(start 124.275088 -90.364818)
		(mid 124.20229 -90.074055)
		(end 124.281438 -89.784936)
		(width 0.0889)
		(layer "B.Cu")
		(net "P3E_CPU1_PE3_MP_TXN<9>")
	)
	(arc
		(start 131.149598 -84.831936)
		(mid 131.356602 -84.621072)
		(end 131.639818 -84.536788)
		(width 0.0889)
		(layer "B.Cu")
		(net "P3E_CPU1_PE3_MP_TXN<9>")
	)
	(arc
		(start 131.661408 -84.536788)
		(mid 131.858569 -84.484829)
		(end 132.004562 -84.342478)
		(width 0.0889)
		(layer "B.Cu")
		(net "P3E_CPU1_PE3_MP_TXN<9>")
	)
	(arc
		(start 141.623034 -88.309704)
		(mid 141.695832 -88.600467)
		(end 141.616684 -88.889586)
		(width 0.0889)
		(layer "B.Cu")
		(net "P3E_CPU1_PE3_MP_TXN<9>")
	)
	(arc
		(start 136.833864 -83.546188)
		(mid 137.117081 -83.630469)
		(end 137.324084 -83.841336)
		(width 0.0889)
		(layer "B.Cu")
		(net "P3E_CPU1_PE3_MP_TXN<9>")
	)
	(arc
		(start 134.583424 -82.850736)
		(mid 134.790211 -82.640003)
		(end 135.073136 -82.555588)
		(width 0.0889)
		(layer "B.Cu")
		(net "P3E_CPU1_PE3_MP_TXN<9>")
	)
	(arc
		(start 134.2517 -83.050634)
		(mid 134.443342 -82.993468)
		(end 134.583424 -82.850736)
		(width 0.0889)
		(layer "B.Cu")
		(net "P3E_CPU1_PE3_MP_TXN<9>")
	)
	(arc
		(start 139.041124 -84.831936)
		(mid 139.181203 -84.974672)
		(end 139.372848 -85.031834)
		(width 0.0889)
		(layer "B.Cu")
		(net "P3E_CPU1_PE3_MP_TXN<9>")
	)
	(arc
		(start 125.998478 -87.803736)
		(mid 126.205482 -87.592872)
		(end 126.488698 -87.508588)
		(width 0.0889)
		(layer "B.Cu")
		(net "P3E_CPU1_PE3_MP_TXN<9>")
	)
	(arc
		(start 128.238504 -86.517988)
		(mid 128.432354 -86.461638)
		(end 128.574038 -86.317836)
		(width 0.0889)
		(layer "B.Cu")
		(net "P3E_CPU1_PE3_MP_TXN<9>")
	)
	(arc
		(start 124.281438 -99.690936)
		(mid 124.334908 -99.495873)
		(end 124.286264 -99.299522)
		(width 0.0889)
		(layer "B.Cu")
		(net "P3E_CPU1_PE3_MP_TXN<9>")
	)
	(arc
		(start 124.275088 -97.299018)
		(mid 124.20229 -97.008255)
		(end 124.281438 -96.719136)
		(width 0.0889)
		(layer "B.Cu")
		(net "P3E_CPU1_PE3_MP_TXN<9>")
	)
	(arc
		(start 141.616684 -89.880186)
		(mid 141.575888 -89.979802)
		(end 141.56309 -90.086688)
		(width 0.0889)
		(layer "B.Cu")
		(net "P3E_CPU1_PE3_MP_TXN<9>")
	)
	(arc
		(start 125.666754 -88.003634)
		(mid 125.858396 -87.946468)
		(end 125.998478 -87.803736)
		(width 0.0889)
		(layer "B.Cu")
		(net "P3E_CPU1_PE3_MP_TXN<9>")
	)
	(arc
		(start 124.275088 -91.355418)
		(mid 124.20229 -91.064655)
		(end 124.281438 -90.775536)
		(width 0.0889)
		(layer "B.Cu")
		(net "P3E_CPU1_PE3_MP_TXN<9>")
	)
	(arc
		(start 133.724904 -83.346036)
		(mid 133.933512 -83.134104)
		(end 134.218934 -83.050634)
		(width 0.0889)
		(layer "B.Cu")
		(net "P3E_CPU1_PE3_MP_TXN<9>")
	)
	(arc
		(start 127.715518 -86.813136)
		(mid 127.922522 -86.602272)
		(end 128.205738 -86.517988)
		(width 0.0889)
		(layer "B.Cu")
		(net "P3E_CPU1_PE3_MP_TXN<9>")
	)
	(arc
		(start 137.324084 -83.841336)
		(mid 137.464163 -83.984072)
		(end 137.655808 -84.041234)
		(width 0.0889)
		(layer "B.Cu")
		(net "P3E_CPU1_PE3_MP_TXN<9>")
	)
	(arc
		(start 135.607044 -82.850736)
		(mid 135.747123 -82.993472)
		(end 135.938768 -83.050634)
		(width 0.0889)
		(layer "B.Cu")
		(net "P3E_CPU1_PE3_MP_TXN<9>")
	)
	(arc
		(start 137.688574 -84.041234)
		(mid 137.973998 -84.124701)
		(end 138.182604 -84.336636)
		(width 0.0889)
		(layer "B.Cu")
		(net "P3E_CPU1_PE3_MP_TXN<9>")
	)
	(arc
		(start 138.550904 -84.536788)
		(mid 138.834121 -84.621069)
		(end 139.041124 -84.831936)
		(width 0.0889)
		(layer "B.Cu")
		(net "P3E_CPU1_PE3_MP_TXN<9>")
	)
	(arc
		(start 141.122654 -86.022434)
		(mid 141.620905 -86.325274)
		(end 141.616684 -86.908386)
		(width 0.0889)
		(layer "B.Cu")
		(net "P3E_CPU1_PE3_MP_TXN<9>")
	)
	(arc
		(start 140.231368 -96.614488)
		(mid 140.039726 -96.671654)
		(end 139.899644 -96.814386)
		(width 0.0889)
		(layer "B.Cu")
		(net "P3E_CPU1_PE3_MP_TXN<9>")
	)
	(arc
		(start 124.281438 -98.700336)
		(mid 124.334908 -98.505273)
		(end 124.286264 -98.308922)
		(width 0.0889)
		(layer "B.Cu")
		(net "P3E_CPU1_PE3_MP_TXN<9>")
	)
	(arc
		(start 135.073136 -82.555588)
		(mid 135.095234 -82.555175)
		(end 135.117332 -82.555588)
		(width 0.0889)
		(layer "B.Cu")
		(net "P3E_CPU1_PE3_MP_TXN<9>")
	)
	(arc
		(start 130.817874 -85.031834)
		(mid 131.009516 -84.974668)
		(end 131.149598 -84.831936)
		(width 0.0889)
		(layer "B.Cu")
		(net "P3E_CPU1_PE3_MP_TXN<9>")
	)
	(arc
		(start 130.291078 -85.327236)
		(mid 130.499686 -85.115304)
		(end 130.785108 -85.031834)
		(width 0.0889)
		(layer "B.Cu")
		(net "P3E_CPU1_PE3_MP_TXN<9>")
	)
	(arc
		(start 123.952762 -100.881434)
		(mid 124.285678 -100.673982)
		(end 124.281438 -100.28174)
		(width 0.0889)
		(layer "B.Cu")
		(net "P3E_CPU1_PE3_MP_TXN<9>")
	)
	(arc
		(start 124.281438 -93.747336)
		(mid 124.334908 -93.552273)
		(end 124.286264 -93.355922)
		(width 0.0889)
		(layer "B.Cu")
		(net "P3E_CPU1_PE3_MP_TXN<9>")
	)
	(arc
		(start 139.405614 -85.031834)
		(mid 139.691038 -85.115301)
		(end 139.899644 -85.327236)
		(width 0.0889)
		(layer "B.Cu")
		(net "P3E_CPU1_PE3_MP_TXN<9>")
	)
	(arc
		(start 141.616684 -87.898986)
		(mid 141.563214 -88.094049)
		(end 141.611858 -88.2904)
		(width 0.0889)
		(layer "B.Cu")
		(net "P3E_CPU1_PE3_MP_TXN<9>")
	)
	(arc
		(start 126.856998 -87.308436)
		(mid 127.065606 -87.096504)
		(end 127.351028 -87.013034)
		(width 0.0889)
		(layer "B.Cu")
		(net "P3E_CPU1_PE3_MP_TXN<9>")
	)
	(arc
		(start 141.662404 -95.246952)
		(mid 141.683465 -95.763493)
		(end 141.308074 -96.118934)
		(width 0.0889)
		(layer "B.Cu")
		(net "P3E_CPU1_PE3_MP_TXN<9>")
	)
	(arc
		(start 139.899644 -85.327236)
		(mid 140.041327 -85.47104)
		(end 140.235178 -85.527388)
		(width 0.0889)
		(layer "B.Cu")
		(net "P3E_CPU1_PE3_MP_TXN<9>")
	)
	(arc
		(start 129.955544 -85.527388)
		(mid 130.149394 -85.471038)
		(end 130.291078 -85.327236)
		(width 0.0889)
		(layer "B.Cu")
		(net "P3E_CPU1_PE3_MP_TXN<9>")
	)
	(arc
		(start 127.383794 -87.013034)
		(mid 127.575436 -86.955868)
		(end 127.715518 -86.813136)
		(width 0.0889)
		(layer "B.Cu")
		(net "P3E_CPU1_PE3_MP_TXN<9>")
	)
	(arc
		(start 124.281438 -92.756736)
		(mid 124.334908 -92.561673)
		(end 124.286264 -92.365322)
		(width 0.0889)
		(layer "B.Cu")
		(net "P3E_CPU1_PE3_MP_TXN<9>")
	)
	(arc
		(start 141.616684 -88.889586)
		(mid 141.563214 -89.084649)
		(end 141.611858 -89.281)
		(width 0.0889)
		(layer "B.Cu")
		(net "P3E_CPU1_PE3_MP_TXN<9>")
	)
	(arc
		(start 141.656562 -94.830138)
		(mid 141.606149 -95.033084)
		(end 141.656562 -95.23603)
		(width 0.0889)
		(layer "B.Cu")
		(net "P3E_CPU1_PE3_MP_TXN<9>")
	)
	(arc
		(start 132.866384 -83.841336)
		(mid 133.073388 -83.630472)
		(end 133.356604 -83.546188)
		(width 0.0889)
		(layer "B.Cu")
		(net "P3E_CPU1_PE3_MP_TXN<9>")
	)
	(arc
		(start 124.275088 -93.336618)
		(mid 124.20229 -93.045855)
		(end 124.281438 -92.756736)
		(width 0.0889)
		(layer "B.Cu")
		(net "P3E_CPU1_PE3_MP_TXN<9>")
	)
	(arc
		(start 139.899644 -96.814386)
		(mid 139.711116 -97.013759)
		(end 139.452858 -97.106486)
		(width 0.0889)
		(layer "B.Cu")
		(net "P3E_CPU1_PE3_MP_TXN<9>")
	)
	(arc
		(start 140.758164 -85.822536)
		(mid 140.898243 -85.965272)
		(end 141.089888 -86.022434)
		(width 0.0889)
		(layer "B.Cu")
		(net "P3E_CPU1_PE3_MP_TXN<9>")
	)
	(arc
		(start 129.432558 -85.822536)
		(mid 129.639562 -85.611672)
		(end 129.922778 -85.527388)
		(width 0.0889)
		(layer "B.Cu")
		(net "P3E_CPU1_PE3_MP_TXN<9>")
	)
	(arc
		(start 124.281438 -95.328486)
		(mid 124.202216 -95.039368)
		(end 124.275088 -94.748604)
		(width 0.0889)
		(layer "B.Cu")
		(net "P3E_CPU1_PE3_MP_TXN<9>")
	)
	(arc
		(start 124.804424 -88.499188)
		(mid 124.998274 -88.442838)
		(end 125.139958 -88.299036)
		(width 0.0889)
		(layer "B.Cu")
		(net "P3E_CPU1_PE3_MP_TXN<9>")
	)
	(arc
		(start 129.100834 -86.022434)
		(mid 129.292476 -85.965268)
		(end 129.432558 -85.822536)
		(width 0.0889)
		(layer "B.Cu")
		(net "P3E_CPU1_PE3_MP_TXN<9>")
	)
	(arc
		(start 133.38937 -83.546188)
		(mid 133.58322 -83.489838)
		(end 133.724904 -83.346036)
		(width 0.0889)
		(layer "B.Cu")
		(net "P3E_CPU1_PE3_MP_TXN<9>")
	)
	(arc
		(start 124.275088 -89.374218)
		(mid 124.279119 -88.798036)
		(end 124.771658 -88.499188)
		(width 0.0889)
		(layer "B.Cu")
		(net "P3E_CPU1_PE3_MP_TXN<9>")
	)
	(arc
		(start 124.281438 -91.766136)
		(mid 124.334908 -91.571073)
		(end 124.286264 -91.374722)
		(width 0.0889)
		(layer "B.Cu")
		(net "P3E_CPU1_PE3_MP_TXN<9>")
	)
	(arc
		(start 138.182604 -84.336636)
		(mid 138.324287 -84.48044)
		(end 138.518138 -84.536788)
		(width 0.0889)
		(layer "B.Cu")
		(net "P3E_CPU1_PE3_MP_TXN<9>")
	)
	(arc
		(start 124.275088 -98.289618)
		(mid 124.20229 -97.998855)
		(end 124.281438 -97.709736)
		(width 0.0889)
		(layer "B.Cu")
		(net "P3E_CPU1_PE3_MP_TXN<9>")
	)
	(arc
		(start 141.616684 -86.908386)
		(mid 141.563214 -87.103449)
		(end 141.611858 -87.2998)
		(width 0.0889)
		(layer "B.Cu")
		(net "P3E_CPU1_PE3_MP_TXN<9>")
	)
	(arc
		(start 135.117332 -82.555588)
		(mid 135.400268 -82.639984)
		(end 135.607044 -82.850736)
		(width 0.0889)
		(layer "B.Cu")
		(net "P3E_CPU1_PE3_MP_TXN<9>")
	)
	(arc
		(start 124.281438 -94.737936)
		(mid 124.334937 -94.538038)
		(end 124.281438 -94.33814)
		(width 0.0889)
		(layer "B.Cu")
		(net "P3E_CPU1_PE3_MP_TXN<9>")
	)
	(arc
		(start 124.281438 -94.33814)
		(mid 124.202307 -94.042738)
		(end 124.281438 -93.747336)
		(width 0.0889)
		(layer "B.Cu")
		(net "P3E_CPU1_PE3_MP_TXN<9>")
	)
	(arc
		(start 124.275088 -96.308418)
		(mid 124.20229 -96.017655)
		(end 124.281438 -95.728536)
		(width 0.0889)
		(layer "B.Cu")
		(net "P3E_CPU1_PE3_MP_TXN<9>")
	)
	(arc
		(start 140.758164 -96.319086)
		(mid 140.549556 -96.531018)
		(end 140.264134 -96.614488)
		(width 0.0889)
		(layer "B.Cu")
		(net "P3E_CPU1_PE3_MP_TXN<9>")
	)
	(arc
		(start 135.971534 -83.050634)
		(mid 136.256958 -83.134101)
		(end 136.465564 -83.346036)
		(width 0.0889)
		(layer "B.Cu")
		(net "P3E_CPU1_PE3_MP_TXN<9>")
	)
	(arc
		(start 141.656562 -94.245684)
		(mid 141.729206 -94.531733)
		(end 141.662404 -94.819216)
		(width 0.0889)
		(layer "B.Cu")
		(net "P3E_CPU1_PE3_MP_TXN<9>")
	)
	(arc
		(start 125.139958 -88.299036)
		(mid 125.348566 -88.087104)
		(end 125.633988 -88.003634)
		(width 0.0889)
		(layer "B.Cu")
		(net "P3E_CPU1_PE3_MP_TXN<9>")
	)
	(arc
		(start 124.281438 -100.28174)
		(mid 124.202307 -99.986338)
		(end 124.281438 -99.690936)
		(width 0.0889)
		(layer "B.Cu")
		(net "P3E_CPU1_PE3_MP_TXN<9>")
	)
	(arc
		(start 132.53466 -84.041234)
		(mid 132.726302 -83.984068)
		(end 132.866384 -83.841336)
		(width 0.0889)
		(layer "B.Cu")
		(net "P3E_CPU1_PE3_MP_TXN<9>")
	)
	(arc
		(start 140.267944 -85.527388)
		(mid 140.551161 -85.611669)
		(end 140.758164 -85.822536)
		(width 0.0889)
		(layer "B.Cu")
		(net "P3E_CPU1_PE3_MP_TXN<9>")
	)
	(arc
		(start 124.281438 -96.719136)
		(mid 124.334908 -96.524073)
		(end 124.286264 -96.327722)
		(width 0.0889)
		(layer "B.Cu")
		(net "P3E_CPU1_PE3_MP_TXN<9>")
	)
	(arc
		(start 132.007864 -84.336636)
		(mid 132.216472 -84.124704)
		(end 132.501894 -84.041234)
		(width 0.0889)
		(layer "B.Cu")
		(net "P3E_CPU1_PE3_MP_TXN<9>")
	)
	(arc
		(start 141.616684 -89.289636)
		(mid 141.695815 -89.585038)
		(end 141.616684 -89.88044)
		(width 0.0889)
		(layer "B.Cu")
		(net "P3E_CPU1_PE3_MP_TXN<9>")
	)
	(segment
		(start 137.670794 -96.518984)
		(end 137.099294 -96.518984)
		(width 0.1143)
		(layer "F.Cu")
		(net "P3E_CPU1_PE3_MP_TXN<8>")
	)
	(via
		(at 137.670794 -96.518984)
		(size 0.508)
		(drill 0.254)
		(layers "F.Cu" "B.Cu")
		(net "P3E_CPU1_PE3_MP_TXN<8>")
	)
	(via
		(at 21.468588 -99.054158)
		(size 0.508)
		(drill 0.254)
		(layers "F.Cu" "B.Cu")
		(net "P3E_CPU1_PE3_MP_TXN<8>")
	)
	(segment
		(start 129.100834 -85.031834)
		(end 129.068068 -85.031834)
		(width 0.0889)
		(layer "B.Cu")
		(net "P3E_CPU1_PE3_MP_TXN<8>")
	)
	(segment
		(start 141.093698 -97.109534)
		(end 141.308074 -97.109534)
		(width 0.0889)
		(layer "B.Cu")
		(net "P3E_CPU1_PE3_MP_TXN<8>")
	)
	(segment
		(start 116.557298 -104.634538)
		(end 116.42344 -104.544114)
		(width 0.1143)
		(layer "B.Cu")
		(net "P3E_CPU1_PE3_MP_TXN<8>")
	)
	(segment
		(start 123.422918 -93.252036)
		(end 123.416568 -93.262704)
		(width 0.0889)
		(layer "B.Cu")
		(net "P3E_CPU1_PE3_MP_TXN<8>")
	)
	(segment
		(start 115.996466 -104.743504)
		(end 115.659662 -104.808782)
		(width 0.1143)
		(layer "B.Cu")
		(net "P3E_CPU1_PE3_MP_TXN<8>")
	)
	(segment
		(start 134.24789 -82.060034)
		(end 134.215124 -82.060034)
		(width 0.0889)
		(layer "B.Cu")
		(net "P3E_CPU1_PE3_MP_TXN<8>")
	)
	(segment
		(start 123.427744 -92.2528)
		(end 123.422918 -92.261436)
		(width 0.0889)
		(layer "B.Cu")
		(net "P3E_CPU1_PE3_MP_TXN<8>")
	)
	(segment
		(start 106.524044 -105.233978)
		(end 106.389678 -105.144316)
		(width 0.1143)
		(layer "B.Cu")
		(net "P3E_CPU1_PE3_MP_TXN<8>")
	)
	(segment
		(start 97.862898 -105.567226)
		(end 97.209102 -105.698036)
		(width 0.1143)
		(layer "B.Cu")
		(net "P3E_CPU1_PE3_MP_TXN<8>")
	)
	(segment
		(start 132.007864 -83.346036)
		(end 132.004562 -83.351878)
		(width 0.0889)
		(layer "B.Cu")
		(net "P3E_CPU1_PE3_MP_TXN<8>")
	)
	(segment
		(start 98.84918 -105.253536)
		(end 98.759518 -105.387902)
		(width 0.1143)
		(layer "B.Cu")
		(net "P3E_CPU1_PE3_MP_TXN<8>")
	)
	(segment
		(start 110.715044 -104.981248)
		(end 110.379002 -104.913938)
		(width 0.1143)
		(layer "B.Cu")
		(net "P3E_CPU1_PE3_MP_TXN<8>")
	)
	(segment
		(start 33.111186 -110.210854)
		(end 31.723584 -109.635798)
		(width 0.1143)
		(layer "B.Cu")
		(net "P3E_CPU1_PE3_MP_TXN<8>")
	)
	(segment
		(start 98.423222 -105.455212)
		(end 98.288856 -105.36555)
		(width 0.1143)
		(layer "B.Cu")
		(net "P3E_CPU1_PE3_MP_TXN<8>")
	)
	(segment
		(start 23.356316 -100.941886)
		(end 21.468588 -99.054158)
		(width 0.1143)
		(layer "B.Cu")
		(net "P3E_CPU1_PE3_MP_TXN<8>")
	)
	(segment
		(start 142.481554 -88.805258)
		(end 142.475204 -88.79459)
		(width 0.0889)
		(layer "B.Cu")
		(net "P3E_CPU1_PE3_MP_TXN<8>")
	)
	(segment
		(start 127.383794 -86.022434)
		(end 127.351028 -86.022434)
		(width 0.0889)
		(layer "B.Cu")
		(net "P3E_CPU1_PE3_MP_TXN<8>")
	)
	(segment
		(start 115.659662 -104.808782)
		(end 115.525804 -104.718358)
		(width 0.1143)
		(layer "B.Cu")
		(net "P3E_CPU1_PE3_MP_TXN<8>")
	)
	(segment
		(start 123.422918 -92.261436)
		(end 123.416568 -92.272104)
		(width 0.0889)
		(layer "B.Cu")
		(net "P3E_CPU1_PE3_MP_TXN<8>")
	)
	(segment
		(start 123.422918 -96.223836)
		(end 123.416568 -96.234504)
		(width 0.0889)
		(layer "B.Cu")
		(net "P3E_CPU1_PE3_MP_TXN<8>")
	)
	(segment
		(start 123.427744 -98.1964)
		(end 123.422918 -98.205036)
		(width 0.0889)
		(layer "B.Cu")
		(net "P3E_CPU1_PE3_MP_TXN<8>")
	)
	(segment
		(start 142.475204 -87.403686)
		(end 142.481554 -87.393018)
		(width 0.0889)
		(layer "B.Cu")
		(net "P3E_CPU1_PE3_MP_TXN<8>")
	)
	(segment
		(start 140.231368 -97.605088)
		(end 140.264134 -97.605088)
		(width 0.0889)
		(layer "B.Cu")
		(net "P3E_CPU1_PE3_MP_TXN<8>")
	)
	(segment
		(start 136.825228 -82.555334)
		(end 136.801098 -82.555334)
		(width 0.0889)
		(layer "B.Cu")
		(net "P3E_CPU1_PE3_MP_TXN<8>")
	)
	(segment
		(start 14.753336 -97.441258)
		(end 14.324838 -97.441258)
		(width 0.1143)
		(layer "B.Cu")
		(net "P3E_CPU1_PE3_MP_TXN<8>")
	)
	(segment
		(start 90.57894 -104.372156)
		(end 89.028016 -103.338376)
		(width 0.1143)
		(layer "B.Cu")
		(net "P3E_CPU1_PE3_MP_TXN<8>")
	)
	(segment
		(start 89.028016 -103.338376)
		(end 83.99145 -102.331266)
		(width 0.1143)
		(layer "B.Cu")
		(net "P3E_CPU1_PE3_MP_TXN<8>")
	)
	(segment
		(start 103.834438 -104.938068)
		(end 103.498142 -104.870758)
		(width 0.1143)
		(layer "B.Cu")
		(net "P3E_CPU1_PE3_MP_TXN<8>")
	)
	(segment
		(start 103.9241 -105.072434)
		(end 103.834438 -104.938068)
		(width 0.1143)
		(layer "B.Cu")
		(net "P3E_CPU1_PE3_MP_TXN<8>")
	)
	(segment
		(start 115.525804 -104.718358)
		(end 115.189 -104.78389)
		(width 0.1143)
		(layer "B.Cu")
		(net "P3E_CPU1_PE3_MP_TXN<8>")
	)
	(segment
		(start 142.6337 -90.051382)
		(end 142.47495 -89.776808)
		(width 0.0889)
		(layer "B.Cu")
		(net "P3E_CPU1_PE3_MP_TXN<8>")
	)
	(segment
		(start 142.470378 -86.421722)
		(end 142.475204 -86.413086)
		(width 0.0889)
		(layer "B.Cu")
		(net "P3E_CPU1_PE3_MP_TXN<8>")
	)
	(segment
		(start 142.387066 -96.604074)
		(end 142.6337 -96.35744)
		(width 0.0889)
		(layer "B.Cu")
		(net "P3E_CPU1_PE3_MP_TXN<8>")
	)
	(segment
		(start 20.73783 -98.3234)
		(end 16.857218 -98.3234)
		(width 0.1143)
		(layer "B.Cu")
		(net "P3E_CPU1_PE3_MP_TXN<8>")
	)
	(segment
		(start 117.321076 -104.36987)
		(end 116.984526 -104.435402)
		(width 0.1143)
		(layer "B.Cu")
		(net "P3E_CPU1_PE3_MP_TXN<8>")
	)
	(segment
		(start 108.95965 -104.746806)
		(end 107.420664 -105.054654)
		(width 0.1143)
		(layer "B.Cu")
		(net "P3E_CPU1_PE3_MP_TXN<8>")
	)
	(segment
		(start 123.422918 -91.270836)
		(end 123.416568 -91.281504)
		(width 0.0889)
		(layer "B.Cu")
		(net "P3E_CPU1_PE3_MP_TXN<8>")
	)
	(segment
		(start 117.454934 -104.460294)
		(end 117.321076 -104.36987)
		(width 0.1143)
		(layer "B.Cu")
		(net "P3E_CPU1_PE3_MP_TXN<8>")
	)
	(segment
		(start 125.666754 -87.013034)
		(end 125.633988 -87.013034)
		(width 0.0889)
		(layer "B.Cu")
		(net "P3E_CPU1_PE3_MP_TXN<8>")
	)
	(segment
		(start 102.601522 -104.691434)
		(end 102.467156 -104.781096)
		(width 0.1143)
		(layer "B.Cu")
		(net "P3E_CPU1_PE3_MP_TXN<8>")
	)
	(segment
		(start 103.498142 -104.870758)
		(end 103.363776 -104.96042)
		(width 0.1143)
		(layer "B.Cu")
		(net "P3E_CPU1_PE3_MP_TXN<8>")
	)
	(segment
		(start 132.53466 -83.050634)
		(end 132.501894 -83.050634)
		(width 0.0889)
		(layer "B.Cu")
		(net "P3E_CPU1_PE3_MP_TXN<8>")
	)
	(segment
		(start 34.699702 -110.210854)
		(end 33.111186 -110.210854)
		(width 0.1143)
		(layer "B.Cu")
		(net "P3E_CPU1_PE3_MP_TXN<8>")
	)
	(segment
		(start 105.96372 -105.345992)
		(end 105.627424 -105.413302)
		(width 0.1143)
		(layer "B.Cu")
		(net "P3E_CPU1_PE3_MP_TXN<8>")
	)
	(segment
		(start 139.405614 -84.041234)
		(end 139.372848 -84.041234)
		(width 0.0889)
		(layer "B.Cu")
		(net "P3E_CPU1_PE3_MP_TXN<8>")
	)
	(segment
		(start 115.189 -104.78389)
		(end 115.098576 -104.917748)
		(width 0.1143)
		(layer "B.Cu")
		(net "P3E_CPU1_PE3_MP_TXN<8>")
	)
	(segment
		(start 138.550904 -83.546188)
		(end 138.518138 -83.546188)
		(width 0.0889)
		(layer "B.Cu")
		(net "P3E_CPU1_PE3_MP_TXN<8>")
	)
	(segment
		(start 119.478806 -104.04856)
		(end 118.811548 -104.223058)
		(width 0.0889)
		(layer "B.Cu")
		(net "P3E_CPU1_PE3_MP_TXN<8>")
	)
	(segment
		(start 142.475204 -86.413086)
		(end 142.481554 -86.402418)
		(width 0.0889)
		(layer "B.Cu")
		(net "P3E_CPU1_PE3_MP_TXN<8>")
	)
	(segment
		(start 97.209102 -105.698036)
		(end 90.57894 -104.372156)
		(width 0.1143)
		(layer "B.Cu")
		(net "P3E_CPU1_PE3_MP_TXN<8>")
	)
	(segment
		(start 123.427744 -90.2716)
		(end 123.422918 -90.280236)
		(width 0.0889)
		(layer "B.Cu")
		(net "P3E_CPU1_PE3_MP_TXN<8>")
	)
	(segment
		(start 118.811548 -104.223058)
		(end 118.630446 -104.25811)
		(width 0.0889)
		(layer "B.Cu")
		(net "P3E_CPU1_PE3_MP_TXN<8>")
	)
	(segment
		(start 103.363776 -104.96042)
		(end 103.02748 -104.89311)
		(width 0.1143)
		(layer "B.Cu")
		(net "P3E_CPU1_PE3_MP_TXN<8>")
	)
	(segment
		(start 118.601236 -104.238044)
		(end 118.579646 -104.242108)
		(width 0.0889)
		(layer "B.Cu")
		(net "P3E_CPU1_PE3_MP_TXN<8>")
	)
	(segment
		(start 114.20094 -105.091992)
		(end 112.41786 -105.438194)
		(width 0.1143)
		(layer "B.Cu")
		(net "P3E_CPU1_PE3_MP_TXN<8>")
	)
	(segment
		(start 114.291364 -104.958134)
		(end 114.20094 -105.091992)
		(width 0.1143)
		(layer "B.Cu")
		(net "P3E_CPU1_PE3_MP_TXN<8>")
	)
	(segment
		(start 142.470378 -87.412322)
		(end 142.475204 -87.403686)
		(width 0.0889)
		(layer "B.Cu")
		(net "P3E_CPU1_PE3_MP_TXN<8>")
	)
	(segment
		(start 106.389678 -105.144316)
		(end 106.053382 -105.211626)
		(width 0.1143)
		(layer "B.Cu")
		(net "P3E_CPU1_PE3_MP_TXN<8>")
	)
	(segment
		(start 131.661408 -83.546188)
		(end 131.639818 -83.546188)
		(width 0.0889)
		(layer "B.Cu")
		(net "P3E_CPU1_PE3_MP_TXN<8>")
	)
	(segment
		(start 21.468588 -99.054158)
		(end 20.73783 -98.3234)
		(width 0.1143)
		(layer "B.Cu")
		(net "P3E_CPU1_PE3_MP_TXN<8>")
	)
	(segment
		(start 102.937818 -104.758744)
		(end 102.601522 -104.691434)
		(width 0.1143)
		(layer "B.Cu")
		(net "P3E_CPU1_PE3_MP_TXN<8>")
	)
	(segment
		(start 116.984526 -104.435402)
		(end 116.894102 -104.56926)
		(width 0.1143)
		(layer "B.Cu")
		(net "P3E_CPU1_PE3_MP_TXN<8>")
	)
	(segment
		(start 123.36145 -100.293424)
		(end 123.117102 -100.549964)
		(width 0.0889)
		(layer "B.Cu")
		(net "P3E_CPU1_PE3_MP_TXN<8>")
	)
	(segment
		(start 24.616918 -103.986076)
		(end 23.356316 -100.941886)
		(width 0.1143)
		(layer "B.Cu")
		(net "P3E_CPU1_PE3_MP_TXN<8>")
	)
	(segment
		(start 129.955544 -84.536788)
		(end 129.922778 -84.536788)
		(width 0.0889)
		(layer "B.Cu")
		(net "P3E_CPU1_PE3_MP_TXN<8>")
	)
	(segment
		(start 142.6337 -96.35744)
		(end 142.6337 -90.051382)
		(width 0.0889)
		(layer "B.Cu")
		(net "P3E_CPU1_PE3_MP_TXN<8>")
	)
	(segment
		(start 118.630446 -104.25811)
		(end 118.601236 -104.238044)
		(width 0.0889)
		(layer "B.Cu")
		(net "P3E_CPU1_PE3_MP_TXN<8>")
	)
	(segment
		(start 107.286298 -104.964992)
		(end 106.950002 -105.032302)
		(width 0.1143)
		(layer "B.Cu")
		(net "P3E_CPU1_PE3_MP_TXN<8>")
	)
	(segment
		(start 123.422918 -97.214436)
		(end 123.416568 -97.225104)
		(width 0.0889)
		(layer "B.Cu")
		(net "P3E_CPU1_PE3_MP_TXN<8>")
	)
	(segment
		(start 123.117102 -100.549964)
		(end 122.775218 -100.752148)
		(width 0.0889)
		(layer "B.Cu")
		(net "P3E_CPU1_PE3_MP_TXN<8>")
	)
	(segment
		(start 123.422918 -98.205036)
		(end 123.416568 -98.215704)
		(width 0.0889)
		(layer "B.Cu")
		(net "P3E_CPU1_PE3_MP_TXN<8>")
	)
	(segment
		(start 105.627424 -105.413302)
		(end 103.9241 -105.072434)
		(width 0.1143)
		(layer "B.Cu")
		(net "P3E_CPU1_PE3_MP_TXN<8>")
	)
	(segment
		(start 118.579646 -104.242108)
		(end 117.454934 -104.460294)
		(width 0.1143)
		(layer "B.Cu")
		(net "P3E_CPU1_PE3_MP_TXN<8>")
	)
	(segment
		(start 128.238504 -85.527388)
		(end 128.205738 -85.527388)
		(width 0.0889)
		(layer "B.Cu")
		(net "P3E_CPU1_PE3_MP_TXN<8>")
	)
	(segment
		(start 16.857218 -98.3234)
		(end 14.771624 -97.459546)
		(width 0.1143)
		(layer "B.Cu")
		(net "P3E_CPU1_PE3_MP_TXN<8>")
	)
	(segment
		(start 99.185476 -105.186226)
		(end 98.84918 -105.253536)
		(width 0.1143)
		(layer "B.Cu")
		(net "P3E_CPU1_PE3_MP_TXN<8>")
	)
	(segment
		(start 137.670794 -96.518984)
		(end 137.96391 -96.688148)
		(width 0.0889)
		(layer "B.Cu")
		(net "P3E_CPU1_PE3_MP_TXN<8>")
	)
	(segment
		(start 123.427744 -99.187)
		(end 123.422918 -99.195636)
		(width 0.0889)
		(layer "B.Cu")
		(net "P3E_CPU1_PE3_MP_TXN<8>")
	)
	(segment
		(start 31.723584 -109.635798)
		(end 30.87751 -108.789978)
		(width 0.1143)
		(layer "B.Cu")
		(net "P3E_CPU1_PE3_MP_TXN<8>")
	)
	(segment
		(start 123.427744 -100.1776)
		(end 123.36145 -100.293424)
		(width 0.0889)
		(layer "B.Cu")
		(net "P3E_CPU1_PE3_MP_TXN<8>")
	)
	(segment
		(start 102.467156 -104.781096)
		(end 102.13086 -104.713786)
		(width 0.1143)
		(layer "B.Cu")
		(net "P3E_CPU1_PE3_MP_TXN<8>")
	)
	(segment
		(start 142.00124 -96.604074)
		(end 142.387066 -96.604074)
		(width 0.0889)
		(layer "B.Cu")
		(net "P3E_CPU1_PE3_MP_TXN<8>")
	)
	(segment
		(start 123.949714 -88.003634)
		(end 123.916948 -88.003634)
		(width 0.0889)
		(layer "B.Cu")
		(net "P3E_CPU1_PE3_MP_TXN<8>")
	)
	(segment
		(start 123.427744 -91.2622)
		(end 123.422918 -91.270836)
		(width 0.0889)
		(layer "B.Cu")
		(net "P3E_CPU1_PE3_MP_TXN<8>")
	)
	(segment
		(start 111.141002 -105.182924)
		(end 110.804706 -105.115614)
		(width 0.1143)
		(layer "B.Cu")
		(net "P3E_CPU1_PE3_MP_TXN<8>")
	)
	(segment
		(start 123.427744 -96.2152)
		(end 123.422918 -96.223836)
		(width 0.0889)
		(layer "B.Cu")
		(net "P3E_CPU1_PE3_MP_TXN<8>")
	)
	(segment
		(start 138.511534 -97.605088)
		(end 138.5443 -97.605088)
		(width 0.0889)
		(layer "B.Cu")
		(net "P3E_CPU1_PE3_MP_TXN<8>")
	)
	(segment
		(start 69.046344 -105.318306)
		(end 54.159912 -108.293916)
		(width 0.1143)
		(layer "B.Cu")
		(net "P3E_CPU1_PE3_MP_TXN<8>")
	)
	(segment
		(start 103.02748 -104.89311)
		(end 102.937818 -104.758744)
		(width 0.1143)
		(layer "B.Cu")
		(net "P3E_CPU1_PE3_MP_TXN<8>")
	)
	(segment
		(start 141.984984 -85.527388)
		(end 141.952218 -85.527388)
		(width 0.0889)
		(layer "B.Cu")
		(net "P3E_CPU1_PE3_MP_TXN<8>")
	)
	(segment
		(start 116.42344 -104.544114)
		(end 116.08689 -104.609646)
		(width 0.1143)
		(layer "B.Cu")
		(net "P3E_CPU1_PE3_MP_TXN<8>")
	)
	(segment
		(start 114.762026 -104.983026)
		(end 114.628168 -104.892602)
		(width 0.1143)
		(layer "B.Cu")
		(net "P3E_CPU1_PE3_MP_TXN<8>")
	)
	(segment
		(start 110.244382 -105.0036)
		(end 108.95965 -104.746806)
		(width 0.1143)
		(layer "B.Cu")
		(net "P3E_CPU1_PE3_MP_TXN<8>")
	)
	(segment
		(start 106.86034 -105.166668)
		(end 106.524044 -105.233978)
		(width 0.1143)
		(layer "B.Cu")
		(net "P3E_CPU1_PE3_MP_TXN<8>")
	)
	(segment
		(start 139.366244 -98.100134)
		(end 139.409424 -98.100134)
		(width 0.0889)
		(layer "B.Cu")
		(net "P3E_CPU1_PE3_MP_TXN<8>")
	)
	(segment
		(start 122.775218 -100.752148)
		(end 119.478806 -104.04856)
		(width 0.0889)
		(layer "B.Cu")
		(net "P3E_CPU1_PE3_MP_TXN<8>")
	)
	(segment
		(start 107.420664 -105.054654)
		(end 107.286298 -104.964992)
		(width 0.1143)
		(layer "B.Cu")
		(net "P3E_CPU1_PE3_MP_TXN<8>")
	)
	(segment
		(start 106.053382 -105.211626)
		(end 105.96372 -105.345992)
		(width 0.1143)
		(layer "B.Cu")
		(net "P3E_CPU1_PE3_MP_TXN<8>")
	)
	(segment
		(start 102.13086 -104.713786)
		(end 99.319842 -105.275888)
		(width 0.1143)
		(layer "B.Cu")
		(net "P3E_CPU1_PE3_MP_TXN<8>")
	)
	(segment
		(start 123.427744 -97.2058)
		(end 123.422918 -97.214436)
		(width 0.0889)
		(layer "B.Cu")
		(net "P3E_CPU1_PE3_MP_TXN<8>")
	)
	(segment
		(start 110.804706 -105.115614)
		(end 110.715044 -104.981248)
		(width 0.1143)
		(layer "B.Cu")
		(net "P3E_CPU1_PE3_MP_TXN<8>")
	)
	(segment
		(start 123.427744 -93.2434)
		(end 123.422918 -93.252036)
		(width 0.0889)
		(layer "B.Cu")
		(net "P3E_CPU1_PE3_MP_TXN<8>")
	)
	(segment
		(start 116.08689 -104.609646)
		(end 115.996466 -104.743504)
		(width 0.1143)
		(layer "B.Cu")
		(net "P3E_CPU1_PE3_MP_TXN<8>")
	)
	(segment
		(start 123.427744 -89.281)
		(end 123.422918 -89.289636)
		(width 0.0889)
		(layer "B.Cu")
		(net "P3E_CPU1_PE3_MP_TXN<8>")
	)
	(segment
		(start 115.098576 -104.917748)
		(end 114.762026 -104.983026)
		(width 0.1143)
		(layer "B.Cu")
		(net "P3E_CPU1_PE3_MP_TXN<8>")
	)
	(segment
		(start 110.379002 -104.913938)
		(end 110.244382 -105.0036)
		(width 0.1143)
		(layer "B.Cu")
		(net "P3E_CPU1_PE3_MP_TXN<8>")
	)
	(segment
		(start 98.288856 -105.36555)
		(end 97.95256 -105.432606)
		(width 0.1143)
		(layer "B.Cu")
		(net "P3E_CPU1_PE3_MP_TXN<8>")
	)
	(segment
		(start 116.894102 -104.56926)
		(end 116.557298 -104.634538)
		(width 0.1143)
		(layer "B.Cu")
		(net "P3E_CPU1_PE3_MP_TXN<8>")
	)
	(segment
		(start 137.96391 -96.688148)
		(end 137.987786 -96.777556)
		(width 0.0889)
		(layer "B.Cu")
		(net "P3E_CPU1_PE3_MP_TXN<8>")
	)
	(segment
		(start 97.95256 -105.432606)
		(end 97.862898 -105.567226)
		(width 0.1143)
		(layer "B.Cu")
		(net "P3E_CPU1_PE3_MP_TXN<8>")
	)
	(segment
		(start 123.422918 -90.280236)
		(end 123.416568 -90.290904)
		(width 0.0889)
		(layer "B.Cu")
		(net "P3E_CPU1_PE3_MP_TXN<8>")
	)
	(segment
		(start 98.759518 -105.387902)
		(end 98.423222 -105.455212)
		(width 0.1143)
		(layer "B.Cu")
		(net "P3E_CPU1_PE3_MP_TXN<8>")
	)
	(segment
		(start 111.275622 -105.093262)
		(end 111.141002 -105.182924)
		(width 0.1143)
		(layer "B.Cu")
		(net "P3E_CPU1_PE3_MP_TXN<8>")
	)
	(segment
		(start 126.521464 -86.517988)
		(end 126.488698 -86.517988)
		(width 0.0889)
		(layer "B.Cu")
		(net "P3E_CPU1_PE3_MP_TXN<8>")
	)
	(segment
		(start 99.319842 -105.275888)
		(end 99.185476 -105.186226)
		(width 0.1143)
		(layer "B.Cu")
		(net "P3E_CPU1_PE3_MP_TXN<8>")
	)
	(segment
		(start 123.416568 -94.822518)
		(end 123.422918 -94.833186)
		(width 0.0889)
		(layer "B.Cu")
		(net "P3E_CPU1_PE3_MP_TXN<8>")
	)
	(segment
		(start 14.324838 -97.441258)
		(end 13.99794 -97.11436)
		(width 0.1143)
		(layer "B.Cu")
		(net "P3E_CPU1_PE3_MP_TXN<8>")
	)
	(segment
		(start 26.608532 -105.97769)
		(end 24.616918 -103.986076)
		(width 0.1143)
		(layer "B.Cu")
		(net "P3E_CPU1_PE3_MP_TXN<8>")
	)
	(segment
		(start 142.475204 -88.79459)
		(end 142.470378 -88.785954)
		(width 0.0889)
		(layer "B.Cu")
		(net "P3E_CPU1_PE3_MP_TXN<8>")
	)
	(segment
		(start 141.122654 -85.031834)
		(end 141.089888 -85.031834)
		(width 0.0889)
		(layer "B.Cu")
		(net "P3E_CPU1_PE3_MP_TXN<8>")
	)
	(segment
		(start 114.628168 -104.892602)
		(end 114.291364 -104.958134)
		(width 0.1143)
		(layer "B.Cu")
		(net "P3E_CPU1_PE3_MP_TXN<8>")
	)
	(segment
		(start 135.116824 -81.564734)
		(end 135.073644 -81.564734)
		(width 0.0889)
		(layer "B.Cu")
		(net "P3E_CPU1_PE3_MP_TXN<8>")
	)
	(segment
		(start 111.70158 -105.294938)
		(end 111.611918 -105.160572)
		(width 0.1143)
		(layer "B.Cu")
		(net "P3E_CPU1_PE3_MP_TXN<8>")
	)
	(segment
		(start 54.159912 -108.293916)
		(end 34.699702 -110.210854)
		(width 0.1143)
		(layer "B.Cu")
		(net "P3E_CPU1_PE3_MP_TXN<8>")
	)
	(segment
		(start 26.608532 -106.694732)
		(end 26.608532 -105.97769)
		(width 0.1143)
		(layer "B.Cu")
		(net "P3E_CPU1_PE3_MP_TXN<8>")
	)
	(segment
		(start 83.99145 -102.331266)
		(end 69.046344 -105.318306)
		(width 0.1143)
		(layer "B.Cu")
		(net "P3E_CPU1_PE3_MP_TXN<8>")
	)
	(segment
		(start 135.975344 -82.060034)
		(end 135.942578 -82.060034)
		(width 0.0889)
		(layer "B.Cu")
		(net "P3E_CPU1_PE3_MP_TXN<8>")
	)
	(segment
		(start 133.38937 -82.555334)
		(end 133.36524 -82.555334)
		(width 0.0889)
		(layer "B.Cu")
		(net "P3E_CPU1_PE3_MP_TXN<8>")
	)
	(segment
		(start 14.771624 -97.459546)
		(end 14.753336 -97.441258)
		(width 0.1143)
		(layer "B.Cu")
		(net "P3E_CPU1_PE3_MP_TXN<8>")
	)
	(segment
		(start 137.688574 -83.050634)
		(end 137.655808 -83.050634)
		(width 0.0889)
		(layer "B.Cu")
		(net "P3E_CPU1_PE3_MP_TXN<8>")
	)
	(segment
		(start 140.267944 -84.536788)
		(end 140.235178 -84.536788)
		(width 0.0889)
		(layer "B.Cu")
		(net "P3E_CPU1_PE3_MP_TXN<8>")
	)
	(segment
		(start 28.135072 -108.221272)
		(end 26.608532 -106.694732)
		(width 0.1143)
		(layer "B.Cu")
		(net "P3E_CPU1_PE3_MP_TXN<8>")
	)
	(segment
		(start 124.804424 -87.508588)
		(end 124.771658 -87.508588)
		(width 0.0889)
		(layer "B.Cu")
		(net "P3E_CPU1_PE3_MP_TXN<8>")
	)
	(segment
		(start 30.87751 -108.789978)
		(end 28.135072 -108.221272)
		(width 0.1143)
		(layer "B.Cu")
		(net "P3E_CPU1_PE3_MP_TXN<8>")
	)
	(segment
		(start 123.427744 -94.234)
		(end 123.422918 -94.242636)
		(width 0.0889)
		(layer "B.Cu")
		(net "P3E_CPU1_PE3_MP_TXN<8>")
	)
	(segment
		(start 130.817874 -84.041234)
		(end 130.785108 -84.041234)
		(width 0.0889)
		(layer "B.Cu")
		(net "P3E_CPU1_PE3_MP_TXN<8>")
	)
	(segment
		(start 112.41786 -105.438194)
		(end 111.70158 -105.294938)
		(width 0.1143)
		(layer "B.Cu")
		(net "P3E_CPU1_PE3_MP_TXN<8>")
	)
	(segment
		(start 111.611918 -105.160572)
		(end 111.275622 -105.093262)
		(width 0.1143)
		(layer "B.Cu")
		(net "P3E_CPU1_PE3_MP_TXN<8>")
	)
	(segment
		(start 123.422918 -99.195636)
		(end 123.416568 -99.206304)
		(width 0.0889)
		(layer "B.Cu")
		(net "P3E_CPU1_PE3_MP_TXN<8>")
	)
	(segment
		(start 123.422918 -89.289636)
		(end 123.416568 -89.300304)
		(width 0.0889)
		(layer "B.Cu")
		(net "P3E_CPU1_PE3_MP_TXN<8>")
	)
	(segment
		(start 106.950002 -105.032302)
		(end 106.86034 -105.166668)
		(width 0.1143)
		(layer "B.Cu")
		(net "P3E_CPU1_PE3_MP_TXN<8>")
	)
	(arc
		(start 135.607044 -81.859882)
		(mid 135.40004 -81.649018)
		(end 135.116824 -81.564734)
		(width 0.0889)
		(layer "B.Cu")
		(net "P3E_CPU1_PE3_MP_TXN<8>")
	)
	(arc
		(start 125.139958 -87.308436)
		(mid 124.998275 -87.45224)
		(end 124.804424 -87.508588)
		(width 0.0889)
		(layer "B.Cu")
		(net "P3E_CPU1_PE3_MP_TXN<8>")
	)
	(arc
		(start 138.182604 -83.346036)
		(mid 137.973996 -83.134104)
		(end 137.688574 -83.050634)
		(width 0.0889)
		(layer "B.Cu")
		(net "P3E_CPU1_PE3_MP_TXN<8>")
	)
	(arc
		(start 123.916948 -88.003634)
		(mid 123.418697 -88.306474)
		(end 123.422918 -88.889586)
		(width 0.0889)
		(layer "B.Cu")
		(net "P3E_CPU1_PE3_MP_TXN<8>")
	)
	(arc
		(start 130.785108 -84.041234)
		(mid 130.499684 -84.124701)
		(end 130.291078 -84.336636)
		(width 0.0889)
		(layer "B.Cu")
		(net "P3E_CPU1_PE3_MP_TXN<8>")
	)
	(arc
		(start 139.409424 -98.100134)
		(mid 139.692641 -98.015853)
		(end 139.899644 -97.804986)
		(width 0.0889)
		(layer "B.Cu")
		(net "P3E_CPU1_PE3_MP_TXN<8>")
	)
	(arc
		(start 139.041124 -83.841336)
		(mid 138.83412 -83.630472)
		(end 138.550904 -83.546188)
		(width 0.0889)
		(layer "B.Cu")
		(net "P3E_CPU1_PE3_MP_TXN<8>")
	)
	(arc
		(start 140.758164 -84.831936)
		(mid 140.55116 -84.621072)
		(end 140.267944 -84.536788)
		(width 0.0889)
		(layer "B.Cu")
		(net "P3E_CPU1_PE3_MP_TXN<8>")
	)
	(arc
		(start 129.922778 -84.536788)
		(mid 129.639561 -84.621069)
		(end 129.432558 -84.831936)
		(width 0.0889)
		(layer "B.Cu")
		(net "P3E_CPU1_PE3_MP_TXN<8>")
	)
	(arc
		(start 130.291078 -84.336636)
		(mid 130.149395 -84.48044)
		(end 129.955544 -84.536788)
		(width 0.0889)
		(layer "B.Cu")
		(net "P3E_CPU1_PE3_MP_TXN<8>")
	)
	(arc
		(start 123.422918 -89.880186)
		(mid 123.476388 -90.075249)
		(end 123.427744 -90.2716)
		(width 0.0889)
		(layer "B.Cu")
		(net "P3E_CPU1_PE3_MP_TXN<8>")
	)
	(arc
		(start 128.574038 -85.327236)
		(mid 128.432355 -85.47104)
		(end 128.238504 -85.527388)
		(width 0.0889)
		(layer "B.Cu")
		(net "P3E_CPU1_PE3_MP_TXN<8>")
	)
	(arc
		(start 127.715518 -85.822536)
		(mid 127.575439 -85.965272)
		(end 127.383794 -86.022434)
		(width 0.0889)
		(layer "B.Cu")
		(net "P3E_CPU1_PE3_MP_TXN<8>")
	)
	(arc
		(start 131.149598 -83.841336)
		(mid 131.009519 -83.984072)
		(end 130.817874 -84.041234)
		(width 0.0889)
		(layer "B.Cu")
		(net "P3E_CPU1_PE3_MP_TXN<8>")
	)
	(arc
		(start 123.416568 -93.262704)
		(mid 123.34377 -93.553467)
		(end 123.422918 -93.842586)
		(width 0.0889)
		(layer "B.Cu")
		(net "P3E_CPU1_PE3_MP_TXN<8>")
	)
	(arc
		(start 123.416568 -91.281504)
		(mid 123.34377 -91.572267)
		(end 123.422918 -91.861386)
		(width 0.0889)
		(layer "B.Cu")
		(net "P3E_CPU1_PE3_MP_TXN<8>")
	)
	(arc
		(start 132.004562 -83.351878)
		(mid 131.858596 -83.494277)
		(end 131.661408 -83.546188)
		(width 0.0889)
		(layer "B.Cu")
		(net "P3E_CPU1_PE3_MP_TXN<8>")
	)
	(arc
		(start 123.416568 -99.206304)
		(mid 123.34377 -99.497067)
		(end 123.422918 -99.786186)
		(width 0.0889)
		(layer "B.Cu")
		(net "P3E_CPU1_PE3_MP_TXN<8>")
	)
	(arc
		(start 124.771658 -87.508588)
		(mid 124.488441 -87.592869)
		(end 124.281438 -87.803736)
		(width 0.0889)
		(layer "B.Cu")
		(net "P3E_CPU1_PE3_MP_TXN<8>")
	)
	(arc
		(start 142.481554 -87.393018)
		(mid 142.554352 -87.102255)
		(end 142.475204 -86.813136)
		(width 0.0889)
		(layer "B.Cu")
		(net "P3E_CPU1_PE3_MP_TXN<8>")
	)
	(arc
		(start 123.422918 -88.889586)
		(mid 123.476388 -89.084649)
		(end 123.427744 -89.281)
		(width 0.0889)
		(layer "B.Cu")
		(net "P3E_CPU1_PE3_MP_TXN<8>")
	)
	(arc
		(start 142.475204 -87.803736)
		(mid 142.421734 -87.608673)
		(end 142.470378 -87.412322)
		(width 0.0889)
		(layer "B.Cu")
		(net "P3E_CPU1_PE3_MP_TXN<8>")
	)
	(arc
		(start 123.422918 -96.814386)
		(mid 123.476388 -97.009449)
		(end 123.427744 -97.2058)
		(width 0.0889)
		(layer "B.Cu")
		(net "P3E_CPU1_PE3_MP_TXN<8>")
	)
	(arc
		(start 135.942578 -82.060034)
		(mid 135.748728 -82.003684)
		(end 135.607044 -81.859882)
		(width 0.0889)
		(layer "B.Cu")
		(net "P3E_CPU1_PE3_MP_TXN<8>")
	)
	(arc
		(start 138.876024 -97.804986)
		(mid 139.083028 -98.01585)
		(end 139.366244 -98.100134)
		(width 0.0889)
		(layer "B.Cu")
		(net "P3E_CPU1_PE3_MP_TXN<8>")
	)
	(arc
		(start 139.899644 -97.804986)
		(mid 140.039723 -97.66225)
		(end 140.231368 -97.605088)
		(width 0.0889)
		(layer "B.Cu")
		(net "P3E_CPU1_PE3_MP_TXN<8>")
	)
	(arc
		(start 142.475204 -88.39454)
		(mid 142.554267 -88.099138)
		(end 142.475204 -87.803736)
		(width 0.0889)
		(layer "B.Cu")
		(net "P3E_CPU1_PE3_MP_TXN<8>")
	)
	(arc
		(start 133.724904 -82.355182)
		(mid 133.583221 -82.498986)
		(end 133.38937 -82.555334)
		(width 0.0889)
		(layer "B.Cu")
		(net "P3E_CPU1_PE3_MP_TXN<8>")
	)
	(arc
		(start 139.372848 -84.041234)
		(mid 139.181206 -83.984068)
		(end 139.041124 -83.841336)
		(width 0.0889)
		(layer "B.Cu")
		(net "P3E_CPU1_PE3_MP_TXN<8>")
	)
	(arc
		(start 123.416568 -98.215704)
		(mid 123.34377 -98.506467)
		(end 123.422918 -98.795586)
		(width 0.0889)
		(layer "B.Cu")
		(net "P3E_CPU1_PE3_MP_TXN<8>")
	)
	(arc
		(start 140.264134 -97.605088)
		(mid 140.549558 -97.521621)
		(end 140.758164 -97.309686)
		(width 0.0889)
		(layer "B.Cu")
		(net "P3E_CPU1_PE3_MP_TXN<8>")
	)
	(arc
		(start 123.422918 -94.833186)
		(mid 123.476417 -95.033084)
		(end 123.422918 -95.232982)
		(width 0.0889)
		(layer "B.Cu")
		(net "P3E_CPU1_PE3_MP_TXN<8>")
	)
	(arc
		(start 142.475204 -86.813136)
		(mid 142.421734 -86.618073)
		(end 142.470378 -86.421722)
		(width 0.0889)
		(layer "B.Cu")
		(net "P3E_CPU1_PE3_MP_TXN<8>")
	)
	(arc
		(start 123.422918 -92.851986)
		(mid 123.476388 -93.047049)
		(end 123.427744 -93.2434)
		(width 0.0889)
		(layer "B.Cu")
		(net "P3E_CPU1_PE3_MP_TXN<8>")
	)
	(arc
		(start 137.655808 -83.050634)
		(mid 137.464166 -82.993468)
		(end 137.324084 -82.850736)
		(width 0.0889)
		(layer "B.Cu")
		(net "P3E_CPU1_PE3_MP_TXN<8>")
	)
	(arc
		(start 123.422918 -98.795586)
		(mid 123.476388 -98.990649)
		(end 123.427744 -99.187)
		(width 0.0889)
		(layer "B.Cu")
		(net "P3E_CPU1_PE3_MP_TXN<8>")
	)
	(arc
		(start 141.656562 -96.811592)
		(mid 141.800096 -96.660008)
		(end 142.00124 -96.604074)
		(width 0.0889)
		(layer "B.Cu")
		(net "P3E_CPU1_PE3_MP_TXN<8>")
	)
	(arc
		(start 138.518138 -83.546188)
		(mid 138.324288 -83.489838)
		(end 138.182604 -83.346036)
		(width 0.0889)
		(layer "B.Cu")
		(net "P3E_CPU1_PE3_MP_TXN<8>")
	)
	(arc
		(start 141.308074 -97.109534)
		(mid 141.510668 -96.993716)
		(end 141.656562 -96.811592)
		(width 0.0889)
		(layer "B.Cu")
		(net "P3E_CPU1_PE3_MP_TXN<8>")
	)
	(arc
		(start 142.47495 -89.776808)
		(mid 142.422487 -89.580945)
		(end 142.475204 -89.38514)
		(width 0.0889)
		(layer "B.Cu")
		(net "P3E_CPU1_PE3_MP_TXN<8>")
	)
	(arc
		(start 123.422918 -91.861386)
		(mid 123.476388 -92.056449)
		(end 123.427744 -92.2528)
		(width 0.0889)
		(layer "B.Cu")
		(net "P3E_CPU1_PE3_MP_TXN<8>")
	)
	(arc
		(start 129.432558 -84.831936)
		(mid 129.292479 -84.974672)
		(end 129.100834 -85.031834)
		(width 0.0889)
		(layer "B.Cu")
		(net "P3E_CPU1_PE3_MP_TXN<8>")
	)
	(arc
		(start 127.351028 -86.022434)
		(mid 127.065604 -86.105901)
		(end 126.856998 -86.317836)
		(width 0.0889)
		(layer "B.Cu")
		(net "P3E_CPU1_PE3_MP_TXN<8>")
	)
	(arc
		(start 140.758164 -97.309686)
		(mid 140.899847 -97.165882)
		(end 141.093698 -97.109534)
		(width 0.0889)
		(layer "B.Cu")
		(net "P3E_CPU1_PE3_MP_TXN<8>")
	)
	(arc
		(start 131.639818 -83.546188)
		(mid 131.356601 -83.630469)
		(end 131.149598 -83.841336)
		(width 0.0889)
		(layer "B.Cu")
		(net "P3E_CPU1_PE3_MP_TXN<8>")
	)
	(arc
		(start 123.416568 -90.290904)
		(mid 123.34377 -90.581667)
		(end 123.422918 -90.870786)
		(width 0.0889)
		(layer "B.Cu")
		(net "P3E_CPU1_PE3_MP_TXN<8>")
	)
	(arc
		(start 123.422918 -97.804986)
		(mid 123.476388 -98.000049)
		(end 123.427744 -98.1964)
		(width 0.0889)
		(layer "B.Cu")
		(net "P3E_CPU1_PE3_MP_TXN<8>")
	)
	(arc
		(start 123.416568 -89.300304)
		(mid 123.34377 -89.591067)
		(end 123.422918 -89.880186)
		(width 0.0889)
		(layer "B.Cu")
		(net "P3E_CPU1_PE3_MP_TXN<8>")
	)
	(arc
		(start 123.422918 -99.786186)
		(mid 123.476388 -99.981249)
		(end 123.427744 -100.1776)
		(width 0.0889)
		(layer "B.Cu")
		(net "P3E_CPU1_PE3_MP_TXN<8>")
	)
	(arc
		(start 141.952218 -85.527388)
		(mid 141.758368 -85.471038)
		(end 141.616684 -85.327236)
		(width 0.0889)
		(layer "B.Cu")
		(net "P3E_CPU1_PE3_MP_TXN<8>")
	)
	(arc
		(start 135.073644 -81.564734)
		(mid 134.790427 -81.649015)
		(end 134.583424 -81.859882)
		(width 0.0889)
		(layer "B.Cu")
		(net "P3E_CPU1_PE3_MP_TXN<8>")
	)
	(arc
		(start 142.475204 -89.38514)
		(mid 142.554426 -89.096022)
		(end 142.481554 -88.805258)
		(width 0.0889)
		(layer "B.Cu")
		(net "P3E_CPU1_PE3_MP_TXN<8>")
	)
	(arc
		(start 123.422918 -95.232982)
		(mid 123.343787 -95.528384)
		(end 123.422918 -95.823786)
		(width 0.0889)
		(layer "B.Cu")
		(net "P3E_CPU1_PE3_MP_TXN<8>")
	)
	(arc
		(start 140.235178 -84.536788)
		(mid 140.041328 -84.480438)
		(end 139.899644 -84.336636)
		(width 0.0889)
		(layer "B.Cu")
		(net "P3E_CPU1_PE3_MP_TXN<8>")
	)
	(arc
		(start 137.987786 -96.777556)
		(mid 138.029765 -97.330516)
		(end 138.511534 -97.605088)
		(width 0.0889)
		(layer "B.Cu")
		(net "P3E_CPU1_PE3_MP_TXN<8>")
	)
	(arc
		(start 142.470378 -88.785954)
		(mid 142.421623 -88.589602)
		(end 142.475204 -88.39454)
		(width 0.0889)
		(layer "B.Cu")
		(net "P3E_CPU1_PE3_MP_TXN<8>")
	)
	(arc
		(start 123.422918 -93.842586)
		(mid 123.476388 -94.037649)
		(end 123.427744 -94.234)
		(width 0.0889)
		(layer "B.Cu")
		(net "P3E_CPU1_PE3_MP_TXN<8>")
	)
	(arc
		(start 136.801098 -82.555334)
		(mid 136.607248 -82.498984)
		(end 136.465564 -82.355182)
		(width 0.0889)
		(layer "B.Cu")
		(net "P3E_CPU1_PE3_MP_TXN<8>")
	)
	(arc
		(start 123.422918 -95.823786)
		(mid 123.476388 -96.018849)
		(end 123.427744 -96.2152)
		(width 0.0889)
		(layer "B.Cu")
		(net "P3E_CPU1_PE3_MP_TXN<8>")
	)
	(arc
		(start 125.998478 -86.813136)
		(mid 125.858399 -86.955872)
		(end 125.666754 -87.013034)
		(width 0.0889)
		(layer "B.Cu")
		(net "P3E_CPU1_PE3_MP_TXN<8>")
	)
	(arc
		(start 126.488698 -86.517988)
		(mid 126.205481 -86.602269)
		(end 125.998478 -86.813136)
		(width 0.0889)
		(layer "B.Cu")
		(net "P3E_CPU1_PE3_MP_TXN<8>")
	)
	(arc
		(start 132.501894 -83.050634)
		(mid 132.21647 -83.134101)
		(end 132.007864 -83.346036)
		(width 0.0889)
		(layer "B.Cu")
		(net "P3E_CPU1_PE3_MP_TXN<8>")
	)
	(arc
		(start 123.416568 -97.225104)
		(mid 123.34377 -97.515867)
		(end 123.422918 -97.804986)
		(width 0.0889)
		(layer "B.Cu")
		(net "P3E_CPU1_PE3_MP_TXN<8>")
	)
	(arc
		(start 123.422918 -90.870786)
		(mid 123.476388 -91.065849)
		(end 123.427744 -91.2622)
		(width 0.0889)
		(layer "B.Cu")
		(net "P3E_CPU1_PE3_MP_TXN<8>")
	)
	(arc
		(start 124.281438 -87.803736)
		(mid 124.141359 -87.946472)
		(end 123.949714 -88.003634)
		(width 0.0889)
		(layer "B.Cu")
		(net "P3E_CPU1_PE3_MP_TXN<8>")
	)
	(arc
		(start 133.36524 -82.555334)
		(mid 133.077095 -82.637653)
		(end 132.866384 -82.850736)
		(width 0.0889)
		(layer "B.Cu")
		(net "P3E_CPU1_PE3_MP_TXN<8>")
	)
	(arc
		(start 134.215124 -82.060034)
		(mid 133.931907 -82.144315)
		(end 133.724904 -82.355182)
		(width 0.0889)
		(layer "B.Cu")
		(net "P3E_CPU1_PE3_MP_TXN<8>")
	)
	(arc
		(start 138.5443 -97.605088)
		(mid 138.735942 -97.662254)
		(end 138.876024 -97.804986)
		(width 0.0889)
		(layer "B.Cu")
		(net "P3E_CPU1_PE3_MP_TXN<8>")
	)
	(arc
		(start 126.856998 -86.317836)
		(mid 126.715315 -86.46164)
		(end 126.521464 -86.517988)
		(width 0.0889)
		(layer "B.Cu")
		(net "P3E_CPU1_PE3_MP_TXN<8>")
	)
	(arc
		(start 128.205738 -85.527388)
		(mid 127.922521 -85.611669)
		(end 127.715518 -85.822536)
		(width 0.0889)
		(layer "B.Cu")
		(net "P3E_CPU1_PE3_MP_TXN<8>")
	)
	(arc
		(start 129.068068 -85.031834)
		(mid 128.782644 -85.115301)
		(end 128.574038 -85.327236)
		(width 0.0889)
		(layer "B.Cu")
		(net "P3E_CPU1_PE3_MP_TXN<8>")
	)
	(arc
		(start 123.422918 -94.242636)
		(mid 123.343696 -94.531754)
		(end 123.416568 -94.822518)
		(width 0.0889)
		(layer "B.Cu")
		(net "P3E_CPU1_PE3_MP_TXN<8>")
	)
	(arc
		(start 123.416568 -96.234504)
		(mid 123.34377 -96.525267)
		(end 123.422918 -96.814386)
		(width 0.0889)
		(layer "B.Cu")
		(net "P3E_CPU1_PE3_MP_TXN<8>")
	)
	(arc
		(start 137.324084 -82.850736)
		(mid 137.113371 -82.637657)
		(end 136.825228 -82.555334)
		(width 0.0889)
		(layer "B.Cu")
		(net "P3E_CPU1_PE3_MP_TXN<8>")
	)
	(arc
		(start 141.089888 -85.031834)
		(mid 140.898246 -84.974668)
		(end 140.758164 -84.831936)
		(width 0.0889)
		(layer "B.Cu")
		(net "P3E_CPU1_PE3_MP_TXN<8>")
	)
	(arc
		(start 139.899644 -84.336636)
		(mid 139.691036 -84.124704)
		(end 139.405614 -84.041234)
		(width 0.0889)
		(layer "B.Cu")
		(net "P3E_CPU1_PE3_MP_TXN<8>")
	)
	(arc
		(start 136.465564 -82.355182)
		(mid 136.25856 -82.144318)
		(end 135.975344 -82.060034)
		(width 0.0889)
		(layer "B.Cu")
		(net "P3E_CPU1_PE3_MP_TXN<8>")
	)
	(arc
		(start 132.866384 -82.850736)
		(mid 132.726305 -82.993472)
		(end 132.53466 -83.050634)
		(width 0.0889)
		(layer "B.Cu")
		(net "P3E_CPU1_PE3_MP_TXN<8>")
	)
	(arc
		(start 123.416568 -92.272104)
		(mid 123.34377 -92.562867)
		(end 123.422918 -92.851986)
		(width 0.0889)
		(layer "B.Cu")
		(net "P3E_CPU1_PE3_MP_TXN<8>")
	)
	(arc
		(start 134.583424 -81.859882)
		(mid 134.441741 -82.003686)
		(end 134.24789 -82.060034)
		(width 0.0889)
		(layer "B.Cu")
		(net "P3E_CPU1_PE3_MP_TXN<8>")
	)
	(arc
		(start 142.481554 -86.402418)
		(mid 142.477523 -85.826236)
		(end 141.984984 -85.527388)
		(width 0.0889)
		(layer "B.Cu")
		(net "P3E_CPU1_PE3_MP_TXN<8>")
	)
	(arc
		(start 141.616684 -85.327236)
		(mid 141.408076 -85.115304)
		(end 141.122654 -85.031834)
		(width 0.0889)
		(layer "B.Cu")
		(net "P3E_CPU1_PE3_MP_TXN<8>")
	)
	(arc
		(start 125.633988 -87.013034)
		(mid 125.348564 -87.096501)
		(end 125.139958 -87.308436)
		(width 0.0889)
		(layer "B.Cu")
		(net "P3E_CPU1_PE3_MP_TXN<8>")
	)
	(segment
		(start 138.816334 -90.575384)
		(end 139.387834 -90.575384)
		(width 0.1143)
		(layer "F.Cu")
		(net "P3E_CPU1_PE3_MP_TXN<15>")
	)
	(via
		(at 20.945856 -103.535988)
		(size 0.508)
		(drill 0.254)
		(layers "F.Cu" "B.Cu")
		(net "P3E_CPU1_PE3_MP_TXN<15>")
	)
	(via
		(at 139.387834 -90.575384)
		(size 0.508)
		(drill 0.254)
		(layers "F.Cu" "B.Cu")
		(net "P3E_CPU1_PE3_MP_TXN<15>")
	)
	(segment
		(start 30.404562 -112.319308)
		(end 32.51835 -113.1951)
		(width 0.1143)
		(layer "B.Cu")
		(net "P3E_CPU1_PE3_MP_TXN<15>")
	)
	(segment
		(start 127.351028 -88.994234)
		(end 127.383794 -88.994234)
		(width 0.0889)
		(layer "B.Cu")
		(net "P3E_CPU1_PE3_MP_TXN<15>")
	)
	(segment
		(start 121.57456 -106.644694)
		(end 121.590054 -106.6292)
		(width 0.0889)
		(layer "B.Cu")
		(net "P3E_CPU1_PE3_MP_TXN<15>")
	)
	(segment
		(start 118.919244 -107.593638)
		(end 119.25554 -107.526836)
		(width 0.1143)
		(layer "B.Cu")
		(net "P3E_CPU1_PE3_MP_TXN<15>")
	)
	(segment
		(start 125.998478 -96.319086)
		(end 125.992128 -96.308418)
		(width 0.0889)
		(layer "B.Cu")
		(net "P3E_CPU1_PE3_MP_TXN<15>")
	)
	(segment
		(start 122.457718 -105.797096)
		(end 122.457972 -105.797096)
		(width 0.0889)
		(layer "B.Cu")
		(net "P3E_CPU1_PE3_MP_TXN<15>")
	)
	(segment
		(start 115.410996 -108.17479)
		(end 115.747292 -108.107988)
		(width 0.1143)
		(layer "B.Cu")
		(net "P3E_CPU1_PE3_MP_TXN<15>")
	)
	(segment
		(start 20.159218 -102.748588)
		(end 20.840192 -103.43007)
		(width 0.1143)
		(layer "B.Cu")
		(net "P3E_CPU1_PE3_MP_TXN<15>")
	)
	(segment
		(start 125.998478 -90.375486)
		(end 125.992128 -90.364818)
		(width 0.0889)
		(layer "B.Cu")
		(net "P3E_CPU1_PE3_MP_TXN<15>")
	)
	(segment
		(start 112.239806 -108.457492)
		(end 112.329722 -108.591858)
		(width 0.1143)
		(layer "B.Cu")
		(net "P3E_CPU1_PE3_MP_TXN<15>")
	)
	(segment
		(start 91.56319 -107.634024)
		(end 91.899232 -107.701334)
		(width 0.1143)
		(layer "B.Cu")
		(net "P3E_CPU1_PE3_MP_TXN<15>")
	)
	(segment
		(start 129.922778 -87.508588)
		(end 129.955544 -87.508588)
		(width 0.0889)
		(layer "B.Cu")
		(net "P3E_CPU1_PE3_MP_TXN<15>")
	)
	(segment
		(start 133.356604 -85.527388)
		(end 133.38937 -85.527388)
		(width 0.0889)
		(layer "B.Cu")
		(net "P3E_CPU1_PE3_MP_TXN<15>")
	)
	(segment
		(start 139.452858 -90.172286)
		(end 139.387834 -90.23731)
		(width 0.0889)
		(layer "B.Cu")
		(net "P3E_CPU1_PE3_MP_TXN<15>")
	)
	(segment
		(start 131.639818 -86.517988)
		(end 131.661408 -86.517988)
		(width 0.0889)
		(layer "B.Cu")
		(net "P3E_CPU1_PE3_MP_TXN<15>")
	)
	(segment
		(start 129.068068 -88.003634)
		(end 129.100834 -88.003634)
		(width 0.0889)
		(layer "B.Cu")
		(net "P3E_CPU1_PE3_MP_TXN<15>")
	)
	(segment
		(start 113.112804 -108.748576)
		(end 114.424206 -108.487718)
		(width 0.1143)
		(layer "B.Cu")
		(net "P3E_CPU1_PE3_MP_TXN<15>")
	)
	(segment
		(start 132.501894 -86.022434)
		(end 132.53466 -86.022434)
		(width 0.0889)
		(layer "B.Cu")
		(net "P3E_CPU1_PE3_MP_TXN<15>")
	)
	(segment
		(start 126.003304 -96.327722)
		(end 125.998478 -96.319086)
		(width 0.0889)
		(layer "B.Cu")
		(net "P3E_CPU1_PE3_MP_TXN<15>")
	)
	(segment
		(start 119.816118 -107.41533)
		(end 120.152414 -107.348274)
		(width 0.1143)
		(layer "B.Cu")
		(net "P3E_CPU1_PE3_MP_TXN<15>")
	)
	(segment
		(start 111.432848 -108.412788)
		(end 111.769144 -108.479844)
		(width 0.1143)
		(layer "B.Cu")
		(net "P3E_CPU1_PE3_MP_TXN<15>")
	)
	(segment
		(start 111.769144 -108.479844)
		(end 111.903764 -108.390182)
		(width 0.1143)
		(layer "B.Cu")
		(net "P3E_CPU1_PE3_MP_TXN<15>")
	)
	(segment
		(start 126.096014 -102.159054)
		(end 126.096014 -101.44125)
		(width 0.0889)
		(layer "B.Cu")
		(net "P3E_CPU1_PE3_MP_TXN<15>")
	)
	(segment
		(start 19.017488 -102.748588)
		(end 20.159218 -102.748588)
		(width 0.1143)
		(layer "B.Cu")
		(net "P3E_CPU1_PE3_MP_TXN<15>")
	)
	(segment
		(start 119.681752 -107.325414)
		(end 119.816118 -107.41533)
		(width 0.1143)
		(layer "B.Cu")
		(net "P3E_CPU1_PE3_MP_TXN<15>")
	)
	(segment
		(start 139.387834 -90.23731)
		(end 139.387834 -90.575384)
		(width 0.0889)
		(layer "B.Cu")
		(net "P3E_CPU1_PE3_MP_TXN<15>")
	)
	(segment
		(start 139.372848 -87.013034)
		(end 139.405614 -87.013034)
		(width 0.0889)
		(layer "B.Cu")
		(net "P3E_CPU1_PE3_MP_TXN<15>")
	)
	(segment
		(start 126.003304 -97.318322)
		(end 125.998478 -97.309686)
		(width 0.0889)
		(layer "B.Cu")
		(net "P3E_CPU1_PE3_MP_TXN<15>")
	)
	(segment
		(start 97.322132 -108.902246)
		(end 102.5779 -107.851194)
		(width 0.1143)
		(layer "B.Cu")
		(net "P3E_CPU1_PE3_MP_TXN<15>")
	)
	(segment
		(start 91.899232 -107.701334)
		(end 91.988894 -107.8357)
		(width 0.1143)
		(layer "B.Cu")
		(net "P3E_CPU1_PE3_MP_TXN<15>")
	)
	(segment
		(start 114.424206 -108.487718)
		(end 114.514122 -108.353352)
		(width 0.1143)
		(layer "B.Cu")
		(net "P3E_CPU1_PE3_MP_TXN<15>")
	)
	(segment
		(start 102.5779 -107.851194)
		(end 105.717594 -108.479082)
		(width 0.1143)
		(layer "B.Cu")
		(net "P3E_CPU1_PE3_MP_TXN<15>")
	)
	(segment
		(start 136.801098 -85.527388)
		(end 136.833864 -85.527388)
		(width 0.0889)
		(layer "B.Cu")
		(net "P3E_CPU1_PE3_MP_TXN<15>")
	)
	(segment
		(start 120.152414 -107.348274)
		(end 120.24233 -107.213908)
		(width 0.1143)
		(layer "B.Cu")
		(net "P3E_CPU1_PE3_MP_TXN<15>")
	)
	(segment
		(start 126.488698 -89.489788)
		(end 126.521464 -89.489788)
		(width 0.0889)
		(layer "B.Cu")
		(net "P3E_CPU1_PE3_MP_TXN<15>")
	)
	(segment
		(start 126.003304 -93.355922)
		(end 125.998478 -93.347286)
		(width 0.0889)
		(layer "B.Cu")
		(net "P3E_CPU1_PE3_MP_TXN<15>")
	)
	(segment
		(start 111.903764 -108.390182)
		(end 112.239806 -108.457492)
		(width 0.1143)
		(layer "B.Cu")
		(net "P3E_CPU1_PE3_MP_TXN<15>")
	)
	(segment
		(start 121.049288 -107.169966)
		(end 121.57456 -106.644694)
		(width 0.1143)
		(layer "B.Cu")
		(net "P3E_CPU1_PE3_MP_TXN<15>")
	)
	(segment
		(start 132.004562 -86.323678)
		(end 132.007864 -86.317836)
		(width 0.0889)
		(layer "B.Cu")
		(net "P3E_CPU1_PE3_MP_TXN<15>")
	)
	(segment
		(start 92.45981 -107.813348)
		(end 92.795852 -107.880658)
		(width 0.1143)
		(layer "B.Cu")
		(net "P3E_CPU1_PE3_MP_TXN<15>")
	)
	(segment
		(start 125.992128 -100.692204)
		(end 125.998478 -100.681536)
		(width 0.0889)
		(layer "B.Cu")
		(net "P3E_CPU1_PE3_MP_TXN<15>")
	)
	(segment
		(start 114.514122 -108.353352)
		(end 114.850418 -108.286296)
		(width 0.1143)
		(layer "B.Cu")
		(net "P3E_CPU1_PE3_MP_TXN<15>")
	)
	(segment
		(start 125.998478 -99.290886)
		(end 125.992128 -99.280218)
		(width 0.0889)
		(layer "B.Cu")
		(net "P3E_CPU1_PE3_MP_TXN<15>")
	)
	(segment
		(start 110.872524 -108.30052)
		(end 111.007144 -108.210858)
		(width 0.1143)
		(layer "B.Cu")
		(net "P3E_CPU1_PE3_MP_TXN<15>")
	)
	(segment
		(start 22.109938 -105.61447)
		(end 23.581106 -107.085638)
		(width 0.1143)
		(layer "B.Cu")
		(net "P3E_CPU1_PE3_MP_TXN<15>")
	)
	(segment
		(start 118.448582 -107.570778)
		(end 118.784878 -107.503722)
		(width 0.1143)
		(layer "B.Cu")
		(net "P3E_CPU1_PE3_MP_TXN<15>")
	)
	(segment
		(start 126.003304 -99.299522)
		(end 125.998478 -99.290886)
		(width 0.0889)
		(layer "B.Cu")
		(net "P3E_CPU1_PE3_MP_TXN<15>")
	)
	(segment
		(start 121.590054 -106.6292)
		(end 121.625614 -106.6292)
		(width 0.0889)
		(layer "B.Cu")
		(net "P3E_CPU1_PE3_MP_TXN<15>")
	)
	(segment
		(start 126.003304 -98.308922)
		(end 125.998478 -98.300286)
		(width 0.0889)
		(layer "B.Cu")
		(net "P3E_CPU1_PE3_MP_TXN<15>")
	)
	(segment
		(start 126.003304 -92.365322)
		(end 125.998478 -92.356686)
		(width 0.0889)
		(layer "B.Cu")
		(net "P3E_CPU1_PE3_MP_TXN<15>")
	)
	(segment
		(start 112.329722 -108.591858)
		(end 113.112804 -108.748576)
		(width 0.1143)
		(layer "B.Cu")
		(net "P3E_CPU1_PE3_MP_TXN<15>")
	)
	(segment
		(start 18.72742 -102.45852)
		(end 19.017488 -102.748588)
		(width 0.1143)
		(layer "B.Cu")
		(net "P3E_CPU1_PE3_MP_TXN<15>")
	)
	(segment
		(start 109.549946 -107.91952)
		(end 109.639608 -108.05414)
		(width 0.1143)
		(layer "B.Cu")
		(net "P3E_CPU1_PE3_MP_TXN<15>")
	)
	(segment
		(start 20.840192 -103.43007)
		(end 20.945856 -103.535988)
		(width 0.1143)
		(layer "B.Cu")
		(net "P3E_CPU1_PE3_MP_TXN<15>")
	)
	(segment
		(start 122.457972 -105.797096)
		(end 126.096014 -102.159054)
		(width 0.0889)
		(layer "B.Cu")
		(net "P3E_CPU1_PE3_MP_TXN<15>")
	)
	(segment
		(start 125.998478 -97.309686)
		(end 125.992128 -97.299018)
		(width 0.0889)
		(layer "B.Cu")
		(net "P3E_CPU1_PE3_MP_TXN<15>")
	)
	(segment
		(start 91.42857 -107.723686)
		(end 91.56319 -107.634024)
		(width 0.1143)
		(layer "B.Cu")
		(net "P3E_CPU1_PE3_MP_TXN<15>")
	)
	(segment
		(start 109.079284 -107.942126)
		(end 109.21365 -107.852464)
		(width 0.1143)
		(layer "B.Cu")
		(net "P3E_CPU1_PE3_MP_TXN<15>")
	)
	(segment
		(start 135.938768 -85.031834)
		(end 135.971534 -85.031834)
		(width 0.0889)
		(layer "B.Cu")
		(net "P3E_CPU1_PE3_MP_TXN<15>")
	)
	(segment
		(start 108.742988 -107.874816)
		(end 109.079284 -107.942126)
		(width 0.1143)
		(layer "B.Cu")
		(net "P3E_CPU1_PE3_MP_TXN<15>")
	)
	(segment
		(start 119.345456 -107.39247)
		(end 119.681752 -107.325414)
		(width 0.1143)
		(layer "B.Cu")
		(net "P3E_CPU1_PE3_MP_TXN<15>")
	)
	(segment
		(start 91.988894 -107.8357)
		(end 92.32519 -107.90301)
		(width 0.1143)
		(layer "B.Cu")
		(net "P3E_CPU1_PE3_MP_TXN<15>")
	)
	(segment
		(start 83.801204 -105.365296)
		(end 87.100918 -106.025696)
		(width 0.1143)
		(layer "B.Cu")
		(net "P3E_CPU1_PE3_MP_TXN<15>")
	)
	(segment
		(start 109.639608 -108.05414)
		(end 109.975904 -108.12145)
		(width 0.1143)
		(layer "B.Cu")
		(net "P3E_CPU1_PE3_MP_TXN<15>")
	)
	(segment
		(start 109.975904 -108.12145)
		(end 110.11027 -108.031534)
		(width 0.1143)
		(layer "B.Cu")
		(net "P3E_CPU1_PE3_MP_TXN<15>")
	)
	(segment
		(start 114.850418 -108.286296)
		(end 114.984784 -108.376212)
		(width 0.1143)
		(layer "B.Cu")
		(net "P3E_CPU1_PE3_MP_TXN<15>")
	)
	(segment
		(start 119.25554 -107.526836)
		(end 119.345456 -107.39247)
		(width 0.1143)
		(layer "B.Cu")
		(net "P3E_CPU1_PE3_MP_TXN<15>")
	)
	(segment
		(start 114.984784 -108.376212)
		(end 115.32108 -108.30941)
		(width 0.1143)
		(layer "B.Cu")
		(net "P3E_CPU1_PE3_MP_TXN<15>")
	)
	(segment
		(start 111.343186 -108.278168)
		(end 111.432848 -108.412788)
		(width 0.1143)
		(layer "B.Cu")
		(net "P3E_CPU1_PE3_MP_TXN<15>")
	)
	(segment
		(start 138.518138 -86.517988)
		(end 138.550904 -86.517988)
		(width 0.0889)
		(layer "B.Cu")
		(net "P3E_CPU1_PE3_MP_TXN<15>")
	)
	(segment
		(start 110.11027 -108.031534)
		(end 110.446566 -108.098844)
		(width 0.1143)
		(layer "B.Cu")
		(net "P3E_CPU1_PE3_MP_TXN<15>")
	)
	(segment
		(start 125.998478 -91.366086)
		(end 125.992128 -91.355418)
		(width 0.0889)
		(layer "B.Cu")
		(net "P3E_CPU1_PE3_MP_TXN<15>")
	)
	(segment
		(start 117.888004 -107.682284)
		(end 118.02237 -107.771946)
		(width 0.1143)
		(layer "B.Cu")
		(net "P3E_CPU1_PE3_MP_TXN<15>")
	)
	(segment
		(start 128.205738 -88.499188)
		(end 128.238504 -88.499188)
		(width 0.0889)
		(layer "B.Cu")
		(net "P3E_CPU1_PE3_MP_TXN<15>")
	)
	(segment
		(start 92.885514 -108.015024)
		(end 97.322132 -108.902246)
		(width 0.1143)
		(layer "B.Cu")
		(net "P3E_CPU1_PE3_MP_TXN<15>")
	)
	(segment
		(start 125.998478 -98.300286)
		(end 125.992128 -98.289618)
		(width 0.0889)
		(layer "B.Cu")
		(net "P3E_CPU1_PE3_MP_TXN<15>")
	)
	(segment
		(start 105.717594 -108.479082)
		(end 108.742988 -107.874816)
		(width 0.1143)
		(layer "B.Cu")
		(net "P3E_CPU1_PE3_MP_TXN<15>")
	)
	(segment
		(start 117.462046 -107.883452)
		(end 117.551708 -107.749086)
		(width 0.1143)
		(layer "B.Cu")
		(net "P3E_CPU1_PE3_MP_TXN<15>")
	)
	(segment
		(start 126.096014 -101.44125)
		(end 125.998478 -101.272086)
		(width 0.0889)
		(layer "B.Cu")
		(net "P3E_CPU1_PE3_MP_TXN<15>")
	)
	(segment
		(start 120.24233 -107.213908)
		(end 120.578626 -107.147106)
		(width 0.1143)
		(layer "B.Cu")
		(net "P3E_CPU1_PE3_MP_TXN<15>")
	)
	(segment
		(start 120.712992 -107.236768)
		(end 121.049288 -107.169966)
		(width 0.1143)
		(layer "B.Cu")
		(net "P3E_CPU1_PE3_MP_TXN<15>")
	)
	(segment
		(start 53.35397 -111.451136)
		(end 83.801204 -105.365296)
		(width 0.1143)
		(layer "B.Cu")
		(net "P3E_CPU1_PE3_MP_TXN<15>")
	)
	(segment
		(start 125.998478 -92.356686)
		(end 125.992128 -92.346018)
		(width 0.0889)
		(layer "B.Cu")
		(net "P3E_CPU1_PE3_MP_TXN<15>")
	)
	(segment
		(start 35.646614 -113.1951)
		(end 53.35397 -111.451136)
		(width 0.1143)
		(layer "B.Cu")
		(net "P3E_CPU1_PE3_MP_TXN<15>")
	)
	(segment
		(start 117.551708 -107.749086)
		(end 117.888004 -107.682284)
		(width 0.1143)
		(layer "B.Cu")
		(net "P3E_CPU1_PE3_MP_TXN<15>")
	)
	(segment
		(start 111.007144 -108.210858)
		(end 111.343186 -108.278168)
		(width 0.1143)
		(layer "B.Cu")
		(net "P3E_CPU1_PE3_MP_TXN<15>")
	)
	(segment
		(start 92.795852 -107.880658)
		(end 92.885514 -108.015024)
		(width 0.1143)
		(layer "B.Cu")
		(net "P3E_CPU1_PE3_MP_TXN<15>")
	)
	(segment
		(start 88.88349 -107.21467)
		(end 91.42857 -107.723686)
		(width 0.1143)
		(layer "B.Cu")
		(net "P3E_CPU1_PE3_MP_TXN<15>")
	)
	(segment
		(start 126.003304 -90.384122)
		(end 125.998478 -90.375486)
		(width 0.0889)
		(layer "B.Cu")
		(net "P3E_CPU1_PE3_MP_TXN<15>")
	)
	(segment
		(start 32.51835 -113.1951)
		(end 35.646614 -113.1951)
		(width 0.1143)
		(layer "B.Cu")
		(net "P3E_CPU1_PE3_MP_TXN<15>")
	)
	(segment
		(start 109.21365 -107.852464)
		(end 109.549946 -107.91952)
		(width 0.1143)
		(layer "B.Cu")
		(net "P3E_CPU1_PE3_MP_TXN<15>")
	)
	(segment
		(start 135.073644 -84.536788)
		(end 135.116824 -84.536788)
		(width 0.0889)
		(layer "B.Cu")
		(net "P3E_CPU1_PE3_MP_TXN<15>")
	)
	(segment
		(start 120.578626 -107.147106)
		(end 120.712992 -107.236768)
		(width 0.1143)
		(layer "B.Cu")
		(net "P3E_CPU1_PE3_MP_TXN<15>")
	)
	(segment
		(start 125.992128 -94.748604)
		(end 125.998478 -94.737936)
		(width 0.0889)
		(layer "B.Cu")
		(net "P3E_CPU1_PE3_MP_TXN<15>")
	)
	(segment
		(start 115.32108 -108.30941)
		(end 115.410996 -108.17479)
		(width 0.1143)
		(layer "B.Cu")
		(net "P3E_CPU1_PE3_MP_TXN<15>")
	)
	(segment
		(start 92.32519 -107.90301)
		(end 92.45981 -107.813348)
		(width 0.1143)
		(layer "B.Cu")
		(net "P3E_CPU1_PE3_MP_TXN<15>")
	)
	(segment
		(start 115.881658 -108.197904)
		(end 117.462046 -107.883452)
		(width 0.1143)
		(layer "B.Cu")
		(net "P3E_CPU1_PE3_MP_TXN<15>")
	)
	(segment
		(start 115.747292 -108.107988)
		(end 115.881658 -108.197904)
		(width 0.1143)
		(layer "B.Cu")
		(net "P3E_CPU1_PE3_MP_TXN<15>")
	)
	(segment
		(start 87.100918 -106.025696)
		(end 88.88349 -107.21467)
		(width 0.1143)
		(layer "B.Cu")
		(net "P3E_CPU1_PE3_MP_TXN<15>")
	)
	(segment
		(start 21.463254 -104.054148)
		(end 22.109938 -105.61447)
		(width 0.1143)
		(layer "B.Cu")
		(net "P3E_CPU1_PE3_MP_TXN<15>")
	)
	(segment
		(start 121.625614 -106.6292)
		(end 122.457718 -105.797096)
		(width 0.0889)
		(layer "B.Cu")
		(net "P3E_CPU1_PE3_MP_TXN<15>")
	)
	(segment
		(start 126.003304 -95.337122)
		(end 125.998478 -95.328486)
		(width 0.0889)
		(layer "B.Cu")
		(net "P3E_CPU1_PE3_MP_TXN<15>")
	)
	(segment
		(start 126.003304 -91.374722)
		(end 125.998478 -91.366086)
		(width 0.0889)
		(layer "B.Cu")
		(net "P3E_CPU1_PE3_MP_TXN<15>")
	)
	(segment
		(start 125.998478 -93.347286)
		(end 125.992128 -93.336618)
		(width 0.0889)
		(layer "B.Cu")
		(net "P3E_CPU1_PE3_MP_TXN<15>")
	)
	(segment
		(start 110.536228 -108.233464)
		(end 110.872524 -108.30052)
		(width 0.1143)
		(layer "B.Cu")
		(net "P3E_CPU1_PE3_MP_TXN<15>")
	)
	(segment
		(start 110.446566 -108.098844)
		(end 110.536228 -108.233464)
		(width 0.1143)
		(layer "B.Cu")
		(net "P3E_CPU1_PE3_MP_TXN<15>")
	)
	(segment
		(start 20.945856 -103.535988)
		(end 21.463254 -104.054148)
		(width 0.1143)
		(layer "B.Cu")
		(net "P3E_CPU1_PE3_MP_TXN<15>")
	)
	(segment
		(start 134.218934 -85.031834)
		(end 134.2517 -85.031834)
		(width 0.0889)
		(layer "B.Cu")
		(net "P3E_CPU1_PE3_MP_TXN<15>")
	)
	(segment
		(start 130.785108 -87.013034)
		(end 130.817874 -87.013034)
		(width 0.0889)
		(layer "B.Cu")
		(net "P3E_CPU1_PE3_MP_TXN<15>")
	)
	(segment
		(start 29.052266 -111.415576)
		(end 30.404562 -112.319308)
		(width 0.1143)
		(layer "B.Cu")
		(net "P3E_CPU1_PE3_MP_TXN<15>")
	)
	(segment
		(start 118.784878 -107.503722)
		(end 118.919244 -107.593638)
		(width 0.1143)
		(layer "B.Cu")
		(net "P3E_CPU1_PE3_MP_TXN<15>")
	)
	(segment
		(start 23.581106 -107.808268)
		(end 26.70175 -110.927642)
		(width 0.1143)
		(layer "B.Cu")
		(net "P3E_CPU1_PE3_MP_TXN<15>")
	)
	(segment
		(start 26.70175 -110.927642)
		(end 29.052266 -111.415576)
		(width 0.1143)
		(layer "B.Cu")
		(net "P3E_CPU1_PE3_MP_TXN<15>")
	)
	(segment
		(start 139.899644 -89.289636)
		(end 139.905994 -89.300304)
		(width 0.0889)
		(layer "B.Cu")
		(net "P3E_CPU1_PE3_MP_TXN<15>")
	)
	(segment
		(start 118.35892 -107.705144)
		(end 118.448582 -107.570778)
		(width 0.1143)
		(layer "B.Cu")
		(net "P3E_CPU1_PE3_MP_TXN<15>")
	)
	(segment
		(start 118.02237 -107.771946)
		(end 118.35892 -107.705144)
		(width 0.1143)
		(layer "B.Cu")
		(net "P3E_CPU1_PE3_MP_TXN<15>")
	)
	(segment
		(start 23.581106 -107.085638)
		(end 23.581106 -107.808268)
		(width 0.1143)
		(layer "B.Cu")
		(net "P3E_CPU1_PE3_MP_TXN<15>")
	)
	(segment
		(start 139.894818 -89.281)
		(end 139.899644 -89.289636)
		(width 0.0889)
		(layer "B.Cu")
		(net "P3E_CPU1_PE3_MP_TXN<15>")
	)
	(segment
		(start 137.655808 -86.022434)
		(end 137.688574 -86.022434)
		(width 0.0889)
		(layer "B.Cu")
		(net "P3E_CPU1_PE3_MP_TXN<15>")
	)
	(arc
		(start 136.833864 -85.527388)
		(mid 137.117081 -85.611669)
		(end 137.324084 -85.822536)
		(width 0.0889)
		(layer "B.Cu")
		(net "P3E_CPU1_PE3_MP_TXN<15>")
	)
	(arc
		(start 125.992128 -96.308418)
		(mid 125.91933 -96.017655)
		(end 125.998478 -95.728536)
		(width 0.0889)
		(layer "B.Cu")
		(net "P3E_CPU1_PE3_MP_TXN<15>")
	)
	(arc
		(start 129.955544 -87.508588)
		(mid 130.149394 -87.452238)
		(end 130.291078 -87.308436)
		(width 0.0889)
		(layer "B.Cu")
		(net "P3E_CPU1_PE3_MP_TXN<15>")
	)
	(arc
		(start 127.383794 -88.994234)
		(mid 127.575436 -88.937068)
		(end 127.715518 -88.794336)
		(width 0.0889)
		(layer "B.Cu")
		(net "P3E_CPU1_PE3_MP_TXN<15>")
	)
	(arc
		(start 131.149598 -86.813136)
		(mid 131.356602 -86.602272)
		(end 131.639818 -86.517988)
		(width 0.0889)
		(layer "B.Cu")
		(net "P3E_CPU1_PE3_MP_TXN<15>")
	)
	(arc
		(start 125.998478 -94.33814)
		(mid 125.919347 -94.042738)
		(end 125.998478 -93.747336)
		(width 0.0889)
		(layer "B.Cu")
		(net "P3E_CPU1_PE3_MP_TXN<15>")
	)
	(arc
		(start 125.998478 -100.28174)
		(mid 125.919347 -99.986338)
		(end 125.998478 -99.690936)
		(width 0.0889)
		(layer "B.Cu")
		(net "P3E_CPU1_PE3_MP_TXN<15>")
	)
	(arc
		(start 134.583424 -84.831936)
		(mid 134.790428 -84.621072)
		(end 135.073644 -84.536788)
		(width 0.0889)
		(layer "B.Cu")
		(net "P3E_CPU1_PE3_MP_TXN<15>")
	)
	(arc
		(start 125.998478 -95.328486)
		(mid 125.919256 -95.039368)
		(end 125.992128 -94.748604)
		(width 0.0889)
		(layer "B.Cu")
		(net "P3E_CPU1_PE3_MP_TXN<15>")
	)
	(arc
		(start 125.992128 -93.336618)
		(mid 125.91933 -93.045855)
		(end 125.998478 -92.756736)
		(width 0.0889)
		(layer "B.Cu")
		(net "P3E_CPU1_PE3_MP_TXN<15>")
	)
	(arc
		(start 125.998478 -95.728536)
		(mid 126.051948 -95.533473)
		(end 126.003304 -95.337122)
		(width 0.0889)
		(layer "B.Cu")
		(net "P3E_CPU1_PE3_MP_TXN<15>")
	)
	(arc
		(start 125.998478 -101.272086)
		(mid 125.919256 -100.982968)
		(end 125.992128 -100.692204)
		(width 0.0889)
		(layer "B.Cu")
		(net "P3E_CPU1_PE3_MP_TXN<15>")
	)
	(arc
		(start 125.992128 -99.280218)
		(mid 125.91933 -98.989455)
		(end 125.998478 -98.700336)
		(width 0.0889)
		(layer "B.Cu")
		(net "P3E_CPU1_PE3_MP_TXN<15>")
	)
	(arc
		(start 125.998478 -92.756736)
		(mid 126.051948 -92.561673)
		(end 126.003304 -92.365322)
		(width 0.0889)
		(layer "B.Cu")
		(net "P3E_CPU1_PE3_MP_TXN<15>")
	)
	(arc
		(start 134.2517 -85.031834)
		(mid 134.443342 -84.974668)
		(end 134.583424 -84.831936)
		(width 0.0889)
		(layer "B.Cu")
		(net "P3E_CPU1_PE3_MP_TXN<15>")
	)
	(arc
		(start 125.998478 -94.737936)
		(mid 126.051977 -94.538038)
		(end 125.998478 -94.33814)
		(width 0.0889)
		(layer "B.Cu")
		(net "P3E_CPU1_PE3_MP_TXN<15>")
	)
	(arc
		(start 139.405614 -87.013034)
		(mid 139.903865 -87.315874)
		(end 139.899644 -87.898986)
		(width 0.0889)
		(layer "B.Cu")
		(net "P3E_CPU1_PE3_MP_TXN<15>")
	)
	(arc
		(start 137.688574 -86.022434)
		(mid 137.973998 -86.105901)
		(end 138.182604 -86.317836)
		(width 0.0889)
		(layer "B.Cu")
		(net "P3E_CPU1_PE3_MP_TXN<15>")
	)
	(arc
		(start 127.715518 -88.794336)
		(mid 127.922522 -88.583472)
		(end 128.205738 -88.499188)
		(width 0.0889)
		(layer "B.Cu")
		(net "P3E_CPU1_PE3_MP_TXN<15>")
	)
	(arc
		(start 126.521464 -89.489788)
		(mid 126.715314 -89.433438)
		(end 126.856998 -89.289636)
		(width 0.0889)
		(layer "B.Cu")
		(net "P3E_CPU1_PE3_MP_TXN<15>")
	)
	(arc
		(start 125.998478 -99.690936)
		(mid 126.051948 -99.495873)
		(end 126.003304 -99.299522)
		(width 0.0889)
		(layer "B.Cu")
		(net "P3E_CPU1_PE3_MP_TXN<15>")
	)
	(arc
		(start 125.998478 -93.747336)
		(mid 126.051948 -93.552273)
		(end 126.003304 -93.355922)
		(width 0.0889)
		(layer "B.Cu")
		(net "P3E_CPU1_PE3_MP_TXN<15>")
	)
	(arc
		(start 135.971534 -85.031834)
		(mid 136.256958 -85.115301)
		(end 136.465564 -85.327236)
		(width 0.0889)
		(layer "B.Cu")
		(net "P3E_CPU1_PE3_MP_TXN<15>")
	)
	(arc
		(start 139.899644 -87.898986)
		(mid 139.846174 -88.094049)
		(end 139.894818 -88.2904)
		(width 0.0889)
		(layer "B.Cu")
		(net "P3E_CPU1_PE3_MP_TXN<15>")
	)
	(arc
		(start 125.992128 -92.346018)
		(mid 125.91933 -92.055255)
		(end 125.998478 -91.766136)
		(width 0.0889)
		(layer "B.Cu")
		(net "P3E_CPU1_PE3_MP_TXN<15>")
	)
	(arc
		(start 128.238504 -88.499188)
		(mid 128.432354 -88.442838)
		(end 128.574038 -88.299036)
		(width 0.0889)
		(layer "B.Cu")
		(net "P3E_CPU1_PE3_MP_TXN<15>")
	)
	(arc
		(start 129.432558 -87.803736)
		(mid 129.639562 -87.592872)
		(end 129.922778 -87.508588)
		(width 0.0889)
		(layer "B.Cu")
		(net "P3E_CPU1_PE3_MP_TXN<15>")
	)
	(arc
		(start 135.607044 -84.831936)
		(mid 135.747123 -84.974672)
		(end 135.938768 -85.031834)
		(width 0.0889)
		(layer "B.Cu")
		(net "P3E_CPU1_PE3_MP_TXN<15>")
	)
	(arc
		(start 125.992128 -90.364818)
		(mid 125.996159 -89.788636)
		(end 126.488698 -89.489788)
		(width 0.0889)
		(layer "B.Cu")
		(net "P3E_CPU1_PE3_MP_TXN<15>")
	)
	(arc
		(start 125.998478 -98.700336)
		(mid 126.051948 -98.505273)
		(end 126.003304 -98.308922)
		(width 0.0889)
		(layer "B.Cu")
		(net "P3E_CPU1_PE3_MP_TXN<15>")
	)
	(arc
		(start 133.724904 -85.327236)
		(mid 133.933512 -85.115304)
		(end 134.218934 -85.031834)
		(width 0.0889)
		(layer "B.Cu")
		(net "P3E_CPU1_PE3_MP_TXN<15>")
	)
	(arc
		(start 133.38937 -85.527388)
		(mid 133.58322 -85.471038)
		(end 133.724904 -85.327236)
		(width 0.0889)
		(layer "B.Cu")
		(net "P3E_CPU1_PE3_MP_TXN<15>")
	)
	(arc
		(start 130.291078 -87.308436)
		(mid 130.499686 -87.096504)
		(end 130.785108 -87.013034)
		(width 0.0889)
		(layer "B.Cu")
		(net "P3E_CPU1_PE3_MP_TXN<15>")
	)
	(arc
		(start 132.53466 -86.022434)
		(mid 132.726302 -85.965268)
		(end 132.866384 -85.822536)
		(width 0.0889)
		(layer "B.Cu")
		(net "P3E_CPU1_PE3_MP_TXN<15>")
	)
	(arc
		(start 139.899644 -88.889586)
		(mid 139.846174 -89.084649)
		(end 139.894818 -89.281)
		(width 0.0889)
		(layer "B.Cu")
		(net "P3E_CPU1_PE3_MP_TXN<15>")
	)
	(arc
		(start 139.894818 -88.2904)
		(mid 139.900518 -88.299987)
		(end 139.905994 -88.309704)
		(width 0.0889)
		(layer "B.Cu")
		(net "P3E_CPU1_PE3_MP_TXN<15>")
	)
	(arc
		(start 125.998478 -97.709736)
		(mid 126.051948 -97.514673)
		(end 126.003304 -97.318322)
		(width 0.0889)
		(layer "B.Cu")
		(net "P3E_CPU1_PE3_MP_TXN<15>")
	)
	(arc
		(start 125.998478 -96.719136)
		(mid 126.051948 -96.524073)
		(end 126.003304 -96.327722)
		(width 0.0889)
		(layer "B.Cu")
		(net "P3E_CPU1_PE3_MP_TXN<15>")
	)
	(arc
		(start 130.817874 -87.013034)
		(mid 131.009516 -86.955868)
		(end 131.149598 -86.813136)
		(width 0.0889)
		(layer "B.Cu")
		(net "P3E_CPU1_PE3_MP_TXN<15>")
	)
	(arc
		(start 139.905994 -88.309704)
		(mid 139.978792 -88.600467)
		(end 139.899644 -88.889586)
		(width 0.0889)
		(layer "B.Cu")
		(net "P3E_CPU1_PE3_MP_TXN<15>")
	)
	(arc
		(start 136.465564 -85.327236)
		(mid 136.607247 -85.47104)
		(end 136.801098 -85.527388)
		(width 0.0889)
		(layer "B.Cu")
		(net "P3E_CPU1_PE3_MP_TXN<15>")
	)
	(arc
		(start 137.324084 -85.822536)
		(mid 137.464163 -85.965272)
		(end 137.655808 -86.022434)
		(width 0.0889)
		(layer "B.Cu")
		(net "P3E_CPU1_PE3_MP_TXN<15>")
	)
	(arc
		(start 125.998478 -100.681536)
		(mid 126.051977 -100.481638)
		(end 125.998478 -100.28174)
		(width 0.0889)
		(layer "B.Cu")
		(net "P3E_CPU1_PE3_MP_TXN<15>")
	)
	(arc
		(start 125.992128 -91.355418)
		(mid 125.91933 -91.064655)
		(end 125.998478 -90.775536)
		(width 0.0889)
		(layer "B.Cu")
		(net "P3E_CPU1_PE3_MP_TXN<15>")
	)
	(arc
		(start 135.116824 -84.536788)
		(mid 135.400041 -84.621069)
		(end 135.607044 -84.831936)
		(width 0.0889)
		(layer "B.Cu")
		(net "P3E_CPU1_PE3_MP_TXN<15>")
	)
	(arc
		(start 131.661408 -86.517988)
		(mid 131.858569 -86.466029)
		(end 132.004562 -86.323678)
		(width 0.0889)
		(layer "B.Cu")
		(net "P3E_CPU1_PE3_MP_TXN<15>")
	)
	(arc
		(start 129.100834 -88.003634)
		(mid 129.292476 -87.946468)
		(end 129.432558 -87.803736)
		(width 0.0889)
		(layer "B.Cu")
		(net "P3E_CPU1_PE3_MP_TXN<15>")
	)
	(arc
		(start 126.856998 -89.289636)
		(mid 127.065606 -89.077704)
		(end 127.351028 -88.994234)
		(width 0.0889)
		(layer "B.Cu")
		(net "P3E_CPU1_PE3_MP_TXN<15>")
	)
	(arc
		(start 125.998478 -91.766136)
		(mid 126.051948 -91.571073)
		(end 126.003304 -91.374722)
		(width 0.0889)
		(layer "B.Cu")
		(net "P3E_CPU1_PE3_MP_TXN<15>")
	)
	(arc
		(start 125.992128 -97.299018)
		(mid 125.91933 -97.008255)
		(end 125.998478 -96.719136)
		(width 0.0889)
		(layer "B.Cu")
		(net "P3E_CPU1_PE3_MP_TXN<15>")
	)
	(arc
		(start 125.992128 -98.289618)
		(mid 125.91933 -97.998855)
		(end 125.998478 -97.709736)
		(width 0.0889)
		(layer "B.Cu")
		(net "P3E_CPU1_PE3_MP_TXN<15>")
	)
	(arc
		(start 128.574038 -88.299036)
		(mid 128.782646 -88.087104)
		(end 129.068068 -88.003634)
		(width 0.0889)
		(layer "B.Cu")
		(net "P3E_CPU1_PE3_MP_TXN<15>")
	)
	(arc
		(start 125.998478 -90.775536)
		(mid 126.051948 -90.580473)
		(end 126.003304 -90.384122)
		(width 0.0889)
		(layer "B.Cu")
		(net "P3E_CPU1_PE3_MP_TXN<15>")
	)
	(arc
		(start 138.550904 -86.517988)
		(mid 138.834121 -86.602269)
		(end 139.041124 -86.813136)
		(width 0.0889)
		(layer "B.Cu")
		(net "P3E_CPU1_PE3_MP_TXN<15>")
	)
	(arc
		(start 132.866384 -85.822536)
		(mid 133.073388 -85.611672)
		(end 133.356604 -85.527388)
		(width 0.0889)
		(layer "B.Cu")
		(net "P3E_CPU1_PE3_MP_TXN<15>")
	)
	(arc
		(start 139.905994 -89.300304)
		(mid 139.912359 -89.85735)
		(end 139.452858 -90.172286)
		(width 0.0889)
		(layer "B.Cu")
		(net "P3E_CPU1_PE3_MP_TXN<15>")
	)
	(arc
		(start 132.007864 -86.317836)
		(mid 132.216472 -86.105904)
		(end 132.501894 -86.022434)
		(width 0.0889)
		(layer "B.Cu")
		(net "P3E_CPU1_PE3_MP_TXN<15>")
	)
	(arc
		(start 139.041124 -86.813136)
		(mid 139.181203 -86.955872)
		(end 139.372848 -87.013034)
		(width 0.0889)
		(layer "B.Cu")
		(net "P3E_CPU1_PE3_MP_TXN<15>")
	)
	(arc
		(start 138.182604 -86.317836)
		(mid 138.324287 -86.46164)
		(end 138.518138 -86.517988)
		(width 0.0889)
		(layer "B.Cu")
		(net "P3E_CPU1_PE3_MP_TXN<15>")
	)
	(segment
		(start 138.816334 -91.565984)
		(end 139.387834 -91.565984)
		(width 0.1143)
		(layer "F.Cu")
		(net "P3E_CPU1_PE3_MP_TXN<14>")
	)
	(via
		(at 24.870664 -110.861602)
		(size 0.508)
		(drill 0.254)
		(layers "F.Cu" "B.Cu")
		(net "P3E_CPU1_PE3_MP_TXN<14>")
	)
	(via
		(at 139.387834 -91.565984)
		(size 0.508)
		(drill 0.254)
		(layers "F.Cu" "B.Cu")
		(net "P3E_CPU1_PE3_MP_TXN<14>")
	)
	(segment
		(start 136.82726 -86.708488)
		(end 136.794494 -86.708488)
		(width 0.0889)
		(layer "B.Cu")
		(net "P3E_CPU1_PE3_MP_TXN<14>")
	)
	(segment
		(start 127.022098 -98.300286)
		(end 127.017272 -98.308922)
		(width 0.0889)
		(layer "B.Cu")
		(net "P3E_CPU1_PE3_MP_TXN<14>")
	)
	(segment
		(start 16.51762 -104.52862)
		(end 16.86052 -104.52862)
		(width 0.1143)
		(layer "B.Cu")
		(net "P3E_CPU1_PE3_MP_TXN<14>")
	)
	(segment
		(start 16.40332 -104.41432)
		(end 16.51762 -104.52862)
		(width 0.1143)
		(layer "B.Cu")
		(net "P3E_CPU1_PE3_MP_TXN<14>")
	)
	(segment
		(start 126.817628 -103.267256)
		(end 126.691898 -103.392986)
		(width 0.0889)
		(layer "B.Cu")
		(net "P3E_CPU1_PE3_MP_TXN<14>")
	)
	(segment
		(start 134.258304 -86.212934)
		(end 134.225538 -86.212934)
		(width 0.0889)
		(layer "B.Cu")
		(net "P3E_CPU1_PE3_MP_TXN<14>")
	)
	(segment
		(start 14.23289 -102.06609)
		(end 14.94663 -102.780084)
		(width 0.1143)
		(layer "B.Cu")
		(net "P3E_CPU1_PE3_MP_TXN<14>")
	)
	(segment
		(start 126.691898 -103.392986)
		(end 126.551436 -103.392986)
		(width 0.0889)
		(layer "B.Cu")
		(net "P3E_CPU1_PE3_MP_TXN<14>")
	)
	(segment
		(start 138.876024 -89.289636)
		(end 138.88085 -89.281)
		(width 0.0889)
		(layer "B.Cu")
		(net "P3E_CPU1_PE3_MP_TXN<14>")
	)
	(segment
		(start 28.52039 -112.5601)
		(end 26.0985 -112.089692)
		(width 0.1143)
		(layer "B.Cu")
		(net "P3E_CPU1_PE3_MP_TXN<14>")
	)
	(segment
		(start 127.022098 -99.290886)
		(end 127.017272 -99.299522)
		(width 0.0889)
		(layer "B.Cu")
		(net "P3E_CPU1_PE3_MP_TXN<14>")
	)
	(segment
		(start 138.869674 -89.300304)
		(end 138.876024 -89.289636)
		(width 0.0889)
		(layer "B.Cu")
		(net "P3E_CPU1_PE3_MP_TXN<14>")
	)
	(segment
		(start 127.022098 -96.319086)
		(end 127.017272 -96.327722)
		(width 0.0889)
		(layer "B.Cu")
		(net "P3E_CPU1_PE3_MP_TXN<14>")
	)
	(segment
		(start 126.551436 -103.392986)
		(end 126.42596 -103.518462)
		(width 0.0889)
		(layer "B.Cu")
		(net "P3E_CPU1_PE3_MP_TXN<14>")
	)
	(segment
		(start 15.472918 -104.005888)
		(end 15.796006 -104.328468)
		(width 0.1143)
		(layer "B.Cu")
		(net "P3E_CPU1_PE3_MP_TXN<14>")
	)
	(segment
		(start 125.250956 -104.693466)
		(end 125.250956 -104.833928)
		(width 0.0889)
		(layer "B.Cu")
		(net "P3E_CPU1_PE3_MP_TXN<14>")
	)
	(segment
		(start 125.642624 -104.301798)
		(end 125.642624 -104.44226)
		(width 0.0889)
		(layer "B.Cu")
		(net "P3E_CPU1_PE3_MP_TXN<14>")
	)
	(segment
		(start 88.446356 -108.502958)
		(end 86.581488 -107.259628)
		(width 0.1143)
		(layer "B.Cu")
		(net "P3E_CPU1_PE3_MP_TXN<14>")
	)
	(segment
		(start 16.97482 -104.41432)
		(end 17.31772 -104.41432)
		(width 0.1143)
		(layer "B.Cu")
		(net "P3E_CPU1_PE3_MP_TXN<14>")
	)
	(segment
		(start 125.125226 -104.959658)
		(end 124.984764 -104.959658)
		(width 0.0889)
		(layer "B.Cu")
		(net "P3E_CPU1_PE3_MP_TXN<14>")
	)
	(segment
		(start 126.961392 -101.402388)
		(end 126.961392 -102.98303)
		(width 0.0889)
		(layer "B.Cu")
		(net "P3E_CPU1_PE3_MP_TXN<14>")
	)
	(segment
		(start 127.028448 -91.355418)
		(end 127.022098 -91.366086)
		(width 0.0889)
		(layer "B.Cu")
		(net "P3E_CPU1_PE3_MP_TXN<14>")
	)
	(segment
		(start 137.68197 -87.203534)
		(end 137.649204 -87.203534)
		(width 0.0889)
		(layer "B.Cu")
		(net "P3E_CPU1_PE3_MP_TXN<14>")
	)
	(segment
		(start 125.7681 -104.176322)
		(end 125.642624 -104.301798)
		(width 0.0889)
		(layer "B.Cu")
		(net "P3E_CPU1_PE3_MP_TXN<14>")
	)
	(segment
		(start 124.984764 -104.959658)
		(end 123.429268 -106.515154)
		(width 0.0889)
		(layer "B.Cu")
		(net "P3E_CPU1_PE3_MP_TXN<14>")
	)
	(segment
		(start 16.001746 -104.41432)
		(end 16.40332 -104.41432)
		(width 0.1143)
		(layer "B.Cu")
		(net "P3E_CPU1_PE3_MP_TXN<14>")
	)
	(segment
		(start 36.287202 -114.426746)
		(end 32.324548 -114.426746)
		(width 0.1143)
		(layer "B.Cu")
		(net "P3E_CPU1_PE3_MP_TXN<14>")
	)
	(segment
		(start 138.876024 -88.299036)
		(end 138.88085 -88.2904)
		(width 0.0889)
		(layer "B.Cu")
		(net "P3E_CPU1_PE3_MP_TXN<14>")
	)
	(segment
		(start 113.10239 -109.983524)
		(end 108.89107 -109.141006)
		(width 0.1143)
		(layer "B.Cu")
		(net "P3E_CPU1_PE3_MP_TXN<14>")
	)
	(segment
		(start 108.89107 -109.141006)
		(end 105.725214 -109.774228)
		(width 0.1143)
		(layer "B.Cu")
		(net "P3E_CPU1_PE3_MP_TXN<14>")
	)
	(segment
		(start 13.29182 -102.46868)
		(end 13.69441 -102.06609)
		(width 0.1143)
		(layer "B.Cu")
		(net "P3E_CPU1_PE3_MP_TXN<14>")
	)
	(segment
		(start 18.23212 -104.41432)
		(end 18.34642 -104.52862)
		(width 0.1143)
		(layer "B.Cu")
		(net "P3E_CPU1_PE3_MP_TXN<14>")
	)
	(segment
		(start 14.94663 -102.780084)
		(end 15.363698 -103.787702)
		(width 0.1143)
		(layer "B.Cu")
		(net "P3E_CPU1_PE3_MP_TXN<14>")
	)
	(segment
		(start 15.363698 -103.787702)
		(end 15.472918 -104.005888)
		(width 0.1143)
		(layer "B.Cu")
		(net "P3E_CPU1_PE3_MP_TXN<14>")
	)
	(segment
		(start 25.357074 -111.348012)
		(end 24.870664 -110.861602)
		(width 0.1143)
		(layer "B.Cu")
		(net "P3E_CPU1_PE3_MP_TXN<14>")
	)
	(segment
		(start 19.14652 -104.41432)
		(end 22.354286 -107.622086)
		(width 0.1143)
		(layer "B.Cu")
		(net "P3E_CPU1_PE3_MP_TXN<14>")
	)
	(segment
		(start 123.429268 -106.551222)
		(end 123.413774 -106.566716)
		(width 0.0889)
		(layer "B.Cu")
		(net "P3E_CPU1_PE3_MP_TXN<14>")
	)
	(segment
		(start 123.429268 -106.515154)
		(end 123.429268 -106.551222)
		(width 0.0889)
		(layer "B.Cu")
		(net "P3E_CPU1_PE3_MP_TXN<14>")
	)
	(segment
		(start 102.732586 -109.175804)
		(end 97.27184 -110.268004)
		(width 0.1143)
		(layer "B.Cu")
		(net "P3E_CPU1_PE3_MP_TXN<14>")
	)
	(segment
		(start 127.022098 -91.366086)
		(end 127.017272 -91.374722)
		(width 0.0889)
		(layer "B.Cu")
		(net "P3E_CPU1_PE3_MP_TXN<14>")
	)
	(segment
		(start 128.245108 -89.680288)
		(end 128.212342 -89.680288)
		(width 0.0889)
		(layer "B.Cu")
		(net "P3E_CPU1_PE3_MP_TXN<14>")
	)
	(segment
		(start 26.0985 -112.089692)
		(end 25.357074 -111.348266)
		(width 0.1143)
		(layer "B.Cu")
		(net "P3E_CPU1_PE3_MP_TXN<14>")
	)
	(segment
		(start 97.27184 -110.268004)
		(end 88.446356 -108.502958)
		(width 0.1143)
		(layer "B.Cu")
		(net "P3E_CPU1_PE3_MP_TXN<14>")
	)
	(segment
		(start 16.86052 -104.52862)
		(end 16.97482 -104.41432)
		(width 0.1143)
		(layer "B.Cu")
		(net "P3E_CPU1_PE3_MP_TXN<14>")
	)
	(segment
		(start 126.034292 -103.91013)
		(end 126.034292 -104.050592)
		(width 0.0889)
		(layer "B.Cu")
		(net "P3E_CPU1_PE3_MP_TXN<14>")
	)
	(segment
		(start 15.796006 -104.328468)
		(end 16.001746 -104.41432)
		(width 0.1143)
		(layer "B.Cu")
		(net "P3E_CPU1_PE3_MP_TXN<14>")
	)
	(segment
		(start 32.324548 -114.426746)
		(end 29.655262 -113.321084)
		(width 0.1143)
		(layer "B.Cu")
		(net "P3E_CPU1_PE3_MP_TXN<14>")
	)
	(segment
		(start 139.68095 -91.397074)
		(end 139.702032 -91.318334)
		(width 0.0889)
		(layer "B.Cu")
		(net "P3E_CPU1_PE3_MP_TXN<14>")
	)
	(segment
		(start 135.96493 -86.212934)
		(end 135.932164 -86.212934)
		(width 0.0889)
		(layer "B.Cu")
		(net "P3E_CPU1_PE3_MP_TXN<14>")
	)
	(segment
		(start 29.655262 -113.321084)
		(end 28.52039 -112.5601)
		(width 0.1143)
		(layer "B.Cu")
		(net "P3E_CPU1_PE3_MP_TXN<14>")
	)
	(segment
		(start 138.869674 -90.290904)
		(end 138.876024 -90.280236)
		(width 0.0889)
		(layer "B.Cu")
		(net "P3E_CPU1_PE3_MP_TXN<14>")
	)
	(segment
		(start 13.69441 -102.06609)
		(end 14.23289 -102.06609)
		(width 0.1143)
		(layer "B.Cu")
		(net "P3E_CPU1_PE3_MP_TXN<14>")
	)
	(segment
		(start 127.022098 -92.356686)
		(end 127.017272 -92.365322)
		(width 0.0889)
		(layer "B.Cu")
		(net "P3E_CPU1_PE3_MP_TXN<14>")
	)
	(segment
		(start 125.516894 -104.56799)
		(end 125.376432 -104.56799)
		(width 0.0889)
		(layer "B.Cu")
		(net "P3E_CPU1_PE3_MP_TXN<14>")
	)
	(segment
		(start 127.01905 -101.31552)
		(end 126.961392 -101.402388)
		(width 0.0889)
		(layer "B.Cu")
		(net "P3E_CPU1_PE3_MP_TXN<14>")
	)
	(segment
		(start 126.817628 -103.126794)
		(end 126.817628 -103.267256)
		(width 0.0889)
		(layer "B.Cu")
		(net "P3E_CPU1_PE3_MP_TXN<14>")
	)
	(segment
		(start 127.028448 -96.308418)
		(end 127.022098 -96.319086)
		(width 0.0889)
		(layer "B.Cu")
		(net "P3E_CPU1_PE3_MP_TXN<14>")
	)
	(segment
		(start 139.39901 -91.165934)
		(end 139.366244 -91.165934)
		(width 0.0889)
		(layer "B.Cu")
		(net "P3E_CPU1_PE3_MP_TXN<14>")
	)
	(segment
		(start 83.587336 -106.660696)
		(end 52.951634 -112.785144)
		(width 0.1143)
		(layer "B.Cu")
		(net "P3E_CPU1_PE3_MP_TXN<14>")
	)
	(segment
		(start 127.022098 -97.309686)
		(end 127.017272 -97.318322)
		(width 0.0889)
		(layer "B.Cu")
		(net "P3E_CPU1_PE3_MP_TXN<14>")
	)
	(segment
		(start 22.354286 -108.344716)
		(end 24.870664 -110.861602)
		(width 0.1143)
		(layer "B.Cu")
		(net "P3E_CPU1_PE3_MP_TXN<14>")
	)
	(segment
		(start 126.159768 -103.784654)
		(end 126.034292 -103.91013)
		(width 0.0889)
		(layer "B.Cu")
		(net "P3E_CPU1_PE3_MP_TXN<14>")
	)
	(segment
		(start 129.107438 -89.184734)
		(end 129.074672 -89.184734)
		(width 0.0889)
		(layer "B.Cu")
		(net "P3E_CPU1_PE3_MP_TXN<14>")
	)
	(segment
		(start 125.376432 -104.56799)
		(end 125.250956 -104.693466)
		(width 0.0889)
		(layer "B.Cu")
		(net "P3E_CPU1_PE3_MP_TXN<14>")
	)
	(segment
		(start 121.70918 -108.27131)
		(end 113.10239 -109.983524)
		(width 0.1143)
		(layer "B.Cu")
		(net "P3E_CPU1_PE3_MP_TXN<14>")
	)
	(segment
		(start 138.869674 -88.309704)
		(end 138.876024 -88.299036)
		(width 0.0889)
		(layer "B.Cu")
		(net "P3E_CPU1_PE3_MP_TXN<14>")
	)
	(segment
		(start 25.357074 -111.348266)
		(end 25.357074 -111.348012)
		(width 0.1143)
		(layer "B.Cu")
		(net "P3E_CPU1_PE3_MP_TXN<14>")
	)
	(segment
		(start 127.028448 -92.346018)
		(end 127.022098 -92.356686)
		(width 0.0889)
		(layer "B.Cu")
		(net "P3E_CPU1_PE3_MP_TXN<14>")
	)
	(segment
		(start 123.413774 -106.566716)
		(end 121.70918 -108.27131)
		(width 0.1143)
		(layer "B.Cu")
		(net "P3E_CPU1_PE3_MP_TXN<14>")
	)
	(segment
		(start 132.541264 -87.203534)
		(end 132.519674 -87.203534)
		(width 0.0889)
		(layer "B.Cu")
		(net "P3E_CPU1_PE3_MP_TXN<14>")
	)
	(segment
		(start 126.30023 -103.784654)
		(end 126.159768 -103.784654)
		(width 0.0889)
		(layer "B.Cu")
		(net "P3E_CPU1_PE3_MP_TXN<14>")
	)
	(segment
		(start 127.022098 -93.347286)
		(end 127.017272 -93.355922)
		(width 0.0889)
		(layer "B.Cu")
		(net "P3E_CPU1_PE3_MP_TXN<14>")
	)
	(segment
		(start 125.250956 -104.833928)
		(end 125.125226 -104.959658)
		(width 0.0889)
		(layer "B.Cu")
		(net "P3E_CPU1_PE3_MP_TXN<14>")
	)
	(segment
		(start 125.908562 -104.176322)
		(end 125.7681 -104.176322)
		(width 0.0889)
		(layer "B.Cu")
		(net "P3E_CPU1_PE3_MP_TXN<14>")
	)
	(segment
		(start 126.42596 -103.658924)
		(end 126.30023 -103.784654)
		(width 0.0889)
		(layer "B.Cu")
		(net "P3E_CPU1_PE3_MP_TXN<14>")
	)
	(segment
		(start 127.028448 -99.280218)
		(end 127.022098 -99.290886)
		(width 0.0889)
		(layer "B.Cu")
		(net "P3E_CPU1_PE3_MP_TXN<14>")
	)
	(segment
		(start 132.17652 -87.397844)
		(end 132.173218 -87.403686)
		(width 0.0889)
		(layer "B.Cu")
		(net "P3E_CPU1_PE3_MP_TXN<14>")
	)
	(segment
		(start 18.68932 -104.52862)
		(end 18.80362 -104.41432)
		(width 0.1143)
		(layer "B.Cu")
		(net "P3E_CPU1_PE3_MP_TXN<14>")
	)
	(segment
		(start 138.5443 -87.699088)
		(end 138.511534 -87.699088)
		(width 0.0889)
		(layer "B.Cu")
		(net "P3E_CPU1_PE3_MP_TXN<14>")
	)
	(segment
		(start 17.77492 -104.52862)
		(end 17.88922 -104.41432)
		(width 0.1143)
		(layer "B.Cu")
		(net "P3E_CPU1_PE3_MP_TXN<14>")
	)
	(segment
		(start 135.11022 -85.717888)
		(end 135.080248 -85.717888)
		(width 0.0889)
		(layer "B.Cu")
		(net "P3E_CPU1_PE3_MP_TXN<14>")
	)
	(segment
		(start 139.387834 -91.565984)
		(end 139.68095 -91.397074)
		(width 0.0889)
		(layer "B.Cu")
		(net "P3E_CPU1_PE3_MP_TXN<14>")
	)
	(segment
		(start 131.679188 -87.699088)
		(end 131.646422 -87.699088)
		(width 0.0889)
		(layer "B.Cu")
		(net "P3E_CPU1_PE3_MP_TXN<14>")
	)
	(segment
		(start 52.951634 -112.785144)
		(end 36.287202 -114.426746)
		(width 0.1143)
		(layer "B.Cu")
		(net "P3E_CPU1_PE3_MP_TXN<14>")
	)
	(segment
		(start 86.581488 -107.259628)
		(end 83.587336 -106.660696)
		(width 0.1143)
		(layer "B.Cu")
		(net "P3E_CPU1_PE3_MP_TXN<14>")
	)
	(segment
		(start 127.028448 -98.289618)
		(end 127.022098 -98.300286)
		(width 0.0889)
		(layer "B.Cu")
		(net "P3E_CPU1_PE3_MP_TXN<14>")
	)
	(segment
		(start 127.390398 -90.175334)
		(end 127.357632 -90.175334)
		(width 0.0889)
		(layer "B.Cu")
		(net "P3E_CPU1_PE3_MP_TXN<14>")
	)
	(segment
		(start 127.028448 -97.299018)
		(end 127.022098 -97.309686)
		(width 0.0889)
		(layer "B.Cu")
		(net "P3E_CPU1_PE3_MP_TXN<14>")
	)
	(segment
		(start 18.80362 -104.41432)
		(end 19.14652 -104.41432)
		(width 0.1143)
		(layer "B.Cu")
		(net "P3E_CPU1_PE3_MP_TXN<14>")
	)
	(segment
		(start 127.022098 -94.737936)
		(end 127.028448 -94.748604)
		(width 0.0889)
		(layer "B.Cu")
		(net "P3E_CPU1_PE3_MP_TXN<14>")
	)
	(segment
		(start 138.876024 -90.280236)
		(end 138.88085 -90.2716)
		(width 0.0889)
		(layer "B.Cu")
		(net "P3E_CPU1_PE3_MP_TXN<14>")
	)
	(segment
		(start 127.022098 -100.681536)
		(end 127.100584 -100.817426)
		(width 0.0889)
		(layer "B.Cu")
		(net "P3E_CPU1_PE3_MP_TXN<14>")
	)
	(segment
		(start 129.962148 -88.689688)
		(end 129.929382 -88.689688)
		(width 0.0889)
		(layer "B.Cu")
		(net "P3E_CPU1_PE3_MP_TXN<14>")
	)
	(segment
		(start 125.642624 -104.44226)
		(end 125.516894 -104.56799)
		(width 0.0889)
		(layer "B.Cu")
		(net "P3E_CPU1_PE3_MP_TXN<14>")
	)
	(segment
		(start 18.34642 -104.52862)
		(end 18.68932 -104.52862)
		(width 0.1143)
		(layer "B.Cu")
		(net "P3E_CPU1_PE3_MP_TXN<14>")
	)
	(segment
		(start 17.31772 -104.41432)
		(end 17.43202 -104.52862)
		(width 0.1143)
		(layer "B.Cu")
		(net "P3E_CPU1_PE3_MP_TXN<14>")
	)
	(segment
		(start 17.88922 -104.41432)
		(end 18.23212 -104.41432)
		(width 0.1143)
		(layer "B.Cu")
		(net "P3E_CPU1_PE3_MP_TXN<14>")
	)
	(segment
		(start 127.028448 -93.336618)
		(end 127.022098 -93.347286)
		(width 0.0889)
		(layer "B.Cu")
		(net "P3E_CPU1_PE3_MP_TXN<14>")
	)
	(segment
		(start 105.725214 -109.774228)
		(end 102.732586 -109.175804)
		(width 0.1143)
		(layer "B.Cu")
		(net "P3E_CPU1_PE3_MP_TXN<14>")
	)
	(segment
		(start 133.395974 -86.708488)
		(end 133.363208 -86.708488)
		(width 0.0889)
		(layer "B.Cu")
		(net "P3E_CPU1_PE3_MP_TXN<14>")
	)
	(segment
		(start 130.824478 -88.194134)
		(end 130.791712 -88.194134)
		(width 0.0889)
		(layer "B.Cu")
		(net "P3E_CPU1_PE3_MP_TXN<14>")
	)
	(segment
		(start 127.022098 -95.328486)
		(end 127.017272 -95.337122)
		(width 0.0889)
		(layer "B.Cu")
		(net "P3E_CPU1_PE3_MP_TXN<14>")
	)
	(segment
		(start 17.43202 -104.52862)
		(end 17.77492 -104.52862)
		(width 0.1143)
		(layer "B.Cu")
		(net "P3E_CPU1_PE3_MP_TXN<14>")
	)
	(segment
		(start 126.42596 -103.518462)
		(end 126.42596 -103.658924)
		(width 0.0889)
		(layer "B.Cu")
		(net "P3E_CPU1_PE3_MP_TXN<14>")
	)
	(segment
		(start 126.034292 -104.050592)
		(end 125.908562 -104.176322)
		(width 0.0889)
		(layer "B.Cu")
		(net "P3E_CPU1_PE3_MP_TXN<14>")
	)
	(segment
		(start 22.354286 -107.622086)
		(end 22.354286 -108.344716)
		(width 0.1143)
		(layer "B.Cu")
		(net "P3E_CPU1_PE3_MP_TXN<14>")
	)
	(segment
		(start 126.961392 -102.98303)
		(end 126.817628 -103.126794)
		(width 0.0889)
		(layer "B.Cu")
		(net "P3E_CPU1_PE3_MP_TXN<14>")
	)
	(arc
		(start 138.876024 -88.889586)
		(mid 138.796802 -88.600468)
		(end 138.869674 -88.309704)
		(width 0.0889)
		(layer "B.Cu")
		(net "P3E_CPU1_PE3_MP_TXN<14>")
	)
	(arc
		(start 127.022098 -96.719136)
		(mid 127.10132 -97.008254)
		(end 127.028448 -97.299018)
		(width 0.0889)
		(layer "B.Cu")
		(net "P3E_CPU1_PE3_MP_TXN<14>")
	)
	(arc
		(start 133.890004 -86.413086)
		(mid 133.681396 -86.625018)
		(end 133.395974 -86.708488)
		(width 0.0889)
		(layer "B.Cu")
		(net "P3E_CPU1_PE3_MP_TXN<14>")
	)
	(arc
		(start 127.022098 -95.728536)
		(mid 127.10132 -96.017654)
		(end 127.028448 -96.308418)
		(width 0.0889)
		(layer "B.Cu")
		(net "P3E_CPU1_PE3_MP_TXN<14>")
	)
	(arc
		(start 127.022098 -94.33814)
		(mid 126.968599 -94.538038)
		(end 127.022098 -94.737936)
		(width 0.0889)
		(layer "B.Cu")
		(net "P3E_CPU1_PE3_MP_TXN<14>")
	)
	(arc
		(start 127.022098 -91.766136)
		(mid 127.10132 -92.055254)
		(end 127.028448 -92.346018)
		(width 0.0889)
		(layer "B.Cu")
		(net "P3E_CPU1_PE3_MP_TXN<14>")
	)
	(arc
		(start 138.88085 -88.2904)
		(mid 138.877103 -87.901144)
		(end 138.5443 -87.699088)
		(width 0.0889)
		(layer "B.Cu")
		(net "P3E_CPU1_PE3_MP_TXN<14>")
	)
	(arc
		(start 127.022098 -100.28174)
		(mid 126.968599 -100.481638)
		(end 127.022098 -100.681536)
		(width 0.0889)
		(layer "B.Cu")
		(net "P3E_CPU1_PE3_MP_TXN<14>")
	)
	(arc
		(start 128.739138 -89.384886)
		(mid 128.53053 -89.596818)
		(end 128.245108 -89.680288)
		(width 0.0889)
		(layer "B.Cu")
		(net "P3E_CPU1_PE3_MP_TXN<14>")
	)
	(arc
		(start 137.158984 -86.908386)
		(mid 137.018905 -86.76565)
		(end 136.82726 -86.708488)
		(width 0.0889)
		(layer "B.Cu")
		(net "P3E_CPU1_PE3_MP_TXN<14>")
	)
	(arc
		(start 138.511534 -87.699088)
		(mid 138.22611 -87.615621)
		(end 138.017504 -87.403686)
		(width 0.0889)
		(layer "B.Cu")
		(net "P3E_CPU1_PE3_MP_TXN<14>")
	)
	(arc
		(start 129.074672 -89.184734)
		(mid 128.880822 -89.241084)
		(end 128.739138 -89.384886)
		(width 0.0889)
		(layer "B.Cu")
		(net "P3E_CPU1_PE3_MP_TXN<14>")
	)
	(arc
		(start 128.212342 -89.680288)
		(mid 128.0207 -89.737454)
		(end 127.880618 -89.880186)
		(width 0.0889)
		(layer "B.Cu")
		(net "P3E_CPU1_PE3_MP_TXN<14>")
	)
	(arc
		(start 130.456178 -88.394286)
		(mid 130.24757 -88.606218)
		(end 129.962148 -88.689688)
		(width 0.0889)
		(layer "B.Cu")
		(net "P3E_CPU1_PE3_MP_TXN<14>")
	)
	(arc
		(start 139.702032 -91.318334)
		(mid 139.56747 -91.208422)
		(end 139.39901 -91.165934)
		(width 0.0889)
		(layer "B.Cu")
		(net "P3E_CPU1_PE3_MP_TXN<14>")
	)
	(arc
		(start 127.017272 -95.337122)
		(mid 126.968517 -95.533474)
		(end 127.022098 -95.728536)
		(width 0.0889)
		(layer "B.Cu")
		(net "P3E_CPU1_PE3_MP_TXN<14>")
	)
	(arc
		(start 130.791712 -88.194134)
		(mid 130.597862 -88.250484)
		(end 130.456178 -88.394286)
		(width 0.0889)
		(layer "B.Cu")
		(net "P3E_CPU1_PE3_MP_TXN<14>")
	)
	(arc
		(start 129.929382 -88.689688)
		(mid 129.73774 -88.746854)
		(end 129.597658 -88.889586)
		(width 0.0889)
		(layer "B.Cu")
		(net "P3E_CPU1_PE3_MP_TXN<14>")
	)
	(arc
		(start 127.108204 -100.84943)
		(mid 127.110719 -101.091487)
		(end 127.01905 -101.31552)
		(width 0.0889)
		(layer "B.Cu")
		(net "P3E_CPU1_PE3_MP_TXN<14>")
	)
	(arc
		(start 138.88085 -90.2716)
		(mid 138.929605 -90.075248)
		(end 138.876024 -89.880186)
		(width 0.0889)
		(layer "B.Cu")
		(net "P3E_CPU1_PE3_MP_TXN<14>")
	)
	(arc
		(start 135.932164 -86.212934)
		(mid 135.648947 -86.128653)
		(end 135.441944 -85.917786)
		(width 0.0889)
		(layer "B.Cu")
		(net "P3E_CPU1_PE3_MP_TXN<14>")
	)
	(arc
		(start 133.031484 -86.908386)
		(mid 132.82448 -87.11925)
		(end 132.541264 -87.203534)
		(width 0.0889)
		(layer "B.Cu")
		(net "P3E_CPU1_PE3_MP_TXN<14>")
	)
	(arc
		(start 127.028448 -94.748604)
		(mid 127.101246 -95.039367)
		(end 127.022098 -95.328486)
		(width 0.0889)
		(layer "B.Cu")
		(net "P3E_CPU1_PE3_MP_TXN<14>")
	)
	(arc
		(start 134.225538 -86.212934)
		(mid 134.031688 -86.269284)
		(end 133.890004 -86.413086)
		(width 0.0889)
		(layer "B.Cu")
		(net "P3E_CPU1_PE3_MP_TXN<14>")
	)
	(arc
		(start 129.597658 -88.889586)
		(mid 129.390654 -89.10045)
		(end 129.107438 -89.184734)
		(width 0.0889)
		(layer "B.Cu")
		(net "P3E_CPU1_PE3_MP_TXN<14>")
	)
	(arc
		(start 136.794494 -86.708488)
		(mid 136.50907 -86.625021)
		(end 136.300464 -86.413086)
		(width 0.0889)
		(layer "B.Cu")
		(net "P3E_CPU1_PE3_MP_TXN<14>")
	)
	(arc
		(start 138.876024 -89.880186)
		(mid 138.796802 -89.591068)
		(end 138.869674 -89.300304)
		(width 0.0889)
		(layer "B.Cu")
		(net "P3E_CPU1_PE3_MP_TXN<14>")
	)
	(arc
		(start 131.646422 -87.699088)
		(mid 131.45478 -87.756254)
		(end 131.314698 -87.898986)
		(width 0.0889)
		(layer "B.Cu")
		(net "P3E_CPU1_PE3_MP_TXN<14>")
	)
	(arc
		(start 135.441944 -85.917786)
		(mid 135.301865 -85.77505)
		(end 135.11022 -85.717888)
		(width 0.0889)
		(layer "B.Cu")
		(net "P3E_CPU1_PE3_MP_TXN<14>")
	)
	(arc
		(start 137.649204 -87.203534)
		(mid 137.365987 -87.119253)
		(end 137.158984 -86.908386)
		(width 0.0889)
		(layer "B.Cu")
		(net "P3E_CPU1_PE3_MP_TXN<14>")
	)
	(arc
		(start 132.173218 -87.403686)
		(mid 131.96461 -87.615618)
		(end 131.679188 -87.699088)
		(width 0.0889)
		(layer "B.Cu")
		(net "P3E_CPU1_PE3_MP_TXN<14>")
	)
	(arc
		(start 133.363208 -86.708488)
		(mid 133.171566 -86.765654)
		(end 133.031484 -86.908386)
		(width 0.0889)
		(layer "B.Cu")
		(net "P3E_CPU1_PE3_MP_TXN<14>")
	)
	(arc
		(start 127.017272 -96.327722)
		(mid 126.968517 -96.524074)
		(end 127.022098 -96.719136)
		(width 0.0889)
		(layer "B.Cu")
		(net "P3E_CPU1_PE3_MP_TXN<14>")
	)
	(arc
		(start 132.519674 -87.203534)
		(mid 132.322513 -87.255493)
		(end 132.17652 -87.397844)
		(width 0.0889)
		(layer "B.Cu")
		(net "P3E_CPU1_PE3_MP_TXN<14>")
	)
	(arc
		(start 127.017272 -98.308922)
		(mid 126.968517 -98.505274)
		(end 127.022098 -98.700336)
		(width 0.0889)
		(layer "B.Cu")
		(net "P3E_CPU1_PE3_MP_TXN<14>")
	)
	(arc
		(start 136.300464 -86.413086)
		(mid 136.158781 -86.269282)
		(end 135.96493 -86.212934)
		(width 0.0889)
		(layer "B.Cu")
		(net "P3E_CPU1_PE3_MP_TXN<14>")
	)
	(arc
		(start 127.022098 -99.690936)
		(mid 127.101229 -99.986338)
		(end 127.022098 -100.28174)
		(width 0.0889)
		(layer "B.Cu")
		(net "P3E_CPU1_PE3_MP_TXN<14>")
	)
	(arc
		(start 138.017504 -87.403686)
		(mid 137.875821 -87.259882)
		(end 137.68197 -87.203534)
		(width 0.0889)
		(layer "B.Cu")
		(net "P3E_CPU1_PE3_MP_TXN<14>")
	)
	(arc
		(start 131.314698 -87.898986)
		(mid 131.107694 -88.10985)
		(end 130.824478 -88.194134)
		(width 0.0889)
		(layer "B.Cu")
		(net "P3E_CPU1_PE3_MP_TXN<14>")
	)
	(arc
		(start 127.022098 -92.756736)
		(mid 127.10132 -93.045854)
		(end 127.028448 -93.336618)
		(width 0.0889)
		(layer "B.Cu")
		(net "P3E_CPU1_PE3_MP_TXN<14>")
	)
	(arc
		(start 127.022098 -90.775536)
		(mid 127.10132 -91.064654)
		(end 127.028448 -91.355418)
		(width 0.0889)
		(layer "B.Cu")
		(net "P3E_CPU1_PE3_MP_TXN<14>")
	)
	(arc
		(start 127.100584 -100.817426)
		(mid 127.104608 -100.833377)
		(end 127.108204 -100.84943)
		(width 0.0889)
		(layer "B.Cu")
		(net "P3E_CPU1_PE3_MP_TXN<14>")
	)
	(arc
		(start 139.366244 -91.165934)
		(mid 138.873854 -90.867001)
		(end 138.869674 -90.290904)
		(width 0.0889)
		(layer "B.Cu")
		(net "P3E_CPU1_PE3_MP_TXN<14>")
	)
	(arc
		(start 127.357632 -90.175334)
		(mid 127.019463 -90.380132)
		(end 127.022098 -90.775536)
		(width 0.0889)
		(layer "B.Cu")
		(net "P3E_CPU1_PE3_MP_TXN<14>")
	)
	(arc
		(start 127.022098 -98.700336)
		(mid 127.10132 -98.989454)
		(end 127.028448 -99.280218)
		(width 0.0889)
		(layer "B.Cu")
		(net "P3E_CPU1_PE3_MP_TXN<14>")
	)
	(arc
		(start 135.080248 -85.717888)
		(mid 134.888606 -85.775054)
		(end 134.748524 -85.917786)
		(width 0.0889)
		(layer "B.Cu")
		(net "P3E_CPU1_PE3_MP_TXN<14>")
	)
	(arc
		(start 127.017272 -92.365322)
		(mid 126.968517 -92.561674)
		(end 127.022098 -92.756736)
		(width 0.0889)
		(layer "B.Cu")
		(net "P3E_CPU1_PE3_MP_TXN<14>")
	)
	(arc
		(start 127.017272 -91.374722)
		(mid 126.968517 -91.571074)
		(end 127.022098 -91.766136)
		(width 0.0889)
		(layer "B.Cu")
		(net "P3E_CPU1_PE3_MP_TXN<14>")
	)
	(arc
		(start 127.022098 -97.709736)
		(mid 127.10132 -97.998854)
		(end 127.028448 -98.289618)
		(width 0.0889)
		(layer "B.Cu")
		(net "P3E_CPU1_PE3_MP_TXN<14>")
	)
	(arc
		(start 127.017272 -99.299522)
		(mid 126.968517 -99.495874)
		(end 127.022098 -99.690936)
		(width 0.0889)
		(layer "B.Cu")
		(net "P3E_CPU1_PE3_MP_TXN<14>")
	)
	(arc
		(start 127.022098 -93.747336)
		(mid 127.101229 -94.042738)
		(end 127.022098 -94.33814)
		(width 0.0889)
		(layer "B.Cu")
		(net "P3E_CPU1_PE3_MP_TXN<14>")
	)
	(arc
		(start 134.748524 -85.917786)
		(mid 134.54152 -86.12865)
		(end 134.258304 -86.212934)
		(width 0.0889)
		(layer "B.Cu")
		(net "P3E_CPU1_PE3_MP_TXN<14>")
	)
	(arc
		(start 127.880618 -89.880186)
		(mid 127.673614 -90.09105)
		(end 127.390398 -90.175334)
		(width 0.0889)
		(layer "B.Cu")
		(net "P3E_CPU1_PE3_MP_TXN<14>")
	)
	(arc
		(start 127.017272 -93.355922)
		(mid 126.968517 -93.552274)
		(end 127.022098 -93.747336)
		(width 0.0889)
		(layer "B.Cu")
		(net "P3E_CPU1_PE3_MP_TXN<14>")
	)
	(arc
		(start 127.017272 -97.318322)
		(mid 126.968517 -97.514674)
		(end 127.022098 -97.709736)
		(width 0.0889)
		(layer "B.Cu")
		(net "P3E_CPU1_PE3_MP_TXN<14>")
	)
	(arc
		(start 138.88085 -89.281)
		(mid 138.929605 -89.084648)
		(end 138.876024 -88.889586)
		(width 0.0889)
		(layer "B.Cu")
		(net "P3E_CPU1_PE3_MP_TXN<14>")
	)
	(segment
		(start 138.816334 -92.556584)
		(end 139.387834 -92.556584)
		(width 0.1143)
		(layer "F.Cu")
		(net "P3E_CPU1_PE3_MP_TXN<13>")
	)
	(via
		(at 139.387834 -92.556584)
		(size 0.508)
		(drill 0.254)
		(layers "F.Cu" "B.Cu")
		(net "P3E_CPU1_PE3_MP_TXN<13>")
	)
	(via
		(at 35.3822 -115.1763)
		(size 0.508)
		(drill 0.254)
		(layers "F.Cu" "B.Cu")
		(net "P3E_CPU1_PE3_MP_TXN<13>")
	)
	(segment
		(start 121.91111 -109.138466)
		(end 124.876052 -106.173524)
		(width 0.1143)
		(layer "B.Cu")
		(net "P3E_CPU1_PE3_MP_TXN<13>")
	)
	(segment
		(start 138.177778 -89.281)
		(end 138.182604 -89.289636)
		(width 0.0889)
		(layer "B.Cu")
		(net "P3E_CPU1_PE3_MP_TXN<13>")
	)
	(segment
		(start 127.720344 -93.355922)
		(end 127.715518 -93.347286)
		(width 0.0889)
		(layer "B.Cu")
		(net "P3E_CPU1_PE3_MP_TXN<13>")
	)
	(segment
		(start 127.709676 -100.691696)
		(end 127.720852 -100.672646)
		(width 0.0889)
		(layer "B.Cu")
		(net "P3E_CPU1_PE3_MP_TXN<13>")
	)
	(segment
		(start 109.744764 -110.065058)
		(end 110.08106 -110.132114)
		(width 0.1143)
		(layer "B.Cu")
		(net "P3E_CPU1_PE3_MP_TXN<13>")
	)
	(segment
		(start 112.300258 -110.692692)
		(end 112.434624 -110.60303)
		(width 0.1143)
		(layer "B.Cu")
		(net "P3E_CPU1_PE3_MP_TXN<13>")
	)
	(segment
		(start 53.09489 -113.532158)
		(end 83.638644 -107.427268)
		(width 0.1143)
		(layer "B.Cu")
		(net "P3E_CPU1_PE3_MP_TXN<13>")
	)
	(segment
		(start 136.801098 -87.508588)
		(end 136.833864 -87.508588)
		(width 0.0889)
		(layer "B.Cu")
		(net "P3E_CPU1_PE3_MP_TXN<13>")
	)
	(segment
		(start 111.8743 -110.491016)
		(end 111.963962 -110.625382)
		(width 0.1143)
		(layer "B.Cu")
		(net "P3E_CPU1_PE3_MP_TXN<13>")
	)
	(segment
		(start 19.26971 -105.569258)
		(end 21.60397 -107.903518)
		(width 0.1143)
		(layer "B.Cu")
		(net "P3E_CPU1_PE3_MP_TXN<13>")
	)
	(segment
		(start 127.720344 -95.337122)
		(end 127.715518 -95.328486)
		(width 0.0889)
		(layer "B.Cu")
		(net "P3E_CPU1_PE3_MP_TXN<13>")
	)
	(segment
		(start 127.735584 -102.298246)
		(end 127.72644 -102.282498)
		(width 0.0889)
		(layer "B.Cu")
		(net "P3E_CPU1_PE3_MP_TXN<13>")
	)
	(segment
		(start 21.60397 -107.903518)
		(end 21.60397 -108.629704)
		(width 0.1143)
		(layer "B.Cu")
		(net "P3E_CPU1_PE3_MP_TXN<13>")
	)
	(segment
		(start 108.621322 -109.956854)
		(end 109.610398 -110.15472)
		(width 0.1143)
		(layer "B.Cu")
		(net "P3E_CPU1_PE3_MP_TXN<13>")
	)
	(segment
		(start 127.715772 -100.28174)
		(end 127.715518 -100.28174)
		(width 0.0889)
		(layer "B.Cu")
		(net "P3E_CPU1_PE3_MP_TXN<13>")
	)
	(segment
		(start 128.205738 -90.480388)
		(end 128.238504 -90.480388)
		(width 0.0889)
		(layer "B.Cu")
		(net "P3E_CPU1_PE3_MP_TXN<13>")
	)
	(segment
		(start 127.715518 -92.356686)
		(end 127.709168 -92.346018)
		(width 0.0889)
		(layer "B.Cu")
		(net "P3E_CPU1_PE3_MP_TXN<13>")
	)
	(segment
		(start 127.735584 -103.349806)
		(end 127.735584 -102.298246)
		(width 0.0889)
		(layer "B.Cu")
		(net "P3E_CPU1_PE3_MP_TXN<13>")
	)
	(segment
		(start 36.400994 -115.1763)
		(end 53.09489 -113.532158)
		(width 0.1143)
		(layer "B.Cu")
		(net "P3E_CPU1_PE3_MP_TXN<13>")
	)
	(segment
		(start 110.08106 -110.132114)
		(end 110.170722 -110.266734)
		(width 0.1143)
		(layer "B.Cu")
		(net "P3E_CPU1_PE3_MP_TXN<13>")
	)
	(segment
		(start 115.75542 -110.246414)
		(end 115.889786 -110.33633)
		(width 0.1143)
		(layer "B.Cu")
		(net "P3E_CPU1_PE3_MP_TXN<13>")
	)
	(segment
		(start 127.715518 -99.290886)
		(end 127.709168 -99.280218)
		(width 0.0889)
		(layer "B.Cu")
		(net "P3E_CPU1_PE3_MP_TXN<13>")
	)
	(segment
		(start 139.070842 -92.29852)
		(end 139.094718 -92.387674)
		(width 0.0889)
		(layer "B.Cu")
		(net "P3E_CPU1_PE3_MP_TXN<13>")
	)
	(segment
		(start 134.218934 -87.013034)
		(end 134.2517 -87.013034)
		(width 0.0889)
		(layer "B.Cu")
		(net "P3E_CPU1_PE3_MP_TXN<13>")
	)
	(segment
		(start 111.963962 -110.625382)
		(end 112.300258 -110.692692)
		(width 0.1143)
		(layer "B.Cu")
		(net "P3E_CPU1_PE3_MP_TXN<13>")
	)
	(segment
		(start 111.403638 -110.513368)
		(end 111.538004 -110.423706)
		(width 0.1143)
		(layer "B.Cu")
		(net "P3E_CPU1_PE3_MP_TXN<13>")
	)
	(segment
		(start 127.715518 -98.300286)
		(end 127.709168 -98.289618)
		(width 0.0889)
		(layer "B.Cu")
		(net "P3E_CPU1_PE3_MP_TXN<13>")
	)
	(segment
		(start 88.041734 -109.244892)
		(end 97.386394 -111.11357)
		(width 0.1143)
		(layer "B.Cu")
		(net "P3E_CPU1_PE3_MP_TXN<13>")
	)
	(segment
		(start 21.60397 -108.629704)
		(end 26.053288 -113.079022)
		(width 0.1143)
		(layer "B.Cu")
		(net "P3E_CPU1_PE3_MP_TXN<13>")
	)
	(segment
		(start 129.068068 -89.984834)
		(end 129.100834 -89.984834)
		(width 0.0889)
		(layer "B.Cu")
		(net "P3E_CPU1_PE3_MP_TXN<13>")
	)
	(segment
		(start 130.785108 -88.994234)
		(end 130.817874 -88.994234)
		(width 0.0889)
		(layer "B.Cu")
		(net "P3E_CPU1_PE3_MP_TXN<13>")
	)
	(segment
		(start 138.518138 -91.470988)
		(end 138.550904 -91.470988)
		(width 0.0889)
		(layer "B.Cu")
		(net "P3E_CPU1_PE3_MP_TXN<13>")
	)
	(segment
		(start 31.11627 -115.1763)
		(end 35.3822 -115.1763)
		(width 0.1143)
		(layer "B.Cu")
		(net "P3E_CPU1_PE3_MP_TXN<13>")
	)
	(segment
		(start 127.720344 -97.318322)
		(end 127.715518 -97.309686)
		(width 0.0889)
		(layer "B.Cu")
		(net "P3E_CPU1_PE3_MP_TXN<13>")
	)
	(segment
		(start 35.3822 -115.1763)
		(end 36.400994 -115.1763)
		(width 0.1143)
		(layer "B.Cu")
		(net "P3E_CPU1_PE3_MP_TXN<13>")
	)
	(segment
		(start 138.182604 -90.280236)
		(end 138.188954 -90.290904)
		(width 0.0889)
		(layer "B.Cu")
		(net "P3E_CPU1_PE3_MP_TXN<13>")
	)
	(segment
		(start 113.196878 -110.872016)
		(end 115.329208 -110.447836)
		(width 0.1143)
		(layer "B.Cu")
		(net "P3E_CPU1_PE3_MP_TXN<13>")
	)
	(segment
		(start 112.860582 -110.804706)
		(end 113.196878 -110.872016)
		(width 0.1143)
		(layer "B.Cu")
		(net "P3E_CPU1_PE3_MP_TXN<13>")
	)
	(segment
		(start 110.641384 -110.244382)
		(end 110.97768 -110.311692)
		(width 0.1143)
		(layer "B.Cu")
		(net "P3E_CPU1_PE3_MP_TXN<13>")
	)
	(segment
		(start 112.434624 -110.60303)
		(end 112.77092 -110.67034)
		(width 0.1143)
		(layer "B.Cu")
		(net "P3E_CPU1_PE3_MP_TXN<13>")
	)
	(segment
		(start 26.053288 -113.079022)
		(end 31.11627 -115.1763)
		(width 0.1143)
		(layer "B.Cu")
		(net "P3E_CPU1_PE3_MP_TXN<13>")
	)
	(segment
		(start 124.876052 -106.173524)
		(end 124.891546 -106.15803)
		(width 0.0889)
		(layer "B.Cu")
		(net "P3E_CPU1_PE3_MP_TXN<13>")
	)
	(segment
		(start 111.538004 -110.423706)
		(end 111.8743 -110.491016)
		(width 0.1143)
		(layer "B.Cu")
		(net "P3E_CPU1_PE3_MP_TXN<13>")
	)
	(segment
		(start 86.033102 -107.905804)
		(end 88.041734 -109.244892)
		(width 0.1143)
		(layer "B.Cu")
		(net "P3E_CPU1_PE3_MP_TXN<13>")
	)
	(segment
		(start 135.073644 -86.517988)
		(end 135.116824 -86.517988)
		(width 0.0889)
		(layer "B.Cu")
		(net "P3E_CPU1_PE3_MP_TXN<13>")
	)
	(segment
		(start 127.715518 -96.319086)
		(end 127.709168 -96.308418)
		(width 0.0889)
		(layer "B.Cu")
		(net "P3E_CPU1_PE3_MP_TXN<13>")
	)
	(segment
		(start 105.419144 -110.596934)
		(end 108.621322 -109.956854)
		(width 0.1143)
		(layer "B.Cu")
		(net "P3E_CPU1_PE3_MP_TXN<13>")
	)
	(segment
		(start 83.638644 -107.427268)
		(end 86.033102 -107.905804)
		(width 0.1143)
		(layer "B.Cu")
		(net "P3E_CPU1_PE3_MP_TXN<13>")
	)
	(segment
		(start 129.922778 -89.489788)
		(end 129.955544 -89.489788)
		(width 0.0889)
		(layer "B.Cu")
		(net "P3E_CPU1_PE3_MP_TXN<13>")
	)
	(segment
		(start 127.34544 -103.73995)
		(end 127.735584 -103.349806)
		(width 0.0889)
		(layer "B.Cu")
		(net "P3E_CPU1_PE3_MP_TXN<13>")
	)
	(segment
		(start 127.720344 -91.374722)
		(end 127.715518 -91.366086)
		(width 0.0889)
		(layer "B.Cu")
		(net "P3E_CPU1_PE3_MP_TXN<13>")
	)
	(segment
		(start 124.927106 -106.15803)
		(end 127.34544 -103.739696)
		(width 0.0889)
		(layer "B.Cu")
		(net "P3E_CPU1_PE3_MP_TXN<13>")
	)
	(segment
		(start 137.655808 -88.003634)
		(end 137.688574 -88.003634)
		(width 0.0889)
		(layer "B.Cu")
		(net "P3E_CPU1_PE3_MP_TXN<13>")
	)
	(segment
		(start 124.891546 -106.15803)
		(end 124.927106 -106.15803)
		(width 0.0889)
		(layer "B.Cu")
		(net "P3E_CPU1_PE3_MP_TXN<13>")
	)
	(segment
		(start 111.067342 -110.446058)
		(end 111.403638 -110.513368)
		(width 0.1143)
		(layer "B.Cu")
		(net "P3E_CPU1_PE3_MP_TXN<13>")
	)
	(segment
		(start 127.715518 -91.366086)
		(end 127.709168 -91.355418)
		(width 0.0889)
		(layer "B.Cu")
		(net "P3E_CPU1_PE3_MP_TXN<13>")
	)
	(segment
		(start 127.715518 -97.309686)
		(end 127.709168 -97.299018)
		(width 0.0889)
		(layer "B.Cu")
		(net "P3E_CPU1_PE3_MP_TXN<13>")
	)
	(segment
		(start 138.177778 -90.2716)
		(end 138.182604 -90.280236)
		(width 0.0889)
		(layer "B.Cu")
		(net "P3E_CPU1_PE3_MP_TXN<13>")
	)
	(segment
		(start 139.094718 -92.387674)
		(end 139.387834 -92.556584)
		(width 0.0889)
		(layer "B.Cu")
		(net "P3E_CPU1_PE3_MP_TXN<13>")
	)
	(segment
		(start 127.34544 -103.739696)
		(end 127.34544 -103.73995)
		(width 0.0889)
		(layer "B.Cu")
		(net "P3E_CPU1_PE3_MP_TXN<13>")
	)
	(segment
		(start 127.720344 -98.308922)
		(end 127.715518 -98.300286)
		(width 0.0889)
		(layer "B.Cu")
		(net "P3E_CPU1_PE3_MP_TXN<13>")
	)
	(segment
		(start 109.610398 -110.15472)
		(end 109.744764 -110.065058)
		(width 0.1143)
		(layer "B.Cu")
		(net "P3E_CPU1_PE3_MP_TXN<13>")
	)
	(segment
		(start 110.97768 -110.311692)
		(end 111.067342 -110.446058)
		(width 0.1143)
		(layer "B.Cu")
		(net "P3E_CPU1_PE3_MP_TXN<13>")
	)
	(segment
		(start 102.694994 -110.05185)
		(end 105.419144 -110.596934)
		(width 0.1143)
		(layer "B.Cu")
		(net "P3E_CPU1_PE3_MP_TXN<13>")
	)
	(segment
		(start 132.501894 -88.003634)
		(end 132.53466 -88.003634)
		(width 0.0889)
		(layer "B.Cu")
		(net "P3E_CPU1_PE3_MP_TXN<13>")
	)
	(segment
		(start 133.356604 -87.508588)
		(end 133.38937 -87.508588)
		(width 0.0889)
		(layer "B.Cu")
		(net "P3E_CPU1_PE3_MP_TXN<13>")
	)
	(segment
		(start 127.715518 -93.347286)
		(end 127.709168 -93.336618)
		(width 0.0889)
		(layer "B.Cu")
		(net "P3E_CPU1_PE3_MP_TXN<13>")
	)
	(segment
		(start 97.386394 -111.11357)
		(end 102.694994 -110.05185)
		(width 0.1143)
		(layer "B.Cu")
		(net "P3E_CPU1_PE3_MP_TXN<13>")
	)
	(segment
		(start 127.720344 -99.299522)
		(end 127.715518 -99.290886)
		(width 0.0889)
		(layer "B.Cu")
		(net "P3E_CPU1_PE3_MP_TXN<13>")
	)
	(segment
		(start 135.938768 -87.013034)
		(end 135.971534 -87.013034)
		(width 0.0889)
		(layer "B.Cu")
		(net "P3E_CPU1_PE3_MP_TXN<13>")
	)
	(segment
		(start 110.507018 -110.334044)
		(end 110.641384 -110.244382)
		(width 0.1143)
		(layer "B.Cu")
		(net "P3E_CPU1_PE3_MP_TXN<13>")
	)
	(segment
		(start 127.720344 -92.365322)
		(end 127.715518 -92.356686)
		(width 0.0889)
		(layer "B.Cu")
		(net "P3E_CPU1_PE3_MP_TXN<13>")
	)
	(segment
		(start 131.639818 -88.499188)
		(end 131.661408 -88.499188)
		(width 0.0889)
		(layer "B.Cu")
		(net "P3E_CPU1_PE3_MP_TXN<13>")
	)
	(segment
		(start 127.720344 -96.327722)
		(end 127.715518 -96.319086)
		(width 0.0889)
		(layer "B.Cu")
		(net "P3E_CPU1_PE3_MP_TXN<13>")
	)
	(segment
		(start 115.419124 -110.31347)
		(end 115.75542 -110.246414)
		(width 0.1143)
		(layer "B.Cu")
		(net "P3E_CPU1_PE3_MP_TXN<13>")
	)
	(segment
		(start 18.72742 -105.20172)
		(end 19.094958 -105.569258)
		(width 0.1143)
		(layer "B.Cu")
		(net "P3E_CPU1_PE3_MP_TXN<13>")
	)
	(segment
		(start 115.329208 -110.447836)
		(end 115.419124 -110.31347)
		(width 0.1143)
		(layer "B.Cu")
		(net "P3E_CPU1_PE3_MP_TXN<13>")
	)
	(segment
		(start 112.77092 -110.67034)
		(end 112.860582 -110.804706)
		(width 0.1143)
		(layer "B.Cu")
		(net "P3E_CPU1_PE3_MP_TXN<13>")
	)
	(segment
		(start 19.094958 -105.569258)
		(end 19.26971 -105.569258)
		(width 0.1143)
		(layer "B.Cu")
		(net "P3E_CPU1_PE3_MP_TXN<13>")
	)
	(segment
		(start 110.170722 -110.266734)
		(end 110.507018 -110.334044)
		(width 0.1143)
		(layer "B.Cu")
		(net "P3E_CPU1_PE3_MP_TXN<13>")
	)
	(segment
		(start 132.004562 -88.304878)
		(end 132.007864 -88.299036)
		(width 0.0889)
		(layer "B.Cu")
		(net "P3E_CPU1_PE3_MP_TXN<13>")
	)
	(segment
		(start 138.182604 -89.289636)
		(end 138.188954 -89.300304)
		(width 0.0889)
		(layer "B.Cu")
		(net "P3E_CPU1_PE3_MP_TXN<13>")
	)
	(segment
		(start 127.709168 -94.748604)
		(end 127.715518 -94.737936)
		(width 0.0889)
		(layer "B.Cu")
		(net "P3E_CPU1_PE3_MP_TXN<13>")
	)
	(segment
		(start 115.889786 -110.33633)
		(end 121.91111 -109.138466)
		(width 0.1143)
		(layer "B.Cu")
		(net "P3E_CPU1_PE3_MP_TXN<13>")
	)
	(arc
		(start 127.715518 -98.700336)
		(mid 127.768988 -98.505273)
		(end 127.720344 -98.308922)
		(width 0.0889)
		(layer "B.Cu")
		(net "P3E_CPU1_PE3_MP_TXN<13>")
	)
	(arc
		(start 127.715518 -94.737936)
		(mid 127.769017 -94.538038)
		(end 127.715518 -94.33814)
		(width 0.0889)
		(layer "B.Cu")
		(net "P3E_CPU1_PE3_MP_TXN<13>")
	)
	(arc
		(start 127.715518 -95.728536)
		(mid 127.768988 -95.533473)
		(end 127.720344 -95.337122)
		(width 0.0889)
		(layer "B.Cu")
		(net "P3E_CPU1_PE3_MP_TXN<13>")
	)
	(arc
		(start 127.715518 -91.766136)
		(mid 127.768988 -91.571073)
		(end 127.720344 -91.374722)
		(width 0.0889)
		(layer "B.Cu")
		(net "P3E_CPU1_PE3_MP_TXN<13>")
	)
	(arc
		(start 135.971534 -87.013034)
		(mid 136.256958 -87.096501)
		(end 136.465564 -87.308436)
		(width 0.0889)
		(layer "B.Cu")
		(net "P3E_CPU1_PE3_MP_TXN<13>")
	)
	(arc
		(start 129.432558 -89.784936)
		(mid 129.639562 -89.574072)
		(end 129.922778 -89.489788)
		(width 0.0889)
		(layer "B.Cu")
		(net "P3E_CPU1_PE3_MP_TXN<13>")
	)
	(arc
		(start 127.709168 -92.346018)
		(mid 127.63637 -92.055255)
		(end 127.715518 -91.766136)
		(width 0.0889)
		(layer "B.Cu")
		(net "P3E_CPU1_PE3_MP_TXN<13>")
	)
	(arc
		(start 128.238504 -90.480388)
		(mid 128.432354 -90.424038)
		(end 128.574038 -90.280236)
		(width 0.0889)
		(layer "B.Cu")
		(net "P3E_CPU1_PE3_MP_TXN<13>")
	)
	(arc
		(start 136.833864 -87.508588)
		(mid 137.117081 -87.592869)
		(end 137.324084 -87.803736)
		(width 0.0889)
		(layer "B.Cu")
		(net "P3E_CPU1_PE3_MP_TXN<13>")
	)
	(arc
		(start 135.607044 -86.813136)
		(mid 135.747123 -86.955872)
		(end 135.938768 -87.013034)
		(width 0.0889)
		(layer "B.Cu")
		(net "P3E_CPU1_PE3_MP_TXN<13>")
	)
	(arc
		(start 137.688574 -88.003634)
		(mid 138.186825 -88.306474)
		(end 138.182604 -88.889586)
		(width 0.0889)
		(layer "B.Cu")
		(net "P3E_CPU1_PE3_MP_TXN<13>")
	)
	(arc
		(start 134.583424 -86.813136)
		(mid 134.790428 -86.602272)
		(end 135.073644 -86.517988)
		(width 0.0889)
		(layer "B.Cu")
		(net "P3E_CPU1_PE3_MP_TXN<13>")
	)
	(arc
		(start 127.709168 -91.355418)
		(mid 127.713199 -90.779236)
		(end 128.205738 -90.480388)
		(width 0.0889)
		(layer "B.Cu")
		(net "P3E_CPU1_PE3_MP_TXN<13>")
	)
	(arc
		(start 138.182604 -90.870786)
		(mid 138.179856 -91.266253)
		(end 138.518138 -91.470988)
		(width 0.0889)
		(layer "B.Cu")
		(net "P3E_CPU1_PE3_MP_TXN<13>")
	)
	(arc
		(start 132.53466 -88.003634)
		(mid 132.726302 -87.946468)
		(end 132.866384 -87.803736)
		(width 0.0889)
		(layer "B.Cu")
		(net "P3E_CPU1_PE3_MP_TXN<13>")
	)
	(arc
		(start 127.715518 -100.28174)
		(mid 127.636387 -99.986338)
		(end 127.715518 -99.690936)
		(width 0.0889)
		(layer "B.Cu")
		(net "P3E_CPU1_PE3_MP_TXN<13>")
	)
	(arc
		(start 127.720852 -100.672646)
		(mid 127.769299 -100.476518)
		(end 127.715772 -100.28174)
		(width 0.0889)
		(layer "B.Cu")
		(net "P3E_CPU1_PE3_MP_TXN<13>")
	)
	(arc
		(start 130.291078 -89.289636)
		(mid 130.499686 -89.077704)
		(end 130.785108 -88.994234)
		(width 0.0889)
		(layer "B.Cu")
		(net "P3E_CPU1_PE3_MP_TXN<13>")
	)
	(arc
		(start 132.007864 -88.299036)
		(mid 132.216472 -88.087104)
		(end 132.501894 -88.003634)
		(width 0.0889)
		(layer "B.Cu")
		(net "P3E_CPU1_PE3_MP_TXN<13>")
	)
	(arc
		(start 128.574038 -90.280236)
		(mid 128.782646 -90.068304)
		(end 129.068068 -89.984834)
		(width 0.0889)
		(layer "B.Cu")
		(net "P3E_CPU1_PE3_MP_TXN<13>")
	)
	(arc
		(start 138.550904 -91.470988)
		(mid 139.029721 -91.7472)
		(end 139.070842 -92.29852)
		(width 0.0889)
		(layer "B.Cu")
		(net "P3E_CPU1_PE3_MP_TXN<13>")
	)
	(arc
		(start 127.709168 -96.308418)
		(mid 127.63637 -96.017655)
		(end 127.715518 -95.728536)
		(width 0.0889)
		(layer "B.Cu")
		(net "P3E_CPU1_PE3_MP_TXN<13>")
	)
	(arc
		(start 136.465564 -87.308436)
		(mid 136.607247 -87.45224)
		(end 136.801098 -87.508588)
		(width 0.0889)
		(layer "B.Cu")
		(net "P3E_CPU1_PE3_MP_TXN<13>")
	)
	(arc
		(start 137.324084 -87.803736)
		(mid 137.464163 -87.946472)
		(end 137.655808 -88.003634)
		(width 0.0889)
		(layer "B.Cu")
		(net "P3E_CPU1_PE3_MP_TXN<13>")
	)
	(arc
		(start 127.715518 -92.756736)
		(mid 127.768988 -92.561673)
		(end 127.720344 -92.365322)
		(width 0.0889)
		(layer "B.Cu")
		(net "P3E_CPU1_PE3_MP_TXN<13>")
	)
	(arc
		(start 138.188954 -89.300304)
		(mid 138.261752 -89.591067)
		(end 138.182604 -89.880186)
		(width 0.0889)
		(layer "B.Cu")
		(net "P3E_CPU1_PE3_MP_TXN<13>")
	)
	(arc
		(start 138.182604 -89.880186)
		(mid 138.129134 -90.075249)
		(end 138.177778 -90.2716)
		(width 0.0889)
		(layer "B.Cu")
		(net "P3E_CPU1_PE3_MP_TXN<13>")
	)
	(arc
		(start 127.709168 -98.289618)
		(mid 127.63637 -97.998855)
		(end 127.715518 -97.709736)
		(width 0.0889)
		(layer "B.Cu")
		(net "P3E_CPU1_PE3_MP_TXN<13>")
	)
	(arc
		(start 127.709168 -93.336618)
		(mid 127.63637 -93.045855)
		(end 127.715518 -92.756736)
		(width 0.0889)
		(layer "B.Cu")
		(net "P3E_CPU1_PE3_MP_TXN<13>")
	)
	(arc
		(start 127.709168 -97.299018)
		(mid 127.63637 -97.008255)
		(end 127.715518 -96.719136)
		(width 0.0889)
		(layer "B.Cu")
		(net "P3E_CPU1_PE3_MP_TXN<13>")
	)
	(arc
		(start 130.817874 -88.994234)
		(mid 131.009516 -88.937068)
		(end 131.149598 -88.794336)
		(width 0.0889)
		(layer "B.Cu")
		(net "P3E_CPU1_PE3_MP_TXN<13>")
	)
	(arc
		(start 127.715518 -99.690936)
		(mid 127.768988 -99.495873)
		(end 127.720344 -99.299522)
		(width 0.0889)
		(layer "B.Cu")
		(net "P3E_CPU1_PE3_MP_TXN<13>")
	)
	(arc
		(start 138.188954 -90.290904)
		(mid 138.261752 -90.581667)
		(end 138.182604 -90.870786)
		(width 0.0889)
		(layer "B.Cu")
		(net "P3E_CPU1_PE3_MP_TXN<13>")
	)
	(arc
		(start 127.72644 -102.282498)
		(mid 127.509481 -101.489298)
		(end 127.709676 -100.691696)
		(width 0.0889)
		(layer "B.Cu")
		(net "P3E_CPU1_PE3_MP_TXN<13>")
	)
	(arc
		(start 129.955544 -89.489788)
		(mid 130.149394 -89.433438)
		(end 130.291078 -89.289636)
		(width 0.0889)
		(layer "B.Cu")
		(net "P3E_CPU1_PE3_MP_TXN<13>")
	)
	(arc
		(start 127.715518 -94.33814)
		(mid 127.636387 -94.042738)
		(end 127.715518 -93.747336)
		(width 0.0889)
		(layer "B.Cu")
		(net "P3E_CPU1_PE3_MP_TXN<13>")
	)
	(arc
		(start 133.38937 -87.508588)
		(mid 133.58322 -87.452238)
		(end 133.724904 -87.308436)
		(width 0.0889)
		(layer "B.Cu")
		(net "P3E_CPU1_PE3_MP_TXN<13>")
	)
	(arc
		(start 135.116824 -86.517988)
		(mid 135.400041 -86.602269)
		(end 135.607044 -86.813136)
		(width 0.0889)
		(layer "B.Cu")
		(net "P3E_CPU1_PE3_MP_TXN<13>")
	)
	(arc
		(start 134.2517 -87.013034)
		(mid 134.443342 -86.955868)
		(end 134.583424 -86.813136)
		(width 0.0889)
		(layer "B.Cu")
		(net "P3E_CPU1_PE3_MP_TXN<13>")
	)
	(arc
		(start 127.715518 -95.328486)
		(mid 127.636296 -95.039368)
		(end 127.709168 -94.748604)
		(width 0.0889)
		(layer "B.Cu")
		(net "P3E_CPU1_PE3_MP_TXN<13>")
	)
	(arc
		(start 127.715518 -93.747336)
		(mid 127.768988 -93.552273)
		(end 127.720344 -93.355922)
		(width 0.0889)
		(layer "B.Cu")
		(net "P3E_CPU1_PE3_MP_TXN<13>")
	)
	(arc
		(start 131.661408 -88.499188)
		(mid 131.858569 -88.447229)
		(end 132.004562 -88.304878)
		(width 0.0889)
		(layer "B.Cu")
		(net "P3E_CPU1_PE3_MP_TXN<13>")
	)
	(arc
		(start 131.149598 -88.794336)
		(mid 131.356602 -88.583472)
		(end 131.639818 -88.499188)
		(width 0.0889)
		(layer "B.Cu")
		(net "P3E_CPU1_PE3_MP_TXN<13>")
	)
	(arc
		(start 129.100834 -89.984834)
		(mid 129.292476 -89.927668)
		(end 129.432558 -89.784936)
		(width 0.0889)
		(layer "B.Cu")
		(net "P3E_CPU1_PE3_MP_TXN<13>")
	)
	(arc
		(start 127.715518 -96.719136)
		(mid 127.768988 -96.524073)
		(end 127.720344 -96.327722)
		(width 0.0889)
		(layer "B.Cu")
		(net "P3E_CPU1_PE3_MP_TXN<13>")
	)
	(arc
		(start 127.709168 -99.280218)
		(mid 127.63637 -98.989455)
		(end 127.715518 -98.700336)
		(width 0.0889)
		(layer "B.Cu")
		(net "P3E_CPU1_PE3_MP_TXN<13>")
	)
	(arc
		(start 132.866384 -87.803736)
		(mid 133.073388 -87.592872)
		(end 133.356604 -87.508588)
		(width 0.0889)
		(layer "B.Cu")
		(net "P3E_CPU1_PE3_MP_TXN<13>")
	)
	(arc
		(start 127.715518 -97.709736)
		(mid 127.768988 -97.514673)
		(end 127.720344 -97.318322)
		(width 0.0889)
		(layer "B.Cu")
		(net "P3E_CPU1_PE3_MP_TXN<13>")
	)
	(arc
		(start 133.724904 -87.308436)
		(mid 133.933512 -87.096504)
		(end 134.218934 -87.013034)
		(width 0.0889)
		(layer "B.Cu")
		(net "P3E_CPU1_PE3_MP_TXN<13>")
	)
	(arc
		(start 138.182604 -88.889586)
		(mid 138.129134 -89.084649)
		(end 138.177778 -89.281)
		(width 0.0889)
		(layer "B.Cu")
		(net "P3E_CPU1_PE3_MP_TXN<13>")
	)
	(segment
		(start 137.957814 -95.033084)
		(end 138.529314 -95.033084)
		(width 0.1143)
		(layer "F.Cu")
		(net "P3E_CPU1_PE3_MP_TXN<12>")
	)
	(via
		(at 138.529314 -95.033084)
		(size 0.508)
		(drill 0.254)
		(layers "F.Cu" "B.Cu")
		(net "P3E_CPU1_PE3_MP_TXN<12>")
	)
	(via
		(at 25.472898 -108.327952)
		(size 0.508)
		(drill 0.254)
		(layers "F.Cu" "B.Cu")
		(net "P3E_CPU1_PE3_MP_TXN<12>")
	)
	(segment
		(start 119.367808 -106.351578)
		(end 120.21947 -106.18216)
		(width 0.1143)
		(layer "B.Cu")
		(net "P3E_CPU1_PE3_MP_TXN<12>")
	)
	(segment
		(start 102.020878 -106.97464)
		(end 102.610158 -106.856784)
		(width 0.1143)
		(layer "B.Cu")
		(net "P3E_CPU1_PE3_MP_TXN<12>")
	)
	(segment
		(start 125.133608 -97.225104)
		(end 125.139958 -97.214436)
		(width 0.0889)
		(layer "B.Cu")
		(net "P3E_CPU1_PE3_MP_TXN<12>")
	)
	(segment
		(start 127.351028 -88.003634)
		(end 127.383794 -88.003634)
		(width 0.0889)
		(layer "B.Cu")
		(net "P3E_CPU1_PE3_MP_TXN<12>")
	)
	(segment
		(start 125.133608 -92.272104)
		(end 125.139958 -92.261436)
		(width 0.0889)
		(layer "B.Cu")
		(net "P3E_CPU1_PE3_MP_TXN<12>")
	)
	(segment
		(start 83.880452 -104.357932)
		(end 87.738966 -105.131362)
		(width 0.1143)
		(layer "B.Cu")
		(net "P3E_CPU1_PE3_MP_TXN<12>")
	)
	(segment
		(start 132.004562 -85.333078)
		(end 132.007864 -85.327236)
		(width 0.0889)
		(layer "B.Cu")
		(net "P3E_CPU1_PE3_MP_TXN<12>")
	)
	(segment
		(start 113.853468 -107.331764)
		(end 113.987834 -107.42168)
		(width 0.1143)
		(layer "B.Cu")
		(net "P3E_CPU1_PE3_MP_TXN<12>")
	)
	(segment
		(start 25.472898 -108.327952)
		(end 24.562308 -107.417616)
		(width 0.1143)
		(layer "B.Cu")
		(net "P3E_CPU1_PE3_MP_TXN<12>")
	)
	(segment
		(start 140.758164 -87.403686)
		(end 140.753338 -87.412322)
		(width 0.0889)
		(layer "B.Cu")
		(net "P3E_CPU1_PE3_MP_TXN<12>")
	)
	(segment
		(start 120.602248 -106.131614)
		(end 123.726448 -103.007414)
		(width 0.0889)
		(layer "B.Cu")
		(net "P3E_CPU1_PE3_MP_TXN<12>")
	)
	(segment
		(start 124.36856 -103.007414)
		(end 125.191774 -102.1842)
		(width 0.0889)
		(layer "B.Cu")
		(net "P3E_CPU1_PE3_MP_TXN<12>")
	)
	(segment
		(start 131.639818 -85.527388)
		(end 131.661408 -85.527388)
		(width 0.0889)
		(layer "B.Cu")
		(net "P3E_CPU1_PE3_MP_TXN<12>")
	)
	(segment
		(start 125.139958 -99.195636)
		(end 125.144784 -99.187)
		(width 0.0889)
		(layer "B.Cu")
		(net "P3E_CPU1_PE3_MP_TXN<12>")
	)
	(segment
		(start 113.427256 -107.533186)
		(end 113.517172 -107.39882)
		(width 0.1143)
		(layer "B.Cu")
		(net "P3E_CPU1_PE3_MP_TXN<12>")
	)
	(segment
		(start 109.125258 -106.807)
		(end 113.09096 -107.599988)
		(width 0.1143)
		(layer "B.Cu")
		(net "P3E_CPU1_PE3_MP_TXN<12>")
	)
	(segment
		(start 138.83894 -94.545912)
		(end 138.782298 -94.58071)
		(width 0.0889)
		(layer "B.Cu")
		(net "P3E_CPU1_PE3_MP_TXN<12>")
	)
	(segment
		(start 30.7594 -111.387636)
		(end 30.761432 -111.388398)
		(width 0.1143)
		(layer "B.Cu")
		(net "P3E_CPU1_PE3_MP_TXN<12>")
	)
	(segment
		(start 125.139958 -98.205036)
		(end 125.144784 -98.1964)
		(width 0.0889)
		(layer "B.Cu")
		(net "P3E_CPU1_PE3_MP_TXN<12>")
	)
	(segment
		(start 30.778704 -111.395764)
		(end 32.585914 -112.144556)
		(width 0.1143)
		(layer "B.Cu")
		(net "P3E_CPU1_PE3_MP_TXN<12>")
	)
	(segment
		(start 30.773624 -111.393732)
		(end 30.774894 -111.39424)
		(width 0.1143)
		(layer "B.Cu")
		(net "P3E_CPU1_PE3_MP_TXN<12>")
	)
	(segment
		(start 140.758164 -88.394286)
		(end 140.753338 -88.402922)
		(width 0.0889)
		(layer "B.Cu")
		(net "P3E_CPU1_PE3_MP_TXN<12>")
	)
	(segment
		(start 125.139958 -92.261436)
		(end 125.144784 -92.2528)
		(width 0.0889)
		(layer "B.Cu")
		(net "P3E_CPU1_PE3_MP_TXN<12>")
	)
	(segment
		(start 125.139958 -93.252036)
		(end 125.144784 -93.2434)
		(width 0.0889)
		(layer "B.Cu")
		(net "P3E_CPU1_PE3_MP_TXN<12>")
	)
	(segment
		(start 115.781582 -107.06481)
		(end 116.117878 -106.998008)
		(width 0.1143)
		(layer "B.Cu")
		(net "P3E_CPU1_PE3_MP_TXN<12>")
	)
	(segment
		(start 114.750342 -107.153456)
		(end 114.884708 -107.243118)
		(width 0.1143)
		(layer "B.Cu")
		(net "P3E_CPU1_PE3_MP_TXN<12>")
	)
	(segment
		(start 116.20754 -106.863642)
		(end 116.543836 -106.796586)
		(width 0.1143)
		(layer "B.Cu")
		(net "P3E_CPU1_PE3_MP_TXN<12>")
	)
	(segment
		(start 125.133608 -98.215704)
		(end 125.139958 -98.205036)
		(width 0.0889)
		(layer "B.Cu")
		(net "P3E_CPU1_PE3_MP_TXN<12>")
	)
	(segment
		(start 140.264134 -93.642688)
		(end 140.231368 -93.642688)
		(width 0.0889)
		(layer "B.Cu")
		(net "P3E_CPU1_PE3_MP_TXN<12>")
	)
	(segment
		(start 120.21947 -106.18216)
		(end 120.24106 -106.177842)
		(width 0.0889)
		(layer "B.Cu")
		(net "P3E_CPU1_PE3_MP_TXN<12>")
	)
	(segment
		(start 125.139958 -90.280236)
		(end 125.144784 -90.2716)
		(width 0.0889)
		(layer "B.Cu")
		(net "P3E_CPU1_PE3_MP_TXN<12>")
	)
	(segment
		(start 101.550216 -106.952288)
		(end 101.886512 -106.884978)
		(width 0.1143)
		(layer "B.Cu")
		(net "P3E_CPU1_PE3_MP_TXN<12>")
	)
	(segment
		(start 101.886512 -106.884978)
		(end 102.020878 -106.97464)
		(width 0.1143)
		(layer "B.Cu")
		(net "P3E_CPU1_PE3_MP_TXN<12>")
	)
	(segment
		(start 15.748 -100.5078)
		(end 15.182342 -99.942142)
		(width 0.1143)
		(layer "B.Cu")
		(net "P3E_CPU1_PE3_MP_TXN<12>")
	)
	(segment
		(start 30.761432 -111.388398)
		(end 30.773624 -111.393732)
		(width 0.1143)
		(layer "B.Cu")
		(net "P3E_CPU1_PE3_MP_TXN<12>")
	)
	(segment
		(start 113.09096 -107.599988)
		(end 113.427256 -107.533186)
		(width 0.1143)
		(layer "B.Cu")
		(net "P3E_CPU1_PE3_MP_TXN<12>")
	)
	(segment
		(start 125.139958 -94.242636)
		(end 125.144784 -94.234)
		(width 0.0889)
		(layer "B.Cu")
		(net "P3E_CPU1_PE3_MP_TXN<12>")
	)
	(segment
		(start 140.764514 -87.393018)
		(end 140.758164 -87.403686)
		(width 0.0889)
		(layer "B.Cu")
		(net "P3E_CPU1_PE3_MP_TXN<12>")
	)
	(segment
		(start 125.133608 -91.281504)
		(end 125.139958 -91.270836)
		(width 0.0889)
		(layer "B.Cu")
		(net "P3E_CPU1_PE3_MP_TXN<12>")
	)
	(segment
		(start 139.400788 -94.137988)
		(end 139.376658 -94.137988)
		(width 0.0889)
		(layer "B.Cu")
		(net "P3E_CPU1_PE3_MP_TXN<12>")
	)
	(segment
		(start 132.501894 -85.031834)
		(end 132.53466 -85.031834)
		(width 0.0889)
		(layer "B.Cu")
		(net "P3E_CPU1_PE3_MP_TXN<12>")
	)
	(segment
		(start 24.562308 -106.675174)
		(end 22.94001 -105.052876)
		(width 0.1143)
		(layer "B.Cu")
		(net "P3E_CPU1_PE3_MP_TXN<12>")
	)
	(segment
		(start 101.460554 -107.086654)
		(end 101.550216 -106.952288)
		(width 0.1143)
		(layer "B.Cu")
		(net "P3E_CPU1_PE3_MP_TXN<12>")
	)
	(segment
		(start 125.133608 -96.234504)
		(end 125.139958 -96.223836)
		(width 0.0889)
		(layer "B.Cu")
		(net "P3E_CPU1_PE3_MP_TXN<12>")
	)
	(segment
		(start 125.133608 -93.262704)
		(end 125.139958 -93.252036)
		(width 0.0889)
		(layer "B.Cu")
		(net "P3E_CPU1_PE3_MP_TXN<12>")
	)
	(segment
		(start 138.518138 -85.527388)
		(end 138.550904 -85.527388)
		(width 0.0889)
		(layer "B.Cu")
		(net "P3E_CPU1_PE3_MP_TXN<12>")
	)
	(segment
		(start 101.124258 -107.153964)
		(end 101.460554 -107.086654)
		(width 0.1143)
		(layer "B.Cu")
		(net "P3E_CPU1_PE3_MP_TXN<12>")
	)
	(segment
		(start 116.543836 -106.796586)
		(end 116.678202 -106.886502)
		(width 0.1143)
		(layer "B.Cu")
		(net "P3E_CPU1_PE3_MP_TXN<12>")
	)
	(segment
		(start 113.517172 -107.39882)
		(end 113.853468 -107.331764)
		(width 0.1143)
		(layer "B.Cu")
		(net "P3E_CPU1_PE3_MP_TXN<12>")
	)
	(segment
		(start 140.839698 -90.144346)
		(end 140.839698 -92.052648)
		(width 0.0889)
		(layer "B.Cu")
		(net "P3E_CPU1_PE3_MP_TXN<12>")
	)
	(segment
		(start 125.139958 -100.186236)
		(end 125.144784 -100.1776)
		(width 0.0889)
		(layer "B.Cu")
		(net "P3E_CPU1_PE3_MP_TXN<12>")
	)
	(segment
		(start 115.646962 -106.975148)
		(end 115.781582 -107.06481)
		(width 0.1143)
		(layer "B.Cu")
		(net "P3E_CPU1_PE3_MP_TXN<12>")
	)
	(segment
		(start 14.372082 -99.942142)
		(end 14.00302 -99.57308)
		(width 0.1143)
		(layer "B.Cu")
		(net "P3E_CPU1_PE3_MP_TXN<12>")
	)
	(segment
		(start 126.488698 -88.499188)
		(end 126.521464 -88.499188)
		(width 0.0889)
		(layer "B.Cu")
		(net "P3E_CPU1_PE3_MP_TXN<12>")
	)
	(segment
		(start 30.774894 -111.39424)
		(end 30.77591 -111.394748)
		(width 0.1143)
		(layer "B.Cu")
		(net "P3E_CPU1_PE3_MP_TXN<12>")
	)
	(segment
		(start 53.246274 -110.480602)
		(end 83.880452 -104.357932)
		(width 0.1143)
		(layer "B.Cu")
		(net "P3E_CPU1_PE3_MP_TXN<12>")
	)
	(segment
		(start 15.748 -101.0666)
		(end 15.748 -100.5078)
		(width 0.1143)
		(layer "B.Cu")
		(net "P3E_CPU1_PE3_MP_TXN<12>")
	)
	(segment
		(start 118.897146 -106.328718)
		(end 119.233442 -106.261662)
		(width 0.1143)
		(layer "B.Cu")
		(net "P3E_CPU1_PE3_MP_TXN<12>")
	)
	(segment
		(start 125.191774 -102.1842)
		(end 125.191774 -101.857302)
		(width 0.0889)
		(layer "B.Cu")
		(net "P3E_CPU1_PE3_MP_TXN<12>")
	)
	(segment
		(start 115.310666 -107.04195)
		(end 115.646962 -106.975148)
		(width 0.1143)
		(layer "B.Cu")
		(net "P3E_CPU1_PE3_MP_TXN<12>")
	)
	(segment
		(start 116.117878 -106.998008)
		(end 116.20754 -106.863642)
		(width 0.1143)
		(layer "B.Cu")
		(net "P3E_CPU1_PE3_MP_TXN<12>")
	)
	(segment
		(start 120.24106 -106.177842)
		(end 120.27027 -106.197654)
		(width 0.0889)
		(layer "B.Cu")
		(net "P3E_CPU1_PE3_MP_TXN<12>")
	)
	(segment
		(start 129.922778 -86.517988)
		(end 129.955544 -86.517988)
		(width 0.0889)
		(layer "B.Cu")
		(net "P3E_CPU1_PE3_MP_TXN<12>")
	)
	(segment
		(start 116.678202 -106.886502)
		(end 117.91061 -106.641392)
		(width 0.1143)
		(layer "B.Cu")
		(net "P3E_CPU1_PE3_MP_TXN<12>")
	)
	(segment
		(start 125.139958 -97.214436)
		(end 125.144784 -97.2058)
		(width 0.0889)
		(layer "B.Cu")
		(net "P3E_CPU1_PE3_MP_TXN<12>")
	)
	(segment
		(start 22.306788 -103.524812)
		(end 20.47113 -101.6889)
		(width 0.1143)
		(layer "B.Cu")
		(net "P3E_CPU1_PE3_MP_TXN<12>")
	)
	(segment
		(start 19.3675 -101.6889)
		(end 19.12112 -101.44252)
		(width 0.1143)
		(layer "B.Cu")
		(net "P3E_CPU1_PE3_MP_TXN<12>")
	)
	(segment
		(start 16.12392 -101.44252)
		(end 15.748 -101.0666)
		(width 0.1143)
		(layer "B.Cu")
		(net "P3E_CPU1_PE3_MP_TXN<12>")
	)
	(segment
		(start 20.47113 -101.6889)
		(end 19.3675 -101.6889)
		(width 0.1143)
		(layer "B.Cu")
		(net "P3E_CPU1_PE3_MP_TXN<12>")
	)
	(segment
		(start 125.191774 -101.857302)
		(end 125.139958 -101.767386)
		(width 0.0889)
		(layer "B.Cu")
		(net "P3E_CPU1_PE3_MP_TXN<12>")
	)
	(segment
		(start 29.798772 -110.571026)
		(end 30.7594 -111.387636)
		(width 0.1143)
		(layer "B.Cu")
		(net "P3E_CPU1_PE3_MP_TXN<12>")
	)
	(segment
		(start 102.610158 -106.856784)
		(end 105.743756 -107.483656)
		(width 0.1143)
		(layer "B.Cu")
		(net "P3E_CPU1_PE3_MP_TXN<12>")
	)
	(segment
		(start 118.470934 -106.529886)
		(end 118.80723 -106.463084)
		(width 0.1143)
		(layer "B.Cu")
		(net "P3E_CPU1_PE3_MP_TXN<12>")
	)
	(segment
		(start 125.139958 -94.833186)
		(end 125.133608 -94.822518)
		(width 0.0889)
		(layer "B.Cu")
		(net "P3E_CPU1_PE3_MP_TXN<12>")
	)
	(segment
		(start 134.218934 -84.041234)
		(end 134.2517 -84.041234)
		(width 0.0889)
		(layer "B.Cu")
		(net "P3E_CPU1_PE3_MP_TXN<12>")
	)
	(segment
		(start 137.655808 -85.031834)
		(end 137.688574 -85.031834)
		(width 0.0889)
		(layer "B.Cu")
		(net "P3E_CPU1_PE3_MP_TXN<12>")
	)
	(segment
		(start 118.000272 -106.507026)
		(end 118.336568 -106.440224)
		(width 0.1143)
		(layer "B.Cu")
		(net "P3E_CPU1_PE3_MP_TXN<12>")
	)
	(segment
		(start 115.221004 -107.176316)
		(end 115.310666 -107.04195)
		(width 0.1143)
		(layer "B.Cu")
		(net "P3E_CPU1_PE3_MP_TXN<12>")
	)
	(segment
		(start 139.372848 -86.022434)
		(end 139.405614 -86.022434)
		(width 0.0889)
		(layer "B.Cu")
		(net "P3E_CPU1_PE3_MP_TXN<12>")
	)
	(segment
		(start 140.235178 -86.517988)
		(end 140.267944 -86.517988)
		(width 0.0889)
		(layer "B.Cu")
		(net "P3E_CPU1_PE3_MP_TXN<12>")
	)
	(segment
		(start 118.80723 -106.463084)
		(end 118.897146 -106.328718)
		(width 0.1143)
		(layer "B.Cu")
		(net "P3E_CPU1_PE3_MP_TXN<12>")
	)
	(segment
		(start 118.336568 -106.440224)
		(end 118.470934 -106.529886)
		(width 0.1143)
		(layer "B.Cu")
		(net "P3E_CPU1_PE3_MP_TXN<12>")
	)
	(segment
		(start 140.764514 -88.383618)
		(end 140.758164 -88.394286)
		(width 0.0889)
		(layer "B.Cu")
		(net "P3E_CPU1_PE3_MP_TXN<12>")
	)
	(segment
		(start 22.94001 -105.052876)
		(end 22.306788 -103.524812)
		(width 0.1143)
		(layer "B.Cu")
		(net "P3E_CPU1_PE3_MP_TXN<12>")
	)
	(segment
		(start 130.785108 -86.022434)
		(end 130.817874 -86.022434)
		(width 0.0889)
		(layer "B.Cu")
		(net "P3E_CPU1_PE3_MP_TXN<12>")
	)
	(segment
		(start 135.073644 -83.546188)
		(end 135.116824 -83.546188)
		(width 0.0889)
		(layer "B.Cu")
		(net "P3E_CPU1_PE3_MP_TXN<12>")
	)
	(segment
		(start 114.413792 -107.220258)
		(end 114.750342 -107.153456)
		(width 0.1143)
		(layer "B.Cu")
		(net "P3E_CPU1_PE3_MP_TXN<12>")
	)
	(segment
		(start 120.271032 -106.1974)
		(end 120.602248 -106.131614)
		(width 0.0889)
		(layer "B.Cu")
		(net "P3E_CPU1_PE3_MP_TXN<12>")
	)
	(segment
		(start 128.205738 -87.508588)
		(end 128.238504 -87.508588)
		(width 0.0889)
		(layer "B.Cu")
		(net "P3E_CPU1_PE3_MP_TXN<12>")
	)
	(segment
		(start 100.989892 -107.064302)
		(end 101.124258 -107.153964)
		(width 0.1143)
		(layer "B.Cu")
		(net "P3E_CPU1_PE3_MP_TXN<12>")
	)
	(segment
		(start 136.801098 -84.536788)
		(end 136.833864 -84.536788)
		(width 0.0889)
		(layer "B.Cu")
		(net "P3E_CPU1_PE3_MP_TXN<12>")
	)
	(segment
		(start 114.884708 -107.243118)
		(end 115.221004 -107.176316)
		(width 0.1143)
		(layer "B.Cu")
		(net "P3E_CPU1_PE3_MP_TXN<12>")
	)
	(segment
		(start 125.139958 -100.776786)
		(end 125.133608 -100.766118)
		(width 0.0889)
		(layer "B.Cu")
		(net "P3E_CPU1_PE3_MP_TXN<12>")
	)
	(segment
		(start 30.77591 -111.394748)
		(end 30.778704 -111.395764)
		(width 0.1143)
		(layer "B.Cu")
		(net "P3E_CPU1_PE3_MP_TXN<12>")
	)
	(segment
		(start 89.198958 -106.104944)
		(end 97.78492 -107.82173)
		(width 0.1143)
		(layer "B.Cu")
		(net "P3E_CPU1_PE3_MP_TXN<12>")
	)
	(segment
		(start 117.91061 -106.641392)
		(end 118.000272 -106.507026)
		(width 0.1143)
		(layer "B.Cu")
		(net "P3E_CPU1_PE3_MP_TXN<12>")
	)
	(segment
		(start 125.139958 -96.223836)
		(end 125.144784 -96.2152)
		(width 0.0889)
		(layer "B.Cu")
		(net "P3E_CPU1_PE3_MP_TXN<12>")
	)
	(segment
		(start 24.562308 -107.417616)
		(end 24.562308 -106.675174)
		(width 0.1143)
		(layer "B.Cu")
		(net "P3E_CPU1_PE3_MP_TXN<12>")
	)
	(segment
		(start 87.738966 -105.131362)
		(end 89.198958 -106.104944)
		(width 0.1143)
		(layer "B.Cu")
		(net "P3E_CPU1_PE3_MP_TXN<12>")
	)
	(segment
		(start 125.633988 -88.994234)
		(end 125.666754 -88.994234)
		(width 0.0889)
		(layer "B.Cu")
		(net "P3E_CPU1_PE3_MP_TXN<12>")
	)
	(segment
		(start 100.563934 -107.265978)
		(end 100.653596 -107.131612)
		(width 0.1143)
		(layer "B.Cu")
		(net "P3E_CPU1_PE3_MP_TXN<12>")
	)
	(segment
		(start 125.133608 -99.206304)
		(end 125.139958 -99.195636)
		(width 0.0889)
		(layer "B.Cu")
		(net "P3E_CPU1_PE3_MP_TXN<12>")
	)
	(segment
		(start 100.653596 -107.131612)
		(end 100.989892 -107.064302)
		(width 0.1143)
		(layer "B.Cu")
		(net "P3E_CPU1_PE3_MP_TXN<12>")
	)
	(segment
		(start 119.233442 -106.261662)
		(end 119.367808 -106.351578)
		(width 0.1143)
		(layer "B.Cu")
		(net "P3E_CPU1_PE3_MP_TXN<12>")
	)
	(segment
		(start 113.987834 -107.42168)
		(end 114.32413 -107.354624)
		(width 0.1143)
		(layer "B.Cu")
		(net "P3E_CPU1_PE3_MP_TXN<12>")
	)
	(segment
		(start 25.472898 -108.327952)
		(end 27.171396 -110.025688)
		(width 0.1143)
		(layer "B.Cu")
		(net "P3E_CPU1_PE3_MP_TXN<12>")
	)
	(segment
		(start 123.726448 -103.007414)
		(end 124.36856 -103.007414)
		(width 0.0889)
		(layer "B.Cu")
		(net "P3E_CPU1_PE3_MP_TXN<12>")
	)
	(segment
		(start 125.133608 -90.290904)
		(end 125.139958 -90.280236)
		(width 0.0889)
		(layer "B.Cu")
		(net "P3E_CPU1_PE3_MP_TXN<12>")
	)
	(segment
		(start 120.27027 -106.197654)
		(end 120.271032 -106.1974)
		(width 0.0889)
		(layer "B.Cu")
		(net "P3E_CPU1_PE3_MP_TXN<12>")
	)
	(segment
		(start 125.139958 -91.270836)
		(end 125.144784 -91.2622)
		(width 0.0889)
		(layer "B.Cu")
		(net "P3E_CPU1_PE3_MP_TXN<12>")
	)
	(segment
		(start 97.78492 -107.82173)
		(end 100.563934 -107.265978)
		(width 0.1143)
		(layer "B.Cu")
		(net "P3E_CPU1_PE3_MP_TXN<12>")
	)
	(segment
		(start 114.32413 -107.354624)
		(end 114.413792 -107.220258)
		(width 0.1143)
		(layer "B.Cu")
		(net "P3E_CPU1_PE3_MP_TXN<12>")
	)
	(segment
		(start 129.068068 -87.013034)
		(end 129.100834 -87.013034)
		(width 0.0889)
		(layer "B.Cu")
		(net "P3E_CPU1_PE3_MP_TXN<12>")
	)
	(segment
		(start 133.356604 -84.536788)
		(end 133.38937 -84.536788)
		(width 0.0889)
		(layer "B.Cu")
		(net "P3E_CPU1_PE3_MP_TXN<12>")
	)
	(segment
		(start 15.182342 -99.942142)
		(end 14.372082 -99.942142)
		(width 0.1143)
		(layer "B.Cu")
		(net "P3E_CPU1_PE3_MP_TXN<12>")
	)
	(segment
		(start 135.938768 -84.041234)
		(end 135.971534 -84.041234)
		(width 0.0889)
		(layer "B.Cu")
		(net "P3E_CPU1_PE3_MP_TXN<12>")
	)
	(segment
		(start 105.743756 -107.483656)
		(end 109.125258 -106.807)
		(width 0.1143)
		(layer "B.Cu")
		(net "P3E_CPU1_PE3_MP_TXN<12>")
	)
	(segment
		(start 32.585914 -112.144556)
		(end 36.354258 -112.144556)
		(width 0.1143)
		(layer "B.Cu")
		(net "P3E_CPU1_PE3_MP_TXN<12>")
	)
	(segment
		(start 36.354258 -112.144556)
		(end 53.246274 -110.480602)
		(width 0.1143)
		(layer "B.Cu")
		(net "P3E_CPU1_PE3_MP_TXN<12>")
	)
	(segment
		(start 19.12112 -101.44252)
		(end 16.12392 -101.44252)
		(width 0.1143)
		(layer "B.Cu")
		(net "P3E_CPU1_PE3_MP_TXN<12>")
	)
	(segment
		(start 27.171396 -110.025688)
		(end 29.798772 -110.571026)
		(width 0.1143)
		(layer "B.Cu")
		(net "P3E_CPU1_PE3_MP_TXN<12>")
	)
	(arc
		(start 128.574038 -87.308436)
		(mid 128.782646 -87.096504)
		(end 129.068068 -87.013034)
		(width 0.0889)
		(layer "B.Cu")
		(net "P3E_CPU1_PE3_MP_TXN<12>")
	)
	(arc
		(start 128.238504 -87.508588)
		(mid 128.432354 -87.452238)
		(end 128.574038 -87.308436)
		(width 0.0889)
		(layer "B.Cu")
		(net "P3E_CPU1_PE3_MP_TXN<12>")
	)
	(arc
		(start 125.139958 -96.814386)
		(mid 125.060736 -96.525268)
		(end 125.133608 -96.234504)
		(width 0.0889)
		(layer "B.Cu")
		(net "P3E_CPU1_PE3_MP_TXN<12>")
	)
	(arc
		(start 125.139958 -98.795586)
		(mid 125.060736 -98.506468)
		(end 125.133608 -98.215704)
		(width 0.0889)
		(layer "B.Cu")
		(net "P3E_CPU1_PE3_MP_TXN<12>")
	)
	(arc
		(start 140.267944 -86.517988)
		(mid 140.760334 -86.816921)
		(end 140.764514 -87.393018)
		(width 0.0889)
		(layer "B.Cu")
		(net "P3E_CPU1_PE3_MP_TXN<12>")
	)
	(arc
		(start 125.139958 -101.767386)
		(mid 125.060827 -101.471984)
		(end 125.139958 -101.176582)
		(width 0.0889)
		(layer "B.Cu")
		(net "P3E_CPU1_PE3_MP_TXN<12>")
	)
	(arc
		(start 138.782298 -94.58071)
		(mid 138.596826 -94.77392)
		(end 138.529314 -95.033084)
		(width 0.0889)
		(layer "B.Cu")
		(net "P3E_CPU1_PE3_MP_TXN<12>")
	)
	(arc
		(start 140.753338 -87.412322)
		(mid 140.704583 -87.608674)
		(end 140.758164 -87.803736)
		(width 0.0889)
		(layer "B.Cu")
		(net "P3E_CPU1_PE3_MP_TXN<12>")
	)
	(arc
		(start 140.842238 -90.100404)
		(mid 140.841374 -90.122398)
		(end 140.839698 -90.144346)
		(width 0.0889)
		(layer "B.Cu")
		(net "P3E_CPU1_PE3_MP_TXN<12>")
	)
	(arc
		(start 140.758164 -87.803736)
		(mid 140.837386 -88.092854)
		(end 140.764514 -88.383618)
		(width 0.0889)
		(layer "B.Cu")
		(net "P3E_CPU1_PE3_MP_TXN<12>")
	)
	(arc
		(start 125.139958 -95.232982)
		(mid 125.193457 -95.033084)
		(end 125.139958 -94.833186)
		(width 0.0889)
		(layer "B.Cu")
		(net "P3E_CPU1_PE3_MP_TXN<12>")
	)
	(arc
		(start 135.116824 -83.546188)
		(mid 135.400041 -83.630469)
		(end 135.607044 -83.841336)
		(width 0.0889)
		(layer "B.Cu")
		(net "P3E_CPU1_PE3_MP_TXN<12>")
	)
	(arc
		(start 125.139958 -93.842586)
		(mid 125.060736 -93.553468)
		(end 125.133608 -93.262704)
		(width 0.0889)
		(layer "B.Cu")
		(net "P3E_CPU1_PE3_MP_TXN<12>")
	)
	(arc
		(start 140.758164 -92.756736)
		(mid 140.762493 -93.339908)
		(end 140.264134 -93.642688)
		(width 0.0889)
		(layer "B.Cu")
		(net "P3E_CPU1_PE3_MP_TXN<12>")
	)
	(arc
		(start 135.971534 -84.041234)
		(mid 136.256958 -84.124701)
		(end 136.465564 -84.336636)
		(width 0.0889)
		(layer "B.Cu")
		(net "P3E_CPU1_PE3_MP_TXN<12>")
	)
	(arc
		(start 129.955544 -86.517988)
		(mid 130.149394 -86.461638)
		(end 130.291078 -86.317836)
		(width 0.0889)
		(layer "B.Cu")
		(net "P3E_CPU1_PE3_MP_TXN<12>")
	)
	(arc
		(start 125.144784 -98.1964)
		(mid 125.193539 -98.000048)
		(end 125.139958 -97.804986)
		(width 0.0889)
		(layer "B.Cu")
		(net "P3E_CPU1_PE3_MP_TXN<12>")
	)
	(arc
		(start 130.291078 -86.317836)
		(mid 130.499686 -86.105904)
		(end 130.785108 -86.022434)
		(width 0.0889)
		(layer "B.Cu")
		(net "P3E_CPU1_PE3_MP_TXN<12>")
	)
	(arc
		(start 137.324084 -84.831936)
		(mid 137.464163 -84.974672)
		(end 137.655808 -85.031834)
		(width 0.0889)
		(layer "B.Cu")
		(net "P3E_CPU1_PE3_MP_TXN<12>")
	)
	(arc
		(start 136.465564 -84.336636)
		(mid 136.607247 -84.48044)
		(end 136.801098 -84.536788)
		(width 0.0889)
		(layer "B.Cu")
		(net "P3E_CPU1_PE3_MP_TXN<12>")
	)
	(arc
		(start 126.856998 -88.299036)
		(mid 127.065606 -88.087104)
		(end 127.351028 -88.003634)
		(width 0.0889)
		(layer "B.Cu")
		(net "P3E_CPU1_PE3_MP_TXN<12>")
	)
	(arc
		(start 125.139958 -97.804986)
		(mid 125.060736 -97.515868)
		(end 125.133608 -97.225104)
		(width 0.0889)
		(layer "B.Cu")
		(net "P3E_CPU1_PE3_MP_TXN<12>")
	)
	(arc
		(start 125.139958 -101.176582)
		(mid 125.193457 -100.976684)
		(end 125.139958 -100.776786)
		(width 0.0889)
		(layer "B.Cu")
		(net "P3E_CPU1_PE3_MP_TXN<12>")
	)
	(arc
		(start 125.144784 -91.2622)
		(mid 125.193539 -91.065848)
		(end 125.139958 -90.870786)
		(width 0.0889)
		(layer "B.Cu")
		(net "P3E_CPU1_PE3_MP_TXN<12>")
	)
	(arc
		(start 125.144784 -94.234)
		(mid 125.193539 -94.037648)
		(end 125.139958 -93.842586)
		(width 0.0889)
		(layer "B.Cu")
		(net "P3E_CPU1_PE3_MP_TXN<12>")
	)
	(arc
		(start 125.144784 -93.2434)
		(mid 125.193539 -93.047048)
		(end 125.139958 -92.851986)
		(width 0.0889)
		(layer "B.Cu")
		(net "P3E_CPU1_PE3_MP_TXN<12>")
	)
	(arc
		(start 140.758164 -89.38514)
		(mid 140.704665 -89.585038)
		(end 140.758164 -89.784936)
		(width 0.0889)
		(layer "B.Cu")
		(net "P3E_CPU1_PE3_MP_TXN<12>")
	)
	(arc
		(start 125.144784 -90.2716)
		(mid 125.193539 -90.075248)
		(end 125.139958 -89.880186)
		(width 0.0889)
		(layer "B.Cu")
		(net "P3E_CPU1_PE3_MP_TXN<12>")
	)
	(arc
		(start 125.666754 -88.994234)
		(mid 125.858396 -88.937068)
		(end 125.998478 -88.794336)
		(width 0.0889)
		(layer "B.Cu")
		(net "P3E_CPU1_PE3_MP_TXN<12>")
	)
	(arc
		(start 125.144784 -100.1776)
		(mid 125.193539 -99.981248)
		(end 125.139958 -99.786186)
		(width 0.0889)
		(layer "B.Cu")
		(net "P3E_CPU1_PE3_MP_TXN<12>")
	)
	(arc
		(start 129.432558 -86.813136)
		(mid 129.639562 -86.602272)
		(end 129.922778 -86.517988)
		(width 0.0889)
		(layer "B.Cu")
		(net "P3E_CPU1_PE3_MP_TXN<12>")
	)
	(arc
		(start 127.715518 -87.803736)
		(mid 127.922522 -87.592872)
		(end 128.205738 -87.508588)
		(width 0.0889)
		(layer "B.Cu")
		(net "P3E_CPU1_PE3_MP_TXN<12>")
	)
	(arc
		(start 125.998478 -88.794336)
		(mid 126.205482 -88.583472)
		(end 126.488698 -88.499188)
		(width 0.0889)
		(layer "B.Cu")
		(net "P3E_CPU1_PE3_MP_TXN<12>")
	)
	(arc
		(start 138.182604 -85.327236)
		(mid 138.324287 -85.47104)
		(end 138.518138 -85.527388)
		(width 0.0889)
		(layer "B.Cu")
		(net "P3E_CPU1_PE3_MP_TXN<12>")
	)
	(arc
		(start 125.139958 -91.861386)
		(mid 125.060736 -91.572268)
		(end 125.133608 -91.281504)
		(width 0.0889)
		(layer "B.Cu")
		(net "P3E_CPU1_PE3_MP_TXN<12>")
	)
	(arc
		(start 132.53466 -85.031834)
		(mid 132.726302 -84.974668)
		(end 132.866384 -84.831936)
		(width 0.0889)
		(layer "B.Cu")
		(net "P3E_CPU1_PE3_MP_TXN<12>")
	)
	(arc
		(start 125.139958 -99.786186)
		(mid 125.060736 -99.497068)
		(end 125.133608 -99.206304)
		(width 0.0889)
		(layer "B.Cu")
		(net "P3E_CPU1_PE3_MP_TXN<12>")
	)
	(arc
		(start 127.383794 -88.003634)
		(mid 127.575436 -87.946468)
		(end 127.715518 -87.803736)
		(width 0.0889)
		(layer "B.Cu")
		(net "P3E_CPU1_PE3_MP_TXN<12>")
	)
	(arc
		(start 140.758164 -89.784936)
		(mid 140.763864 -89.794523)
		(end 140.76934 -89.80424)
		(width 0.0889)
		(layer "B.Cu")
		(net "P3E_CPU1_PE3_MP_TXN<12>")
	)
	(arc
		(start 125.133608 -100.766118)
		(mid 125.06081 -100.475355)
		(end 125.139958 -100.186236)
		(width 0.0889)
		(layer "B.Cu")
		(net "P3E_CPU1_PE3_MP_TXN<12>")
	)
	(arc
		(start 130.817874 -86.022434)
		(mid 131.009516 -85.965268)
		(end 131.149598 -85.822536)
		(width 0.0889)
		(layer "B.Cu")
		(net "P3E_CPU1_PE3_MP_TXN<12>")
	)
	(arc
		(start 140.839698 -92.052648)
		(mid 140.818974 -92.210046)
		(end 140.758164 -92.356686)
		(width 0.0889)
		(layer "B.Cu")
		(net "P3E_CPU1_PE3_MP_TXN<12>")
	)
	(arc
		(start 140.758164 -88.794336)
		(mid 140.837295 -89.089738)
		(end 140.758164 -89.38514)
		(width 0.0889)
		(layer "B.Cu")
		(net "P3E_CPU1_PE3_MP_TXN<12>")
	)
	(arc
		(start 125.139958 -90.870786)
		(mid 125.060736 -90.581668)
		(end 125.133608 -90.290904)
		(width 0.0889)
		(layer "B.Cu")
		(net "P3E_CPU1_PE3_MP_TXN<12>")
	)
	(arc
		(start 131.149598 -85.822536)
		(mid 131.356602 -85.611672)
		(end 131.639818 -85.527388)
		(width 0.0889)
		(layer "B.Cu")
		(net "P3E_CPU1_PE3_MP_TXN<12>")
	)
	(arc
		(start 135.607044 -83.841336)
		(mid 135.747123 -83.984072)
		(end 135.938768 -84.041234)
		(width 0.0889)
		(layer "B.Cu")
		(net "P3E_CPU1_PE3_MP_TXN<12>")
	)
	(arc
		(start 125.139958 -89.880186)
		(mid 125.135629 -89.297014)
		(end 125.633988 -88.994234)
		(width 0.0889)
		(layer "B.Cu")
		(net "P3E_CPU1_PE3_MP_TXN<12>")
	)
	(arc
		(start 140.758164 -92.356686)
		(mid 140.704694 -92.551749)
		(end 140.753338 -92.7481)
		(width 0.0889)
		(layer "B.Cu")
		(net "P3E_CPU1_PE3_MP_TXN<12>")
	)
	(arc
		(start 125.144784 -92.2528)
		(mid 125.193539 -92.056448)
		(end 125.139958 -91.861386)
		(width 0.0889)
		(layer "B.Cu")
		(net "P3E_CPU1_PE3_MP_TXN<12>")
	)
	(arc
		(start 125.139958 -92.851986)
		(mid 125.060736 -92.562868)
		(end 125.133608 -92.272104)
		(width 0.0889)
		(layer "B.Cu")
		(net "P3E_CPU1_PE3_MP_TXN<12>")
	)
	(arc
		(start 139.899644 -93.842586)
		(mid 139.688931 -94.055665)
		(end 139.400788 -94.137988)
		(width 0.0889)
		(layer "B.Cu")
		(net "P3E_CPU1_PE3_MP_TXN<12>")
	)
	(arc
		(start 125.144784 -97.2058)
		(mid 125.193539 -97.009448)
		(end 125.139958 -96.814386)
		(width 0.0889)
		(layer "B.Cu")
		(net "P3E_CPU1_PE3_MP_TXN<12>")
	)
	(arc
		(start 138.550904 -85.527388)
		(mid 138.834121 -85.611669)
		(end 139.041124 -85.822536)
		(width 0.0889)
		(layer "B.Cu")
		(net "P3E_CPU1_PE3_MP_TXN<12>")
	)
	(arc
		(start 131.661408 -85.527388)
		(mid 131.858569 -85.475429)
		(end 132.004562 -85.333078)
		(width 0.0889)
		(layer "B.Cu")
		(net "P3E_CPU1_PE3_MP_TXN<12>")
	)
	(arc
		(start 129.100834 -87.013034)
		(mid 129.292476 -86.955868)
		(end 129.432558 -86.813136)
		(width 0.0889)
		(layer "B.Cu")
		(net "P3E_CPU1_PE3_MP_TXN<12>")
	)
	(arc
		(start 137.688574 -85.031834)
		(mid 137.973998 -85.115301)
		(end 138.182604 -85.327236)
		(width 0.0889)
		(layer "B.Cu")
		(net "P3E_CPU1_PE3_MP_TXN<12>")
	)
	(arc
		(start 132.007864 -85.327236)
		(mid 132.216472 -85.115304)
		(end 132.501894 -85.031834)
		(width 0.0889)
		(layer "B.Cu")
		(net "P3E_CPU1_PE3_MP_TXN<12>")
	)
	(arc
		(start 140.753338 -88.402922)
		(mid 140.704583 -88.599274)
		(end 140.758164 -88.794336)
		(width 0.0889)
		(layer "B.Cu")
		(net "P3E_CPU1_PE3_MP_TXN<12>")
	)
	(arc
		(start 140.76934 -89.80424)
		(mid 140.82519 -89.947543)
		(end 140.842238 -90.100404)
		(width 0.0889)
		(layer "B.Cu")
		(net "P3E_CPU1_PE3_MP_TXN<12>")
	)
	(arc
		(start 139.405614 -86.022434)
		(mid 139.691038 -86.105901)
		(end 139.899644 -86.317836)
		(width 0.0889)
		(layer "B.Cu")
		(net "P3E_CPU1_PE3_MP_TXN<12>")
	)
	(arc
		(start 139.041124 -94.33814)
		(mid 138.95296 -94.454602)
		(end 138.83894 -94.545912)
		(width 0.0889)
		(layer "B.Cu")
		(net "P3E_CPU1_PE3_MP_TXN<12>")
	)
	(arc
		(start 125.133608 -94.822518)
		(mid 125.06081 -94.531755)
		(end 125.139958 -94.242636)
		(width 0.0889)
		(layer "B.Cu")
		(net "P3E_CPU1_PE3_MP_TXN<12>")
	)
	(arc
		(start 139.899644 -86.317836)
		(mid 140.041327 -86.46164)
		(end 140.235178 -86.517988)
		(width 0.0889)
		(layer "B.Cu")
		(net "P3E_CPU1_PE3_MP_TXN<12>")
	)
	(arc
		(start 126.521464 -88.499188)
		(mid 126.715314 -88.442838)
		(end 126.856998 -88.299036)
		(width 0.0889)
		(layer "B.Cu")
		(net "P3E_CPU1_PE3_MP_TXN<12>")
	)
	(arc
		(start 125.144784 -99.187)
		(mid 125.193539 -98.990648)
		(end 125.139958 -98.795586)
		(width 0.0889)
		(layer "B.Cu")
		(net "P3E_CPU1_PE3_MP_TXN<12>")
	)
	(arc
		(start 133.38937 -84.536788)
		(mid 133.58322 -84.480438)
		(end 133.724904 -84.336636)
		(width 0.0889)
		(layer "B.Cu")
		(net "P3E_CPU1_PE3_MP_TXN<12>")
	)
	(arc
		(start 139.376658 -94.137988)
		(mid 139.182808 -94.194338)
		(end 139.041124 -94.33814)
		(width 0.0889)
		(layer "B.Cu")
		(net "P3E_CPU1_PE3_MP_TXN<12>")
	)
	(arc
		(start 134.583424 -83.841336)
		(mid 134.790428 -83.630472)
		(end 135.073644 -83.546188)
		(width 0.0889)
		(layer "B.Cu")
		(net "P3E_CPU1_PE3_MP_TXN<12>")
	)
	(arc
		(start 140.753338 -92.7481)
		(mid 140.755721 -92.752434)
		(end 140.758164 -92.756736)
		(width 0.0889)
		(layer "B.Cu")
		(net "P3E_CPU1_PE3_MP_TXN<12>")
	)
	(arc
		(start 125.144784 -96.2152)
		(mid 125.193539 -96.018848)
		(end 125.139958 -95.823786)
		(width 0.0889)
		(layer "B.Cu")
		(net "P3E_CPU1_PE3_MP_TXN<12>")
	)
	(arc
		(start 140.231368 -93.642688)
		(mid 140.039726 -93.699854)
		(end 139.899644 -93.842586)
		(width 0.0889)
		(layer "B.Cu")
		(net "P3E_CPU1_PE3_MP_TXN<12>")
	)
	(arc
		(start 132.866384 -84.831936)
		(mid 133.073388 -84.621072)
		(end 133.356604 -84.536788)
		(width 0.0889)
		(layer "B.Cu")
		(net "P3E_CPU1_PE3_MP_TXN<12>")
	)
	(arc
		(start 133.724904 -84.336636)
		(mid 133.933512 -84.124704)
		(end 134.218934 -84.041234)
		(width 0.0889)
		(layer "B.Cu")
		(net "P3E_CPU1_PE3_MP_TXN<12>")
	)
	(arc
		(start 125.139958 -95.823786)
		(mid 125.060827 -95.528384)
		(end 125.139958 -95.232982)
		(width 0.0889)
		(layer "B.Cu")
		(net "P3E_CPU1_PE3_MP_TXN<12>")
	)
	(arc
		(start 134.2517 -84.041234)
		(mid 134.443342 -83.984068)
		(end 134.583424 -83.841336)
		(width 0.0889)
		(layer "B.Cu")
		(net "P3E_CPU1_PE3_MP_TXN<12>")
	)
	(arc
		(start 136.833864 -84.536788)
		(mid 137.117081 -84.621069)
		(end 137.324084 -84.831936)
		(width 0.0889)
		(layer "B.Cu")
		(net "P3E_CPU1_PE3_MP_TXN<12>")
	)
	(arc
		(start 139.041124 -85.822536)
		(mid 139.181203 -85.965272)
		(end 139.372848 -86.022434)
		(width 0.0889)
		(layer "B.Cu")
		(net "P3E_CPU1_PE3_MP_TXN<12>")
	)
	(segment
		(start 139.674854 -95.033084)
		(end 140.246354 -95.033084)
		(width 0.1143)
		(layer "F.Cu")
		(net "P3E_CPU1_PE3_MP_TXN<11>")
	)
	(via
		(at 23.065994 -112.980724)
		(size 0.508)
		(drill 0.254)
		(layers "F.Cu" "B.Cu")
		(net "P3E_CPU1_PE3_MP_TXN<11>")
	)
	(via
		(at 140.246354 -95.033084)
		(size 0.508)
		(drill 0.254)
		(layers "F.Cu" "B.Cu")
		(net "P3E_CPU1_PE3_MP_TXN<11>")
	)
	(segment
		(start 138.017504 -93.347286)
		(end 138.011154 -93.336618)
		(width 0.0889)
		(layer "B.Cu")
		(net "P3E_CPU1_PE3_MP_TXN<11>")
	)
	(segment
		(start 30.631384 -116.4336)
		(end 23.61057 -113.525554)
		(width 0.1143)
		(layer "B.Cu")
		(net "P3E_CPU1_PE3_MP_TXN<11>")
	)
	(segment
		(start 137.152634 -90.290904)
		(end 137.158984 -90.280236)
		(width 0.0889)
		(layer "B.Cu")
		(net "P3E_CPU1_PE3_MP_TXN<11>")
	)
	(segment
		(start 128.818132 -100.97643)
		(end 128.818132 -103.942388)
		(width 0.0889)
		(layer "B.Cu")
		(net "P3E_CPU1_PE3_MP_TXN<11>")
	)
	(segment
		(start 127.959104 -104.801416)
		(end 127.959104 -104.80167)
		(width 0.0889)
		(layer "B.Cu")
		(net "P3E_CPU1_PE3_MP_TXN<11>")
	)
	(segment
		(start 134.258304 -88.194134)
		(end 134.225538 -88.194134)
		(width 0.0889)
		(layer "B.Cu")
		(net "P3E_CPU1_PE3_MP_TXN<11>")
	)
	(segment
		(start 23.61057 -113.525554)
		(end 23.065994 -112.980724)
		(width 0.1143)
		(layer "B.Cu")
		(net "P3E_CPU1_PE3_MP_TXN<11>")
	)
	(segment
		(start 102.469188 -111.506762)
		(end 97.234248 -112.55375)
		(width 0.1143)
		(layer "B.Cu")
		(net "P3E_CPU1_PE3_MP_TXN<11>")
	)
	(segment
		(start 137.152634 -91.281504)
		(end 137.158984 -91.270836)
		(width 0.0889)
		(layer "B.Cu")
		(net "P3E_CPU1_PE3_MP_TXN<11>")
	)
	(segment
		(start 108.982256 -111.281464)
		(end 105.162858 -112.045242)
		(width 0.1143)
		(layer "B.Cu")
		(net "P3E_CPU1_PE3_MP_TXN<11>")
	)
	(segment
		(start 137.158984 -91.270836)
		(end 137.16381 -91.2622)
		(width 0.0889)
		(layer "B.Cu")
		(net "P3E_CPU1_PE3_MP_TXN<11>")
	)
	(segment
		(start 19.558 -109.472476)
		(end 23.065994 -112.980724)
		(width 0.1143)
		(layer "B.Cu")
		(net "P3E_CPU1_PE3_MP_TXN<11>")
	)
	(segment
		(start 129.962148 -90.670888)
		(end 129.929382 -90.670888)
		(width 0.0889)
		(layer "B.Cu")
		(net "P3E_CPU1_PE3_MP_TXN<11>")
	)
	(segment
		(start 127.959358 -104.836976)
		(end 127.95123 -104.845104)
		(width 0.0889)
		(layer "B.Cu")
		(net "P3E_CPU1_PE3_MP_TXN<11>")
	)
	(segment
		(start 53.281834 -114.746024)
		(end 36.14674 -116.4336)
		(width 0.1143)
		(layer "B.Cu")
		(net "P3E_CPU1_PE3_MP_TXN<11>")
	)
	(segment
		(start 131.679188 -89.680288)
		(end 131.646422 -89.680288)
		(width 0.0889)
		(layer "B.Cu")
		(net "P3E_CPU1_PE3_MP_TXN<11>")
	)
	(segment
		(start 132.17652 -89.379044)
		(end 132.173218 -89.384886)
		(width 0.0889)
		(layer "B.Cu")
		(net "P3E_CPU1_PE3_MP_TXN<11>")
	)
	(segment
		(start 105.162858 -112.045242)
		(end 102.469188 -111.506762)
		(width 0.1143)
		(layer "B.Cu")
		(net "P3E_CPU1_PE3_MP_TXN<11>")
	)
	(segment
		(start 127.95123 -104.845104)
		(end 122.316494 -110.47984)
		(width 0.1143)
		(layer "B.Cu")
		(net "P3E_CPU1_PE3_MP_TXN<11>")
	)
	(segment
		(start 128.739138 -93.347286)
		(end 128.734312 -93.355922)
		(width 0.0889)
		(layer "B.Cu")
		(net "P3E_CPU1_PE3_MP_TXN<11>")
	)
	(segment
		(start 137.152634 -89.300304)
		(end 137.158984 -89.289636)
		(width 0.0889)
		(layer "B.Cu")
		(net "P3E_CPU1_PE3_MP_TXN<11>")
	)
	(segment
		(start 135.11022 -87.699088)
		(end 135.080248 -87.699088)
		(width 0.0889)
		(layer "B.Cu")
		(net "P3E_CPU1_PE3_MP_TXN<11>")
	)
	(segment
		(start 138.011154 -94.748604)
		(end 138.017504 -94.737936)
		(width 0.0889)
		(layer "B.Cu")
		(net "P3E_CPU1_PE3_MP_TXN<11>")
	)
	(segment
		(start 90.257376 -111.274606)
		(end 89.92108 -111.20755)
		(width 0.1143)
		(layer "B.Cu")
		(net "P3E_CPU1_PE3_MP_TXN<11>")
	)
	(segment
		(start 89.02446 -111.028226)
		(end 88.934798 -110.893606)
		(width 0.1143)
		(layer "B.Cu")
		(net "P3E_CPU1_PE3_MP_TXN<11>")
	)
	(segment
		(start 128.745488 -98.289618)
		(end 128.739138 -98.300286)
		(width 0.0889)
		(layer "B.Cu")
		(net "P3E_CPU1_PE3_MP_TXN<11>")
	)
	(segment
		(start 83.442302 -108.718604)
		(end 53.281834 -114.746024)
		(width 0.1143)
		(layer "B.Cu")
		(net "P3E_CPU1_PE3_MP_TXN<11>")
	)
	(segment
		(start 89.92108 -111.20755)
		(end 89.831418 -111.07293)
		(width 0.1143)
		(layer "B.Cu")
		(net "P3E_CPU1_PE3_MP_TXN<11>")
	)
	(segment
		(start 128.739138 -92.356686)
		(end 128.734312 -92.365322)
		(width 0.0889)
		(layer "B.Cu")
		(net "P3E_CPU1_PE3_MP_TXN<11>")
	)
	(segment
		(start 14.72946 -107.48518)
		(end 15.07236 -107.14228)
		(width 0.1143)
		(layer "B.Cu")
		(net "P3E_CPU1_PE3_MP_TXN<11>")
	)
	(segment
		(start 88.934798 -110.893606)
		(end 87.411052 -110.588806)
		(width 0.1143)
		(layer "B.Cu")
		(net "P3E_CPU1_PE3_MP_TXN<11>")
	)
	(segment
		(start 15.07236 -107.14228)
		(end 17.750282 -107.14228)
		(width 0.1143)
		(layer "B.Cu")
		(net "P3E_CPU1_PE3_MP_TXN<11>")
	)
	(segment
		(start 128.745488 -99.280218)
		(end 128.739138 -99.290886)
		(width 0.0889)
		(layer "B.Cu")
		(net "P3E_CPU1_PE3_MP_TXN<11>")
	)
	(segment
		(start 139.376658 -95.12808)
		(end 139.376658 -95.128334)
		(width 0.0889)
		(layer "B.Cu")
		(net "P3E_CPU1_PE3_MP_TXN<11>")
	)
	(segment
		(start 129.107438 -91.165934)
		(end 129.074672 -91.165934)
		(width 0.0889)
		(layer "B.Cu")
		(net "P3E_CPU1_PE3_MP_TXN<11>")
	)
	(segment
		(start 89.360756 -111.095282)
		(end 89.02446 -111.028226)
		(width 0.1143)
		(layer "B.Cu")
		(net "P3E_CPU1_PE3_MP_TXN<11>")
	)
	(segment
		(start 97.234248 -112.55375)
		(end 90.391742 -111.184944)
		(width 0.1143)
		(layer "B.Cu")
		(net "P3E_CPU1_PE3_MP_TXN<11>")
	)
	(segment
		(start 128.739138 -94.737936)
		(end 128.745488 -94.748604)
		(width 0.0889)
		(layer "B.Cu")
		(net "P3E_CPU1_PE3_MP_TXN<11>")
	)
	(segment
		(start 90.391742 -111.184944)
		(end 90.257376 -111.274606)
		(width 0.1143)
		(layer "B.Cu")
		(net "P3E_CPU1_PE3_MP_TXN<11>")
	)
	(segment
		(start 18.667476 -107.522518)
		(end 19.558 -108.413042)
		(width 0.1143)
		(layer "B.Cu")
		(net "P3E_CPU1_PE3_MP_TXN<11>")
	)
	(segment
		(start 128.745488 -97.299018)
		(end 128.739138 -97.309686)
		(width 0.0889)
		(layer "B.Cu")
		(net "P3E_CPU1_PE3_MP_TXN<11>")
	)
	(segment
		(start 128.745488 -92.346018)
		(end 128.739138 -92.356686)
		(width 0.0889)
		(layer "B.Cu")
		(net "P3E_CPU1_PE3_MP_TXN<11>")
	)
	(segment
		(start 133.395974 -88.689688)
		(end 133.363208 -88.689688)
		(width 0.0889)
		(layer "B.Cu")
		(net "P3E_CPU1_PE3_MP_TXN<11>")
	)
	(segment
		(start 136.82726 -88.689688)
		(end 136.794494 -88.689688)
		(width 0.0889)
		(layer "B.Cu")
		(net "P3E_CPU1_PE3_MP_TXN<11>")
	)
	(segment
		(start 137.68197 -92.156534)
		(end 137.649204 -92.156534)
		(width 0.0889)
		(layer "B.Cu")
		(net "P3E_CPU1_PE3_MP_TXN<11>")
	)
	(segment
		(start 17.750282 -107.14228)
		(end 18.667476 -107.522518)
		(width 0.1143)
		(layer "B.Cu")
		(net "P3E_CPU1_PE3_MP_TXN<11>")
	)
	(segment
		(start 130.824478 -90.175334)
		(end 130.791712 -90.175334)
		(width 0.0889)
		(layer "B.Cu")
		(net "P3E_CPU1_PE3_MP_TXN<11>")
	)
	(segment
		(start 113.608358 -112.211612)
		(end 108.982256 -111.281464)
		(width 0.1143)
		(layer "B.Cu")
		(net "P3E_CPU1_PE3_MP_TXN<11>")
	)
	(segment
		(start 89.831418 -111.07293)
		(end 89.495122 -111.00562)
		(width 0.1143)
		(layer "B.Cu")
		(net "P3E_CPU1_PE3_MP_TXN<11>")
	)
	(segment
		(start 128.818132 -103.942388)
		(end 127.959104 -104.801416)
		(width 0.0889)
		(layer "B.Cu")
		(net "P3E_CPU1_PE3_MP_TXN<11>")
	)
	(segment
		(start 132.541264 -89.184734)
		(end 132.519674 -89.184734)
		(width 0.0889)
		(layer "B.Cu")
		(net "P3E_CPU1_PE3_MP_TXN<11>")
	)
	(segment
		(start 128.739138 -99.290886)
		(end 128.734312 -99.299522)
		(width 0.0889)
		(layer "B.Cu")
		(net "P3E_CPU1_PE3_MP_TXN<11>")
	)
	(segment
		(start 128.739138 -98.300286)
		(end 128.734312 -98.308922)
		(width 0.0889)
		(layer "B.Cu")
		(net "P3E_CPU1_PE3_MP_TXN<11>")
	)
	(segment
		(start 128.739138 -97.309686)
		(end 128.734312 -97.318322)
		(width 0.0889)
		(layer "B.Cu")
		(net "P3E_CPU1_PE3_MP_TXN<11>")
	)
	(segment
		(start 19.558 -108.413042)
		(end 19.558 -109.472476)
		(width 0.1143)
		(layer "B.Cu")
		(net "P3E_CPU1_PE3_MP_TXN<11>")
	)
	(segment
		(start 36.14674 -116.4336)
		(end 30.631384 -116.4336)
		(width 0.1143)
		(layer "B.Cu")
		(net "P3E_CPU1_PE3_MP_TXN<11>")
	)
	(segment
		(start 138.02233 -93.355922)
		(end 138.017504 -93.347286)
		(width 0.0889)
		(layer "B.Cu")
		(net "P3E_CPU1_PE3_MP_TXN<11>")
	)
	(segment
		(start 127.959104 -104.80167)
		(end 127.959358 -104.821736)
		(width 0.0889)
		(layer "B.Cu")
		(net "P3E_CPU1_PE3_MP_TXN<11>")
	)
	(segment
		(start 128.745488 -93.336618)
		(end 128.739138 -93.347286)
		(width 0.0889)
		(layer "B.Cu")
		(net "P3E_CPU1_PE3_MP_TXN<11>")
	)
	(segment
		(start 128.739138 -95.328486)
		(end 128.734312 -95.337122)
		(width 0.0889)
		(layer "B.Cu")
		(net "P3E_CPU1_PE3_MP_TXN<11>")
	)
	(segment
		(start 122.316494 -110.47984)
		(end 113.608358 -112.211612)
		(width 0.1143)
		(layer "B.Cu")
		(net "P3E_CPU1_PE3_MP_TXN<11>")
	)
	(segment
		(start 85.104732 -109.05109)
		(end 83.442302 -108.718604)
		(width 0.1143)
		(layer "B.Cu")
		(net "P3E_CPU1_PE3_MP_TXN<11>")
	)
	(segment
		(start 89.495122 -111.00562)
		(end 89.360756 -111.095282)
		(width 0.1143)
		(layer "B.Cu")
		(net "P3E_CPU1_PE3_MP_TXN<11>")
	)
	(segment
		(start 87.411052 -110.588806)
		(end 85.104732 -109.05109)
		(width 0.1143)
		(layer "B.Cu")
		(net "P3E_CPU1_PE3_MP_TXN<11>")
	)
	(segment
		(start 137.158984 -89.289636)
		(end 137.16381 -89.281)
		(width 0.0889)
		(layer "B.Cu")
		(net "P3E_CPU1_PE3_MP_TXN<11>")
	)
	(segment
		(start 135.96493 -88.194134)
		(end 135.932164 -88.194134)
		(width 0.0889)
		(layer "B.Cu")
		(net "P3E_CPU1_PE3_MP_TXN<11>")
	)
	(segment
		(start 127.959358 -104.821736)
		(end 127.959358 -104.836976)
		(width 0.0889)
		(layer "B.Cu")
		(net "P3E_CPU1_PE3_MP_TXN<11>")
	)
	(segment
		(start 128.739138 -96.319086)
		(end 128.734312 -96.327722)
		(width 0.0889)
		(layer "B.Cu")
		(net "P3E_CPU1_PE3_MP_TXN<11>")
	)
	(segment
		(start 128.745488 -96.308418)
		(end 128.739138 -96.319086)
		(width 0.0889)
		(layer "B.Cu")
		(net "P3E_CPU1_PE3_MP_TXN<11>")
	)
	(segment
		(start 137.158984 -90.280236)
		(end 137.16381 -90.2716)
		(width 0.0889)
		(layer "B.Cu")
		(net "P3E_CPU1_PE3_MP_TXN<11>")
	)
	(arc
		(start 137.16381 -91.2622)
		(mid 137.212565 -91.065848)
		(end 137.158984 -90.870786)
		(width 0.0889)
		(layer "B.Cu")
		(net "P3E_CPU1_PE3_MP_TXN<11>")
	)
	(arc
		(start 133.031484 -88.889586)
		(mid 132.82448 -89.10045)
		(end 132.541264 -89.184734)
		(width 0.0889)
		(layer "B.Cu")
		(net "P3E_CPU1_PE3_MP_TXN<11>")
	)
	(arc
		(start 132.173218 -89.384886)
		(mid 131.96461 -89.596818)
		(end 131.679188 -89.680288)
		(width 0.0889)
		(layer "B.Cu")
		(net "P3E_CPU1_PE3_MP_TXN<11>")
	)
	(arc
		(start 128.734312 -97.318322)
		(mid 128.685557 -97.514674)
		(end 128.739138 -97.709736)
		(width 0.0889)
		(layer "B.Cu")
		(net "P3E_CPU1_PE3_MP_TXN<11>")
	)
	(arc
		(start 138.017504 -93.747336)
		(mid 138.070974 -93.552273)
		(end 138.02233 -93.355922)
		(width 0.0889)
		(layer "B.Cu")
		(net "P3E_CPU1_PE3_MP_TXN<11>")
	)
	(arc
		(start 135.932164 -88.194134)
		(mid 135.648947 -88.109853)
		(end 135.441944 -87.898986)
		(width 0.0889)
		(layer "B.Cu")
		(net "P3E_CPU1_PE3_MP_TXN<11>")
	)
	(arc
		(start 128.739138 -97.709736)
		(mid 128.81836 -97.998854)
		(end 128.745488 -98.289618)
		(width 0.0889)
		(layer "B.Cu")
		(net "P3E_CPU1_PE3_MP_TXN<11>")
	)
	(arc
		(start 128.734312 -95.337122)
		(mid 128.685557 -95.533474)
		(end 128.739138 -95.728536)
		(width 0.0889)
		(layer "B.Cu")
		(net "P3E_CPU1_PE3_MP_TXN<11>")
	)
	(arc
		(start 128.739138 -100.28174)
		(mid 128.685639 -100.481638)
		(end 128.739138 -100.681536)
		(width 0.0889)
		(layer "B.Cu")
		(net "P3E_CPU1_PE3_MP_TXN<11>")
	)
	(arc
		(start 128.734312 -92.365322)
		(mid 128.685557 -92.561674)
		(end 128.739138 -92.756736)
		(width 0.0889)
		(layer "B.Cu")
		(net "P3E_CPU1_PE3_MP_TXN<11>")
	)
	(arc
		(start 135.080248 -87.699088)
		(mid 134.888606 -87.756254)
		(end 134.748524 -87.898986)
		(width 0.0889)
		(layer "B.Cu")
		(net "P3E_CPU1_PE3_MP_TXN<11>")
	)
	(arc
		(start 128.739138 -95.728536)
		(mid 128.81836 -96.017654)
		(end 128.745488 -96.308418)
		(width 0.0889)
		(layer "B.Cu")
		(net "P3E_CPU1_PE3_MP_TXN<11>")
	)
	(arc
		(start 128.734312 -98.308922)
		(mid 128.685557 -98.505274)
		(end 128.739138 -98.700336)
		(width 0.0889)
		(layer "B.Cu")
		(net "P3E_CPU1_PE3_MP_TXN<11>")
	)
	(arc
		(start 128.739138 -93.747336)
		(mid 128.818269 -94.042738)
		(end 128.739138 -94.33814)
		(width 0.0889)
		(layer "B.Cu")
		(net "P3E_CPU1_PE3_MP_TXN<11>")
	)
	(arc
		(start 130.456178 -90.375486)
		(mid 130.24757 -90.587418)
		(end 129.962148 -90.670888)
		(width 0.0889)
		(layer "B.Cu")
		(net "P3E_CPU1_PE3_MP_TXN<11>")
	)
	(arc
		(start 128.745488 -94.748604)
		(mid 128.818286 -95.039367)
		(end 128.739138 -95.328486)
		(width 0.0889)
		(layer "B.Cu")
		(net "P3E_CPU1_PE3_MP_TXN<11>")
	)
	(arc
		(start 136.794494 -88.689688)
		(mid 136.50907 -88.606221)
		(end 136.300464 -88.394286)
		(width 0.0889)
		(layer "B.Cu")
		(net "P3E_CPU1_PE3_MP_TXN<11>")
	)
	(arc
		(start 137.16381 -89.281)
		(mid 137.160063 -88.891744)
		(end 136.82726 -88.689688)
		(width 0.0889)
		(layer "B.Cu")
		(net "P3E_CPU1_PE3_MP_TXN<11>")
	)
	(arc
		(start 129.597658 -90.870786)
		(mid 129.390654 -91.08165)
		(end 129.107438 -91.165934)
		(width 0.0889)
		(layer "B.Cu")
		(net "P3E_CPU1_PE3_MP_TXN<11>")
	)
	(arc
		(start 137.158984 -90.870786)
		(mid 137.079762 -90.581668)
		(end 137.152634 -90.290904)
		(width 0.0889)
		(layer "B.Cu")
		(net "P3E_CPU1_PE3_MP_TXN<11>")
	)
	(arc
		(start 138.017504 -94.33814)
		(mid 137.938373 -94.042738)
		(end 138.017504 -93.747336)
		(width 0.0889)
		(layer "B.Cu")
		(net "P3E_CPU1_PE3_MP_TXN<11>")
	)
	(arc
		(start 140.246354 -95.033084)
		(mid 140.016565 -94.775926)
		(end 139.704318 -94.922086)
		(width 0.0889)
		(layer "B.Cu")
		(net "P3E_CPU1_PE3_MP_TXN<11>")
	)
	(arc
		(start 128.739138 -91.766136)
		(mid 128.81836 -92.055254)
		(end 128.745488 -92.346018)
		(width 0.0889)
		(layer "B.Cu")
		(net "P3E_CPU1_PE3_MP_TXN<11>")
	)
	(arc
		(start 128.739138 -96.719136)
		(mid 128.81836 -97.008254)
		(end 128.745488 -97.299018)
		(width 0.0889)
		(layer "B.Cu")
		(net "P3E_CPU1_PE3_MP_TXN<11>")
	)
	(arc
		(start 130.791712 -90.175334)
		(mid 130.597862 -90.231684)
		(end 130.456178 -90.375486)
		(width 0.0889)
		(layer "B.Cu")
		(net "P3E_CPU1_PE3_MP_TXN<11>")
	)
	(arc
		(start 137.649204 -92.156534)
		(mid 137.156814 -91.857601)
		(end 137.152634 -91.281504)
		(width 0.0889)
		(layer "B.Cu")
		(net "P3E_CPU1_PE3_MP_TXN<11>")
	)
	(arc
		(start 131.314698 -89.880186)
		(mid 131.107694 -90.09105)
		(end 130.824478 -90.175334)
		(width 0.0889)
		(layer "B.Cu")
		(net "P3E_CPU1_PE3_MP_TXN<11>")
	)
	(arc
		(start 135.441944 -87.898986)
		(mid 135.301865 -87.75625)
		(end 135.11022 -87.699088)
		(width 0.0889)
		(layer "B.Cu")
		(net "P3E_CPU1_PE3_MP_TXN<11>")
	)
	(arc
		(start 133.363208 -88.689688)
		(mid 133.171566 -88.746854)
		(end 133.031484 -88.889586)
		(width 0.0889)
		(layer "B.Cu")
		(net "P3E_CPU1_PE3_MP_TXN<11>")
	)
	(arc
		(start 137.16381 -90.2716)
		(mid 137.212565 -90.075248)
		(end 137.158984 -89.880186)
		(width 0.0889)
		(layer "B.Cu")
		(net "P3E_CPU1_PE3_MP_TXN<11>")
	)
	(arc
		(start 134.225538 -88.194134)
		(mid 134.031688 -88.250484)
		(end 133.890004 -88.394286)
		(width 0.0889)
		(layer "B.Cu")
		(net "P3E_CPU1_PE3_MP_TXN<11>")
	)
	(arc
		(start 128.739138 -100.681536)
		(mid 128.798017 -100.823792)
		(end 128.818132 -100.97643)
		(width 0.0889)
		(layer "B.Cu")
		(net "P3E_CPU1_PE3_MP_TXN<11>")
	)
	(arc
		(start 129.074672 -91.165934)
		(mid 128.736503 -91.370732)
		(end 128.739138 -91.766136)
		(width 0.0889)
		(layer "B.Cu")
		(net "P3E_CPU1_PE3_MP_TXN<11>")
	)
	(arc
		(start 128.739138 -99.690936)
		(mid 128.818269 -99.986338)
		(end 128.739138 -100.28174)
		(width 0.0889)
		(layer "B.Cu")
		(net "P3E_CPU1_PE3_MP_TXN<11>")
	)
	(arc
		(start 133.890004 -88.394286)
		(mid 133.681396 -88.606218)
		(end 133.395974 -88.689688)
		(width 0.0889)
		(layer "B.Cu")
		(net "P3E_CPU1_PE3_MP_TXN<11>")
	)
	(arc
		(start 139.041124 -95.328486)
		(mid 138.239399 -95.548022)
		(end 138.011154 -94.748604)
		(width 0.0889)
		(layer "B.Cu")
		(net "P3E_CPU1_PE3_MP_TXN<11>")
	)
	(arc
		(start 138.017504 -92.756736)
		(mid 138.020252 -92.361269)
		(end 137.68197 -92.156534)
		(width 0.0889)
		(layer "B.Cu")
		(net "P3E_CPU1_PE3_MP_TXN<11>")
	)
	(arc
		(start 131.646422 -89.680288)
		(mid 131.45478 -89.737454)
		(end 131.314698 -89.880186)
		(width 0.0889)
		(layer "B.Cu")
		(net "P3E_CPU1_PE3_MP_TXN<11>")
	)
	(arc
		(start 128.734312 -93.355922)
		(mid 128.685557 -93.552274)
		(end 128.739138 -93.747336)
		(width 0.0889)
		(layer "B.Cu")
		(net "P3E_CPU1_PE3_MP_TXN<11>")
	)
	(arc
		(start 137.158984 -89.880186)
		(mid 137.079762 -89.591068)
		(end 137.152634 -89.300304)
		(width 0.0889)
		(layer "B.Cu")
		(net "P3E_CPU1_PE3_MP_TXN<11>")
	)
	(arc
		(start 132.519674 -89.184734)
		(mid 132.322513 -89.236693)
		(end 132.17652 -89.379044)
		(width 0.0889)
		(layer "B.Cu")
		(net "P3E_CPU1_PE3_MP_TXN<11>")
	)
	(arc
		(start 139.704318 -94.922086)
		(mid 139.567667 -95.068288)
		(end 139.376658 -95.12808)
		(width 0.0889)
		(layer "B.Cu")
		(net "P3E_CPU1_PE3_MP_TXN<11>")
	)
	(arc
		(start 128.734312 -99.299522)
		(mid 128.685557 -99.495874)
		(end 128.739138 -99.690936)
		(width 0.0889)
		(layer "B.Cu")
		(net "P3E_CPU1_PE3_MP_TXN<11>")
	)
	(arc
		(start 134.748524 -87.898986)
		(mid 134.54152 -88.10985)
		(end 134.258304 -88.194134)
		(width 0.0889)
		(layer "B.Cu")
		(net "P3E_CPU1_PE3_MP_TXN<11>")
	)
	(arc
		(start 136.300464 -88.394286)
		(mid 136.158781 -88.250482)
		(end 135.96493 -88.194134)
		(width 0.0889)
		(layer "B.Cu")
		(net "P3E_CPU1_PE3_MP_TXN<11>")
	)
	(arc
		(start 129.929382 -90.670888)
		(mid 129.73774 -90.728054)
		(end 129.597658 -90.870786)
		(width 0.0889)
		(layer "B.Cu")
		(net "P3E_CPU1_PE3_MP_TXN<11>")
	)
	(arc
		(start 128.739138 -98.700336)
		(mid 128.81836 -98.989454)
		(end 128.745488 -99.280218)
		(width 0.0889)
		(layer "B.Cu")
		(net "P3E_CPU1_PE3_MP_TXN<11>")
	)
	(arc
		(start 128.739138 -92.756736)
		(mid 128.81836 -93.045854)
		(end 128.745488 -93.336618)
		(width 0.0889)
		(layer "B.Cu")
		(net "P3E_CPU1_PE3_MP_TXN<11>")
	)
	(arc
		(start 128.739138 -94.33814)
		(mid 128.685639 -94.538038)
		(end 128.739138 -94.737936)
		(width 0.0889)
		(layer "B.Cu")
		(net "P3E_CPU1_PE3_MP_TXN<11>")
	)
	(arc
		(start 139.376658 -95.128334)
		(mid 139.182808 -95.184684)
		(end 139.041124 -95.328486)
		(width 0.0889)
		(layer "B.Cu")
		(net "P3E_CPU1_PE3_MP_TXN<11>")
	)
	(arc
		(start 138.011154 -93.336618)
		(mid 137.938356 -93.045855)
		(end 138.017504 -92.756736)
		(width 0.0889)
		(layer "B.Cu")
		(net "P3E_CPU1_PE3_MP_TXN<11>")
	)
	(arc
		(start 138.017504 -94.737936)
		(mid 138.071003 -94.538038)
		(end 138.017504 -94.33814)
		(width 0.0889)
		(layer "B.Cu")
		(net "P3E_CPU1_PE3_MP_TXN<11>")
	)
	(arc
		(start 128.734312 -96.327722)
		(mid 128.685557 -96.524074)
		(end 128.739138 -96.719136)
		(width 0.0889)
		(layer "B.Cu")
		(net "P3E_CPU1_PE3_MP_TXN<11>")
	)
	(segment
		(start 137.957814 -96.023938)
		(end 138.529314 -96.023938)
		(width 0.1143)
		(layer "F.Cu")
		(net "P3E_CPU1_PE3_MP_TXN<10>")
	)
	(via
		(at 34.036 -117.1829)
		(size 0.508)
		(drill 0.254)
		(layers "F.Cu" "B.Cu")
		(net "P3E_CPU1_PE3_MP_TXN<10>")
	)
	(via
		(at 138.529314 -96.023938)
		(size 0.508)
		(drill 0.254)
		(layers "F.Cu" "B.Cu")
		(net "P3E_CPU1_PE3_MP_TXN<10>")
	)
	(segment
		(start 129.309368 -104.418384)
		(end 129.309368 -104.698038)
		(width 0.1143)
		(layer "B.Cu")
		(net "P3E_CPU1_PE3_MP_TXN<10>")
	)
	(segment
		(start 129.432558 -93.347286)
		(end 129.437384 -93.355922)
		(width 0.0889)
		(layer "B.Cu")
		(net "P3E_CPU1_PE3_MP_TXN<10>")
	)
	(segment
		(start 122.905774 -111.101886)
		(end 113.298478 -113.012474)
		(width 0.1143)
		(layer "B.Cu")
		(net "P3E_CPU1_PE3_MP_TXN<10>")
	)
	(segment
		(start 105.139744 -112.807496)
		(end 102.780338 -112.335564)
		(width 0.1143)
		(layer "B.Cu")
		(net "P3E_CPU1_PE3_MP_TXN<10>")
	)
	(segment
		(start 23.19782 -114.14125)
		(end 30.539944 -117.1829)
		(width 0.1143)
		(layer "B.Cu")
		(net "P3E_CPU1_PE3_MP_TXN<10>")
	)
	(segment
		(start 96.363282 -113.619026)
		(end 91.417394 -112.62995)
		(width 0.1143)
		(layer "B.Cu")
		(net "P3E_CPU1_PE3_MP_TXN<10>")
	)
	(segment
		(start 129.432558 -98.300286)
		(end 129.437384 -98.308922)
		(width 0.0889)
		(layer "B.Cu")
		(net "P3E_CPU1_PE3_MP_TXN<10>")
	)
	(segment
		(start 130.817874 -90.975434)
		(end 130.785108 -90.975434)
		(width 0.0889)
		(layer "B.Cu")
		(net "P3E_CPU1_PE3_MP_TXN<10>")
	)
	(segment
		(start 129.432558 -95.328486)
		(end 129.437384 -95.337122)
		(width 0.0889)
		(layer "B.Cu")
		(net "P3E_CPU1_PE3_MP_TXN<10>")
	)
	(segment
		(start 129.426208 -98.289618)
		(end 129.432558 -98.300286)
		(width 0.0889)
		(layer "B.Cu")
		(net "P3E_CPU1_PE3_MP_TXN<10>")
	)
	(segment
		(start 70.602856 -112.100106)
		(end 53.386228 -115.505484)
		(width 0.1143)
		(layer "B.Cu")
		(net "P3E_CPU1_PE3_MP_TXN<10>")
	)
	(segment
		(start 129.334768 -100.851462)
		(end 129.334768 -101.134418)
		(width 0.0889)
		(layer "B.Cu")
		(net "P3E_CPU1_PE3_MP_TXN<10>")
	)
	(segment
		(start 134.2517 -88.994234)
		(end 134.218934 -88.994234)
		(width 0.0889)
		(layer "B.Cu")
		(net "P3E_CPU1_PE3_MP_TXN<10>")
	)
	(segment
		(start 131.661408 -90.480388)
		(end 131.639818 -90.480388)
		(width 0.0889)
		(layer "B.Cu")
		(net "P3E_CPU1_PE3_MP_TXN<10>")
	)
	(segment
		(start 113.298478 -113.012474)
		(end 108.706666 -112.094264)
		(width 0.1143)
		(layer "B.Cu")
		(net "P3E_CPU1_PE3_MP_TXN<10>")
	)
	(segment
		(start 136.471914 -91.281504)
		(end 136.465564 -91.270836)
		(width 0.0889)
		(layer "B.Cu")
		(net "P3E_CPU1_PE3_MP_TXN<10>")
	)
	(segment
		(start 136.465564 -91.270836)
		(end 136.460738 -91.2622)
		(width 0.0889)
		(layer "B.Cu")
		(net "P3E_CPU1_PE3_MP_TXN<10>")
	)
	(segment
		(start 129.432558 -96.319086)
		(end 129.437384 -96.327722)
		(width 0.0889)
		(layer "B.Cu")
		(net "P3E_CPU1_PE3_MP_TXN<10>")
	)
	(segment
		(start 30.539944 -117.1829)
		(end 34.036 -117.1829)
		(width 0.1143)
		(layer "B.Cu")
		(net "P3E_CPU1_PE3_MP_TXN<10>")
	)
	(segment
		(start 91.417394 -112.62995)
		(end 82.333846 -114.446812)
		(width 0.1143)
		(layer "B.Cu")
		(net "P3E_CPU1_PE3_MP_TXN<10>")
	)
	(segment
		(start 129.334768 -101.514402)
		(end 129.334768 -104.370886)
		(width 0.0889)
		(layer "B.Cu")
		(net "P3E_CPU1_PE3_MP_TXN<10>")
	)
	(segment
		(start 129.334768 -101.134418)
		(end 129.233676 -101.23551)
		(width 0.0889)
		(layer "B.Cu")
		(net "P3E_CPU1_PE3_MP_TXN<10>")
	)
	(segment
		(start 136.465564 -90.280236)
		(end 136.460738 -90.2716)
		(width 0.0889)
		(layer "B.Cu")
		(net "P3E_CPU1_PE3_MP_TXN<10>")
	)
	(segment
		(start 137.319258 -95.337122)
		(end 137.324084 -95.328486)
		(width 0.0889)
		(layer "B.Cu")
		(net "P3E_CPU1_PE3_MP_TXN<10>")
	)
	(segment
		(start 82.333846 -114.446812)
		(end 70.602856 -112.100106)
		(width 0.1143)
		(layer "B.Cu")
		(net "P3E_CPU1_PE3_MP_TXN<10>")
	)
	(segment
		(start 129.309368 -104.698038)
		(end 122.905774 -111.101886)
		(width 0.1143)
		(layer "B.Cu")
		(net "P3E_CPU1_PE3_MP_TXN<10>")
	)
	(segment
		(start 129.334768 -104.370886)
		(end 129.309368 -104.396286)
		(width 0.0889)
		(layer "B.Cu")
		(net "P3E_CPU1_PE3_MP_TXN<10>")
	)
	(segment
		(start 18.547588 -108.577888)
		(end 18.547588 -109.491272)
		(width 0.1143)
		(layer "B.Cu")
		(net "P3E_CPU1_PE3_MP_TXN<10>")
	)
	(segment
		(start 17.71142 -107.94492)
		(end 17.9959 -108.2294)
		(width 0.1143)
		(layer "B.Cu")
		(net "P3E_CPU1_PE3_MP_TXN<10>")
	)
	(segment
		(start 136.833864 -92.461588)
		(end 136.801098 -92.461588)
		(width 0.0889)
		(layer "B.Cu")
		(net "P3E_CPU1_PE3_MP_TXN<10>")
	)
	(segment
		(start 129.955544 -91.470988)
		(end 129.922778 -91.470988)
		(width 0.0889)
		(layer "B.Cu")
		(net "P3E_CPU1_PE3_MP_TXN<10>")
	)
	(segment
		(start 129.426208 -96.308418)
		(end 129.432558 -96.319086)
		(width 0.0889)
		(layer "B.Cu")
		(net "P3E_CPU1_PE3_MP_TXN<10>")
	)
	(segment
		(start 17.9959 -108.2294)
		(end 18.1991 -108.2294)
		(width 0.1143)
		(layer "B.Cu")
		(net "P3E_CPU1_PE3_MP_TXN<10>")
	)
	(segment
		(start 129.233676 -101.41331)
		(end 129.334768 -101.514402)
		(width 0.0889)
		(layer "B.Cu")
		(net "P3E_CPU1_PE3_MP_TXN<10>")
	)
	(segment
		(start 129.233676 -101.23551)
		(end 129.233676 -101.41331)
		(width 0.0889)
		(layer "B.Cu")
		(net "P3E_CPU1_PE3_MP_TXN<10>")
	)
	(segment
		(start 129.426208 -97.299018)
		(end 129.432558 -97.309686)
		(width 0.0889)
		(layer "B.Cu")
		(net "P3E_CPU1_PE3_MP_TXN<10>")
	)
	(segment
		(start 18.1991 -108.2294)
		(end 18.547588 -108.577888)
		(width 0.1143)
		(layer "B.Cu")
		(net "P3E_CPU1_PE3_MP_TXN<10>")
	)
	(segment
		(start 129.426208 -92.346018)
		(end 129.432558 -92.356686)
		(width 0.0889)
		(layer "B.Cu")
		(net "P3E_CPU1_PE3_MP_TXN<10>")
	)
	(segment
		(start 129.432558 -92.356686)
		(end 129.437384 -92.365322)
		(width 0.0889)
		(layer "B.Cu")
		(net "P3E_CPU1_PE3_MP_TXN<10>")
	)
	(segment
		(start 133.38937 -89.489788)
		(end 133.356604 -89.489788)
		(width 0.0889)
		(layer "B.Cu")
		(net "P3E_CPU1_PE3_MP_TXN<10>")
	)
	(segment
		(start 129.432558 -100.68179)
		(end 129.334768 -100.851462)
		(width 0.0889)
		(layer "B.Cu")
		(net "P3E_CPU1_PE3_MP_TXN<10>")
	)
	(segment
		(start 129.426208 -93.336618)
		(end 129.432558 -93.347286)
		(width 0.0889)
		(layer "B.Cu")
		(net "P3E_CPU1_PE3_MP_TXN<10>")
	)
	(segment
		(start 129.309368 -104.396286)
		(end 129.309368 -104.418384)
		(width 0.0889)
		(layer "B.Cu")
		(net "P3E_CPU1_PE3_MP_TXN<10>")
	)
	(segment
		(start 108.706666 -112.094264)
		(end 105.139744 -112.807496)
		(width 0.1143)
		(layer "B.Cu")
		(net "P3E_CPU1_PE3_MP_TXN<10>")
	)
	(segment
		(start 129.432558 -100.681536)
		(end 129.432558 -100.68179)
		(width 0.0889)
		(layer "B.Cu")
		(net "P3E_CPU1_PE3_MP_TXN<10>")
	)
	(segment
		(start 138.82243 -95.854774)
		(end 138.90117 -95.87611)
		(width 0.0889)
		(layer "B.Cu")
		(net "P3E_CPU1_PE3_MP_TXN<10>")
	)
	(segment
		(start 18.547588 -109.491272)
		(end 23.19782 -114.14125)
		(width 0.1143)
		(layer "B.Cu")
		(net "P3E_CPU1_PE3_MP_TXN<10>")
	)
	(segment
		(start 129.426208 -99.280218)
		(end 129.432558 -99.290886)
		(width 0.0889)
		(layer "B.Cu")
		(net "P3E_CPU1_PE3_MP_TXN<10>")
	)
	(segment
		(start 137.324084 -93.347286)
		(end 137.330434 -93.336618)
		(width 0.0889)
		(layer "B.Cu")
		(net "P3E_CPU1_PE3_MP_TXN<10>")
	)
	(segment
		(start 137.330434 -94.748604)
		(end 137.324084 -94.737936)
		(width 0.0889)
		(layer "B.Cu")
		(net "P3E_CPU1_PE3_MP_TXN<10>")
	)
	(segment
		(start 36.355782 -117.1829)
		(end 34.036 -117.1829)
		(width 0.1143)
		(layer "B.Cu")
		(net "P3E_CPU1_PE3_MP_TXN<10>")
	)
	(segment
		(start 129.432558 -99.290886)
		(end 129.437384 -99.299522)
		(width 0.0889)
		(layer "B.Cu")
		(net "P3E_CPU1_PE3_MP_TXN<10>")
	)
	(segment
		(start 129.432558 -97.309686)
		(end 129.437384 -97.318322)
		(width 0.0889)
		(layer "B.Cu")
		(net "P3E_CPU1_PE3_MP_TXN<10>")
	)
	(segment
		(start 137.688574 -95.928434)
		(end 137.655808 -95.928434)
		(width 0.0889)
		(layer "B.Cu")
		(net "P3E_CPU1_PE3_MP_TXN<10>")
	)
	(segment
		(start 102.581202 -112.375188)
		(end 96.363282 -113.619026)
		(width 0.1143)
		(layer "B.Cu")
		(net "P3E_CPU1_PE3_MP_TXN<10>")
	)
	(segment
		(start 129.432558 -94.737936)
		(end 129.426208 -94.748604)
		(width 0.0889)
		(layer "B.Cu")
		(net "P3E_CPU1_PE3_MP_TXN<10>")
	)
	(segment
		(start 102.780338 -112.335564)
		(end 102.581202 -112.375188)
		(width 0.1143)
		(layer "B.Cu")
		(net "P3E_CPU1_PE3_MP_TXN<10>")
	)
	(segment
		(start 136.471914 -90.290904)
		(end 136.465564 -90.280236)
		(width 0.0889)
		(layer "B.Cu")
		(net "P3E_CPU1_PE3_MP_TXN<10>")
	)
	(segment
		(start 132.007864 -90.280236)
		(end 132.004562 -90.286078)
		(width 0.0889)
		(layer "B.Cu")
		(net "P3E_CPU1_PE3_MP_TXN<10>")
	)
	(segment
		(start 137.319258 -93.355922)
		(end 137.324084 -93.347286)
		(width 0.0889)
		(layer "B.Cu")
		(net "P3E_CPU1_PE3_MP_TXN<10>")
	)
	(segment
		(start 138.529314 -96.023938)
		(end 138.82243 -95.854774)
		(width 0.0889)
		(layer "B.Cu")
		(net "P3E_CPU1_PE3_MP_TXN<10>")
	)
	(segment
		(start 135.971534 -88.994234)
		(end 135.938768 -88.994234)
		(width 0.0889)
		(layer "B.Cu")
		(net "P3E_CPU1_PE3_MP_TXN<10>")
	)
	(segment
		(start 132.53466 -89.984834)
		(end 132.501894 -89.984834)
		(width 0.0889)
		(layer "B.Cu")
		(net "P3E_CPU1_PE3_MP_TXN<10>")
	)
	(segment
		(start 135.116824 -88.499188)
		(end 135.073644 -88.499188)
		(width 0.0889)
		(layer "B.Cu")
		(net "P3E_CPU1_PE3_MP_TXN<10>")
	)
	(segment
		(start 53.386228 -115.505484)
		(end 36.355782 -117.1829)
		(width 0.1143)
		(layer "B.Cu")
		(net "P3E_CPU1_PE3_MP_TXN<10>")
	)
	(arc
		(start 129.432558 -92.756736)
		(mid 129.353336 -93.045854)
		(end 129.426208 -93.336618)
		(width 0.0889)
		(layer "B.Cu")
		(net "P3E_CPU1_PE3_MP_TXN<10>")
	)
	(arc
		(start 129.426208 -94.748604)
		(mid 129.35341 -95.039367)
		(end 129.432558 -95.328486)
		(width 0.0889)
		(layer "B.Cu")
		(net "P3E_CPU1_PE3_MP_TXN<10>")
	)
	(arc
		(start 137.324084 -94.737936)
		(mid 137.270585 -94.538038)
		(end 137.324084 -94.33814)
		(width 0.0889)
		(layer "B.Cu")
		(net "P3E_CPU1_PE3_MP_TXN<10>")
	)
	(arc
		(start 137.324084 -93.747336)
		(mid 137.270614 -93.552273)
		(end 137.319258 -93.355922)
		(width 0.0889)
		(layer "B.Cu")
		(net "P3E_CPU1_PE3_MP_TXN<10>")
	)
	(arc
		(start 135.073644 -88.499188)
		(mid 134.790427 -88.583469)
		(end 134.583424 -88.794336)
		(width 0.0889)
		(layer "B.Cu")
		(net "P3E_CPU1_PE3_MP_TXN<10>")
	)
	(arc
		(start 129.432558 -95.728536)
		(mid 129.353336 -96.017654)
		(end 129.426208 -96.308418)
		(width 0.0889)
		(layer "B.Cu")
		(net "P3E_CPU1_PE3_MP_TXN<10>")
	)
	(arc
		(start 129.432558 -98.700336)
		(mid 129.353336 -98.989454)
		(end 129.426208 -99.280218)
		(width 0.0889)
		(layer "B.Cu")
		(net "P3E_CPU1_PE3_MP_TXN<10>")
	)
	(arc
		(start 138.90117 -95.87611)
		(mid 138.856832 -96.253439)
		(end 138.517122 -96.423734)
		(width 0.0889)
		(layer "B.Cu")
		(net "P3E_CPU1_PE3_MP_TXN<10>")
	)
	(arc
		(start 138.182604 -96.223836)
		(mid 137.973996 -96.011904)
		(end 137.688574 -95.928434)
		(width 0.0889)
		(layer "B.Cu")
		(net "P3E_CPU1_PE3_MP_TXN<10>")
	)
	(arc
		(start 136.801098 -92.461588)
		(mid 136.462929 -92.25679)
		(end 136.465564 -91.861386)
		(width 0.0889)
		(layer "B.Cu")
		(net "P3E_CPU1_PE3_MP_TXN<10>")
	)
	(arc
		(start 137.330434 -93.336618)
		(mid 137.326403 -92.760436)
		(end 136.833864 -92.461588)
		(width 0.0889)
		(layer "B.Cu")
		(net "P3E_CPU1_PE3_MP_TXN<10>")
	)
	(arc
		(start 132.501894 -89.984834)
		(mid 132.21647 -90.068301)
		(end 132.007864 -90.280236)
		(width 0.0889)
		(layer "B.Cu")
		(net "P3E_CPU1_PE3_MP_TXN<10>")
	)
	(arc
		(start 135.607044 -88.794336)
		(mid 135.40004 -88.583472)
		(end 135.116824 -88.499188)
		(width 0.0889)
		(layer "B.Cu")
		(net "P3E_CPU1_PE3_MP_TXN<10>")
	)
	(arc
		(start 132.866384 -89.784936)
		(mid 132.726305 -89.927672)
		(end 132.53466 -89.984834)
		(width 0.0889)
		(layer "B.Cu")
		(net "P3E_CPU1_PE3_MP_TXN<10>")
	)
	(arc
		(start 129.432558 -93.747336)
		(mid 129.353427 -94.042738)
		(end 129.432558 -94.33814)
		(width 0.0889)
		(layer "B.Cu")
		(net "P3E_CPU1_PE3_MP_TXN<10>")
	)
	(arc
		(start 136.465564 -89.880186)
		(mid 136.469893 -89.297014)
		(end 135.971534 -88.994234)
		(width 0.0889)
		(layer "B.Cu")
		(net "P3E_CPU1_PE3_MP_TXN<10>")
	)
	(arc
		(start 136.465564 -90.870786)
		(mid 136.544786 -90.581668)
		(end 136.471914 -90.290904)
		(width 0.0889)
		(layer "B.Cu")
		(net "P3E_CPU1_PE3_MP_TXN<10>")
	)
	(arc
		(start 131.149598 -90.775536)
		(mid 131.009519 -90.918272)
		(end 130.817874 -90.975434)
		(width 0.0889)
		(layer "B.Cu")
		(net "P3E_CPU1_PE3_MP_TXN<10>")
	)
	(arc
		(start 133.724904 -89.289636)
		(mid 133.583221 -89.43344)
		(end 133.38937 -89.489788)
		(width 0.0889)
		(layer "B.Cu")
		(net "P3E_CPU1_PE3_MP_TXN<10>")
	)
	(arc
		(start 129.437384 -93.355922)
		(mid 129.486139 -93.552274)
		(end 129.432558 -93.747336)
		(width 0.0889)
		(layer "B.Cu")
		(net "P3E_CPU1_PE3_MP_TXN<10>")
	)
	(arc
		(start 136.465564 -91.861386)
		(mid 136.544786 -91.572268)
		(end 136.471914 -91.281504)
		(width 0.0889)
		(layer "B.Cu")
		(net "P3E_CPU1_PE3_MP_TXN<10>")
	)
	(arc
		(start 134.583424 -88.794336)
		(mid 134.443345 -88.937072)
		(end 134.2517 -88.994234)
		(width 0.0889)
		(layer "B.Cu")
		(net "P3E_CPU1_PE3_MP_TXN<10>")
	)
	(arc
		(start 135.938768 -88.994234)
		(mid 135.747126 -88.937068)
		(end 135.607044 -88.794336)
		(width 0.0889)
		(layer "B.Cu")
		(net "P3E_CPU1_PE3_MP_TXN<10>")
	)
	(arc
		(start 129.437384 -95.337122)
		(mid 129.486139 -95.533474)
		(end 129.432558 -95.728536)
		(width 0.0889)
		(layer "B.Cu")
		(net "P3E_CPU1_PE3_MP_TXN<10>")
	)
	(arc
		(start 129.437384 -98.308922)
		(mid 129.486139 -98.505274)
		(end 129.432558 -98.700336)
		(width 0.0889)
		(layer "B.Cu")
		(net "P3E_CPU1_PE3_MP_TXN<10>")
	)
	(arc
		(start 137.655808 -95.928434)
		(mid 137.32289 -95.726443)
		(end 137.319258 -95.337122)
		(width 0.0889)
		(layer "B.Cu")
		(net "P3E_CPU1_PE3_MP_TXN<10>")
	)
	(arc
		(start 136.460738 -90.2716)
		(mid 136.411983 -90.075248)
		(end 136.465564 -89.880186)
		(width 0.0889)
		(layer "B.Cu")
		(net "P3E_CPU1_PE3_MP_TXN<10>")
	)
	(arc
		(start 129.922778 -91.470988)
		(mid 129.430388 -91.769921)
		(end 129.426208 -92.346018)
		(width 0.0889)
		(layer "B.Cu")
		(net "P3E_CPU1_PE3_MP_TXN<10>")
	)
	(arc
		(start 129.437384 -92.365322)
		(mid 129.486139 -92.561674)
		(end 129.432558 -92.756736)
		(width 0.0889)
		(layer "B.Cu")
		(net "P3E_CPU1_PE3_MP_TXN<10>")
	)
	(arc
		(start 129.437384 -97.318322)
		(mid 129.486139 -97.514674)
		(end 129.432558 -97.709736)
		(width 0.0889)
		(layer "B.Cu")
		(net "P3E_CPU1_PE3_MP_TXN<10>")
	)
	(arc
		(start 136.460738 -91.2622)
		(mid 136.411983 -91.065848)
		(end 136.465564 -90.870786)
		(width 0.0889)
		(layer "B.Cu")
		(net "P3E_CPU1_PE3_MP_TXN<10>")
	)
	(arc
		(start 129.432558 -97.709736)
		(mid 129.353336 -97.998854)
		(end 129.426208 -98.289618)
		(width 0.0889)
		(layer "B.Cu")
		(net "P3E_CPU1_PE3_MP_TXN<10>")
	)
	(arc
		(start 129.437384 -96.327722)
		(mid 129.486139 -96.524074)
		(end 129.432558 -96.719136)
		(width 0.0889)
		(layer "B.Cu")
		(net "P3E_CPU1_PE3_MP_TXN<10>")
	)
	(arc
		(start 137.324084 -94.33814)
		(mid 137.403215 -94.042738)
		(end 137.324084 -93.747336)
		(width 0.0889)
		(layer "B.Cu")
		(net "P3E_CPU1_PE3_MP_TXN<10>")
	)
	(arc
		(start 129.432558 -99.690936)
		(mid 129.353427 -99.986338)
		(end 129.432558 -100.28174)
		(width 0.0889)
		(layer "B.Cu")
		(net "P3E_CPU1_PE3_MP_TXN<10>")
	)
	(arc
		(start 129.437384 -99.299522)
		(mid 129.486139 -99.495874)
		(end 129.432558 -99.690936)
		(width 0.0889)
		(layer "B.Cu")
		(net "P3E_CPU1_PE3_MP_TXN<10>")
	)
	(arc
		(start 134.218934 -88.994234)
		(mid 133.93351 -89.077701)
		(end 133.724904 -89.289636)
		(width 0.0889)
		(layer "B.Cu")
		(net "P3E_CPU1_PE3_MP_TXN<10>")
	)
	(arc
		(start 130.785108 -90.975434)
		(mid 130.499684 -91.058901)
		(end 130.291078 -91.270836)
		(width 0.0889)
		(layer "B.Cu")
		(net "P3E_CPU1_PE3_MP_TXN<10>")
	)
	(arc
		(start 138.517122 -96.423734)
		(mid 138.323845 -96.367296)
		(end 138.182604 -96.223836)
		(width 0.0889)
		(layer "B.Cu")
		(net "P3E_CPU1_PE3_MP_TXN<10>")
	)
	(arc
		(start 133.356604 -89.489788)
		(mid 133.073387 -89.574069)
		(end 132.866384 -89.784936)
		(width 0.0889)
		(layer "B.Cu")
		(net "P3E_CPU1_PE3_MP_TXN<10>")
	)
	(arc
		(start 137.324084 -95.328486)
		(mid 137.403306 -95.039368)
		(end 137.330434 -94.748604)
		(width 0.0889)
		(layer "B.Cu")
		(net "P3E_CPU1_PE3_MP_TXN<10>")
	)
	(arc
		(start 129.432558 -100.28174)
		(mid 129.486057 -100.481638)
		(end 129.432558 -100.681536)
		(width 0.0889)
		(layer "B.Cu")
		(net "P3E_CPU1_PE3_MP_TXN<10>")
	)
	(arc
		(start 131.639818 -90.480388)
		(mid 131.356601 -90.564669)
		(end 131.149598 -90.775536)
		(width 0.0889)
		(layer "B.Cu")
		(net "P3E_CPU1_PE3_MP_TXN<10>")
	)
	(arc
		(start 129.432558 -94.33814)
		(mid 129.486057 -94.538038)
		(end 129.432558 -94.737936)
		(width 0.0889)
		(layer "B.Cu")
		(net "P3E_CPU1_PE3_MP_TXN<10>")
	)
	(arc
		(start 130.291078 -91.270836)
		(mid 130.149395 -91.41464)
		(end 129.955544 -91.470988)
		(width 0.0889)
		(layer "B.Cu")
		(net "P3E_CPU1_PE3_MP_TXN<10>")
	)
	(arc
		(start 129.432558 -96.719136)
		(mid 129.353336 -97.008254)
		(end 129.426208 -97.299018)
		(width 0.0889)
		(layer "B.Cu")
		(net "P3E_CPU1_PE3_MP_TXN<10>")
	)
	(arc
		(start 132.004562 -90.286078)
		(mid 131.858596 -90.428477)
		(end 131.661408 -90.480388)
		(width 0.0889)
		(layer "B.Cu")
		(net "P3E_CPU1_PE3_MP_TXN<10>")
	)
	(segment
		(start 133.665214 -94.538038)
		(end 134.236714 -94.538038)
		(width 0.1143)
		(layer "F.Cu")
		(net "P3E_CPU1_PE3_MP_RXP<9>")
	)
	(via
		(at 134.236714 -94.538038)
		(size 0.508)
		(drill 0.254)
		(layers "F.Cu" "B.Cu")
		(net "P3E_CPU1_PE3_MP_RXP<9>")
	)
	(via
		(at 1.78435 -107.9119)
		(size 0.508)
		(drill 0.254)
		(layers "F.Cu" "B.Cu")
		(net "P3E_CPU1_PE3_MP_RXP<9>")
	)
	(segment
		(start 133.896354 -102.252018)
		(end 133.890004 -102.262686)
		(width 0.0889)
		(layer "B.Cu")
		(net "P3E_CPU1_PE3_MP_RXP<9>")
	)
	(segment
		(start 82.541618 -120.851422)
		(end 73.992232 -119.141494)
		(width 0.1143)
		(layer "B.Cu")
		(net "P3E_CPU1_PE3_MP_RXP<9>")
	)
	(segment
		(start 133.890004 -96.319086)
		(end 133.885178 -96.327722)
		(width 0.0889)
		(layer "B.Cu")
		(net "P3E_CPU1_PE3_MP_RXP<9>")
	)
	(segment
		(start 133.890004 -95.328486)
		(end 133.885178 -95.337122)
		(width 0.0889)
		(layer "B.Cu")
		(net "P3E_CPU1_PE3_MP_RXP<9>")
	)
	(segment
		(start 133.838442 -107.409742)
		(end 133.863842 -107.435142)
		(width 0.0889)
		(layer "B.Cu")
		(net "P3E_CPU1_PE3_MP_RXP<9>")
	)
	(segment
		(start 133.890004 -102.662736)
		(end 134.0739 -102.981506)
		(width 0.0889)
		(layer "B.Cu")
		(net "P3E_CPU1_PE3_MP_RXP<9>")
	)
	(segment
		(start 133.890004 -102.262686)
		(end 133.885178 -102.271322)
		(width 0.0889)
		(layer "B.Cu")
		(net "P3E_CPU1_PE3_MP_RXP<9>")
	)
	(segment
		(start 122.620024 -120.357646)
		(end 117.02796 -119.239284)
		(width 0.1143)
		(layer "B.Cu")
		(net "P3E_CPU1_PE3_MP_RXP<9>")
	)
	(segment
		(start 133.890004 -100.681536)
		(end 133.896354 -100.692204)
		(width 0.0889)
		(layer "B.Cu")
		(net "P3E_CPU1_PE3_MP_RXP<9>")
	)
	(segment
		(start 133.863842 -107.435142)
		(end 133.863842 -107.45724)
		(width 0.0889)
		(layer "B.Cu")
		(net "P3E_CPU1_PE3_MP_RXP<9>")
	)
	(segment
		(start 134.0739 -106.8324)
		(end 133.838442 -107.067858)
		(width 0.0889)
		(layer "B.Cu")
		(net "P3E_CPU1_PE3_MP_RXP<9>")
	)
	(segment
		(start 30.367986 -122.7328)
		(end 20.99945 -119.38)
		(width 0.1143)
		(layer "B.Cu")
		(net "P3E_CPU1_PE3_MP_RXP<9>")
	)
	(segment
		(start 133.896354 -96.308418)
		(end 133.890004 -96.319086)
		(width 0.0889)
		(layer "B.Cu")
		(net "P3E_CPU1_PE3_MP_RXP<9>")
	)
	(segment
		(start 73.992232 -119.141494)
		(end 64.31026 -121.077736)
		(width 0.1143)
		(layer "B.Cu")
		(net "P3E_CPU1_PE3_MP_RXP<9>")
	)
	(segment
		(start 133.890004 -98.300286)
		(end 133.885178 -98.308922)
		(width 0.0889)
		(layer "B.Cu")
		(net "P3E_CPU1_PE3_MP_RXP<9>")
	)
	(segment
		(start 64.31026 -121.077736)
		(end 60.159646 -120.247664)
		(width 0.1143)
		(layer "B.Cu")
		(net "P3E_CPU1_PE3_MP_RXP<9>")
	)
	(segment
		(start 97.429828 -120.497092)
		(end 90.871294 -119.185436)
		(width 0.1143)
		(layer "B.Cu")
		(net "P3E_CPU1_PE3_MP_RXP<9>")
	)
	(segment
		(start 117.02796 -119.239284)
		(end 109.351318 -120.774714)
		(width 0.1143)
		(layer "B.Cu")
		(net "P3E_CPU1_PE3_MP_RXP<9>")
	)
	(segment
		(start 129.791968 -118.923308)
		(end 122.620024 -120.357646)
		(width 0.1143)
		(layer "B.Cu")
		(net "P3E_CPU1_PE3_MP_RXP<9>")
	)
	(segment
		(start 7.014972 -109.657134)
		(end 6.200902 -107.931966)
		(width 0.1143)
		(layer "B.Cu")
		(net "P3E_CPU1_PE3_MP_RXP<9>")
	)
	(segment
		(start 133.890004 -97.309686)
		(end 133.885178 -97.318322)
		(width 0.0889)
		(layer "B.Cu")
		(net "P3E_CPU1_PE3_MP_RXP<9>")
	)
	(segment
		(start 133.863842 -107.45724)
		(end 133.863842 -114.851434)
		(width 0.1143)
		(layer "B.Cu")
		(net "P3E_CPU1_PE3_MP_RXP<9>")
	)
	(segment
		(start 109.351318 -120.774714)
		(end 102.696264 -119.443754)
		(width 0.1143)
		(layer "B.Cu")
		(net "P3E_CPU1_PE3_MP_RXP<9>")
	)
	(segment
		(start 133.943598 -94.706948)
		(end 133.919722 -94.796102)
		(width 0.0889)
		(layer "B.Cu")
		(net "P3E_CPU1_PE3_MP_RXP<9>")
	)
	(segment
		(start 133.890004 -101.272086)
		(end 133.885178 -101.280722)
		(width 0.0889)
		(layer "B.Cu")
		(net "P3E_CPU1_PE3_MP_RXP<9>")
	)
	(segment
		(start 1.3843 -107.9119)
		(end 1.78435 -107.9119)
		(width 0.1143)
		(layer "B.Cu")
		(net "P3E_CPU1_PE3_MP_RXP<9>")
	)
	(segment
		(start 133.890004 -99.290886)
		(end 133.885178 -99.299522)
		(width 0.0889)
		(layer "B.Cu")
		(net "P3E_CPU1_PE3_MP_RXP<9>")
	)
	(segment
		(start 134.0739 -102.981506)
		(end 134.0739 -106.8324)
		(width 0.0889)
		(layer "B.Cu")
		(net "P3E_CPU1_PE3_MP_RXP<9>")
	)
	(segment
		(start 1.5748 -107.0991)
		(end 1.27 -107.4039)
		(width 0.1143)
		(layer "B.Cu")
		(net "P3E_CPU1_PE3_MP_RXP<9>")
	)
	(segment
		(start 60.159646 -120.247664)
		(end 34.926016 -122.7328)
		(width 0.1143)
		(layer "B.Cu")
		(net "P3E_CPU1_PE3_MP_RXP<9>")
	)
	(segment
		(start 90.871294 -119.185436)
		(end 82.541618 -120.851422)
		(width 0.1143)
		(layer "B.Cu")
		(net "P3E_CPU1_PE3_MP_RXP<9>")
	)
	(segment
		(start 8.80745 -111.449866)
		(end 7.014972 -109.657134)
		(width 0.1143)
		(layer "B.Cu")
		(net "P3E_CPU1_PE3_MP_RXP<9>")
	)
	(segment
		(start 16.083788 -114.464338)
		(end 8.80745 -111.449866)
		(width 0.1143)
		(layer "B.Cu")
		(net "P3E_CPU1_PE3_MP_RXP<9>")
	)
	(segment
		(start 4.570984 -107.0991)
		(end 1.5748 -107.0991)
		(width 0.1143)
		(layer "B.Cu")
		(net "P3E_CPU1_PE3_MP_RXP<9>")
	)
	(segment
		(start 102.696264 -119.443754)
		(end 97.429828 -120.497092)
		(width 0.1143)
		(layer "B.Cu")
		(net "P3E_CPU1_PE3_MP_RXP<9>")
	)
	(segment
		(start 1.27 -107.4039)
		(end 1.27 -107.7976)
		(width 0.1143)
		(layer "B.Cu")
		(net "P3E_CPU1_PE3_MP_RXP<9>")
	)
	(segment
		(start 1.27 -107.7976)
		(end 1.3843 -107.9119)
		(width 0.1143)
		(layer "B.Cu")
		(net "P3E_CPU1_PE3_MP_RXP<9>")
	)
	(segment
		(start 34.926016 -122.7328)
		(end 30.367986 -122.7328)
		(width 0.1143)
		(layer "B.Cu")
		(net "P3E_CPU1_PE3_MP_RXP<9>")
	)
	(segment
		(start 133.896354 -98.289618)
		(end 133.890004 -98.300286)
		(width 0.0889)
		(layer "B.Cu")
		(net "P3E_CPU1_PE3_MP_RXP<9>")
	)
	(segment
		(start 134.236714 -94.538038)
		(end 133.943598 -94.706948)
		(width 0.0889)
		(layer "B.Cu")
		(net "P3E_CPU1_PE3_MP_RXP<9>")
	)
	(segment
		(start 133.838442 -107.067858)
		(end 133.838442 -107.409742)
		(width 0.0889)
		(layer "B.Cu")
		(net "P3E_CPU1_PE3_MP_RXP<9>")
	)
	(segment
		(start 20.99945 -119.38)
		(end 16.083788 -114.464338)
		(width 0.1143)
		(layer "B.Cu")
		(net "P3E_CPU1_PE3_MP_RXP<9>")
	)
	(segment
		(start 6.200902 -107.931966)
		(end 4.570984 -107.0991)
		(width 0.1143)
		(layer "B.Cu")
		(net "P3E_CPU1_PE3_MP_RXP<9>")
	)
	(segment
		(start 133.896354 -97.299018)
		(end 133.890004 -97.309686)
		(width 0.0889)
		(layer "B.Cu")
		(net "P3E_CPU1_PE3_MP_RXP<9>")
	)
	(segment
		(start 133.896354 -99.280218)
		(end 133.890004 -99.290886)
		(width 0.0889)
		(layer "B.Cu")
		(net "P3E_CPU1_PE3_MP_RXP<9>")
	)
	(segment
		(start 133.863842 -114.851434)
		(end 129.791968 -118.923308)
		(width 0.1143)
		(layer "B.Cu")
		(net "P3E_CPU1_PE3_MP_RXP<9>")
	)
	(arc
		(start 133.885178 -96.327722)
		(mid 133.836423 -96.524074)
		(end 133.890004 -96.719136)
		(width 0.0889)
		(layer "B.Cu")
		(net "P3E_CPU1_PE3_MP_RXP<9>")
	)
	(arc
		(start 133.885178 -102.271322)
		(mid 133.836423 -102.467674)
		(end 133.890004 -102.662736)
		(width 0.0889)
		(layer "B.Cu")
		(net "P3E_CPU1_PE3_MP_RXP<9>")
	)
	(arc
		(start 133.896354 -100.692204)
		(mid 133.969152 -100.982967)
		(end 133.890004 -101.272086)
		(width 0.0889)
		(layer "B.Cu")
		(net "P3E_CPU1_PE3_MP_RXP<9>")
	)
	(arc
		(start 133.885178 -97.318322)
		(mid 133.836423 -97.514674)
		(end 133.890004 -97.709736)
		(width 0.0889)
		(layer "B.Cu")
		(net "P3E_CPU1_PE3_MP_RXP<9>")
	)
	(arc
		(start 133.890004 -99.690936)
		(mid 133.969135 -99.986338)
		(end 133.890004 -100.28174)
		(width 0.0889)
		(layer "B.Cu")
		(net "P3E_CPU1_PE3_MP_RXP<9>")
	)
	(arc
		(start 133.885178 -101.280722)
		(mid 133.836423 -101.477074)
		(end 133.890004 -101.672136)
		(width 0.0889)
		(layer "B.Cu")
		(net "P3E_CPU1_PE3_MP_RXP<9>")
	)
	(arc
		(start 133.885178 -99.299522)
		(mid 133.836423 -99.495874)
		(end 133.890004 -99.690936)
		(width 0.0889)
		(layer "B.Cu")
		(net "P3E_CPU1_PE3_MP_RXP<9>")
	)
	(arc
		(start 133.919722 -94.796102)
		(mid 133.968282 -95.065827)
		(end 133.890004 -95.328486)
		(width 0.0889)
		(layer "B.Cu")
		(net "P3E_CPU1_PE3_MP_RXP<9>")
	)
	(arc
		(start 133.890004 -95.728536)
		(mid 133.969226 -96.017654)
		(end 133.896354 -96.308418)
		(width 0.0889)
		(layer "B.Cu")
		(net "P3E_CPU1_PE3_MP_RXP<9>")
	)
	(arc
		(start 133.890004 -98.700336)
		(mid 133.969226 -98.989454)
		(end 133.896354 -99.280218)
		(width 0.0889)
		(layer "B.Cu")
		(net "P3E_CPU1_PE3_MP_RXP<9>")
	)
	(arc
		(start 133.890004 -96.719136)
		(mid 133.969226 -97.008254)
		(end 133.896354 -97.299018)
		(width 0.0889)
		(layer "B.Cu")
		(net "P3E_CPU1_PE3_MP_RXP<9>")
	)
	(arc
		(start 133.885178 -98.308922)
		(mid 133.836423 -98.505274)
		(end 133.890004 -98.700336)
		(width 0.0889)
		(layer "B.Cu")
		(net "P3E_CPU1_PE3_MP_RXP<9>")
	)
	(arc
		(start 133.890004 -101.672136)
		(mid 133.969226 -101.961254)
		(end 133.896354 -102.252018)
		(width 0.0889)
		(layer "B.Cu")
		(net "P3E_CPU1_PE3_MP_RXP<9>")
	)
	(arc
		(start 133.885178 -95.337122)
		(mid 133.836423 -95.533474)
		(end 133.890004 -95.728536)
		(width 0.0889)
		(layer "B.Cu")
		(net "P3E_CPU1_PE3_MP_RXP<9>")
	)
	(arc
		(start 133.890004 -97.709736)
		(mid 133.969226 -97.998854)
		(end 133.896354 -98.289618)
		(width 0.0889)
		(layer "B.Cu")
		(net "P3E_CPU1_PE3_MP_RXP<9>")
	)
	(arc
		(start 133.890004 -100.28174)
		(mid 133.836505 -100.481638)
		(end 133.890004 -100.681536)
		(width 0.0889)
		(layer "B.Cu")
		(net "P3E_CPU1_PE3_MP_RXP<9>")
	)
	(segment
		(start 1.146048 -104.88422)
		(end 1.146048 -106.601768)
		(width 0.1143)
		(layer "In4.Cu")
		(net "P3E_CPU1_PE3_MP_RXP<9>")
	)
	(segment
		(start 1.2954 -107.7976)
		(end 1.4097 -107.9119)
		(width 0.1143)
		(layer "In4.Cu")
		(net "P3E_CPU1_PE3_MP_RXP<9>")
	)
	(segment
		(start 1.4097 -107.9119)
		(end 1.78435 -107.9119)
		(width 0.1143)
		(layer "In4.Cu")
		(net "P3E_CPU1_PE3_MP_RXP<9>")
	)
	(segment
		(start 1.260348 -104.76992)
		(end 1.146048 -104.88422)
		(width 0.1143)
		(layer "In4.Cu")
		(net "P3E_CPU1_PE3_MP_RXP<9>")
	)
	(segment
		(start 1.146048 -106.601768)
		(end 1.2954 -106.75112)
		(width 0.1143)
		(layer "In4.Cu")
		(net "P3E_CPU1_PE3_MP_RXP<9>")
	)
	(segment
		(start 1.700022 -104.76992)
		(end 1.260348 -104.76992)
		(width 0.1143)
		(layer "In4.Cu")
		(net "P3E_CPU1_PE3_MP_RXP<9>")
	)
	(segment
		(start 1.2954 -106.75112)
		(end 1.2954 -107.7976)
		(width 0.1143)
		(layer "In4.Cu")
		(net "P3E_CPU1_PE3_MP_RXP<9>")
	)
	(segment
		(start 131.948174 -95.528384)
		(end 132.519674 -95.528384)
		(width 0.1143)
		(layer "F.Cu")
		(net "P3E_CPU1_PE3_MP_RXP<8>")
	)
	(via
		(at 132.519674 -95.528384)
		(size 0.508)
		(drill 0.254)
		(layers "F.Cu" "B.Cu")
		(net "P3E_CPU1_PE3_MP_RXP<8>")
	)
	(segment
		(start -2.607056 -105.860342)
		(end 4.800346 -105.860342)
		(width 0.1143)
		(layer "B.Cu")
		(net "P3E_CPU1_PE3_MP_RXP<8>")
	)
	(segment
		(start 132.87121 -102.271322)
		(end 132.866384 -102.262686)
		(width 0.0889)
		(layer "B.Cu")
		(net "P3E_CPU1_PE3_MP_RXP<8>")
	)
	(segment
		(start 9.494774 -110.427262)
		(end 16.777462 -113.444274)
		(width 0.1143)
		(layer "B.Cu")
		(net "P3E_CPU1_PE3_MP_RXP<8>")
	)
	(segment
		(start 132.6261 -107.115864)
		(end 132.6261 -107.093766)
		(width 0.0889)
		(layer "B.Cu")
		(net "P3E_CPU1_PE3_MP_RXP<8>")
	)
	(segment
		(start 21.64334 -118.310406)
		(end 30.557724 -121.5009)
		(width 0.1143)
		(layer "B.Cu")
		(net "P3E_CPU1_PE3_MP_RXP<8>")
	)
	(segment
		(start 82.922872 -119.52605)
		(end 91.251024 -117.860572)
		(width 0.1143)
		(layer "B.Cu")
		(net "P3E_CPU1_PE3_MP_RXP<8>")
	)
	(segment
		(start 132.87121 -101.280722)
		(end 132.866384 -101.272086)
		(width 0.0889)
		(layer "B.Cu")
		(net "P3E_CPU1_PE3_MP_RXP<8>")
	)
	(segment
		(start 132.81279 -95.697548)
		(end 132.519674 -95.528384)
		(width 0.0889)
		(layer "B.Cu")
		(net "P3E_CPU1_PE3_MP_RXP<8>")
	)
	(segment
		(start 132.866384 -99.290886)
		(end 132.860034 -99.280218)
		(width 0.0889)
		(layer "B.Cu")
		(net "P3E_CPU1_PE3_MP_RXP<8>")
	)
	(segment
		(start 132.87121 -98.308922)
		(end 132.866384 -98.300286)
		(width 0.0889)
		(layer "B.Cu")
		(net "P3E_CPU1_PE3_MP_RXP<8>")
	)
	(segment
		(start 62.30493 -119.305578)
		(end 64.198754 -119.684546)
		(width 0.1143)
		(layer "B.Cu")
		(net "P3E_CPU1_PE3_MP_RXP<8>")
	)
	(segment
		(start 132.866384 -97.309686)
		(end 132.860034 -97.299018)
		(width 0.0889)
		(layer "B.Cu")
		(net "P3E_CPU1_PE3_MP_RXP<8>")
	)
	(segment
		(start 102.721156 -118.044214)
		(end 109.14507 -119.3292)
		(width 0.1143)
		(layer "B.Cu")
		(net "P3E_CPU1_PE3_MP_RXP<8>")
	)
	(segment
		(start 132.866384 -98.300286)
		(end 132.860034 -98.289618)
		(width 0.0889)
		(layer "B.Cu")
		(net "P3E_CPU1_PE3_MP_RXP<8>")
	)
	(segment
		(start 132.6261 -107.093766)
		(end 132.6515 -107.068366)
		(width 0.0889)
		(layer "B.Cu")
		(net "P3E_CPU1_PE3_MP_RXP<8>")
	)
	(segment
		(start 91.251024 -117.860572)
		(end 97.445322 -119.09933)
		(width 0.1143)
		(layer "B.Cu")
		(net "P3E_CPU1_PE3_MP_RXP<8>")
	)
	(segment
		(start 132.6515 -107.068366)
		(end 132.6515 -106.718354)
		(width 0.0889)
		(layer "B.Cu")
		(net "P3E_CPU1_PE3_MP_RXP<8>")
	)
	(segment
		(start 8.059166 -108.991654)
		(end 9.494774 -110.427262)
		(width 0.1143)
		(layer "B.Cu")
		(net "P3E_CPU1_PE3_MP_RXP<8>")
	)
	(segment
		(start 4.800346 -105.860342)
		(end 7.146544 -107.058968)
		(width 0.1143)
		(layer "B.Cu")
		(net "P3E_CPU1_PE3_MP_RXP<8>")
	)
	(segment
		(start 122.030998 -118.819422)
		(end 129.673096 -117.29085)
		(width 0.1143)
		(layer "B.Cu")
		(net "P3E_CPU1_PE3_MP_RXP<8>")
	)
	(segment
		(start -2.500122 -104.76992)
		(end -2.72542 -104.76992)
		(width 0.1143)
		(layer "B.Cu")
		(net "P3E_CPU1_PE3_MP_RXP<8>")
	)
	(segment
		(start 132.6261 -114.337846)
		(end 132.6261 -107.115864)
		(width 0.1143)
		(layer "B.Cu")
		(net "P3E_CPU1_PE3_MP_RXP<8>")
	)
	(segment
		(start 132.87121 -97.318322)
		(end 132.866384 -97.309686)
		(width 0.0889)
		(layer "B.Cu")
		(net "P3E_CPU1_PE3_MP_RXP<8>")
	)
	(segment
		(start 132.6515 -106.718354)
		(end 132.981192 -106.388662)
		(width 0.0889)
		(layer "B.Cu")
		(net "P3E_CPU1_PE3_MP_RXP<8>")
	)
	(segment
		(start 64.198754 -119.684546)
		(end 73.956926 -117.73281)
		(width 0.1143)
		(layer "B.Cu")
		(net "P3E_CPU1_PE3_MP_RXP<8>")
	)
	(segment
		(start 62.30493 -119.305324)
		(end 62.30493 -119.305578)
		(width 0.1143)
		(layer "B.Cu")
		(net "P3E_CPU1_PE3_MP_RXP<8>")
	)
	(segment
		(start 132.860034 -100.692204)
		(end 132.866384 -100.681536)
		(width 0.0889)
		(layer "B.Cu")
		(net "P3E_CPU1_PE3_MP_RXP<8>")
	)
	(segment
		(start 60.411868 -118.926864)
		(end 62.30493 -119.305324)
		(width 0.1143)
		(layer "B.Cu")
		(net "P3E_CPU1_PE3_MP_RXP<8>")
	)
	(segment
		(start 34.278316 -121.5009)
		(end 60.411868 -118.926864)
		(width 0.1143)
		(layer "B.Cu")
		(net "P3E_CPU1_PE3_MP_RXP<8>")
	)
	(segment
		(start 132.87121 -99.299522)
		(end 132.866384 -99.290886)
		(width 0.0889)
		(layer "B.Cu")
		(net "P3E_CPU1_PE3_MP_RXP<8>")
	)
	(segment
		(start 30.557724 -121.5009)
		(end 34.278316 -121.5009)
		(width 0.1143)
		(layer "B.Cu")
		(net "P3E_CPU1_PE3_MP_RXP<8>")
	)
	(segment
		(start 97.445322 -119.09933)
		(end 102.721156 -118.044214)
		(width 0.1143)
		(layer "B.Cu")
		(net "P3E_CPU1_PE3_MP_RXP<8>")
	)
	(segment
		(start 129.673096 -117.29085)
		(end 132.6261 -114.337846)
		(width 0.1143)
		(layer "B.Cu")
		(net "P3E_CPU1_PE3_MP_RXP<8>")
	)
	(segment
		(start -2.72542 -104.76992)
		(end -2.95148 -104.99598)
		(width 0.1143)
		(layer "B.Cu")
		(net "P3E_CPU1_PE3_MP_RXP<8>")
	)
	(segment
		(start 7.146544 -107.058968)
		(end 8.059166 -108.991654)
		(width 0.1143)
		(layer "B.Cu")
		(net "P3E_CPU1_PE3_MP_RXP<8>")
	)
	(segment
		(start 132.981192 -103.452422)
		(end 132.866384 -103.253794)
		(width 0.0889)
		(layer "B.Cu")
		(net "P3E_CPU1_PE3_MP_RXP<8>")
	)
	(segment
		(start 132.836666 -95.786956)
		(end 132.81279 -95.697548)
		(width 0.0889)
		(layer "B.Cu")
		(net "P3E_CPU1_PE3_MP_RXP<8>")
	)
	(segment
		(start 132.981192 -106.388662)
		(end 132.981192 -103.452422)
		(width 0.0889)
		(layer "B.Cu")
		(net "P3E_CPU1_PE3_MP_RXP<8>")
	)
	(segment
		(start -2.95148 -105.515918)
		(end -2.607056 -105.860342)
		(width 0.1143)
		(layer "B.Cu")
		(net "P3E_CPU1_PE3_MP_RXP<8>")
	)
	(segment
		(start 132.866384 -102.262686)
		(end 132.860034 -102.252018)
		(width 0.0889)
		(layer "B.Cu")
		(net "P3E_CPU1_PE3_MP_RXP<8>")
	)
	(segment
		(start 116.862352 -117.785642)
		(end 122.030998 -118.819422)
		(width 0.1143)
		(layer "B.Cu")
		(net "P3E_CPU1_PE3_MP_RXP<8>")
	)
	(segment
		(start 109.14507 -119.3292)
		(end 116.862352 -117.785642)
		(width 0.1143)
		(layer "B.Cu")
		(net "P3E_CPU1_PE3_MP_RXP<8>")
	)
	(segment
		(start 16.777462 -113.444274)
		(end 21.64334 -118.310406)
		(width 0.1143)
		(layer "B.Cu")
		(net "P3E_CPU1_PE3_MP_RXP<8>")
	)
	(segment
		(start -2.95148 -104.99598)
		(end -2.95148 -105.515918)
		(width 0.1143)
		(layer "B.Cu")
		(net "P3E_CPU1_PE3_MP_RXP<8>")
	)
	(segment
		(start 73.956926 -117.73281)
		(end 82.922872 -119.52605)
		(width 0.1143)
		(layer "B.Cu")
		(net "P3E_CPU1_PE3_MP_RXP<8>")
	)
	(segment
		(start 132.87121 -96.327722)
		(end 132.866384 -96.319086)
		(width 0.0889)
		(layer "B.Cu")
		(net "P3E_CPU1_PE3_MP_RXP<8>")
	)
	(segment
		(start 132.866384 -96.319086)
		(end 132.860034 -96.308418)
		(width 0.0889)
		(layer "B.Cu")
		(net "P3E_CPU1_PE3_MP_RXP<8>")
	)
	(arc
		(start 132.866384 -96.719136)
		(mid 132.919854 -96.524073)
		(end 132.87121 -96.327722)
		(width 0.0889)
		(layer "B.Cu")
		(net "P3E_CPU1_PE3_MP_RXP<8>")
	)
	(arc
		(start 132.866384 -103.253794)
		(mid 132.787253 -102.958282)
		(end 132.866384 -102.662736)
		(width 0.0889)
		(layer "B.Cu")
		(net "P3E_CPU1_PE3_MP_RXP<8>")
	)
	(arc
		(start 132.866384 -100.681536)
		(mid 132.919883 -100.481638)
		(end 132.866384 -100.28174)
		(width 0.0889)
		(layer "B.Cu")
		(net "P3E_CPU1_PE3_MP_RXP<8>")
	)
	(arc
		(start 132.866384 -100.28174)
		(mid 132.787253 -99.986338)
		(end 132.866384 -99.690936)
		(width 0.0889)
		(layer "B.Cu")
		(net "P3E_CPU1_PE3_MP_RXP<8>")
	)
	(arc
		(start 132.866384 -101.672136)
		(mid 132.919854 -101.477073)
		(end 132.87121 -101.280722)
		(width 0.0889)
		(layer "B.Cu")
		(net "P3E_CPU1_PE3_MP_RXP<8>")
	)
	(arc
		(start 132.866384 -101.272086)
		(mid 132.787162 -100.982968)
		(end 132.860034 -100.692204)
		(width 0.0889)
		(layer "B.Cu")
		(net "P3E_CPU1_PE3_MP_RXP<8>")
	)
	(arc
		(start 132.866384 -99.690936)
		(mid 132.919854 -99.495873)
		(end 132.87121 -99.299522)
		(width 0.0889)
		(layer "B.Cu")
		(net "P3E_CPU1_PE3_MP_RXP<8>")
	)
	(arc
		(start 132.866384 -98.700336)
		(mid 132.919854 -98.505273)
		(end 132.87121 -98.308922)
		(width 0.0889)
		(layer "B.Cu")
		(net "P3E_CPU1_PE3_MP_RXP<8>")
	)
	(arc
		(start 132.860034 -96.308418)
		(mid 132.787639 -96.050406)
		(end 132.836666 -95.786956)
		(width 0.0889)
		(layer "B.Cu")
		(net "P3E_CPU1_PE3_MP_RXP<8>")
	)
	(arc
		(start 132.860034 -97.299018)
		(mid 132.787236 -97.008255)
		(end 132.866384 -96.719136)
		(width 0.0889)
		(layer "B.Cu")
		(net "P3E_CPU1_PE3_MP_RXP<8>")
	)
	(arc
		(start 132.866384 -97.709736)
		(mid 132.919854 -97.514673)
		(end 132.87121 -97.318322)
		(width 0.0889)
		(layer "B.Cu")
		(net "P3E_CPU1_PE3_MP_RXP<8>")
	)
	(arc
		(start 132.860034 -98.289618)
		(mid 132.787236 -97.998855)
		(end 132.866384 -97.709736)
		(width 0.0889)
		(layer "B.Cu")
		(net "P3E_CPU1_PE3_MP_RXP<8>")
	)
	(arc
		(start 132.860034 -99.280218)
		(mid 132.787236 -98.989455)
		(end 132.866384 -98.700336)
		(width 0.0889)
		(layer "B.Cu")
		(net "P3E_CPU1_PE3_MP_RXP<8>")
	)
	(arc
		(start 132.860034 -102.252018)
		(mid 132.787236 -101.961255)
		(end 132.866384 -101.672136)
		(width 0.0889)
		(layer "B.Cu")
		(net "P3E_CPU1_PE3_MP_RXP<8>")
	)
	(arc
		(start 132.866384 -102.662736)
		(mid 132.919854 -102.467673)
		(end 132.87121 -102.271322)
		(width 0.0889)
		(layer "B.Cu")
		(net "P3E_CPU1_PE3_MP_RXP<8>")
	)
	(segment
		(start 134.523734 -89.089738)
		(end 135.095234 -89.089738)
		(width 0.1143)
		(layer "F.Cu")
		(net "P3E_CPU1_PE3_MP_RXP<15>")
	)
	(via
		(at 137.23874 -112.587786)
		(size 0.1016)
		(drill 0.0508)
		(layers "F.Cu" "B.Cu")
		(net "P3E_CPU1_PE3_MP_RXP<15>")
	)
	(via
		(at 4.009644 -112.21339)
		(size 0.508)
		(drill 0.254)
		(layers "F.Cu" "B.Cu")
		(net "P3E_CPU1_PE3_MP_RXP<15>")
	)
	(via
		(at 135.095234 -89.089738)
		(size 0.508)
		(drill 0.254)
		(layers "F.Cu" "B.Cu")
		(net "P3E_CPU1_PE3_MP_RXP<15>")
	)
	(segment
		(start 129.057146 -122.23369)
		(end 128.72085 -122.301)
		(width 0.1143)
		(layer "B.Cu")
		(net "P3E_CPU1_PE3_MP_RXP<15>")
	)
	(segment
		(start 13.659866 -117.329712)
		(end 12.069572 -115.739418)
		(width 0.1143)
		(layer "B.Cu")
		(net "P3E_CPU1_PE3_MP_RXP<15>")
	)
	(segment
		(start 3.495294 -112.489488)
		(end 3.495294 -112.32769)
		(width 0.1143)
		(layer "B.Cu")
		(net "P3E_CPU1_PE3_MP_RXP<15>")
	)
	(segment
		(start 135.441944 -92.261436)
		(end 135.44677 -92.2528)
		(width 0.0889)
		(layer "B.Cu")
		(net "P3E_CPU1_PE3_MP_RXP<15>")
	)
	(segment
		(start 109.54639 -124.180092)
		(end 101.475032 -122.565922)
		(width 0.1143)
		(layer "B.Cu")
		(net "P3E_CPU1_PE3_MP_RXP<15>")
	)
	(segment
		(start 135.38835 -89.258648)
		(end 135.095234 -89.089738)
		(width 0.0889)
		(layer "B.Cu")
		(net "P3E_CPU1_PE3_MP_RXP<15>")
	)
	(segment
		(start 4.40436 -112.89284)
		(end 3.898646 -112.89284)
		(width 0.1143)
		(layer "B.Cu")
		(net "P3E_CPU1_PE3_MP_RXP<15>")
	)
	(segment
		(start 135.441944 -90.280236)
		(end 135.44677 -90.2716)
		(width 0.0889)
		(layer "B.Cu")
		(net "P3E_CPU1_PE3_MP_RXP<15>")
	)
	(segment
		(start 73.872852 -122.136408)
		(end 64.657224 -123.979178)
		(width 0.1143)
		(layer "B.Cu")
		(net "P3E_CPU1_PE3_MP_RXP<15>")
	)
	(segment
		(start 137.26414 -101.274118)
		(end 136.39419 -100.404168)
		(width 0.0889)
		(layer "B.Cu")
		(net "P3E_CPU1_PE3_MP_RXP<15>")
	)
	(segment
		(start 135.96493 -93.147134)
		(end 135.932164 -93.147134)
		(width 0.0889)
		(layer "B.Cu")
		(net "P3E_CPU1_PE3_MP_RXP<15>")
	)
	(segment
		(start 137.26414 -104.08539)
		(end 137.26414 -101.274118)
		(width 0.0889)
		(layer "B.Cu")
		(net "P3E_CPU1_PE3_MP_RXP<15>")
	)
	(segment
		(start 136.30529 -96.327722)
		(end 136.300464 -96.319086)
		(width 0.0889)
		(layer "B.Cu")
		(net "P3E_CPU1_PE3_MP_RXP<15>")
	)
	(segment
		(start 82.24901 -123.811792)
		(end 73.872852 -122.136408)
		(width 0.1143)
		(layer "B.Cu")
		(net "P3E_CPU1_PE3_MP_RXP<15>")
	)
	(segment
		(start 128.631188 -122.435366)
		(end 122.724164 -123.617228)
		(width 0.1143)
		(layer "B.Cu")
		(net "P3E_CPU1_PE3_MP_RXP<15>")
	)
	(segment
		(start 137.23874 -115.26266)
		(end 130.424428 -122.076718)
		(width 0.1143)
		(layer "B.Cu")
		(net "P3E_CPU1_PE3_MP_RXP<15>")
	)
	(segment
		(start 129.527808 -122.256042)
		(end 129.191512 -122.323352)
		(width 0.1143)
		(layer "B.Cu")
		(net "P3E_CPU1_PE3_MP_RXP<15>")
	)
	(segment
		(start 136.30275 -99.295204)
		(end 136.301988 -99.29368)
		(width 0.0889)
		(layer "B.Cu")
		(net "P3E_CPU1_PE3_MP_RXP<15>")
	)
	(segment
		(start 130.088132 -122.144028)
		(end 129.953766 -122.054366)
		(width 0.1143)
		(layer "B.Cu")
		(net "P3E_CPU1_PE3_MP_RXP<15>")
	)
	(segment
		(start 136.296654 -100.275136)
		(end 136.296146 -100.274628)
		(width 0.0889)
		(layer "B.Cu")
		(net "P3E_CPU1_PE3_MP_RXP<15>")
	)
	(segment
		(start 136.299956 -99.69119)
		(end 136.30783 -99.677474)
		(width 0.0889)
		(layer "B.Cu")
		(net "P3E_CPU1_PE3_MP_RXP<15>")
	)
	(segment
		(start 135.412226 -89.347802)
		(end 135.38835 -89.258648)
		(width 0.0889)
		(layer "B.Cu")
		(net "P3E_CPU1_PE3_MP_RXP<15>")
	)
	(segment
		(start 17.536922 -122.302016)
		(end 16.562324 -121.896124)
		(width 0.1143)
		(layer "B.Cu")
		(net "P3E_CPU1_PE3_MP_RXP<15>")
	)
	(segment
		(start 136.301988 -99.29368)
		(end 136.30148 -99.292918)
		(width 0.0889)
		(layer "B.Cu")
		(net "P3E_CPU1_PE3_MP_RXP<15>")
	)
	(segment
		(start 136.300464 -96.319086)
		(end 136.294114 -96.308418)
		(width 0.0889)
		(layer "B.Cu")
		(net "P3E_CPU1_PE3_MP_RXP<15>")
	)
	(segment
		(start 135.435594 -90.290904)
		(end 135.441944 -90.280236)
		(width 0.0889)
		(layer "B.Cu")
		(net "P3E_CPU1_PE3_MP_RXP<15>")
	)
	(segment
		(start 136.30529 -97.318322)
		(end 136.300464 -97.309686)
		(width 0.0889)
		(layer "B.Cu")
		(net "P3E_CPU1_PE3_MP_RXP<15>")
	)
	(segment
		(start 64.657224 -123.979178)
		(end 60.383166 -123.124468)
		(width 0.1143)
		(layer "B.Cu")
		(net "P3E_CPU1_PE3_MP_RXP<15>")
	)
	(segment
		(start 9.798812 -114.798856)
		(end 7.528052 -113.85804)
		(width 0.1143)
		(layer "B.Cu")
		(net "P3E_CPU1_PE3_MP_RXP<15>")
	)
	(segment
		(start 135.441944 -91.270836)
		(end 135.44677 -91.2622)
		(width 0.0889)
		(layer "B.Cu")
		(net "P3E_CPU1_PE3_MP_RXP<15>")
	)
	(segment
		(start 19.792442 -122.302016)
		(end 17.536922 -122.302016)
		(width 0.1143)
		(layer "B.Cu")
		(net "P3E_CPU1_PE3_MP_RXP<15>")
	)
	(segment
		(start 136.30529 -99.299522)
		(end 136.30275 -99.295204)
		(width 0.0889)
		(layer "B.Cu")
		(net "P3E_CPU1_PE3_MP_RXP<15>")
	)
	(segment
		(start 136.30148 -99.292918)
		(end 136.300464 -99.290886)
		(width 0.0889)
		(layer "B.Cu")
		(net "P3E_CPU1_PE3_MP_RXP<15>")
	)
	(segment
		(start 96.93148 -123.474734)
		(end 90.432382 -122.175016)
		(width 0.1143)
		(layer "B.Cu")
		(net "P3E_CPU1_PE3_MP_RXP<15>")
	)
	(segment
		(start 3.495294 -112.32769)
		(end 3.609594 -112.21339)
		(width 0.1143)
		(layer "B.Cu")
		(net "P3E_CPU1_PE3_MP_RXP<15>")
	)
	(segment
		(start 137.23874 -112.587786)
		(end 137.23874 -104.132888)
		(width 0.1143)
		(layer "B.Cu")
		(net "P3E_CPU1_PE3_MP_RXP<15>")
	)
	(segment
		(start 16.562324 -121.896124)
		(end 14.224 -119.5578)
		(width 0.1143)
		(layer "B.Cu")
		(net "P3E_CPU1_PE3_MP_RXP<15>")
	)
	(segment
		(start 136.294114 -94.748604)
		(end 136.300464 -94.737936)
		(width 0.0889)
		(layer "B.Cu")
		(net "P3E_CPU1_PE3_MP_RXP<15>")
	)
	(segment
		(start 128.631188 -122.43562)
		(end 128.631188 -122.435366)
		(width 0.1143)
		(layer "B.Cu")
		(net "P3E_CPU1_PE3_MP_RXP<15>")
	)
	(segment
		(start 27.363928 -125.4379)
		(end 19.792442 -122.302016)
		(width 0.1143)
		(layer "B.Cu")
		(net "P3E_CPU1_PE3_MP_RXP<15>")
	)
	(segment
		(start 129.953766 -122.054366)
		(end 129.61747 -122.121676)
		(width 0.1143)
		(layer "B.Cu")
		(net "P3E_CPU1_PE3_MP_RXP<15>")
	)
	(segment
		(start 136.300464 -98.300286)
		(end 136.294114 -98.289618)
		(width 0.0889)
		(layer "B.Cu")
		(net "P3E_CPU1_PE3_MP_RXP<15>")
	)
	(segment
		(start 136.300464 -99.290886)
		(end 136.294114 -99.280218)
		(width 0.0889)
		(layer "B.Cu")
		(net "P3E_CPU1_PE3_MP_RXP<15>")
	)
	(segment
		(start 5.36956 -113.85804)
		(end 4.40436 -112.89284)
		(width 0.1143)
		(layer "B.Cu")
		(net "P3E_CPU1_PE3_MP_RXP<15>")
	)
	(segment
		(start 101.475032 -122.565922)
		(end 96.93148 -123.474734)
		(width 0.1143)
		(layer "B.Cu")
		(net "P3E_CPU1_PE3_MP_RXP<15>")
	)
	(segment
		(start 136.30529 -98.308922)
		(end 136.300464 -98.300286)
		(width 0.0889)
		(layer "B.Cu")
		(net "P3E_CPU1_PE3_MP_RXP<15>")
	)
	(segment
		(start 14.224 -119.5578)
		(end 14.224 -117.8941)
		(width 0.1143)
		(layer "B.Cu")
		(net "P3E_CPU1_PE3_MP_RXP<15>")
	)
	(segment
		(start 12.069572 -115.739418)
		(end 9.798812 -114.798856)
		(width 0.1143)
		(layer "B.Cu")
		(net "P3E_CPU1_PE3_MP_RXP<15>")
	)
	(segment
		(start 36.894008 -125.4379)
		(end 27.363928 -125.4379)
		(width 0.1143)
		(layer "B.Cu")
		(net "P3E_CPU1_PE3_MP_RXP<15>")
	)
	(segment
		(start 137.23874 -104.132888)
		(end 137.23874 -104.11079)
		(width 0.0889)
		(layer "B.Cu")
		(net "P3E_CPU1_PE3_MP_RXP<15>")
	)
	(segment
		(start 14.224 -117.8941)
		(end 13.659866 -117.329712)
		(width 0.1143)
		(layer "B.Cu")
		(net "P3E_CPU1_PE3_MP_RXP<15>")
	)
	(segment
		(start 3.609594 -112.21339)
		(end 4.009644 -112.21339)
		(width 0.1143)
		(layer "B.Cu")
		(net "P3E_CPU1_PE3_MP_RXP<15>")
	)
	(segment
		(start 3.898646 -112.89284)
		(end 3.495294 -112.489488)
		(width 0.1143)
		(layer "B.Cu")
		(net "P3E_CPU1_PE3_MP_RXP<15>")
	)
	(segment
		(start 117.542818 -122.580908)
		(end 117.54231 -122.580908)
		(width 0.1143)
		(layer "B.Cu")
		(net "P3E_CPU1_PE3_MP_RXP<15>")
	)
	(segment
		(start 122.724164 -123.617228)
		(end 122.723402 -123.617482)
		(width 0.1143)
		(layer "B.Cu")
		(net "P3E_CPU1_PE3_MP_RXP<15>")
	)
	(segment
		(start 137.23874 -112.587786)
		(end 137.23874 -115.26266)
		(width 0.1143)
		(layer "B.Cu")
		(net "P3E_CPU1_PE3_MP_RXP<15>")
	)
	(segment
		(start 135.435594 -91.281504)
		(end 135.441944 -91.270836)
		(width 0.0889)
		(layer "B.Cu")
		(net "P3E_CPU1_PE3_MP_RXP<15>")
	)
	(segment
		(start 136.300464 -97.309686)
		(end 136.294114 -97.299018)
		(width 0.0889)
		(layer "B.Cu")
		(net "P3E_CPU1_PE3_MP_RXP<15>")
	)
	(segment
		(start 136.30529 -95.337122)
		(end 136.300464 -95.328486)
		(width 0.0889)
		(layer "B.Cu")
		(net "P3E_CPU1_PE3_MP_RXP<15>")
	)
	(segment
		(start 117.54231 -122.580908)
		(end 109.54639 -124.180092)
		(width 0.1143)
		(layer "B.Cu")
		(net "P3E_CPU1_PE3_MP_RXP<15>")
	)
	(segment
		(start 137.23874 -104.11079)
		(end 137.26414 -104.08539)
		(width 0.0889)
		(layer "B.Cu")
		(net "P3E_CPU1_PE3_MP_RXP<15>")
	)
	(segment
		(start 129.61747 -122.121676)
		(end 129.527808 -122.256042)
		(width 0.1143)
		(layer "B.Cu")
		(net "P3E_CPU1_PE3_MP_RXP<15>")
	)
	(segment
		(start 90.432382 -122.175016)
		(end 82.24901 -123.811792)
		(width 0.1143)
		(layer "B.Cu")
		(net "P3E_CPU1_PE3_MP_RXP<15>")
	)
	(segment
		(start 129.191512 -122.323352)
		(end 129.057146 -122.23369)
		(width 0.1143)
		(layer "B.Cu")
		(net "P3E_CPU1_PE3_MP_RXP<15>")
	)
	(segment
		(start 7.528052 -113.85804)
		(end 5.36956 -113.85804)
		(width 0.1143)
		(layer "B.Cu")
		(net "P3E_CPU1_PE3_MP_RXP<15>")
	)
	(segment
		(start 122.723402 -123.617482)
		(end 117.542818 -122.580908)
		(width 0.1143)
		(layer "B.Cu")
		(net "P3E_CPU1_PE3_MP_RXP<15>")
	)
	(segment
		(start 60.383166 -123.124468)
		(end 36.894008 -125.4379)
		(width 0.1143)
		(layer "B.Cu")
		(net "P3E_CPU1_PE3_MP_RXP<15>")
	)
	(segment
		(start 128.72085 -122.301)
		(end 128.631188 -122.43562)
		(width 0.1143)
		(layer "B.Cu")
		(net "P3E_CPU1_PE3_MP_RXP<15>")
	)
	(segment
		(start 135.435594 -92.272104)
		(end 135.441944 -92.261436)
		(width 0.0889)
		(layer "B.Cu")
		(net "P3E_CPU1_PE3_MP_RXP<15>")
	)
	(segment
		(start 130.424428 -122.076718)
		(end 130.088132 -122.144028)
		(width 0.1143)
		(layer "B.Cu")
		(net "P3E_CPU1_PE3_MP_RXP<15>")
	)
	(arc
		(start 136.300464 -97.709736)
		(mid 136.353934 -97.514673)
		(end 136.30529 -97.318322)
		(width 0.0889)
		(layer "B.Cu")
		(net "P3E_CPU1_PE3_MP_RXP<15>")
	)
	(arc
		(start 136.300464 -98.700336)
		(mid 136.353934 -98.505273)
		(end 136.30529 -98.308922)
		(width 0.0889)
		(layer "B.Cu")
		(net "P3E_CPU1_PE3_MP_RXP<15>")
	)
	(arc
		(start 136.39419 -100.404168)
		(mid 136.358175 -100.36469)
		(end 136.325864 -100.322126)
		(width 0.0889)
		(layer "B.Cu")
		(net "P3E_CPU1_PE3_MP_RXP<15>")
	)
	(arc
		(start 136.300464 -94.737936)
		(mid 136.353963 -94.538038)
		(end 136.300464 -94.33814)
		(width 0.0889)
		(layer "B.Cu")
		(net "P3E_CPU1_PE3_MP_RXP<15>")
	)
	(arc
		(start 136.325864 -100.322126)
		(mid 136.310702 -100.298977)
		(end 136.296654 -100.275136)
		(width 0.0889)
		(layer "B.Cu")
		(net "P3E_CPU1_PE3_MP_RXP<15>")
	)
	(arc
		(start 136.296146 -100.274628)
		(mid 136.221102 -99.982416)
		(end 136.299956 -99.69119)
		(width 0.0889)
		(layer "B.Cu")
		(net "P3E_CPU1_PE3_MP_RXP<15>")
	)
	(arc
		(start 136.294114 -98.289618)
		(mid 136.221316 -97.998855)
		(end 136.300464 -97.709736)
		(width 0.0889)
		(layer "B.Cu")
		(net "P3E_CPU1_PE3_MP_RXP<15>")
	)
	(arc
		(start 136.294114 -97.299018)
		(mid 136.221316 -97.008255)
		(end 136.300464 -96.719136)
		(width 0.0889)
		(layer "B.Cu")
		(net "P3E_CPU1_PE3_MP_RXP<15>")
	)
	(arc
		(start 136.300464 -95.728536)
		(mid 136.353934 -95.533473)
		(end 136.30529 -95.337122)
		(width 0.0889)
		(layer "B.Cu")
		(net "P3E_CPU1_PE3_MP_RXP<15>")
	)
	(arc
		(start 135.44677 -90.2716)
		(mid 135.495525 -90.075248)
		(end 135.441944 -89.880186)
		(width 0.0889)
		(layer "B.Cu")
		(net "P3E_CPU1_PE3_MP_RXP<15>")
	)
	(arc
		(start 136.300464 -95.328486)
		(mid 136.221242 -95.039368)
		(end 136.294114 -94.748604)
		(width 0.0889)
		(layer "B.Cu")
		(net "P3E_CPU1_PE3_MP_RXP<15>")
	)
	(arc
		(start 136.300464 -96.719136)
		(mid 136.353934 -96.524073)
		(end 136.30529 -96.327722)
		(width 0.0889)
		(layer "B.Cu")
		(net "P3E_CPU1_PE3_MP_RXP<15>")
	)
	(arc
		(start 135.441944 -90.870786)
		(mid 135.362722 -90.581668)
		(end 135.435594 -90.290904)
		(width 0.0889)
		(layer "B.Cu")
		(net "P3E_CPU1_PE3_MP_RXP<15>")
	)
	(arc
		(start 136.300464 -94.33814)
		(mid 136.221333 -94.042738)
		(end 136.300464 -93.747336)
		(width 0.0889)
		(layer "B.Cu")
		(net "P3E_CPU1_PE3_MP_RXP<15>")
	)
	(arc
		(start 135.44677 -92.2528)
		(mid 135.495525 -92.056448)
		(end 135.441944 -91.861386)
		(width 0.0889)
		(layer "B.Cu")
		(net "P3E_CPU1_PE3_MP_RXP<15>")
	)
	(arc
		(start 135.44677 -91.2622)
		(mid 135.495525 -91.065848)
		(end 135.441944 -90.870786)
		(width 0.0889)
		(layer "B.Cu")
		(net "P3E_CPU1_PE3_MP_RXP<15>")
	)
	(arc
		(start 136.30783 -99.677474)
		(mid 136.354024 -99.488169)
		(end 136.30529 -99.299522)
		(width 0.0889)
		(layer "B.Cu")
		(net "P3E_CPU1_PE3_MP_RXP<15>")
	)
	(arc
		(start 135.441944 -91.861386)
		(mid 135.362722 -91.572268)
		(end 135.435594 -91.281504)
		(width 0.0889)
		(layer "B.Cu")
		(net "P3E_CPU1_PE3_MP_RXP<15>")
	)
	(arc
		(start 136.300464 -93.747336)
		(mid 136.303212 -93.351869)
		(end 135.96493 -93.147134)
		(width 0.0889)
		(layer "B.Cu")
		(net "P3E_CPU1_PE3_MP_RXP<15>")
	)
	(arc
		(start 136.294114 -99.280218)
		(mid 136.221316 -98.989455)
		(end 136.300464 -98.700336)
		(width 0.0889)
		(layer "B.Cu")
		(net "P3E_CPU1_PE3_MP_RXP<15>")
	)
	(arc
		(start 135.441944 -89.880186)
		(mid 135.363607 -89.61753)
		(end 135.412226 -89.347802)
		(width 0.0889)
		(layer "B.Cu")
		(net "P3E_CPU1_PE3_MP_RXP<15>")
	)
	(arc
		(start 136.294114 -96.308418)
		(mid 136.221316 -96.017655)
		(end 136.300464 -95.728536)
		(width 0.0889)
		(layer "B.Cu")
		(net "P3E_CPU1_PE3_MP_RXP<15>")
	)
	(arc
		(start 135.932164 -93.147134)
		(mid 135.439774 -92.848201)
		(end 135.435594 -92.272104)
		(width 0.0889)
		(layer "B.Cu")
		(net "P3E_CPU1_PE3_MP_RXP<15>")
	)
	(segment
		(start 1.700022 -100.769928)
		(end 1.260348 -100.769928)
		(width 0.1143)
		(layer "In4.Cu")
		(net "P3E_CPU1_PE3_MP_RXP<15>")
	)
	(segment
		(start 1.146048 -101.362764)
		(end 1.41224 -101.628956)
		(width 0.1143)
		(layer "In4.Cu")
		(net "P3E_CPU1_PE3_MP_RXP<15>")
	)
	(segment
		(start 8.786368 -101.628956)
		(end 9.4869 -102.329488)
		(width 0.1143)
		(layer "In4.Cu")
		(net "P3E_CPU1_PE3_MP_RXP<15>")
	)
	(segment
		(start 1.260348 -100.769928)
		(end 1.146048 -100.884228)
		(width 0.1143)
		(layer "In4.Cu")
		(net "P3E_CPU1_PE3_MP_RXP<15>")
	)
	(segment
		(start 4.672838 -111.65332)
		(end 3.693414 -111.65332)
		(width 0.1143)
		(layer "In4.Cu")
		(net "P3E_CPU1_PE3_MP_RXP<15>")
	)
	(segment
		(start 9.4869 -105.033064)
		(end 6.380988 -108.13923)
		(width 0.1143)
		(layer "In4.Cu")
		(net "P3E_CPU1_PE3_MP_RXP<15>")
	)
	(segment
		(start 3.520694 -112.09909)
		(end 3.634994 -112.21339)
		(width 0.1143)
		(layer "In4.Cu")
		(net "P3E_CPU1_PE3_MP_RXP<15>")
	)
	(segment
		(start 3.634994 -112.21339)
		(end 4.009644 -112.21339)
		(width 0.1143)
		(layer "In4.Cu")
		(net "P3E_CPU1_PE3_MP_RXP<15>")
	)
	(segment
		(start 5.104384 -111.222028)
		(end 4.672838 -111.65332)
		(width 0.1143)
		(layer "In4.Cu")
		(net "P3E_CPU1_PE3_MP_RXP<15>")
	)
	(segment
		(start 1.146048 -100.884228)
		(end 1.146048 -101.362764)
		(width 0.1143)
		(layer "In4.Cu")
		(net "P3E_CPU1_PE3_MP_RXP<15>")
	)
	(segment
		(start 6.380988 -108.13923)
		(end 5.104384 -111.222028)
		(width 0.1143)
		(layer "In4.Cu")
		(net "P3E_CPU1_PE3_MP_RXP<15>")
	)
	(segment
		(start 3.693414 -111.65332)
		(end 3.520694 -111.82604)
		(width 0.1143)
		(layer "In4.Cu")
		(net "P3E_CPU1_PE3_MP_RXP<15>")
	)
	(segment
		(start 3.520694 -111.82604)
		(end 3.520694 -112.09909)
		(width 0.1143)
		(layer "In4.Cu")
		(net "P3E_CPU1_PE3_MP_RXP<15>")
	)
	(segment
		(start 1.41224 -101.628956)
		(end 8.786368 -101.628956)
		(width 0.1143)
		(layer "In4.Cu")
		(net "P3E_CPU1_PE3_MP_RXP<15>")
	)
	(segment
		(start 9.4869 -102.329488)
		(end 9.4869 -105.033064)
		(width 0.1143)
		(layer "In4.Cu")
		(net "P3E_CPU1_PE3_MP_RXP<15>")
	)
	(segment
		(start 134.523734 -90.080338)
		(end 135.095234 -90.080338)
		(width 0.1143)
		(layer "F.Cu")
		(net "P3E_CPU1_PE3_MP_RXP<14>")
	)
	(via
		(at 6.209538 -112.865916)
		(size 0.508)
		(drill 0.254)
		(layers "F.Cu" "B.Cu")
		(net "P3E_CPU1_PE3_MP_RXP<14>")
	)
	(via
		(at 135.095234 -90.080338)
		(size 0.508)
		(drill 0.254)
		(layers "F.Cu" "B.Cu")
		(net "P3E_CPU1_PE3_MP_RXP<14>")
	)
	(segment
		(start 134.778242 -90.338402)
		(end 134.802118 -90.249248)
		(width 0.0889)
		(layer "B.Cu")
		(net "P3E_CPU1_PE3_MP_RXP<14>")
	)
	(segment
		(start 128.27889 -121.488708)
		(end 128.615186 -121.421652)
		(width 0.1143)
		(layer "B.Cu")
		(net "P3E_CPU1_PE3_MP_RXP<14>")
	)
	(segment
		(start 128.189228 -121.623328)
		(end 128.27889 -121.488708)
		(width 0.1143)
		(layer "B.Cu")
		(net "P3E_CPU1_PE3_MP_RXP<14>")
	)
	(segment
		(start 135.613394 -94.748604)
		(end 135.607044 -94.737936)
		(width 0.0889)
		(layer "B.Cu")
		(net "P3E_CPU1_PE3_MP_RXP<14>")
	)
	(segment
		(start 136.035542 -105.981754)
		(end 136.035542 -105.959656)
		(width 0.0889)
		(layer "B.Cu")
		(net "P3E_CPU1_PE3_MP_RXP<14>")
	)
	(segment
		(start 117.09527 -121.593356)
		(end 122.42673 -122.659648)
		(width 0.1143)
		(layer "B.Cu")
		(net "P3E_CPU1_PE3_MP_RXP<14>")
	)
	(segment
		(start 60.369196 -122.315986)
		(end 64.753998 -123.192794)
		(width 0.1143)
		(layer "B.Cu")
		(net "P3E_CPU1_PE3_MP_RXP<14>")
	)
	(segment
		(start 96.962214 -122.700796)
		(end 101.934264 -121.706386)
		(width 0.1143)
		(layer "B.Cu")
		(net "P3E_CPU1_PE3_MP_RXP<14>")
	)
	(segment
		(start 136.035542 -105.959656)
		(end 136.010142 -105.934256)
		(width 0.0889)
		(layer "B.Cu")
		(net "P3E_CPU1_PE3_MP_RXP<14>")
	)
	(segment
		(start 135.602218 -101.280722)
		(end 135.607044 -101.272086)
		(width 0.0889)
		(layer "B.Cu")
		(net "P3E_CPU1_PE3_MP_RXP<14>")
	)
	(segment
		(start 134.754874 -91.281504)
		(end 134.748524 -91.270836)
		(width 0.0889)
		(layer "B.Cu")
		(net "P3E_CPU1_PE3_MP_RXP<14>")
	)
	(segment
		(start 129.17551 -121.309384)
		(end 129.511806 -121.242074)
		(width 0.1143)
		(layer "B.Cu")
		(net "P3E_CPU1_PE3_MP_RXP<14>")
	)
	(segment
		(start 135.607044 -97.309686)
		(end 135.613394 -97.299018)
		(width 0.0889)
		(layer "B.Cu")
		(net "P3E_CPU1_PE3_MP_RXP<14>")
	)
	(segment
		(start 126.821946 -121.7803)
		(end 126.956312 -121.869962)
		(width 0.1143)
		(layer "B.Cu")
		(net "P3E_CPU1_PE3_MP_RXP<14>")
	)
	(segment
		(start 82.080354 -122.98934)
		(end 90.242644 -121.356882)
		(width 0.1143)
		(layer "B.Cu")
		(net "P3E_CPU1_PE3_MP_RXP<14>")
	)
	(segment
		(start 136.010142 -103.361236)
		(end 135.607044 -102.662482)
		(width 0.0889)
		(layer "B.Cu")
		(net "P3E_CPU1_PE3_MP_RXP<14>")
	)
	(segment
		(start 64.753998 -123.192794)
		(end 73.925938 -121.35866)
		(width 0.1143)
		(layer "B.Cu")
		(net "P3E_CPU1_PE3_MP_RXP<14>")
	)
	(segment
		(start 134.748524 -92.261436)
		(end 134.743698 -92.2528)
		(width 0.0889)
		(layer "B.Cu")
		(net "P3E_CPU1_PE3_MP_RXP<14>")
	)
	(segment
		(start 129.511806 -121.242074)
		(end 129.646172 -121.331736)
		(width 0.1143)
		(layer "B.Cu")
		(net "P3E_CPU1_PE3_MP_RXP<14>")
	)
	(segment
		(start 129.982468 -121.264426)
		(end 130.07213 -121.13006)
		(width 0.1143)
		(layer "B.Cu")
		(net "P3E_CPU1_PE3_MP_RXP<14>")
	)
	(segment
		(start 130.07213 -121.13006)
		(end 130.408426 -121.06275)
		(width 0.1143)
		(layer "B.Cu")
		(net "P3E_CPU1_PE3_MP_RXP<14>")
	)
	(segment
		(start 109.231684 -123.16587)
		(end 117.09527 -121.593356)
		(width 0.1143)
		(layer "B.Cu")
		(net "P3E_CPU1_PE3_MP_RXP<14>")
	)
	(segment
		(start 134.802118 -90.249248)
		(end 135.095234 -90.080338)
		(width 0.0889)
		(layer "B.Cu")
		(net "P3E_CPU1_PE3_MP_RXP<14>")
	)
	(segment
		(start 48.26 -123.50877)
		(end 60.369196 -122.315986)
		(width 0.1143)
		(layer "B.Cu")
		(net "P3E_CPU1_PE3_MP_RXP<14>")
	)
	(segment
		(start 6.323838 -112.351566)
		(end 6.837426 -112.351566)
		(width 0.1143)
		(layer "B.Cu")
		(net "P3E_CPU1_PE3_MP_RXP<14>")
	)
	(segment
		(start 135.602218 -95.337122)
		(end 135.607044 -95.328486)
		(width 0.0889)
		(layer "B.Cu")
		(net "P3E_CPU1_PE3_MP_RXP<14>")
	)
	(segment
		(start 127.718566 -121.600976)
		(end 127.852932 -121.690638)
		(width 0.1143)
		(layer "B.Cu")
		(net "P3E_CPU1_PE3_MP_RXP<14>")
	)
	(segment
		(start 20.79371 -121.931176)
		(end 27.481022 -124.7013)
		(width 0.1143)
		(layer "B.Cu")
		(net "P3E_CPU1_PE3_MP_RXP<14>")
	)
	(segment
		(start 127.852932 -121.690638)
		(end 128.189228 -121.623328)
		(width 0.1143)
		(layer "B.Cu")
		(net "P3E_CPU1_PE3_MP_RXP<14>")
	)
	(segment
		(start 73.925938 -121.35866)
		(end 82.080354 -122.98934)
		(width 0.1143)
		(layer "B.Cu")
		(net "P3E_CPU1_PE3_MP_RXP<14>")
	)
	(segment
		(start 136.035542 -115.43538)
		(end 136.035542 -105.981754)
		(width 0.1143)
		(layer "B.Cu")
		(net "P3E_CPU1_PE3_MP_RXP<14>")
	)
	(segment
		(start 135.602218 -97.318322)
		(end 135.607044 -97.309686)
		(width 0.0889)
		(layer "B.Cu")
		(net "P3E_CPU1_PE3_MP_RXP<14>")
	)
	(segment
		(start 135.602218 -99.299522)
		(end 135.607044 -99.290886)
		(width 0.0889)
		(layer "B.Cu")
		(net "P3E_CPU1_PE3_MP_RXP<14>")
	)
	(segment
		(start 136.010142 -105.934256)
		(end 136.010142 -103.361236)
		(width 0.0889)
		(layer "B.Cu")
		(net "P3E_CPU1_PE3_MP_RXP<14>")
	)
	(segment
		(start 6.209538 -112.465866)
		(end 6.323838 -112.351566)
		(width 0.1143)
		(layer "B.Cu")
		(net "P3E_CPU1_PE3_MP_RXP<14>")
	)
	(segment
		(start 135.607044 -96.319086)
		(end 135.613394 -96.308418)
		(width 0.0889)
		(layer "B.Cu")
		(net "P3E_CPU1_PE3_MP_RXP<14>")
	)
	(segment
		(start 135.602218 -98.308922)
		(end 135.607044 -98.300286)
		(width 0.0889)
		(layer "B.Cu")
		(net "P3E_CPU1_PE3_MP_RXP<14>")
	)
	(segment
		(start 135.607044 -98.300286)
		(end 135.613394 -98.289618)
		(width 0.0889)
		(layer "B.Cu")
		(net "P3E_CPU1_PE3_MP_RXP<14>")
	)
	(segment
		(start 130.408426 -121.06275)
		(end 136.035542 -115.43538)
		(width 0.1143)
		(layer "B.Cu")
		(net "P3E_CPU1_PE3_MP_RXP<14>")
	)
	(segment
		(start 101.934264 -121.706386)
		(end 109.231684 -123.16587)
		(width 0.1143)
		(layer "B.Cu")
		(net "P3E_CPU1_PE3_MP_RXP<14>")
	)
	(segment
		(start 135.613394 -100.692204)
		(end 135.607044 -100.681536)
		(width 0.0889)
		(layer "B.Cu")
		(net "P3E_CPU1_PE3_MP_RXP<14>")
	)
	(segment
		(start 127.292608 -121.802652)
		(end 127.38227 -121.668286)
		(width 0.1143)
		(layer "B.Cu")
		(net "P3E_CPU1_PE3_MP_RXP<14>")
	)
	(segment
		(start 134.748524 -91.270836)
		(end 134.743698 -91.2622)
		(width 0.0889)
		(layer "B.Cu")
		(net "P3E_CPU1_PE3_MP_RXP<14>")
	)
	(segment
		(start 129.646172 -121.331736)
		(end 129.982468 -121.264426)
		(width 0.1143)
		(layer "B.Cu")
		(net "P3E_CPU1_PE3_MP_RXP<14>")
	)
	(segment
		(start 90.242644 -121.356882)
		(end 96.962214 -122.700796)
		(width 0.1143)
		(layer "B.Cu")
		(net "P3E_CPU1_PE3_MP_RXP<14>")
	)
	(segment
		(start 122.42673 -122.659648)
		(end 126.821946 -121.7803)
		(width 0.1143)
		(layer "B.Cu")
		(net "P3E_CPU1_PE3_MP_RXP<14>")
	)
	(segment
		(start 127.38227 -121.668286)
		(end 127.718566 -121.600976)
		(width 0.1143)
		(layer "B.Cu")
		(net "P3E_CPU1_PE3_MP_RXP<14>")
	)
	(segment
		(start 27.481022 -124.7013)
		(end 36.151058 -124.7013)
		(width 0.1143)
		(layer "B.Cu")
		(net "P3E_CPU1_PE3_MP_RXP<14>")
	)
	(segment
		(start 7.523226 -113.037366)
		(end 14.995398 -116.132864)
		(width 0.1143)
		(layer "B.Cu")
		(net "P3E_CPU1_PE3_MP_RXP<14>")
	)
	(segment
		(start 128.615186 -121.421652)
		(end 128.749552 -121.511314)
		(width 0.1143)
		(layer "B.Cu")
		(net "P3E_CPU1_PE3_MP_RXP<14>")
	)
	(segment
		(start 128.749552 -121.511314)
		(end 129.085848 -121.444004)
		(width 0.1143)
		(layer "B.Cu")
		(net "P3E_CPU1_PE3_MP_RXP<14>")
	)
	(segment
		(start 14.995398 -116.132864)
		(end 20.79371 -121.931176)
		(width 0.1143)
		(layer "B.Cu")
		(net "P3E_CPU1_PE3_MP_RXP<14>")
	)
	(segment
		(start 135.607044 -99.290886)
		(end 135.613394 -99.280218)
		(width 0.0889)
		(layer "B.Cu")
		(net "P3E_CPU1_PE3_MP_RXP<14>")
	)
	(segment
		(start 126.956312 -121.869962)
		(end 127.292608 -121.802652)
		(width 0.1143)
		(layer "B.Cu")
		(net "P3E_CPU1_PE3_MP_RXP<14>")
	)
	(segment
		(start 6.837426 -112.351566)
		(end 7.523226 -113.037366)
		(width 0.1143)
		(layer "B.Cu")
		(net "P3E_CPU1_PE3_MP_RXP<14>")
	)
	(segment
		(start 129.085848 -121.444004)
		(end 129.17551 -121.309384)
		(width 0.1143)
		(layer "B.Cu")
		(net "P3E_CPU1_PE3_MP_RXP<14>")
	)
	(segment
		(start 134.754874 -92.272104)
		(end 134.748524 -92.261436)
		(width 0.0889)
		(layer "B.Cu")
		(net "P3E_CPU1_PE3_MP_RXP<14>")
	)
	(segment
		(start 48.259746 -123.50877)
		(end 48.26 -123.50877)
		(width 0.1143)
		(layer "B.Cu")
		(net "P3E_CPU1_PE3_MP_RXP<14>")
	)
	(segment
		(start 6.209538 -112.865916)
		(end 6.209538 -112.465866)
		(width 0.1143)
		(layer "B.Cu")
		(net "P3E_CPU1_PE3_MP_RXP<14>")
	)
	(segment
		(start 135.602218 -96.327722)
		(end 135.607044 -96.319086)
		(width 0.0889)
		(layer "B.Cu")
		(net "P3E_CPU1_PE3_MP_RXP<14>")
	)
	(segment
		(start 135.116824 -93.452188)
		(end 135.084058 -93.452188)
		(width 0.0889)
		(layer "B.Cu")
		(net "P3E_CPU1_PE3_MP_RXP<14>")
	)
	(segment
		(start 36.151058 -124.7013)
		(end 48.259746 -123.50877)
		(width 0.1143)
		(layer "B.Cu")
		(net "P3E_CPU1_PE3_MP_RXP<14>")
	)
	(arc
		(start 134.743698 -92.2528)
		(mid 134.694943 -92.056448)
		(end 134.748524 -91.861386)
		(width 0.0889)
		(layer "B.Cu")
		(net "P3E_CPU1_PE3_MP_RXP<14>")
	)
	(arc
		(start 135.613394 -98.289618)
		(mid 135.686192 -97.998855)
		(end 135.607044 -97.709736)
		(width 0.0889)
		(layer "B.Cu")
		(net "P3E_CPU1_PE3_MP_RXP<14>")
	)
	(arc
		(start 135.613394 -96.308418)
		(mid 135.686192 -96.017655)
		(end 135.607044 -95.728536)
		(width 0.0889)
		(layer "B.Cu")
		(net "P3E_CPU1_PE3_MP_RXP<14>")
	)
	(arc
		(start 135.613394 -97.299018)
		(mid 135.686192 -97.008255)
		(end 135.607044 -96.719136)
		(width 0.0889)
		(layer "B.Cu")
		(net "P3E_CPU1_PE3_MP_RXP<14>")
	)
	(arc
		(start 134.748524 -90.870786)
		(mid 134.826861 -90.60813)
		(end 134.778242 -90.338402)
		(width 0.0889)
		(layer "B.Cu")
		(net "P3E_CPU1_PE3_MP_RXP<14>")
	)
	(arc
		(start 135.607044 -94.33814)
		(mid 135.612298 -93.756632)
		(end 135.116824 -93.452188)
		(width 0.0889)
		(layer "B.Cu")
		(net "P3E_CPU1_PE3_MP_RXP<14>")
	)
	(arc
		(start 135.607044 -95.328486)
		(mid 135.686266 -95.039368)
		(end 135.613394 -94.748604)
		(width 0.0889)
		(layer "B.Cu")
		(net "P3E_CPU1_PE3_MP_RXP<14>")
	)
	(arc
		(start 135.607044 -100.681536)
		(mid 135.553545 -100.481638)
		(end 135.607044 -100.28174)
		(width 0.0889)
		(layer "B.Cu")
		(net "P3E_CPU1_PE3_MP_RXP<14>")
	)
	(arc
		(start 135.607044 -94.737936)
		(mid 135.553545 -94.538038)
		(end 135.607044 -94.33814)
		(width 0.0889)
		(layer "B.Cu")
		(net "P3E_CPU1_PE3_MP_RXP<14>")
	)
	(arc
		(start 135.613394 -99.280218)
		(mid 135.686192 -98.989455)
		(end 135.607044 -98.700336)
		(width 0.0889)
		(layer "B.Cu")
		(net "P3E_CPU1_PE3_MP_RXP<14>")
	)
	(arc
		(start 135.607044 -101.672136)
		(mid 135.553574 -101.477073)
		(end 135.602218 -101.280722)
		(width 0.0889)
		(layer "B.Cu")
		(net "P3E_CPU1_PE3_MP_RXP<14>")
	)
	(arc
		(start 134.748524 -91.861386)
		(mid 134.827746 -91.572268)
		(end 134.754874 -91.281504)
		(width 0.0889)
		(layer "B.Cu")
		(net "P3E_CPU1_PE3_MP_RXP<14>")
	)
	(arc
		(start 135.607044 -96.719136)
		(mid 135.553574 -96.524073)
		(end 135.602218 -96.327722)
		(width 0.0889)
		(layer "B.Cu")
		(net "P3E_CPU1_PE3_MP_RXP<14>")
	)
	(arc
		(start 134.743698 -91.2622)
		(mid 134.694943 -91.065848)
		(end 134.748524 -90.870786)
		(width 0.0889)
		(layer "B.Cu")
		(net "P3E_CPU1_PE3_MP_RXP<14>")
	)
	(arc
		(start 135.607044 -102.26294)
		(mid 135.686107 -101.967538)
		(end 135.607044 -101.672136)
		(width 0.0889)
		(layer "B.Cu")
		(net "P3E_CPU1_PE3_MP_RXP<14>")
	)
	(arc
		(start 135.607044 -101.272086)
		(mid 135.686266 -100.982968)
		(end 135.613394 -100.692204)
		(width 0.0889)
		(layer "B.Cu")
		(net "P3E_CPU1_PE3_MP_RXP<14>")
	)
	(arc
		(start 135.607044 -97.709736)
		(mid 135.553574 -97.514673)
		(end 135.602218 -97.318322)
		(width 0.0889)
		(layer "B.Cu")
		(net "P3E_CPU1_PE3_MP_RXP<14>")
	)
	(arc
		(start 135.607044 -102.662482)
		(mid 135.553638 -102.462728)
		(end 135.607044 -102.26294)
		(width 0.0889)
		(layer "B.Cu")
		(net "P3E_CPU1_PE3_MP_RXP<14>")
	)
	(arc
		(start 135.607044 -100.28174)
		(mid 135.686175 -99.986338)
		(end 135.607044 -99.690936)
		(width 0.0889)
		(layer "B.Cu")
		(net "P3E_CPU1_PE3_MP_RXP<14>")
	)
	(arc
		(start 135.607044 -95.728536)
		(mid 135.553574 -95.533473)
		(end 135.602218 -95.337122)
		(width 0.0889)
		(layer "B.Cu")
		(net "P3E_CPU1_PE3_MP_RXP<14>")
	)
	(arc
		(start 135.607044 -99.690936)
		(mid 135.553574 -99.495873)
		(end 135.602218 -99.299522)
		(width 0.0889)
		(layer "B.Cu")
		(net "P3E_CPU1_PE3_MP_RXP<14>")
	)
	(arc
		(start 135.084058 -93.452188)
		(mid 134.745889 -93.24739)
		(end 134.748524 -92.851986)
		(width 0.0889)
		(layer "B.Cu")
		(net "P3E_CPU1_PE3_MP_RXP<14>")
	)
	(arc
		(start 134.748524 -92.851986)
		(mid 134.827746 -92.562868)
		(end 134.754874 -92.272104)
		(width 0.0889)
		(layer "B.Cu")
		(net "P3E_CPU1_PE3_MP_RXP<14>")
	)
	(arc
		(start 135.607044 -98.700336)
		(mid 135.553574 -98.505273)
		(end 135.602218 -98.308922)
		(width 0.0889)
		(layer "B.Cu")
		(net "P3E_CPU1_PE3_MP_RXP<14>")
	)
	(segment
		(start 6.209538 -112.549686)
		(end 6.209538 -112.865916)
		(width 0.1143)
		(layer "In4.Cu")
		(net "P3E_CPU1_PE3_MP_RXP<14>")
	)
	(segment
		(start -3.551682 -100.769928)
		(end -3.437382 -100.655628)
		(width 0.1143)
		(layer "In4.Cu")
		(net "P3E_CPU1_PE3_MP_RXP<14>")
	)
	(segment
		(start 10.188448 -101.696774)
		(end 10.188448 -105.749852)
		(width 0.1143)
		(layer "In4.Cu")
		(net "P3E_CPU1_PE3_MP_RXP<14>")
	)
	(segment
		(start 8.120634 -99.62896)
		(end 10.188448 -101.696774)
		(width 0.1143)
		(layer "In4.Cu")
		(net "P3E_CPU1_PE3_MP_RXP<14>")
	)
	(segment
		(start 6.323838 -112.435386)
		(end 6.209538 -112.549686)
		(width 0.1143)
		(layer "In4.Cu")
		(net "P3E_CPU1_PE3_MP_RXP<14>")
	)
	(segment
		(start 10.188448 -105.749852)
		(end 7.60984 -108.32846)
		(width 0.1143)
		(layer "In4.Cu")
		(net "P3E_CPU1_PE3_MP_RXP<14>")
	)
	(segment
		(start -3.437382 -100.655628)
		(end -3.437382 -100.135436)
		(width 0.1143)
		(layer "In4.Cu")
		(net "P3E_CPU1_PE3_MP_RXP<14>")
	)
	(segment
		(start -3.899916 -100.769928)
		(end -3.551682 -100.769928)
		(width 0.1143)
		(layer "In4.Cu")
		(net "P3E_CPU1_PE3_MP_RXP<14>")
	)
	(segment
		(start -3.437382 -100.135436)
		(end -2.930906 -99.62896)
		(width 0.1143)
		(layer "In4.Cu")
		(net "P3E_CPU1_PE3_MP_RXP<14>")
	)
	(segment
		(start 7.60984 -112.02162)
		(end 7.196074 -112.435386)
		(width 0.1143)
		(layer "In4.Cu")
		(net "P3E_CPU1_PE3_MP_RXP<14>")
	)
	(segment
		(start 7.196074 -112.435386)
		(end 6.323838 -112.435386)
		(width 0.1143)
		(layer "In4.Cu")
		(net "P3E_CPU1_PE3_MP_RXP<14>")
	)
	(segment
		(start -2.930906 -99.62896)
		(end 8.120634 -99.62896)
		(width 0.1143)
		(layer "In4.Cu")
		(net "P3E_CPU1_PE3_MP_RXP<14>")
	)
	(segment
		(start 7.60984 -108.32846)
		(end 7.60984 -112.02162)
		(width 0.1143)
		(layer "In4.Cu")
		(net "P3E_CPU1_PE3_MP_RXP<14>")
	)
	(segment
		(start 132.806694 -91.070938)
		(end 133.378194 -91.070938)
		(width 0.1143)
		(layer "F.Cu")
		(net "P3E_CPU1_PE3_MP_RXP<13>")
	)
	(via
		(at 133.378194 -91.070938)
		(size 0.508)
		(drill 0.254)
		(layers "F.Cu" "B.Cu")
		(net "P3E_CPU1_PE3_MP_RXP<13>")
	)
	(segment
		(start 118.83517 -114.27714)
		(end 118.745508 -114.142774)
		(width 0.1143)
		(layer "B.Cu")
		(net "P3E_CPU1_PE3_MP_RXP<13>")
	)
	(segment
		(start 8.746998 -101.547676)
		(end 7.037324 -101.547676)
		(width 0.1143)
		(layer "B.Cu")
		(net "P3E_CPU1_PE3_MP_RXP<13>")
	)
	(segment
		(start 6.43636 -102.659942)
		(end 6.326378 -102.769924)
		(width 0.1143)
		(layer "B.Cu")
		(net "P3E_CPU1_PE3_MP_RXP<13>")
	)
	(segment
		(start 130.295904 -102.1588)
		(end 130.291078 -102.167436)
		(width 0.0889)
		(layer "B.Cu")
		(net "P3E_CPU1_PE3_MP_RXP<13>")
	)
	(segment
		(start 130.295904 -97.2058)
		(end 130.291078 -97.214436)
		(width 0.0889)
		(layer "B.Cu")
		(net "P3E_CPU1_PE3_MP_RXP<13>")
	)
	(segment
		(start 69.813932 -113.396522)
		(end 53.91658 -116.576094)
		(width 0.1143)
		(layer "B.Cu")
		(net "P3E_CPU1_PE3_MP_RXP<13>")
	)
	(segment
		(start 112.299496 -114.50828)
		(end 112.164876 -114.418618)
		(width 0.1143)
		(layer "B.Cu")
		(net "P3E_CPU1_PE3_MP_RXP<13>")
	)
	(segment
		(start 104.226106 -114.161062)
		(end 104.136444 -114.295428)
		(width 0.1143)
		(layer "B.Cu")
		(net "P3E_CPU1_PE3_MP_RXP<13>")
	)
	(segment
		(start 6.326378 -102.769924)
		(end 5.80009 -102.769924)
		(width 0.1143)
		(layer "B.Cu")
		(net "P3E_CPU1_PE3_MP_RXP<13>")
	)
	(segment
		(start 44.930314 -117.46103)
		(end 35.944302 -118.345966)
		(width 0.1143)
		(layer "B.Cu")
		(net "P3E_CPU1_PE3_MP_RXP<13>")
	)
	(segment
		(start 116.14531 -113.739168)
		(end 114.092736 -114.149632)
		(width 0.1143)
		(layer "B.Cu")
		(net "P3E_CPU1_PE3_MP_RXP<13>")
	)
	(segment
		(start 129.6797 -113.027714)
		(end 128.713738 -113.993676)
		(width 0.1143)
		(layer "B.Cu")
		(net "P3E_CPU1_PE3_MP_RXP<13>")
	)
	(segment
		(start 123.065794 -115.123214)
		(end 118.83517 -114.276886)
		(width 0.1143)
		(layer "B.Cu")
		(net "P3E_CPU1_PE3_MP_RXP<13>")
	)
	(segment
		(start 116.481606 -113.806478)
		(end 116.14531 -113.739168)
		(width 0.1143)
		(layer "B.Cu")
		(net "P3E_CPU1_PE3_MP_RXP<13>")
	)
	(segment
		(start 23.270972 -115.781328)
		(end 18.457164 -110.981744)
		(width 0.1143)
		(layer "B.Cu")
		(net "P3E_CPU1_PE3_MP_RXP<13>")
	)
	(segment
		(start 129.6797 -106.1974)
		(end 129.6797 -106.219498)
		(width 0.0889)
		(layer "B.Cu")
		(net "P3E_CPU1_PE3_MP_RXP<13>")
	)
	(segment
		(start 118.274846 -114.165126)
		(end 117.93855 -114.097816)
		(width 0.1143)
		(layer "B.Cu")
		(net "P3E_CPU1_PE3_MP_RXP<13>")
	)
	(segment
		(start 130.284728 -100.766118)
		(end 130.291078 -100.776786)
		(width 0.0889)
		(layer "B.Cu")
		(net "P3E_CPU1_PE3_MP_RXP<13>")
	)
	(segment
		(start 113.196116 -114.328956)
		(end 113.061496 -114.239294)
		(width 0.1143)
		(layer "B.Cu")
		(net "P3E_CPU1_PE3_MP_RXP<13>")
	)
	(segment
		(start 110.93196 -114.665252)
		(end 110.842298 -114.799872)
		(width 0.1143)
		(layer "B.Cu")
		(net "P3E_CPU1_PE3_MP_RXP<13>")
	)
	(segment
		(start 117.04193 -113.918492)
		(end 116.952268 -113.784126)
		(width 0.1143)
		(layer "B.Cu")
		(net "P3E_CPU1_PE3_MP_RXP<13>")
	)
	(segment
		(start 130.291078 -102.757986)
		(end 130.291332 -102.75824)
		(width 0.0889)
		(layer "B.Cu")
		(net "P3E_CPU1_PE3_MP_RXP<13>")
	)
	(segment
		(start 118.409212 -114.075464)
		(end 118.274846 -114.165126)
		(width 0.1143)
		(layer "B.Cu")
		(net "P3E_CPU1_PE3_MP_RXP<13>")
	)
	(segment
		(start 130.284728 -94.822518)
		(end 130.291078 -94.833186)
		(width 0.0889)
		(layer "B.Cu")
		(net "P3E_CPU1_PE3_MP_RXP<13>")
	)
	(segment
		(start 118.745508 -114.142774)
		(end 118.409212 -114.075464)
		(width 0.1143)
		(layer "B.Cu")
		(net "P3E_CPU1_PE3_MP_RXP<13>")
	)
	(segment
		(start 53.91658 -116.576094)
		(end 44.930314 -117.46103)
		(width 0.1143)
		(layer "B.Cu")
		(net "P3E_CPU1_PE3_MP_RXP<13>")
	)
	(segment
		(start 107.94619 -114.494818)
		(end 107.81157 -114.58448)
		(width 0.1143)
		(layer "B.Cu")
		(net "P3E_CPU1_PE3_MP_RXP<13>")
	)
	(segment
		(start 130.295904 -94.234)
		(end 130.291078 -94.242636)
		(width 0.0889)
		(layer "B.Cu")
		(net "P3E_CPU1_PE3_MP_RXP<13>")
	)
	(segment
		(start 104.562402 -114.093752)
		(end 104.226106 -114.161062)
		(width 0.1143)
		(layer "B.Cu")
		(net "P3E_CPU1_PE3_MP_RXP<13>")
	)
	(segment
		(start 98.294698 -115.463828)
		(end 90.597482 -113.924588)
		(width 0.1143)
		(layer "B.Cu")
		(net "P3E_CPU1_PE3_MP_RXP<13>")
	)
	(segment
		(start 114.092736 -114.149632)
		(end 113.958116 -114.05997)
		(width 0.1143)
		(layer "B.Cu")
		(net "P3E_CPU1_PE3_MP_RXP<13>")
	)
	(segment
		(start 108.84281 -114.674142)
		(end 108.708444 -114.763804)
		(width 0.1143)
		(layer "B.Cu")
		(net "P3E_CPU1_PE3_MP_RXP<13>")
	)
	(segment
		(start 111.82858 -114.485928)
		(end 111.738918 -114.620548)
		(width 0.1143)
		(layer "B.Cu")
		(net "P3E_CPU1_PE3_MP_RXP<13>")
	)
	(segment
		(start 116.952268 -113.784126)
		(end 116.615972 -113.716816)
		(width 0.1143)
		(layer "B.Cu")
		(net "P3E_CPU1_PE3_MP_RXP<13>")
	)
	(segment
		(start 108.708444 -114.763804)
		(end 108.372148 -114.696494)
		(width 0.1143)
		(layer "B.Cu")
		(net "P3E_CPU1_PE3_MP_RXP<13>")
	)
	(segment
		(start 6.43636 -102.14864)
		(end 6.43636 -102.659942)
		(width 0.1143)
		(layer "B.Cu")
		(net "P3E_CPU1_PE3_MP_RXP<13>")
	)
	(segment
		(start 105.251504 -114.072416)
		(end 104.696768 -114.183414)
		(width 0.1143)
		(layer "B.Cu")
		(net "P3E_CPU1_PE3_MP_RXP<13>")
	)
	(segment
		(start 113.061496 -114.239294)
		(end 112.725454 -114.306604)
		(width 0.1143)
		(layer "B.Cu")
		(net "P3E_CPU1_PE3_MP_RXP<13>")
	)
	(segment
		(start 107.04957 -114.315494)
		(end 106.91495 -114.405156)
		(width 0.1143)
		(layer "B.Cu")
		(net "P3E_CPU1_PE3_MP_RXP<13>")
	)
	(segment
		(start 130.291078 -96.223836)
		(end 130.284728 -96.234504)
		(width 0.0889)
		(layer "B.Cu")
		(net "P3E_CPU1_PE3_MP_RXP<13>")
	)
	(segment
		(start 110.842298 -114.799872)
		(end 109.865414 -114.995198)
		(width 0.1143)
		(layer "B.Cu")
		(net "P3E_CPU1_PE3_MP_RXP<13>")
	)
	(segment
		(start 123.065794 -115.123468)
		(end 123.065794 -115.123214)
		(width 0.1143)
		(layer "B.Cu")
		(net "P3E_CPU1_PE3_MP_RXP<13>")
	)
	(segment
		(start 107.475528 -114.51717)
		(end 107.385866 -114.382804)
		(width 0.1143)
		(layer "B.Cu")
		(net "P3E_CPU1_PE3_MP_RXP<13>")
	)
	(segment
		(start 129.6797 -106.219498)
		(end 129.6797 -113.027714)
		(width 0.1143)
		(layer "B.Cu")
		(net "P3E_CPU1_PE3_MP_RXP<13>")
	)
	(segment
		(start 129.7051 -106.172)
		(end 129.6797 -106.1974)
		(width 0.0889)
		(layer "B.Cu")
		(net "P3E_CPU1_PE3_MP_RXP<13>")
	)
	(segment
		(start 130.291078 -97.214436)
		(end 130.284728 -97.225104)
		(width 0.0889)
		(layer "B.Cu")
		(net "P3E_CPU1_PE3_MP_RXP<13>")
	)
	(segment
		(start 130.291078 -98.205036)
		(end 130.284728 -98.215704)
		(width 0.0889)
		(layer "B.Cu")
		(net "P3E_CPU1_PE3_MP_RXP<13>")
	)
	(segment
		(start 117.93855 -114.097816)
		(end 117.848888 -113.96345)
		(width 0.1143)
		(layer "B.Cu")
		(net "P3E_CPU1_PE3_MP_RXP<13>")
	)
	(segment
		(start 104.696768 -114.183414)
		(end 104.562402 -114.093752)
		(width 0.1143)
		(layer "B.Cu")
		(net "P3E_CPU1_PE3_MP_RXP<13>")
	)
	(segment
		(start 35.944302 -118.345966)
		(end 30.435804 -118.345966)
		(width 0.1143)
		(layer "B.Cu")
		(net "P3E_CPU1_PE3_MP_RXP<13>")
	)
	(segment
		(start 133.38937 -91.470988)
		(end 133.356604 -91.470988)
		(width 0.0889)
		(layer "B.Cu")
		(net "P3E_CPU1_PE3_MP_RXP<13>")
	)
	(segment
		(start 133.378194 -91.070938)
		(end 133.67131 -91.239848)
		(width 0.0889)
		(layer "B.Cu")
		(net "P3E_CPU1_PE3_MP_RXP<13>")
	)
	(segment
		(start 108.372148 -114.696494)
		(end 108.282486 -114.562128)
		(width 0.1143)
		(layer "B.Cu")
		(net "P3E_CPU1_PE3_MP_RXP<13>")
	)
	(segment
		(start 113.622074 -114.12728)
		(end 113.532412 -114.2619)
		(width 0.1143)
		(layer "B.Cu")
		(net "P3E_CPU1_PE3_MP_RXP<13>")
	)
	(segment
		(start 132.007864 -92.261436)
		(end 132.004562 -92.267278)
		(width 0.0889)
		(layer "B.Cu")
		(net "P3E_CPU1_PE3_MP_RXP<13>")
	)
	(segment
		(start 130.295904 -98.1964)
		(end 130.291078 -98.205036)
		(width 0.0889)
		(layer "B.Cu")
		(net "P3E_CPU1_PE3_MP_RXP<13>")
	)
	(segment
		(start 129.7051 -105.716578)
		(end 129.7051 -106.172)
		(width 0.0889)
		(layer "B.Cu")
		(net "P3E_CPU1_PE3_MP_RXP<13>")
	)
	(segment
		(start 108.282486 -114.562128)
		(end 107.94619 -114.494818)
		(width 0.1143)
		(layer "B.Cu")
		(net "P3E_CPU1_PE3_MP_RXP<13>")
	)
	(segment
		(start 130.342132 -103.05161)
		(end 130.326384 -103.13797)
		(width 0.0889)
		(layer "B.Cu")
		(net "P3E_CPU1_PE3_MP_RXP<13>")
	)
	(segment
		(start 109.268768 -114.875818)
		(end 109.179106 -114.741452)
		(width 0.1143)
		(layer "B.Cu")
		(net "P3E_CPU1_PE3_MP_RXP<13>")
	)
	(segment
		(start 130.295904 -100.1776)
		(end 130.291078 -100.186236)
		(width 0.0889)
		(layer "B.Cu")
		(net "P3E_CPU1_PE3_MP_RXP<13>")
	)
	(segment
		(start 112.725454 -114.306604)
		(end 112.635792 -114.441224)
		(width 0.1143)
		(layer "B.Cu")
		(net "P3E_CPU1_PE3_MP_RXP<13>")
	)
	(segment
		(start 130.291078 -99.195636)
		(end 130.284728 -99.206304)
		(width 0.0889)
		(layer "B.Cu")
		(net "P3E_CPU1_PE3_MP_RXP<13>")
	)
	(segment
		(start 109.179106 -114.741452)
		(end 108.84281 -114.674142)
		(width 0.1143)
		(layer "B.Cu")
		(net "P3E_CPU1_PE3_MP_RXP<13>")
	)
	(segment
		(start 130.817874 -92.956634)
		(end 130.785108 -92.956634)
		(width 0.0889)
		(layer "B.Cu")
		(net "P3E_CPU1_PE3_MP_RXP<13>")
	)
	(segment
		(start 130.295904 -99.187)
		(end 130.291078 -99.195636)
		(width 0.0889)
		(layer "B.Cu")
		(net "P3E_CPU1_PE3_MP_RXP<13>")
	)
	(segment
		(start 107.385866 -114.382804)
		(end 107.04957 -114.315494)
		(width 0.1143)
		(layer "B.Cu")
		(net "P3E_CPU1_PE3_MP_RXP<13>")
	)
	(segment
		(start 111.738918 -114.620548)
		(end 111.402876 -114.687604)
		(width 0.1143)
		(layer "B.Cu")
		(net "P3E_CPU1_PE3_MP_RXP<13>")
	)
	(segment
		(start 130.2512 -103.284274)
		(end 130.2512 -105.170478)
		(width 0.0889)
		(layer "B.Cu")
		(net "P3E_CPU1_PE3_MP_RXP<13>")
	)
	(segment
		(start 130.2512 -105.170478)
		(end 129.7051 -105.716578)
		(width 0.0889)
		(layer "B.Cu")
		(net "P3E_CPU1_PE3_MP_RXP<13>")
	)
	(segment
		(start 116.615972 -113.716816)
		(end 116.481606 -113.806478)
		(width 0.1143)
		(layer "B.Cu")
		(net "P3E_CPU1_PE3_MP_RXP<13>")
	)
	(segment
		(start 107.81157 -114.58448)
		(end 107.475528 -114.51717)
		(width 0.1143)
		(layer "B.Cu")
		(net "P3E_CPU1_PE3_MP_RXP<13>")
	)
	(segment
		(start 111.268256 -114.597942)
		(end 110.93196 -114.665252)
		(width 0.1143)
		(layer "B.Cu")
		(net "P3E_CPU1_PE3_MP_RXP<13>")
	)
	(segment
		(start 7.037324 -101.547676)
		(end 6.43636 -102.14864)
		(width 0.1143)
		(layer "B.Cu")
		(net "P3E_CPU1_PE3_MP_RXP<13>")
	)
	(segment
		(start 130.326384 -103.13797)
		(end 130.2512 -103.284274)
		(width 0.0889)
		(layer "B.Cu")
		(net "P3E_CPU1_PE3_MP_RXP<13>")
	)
	(segment
		(start 90.597482 -113.924588)
		(end 81.526634 -115.73891)
		(width 0.1143)
		(layer "B.Cu")
		(net "P3E_CPU1_PE3_MP_RXP<13>")
	)
	(segment
		(start 111.402876 -114.687604)
		(end 111.268256 -114.597942)
		(width 0.1143)
		(layer "B.Cu")
		(net "P3E_CPU1_PE3_MP_RXP<13>")
	)
	(segment
		(start 118.83517 -114.276886)
		(end 118.83517 -114.27714)
		(width 0.1143)
		(layer "B.Cu")
		(net "P3E_CPU1_PE3_MP_RXP<13>")
	)
	(segment
		(start 112.164876 -114.418618)
		(end 111.82858 -114.485928)
		(width 0.1143)
		(layer "B.Cu")
		(net "P3E_CPU1_PE3_MP_RXP<13>")
	)
	(segment
		(start 81.526634 -115.73891)
		(end 69.813932 -113.396522)
		(width 0.1143)
		(layer "B.Cu")
		(net "P3E_CPU1_PE3_MP_RXP<13>")
	)
	(segment
		(start 104.136444 -114.295428)
		(end 98.294698 -115.463828)
		(width 0.1143)
		(layer "B.Cu")
		(net "P3E_CPU1_PE3_MP_RXP<13>")
	)
	(segment
		(start 132.53466 -91.966034)
		(end 132.501894 -91.966034)
		(width 0.0889)
		(layer "B.Cu")
		(net "P3E_CPU1_PE3_MP_RXP<13>")
	)
	(segment
		(start 11.622786 -107.704636)
		(end 9.302496 -102.10292)
		(width 0.1143)
		(layer "B.Cu")
		(net "P3E_CPU1_PE3_MP_RXP<13>")
	)
	(segment
		(start 130.291078 -102.167436)
		(end 130.284728 -102.178104)
		(width 0.0889)
		(layer "B.Cu")
		(net "P3E_CPU1_PE3_MP_RXP<13>")
	)
	(segment
		(start 128.713738 -113.993676)
		(end 123.065794 -115.123468)
		(width 0.1143)
		(layer "B.Cu")
		(net "P3E_CPU1_PE3_MP_RXP<13>")
	)
	(segment
		(start 12.386056 -108.467652)
		(end 11.622786 -107.704636)
		(width 0.1143)
		(layer "B.Cu")
		(net "P3E_CPU1_PE3_MP_RXP<13>")
	)
	(segment
		(start 106.91495 -114.405156)
		(end 105.251504 -114.072416)
		(width 0.1143)
		(layer "B.Cu")
		(net "P3E_CPU1_PE3_MP_RXP<13>")
	)
	(segment
		(start 30.435804 -118.345966)
		(end 23.270972 -115.781328)
		(width 0.1143)
		(layer "B.Cu")
		(net "P3E_CPU1_PE3_MP_RXP<13>")
	)
	(segment
		(start 130.295904 -96.2152)
		(end 130.291078 -96.223836)
		(width 0.0889)
		(layer "B.Cu")
		(net "P3E_CPU1_PE3_MP_RXP<13>")
	)
	(segment
		(start 109.865414 -114.995198)
		(end 109.268768 -114.875818)
		(width 0.1143)
		(layer "B.Cu")
		(net "P3E_CPU1_PE3_MP_RXP<13>")
	)
	(segment
		(start 18.457164 -110.981744)
		(end 12.386056 -108.467652)
		(width 0.1143)
		(layer "B.Cu")
		(net "P3E_CPU1_PE3_MP_RXP<13>")
	)
	(segment
		(start 131.661408 -92.461588)
		(end 131.639818 -92.461588)
		(width 0.0889)
		(layer "B.Cu")
		(net "P3E_CPU1_PE3_MP_RXP<13>")
	)
	(segment
		(start 117.378226 -113.985802)
		(end 117.04193 -113.918492)
		(width 0.1143)
		(layer "B.Cu")
		(net "P3E_CPU1_PE3_MP_RXP<13>")
	)
	(segment
		(start 117.848888 -113.96345)
		(end 117.512592 -113.89614)
		(width 0.1143)
		(layer "B.Cu")
		(net "P3E_CPU1_PE3_MP_RXP<13>")
	)
	(segment
		(start 113.958116 -114.05997)
		(end 113.622074 -114.12728)
		(width 0.1143)
		(layer "B.Cu")
		(net "P3E_CPU1_PE3_MP_RXP<13>")
	)
	(segment
		(start 117.512592 -113.89614)
		(end 117.378226 -113.985802)
		(width 0.1143)
		(layer "B.Cu")
		(net "P3E_CPU1_PE3_MP_RXP<13>")
	)
	(segment
		(start 113.532412 -114.2619)
		(end 113.196116 -114.328956)
		(width 0.1143)
		(layer "B.Cu")
		(net "P3E_CPU1_PE3_MP_RXP<13>")
	)
	(segment
		(start 112.635792 -114.441224)
		(end 112.299496 -114.50828)
		(width 0.1143)
		(layer "B.Cu")
		(net "P3E_CPU1_PE3_MP_RXP<13>")
	)
	(segment
		(start 133.67131 -91.239848)
		(end 133.692392 -91.318588)
		(width 0.0889)
		(layer "B.Cu")
		(net "P3E_CPU1_PE3_MP_RXP<13>")
	)
	(segment
		(start 9.302496 -102.10292)
		(end 8.746998 -101.547676)
		(width 0.1143)
		(layer "B.Cu")
		(net "P3E_CPU1_PE3_MP_RXP<13>")
	)
	(arc
		(start 130.291078 -101.767386)
		(mid 130.344548 -101.962449)
		(end 130.295904 -102.1588)
		(width 0.0889)
		(layer "B.Cu")
		(net "P3E_CPU1_PE3_MP_RXP<13>")
	)
	(arc
		(start 130.291078 -97.804986)
		(mid 130.344548 -98.000049)
		(end 130.295904 -98.1964)
		(width 0.0889)
		(layer "B.Cu")
		(net "P3E_CPU1_PE3_MP_RXP<13>")
	)
	(arc
		(start 130.291078 -96.814386)
		(mid 130.344548 -97.009449)
		(end 130.295904 -97.2058)
		(width 0.0889)
		(layer "B.Cu")
		(net "P3E_CPU1_PE3_MP_RXP<13>")
	)
	(arc
		(start 130.284728 -96.234504)
		(mid 130.21193 -96.525267)
		(end 130.291078 -96.814386)
		(width 0.0889)
		(layer "B.Cu")
		(net "P3E_CPU1_PE3_MP_RXP<13>")
	)
	(arc
		(start 130.291078 -100.776786)
		(mid 130.344577 -100.976684)
		(end 130.291078 -101.176582)
		(width 0.0889)
		(layer "B.Cu")
		(net "P3E_CPU1_PE3_MP_RXP<13>")
	)
	(arc
		(start 133.356604 -91.470988)
		(mid 133.073387 -91.555269)
		(end 132.866384 -91.766136)
		(width 0.0889)
		(layer "B.Cu")
		(net "P3E_CPU1_PE3_MP_RXP<13>")
	)
	(arc
		(start 130.284728 -98.215704)
		(mid 130.21193 -98.506467)
		(end 130.291078 -98.795586)
		(width 0.0889)
		(layer "B.Cu")
		(net "P3E_CPU1_PE3_MP_RXP<13>")
	)
	(arc
		(start 130.284728 -97.225104)
		(mid 130.21193 -97.515867)
		(end 130.291078 -97.804986)
		(width 0.0889)
		(layer "B.Cu")
		(net "P3E_CPU1_PE3_MP_RXP<13>")
	)
	(arc
		(start 130.291078 -95.232982)
		(mid 130.211947 -95.528384)
		(end 130.291078 -95.823786)
		(width 0.0889)
		(layer "B.Cu")
		(net "P3E_CPU1_PE3_MP_RXP<13>")
	)
	(arc
		(start 130.284728 -99.206304)
		(mid 130.21193 -99.497067)
		(end 130.291078 -99.786186)
		(width 0.0889)
		(layer "B.Cu")
		(net "P3E_CPU1_PE3_MP_RXP<13>")
	)
	(arc
		(start 130.291078 -98.795586)
		(mid 130.344548 -98.990649)
		(end 130.295904 -99.187)
		(width 0.0889)
		(layer "B.Cu")
		(net "P3E_CPU1_PE3_MP_RXP<13>")
	)
	(arc
		(start 131.149598 -92.756736)
		(mid 131.009519 -92.899472)
		(end 130.817874 -92.956634)
		(width 0.0889)
		(layer "B.Cu")
		(net "P3E_CPU1_PE3_MP_RXP<13>")
	)
	(arc
		(start 133.692392 -91.318588)
		(mid 133.55783 -91.4285)
		(end 133.38937 -91.470988)
		(width 0.0889)
		(layer "B.Cu")
		(net "P3E_CPU1_PE3_MP_RXP<13>")
	)
	(arc
		(start 130.284728 -102.178104)
		(mid 130.21193 -102.468867)
		(end 130.291078 -102.757986)
		(width 0.0889)
		(layer "B.Cu")
		(net "P3E_CPU1_PE3_MP_RXP<13>")
	)
	(arc
		(start 130.291078 -101.176582)
		(mid 130.211947 -101.471984)
		(end 130.291078 -101.767386)
		(width 0.0889)
		(layer "B.Cu")
		(net "P3E_CPU1_PE3_MP_RXP<13>")
	)
	(arc
		(start 132.004562 -92.267278)
		(mid 131.858596 -92.409677)
		(end 131.661408 -92.461588)
		(width 0.0889)
		(layer "B.Cu")
		(net "P3E_CPU1_PE3_MP_RXP<13>")
	)
	(arc
		(start 130.291078 -93.842586)
		(mid 130.344548 -94.037649)
		(end 130.295904 -94.234)
		(width 0.0889)
		(layer "B.Cu")
		(net "P3E_CPU1_PE3_MP_RXP<13>")
	)
	(arc
		(start 130.291078 -94.242636)
		(mid 130.211856 -94.531754)
		(end 130.284728 -94.822518)
		(width 0.0889)
		(layer "B.Cu")
		(net "P3E_CPU1_PE3_MP_RXP<13>")
	)
	(arc
		(start 132.501894 -91.966034)
		(mid 132.21647 -92.049501)
		(end 132.007864 -92.261436)
		(width 0.0889)
		(layer "B.Cu")
		(net "P3E_CPU1_PE3_MP_RXP<13>")
	)
	(arc
		(start 130.785108 -92.956634)
		(mid 130.286857 -93.259474)
		(end 130.291078 -93.842586)
		(width 0.0889)
		(layer "B.Cu")
		(net "P3E_CPU1_PE3_MP_RXP<13>")
	)
	(arc
		(start 131.639818 -92.461588)
		(mid 131.356601 -92.545869)
		(end 131.149598 -92.756736)
		(width 0.0889)
		(layer "B.Cu")
		(net "P3E_CPU1_PE3_MP_RXP<13>")
	)
	(arc
		(start 130.291078 -95.823786)
		(mid 130.344548 -96.018849)
		(end 130.295904 -96.2152)
		(width 0.0889)
		(layer "B.Cu")
		(net "P3E_CPU1_PE3_MP_RXP<13>")
	)
	(arc
		(start 130.291078 -94.833186)
		(mid 130.344577 -95.033084)
		(end 130.291078 -95.232982)
		(width 0.0889)
		(layer "B.Cu")
		(net "P3E_CPU1_PE3_MP_RXP<13>")
	)
	(arc
		(start 132.866384 -91.766136)
		(mid 132.726305 -91.908872)
		(end 132.53466 -91.966034)
		(width 0.0889)
		(layer "B.Cu")
		(net "P3E_CPU1_PE3_MP_RXP<13>")
	)
	(arc
		(start 130.291332 -102.75824)
		(mid 130.342757 -102.900415)
		(end 130.342132 -103.05161)
		(width 0.0889)
		(layer "B.Cu")
		(net "P3E_CPU1_PE3_MP_RXP<13>")
	)
	(arc
		(start 130.291078 -99.786186)
		(mid 130.344548 -99.981249)
		(end 130.295904 -100.1776)
		(width 0.0889)
		(layer "B.Cu")
		(net "P3E_CPU1_PE3_MP_RXP<13>")
	)
	(arc
		(start 130.291078 -100.186236)
		(mid 130.211856 -100.475354)
		(end 130.284728 -100.766118)
		(width 0.0889)
		(layer "B.Cu")
		(net "P3E_CPU1_PE3_MP_RXP<13>")
	)
	(segment
		(start 131.948174 -92.556584)
		(end 132.519674 -92.556584)
		(width 0.1143)
		(layer "F.Cu")
		(net "P3E_CPU1_PE3_MP_RXP<12>")
	)
	(via
		(at 132.519674 -92.556584)
		(size 0.508)
		(drill 0.254)
		(layers "F.Cu" "B.Cu")
		(net "P3E_CPU1_PE3_MP_RXP<12>")
	)
	(segment
		(start 69.462396 -114.45367)
		(end 53.519324 -117.642386)
		(width 0.1143)
		(layer "B.Cu")
		(net "P3E_CPU1_PE3_MP_RXP<12>")
	)
	(segment
		(start 131.661408 -93.452188)
		(end 131.639818 -93.452188)
		(width 0.0889)
		(layer "B.Cu")
		(net "P3E_CPU1_PE3_MP_RXP<12>")
	)
	(segment
		(start 128.483106 -115.069112)
		(end 128.14681 -115.136168)
		(width 0.1143)
		(layer "B.Cu")
		(net "P3E_CPU1_PE3_MP_RXP<12>")
	)
	(segment
		(start 130.683 -106.772202)
		(end 130.6576 -106.797602)
		(width 0.0889)
		(layer "B.Cu")
		(net "P3E_CPU1_PE3_MP_RXP<12>")
	)
	(segment
		(start 131.149598 -99.290886)
		(end 131.154424 -99.299522)
		(width 0.0889)
		(layer "B.Cu")
		(net "P3E_CPU1_PE3_MP_RXP<12>")
	)
	(segment
		(start 127.721106 -115.338098)
		(end 127.586486 -115.248436)
		(width 0.1143)
		(layer "B.Cu")
		(net "P3E_CPU1_PE3_MP_RXP<12>")
	)
	(segment
		(start 131.1529 -103.834692)
		(end 131.05384 -103.933752)
		(width 0.0889)
		(layer "B.Cu")
		(net "P3E_CPU1_PE3_MP_RXP<12>")
	)
	(segment
		(start 131.05384 -104.111552)
		(end 131.1529 -104.210612)
		(width 0.0889)
		(layer "B.Cu")
		(net "P3E_CPU1_PE3_MP_RXP<12>")
	)
	(segment
		(start 131.1529 -104.210612)
		(end 131.1529 -105.686606)
		(width 0.0889)
		(layer "B.Cu")
		(net "P3E_CPU1_PE3_MP_RXP<12>")
	)
	(segment
		(start 2.591816 -102.769924)
		(end 2.999994 -102.769924)
		(width 0.1143)
		(layer "B.Cu")
		(net "P3E_CPU1_PE3_MP_RXP<12>")
	)
	(segment
		(start 131.149598 -102.262686)
		(end 131.154424 -102.271322)
		(width 0.0889)
		(layer "B.Cu")
		(net "P3E_CPU1_PE3_MP_RXP<12>")
	)
	(segment
		(start 129.109724 -115.060476)
		(end 129.109724 -115.060222)
		(width 0.1143)
		(layer "B.Cu")
		(net "P3E_CPU1_PE3_MP_RXP<12>")
	)
	(segment
		(start 131.143248 -98.289618)
		(end 131.149598 -98.300286)
		(width 0.0889)
		(layer "B.Cu")
		(net "P3E_CPU1_PE3_MP_RXP<12>")
	)
	(segment
		(start 130.6576 -113.5126)
		(end 129.109724 -115.060476)
		(width 0.1143)
		(layer "B.Cu")
		(net "P3E_CPU1_PE3_MP_RXP<12>")
	)
	(segment
		(start 126.263908 -115.629436)
		(end 123.00204 -116.281962)
		(width 0.1143)
		(layer "B.Cu")
		(net "P3E_CPU1_PE3_MP_RXP<12>")
	)
	(segment
		(start 53.519324 -117.642386)
		(end 35.367468 -119.4308)
		(width 0.1143)
		(layer "B.Cu")
		(net "P3E_CPU1_PE3_MP_RXP<12>")
	)
	(segment
		(start 123.00204 -116.281962)
		(end 116.448586 -114.971322)
		(width 0.1143)
		(layer "B.Cu")
		(net "P3E_CPU1_PE3_MP_RXP<12>")
	)
	(segment
		(start 131.149598 -97.309686)
		(end 131.154424 -97.318322)
		(width 0.0889)
		(layer "B.Cu")
		(net "P3E_CPU1_PE3_MP_RXP<12>")
	)
	(segment
		(start 30.599888 -119.4308)
		(end 22.689312 -116.599716)
		(width 0.1143)
		(layer "B.Cu")
		(net "P3E_CPU1_PE3_MP_RXP<12>")
	)
	(segment
		(start 132.53466 -92.956634)
		(end 132.501894 -92.956634)
		(width 0.0889)
		(layer "B.Cu")
		(net "P3E_CPU1_PE3_MP_RXP<12>")
	)
	(segment
		(start 126.689866 -115.42776)
		(end 126.35357 -115.49507)
		(width 0.1143)
		(layer "B.Cu")
		(net "P3E_CPU1_PE3_MP_RXP<12>")
	)
	(segment
		(start 127.586486 -115.248436)
		(end 127.25019 -115.315492)
		(width 0.1143)
		(layer "B.Cu")
		(net "P3E_CPU1_PE3_MP_RXP<12>")
	)
	(segment
		(start 98.020632 -116.556282)
		(end 90.896694 -115.131596)
		(width 0.1143)
		(layer "B.Cu")
		(net "P3E_CPU1_PE3_MP_RXP<12>")
	)
	(segment
		(start 104.54386 -115.251738)
		(end 98.020632 -116.556282)
		(width 0.1143)
		(layer "B.Cu")
		(net "P3E_CPU1_PE3_MP_RXP<12>")
	)
	(segment
		(start 130.683 -106.156506)
		(end 130.683 -106.772202)
		(width 0.0889)
		(layer "B.Cu")
		(net "P3E_CPU1_PE3_MP_RXP<12>")
	)
	(segment
		(start 131.1529 -103.656892)
		(end 131.1529 -103.834692)
		(width 0.0889)
		(layer "B.Cu")
		(net "P3E_CPU1_PE3_MP_RXP<12>")
	)
	(segment
		(start 7.845806 -103.654352)
		(end 2.816352 -103.654352)
		(width 0.1143)
		(layer "B.Cu")
		(net "P3E_CPU1_PE3_MP_RXP<12>")
	)
	(segment
		(start 127.25019 -115.315492)
		(end 127.160528 -115.450112)
		(width 0.1143)
		(layer "B.Cu")
		(net "P3E_CPU1_PE3_MP_RXP<12>")
	)
	(segment
		(start 131.149598 -94.737936)
		(end 131.143248 -94.748604)
		(width 0.0889)
		(layer "B.Cu")
		(net "P3E_CPU1_PE3_MP_RXP<12>")
	)
	(segment
		(start 2.4638 -102.89794)
		(end 2.591816 -102.769924)
		(width 0.1143)
		(layer "B.Cu")
		(net "P3E_CPU1_PE3_MP_RXP<12>")
	)
	(segment
		(start 131.143248 -102.252018)
		(end 131.149598 -102.262686)
		(width 0.0889)
		(layer "B.Cu")
		(net "P3E_CPU1_PE3_MP_RXP<12>")
	)
	(segment
		(start 2.4638 -103.3018)
		(end 2.4638 -102.89794)
		(width 0.1143)
		(layer "B.Cu")
		(net "P3E_CPU1_PE3_MP_RXP<12>")
	)
	(segment
		(start 127.160528 -115.450112)
		(end 126.824486 -115.517422)
		(width 0.1143)
		(layer "B.Cu")
		(net "P3E_CPU1_PE3_MP_RXP<12>")
	)
	(segment
		(start 126.35357 -115.49507)
		(end 126.263908 -115.629436)
		(width 0.1143)
		(layer "B.Cu")
		(net "P3E_CPU1_PE3_MP_RXP<12>")
	)
	(segment
		(start 131.149598 -102.662736)
		(end 131.0513 -102.832916)
		(width 0.0889)
		(layer "B.Cu")
		(net "P3E_CPU1_PE3_MP_RXP<12>")
	)
	(segment
		(start 10.793984 -108.245402)
		(end 9.632442 -105.440988)
		(width 0.1143)
		(layer "B.Cu")
		(net "P3E_CPU1_PE3_MP_RXP<12>")
	)
	(segment
		(start 132.007864 -93.252036)
		(end 132.004562 -93.257878)
		(width 0.0889)
		(layer "B.Cu")
		(net "P3E_CPU1_PE3_MP_RXP<12>")
	)
	(segment
		(start 131.149598 -101.272086)
		(end 131.154424 -101.280722)
		(width 0.0889)
		(layer "B.Cu")
		(net "P3E_CPU1_PE3_MP_RXP<12>")
	)
	(segment
		(start 131.149598 -95.328486)
		(end 131.154424 -95.337122)
		(width 0.0889)
		(layer "B.Cu")
		(net "P3E_CPU1_PE3_MP_RXP<12>")
	)
	(segment
		(start 90.896694 -115.131596)
		(end 81.873598 -116.936266)
		(width 0.1143)
		(layer "B.Cu")
		(net "P3E_CPU1_PE3_MP_RXP<12>")
	)
	(segment
		(start 9.632442 -105.440988)
		(end 7.845806 -103.654352)
		(width 0.1143)
		(layer "B.Cu")
		(net "P3E_CPU1_PE3_MP_RXP<12>")
	)
	(segment
		(start 81.873598 -116.936266)
		(end 69.462396 -114.45367)
		(width 0.1143)
		(layer "B.Cu")
		(net "P3E_CPU1_PE3_MP_RXP<12>")
	)
	(segment
		(start 131.149598 -96.319086)
		(end 131.154424 -96.327722)
		(width 0.0889)
		(layer "B.Cu")
		(net "P3E_CPU1_PE3_MP_RXP<12>")
	)
	(segment
		(start 130.6576 -106.8197)
		(end 130.6576 -113.5126)
		(width 0.1143)
		(layer "B.Cu")
		(net "P3E_CPU1_PE3_MP_RXP<12>")
	)
	(segment
		(start 128.057148 -115.270788)
		(end 127.721106 -115.338098)
		(width 0.1143)
		(layer "B.Cu")
		(net "P3E_CPU1_PE3_MP_RXP<12>")
	)
	(segment
		(start 131.143248 -99.280218)
		(end 131.149598 -99.290886)
		(width 0.0889)
		(layer "B.Cu")
		(net "P3E_CPU1_PE3_MP_RXP<12>")
	)
	(segment
		(start 131.0513 -102.832916)
		(end 131.0513 -103.411274)
		(width 0.0889)
		(layer "B.Cu")
		(net "P3E_CPU1_PE3_MP_RXP<12>")
	)
	(segment
		(start 131.1529 -105.686606)
		(end 130.683 -106.156506)
		(width 0.0889)
		(layer "B.Cu")
		(net "P3E_CPU1_PE3_MP_RXP<12>")
	)
	(segment
		(start 109.795056 -116.302028)
		(end 104.54386 -115.251738)
		(width 0.1143)
		(layer "B.Cu")
		(net "P3E_CPU1_PE3_MP_RXP<12>")
	)
	(segment
		(start 131.0513 -103.411274)
		(end 131.1529 -103.656892)
		(width 0.0889)
		(layer "B.Cu")
		(net "P3E_CPU1_PE3_MP_RXP<12>")
	)
	(segment
		(start 2.816352 -103.654352)
		(end 2.4638 -103.3018)
		(width 0.1143)
		(layer "B.Cu")
		(net "P3E_CPU1_PE3_MP_RXP<12>")
	)
	(segment
		(start 132.519674 -92.556584)
		(end 132.89153 -92.40901)
		(width 0.0889)
		(layer "B.Cu")
		(net "P3E_CPU1_PE3_MP_RXP<12>")
	)
	(segment
		(start 131.149598 -98.300286)
		(end 131.154424 -98.308922)
		(width 0.0889)
		(layer "B.Cu")
		(net "P3E_CPU1_PE3_MP_RXP<12>")
	)
	(segment
		(start 131.05384 -103.933752)
		(end 131.05384 -104.111552)
		(width 0.0889)
		(layer "B.Cu")
		(net "P3E_CPU1_PE3_MP_RXP<12>")
	)
	(segment
		(start 22.689312 -116.599716)
		(end 17.883378 -111.793274)
		(width 0.1143)
		(layer "B.Cu")
		(net "P3E_CPU1_PE3_MP_RXP<12>")
	)
	(segment
		(start 126.824486 -115.517422)
		(end 126.689866 -115.42776)
		(width 0.1143)
		(layer "B.Cu")
		(net "P3E_CPU1_PE3_MP_RXP<12>")
	)
	(segment
		(start 129.109724 -115.060222)
		(end 128.617726 -115.158774)
		(width 0.1143)
		(layer "B.Cu")
		(net "P3E_CPU1_PE3_MP_RXP<12>")
	)
	(segment
		(start 35.367468 -119.4308)
		(end 30.599888 -119.4308)
		(width 0.1143)
		(layer "B.Cu")
		(net "P3E_CPU1_PE3_MP_RXP<12>")
	)
	(segment
		(start 131.149598 -100.681536)
		(end 131.143248 -100.692204)
		(width 0.0889)
		(layer "B.Cu")
		(net "P3E_CPU1_PE3_MP_RXP<12>")
	)
	(segment
		(start 11.829034 -109.285786)
		(end 10.793984 -108.245402)
		(width 0.1143)
		(layer "B.Cu")
		(net "P3E_CPU1_PE3_MP_RXP<12>")
	)
	(segment
		(start 128.14681 -115.136168)
		(end 128.057148 -115.270788)
		(width 0.1143)
		(layer "B.Cu")
		(net "P3E_CPU1_PE3_MP_RXP<12>")
	)
	(segment
		(start 131.143248 -96.308418)
		(end 131.149598 -96.319086)
		(width 0.0889)
		(layer "B.Cu")
		(net "P3E_CPU1_PE3_MP_RXP<12>")
	)
	(segment
		(start 116.448586 -114.971322)
		(end 109.795056 -116.302028)
		(width 0.1143)
		(layer "B.Cu")
		(net "P3E_CPU1_PE3_MP_RXP<12>")
	)
	(segment
		(start 131.143248 -97.299018)
		(end 131.149598 -97.309686)
		(width 0.0889)
		(layer "B.Cu")
		(net "P3E_CPU1_PE3_MP_RXP<12>")
	)
	(segment
		(start 17.883378 -111.793274)
		(end 11.829034 -109.285786)
		(width 0.1143)
		(layer "B.Cu")
		(net "P3E_CPU1_PE3_MP_RXP<12>")
	)
	(segment
		(start 130.6576 -106.797602)
		(end 130.6576 -106.8197)
		(width 0.0889)
		(layer "B.Cu")
		(net "P3E_CPU1_PE3_MP_RXP<12>")
	)
	(segment
		(start 128.617726 -115.158774)
		(end 128.483106 -115.069112)
		(width 0.1143)
		(layer "B.Cu")
		(net "P3E_CPU1_PE3_MP_RXP<12>")
	)
	(arc
		(start 131.154424 -101.280722)
		(mid 131.203179 -101.477074)
		(end 131.149598 -101.672136)
		(width 0.0889)
		(layer "B.Cu")
		(net "P3E_CPU1_PE3_MP_RXP<12>")
	)
	(arc
		(start 131.154424 -99.299522)
		(mid 131.203179 -99.495874)
		(end 131.149598 -99.690936)
		(width 0.0889)
		(layer "B.Cu")
		(net "P3E_CPU1_PE3_MP_RXP<12>")
	)
	(arc
		(start 131.149598 -99.690936)
		(mid 131.070467 -99.986338)
		(end 131.149598 -100.28174)
		(width 0.0889)
		(layer "B.Cu")
		(net "P3E_CPU1_PE3_MP_RXP<12>")
	)
	(arc
		(start 131.154424 -97.318322)
		(mid 131.203179 -97.514674)
		(end 131.149598 -97.709736)
		(width 0.0889)
		(layer "B.Cu")
		(net "P3E_CPU1_PE3_MP_RXP<12>")
	)
	(arc
		(start 132.004562 -93.257878)
		(mid 131.858596 -93.400277)
		(end 131.661408 -93.452188)
		(width 0.0889)
		(layer "B.Cu")
		(net "P3E_CPU1_PE3_MP_RXP<12>")
	)
	(arc
		(start 131.154424 -96.327722)
		(mid 131.203179 -96.524074)
		(end 131.149598 -96.719136)
		(width 0.0889)
		(layer "B.Cu")
		(net "P3E_CPU1_PE3_MP_RXP<12>")
	)
	(arc
		(start 131.639818 -93.452188)
		(mid 131.144341 -93.756631)
		(end 131.149598 -94.33814)
		(width 0.0889)
		(layer "B.Cu")
		(net "P3E_CPU1_PE3_MP_RXP<12>")
	)
	(arc
		(start 131.149598 -96.719136)
		(mid 131.070376 -97.008254)
		(end 131.143248 -97.299018)
		(width 0.0889)
		(layer "B.Cu")
		(net "P3E_CPU1_PE3_MP_RXP<12>")
	)
	(arc
		(start 132.501894 -92.956634)
		(mid 132.21647 -93.040101)
		(end 132.007864 -93.252036)
		(width 0.0889)
		(layer "B.Cu")
		(net "P3E_CPU1_PE3_MP_RXP<12>")
	)
	(arc
		(start 131.149598 -97.709736)
		(mid 131.070376 -97.998854)
		(end 131.143248 -98.289618)
		(width 0.0889)
		(layer "B.Cu")
		(net "P3E_CPU1_PE3_MP_RXP<12>")
	)
	(arc
		(start 131.154424 -95.337122)
		(mid 131.203179 -95.533474)
		(end 131.149598 -95.728536)
		(width 0.0889)
		(layer "B.Cu")
		(net "P3E_CPU1_PE3_MP_RXP<12>")
	)
	(arc
		(start 131.149598 -100.28174)
		(mid 131.203097 -100.481638)
		(end 131.149598 -100.681536)
		(width 0.0889)
		(layer "B.Cu")
		(net "P3E_CPU1_PE3_MP_RXP<12>")
	)
	(arc
		(start 131.149598 -94.33814)
		(mid 131.203097 -94.538038)
		(end 131.149598 -94.737936)
		(width 0.0889)
		(layer "B.Cu")
		(net "P3E_CPU1_PE3_MP_RXP<12>")
	)
	(arc
		(start 132.89153 -92.40901)
		(mid 132.85479 -92.775149)
		(end 132.53466 -92.956634)
		(width 0.0889)
		(layer "B.Cu")
		(net "P3E_CPU1_PE3_MP_RXP<12>")
	)
	(arc
		(start 131.154424 -102.271322)
		(mid 131.203179 -102.467674)
		(end 131.149598 -102.662736)
		(width 0.0889)
		(layer "B.Cu")
		(net "P3E_CPU1_PE3_MP_RXP<12>")
	)
	(arc
		(start 131.149598 -95.728536)
		(mid 131.070376 -96.017654)
		(end 131.143248 -96.308418)
		(width 0.0889)
		(layer "B.Cu")
		(net "P3E_CPU1_PE3_MP_RXP<12>")
	)
	(arc
		(start 131.154424 -98.308922)
		(mid 131.203179 -98.505274)
		(end 131.149598 -98.700336)
		(width 0.0889)
		(layer "B.Cu")
		(net "P3E_CPU1_PE3_MP_RXP<12>")
	)
	(arc
		(start 131.149598 -98.700336)
		(mid 131.070376 -98.989454)
		(end 131.143248 -99.280218)
		(width 0.0889)
		(layer "B.Cu")
		(net "P3E_CPU1_PE3_MP_RXP<12>")
	)
	(arc
		(start 131.149598 -101.672136)
		(mid 131.070376 -101.961254)
		(end 131.143248 -102.252018)
		(width 0.0889)
		(layer "B.Cu")
		(net "P3E_CPU1_PE3_MP_RXP<12>")
	)
	(arc
		(start 131.143248 -94.748604)
		(mid 131.07045 -95.039367)
		(end 131.149598 -95.328486)
		(width 0.0889)
		(layer "B.Cu")
		(net "P3E_CPU1_PE3_MP_RXP<12>")
	)
	(arc
		(start 131.143248 -100.692204)
		(mid 131.07045 -100.982967)
		(end 131.149598 -101.272086)
		(width 0.0889)
		(layer "B.Cu")
		(net "P3E_CPU1_PE3_MP_RXP<12>")
	)
	(segment
		(start 133.665214 -93.547184)
		(end 134.236714 -93.547184)
		(width 0.1143)
		(layer "F.Cu")
		(net "P3E_CPU1_PE3_MP_RXP<11>")
	)
	(via
		(at 4.32435 -107.9119)
		(size 0.508)
		(drill 0.254)
		(layers "F.Cu" "B.Cu")
		(net "P3E_CPU1_PE3_MP_RXP<11>")
	)
	(via
		(at 134.236714 -93.547184)
		(size 0.508)
		(drill 0.254)
		(layers "F.Cu" "B.Cu")
		(net "P3E_CPU1_PE3_MP_RXP<11>")
	)
	(segment
		(start 20.587208 -120.004078)
		(end 15.65402 -115.07089)
		(width 0.1143)
		(layer "B.Cu")
		(net "P3E_CPU1_PE3_MP_RXP<11>")
	)
	(segment
		(start 134.583424 -102.262686)
		(end 134.58825 -102.271322)
		(width 0.0889)
		(layer "B.Cu")
		(net "P3E_CPU1_PE3_MP_RXP<11>")
	)
	(segment
		(start 3.81 -108.48848)
		(end 3.81 -108.0262)
		(width 0.1143)
		(layer "B.Cu")
		(net "P3E_CPU1_PE3_MP_RXP<11>")
	)
	(segment
		(start 8.303514 -112.025684)
		(end 5.106416 -108.82884)
		(width 0.1143)
		(layer "B.Cu")
		(net "P3E_CPU1_PE3_MP_RXP<11>")
	)
	(segment
		(start 129.87274 -119.88673)
		(end 122.718068 -121.317258)
		(width 0.1143)
		(layer "B.Cu")
		(net "P3E_CPU1_PE3_MP_RXP<11>")
	)
	(segment
		(start 122.718068 -121.317258)
		(end 122.718068 -121.317512)
		(width 0.1143)
		(layer "B.Cu")
		(net "P3E_CPU1_PE3_MP_RXP<11>")
	)
	(segment
		(start 134.577074 -97.299018)
		(end 134.583424 -97.309686)
		(width 0.0889)
		(layer "B.Cu")
		(net "P3E_CPU1_PE3_MP_RXP<11>")
	)
	(segment
		(start 90.365834 -120.037606)
		(end 82.155792 -121.679462)
		(width 0.1143)
		(layer "B.Cu")
		(net "P3E_CPU1_PE3_MP_RXP<11>")
	)
	(segment
		(start 134.583424 -103.25354)
		(end 134.817612 -103.659178)
		(width 0.0889)
		(layer "B.Cu")
		(net "P3E_CPU1_PE3_MP_RXP<11>")
	)
	(segment
		(start 134.52983 -93.716348)
		(end 134.553706 -93.805756)
		(width 0.0889)
		(layer "B.Cu")
		(net "P3E_CPU1_PE3_MP_RXP<11>")
	)
	(segment
		(start 134.792212 -106.262678)
		(end 134.792212 -106.284776)
		(width 0.0889)
		(layer "B.Cu")
		(net "P3E_CPU1_PE3_MP_RXP<11>")
	)
	(segment
		(start 134.577074 -99.280218)
		(end 134.583424 -99.290886)
		(width 0.0889)
		(layer "B.Cu")
		(net "P3E_CPU1_PE3_MP_RXP<11>")
	)
	(segment
		(start 134.583424 -94.737936)
		(end 134.577074 -94.748604)
		(width 0.0889)
		(layer "B.Cu")
		(net "P3E_CPU1_PE3_MP_RXP<11>")
	)
	(segment
		(start 134.577074 -98.289618)
		(end 134.583424 -98.300286)
		(width 0.0889)
		(layer "B.Cu")
		(net "P3E_CPU1_PE3_MP_RXP<11>")
	)
	(segment
		(start 134.583424 -99.290886)
		(end 134.58825 -99.299522)
		(width 0.0889)
		(layer "B.Cu")
		(net "P3E_CPU1_PE3_MP_RXP<11>")
	)
	(segment
		(start 134.817612 -103.659178)
		(end 134.817612 -106.237278)
		(width 0.0889)
		(layer "B.Cu")
		(net "P3E_CPU1_PE3_MP_RXP<11>")
	)
	(segment
		(start 117.017546 -120.177814)
		(end 109.044994 -121.772426)
		(width 0.1143)
		(layer "B.Cu")
		(net "P3E_CPU1_PE3_MP_RXP<11>")
	)
	(segment
		(start 82.155792 -121.679462)
		(end 74.033634 -120.055132)
		(width 0.1143)
		(layer "B.Cu")
		(net "P3E_CPU1_PE3_MP_RXP<11>")
	)
	(segment
		(start 4.15036 -108.82884)
		(end 3.81 -108.48848)
		(width 0.1143)
		(layer "B.Cu")
		(net "P3E_CPU1_PE3_MP_RXP<11>")
	)
	(segment
		(start 134.817612 -106.237278)
		(end 134.792212 -106.262678)
		(width 0.0889)
		(layer "B.Cu")
		(net "P3E_CPU1_PE3_MP_RXP<11>")
	)
	(segment
		(start 134.583424 -96.319086)
		(end 134.58825 -96.327722)
		(width 0.0889)
		(layer "B.Cu")
		(net "P3E_CPU1_PE3_MP_RXP<11>")
	)
	(segment
		(start 134.583424 -100.681536)
		(end 134.577074 -100.692204)
		(width 0.0889)
		(layer "B.Cu")
		(net "P3E_CPU1_PE3_MP_RXP<11>")
	)
	(segment
		(start 64.71666 -121.91873)
		(end 60.27674 -121.030492)
		(width 0.1143)
		(layer "B.Cu")
		(net "P3E_CPU1_PE3_MP_RXP<11>")
	)
	(segment
		(start 35.385502 -123.4821)
		(end 30.150054 -123.4821)
		(width 0.1143)
		(layer "B.Cu")
		(net "P3E_CPU1_PE3_MP_RXP<11>")
	)
	(segment
		(start 122.718068 -121.317512)
		(end 117.017546 -120.177814)
		(width 0.1143)
		(layer "B.Cu")
		(net "P3E_CPU1_PE3_MP_RXP<11>")
	)
	(segment
		(start 134.583424 -98.300286)
		(end 134.58825 -98.308922)
		(width 0.0889)
		(layer "B.Cu")
		(net "P3E_CPU1_PE3_MP_RXP<11>")
	)
	(segment
		(start 134.236714 -93.547184)
		(end 134.52983 -93.716348)
		(width 0.0889)
		(layer "B.Cu")
		(net "P3E_CPU1_PE3_MP_RXP<11>")
	)
	(segment
		(start 30.150054 -123.4821)
		(end 20.587208 -120.004078)
		(width 0.1143)
		(layer "B.Cu")
		(net "P3E_CPU1_PE3_MP_RXP<11>")
	)
	(segment
		(start 134.577074 -96.308418)
		(end 134.583424 -96.319086)
		(width 0.0889)
		(layer "B.Cu")
		(net "P3E_CPU1_PE3_MP_RXP<11>")
	)
	(segment
		(start 102.144576 -120.392444)
		(end 97.1423 -121.39295)
		(width 0.1143)
		(layer "B.Cu")
		(net "P3E_CPU1_PE3_MP_RXP<11>")
	)
	(segment
		(start 134.583424 -101.272086)
		(end 134.58825 -101.280722)
		(width 0.0889)
		(layer "B.Cu")
		(net "P3E_CPU1_PE3_MP_RXP<11>")
	)
	(segment
		(start 15.65402 -115.07089)
		(end 8.303514 -112.025684)
		(width 0.1143)
		(layer "B.Cu")
		(net "P3E_CPU1_PE3_MP_RXP<11>")
	)
	(segment
		(start 134.792212 -106.284776)
		(end 134.792212 -114.967512)
		(width 0.1143)
		(layer "B.Cu")
		(net "P3E_CPU1_PE3_MP_RXP<11>")
	)
	(segment
		(start 109.044994 -121.772426)
		(end 102.144576 -120.392444)
		(width 0.1143)
		(layer "B.Cu")
		(net "P3E_CPU1_PE3_MP_RXP<11>")
	)
	(segment
		(start 134.792212 -114.967512)
		(end 129.87274 -119.88673)
		(width 0.1143)
		(layer "B.Cu")
		(net "P3E_CPU1_PE3_MP_RXP<11>")
	)
	(segment
		(start 97.1423 -121.39295)
		(end 90.365834 -120.037606)
		(width 0.1143)
		(layer "B.Cu")
		(net "P3E_CPU1_PE3_MP_RXP<11>")
	)
	(segment
		(start 134.577074 -102.252018)
		(end 134.583424 -102.262686)
		(width 0.0889)
		(layer "B.Cu")
		(net "P3E_CPU1_PE3_MP_RXP<11>")
	)
	(segment
		(start 3.81 -108.0262)
		(end 3.9243 -107.9119)
		(width 0.1143)
		(layer "B.Cu")
		(net "P3E_CPU1_PE3_MP_RXP<11>")
	)
	(segment
		(start 134.583424 -97.309686)
		(end 134.58825 -97.318322)
		(width 0.0889)
		(layer "B.Cu")
		(net "P3E_CPU1_PE3_MP_RXP<11>")
	)
	(segment
		(start 3.9243 -107.9119)
		(end 4.32435 -107.9119)
		(width 0.1143)
		(layer "B.Cu")
		(net "P3E_CPU1_PE3_MP_RXP<11>")
	)
	(segment
		(start 134.583424 -95.328486)
		(end 134.58825 -95.337122)
		(width 0.0889)
		(layer "B.Cu")
		(net "P3E_CPU1_PE3_MP_RXP<11>")
	)
	(segment
		(start 5.106416 -108.82884)
		(end 4.15036 -108.82884)
		(width 0.1143)
		(layer "B.Cu")
		(net "P3E_CPU1_PE3_MP_RXP<11>")
	)
	(segment
		(start 74.033634 -120.055132)
		(end 64.71666 -121.91873)
		(width 0.1143)
		(layer "B.Cu")
		(net "P3E_CPU1_PE3_MP_RXP<11>")
	)
	(segment
		(start 60.27674 -121.030492)
		(end 35.385502 -123.4821)
		(width 0.1143)
		(layer "B.Cu")
		(net "P3E_CPU1_PE3_MP_RXP<11>")
	)
	(arc
		(start 134.583424 -97.709736)
		(mid 134.504202 -97.998854)
		(end 134.577074 -98.289618)
		(width 0.0889)
		(layer "B.Cu")
		(net "P3E_CPU1_PE3_MP_RXP<11>")
	)
	(arc
		(start 134.583424 -101.672136)
		(mid 134.504202 -101.961254)
		(end 134.577074 -102.252018)
		(width 0.0889)
		(layer "B.Cu")
		(net "P3E_CPU1_PE3_MP_RXP<11>")
	)
	(arc
		(start 134.583424 -96.719136)
		(mid 134.504202 -97.008254)
		(end 134.577074 -97.299018)
		(width 0.0889)
		(layer "B.Cu")
		(net "P3E_CPU1_PE3_MP_RXP<11>")
	)
	(arc
		(start 134.58825 -97.318322)
		(mid 134.637005 -97.514674)
		(end 134.583424 -97.709736)
		(width 0.0889)
		(layer "B.Cu")
		(net "P3E_CPU1_PE3_MP_RXP<11>")
	)
	(arc
		(start 134.583424 -99.690936)
		(mid 134.504293 -99.986338)
		(end 134.583424 -100.28174)
		(width 0.0889)
		(layer "B.Cu")
		(net "P3E_CPU1_PE3_MP_RXP<11>")
	)
	(arc
		(start 134.58825 -102.271322)
		(mid 134.637005 -102.467674)
		(end 134.583424 -102.662736)
		(width 0.0889)
		(layer "B.Cu")
		(net "P3E_CPU1_PE3_MP_RXP<11>")
	)
	(arc
		(start 134.58825 -98.308922)
		(mid 134.637005 -98.505274)
		(end 134.583424 -98.700336)
		(width 0.0889)
		(layer "B.Cu")
		(net "P3E_CPU1_PE3_MP_RXP<11>")
	)
	(arc
		(start 134.58825 -99.299522)
		(mid 134.637005 -99.495874)
		(end 134.583424 -99.690936)
		(width 0.0889)
		(layer "B.Cu")
		(net "P3E_CPU1_PE3_MP_RXP<11>")
	)
	(arc
		(start 134.553706 -93.805756)
		(mid 134.505146 -94.075481)
		(end 134.583424 -94.33814)
		(width 0.0889)
		(layer "B.Cu")
		(net "P3E_CPU1_PE3_MP_RXP<11>")
	)
	(arc
		(start 134.58825 -95.337122)
		(mid 134.637005 -95.533474)
		(end 134.583424 -95.728536)
		(width 0.0889)
		(layer "B.Cu")
		(net "P3E_CPU1_PE3_MP_RXP<11>")
	)
	(arc
		(start 134.577074 -100.692204)
		(mid 134.504276 -100.982967)
		(end 134.583424 -101.272086)
		(width 0.0889)
		(layer "B.Cu")
		(net "P3E_CPU1_PE3_MP_RXP<11>")
	)
	(arc
		(start 134.583424 -95.728536)
		(mid 134.504202 -96.017654)
		(end 134.577074 -96.308418)
		(width 0.0889)
		(layer "B.Cu")
		(net "P3E_CPU1_PE3_MP_RXP<11>")
	)
	(arc
		(start 134.58825 -101.280722)
		(mid 134.637005 -101.477074)
		(end 134.583424 -101.672136)
		(width 0.0889)
		(layer "B.Cu")
		(net "P3E_CPU1_PE3_MP_RXP<11>")
	)
	(arc
		(start 134.577074 -94.748604)
		(mid 134.504276 -95.039367)
		(end 134.583424 -95.328486)
		(width 0.0889)
		(layer "B.Cu")
		(net "P3E_CPU1_PE3_MP_RXP<11>")
	)
	(arc
		(start 134.583424 -102.662736)
		(mid 134.504293 -102.958138)
		(end 134.583424 -103.25354)
		(width 0.0889)
		(layer "B.Cu")
		(net "P3E_CPU1_PE3_MP_RXP<11>")
	)
	(arc
		(start 134.583424 -94.33814)
		(mid 134.636923 -94.538038)
		(end 134.583424 -94.737936)
		(width 0.0889)
		(layer "B.Cu")
		(net "P3E_CPU1_PE3_MP_RXP<11>")
	)
	(arc
		(start 134.583424 -98.700336)
		(mid 134.504202 -98.989454)
		(end 134.577074 -99.280218)
		(width 0.0889)
		(layer "B.Cu")
		(net "P3E_CPU1_PE3_MP_RXP<11>")
	)
	(arc
		(start 134.58825 -96.327722)
		(mid 134.637005 -96.524074)
		(end 134.583424 -96.719136)
		(width 0.0889)
		(layer "B.Cu")
		(net "P3E_CPU1_PE3_MP_RXP<11>")
	)
	(arc
		(start 134.583424 -100.28174)
		(mid 134.636923 -100.481638)
		(end 134.583424 -100.681536)
		(width 0.0889)
		(layer "B.Cu")
		(net "P3E_CPU1_PE3_MP_RXP<11>")
	)
	(segment
		(start -1.75387 -103.301038)
		(end -1.425956 -103.628952)
		(width 0.1143)
		(layer "In4.Cu")
		(net "P3E_CPU1_PE3_MP_RXP<11>")
	)
	(segment
		(start 3.9497 -107.9119)
		(end 4.32435 -107.9119)
		(width 0.1143)
		(layer "In4.Cu")
		(net "P3E_CPU1_PE3_MP_RXP<11>")
	)
	(segment
		(start 8.2677 -105.189782)
		(end 7.542022 -105.915714)
		(width 0.1143)
		(layer "In4.Cu")
		(net "P3E_CPU1_PE3_MP_RXP<11>")
	)
	(segment
		(start 4.092702 -106.945684)
		(end 3.8354 -107.368594)
		(width 0.1143)
		(layer "In4.Cu")
		(net "P3E_CPU1_PE3_MP_RXP<11>")
	)
	(segment
		(start -1.63957 -102.769924)
		(end -1.75387 -102.884224)
		(width 0.1143)
		(layer "In4.Cu")
		(net "P3E_CPU1_PE3_MP_RXP<11>")
	)
	(segment
		(start 8.2677 -104.348788)
		(end 8.2677 -105.189782)
		(width 0.1143)
		(layer "In4.Cu")
		(net "P3E_CPU1_PE3_MP_RXP<11>")
	)
	(segment
		(start 7.542022 -105.915714)
		(end 4.092702 -106.945684)
		(width 0.1143)
		(layer "In4.Cu")
		(net "P3E_CPU1_PE3_MP_RXP<11>")
	)
	(segment
		(start -1.75387 -102.884224)
		(end -1.75387 -103.301038)
		(width 0.1143)
		(layer "In4.Cu")
		(net "P3E_CPU1_PE3_MP_RXP<11>")
	)
	(segment
		(start 7.547864 -103.628952)
		(end 8.2677 -104.348788)
		(width 0.1143)
		(layer "In4.Cu")
		(net "P3E_CPU1_PE3_MP_RXP<11>")
	)
	(segment
		(start 3.8354 -107.368594)
		(end 3.8354 -107.7976)
		(width 0.1143)
		(layer "In4.Cu")
		(net "P3E_CPU1_PE3_MP_RXP<11>")
	)
	(segment
		(start -1.425956 -103.628952)
		(end 7.547864 -103.628952)
		(width 0.1143)
		(layer "In4.Cu")
		(net "P3E_CPU1_PE3_MP_RXP<11>")
	)
	(segment
		(start 3.8354 -107.7976)
		(end 3.9497 -107.9119)
		(width 0.1143)
		(layer "In4.Cu")
		(net "P3E_CPU1_PE3_MP_RXP<11>")
	)
	(segment
		(start -1.20015 -102.769924)
		(end -1.63957 -102.769924)
		(width 0.1143)
		(layer "In4.Cu")
		(net "P3E_CPU1_PE3_MP_RXP<11>")
	)
	(segment
		(start 132.806694 -93.052138)
		(end 133.378194 -93.052138)
		(width 0.1143)
		(layer "F.Cu")
		(net "P3E_CPU1_PE3_MP_RXP<10>")
	)
	(via
		(at 133.378194 -93.052138)
		(size 0.508)
		(drill 0.254)
		(layers "F.Cu" "B.Cu")
		(net "P3E_CPU1_PE3_MP_RXP<10>")
	)
	(segment
		(start 116.6749 -116.715794)
		(end 122.351546 -117.850666)
		(width 0.1143)
		(layer "B.Cu")
		(net "P3E_CPU1_PE3_MP_RXP<10>")
	)
	(segment
		(start 108.887514 -118.273068)
		(end 116.6749 -116.715794)
		(width 0.1143)
		(layer "B.Cu")
		(net "P3E_CPU1_PE3_MP_RXP<10>")
	)
	(segment
		(start 131.877308 -106.845608)
		(end 131.851908 -106.820208)
		(width 0.0889)
		(layer "B.Cu")
		(net "P3E_CPU1_PE3_MP_RXP<10>")
	)
	(segment
		(start 64.56045 -118.381018)
		(end 64.293496 -117.04828)
		(width 0.1143)
		(layer "B.Cu")
		(net "P3E_CPU1_PE3_MP_RXP<10>")
	)
	(segment
		(start 132.179568 -101.683058)
		(end 132.173218 -101.67239)
		(width 0.0889)
		(layer "B.Cu")
		(net "P3E_CPU1_PE3_MP_RXP<10>")
	)
	(segment
		(start 122.351546 -117.850666)
		(end 129.500376 -116.421154)
		(width 0.1143)
		(layer "B.Cu")
		(net "P3E_CPU1_PE3_MP_RXP<10>")
	)
	(segment
		(start 8.727948 -108.627672)
		(end 9.903714 -109.803438)
		(width 0.1143)
		(layer "B.Cu")
		(net "P3E_CPU1_PE3_MP_RXP<10>")
	)
	(segment
		(start 5.56514 -105.631742)
		(end 6.01345 -105.631742)
		(width 0.1143)
		(layer "B.Cu")
		(net "P3E_CPU1_PE3_MP_RXP<10>")
	)
	(segment
		(start 63.84163 -118.785386)
		(end 64.360044 -118.681754)
		(width 0.1143)
		(layer "B.Cu")
		(net "P3E_CPU1_PE3_MP_RXP<10>")
	)
	(segment
		(start 90.805 -116.81206)
		(end 97.572068 -118.165372)
		(width 0.1143)
		(layer "B.Cu")
		(net "P3E_CPU1_PE3_MP_RXP<10>")
	)
	(segment
		(start 69.158358 -115.958874)
		(end 69.29247 -116.048536)
		(width 0.1143)
		(layer "B.Cu")
		(net "P3E_CPU1_PE3_MP_RXP<10>")
	)
	(segment
		(start 65.47231 -118.458996)
		(end 73.705212 -116.812568)
		(width 0.1143)
		(layer "B.Cu")
		(net "P3E_CPU1_PE3_MP_RXP<10>")
	)
	(segment
		(start 133.378194 -93.390212)
		(end 133.378194 -93.052138)
		(width 0.0889)
		(layer "B.Cu")
		(net "P3E_CPU1_PE3_MP_RXP<10>")
	)
	(segment
		(start 34.45256 -120.7516)
		(end 60.731908 -118.163594)
		(width 0.1143)
		(layer "B.Cu")
		(net "P3E_CPU1_PE3_MP_RXP<10>")
	)
	(segment
		(start 131.851908 -106.820208)
		(end 131.851908 -106.527092)
		(width 0.0889)
		(layer "B.Cu")
		(net "P3E_CPU1_PE3_MP_RXP<10>")
	)
	(segment
		(start 9.903714 -109.803438)
		(end 17.206722 -112.828832)
		(width 0.1143)
		(layer "B.Cu")
		(net "P3E_CPU1_PE3_MP_RXP<10>")
	)
	(segment
		(start 132.507482 -95.128588)
		(end 132.537454 -95.128588)
		(width 0.0889)
		(layer "B.Cu")
		(net "P3E_CPU1_PE3_MP_RXP<10>")
	)
	(segment
		(start 60.731908 -118.163594)
		(end 63.84163 -118.785386)
		(width 0.1143)
		(layer "B.Cu")
		(net "P3E_CPU1_PE3_MP_RXP<10>")
	)
	(segment
		(start 82.253328 -118.522242)
		(end 90.805 -116.81206)
		(width 0.1143)
		(layer "B.Cu")
		(net "P3E_CPU1_PE3_MP_RXP<10>")
	)
	(segment
		(start 102.959916 -117.08765)
		(end 108.887514 -118.273068)
		(width 0.1143)
		(layer "B.Cu")
		(net "P3E_CPU1_PE3_MP_RXP<10>")
	)
	(segment
		(start 132.173218 -101.67239)
		(end 132.168392 -101.663754)
		(width 0.0889)
		(layer "B.Cu")
		(net "P3E_CPU1_PE3_MP_RXP<10>")
	)
	(segment
		(start 129.500376 -116.421154)
		(end 131.877308 -114.044222)
		(width 0.1143)
		(layer "B.Cu")
		(net "P3E_CPU1_PE3_MP_RXP<10>")
	)
	(segment
		(start 132.256784 -102.778306)
		(end 132.19938 -102.701598)
		(width 0.0889)
		(layer "B.Cu")
		(net "P3E_CPU1_PE3_MP_RXP<10>")
	)
	(segment
		(start 5.079492 -105.146094)
		(end 5.56514 -105.631742)
		(width 0.1143)
		(layer "B.Cu")
		(net "P3E_CPU1_PE3_MP_RXP<10>")
	)
	(segment
		(start 132.173218 -97.309686)
		(end 132.182108 -97.294446)
		(width 0.0889)
		(layer "B.Cu")
		(net "P3E_CPU1_PE3_MP_RXP<10>")
	)
	(segment
		(start 131.877308 -106.867706)
		(end 131.877308 -106.845608)
		(width 0.0889)
		(layer "B.Cu")
		(net "P3E_CPU1_PE3_MP_RXP<10>")
	)
	(segment
		(start 132.173218 -99.290886)
		(end 132.182108 -99.275646)
		(width 0.0889)
		(layer "B.Cu")
		(net "P3E_CPU1_PE3_MP_RXP<10>")
	)
	(segment
		(start 17.206722 -112.828832)
		(end 22.063202 -117.68582)
		(width 0.1143)
		(layer "B.Cu")
		(net "P3E_CPU1_PE3_MP_RXP<10>")
	)
	(segment
		(start 97.572068 -118.165372)
		(end 102.959916 -117.08765)
		(width 0.1143)
		(layer "B.Cu")
		(net "P3E_CPU1_PE3_MP_RXP<10>")
	)
	(segment
		(start 64.360044 -118.681754)
		(end 64.56045 -118.381018)
		(width 0.1143)
		(layer "B.Cu")
		(net "P3E_CPU1_PE3_MP_RXP<10>")
	)
	(segment
		(start 30.631638 -120.7516)
		(end 34.45256 -120.7516)
		(width 0.1143)
		(layer "B.Cu")
		(net "P3E_CPU1_PE3_MP_RXP<10>")
	)
	(segment
		(start 132.173218 -98.300286)
		(end 132.182108 -98.285046)
		(width 0.0889)
		(layer "B.Cu")
		(net "P3E_CPU1_PE3_MP_RXP<10>")
	)
	(segment
		(start 131.851908 -106.527092)
		(end 132.256784 -106.122216)
		(width 0.0889)
		(layer "B.Cu")
		(net "P3E_CPU1_PE3_MP_RXP<10>")
	)
	(segment
		(start 65.171574 -118.25859)
		(end 65.47231 -118.458996)
		(width 0.1143)
		(layer "B.Cu")
		(net "P3E_CPU1_PE3_MP_RXP<10>")
	)
	(segment
		(start 65.054734 -117.675914)
		(end 65.171574 -118.25859)
		(width 0.1143)
		(layer "B.Cu")
		(net "P3E_CPU1_PE3_MP_RXP<10>")
	)
	(segment
		(start 131.877308 -114.044222)
		(end 131.877308 -106.867706)
		(width 0.1143)
		(layer "B.Cu")
		(net "P3E_CPU1_PE3_MP_RXP<10>")
	)
	(segment
		(start 65.255648 -117.375178)
		(end 65.054734 -117.675914)
		(width 0.1143)
		(layer "B.Cu")
		(net "P3E_CPU1_PE3_MP_RXP<10>")
	)
	(segment
		(start 64.383158 -116.914168)
		(end 69.158358 -115.958874)
		(width 0.1143)
		(layer "B.Cu")
		(net "P3E_CPU1_PE3_MP_RXP<10>")
	)
	(segment
		(start 133.443218 -93.455236)
		(end 133.378194 -93.390212)
		(width 0.0889)
		(layer "B.Cu")
		(net "P3E_CPU1_PE3_MP_RXP<10>")
	)
	(segment
		(start 69.370194 -116.43614)
		(end 69.280786 -116.570252)
		(width 0.1143)
		(layer "B.Cu")
		(net "P3E_CPU1_PE3_MP_RXP<10>")
	)
	(segment
		(start 132.179568 -100.692204)
		(end 132.173218 -100.681536)
		(width 0.0889)
		(layer "B.Cu")
		(net "P3E_CPU1_PE3_MP_RXP<10>")
	)
	(segment
		(start 132.173218 -96.319086)
		(end 132.182108 -96.303846)
		(width 0.0889)
		(layer "B.Cu")
		(net "P3E_CPU1_PE3_MP_RXP<10>")
	)
	(segment
		(start 132.173218 -100.28174)
		(end 132.179568 -100.271072)
		(width 0.0889)
		(layer "B.Cu")
		(net "P3E_CPU1_PE3_MP_RXP<10>")
	)
	(segment
		(start 69.280786 -116.570252)
		(end 65.255648 -117.375178)
		(width 0.1143)
		(layer "B.Cu")
		(net "P3E_CPU1_PE3_MP_RXP<10>")
	)
	(segment
		(start 133.36016 -94.633288)
		(end 133.399784 -94.633288)
		(width 0.0889)
		(layer "B.Cu")
		(net "P3E_CPU1_PE3_MP_RXP<10>")
	)
	(segment
		(start 4.499864 -104.76992)
		(end 4.965192 -104.76992)
		(width 0.1143)
		(layer "B.Cu")
		(net "P3E_CPU1_PE3_MP_RXP<10>")
	)
	(segment
		(start 132.256784 -106.122216)
		(end 132.256784 -102.778306)
		(width 0.0889)
		(layer "B.Cu")
		(net "P3E_CPU1_PE3_MP_RXP<10>")
	)
	(segment
		(start 69.29247 -116.048536)
		(end 69.370194 -116.43614)
		(width 0.1143)
		(layer "B.Cu")
		(net "P3E_CPU1_PE3_MP_RXP<10>")
	)
	(segment
		(start 4.965192 -104.76992)
		(end 5.079492 -104.88422)
		(width 0.1143)
		(layer "B.Cu")
		(net "P3E_CPU1_PE3_MP_RXP<10>")
	)
	(segment
		(start 22.063202 -117.68582)
		(end 30.631638 -120.7516)
		(width 0.1143)
		(layer "B.Cu")
		(net "P3E_CPU1_PE3_MP_RXP<10>")
	)
	(segment
		(start 7.88162 -106.585766)
		(end 8.727948 -108.627672)
		(width 0.1143)
		(layer "B.Cu")
		(net "P3E_CPU1_PE3_MP_RXP<10>")
	)
	(segment
		(start 73.705212 -116.812568)
		(end 82.253328 -118.522242)
		(width 0.1143)
		(layer "B.Cu")
		(net "P3E_CPU1_PE3_MP_RXP<10>")
	)
	(segment
		(start 64.293496 -117.04828)
		(end 64.383158 -116.914168)
		(width 0.1143)
		(layer "B.Cu")
		(net "P3E_CPU1_PE3_MP_RXP<10>")
	)
	(segment
		(start 6.01345 -105.631742)
		(end 7.88162 -106.585766)
		(width 0.1143)
		(layer "B.Cu")
		(net "P3E_CPU1_PE3_MP_RXP<10>")
	)
	(segment
		(start 5.079492 -104.88422)
		(end 5.079492 -105.146094)
		(width 0.1143)
		(layer "B.Cu")
		(net "P3E_CPU1_PE3_MP_RXP<10>")
	)
	(arc
		(start 132.173218 -101.27234)
		(mid 132.252306 -100.983111)
		(end 132.179568 -100.692204)
		(width 0.0889)
		(layer "B.Cu")
		(net "P3E_CPU1_PE3_MP_RXP<10>")
	)
	(arc
		(start 132.173218 -99.690682)
		(mid 132.119685 -99.490784)
		(end 132.173218 -99.290886)
		(width 0.0889)
		(layer "B.Cu")
		(net "P3E_CPU1_PE3_MP_RXP<10>")
	)
	(arc
		(start 132.537454 -95.128588)
		(mid 132.822878 -95.045121)
		(end 133.031484 -94.833186)
		(width 0.0889)
		(layer "B.Cu")
		(net "P3E_CPU1_PE3_MP_RXP<10>")
	)
	(arc
		(start 132.173218 -98.700082)
		(mid 132.119685 -98.500184)
		(end 132.173218 -98.300286)
		(width 0.0889)
		(layer "B.Cu")
		(net "P3E_CPU1_PE3_MP_RXP<10>")
	)
	(arc
		(start 132.168392 -101.663754)
		(mid 132.119637 -101.467402)
		(end 132.173218 -101.27234)
		(width 0.0889)
		(layer "B.Cu")
		(net "P3E_CPU1_PE3_MP_RXP<10>")
	)
	(arc
		(start 132.173218 -97.709482)
		(mid 132.119685 -97.509584)
		(end 132.173218 -97.309686)
		(width 0.0889)
		(layer "B.Cu")
		(net "P3E_CPU1_PE3_MP_RXP<10>")
	)
	(arc
		(start 132.173218 -102.26294)
		(mid 132.25244 -101.973822)
		(end 132.179568 -101.683058)
		(width 0.0889)
		(layer "B.Cu")
		(net "P3E_CPU1_PE3_MP_RXP<10>")
	)
	(arc
		(start 132.173218 -95.728282)
		(mid 132.170293 -95.333644)
		(end 132.507482 -95.128588)
		(width 0.0889)
		(layer "B.Cu")
		(net "P3E_CPU1_PE3_MP_RXP<10>")
	)
	(arc
		(start 132.173218 -100.681536)
		(mid 132.119685 -100.481638)
		(end 132.173218 -100.28174)
		(width 0.0889)
		(layer "B.Cu")
		(net "P3E_CPU1_PE3_MP_RXP<10>")
	)
	(arc
		(start 132.182108 -99.275646)
		(mid 132.252505 -98.986695)
		(end 132.173218 -98.700082)
		(width 0.0889)
		(layer "B.Cu")
		(net "P3E_CPU1_PE3_MP_RXP<10>")
	)
	(arc
		(start 132.182108 -98.285046)
		(mid 132.252505 -97.996095)
		(end 132.173218 -97.709482)
		(width 0.0889)
		(layer "B.Cu")
		(net "P3E_CPU1_PE3_MP_RXP<10>")
	)
	(arc
		(start 132.179568 -100.271072)
		(mid 132.252488 -99.980055)
		(end 132.173218 -99.690682)
		(width 0.0889)
		(layer "B.Cu")
		(net "P3E_CPU1_PE3_MP_RXP<10>")
	)
	(arc
		(start 132.19938 -102.701598)
		(mid 132.120439 -102.48618)
		(end 132.173218 -102.26294)
		(width 0.0889)
		(layer "B.Cu")
		(net "P3E_CPU1_PE3_MP_RXP<10>")
	)
	(arc
		(start 132.182108 -97.294446)
		(mid 132.252505 -97.005495)
		(end 132.173218 -96.718882)
		(width 0.0889)
		(layer "B.Cu")
		(net "P3E_CPU1_PE3_MP_RXP<10>")
	)
	(arc
		(start 133.031484 -94.833186)
		(mid 133.170228 -94.691153)
		(end 133.36016 -94.633288)
		(width 0.0889)
		(layer "B.Cu")
		(net "P3E_CPU1_PE3_MP_RXP<10>")
	)
	(arc
		(start 132.182108 -96.303846)
		(mid 132.252505 -96.014895)
		(end 132.173218 -95.728282)
		(width 0.0889)
		(layer "B.Cu")
		(net "P3E_CPU1_PE3_MP_RXP<10>")
	)
	(arc
		(start 133.399784 -94.633288)
		(mid 133.968982 -94.064506)
		(end 133.443218 -93.455236)
		(width 0.0889)
		(layer "B.Cu")
		(net "P3E_CPU1_PE3_MP_RXP<10>")
	)
	(arc
		(start 132.173218 -96.718882)
		(mid 132.119685 -96.518984)
		(end 132.173218 -96.319086)
		(width 0.0889)
		(layer "B.Cu")
		(net "P3E_CPU1_PE3_MP_RXP<10>")
	)
	(segment
		(start 132.806694 -95.033084)
		(end 133.378194 -95.033084)
		(width 0.1143)
		(layer "F.Cu")
		(net "P3E_CPU1_PE3_MP_RXN<9>")
	)
	(via
		(at 133.378194 -95.033084)
		(size 0.508)
		(drill 0.254)
		(layers "F.Cu" "B.Cu")
		(net "P3E_CPU1_PE3_MP_RXN<9>")
	)
	(via
		(at 0.51435 -107.9119)
		(size 0.508)
		(drill 0.254)
		(layers "F.Cu" "B.Cu")
		(net "P3E_CPU1_PE3_MP_RXN<9>")
	)
	(segment
		(start 133.724904 -99.195636)
		(end 133.718554 -99.206304)
		(width 0.0889)
		(layer "B.Cu")
		(net "P3E_CPU1_PE3_MP_RXN<9>")
	)
	(segment
		(start 133.72973 -100.1776)
		(end 133.724904 -100.186236)
		(width 0.0889)
		(layer "B.Cu")
		(net "P3E_CPU1_PE3_MP_RXN<9>")
	)
	(segment
		(start 133.72973 -97.2058)
		(end 133.724904 -97.214436)
		(width 0.0889)
		(layer "B.Cu")
		(net "P3E_CPU1_PE3_MP_RXN<9>")
	)
	(segment
		(start 126.206504 -119.394224)
		(end 126.072138 -119.304562)
		(width 0.1143)
		(layer "B.Cu")
		(net "P3E_CPU1_PE3_MP_RXN<9>")
	)
	(segment
		(start 16.220694 -114.259614)
		(end 8.944356 -111.245142)
		(width 0.1143)
		(layer "B.Cu")
		(net "P3E_CPU1_PE3_MP_RXN<9>")
	)
	(segment
		(start 133.622542 -114.751358)
		(end 129.672842 -118.700804)
		(width 0.1143)
		(layer "B.Cu")
		(net "P3E_CPU1_PE3_MP_RXN<9>")
	)
	(segment
		(start 133.72973 -102.1588)
		(end 133.724904 -102.167436)
		(width 0.0889)
		(layer "B.Cu")
		(net "P3E_CPU1_PE3_MP_RXN<9>")
	)
	(segment
		(start 30.409896 -122.4915)
		(end 21.131784 -119.170958)
		(width 0.1143)
		(layer "B.Cu")
		(net "P3E_CPU1_PE3_MP_RXN<9>")
	)
	(segment
		(start 109.351318 -120.528588)
		(end 102.696264 -119.197628)
		(width 0.1143)
		(layer "B.Cu")
		(net "P3E_CPU1_PE3_MP_RXN<9>")
	)
	(segment
		(start 133.545072 -94.937072)
		(end 133.67131 -94.864174)
		(width 0.0889)
		(layer "B.Cu")
		(net "P3E_CPU1_PE3_MP_RXN<9>")
	)
	(segment
		(start 64.31026 -120.83161)
		(end 60.171838 -120.003824)
		(width 0.1143)
		(layer "B.Cu")
		(net "P3E_CPU1_PE3_MP_RXN<9>")
	)
	(segment
		(start 122.95632 -120.04421)
		(end 122.620024 -120.11152)
		(width 0.1143)
		(layer "B.Cu")
		(net "P3E_CPU1_PE3_MP_RXN<9>")
	)
	(segment
		(start 133.8834 -104.502712)
		(end 133.8834 -106.753406)
		(width 0.0889)
		(layer "B.Cu")
		(net "P3E_CPU1_PE3_MP_RXN<9>")
	)
	(segment
		(start 118.907814 -119.369078)
		(end 118.571772 -119.301768)
		(width 0.1143)
		(layer "B.Cu")
		(net "P3E_CPU1_PE3_MP_RXN<9>")
	)
	(segment
		(start 124.413264 -119.752872)
		(end 124.278898 -119.66321)
		(width 0.1143)
		(layer "B.Cu")
		(net "P3E_CPU1_PE3_MP_RXN<9>")
	)
	(segment
		(start 1.474724 -106.8578)
		(end 1.0287 -107.303824)
		(width 0.1143)
		(layer "B.Cu")
		(net "P3E_CPU1_PE3_MP_RXN<9>")
	)
	(segment
		(start 117.02796 -118.993158)
		(end 109.351318 -120.528588)
		(width 0.1143)
		(layer "B.Cu")
		(net "P3E_CPU1_PE3_MP_RXN<9>")
	)
	(segment
		(start 133.724904 -102.757986)
		(end 133.8834 -103.03256)
		(width 0.0889)
		(layer "B.Cu")
		(net "P3E_CPU1_PE3_MP_RXN<9>")
	)
	(segment
		(start 118.145814 -119.100092)
		(end 118.011194 -119.189754)
		(width 0.1143)
		(layer "B.Cu")
		(net "P3E_CPU1_PE3_MP_RXN<9>")
	)
	(segment
		(start 133.72973 -98.1964)
		(end 133.724904 -98.205036)
		(width 0.0889)
		(layer "B.Cu")
		(net "P3E_CPU1_PE3_MP_RXN<9>")
	)
	(segment
		(start 97.429828 -120.250966)
		(end 90.871294 -118.93931)
		(width 0.1143)
		(layer "B.Cu")
		(net "P3E_CPU1_PE3_MP_RXN<9>")
	)
	(segment
		(start 125.175518 -119.483886)
		(end 124.839222 -119.551196)
		(width 0.1143)
		(layer "B.Cu")
		(net "P3E_CPU1_PE3_MP_RXN<9>")
	)
	(segment
		(start 124.839222 -119.551196)
		(end 124.74956 -119.685562)
		(width 0.1143)
		(layer "B.Cu")
		(net "P3E_CPU1_PE3_MP_RXN<9>")
	)
	(segment
		(start 124.278898 -119.66321)
		(end 123.942602 -119.73052)
		(width 0.1143)
		(layer "B.Cu")
		(net "P3E_CPU1_PE3_MP_RXN<9>")
	)
	(segment
		(start 133.78434 -104.225852)
		(end 133.78434 -104.403652)
		(width 0.0889)
		(layer "B.Cu")
		(net "P3E_CPU1_PE3_MP_RXN<9>")
	)
	(segment
		(start 60.171838 -120.003824)
		(end 34.914078 -122.4915)
		(width 0.1143)
		(layer "B.Cu")
		(net "P3E_CPU1_PE3_MP_RXN<9>")
	)
	(segment
		(start 1.0287 -107.303824)
		(end 1.0287 -107.7976)
		(width 0.1143)
		(layer "B.Cu")
		(net "P3E_CPU1_PE3_MP_RXN<9>")
	)
	(segment
		(start 133.67131 -94.864174)
		(end 133.75005 -94.88551)
		(width 0.0889)
		(layer "B.Cu")
		(net "P3E_CPU1_PE3_MP_RXN<9>")
	)
	(segment
		(start 90.871294 -118.93931)
		(end 82.541618 -120.605296)
		(width 0.1143)
		(layer "B.Cu")
		(net "P3E_CPU1_PE3_MP_RXN<9>")
	)
	(segment
		(start 133.78434 -104.403652)
		(end 133.8834 -104.502712)
		(width 0.0889)
		(layer "B.Cu")
		(net "P3E_CPU1_PE3_MP_RXN<9>")
	)
	(segment
		(start 133.622542 -107.45724)
		(end 133.622542 -114.751358)
		(width 0.1143)
		(layer "B.Cu")
		(net "P3E_CPU1_PE3_MP_RXN<9>")
	)
	(segment
		(start 123.045982 -119.909844)
		(end 122.95632 -120.04421)
		(width 0.1143)
		(layer "B.Cu")
		(net "P3E_CPU1_PE3_MP_RXN<9>")
	)
	(segment
		(start 102.696264 -119.197628)
		(end 97.429828 -120.250966)
		(width 0.1143)
		(layer "B.Cu")
		(net "P3E_CPU1_PE3_MP_RXN<9>")
	)
	(segment
		(start 122.620024 -120.11152)
		(end 119.468392 -119.481092)
		(width 0.1143)
		(layer "B.Cu")
		(net "P3E_CPU1_PE3_MP_RXN<9>")
	)
	(segment
		(start 118.571772 -119.301768)
		(end 118.48211 -119.167402)
		(width 0.1143)
		(layer "B.Cu")
		(net "P3E_CPU1_PE3_MP_RXN<9>")
	)
	(segment
		(start 133.378194 -95.033084)
		(end 133.545072 -94.937072)
		(width 0.0889)
		(layer "B.Cu")
		(net "P3E_CPU1_PE3_MP_RXN<9>")
	)
	(segment
		(start 126.072138 -119.304562)
		(end 125.735842 -119.371618)
		(width 0.1143)
		(layer "B.Cu")
		(net "P3E_CPU1_PE3_MP_RXN<9>")
	)
	(segment
		(start 133.718554 -100.766118)
		(end 133.724904 -100.776786)
		(width 0.0889)
		(layer "B.Cu")
		(net "P3E_CPU1_PE3_MP_RXN<9>")
	)
	(segment
		(start 123.516644 -119.932196)
		(end 123.382278 -119.842534)
		(width 0.1143)
		(layer "B.Cu")
		(net "P3E_CPU1_PE3_MP_RXN<9>")
	)
	(segment
		(start 0.9144 -107.9119)
		(end 0.51435 -107.9119)
		(width 0.1143)
		(layer "B.Cu")
		(net "P3E_CPU1_PE3_MP_RXN<9>")
	)
	(segment
		(start 7.215378 -109.516164)
		(end 6.384036 -107.75442)
		(width 0.1143)
		(layer "B.Cu")
		(net "P3E_CPU1_PE3_MP_RXN<9>")
	)
	(segment
		(start 1.0287 -107.7976)
		(end 0.9144 -107.9119)
		(width 0.1143)
		(layer "B.Cu")
		(net "P3E_CPU1_PE3_MP_RXN<9>")
	)
	(segment
		(start 125.309884 -119.573548)
		(end 125.175518 -119.483886)
		(width 0.1143)
		(layer "B.Cu")
		(net "P3E_CPU1_PE3_MP_RXN<9>")
	)
	(segment
		(start 73.992232 -118.895368)
		(end 64.31026 -120.83161)
		(width 0.1143)
		(layer "B.Cu")
		(net "P3E_CPU1_PE3_MP_RXN<9>")
	)
	(segment
		(start 133.724904 -98.205036)
		(end 133.718554 -98.215704)
		(width 0.0889)
		(layer "B.Cu")
		(net "P3E_CPU1_PE3_MP_RXN<9>")
	)
	(segment
		(start 34.914078 -122.4915)
		(end 30.409896 -122.4915)
		(width 0.1143)
		(layer "B.Cu")
		(net "P3E_CPU1_PE3_MP_RXN<9>")
	)
	(segment
		(start 133.8834 -104.126792)
		(end 133.78434 -104.225852)
		(width 0.0889)
		(layer "B.Cu")
		(net "P3E_CPU1_PE3_MP_RXN<9>")
	)
	(segment
		(start 133.724904 -97.214436)
		(end 133.718554 -97.225104)
		(width 0.0889)
		(layer "B.Cu")
		(net "P3E_CPU1_PE3_MP_RXN<9>")
	)
	(segment
		(start 133.8834 -103.03256)
		(end 133.8834 -104.126792)
		(width 0.0889)
		(layer "B.Cu")
		(net "P3E_CPU1_PE3_MP_RXN<9>")
	)
	(segment
		(start 129.672842 -118.700804)
		(end 126.206504 -119.394224)
		(width 0.1143)
		(layer "B.Cu")
		(net "P3E_CPU1_PE3_MP_RXN<9>")
	)
	(segment
		(start 6.384036 -107.75442)
		(end 4.62915 -106.8578)
		(width 0.1143)
		(layer "B.Cu")
		(net "P3E_CPU1_PE3_MP_RXN<9>")
	)
	(segment
		(start 133.647942 -107.409742)
		(end 133.622542 -107.435142)
		(width 0.0889)
		(layer "B.Cu")
		(net "P3E_CPU1_PE3_MP_RXN<9>")
	)
	(segment
		(start 118.011194 -119.189754)
		(end 117.02796 -118.993158)
		(width 0.1143)
		(layer "B.Cu")
		(net "P3E_CPU1_PE3_MP_RXN<9>")
	)
	(segment
		(start 133.8834 -106.753406)
		(end 133.647942 -106.988864)
		(width 0.0889)
		(layer "B.Cu")
		(net "P3E_CPU1_PE3_MP_RXN<9>")
	)
	(segment
		(start 124.74956 -119.685562)
		(end 124.413264 -119.752872)
		(width 0.1143)
		(layer "B.Cu")
		(net "P3E_CPU1_PE3_MP_RXN<9>")
	)
	(segment
		(start 125.64618 -119.506238)
		(end 125.309884 -119.573548)
		(width 0.1143)
		(layer "B.Cu")
		(net "P3E_CPU1_PE3_MP_RXN<9>")
	)
	(segment
		(start 133.72973 -99.187)
		(end 133.724904 -99.195636)
		(width 0.0889)
		(layer "B.Cu")
		(net "P3E_CPU1_PE3_MP_RXN<9>")
	)
	(segment
		(start 123.382278 -119.842534)
		(end 123.045982 -119.909844)
		(width 0.1143)
		(layer "B.Cu")
		(net "P3E_CPU1_PE3_MP_RXN<9>")
	)
	(segment
		(start 119.042434 -119.279416)
		(end 118.907814 -119.369078)
		(width 0.1143)
		(layer "B.Cu")
		(net "P3E_CPU1_PE3_MP_RXN<9>")
	)
	(segment
		(start 21.131784 -119.170958)
		(end 16.220694 -114.259614)
		(width 0.1143)
		(layer "B.Cu")
		(net "P3E_CPU1_PE3_MP_RXN<9>")
	)
	(segment
		(start 119.468392 -119.481092)
		(end 119.37873 -119.346726)
		(width 0.1143)
		(layer "B.Cu")
		(net "P3E_CPU1_PE3_MP_RXN<9>")
	)
	(segment
		(start 133.72973 -96.2152)
		(end 133.724904 -96.223836)
		(width 0.0889)
		(layer "B.Cu")
		(net "P3E_CPU1_PE3_MP_RXN<9>")
	)
	(segment
		(start 133.724904 -102.167436)
		(end 133.718554 -102.178104)
		(width 0.0889)
		(layer "B.Cu")
		(net "P3E_CPU1_PE3_MP_RXN<9>")
	)
	(segment
		(start 119.37873 -119.346726)
		(end 119.042434 -119.279416)
		(width 0.1143)
		(layer "B.Cu")
		(net "P3E_CPU1_PE3_MP_RXN<9>")
	)
	(segment
		(start 4.62915 -106.8578)
		(end 1.474724 -106.8578)
		(width 0.1143)
		(layer "B.Cu")
		(net "P3E_CPU1_PE3_MP_RXN<9>")
	)
	(segment
		(start 123.85294 -119.864886)
		(end 123.516644 -119.932196)
		(width 0.1143)
		(layer "B.Cu")
		(net "P3E_CPU1_PE3_MP_RXN<9>")
	)
	(segment
		(start 8.944356 -111.245142)
		(end 7.215378 -109.516164)
		(width 0.1143)
		(layer "B.Cu")
		(net "P3E_CPU1_PE3_MP_RXN<9>")
	)
	(segment
		(start 82.541618 -120.605296)
		(end 73.992232 -118.895368)
		(width 0.1143)
		(layer "B.Cu")
		(net "P3E_CPU1_PE3_MP_RXN<9>")
	)
	(segment
		(start 118.48211 -119.167402)
		(end 118.145814 -119.100092)
		(width 0.1143)
		(layer "B.Cu")
		(net "P3E_CPU1_PE3_MP_RXN<9>")
	)
	(segment
		(start 123.942602 -119.73052)
		(end 123.85294 -119.864886)
		(width 0.1143)
		(layer "B.Cu")
		(net "P3E_CPU1_PE3_MP_RXN<9>")
	)
	(segment
		(start 133.622542 -107.435142)
		(end 133.622542 -107.45724)
		(width 0.0889)
		(layer "B.Cu")
		(net "P3E_CPU1_PE3_MP_RXN<9>")
	)
	(segment
		(start 133.647942 -106.988864)
		(end 133.647942 -107.409742)
		(width 0.0889)
		(layer "B.Cu")
		(net "P3E_CPU1_PE3_MP_RXN<9>")
	)
	(segment
		(start 125.735842 -119.371618)
		(end 125.64618 -119.506238)
		(width 0.1143)
		(layer "B.Cu")
		(net "P3E_CPU1_PE3_MP_RXN<9>")
	)
	(segment
		(start 133.724904 -96.223836)
		(end 133.718554 -96.234504)
		(width 0.0889)
		(layer "B.Cu")
		(net "P3E_CPU1_PE3_MP_RXN<9>")
	)
	(arc
		(start 133.724904 -101.767386)
		(mid 133.778374 -101.962449)
		(end 133.72973 -102.1588)
		(width 0.0889)
		(layer "B.Cu")
		(net "P3E_CPU1_PE3_MP_RXN<9>")
	)
	(arc
		(start 133.718554 -99.206304)
		(mid 133.645756 -99.497067)
		(end 133.724904 -99.786186)
		(width 0.0889)
		(layer "B.Cu")
		(net "P3E_CPU1_PE3_MP_RXN<9>")
	)
	(arc
		(start 133.718554 -97.225104)
		(mid 133.645756 -97.515867)
		(end 133.724904 -97.804986)
		(width 0.0889)
		(layer "B.Cu")
		(net "P3E_CPU1_PE3_MP_RXN<9>")
	)
	(arc
		(start 133.724904 -100.186236)
		(mid 133.645682 -100.475354)
		(end 133.718554 -100.766118)
		(width 0.0889)
		(layer "B.Cu")
		(net "P3E_CPU1_PE3_MP_RXN<9>")
	)
	(arc
		(start 133.724904 -97.804986)
		(mid 133.778374 -98.000049)
		(end 133.72973 -98.1964)
		(width 0.0889)
		(layer "B.Cu")
		(net "P3E_CPU1_PE3_MP_RXN<9>")
	)
	(arc
		(start 133.724904 -99.786186)
		(mid 133.778374 -99.981249)
		(end 133.72973 -100.1776)
		(width 0.0889)
		(layer "B.Cu")
		(net "P3E_CPU1_PE3_MP_RXN<9>")
	)
	(arc
		(start 133.724904 -95.823786)
		(mid 133.778374 -96.018849)
		(end 133.72973 -96.2152)
		(width 0.0889)
		(layer "B.Cu")
		(net "P3E_CPU1_PE3_MP_RXN<9>")
	)
	(arc
		(start 133.75005 -94.88551)
		(mid 133.777319 -95.062139)
		(end 133.724904 -95.232982)
		(width 0.0889)
		(layer "B.Cu")
		(net "P3E_CPU1_PE3_MP_RXN<9>")
	)
	(arc
		(start 133.724904 -100.776786)
		(mid 133.778403 -100.976684)
		(end 133.724904 -101.176582)
		(width 0.0889)
		(layer "B.Cu")
		(net "P3E_CPU1_PE3_MP_RXN<9>")
	)
	(arc
		(start 133.724904 -96.814386)
		(mid 133.778374 -97.009449)
		(end 133.72973 -97.2058)
		(width 0.0889)
		(layer "B.Cu")
		(net "P3E_CPU1_PE3_MP_RXN<9>")
	)
	(arc
		(start 133.724904 -95.232982)
		(mid 133.645773 -95.528384)
		(end 133.724904 -95.823786)
		(width 0.0889)
		(layer "B.Cu")
		(net "P3E_CPU1_PE3_MP_RXN<9>")
	)
	(arc
		(start 133.724904 -98.795586)
		(mid 133.778374 -98.990649)
		(end 133.72973 -99.187)
		(width 0.0889)
		(layer "B.Cu")
		(net "P3E_CPU1_PE3_MP_RXN<9>")
	)
	(arc
		(start 133.718554 -98.215704)
		(mid 133.645756 -98.506467)
		(end 133.724904 -98.795586)
		(width 0.0889)
		(layer "B.Cu")
		(net "P3E_CPU1_PE3_MP_RXN<9>")
	)
	(arc
		(start 133.724904 -101.176582)
		(mid 133.645773 -101.471984)
		(end 133.724904 -101.767386)
		(width 0.0889)
		(layer "B.Cu")
		(net "P3E_CPU1_PE3_MP_RXN<9>")
	)
	(arc
		(start 133.718554 -102.178104)
		(mid 133.645756 -102.468867)
		(end 133.724904 -102.757986)
		(width 0.0889)
		(layer "B.Cu")
		(net "P3E_CPU1_PE3_MP_RXN<9>")
	)
	(arc
		(start 133.718554 -96.234504)
		(mid 133.645756 -96.525267)
		(end 133.724904 -96.814386)
		(width 0.0889)
		(layer "B.Cu")
		(net "P3E_CPU1_PE3_MP_RXN<9>")
	)
	(segment
		(start 1.0033 -106.872278)
		(end 0.853948 -106.722926)
		(width 0.1143)
		(layer "In4.Cu")
		(net "P3E_CPU1_PE3_MP_RXN<9>")
	)
	(segment
		(start 0.739648 -104.76992)
		(end 0.299974 -104.76992)
		(width 0.1143)
		(layer "In4.Cu")
		(net "P3E_CPU1_PE3_MP_RXN<9>")
	)
	(segment
		(start 0.853948 -106.722926)
		(end 0.853948 -104.88422)
		(width 0.1143)
		(layer "In4.Cu")
		(net "P3E_CPU1_PE3_MP_RXN<9>")
	)
	(segment
		(start 0.853948 -104.88422)
		(end 0.739648 -104.76992)
		(width 0.1143)
		(layer "In4.Cu")
		(net "P3E_CPU1_PE3_MP_RXN<9>")
	)
	(segment
		(start 1.0033 -107.7976)
		(end 1.0033 -106.872278)
		(width 0.1143)
		(layer "In4.Cu")
		(net "P3E_CPU1_PE3_MP_RXN<9>")
	)
	(segment
		(start 0.889 -107.9119)
		(end 1.0033 -107.7976)
		(width 0.1143)
		(layer "In4.Cu")
		(net "P3E_CPU1_PE3_MP_RXN<9>")
	)
	(segment
		(start 0.51435 -107.9119)
		(end 0.889 -107.9119)
		(width 0.1143)
		(layer "In4.Cu")
		(net "P3E_CPU1_PE3_MP_RXN<9>")
	)
	(segment
		(start 132.806694 -96.023938)
		(end 133.378194 -96.023938)
		(width 0.1143)
		(layer "F.Cu")
		(net "P3E_CPU1_PE3_MP_RXN<8>")
	)
	(via
		(at 133.378194 -96.023938)
		(size 0.508)
		(drill 0.254)
		(layers "F.Cu" "B.Cu")
		(net "P3E_CPU1_PE3_MP_RXN<8>")
	)
	(segment
		(start 30.515814 -121.7422)
		(end 21.511006 -118.519448)
		(width 0.1143)
		(layer "B.Cu")
		(net "P3E_CPU1_PE3_MP_RXN<8>")
	)
	(segment
		(start 133.270752 -103.907082)
		(end 133.171692 -104.006142)
		(width 0.0889)
		(layer "B.Cu")
		(net "P3E_CPU1_PE3_MP_RXN<8>")
	)
	(segment
		(start 132.8674 -107.115864)
		(end 132.8674 -114.437922)
		(width 0.1143)
		(layer "B.Cu")
		(net "P3E_CPU1_PE3_MP_RXN<8>")
	)
	(segment
		(start 133.031484 -99.195636)
		(end 133.037834 -99.206304)
		(width 0.0889)
		(layer "B.Cu")
		(net "P3E_CPU1_PE3_MP_RXN<8>")
	)
	(segment
		(start 133.026658 -96.2152)
		(end 133.031484 -96.223836)
		(width 0.0889)
		(layer "B.Cu")
		(net "P3E_CPU1_PE3_MP_RXN<8>")
	)
	(segment
		(start 122.030998 -119.065548)
		(end 116.862352 -118.031768)
		(width 0.1143)
		(layer "B.Cu")
		(net "P3E_CPU1_PE3_MP_RXN<8>")
	)
	(segment
		(start 133.031484 -102.167436)
		(end 133.037834 -102.178104)
		(width 0.0889)
		(layer "B.Cu")
		(net "P3E_CPU1_PE3_MP_RXN<8>")
	)
	(segment
		(start 133.1722 -103.373936)
		(end 133.1722 -103.451914)
		(width 0.0889)
		(layer "B.Cu")
		(net "P3E_CPU1_PE3_MP_RXN<8>")
	)
	(segment
		(start 133.171692 -103.452422)
		(end 133.171692 -103.630222)
		(width 0.0889)
		(layer "B.Cu")
		(net "P3E_CPU1_PE3_MP_RXN<8>")
	)
	(segment
		(start 133.1722 -103.451914)
		(end 133.171692 -103.452422)
		(width 0.0889)
		(layer "B.Cu")
		(net "P3E_CPU1_PE3_MP_RXN<8>")
	)
	(segment
		(start 133.026658 -100.1776)
		(end 133.031484 -100.186236)
		(width 0.0889)
		(layer "B.Cu")
		(net "P3E_CPU1_PE3_MP_RXN<8>")
	)
	(segment
		(start 133.026658 -102.1588)
		(end 133.031484 -102.167436)
		(width 0.0889)
		(layer "B.Cu")
		(net "P3E_CPU1_PE3_MP_RXN<8>")
	)
	(segment
		(start 109.14507 -119.575326)
		(end 102.721156 -118.29034)
		(width 0.1143)
		(layer "B.Cu")
		(net "P3E_CPU1_PE3_MP_RXN<8>")
	)
	(segment
		(start 16.640556 -113.648998)
		(end 9.357868 -110.631986)
		(width 0.1143)
		(layer "B.Cu")
		(net "P3E_CPU1_PE3_MP_RXN<8>")
	)
	(segment
		(start 133.026658 -99.187)
		(end 133.031484 -99.195636)
		(width 0.0889)
		(layer "B.Cu")
		(net "P3E_CPU1_PE3_MP_RXN<8>")
	)
	(segment
		(start 133.133592 -103.335328)
		(end 133.1722 -103.373936)
		(width 0.0889)
		(layer "B.Cu")
		(net "P3E_CPU1_PE3_MP_RXN<8>")
	)
	(segment
		(start -3.19278 -104.947974)
		(end -3.370834 -104.76992)
		(width 0.1143)
		(layer "B.Cu")
		(net "P3E_CPU1_PE3_MP_RXN<8>")
	)
	(segment
		(start 133.031484 -96.223836)
		(end 133.037834 -96.234504)
		(width 0.0889)
		(layer "B.Cu")
		(net "P3E_CPU1_PE3_MP_RXN<8>")
	)
	(segment
		(start 60.399676 -119.170704)
		(end 34.290254 -121.7422)
		(width 0.1143)
		(layer "B.Cu")
		(net "P3E_CPU1_PE3_MP_RXN<8>")
	)
	(segment
		(start 91.251024 -118.106698)
		(end 82.922872 -119.772176)
		(width 0.1143)
		(layer "B.Cu")
		(net "P3E_CPU1_PE3_MP_RXN<8>")
	)
	(segment
		(start 7.85876 -109.132624)
		(end 6.96341 -107.236514)
		(width 0.1143)
		(layer "B.Cu")
		(net "P3E_CPU1_PE3_MP_RXN<8>")
	)
	(segment
		(start 133.031484 -97.214436)
		(end 133.037834 -97.225104)
		(width 0.0889)
		(layer "B.Cu")
		(net "P3E_CPU1_PE3_MP_RXN<8>")
	)
	(segment
		(start 133.378194 -96.023938)
		(end 133.085078 -95.854774)
		(width 0.0889)
		(layer "B.Cu")
		(net "P3E_CPU1_PE3_MP_RXN<8>")
	)
	(segment
		(start 73.956926 -117.978936)
		(end 64.198754 -119.930672)
		(width 0.1143)
		(layer "B.Cu")
		(net "P3E_CPU1_PE3_MP_RXN<8>")
	)
	(segment
		(start -2.707132 -106.101642)
		(end -3.19278 -105.615994)
		(width 0.1143)
		(layer "B.Cu")
		(net "P3E_CPU1_PE3_MP_RXN<8>")
	)
	(segment
		(start 132.8674 -107.093766)
		(end 132.8674 -107.115864)
		(width 0.0889)
		(layer "B.Cu")
		(net "P3E_CPU1_PE3_MP_RXN<8>")
	)
	(segment
		(start 133.270752 -103.729282)
		(end 133.270752 -103.907082)
		(width 0.0889)
		(layer "B.Cu")
		(net "P3E_CPU1_PE3_MP_RXN<8>")
	)
	(segment
		(start 133.031484 -103.15829)
		(end 133.03123 -103.15829)
		(width 0.0889)
		(layer "B.Cu")
		(net "P3E_CPU1_PE3_MP_RXN<8>")
	)
	(segment
		(start 82.922872 -119.772176)
		(end 73.956926 -117.978936)
		(width 0.1143)
		(layer "B.Cu")
		(net "P3E_CPU1_PE3_MP_RXN<8>")
	)
	(segment
		(start 133.03123 -103.15829)
		(end 133.133592 -103.335328)
		(width 0.0889)
		(layer "B.Cu")
		(net "P3E_CPU1_PE3_MP_RXN<8>")
	)
	(segment
		(start 132.842 -107.068366)
		(end 132.8674 -107.093766)
		(width 0.0889)
		(layer "B.Cu")
		(net "P3E_CPU1_PE3_MP_RXN<8>")
	)
	(segment
		(start 4.74218 -106.101642)
		(end -2.707132 -106.101642)
		(width 0.1143)
		(layer "B.Cu")
		(net "P3E_CPU1_PE3_MP_RXN<8>")
	)
	(segment
		(start 133.026658 -97.2058)
		(end 133.031484 -97.214436)
		(width 0.0889)
		(layer "B.Cu")
		(net "P3E_CPU1_PE3_MP_RXN<8>")
	)
	(segment
		(start 133.037834 -100.766118)
		(end 133.031484 -100.776786)
		(width 0.0889)
		(layer "B.Cu")
		(net "P3E_CPU1_PE3_MP_RXN<8>")
	)
	(segment
		(start 133.031484 -98.205036)
		(end 133.037834 -98.215704)
		(width 0.0889)
		(layer "B.Cu")
		(net "P3E_CPU1_PE3_MP_RXN<8>")
	)
	(segment
		(start 21.511006 -118.519448)
		(end 16.640556 -113.648998)
		(width 0.1143)
		(layer "B.Cu")
		(net "P3E_CPU1_PE3_MP_RXN<8>")
	)
	(segment
		(start 133.171692 -104.006142)
		(end 133.171692 -106.467656)
		(width 0.0889)
		(layer "B.Cu")
		(net "P3E_CPU1_PE3_MP_RXN<8>")
	)
	(segment
		(start 64.198754 -119.930672)
		(end 60.399676 -119.170704)
		(width 0.1143)
		(layer "B.Cu")
		(net "P3E_CPU1_PE3_MP_RXN<8>")
	)
	(segment
		(start 133.171692 -103.630222)
		(end 133.270752 -103.729282)
		(width 0.0889)
		(layer "B.Cu")
		(net "P3E_CPU1_PE3_MP_RXN<8>")
	)
	(segment
		(start 133.085078 -95.854774)
		(end 133.006338 -95.87611)
		(width 0.0889)
		(layer "B.Cu")
		(net "P3E_CPU1_PE3_MP_RXN<8>")
	)
	(segment
		(start 34.290254 -121.7422)
		(end 30.515814 -121.7422)
		(width 0.1143)
		(layer "B.Cu")
		(net "P3E_CPU1_PE3_MP_RXN<8>")
	)
	(segment
		(start -3.19278 -105.615994)
		(end -3.19278 -104.947974)
		(width 0.1143)
		(layer "B.Cu")
		(net "P3E_CPU1_PE3_MP_RXN<8>")
	)
	(segment
		(start 133.026658 -98.1964)
		(end 133.031484 -98.205036)
		(width 0.0889)
		(layer "B.Cu")
		(net "P3E_CPU1_PE3_MP_RXN<8>")
	)
	(segment
		(start 116.862352 -118.031768)
		(end 109.14507 -119.575326)
		(width 0.1143)
		(layer "B.Cu")
		(net "P3E_CPU1_PE3_MP_RXN<8>")
	)
	(segment
		(start 6.96341 -107.236514)
		(end 4.74218 -106.101642)
		(width 0.1143)
		(layer "B.Cu")
		(net "P3E_CPU1_PE3_MP_RXN<8>")
	)
	(segment
		(start 102.721156 -118.29034)
		(end 97.445322 -119.345456)
		(width 0.1143)
		(layer "B.Cu")
		(net "P3E_CPU1_PE3_MP_RXN<8>")
	)
	(segment
		(start -3.370834 -104.76992)
		(end -3.899916 -104.76992)
		(width 0.1143)
		(layer "B.Cu")
		(net "P3E_CPU1_PE3_MP_RXN<8>")
	)
	(segment
		(start 129.792222 -117.513354)
		(end 122.030998 -119.065548)
		(width 0.1143)
		(layer "B.Cu")
		(net "P3E_CPU1_PE3_MP_RXN<8>")
	)
	(segment
		(start 9.357868 -110.631986)
		(end 7.85876 -109.132624)
		(width 0.1143)
		(layer "B.Cu")
		(net "P3E_CPU1_PE3_MP_RXN<8>")
	)
	(segment
		(start 97.445322 -119.345456)
		(end 91.251024 -118.106698)
		(width 0.1143)
		(layer "B.Cu")
		(net "P3E_CPU1_PE3_MP_RXN<8>")
	)
	(segment
		(start 132.8674 -114.437922)
		(end 129.792222 -117.513354)
		(width 0.1143)
		(layer "B.Cu")
		(net "P3E_CPU1_PE3_MP_RXN<8>")
	)
	(segment
		(start 132.842 -106.797348)
		(end 132.842 -107.068366)
		(width 0.0889)
		(layer "B.Cu")
		(net "P3E_CPU1_PE3_MP_RXN<8>")
	)
	(segment
		(start 133.171692 -106.467656)
		(end 132.842 -106.797348)
		(width 0.0889)
		(layer "B.Cu")
		(net "P3E_CPU1_PE3_MP_RXN<8>")
	)
	(arc
		(start 133.031484 -100.776786)
		(mid 132.977985 -100.976684)
		(end 133.031484 -101.176582)
		(width 0.0889)
		(layer "B.Cu")
		(net "P3E_CPU1_PE3_MP_RXN<8>")
	)
	(arc
		(start 133.031484 -101.176582)
		(mid 133.110615 -101.471984)
		(end 133.031484 -101.767386)
		(width 0.0889)
		(layer "B.Cu")
		(net "P3E_CPU1_PE3_MP_RXN<8>")
	)
	(arc
		(start 133.031484 -97.804986)
		(mid 132.978014 -98.000049)
		(end 133.026658 -98.1964)
		(width 0.0889)
		(layer "B.Cu")
		(net "P3E_CPU1_PE3_MP_RXN<8>")
	)
	(arc
		(start 133.037834 -96.234504)
		(mid 133.110632 -96.525267)
		(end 133.031484 -96.814386)
		(width 0.0889)
		(layer "B.Cu")
		(net "P3E_CPU1_PE3_MP_RXN<8>")
	)
	(arc
		(start 133.037834 -102.178104)
		(mid 133.110632 -102.468867)
		(end 133.031484 -102.757986)
		(width 0.0889)
		(layer "B.Cu")
		(net "P3E_CPU1_PE3_MP_RXN<8>")
	)
	(arc
		(start 133.037834 -99.206304)
		(mid 133.110632 -99.497067)
		(end 133.031484 -99.786186)
		(width 0.0889)
		(layer "B.Cu")
		(net "P3E_CPU1_PE3_MP_RXN<8>")
	)
	(arc
		(start 133.031484 -99.786186)
		(mid 132.978014 -99.981249)
		(end 133.026658 -100.1776)
		(width 0.0889)
		(layer "B.Cu")
		(net "P3E_CPU1_PE3_MP_RXN<8>")
	)
	(arc
		(start 133.006338 -95.87611)
		(mid 132.978768 -96.047913)
		(end 133.026658 -96.2152)
		(width 0.0889)
		(layer "B.Cu")
		(net "P3E_CPU1_PE3_MP_RXN<8>")
	)
	(arc
		(start 133.031484 -98.795586)
		(mid 132.978014 -98.990649)
		(end 133.026658 -99.187)
		(width 0.0889)
		(layer "B.Cu")
		(net "P3E_CPU1_PE3_MP_RXN<8>")
	)
	(arc
		(start 133.037834 -98.215704)
		(mid 133.110632 -98.506467)
		(end 133.031484 -98.795586)
		(width 0.0889)
		(layer "B.Cu")
		(net "P3E_CPU1_PE3_MP_RXN<8>")
	)
	(arc
		(start 133.031484 -102.757986)
		(mid 132.977858 -102.958138)
		(end 133.031484 -103.15829)
		(width 0.0889)
		(layer "B.Cu")
		(net "P3E_CPU1_PE3_MP_RXN<8>")
	)
	(arc
		(start 133.031484 -100.186236)
		(mid 133.110706 -100.475354)
		(end 133.037834 -100.766118)
		(width 0.0889)
		(layer "B.Cu")
		(net "P3E_CPU1_PE3_MP_RXN<8>")
	)
	(arc
		(start 133.031484 -101.767386)
		(mid 132.978014 -101.962449)
		(end 133.026658 -102.1588)
		(width 0.0889)
		(layer "B.Cu")
		(net "P3E_CPU1_PE3_MP_RXN<8>")
	)
	(arc
		(start 133.031484 -96.814386)
		(mid 132.978014 -97.009449)
		(end 133.026658 -97.2058)
		(width 0.0889)
		(layer "B.Cu")
		(net "P3E_CPU1_PE3_MP_RXN<8>")
	)
	(arc
		(start 133.037834 -97.225104)
		(mid 133.110632 -97.515867)
		(end 133.031484 -97.804986)
		(width 0.0889)
		(layer "B.Cu")
		(net "P3E_CPU1_PE3_MP_RXN<8>")
	)
	(segment
		(start 135.382254 -89.584784)
		(end 135.953754 -89.584784)
		(width 0.1143)
		(layer "F.Cu")
		(net "P3E_CPU1_PE3_MP_RXN<15>")
	)
	(via
		(at 2.739644 -112.21339)
		(size 0.508)
		(drill 0.254)
		(layers "F.Cu" "B.Cu")
		(net "P3E_CPU1_PE3_MP_RXN<15>")
	)
	(via
		(at 135.953754 -89.584784)
		(size 0.508)
		(drill 0.254)
		(layers "F.Cu" "B.Cu")
		(net "P3E_CPU1_PE3_MP_RXN<15>")
	)
	(via
		(at 137.48004 -109.08538)
		(size 0.1016)
		(drill 0.0508)
		(layers "F.Cu" "B.Cu")
		(net "P3E_CPU1_PE3_MP_RXN<15>")
	)
	(segment
		(start 137.48004 -115.362736)
		(end 130.543554 -122.299222)
		(width 0.1143)
		(layer "B.Cu")
		(net "P3E_CPU1_PE3_MP_RXN<15>")
	)
	(segment
		(start 64.657224 -124.225304)
		(end 60.370974 -123.368308)
		(width 0.1143)
		(layer "B.Cu")
		(net "P3E_CPU1_PE3_MP_RXN<15>")
	)
	(segment
		(start 137.45464 -102.534974)
		(end 137.5537 -102.435914)
		(width 0.0889)
		(layer "B.Cu")
		(net "P3E_CPU1_PE3_MP_RXN<15>")
	)
	(segment
		(start 136.471914 -96.234504)
		(end 136.465564 -96.223836)
		(width 0.0889)
		(layer "B.Cu")
		(net "P3E_CPU1_PE3_MP_RXN<15>")
	)
	(segment
		(start 136.46531 -99.78644)
		(end 136.46531 -99.786694)
		(width 0.0889)
		(layer "B.Cu")
		(net "P3E_CPU1_PE3_MP_RXN<15>")
	)
	(segment
		(start 137.45464 -101.195124)
		(end 136.529064 -100.269548)
		(width 0.0889)
		(layer "B.Cu")
		(net "P3E_CPU1_PE3_MP_RXN<15>")
	)
	(segment
		(start 3.253994 -112.32769)
		(end 3.139694 -112.21339)
		(width 0.1143)
		(layer "B.Cu")
		(net "P3E_CPU1_PE3_MP_RXN<15>")
	)
	(segment
		(start 36.905946 -125.6792)
		(end 27.315922 -125.6792)
		(width 0.1143)
		(layer "B.Cu")
		(net "P3E_CPU1_PE3_MP_RXN<15>")
	)
	(segment
		(start 60.370974 -123.368308)
		(end 36.905946 -125.6792)
		(width 0.1143)
		(layer "B.Cu")
		(net "P3E_CPU1_PE3_MP_RXN<15>")
	)
	(segment
		(start 137.5537 -102.435914)
		(end 137.5537 -102.258114)
		(width 0.0889)
		(layer "B.Cu")
		(net "P3E_CPU1_PE3_MP_RXN<15>")
	)
	(segment
		(start 16.425418 -122.100594)
		(end 13.9827 -119.657876)
		(width 0.1143)
		(layer "B.Cu")
		(net "P3E_CPU1_PE3_MP_RXN<15>")
	)
	(segment
		(start 13.9827 -119.657876)
		(end 13.9827 -117.994176)
		(width 0.1143)
		(layer "B.Cu")
		(net "P3E_CPU1_PE3_MP_RXN<15>")
	)
	(segment
		(start 135.602218 -90.384122)
		(end 135.607044 -90.375486)
		(width 0.0889)
		(layer "B.Cu")
		(net "P3E_CPU1_PE3_MP_RXN<15>")
	)
	(segment
		(start 135.602218 -92.365322)
		(end 135.607044 -92.356686)
		(width 0.0889)
		(layer "B.Cu")
		(net "P3E_CPU1_PE3_MP_RXN<15>")
	)
	(segment
		(start 130.543554 -122.299222)
		(end 122.723402 -123.863608)
		(width 0.1143)
		(layer "B.Cu")
		(net "P3E_CPU1_PE3_MP_RXN<15>")
	)
	(segment
		(start 122.723402 -123.863608)
		(end 117.542818 -122.827034)
		(width 0.1143)
		(layer "B.Cu")
		(net "P3E_CPU1_PE3_MP_RXN<15>")
	)
	(segment
		(start 137.48004 -104.11079)
		(end 137.45464 -104.08539)
		(width 0.0889)
		(layer "B.Cu")
		(net "P3E_CPU1_PE3_MP_RXN<15>")
	)
	(segment
		(start 7.479792 -114.09934)
		(end 5.269484 -114.09934)
		(width 0.1143)
		(layer "B.Cu")
		(net "P3E_CPU1_PE3_MP_RXN<15>")
	)
	(segment
		(start 136.465564 -97.214436)
		(end 136.460738 -97.2058)
		(width 0.0889)
		(layer "B.Cu")
		(net "P3E_CPU1_PE3_MP_RXN<15>")
	)
	(segment
		(start 135.581898 -89.43721)
		(end 135.660638 -89.415874)
		(width 0.0889)
		(layer "B.Cu")
		(net "P3E_CPU1_PE3_MP_RXN<15>")
	)
	(segment
		(start 136.465564 -94.242636)
		(end 136.460738 -94.234)
		(width 0.0889)
		(layer "B.Cu")
		(net "P3E_CPU1_PE3_MP_RXN<15>")
	)
	(segment
		(start 135.660638 -89.415874)
		(end 135.953754 -89.584784)
		(width 0.0889)
		(layer "B.Cu")
		(net "P3E_CPU1_PE3_MP_RXN<15>")
	)
	(segment
		(start 101.475032 -122.812048)
		(end 96.93148 -123.72086)
		(width 0.1143)
		(layer "B.Cu")
		(net "P3E_CPU1_PE3_MP_RXN<15>")
	)
	(segment
		(start 136.465564 -96.223836)
		(end 136.460738 -96.2152)
		(width 0.0889)
		(layer "B.Cu")
		(net "P3E_CPU1_PE3_MP_RXN<15>")
	)
	(segment
		(start 27.315922 -125.6792)
		(end 19.744436 -122.543316)
		(width 0.1143)
		(layer "B.Cu")
		(net "P3E_CPU1_PE3_MP_RXN<15>")
	)
	(segment
		(start 135.607044 -91.366086)
		(end 135.613394 -91.355418)
		(width 0.0889)
		(layer "B.Cu")
		(net "P3E_CPU1_PE3_MP_RXN<15>")
	)
	(segment
		(start 135.607044 -92.356686)
		(end 135.613394 -92.346018)
		(width 0.0889)
		(layer "B.Cu")
		(net "P3E_CPU1_PE3_MP_RXN<15>")
	)
	(segment
		(start 137.48004 -109.08538)
		(end 137.48004 -115.362736)
		(width 0.1143)
		(layer "B.Cu")
		(net "P3E_CPU1_PE3_MP_RXN<15>")
	)
	(segment
		(start 136.471914 -98.215704)
		(end 136.465564 -98.205036)
		(width 0.0889)
		(layer "B.Cu")
		(net "P3E_CPU1_PE3_MP_RXN<15>")
	)
	(segment
		(start 13.9827 -117.994176)
		(end 11.932666 -115.944142)
		(width 0.1143)
		(layer "B.Cu")
		(net "P3E_CPU1_PE3_MP_RXN<15>")
	)
	(segment
		(start 137.48004 -109.08538)
		(end 137.48004 -104.132888)
		(width 0.1143)
		(layer "B.Cu")
		(net "P3E_CPU1_PE3_MP_RXN<15>")
	)
	(segment
		(start 137.5537 -102.258114)
		(end 137.45464 -102.159054)
		(width 0.0889)
		(layer "B.Cu")
		(net "P3E_CPU1_PE3_MP_RXN<15>")
	)
	(segment
		(start 135.971534 -92.956634)
		(end 135.938768 -92.956634)
		(width 0.0889)
		(layer "B.Cu")
		(net "P3E_CPU1_PE3_MP_RXN<15>")
	)
	(segment
		(start 136.471914 -97.225104)
		(end 136.465564 -97.214436)
		(width 0.0889)
		(layer "B.Cu")
		(net "P3E_CPU1_PE3_MP_RXN<15>")
	)
	(segment
		(start 4.304284 -113.13414)
		(end 3.79857 -113.13414)
		(width 0.1143)
		(layer "B.Cu")
		(net "P3E_CPU1_PE3_MP_RXN<15>")
	)
	(segment
		(start 136.465564 -98.205036)
		(end 136.460738 -98.1964)
		(width 0.0889)
		(layer "B.Cu")
		(net "P3E_CPU1_PE3_MP_RXN<15>")
	)
	(segment
		(start 3.79857 -113.13414)
		(end 3.253994 -112.589564)
		(width 0.1143)
		(layer "B.Cu")
		(net "P3E_CPU1_PE3_MP_RXN<15>")
	)
	(segment
		(start 90.432382 -122.421142)
		(end 82.24901 -124.057918)
		(width 0.1143)
		(layer "B.Cu")
		(net "P3E_CPU1_PE3_MP_RXN<15>")
	)
	(segment
		(start 135.607044 -90.375486)
		(end 135.613394 -90.364818)
		(width 0.0889)
		(layer "B.Cu")
		(net "P3E_CPU1_PE3_MP_RXN<15>")
	)
	(segment
		(start 3.253994 -112.589564)
		(end 3.253994 -112.32769)
		(width 0.1143)
		(layer "B.Cu")
		(net "P3E_CPU1_PE3_MP_RXN<15>")
	)
	(segment
		(start 109.54639 -124.426218)
		(end 101.475032 -122.812048)
		(width 0.1143)
		(layer "B.Cu")
		(net "P3E_CPU1_PE3_MP_RXN<15>")
	)
	(segment
		(start 137.48004 -104.132888)
		(end 137.48004 -104.11079)
		(width 0.0889)
		(layer "B.Cu")
		(net "P3E_CPU1_PE3_MP_RXN<15>")
	)
	(segment
		(start 11.932666 -115.944142)
		(end 7.479792 -114.09934)
		(width 0.1143)
		(layer "B.Cu")
		(net "P3E_CPU1_PE3_MP_RXN<15>")
	)
	(segment
		(start 137.45464 -102.159054)
		(end 137.45464 -101.195124)
		(width 0.0889)
		(layer "B.Cu")
		(net "P3E_CPU1_PE3_MP_RXN<15>")
	)
	(segment
		(start 5.269484 -114.09934)
		(end 4.304284 -113.13414)
		(width 0.1143)
		(layer "B.Cu")
		(net "P3E_CPU1_PE3_MP_RXN<15>")
	)
	(segment
		(start 136.465564 -94.833186)
		(end 136.471914 -94.822518)
		(width 0.0889)
		(layer "B.Cu")
		(net "P3E_CPU1_PE3_MP_RXN<15>")
	)
	(segment
		(start 137.45464 -104.08539)
		(end 137.45464 -102.534974)
		(width 0.0889)
		(layer "B.Cu")
		(net "P3E_CPU1_PE3_MP_RXN<15>")
	)
	(segment
		(start 96.93148 -123.72086)
		(end 90.432382 -122.421142)
		(width 0.1143)
		(layer "B.Cu")
		(net "P3E_CPU1_PE3_MP_RXN<15>")
	)
	(segment
		(start 135.602218 -91.374722)
		(end 135.607044 -91.366086)
		(width 0.0889)
		(layer "B.Cu")
		(net "P3E_CPU1_PE3_MP_RXN<15>")
	)
	(segment
		(start 136.472168 -99.20732)
		(end 136.460738 -99.187)
		(width 0.0889)
		(layer "B.Cu")
		(net "P3E_CPU1_PE3_MP_RXN<15>")
	)
	(segment
		(start 73.872852 -122.382534)
		(end 64.657224 -124.225304)
		(width 0.1143)
		(layer "B.Cu")
		(net "P3E_CPU1_PE3_MP_RXN<15>")
	)
	(segment
		(start 3.139694 -112.21339)
		(end 2.739644 -112.21339)
		(width 0.1143)
		(layer "B.Cu")
		(net "P3E_CPU1_PE3_MP_RXN<15>")
	)
	(segment
		(start 19.744436 -122.543316)
		(end 17.488662 -122.543316)
		(width 0.1143)
		(layer "B.Cu")
		(net "P3E_CPU1_PE3_MP_RXN<15>")
	)
	(segment
		(start 17.488662 -122.543316)
		(end 16.425418 -122.100594)
		(width 0.1143)
		(layer "B.Cu")
		(net "P3E_CPU1_PE3_MP_RXN<15>")
	)
	(segment
		(start 82.24901 -124.057918)
		(end 73.872852 -122.382534)
		(width 0.1143)
		(layer "B.Cu")
		(net "P3E_CPU1_PE3_MP_RXN<15>")
	)
	(segment
		(start 117.542818 -122.827034)
		(end 109.54639 -124.426218)
		(width 0.1143)
		(layer "B.Cu")
		(net "P3E_CPU1_PE3_MP_RXN<15>")
	)
	(arc
		(start 136.465564 -99.786186)
		(mid 136.471121 -99.776333)
		(end 136.476486 -99.766374)
		(width 0.0889)
		(layer "B.Cu")
		(net "P3E_CPU1_PE3_MP_RXN<15>")
	)
	(arc
		(start 136.529064 -100.269548)
		(mid 136.504698 -100.242776)
		(end 136.482836 -100.213922)
		(width 0.0889)
		(layer "B.Cu")
		(net "P3E_CPU1_PE3_MP_RXN<15>")
	)
	(arc
		(start 136.465564 -95.232982)
		(mid 136.412065 -95.033084)
		(end 136.465564 -94.833186)
		(width 0.0889)
		(layer "B.Cu")
		(net "P3E_CPU1_PE3_MP_RXN<15>")
	)
	(arc
		(start 136.465564 -96.814386)
		(mid 136.544786 -96.525268)
		(end 136.471914 -96.234504)
		(width 0.0889)
		(layer "B.Cu")
		(net "P3E_CPU1_PE3_MP_RXN<15>")
	)
	(arc
		(start 136.465564 -97.804986)
		(mid 136.544786 -97.515868)
		(end 136.471914 -97.225104)
		(width 0.0889)
		(layer "B.Cu")
		(net "P3E_CPU1_PE3_MP_RXN<15>")
	)
	(arc
		(start 135.613394 -92.346018)
		(mid 135.686192 -92.055255)
		(end 135.607044 -91.766136)
		(width 0.0889)
		(layer "B.Cu")
		(net "P3E_CPU1_PE3_MP_RXN<15>")
	)
	(arc
		(start 135.613394 -91.355418)
		(mid 135.686192 -91.064655)
		(end 135.607044 -90.775536)
		(width 0.0889)
		(layer "B.Cu")
		(net "P3E_CPU1_PE3_MP_RXN<15>")
	)
	(arc
		(start 135.607044 -90.775536)
		(mid 135.553574 -90.580473)
		(end 135.602218 -90.384122)
		(width 0.0889)
		(layer "B.Cu")
		(net "P3E_CPU1_PE3_MP_RXN<15>")
	)
	(arc
		(start 136.482836 -100.213922)
		(mid 136.47187 -100.197167)
		(end 136.461754 -100.179886)
		(width 0.0889)
		(layer "B.Cu")
		(net "P3E_CPU1_PE3_MP_RXN<15>")
	)
	(arc
		(start 135.607044 -91.766136)
		(mid 135.553574 -91.571073)
		(end 135.602218 -91.374722)
		(width 0.0889)
		(layer "B.Cu")
		(net "P3E_CPU1_PE3_MP_RXN<15>")
	)
	(arc
		(start 135.613394 -90.364818)
		(mid 135.686192 -90.074055)
		(end 135.607044 -89.784936)
		(width 0.0889)
		(layer "B.Cu")
		(net "P3E_CPU1_PE3_MP_RXN<15>")
	)
	(arc
		(start 136.465564 -98.795586)
		(mid 136.544786 -98.506468)
		(end 136.471914 -98.215704)
		(width 0.0889)
		(layer "B.Cu")
		(net "P3E_CPU1_PE3_MP_RXN<15>")
	)
	(arc
		(start 136.460738 -99.187)
		(mid 136.411983 -98.990648)
		(end 136.465564 -98.795586)
		(width 0.0889)
		(layer "B.Cu")
		(net "P3E_CPU1_PE3_MP_RXN<15>")
	)
	(arc
		(start 136.465564 -95.823786)
		(mid 136.544695 -95.528384)
		(end 136.465564 -95.232982)
		(width 0.0889)
		(layer "B.Cu")
		(net "P3E_CPU1_PE3_MP_RXN<15>")
	)
	(arc
		(start 136.476486 -99.766374)
		(mid 136.544667 -99.486294)
		(end 136.472168 -99.20732)
		(width 0.0889)
		(layer "B.Cu")
		(net "P3E_CPU1_PE3_MP_RXN<15>")
	)
	(arc
		(start 136.461754 -100.179886)
		(mid 136.411884 -99.982699)
		(end 136.46531 -99.78644)
		(width 0.0889)
		(layer "B.Cu")
		(net "P3E_CPU1_PE3_MP_RXN<15>")
	)
	(arc
		(start 136.465564 -93.842586)
		(mid 136.469893 -93.259414)
		(end 135.971534 -92.956634)
		(width 0.0889)
		(layer "B.Cu")
		(net "P3E_CPU1_PE3_MP_RXN<15>")
	)
	(arc
		(start 136.471914 -94.822518)
		(mid 136.544712 -94.531755)
		(end 136.465564 -94.242636)
		(width 0.0889)
		(layer "B.Cu")
		(net "P3E_CPU1_PE3_MP_RXN<15>")
	)
	(arc
		(start 136.460738 -98.1964)
		(mid 136.411983 -98.000048)
		(end 136.465564 -97.804986)
		(width 0.0889)
		(layer "B.Cu")
		(net "P3E_CPU1_PE3_MP_RXN<15>")
	)
	(arc
		(start 135.607044 -89.784936)
		(mid 135.554624 -89.613951)
		(end 135.581898 -89.43721)
		(width 0.0889)
		(layer "B.Cu")
		(net "P3E_CPU1_PE3_MP_RXN<15>")
	)
	(arc
		(start 136.460738 -96.2152)
		(mid 136.411983 -96.018848)
		(end 136.465564 -95.823786)
		(width 0.0889)
		(layer "B.Cu")
		(net "P3E_CPU1_PE3_MP_RXN<15>")
	)
	(arc
		(start 136.46531 -99.786694)
		(mid 136.465437 -99.78644)
		(end 136.465564 -99.786186)
		(width 0.0889)
		(layer "B.Cu")
		(net "P3E_CPU1_PE3_MP_RXN<15>")
	)
	(arc
		(start 136.460738 -94.234)
		(mid 136.411983 -94.037648)
		(end 136.465564 -93.842586)
		(width 0.0889)
		(layer "B.Cu")
		(net "P3E_CPU1_PE3_MP_RXN<15>")
	)
	(arc
		(start 136.460738 -97.2058)
		(mid 136.411983 -97.009448)
		(end 136.465564 -96.814386)
		(width 0.0889)
		(layer "B.Cu")
		(net "P3E_CPU1_PE3_MP_RXN<15>")
	)
	(arc
		(start 135.938768 -92.956634)
		(mid 135.60585 -92.754643)
		(end 135.602218 -92.365322)
		(width 0.0889)
		(layer "B.Cu")
		(net "P3E_CPU1_PE3_MP_RXN<15>")
	)
	(segment
		(start 3.572256 -111.36122)
		(end 4.55168 -111.36122)
		(width 0.1143)
		(layer "In4.Cu")
		(net "P3E_CPU1_PE3_MP_RXN<15>")
	)
	(segment
		(start 0.853948 -101.483922)
		(end 0.853948 -100.884228)
		(width 0.1143)
		(layer "In4.Cu")
		(net "P3E_CPU1_PE3_MP_RXN<15>")
	)
	(segment
		(start 0.853948 -100.884228)
		(end 0.739648 -100.769928)
		(width 0.1143)
		(layer "In4.Cu")
		(net "P3E_CPU1_PE3_MP_RXN<15>")
	)
	(segment
		(start 8.66521 -101.921056)
		(end 1.291082 -101.921056)
		(width 0.1143)
		(layer "In4.Cu")
		(net "P3E_CPU1_PE3_MP_RXN<15>")
	)
	(segment
		(start 2.739644 -112.21339)
		(end 3.114294 -112.21339)
		(width 0.1143)
		(layer "In4.Cu")
		(net "P3E_CPU1_PE3_MP_RXN<15>")
	)
	(segment
		(start 1.291082 -101.921056)
		(end 0.853948 -101.483922)
		(width 0.1143)
		(layer "In4.Cu")
		(net "P3E_CPU1_PE3_MP_RXN<15>")
	)
	(segment
		(start 0.739648 -100.769928)
		(end 0.299974 -100.769928)
		(width 0.1143)
		(layer "In4.Cu")
		(net "P3E_CPU1_PE3_MP_RXN<15>")
	)
	(segment
		(start 4.55168 -111.36122)
		(end 4.85648 -111.05642)
		(width 0.1143)
		(layer "In4.Cu")
		(net "P3E_CPU1_PE3_MP_RXN<15>")
	)
	(segment
		(start 6.133084 -107.973622)
		(end 9.1948 -104.911906)
		(width 0.1143)
		(layer "In4.Cu")
		(net "P3E_CPU1_PE3_MP_RXN<15>")
	)
	(segment
		(start 9.1948 -102.450646)
		(end 8.66521 -101.921056)
		(width 0.1143)
		(layer "In4.Cu")
		(net "P3E_CPU1_PE3_MP_RXN<15>")
	)
	(segment
		(start 3.228594 -111.704882)
		(end 3.572256 -111.36122)
		(width 0.1143)
		(layer "In4.Cu")
		(net "P3E_CPU1_PE3_MP_RXN<15>")
	)
	(segment
		(start 3.228594 -112.09909)
		(end 3.228594 -111.704882)
		(width 0.1143)
		(layer "In4.Cu")
		(net "P3E_CPU1_PE3_MP_RXN<15>")
	)
	(segment
		(start 9.1948 -104.911906)
		(end 9.1948 -102.450646)
		(width 0.1143)
		(layer "In4.Cu")
		(net "P3E_CPU1_PE3_MP_RXN<15>")
	)
	(segment
		(start 4.85648 -111.05642)
		(end 6.133084 -107.973622)
		(width 0.1143)
		(layer "In4.Cu")
		(net "P3E_CPU1_PE3_MP_RXN<15>")
	)
	(segment
		(start 3.114294 -112.21339)
		(end 3.228594 -112.09909)
		(width 0.1143)
		(layer "In4.Cu")
		(net "P3E_CPU1_PE3_MP_RXN<15>")
	)
	(segment
		(start 133.665214 -90.575384)
		(end 134.236714 -90.575384)
		(width 0.1143)
		(layer "F.Cu")
		(net "P3E_CPU1_PE3_MP_RXN<14>")
	)
	(via
		(at 6.209538 -111.595916)
		(size 0.508)
		(drill 0.254)
		(layers "F.Cu" "B.Cu")
		(net "P3E_CPU1_PE3_MP_RXN<14>")
	)
	(via
		(at 134.236714 -90.575384)
		(size 0.508)
		(drill 0.254)
		(layers "F.Cu" "B.Cu")
		(net "P3E_CPU1_PE3_MP_RXN<14>")
	)
	(segment
		(start 135.441944 -97.214436)
		(end 135.435594 -97.225104)
		(width 0.0889)
		(layer "B.Cu")
		(net "P3E_CPU1_PE3_MP_RXN<14>")
	)
	(segment
		(start 82.080354 -122.743214)
		(end 73.925938 -121.112534)
		(width 0.1143)
		(layer "B.Cu")
		(net "P3E_CPU1_PE3_MP_RXN<14>")
	)
	(segment
		(start 135.441944 -96.223836)
		(end 135.435594 -96.234504)
		(width 0.0889)
		(layer "B.Cu")
		(net "P3E_CPU1_PE3_MP_RXN<14>")
	)
	(segment
		(start 134.583424 -91.366086)
		(end 134.58825 -91.374722)
		(width 0.0889)
		(layer "B.Cu")
		(net "P3E_CPU1_PE3_MP_RXN<14>")
	)
	(segment
		(start 96.962214 -122.45467)
		(end 90.242644 -121.110756)
		(width 0.1143)
		(layer "B.Cu")
		(net "P3E_CPU1_PE3_MP_RXN<14>")
	)
	(segment
		(start 64.753998 -122.946668)
		(end 62.56782 -122.509534)
		(width 0.1143)
		(layer "B.Cu")
		(net "P3E_CPU1_PE3_MP_RXN<14>")
	)
	(segment
		(start 135.720582 -104.574848)
		(end 135.720582 -104.752648)
		(width 0.0889)
		(layer "B.Cu")
		(net "P3E_CPU1_PE3_MP_RXN<14>")
	)
	(segment
		(start 135.819642 -105.405428)
		(end 135.819642 -105.934256)
		(width 0.0889)
		(layer "B.Cu")
		(net "P3E_CPU1_PE3_MP_RXN<14>")
	)
	(segment
		(start 6.937502 -112.110266)
		(end 6.323838 -112.110266)
		(width 0.1143)
		(layer "B.Cu")
		(net "P3E_CPU1_PE3_MP_RXN<14>")
	)
	(segment
		(start 134.577074 -92.346018)
		(end 134.583424 -92.356686)
		(width 0.0889)
		(layer "B.Cu")
		(net "P3E_CPU1_PE3_MP_RXN<14>")
	)
	(segment
		(start 135.819642 -105.029508)
		(end 135.720582 -105.128568)
		(width 0.0889)
		(layer "B.Cu")
		(net "P3E_CPU1_PE3_MP_RXN<14>")
	)
	(segment
		(start 135.44677 -96.2152)
		(end 135.441944 -96.223836)
		(width 0.0889)
		(layer "B.Cu")
		(net "P3E_CPU1_PE3_MP_RXN<14>")
	)
	(segment
		(start 6.323838 -112.110266)
		(end 6.209538 -111.995966)
		(width 0.1143)
		(layer "B.Cu")
		(net "P3E_CPU1_PE3_MP_RXN<14>")
	)
	(segment
		(start 109.231684 -122.919744)
		(end 101.934264 -121.46026)
		(width 0.1143)
		(layer "B.Cu")
		(net "P3E_CPU1_PE3_MP_RXN<14>")
	)
	(segment
		(start 6.209538 -111.995966)
		(end 6.209538 -111.595916)
		(width 0.1143)
		(layer "B.Cu")
		(net "P3E_CPU1_PE3_MP_RXN<14>")
	)
	(segment
		(start 73.925938 -121.112534)
		(end 64.753998 -122.946668)
		(width 0.1143)
		(layer "B.Cu")
		(net "P3E_CPU1_PE3_MP_RXN<14>")
	)
	(segment
		(start 135.819642 -105.934256)
		(end 135.794242 -105.959656)
		(width 0.0889)
		(layer "B.Cu")
		(net "P3E_CPU1_PE3_MP_RXN<14>")
	)
	(segment
		(start 101.934264 -121.46026)
		(end 96.962214 -122.45467)
		(width 0.1143)
		(layer "B.Cu")
		(net "P3E_CPU1_PE3_MP_RXN<14>")
	)
	(segment
		(start 135.441944 -102.757986)
		(end 135.819642 -103.41229)
		(width 0.0889)
		(layer "B.Cu")
		(net "P3E_CPU1_PE3_MP_RXN<14>")
	)
	(segment
		(start 134.583424 -92.356686)
		(end 134.58825 -92.365322)
		(width 0.0889)
		(layer "B.Cu")
		(net "P3E_CPU1_PE3_MP_RXN<14>")
	)
	(segment
		(start 135.435594 -94.822518)
		(end 135.441944 -94.833186)
		(width 0.0889)
		(layer "B.Cu")
		(net "P3E_CPU1_PE3_MP_RXN<14>")
	)
	(segment
		(start 135.819642 -104.475788)
		(end 135.720582 -104.574848)
		(width 0.0889)
		(layer "B.Cu")
		(net "P3E_CPU1_PE3_MP_RXN<14>")
	)
	(segment
		(start 135.819642 -104.851708)
		(end 135.819642 -105.029508)
		(width 0.0889)
		(layer "B.Cu")
		(net "P3E_CPU1_PE3_MP_RXN<14>")
	)
	(segment
		(start 135.720582 -105.128568)
		(end 135.720582 -105.306368)
		(width 0.0889)
		(layer "B.Cu")
		(net "P3E_CPU1_PE3_MP_RXN<14>")
	)
	(segment
		(start 135.441944 -99.195636)
		(end 135.435594 -99.206304)
		(width 0.0889)
		(layer "B.Cu")
		(net "P3E_CPU1_PE3_MP_RXN<14>")
	)
	(segment
		(start 135.720582 -104.752648)
		(end 135.819642 -104.851708)
		(width 0.0889)
		(layer "B.Cu")
		(net "P3E_CPU1_PE3_MP_RXN<14>")
	)
	(segment
		(start 134.52983 -90.406474)
		(end 134.60857 -90.42781)
		(width 0.0889)
		(layer "B.Cu")
		(net "P3E_CPU1_PE3_MP_RXN<14>")
	)
	(segment
		(start 36.13912 -124.46)
		(end 27.529028 -124.46)
		(width 0.1143)
		(layer "B.Cu")
		(net "P3E_CPU1_PE3_MP_RXN<14>")
	)
	(segment
		(start 134.236714 -90.575384)
		(end 134.52983 -90.406474)
		(width 0.0889)
		(layer "B.Cu")
		(net "P3E_CPU1_PE3_MP_RXN<14>")
	)
	(segment
		(start 135.435594 -100.766118)
		(end 135.441944 -100.776786)
		(width 0.0889)
		(layer "B.Cu")
		(net "P3E_CPU1_PE3_MP_RXN<14>")
	)
	(segment
		(start 60.381388 -122.072146)
		(end 36.13912 -124.46)
		(width 0.1143)
		(layer "B.Cu")
		(net "P3E_CPU1_PE3_MP_RXN<14>")
	)
	(segment
		(start 90.242644 -121.110756)
		(end 82.080354 -122.743214)
		(width 0.1143)
		(layer "B.Cu")
		(net "P3E_CPU1_PE3_MP_RXN<14>")
	)
	(segment
		(start 135.44677 -100.1776)
		(end 135.441944 -100.186236)
		(width 0.0889)
		(layer "B.Cu")
		(net "P3E_CPU1_PE3_MP_RXN<14>")
	)
	(segment
		(start 135.44677 -97.2058)
		(end 135.441944 -97.214436)
		(width 0.0889)
		(layer "B.Cu")
		(net "P3E_CPU1_PE3_MP_RXN<14>")
	)
	(segment
		(start 135.794242 -105.981754)
		(end 135.794242 -115.335304)
		(width 0.1143)
		(layer "B.Cu")
		(net "P3E_CPU1_PE3_MP_RXN<14>")
	)
	(segment
		(start 117.09527 -121.34723)
		(end 109.231684 -122.919744)
		(width 0.1143)
		(layer "B.Cu")
		(net "P3E_CPU1_PE3_MP_RXN<14>")
	)
	(segment
		(start 27.529028 -124.46)
		(end 20.930616 -121.726452)
		(width 0.1143)
		(layer "B.Cu")
		(net "P3E_CPU1_PE3_MP_RXN<14>")
	)
	(segment
		(start 62.56782 -122.509534)
		(end 60.381388 -122.072146)
		(width 0.1143)
		(layer "B.Cu")
		(net "P3E_CPU1_PE3_MP_RXN<14>")
	)
	(segment
		(start 130.2893 -120.840246)
		(end 122.42673 -122.413522)
		(width 0.1143)
		(layer "B.Cu")
		(net "P3E_CPU1_PE3_MP_RXN<14>")
	)
	(segment
		(start 135.44677 -98.1964)
		(end 135.441944 -98.205036)
		(width 0.0889)
		(layer "B.Cu")
		(net "P3E_CPU1_PE3_MP_RXN<14>")
	)
	(segment
		(start 15.132304 -115.92814)
		(end 7.659624 -112.832388)
		(width 0.1143)
		(layer "B.Cu")
		(net "P3E_CPU1_PE3_MP_RXN<14>")
	)
	(segment
		(start 20.930616 -121.726452)
		(end 15.132304 -115.92814)
		(width 0.1143)
		(layer "B.Cu")
		(net "P3E_CPU1_PE3_MP_RXN<14>")
	)
	(segment
		(start 135.794242 -115.335304)
		(end 130.2893 -120.840246)
		(width 0.1143)
		(layer "B.Cu")
		(net "P3E_CPU1_PE3_MP_RXN<14>")
	)
	(segment
		(start 134.577074 -91.355418)
		(end 134.583424 -91.366086)
		(width 0.0889)
		(layer "B.Cu")
		(net "P3E_CPU1_PE3_MP_RXN<14>")
	)
	(segment
		(start 7.659624 -112.832388)
		(end 6.937502 -112.110266)
		(width 0.1143)
		(layer "B.Cu")
		(net "P3E_CPU1_PE3_MP_RXN<14>")
	)
	(segment
		(start 135.819642 -103.41229)
		(end 135.819642 -104.475788)
		(width 0.0889)
		(layer "B.Cu")
		(net "P3E_CPU1_PE3_MP_RXN<14>")
	)
	(segment
		(start 135.44677 -94.234)
		(end 135.441944 -94.242636)
		(width 0.0889)
		(layer "B.Cu")
		(net "P3E_CPU1_PE3_MP_RXN<14>")
	)
	(segment
		(start 122.42673 -122.413522)
		(end 117.09527 -121.34723)
		(width 0.1143)
		(layer "B.Cu")
		(net "P3E_CPU1_PE3_MP_RXN<14>")
	)
	(segment
		(start 135.794242 -105.959656)
		(end 135.794242 -105.981754)
		(width 0.0889)
		(layer "B.Cu")
		(net "P3E_CPU1_PE3_MP_RXN<14>")
	)
	(segment
		(start 135.44677 -99.187)
		(end 135.441944 -99.195636)
		(width 0.0889)
		(layer "B.Cu")
		(net "P3E_CPU1_PE3_MP_RXN<14>")
	)
	(segment
		(start 135.720582 -105.306368)
		(end 135.819642 -105.405428)
		(width 0.0889)
		(layer "B.Cu")
		(net "P3E_CPU1_PE3_MP_RXN<14>")
	)
	(segment
		(start 135.441944 -98.205036)
		(end 135.435594 -98.215704)
		(width 0.0889)
		(layer "B.Cu")
		(net "P3E_CPU1_PE3_MP_RXN<14>")
	)
	(segment
		(start 135.077454 -93.642688)
		(end 135.11022 -93.642688)
		(width 0.0889)
		(layer "B.Cu")
		(net "P3E_CPU1_PE3_MP_RXN<14>")
	)
	(arc
		(start 135.441944 -100.776786)
		(mid 135.495443 -100.976684)
		(end 135.441944 -101.176582)
		(width 0.0889)
		(layer "B.Cu")
		(net "P3E_CPU1_PE3_MP_RXN<14>")
	)
	(arc
		(start 135.441944 -97.804986)
		(mid 135.495414 -98.000049)
		(end 135.44677 -98.1964)
		(width 0.0889)
		(layer "B.Cu")
		(net "P3E_CPU1_PE3_MP_RXN<14>")
	)
	(arc
		(start 135.441944 -99.786186)
		(mid 135.495414 -99.981249)
		(end 135.44677 -100.1776)
		(width 0.0889)
		(layer "B.Cu")
		(net "P3E_CPU1_PE3_MP_RXN<14>")
	)
	(arc
		(start 134.583424 -90.775536)
		(mid 134.504202 -91.064654)
		(end 134.577074 -91.355418)
		(width 0.0889)
		(layer "B.Cu")
		(net "P3E_CPU1_PE3_MP_RXN<14>")
	)
	(arc
		(start 135.435594 -99.206304)
		(mid 135.362796 -99.497067)
		(end 135.441944 -99.786186)
		(width 0.0889)
		(layer "B.Cu")
		(net "P3E_CPU1_PE3_MP_RXN<14>")
	)
	(arc
		(start 135.11022 -93.642688)
		(mid 135.443138 -93.844679)
		(end 135.44677 -94.234)
		(width 0.0889)
		(layer "B.Cu")
		(net "P3E_CPU1_PE3_MP_RXN<14>")
	)
	(arc
		(start 134.60857 -90.42781)
		(mid 134.635813 -90.604549)
		(end 134.583424 -90.775536)
		(width 0.0889)
		(layer "B.Cu")
		(net "P3E_CPU1_PE3_MP_RXN<14>")
	)
	(arc
		(start 135.441944 -94.242636)
		(mid 135.362722 -94.531754)
		(end 135.435594 -94.822518)
		(width 0.0889)
		(layer "B.Cu")
		(net "P3E_CPU1_PE3_MP_RXN<14>")
	)
	(arc
		(start 135.435594 -98.215704)
		(mid 135.362796 -98.506467)
		(end 135.441944 -98.795586)
		(width 0.0889)
		(layer "B.Cu")
		(net "P3E_CPU1_PE3_MP_RXN<14>")
	)
	(arc
		(start 134.583424 -91.766136)
		(mid 134.504202 -92.055254)
		(end 134.577074 -92.346018)
		(width 0.0889)
		(layer "B.Cu")
		(net "P3E_CPU1_PE3_MP_RXN<14>")
	)
	(arc
		(start 135.441944 -95.823786)
		(mid 135.495414 -96.018849)
		(end 135.44677 -96.2152)
		(width 0.0889)
		(layer "B.Cu")
		(net "P3E_CPU1_PE3_MP_RXN<14>")
	)
	(arc
		(start 135.441944 -101.767386)
		(mid 135.49557 -101.967538)
		(end 135.441944 -102.16769)
		(width 0.0889)
		(layer "B.Cu")
		(net "P3E_CPU1_PE3_MP_RXN<14>")
	)
	(arc
		(start 135.441944 -100.186236)
		(mid 135.362722 -100.475354)
		(end 135.435594 -100.766118)
		(width 0.0889)
		(layer "B.Cu")
		(net "P3E_CPU1_PE3_MP_RXN<14>")
	)
	(arc
		(start 135.441944 -98.795586)
		(mid 135.495414 -98.990649)
		(end 135.44677 -99.187)
		(width 0.0889)
		(layer "B.Cu")
		(net "P3E_CPU1_PE3_MP_RXN<14>")
	)
	(arc
		(start 134.58825 -92.365322)
		(mid 134.637005 -92.561674)
		(end 134.583424 -92.756736)
		(width 0.0889)
		(layer "B.Cu")
		(net "P3E_CPU1_PE3_MP_RXN<14>")
	)
	(arc
		(start 135.441944 -94.833186)
		(mid 135.495443 -95.033084)
		(end 135.441944 -95.232982)
		(width 0.0889)
		(layer "B.Cu")
		(net "P3E_CPU1_PE3_MP_RXN<14>")
	)
	(arc
		(start 135.441944 -101.176582)
		(mid 135.362813 -101.471984)
		(end 135.441944 -101.767386)
		(width 0.0889)
		(layer "B.Cu")
		(net "P3E_CPU1_PE3_MP_RXN<14>")
	)
	(arc
		(start 135.441944 -96.814386)
		(mid 135.495414 -97.009449)
		(end 135.44677 -97.2058)
		(width 0.0889)
		(layer "B.Cu")
		(net "P3E_CPU1_PE3_MP_RXN<14>")
	)
	(arc
		(start 134.58825 -91.374722)
		(mid 134.637005 -91.571074)
		(end 134.583424 -91.766136)
		(width 0.0889)
		(layer "B.Cu")
		(net "P3E_CPU1_PE3_MP_RXN<14>")
	)
	(arc
		(start 134.583424 -92.756736)
		(mid 134.579095 -93.339908)
		(end 135.077454 -93.642688)
		(width 0.0889)
		(layer "B.Cu")
		(net "P3E_CPU1_PE3_MP_RXN<14>")
	)
	(arc
		(start 135.441944 -95.232982)
		(mid 135.362813 -95.528384)
		(end 135.441944 -95.823786)
		(width 0.0889)
		(layer "B.Cu")
		(net "P3E_CPU1_PE3_MP_RXN<14>")
	)
	(arc
		(start 135.435594 -96.234504)
		(mid 135.362796 -96.525267)
		(end 135.441944 -96.814386)
		(width 0.0889)
		(layer "B.Cu")
		(net "P3E_CPU1_PE3_MP_RXN<14>")
	)
	(arc
		(start 135.441944 -102.16769)
		(mid 135.362871 -102.462838)
		(end 135.441944 -102.757986)
		(width 0.0889)
		(layer "B.Cu")
		(net "P3E_CPU1_PE3_MP_RXN<14>")
	)
	(arc
		(start 135.435594 -97.225104)
		(mid 135.362796 -97.515867)
		(end 135.441944 -97.804986)
		(width 0.0889)
		(layer "B.Cu")
		(net "P3E_CPU1_PE3_MP_RXN<14>")
	)
	(segment
		(start 7.15264 -109.731302)
		(end 7.15264 -110.074202)
		(width 0.1143)
		(layer "In4.Cu")
		(net "P3E_CPU1_PE3_MP_RXN<14>")
	)
	(segment
		(start 6.209538 -112.028986)
		(end 6.209538 -111.595916)
		(width 0.1143)
		(layer "In4.Cu")
		(net "P3E_CPU1_PE3_MP_RXN<14>")
	)
	(segment
		(start 8.70204 -106.589576)
		(end 8.45947 -106.832146)
		(width 0.1143)
		(layer "In4.Cu")
		(net "P3E_CPU1_PE3_MP_RXN<14>")
	)
	(segment
		(start 7.31774 -108.550202)
		(end 7.15264 -108.715302)
		(width 0.1143)
		(layer "In4.Cu")
		(net "P3E_CPU1_PE3_MP_RXN<14>")
	)
	(segment
		(start 9.896348 -105.628694)
		(end 9.653778 -105.871264)
		(width 0.1143)
		(layer "In4.Cu")
		(net "P3E_CPU1_PE3_MP_RXN<14>")
	)
	(segment
		(start 7.15264 -110.747302)
		(end 7.15264 -111.090202)
		(width 0.1143)
		(layer "In4.Cu")
		(net "P3E_CPU1_PE3_MP_RXN<14>")
	)
	(segment
		(start 8.242046 -100.16363)
		(end 8.242046 -100.397056)
		(width 0.1143)
		(layer "In4.Cu")
		(net "P3E_CPU1_PE3_MP_RXN<14>")
	)
	(segment
		(start 8.935466 -106.589576)
		(end 8.70204 -106.589576)
		(width 0.1143)
		(layer "In4.Cu")
		(net "P3E_CPU1_PE3_MP_RXN<14>")
	)
	(segment
		(start 7.074916 -112.143286)
		(end 6.323838 -112.143286)
		(width 0.1143)
		(layer "In4.Cu")
		(net "P3E_CPU1_PE3_MP_RXN<14>")
	)
	(segment
		(start 8.45947 -107.065572)
		(end 8.2169 -107.308142)
		(width 0.1143)
		(layer "In4.Cu")
		(net "P3E_CPU1_PE3_MP_RXN<14>")
	)
	(segment
		(start 9.202928 -101.357938)
		(end 9.436354 -101.357938)
		(width 0.1143)
		(layer "In4.Cu")
		(net "P3E_CPU1_PE3_MP_RXN<14>")
	)
	(segment
		(start -3.145282 -100.256594)
		(end -2.809748 -99.92106)
		(width 0.1143)
		(layer "In4.Cu")
		(net "P3E_CPU1_PE3_MP_RXN<14>")
	)
	(segment
		(start 7.31774 -110.239302)
		(end 7.31774 -110.582202)
		(width 0.1143)
		(layer "In4.Cu")
		(net "P3E_CPU1_PE3_MP_RXN<14>")
	)
	(segment
		(start 7.31774 -109.223302)
		(end 7.31774 -109.566202)
		(width 0.1143)
		(layer "In4.Cu")
		(net "P3E_CPU1_PE3_MP_RXN<14>")
	)
	(segment
		(start 8.717788 -100.639372)
		(end 8.960358 -100.881942)
		(width 0.1143)
		(layer "In4.Cu")
		(net "P3E_CPU1_PE3_MP_RXN<14>")
	)
	(segment
		(start -3.030982 -100.769928)
		(end -3.145282 -100.655628)
		(width 0.1143)
		(layer "In4.Cu")
		(net "P3E_CPU1_PE3_MP_RXN<14>")
	)
	(segment
		(start 6.323838 -112.143286)
		(end 6.209538 -112.028986)
		(width 0.1143)
		(layer "In4.Cu")
		(net "P3E_CPU1_PE3_MP_RXN<14>")
	)
	(segment
		(start 8.2169 -107.308142)
		(end 7.983474 -107.308142)
		(width 0.1143)
		(layer "In4.Cu")
		(net "P3E_CPU1_PE3_MP_RXN<14>")
	)
	(segment
		(start 7.741158 -107.550458)
		(end 7.741158 -107.783884)
		(width 0.1143)
		(layer "In4.Cu")
		(net "P3E_CPU1_PE3_MP_RXN<14>")
	)
	(segment
		(start 7.31774 -111.900462)
		(end 7.074916 -112.143286)
		(width 0.1143)
		(layer "In4.Cu")
		(net "P3E_CPU1_PE3_MP_RXN<14>")
	)
	(segment
		(start 8.960358 -100.881942)
		(end 8.960358 -101.115368)
		(width 0.1143)
		(layer "In4.Cu")
		(net "P3E_CPU1_PE3_MP_RXN<14>")
	)
	(segment
		(start 9.178036 -106.347006)
		(end 8.935466 -106.589576)
		(width 0.1143)
		(layer "In4.Cu")
		(net "P3E_CPU1_PE3_MP_RXN<14>")
	)
	(segment
		(start 7.999476 -99.92106)
		(end 8.242046 -100.16363)
		(width 0.1143)
		(layer "In4.Cu")
		(net "P3E_CPU1_PE3_MP_RXN<14>")
	)
	(segment
		(start 7.983474 -107.308142)
		(end 7.741158 -107.550458)
		(width 0.1143)
		(layer "In4.Cu")
		(net "P3E_CPU1_PE3_MP_RXN<14>")
	)
	(segment
		(start 7.31774 -111.255302)
		(end 7.31774 -111.900462)
		(width 0.1143)
		(layer "In4.Cu")
		(net "P3E_CPU1_PE3_MP_RXN<14>")
	)
	(segment
		(start 8.960358 -101.115368)
		(end 9.202928 -101.357938)
		(width 0.1143)
		(layer "In4.Cu")
		(net "P3E_CPU1_PE3_MP_RXN<14>")
	)
	(segment
		(start 9.653778 -105.871264)
		(end 9.420352 -105.871264)
		(width 0.1143)
		(layer "In4.Cu")
		(net "P3E_CPU1_PE3_MP_RXN<14>")
	)
	(segment
		(start 7.15264 -109.058202)
		(end 7.31774 -109.223302)
		(width 0.1143)
		(layer "In4.Cu")
		(net "P3E_CPU1_PE3_MP_RXN<14>")
	)
	(segment
		(start -3.145282 -100.655628)
		(end -3.145282 -100.256594)
		(width 0.1143)
		(layer "In4.Cu")
		(net "P3E_CPU1_PE3_MP_RXN<14>")
	)
	(segment
		(start 7.31774 -109.566202)
		(end 7.15264 -109.731302)
		(width 0.1143)
		(layer "In4.Cu")
		(net "P3E_CPU1_PE3_MP_RXN<14>")
	)
	(segment
		(start 9.436354 -101.357938)
		(end 9.896348 -101.817932)
		(width 0.1143)
		(layer "In4.Cu")
		(net "P3E_CPU1_PE3_MP_RXN<14>")
	)
	(segment
		(start -2.809748 -99.92106)
		(end 7.999476 -99.92106)
		(width 0.1143)
		(layer "In4.Cu")
		(net "P3E_CPU1_PE3_MP_RXN<14>")
	)
	(segment
		(start 7.31774 -108.207302)
		(end 7.31774 -108.550202)
		(width 0.1143)
		(layer "In4.Cu")
		(net "P3E_CPU1_PE3_MP_RXN<14>")
	)
	(segment
		(start 7.15264 -108.715302)
		(end 7.15264 -109.058202)
		(width 0.1143)
		(layer "In4.Cu")
		(net "P3E_CPU1_PE3_MP_RXN<14>")
	)
	(segment
		(start 9.178036 -106.11358)
		(end 9.178036 -106.347006)
		(width 0.1143)
		(layer "In4.Cu")
		(net "P3E_CPU1_PE3_MP_RXN<14>")
	)
	(segment
		(start -2.500122 -100.769928)
		(end -3.030982 -100.769928)
		(width 0.1143)
		(layer "In4.Cu")
		(net "P3E_CPU1_PE3_MP_RXN<14>")
	)
	(segment
		(start 7.15264 -110.074202)
		(end 7.31774 -110.239302)
		(width 0.1143)
		(layer "In4.Cu")
		(net "P3E_CPU1_PE3_MP_RXN<14>")
	)
	(segment
		(start 8.242046 -100.397056)
		(end 8.484362 -100.639372)
		(width 0.1143)
		(layer "In4.Cu")
		(net "P3E_CPU1_PE3_MP_RXN<14>")
	)
	(segment
		(start 8.45947 -106.832146)
		(end 8.45947 -107.065572)
		(width 0.1143)
		(layer "In4.Cu")
		(net "P3E_CPU1_PE3_MP_RXN<14>")
	)
	(segment
		(start 8.484362 -100.639372)
		(end 8.717788 -100.639372)
		(width 0.1143)
		(layer "In4.Cu")
		(net "P3E_CPU1_PE3_MP_RXN<14>")
	)
	(segment
		(start 7.741158 -107.783884)
		(end 7.31774 -108.207302)
		(width 0.1143)
		(layer "In4.Cu")
		(net "P3E_CPU1_PE3_MP_RXN<14>")
	)
	(segment
		(start 7.15264 -111.090202)
		(end 7.31774 -111.255302)
		(width 0.1143)
		(layer "In4.Cu")
		(net "P3E_CPU1_PE3_MP_RXN<14>")
	)
	(segment
		(start 7.31774 -110.582202)
		(end 7.15264 -110.747302)
		(width 0.1143)
		(layer "In4.Cu")
		(net "P3E_CPU1_PE3_MP_RXN<14>")
	)
	(segment
		(start 9.896348 -101.817932)
		(end 9.896348 -105.628694)
		(width 0.1143)
		(layer "In4.Cu")
		(net "P3E_CPU1_PE3_MP_RXN<14>")
	)
	(segment
		(start 9.420352 -105.871264)
		(end 9.178036 -106.11358)
		(width 0.1143)
		(layer "In4.Cu")
		(net "P3E_CPU1_PE3_MP_RXN<14>")
	)
	(segment
		(start 133.665214 -91.565984)
		(end 134.236714 -91.565984)
		(width 0.1143)
		(layer "F.Cu")
		(net "P3E_CPU1_PE3_MP_RXN<13>")
	)
	(via
		(at 134.236714 -91.565984)
		(size 0.508)
		(drill 0.254)
		(layers "F.Cu" "B.Cu")
		(net "P3E_CPU1_PE3_MP_RXN<13>")
	)
	(segment
		(start 134.236714 -91.565984)
		(end 133.943598 -91.397074)
		(width 0.0889)
		(layer "B.Cu")
		(net "P3E_CPU1_PE3_MP_RXN<13>")
	)
	(segment
		(start 130.456178 -99.290886)
		(end 130.451352 -99.299522)
		(width 0.0889)
		(layer "B.Cu")
		(net "P3E_CPU1_PE3_MP_RXN<13>")
	)
	(segment
		(start 131.679188 -92.652088)
		(end 131.646422 -92.652088)
		(width 0.0889)
		(layer "B.Cu")
		(net "P3E_CPU1_PE3_MP_RXN<13>")
	)
	(segment
		(start 130.456178 -96.319086)
		(end 130.451352 -96.327722)
		(width 0.0889)
		(layer "B.Cu")
		(net "P3E_CPU1_PE3_MP_RXN<13>")
	)
	(segment
		(start 116.14531 -113.985294)
		(end 109.865414 -115.241324)
		(width 0.1143)
		(layer "B.Cu")
		(net "P3E_CPU1_PE3_MP_RXN<13>")
	)
	(segment
		(start 81.526634 -115.985036)
		(end 69.813932 -113.642648)
		(width 0.1143)
		(layer "B.Cu")
		(net "P3E_CPU1_PE3_MP_RXN<13>")
	)
	(segment
		(start 130.508756 -103.199946)
		(end 130.4417 -103.330502)
		(width 0.0889)
		(layer "B.Cu")
		(net "P3E_CPU1_PE3_MP_RXN<13>")
	)
	(segment
		(start 133.943598 -91.397074)
		(end 133.85419 -91.421204)
		(width 0.0889)
		(layer "B.Cu")
		(net "P3E_CPU1_PE3_MP_RXN<13>")
	)
	(segment
		(start 129.921 -106.219498)
		(end 129.921 -113.12779)
		(width 0.1143)
		(layer "B.Cu")
		(net "P3E_CPU1_PE3_MP_RXN<13>")
	)
	(segment
		(start 130.4417 -103.330502)
		(end 130.4417 -103.508302)
		(width 0.0889)
		(layer "B.Cu")
		(net "P3E_CPU1_PE3_MP_RXN<13>")
	)
	(segment
		(start 98.294698 -115.709954)
		(end 90.597482 -114.170714)
		(width 0.1143)
		(layer "B.Cu")
		(net "P3E_CPU1_PE3_MP_RXN<13>")
	)
	(segment
		(start 130.456178 -94.737936)
		(end 130.462528 -94.748604)
		(width 0.0889)
		(layer "B.Cu")
		(net "P3E_CPU1_PE3_MP_RXN<13>")
	)
	(segment
		(start 105.251504 -114.318542)
		(end 98.294698 -115.709954)
		(width 0.1143)
		(layer "B.Cu")
		(net "P3E_CPU1_PE3_MP_RXN<13>")
	)
	(segment
		(start 130.456178 -97.309686)
		(end 130.451352 -97.318322)
		(width 0.0889)
		(layer "B.Cu")
		(net "P3E_CPU1_PE3_MP_RXN<13>")
	)
	(segment
		(start 69.813932 -113.642902)
		(end 53.95214 -116.815108)
		(width 0.1143)
		(layer "B.Cu")
		(net "P3E_CPU1_PE3_MP_RXN<13>")
	)
	(segment
		(start 129.921 -106.1974)
		(end 129.921 -106.219498)
		(width 0.0889)
		(layer "B.Cu")
		(net "P3E_CPU1_PE3_MP_RXN<13>")
	)
	(segment
		(start 132.17652 -92.350844)
		(end 132.173218 -92.356686)
		(width 0.0889)
		(layer "B.Cu")
		(net "P3E_CPU1_PE3_MP_RXN<13>")
	)
	(segment
		(start 132.541264 -92.156534)
		(end 132.519674 -92.156534)
		(width 0.0889)
		(layer "B.Cu")
		(net "P3E_CPU1_PE3_MP_RXN<13>")
	)
	(segment
		(start 23.138638 -115.990624)
		(end 18.320512 -111.186722)
		(width 0.1143)
		(layer "B.Cu")
		(net "P3E_CPU1_PE3_MP_RXN<13>")
	)
	(segment
		(start 129.921 -113.12779)
		(end 128.832864 -114.21618)
		(width 0.1143)
		(layer "B.Cu")
		(net "P3E_CPU1_PE3_MP_RXN<13>")
	)
	(segment
		(start 130.462528 -102.252018)
		(end 130.456178 -102.262686)
		(width 0.0889)
		(layer "B.Cu")
		(net "P3E_CPU1_PE3_MP_RXN<13>")
	)
	(segment
		(start 130.529584 -103.085646)
		(end 130.508756 -103.199946)
		(width 0.0889)
		(layer "B.Cu")
		(net "P3E_CPU1_PE3_MP_RXN<13>")
	)
	(segment
		(start 130.4417 -103.884222)
		(end 130.4417 -104.062022)
		(width 0.0889)
		(layer "B.Cu")
		(net "P3E_CPU1_PE3_MP_RXN<13>")
	)
	(segment
		(start 130.54076 -103.785162)
		(end 130.4417 -103.884222)
		(width 0.0889)
		(layer "B.Cu")
		(net "P3E_CPU1_PE3_MP_RXN<13>")
	)
	(segment
		(start 130.456178 -100.681536)
		(end 130.462528 -100.692204)
		(width 0.0889)
		(layer "B.Cu")
		(net "P3E_CPU1_PE3_MP_RXN<13>")
	)
	(segment
		(start 130.462528 -97.299018)
		(end 130.456178 -97.309686)
		(width 0.0889)
		(layer "B.Cu")
		(net "P3E_CPU1_PE3_MP_RXN<13>")
	)
	(segment
		(start 90.597482 -114.170714)
		(end 81.526634 -115.985036)
		(width 0.1143)
		(layer "B.Cu")
		(net "P3E_CPU1_PE3_MP_RXN<13>")
	)
	(segment
		(start 109.865414 -115.241324)
		(end 105.251504 -114.318542)
		(width 0.1143)
		(layer "B.Cu")
		(net "P3E_CPU1_PE3_MP_RXN<13>")
	)
	(segment
		(start 130.456178 -98.300286)
		(end 130.451352 -98.308922)
		(width 0.0889)
		(layer "B.Cu")
		(net "P3E_CPU1_PE3_MP_RXN<13>")
	)
	(segment
		(start 53.95214 -116.815108)
		(end 35.95624 -118.587266)
		(width 0.1143)
		(layer "B.Cu")
		(net "P3E_CPU1_PE3_MP_RXN<13>")
	)
	(segment
		(start 130.456178 -101.272086)
		(end 130.451352 -101.280722)
		(width 0.0889)
		(layer "B.Cu")
		(net "P3E_CPU1_PE3_MP_RXN<13>")
	)
	(segment
		(start 133.395974 -91.661488)
		(end 133.363208 -91.661488)
		(width 0.0889)
		(layer "B.Cu")
		(net "P3E_CPU1_PE3_MP_RXN<13>")
	)
	(segment
		(start 130.4417 -103.508302)
		(end 130.54076 -103.607362)
		(width 0.0889)
		(layer "B.Cu")
		(net "P3E_CPU1_PE3_MP_RXN<13>")
	)
	(segment
		(start 35.95624 -118.587266)
		(end 30.393894 -118.587266)
		(width 0.1143)
		(layer "B.Cu")
		(net "P3E_CPU1_PE3_MP_RXN<13>")
	)
	(segment
		(start 18.320512 -111.186722)
		(end 12.24915 -108.672376)
		(width 0.1143)
		(layer "B.Cu")
		(net "P3E_CPU1_PE3_MP_RXN<13>")
	)
	(segment
		(start 130.462528 -98.289618)
		(end 130.456178 -98.300286)
		(width 0.0889)
		(layer "B.Cu")
		(net "P3E_CPU1_PE3_MP_RXN<13>")
	)
	(segment
		(start 130.824478 -93.147134)
		(end 130.791712 -93.147134)
		(width 0.0889)
		(layer "B.Cu")
		(net "P3E_CPU1_PE3_MP_RXN<13>")
	)
	(segment
		(start 130.456178 -95.328486)
		(end 130.451352 -95.337122)
		(width 0.0889)
		(layer "B.Cu")
		(net "P3E_CPU1_PE3_MP_RXN<13>")
	)
	(segment
		(start 130.4417 -104.062022)
		(end 130.54076 -104.161082)
		(width 0.0889)
		(layer "B.Cu")
		(net "P3E_CPU1_PE3_MP_RXN<13>")
	)
	(segment
		(start 8.646922 -101.788976)
		(end 7.1374 -101.788976)
		(width 0.1143)
		(layer "B.Cu")
		(net "P3E_CPU1_PE3_MP_RXN<13>")
	)
	(segment
		(start 12.24915 -108.672376)
		(end 11.418062 -107.841542)
		(width 0.1143)
		(layer "B.Cu")
		(net "P3E_CPU1_PE3_MP_RXN<13>")
	)
	(segment
		(start 7.1374 -101.788976)
		(end 6.67766 -102.248716)
		(width 0.1143)
		(layer "B.Cu")
		(net "P3E_CPU1_PE3_MP_RXN<13>")
	)
	(segment
		(start 130.4417 -105.249472)
		(end 129.8956 -105.795572)
		(width 0.0889)
		(layer "B.Cu")
		(net "P3E_CPU1_PE3_MP_RXN<13>")
	)
	(segment
		(start 6.910324 -102.769924)
		(end 7.199884 -102.769924)
		(width 0.1143)
		(layer "B.Cu")
		(net "P3E_CPU1_PE3_MP_RXN<13>")
	)
	(segment
		(start 130.54076 -103.607362)
		(end 130.54076 -103.785162)
		(width 0.0889)
		(layer "B.Cu")
		(net "P3E_CPU1_PE3_MP_RXN<13>")
	)
	(segment
		(start 130.462528 -99.280218)
		(end 130.456178 -99.290886)
		(width 0.0889)
		(layer "B.Cu")
		(net "P3E_CPU1_PE3_MP_RXN<13>")
	)
	(segment
		(start 129.8956 -105.795572)
		(end 129.8956 -106.172)
		(width 0.0889)
		(layer "B.Cu")
		(net "P3E_CPU1_PE3_MP_RXN<13>")
	)
	(segment
		(start 123.066302 -115.369594)
		(end 116.14531 -113.985294)
		(width 0.1143)
		(layer "B.Cu")
		(net "P3E_CPU1_PE3_MP_RXN<13>")
	)
	(segment
		(start 130.462528 -96.308418)
		(end 130.456178 -96.319086)
		(width 0.0889)
		(layer "B.Cu")
		(net "P3E_CPU1_PE3_MP_RXN<13>")
	)
	(segment
		(start 130.456178 -102.262686)
		(end 130.451352 -102.271322)
		(width 0.0889)
		(layer "B.Cu")
		(net "P3E_CPU1_PE3_MP_RXN<13>")
	)
	(segment
		(start 129.8956 -106.172)
		(end 129.921 -106.1974)
		(width 0.0889)
		(layer "B.Cu")
		(net "P3E_CPU1_PE3_MP_RXN<13>")
	)
	(segment
		(start 6.67766 -102.53726)
		(end 6.910324 -102.769924)
		(width 0.1143)
		(layer "B.Cu")
		(net "P3E_CPU1_PE3_MP_RXN<13>")
	)
	(segment
		(start 69.813932 -113.642648)
		(end 69.813932 -113.642902)
		(width 0.1143)
		(layer "B.Cu")
		(net "P3E_CPU1_PE3_MP_RXN<13>")
	)
	(segment
		(start 30.393894 -118.587266)
		(end 23.138638 -115.990624)
		(width 0.1143)
		(layer "B.Cu")
		(net "P3E_CPU1_PE3_MP_RXN<13>")
	)
	(segment
		(start 9.097772 -102.239826)
		(end 8.646922 -101.788976)
		(width 0.1143)
		(layer "B.Cu")
		(net "P3E_CPU1_PE3_MP_RXN<13>")
	)
	(segment
		(start 130.54076 -104.161082)
		(end 130.54076 -104.338882)
		(width 0.0889)
		(layer "B.Cu")
		(net "P3E_CPU1_PE3_MP_RXN<13>")
	)
	(segment
		(start 130.4417 -104.437942)
		(end 130.4417 -105.249472)
		(width 0.0889)
		(layer "B.Cu")
		(net "P3E_CPU1_PE3_MP_RXN<13>")
	)
	(segment
		(start 11.418062 -107.841542)
		(end 9.097772 -102.239826)
		(width 0.1143)
		(layer "B.Cu")
		(net "P3E_CPU1_PE3_MP_RXN<13>")
	)
	(segment
		(start 128.832864 -114.21618)
		(end 123.066302 -115.369594)
		(width 0.1143)
		(layer "B.Cu")
		(net "P3E_CPU1_PE3_MP_RXN<13>")
	)
	(segment
		(start 6.67766 -102.248716)
		(end 6.67766 -102.53726)
		(width 0.1143)
		(layer "B.Cu")
		(net "P3E_CPU1_PE3_MP_RXN<13>")
	)
	(segment
		(start 130.54076 -104.338882)
		(end 130.4417 -104.437942)
		(width 0.0889)
		(layer "B.Cu")
		(net "P3E_CPU1_PE3_MP_RXN<13>")
	)
	(arc
		(start 130.462528 -100.692204)
		(mid 130.535326 -100.982967)
		(end 130.456178 -101.272086)
		(width 0.0889)
		(layer "B.Cu")
		(net "P3E_CPU1_PE3_MP_RXN<13>")
	)
	(arc
		(start 130.451352 -95.337122)
		(mid 130.402597 -95.533474)
		(end 130.456178 -95.728536)
		(width 0.0889)
		(layer "B.Cu")
		(net "P3E_CPU1_PE3_MP_RXN<13>")
	)
	(arc
		(start 131.314698 -92.851986)
		(mid 131.107694 -93.06285)
		(end 130.824478 -93.147134)
		(width 0.0889)
		(layer "B.Cu")
		(net "P3E_CPU1_PE3_MP_RXN<13>")
	)
	(arc
		(start 133.85419 -91.421204)
		(mid 133.65278 -91.594157)
		(end 133.395974 -91.661488)
		(width 0.0889)
		(layer "B.Cu")
		(net "P3E_CPU1_PE3_MP_RXN<13>")
	)
	(arc
		(start 130.456178 -93.747336)
		(mid 130.535309 -94.042738)
		(end 130.456178 -94.33814)
		(width 0.0889)
		(layer "B.Cu")
		(net "P3E_CPU1_PE3_MP_RXN<13>")
	)
	(arc
		(start 130.456178 -102.662736)
		(mid 130.530465 -102.867666)
		(end 130.529584 -103.085646)
		(width 0.0889)
		(layer "B.Cu")
		(net "P3E_CPU1_PE3_MP_RXN<13>")
	)
	(arc
		(start 130.456178 -100.28174)
		(mid 130.402679 -100.481638)
		(end 130.456178 -100.681536)
		(width 0.0889)
		(layer "B.Cu")
		(net "P3E_CPU1_PE3_MP_RXN<13>")
	)
	(arc
		(start 130.462528 -94.748604)
		(mid 130.535326 -95.039367)
		(end 130.456178 -95.328486)
		(width 0.0889)
		(layer "B.Cu")
		(net "P3E_CPU1_PE3_MP_RXN<13>")
	)
	(arc
		(start 133.031484 -91.861386)
		(mid 132.82448 -92.07225)
		(end 132.541264 -92.156534)
		(width 0.0889)
		(layer "B.Cu")
		(net "P3E_CPU1_PE3_MP_RXN<13>")
	)
	(arc
		(start 130.456178 -94.33814)
		(mid 130.402679 -94.538038)
		(end 130.456178 -94.737936)
		(width 0.0889)
		(layer "B.Cu")
		(net "P3E_CPU1_PE3_MP_RXN<13>")
	)
	(arc
		(start 130.451352 -101.280722)
		(mid 130.402597 -101.477074)
		(end 130.456178 -101.672136)
		(width 0.0889)
		(layer "B.Cu")
		(net "P3E_CPU1_PE3_MP_RXN<13>")
	)
	(arc
		(start 130.456178 -97.709736)
		(mid 130.5354 -97.998854)
		(end 130.462528 -98.289618)
		(width 0.0889)
		(layer "B.Cu")
		(net "P3E_CPU1_PE3_MP_RXN<13>")
	)
	(arc
		(start 130.451352 -99.299522)
		(mid 130.402597 -99.495874)
		(end 130.456178 -99.690936)
		(width 0.0889)
		(layer "B.Cu")
		(net "P3E_CPU1_PE3_MP_RXN<13>")
	)
	(arc
		(start 130.791712 -93.147134)
		(mid 130.453543 -93.351932)
		(end 130.456178 -93.747336)
		(width 0.0889)
		(layer "B.Cu")
		(net "P3E_CPU1_PE3_MP_RXN<13>")
	)
	(arc
		(start 130.456178 -96.719136)
		(mid 130.5354 -97.008254)
		(end 130.462528 -97.299018)
		(width 0.0889)
		(layer "B.Cu")
		(net "P3E_CPU1_PE3_MP_RXN<13>")
	)
	(arc
		(start 132.519674 -92.156534)
		(mid 132.322513 -92.208493)
		(end 132.17652 -92.350844)
		(width 0.0889)
		(layer "B.Cu")
		(net "P3E_CPU1_PE3_MP_RXN<13>")
	)
	(arc
		(start 130.451352 -102.271322)
		(mid 130.402597 -102.467674)
		(end 130.456178 -102.662736)
		(width 0.0889)
		(layer "B.Cu")
		(net "P3E_CPU1_PE3_MP_RXN<13>")
	)
	(arc
		(start 131.646422 -92.652088)
		(mid 131.45478 -92.709254)
		(end 131.314698 -92.851986)
		(width 0.0889)
		(layer "B.Cu")
		(net "P3E_CPU1_PE3_MP_RXN<13>")
	)
	(arc
		(start 130.451352 -98.308922)
		(mid 130.402597 -98.505274)
		(end 130.456178 -98.700336)
		(width 0.0889)
		(layer "B.Cu")
		(net "P3E_CPU1_PE3_MP_RXN<13>")
	)
	(arc
		(start 130.456178 -99.690936)
		(mid 130.535309 -99.986338)
		(end 130.456178 -100.28174)
		(width 0.0889)
		(layer "B.Cu")
		(net "P3E_CPU1_PE3_MP_RXN<13>")
	)
	(arc
		(start 132.173218 -92.356686)
		(mid 131.96461 -92.568618)
		(end 131.679188 -92.652088)
		(width 0.0889)
		(layer "B.Cu")
		(net "P3E_CPU1_PE3_MP_RXN<13>")
	)
	(arc
		(start 133.363208 -91.661488)
		(mid 133.171566 -91.718654)
		(end 133.031484 -91.861386)
		(width 0.0889)
		(layer "B.Cu")
		(net "P3E_CPU1_PE3_MP_RXN<13>")
	)
	(arc
		(start 130.456178 -101.672136)
		(mid 130.5354 -101.961254)
		(end 130.462528 -102.252018)
		(width 0.0889)
		(layer "B.Cu")
		(net "P3E_CPU1_PE3_MP_RXN<13>")
	)
	(arc
		(start 130.456178 -95.728536)
		(mid 130.5354 -96.017654)
		(end 130.462528 -96.308418)
		(width 0.0889)
		(layer "B.Cu")
		(net "P3E_CPU1_PE3_MP_RXN<13>")
	)
	(arc
		(start 130.451352 -97.318322)
		(mid 130.402597 -97.514674)
		(end 130.456178 -97.709736)
		(width 0.0889)
		(layer "B.Cu")
		(net "P3E_CPU1_PE3_MP_RXN<13>")
	)
	(arc
		(start 130.456178 -98.700336)
		(mid 130.5354 -98.989454)
		(end 130.462528 -99.280218)
		(width 0.0889)
		(layer "B.Cu")
		(net "P3E_CPU1_PE3_MP_RXN<13>")
	)
	(arc
		(start 130.451352 -96.327722)
		(mid 130.402597 -96.524074)
		(end 130.456178 -96.719136)
		(width 0.0889)
		(layer "B.Cu")
		(net "P3E_CPU1_PE3_MP_RXN<13>")
	)
	(segment
		(start 132.806694 -92.061538)
		(end 133.378194 -92.061538)
		(width 0.1143)
		(layer "F.Cu")
		(net "P3E_CPU1_PE3_MP_RXN<12>")
	)
	(via
		(at 133.378194 -92.061538)
		(size 0.508)
		(drill 0.254)
		(layers "F.Cu" "B.Cu")
		(net "P3E_CPU1_PE3_MP_RXN<12>")
	)
	(segment
		(start 10.58926 -108.3818)
		(end 9.427718 -105.577894)
		(width 0.1143)
		(layer "B.Cu")
		(net "P3E_CPU1_PE3_MP_RXN<12>")
	)
	(segment
		(start 131.679188 -93.642688)
		(end 131.646422 -93.642688)
		(width 0.0889)
		(layer "B.Cu")
		(net "P3E_CPU1_PE3_MP_RXN<12>")
	)
	(segment
		(start 131.309872 -94.234)
		(end 131.314698 -94.242636)
		(width 0.0889)
		(layer "B.Cu")
		(net "P3E_CPU1_PE3_MP_RXN<12>")
	)
	(segment
		(start 131.314698 -98.205036)
		(end 131.321048 -98.215704)
		(width 0.0889)
		(layer "B.Cu")
		(net "P3E_CPU1_PE3_MP_RXN<12>")
	)
	(segment
		(start 90.896694 -115.377722)
		(end 81.873598 -117.182392)
		(width 0.1143)
		(layer "B.Cu")
		(net "P3E_CPU1_PE3_MP_RXN<12>")
	)
	(segment
		(start 22.556978 -116.808758)
		(end 17.746472 -111.997998)
		(width 0.1143)
		(layer "B.Cu")
		(net "P3E_CPU1_PE3_MP_RXN<12>")
	)
	(segment
		(start 2.2225 -102.93096)
		(end 2.061464 -102.769924)
		(width 0.1143)
		(layer "B.Cu")
		(net "P3E_CPU1_PE3_MP_RXN<12>")
	)
	(segment
		(start 69.462396 -114.699796)
		(end 69.462396 -114.70005)
		(width 0.1143)
		(layer "B.Cu")
		(net "P3E_CPU1_PE3_MP_RXN<12>")
	)
	(segment
		(start 132.17652 -93.341444)
		(end 132.173218 -93.347286)
		(width 0.0889)
		(layer "B.Cu")
		(net "P3E_CPU1_PE3_MP_RXN<12>")
	)
	(segment
		(start 131.309872 -100.1776)
		(end 131.314698 -100.186236)
		(width 0.0889)
		(layer "B.Cu")
		(net "P3E_CPU1_PE3_MP_RXN<12>")
	)
	(segment
		(start 131.3434 -105.7656)
		(end 130.8735 -106.2355)
		(width 0.0889)
		(layer "B.Cu")
		(net "P3E_CPU1_PE3_MP_RXN<12>")
	)
	(segment
		(start 81.873598 -117.182392)
		(end 69.462396 -114.699796)
		(width 0.1143)
		(layer "B.Cu")
		(net "P3E_CPU1_PE3_MP_RXN<12>")
	)
	(segment
		(start 131.321048 -94.822518)
		(end 131.314698 -94.833186)
		(width 0.0889)
		(layer "B.Cu")
		(net "P3E_CPU1_PE3_MP_RXN<12>")
	)
	(segment
		(start 131.314698 -96.223836)
		(end 131.321048 -96.234504)
		(width 0.0889)
		(layer "B.Cu")
		(net "P3E_CPU1_PE3_MP_RXN<12>")
	)
	(segment
		(start 131.309872 -98.1964)
		(end 131.314698 -98.205036)
		(width 0.0889)
		(layer "B.Cu")
		(net "P3E_CPU1_PE3_MP_RXN<12>")
	)
	(segment
		(start 131.309872 -97.2058)
		(end 131.314698 -97.214436)
		(width 0.0889)
		(layer "B.Cu")
		(net "P3E_CPU1_PE3_MP_RXN<12>")
	)
	(segment
		(start 11.691874 -109.49051)
		(end 10.58926 -108.3818)
		(width 0.1143)
		(layer "B.Cu")
		(net "P3E_CPU1_PE3_MP_RXN<12>")
	)
	(segment
		(start 30.557978 -119.6721)
		(end 22.556978 -116.808758)
		(width 0.1143)
		(layer "B.Cu")
		(net "P3E_CPU1_PE3_MP_RXN<12>")
	)
	(segment
		(start 131.314698 -102.757986)
		(end 131.2418 -102.884224)
		(width 0.0889)
		(layer "B.Cu")
		(net "P3E_CPU1_PE3_MP_RXN<12>")
	)
	(segment
		(start 131.2418 -103.373428)
		(end 131.3434 -103.619046)
		(width 0.0889)
		(layer "B.Cu")
		(net "P3E_CPU1_PE3_MP_RXN<12>")
	)
	(segment
		(start 130.8735 -106.772202)
		(end 130.8989 -106.797602)
		(width 0.0889)
		(layer "B.Cu")
		(net "P3E_CPU1_PE3_MP_RXN<12>")
	)
	(segment
		(start 132.541264 -93.147134)
		(end 132.519674 -93.147134)
		(width 0.0889)
		(layer "B.Cu")
		(net "P3E_CPU1_PE3_MP_RXN<12>")
	)
	(segment
		(start 116.448586 -115.217448)
		(end 109.795056 -116.548154)
		(width 0.1143)
		(layer "B.Cu")
		(net "P3E_CPU1_PE3_MP_RXN<12>")
	)
	(segment
		(start 131.309872 -99.187)
		(end 131.314698 -99.195636)
		(width 0.0889)
		(layer "B.Cu")
		(net "P3E_CPU1_PE3_MP_RXN<12>")
	)
	(segment
		(start 131.309872 -96.2152)
		(end 131.314698 -96.223836)
		(width 0.0889)
		(layer "B.Cu")
		(net "P3E_CPU1_PE3_MP_RXN<12>")
	)
	(segment
		(start 131.321048 -100.766118)
		(end 131.314698 -100.776786)
		(width 0.0889)
		(layer "B.Cu")
		(net "P3E_CPU1_PE3_MP_RXN<12>")
	)
	(segment
		(start 131.2418 -102.884224)
		(end 131.2418 -103.373428)
		(width 0.0889)
		(layer "B.Cu")
		(net "P3E_CPU1_PE3_MP_RXN<12>")
	)
	(segment
		(start 131.314698 -102.167436)
		(end 131.321048 -102.178104)
		(width 0.0889)
		(layer "B.Cu")
		(net "P3E_CPU1_PE3_MP_RXN<12>")
	)
	(segment
		(start 123.00204 -116.528088)
		(end 116.448586 -115.217448)
		(width 0.1143)
		(layer "B.Cu")
		(net "P3E_CPU1_PE3_MP_RXN<12>")
	)
	(segment
		(start 133.378194 -92.061538)
		(end 133.061202 -92.319602)
		(width 0.0889)
		(layer "B.Cu")
		(net "P3E_CPU1_PE3_MP_RXN<12>")
	)
	(segment
		(start 35.379406 -119.6721)
		(end 30.557978 -119.6721)
		(width 0.1143)
		(layer "B.Cu")
		(net "P3E_CPU1_PE3_MP_RXN<12>")
	)
	(segment
		(start 131.3434 -103.619046)
		(end 131.3434 -105.7656)
		(width 0.0889)
		(layer "B.Cu")
		(net "P3E_CPU1_PE3_MP_RXN<12>")
	)
	(segment
		(start 98.020632 -116.802408)
		(end 90.896694 -115.377722)
		(width 0.1143)
		(layer "B.Cu")
		(net "P3E_CPU1_PE3_MP_RXN<12>")
	)
	(segment
		(start 2.2225 -103.401876)
		(end 2.2225 -102.93096)
		(width 0.1143)
		(layer "B.Cu")
		(net "P3E_CPU1_PE3_MP_RXN<12>")
	)
	(segment
		(start 53.554884 -117.8814)
		(end 35.379406 -119.6721)
		(width 0.1143)
		(layer "B.Cu")
		(net "P3E_CPU1_PE3_MP_RXN<12>")
	)
	(segment
		(start 7.74573 -103.895652)
		(end 2.716276 -103.895652)
		(width 0.1143)
		(layer "B.Cu")
		(net "P3E_CPU1_PE3_MP_RXN<12>")
	)
	(segment
		(start 130.8735 -106.2355)
		(end 130.8735 -106.772202)
		(width 0.0889)
		(layer "B.Cu")
		(net "P3E_CPU1_PE3_MP_RXN<12>")
	)
	(segment
		(start 130.8989 -106.8197)
		(end 130.8989 -113.612676)
		(width 0.1143)
		(layer "B.Cu")
		(net "P3E_CPU1_PE3_MP_RXN<12>")
	)
	(segment
		(start 131.314698 -99.195636)
		(end 131.321048 -99.206304)
		(width 0.0889)
		(layer "B.Cu")
		(net "P3E_CPU1_PE3_MP_RXN<12>")
	)
	(segment
		(start 104.54386 -115.497864)
		(end 98.020632 -116.802408)
		(width 0.1143)
		(layer "B.Cu")
		(net "P3E_CPU1_PE3_MP_RXN<12>")
	)
	(segment
		(start 2.061464 -102.769924)
		(end 1.599946 -102.769924)
		(width 0.1143)
		(layer "B.Cu")
		(net "P3E_CPU1_PE3_MP_RXN<12>")
	)
	(segment
		(start 2.716276 -103.895652)
		(end 2.2225 -103.401876)
		(width 0.1143)
		(layer "B.Cu")
		(net "P3E_CPU1_PE3_MP_RXN<12>")
	)
	(segment
		(start 69.462396 -114.70005)
		(end 53.554884 -117.8814)
		(width 0.1143)
		(layer "B.Cu")
		(net "P3E_CPU1_PE3_MP_RXN<12>")
	)
	(segment
		(start 130.8989 -113.612676)
		(end 129.22885 -115.282726)
		(width 0.1143)
		(layer "B.Cu")
		(net "P3E_CPU1_PE3_MP_RXN<12>")
	)
	(segment
		(start 129.22885 -115.282726)
		(end 123.00204 -116.528088)
		(width 0.1143)
		(layer "B.Cu")
		(net "P3E_CPU1_PE3_MP_RXN<12>")
	)
	(segment
		(start 131.314698 -97.214436)
		(end 131.321048 -97.225104)
		(width 0.0889)
		(layer "B.Cu")
		(net "P3E_CPU1_PE3_MP_RXN<12>")
	)
	(segment
		(start 17.746472 -111.997998)
		(end 11.691874 -109.49051)
		(width 0.1143)
		(layer "B.Cu")
		(net "P3E_CPU1_PE3_MP_RXN<12>")
	)
	(segment
		(start 109.795056 -116.548154)
		(end 104.54386 -115.497864)
		(width 0.1143)
		(layer "B.Cu")
		(net "P3E_CPU1_PE3_MP_RXN<12>")
	)
	(segment
		(start 9.427718 -105.577894)
		(end 7.74573 -103.895652)
		(width 0.1143)
		(layer "B.Cu")
		(net "P3E_CPU1_PE3_MP_RXN<12>")
	)
	(segment
		(start 131.309872 -102.1588)
		(end 131.314698 -102.167436)
		(width 0.0889)
		(layer "B.Cu")
		(net "P3E_CPU1_PE3_MP_RXN<12>")
	)
	(segment
		(start 130.8989 -106.797602)
		(end 130.8989 -106.8197)
		(width 0.0889)
		(layer "B.Cu")
		(net "P3E_CPU1_PE3_MP_RXN<12>")
	)
	(arc
		(start 131.321048 -98.215704)
		(mid 131.393846 -98.506467)
		(end 131.314698 -98.795586)
		(width 0.0889)
		(layer "B.Cu")
		(net "P3E_CPU1_PE3_MP_RXN<12>")
	)
	(arc
		(start 131.314698 -98.795586)
		(mid 131.261228 -98.990649)
		(end 131.309872 -99.187)
		(width 0.0889)
		(layer "B.Cu")
		(net "P3E_CPU1_PE3_MP_RXN<12>")
	)
	(arc
		(start 131.314698 -94.833186)
		(mid 131.261199 -95.033084)
		(end 131.314698 -95.232982)
		(width 0.0889)
		(layer "B.Cu")
		(net "P3E_CPU1_PE3_MP_RXN<12>")
	)
	(arc
		(start 131.646422 -93.642688)
		(mid 131.313504 -93.844679)
		(end 131.309872 -94.234)
		(width 0.0889)
		(layer "B.Cu")
		(net "P3E_CPU1_PE3_MP_RXN<12>")
	)
	(arc
		(start 133.061202 -92.319602)
		(mid 133.020222 -92.871011)
		(end 132.541264 -93.147134)
		(width 0.0889)
		(layer "B.Cu")
		(net "P3E_CPU1_PE3_MP_RXN<12>")
	)
	(arc
		(start 131.314698 -101.176582)
		(mid 131.393829 -101.471984)
		(end 131.314698 -101.767386)
		(width 0.0889)
		(layer "B.Cu")
		(net "P3E_CPU1_PE3_MP_RXN<12>")
	)
	(arc
		(start 131.314698 -100.776786)
		(mid 131.261199 -100.976684)
		(end 131.314698 -101.176582)
		(width 0.0889)
		(layer "B.Cu")
		(net "P3E_CPU1_PE3_MP_RXN<12>")
	)
	(arc
		(start 132.173218 -93.347286)
		(mid 131.96461 -93.559218)
		(end 131.679188 -93.642688)
		(width 0.0889)
		(layer "B.Cu")
		(net "P3E_CPU1_PE3_MP_RXN<12>")
	)
	(arc
		(start 131.314698 -97.804986)
		(mid 131.261228 -98.000049)
		(end 131.309872 -98.1964)
		(width 0.0889)
		(layer "B.Cu")
		(net "P3E_CPU1_PE3_MP_RXN<12>")
	)
	(arc
		(start 131.321048 -102.178104)
		(mid 131.393846 -102.468867)
		(end 131.314698 -102.757986)
		(width 0.0889)
		(layer "B.Cu")
		(net "P3E_CPU1_PE3_MP_RXN<12>")
	)
	(arc
		(start 132.519674 -93.147134)
		(mid 132.322513 -93.199093)
		(end 132.17652 -93.341444)
		(width 0.0889)
		(layer "B.Cu")
		(net "P3E_CPU1_PE3_MP_RXN<12>")
	)
	(arc
		(start 131.314698 -96.814386)
		(mid 131.261228 -97.009449)
		(end 131.309872 -97.2058)
		(width 0.0889)
		(layer "B.Cu")
		(net "P3E_CPU1_PE3_MP_RXN<12>")
	)
	(arc
		(start 131.314698 -95.232982)
		(mid 131.393829 -95.528384)
		(end 131.314698 -95.823786)
		(width 0.0889)
		(layer "B.Cu")
		(net "P3E_CPU1_PE3_MP_RXN<12>")
	)
	(arc
		(start 131.321048 -99.206304)
		(mid 131.393846 -99.497067)
		(end 131.314698 -99.786186)
		(width 0.0889)
		(layer "B.Cu")
		(net "P3E_CPU1_PE3_MP_RXN<12>")
	)
	(arc
		(start 131.314698 -95.823786)
		(mid 131.261228 -96.018849)
		(end 131.309872 -96.2152)
		(width 0.0889)
		(layer "B.Cu")
		(net "P3E_CPU1_PE3_MP_RXN<12>")
	)
	(arc
		(start 131.314698 -99.786186)
		(mid 131.261228 -99.981249)
		(end 131.309872 -100.1776)
		(width 0.0889)
		(layer "B.Cu")
		(net "P3E_CPU1_PE3_MP_RXN<12>")
	)
	(arc
		(start 131.314698 -101.767386)
		(mid 131.261228 -101.962449)
		(end 131.309872 -102.1588)
		(width 0.0889)
		(layer "B.Cu")
		(net "P3E_CPU1_PE3_MP_RXN<12>")
	)
	(arc
		(start 131.321048 -96.234504)
		(mid 131.393846 -96.525267)
		(end 131.314698 -96.814386)
		(width 0.0889)
		(layer "B.Cu")
		(net "P3E_CPU1_PE3_MP_RXN<12>")
	)
	(arc
		(start 131.314698 -100.186236)
		(mid 131.39392 -100.475354)
		(end 131.321048 -100.766118)
		(width 0.0889)
		(layer "B.Cu")
		(net "P3E_CPU1_PE3_MP_RXN<12>")
	)
	(arc
		(start 131.321048 -97.225104)
		(mid 131.393846 -97.515867)
		(end 131.314698 -97.804986)
		(width 0.0889)
		(layer "B.Cu")
		(net "P3E_CPU1_PE3_MP_RXN<12>")
	)
	(arc
		(start 131.314698 -94.242636)
		(mid 131.39392 -94.531754)
		(end 131.321048 -94.822518)
		(width 0.0889)
		(layer "B.Cu")
		(net "P3E_CPU1_PE3_MP_RXN<12>")
	)
	(segment
		(start 134.523734 -94.042738)
		(end 135.095234 -94.042738)
		(width 0.1143)
		(layer "F.Cu")
		(net "P3E_CPU1_PE3_MP_RXN<11>")
	)
	(via
		(at 3.05435 -107.9119)
		(size 0.508)
		(drill 0.254)
		(layers "F.Cu" "B.Cu")
		(net "P3E_CPU1_PE3_MP_RXN<11>")
	)
	(via
		(at 135.095234 -94.042738)
		(size 0.508)
		(drill 0.254)
		(layers "F.Cu" "B.Cu")
		(net "P3E_CPU1_PE3_MP_RXN<11>")
	)
	(segment
		(start 97.1423 -121.639076)
		(end 90.365834 -120.283732)
		(width 0.1143)
		(layer "B.Cu")
		(net "P3E_CPU1_PE3_MP_RXN<11>")
	)
	(segment
		(start 134.743698 -98.1964)
		(end 134.748524 -98.205036)
		(width 0.0889)
		(layer "B.Cu")
		(net "P3E_CPU1_PE3_MP_RXN<11>")
	)
	(segment
		(start 135.008112 -106.237278)
		(end 135.033512 -106.262678)
		(width 0.0889)
		(layer "B.Cu")
		(net "P3E_CPU1_PE3_MP_RXN<11>")
	)
	(segment
		(start 135.033512 -115.067588)
		(end 129.991866 -120.109234)
		(width 0.1143)
		(layer "B.Cu")
		(net "P3E_CPU1_PE3_MP_RXN<11>")
	)
	(segment
		(start 3.5687 -108.0262)
		(end 3.4544 -107.9119)
		(width 0.1143)
		(layer "B.Cu")
		(net "P3E_CPU1_PE3_MP_RXN<11>")
	)
	(segment
		(start 134.743698 -100.1776)
		(end 134.748524 -100.186236)
		(width 0.0889)
		(layer "B.Cu")
		(net "P3E_CPU1_PE3_MP_RXN<11>")
	)
	(segment
		(start 102.144576 -120.63857)
		(end 97.1423 -121.639076)
		(width 0.1143)
		(layer "B.Cu")
		(net "P3E_CPU1_PE3_MP_RXN<11>")
	)
	(segment
		(start 15.517114 -115.275614)
		(end 8.166608 -112.230408)
		(width 0.1143)
		(layer "B.Cu")
		(net "P3E_CPU1_PE3_MP_RXN<11>")
	)
	(segment
		(start 117.017546 -120.42394)
		(end 117.017546 -120.424194)
		(width 0.1143)
		(layer "B.Cu")
		(net "P3E_CPU1_PE3_MP_RXN<11>")
	)
	(segment
		(start 134.748524 -103.15829)
		(end 135.008112 -103.608124)
		(width 0.0889)
		(layer "B.Cu")
		(net "P3E_CPU1_PE3_MP_RXN<11>")
	)
	(segment
		(start 4.050284 -109.07014)
		(end 3.5687 -108.588556)
		(width 0.1143)
		(layer "B.Cu")
		(net "P3E_CPU1_PE3_MP_RXN<11>")
	)
	(segment
		(start 135.008112 -103.608124)
		(end 135.008112 -103.785924)
		(width 0.0889)
		(layer "B.Cu")
		(net "P3E_CPU1_PE3_MP_RXN<11>")
	)
	(segment
		(start 134.748524 -102.167436)
		(end 134.754874 -102.178104)
		(width 0.0889)
		(layer "B.Cu")
		(net "P3E_CPU1_PE3_MP_RXN<11>")
	)
	(segment
		(start 135.033512 -106.284776)
		(end 135.033512 -115.067588)
		(width 0.1143)
		(layer "B.Cu")
		(net "P3E_CPU1_PE3_MP_RXN<11>")
	)
	(segment
		(start 134.748524 -96.223836)
		(end 134.754874 -96.234504)
		(width 0.0889)
		(layer "B.Cu")
		(net "P3E_CPU1_PE3_MP_RXN<11>")
	)
	(segment
		(start 3.5687 -108.588556)
		(end 3.5687 -108.0262)
		(width 0.1143)
		(layer "B.Cu")
		(net "P3E_CPU1_PE3_MP_RXN<11>")
	)
	(segment
		(start 135.107172 -104.062784)
		(end 135.008112 -104.161844)
		(width 0.0889)
		(layer "B.Cu")
		(net "P3E_CPU1_PE3_MP_RXN<11>")
	)
	(segment
		(start 30.107382 -123.7234)
		(end 20.454366 -120.212612)
		(width 0.1143)
		(layer "B.Cu")
		(net "P3E_CPU1_PE3_MP_RXN<11>")
	)
	(segment
		(start 8.166608 -112.230408)
		(end 5.00634 -109.07014)
		(width 0.1143)
		(layer "B.Cu")
		(net "P3E_CPU1_PE3_MP_RXN<11>")
	)
	(segment
		(start 134.754874 -94.822518)
		(end 134.748524 -94.833186)
		(width 0.0889)
		(layer "B.Cu")
		(net "P3E_CPU1_PE3_MP_RXN<11>")
	)
	(segment
		(start 134.743698 -94.234)
		(end 134.748524 -94.242636)
		(width 0.0889)
		(layer "B.Cu")
		(net "P3E_CPU1_PE3_MP_RXN<11>")
	)
	(segment
		(start 134.748524 -98.205036)
		(end 134.754874 -98.215704)
		(width 0.0889)
		(layer "B.Cu")
		(net "P3E_CPU1_PE3_MP_RXN<11>")
	)
	(segment
		(start 135.095234 -94.042738)
		(end 134.802118 -93.873574)
		(width 0.0889)
		(layer "B.Cu")
		(net "P3E_CPU1_PE3_MP_RXN<11>")
	)
	(segment
		(start 129.991866 -120.109234)
		(end 122.71756 -121.563638)
		(width 0.1143)
		(layer "B.Cu")
		(net "P3E_CPU1_PE3_MP_RXN<11>")
	)
	(segment
		(start 64.71666 -122.164856)
		(end 60.264548 -121.274332)
		(width 0.1143)
		(layer "B.Cu")
		(net "P3E_CPU1_PE3_MP_RXN<11>")
	)
	(segment
		(start 134.748524 -99.195636)
		(end 134.754874 -99.206304)
		(width 0.0889)
		(layer "B.Cu")
		(net "P3E_CPU1_PE3_MP_RXN<11>")
	)
	(segment
		(start 122.71756 -121.563638)
		(end 117.017546 -120.42394)
		(width 0.1143)
		(layer "B.Cu")
		(net "P3E_CPU1_PE3_MP_RXN<11>")
	)
	(segment
		(start 135.008112 -104.161844)
		(end 135.008112 -106.237278)
		(width 0.0889)
		(layer "B.Cu")
		(net "P3E_CPU1_PE3_MP_RXN<11>")
	)
	(segment
		(start 90.365834 -120.283732)
		(end 82.155792 -121.925588)
		(width 0.1143)
		(layer "B.Cu")
		(net "P3E_CPU1_PE3_MP_RXN<11>")
	)
	(segment
		(start 134.802118 -93.873574)
		(end 134.723378 -93.89491)
		(width 0.0889)
		(layer "B.Cu")
		(net "P3E_CPU1_PE3_MP_RXN<11>")
	)
	(segment
		(start 3.4544 -107.9119)
		(end 3.05435 -107.9119)
		(width 0.1143)
		(layer "B.Cu")
		(net "P3E_CPU1_PE3_MP_RXN<11>")
	)
	(segment
		(start 117.017546 -120.424194)
		(end 109.044994 -122.018552)
		(width 0.1143)
		(layer "B.Cu")
		(net "P3E_CPU1_PE3_MP_RXN<11>")
	)
	(segment
		(start 134.748524 -97.214436)
		(end 134.754874 -97.225104)
		(width 0.0889)
		(layer "B.Cu")
		(net "P3E_CPU1_PE3_MP_RXN<11>")
	)
	(segment
		(start 35.39744 -123.7234)
		(end 30.107382 -123.7234)
		(width 0.1143)
		(layer "B.Cu")
		(net "P3E_CPU1_PE3_MP_RXN<11>")
	)
	(segment
		(start 5.00634 -109.07014)
		(end 4.050284 -109.07014)
		(width 0.1143)
		(layer "B.Cu")
		(net "P3E_CPU1_PE3_MP_RXN<11>")
	)
	(segment
		(start 60.264548 -121.274332)
		(end 35.39744 -123.7234)
		(width 0.1143)
		(layer "B.Cu")
		(net "P3E_CPU1_PE3_MP_RXN<11>")
	)
	(segment
		(start 82.155792 -121.925588)
		(end 74.033634 -120.301258)
		(width 0.1143)
		(layer "B.Cu")
		(net "P3E_CPU1_PE3_MP_RXN<11>")
	)
	(segment
		(start 74.033634 -120.301258)
		(end 64.71666 -122.164856)
		(width 0.1143)
		(layer "B.Cu")
		(net "P3E_CPU1_PE3_MP_RXN<11>")
	)
	(segment
		(start 134.743698 -99.187)
		(end 134.748524 -99.195636)
		(width 0.0889)
		(layer "B.Cu")
		(net "P3E_CPU1_PE3_MP_RXN<11>")
	)
	(segment
		(start 135.033512 -106.262678)
		(end 135.033512 -106.284776)
		(width 0.0889)
		(layer "B.Cu")
		(net "P3E_CPU1_PE3_MP_RXN<11>")
	)
	(segment
		(start 134.743698 -97.2058)
		(end 134.748524 -97.214436)
		(width 0.0889)
		(layer "B.Cu")
		(net "P3E_CPU1_PE3_MP_RXN<11>")
	)
	(segment
		(start 135.008112 -103.785924)
		(end 135.107172 -103.884984)
		(width 0.0889)
		(layer "B.Cu")
		(net "P3E_CPU1_PE3_MP_RXN<11>")
	)
	(segment
		(start 135.107172 -103.884984)
		(end 135.107172 -104.062784)
		(width 0.0889)
		(layer "B.Cu")
		(net "P3E_CPU1_PE3_MP_RXN<11>")
	)
	(segment
		(start 134.754874 -100.766118)
		(end 134.748524 -100.776786)
		(width 0.0889)
		(layer "B.Cu")
		(net "P3E_CPU1_PE3_MP_RXN<11>")
	)
	(segment
		(start 134.743698 -102.1588)
		(end 134.748524 -102.167436)
		(width 0.0889)
		(layer "B.Cu")
		(net "P3E_CPU1_PE3_MP_RXN<11>")
	)
	(segment
		(start 134.743698 -96.2152)
		(end 134.748524 -96.223836)
		(width 0.0889)
		(layer "B.Cu")
		(net "P3E_CPU1_PE3_MP_RXN<11>")
	)
	(segment
		(start 20.454366 -120.212612)
		(end 15.517114 -115.275614)
		(width 0.1143)
		(layer "B.Cu")
		(net "P3E_CPU1_PE3_MP_RXN<11>")
	)
	(segment
		(start 109.044994 -122.018552)
		(end 102.144576 -120.63857)
		(width 0.1143)
		(layer "B.Cu")
		(net "P3E_CPU1_PE3_MP_RXN<11>")
	)
	(arc
		(start 134.748524 -96.814386)
		(mid 134.695054 -97.009449)
		(end 134.743698 -97.2058)
		(width 0.0889)
		(layer "B.Cu")
		(net "P3E_CPU1_PE3_MP_RXN<11>")
	)
	(arc
		(start 134.754874 -99.206304)
		(mid 134.827672 -99.497067)
		(end 134.748524 -99.786186)
		(width 0.0889)
		(layer "B.Cu")
		(net "P3E_CPU1_PE3_MP_RXN<11>")
	)
	(arc
		(start 134.748524 -100.186236)
		(mid 134.827746 -100.475354)
		(end 134.754874 -100.766118)
		(width 0.0889)
		(layer "B.Cu")
		(net "P3E_CPU1_PE3_MP_RXN<11>")
	)
	(arc
		(start 134.748524 -102.757986)
		(mid 134.694898 -102.958138)
		(end 134.748524 -103.15829)
		(width 0.0889)
		(layer "B.Cu")
		(net "P3E_CPU1_PE3_MP_RXN<11>")
	)
	(arc
		(start 134.723378 -93.89491)
		(mid 134.695808 -94.066713)
		(end 134.743698 -94.234)
		(width 0.0889)
		(layer "B.Cu")
		(net "P3E_CPU1_PE3_MP_RXN<11>")
	)
	(arc
		(start 134.754874 -102.178104)
		(mid 134.827672 -102.468867)
		(end 134.748524 -102.757986)
		(width 0.0889)
		(layer "B.Cu")
		(net "P3E_CPU1_PE3_MP_RXN<11>")
	)
	(arc
		(start 134.748524 -95.823786)
		(mid 134.695054 -96.018849)
		(end 134.743698 -96.2152)
		(width 0.0889)
		(layer "B.Cu")
		(net "P3E_CPU1_PE3_MP_RXN<11>")
	)
	(arc
		(start 134.754874 -97.225104)
		(mid 134.827672 -97.515867)
		(end 134.748524 -97.804986)
		(width 0.0889)
		(layer "B.Cu")
		(net "P3E_CPU1_PE3_MP_RXN<11>")
	)
	(arc
		(start 134.748524 -98.795586)
		(mid 134.695054 -98.990649)
		(end 134.743698 -99.187)
		(width 0.0889)
		(layer "B.Cu")
		(net "P3E_CPU1_PE3_MP_RXN<11>")
	)
	(arc
		(start 134.748524 -101.767386)
		(mid 134.695054 -101.962449)
		(end 134.743698 -102.1588)
		(width 0.0889)
		(layer "B.Cu")
		(net "P3E_CPU1_PE3_MP_RXN<11>")
	)
	(arc
		(start 134.748524 -94.242636)
		(mid 134.827746 -94.531754)
		(end 134.754874 -94.822518)
		(width 0.0889)
		(layer "B.Cu")
		(net "P3E_CPU1_PE3_MP_RXN<11>")
	)
	(arc
		(start 134.754874 -98.215704)
		(mid 134.827672 -98.506467)
		(end 134.748524 -98.795586)
		(width 0.0889)
		(layer "B.Cu")
		(net "P3E_CPU1_PE3_MP_RXN<11>")
	)
	(arc
		(start 134.748524 -95.232982)
		(mid 134.827655 -95.528384)
		(end 134.748524 -95.823786)
		(width 0.0889)
		(layer "B.Cu")
		(net "P3E_CPU1_PE3_MP_RXN<11>")
	)
	(arc
		(start 134.748524 -101.176582)
		(mid 134.827655 -101.471984)
		(end 134.748524 -101.767386)
		(width 0.0889)
		(layer "B.Cu")
		(net "P3E_CPU1_PE3_MP_RXN<11>")
	)
	(arc
		(start 134.748524 -97.804986)
		(mid 134.695054 -98.000049)
		(end 134.743698 -98.1964)
		(width 0.0889)
		(layer "B.Cu")
		(net "P3E_CPU1_PE3_MP_RXN<11>")
	)
	(arc
		(start 134.748524 -94.833186)
		(mid 134.695025 -95.033084)
		(end 134.748524 -95.232982)
		(width 0.0889)
		(layer "B.Cu")
		(net "P3E_CPU1_PE3_MP_RXN<11>")
	)
	(arc
		(start 134.748524 -99.786186)
		(mid 134.695054 -99.981249)
		(end 134.743698 -100.1776)
		(width 0.0889)
		(layer "B.Cu")
		(net "P3E_CPU1_PE3_MP_RXN<11>")
	)
	(arc
		(start 134.754874 -96.234504)
		(mid 134.827672 -96.525267)
		(end 134.748524 -96.814386)
		(width 0.0889)
		(layer "B.Cu")
		(net "P3E_CPU1_PE3_MP_RXN<11>")
	)
	(arc
		(start 134.748524 -100.776786)
		(mid 134.695025 -100.976684)
		(end 134.748524 -101.176582)
		(width 0.0889)
		(layer "B.Cu")
		(net "P3E_CPU1_PE3_MP_RXN<11>")
	)
	(segment
		(start 3.5433 -107.286552)
		(end 3.90144 -106.69778)
		(width 0.1143)
		(layer "In4.Cu")
		(net "P3E_CPU1_PE3_MP_RXN<11>")
	)
	(segment
		(start -1.547114 -103.921052)
		(end -2.04597 -103.422196)
		(width 0.1143)
		(layer "In4.Cu")
		(net "P3E_CPU1_PE3_MP_RXN<11>")
	)
	(segment
		(start 3.5433 -107.7976)
		(end 3.5433 -107.286552)
		(width 0.1143)
		(layer "In4.Cu")
		(net "P3E_CPU1_PE3_MP_RXN<11>")
	)
	(segment
		(start 3.429 -107.9119)
		(end 3.5433 -107.7976)
		(width 0.1143)
		(layer "In4.Cu")
		(net "P3E_CPU1_PE3_MP_RXN<11>")
	)
	(segment
		(start 7.426706 -103.921052)
		(end -1.547114 -103.921052)
		(width 0.1143)
		(layer "In4.Cu")
		(net "P3E_CPU1_PE3_MP_RXN<11>")
	)
	(segment
		(start -2.04597 -102.884224)
		(end -2.16027 -102.769924)
		(width 0.1143)
		(layer "In4.Cu")
		(net "P3E_CPU1_PE3_MP_RXN<11>")
	)
	(segment
		(start 7.9756 -105.068624)
		(end 7.9756 -104.469946)
		(width 0.1143)
		(layer "In4.Cu")
		(net "P3E_CPU1_PE3_MP_RXN<11>")
	)
	(segment
		(start 3.05435 -107.9119)
		(end 3.429 -107.9119)
		(width 0.1143)
		(layer "In4.Cu")
		(net "P3E_CPU1_PE3_MP_RXN<11>")
	)
	(segment
		(start 7.38759 -105.656888)
		(end 7.9756 -105.068624)
		(width 0.1143)
		(layer "In4.Cu")
		(net "P3E_CPU1_PE3_MP_RXN<11>")
	)
	(segment
		(start 3.90144 -106.69778)
		(end 7.38759 -105.656888)
		(width 0.1143)
		(layer "In4.Cu")
		(net "P3E_CPU1_PE3_MP_RXN<11>")
	)
	(segment
		(start 7.9756 -104.469946)
		(end 7.426706 -103.921052)
		(width 0.1143)
		(layer "In4.Cu")
		(net "P3E_CPU1_PE3_MP_RXN<11>")
	)
	(segment
		(start -2.04597 -103.422196)
		(end -2.04597 -102.884224)
		(width 0.1143)
		(layer "In4.Cu")
		(net "P3E_CPU1_PE3_MP_RXN<11>")
	)
	(segment
		(start -2.16027 -102.769924)
		(end -2.599944 -102.769924)
		(width 0.1143)
		(layer "In4.Cu")
		(net "P3E_CPU1_PE3_MP_RXN<11>")
	)
	(segment
		(start 132.806694 -94.042738)
		(end 133.378194 -94.042738)
		(width 0.1143)
		(layer "F.Cu")
		(net "P3E_CPU1_PE3_MP_RXN<10>")
	)
	(via
		(at 133.378194 -94.042738)
		(size 0.508)
		(drill 0.254)
		(layers "F.Cu" "B.Cu")
		(net "P3E_CPU1_PE3_MP_RXN<10>")
	)
	(segment
		(start 132.007864 -99.195636)
		(end 131.998974 -99.210876)
		(width 0.0889)
		(layer "B.Cu")
		(net "P3E_CPU1_PE3_MP_RXN<10>")
	)
	(segment
		(start 131.967224 -103.713788)
		(end 132.066284 -103.812848)
		(width 0.0889)
		(layer "B.Cu")
		(net "P3E_CPU1_PE3_MP_RXN<10>")
	)
	(segment
		(start 129.38125 -116.19865)
		(end 129.044954 -116.26596)
		(width 0.1143)
		(layer "B.Cu")
		(net "P3E_CPU1_PE3_MP_RXN<10>")
	)
	(segment
		(start 126.69139 -116.736622)
		(end 122.351546 -117.60454)
		(width 0.1143)
		(layer "B.Cu")
		(net "P3E_CPU1_PE3_MP_RXN<10>")
	)
	(segment
		(start 128.910588 -116.176298)
		(end 128.574292 -116.243608)
		(width 0.1143)
		(layer "B.Cu")
		(net "P3E_CPU1_PE3_MP_RXN<10>")
	)
	(segment
		(start 8.932672 -108.490766)
		(end 8.070596 -106.411268)
		(width 0.1143)
		(layer "B.Cu")
		(net "P3E_CPU1_PE3_MP_RXN<10>")
	)
	(segment
		(start 132.008118 -101.76764)
		(end 132.012944 -101.776276)
		(width 0.0889)
		(layer "B.Cu")
		(net "P3E_CPU1_PE3_MP_RXN<10>")
	)
	(segment
		(start 126.781052 -116.602256)
		(end 126.69139 -116.736622)
		(width 0.1143)
		(layer "B.Cu")
		(net "P3E_CPU1_PE3_MP_RXN<10>")
	)
	(segment
		(start 73.705212 -116.566442)
		(end 65.52311 -118.20271)
		(width 0.1143)
		(layer "B.Cu")
		(net "P3E_CPU1_PE3_MP_RXN<10>")
	)
	(segment
		(start 132.007864 -96.223836)
		(end 131.998974 -96.239076)
		(width 0.0889)
		(layer "B.Cu")
		(net "P3E_CPU1_PE3_MP_RXN<10>")
	)
	(segment
		(start 129.044954 -116.26596)
		(end 128.910588 -116.176298)
		(width 0.1143)
		(layer "B.Cu")
		(net "P3E_CPU1_PE3_MP_RXN<10>")
	)
	(segment
		(start 132.066284 -106.043222)
		(end 131.661408 -106.448098)
		(width 0.0889)
		(layer "B.Cu")
		(net "P3E_CPU1_PE3_MP_RXN<10>")
	)
	(segment
		(start 69.626734 -116.48694)
		(end 69.50964 -115.902994)
		(width 0.1143)
		(layer "B.Cu")
		(net "P3E_CPU1_PE3_MP_RXN<10>")
	)
	(segment
		(start 131.967224 -104.821228)
		(end 132.066284 -104.920288)
		(width 0.0889)
		(layer "B.Cu")
		(net "P3E_CPU1_PE3_MP_RXN<10>")
	)
	(segment
		(start 131.636008 -106.867706)
		(end 131.636008 -113.944146)
		(width 0.1143)
		(layer "B.Cu")
		(net "P3E_CPU1_PE3_MP_RXN<10>")
	)
	(segment
		(start 132.066284 -103.812848)
		(end 132.066284 -103.990648)
		(width 0.0889)
		(layer "B.Cu")
		(net "P3E_CPU1_PE3_MP_RXN<10>")
	)
	(segment
		(start 69.50964 -115.902994)
		(end 69.209158 -115.702588)
		(width 0.1143)
		(layer "B.Cu")
		(net "P3E_CPU1_PE3_MP_RXN<10>")
	)
	(segment
		(start 131.661408 -106.820208)
		(end 131.636008 -106.845608)
		(width 0.0889)
		(layer "B.Cu")
		(net "P3E_CPU1_PE3_MP_RXN<10>")
	)
	(segment
		(start 132.007864 -98.205036)
		(end 131.998974 -98.220276)
		(width 0.0889)
		(layer "B.Cu")
		(net "P3E_CPU1_PE3_MP_RXN<10>")
	)
	(segment
		(start 69.209158 -115.702588)
		(end 64.237616 -116.696998)
		(width 0.1143)
		(layer "B.Cu")
		(net "P3E_CPU1_PE3_MP_RXN<10>")
	)
	(segment
		(start 127.251714 -116.624608)
		(end 127.117348 -116.534946)
		(width 0.1143)
		(layer "B.Cu")
		(net "P3E_CPU1_PE3_MP_RXN<10>")
	)
	(segment
		(start 131.967224 -104.267508)
		(end 132.066284 -104.366568)
		(width 0.0889)
		(layer "B.Cu")
		(net "P3E_CPU1_PE3_MP_RXN<10>")
	)
	(segment
		(start 131.636008 -106.845608)
		(end 131.636008 -106.867706)
		(width 0.0889)
		(layer "B.Cu")
		(net "P3E_CPU1_PE3_MP_RXN<10>")
	)
	(segment
		(start 128.013968 -116.355622)
		(end 127.677672 -116.422932)
		(width 0.1143)
		(layer "B.Cu")
		(net "P3E_CPU1_PE3_MP_RXN<10>")
	)
	(segment
		(start 127.117348 -116.534946)
		(end 126.781052 -116.602256)
		(width 0.1143)
		(layer "B.Cu")
		(net "P3E_CPU1_PE3_MP_RXN<10>")
	)
	(segment
		(start 64.304164 -118.330218)
		(end 64.214502 -118.464584)
		(width 0.1143)
		(layer "B.Cu")
		(net "P3E_CPU1_PE3_MP_RXN<10>")
	)
	(segment
		(start 131.967224 -103.535988)
		(end 131.967224 -103.713788)
		(width 0.0889)
		(layer "B.Cu")
		(net "P3E_CPU1_PE3_MP_RXN<10>")
	)
	(segment
		(start 132.066284 -104.920288)
		(end 132.066284 -106.043222)
		(width 0.0889)
		(layer "B.Cu")
		(net "P3E_CPU1_PE3_MP_RXN<10>")
	)
	(segment
		(start 60.7441 -117.919754)
		(end 34.440622 -120.5103)
		(width 0.1143)
		(layer "B.Cu")
		(net "P3E_CPU1_PE3_MP_RXN<10>")
	)
	(segment
		(start 69.426328 -116.787422)
		(end 69.626734 -116.48694)
		(width 0.1143)
		(layer "B.Cu")
		(net "P3E_CPU1_PE3_MP_RXN<10>")
	)
	(segment
		(start 64.237616 -116.696998)
		(end 64.03721 -116.99748)
		(width 0.1143)
		(layer "B.Cu")
		(net "P3E_CPU1_PE3_MP_RXN<10>")
	)
	(segment
		(start 132.001768 -101.756972)
		(end 132.008118 -101.76764)
		(width 0.0889)
		(layer "B.Cu")
		(net "P3E_CPU1_PE3_MP_RXN<10>")
	)
	(segment
		(start 65.311274 -117.726714)
		(end 65.400936 -117.592348)
		(width 0.1143)
		(layer "B.Cu")
		(net "P3E_CPU1_PE3_MP_RXN<10>")
	)
	(segment
		(start 82.253328 -118.276116)
		(end 73.705212 -116.566442)
		(width 0.1143)
		(layer "B.Cu")
		(net "P3E_CPU1_PE3_MP_RXN<10>")
	)
	(segment
		(start 132.066284 -103.990648)
		(end 131.967224 -104.089708)
		(width 0.0889)
		(layer "B.Cu")
		(net "P3E_CPU1_PE3_MP_RXN<10>")
	)
	(segment
		(start 132.007864 -97.214436)
		(end 131.998974 -97.229676)
		(width 0.0889)
		(layer "B.Cu")
		(net "P3E_CPU1_PE3_MP_RXN<10>")
	)
	(segment
		(start 22.195536 -117.476778)
		(end 17.343628 -112.624108)
		(width 0.1143)
		(layer "B.Cu")
		(net "P3E_CPU1_PE3_MP_RXN<10>")
	)
	(segment
		(start 30.673548 -120.5103)
		(end 22.195536 -117.476778)
		(width 0.1143)
		(layer "B.Cu")
		(net "P3E_CPU1_PE3_MP_RXN<10>")
	)
	(segment
		(start 122.351546 -117.60454)
		(end 116.6749 -116.469668)
		(width 0.1143)
		(layer "B.Cu")
		(net "P3E_CPU1_PE3_MP_RXN<10>")
	)
	(segment
		(start 131.967224 -104.643428)
		(end 131.967224 -104.821228)
		(width 0.0889)
		(layer "B.Cu")
		(net "P3E_CPU1_PE3_MP_RXN<10>")
	)
	(segment
		(start 132.066284 -102.841806)
		(end 132.066284 -103.436928)
		(width 0.0889)
		(layer "B.Cu")
		(net "P3E_CPU1_PE3_MP_RXN<10>")
	)
	(segment
		(start 127.677672 -116.422932)
		(end 127.58801 -116.557298)
		(width 0.1143)
		(layer "B.Cu")
		(net "P3E_CPU1_PE3_MP_RXN<10>")
	)
	(segment
		(start 128.48463 -116.377974)
		(end 128.148334 -116.445284)
		(width 0.1143)
		(layer "B.Cu")
		(net "P3E_CPU1_PE3_MP_RXN<10>")
	)
	(segment
		(start 131.967224 -104.089708)
		(end 131.967224 -104.267508)
		(width 0.0889)
		(layer "B.Cu")
		(net "P3E_CPU1_PE3_MP_RXN<10>")
	)
	(segment
		(start 102.959916 -116.841524)
		(end 97.572068 -117.919246)
		(width 0.1143)
		(layer "B.Cu")
		(net "P3E_CPU1_PE3_MP_RXN<10>")
	)
	(segment
		(start 90.805 -116.565934)
		(end 82.253328 -118.276116)
		(width 0.1143)
		(layer "B.Cu")
		(net "P3E_CPU1_PE3_MP_RXN<10>")
	)
	(segment
		(start 128.148334 -116.445284)
		(end 128.013968 -116.355622)
		(width 0.1143)
		(layer "B.Cu")
		(net "P3E_CPU1_PE3_MP_RXN<10>")
	)
	(segment
		(start 132.066284 -103.436928)
		(end 131.967224 -103.535988)
		(width 0.0889)
		(layer "B.Cu")
		(net "P3E_CPU1_PE3_MP_RXN<10>")
	)
	(segment
		(start 97.572068 -117.919246)
		(end 90.805 -116.565934)
		(width 0.1143)
		(layer "B.Cu")
		(net "P3E_CPU1_PE3_MP_RXN<10>")
	)
	(segment
		(start 34.440622 -120.5103)
		(end 30.673548 -120.5103)
		(width 0.1143)
		(layer "B.Cu")
		(net "P3E_CPU1_PE3_MP_RXN<10>")
	)
	(segment
		(start 5.320792 -104.88422)
		(end 5.435092 -104.76992)
		(width 0.1143)
		(layer "B.Cu")
		(net "P3E_CPU1_PE3_MP_RXN<10>")
	)
	(segment
		(start 132.066284 -104.544368)
		(end 131.967224 -104.643428)
		(width 0.0889)
		(layer "B.Cu")
		(net "P3E_CPU1_PE3_MP_RXN<10>")
	)
	(segment
		(start 128.574292 -116.243608)
		(end 128.48463 -116.377974)
		(width 0.1143)
		(layer "B.Cu")
		(net "P3E_CPU1_PE3_MP_RXN<10>")
	)
	(segment
		(start 65.52311 -118.20271)
		(end 65.388744 -118.113048)
		(width 0.1143)
		(layer "B.Cu")
		(net "P3E_CPU1_PE3_MP_RXN<10>")
	)
	(segment
		(start 5.665216 -105.390442)
		(end 5.320792 -105.046018)
		(width 0.1143)
		(layer "B.Cu")
		(net "P3E_CPU1_PE3_MP_RXN<10>")
	)
	(segment
		(start 5.435092 -104.76992)
		(end 5.899912 -104.76992)
		(width 0.1143)
		(layer "B.Cu")
		(net "P3E_CPU1_PE3_MP_RXN<10>")
	)
	(segment
		(start 132.066284 -104.366568)
		(end 132.066284 -104.544368)
		(width 0.0889)
		(layer "B.Cu")
		(net "P3E_CPU1_PE3_MP_RXN<10>")
	)
	(segment
		(start 10.04062 -109.598714)
		(end 8.932672 -108.490766)
		(width 0.1143)
		(layer "B.Cu")
		(net "P3E_CPU1_PE3_MP_RXN<10>")
	)
	(segment
		(start 127.58801 -116.557298)
		(end 127.251714 -116.624608)
		(width 0.1143)
		(layer "B.Cu")
		(net "P3E_CPU1_PE3_MP_RXN<10>")
	)
	(segment
		(start 133.396228 -94.442534)
		(end 133.360414 -94.442534)
		(width 0.0889)
		(layer "B.Cu")
		(net "P3E_CPU1_PE3_MP_RXN<10>")
	)
	(segment
		(start 65.400936 -117.592348)
		(end 69.426328 -116.787422)
		(width 0.1143)
		(layer "B.Cu")
		(net "P3E_CPU1_PE3_MP_RXN<10>")
	)
	(segment
		(start 64.214502 -118.464584)
		(end 63.84163 -118.53926)
		(width 0.1143)
		(layer "B.Cu")
		(net "P3E_CPU1_PE3_MP_RXN<10>")
	)
	(segment
		(start 5.320792 -105.046018)
		(end 5.320792 -104.88422)
		(width 0.1143)
		(layer "B.Cu")
		(net "P3E_CPU1_PE3_MP_RXN<10>")
	)
	(segment
		(start 64.03721 -116.99748)
		(end 64.304164 -118.330218)
		(width 0.1143)
		(layer "B.Cu")
		(net "P3E_CPU1_PE3_MP_RXN<10>")
	)
	(segment
		(start 132.537708 -94.937834)
		(end 132.498084 -94.937834)
		(width 0.0889)
		(layer "B.Cu")
		(net "P3E_CPU1_PE3_MP_RXN<10>")
	)
	(segment
		(start 65.388744 -118.113048)
		(end 65.311274 -117.726714)
		(width 0.1143)
		(layer "B.Cu")
		(net "P3E_CPU1_PE3_MP_RXN<10>")
	)
	(segment
		(start 131.661408 -106.448098)
		(end 131.661408 -106.820208)
		(width 0.0889)
		(layer "B.Cu")
		(net "P3E_CPU1_PE3_MP_RXN<10>")
	)
	(segment
		(start 8.070596 -106.411268)
		(end 6.071616 -105.390442)
		(width 0.1143)
		(layer "B.Cu")
		(net "P3E_CPU1_PE3_MP_RXN<10>")
	)
	(segment
		(start 63.84163 -118.53926)
		(end 60.7441 -117.919754)
		(width 0.1143)
		(layer "B.Cu")
		(net "P3E_CPU1_PE3_MP_RXN<10>")
	)
	(segment
		(start 17.343628 -112.624108)
		(end 10.04062 -109.598714)
		(width 0.1143)
		(layer "B.Cu")
		(net "P3E_CPU1_PE3_MP_RXN<10>")
	)
	(segment
		(start 133.378194 -93.704664)
		(end 133.436106 -93.646752)
		(width 0.0889)
		(layer "B.Cu")
		(net "P3E_CPU1_PE3_MP_RXN<10>")
	)
	(segment
		(start 133.378194 -94.042738)
		(end 133.378194 -93.704664)
		(width 0.0889)
		(layer "B.Cu")
		(net "P3E_CPU1_PE3_MP_RXN<10>")
	)
	(segment
		(start 6.071616 -105.390442)
		(end 5.665216 -105.390442)
		(width 0.1143)
		(layer "B.Cu")
		(net "P3E_CPU1_PE3_MP_RXN<10>")
	)
	(segment
		(start 131.636008 -113.944146)
		(end 129.38125 -116.19865)
		(width 0.1143)
		(layer "B.Cu")
		(net "P3E_CPU1_PE3_MP_RXN<10>")
	)
	(segment
		(start 116.6749 -116.469668)
		(end 108.887514 -118.026942)
		(width 0.1143)
		(layer "B.Cu")
		(net "P3E_CPU1_PE3_MP_RXN<10>")
	)
	(segment
		(start 132.046726 -102.815898)
		(end 132.066284 -102.841806)
		(width 0.0889)
		(layer "B.Cu")
		(net "P3E_CPU1_PE3_MP_RXN<10>")
	)
	(segment
		(start 108.887514 -118.026942)
		(end 102.959916 -116.841524)
		(width 0.1143)
		(layer "B.Cu")
		(net "P3E_CPU1_PE3_MP_RXN<10>")
	)
	(arc
		(start 132.001514 -100.766118)
		(mid 132.061712 -100.970701)
		(end 132.008118 -101.17709)
		(width 0.0889)
		(layer "B.Cu")
		(net "P3E_CPU1_PE3_MP_RXN<10>")
	)
	(arc
		(start 131.998974 -96.239076)
		(mid 131.928577 -96.528027)
		(end 132.007864 -96.81464)
		(width 0.0889)
		(layer "B.Cu")
		(net "P3E_CPU1_PE3_MP_RXN<10>")
	)
	(arc
		(start 132.007864 -96.81464)
		(mid 132.061397 -97.014538)
		(end 132.007864 -97.214436)
		(width 0.0889)
		(layer "B.Cu")
		(net "P3E_CPU1_PE3_MP_RXN<10>")
	)
	(arc
		(start 132.007864 -97.80524)
		(mid 132.061397 -98.005138)
		(end 132.007864 -98.205036)
		(width 0.0889)
		(layer "B.Cu")
		(net "P3E_CPU1_PE3_MP_RXN<10>")
	)
	(arc
		(start 132.008118 -102.16769)
		(mid 131.930145 -102.497598)
		(end 132.046726 -102.815898)
		(width 0.0889)
		(layer "B.Cu")
		(net "P3E_CPU1_PE3_MP_RXN<10>")
	)
	(arc
		(start 132.007864 -100.186236)
		(mid 131.928642 -100.475354)
		(end 132.001514 -100.766118)
		(width 0.0889)
		(layer "B.Cu")
		(net "P3E_CPU1_PE3_MP_RXN<10>")
	)
	(arc
		(start 131.998974 -97.229676)
		(mid 131.928577 -97.518627)
		(end 132.007864 -97.80524)
		(width 0.0889)
		(layer "B.Cu")
		(net "P3E_CPU1_PE3_MP_RXN<10>")
	)
	(arc
		(start 131.998974 -99.210876)
		(mid 131.928577 -99.499827)
		(end 132.007864 -99.78644)
		(width 0.0889)
		(layer "B.Cu")
		(net "P3E_CPU1_PE3_MP_RXN<10>")
	)
	(arc
		(start 132.498084 -94.937834)
		(mid 132.002554 -95.242373)
		(end 132.007864 -95.82404)
		(width 0.0889)
		(layer "B.Cu")
		(net "P3E_CPU1_PE3_MP_RXN<10>")
	)
	(arc
		(start 131.998974 -98.220276)
		(mid 131.928577 -98.509227)
		(end 132.007864 -98.79584)
		(width 0.0889)
		(layer "B.Cu")
		(net "P3E_CPU1_PE3_MP_RXN<10>")
	)
	(arc
		(start 133.360414 -94.442534)
		(mid 133.07499 -94.526001)
		(end 132.866384 -94.737936)
		(width 0.0889)
		(layer "B.Cu")
		(net "P3E_CPU1_PE3_MP_RXN<10>")
	)
	(arc
		(start 133.436106 -93.646752)
		(mid 133.778108 -94.062767)
		(end 133.396228 -94.442534)
		(width 0.0889)
		(layer "B.Cu")
		(net "P3E_CPU1_PE3_MP_RXN<10>")
	)
	(arc
		(start 132.008118 -101.17709)
		(mid 131.928896 -101.466208)
		(end 132.001768 -101.756972)
		(width 0.0889)
		(layer "B.Cu")
		(net "P3E_CPU1_PE3_MP_RXN<10>")
	)
	(arc
		(start 132.012944 -101.776276)
		(mid 132.061699 -101.972628)
		(end 132.008118 -102.16769)
		(width 0.0889)
		(layer "B.Cu")
		(net "P3E_CPU1_PE3_MP_RXN<10>")
	)
	(arc
		(start 132.007864 -98.79584)
		(mid 132.061397 -98.995738)
		(end 132.007864 -99.195636)
		(width 0.0889)
		(layer "B.Cu")
		(net "P3E_CPU1_PE3_MP_RXN<10>")
	)
	(arc
		(start 132.007864 -99.78644)
		(mid 132.061397 -99.986338)
		(end 132.007864 -100.186236)
		(width 0.0889)
		(layer "B.Cu")
		(net "P3E_CPU1_PE3_MP_RXN<10>")
	)
	(arc
		(start 132.007864 -95.82404)
		(mid 132.061397 -96.023938)
		(end 132.007864 -96.223836)
		(width 0.0889)
		(layer "B.Cu")
		(net "P3E_CPU1_PE3_MP_RXN<10>")
	)
	(arc
		(start 132.866384 -94.737936)
		(mid 132.72764 -94.879969)
		(end 132.537708 -94.937834)
		(width 0.0889)
		(layer "B.Cu")
		(net "P3E_CPU1_PE3_MP_RXN<10>")
	)
	(segment
		(start 394.1064 -0.2286)
		(end 394.1064 -0.6858)
		(width 0.10795)
		(layer "F.Cu")
		(net "JTAG_PCH_GBE_TMS")
	)
	(segment
		(start 401.295108 -102.855014)
		(end 402.134832 -102.855014)
		(width 0.10795)
		(layer "F.Cu")
		(net "JTAG_PCH_GBE_TMS")
	)
	(segment
		(start 394.1064 -0.6858)
		(end 394.2842 -0.8636)
		(width 0.10795)
		(layer "F.Cu")
		(net "JTAG_PCH_GBE_TMS")
	)
	(via
		(at 455.041 -6.837172)
		(size 0.508)
		(drill 0.254)
		(layers "F.Cu" "B.Cu")
		(net "JTAG_PCH_GBE_TMS")
	)
	(via
		(at 402.134832 -102.855014)
		(size 0.508)
		(drill 0.254)
		(layers "F.Cu" "B.Cu")
		(net "JTAG_PCH_GBE_TMS")
	)
	(via
		(at 394.2842 -0.8636)
		(size 0.508)
		(drill 0.254)
		(layers "F.Cu" "B.Cu")
		(net "JTAG_PCH_GBE_TMS")
	)
	(segment
		(start 412.727394 1.24079)
		(end 412.326582 1.24079)
		(width 0.089408)
		(layer "In4.Cu")
		(net "JTAG_PCH_GBE_TMS")
	)
	(segment
		(start 403.934676 0.818388)
		(end 402.005546 0.818388)
		(width 0.089408)
		(layer "In4.Cu")
		(net "JTAG_PCH_GBE_TMS")
	)
	(segment
		(start 412.326582 1.24079)
		(end 411.752796 1.814576)
		(width 0.089408)
		(layer "In4.Cu")
		(net "JTAG_PCH_GBE_TMS")
	)
	(segment
		(start 401.787614 1.03632)
		(end 400.346418 1.03632)
		(width 0.089408)
		(layer "In4.Cu")
		(net "JTAG_PCH_GBE_TMS")
	)
	(segment
		(start 404.335742 0.818134)
		(end 403.93493 0.818134)
		(width 0.089408)
		(layer "In4.Cu")
		(net "JTAG_PCH_GBE_TMS")
	)
	(segment
		(start 405.332184 1.814576)
		(end 404.335742 0.818134)
		(width 0.089408)
		(layer "In4.Cu")
		(net "JTAG_PCH_GBE_TMS")
	)
	(segment
		(start 450.113146 -0.682244)
		(end 431.789078 -0.682244)
		(width 0.089408)
		(layer "In4.Cu")
		(net "JTAG_PCH_GBE_TMS")
	)
	(segment
		(start 455.041 -5.610098)
		(end 450.113146 -0.682244)
		(width 0.089408)
		(layer "In4.Cu")
		(net "JTAG_PCH_GBE_TMS")
	)
	(segment
		(start 420.892732 2.543302)
		(end 415.773362 2.543302)
		(width 0.089408)
		(layer "In4.Cu")
		(net "JTAG_PCH_GBE_TMS")
	)
	(segment
		(start 422.420034 1.016)
		(end 420.892732 2.543302)
		(width 0.089408)
		(layer "In4.Cu")
		(net "JTAG_PCH_GBE_TMS")
	)
	(segment
		(start 403.93493 0.818134)
		(end 403.934676 0.818388)
		(width 0.089408)
		(layer "In4.Cu")
		(net "JTAG_PCH_GBE_TMS")
	)
	(segment
		(start 430.090834 1.016)
		(end 422.420034 1.016)
		(width 0.089408)
		(layer "In4.Cu")
		(net "JTAG_PCH_GBE_TMS")
	)
	(segment
		(start 431.789078 -0.682244)
		(end 430.090834 1.016)
		(width 0.089408)
		(layer "In4.Cu")
		(net "JTAG_PCH_GBE_TMS")
	)
	(segment
		(start 411.752796 1.814576)
		(end 405.332184 1.814576)
		(width 0.089408)
		(layer "In4.Cu")
		(net "JTAG_PCH_GBE_TMS")
	)
	(segment
		(start 402.005546 0.818388)
		(end 401.787614 1.03632)
		(width 0.089408)
		(layer "In4.Cu")
		(net "JTAG_PCH_GBE_TMS")
	)
	(segment
		(start 455.041 -6.837172)
		(end 455.041 -5.610098)
		(width 0.089408)
		(layer "In4.Cu")
		(net "JTAG_PCH_GBE_TMS")
	)
	(segment
		(start 400.117818 1.26492)
		(end 396.41272 1.26492)
		(width 0.089408)
		(layer "In4.Cu")
		(net "JTAG_PCH_GBE_TMS")
	)
	(segment
		(start 412.727648 1.241044)
		(end 412.727394 1.24079)
		(width 0.089408)
		(layer "In4.Cu")
		(net "JTAG_PCH_GBE_TMS")
	)
	(segment
		(start 414.471104 1.241044)
		(end 412.727648 1.241044)
		(width 0.089408)
		(layer "In4.Cu")
		(net "JTAG_PCH_GBE_TMS")
	)
	(segment
		(start 396.41272 1.26492)
		(end 394.2842 -0.8636)
		(width 0.089408)
		(layer "In4.Cu")
		(net "JTAG_PCH_GBE_TMS")
	)
	(segment
		(start 415.773362 2.543302)
		(end 414.471104 1.241044)
		(width 0.089408)
		(layer "In4.Cu")
		(net "JTAG_PCH_GBE_TMS")
	)
	(segment
		(start 400.346418 1.03632)
		(end 400.117818 1.26492)
		(width 0.089408)
		(layer "In4.Cu")
		(net "JTAG_PCH_GBE_TMS")
	)
	(segment
		(start 454.651364 -7.226808)
		(end 454.34885 -7.226808)
		(width 0.089408)
		(layer "In11.Cu")
		(net "JTAG_PCH_GBE_TMS")
	)
	(segment
		(start 399.845784 -78.767178)
		(end 399.881852 -78.803246)
		(width 0.089408)
		(layer "In11.Cu")
		(net "JTAG_PCH_GBE_TMS")
	)
	(segment
		(start 394.731494 -58.156348)
		(end 394.731494 -64.098932)
		(width 0.089408)
		(layer "In11.Cu")
		(net "JTAG_PCH_GBE_TMS")
	)
	(segment
		(start 439.89498 -14.059916)
		(end 438.36336 -15.591536)
		(width 0.089408)
		(layer "In11.Cu")
		(net "JTAG_PCH_GBE_TMS")
	)
	(segment
		(start 402.37918 -99.14382)
		(end 402.0058 -99.5172)
		(width 0.089408)
		(layer "In11.Cu")
		(net "JTAG_PCH_GBE_TMS")
	)
	(segment
		(start 399.571718 -83.053428)
		(end 400.130772 -83.612482)
		(width 0.089408)
		(layer "In11.Cu")
		(net "JTAG_PCH_GBE_TMS")
	)
	(segment
		(start 400.77898 -15.054834)
		(end 399.976848 -15.054834)
		(width 0.089408)
		(layer "In11.Cu")
		(net "JTAG_PCH_GBE_TMS")
	)
	(segment
		(start 399.445734 -77.140054)
		(end 399.845784 -77.540104)
		(width 0.089408)
		(layer "In11.Cu")
		(net "JTAG_PCH_GBE_TMS")
	)
	(segment
		(start 384.377946 -45.085)
		(end 387.58622 -48.293274)
		(width 0.089408)
		(layer "In11.Cu")
		(net "JTAG_PCH_GBE_TMS")
	)
	(segment
		(start 454.34885 -7.226808)
		(end 452.72198 -8.853678)
		(width 0.089408)
		(layer "In11.Cu")
		(net "JTAG_PCH_GBE_TMS")
	)
	(segment
		(start 420.127938 -15.77975)
		(end 417.698428 -13.35024)
		(width 0.089408)
		(layer "In11.Cu")
		(net "JTAG_PCH_GBE_TMS")
	)
	(segment
		(start 402.37918 -92.891102)
		(end 402.37918 -99.14382)
		(width 0.089408)
		(layer "In11.Cu")
		(net "JTAG_PCH_GBE_TMS")
	)
	(segment
		(start 402.0058 -99.5172)
		(end 402.0058 -100.203)
		(width 0.089408)
		(layer "In11.Cu")
		(net "JTAG_PCH_GBE_TMS")
	)
	(segment
		(start 400.130772 -84.514436)
		(end 400.903948 -85.287612)
		(width 0.089408)
		(layer "In11.Cu")
		(net "JTAG_PCH_GBE_TMS")
	)
	(segment
		(start 431.868326 -15.77975)
		(end 420.127938 -15.77975)
		(width 0.089408)
		(layer "In11.Cu")
		(net "JTAG_PCH_GBE_TMS")
	)
	(segment
		(start 455.041 -6.837172)
		(end 454.651364 -7.226808)
		(width 0.089408)
		(layer "In11.Cu")
		(net "JTAG_PCH_GBE_TMS")
	)
	(segment
		(start 399.976594 -15.05458)
		(end 382.853184 -15.05458)
		(width 0.089408)
		(layer "In11.Cu")
		(net "JTAG_PCH_GBE_TMS")
	)
	(segment
		(start 378.75464 -41.373806)
		(end 382.465834 -45.085)
		(width 0.089408)
		(layer "In11.Cu")
		(net "JTAG_PCH_GBE_TMS")
	)
	(segment
		(start 379.088904 -37.751512)
		(end 378.27839 -38.562026)
		(width 0.089408)
		(layer "In11.Cu")
		(net "JTAG_PCH_GBE_TMS")
	)
	(segment
		(start 399.881852 -78.803246)
		(end 399.881852 -80.082898)
		(width 0.089408)
		(layer "In11.Cu")
		(net "JTAG_PCH_GBE_TMS")
	)
	(segment
		(start 432.05654 -15.591536)
		(end 431.868326 -15.77975)
		(width 0.089408)
		(layer "In11.Cu")
		(net "JTAG_PCH_GBE_TMS")
	)
	(segment
		(start 402.2598 -100.733352)
		(end 402.20138 -100.791772)
		(width 0.089408)
		(layer "In11.Cu")
		(net "JTAG_PCH_GBE_TMS")
	)
	(segment
		(start 400.130772 -83.612482)
		(end 400.130772 -84.514436)
		(width 0.089408)
		(layer "In11.Cu")
		(net "JTAG_PCH_GBE_TMS")
	)
	(segment
		(start 397.889222 -72.949562)
		(end 399.222976 -74.283316)
		(width 0.089408)
		(layer "In11.Cu")
		(net "JTAG_PCH_GBE_TMS")
	)
	(segment
		(start 402.20138 -102.788466)
		(end 402.134832 -102.855014)
		(width 0.089408)
		(layer "In11.Cu")
		(net "JTAG_PCH_GBE_TMS")
	)
	(segment
		(start 400.903948 -88.935306)
		(end 401.328636 -89.359994)
		(width 0.089408)
		(layer "In11.Cu")
		(net "JTAG_PCH_GBE_TMS")
	)
	(segment
		(start 379.68936 -18.757646)
		(end 375.821702 -22.625304)
		(width 0.089408)
		(layer "In11.Cu")
		(net "JTAG_PCH_GBE_TMS")
	)
	(segment
		(start 394.731494 -64.098932)
		(end 396.23365 -65.601088)
		(width 0.089408)
		(layer "In11.Cu")
		(net "JTAG_PCH_GBE_TMS")
	)
	(segment
		(start 399.976848 -15.054834)
		(end 399.976594 -15.05458)
		(width 0.089408)
		(layer "In11.Cu")
		(net "JTAG_PCH_GBE_TMS")
	)
	(segment
		(start 399.571718 -80.393032)
		(end 399.571718 -83.053428)
		(width 0.089408)
		(layer "In11.Cu")
		(net "JTAG_PCH_GBE_TMS")
	)
	(segment
		(start 402.0058 -100.203)
		(end 402.2598 -100.457)
		(width 0.089408)
		(layer "In11.Cu")
		(net "JTAG_PCH_GBE_TMS")
	)
	(segment
		(start 399.222976 -75.93203)
		(end 399.445734 -76.154788)
		(width 0.089408)
		(layer "In11.Cu")
		(net "JTAG_PCH_GBE_TMS")
	)
	(segment
		(start 438.36336 -15.591536)
		(end 432.05654 -15.591536)
		(width 0.089408)
		(layer "In11.Cu")
		(net "JTAG_PCH_GBE_TMS")
	)
	(segment
		(start 402.483574 -13.35024)
		(end 400.77898 -15.054834)
		(width 0.089408)
		(layer "In11.Cu")
		(net "JTAG_PCH_GBE_TMS")
	)
	(segment
		(start 397.889222 -72.01408)
		(end 397.889222 -72.949562)
		(width 0.089408)
		(layer "In11.Cu")
		(net "JTAG_PCH_GBE_TMS")
	)
	(segment
		(start 399.445734 -76.154788)
		(end 399.445734 -77.140054)
		(width 0.089408)
		(layer "In11.Cu")
		(net "JTAG_PCH_GBE_TMS")
	)
	(segment
		(start 378.27839 -38.562026)
		(end 378.27839 -39.812214)
		(width 0.089408)
		(layer "In11.Cu")
		(net "JTAG_PCH_GBE_TMS")
	)
	(segment
		(start 399.845784 -77.540104)
		(end 399.845784 -78.767178)
		(width 0.089408)
		(layer "In11.Cu")
		(net "JTAG_PCH_GBE_TMS")
	)
	(segment
		(start 396.23365 -70.358508)
		(end 397.889222 -72.01408)
		(width 0.089408)
		(layer "In11.Cu")
		(net "JTAG_PCH_GBE_TMS")
	)
	(segment
		(start 379.088904 -37.018976)
		(end 379.088904 -37.751512)
		(width 0.089408)
		(layer "In11.Cu")
		(net "JTAG_PCH_GBE_TMS")
	)
	(segment
		(start 378.75464 -40.288464)
		(end 378.75464 -41.373806)
		(width 0.089408)
		(layer "In11.Cu")
		(net "JTAG_PCH_GBE_TMS")
	)
	(segment
		(start 401.328636 -89.359994)
		(end 401.328636 -91.840558)
		(width 0.089408)
		(layer "In11.Cu")
		(net "JTAG_PCH_GBE_TMS")
	)
	(segment
		(start 417.698428 -13.35024)
		(end 402.483574 -13.35024)
		(width 0.089408)
		(layer "In11.Cu")
		(net "JTAG_PCH_GBE_TMS")
	)
	(segment
		(start 396.23365 -65.601088)
		(end 396.23365 -70.358508)
		(width 0.089408)
		(layer "In11.Cu")
		(net "JTAG_PCH_GBE_TMS")
	)
	(segment
		(start 402.2598 -100.457)
		(end 402.2598 -100.733352)
		(width 0.089408)
		(layer "In11.Cu")
		(net "JTAG_PCH_GBE_TMS")
	)
	(segment
		(start 451.112382 -8.853678)
		(end 445.906144 -14.059916)
		(width 0.089408)
		(layer "In11.Cu")
		(net "JTAG_PCH_GBE_TMS")
	)
	(segment
		(start 379.68936 -18.218404)
		(end 379.68936 -18.757646)
		(width 0.089408)
		(layer "In11.Cu")
		(net "JTAG_PCH_GBE_TMS")
	)
	(segment
		(start 399.222976 -74.283316)
		(end 399.222976 -75.93203)
		(width 0.089408)
		(layer "In11.Cu")
		(net "JTAG_PCH_GBE_TMS")
	)
	(segment
		(start 402.20138 -100.791772)
		(end 402.20138 -102.788466)
		(width 0.089408)
		(layer "In11.Cu")
		(net "JTAG_PCH_GBE_TMS")
	)
	(segment
		(start 382.465834 -45.085)
		(end 384.377946 -45.085)
		(width 0.089408)
		(layer "In11.Cu")
		(net "JTAG_PCH_GBE_TMS")
	)
	(segment
		(start 400.903948 -85.287612)
		(end 400.903948 -88.935306)
		(width 0.089408)
		(layer "In11.Cu")
		(net "JTAG_PCH_GBE_TMS")
	)
	(segment
		(start 388.891526 -50.60315)
		(end 388.891526 -52.31638)
		(width 0.089408)
		(layer "In11.Cu")
		(net "JTAG_PCH_GBE_TMS")
	)
	(segment
		(start 387.58622 -48.293274)
		(end 387.58622 -49.297844)
		(width 0.089408)
		(layer "In11.Cu")
		(net "JTAG_PCH_GBE_TMS")
	)
	(segment
		(start 401.328636 -91.840558)
		(end 402.37918 -92.891102)
		(width 0.089408)
		(layer "In11.Cu")
		(net "JTAG_PCH_GBE_TMS")
	)
	(segment
		(start 399.881852 -80.082898)
		(end 399.571718 -80.393032)
		(width 0.089408)
		(layer "In11.Cu")
		(net "JTAG_PCH_GBE_TMS")
	)
	(segment
		(start 387.58622 -49.297844)
		(end 388.891526 -50.60315)
		(width 0.089408)
		(layer "In11.Cu")
		(net "JTAG_PCH_GBE_TMS")
	)
	(segment
		(start 378.27839 -39.812214)
		(end 378.75464 -40.288464)
		(width 0.089408)
		(layer "In11.Cu")
		(net "JTAG_PCH_GBE_TMS")
	)
	(segment
		(start 388.891526 -52.31638)
		(end 394.731494 -58.156348)
		(width 0.089408)
		(layer "In11.Cu")
		(net "JTAG_PCH_GBE_TMS")
	)
	(segment
		(start 382.853184 -15.05458)
		(end 379.68936 -18.218404)
		(width 0.089408)
		(layer "In11.Cu")
		(net "JTAG_PCH_GBE_TMS")
	)
	(segment
		(start 452.72198 -8.853678)
		(end 451.112382 -8.853678)
		(width 0.089408)
		(layer "In11.Cu")
		(net "JTAG_PCH_GBE_TMS")
	)
	(segment
		(start 375.821702 -22.625304)
		(end 375.821702 -33.751774)
		(width 0.089408)
		(layer "In11.Cu")
		(net "JTAG_PCH_GBE_TMS")
	)
	(segment
		(start 445.906144 -14.059916)
		(end 439.89498 -14.059916)
		(width 0.089408)
		(layer "In11.Cu")
		(net "JTAG_PCH_GBE_TMS")
	)
	(segment
		(start 375.821702 -33.751774)
		(end 379.088904 -37.018976)
		(width 0.089408)
		(layer "In11.Cu")
		(net "JTAG_PCH_GBE_TMS")
	)
	(segment
		(start 404.007574 -102.376732)
		(end 403.754844 -102.124002)
		(width 0.10795)
		(layer "F.Cu")
		(net "JTAG_PCH_GBE_TDO")
	)
	(segment
		(start 401.54606 -101.79304)
		(end 401.484084 -101.855016)
		(width 0.0889)
		(layer "F.Cu")
		(net "JTAG_PCH_GBE_TDO")
	)
	(segment
		(start 403.322282 -102.006146)
		(end 403.109176 -101.79304)
		(width 0.0889)
		(layer "F.Cu")
		(net "JTAG_PCH_GBE_TDO")
	)
	(segment
		(start 403.109176 -101.79304)
		(end 401.54606 -101.79304)
		(width 0.0889)
		(layer "F.Cu")
		(net "JTAG_PCH_GBE_TDO")
	)
	(segment
		(start 401.484084 -101.855016)
		(end 401.295108 -101.855016)
		(width 0.0889)
		(layer "F.Cu")
		(net "JTAG_PCH_GBE_TDO")
	)
	(segment
		(start 403.754844 -102.124002)
		(end 403.636988 -102.006146)
		(width 0.0889)
		(layer "F.Cu")
		(net "JTAG_PCH_GBE_TDO")
	)
	(segment
		(start 404.007574 -102.65918)
		(end 404.007574 -102.376732)
		(width 0.10795)
		(layer "F.Cu")
		(net "JTAG_PCH_GBE_TDO")
	)
	(segment
		(start 403.636988 -102.006146)
		(end 403.322282 -102.006146)
		(width 0.0889)
		(layer "F.Cu")
		(net "JTAG_PCH_GBE_TDO")
	)
	(segment
		(start 385.2926 -0.254)
		(end 385.2926 -0.889)
		(width 0.10795)
		(layer "F.Cu")
		(net "JTAG_PCH_GBE_TDO")
	)
	(via
		(at 404.007574 -102.65918)
		(size 0.508)
		(drill 0.254)
		(layers "F.Cu" "B.Cu")
		(net "JTAG_PCH_GBE_TDO")
	)
	(via
		(at 385.2926 -0.889)
		(size 0.508)
		(drill 0.254)
		(layers "F.Cu" "B.Cu")
		(net "JTAG_PCH_GBE_TDO")
	)
	(via
		(at 467.687406 -5.494274)
		(size 0.508)
		(drill 0.254)
		(layers "F.Cu" "B.Cu")
		(net "JTAG_PCH_GBE_TDO")
	)
	(segment
		(start 458.628242 0.781304)
		(end 459.09865 0.310896)
		(width 0.089408)
		(layer "In2.Cu")
		(net "JTAG_PCH_GBE_TDO")
	)
	(segment
		(start 463.83702 0.310896)
		(end 464.0834 0.064516)
		(width 0.089408)
		(layer "In2.Cu")
		(net "JTAG_PCH_GBE_TDO")
	)
	(segment
		(start 425.549822 0.68072)
		(end 425.945046 0.285496)
		(width 0.089408)
		(layer "In2.Cu")
		(net "JTAG_PCH_GBE_TDO")
	)
	(segment
		(start 399.18767 1.042416)
		(end 404.54834 1.042416)
		(width 0.089408)
		(layer "In2.Cu")
		(net "JTAG_PCH_GBE_TDO")
	)
	(segment
		(start 459.09865 0.310896)
		(end 463.83702 0.310896)
		(width 0.089408)
		(layer "In2.Cu")
		(net "JTAG_PCH_GBE_TDO")
	)
	(segment
		(start 464.0834 -1.5494)
		(end 464.391248 -1.857248)
		(width 0.089408)
		(layer "In2.Cu")
		(net "JTAG_PCH_GBE_TDO")
	)
	(segment
		(start 388.94639 0.051054)
		(end 388.946644 0.0508)
		(width 0.089408)
		(layer "In2.Cu")
		(net "JTAG_PCH_GBE_TDO")
	)
	(segment
		(start 464.391248 -3.452876)
		(end 465.660486 -4.722114)
		(width 0.089408)
		(layer "In2.Cu")
		(net "JTAG_PCH_GBE_TDO")
	)
	(segment
		(start 457.587096 0.285496)
		(end 458.082904 0.781304)
		(width 0.089408)
		(layer "In2.Cu")
		(net "JTAG_PCH_GBE_TDO")
	)
	(segment
		(start 422.393872 0.68072)
		(end 425.549822 0.68072)
		(width 0.089408)
		(layer "In2.Cu")
		(net "JTAG_PCH_GBE_TDO")
	)
	(segment
		(start 404.54834 1.042416)
		(end 405.729948 2.224024)
		(width 0.089408)
		(layer "In2.Cu")
		(net "JTAG_PCH_GBE_TDO")
	)
	(segment
		(start 425.945046 0.285496)
		(end 457.587096 0.285496)
		(width 0.089408)
		(layer "In2.Cu")
		(net "JTAG_PCH_GBE_TDO")
	)
	(segment
		(start 385.2926 -0.889)
		(end 386.2324 0.0508)
		(width 0.089408)
		(layer "In2.Cu")
		(net "JTAG_PCH_GBE_TDO")
	)
	(segment
		(start 466.915246 -4.722114)
		(end 467.687406 -5.494274)
		(width 0.089408)
		(layer "In2.Cu")
		(net "JTAG_PCH_GBE_TDO")
	)
	(segment
		(start 464.0834 0.064516)
		(end 464.0834 -1.5494)
		(width 0.089408)
		(layer "In2.Cu")
		(net "JTAG_PCH_GBE_TDO")
	)
	(segment
		(start 420.850568 2.224024)
		(end 422.393872 0.68072)
		(width 0.089408)
		(layer "In2.Cu")
		(net "JTAG_PCH_GBE_TDO")
	)
	(segment
		(start 386.2324 0.0508)
		(end 388.545324 0.0508)
		(width 0.089408)
		(layer "In2.Cu")
		(net "JTAG_PCH_GBE_TDO")
	)
	(segment
		(start 388.545578 0.051054)
		(end 388.94639 0.051054)
		(width 0.089408)
		(layer "In2.Cu")
		(net "JTAG_PCH_GBE_TDO")
	)
	(segment
		(start 405.729948 2.224024)
		(end 420.850568 2.224024)
		(width 0.089408)
		(layer "In2.Cu")
		(net "JTAG_PCH_GBE_TDO")
	)
	(segment
		(start 458.082904 0.781304)
		(end 458.628242 0.781304)
		(width 0.089408)
		(layer "In2.Cu")
		(net "JTAG_PCH_GBE_TDO")
	)
	(segment
		(start 388.545324 0.0508)
		(end 388.545578 0.051054)
		(width 0.089408)
		(layer "In2.Cu")
		(net "JTAG_PCH_GBE_TDO")
	)
	(segment
		(start 464.391248 -1.857248)
		(end 464.391248 -3.452876)
		(width 0.089408)
		(layer "In2.Cu")
		(net "JTAG_PCH_GBE_TDO")
	)
	(segment
		(start 465.660486 -4.722114)
		(end 466.915246 -4.722114)
		(width 0.089408)
		(layer "In2.Cu")
		(net "JTAG_PCH_GBE_TDO")
	)
	(segment
		(start 388.946644 0.0508)
		(end 398.196054 0.0508)
		(width 0.089408)
		(layer "In2.Cu")
		(net "JTAG_PCH_GBE_TDO")
	)
	(segment
		(start 398.196054 0.0508)
		(end 399.18767 1.042416)
		(width 0.089408)
		(layer "In2.Cu")
		(net "JTAG_PCH_GBE_TDO")
	)
	(segment
		(start 400.963892 -104.248204)
		(end 400.963892 -95.691452)
		(width 0.089408)
		(layer "In11.Cu")
		(net "JTAG_PCH_GBE_TDO")
	)
	(segment
		(start 386.378958 -49.602898)
		(end 386.378958 -48.598328)
		(width 0.089408)
		(layer "In11.Cu")
		(net "JTAG_PCH_GBE_TDO")
	)
	(segment
		(start 400.277584 -14.329156)
		(end 400.277838 -14.32941)
		(width 0.089408)
		(layer "In11.Cu")
		(net "JTAG_PCH_GBE_TDO")
	)
	(segment
		(start 431.567336 -15.054326)
		(end 431.75555 -14.866112)
		(width 0.089408)
		(layer "In11.Cu")
		(net "JTAG_PCH_GBE_TDO")
	)
	(segment
		(start 400.47799 -14.32941)
		(end 402.182584 -12.624816)
		(width 0.089408)
		(layer "In11.Cu")
		(net "JTAG_PCH_GBE_TDO")
	)
	(segment
		(start 456.982322 -6.222492)
		(end 457.500228 -5.704586)
		(width 0.089408)
		(layer "In11.Cu")
		(net "JTAG_PCH_GBE_TDO")
	)
	(segment
		(start 400.963892 -95.691452)
		(end 398.550384 -93.277944)
		(width 0.089408)
		(layer "In11.Cu")
		(net "JTAG_PCH_GBE_TDO")
	)
	(segment
		(start 399.030698 -86.077298)
		(end 399.030698 -84.024724)
		(width 0.089408)
		(layer "In11.Cu")
		(net "JTAG_PCH_GBE_TDO")
	)
	(segment
		(start 398.262602 -76.493624)
		(end 396.68958 -74.920602)
		(width 0.089408)
		(layer "In11.Cu")
		(net "JTAG_PCH_GBE_TDO")
	)
	(segment
		(start 438.06237 -14.866112)
		(end 440.035442 -12.89304)
		(width 0.089408)
		(layer "In11.Cu")
		(net "JTAG_PCH_GBE_TDO")
	)
	(segment
		(start 395.164818 -70.801992)
		(end 395.164818 -66.044572)
		(width 0.089408)
		(layer "In11.Cu")
		(net "JTAG_PCH_GBE_TDO")
	)
	(segment
		(start 431.75555 -14.866112)
		(end 438.06237 -14.866112)
		(width 0.089408)
		(layer "In11.Cu")
		(net "JTAG_PCH_GBE_TDO")
	)
	(segment
		(start 398.262602 -77.43571)
		(end 398.262602 -76.493624)
		(width 0.089408)
		(layer "In11.Cu")
		(net "JTAG_PCH_GBE_TDO")
	)
	(segment
		(start 403.999192 -105.299002)
		(end 402.01469 -105.299002)
		(width 0.089408)
		(layer "In11.Cu")
		(net "JTAG_PCH_GBE_TDO")
	)
	(segment
		(start 404.375112 -104.70515)
		(end 404.375112 -104.923082)
		(width 0.089408)
		(layer "In11.Cu")
		(net "JTAG_PCH_GBE_TDO")
	)
	(segment
		(start 378.686822 -45.663358)
		(end 378.66828 -45.644816)
		(width 0.089408)
		(layer "In11.Cu")
		(net "JTAG_PCH_GBE_TDO")
	)
	(segment
		(start 440.035442 -12.89304)
		(end 446.01892 -12.89304)
		(width 0.089408)
		(layer "In11.Cu")
		(net "JTAG_PCH_GBE_TDO")
	)
	(segment
		(start 417.999418 -12.624816)
		(end 420.428928 -15.054326)
		(width 0.089408)
		(layer "In11.Cu")
		(net "JTAG_PCH_GBE_TDO")
	)
	(segment
		(start 377.095512 -36.051998)
		(end 375.096278 -34.052764)
		(width 0.089408)
		(layer "In11.Cu")
		(net "JTAG_PCH_GBE_TDO")
	)
	(segment
		(start 398.550384 -93.277944)
		(end 398.550384 -91.13774)
		(width 0.089408)
		(layer "In11.Cu")
		(net "JTAG_PCH_GBE_TDO")
	)
	(segment
		(start 398.8054 -79.647034)
		(end 398.8054 -79.272638)
		(width 0.089408)
		(layer "In11.Cu")
		(net "JTAG_PCH_GBE_TDO")
	)
	(segment
		(start 454.627234 -5.871718)
		(end 455.898504 -5.871718)
		(width 0.089408)
		(layer "In11.Cu")
		(net "JTAG_PCH_GBE_TDO")
	)
	(segment
		(start 461.922114 -6.153912)
		(end 464.442048 -6.153912)
		(width 0.089408)
		(layer "In11.Cu")
		(net "JTAG_PCH_GBE_TDO")
	)
	(segment
		(start 404.375112 -104.923082)
		(end 403.999192 -105.299002)
		(width 0.089408)
		(layer "In11.Cu")
		(net "JTAG_PCH_GBE_TDO")
	)
	(segment
		(start 387.492748 -50.716688)
		(end 386.378958 -49.602898)
		(width 0.089408)
		(layer "In11.Cu")
		(net "JTAG_PCH_GBE_TDO")
	)
	(segment
		(start 399.030698 -84.024724)
		(end 398.502886 -83.496912)
		(width 0.089408)
		(layer "In11.Cu")
		(net "JTAG_PCH_GBE_TDO")
	)
	(segment
		(start 393.605004 -58.542174)
		(end 387.492748 -52.429918)
		(width 0.089408)
		(layer "In11.Cu")
		(net "JTAG_PCH_GBE_TDO")
	)
	(segment
		(start 404.623524 -104.456738)
		(end 404.375112 -104.70515)
		(width 0.089408)
		(layer "In11.Cu")
		(net "JTAG_PCH_GBE_TDO")
	)
	(segment
		(start 398.502886 -79.949548)
		(end 398.8054 -79.647034)
		(width 0.089408)
		(layer "In11.Cu")
		(net "JTAG_PCH_GBE_TDO")
	)
	(segment
		(start 454.049384 -6.353048)
		(end 454.145904 -6.353048)
		(width 0.089408)
		(layer "In11.Cu")
		(net "JTAG_PCH_GBE_TDO")
	)
	(segment
		(start 398.502886 -83.496912)
		(end 398.502886 -79.949548)
		(width 0.089408)
		(layer "In11.Cu")
		(net "JTAG_PCH_GBE_TDO")
	)
	(segment
		(start 458.351382 -4.60248)
		(end 460.370682 -4.60248)
		(width 0.089408)
		(layer "In11.Cu")
		(net "JTAG_PCH_GBE_TDO")
	)
	(segment
		(start 396.68958 -74.920602)
		(end 396.68958 -74.919078)
		(width 0.089408)
		(layer "In11.Cu")
		(net "JTAG_PCH_GBE_TDO")
	)
	(segment
		(start 378.496068 -44.476416)
		(end 377.914408 -44.476416)
		(width 0.089408)
		(layer "In11.Cu")
		(net "JTAG_PCH_GBE_TDO")
	)
	(segment
		(start 398.550384 -91.13774)
		(end 399.3261 -90.362024)
		(width 0.089408)
		(layer "In11.Cu")
		(net "JTAG_PCH_GBE_TDO")
	)
	(segment
		(start 402.01469 -105.299002)
		(end 400.963892 -104.248204)
		(width 0.089408)
		(layer "In11.Cu")
		(net "JTAG_PCH_GBE_TDO")
	)
	(segment
		(start 460.370682 -4.60248)
		(end 461.922114 -6.153912)
		(width 0.089408)
		(layer "In11.Cu")
		(net "JTAG_PCH_GBE_TDO")
	)
	(segment
		(start 377.538488 -42.252646)
		(end 377.095512 -41.80967)
		(width 0.089408)
		(layer "In11.Cu")
		(net "JTAG_PCH_GBE_TDO")
	)
	(segment
		(start 398.068292 -77.63002)
		(end 398.262602 -77.43571)
		(width 0.089408)
		(layer "In11.Cu")
		(net "JTAG_PCH_GBE_TDO")
	)
	(segment
		(start 383.10439 -48.206406)
		(end 382.904238 -48.206406)
		(width 0.089408)
		(layer "In11.Cu")
		(net "JTAG_PCH_GBE_TDO")
	)
	(segment
		(start 399.3261 -90.362024)
		(end 399.3261 -86.3727)
		(width 0.089408)
		(layer "In11.Cu")
		(net "JTAG_PCH_GBE_TDO")
	)
	(segment
		(start 395.164818 -66.044572)
		(end 393.605004 -64.484758)
		(width 0.089408)
		(layer "In11.Cu")
		(net "JTAG_PCH_GBE_TDO")
	)
	(segment
		(start 455.898504 -5.871718)
		(end 456.249278 -6.222492)
		(width 0.089408)
		(layer "In11.Cu")
		(net "JTAG_PCH_GBE_TDO")
	)
	(segment
		(start 404.623524 -103.27513)
		(end 404.623524 -104.456738)
		(width 0.089408)
		(layer "In11.Cu")
		(net "JTAG_PCH_GBE_TDO")
	)
	(segment
		(start 385.986782 -48.206152)
		(end 383.104644 -48.206152)
		(width 0.089408)
		(layer "In11.Cu")
		(net "JTAG_PCH_GBE_TDO")
	)
	(segment
		(start 380.324868 -47.301404)
		(end 378.988066 -45.964602)
		(width 0.089408)
		(layer "In11.Cu")
		(net "JTAG_PCH_GBE_TDO")
	)
	(segment
		(start 382.904238 -48.206406)
		(end 382.903984 -48.206152)
		(width 0.089408)
		(layer "In11.Cu")
		(net "JTAG_PCH_GBE_TDO")
	)
	(segment
		(start 377.538488 -44.100496)
		(end 377.538488 -42.252646)
		(width 0.089408)
		(layer "In11.Cu")
		(net "JTAG_PCH_GBE_TDO")
	)
	(segment
		(start 457.500228 -5.704586)
		(end 457.500228 -5.453634)
		(width 0.089408)
		(layer "In11.Cu")
		(net "JTAG_PCH_GBE_TDO")
	)
	(segment
		(start 383.104644 -48.206152)
		(end 383.10439 -48.206406)
		(width 0.089408)
		(layer "In11.Cu")
		(net "JTAG_PCH_GBE_TDO")
	)
	(segment
		(start 456.249278 -6.222492)
		(end 456.982322 -6.222492)
		(width 0.089408)
		(layer "In11.Cu")
		(net "JTAG_PCH_GBE_TDO")
	)
	(segment
		(start 464.442048 -6.153912)
		(end 464.497674 -6.098286)
		(width 0.089408)
		(layer "In11.Cu")
		(net "JTAG_PCH_GBE_TDO")
	)
	(segment
		(start 378.686822 -45.73016)
		(end 378.686822 -45.663358)
		(width 0.089408)
		(layer "In11.Cu")
		(net "JTAG_PCH_GBE_TDO")
	)
	(segment
		(start 396.62608 -74.855578)
		(end 396.62608 -72.263254)
		(width 0.089408)
		(layer "In11.Cu")
		(net "JTAG_PCH_GBE_TDO")
	)
	(segment
		(start 382.903984 -48.206152)
		(end 382.792986 -48.206152)
		(width 0.089408)
		(layer "In11.Cu")
		(net "JTAG_PCH_GBE_TDO")
	)
	(segment
		(start 400.277838 -14.32941)
		(end 400.47799 -14.32941)
		(width 0.089408)
		(layer "In11.Cu")
		(net "JTAG_PCH_GBE_TDO")
	)
	(segment
		(start 375.096278 -34.052764)
		(end 375.096278 -21.32457)
		(width 0.089408)
		(layer "In11.Cu")
		(net "JTAG_PCH_GBE_TDO")
	)
	(segment
		(start 454.145904 -6.353048)
		(end 454.627234 -5.871718)
		(width 0.089408)
		(layer "In11.Cu")
		(net "JTAG_PCH_GBE_TDO")
	)
	(segment
		(start 396.62608 -72.263254)
		(end 395.164818 -70.801992)
		(width 0.089408)
		(layer "In11.Cu")
		(net "JTAG_PCH_GBE_TDO")
	)
	(segment
		(start 382.792986 -48.206152)
		(end 381.888238 -47.301404)
		(width 0.089408)
		(layer "In11.Cu")
		(net "JTAG_PCH_GBE_TDO")
	)
	(segment
		(start 454.039732 -6.3627)
		(end 454.049384 -6.353048)
		(width 0.089408)
		(layer "In11.Cu")
		(net "JTAG_PCH_GBE_TDO")
	)
	(segment
		(start 420.428928 -15.054326)
		(end 431.567336 -15.054326)
		(width 0.089408)
		(layer "In11.Cu")
		(net "JTAG_PCH_GBE_TDO")
	)
	(segment
		(start 378.66828 -44.648628)
		(end 378.496068 -44.476416)
		(width 0.089408)
		(layer "In11.Cu")
		(net "JTAG_PCH_GBE_TDO")
	)
	(segment
		(start 398.8054 -79.272638)
		(end 398.068292 -78.53553)
		(width 0.089408)
		(layer "In11.Cu")
		(net "JTAG_PCH_GBE_TDO")
	)
	(segment
		(start 378.66828 -45.644816)
		(end 378.66828 -44.648628)
		(width 0.089408)
		(layer "In11.Cu")
		(net "JTAG_PCH_GBE_TDO")
	)
	(segment
		(start 404.007574 -102.65918)
		(end 404.623524 -103.27513)
		(width 0.089408)
		(layer "In11.Cu")
		(net "JTAG_PCH_GBE_TDO")
	)
	(segment
		(start 464.697826 -6.098286)
		(end 464.69808 -6.09854)
		(width 0.089408)
		(layer "In11.Cu")
		(net "JTAG_PCH_GBE_TDO")
	)
	(segment
		(start 452.54926 -6.3627)
		(end 454.039732 -6.3627)
		(width 0.089408)
		(layer "In11.Cu")
		(net "JTAG_PCH_GBE_TDO")
	)
	(segment
		(start 399.3261 -86.3727)
		(end 399.030698 -86.077298)
		(width 0.089408)
		(layer "In11.Cu")
		(net "JTAG_PCH_GBE_TDO")
	)
	(segment
		(start 464.69808 -6.09854)
		(end 467.08314 -6.09854)
		(width 0.089408)
		(layer "In11.Cu")
		(net "JTAG_PCH_GBE_TDO")
	)
	(segment
		(start 381.888238 -47.301404)
		(end 380.324868 -47.301404)
		(width 0.089408)
		(layer "In11.Cu")
		(net "JTAG_PCH_GBE_TDO")
	)
	(segment
		(start 457.500228 -5.453634)
		(end 458.351382 -4.60248)
		(width 0.089408)
		(layer "In11.Cu")
		(net "JTAG_PCH_GBE_TDO")
	)
	(segment
		(start 377.914408 -44.476416)
		(end 377.538488 -44.100496)
		(width 0.089408)
		(layer "In11.Cu")
		(net "JTAG_PCH_GBE_TDO")
	)
	(segment
		(start 446.01892 -12.89304)
		(end 452.54926 -6.3627)
		(width 0.089408)
		(layer "In11.Cu")
		(net "JTAG_PCH_GBE_TDO")
	)
	(segment
		(start 393.605004 -64.484758)
		(end 393.605004 -58.542174)
		(width 0.089408)
		(layer "In11.Cu")
		(net "JTAG_PCH_GBE_TDO")
	)
	(segment
		(start 467.08314 -6.09854)
		(end 467.687406 -5.494274)
		(width 0.089408)
		(layer "In11.Cu")
		(net "JTAG_PCH_GBE_TDO")
	)
	(segment
		(start 378.921264 -45.964602)
		(end 378.686822 -45.73016)
		(width 0.089408)
		(layer "In11.Cu")
		(net "JTAG_PCH_GBE_TDO")
	)
	(segment
		(start 386.378958 -48.598328)
		(end 385.986782 -48.206152)
		(width 0.089408)
		(layer "In11.Cu")
		(net "JTAG_PCH_GBE_TDO")
	)
	(segment
		(start 377.095512 -41.80967)
		(end 377.095512 -36.051998)
		(width 0.089408)
		(layer "In11.Cu")
		(net "JTAG_PCH_GBE_TDO")
	)
	(segment
		(start 382.091692 -14.329156)
		(end 400.277584 -14.329156)
		(width 0.089408)
		(layer "In11.Cu")
		(net "JTAG_PCH_GBE_TDO")
	)
	(segment
		(start 402.182584 -12.624816)
		(end 417.999418 -12.624816)
		(width 0.089408)
		(layer "In11.Cu")
		(net "JTAG_PCH_GBE_TDO")
	)
	(segment
		(start 464.497674 -6.098286)
		(end 464.697826 -6.098286)
		(width 0.089408)
		(layer "In11.Cu")
		(net "JTAG_PCH_GBE_TDO")
	)
	(segment
		(start 375.096278 -21.32457)
		(end 382.091692 -14.329156)
		(width 0.089408)
		(layer "In11.Cu")
		(net "JTAG_PCH_GBE_TDO")
	)
	(segment
		(start 398.068292 -78.53553)
		(end 398.068292 -77.63002)
		(width 0.089408)
		(layer "In11.Cu")
		(net "JTAG_PCH_GBE_TDO")
	)
	(segment
		(start 396.68958 -74.919078)
		(end 396.62608 -74.855578)
		(width 0.089408)
		(layer "In11.Cu")
		(net "JTAG_PCH_GBE_TDO")
	)
	(segment
		(start 387.492748 -52.429918)
		(end 387.492748 -50.716688)
		(width 0.089408)
		(layer "In11.Cu")
		(net "JTAG_PCH_GBE_TDO")
	)
	(segment
		(start 378.988066 -45.964602)
		(end 378.921264 -45.964602)
		(width 0.089408)
		(layer "In11.Cu")
		(net "JTAG_PCH_GBE_TDO")
	)
	(segment
		(start 400.880072 -103.354886)
		(end 401.51304 -103.354886)
		(width 0.0889)
		(layer "F.Cu")
		(net "JTAG_PCH_GBE_TDI")
	)
	(segment
		(start 388.8232 -0.254)
		(end 388.8232 -0.889)
		(width 0.10795)
		(layer "F.Cu")
		(net "JTAG_PCH_GBE_TDI")
	)
	(segment
		(start 401.628356 -103.470202)
		(end 402.773134 -103.470202)
		(width 0.0889)
		(layer "F.Cu")
		(net "JTAG_PCH_GBE_TDI")
	)
	(segment
		(start 403.918928 -103.817928)
		(end 404.09876 -103.99776)
		(width 0.0889)
		(layer "F.Cu")
		(net "JTAG_PCH_GBE_TDI")
	)
	(segment
		(start 402.773134 -103.470202)
		(end 403.12086 -103.817928)
		(width 0.0889)
		(layer "F.Cu")
		(net "JTAG_PCH_GBE_TDI")
	)
	(segment
		(start 401.51304 -103.354886)
		(end 401.628356 -103.470202)
		(width 0.0889)
		(layer "F.Cu")
		(net "JTAG_PCH_GBE_TDI")
	)
	(segment
		(start 403.12086 -103.817928)
		(end 403.918928 -103.817928)
		(width 0.0889)
		(layer "F.Cu")
		(net "JTAG_PCH_GBE_TDI")
	)
	(segment
		(start 404.09876 -103.99776)
		(end 404.22322 -103.99776)
		(width 0.0889)
		(layer "F.Cu")
		(net "JTAG_PCH_GBE_TDI")
	)
	(via
		(at 469.473788 -3.231642)
		(size 0.508)
		(drill 0.254)
		(layers "F.Cu" "B.Cu")
		(net "JTAG_PCH_GBE_TDI")
	)
	(via
		(at 404.22322 -103.99776)
		(size 0.508)
		(drill 0.254)
		(layers "F.Cu" "B.Cu")
		(net "JTAG_PCH_GBE_TDI")
	)
	(via
		(at 388.8232 -0.889)
		(size 0.508)
		(drill 0.254)
		(layers "F.Cu" "B.Cu")
		(net "JTAG_PCH_GBE_TDI")
	)
	(via
		(at 469.011 -2.667)
		(size 0.6604)
		(drill 0.3302)
		(layers "F.Cu" "B.Cu")
		(net "JTAG_PCH_GBE_TDI")
	)
	(segment
		(start 469.473788 -3.231642)
		(end 469.473788 -3.129788)
		(width 0.10795)
		(layer "B.Cu")
		(net "JTAG_PCH_GBE_TDI")
	)
	(segment
		(start 469.473788 -3.129788)
		(end 469.011 -2.667)
		(width 0.10795)
		(layer "B.Cu")
		(net "JTAG_PCH_GBE_TDI")
	)
	(segment
		(start 396.5194 3.6322)
		(end 395.6304 2.7432)
		(width 0.089408)
		(layer "In4.Cu")
		(net "JTAG_PCH_GBE_TDI")
	)
	(segment
		(start 391.81151 0.2032)
		(end 389.9154 0.2032)
		(width 0.089408)
		(layer "In4.Cu")
		(net "JTAG_PCH_GBE_TDI")
	)
	(segment
		(start 394.35151 2.7432)
		(end 391.81151 0.2032)
		(width 0.089408)
		(layer "In4.Cu")
		(net "JTAG_PCH_GBE_TDI")
	)
	(segment
		(start 463.942938 2.934462)
		(end 463.942938 4.483862)
		(width 0.089408)
		(layer "In4.Cu")
		(net "JTAG_PCH_GBE_TDI")
	)
	(segment
		(start 389.9154 0.2032)
		(end 388.8232 -0.889)
		(width 0.089408)
		(layer "In4.Cu")
		(net "JTAG_PCH_GBE_TDI")
	)
	(segment
		(start 469.473788 -2.004568)
		(end 467.437724 0.031496)
		(width 0.089408)
		(layer "In4.Cu")
		(net "JTAG_PCH_GBE_TDI")
	)
	(segment
		(start 462.9404 5.4864)
		(end 397.4338 5.4864)
		(width 0.089408)
		(layer "In4.Cu")
		(net "JTAG_PCH_GBE_TDI")
	)
	(segment
		(start 467.437724 0.031496)
		(end 465.728304 0.031496)
		(width 0.089408)
		(layer "In4.Cu")
		(net "JTAG_PCH_GBE_TDI")
	)
	(segment
		(start 465.2772 0.4826)
		(end 465.2772 1.6002)
		(width 0.089408)
		(layer "In4.Cu")
		(net "JTAG_PCH_GBE_TDI")
	)
	(segment
		(start 463.942938 4.483862)
		(end 462.9404 5.4864)
		(width 0.089408)
		(layer "In4.Cu")
		(net "JTAG_PCH_GBE_TDI")
	)
	(segment
		(start 397.4338 5.4864)
		(end 396.5194 4.572)
		(width 0.089408)
		(layer "In4.Cu")
		(net "JTAG_PCH_GBE_TDI")
	)
	(segment
		(start 396.5194 4.572)
		(end 396.5194 3.6322)
		(width 0.089408)
		(layer "In4.Cu")
		(net "JTAG_PCH_GBE_TDI")
	)
	(segment
		(start 465.2772 1.6002)
		(end 463.942938 2.934462)
		(width 0.089408)
		(layer "In4.Cu")
		(net "JTAG_PCH_GBE_TDI")
	)
	(segment
		(start 395.6304 2.7432)
		(end 394.35151 2.7432)
		(width 0.089408)
		(layer "In4.Cu")
		(net "JTAG_PCH_GBE_TDI")
	)
	(segment
		(start 469.473788 -3.231642)
		(end 469.473788 -2.004568)
		(width 0.089408)
		(layer "In4.Cu")
		(net "JTAG_PCH_GBE_TDI")
	)
	(segment
		(start 465.728304 0.031496)
		(end 465.2772 0.4826)
		(width 0.089408)
		(layer "In4.Cu")
		(net "JTAG_PCH_GBE_TDI")
	)
	(segment
		(start 396.867888 -72.162924)
		(end 395.406626 -70.701662)
		(width 0.089408)
		(layer "In11.Cu")
		(net "JTAG_PCH_GBE_TDI")
	)
	(segment
		(start 377.33732 -35.951668)
		(end 375.338086 -33.952434)
		(width 0.089408)
		(layer "In11.Cu")
		(net "JTAG_PCH_GBE_TDI")
	)
	(segment
		(start 468.08771 -5.660136)
		(end 468.08771 -4.835144)
		(width 0.089408)
		(layer "In11.Cu")
		(net "JTAG_PCH_GBE_TDI")
	)
	(segment
		(start 455.798174 -6.113526)
		(end 456.148948 -6.4643)
		(width 0.089408)
		(layer "In11.Cu")
		(net "JTAG_PCH_GBE_TDI")
	)
	(segment
		(start 378.014738 -44.234608)
		(end 377.780296 -44.000166)
		(width 0.089408)
		(layer "In11.Cu")
		(net "JTAG_PCH_GBE_TDI")
	)
	(segment
		(start 386.62102 -48.498252)
		(end 386.087112 -47.964344)
		(width 0.089408)
		(layer "In11.Cu")
		(net "JTAG_PCH_GBE_TDI")
	)
	(segment
		(start 398.3101 -78.4352)
		(end 398.3101 -78.061312)
		(width 0.089408)
		(layer "In11.Cu")
		(net "JTAG_PCH_GBE_TDI")
	)
	(segment
		(start 398.50441 -77.867002)
		(end 398.50441 -76.39177)
		(width 0.089408)
		(layer "In11.Cu")
		(net "JTAG_PCH_GBE_TDI")
	)
	(segment
		(start 399.272506 -85.920072)
		(end 399.272506 -83.924394)
		(width 0.089408)
		(layer "In11.Cu")
		(net "JTAG_PCH_GBE_TDI")
	)
	(segment
		(start 420.328598 -15.296134)
		(end 431.667666 -15.296134)
		(width 0.089408)
		(layer "In11.Cu")
		(net "JTAG_PCH_GBE_TDI")
	)
	(segment
		(start 379.531626 -44.491656)
		(end 378.853446 -44.491656)
		(width 0.089408)
		(layer "In11.Cu")
		(net "JTAG_PCH_GBE_TDI")
	)
	(segment
		(start 387.73481 -50.616612)
		(end 386.62102 -49.502822)
		(width 0.089408)
		(layer "In11.Cu")
		(net "JTAG_PCH_GBE_TDI")
	)
	(segment
		(start 446.038224 -13.215874)
		(end 452.015098 -7.239)
		(width 0.089408)
		(layer "In11.Cu")
		(net "JTAG_PCH_GBE_TDI")
	)
	(segment
		(start 454.727564 -6.113526)
		(end 455.798174 -6.113526)
		(width 0.089408)
		(layer "In11.Cu")
		(net "JTAG_PCH_GBE_TDI")
	)
	(segment
		(start 393.90447 -64.442086)
		(end 393.90447 -58.499502)
		(width 0.089408)
		(layer "In11.Cu")
		(net "JTAG_PCH_GBE_TDI")
	)
	(segment
		(start 395.406626 -70.701662)
		(end 395.406626 -65.944242)
		(width 0.089408)
		(layer "In11.Cu")
		(net "JTAG_PCH_GBE_TDI")
	)
	(segment
		(start 453.60209 -7.239)
		(end 454.727564 -6.113526)
		(width 0.089408)
		(layer "In11.Cu")
		(net "JTAG_PCH_GBE_TDI")
	)
	(segment
		(start 398.744694 -83.396582)
		(end 398.744694 -80.049878)
		(width 0.089408)
		(layer "In11.Cu")
		(net "JTAG_PCH_GBE_TDI")
	)
	(segment
		(start 402.947124 -105.057194)
		(end 401.213066 -103.323136)
		(width 0.089408)
		(layer "In11.Cu")
		(net "JTAG_PCH_GBE_TDI")
	)
	(segment
		(start 395.406626 -65.944242)
		(end 393.90447 -64.442086)
		(width 0.089408)
		(layer "In11.Cu")
		(net "JTAG_PCH_GBE_TDI")
	)
	(segment
		(start 457.742036 -5.553964)
		(end 458.451712 -4.844288)
		(width 0.089408)
		(layer "In11.Cu")
		(net "JTAG_PCH_GBE_TDI")
	)
	(segment
		(start 431.85588 -15.10792)
		(end 438.1627 -15.10792)
		(width 0.089408)
		(layer "In11.Cu")
		(net "JTAG_PCH_GBE_TDI")
	)
	(segment
		(start 399.567908 -92.013786)
		(end 399.567908 -86.215474)
		(width 0.089408)
		(layer "In11.Cu")
		(net "JTAG_PCH_GBE_TDI")
	)
	(segment
		(start 399.567908 -86.215474)
		(end 399.272506 -85.920072)
		(width 0.089408)
		(layer "In11.Cu")
		(net "JTAG_PCH_GBE_TDI")
	)
	(segment
		(start 460.223108 -4.844288)
		(end 461.774794 -6.395974)
		(width 0.089408)
		(layer "In11.Cu")
		(net "JTAG_PCH_GBE_TDI")
	)
	(segment
		(start 404.133304 -104.822752)
		(end 403.898862 -105.057194)
		(width 0.089408)
		(layer "In11.Cu")
		(net "JTAG_PCH_GBE_TDI")
	)
	(segment
		(start 396.867888 -74.755248)
		(end 396.867888 -72.162924)
		(width 0.089408)
		(layer "In11.Cu")
		(net "JTAG_PCH_GBE_TDI")
	)
	(segment
		(start 375.338086 -21.4249)
		(end 382.192022 -14.570964)
		(width 0.089408)
		(layer "In11.Cu")
		(net "JTAG_PCH_GBE_TDI")
	)
	(segment
		(start 398.3101 -78.061312)
		(end 398.50441 -77.867002)
		(width 0.089408)
		(layer "In11.Cu")
		(net "JTAG_PCH_GBE_TDI")
	)
	(segment
		(start 399.275554 -92.30614)
		(end 399.567908 -92.013786)
		(width 0.089408)
		(layer "In11.Cu")
		(net "JTAG_PCH_GBE_TDI")
	)
	(segment
		(start 379.826012 -44.78147)
		(end 379.82144 -44.78147)
		(width 0.089408)
		(layer "In11.Cu")
		(net "JTAG_PCH_GBE_TDI")
	)
	(segment
		(start 377.780296 -42.152316)
		(end 377.33732 -41.70934)
		(width 0.089408)
		(layer "In11.Cu")
		(net "JTAG_PCH_GBE_TDI")
	)
	(segment
		(start 417.899088 -12.866624)
		(end 420.328598 -15.296134)
		(width 0.089408)
		(layer "In11.Cu")
		(net "JTAG_PCH_GBE_TDI")
	)
	(segment
		(start 377.780296 -44.000166)
		(end 377.780296 -42.152316)
		(width 0.089408)
		(layer "In11.Cu")
		(net "JTAG_PCH_GBE_TDI")
	)
	(segment
		(start 401.213066 -95.61322)
		(end 399.275554 -93.675708)
		(width 0.089408)
		(layer "In11.Cu")
		(net "JTAG_PCH_GBE_TDI")
	)
	(segment
		(start 399.054828 -79.739744)
		(end 399.054828 -79.179928)
		(width 0.089408)
		(layer "In11.Cu")
		(net "JTAG_PCH_GBE_TDI")
	)
	(segment
		(start 404.22322 -104.506268)
		(end 404.133304 -104.596184)
		(width 0.089408)
		(layer "In11.Cu")
		(net "JTAG_PCH_GBE_TDI")
	)
	(segment
		(start 386.087112 -47.964344)
		(end 383.004314 -47.964344)
		(width 0.089408)
		(layer "In11.Cu")
		(net "JTAG_PCH_GBE_TDI")
	)
	(segment
		(start 452.015098 -7.239)
		(end 453.60209 -7.239)
		(width 0.089408)
		(layer "In11.Cu")
		(net "JTAG_PCH_GBE_TDI")
	)
	(segment
		(start 382.192022 -14.570964)
		(end 400.177254 -14.570964)
		(width 0.089408)
		(layer "In11.Cu")
		(net "JTAG_PCH_GBE_TDI")
	)
	(segment
		(start 469.473788 -3.449066)
		(end 469.473788 -3.231642)
		(width 0.089408)
		(layer "In11.Cu")
		(net "JTAG_PCH_GBE_TDI")
	)
	(segment
		(start 467.407498 -6.340348)
		(end 468.08771 -5.660136)
		(width 0.089408)
		(layer "In11.Cu")
		(net "JTAG_PCH_GBE_TDI")
	)
	(segment
		(start 456.148948 -6.4643)
		(end 457.082652 -6.4643)
		(width 0.089408)
		(layer "In11.Cu")
		(net "JTAG_PCH_GBE_TDI")
	)
	(segment
		(start 377.33732 -41.70934)
		(end 377.33732 -35.951668)
		(width 0.089408)
		(layer "In11.Cu")
		(net "JTAG_PCH_GBE_TDI")
	)
	(segment
		(start 398.744694 -80.049878)
		(end 399.054828 -79.739744)
		(width 0.089408)
		(layer "In11.Cu")
		(net "JTAG_PCH_GBE_TDI")
	)
	(segment
		(start 378.596398 -44.234608)
		(end 378.014738 -44.234608)
		(width 0.089408)
		(layer "In11.Cu")
		(net "JTAG_PCH_GBE_TDI")
	)
	(segment
		(start 464.59775 -6.340348)
		(end 467.407498 -6.340348)
		(width 0.089408)
		(layer "In11.Cu")
		(net "JTAG_PCH_GBE_TDI")
	)
	(segment
		(start 378.853446 -44.491656)
		(end 378.596398 -44.234608)
		(width 0.089408)
		(layer "In11.Cu")
		(net "JTAG_PCH_GBE_TDI")
	)
	(segment
		(start 399.054828 -79.179928)
		(end 398.3101 -78.4352)
		(width 0.089408)
		(layer "In11.Cu")
		(net "JTAG_PCH_GBE_TDI")
	)
	(segment
		(start 458.451712 -4.844288)
		(end 460.223108 -4.844288)
		(width 0.089408)
		(layer "In11.Cu")
		(net "JTAG_PCH_GBE_TDI")
	)
	(segment
		(start 375.338086 -33.952434)
		(end 375.338086 -21.4249)
		(width 0.089408)
		(layer "In11.Cu")
		(net "JTAG_PCH_GBE_TDI")
	)
	(segment
		(start 457.082652 -6.4643)
		(end 457.742036 -5.804916)
		(width 0.089408)
		(layer "In11.Cu")
		(net "JTAG_PCH_GBE_TDI")
	)
	(segment
		(start 402.282914 -12.866624)
		(end 417.899088 -12.866624)
		(width 0.089408)
		(layer "In11.Cu")
		(net "JTAG_PCH_GBE_TDI")
	)
	(segment
		(start 440.054746 -13.215874)
		(end 446.038224 -13.215874)
		(width 0.089408)
		(layer "In11.Cu")
		(net "JTAG_PCH_GBE_TDI")
	)
	(segment
		(start 399.275554 -93.675708)
		(end 399.275554 -92.30614)
		(width 0.089408)
		(layer "In11.Cu")
		(net "JTAG_PCH_GBE_TDI")
	)
	(segment
		(start 380.075186 -45.022516)
		(end 379.840744 -44.788074)
		(width 0.089408)
		(layer "In11.Cu")
		(net "JTAG_PCH_GBE_TDI")
	)
	(segment
		(start 462.273142 -6.395974)
		(end 462.273396 -6.39572)
		(width 0.089408)
		(layer "In11.Cu")
		(net "JTAG_PCH_GBE_TDI")
	)
	(segment
		(start 404.22322 -103.99776)
		(end 404.22322 -104.506268)
		(width 0.089408)
		(layer "In11.Cu")
		(net "JTAG_PCH_GBE_TDI")
	)
	(segment
		(start 379.832616 -44.788074)
		(end 379.826012 -44.78147)
		(width 0.089408)
		(layer "In11.Cu")
		(net "JTAG_PCH_GBE_TDI")
	)
	(segment
		(start 383.004314 -47.964344)
		(end 380.075186 -45.035216)
		(width 0.089408)
		(layer "In11.Cu")
		(net "JTAG_PCH_GBE_TDI")
	)
	(segment
		(start 400.57832 -14.571218)
		(end 402.282914 -12.866624)
		(width 0.089408)
		(layer "In11.Cu")
		(net "JTAG_PCH_GBE_TDI")
	)
	(segment
		(start 401.213066 -103.323136)
		(end 401.213066 -95.61322)
		(width 0.089408)
		(layer "In11.Cu")
		(net "JTAG_PCH_GBE_TDI")
	)
	(segment
		(start 462.273396 -6.39572)
		(end 464.542378 -6.39572)
		(width 0.089408)
		(layer "In11.Cu")
		(net "JTAG_PCH_GBE_TDI")
	)
	(segment
		(start 379.82144 -44.78147)
		(end 379.531626 -44.491656)
		(width 0.089408)
		(layer "In11.Cu")
		(net "JTAG_PCH_GBE_TDI")
	)
	(segment
		(start 399.272506 -83.924394)
		(end 398.744694 -83.396582)
		(width 0.089408)
		(layer "In11.Cu")
		(net "JTAG_PCH_GBE_TDI")
	)
	(segment
		(start 438.1627 -15.10792)
		(end 440.054746 -13.215874)
		(width 0.089408)
		(layer "In11.Cu")
		(net "JTAG_PCH_GBE_TDI")
	)
	(segment
		(start 464.542378 -6.39572)
		(end 464.59775 -6.340348)
		(width 0.089408)
		(layer "In11.Cu")
		(net "JTAG_PCH_GBE_TDI")
	)
	(segment
		(start 403.898862 -105.057194)
		(end 402.947124 -105.057194)
		(width 0.089408)
		(layer "In11.Cu")
		(net "JTAG_PCH_GBE_TDI")
	)
	(segment
		(start 393.90447 -58.499502)
		(end 387.73481 -52.329842)
		(width 0.089408)
		(layer "In11.Cu")
		(net "JTAG_PCH_GBE_TDI")
	)
	(segment
		(start 386.62102 -49.502822)
		(end 386.62102 -48.498252)
		(width 0.089408)
		(layer "In11.Cu")
		(net "JTAG_PCH_GBE_TDI")
	)
	(segment
		(start 387.73481 -52.329842)
		(end 387.73481 -50.616612)
		(width 0.089408)
		(layer "In11.Cu")
		(net "JTAG_PCH_GBE_TDI")
	)
	(segment
		(start 461.774794 -6.395974)
		(end 462.273142 -6.395974)
		(width 0.089408)
		(layer "In11.Cu")
		(net "JTAG_PCH_GBE_TDI")
	)
	(segment
		(start 400.177508 -14.571218)
		(end 400.57832 -14.571218)
		(width 0.089408)
		(layer "In11.Cu")
		(net "JTAG_PCH_GBE_TDI")
	)
	(segment
		(start 404.133304 -104.596184)
		(end 404.133304 -104.822752)
		(width 0.089408)
		(layer "In11.Cu")
		(net "JTAG_PCH_GBE_TDI")
	)
	(segment
		(start 400.177254 -14.570964)
		(end 400.177508 -14.571218)
		(width 0.089408)
		(layer "In11.Cu")
		(net "JTAG_PCH_GBE_TDI")
	)
	(segment
		(start 379.840744 -44.788074)
		(end 379.832616 -44.788074)
		(width 0.089408)
		(layer "In11.Cu")
		(net "JTAG_PCH_GBE_TDI")
	)
	(segment
		(start 380.075186 -45.035216)
		(end 380.075186 -45.022516)
		(width 0.089408)
		(layer "In11.Cu")
		(net "JTAG_PCH_GBE_TDI")
	)
	(segment
		(start 431.667666 -15.296134)
		(end 431.85588 -15.10792)
		(width 0.089408)
		(layer "In11.Cu")
		(net "JTAG_PCH_GBE_TDI")
	)
	(segment
		(start 398.50441 -76.39177)
		(end 396.867888 -74.755248)
		(width 0.089408)
		(layer "In11.Cu")
		(net "JTAG_PCH_GBE_TDI")
	)
	(segment
		(start 457.742036 -5.804916)
		(end 457.742036 -5.553964)
		(width 0.089408)
		(layer "In11.Cu")
		(net "JTAG_PCH_GBE_TDI")
	)
	(segment
		(start 468.08771 -4.835144)
		(end 469.473788 -3.449066)
		(width 0.089408)
		(layer "In11.Cu")
		(net "JTAG_PCH_GBE_TDI")
	)
	(segment
		(start 401.456144 -102.163626)
		(end 401.151344 -102.163626)
		(width 0.0889)
		(layer "F.Cu")
		(net "JTAG_PCH_GBE_CLK")
	)
	(segment
		(start 401.63623 -101.98354)
		(end 401.456144 -102.163626)
		(width 0.0889)
		(layer "F.Cu")
		(net "JTAG_PCH_GBE_CLK")
	)
	(segment
		(start 397.3576 -0.2286)
		(end 397.3576 -0.5588)
		(width 0.10795)
		(layer "F.Cu")
		(net "JTAG_PCH_GBE_CLK")
	)
	(segment
		(start 401.029932 -102.042214)
		(end 400.734784 -102.042214)
		(width 0.0889)
		(layer "F.Cu")
		(net "JTAG_PCH_GBE_CLK")
	)
	(segment
		(start 400.734784 -102.042214)
		(end 400.42211 -102.354888)
		(width 0.0889)
		(layer "F.Cu")
		(net "JTAG_PCH_GBE_CLK")
	)
	(segment
		(start 403.343872 -102.419912)
		(end 402.9075 -101.98354)
		(width 0.0889)
		(layer "F.Cu")
		(net "JTAG_PCH_GBE_CLK")
	)
	(segment
		(start 403.343872 -102.455472)
		(end 403.343872 -102.419912)
		(width 0.0889)
		(layer "F.Cu")
		(net "JTAG_PCH_GBE_CLK")
	)
	(segment
		(start 397.3576 -0.5588)
		(end 397.0528 -0.8636)
		(width 0.10795)
		(layer "F.Cu")
		(net "JTAG_PCH_GBE_CLK")
	)
	(segment
		(start 402.9075 -101.98354)
		(end 401.63623 -101.98354)
		(width 0.0889)
		(layer "F.Cu")
		(net "JTAG_PCH_GBE_CLK")
	)
	(segment
		(start 400.42211 -102.354888)
		(end 400.05 -102.354888)
		(width 0.0889)
		(layer "F.Cu")
		(net "JTAG_PCH_GBE_CLK")
	)
	(segment
		(start 401.151344 -102.163626)
		(end 401.029932 -102.042214)
		(width 0.0889)
		(layer "F.Cu")
		(net "JTAG_PCH_GBE_CLK")
	)
	(via
		(at 452.0565 -9.27862)
		(size 0.508)
		(drill 0.254)
		(layers "F.Cu" "B.Cu")
		(net "JTAG_PCH_GBE_CLK")
	)
	(via
		(at 397.0528 -0.8636)
		(size 0.508)
		(drill 0.254)
		(layers "F.Cu" "B.Cu")
		(net "JTAG_PCH_GBE_CLK")
	)
	(via
		(at 403.343872 -102.455472)
		(size 0.508)
		(drill 0.254)
		(layers "F.Cu" "B.Cu")
		(net "JTAG_PCH_GBE_CLK")
	)
	(segment
		(start 407.67635 0.03048)
		(end 407.154126 0.552704)
		(width 0.089408)
		(layer "In4.Cu")
		(net "JTAG_PCH_GBE_CLK")
	)
	(segment
		(start 420.491412 1.57607)
		(end 417.277042 1.57607)
		(width 0.089408)
		(layer "In4.Cu")
		(net "JTAG_PCH_GBE_CLK")
	)
	(segment
		(start 397.453104 -0.463296)
		(end 397.0528 -0.8636)
		(width 0.089408)
		(layer "In4.Cu")
		(net "JTAG_PCH_GBE_CLK")
	)
	(segment
		(start 402.75637 -0.520192)
		(end 399.276316 -0.520192)
		(width 0.089408)
		(layer "In4.Cu")
		(net "JTAG_PCH_GBE_CLK")
	)
	(segment
		(start 431.387758 -1.649476)
		(end 429.738282 0)
		(width 0.089408)
		(layer "In4.Cu")
		(net "JTAG_PCH_GBE_CLK")
	)
	(segment
		(start 452.0565 -9.27862)
		(end 452.0565 -6.97357)
		(width 0.089408)
		(layer "In4.Cu")
		(net "JTAG_PCH_GBE_CLK")
	)
	(segment
		(start 399.276316 -0.520192)
		(end 399.21942 -0.463296)
		(width 0.089408)
		(layer "In4.Cu")
		(net "JTAG_PCH_GBE_CLK")
	)
	(segment
		(start 402.967698 -0.73152)
		(end 402.75637 -0.520192)
		(width 0.089408)
		(layer "In4.Cu")
		(net "JTAG_PCH_GBE_CLK")
	)
	(segment
		(start 422.067482 0)
		(end 420.491412 1.57607)
		(width 0.089408)
		(layer "In4.Cu")
		(net "JTAG_PCH_GBE_CLK")
	)
	(segment
		(start 407.154126 0.552704)
		(end 405.879046 0.552704)
		(width 0.089408)
		(layer "In4.Cu")
		(net "JTAG_PCH_GBE_CLK")
	)
	(segment
		(start 399.21942 -0.463296)
		(end 397.453104 -0.463296)
		(width 0.089408)
		(layer "In4.Cu")
		(net "JTAG_PCH_GBE_CLK")
	)
	(segment
		(start 404.594822 -0.73152)
		(end 402.967698 -0.73152)
		(width 0.089408)
		(layer "In4.Cu")
		(net "JTAG_PCH_GBE_CLK")
	)
	(segment
		(start 405.879046 0.552704)
		(end 404.594822 -0.73152)
		(width 0.089408)
		(layer "In4.Cu")
		(net "JTAG_PCH_GBE_CLK")
	)
	(segment
		(start 446.732406 -1.649476)
		(end 431.387758 -1.649476)
		(width 0.089408)
		(layer "In4.Cu")
		(net "JTAG_PCH_GBE_CLK")
	)
	(segment
		(start 452.0565 -6.97357)
		(end 446.732406 -1.649476)
		(width 0.089408)
		(layer "In4.Cu")
		(net "JTAG_PCH_GBE_CLK")
	)
	(segment
		(start 415.731452 0.03048)
		(end 407.67635 0.03048)
		(width 0.089408)
		(layer "In4.Cu")
		(net "JTAG_PCH_GBE_CLK")
	)
	(segment
		(start 429.738282 0)
		(end 422.067482 0)
		(width 0.089408)
		(layer "In4.Cu")
		(net "JTAG_PCH_GBE_CLK")
	)
	(segment
		(start 417.277042 1.57607)
		(end 415.731452 0.03048)
		(width 0.089408)
		(layer "In4.Cu")
		(net "JTAG_PCH_GBE_CLK")
	)
	(segment
		(start 389.375142 -51.167284)
		(end 395.21511 -57.007252)
		(width 0.089408)
		(layer "In11.Cu")
		(net "JTAG_PCH_GBE_CLK")
	)
	(segment
		(start 378.520198 -39.711884)
		(end 379.314202 -40.505888)
		(width 0.089408)
		(layer "In11.Cu")
		(net "JTAG_PCH_GBE_CLK")
	)
	(segment
		(start 403.86 -100.075746)
		(end 403.86 -102.006908)
		(width 0.089408)
		(layer "In11.Cu")
		(net "JTAG_PCH_GBE_CLK")
	)
	(segment
		(start 417.598098 -13.592048)
		(end 402.583904 -13.592048)
		(width 0.089408)
		(layer "In11.Cu")
		(net "JTAG_PCH_GBE_CLK")
	)
	(segment
		(start 438.46369 -15.833344)
		(end 432.15687 -15.833344)
		(width 0.089408)
		(layer "In11.Cu")
		(net "JTAG_PCH_GBE_CLK")
	)
	(segment
		(start 432.15687 -15.833344)
		(end 431.968656 -16.021558)
		(width 0.089408)
		(layer "In11.Cu")
		(net "JTAG_PCH_GBE_CLK")
	)
	(segment
		(start 400.87931 -15.296642)
		(end 399.876518 -15.296642)
		(width 0.089408)
		(layer "In11.Cu")
		(net "JTAG_PCH_GBE_CLK")
	)
	(segment
		(start 450.843904 -9.926066)
		(end 450.839586 -9.930384)
		(width 0.089408)
		(layer "In11.Cu")
		(net "JTAG_PCH_GBE_CLK")
	)
	(segment
		(start 400.553682 -75.205082)
		(end 401.080224 -75.731624)
		(width 0.089408)
		(layer "In11.Cu")
		(net "JTAG_PCH_GBE_CLK")
	)
	(segment
		(start 382.953514 -15.296388)
		(end 379.931168 -18.318734)
		(width 0.089408)
		(layer "In11.Cu")
		(net "JTAG_PCH_GBE_CLK")
	)
	(segment
		(start 404.608284 -86.592156)
		(end 404.608284 -91.935046)
		(width 0.089408)
		(layer "In11.Cu")
		(net "JTAG_PCH_GBE_CLK")
	)
	(segment
		(start 439.99531 -14.301724)
		(end 438.46369 -15.833344)
		(width 0.089408)
		(layer "In11.Cu")
		(net "JTAG_PCH_GBE_CLK")
	)
	(segment
		(start 446.011046 -14.301724)
		(end 439.99531 -14.301724)
		(width 0.089408)
		(layer "In11.Cu")
		(net "JTAG_PCH_GBE_CLK")
	)
	(segment
		(start 376.06351 -22.725634)
		(end 376.06351 -33.645348)
		(width 0.089408)
		(layer "In11.Cu")
		(net "JTAG_PCH_GBE_CLK")
	)
	(segment
		(start 402.583904 -13.592048)
		(end 400.87931 -15.296642)
		(width 0.089408)
		(layer "In11.Cu")
		(net "JTAG_PCH_GBE_CLK")
	)
	(segment
		(start 404.608284 -91.935046)
		(end 403.310344 -93.232986)
		(width 0.089408)
		(layer "In11.Cu")
		(net "JTAG_PCH_GBE_CLK")
	)
	(segment
		(start 396.34795 -61.96838)
		(end 398.241012 -61.96838)
		(width 0.089408)
		(layer "In11.Cu")
		(net "JTAG_PCH_GBE_CLK")
	)
	(segment
		(start 379.314202 -40.505888)
		(end 379.314202 -40.678862)
		(width 0.089408)
		(layer "In11.Cu")
		(net "JTAG_PCH_GBE_CLK")
	)
	(segment
		(start 403.411436 -102.455472)
		(end 403.343872 -102.455472)
		(width 0.089408)
		(layer "In11.Cu")
		(net "JTAG_PCH_GBE_CLK")
	)
	(segment
		(start 379.314202 -40.678862)
		(end 379.840998 -41.205658)
		(width 0.089408)
		(layer "In11.Cu")
		(net "JTAG_PCH_GBE_CLK")
	)
	(segment
		(start 379.840998 -41.34739)
		(end 381.35052 -42.856912)
		(width 0.089408)
		(layer "In11.Cu")
		(net "JTAG_PCH_GBE_CLK")
	)
	(segment
		(start 376.06351 -33.645348)
		(end 379.330712 -36.91255)
		(width 0.089408)
		(layer "In11.Cu")
		(net "JTAG_PCH_GBE_CLK")
	)
	(segment
		(start 379.931168 -18.857976)
		(end 376.06351 -22.725634)
		(width 0.089408)
		(layer "In11.Cu")
		(net "JTAG_PCH_GBE_CLK")
	)
	(segment
		(start 379.330712 -37.851842)
		(end 378.520198 -38.662356)
		(width 0.089408)
		(layer "In11.Cu")
		(net "JTAG_PCH_GBE_CLK")
	)
	(segment
		(start 399.876518 -15.296642)
		(end 399.876264 -15.296388)
		(width 0.089408)
		(layer "In11.Cu")
		(net "JTAG_PCH_GBE_CLK")
	)
	(segment
		(start 401.080224 -75.731624)
		(end 401.080224 -77.207618)
		(width 0.089408)
		(layer "In11.Cu")
		(net "JTAG_PCH_GBE_CLK")
	)
	(segment
		(start 402.741384 -84.725256)
		(end 404.608284 -86.592156)
		(width 0.089408)
		(layer "In11.Cu")
		(net "JTAG_PCH_GBE_CLK")
	)
	(segment
		(start 401.572984 -77.700378)
		(end 401.572984 -78.823312)
		(width 0.089408)
		(layer "In11.Cu")
		(net "JTAG_PCH_GBE_CLK")
	)
	(segment
		(start 403.310344 -99.52609)
		(end 403.86 -100.075746)
		(width 0.089408)
		(layer "In11.Cu")
		(net "JTAG_PCH_GBE_CLK")
	)
	(segment
		(start 450.839586 -9.930384)
		(end 450.382386 -9.930384)
		(width 0.089408)
		(layer "In11.Cu")
		(net "JTAG_PCH_GBE_CLK")
	)
	(segment
		(start 401.572984 -78.823312)
		(end 401.385532 -79.010764)
		(width 0.089408)
		(layer "In11.Cu")
		(net "JTAG_PCH_GBE_CLK")
	)
	(segment
		(start 420.027608 -16.021558)
		(end 417.598098 -13.592048)
		(width 0.089408)
		(layer "In11.Cu")
		(net "JTAG_PCH_GBE_CLK")
	)
	(segment
		(start 403.86 -102.006908)
		(end 403.411436 -102.455472)
		(width 0.089408)
		(layer "In11.Cu")
		(net "JTAG_PCH_GBE_CLK")
	)
	(segment
		(start 399.656808 -63.384176)
		(end 399.656808 -70.924928)
		(width 0.089408)
		(layer "In11.Cu")
		(net "JTAG_PCH_GBE_CLK")
	)
	(segment
		(start 402.741384 -83.482942)
		(end 402.741384 -84.725256)
		(width 0.089408)
		(layer "In11.Cu")
		(net "JTAG_PCH_GBE_CLK")
	)
	(segment
		(start 389.375142 -50.40249)
		(end 389.375142 -51.167284)
		(width 0.089408)
		(layer "In11.Cu")
		(net "JTAG_PCH_GBE_CLK")
	)
	(segment
		(start 452.0565 -9.27862)
		(end 451.409054 -9.926066)
		(width 0.089408)
		(layer "In11.Cu")
		(net "JTAG_PCH_GBE_CLK")
	)
	(segment
		(start 401.385532 -79.010764)
		(end 401.385532 -82.12709)
		(width 0.089408)
		(layer "In11.Cu")
		(net "JTAG_PCH_GBE_CLK")
	)
	(segment
		(start 398.241012 -61.96838)
		(end 399.656808 -63.384176)
		(width 0.089408)
		(layer "In11.Cu")
		(net "JTAG_PCH_GBE_CLK")
	)
	(segment
		(start 399.876264 -15.296388)
		(end 382.953514 -15.296388)
		(width 0.089408)
		(layer "In11.Cu")
		(net "JTAG_PCH_GBE_CLK")
	)
	(segment
		(start 382.834134 -42.856912)
		(end 388.069836 -48.092614)
		(width 0.089408)
		(layer "In11.Cu")
		(net "JTAG_PCH_GBE_CLK")
	)
	(segment
		(start 378.520198 -38.662356)
		(end 378.520198 -39.711884)
		(width 0.089408)
		(layer "In11.Cu")
		(net "JTAG_PCH_GBE_CLK")
	)
	(segment
		(start 399.656808 -70.924928)
		(end 400.553682 -71.821802)
		(width 0.089408)
		(layer "In11.Cu")
		(net "JTAG_PCH_GBE_CLK")
	)
	(segment
		(start 400.553682 -71.821802)
		(end 400.553682 -75.205082)
		(width 0.089408)
		(layer "In11.Cu")
		(net "JTAG_PCH_GBE_CLK")
	)
	(segment
		(start 450.382386 -9.930384)
		(end 446.011046 -14.301724)
		(width 0.089408)
		(layer "In11.Cu")
		(net "JTAG_PCH_GBE_CLK")
	)
	(segment
		(start 451.409054 -9.926066)
		(end 450.843904 -9.926066)
		(width 0.089408)
		(layer "In11.Cu")
		(net "JTAG_PCH_GBE_CLK")
	)
	(segment
		(start 395.21511 -57.007252)
		(end 395.21511 -60.83554)
		(width 0.089408)
		(layer "In11.Cu")
		(net "JTAG_PCH_GBE_CLK")
	)
	(segment
		(start 401.080224 -77.207618)
		(end 401.572984 -77.700378)
		(width 0.089408)
		(layer "In11.Cu")
		(net "JTAG_PCH_GBE_CLK")
	)
	(segment
		(start 401.385532 -82.12709)
		(end 402.741384 -83.482942)
		(width 0.089408)
		(layer "In11.Cu")
		(net "JTAG_PCH_GBE_CLK")
	)
	(segment
		(start 388.069836 -49.097184)
		(end 389.375142 -50.40249)
		(width 0.089408)
		(layer "In11.Cu")
		(net "JTAG_PCH_GBE_CLK")
	)
	(segment
		(start 381.35052 -42.856912)
		(end 382.834134 -42.856912)
		(width 0.089408)
		(layer "In11.Cu")
		(net "JTAG_PCH_GBE_CLK")
	)
	(segment
		(start 431.968656 -16.021558)
		(end 420.027608 -16.021558)
		(width 0.089408)
		(layer "In11.Cu")
		(net "JTAG_PCH_GBE_CLK")
	)
	(segment
		(start 379.330712 -36.91255)
		(end 379.330712 -37.851842)
		(width 0.089408)
		(layer "In11.Cu")
		(net "JTAG_PCH_GBE_CLK")
	)
	(segment
		(start 395.21511 -60.83554)
		(end 396.34795 -61.96838)
		(width 0.089408)
		(layer "In11.Cu")
		(net "JTAG_PCH_GBE_CLK")
	)
	(segment
		(start 403.310344 -93.232986)
		(end 403.310344 -99.52609)
		(width 0.089408)
		(layer "In11.Cu")
		(net "JTAG_PCH_GBE_CLK")
	)
	(segment
		(start 388.069836 -48.092614)
		(end 388.069836 -49.097184)
		(width 0.089408)
		(layer "In11.Cu")
		(net "JTAG_PCH_GBE_CLK")
	)
	(segment
		(start 379.840998 -41.205658)
		(end 379.840998 -41.34739)
		(width 0.089408)
		(layer "In11.Cu")
		(net "JTAG_PCH_GBE_CLK")
	)
	(segment
		(start 379.931168 -18.318734)
		(end 379.931168 -18.857976)
		(width 0.089408)
		(layer "In11.Cu")
		(net "JTAG_PCH_GBE_CLK")
	)
	(segment
		(start 408.690064 -32.134556)
		(end 409.090114 -31.734506)
		(width 0.089408)
		(layer "F.Cu")
		(net "JTAG_BMC_TMS")
	)
	(segment
		(start 394.9192 -0.2286)
		(end 394.9192 -0.8636)
		(width 0.10795)
		(layer "F.Cu")
		(net "JTAG_BMC_TMS")
	)
	(via
		(at 486.8418 -31.1658)
		(size 0.6604)
		(drill 0.3302)
		(layers "F.Cu" "B.Cu")
		(net "JTAG_BMC_TMS")
	)
	(via
		(at 482.553264 -59.69889)
		(size 0.508)
		(drill 0.254)
		(layers "F.Cu" "B.Cu")
		(net "JTAG_BMC_TMS")
	)
	(via
		(at 409.090114 -31.734506)
		(size 0.4572)
		(drill 0.2032)
		(layers "F.Cu" "B.Cu")
		(net "JTAG_BMC_TMS")
	)
	(via
		(at 394.9192 -0.8636)
		(size 0.508)
		(drill 0.254)
		(layers "F.Cu" "B.Cu")
		(net "JTAG_BMC_TMS")
	)
	(via
		(at 442.7474 -142.6718)
		(size 0.508)
		(drill 0.254)
		(layers "F.Cu" "B.Cu")
		(net "JTAG_BMC_TMS")
	)
	(via
		(at 473.617798 -51.272694)
		(size 0.508)
		(drill 0.254)
		(layers "F.Cu" "B.Cu")
		(net "JTAG_BMC_TMS")
	)
	(via
		(at 424.958256 -113.289588)
		(size 0.508)
		(drill 0.254)
		(layers "F.Cu" "B.Cu")
		(net "JTAG_BMC_TMS")
	)
	(via
		(at 487.296206 -53.978302)
		(size 0.508)
		(drill 0.254)
		(layers "F.Cu" "B.Cu")
		(net "JTAG_BMC_TMS")
	)
	(via
		(at 487.604308 -31.98368)
		(size 0.508)
		(drill 0.254)
		(layers "F.Cu" "B.Cu")
		(net "JTAG_BMC_TMS")
	)
	(segment
		(start 442.7474 -142.6718)
		(end 442.341 -143.0782)
		(width 0.10795)
		(layer "B.Cu")
		(net "JTAG_BMC_TMS")
	)
	(segment
		(start 443.9158 -145.9992)
		(end 446.172336 -145.9992)
		(width 0.10795)
		(layer "B.Cu")
		(net "JTAG_BMC_TMS")
	)
	(segment
		(start 441.969398 -144.161002)
		(end 441.969398 -146.180048)
		(width 0.10795)
		(layer "B.Cu")
		(net "JTAG_BMC_TMS")
	)
	(segment
		(start 442.341 -143.533368)
		(end 442.070998 -143.80337)
		(width 0.10795)
		(layer "B.Cu")
		(net "JTAG_BMC_TMS")
	)
	(segment
		(start 446.630044 -145.541492)
		(end 446.630044 -144.765268)
		(width 0.10795)
		(layer "B.Cu")
		(net "JTAG_BMC_TMS")
	)
	(segment
		(start 486.8418 -31.221172)
		(end 486.8418 -31.1658)
		(width 0.10795)
		(layer "B.Cu")
		(net "JTAG_BMC_TMS")
	)
	(segment
		(start 442.070998 -144.059402)
		(end 441.969398 -144.161002)
		(width 0.10795)
		(layer "B.Cu")
		(net "JTAG_BMC_TMS")
	)
	(segment
		(start 442.22035 -146.431)
		(end 443.484 -146.431)
		(width 0.10795)
		(layer "B.Cu")
		(net "JTAG_BMC_TMS")
	)
	(segment
		(start 442.341 -143.0782)
		(end 442.341 -143.533368)
		(width 0.10795)
		(layer "B.Cu")
		(net "JTAG_BMC_TMS")
	)
	(segment
		(start 443.484 -146.431)
		(end 443.9158 -145.9992)
		(width 0.10795)
		(layer "B.Cu")
		(net "JTAG_BMC_TMS")
	)
	(segment
		(start 446.172336 -145.9992)
		(end 446.630044 -145.541492)
		(width 0.10795)
		(layer "B.Cu")
		(net "JTAG_BMC_TMS")
	)
	(segment
		(start 442.070998 -143.80337)
		(end 442.070998 -144.059402)
		(width 0.10795)
		(layer "B.Cu")
		(net "JTAG_BMC_TMS")
	)
	(segment
		(start 441.969398 -146.180048)
		(end 442.22035 -146.431)
		(width 0.10795)
		(layer "B.Cu")
		(net "JTAG_BMC_TMS")
	)
	(segment
		(start 487.604308 -31.98368)
		(end 486.8418 -31.221172)
		(width 0.10795)
		(layer "B.Cu")
		(net "JTAG_BMC_TMS")
	)
	(segment
		(start 425.83608 -80.481932)
		(end 425.835826 -80.482186)
		(width 0.089408)
		(layer "In2.Cu")
		(net "JTAG_BMC_TMS")
	)
	(segment
		(start 487.040936 -54.233572)
		(end 483.623366 -54.233572)
		(width 0.089408)
		(layer "In2.Cu")
		(net "JTAG_BMC_TMS")
	)
	(segment
		(start 425.497244 -112.7506)
		(end 424.958256 -113.289588)
		(width 0.089408)
		(layer "In2.Cu")
		(net "JTAG_BMC_TMS")
	)
	(segment
		(start 425.215304 -77.090524)
		(end 425.215304 -78.129638)
		(width 0.089408)
		(layer "In2.Cu")
		(net "JTAG_BMC_TMS")
	)
	(segment
		(start 483.623366 -54.233572)
		(end 482.342698 -52.952904)
		(width 0.089408)
		(layer "In2.Cu")
		(net "JTAG_BMC_TMS")
	)
	(segment
		(start 479.171 -60.392818)
		(end 473.747338 -65.81648)
		(width 0.089408)
		(layer "In2.Cu")
		(net "JTAG_BMC_TMS")
	)
	(segment
		(start 480.993196 -50.461418)
		(end 480.724972 -50.193194)
		(width 0.089408)
		(layer "In2.Cu")
		(net "JTAG_BMC_TMS")
	)
	(segment
		(start 425.83608 -79.362808)
		(end 425.83608 -80.481932)
		(width 0.089408)
		(layer "In2.Cu")
		(net "JTAG_BMC_TMS")
	)
	(segment
		(start 424.52417 -75.525122)
		(end 425.215558 -76.21651)
		(width 0.089408)
		(layer "In2.Cu")
		(net "JTAG_BMC_TMS")
	)
	(segment
		(start 481.859336 -60.392818)
		(end 479.171 -60.392818)
		(width 0.089408)
		(layer "In2.Cu")
		(net "JTAG_BMC_TMS")
	)
	(segment
		(start 427.55058 -65.81648)
		(end 427.550326 -65.816226)
		(width 0.089408)
		(layer "In2.Cu")
		(net "JTAG_BMC_TMS")
	)
	(segment
		(start 425.080176 -111.857536)
		(end 425.497244 -112.274604)
		(width 0.089408)
		(layer "In2.Cu")
		(net "JTAG_BMC_TMS")
	)
	(segment
		(start 425.835826 -110.770162)
		(end 425.080176 -111.525812)
		(width 0.089408)
		(layer "In2.Cu")
		(net "JTAG_BMC_TMS")
	)
	(segment
		(start 482.342698 -51.214274)
		(end 481.589842 -50.461418)
		(width 0.089408)
		(layer "In2.Cu")
		(net "JTAG_BMC_TMS")
	)
	(segment
		(start 425.215558 -76.21651)
		(end 425.215558 -77.09027)
		(width 0.089408)
		(layer "In2.Cu")
		(net "JTAG_BMC_TMS")
	)
	(segment
		(start 427.550326 -65.816226)
		(end 426.832522 -65.816226)
		(width 0.089408)
		(layer "In2.Cu")
		(net "JTAG_BMC_TMS")
	)
	(segment
		(start 480.724972 -50.193194)
		(end 475.83725 -50.193194)
		(width 0.089408)
		(layer "In2.Cu")
		(net "JTAG_BMC_TMS")
	)
	(segment
		(start 425.080176 -111.525812)
		(end 425.080176 -111.857536)
		(width 0.089408)
		(layer "In2.Cu")
		(net "JTAG_BMC_TMS")
	)
	(segment
		(start 425.835826 -78.75016)
		(end 425.835826 -79.362554)
		(width 0.089408)
		(layer "In2.Cu")
		(net "JTAG_BMC_TMS")
	)
	(segment
		(start 473.747338 -65.81648)
		(end 427.55058 -65.81648)
		(width 0.089408)
		(layer "In2.Cu")
		(net "JTAG_BMC_TMS")
	)
	(segment
		(start 424.52417 -68.124578)
		(end 424.52417 -75.525122)
		(width 0.089408)
		(layer "In2.Cu")
		(net "JTAG_BMC_TMS")
	)
	(segment
		(start 425.835826 -79.362554)
		(end 425.83608 -79.362808)
		(width 0.089408)
		(layer "In2.Cu")
		(net "JTAG_BMC_TMS")
	)
	(segment
		(start 425.497244 -112.274604)
		(end 425.497244 -112.7506)
		(width 0.089408)
		(layer "In2.Cu")
		(net "JTAG_BMC_TMS")
	)
	(segment
		(start 426.832522 -65.816226)
		(end 424.52417 -68.124578)
		(width 0.089408)
		(layer "In2.Cu")
		(net "JTAG_BMC_TMS")
	)
	(segment
		(start 482.342698 -52.952904)
		(end 482.342698 -51.214274)
		(width 0.089408)
		(layer "In2.Cu")
		(net "JTAG_BMC_TMS")
	)
	(segment
		(start 487.296206 -53.978302)
		(end 487.040936 -54.233572)
		(width 0.089408)
		(layer "In2.Cu")
		(net "JTAG_BMC_TMS")
	)
	(segment
		(start 475.83725 -50.193194)
		(end 474.75775 -51.272694)
		(width 0.089408)
		(layer "In2.Cu")
		(net "JTAG_BMC_TMS")
	)
	(segment
		(start 474.75775 -51.272694)
		(end 473.617798 -51.272694)
		(width 0.089408)
		(layer "In2.Cu")
		(net "JTAG_BMC_TMS")
	)
	(segment
		(start 425.215304 -78.129638)
		(end 425.835826 -78.75016)
		(width 0.089408)
		(layer "In2.Cu")
		(net "JTAG_BMC_TMS")
	)
	(segment
		(start 425.835826 -80.482186)
		(end 425.835826 -110.770162)
		(width 0.089408)
		(layer "In2.Cu")
		(net "JTAG_BMC_TMS")
	)
	(segment
		(start 482.553264 -59.69889)
		(end 481.859336 -60.392818)
		(width 0.089408)
		(layer "In2.Cu")
		(net "JTAG_BMC_TMS")
	)
	(segment
		(start 481.589842 -50.461418)
		(end 480.993196 -50.461418)
		(width 0.089408)
		(layer "In2.Cu")
		(net "JTAG_BMC_TMS")
	)
	(segment
		(start 425.215558 -77.09027)
		(end 425.215304 -77.090524)
		(width 0.089408)
		(layer "In2.Cu")
		(net "JTAG_BMC_TMS")
	)
	(segment
		(start 409.090114 -31.734506)
		(end 409.500832 -32.145224)
		(width 0.089408)
		(layer "In4.Cu")
		(net "JTAG_BMC_TMS")
	)
	(segment
		(start 412.827724 0.998982)
		(end 412.226252 0.998982)
		(width 0.089408)
		(layer "In4.Cu")
		(net "JTAG_BMC_TMS")
	)
	(segment
		(start 405.432514 1.572768)
		(end 404.436072 0.576326)
		(width 0.089408)
		(layer "In4.Cu")
		(net "JTAG_BMC_TMS")
	)
	(segment
		(start 404.436072 0.576326)
		(end 403.8346 0.576326)
		(width 0.089408)
		(layer "In4.Cu")
		(net "JTAG_BMC_TMS")
	)
	(segment
		(start 420.826438 -31.201106)
		(end 420.934642 -31.30931)
		(width 0.089408)
		(layer "In4.Cu")
		(net "JTAG_BMC_TMS")
	)
	(segment
		(start 474.65615 -50.677826)
		(end 474.061282 -51.272694)
		(width 0.089408)
		(layer "In4.Cu")
		(net "JTAG_BMC_TMS")
	)
	(segment
		(start 444.290196 -26.499058)
		(end 444.290196 -29.280104)
		(width 0.089408)
		(layer "In4.Cu")
		(net "JTAG_BMC_TMS")
	)
	(segment
		(start 472.66733 -43.948096)
		(end 473.91955 -43.948096)
		(width 0.089408)
		(layer "In4.Cu")
		(net "JTAG_BMC_TMS")
	)
	(segment
		(start 420.455852 -31.33471)
		(end 420.589456 -31.201106)
		(width 0.089408)
		(layer "In4.Cu")
		(net "JTAG_BMC_TMS")
	)
	(segment
		(start 446.263522 -31.87192)
		(end 449.35648 -31.87192)
		(width 0.089408)
		(layer "In4.Cu")
		(net "JTAG_BMC_TMS")
	)
	(segment
		(start 413.131762 -32.624522)
		(end 414.382712 -32.624522)
		(width 0.089408)
		(layer "In4.Cu")
		(net "JTAG_BMC_TMS")
	)
	(segment
		(start 457.637896 -10.300462)
		(end 457.637896 -9.341104)
		(width 0.089408)
		(layer "In4.Cu")
		(net "JTAG_BMC_TMS")
	)
	(segment
		(start 466.790024 -37.51199)
		(end 467.21395 -37.51199)
		(width 0.089408)
		(layer "In4.Cu")
		(net "JTAG_BMC_TMS")
	)
	(segment
		(start 421.728138 -30.502606)
		(end 421.734742 -30.50921)
		(width 0.089408)
		(layer "In4.Cu")
		(net "JTAG_BMC_TMS")
	)
	(segment
		(start 425.221908 -30.07614)
		(end 425.880276 -29.417772)
		(width 0.089408)
		(layer "In4.Cu")
		(net "JTAG_BMC_TMS")
	)
	(segment
		(start 420.589456 -31.201106)
		(end 420.826438 -31.201106)
		(width 0.089408)
		(layer "In4.Cu")
		(net "JTAG_BMC_TMS")
	)
	(segment
		(start 431.880518 -27.610816)
		(end 433.168044 -27.610816)
		(width 0.089408)
		(layer "In4.Cu")
		(net "JTAG_BMC_TMS")
	)
	(segment
		(start 419.872922 -30.779974)
		(end 419.872922 -31.083504)
		(width 0.089408)
		(layer "In4.Cu")
		(net "JTAG_BMC_TMS")
	)
	(segment
		(start 457.100432 -7.911592)
		(end 455.549254 -7.911592)
		(width 0.089408)
		(layer "In4.Cu")
		(net "JTAG_BMC_TMS")
	)
	(segment
		(start 482.843586 -25.962356)
		(end 482.843586 -23.058882)
		(width 0.089408)
		(layer "In4.Cu")
		(net "JTAG_BMC_TMS")
	)
	(segment
		(start 444.290196 -29.280104)
		(end 446.000378 -30.990286)
		(width 0.089408)
		(layer "In4.Cu")
		(net "JTAG_BMC_TMS")
	)
	(segment
		(start 455.549254 -7.911592)
		(end 454.602088 -6.964426)
		(width 0.089408)
		(layer "In4.Cu")
		(net "JTAG_BMC_TMS")
	)
	(segment
		(start 412.226252 0.998982)
		(end 411.652466 1.572768)
		(width 0.089408)
		(layer "In4.Cu")
		(net "JTAG_BMC_TMS")
	)
	(segment
		(start 414.571434 0.999236)
		(end 412.827978 0.999236)
		(width 0.089408)
		(layer "In4.Cu")
		(net "JTAG_BMC_TMS")
	)
	(segment
		(start 474.65615 -44.684696)
		(end 474.65615 -50.677826)
		(width 0.089408)
		(layer "In4.Cu")
		(net "JTAG_BMC_TMS")
	)
	(segment
		(start 431.688748 -0.924052)
		(end 430.002696 0.762)
		(width 0.089408)
		(layer "In4.Cu")
		(net "JTAG_BMC_TMS")
	)
	(segment
		(start 422.534842 -29.75991)
		(end 422.845738 -29.75991)
		(width 0.089408)
		(layer "In4.Cu")
		(net "JTAG_BMC_TMS")
	)
	(segment
		(start 422.26484 -30.029912)
		(end 422.534842 -29.75991)
		(width 0.089408)
		(layer "In4.Cu")
		(net "JTAG_BMC_TMS")
	)
	(segment
		(start 482.843586 -23.058882)
		(end 477.652588 -17.867884)
		(width 0.089408)
		(layer "In4.Cu")
		(net "JTAG_BMC_TMS")
	)
	(segment
		(start 400.246088 0.794512)
		(end 400.017488 1.023112)
		(width 0.089408)
		(layer "In4.Cu")
		(net "JTAG_BMC_TMS")
	)
	(segment
		(start 419.872922 -31.083504)
		(end 420.124128 -31.33471)
		(width 0.089408)
		(layer "In4.Cu")
		(net "JTAG_BMC_TMS")
	)
	(segment
		(start 468.339424 -38.637464)
		(end 468.339424 -40.435276)
		(width 0.089408)
		(layer "In4.Cu")
		(net "JTAG_BMC_TMS")
	)
	(segment
		(start 418.741352 -31.126176)
		(end 419.307518 -30.56001)
		(width 0.089408)
		(layer "In4.Cu")
		(net "JTAG_BMC_TMS")
	)
	(segment
		(start 471.907616 -43.188382)
		(end 472.66733 -43.948096)
		(width 0.089408)
		(layer "In4.Cu")
		(net "JTAG_BMC_TMS")
	)
	(segment
		(start 470.496646 -12.65174)
		(end 469.213692 -11.368786)
		(width 0.089408)
		(layer "In4.Cu")
		(net "JTAG_BMC_TMS")
	)
	(segment
		(start 422.845738 -29.75991)
		(end 423.16273 -30.07614)
		(width 0.089408)
		(layer "In4.Cu")
		(net "JTAG_BMC_TMS")
	)
	(segment
		(start 476.831152 -17.867884)
		(end 471.615008 -12.65174)
		(width 0.089408)
		(layer "In4.Cu")
		(net "JTAG_BMC_TMS")
	)
	(segment
		(start 409.500832 -32.675322)
		(end 409.734766 -32.909256)
		(width 0.089408)
		(layer "In4.Cu")
		(net "JTAG_BMC_TMS")
	)
	(segment
		(start 454.602088 -5.513324)
		(end 450.012816 -0.924052)
		(width 0.089408)
		(layer "In4.Cu")
		(net "JTAG_BMC_TMS")
	)
	(segment
		(start 487.35615 -31.735522)
		(end 487.35615 -30.551374)
		(width 0.089408)
		(layer "In4.Cu")
		(net "JTAG_BMC_TMS")
	)
	(segment
		(start 486.65892 -29.854144)
		(end 486.036874 -29.854144)
		(width 0.089408)
		(layer "In4.Cu")
		(net "JTAG_BMC_TMS")
	)
	(segment
		(start 401.905216 0.57658)
		(end 401.687284 0.794512)
		(width 0.089408)
		(layer "In4.Cu")
		(net "JTAG_BMC_TMS")
	)
	(segment
		(start 409.734766 -32.909256)
		(end 412.847028 -32.909256)
		(width 0.089408)
		(layer "In4.Cu")
		(net "JTAG_BMC_TMS")
	)
	(segment
		(start 454.602088 -6.964426)
		(end 454.602088 -5.513324)
		(width 0.089408)
		(layer "In4.Cu")
		(net "JTAG_BMC_TMS")
	)
	(segment
		(start 446.000378 -31.608776)
		(end 446.263522 -31.87192)
		(width 0.089408)
		(layer "In4.Cu")
		(net "JTAG_BMC_TMS")
	)
	(segment
		(start 415.881058 -31.126176)
		(end 418.741352 -31.126176)
		(width 0.089408)
		(layer "In4.Cu")
		(net "JTAG_BMC_TMS")
	)
	(segment
		(start 415.873692 2.301494)
		(end 414.571434 0.999236)
		(width 0.089408)
		(layer "In4.Cu")
		(net "JTAG_BMC_TMS")
	)
	(segment
		(start 401.687284 0.794512)
		(end 400.246088 0.794512)
		(width 0.089408)
		(layer "In4.Cu")
		(net "JTAG_BMC_TMS")
	)
	(segment
		(start 430.073562 -29.417772)
		(end 431.880518 -27.610816)
		(width 0.089408)
		(layer "In4.Cu")
		(net "JTAG_BMC_TMS")
	)
	(segment
		(start 458.70622 -11.368786)
		(end 457.637896 -10.300462)
		(width 0.089408)
		(layer "In4.Cu")
		(net "JTAG_BMC_TMS")
	)
	(segment
		(start 469.213692 -11.368786)
		(end 458.70622 -11.368786)
		(width 0.089408)
		(layer "In4.Cu")
		(net "JTAG_BMC_TMS")
	)
	(segment
		(start 422.045638 -30.50921)
		(end 422.26484 -30.290008)
		(width 0.089408)
		(layer "In4.Cu")
		(net "JTAG_BMC_TMS")
	)
	(segment
		(start 403.8346 0.576326)
		(end 403.834346 0.57658)
		(width 0.089408)
		(layer "In4.Cu")
		(net "JTAG_BMC_TMS")
	)
	(segment
		(start 487.35615 -30.551374)
		(end 486.65892 -29.854144)
		(width 0.089408)
		(layer "In4.Cu")
		(net "JTAG_BMC_TMS")
	)
	(segment
		(start 421.46474 -30.766004)
		(end 421.728138 -30.502606)
		(width 0.089408)
		(layer "In4.Cu")
		(net "JTAG_BMC_TMS")
	)
	(segment
		(start 449.35648 -31.87192)
		(end 452.35622 -34.87166)
		(width 0.089408)
		(layer "In4.Cu")
		(net "JTAG_BMC_TMS")
	)
	(segment
		(start 420.934642 -31.30931)
		(end 421.245538 -31.30931)
		(width 0.089408)
		(layer "In4.Cu")
		(net "JTAG_BMC_TMS")
	)
	(segment
		(start 430.002696 0.762)
		(end 422.331896 0.762)
		(width 0.089408)
		(layer "In4.Cu")
		(net "JTAG_BMC_TMS")
	)
	(segment
		(start 421.734742 -30.50921)
		(end 422.045638 -30.50921)
		(width 0.089408)
		(layer "In4.Cu")
		(net "JTAG_BMC_TMS")
	)
	(segment
		(start 465.082128 -35.804094)
		(end 466.790024 -37.51199)
		(width 0.089408)
		(layer "In4.Cu")
		(net "JTAG_BMC_TMS")
	)
	(segment
		(start 409.500832 -32.145224)
		(end 409.500832 -32.675322)
		(width 0.089408)
		(layer "In4.Cu")
		(net "JTAG_BMC_TMS")
	)
	(segment
		(start 471.244422 -41.014142)
		(end 471.907616 -41.677336)
		(width 0.089408)
		(layer "In4.Cu")
		(net "JTAG_BMC_TMS")
	)
	(segment
		(start 474.061282 -51.272694)
		(end 473.617798 -51.272694)
		(width 0.089408)
		(layer "In4.Cu")
		(net "JTAG_BMC_TMS")
	)
	(segment
		(start 457.637896 -9.341104)
		(end 457.784708 -9.194292)
		(width 0.089408)
		(layer "In4.Cu")
		(net "JTAG_BMC_TMS")
	)
	(segment
		(start 443.249558 -25.45842)
		(end 444.290196 -26.499058)
		(width 0.089408)
		(layer "In4.Cu")
		(net "JTAG_BMC_TMS")
	)
	(segment
		(start 486.036874 -29.854144)
		(end 483.535228 -27.352498)
		(width 0.089408)
		(layer "In4.Cu")
		(net "JTAG_BMC_TMS")
	)
	(segment
		(start 412.847028 -32.909256)
		(end 413.131762 -32.624522)
		(width 0.089408)
		(layer "In4.Cu")
		(net "JTAG_BMC_TMS")
	)
	(segment
		(start 452.35622 -34.87166)
		(end 458.653134 -34.87166)
		(width 0.089408)
		(layer "In4.Cu")
		(net "JTAG_BMC_TMS")
	)
	(segment
		(start 467.21395 -37.51199)
		(end 468.339424 -38.637464)
		(width 0.089408)
		(layer "In4.Cu")
		(net "JTAG_BMC_TMS")
	)
	(segment
		(start 414.382712 -32.624522)
		(end 415.881058 -31.126176)
		(width 0.089408)
		(layer "In4.Cu")
		(net "JTAG_BMC_TMS")
	)
	(segment
		(start 462.931002 -35.804094)
		(end 465.082128 -35.804094)
		(width 0.089408)
		(layer "In4.Cu")
		(net "JTAG_BMC_TMS")
	)
	(segment
		(start 412.827978 0.999236)
		(end 412.827724 0.998982)
		(width 0.089408)
		(layer "In4.Cu")
		(net "JTAG_BMC_TMS")
	)
	(segment
		(start 468.339424 -40.435276)
		(end 468.91829 -41.014142)
		(width 0.089408)
		(layer "In4.Cu")
		(net "JTAG_BMC_TMS")
	)
	(segment
		(start 446.000378 -30.990286)
		(end 446.000378 -31.608776)
		(width 0.089408)
		(layer "In4.Cu")
		(net "JTAG_BMC_TMS")
	)
	(segment
		(start 400.017488 1.023112)
		(end 396.805912 1.023112)
		(width 0.089408)
		(layer "In4.Cu")
		(net "JTAG_BMC_TMS")
	)
	(segment
		(start 422.331896 0.762)
		(end 420.792402 2.301494)
		(width 0.089408)
		(layer "In4.Cu")
		(net "JTAG_BMC_TMS")
	)
	(segment
		(start 468.91829 -41.014142)
		(end 471.244422 -41.014142)
		(width 0.089408)
		(layer "In4.Cu")
		(net "JTAG_BMC_TMS")
	)
	(segment
		(start 477.652588 -17.867884)
		(end 476.831152 -17.867884)
		(width 0.089408)
		(layer "In4.Cu")
		(net "JTAG_BMC_TMS")
	)
	(segment
		(start 420.792402 2.301494)
		(end 415.873692 2.301494)
		(width 0.089408)
		(layer "In4.Cu")
		(net "JTAG_BMC_TMS")
	)
	(segment
		(start 473.91955 -43.948096)
		(end 474.65615 -44.684696)
		(width 0.089408)
		(layer "In4.Cu")
		(net "JTAG_BMC_TMS")
	)
	(segment
		(start 419.307518 -30.56001)
		(end 419.652958 -30.56001)
		(width 0.089408)
		(layer "In4.Cu")
		(net "JTAG_BMC_TMS")
	)
	(segment
		(start 396.805912 1.023112)
		(end 394.9192 -0.8636)
		(width 0.089408)
		(layer "In4.Cu")
		(net "JTAG_BMC_TMS")
	)
	(segment
		(start 403.834346 0.57658)
		(end 401.905216 0.57658)
		(width 0.089408)
		(layer "In4.Cu")
		(net "JTAG_BMC_TMS")
	)
	(segment
		(start 471.615008 -12.65174)
		(end 470.496646 -12.65174)
		(width 0.089408)
		(layer "In4.Cu")
		(net "JTAG_BMC_TMS")
	)
	(segment
		(start 411.652466 1.572768)
		(end 405.432514 1.572768)
		(width 0.089408)
		(layer "In4.Cu")
		(net "JTAG_BMC_TMS")
	)
	(segment
		(start 457.784708 -8.595868)
		(end 457.100432 -7.911592)
		(width 0.089408)
		(layer "In4.Cu")
		(net "JTAG_BMC_TMS")
	)
	(segment
		(start 435.32044 -25.45842)
		(end 443.249558 -25.45842)
		(width 0.089408)
		(layer "In4.Cu")
		(net "JTAG_BMC_TMS")
	)
	(segment
		(start 420.124128 -31.33471)
		(end 420.455852 -31.33471)
		(width 0.089408)
		(layer "In4.Cu")
		(net "JTAG_BMC_TMS")
	)
	(segment
		(start 462.477612 -35.350704)
		(end 462.931002 -35.804094)
		(width 0.089408)
		(layer "In4.Cu")
		(net "JTAG_BMC_TMS")
	)
	(segment
		(start 487.604308 -31.98368)
		(end 487.35615 -31.735522)
		(width 0.089408)
		(layer "In4.Cu")
		(net "JTAG_BMC_TMS")
	)
	(segment
		(start 421.245538 -31.30931)
		(end 421.46474 -31.090108)
		(width 0.089408)
		(layer "In4.Cu")
		(net "JTAG_BMC_TMS")
	)
	(segment
		(start 471.907616 -41.677336)
		(end 471.907616 -43.188382)
		(width 0.089408)
		(layer "In4.Cu")
		(net "JTAG_BMC_TMS")
	)
	(segment
		(start 459.132178 -35.350704)
		(end 462.477612 -35.350704)
		(width 0.089408)
		(layer "In4.Cu")
		(net "JTAG_BMC_TMS")
	)
	(segment
		(start 483.535228 -26.653998)
		(end 482.843586 -25.962356)
		(width 0.089408)
		(layer "In4.Cu")
		(net "JTAG_BMC_TMS")
	)
	(segment
		(start 425.880276 -29.417772)
		(end 430.073562 -29.417772)
		(width 0.089408)
		(layer "In4.Cu")
		(net "JTAG_BMC_TMS")
	)
	(segment
		(start 423.16273 -30.07614)
		(end 425.221908 -30.07614)
		(width 0.089408)
		(layer "In4.Cu")
		(net "JTAG_BMC_TMS")
	)
	(segment
		(start 433.168044 -27.610816)
		(end 435.32044 -25.45842)
		(width 0.089408)
		(layer "In4.Cu")
		(net "JTAG_BMC_TMS")
	)
	(segment
		(start 483.535228 -27.352498)
		(end 483.535228 -26.653998)
		(width 0.089408)
		(layer "In4.Cu")
		(net "JTAG_BMC_TMS")
	)
	(segment
		(start 458.653134 -34.87166)
		(end 459.132178 -35.350704)
		(width 0.089408)
		(layer "In4.Cu")
		(net "JTAG_BMC_TMS")
	)
	(segment
		(start 421.46474 -31.090108)
		(end 421.46474 -30.766004)
		(width 0.089408)
		(layer "In4.Cu")
		(net "JTAG_BMC_TMS")
	)
	(segment
		(start 457.784708 -9.194292)
		(end 457.784708 -8.595868)
		(width 0.089408)
		(layer "In4.Cu")
		(net "JTAG_BMC_TMS")
	)
	(segment
		(start 422.26484 -30.290008)
		(end 422.26484 -30.029912)
		(width 0.089408)
		(layer "In4.Cu")
		(net "JTAG_BMC_TMS")
	)
	(segment
		(start 419.652958 -30.56001)
		(end 419.872922 -30.779974)
		(width 0.089408)
		(layer "In4.Cu")
		(net "JTAG_BMC_TMS")
	)
	(segment
		(start 450.012816 -0.924052)
		(end 431.688748 -0.924052)
		(width 0.089408)
		(layer "In4.Cu")
		(net "JTAG_BMC_TMS")
	)
	(segment
		(start 489.0516 -36.3982)
		(end 488.4928 -35.8394)
		(width 0.089408)
		(layer "In9.Cu")
		(net "JTAG_BMC_TMS")
	)
	(segment
		(start 423.539666 -124.038868)
		(end 423.539666 -127.01016)
		(width 0.089408)
		(layer "In9.Cu")
		(net "JTAG_BMC_TMS")
	)
	(segment
		(start 487.616246 -53.658262)
		(end 487.616246 -52.438554)
		(width 0.089408)
		(layer "In9.Cu")
		(net "JTAG_BMC_TMS")
	)
	(segment
		(start 424.528234 -119.564658)
		(end 424.113198 -119.979694)
		(width 0.089408)
		(layer "In9.Cu")
		(net "JTAG_BMC_TMS")
	)
	(segment
		(start 424.318684 -117.22227)
		(end 424.528234 -117.43182)
		(width 0.089408)
		(layer "In9.Cu")
		(net "JTAG_BMC_TMS")
	)
	(segment
		(start 486.6894 -58.203338)
		(end 484.935784 -59.956954)
		(width 0.089408)
		(layer "In9.Cu")
		(net "JTAG_BMC_TMS")
	)
	(segment
		(start 488.668314 -51.386486)
		(end 488.668314 -50.04308)
		(width 0.089408)
		(layer "In9.Cu")
		(net "JTAG_BMC_TMS")
	)
	(segment
		(start 484.935784 -59.956954)
		(end 482.811328 -59.956954)
		(width 0.089408)
		(layer "In9.Cu")
		(net "JTAG_BMC_TMS")
	)
	(segment
		(start 443.516512 -142.6718)
		(end 442.7474 -142.6718)
		(width 0.089408)
		(layer "In9.Cu")
		(net "JTAG_BMC_TMS")
	)
	(segment
		(start 488.4928 -32.872172)
		(end 487.604308 -31.98368)
		(width 0.089408)
		(layer "In9.Cu")
		(net "JTAG_BMC_TMS")
	)
	(segment
		(start 424.282362 -123.296172)
		(end 423.539666 -124.038868)
		(width 0.089408)
		(layer "In9.Cu")
		(net "JTAG_BMC_TMS")
	)
	(segment
		(start 489.0516 -39.0398)
		(end 489.0516 -36.3982)
		(width 0.089408)
		(layer "In9.Cu")
		(net "JTAG_BMC_TMS")
	)
	(segment
		(start 423.539666 -127.01016)
		(end 424.700954 -128.171448)
		(width 0.089408)
		(layer "In9.Cu")
		(net "JTAG_BMC_TMS")
	)
	(segment
		(start 424.847004 -121.352818)
		(end 424.847004 -123.000262)
		(width 0.089408)
		(layer "In9.Cu")
		(net "JTAG_BMC_TMS")
	)
	(segment
		(start 441.071 -137.217658)
		(end 443.60592 -139.752578)
		(width 0.089408)
		(layer "In9.Cu")
		(net "JTAG_BMC_TMS")
	)
	(segment
		(start 441.071 -133.114034)
		(end 441.071 -137.217658)
		(width 0.089408)
		(layer "In9.Cu")
		(net "JTAG_BMC_TMS")
	)
	(segment
		(start 424.113198 -119.979694)
		(end 424.113198 -120.619012)
		(width 0.089408)
		(layer "In9.Cu")
		(net "JTAG_BMC_TMS")
	)
	(segment
		(start 443.60592 -142.582392)
		(end 443.516512 -142.6718)
		(width 0.089408)
		(layer "In9.Cu")
		(net "JTAG_BMC_TMS")
	)
	(segment
		(start 429.038512 -127.693166)
		(end 429.117252 -127.614426)
		(width 0.089408)
		(layer "In9.Cu")
		(net "JTAG_BMC_TMS")
	)
	(segment
		(start 424.958256 -113.289588)
		(end 424.54322 -113.704624)
		(width 0.089408)
		(layer "In9.Cu")
		(net "JTAG_BMC_TMS")
	)
	(segment
		(start 487.616246 -52.438554)
		(end 488.668314 -51.386486)
		(width 0.089408)
		(layer "In9.Cu")
		(net "JTAG_BMC_TMS")
	)
	(segment
		(start 443.60592 -139.752578)
		(end 443.60592 -142.582392)
		(width 0.089408)
		(layer "In9.Cu")
		(net "JTAG_BMC_TMS")
	)
	(segment
		(start 488.117388 -47.097188)
		(end 488.117388 -39.974012)
		(width 0.089408)
		(layer "In9.Cu")
		(net "JTAG_BMC_TMS")
	)
	(segment
		(start 489.350304 -48.330104)
		(end 488.117388 -47.097188)
		(width 0.089408)
		(layer "In9.Cu")
		(net "JTAG_BMC_TMS")
	)
	(segment
		(start 426.614082 -127.693166)
		(end 429.038512 -127.693166)
		(width 0.089408)
		(layer "In9.Cu")
		(net "JTAG_BMC_TMS")
	)
	(segment
		(start 488.4928 -35.8394)
		(end 488.4928 -32.872172)
		(width 0.089408)
		(layer "In9.Cu")
		(net "JTAG_BMC_TMS")
	)
	(segment
		(start 429.4886 -127.614426)
		(end 429.632618 -127.758444)
		(width 0.089408)
		(layer "In9.Cu")
		(net "JTAG_BMC_TMS")
	)
	(segment
		(start 429.117252 -127.614426)
		(end 429.4886 -127.614426)
		(width 0.089408)
		(layer "In9.Cu")
		(net "JTAG_BMC_TMS")
	)
	(segment
		(start 488.117388 -39.974012)
		(end 489.0516 -39.0398)
		(width 0.089408)
		(layer "In9.Cu")
		(net "JTAG_BMC_TMS")
	)
	(segment
		(start 488.651296 -49.694338)
		(end 489.350304 -48.99533)
		(width 0.089408)
		(layer "In9.Cu")
		(net "JTAG_BMC_TMS")
	)
	(segment
		(start 482.811328 -59.956954)
		(end 482.553264 -59.69889)
		(width 0.089408)
		(layer "In9.Cu")
		(net "JTAG_BMC_TMS")
	)
	(segment
		(start 489.350304 -48.99533)
		(end 489.350304 -48.330104)
		(width 0.089408)
		(layer "In9.Cu")
		(net "JTAG_BMC_TMS")
	)
	(segment
		(start 488.668314 -50.04308)
		(end 488.651296 -50.026062)
		(width 0.089408)
		(layer "In9.Cu")
		(net "JTAG_BMC_TMS")
	)
	(segment
		(start 487.296206 -53.978302)
		(end 487.296206 -55.063898)
		(width 0.089408)
		(layer "In9.Cu")
		(net "JTAG_BMC_TMS")
	)
	(segment
		(start 429.632618 -127.758444)
		(end 430.234598 -127.758444)
		(width 0.089408)
		(layer "In9.Cu")
		(net "JTAG_BMC_TMS")
	)
	(segment
		(start 488.651296 -50.026062)
		(end 488.651296 -49.694338)
		(width 0.089408)
		(layer "In9.Cu")
		(net "JTAG_BMC_TMS")
	)
	(segment
		(start 439.127646 -131.17068)
		(end 441.071 -133.114034)
		(width 0.089408)
		(layer "In9.Cu")
		(net "JTAG_BMC_TMS")
	)
	(segment
		(start 424.700954 -128.171448)
		(end 426.1358 -128.171448)
		(width 0.089408)
		(layer "In9.Cu")
		(net "JTAG_BMC_TMS")
	)
	(segment
		(start 424.551094 -123.296172)
		(end 424.282362 -123.296172)
		(width 0.089408)
		(layer "In9.Cu")
		(net "JTAG_BMC_TMS")
	)
	(segment
		(start 424.847004 -123.000262)
		(end 424.551094 -123.296172)
		(width 0.089408)
		(layer "In9.Cu")
		(net "JTAG_BMC_TMS")
	)
	(segment
		(start 430.234598 -127.758444)
		(end 433.646834 -131.17068)
		(width 0.089408)
		(layer "In9.Cu")
		(net "JTAG_BMC_TMS")
	)
	(segment
		(start 424.528234 -117.43182)
		(end 424.528234 -119.564658)
		(width 0.089408)
		(layer "In9.Cu")
		(net "JTAG_BMC_TMS")
	)
	(segment
		(start 426.1358 -128.171448)
		(end 426.614082 -127.693166)
		(width 0.089408)
		(layer "In9.Cu")
		(net "JTAG_BMC_TMS")
	)
	(segment
		(start 486.6894 -55.670704)
		(end 486.6894 -58.203338)
		(width 0.089408)
		(layer "In9.Cu")
		(net "JTAG_BMC_TMS")
	)
	(segment
		(start 424.54322 -114.4016)
		(end 424.318684 -114.626136)
		(width 0.089408)
		(layer "In9.Cu")
		(net "JTAG_BMC_TMS")
	)
	(segment
		(start 487.296206 -55.063898)
		(end 486.6894 -55.670704)
		(width 0.089408)
		(layer "In9.Cu")
		(net "JTAG_BMC_TMS")
	)
	(segment
		(start 424.318684 -114.626136)
		(end 424.318684 -117.22227)
		(width 0.089408)
		(layer "In9.Cu")
		(net "JTAG_BMC_TMS")
	)
	(segment
		(start 433.646834 -131.17068)
		(end 439.127646 -131.17068)
		(width 0.089408)
		(layer "In9.Cu")
		(net "JTAG_BMC_TMS")
	)
	(segment
		(start 424.54322 -113.704624)
		(end 424.54322 -114.4016)
		(width 0.089408)
		(layer "In9.Cu")
		(net "JTAG_BMC_TMS")
	)
	(segment
		(start 424.113198 -120.619012)
		(end 424.847004 -121.352818)
		(width 0.089408)
		(layer "In9.Cu")
		(net "JTAG_BMC_TMS")
	)
	(segment
		(start 487.296206 -53.978302)
		(end 487.616246 -53.658262)
		(width 0.089408)
		(layer "In9.Cu")
		(net "JTAG_BMC_TMS")
	)
	(segment
		(start 409.490164 -34.534602)
		(end 409.090114 -34.934652)
		(width 0.10795)
		(layer "F.Cu")
		(net "JTAG_BMC_TDO")
	)
	(segment
		(start 386.1054 -0.254)
		(end 386.1054 -0.889)
		(width 0.10795)
		(layer "F.Cu")
		(net "JTAG_BMC_TDO")
	)
	(via
		(at 471.893646 -37.612066)
		(size 0.508)
		(drill 0.254)
		(layers "F.Cu" "B.Cu")
		(net "JTAG_BMC_TDO")
	)
	(via
		(at 386.1054 -0.889)
		(size 0.508)
		(drill 0.254)
		(layers "F.Cu" "B.Cu")
		(net "JTAG_BMC_TDO")
	)
	(via
		(at 441.474352 -139.954)
		(size 0.508)
		(drill 0.254)
		(layers "F.Cu" "B.Cu")
		(net "JTAG_BMC_TDO")
	)
	(via
		(at 461.0481 -6.7691)
		(size 0.508)
		(drill 0.254)
		(layers "F.Cu" "B.Cu")
		(net "JTAG_BMC_TDO")
	)
	(via
		(at 409.090114 -34.934652)
		(size 0.4572)
		(drill 0.2032)
		(layers "F.Cu" "B.Cu")
		(net "JTAG_BMC_TDO")
	)
	(via
		(at 478.701354 -59.68365)
		(size 0.508)
		(drill 0.254)
		(layers "F.Cu" "B.Cu")
		(net "JTAG_BMC_TDO")
	)
	(via
		(at 491.374176 -32.501078)
		(size 0.508)
		(drill 0.254)
		(layers "F.Cu" "B.Cu")
		(net "JTAG_BMC_TDO")
	)
	(via
		(at 424.170348 -111.94669)
		(size 0.508)
		(drill 0.254)
		(layers "F.Cu" "B.Cu")
		(net "JTAG_BMC_TDO")
	)
	(segment
		(start 447.129916 -141.261084)
		(end 447.129916 -141.665452)
		(width 0.10795)
		(layer "B.Cu")
		(net "JTAG_BMC_TDO")
	)
	(segment
		(start 446.927986 -139.7)
		(end 447.421 -140.193014)
		(width 0.10795)
		(layer "B.Cu")
		(net "JTAG_BMC_TDO")
	)
	(segment
		(start 445.135 -139.7)
		(end 446.927986 -139.7)
		(width 0.10795)
		(layer "B.Cu")
		(net "JTAG_BMC_TDO")
	)
	(segment
		(start 444.881 -139.954)
		(end 445.135 -139.7)
		(width 0.10795)
		(layer "B.Cu")
		(net "JTAG_BMC_TDO")
	)
	(segment
		(start 441.474352 -139.954)
		(end 444.881 -139.954)
		(width 0.10795)
		(layer "B.Cu")
		(net "JTAG_BMC_TDO")
	)
	(segment
		(start 447.421 -140.97)
		(end 447.129916 -141.261084)
		(width 0.10795)
		(layer "B.Cu")
		(net "JTAG_BMC_TDO")
	)
	(segment
		(start 447.421 -140.193014)
		(end 447.421 -140.97)
		(width 0.10795)
		(layer "B.Cu")
		(net "JTAG_BMC_TDO")
	)
	(segment
		(start 425.161202 -79.030068)
		(end 424.54068 -78.409546)
		(width 0.089408)
		(layer "In2.Cu")
		(net "JTAG_BMC_TDO")
	)
	(segment
		(start 388.422896 -1.04267)
		(end 388.422896 -0.723138)
		(width 0.089408)
		(layer "In2.Cu")
		(net "JTAG_BMC_TDO")
	)
	(segment
		(start 461.734916 -1.791462)
		(end 462.31048 -2.367026)
		(width 0.089408)
		(layer "In2.Cu")
		(net "JTAG_BMC_TDO")
	)
	(segment
		(start 461.0481 -5.387086)
		(end 461.0481 -6.7691)
		(width 0.089408)
		(layer "In2.Cu")
		(net "JTAG_BMC_TDO")
	)
	(segment
		(start 473.53855 -37.991288)
		(end 475.436692 -36.093146)
		(width 0.089408)
		(layer "In2.Cu")
		(net "JTAG_BMC_TDO")
	)
	(segment
		(start 420.649908 1.740408)
		(end 422.193212 0.197104)
		(width 0.089408)
		(layer "In2.Cu")
		(net "JTAG_BMC_TDO")
	)
	(segment
		(start 485.388412 -18.1356)
		(end 479.72218 -18.1356)
		(width 0.089408)
		(layer "In2.Cu")
		(net "JTAG_BMC_TDO")
	)
	(segment
		(start 486.46588 -36.265358)
		(end 487.767122 -34.964116)
		(width 0.089408)
		(layer "In2.Cu")
		(net "JTAG_BMC_TDO")
	)
	(segment
		(start 441.641992 -2.19583)
		(end 441.641992 -2.60223)
		(width 0.089408)
		(layer "In2.Cu")
		(net "JTAG_BMC_TDO")
	)
	(segment
		(start 476.353124 -36.310062)
		(end 476.553276 -36.310062)
		(width 0.089408)
		(layer "In2.Cu")
		(net "JTAG_BMC_TDO")
	)
	(segment
		(start 486.46588 -36.393374)
		(end 486.46588 -36.265358)
		(width 0.089408)
		(layer "In2.Cu")
		(net "JTAG_BMC_TDO")
	)
	(segment
		(start 427.830234 -65.141602)
		(end 427.830488 -65.141856)
		(width 0.089408)
		(layer "In2.Cu")
		(net "JTAG_BMC_TDO")
	)
	(segment
		(start 479.763836 -35.395408)
		(end 480.937824 -36.569396)
		(width 0.089408)
		(layer "In2.Cu")
		(net "JTAG_BMC_TDO")
	)
	(segment
		(start 483.064566 -37.082984)
		(end 485.77627 -37.082984)
		(width 0.089408)
		(layer "In2.Cu")
		(net "JTAG_BMC_TDO")
	)
	(segment
		(start 490.229906 -25.884632)
		(end 490.229906 -22.977094)
		(width 0.089408)
		(layer "In2.Cu")
		(net "JTAG_BMC_TDO")
	)
	(segment
		(start 476.00108 -10.882376)
		(end 474.528896 -9.410192)
		(width 0.089408)
		(layer "In2.Cu")
		(net "JTAG_BMC_TDO")
	)
	(segment
		(start 480.937824 -36.569396)
		(end 481.63607 -36.569396)
		(width 0.089408)
		(layer "In2.Cu")
		(net "JTAG_BMC_TDO")
	)
	(segment
		(start 441.048902 -1.60274)
		(end 441.641992 -2.19583)
		(width 0.089408)
		(layer "In2.Cu")
		(net "JTAG_BMC_TDO")
	)
	(segment
		(start 478.701354 -59.805316)
		(end 478.701354 -59.68365)
		(width 0.089408)
		(layer "In2.Cu")
		(net "JTAG_BMC_TDO")
	)
	(segment
		(start 425.349162 0.197104)
		(end 426.053504 -0.507238)
		(width 0.089408)
		(layer "In2.Cu")
		(net "JTAG_BMC_TDO")
	)
	(segment
		(start 468.6554 -63.7032)
		(end 469.8238 -62.5348)
		(width 0.089408)
		(layer "In2.Cu")
		(net "JTAG_BMC_TDO")
	)
	(segment
		(start 404.749 0.5588)
		(end 405.930608 1.740408)
		(width 0.089408)
		(layer "In2.Cu")
		(net "JTAG_BMC_TDO")
	)
	(segment
		(start 425.161202 -80.202278)
		(end 425.161456 -80.202024)
		(width 0.089408)
		(layer "In2.Cu")
		(net "JTAG_BMC_TDO")
	)
	(segment
		(start 425.161456 -80.202024)
		(end 425.161456 -79.642716)
		(width 0.089408)
		(layer "In2.Cu")
		(net "JTAG_BMC_TDO")
	)
	(segment
		(start 400.252184 -0.432816)
		(end 401.2438 0.5588)
		(width 0.089408)
		(layer "In2.Cu")
		(net "JTAG_BMC_TDO")
	)
	(segment
		(start 424.133264 -111.94669)
		(end 424.386248 -111.693706)
		(width 0.089408)
		(layer "In2.Cu")
		(net "JTAG_BMC_TDO")
	)
	(segment
		(start 491.374176 -31.227268)
		(end 491.882176 -30.719268)
		(width 0.089408)
		(layer "In2.Cu")
		(net "JTAG_BMC_TDO")
	)
	(segment
		(start 465.870544 -65.141856)
		(end 467.3092 -63.7032)
		(width 0.089408)
		(layer "In2.Cu")
		(net "JTAG_BMC_TDO")
	)
	(segment
		(start 388.713218 -0.432816)
		(end 400.252184 -0.432816)
		(width 0.089408)
		(layer "In2.Cu")
		(net "JTAG_BMC_TDO")
	)
	(segment
		(start 401.2438 0.5588)
		(end 404.749 0.5588)
		(width 0.089408)
		(layer "In2.Cu")
		(net "JTAG_BMC_TDO")
	)
	(segment
		(start 462.31048 -2.367026)
		(end 462.31048 -2.647442)
		(width 0.089408)
		(layer "In2.Cu")
		(net "JTAG_BMC_TDO")
	)
	(segment
		(start 477.29648 -15.7099)
		(end 477.29648 -14.790674)
		(width 0.089408)
		(layer "In2.Cu")
		(net "JTAG_BMC_TDO")
	)
	(segment
		(start 426.053504 -0.507238)
		(end 426.053504 -1.105154)
		(width 0.089408)
		(layer "In2.Cu")
		(net "JTAG_BMC_TDO")
	)
	(segment
		(start 476.00108 -11.23442)
		(end 476.00108 -10.882376)
		(width 0.089408)
		(layer "In2.Cu")
		(net "JTAG_BMC_TDO")
	)
	(segment
		(start 477.29648 -14.790674)
		(end 476.81896 -14.313154)
		(width 0.089408)
		(layer "In2.Cu")
		(net "JTAG_BMC_TDO")
	)
	(segment
		(start 487.767122 -34.964116)
		(end 490.823758 -34.964116)
		(width 0.089408)
		(layer "In2.Cu")
		(net "JTAG_BMC_TDO")
	)
	(segment
		(start 426.552614 -65.141602)
		(end 427.830234 -65.141602)
		(width 0.089408)
		(layer "In2.Cu")
		(net "JTAG_BMC_TDO")
	)
	(segment
		(start 472.272868 -37.991288)
		(end 473.53855 -37.991288)
		(width 0.089408)
		(layer "In2.Cu")
		(net "JTAG_BMC_TDO")
	)
	(segment
		(start 491.882176 -27.536902)
		(end 490.229906 -25.884632)
		(width 0.089408)
		(layer "In2.Cu")
		(net "JTAG_BMC_TDO")
	)
	(segment
		(start 456.240134 -1.080008)
		(end 459.71206 -1.080008)
		(width 0.089408)
		(layer "In2.Cu")
		(net "JTAG_BMC_TDO")
	)
	(segment
		(start 479.72218 -18.1356)
		(end 477.29648 -15.7099)
		(width 0.089408)
		(layer "In2.Cu")
		(net "JTAG_BMC_TDO")
	)
	(segment
		(start 471.8304 -62.5348)
		(end 472.7194 -63.4238)
		(width 0.089408)
		(layer "In2.Cu")
		(net "JTAG_BMC_TDO")
	)
	(segment
		(start 491.374176 -32.501078)
		(end 491.374176 -31.227268)
		(width 0.089408)
		(layer "In2.Cu")
		(net "JTAG_BMC_TDO")
	)
	(segment
		(start 476.81896 -12.0523)
		(end 476.00108 -11.23442)
		(width 0.089408)
		(layer "In2.Cu")
		(net "JTAG_BMC_TDO")
	)
	(segment
		(start 442.16447 -3.124708)
		(end 450.459602 -3.124708)
		(width 0.089408)
		(layer "In2.Cu")
		(net "JTAG_BMC_TDO")
	)
	(segment
		(start 386.1054 -0.889)
		(end 386.6642 -0.889)
		(width 0.089408)
		(layer "In2.Cu")
		(net "JTAG_BMC_TDO")
	)
	(segment
		(start 426.053504 -1.105154)
		(end 426.55109 -1.60274)
		(width 0.089408)
		(layer "In2.Cu")
		(net "JTAG_BMC_TDO")
	)
	(segment
		(start 485.77627 -37.082984)
		(end 486.46588 -36.393374)
		(width 0.089408)
		(layer "In2.Cu")
		(net "JTAG_BMC_TDO")
	)
	(segment
		(start 476.553276 -36.310062)
		(end 476.55353 -36.309808)
		(width 0.089408)
		(layer "In2.Cu")
		(net "JTAG_BMC_TDO")
	)
	(segment
		(start 482.772974 -37.374576)
		(end 483.064566 -37.082984)
		(width 0.089408)
		(layer "In2.Cu")
		(net "JTAG_BMC_TDO")
	)
	(segment
		(start 491.882176 -30.719268)
		(end 491.882176 -27.536902)
		(width 0.089408)
		(layer "In2.Cu")
		(net "JTAG_BMC_TDO")
	)
	(segment
		(start 450.459602 -3.124708)
		(end 452.664322 -0.919988)
		(width 0.089408)
		(layer "In2.Cu")
		(net "JTAG_BMC_TDO")
	)
	(segment
		(start 476.136208 -36.093146)
		(end 476.353124 -36.310062)
		(width 0.089408)
		(layer "In2.Cu")
		(net "JTAG_BMC_TDO")
	)
	(segment
		(start 467.184486 -9.91108)
		(end 467.087966 -9.81456)
		(width 0.089408)
		(layer "In2.Cu")
		(net "JTAG_BMC_TDO")
	)
	(segment
		(start 426.55109 -1.60274)
		(end 441.048902 -1.60274)
		(width 0.089408)
		(layer "In2.Cu")
		(net "JTAG_BMC_TDO")
	)
	(segment
		(start 424.54068 -78.409546)
		(end 424.54068 -76.496164)
		(width 0.089408)
		(layer "In2.Cu")
		(net "JTAG_BMC_TDO")
	)
	(segment
		(start 388.170166 -1.2954)
		(end 388.422896 -1.04267)
		(width 0.089408)
		(layer "In2.Cu")
		(net "JTAG_BMC_TDO")
	)
	(segment
		(start 460.423514 -1.791462)
		(end 461.734916 -1.791462)
		(width 0.089408)
		(layer "In2.Cu")
		(net "JTAG_BMC_TDO")
	)
	(segment
		(start 424.386248 -111.693706)
		(end 424.386248 -111.18469)
		(width 0.089408)
		(layer "In2.Cu")
		(net "JTAG_BMC_TDO")
	)
	(segment
		(start 423.849546 -67.84467)
		(end 426.552614 -65.141602)
		(width 0.089408)
		(layer "In2.Cu")
		(net "JTAG_BMC_TDO")
	)
	(segment
		(start 491.374176 -34.413698)
		(end 491.374176 -32.501078)
		(width 0.089408)
		(layer "In2.Cu")
		(net "JTAG_BMC_TDO")
	)
	(segment
		(start 477.72193 -36.309808)
		(end 478.63633 -35.395408)
		(width 0.089408)
		(layer "In2.Cu")
		(net "JTAG_BMC_TDO")
	)
	(segment
		(start 424.54068 -76.496164)
		(end 423.849546 -75.80503)
		(width 0.089408)
		(layer "In2.Cu")
		(net "JTAG_BMC_TDO")
	)
	(segment
		(start 459.71206 -1.080008)
		(end 460.423514 -1.791462)
		(width 0.089408)
		(layer "In2.Cu")
		(net "JTAG_BMC_TDO")
	)
	(segment
		(start 467.087966 -9.81456)
		(end 465.935822 -9.81456)
		(width 0.089408)
		(layer "In2.Cu")
		(net "JTAG_BMC_TDO")
	)
	(segment
		(start 425.161202 -79.642462)
		(end 425.161202 -79.030068)
		(width 0.089408)
		(layer "In2.Cu")
		(net "JTAG_BMC_TDO")
	)
	(segment
		(start 471.02522 -9.91108)
		(end 467.184486 -9.91108)
		(width 0.089408)
		(layer "In2.Cu")
		(net "JTAG_BMC_TDO")
	)
	(segment
		(start 456.080114 -0.919988)
		(end 456.240134 -1.080008)
		(width 0.089408)
		(layer "In2.Cu")
		(net "JTAG_BMC_TDO")
	)
	(segment
		(start 467.3092 -63.7032)
		(end 468.6554 -63.7032)
		(width 0.089408)
		(layer "In2.Cu")
		(net "JTAG_BMC_TDO")
	)
	(segment
		(start 481.63607 -36.569396)
		(end 482.44125 -37.374576)
		(width 0.089408)
		(layer "In2.Cu")
		(net "JTAG_BMC_TDO")
	)
	(segment
		(start 490.823758 -34.964116)
		(end 491.374176 -34.413698)
		(width 0.089408)
		(layer "In2.Cu")
		(net "JTAG_BMC_TDO")
	)
	(segment
		(start 441.641992 -2.60223)
		(end 442.16447 -3.124708)
		(width 0.089408)
		(layer "In2.Cu")
		(net "JTAG_BMC_TDO")
	)
	(segment
		(start 475.08287 -63.4238)
		(end 478.701354 -59.805316)
		(width 0.089408)
		(layer "In2.Cu")
		(net "JTAG_BMC_TDO")
	)
	(segment
		(start 388.422896 -0.723138)
		(end 388.713218 -0.432816)
		(width 0.089408)
		(layer "In2.Cu")
		(net "JTAG_BMC_TDO")
	)
	(segment
		(start 472.7194 -63.4238)
		(end 475.08287 -63.4238)
		(width 0.089408)
		(layer "In2.Cu")
		(net "JTAG_BMC_TDO")
	)
	(segment
		(start 490.229906 -22.977094)
		(end 485.388412 -18.1356)
		(width 0.089408)
		(layer "In2.Cu")
		(net "JTAG_BMC_TDO")
	)
	(segment
		(start 471.893646 -37.612066)
		(end 472.272868 -37.991288)
		(width 0.089408)
		(layer "In2.Cu")
		(net "JTAG_BMC_TDO")
	)
	(segment
		(start 462.577434 -3.857752)
		(end 461.0481 -5.387086)
		(width 0.089408)
		(layer "In2.Cu")
		(net "JTAG_BMC_TDO")
	)
	(segment
		(start 425.161202 -110.409736)
		(end 425.161202 -80.202278)
		(width 0.089408)
		(layer "In2.Cu")
		(net "JTAG_BMC_TDO")
	)
	(segment
		(start 475.436692 -36.093146)
		(end 476.136208 -36.093146)
		(width 0.089408)
		(layer "In2.Cu")
		(net "JTAG_BMC_TDO")
	)
	(segment
		(start 462.577434 -2.914396)
		(end 462.577434 -3.857752)
		(width 0.089408)
		(layer "In2.Cu")
		(net "JTAG_BMC_TDO")
	)
	(segment
		(start 469.8238 -62.5348)
		(end 471.8304 -62.5348)
		(width 0.089408)
		(layer "In2.Cu")
		(net "JTAG_BMC_TDO")
	)
	(segment
		(start 476.81896 -14.313154)
		(end 476.81896 -12.0523)
		(width 0.089408)
		(layer "In2.Cu")
		(net "JTAG_BMC_TDO")
	)
	(segment
		(start 476.55353 -36.309808)
		(end 477.72193 -36.309808)
		(width 0.089408)
		(layer "In2.Cu")
		(net "JTAG_BMC_TDO")
	)
	(segment
		(start 405.930608 1.740408)
		(end 420.649908 1.740408)
		(width 0.089408)
		(layer "In2.Cu")
		(net "JTAG_BMC_TDO")
	)
	(segment
		(start 471.526108 -9.410192)
		(end 471.02522 -9.91108)
		(width 0.089408)
		(layer "In2.Cu")
		(net "JTAG_BMC_TDO")
	)
	(segment
		(start 461.7085 -7.4295)
		(end 461.0481 -6.7691)
		(width 0.089408)
		(layer "In2.Cu")
		(net "JTAG_BMC_TDO")
	)
	(segment
		(start 452.664322 -0.919988)
		(end 456.080114 -0.919988)
		(width 0.089408)
		(layer "In2.Cu")
		(net "JTAG_BMC_TDO")
	)
	(segment
		(start 424.386248 -111.18469)
		(end 425.161202 -110.409736)
		(width 0.089408)
		(layer "In2.Cu")
		(net "JTAG_BMC_TDO")
	)
	(segment
		(start 387.0706 -1.2954)
		(end 388.170166 -1.2954)
		(width 0.089408)
		(layer "In2.Cu")
		(net "JTAG_BMC_TDO")
	)
	(segment
		(start 478.63633 -35.395408)
		(end 479.763836 -35.395408)
		(width 0.089408)
		(layer "In2.Cu")
		(net "JTAG_BMC_TDO")
	)
	(segment
		(start 424.170348 -111.94669)
		(end 424.133264 -111.94669)
		(width 0.089408)
		(layer "In2.Cu")
		(net "JTAG_BMC_TDO")
	)
	(segment
		(start 462.31048 -2.647442)
		(end 462.577434 -2.914396)
		(width 0.089408)
		(layer "In2.Cu")
		(net "JTAG_BMC_TDO")
	)
	(segment
		(start 482.44125 -37.374576)
		(end 482.772974 -37.374576)
		(width 0.089408)
		(layer "In2.Cu")
		(net "JTAG_BMC_TDO")
	)
	(segment
		(start 422.193212 0.197104)
		(end 425.349162 0.197104)
		(width 0.089408)
		(layer "In2.Cu")
		(net "JTAG_BMC_TDO")
	)
	(segment
		(start 386.6642 -0.889)
		(end 387.0706 -1.2954)
		(width 0.089408)
		(layer "In2.Cu")
		(net "JTAG_BMC_TDO")
	)
	(segment
		(start 425.161456 -79.642716)
		(end 425.161202 -79.642462)
		(width 0.089408)
		(layer "In2.Cu")
		(net "JTAG_BMC_TDO")
	)
	(segment
		(start 463.550762 -7.4295)
		(end 461.7085 -7.4295)
		(width 0.089408)
		(layer "In2.Cu")
		(net "JTAG_BMC_TDO")
	)
	(segment
		(start 427.830488 -65.141856)
		(end 465.870544 -65.141856)
		(width 0.089408)
		(layer "In2.Cu")
		(net "JTAG_BMC_TDO")
	)
	(segment
		(start 474.528896 -9.410192)
		(end 471.526108 -9.410192)
		(width 0.089408)
		(layer "In2.Cu")
		(net "JTAG_BMC_TDO")
	)
	(segment
		(start 465.935822 -9.81456)
		(end 463.550762 -7.4295)
		(width 0.089408)
		(layer "In2.Cu")
		(net "JTAG_BMC_TDO")
	)
	(segment
		(start 423.849546 -75.80503)
		(end 423.849546 -67.84467)
		(width 0.089408)
		(layer "In2.Cu")
		(net "JTAG_BMC_TDO")
	)
	(segment
		(start 491.16361 -38.95598)
		(end 491.16361 -41.856406)
		(width 0.089408)
		(layer "In9.Cu")
		(net "JTAG_BMC_TDO")
	)
	(segment
		(start 479.685604 -60.6679)
		(end 478.701354 -59.68365)
		(width 0.089408)
		(layer "In9.Cu")
		(net "JTAG_BMC_TDO")
	)
	(segment
		(start 492.170974 -51.046126)
		(end 491.0455 -52.1716)
		(width 0.089408)
		(layer "In9.Cu")
		(net "JTAG_BMC_TDO")
	)
	(segment
		(start 423.300144 -116.755672)
		(end 423.300144 -113.284254)
		(width 0.089408)
		(layer "In9.Cu")
		(net "JTAG_BMC_TDO")
	)
	(segment
		(start 492.170974 -49.53254)
		(end 492.170974 -51.046126)
		(width 0.089408)
		(layer "In9.Cu")
		(net "JTAG_BMC_TDO")
	)
	(segment
		(start 439.215022 -135.685784)
		(end 437.253126 -133.723888)
		(width 0.089408)
		(layer "In9.Cu")
		(net "JTAG_BMC_TDO")
	)
	(segment
		(start 491.163864 -46.638464)
		(end 492.170974 -47.645574)
		(width 0.089408)
		(layer "In9.Cu")
		(net "JTAG_BMC_TDO")
	)
	(segment
		(start 490.691424 -38.483794)
		(end 491.16361 -38.95598)
		(width 0.089408)
		(layer "In9.Cu")
		(net "JTAG_BMC_TDO")
	)
	(segment
		(start 487.562398 -58.445654)
		(end 485.340152 -60.6679)
		(width 0.089408)
		(layer "In9.Cu")
		(net "JTAG_BMC_TDO")
	)
	(segment
		(start 423.72026 -112.864138)
		(end 423.72026 -112.396778)
		(width 0.089408)
		(layer "In9.Cu")
		(net "JTAG_BMC_TDO")
	)
	(segment
		(start 487.562144 -56.666384)
		(end 487.562144 -58.245248)
		(width 0.089408)
		(layer "In9.Cu")
		(net "JTAG_BMC_TDO")
	)
	(segment
		(start 491.163864 -41.85666)
		(end 491.163864 -46.638464)
		(width 0.089408)
		(layer "In9.Cu")
		(net "JTAG_BMC_TDO")
	)
	(segment
		(start 419.448234 -124.983748)
		(end 419.145212 -124.680726)
		(width 0.089408)
		(layer "In9.Cu")
		(net "JTAG_BMC_TDO")
	)
	(segment
		(start 441.345574 -139.954)
		(end 439.215022 -137.823448)
		(width 0.089408)
		(layer "In9.Cu")
		(net "JTAG_BMC_TDO")
	)
	(segment
		(start 491.374176 -32.501078)
		(end 491.374176 -36.234624)
		(width 0.089408)
		(layer "In9.Cu")
		(net "JTAG_BMC_TDO")
	)
	(segment
		(start 487.562144 -58.245248)
		(end 487.562398 -58.245502)
		(width 0.089408)
		(layer "In9.Cu")
		(net "JTAG_BMC_TDO")
	)
	(segment
		(start 485.340152 -60.6679)
		(end 479.685604 -60.6679)
		(width 0.089408)
		(layer "In9.Cu")
		(net "JTAG_BMC_TDO")
	)
	(segment
		(start 490.691424 -36.917376)
		(end 490.691424 -38.483794)
		(width 0.089408)
		(layer "In9.Cu")
		(net "JTAG_BMC_TDO")
	)
	(segment
		(start 491.16361 -41.856406)
		(end 491.163864 -41.85666)
		(width 0.089408)
		(layer "In9.Cu")
		(net "JTAG_BMC_TDO")
	)
	(segment
		(start 441.474352 -139.954)
		(end 441.345574 -139.954)
		(width 0.089408)
		(layer "In9.Cu")
		(net "JTAG_BMC_TDO")
	)
	(segment
		(start 491.374176 -36.234624)
		(end 490.691424 -36.917376)
		(width 0.089408)
		(layer "In9.Cu")
		(net "JTAG_BMC_TDO")
	)
	(segment
		(start 424.691556 -131.13131)
		(end 419.448234 -125.887988)
		(width 0.089408)
		(layer "In9.Cu")
		(net "JTAG_BMC_TDO")
	)
	(segment
		(start 491.0455 -52.1716)
		(end 489.407708 -52.1716)
		(width 0.089408)
		(layer "In9.Cu")
		(net "JTAG_BMC_TDO")
	)
	(segment
		(start 419.145212 -124.680726)
		(end 419.145212 -120.910604)
		(width 0.089408)
		(layer "In9.Cu")
		(net "JTAG_BMC_TDO")
	)
	(segment
		(start 423.72026 -112.396778)
		(end 424.170348 -111.94669)
		(width 0.089408)
		(layer "In9.Cu")
		(net "JTAG_BMC_TDO")
	)
	(segment
		(start 430.196498 -133.723888)
		(end 427.60392 -131.13131)
		(width 0.089408)
		(layer "In9.Cu")
		(net "JTAG_BMC_TDO")
	)
	(segment
		(start 492.170974 -49.17186)
		(end 492.156496 -49.186338)
		(width 0.089408)
		(layer "In9.Cu")
		(net "JTAG_BMC_TDO")
	)
	(segment
		(start 488.7468 -55.481728)
		(end 487.562144 -56.666384)
		(width 0.089408)
		(layer "In9.Cu")
		(net "JTAG_BMC_TDO")
	)
	(segment
		(start 487.562398 -58.245502)
		(end 487.562398 -58.445654)
		(width 0.089408)
		(layer "In9.Cu")
		(net "JTAG_BMC_TDO")
	)
	(segment
		(start 419.448234 -125.887988)
		(end 419.448234 -124.983748)
		(width 0.089408)
		(layer "In9.Cu")
		(net "JTAG_BMC_TDO")
	)
	(segment
		(start 489.407708 -52.1716)
		(end 488.7468 -52.832508)
		(width 0.089408)
		(layer "In9.Cu")
		(net "JTAG_BMC_TDO")
	)
	(segment
		(start 492.156496 -49.518062)
		(end 492.170974 -49.53254)
		(width 0.089408)
		(layer "In9.Cu")
		(net "JTAG_BMC_TDO")
	)
	(segment
		(start 427.60392 -131.13131)
		(end 424.691556 -131.13131)
		(width 0.089408)
		(layer "In9.Cu")
		(net "JTAG_BMC_TDO")
	)
	(segment
		(start 419.145212 -120.910604)
		(end 423.300144 -116.755672)
		(width 0.089408)
		(layer "In9.Cu")
		(net "JTAG_BMC_TDO")
	)
	(segment
		(start 492.156496 -49.186338)
		(end 492.156496 -49.518062)
		(width 0.089408)
		(layer "In9.Cu")
		(net "JTAG_BMC_TDO")
	)
	(segment
		(start 439.215022 -137.823448)
		(end 439.215022 -135.685784)
		(width 0.089408)
		(layer "In9.Cu")
		(net "JTAG_BMC_TDO")
	)
	(segment
		(start 423.300144 -113.284254)
		(end 423.72026 -112.864138)
		(width 0.089408)
		(layer "In9.Cu")
		(net "JTAG_BMC_TDO")
	)
	(segment
		(start 492.170974 -47.645574)
		(end 492.170974 -49.17186)
		(width 0.089408)
		(layer "In9.Cu")
		(net "JTAG_BMC_TDO")
	)
	(segment
		(start 488.7468 -52.832508)
		(end 488.7468 -55.481728)
		(width 0.089408)
		(layer "In9.Cu")
		(net "JTAG_BMC_TDO")
	)
	(segment
		(start 437.253126 -133.723888)
		(end 430.196498 -133.723888)
		(width 0.089408)
		(layer "In9.Cu")
		(net "JTAG_BMC_TDO")
	)
	(segment
		(start 444.06693 -39.02837)
		(end 446.415668 -39.02837)
		(width 0.089408)
		(layer "In11.Cu")
		(net "JTAG_BMC_TDO")
	)
	(segment
		(start 409.210764 -34.934652)
		(end 409.600146 -35.324034)
		(width 0.089408)
		(layer "In11.Cu")
		(net "JTAG_BMC_TDO")
	)
	(segment
		(start 468.600282 -38.550088)
		(end 469.81745 -38.550088)
		(width 0.089408)
		(layer "In11.Cu")
		(net "JTAG_BMC_TDO")
	)
	(segment
		(start 470.021412 -38.546786)
		(end 470.958926 -38.546786)
		(width 0.089408)
		(layer "In11.Cu")
		(net "JTAG_BMC_TDO")
	)
	(segment
		(start 463.122518 -38.19144)
		(end 464.33232 -39.401242)
		(width 0.089408)
		(layer "In11.Cu")
		(net "JTAG_BMC_TDO")
	)
	(segment
		(start 455.284586 -37.249862)
		(end 456.226164 -38.19144)
		(width 0.089408)
		(layer "In11.Cu")
		(net "JTAG_BMC_TDO")
	)
	(segment
		(start 448.194176 -37.249862)
		(end 455.284586 -37.249862)
		(width 0.089408)
		(layer "In11.Cu")
		(net "JTAG_BMC_TDO")
	)
	(segment
		(start 446.415668 -39.02837)
		(end 448.194176 -37.249862)
		(width 0.089408)
		(layer "In11.Cu")
		(net "JTAG_BMC_TDO")
	)
	(segment
		(start 413.844486 -35.910266)
		(end 417.562792 -35.910266)
		(width 0.089408)
		(layer "In11.Cu")
		(net "JTAG_BMC_TDO")
	)
	(segment
		(start 456.226164 -38.19144)
		(end 460.804514 -38.19144)
		(width 0.089408)
		(layer "In11.Cu")
		(net "JTAG_BMC_TDO")
	)
	(segment
		(start 469.81745 -38.550088)
		(end 469.817704 -38.550342)
		(width 0.089408)
		(layer "In11.Cu")
		(net "JTAG_BMC_TDO")
	)
	(segment
		(start 470.958926 -38.546786)
		(end 471.893646 -37.612066)
		(width 0.089408)
		(layer "In11.Cu")
		(net "JTAG_BMC_TDO")
	)
	(segment
		(start 417.807394 -36.154868)
		(end 424.538648 -36.154868)
		(width 0.089408)
		(layer "In11.Cu")
		(net "JTAG_BMC_TDO")
	)
	(segment
		(start 417.562792 -35.910266)
		(end 417.807394 -36.154868)
		(width 0.089408)
		(layer "In11.Cu")
		(net "JTAG_BMC_TDO")
	)
	(segment
		(start 434.780944 -39.275766)
		(end 435.02199 -39.275766)
		(width 0.089408)
		(layer "In11.Cu")
		(net "JTAG_BMC_TDO")
	)
	(segment
		(start 460.806292 -38.189662)
		(end 462.990692 -38.189662)
		(width 0.089408)
		(layer "In11.Cu")
		(net "JTAG_BMC_TDO")
	)
	(segment
		(start 443.79642 -39.29888)
		(end 444.06693 -39.02837)
		(width 0.089408)
		(layer "In11.Cu")
		(net "JTAG_BMC_TDO")
	)
	(segment
		(start 462.990692 -38.189662)
		(end 462.99247 -38.19144)
		(width 0.089408)
		(layer "In11.Cu")
		(net "JTAG_BMC_TDO")
	)
	(segment
		(start 424.538648 -36.154868)
		(end 427.14799 -38.76421)
		(width 0.089408)
		(layer "In11.Cu")
		(net "JTAG_BMC_TDO")
	)
	(segment
		(start 462.99247 -38.19144)
		(end 463.122518 -38.19144)
		(width 0.089408)
		(layer "In11.Cu")
		(net "JTAG_BMC_TDO")
	)
	(segment
		(start 409.090114 -34.934652)
		(end 409.210764 -34.934652)
		(width 0.089408)
		(layer "In11.Cu")
		(net "JTAG_BMC_TDO")
	)
	(segment
		(start 435.02199 -39.275766)
		(end 435.045104 -39.29888)
		(width 0.089408)
		(layer "In11.Cu")
		(net "JTAG_BMC_TDO")
	)
	(segment
		(start 430.18075 -38.76421)
		(end 430.766982 -38.177978)
		(width 0.089408)
		(layer "In11.Cu")
		(net "JTAG_BMC_TDO")
	)
	(segment
		(start 464.33232 -39.401242)
		(end 467.749128 -39.401242)
		(width 0.089408)
		(layer "In11.Cu")
		(net "JTAG_BMC_TDO")
	)
	(segment
		(start 433.683156 -38.177978)
		(end 434.780944 -39.275766)
		(width 0.089408)
		(layer "In11.Cu")
		(net "JTAG_BMC_TDO")
	)
	(segment
		(start 460.804514 -38.19144)
		(end 460.806292 -38.189662)
		(width 0.089408)
		(layer "In11.Cu")
		(net "JTAG_BMC_TDO")
	)
	(segment
		(start 467.749128 -39.401242)
		(end 468.600282 -38.550088)
		(width 0.089408)
		(layer "In11.Cu")
		(net "JTAG_BMC_TDO")
	)
	(segment
		(start 435.045104 -39.29888)
		(end 443.79642 -39.29888)
		(width 0.089408)
		(layer "In11.Cu")
		(net "JTAG_BMC_TDO")
	)
	(segment
		(start 469.817704 -38.550342)
		(end 470.017856 -38.550342)
		(width 0.089408)
		(layer "In11.Cu")
		(net "JTAG_BMC_TDO")
	)
	(segment
		(start 430.766982 -38.177978)
		(end 433.683156 -38.177978)
		(width 0.089408)
		(layer "In11.Cu")
		(net "JTAG_BMC_TDO")
	)
	(segment
		(start 427.14799 -38.76421)
		(end 430.18075 -38.76421)
		(width 0.089408)
		(layer "In11.Cu")
		(net "JTAG_BMC_TDO")
	)
	(segment
		(start 413.258254 -35.324034)
		(end 413.844486 -35.910266)
		(width 0.089408)
		(layer "In11.Cu")
		(net "JTAG_BMC_TDO")
	)
	(segment
		(start 470.017856 -38.550342)
		(end 470.021412 -38.546786)
		(width 0.089408)
		(layer "In11.Cu")
		(net "JTAG_BMC_TDO")
	)
	(segment
		(start 409.600146 -35.324034)
		(end 413.258254 -35.324034)
		(width 0.089408)
		(layer "In11.Cu")
		(net "JTAG_BMC_TDO")
	)
	(segment
		(start 409.490164 -35.334702)
		(end 409.090114 -35.734752)
		(width 0.10795)
		(layer "F.Cu")
		(net "JTAG_BMC_TDI")
	)
	(segment
		(start 388.0104 -0.254)
		(end 388.0104 -0.889)
		(width 0.10795)
		(layer "F.Cu")
		(net "JTAG_BMC_TDI")
	)
	(via
		(at 424.133264 -114.034062)
		(size 0.508)
		(drill 0.254)
		(layers "F.Cu" "B.Cu")
		(net "JTAG_BMC_TDI")
	)
	(via
		(at 409.090114 -35.734752)
		(size 0.4572)
		(drill 0.2032)
		(layers "F.Cu" "B.Cu")
		(net "JTAG_BMC_TDI")
	)
	(via
		(at 442.7728 -144.0942)
		(size 0.508)
		(drill 0.254)
		(layers "F.Cu" "B.Cu")
		(net "JTAG_BMC_TDI")
	)
	(via
		(at 388.024878 -70.7898)
		(size 0.508)
		(drill 0.254)
		(layers "F.Cu" "B.Cu")
		(net "JTAG_BMC_TDI")
	)
	(via
		(at 388.0104 -0.889)
		(size 0.508)
		(drill 0.254)
		(layers "F.Cu" "B.Cu")
		(net "JTAG_BMC_TDI")
	)
	(via
		(at 467.327742 -40.476932)
		(size 0.508)
		(drill 0.254)
		(layers "F.Cu" "B.Cu")
		(net "JTAG_BMC_TDI")
	)
	(via
		(at 412.355538 -69.411342)
		(size 0.508)
		(drill 0.254)
		(layers "F.Cu" "B.Cu")
		(net "JTAG_BMC_TDI")
	)
	(via
		(at 423.1386 -113.538)
		(size 0.6604)
		(drill 0.3302)
		(layers "F.Cu" "B.Cu")
		(net "JTAG_BMC_TDI")
	)
	(segment
		(start 418.018214 -80.655668)
		(end 417.219892 -79.857346)
		(width 0.10795)
		(layer "B.Cu")
		(net "JTAG_BMC_TDI")
	)
	(segment
		(start 422.196514 -86.76894)
		(end 421.324532 -85.896958)
		(width 0.10795)
		(layer "B.Cu")
		(net "JTAG_BMC_TDI")
	)
	(segment
		(start 417.219892 -79.857346)
		(end 415.7218 -79.857346)
		(width 0.10795)
		(layer "B.Cu")
		(net "JTAG_BMC_TDI")
	)
	(segment
		(start 415.324798 -79.460344)
		(end 415.324798 -72.58558)
		(width 0.10795)
		(layer "B.Cu")
		(net "JTAG_BMC_TDI")
	)
	(segment
		(start 416.361118 -68.575936)
		(end 416.10026 -68.315078)
		(width 0.10795)
		(layer "B.Cu")
		(net "JTAG_BMC_TDI")
	)
	(segment
		(start 416.10026 -68.315078)
		(end 415.524188 -68.315078)
		(width 0.10795)
		(layer "B.Cu")
		(net "JTAG_BMC_TDI")
	)
	(segment
		(start 418.018214 -83.106006)
		(end 418.018214 -80.655668)
		(width 0.10795)
		(layer "B.Cu")
		(net "JTAG_BMC_TDI")
	)
	(segment
		(start 422.071546 -112.8776)
		(end 422.071546 -103.81488)
		(width 0.10795)
		(layer "B.Cu")
		(net "JTAG_BMC_TDI")
	)
	(segment
		(start 421.324532 -85.314282)
		(end 421.0685 -85.05825)
		(width 0.10795)
		(layer "B.Cu")
		(net "JTAG_BMC_TDI")
	)
	(segment
		(start 423.1386 -113.538)
		(end 422.731946 -113.538)
		(width 0.10795)
		(layer "B.Cu")
		(net "JTAG_BMC_TDI")
	)
	(segment
		(start 422.731946 -113.538)
		(end 422.071546 -112.8776)
		(width 0.10795)
		(layer "B.Cu")
		(net "JTAG_BMC_TDI")
	)
	(segment
		(start 415.558986 -72.351392)
		(end 416.21837 -72.351392)
		(width 0.10795)
		(layer "B.Cu")
		(net "JTAG_BMC_TDI")
	)
	(segment
		(start 415.524188 -68.315078)
		(end 413.839406 -69.99986)
		(width 0.10795)
		(layer "B.Cu")
		(net "JTAG_BMC_TDI")
	)
	(segment
		(start 419.970458 -85.05825)
		(end 418.018214 -83.106006)
		(width 0.10795)
		(layer "B.Cu")
		(net "JTAG_BMC_TDI")
	)
	(segment
		(start 421.324532 -85.896958)
		(end 421.324532 -85.314282)
		(width 0.10795)
		(layer "B.Cu")
		(net "JTAG_BMC_TDI")
	)
	(segment
		(start 412.355538 -69.538342)
		(end 412.355538 -69.411342)
		(width 0.10795)
		(layer "B.Cu")
		(net "JTAG_BMC_TDI")
	)
	(segment
		(start 416.361118 -72.208644)
		(end 416.361118 -68.575936)
		(width 0.10795)
		(layer "B.Cu")
		(net "JTAG_BMC_TDI")
	)
	(segment
		(start 413.839406 -69.99986)
		(end 412.817056 -69.99986)
		(width 0.10795)
		(layer "B.Cu")
		(net "JTAG_BMC_TDI")
	)
	(segment
		(start 422.686988 -103.199438)
		(end 422.686988 -97.196656)
		(width 0.10795)
		(layer "B.Cu")
		(net "JTAG_BMC_TDI")
	)
	(segment
		(start 444.815468 -144.765268)
		(end 444.4492 -144.399)
		(width 0.10795)
		(layer "B.Cu")
		(net "JTAG_BMC_TDI")
	)
	(segment
		(start 422.071546 -103.81488)
		(end 422.686988 -103.199438)
		(width 0.10795)
		(layer "B.Cu")
		(net "JTAG_BMC_TDI")
	)
	(segment
		(start 444.4492 -144.399)
		(end 443.0776 -144.399)
		(width 0.10795)
		(layer "B.Cu")
		(net "JTAG_BMC_TDI")
	)
	(segment
		(start 423.637202 -113.538)
		(end 423.1386 -113.538)
		(width 0.10795)
		(layer "B.Cu")
		(net "JTAG_BMC_TDI")
	)
	(segment
		(start 416.21837 -72.351392)
		(end 416.361118 -72.208644)
		(width 0.10795)
		(layer "B.Cu")
		(net "JTAG_BMC_TDI")
	)
	(segment
		(start 445.12992 -144.765268)
		(end 444.815468 -144.765268)
		(width 0.10795)
		(layer "B.Cu")
		(net "JTAG_BMC_TDI")
	)
	(segment
		(start 415.7218 -79.857346)
		(end 415.324798 -79.460344)
		(width 0.10795)
		(layer "B.Cu")
		(net "JTAG_BMC_TDI")
	)
	(segment
		(start 421.0685 -85.05825)
		(end 419.970458 -85.05825)
		(width 0.10795)
		(layer "B.Cu")
		(net "JTAG_BMC_TDI")
	)
	(segment
		(start 422.196514 -95.1103)
		(end 422.196514 -86.76894)
		(width 0.10795)
		(layer "B.Cu")
		(net "JTAG_BMC_TDI")
	)
	(segment
		(start 443.0776 -144.399)
		(end 442.7728 -144.0942)
		(width 0.10795)
		(layer "B.Cu")
		(net "JTAG_BMC_TDI")
	)
	(segment
		(start 421.959532 -96.4692)
		(end 421.959532 -95.347282)
		(width 0.10795)
		(layer "B.Cu")
		(net "JTAG_BMC_TDI")
	)
	(segment
		(start 412.817056 -69.99986)
		(end 412.355538 -69.538342)
		(width 0.10795)
		(layer "B.Cu")
		(net "JTAG_BMC_TDI")
	)
	(segment
		(start 422.686988 -97.196656)
		(end 421.959532 -96.4692)
		(width 0.10795)
		(layer "B.Cu")
		(net "JTAG_BMC_TDI")
	)
	(segment
		(start 421.959532 -95.347282)
		(end 422.196514 -95.1103)
		(width 0.10795)
		(layer "B.Cu")
		(net "JTAG_BMC_TDI")
	)
	(segment
		(start 424.133264 -114.034062)
		(end 423.637202 -113.538)
		(width 0.10795)
		(layer "B.Cu")
		(net "JTAG_BMC_TDI")
	)
	(segment
		(start 415.324798 -72.58558)
		(end 415.558986 -72.351392)
		(width 0.10795)
		(layer "B.Cu")
		(net "JTAG_BMC_TDI")
	)
	(segment
		(start 492.123984 -30.819598)
		(end 491.8202 -31.123382)
		(width 0.089408)
		(layer "In2.Cu")
		(net "JTAG_BMC_TDI")
	)
	(segment
		(start 456.340464 -0.8382)
		(end 459.81239 -0.8382)
		(width 0.089408)
		(layer "In2.Cu")
		(net "JTAG_BMC_TDI")
	)
	(segment
		(start 487.867452 -35.205924)
		(end 486.707688 -36.365688)
		(width 0.089408)
		(layer "In2.Cu")
		(net "JTAG_BMC_TDI")
	)
	(segment
		(start 492.123984 -27.436572)
		(end 492.123984 -30.819598)
		(width 0.089408)
		(layer "In2.Cu")
		(net "JTAG_BMC_TDI")
	)
	(segment
		(start 461.53705 -6.12775)
		(end 462.534 -7.1247)
		(width 0.089408)
		(layer "In2.Cu")
		(net "JTAG_BMC_TDI")
	)
	(segment
		(start 477.5581 -15.488666)
		(end 479.887534 -17.8181)
		(width 0.089408)
		(layer "In2.Cu")
		(net "JTAG_BMC_TDI")
	)
	(segment
		(start 486.707688 -36.365688)
		(end 486.707688 -36.493704)
		(width 0.089408)
		(layer "In2.Cu")
		(net "JTAG_BMC_TDI")
	)
	(segment
		(start 388.0104 -0.793496)
		(end 388.612888 -0.191008)
		(width 0.089408)
		(layer "In2.Cu")
		(net "JTAG_BMC_TDI")
	)
	(segment
		(start 389.422894 -57.83326)
		(end 389.422894 -59.876436)
		(width 0.089408)
		(layer "In2.Cu")
		(net "JTAG_BMC_TDI")
	)
	(segment
		(start 481.656136 -36.9316)
		(end 477.217232 -36.9316)
		(width 0.089408)
		(layer "In2.Cu")
		(net "JTAG_BMC_TDI")
	)
	(segment
		(start 441.8838 -2.5019)
		(end 442.2648 -2.8829)
		(width 0.089408)
		(layer "In2.Cu")
		(net "JTAG_BMC_TDI")
	)
	(segment
		(start 389.42264 -60.34278)
		(end 390.421622 -61.341762)
		(width 0.089408)
		(layer "In2.Cu")
		(net "JTAG_BMC_TDI")
	)
	(segment
		(start 462.552288 -2.547112)
		(end 462.819242 -2.814066)
		(width 0.089408)
		(layer "In2.Cu")
		(net "JTAG_BMC_TDI")
	)
	(segment
		(start 474.670628 -9.168384)
		(end 476.26016 -10.757916)
		(width 0.089408)
		(layer "In2.Cu")
		(net "JTAG_BMC_TDI")
	)
	(segment
		(start 442.2648 -2.8829)
		(end 450.177154 -2.8829)
		(width 0.089408)
		(layer "In2.Cu")
		(net "JTAG_BMC_TDI")
	)
	(segment
		(start 387.836664 -70.221094)
		(end 388.024878 -70.409308)
		(width 0.089408)
		(layer "In2.Cu")
		(net "JTAG_BMC_TDI")
	)
	(segment
		(start 477.5581 -14.6431)
		(end 477.5581 -15.488666)
		(width 0.089408)
		(layer "In2.Cu")
		(net "JTAG_BMC_TDI")
	)
	(segment
		(start 390.249664 -43.653964)
		(end 389.98779 -43.653964)
		(width 0.089408)
		(layer "In2.Cu")
		(net "JTAG_BMC_TDI")
	)
	(segment
		(start 468.11565 -41.26484)
		(end 467.327742 -40.476932)
		(width 0.089408)
		(layer "In2.Cu")
		(net "JTAG_BMC_TDI")
	)
	(segment
		(start 388.0104 -0.889)
		(end 388.0104 -0.793496)
		(width 0.089408)
		(layer "In2.Cu")
		(net "JTAG_BMC_TDI")
	)
	(segment
		(start 476.26016 -11.151362)
		(end 477.09074 -11.981942)
		(width 0.089408)
		(layer "In2.Cu")
		(net "JTAG_BMC_TDI")
	)
	(segment
		(start 401.14347 0.800608)
		(end 404.64867 0.800608)
		(width 0.089408)
		(layer "In2.Cu")
		(net "JTAG_BMC_TDI")
	)
	(segment
		(start 389.987028 -43.654726)
		(end 388.417054 -43.654726)
		(width 0.089408)
		(layer "In2.Cu")
		(net "JTAG_BMC_TDI")
	)
	(segment
		(start 462.819242 -3.958082)
		(end 461.53705 -5.240274)
		(width 0.089408)
		(layer "In2.Cu")
		(net "JTAG_BMC_TDI")
	)
	(segment
		(start 474.128084 -38.07079)
		(end 472.325192 -39.873682)
		(width 0.089408)
		(layer "In2.Cu")
		(net "JTAG_BMC_TDI")
	)
	(segment
		(start 472.325192 -40.237918)
		(end 471.29827 -41.26484)
		(width 0.089408)
		(layer "In2.Cu")
		(net "JTAG_BMC_TDI")
	)
	(segment
		(start 426.7962 -1.360932)
		(end 441.149232 -1.360932)
		(width 0.089408)
		(layer "In2.Cu")
		(net "JTAG_BMC_TDI")
	)
	(segment
		(start 420.750238 1.982216)
		(end 422.293542 0.438912)
		(width 0.089408)
		(layer "In2.Cu")
		(net "JTAG_BMC_TDI")
	)
	(segment
		(start 482.34092 -37.616384)
		(end 481.656136 -36.9316)
		(width 0.089408)
		(layer "In2.Cu")
		(net "JTAG_BMC_TDI")
	)
	(segment
		(start 390.421622 -61.341762)
		(end 390.421622 -64.144144)
		(width 0.089408)
		(layer "In2.Cu")
		(net "JTAG_BMC_TDI")
	)
	(segment
		(start 471.425778 -9.168384)
		(end 474.670628 -9.168384)
		(width 0.089408)
		(layer "In2.Cu")
		(net "JTAG_BMC_TDI")
	)
	(segment
		(start 450.177154 -2.8829)
		(end 452.399654 -0.6604)
		(width 0.089408)
		(layer "In2.Cu")
		(net "JTAG_BMC_TDI")
	)
	(segment
		(start 476.078042 -38.07079)
		(end 474.128084 -38.07079)
		(width 0.089408)
		(layer "In2.Cu")
		(net "JTAG_BMC_TDI")
	)
	(segment
		(start 388.164578 -55.675022)
		(end 388.695184 -56.205628)
		(width 0.089408)
		(layer "In2.Cu")
		(net "JTAG_BMC_TDI")
	)
	(segment
		(start 460.523844 -1.549654)
		(end 461.835246 -1.549654)
		(width 0.089408)
		(layer "In2.Cu")
		(net "JTAG_BMC_TDI")
	)
	(segment
		(start 389.98779 -43.653964)
		(end 389.987028 -43.654726)
		(width 0.089408)
		(layer "In2.Cu")
		(net "JTAG_BMC_TDI")
	)
	(segment
		(start 482.873304 -37.616384)
		(end 482.34092 -37.616384)
		(width 0.089408)
		(layer "In2.Cu")
		(net "JTAG_BMC_TDI")
	)
	(segment
		(start 399.876518 -36.00958)
		(end 397.480028 -38.40607)
		(width 0.089408)
		(layer "In2.Cu")
		(net "JTAG_BMC_TDI")
	)
	(segment
		(start 459.81239 -0.8382)
		(end 460.523844 -1.549654)
		(width 0.089408)
		(layer "In2.Cu")
		(net "JTAG_BMC_TDI")
	)
	(segment
		(start 491.8202 -31.123382)
		(end 491.8202 -34.41065)
		(width 0.089408)
		(layer "In2.Cu")
		(net "JTAG_BMC_TDI")
	)
	(segment
		(start 483.164896 -37.324792)
		(end 482.873304 -37.616384)
		(width 0.089408)
		(layer "In2.Cu")
		(net "JTAG_BMC_TDI")
	)
	(segment
		(start 491.8202 -34.41065)
		(end 491.024926 -35.205924)
		(width 0.089408)
		(layer "In2.Cu")
		(net "JTAG_BMC_TDI")
	)
	(segment
		(start 390.421622 -64.144144)
		(end 387.836664 -66.729102)
		(width 0.089408)
		(layer "In2.Cu")
		(net "JTAG_BMC_TDI")
	)
	(segment
		(start 388.0612 -70.7898)
		(end 388.024878 -70.7898)
		(width 0.089408)
		(layer "In2.Cu")
		(net "JTAG_BMC_TDI")
	)
	(segment
		(start 467.284816 -9.669272)
		(end 470.92489 -9.669272)
		(width 0.089408)
		(layer "In2.Cu")
		(net "JTAG_BMC_TDI")
	)
	(segment
		(start 462.826862 -7.124954)
		(end 462.827116 -7.1247)
		(width 0.089408)
		(layer "In2.Cu")
		(net "JTAG_BMC_TDI")
	)
	(segment
		(start 463.5881 -7.1247)
		(end 466.036152 -9.572752)
		(width 0.089408)
		(layer "In2.Cu")
		(net "JTAG_BMC_TDI")
	)
	(segment
		(start 485.415844 -37.325046)
		(end 485.41559 -37.324792)
		(width 0.089408)
		(layer "In2.Cu")
		(net "JTAG_BMC_TDI")
	)
	(segment
		(start 409.090114 -35.734752)
		(end 407.844498 -35.734752)
		(width 0.089408)
		(layer "In2.Cu")
		(net "JTAG_BMC_TDI")
	)
	(segment
		(start 406.96515 -36.6141)
		(end 403.377654 -36.6141)
		(width 0.089408)
		(layer "In2.Cu")
		(net "JTAG_BMC_TDI")
	)
	(segment
		(start 394.40612 -38.40607)
		(end 391.937748 -40.874442)
		(width 0.089408)
		(layer "In2.Cu")
		(net "JTAG_BMC_TDI")
	)
	(segment
		(start 452.399654 -0.6604)
		(end 456.162664 -0.6604)
		(width 0.089408)
		(layer "In2.Cu")
		(net "JTAG_BMC_TDI")
	)
	(segment
		(start 470.92489 -9.669272)
		(end 471.425778 -9.168384)
		(width 0.089408)
		(layer "In2.Cu")
		(net "JTAG_BMC_TDI")
	)
	(segment
		(start 387.836664 -66.729102)
		(end 387.836664 -70.221094)
		(width 0.089408)
		(layer "In2.Cu")
		(net "JTAG_BMC_TDI")
	)
	(segment
		(start 462.552288 -2.266696)
		(end 462.552288 -2.547112)
		(width 0.089408)
		(layer "In2.Cu")
		(net "JTAG_BMC_TDI")
	)
	(segment
		(start 425.449492 0.438912)
		(end 426.328332 -0.439928)
		(width 0.089408)
		(layer "In2.Cu")
		(net "JTAG_BMC_TDI")
	)
	(segment
		(start 441.149232 -1.360932)
		(end 441.8838 -2.0955)
		(width 0.089408)
		(layer "In2.Cu")
		(net "JTAG_BMC_TDI")
	)
	(segment
		(start 485.8766 -37.324792)
		(end 485.61625 -37.324792)
		(width 0.089408)
		(layer "In2.Cu")
		(net "JTAG_BMC_TDI")
	)
	(segment
		(start 490.471714 -22.876764)
		(end 490.471714 -25.784302)
		(width 0.089408)
		(layer "In2.Cu")
		(net "JTAG_BMC_TDI")
	)
	(segment
		(start 477.217232 -36.9316)
		(end 476.078042 -38.07079)
		(width 0.089408)
		(layer "In2.Cu")
		(net "JTAG_BMC_TDI")
	)
	(segment
		(start 400.151854 -0.191008)
		(end 401.14347 0.800608)
		(width 0.089408)
		(layer "In2.Cu")
		(net "JTAG_BMC_TDI")
	)
	(segment
		(start 485.61625 -37.324792)
		(end 485.615996 -37.325046)
		(width 0.089408)
		(layer "In2.Cu")
		(net "JTAG_BMC_TDI")
	)
	(segment
		(start 477.09074 -11.981942)
		(end 477.09074 -14.17574)
		(width 0.089408)
		(layer "In2.Cu")
		(net "JTAG_BMC_TDI")
	)
	(segment
		(start 461.53705 -5.240274)
		(end 461.53705 -6.12775)
		(width 0.089408)
		(layer "In2.Cu")
		(net "JTAG_BMC_TDI")
	)
	(segment
		(start 479.887534 -17.8181)
		(end 485.41305 -17.8181)
		(width 0.089408)
		(layer "In2.Cu")
		(net "JTAG_BMC_TDI")
	)
	(segment
		(start 490.471714 -25.784302)
		(end 492.123984 -27.436572)
		(width 0.089408)
		(layer "In2.Cu")
		(net "JTAG_BMC_TDI")
	)
	(segment
		(start 486.707688 -36.493704)
		(end 485.8766 -37.324792)
		(width 0.089408)
		(layer "In2.Cu")
		(net "JTAG_BMC_TDI")
	)
	(segment
		(start 441.8838 -2.0955)
		(end 441.8838 -2.5019)
		(width 0.089408)
		(layer "In2.Cu")
		(net "JTAG_BMC_TDI")
	)
	(segment
		(start 388.417054 -43.654726)
		(end 388.164578 -43.907202)
		(width 0.089408)
		(layer "In2.Cu")
		(net "JTAG_BMC_TDI")
	)
	(segment
		(start 388.612888 -0.191008)
		(end 400.151854 -0.191008)
		(width 0.089408)
		(layer "In2.Cu")
		(net "JTAG_BMC_TDI")
	)
	(segment
		(start 404.64867 0.800608)
		(end 405.830278 1.982216)
		(width 0.089408)
		(layer "In2.Cu")
		(net "JTAG_BMC_TDI")
	)
	(segment
		(start 462.626456 -7.1247)
		(end 462.62671 -7.124954)
		(width 0.089408)
		(layer "In2.Cu")
		(net "JTAG_BMC_TDI")
	)
	(segment
		(start 397.480028 -38.40607)
		(end 394.40612 -38.40607)
		(width 0.089408)
		(layer "In2.Cu")
		(net "JTAG_BMC_TDI")
	)
	(segment
		(start 456.162664 -0.6604)
		(end 456.340464 -0.8382)
		(width 0.089408)
		(layer "In2.Cu")
		(net "JTAG_BMC_TDI")
	)
	(segment
		(start 485.615996 -37.325046)
		(end 485.415844 -37.325046)
		(width 0.089408)
		(layer "In2.Cu")
		(net "JTAG_BMC_TDI")
	)
	(segment
		(start 391.937748 -40.874442)
		(end 391.937748 -41.96588)
		(width 0.089408)
		(layer "In2.Cu")
		(net "JTAG_BMC_TDI")
	)
	(segment
		(start 391.937748 -41.96588)
		(end 390.249664 -43.653964)
		(width 0.089408)
		(layer "In2.Cu")
		(net "JTAG_BMC_TDI")
	)
	(segment
		(start 388.024878 -70.753478)
		(end 388.0612 -70.7898)
		(width 0.089408)
		(layer "In2.Cu")
		(net "JTAG_BMC_TDI")
	)
	(segment
		(start 426.328332 -0.893064)
		(end 426.7962 -1.360932)
		(width 0.089408)
		(layer "In2.Cu")
		(net "JTAG_BMC_TDI")
	)
	(segment
		(start 389.422894 -59.876436)
		(end 389.42264 -59.87669)
		(width 0.089408)
		(layer "In2.Cu")
		(net "JTAG_BMC_TDI")
	)
	(segment
		(start 462.819242 -2.814066)
		(end 462.819242 -3.958082)
		(width 0.089408)
		(layer "In2.Cu")
		(net "JTAG_BMC_TDI")
	)
	(segment
		(start 422.293542 0.438912)
		(end 425.449492 0.438912)
		(width 0.089408)
		(layer "In2.Cu")
		(net "JTAG_BMC_TDI")
	)
	(segment
		(start 407.844498 -35.734752)
		(end 406.96515 -36.6141)
		(width 0.089408)
		(layer "In2.Cu")
		(net "JTAG_BMC_TDI")
	)
	(segment
		(start 388.695184 -57.10555)
		(end 389.422894 -57.83326)
		(width 0.089408)
		(layer "In2.Cu")
		(net "JTAG_BMC_TDI")
	)
	(segment
		(start 485.41559 -37.324792)
		(end 483.164896 -37.324792)
		(width 0.089408)
		(layer "In2.Cu")
		(net "JTAG_BMC_TDI")
	)
	(segment
		(start 476.26016 -10.757916)
		(end 476.26016 -11.151362)
		(width 0.089408)
		(layer "In2.Cu")
		(net "JTAG_BMC_TDI")
	)
	(segment
		(start 388.695184 -56.205628)
		(end 388.695184 -57.10555)
		(width 0.089408)
		(layer "In2.Cu")
		(net "JTAG_BMC_TDI")
	)
	(segment
		(start 485.41305 -17.8181)
		(end 490.471714 -22.876764)
		(width 0.089408)
		(layer "In2.Cu")
		(net "JTAG_BMC_TDI")
	)
	(segment
		(start 402.773134 -36.00958)
		(end 399.876518 -36.00958)
		(width 0.089408)
		(layer "In2.Cu")
		(net "JTAG_BMC_TDI")
	)
	(segment
		(start 472.325192 -39.873682)
		(end 472.325192 -40.237918)
		(width 0.089408)
		(layer "In2.Cu")
		(net "JTAG_BMC_TDI")
	)
	(segment
		(start 466.036152 -9.572752)
		(end 467.188296 -9.572752)
		(width 0.089408)
		(layer "In2.Cu")
		(net "JTAG_BMC_TDI")
	)
	(segment
		(start 388.024878 -70.409308)
		(end 388.024878 -70.753478)
		(width 0.089408)
		(layer "In2.Cu")
		(net "JTAG_BMC_TDI")
	)
	(segment
		(start 426.328332 -0.439928)
		(end 426.328332 -0.893064)
		(width 0.089408)
		(layer "In2.Cu")
		(net "JTAG_BMC_TDI")
	)
	(segment
		(start 461.835246 -1.549654)
		(end 462.552288 -2.266696)
		(width 0.089408)
		(layer "In2.Cu")
		(net "JTAG_BMC_TDI")
	)
	(segment
		(start 462.534 -7.1247)
		(end 462.626456 -7.1247)
		(width 0.089408)
		(layer "In2.Cu")
		(net "JTAG_BMC_TDI")
	)
	(segment
		(start 462.827116 -7.1247)
		(end 463.5881 -7.1247)
		(width 0.089408)
		(layer "In2.Cu")
		(net "JTAG_BMC_TDI")
	)
	(segment
		(start 403.377654 -36.6141)
		(end 402.773134 -36.00958)
		(width 0.089408)
		(layer "In2.Cu")
		(net "JTAG_BMC_TDI")
	)
	(segment
		(start 462.62671 -7.124954)
		(end 462.826862 -7.124954)
		(width 0.089408)
		(layer "In2.Cu")
		(net "JTAG_BMC_TDI")
	)
	(segment
		(start 471.29827 -41.26484)
		(end 468.11565 -41.26484)
		(width 0.089408)
		(layer "In2.Cu")
		(net "JTAG_BMC_TDI")
	)
	(segment
		(start 477.09074 -14.17574)
		(end 477.5581 -14.6431)
		(width 0.089408)
		(layer "In2.Cu")
		(net "JTAG_BMC_TDI")
	)
	(segment
		(start 491.024926 -35.205924)
		(end 487.867452 -35.205924)
		(width 0.089408)
		(layer "In2.Cu")
		(net "JTAG_BMC_TDI")
	)
	(segment
		(start 467.188296 -9.572752)
		(end 467.284816 -9.669272)
		(width 0.089408)
		(layer "In2.Cu")
		(net "JTAG_BMC_TDI")
	)
	(segment
		(start 389.42264 -59.87669)
		(end 389.42264 -60.34278)
		(width 0.089408)
		(layer "In2.Cu")
		(net "JTAG_BMC_TDI")
	)
	(segment
		(start 405.830278 1.982216)
		(end 420.750238 1.982216)
		(width 0.089408)
		(layer "In2.Cu")
		(net "JTAG_BMC_TDI")
	)
	(segment
		(start 388.164578 -43.907202)
		(end 388.164578 -55.675022)
		(width 0.089408)
		(layer "In2.Cu")
		(net "JTAG_BMC_TDI")
	)
	(segment
		(start 388.959598 -70.7898)
		(end 389.165338 -70.58406)
		(width 0.089408)
		(layer "In4.Cu")
		(net "JTAG_BMC_TDI")
	)
	(segment
		(start 412.292038 -69.474842)
		(end 412.355538 -69.411342)
		(width 0.089408)
		(layer "In4.Cu")
		(net "JTAG_BMC_TDI")
	)
	(segment
		(start 411.099762 -70.176898)
		(end 411.801818 -69.474842)
		(width 0.089408)
		(layer "In4.Cu")
		(net "JTAG_BMC_TDI")
	)
	(segment
		(start 411.801818 -69.474842)
		(end 412.292038 -69.474842)
		(width 0.089408)
		(layer "In4.Cu")
		(net "JTAG_BMC_TDI")
	)
	(segment
		(start 408.813254 -70.176898)
		(end 411.099762 -70.176898)
		(width 0.089408)
		(layer "In4.Cu")
		(net "JTAG_BMC_TDI")
	)
	(segment
		(start 389.165338 -70.58406)
		(end 408.406092 -70.58406)
		(width 0.089408)
		(layer "In4.Cu")
		(net "JTAG_BMC_TDI")
	)
	(segment
		(start 408.406092 -70.58406)
		(end 408.813254 -70.176898)
		(width 0.089408)
		(layer "In4.Cu")
		(net "JTAG_BMC_TDI")
	)
	(segment
		(start 388.024878 -70.7898)
		(end 388.959598 -70.7898)
		(width 0.089408)
		(layer "In4.Cu")
		(net "JTAG_BMC_TDI")
	)
	(segment
		(start 442.214 -142.621)
		(end 443.364112 -141.470888)
		(width 0.089408)
		(layer "In9.Cu")
		(net "JTAG_BMC_TDI")
	)
	(segment
		(start 442.214 -143.637)
		(end 442.214 -142.621)
		(width 0.089408)
		(layer "In9.Cu")
		(net "JTAG_BMC_TDI")
	)
	(segment
		(start 440.816492 -137.305288)
		(end 440.816492 -135.545068)
		(width 0.089408)
		(layer "In9.Cu")
		(net "JTAG_BMC_TDI")
	)
	(segment
		(start 440.816492 -135.545068)
		(end 437.800496 -132.529072)
		(width 0.089408)
		(layer "In9.Cu")
		(net "JTAG_BMC_TDI")
	)
	(segment
		(start 424.286426 -119.464328)
		(end 424.286426 -117.53215)
		(width 0.089408)
		(layer "In9.Cu")
		(net "JTAG_BMC_TDI")
	)
	(segment
		(start 422.763442 -127.332232)
		(end 422.763442 -120.987312)
		(width 0.089408)
		(layer "In9.Cu")
		(net "JTAG_BMC_TDI")
	)
	(segment
		(start 442.7728 -144.0942)
		(end 442.6712 -144.0942)
		(width 0.089408)
		(layer "In9.Cu")
		(net "JTAG_BMC_TDI")
	)
	(segment
		(start 443.364112 -141.470888)
		(end 443.364112 -139.852908)
		(width 0.089408)
		(layer "In9.Cu")
		(net "JTAG_BMC_TDI")
	)
	(segment
		(start 424.286426 -117.53215)
		(end 424.076876 -117.3226)
		(width 0.089408)
		(layer "In9.Cu")
		(net "JTAG_BMC_TDI")
	)
	(segment
		(start 437.800496 -132.529072)
		(end 430.703228 -132.529072)
		(width 0.089408)
		(layer "In9.Cu")
		(net "JTAG_BMC_TDI")
	)
	(segment
		(start 430.703228 -132.529072)
		(end 427.406054 -129.231898)
		(width 0.089408)
		(layer "In9.Cu")
		(net "JTAG_BMC_TDI")
	)
	(segment
		(start 424.663108 -129.231898)
		(end 422.763442 -127.332232)
		(width 0.089408)
		(layer "In9.Cu")
		(net "JTAG_BMC_TDI")
	)
	(segment
		(start 443.364112 -139.852908)
		(end 440.816492 -137.305288)
		(width 0.089408)
		(layer "In9.Cu")
		(net "JTAG_BMC_TDI")
	)
	(segment
		(start 424.076876 -117.3226)
		(end 424.076876 -114.09045)
		(width 0.089408)
		(layer "In9.Cu")
		(net "JTAG_BMC_TDI")
	)
	(segment
		(start 422.763442 -120.987312)
		(end 424.286426 -119.464328)
		(width 0.089408)
		(layer "In9.Cu")
		(net "JTAG_BMC_TDI")
	)
	(segment
		(start 442.6712 -144.0942)
		(end 442.214 -143.637)
		(width 0.089408)
		(layer "In9.Cu")
		(net "JTAG_BMC_TDI")
	)
	(segment
		(start 427.406054 -129.231898)
		(end 424.663108 -129.231898)
		(width 0.089408)
		(layer "In9.Cu")
		(net "JTAG_BMC_TDI")
	)
	(segment
		(start 424.076876 -114.09045)
		(end 424.133264 -114.034062)
		(width 0.089408)
		(layer "In9.Cu")
		(net "JTAG_BMC_TDI")
	)
	(segment
		(start 456.682602 -39.005002)
		(end 455.280776 -37.603176)
		(width 0.089408)
		(layer "In11.Cu")
		(net "JTAG_BMC_TDI")
	)
	(segment
		(start 430.12614 -39.078662)
		(end 426.778928 -39.078662)
		(width 0.089408)
		(layer "In11.Cu")
		(net "JTAG_BMC_TDI")
	)
	(segment
		(start 466.63864 -40.425878)
		(end 466.021674 -39.808912)
		(width 0.089408)
		(layer "In11.Cu")
		(net "JTAG_BMC_TDI")
	)
	(segment
		(start 443.969648 -39.517574)
		(end 434.626004 -39.517574)
		(width 0.089408)
		(layer "In11.Cu")
		(net "JTAG_BMC_TDI")
	)
	(segment
		(start 455.280776 -37.603176)
		(end 448.40017 -37.603176)
		(width 0.089408)
		(layer "In11.Cu")
		(net "JTAG_BMC_TDI")
	)
	(segment
		(start 457.785724 -39.005002)
		(end 456.682602 -39.005002)
		(width 0.089408)
		(layer "In11.Cu")
		(net "JTAG_BMC_TDI")
	)
	(segment
		(start 409.740354 -36.170362)
		(end 409.304744 -35.734752)
		(width 0.089408)
		(layer "In11.Cu")
		(net "JTAG_BMC_TDI")
	)
	(segment
		(start 461.798162 -38.43147)
		(end 460.906622 -38.43147)
		(width 0.089408)
		(layer "In11.Cu")
		(net "JTAG_BMC_TDI")
	)
	(segment
		(start 418.779452 -36.951158)
		(end 418.589714 -37.140896)
		(width 0.089408)
		(layer "In11.Cu")
		(net "JTAG_BMC_TDI")
	)
	(segment
		(start 412.609792 -36.170362)
		(end 409.740354 -36.170362)
		(width 0.089408)
		(layer "In11.Cu")
		(net "JTAG_BMC_TDI")
	)
	(segment
		(start 446.730374 -39.272972)
		(end 444.21425 -39.272972)
		(width 0.089408)
		(layer "In11.Cu")
		(net "JTAG_BMC_TDI")
	)
	(segment
		(start 434.54066 -39.43223)
		(end 430.479708 -39.43223)
		(width 0.089408)
		(layer "In11.Cu")
		(net "JTAG_BMC_TDI")
	)
	(segment
		(start 458.357478 -38.433248)
		(end 457.785724 -39.005002)
		(width 0.089408)
		(layer "In11.Cu")
		(net "JTAG_BMC_TDI")
	)
	(segment
		(start 460.906622 -38.43147)
		(end 460.904844 -38.433248)
		(width 0.089408)
		(layer "In11.Cu")
		(net "JTAG_BMC_TDI")
	)
	(segment
		(start 448.40017 -37.603176)
		(end 446.730374 -39.272972)
		(width 0.089408)
		(layer "In11.Cu")
		(net "JTAG_BMC_TDI")
	)
	(segment
		(start 461.79994 -38.433248)
		(end 461.798162 -38.43147)
		(width 0.089408)
		(layer "In11.Cu")
		(net "JTAG_BMC_TDI")
	)
	(segment
		(start 409.304744 -35.734752)
		(end 409.090114 -35.734752)
		(width 0.089408)
		(layer "In11.Cu")
		(net "JTAG_BMC_TDI")
	)
	(segment
		(start 426.778928 -39.078662)
		(end 424.651424 -36.951158)
		(width 0.089408)
		(layer "In11.Cu")
		(net "JTAG_BMC_TDI")
	)
	(segment
		(start 467.276688 -40.425878)
		(end 466.63864 -40.425878)
		(width 0.089408)
		(layer "In11.Cu")
		(net "JTAG_BMC_TDI")
	)
	(segment
		(start 430.479708 -39.43223)
		(end 430.12614 -39.078662)
		(width 0.089408)
		(layer "In11.Cu")
		(net "JTAG_BMC_TDI")
	)
	(segment
		(start 467.327742 -40.476932)
		(end 467.276688 -40.425878)
		(width 0.089408)
		(layer "In11.Cu")
		(net "JTAG_BMC_TDI")
	)
	(segment
		(start 466.021674 -39.808912)
		(end 464.397852 -39.808912)
		(width 0.089408)
		(layer "In11.Cu")
		(net "JTAG_BMC_TDI")
	)
	(segment
		(start 463.022188 -38.433248)
		(end 462.89214 -38.433248)
		(width 0.089408)
		(layer "In11.Cu")
		(net "JTAG_BMC_TDI")
	)
	(segment
		(start 461.997044 -38.433248)
		(end 461.79994 -38.433248)
		(width 0.089408)
		(layer "In11.Cu")
		(net "JTAG_BMC_TDI")
	)
	(segment
		(start 464.397852 -39.808912)
		(end 463.022188 -38.433248)
		(width 0.089408)
		(layer "In11.Cu")
		(net "JTAG_BMC_TDI")
	)
	(segment
		(start 413.580326 -37.140896)
		(end 412.609792 -36.170362)
		(width 0.089408)
		(layer "In11.Cu")
		(net "JTAG_BMC_TDI")
	)
	(segment
		(start 424.651424 -36.951158)
		(end 418.779452 -36.951158)
		(width 0.089408)
		(layer "In11.Cu")
		(net "JTAG_BMC_TDI")
	)
	(segment
		(start 418.589714 -37.140896)
		(end 413.580326 -37.140896)
		(width 0.089408)
		(layer "In11.Cu")
		(net "JTAG_BMC_TDI")
	)
	(segment
		(start 462.89214 -38.433248)
		(end 462.890362 -38.43147)
		(width 0.089408)
		(layer "In11.Cu")
		(net "JTAG_BMC_TDI")
	)
	(segment
		(start 444.21425 -39.272972)
		(end 443.969648 -39.517574)
		(width 0.089408)
		(layer "In11.Cu")
		(net "JTAG_BMC_TDI")
	)
	(segment
		(start 462.890362 -38.43147)
		(end 461.998822 -38.43147)
		(width 0.089408)
		(layer "In11.Cu")
		(net "JTAG_BMC_TDI")
	)
	(segment
		(start 461.998822 -38.43147)
		(end 461.997044 -38.433248)
		(width 0.089408)
		(layer "In11.Cu")
		(net "JTAG_BMC_TDI")
	)
	(segment
		(start 460.904844 -38.433248)
		(end 458.357478 -38.433248)
		(width 0.089408)
		(layer "In11.Cu")
		(net "JTAG_BMC_TDI")
	)
	(segment
		(start 434.626004 -39.517574)
		(end 434.54066 -39.43223)
		(width 0.089408)
		(layer "In11.Cu")
		(net "JTAG_BMC_TDI")
	)
	(segment
		(start 438.091072 -140.9954)
		(end 438.8104 -140.9954)
		(width 0.10795)
		(layer "F.Cu")
		(net "JTAG_BMC_TCK")
	)
	(segment
		(start 395.732 -0.2286)
		(end 395.732 -0.8636)
		(width 0.10795)
		(layer "F.Cu")
		(net "JTAG_BMC_TCK")
	)
	(segment
		(start 437.515 -142.748)
		(end 437.515 -141.571472)
		(width 0.10795)
		(layer "F.Cu")
		(net "JTAG_BMC_TCK")
	)
	(segment
		(start 437.515 -142.748)
		(end 437.515 -145.2626)
		(width 0.10795)
		(layer "F.Cu")
		(net "JTAG_BMC_TCK")
	)
	(segment
		(start 408.690064 -33.734756)
		(end 408.290014 -34.134806)
		(width 0.10795)
		(layer "F.Cu")
		(net "JTAG_BMC_TCK")
	)
	(segment
		(start 437.515 -141.571472)
		(end 438.091072 -140.9954)
		(width 0.10795)
		(layer "F.Cu")
		(net "JTAG_BMC_TCK")
	)
	(segment
		(start 437.515 -145.2626)
		(end 438.079642 -145.827242)
		(width 0.10795)
		(layer "F.Cu")
		(net "JTAG_BMC_TCK")
	)
	(segment
		(start 438.079642 -145.827242)
		(end 439.626756 -145.827242)
		(width 0.10795)
		(layer "F.Cu")
		(net "JTAG_BMC_TCK")
	)
	(via
		(at 395.732 -0.8636)
		(size 0.508)
		(drill 0.254)
		(layers "F.Cu" "B.Cu")
		(net "JTAG_BMC_TCK")
	)
	(via
		(at 437.515 -142.748)
		(size 0.508)
		(drill 0.254)
		(layers "F.Cu" "B.Cu")
		(net "JTAG_BMC_TCK")
	)
	(via
		(at 487.556556 -33.452054)
		(size 0.508)
		(drill 0.254)
		(layers "F.Cu" "B.Cu")
		(net "JTAG_BMC_TCK")
	)
	(via
		(at 408.290014 -34.134806)
		(size 0.4572)
		(drill 0.2032)
		(layers "F.Cu" "B.Cu")
		(net "JTAG_BMC_TCK")
	)
	(via
		(at 421.254428 -126.73965)
		(size 0.6604)
		(drill 0.3302)
		(layers "F.Cu" "B.Cu")
		(net "JTAG_BMC_TCK")
	)
	(via
		(at 403.726904 -82.030062)
		(size 0.508)
		(drill 0.254)
		(layers "F.Cu" "B.Cu")
		(net "JTAG_BMC_TCK")
	)
	(via
		(at 438.8104 -140.9954)
		(size 0.762)
		(drill 0.381)
		(layers "F.Cu" "B.Cu")
		(net "JTAG_BMC_TCK")
	)
	(via
		(at 466.62086 -38.05682)
		(size 0.508)
		(drill 0.254)
		(layers "F.Cu" "B.Cu")
		(net "JTAG_BMC_TCK")
	)
	(via
		(at 402.480272 -71.460106)
		(size 0.508)
		(drill 0.254)
		(layers "F.Cu" "B.Cu")
		(net "JTAG_BMC_TCK")
	)
	(via
		(at 418.67582 -128.154176)
		(size 0.508)
		(drill 0.254)
		(layers "F.Cu" "B.Cu")
		(net "JTAG_BMC_TCK")
	)
	(segment
		(start 417.522406 -90.73007)
		(end 417.27501 -90.482674)
		(width 0.10795)
		(layer "B.Cu")
		(net "JTAG_BMC_TCK")
	)
	(segment
		(start 418.811202 -103.387398)
		(end 417.020756 -101.596952)
		(width 0.10795)
		(layer "B.Cu")
		(net "JTAG_BMC_TCK")
	)
	(segment
		(start 416.339274 -90.482674)
		(end 415.595562 -89.738962)
		(width 0.10795)
		(layer "B.Cu")
		(net "JTAG_BMC_TCK")
	)
	(segment
		(start 418.811202 -118.035578)
		(end 418.811202 -103.387398)
		(width 0.10795)
		(layer "B.Cu")
		(net "JTAG_BMC_TCK")
	)
	(segment
		(start 417.522406 -93.680026)
		(end 417.522406 -90.73007)
		(width 0.10795)
		(layer "B.Cu")
		(net "JTAG_BMC_TCK")
	)
	(segment
		(start 417.27501 -90.482674)
		(end 416.339274 -90.482674)
		(width 0.10795)
		(layer "B.Cu")
		(net "JTAG_BMC_TCK")
	)
	(segment
		(start 414.21558 -85.79231)
		(end 413.77362 -85.79231)
		(width 0.10795)
		(layer "B.Cu")
		(net "JTAG_BMC_TCK")
	)
	(segment
		(start 415.144966 -87.571072)
		(end 415.144966 -86.721696)
		(width 0.10795)
		(layer "B.Cu")
		(net "JTAG_BMC_TCK")
	)
	(segment
		(start 415.144966 -86.721696)
		(end 414.21558 -85.79231)
		(width 0.10795)
		(layer "B.Cu")
		(net "JTAG_BMC_TCK")
	)
	(segment
		(start 422.519348 -121.743724)
		(end 418.811202 -118.035578)
		(width 0.10795)
		(layer "B.Cu")
		(net "JTAG_BMC_TCK")
	)
	(segment
		(start 421.254428 -126.73965)
		(end 421.964104 -126.73965)
		(width 0.10795)
		(layer "B.Cu")
		(net "JTAG_BMC_TCK")
	)
	(segment
		(start 419.238176 -127.59182)
		(end 419.897814 -127.59182)
		(width 0.10795)
		(layer "B.Cu")
		(net "JTAG_BMC_TCK")
	)
	(segment
		(start 417.020756 -94.181676)
		(end 417.522406 -93.680026)
		(width 0.10795)
		(layer "B.Cu")
		(net "JTAG_BMC_TCK")
	)
	(segment
		(start 407.534364 -83.578954)
		(end 407.398474 -83.443064)
		(width 0.10795)
		(layer "B.Cu")
		(net "JTAG_BMC_TCK")
	)
	(segment
		(start 417.020756 -101.596952)
		(end 417.020756 -94.181676)
		(width 0.10795)
		(layer "B.Cu")
		(net "JTAG_BMC_TCK")
	)
	(segment
		(start 403.092412 -83.003644)
		(end 403.092412 -82.435954)
		(width 0.10795)
		(layer "B.Cu")
		(net "JTAG_BMC_TCK")
	)
	(segment
		(start 415.595562 -89.738962)
		(end 415.595562 -88.670892)
		(width 0.10795)
		(layer "B.Cu")
		(net "JTAG_BMC_TCK")
	)
	(segment
		(start 403.092412 -82.435954)
		(end 403.498304 -82.030062)
		(width 0.10795)
		(layer "B.Cu")
		(net "JTAG_BMC_TCK")
	)
	(segment
		(start 411.560264 -83.578954)
		(end 407.534364 -83.578954)
		(width 0.10795)
		(layer "B.Cu")
		(net "JTAG_BMC_TCK")
	)
	(segment
		(start 413.77362 -85.79231)
		(end 411.560264 -83.578954)
		(width 0.10795)
		(layer "B.Cu")
		(net "JTAG_BMC_TCK")
	)
	(segment
		(start 407.398474 -83.443064)
		(end 403.531832 -83.443064)
		(width 0.10795)
		(layer "B.Cu")
		(net "JTAG_BMC_TCK")
	)
	(segment
		(start 422.519348 -126.184406)
		(end 422.519348 -121.743724)
		(width 0.10795)
		(layer "B.Cu")
		(net "JTAG_BMC_TCK")
	)
	(segment
		(start 418.67582 -128.154176)
		(end 419.238176 -127.59182)
		(width 0.10795)
		(layer "B.Cu")
		(net "JTAG_BMC_TCK")
	)
	(segment
		(start 414.99536 -87.720678)
		(end 415.144966 -87.571072)
		(width 0.10795)
		(layer "B.Cu")
		(net "JTAG_BMC_TCK")
	)
	(segment
		(start 403.498304 -82.030062)
		(end 403.726904 -82.030062)
		(width 0.10795)
		(layer "B.Cu")
		(net "JTAG_BMC_TCK")
	)
	(segment
		(start 403.531832 -83.443064)
		(end 403.092412 -83.003644)
		(width 0.10795)
		(layer "B.Cu")
		(net "JTAG_BMC_TCK")
	)
	(segment
		(start 421.964104 -126.73965)
		(end 422.519348 -126.184406)
		(width 0.10795)
		(layer "B.Cu")
		(net "JTAG_BMC_TCK")
	)
	(segment
		(start 415.595562 -88.670892)
		(end 414.99536 -88.07069)
		(width 0.10795)
		(layer "B.Cu")
		(net "JTAG_BMC_TCK")
	)
	(segment
		(start 414.99536 -88.07069)
		(end 414.99536 -87.720678)
		(width 0.10795)
		(layer "B.Cu")
		(net "JTAG_BMC_TCK")
	)
	(segment
		(start 420.749984 -126.73965)
		(end 421.254428 -126.73965)
		(width 0.10795)
		(layer "B.Cu")
		(net "JTAG_BMC_TCK")
	)
	(segment
		(start 419.897814 -127.59182)
		(end 420.749984 -126.73965)
		(width 0.10795)
		(layer "B.Cu")
		(net "JTAG_BMC_TCK")
	)
	(segment
		(start 487.556556 -33.452054)
		(end 487.146346 -33.452054)
		(width 0.089408)
		(layer "In2.Cu")
		(net "JTAG_BMC_TCK")
	)
	(segment
		(start 487.146346 -33.452054)
		(end 486.86212 -33.73628)
		(width 0.089408)
		(layer "In2.Cu")
		(net "JTAG_BMC_TCK")
	)
	(segment
		(start 472.128342 -36.36518)
		(end 470.513664 -37.979858)
		(width 0.089408)
		(layer "In2.Cu")
		(net "JTAG_BMC_TCK")
	)
	(segment
		(start 485.926638 -35.706812)
		(end 485.926384 -35.706558)
		(width 0.089408)
		(layer "In2.Cu")
		(net "JTAG_BMC_TCK")
	)
	(segment
		(start 486.86212 -34.971482)
		(end 486.12679 -35.706812)
		(width 0.089408)
		(layer "In2.Cu")
		(net "JTAG_BMC_TCK")
	)
	(segment
		(start 486.86212 -33.73628)
		(end 486.86212 -34.971482)
		(width 0.089408)
		(layer "In2.Cu")
		(net "JTAG_BMC_TCK")
	)
	(segment
		(start 485.926384 -35.706558)
		(end 484.588312 -35.706558)
		(width 0.089408)
		(layer "In2.Cu")
		(net "JTAG_BMC_TCK")
	)
	(segment
		(start 482.848158 -35.11042)
		(end 481.589588 -33.85185)
		(width 0.089408)
		(layer "In2.Cu")
		(net "JTAG_BMC_TCK")
	)
	(segment
		(start 474.312488 -35.498278)
		(end 473.445586 -36.36518)
		(width 0.089408)
		(layer "In2.Cu")
		(net "JTAG_BMC_TCK")
	)
	(segment
		(start 470.513664 -37.979858)
		(end 466.697822 -37.979858)
		(width 0.089408)
		(layer "In2.Cu")
		(net "JTAG_BMC_TCK")
	)
	(segment
		(start 474.312996 -35.498278)
		(end 474.312488 -35.498278)
		(width 0.089408)
		(layer "In2.Cu")
		(net "JTAG_BMC_TCK")
	)
	(segment
		(start 466.697822 -37.979858)
		(end 466.62086 -38.05682)
		(width 0.089408)
		(layer "In2.Cu")
		(net "JTAG_BMC_TCK")
	)
	(segment
		(start 475.959424 -33.85185)
		(end 474.312996 -35.498278)
		(width 0.089408)
		(layer "In2.Cu")
		(net "JTAG_BMC_TCK")
	)
	(segment
		(start 486.12679 -35.706812)
		(end 485.926638 -35.706812)
		(width 0.089408)
		(layer "In2.Cu")
		(net "JTAG_BMC_TCK")
	)
	(segment
		(start 481.589588 -33.85185)
		(end 475.959424 -33.85185)
		(width 0.089408)
		(layer "In2.Cu")
		(net "JTAG_BMC_TCK")
	)
	(segment
		(start 483.992174 -35.11042)
		(end 482.848158 -35.11042)
		(width 0.089408)
		(layer "In2.Cu")
		(net "JTAG_BMC_TCK")
	)
	(segment
		(start 484.588312 -35.706558)
		(end 483.992174 -35.11042)
		(width 0.089408)
		(layer "In2.Cu")
		(net "JTAG_BMC_TCK")
	)
	(segment
		(start 473.445586 -36.36518)
		(end 472.128342 -36.36518)
		(width 0.089408)
		(layer "In2.Cu")
		(net "JTAG_BMC_TCK")
	)
	(segment
		(start 417.076382 2.059686)
		(end 415.530792 0.514096)
		(width 0.089408)
		(layer "In4.Cu")
		(net "JTAG_BMC_TCK")
	)
	(segment
		(start 483.29342 -27.452828)
		(end 483.29342 -26.786078)
		(width 0.089408)
		(layer "In4.Cu")
		(net "JTAG_BMC_TCK")
	)
	(segment
		(start 419.257734 -36.931346)
		(end 423.622216 -36.931346)
		(width 0.089408)
		(layer "In4.Cu")
		(net "JTAG_BMC_TCK")
	)
	(segment
		(start 444.314834 -37.47516)
		(end 445.126618 -36.663376)
		(width 0.089408)
		(layer "In4.Cu")
		(net "JTAG_BMC_TCK")
	)
	(segment
		(start 486.55859 -30.095952)
		(end 485.936544 -30.095952)
		(width 0.089408)
		(layer "In4.Cu")
		(net "JTAG_BMC_TCK")
	)
	(segment
		(start 402.585682 0.334772)
		(end 401.804886 0.334772)
		(width 0.089408)
		(layer "In4.Cu")
		(net "JTAG_BMC_TCK")
	)
	(segment
		(start 449.912486 -1.16586)
		(end 431.588418 -1.16586)
		(width 0.089408)
		(layer "In4.Cu")
		(net "JTAG_BMC_TCK")
	)
	(segment
		(start 431.588418 -1.16586)
		(end 429.914558 0.508)
		(width 0.089408)
		(layer "In4.Cu")
		(net "JTAG_BMC_TCK")
	)
	(segment
		(start 469.074754 -11.610594)
		(end 458.60589 -11.610594)
		(width 0.089408)
		(layer "In4.Cu")
		(net "JTAG_BMC_TCK")
	)
	(segment
		(start 458.963776 -35.592512)
		(end 462.377282 -35.592512)
		(width 0.089408)
		(layer "In4.Cu")
		(net "JTAG_BMC_TCK")
	)
	(segment
		(start 457.000102 -8.1534)
		(end 455.448924 -8.1534)
		(width 0.089408)
		(layer "In4.Cu")
		(net "JTAG_BMC_TCK")
	)
	(segment
		(start 440.187334 -37.739066)
		(end 440.45124 -37.47516)
		(width 0.089408)
		(layer "In4.Cu")
		(net "JTAG_BMC_TCK")
	)
	(segment
		(start 408.290014 -34.134806)
		(end 408.290014 -34.091372)
		(width 0.089408)
		(layer "In4.Cu")
		(net "JTAG_BMC_TCK")
	)
	(segment
		(start 464.677252 -36.89985)
		(end 465.834222 -38.05682)
		(width 0.089408)
		(layer "In4.Cu")
		(net "JTAG_BMC_TCK")
	)
	(segment
		(start 464.677252 -36.4236)
		(end 464.677252 -36.89985)
		(width 0.089408)
		(layer "In4.Cu")
		(net "JTAG_BMC_TCK")
	)
	(segment
		(start 447.33591 -35.16884)
		(end 458.540104 -35.16884)
		(width 0.089408)
		(layer "In4.Cu")
		(net "JTAG_BMC_TCK")
	)
	(segment
		(start 485.936544 -30.095952)
		(end 483.29342 -27.452828)
		(width 0.089408)
		(layer "In4.Cu")
		(net "JTAG_BMC_TCK")
	)
	(segment
		(start 465.834222 -38.05682)
		(end 466.62086 -38.05682)
		(width 0.089408)
		(layer "In4.Cu")
		(net "JTAG_BMC_TCK")
	)
	(segment
		(start 405.532844 1.33096)
		(end 403.95398 -0.247904)
		(width 0.089408)
		(layer "In4.Cu")
		(net "JTAG_BMC_TCK")
	)
	(segment
		(start 482.601778 -23.159212)
		(end 477.552258 -18.109692)
		(width 0.089408)
		(layer "In4.Cu")
		(net "JTAG_BMC_TCK")
	)
	(segment
		(start 457.5429 -8.696198)
		(end 457.000102 -8.1534)
		(width 0.089408)
		(layer "In4.Cu")
		(net "JTAG_BMC_TCK")
	)
	(segment
		(start 487.556556 -33.452054)
		(end 487.114342 -33.00984)
		(width 0.089408)
		(layer "In4.Cu")
		(net "JTAG_BMC_TCK")
	)
	(segment
		(start 457.396088 -10.400792)
		(end 457.396088 -9.174734)
		(width 0.089408)
		(layer "In4.Cu")
		(net "JTAG_BMC_TCK")
	)
	(segment
		(start 415.530792 0.514096)
		(end 412.0642 0.514096)
		(width 0.089408)
		(layer "In4.Cu")
		(net "JTAG_BMC_TCK")
	)
	(segment
		(start 408.290014 -34.091372)
		(end 408.859228 -33.522158)
		(width 0.089408)
		(layer "In4.Cu")
		(net "JTAG_BMC_TCK")
	)
	(segment
		(start 482.601778 -26.094436)
		(end 482.601778 -23.159212)
		(width 0.089408)
		(layer "In4.Cu")
		(net "JTAG_BMC_TCK")
	)
	(segment
		(start 457.5429 -9.027922)
		(end 457.5429 -8.696198)
		(width 0.089408)
		(layer "In4.Cu")
		(net "JTAG_BMC_TCK")
	)
	(segment
		(start 399.878296 0.781304)
		(end 397.376904 0.781304)
		(width 0.089408)
		(layer "In4.Cu")
		(net "JTAG_BMC_TCK")
	)
	(segment
		(start 457.396088 -9.174734)
		(end 457.5429 -9.027922)
		(width 0.089408)
		(layer "In4.Cu")
		(net "JTAG_BMC_TCK")
	)
	(segment
		(start 445.126618 -36.663376)
		(end 445.841374 -36.663376)
		(width 0.089408)
		(layer "In4.Cu")
		(net "JTAG_BMC_TCK")
	)
	(segment
		(start 462.377282 -35.592512)
		(end 462.830672 -36.045902)
		(width 0.089408)
		(layer "In4.Cu")
		(net "JTAG_BMC_TCK")
	)
	(segment
		(start 435.613048 -36.721796)
		(end 436.630318 -37.739066)
		(width 0.089408)
		(layer "In4.Cu")
		(net "JTAG_BMC_TCK")
	)
	(segment
		(start 436.630318 -37.739066)
		(end 440.187334 -37.739066)
		(width 0.089408)
		(layer "In4.Cu")
		(net "JTAG_BMC_TCK")
	)
	(segment
		(start 413.382968 -35.405822)
		(end 414.99409 -37.016944)
		(width 0.089408)
		(layer "In4.Cu")
		(net "JTAG_BMC_TCK")
	)
	(segment
		(start 476.730822 -18.109692)
		(end 471.52687 -12.90574)
		(width 0.089408)
		(layer "In4.Cu")
		(net "JTAG_BMC_TCK")
	)
	(segment
		(start 414.99409 -37.016944)
		(end 419.172136 -37.016944)
		(width 0.089408)
		(layer "In4.Cu")
		(net "JTAG_BMC_TCK")
	)
	(segment
		(start 400.106896 0.552704)
		(end 399.878296 0.781304)
		(width 0.089408)
		(layer "In4.Cu")
		(net "JTAG_BMC_TCK")
	)
	(segment
		(start 470.3699 -12.90574)
		(end 469.074754 -11.610594)
		(width 0.089408)
		(layer "In4.Cu")
		(net "JTAG_BMC_TCK")
	)
	(segment
		(start 471.52687 -12.90574)
		(end 470.3699 -12.90574)
		(width 0.089408)
		(layer "In4.Cu")
		(net "JTAG_BMC_TCK")
	)
	(segment
		(start 412.57093 -33.522158)
		(end 413.382968 -34.334196)
		(width 0.089408)
		(layer "In4.Cu")
		(net "JTAG_BMC_TCK")
	)
	(segment
		(start 420.692072 2.059686)
		(end 417.076382 2.059686)
		(width 0.089408)
		(layer "In4.Cu")
		(net "JTAG_BMC_TCK")
	)
	(segment
		(start 464.299554 -36.045902)
		(end 464.677252 -36.4236)
		(width 0.089408)
		(layer "In4.Cu")
		(net "JTAG_BMC_TCK")
	)
	(segment
		(start 412.0642 0.514096)
		(end 411.247336 1.33096)
		(width 0.089408)
		(layer "In4.Cu")
		(net "JTAG_BMC_TCK")
	)
	(segment
		(start 397.376904 0.781304)
		(end 395.732 -0.8636)
		(width 0.089408)
		(layer "In4.Cu")
		(net "JTAG_BMC_TCK")
	)
	(segment
		(start 403.95398 -0.247904)
		(end 403.168358 -0.247904)
		(width 0.089408)
		(layer "In4.Cu")
		(net "JTAG_BMC_TCK")
	)
	(segment
		(start 401.804886 0.334772)
		(end 401.586954 0.552704)
		(width 0.089408)
		(layer "In4.Cu")
		(net "JTAG_BMC_TCK")
	)
	(segment
		(start 423.831766 -36.721796)
		(end 435.613048 -36.721796)
		(width 0.089408)
		(layer "In4.Cu")
		(net "JTAG_BMC_TCK")
	)
	(segment
		(start 458.60589 -11.610594)
		(end 457.396088 -10.400792)
		(width 0.089408)
		(layer "In4.Cu")
		(net "JTAG_BMC_TCK")
	)
	(segment
		(start 458.540104 -35.16884)
		(end 458.963776 -35.592512)
		(width 0.089408)
		(layer "In4.Cu")
		(net "JTAG_BMC_TCK")
	)
	(segment
		(start 454.344786 -7.049262)
		(end 454.344786 -5.59816)
		(width 0.089408)
		(layer "In4.Cu")
		(net "JTAG_BMC_TCK")
	)
	(segment
		(start 423.622216 -36.931346)
		(end 423.831766 -36.721796)
		(width 0.089408)
		(layer "In4.Cu")
		(net "JTAG_BMC_TCK")
	)
	(segment
		(start 487.114342 -33.00984)
		(end 487.114342 -30.651704)
		(width 0.089408)
		(layer "In4.Cu")
		(net "JTAG_BMC_TCK")
	)
	(segment
		(start 445.841374 -36.663376)
		(end 447.33591 -35.16884)
		(width 0.089408)
		(layer "In4.Cu")
		(net "JTAG_BMC_TCK")
	)
	(segment
		(start 455.448924 -8.1534)
		(end 454.344786 -7.049262)
		(width 0.089408)
		(layer "In4.Cu")
		(net "JTAG_BMC_TCK")
	)
	(segment
		(start 462.830672 -36.045902)
		(end 464.299554 -36.045902)
		(width 0.089408)
		(layer "In4.Cu")
		(net "JTAG_BMC_TCK")
	)
	(segment
		(start 422.243758 0.508)
		(end 420.692072 2.059686)
		(width 0.089408)
		(layer "In4.Cu")
		(net "JTAG_BMC_TCK")
	)
	(segment
		(start 477.552258 -18.109692)
		(end 476.730822 -18.109692)
		(width 0.089408)
		(layer "In4.Cu")
		(net "JTAG_BMC_TCK")
	)
	(segment
		(start 403.168358 -0.247904)
		(end 402.585682 0.334772)
		(width 0.089408)
		(layer "In4.Cu")
		(net "JTAG_BMC_TCK")
	)
	(segment
		(start 440.45124 -37.47516)
		(end 444.314834 -37.47516)
		(width 0.089408)
		(layer "In4.Cu")
		(net "JTAG_BMC_TCK")
	)
	(segment
		(start 408.859228 -33.522158)
		(end 412.57093 -33.522158)
		(width 0.089408)
		(layer "In4.Cu")
		(net "JTAG_BMC_TCK")
	)
	(segment
		(start 429.914558 0.508)
		(end 422.243758 0.508)
		(width 0.089408)
		(layer "In4.Cu")
		(net "JTAG_BMC_TCK")
	)
	(segment
		(start 401.586954 0.552704)
		(end 400.106896 0.552704)
		(width 0.089408)
		(layer "In4.Cu")
		(net "JTAG_BMC_TCK")
	)
	(segment
		(start 487.114342 -30.651704)
		(end 486.55859 -30.095952)
		(width 0.089408)
		(layer "In4.Cu")
		(net "JTAG_BMC_TCK")
	)
	(segment
		(start 413.382968 -34.334196)
		(end 413.382968 -35.405822)
		(width 0.089408)
		(layer "In4.Cu")
		(net "JTAG_BMC_TCK")
	)
	(segment
		(start 411.247336 1.33096)
		(end 405.532844 1.33096)
		(width 0.089408)
		(layer "In4.Cu")
		(net "JTAG_BMC_TCK")
	)
	(segment
		(start 419.172136 -37.016944)
		(end 419.257734 -36.931346)
		(width 0.089408)
		(layer "In4.Cu")
		(net "JTAG_BMC_TCK")
	)
	(segment
		(start 483.29342 -26.786078)
		(end 482.601778 -26.094436)
		(width 0.089408)
		(layer "In4.Cu")
		(net "JTAG_BMC_TCK")
	)
	(segment
		(start 454.344786 -5.59816)
		(end 449.912486 -1.16586)
		(width 0.089408)
		(layer "In4.Cu")
		(net "JTAG_BMC_TCK")
	)
	(segment
		(start 404.498048 -63.772796)
		(end 404.498048 -64.433196)
		(width 0.089408)
		(layer "In9.Cu")
		(net "JTAG_BMC_TCK")
	)
	(segment
		(start 408.934666 -35.360102)
		(end 410.045662 -35.360102)
		(width 0.089408)
		(layer "In9.Cu")
		(net "JTAG_BMC_TCK")
	)
	(segment
		(start 411.064964 -37.97935)
		(end 411.064964 -38.278562)
		(width 0.089408)
		(layer "In9.Cu")
		(net "JTAG_BMC_TCK")
	)
	(segment
		(start 406.55494 -45.734224)
		(end 406.55494 -46.20006)
		(width 0.089408)
		(layer "In9.Cu")
		(net "JTAG_BMC_TCK")
	)
	(segment
		(start 410.774642 -45.365162)
		(end 410.165804 -45.974)
		(width 0.089408)
		(layer "In9.Cu")
		(net "JTAG_BMC_TCK")
	)
	(segment
		(start 404.988014 -66.322702)
		(end 402.480272 -68.830444)
		(width 0.089408)
		(layer "In9.Cu")
		(net "JTAG_BMC_TCK")
	)
	(segment
		(start 412.715456 -39.970456)
		(end 412.715456 -43.018456)
		(width 0.089408)
		(layer "In9.Cu")
		(net "JTAG_BMC_TCK")
	)
	(segment
		(start 410.165804 -45.974)
		(end 409.194 -45.974)
		(width 0.089408)
		(layer "In9.Cu")
		(net "JTAG_BMC_TCK")
	)
	(segment
		(start 411.88005 -39.13505)
		(end 412.715456 -39.970456)
		(width 0.089408)
		(layer "In9.Cu")
		(net "JTAG_BMC_TCK")
	)
	(segment
		(start 404.991824 -65.722754)
		(end 404.991824 -66.318638)
		(width 0.089408)
		(layer "In9.Cu")
		(net "JTAG_BMC_TCK")
	)
	(segment
		(start 411.064964 -38.278562)
		(end 411.349952 -38.56355)
		(width 0.089408)
		(layer "In9.Cu")
		(net "JTAG_BMC_TCK")
	)
	(segment
		(start 412.715456 -43.018456)
		(end 413.131 -43.434)
		(width 0.089408)
		(layer "In9.Cu")
		(net "JTAG_BMC_TCK")
	)
	(segment
		(start 404.992078 -64.927226)
		(end 404.992078 -65.179702)
		(width 0.089408)
		(layer "In9.Cu")
		(net "JTAG_BMC_TCK")
	)
	(segment
		(start 425.904152 -133.169152)
		(end 425.577 -132.842)
		(width 0.089408)
		(layer "In9.Cu")
		(net "JTAG_BMC_TCK")
	)
	(segment
		(start 410.378148 -37.760148)
		(end 410.845762 -37.760148)
		(width 0.089408)
		(layer "In9.Cu")
		(net "JTAG_BMC_TCK")
	)
	(segment
		(start 406.823164 -45.466)
		(end 406.55494 -45.734224)
		(width 0.089408)
		(layer "In9.Cu")
		(net "JTAG_BMC_TCK")
	)
	(segment
		(start 411.88005 -38.782752)
		(end 411.88005 -39.13505)
		(width 0.089408)
		(layer "In9.Cu")
		(net "JTAG_BMC_TCK")
	)
	(segment
		(start 406.136094 -46.618906)
		(end 406.136094 -47.615094)
		(width 0.089408)
		(layer "In9.Cu")
		(net "JTAG_BMC_TCK")
	)
	(segment
		(start 418.67582 -128.286256)
		(end 418.67582 -128.154176)
		(width 0.089408)
		(layer "In9.Cu")
		(net "JTAG_BMC_TCK")
	)
	(segment
		(start 408.686 -45.466)
		(end 406.823164 -45.466)
		(width 0.089408)
		(layer "In9.Cu")
		(net "JTAG_BMC_TCK")
	)
	(segment
		(start 410.264864 -35.579304)
		(end 410.264864 -37.646864)
		(width 0.089408)
		(layer "In9.Cu")
		(net "JTAG_BMC_TCK")
	)
	(segment
		(start 404.992078 -65.179702)
		(end 404.991824 -65.179956)
		(width 0.089408)
		(layer "In9.Cu")
		(net "JTAG_BMC_TCK")
	)
	(segment
		(start 437.388 -142.621)
		(end 437.388 -136.525)
		(width 0.089408)
		(layer "In9.Cu")
		(net "JTAG_BMC_TCK")
	)
	(segment
		(start 406.781 -49.475898)
		(end 406.527 -49.729898)
		(width 0.089408)
		(layer "In9.Cu")
		(net "JTAG_BMC_TCK")
	)
	(segment
		(start 404.498048 -64.433196)
		(end 404.992078 -64.927226)
		(width 0.089408)
		(layer "In9.Cu")
		(net "JTAG_BMC_TCK")
	)
	(segment
		(start 402.480272 -68.830444)
		(end 402.480272 -71.460106)
		(width 0.089408)
		(layer "In9.Cu")
		(net "JTAG_BMC_TCK")
	)
	(segment
		(start 408.715464 -34.446464)
		(end 408.715464 -35.1409)
		(width 0.089408)
		(layer "In9.Cu")
		(net "JTAG_BMC_TCK")
	)
	(segment
		(start 411.072838 -45.365162)
		(end 410.774642 -45.365162)
		(width 0.089408)
		(layer "In9.Cu")
		(net "JTAG_BMC_TCK")
	)
	(segment
		(start 409.194 -45.974)
		(end 408.686 -45.466)
		(width 0.089408)
		(layer "In9.Cu")
		(net "JTAG_BMC_TCK")
	)
	(segment
		(start 404.991824 -65.47612)
		(end 404.992332 -65.476628)
		(width 0.089408)
		(layer "In9.Cu")
		(net "JTAG_BMC_TCK")
	)
	(segment
		(start 405.435816 -58.932064)
		(end 404.821644 -59.546236)
		(width 0.089408)
		(layer "In9.Cu")
		(net "JTAG_BMC_TCK")
	)
	(segment
		(start 404.988014 -66.322448)
		(end 404.988014 -66.322702)
		(width 0.089408)
		(layer "In9.Cu")
		(net "JTAG_BMC_TCK")
	)
	(segment
		(start 406.136094 -47.615094)
		(end 406.781 -48.26)
		(width 0.089408)
		(layer "In9.Cu")
		(net "JTAG_BMC_TCK")
	)
	(segment
		(start 437.515 -142.748)
		(end 437.388 -142.621)
		(width 0.089408)
		(layer "In9.Cu")
		(net "JTAG_BMC_TCK")
	)
	(segment
		(start 405.435816 -52.907184)
		(end 405.435816 -58.932064)
		(width 0.089408)
		(layer "In9.Cu")
		(net "JTAG_BMC_TCK")
	)
	(segment
		(start 404.991824 -66.318638)
		(end 404.988014 -66.322448)
		(width 0.089408)
		(layer "In9.Cu")
		(net "JTAG_BMC_TCK")
	)
	(segment
		(start 408.403806 -34.134806)
		(end 408.715464 -34.446464)
		(width 0.089408)
		(layer "In9.Cu")
		(net "JTAG_BMC_TCK")
	)
	(segment
		(start 406.527 -49.729898)
		(end 406.527 -51.816)
		(width 0.089408)
		(layer "In9.Cu")
		(net "JTAG_BMC_TCK")
	)
	(segment
		(start 410.264864 -37.646864)
		(end 410.378148 -37.760148)
		(width 0.089408)
		(layer "In9.Cu")
		(net "JTAG_BMC_TCK")
	)
	(segment
		(start 426.179234 -133.331966)
		(end 425.986448 -133.203442)
		(width 0.089408)
		(layer "In9.Cu")
		(net "JTAG_BMC_TCK")
	)
	(segment
		(start 408.290014 -34.134806)
		(end 408.403806 -34.134806)
		(width 0.089408)
		(layer "In9.Cu")
		(net "JTAG_BMC_TCK")
	)
	(segment
		(start 404.821644 -60.606432)
		(end 404.002748 -61.425328)
		(width 0.089408)
		(layer "In9.Cu")
		(net "JTAG_BMC_TCK")
	)
	(segment
		(start 412.823152 -44.376848)
		(end 412.061152 -44.376848)
		(width 0.089408)
		(layer "In9.Cu")
		(net "JTAG_BMC_TCK")
	)
	(segment
		(start 413.131 -44.069)
		(end 412.823152 -44.376848)
		(width 0.089408)
		(layer "In9.Cu")
		(net "JTAG_BMC_TCK")
	)
	(segment
		(start 410.045662 -35.360102)
		(end 410.264864 -35.579304)
		(width 0.089408)
		(layer "In9.Cu")
		(net "JTAG_BMC_TCK")
	)
	(segment
		(start 425.577 -132.842)
		(end 423.231564 -132.842)
		(width 0.089408)
		(layer "In9.Cu")
		(net "JTAG_BMC_TCK")
	)
	(segment
		(start 408.715464 -35.1409)
		(end 408.934666 -35.360102)
		(width 0.089408)
		(layer "In9.Cu")
		(net "JTAG_BMC_TCK")
	)
	(segment
		(start 410.845762 -37.760148)
		(end 411.064964 -37.97935)
		(width 0.089408)
		(layer "In9.Cu")
		(net "JTAG_BMC_TCK")
	)
	(segment
		(start 404.991824 -65.179956)
		(end 404.991824 -65.47612)
		(width 0.089408)
		(layer "In9.Cu")
		(net "JTAG_BMC_TCK")
	)
	(segment
		(start 404.002748 -61.425328)
		(end 404.002748 -63.277496)
		(width 0.089408)
		(layer "In9.Cu")
		(net "JTAG_BMC_TCK")
	)
	(segment
		(start 423.231564 -132.842)
		(end 418.67582 -128.286256)
		(width 0.089408)
		(layer "In9.Cu")
		(net "JTAG_BMC_TCK")
	)
	(segment
		(start 413.131 -43.434)
		(end 413.131 -44.069)
		(width 0.089408)
		(layer "In9.Cu")
		(net "JTAG_BMC_TCK")
	)
	(segment
		(start 428.483268 -135.636)
		(end 426.179234 -133.331966)
		(width 0.089408)
		(layer "In9.Cu")
		(net "JTAG_BMC_TCK")
	)
	(segment
		(start 437.388 -136.525)
		(end 436.499 -135.636)
		(width 0.089408)
		(layer "In9.Cu")
		(net "JTAG_BMC_TCK")
	)
	(segment
		(start 436.499 -135.636)
		(end 428.483268 -135.636)
		(width 0.089408)
		(layer "In9.Cu")
		(net "JTAG_BMC_TCK")
	)
	(segment
		(start 404.002748 -63.277496)
		(end 404.498048 -63.772796)
		(width 0.089408)
		(layer "In9.Cu")
		(net "JTAG_BMC_TCK")
	)
	(segment
		(start 406.527 -51.816)
		(end 405.435816 -52.907184)
		(width 0.089408)
		(layer "In9.Cu")
		(net "JTAG_BMC_TCK")
	)
	(segment
		(start 406.781 -48.26)
		(end 406.781 -49.475898)
		(width 0.089408)
		(layer "In9.Cu")
		(net "JTAG_BMC_TCK")
	)
	(segment
		(start 406.55494 -46.20006)
		(end 406.136094 -46.618906)
		(width 0.089408)
		(layer "In9.Cu")
		(net "JTAG_BMC_TCK")
	)
	(segment
		(start 412.061152 -44.376848)
		(end 411.072838 -45.365162)
		(width 0.089408)
		(layer "In9.Cu")
		(net "JTAG_BMC_TCK")
	)
	(segment
		(start 404.992332 -65.718944)
		(end 404.9903 -65.72123)
		(width 0.089408)
		(layer "In9.Cu")
		(net "JTAG_BMC_TCK")
	)
	(segment
		(start 404.821644 -59.546236)
		(end 404.821644 -60.606432)
		(width 0.089408)
		(layer "In9.Cu")
		(net "JTAG_BMC_TCK")
	)
	(segment
		(start 411.660848 -38.56355)
		(end 411.88005 -38.782752)
		(width 0.089408)
		(layer "In9.Cu")
		(net "JTAG_BMC_TCK")
	)
	(segment
		(start 411.349952 -38.56355)
		(end 411.660848 -38.56355)
		(width 0.089408)
		(layer "In9.Cu")
		(net "JTAG_BMC_TCK")
	)
	(segment
		(start 425.986448 -133.203442)
		(end 425.904152 -133.169152)
		(width 0.089408)
		(layer "In9.Cu")
		(net "JTAG_BMC_TCK")
	)
	(segment
		(start 404.992332 -65.476628)
		(end 404.992332 -65.718944)
		(width 0.089408)
		(layer "In9.Cu")
		(net "JTAG_BMC_TCK")
	)
	(segment
		(start 404.9903 -65.72123)
		(end 404.991824 -65.722754)
		(width 0.089408)
		(layer "In9.Cu")
		(net "JTAG_BMC_TCK")
	)
	(segment
		(start 402.6408 -78.937612)
		(end 403.442678 -79.73949)
		(width 0.089408)
		(layer "In11.Cu")
		(net "JTAG_BMC_TCK")
	)
	(segment
		(start 402.480272 -71.460106)
		(end 402.73859 -71.718424)
		(width 0.089408)
		(layer "In11.Cu")
		(net "JTAG_BMC_TCK")
	)
	(segment
		(start 403.442678 -81.745836)
		(end 403.726904 -82.030062)
		(width 0.089408)
		(layer "In11.Cu")
		(net "JTAG_BMC_TCK")
	)
	(segment
		(start 402.6408 -75.740006)
		(end 402.6408 -78.937612)
		(width 0.089408)
		(layer "In11.Cu")
		(net "JTAG_BMC_TCK")
	)
	(segment
		(start 402.73859 -75.642216)
		(end 402.6408 -75.740006)
		(width 0.089408)
		(layer "In11.Cu")
		(net "JTAG_BMC_TCK")
	)
	(segment
		(start 402.73859 -71.718424)
		(end 402.73859 -75.642216)
		(width 0.089408)
		(layer "In11.Cu")
		(net "JTAG_BMC_TCK")
	)
	(segment
		(start 403.442678 -79.73949)
		(end 403.442678 -81.745836)
		(width 0.089408)
		(layer "In11.Cu")
		(net "JTAG_BMC_TCK")
	)
	(segment
		(start 119.357902 -66.800984)
		(end 119.929402 -66.800984)
		(width 0.127)
		(layer "F.Cu")
		(net "CLK_100M_CPU1_RC_REFCLK0_DP")
	)
	(segment
		(start 162.054794 -80.028288)
		(end 162.579304 -80.028288)
		(width 0.127)
		(layer "F.Cu")
		(net "CLK_100M_CPU1_RC_REFCLK0_DP")
	)
	(segment
		(start 162.579304 -80.028288)
		(end 162.687 -80.135984)
		(width 0.127)
		(layer "F.Cu")
		(net "CLK_100M_CPU1_RC_REFCLK0_DP")
	)
	(segment
		(start 161.940494 -80.142588)
		(end 162.054794 -80.028288)
		(width 0.127)
		(layer "F.Cu")
		(net "CLK_100M_CPU1_RC_REFCLK0_DP")
	)
	(segment
		(start 162.687 -80.135984)
		(end 162.687 -80.518)
		(width 0.127)
		(layer "F.Cu")
		(net "CLK_100M_CPU1_RC_REFCLK0_DP")
	)
	(segment
		(start 161.940494 -80.518)
		(end 161.940494 -80.142588)
		(width 0.127)
		(layer "F.Cu")
		(net "CLK_100M_CPU1_RC_REFCLK0_DP")
	)
	(via
		(at 161.940494 -80.518)
		(size 0.508)
		(drill 0.254)
		(layers "F.Cu" "B.Cu")
		(net "CLK_100M_CPU1_RC_REFCLK0_DP")
	)
	(via
		(at 119.357902 -66.800984)
		(size 0.508)
		(drill 0.254)
		(layers "F.Cu" "B.Cu")
		(net "CLK_100M_CPU1_RC_REFCLK0_DP")
	)
	(segment
		(start 162.053524 -79.96047)
		(end 162.40887 -79.96047)
		(width 0.127)
		(layer "B.Cu")
		(net "CLK_100M_CPU1_RC_REFCLK0_DP")
	)
	(segment
		(start 161.940494 -80.518)
		(end 161.940494 -80.0735)
		(width 0.127)
		(layer "B.Cu")
		(net "CLK_100M_CPU1_RC_REFCLK0_DP")
	)
	(segment
		(start 162.40887 -79.96047)
		(end 162.7886 -80.3402)
		(width 0.127)
		(layer "B.Cu")
		(net "CLK_100M_CPU1_RC_REFCLK0_DP")
	)
	(segment
		(start 161.940494 -80.0735)
		(end 162.053524 -79.96047)
		(width 0.127)
		(layer "B.Cu")
		(net "CLK_100M_CPU1_RC_REFCLK0_DP")
	)
	(segment
		(start 140.221462 -73.830434)
		(end 140.852144 -73.830434)
		(width 0.0889)
		(layer "In4.Cu")
		(net "CLK_100M_CPU1_RC_REFCLK0_DP")
	)
	(segment
		(start 157.412436 -82.719672)
		(end 157.412436 -83.12277)
		(width 0.1143)
		(layer "In4.Cu")
		(net "CLK_100M_CPU1_RC_REFCLK0_DP")
	)
	(segment
		(start 159.53232 -80.599788)
		(end 157.412436 -82.719672)
		(width 0.1143)
		(layer "In4.Cu")
		(net "CLK_100M_CPU1_RC_REFCLK0_DP")
	)
	(segment
		(start 141.83995 -75.355196)
		(end 141.78915 -75.405996)
		(width 0.0889)
		(layer "In4.Cu")
		(net "CLK_100M_CPU1_RC_REFCLK0_DP")
	)
	(segment
		(start 119.701056 -68.57619)
		(end 119.779288 -68.724018)
		(width 0.0889)
		(layer "In4.Cu")
		(net "CLK_100M_CPU1_RC_REFCLK0_DP")
	)
	(segment
		(start 156.462222 -88.202262)
		(end 156.782262 -87.882222)
		(width 0.1143)
		(layer "In4.Cu")
		(net "CLK_100M_CPU1_RC_REFCLK0_DP")
	)
	(segment
		(start 123.051316 -73.830434)
		(end 123.1011 -73.830434)
		(width 0.0889)
		(layer "In4.Cu")
		(net "CLK_100M_CPU1_RC_REFCLK0_DP")
	)
	(segment
		(start 145.003266 -83.43646)
		(end 145.114264 -83.325462)
		(width 0.1143)
		(layer "In4.Cu")
		(net "CLK_100M_CPU1_RC_REFCLK0_DP")
	)
	(segment
		(start 155.320238 -83.440016)
		(end 155.320238 -87.91702)
		(width 0.1143)
		(layer "In4.Cu")
		(net "CLK_100M_CPU1_RC_REFCLK0_DP")
	)
	(segment
		(start 131.636516 -73.830434)
		(end 131.6863 -73.830434)
		(width 0.0889)
		(layer "In4.Cu")
		(net "CLK_100M_CPU1_RC_REFCLK0_DP")
	)
	(segment
		(start 161.940494 -80.146398)
		(end 161.940494 -80.518)
		(width 0.1143)
		(layer "In4.Cu")
		(net "CLK_100M_CPU1_RC_REFCLK0_DP")
	)
	(segment
		(start 145.003266 -83.709764)
		(end 145.003266 -83.43646)
		(width 0.1143)
		(layer "In4.Cu")
		(net "CLK_100M_CPU1_RC_REFCLK0_DP")
	)
	(segment
		(start 154.799538 -85.757004)
		(end 154.514296 -85.471762)
		(width 0.1143)
		(layer "In4.Cu")
		(net "CLK_100M_CPU1_RC_REFCLK0_DP")
	)
	(segment
		(start 155.205684 -83.325462)
		(end 155.320238 -83.440016)
		(width 0.1143)
		(layer "In4.Cu")
		(net "CLK_100M_CPU1_RC_REFCLK0_DP")
	)
	(segment
		(start 159.387794 -80.23606)
		(end 159.53232 -80.380586)
		(width 0.1143)
		(layer "In4.Cu")
		(net "CLK_100M_CPU1_RC_REFCLK0_DP")
	)
	(segment
		(start 119.779288 -68.724018)
		(end 119.779288 -70.050406)
		(width 0.0889)
		(layer "In4.Cu")
		(net "CLK_100M_CPU1_RC_REFCLK0_DP")
	)
	(segment
		(start 154.799538 -87.91702)
		(end 154.799538 -87.382604)
		(width 0.1143)
		(layer "In4.Cu")
		(net "CLK_100M_CPU1_RC_REFCLK0_DP")
	)
	(segment
		(start 119.357902 -66.800984)
		(end 119.357902 -67.139058)
		(width 0.0889)
		(layer "In4.Cu")
		(net "CLK_100M_CPU1_RC_REFCLK0_DP")
	)
	(segment
		(start 124.768356 -73.830434)
		(end 124.81814 -73.830434)
		(width 0.0889)
		(layer "In4.Cu")
		(net "CLK_100M_CPU1_RC_REFCLK0_DP")
	)
	(segment
		(start 119.779288 -70.050406)
		(end 119.911114 -70.182232)
		(width 0.0889)
		(layer "In4.Cu")
		(net "CLK_100M_CPU1_RC_REFCLK0_DP")
	)
	(segment
		(start 141.78915 -75.405996)
		(end 141.78915 -75.428094)
		(width 0.0889)
		(layer "In4.Cu")
		(net "CLK_100M_CPU1_RC_REFCLK0_DP")
	)
	(segment
		(start 143.183102 -83.493102)
		(end 147.892262 -88.202262)
		(width 0.1143)
		(layer "In4.Cu")
		(net "CLK_100M_CPU1_RC_REFCLK0_DP")
	)
	(segment
		(start 154.514296 -88.202262)
		(end 154.799538 -87.91702)
		(width 0.1143)
		(layer "In4.Cu")
		(net "CLK_100M_CPU1_RC_REFCLK0_DP")
	)
	(segment
		(start 133.353302 -73.830434)
		(end 133.403086 -73.830434)
		(width 0.0889)
		(layer "In4.Cu")
		(net "CLK_100M_CPU1_RC_REFCLK0_DP")
	)
	(segment
		(start 119.911114 -70.182232)
		(end 119.911114 -72.45223)
		(width 0.0889)
		(layer "In4.Cu")
		(net "CLK_100M_CPU1_RC_REFCLK0_DP")
	)
	(segment
		(start 161.826194 -80.032098)
		(end 161.940494 -80.146398)
		(width 0.1143)
		(layer "In4.Cu")
		(net "CLK_100M_CPU1_RC_REFCLK0_DP")
	)
	(segment
		(start 143.183102 -80.353916)
		(end 143.183102 -83.493102)
		(width 0.1143)
		(layer "In4.Cu")
		(net "CLK_100M_CPU1_RC_REFCLK0_DP")
	)
	(segment
		(start 148.36013 -87.097362)
		(end 148.225764 -86.962996)
		(width 0.1143)
		(layer "In4.Cu")
		(net "CLK_100M_CPU1_RC_REFCLK0_DP")
	)
	(segment
		(start 132.173218 -73.535286)
		(end 132.17652 -73.529444)
		(width 0.0889)
		(layer "In4.Cu")
		(net "CLK_100M_CPU1_RC_REFCLK0_DP")
	)
	(segment
		(start 154.514296 -85.471762)
		(end 146.824446 -85.471762)
		(width 0.1143)
		(layer "In4.Cu")
		(net "CLK_100M_CPU1_RC_REFCLK0_DP")
	)
	(segment
		(start 141.78915 -78.959964)
		(end 143.183102 -80.353916)
		(width 0.1143)
		(layer "In4.Cu")
		(net "CLK_100M_CPU1_RC_REFCLK0_DP")
	)
	(segment
		(start 154.514296 -84.951062)
		(end 154.799538 -84.66582)
		(width 0.1143)
		(layer "In4.Cu")
		(net "CLK_100M_CPU1_RC_REFCLK0_DP")
	)
	(segment
		(start 158.207964 -83.488022)
		(end 161.663888 -80.032098)
		(width 0.1143)
		(layer "In4.Cu")
		(net "CLK_100M_CPU1_RC_REFCLK0_DP")
	)
	(segment
		(start 141.78915 -75.428094)
		(end 141.78915 -78.959964)
		(width 0.1143)
		(layer "In4.Cu")
		(net "CLK_100M_CPU1_RC_REFCLK0_DP")
	)
	(segment
		(start 157.777688 -83.488022)
		(end 158.207964 -83.488022)
		(width 0.1143)
		(layer "In4.Cu")
		(net "CLK_100M_CPU1_RC_REFCLK0_DP")
	)
	(segment
		(start 136.787382 -73.830434)
		(end 136.837166 -73.830434)
		(width 0.0889)
		(layer "In4.Cu")
		(net "CLK_100M_CPU1_RC_REFCLK0_DP")
	)
	(segment
		(start 161.663888 -80.032098)
		(end 161.826194 -80.032098)
		(width 0.1143)
		(layer "In4.Cu")
		(net "CLK_100M_CPU1_RC_REFCLK0_DP")
	)
	(segment
		(start 146.696684 -85.07222)
		(end 146.817842 -84.951062)
		(width 0.1143)
		(layer "In4.Cu")
		(net "CLK_100M_CPU1_RC_REFCLK0_DP")
	)
	(segment
		(start 145.114264 -83.325462)
		(end 155.205684 -83.325462)
		(width 0.1143)
		(layer "In4.Cu")
		(net "CLK_100M_CPU1_RC_REFCLK0_DP")
	)
	(segment
		(start 120.298972 -72.840088)
		(end 121.374154 -72.840088)
		(width 0.0889)
		(layer "In4.Cu")
		(net "CLK_100M_CPU1_RC_REFCLK0_DP")
	)
	(segment
		(start 126.492508 -73.830688)
		(end 126.528068 -73.830688)
		(width 0.0889)
		(layer "In4.Cu")
		(net "CLK_100M_CPU1_RC_REFCLK0_DP")
	)
	(segment
		(start 122.196352 -73.335134)
		(end 122.228864 -73.335134)
		(width 0.0889)
		(layer "In4.Cu")
		(net "CLK_100M_CPU1_RC_REFCLK0_DP")
	)
	(segment
		(start 156.782262 -87.882222)
		(end 156.782262 -82.612992)
		(width 0.1143)
		(layer "In4.Cu")
		(net "CLK_100M_CPU1_RC_REFCLK0_DP")
	)
	(segment
		(start 154.514296 -87.097362)
		(end 148.36013 -87.097362)
		(width 0.1143)
		(layer "In4.Cu")
		(net "CLK_100M_CPU1_RC_REFCLK0_DP")
	)
	(segment
		(start 145.139664 -83.846162)
		(end 145.003266 -83.709764)
		(width 0.1143)
		(layer "In4.Cu")
		(net "CLK_100M_CPU1_RC_REFCLK0_DP")
	)
	(segment
		(start 148.340064 -86.576662)
		(end 154.514296 -86.576662)
		(width 0.1143)
		(layer "In4.Cu")
		(net "CLK_100M_CPU1_RC_REFCLK0_DP")
	)
	(segment
		(start 154.514296 -83.846162)
		(end 145.139664 -83.846162)
		(width 0.1143)
		(layer "In4.Cu")
		(net "CLK_100M_CPU1_RC_REFCLK0_DP")
	)
	(segment
		(start 159.53232 -80.380586)
		(end 159.53232 -80.599788)
		(width 0.1143)
		(layer "In4.Cu")
		(net "CLK_100M_CPU1_RC_REFCLK0_DP")
	)
	(segment
		(start 138.504422 -73.830434)
		(end 138.554206 -73.830434)
		(width 0.0889)
		(layer "In4.Cu")
		(net "CLK_100M_CPU1_RC_REFCLK0_DP")
	)
	(segment
		(start 140.852144 -73.830434)
		(end 141.83995 -74.81824)
		(width 0.0889)
		(layer "In4.Cu")
		(net "CLK_100M_CPU1_RC_REFCLK0_DP")
	)
	(segment
		(start 155.320238 -87.91702)
		(end 155.60548 -88.202262)
		(width 0.1143)
		(layer "In4.Cu")
		(net "CLK_100M_CPU1_RC_REFCLK0_DP")
	)
	(segment
		(start 156.782262 -82.612992)
		(end 159.159194 -80.23606)
		(width 0.1143)
		(layer "In4.Cu")
		(net "CLK_100M_CPU1_RC_REFCLK0_DP")
	)
	(segment
		(start 135.070342 -73.830434)
		(end 135.120126 -73.830434)
		(width 0.0889)
		(layer "In4.Cu")
		(net "CLK_100M_CPU1_RC_REFCLK0_DP")
	)
	(segment
		(start 119.357902 -67.139058)
		(end 119.292624 -67.204336)
		(width 0.0889)
		(layer "In4.Cu")
		(net "CLK_100M_CPU1_RC_REFCLK0_DP")
	)
	(segment
		(start 148.225764 -86.690962)
		(end 148.340064 -86.576662)
		(width 0.1143)
		(layer "In4.Cu")
		(net "CLK_100M_CPU1_RC_REFCLK0_DP")
	)
	(segment
		(start 128.209548 -73.830688)
		(end 128.245108 -73.830688)
		(width 0.0889)
		(layer "In4.Cu")
		(net "CLK_100M_CPU1_RC_REFCLK0_DP")
	)
	(segment
		(start 157.412436 -83.12277)
		(end 157.777688 -83.488022)
		(width 0.1143)
		(layer "In4.Cu")
		(net "CLK_100M_CPU1_RC_REFCLK0_DP")
	)
	(segment
		(start 154.799538 -84.131404)
		(end 154.514296 -83.846162)
		(width 0.1143)
		(layer "In4.Cu")
		(net "CLK_100M_CPU1_RC_REFCLK0_DP")
	)
	(segment
		(start 119.911114 -72.45223)
		(end 120.298972 -72.840088)
		(width 0.0889)
		(layer "In4.Cu")
		(net "CLK_100M_CPU1_RC_REFCLK0_DP")
	)
	(segment
		(start 146.824446 -85.471762)
		(end 146.696684 -85.344)
		(width 0.1143)
		(layer "In4.Cu")
		(net "CLK_100M_CPU1_RC_REFCLK0_DP")
	)
	(segment
		(start 146.696684 -85.344)
		(end 146.696684 -85.07222)
		(width 0.1143)
		(layer "In4.Cu")
		(net "CLK_100M_CPU1_RC_REFCLK0_DP")
	)
	(segment
		(start 129.919476 -73.830434)
		(end 129.96926 -73.830434)
		(width 0.0889)
		(layer "In4.Cu")
		(net "CLK_100M_CPU1_RC_REFCLK0_DP")
	)
	(segment
		(start 159.159194 -80.23606)
		(end 159.387794 -80.23606)
		(width 0.1143)
		(layer "In4.Cu")
		(net "CLK_100M_CPU1_RC_REFCLK0_DP")
	)
	(segment
		(start 154.514296 -86.576662)
		(end 154.799538 -86.29142)
		(width 0.1143)
		(layer "In4.Cu")
		(net "CLK_100M_CPU1_RC_REFCLK0_DP")
	)
	(segment
		(start 154.799538 -87.382604)
		(end 154.514296 -87.097362)
		(width 0.1143)
		(layer "In4.Cu")
		(net "CLK_100M_CPU1_RC_REFCLK0_DP")
	)
	(segment
		(start 146.817842 -84.951062)
		(end 154.514296 -84.951062)
		(width 0.1143)
		(layer "In4.Cu")
		(net "CLK_100M_CPU1_RC_REFCLK0_DP")
	)
	(segment
		(start 141.83995 -74.81824)
		(end 141.83995 -75.355196)
		(width 0.0889)
		(layer "In4.Cu")
		(net "CLK_100M_CPU1_RC_REFCLK0_DP")
	)
	(segment
		(start 154.799538 -84.66582)
		(end 154.799538 -84.131404)
		(width 0.1143)
		(layer "In4.Cu")
		(net "CLK_100M_CPU1_RC_REFCLK0_DP")
	)
	(segment
		(start 154.799538 -86.29142)
		(end 154.799538 -85.757004)
		(width 0.1143)
		(layer "In4.Cu")
		(net "CLK_100M_CPU1_RC_REFCLK0_DP")
	)
	(segment
		(start 147.892262 -88.202262)
		(end 154.514296 -88.202262)
		(width 0.1143)
		(layer "In4.Cu")
		(net "CLK_100M_CPU1_RC_REFCLK0_DP")
	)
	(segment
		(start 148.225764 -86.962996)
		(end 148.225764 -86.690962)
		(width 0.1143)
		(layer "In4.Cu")
		(net "CLK_100M_CPU1_RC_REFCLK0_DP")
	)
	(segment
		(start 155.60548 -88.202262)
		(end 156.462222 -88.202262)
		(width 0.1143)
		(layer "In4.Cu")
		(net "CLK_100M_CPU1_RC_REFCLK0_DP")
	)
	(segment
		(start 119.336312 -68.382134)
		(end 119.37238 -68.382134)
		(width 0.0889)
		(layer "In4.Cu")
		(net "CLK_100M_CPU1_RC_REFCLK0_DP")
	)
	(arc
		(start 139.375896 -73.335134)
		(mid 139.387834 -73.334956)
		(end 139.399772 -73.335134)
		(width 0.0889)
		(layer "In4.Cu")
		(net "CLK_100M_CPU1_RC_REFCLK0_DP")
	)
	(arc
		(start 138.554206 -73.830434)
		(mid 138.835568 -73.745388)
		(end 139.041124 -73.535286)
		(width 0.0889)
		(layer "In4.Cu")
		(net "CLK_100M_CPU1_RC_REFCLK0_DP")
	)
	(arc
		(start 129.097786 -73.335134)
		(mid 129.291212 -73.391661)
		(end 129.432558 -73.535286)
		(width 0.0889)
		(layer "In4.Cu")
		(net "CLK_100M_CPU1_RC_REFCLK0_DP")
	)
	(arc
		(start 123.588018 -73.535286)
		(mid 123.934728 -73.334975)
		(end 124.281438 -73.535286)
		(width 0.0889)
		(layer "In4.Cu")
		(net "CLK_100M_CPU1_RC_REFCLK0_DP")
	)
	(arc
		(start 132.507736 -73.335134)
		(mid 132.519674 -73.334956)
		(end 132.531612 -73.335134)
		(width 0.0889)
		(layer "In4.Cu")
		(net "CLK_100M_CPU1_RC_REFCLK0_DP")
	)
	(arc
		(start 129.07391 -73.335134)
		(mid 129.085848 -73.334956)
		(end 129.097786 -73.335134)
		(width 0.0889)
		(layer "In4.Cu")
		(net "CLK_100M_CPU1_RC_REFCLK0_DP")
	)
	(arc
		(start 127.380746 -73.335134)
		(mid 127.574172 -73.391661)
		(end 127.715518 -73.535286)
		(width 0.0889)
		(layer "In4.Cu")
		(net "CLK_100M_CPU1_RC_REFCLK0_DP")
	)
	(arc
		(start 119.37238 -68.382134)
		(mid 119.561366 -68.437435)
		(end 119.701056 -68.57619)
		(width 0.0889)
		(layer "In4.Cu")
		(net "CLK_100M_CPU1_RC_REFCLK0_DP")
	)
	(arc
		(start 121.705878 -73.039986)
		(mid 121.912991 -73.250916)
		(end 122.196352 -73.335134)
		(width 0.0889)
		(layer "In4.Cu")
		(net "CLK_100M_CPU1_RC_REFCLK0_DP")
	)
	(arc
		(start 138.017504 -73.535286)
		(mid 138.223063 -73.745383)
		(end 138.504422 -73.830434)
		(width 0.0889)
		(layer "In4.Cu")
		(net "CLK_100M_CPU1_RC_REFCLK0_DP")
	)
	(arc
		(start 139.041124 -73.535286)
		(mid 139.18248 -73.391677)
		(end 139.375896 -73.335134)
		(width 0.0889)
		(layer "In4.Cu")
		(net "CLK_100M_CPU1_RC_REFCLK0_DP")
	)
	(arc
		(start 122.564398 -73.535286)
		(mid 122.769957 -73.745383)
		(end 123.051316 -73.830434)
		(width 0.0889)
		(layer "In4.Cu")
		(net "CLK_100M_CPU1_RC_REFCLK0_DP")
	)
	(arc
		(start 121.374154 -72.840088)
		(mid 121.565796 -72.897254)
		(end 121.705878 -73.039986)
		(width 0.0889)
		(layer "In4.Cu")
		(net "CLK_100M_CPU1_RC_REFCLK0_DP")
	)
	(arc
		(start 135.965692 -73.335134)
		(mid 136.159118 -73.391661)
		(end 136.300464 -73.535286)
		(width 0.0889)
		(layer "In4.Cu")
		(net "CLK_100M_CPU1_RC_REFCLK0_DP")
	)
	(arc
		(start 134.248652 -73.335134)
		(mid 134.442078 -73.391661)
		(end 134.583424 -73.535286)
		(width 0.0889)
		(layer "In4.Cu")
		(net "CLK_100M_CPU1_RC_REFCLK0_DP")
	)
	(arc
		(start 132.866384 -73.535286)
		(mid 133.071943 -73.745383)
		(end 133.353302 -73.830434)
		(width 0.0889)
		(layer "In4.Cu")
		(net "CLK_100M_CPU1_RC_REFCLK0_DP")
	)
	(arc
		(start 124.81814 -73.830434)
		(mid 125.099502 -73.745388)
		(end 125.305058 -73.535286)
		(width 0.0889)
		(layer "In4.Cu")
		(net "CLK_100M_CPU1_RC_REFCLK0_DP")
	)
	(arc
		(start 125.663706 -73.335134)
		(mid 125.857132 -73.391661)
		(end 125.998478 -73.535286)
		(width 0.0889)
		(layer "In4.Cu")
		(net "CLK_100M_CPU1_RC_REFCLK0_DP")
	)
	(arc
		(start 129.96926 -73.830434)
		(mid 130.250622 -73.745388)
		(end 130.456178 -73.535286)
		(width 0.0889)
		(layer "In4.Cu")
		(net "CLK_100M_CPU1_RC_REFCLK0_DP")
	)
	(arc
		(start 131.6863 -73.830434)
		(mid 131.967662 -73.745388)
		(end 132.173218 -73.535286)
		(width 0.0889)
		(layer "In4.Cu")
		(net "CLK_100M_CPU1_RC_REFCLK0_DP")
	)
	(arc
		(start 136.300464 -73.535286)
		(mid 136.506023 -73.745383)
		(end 136.787382 -73.830434)
		(width 0.0889)
		(layer "In4.Cu")
		(net "CLK_100M_CPU1_RC_REFCLK0_DP")
	)
	(arc
		(start 127.022098 -73.535286)
		(mid 127.163454 -73.391677)
		(end 127.35687 -73.335134)
		(width 0.0889)
		(layer "In4.Cu")
		(net "CLK_100M_CPU1_RC_REFCLK0_DP")
	)
	(arc
		(start 137.658856 -73.335134)
		(mid 137.670794 -73.334956)
		(end 137.682732 -73.335134)
		(width 0.0889)
		(layer "In4.Cu")
		(net "CLK_100M_CPU1_RC_REFCLK0_DP")
	)
	(arc
		(start 127.715518 -73.535286)
		(mid 127.924126 -73.747218)
		(end 128.209548 -73.830688)
		(width 0.0889)
		(layer "In4.Cu")
		(net "CLK_100M_CPU1_RC_REFCLK0_DP")
	)
	(arc
		(start 124.281438 -73.535286)
		(mid 124.486997 -73.745383)
		(end 124.768356 -73.830434)
		(width 0.0889)
		(layer "In4.Cu")
		(net "CLK_100M_CPU1_RC_REFCLK0_DP")
	)
	(arc
		(start 132.17652 -73.529444)
		(mid 132.317293 -73.389935)
		(end 132.507736 -73.335134)
		(width 0.0889)
		(layer "In4.Cu")
		(net "CLK_100M_CPU1_RC_REFCLK0_DP")
	)
	(arc
		(start 126.528068 -73.830688)
		(mid 126.813492 -73.747221)
		(end 127.022098 -73.535286)
		(width 0.0889)
		(layer "In4.Cu")
		(net "CLK_100M_CPU1_RC_REFCLK0_DP")
	)
	(arc
		(start 136.837166 -73.830434)
		(mid 137.118528 -73.745388)
		(end 137.324084 -73.535286)
		(width 0.0889)
		(layer "In4.Cu")
		(net "CLK_100M_CPU1_RC_REFCLK0_DP")
	)
	(arc
		(start 125.305058 -73.535286)
		(mid 125.446414 -73.391677)
		(end 125.63983 -73.335134)
		(width 0.0889)
		(layer "In4.Cu")
		(net "CLK_100M_CPU1_RC_REFCLK0_DP")
	)
	(arc
		(start 131.149598 -73.535286)
		(mid 131.355157 -73.745383)
		(end 131.636516 -73.830434)
		(width 0.0889)
		(layer "In4.Cu")
		(net "CLK_100M_CPU1_RC_REFCLK0_DP")
	)
	(arc
		(start 128.739138 -73.535286)
		(mid 128.880494 -73.391677)
		(end 129.07391 -73.335134)
		(width 0.0889)
		(layer "In4.Cu")
		(net "CLK_100M_CPU1_RC_REFCLK0_DP")
	)
	(arc
		(start 135.607044 -73.535286)
		(mid 135.7484 -73.391677)
		(end 135.941816 -73.335134)
		(width 0.0889)
		(layer "In4.Cu")
		(net "CLK_100M_CPU1_RC_REFCLK0_DP")
	)
	(arc
		(start 139.399772 -73.335134)
		(mid 139.593198 -73.391661)
		(end 139.734544 -73.535286)
		(width 0.0889)
		(layer "In4.Cu")
		(net "CLK_100M_CPU1_RC_REFCLK0_DP")
	)
	(arc
		(start 130.79095 -73.335134)
		(mid 130.802888 -73.334956)
		(end 130.814826 -73.335134)
		(width 0.0889)
		(layer "In4.Cu")
		(net "CLK_100M_CPU1_RC_REFCLK0_DP")
	)
	(arc
		(start 128.245108 -73.830688)
		(mid 128.530532 -73.747221)
		(end 128.739138 -73.535286)
		(width 0.0889)
		(layer "In4.Cu")
		(net "CLK_100M_CPU1_RC_REFCLK0_DP")
	)
	(arc
		(start 122.228864 -73.335134)
		(mid 122.422714 -73.391484)
		(end 122.564398 -73.535286)
		(width 0.0889)
		(layer "In4.Cu")
		(net "CLK_100M_CPU1_RC_REFCLK0_DP")
	)
	(arc
		(start 133.403086 -73.830434)
		(mid 133.684448 -73.745388)
		(end 133.890004 -73.535286)
		(width 0.0889)
		(layer "In4.Cu")
		(net "CLK_100M_CPU1_RC_REFCLK0_DP")
	)
	(arc
		(start 125.998478 -73.535286)
		(mid 126.207086 -73.747218)
		(end 126.492508 -73.830688)
		(width 0.0889)
		(layer "In4.Cu")
		(net "CLK_100M_CPU1_RC_REFCLK0_DP")
	)
	(arc
		(start 119.292624 -67.204336)
		(mid 118.767443 -67.813489)
		(end 119.336312 -68.382134)
		(width 0.0889)
		(layer "In4.Cu")
		(net "CLK_100M_CPU1_RC_REFCLK0_DP")
	)
	(arc
		(start 135.120126 -73.830434)
		(mid 135.401488 -73.745388)
		(end 135.607044 -73.535286)
		(width 0.0889)
		(layer "In4.Cu")
		(net "CLK_100M_CPU1_RC_REFCLK0_DP")
	)
	(arc
		(start 130.456178 -73.535286)
		(mid 130.597534 -73.391677)
		(end 130.79095 -73.335134)
		(width 0.0889)
		(layer "In4.Cu")
		(net "CLK_100M_CPU1_RC_REFCLK0_DP")
	)
	(arc
		(start 127.35687 -73.335134)
		(mid 127.368808 -73.334956)
		(end 127.380746 -73.335134)
		(width 0.0889)
		(layer "In4.Cu")
		(net "CLK_100M_CPU1_RC_REFCLK0_DP")
	)
	(arc
		(start 135.941816 -73.335134)
		(mid 135.953754 -73.334956)
		(end 135.965692 -73.335134)
		(width 0.0889)
		(layer "In4.Cu")
		(net "CLK_100M_CPU1_RC_REFCLK0_DP")
	)
	(arc
		(start 123.1011 -73.830434)
		(mid 123.382462 -73.745388)
		(end 123.588018 -73.535286)
		(width 0.0889)
		(layer "In4.Cu")
		(net "CLK_100M_CPU1_RC_REFCLK0_DP")
	)
	(arc
		(start 132.531612 -73.335134)
		(mid 132.725038 -73.391661)
		(end 132.866384 -73.535286)
		(width 0.0889)
		(layer "In4.Cu")
		(net "CLK_100M_CPU1_RC_REFCLK0_DP")
	)
	(arc
		(start 134.224776 -73.335134)
		(mid 134.236714 -73.334956)
		(end 134.248652 -73.335134)
		(width 0.0889)
		(layer "In4.Cu")
		(net "CLK_100M_CPU1_RC_REFCLK0_DP")
	)
	(arc
		(start 137.682732 -73.335134)
		(mid 137.876158 -73.391661)
		(end 138.017504 -73.535286)
		(width 0.0889)
		(layer "In4.Cu")
		(net "CLK_100M_CPU1_RC_REFCLK0_DP")
	)
	(arc
		(start 129.432558 -73.535286)
		(mid 129.638117 -73.745383)
		(end 129.919476 -73.830434)
		(width 0.0889)
		(layer "In4.Cu")
		(net "CLK_100M_CPU1_RC_REFCLK0_DP")
	)
	(arc
		(start 137.324084 -73.535286)
		(mid 137.46544 -73.391677)
		(end 137.658856 -73.335134)
		(width 0.0889)
		(layer "In4.Cu")
		(net "CLK_100M_CPU1_RC_REFCLK0_DP")
	)
	(arc
		(start 133.890004 -73.535286)
		(mid 134.03136 -73.391677)
		(end 134.224776 -73.335134)
		(width 0.0889)
		(layer "In4.Cu")
		(net "CLK_100M_CPU1_RC_REFCLK0_DP")
	)
	(arc
		(start 130.814826 -73.335134)
		(mid 131.008252 -73.391661)
		(end 131.149598 -73.535286)
		(width 0.0889)
		(layer "In4.Cu")
		(net "CLK_100M_CPU1_RC_REFCLK0_DP")
	)
	(arc
		(start 125.63983 -73.335134)
		(mid 125.651768 -73.334956)
		(end 125.663706 -73.335134)
		(width 0.0889)
		(layer "In4.Cu")
		(net "CLK_100M_CPU1_RC_REFCLK0_DP")
	)
	(arc
		(start 139.734544 -73.535286)
		(mid 139.940103 -73.745383)
		(end 140.221462 -73.830434)
		(width 0.0889)
		(layer "In4.Cu")
		(net "CLK_100M_CPU1_RC_REFCLK0_DP")
	)
	(arc
		(start 134.583424 -73.535286)
		(mid 134.788983 -73.745383)
		(end 135.070342 -73.830434)
		(width 0.0889)
		(layer "In4.Cu")
		(net "CLK_100M_CPU1_RC_REFCLK0_DP")
	)
	(segment
		(start 162.687 -79.654654)
		(end 162.618166 -79.723488)
		(width 0.127)
		(layer "F.Cu")
		(net "CLK_100M_CPU1_RC_REFCLK0_DN")
	)
	(segment
		(start 162.687 -79.248)
		(end 162.687 -79.654654)
		(width 0.127)
		(layer "F.Cu")
		(net "CLK_100M_CPU1_RC_REFCLK0_DN")
	)
	(segment
		(start 162.015932 -79.723488)
		(end 161.940494 -79.64805)
		(width 0.127)
		(layer "F.Cu")
		(net "CLK_100M_CPU1_RC_REFCLK0_DN")
	)
	(segment
		(start 119.357902 -67.791584)
		(end 119.929402 -67.791584)
		(width 0.127)
		(layer "F.Cu")
		(net "CLK_100M_CPU1_RC_REFCLK0_DN")
	)
	(segment
		(start 162.618166 -79.723488)
		(end 162.015932 -79.723488)
		(width 0.127)
		(layer "F.Cu")
		(net "CLK_100M_CPU1_RC_REFCLK0_DN")
	)
	(segment
		(start 161.940494 -79.64805)
		(end 161.940494 -79.248)
		(width 0.127)
		(layer "F.Cu")
		(net "CLK_100M_CPU1_RC_REFCLK0_DN")
	)
	(via
		(at 161.940494 -79.248)
		(size 0.508)
		(drill 0.254)
		(layers "F.Cu" "B.Cu")
		(net "CLK_100M_CPU1_RC_REFCLK0_DN")
	)
	(via
		(at 119.357902 -67.791584)
		(size 0.508)
		(drill 0.254)
		(layers "F.Cu" "B.Cu")
		(net "CLK_100M_CPU1_RC_REFCLK0_DN")
	)
	(segment
		(start 161.940494 -79.605378)
		(end 161.940494 -79.248)
		(width 0.127)
		(layer "B.Cu")
		(net "CLK_100M_CPU1_RC_REFCLK0_DN")
	)
	(segment
		(start 162.687 -79.605378)
		(end 162.560508 -79.73187)
		(width 0.127)
		(layer "B.Cu")
		(net "CLK_100M_CPU1_RC_REFCLK0_DN")
	)
	(segment
		(start 162.7886 -79.248)
		(end 162.687 -79.3496)
		(width 0.127)
		(layer "B.Cu")
		(net "CLK_100M_CPU1_RC_REFCLK0_DN")
	)
	(segment
		(start 162.687 -79.3496)
		(end 162.687 -79.605378)
		(width 0.127)
		(layer "B.Cu")
		(net "CLK_100M_CPU1_RC_REFCLK0_DN")
	)
	(segment
		(start 162.560508 -79.73187)
		(end 162.066986 -79.73187)
		(width 0.127)
		(layer "B.Cu")
		(net "CLK_100M_CPU1_RC_REFCLK0_DN")
	)
	(segment
		(start 162.066986 -79.73187)
		(end 161.940494 -79.605378)
		(width 0.127)
		(layer "B.Cu")
		(net "CLK_100M_CPU1_RC_REFCLK0_DN")
	)
	(segment
		(start 120.101614 -70.103238)
		(end 120.101614 -70.369938)
		(width 0.0889)
		(layer "In4.Cu")
		(net "CLK_100M_CPU1_RC_REFCLK0_DN")
	)
	(segment
		(start 142.08125 -76.444094)
		(end 142.08125 -76.786994)
		(width 0.1143)
		(layer "In4.Cu")
		(net "CLK_100M_CPU1_RC_REFCLK0_DN")
	)
	(segment
		(start 142.24635 -78.310994)
		(end 142.08125 -78.476094)
		(width 0.1143)
		(layer "In4.Cu")
		(net "CLK_100M_CPU1_RC_REFCLK0_DN")
	)
	(segment
		(start 145.018506 -84.138262)
		(end 144.711166 -83.830922)
		(width 0.1143)
		(layer "In4.Cu")
		(net "CLK_100M_CPU1_RC_REFCLK0_DN")
	)
	(segment
		(start 119.969788 -68.96735)
		(end 120.058688 -69.05625)
		(width 0.0889)
		(layer "In4.Cu")
		(net "CLK_100M_CPU1_RC_REFCLK0_DN")
	)
	(segment
		(start 142.08125 -75.405996)
		(end 142.08125 -75.428094)
		(width 0.0889)
		(layer "In4.Cu")
		(net "CLK_100M_CPU1_RC_REFCLK0_DN")
	)
	(segment
		(start 123.058174 -73.639934)
		(end 123.094242 -73.639934)
		(width 0.0889)
		(layer "In4.Cu")
		(net "CLK_100M_CPU1_RC_REFCLK0_DN")
	)
	(segment
		(start 120.101614 -72.373236)
		(end 120.377966 -72.649588)
		(width 0.0889)
		(layer "In4.Cu")
		(net "CLK_100M_CPU1_RC_REFCLK0_DN")
	)
	(segment
		(start 158.086806 -83.195922)
		(end 161.54273 -79.739998)
		(width 0.1143)
		(layer "In4.Cu")
		(net "CLK_100M_CPU1_RC_REFCLK0_DN")
	)
	(segment
		(start 154.507438 -87.503762)
		(end 154.393138 -87.389462)
		(width 0.1143)
		(layer "In4.Cu")
		(net "CLK_100M_CPU1_RC_REFCLK0_DN")
	)
	(segment
		(start 120.058688 -69.05625)
		(end 120.058688 -69.32295)
		(width 0.0889)
		(layer "In4.Cu")
		(net "CLK_100M_CPU1_RC_REFCLK0_DN")
	)
	(segment
		(start 161.940494 -79.62265)
		(end 161.940494 -79.248)
		(width 0.1143)
		(layer "In4.Cu")
		(net "CLK_100M_CPU1_RC_REFCLK0_DN")
	)
	(segment
		(start 122.200162 -73.144634)
		(end 122.235468 -73.144634)
		(width 0.0889)
		(layer "In4.Cu")
		(net "CLK_100M_CPU1_RC_REFCLK0_DN")
	)
	(segment
		(start 156.490162 -82.491834)
		(end 159.038036 -79.94396)
		(width 0.1143)
		(layer "In4.Cu")
		(net "CLK_100M_CPU1_RC_REFCLK0_DN")
	)
	(segment
		(start 143.475202 -83.371944)
		(end 148.01342 -87.910162)
		(width 0.1143)
		(layer "In4.Cu")
		(net "CLK_100M_CPU1_RC_REFCLK0_DN")
	)
	(segment
		(start 146.696684 -84.658962)
		(end 154.393138 -84.658962)
		(width 0.1143)
		(layer "In4.Cu")
		(net "CLK_100M_CPU1_RC_REFCLK0_DN")
	)
	(segment
		(start 120.646444 -72.649588)
		(end 120.735344 -72.560688)
		(width 0.0889)
		(layer "In4.Cu")
		(net "CLK_100M_CPU1_RC_REFCLK0_DN")
	)
	(segment
		(start 154.393138 -84.138262)
		(end 145.018506 -84.138262)
		(width 0.1143)
		(layer "In4.Cu")
		(net "CLK_100M_CPU1_RC_REFCLK0_DN")
	)
	(segment
		(start 157.898846 -83.195922)
		(end 158.086806 -83.195922)
		(width 0.1143)
		(layer "In4.Cu")
		(net "CLK_100M_CPU1_RC_REFCLK0_DN")
	)
	(segment
		(start 161.823146 -79.739998)
		(end 161.940494 -79.62265)
		(width 0.1143)
		(layer "In4.Cu")
		(net "CLK_100M_CPU1_RC_REFCLK0_DN")
	)
	(segment
		(start 154.507438 -87.795862)
		(end 154.507438 -87.503762)
		(width 0.1143)
		(layer "In4.Cu")
		(net "CLK_100M_CPU1_RC_REFCLK0_DN")
	)
	(segment
		(start 144.711166 -83.830922)
		(end 144.711166 -83.315302)
		(width 0.1143)
		(layer "In4.Cu")
		(net "CLK_100M_CPU1_RC_REFCLK0_DN")
	)
	(segment
		(start 142.24635 -77.968094)
		(end 142.24635 -78.310994)
		(width 0.1143)
		(layer "In4.Cu")
		(net "CLK_100M_CPU1_RC_REFCLK0_DN")
	)
	(segment
		(start 141.406118 -73.989184)
		(end 141.594586 -74.177652)
		(width 0.0889)
		(layer "In4.Cu")
		(net "CLK_100M_CPU1_RC_REFCLK0_DN")
	)
	(segment
		(start 148.218906 -86.284562)
		(end 154.393138 -86.284562)
		(width 0.1143)
		(layer "In4.Cu")
		(net "CLK_100M_CPU1_RC_REFCLK0_DN")
	)
	(segment
		(start 141.594586 -74.177652)
		(end 141.594586 -74.303382)
		(width 0.0889)
		(layer "In4.Cu")
		(net "CLK_100M_CPU1_RC_REFCLK0_DN")
	)
	(segment
		(start 119.867426 -68.482972)
		(end 119.969788 -68.676774)
		(width 0.0889)
		(layer "In4.Cu")
		(net "CLK_100M_CPU1_RC_REFCLK0_DN")
	)
	(segment
		(start 142.03045 -74.739246)
		(end 142.03045 -75.355196)
		(width 0.0889)
		(layer "In4.Cu")
		(net "CLK_100M_CPU1_RC_REFCLK0_DN")
	)
	(segment
		(start 138.51128 -73.639934)
		(end 138.547348 -73.639934)
		(width 0.0889)
		(layer "In4.Cu")
		(net "CLK_100M_CPU1_RC_REFCLK0_DN")
	)
	(segment
		(start 142.08125 -75.428094)
		(end 142.08125 -75.770994)
		(width 0.1143)
		(layer "In4.Cu")
		(net "CLK_100M_CPU1_RC_REFCLK0_DN")
	)
	(segment
		(start 132.501894 -73.144634)
		(end 132.537454 -73.144634)
		(width 0.0889)
		(layer "In4.Cu")
		(net "CLK_100M_CPU1_RC_REFCLK0_DN")
	)
	(segment
		(start 146.404584 -85.465158)
		(end 146.404584 -84.951062)
		(width 0.1143)
		(layer "In4.Cu")
		(net "CLK_100M_CPU1_RC_REFCLK0_DN")
	)
	(segment
		(start 159.508952 -79.94396)
		(end 159.82442 -80.259428)
		(width 0.1143)
		(layer "In4.Cu")
		(net "CLK_100M_CPU1_RC_REFCLK0_DN")
	)
	(segment
		(start 134.218934 -73.144634)
		(end 134.254494 -73.144634)
		(width 0.0889)
		(layer "In4.Cu")
		(net "CLK_100M_CPU1_RC_REFCLK0_DN")
	)
	(segment
		(start 125.633988 -73.144634)
		(end 125.669548 -73.144634)
		(width 0.0889)
		(layer "In4.Cu")
		(net "CLK_100M_CPU1_RC_REFCLK0_DN")
	)
	(segment
		(start 142.08125 -77.460094)
		(end 142.08125 -77.802994)
		(width 0.1143)
		(layer "In4.Cu")
		(net "CLK_100M_CPU1_RC_REFCLK0_DN")
	)
	(segment
		(start 154.507438 -85.878162)
		(end 154.393138 -85.763862)
		(width 0.1143)
		(layer "In4.Cu")
		(net "CLK_100M_CPU1_RC_REFCLK0_DN")
	)
	(segment
		(start 142.08125 -78.838806)
		(end 143.475202 -80.232758)
		(width 0.1143)
		(layer "In4.Cu")
		(net "CLK_100M_CPU1_RC_REFCLK0_DN")
	)
	(segment
		(start 120.101614 -70.369938)
		(end 120.190514 -70.458838)
		(width 0.0889)
		(layer "In4.Cu")
		(net "CLK_100M_CPU1_RC_REFCLK0_DN")
	)
	(segment
		(start 120.377966 -72.649588)
		(end 120.646444 -72.649588)
		(width 0.0889)
		(layer "In4.Cu")
		(net "CLK_100M_CPU1_RC_REFCLK0_DN")
	)
	(segment
		(start 142.08125 -77.802994)
		(end 142.24635 -77.968094)
		(width 0.1143)
		(layer "In4.Cu")
		(net "CLK_100M_CPU1_RC_REFCLK0_DN")
	)
	(segment
		(start 161.54273 -79.739998)
		(end 161.823146 -79.739998)
		(width 0.1143)
		(layer "In4.Cu")
		(net "CLK_100M_CPU1_RC_REFCLK0_DN")
	)
	(segment
		(start 144.993106 -83.033362)
		(end 155.326842 -83.033362)
		(width 0.1143)
		(layer "In4.Cu")
		(net "CLK_100M_CPU1_RC_REFCLK0_DN")
	)
	(segment
		(start 119.357902 -67.791584)
		(end 119.357902 -67.45351)
		(width 0.0889)
		(layer "In4.Cu")
		(net "CLK_100M_CPU1_RC_REFCLK0_DN")
	)
	(segment
		(start 135.0772 -73.639934)
		(end 135.113268 -73.639934)
		(width 0.0889)
		(layer "In4.Cu")
		(net "CLK_100M_CPU1_RC_REFCLK0_DN")
	)
	(segment
		(start 159.82442 -80.259428)
		(end 159.82442 -80.720946)
		(width 0.1143)
		(layer "In4.Cu")
		(net "CLK_100M_CPU1_RC_REFCLK0_DN")
	)
	(segment
		(start 146.703288 -85.763862)
		(end 146.404584 -85.465158)
		(width 0.1143)
		(layer "In4.Cu")
		(net "CLK_100M_CPU1_RC_REFCLK0_DN")
	)
	(segment
		(start 120.190514 -71.170038)
		(end 120.190514 -71.436738)
		(width 0.0889)
		(layer "In4.Cu")
		(net "CLK_100M_CPU1_RC_REFCLK0_DN")
	)
	(segment
		(start 142.24635 -77.294994)
		(end 142.08125 -77.460094)
		(width 0.1143)
		(layer "In4.Cu")
		(net "CLK_100M_CPU1_RC_REFCLK0_DN")
	)
	(segment
		(start 154.393138 -87.910162)
		(end 154.507438 -87.795862)
		(width 0.1143)
		(layer "In4.Cu")
		(net "CLK_100M_CPU1_RC_REFCLK0_DN")
	)
	(segment
		(start 127.351028 -73.144634)
		(end 127.386588 -73.144634)
		(width 0.0889)
		(layer "In4.Cu")
		(net "CLK_100M_CPU1_RC_REFCLK0_DN")
	)
	(segment
		(start 156.490162 -87.761064)
		(end 156.490162 -82.491834)
		(width 0.1143)
		(layer "In4.Cu")
		(net "CLK_100M_CPU1_RC_REFCLK0_DN")
	)
	(segment
		(start 140.22832 -73.639934)
		(end 140.931138 -73.639934)
		(width 0.0889)
		(layer "In4.Cu")
		(net "CLK_100M_CPU1_RC_REFCLK0_DN")
	)
	(segment
		(start 142.08125 -76.786994)
		(end 142.24635 -76.952094)
		(width 0.1143)
		(layer "In4.Cu")
		(net "CLK_100M_CPU1_RC_REFCLK0_DN")
	)
	(segment
		(start 148.01342 -87.910162)
		(end 154.393138 -87.910162)
		(width 0.1143)
		(layer "In4.Cu")
		(net "CLK_100M_CPU1_RC_REFCLK0_DN")
	)
	(segment
		(start 156.341064 -87.910162)
		(end 156.490162 -87.761064)
		(width 0.1143)
		(layer "In4.Cu")
		(net "CLK_100M_CPU1_RC_REFCLK0_DN")
	)
	(segment
		(start 135.935974 -73.144634)
		(end 135.971534 -73.144634)
		(width 0.0889)
		(layer "In4.Cu")
		(net "CLK_100M_CPU1_RC_REFCLK0_DN")
	)
	(segment
		(start 120.058688 -69.32295)
		(end 119.969788 -69.41185)
		(width 0.0889)
		(layer "In4.Cu")
		(net "CLK_100M_CPU1_RC_REFCLK0_DN")
	)
	(segment
		(start 120.190514 -71.436738)
		(end 120.101614 -71.525638)
		(width 0.0889)
		(layer "In4.Cu")
		(net "CLK_100M_CPU1_RC_REFCLK0_DN")
	)
	(segment
		(start 121.002044 -72.560688)
		(end 121.090944 -72.649588)
		(width 0.0889)
		(layer "In4.Cu")
		(net "CLK_100M_CPU1_RC_REFCLK0_DN")
	)
	(segment
		(start 154.393138 -87.389462)
		(end 148.238972 -87.389462)
		(width 0.1143)
		(layer "In4.Cu")
		(net "CLK_100M_CPU1_RC_REFCLK0_DN")
	)
	(segment
		(start 136.79424 -73.639934)
		(end 136.830308 -73.639934)
		(width 0.0889)
		(layer "In4.Cu")
		(net "CLK_100M_CPU1_RC_REFCLK0_DN")
	)
	(segment
		(start 159.82442 -80.720946)
		(end 157.704536 -82.84083)
		(width 0.1143)
		(layer "In4.Cu")
		(net "CLK_100M_CPU1_RC_REFCLK0_DN")
	)
	(segment
		(start 148.238972 -87.389462)
		(end 147.933664 -87.084154)
		(width 0.1143)
		(layer "In4.Cu")
		(net "CLK_100M_CPU1_RC_REFCLK0_DN")
	)
	(segment
		(start 120.101614 -71.525638)
		(end 120.101614 -72.373236)
		(width 0.0889)
		(layer "In4.Cu")
		(net "CLK_100M_CPU1_RC_REFCLK0_DN")
	)
	(segment
		(start 131.643374 -73.639934)
		(end 131.6736 -73.639934)
		(width 0.0889)
		(layer "In4.Cu")
		(net "CLK_100M_CPU1_RC_REFCLK0_DN")
	)
	(segment
		(start 119.969788 -68.676774)
		(end 119.969788 -68.96735)
		(width 0.0889)
		(layer "In4.Cu")
		(net "CLK_100M_CPU1_RC_REFCLK0_DN")
	)
	(segment
		(start 154.507438 -84.252562)
		(end 154.393138 -84.138262)
		(width 0.1143)
		(layer "In4.Cu")
		(net "CLK_100M_CPU1_RC_REFCLK0_DN")
	)
	(segment
		(start 142.24635 -76.278994)
		(end 142.08125 -76.444094)
		(width 0.1143)
		(layer "In4.Cu")
		(net "CLK_100M_CPU1_RC_REFCLK0_DN")
	)
	(segment
		(start 157.704536 -83.001612)
		(end 157.898846 -83.195922)
		(width 0.1143)
		(layer "In4.Cu")
		(net "CLK_100M_CPU1_RC_REFCLK0_DN")
	)
	(segment
		(start 154.507438 -86.170262)
		(end 154.507438 -85.878162)
		(width 0.1143)
		(layer "In4.Cu")
		(net "CLK_100M_CPU1_RC_REFCLK0_DN")
	)
	(segment
		(start 146.404584 -84.951062)
		(end 146.696684 -84.658962)
		(width 0.1143)
		(layer "In4.Cu")
		(net "CLK_100M_CPU1_RC_REFCLK0_DN")
	)
	(segment
		(start 119.969788 -69.971412)
		(end 120.101614 -70.103238)
		(width 0.0889)
		(layer "In4.Cu")
		(net "CLK_100M_CPU1_RC_REFCLK0_DN")
	)
	(segment
		(start 157.704536 -82.84083)
		(end 157.704536 -83.001612)
		(width 0.1143)
		(layer "In4.Cu")
		(net "CLK_100M_CPU1_RC_REFCLK0_DN")
	)
	(segment
		(start 137.653014 -73.144634)
		(end 137.688574 -73.144634)
		(width 0.0889)
		(layer "In4.Cu")
		(net "CLK_100M_CPU1_RC_REFCLK0_DN")
	)
	(segment
		(start 119.357902 -67.45351)
		(end 119.29999 -67.395598)
		(width 0.0889)
		(layer "In4.Cu")
		(net "CLK_100M_CPU1_RC_REFCLK0_DN")
	)
	(segment
		(start 159.038036 -79.94396)
		(end 159.508952 -79.94396)
		(width 0.1143)
		(layer "In4.Cu")
		(net "CLK_100M_CPU1_RC_REFCLK0_DN")
	)
	(segment
		(start 120.101614 -71.081138)
		(end 120.190514 -71.170038)
		(width 0.0889)
		(layer "In4.Cu")
		(net "CLK_100M_CPU1_RC_REFCLK0_DN")
	)
	(segment
		(start 155.612338 -87.795862)
		(end 155.726638 -87.910162)
		(width 0.1143)
		(layer "In4.Cu")
		(net "CLK_100M_CPU1_RC_REFCLK0_DN")
	)
	(segment
		(start 154.507438 -84.544662)
		(end 154.507438 -84.252562)
		(width 0.1143)
		(layer "In4.Cu")
		(net "CLK_100M_CPU1_RC_REFCLK0_DN")
	)
	(segment
		(start 143.475202 -80.232758)
		(end 143.475202 -83.371944)
		(width 0.1143)
		(layer "In4.Cu")
		(net "CLK_100M_CPU1_RC_REFCLK0_DN")
	)
	(segment
		(start 120.101614 -70.814438)
		(end 120.101614 -71.081138)
		(width 0.0889)
		(layer "In4.Cu")
		(net "CLK_100M_CPU1_RC_REFCLK0_DN")
	)
	(segment
		(start 154.393138 -86.284562)
		(end 154.507438 -86.170262)
		(width 0.1143)
		(layer "In4.Cu")
		(net "CLK_100M_CPU1_RC_REFCLK0_DN")
	)
	(segment
		(start 120.735344 -72.560688)
		(end 121.002044 -72.560688)
		(width 0.0889)
		(layer "In4.Cu")
		(net "CLK_100M_CPU1_RC_REFCLK0_DN")
	)
	(segment
		(start 147.933664 -87.084154)
		(end 147.933664 -86.569804)
		(width 0.1143)
		(layer "In4.Cu")
		(net "CLK_100M_CPU1_RC_REFCLK0_DN")
	)
	(segment
		(start 142.08125 -75.770994)
		(end 142.24635 -75.936094)
		(width 0.1143)
		(layer "In4.Cu")
		(net "CLK_100M_CPU1_RC_REFCLK0_DN")
	)
	(segment
		(start 142.03045 -75.355196)
		(end 142.08125 -75.405996)
		(width 0.0889)
		(layer "In4.Cu")
		(net "CLK_100M_CPU1_RC_REFCLK0_DN")
	)
	(segment
		(start 124.775214 -73.639934)
		(end 124.811282 -73.639934)
		(width 0.0889)
		(layer "In4.Cu")
		(net "CLK_100M_CPU1_RC_REFCLK0_DN")
	)
	(segment
		(start 154.393138 -85.763862)
		(end 146.703288 -85.763862)
		(width 0.1143)
		(layer "In4.Cu")
		(net "CLK_100M_CPU1_RC_REFCLK0_DN")
	)
	(segment
		(start 130.785108 -73.144634)
		(end 130.820668 -73.144634)
		(width 0.0889)
		(layer "In4.Cu")
		(net "CLK_100M_CPU1_RC_REFCLK0_DN")
	)
	(segment
		(start 142.24635 -75.936094)
		(end 142.24635 -76.278994)
		(width 0.1143)
		(layer "In4.Cu")
		(net "CLK_100M_CPU1_RC_REFCLK0_DN")
	)
	(segment
		(start 139.370054 -73.144634)
		(end 139.405614 -73.144634)
		(width 0.0889)
		(layer "In4.Cu")
		(net "CLK_100M_CPU1_RC_REFCLK0_DN")
	)
	(segment
		(start 147.933664 -86.569804)
		(end 148.218906 -86.284562)
		(width 0.1143)
		(layer "In4.Cu")
		(net "CLK_100M_CPU1_RC_REFCLK0_DN")
	)
	(segment
		(start 129.926334 -73.639934)
		(end 129.962402 -73.639934)
		(width 0.0889)
		(layer "In4.Cu")
		(net "CLK_100M_CPU1_RC_REFCLK0_DN")
	)
	(segment
		(start 141.280388 -73.989184)
		(end 141.406118 -73.989184)
		(width 0.0889)
		(layer "In4.Cu")
		(net "CLK_100M_CPU1_RC_REFCLK0_DN")
	)
	(segment
		(start 129.068068 -73.144634)
		(end 129.103628 -73.144634)
		(width 0.0889)
		(layer "In4.Cu")
		(net "CLK_100M_CPU1_RC_REFCLK0_DN")
	)
	(segment
		(start 155.326842 -83.033362)
		(end 155.612338 -83.318858)
		(width 0.1143)
		(layer "In4.Cu")
		(net "CLK_100M_CPU1_RC_REFCLK0_DN")
	)
	(segment
		(start 120.190514 -70.725538)
		(end 120.101614 -70.814438)
		(width 0.0889)
		(layer "In4.Cu")
		(net "CLK_100M_CPU1_RC_REFCLK0_DN")
	)
	(segment
		(start 121.090944 -72.649588)
		(end 121.377456 -72.649588)
		(width 0.0889)
		(layer "In4.Cu")
		(net "CLK_100M_CPU1_RC_REFCLK0_DN")
	)
	(segment
		(start 144.711166 -83.315302)
		(end 144.993106 -83.033362)
		(width 0.1143)
		(layer "In4.Cu")
		(net "CLK_100M_CPU1_RC_REFCLK0_DN")
	)
	(segment
		(start 140.931138 -73.639934)
		(end 141.280388 -73.989184)
		(width 0.0889)
		(layer "In4.Cu")
		(net "CLK_100M_CPU1_RC_REFCLK0_DN")
	)
	(segment
		(start 142.08125 -78.476094)
		(end 142.08125 -78.838806)
		(width 0.1143)
		(layer "In4.Cu")
		(net "CLK_100M_CPU1_RC_REFCLK0_DN")
	)
	(segment
		(start 120.190514 -70.458838)
		(end 120.190514 -70.725538)
		(width 0.0889)
		(layer "In4.Cu")
		(net "CLK_100M_CPU1_RC_REFCLK0_DN")
	)
	(segment
		(start 119.969788 -69.41185)
		(end 119.969788 -69.971412)
		(width 0.0889)
		(layer "In4.Cu")
		(net "CLK_100M_CPU1_RC_REFCLK0_DN")
	)
	(segment
		(start 155.612338 -83.318858)
		(end 155.612338 -87.795862)
		(width 0.1143)
		(layer "In4.Cu")
		(net "CLK_100M_CPU1_RC_REFCLK0_DN")
	)
	(segment
		(start 119.342916 -68.191634)
		(end 119.375682 -68.191634)
		(width 0.0889)
		(layer "In4.Cu")
		(net "CLK_100M_CPU1_RC_REFCLK0_DN")
	)
	(segment
		(start 154.393138 -84.658962)
		(end 154.507438 -84.544662)
		(width 0.1143)
		(layer "In4.Cu")
		(net "CLK_100M_CPU1_RC_REFCLK0_DN")
	)
	(segment
		(start 141.594586 -74.303382)
		(end 142.03045 -74.739246)
		(width 0.0889)
		(layer "In4.Cu")
		(net "CLK_100M_CPU1_RC_REFCLK0_DN")
	)
	(segment
		(start 142.24635 -76.952094)
		(end 142.24635 -77.294994)
		(width 0.1143)
		(layer "In4.Cu")
		(net "CLK_100M_CPU1_RC_REFCLK0_DN")
	)
	(segment
		(start 155.726638 -87.910162)
		(end 156.341064 -87.910162)
		(width 0.1143)
		(layer "In4.Cu")
		(net "CLK_100M_CPU1_RC_REFCLK0_DN")
	)
	(segment
		(start 133.36016 -73.639934)
		(end 133.396228 -73.639934)
		(width 0.0889)
		(layer "In4.Cu")
		(net "CLK_100M_CPU1_RC_REFCLK0_DN")
	)
	(arc
		(start 119.29999 -67.395598)
		(mid 118.958067 -67.813139)
		(end 119.342916 -68.191634)
		(width 0.0889)
		(layer "In4.Cu")
		(net "CLK_100M_CPU1_RC_REFCLK0_DN")
	)
	(arc
		(start 128.21539 -73.640188)
		(mid 128.227328 -73.640366)
		(end 128.239266 -73.640188)
		(width 0.0889)
		(layer "In4.Cu")
		(net "CLK_100M_CPU1_RC_REFCLK0_DN")
	)
	(arc
		(start 122.235468 -73.144634)
		(mid 122.520892 -73.228101)
		(end 122.729498 -73.440036)
		(width 0.0889)
		(layer "In4.Cu")
		(net "CLK_100M_CPU1_RC_REFCLK0_DN")
	)
	(arc
		(start 127.386588 -73.144634)
		(mid 127.672012 -73.228101)
		(end 127.880618 -73.440036)
		(width 0.0889)
		(layer "In4.Cu")
		(net "CLK_100M_CPU1_RC_REFCLK0_DN")
	)
	(arc
		(start 126.49835 -73.640188)
		(mid 126.510288 -73.640366)
		(end 126.522226 -73.640188)
		(width 0.0889)
		(layer "In4.Cu")
		(net "CLK_100M_CPU1_RC_REFCLK0_DN")
	)
	(arc
		(start 123.422918 -73.440036)
		(mid 123.934728 -73.144369)
		(end 124.446538 -73.440036)
		(width 0.0889)
		(layer "In4.Cu")
		(net "CLK_100M_CPU1_RC_REFCLK0_DN")
	)
	(arc
		(start 139.405614 -73.144634)
		(mid 139.691038 -73.228101)
		(end 139.899644 -73.440036)
		(width 0.0889)
		(layer "In4.Cu")
		(net "CLK_100M_CPU1_RC_REFCLK0_DN")
	)
	(arc
		(start 125.139958 -73.440036)
		(mid 125.348566 -73.228104)
		(end 125.633988 -73.144634)
		(width 0.0889)
		(layer "In4.Cu")
		(net "CLK_100M_CPU1_RC_REFCLK0_DN")
	)
	(arc
		(start 133.724904 -73.440036)
		(mid 133.933512 -73.228104)
		(end 134.218934 -73.144634)
		(width 0.0889)
		(layer "In4.Cu")
		(net "CLK_100M_CPU1_RC_REFCLK0_DN")
	)
	(arc
		(start 127.880618 -73.440036)
		(mid 128.021974 -73.583645)
		(end 128.21539 -73.640188)
		(width 0.0889)
		(layer "In4.Cu")
		(net "CLK_100M_CPU1_RC_REFCLK0_DN")
	)
	(arc
		(start 136.830308 -73.639934)
		(mid 137.020237 -73.582064)
		(end 137.158984 -73.440036)
		(width 0.0889)
		(layer "In4.Cu")
		(net "CLK_100M_CPU1_RC_REFCLK0_DN")
	)
	(arc
		(start 129.597658 -73.440036)
		(mid 129.736402 -73.582069)
		(end 129.926334 -73.639934)
		(width 0.0889)
		(layer "In4.Cu")
		(net "CLK_100M_CPU1_RC_REFCLK0_DN")
	)
	(arc
		(start 137.158984 -73.440036)
		(mid 137.367592 -73.228104)
		(end 137.653014 -73.144634)
		(width 0.0889)
		(layer "In4.Cu")
		(net "CLK_100M_CPU1_RC_REFCLK0_DN")
	)
	(arc
		(start 122.729498 -73.440036)
		(mid 122.868242 -73.582069)
		(end 123.058174 -73.639934)
		(width 0.0889)
		(layer "In4.Cu")
		(net "CLK_100M_CPU1_RC_REFCLK0_DN")
	)
	(arc
		(start 131.314698 -73.440036)
		(mid 131.453442 -73.582069)
		(end 131.643374 -73.639934)
		(width 0.0889)
		(layer "In4.Cu")
		(net "CLK_100M_CPU1_RC_REFCLK0_DN")
	)
	(arc
		(start 135.971534 -73.144634)
		(mid 136.256958 -73.228101)
		(end 136.465564 -73.440036)
		(width 0.0889)
		(layer "In4.Cu")
		(net "CLK_100M_CPU1_RC_REFCLK0_DN")
	)
	(arc
		(start 136.465564 -73.440036)
		(mid 136.604308 -73.582069)
		(end 136.79424 -73.639934)
		(width 0.0889)
		(layer "In4.Cu")
		(net "CLK_100M_CPU1_RC_REFCLK0_DN")
	)
	(arc
		(start 126.522226 -73.640188)
		(mid 126.715652 -73.583661)
		(end 126.856998 -73.440036)
		(width 0.0889)
		(layer "In4.Cu")
		(net "CLK_100M_CPU1_RC_REFCLK0_DN")
	)
	(arc
		(start 124.811282 -73.639934)
		(mid 125.001211 -73.582064)
		(end 125.139958 -73.440036)
		(width 0.0889)
		(layer "In4.Cu")
		(net "CLK_100M_CPU1_RC_REFCLK0_DN")
	)
	(arc
		(start 129.103628 -73.144634)
		(mid 129.389052 -73.228101)
		(end 129.597658 -73.440036)
		(width 0.0889)
		(layer "In4.Cu")
		(net "CLK_100M_CPU1_RC_REFCLK0_DN")
	)
	(arc
		(start 134.748524 -73.440036)
		(mid 134.887268 -73.582069)
		(end 135.0772 -73.639934)
		(width 0.0889)
		(layer "In4.Cu")
		(net "CLK_100M_CPU1_RC_REFCLK0_DN")
	)
	(arc
		(start 121.870978 -72.944736)
		(mid 122.009971 -73.086816)
		(end 122.200162 -73.144634)
		(width 0.0889)
		(layer "In4.Cu")
		(net "CLK_100M_CPU1_RC_REFCLK0_DN")
	)
	(arc
		(start 123.094242 -73.639934)
		(mid 123.284171 -73.582064)
		(end 123.422918 -73.440036)
		(width 0.0889)
		(layer "In4.Cu")
		(net "CLK_100M_CPU1_RC_REFCLK0_DN")
	)
	(arc
		(start 134.254494 -73.144634)
		(mid 134.539918 -73.228101)
		(end 134.748524 -73.440036)
		(width 0.0889)
		(layer "In4.Cu")
		(net "CLK_100M_CPU1_RC_REFCLK0_DN")
	)
	(arc
		(start 126.856998 -73.440036)
		(mid 127.065606 -73.228104)
		(end 127.351028 -73.144634)
		(width 0.0889)
		(layer "In4.Cu")
		(net "CLK_100M_CPU1_RC_REFCLK0_DN")
	)
	(arc
		(start 125.669548 -73.144634)
		(mid 125.954972 -73.228101)
		(end 126.163578 -73.440036)
		(width 0.0889)
		(layer "In4.Cu")
		(net "CLK_100M_CPU1_RC_REFCLK0_DN")
	)
	(arc
		(start 138.182604 -73.440036)
		(mid 138.321348 -73.582069)
		(end 138.51128 -73.639934)
		(width 0.0889)
		(layer "In4.Cu")
		(net "CLK_100M_CPU1_RC_REFCLK0_DN")
	)
	(arc
		(start 124.446538 -73.440036)
		(mid 124.585282 -73.582069)
		(end 124.775214 -73.639934)
		(width 0.0889)
		(layer "In4.Cu")
		(net "CLK_100M_CPU1_RC_REFCLK0_DN")
	)
	(arc
		(start 119.375682 -68.191634)
		(mid 119.659103 -68.273909)
		(end 119.867426 -68.482972)
		(width 0.0889)
		(layer "In4.Cu")
		(net "CLK_100M_CPU1_RC_REFCLK0_DN")
	)
	(arc
		(start 121.377456 -72.649588)
		(mid 121.662503 -72.733116)
		(end 121.870978 -72.944736)
		(width 0.0889)
		(layer "In4.Cu")
		(net "CLK_100M_CPU1_RC_REFCLK0_DN")
	)
	(arc
		(start 138.547348 -73.639934)
		(mid 138.737277 -73.582064)
		(end 138.876024 -73.440036)
		(width 0.0889)
		(layer "In4.Cu")
		(net "CLK_100M_CPU1_RC_REFCLK0_DN")
	)
	(arc
		(start 133.396228 -73.639934)
		(mid 133.586157 -73.582064)
		(end 133.724904 -73.440036)
		(width 0.0889)
		(layer "In4.Cu")
		(net "CLK_100M_CPU1_RC_REFCLK0_DN")
	)
	(arc
		(start 128.239266 -73.640188)
		(mid 128.432692 -73.583661)
		(end 128.574038 -73.440036)
		(width 0.0889)
		(layer "In4.Cu")
		(net "CLK_100M_CPU1_RC_REFCLK0_DN")
	)
	(arc
		(start 139.899644 -73.440036)
		(mid 140.038388 -73.582069)
		(end 140.22832 -73.639934)
		(width 0.0889)
		(layer "In4.Cu")
		(net "CLK_100M_CPU1_RC_REFCLK0_DN")
	)
	(arc
		(start 130.291078 -73.440036)
		(mid 130.499686 -73.228104)
		(end 130.785108 -73.144634)
		(width 0.0889)
		(layer "In4.Cu")
		(net "CLK_100M_CPU1_RC_REFCLK0_DN")
	)
	(arc
		(start 133.031484 -73.440036)
		(mid 133.170228 -73.582069)
		(end 133.36016 -73.639934)
		(width 0.0889)
		(layer "In4.Cu")
		(net "CLK_100M_CPU1_RC_REFCLK0_DN")
	)
	(arc
		(start 130.820668 -73.144634)
		(mid 131.106092 -73.228101)
		(end 131.314698 -73.440036)
		(width 0.0889)
		(layer "In4.Cu")
		(net "CLK_100M_CPU1_RC_REFCLK0_DN")
	)
	(arc
		(start 132.007864 -73.440036)
		(mid 132.216472 -73.228104)
		(end 132.501894 -73.144634)
		(width 0.0889)
		(layer "In4.Cu")
		(net "CLK_100M_CPU1_RC_REFCLK0_DN")
	)
	(arc
		(start 131.6736 -73.639934)
		(mid 131.866703 -73.583415)
		(end 132.007864 -73.440036)
		(width 0.0889)
		(layer "In4.Cu")
		(net "CLK_100M_CPU1_RC_REFCLK0_DN")
	)
	(arc
		(start 132.537454 -73.144634)
		(mid 132.822878 -73.228101)
		(end 133.031484 -73.440036)
		(width 0.0889)
		(layer "In4.Cu")
		(net "CLK_100M_CPU1_RC_REFCLK0_DN")
	)
	(arc
		(start 128.574038 -73.440036)
		(mid 128.782646 -73.228104)
		(end 129.068068 -73.144634)
		(width 0.0889)
		(layer "In4.Cu")
		(net "CLK_100M_CPU1_RC_REFCLK0_DN")
	)
	(arc
		(start 129.962402 -73.639934)
		(mid 130.152331 -73.582064)
		(end 130.291078 -73.440036)
		(width 0.0889)
		(layer "In4.Cu")
		(net "CLK_100M_CPU1_RC_REFCLK0_DN")
	)
	(arc
		(start 135.113268 -73.639934)
		(mid 135.303197 -73.582064)
		(end 135.441944 -73.440036)
		(width 0.0889)
		(layer "In4.Cu")
		(net "CLK_100M_CPU1_RC_REFCLK0_DN")
	)
	(arc
		(start 138.876024 -73.440036)
		(mid 139.084632 -73.228104)
		(end 139.370054 -73.144634)
		(width 0.0889)
		(layer "In4.Cu")
		(net "CLK_100M_CPU1_RC_REFCLK0_DN")
	)
	(arc
		(start 137.688574 -73.144634)
		(mid 137.973998 -73.228101)
		(end 138.182604 -73.440036)
		(width 0.0889)
		(layer "In4.Cu")
		(net "CLK_100M_CPU1_RC_REFCLK0_DN")
	)
	(arc
		(start 135.441944 -73.440036)
		(mid 135.650552 -73.228104)
		(end 135.935974 -73.144634)
		(width 0.0889)
		(layer "In4.Cu")
		(net "CLK_100M_CPU1_RC_REFCLK0_DN")
	)
	(arc
		(start 126.163578 -73.440036)
		(mid 126.304934 -73.583645)
		(end 126.49835 -73.640188)
		(width 0.0889)
		(layer "In4.Cu")
		(net "CLK_100M_CPU1_RC_REFCLK0_DN")
	)
	(segment
		(start 123.076208 -80.174338)
		(end 122.504708 -80.174338)
		(width 0.127)
		(layer "F.Cu")
		(net "CLK_100M_CPU1_PE_REFCLK_DP")
	)
	(segment
		(start 161.834322 -82.681572)
		(end 161.948622 -82.567272)
		(width 0.127)
		(layer "F.Cu")
		(net "CLK_100M_CPU1_PE_REFCLK_DP")
	)
	(segment
		(start 162.579304 -82.567272)
		(end 162.687 -82.674968)
		(width 0.127)
		(layer "F.Cu")
		(net "CLK_100M_CPU1_PE_REFCLK_DP")
	)
	(segment
		(start 161.948622 -82.567272)
		(end 162.579304 -82.567272)
		(width 0.127)
		(layer "F.Cu")
		(net "CLK_100M_CPU1_PE_REFCLK_DP")
	)
	(segment
		(start 162.687 -82.674968)
		(end 162.687 -83.058)
		(width 0.127)
		(layer "F.Cu")
		(net "CLK_100M_CPU1_PE_REFCLK_DP")
	)
	(segment
		(start 161.834322 -83.058)
		(end 161.834322 -82.681572)
		(width 0.127)
		(layer "F.Cu")
		(net "CLK_100M_CPU1_PE_REFCLK_DP")
	)
	(via
		(at 161.834322 -83.058)
		(size 0.508)
		(drill 0.254)
		(layers "F.Cu" "B.Cu")
		(net "CLK_100M_CPU1_PE_REFCLK_DP")
	)
	(via
		(at 123.076208 -80.174338)
		(size 0.508)
		(drill 0.254)
		(layers "F.Cu" "B.Cu")
		(net "CLK_100M_CPU1_PE_REFCLK_DP")
	)
	(segment
		(start 161.834322 -83.058)
		(end 161.834322 -82.697066)
		(width 0.127)
		(layer "B.Cu")
		(net "CLK_100M_CPU1_PE_REFCLK_DP")
	)
	(segment
		(start 161.834322 -82.697066)
		(end 161.948622 -82.582766)
		(width 0.127)
		(layer "B.Cu")
		(net "CLK_100M_CPU1_PE_REFCLK_DP")
	)
	(segment
		(start 161.948622 -82.582766)
		(end 162.5727 -82.582766)
		(width 0.127)
		(layer "B.Cu")
		(net "CLK_100M_CPU1_PE_REFCLK_DP")
	)
	(segment
		(start 162.5727 -82.582766)
		(end 162.687 -82.697066)
		(width 0.127)
		(layer "B.Cu")
		(net "CLK_100M_CPU1_PE_REFCLK_DP")
	)
	(segment
		(start 162.687 -82.697066)
		(end 162.687 -83.058)
		(width 0.127)
		(layer "B.Cu")
		(net "CLK_100M_CPU1_PE_REFCLK_DP")
	)
	(segment
		(start 157.412436 -93.536262)
		(end 157.111192 -93.837506)
		(width 0.1143)
		(layer "In4.Cu")
		(net "CLK_100M_CPU1_PE_REFCLK_DP")
	)
	(segment
		(start 140.264134 -85.717888)
		(end 140.228574 -85.717888)
		(width 0.0889)
		(layer "In4.Cu")
		(net "CLK_100M_CPU1_PE_REFCLK_DP")
	)
	(segment
		(start 157.219396 -94.358206)
		(end 157.504638 -94.643448)
		(width 0.1143)
		(layer "In4.Cu")
		(net "CLK_100M_CPU1_PE_REFCLK_DP")
	)
	(segment
		(start 161.720022 -82.56905)
		(end 160.281112 -82.56905)
		(width 0.1143)
		(layer "In4.Cu")
		(net "CLK_100M_CPU1_PE_REFCLK_DP")
	)
	(segment
		(start 149.820122 -94.243906)
		(end 149.934422 -94.358206)
		(width 0.1143)
		(layer "In4.Cu")
		(net "CLK_100M_CPU1_PE_REFCLK_DP")
	)
	(segment
		(start 127.379984 -82.250534)
		(end 127.347218 -82.250534)
		(width 0.0889)
		(layer "In4.Cu")
		(net "CLK_100M_CPU1_PE_REFCLK_DP")
	)
	(segment
		(start 147.21586 -90.489532)
		(end 147.21586 -88.642952)
		(width 0.1143)
		(layer "In4.Cu")
		(net "CLK_100M_CPU1_PE_REFCLK_DP")
	)
	(segment
		(start 157.219396 -92.211906)
		(end 149.77491 -92.211906)
		(width 0.1143)
		(layer "In4.Cu")
		(net "CLK_100M_CPU1_PE_REFCLK_DP")
	)
	(segment
		(start 157.634686 -85.215476)
		(end 157.634686 -88.54821)
		(width 0.1143)
		(layer "In4.Cu")
		(net "CLK_100M_CPU1_PE_REFCLK_DP")
	)
	(segment
		(start 149.396704 -90.707464)
		(end 149.396704 -90.992706)
		(width 0.1143)
		(layer "In4.Cu")
		(net "CLK_100M_CPU1_PE_REFCLK_DP")
	)
	(segment
		(start 123.945904 -80.269334)
		(end 123.913138 -80.269334)
		(width 0.0889)
		(layer "In4.Cu")
		(net "CLK_100M_CPU1_PE_REFCLK_DP")
	)
	(segment
		(start 157.504638 -95.143828)
		(end 157.18536 -95.463106)
		(width 0.1143)
		(layer "In4.Cu")
		(net "CLK_100M_CPU1_PE_REFCLK_DP")
	)
	(segment
		(start 123.076208 -79.836264)
		(end 123.076208 -80.174338)
		(width 0.0889)
		(layer "In4.Cu")
		(net "CLK_100M_CPU1_PE_REFCLK_DP")
	)
	(segment
		(start 157.504638 -91.412568)
		(end 157.504638 -91.926664)
		(width 0.1143)
		(layer "In4.Cu")
		(net "CLK_100M_CPU1_PE_REFCLK_DP")
	)
	(segment
		(start 148.444204 -88.960706)
		(end 148.30298 -89.10193)
		(width 0.1143)
		(layer "In4.Cu")
		(net "CLK_100M_CPU1_PE_REFCLK_DP")
	)
	(segment
		(start 123.13412 -79.778352)
		(end 123.076208 -79.836264)
		(width 0.0889)
		(layer "In4.Cu")
		(net "CLK_100M_CPU1_PE_REFCLK_DP")
	)
	(segment
		(start 148.30298 -89.10193)
		(end 148.30298 -89.33307)
		(width 0.1143)
		(layer "In4.Cu")
		(net "CLK_100M_CPU1_PE_REFCLK_DP")
	)
	(segment
		(start 132.53085 -85.222334)
		(end 132.494782 -85.222334)
		(width 0.0889)
		(layer "In4.Cu")
		(net "CLK_100M_CPU1_PE_REFCLK_DP")
	)
	(segment
		(start 157.412436 -93.017848)
		(end 157.412436 -93.536262)
		(width 0.1143)
		(layer "In4.Cu")
		(net "CLK_100M_CPU1_PE_REFCLK_DP")
	)
	(segment
		(start 143.396716 -85.273134)
		(end 143.374618 -85.273134)
		(width 0.0889)
		(layer "In4.Cu")
		(net "CLK_100M_CPU1_PE_REFCLK_DP")
	)
	(segment
		(start 130.814064 -84.231734)
		(end 130.781298 -84.231734)
		(width 0.0889)
		(layer "In4.Cu")
		(net "CLK_100M_CPU1_PE_REFCLK_DP")
	)
	(segment
		(start 160.281112 -82.56905)
		(end 157.634686 -85.215476)
		(width 0.1143)
		(layer "In4.Cu")
		(net "CLK_100M_CPU1_PE_REFCLK_DP")
	)
	(segment
		(start 149.66061 -92.591128)
		(end 149.802088 -92.732606)
		(width 0.1143)
		(layer "In4.Cu")
		(net "CLK_100M_CPU1_PE_REFCLK_DP")
	)
	(segment
		(start 143.846042 -85.273134)
		(end 143.396716 -85.273134)
		(width 0.1143)
		(layer "In4.Cu")
		(net "CLK_100M_CPU1_PE_REFCLK_DP")
	)
	(segment
		(start 157.22219 -88.960706)
		(end 148.444204 -88.960706)
		(width 0.1143)
		(layer "In4.Cu")
		(net "CLK_100M_CPU1_PE_REFCLK_DP")
	)
	(segment
		(start 149.934422 -94.358206)
		(end 157.219396 -94.358206)
		(width 0.1143)
		(layer "In4.Cu")
		(net "CLK_100M_CPU1_PE_REFCLK_DP")
	)
	(segment
		(start 143.323818 -85.222334)
		(end 142.731744 -85.222334)
		(width 0.0889)
		(layer "In4.Cu")
		(net "CLK_100M_CPU1_PE_REFCLK_DP")
	)
	(segment
		(start 148.451316 -89.481406)
		(end 157.18663 -89.481406)
		(width 0.1143)
		(layer "In4.Cu")
		(net "CLK_100M_CPU1_PE_REFCLK_DP")
	)
	(segment
		(start 129.097024 -83.241134)
		(end 129.064258 -83.241134)
		(width 0.0889)
		(layer "In4.Cu")
		(net "CLK_100M_CPU1_PE_REFCLK_DP")
	)
	(segment
		(start 136.830054 -85.717888)
		(end 136.794494 -85.717888)
		(width 0.0889)
		(layer "In4.Cu")
		(net "CLK_100M_CPU1_PE_REFCLK_DP")
	)
	(segment
		(start 149.934422 -93.837506)
		(end 149.820122 -93.951806)
		(width 0.1143)
		(layer "In4.Cu")
		(net "CLK_100M_CPU1_PE_REFCLK_DP")
	)
	(segment
		(start 147.21586 -88.642952)
		(end 143.846042 -85.273134)
		(width 0.1143)
		(layer "In4.Cu")
		(net "CLK_100M_CPU1_PE_REFCLK_DP")
	)
	(segment
		(start 157.203648 -90.586306)
		(end 149.517862 -90.586306)
		(width 0.1143)
		(layer "In4.Cu")
		(net "CLK_100M_CPU1_PE_REFCLK_DP")
	)
	(segment
		(start 161.834322 -82.68335)
		(end 161.720022 -82.56905)
		(width 0.1143)
		(layer "In4.Cu")
		(net "CLK_100M_CPU1_PE_REFCLK_DP")
	)
	(segment
		(start 157.18663 -89.481406)
		(end 157.492192 -89.786968)
		(width 0.1143)
		(layer "In4.Cu")
		(net "CLK_100M_CPU1_PE_REFCLK_DP")
	)
	(segment
		(start 157.18536 -95.463106)
		(end 149.38121 -95.463106)
		(width 0.1143)
		(layer "In4.Cu")
		(net "CLK_100M_CPU1_PE_REFCLK_DP")
	)
	(segment
		(start 149.820122 -93.951806)
		(end 149.820122 -94.243906)
		(width 0.1143)
		(layer "In4.Cu")
		(net "CLK_100M_CPU1_PE_REFCLK_DP")
	)
	(segment
		(start 149.66061 -92.326206)
		(end 149.66061 -92.591128)
		(width 0.1143)
		(layer "In4.Cu")
		(net "CLK_100M_CPU1_PE_REFCLK_DP")
	)
	(segment
		(start 133.395974 -85.717888)
		(end 133.360414 -85.717888)
		(width 0.0889)
		(layer "In4.Cu")
		(net "CLK_100M_CPU1_PE_REFCLK_DP")
	)
	(segment
		(start 149.517862 -90.586306)
		(end 149.396704 -90.707464)
		(width 0.1143)
		(layer "In4.Cu")
		(net "CLK_100M_CPU1_PE_REFCLK_DP")
	)
	(segment
		(start 126.528322 -81.755488)
		(end 126.492508 -81.755488)
		(width 0.0889)
		(layer "In4.Cu")
		(net "CLK_100M_CPU1_PE_REFCLK_DP")
	)
	(segment
		(start 142.166086 -85.717888)
		(end 141.945614 -85.717888)
		(width 0.0889)
		(layer "In4.Cu")
		(net "CLK_100M_CPU1_PE_REFCLK_DP")
	)
	(segment
		(start 149.38121 -95.463106)
		(end 148.514308 -94.596204)
		(width 0.1143)
		(layer "In4.Cu")
		(net "CLK_100M_CPU1_PE_REFCLK_DP")
	)
	(segment
		(start 157.127194 -92.732606)
		(end 157.412436 -93.017848)
		(width 0.1143)
		(layer "In4.Cu")
		(net "CLK_100M_CPU1_PE_REFCLK_DP")
	)
	(segment
		(start 132.007864 -84.92744)
		(end 132.004562 -84.921598)
		(width 0.0889)
		(layer "In4.Cu")
		(net "CLK_100M_CPU1_PE_REFCLK_DP")
	)
	(segment
		(start 148.514308 -91.78798)
		(end 147.21586 -90.489532)
		(width 0.1143)
		(layer "In4.Cu")
		(net "CLK_100M_CPU1_PE_REFCLK_DP")
	)
	(segment
		(start 149.396704 -90.992706)
		(end 149.511004 -91.107006)
		(width 0.1143)
		(layer "In4.Cu")
		(net "CLK_100M_CPU1_PE_REFCLK_DP")
	)
	(segment
		(start 157.199076 -91.107006)
		(end 157.504638 -91.412568)
		(width 0.1143)
		(layer "In4.Cu")
		(net "CLK_100M_CPU1_PE_REFCLK_DP")
	)
	(segment
		(start 143.374618 -85.273134)
		(end 143.323818 -85.222334)
		(width 0.0889)
		(layer "In4.Cu")
		(net "CLK_100M_CPU1_PE_REFCLK_DP")
	)
	(segment
		(start 124.808234 -80.764888)
		(end 124.775468 -80.764888)
		(width 0.0889)
		(layer "In4.Cu")
		(net "CLK_100M_CPU1_PE_REFCLK_DP")
	)
	(segment
		(start 161.834322 -83.058)
		(end 161.834322 -82.68335)
		(width 0.1143)
		(layer "In4.Cu")
		(net "CLK_100M_CPU1_PE_REFCLK_DP")
	)
	(segment
		(start 157.634686 -88.54821)
		(end 157.22219 -88.960706)
		(width 0.1143)
		(layer "In4.Cu")
		(net "CLK_100M_CPU1_PE_REFCLK_DP")
	)
	(segment
		(start 157.492192 -90.297762)
		(end 157.203648 -90.586306)
		(width 0.1143)
		(layer "In4.Cu")
		(net "CLK_100M_CPU1_PE_REFCLK_DP")
	)
	(segment
		(start 149.77491 -92.211906)
		(end 149.66061 -92.326206)
		(width 0.1143)
		(layer "In4.Cu")
		(net "CLK_100M_CPU1_PE_REFCLK_DP")
	)
	(segment
		(start 157.111192 -93.837506)
		(end 149.934422 -93.837506)
		(width 0.1143)
		(layer "In4.Cu")
		(net "CLK_100M_CPU1_PE_REFCLK_DP")
	)
	(segment
		(start 149.802088 -92.732606)
		(end 157.127194 -92.732606)
		(width 0.1143)
		(layer "In4.Cu")
		(net "CLK_100M_CPU1_PE_REFCLK_DP")
	)
	(segment
		(start 128.242314 -82.746088)
		(end 128.214374 -82.746088)
		(width 0.0889)
		(layer "In4.Cu")
		(net "CLK_100M_CPU1_PE_REFCLK_DP")
	)
	(segment
		(start 138.547094 -85.717888)
		(end 138.511534 -85.717888)
		(width 0.0889)
		(layer "In4.Cu")
		(net "CLK_100M_CPU1_PE_REFCLK_DP")
	)
	(segment
		(start 157.492192 -89.786968)
		(end 157.492192 -90.297762)
		(width 0.1143)
		(layer "In4.Cu")
		(net "CLK_100M_CPU1_PE_REFCLK_DP")
	)
	(segment
		(start 157.504638 -94.643448)
		(end 157.504638 -95.143828)
		(width 0.1143)
		(layer "In4.Cu")
		(net "CLK_100M_CPU1_PE_REFCLK_DP")
	)
	(segment
		(start 131.661408 -84.727288)
		(end 131.643628 -84.727288)
		(width 0.0889)
		(layer "In4.Cu")
		(net "CLK_100M_CPU1_PE_REFCLK_DP")
	)
	(segment
		(start 157.504638 -91.926664)
		(end 157.219396 -92.211906)
		(width 0.1143)
		(layer "In4.Cu")
		(net "CLK_100M_CPU1_PE_REFCLK_DP")
	)
	(segment
		(start 129.959354 -83.736688)
		(end 129.926588 -83.736688)
		(width 0.0889)
		(layer "In4.Cu")
		(net "CLK_100M_CPU1_PE_REFCLK_DP")
	)
	(segment
		(start 148.514308 -94.596204)
		(end 148.514308 -91.78798)
		(width 0.1143)
		(layer "In4.Cu")
		(net "CLK_100M_CPU1_PE_REFCLK_DP")
	)
	(segment
		(start 125.662944 -81.259934)
		(end 125.630178 -81.259934)
		(width 0.0889)
		(layer "In4.Cu")
		(net "CLK_100M_CPU1_PE_REFCLK_DP")
	)
	(segment
		(start 149.511004 -91.107006)
		(end 157.199076 -91.107006)
		(width 0.1143)
		(layer "In4.Cu")
		(net "CLK_100M_CPU1_PE_REFCLK_DP")
	)
	(segment
		(start 148.30298 -89.33307)
		(end 148.451316 -89.481406)
		(width 0.1143)
		(layer "In4.Cu")
		(net "CLK_100M_CPU1_PE_REFCLK_DP")
	)
	(arc
		(start 124.775468 -80.764888)
		(mid 124.490044 -80.681421)
		(end 124.281438 -80.469486)
		(width 0.0889)
		(layer "In4.Cu")
		(net "CLK_100M_CPU1_PE_REFCLK_DP")
	)
	(arc
		(start 135.607044 -85.422486)
		(mid 135.095234 -85.718153)
		(end 134.583424 -85.422486)
		(width 0.0889)
		(layer "In4.Cu")
		(net "CLK_100M_CPU1_PE_REFCLK_DP")
	)
	(arc
		(start 123.422918 -79.974186)
		(mid 123.300973 -79.843154)
		(end 123.13412 -79.778352)
		(width 0.0889)
		(layer "In4.Cu")
		(net "CLK_100M_CPU1_PE_REFCLK_DP")
	)
	(arc
		(start 140.758164 -85.422486)
		(mid 140.549556 -85.634418)
		(end 140.264134 -85.717888)
		(width 0.0889)
		(layer "In4.Cu")
		(net "CLK_100M_CPU1_PE_REFCLK_DP")
	)
	(arc
		(start 137.682732 -85.222334)
		(mid 137.670794 -85.222156)
		(end 137.658856 -85.222334)
		(width 0.0889)
		(layer "In4.Cu")
		(net "CLK_100M_CPU1_PE_REFCLK_DP")
	)
	(arc
		(start 136.300464 -85.422486)
		(mid 136.159108 -85.278877)
		(end 135.965692 -85.222334)
		(width 0.0889)
		(layer "In4.Cu")
		(net "CLK_100M_CPU1_PE_REFCLK_DP")
	)
	(arc
		(start 132.004562 -84.921598)
		(mid 131.858596 -84.779199)
		(end 131.661408 -84.727288)
		(width 0.0889)
		(layer "In4.Cu")
		(net "CLK_100M_CPU1_PE_REFCLK_DP")
	)
	(arc
		(start 138.511534 -85.717888)
		(mid 138.22611 -85.634421)
		(end 138.017504 -85.422486)
		(width 0.0889)
		(layer "In4.Cu")
		(net "CLK_100M_CPU1_PE_REFCLK_DP")
	)
	(arc
		(start 132.494782 -85.222334)
		(mid 132.213482 -85.137368)
		(end 132.007864 -84.92744)
		(width 0.0889)
		(layer "In4.Cu")
		(net "CLK_100M_CPU1_PE_REFCLK_DP")
	)
	(arc
		(start 134.248652 -85.222334)
		(mid 134.236714 -85.222156)
		(end 134.224776 -85.222334)
		(width 0.0889)
		(layer "In4.Cu")
		(net "CLK_100M_CPU1_PE_REFCLK_DP")
	)
	(arc
		(start 128.214374 -82.746088)
		(mid 127.926229 -82.663769)
		(end 127.715518 -82.450686)
		(width 0.0889)
		(layer "In4.Cu")
		(net "CLK_100M_CPU1_PE_REFCLK_DP")
	)
	(arc
		(start 127.347218 -82.250534)
		(mid 127.064001 -82.166253)
		(end 126.856998 -81.955386)
		(width 0.0889)
		(layer "In4.Cu")
		(net "CLK_100M_CPU1_PE_REFCLK_DP")
	)
	(arc
		(start 125.139958 -80.964786)
		(mid 124.999879 -80.82205)
		(end 124.808234 -80.764888)
		(width 0.0889)
		(layer "In4.Cu")
		(net "CLK_100M_CPU1_PE_REFCLK_DP")
	)
	(arc
		(start 137.324084 -85.422486)
		(mid 137.115476 -85.634418)
		(end 136.830054 -85.717888)
		(width 0.0889)
		(layer "In4.Cu")
		(net "CLK_100M_CPU1_PE_REFCLK_DP")
	)
	(arc
		(start 135.941816 -85.222334)
		(mid 135.74839 -85.278861)
		(end 135.607044 -85.422486)
		(width 0.0889)
		(layer "In4.Cu")
		(net "CLK_100M_CPU1_PE_REFCLK_DP")
	)
	(arc
		(start 132.866384 -85.422486)
		(mid 132.724701 -85.278682)
		(end 132.53085 -85.222334)
		(width 0.0889)
		(layer "In4.Cu")
		(net "CLK_100M_CPU1_PE_REFCLK_DP")
	)
	(arc
		(start 124.281438 -80.469486)
		(mid 124.139755 -80.325682)
		(end 123.945904 -80.269334)
		(width 0.0889)
		(layer "In4.Cu")
		(net "CLK_100M_CPU1_PE_REFCLK_DP")
	)
	(arc
		(start 126.856998 -81.955386)
		(mid 126.718254 -81.813353)
		(end 126.528322 -81.755488)
		(width 0.0889)
		(layer "In4.Cu")
		(net "CLK_100M_CPU1_PE_REFCLK_DP")
	)
	(arc
		(start 129.064258 -83.241134)
		(mid 128.781041 -83.156853)
		(end 128.574038 -82.945986)
		(width 0.0889)
		(layer "In4.Cu")
		(net "CLK_100M_CPU1_PE_REFCLK_DP")
	)
	(arc
		(start 135.965692 -85.222334)
		(mid 135.953754 -85.222156)
		(end 135.941816 -85.222334)
		(width 0.0889)
		(layer "In4.Cu")
		(net "CLK_100M_CPU1_PE_REFCLK_DP")
	)
	(arc
		(start 133.890004 -85.422486)
		(mid 133.681396 -85.634418)
		(end 133.395974 -85.717888)
		(width 0.0889)
		(layer "In4.Cu")
		(net "CLK_100M_CPU1_PE_REFCLK_DP")
	)
	(arc
		(start 139.399772 -85.222334)
		(mid 139.387834 -85.222156)
		(end 139.375896 -85.222334)
		(width 0.0889)
		(layer "In4.Cu")
		(net "CLK_100M_CPU1_PE_REFCLK_DP")
	)
	(arc
		(start 131.643628 -84.727288)
		(mid 131.358204 -84.643821)
		(end 131.149598 -84.431886)
		(width 0.0889)
		(layer "In4.Cu")
		(net "CLK_100M_CPU1_PE_REFCLK_DP")
	)
	(arc
		(start 142.515082 -85.419692)
		(mid 142.368982 -85.602026)
		(end 142.166086 -85.717888)
		(width 0.0889)
		(layer "In4.Cu")
		(net "CLK_100M_CPU1_PE_REFCLK_DP")
	)
	(arc
		(start 130.781298 -84.231734)
		(mid 130.498081 -84.147453)
		(end 130.291078 -83.936586)
		(width 0.0889)
		(layer "In4.Cu")
		(net "CLK_100M_CPU1_PE_REFCLK_DP")
	)
	(arc
		(start 140.228574 -85.717888)
		(mid 139.94315 -85.634421)
		(end 139.734544 -85.422486)
		(width 0.0889)
		(layer "In4.Cu")
		(net "CLK_100M_CPU1_PE_REFCLK_DP")
	)
	(arc
		(start 136.794494 -85.717888)
		(mid 136.50907 -85.634421)
		(end 136.300464 -85.422486)
		(width 0.0889)
		(layer "In4.Cu")
		(net "CLK_100M_CPU1_PE_REFCLK_DP")
	)
	(arc
		(start 139.734544 -85.422486)
		(mid 139.593188 -85.278877)
		(end 139.399772 -85.222334)
		(width 0.0889)
		(layer "In4.Cu")
		(net "CLK_100M_CPU1_PE_REFCLK_DP")
	)
	(arc
		(start 141.451584 -85.422486)
		(mid 141.310228 -85.278877)
		(end 141.116812 -85.222334)
		(width 0.0889)
		(layer "In4.Cu")
		(net "CLK_100M_CPU1_PE_REFCLK_DP")
	)
	(arc
		(start 125.998478 -81.460086)
		(mid 125.856795 -81.316282)
		(end 125.662944 -81.259934)
		(width 0.0889)
		(layer "In4.Cu")
		(net "CLK_100M_CPU1_PE_REFCLK_DP")
	)
	(arc
		(start 131.149598 -84.431886)
		(mid 131.007915 -84.288082)
		(end 130.814064 -84.231734)
		(width 0.0889)
		(layer "In4.Cu")
		(net "CLK_100M_CPU1_PE_REFCLK_DP")
	)
	(arc
		(start 123.913138 -80.269334)
		(mid 123.629921 -80.185053)
		(end 123.422918 -79.974186)
		(width 0.0889)
		(layer "In4.Cu")
		(net "CLK_100M_CPU1_PE_REFCLK_DP")
	)
	(arc
		(start 141.092936 -85.222334)
		(mid 140.89951 -85.278861)
		(end 140.758164 -85.422486)
		(width 0.0889)
		(layer "In4.Cu")
		(net "CLK_100M_CPU1_PE_REFCLK_DP")
	)
	(arc
		(start 125.630178 -81.259934)
		(mid 125.346961 -81.175653)
		(end 125.139958 -80.964786)
		(width 0.0889)
		(layer "In4.Cu")
		(net "CLK_100M_CPU1_PE_REFCLK_DP")
	)
	(arc
		(start 142.731744 -85.222334)
		(mid 142.606257 -85.302167)
		(end 142.515082 -85.419692)
		(width 0.0889)
		(layer "In4.Cu")
		(net "CLK_100M_CPU1_PE_REFCLK_DP")
	)
	(arc
		(start 130.291078 -83.936586)
		(mid 130.150999 -83.79385)
		(end 129.959354 -83.736688)
		(width 0.0889)
		(layer "In4.Cu")
		(net "CLK_100M_CPU1_PE_REFCLK_DP")
	)
	(arc
		(start 134.583424 -85.422486)
		(mid 134.442068 -85.278877)
		(end 134.248652 -85.222334)
		(width 0.0889)
		(layer "In4.Cu")
		(net "CLK_100M_CPU1_PE_REFCLK_DP")
	)
	(arc
		(start 137.658856 -85.222334)
		(mid 137.46543 -85.278861)
		(end 137.324084 -85.422486)
		(width 0.0889)
		(layer "In4.Cu")
		(net "CLK_100M_CPU1_PE_REFCLK_DP")
	)
	(arc
		(start 129.432558 -83.441286)
		(mid 129.290875 -83.297482)
		(end 129.097024 -83.241134)
		(width 0.0889)
		(layer "In4.Cu")
		(net "CLK_100M_CPU1_PE_REFCLK_DP")
	)
	(arc
		(start 139.041124 -85.422486)
		(mid 138.832516 -85.634418)
		(end 138.547094 -85.717888)
		(width 0.0889)
		(layer "In4.Cu")
		(net "CLK_100M_CPU1_PE_REFCLK_DP")
	)
	(arc
		(start 138.017504 -85.422486)
		(mid 137.876148 -85.278877)
		(end 137.682732 -85.222334)
		(width 0.0889)
		(layer "In4.Cu")
		(net "CLK_100M_CPU1_PE_REFCLK_DP")
	)
	(arc
		(start 129.926588 -83.736688)
		(mid 129.641164 -83.653221)
		(end 129.432558 -83.441286)
		(width 0.0889)
		(layer "In4.Cu")
		(net "CLK_100M_CPU1_PE_REFCLK_DP")
	)
	(arc
		(start 141.945614 -85.717888)
		(mid 141.66019 -85.634421)
		(end 141.451584 -85.422486)
		(width 0.0889)
		(layer "In4.Cu")
		(net "CLK_100M_CPU1_PE_REFCLK_DP")
	)
	(arc
		(start 141.116812 -85.222334)
		(mid 141.104874 -85.222156)
		(end 141.092936 -85.222334)
		(width 0.0889)
		(layer "In4.Cu")
		(net "CLK_100M_CPU1_PE_REFCLK_DP")
	)
	(arc
		(start 133.360414 -85.717888)
		(mid 133.07499 -85.634421)
		(end 132.866384 -85.422486)
		(width 0.0889)
		(layer "In4.Cu")
		(net "CLK_100M_CPU1_PE_REFCLK_DP")
	)
	(arc
		(start 139.375896 -85.222334)
		(mid 139.18247 -85.278861)
		(end 139.041124 -85.422486)
		(width 0.0889)
		(layer "In4.Cu")
		(net "CLK_100M_CPU1_PE_REFCLK_DP")
	)
	(arc
		(start 134.224776 -85.222334)
		(mid 134.03135 -85.278861)
		(end 133.890004 -85.422486)
		(width 0.0889)
		(layer "In4.Cu")
		(net "CLK_100M_CPU1_PE_REFCLK_DP")
	)
	(arc
		(start 127.715518 -82.450686)
		(mid 127.573835 -82.306882)
		(end 127.379984 -82.250534)
		(width 0.0889)
		(layer "In4.Cu")
		(net "CLK_100M_CPU1_PE_REFCLK_DP")
	)
	(arc
		(start 128.574038 -82.945986)
		(mid 128.433959 -82.80325)
		(end 128.242314 -82.746088)
		(width 0.0889)
		(layer "In4.Cu")
		(net "CLK_100M_CPU1_PE_REFCLK_DP")
	)
	(arc
		(start 126.492508 -81.755488)
		(mid 126.207084 -81.672021)
		(end 125.998478 -81.460086)
		(width 0.0889)
		(layer "In4.Cu")
		(net "CLK_100M_CPU1_PE_REFCLK_DP")
	)
	(segment
		(start 173.433232 -89.206324)
		(end 173.785276 -89.206324)
		(width 0.1143)
		(layer "F.Cu")
		(net "CLK_100M_CPU0_RC_REFCLK0_DP")
	)
	(segment
		(start 173.230286 -87.970614)
		(end 173.230286 -89.003378)
		(width 0.1143)
		(layer "F.Cu")
		(net "CLK_100M_CPU0_RC_REFCLK0_DP")
	)
	(segment
		(start 173.4439 -87.757)
		(end 173.230286 -87.970614)
		(width 0.1143)
		(layer "F.Cu")
		(net "CLK_100M_CPU0_RC_REFCLK0_DP")
	)
	(segment
		(start 284.358334 -66.800984)
		(end 284.929834 -66.800984)
		(width 0.127)
		(layer "F.Cu")
		(net "CLK_100M_CPU0_RC_REFCLK0_DP")
	)
	(segment
		(start 173.230286 -89.003378)
		(end 173.433232 -89.206324)
		(width 0.1143)
		(layer "F.Cu")
		(net "CLK_100M_CPU0_RC_REFCLK0_DP")
	)
	(segment
		(start 173.736 -87.757)
		(end 173.4439 -87.757)
		(width 0.1143)
		(layer "F.Cu")
		(net "CLK_100M_CPU0_RC_REFCLK0_DP")
	)
	(via
		(at 284.358334 -66.800984)
		(size 0.508)
		(drill 0.254)
		(layers "F.Cu" "B.Cu")
		(net "CLK_100M_CPU0_RC_REFCLK0_DP")
	)
	(via
		(at 173.785276 -89.206324)
		(size 0.508)
		(drill 0.254)
		(layers "F.Cu" "B.Cu")
		(net "CLK_100M_CPU0_RC_REFCLK0_DP")
	)
	(segment
		(start 173.736 -87.757)
		(end 173.406054 -87.757)
		(width 0.127)
		(layer "B.Cu")
		(net "CLK_100M_CPU0_RC_REFCLK0_DP")
	)
	(segment
		(start 173.264322 -87.898732)
		(end 173.264322 -88.68537)
		(width 0.127)
		(layer "B.Cu")
		(net "CLK_100M_CPU0_RC_REFCLK0_DP")
	)
	(segment
		(start 173.406054 -87.757)
		(end 173.264322 -87.898732)
		(width 0.127)
		(layer "B.Cu")
		(net "CLK_100M_CPU0_RC_REFCLK0_DP")
	)
	(segment
		(start 173.264322 -88.68537)
		(end 173.785276 -89.206324)
		(width 0.127)
		(layer "B.Cu")
		(net "CLK_100M_CPU0_RC_REFCLK0_DP")
	)
	(segment
		(start 266.00785 -56.878728)
		(end 266.006326 -56.876188)
		(width 0.0889)
		(layer "In9.Cu")
		(net "CLK_100M_CPU0_RC_REFCLK0_DP")
	)
	(segment
		(start 280.93543 -64.419734)
		(end 280.902664 -64.419734)
		(width 0.0889)
		(layer "In9.Cu")
		(net "CLK_100M_CPU0_RC_REFCLK0_DP")
	)
	(segment
		(start 268.089888 -57.666382)
		(end 267.595096 -57.17159)
		(width 0.0889)
		(layer "In9.Cu")
		(net "CLK_100M_CPU0_RC_REFCLK0_DP")
	)
	(segment
		(start 258.802886 -52.713636)
		(end 258.77012 -52.713636)
		(width 0.0889)
		(layer "In9.Cu")
		(net "CLK_100M_CPU0_RC_REFCLK0_DP")
	)
	(segment
		(start 235.912152 -50.047144)
		(end 235.569252 -50.047144)
		(width 0.1143)
		(layer "In9.Cu")
		(net "CLK_100M_CPU0_RC_REFCLK0_DP")
	)
	(segment
		(start 270.706342 -58.476388)
		(end 270.70558 -58.476134)
		(width 0.0889)
		(layer "In9.Cu")
		(net "CLK_100M_CPU0_RC_REFCLK0_DP")
	)
	(segment
		(start 257.32105 -51.74996)
		(end 257.073654 -51.502564)
		(width 0.0889)
		(layer "In9.Cu")
		(net "CLK_100M_CPU0_RC_REFCLK0_DP")
	)
	(segment
		(start 256.558542 -51.502564)
		(end 256.469642 -51.591464)
		(width 0.0889)
		(layer "In9.Cu")
		(net "CLK_100M_CPU0_RC_REFCLK0_DP")
	)
	(segment
		(start 278.36368 -62.934088)
		(end 278.330914 -62.934088)
		(width 0.0889)
		(layer "In9.Cu")
		(net "CLK_100M_CPU0_RC_REFCLK0_DP")
	)
	(segment
		(start 271.498822 -58.971688)
		(end 271.315434 -58.971688)
		(width 0.0889)
		(layer "In9.Cu")
		(net "CLK_100M_CPU0_RC_REFCLK0_DP")
	)
	(segment
		(start 253.725934 -51.198526)
		(end 250.496578 -51.198526)
		(width 0.1143)
		(layer "In9.Cu")
		(net "CLK_100M_CPU0_RC_REFCLK0_DP")
	)
	(segment
		(start 261.382256 -54.19979)
		(end 261.34949 -54.19979)
		(width 0.0889)
		(layer "In9.Cu")
		(net "CLK_100M_CPU0_RC_REFCLK0_DP")
	)
	(segment
		(start 185.8264 -58.019442)
		(end 186.154568 -58.34761)
		(width 0.1143)
		(layer "In9.Cu")
		(net "CLK_100M_CPU0_RC_REFCLK0_DP")
	)
	(segment
		(start 174.03572 -87.072978)
		(end 173.31944 -87.789258)
		(width 0.1143)
		(layer "In9.Cu")
		(net "CLK_100M_CPU0_RC_REFCLK0_DP")
	)
	(segment
		(start 235.404152 -49.882044)
		(end 207.93329 -49.882044)
		(width 0.1143)
		(layer "In9.Cu")
		(net "CLK_100M_CPU0_RC_REFCLK0_DP")
	)
	(segment
		(start 179.85359 -75.05827)
		(end 178.773582 -76.138278)
		(width 0.1143)
		(layer "In9.Cu")
		(net "CLK_100M_CPU0_RC_REFCLK0_DP")
	)
	(segment
		(start 173.31944 -87.789258)
		(end 173.31944 -88.98382)
		(width 0.1143)
		(layer "In9.Cu")
		(net "CLK_100M_CPU0_RC_REFCLK0_DP")
	)
	(segment
		(start 267.075158 -57.26049)
		(end 266.808458 -57.26049)
		(width 0.0889)
		(layer "In9.Cu")
		(net "CLK_100M_CPU0_RC_REFCLK0_DP")
	)
	(segment
		(start 239.286288 -49.7205)
		(end 239.124744 -49.882044)
		(width 0.1143)
		(layer "In9.Cu")
		(net "CLK_100M_CPU0_RC_REFCLK0_DP")
	)
	(segment
		(start 237.436152 -49.882044)
		(end 237.093252 -49.882044)
		(width 0.1143)
		(layer "In9.Cu")
		(net "CLK_100M_CPU0_RC_REFCLK0_DP")
	)
	(segment
		(start 202.64247 -49.09058)
		(end 200.550272 -51.182778)
		(width 0.1143)
		(layer "In9.Cu")
		(net "CLK_100M_CPU0_RC_REFCLK0_DP")
	)
	(segment
		(start 268.798548 -57.666382)
		(end 268.089888 -57.666382)
		(width 0.0889)
		(layer "In9.Cu")
		(net "CLK_100M_CPU0_RC_REFCLK0_DP")
	)
	(segment
		(start 263.099296 -55.19039)
		(end 263.06653 -55.19039)
		(width 0.0889)
		(layer "In9.Cu")
		(net "CLK_100M_CPU0_RC_REFCLK0_DP")
	)
	(segment
		(start 179.85359 -73.518522)
		(end 179.85359 -75.05827)
		(width 0.1143)
		(layer "In9.Cu")
		(net "CLK_100M_CPU0_RC_REFCLK0_DP")
	)
	(segment
		(start 174.269146 -87.072978)
		(end 174.03572 -87.072978)
		(width 0.1143)
		(layer "In9.Cu")
		(net "CLK_100M_CPU0_RC_REFCLK0_DP")
	)
	(segment
		(start 244.849142 -51.6763)
		(end 244.278658 -51.6763)
		(width 0.1143)
		(layer "In9.Cu")
		(net "CLK_100M_CPU0_RC_REFCLK0_DP")
	)
	(segment
		(start 256.114042 -51.502564)
		(end 255.28778 -51.502564)
		(width 0.0889)
		(layer "In9.Cu")
		(net "CLK_100M_CPU0_RC_REFCLK0_DP")
	)
	(segment
		(start 282.65247 -65.410334)
		(end 282.619704 -65.410334)
		(width 0.0889)
		(layer "In9.Cu")
		(net "CLK_100M_CPU0_RC_REFCLK0_DP")
	)
	(segment
		(start 186.154568 -58.34761)
		(end 186.154568 -61.74613)
		(width 0.1143)
		(layer "In9.Cu")
		(net "CLK_100M_CPU0_RC_REFCLK0_DP")
	)
	(segment
		(start 237.944152 -50.047144)
		(end 237.601252 -50.047144)
		(width 0.1143)
		(layer "In9.Cu")
		(net "CLK_100M_CPU0_RC_REFCLK0_DP")
	)
	(segment
		(start 255.23698 -51.553364)
		(end 255.214882 -51.553364)
		(width 0.0889)
		(layer "In9.Cu")
		(net "CLK_100M_CPU0_RC_REFCLK0_DP")
	)
	(segment
		(start 255.28778 -51.502564)
		(end 255.23698 -51.553364)
		(width 0.0889)
		(layer "In9.Cu")
		(net "CLK_100M_CPU0_RC_REFCLK0_DP")
	)
	(segment
		(start 269.243048 -57.666382)
		(end 269.154148 -57.755282)
		(width 0.0889)
		(layer "In9.Cu")
		(net "CLK_100M_CPU0_RC_REFCLK0_DP")
	)
	(segment
		(start 256.202942 -51.591464)
		(end 256.114042 -51.502564)
		(width 0.0889)
		(layer "In9.Cu")
		(net "CLK_100M_CPU0_RC_REFCLK0_DP")
	)
	(segment
		(start 174.511716 -86.830408)
		(end 174.269146 -87.072978)
		(width 0.1143)
		(layer "In9.Cu")
		(net "CLK_100M_CPU0_RC_REFCLK0_DP")
	)
	(segment
		(start 268.887448 -57.755282)
		(end 268.798548 -57.666382)
		(width 0.0889)
		(layer "In9.Cu")
		(net "CLK_100M_CPU0_RC_REFCLK0_DP")
	)
	(segment
		(start 175.735742 -80.778858)
		(end 175.735742 -85.372956)
		(width 0.1143)
		(layer "In9.Cu")
		(net "CLK_100M_CPU0_RC_REFCLK0_DP")
	)
	(segment
		(start 269.154148 -57.755282)
		(end 268.887448 -57.755282)
		(width 0.0889)
		(layer "In9.Cu")
		(net "CLK_100M_CPU0_RC_REFCLK0_DP")
	)
	(segment
		(start 275.78431 -61.447934)
		(end 275.751544 -61.447934)
		(width 0.0889)
		(layer "In9.Cu")
		(net "CLK_100M_CPU0_RC_REFCLK0_DP")
	)
	(segment
		(start 256.469642 -51.591464)
		(end 256.202942 -51.591464)
		(width 0.0889)
		(layer "In9.Cu")
		(net "CLK_100M_CPU0_RC_REFCLK0_DP")
	)
	(segment
		(start 176.938432 -80.241902)
		(end 176.272698 -80.241902)
		(width 0.1143)
		(layer "In9.Cu")
		(net "CLK_100M_CPU0_RC_REFCLK0_DP")
	)
	(segment
		(start 264.289286 -55.885588)
		(end 264.285984 -55.879746)
		(width 0.0889)
		(layer "In9.Cu")
		(net "CLK_100M_CPU0_RC_REFCLK0_DP")
	)
	(segment
		(start 176.272698 -80.241902)
		(end 175.735742 -80.778858)
		(width 0.1143)
		(layer "In9.Cu")
		(net "CLK_100M_CPU0_RC_REFCLK0_DP")
	)
	(segment
		(start 235.569252 -50.047144)
		(end 235.404152 -49.882044)
		(width 0.1143)
		(layer "In9.Cu")
		(net "CLK_100M_CPU0_RC_REFCLK0_DP")
	)
	(segment
		(start 269.509748 -57.666382)
		(end 269.243048 -57.666382)
		(width 0.0889)
		(layer "In9.Cu")
		(net "CLK_100M_CPU0_RC_REFCLK0_DP")
	)
	(segment
		(start 185.8264 -54.387242)
		(end 185.8264 -58.019442)
		(width 0.1143)
		(layer "In9.Cu")
		(net "CLK_100M_CPU0_RC_REFCLK0_DP")
	)
	(segment
		(start 173.541944 -89.206324)
		(end 173.785276 -89.206324)
		(width 0.1143)
		(layer "In9.Cu")
		(net "CLK_100M_CPU0_RC_REFCLK0_DP")
	)
	(segment
		(start 255.214882 -51.553364)
		(end 254.080772 -51.553364)
		(width 0.1143)
		(layer "In9.Cu")
		(net "CLK_100M_CPU0_RC_REFCLK0_DP")
	)
	(segment
		(start 274.9296 -60.952888)
		(end 274.896834 -60.952888)
		(width 0.0889)
		(layer "In9.Cu")
		(net "CLK_100M_CPU0_RC_REFCLK0_DP")
	)
	(segment
		(start 250.496578 -51.198526)
		(end 249.294904 -52.4002)
		(width 0.1143)
		(layer "In9.Cu")
		(net "CLK_100M_CPU0_RC_REFCLK0_DP")
	)
	(segment
		(start 273.212814 -59.962288)
		(end 273.184874 -59.962288)
		(width 0.0889)
		(layer "In9.Cu")
		(net "CLK_100M_CPU0_RC_REFCLK0_DP")
	)
	(segment
		(start 265.670792 -56.676036)
		(end 265.638026 -56.676036)
		(width 0.0889)
		(layer "In9.Cu")
		(net "CLK_100M_CPU0_RC_REFCLK0_DP")
	)
	(segment
		(start 200.550272 -51.182778)
		(end 193.36512 -51.182778)
		(width 0.1143)
		(layer "In9.Cu")
		(net "CLK_100M_CPU0_RC_REFCLK0_DP")
	)
	(segment
		(start 236.420152 -49.882044)
		(end 236.077252 -49.882044)
		(width 0.1143)
		(layer "In9.Cu")
		(net "CLK_100M_CPU0_RC_REFCLK0_DP")
	)
	(segment
		(start 181.337458 -68.305426)
		(end 181.337458 -72.034654)
		(width 0.1143)
		(layer "In9.Cu")
		(net "CLK_100M_CPU0_RC_REFCLK0_DP")
	)
	(segment
		(start 192.982342 -50.8)
		(end 189.413642 -50.8)
		(width 0.1143)
		(layer "In9.Cu")
		(net "CLK_100M_CPU0_RC_REFCLK0_DP")
	)
	(segment
		(start 240.467642 -49.7205)
		(end 239.286288 -49.7205)
		(width 0.1143)
		(layer "In9.Cu")
		(net "CLK_100M_CPU0_RC_REFCLK0_DP")
	)
	(segment
		(start 181.337458 -72.034654)
		(end 179.85359 -73.518522)
		(width 0.1143)
		(layer "In9.Cu")
		(net "CLK_100M_CPU0_RC_REFCLK0_DP")
	)
	(segment
		(start 262.236966 -54.694836)
		(end 262.2042 -54.694836)
		(width 0.0889)
		(layer "In9.Cu")
		(net "CLK_100M_CPU0_RC_REFCLK0_DP")
	)
	(segment
		(start 245.573042 -52.4002)
		(end 244.849142 -51.6763)
		(width 0.1143)
		(layer "In9.Cu")
		(net "CLK_100M_CPU0_RC_REFCLK0_DP")
	)
	(segment
		(start 279.21839 -63.429134)
		(end 279.185624 -63.429134)
		(width 0.0889)
		(layer "In9.Cu")
		(net "CLK_100M_CPU0_RC_REFCLK0_DP")
	)
	(segment
		(start 270.048228 -58.204862)
		(end 269.509748 -57.666382)
		(width 0.0889)
		(layer "In9.Cu")
		(net "CLK_100M_CPU0_RC_REFCLK0_DP")
	)
	(segment
		(start 207.93329 -49.882044)
		(end 207.141826 -49.09058)
		(width 0.1143)
		(layer "In9.Cu")
		(net "CLK_100M_CPU0_RC_REFCLK0_DP")
	)
	(segment
		(start 236.928152 -50.047144)
		(end 236.585252 -50.047144)
		(width 0.1143)
		(layer "In9.Cu")
		(net "CLK_100M_CPU0_RC_REFCLK0_DP")
	)
	(segment
		(start 249.294904 -52.4002)
		(end 245.573042 -52.4002)
		(width 0.1143)
		(layer "In9.Cu")
		(net "CLK_100M_CPU0_RC_REFCLK0_DP")
	)
	(segment
		(start 244.113558 -51.8414)
		(end 242.588542 -51.8414)
		(width 0.1143)
		(layer "In9.Cu")
		(net "CLK_100M_CPU0_RC_REFCLK0_DP")
	)
	(segment
		(start 266.808458 -57.26049)
		(end 266.719558 -57.17159)
		(width 0.0889)
		(layer "In9.Cu")
		(net "CLK_100M_CPU0_RC_REFCLK0_DP")
	)
	(segment
		(start 184.46242 -66.87058)
		(end 182.772304 -66.87058)
		(width 0.1143)
		(layer "In9.Cu")
		(net "CLK_100M_CPU0_RC_REFCLK0_DP")
	)
	(segment
		(start 281.79776 -64.915288)
		(end 281.764994 -64.915288)
		(width 0.0889)
		(layer "In9.Cu")
		(net "CLK_100M_CPU0_RC_REFCLK0_DP")
	)
	(segment
		(start 186.154568 -61.74613)
		(end 186.55538 -62.146942)
		(width 0.1143)
		(layer "In9.Cu")
		(net "CLK_100M_CPU0_RC_REFCLK0_DP")
	)
	(segment
		(start 238.109252 -49.882044)
		(end 237.944152 -50.047144)
		(width 0.1143)
		(layer "In9.Cu")
		(net "CLK_100M_CPU0_RC_REFCLK0_DP")
	)
	(segment
		(start 239.124744 -49.882044)
		(end 238.109252 -49.882044)
		(width 0.1143)
		(layer "In9.Cu")
		(net "CLK_100M_CPU0_RC_REFCLK0_DP")
	)
	(segment
		(start 207.141826 -49.09058)
		(end 202.64247 -49.09058)
		(width 0.1143)
		(layer "In9.Cu")
		(net "CLK_100M_CPU0_RC_REFCLK0_DP")
	)
	(segment
		(start 264.816082 -56.18099)
		(end 264.783316 -56.18099)
		(width 0.0889)
		(layer "In9.Cu")
		(net "CLK_100M_CPU0_RC_REFCLK0_DP")
	)
	(segment
		(start 266.009374 -56.881522)
		(end 266.00785 -56.878728)
		(width 0.0889)
		(layer "In9.Cu")
		(net "CLK_100M_CPU0_RC_REFCLK0_DP")
	)
	(segment
		(start 267.164058 -57.17159)
		(end 267.075158 -57.26049)
		(width 0.0889)
		(layer "In9.Cu")
		(net "CLK_100M_CPU0_RC_REFCLK0_DP")
	)
	(segment
		(start 242.588542 -51.8414)
		(end 240.467642 -49.7205)
		(width 0.1143)
		(layer "In9.Cu")
		(net "CLK_100M_CPU0_RC_REFCLK0_DP")
	)
	(segment
		(start 266.719558 -57.17159)
		(end 266.452858 -57.17159)
		(width 0.0889)
		(layer "In9.Cu")
		(net "CLK_100M_CPU0_RC_REFCLK0_DP")
	)
	(segment
		(start 283.5148 -65.905888)
		(end 283.482034 -65.905888)
		(width 0.0889)
		(layer "In9.Cu")
		(net "CLK_100M_CPU0_RC_REFCLK0_DP")
	)
	(segment
		(start 257.073654 -51.502564)
		(end 256.558542 -51.502564)
		(width 0.0889)
		(layer "In9.Cu")
		(net "CLK_100M_CPU0_RC_REFCLK0_DP")
	)
	(segment
		(start 257.948176 -52.21859)
		(end 257.919474 -52.21859)
		(width 0.0889)
		(layer "In9.Cu")
		(net "CLK_100M_CPU0_RC_REFCLK0_DP")
	)
	(segment
		(start 284.358334 -66.400934)
		(end 284.336744 -66.400934)
		(width 0.0889)
		(layer "In9.Cu")
		(net "CLK_100M_CPU0_RC_REFCLK0_DP")
	)
	(segment
		(start 237.601252 -50.047144)
		(end 237.436152 -49.882044)
		(width 0.1143)
		(layer "In9.Cu")
		(net "CLK_100M_CPU0_RC_REFCLK0_DP")
	)
	(segment
		(start 237.093252 -49.882044)
		(end 236.928152 -50.047144)
		(width 0.1143)
		(layer "In9.Cu")
		(net "CLK_100M_CPU0_RC_REFCLK0_DP")
	)
	(segment
		(start 174.511716 -86.596982)
		(end 174.511716 -86.830408)
		(width 0.1143)
		(layer "In9.Cu")
		(net "CLK_100M_CPU0_RC_REFCLK0_DP")
	)
	(segment
		(start 277.50135 -62.438534)
		(end 277.468584 -62.438534)
		(width 0.0889)
		(layer "In9.Cu")
		(net "CLK_100M_CPU0_RC_REFCLK0_DP")
	)
	(segment
		(start 236.077252 -49.882044)
		(end 235.912152 -50.047144)
		(width 0.1143)
		(layer "In9.Cu")
		(net "CLK_100M_CPU0_RC_REFCLK0_DP")
	)
	(segment
		(start 236.585252 -50.047144)
		(end 236.420152 -49.882044)
		(width 0.1143)
		(layer "In9.Cu")
		(net "CLK_100M_CPU0_RC_REFCLK0_DP")
	)
	(segment
		(start 186.55538 -62.146942)
		(end 186.55538 -64.77762)
		(width 0.1143)
		(layer "In9.Cu")
		(net "CLK_100M_CPU0_RC_REFCLK0_DP")
	)
	(segment
		(start 193.36512 -51.182778)
		(end 192.982342 -50.8)
		(width 0.1143)
		(layer "In9.Cu")
		(net "CLK_100M_CPU0_RC_REFCLK0_DP")
	)
	(segment
		(start 173.31944 -88.98382)
		(end 173.541944 -89.206324)
		(width 0.1143)
		(layer "In9.Cu")
		(net "CLK_100M_CPU0_RC_REFCLK0_DP")
	)
	(segment
		(start 254.080772 -51.553364)
		(end 253.725934 -51.198526)
		(width 0.1143)
		(layer "In9.Cu")
		(net "CLK_100M_CPU0_RC_REFCLK0_DP")
	)
	(segment
		(start 189.413642 -50.8)
		(end 185.8264 -54.387242)
		(width 0.1143)
		(layer "In9.Cu")
		(net "CLK_100M_CPU0_RC_REFCLK0_DP")
	)
	(segment
		(start 260.519926 -53.704236)
		(end 260.48716 -53.704236)
		(width 0.0889)
		(layer "In9.Cu")
		(net "CLK_100M_CPU0_RC_REFCLK0_DP")
	)
	(segment
		(start 272.357342 -59.466988)
		(end 272.321528 -59.466988)
		(width 0.0889)
		(layer "In9.Cu")
		(net "CLK_100M_CPU0_RC_REFCLK0_DP")
	)
	(segment
		(start 267.595096 -57.17159)
		(end 267.164058 -57.17159)
		(width 0.0889)
		(layer "In9.Cu")
		(net "CLK_100M_CPU0_RC_REFCLK0_DP")
	)
	(segment
		(start 270.70558 -58.476134)
		(end 270.407638 -58.476134)
		(width 0.0889)
		(layer "In9.Cu")
		(net "CLK_100M_CPU0_RC_REFCLK0_DP")
	)
	(segment
		(start 178.773582 -76.138278)
		(end 178.773582 -78.406752)
		(width 0.1143)
		(layer "In9.Cu")
		(net "CLK_100M_CPU0_RC_REFCLK0_DP")
	)
	(segment
		(start 186.55538 -64.77762)
		(end 184.46242 -66.87058)
		(width 0.1143)
		(layer "In9.Cu")
		(net "CLK_100M_CPU0_RC_REFCLK0_DP")
	)
	(segment
		(start 182.772304 -66.87058)
		(end 181.337458 -68.305426)
		(width 0.1143)
		(layer "In9.Cu")
		(net "CLK_100M_CPU0_RC_REFCLK0_DP")
	)
	(segment
		(start 175.735742 -85.372956)
		(end 174.511716 -86.596982)
		(width 0.1143)
		(layer "In9.Cu")
		(net "CLK_100M_CPU0_RC_REFCLK0_DP")
	)
	(segment
		(start 274.056348 -60.457334)
		(end 274.034758 -60.457334)
		(width 0.0889)
		(layer "In9.Cu")
		(net "CLK_100M_CPU0_RC_REFCLK0_DP")
	)
	(segment
		(start 274.402804 -60.657486)
		(end 274.399502 -60.651644)
		(width 0.0889)
		(layer "In9.Cu")
		(net "CLK_100M_CPU0_RC_REFCLK0_DP")
	)
	(segment
		(start 259.665216 -53.20919)
		(end 259.637276 -53.20919)
		(width 0.0889)
		(layer "In9.Cu")
		(net "CLK_100M_CPU0_RC_REFCLK0_DP")
	)
	(segment
		(start 276.64664 -61.943488)
		(end 276.613874 -61.943488)
		(width 0.0889)
		(layer "In9.Cu")
		(net "CLK_100M_CPU0_RC_REFCLK0_DP")
	)
	(segment
		(start 257.42138 -51.923442)
		(end 257.32105 -51.74996)
		(width 0.0889)
		(layer "In9.Cu")
		(net "CLK_100M_CPU0_RC_REFCLK0_DP")
	)
	(segment
		(start 280.08072 -63.924688)
		(end 280.047954 -63.924688)
		(width 0.0889)
		(layer "In9.Cu")
		(net "CLK_100M_CPU0_RC_REFCLK0_DP")
	)
	(segment
		(start 178.773582 -78.406752)
		(end 176.938432 -80.241902)
		(width 0.1143)
		(layer "In9.Cu")
		(net "CLK_100M_CPU0_RC_REFCLK0_DP")
	)
	(segment
		(start 244.278658 -51.6763)
		(end 244.113558 -51.8414)
		(width 0.1143)
		(layer "In9.Cu")
		(net "CLK_100M_CPU0_RC_REFCLK0_DP")
	)
	(segment
		(start 263.94283 -55.685436)
		(end 263.92124 -55.685436)
		(width 0.0889)
		(layer "In9.Cu")
		(net "CLK_100M_CPU0_RC_REFCLK0_DP")
	)
	(arc
		(start 264.783316 -56.18099)
		(mid 264.497892 -56.097523)
		(end 264.289286 -55.885588)
		(width 0.0889)
		(layer "In9.Cu")
		(net "CLK_100M_CPU0_RC_REFCLK0_DP")
	)
	(arc
		(start 259.637276 -53.20919)
		(mid 259.349131 -53.126871)
		(end 259.13842 -52.913788)
		(width 0.0889)
		(layer "In9.Cu")
		(net "CLK_100M_CPU0_RC_REFCLK0_DP")
	)
	(arc
		(start 266.006326 -56.876188)
		(mid 265.864643 -56.732384)
		(end 265.670792 -56.676036)
		(width 0.0889)
		(layer "In9.Cu")
		(net "CLK_100M_CPU0_RC_REFCLK0_DP")
	)
	(arc
		(start 261.34949 -54.19979)
		(mid 261.064066 -54.116323)
		(end 260.85546 -53.904388)
		(width 0.0889)
		(layer "In9.Cu")
		(net "CLK_100M_CPU0_RC_REFCLK0_DP")
	)
	(arc
		(start 284.587696 -67.128644)
		(mid 284.739899 -66.680762)
		(end 284.358334 -66.400934)
		(width 0.0889)
		(layer "In9.Cu")
		(net "CLK_100M_CPU0_RC_REFCLK0_DP")
	)
	(arc
		(start 284.358334 -66.800984)
		(mid 284.187681 -66.892272)
		(end 284.186122 -67.085718)
		(width 0.0889)
		(layer "In9.Cu")
		(net "CLK_100M_CPU0_RC_REFCLK0_DP")
	)
	(arc
		(start 281.764994 -64.915288)
		(mid 281.47957 -64.831821)
		(end 281.270964 -64.619886)
		(width 0.0889)
		(layer "In9.Cu")
		(net "CLK_100M_CPU0_RC_REFCLK0_DP")
	)
	(arc
		(start 281.270964 -64.619886)
		(mid 281.129281 -64.476082)
		(end 280.93543 -64.419734)
		(width 0.0889)
		(layer "In9.Cu")
		(net "CLK_100M_CPU0_RC_REFCLK0_DP")
	)
	(arc
		(start 273.184874 -59.962288)
		(mid 272.896729 -59.879969)
		(end 272.686018 -59.666886)
		(width 0.0889)
		(layer "In9.Cu")
		(net "CLK_100M_CPU0_RC_REFCLK0_DP")
	)
	(arc
		(start 263.92124 -55.685436)
		(mid 263.638023 -55.601155)
		(end 263.43102 -55.390288)
		(width 0.0889)
		(layer "In9.Cu")
		(net "CLK_100M_CPU0_RC_REFCLK0_DP")
	)
	(arc
		(start 280.047954 -63.924688)
		(mid 279.76253 -63.841221)
		(end 279.553924 -63.629286)
		(width 0.0889)
		(layer "In9.Cu")
		(net "CLK_100M_CPU0_RC_REFCLK0_DP")
	)
	(arc
		(start 280.902664 -64.419734)
		(mid 280.619447 -64.335453)
		(end 280.412444 -64.124586)
		(width 0.0889)
		(layer "In9.Cu")
		(net "CLK_100M_CPU0_RC_REFCLK0_DP")
	)
	(arc
		(start 260.85546 -53.904388)
		(mid 260.713777 -53.760584)
		(end 260.519926 -53.704236)
		(width 0.0889)
		(layer "In9.Cu")
		(net "CLK_100M_CPU0_RC_REFCLK0_DP")
	)
	(arc
		(start 282.988004 -65.610486)
		(mid 282.846321 -65.466682)
		(end 282.65247 -65.410334)
		(width 0.0889)
		(layer "In9.Cu")
		(net "CLK_100M_CPU0_RC_REFCLK0_DP")
	)
	(arc
		(start 258.2799 -52.418488)
		(mid 258.139821 -52.275752)
		(end 257.948176 -52.21859)
		(width 0.0889)
		(layer "In9.Cu")
		(net "CLK_100M_CPU0_RC_REFCLK0_DP")
	)
	(arc
		(start 284.186122 -67.085718)
		(mid 284.284058 -67.17644)
		(end 284.415992 -67.196716)
		(width 0.0889)
		(layer "In9.Cu")
		(net "CLK_100M_CPU0_RC_REFCLK0_DP")
	)
	(arc
		(start 284.336744 -66.400934)
		(mid 284.053527 -66.316653)
		(end 283.846524 -66.105786)
		(width 0.0889)
		(layer "In9.Cu")
		(net "CLK_100M_CPU0_RC_REFCLK0_DP")
	)
	(arc
		(start 258.77012 -52.713636)
		(mid 258.486903 -52.629355)
		(end 258.2799 -52.418488)
		(width 0.0889)
		(layer "In9.Cu")
		(net "CLK_100M_CPU0_RC_REFCLK0_DP")
	)
	(arc
		(start 279.185624 -63.429134)
		(mid 278.902407 -63.344853)
		(end 278.695404 -63.133986)
		(width 0.0889)
		(layer "In9.Cu")
		(net "CLK_100M_CPU0_RC_REFCLK0_DP")
	)
	(arc
		(start 260.48716 -53.704236)
		(mid 260.203943 -53.619955)
		(end 259.99694 -53.409088)
		(width 0.0889)
		(layer "In9.Cu")
		(net "CLK_100M_CPU0_RC_REFCLK0_DP")
	)
	(arc
		(start 266.452858 -57.17159)
		(mid 266.196485 -57.079492)
		(end 266.009374 -56.881522)
		(width 0.0889)
		(layer "In9.Cu")
		(net "CLK_100M_CPU0_RC_REFCLK0_DP")
	)
	(arc
		(start 283.482034 -65.905888)
		(mid 283.19661 -65.822421)
		(end 282.988004 -65.610486)
		(width 0.0889)
		(layer "In9.Cu")
		(net "CLK_100M_CPU0_RC_REFCLK0_DP")
	)
	(arc
		(start 279.553924 -63.629286)
		(mid 279.412241 -63.485482)
		(end 279.21839 -63.429134)
		(width 0.0889)
		(layer "In9.Cu")
		(net "CLK_100M_CPU0_RC_REFCLK0_DP")
	)
	(arc
		(start 274.399502 -60.651644)
		(mid 274.253536 -60.509245)
		(end 274.056348 -60.457334)
		(width 0.0889)
		(layer "In9.Cu")
		(net "CLK_100M_CPU0_RC_REFCLK0_DP")
	)
	(arc
		(start 278.330914 -62.934088)
		(mid 278.04549 -62.850621)
		(end 277.836884 -62.638686)
		(width 0.0889)
		(layer "In9.Cu")
		(net "CLK_100M_CPU0_RC_REFCLK0_DP")
	)
	(arc
		(start 276.978364 -62.143386)
		(mid 276.838285 -62.00065)
		(end 276.64664 -61.943488)
		(width 0.0889)
		(layer "In9.Cu")
		(net "CLK_100M_CPU0_RC_REFCLK0_DP")
	)
	(arc
		(start 261.71398 -54.399688)
		(mid 261.573901 -54.256952)
		(end 261.382256 -54.19979)
		(width 0.0889)
		(layer "In9.Cu")
		(net "CLK_100M_CPU0_RC_REFCLK0_DP")
	)
	(arc
		(start 263.06653 -55.19039)
		(mid 262.781106 -55.106923)
		(end 262.5725 -54.894988)
		(width 0.0889)
		(layer "In9.Cu")
		(net "CLK_100M_CPU0_RC_REFCLK0_DP")
	)
	(arc
		(start 271.315434 -58.971688)
		(mid 271.098771 -58.860882)
		(end 270.942308 -58.674508)
		(width 0.0889)
		(layer "In9.Cu")
		(net "CLK_100M_CPU0_RC_REFCLK0_DP")
	)
	(arc
		(start 277.836884 -62.638686)
		(mid 277.695201 -62.494882)
		(end 277.50135 -62.438534)
		(width 0.0889)
		(layer "In9.Cu")
		(net "CLK_100M_CPU0_RC_REFCLK0_DP")
	)
	(arc
		(start 284.415992 -67.196716)
		(mid 284.505816 -67.172706)
		(end 284.587696 -67.128644)
		(width 0.0889)
		(layer "In9.Cu")
		(net "CLK_100M_CPU0_RC_REFCLK0_DP")
	)
	(arc
		(start 275.261324 -61.152786)
		(mid 275.121245 -61.01005)
		(end 274.9296 -60.952888)
		(width 0.0889)
		(layer "In9.Cu")
		(net "CLK_100M_CPU0_RC_REFCLK0_DP")
	)
	(arc
		(start 282.619704 -65.410334)
		(mid 282.336487 -65.326053)
		(end 282.129484 -65.115186)
		(width 0.0889)
		(layer "In9.Cu")
		(net "CLK_100M_CPU0_RC_REFCLK0_DP")
	)
	(arc
		(start 262.5725 -54.894988)
		(mid 262.430817 -54.751184)
		(end 262.236966 -54.694836)
		(width 0.0889)
		(layer "In9.Cu")
		(net "CLK_100M_CPU0_RC_REFCLK0_DP")
	)
	(arc
		(start 283.846524 -66.105786)
		(mid 283.706445 -65.96305)
		(end 283.5148 -65.905888)
		(width 0.0889)
		(layer "In9.Cu")
		(net "CLK_100M_CPU0_RC_REFCLK0_DP")
	)
	(arc
		(start 271.827498 -59.171586)
		(mid 271.688754 -59.029553)
		(end 271.498822 -58.971688)
		(width 0.0889)
		(layer "In9.Cu")
		(net "CLK_100M_CPU0_RC_REFCLK0_DP")
	)
	(arc
		(start 265.638026 -56.676036)
		(mid 265.354809 -56.591755)
		(end 265.147806 -56.380888)
		(width 0.0889)
		(layer "In9.Cu")
		(net "CLK_100M_CPU0_RC_REFCLK0_DP")
	)
	(arc
		(start 262.2042 -54.694836)
		(mid 261.920983 -54.610555)
		(end 261.71398 -54.399688)
		(width 0.0889)
		(layer "In9.Cu")
		(net "CLK_100M_CPU0_RC_REFCLK0_DP")
	)
	(arc
		(start 274.034758 -60.457334)
		(mid 273.751541 -60.373053)
		(end 273.544538 -60.162186)
		(width 0.0889)
		(layer "In9.Cu")
		(net "CLK_100M_CPU0_RC_REFCLK0_DP")
	)
	(arc
		(start 264.285984 -55.879746)
		(mid 264.140018 -55.737347)
		(end 263.94283 -55.685436)
		(width 0.0889)
		(layer "In9.Cu")
		(net "CLK_100M_CPU0_RC_REFCLK0_DP")
	)
	(arc
		(start 273.544538 -60.162186)
		(mid 273.404459 -60.01945)
		(end 273.212814 -59.962288)
		(width 0.0889)
		(layer "In9.Cu")
		(net "CLK_100M_CPU0_RC_REFCLK0_DP")
	)
	(arc
		(start 270.942308 -58.674508)
		(mid 270.843062 -58.55312)
		(end 270.706342 -58.476388)
		(width 0.0889)
		(layer "In9.Cu")
		(net "CLK_100M_CPU0_RC_REFCLK0_DP")
	)
	(arc
		(start 272.321528 -59.466988)
		(mid 272.036104 -59.383521)
		(end 271.827498 -59.171586)
		(width 0.0889)
		(layer "In9.Cu")
		(net "CLK_100M_CPU0_RC_REFCLK0_DP")
	)
	(arc
		(start 277.468584 -62.438534)
		(mid 277.185367 -62.354253)
		(end 276.978364 -62.143386)
		(width 0.0889)
		(layer "In9.Cu")
		(net "CLK_100M_CPU0_RC_REFCLK0_DP")
	)
	(arc
		(start 263.43102 -55.390288)
		(mid 263.290941 -55.247552)
		(end 263.099296 -55.19039)
		(width 0.0889)
		(layer "In9.Cu")
		(net "CLK_100M_CPU0_RC_REFCLK0_DP")
	)
	(arc
		(start 274.896834 -60.952888)
		(mid 274.61141 -60.869421)
		(end 274.402804 -60.657486)
		(width 0.0889)
		(layer "In9.Cu")
		(net "CLK_100M_CPU0_RC_REFCLK0_DP")
	)
	(arc
		(start 276.119844 -61.648086)
		(mid 275.978161 -61.504282)
		(end 275.78431 -61.447934)
		(width 0.0889)
		(layer "In9.Cu")
		(net "CLK_100M_CPU0_RC_REFCLK0_DP")
	)
	(arc
		(start 272.686018 -59.666886)
		(mid 272.547274 -59.524853)
		(end 272.357342 -59.466988)
		(width 0.0889)
		(layer "In9.Cu")
		(net "CLK_100M_CPU0_RC_REFCLK0_DP")
	)
	(arc
		(start 270.407638 -58.476134)
		(mid 270.202158 -58.374664)
		(end 270.048228 -58.204862)
		(width 0.0889)
		(layer "In9.Cu")
		(net "CLK_100M_CPU0_RC_REFCLK0_DP")
	)
	(arc
		(start 275.751544 -61.447934)
		(mid 275.468327 -61.363653)
		(end 275.261324 -61.152786)
		(width 0.0889)
		(layer "In9.Cu")
		(net "CLK_100M_CPU0_RC_REFCLK0_DP")
	)
	(arc
		(start 257.919474 -52.21859)
		(mid 257.631794 -52.136217)
		(end 257.42138 -51.923442)
		(width 0.0889)
		(layer "In9.Cu")
		(net "CLK_100M_CPU0_RC_REFCLK0_DP")
	)
	(arc
		(start 278.695404 -63.133986)
		(mid 278.555325 -62.99125)
		(end 278.36368 -62.934088)
		(width 0.0889)
		(layer "In9.Cu")
		(net "CLK_100M_CPU0_RC_REFCLK0_DP")
	)
	(arc
		(start 282.129484 -65.115186)
		(mid 281.989405 -64.97245)
		(end 281.79776 -64.915288)
		(width 0.0889)
		(layer "In9.Cu")
		(net "CLK_100M_CPU0_RC_REFCLK0_DP")
	)
	(arc
		(start 259.13842 -52.913788)
		(mid 258.996737 -52.769984)
		(end 258.802886 -52.713636)
		(width 0.0889)
		(layer "In9.Cu")
		(net "CLK_100M_CPU0_RC_REFCLK0_DP")
	)
	(arc
		(start 276.613874 -61.943488)
		(mid 276.32845 -61.860021)
		(end 276.119844 -61.648086)
		(width 0.0889)
		(layer "In9.Cu")
		(net "CLK_100M_CPU0_RC_REFCLK0_DP")
	)
	(arc
		(start 259.99694 -53.409088)
		(mid 259.856861 -53.266352)
		(end 259.665216 -53.20919)
		(width 0.0889)
		(layer "In9.Cu")
		(net "CLK_100M_CPU0_RC_REFCLK0_DP")
	)
	(arc
		(start 280.412444 -64.124586)
		(mid 280.272365 -63.98185)
		(end 280.08072 -63.924688)
		(width 0.0889)
		(layer "In9.Cu")
		(net "CLK_100M_CPU0_RC_REFCLK0_DP")
	)
	(arc
		(start 265.147806 -56.380888)
		(mid 265.007727 -56.238152)
		(end 264.816082 -56.18099)
		(width 0.0889)
		(layer "In9.Cu")
		(net "CLK_100M_CPU0_RC_REFCLK0_DP")
	)
	(segment
		(start 173.014386 -87.984584)
		(end 172.786802 -87.757)
		(width 0.1143)
		(layer "F.Cu")
		(net "CLK_100M_CPU0_RC_REFCLK0_DN")
	)
	(segment
		(start 172.80636 -89.206324)
		(end 173.014386 -88.998298)
		(width 0.1143)
		(layer "F.Cu")
		(net "CLK_100M_CPU0_RC_REFCLK0_DN")
	)
	(segment
		(start 172.786802 -87.757)
		(end 172.466 -87.757)
		(width 0.1143)
		(layer "F.Cu")
		(net "CLK_100M_CPU0_RC_REFCLK0_DN")
	)
	(segment
		(start 172.515276 -89.206324)
		(end 172.80636 -89.206324)
		(width 0.1143)
		(layer "F.Cu")
		(net "CLK_100M_CPU0_RC_REFCLK0_DN")
	)
	(segment
		(start 173.014386 -88.998298)
		(end 173.014386 -87.984584)
		(width 0.1143)
		(layer "F.Cu")
		(net "CLK_100M_CPU0_RC_REFCLK0_DN")
	)
	(segment
		(start 284.358334 -67.791584)
		(end 284.929834 -67.791584)
		(width 0.127)
		(layer "F.Cu")
		(net "CLK_100M_CPU0_RC_REFCLK0_DN")
	)
	(via
		(at 284.358334 -67.791584)
		(size 0.508)
		(drill 0.254)
		(layers "F.Cu" "B.Cu")
		(net "CLK_100M_CPU0_RC_REFCLK0_DN")
	)
	(via
		(at 172.515276 -89.206324)
		(size 0.508)
		(drill 0.254)
		(layers "F.Cu" "B.Cu")
		(net "CLK_100M_CPU0_RC_REFCLK0_DN")
	)
	(segment
		(start 172.959522 -88.762078)
		(end 172.515276 -89.206324)
		(width 0.127)
		(layer "B.Cu")
		(net "CLK_100M_CPU0_RC_REFCLK0_DN")
	)
	(segment
		(start 172.6946 -87.757)
		(end 172.959522 -88.021922)
		(width 0.127)
		(layer "B.Cu")
		(net "CLK_100M_CPU0_RC_REFCLK0_DN")
	)
	(segment
		(start 172.466 -87.757)
		(end 172.6946 -87.757)
		(width 0.127)
		(layer "B.Cu")
		(net "CLK_100M_CPU0_RC_REFCLK0_DN")
	)
	(segment
		(start 172.959522 -88.021922)
		(end 172.959522 -88.762078)
		(width 0.127)
		(layer "B.Cu")
		(net "CLK_100M_CPU0_RC_REFCLK0_DN")
	)
	(segment
		(start 244.9703 -51.3842)
		(end 244.1575 -51.3842)
		(width 0.1143)
		(layer "In9.Cu")
		(net "CLK_100M_CPU0_RC_REFCLK0_DN")
	)
	(segment
		(start 239.003586 -49.589944)
		(end 208.054448 -49.589944)
		(width 0.1143)
		(layer "In9.Cu")
		(net "CLK_100M_CPU0_RC_REFCLK0_DN")
	)
	(segment
		(start 243.9924 -51.5493)
		(end 242.7097 -51.5493)
		(width 0.1143)
		(layer "In9.Cu")
		(net "CLK_100M_CPU0_RC_REFCLK0_DN")
	)
	(segment
		(start 264.822686 -55.99049)
		(end 264.801096 -55.99049)
		(width 0.0889)
		(layer "In9.Cu")
		(net "CLK_100M_CPU0_RC_REFCLK0_DN")
	)
	(segment
		(start 281.804364 -64.724788)
		(end 281.771598 -64.724788)
		(width 0.0889)
		(layer "In9.Cu")
		(net "CLK_100M_CPU0_RC_REFCLK0_DN")
	)
	(segment
		(start 175.443642 -85.251798)
		(end 173.02734 -87.6681)
		(width 0.1143)
		(layer "In9.Cu")
		(net "CLK_100M_CPU0_RC_REFCLK0_DN")
	)
	(segment
		(start 185.862468 -61.867288)
		(end 186.26328 -62.2681)
		(width 0.1143)
		(layer "In9.Cu")
		(net "CLK_100M_CPU0_RC_REFCLK0_DN")
	)
	(segment
		(start 277.507954 -62.248034)
		(end 277.475188 -62.248034)
		(width 0.0889)
		(layer "In9.Cu")
		(net "CLK_100M_CPU0_RC_REFCLK0_DN")
	)
	(segment
		(start 261.38886 -54.00929)
		(end 261.356094 -54.00929)
		(width 0.0889)
		(layer "In9.Cu")
		(net "CLK_100M_CPU0_RC_REFCLK0_DN")
	)
	(segment
		(start 181.045358 -71.913496)
		(end 179.56149 -73.397364)
		(width 0.1143)
		(layer "In9.Cu")
		(net "CLK_100M_CPU0_RC_REFCLK0_DN")
	)
	(segment
		(start 185.862468 -58.468768)
		(end 185.862468 -61.867288)
		(width 0.1143)
		(layer "In9.Cu")
		(net "CLK_100M_CPU0_RC_REFCLK0_DN")
	)
	(segment
		(start 178.481482 -78.285594)
		(end 176.817274 -79.949802)
		(width 0.1143)
		(layer "In9.Cu")
		(net "CLK_100M_CPU0_RC_REFCLK0_DN")
	)
	(segment
		(start 200.429114 -50.890678)
		(end 193.486278 -50.890678)
		(width 0.1143)
		(layer "In9.Cu")
		(net "CLK_100M_CPU0_RC_REFCLK0_DN")
	)
	(segment
		(start 253.847092 -50.906426)
		(end 250.37542 -50.906426)
		(width 0.1143)
		(layer "In9.Cu")
		(net "CLK_100M_CPU0_RC_REFCLK0_DN")
	)
	(segment
		(start 283.521404 -65.715388)
		(end 283.488638 -65.715388)
		(width 0.0889)
		(layer "In9.Cu")
		(net "CLK_100M_CPU0_RC_REFCLK0_DN")
	)
	(segment
		(start 258.8133 -52.523136)
		(end 258.776724 -52.523136)
		(width 0.0889)
		(layer "In9.Cu")
		(net "CLK_100M_CPU0_RC_REFCLK0_DN")
	)
	(segment
		(start 254.20193 -51.261264)
		(end 253.847092 -50.906426)
		(width 0.1143)
		(layer "In9.Cu")
		(net "CLK_100M_CPU0_RC_REFCLK0_DN")
	)
	(segment
		(start 266.173458 -56.784494)
		(end 266.17168 -56.781192)
		(width 0.0889)
		(layer "In9.Cu")
		(net "CLK_100M_CPU0_RC_REFCLK0_DN")
	)
	(segment
		(start 259.663184 -53.018436)
		(end 259.639054 -53.018436)
		(width 0.0889)
		(layer "In9.Cu")
		(net "CLK_100M_CPU0_RC_REFCLK0_DN")
	)
	(segment
		(start 280.942034 -64.229234)
		(end 280.909268 -64.229234)
		(width 0.0889)
		(layer "In9.Cu")
		(net "CLK_100M_CPU0_RC_REFCLK0_DN")
	)
	(segment
		(start 181.045358 -68.184268)
		(end 181.045358 -71.913496)
		(width 0.1143)
		(layer "In9.Cu")
		(net "CLK_100M_CPU0_RC_REFCLK0_DN")
	)
	(segment
		(start 207.262984 -48.79848)
		(end 202.521312 -48.79848)
		(width 0.1143)
		(layer "In9.Cu")
		(net "CLK_100M_CPU0_RC_REFCLK0_DN")
	)
	(segment
		(start 255.28778 -51.312064)
		(end 255.23698 -51.261264)
		(width 0.0889)
		(layer "In9.Cu")
		(net "CLK_100M_CPU0_RC_REFCLK0_DN")
	)
	(segment
		(start 270.735806 -58.285634)
		(end 270.436086 -58.285634)
		(width 0.0889)
		(layer "In9.Cu")
		(net "CLK_100M_CPU0_RC_REFCLK0_DN")
	)
	(segment
		(start 265.673332 -56.485536)
		(end 265.64463 -56.485536)
		(width 0.0889)
		(layer "In9.Cu")
		(net "CLK_100M_CPU0_RC_REFCLK0_DN")
	)
	(segment
		(start 202.521312 -48.79848)
		(end 200.429114 -50.890678)
		(width 0.1143)
		(layer "In9.Cu")
		(net "CLK_100M_CPU0_RC_REFCLK0_DN")
	)
	(segment
		(start 249.173746 -52.1081)
		(end 245.6942 -52.1081)
		(width 0.1143)
		(layer "In9.Cu")
		(net "CLK_100M_CPU0_RC_REFCLK0_DN")
	)
	(segment
		(start 268.168882 -57.475882)
		(end 267.67409 -56.98109)
		(width 0.0889)
		(layer "In9.Cu")
		(net "CLK_100M_CPU0_RC_REFCLK0_DN")
	)
	(segment
		(start 262.24357 -54.504336)
		(end 262.210804 -54.504336)
		(width 0.0889)
		(layer "In9.Cu")
		(net "CLK_100M_CPU0_RC_REFCLK0_DN")
	)
	(segment
		(start 274.936204 -60.762388)
		(end 274.914614 -60.762388)
		(width 0.0889)
		(layer "In9.Cu")
		(net "CLK_100M_CPU0_RC_REFCLK0_DN")
	)
	(segment
		(start 176.15154 -79.949802)
		(end 175.443642 -80.6577)
		(width 0.1143)
		(layer "In9.Cu")
		(net "CLK_100M_CPU0_RC_REFCLK0_DN")
	)
	(segment
		(start 257.152648 -51.312064)
		(end 255.28778 -51.312064)
		(width 0.0889)
		(layer "In9.Cu")
		(net "CLK_100M_CPU0_RC_REFCLK0_DN")
	)
	(segment
		(start 278.370284 -62.743588)
		(end 278.337518 -62.743588)
		(width 0.0889)
		(layer "In9.Cu")
		(net "CLK_100M_CPU0_RC_REFCLK0_DN")
	)
	(segment
		(start 185.5343 -54.266084)
		(end 185.5343 -58.1406)
		(width 0.1143)
		(layer "In9.Cu")
		(net "CLK_100M_CPU0_RC_REFCLK0_DN")
	)
	(segment
		(start 266.17168 -56.781192)
		(end 266.171426 -56.780938)
		(width 0.0889)
		(layer "In9.Cu")
		(net "CLK_100M_CPU0_RC_REFCLK0_DN")
	)
	(segment
		(start 179.56149 -74.937112)
		(end 178.481482 -76.01712)
		(width 0.1143)
		(layer "In9.Cu")
		(net "CLK_100M_CPU0_RC_REFCLK0_DN")
	)
	(segment
		(start 182.651146 -66.57848)
		(end 181.045358 -68.184268)
		(width 0.1143)
		(layer "In9.Cu")
		(net "CLK_100M_CPU0_RC_REFCLK0_DN")
	)
	(segment
		(start 208.054448 -49.589944)
		(end 207.262984 -48.79848)
		(width 0.1143)
		(layer "In9.Cu")
		(net "CLK_100M_CPU0_RC_REFCLK0_DN")
	)
	(segment
		(start 267.67409 -56.98109)
		(end 266.464542 -56.98109)
		(width 0.0889)
		(layer "In9.Cu")
		(net "CLK_100M_CPU0_RC_REFCLK0_DN")
	)
	(segment
		(start 184.341262 -66.57848)
		(end 182.651146 -66.57848)
		(width 0.1143)
		(layer "In9.Cu")
		(net "CLK_100M_CPU0_RC_REFCLK0_DN")
	)
	(segment
		(start 271.498568 -58.780934)
		(end 271.345152 -58.780934)
		(width 0.0889)
		(layer "In9.Cu")
		(net "CLK_100M_CPU0_RC_REFCLK0_DN")
	)
	(segment
		(start 257.95478 -52.02809)
		(end 257.922014 -52.02809)
		(width 0.0889)
		(layer "In9.Cu")
		(net "CLK_100M_CPU0_RC_REFCLK0_DN")
	)
	(segment
		(start 186.26328 -62.2681)
		(end 186.26328 -64.656462)
		(width 0.1143)
		(layer "In9.Cu")
		(net "CLK_100M_CPU0_RC_REFCLK0_DN")
	)
	(segment
		(start 270.200628 -58.087768)
		(end 269.588742 -57.475882)
		(width 0.0889)
		(layer "In9.Cu")
		(net "CLK_100M_CPU0_RC_REFCLK0_DN")
	)
	(segment
		(start 279.224994 -63.238634)
		(end 279.192228 -63.238634)
		(width 0.0889)
		(layer "In9.Cu")
		(net "CLK_100M_CPU0_RC_REFCLK0_DN")
	)
	(segment
		(start 193.1035 -50.5079)
		(end 189.292484 -50.5079)
		(width 0.1143)
		(layer "In9.Cu")
		(net "CLK_100M_CPU0_RC_REFCLK0_DN")
	)
	(segment
		(start 269.588742 -57.475882)
		(end 268.168882 -57.475882)
		(width 0.0889)
		(layer "In9.Cu")
		(net "CLK_100M_CPU0_RC_REFCLK0_DN")
	)
	(segment
		(start 189.292484 -50.5079)
		(end 185.5343 -54.266084)
		(width 0.1143)
		(layer "In9.Cu")
		(net "CLK_100M_CPU0_RC_REFCLK0_DN")
	)
	(segment
		(start 266.174474 -56.786272)
		(end 266.173458 -56.784494)
		(width 0.0889)
		(layer "In9.Cu")
		(net "CLK_100M_CPU0_RC_REFCLK0_DN")
	)
	(segment
		(start 179.56149 -73.397364)
		(end 179.56149 -74.937112)
		(width 0.1143)
		(layer "In9.Cu")
		(net "CLK_100M_CPU0_RC_REFCLK0_DN")
	)
	(segment
		(start 255.214882 -51.261264)
		(end 254.20193 -51.261264)
		(width 0.1143)
		(layer "In9.Cu")
		(net "CLK_100M_CPU0_RC_REFCLK0_DN")
	)
	(segment
		(start 176.817274 -79.949802)
		(end 176.15154 -79.949802)
		(width 0.1143)
		(layer "In9.Cu")
		(net "CLK_100M_CPU0_RC_REFCLK0_DN")
	)
	(segment
		(start 173.02734 -88.94318)
		(end 172.764196 -89.206324)
		(width 0.1143)
		(layer "In9.Cu")
		(net "CLK_100M_CPU0_RC_REFCLK0_DN")
	)
	(segment
		(start 273.210782 -59.771534)
		(end 273.186652 -59.771534)
		(width 0.0889)
		(layer "In9.Cu")
		(net "CLK_100M_CPU0_RC_REFCLK0_DN")
	)
	(segment
		(start 245.6942 -52.1081)
		(end 244.9703 -51.3842)
		(width 0.1143)
		(layer "In9.Cu")
		(net "CLK_100M_CPU0_RC_REFCLK0_DN")
	)
	(segment
		(start 239.16513 -49.4284)
		(end 239.003586 -49.589944)
		(width 0.1143)
		(layer "In9.Cu")
		(net "CLK_100M_CPU0_RC_REFCLK0_DN")
	)
	(segment
		(start 173.02734 -87.6681)
		(end 173.02734 -88.94318)
		(width 0.1143)
		(layer "In9.Cu")
		(net "CLK_100M_CPU0_RC_REFCLK0_DN")
	)
	(segment
		(start 263.96061 -55.494936)
		(end 263.927844 -55.494936)
		(width 0.0889)
		(layer "In9.Cu")
		(net "CLK_100M_CPU0_RC_REFCLK0_DN")
	)
	(segment
		(start 250.37542 -50.906426)
		(end 249.173746 -52.1081)
		(width 0.1143)
		(layer "In9.Cu")
		(net "CLK_100M_CPU0_RC_REFCLK0_DN")
	)
	(segment
		(start 255.23698 -51.261264)
		(end 255.214882 -51.261264)
		(width 0.0889)
		(layer "In9.Cu")
		(net "CLK_100M_CPU0_RC_REFCLK0_DN")
	)
	(segment
		(start 275.790914 -61.257434)
		(end 275.758148 -61.257434)
		(width 0.0889)
		(layer "In9.Cu")
		(net "CLK_100M_CPU0_RC_REFCLK0_DN")
	)
	(segment
		(start 257.58648 -51.827938)
		(end 257.47345 -51.632612)
		(width 0.0889)
		(layer "In9.Cu")
		(net "CLK_100M_CPU0_RC_REFCLK0_DN")
	)
	(segment
		(start 185.5343 -58.1406)
		(end 185.862468 -58.468768)
		(width 0.1143)
		(layer "In9.Cu")
		(net "CLK_100M_CPU0_RC_REFCLK0_DN")
	)
	(segment
		(start 272.360898 -59.276234)
		(end 272.321274 -59.276234)
		(width 0.0889)
		(layer "In9.Cu")
		(net "CLK_100M_CPU0_RC_REFCLK0_DN")
	)
	(segment
		(start 172.764196 -89.206324)
		(end 172.515276 -89.206324)
		(width 0.1143)
		(layer "In9.Cu")
		(net "CLK_100M_CPU0_RC_REFCLK0_DN")
	)
	(segment
		(start 274.074128 -60.266834)
		(end 274.041362 -60.266834)
		(width 0.0889)
		(layer "In9.Cu")
		(net "CLK_100M_CPU0_RC_REFCLK0_DN")
	)
	(segment
		(start 284.376114 -66.210434)
		(end 284.343348 -66.210434)
		(width 0.0889)
		(layer "In9.Cu")
		(net "CLK_100M_CPU0_RC_REFCLK0_DN")
	)
	(segment
		(start 280.087324 -63.734188)
		(end 280.054558 -63.734188)
		(width 0.0889)
		(layer "In9.Cu")
		(net "CLK_100M_CPU0_RC_REFCLK0_DN")
	)
	(segment
		(start 242.7097 -51.5493)
		(end 240.5888 -49.4284)
		(width 0.1143)
		(layer "In9.Cu")
		(net "CLK_100M_CPU0_RC_REFCLK0_DN")
	)
	(segment
		(start 244.1575 -51.3842)
		(end 243.9924 -51.5493)
		(width 0.1143)
		(layer "In9.Cu")
		(net "CLK_100M_CPU0_RC_REFCLK0_DN")
	)
	(segment
		(start 260.52653 -53.513736)
		(end 260.493764 -53.513736)
		(width 0.0889)
		(layer "In9.Cu")
		(net "CLK_100M_CPU0_RC_REFCLK0_DN")
	)
	(segment
		(start 257.47345 -51.632612)
		(end 257.152648 -51.312064)
		(width 0.0889)
		(layer "In9.Cu")
		(net "CLK_100M_CPU0_RC_REFCLK0_DN")
	)
	(segment
		(start 276.653244 -61.752988)
		(end 276.620478 -61.752988)
		(width 0.0889)
		(layer "In9.Cu")
		(net "CLK_100M_CPU0_RC_REFCLK0_DN")
	)
	(segment
		(start 274.57146 -60.568078)
		(end 274.568158 -60.562236)
		(width 0.0889)
		(layer "In9.Cu")
		(net "CLK_100M_CPU0_RC_REFCLK0_DN")
	)
	(segment
		(start 282.659074 -65.219834)
		(end 282.626308 -65.219834)
		(width 0.0889)
		(layer "In9.Cu")
		(net "CLK_100M_CPU0_RC_REFCLK0_DN")
	)
	(segment
		(start 186.26328 -64.656462)
		(end 184.341262 -66.57848)
		(width 0.1143)
		(layer "In9.Cu")
		(net "CLK_100M_CPU0_RC_REFCLK0_DN")
	)
	(segment
		(start 193.486278 -50.890678)
		(end 193.1035 -50.5079)
		(width 0.1143)
		(layer "In9.Cu")
		(net "CLK_100M_CPU0_RC_REFCLK0_DN")
	)
	(segment
		(start 175.443642 -80.6577)
		(end 175.443642 -85.251798)
		(width 0.1143)
		(layer "In9.Cu")
		(net "CLK_100M_CPU0_RC_REFCLK0_DN")
	)
	(segment
		(start 264.457942 -55.79618)
		(end 264.45464 -55.790338)
		(width 0.0889)
		(layer "In9.Cu")
		(net "CLK_100M_CPU0_RC_REFCLK0_DN")
	)
	(segment
		(start 263.1059 -54.99989)
		(end 263.073134 -54.99989)
		(width 0.0889)
		(layer "In9.Cu")
		(net "CLK_100M_CPU0_RC_REFCLK0_DN")
	)
	(segment
		(start 178.481482 -76.01712)
		(end 178.481482 -78.285594)
		(width 0.1143)
		(layer "In9.Cu")
		(net "CLK_100M_CPU0_RC_REFCLK0_DN")
	)
	(segment
		(start 240.5888 -49.4284)
		(end 239.16513 -49.4284)
		(width 0.1143)
		(layer "In9.Cu")
		(net "CLK_100M_CPU0_RC_REFCLK0_DN")
	)
	(arc
		(start 272.851118 -59.571382)
		(mid 272.644114 -59.360518)
		(end 272.360898 -59.276234)
		(width 0.0889)
		(layer "In9.Cu")
		(net "CLK_100M_CPU0_RC_REFCLK0_DN")
	)
	(arc
		(start 278.001984 -62.543436)
		(mid 277.793376 -62.331504)
		(end 277.507954 -62.248034)
		(width 0.0889)
		(layer "In9.Cu")
		(net "CLK_100M_CPU0_RC_REFCLK0_DN")
	)
	(arc
		(start 278.860504 -63.038736)
		(mid 278.6535 -62.827872)
		(end 278.370284 -62.743588)
		(width 0.0889)
		(layer "In9.Cu")
		(net "CLK_100M_CPU0_RC_REFCLK0_DN")
	)
	(arc
		(start 281.771598 -64.724788)
		(mid 281.577748 -64.668438)
		(end 281.436064 -64.524636)
		(width 0.0889)
		(layer "In9.Cu")
		(net "CLK_100M_CPU0_RC_REFCLK0_DN")
	)
	(arc
		(start 274.914614 -60.762388)
		(mid 274.717453 -60.710429)
		(end 274.57146 -60.568078)
		(width 0.0889)
		(layer "In9.Cu")
		(net "CLK_100M_CPU0_RC_REFCLK0_DN")
	)
	(arc
		(start 263.073134 -54.99989)
		(mid 262.879284 -54.94354)
		(end 262.7376 -54.799738)
		(width 0.0889)
		(layer "In9.Cu")
		(net "CLK_100M_CPU0_RC_REFCLK0_DN")
	)
	(arc
		(start 274.041362 -60.266834)
		(mid 273.84972 -60.209668)
		(end 273.709638 -60.066936)
		(width 0.0889)
		(layer "In9.Cu")
		(net "CLK_100M_CPU0_RC_REFCLK0_DN")
	)
	(arc
		(start 283.488638 -65.715388)
		(mid 283.294788 -65.659038)
		(end 283.153104 -65.515236)
		(width 0.0889)
		(layer "In9.Cu")
		(net "CLK_100M_CPU0_RC_REFCLK0_DN")
	)
	(arc
		(start 280.577544 -64.029336)
		(mid 280.37054 -63.818472)
		(end 280.087324 -63.734188)
		(width 0.0889)
		(layer "In9.Cu")
		(net "CLK_100M_CPU0_RC_REFCLK0_DN")
	)
	(arc
		(start 279.192228 -63.238634)
		(mid 279.000586 -63.181468)
		(end 278.860504 -63.038736)
		(width 0.0889)
		(layer "In9.Cu")
		(net "CLK_100M_CPU0_RC_REFCLK0_DN")
	)
	(arc
		(start 273.186652 -59.771534)
		(mid 272.992802 -59.715184)
		(end 272.851118 -59.571382)
		(width 0.0889)
		(layer "In9.Cu")
		(net "CLK_100M_CPU0_RC_REFCLK0_DN")
	)
	(arc
		(start 279.719024 -63.534036)
		(mid 279.510416 -63.322104)
		(end 279.224994 -63.238634)
		(width 0.0889)
		(layer "In9.Cu")
		(net "CLK_100M_CPU0_RC_REFCLK0_DN")
	)
	(arc
		(start 262.7376 -54.799738)
		(mid 262.528992 -54.587806)
		(end 262.24357 -54.504336)
		(width 0.0889)
		(layer "In9.Cu")
		(net "CLK_100M_CPU0_RC_REFCLK0_DN")
	)
	(arc
		(start 284.011624 -66.010536)
		(mid 283.80462 -65.799672)
		(end 283.521404 -65.715388)
		(width 0.0889)
		(layer "In9.Cu")
		(net "CLK_100M_CPU0_RC_REFCLK0_DN")
	)
	(arc
		(start 280.909268 -64.229234)
		(mid 280.717626 -64.172068)
		(end 280.577544 -64.029336)
		(width 0.0889)
		(layer "In9.Cu")
		(net "CLK_100M_CPU0_RC_REFCLK0_DN")
	)
	(arc
		(start 266.464542 -56.98109)
		(mid 266.296895 -56.91736)
		(end 266.174474 -56.786272)
		(width 0.0889)
		(layer "In9.Cu")
		(net "CLK_100M_CPU0_RC_REFCLK0_DN")
	)
	(arc
		(start 265.312906 -56.285638)
		(mid 265.105902 -56.074774)
		(end 264.822686 -55.99049)
		(width 0.0889)
		(layer "In9.Cu")
		(net "CLK_100M_CPU0_RC_REFCLK0_DN")
	)
	(arc
		(start 278.337518 -62.743588)
		(mid 278.143668 -62.687238)
		(end 278.001984 -62.543436)
		(width 0.0889)
		(layer "In9.Cu")
		(net "CLK_100M_CPU0_RC_REFCLK0_DN")
	)
	(arc
		(start 261.02056 -53.809138)
		(mid 260.811952 -53.597206)
		(end 260.52653 -53.513736)
		(width 0.0889)
		(layer "In9.Cu")
		(net "CLK_100M_CPU0_RC_REFCLK0_DN")
	)
	(arc
		(start 264.801096 -55.99049)
		(mid 264.603935 -55.938531)
		(end 264.457942 -55.79618)
		(width 0.0889)
		(layer "In9.Cu")
		(net "CLK_100M_CPU0_RC_REFCLK0_DN")
	)
	(arc
		(start 283.153104 -65.515236)
		(mid 282.944496 -65.303304)
		(end 282.659074 -65.219834)
		(width 0.0889)
		(layer "In9.Cu")
		(net "CLK_100M_CPU0_RC_REFCLK0_DN")
	)
	(arc
		(start 273.709638 -60.066936)
		(mid 273.498925 -59.853857)
		(end 273.210782 -59.771534)
		(width 0.0889)
		(layer "In9.Cu")
		(net "CLK_100M_CPU0_RC_REFCLK0_DN")
	)
	(arc
		(start 270.436086 -58.285634)
		(mid 270.299721 -58.208883)
		(end 270.200628 -58.087768)
		(width 0.0889)
		(layer "In9.Cu")
		(net "CLK_100M_CPU0_RC_REFCLK0_DN")
	)
	(arc
		(start 276.284944 -61.552836)
		(mid 276.076336 -61.340904)
		(end 275.790914 -61.257434)
		(width 0.0889)
		(layer "In9.Cu")
		(net "CLK_100M_CPU0_RC_REFCLK0_DN")
	)
	(arc
		(start 263.927844 -55.494936)
		(mid 263.736202 -55.43777)
		(end 263.59612 -55.295038)
		(width 0.0889)
		(layer "In9.Cu")
		(net "CLK_100M_CPU0_RC_REFCLK0_DN")
	)
	(arc
		(start 274.568158 -60.562236)
		(mid 274.35955 -60.350304)
		(end 274.074128 -60.266834)
		(width 0.0889)
		(layer "In9.Cu")
		(net "CLK_100M_CPU0_RC_REFCLK0_DN")
	)
	(arc
		(start 266.171426 -56.780938)
		(mid 265.961073 -56.567966)
		(end 265.673332 -56.485536)
		(width 0.0889)
		(layer "In9.Cu")
		(net "CLK_100M_CPU0_RC_REFCLK0_DN")
	)
	(arc
		(start 258.776724 -52.523136)
		(mid 258.585082 -52.46597)
		(end 258.445 -52.323238)
		(width 0.0889)
		(layer "In9.Cu")
		(net "CLK_100M_CPU0_RC_REFCLK0_DN")
	)
	(arc
		(start 284.343348 -66.210434)
		(mid 284.151706 -66.153268)
		(end 284.011624 -66.010536)
		(width 0.0889)
		(layer "In9.Cu")
		(net "CLK_100M_CPU0_RC_REFCLK0_DN")
	)
	(arc
		(start 262.210804 -54.504336)
		(mid 262.019162 -54.44717)
		(end 261.87908 -54.304438)
		(width 0.0889)
		(layer "In9.Cu")
		(net "CLK_100M_CPU0_RC_REFCLK0_DN")
	)
	(arc
		(start 260.493764 -53.513736)
		(mid 260.302122 -53.45657)
		(end 260.16204 -53.313838)
		(width 0.0889)
		(layer "In9.Cu")
		(net "CLK_100M_CPU0_RC_REFCLK0_DN")
	)
	(arc
		(start 259.30352 -52.818284)
		(mid 259.096516 -52.60742)
		(end 258.8133 -52.523136)
		(width 0.0889)
		(layer "In9.Cu")
		(net "CLK_100M_CPU0_RC_REFCLK0_DN")
	)
	(arc
		(start 264.45464 -55.790338)
		(mid 264.246032 -55.578406)
		(end 263.96061 -55.494936)
		(width 0.0889)
		(layer "In9.Cu")
		(net "CLK_100M_CPU0_RC_REFCLK0_DN")
	)
	(arc
		(start 272.321274 -59.276234)
		(mid 272.131345 -59.218364)
		(end 271.992598 -59.076336)
		(width 0.0889)
		(layer "In9.Cu")
		(net "CLK_100M_CPU0_RC_REFCLK0_DN")
	)
	(arc
		(start 257.922014 -52.02809)
		(mid 257.728164 -51.97174)
		(end 257.58648 -51.827938)
		(width 0.0889)
		(layer "In9.Cu")
		(net "CLK_100M_CPU0_RC_REFCLK0_DN")
	)
	(arc
		(start 259.639054 -53.018436)
		(mid 259.445204 -52.962086)
		(end 259.30352 -52.818284)
		(width 0.0889)
		(layer "In9.Cu")
		(net "CLK_100M_CPU0_RC_REFCLK0_DN")
	)
	(arc
		(start 270.767302 -58.295286)
		(mid 270.751619 -58.290248)
		(end 270.735806 -58.285634)
		(width 0.0889)
		(layer "In9.Cu")
		(net "CLK_100M_CPU0_RC_REFCLK0_DN")
	)
	(arc
		(start 271.109948 -58.583068)
		(mid 270.965798 -58.406831)
		(end 270.767302 -58.295286)
		(width 0.0889)
		(layer "In9.Cu")
		(net "CLK_100M_CPU0_RC_REFCLK0_DN")
	)
	(arc
		(start 271.345152 -58.780934)
		(mid 271.208935 -58.70414)
		(end 271.109948 -58.583068)
		(width 0.0889)
		(layer "In9.Cu")
		(net "CLK_100M_CPU0_RC_REFCLK0_DN")
	)
	(arc
		(start 281.436064 -64.524636)
		(mid 281.227456 -64.312704)
		(end 280.942034 -64.229234)
		(width 0.0889)
		(layer "In9.Cu")
		(net "CLK_100M_CPU0_RC_REFCLK0_DN")
	)
	(arc
		(start 282.294584 -65.019936)
		(mid 282.08758 -64.809072)
		(end 281.804364 -64.724788)
		(width 0.0889)
		(layer "In9.Cu")
		(net "CLK_100M_CPU0_RC_REFCLK0_DN")
	)
	(arc
		(start 284.358334 -67.791584)
		(mid 284.480279 -67.506581)
		(end 284.69717 -67.285108)
		(width 0.0889)
		(layer "In9.Cu")
		(net "CLK_100M_CPU0_RC_REFCLK0_DN")
	)
	(arc
		(start 280.054558 -63.734188)
		(mid 279.860708 -63.677838)
		(end 279.719024 -63.534036)
		(width 0.0889)
		(layer "In9.Cu")
		(net "CLK_100M_CPU0_RC_REFCLK0_DN")
	)
	(arc
		(start 261.356094 -54.00929)
		(mid 261.162244 -53.95294)
		(end 261.02056 -53.809138)
		(width 0.0889)
		(layer "In9.Cu")
		(net "CLK_100M_CPU0_RC_REFCLK0_DN")
	)
	(arc
		(start 277.475188 -62.248034)
		(mid 277.283546 -62.190868)
		(end 277.143464 -62.048136)
		(width 0.0889)
		(layer "In9.Cu")
		(net "CLK_100M_CPU0_RC_REFCLK0_DN")
	)
	(arc
		(start 276.620478 -61.752988)
		(mid 276.426628 -61.696638)
		(end 276.284944 -61.552836)
		(width 0.0889)
		(layer "In9.Cu")
		(net "CLK_100M_CPU0_RC_REFCLK0_DN")
	)
	(arc
		(start 258.445 -52.323238)
		(mid 258.237996 -52.112374)
		(end 257.95478 -52.02809)
		(width 0.0889)
		(layer "In9.Cu")
		(net "CLK_100M_CPU0_RC_REFCLK0_DN")
	)
	(arc
		(start 265.64463 -56.485536)
		(mid 265.452988 -56.42837)
		(end 265.312906 -56.285638)
		(width 0.0889)
		(layer "In9.Cu")
		(net "CLK_100M_CPU0_RC_REFCLK0_DN")
	)
	(arc
		(start 282.626308 -65.219834)
		(mid 282.434666 -65.162668)
		(end 282.294584 -65.019936)
		(width 0.0889)
		(layer "In9.Cu")
		(net "CLK_100M_CPU0_RC_REFCLK0_DN")
	)
	(arc
		(start 271.992598 -59.076336)
		(mid 271.78399 -58.864404)
		(end 271.498568 -58.780934)
		(width 0.0889)
		(layer "In9.Cu")
		(net "CLK_100M_CPU0_RC_REFCLK0_DN")
	)
	(arc
		(start 275.426424 -61.057536)
		(mid 275.21942 -60.846672)
		(end 274.936204 -60.762388)
		(width 0.0889)
		(layer "In9.Cu")
		(net "CLK_100M_CPU0_RC_REFCLK0_DN")
	)
	(arc
		(start 260.16204 -53.313838)
		(mid 259.951327 -53.100759)
		(end 259.663184 -53.018436)
		(width 0.0889)
		(layer "In9.Cu")
		(net "CLK_100M_CPU0_RC_REFCLK0_DN")
	)
	(arc
		(start 277.143464 -62.048136)
		(mid 276.93646 -61.837272)
		(end 276.653244 -61.752988)
		(width 0.0889)
		(layer "In9.Cu")
		(net "CLK_100M_CPU0_RC_REFCLK0_DN")
	)
	(arc
		(start 275.758148 -61.257434)
		(mid 275.566506 -61.200268)
		(end 275.426424 -61.057536)
		(width 0.0889)
		(layer "In9.Cu")
		(net "CLK_100M_CPU0_RC_REFCLK0_DN")
	)
	(arc
		(start 261.87908 -54.304438)
		(mid 261.672076 -54.093574)
		(end 261.38886 -54.00929)
		(width 0.0889)
		(layer "In9.Cu")
		(net "CLK_100M_CPU0_RC_REFCLK0_DN")
	)
	(arc
		(start 263.59612 -55.295038)
		(mid 263.389116 -55.084174)
		(end 263.1059 -54.99989)
		(width 0.0889)
		(layer "In9.Cu")
		(net "CLK_100M_CPU0_RC_REFCLK0_DN")
	)
	(arc
		(start 284.69717 -67.285108)
		(mid 284.924532 -66.631852)
		(end 284.376114 -66.210434)
		(width 0.0889)
		(layer "In9.Cu")
		(net "CLK_100M_CPU0_RC_REFCLK0_DN")
	)
	(segment
		(start 288.07664 -80.174338)
		(end 287.50514 -80.174338)
		(width 0.127)
		(layer "F.Cu")
		(net "CLK_100M_CPU0_PE_REFCLK_DP")
	)
	(segment
		(start 176.972976 -84.44357)
		(end 176.365916 -84.44357)
		(width 0.127)
		(layer "F.Cu")
		(net "CLK_100M_CPU0_PE_REFCLK_DP")
	)
	(segment
		(start 176.365916 -84.44357)
		(end 176.276 -84.353654)
		(width 0.127)
		(layer "F.Cu")
		(net "CLK_100M_CPU0_PE_REFCLK_DP")
	)
	(segment
		(start 177.127408 -83.947)
		(end 177.127408 -84.289138)
		(width 0.127)
		(layer "F.Cu")
		(net "CLK_100M_CPU0_PE_REFCLK_DP")
	)
	(segment
		(start 177.127408 -84.289138)
		(end 176.972976 -84.44357)
		(width 0.127)
		(layer "F.Cu")
		(net "CLK_100M_CPU0_PE_REFCLK_DP")
	)
	(segment
		(start 176.276 -84.353654)
		(end 176.276 -83.947)
		(width 0.127)
		(layer "F.Cu")
		(net "CLK_100M_CPU0_PE_REFCLK_DP")
	)
	(via
		(at 288.07664 -80.174338)
		(size 0.508)
		(drill 0.254)
		(layers "F.Cu" "B.Cu")
		(net "CLK_100M_CPU0_PE_REFCLK_DP")
	)
	(via
		(at 177.127408 -83.947)
		(size 0.508)
		(drill 0.254)
		(layers "F.Cu" "B.Cu")
		(net "CLK_100M_CPU0_PE_REFCLK_DP")
	)
	(segment
		(start 177.127408 -84.34705)
		(end 177.127408 -83.947)
		(width 0.127)
		(layer "B.Cu")
		(net "CLK_100M_CPU0_PE_REFCLK_DP")
	)
	(segment
		(start 176.685702 -84.419948)
		(end 177.05451 -84.419948)
		(width 0.127)
		(layer "B.Cu")
		(net "CLK_100M_CPU0_PE_REFCLK_DP")
	)
	(segment
		(start 176.212754 -83.947)
		(end 176.685702 -84.419948)
		(width 0.127)
		(layer "B.Cu")
		(net "CLK_100M_CPU0_PE_REFCLK_DP")
	)
	(segment
		(start 177.05451 -84.419948)
		(end 177.127408 -84.34705)
		(width 0.127)
		(layer "B.Cu")
		(net "CLK_100M_CPU0_PE_REFCLK_DP")
	)
	(segment
		(start 288.42335 -88.299036)
		(end 288.417 -88.309704)
		(width 0.0889)
		(layer "In9.Cu")
		(net "CLK_100M_CPU0_PE_REFCLK_DP")
	)
	(segment
		(start 200.028556 -103.86314)
		(end 197.81012 -103.86314)
		(width 0.1143)
		(layer "In9.Cu")
		(net "CLK_100M_CPU0_PE_REFCLK_DP")
	)
	(segment
		(start 285.807912 -100.913946)
		(end 285.807912 -101.180646)
		(width 0.0889)
		(layer "In9.Cu")
		(net "CLK_100M_CPU0_PE_REFCLK_DP")
	)
	(segment
		(start 288.428176 -96.2152)
		(end 288.42335 -96.223836)
		(width 0.0889)
		(layer "In9.Cu")
		(net "CLK_100M_CPU0_PE_REFCLK_DP")
	)
	(segment
		(start 193.058796 -103.834184)
		(end 192.268348 -103.043736)
		(width 0.1143)
		(layer "In9.Cu")
		(net "CLK_100M_CPU0_PE_REFCLK_DP")
	)
	(segment
		(start 244.873526 -102.820978)
		(end 242.33378 -103.872284)
		(width 0.1143)
		(layer "In9.Cu")
		(net "CLK_100M_CPU0_PE_REFCLK_DP")
	)
	(segment
		(start 285.807912 -102.167944)
		(end 285.619444 -102.356412)
		(width 0.0889)
		(layer "In9.Cu")
		(net "CLK_100M_CPU0_PE_REFCLK_DP")
	)
	(segment
		(start 288.42335 -96.223836)
		(end 288.417 -96.234504)
		(width 0.0889)
		(layer "In9.Cu")
		(net "CLK_100M_CPU0_PE_REFCLK_DP")
	)
	(segment
		(start 179.098194 -86.863936)
		(end 179.263294 -86.698836)
		(width 0.1143)
		(layer "In9.Cu")
		(net "CLK_100M_CPU0_PE_REFCLK_DP")
	)
	(segment
		(start 288.087816 -98.405188)
		(end 288.05505 -98.405188)
		(width 0.0889)
		(layer "In9.Cu")
		(net "CLK_100M_CPU0_PE_REFCLK_DP")
	)
	(segment
		(start 266.247118 -104.848406)
		(end 265.138154 -103.739442)
		(width 0.1143)
		(layer "In9.Cu")
		(net "CLK_100M_CPU0_PE_REFCLK_DP")
	)
	(segment
		(start 285.807912 -100.151946)
		(end 285.807912 -100.469446)
		(width 0.0889)
		(layer "In9.Cu")
		(net "CLK_100M_CPU0_PE_REFCLK_DP")
	)
	(segment
		(start 285.807912 -101.625146)
		(end 285.807912 -102.167944)
		(width 0.0889)
		(layer "In9.Cu")
		(net "CLK_100M_CPU0_PE_REFCLK_DP")
	)
	(segment
		(start 288.42335 -86.317836)
		(end 288.417 -86.328504)
		(width 0.0889)
		(layer "In9.Cu")
		(net "CLK_100M_CPU0_PE_REFCLK_DP")
	)
	(segment
		(start 288.428176 -93.2434)
		(end 288.42335 -93.252036)
		(width 0.0889)
		(layer "In9.Cu")
		(net "CLK_100M_CPU0_PE_REFCLK_DP")
	)
	(segment
		(start 177.127408 -84.32165)
		(end 177.127408 -83.947)
		(width 0.1143)
		(layer "In9.Cu")
		(net "CLK_100M_CPU0_PE_REFCLK_DP")
	)
	(segment
		(start 265.138154 -103.739442)
		(end 252.76302 -103.739442)
		(width 0.1143)
		(layer "In9.Cu")
		(net "CLK_100M_CPU0_PE_REFCLK_DP")
	)
	(segment
		(start 288.428176 -89.281)
		(end 288.42335 -89.289636)
		(width 0.0889)
		(layer "In9.Cu")
		(net "CLK_100M_CPU0_PE_REFCLK_DP")
	)
	(segment
		(start 285.304992 -102.670864)
		(end 285.116524 -102.859332)
		(width 0.0889)
		(layer "In9.Cu")
		(net "CLK_100M_CPU0_PE_REFCLK_DP")
	)
	(segment
		(start 288.428176 -86.3092)
		(end 288.42335 -86.317836)
		(width 0.0889)
		(layer "In9.Cu")
		(net "CLK_100M_CPU0_PE_REFCLK_DP")
	)
	(segment
		(start 285.719012 -101.269546)
		(end 285.719012 -101.536246)
		(width 0.0889)
		(layer "In9.Cu")
		(net "CLK_100M_CPU0_PE_REFCLK_DP")
	)
	(segment
		(start 283.502862 -104.400858)
		(end 283.159962 -104.400858)
		(width 0.1143)
		(layer "In9.Cu")
		(net "CLK_100M_CPU0_PE_REFCLK_DP")
	)
	(segment
		(start 285.116524 -102.859332)
		(end 284.990794 -102.859332)
		(width 0.0889)
		(layer "In9.Cu")
		(net "CLK_100M_CPU0_PE_REFCLK_DP")
	)
	(segment
		(start 285.719012 -100.558346)
		(end 285.719012 -100.825046)
		(width 0.0889)
		(layer "In9.Cu")
		(net "CLK_100M_CPU0_PE_REFCLK_DP")
	)
	(segment
		(start 286.280606 -99.679252)
		(end 286.154876 -99.679252)
		(width 0.0889)
		(layer "In9.Cu")
		(net "CLK_100M_CPU0_PE_REFCLK_DP")
	)
	(segment
		(start 285.719012 -100.825046)
		(end 285.807912 -100.913946)
		(width 0.0889)
		(layer "In9.Cu")
		(net "CLK_100M_CPU0_PE_REFCLK_DP")
	)
	(segment
		(start 288.428176 -90.2716)
		(end 288.42335 -90.280236)
		(width 0.0889)
		(layer "In9.Cu")
		(net "CLK_100M_CPU0_PE_REFCLK_DP")
	)
	(segment
		(start 285.966154 -99.993704)
		(end 285.807912 -100.151946)
		(width 0.0889)
		(layer "In9.Cu")
		(net "CLK_100M_CPU0_PE_REFCLK_DP")
	)
	(segment
		(start 282.651962 -104.235758)
		(end 282.486862 -104.400858)
		(width 0.1143)
		(layer "In9.Cu")
		(net "CLK_100M_CPU0_PE_REFCLK_DP")
	)
	(segment
		(start 285.304992 -102.545134)
		(end 285.304992 -102.670864)
		(width 0.0889)
		(layer "In9.Cu")
		(net "CLK_100M_CPU0_PE_REFCLK_DP")
	)
	(segment
		(start 288.42335 -85.327236)
		(end 288.417 -85.337904)
		(width 0.0889)
		(layer "In9.Cu")
		(net "CLK_100M_CPU0_PE_REFCLK_DP")
	)
	(segment
		(start 285.807912 -101.180646)
		(end 285.719012 -101.269546)
		(width 0.0889)
		(layer "In9.Cu")
		(net "CLK_100M_CPU0_PE_REFCLK_DP")
	)
	(segment
		(start 287.233106 -98.900234)
		(end 287.20034 -98.900234)
		(width 0.0889)
		(layer "In9.Cu")
		(net "CLK_100M_CPU0_PE_REFCLK_DP")
	)
	(segment
		(start 285.493714 -102.356412)
		(end 285.304992 -102.545134)
		(width 0.0889)
		(layer "In9.Cu")
		(net "CLK_100M_CPU0_PE_REFCLK_DP")
	)
	(segment
		(start 288.42335 -80.374236)
		(end 288.417 -80.384904)
		(width 0.0889)
		(layer "In9.Cu")
		(net "CLK_100M_CPU0_PE_REFCLK_DP")
	)
	(segment
		(start 288.42335 -92.261436)
		(end 288.417 -92.272104)
		(width 0.0889)
		(layer "In9.Cu")
		(net "CLK_100M_CPU0_PE_REFCLK_DP")
	)
	(segment
		(start 288.428176 -87.2998)
		(end 288.42335 -87.308436)
		(width 0.0889)
		(layer "In9.Cu")
		(net "CLK_100M_CPU0_PE_REFCLK_DP")
	)
	(segment
		(start 211.07019 -106.8578)
		(end 203.023216 -106.8578)
		(width 0.1143)
		(layer "In9.Cu")
		(net "CLK_100M_CPU0_PE_REFCLK_DP")
	)
	(segment
		(start 288.428176 -83.3374)
		(end 288.42335 -83.346036)
		(width 0.0889)
		(layer "In9.Cu")
		(net "CLK_100M_CPU0_PE_REFCLK_DP")
	)
	(segment
		(start 286.154876 -99.679252)
		(end 285.966154 -99.86772)
		(width 0.0889)
		(layer "In9.Cu")
		(net "CLK_100M_CPU0_PE_REFCLK_DP")
	)
	(segment
		(start 285.619444 -102.356412)
		(end 285.493714 -102.356412)
		(width 0.0889)
		(layer "In9.Cu")
		(net "CLK_100M_CPU0_PE_REFCLK_DP")
	)
	(segment
		(start 179.098194 -93.017594)
		(end 179.098194 -86.863936)
		(width 0.1143)
		(layer "In9.Cu")
		(net "CLK_100M_CPU0_PE_REFCLK_DP")
	)
	(segment
		(start 252.76302 -103.739442)
		(end 251.844556 -102.820978)
		(width 0.1143)
		(layer "In9.Cu")
		(net "CLK_100M_CPU0_PE_REFCLK_DP")
	)
	(segment
		(start 285.719012 -101.536246)
		(end 285.807912 -101.625146)
		(width 0.0889)
		(layer "In9.Cu")
		(net "CLK_100M_CPU0_PE_REFCLK_DP")
	)
	(segment
		(start 288.42335 -83.346036)
		(end 288.417 -83.356704)
		(width 0.0889)
		(layer "In9.Cu")
		(net "CLK_100M_CPU0_PE_REFCLK_DP")
	)
	(segment
		(start 284.802072 -103.048054)
		(end 284.802072 -103.173784)
		(width 0.0889)
		(layer "In9.Cu")
		(net "CLK_100M_CPU0_PE_REFCLK_DP")
	)
	(segment
		(start 288.428176 -91.2622)
		(end 288.42335 -91.270836)
		(width 0.0889)
		(layer "In9.Cu")
		(net "CLK_100M_CPU0_PE_REFCLK_DP")
	)
	(segment
		(start 284.990794 -102.859332)
		(end 284.802072 -103.048054)
		(width 0.0889)
		(layer "In9.Cu")
		(net "CLK_100M_CPU0_PE_REFCLK_DP")
	)
	(segment
		(start 203.023216 -106.8578)
		(end 200.028556 -103.86314)
		(width 0.1143)
		(layer "In9.Cu")
		(net "CLK_100M_CPU0_PE_REFCLK_DP")
	)
	(segment
		(start 288.428176 -88.2904)
		(end 288.42335 -88.299036)
		(width 0.0889)
		(layer "In9.Cu")
		(net "CLK_100M_CPU0_PE_REFCLK_DP")
	)
	(segment
		(start 197.81012 -103.86314)
		(end 197.02526 -104.648)
		(width 0.1143)
		(layer "In9.Cu")
		(net "CLK_100M_CPU0_PE_REFCLK_DP")
	)
	(segment
		(start 288.428176 -94.234)
		(end 288.42335 -94.242636)
		(width 0.0889)
		(layer "In9.Cu")
		(net "CLK_100M_CPU0_PE_REFCLK_DP")
	)
	(segment
		(start 285.966154 -99.86772)
		(end 285.966154 -99.993704)
		(width 0.0889)
		(layer "In9.Cu")
		(net "CLK_100M_CPU0_PE_REFCLK_DP")
	)
	(segment
		(start 288.42335 -89.289636)
		(end 288.417 -89.300304)
		(width 0.0889)
		(layer "In9.Cu")
		(net "CLK_100M_CPU0_PE_REFCLK_DP")
	)
	(segment
		(start 288.42335 -97.214436)
		(end 288.417 -97.225104)
		(width 0.0889)
		(layer "In9.Cu")
		(net "CLK_100M_CPU0_PE_REFCLK_DP")
	)
	(segment
		(start 288.428176 -84.328)
		(end 288.42335 -84.336636)
		(width 0.0889)
		(layer "In9.Cu")
		(net "CLK_100M_CPU0_PE_REFCLK_DP")
	)
	(segment
		(start 288.42335 -84.336636)
		(end 288.417 -84.347304)
		(width 0.0889)
		(layer "In9.Cu")
		(net "CLK_100M_CPU0_PE_REFCLK_DP")
	)
	(segment
		(start 286.62757 -99.332034)
		(end 286.280606 -99.679252)
		(width 0.0889)
		(layer "In9.Cu")
		(net "CLK_100M_CPU0_PE_REFCLK_DP")
	)
	(segment
		(start 288.42335 -90.280236)
		(end 288.417 -90.290904)
		(width 0.0889)
		(layer "In9.Cu")
		(net "CLK_100M_CPU0_PE_REFCLK_DP")
	)
	(segment
		(start 197.02526 -104.648)
		(end 195.280534 -104.648)
		(width 0.1143)
		(layer "In9.Cu")
		(net "CLK_100M_CPU0_PE_REFCLK_DP")
	)
	(segment
		(start 288.42335 -91.270836)
		(end 288.417 -91.281504)
		(width 0.0889)
		(layer "In9.Cu")
		(net "CLK_100M_CPU0_PE_REFCLK_DP")
	)
	(segment
		(start 284.299152 -103.676704)
		(end 283.832554 -104.143302)
		(width 0.0889)
		(layer "In9.Cu")
		(net "CLK_100M_CPU0_PE_REFCLK_DP")
	)
	(segment
		(start 179.098194 -86.190836)
		(end 179.098194 -85.847936)
		(width 0.1143)
		(layer "In9.Cu")
		(net "CLK_100M_CPU0_PE_REFCLK_DP")
	)
	(segment
		(start 288.417 -94.822518)
		(end 288.42335 -94.833186)
		(width 0.0889)
		(layer "In9.Cu")
		(net "CLK_100M_CPU0_PE_REFCLK_DP")
	)
	(segment
		(start 282.994862 -104.235758)
		(end 282.651962 -104.235758)
		(width 0.1143)
		(layer "In9.Cu")
		(net "CLK_100M_CPU0_PE_REFCLK_DP")
	)
	(segment
		(start 286.70631 -99.195636)
		(end 286.62757 -99.332034)
		(width 0.0889)
		(layer "In9.Cu")
		(net "CLK_100M_CPU0_PE_REFCLK_DP")
	)
	(segment
		(start 284.487874 -103.362252)
		(end 284.299152 -103.550974)
		(width 0.0889)
		(layer "In9.Cu")
		(net "CLK_100M_CPU0_PE_REFCLK_DP")
	)
	(segment
		(start 288.42335 -87.308436)
		(end 288.417 -87.319104)
		(width 0.0889)
		(layer "In9.Cu")
		(net "CLK_100M_CPU0_PE_REFCLK_DP")
	)
	(segment
		(start 283.832554 -104.143302)
		(end 283.760418 -104.143302)
		(width 0.0889)
		(layer "In9.Cu")
		(net "CLK_100M_CPU0_PE_REFCLK_DP")
	)
	(segment
		(start 284.613604 -103.362252)
		(end 284.487874 -103.362252)
		(width 0.0889)
		(layer "In9.Cu")
		(net "CLK_100M_CPU0_PE_REFCLK_DP")
	)
	(segment
		(start 288.07664 -79.836264)
		(end 288.134552 -79.778352)
		(width 0.0889)
		(layer "In9.Cu")
		(net "CLK_100M_CPU0_PE_REFCLK_DP")
	)
	(segment
		(start 194.466718 -103.834184)
		(end 193.058796 -103.834184)
		(width 0.1143)
		(layer "In9.Cu")
		(net "CLK_100M_CPU0_PE_REFCLK_DP")
	)
	(segment
		(start 282.486862 -104.400858)
		(end 280.191972 -104.400858)
		(width 0.1143)
		(layer "In9.Cu")
		(net "CLK_100M_CPU0_PE_REFCLK_DP")
	)
	(segment
		(start 283.159962 -104.400858)
		(end 282.994862 -104.235758)
		(width 0.1143)
		(layer "In9.Cu")
		(net "CLK_100M_CPU0_PE_REFCLK_DP")
	)
	(segment
		(start 288.42335 -93.252036)
		(end 288.417 -93.262704)
		(width 0.0889)
		(layer "In9.Cu")
		(net "CLK_100M_CPU0_PE_REFCLK_DP")
	)
	(segment
		(start 288.42335 -81.364836)
		(end 288.417 -81.375504)
		(width 0.0889)
		(layer "In9.Cu")
		(net "CLK_100M_CPU0_PE_REFCLK_DP")
	)
	(segment
		(start 179.263294 -86.698836)
		(end 179.263294 -86.355936)
		(width 0.1143)
		(layer "In9.Cu")
		(net "CLK_100M_CPU0_PE_REFCLK_DP")
	)
	(segment
		(start 288.07664 -80.174338)
		(end 288.07664 -79.836264)
		(width 0.0889)
		(layer "In9.Cu")
		(net "CLK_100M_CPU0_PE_REFCLK_DP")
	)
	(segment
		(start 285.807912 -100.469446)
		(end 285.719012 -100.558346)
		(width 0.0889)
		(layer "In9.Cu")
		(net "CLK_100M_CPU0_PE_REFCLK_DP")
	)
	(segment
		(start 177.686208 -84.43595)
		(end 177.241708 -84.43595)
		(width 0.1143)
		(layer "In9.Cu")
		(net "CLK_100M_CPU0_PE_REFCLK_DP")
	)
	(segment
		(start 179.098194 -85.847936)
		(end 177.686208 -84.43595)
		(width 0.1143)
		(layer "In9.Cu")
		(net "CLK_100M_CPU0_PE_REFCLK_DP")
	)
	(segment
		(start 189.124336 -103.043736)
		(end 179.098194 -93.017594)
		(width 0.1143)
		(layer "In9.Cu")
		(net "CLK_100M_CPU0_PE_REFCLK_DP")
	)
	(segment
		(start 288.428176 -85.3186)
		(end 288.42335 -85.327236)
		(width 0.0889)
		(layer "In9.Cu")
		(net "CLK_100M_CPU0_PE_REFCLK_DP")
	)
	(segment
		(start 284.299152 -103.550974)
		(end 284.299152 -103.676704)
		(width 0.0889)
		(layer "In9.Cu")
		(net "CLK_100M_CPU0_PE_REFCLK_DP")
	)
	(segment
		(start 280.191972 -104.400858)
		(end 279.744424 -104.848406)
		(width 0.1143)
		(layer "In9.Cu")
		(net "CLK_100M_CPU0_PE_REFCLK_DP")
	)
	(segment
		(start 251.844556 -102.820978)
		(end 244.873526 -102.820978)
		(width 0.1143)
		(layer "In9.Cu")
		(net "CLK_100M_CPU0_PE_REFCLK_DP")
	)
	(segment
		(start 279.744424 -104.848406)
		(end 266.247118 -104.848406)
		(width 0.1143)
		(layer "In9.Cu")
		(net "CLK_100M_CPU0_PE_REFCLK_DP")
	)
	(segment
		(start 242.33378 -103.872284)
		(end 224.095564 -103.872284)
		(width 0.1143)
		(layer "In9.Cu")
		(net "CLK_100M_CPU0_PE_REFCLK_DP")
	)
	(segment
		(start 288.428176 -80.3656)
		(end 288.42335 -80.374236)
		(width 0.0889)
		(layer "In9.Cu")
		(net "CLK_100M_CPU0_PE_REFCLK_DP")
	)
	(segment
		(start 288.428176 -97.2058)
		(end 288.42335 -97.214436)
		(width 0.0889)
		(layer "In9.Cu")
		(net "CLK_100M_CPU0_PE_REFCLK_DP")
	)
	(segment
		(start 177.241708 -84.43595)
		(end 177.127408 -84.32165)
		(width 0.1143)
		(layer "In9.Cu")
		(net "CLK_100M_CPU0_PE_REFCLK_DP")
	)
	(segment
		(start 288.428176 -92.2528)
		(end 288.42335 -92.261436)
		(width 0.0889)
		(layer "In9.Cu")
		(net "CLK_100M_CPU0_PE_REFCLK_DP")
	)
	(segment
		(start 192.268348 -103.043736)
		(end 189.124336 -103.043736)
		(width 0.1143)
		(layer "In9.Cu")
		(net "CLK_100M_CPU0_PE_REFCLK_DP")
	)
	(segment
		(start 224.095564 -103.872284)
		(end 211.07019 -106.8578)
		(width 0.1143)
		(layer "In9.Cu")
		(net "CLK_100M_CPU0_PE_REFCLK_DP")
	)
	(segment
		(start 284.802072 -103.173784)
		(end 284.613604 -103.362252)
		(width 0.0889)
		(layer "In9.Cu")
		(net "CLK_100M_CPU0_PE_REFCLK_DP")
	)
	(segment
		(start 283.74467 -104.15905)
		(end 283.502862 -104.400858)
		(width 0.1143)
		(layer "In9.Cu")
		(net "CLK_100M_CPU0_PE_REFCLK_DP")
	)
	(segment
		(start 179.263294 -86.355936)
		(end 179.098194 -86.190836)
		(width 0.1143)
		(layer "In9.Cu")
		(net "CLK_100M_CPU0_PE_REFCLK_DP")
	)
	(segment
		(start 283.760418 -104.143302)
		(end 283.74467 -104.15905)
		(width 0.0889)
		(layer "In9.Cu")
		(net "CLK_100M_CPU0_PE_REFCLK_DP")
	)
	(segment
		(start 195.280534 -104.648)
		(end 194.466718 -103.834184)
		(width 0.1143)
		(layer "In9.Cu")
		(net "CLK_100M_CPU0_PE_REFCLK_DP")
	)
	(segment
		(start 288.428176 -81.3562)
		(end 288.42335 -81.364836)
		(width 0.0889)
		(layer "In9.Cu")
		(net "CLK_100M_CPU0_PE_REFCLK_DP")
	)
	(arc
		(start 288.417 -88.309704)
		(mid 288.344202 -88.600467)
		(end 288.42335 -88.889586)
		(width 0.0889)
		(layer "In9.Cu")
		(net "CLK_100M_CPU0_PE_REFCLK_DP")
	)
	(arc
		(start 288.42335 -80.964786)
		(mid 288.47682 -81.159849)
		(end 288.428176 -81.3562)
		(width 0.0889)
		(layer "In9.Cu")
		(net "CLK_100M_CPU0_PE_REFCLK_DP")
	)
	(arc
		(start 288.417 -93.262704)
		(mid 288.344202 -93.553467)
		(end 288.42335 -93.842586)
		(width 0.0889)
		(layer "In9.Cu")
		(net "CLK_100M_CPU0_PE_REFCLK_DP")
	)
	(arc
		(start 288.417 -91.281504)
		(mid 288.344202 -91.572267)
		(end 288.42335 -91.861386)
		(width 0.0889)
		(layer "In9.Cu")
		(net "CLK_100M_CPU0_PE_REFCLK_DP")
	)
	(arc
		(start 288.42335 -95.823786)
		(mid 288.47682 -96.018849)
		(end 288.428176 -96.2152)
		(width 0.0889)
		(layer "In9.Cu")
		(net "CLK_100M_CPU0_PE_REFCLK_DP")
	)
	(arc
		(start 288.05505 -98.405188)
		(mid 287.771833 -98.489469)
		(end 287.56483 -98.700336)
		(width 0.0889)
		(layer "In9.Cu")
		(net "CLK_100M_CPU0_PE_REFCLK_DP")
	)
	(arc
		(start 287.20034 -98.900234)
		(mid 286.914916 -98.983701)
		(end 286.70631 -99.195636)
		(width 0.0889)
		(layer "In9.Cu")
		(net "CLK_100M_CPU0_PE_REFCLK_DP")
	)
	(arc
		(start 288.42335 -92.851986)
		(mid 288.47682 -93.047049)
		(end 288.428176 -93.2434)
		(width 0.0889)
		(layer "In9.Cu")
		(net "CLK_100M_CPU0_PE_REFCLK_DP")
	)
	(arc
		(start 288.42335 -95.232982)
		(mid 288.344219 -95.528384)
		(end 288.42335 -95.823786)
		(width 0.0889)
		(layer "In9.Cu")
		(net "CLK_100M_CPU0_PE_REFCLK_DP")
	)
	(arc
		(start 288.417 -86.328504)
		(mid 288.344202 -86.619267)
		(end 288.42335 -86.908386)
		(width 0.0889)
		(layer "In9.Cu")
		(net "CLK_100M_CPU0_PE_REFCLK_DP")
	)
	(arc
		(start 288.42335 -84.927186)
		(mid 288.47682 -85.122249)
		(end 288.428176 -85.3186)
		(width 0.0889)
		(layer "In9.Cu")
		(net "CLK_100M_CPU0_PE_REFCLK_DP")
	)
	(arc
		(start 288.417 -89.300304)
		(mid 288.344202 -89.591067)
		(end 288.42335 -89.880186)
		(width 0.0889)
		(layer "In9.Cu")
		(net "CLK_100M_CPU0_PE_REFCLK_DP")
	)
	(arc
		(start 288.42335 -88.889586)
		(mid 288.47682 -89.084649)
		(end 288.428176 -89.281)
		(width 0.0889)
		(layer "In9.Cu")
		(net "CLK_100M_CPU0_PE_REFCLK_DP")
	)
	(arc
		(start 288.417 -80.384904)
		(mid 288.344202 -80.675667)
		(end 288.42335 -80.964786)
		(width 0.0889)
		(layer "In9.Cu")
		(net "CLK_100M_CPU0_PE_REFCLK_DP")
	)
	(arc
		(start 288.42335 -86.908386)
		(mid 288.47682 -87.103449)
		(end 288.428176 -87.2998)
		(width 0.0889)
		(layer "In9.Cu")
		(net "CLK_100M_CPU0_PE_REFCLK_DP")
	)
	(arc
		(start 288.417 -90.290904)
		(mid 288.344202 -90.581667)
		(end 288.42335 -90.870786)
		(width 0.0889)
		(layer "In9.Cu")
		(net "CLK_100M_CPU0_PE_REFCLK_DP")
	)
	(arc
		(start 288.42335 -85.917786)
		(mid 288.47682 -86.112849)
		(end 288.428176 -86.3092)
		(width 0.0889)
		(layer "In9.Cu")
		(net "CLK_100M_CPU0_PE_REFCLK_DP")
	)
	(arc
		(start 288.42335 -94.242636)
		(mid 288.344128 -94.531754)
		(end 288.417 -94.822518)
		(width 0.0889)
		(layer "In9.Cu")
		(net "CLK_100M_CPU0_PE_REFCLK_DP")
	)
	(arc
		(start 288.42335 -82.945986)
		(mid 288.47682 -83.141049)
		(end 288.428176 -83.3374)
		(width 0.0889)
		(layer "In9.Cu")
		(net "CLK_100M_CPU0_PE_REFCLK_DP")
	)
	(arc
		(start 288.417 -84.347304)
		(mid 288.344202 -84.638067)
		(end 288.42335 -84.927186)
		(width 0.0889)
		(layer "In9.Cu")
		(net "CLK_100M_CPU0_PE_REFCLK_DP")
	)
	(arc
		(start 288.417 -85.337904)
		(mid 288.344202 -85.628667)
		(end 288.42335 -85.917786)
		(width 0.0889)
		(layer "In9.Cu")
		(net "CLK_100M_CPU0_PE_REFCLK_DP")
	)
	(arc
		(start 288.42335 -82.355182)
		(mid 288.344219 -82.650584)
		(end 288.42335 -82.945986)
		(width 0.0889)
		(layer "In9.Cu")
		(net "CLK_100M_CPU0_PE_REFCLK_DP")
	)
	(arc
		(start 288.417 -83.356704)
		(mid 288.344202 -83.647467)
		(end 288.42335 -83.936586)
		(width 0.0889)
		(layer "In9.Cu")
		(net "CLK_100M_CPU0_PE_REFCLK_DP")
	)
	(arc
		(start 287.56483 -98.700336)
		(mid 287.424751 -98.843072)
		(end 287.233106 -98.900234)
		(width 0.0889)
		(layer "In9.Cu")
		(net "CLK_100M_CPU0_PE_REFCLK_DP")
	)
	(arc
		(start 288.42335 -83.936586)
		(mid 288.47682 -84.131649)
		(end 288.428176 -84.328)
		(width 0.0889)
		(layer "In9.Cu")
		(net "CLK_100M_CPU0_PE_REFCLK_DP")
	)
	(arc
		(start 288.417 -87.319104)
		(mid 288.344202 -87.609867)
		(end 288.42335 -87.898986)
		(width 0.0889)
		(layer "In9.Cu")
		(net "CLK_100M_CPU0_PE_REFCLK_DP")
	)
	(arc
		(start 288.42335 -81.955386)
		(mid 288.476849 -82.155284)
		(end 288.42335 -82.355182)
		(width 0.0889)
		(layer "In9.Cu")
		(net "CLK_100M_CPU0_PE_REFCLK_DP")
	)
	(arc
		(start 288.42335 -90.870786)
		(mid 288.47682 -91.065849)
		(end 288.428176 -91.2622)
		(width 0.0889)
		(layer "In9.Cu")
		(net "CLK_100M_CPU0_PE_REFCLK_DP")
	)
	(arc
		(start 288.42335 -89.880186)
		(mid 288.47682 -90.075249)
		(end 288.428176 -90.2716)
		(width 0.0889)
		(layer "In9.Cu")
		(net "CLK_100M_CPU0_PE_REFCLK_DP")
	)
	(arc
		(start 288.417 -92.272104)
		(mid 288.344202 -92.562867)
		(end 288.42335 -92.851986)
		(width 0.0889)
		(layer "In9.Cu")
		(net "CLK_100M_CPU0_PE_REFCLK_DP")
	)
	(arc
		(start 288.42335 -96.814386)
		(mid 288.47682 -97.009449)
		(end 288.428176 -97.2058)
		(width 0.0889)
		(layer "In9.Cu")
		(net "CLK_100M_CPU0_PE_REFCLK_DP")
	)
	(arc
		(start 288.417 -81.375504)
		(mid 288.344202 -81.666267)
		(end 288.42335 -81.955386)
		(width 0.0889)
		(layer "In9.Cu")
		(net "CLK_100M_CPU0_PE_REFCLK_DP")
	)
	(arc
		(start 288.134552 -79.778352)
		(mid 288.434588 -79.995364)
		(end 288.428176 -80.3656)
		(width 0.0889)
		(layer "In9.Cu")
		(net "CLK_100M_CPU0_PE_REFCLK_DP")
	)
	(arc
		(start 288.42335 -91.861386)
		(mid 288.47682 -92.056449)
		(end 288.428176 -92.2528)
		(width 0.0889)
		(layer "In9.Cu")
		(net "CLK_100M_CPU0_PE_REFCLK_DP")
	)
	(arc
		(start 288.42335 -93.842586)
		(mid 288.47682 -94.037649)
		(end 288.428176 -94.234)
		(width 0.0889)
		(layer "In9.Cu")
		(net "CLK_100M_CPU0_PE_REFCLK_DP")
	)
	(arc
		(start 288.42335 -87.898986)
		(mid 288.47682 -88.094049)
		(end 288.428176 -88.2904)
		(width 0.0889)
		(layer "In9.Cu")
		(net "CLK_100M_CPU0_PE_REFCLK_DP")
	)
	(arc
		(start 288.42335 -94.833186)
		(mid 288.476849 -95.033084)
		(end 288.42335 -95.232982)
		(width 0.0889)
		(layer "In9.Cu")
		(net "CLK_100M_CPU0_PE_REFCLK_DP")
	)
	(arc
		(start 288.417 -97.225104)
		(mid 288.344202 -97.515867)
		(end 288.42335 -97.804986)
		(width 0.0889)
		(layer "In9.Cu")
		(net "CLK_100M_CPU0_PE_REFCLK_DP")
	)
	(arc
		(start 288.42335 -97.804986)
		(mid 288.426098 -98.200453)
		(end 288.087816 -98.405188)
		(width 0.0889)
		(layer "In9.Cu")
		(net "CLK_100M_CPU0_PE_REFCLK_DP")
	)
	(arc
		(start 288.417 -96.234504)
		(mid 288.344202 -96.525267)
		(end 288.42335 -96.814386)
		(width 0.0889)
		(layer "In9.Cu")
		(net "CLK_100M_CPU0_PE_REFCLK_DP")
	)
	(segment
		(start 176.276 -84.842096)
		(end 176.276 -85.217)
		(width 0.127)
		(layer "F.Cu")
		(net "CLK_100M_CPU0_PE_REFCLK_DN")
	)
	(segment
		(start 288.07664 -79.183738)
		(end 287.50514 -79.183738)
		(width 0.127)
		(layer "F.Cu")
		(net "CLK_100M_CPU0_PE_REFCLK_DN")
	)
	(segment
		(start 177.027078 -84.74837)
		(end 176.369726 -84.74837)
		(width 0.127)
		(layer "F.Cu")
		(net "CLK_100M_CPU0_PE_REFCLK_DN")
	)
	(segment
		(start 177.127408 -85.217)
		(end 177.127408 -84.8487)
		(width 0.127)
		(layer "F.Cu")
		(net "CLK_100M_CPU0_PE_REFCLK_DN")
	)
	(segment
		(start 176.369726 -84.74837)
		(end 176.276 -84.842096)
		(width 0.127)
		(layer "F.Cu")
		(net "CLK_100M_CPU0_PE_REFCLK_DN")
	)
	(segment
		(start 177.127408 -84.8487)
		(end 177.027078 -84.74837)
		(width 0.127)
		(layer "F.Cu")
		(net "CLK_100M_CPU0_PE_REFCLK_DN")
	)
	(via
		(at 177.127408 -85.217)
		(size 0.508)
		(drill 0.254)
		(layers "F.Cu" "B.Cu")
		(net "CLK_100M_CPU0_PE_REFCLK_DN")
	)
	(via
		(at 288.07664 -79.183738)
		(size 0.508)
		(drill 0.254)
		(layers "F.Cu" "B.Cu")
		(net "CLK_100M_CPU0_PE_REFCLK_DN")
	)
	(segment
		(start 176.705006 -84.724748)
		(end 177.013108 -84.724748)
		(width 0.127)
		(layer "B.Cu")
		(net "CLK_100M_CPU0_PE_REFCLK_DN")
	)
	(segment
		(start 177.127408 -84.839048)
		(end 177.127408 -85.217)
		(width 0.127)
		(layer "B.Cu")
		(net "CLK_100M_CPU0_PE_REFCLK_DN")
	)
	(segment
		(start 176.212754 -85.217)
		(end 176.705006 -84.724748)
		(width 0.127)
		(layer "B.Cu")
		(net "CLK_100M_CPU0_PE_REFCLK_DN")
	)
	(segment
		(start 177.013108 -84.724748)
		(end 177.127408 -84.839048)
		(width 0.127)
		(layer "B.Cu")
		(net "CLK_100M_CPU0_PE_REFCLK_DN")
	)
	(segment
		(start 288.58845 -89.384886)
		(end 288.583624 -89.393522)
		(width 0.0889)
		(layer "In9.Cu")
		(net "CLK_100M_CPU0_PE_REFCLK_DN")
	)
	(segment
		(start 288.58845 -92.356686)
		(end 288.583624 -92.365322)
		(width 0.0889)
		(layer "In9.Cu")
		(net "CLK_100M_CPU0_PE_REFCLK_DN")
	)
	(segment
		(start 285.998412 -102.246938)
		(end 283.967174 -104.278176)
		(width 0.0889)
		(layer "In9.Cu")
		(net "CLK_100M_CPU0_PE_REFCLK_DN")
	)
	(segment
		(start 283.967174 -104.27843)
		(end 283.96692 -104.27843)
		(width 0.0889)
		(layer "In9.Cu")
		(net "CLK_100M_CPU0_PE_REFCLK_DN")
	)
	(segment
		(start 288.09442 -98.595688)
		(end 288.061654 -98.595688)
		(width 0.0889)
		(layer "In9.Cu")
		(net "CLK_100M_CPU0_PE_REFCLK_DN")
	)
	(segment
		(start 288.5948 -86.402418)
		(end 288.58845 -86.413086)
		(width 0.0889)
		(layer "In9.Cu")
		(net "CLK_100M_CPU0_PE_REFCLK_DN")
	)
	(segment
		(start 288.58845 -82.450686)
		(end 288.583624 -82.459322)
		(width 0.0889)
		(layer "In9.Cu")
		(net "CLK_100M_CPU0_PE_REFCLK_DN")
	)
	(segment
		(start 288.5948 -96.308418)
		(end 288.58845 -96.319086)
		(width 0.0889)
		(layer "In9.Cu")
		(net "CLK_100M_CPU0_PE_REFCLK_DN")
	)
	(segment
		(start 283.96692 -104.350058)
		(end 283.951426 -104.365552)
		(width 0.0889)
		(layer "In9.Cu")
		(net "CLK_100M_CPU0_PE_REFCLK_DN")
	)
	(segment
		(start 288.5948 -90.364818)
		(end 288.58845 -90.375486)
		(width 0.0889)
		(layer "In9.Cu")
		(net "CLK_100M_CPU0_PE_REFCLK_DN")
	)
	(segment
		(start 288.58845 -84.431886)
		(end 288.583624 -84.440522)
		(width 0.0889)
		(layer "In9.Cu")
		(net "CLK_100M_CPU0_PE_REFCLK_DN")
	)
	(segment
		(start 202.902058 -107.1499)
		(end 199.907398 -104.15524)
		(width 0.1143)
		(layer "In9.Cu")
		(net "CLK_100M_CPU0_PE_REFCLK_DN")
	)
	(segment
		(start 288.5948 -89.374218)
		(end 288.58845 -89.384886)
		(width 0.0889)
		(layer "In9.Cu")
		(net "CLK_100M_CPU0_PE_REFCLK_DN")
	)
	(segment
		(start 192.14719 -103.335836)
		(end 189.003178 -103.335836)
		(width 0.1143)
		(layer "In9.Cu")
		(net "CLK_100M_CPU0_PE_REFCLK_DN")
	)
	(segment
		(start 287.23971 -99.090734)
		(end 287.206944 -99.090734)
		(width 0.0889)
		(layer "In9.Cu")
		(net "CLK_100M_CPU0_PE_REFCLK_DN")
	)
	(segment
		(start 242.391946 -104.164384)
		(end 224.128838 -104.164384)
		(width 0.1143)
		(layer "In9.Cu")
		(net "CLK_100M_CPU0_PE_REFCLK_DN")
	)
	(segment
		(start 286.87141 -99.290886)
		(end 286.77997 -99.449382)
		(width 0.0889)
		(layer "In9.Cu")
		(net "CLK_100M_CPU0_PE_REFCLK_DN")
	)
	(segment
		(start 286.77997 -99.449382)
		(end 285.998412 -100.23094)
		(width 0.0889)
		(layer "In9.Cu")
		(net "CLK_100M_CPU0_PE_REFCLK_DN")
	)
	(segment
		(start 283.967174 -104.278176)
		(end 283.967174 -104.27843)
		(width 0.0889)
		(layer "In9.Cu")
		(net "CLK_100M_CPU0_PE_REFCLK_DN")
	)
	(segment
		(start 266.12596 -105.140506)
		(end 265.016996 -104.031542)
		(width 0.1143)
		(layer "In9.Cu")
		(net "CLK_100M_CPU0_PE_REFCLK_DN")
	)
	(segment
		(start 288.5948 -83.430618)
		(end 288.58845 -83.441286)
		(width 0.0889)
		(layer "In9.Cu")
		(net "CLK_100M_CPU0_PE_REFCLK_DN")
	)
	(segment
		(start 197.146418 -104.9401)
		(end 195.159376 -104.9401)
		(width 0.1143)
		(layer "In9.Cu")
		(net "CLK_100M_CPU0_PE_REFCLK_DN")
	)
	(segment
		(start 288.58845 -96.319086)
		(end 288.583624 -96.327722)
		(width 0.0889)
		(layer "In9.Cu")
		(net "CLK_100M_CPU0_PE_REFCLK_DN")
	)
	(segment
		(start 288.5948 -93.336618)
		(end 288.58845 -93.347286)
		(width 0.0889)
		(layer "In9.Cu")
		(net "CLK_100M_CPU0_PE_REFCLK_DN")
	)
	(segment
		(start 288.5948 -91.355418)
		(end 288.58845 -91.366086)
		(width 0.0889)
		(layer "In9.Cu")
		(net "CLK_100M_CPU0_PE_REFCLK_DN")
	)
	(segment
		(start 288.58845 -86.413086)
		(end 288.583624 -86.421722)
		(width 0.0889)
		(layer "In9.Cu")
		(net "CLK_100M_CPU0_PE_REFCLK_DN")
	)
	(segment
		(start 288.58845 -83.441286)
		(end 288.583624 -83.449922)
		(width 0.0889)
		(layer "In9.Cu")
		(net "CLK_100M_CPU0_PE_REFCLK_DN")
	)
	(segment
		(start 288.5948 -80.458818)
		(end 288.58845 -80.469486)
		(width 0.0889)
		(layer "In9.Cu")
		(net "CLK_100M_CPU0_PE_REFCLK_DN")
	)
	(segment
		(start 195.159376 -104.9401)
		(end 194.34556 -104.126284)
		(width 0.1143)
		(layer "In9.Cu")
		(net "CLK_100M_CPU0_PE_REFCLK_DN")
	)
	(segment
		(start 194.34556 -104.126284)
		(end 192.937638 -104.126284)
		(width 0.1143)
		(layer "In9.Cu")
		(net "CLK_100M_CPU0_PE_REFCLK_DN")
	)
	(segment
		(start 285.998412 -100.23094)
		(end 285.998412 -102.246938)
		(width 0.0889)
		(layer "In9.Cu")
		(net "CLK_100M_CPU0_PE_REFCLK_DN")
	)
	(segment
		(start 288.58845 -85.422486)
		(end 288.583624 -85.431122)
		(width 0.0889)
		(layer "In9.Cu")
		(net "CLK_100M_CPU0_PE_REFCLK_DN")
	)
	(segment
		(start 178.806094 -85.969094)
		(end 177.56505 -84.72805)
		(width 0.1143)
		(layer "In9.Cu")
		(net "CLK_100M_CPU0_PE_REFCLK_DN")
	)
	(segment
		(start 211.103464 -107.1499)
		(end 202.902058 -107.1499)
		(width 0.1143)
		(layer "In9.Cu")
		(net "CLK_100M_CPU0_PE_REFCLK_DN")
	)
	(segment
		(start 189.003178 -103.335836)
		(end 178.806094 -93.138752)
		(width 0.1143)
		(layer "In9.Cu")
		(net "CLK_100M_CPU0_PE_REFCLK_DN")
	)
	(segment
		(start 288.07664 -79.183738)
		(end 288.07664 -79.521812)
		(width 0.0889)
		(layer "In9.Cu")
		(net "CLK_100M_CPU0_PE_REFCLK_DN")
	)
	(segment
		(start 288.5948 -87.393018)
		(end 288.58845 -87.403686)
		(width 0.0889)
		(layer "In9.Cu")
		(net "CLK_100M_CPU0_PE_REFCLK_DN")
	)
	(segment
		(start 177.241708 -84.72805)
		(end 177.127408 -84.84235)
		(width 0.1143)
		(layer "In9.Cu")
		(net "CLK_100M_CPU0_PE_REFCLK_DN")
	)
	(segment
		(start 244.931692 -103.113078)
		(end 242.391946 -104.164384)
		(width 0.1143)
		(layer "In9.Cu")
		(net "CLK_100M_CPU0_PE_REFCLK_DN")
	)
	(segment
		(start 197.931278 -104.15524)
		(end 197.146418 -104.9401)
		(width 0.1143)
		(layer "In9.Cu")
		(net "CLK_100M_CPU0_PE_REFCLK_DN")
	)
	(segment
		(start 265.016996 -104.031542)
		(end 252.641862 -104.031542)
		(width 0.1143)
		(layer "In9.Cu")
		(net "CLK_100M_CPU0_PE_REFCLK_DN")
	)
	(segment
		(start 288.58845 -95.328486)
		(end 288.583624 -95.337122)
		(width 0.0889)
		(layer "In9.Cu")
		(net "CLK_100M_CPU0_PE_REFCLK_DN")
	)
	(segment
		(start 288.58845 -94.737936)
		(end 288.5948 -94.748604)
		(width 0.0889)
		(layer "In9.Cu")
		(net "CLK_100M_CPU0_PE_REFCLK_DN")
	)
	(segment
		(start 288.58845 -93.347286)
		(end 288.583624 -93.355922)
		(width 0.0889)
		(layer "In9.Cu")
		(net "CLK_100M_CPU0_PE_REFCLK_DN")
	)
	(segment
		(start 288.58845 -97.309686)
		(end 288.583624 -97.318322)
		(width 0.0889)
		(layer "In9.Cu")
		(net "CLK_100M_CPU0_PE_REFCLK_DN")
	)
	(segment
		(start 288.5948 -81.449418)
		(end 288.58845 -81.460086)
		(width 0.0889)
		(layer "In9.Cu")
		(net "CLK_100M_CPU0_PE_REFCLK_DN")
	)
	(segment
		(start 288.5948 -85.411818)
		(end 288.58845 -85.422486)
		(width 0.0889)
		(layer "In9.Cu")
		(net "CLK_100M_CPU0_PE_REFCLK_DN")
	)
	(segment
		(start 288.58845 -88.394286)
		(end 288.583624 -88.402922)
		(width 0.0889)
		(layer "In9.Cu")
		(net "CLK_100M_CPU0_PE_REFCLK_DN")
	)
	(segment
		(start 288.5948 -84.421218)
		(end 288.58845 -84.431886)
		(width 0.0889)
		(layer "In9.Cu")
		(net "CLK_100M_CPU0_PE_REFCLK_DN")
	)
	(segment
		(start 288.07664 -79.521812)
		(end 288.141664 -79.586836)
		(width 0.0889)
		(layer "In9.Cu")
		(net "CLK_100M_CPU0_PE_REFCLK_DN")
	)
	(segment
		(start 288.58845 -80.469486)
		(end 288.583624 -80.478122)
		(width 0.0889)
		(layer "In9.Cu")
		(net "CLK_100M_CPU0_PE_REFCLK_DN")
	)
	(segment
		(start 283.96692 -104.27843)
		(end 283.96692 -104.350058)
		(width 0.0889)
		(layer "In9.Cu")
		(net "CLK_100M_CPU0_PE_REFCLK_DN")
	)
	(segment
		(start 252.641862 -104.031542)
		(end 251.723398 -103.113078)
		(width 0.1143)
		(layer "In9.Cu")
		(net "CLK_100M_CPU0_PE_REFCLK_DN")
	)
	(segment
		(start 177.56505 -84.72805)
		(end 177.241708 -84.72805)
		(width 0.1143)
		(layer "In9.Cu")
		(net "CLK_100M_CPU0_PE_REFCLK_DN")
	)
	(segment
		(start 288.58845 -90.375486)
		(end 288.583624 -90.384122)
		(width 0.0889)
		(layer "In9.Cu")
		(net "CLK_100M_CPU0_PE_REFCLK_DN")
	)
	(segment
		(start 251.723398 -103.113078)
		(end 244.931692 -103.113078)
		(width 0.1143)
		(layer "In9.Cu")
		(net "CLK_100M_CPU0_PE_REFCLK_DN")
	)
	(segment
		(start 199.907398 -104.15524)
		(end 197.931278 -104.15524)
		(width 0.1143)
		(layer "In9.Cu")
		(net "CLK_100M_CPU0_PE_REFCLK_DN")
	)
	(segment
		(start 288.5948 -92.346018)
		(end 288.58845 -92.356686)
		(width 0.0889)
		(layer "In9.Cu")
		(net "CLK_100M_CPU0_PE_REFCLK_DN")
	)
	(segment
		(start 279.865582 -105.140506)
		(end 266.12596 -105.140506)
		(width 0.1143)
		(layer "In9.Cu")
		(net "CLK_100M_CPU0_PE_REFCLK_DN")
	)
	(segment
		(start 280.31313 -104.692958)
		(end 279.865582 -105.140506)
		(width 0.1143)
		(layer "In9.Cu")
		(net "CLK_100M_CPU0_PE_REFCLK_DN")
	)
	(segment
		(start 288.5948 -88.383618)
		(end 288.58845 -88.394286)
		(width 0.0889)
		(layer "In9.Cu")
		(net "CLK_100M_CPU0_PE_REFCLK_DN")
	)
	(segment
		(start 224.128838 -104.164384)
		(end 211.103464 -107.1499)
		(width 0.1143)
		(layer "In9.Cu")
		(net "CLK_100M_CPU0_PE_REFCLK_DN")
	)
	(segment
		(start 192.937638 -104.126284)
		(end 192.14719 -103.335836)
		(width 0.1143)
		(layer "In9.Cu")
		(net "CLK_100M_CPU0_PE_REFCLK_DN")
	)
	(segment
		(start 177.127408 -84.84235)
		(end 177.127408 -85.217)
		(width 0.1143)
		(layer "In9.Cu")
		(net "CLK_100M_CPU0_PE_REFCLK_DN")
	)
	(segment
		(start 288.58845 -91.366086)
		(end 288.583624 -91.374722)
		(width 0.0889)
		(layer "In9.Cu")
		(net "CLK_100M_CPU0_PE_REFCLK_DN")
	)
	(segment
		(start 288.5948 -97.299018)
		(end 288.58845 -97.309686)
		(width 0.0889)
		(layer "In9.Cu")
		(net "CLK_100M_CPU0_PE_REFCLK_DN")
	)
	(segment
		(start 283.62402 -104.692958)
		(end 280.31313 -104.692958)
		(width 0.1143)
		(layer "In9.Cu")
		(net "CLK_100M_CPU0_PE_REFCLK_DN")
	)
	(segment
		(start 178.806094 -93.138752)
		(end 178.806094 -85.969094)
		(width 0.1143)
		(layer "In9.Cu")
		(net "CLK_100M_CPU0_PE_REFCLK_DN")
	)
	(segment
		(start 283.951426 -104.365552)
		(end 283.62402 -104.692958)
		(width 0.1143)
		(layer "In9.Cu")
		(net "CLK_100M_CPU0_PE_REFCLK_DN")
	)
	(segment
		(start 288.58845 -87.403686)
		(end 288.583624 -87.412322)
		(width 0.0889)
		(layer "In9.Cu")
		(net "CLK_100M_CPU0_PE_REFCLK_DN")
	)
	(arc
		(start 288.58845 -89.784936)
		(mid 288.667672 -90.074054)
		(end 288.5948 -90.364818)
		(width 0.0889)
		(layer "In9.Cu")
		(net "CLK_100M_CPU0_PE_REFCLK_DN")
	)
	(arc
		(start 288.58845 -86.813136)
		(mid 288.667672 -87.102254)
		(end 288.5948 -87.393018)
		(width 0.0889)
		(layer "In9.Cu")
		(net "CLK_100M_CPU0_PE_REFCLK_DN")
	)
	(arc
		(start 288.58845 -85.822536)
		(mid 288.667672 -86.111654)
		(end 288.5948 -86.402418)
		(width 0.0889)
		(layer "In9.Cu")
		(net "CLK_100M_CPU0_PE_REFCLK_DN")
	)
	(arc
		(start 288.583624 -83.449922)
		(mid 288.534869 -83.646274)
		(end 288.58845 -83.841336)
		(width 0.0889)
		(layer "In9.Cu")
		(net "CLK_100M_CPU0_PE_REFCLK_DN")
	)
	(arc
		(start 288.58845 -87.803736)
		(mid 288.667672 -88.092854)
		(end 288.5948 -88.383618)
		(width 0.0889)
		(layer "In9.Cu")
		(net "CLK_100M_CPU0_PE_REFCLK_DN")
	)
	(arc
		(start 288.583624 -90.384122)
		(mid 288.534869 -90.580474)
		(end 288.58845 -90.775536)
		(width 0.0889)
		(layer "In9.Cu")
		(net "CLK_100M_CPU0_PE_REFCLK_DN")
	)
	(arc
		(start 288.583624 -96.327722)
		(mid 288.534869 -96.524074)
		(end 288.58845 -96.719136)
		(width 0.0889)
		(layer "In9.Cu")
		(net "CLK_100M_CPU0_PE_REFCLK_DN")
	)
	(arc
		(start 288.141664 -79.586836)
		(mid 288.601141 -79.901785)
		(end 288.5948 -80.458818)
		(width 0.0889)
		(layer "In9.Cu")
		(net "CLK_100M_CPU0_PE_REFCLK_DN")
	)
	(arc
		(start 288.58845 -96.719136)
		(mid 288.667672 -97.008254)
		(end 288.5948 -97.299018)
		(width 0.0889)
		(layer "In9.Cu")
		(net "CLK_100M_CPU0_PE_REFCLK_DN")
	)
	(arc
		(start 288.58845 -81.859882)
		(mid 288.667581 -82.155284)
		(end 288.58845 -82.450686)
		(width 0.0889)
		(layer "In9.Cu")
		(net "CLK_100M_CPU0_PE_REFCLK_DN")
	)
	(arc
		(start 288.58845 -97.709736)
		(mid 288.592779 -98.292908)
		(end 288.09442 -98.595688)
		(width 0.0889)
		(layer "In9.Cu")
		(net "CLK_100M_CPU0_PE_REFCLK_DN")
	)
	(arc
		(start 288.583624 -93.355922)
		(mid 288.534869 -93.552274)
		(end 288.58845 -93.747336)
		(width 0.0889)
		(layer "In9.Cu")
		(net "CLK_100M_CPU0_PE_REFCLK_DN")
	)
	(arc
		(start 288.58845 -91.766136)
		(mid 288.667672 -92.055254)
		(end 288.5948 -92.346018)
		(width 0.0889)
		(layer "In9.Cu")
		(net "CLK_100M_CPU0_PE_REFCLK_DN")
	)
	(arc
		(start 287.72993 -98.795586)
		(mid 287.522926 -99.00645)
		(end 287.23971 -99.090734)
		(width 0.0889)
		(layer "In9.Cu")
		(net "CLK_100M_CPU0_PE_REFCLK_DN")
	)
	(arc
		(start 288.58845 -93.747336)
		(mid 288.667581 -94.042738)
		(end 288.58845 -94.33814)
		(width 0.0889)
		(layer "In9.Cu")
		(net "CLK_100M_CPU0_PE_REFCLK_DN")
	)
	(arc
		(start 287.206944 -99.090734)
		(mid 287.013094 -99.147084)
		(end 286.87141 -99.290886)
		(width 0.0889)
		(layer "In9.Cu")
		(net "CLK_100M_CPU0_PE_REFCLK_DN")
	)
	(arc
		(start 288.58845 -84.831936)
		(mid 288.667672 -85.121054)
		(end 288.5948 -85.411818)
		(width 0.0889)
		(layer "In9.Cu")
		(net "CLK_100M_CPU0_PE_REFCLK_DN")
	)
	(arc
		(start 288.5948 -94.748604)
		(mid 288.667598 -95.039367)
		(end 288.58845 -95.328486)
		(width 0.0889)
		(layer "In9.Cu")
		(net "CLK_100M_CPU0_PE_REFCLK_DN")
	)
	(arc
		(start 288.583624 -82.459322)
		(mid 288.534869 -82.655674)
		(end 288.58845 -82.850736)
		(width 0.0889)
		(layer "In9.Cu")
		(net "CLK_100M_CPU0_PE_REFCLK_DN")
	)
	(arc
		(start 288.58845 -82.850736)
		(mid 288.667672 -83.139854)
		(end 288.5948 -83.430618)
		(width 0.0889)
		(layer "In9.Cu")
		(net "CLK_100M_CPU0_PE_REFCLK_DN")
	)
	(arc
		(start 288.58845 -94.33814)
		(mid 288.534951 -94.538038)
		(end 288.58845 -94.737936)
		(width 0.0889)
		(layer "In9.Cu")
		(net "CLK_100M_CPU0_PE_REFCLK_DN")
	)
	(arc
		(start 288.583624 -80.478122)
		(mid 288.534869 -80.674474)
		(end 288.58845 -80.869536)
		(width 0.0889)
		(layer "In9.Cu")
		(net "CLK_100M_CPU0_PE_REFCLK_DN")
	)
	(arc
		(start 288.58845 -80.869536)
		(mid 288.667672 -81.158654)
		(end 288.5948 -81.449418)
		(width 0.0889)
		(layer "In9.Cu")
		(net "CLK_100M_CPU0_PE_REFCLK_DN")
	)
	(arc
		(start 288.583624 -92.365322)
		(mid 288.534869 -92.561674)
		(end 288.58845 -92.756736)
		(width 0.0889)
		(layer "In9.Cu")
		(net "CLK_100M_CPU0_PE_REFCLK_DN")
	)
	(arc
		(start 288.583624 -91.374722)
		(mid 288.534869 -91.571074)
		(end 288.58845 -91.766136)
		(width 0.0889)
		(layer "In9.Cu")
		(net "CLK_100M_CPU0_PE_REFCLK_DN")
	)
	(arc
		(start 288.58845 -92.756736)
		(mid 288.667672 -93.045854)
		(end 288.5948 -93.336618)
		(width 0.0889)
		(layer "In9.Cu")
		(net "CLK_100M_CPU0_PE_REFCLK_DN")
	)
	(arc
		(start 288.061654 -98.595688)
		(mid 287.870012 -98.652854)
		(end 287.72993 -98.795586)
		(width 0.0889)
		(layer "In9.Cu")
		(net "CLK_100M_CPU0_PE_REFCLK_DN")
	)
	(arc
		(start 288.583624 -88.402922)
		(mid 288.534869 -88.599274)
		(end 288.58845 -88.794336)
		(width 0.0889)
		(layer "In9.Cu")
		(net "CLK_100M_CPU0_PE_REFCLK_DN")
	)
	(arc
		(start 288.583624 -89.393522)
		(mid 288.534869 -89.589874)
		(end 288.58845 -89.784936)
		(width 0.0889)
		(layer "In9.Cu")
		(net "CLK_100M_CPU0_PE_REFCLK_DN")
	)
	(arc
		(start 288.583624 -85.431122)
		(mid 288.534869 -85.627474)
		(end 288.58845 -85.822536)
		(width 0.0889)
		(layer "In9.Cu")
		(net "CLK_100M_CPU0_PE_REFCLK_DN")
	)
	(arc
		(start 288.58845 -81.460086)
		(mid 288.534951 -81.659984)
		(end 288.58845 -81.859882)
		(width 0.0889)
		(layer "In9.Cu")
		(net "CLK_100M_CPU0_PE_REFCLK_DN")
	)
	(arc
		(start 288.583624 -87.412322)
		(mid 288.534869 -87.608674)
		(end 288.58845 -87.803736)
		(width 0.0889)
		(layer "In9.Cu")
		(net "CLK_100M_CPU0_PE_REFCLK_DN")
	)
	(arc
		(start 288.583624 -84.440522)
		(mid 288.534869 -84.636874)
		(end 288.58845 -84.831936)
		(width 0.0889)
		(layer "In9.Cu")
		(net "CLK_100M_CPU0_PE_REFCLK_DN")
	)
	(arc
		(start 288.583624 -97.318322)
		(mid 288.534869 -97.514674)
		(end 288.58845 -97.709736)
		(width 0.0889)
		(layer "In9.Cu")
		(net "CLK_100M_CPU0_PE_REFCLK_DN")
	)
	(arc
		(start 288.58845 -95.728536)
		(mid 288.667672 -96.017654)
		(end 288.5948 -96.308418)
		(width 0.0889)
		(layer "In9.Cu")
		(net "CLK_100M_CPU0_PE_REFCLK_DN")
	)
	(arc
		(start 288.58845 -83.841336)
		(mid 288.667672 -84.130454)
		(end 288.5948 -84.421218)
		(width 0.0889)
		(layer "In9.Cu")
		(net "CLK_100M_CPU0_PE_REFCLK_DN")
	)
	(arc
		(start 288.58845 -88.794336)
		(mid 288.667672 -89.083454)
		(end 288.5948 -89.374218)
		(width 0.0889)
		(layer "In9.Cu")
		(net "CLK_100M_CPU0_PE_REFCLK_DN")
	)
	(arc
		(start 288.583624 -86.421722)
		(mid 288.534869 -86.618074)
		(end 288.58845 -86.813136)
		(width 0.0889)
		(layer "In9.Cu")
		(net "CLK_100M_CPU0_PE_REFCLK_DN")
	)
	(arc
		(start 288.583624 -95.337122)
		(mid 288.534869 -95.533474)
		(end 288.58845 -95.728536)
		(width 0.0889)
		(layer "In9.Cu")
		(net "CLK_100M_CPU0_PE_REFCLK_DN")
	)
	(arc
		(start 288.58845 -90.775536)
		(mid 288.667672 -91.064654)
		(end 288.5948 -91.355418)
		(width 0.0889)
		(layer "In9.Cu")
		(net "CLK_100M_CPU0_PE_REFCLK_DN")
	)
	(segment
		(start 170.973496 -89.206324)
		(end 170.715686 -88.948514)
		(width 0.1143)
		(layer "F.Cu")
		(net "CLK_100M_CPU0_RC_REFCLK1_DP")
	)
	(segment
		(start 171.245276 -89.206324)
		(end 170.973496 -89.206324)
		(width 0.1143)
		(layer "F.Cu")
		(net "CLK_100M_CPU0_RC_REFCLK1_DP")
	)
	(segment
		(start 170.715686 -87.919814)
		(end 170.8785 -87.757)
		(width 0.1143)
		(layer "F.Cu")
		(net "CLK_100M_CPU0_RC_REFCLK1_DP")
	)
	(segment
		(start 170.715686 -88.948514)
		(end 170.715686 -87.919814)
		(width 0.1143)
		(layer "F.Cu")
		(net "CLK_100M_CPU0_RC_REFCLK1_DP")
	)
	(segment
		(start 287.21812 -72.744584)
		(end 286.64662 -72.744584)
		(width 0.1143)
		(layer "F.Cu")
		(net "CLK_100M_CPU0_RC_REFCLK1_DP")
	)
	(segment
		(start 170.8785 -87.757)
		(end 171.196 -87.757)
		(width 0.1143)
		(layer "F.Cu")
		(net "CLK_100M_CPU0_RC_REFCLK1_DP")
	)
	(via
		(at 171.245276 -89.206324)
		(size 0.508)
		(drill 0.254)
		(layers "F.Cu" "B.Cu")
		(net "CLK_100M_CPU0_RC_REFCLK1_DP")
	)
	(via
		(at 287.21812 -72.744584)
		(size 0.508)
		(drill 0.254)
		(layers "F.Cu" "B.Cu")
		(net "CLK_100M_CPU0_RC_REFCLK1_DP")
	)
	(segment
		(start 171.196 -87.757)
		(end 170.882564 -87.757)
		(width 0.1143)
		(layer "B.Cu")
		(net "CLK_100M_CPU0_RC_REFCLK1_DP")
	)
	(segment
		(start 170.882564 -87.757)
		(end 170.663616 -87.975948)
		(width 0.1143)
		(layer "B.Cu")
		(net "CLK_100M_CPU0_RC_REFCLK1_DP")
	)
	(segment
		(start 170.663616 -87.975948)
		(end 170.663616 -88.624664)
		(width 0.1143)
		(layer "B.Cu")
		(net "CLK_100M_CPU0_RC_REFCLK1_DP")
	)
	(segment
		(start 170.663616 -88.624664)
		(end 171.245276 -89.206324)
		(width 0.1143)
		(layer "B.Cu")
		(net "CLK_100M_CPU0_RC_REFCLK1_DP")
	)
	(segment
		(start 286.70631 -70.068186)
		(end 286.70631 -70.067932)
		(width 0.0889)
		(layer "In9.Cu")
		(net "CLK_100M_CPU0_RC_REFCLK1_DP")
	)
	(segment
		(start 180.781198 -64.92748)
		(end 179.7685 -65.940178)
		(width 0.1143)
		(layer "In9.Cu")
		(net "CLK_100M_CPU0_RC_REFCLK1_DP")
	)
	(segment
		(start 258.767326 -51.570382)
		(end 257.349244 -50.1523)
		(width 0.1143)
		(layer "In9.Cu")
		(net "CLK_100M_CPU0_RC_REFCLK1_DP")
	)
	(segment
		(start 178.253644 -69.75856)
		(end 178.253644 -75.207876)
		(width 0.1143)
		(layer "In9.Cu")
		(net "CLK_100M_CPU0_RC_REFCLK1_DP")
	)
	(segment
		(start 254.301244 -50.1523)
		(end 253.958344 -50.1523)
		(width 0.1143)
		(layer "In9.Cu")
		(net "CLK_100M_CPU0_RC_REFCLK1_DP")
	)
	(segment
		(start 262.236966 -52.713636)
		(end 262.2042 -52.713636)
		(width 0.0889)
		(layer "In9.Cu")
		(net "CLK_100M_CPU0_RC_REFCLK1_DP")
	)
	(segment
		(start 208.483454 -48.9966)
		(end 207.776826 -48.289972)
		(width 0.1143)
		(layer "In9.Cu")
		(net "CLK_100M_CPU0_RC_REFCLK1_DP")
	)
	(segment
		(start 177.96383 -78.097634)
		(end 176.918112 -79.143352)
		(width 0.1143)
		(layer "In9.Cu")
		(net "CLK_100M_CPU0_RC_REFCLK1_DP")
	)
	(segment
		(start 285.55696 -66.516504)
		(end 285.56331 -66.505836)
		(width 0.0889)
		(layer "In9.Cu")
		(net "CLK_100M_CPU0_RC_REFCLK1_DP")
	)
	(segment
		(start 202.271122 -48.289972)
		(end 200.213214 -50.34788)
		(width 0.1143)
		(layer "In9.Cu")
		(net "CLK_100M_CPU0_RC_REFCLK1_DP")
	)
	(segment
		(start 261.71398 -52.418488)
		(end 261.648956 -52.305712)
		(width 0.0889)
		(layer "In9.Cu")
		(net "CLK_100M_CPU0_RC_REFCLK1_DP")
	)
	(segment
		(start 184.50052 -62.336172)
		(end 185.255408 -63.09106)
		(width 0.1143)
		(layer "In9.Cu")
		(net "CLK_100M_CPU0_RC_REFCLK1_DP")
	)
	(segment
		(start 254.809244 -50.3174)
		(end 254.466344 -50.3174)
		(width 0.1143)
		(layer "In9.Cu")
		(net "CLK_100M_CPU0_RC_REFCLK1_DP")
	)
	(segment
		(start 271.495774 -57.981088)
		(end 271.315942 -57.981088)
		(width 0.0889)
		(layer "In9.Cu")
		(net "CLK_100M_CPU0_RC_REFCLK1_DP")
	)
	(segment
		(start 286.69996 -71.469504)
		(end 286.70631 -71.458836)
		(width 0.0889)
		(layer "In9.Cu")
		(net "CLK_100M_CPU0_RC_REFCLK1_DP")
	)
	(segment
		(start 280.08072 -62.934088)
		(end 280.047954 -62.934088)
		(width 0.0889)
		(layer "In9.Cu")
		(net "CLK_100M_CPU0_RC_REFCLK1_DP")
	)
	(segment
		(start 183.83123 -59.981846)
		(end 183.83123 -61.911484)
		(width 0.1143)
		(layer "In9.Cu")
		(net "CLK_100M_CPU0_RC_REFCLK1_DP")
	)
	(segment
		(start 286.70631 -71.458836)
		(end 286.711136 -71.4502)
		(width 0.0889)
		(layer "In9.Cu")
		(net "CLK_100M_CPU0_RC_REFCLK1_DP")
	)
	(segment
		(start 253.793244 -50.3174)
		(end 253.450344 -50.3174)
		(width 0.1143)
		(layer "In9.Cu")
		(net "CLK_100M_CPU0_RC_REFCLK1_DP")
	)
	(segment
		(start 255.317244 -50.1523)
		(end 254.974344 -50.1523)
		(width 0.1143)
		(layer "In9.Cu")
		(net "CLK_100M_CPU0_RC_REFCLK1_DP")
	)
	(segment
		(start 248.8692 -50.6984)
		(end 243.522754 -50.6984)
		(width 0.1143)
		(layer "In9.Cu")
		(net "CLK_100M_CPU0_RC_REFCLK1_DP")
	)
	(segment
		(start 254.974344 -50.1523)
		(end 254.809244 -50.3174)
		(width 0.1143)
		(layer "In9.Cu")
		(net "CLK_100M_CPU0_RC_REFCLK1_DP")
	)
	(segment
		(start 170.905424 -89.206324)
		(end 171.245276 -89.206324)
		(width 0.1143)
		(layer "In9.Cu")
		(net "CLK_100M_CPU0_RC_REFCLK1_DP")
	)
	(segment
		(start 255.825244 -50.3174)
		(end 255.482344 -50.3174)
		(width 0.1143)
		(layer "In9.Cu")
		(net "CLK_100M_CPU0_RC_REFCLK1_DP")
	)
	(segment
		(start 268.25702 -56.676036)
		(end 266.771374 -55.19039)
		(width 0.0889)
		(layer "In9.Cu")
		(net "CLK_100M_CPU0_RC_REFCLK1_DP")
	)
	(segment
		(start 261.027164 -51.90236)
		(end 260.585204 -51.570382)
		(width 0.1143)
		(layer "In9.Cu")
		(net "CLK_100M_CPU0_RC_REFCLK1_DP")
	)
	(segment
		(start 170.705272 -88.146128)
		(end 170.705272 -89.006172)
		(width 0.1143)
		(layer "In9.Cu")
		(net "CLK_100M_CPU0_RC_REFCLK1_DP")
	)
	(segment
		(start 279.21839 -62.438534)
		(end 279.185624 -62.438534)
		(width 0.0889)
		(layer "In9.Cu")
		(net "CLK_100M_CPU0_RC_REFCLK1_DP")
	)
	(segment
		(start 256.333244 -50.1523)
		(end 255.990344 -50.1523)
		(width 0.1143)
		(layer "In9.Cu")
		(net "CLK_100M_CPU0_RC_REFCLK1_DP")
	)
	(segment
		(start 261.11581 -51.905154)
		(end 261.044436 -51.915314)
		(width 0.0889)
		(layer "In9.Cu")
		(net "CLK_100M_CPU0_RC_REFCLK1_DP")
	)
	(segment
		(start 185.255408 -63.09106)
		(end 185.255408 -63.88227)
		(width 0.1143)
		(layer "In9.Cu")
		(net "CLK_100M_CPU0_RC_REFCLK1_DP")
	)
	(segment
		(start 256.841244 -50.3174)
		(end 256.498344 -50.3174)
		(width 0.1143)
		(layer "In9.Cu")
		(net "CLK_100M_CPU0_RC_REFCLK1_DP")
	)
	(segment
		(start 286.70631 -70.067932)
		(end 285.56331 -68.086986)
		(width 0.0889)
		(layer "In9.Cu")
		(net "CLK_100M_CPU0_RC_REFCLK1_DP")
	)
	(segment
		(start 179.7685 -65.940178)
		(end 179.7685 -68.243704)
		(width 0.1143)
		(layer "In9.Cu")
		(net "CLK_100M_CPU0_RC_REFCLK1_DP")
	)
	(segment
		(start 270.368776 -57.485534)
		(end 268.687296 -56.676036)
		(width 0.0889)
		(layer "In9.Cu")
		(net "CLK_100M_CPU0_RC_REFCLK1_DP")
	)
	(segment
		(start 249.4153 -50.1523)
		(end 248.8692 -50.6984)
		(width 0.1143)
		(layer "In9.Cu")
		(net "CLK_100M_CPU0_RC_REFCLK1_DP")
	)
	(segment
		(start 257.006344 -50.1523)
		(end 256.841244 -50.3174)
		(width 0.1143)
		(layer "In9.Cu")
		(net "CLK_100M_CPU0_RC_REFCLK1_DP")
	)
	(segment
		(start 265.670792 -54.694836)
		(end 265.638026 -54.694836)
		(width 0.0889)
		(layer "In9.Cu")
		(net "CLK_100M_CPU0_RC_REFCLK1_DP")
	)
	(segment
		(start 257.349244 -50.1523)
		(end 257.006344 -50.1523)
		(width 0.1143)
		(layer "In9.Cu")
		(net "CLK_100M_CPU0_RC_REFCLK1_DP")
	)
	(segment
		(start 272.350484 -58.476388)
		(end 272.326354 -58.476388)
		(width 0.0889)
		(layer "In9.Cu")
		(net "CLK_100M_CPU0_RC_REFCLK1_DP")
	)
	(segment
		(start 287.21812 -72.744584)
		(end 287.21812 -72.40651)
		(width 0.0889)
		(layer "In9.Cu")
		(net "CLK_100M_CPU0_RC_REFCLK1_DP")
	)
	(segment
		(start 173.9392 -80.315816)
		(end 173.9392 -84.9122)
		(width 0.1143)
		(layer "In9.Cu")
		(net "CLK_100M_CPU0_RC_REFCLK1_DP")
	)
	(segment
		(start 263.099296 -53.20919)
		(end 263.06653 -53.20919)
		(width 0.0889)
		(layer "In9.Cu")
		(net "CLK_100M_CPU0_RC_REFCLK1_DP")
	)
	(segment
		(start 253.450344 -50.3174)
		(end 253.285244 -50.1523)
		(width 0.1143)
		(layer "In9.Cu")
		(net "CLK_100M_CPU0_RC_REFCLK1_DP")
	)
	(segment
		(start 285.56331 -67.496436)
		(end 285.568136 -67.4878)
		(width 0.0889)
		(layer "In9.Cu")
		(net "CLK_100M_CPU0_RC_REFCLK1_DP")
	)
	(segment
		(start 285.55696 -67.507104)
		(end 285.56331 -67.496436)
		(width 0.0889)
		(layer "In9.Cu")
		(net "CLK_100M_CPU0_RC_REFCLK1_DP")
	)
	(segment
		(start 270.942308 -57.683654)
		(end 270.942562 -57.683654)
		(width 0.0889)
		(layer "In9.Cu")
		(net "CLK_100M_CPU0_RC_REFCLK1_DP")
	)
	(segment
		(start 185.255408 -63.88227)
		(end 184.210198 -64.92748)
		(width 0.1143)
		(layer "In9.Cu")
		(net "CLK_100M_CPU0_RC_REFCLK1_DP")
	)
	(segment
		(start 284.70479 -65.610486)
		(end 284.701488 -65.604644)
		(width 0.0889)
		(layer "In9.Cu")
		(net "CLK_100M_CPU0_RC_REFCLK1_DP")
	)
	(segment
		(start 253.958344 -50.1523)
		(end 253.793244 -50.3174)
		(width 0.1143)
		(layer "In9.Cu")
		(net "CLK_100M_CPU0_RC_REFCLK1_DP")
	)
	(segment
		(start 185.039 -54.031134)
		(end 185.039 -58.774076)
		(width 0.1143)
		(layer "In9.Cu")
		(net "CLK_100M_CPU0_RC_REFCLK1_DP")
	)
	(segment
		(start 200.213214 -50.34788)
		(end 193.901822 -50.34788)
		(width 0.1143)
		(layer "In9.Cu")
		(net "CLK_100M_CPU0_RC_REFCLK1_DP")
	)
	(segment
		(start 276.64664 -60.952888)
		(end 276.613874 -60.952888)
		(width 0.0889)
		(layer "In9.Cu")
		(net "CLK_100M_CPU0_RC_REFCLK1_DP")
	)
	(segment
		(start 285.56331 -66.505836)
		(end 285.568136 -66.4972)
		(width 0.0889)
		(layer "In9.Cu")
		(net "CLK_100M_CPU0_RC_REFCLK1_DP")
	)
	(segment
		(start 287.21812 -72.40651)
		(end 287.153096 -72.341486)
		(width 0.0889)
		(layer "In9.Cu")
		(net "CLK_100M_CPU0_RC_REFCLK1_DP")
	)
	(segment
		(start 266.771374 -55.19039)
		(end 266.500356 -55.19039)
		(width 0.0889)
		(layer "In9.Cu")
		(net "CLK_100M_CPU0_RC_REFCLK1_DP")
	)
	(segment
		(start 273.215862 -58.971688)
		(end 273.176238 -58.971688)
		(width 0.0889)
		(layer "In9.Cu")
		(net "CLK_100M_CPU0_RC_REFCLK1_DP")
	)
	(segment
		(start 255.990344 -50.1523)
		(end 255.825244 -50.3174)
		(width 0.1143)
		(layer "In9.Cu")
		(net "CLK_100M_CPU0_RC_REFCLK1_DP")
	)
	(segment
		(start 177.96383 -75.49769)
		(end 177.96383 -78.097634)
		(width 0.1143)
		(layer "In9.Cu")
		(net "CLK_100M_CPU0_RC_REFCLK1_DP")
	)
	(segment
		(start 281.79776 -63.924688)
		(end 281.764994 -63.924688)
		(width 0.0889)
		(layer "In9.Cu")
		(net "CLK_100M_CPU0_RC_REFCLK1_DP")
	)
	(segment
		(start 261.044436 -51.915314)
		(end 261.027164 -51.90236)
		(width 0.0889)
		(layer "In9.Cu")
		(net "CLK_100M_CPU0_RC_REFCLK1_DP")
	)
	(segment
		(start 243.522754 -50.6984)
		(end 241.820954 -48.9966)
		(width 0.1143)
		(layer "In9.Cu")
		(net "CLK_100M_CPU0_RC_REFCLK1_DP")
	)
	(segment
		(start 280.93543 -63.429134)
		(end 280.902664 -63.429134)
		(width 0.0889)
		(layer "In9.Cu")
		(net "CLK_100M_CPU0_RC_REFCLK1_DP")
	)
	(segment
		(start 274.06854 -59.466988)
		(end 274.038568 -59.466988)
		(width 0.0889)
		(layer "In9.Cu")
		(net "CLK_100M_CPU0_RC_REFCLK1_DP")
	)
	(segment
		(start 268.687296 -56.676036)
		(end 268.25702 -56.676036)
		(width 0.0889)
		(layer "In9.Cu")
		(net "CLK_100M_CPU0_RC_REFCLK1_DP")
	)
	(segment
		(start 255.482344 -50.3174)
		(end 255.317244 -50.1523)
		(width 0.1143)
		(layer "In9.Cu")
		(net "CLK_100M_CPU0_RC_REFCLK1_DP")
	)
	(segment
		(start 278.36368 -61.943488)
		(end 278.330914 -61.943488)
		(width 0.0889)
		(layer "In9.Cu")
		(net "CLK_100M_CPU0_RC_REFCLK1_DP")
	)
	(segment
		(start 170.705272 -89.006172)
		(end 170.905424 -89.206324)
		(width 0.1143)
		(layer "In9.Cu")
		(net "CLK_100M_CPU0_RC_REFCLK1_DP")
	)
	(segment
		(start 184.255918 -62.336172)
		(end 184.50052 -62.336172)
		(width 0.1143)
		(layer "In9.Cu")
		(net "CLK_100M_CPU0_RC_REFCLK1_DP")
	)
	(segment
		(start 241.820954 -48.9966)
		(end 208.483454 -48.9966)
		(width 0.1143)
		(layer "In9.Cu")
		(net "CLK_100M_CPU0_RC_REFCLK1_DP")
	)
	(segment
		(start 193.566542 -50.0126)
		(end 189.057534 -50.0126)
		(width 0.1143)
		(layer "In9.Cu")
		(net "CLK_100M_CPU0_RC_REFCLK1_DP")
	)
	(segment
		(start 207.776826 -48.289972)
		(end 202.271122 -48.289972)
		(width 0.1143)
		(layer "In9.Cu")
		(net "CLK_100M_CPU0_RC_REFCLK1_DP")
	)
	(segment
		(start 274.9296 -59.962288)
		(end 274.90166 -59.962288)
		(width 0.0889)
		(layer "In9.Cu")
		(net "CLK_100M_CPU0_RC_REFCLK1_DP")
	)
	(segment
		(start 283.5148 -64.915288)
		(end 283.482034 -64.915288)
		(width 0.0889)
		(layer "In9.Cu")
		(net "CLK_100M_CPU0_RC_REFCLK1_DP")
	)
	(segment
		(start 261.648956 -52.305712)
		(end 261.11581 -51.905154)
		(width 0.0889)
		(layer "In9.Cu")
		(net "CLK_100M_CPU0_RC_REFCLK1_DP")
	)
	(segment
		(start 256.498344 -50.3174)
		(end 256.333244 -50.1523)
		(width 0.1143)
		(layer "In9.Cu")
		(net "CLK_100M_CPU0_RC_REFCLK1_DP")
	)
	(segment
		(start 173.9392 -84.9122)
		(end 170.705272 -88.146128)
		(width 0.1143)
		(layer "In9.Cu")
		(net "CLK_100M_CPU0_RC_REFCLK1_DP")
	)
	(segment
		(start 284.358334 -65.410334)
		(end 284.336744 -65.410334)
		(width 0.0889)
		(layer "In9.Cu")
		(net "CLK_100M_CPU0_RC_REFCLK1_DP")
	)
	(segment
		(start 282.65247 -64.419734)
		(end 282.619704 -64.419734)
		(width 0.0889)
		(layer "In9.Cu")
		(net "CLK_100M_CPU0_RC_REFCLK1_DP")
	)
	(segment
		(start 285.231586 -65.905888)
		(end 285.19882 -65.905888)
		(width 0.0889)
		(layer "In9.Cu")
		(net "CLK_100M_CPU0_RC_REFCLK1_DP")
	)
	(segment
		(start 185.039 -58.774076)
		(end 183.83123 -59.981846)
		(width 0.1143)
		(layer "In9.Cu")
		(net "CLK_100M_CPU0_RC_REFCLK1_DP")
	)
	(segment
		(start 253.285244 -50.1523)
		(end 249.4153 -50.1523)
		(width 0.1143)
		(layer "In9.Cu")
		(net "CLK_100M_CPU0_RC_REFCLK1_DP")
	)
	(segment
		(start 277.50135 -61.447934)
		(end 277.468584 -61.447934)
		(width 0.0889)
		(layer "In9.Cu")
		(net "CLK_100M_CPU0_RC_REFCLK1_DP")
	)
	(segment
		(start 264.289286 -53.904388)
		(end 264.285984 -53.898546)
		(width 0.0889)
		(layer "In9.Cu")
		(net "CLK_100M_CPU0_RC_REFCLK1_DP")
	)
	(segment
		(start 178.253644 -75.207876)
		(end 177.96383 -75.49769)
		(width 0.1143)
		(layer "In9.Cu")
		(net "CLK_100M_CPU0_RC_REFCLK1_DP")
	)
	(segment
		(start 263.94283 -53.704236)
		(end 263.92124 -53.704236)
		(width 0.0889)
		(layer "In9.Cu")
		(net "CLK_100M_CPU0_RC_REFCLK1_DP")
	)
	(segment
		(start 275.78431 -60.457334)
		(end 275.751544 -60.457334)
		(width 0.0889)
		(layer "In9.Cu")
		(net "CLK_100M_CPU0_RC_REFCLK1_DP")
	)
	(segment
		(start 184.210198 -64.92748)
		(end 180.781198 -64.92748)
		(width 0.1143)
		(layer "In9.Cu")
		(net "CLK_100M_CPU0_RC_REFCLK1_DP")
	)
	(segment
		(start 179.7685 -68.243704)
		(end 178.253644 -69.75856)
		(width 0.1143)
		(layer "In9.Cu")
		(net "CLK_100M_CPU0_RC_REFCLK1_DP")
	)
	(segment
		(start 193.901822 -50.34788)
		(end 193.566542 -50.0126)
		(width 0.1143)
		(layer "In9.Cu")
		(net "CLK_100M_CPU0_RC_REFCLK1_DP")
	)
	(segment
		(start 260.585204 -51.570382)
		(end 258.767326 -51.570382)
		(width 0.1143)
		(layer "In9.Cu")
		(net "CLK_100M_CPU0_RC_REFCLK1_DP")
	)
	(segment
		(start 176.918112 -79.143352)
		(end 175.111664 -79.143352)
		(width 0.1143)
		(layer "In9.Cu")
		(net "CLK_100M_CPU0_RC_REFCLK1_DP")
	)
	(segment
		(start 189.057534 -50.0126)
		(end 185.039 -54.031134)
		(width 0.1143)
		(layer "In9.Cu")
		(net "CLK_100M_CPU0_RC_REFCLK1_DP")
	)
	(segment
		(start 183.83123 -61.911484)
		(end 184.255918 -62.336172)
		(width 0.1143)
		(layer "In9.Cu")
		(net "CLK_100M_CPU0_RC_REFCLK1_DP")
	)
	(segment
		(start 175.111664 -79.143352)
		(end 173.9392 -80.315816)
		(width 0.1143)
		(layer "In9.Cu")
		(net "CLK_100M_CPU0_RC_REFCLK1_DP")
	)
	(segment
		(start 254.466344 -50.3174)
		(end 254.301244 -50.1523)
		(width 0.1143)
		(layer "In9.Cu")
		(net "CLK_100M_CPU0_RC_REFCLK1_DP")
	)
	(segment
		(start 264.816082 -54.19979)
		(end 264.783316 -54.19979)
		(width 0.0889)
		(layer "In9.Cu")
		(net "CLK_100M_CPU0_RC_REFCLK1_DP")
	)
	(segment
		(start 270.707612 -57.485534)
		(end 270.368776 -57.485534)
		(width 0.0889)
		(layer "In9.Cu")
		(net "CLK_100M_CPU0_RC_REFCLK1_DP")
	)
	(arc
		(start 282.129484 -64.124586)
		(mid 281.989405 -63.98185)
		(end 281.79776 -63.924688)
		(width 0.0889)
		(layer "In9.Cu")
		(net "CLK_100M_CPU0_RC_REFCLK1_DP")
	)
	(arc
		(start 281.764994 -63.924688)
		(mid 281.47957 -63.841221)
		(end 281.270964 -63.629286)
		(width 0.0889)
		(layer "In9.Cu")
		(net "CLK_100M_CPU0_RC_REFCLK1_DP")
	)
	(arc
		(start 277.468584 -61.447934)
		(mid 277.185367 -61.363653)
		(end 276.978364 -61.152786)
		(width 0.0889)
		(layer "In9.Cu")
		(net "CLK_100M_CPU0_RC_REFCLK1_DP")
	)
	(arc
		(start 279.553924 -62.638686)
		(mid 279.412241 -62.494882)
		(end 279.21839 -62.438534)
		(width 0.0889)
		(layer "In9.Cu")
		(net "CLK_100M_CPU0_RC_REFCLK1_DP")
	)
	(arc
		(start 273.176238 -58.971688)
		(mid 272.893021 -58.887407)
		(end 272.686018 -58.67654)
		(width 0.0889)
		(layer "In9.Cu")
		(net "CLK_100M_CPU0_RC_REFCLK1_DP")
	)
	(arc
		(start 281.270964 -63.629286)
		(mid 281.129281 -63.485482)
		(end 280.93543 -63.429134)
		(width 0.0889)
		(layer "In9.Cu")
		(net "CLK_100M_CPU0_RC_REFCLK1_DP")
	)
	(arc
		(start 284.701488 -65.604644)
		(mid 284.555522 -65.462245)
		(end 284.358334 -65.410334)
		(width 0.0889)
		(layer "In9.Cu")
		(net "CLK_100M_CPU0_RC_REFCLK1_DP")
	)
	(arc
		(start 280.047954 -62.934088)
		(mid 279.76253 -62.850621)
		(end 279.553924 -62.638686)
		(width 0.0889)
		(layer "In9.Cu")
		(net "CLK_100M_CPU0_RC_REFCLK1_DP")
	)
	(arc
		(start 266.500356 -55.19039)
		(mid 266.214932 -55.106923)
		(end 266.006326 -54.894988)
		(width 0.0889)
		(layer "In9.Cu")
		(net "CLK_100M_CPU0_RC_REFCLK1_DP")
	)
	(arc
		(start 275.751544 -60.457334)
		(mid 275.468327 -60.373053)
		(end 275.261324 -60.162186)
		(width 0.0889)
		(layer "In9.Cu")
		(net "CLK_100M_CPU0_RC_REFCLK1_DP")
	)
	(arc
		(start 280.412444 -63.133986)
		(mid 280.272365 -62.99125)
		(end 280.08072 -62.934088)
		(width 0.0889)
		(layer "In9.Cu")
		(net "CLK_100M_CPU0_RC_REFCLK1_DP")
	)
	(arc
		(start 278.330914 -61.943488)
		(mid 278.04549 -61.860021)
		(end 277.836884 -61.648086)
		(width 0.0889)
		(layer "In9.Cu")
		(net "CLK_100M_CPU0_RC_REFCLK1_DP")
	)
	(arc
		(start 272.686018 -58.67654)
		(mid 272.544335 -58.532736)
		(end 272.350484 -58.476388)
		(width 0.0889)
		(layer "In9.Cu")
		(net "CLK_100M_CPU0_RC_REFCLK1_DP")
	)
	(arc
		(start 282.619704 -64.419734)
		(mid 282.336487 -64.335453)
		(end 282.129484 -64.124586)
		(width 0.0889)
		(layer "In9.Cu")
		(net "CLK_100M_CPU0_RC_REFCLK1_DP")
	)
	(arc
		(start 264.783316 -54.19979)
		(mid 264.497892 -54.116323)
		(end 264.289286 -53.904388)
		(width 0.0889)
		(layer "In9.Cu")
		(net "CLK_100M_CPU0_RC_REFCLK1_DP")
	)
	(arc
		(start 262.5725 -52.913788)
		(mid 262.430817 -52.769984)
		(end 262.236966 -52.713636)
		(width 0.0889)
		(layer "In9.Cu")
		(net "CLK_100M_CPU0_RC_REFCLK1_DP")
	)
	(arc
		(start 272.326354 -58.476388)
		(mid 272.038209 -58.394069)
		(end 271.827498 -58.180986)
		(width 0.0889)
		(layer "In9.Cu")
		(net "CLK_100M_CPU0_RC_REFCLK1_DP")
	)
	(arc
		(start 284.336744 -65.410334)
		(mid 284.053527 -65.326053)
		(end 283.846524 -65.115186)
		(width 0.0889)
		(layer "In9.Cu")
		(net "CLK_100M_CPU0_RC_REFCLK1_DP")
	)
	(arc
		(start 264.285984 -53.898546)
		(mid 264.140018 -53.756147)
		(end 263.94283 -53.704236)
		(width 0.0889)
		(layer "In9.Cu")
		(net "CLK_100M_CPU0_RC_REFCLK1_DP")
	)
	(arc
		(start 263.43102 -53.409088)
		(mid 263.290941 -53.266352)
		(end 263.099296 -53.20919)
		(width 0.0889)
		(layer "In9.Cu")
		(net "CLK_100M_CPU0_RC_REFCLK1_DP")
	)
	(arc
		(start 280.902664 -63.429134)
		(mid 280.619447 -63.344853)
		(end 280.412444 -63.133986)
		(width 0.0889)
		(layer "In9.Cu")
		(net "CLK_100M_CPU0_RC_REFCLK1_DP")
	)
	(arc
		(start 285.56331 -67.096386)
		(mid 285.484088 -66.807268)
		(end 285.55696 -66.516504)
		(width 0.0889)
		(layer "In9.Cu")
		(net "CLK_100M_CPU0_RC_REFCLK1_DP")
	)
	(arc
		(start 265.638026 -54.694836)
		(mid 265.354809 -54.610555)
		(end 265.147806 -54.399688)
		(width 0.0889)
		(layer "In9.Cu")
		(net "CLK_100M_CPU0_RC_REFCLK1_DP")
	)
	(arc
		(start 285.56331 -68.086986)
		(mid 285.484088 -67.797868)
		(end 285.55696 -67.507104)
		(width 0.0889)
		(layer "In9.Cu")
		(net "CLK_100M_CPU0_RC_REFCLK1_DP")
	)
	(arc
		(start 274.038568 -59.466988)
		(mid 273.753144 -59.383521)
		(end 273.544538 -59.171586)
		(width 0.0889)
		(layer "In9.Cu")
		(net "CLK_100M_CPU0_RC_REFCLK1_DP")
	)
	(arc
		(start 283.846524 -65.115186)
		(mid 283.706445 -64.97245)
		(end 283.5148 -64.915288)
		(width 0.0889)
		(layer "In9.Cu")
		(net "CLK_100M_CPU0_RC_REFCLK1_DP")
	)
	(arc
		(start 283.482034 -64.915288)
		(mid 283.19661 -64.831821)
		(end 282.988004 -64.619886)
		(width 0.0889)
		(layer "In9.Cu")
		(net "CLK_100M_CPU0_RC_REFCLK1_DP")
	)
	(arc
		(start 286.70631 -71.058786)
		(mid 286.627179 -70.763384)
		(end 286.70631 -70.467982)
		(width 0.0889)
		(layer "In9.Cu")
		(net "CLK_100M_CPU0_RC_REFCLK1_DP")
	)
	(arc
		(start 278.695404 -62.143386)
		(mid 278.555325 -62.00065)
		(end 278.36368 -61.943488)
		(width 0.0889)
		(layer "In9.Cu")
		(net "CLK_100M_CPU0_RC_REFCLK1_DP")
	)
	(arc
		(start 274.402804 -59.666886)
		(mid 274.261647 -59.523501)
		(end 274.06854 -59.466988)
		(width 0.0889)
		(layer "In9.Cu")
		(net "CLK_100M_CPU0_RC_REFCLK1_DP")
	)
	(arc
		(start 274.90166 -59.962288)
		(mid 274.613515 -59.879969)
		(end 274.402804 -59.666886)
		(width 0.0889)
		(layer "In9.Cu")
		(net "CLK_100M_CPU0_RC_REFCLK1_DP")
	)
	(arc
		(start 270.942562 -57.683654)
		(mid 270.843712 -57.562521)
		(end 270.707612 -57.485534)
		(width 0.0889)
		(layer "In9.Cu")
		(net "CLK_100M_CPU0_RC_REFCLK1_DP")
	)
	(arc
		(start 263.06653 -53.20919)
		(mid 262.781106 -53.125723)
		(end 262.5725 -52.913788)
		(width 0.0889)
		(layer "In9.Cu")
		(net "CLK_100M_CPU0_RC_REFCLK1_DP")
	)
	(arc
		(start 276.978364 -61.152786)
		(mid 276.838285 -61.01005)
		(end 276.64664 -60.952888)
		(width 0.0889)
		(layer "In9.Cu")
		(net "CLK_100M_CPU0_RC_REFCLK1_DP")
	)
	(arc
		(start 286.70631 -70.467982)
		(mid 286.759809 -70.268084)
		(end 286.70631 -70.068186)
		(width 0.0889)
		(layer "In9.Cu")
		(net "CLK_100M_CPU0_RC_REFCLK1_DP")
	)
	(arc
		(start 276.119844 -60.657486)
		(mid 275.978161 -60.513682)
		(end 275.78431 -60.457334)
		(width 0.0889)
		(layer "In9.Cu")
		(net "CLK_100M_CPU0_RC_REFCLK1_DP")
	)
	(arc
		(start 287.153096 -72.341486)
		(mid 286.693619 -72.026537)
		(end 286.69996 -71.469504)
		(width 0.0889)
		(layer "In9.Cu")
		(net "CLK_100M_CPU0_RC_REFCLK1_DP")
	)
	(arc
		(start 275.261324 -60.162186)
		(mid 275.121245 -60.01945)
		(end 274.9296 -59.962288)
		(width 0.0889)
		(layer "In9.Cu")
		(net "CLK_100M_CPU0_RC_REFCLK1_DP")
	)
	(arc
		(start 262.2042 -52.713636)
		(mid 261.920983 -52.629355)
		(end 261.71398 -52.418488)
		(width 0.0889)
		(layer "In9.Cu")
		(net "CLK_100M_CPU0_RC_REFCLK1_DP")
	)
	(arc
		(start 285.568136 -66.4972)
		(mid 285.564389 -66.107944)
		(end 285.231586 -65.905888)
		(width 0.0889)
		(layer "In9.Cu")
		(net "CLK_100M_CPU0_RC_REFCLK1_DP")
	)
	(arc
		(start 286.711136 -71.4502)
		(mid 286.759891 -71.253848)
		(end 286.70631 -71.058786)
		(width 0.0889)
		(layer "In9.Cu")
		(net "CLK_100M_CPU0_RC_REFCLK1_DP")
	)
	(arc
		(start 285.568136 -67.4878)
		(mid 285.616891 -67.291448)
		(end 285.56331 -67.096386)
		(width 0.0889)
		(layer "In9.Cu")
		(net "CLK_100M_CPU0_RC_REFCLK1_DP")
	)
	(arc
		(start 277.836884 -61.648086)
		(mid 277.695201 -61.504282)
		(end 277.50135 -61.447934)
		(width 0.0889)
		(layer "In9.Cu")
		(net "CLK_100M_CPU0_RC_REFCLK1_DP")
	)
	(arc
		(start 276.613874 -60.952888)
		(mid 276.32845 -60.869421)
		(end 276.119844 -60.657486)
		(width 0.0889)
		(layer "In9.Cu")
		(net "CLK_100M_CPU0_RC_REFCLK1_DP")
	)
	(arc
		(start 266.006326 -54.894988)
		(mid 265.864643 -54.751184)
		(end 265.670792 -54.694836)
		(width 0.0889)
		(layer "In9.Cu")
		(net "CLK_100M_CPU0_RC_REFCLK1_DP")
	)
	(arc
		(start 265.147806 -54.399688)
		(mid 265.007727 -54.256952)
		(end 264.816082 -54.19979)
		(width 0.0889)
		(layer "In9.Cu")
		(net "CLK_100M_CPU0_RC_REFCLK1_DP")
	)
	(arc
		(start 263.92124 -53.704236)
		(mid 263.638023 -53.619955)
		(end 263.43102 -53.409088)
		(width 0.0889)
		(layer "In9.Cu")
		(net "CLK_100M_CPU0_RC_REFCLK1_DP")
	)
	(arc
		(start 279.185624 -62.438534)
		(mid 278.902407 -62.354253)
		(end 278.695404 -62.143386)
		(width 0.0889)
		(layer "In9.Cu")
		(net "CLK_100M_CPU0_RC_REFCLK1_DP")
	)
	(arc
		(start 285.19882 -65.905888)
		(mid 284.913396 -65.822421)
		(end 284.70479 -65.610486)
		(width 0.0889)
		(layer "In9.Cu")
		(net "CLK_100M_CPU0_RC_REFCLK1_DP")
	)
	(arc
		(start 271.827498 -58.180986)
		(mid 271.687419 -58.03825)
		(end 271.495774 -57.981088)
		(width 0.0889)
		(layer "In9.Cu")
		(net "CLK_100M_CPU0_RC_REFCLK1_DP")
	)
	(arc
		(start 273.544538 -59.171586)
		(mid 273.405794 -59.029553)
		(end 273.215862 -58.971688)
		(width 0.0889)
		(layer "In9.Cu")
		(net "CLK_100M_CPU0_RC_REFCLK1_DP")
	)
	(arc
		(start 282.988004 -64.619886)
		(mid 282.846321 -64.476082)
		(end 282.65247 -64.419734)
		(width 0.0889)
		(layer "In9.Cu")
		(net "CLK_100M_CPU0_RC_REFCLK1_DP")
	)
	(arc
		(start 271.315942 -57.981088)
		(mid 271.09896 -57.870258)
		(end 270.942308 -57.683654)
		(width 0.0889)
		(layer "In9.Cu")
		(net "CLK_100M_CPU0_RC_REFCLK1_DP")
	)
	(segment
		(start 170.474386 -87.959184)
		(end 170.272202 -87.757)
		(width 0.1143)
		(layer "F.Cu")
		(net "CLK_100M_CPU0_RC_REFCLK1_DN")
	)
	(segment
		(start 170.190668 -89.206324)
		(end 170.474386 -88.922606)
		(width 0.1143)
		(layer "F.Cu")
		(net "CLK_100M_CPU0_RC_REFCLK1_DN")
	)
	(segment
		(start 170.474386 -88.922606)
		(end 170.474386 -87.959184)
		(width 0.1143)
		(layer "F.Cu")
		(net "CLK_100M_CPU0_RC_REFCLK1_DN")
	)
	(segment
		(start 170.272202 -87.757)
		(end 169.926 -87.757)
		(width 0.1143)
		(layer "F.Cu")
		(net "CLK_100M_CPU0_RC_REFCLK1_DN")
	)
	(segment
		(start 169.975276 -89.206324)
		(end 170.190668 -89.206324)
		(width 0.1143)
		(layer "F.Cu")
		(net "CLK_100M_CPU0_RC_REFCLK1_DN")
	)
	(segment
		(start 287.21812 -71.753984)
		(end 286.64662 -71.753984)
		(width 0.1143)
		(layer "F.Cu")
		(net "CLK_100M_CPU0_RC_REFCLK1_DN")
	)
	(via
		(at 287.21812 -71.753984)
		(size 0.508)
		(drill 0.254)
		(layers "F.Cu" "B.Cu")
		(net "CLK_100M_CPU0_RC_REFCLK1_DN")
	)
	(via
		(at 169.975276 -89.206324)
		(size 0.508)
		(drill 0.254)
		(layers "F.Cu" "B.Cu")
		(net "CLK_100M_CPU0_RC_REFCLK1_DN")
	)
	(segment
		(start 170.422316 -87.965788)
		(end 170.422316 -88.759284)
		(width 0.1143)
		(layer "B.Cu")
		(net "CLK_100M_CPU0_RC_REFCLK1_DN")
	)
	(segment
		(start 170.422316 -88.759284)
		(end 169.975276 -89.206324)
		(width 0.1143)
		(layer "B.Cu")
		(net "CLK_100M_CPU0_RC_REFCLK1_DN")
	)
	(segment
		(start 169.926 -87.757)
		(end 170.213528 -87.757)
		(width 0.1143)
		(layer "B.Cu")
		(net "CLK_100M_CPU0_RC_REFCLK1_DN")
	)
	(segment
		(start 170.213528 -87.757)
		(end 170.422316 -87.965788)
		(width 0.1143)
		(layer "B.Cu")
		(net "CLK_100M_CPU0_RC_REFCLK1_DN")
	)
	(segment
		(start 180.66004 -64.63538)
		(end 179.4764 -65.81902)
		(width 0.1143)
		(layer "In9.Cu")
		(net "CLK_100M_CPU0_RC_REFCLK1_DN")
	)
	(segment
		(start 285.723584 -67.600322)
		(end 285.72841 -67.591686)
		(width 0.0889)
		(layer "In9.Cu")
		(net "CLK_100M_CPU0_RC_REFCLK1_DN")
	)
	(segment
		(start 183.53913 -62.032642)
		(end 184.13476 -62.628272)
		(width 0.1143)
		(layer "In9.Cu")
		(net "CLK_100M_CPU0_RC_REFCLK1_DN")
	)
	(segment
		(start 287.21812 -71.753984)
		(end 287.21812 -72.092058)
		(width 0.0889)
		(layer "In9.Cu")
		(net "CLK_100M_CPU0_RC_REFCLK1_DN")
	)
	(segment
		(start 268.147546 -56.297068)
		(end 268.147546 -56.171338)
		(width 0.0889)
		(layer "In9.Cu")
		(net "CLK_100M_CPU0_RC_REFCLK1_DN")
	)
	(segment
		(start 248.748042 -50.4063)
		(end 243.643912 -50.4063)
		(width 0.1143)
		(layer "In9.Cu")
		(net "CLK_100M_CPU0_RC_REFCLK1_DN")
	)
	(segment
		(start 262.24357 -52.523136)
		(end 262.208264 -52.523136)
		(width 0.0889)
		(layer "In9.Cu")
		(net "CLK_100M_CPU0_RC_REFCLK1_DN")
	)
	(segment
		(start 270.412464 -57.295034)
		(end 268.730984 -56.485536)
		(width 0.0889)
		(layer "In9.Cu")
		(net "CLK_100M_CPU0_RC_REFCLK1_DN")
	)
	(segment
		(start 173.6471 -84.791042)
		(end 170.413172 -88.02497)
		(width 0.1143)
		(layer "In9.Cu")
		(net "CLK_100M_CPU0_RC_REFCLK1_DN")
	)
	(segment
		(start 188.936376 -49.7205)
		(end 184.7469 -53.909976)
		(width 0.1143)
		(layer "In9.Cu")
		(net "CLK_100M_CPU0_RC_REFCLK1_DN")
	)
	(segment
		(start 266.850368 -54.99989)
		(end 266.503658 -54.99989)
		(width 0.0889)
		(layer "In9.Cu")
		(net "CLK_100M_CPU0_RC_REFCLK1_DN")
	)
	(segment
		(start 273.215608 -58.780934)
		(end 273.179794 -58.780934)
		(width 0.0889)
		(layer "In9.Cu")
		(net "CLK_100M_CPU0_RC_REFCLK1_DN")
	)
	(segment
		(start 264.822686 -54.00929)
		(end 264.801096 -54.00929)
		(width 0.0889)
		(layer "In9.Cu")
		(net "CLK_100M_CPU0_RC_REFCLK1_DN")
	)
	(segment
		(start 279.224994 -62.248034)
		(end 279.192228 -62.248034)
		(width 0.0889)
		(layer "In9.Cu")
		(net "CLK_100M_CPU0_RC_REFCLK1_DN")
	)
	(segment
		(start 257.470402 -49.8602)
		(end 249.294142 -49.8602)
		(width 0.1143)
		(layer "In9.Cu")
		(net "CLK_100M_CPU0_RC_REFCLK1_DN")
	)
	(segment
		(start 194.02298 -50.05578)
		(end 193.6877 -49.7205)
		(width 0.1143)
		(layer "In9.Cu")
		(net "CLK_100M_CPU0_RC_REFCLK1_DN")
	)
	(segment
		(start 260.68274 -51.278282)
		(end 258.888484 -51.278282)
		(width 0.1143)
		(layer "In9.Cu")
		(net "CLK_100M_CPU0_RC_REFCLK1_DN")
	)
	(segment
		(start 261.87908 -52.323238)
		(end 261.794498 -52.17668)
		(width 0.0889)
		(layer "In9.Cu")
		(net "CLK_100M_CPU0_RC_REFCLK1_DN")
	)
	(segment
		(start 267.833094 -55.982616)
		(end 267.644626 -55.794148)
		(width 0.0889)
		(layer "In9.Cu")
		(net "CLK_100M_CPU0_RC_REFCLK1_DN")
	)
	(segment
		(start 184.13476 -62.628272)
		(end 184.379362 -62.628272)
		(width 0.1143)
		(layer "In9.Cu")
		(net "CLK_100M_CPU0_RC_REFCLK1_DN")
	)
	(segment
		(start 265.677396 -54.504336)
		(end 265.64463 -54.504336)
		(width 0.0889)
		(layer "In9.Cu")
		(net "CLK_100M_CPU0_RC_REFCLK1_DN")
	)
	(segment
		(start 286.866584 -70.572122)
		(end 286.87141 -70.563486)
		(width 0.0889)
		(layer "In9.Cu")
		(net "CLK_100M_CPU0_RC_REFCLK1_DN")
	)
	(segment
		(start 243.643912 -50.4063)
		(end 241.942112 -48.7045)
		(width 0.1143)
		(layer "In9.Cu")
		(net "CLK_100M_CPU0_RC_REFCLK1_DN")
	)
	(segment
		(start 267.330174 -55.479696)
		(end 266.850368 -54.99989)
		(width 0.0889)
		(layer "In9.Cu")
		(net "CLK_100M_CPU0_RC_REFCLK1_DN")
	)
	(segment
		(start 271.502378 -57.790588)
		(end 271.345914 -57.790588)
		(width 0.0889)
		(layer "In9.Cu")
		(net "CLK_100M_CPU0_RC_REFCLK1_DN")
	)
	(segment
		(start 241.942112 -48.7045)
		(end 208.604612 -48.7045)
		(width 0.1143)
		(layer "In9.Cu")
		(net "CLK_100M_CPU0_RC_REFCLK1_DN")
	)
	(segment
		(start 267.958824 -55.982616)
		(end 267.833094 -55.982616)
		(width 0.0889)
		(layer "In9.Cu")
		(net "CLK_100M_CPU0_RC_REFCLK1_DN")
	)
	(segment
		(start 275.790914 -60.266834)
		(end 275.758148 -60.266834)
		(width 0.0889)
		(layer "In9.Cu")
		(net "CLK_100M_CPU0_RC_REFCLK1_DN")
	)
	(segment
		(start 270.736314 -57.295034)
		(end 270.412464 -57.295034)
		(width 0.0889)
		(layer "In9.Cu")
		(net "CLK_100M_CPU0_RC_REFCLK1_DN")
	)
	(segment
		(start 184.7469 -53.909976)
		(end 184.7469 -58.652918)
		(width 0.1143)
		(layer "In9.Cu")
		(net "CLK_100M_CPU0_RC_REFCLK1_DN")
	)
	(segment
		(start 285.72841 -66.601086)
		(end 285.73476 -66.590418)
		(width 0.0889)
		(layer "In9.Cu")
		(net "CLK_100M_CPU0_RC_REFCLK1_DN")
	)
	(segment
		(start 272.352262 -58.285634)
		(end 272.324322 -58.285634)
		(width 0.0889)
		(layer "In9.Cu")
		(net "CLK_100M_CPU0_RC_REFCLK1_DN")
	)
	(segment
		(start 268.730984 -56.485536)
		(end 268.336014 -56.485536)
		(width 0.0889)
		(layer "In9.Cu")
		(net "CLK_100M_CPU0_RC_REFCLK1_DN")
	)
	(segment
		(start 267.644626 -55.668418)
		(end 267.455904 -55.479696)
		(width 0.0889)
		(layer "In9.Cu")
		(net "CLK_100M_CPU0_RC_REFCLK1_DN")
	)
	(segment
		(start 281.804364 -63.734188)
		(end 281.771598 -63.734188)
		(width 0.0889)
		(layer "In9.Cu")
		(net "CLK_100M_CPU0_RC_REFCLK1_DN")
	)
	(segment
		(start 263.1059 -53.01869)
		(end 263.073134 -53.01869)
		(width 0.0889)
		(layer "In9.Cu")
		(net "CLK_100M_CPU0_RC_REFCLK1_DN")
	)
	(segment
		(start 207.897984 -47.997872)
		(end 202.149964 -47.997872)
		(width 0.1143)
		(layer "In9.Cu")
		(net "CLK_100M_CPU0_RC_REFCLK1_DN")
	)
	(segment
		(start 285.23819 -65.715388)
		(end 285.2166 -65.715388)
		(width 0.0889)
		(layer "In9.Cu")
		(net "CLK_100M_CPU0_RC_REFCLK1_DN")
	)
	(segment
		(start 278.370284 -61.752988)
		(end 278.337518 -61.752988)
		(width 0.0889)
		(layer "In9.Cu")
		(net "CLK_100M_CPU0_RC_REFCLK1_DN")
	)
	(segment
		(start 286.87141 -69.972682)
		(end 285.72841 -67.991736)
		(width 0.0889)
		(layer "In9.Cu")
		(net "CLK_100M_CPU0_RC_REFCLK1_DN")
	)
	(segment
		(start 249.294142 -49.8602)
		(end 248.748042 -50.4063)
		(width 0.1143)
		(layer "In9.Cu")
		(net "CLK_100M_CPU0_RC_REFCLK1_DN")
	)
	(segment
		(start 202.149964 -47.997872)
		(end 200.092056 -50.05578)
		(width 0.1143)
		(layer "In9.Cu")
		(net "CLK_100M_CPU0_RC_REFCLK1_DN")
	)
	(segment
		(start 264.457942 -53.81498)
		(end 264.45464 -53.809138)
		(width 0.0889)
		(layer "In9.Cu")
		(net "CLK_100M_CPU0_RC_REFCLK1_DN")
	)
	(segment
		(start 170.413172 -88.02497)
		(end 170.413172 -88.975692)
		(width 0.1143)
		(layer "In9.Cu")
		(net "CLK_100M_CPU0_RC_REFCLK1_DN")
	)
	(segment
		(start 177.961544 -69.637402)
		(end 177.961544 -75.086718)
		(width 0.1143)
		(layer "In9.Cu")
		(net "CLK_100M_CPU0_RC_REFCLK1_DN")
	)
	(segment
		(start 184.963308 -63.761112)
		(end 184.08904 -64.63538)
		(width 0.1143)
		(layer "In9.Cu")
		(net "CLK_100M_CPU0_RC_REFCLK1_DN")
	)
	(segment
		(start 277.507954 -61.257434)
		(end 277.475188 -61.257434)
		(width 0.0889)
		(layer "In9.Cu")
		(net "CLK_100M_CPU0_RC_REFCLK1_DN")
	)
	(segment
		(start 261.229856 -51.7525)
		(end 261.220204 -51.681888)
		(width 0.0889)
		(layer "In9.Cu")
		(net "CLK_100M_CPU0_RC_REFCLK1_DN")
	)
	(segment
		(start 274.927568 -59.771534)
		(end 274.914614 -59.771534)
		(width 0.0889)
		(layer "In9.Cu")
		(net "CLK_100M_CPU0_RC_REFCLK1_DN")
	)
	(segment
		(start 267.644626 -55.794148)
		(end 267.644626 -55.668418)
		(width 0.0889)
		(layer "In9.Cu")
		(net "CLK_100M_CPU0_RC_REFCLK1_DN")
	)
	(segment
		(start 284.873446 -65.521078)
		(end 284.870144 -65.515236)
		(width 0.0889)
		(layer "In9.Cu")
		(net "CLK_100M_CPU0_RC_REFCLK1_DN")
	)
	(segment
		(start 174.990506 -78.851252)
		(end 173.6471 -80.194658)
		(width 0.1143)
		(layer "In9.Cu")
		(net "CLK_100M_CPU0_RC_REFCLK1_DN")
	)
	(segment
		(start 263.96061 -53.513736)
		(end 263.927844 -53.513736)
		(width 0.0889)
		(layer "In9.Cu")
		(net "CLK_100M_CPU0_RC_REFCLK1_DN")
	)
	(segment
		(start 268.336014 -56.485536)
		(end 268.147546 -56.297068)
		(width 0.0889)
		(layer "In9.Cu")
		(net "CLK_100M_CPU0_RC_REFCLK1_DN")
	)
	(segment
		(start 177.961544 -75.086718)
		(end 177.67173 -75.376532)
		(width 0.1143)
		(layer "In9.Cu")
		(net "CLK_100M_CPU0_RC_REFCLK1_DN")
	)
	(segment
		(start 280.942034 -63.238634)
		(end 280.909268 -63.238634)
		(width 0.0889)
		(layer "In9.Cu")
		(net "CLK_100M_CPU0_RC_REFCLK1_DN")
	)
	(segment
		(start 177.67173 -77.976476)
		(end 176.796954 -78.851252)
		(width 0.1143)
		(layer "In9.Cu")
		(net "CLK_100M_CPU0_RC_REFCLK1_DN")
	)
	(segment
		(start 170.18254 -89.206324)
		(end 169.975276 -89.206324)
		(width 0.1143)
		(layer "In9.Cu")
		(net "CLK_100M_CPU0_RC_REFCLK1_DN")
	)
	(segment
		(start 261.202678 -51.66868)
		(end 260.68274 -51.278282)
		(width 0.1143)
		(layer "In9.Cu")
		(net "CLK_100M_CPU0_RC_REFCLK1_DN")
	)
	(segment
		(start 274.077938 -59.276234)
		(end 274.038314 -59.276234)
		(width 0.0889)
		(layer "In9.Cu")
		(net "CLK_100M_CPU0_RC_REFCLK1_DN")
	)
	(segment
		(start 280.087324 -62.743588)
		(end 280.054558 -62.743588)
		(width 0.0889)
		(layer "In9.Cu")
		(net "CLK_100M_CPU0_RC_REFCLK1_DN")
	)
	(segment
		(start 284.376114 -65.219834)
		(end 284.343348 -65.219834)
		(width 0.0889)
		(layer "In9.Cu")
		(net "CLK_100M_CPU0_RC_REFCLK1_DN")
	)
	(segment
		(start 282.659074 -64.229234)
		(end 282.626308 -64.229234)
		(width 0.0889)
		(layer "In9.Cu")
		(net "CLK_100M_CPU0_RC_REFCLK1_DN")
	)
	(segment
		(start 200.092056 -50.05578)
		(end 194.02298 -50.05578)
		(width 0.1143)
		(layer "In9.Cu")
		(net "CLK_100M_CPU0_RC_REFCLK1_DN")
	)
	(segment
		(start 184.7469 -58.652918)
		(end 183.53913 -59.860688)
		(width 0.1143)
		(layer "In9.Cu")
		(net "CLK_100M_CPU0_RC_REFCLK1_DN")
	)
	(segment
		(start 183.53913 -59.860688)
		(end 183.53913 -62.032642)
		(width 0.1143)
		(layer "In9.Cu")
		(net "CLK_100M_CPU0_RC_REFCLK1_DN")
	)
	(segment
		(start 261.794498 -52.17668)
		(end 261.229856 -51.7525)
		(width 0.0889)
		(layer "In9.Cu")
		(net "CLK_100M_CPU0_RC_REFCLK1_DN")
	)
	(segment
		(start 268.147546 -56.171338)
		(end 267.958824 -55.982616)
		(width 0.0889)
		(layer "In9.Cu")
		(net "CLK_100M_CPU0_RC_REFCLK1_DN")
	)
	(segment
		(start 261.220204 -51.681888)
		(end 261.202678 -51.66868)
		(width 0.0889)
		(layer "In9.Cu")
		(net "CLK_100M_CPU0_RC_REFCLK1_DN")
	)
	(segment
		(start 276.653244 -60.762388)
		(end 276.620478 -60.762388)
		(width 0.0889)
		(layer "In9.Cu")
		(net "CLK_100M_CPU0_RC_REFCLK1_DN")
	)
	(segment
		(start 208.604612 -48.7045)
		(end 207.897984 -47.997872)
		(width 0.1143)
		(layer "In9.Cu")
		(net "CLK_100M_CPU0_RC_REFCLK1_DN")
	)
	(segment
		(start 177.67173 -75.376532)
		(end 177.67173 -77.976476)
		(width 0.1143)
		(layer "In9.Cu")
		(net "CLK_100M_CPU0_RC_REFCLK1_DN")
	)
	(segment
		(start 184.08904 -64.63538)
		(end 180.66004 -64.63538)
		(width 0.1143)
		(layer "In9.Cu")
		(net "CLK_100M_CPU0_RC_REFCLK1_DN")
	)
	(segment
		(start 176.796954 -78.851252)
		(end 174.990506 -78.851252)
		(width 0.1143)
		(layer "In9.Cu")
		(net "CLK_100M_CPU0_RC_REFCLK1_DN")
	)
	(segment
		(start 286.87141 -71.554086)
		(end 286.87776 -71.543418)
		(width 0.0889)
		(layer "In9.Cu")
		(net "CLK_100M_CPU0_RC_REFCLK1_DN")
	)
	(segment
		(start 173.6471 -80.194658)
		(end 173.6471 -84.791042)
		(width 0.1143)
		(layer "In9.Cu")
		(net "CLK_100M_CPU0_RC_REFCLK1_DN")
	)
	(segment
		(start 170.413172 -88.975692)
		(end 170.18254 -89.206324)
		(width 0.1143)
		(layer "In9.Cu")
		(net "CLK_100M_CPU0_RC_REFCLK1_DN")
	)
	(segment
		(start 286.866584 -71.562722)
		(end 286.87141 -71.554086)
		(width 0.0889)
		(layer "In9.Cu")
		(net "CLK_100M_CPU0_RC_REFCLK1_DN")
	)
	(segment
		(start 258.888484 -51.278282)
		(end 257.470402 -49.8602)
		(width 0.1143)
		(layer "In9.Cu")
		(net "CLK_100M_CPU0_RC_REFCLK1_DN")
	)
	(segment
		(start 267.455904 -55.479696)
		(end 267.330174 -55.479696)
		(width 0.0889)
		(layer "In9.Cu")
		(net "CLK_100M_CPU0_RC_REFCLK1_DN")
	)
	(segment
		(start 274.57146 -59.577224)
		(end 274.568158 -59.571382)
		(width 0.0889)
		(layer "In9.Cu")
		(net "CLK_100M_CPU0_RC_REFCLK1_DN")
	)
	(segment
		(start 287.21812 -72.092058)
		(end 287.160208 -72.14997)
		(width 0.0889)
		(layer "In9.Cu")
		(net "CLK_100M_CPU0_RC_REFCLK1_DN")
	)
	(segment
		(start 179.4764 -68.122546)
		(end 177.961544 -69.637402)
		(width 0.1143)
		(layer "In9.Cu")
		(net "CLK_100M_CPU0_RC_REFCLK1_DN")
	)
	(segment
		(start 285.72841 -67.591686)
		(end 285.73476 -67.581018)
		(width 0.0889)
		(layer "In9.Cu")
		(net "CLK_100M_CPU0_RC_REFCLK1_DN")
	)
	(segment
		(start 283.521404 -64.724788)
		(end 283.488638 -64.724788)
		(width 0.0889)
		(layer "In9.Cu")
		(net "CLK_100M_CPU0_RC_REFCLK1_DN")
	)
	(segment
		(start 285.723584 -66.609722)
		(end 285.72841 -66.601086)
		(width 0.0889)
		(layer "In9.Cu")
		(net "CLK_100M_CPU0_RC_REFCLK1_DN")
	)
	(segment
		(start 184.963308 -63.212218)
		(end 184.963308 -63.761112)
		(width 0.1143)
		(layer "In9.Cu")
		(net "CLK_100M_CPU0_RC_REFCLK1_DN")
	)
	(segment
		(start 179.4764 -65.81902)
		(end 179.4764 -68.122546)
		(width 0.1143)
		(layer "In9.Cu")
		(net "CLK_100M_CPU0_RC_REFCLK1_DN")
	)
	(segment
		(start 184.379362 -62.628272)
		(end 184.963308 -63.212218)
		(width 0.1143)
		(layer "In9.Cu")
		(net "CLK_100M_CPU0_RC_REFCLK1_DN")
	)
	(segment
		(start 193.6877 -49.7205)
		(end 188.936376 -49.7205)
		(width 0.1143)
		(layer "In9.Cu")
		(net "CLK_100M_CPU0_RC_REFCLK1_DN")
	)
	(arc
		(start 275.426424 -60.066936)
		(mid 275.215711 -59.853857)
		(end 274.927568 -59.771534)
		(width 0.0889)
		(layer "In9.Cu")
		(net "CLK_100M_CPU0_RC_REFCLK1_DN")
	)
	(arc
		(start 281.771598 -63.734188)
		(mid 281.577748 -63.677838)
		(end 281.436064 -63.534036)
		(width 0.0889)
		(layer "In9.Cu")
		(net "CLK_100M_CPU0_RC_REFCLK1_DN")
	)
	(arc
		(start 278.001984 -61.552836)
		(mid 277.793376 -61.340904)
		(end 277.507954 -61.257434)
		(width 0.0889)
		(layer "In9.Cu")
		(net "CLK_100M_CPU0_RC_REFCLK1_DN")
	)
	(arc
		(start 280.909268 -63.238634)
		(mid 280.717626 -63.181468)
		(end 280.577544 -63.038736)
		(width 0.0889)
		(layer "In9.Cu")
		(net "CLK_100M_CPU0_RC_REFCLK1_DN")
	)
	(arc
		(start 285.72841 -67.991736)
		(mid 285.67494 -67.796673)
		(end 285.723584 -67.600322)
		(width 0.0889)
		(layer "In9.Cu")
		(net "CLK_100M_CPU0_RC_REFCLK1_DN")
	)
	(arc
		(start 286.87141 -70.563486)
		(mid 286.950541 -70.268084)
		(end 286.87141 -69.972682)
		(width 0.0889)
		(layer "In9.Cu")
		(net "CLK_100M_CPU0_RC_REFCLK1_DN")
	)
	(arc
		(start 276.284944 -60.562236)
		(mid 276.076336 -60.350304)
		(end 275.790914 -60.266834)
		(width 0.0889)
		(layer "In9.Cu")
		(net "CLK_100M_CPU0_RC_REFCLK1_DN")
	)
	(arc
		(start 278.860504 -62.048136)
		(mid 278.6535 -61.837272)
		(end 278.370284 -61.752988)
		(width 0.0889)
		(layer "In9.Cu")
		(net "CLK_100M_CPU0_RC_REFCLK1_DN")
	)
	(arc
		(start 263.59612 -53.313838)
		(mid 263.389116 -53.102974)
		(end 263.1059 -53.01869)
		(width 0.0889)
		(layer "In9.Cu")
		(net "CLK_100M_CPU0_RC_REFCLK1_DN")
	)
	(arc
		(start 274.038314 -59.276234)
		(mid 273.848385 -59.218364)
		(end 273.709638 -59.076336)
		(width 0.0889)
		(layer "In9.Cu")
		(net "CLK_100M_CPU0_RC_REFCLK1_DN")
	)
	(arc
		(start 282.294584 -64.029336)
		(mid 282.08758 -63.818472)
		(end 281.804364 -63.734188)
		(width 0.0889)
		(layer "In9.Cu")
		(net "CLK_100M_CPU0_RC_REFCLK1_DN")
	)
	(arc
		(start 274.914614 -59.771534)
		(mid 274.717453 -59.719575)
		(end 274.57146 -59.577224)
		(width 0.0889)
		(layer "In9.Cu")
		(net "CLK_100M_CPU0_RC_REFCLK1_DN")
	)
	(arc
		(start 279.719024 -62.543436)
		(mid 279.510416 -62.331504)
		(end 279.224994 -62.248034)
		(width 0.0889)
		(layer "In9.Cu")
		(net "CLK_100M_CPU0_RC_REFCLK1_DN")
	)
	(arc
		(start 273.179794 -58.780934)
		(mid 272.989865 -58.723064)
		(end 272.851118 -58.581036)
		(width 0.0889)
		(layer "In9.Cu")
		(net "CLK_100M_CPU0_RC_REFCLK1_DN")
	)
	(arc
		(start 277.475188 -61.257434)
		(mid 277.283546 -61.200268)
		(end 277.143464 -61.057536)
		(width 0.0889)
		(layer "In9.Cu")
		(net "CLK_100M_CPU0_RC_REFCLK1_DN")
	)
	(arc
		(start 262.208264 -52.523136)
		(mid 262.018022 -52.465401)
		(end 261.87908 -52.323238)
		(width 0.0889)
		(layer "In9.Cu")
		(net "CLK_100M_CPU0_RC_REFCLK1_DN")
	)
	(arc
		(start 283.488638 -64.724788)
		(mid 283.294788 -64.668438)
		(end 283.153104 -64.524636)
		(width 0.0889)
		(layer "In9.Cu")
		(net "CLK_100M_CPU0_RC_REFCLK1_DN")
	)
	(arc
		(start 277.143464 -61.057536)
		(mid 276.93646 -60.846672)
		(end 276.653244 -60.762388)
		(width 0.0889)
		(layer "In9.Cu")
		(net "CLK_100M_CPU0_RC_REFCLK1_DN")
	)
	(arc
		(start 284.343348 -65.219834)
		(mid 284.151706 -65.162668)
		(end 284.011624 -65.019936)
		(width 0.0889)
		(layer "In9.Cu")
		(net "CLK_100M_CPU0_RC_REFCLK1_DN")
	)
	(arc
		(start 285.2166 -65.715388)
		(mid 285.019439 -65.663429)
		(end 284.873446 -65.521078)
		(width 0.0889)
		(layer "In9.Cu")
		(net "CLK_100M_CPU0_RC_REFCLK1_DN")
	)
	(arc
		(start 265.312906 -54.304438)
		(mid 265.105902 -54.093574)
		(end 264.822686 -54.00929)
		(width 0.0889)
		(layer "In9.Cu")
		(net "CLK_100M_CPU0_RC_REFCLK1_DN")
	)
	(arc
		(start 285.73476 -66.590418)
		(mid 285.730729 -66.014236)
		(end 285.23819 -65.715388)
		(width 0.0889)
		(layer "In9.Cu")
		(net "CLK_100M_CPU0_RC_REFCLK1_DN")
	)
	(arc
		(start 271.992598 -58.085736)
		(mid 271.785594 -57.874872)
		(end 271.502378 -57.790588)
		(width 0.0889)
		(layer "In9.Cu")
		(net "CLK_100M_CPU0_RC_REFCLK1_DN")
	)
	(arc
		(start 264.45464 -53.809138)
		(mid 264.246032 -53.597206)
		(end 263.96061 -53.513736)
		(width 0.0889)
		(layer "In9.Cu")
		(net "CLK_100M_CPU0_RC_REFCLK1_DN")
	)
	(arc
		(start 286.87141 -70.963536)
		(mid 286.81794 -70.768473)
		(end 286.866584 -70.572122)
		(width 0.0889)
		(layer "In9.Cu")
		(net "CLK_100M_CPU0_RC_REFCLK1_DN")
	)
	(arc
		(start 275.758148 -60.266834)
		(mid 275.566506 -60.209668)
		(end 275.426424 -60.066936)
		(width 0.0889)
		(layer "In9.Cu")
		(net "CLK_100M_CPU0_RC_REFCLK1_DN")
	)
	(arc
		(start 284.870144 -65.515236)
		(mid 284.661536 -65.303304)
		(end 284.376114 -65.219834)
		(width 0.0889)
		(layer "In9.Cu")
		(net "CLK_100M_CPU0_RC_REFCLK1_DN")
	)
	(arc
		(start 279.192228 -62.248034)
		(mid 279.000586 -62.190868)
		(end 278.860504 -62.048136)
		(width 0.0889)
		(layer "In9.Cu")
		(net "CLK_100M_CPU0_RC_REFCLK1_DN")
	)
	(arc
		(start 272.324322 -58.285634)
		(mid 272.13268 -58.228468)
		(end 271.992598 -58.085736)
		(width 0.0889)
		(layer "In9.Cu")
		(net "CLK_100M_CPU0_RC_REFCLK1_DN")
	)
	(arc
		(start 286.87776 -71.543418)
		(mid 286.950558 -71.252655)
		(end 286.87141 -70.963536)
		(width 0.0889)
		(layer "In9.Cu")
		(net "CLK_100M_CPU0_RC_REFCLK1_DN")
	)
	(arc
		(start 282.626308 -64.229234)
		(mid 282.434666 -64.172068)
		(end 282.294584 -64.029336)
		(width 0.0889)
		(layer "In9.Cu")
		(net "CLK_100M_CPU0_RC_REFCLK1_DN")
	)
	(arc
		(start 266.171426 -54.799738)
		(mid 265.962818 -54.587806)
		(end 265.677396 -54.504336)
		(width 0.0889)
		(layer "In9.Cu")
		(net "CLK_100M_CPU0_RC_REFCLK1_DN")
	)
	(arc
		(start 287.160208 -72.14997)
		(mid 286.860172 -71.932958)
		(end 286.866584 -71.562722)
		(width 0.0889)
		(layer "In9.Cu")
		(net "CLK_100M_CPU0_RC_REFCLK1_DN")
	)
	(arc
		(start 281.436064 -63.534036)
		(mid 281.227456 -63.322104)
		(end 280.942034 -63.238634)
		(width 0.0889)
		(layer "In9.Cu")
		(net "CLK_100M_CPU0_RC_REFCLK1_DN")
	)
	(arc
		(start 278.337518 -61.752988)
		(mid 278.143668 -61.696638)
		(end 278.001984 -61.552836)
		(width 0.0889)
		(layer "In9.Cu")
		(net "CLK_100M_CPU0_RC_REFCLK1_DN")
	)
	(arc
		(start 271.109948 -57.592468)
		(mid 270.953273 -57.405894)
		(end 270.736314 -57.295034)
		(width 0.0889)
		(layer "In9.Cu")
		(net "CLK_100M_CPU0_RC_REFCLK1_DN")
	)
	(arc
		(start 265.64463 -54.504336)
		(mid 265.452988 -54.44717)
		(end 265.312906 -54.304438)
		(width 0.0889)
		(layer "In9.Cu")
		(net "CLK_100M_CPU0_RC_REFCLK1_DN")
	)
	(arc
		(start 263.927844 -53.513736)
		(mid 263.736202 -53.45657)
		(end 263.59612 -53.313838)
		(width 0.0889)
		(layer "In9.Cu")
		(net "CLK_100M_CPU0_RC_REFCLK1_DN")
	)
	(arc
		(start 276.620478 -60.762388)
		(mid 276.426628 -60.706038)
		(end 276.284944 -60.562236)
		(width 0.0889)
		(layer "In9.Cu")
		(net "CLK_100M_CPU0_RC_REFCLK1_DN")
	)
	(arc
		(start 263.073134 -53.01869)
		(mid 262.879284 -52.96234)
		(end 262.7376 -52.818538)
		(width 0.0889)
		(layer "In9.Cu")
		(net "CLK_100M_CPU0_RC_REFCLK1_DN")
	)
	(arc
		(start 264.801096 -54.00929)
		(mid 264.603935 -53.957331)
		(end 264.457942 -53.81498)
		(width 0.0889)
		(layer "In9.Cu")
		(net "CLK_100M_CPU0_RC_REFCLK1_DN")
	)
	(arc
		(start 262.7376 -52.818538)
		(mid 262.528992 -52.606606)
		(end 262.24357 -52.523136)
		(width 0.0889)
		(layer "In9.Cu")
		(net "CLK_100M_CPU0_RC_REFCLK1_DN")
	)
	(arc
		(start 280.577544 -63.038736)
		(mid 280.37054 -62.827872)
		(end 280.087324 -62.743588)
		(width 0.0889)
		(layer "In9.Cu")
		(net "CLK_100M_CPU0_RC_REFCLK1_DN")
	)
	(arc
		(start 271.345914 -57.790588)
		(mid 271.209245 -57.713795)
		(end 271.109948 -57.592468)
		(width 0.0889)
		(layer "In9.Cu")
		(net "CLK_100M_CPU0_RC_REFCLK1_DN")
	)
	(arc
		(start 272.851118 -58.581036)
		(mid 272.640405 -58.367957)
		(end 272.352262 -58.285634)
		(width 0.0889)
		(layer "In9.Cu")
		(net "CLK_100M_CPU0_RC_REFCLK1_DN")
	)
	(arc
		(start 285.72841 -67.001136)
		(mid 285.67494 -66.806073)
		(end 285.723584 -66.609722)
		(width 0.0889)
		(layer "In9.Cu")
		(net "CLK_100M_CPU0_RC_REFCLK1_DN")
	)
	(arc
		(start 273.709638 -59.076336)
		(mid 273.50103 -58.864404)
		(end 273.215608 -58.780934)
		(width 0.0889)
		(layer "In9.Cu")
		(net "CLK_100M_CPU0_RC_REFCLK1_DN")
	)
	(arc
		(start 285.73476 -67.581018)
		(mid 285.807558 -67.290255)
		(end 285.72841 -67.001136)
		(width 0.0889)
		(layer "In9.Cu")
		(net "CLK_100M_CPU0_RC_REFCLK1_DN")
	)
	(arc
		(start 280.054558 -62.743588)
		(mid 279.860708 -62.687238)
		(end 279.719024 -62.543436)
		(width 0.0889)
		(layer "In9.Cu")
		(net "CLK_100M_CPU0_RC_REFCLK1_DN")
	)
	(arc
		(start 284.011624 -65.019936)
		(mid 283.80462 -64.809072)
		(end 283.521404 -64.724788)
		(width 0.0889)
		(layer "In9.Cu")
		(net "CLK_100M_CPU0_RC_REFCLK1_DN")
	)
	(arc
		(start 283.153104 -64.524636)
		(mid 282.944496 -64.312704)
		(end 282.659074 -64.229234)
		(width 0.0889)
		(layer "In9.Cu")
		(net "CLK_100M_CPU0_RC_REFCLK1_DN")
	)
	(arc
		(start 274.568158 -59.571382)
		(mid 274.361154 -59.360518)
		(end 274.077938 -59.276234)
		(width 0.0889)
		(layer "In9.Cu")
		(net "CLK_100M_CPU0_RC_REFCLK1_DN")
	)
	(arc
		(start 266.503658 -54.99989)
		(mid 266.311641 -54.942782)
		(end 266.171426 -54.799738)
		(width 0.0889)
		(layer "In9.Cu")
		(net "CLK_100M_CPU0_RC_REFCLK1_DN")
	)
	(segment
		(start 475.6912 -41.7576)
		(end 474.366336 -41.7576)
		(width 0.10795)
		(layer "F.Cu")
		(net "XTAL_25MHZ_OUT_R")
	)
	(segment
		(start 475.9325 -41.9989)
		(end 475.6912 -41.7576)
		(width 0.10795)
		(layer "F.Cu")
		(net "XTAL_25MHZ_OUT_R")
	)
	(segment
		(start 476.9612 -42.1894)
		(end 476.7707 -41.9989)
		(width 0.10795)
		(layer "F.Cu")
		(net "XTAL_25MHZ_OUT_R")
	)
	(segment
		(start 476.7707 -41.9989)
		(end 476.4786 -41.9989)
		(width 0.10795)
		(layer "F.Cu")
		(net "XTAL_25MHZ_OUT_R")
	)
	(segment
		(start 474.366336 -41.7576)
		(end 473.3925 -42.731436)
		(width 0.10795)
		(layer "F.Cu")
		(net "XTAL_25MHZ_OUT_R")
	)
	(segment
		(start 476.4786 -41.9989)
		(end 475.9325 -41.9989)
		(width 0.10795)
		(layer "F.Cu")
		(net "XTAL_25MHZ_OUT_R")
	)
	(segment
		(start 477.3041 -42.1894)
		(end 476.9612 -42.1894)
		(width 0.10795)
		(layer "F.Cu")
		(net "XTAL_25MHZ_OUT_R")
	)
	(segment
		(start 374.33504 -110.16488)
		(end 374.18772 -110.3122)
		(width 0.0889)
		(layer "F.Cu")
		(net "TP_CLK_100M_NSSCC1_DP")
	)
	(segment
		(start 375.531126 -110.355126)
		(end 375.219976 -110.043976)
		(width 0.0889)
		(layer "F.Cu")
		(net "TP_CLK_100M_NSSCC1_DP")
	)
	(segment
		(start 375.219976 -110.043976)
		(end 374.934734 -110.043976)
		(width 0.0889)
		(layer "F.Cu")
		(net "TP_CLK_100M_NSSCC1_DP")
	)
	(segment
		(start 375.92 -110.355126)
		(end 375.531126 -110.355126)
		(width 0.0889)
		(layer "F.Cu")
		(net "TP_CLK_100M_NSSCC1_DP")
	)
	(segment
		(start 373.732806 -110.3122)
		(end 373.362474 -109.941868)
		(width 0.0889)
		(layer "F.Cu")
		(net "TP_CLK_100M_NSSCC1_DP")
	)
	(segment
		(start 374.814084 -110.164626)
		(end 374.384062 -110.164626)
		(width 0.0889)
		(layer "F.Cu")
		(net "TP_CLK_100M_NSSCC1_DP")
	)
	(segment
		(start 374.383808 -110.16488)
		(end 374.33504 -110.16488)
		(width 0.0889)
		(layer "F.Cu")
		(net "TP_CLK_100M_NSSCC1_DP")
	)
	(segment
		(start 374.18772 -110.3122)
		(end 373.732806 -110.3122)
		(width 0.0889)
		(layer "F.Cu")
		(net "TP_CLK_100M_NSSCC1_DP")
	)
	(segment
		(start 374.384062 -110.164626)
		(end 374.383808 -110.16488)
		(width 0.0889)
		(layer "F.Cu")
		(net "TP_CLK_100M_NSSCC1_DP")
	)
	(segment
		(start 374.934734 -110.043976)
		(end 374.814084 -110.164626)
		(width 0.0889)
		(layer "F.Cu")
		(net "TP_CLK_100M_NSSCC1_DP")
	)
	(via
		(at 373.362474 -109.941868)
		(size 0.508)
		(drill 0.254)
		(layers "F.Cu" "B.Cu")
		(net "TP_CLK_100M_NSSCC1_DP")
	)
	(segment
		(start 375.089928 -110.355126)
		(end 374.4214 -110.355126)
		(width 0.0889)
		(layer "F.Cu")
		(net "TP_CLK_100M_NSSCC1_DN")
	)
	(segment
		(start 373.249444 -110.5027)
		(end 372.70817 -109.961426)
		(width 0.0889)
		(layer "F.Cu")
		(net "TP_CLK_100M_NSSCC1_DN")
	)
	(segment
		(start 374.4214 -110.355126)
		(end 374.273826 -110.5027)
		(width 0.0889)
		(layer "F.Cu")
		(net "TP_CLK_100M_NSSCC1_DN")
	)
	(segment
		(start 374.273826 -110.5027)
		(end 373.249444 -110.5027)
		(width 0.0889)
		(layer "F.Cu")
		(net "TP_CLK_100M_NSSCC1_DN")
	)
	(via
		(at 372.70817 -109.961426)
		(size 0.508)
		(drill 0.254)
		(layers "F.Cu" "B.Cu")
		(net "TP_CLK_100M_NSSCC1_DN")
	)
	(segment
		(start 131.089908 -70.268084)
		(end 131.661408 -70.268084)
		(width 0.10795)
		(layer "F.Cu")
		(net "PD_CPU1_KSFC_DIS")
	)
	(via
		(at 131.661408 -70.268084)
		(size 0.508)
		(drill 0.254)
		(layers "F.Cu" "B.Cu")
		(net "PD_CPU1_KSFC_DIS")
	)
	(segment
		(start 124.597414 -73.766426)
		(end 124.10948 -73.278492)
		(width 0.10795)
		(layer "B.Cu")
		(net "PD_CPU1_KSFC_DIS")
	)
	(segment
		(start 122.8598 -73.6854)
		(end 122.428 -73.2536)
		(width 0.10795)
		(layer "B.Cu")
		(net "PD_CPU1_KSFC_DIS")
	)
	(segment
		(start 118.773448 -73.56983)
		(end 118.37797 -73.56983)
		(width 0.10795)
		(layer "B.Cu")
		(net "PD_CPU1_KSFC_DIS")
	)
	(segment
		(start 117.221 -74.7268)
		(end 117.221 -74.93)
		(width 0.10795)
		(layer "B.Cu")
		(net "PD_CPU1_KSFC_DIS")
	)
	(segment
		(start 122.428 -73.2536)
		(end 122.047 -73.2536)
		(width 0.10795)
		(layer "B.Cu")
		(net "PD_CPU1_KSFC_DIS")
	)
	(segment
		(start 129.748026 -70.69201)
		(end 129.193036 -71.247)
		(width 0.10795)
		(layer "B.Cu")
		(net "PD_CPU1_KSFC_DIS")
	)
	(segment
		(start 130.631692 -70.268084)
		(end 130.207766 -70.69201)
		(width 0.10795)
		(layer "B.Cu")
		(net "PD_CPU1_KSFC_DIS")
	)
	(segment
		(start 125.000766 -73.766426)
		(end 124.597414 -73.766426)
		(width 0.10795)
		(layer "B.Cu")
		(net "PD_CPU1_KSFC_DIS")
	)
	(segment
		(start 131.661408 -70.268084)
		(end 130.631692 -70.268084)
		(width 0.10795)
		(layer "B.Cu")
		(net "PD_CPU1_KSFC_DIS")
	)
	(segment
		(start 119.064278 -73.279)
		(end 118.773448 -73.56983)
		(width 0.10795)
		(layer "B.Cu")
		(net "PD_CPU1_KSFC_DIS")
	)
	(segment
		(start 125.8062 -73.2536)
		(end 125.513592 -73.2536)
		(width 0.10795)
		(layer "B.Cu")
		(net "PD_CPU1_KSFC_DIS")
	)
	(segment
		(start 125.513592 -73.2536)
		(end 125.000766 -73.766426)
		(width 0.10795)
		(layer "B.Cu")
		(net "PD_CPU1_KSFC_DIS")
	)
	(segment
		(start 121.622312 -73.678288)
		(end 121.049288 -73.678288)
		(width 0.10795)
		(layer "B.Cu")
		(net "PD_CPU1_KSFC_DIS")
	)
	(segment
		(start 124.10948 -73.278492)
		(end 123.647708 -73.278492)
		(width 0.10795)
		(layer "B.Cu")
		(net "PD_CPU1_KSFC_DIS")
	)
	(segment
		(start 123.2408 -73.6854)
		(end 122.8598 -73.6854)
		(width 0.10795)
		(layer "B.Cu")
		(net "PD_CPU1_KSFC_DIS")
	)
	(segment
		(start 121.049288 -73.678288)
		(end 120.65 -73.279)
		(width 0.10795)
		(layer "B.Cu")
		(net "PD_CPU1_KSFC_DIS")
	)
	(segment
		(start 128.2954 -71.8312)
		(end 127.889 -71.8312)
		(width 0.10795)
		(layer "B.Cu")
		(net "PD_CPU1_KSFC_DIS")
	)
	(segment
		(start 128.8796 -71.247)
		(end 128.2954 -71.8312)
		(width 0.10795)
		(layer "B.Cu")
		(net "PD_CPU1_KSFC_DIS")
	)
	(segment
		(start 122.047 -73.2536)
		(end 121.622312 -73.678288)
		(width 0.10795)
		(layer "B.Cu")
		(net "PD_CPU1_KSFC_DIS")
	)
	(segment
		(start 129.193036 -71.247)
		(end 128.8796 -71.247)
		(width 0.10795)
		(layer "B.Cu")
		(net "PD_CPU1_KSFC_DIS")
	)
	(segment
		(start 127.15113 -72.200262)
		(end 126.580392 -72.771)
		(width 0.10795)
		(layer "B.Cu")
		(net "PD_CPU1_KSFC_DIS")
	)
	(segment
		(start 126.580392 -72.771)
		(end 126.2888 -72.771)
		(width 0.10795)
		(layer "B.Cu")
		(net "PD_CPU1_KSFC_DIS")
	)
	(segment
		(start 127.519938 -72.200262)
		(end 127.15113 -72.200262)
		(width 0.10795)
		(layer "B.Cu")
		(net "PD_CPU1_KSFC_DIS")
	)
	(segment
		(start 126.2888 -72.771)
		(end 125.8062 -73.2536)
		(width 0.10795)
		(layer "B.Cu")
		(net "PD_CPU1_KSFC_DIS")
	)
	(segment
		(start 120.65 -73.279)
		(end 119.064278 -73.279)
		(width 0.10795)
		(layer "B.Cu")
		(net "PD_CPU1_KSFC_DIS")
	)
	(segment
		(start 123.647708 -73.278492)
		(end 123.2408 -73.6854)
		(width 0.10795)
		(layer "B.Cu")
		(net "PD_CPU1_KSFC_DIS")
	)
	(segment
		(start 127.889 -71.8312)
		(end 127.519938 -72.200262)
		(width 0.10795)
		(layer "B.Cu")
		(net "PD_CPU1_KSFC_DIS")
	)
	(segment
		(start 118.37797 -73.56983)
		(end 117.221 -74.7268)
		(width 0.10795)
		(layer "B.Cu")
		(net "PD_CPU1_KSFC_DIS")
	)
	(segment
		(start 130.207766 -70.69201)
		(end 129.748026 -70.69201)
		(width 0.10795)
		(layer "B.Cu")
		(net "PD_CPU1_KSFC_DIS")
	)
	(segment
		(start 296.66184 -70.268084)
		(end 296.09034 -70.268084)
		(width 0.10795)
		(layer "F.Cu")
		(net "PD_CPU0_KSFC_DIS")
	)
	(via
		(at 296.66184 -70.268084)
		(size 0.508)
		(drill 0.254)
		(layers "F.Cu" "B.Cu")
		(net "PD_CPU0_KSFC_DIS")
	)
	(via
		(at 285.307024 -71.877936)
		(size 0.6604)
		(drill 0.3302)
		(layers "F.Cu" "B.Cu")
		(net "PD_CPU0_KSFC_DIS")
	)
	(segment
		(start 296.009822 -70.271132)
		(end 296.01287 -70.268084)
		(width 0.10795)
		(layer "B.Cu")
		(net "PD_CPU0_KSFC_DIS")
	)
	(segment
		(start 293.420546 -69.85)
		(end 293.925752 -70.355206)
		(width 0.10795)
		(layer "B.Cu")
		(net "PD_CPU0_KSFC_DIS")
	)
	(segment
		(start 289.991546 -69.8246)
		(end 290.522152 -70.355206)
		(width 0.10795)
		(layer "B.Cu")
		(net "PD_CPU0_KSFC_DIS")
	)
	(segment
		(start 294.211248 -70.355206)
		(end 294.741854 -69.8246)
		(width 0.10795)
		(layer "B.Cu")
		(net "PD_CPU0_KSFC_DIS")
	)
	(segment
		(start 288.724594 -70.355206)
		(end 289.029648 -70.355206)
		(width 0.10795)
		(layer "B.Cu")
		(net "PD_CPU0_KSFC_DIS")
	)
	(segment
		(start 296.01287 -70.268084)
		(end 296.66184 -70.268084)
		(width 0.10795)
		(layer "B.Cu")
		(net "PD_CPU0_KSFC_DIS")
	)
	(segment
		(start 284.960314 -72.224646)
		(end 285.307024 -71.877936)
		(width 0.10795)
		(layer "B.Cu")
		(net "PD_CPU0_KSFC_DIS")
	)
	(segment
		(start 284.26537 -73.23963)
		(end 284.6324 -73.23963)
		(width 0.10795)
		(layer "B.Cu")
		(net "PD_CPU0_KSFC_DIS")
	)
	(segment
		(start 291.752528 -70.766432)
		(end 292.163754 -70.355206)
		(width 0.10795)
		(layer "B.Cu")
		(net "PD_CPU0_KSFC_DIS")
	)
	(segment
		(start 292.989254 -69.85)
		(end 293.420546 -69.85)
		(width 0.10795)
		(layer "B.Cu")
		(net "PD_CPU0_KSFC_DIS")
	)
	(segment
		(start 282.2702 -74.803)
		(end 282.702 -74.803)
		(width 0.10795)
		(layer "B.Cu")
		(net "PD_CPU0_KSFC_DIS")
	)
	(segment
		(start 284.6324 -73.23963)
		(end 284.960314 -72.911716)
		(width 0.10795)
		(layer "B.Cu")
		(net "PD_CPU0_KSFC_DIS")
	)
	(segment
		(start 292.163754 -70.355206)
		(end 292.484048 -70.355206)
		(width 0.10795)
		(layer "B.Cu")
		(net "PD_CPU0_KSFC_DIS")
	)
	(segment
		(start 290.821364 -70.355206)
		(end 291.23259 -70.766432)
		(width 0.10795)
		(layer "B.Cu")
		(net "PD_CPU0_KSFC_DIS")
	)
	(segment
		(start 287.024318 -71.171562)
		(end 287.387284 -71.171562)
		(width 0.10795)
		(layer "B.Cu")
		(net "PD_CPU0_KSFC_DIS")
	)
	(segment
		(start 290.522152 -70.355206)
		(end 290.821364 -70.355206)
		(width 0.10795)
		(layer "B.Cu")
		(net "PD_CPU0_KSFC_DIS")
	)
	(segment
		(start 289.560254 -69.8246)
		(end 289.991546 -69.8246)
		(width 0.10795)
		(layer "B.Cu")
		(net "PD_CPU0_KSFC_DIS")
	)
	(segment
		(start 289.029648 -70.355206)
		(end 289.560254 -69.8246)
		(width 0.10795)
		(layer "B.Cu")
		(net "PD_CPU0_KSFC_DIS")
	)
	(segment
		(start 282.702 -74.803)
		(end 284.26537 -73.23963)
		(width 0.10795)
		(layer "B.Cu")
		(net "PD_CPU0_KSFC_DIS")
	)
	(segment
		(start 285.307024 -71.877936)
		(end 285.50616 -71.6788)
		(width 0.10795)
		(layer "B.Cu")
		(net "PD_CPU0_KSFC_DIS")
	)
	(segment
		(start 286.51708 -71.6788)
		(end 287.024318 -71.171562)
		(width 0.10795)
		(layer "B.Cu")
		(net "PD_CPU0_KSFC_DIS")
	)
	(segment
		(start 293.925752 -70.355206)
		(end 294.211248 -70.355206)
		(width 0.10795)
		(layer "B.Cu")
		(net "PD_CPU0_KSFC_DIS")
	)
	(segment
		(start 294.741854 -69.8246)
		(end 295.122346 -69.8246)
		(width 0.10795)
		(layer "B.Cu")
		(net "PD_CPU0_KSFC_DIS")
	)
	(segment
		(start 287.387284 -71.171562)
		(end 287.769046 -70.7898)
		(width 0.10795)
		(layer "B.Cu")
		(net "PD_CPU0_KSFC_DIS")
	)
	(segment
		(start 292.484048 -70.355206)
		(end 292.989254 -69.85)
		(width 0.10795)
		(layer "B.Cu")
		(net "PD_CPU0_KSFC_DIS")
	)
	(segment
		(start 284.960314 -72.911716)
		(end 284.960314 -72.224646)
		(width 0.10795)
		(layer "B.Cu")
		(net "PD_CPU0_KSFC_DIS")
	)
	(segment
		(start 295.568878 -70.271132)
		(end 296.009822 -70.271132)
		(width 0.10795)
		(layer "B.Cu")
		(net "PD_CPU0_KSFC_DIS")
	)
	(segment
		(start 287.769046 -70.7898)
		(end 288.29 -70.7898)
		(width 0.10795)
		(layer "B.Cu")
		(net "PD_CPU0_KSFC_DIS")
	)
	(segment
		(start 291.23259 -70.766432)
		(end 291.752528 -70.766432)
		(width 0.10795)
		(layer "B.Cu")
		(net "PD_CPU0_KSFC_DIS")
	)
	(segment
		(start 285.50616 -71.6788)
		(end 286.51708 -71.6788)
		(width 0.10795)
		(layer "B.Cu")
		(net "PD_CPU0_KSFC_DIS")
	)
	(segment
		(start 288.29 -70.7898)
		(end 288.724594 -70.355206)
		(width 0.10795)
		(layer "B.Cu")
		(net "PD_CPU0_KSFC_DIS")
	)
	(segment
		(start 295.122346 -69.8246)
		(end 295.568878 -70.271132)
		(width 0.10795)
		(layer "B.Cu")
		(net "PD_CPU0_KSFC_DIS")
	)
	(segment
		(start 163.576 -82.9437)
		(end 163.576 -83.058)
		(width 0.127)
		(layer "F.Cu")
		(net "CLK_100M_CPU1_PE_REFCLK_R_DP")
	)
	(segment
		(start 165.054026 -82.212434)
		(end 164.307266 -82.212434)
		(width 0.127)
		(layer "F.Cu")
		(net "CLK_100M_CPU1_PE_REFCLK_R_DP")
	)
	(segment
		(start 164.307266 -82.212434)
		(end 163.576 -82.9437)
		(width 0.127)
		(layer "F.Cu")
		(net "CLK_100M_CPU1_PE_REFCLK_R_DP")
	)
	(segment
		(start 164.497766 -81.907634)
		(end 164.180774 -81.907634)
		(width 0.127)
		(layer "F.Cu")
		(net "CLK_100M_CPU1_PE_REFCLK_R_DN")
	)
	(segment
		(start 165.054026 -81.712308)
		(end 164.693092 -81.712308)
		(width 0.127)
		(layer "F.Cu")
		(net "CLK_100M_CPU1_PE_REFCLK_R_DN")
	)
	(segment
		(start 163.576 -81.9785)
		(end 163.576 -81.788)
		(width 0.127)
		(layer "F.Cu")
		(net "CLK_100M_CPU1_PE_REFCLK_R_DN")
	)
	(segment
		(start 164.693092 -81.712308)
		(end 164.497766 -81.907634)
		(width 0.127)
		(layer "F.Cu")
		(net "CLK_100M_CPU1_PE_REFCLK_R_DN")
	)
	(segment
		(start 163.982908 -82.1055)
		(end 163.703 -82.1055)
		(width 0.127)
		(layer "F.Cu")
		(net "CLK_100M_CPU1_PE_REFCLK_R_DN")
	)
	(segment
		(start 164.180774 -81.907634)
		(end 163.982908 -82.1055)
		(width 0.127)
		(layer "F.Cu")
		(net "CLK_100M_CPU1_PE_REFCLK_R_DN")
	)
	(segment
		(start 163.703 -82.1055)
		(end 163.576 -81.9785)
		(width 0.127)
		(layer "F.Cu")
		(net "CLK_100M_CPU1_PE_REFCLK_R_DN")
	)
	(segment
		(start 175.250094 -84.451698)
		(end 175.387 -84.314792)
		(width 0.127)
		(layer "F.Cu")
		(net "CLK_100M_CPU0_PE_REFCLK_R_DP")
	)
	(segment
		(start 175.387 -84.314792)
		(end 175.387 -83.947)
		(width 0.127)
		(layer "F.Cu")
		(net "CLK_100M_CPU0_PE_REFCLK_R_DP")
	)
	(segment
		(start 175.088042 -84.451698)
		(end 175.250094 -84.451698)
		(width 0.127)
		(layer "F.Cu")
		(net "CLK_100M_CPU0_PE_REFCLK_R_DP")
	)
	(segment
		(start 174.079408 -83.712812)
		(end 174.199296 -83.8327)
		(width 0.127)
		(layer "F.Cu")
		(net "CLK_100M_CPU0_PE_REFCLK_R_DP")
	)
	(segment
		(start 173.791626 -83.712812)
		(end 174.079408 -83.712812)
		(width 0.127)
		(layer "F.Cu")
		(net "CLK_100M_CPU0_PE_REFCLK_R_DP")
	)
	(segment
		(start 174.199296 -83.8327)
		(end 174.469044 -83.8327)
		(width 0.127)
		(layer "F.Cu")
		(net "CLK_100M_CPU0_PE_REFCLK_R_DP")
	)
	(segment
		(start 174.469044 -83.8327)
		(end 175.088042 -84.451698)
		(width 0.127)
		(layer "F.Cu")
		(net "CLK_100M_CPU0_PE_REFCLK_R_DP")
	)
	(segment
		(start 175.282098 -84.756498)
		(end 175.387 -84.8614)
		(width 0.127)
		(layer "F.Cu")
		(net "CLK_100M_CPU0_PE_REFCLK_R_DN")
	)
	(segment
		(start 174.342552 -84.1375)
		(end 174.96155 -84.756498)
		(width 0.127)
		(layer "F.Cu")
		(net "CLK_100M_CPU0_PE_REFCLK_R_DN")
	)
	(segment
		(start 175.387 -84.8614)
		(end 175.387 -85.217)
		(width 0.127)
		(layer "F.Cu")
		(net "CLK_100M_CPU0_PE_REFCLK_R_DN")
	)
	(segment
		(start 174.2059 -84.1375)
		(end 174.342552 -84.1375)
		(width 0.127)
		(layer "F.Cu")
		(net "CLK_100M_CPU0_PE_REFCLK_R_DN")
	)
	(segment
		(start 174.130462 -84.212938)
		(end 174.2059 -84.1375)
		(width 0.127)
		(layer "F.Cu")
		(net "CLK_100M_CPU0_PE_REFCLK_R_DN")
	)
	(segment
		(start 173.791626 -84.212938)
		(end 174.130462 -84.212938)
		(width 0.127)
		(layer "F.Cu")
		(net "CLK_100M_CPU0_PE_REFCLK_R_DN")
	)
	(segment
		(start 174.96155 -84.756498)
		(end 175.282098 -84.756498)
		(width 0.127)
		(layer "F.Cu")
		(net "CLK_100M_CPU0_PE_REFCLK_R_DN")
	)
	(segment
		(start 164.342572 -77.531976)
		(end 163.6903 -77.531976)
		(width 0.1143)
		(layer "F.Cu")
		(net "CLK_100M_CPU1_RC_REFCLK1_R_DP")
	)
	(segment
		(start 163.576 -77.646276)
		(end 163.576 -77.978)
		(width 0.1143)
		(layer "F.Cu")
		(net "CLK_100M_CPU1_RC_REFCLK1_R_DP")
	)
	(segment
		(start 164.521896 -77.7113)
		(end 164.342572 -77.531976)
		(width 0.1143)
		(layer "F.Cu")
		(net "CLK_100M_CPU1_RC_REFCLK1_R_DP")
	)
	(segment
		(start 163.6903 -77.531976)
		(end 163.576 -77.646276)
		(width 0.1143)
		(layer "F.Cu")
		(net "CLK_100M_CPU1_RC_REFCLK1_R_DP")
	)
	(segment
		(start 165.054026 -77.7113)
		(end 164.521896 -77.7113)
		(width 0.1143)
		(layer "F.Cu")
		(net "CLK_100M_CPU1_RC_REFCLK1_R_DP")
	)
	(segment
		(start 164.442648 -77.290676)
		(end 163.811712 -77.290676)
		(width 0.1143)
		(layer "F.Cu")
		(net "CLK_100M_CPU1_RC_REFCLK1_R_DN")
	)
	(segment
		(start 163.811712 -77.290676)
		(end 163.576 -77.054964)
		(width 0.1143)
		(layer "F.Cu")
		(net "CLK_100M_CPU1_RC_REFCLK1_R_DN")
	)
	(segment
		(start 164.52215 -77.211174)
		(end 164.442648 -77.290676)
		(width 0.1143)
		(layer "F.Cu")
		(net "CLK_100M_CPU1_RC_REFCLK1_R_DN")
	)
	(segment
		(start 165.054026 -77.211174)
		(end 164.52215 -77.211174)
		(width 0.1143)
		(layer "F.Cu")
		(net "CLK_100M_CPU1_RC_REFCLK1_R_DN")
	)
	(segment
		(start 163.576 -77.054964)
		(end 163.576 -76.708)
		(width 0.1143)
		(layer "F.Cu")
		(net "CLK_100M_CPU1_RC_REFCLK1_R_DN")
	)
	(segment
		(start 165.054026 -79.711804)
		(end 164.700204 -79.711804)
		(width 0.127)
		(layer "F.Cu")
		(net "CLK_100M_CPU1_RC_REFCLK0_R_DP")
	)
	(segment
		(start 164.700204 -79.711804)
		(end 164.587936 -79.599536)
		(width 0.127)
		(layer "F.Cu")
		(net "CLK_100M_CPU1_RC_REFCLK0_R_DP")
	)
	(segment
		(start 164.426138 -79.599536)
		(end 163.99129 -80.034384)
		(width 0.127)
		(layer "F.Cu")
		(net "CLK_100M_CPU1_RC_REFCLK0_R_DP")
	)
	(segment
		(start 163.99129 -80.034384)
		(end 163.68395 -80.034384)
		(width 0.127)
		(layer "F.Cu")
		(net "CLK_100M_CPU1_RC_REFCLK0_R_DP")
	)
	(segment
		(start 164.587936 -79.599536)
		(end 164.426138 -79.599536)
		(width 0.127)
		(layer "F.Cu")
		(net "CLK_100M_CPU1_RC_REFCLK0_R_DP")
	)
	(segment
		(start 163.68395 -80.034384)
		(end 163.576 -80.142334)
		(width 0.127)
		(layer "F.Cu")
		(net "CLK_100M_CPU1_RC_REFCLK0_R_DP")
	)
	(segment
		(start 163.576 -80.142334)
		(end 163.576 -80.518)
		(width 0.127)
		(layer "F.Cu")
		(net "CLK_100M_CPU1_RC_REFCLK0_R_DP")
	)
	(segment
		(start 164.299646 -79.294736)
		(end 163.864798 -79.729584)
		(width 0.127)
		(layer "F.Cu")
		(net "CLK_100M_CPU1_RC_REFCLK0_R_DN")
	)
	(segment
		(start 163.651184 -79.729584)
		(end 163.576 -79.6544)
		(width 0.127)
		(layer "F.Cu")
		(net "CLK_100M_CPU1_RC_REFCLK0_R_DN")
	)
	(segment
		(start 163.576 -79.6544)
		(end 163.576 -79.248)
		(width 0.127)
		(layer "F.Cu")
		(net "CLK_100M_CPU1_RC_REFCLK0_R_DN")
	)
	(segment
		(start 165.054026 -79.211678)
		(end 164.691822 -79.211678)
		(width 0.127)
		(layer "F.Cu")
		(net "CLK_100M_CPU1_RC_REFCLK0_R_DN")
	)
	(segment
		(start 164.608764 -79.294736)
		(end 164.299646 -79.294736)
		(width 0.127)
		(layer "F.Cu")
		(net "CLK_100M_CPU1_RC_REFCLK0_R_DN")
	)
	(segment
		(start 164.691822 -79.211678)
		(end 164.608764 -79.294736)
		(width 0.127)
		(layer "F.Cu")
		(net "CLK_100M_CPU1_RC_REFCLK0_R_DN")
	)
	(segment
		(start 163.864798 -79.729584)
		(end 163.651184 -79.729584)
		(width 0.127)
		(layer "F.Cu")
		(net "CLK_100M_CPU1_RC_REFCLK0_R_DN")
	)
	(segment
		(start 170.551856 -85.955632)
		(end 170.551856 -86.105746)
		(width 0.1143)
		(layer "F.Cu")
		(net "CLK_100M_CPU0_RC_REFCLK1_R_DP")
	)
	(segment
		(start 170.673268 -85.330792)
		(end 170.673268 -85.83422)
		(width 0.1143)
		(layer "F.Cu")
		(net "CLK_100M_CPU0_RC_REFCLK1_R_DP")
	)
	(segment
		(start 170.683936 -86.237826)
		(end 170.683936 -86.597998)
		(width 0.1143)
		(layer "F.Cu")
		(net "CLK_100M_CPU0_RC_REFCLK1_R_DP")
	)
	(segment
		(start 170.953938 -86.868)
		(end 171.196 -86.868)
		(width 0.1143)
		(layer "F.Cu")
		(net "CLK_100M_CPU0_RC_REFCLK1_R_DP")
	)
	(segment
		(start 170.551856 -86.105746)
		(end 170.683936 -86.237826)
		(width 0.1143)
		(layer "F.Cu")
		(net "CLK_100M_CPU0_RC_REFCLK1_R_DP")
	)
	(segment
		(start 170.683936 -86.597998)
		(end 170.953938 -86.868)
		(width 0.1143)
		(layer "F.Cu")
		(net "CLK_100M_CPU0_RC_REFCLK1_R_DP")
	)
	(segment
		(start 170.673268 -85.83422)
		(end 170.551856 -85.955632)
		(width 0.1143)
		(layer "F.Cu")
		(net "CLK_100M_CPU0_RC_REFCLK1_R_DP")
	)
	(segment
		(start 170.442636 -86.597998)
		(end 170.172634 -86.868)
		(width 0.1143)
		(layer "F.Cu")
		(net "CLK_100M_CPU0_RC_REFCLK1_R_DN")
	)
	(segment
		(start 170.173142 -85.330792)
		(end 170.173142 -85.828632)
		(width 0.1143)
		(layer "F.Cu")
		(net "CLK_100M_CPU0_RC_REFCLK1_R_DN")
	)
	(segment
		(start 170.173142 -85.828632)
		(end 170.310556 -85.966046)
		(width 0.1143)
		(layer "F.Cu")
		(net "CLK_100M_CPU0_RC_REFCLK1_R_DN")
	)
	(segment
		(start 170.172634 -86.868)
		(end 169.926 -86.868)
		(width 0.1143)
		(layer "F.Cu")
		(net "CLK_100M_CPU0_RC_REFCLK1_R_DN")
	)
	(segment
		(start 170.310556 -86.205822)
		(end 170.442636 -86.337902)
		(width 0.1143)
		(layer "F.Cu")
		(net "CLK_100M_CPU0_RC_REFCLK1_R_DN")
	)
	(segment
		(start 170.442636 -86.337902)
		(end 170.442636 -86.597998)
		(width 0.1143)
		(layer "F.Cu")
		(net "CLK_100M_CPU0_RC_REFCLK1_R_DN")
	)
	(segment
		(start 170.310556 -85.966046)
		(end 170.310556 -86.205822)
		(width 0.1143)
		(layer "F.Cu")
		(net "CLK_100M_CPU0_RC_REFCLK1_R_DN")
	)
	(segment
		(start 172.57014 -85.74786)
		(end 172.57014 -85.952838)
		(width 0.127)
		(layer "F.Cu")
		(net "CLK_100M_CPU0_RC_REFCLK0_R_DP")
	)
	(segment
		(start 173.249336 -86.711536)
		(end 173.4058 -86.868)
		(width 0.127)
		(layer "F.Cu")
		(net "CLK_100M_CPU0_RC_REFCLK0_R_DP")
	)
	(segment
		(start 172.57014 -85.952838)
		(end 172.644054 -86.026752)
		(width 0.127)
		(layer "F.Cu")
		(net "CLK_100M_CPU0_RC_REFCLK0_R_DP")
	)
	(segment
		(start 172.673772 -85.644228)
		(end 172.57014 -85.74786)
		(width 0.127)
		(layer "F.Cu")
		(net "CLK_100M_CPU0_RC_REFCLK0_R_DP")
	)
	(segment
		(start 172.847254 -86.026752)
		(end 173.249336 -86.428834)
		(width 0.127)
		(layer "F.Cu")
		(net "CLK_100M_CPU0_RC_REFCLK0_R_DP")
	)
	(segment
		(start 173.249336 -86.428834)
		(end 173.249336 -86.711536)
		(width 0.127)
		(layer "F.Cu")
		(net "CLK_100M_CPU0_RC_REFCLK0_R_DP")
	)
	(segment
		(start 172.644054 -86.026752)
		(end 172.847254 -86.026752)
		(width 0.127)
		(layer "F.Cu")
		(net "CLK_100M_CPU0_RC_REFCLK0_R_DP")
	)
	(segment
		(start 172.673772 -85.330792)
		(end 172.673772 -85.644228)
		(width 0.127)
		(layer "F.Cu")
		(net "CLK_100M_CPU0_RC_REFCLK0_R_DP")
	)
	(segment
		(start 173.4058 -86.868)
		(end 173.736 -86.868)
		(width 0.127)
		(layer "F.Cu")
		(net "CLK_100M_CPU0_RC_REFCLK0_R_DP")
	)
	(segment
		(start 172.173646 -85.330792)
		(end 172.173646 -85.661246)
		(width 0.127)
		(layer "F.Cu")
		(net "CLK_100M_CPU0_RC_REFCLK0_R_DN")
	)
	(segment
		(start 172.818806 -86.868)
		(end 172.466 -86.868)
		(width 0.127)
		(layer "F.Cu")
		(net "CLK_100M_CPU0_RC_REFCLK0_R_DN")
	)
	(segment
		(start 172.944536 -86.74227)
		(end 172.818806 -86.868)
		(width 0.127)
		(layer "F.Cu")
		(net "CLK_100M_CPU0_RC_REFCLK0_R_DN")
	)
	(segment
		(start 172.26534 -85.75294)
		(end 172.26534 -86.07933)
		(width 0.127)
		(layer "F.Cu")
		(net "CLK_100M_CPU0_RC_REFCLK0_R_DN")
	)
	(segment
		(start 172.26534 -86.07933)
		(end 172.517562 -86.331552)
		(width 0.127)
		(layer "F.Cu")
		(net "CLK_100M_CPU0_RC_REFCLK0_R_DN")
	)
	(segment
		(start 172.720762 -86.331552)
		(end 172.944536 -86.555326)
		(width 0.127)
		(layer "F.Cu")
		(net "CLK_100M_CPU0_RC_REFCLK0_R_DN")
	)
	(segment
		(start 172.173646 -85.661246)
		(end 172.26534 -85.75294)
		(width 0.127)
		(layer "F.Cu")
		(net "CLK_100M_CPU0_RC_REFCLK0_R_DN")
	)
	(segment
		(start 172.517562 -86.331552)
		(end 172.720762 -86.331552)
		(width 0.127)
		(layer "F.Cu")
		(net "CLK_100M_CPU0_RC_REFCLK0_R_DN")
	)
	(segment
		(start 172.944536 -86.555326)
		(end 172.944536 -86.74227)
		(width 0.127)
		(layer "F.Cu")
		(net "CLK_100M_CPU0_RC_REFCLK0_R_DN")
	)
	(segment
		(start 161.921444 -82.262472)
		(end 161.834322 -82.17535)
		(width 0.127)
		(layer "F.Cu")
		(net "CLK_100M_CPU1_PE_REFCLK_DN")
	)
	(segment
		(start 162.687 -82.181954)
		(end 162.606482 -82.262472)
		(width 0.127)
		(layer "F.Cu")
		(net "CLK_100M_CPU1_PE_REFCLK_DN")
	)
	(segment
		(start 162.606482 -82.262472)
		(end 161.921444 -82.262472)
		(width 0.127)
		(layer "F.Cu")
		(net "CLK_100M_CPU1_PE_REFCLK_DN")
	)
	(segment
		(start 162.687 -81.788)
		(end 162.687 -82.181954)
		(width 0.127)
		(layer "F.Cu")
		(net "CLK_100M_CPU1_PE_REFCLK_DN")
	)
	(segment
		(start 161.834322 -82.17535)
		(end 161.834322 -81.788)
		(width 0.127)
		(layer "F.Cu")
		(net "CLK_100M_CPU1_PE_REFCLK_DN")
	)
	(segment
		(start 123.076208 -79.183738)
		(end 122.504708 -79.183738)
		(width 0.127)
		(layer "F.Cu")
		(net "CLK_100M_CPU1_PE_REFCLK_DN")
	)
	(via
		(at 161.834322 -81.788)
		(size 0.508)
		(drill 0.254)
		(layers "F.Cu" "B.Cu")
		(net "CLK_100M_CPU1_PE_REFCLK_DN")
	)
	(via
		(at 123.076208 -79.183738)
		(size 0.508)
		(drill 0.254)
		(layers "F.Cu" "B.Cu")
		(net "CLK_100M_CPU1_PE_REFCLK_DN")
	)
	(segment
		(start 162.687 -81.788)
		(end 162.687 -82.159602)
		(width 0.127)
		(layer "B.Cu")
		(net "CLK_100M_CPU1_PE_REFCLK_DN")
	)
	(segment
		(start 162.687 -82.159602)
		(end 162.568636 -82.277966)
		(width 0.127)
		(layer "B.Cu")
		(net "CLK_100M_CPU1_PE_REFCLK_DN")
	)
	(segment
		(start 161.834322 -82.18805)
		(end 161.834322 -81.788)
		(width 0.127)
		(layer "B.Cu")
		(net "CLK_100M_CPU1_PE_REFCLK_DN")
	)
	(segment
		(start 161.924238 -82.277966)
		(end 161.834322 -82.18805)
		(width 0.127)
		(layer "B.Cu")
		(net "CLK_100M_CPU1_PE_REFCLK_DN")
	)
	(segment
		(start 162.568636 -82.277966)
		(end 161.924238 -82.277966)
		(width 0.127)
		(layer "B.Cu")
		(net "CLK_100M_CPU1_PE_REFCLK_DN")
	)
	(segment
		(start 149.389846 -91.399106)
		(end 157.077918 -91.399106)
		(width 0.1143)
		(layer "In4.Cu")
		(net "CLK_100M_CPU1_PE_REFCLK_DN")
	)
	(segment
		(start 157.101032 -88.668606)
		(end 148.323046 -88.668606)
		(width 0.1143)
		(layer "In4.Cu")
		(net "CLK_100M_CPU1_PE_REFCLK_DN")
	)
	(segment
		(start 157.212538 -94.764606)
		(end 157.212538 -95.02267)
		(width 0.1143)
		(layer "In4.Cu")
		(net "CLK_100M_CPU1_PE_REFCLK_DN")
	)
	(segment
		(start 149.653752 -91.919806)
		(end 149.36851 -92.205048)
		(width 0.1143)
		(layer "In4.Cu")
		(net "CLK_100M_CPU1_PE_REFCLK_DN")
	)
	(segment
		(start 157.200092 -89.908126)
		(end 157.200092 -90.176604)
		(width 0.1143)
		(layer "In4.Cu")
		(net "CLK_100M_CPU1_PE_REFCLK_DN")
	)
	(segment
		(start 149.396704 -90.294206)
		(end 149.104604 -90.586306)
		(width 0.1143)
		(layer "In4.Cu")
		(net "CLK_100M_CPU1_PE_REFCLK_DN")
	)
	(segment
		(start 149.104604 -90.586306)
		(end 149.104604 -91.113864)
		(width 0.1143)
		(layer "In4.Cu")
		(net "CLK_100M_CPU1_PE_REFCLK_DN")
	)
	(segment
		(start 143.374618 -84.981034)
		(end 143.323818 -85.031834)
		(width 0.0889)
		(layer "In4.Cu")
		(net "CLK_100M_CPU1_PE_REFCLK_DN")
	)
	(segment
		(start 149.36851 -92.712286)
		(end 149.68093 -93.024706)
		(width 0.1143)
		(layer "In4.Cu")
		(net "CLK_100M_CPU1_PE_REFCLK_DN")
	)
	(segment
		(start 125.669548 -81.069434)
		(end 125.636782 -81.069434)
		(width 0.0889)
		(layer "In4.Cu")
		(net "CLK_100M_CPU1_PE_REFCLK_DN")
	)
	(segment
		(start 149.68093 -93.024706)
		(end 157.006036 -93.024706)
		(width 0.1143)
		(layer "In4.Cu")
		(net "CLK_100M_CPU1_PE_REFCLK_DN")
	)
	(segment
		(start 148.323046 -88.668606)
		(end 148.01088 -88.980772)
		(width 0.1143)
		(layer "In4.Cu")
		(net "CLK_100M_CPU1_PE_REFCLK_DN")
	)
	(segment
		(start 148.01088 -88.980772)
		(end 148.01088 -89.454228)
		(width 0.1143)
		(layer "In4.Cu")
		(net "CLK_100M_CPU1_PE_REFCLK_DN")
	)
	(segment
		(start 157.006036 -93.024706)
		(end 157.120336 -93.139006)
		(width 0.1143)
		(layer "In4.Cu")
		(net "CLK_100M_CPU1_PE_REFCLK_DN")
	)
	(segment
		(start 157.077918 -91.399106)
		(end 157.212538 -91.533726)
		(width 0.1143)
		(layer "In4.Cu")
		(net "CLK_100M_CPU1_PE_REFCLK_DN")
	)
	(segment
		(start 139.405614 -85.031834)
		(end 139.370054 -85.031834)
		(width 0.0889)
		(layer "In4.Cu")
		(net "CLK_100M_CPU1_PE_REFCLK_DN")
	)
	(segment
		(start 149.528022 -94.365064)
		(end 149.813264 -94.650306)
		(width 0.1143)
		(layer "In4.Cu")
		(net "CLK_100M_CPU1_PE_REFCLK_DN")
	)
	(segment
		(start 123.076208 -79.521812)
		(end 123.076208 -79.183738)
		(width 0.0889)
		(layer "In4.Cu")
		(net "CLK_100M_CPU1_PE_REFCLK_DN")
	)
	(segment
		(start 143.323818 -85.031834)
		(end 142.695422 -85.031834)
		(width 0.0889)
		(layer "In4.Cu")
		(net "CLK_100M_CPU1_PE_REFCLK_DN")
	)
	(segment
		(start 129.965958 -83.546188)
		(end 129.933192 -83.546188)
		(width 0.0889)
		(layer "In4.Cu")
		(net "CLK_100M_CPU1_PE_REFCLK_DN")
	)
	(segment
		(start 157.342586 -85.094318)
		(end 157.342586 -88.427052)
		(width 0.1143)
		(layer "In4.Cu")
		(net "CLK_100M_CPU1_PE_REFCLK_DN")
	)
	(segment
		(start 137.688574 -85.031834)
		(end 137.653014 -85.031834)
		(width 0.0889)
		(layer "In4.Cu")
		(net "CLK_100M_CPU1_PE_REFCLK_DN")
	)
	(segment
		(start 149.36851 -92.205048)
		(end 149.36851 -92.712286)
		(width 0.1143)
		(layer "In4.Cu")
		(net "CLK_100M_CPU1_PE_REFCLK_DN")
	)
	(segment
		(start 132.17652 -84.837524)
		(end 132.173218 -84.831682)
		(width 0.0889)
		(layer "In4.Cu")
		(net "CLK_100M_CPU1_PE_REFCLK_DN")
	)
	(segment
		(start 123.141232 -79.586836)
		(end 123.076208 -79.521812)
		(width 0.0889)
		(layer "In4.Cu")
		(net "CLK_100M_CPU1_PE_REFCLK_DN")
	)
	(segment
		(start 129.103628 -83.050634)
		(end 129.070862 -83.050634)
		(width 0.0889)
		(layer "In4.Cu")
		(net "CLK_100M_CPU1_PE_REFCLK_DN")
	)
	(segment
		(start 161.834322 -82.16265)
		(end 161.720022 -82.27695)
		(width 0.1143)
		(layer "In4.Cu")
		(net "CLK_100M_CPU1_PE_REFCLK_DN")
	)
	(segment
		(start 148.01088 -89.454228)
		(end 148.330158 -89.773506)
		(width 0.1143)
		(layer "In4.Cu")
		(net "CLK_100M_CPU1_PE_REFCLK_DN")
	)
	(segment
		(start 157.064202 -95.171006)
		(end 149.502368 -95.171006)
		(width 0.1143)
		(layer "In4.Cu")
		(net "CLK_100M_CPU1_PE_REFCLK_DN")
	)
	(segment
		(start 134.254494 -85.031834)
		(end 134.218934 -85.031834)
		(width 0.0889)
		(layer "In4.Cu")
		(net "CLK_100M_CPU1_PE_REFCLK_DN")
	)
	(segment
		(start 141.122654 -85.031834)
		(end 141.087094 -85.031834)
		(width 0.0889)
		(layer "In4.Cu")
		(net "CLK_100M_CPU1_PE_REFCLK_DN")
	)
	(segment
		(start 149.813264 -93.545406)
		(end 149.528022 -93.830648)
		(width 0.1143)
		(layer "In4.Cu")
		(net "CLK_100M_CPU1_PE_REFCLK_DN")
	)
	(segment
		(start 149.813264 -94.650306)
		(end 157.098238 -94.650306)
		(width 0.1143)
		(layer "In4.Cu")
		(net "CLK_100M_CPU1_PE_REFCLK_DN")
	)
	(segment
		(start 157.120336 -93.415104)
		(end 156.990034 -93.545406)
		(width 0.1143)
		(layer "In4.Cu")
		(net "CLK_100M_CPU1_PE_REFCLK_DN")
	)
	(segment
		(start 157.342586 -88.427052)
		(end 157.101032 -88.668606)
		(width 0.1143)
		(layer "In4.Cu")
		(net "CLK_100M_CPU1_PE_REFCLK_DN")
	)
	(segment
		(start 149.104604 -91.113864)
		(end 149.389846 -91.399106)
		(width 0.1143)
		(layer "In4.Cu")
		(net "CLK_100M_CPU1_PE_REFCLK_DN")
	)
	(segment
		(start 149.502368 -95.171006)
		(end 148.806408 -94.475046)
		(width 0.1143)
		(layer "In4.Cu")
		(net "CLK_100M_CPU1_PE_REFCLK_DN")
	)
	(segment
		(start 148.806408 -94.475046)
		(end 148.806408 -91.666822)
		(width 0.1143)
		(layer "In4.Cu")
		(net "CLK_100M_CPU1_PE_REFCLK_DN")
	)
	(segment
		(start 142.129764 -85.527388)
		(end 141.952218 -85.527388)
		(width 0.0889)
		(layer "In4.Cu")
		(net "CLK_100M_CPU1_PE_REFCLK_DN")
	)
	(segment
		(start 157.098238 -94.650306)
		(end 157.212538 -94.764606)
		(width 0.1143)
		(layer "In4.Cu")
		(net "CLK_100M_CPU1_PE_REFCLK_DN")
	)
	(segment
		(start 148.806408 -91.666822)
		(end 147.50796 -90.368374)
		(width 0.1143)
		(layer "In4.Cu")
		(net "CLK_100M_CPU1_PE_REFCLK_DN")
	)
	(segment
		(start 161.720022 -82.27695)
		(end 160.159954 -82.27695)
		(width 0.1143)
		(layer "In4.Cu")
		(net "CLK_100M_CPU1_PE_REFCLK_DN")
	)
	(segment
		(start 149.528022 -93.830648)
		(end 149.528022 -94.365064)
		(width 0.1143)
		(layer "In4.Cu")
		(net "CLK_100M_CPU1_PE_REFCLK_DN")
	)
	(segment
		(start 157.065472 -89.773506)
		(end 157.200092 -89.908126)
		(width 0.1143)
		(layer "In4.Cu")
		(net "CLK_100M_CPU1_PE_REFCLK_DN")
	)
	(segment
		(start 157.212538 -95.02267)
		(end 157.064202 -95.171006)
		(width 0.1143)
		(layer "In4.Cu")
		(net "CLK_100M_CPU1_PE_REFCLK_DN")
	)
	(segment
		(start 126.531878 -81.564734)
		(end 126.492254 -81.564734)
		(width 0.0889)
		(layer "In4.Cu")
		(net "CLK_100M_CPU1_PE_REFCLK_DN")
	)
	(segment
		(start 147.50796 -88.521794)
		(end 143.9672 -84.981034)
		(width 0.1143)
		(layer "In4.Cu")
		(net "CLK_100M_CPU1_PE_REFCLK_DN")
	)
	(segment
		(start 156.990034 -93.545406)
		(end 149.813264 -93.545406)
		(width 0.1143)
		(layer "In4.Cu")
		(net "CLK_100M_CPU1_PE_REFCLK_DN")
	)
	(segment
		(start 147.50796 -90.368374)
		(end 147.50796 -88.521794)
		(width 0.1143)
		(layer "In4.Cu")
		(net "CLK_100M_CPU1_PE_REFCLK_DN")
	)
	(segment
		(start 132.537454 -85.031834)
		(end 132.519674 -85.031834)
		(width 0.0889)
		(layer "In4.Cu")
		(net "CLK_100M_CPU1_PE_REFCLK_DN")
	)
	(segment
		(start 157.08249 -90.294206)
		(end 149.396704 -90.294206)
		(width 0.1143)
		(layer "In4.Cu")
		(net "CLK_100M_CPU1_PE_REFCLK_DN")
	)
	(segment
		(start 148.330158 -89.773506)
		(end 157.065472 -89.773506)
		(width 0.1143)
		(layer "In4.Cu")
		(net "CLK_100M_CPU1_PE_REFCLK_DN")
	)
	(segment
		(start 160.159954 -82.27695)
		(end 157.342586 -85.094318)
		(width 0.1143)
		(layer "In4.Cu")
		(net "CLK_100M_CPU1_PE_REFCLK_DN")
	)
	(segment
		(start 157.098238 -91.919806)
		(end 149.653752 -91.919806)
		(width 0.1143)
		(layer "In4.Cu")
		(net "CLK_100M_CPU1_PE_REFCLK_DN")
	)
	(segment
		(start 135.971534 -85.031834)
		(end 135.935974 -85.031834)
		(width 0.0889)
		(layer "In4.Cu")
		(net "CLK_100M_CPU1_PE_REFCLK_DN")
	)
	(segment
		(start 124.814838 -80.574388)
		(end 124.782072 -80.574388)
		(width 0.0889)
		(layer "In4.Cu")
		(net "CLK_100M_CPU1_PE_REFCLK_DN")
	)
	(segment
		(start 131.6863 -84.536788)
		(end 131.650232 -84.536788)
		(width 0.0889)
		(layer "In4.Cu")
		(net "CLK_100M_CPU1_PE_REFCLK_DN")
	)
	(segment
		(start 143.396716 -84.981034)
		(end 143.374618 -84.981034)
		(width 0.0889)
		(layer "In4.Cu")
		(net "CLK_100M_CPU1_PE_REFCLK_DN")
	)
	(segment
		(start 157.120336 -93.139006)
		(end 157.120336 -93.415104)
		(width 0.1143)
		(layer "In4.Cu")
		(net "CLK_100M_CPU1_PE_REFCLK_DN")
	)
	(segment
		(start 161.834322 -81.788)
		(end 161.834322 -82.16265)
		(width 0.1143)
		(layer "In4.Cu")
		(net "CLK_100M_CPU1_PE_REFCLK_DN")
	)
	(segment
		(start 157.212538 -91.805506)
		(end 157.098238 -91.919806)
		(width 0.1143)
		(layer "In4.Cu")
		(net "CLK_100M_CPU1_PE_REFCLK_DN")
	)
	(segment
		(start 130.820668 -84.041234)
		(end 130.787902 -84.041234)
		(width 0.0889)
		(layer "In4.Cu")
		(net "CLK_100M_CPU1_PE_REFCLK_DN")
	)
	(segment
		(start 123.952508 -80.078834)
		(end 123.919742 -80.078834)
		(width 0.0889)
		(layer "In4.Cu")
		(net "CLK_100M_CPU1_PE_REFCLK_DN")
	)
	(segment
		(start 143.9672 -84.981034)
		(end 143.396716 -84.981034)
		(width 0.1143)
		(layer "In4.Cu")
		(net "CLK_100M_CPU1_PE_REFCLK_DN")
	)
	(segment
		(start 157.212538 -91.533726)
		(end 157.212538 -91.805506)
		(width 0.1143)
		(layer "In4.Cu")
		(net "CLK_100M_CPU1_PE_REFCLK_DN")
	)
	(segment
		(start 128.240282 -82.555334)
		(end 128.216152 -82.555334)
		(width 0.0889)
		(layer "In4.Cu")
		(net "CLK_100M_CPU1_PE_REFCLK_DN")
	)
	(segment
		(start 157.200092 -90.176604)
		(end 157.08249 -90.294206)
		(width 0.1143)
		(layer "In4.Cu")
		(net "CLK_100M_CPU1_PE_REFCLK_DN")
	)
	(segment
		(start 127.390398 -82.060034)
		(end 127.357632 -82.060034)
		(width 0.0889)
		(layer "In4.Cu")
		(net "CLK_100M_CPU1_PE_REFCLK_DN")
	)
	(arc
		(start 125.636782 -81.069434)
		(mid 125.44514 -81.012268)
		(end 125.305058 -80.869536)
		(width 0.0889)
		(layer "In4.Cu")
		(net "CLK_100M_CPU1_PE_REFCLK_DN")
	)
	(arc
		(start 131.314698 -84.336636)
		(mid 131.10609 -84.124704)
		(end 130.820668 -84.041234)
		(width 0.0889)
		(layer "In4.Cu")
		(net "CLK_100M_CPU1_PE_REFCLK_DN")
	)
	(arc
		(start 133.366256 -85.527388)
		(mid 133.17283 -85.470861)
		(end 133.031484 -85.327236)
		(width 0.0889)
		(layer "In4.Cu")
		(net "CLK_100M_CPU1_PE_REFCLK_DN")
	)
	(arc
		(start 127.880618 -82.355182)
		(mid 127.673614 -82.144318)
		(end 127.390398 -82.060034)
		(width 0.0889)
		(layer "In4.Cu")
		(net "CLK_100M_CPU1_PE_REFCLK_DN")
	)
	(arc
		(start 133.390132 -85.527388)
		(mid 133.378194 -85.527566)
		(end 133.366256 -85.527388)
		(width 0.0889)
		(layer "In4.Cu")
		(net "CLK_100M_CPU1_PE_REFCLK_DN")
	)
	(arc
		(start 140.593064 -85.327236)
		(mid 140.451708 -85.470845)
		(end 140.258292 -85.527388)
		(width 0.0889)
		(layer "In4.Cu")
		(net "CLK_100M_CPU1_PE_REFCLK_DN")
	)
	(arc
		(start 123.588018 -79.878936)
		(mid 123.39949 -79.679563)
		(end 123.141232 -79.586836)
		(width 0.0889)
		(layer "In4.Cu")
		(net "CLK_100M_CPU1_PE_REFCLK_DN")
	)
	(arc
		(start 129.597658 -83.346036)
		(mid 129.38905 -83.134104)
		(end 129.103628 -83.050634)
		(width 0.0889)
		(layer "In4.Cu")
		(net "CLK_100M_CPU1_PE_REFCLK_DN")
	)
	(arc
		(start 137.158984 -85.327236)
		(mid 137.017628 -85.470845)
		(end 136.824212 -85.527388)
		(width 0.0889)
		(layer "In4.Cu")
		(net "CLK_100M_CPU1_PE_REFCLK_DN")
	)
	(arc
		(start 135.935974 -85.031834)
		(mid 135.65055 -85.115301)
		(end 135.441944 -85.327236)
		(width 0.0889)
		(layer "In4.Cu")
		(net "CLK_100M_CPU1_PE_REFCLK_DN")
	)
	(arc
		(start 133.724904 -85.327236)
		(mid 133.583548 -85.470845)
		(end 133.390132 -85.527388)
		(width 0.0889)
		(layer "In4.Cu")
		(net "CLK_100M_CPU1_PE_REFCLK_DN")
	)
	(arc
		(start 142.695422 -85.031834)
		(mid 142.492524 -85.147694)
		(end 142.346426 -85.33003)
		(width 0.0889)
		(layer "In4.Cu")
		(net "CLK_100M_CPU1_PE_REFCLK_DN")
	)
	(arc
		(start 129.933192 -83.546188)
		(mid 129.739342 -83.489838)
		(end 129.597658 -83.346036)
		(width 0.0889)
		(layer "In4.Cu")
		(net "CLK_100M_CPU1_PE_REFCLK_DN")
	)
	(arc
		(start 129.070862 -83.050634)
		(mid 128.87922 -82.993468)
		(end 128.739138 -82.850736)
		(width 0.0889)
		(layer "In4.Cu")
		(net "CLK_100M_CPU1_PE_REFCLK_DN")
	)
	(arc
		(start 138.876024 -85.327236)
		(mid 138.734668 -85.470845)
		(end 138.541252 -85.527388)
		(width 0.0889)
		(layer "In4.Cu")
		(net "CLK_100M_CPU1_PE_REFCLK_DN")
	)
	(arc
		(start 130.787902 -84.041234)
		(mid 130.59626 -83.984068)
		(end 130.456178 -83.841336)
		(width 0.0889)
		(layer "In4.Cu")
		(net "CLK_100M_CPU1_PE_REFCLK_DN")
	)
	(arc
		(start 136.824212 -85.527388)
		(mid 136.812274 -85.527566)
		(end 136.800336 -85.527388)
		(width 0.0889)
		(layer "In4.Cu")
		(net "CLK_100M_CPU1_PE_REFCLK_DN")
	)
	(arc
		(start 132.173218 -84.831682)
		(mid 131.967597 -84.621759)
		(end 131.6863 -84.536788)
		(width 0.0889)
		(layer "In4.Cu")
		(net "CLK_100M_CPU1_PE_REFCLK_DN")
	)
	(arc
		(start 134.218934 -85.031834)
		(mid 133.93351 -85.115301)
		(end 133.724904 -85.327236)
		(width 0.0889)
		(layer "In4.Cu")
		(net "CLK_100M_CPU1_PE_REFCLK_DN")
	)
	(arc
		(start 138.182604 -85.327236)
		(mid 137.973996 -85.115304)
		(end 137.688574 -85.031834)
		(width 0.0889)
		(layer "In4.Cu")
		(net "CLK_100M_CPU1_PE_REFCLK_DN")
	)
	(arc
		(start 125.305058 -80.869536)
		(mid 125.098054 -80.658672)
		(end 124.814838 -80.574388)
		(width 0.0889)
		(layer "In4.Cu")
		(net "CLK_100M_CPU1_PE_REFCLK_DN")
	)
	(arc
		(start 138.541252 -85.527388)
		(mid 138.529314 -85.527566)
		(end 138.517376 -85.527388)
		(width 0.0889)
		(layer "In4.Cu")
		(net "CLK_100M_CPU1_PE_REFCLK_DN")
	)
	(arc
		(start 132.519674 -85.031834)
		(mid 132.322513 -84.979875)
		(end 132.17652 -84.837524)
		(width 0.0889)
		(layer "In4.Cu")
		(net "CLK_100M_CPU1_PE_REFCLK_DN")
	)
	(arc
		(start 138.517376 -85.527388)
		(mid 138.32395 -85.470861)
		(end 138.182604 -85.327236)
		(width 0.0889)
		(layer "In4.Cu")
		(net "CLK_100M_CPU1_PE_REFCLK_DN")
	)
	(arc
		(start 127.357632 -82.060034)
		(mid 127.163782 -82.003684)
		(end 127.022098 -81.859882)
		(width 0.0889)
		(layer "In4.Cu")
		(net "CLK_100M_CPU1_PE_REFCLK_DN")
	)
	(arc
		(start 131.650232 -84.536788)
		(mid 131.456382 -84.480438)
		(end 131.314698 -84.336636)
		(width 0.0889)
		(layer "In4.Cu")
		(net "CLK_100M_CPU1_PE_REFCLK_DN")
	)
	(arc
		(start 139.899644 -85.327236)
		(mid 139.691036 -85.115304)
		(end 139.405614 -85.031834)
		(width 0.0889)
		(layer "In4.Cu")
		(net "CLK_100M_CPU1_PE_REFCLK_DN")
	)
	(arc
		(start 123.919742 -80.078834)
		(mid 123.7281 -80.021668)
		(end 123.588018 -79.878936)
		(width 0.0889)
		(layer "In4.Cu")
		(net "CLK_100M_CPU1_PE_REFCLK_DN")
	)
	(arc
		(start 142.346426 -85.33003)
		(mid 142.255312 -85.447622)
		(end 142.129764 -85.527388)
		(width 0.0889)
		(layer "In4.Cu")
		(net "CLK_100M_CPU1_PE_REFCLK_DN")
	)
	(arc
		(start 133.031484 -85.327236)
		(mid 132.822876 -85.115304)
		(end 132.537454 -85.031834)
		(width 0.0889)
		(layer "In4.Cu")
		(net "CLK_100M_CPU1_PE_REFCLK_DN")
	)
	(arc
		(start 141.952218 -85.527388)
		(mid 141.758368 -85.471038)
		(end 141.616684 -85.327236)
		(width 0.0889)
		(layer "In4.Cu")
		(net "CLK_100M_CPU1_PE_REFCLK_DN")
	)
	(arc
		(start 124.446538 -80.374236)
		(mid 124.23793 -80.162304)
		(end 123.952508 -80.078834)
		(width 0.0889)
		(layer "In4.Cu")
		(net "CLK_100M_CPU1_PE_REFCLK_DN")
	)
	(arc
		(start 128.216152 -82.555334)
		(mid 128.022302 -82.498984)
		(end 127.880618 -82.355182)
		(width 0.0889)
		(layer "In4.Cu")
		(net "CLK_100M_CPU1_PE_REFCLK_DN")
	)
	(arc
		(start 137.653014 -85.031834)
		(mid 137.36759 -85.115301)
		(end 137.158984 -85.327236)
		(width 0.0889)
		(layer "In4.Cu")
		(net "CLK_100M_CPU1_PE_REFCLK_DN")
	)
	(arc
		(start 127.022098 -81.859882)
		(mid 126.815094 -81.649018)
		(end 126.531878 -81.564734)
		(width 0.0889)
		(layer "In4.Cu")
		(net "CLK_100M_CPU1_PE_REFCLK_DN")
	)
	(arc
		(start 134.748524 -85.327236)
		(mid 134.539916 -85.115304)
		(end 134.254494 -85.031834)
		(width 0.0889)
		(layer "In4.Cu")
		(net "CLK_100M_CPU1_PE_REFCLK_DN")
	)
	(arc
		(start 136.800336 -85.527388)
		(mid 136.60691 -85.470861)
		(end 136.465564 -85.327236)
		(width 0.0889)
		(layer "In4.Cu")
		(net "CLK_100M_CPU1_PE_REFCLK_DN")
	)
	(arc
		(start 130.456178 -83.841336)
		(mid 130.249174 -83.630472)
		(end 129.965958 -83.546188)
		(width 0.0889)
		(layer "In4.Cu")
		(net "CLK_100M_CPU1_PE_REFCLK_DN")
	)
	(arc
		(start 136.465564 -85.327236)
		(mid 136.256956 -85.115304)
		(end 135.971534 -85.031834)
		(width 0.0889)
		(layer "In4.Cu")
		(net "CLK_100M_CPU1_PE_REFCLK_DN")
	)
	(arc
		(start 128.739138 -82.850736)
		(mid 128.528425 -82.637657)
		(end 128.240282 -82.555334)
		(width 0.0889)
		(layer "In4.Cu")
		(net "CLK_100M_CPU1_PE_REFCLK_DN")
	)
	(arc
		(start 140.258292 -85.527388)
		(mid 140.246354 -85.527566)
		(end 140.234416 -85.527388)
		(width 0.0889)
		(layer "In4.Cu")
		(net "CLK_100M_CPU1_PE_REFCLK_DN")
	)
	(arc
		(start 126.163578 -81.364836)
		(mid 125.95497 -81.152904)
		(end 125.669548 -81.069434)
		(width 0.0889)
		(layer "In4.Cu")
		(net "CLK_100M_CPU1_PE_REFCLK_DN")
	)
	(arc
		(start 124.782072 -80.574388)
		(mid 124.588222 -80.518038)
		(end 124.446538 -80.374236)
		(width 0.0889)
		(layer "In4.Cu")
		(net "CLK_100M_CPU1_PE_REFCLK_DN")
	)
	(arc
		(start 126.492254 -81.564734)
		(mid 126.302325 -81.506864)
		(end 126.163578 -81.364836)
		(width 0.0889)
		(layer "In4.Cu")
		(net "CLK_100M_CPU1_PE_REFCLK_DN")
	)
	(arc
		(start 139.370054 -85.031834)
		(mid 139.08463 -85.115301)
		(end 138.876024 -85.327236)
		(width 0.0889)
		(layer "In4.Cu")
		(net "CLK_100M_CPU1_PE_REFCLK_DN")
	)
	(arc
		(start 141.616684 -85.327236)
		(mid 141.408076 -85.115304)
		(end 141.122654 -85.031834)
		(width 0.0889)
		(layer "In4.Cu")
		(net "CLK_100M_CPU1_PE_REFCLK_DN")
	)
	(arc
		(start 135.441944 -85.327236)
		(mid 135.095234 -85.527547)
		(end 134.748524 -85.327236)
		(width 0.0889)
		(layer "In4.Cu")
		(net "CLK_100M_CPU1_PE_REFCLK_DN")
	)
	(arc
		(start 141.087094 -85.031834)
		(mid 140.80167 -85.115301)
		(end 140.593064 -85.327236)
		(width 0.0889)
		(layer "In4.Cu")
		(net "CLK_100M_CPU1_PE_REFCLK_DN")
	)
	(arc
		(start 140.234416 -85.527388)
		(mid 140.04099 -85.470861)
		(end 139.899644 -85.327236)
		(width 0.0889)
		(layer "In4.Cu")
		(net "CLK_100M_CPU1_PE_REFCLK_DN")
	)
	(segment
		(start 164.333936 -84.313776)
		(end 164.333936 -84.821014)
		(width 0.1143)
		(layer "F.Cu")
		(net "CLK_100M_CPU1_BCLK2_R_DP")
	)
	(segment
		(start 164.546788 -84.100924)
		(end 164.333936 -84.313776)
		(width 0.1143)
		(layer "F.Cu")
		(net "CLK_100M_CPU1_BCLK2_R_DP")
	)
	(segment
		(start 163.717478 -85.104732)
		(end 163.576 -85.24621)
		(width 0.1143)
		(layer "F.Cu")
		(net "CLK_100M_CPU1_BCLK2_R_DP")
	)
	(segment
		(start 164.333936 -84.821014)
		(end 164.050218 -85.104732)
		(width 0.1143)
		(layer "F.Cu")
		(net "CLK_100M_CPU1_BCLK2_R_DP")
	)
	(segment
		(start 164.050218 -85.104732)
		(end 163.717478 -85.104732)
		(width 0.1143)
		(layer "F.Cu")
		(net "CLK_100M_CPU1_BCLK2_R_DP")
	)
	(segment
		(start 163.576 -85.24621)
		(end 163.576 -85.598)
		(width 0.1143)
		(layer "F.Cu")
		(net "CLK_100M_CPU1_BCLK2_R_DP")
	)
	(segment
		(start 164.942012 -84.100924)
		(end 164.546788 -84.100924)
		(width 0.1143)
		(layer "F.Cu")
		(net "CLK_100M_CPU1_BCLK2_R_DP")
	)
	(segment
		(start 165.054026 -84.212938)
		(end 164.942012 -84.100924)
		(width 0.1143)
		(layer "F.Cu")
		(net "CLK_100M_CPU1_BCLK2_R_DP")
	)
	(segment
		(start 164.092636 -84.2137)
		(end 164.092636 -84.720938)
		(width 0.1143)
		(layer "F.Cu")
		(net "CLK_100M_CPU1_BCLK2_R_DN")
	)
	(segment
		(start 163.950142 -84.863432)
		(end 163.708334 -84.863432)
		(width 0.1143)
		(layer "F.Cu")
		(net "CLK_100M_CPU1_BCLK2_R_DN")
	)
	(segment
		(start 164.907214 -83.859624)
		(end 164.446712 -83.859624)
		(width 0.1143)
		(layer "F.Cu")
		(net "CLK_100M_CPU1_BCLK2_R_DN")
	)
	(segment
		(start 164.092636 -84.720938)
		(end 163.950142 -84.863432)
		(width 0.1143)
		(layer "F.Cu")
		(net "CLK_100M_CPU1_BCLK2_R_DN")
	)
	(segment
		(start 163.708334 -84.863432)
		(end 163.576 -84.731098)
		(width 0.1143)
		(layer "F.Cu")
		(net "CLK_100M_CPU1_BCLK2_R_DN")
	)
	(segment
		(start 163.576 -84.731098)
		(end 163.576 -84.328)
		(width 0.1143)
		(layer "F.Cu")
		(net "CLK_100M_CPU1_BCLK2_R_DN")
	)
	(segment
		(start 165.054026 -83.712812)
		(end 164.907214 -83.859624)
		(width 0.1143)
		(layer "F.Cu")
		(net "CLK_100M_CPU1_BCLK2_R_DN")
	)
	(segment
		(start 164.446712 -83.859624)
		(end 164.092636 -84.2137)
		(width 0.1143)
		(layer "F.Cu")
		(net "CLK_100M_CPU1_BCLK2_R_DN")
	)
	(segment
		(start 165.594284 -86.486492)
		(end 165.594284 -86.71306)
		(width 0.1143)
		(layer "F.Cu")
		(net "CLK_100M_CPU1_BCLK1_R_DP")
	)
	(segment
		(start 165.594284 -86.71306)
		(end 165.749224 -86.868)
		(width 0.1143)
		(layer "F.Cu")
		(net "CLK_100M_CPU1_BCLK1_R_DP")
	)
	(segment
		(start 166.67226 -85.65134)
		(end 166.499032 -85.824568)
		(width 0.1143)
		(layer "F.Cu")
		(net "CLK_100M_CPU1_BCLK1_R_DP")
	)
	(segment
		(start 165.746176 -86.3346)
		(end 165.594284 -86.486492)
		(width 0.1143)
		(layer "F.Cu")
		(net "CLK_100M_CPU1_BCLK1_R_DP")
	)
	(segment
		(start 166.499032 -85.824568)
		(end 166.499032 -86.044024)
		(width 0.1143)
		(layer "F.Cu")
		(net "CLK_100M_CPU1_BCLK1_R_DP")
	)
	(segment
		(start 165.749224 -86.868)
		(end 166.116 -86.868)
		(width 0.1143)
		(layer "F.Cu")
		(net "CLK_100M_CPU1_BCLK1_R_DP")
	)
	(segment
		(start 166.67226 -85.330792)
		(end 166.67226 -85.65134)
		(width 0.1143)
		(layer "F.Cu")
		(net "CLK_100M_CPU1_BCLK1_R_DP")
	)
	(segment
		(start 166.208456 -86.3346)
		(end 165.746176 -86.3346)
		(width 0.1143)
		(layer "F.Cu")
		(net "CLK_100M_CPU1_BCLK1_R_DP")
	)
	(segment
		(start 166.499032 -86.044024)
		(end 166.208456 -86.3346)
		(width 0.1143)
		(layer "F.Cu")
		(net "CLK_100M_CPU1_BCLK1_R_DP")
	)
	(segment
		(start 166.172134 -85.654134)
		(end 166.257732 -85.739732)
		(width 0.1143)
		(layer "F.Cu")
		(net "CLK_100M_CPU1_BCLK1_R_DN")
	)
	(segment
		(start 165.6461 -86.0933)
		(end 165.352984 -86.386416)
		(width 0.1143)
		(layer "F.Cu")
		(net "CLK_100M_CPU1_BCLK1_R_DN")
	)
	(segment
		(start 166.257732 -85.943948)
		(end 166.10838 -86.0933)
		(width 0.1143)
		(layer "F.Cu")
		(net "CLK_100M_CPU1_BCLK1_R_DN")
	)
	(segment
		(start 166.10838 -86.0933)
		(end 165.6461 -86.0933)
		(width 0.1143)
		(layer "F.Cu")
		(net "CLK_100M_CPU1_BCLK1_R_DN")
	)
	(segment
		(start 166.172134 -85.330792)
		(end 166.172134 -85.654134)
		(width 0.1143)
		(layer "F.Cu")
		(net "CLK_100M_CPU1_BCLK1_R_DN")
	)
	(segment
		(start 165.2016 -86.868)
		(end 164.846 -86.868)
		(width 0.1143)
		(layer "F.Cu")
		(net "CLK_100M_CPU1_BCLK1_R_DN")
	)
	(segment
		(start 166.257732 -85.739732)
		(end 166.257732 -85.943948)
		(width 0.1143)
		(layer "F.Cu")
		(net "CLK_100M_CPU1_BCLK1_R_DN")
	)
	(segment
		(start 165.352984 -86.386416)
		(end 165.352984 -86.716616)
		(width 0.1143)
		(layer "F.Cu")
		(net "CLK_100M_CPU1_BCLK1_R_DN")
	)
	(segment
		(start 165.352984 -86.716616)
		(end 165.2016 -86.868)
		(width 0.1143)
		(layer "F.Cu")
		(net "CLK_100M_CPU1_BCLK1_R_DN")
	)
	(segment
		(start 168.49852 -85.9028)
		(end 168.49852 -86.110826)
		(width 0.1143)
		(layer "F.Cu")
		(net "CLK_100M_CPU1_BCLK0_R_DP")
	)
	(segment
		(start 168.49852 -86.110826)
		(end 168.173146 -86.4362)
		(width 0.1143)
		(layer "F.Cu")
		(net "CLK_100M_CPU1_BCLK0_R_DP")
	)
	(segment
		(start 168.672764 -85.728556)
		(end 168.49852 -85.9028)
		(width 0.1143)
		(layer "F.Cu")
		(net "CLK_100M_CPU1_BCLK0_R_DP")
	)
	(segment
		(start 168.292526 -86.868)
		(end 168.656 -86.868)
		(width 0.1143)
		(layer "F.Cu")
		(net "CLK_100M_CPU1_BCLK0_R_DP")
	)
	(segment
		(start 168.173146 -86.74862)
		(end 168.292526 -86.868)
		(width 0.1143)
		(layer "F.Cu")
		(net "CLK_100M_CPU1_BCLK0_R_DP")
	)
	(segment
		(start 168.173146 -86.4362)
		(end 168.173146 -86.74862)
		(width 0.1143)
		(layer "F.Cu")
		(net "CLK_100M_CPU1_BCLK0_R_DP")
	)
	(segment
		(start 168.672764 -85.330792)
		(end 168.672764 -85.728556)
		(width 0.1143)
		(layer "F.Cu")
		(net "CLK_100M_CPU1_BCLK0_R_DP")
	)
	(segment
		(start 167.931846 -86.336124)
		(end 167.931846 -86.7029)
		(width 0.1143)
		(layer "F.Cu")
		(net "CLK_100M_CPU1_BCLK0_R_DN")
	)
	(segment
		(start 167.931846 -86.7029)
		(end 167.766746 -86.868)
		(width 0.1143)
		(layer "F.Cu")
		(net "CLK_100M_CPU1_BCLK0_R_DN")
	)
	(segment
		(start 168.25722 -86.01075)
		(end 167.931846 -86.336124)
		(width 0.1143)
		(layer "F.Cu")
		(net "CLK_100M_CPU1_BCLK0_R_DN")
	)
	(segment
		(start 168.172638 -85.720682)
		(end 168.25722 -85.805264)
		(width 0.1143)
		(layer "F.Cu")
		(net "CLK_100M_CPU1_BCLK0_R_DN")
	)
	(segment
		(start 167.766746 -86.868)
		(end 167.386 -86.868)
		(width 0.1143)
		(layer "F.Cu")
		(net "CLK_100M_CPU1_BCLK0_R_DN")
	)
	(segment
		(start 168.172638 -85.330792)
		(end 168.172638 -85.720682)
		(width 0.1143)
		(layer "F.Cu")
		(net "CLK_100M_CPU1_BCLK0_R_DN")
	)
	(segment
		(start 168.25722 -85.805264)
		(end 168.25722 -86.01075)
		(width 0.1143)
		(layer "F.Cu")
		(net "CLK_100M_CPU1_BCLK0_R_DN")
	)
	(segment
		(start 175.100488 -81.906872)
		(end 175.387 -81.62036)
		(width 0.1143)
		(layer "F.Cu")
		(net "CLK_100M_CPU0_BCLK2_R_DP")
	)
	(segment
		(start 173.791626 -81.712308)
		(end 174.219616 -81.712308)
		(width 0.1143)
		(layer "F.Cu")
		(net "CLK_100M_CPU0_BCLK2_R_DP")
	)
	(segment
		(start 174.41418 -81.906872)
		(end 175.100488 -81.906872)
		(width 0.1143)
		(layer "F.Cu")
		(net "CLK_100M_CPU0_BCLK2_R_DP")
	)
	(segment
		(start 174.219616 -81.712308)
		(end 174.41418 -81.906872)
		(width 0.1143)
		(layer "F.Cu")
		(net "CLK_100M_CPU0_BCLK2_R_DP")
	)
	(segment
		(start 175.387 -81.62036)
		(end 175.387 -81.407)
		(width 0.1143)
		(layer "F.Cu")
		(net "CLK_100M_CPU0_BCLK2_R_DP")
	)
	(segment
		(start 174.41418 -82.148172)
		(end 175.20666 -82.148172)
		(width 0.1143)
		(layer "F.Cu")
		(net "CLK_100M_CPU0_BCLK2_R_DN")
	)
	(segment
		(start 174.349918 -82.212434)
		(end 174.41418 -82.148172)
		(width 0.1143)
		(layer "F.Cu")
		(net "CLK_100M_CPU0_BCLK2_R_DN")
	)
	(segment
		(start 175.387 -82.328512)
		(end 175.387 -82.677)
		(width 0.1143)
		(layer "F.Cu")
		(net "CLK_100M_CPU0_BCLK2_R_DN")
	)
	(segment
		(start 175.20666 -82.148172)
		(end 175.387 -82.328512)
		(width 0.1143)
		(layer "F.Cu")
		(net "CLK_100M_CPU0_BCLK2_R_DN")
	)
	(segment
		(start 173.791626 -82.212434)
		(end 174.349918 -82.212434)
		(width 0.1143)
		(layer "F.Cu")
		(net "CLK_100M_CPU0_BCLK2_R_DN")
	)
	(segment
		(start 176.691036 -79.340964)
		(end 177.165 -78.867)
		(width 0.1143)
		(layer "F.Cu")
		(net "CLK_100M_CPU0_BCLK1_R_DP")
	)
	(segment
		(start 175.006 -79.340964)
		(end 176.691036 -79.340964)
		(width 0.1143)
		(layer "F.Cu")
		(net "CLK_100M_CPU0_BCLK1_R_DP")
	)
	(segment
		(start 174.323756 -79.211678)
		(end 174.453042 -79.340964)
		(width 0.1143)
		(layer "F.Cu")
		(net "CLK_100M_CPU0_BCLK1_R_DP")
	)
	(segment
		(start 174.453042 -79.340964)
		(end 175.006 -79.340964)
		(width 0.1143)
		(layer "F.Cu")
		(net "CLK_100M_CPU0_BCLK1_R_DP")
	)
	(segment
		(start 173.791626 -79.211678)
		(end 174.323756 -79.211678)
		(width 0.1143)
		(layer "F.Cu")
		(net "CLK_100M_CPU0_BCLK1_R_DP")
	)
	(via
		(at 175.006 -79.340964)
		(size 0.1016)
		(drill 0.0508)
		(layers "F.Cu" "B.Cu")
		(net "CLK_100M_CPU0_BCLK1_R_DP")
	)
	(segment
		(start 173.791626 -79.711804)
		(end 174.323502 -79.711804)
		(width 0.1143)
		(layer "F.Cu")
		(net "CLK_100M_CPU0_BCLK1_R_DN")
	)
	(segment
		(start 176.610264 -79.582264)
		(end 177.165 -80.137)
		(width 0.1143)
		(layer "F.Cu")
		(net "CLK_100M_CPU0_BCLK1_R_DN")
	)
	(segment
		(start 174.453042 -79.582264)
		(end 176.266348 -79.582264)
		(width 0.1143)
		(layer "F.Cu")
		(net "CLK_100M_CPU0_BCLK1_R_DN")
	)
	(segment
		(start 176.266348 -79.582264)
		(end 176.610264 -79.582264)
		(width 0.1143)
		(layer "F.Cu")
		(net "CLK_100M_CPU0_BCLK1_R_DN")
	)
	(segment
		(start 174.323502 -79.711804)
		(end 174.453042 -79.582264)
		(width 0.1143)
		(layer "F.Cu")
		(net "CLK_100M_CPU0_BCLK1_R_DN")
	)
	(via
		(at 176.266348 -79.582264)
		(size 0.1016)
		(drill 0.0508)
		(layers "F.Cu" "B.Cu")
		(net "CLK_100M_CPU0_BCLK1_R_DN")
	)
	(segment
		(start 174.393098 -77.339952)
		(end 174.893224 -76.839826)
		(width 0.1143)
		(layer "F.Cu")
		(net "CLK_100M_CPU0_BCLK0_R_DP")
	)
	(segment
		(start 175.387 -76.705968)
		(end 175.387 -76.327)
		(width 0.1143)
		(layer "F.Cu")
		(net "CLK_100M_CPU0_BCLK0_R_DP")
	)
	(segment
		(start 174.118016 -77.211174)
		(end 174.246794 -77.339952)
		(width 0.1143)
		(layer "F.Cu")
		(net "CLK_100M_CPU0_BCLK0_R_DP")
	)
	(segment
		(start 174.893224 -76.839826)
		(end 175.253142 -76.839826)
		(width 0.1143)
		(layer "F.Cu")
		(net "CLK_100M_CPU0_BCLK0_R_DP")
	)
	(segment
		(start 173.791626 -77.211174)
		(end 174.118016 -77.211174)
		(width 0.1143)
		(layer "F.Cu")
		(net "CLK_100M_CPU0_BCLK0_R_DP")
	)
	(segment
		(start 174.246794 -77.339952)
		(end 174.393098 -77.339952)
		(width 0.1143)
		(layer "F.Cu")
		(net "CLK_100M_CPU0_BCLK0_R_DP")
	)
	(segment
		(start 175.253142 -76.839826)
		(end 175.387 -76.705968)
		(width 0.1143)
		(layer "F.Cu")
		(net "CLK_100M_CPU0_BCLK0_R_DP")
	)
	(segment
		(start 175.387 -77.213968)
		(end 175.387 -77.597)
		(width 0.1143)
		(layer "F.Cu")
		(net "CLK_100M_CPU0_BCLK0_R_DN")
	)
	(segment
		(start 174.9933 -77.081126)
		(end 175.254158 -77.081126)
		(width 0.1143)
		(layer "F.Cu")
		(net "CLK_100M_CPU0_BCLK0_R_DN")
	)
	(segment
		(start 174.109126 -77.7113)
		(end 174.239174 -77.581252)
		(width 0.1143)
		(layer "F.Cu")
		(net "CLK_100M_CPU0_BCLK0_R_DN")
	)
	(segment
		(start 173.791626 -77.7113)
		(end 174.109126 -77.7113)
		(width 0.1143)
		(layer "F.Cu")
		(net "CLK_100M_CPU0_BCLK0_R_DN")
	)
	(segment
		(start 174.493174 -77.581252)
		(end 174.9933 -77.081126)
		(width 0.1143)
		(layer "F.Cu")
		(net "CLK_100M_CPU0_BCLK0_R_DN")
	)
	(segment
		(start 175.254158 -77.081126)
		(end 175.387 -77.213968)
		(width 0.1143)
		(layer "F.Cu")
		(net "CLK_100M_CPU0_BCLK0_R_DN")
	)
	(segment
		(start 174.239174 -77.581252)
		(end 174.493174 -77.581252)
		(width 0.1143)
		(layer "F.Cu")
		(net "CLK_100M_CPU0_BCLK0_R_DN")
	)
	(segment
		(start 377.83135 -110.71352)
		(end 378.32665 -110.943644)
		(width 0.127)
		(layer "F.Cu")
		(net "CLK_100M_AIRMAX8_PE1_DP")
	)
	(via
		(at 378.32665 -110.943644)
		(size 0.508)
		(drill 0.254)
		(layers "F.Cu" "B.Cu")
		(net "CLK_100M_AIRMAX8_PE1_DP")
	)
	(via
		(at 10.40511 -109.076236)
		(size 0.508)
		(drill 0.254)
		(layers "F.Cu" "B.Cu")
		(net "CLK_100M_AIRMAX8_PE1_DP")
	)
	(segment
		(start 13.213588 -94.991936)
		(end 13.213588 -92.230448)
		(width 0.1143)
		(layer "In4.Cu")
		(net "CLK_100M_AIRMAX8_PE1_DP")
	)
	(segment
		(start 16.49857 -49.782222)
		(end 17.663414 -48.617378)
		(width 0.1143)
		(layer "In4.Cu")
		(net "CLK_100M_AIRMAX8_PE1_DP")
	)
	(segment
		(start 10.40511 -109.076236)
		(end 10.13968 -108.762546)
		(width 0.1143)
		(layer "In4.Cu")
		(net "CLK_100M_AIRMAX8_PE1_DP")
	)
	(segment
		(start 12.7254 -79.6544)
		(end 13.614654 -78.765146)
		(width 0.1143)
		(layer "In4.Cu")
		(net "CLK_100M_AIRMAX8_PE1_DP")
	)
	(segment
		(start 12.7254 -80.4164)
		(end 12.7254 -79.6544)
		(width 0.1143)
		(layer "In4.Cu")
		(net "CLK_100M_AIRMAX8_PE1_DP")
	)
	(segment
		(start 11.328654 -37.4396)
		(end 10.795 -36.905946)
		(width 0.1143)
		(layer "In4.Cu")
		(net "CLK_100M_AIRMAX8_PE1_DP")
	)
	(segment
		(start 18.8214 -107.296204)
		(end 18.8214 -100.193856)
		(width 0.1143)
		(layer "In4.Cu")
		(net "CLK_100M_AIRMAX8_PE1_DP")
	)
	(segment
		(start 13.213588 -92.230448)
		(end 13.975842 -91.468194)
		(width 0.1143)
		(layer "In4.Cu")
		(net "CLK_100M_AIRMAX8_PE1_DP")
	)
	(segment
		(start 13.163804 -37.4396)
		(end 11.328654 -37.4396)
		(width 0.1143)
		(layer "In4.Cu")
		(net "CLK_100M_AIRMAX8_PE1_DP")
	)
	(segment
		(start 10.795 -34.593022)
		(end 8.777478 -32.5755)
		(width 0.1143)
		(layer "In4.Cu")
		(net "CLK_100M_AIRMAX8_PE1_DP")
	)
	(segment
		(start 14.076426 -39.622984)
		(end 14.076426 -38.352222)
		(width 0.1143)
		(layer "In4.Cu")
		(net "CLK_100M_AIRMAX8_PE1_DP")
	)
	(segment
		(start 14.1986 -83.4136)
		(end 14.1986 -81.8896)
		(width 0.1143)
		(layer "In4.Cu")
		(net "CLK_100M_AIRMAX8_PE1_DP")
	)
	(segment
		(start 15.9131 -98.2853)
		(end 13.63345 -96.005396)
		(width 0.1143)
		(layer "In4.Cu")
		(net "CLK_100M_AIRMAX8_PE1_DP")
	)
	(segment
		(start 8.777478 -32.5755)
		(end 7.056882 -32.5755)
		(width 0.1143)
		(layer "In4.Cu")
		(net "CLK_100M_AIRMAX8_PE1_DP")
	)
	(segment
		(start 7.056882 -32.5755)
		(end 6.354064 -33.278318)
		(width 0.1143)
		(layer "In4.Cu")
		(net "CLK_100M_AIRMAX8_PE1_DP")
	)
	(segment
		(start 19.129502 -54.604158)
		(end 14.769592 -54.604158)
		(width 0.1143)
		(layer "In4.Cu")
		(net "CLK_100M_AIRMAX8_PE1_DP")
	)
	(segment
		(start 13.716 -83.8962)
		(end 14.1986 -83.4136)
		(width 0.1143)
		(layer "In4.Cu")
		(net "CLK_100M_AIRMAX8_PE1_DP")
	)
	(segment
		(start 13.494258 -83.8962)
		(end 13.716 -83.8962)
		(width 0.1143)
		(layer "In4.Cu")
		(net "CLK_100M_AIRMAX8_PE1_DP")
	)
	(segment
		(start 14.351 -78.3336)
		(end 14.351 -70.76059)
		(width 0.1143)
		(layer "In4.Cu")
		(net "CLK_100M_AIRMAX8_PE1_DP")
	)
	(segment
		(start 13.975842 -87.216742)
		(end 13.208 -86.4489)
		(width 0.1143)
		(layer "In4.Cu")
		(net "CLK_100M_AIRMAX8_PE1_DP")
	)
	(segment
		(start 18.8214 -100.193856)
		(end 16.912844 -98.2853)
		(width 0.1143)
		(layer "In4.Cu")
		(net "CLK_100M_AIRMAX8_PE1_DP")
	)
	(segment
		(start 16.912844 -98.2853)
		(end 15.9131 -98.2853)
		(width 0.1143)
		(layer "In4.Cu")
		(net "CLK_100M_AIRMAX8_PE1_DP")
	)
	(segment
		(start 14.255496 -49.782222)
		(end 16.49857 -49.782222)
		(width 0.1143)
		(layer "In4.Cu")
		(net "CLK_100M_AIRMAX8_PE1_DP")
	)
	(segment
		(start 6.354064 -33.595818)
		(end 6.239764 -33.710118)
		(width 0.1143)
		(layer "In4.Cu")
		(net "CLK_100M_AIRMAX8_PE1_DP")
	)
	(segment
		(start 10.153396 -108.60151)
		(end 10.248392 -108.5215)
		(width 0.1143)
		(layer "In4.Cu")
		(net "CLK_100M_AIRMAX8_PE1_DP")
	)
	(segment
		(start 14.1986 -81.8896)
		(end 12.7254 -80.4164)
		(width 0.1143)
		(layer "In4.Cu")
		(net "CLK_100M_AIRMAX8_PE1_DP")
	)
	(segment
		(start 12.986258 -86.0171)
		(end 12.986258 -84.4042)
		(width 0.1143)
		(layer "In4.Cu")
		(net "CLK_100M_AIRMAX8_PE1_DP")
	)
	(segment
		(start 10.248392 -108.5215)
		(end 13.645388 -108.5215)
		(width 0.1143)
		(layer "In4.Cu")
		(net "CLK_100M_AIRMAX8_PE1_DP")
	)
	(segment
		(start 18.853912 -69.617082)
		(end 20.470876 -68.000118)
		(width 0.1143)
		(layer "In4.Cu")
		(net "CLK_100M_AIRMAX8_PE1_DP")
	)
	(segment
		(start 20.470876 -55.945532)
		(end 19.129502 -54.604158)
		(width 0.1143)
		(layer "In4.Cu")
		(net "CLK_100M_AIRMAX8_PE1_DP")
	)
	(segment
		(start 14.769592 -54.604158)
		(end 13.96365 -53.798216)
		(width 0.1143)
		(layer "In4.Cu")
		(net "CLK_100M_AIRMAX8_PE1_DP")
	)
	(segment
		(start 12.986258 -84.4042)
		(end 13.494258 -83.8962)
		(width 0.1143)
		(layer "In4.Cu")
		(net "CLK_100M_AIRMAX8_PE1_DP")
	)
	(segment
		(start 17.663414 -43.209972)
		(end 14.076426 -39.622984)
		(width 0.1143)
		(layer "In4.Cu")
		(net "CLK_100M_AIRMAX8_PE1_DP")
	)
	(segment
		(start 13.975842 -91.468194)
		(end 13.975842 -87.216742)
		(width 0.1143)
		(layer "In4.Cu")
		(net "CLK_100M_AIRMAX8_PE1_DP")
	)
	(segment
		(start 14.076426 -38.352222)
		(end 13.163804 -37.4396)
		(width 0.1143)
		(layer "In4.Cu")
		(net "CLK_100M_AIRMAX8_PE1_DP")
	)
	(segment
		(start 16.122904 -109.9947)
		(end 18.8214 -107.296204)
		(width 0.1143)
		(layer "In4.Cu")
		(net "CLK_100M_AIRMAX8_PE1_DP")
	)
	(segment
		(start 10.795 -36.905946)
		(end 10.795 -34.593022)
		(width 0.1143)
		(layer "In4.Cu")
		(net "CLK_100M_AIRMAX8_PE1_DP")
	)
	(segment
		(start 15.118588 -109.9947)
		(end 16.122904 -109.9947)
		(width 0.1143)
		(layer "In4.Cu")
		(net "CLK_100M_AIRMAX8_PE1_DP")
	)
	(segment
		(start 13.96365 -50.074068)
		(end 14.255496 -49.782222)
		(width 0.1143)
		(layer "In4.Cu")
		(net "CLK_100M_AIRMAX8_PE1_DP")
	)
	(segment
		(start 14.351 -70.76059)
		(end 15.494508 -69.617082)
		(width 0.1143)
		(layer "In4.Cu")
		(net "CLK_100M_AIRMAX8_PE1_DP")
	)
	(segment
		(start 6.354064 -33.278318)
		(end 6.354064 -33.595818)
		(width 0.1143)
		(layer "In4.Cu")
		(net "CLK_100M_AIRMAX8_PE1_DP")
	)
	(segment
		(start 15.494508 -69.617082)
		(end 18.853912 -69.617082)
		(width 0.1143)
		(layer "In4.Cu")
		(net "CLK_100M_AIRMAX8_PE1_DP")
	)
	(segment
		(start 13.96365 -53.798216)
		(end 13.96365 -50.074068)
		(width 0.1143)
		(layer "In4.Cu")
		(net "CLK_100M_AIRMAX8_PE1_DP")
	)
	(segment
		(start 13.645388 -108.5215)
		(end 15.118588 -109.9947)
		(width 0.1143)
		(layer "In4.Cu")
		(net "CLK_100M_AIRMAX8_PE1_DP")
	)
	(segment
		(start 13.208 -86.4489)
		(end 13.208 -86.238842)
		(width 0.1143)
		(layer "In4.Cu")
		(net "CLK_100M_AIRMAX8_PE1_DP")
	)
	(segment
		(start 17.663414 -48.617378)
		(end 17.663414 -43.209972)
		(width 0.1143)
		(layer "In4.Cu")
		(net "CLK_100M_AIRMAX8_PE1_DP")
	)
	(segment
		(start 13.208 -86.238842)
		(end 12.986258 -86.0171)
		(width 0.1143)
		(layer "In4.Cu")
		(net "CLK_100M_AIRMAX8_PE1_DP")
	)
	(segment
		(start 13.63345 -96.005396)
		(end 13.213588 -94.991936)
		(width 0.1143)
		(layer "In4.Cu")
		(net "CLK_100M_AIRMAX8_PE1_DP")
	)
	(segment
		(start 10.13968 -108.762546)
		(end 10.153396 -108.60151)
		(width 0.1143)
		(layer "In4.Cu")
		(net "CLK_100M_AIRMAX8_PE1_DP")
	)
	(segment
		(start 13.614654 -78.765146)
		(end 13.919454 -78.765146)
		(width 0.1143)
		(layer "In4.Cu")
		(net "CLK_100M_AIRMAX8_PE1_DP")
	)
	(segment
		(start 13.919454 -78.765146)
		(end 14.351 -78.3336)
		(width 0.1143)
		(layer "In4.Cu")
		(net "CLK_100M_AIRMAX8_PE1_DP")
	)
	(segment
		(start 6.239764 -33.710118)
		(end 5.80009 -33.710118)
		(width 0.1143)
		(layer "In4.Cu")
		(net "CLK_100M_AIRMAX8_PE1_DP")
	)
	(segment
		(start 20.470876 -68.000118)
		(end 20.470876 -55.945532)
		(width 0.1143)
		(layer "In4.Cu")
		(net "CLK_100M_AIRMAX8_PE1_DP")
	)
	(segment
		(start 372.994936 -120.81891)
		(end 373.237252 -120.57634)
		(width 0.1143)
		(layer "In9.Cu")
		(net "CLK_100M_AIRMAX8_PE1_DP")
	)
	(segment
		(start 158.710376 -152.197562)
		(end 159.393128 -151.51481)
		(width 0.1143)
		(layer "In9.Cu")
		(net "CLK_100M_AIRMAX8_PE1_DP")
	)
	(segment
		(start 19.500596 -130.600196)
		(end 19.500596 -133.264656)
		(width 0.1143)
		(layer "In9.Cu")
		(net "CLK_100M_AIRMAX8_PE1_DP")
	)
	(segment
		(start 377.19 -113.7412)
		(end 377.701302 -113.229898)
		(width 0.0889)
		(layer "In9.Cu")
		(net "CLK_100M_AIRMAX8_PE1_DP")
	)
	(segment
		(start 374.907556 -119.139716)
		(end 375.150126 -118.897146)
		(width 0.1143)
		(layer "In9.Cu")
		(net "CLK_100M_AIRMAX8_PE1_DP")
	)
	(segment
		(start 367.933224 -129.899918)
		(end 367.933224 -129.666492)
		(width 0.1143)
		(layer "In9.Cu")
		(net "CLK_100M_AIRMAX8_PE1_DP")
	)
	(segment
		(start 378.2314 -111.81334)
		(end 378.2314 -111.780574)
		(width 0.0889)
		(layer "In9.Cu")
		(net "CLK_100M_AIRMAX8_PE1_DP")
	)
	(segment
		(start 330.415646 -138.5189)
		(end 334.980534 -138.5189)
		(width 0.1143)
		(layer "In9.Cu")
		(net "CLK_100M_AIRMAX8_PE1_DP")
	)
	(segment
		(start 330.154026 -147.844002)
		(end 329.922378 -147.612354)
		(width 0.1143)
		(layer "In9.Cu")
		(net "CLK_100M_AIRMAX8_PE1_DP")
	)
	(segment
		(start 343.179654 -137.091674)
		(end 344.227658 -138.139678)
		(width 0.1143)
		(layer "In9.Cu")
		(net "CLK_100M_AIRMAX8_PE1_DP")
	)
	(segment
		(start 361.005374 -135.211566)
		(end 361.005374 -134.718806)
		(width 0.1143)
		(layer "In9.Cu")
		(net "CLK_100M_AIRMAX8_PE1_DP")
	)
	(segment
		(start 340.112858 -137.091674)
		(end 343.179654 -137.091674)
		(width 0.1143)
		(layer "In9.Cu")
		(net "CLK_100M_AIRMAX8_PE1_DP")
	)
	(segment
		(start 347.697552 -138.139678)
		(end 348.121478 -138.563604)
		(width 0.1143)
		(layer "In9.Cu")
		(net "CLK_100M_AIRMAX8_PE1_DP")
	)
	(segment
		(start 364.394242 -130.8608)
		(end 364.559342 -130.6957)
		(width 0.1143)
		(layer "In9.Cu")
		(net "CLK_100M_AIRMAX8_PE1_DP")
	)
	(segment
		(start 372.276624 -121.770648)
		(end 372.276624 -121.537222)
		(width 0.1143)
		(layer "In9.Cu")
		(net "CLK_100M_AIRMAX8_PE1_DP")
	)
	(segment
		(start 164.302186 -151.51481)
		(end 167.480996 -148.336)
		(width 0.1143)
		(layer "In9.Cu")
		(net "CLK_100M_AIRMAX8_PE1_DP")
	)
	(segment
		(start 177.71491 -147.955)
		(end 180.228748 -147.955)
		(width 0.1143)
		(layer "In9.Cu")
		(net "CLK_100M_AIRMAX8_PE1_DP")
	)
	(segment
		(start 368.65179 -128.947926)
		(end 368.894106 -128.70561)
		(width 0.1143)
		(layer "In9.Cu")
		(net "CLK_100M_AIRMAX8_PE1_DP")
	)
	(segment
		(start 376.416316 -115.835176)
		(end 376.851926 -115.835176)
		(width 0.0889)
		(layer "In9.Cu")
		(net "CLK_100M_AIRMAX8_PE1_DP")
	)
	(segment
		(start 26.2382 -138.8872)
		(end 26.2382 -148.963634)
		(width 0.1143)
		(layer "In9.Cu")
		(net "CLK_100M_AIRMAX8_PE1_DP")
	)
	(segment
		(start 367.214912 -130.384804)
		(end 367.457228 -130.142488)
		(width 0.1143)
		(layer "In9.Cu")
		(net "CLK_100M_AIRMAX8_PE1_DP")
	)
	(segment
		(start 377.19 -115.497102)
		(end 377.19 -113.7412)
		(width 0.0889)
		(layer "In9.Cu")
		(net "CLK_100M_AIRMAX8_PE1_DP")
	)
	(segment
		(start 371.57533 -124.83211)
		(end 371.57533 -122.471942)
		(width 0.1143)
		(layer "In9.Cu")
		(net "CLK_100M_AIRMAX8_PE1_DP")
	)
	(segment
		(start 19.500596 -133.264656)
		(end 23.798022 -137.562082)
		(width 0.1143)
		(layer "In9.Cu")
		(net "CLK_100M_AIRMAX8_PE1_DP")
	)
	(segment
		(start 372.994936 -121.052336)
		(end 372.994936 -120.81891)
		(width 0.1143)
		(layer "In9.Cu")
		(net "CLK_100M_AIRMAX8_PE1_DP")
	)
	(segment
		(start 329.49515 -139.439396)
		(end 330.415646 -138.5189)
		(width 0.1143)
		(layer "In9.Cu")
		(net "CLK_100M_AIRMAX8_PE1_DP")
	)
	(segment
		(start 374.189244 -119.858028)
		(end 374.431814 -119.615458)
		(width 0.1143)
		(layer "In9.Cu")
		(net "CLK_100M_AIRMAX8_PE1_DP")
	)
	(segment
		(start 367.690654 -130.142488)
		(end 367.933224 -129.899918)
		(width 0.1143)
		(layer "In9.Cu")
		(net "CLK_100M_AIRMAX8_PE1_DP")
	)
	(segment
		(start 378.722636 -111.001556)
		(end 378.664724 -110.943644)
		(width 0.0889)
		(layer "In9.Cu")
		(net "CLK_100M_AIRMAX8_PE1_DP")
	)
	(segment
		(start 371.57533 -122.471942)
		(end 372.276624 -121.770648)
		(width 0.1143)
		(layer "In9.Cu")
		(net "CLK_100M_AIRMAX8_PE1_DP")
	)
	(segment
		(start 167.480996 -148.336)
		(end 177.33391 -148.336)
		(width 0.1143)
		(layer "In9.Cu")
		(net "CLK_100M_AIRMAX8_PE1_DP")
	)
	(segment
		(start 9.647428 -109.284516)
		(end 19.550126 -119.187214)
		(width 0.1143)
		(layer "In9.Cu")
		(net "CLK_100M_AIRMAX8_PE1_DP")
	)
	(segment
		(start 353.500436 -138.820906)
		(end 355.097842 -137.2235)
		(width 0.1143)
		(layer "In9.Cu")
		(net "CLK_100M_AIRMAX8_PE1_DP")
	)
	(segment
		(start 329.922378 -147.612354)
		(end 329.922378 -143.086582)
		(width 0.1143)
		(layer "In9.Cu")
		(net "CLK_100M_AIRMAX8_PE1_DP")
	)
	(segment
		(start 344.227658 -138.139678)
		(end 347.697552 -138.139678)
		(width 0.1143)
		(layer "In9.Cu")
		(net "CLK_100M_AIRMAX8_PE1_DP")
	)
	(segment
		(start 17.399 -128.4986)
		(end 19.500596 -130.600196)
		(width 0.1143)
		(layer "In9.Cu")
		(net "CLK_100M_AIRMAX8_PE1_DP")
	)
	(segment
		(start 374.67413 -119.139716)
		(end 374.907556 -119.139716)
		(width 0.1143)
		(layer "In9.Cu")
		(net "CLK_100M_AIRMAX8_PE1_DP")
	)
	(segment
		(start 370.79301 -127.040132)
		(end 370.79301 -125.61443)
		(width 0.1143)
		(layer "In9.Cu")
		(net "CLK_100M_AIRMAX8_PE1_DP")
	)
	(segment
		(start 368.894106 -128.70561)
		(end 369.127532 -128.70561)
		(width 0.1143)
		(layer "In9.Cu")
		(net "CLK_100M_AIRMAX8_PE1_DP")
	)
	(segment
		(start 370.79301 -125.61443)
		(end 371.57533 -124.83211)
		(width 0.1143)
		(layer "In9.Cu")
		(net "CLK_100M_AIRMAX8_PE1_DP")
	)
	(segment
		(start 372.752366 -121.294906)
		(end 372.994936 -121.052336)
		(width 0.1143)
		(layer "In9.Cu")
		(net "CLK_100M_AIRMAX8_PE1_DP")
	)
	(segment
		(start 363.886242 -130.6957)
		(end 364.051342 -130.8608)
		(width 0.1143)
		(layer "In9.Cu")
		(net "CLK_100M_AIRMAX8_PE1_DP")
	)
	(segment
		(start 373.713248 -120.100598)
		(end 373.955818 -119.858028)
		(width 0.1143)
		(layer "In9.Cu")
		(net "CLK_100M_AIRMAX8_PE1_DP")
	)
	(segment
		(start 362.0262 -133.69798)
		(end 362.0262 -131.869942)
		(width 0.1143)
		(layer "In9.Cu")
		(net "CLK_100M_AIRMAX8_PE1_DP")
	)
	(segment
		(start 348.121478 -138.563604)
		(end 351.143062 -138.563604)
		(width 0.1143)
		(layer "In9.Cu")
		(net "CLK_100M_AIRMAX8_PE1_DP")
	)
	(segment
		(start 186.553348 -153.97353)
		(end 187.961778 -152.5651)
		(width 0.1143)
		(layer "In9.Cu")
		(net "CLK_100M_AIRMAX8_PE1_DP")
	)
	(segment
		(start 362.0262 -131.869942)
		(end 363.035342 -130.8608)
		(width 0.1143)
		(layer "In9.Cu")
		(net "CLK_100M_AIRMAX8_PE1_DP")
	)
	(segment
		(start 363.543342 -130.6957)
		(end 363.886242 -130.6957)
		(width 0.1143)
		(layer "In9.Cu")
		(net "CLK_100M_AIRMAX8_PE1_DP")
	)
	(segment
		(start 185.860436 -153.97353)
		(end 186.553348 -153.97353)
		(width 0.1143)
		(layer "In9.Cu")
		(net "CLK_100M_AIRMAX8_PE1_DP")
	)
	(segment
		(start 377.701302 -113.229898)
		(end 377.701302 -112.653064)
		(width 0.0889)
		(layer "In9.Cu")
		(net "CLK_100M_AIRMAX8_PE1_DP")
	)
	(segment
		(start 9.647428 -109.122972)
		(end 9.647428 -109.284516)
		(width 0.1143)
		(layer "In9.Cu")
		(net "CLK_100M_AIRMAX8_PE1_DP")
	)
	(segment
		(start 372.51894 -121.294906)
		(end 372.752366 -121.294906)
		(width 0.1143)
		(layer "In9.Cu")
		(net "CLK_100M_AIRMAX8_PE1_DP")
	)
	(segment
		(start 366.083342 -130.8608)
		(end 366.972342 -130.8608)
		(width 0.1143)
		(layer "In9.Cu")
		(net "CLK_100M_AIRMAX8_PE1_DP")
	)
	(segment
		(start 367.214912 -130.61823)
		(end 367.214912 -130.384804)
		(width 0.1143)
		(layer "In9.Cu")
		(net "CLK_100M_AIRMAX8_PE1_DP")
	)
	(segment
		(start 373.470932 -120.57634)
		(end 373.713248 -120.334024)
		(width 0.1143)
		(layer "In9.Cu")
		(net "CLK_100M_AIRMAX8_PE1_DP")
	)
	(segment
		(start 329.49515 -142.659354)
		(end 329.49515 -139.439396)
		(width 0.1143)
		(layer "In9.Cu")
		(net "CLK_100M_AIRMAX8_PE1_DP")
	)
	(segment
		(start 375.150126 -118.483126)
		(end 375.150126 -118.461028)
		(width 0.0889)
		(layer "In9.Cu")
		(net "CLK_100M_AIRMAX8_PE1_DP")
	)
	(segment
		(start 24.913082 -137.562082)
		(end 26.2382 -138.8872)
		(width 0.1143)
		(layer "In9.Cu")
		(net "CLK_100M_AIRMAX8_PE1_DP")
	)
	(segment
		(start 375.200926 -118.410228)
		(end 375.200926 -117.050566)
		(width 0.0889)
		(layer "In9.Cu")
		(net "CLK_100M_AIRMAX8_PE1_DP")
	)
	(segment
		(start 329.922378 -143.086582)
		(end 329.49515 -142.659354)
		(width 0.1143)
		(layer "In9.Cu")
		(net "CLK_100M_AIRMAX8_PE1_DP")
	)
	(segment
		(start 19.550126 -122.747278)
		(end 17.399 -124.898404)
		(width 0.1143)
		(layer "In9.Cu")
		(net "CLK_100M_AIRMAX8_PE1_DP")
	)
	(segment
		(start 339.640926 -136.619742)
		(end 340.112858 -137.091674)
		(width 0.1143)
		(layer "In9.Cu")
		(net "CLK_100M_AIRMAX8_PE1_DP")
	)
	(segment
		(start 372.276624 -121.537222)
		(end 372.51894 -121.294906)
		(width 0.1143)
		(layer "In9.Cu")
		(net "CLK_100M_AIRMAX8_PE1_DP")
	)
	(segment
		(start 367.933224 -129.666492)
		(end 368.175794 -129.423922)
		(width 0.1143)
		(layer "In9.Cu")
		(net "CLK_100M_AIRMAX8_PE1_DP")
	)
	(segment
		(start 368.175794 -129.423922)
		(end 368.40922 -129.423922)
		(width 0.1143)
		(layer "In9.Cu")
		(net "CLK_100M_AIRMAX8_PE1_DP")
	)
	(segment
		(start 177.33391 -148.336)
		(end 177.71491 -147.955)
		(width 0.1143)
		(layer "In9.Cu")
		(net "CLK_100M_AIRMAX8_PE1_DP")
	)
	(segment
		(start 183.768238 -153.028904)
		(end 184.91581 -153.028904)
		(width 0.1143)
		(layer "In9.Cu")
		(net "CLK_100M_AIRMAX8_PE1_DP")
	)
	(segment
		(start 373.237252 -120.57634)
		(end 373.470932 -120.57634)
		(width 0.1143)
		(layer "In9.Cu")
		(net "CLK_100M_AIRMAX8_PE1_DP")
	)
	(segment
		(start 351.143062 -138.563604)
		(end 351.400364 -138.820906)
		(width 0.1143)
		(layer "In9.Cu")
		(net "CLK_100M_AIRMAX8_PE1_DP")
	)
	(segment
		(start 29.472128 -152.197562)
		(end 158.710376 -152.197562)
		(width 0.1143)
		(layer "In9.Cu")
		(net "CLK_100M_AIRMAX8_PE1_DP")
	)
	(segment
		(start 364.902242 -130.6957)
		(end 365.067342 -130.8608)
		(width 0.1143)
		(layer "In9.Cu")
		(net "CLK_100M_AIRMAX8_PE1_DP")
	)
	(segment
		(start 182.99557 -150.721822)
		(end 182.99557 -152.256236)
		(width 0.1143)
		(layer "In9.Cu")
		(net "CLK_100M_AIRMAX8_PE1_DP")
	)
	(segment
		(start 330.154026 -152.231598)
		(end 330.154026 -147.844002)
		(width 0.1143)
		(layer "In9.Cu")
		(net "CLK_100M_AIRMAX8_PE1_DP")
	)
	(segment
		(start 187.961778 -152.5651)
		(end 329.820524 -152.5651)
		(width 0.1143)
		(layer "In9.Cu")
		(net "CLK_100M_AIRMAX8_PE1_DP")
	)
	(segment
		(start 355.097842 -137.2235)
		(end 358.99344 -137.2235)
		(width 0.1143)
		(layer "In9.Cu")
		(net "CLK_100M_AIRMAX8_PE1_DP")
	)
	(segment
		(start 374.431814 -119.615458)
		(end 374.431814 -119.382032)
		(width 0.1143)
		(layer "In9.Cu")
		(net "CLK_100M_AIRMAX8_PE1_DP")
	)
	(segment
		(start 365.918242 -130.6957)
		(end 366.083342 -130.8608)
		(width 0.1143)
		(layer "In9.Cu")
		(net "CLK_100M_AIRMAX8_PE1_DP")
	)
	(segment
		(start 374.431814 -119.382032)
		(end 374.67413 -119.139716)
		(width 0.1143)
		(layer "In9.Cu")
		(net "CLK_100M_AIRMAX8_PE1_DP")
	)
	(segment
		(start 377.853194 -112.251744)
		(end 378.031248 -112.148874)
		(width 0.0889)
		(layer "In9.Cu")
		(net "CLK_100M_AIRMAX8_PE1_DP")
	)
	(segment
		(start 363.378242 -130.8608)
		(end 363.543342 -130.6957)
		(width 0.1143)
		(layer "In9.Cu")
		(net "CLK_100M_AIRMAX8_PE1_DP")
	)
	(segment
		(start 363.035342 -130.8608)
		(end 363.378242 -130.8608)
		(width 0.1143)
		(layer "In9.Cu")
		(net "CLK_100M_AIRMAX8_PE1_DP")
	)
	(segment
		(start 367.457228 -130.142488)
		(end 367.690654 -130.142488)
		(width 0.1143)
		(layer "In9.Cu")
		(net "CLK_100M_AIRMAX8_PE1_DP")
	)
	(segment
		(start 361.005374 -134.718806)
		(end 362.0262 -133.69798)
		(width 0.1143)
		(layer "In9.Cu")
		(net "CLK_100M_AIRMAX8_PE1_DP")
	)
	(segment
		(start 364.559342 -130.6957)
		(end 364.902242 -130.6957)
		(width 0.1143)
		(layer "In9.Cu")
		(net "CLK_100M_AIRMAX8_PE1_DP")
	)
	(segment
		(start 364.051342 -130.8608)
		(end 364.394242 -130.8608)
		(width 0.1143)
		(layer "In9.Cu")
		(net "CLK_100M_AIRMAX8_PE1_DP")
	)
	(segment
		(start 378.664724 -110.943644)
		(end 378.32665 -110.943644)
		(width 0.0889)
		(layer "In9.Cu")
		(net "CLK_100M_AIRMAX8_PE1_DP")
	)
	(segment
		(start 375.150126 -118.897146)
		(end 375.150126 -118.483126)
		(width 0.1143)
		(layer "In9.Cu")
		(net "CLK_100M_AIRMAX8_PE1_DP")
	)
	(segment
		(start 358.99344 -137.2235)
		(end 361.005374 -135.211566)
		(width 0.1143)
		(layer "In9.Cu")
		(net "CLK_100M_AIRMAX8_PE1_DP")
	)
	(segment
		(start 329.820524 -152.5651)
		(end 330.154026 -152.231598)
		(width 0.1143)
		(layer "In9.Cu")
		(net "CLK_100M_AIRMAX8_PE1_DP")
	)
	(segment
		(start 376.851926 -115.835176)
		(end 377.19 -115.497102)
		(width 0.0889)
		(layer "In9.Cu")
		(net "CLK_100M_AIRMAX8_PE1_DP")
	)
	(segment
		(start 334.980534 -138.5189)
		(end 336.879692 -136.619742)
		(width 0.1143)
		(layer "In9.Cu")
		(net "CLK_100M_AIRMAX8_PE1_DP")
	)
	(segment
		(start 336.879692 -136.619742)
		(end 339.640926 -136.619742)
		(width 0.1143)
		(layer "In9.Cu")
		(net "CLK_100M_AIRMAX8_PE1_DP")
	)
	(segment
		(start 365.067342 -130.8608)
		(end 365.410242 -130.8608)
		(width 0.1143)
		(layer "In9.Cu")
		(net "CLK_100M_AIRMAX8_PE1_DP")
	)
	(segment
		(start 19.550126 -119.187214)
		(end 19.550126 -122.747278)
		(width 0.1143)
		(layer "In9.Cu")
		(net "CLK_100M_AIRMAX8_PE1_DP")
	)
	(segment
		(start 9.694164 -109.076236)
		(end 9.647428 -109.122972)
		(width 0.1143)
		(layer "In9.Cu")
		(net "CLK_100M_AIRMAX8_PE1_DP")
	)
	(segment
		(start 368.65179 -129.181352)
		(end 368.65179 -128.947926)
		(width 0.1143)
		(layer "In9.Cu")
		(net "CLK_100M_AIRMAX8_PE1_DP")
	)
	(segment
		(start 375.150126 -118.461028)
		(end 375.200926 -118.410228)
		(width 0.0889)
		(layer "In9.Cu")
		(net "CLK_100M_AIRMAX8_PE1_DP")
	)
	(segment
		(start 159.393128 -151.51481)
		(end 164.302186 -151.51481)
		(width 0.1143)
		(layer "In9.Cu")
		(net "CLK_100M_AIRMAX8_PE1_DP")
	)
	(segment
		(start 26.2382 -148.963634)
		(end 29.472128 -152.197562)
		(width 0.1143)
		(layer "In9.Cu")
		(net "CLK_100M_AIRMAX8_PE1_DP")
	)
	(segment
		(start 180.228748 -147.955)
		(end 182.99557 -150.721822)
		(width 0.1143)
		(layer "In9.Cu")
		(net "CLK_100M_AIRMAX8_PE1_DP")
	)
	(segment
		(start 365.575342 -130.6957)
		(end 365.918242 -130.6957)
		(width 0.1143)
		(layer "In9.Cu")
		(net "CLK_100M_AIRMAX8_PE1_DP")
	)
	(segment
		(start 184.91581 -153.028904)
		(end 185.860436 -153.97353)
		(width 0.1143)
		(layer "In9.Cu")
		(net "CLK_100M_AIRMAX8_PE1_DP")
	)
	(segment
		(start 368.40922 -129.423922)
		(end 368.65179 -129.181352)
		(width 0.1143)
		(layer "In9.Cu")
		(net "CLK_100M_AIRMAX8_PE1_DP")
	)
	(segment
		(start 375.200926 -117.050566)
		(end 376.416316 -115.835176)
		(width 0.0889)
		(layer "In9.Cu")
		(net "CLK_100M_AIRMAX8_PE1_DP")
	)
	(segment
		(start 369.127532 -128.70561)
		(end 370.79301 -127.040132)
		(width 0.1143)
		(layer "In9.Cu")
		(net "CLK_100M_AIRMAX8_PE1_DP")
	)
	(segment
		(start 373.713248 -120.334024)
		(end 373.713248 -120.100598)
		(width 0.1143)
		(layer "In9.Cu")
		(net "CLK_100M_AIRMAX8_PE1_DP")
	)
	(segment
		(start 182.99557 -152.256236)
		(end 183.768238 -153.028904)
		(width 0.1143)
		(layer "In9.Cu")
		(net "CLK_100M_AIRMAX8_PE1_DP")
	)
	(segment
		(start 373.955818 -119.858028)
		(end 374.189244 -119.858028)
		(width 0.1143)
		(layer "In9.Cu")
		(net "CLK_100M_AIRMAX8_PE1_DP")
	)
	(segment
		(start 10.40511 -109.076236)
		(end 9.694164 -109.076236)
		(width 0.1143)
		(layer "In9.Cu")
		(net "CLK_100M_AIRMAX8_PE1_DP")
	)
	(segment
		(start 365.410242 -130.8608)
		(end 365.575342 -130.6957)
		(width 0.1143)
		(layer "In9.Cu")
		(net "CLK_100M_AIRMAX8_PE1_DP")
	)
	(segment
		(start 351.400364 -138.820906)
		(end 353.500436 -138.820906)
		(width 0.1143)
		(layer "In9.Cu")
		(net "CLK_100M_AIRMAX8_PE1_DP")
	)
	(segment
		(start 17.399 -124.898404)
		(end 17.399 -128.4986)
		(width 0.1143)
		(layer "In9.Cu")
		(net "CLK_100M_AIRMAX8_PE1_DP")
	)
	(segment
		(start 366.972342 -130.8608)
		(end 367.214912 -130.61823)
		(width 0.1143)
		(layer "In9.Cu")
		(net "CLK_100M_AIRMAX8_PE1_DP")
	)
	(segment
		(start 23.798022 -137.562082)
		(end 24.913082 -137.562082)
		(width 0.1143)
		(layer "In9.Cu")
		(net "CLK_100M_AIRMAX8_PE1_DP")
	)
	(arc
		(start 378.526548 -111.290354)
		(mid 378.657744 -111.168463)
		(end 378.722636 -111.001556)
		(width 0.0889)
		(layer "In9.Cu")
		(net "CLK_100M_AIRMAX8_PE1_DP")
	)
	(arc
		(start 378.2314 -111.780574)
		(mid 378.315681 -111.497357)
		(end 378.526548 -111.290354)
		(width 0.0889)
		(layer "In9.Cu")
		(net "CLK_100M_AIRMAX8_PE1_DP")
	)
	(arc
		(start 377.701302 -112.653064)
		(mid 377.741777 -112.438984)
		(end 377.853194 -112.251744)
		(width 0.0889)
		(layer "In9.Cu")
		(net "CLK_100M_AIRMAX8_PE1_DP")
	)
	(arc
		(start 378.031248 -112.148874)
		(mid 378.175052 -112.007191)
		(end 378.2314 -111.81334)
		(width 0.0889)
		(layer "In9.Cu")
		(net "CLK_100M_AIRMAX8_PE1_DP")
	)
	(segment
		(start 378.82195 -110.71352)
		(end 379.31725 -110.943644)
		(width 0.127)
		(layer "F.Cu")
		(net "CLK_100M_AIRMAX8_PE1_DN")
	)
	(via
		(at 379.31725 -110.943644)
		(size 0.508)
		(drill 0.254)
		(layers "F.Cu" "B.Cu")
		(net "CLK_100M_AIRMAX8_PE1_DN")
	)
	(via
		(at 9.5377 -108.0516)
		(size 0.508)
		(drill 0.254)
		(layers "F.Cu" "B.Cu")
		(net "CLK_100M_AIRMAX8_PE1_DN")
	)
	(segment
		(start 18.3642 -106.324146)
		(end 18.5293 -106.159046)
		(width 0.1143)
		(layer "In4.Cu")
		(net "CLK_100M_AIRMAX8_PE1_DN")
	)
	(segment
		(start 8.65632 -32.8676)
		(end 7.17804 -32.8676)
		(width 0.1143)
		(layer "In4.Cu")
		(net "CLK_100M_AIRMAX8_PE1_DN")
	)
	(segment
		(start 17.336516 -108.134404)
		(end 17.578832 -107.892088)
		(width 0.1143)
		(layer "In4.Cu")
		(net "CLK_100M_AIRMAX8_PE1_DN")
	)
	(segment
		(start 13.9065 -82.010758)
		(end 12.4333 -80.537558)
		(width 0.1143)
		(layer "In4.Cu")
		(net "CLK_100M_AIRMAX8_PE1_DN")
	)
	(segment
		(start 13.766546 -108.2294)
		(end 15.239746 -109.7026)
		(width 0.1143)
		(layer "In4.Cu")
		(net "CLK_100M_AIRMAX8_PE1_DN")
	)
	(segment
		(start 12.756388 -94.199202)
		(end 12.921488 -94.034102)
		(width 0.1143)
		(layer "In4.Cu")
		(net "CLK_100M_AIRMAX8_PE1_DN")
	)
	(segment
		(start 12.694158 -86.138258)
		(end 12.694158 -84.283042)
		(width 0.1143)
		(layer "In4.Cu")
		(net "CLK_100M_AIRMAX8_PE1_DN")
	)
	(segment
		(start 6.646164 -33.399476)
		(end 6.646164 -33.595818)
		(width 0.1143)
		(layer "In4.Cu")
		(net "CLK_100M_AIRMAX8_PE1_DN")
	)
	(segment
		(start 15.37335 -69.324982)
		(end 18.732754 -69.324982)
		(width 0.1143)
		(layer "In4.Cu")
		(net "CLK_100M_AIRMAX8_PE1_DN")
	)
	(segment
		(start 18.5293 -100.657914)
		(end 18.5293 -100.315014)
		(width 0.1143)
		(layer "In4.Cu")
		(net "CLK_100M_AIRMAX8_PE1_DN")
	)
	(segment
		(start 16.86052 -108.6104)
		(end 17.093946 -108.6104)
		(width 0.1143)
		(layer "In4.Cu")
		(net "CLK_100M_AIRMAX8_PE1_DN")
	)
	(segment
		(start 14.103858 -96.889316)
		(end 13.870432 -96.889316)
		(width 0.1143)
		(layer "In4.Cu")
		(net "CLK_100M_AIRMAX8_PE1_DN")
	)
	(segment
		(start 13.67155 -53.919374)
		(end 13.67155 -49.95291)
		(width 0.1143)
		(layer "In4.Cu")
		(net "CLK_100M_AIRMAX8_PE1_DN")
	)
	(segment
		(start 14.82217 -97.607628)
		(end 14.588744 -97.607628)
		(width 0.1143)
		(layer "In4.Cu")
		(net "CLK_100M_AIRMAX8_PE1_DN")
	)
	(segment
		(start 14.346428 -97.131886)
		(end 14.103858 -96.889316)
		(width 0.1143)
		(layer "In4.Cu")
		(net "CLK_100M_AIRMAX8_PE1_DN")
	)
	(segment
		(start 13.042646 -37.7317)
		(end 11.207496 -37.7317)
		(width 0.1143)
		(layer "In4.Cu")
		(net "CLK_100M_AIRMAX8_PE1_DN")
	)
	(segment
		(start 17.371314 -43.33113)
		(end 13.784326 -39.744142)
		(width 0.1143)
		(layer "In4.Cu")
		(net "CLK_100M_AIRMAX8_PE1_DN")
	)
	(segment
		(start 12.4333 -80.537558)
		(end 12.4333 -79.533242)
		(width 0.1143)
		(layer "In4.Cu")
		(net "CLK_100M_AIRMAX8_PE1_DN")
	)
	(segment
		(start 13.628116 -96.647)
		(end 13.628116 -96.413574)
		(width 0.1143)
		(layer "In4.Cu")
		(net "CLK_100M_AIRMAX8_PE1_DN")
	)
	(segment
		(start 12.921488 -93.691202)
		(end 12.756388 -93.526102)
		(width 0.1143)
		(layer "In4.Cu")
		(net "CLK_100M_AIRMAX8_PE1_DN")
	)
	(segment
		(start 18.5293 -100.315014)
		(end 16.791686 -98.5774)
		(width 0.1143)
		(layer "In4.Cu")
		(net "CLK_100M_AIRMAX8_PE1_DN")
	)
	(segment
		(start 9.5377 -108.0516)
		(end 9.80313 -108.365544)
		(width 0.1143)
		(layer "In4.Cu")
		(net "CLK_100M_AIRMAX8_PE1_DN")
	)
	(segment
		(start 13.67155 -49.95291)
		(end 14.134338 -49.490122)
		(width 0.1143)
		(layer "In4.Cu")
		(net "CLK_100M_AIRMAX8_PE1_DN")
	)
	(segment
		(start 20.178776 -67.87896)
		(end 20.178776 -56.06669)
		(width 0.1143)
		(layer "In4.Cu")
		(net "CLK_100M_AIRMAX8_PE1_DN")
	)
	(segment
		(start 18.5293 -105.143046)
		(end 18.5293 -101.331014)
		(width 0.1143)
		(layer "In4.Cu")
		(net "CLK_100M_AIRMAX8_PE1_DN")
	)
	(segment
		(start 18.3642 -101.165914)
		(end 18.3642 -100.823014)
		(width 0.1143)
		(layer "In4.Cu")
		(net "CLK_100M_AIRMAX8_PE1_DN")
	)
	(segment
		(start 17.812258 -107.892088)
		(end 18.5293 -107.175046)
		(width 0.1143)
		(layer "In4.Cu")
		(net "CLK_100M_AIRMAX8_PE1_DN")
	)
	(segment
		(start 13.870432 -96.889316)
		(end 13.628116 -96.647)
		(width 0.1143)
		(layer "In4.Cu")
		(net "CLK_100M_AIRMAX8_PE1_DN")
	)
	(segment
		(start 10.140696 -108.2294)
		(end 13.766546 -108.2294)
		(width 0.1143)
		(layer "In4.Cu")
		(net "CLK_100M_AIRMAX8_PE1_DN")
	)
	(segment
		(start 14.648434 -54.896258)
		(end 13.67155 -53.919374)
		(width 0.1143)
		(layer "In4.Cu")
		(net "CLK_100M_AIRMAX8_PE1_DN")
	)
	(segment
		(start 17.371314 -48.49622)
		(end 17.371314 -43.33113)
		(width 0.1143)
		(layer "In4.Cu")
		(net "CLK_100M_AIRMAX8_PE1_DN")
	)
	(segment
		(start 13.628116 -96.413574)
		(end 13.385546 -96.171004)
		(width 0.1143)
		(layer "In4.Cu")
		(net "CLK_100M_AIRMAX8_PE1_DN")
	)
	(segment
		(start 18.3642 -100.823014)
		(end 18.5293 -100.657914)
		(width 0.1143)
		(layer "In4.Cu")
		(net "CLK_100M_AIRMAX8_PE1_DN")
	)
	(segment
		(start 16.377412 -49.490122)
		(end 17.371314 -48.49622)
		(width 0.1143)
		(layer "In4.Cu")
		(net "CLK_100M_AIRMAX8_PE1_DN")
	)
	(segment
		(start 12.921488 -92.10929)
		(end 13.683742 -91.347036)
		(width 0.1143)
		(layer "In4.Cu")
		(net "CLK_100M_AIRMAX8_PE1_DN")
	)
	(segment
		(start 12.921488 -94.034102)
		(end 12.921488 -93.691202)
		(width 0.1143)
		(layer "In4.Cu")
		(net "CLK_100M_AIRMAX8_PE1_DN")
	)
	(segment
		(start 13.784326 -39.744142)
		(end 13.784326 -38.47338)
		(width 0.1143)
		(layer "In4.Cu")
		(net "CLK_100M_AIRMAX8_PE1_DN")
	)
	(segment
		(start 14.134338 -49.490122)
		(end 16.377412 -49.490122)
		(width 0.1143)
		(layer "In4.Cu")
		(net "CLK_100M_AIRMAX8_PE1_DN")
	)
	(segment
		(start 12.921488 -94.707202)
		(end 12.756388 -94.542102)
		(width 0.1143)
		(layer "In4.Cu")
		(net "CLK_100M_AIRMAX8_PE1_DN")
	)
	(segment
		(start 18.3642 -105.651046)
		(end 18.3642 -105.308146)
		(width 0.1143)
		(layer "In4.Cu")
		(net "CLK_100M_AIRMAX8_PE1_DN")
	)
	(segment
		(start 11.207496 -37.7317)
		(end 10.5029 -37.027104)
		(width 0.1143)
		(layer "In4.Cu")
		(net "CLK_100M_AIRMAX8_PE1_DN")
	)
	(segment
		(start 13.784326 -38.47338)
		(end 13.042646 -37.7317)
		(width 0.1143)
		(layer "In4.Cu")
		(net "CLK_100M_AIRMAX8_PE1_DN")
	)
	(segment
		(start 12.756388 -93.183202)
		(end 12.921488 -93.018102)
		(width 0.1143)
		(layer "In4.Cu")
		(net "CLK_100M_AIRMAX8_PE1_DN")
	)
	(segment
		(start 13.594842 -83.6041)
		(end 13.9065 -83.292442)
		(width 0.1143)
		(layer "In4.Cu")
		(net "CLK_100M_AIRMAX8_PE1_DN")
	)
	(segment
		(start 18.5293 -105.816146)
		(end 18.3642 -105.651046)
		(width 0.1143)
		(layer "In4.Cu")
		(net "CLK_100M_AIRMAX8_PE1_DN")
	)
	(segment
		(start 12.9159 -86.570058)
		(end 12.9159 -86.36)
		(width 0.1143)
		(layer "In4.Cu")
		(net "CLK_100M_AIRMAX8_PE1_DN")
	)
	(segment
		(start 13.798296 -78.473046)
		(end 14.0589 -78.212442)
		(width 0.1143)
		(layer "In4.Cu")
		(net "CLK_100M_AIRMAX8_PE1_DN")
	)
	(segment
		(start 15.239746 -109.7026)
		(end 16.001746 -109.7026)
		(width 0.1143)
		(layer "In4.Cu")
		(net "CLK_100M_AIRMAX8_PE1_DN")
	)
	(segment
		(start 19.008344 -54.896258)
		(end 14.648434 -54.896258)
		(width 0.1143)
		(layer "In4.Cu")
		(net "CLK_100M_AIRMAX8_PE1_DN")
	)
	(segment
		(start 18.732754 -69.324982)
		(end 20.178776 -67.87896)
		(width 0.1143)
		(layer "In4.Cu")
		(net "CLK_100M_AIRMAX8_PE1_DN")
	)
	(segment
		(start 18.3642 -105.308146)
		(end 18.5293 -105.143046)
		(width 0.1143)
		(layer "In4.Cu")
		(net "CLK_100M_AIRMAX8_PE1_DN")
	)
	(segment
		(start 10.5029 -37.027104)
		(end 10.5029 -34.71418)
		(width 0.1143)
		(layer "In4.Cu")
		(net "CLK_100M_AIRMAX8_PE1_DN")
	)
	(segment
		(start 16.791686 -98.5774)
		(end 15.791942 -98.5774)
		(width 0.1143)
		(layer "In4.Cu")
		(net "CLK_100M_AIRMAX8_PE1_DN")
	)
	(segment
		(start 13.683742 -91.347036)
		(end 13.683742 -87.3379)
		(width 0.1143)
		(layer "In4.Cu")
		(net "CLK_100M_AIRMAX8_PE1_DN")
	)
	(segment
		(start 12.756388 -93.526102)
		(end 12.756388 -93.183202)
		(width 0.1143)
		(layer "In4.Cu")
		(net "CLK_100M_AIRMAX8_PE1_DN")
	)
	(segment
		(start 13.3731 -83.6041)
		(end 13.594842 -83.6041)
		(width 0.1143)
		(layer "In4.Cu")
		(net "CLK_100M_AIRMAX8_PE1_DN")
	)
	(segment
		(start 14.0589 -70.639432)
		(end 15.37335 -69.324982)
		(width 0.1143)
		(layer "In4.Cu")
		(net "CLK_100M_AIRMAX8_PE1_DN")
	)
	(segment
		(start 16.61795 -108.85297)
		(end 16.86052 -108.6104)
		(width 0.1143)
		(layer "In4.Cu")
		(net "CLK_100M_AIRMAX8_PE1_DN")
	)
	(segment
		(start 18.5293 -106.159046)
		(end 18.5293 -105.816146)
		(width 0.1143)
		(layer "In4.Cu")
		(net "CLK_100M_AIRMAX8_PE1_DN")
	)
	(segment
		(start 9.964166 -108.378752)
		(end 10.140696 -108.2294)
		(width 0.1143)
		(layer "In4.Cu")
		(net "CLK_100M_AIRMAX8_PE1_DN")
	)
	(segment
		(start 18.5293 -107.175046)
		(end 18.5293 -106.832146)
		(width 0.1143)
		(layer "In4.Cu")
		(net "CLK_100M_AIRMAX8_PE1_DN")
	)
	(segment
		(start 16.001746 -109.7026)
		(end 16.61795 -109.086396)
		(width 0.1143)
		(layer "In4.Cu")
		(net "CLK_100M_AIRMAX8_PE1_DN")
	)
	(segment
		(start 10.5029 -34.71418)
		(end 8.65632 -32.8676)
		(width 0.1143)
		(layer "In4.Cu")
		(net "CLK_100M_AIRMAX8_PE1_DN")
	)
	(segment
		(start 6.760464 -33.710118)
		(end 7.199884 -33.710118)
		(width 0.1143)
		(layer "In4.Cu")
		(net "CLK_100M_AIRMAX8_PE1_DN")
	)
	(segment
		(start 13.9065 -83.292442)
		(end 13.9065 -82.010758)
		(width 0.1143)
		(layer "In4.Cu")
		(net "CLK_100M_AIRMAX8_PE1_DN")
	)
	(segment
		(start 9.80313 -108.365544)
		(end 9.964166 -108.378752)
		(width 0.1143)
		(layer "In4.Cu")
		(net "CLK_100M_AIRMAX8_PE1_DN")
	)
	(segment
		(start 12.4333 -79.533242)
		(end 13.493496 -78.473046)
		(width 0.1143)
		(layer "In4.Cu")
		(net "CLK_100M_AIRMAX8_PE1_DN")
	)
	(segment
		(start 14.346428 -97.365312)
		(end 14.346428 -97.131886)
		(width 0.1143)
		(layer "In4.Cu")
		(net "CLK_100M_AIRMAX8_PE1_DN")
	)
	(segment
		(start 13.683742 -87.3379)
		(end 12.9159 -86.570058)
		(width 0.1143)
		(layer "In4.Cu")
		(net "CLK_100M_AIRMAX8_PE1_DN")
	)
	(segment
		(start 14.0589 -78.212442)
		(end 14.0589 -70.639432)
		(width 0.1143)
		(layer "In4.Cu")
		(net "CLK_100M_AIRMAX8_PE1_DN")
	)
	(segment
		(start 13.493496 -78.473046)
		(end 13.798296 -78.473046)
		(width 0.1143)
		(layer "In4.Cu")
		(net "CLK_100M_AIRMAX8_PE1_DN")
	)
	(segment
		(start 18.3642 -106.667046)
		(end 18.3642 -106.324146)
		(width 0.1143)
		(layer "In4.Cu")
		(net "CLK_100M_AIRMAX8_PE1_DN")
	)
	(segment
		(start 12.9159 -86.36)
		(end 12.694158 -86.138258)
		(width 0.1143)
		(layer "In4.Cu")
		(net "CLK_100M_AIRMAX8_PE1_DN")
	)
	(segment
		(start 14.588744 -97.607628)
		(end 14.346428 -97.365312)
		(width 0.1143)
		(layer "In4.Cu")
		(net "CLK_100M_AIRMAX8_PE1_DN")
	)
	(segment
		(start 13.385546 -96.171004)
		(end 12.921488 -95.050102)
		(width 0.1143)
		(layer "In4.Cu")
		(net "CLK_100M_AIRMAX8_PE1_DN")
	)
	(segment
		(start 7.17804 -32.8676)
		(end 6.646164 -33.399476)
		(width 0.1143)
		(layer "In4.Cu")
		(net "CLK_100M_AIRMAX8_PE1_DN")
	)
	(segment
		(start 17.093946 -108.6104)
		(end 17.336516 -108.36783)
		(width 0.1143)
		(layer "In4.Cu")
		(net "CLK_100M_AIRMAX8_PE1_DN")
	)
	(segment
		(start 20.178776 -56.06669)
		(end 19.008344 -54.896258)
		(width 0.1143)
		(layer "In4.Cu")
		(net "CLK_100M_AIRMAX8_PE1_DN")
	)
	(segment
		(start 16.61795 -109.086396)
		(end 16.61795 -108.85297)
		(width 0.1143)
		(layer "In4.Cu")
		(net "CLK_100M_AIRMAX8_PE1_DN")
	)
	(segment
		(start 12.694158 -84.283042)
		(end 13.3731 -83.6041)
		(width 0.1143)
		(layer "In4.Cu")
		(net "CLK_100M_AIRMAX8_PE1_DN")
	)
	(segment
		(start 12.921488 -93.018102)
		(end 12.921488 -92.10929)
		(width 0.1143)
		(layer "In4.Cu")
		(net "CLK_100M_AIRMAX8_PE1_DN")
	)
	(segment
		(start 17.336516 -108.36783)
		(end 17.336516 -108.134404)
		(width 0.1143)
		(layer "In4.Cu")
		(net "CLK_100M_AIRMAX8_PE1_DN")
	)
	(segment
		(start 18.5293 -101.331014)
		(end 18.3642 -101.165914)
		(width 0.1143)
		(layer "In4.Cu")
		(net "CLK_100M_AIRMAX8_PE1_DN")
	)
	(segment
		(start 15.791942 -98.5774)
		(end 14.82217 -97.607628)
		(width 0.1143)
		(layer "In4.Cu")
		(net "CLK_100M_AIRMAX8_PE1_DN")
	)
	(segment
		(start 6.646164 -33.595818)
		(end 6.760464 -33.710118)
		(width 0.1143)
		(layer "In4.Cu")
		(net "CLK_100M_AIRMAX8_PE1_DN")
	)
	(segment
		(start 17.578832 -107.892088)
		(end 17.812258 -107.892088)
		(width 0.1143)
		(layer "In4.Cu")
		(net "CLK_100M_AIRMAX8_PE1_DN")
	)
	(segment
		(start 18.5293 -106.832146)
		(end 18.3642 -106.667046)
		(width 0.1143)
		(layer "In4.Cu")
		(net "CLK_100M_AIRMAX8_PE1_DN")
	)
	(segment
		(start 12.921488 -95.050102)
		(end 12.921488 -94.707202)
		(width 0.1143)
		(layer "In4.Cu")
		(net "CLK_100M_AIRMAX8_PE1_DN")
	)
	(segment
		(start 12.756388 -94.542102)
		(end 12.756388 -94.199202)
		(width 0.1143)
		(layer "In4.Cu")
		(net "CLK_100M_AIRMAX8_PE1_DN")
	)
	(segment
		(start 329.78725 -142.538196)
		(end 330.214478 -142.965424)
		(width 0.1143)
		(layer "In9.Cu")
		(net "CLK_100M_AIRMAX8_PE1_DN")
	)
	(segment
		(start 363.1565 -131.1529)
		(end 362.3183 -131.9911)
		(width 0.1143)
		(layer "In9.Cu")
		(net "CLK_100M_AIRMAX8_PE1_DN")
	)
	(segment
		(start 182.70347 -152.377394)
		(end 182.70347 -150.84298)
		(width 0.1143)
		(layer "In9.Cu")
		(net "CLK_100M_AIRMAX8_PE1_DN")
	)
	(segment
		(start 353.621594 -139.113006)
		(end 351.279206 -139.113006)
		(width 0.1143)
		(layer "In9.Cu")
		(net "CLK_100M_AIRMAX8_PE1_DN")
	)
	(segment
		(start 367.0935 -131.1529)
		(end 363.1565 -131.1529)
		(width 0.1143)
		(layer "In9.Cu")
		(net "CLK_100M_AIRMAX8_PE1_DN")
	)
	(segment
		(start 19.208496 -130.721354)
		(end 17.1069 -128.619758)
		(width 0.1143)
		(layer "In9.Cu")
		(net "CLK_100M_AIRMAX8_PE1_DN")
	)
	(segment
		(start 348.00032 -138.855704)
		(end 347.576394 -138.431778)
		(width 0.1143)
		(layer "In9.Cu")
		(net "CLK_100M_AIRMAX8_PE1_DN")
	)
	(segment
		(start 344.1065 -138.431778)
		(end 343.058496 -137.383774)
		(width 0.1143)
		(layer "In9.Cu")
		(net "CLK_100M_AIRMAX8_PE1_DN")
	)
	(segment
		(start 379.31725 -110.943644)
		(end 378.979176 -110.943644)
		(width 0.0889)
		(layer "In9.Cu")
		(net "CLK_100M_AIRMAX8_PE1_DN")
	)
	(segment
		(start 9.355328 -109.001814)
		(end 9.5377 -108.819442)
		(width 0.1143)
		(layer "In9.Cu")
		(net "CLK_100M_AIRMAX8_PE1_DN")
	)
	(segment
		(start 377.3805 -115.576096)
		(end 376.93092 -116.025676)
		(width 0.0889)
		(layer "In9.Cu")
		(net "CLK_100M_AIRMAX8_PE1_DN")
	)
	(segment
		(start 362.3183 -131.9911)
		(end 362.3183 -133.819138)
		(width 0.1143)
		(layer "In9.Cu")
		(net "CLK_100M_AIRMAX8_PE1_DN")
	)
	(segment
		(start 378.4219 -111.790988)
		(end 378.4219 -111.823754)
		(width 0.0889)
		(layer "In9.Cu")
		(net "CLK_100M_AIRMAX8_PE1_DN")
	)
	(segment
		(start 182.70347 -150.84298)
		(end 180.10759 -148.2471)
		(width 0.1143)
		(layer "In9.Cu")
		(net "CLK_100M_AIRMAX8_PE1_DN")
	)
	(segment
		(start 188.082936 -152.8572)
		(end 186.674506 -154.26563)
		(width 0.1143)
		(layer "In9.Cu")
		(net "CLK_100M_AIRMAX8_PE1_DN")
	)
	(segment
		(start 375.442226 -119.018304)
		(end 371.86743 -122.5931)
		(width 0.1143)
		(layer "In9.Cu")
		(net "CLK_100M_AIRMAX8_PE1_DN")
	)
	(segment
		(start 371.08511 -127.161036)
		(end 367.0935 -131.1529)
		(width 0.1143)
		(layer "In9.Cu")
		(net "CLK_100M_AIRMAX8_PE1_DN")
	)
	(segment
		(start 177.836068 -148.2471)
		(end 177.455068 -148.6281)
		(width 0.1143)
		(layer "In9.Cu")
		(net "CLK_100M_AIRMAX8_PE1_DN")
	)
	(segment
		(start 330.446126 -152.352756)
		(end 329.941682 -152.8572)
		(width 0.1143)
		(layer "In9.Cu")
		(net "CLK_100M_AIRMAX8_PE1_DN")
	)
	(segment
		(start 164.423344 -151.80691)
		(end 159.514286 -151.80691)
		(width 0.1143)
		(layer "In9.Cu")
		(net "CLK_100M_AIRMAX8_PE1_DN")
	)
	(segment
		(start 180.10759 -148.2471)
		(end 177.836068 -148.2471)
		(width 0.1143)
		(layer "In9.Cu")
		(net "CLK_100M_AIRMAX8_PE1_DN")
	)
	(segment
		(start 351.021904 -138.855704)
		(end 348.00032 -138.855704)
		(width 0.1143)
		(layer "In9.Cu")
		(net "CLK_100M_AIRMAX8_PE1_DN")
	)
	(segment
		(start 25.9461 -149.084792)
		(end 25.9461 -139.008358)
		(width 0.1143)
		(layer "In9.Cu")
		(net "CLK_100M_AIRMAX8_PE1_DN")
	)
	(segment
		(start 371.86743 -124.953268)
		(end 371.08511 -125.735588)
		(width 0.1143)
		(layer "In9.Cu")
		(net "CLK_100M_AIRMAX8_PE1_DN")
	)
	(segment
		(start 378.979176 -110.943644)
		(end 378.914152 -111.008668)
		(width 0.0889)
		(layer "In9.Cu")
		(net "CLK_100M_AIRMAX8_PE1_DN")
	)
	(segment
		(start 329.78725 -139.560554)
		(end 329.78725 -142.538196)
		(width 0.1143)
		(layer "In9.Cu")
		(net "CLK_100M_AIRMAX8_PE1_DN")
	)
	(segment
		(start 185.739278 -154.26563)
		(end 184.794652 -153.321004)
		(width 0.1143)
		(layer "In9.Cu")
		(net "CLK_100M_AIRMAX8_PE1_DN")
	)
	(segment
		(start 335.101692 -138.811)
		(end 330.536804 -138.811)
		(width 0.1143)
		(layer "In9.Cu")
		(net "CLK_100M_AIRMAX8_PE1_DN")
	)
	(segment
		(start 158.831534 -152.489662)
		(end 29.35097 -152.489662)
		(width 0.1143)
		(layer "In9.Cu")
		(net "CLK_100M_AIRMAX8_PE1_DN")
	)
	(segment
		(start 375.442226 -118.461028)
		(end 375.442226 -118.483126)
		(width 0.0889)
		(layer "In9.Cu")
		(net "CLK_100M_AIRMAX8_PE1_DN")
	)
	(segment
		(start 24.791924 -137.854182)
		(end 23.676864 -137.854182)
		(width 0.1143)
		(layer "In9.Cu")
		(net "CLK_100M_AIRMAX8_PE1_DN")
	)
	(segment
		(start 347.576394 -138.431778)
		(end 344.1065 -138.431778)
		(width 0.1143)
		(layer "In9.Cu")
		(net "CLK_100M_AIRMAX8_PE1_DN")
	)
	(segment
		(start 159.514286 -151.80691)
		(end 158.831534 -152.489662)
		(width 0.1143)
		(layer "In9.Cu")
		(net "CLK_100M_AIRMAX8_PE1_DN")
	)
	(segment
		(start 377.3805 -113.820194)
		(end 377.3805 -115.576096)
		(width 0.0889)
		(layer "In9.Cu")
		(net "CLK_100M_AIRMAX8_PE1_DN")
	)
	(segment
		(start 343.058496 -137.383774)
		(end 339.9917 -137.383774)
		(width 0.1143)
		(layer "In9.Cu")
		(net "CLK_100M_AIRMAX8_PE1_DN")
	)
	(segment
		(start 25.9461 -139.008358)
		(end 24.791924 -137.854182)
		(width 0.1143)
		(layer "In9.Cu")
		(net "CLK_100M_AIRMAX8_PE1_DN")
	)
	(segment
		(start 375.442226 -118.483126)
		(end 375.442226 -119.018304)
		(width 0.1143)
		(layer "In9.Cu")
		(net "CLK_100M_AIRMAX8_PE1_DN")
	)
	(segment
		(start 9.355328 -109.405674)
		(end 9.355328 -109.001814)
		(width 0.1143)
		(layer "In9.Cu")
		(net "CLK_100M_AIRMAX8_PE1_DN")
	)
	(segment
		(start 29.35097 -152.489662)
		(end 25.9461 -149.084792)
		(width 0.1143)
		(layer "In9.Cu")
		(net "CLK_100M_AIRMAX8_PE1_DN")
	)
	(segment
		(start 17.1069 -124.777246)
		(end 19.258026 -122.62612)
		(width 0.1143)
		(layer "In9.Cu")
		(net "CLK_100M_AIRMAX8_PE1_DN")
	)
	(segment
		(start 9.5377 -108.819442)
		(end 9.5377 -108.0516)
		(width 0.1143)
		(layer "In9.Cu")
		(net "CLK_100M_AIRMAX8_PE1_DN")
	)
	(segment
		(start 371.08511 -125.735588)
		(end 371.08511 -127.161036)
		(width 0.1143)
		(layer "In9.Cu")
		(net "CLK_100M_AIRMAX8_PE1_DN")
	)
	(segment
		(start 375.391426 -118.410228)
		(end 375.442226 -118.461028)
		(width 0.0889)
		(layer "In9.Cu")
		(net "CLK_100M_AIRMAX8_PE1_DN")
	)
	(segment
		(start 371.86743 -122.5931)
		(end 371.86743 -124.953268)
		(width 0.1143)
		(layer "In9.Cu")
		(net "CLK_100M_AIRMAX8_PE1_DN")
	)
	(segment
		(start 378.126752 -112.313974)
		(end 377.979432 -112.39881)
		(width 0.0889)
		(layer "In9.Cu")
		(net "CLK_100M_AIRMAX8_PE1_DN")
	)
	(segment
		(start 23.676864 -137.854182)
		(end 19.208496 -133.385814)
		(width 0.1143)
		(layer "In9.Cu")
		(net "CLK_100M_AIRMAX8_PE1_DN")
	)
	(segment
		(start 361.297474 -134.839964)
		(end 361.297474 -135.332724)
		(width 0.1143)
		(layer "In9.Cu")
		(net "CLK_100M_AIRMAX8_PE1_DN")
	)
	(segment
		(start 351.279206 -139.113006)
		(end 351.021904 -138.855704)
		(width 0.1143)
		(layer "In9.Cu")
		(net "CLK_100M_AIRMAX8_PE1_DN")
	)
	(segment
		(start 376.49531 -116.025676)
		(end 375.391426 -117.12956)
		(width 0.0889)
		(layer "In9.Cu")
		(net "CLK_100M_AIRMAX8_PE1_DN")
	)
	(segment
		(start 359.114598 -137.5156)
		(end 355.219 -137.5156)
		(width 0.1143)
		(layer "In9.Cu")
		(net "CLK_100M_AIRMAX8_PE1_DN")
	)
	(segment
		(start 376.93092 -116.025676)
		(end 376.49531 -116.025676)
		(width 0.0889)
		(layer "In9.Cu")
		(net "CLK_100M_AIRMAX8_PE1_DN")
	)
	(segment
		(start 329.941682 -152.8572)
		(end 188.082936 -152.8572)
		(width 0.1143)
		(layer "In9.Cu")
		(net "CLK_100M_AIRMAX8_PE1_DN")
	)
	(segment
		(start 330.536804 -138.811)
		(end 329.78725 -139.560554)
		(width 0.1143)
		(layer "In9.Cu")
		(net "CLK_100M_AIRMAX8_PE1_DN")
	)
	(segment
		(start 377.891802 -113.308892)
		(end 377.3805 -113.820194)
		(width 0.0889)
		(layer "In9.Cu")
		(net "CLK_100M_AIRMAX8_PE1_DN")
	)
	(segment
		(start 330.214478 -142.965424)
		(end 330.214478 -147.491196)
		(width 0.1143)
		(layer "In9.Cu")
		(net "CLK_100M_AIRMAX8_PE1_DN")
	)
	(segment
		(start 355.219 -137.5156)
		(end 353.621594 -139.113006)
		(width 0.1143)
		(layer "In9.Cu")
		(net "CLK_100M_AIRMAX8_PE1_DN")
	)
	(segment
		(start 183.64708 -153.321004)
		(end 182.70347 -152.377394)
		(width 0.1143)
		(layer "In9.Cu")
		(net "CLK_100M_AIRMAX8_PE1_DN")
	)
	(segment
		(start 330.446126 -147.722844)
		(end 330.446126 -152.352756)
		(width 0.1143)
		(layer "In9.Cu")
		(net "CLK_100M_AIRMAX8_PE1_DN")
	)
	(segment
		(start 19.208496 -133.385814)
		(end 19.208496 -130.721354)
		(width 0.1143)
		(layer "In9.Cu")
		(net "CLK_100M_AIRMAX8_PE1_DN")
	)
	(segment
		(start 362.3183 -133.819138)
		(end 361.297474 -134.839964)
		(width 0.1143)
		(layer "In9.Cu")
		(net "CLK_100M_AIRMAX8_PE1_DN")
	)
	(segment
		(start 361.297474 -135.332724)
		(end 359.114598 -137.5156)
		(width 0.1143)
		(layer "In9.Cu")
		(net "CLK_100M_AIRMAX8_PE1_DN")
	)
	(segment
		(start 167.602154 -148.6281)
		(end 164.423344 -151.80691)
		(width 0.1143)
		(layer "In9.Cu")
		(net "CLK_100M_AIRMAX8_PE1_DN")
	)
	(segment
		(start 375.391426 -117.12956)
		(end 375.391426 -118.410228)
		(width 0.0889)
		(layer "In9.Cu")
		(net "CLK_100M_AIRMAX8_PE1_DN")
	)
	(segment
		(start 377.891802 -112.654334)
		(end 377.891802 -113.308892)
		(width 0.0889)
		(layer "In9.Cu")
		(net "CLK_100M_AIRMAX8_PE1_DN")
	)
	(segment
		(start 186.674506 -154.26563)
		(end 185.739278 -154.26563)
		(width 0.1143)
		(layer "In9.Cu")
		(net "CLK_100M_AIRMAX8_PE1_DN")
	)
	(segment
		(start 17.1069 -128.619758)
		(end 17.1069 -124.777246)
		(width 0.1143)
		(layer "In9.Cu")
		(net "CLK_100M_AIRMAX8_PE1_DN")
	)
	(segment
		(start 339.9917 -137.383774)
		(end 339.519768 -136.911842)
		(width 0.1143)
		(layer "In9.Cu")
		(net "CLK_100M_AIRMAX8_PE1_DN")
	)
	(segment
		(start 177.455068 -148.6281)
		(end 167.602154 -148.6281)
		(width 0.1143)
		(layer "In9.Cu")
		(net "CLK_100M_AIRMAX8_PE1_DN")
	)
	(segment
		(start 337.00085 -136.911842)
		(end 335.101692 -138.811)
		(width 0.1143)
		(layer "In9.Cu")
		(net "CLK_100M_AIRMAX8_PE1_DN")
	)
	(segment
		(start 19.258026 -119.308372)
		(end 9.355328 -109.405674)
		(width 0.1143)
		(layer "In9.Cu")
		(net "CLK_100M_AIRMAX8_PE1_DN")
	)
	(segment
		(start 19.258026 -122.62612)
		(end 19.258026 -119.308372)
		(width 0.1143)
		(layer "In9.Cu")
		(net "CLK_100M_AIRMAX8_PE1_DN")
	)
	(segment
		(start 330.214478 -147.491196)
		(end 330.446126 -147.722844)
		(width 0.1143)
		(layer "In9.Cu")
		(net "CLK_100M_AIRMAX8_PE1_DN")
	)
	(segment
		(start 339.519768 -136.911842)
		(end 337.00085 -136.911842)
		(width 0.1143)
		(layer "In9.Cu")
		(net "CLK_100M_AIRMAX8_PE1_DN")
	)
	(segment
		(start 184.794652 -153.321004)
		(end 183.64708 -153.321004)
		(width 0.1143)
		(layer "In9.Cu")
		(net "CLK_100M_AIRMAX8_PE1_DN")
	)
	(arc
		(start 378.914152 -111.008668)
		(mid 378.821444 -111.266938)
		(end 378.622052 -111.455454)
		(width 0.0889)
		(layer "In9.Cu")
		(net "CLK_100M_AIRMAX8_PE1_DN")
	)
	(arc
		(start 377.979432 -112.39881)
		(mid 377.915271 -112.519595)
		(end 377.891802 -112.654334)
		(width 0.0889)
		(layer "In9.Cu")
		(net "CLK_100M_AIRMAX8_PE1_DN")
	)
	(arc
		(start 378.4219 -111.823754)
		(mid 378.337619 -112.106971)
		(end 378.126752 -112.313974)
		(width 0.0889)
		(layer "In9.Cu")
		(net "CLK_100M_AIRMAX8_PE1_DN")
	)
	(arc
		(start 378.622052 -111.455454)
		(mid 378.478248 -111.597137)
		(end 378.4219 -111.790988)
		(width 0.0889)
		(layer "In9.Cu")
		(net "CLK_100M_AIRMAX8_PE1_DN")
	)
	(segment
		(start 466.446108 -148.0185)
		(end 466.09 -148.0185)
		(width 0.10795)
		(layer "F.Cu")
		(net "XDP_SYSPWROK")
	)
	(segment
		(start 465.702142 -148.0185)
		(end 465.120736 -147.437094)
		(width 0.10795)
		(layer "F.Cu")
		(net "XDP_SYSPWROK")
	)
	(segment
		(start 465.120736 -147.437094)
		(end 464.462368 -147.437094)
		(width 0.10795)
		(layer "F.Cu")
		(net "XDP_SYSPWROK")
	)
	(segment
		(start 466.599524 -148.171916)
		(end 466.446108 -148.0185)
		(width 0.10795)
		(layer "F.Cu")
		(net "XDP_SYSPWROK")
	)
	(segment
		(start 370.345208 -78.294738)
		(end 370.745004 -77.894942)
		(width 0.10795)
		(layer "F.Cu")
		(net "XDP_SYSPWROK")
	)
	(segment
		(start 394.462 -41.783)
		(end 394.462 -41.3766)
		(width 0.10795)
		(layer "F.Cu")
		(net "XDP_SYSPWROK")
	)
	(segment
		(start 464.245198 -147.219924)
		(end 462.980278 -147.219924)
		(width 0.10795)
		(layer "F.Cu")
		(net "XDP_SYSPWROK")
	)
	(segment
		(start 394.589 -42.0116)
		(end 394.589 -41.91)
		(width 0.10795)
		(layer "F.Cu")
		(net "XDP_SYSPWROK")
	)
	(segment
		(start 464.462368 -147.437094)
		(end 464.245198 -147.219924)
		(width 0.10795)
		(layer "F.Cu")
		(net "XDP_SYSPWROK")
	)
	(segment
		(start 394.589 -41.91)
		(end 394.462 -41.783)
		(width 0.10795)
		(layer "F.Cu")
		(net "XDP_SYSPWROK")
	)
	(segment
		(start 466.09 -148.0185)
		(end 465.702142 -148.0185)
		(width 0.10795)
		(layer "F.Cu")
		(net "XDP_SYSPWROK")
	)
	(segment
		(start 467.138004 -148.171916)
		(end 466.599524 -148.171916)
		(width 0.10795)
		(layer "F.Cu")
		(net "XDP_SYSPWROK")
	)
	(via
		(at 394.589 -42.0116)
		(size 0.508)
		(drill 0.254)
		(layers "F.Cu" "B.Cu")
		(net "XDP_SYSPWROK")
	)
	(via
		(at 387.521958 -79.20609)
		(size 0.508)
		(drill 0.254)
		(layers "F.Cu" "B.Cu")
		(net "XDP_SYSPWROK")
	)
	(via
		(at 383.702052 -42.22496)
		(size 0.508)
		(drill 0.254)
		(layers "F.Cu" "B.Cu")
		(net "XDP_SYSPWROK")
	)
	(via
		(at 467.138004 -148.171916)
		(size 0.508)
		(drill 0.254)
		(layers "F.Cu" "B.Cu")
		(net "XDP_SYSPWROK")
	)
	(via
		(at 426.847 -120.22455)
		(size 0.508)
		(drill 0.254)
		(layers "F.Cu" "B.Cu")
		(net "XDP_SYSPWROK")
	)
	(via
		(at 370.345208 -78.294738)
		(size 0.4572)
		(drill 0.2032)
		(layers "F.Cu" "B.Cu")
		(net "XDP_SYSPWROK")
	)
	(segment
		(start 424.59275 -112.604296)
		(end 424.59275 -110.928658)
		(width 0.10795)
		(layer "B.Cu")
		(net "XDP_SYSPWROK")
	)
	(segment
		(start 397.053816 -72.38746)
		(end 397.053816 -73.436226)
		(width 0.10795)
		(layer "B.Cu")
		(net "XDP_SYSPWROK")
	)
	(segment
		(start 426.438314 -116.54282)
		(end 426.438314 -113.663984)
		(width 0.10795)
		(layer "B.Cu")
		(net "XDP_SYSPWROK")
	)
	(segment
		(start 426.438314 -113.663984)
		(end 425.641516 -112.867186)
		(width 0.10795)
		(layer "B.Cu")
		(net "XDP_SYSPWROK")
	)
	(segment
		(start 415.455354 -66.699384)
		(end 415.07918 -67.075558)
		(width 0.10795)
		(layer "B.Cu")
		(net "XDP_SYSPWROK")
	)
	(segment
		(start 398.950688 -71.308468)
		(end 398.132808 -71.308468)
		(width 0.10795)
		(layer "B.Cu")
		(net "XDP_SYSPWROK")
	)
	(segment
		(start 391.668 -41.656)
		(end 392.303 -42.291)
		(width 0.10795)
		(layer "B.Cu")
		(net "XDP_SYSPWROK")
	)
	(segment
		(start 423.690288 -100.679758)
		(end 423.683684 -100.673154)
		(width 0.10795)
		(layer "B.Cu")
		(net "XDP_SYSPWROK")
	)
	(segment
		(start 421.33647 -64.827658)
		(end 418.280342 -64.827658)
		(width 0.10795)
		(layer "B.Cu")
		(net "XDP_SYSPWROK")
	)
	(segment
		(start 388.626096 -77.323696)
		(end 388.626096 -78.30693)
		(width 0.10795)
		(layer "B.Cu")
		(net "XDP_SYSPWROK")
	)
	(segment
		(start 384.683 -41.148)
		(end 386.969 -41.148)
		(width 0.10795)
		(layer "B.Cu")
		(net "XDP_SYSPWROK")
	)
	(segment
		(start 386.969 -41.148)
		(end 387.500876 -41.679876)
		(width 0.10795)
		(layer "B.Cu")
		(net "XDP_SYSPWROK")
	)
	(segment
		(start 390.543796 -76.191618)
		(end 390.191244 -76.54417)
		(width 0.10795)
		(layer "B.Cu")
		(net "XDP_SYSPWROK")
	)
	(segment
		(start 389.358124 -41.679876)
		(end 390.144 -40.894)
		(width 0.10795)
		(layer "B.Cu")
		(net "XDP_SYSPWROK")
	)
	(segment
		(start 388.626096 -78.30693)
		(end 388.166864 -78.766162)
		(width 0.10795)
		(layer "B.Cu")
		(net "XDP_SYSPWROK")
	)
	(segment
		(start 391.541 -41.656)
		(end 391.668 -41.656)
		(width 0.10795)
		(layer "B.Cu")
		(net "XDP_SYSPWROK")
	)
	(segment
		(start 389.742172 -76.687172)
		(end 389.741918 -76.686918)
		(width 0.10795)
		(layer "B.Cu")
		(net "XDP_SYSPWROK")
	)
	(segment
		(start 389.741918 -76.686918)
		(end 389.262874 -76.686918)
		(width 0.10795)
		(layer "B.Cu")
		(net "XDP_SYSPWROK")
	)
	(segment
		(start 415.07918 -67.075558)
		(end 415.07918 -67.852798)
		(width 0.10795)
		(layer "B.Cu")
		(net "XDP_SYSPWROK")
	)
	(segment
		(start 465.795614 -147.955254)
		(end 465.595208 -147.955254)
		(width 0.10795)
		(layer "B.Cu")
		(net "XDP_SYSPWROK")
	)
	(segment
		(start 412.266892 -68.62699)
		(end 412.030418 -68.62699)
		(width 0.10795)
		(layer "B.Cu")
		(net "XDP_SYSPWROK")
	)
	(segment
		(start 423.690288 -103.811324)
		(end 423.690288 -100.679758)
		(width 0.10795)
		(layer "B.Cu")
		(net "XDP_SYSPWROK")
	)
	(segment
		(start 415.07918 -67.852798)
		(end 414.325308 -68.60667)
		(width 0.10795)
		(layer "B.Cu")
		(net "XDP_SYSPWROK")
	)
	(segment
		(start 412.030418 -68.62699)
		(end 411.716474 -68.918836)
		(width 0.10795)
		(layer "B.Cu")
		(net "XDP_SYSPWROK")
	)
	(segment
		(start 412.287212 -68.60667)
		(end 412.266892 -68.62699)
		(width 0.10795)
		(layer "B.Cu")
		(net "XDP_SYSPWROK")
	)
	(segment
		(start 426.992796 -117.097302)
		(end 426.438314 -116.54282)
		(width 0.10795)
		(layer "B.Cu")
		(net "XDP_SYSPWROK")
	)
	(segment
		(start 423.2275 -73.822052)
		(end 423.2275 -72.513444)
		(width 0.10795)
		(layer "B.Cu")
		(net "XDP_SYSPWROK")
	)
	(segment
		(start 387.961886 -78.766162)
		(end 387.521958 -79.20609)
		(width 0.10795)
		(layer "B.Cu")
		(net "XDP_SYSPWROK")
	)
	(segment
		(start 423.683684 -91.211146)
		(end 423.199814 -90.727276)
		(width 0.10795)
		(layer "B.Cu")
		(net "XDP_SYSPWROK")
	)
	(segment
		(start 424.85564 -112.867186)
		(end 424.59275 -112.604296)
		(width 0.10795)
		(layer "B.Cu")
		(net "XDP_SYSPWROK")
	)
	(segment
		(start 390.041892 -76.687172)
		(end 389.742172 -76.687172)
		(width 0.10795)
		(layer "B.Cu")
		(net "XDP_SYSPWROK")
	)
	(segment
		(start 466.012276 -148.171916)
		(end 465.795614 -147.955254)
		(width 0.10795)
		(layer "B.Cu")
		(net "XDP_SYSPWROK")
	)
	(segment
		(start 418.280342 -64.827658)
		(end 416.408616 -66.699384)
		(width 0.10795)
		(layer "B.Cu")
		(net "XDP_SYSPWROK")
	)
	(segment
		(start 395.596618 -74.893424)
		(end 395.596618 -74.926952)
		(width 0.10795)
		(layer "B.Cu")
		(net "XDP_SYSPWROK")
	)
	(segment
		(start 416.408616 -66.699384)
		(end 415.455354 -66.699384)
		(width 0.10795)
		(layer "B.Cu")
		(net "XDP_SYSPWROK")
	)
	(segment
		(start 388.166864 -78.766162)
		(end 387.961886 -78.766162)
		(width 0.10795)
		(layer "B.Cu")
		(net "XDP_SYSPWROK")
	)
	(segment
		(start 421.825928 -65.317116)
		(end 421.33647 -64.827658)
		(width 0.10795)
		(layer "B.Cu")
		(net "XDP_SYSPWROK")
	)
	(segment
		(start 423.199814 -87.061802)
		(end 423.3926 -86.869016)
		(width 0.10795)
		(layer "B.Cu")
		(net "XDP_SYSPWROK")
	)
	(segment
		(start 423.3926 -73.987152)
		(end 423.2275 -73.822052)
		(width 0.10795)
		(layer "B.Cu")
		(net "XDP_SYSPWROK")
	)
	(segment
		(start 467.138004 -148.171916)
		(end 466.012276 -148.171916)
		(width 0.10795)
		(layer "B.Cu")
		(net "XDP_SYSPWROK")
	)
	(segment
		(start 414.325308 -68.60667)
		(end 412.287212 -68.60667)
		(width 0.10795)
		(layer "B.Cu")
		(net "XDP_SYSPWROK")
	)
	(segment
		(start 409.485592 -69.906388)
		(end 400.352768 -69.906388)
		(width 0.10795)
		(layer "B.Cu")
		(net "XDP_SYSPWROK")
	)
	(segment
		(start 426.992796 -120.078754)
		(end 426.992796 -117.097302)
		(width 0.10795)
		(layer "B.Cu")
		(net "XDP_SYSPWROK")
	)
	(segment
		(start 400.352768 -69.906388)
		(end 398.950688 -71.308468)
		(width 0.10795)
		(layer "B.Cu")
		(net "XDP_SYSPWROK")
	)
	(segment
		(start 423.221912 -104.2797)
		(end 423.690288 -103.811324)
		(width 0.10795)
		(layer "B.Cu")
		(net "XDP_SYSPWROK")
	)
	(segment
		(start 423.683684 -100.673154)
		(end 423.683684 -91.211146)
		(width 0.10795)
		(layer "B.Cu")
		(net "XDP_SYSPWROK")
	)
	(segment
		(start 424.10126 -107.351068)
		(end 423.221912 -106.47172)
		(width 0.10795)
		(layer "B.Cu")
		(net "XDP_SYSPWROK")
	)
	(segment
		(start 394.331952 -76.191618)
		(end 390.543796 -76.191618)
		(width 0.10795)
		(layer "B.Cu")
		(net "XDP_SYSPWROK")
	)
	(segment
		(start 390.144 -40.894)
		(end 390.779 -40.894)
		(width 0.10795)
		(layer "B.Cu")
		(net "XDP_SYSPWROK")
	)
	(segment
		(start 424.59275 -110.928658)
		(end 424.10126 -110.437168)
		(width 0.10795)
		(layer "B.Cu")
		(net "XDP_SYSPWROK")
	)
	(segment
		(start 398.132808 -71.308468)
		(end 397.053816 -72.38746)
		(width 0.10795)
		(layer "B.Cu")
		(net "XDP_SYSPWROK")
	)
	(segment
		(start 390.184894 -76.54417)
		(end 390.041892 -76.687172)
		(width 0.10795)
		(layer "B.Cu")
		(net "XDP_SYSPWROK")
	)
	(segment
		(start 411.71622 -68.91909)
		(end 410.47289 -68.91909)
		(width 0.10795)
		(layer "B.Cu")
		(net "XDP_SYSPWROK")
	)
	(segment
		(start 390.191244 -76.54417)
		(end 390.184894 -76.54417)
		(width 0.10795)
		(layer "B.Cu")
		(net "XDP_SYSPWROK")
	)
	(segment
		(start 390.779 -40.894)
		(end 391.541 -41.656)
		(width 0.10795)
		(layer "B.Cu")
		(net "XDP_SYSPWROK")
	)
	(segment
		(start 423.199814 -90.727276)
		(end 423.199814 -87.061802)
		(width 0.10795)
		(layer "B.Cu")
		(net "XDP_SYSPWROK")
	)
	(segment
		(start 426.847 -120.22455)
		(end 426.992796 -120.078754)
		(width 0.10795)
		(layer "B.Cu")
		(net "XDP_SYSPWROK")
	)
	(segment
		(start 383.702052 -42.128948)
		(end 384.683 -41.148)
		(width 0.10795)
		(layer "B.Cu")
		(net "XDP_SYSPWROK")
	)
	(segment
		(start 423.3926 -86.869016)
		(end 423.3926 -73.987152)
		(width 0.10795)
		(layer "B.Cu")
		(net "XDP_SYSPWROK")
	)
	(segment
		(start 389.262874 -76.686918)
		(end 388.626096 -77.323696)
		(width 0.10795)
		(layer "B.Cu")
		(net "XDP_SYSPWROK")
	)
	(segment
		(start 383.702052 -42.22496)
		(end 383.702052 -42.128948)
		(width 0.10795)
		(layer "B.Cu")
		(net "XDP_SYSPWROK")
	)
	(segment
		(start 424.10126 -110.437168)
		(end 424.10126 -107.351068)
		(width 0.10795)
		(layer "B.Cu")
		(net "XDP_SYSPWROK")
	)
	(segment
		(start 397.053816 -73.436226)
		(end 395.596618 -74.893424)
		(width 0.10795)
		(layer "B.Cu")
		(net "XDP_SYSPWROK")
	)
	(segment
		(start 423.221912 -106.47172)
		(end 423.221912 -104.2797)
		(width 0.10795)
		(layer "B.Cu")
		(net "XDP_SYSPWROK")
	)
	(segment
		(start 392.303 -42.291)
		(end 394.3096 -42.291)
		(width 0.10795)
		(layer "B.Cu")
		(net "XDP_SYSPWROK")
	)
	(segment
		(start 410.47289 -68.91909)
		(end 409.485592 -69.906388)
		(width 0.10795)
		(layer "B.Cu")
		(net "XDP_SYSPWROK")
	)
	(segment
		(start 394.3096 -42.291)
		(end 394.589 -42.0116)
		(width 0.10795)
		(layer "B.Cu")
		(net "XDP_SYSPWROK")
	)
	(segment
		(start 395.596618 -74.926952)
		(end 394.331952 -76.191618)
		(width 0.10795)
		(layer "B.Cu")
		(net "XDP_SYSPWROK")
	)
	(segment
		(start 423.2275 -72.513444)
		(end 421.825928 -71.111872)
		(width 0.10795)
		(layer "B.Cu")
		(net "XDP_SYSPWROK")
	)
	(segment
		(start 425.641516 -112.867186)
		(end 424.85564 -112.867186)
		(width 0.10795)
		(layer "B.Cu")
		(net "XDP_SYSPWROK")
	)
	(segment
		(start 387.500876 -41.679876)
		(end 389.358124 -41.679876)
		(width 0.10795)
		(layer "B.Cu")
		(net "XDP_SYSPWROK")
	)
	(segment
		(start 411.716474 -68.918836)
		(end 411.71622 -68.91909)
		(width 0.10795)
		(layer "B.Cu")
		(net "XDP_SYSPWROK")
	)
	(segment
		(start 421.825928 -71.111872)
		(end 421.825928 -65.317116)
		(width 0.10795)
		(layer "B.Cu")
		(net "XDP_SYSPWROK")
	)
	(segment
		(start 371.5766 -76.53528)
		(end 371.5766 -76.4794)
		(width 0.089408)
		(layer "In2.Cu")
		(net "XDP_SYSPWROK")
	)
	(segment
		(start 383.702052 -44.607988)
		(end 383.702052 -42.22496)
		(width 0.089408)
		(layer "In2.Cu")
		(net "XDP_SYSPWROK")
	)
	(segment
		(start 376.318272 -70.449948)
		(end 376.318272 -70.010528)
		(width 0.089408)
		(layer "In2.Cu")
		(net "XDP_SYSPWROK")
	)
	(segment
		(start 382.647952 -65.681352)
		(end 382.0922 -65.1256)
		(width 0.089408)
		(layer "In2.Cu")
		(net "XDP_SYSPWROK")
	)
	(segment
		(start 371.310662 -78.294738)
		(end 371.5766 -78.0288)
		(width 0.089408)
		(layer "In2.Cu")
		(net "XDP_SYSPWROK")
	)
	(segment
		(start 370.345208 -78.294738)
		(end 371.310662 -78.294738)
		(width 0.089408)
		(layer "In2.Cu")
		(net "XDP_SYSPWROK")
	)
	(segment
		(start 371.571774 -77.649578)
		(end 371.571774 -77.340206)
		(width 0.089408)
		(layer "In2.Cu")
		(net "XDP_SYSPWROK")
	)
	(segment
		(start 371.571774 -76.849478)
		(end 371.571774 -76.540106)
		(width 0.089408)
		(layer "In2.Cu")
		(net "XDP_SYSPWROK")
	)
	(segment
		(start 371.571774 -76.540106)
		(end 371.5766 -76.53528)
		(width 0.089408)
		(layer "In2.Cu")
		(net "XDP_SYSPWROK")
	)
	(segment
		(start 379.6284 -67.818)
		(end 379.632464 -67.818)
		(width 0.089408)
		(layer "In2.Cu")
		(net "XDP_SYSPWROK")
	)
	(segment
		(start 376.2248 -70.612)
		(end 376.2248 -70.54342)
		(width 0.089408)
		(layer "In2.Cu")
		(net "XDP_SYSPWROK")
	)
	(segment
		(start 381.842518 -56.589676)
		(end 381.682752 -56.42991)
		(width 0.089408)
		(layer "In2.Cu")
		(net "XDP_SYSPWROK")
	)
	(segment
		(start 371.7544 -76.3016)
		(end 372.2624 -76.3016)
		(width 0.089408)
		(layer "In2.Cu")
		(net "XDP_SYSPWROK")
	)
	(segment
		(start 377.682252 -69.921882)
		(end 379.543818 -68.060316)
		(width 0.089408)
		(layer "In2.Cu")
		(net "XDP_SYSPWROK")
	)
	(segment
		(start 376.318272 -70.010528)
		(end 376.406918 -69.921882)
		(width 0.089408)
		(layer "In2.Cu")
		(net "XDP_SYSPWROK")
	)
	(segment
		(start 375.5898 -73.8124)
		(end 375.5898 -72.868282)
		(width 0.089408)
		(layer "In2.Cu")
		(net "XDP_SYSPWROK")
	)
	(segment
		(start 379.543818 -68.060316)
		(end 379.543818 -67.902582)
		(width 0.089408)
		(layer "In2.Cu")
		(net "XDP_SYSPWROK")
	)
	(segment
		(start 375.0818 -74.3204)
		(end 375.5898 -73.8124)
		(width 0.089408)
		(layer "In2.Cu")
		(net "XDP_SYSPWROK")
	)
	(segment
		(start 381.682752 -51.472084)
		(end 381.871982 -51.282854)
		(width 0.089408)
		(layer "In2.Cu")
		(net "XDP_SYSPWROK")
	)
	(segment
		(start 372.2624 -76.3016)
		(end 372.4656 -76.0984)
		(width 0.089408)
		(layer "In2.Cu")
		(net "XDP_SYSPWROK")
	)
	(segment
		(start 371.571774 -77.340206)
		(end 371.5766 -77.33538)
		(width 0.089408)
		(layer "In2.Cu")
		(net "XDP_SYSPWROK")
	)
	(segment
		(start 379.543818 -67.902582)
		(end 379.6284 -67.818)
		(width 0.089408)
		(layer "In2.Cu")
		(net "XDP_SYSPWROK")
	)
	(segment
		(start 382.0922 -65.1256)
		(end 382.0922 -63.754)
		(width 0.089408)
		(layer "In2.Cu")
		(net "XDP_SYSPWROK")
	)
	(segment
		(start 381.254 -60.071)
		(end 381.842518 -59.482482)
		(width 0.089408)
		(layer "In2.Cu")
		(net "XDP_SYSPWROK")
	)
	(segment
		(start 381.240792 -67.4116)
		(end 382.647952 -66.00444)
		(width 0.089408)
		(layer "In2.Cu")
		(net "XDP_SYSPWROK")
	)
	(segment
		(start 375.8946 -70.9422)
		(end 376.2248 -70.612)
		(width 0.089408)
		(layer "In2.Cu")
		(net "XDP_SYSPWROK")
	)
	(segment
		(start 379.632464 -67.818)
		(end 380.038864 -67.4116)
		(width 0.089408)
		(layer "In2.Cu")
		(net "XDP_SYSPWROK")
	)
	(segment
		(start 381.871982 -46.438058)
		(end 383.702052 -44.607988)
		(width 0.089408)
		(layer "In2.Cu")
		(net "XDP_SYSPWROK")
	)
	(segment
		(start 382.0922 -63.754)
		(end 381.254 -62.9158)
		(width 0.089408)
		(layer "In2.Cu")
		(net "XDP_SYSPWROK")
	)
	(segment
		(start 372.4656 -74.9046)
		(end 373.0498 -74.3204)
		(width 0.089408)
		(layer "In2.Cu")
		(net "XDP_SYSPWROK")
	)
	(segment
		(start 375.571512 -72.849994)
		(end 375.571512 -71.112888)
		(width 0.089408)
		(layer "In2.Cu")
		(net "XDP_SYSPWROK")
	)
	(segment
		(start 371.5766 -76.854304)
		(end 371.571774 -76.849478)
		(width 0.089408)
		(layer "In2.Cu")
		(net "XDP_SYSPWROK")
	)
	(segment
		(start 380.038864 -67.4116)
		(end 381.240792 -67.4116)
		(width 0.089408)
		(layer "In2.Cu")
		(net "XDP_SYSPWROK")
	)
	(segment
		(start 373.0498 -74.3204)
		(end 375.0818 -74.3204)
		(width 0.089408)
		(layer "In2.Cu")
		(net "XDP_SYSPWROK")
	)
	(segment
		(start 371.5766 -76.4794)
		(end 371.7544 -76.3016)
		(width 0.089408)
		(layer "In2.Cu")
		(net "XDP_SYSPWROK")
	)
	(segment
		(start 381.842518 -59.482482)
		(end 381.842518 -56.589676)
		(width 0.089408)
		(layer "In2.Cu")
		(net "XDP_SYSPWROK")
	)
	(segment
		(start 371.5766 -77.33538)
		(end 371.5766 -76.854304)
		(width 0.089408)
		(layer "In2.Cu")
		(net "XDP_SYSPWROK")
	)
	(segment
		(start 376.2248 -70.54342)
		(end 376.318272 -70.449948)
		(width 0.089408)
		(layer "In2.Cu")
		(net "XDP_SYSPWROK")
	)
	(segment
		(start 371.5766 -77.654404)
		(end 371.571774 -77.649578)
		(width 0.089408)
		(layer "In2.Cu")
		(net "XDP_SYSPWROK")
	)
	(segment
		(start 375.571512 -71.112888)
		(end 375.7422 -70.9422)
		(width 0.089408)
		(layer "In2.Cu")
		(net "XDP_SYSPWROK")
	)
	(segment
		(start 381.254 -62.9158)
		(end 381.254 -60.071)
		(width 0.089408)
		(layer "In2.Cu")
		(net "XDP_SYSPWROK")
	)
	(segment
		(start 375.7422 -70.9422)
		(end 375.8946 -70.9422)
		(width 0.089408)
		(layer "In2.Cu")
		(net "XDP_SYSPWROK")
	)
	(segment
		(start 376.406918 -69.921882)
		(end 377.682252 -69.921882)
		(width 0.089408)
		(layer "In2.Cu")
		(net "XDP_SYSPWROK")
	)
	(segment
		(start 381.871982 -51.282854)
		(end 381.871982 -46.438058)
		(width 0.089408)
		(layer "In2.Cu")
		(net "XDP_SYSPWROK")
	)
	(segment
		(start 381.682752 -56.42991)
		(end 381.682752 -51.472084)
		(width 0.089408)
		(layer "In2.Cu")
		(net "XDP_SYSPWROK")
	)
	(segment
		(start 382.647952 -66.00444)
		(end 382.647952 -65.681352)
		(width 0.089408)
		(layer "In2.Cu")
		(net "XDP_SYSPWROK")
	)
	(segment
		(start 375.5898 -72.868282)
		(end 375.571512 -72.849994)
		(width 0.089408)
		(layer "In2.Cu")
		(net "XDP_SYSPWROK")
	)
	(segment
		(start 371.5766 -78.0288)
		(end 371.5766 -77.654404)
		(width 0.089408)
		(layer "In2.Cu")
		(net "XDP_SYSPWROK")
	)
	(segment
		(start 372.4656 -76.0984)
		(end 372.4656 -74.9046)
		(width 0.089408)
		(layer "In2.Cu")
		(net "XDP_SYSPWROK")
	)
	(segment
		(start 375.776236 -80.570324)
		(end 376.490738 -81.284826)
		(width 0.089408)
		(layer "In4.Cu")
		(net "XDP_SYSPWROK")
	)
	(segment
		(start 383.880106 -79.768954)
		(end 383.880106 -79.169006)
		(width 0.089408)
		(layer "In4.Cu")
		(net "XDP_SYSPWROK")
	)
	(segment
		(start 376.490738 -81.284826)
		(end 380.078234 -81.284826)
		(width 0.089408)
		(layer "In4.Cu")
		(net "XDP_SYSPWROK")
	)
	(segment
		(start 372.67896 -79.300578)
		(end 372.67896 -79.556864)
		(width 0.089408)
		(layer "In4.Cu")
		(net "XDP_SYSPWROK")
	)
	(segment
		(start 375.354088 -80.570324)
		(end 375.776236 -80.570324)
		(width 0.089408)
		(layer "In4.Cu")
		(net "XDP_SYSPWROK")
	)
	(segment
		(start 372.67896 -79.556864)
		(end 373.41937 -80.297274)
		(width 0.089408)
		(layer "In4.Cu")
		(net "XDP_SYSPWROK")
	)
	(segment
		(start 386.866892 -79.20609)
		(end 387.521958 -79.20609)
		(width 0.089408)
		(layer "In4.Cu")
		(net "XDP_SYSPWROK")
	)
	(segment
		(start 383.880106 -79.169006)
		(end 384.811778 -78.237334)
		(width 0.089408)
		(layer "In4.Cu")
		(net "XDP_SYSPWROK")
	)
	(segment
		(start 384.811778 -78.237334)
		(end 385.898136 -78.237334)
		(width 0.089408)
		(layer "In4.Cu")
		(net "XDP_SYSPWROK")
	)
	(segment
		(start 380.078234 -81.284826)
		(end 381.12954 -80.23352)
		(width 0.089408)
		(layer "In4.Cu")
		(net "XDP_SYSPWROK")
	)
	(segment
		(start 381.12954 -80.23352)
		(end 383.41554 -80.23352)
		(width 0.089408)
		(layer "In4.Cu")
		(net "XDP_SYSPWROK")
	)
	(segment
		(start 375.081038 -80.297274)
		(end 375.354088 -80.570324)
		(width 0.089408)
		(layer "In4.Cu")
		(net "XDP_SYSPWROK")
	)
	(segment
		(start 370.345208 -78.294738)
		(end 370.718588 -78.668118)
		(width 0.089408)
		(layer "In4.Cu")
		(net "XDP_SYSPWROK")
	)
	(segment
		(start 372.0465 -78.668118)
		(end 372.67896 -79.300578)
		(width 0.089408)
		(layer "In4.Cu")
		(net "XDP_SYSPWROK")
	)
	(segment
		(start 385.898136 -78.237334)
		(end 386.866892 -79.20609)
		(width 0.089408)
		(layer "In4.Cu")
		(net "XDP_SYSPWROK")
	)
	(segment
		(start 370.718588 -78.668118)
		(end 372.0465 -78.668118)
		(width 0.089408)
		(layer "In4.Cu")
		(net "XDP_SYSPWROK")
	)
	(segment
		(start 373.41937 -80.297274)
		(end 375.081038 -80.297274)
		(width 0.089408)
		(layer "In4.Cu")
		(net "XDP_SYSPWROK")
	)
	(segment
		(start 383.41554 -80.23352)
		(end 383.880106 -79.768954)
		(width 0.089408)
		(layer "In4.Cu")
		(net "XDP_SYSPWROK")
	)
	(segment
		(start 470.92108 -118.49608)
		(end 470.92108 -116.15166)
		(width 0.089408)
		(layer "In11.Cu")
		(net "XDP_SYSPWROK")
	)
	(segment
		(start 469.167718 -141.499082)
		(end 469.167718 -137.114788)
		(width 0.089408)
		(layer "In11.Cu")
		(net "XDP_SYSPWROK")
	)
	(segment
		(start 464.763358 -113.460276)
		(end 464.058 -114.165634)
		(width 0.089408)
		(layer "In11.Cu")
		(net "XDP_SYSPWROK")
	)
	(segment
		(start 473.661232 -129.894584)
		(end 474.560392 -128.995424)
		(width 0.089408)
		(layer "In11.Cu")
		(net "XDP_SYSPWROK")
	)
	(segment
		(start 437.200294 -117.050058)
		(end 434.396896 -119.853456)
		(width 0.089408)
		(layer "In11.Cu")
		(net "XDP_SYSPWROK")
	)
	(segment
		(start 427.218094 -119.853456)
		(end 426.847 -120.22455)
		(width 0.089408)
		(layer "In11.Cu")
		(net "XDP_SYSPWROK")
	)
	(segment
		(start 472.9099 -120.4849)
		(end 470.92108 -118.49608)
		(width 0.089408)
		(layer "In11.Cu")
		(net "XDP_SYSPWROK")
	)
	(segment
		(start 441.178696 -115.187984)
		(end 439.316622 -117.050058)
		(width 0.089408)
		(layer "In11.Cu")
		(net "XDP_SYSPWROK")
	)
	(segment
		(start 434.396896 -119.853456)
		(end 427.218094 -119.853456)
		(width 0.089408)
		(layer "In11.Cu")
		(net "XDP_SYSPWROK")
	)
	(segment
		(start 469.499188 -114.310668)
		(end 469.080088 -114.310668)
		(width 0.089408)
		(layer "In11.Cu")
		(net "XDP_SYSPWROK")
	)
	(segment
		(start 472.9099 -121.3231)
		(end 472.9099 -120.4849)
		(width 0.089408)
		(layer "In11.Cu")
		(net "XDP_SYSPWROK")
	)
	(segment
		(start 470.604088 -115.415568)
		(end 469.499188 -114.310668)
		(width 0.089408)
		(layer "In11.Cu")
		(net "XDP_SYSPWROK")
	)
	(segment
		(start 474.560392 -128.995424)
		(end 474.560392 -125.234192)
		(width 0.089408)
		(layer "In11.Cu")
		(net "XDP_SYSPWROK")
	)
	(segment
		(start 469.167718 -137.114788)
		(end 469.766396 -136.51611)
		(width 0.089408)
		(layer "In11.Cu")
		(net "XDP_SYSPWROK")
	)
	(segment
		(start 467.138004 -148.171916)
		(end 467.727284 -148.171916)
		(width 0.089408)
		(layer "In11.Cu")
		(net "XDP_SYSPWROK")
	)
	(segment
		(start 467.727284 -148.171916)
		(end 468.659972 -147.239228)
		(width 0.089408)
		(layer "In11.Cu")
		(net "XDP_SYSPWROK")
	)
	(segment
		(start 472.6432 -123.317)
		(end 472.6432 -121.5898)
		(width 0.089408)
		(layer "In11.Cu")
		(net "XDP_SYSPWROK")
	)
	(segment
		(start 468.659972 -142.006828)
		(end 469.167718 -141.499082)
		(width 0.089408)
		(layer "In11.Cu")
		(net "XDP_SYSPWROK")
	)
	(segment
		(start 469.766396 -136.51611)
		(end 469.766396 -132.642864)
		(width 0.089408)
		(layer "In11.Cu")
		(net "XDP_SYSPWROK")
	)
	(segment
		(start 439.316622 -117.050058)
		(end 437.200294 -117.050058)
		(width 0.089408)
		(layer "In11.Cu")
		(net "XDP_SYSPWROK")
	)
	(segment
		(start 469.080088 -114.310668)
		(end 468.229696 -113.460276)
		(width 0.089408)
		(layer "In11.Cu")
		(net "XDP_SYSPWROK")
	)
	(segment
		(start 469.766396 -132.642864)
		(end 472.514676 -129.894584)
		(width 0.089408)
		(layer "In11.Cu")
		(net "XDP_SYSPWROK")
	)
	(segment
		(start 470.92108 -116.15166)
		(end 470.604088 -115.834668)
		(width 0.089408)
		(layer "In11.Cu")
		(net "XDP_SYSPWROK")
	)
	(segment
		(start 470.604088 -115.834668)
		(end 470.604088 -115.415568)
		(width 0.089408)
		(layer "In11.Cu")
		(net "XDP_SYSPWROK")
	)
	(segment
		(start 472.514676 -129.894584)
		(end 473.661232 -129.894584)
		(width 0.089408)
		(layer "In11.Cu")
		(net "XDP_SYSPWROK")
	)
	(segment
		(start 472.6432 -121.5898)
		(end 472.9099 -121.3231)
		(width 0.089408)
		(layer "In11.Cu")
		(net "XDP_SYSPWROK")
	)
	(segment
		(start 474.560392 -125.234192)
		(end 472.6432 -123.317)
		(width 0.089408)
		(layer "In11.Cu")
		(net "XDP_SYSPWROK")
	)
	(segment
		(start 468.659972 -147.239228)
		(end 468.659972 -142.006828)
		(width 0.089408)
		(layer "In11.Cu")
		(net "XDP_SYSPWROK")
	)
	(segment
		(start 464.058 -114.8588)
		(end 463.728816 -115.187984)
		(width 0.089408)
		(layer "In11.Cu")
		(net "XDP_SYSPWROK")
	)
	(segment
		(start 464.058 -114.165634)
		(end 464.058 -114.8588)
		(width 0.089408)
		(layer "In11.Cu")
		(net "XDP_SYSPWROK")
	)
	(segment
		(start 463.728816 -115.187984)
		(end 441.178696 -115.187984)
		(width 0.089408)
		(layer "In11.Cu")
		(net "XDP_SYSPWROK")
	)
	(segment
		(start 468.229696 -113.460276)
		(end 464.763358 -113.460276)
		(width 0.089408)
		(layer "In11.Cu")
		(net "XDP_SYSPWROK")
	)
	(segment
		(start 373.544846 -70.295262)
		(end 373.14505 -70.695058)
		(width 0.1016)
		(layer "F.Cu")
		(net "TP_CPLD1_PT17C")
	)
	(via
		(at 373.544846 -70.295262)
		(size 0.4572)
		(drill 0.2032)
		(layers "F.Cu" "B.Cu")
		(net "TP_CPLD1_PT17C")
	)
	(segment
		(start 415.671 -22.225)
		(end 415.671 -21.875496)
		(width 0.10795)
		(layer "F.Cu")
		(net "SGPIO_BMC_LD_N")
	)
	(segment
		(start 376.744738 -75.894692)
		(end 376.344942 -75.494896)
		(width 0.1016)
		(layer "F.Cu")
		(net "SGPIO_BMC_LD_N")
	)
	(segment
		(start 415.036 -21.240496)
		(end 415.036 -20.574)
		(width 0.10795)
		(layer "F.Cu")
		(net "SGPIO_BMC_LD_N")
	)
	(segment
		(start 415.036 -20.574)
		(end 415.366708 -20.243292)
		(width 0.10795)
		(layer "F.Cu")
		(net "SGPIO_BMC_LD_N")
	)
	(segment
		(start 415.366708 -18.67789)
		(end 415.375598 -18.669)
		(width 0.10795)
		(layer "F.Cu")
		(net "SGPIO_BMC_LD_N")
	)
	(segment
		(start 415.366708 -20.243292)
		(end 415.366708 -18.67789)
		(width 0.10795)
		(layer "F.Cu")
		(net "SGPIO_BMC_LD_N")
	)
	(segment
		(start 415.671 -21.875496)
		(end 415.036 -21.240496)
		(width 0.10795)
		(layer "F.Cu")
		(net "SGPIO_BMC_LD_N")
	)
	(via
		(at 376.744738 -75.894692)
		(size 0.4572)
		(drill 0.2032)
		(layers "F.Cu" "B.Cu")
		(net "SGPIO_BMC_LD_N")
	)
	(via
		(at 415.366708 -20.243292)
		(size 0.762)
		(drill 0.381)
		(layers "F.Cu" "B.Cu")
		(net "SGPIO_BMC_LD_N")
	)
	(via
		(at 415.375598 -18.669)
		(size 0.508)
		(drill 0.254)
		(layers "F.Cu" "B.Cu")
		(net "SGPIO_BMC_LD_N")
	)
	(via
		(at 383.9972 -32.2707)
		(size 0.508)
		(drill 0.254)
		(layers "F.Cu" "B.Cu")
		(net "SGPIO_BMC_LD_N")
	)
	(segment
		(start 381.315976 -35.394646)
		(end 382.148334 -35.394646)
		(width 0.089408)
		(layer "In9.Cu")
		(net "SGPIO_BMC_LD_N")
	)
	(segment
		(start 381.088392 -36.407344)
		(end 381.088392 -35.62223)
		(width 0.089408)
		(layer "In9.Cu")
		(net "SGPIO_BMC_LD_N")
	)
	(segment
		(start 382.143 -40.304466)
		(end 382.143 -37.461952)
		(width 0.089408)
		(layer "In9.Cu")
		(net "SGPIO_BMC_LD_N")
	)
	(segment
		(start 377.171458 -71.740268)
		(end 377.431554 -71.480172)
		(width 0.089408)
		(layer "In9.Cu")
		(net "SGPIO_BMC_LD_N")
	)
	(segment
		(start 382.491742 -43.44543)
		(end 381.131826 -42.085514)
		(width 0.089408)
		(layer "In9.Cu")
		(net "SGPIO_BMC_LD_N")
	)
	(segment
		(start 377.118118 -74.4982)
		(end 376.371358 -73.75144)
		(width 0.089408)
		(layer "In9.Cu")
		(net "SGPIO_BMC_LD_N")
	)
	(segment
		(start 381.131826 -42.085514)
		(end 381.131826 -41.31564)
		(width 0.089408)
		(layer "In9.Cu")
		(net "SGPIO_BMC_LD_N")
	)
	(segment
		(start 379.678946 -63.512192)
		(end 379.678946 -63.001398)
		(width 0.089408)
		(layer "In9.Cu")
		(net "SGPIO_BMC_LD_N")
	)
	(segment
		(start 378.417074 -65.99047)
		(end 378.417074 -65.158874)
		(width 0.089408)
		(layer "In9.Cu")
		(net "SGPIO_BMC_LD_N")
	)
	(segment
		(start 376.846084 -72.321928)
		(end 377.171458 -71.996554)
		(width 0.089408)
		(layer "In9.Cu")
		(net "SGPIO_BMC_LD_N")
	)
	(segment
		(start 376.590052 -72.321928)
		(end 376.846084 -72.321928)
		(width 0.089408)
		(layer "In9.Cu")
		(net "SGPIO_BMC_LD_N")
	)
	(segment
		(start 382.173734 -59.136026)
		(end 382.173734 -56.42229)
		(width 0.089408)
		(layer "In9.Cu")
		(net "SGPIO_BMC_LD_N")
	)
	(segment
		(start 379.543818 -67.117214)
		(end 378.417074 -65.99047)
		(width 0.089408)
		(layer "In9.Cu")
		(net "SGPIO_BMC_LD_N")
	)
	(segment
		(start 382.96215 -33.17875)
		(end 383.8702 -32.2707)
		(width 0.089408)
		(layer "In9.Cu")
		(net "SGPIO_BMC_LD_N")
	)
	(segment
		(start 378.579634 -64.611504)
		(end 379.678946 -63.512192)
		(width 0.089408)
		(layer "In9.Cu")
		(net "SGPIO_BMC_LD_N")
	)
	(segment
		(start 383.8702 -32.2707)
		(end 383.9972 -32.2707)
		(width 0.089408)
		(layer "In9.Cu")
		(net "SGPIO_BMC_LD_N")
	)
	(segment
		(start 376.744738 -75.894692)
		(end 377.118118 -75.521312)
		(width 0.089408)
		(layer "In9.Cu")
		(net "SGPIO_BMC_LD_N")
	)
	(segment
		(start 381.550418 -41.180512)
		(end 382.129284 -40.601646)
		(width 0.089408)
		(layer "In9.Cu")
		(net "SGPIO_BMC_LD_N")
	)
	(segment
		(start 382.006094 -56.230774)
		(end 382.005586 -56.230266)
		(width 0.089408)
		(layer "In9.Cu")
		(net "SGPIO_BMC_LD_N")
	)
	(segment
		(start 381.131826 -41.31564)
		(end 381.266954 -41.180512)
		(width 0.089408)
		(layer "In9.Cu")
		(net "SGPIO_BMC_LD_N")
	)
	(segment
		(start 382.006094 -56.25465)
		(end 382.006094 -56.230774)
		(width 0.089408)
		(layer "In9.Cu")
		(net "SGPIO_BMC_LD_N")
	)
	(segment
		(start 377.118118 -75.521312)
		(end 377.118118 -74.4982)
		(width 0.089408)
		(layer "In9.Cu")
		(net "SGPIO_BMC_LD_N")
	)
	(segment
		(start 381.400304 -59.909456)
		(end 382.173734 -59.136026)
		(width 0.089408)
		(layer "In9.Cu")
		(net "SGPIO_BMC_LD_N")
	)
	(segment
		(start 382.005586 -46.500034)
		(end 382.491742 -46.013878)
		(width 0.089408)
		(layer "In9.Cu")
		(net "SGPIO_BMC_LD_N")
	)
	(segment
		(start 376.371358 -72.540622)
		(end 376.590052 -72.321928)
		(width 0.089408)
		(layer "In9.Cu")
		(net "SGPIO_BMC_LD_N")
	)
	(segment
		(start 382.005586 -56.230266)
		(end 382.005586 -46.500034)
		(width 0.089408)
		(layer "In9.Cu")
		(net "SGPIO_BMC_LD_N")
	)
	(segment
		(start 381.400304 -61.28004)
		(end 381.400304 -59.909456)
		(width 0.089408)
		(layer "In9.Cu")
		(net "SGPIO_BMC_LD_N")
	)
	(segment
		(start 379.678946 -63.001398)
		(end 381.400304 -61.28004)
		(width 0.089408)
		(layer "In9.Cu")
		(net "SGPIO_BMC_LD_N")
	)
	(segment
		(start 382.129284 -40.601646)
		(end 382.129284 -40.318182)
		(width 0.089408)
		(layer "In9.Cu")
		(net "SGPIO_BMC_LD_N")
	)
	(segment
		(start 382.143 -37.461952)
		(end 381.088392 -36.407344)
		(width 0.089408)
		(layer "In9.Cu")
		(net "SGPIO_BMC_LD_N")
	)
	(segment
		(start 379.543818 -68.577206)
		(end 379.543818 -67.117214)
		(width 0.089408)
		(layer "In9.Cu")
		(net "SGPIO_BMC_LD_N")
	)
	(segment
		(start 382.173734 -56.42229)
		(end 382.006094 -56.25465)
		(width 0.089408)
		(layer "In9.Cu")
		(net "SGPIO_BMC_LD_N")
	)
	(segment
		(start 378.417074 -65.158874)
		(end 378.579634 -64.996314)
		(width 0.089408)
		(layer "In9.Cu")
		(net "SGPIO_BMC_LD_N")
	)
	(segment
		(start 376.371358 -73.75144)
		(end 376.371358 -72.540622)
		(width 0.089408)
		(layer "In9.Cu")
		(net "SGPIO_BMC_LD_N")
	)
	(segment
		(start 382.491742 -46.013878)
		(end 382.491742 -43.44543)
		(width 0.089408)
		(layer "In9.Cu")
		(net "SGPIO_BMC_LD_N")
	)
	(segment
		(start 377.431554 -70.68947)
		(end 379.543818 -68.577206)
		(width 0.089408)
		(layer "In9.Cu")
		(net "SGPIO_BMC_LD_N")
	)
	(segment
		(start 377.171458 -71.996554)
		(end 377.171458 -71.740268)
		(width 0.089408)
		(layer "In9.Cu")
		(net "SGPIO_BMC_LD_N")
	)
	(segment
		(start 378.579634 -64.996314)
		(end 378.579634 -64.611504)
		(width 0.089408)
		(layer "In9.Cu")
		(net "SGPIO_BMC_LD_N")
	)
	(segment
		(start 382.148334 -35.394646)
		(end 382.96215 -34.58083)
		(width 0.089408)
		(layer "In9.Cu")
		(net "SGPIO_BMC_LD_N")
	)
	(segment
		(start 381.266954 -41.180512)
		(end 381.550418 -41.180512)
		(width 0.089408)
		(layer "In9.Cu")
		(net "SGPIO_BMC_LD_N")
	)
	(segment
		(start 381.088392 -35.62223)
		(end 381.315976 -35.394646)
		(width 0.089408)
		(layer "In9.Cu")
		(net "SGPIO_BMC_LD_N")
	)
	(segment
		(start 382.96215 -34.58083)
		(end 382.96215 -33.17875)
		(width 0.089408)
		(layer "In9.Cu")
		(net "SGPIO_BMC_LD_N")
	)
	(segment
		(start 377.431554 -71.480172)
		(end 377.431554 -70.68947)
		(width 0.089408)
		(layer "In9.Cu")
		(net "SGPIO_BMC_LD_N")
	)
	(segment
		(start 382.129284 -40.318182)
		(end 382.143 -40.304466)
		(width 0.089408)
		(layer "In9.Cu")
		(net "SGPIO_BMC_LD_N")
	)
	(segment
		(start 379.30074 -30.357318)
		(end 379.30074 -30.72638)
		(width 0.089408)
		(layer "In11.Cu")
		(net "SGPIO_BMC_LD_N")
	)
	(segment
		(start 399.651728 -17.62252)
		(end 399.651728 -18.423128)
		(width 0.089408)
		(layer "In11.Cu")
		(net "SGPIO_BMC_LD_N")
	)
	(segment
		(start 383.7559 -32.0294)
		(end 383.9972 -32.2707)
		(width 0.089408)
		(layer "In11.Cu")
		(net "SGPIO_BMC_LD_N")
	)
	(segment
		(start 382.096518 -32.0294)
		(end 383.7559 -32.0294)
		(width 0.089408)
		(layer "In11.Cu")
		(net "SGPIO_BMC_LD_N")
	)
	(segment
		(start 381.181356 -31.114238)
		(end 382.096518 -32.0294)
		(width 0.089408)
		(layer "In11.Cu")
		(net "SGPIO_BMC_LD_N")
	)
	(segment
		(start 395.97838 -17.11198)
		(end 393.65936 -17.11198)
		(width 0.089408)
		(layer "In11.Cu")
		(net "SGPIO_BMC_LD_N")
	)
	(segment
		(start 402.905976 -14.368272)
		(end 399.651728 -17.62252)
		(width 0.089408)
		(layer "In11.Cu")
		(net "SGPIO_BMC_LD_N")
	)
	(segment
		(start 380.22403 -18.979134)
		(end 376.688858 -22.514306)
		(width 0.089408)
		(layer "In11.Cu")
		(net "SGPIO_BMC_LD_N")
	)
	(segment
		(start 396.65656 -19.762978)
		(end 396.65656 -19.75866)
		(width 0.089408)
		(layer "In11.Cu")
		(net "SGPIO_BMC_LD_N")
	)
	(segment
		(start 382.999742 -15.66418)
		(end 380.22403 -18.439892)
		(width 0.089408)
		(layer "In11.Cu")
		(net "SGPIO_BMC_LD_N")
	)
	(segment
		(start 415.134552 -18.669)
		(end 410.833824 -14.368272)
		(width 0.089408)
		(layer "In11.Cu")
		(net "SGPIO_BMC_LD_N")
	)
	(segment
		(start 399.651728 -18.423128)
		(end 400.124168 -18.895568)
		(width 0.089408)
		(layer "In11.Cu")
		(net "SGPIO_BMC_LD_N")
	)
	(segment
		(start 376.688858 -27.745436)
		(end 379.30074 -30.357318)
		(width 0.089408)
		(layer "In11.Cu")
		(net "SGPIO_BMC_LD_N")
	)
	(segment
		(start 415.375598 -18.669)
		(end 415.134552 -18.669)
		(width 0.089408)
		(layer "In11.Cu")
		(net "SGPIO_BMC_LD_N")
	)
	(segment
		(start 380.22403 -18.439892)
		(end 380.22403 -18.979134)
		(width 0.089408)
		(layer "In11.Cu")
		(net "SGPIO_BMC_LD_N")
	)
	(segment
		(start 379.688598 -31.114238)
		(end 381.181356 -31.114238)
		(width 0.089408)
		(layer "In11.Cu")
		(net "SGPIO_BMC_LD_N")
	)
	(segment
		(start 400.124168 -19.403568)
		(end 399.764758 -19.762978)
		(width 0.089408)
		(layer "In11.Cu")
		(net "SGPIO_BMC_LD_N")
	)
	(segment
		(start 392.21156 -15.66418)
		(end 382.999742 -15.66418)
		(width 0.089408)
		(layer "In11.Cu")
		(net "SGPIO_BMC_LD_N")
	)
	(segment
		(start 393.65936 -17.11198)
		(end 392.21156 -15.66418)
		(width 0.089408)
		(layer "In11.Cu")
		(net "SGPIO_BMC_LD_N")
	)
	(segment
		(start 379.30074 -30.72638)
		(end 379.688598 -31.114238)
		(width 0.089408)
		(layer "In11.Cu")
		(net "SGPIO_BMC_LD_N")
	)
	(segment
		(start 400.124168 -18.895568)
		(end 400.124168 -19.403568)
		(width 0.089408)
		(layer "In11.Cu")
		(net "SGPIO_BMC_LD_N")
	)
	(segment
		(start 376.688858 -22.514306)
		(end 376.688858 -27.745436)
		(width 0.089408)
		(layer "In11.Cu")
		(net "SGPIO_BMC_LD_N")
	)
	(segment
		(start 396.65656 -19.75866)
		(end 396.29334 -19.39544)
		(width 0.089408)
		(layer "In11.Cu")
		(net "SGPIO_BMC_LD_N")
	)
	(segment
		(start 399.764758 -19.762978)
		(end 396.65656 -19.762978)
		(width 0.089408)
		(layer "In11.Cu")
		(net "SGPIO_BMC_LD_N")
	)
	(segment
		(start 396.29334 -17.42694)
		(end 395.97838 -17.11198)
		(width 0.089408)
		(layer "In11.Cu")
		(net "SGPIO_BMC_LD_N")
	)
	(segment
		(start 396.29334 -19.39544)
		(end 396.29334 -17.42694)
		(width 0.089408)
		(layer "In11.Cu")
		(net "SGPIO_BMC_LD_N")
	)
	(segment
		(start 410.833824 -14.368272)
		(end 402.905976 -14.368272)
		(width 0.089408)
		(layer "In11.Cu")
		(net "SGPIO_BMC_LD_N")
	)
	(segment
		(start 417.481766 -20.454366)
		(end 417.449 -20.4216)
		(width 0.10795)
		(layer "F.Cu")
		(net "SGPIO_BMC_DOUT")
	)
	(segment
		(start 379.5014 -75.0824)
		(end 378.332238 -75.0824)
		(width 0.10795)
		(layer "F.Cu")
		(net "SGPIO_BMC_DOUT")
	)
	(segment
		(start 378.332238 -75.0824)
		(end 377.944888 -74.69505)
		(width 0.10795)
		(layer "F.Cu")
		(net "SGPIO_BMC_DOUT")
	)
	(segment
		(start 380.2126 -74.6506)
		(end 379.9332 -74.6506)
		(width 0.10795)
		(layer "F.Cu")
		(net "SGPIO_BMC_DOUT")
	)
	(segment
		(start 379.9332 -74.6506)
		(end 379.5014 -75.0824)
		(width 0.10795)
		(layer "F.Cu")
		(net "SGPIO_BMC_DOUT")
	)
	(segment
		(start 417.481766 -21.160232)
		(end 417.481766 -20.454366)
		(width 0.10795)
		(layer "F.Cu")
		(net "SGPIO_BMC_DOUT")
	)
	(via
		(at 380.2126 -74.6506)
		(size 0.508)
		(drill 0.254)
		(layers "F.Cu" "B.Cu")
		(net "SGPIO_BMC_DOUT")
	)
	(via
		(at 385.978146 -21.873718)
		(size 0.508)
		(drill 0.254)
		(layers "F.Cu" "B.Cu")
		(net "SGPIO_BMC_DOUT")
	)
	(via
		(at 417.449 -20.4216)
		(size 0.508)
		(drill 0.254)
		(layers "F.Cu" "B.Cu")
		(net "SGPIO_BMC_DOUT")
	)
	(segment
		(start 401.75815 -24.349456)
		(end 400.92503 -23.516336)
		(width 0.089408)
		(layer "In4.Cu")
		(net "SGPIO_BMC_DOUT")
	)
	(segment
		(start 394.63472 -24.0157)
		(end 389.863838 -24.0157)
		(width 0.089408)
		(layer "In4.Cu")
		(net "SGPIO_BMC_DOUT")
	)
	(segment
		(start 406.621742 -23.758906)
		(end 406.621742 -24.11476)
		(width 0.089408)
		(layer "In4.Cu")
		(net "SGPIO_BMC_DOUT")
	)
	(segment
		(start 417.449 -20.4216)
		(end 417.219892 -20.650708)
		(width 0.089408)
		(layer "In4.Cu")
		(net "SGPIO_BMC_DOUT")
	)
	(segment
		(start 400.92503 -23.516336)
		(end 395.134084 -23.516336)
		(width 0.089408)
		(layer "In4.Cu")
		(net "SGPIO_BMC_DOUT")
	)
	(segment
		(start 412.814262 -22.229572)
		(end 409.677616 -22.229572)
		(width 0.089408)
		(layer "In4.Cu")
		(net "SGPIO_BMC_DOUT")
	)
	(segment
		(start 395.134084 -23.516336)
		(end 394.63472 -24.0157)
		(width 0.089408)
		(layer "In4.Cu")
		(net "SGPIO_BMC_DOUT")
	)
	(segment
		(start 405.3078 -24.4856)
		(end 405.171656 -24.349456)
		(width 0.089408)
		(layer "In4.Cu")
		(net "SGPIO_BMC_DOUT")
	)
	(segment
		(start 389.863838 -24.0157)
		(end 387.721856 -21.873718)
		(width 0.089408)
		(layer "In4.Cu")
		(net "SGPIO_BMC_DOUT")
	)
	(segment
		(start 414.393126 -20.650708)
		(end 412.814262 -22.229572)
		(width 0.089408)
		(layer "In4.Cu")
		(net "SGPIO_BMC_DOUT")
	)
	(segment
		(start 405.171656 -24.349456)
		(end 401.75815 -24.349456)
		(width 0.089408)
		(layer "In4.Cu")
		(net "SGPIO_BMC_DOUT")
	)
	(segment
		(start 408.67584 -23.231348)
		(end 407.1493 -23.231348)
		(width 0.089408)
		(layer "In4.Cu")
		(net "SGPIO_BMC_DOUT")
	)
	(segment
		(start 406.621742 -24.11476)
		(end 406.250902 -24.4856)
		(width 0.089408)
		(layer "In4.Cu")
		(net "SGPIO_BMC_DOUT")
	)
	(segment
		(start 409.677616 -22.229572)
		(end 408.67584 -23.231348)
		(width 0.089408)
		(layer "In4.Cu")
		(net "SGPIO_BMC_DOUT")
	)
	(segment
		(start 407.1493 -23.231348)
		(end 406.621742 -23.758906)
		(width 0.089408)
		(layer "In4.Cu")
		(net "SGPIO_BMC_DOUT")
	)
	(segment
		(start 417.219892 -20.650708)
		(end 414.393126 -20.650708)
		(width 0.089408)
		(layer "In4.Cu")
		(net "SGPIO_BMC_DOUT")
	)
	(segment
		(start 387.721856 -21.873718)
		(end 385.978146 -21.873718)
		(width 0.089408)
		(layer "In4.Cu")
		(net "SGPIO_BMC_DOUT")
	)
	(segment
		(start 406.250902 -24.4856)
		(end 405.3078 -24.4856)
		(width 0.089408)
		(layer "In4.Cu")
		(net "SGPIO_BMC_DOUT")
	)
	(segment
		(start 382.936496 -66.26225)
		(end 382.024636 -67.17411)
		(width 0.089408)
		(layer "In9.Cu")
		(net "SGPIO_BMC_DOUT")
	)
	(segment
		(start 383.323592 -65.334388)
		(end 382.936496 -65.721484)
		(width 0.089408)
		(layer "In9.Cu")
		(net "SGPIO_BMC_DOUT")
	)
	(segment
		(start 383.323592 -65.333372)
		(end 383.323592 -65.334388)
		(width 0.089408)
		(layer "In9.Cu")
		(net "SGPIO_BMC_DOUT")
	)
	(segment
		(start 385.203446 -32.931354)
		(end 385.203446 -37.64153)
		(width 0.089408)
		(layer "In9.Cu")
		(net "SGPIO_BMC_DOUT")
	)
	(segment
		(start 385.203446 -37.64153)
		(end 383.93624 -38.908736)
		(width 0.089408)
		(layer "In9.Cu")
		(net "SGPIO_BMC_DOUT")
	)
	(segment
		(start 383.36347 -64.673988)
		(end 383.36347 -65.293494)
		(width 0.089408)
		(layer "In9.Cu")
		(net "SGPIO_BMC_DOUT")
	)
	(segment
		(start 383.079498 -64.390016)
		(end 383.36347 -64.673988)
		(width 0.089408)
		(layer "In9.Cu")
		(net "SGPIO_BMC_DOUT")
	)
	(segment
		(start 384.424936 -48.71466)
		(end 384.424936 -49.046384)
		(width 0.089408)
		(layer "In9.Cu")
		(net "SGPIO_BMC_DOUT")
	)
	(segment
		(start 383.93624 -40.659812)
		(end 384.626104 -41.349676)
		(width 0.089408)
		(layer "In9.Cu")
		(net "SGPIO_BMC_DOUT")
	)
	(segment
		(start 385.978146 -21.873718)
		(end 386.083556 -21.979128)
		(width 0.089408)
		(layer "In9.Cu")
		(net "SGPIO_BMC_DOUT")
	)
	(segment
		(start 383.079498 -60.69457)
		(end 383.079498 -64.390016)
		(width 0.089408)
		(layer "In9.Cu")
		(net "SGPIO_BMC_DOUT")
	)
	(segment
		(start 385.628896 -32.505904)
		(end 385.203446 -32.931354)
		(width 0.089408)
		(layer "In9.Cu")
		(net "SGPIO_BMC_DOUT")
	)
	(segment
		(start 384.424936 -49.046384)
		(end 384.626104 -49.247552)
		(width 0.089408)
		(layer "In9.Cu")
		(net "SGPIO_BMC_DOUT")
	)
	(segment
		(start 385.628896 -29.201872)
		(end 385.628896 -32.505904)
		(width 0.089408)
		(layer "In9.Cu")
		(net "SGPIO_BMC_DOUT")
	)
	(segment
		(start 383.781046 -54.05628)
		(end 384.930904 -55.206138)
		(width 0.089408)
		(layer "In9.Cu")
		(net "SGPIO_BMC_DOUT")
	)
	(segment
		(start 383.781046 -51.937158)
		(end 383.781046 -54.05628)
		(width 0.089408)
		(layer "In9.Cu")
		(net "SGPIO_BMC_DOUT")
	)
	(segment
		(start 383.93624 -38.908736)
		(end 383.93624 -40.659812)
		(width 0.089408)
		(layer "In9.Cu")
		(net "SGPIO_BMC_DOUT")
	)
	(segment
		(start 384.626104 -49.247552)
		(end 384.626104 -51.0921)
		(width 0.089408)
		(layer "In9.Cu")
		(net "SGPIO_BMC_DOUT")
	)
	(segment
		(start 386.083556 -28.747212)
		(end 385.628896 -29.201872)
		(width 0.089408)
		(layer "In9.Cu")
		(net "SGPIO_BMC_DOUT")
	)
	(segment
		(start 386.083556 -21.979128)
		(end 386.083556 -28.747212)
		(width 0.089408)
		(layer "In9.Cu")
		(net "SGPIO_BMC_DOUT")
	)
	(segment
		(start 383.849372 -56.678322)
		(end 383.849372 -59.924696)
		(width 0.089408)
		(layer "In9.Cu")
		(net "SGPIO_BMC_DOUT")
	)
	(segment
		(start 381.802894 -71.463662)
		(end 380.547118 -72.719438)
		(width 0.089408)
		(layer "In9.Cu")
		(net "SGPIO_BMC_DOUT")
	)
	(segment
		(start 381.802894 -70.730618)
		(end 381.802894 -71.463662)
		(width 0.089408)
		(layer "In9.Cu")
		(net "SGPIO_BMC_DOUT")
	)
	(segment
		(start 384.304032 -56.223662)
		(end 383.849372 -56.678322)
		(width 0.089408)
		(layer "In9.Cu")
		(net "SGPIO_BMC_DOUT")
	)
	(segment
		(start 384.930904 -55.206138)
		(end 384.930904 -55.596536)
		(width 0.089408)
		(layer "In9.Cu")
		(net "SGPIO_BMC_DOUT")
	)
	(segment
		(start 381.459232 -68.956428)
		(end 381.459232 -70.386956)
		(width 0.089408)
		(layer "In9.Cu")
		(net "SGPIO_BMC_DOUT")
	)
	(segment
		(start 382.936496 -65.721484)
		(end 382.936496 -66.26225)
		(width 0.089408)
		(layer "In9.Cu")
		(net "SGPIO_BMC_DOUT")
	)
	(segment
		(start 384.626104 -41.349676)
		(end 384.626104 -48.513492)
		(width 0.089408)
		(layer "In9.Cu")
		(net "SGPIO_BMC_DOUT")
	)
	(segment
		(start 384.930904 -55.596536)
		(end 384.304032 -56.223408)
		(width 0.089408)
		(layer "In9.Cu")
		(net "SGPIO_BMC_DOUT")
	)
	(segment
		(start 380.547118 -72.719438)
		(end 380.547118 -73.507346)
		(width 0.089408)
		(layer "In9.Cu")
		(net "SGPIO_BMC_DOUT")
	)
	(segment
		(start 383.849372 -59.924696)
		(end 383.079498 -60.69457)
		(width 0.089408)
		(layer "In9.Cu")
		(net "SGPIO_BMC_DOUT")
	)
	(segment
		(start 384.304032 -56.223408)
		(end 384.304032 -56.223662)
		(width 0.089408)
		(layer "In9.Cu")
		(net "SGPIO_BMC_DOUT")
	)
	(segment
		(start 384.626104 -51.0921)
		(end 383.781046 -51.937158)
		(width 0.089408)
		(layer "In9.Cu")
		(net "SGPIO_BMC_DOUT")
	)
	(segment
		(start 381.459232 -70.386956)
		(end 381.802894 -70.730618)
		(width 0.089408)
		(layer "In9.Cu")
		(net "SGPIO_BMC_DOUT")
	)
	(segment
		(start 382.024636 -67.17411)
		(end 382.024636 -68.391024)
		(width 0.089408)
		(layer "In9.Cu")
		(net "SGPIO_BMC_DOUT")
	)
	(segment
		(start 380.547118 -73.507346)
		(end 380.2126 -73.841864)
		(width 0.089408)
		(layer "In9.Cu")
		(net "SGPIO_BMC_DOUT")
	)
	(segment
		(start 382.024636 -68.391024)
		(end 381.459232 -68.956428)
		(width 0.089408)
		(layer "In9.Cu")
		(net "SGPIO_BMC_DOUT")
	)
	(segment
		(start 383.36347 -65.293494)
		(end 383.323592 -65.333372)
		(width 0.089408)
		(layer "In9.Cu")
		(net "SGPIO_BMC_DOUT")
	)
	(segment
		(start 380.2126 -73.841864)
		(end 380.2126 -74.6506)
		(width 0.089408)
		(layer "In9.Cu")
		(net "SGPIO_BMC_DOUT")
	)
	(segment
		(start 384.626104 -48.513492)
		(end 384.424936 -48.71466)
		(width 0.089408)
		(layer "In9.Cu")
		(net "SGPIO_BMC_DOUT")
	)
	(segment
		(start 384.465068 -61.365892)
		(end 384.3401 -61.49086)
		(width 0.10795)
		(layer "F.Cu")
		(net "SGPIO_BMC_DIN")
	)
	(segment
		(start 377.514104 -63.989966)
		(end 377.481338 -63.9572)
		(width 0.10795)
		(layer "F.Cu")
		(net "SGPIO_BMC_DIN")
	)
	(segment
		(start 387.670802 -61.616844)
		(end 387.416802 -61.870844)
		(width 0.10795)
		(layer "F.Cu")
		(net "SGPIO_BMC_DIN")
	)
	(segment
		(start 384.835908 -61.365892)
		(end 384.465068 -61.365892)
		(width 0.10795)
		(layer "F.Cu")
		(net "SGPIO_BMC_DIN")
	)
	(segment
		(start 387.416802 -61.871606)
		(end 387.169406 -62.119002)
		(width 0.10795)
		(layer "F.Cu")
		(net "SGPIO_BMC_DIN")
	)
	(segment
		(start 382.282192 -61.49086)
		(end 379.783086 -63.989966)
		(width 0.10795)
		(layer "F.Cu")
		(net "SGPIO_BMC_DIN")
	)
	(segment
		(start 416.690048 -28.934664)
		(end 417.00958 -28.615132)
		(width 0.10795)
		(layer "F.Cu")
		(net "SGPIO_BMC_DIN")
	)
	(segment
		(start 387.416802 -61.870844)
		(end 387.416802 -61.871606)
		(width 0.10795)
		(layer "F.Cu")
		(net "SGPIO_BMC_DIN")
	)
	(segment
		(start 390.655556 -61.616844)
		(end 387.670802 -61.616844)
		(width 0.10795)
		(layer "F.Cu")
		(net "SGPIO_BMC_DIN")
	)
	(segment
		(start 379.783086 -63.989966)
		(end 377.514104 -63.989966)
		(width 0.10795)
		(layer "F.Cu")
		(net "SGPIO_BMC_DIN")
	)
	(segment
		(start 392.633708 -60.020962)
		(end 392.104118 -60.550552)
		(width 0.10795)
		(layer "F.Cu")
		(net "SGPIO_BMC_DIN")
	)
	(segment
		(start 385.878324 -61.616844)
		(end 385.08686 -61.616844)
		(width 0.10795)
		(layer "F.Cu")
		(net "SGPIO_BMC_DIN")
	)
	(segment
		(start 417.00958 -28.615132)
		(end 417.00958 -28.53436)
		(width 0.10795)
		(layer "F.Cu")
		(net "SGPIO_BMC_DIN")
	)
	(segment
		(start 387.169406 -62.119002)
		(end 386.380482 -62.119002)
		(width 0.10795)
		(layer "F.Cu")
		(net "SGPIO_BMC_DIN")
	)
	(segment
		(start 385.08686 -61.616844)
		(end 384.835908 -61.365892)
		(width 0.10795)
		(layer "F.Cu")
		(net "SGPIO_BMC_DIN")
	)
	(segment
		(start 391.721848 -60.550552)
		(end 390.655556 -61.616844)
		(width 0.10795)
		(layer "F.Cu")
		(net "SGPIO_BMC_DIN")
	)
	(segment
		(start 386.380482 -62.119002)
		(end 385.878324 -61.616844)
		(width 0.10795)
		(layer "F.Cu")
		(net "SGPIO_BMC_DIN")
	)
	(segment
		(start 377.481338 -63.9572)
		(end 377.1138 -63.9572)
		(width 0.10795)
		(layer "F.Cu")
		(net "SGPIO_BMC_DIN")
	)
	(segment
		(start 384.3401 -61.49086)
		(end 382.282192 -61.49086)
		(width 0.10795)
		(layer "F.Cu")
		(net "SGPIO_BMC_DIN")
	)
	(segment
		(start 392.104118 -60.550552)
		(end 391.721848 -60.550552)
		(width 0.10795)
		(layer "F.Cu")
		(net "SGPIO_BMC_DIN")
	)
	(segment
		(start 392.633708 -59.316366)
		(end 392.633708 -60.020962)
		(width 0.10795)
		(layer "F.Cu")
		(net "SGPIO_BMC_DIN")
	)
	(via
		(at 377.1138 -63.9572)
		(size 0.508)
		(drill 0.254)
		(layers "F.Cu" "B.Cu")
		(net "SGPIO_BMC_DIN")
	)
	(via
		(at 392.633708 -59.316366)
		(size 0.508)
		(drill 0.254)
		(layers "F.Cu" "B.Cu")
		(net "SGPIO_BMC_DIN")
	)
	(via
		(at 417.00958 -28.53436)
		(size 0.4572)
		(drill 0.2032)
		(layers "F.Cu" "B.Cu")
		(net "SGPIO_BMC_DIN")
	)
	(via
		(at 389.058404 -31.4452)
		(size 0.508)
		(drill 0.254)
		(layers "F.Cu" "B.Cu")
		(net "SGPIO_BMC_DIN")
	)
	(segment
		(start 374.545352 -64.364362)
		(end 374.703086 -64.364362)
		(width 0.10795)
		(layer "B.Cu")
		(net "SGPIO_BMC_DIN")
	)
	(segment
		(start 374.950482 -64.116966)
		(end 374.950482 -63.959232)
		(width 0.10795)
		(layer "B.Cu")
		(net "SGPIO_BMC_DIN")
	)
	(segment
		(start 373.9896 -64.920114)
		(end 374.545352 -64.364362)
		(width 0.10795)
		(layer "B.Cu")
		(net "SGPIO_BMC_DIN")
	)
	(segment
		(start 375.324116 -63.585598)
		(end 375.714006 -63.585598)
		(width 0.10795)
		(layer "B.Cu")
		(net "SGPIO_BMC_DIN")
	)
	(segment
		(start 374.950482 -63.959232)
		(end 375.324116 -63.585598)
		(width 0.10795)
		(layer "B.Cu")
		(net "SGPIO_BMC_DIN")
	)
	(segment
		(start 376.085608 -63.9572)
		(end 377.1138 -63.9572)
		(width 0.10795)
		(layer "B.Cu")
		(net "SGPIO_BMC_DIN")
	)
	(segment
		(start 374.703086 -64.364362)
		(end 374.950482 -64.116966)
		(width 0.10795)
		(layer "B.Cu")
		(net "SGPIO_BMC_DIN")
	)
	(segment
		(start 373.888 -65.6336)
		(end 373.9896 -65.532)
		(width 0.10795)
		(layer "B.Cu")
		(net "SGPIO_BMC_DIN")
	)
	(segment
		(start 375.714006 -63.585598)
		(end 376.085608 -63.9572)
		(width 0.10795)
		(layer "B.Cu")
		(net "SGPIO_BMC_DIN")
	)
	(segment
		(start 373.9896 -65.532)
		(end 373.9896 -64.920114)
		(width 0.10795)
		(layer "B.Cu")
		(net "SGPIO_BMC_DIN")
	)
	(segment
		(start 373.888 -66.04)
		(end 373.888 -65.6336)
		(width 0.10795)
		(layer "B.Cu")
		(net "SGPIO_BMC_DIN")
	)
	(segment
		(start 392.768836 -31.315152)
		(end 394.669264 -29.414724)
		(width 0.089408)
		(layer "In4.Cu")
		(net "SGPIO_BMC_DIN")
	)
	(segment
		(start 389.188452 -31.315152)
		(end 392.768836 -31.315152)
		(width 0.089408)
		(layer "In4.Cu")
		(net "SGPIO_BMC_DIN")
	)
	(segment
		(start 405.057356 -30.155642)
		(end 405.077676 -30.175962)
		(width 0.089408)
		(layer "In4.Cu")
		(net "SGPIO_BMC_DIN")
	)
	(segment
		(start 401.450556 -29.414724)
		(end 402.191474 -30.155642)
		(width 0.089408)
		(layer "In4.Cu")
		(net "SGPIO_BMC_DIN")
	)
	(segment
		(start 407.856944 -28.949396)
		(end 411.377384 -28.949396)
		(width 0.089408)
		(layer "In4.Cu")
		(net "SGPIO_BMC_DIN")
	)
	(segment
		(start 415.651696 -29.709364)
		(end 416.8267 -28.53436)
		(width 0.089408)
		(layer "In4.Cu")
		(net "SGPIO_BMC_DIN")
	)
	(segment
		(start 394.669264 -29.414724)
		(end 401.450556 -29.414724)
		(width 0.089408)
		(layer "In4.Cu")
		(net "SGPIO_BMC_DIN")
	)
	(segment
		(start 406.630378 -30.175962)
		(end 407.856944 -28.949396)
		(width 0.089408)
		(layer "In4.Cu")
		(net "SGPIO_BMC_DIN")
	)
	(segment
		(start 411.377384 -28.949396)
		(end 412.137352 -29.709364)
		(width 0.089408)
		(layer "In4.Cu")
		(net "SGPIO_BMC_DIN")
	)
	(segment
		(start 405.077676 -30.175962)
		(end 406.630378 -30.175962)
		(width 0.089408)
		(layer "In4.Cu")
		(net "SGPIO_BMC_DIN")
	)
	(segment
		(start 389.058404 -31.4452)
		(end 389.188452 -31.315152)
		(width 0.089408)
		(layer "In4.Cu")
		(net "SGPIO_BMC_DIN")
	)
	(segment
		(start 402.191474 -30.155642)
		(end 405.057356 -30.155642)
		(width 0.089408)
		(layer "In4.Cu")
		(net "SGPIO_BMC_DIN")
	)
	(segment
		(start 412.137352 -29.709364)
		(end 415.651696 -29.709364)
		(width 0.089408)
		(layer "In4.Cu")
		(net "SGPIO_BMC_DIN")
	)
	(segment
		(start 416.8267 -28.53436)
		(end 417.00958 -28.53436)
		(width 0.089408)
		(layer "In4.Cu")
		(net "SGPIO_BMC_DIN")
	)
	(segment
		(start 391.593324 -42.577258)
		(end 391.593578 -42.577004)
		(width 0.089408)
		(layer "In9.Cu")
		(net "SGPIO_BMC_DIN")
	)
	(segment
		(start 391.308336 -47.37989)
		(end 391.06348 -47.135034)
		(width 0.089408)
		(layer "In9.Cu")
		(net "SGPIO_BMC_DIN")
	)
	(segment
		(start 392.448796 -40.464994)
		(end 392.448796 -37.631624)
		(width 0.089408)
		(layer "In9.Cu")
		(net "SGPIO_BMC_DIN")
	)
	(segment
		(start 391.308336 -51.87569)
		(end 391.308336 -47.37989)
		(width 0.089408)
		(layer "In9.Cu")
		(net "SGPIO_BMC_DIN")
	)
	(segment
		(start 392.003026 -58.685684)
		(end 392.003026 -52.57038)
		(width 0.089408)
		(layer "In9.Cu")
		(net "SGPIO_BMC_DIN")
	)
	(segment
		(start 392.003026 -52.57038)
		(end 391.308336 -51.87569)
		(width 0.089408)
		(layer "In9.Cu")
		(net "SGPIO_BMC_DIN")
	)
	(segment
		(start 390.670288 -35.853116)
		(end 390.670288 -33.057084)
		(width 0.089408)
		(layer "In9.Cu")
		(net "SGPIO_BMC_DIN")
	)
	(segment
		(start 391.593578 -42.577004)
		(end 391.593578 -42.516552)
		(width 0.089408)
		(layer "In9.Cu")
		(net "SGPIO_BMC_DIN")
	)
	(segment
		(start 392.633708 -59.316366)
		(end 392.003026 -58.685684)
		(width 0.089408)
		(layer "In9.Cu")
		(net "SGPIO_BMC_DIN")
	)
	(segment
		(start 392.836146 -40.852344)
		(end 392.448796 -40.464994)
		(width 0.089408)
		(layer "In9.Cu")
		(net "SGPIO_BMC_DIN")
	)
	(segment
		(start 391.593832 -45.116242)
		(end 391.593578 -45.115988)
		(width 0.089408)
		(layer "In9.Cu")
		(net "SGPIO_BMC_DIN")
	)
	(segment
		(start 391.593832 -45.358558)
		(end 391.593832 -45.116242)
		(width 0.089408)
		(layer "In9.Cu")
		(net "SGPIO_BMC_DIN")
	)
	(segment
		(start 390.670288 -33.057084)
		(end 389.058404 -31.4452)
		(width 0.089408)
		(layer "In9.Cu")
		(net "SGPIO_BMC_DIN")
	)
	(segment
		(start 391.593578 -45.115988)
		(end 391.593578 -42.819828)
		(width 0.089408)
		(layer "In9.Cu")
		(net "SGPIO_BMC_DIN")
	)
	(segment
		(start 391.593578 -42.516552)
		(end 392.836146 -41.273984)
		(width 0.089408)
		(layer "In9.Cu")
		(net "SGPIO_BMC_DIN")
	)
	(segment
		(start 391.593578 -42.819828)
		(end 391.593324 -42.819574)
		(width 0.089408)
		(layer "In9.Cu")
		(net "SGPIO_BMC_DIN")
	)
	(segment
		(start 392.836146 -41.273984)
		(end 392.836146 -40.852344)
		(width 0.089408)
		(layer "In9.Cu")
		(net "SGPIO_BMC_DIN")
	)
	(segment
		(start 391.593324 -42.819574)
		(end 391.593324 -42.577258)
		(width 0.089408)
		(layer "In9.Cu")
		(net "SGPIO_BMC_DIN")
	)
	(segment
		(start 391.06348 -47.135034)
		(end 391.06348 -45.88891)
		(width 0.089408)
		(layer "In9.Cu")
		(net "SGPIO_BMC_DIN")
	)
	(segment
		(start 392.448796 -37.631624)
		(end 390.670288 -35.853116)
		(width 0.089408)
		(layer "In9.Cu")
		(net "SGPIO_BMC_DIN")
	)
	(segment
		(start 391.06348 -45.88891)
		(end 391.593832 -45.358558)
		(width 0.089408)
		(layer "In9.Cu")
		(net "SGPIO_BMC_DIN")
	)
	(segment
		(start 419.620954 -24.522684)
		(end 419.620954 -23.515066)
		(width 0.10795)
		(layer "F.Cu")
		(net "SGPIO_BMC_CLK")
	)
	(segment
		(start 418.592 -25.551638)
		(end 419.620954 -24.522684)
		(width 0.10795)
		(layer "F.Cu")
		(net "SGPIO_BMC_CLK")
	)
	(segment
		(start 420.055802 -22.39899)
		(end 420.610792 -21.844)
		(width 0.10795)
		(layer "F.Cu")
		(net "SGPIO_BMC_CLK")
	)
	(segment
		(start 378.744988 -74.69505)
		(end 378.778516 -74.661522)
		(width 0.10795)
		(layer "F.Cu")
		(net "SGPIO_BMC_CLK")
	)
	(segment
		(start 420.055802 -23.080218)
		(end 420.055802 -22.39899)
		(width 0.10795)
		(layer "F.Cu")
		(net "SGPIO_BMC_CLK")
	)
	(segment
		(start 420.610792 -21.844)
		(end 420.751 -21.844)
		(width 0.10795)
		(layer "F.Cu")
		(net "SGPIO_BMC_CLK")
	)
	(segment
		(start 378.778516 -74.661522)
		(end 379.290072 -74.661522)
		(width 0.10795)
		(layer "F.Cu")
		(net "SGPIO_BMC_CLK")
	)
	(segment
		(start 419.620954 -23.515066)
		(end 420.055802 -23.080218)
		(width 0.10795)
		(layer "F.Cu")
		(net "SGPIO_BMC_CLK")
	)
	(via
		(at 418.592 -25.551638)
		(size 0.508)
		(drill 0.254)
		(layers "F.Cu" "B.Cu")
		(net "SGPIO_BMC_CLK")
	)
	(via
		(at 378.3584 -74.4982)
		(size 0.6604)
		(drill 0.3302)
		(layers "F.Cu" "B.Cu")
		(net "SGPIO_BMC_CLK")
	)
	(via
		(at 379.290072 -74.661522)
		(size 0.508)
		(drill 0.254)
		(layers "F.Cu" "B.Cu")
		(net "SGPIO_BMC_CLK")
	)
	(segment
		(start 379.290072 -74.661522)
		(end 378.521722 -74.661522)
		(width 0.10795)
		(layer "B.Cu")
		(net "SGPIO_BMC_CLK")
	)
	(segment
		(start 378.521722 -74.661522)
		(end 378.3584 -74.4982)
		(width 0.10795)
		(layer "B.Cu")
		(net "SGPIO_BMC_CLK")
	)
	(segment
		(start 404.96109 -27.036268)
		(end 405.74087 -27.036268)
		(width 0.089408)
		(layer "In2.Cu")
		(net "SGPIO_BMC_CLK")
	)
	(segment
		(start 378.81941 -70.721728)
		(end 379.685042 -69.856096)
		(width 0.089408)
		(layer "In2.Cu")
		(net "SGPIO_BMC_CLK")
	)
	(segment
		(start 382.164844 -51.161696)
		(end 382.16459 -51.161442)
		(width 0.089408)
		(layer "In2.Cu")
		(net "SGPIO_BMC_CLK")
	)
	(segment
		(start 390.07542 -29.848556)
		(end 391.903204 -29.848556)
		(width 0.089408)
		(layer "In2.Cu")
		(net "SGPIO_BMC_CLK")
	)
	(segment
		(start 378.91212 -74.444098)
		(end 377.93549 -73.467468)
		(width 0.089408)
		(layer "In2.Cu")
		(net "SGPIO_BMC_CLK")
	)
	(segment
		(start 382.16459 -46.55947)
		(end 384.347974 -44.376086)
		(width 0.089408)
		(layer "In2.Cu")
		(net "SGPIO_BMC_CLK")
	)
	(segment
		(start 380.156212 -68.991988)
		(end 380.156974 -68.991988)
		(width 0.089408)
		(layer "In2.Cu")
		(net "SGPIO_BMC_CLK")
	)
	(segment
		(start 377.93549 -73.467468)
		(end 377.93549 -70.886828)
		(width 0.089408)
		(layer "In2.Cu")
		(net "SGPIO_BMC_CLK")
	)
	(segment
		(start 409.709874 -26.559764)
		(end 413.18053 -26.559764)
		(width 0.089408)
		(layer "In2.Cu")
		(net "SGPIO_BMC_CLK")
	)
	(segment
		(start 381.97536 -56.308498)
		(end 381.97536 -51.593496)
		(width 0.089408)
		(layer "In2.Cu")
		(net "SGPIO_BMC_CLK")
	)
	(segment
		(start 382.135126 -56.468264)
		(end 381.97536 -56.308498)
		(width 0.089408)
		(layer "In2.Cu")
		(net "SGPIO_BMC_CLK")
	)
	(segment
		(start 388.649464 -31.274512)
		(end 390.07542 -29.848556)
		(width 0.089408)
		(layer "In2.Cu")
		(net "SGPIO_BMC_CLK")
	)
	(segment
		(start 400.162776 -28.648914)
		(end 400.616166 -29.102304)
		(width 0.089408)
		(layer "In2.Cu")
		(net "SGPIO_BMC_CLK")
	)
	(segment
		(start 384.347974 -44.376086)
		(end 384.347974 -41.176956)
		(width 0.089408)
		(layer "In2.Cu")
		(net "SGPIO_BMC_CLK")
	)
	(segment
		(start 380.156974 -68.991988)
		(end 382.94056 -66.208402)
		(width 0.089408)
		(layer "In2.Cu")
		(net "SGPIO_BMC_CLK")
	)
	(segment
		(start 379.072648 -74.444098)
		(end 378.91212 -74.444098)
		(width 0.089408)
		(layer "In2.Cu")
		(net "SGPIO_BMC_CLK")
	)
	(segment
		(start 403.097746 -28.131008)
		(end 403.86635 -28.131008)
		(width 0.089408)
		(layer "In2.Cu")
		(net "SGPIO_BMC_CLK")
	)
	(segment
		(start 393.102846 -28.648914)
		(end 400.162776 -28.648914)
		(width 0.089408)
		(layer "In2.Cu")
		(net "SGPIO_BMC_CLK")
	)
	(segment
		(start 417.953698 -26.18994)
		(end 418.592 -25.551638)
		(width 0.089408)
		(layer "In2.Cu")
		(net "SGPIO_BMC_CLK")
	)
	(segment
		(start 406.83815 -27.305)
		(end 407.166064 -27.632914)
		(width 0.089408)
		(layer "In2.Cu")
		(net "SGPIO_BMC_CLK")
	)
	(segment
		(start 408.636724 -27.632914)
		(end 409.709874 -26.559764)
		(width 0.089408)
		(layer "In2.Cu")
		(net "SGPIO_BMC_CLK")
	)
	(segment
		(start 382.94056 -64.175132)
		(end 381.546608 -62.78118)
		(width 0.089408)
		(layer "In2.Cu")
		(net "SGPIO_BMC_CLK")
	)
	(segment
		(start 379.290072 -74.661522)
		(end 379.072648 -74.444098)
		(width 0.089408)
		(layer "In2.Cu")
		(net "SGPIO_BMC_CLK")
	)
	(segment
		(start 382.164844 -51.404012)
		(end 382.164844 -51.161696)
		(width 0.089408)
		(layer "In2.Cu")
		(net "SGPIO_BMC_CLK")
	)
	(segment
		(start 386.486654 -35.950398)
		(end 386.486654 -34.177732)
		(width 0.089408)
		(layer "In2.Cu")
		(net "SGPIO_BMC_CLK")
	)
	(segment
		(start 378.10059 -70.721728)
		(end 378.81941 -70.721728)
		(width 0.089408)
		(layer "In2.Cu")
		(net "SGPIO_BMC_CLK")
	)
	(segment
		(start 402.12645 -29.102304)
		(end 403.097746 -28.131008)
		(width 0.089408)
		(layer "In2.Cu")
		(net "SGPIO_BMC_CLK")
	)
	(segment
		(start 381.546608 -60.413392)
		(end 382.135126 -59.824874)
		(width 0.089408)
		(layer "In2.Cu")
		(net "SGPIO_BMC_CLK")
	)
	(segment
		(start 379.685042 -69.856096)
		(end 379.685042 -69.463158)
		(width 0.089408)
		(layer "In2.Cu")
		(net "SGPIO_BMC_CLK")
	)
	(segment
		(start 388.649464 -32.014922)
		(end 388.649464 -31.274512)
		(width 0.089408)
		(layer "In2.Cu")
		(net "SGPIO_BMC_CLK")
	)
	(segment
		(start 413.18053 -26.559764)
		(end 413.550354 -26.18994)
		(width 0.089408)
		(layer "In2.Cu")
		(net "SGPIO_BMC_CLK")
	)
	(segment
		(start 379.685042 -69.463158)
		(end 380.156212 -68.991988)
		(width 0.089408)
		(layer "In2.Cu")
		(net "SGPIO_BMC_CLK")
	)
	(segment
		(start 407.166064 -27.632914)
		(end 408.636724 -27.632914)
		(width 0.089408)
		(layer "In2.Cu")
		(net "SGPIO_BMC_CLK")
	)
	(segment
		(start 383.608072 -40.437054)
		(end 383.608072 -38.82898)
		(width 0.089408)
		(layer "In2.Cu")
		(net "SGPIO_BMC_CLK")
	)
	(segment
		(start 381.546608 -62.78118)
		(end 381.546608 -60.413392)
		(width 0.089408)
		(layer "In2.Cu")
		(net "SGPIO_BMC_CLK")
	)
	(segment
		(start 400.616166 -29.102304)
		(end 402.12645 -29.102304)
		(width 0.089408)
		(layer "In2.Cu")
		(net "SGPIO_BMC_CLK")
	)
	(segment
		(start 406.009602 -27.305)
		(end 406.83815 -27.305)
		(width 0.089408)
		(layer "In2.Cu")
		(net "SGPIO_BMC_CLK")
	)
	(segment
		(start 386.486654 -34.177732)
		(end 388.649464 -32.014922)
		(width 0.089408)
		(layer "In2.Cu")
		(net "SGPIO_BMC_CLK")
	)
	(segment
		(start 405.74087 -27.036268)
		(end 406.009602 -27.305)
		(width 0.089408)
		(layer "In2.Cu")
		(net "SGPIO_BMC_CLK")
	)
	(segment
		(start 382.94056 -66.208402)
		(end 382.94056 -64.175132)
		(width 0.089408)
		(layer "In2.Cu")
		(net "SGPIO_BMC_CLK")
	)
	(segment
		(start 403.86635 -28.131008)
		(end 404.96109 -27.036268)
		(width 0.089408)
		(layer "In2.Cu")
		(net "SGPIO_BMC_CLK")
	)
	(segment
		(start 382.135126 -59.824874)
		(end 382.135126 -56.468264)
		(width 0.089408)
		(layer "In2.Cu")
		(net "SGPIO_BMC_CLK")
	)
	(segment
		(start 377.93549 -70.886828)
		(end 378.10059 -70.721728)
		(width 0.089408)
		(layer "In2.Cu")
		(net "SGPIO_BMC_CLK")
	)
	(segment
		(start 413.550354 -26.18994)
		(end 417.953698 -26.18994)
		(width 0.089408)
		(layer "In2.Cu")
		(net "SGPIO_BMC_CLK")
	)
	(segment
		(start 391.903204 -29.848556)
		(end 393.102846 -28.648914)
		(width 0.089408)
		(layer "In2.Cu")
		(net "SGPIO_BMC_CLK")
	)
	(segment
		(start 381.97536 -51.593496)
		(end 382.164844 -51.404012)
		(width 0.089408)
		(layer "In2.Cu")
		(net "SGPIO_BMC_CLK")
	)
	(segment
		(start 384.347974 -41.176956)
		(end 383.608072 -40.437054)
		(width 0.089408)
		(layer "In2.Cu")
		(net "SGPIO_BMC_CLK")
	)
	(segment
		(start 383.608072 -38.82898)
		(end 386.486654 -35.950398)
		(width 0.089408)
		(layer "In2.Cu")
		(net "SGPIO_BMC_CLK")
	)
	(segment
		(start 382.16459 -51.161442)
		(end 382.16459 -46.55947)
		(width 0.089408)
		(layer "In2.Cu")
		(net "SGPIO_BMC_CLK")
	)
	(segment
		(start 371.145308 -79.094838)
		(end 371.545104 -78.695042)
		(width 0.10795)
		(layer "F.Cu")
		(net "RST_CD_CPU1_POR_N")
	)
	(segment
		(start 121.646188 -83.641184)
		(end 122.217688 -83.641184)
		(width 0.1016)
		(layer "F.Cu")
		(net "RST_CD_CPU1_POR_N")
	)
	(via
		(at 340.6267 -126.56185)
		(size 0.508)
		(drill 0.254)
		(layers "F.Cu" "B.Cu")
		(net "RST_CD_CPU1_POR_N")
	)
	(via
		(at 122.217688 -83.641184)
		(size 0.508)
		(drill 0.254)
		(layers "F.Cu" "B.Cu")
		(net "RST_CD_CPU1_POR_N")
	)
	(via
		(at 376.4788 -121.3612)
		(size 0.508)
		(drill 0.254)
		(layers "F.Cu" "B.Cu")
		(net "RST_CD_CPU1_POR_N")
	)
	(via
		(at 364.834932 -133.386068)
		(size 0.508)
		(drill 0.254)
		(layers "F.Cu" "B.Cu")
		(net "RST_CD_CPU1_POR_N")
	)
	(via
		(at 324.4088 -136.9314)
		(size 0.508)
		(drill 0.254)
		(layers "F.Cu" "B.Cu")
		(net "RST_CD_CPU1_POR_N")
	)
	(via
		(at 371.145308 -79.094838)
		(size 0.4572)
		(drill 0.2032)
		(layers "F.Cu" "B.Cu")
		(net "RST_CD_CPU1_POR_N")
	)
	(via
		(at 167.40378 -124.132086)
		(size 0.508)
		(drill 0.254)
		(layers "F.Cu" "B.Cu")
		(net "RST_CD_CPU1_POR_N")
	)
	(via
		(at 191.3382 -150.7744)
		(size 0.508)
		(drill 0.254)
		(layers "F.Cu" "B.Cu")
		(net "RST_CD_CPU1_POR_N")
	)
	(segment
		(start 167.456866 -124.079)
		(end 167.40378 -124.132086)
		(width 0.10795)
		(layer "B.Cu")
		(net "RST_CD_CPU1_POR_N")
	)
	(segment
		(start 168.148 -124.079)
		(end 167.456866 -124.079)
		(width 0.10795)
		(layer "B.Cu")
		(net "RST_CD_CPU1_POR_N")
	)
	(segment
		(start 345.397328 -126.982474)
		(end 345.754706 -127.339852)
		(width 0.089408)
		(layer "In2.Cu")
		(net "RST_CD_CPU1_POR_N")
	)
	(segment
		(start 191.300608 -153.771346)
		(end 191.300608 -156.883608)
		(width 0.089408)
		(layer "In2.Cu")
		(net "RST_CD_CPU1_POR_N")
	)
	(segment
		(start 326.566022 -152.59812)
		(end 324.47992 -150.512018)
		(width 0.089408)
		(layer "In2.Cu")
		(net "RST_CD_CPU1_POR_N")
	)
	(segment
		(start 323.27088 -138.47572)
		(end 324.4088 -137.3378)
		(width 0.089408)
		(layer "In2.Cu")
		(net "RST_CD_CPU1_POR_N")
	)
	(segment
		(start 329.607672 -155.427934)
		(end 329.607672 -154.360372)
		(width 0.089408)
		(layer "In2.Cu")
		(net "RST_CD_CPU1_POR_N")
	)
	(segment
		(start 365.118142 -133.102858)
		(end 364.834932 -133.386068)
		(width 0.089408)
		(layer "In2.Cu")
		(net "RST_CD_CPU1_POR_N")
	)
	(segment
		(start 277.630128 -156.557472)
		(end 278.172418 -156.015182)
		(width 0.089408)
		(layer "In2.Cu")
		(net "RST_CD_CPU1_POR_N")
	)
	(segment
		(start 329.607672 -154.360372)
		(end 327.84542 -152.59812)
		(width 0.089408)
		(layer "In2.Cu")
		(net "RST_CD_CPU1_POR_N")
	)
	(segment
		(start 278.567134 -156.01569)
		(end 323.70649 -156.01569)
		(width 0.089408)
		(layer "In2.Cu")
		(net "RST_CD_CPU1_POR_N")
	)
	(segment
		(start 348.685612 -127.339852)
		(end 349.069152 -127.723392)
		(width 0.089408)
		(layer "In2.Cu")
		(net "RST_CD_CPU1_POR_N")
	)
	(segment
		(start 361.009184 -127.506984)
		(end 365.118142 -131.615942)
		(width 0.089408)
		(layer "In2.Cu")
		(net "RST_CD_CPU1_POR_N")
	)
	(segment
		(start 191.218058 -150.894542)
		(end 191.218058 -153.688796)
		(width 0.089408)
		(layer "In2.Cu")
		(net "RST_CD_CPU1_POR_N")
	)
	(segment
		(start 354.411788 -127.723392)
		(end 354.628196 -127.506984)
		(width 0.089408)
		(layer "In2.Cu")
		(net "RST_CD_CPU1_POR_N")
	)
	(segment
		(start 330.95184 -156.772102)
		(end 329.607672 -155.427934)
		(width 0.089408)
		(layer "In2.Cu")
		(net "RST_CD_CPU1_POR_N")
	)
	(segment
		(start 265.288776 -156.557472)
		(end 277.630128 -156.557472)
		(width 0.089408)
		(layer "In2.Cu")
		(net "RST_CD_CPU1_POR_N")
	)
	(segment
		(start 191.53886 -157.12186)
		(end 264.724388 -157.12186)
		(width 0.089408)
		(layer "In2.Cu")
		(net "RST_CD_CPU1_POR_N")
	)
	(segment
		(start 278.566626 -156.015182)
		(end 278.567134 -156.01569)
		(width 0.089408)
		(layer "In2.Cu")
		(net "RST_CD_CPU1_POR_N")
	)
	(segment
		(start 323.70649 -156.01569)
		(end 325.09333 -157.40253)
		(width 0.089408)
		(layer "In2.Cu")
		(net "RST_CD_CPU1_POR_N")
	)
	(segment
		(start 264.724388 -157.12186)
		(end 265.288776 -156.557472)
		(width 0.089408)
		(layer "In2.Cu")
		(net "RST_CD_CPU1_POR_N")
	)
	(segment
		(start 340.6267 -126.56185)
		(end 341.047324 -126.982474)
		(width 0.089408)
		(layer "In2.Cu")
		(net "RST_CD_CPU1_POR_N")
	)
	(segment
		(start 330.95184 -157.168088)
		(end 330.95184 -156.772102)
		(width 0.089408)
		(layer "In2.Cu")
		(net "RST_CD_CPU1_POR_N")
	)
	(segment
		(start 324.47992 -141.61262)
		(end 323.27088 -140.40358)
		(width 0.089408)
		(layer "In2.Cu")
		(net "RST_CD_CPU1_POR_N")
	)
	(segment
		(start 330.717398 -157.40253)
		(end 330.95184 -157.168088)
		(width 0.089408)
		(layer "In2.Cu")
		(net "RST_CD_CPU1_POR_N")
	)
	(segment
		(start 325.09333 -157.40253)
		(end 330.717398 -157.40253)
		(width 0.089408)
		(layer "In2.Cu")
		(net "RST_CD_CPU1_POR_N")
	)
	(segment
		(start 345.754706 -127.339852)
		(end 348.685612 -127.339852)
		(width 0.089408)
		(layer "In2.Cu")
		(net "RST_CD_CPU1_POR_N")
	)
	(segment
		(start 341.047324 -126.982474)
		(end 345.397328 -126.982474)
		(width 0.089408)
		(layer "In2.Cu")
		(net "RST_CD_CPU1_POR_N")
	)
	(segment
		(start 191.300608 -156.883608)
		(end 191.53886 -157.12186)
		(width 0.089408)
		(layer "In2.Cu")
		(net "RST_CD_CPU1_POR_N")
	)
	(segment
		(start 324.4088 -137.3378)
		(end 324.4088 -136.9314)
		(width 0.089408)
		(layer "In2.Cu")
		(net "RST_CD_CPU1_POR_N")
	)
	(segment
		(start 365.118142 -131.615942)
		(end 365.118142 -133.102858)
		(width 0.089408)
		(layer "In2.Cu")
		(net "RST_CD_CPU1_POR_N")
	)
	(segment
		(start 349.069152 -127.723392)
		(end 354.411788 -127.723392)
		(width 0.089408)
		(layer "In2.Cu")
		(net "RST_CD_CPU1_POR_N")
	)
	(segment
		(start 323.27088 -140.40358)
		(end 323.27088 -138.47572)
		(width 0.089408)
		(layer "In2.Cu")
		(net "RST_CD_CPU1_POR_N")
	)
	(segment
		(start 327.84542 -152.59812)
		(end 326.566022 -152.59812)
		(width 0.089408)
		(layer "In2.Cu")
		(net "RST_CD_CPU1_POR_N")
	)
	(segment
		(start 324.47992 -150.512018)
		(end 324.47992 -141.61262)
		(width 0.089408)
		(layer "In2.Cu")
		(net "RST_CD_CPU1_POR_N")
	)
	(segment
		(start 278.172418 -156.015182)
		(end 278.566626 -156.015182)
		(width 0.089408)
		(layer "In2.Cu")
		(net "RST_CD_CPU1_POR_N")
	)
	(segment
		(start 191.218058 -153.688796)
		(end 191.300608 -153.771346)
		(width 0.089408)
		(layer "In2.Cu")
		(net "RST_CD_CPU1_POR_N")
	)
	(segment
		(start 191.3382 -150.7744)
		(end 191.218058 -150.894542)
		(width 0.089408)
		(layer "In2.Cu")
		(net "RST_CD_CPU1_POR_N")
	)
	(segment
		(start 354.628196 -127.506984)
		(end 361.009184 -127.506984)
		(width 0.089408)
		(layer "In2.Cu")
		(net "RST_CD_CPU1_POR_N")
	)
	(segment
		(start 340.6267 -126.56185)
		(end 340.6267 -126.8095)
		(width 0.089408)
		(layer "In9.Cu")
		(net "RST_CD_CPU1_POR_N")
	)
	(segment
		(start 325.819262 -136.912096)
		(end 324.428104 -136.912096)
		(width 0.089408)
		(layer "In9.Cu")
		(net "RST_CD_CPU1_POR_N")
	)
	(segment
		(start 374.4468 -121.3612)
		(end 376.4788 -121.3612)
		(width 0.089408)
		(layer "In9.Cu")
		(net "RST_CD_CPU1_POR_N")
	)
	(segment
		(start 335.697322 -131.8387)
		(end 334.46466 -131.8387)
		(width 0.089408)
		(layer "In9.Cu")
		(net "RST_CD_CPU1_POR_N")
	)
	(segment
		(start 331.39253 -134.91083)
		(end 331.39253 -135.625586)
		(width 0.089408)
		(layer "In9.Cu")
		(net "RST_CD_CPU1_POR_N")
	)
	(segment
		(start 365.94542 -133.386068)
		(end 371.606572 -127.724916)
		(width 0.089408)
		(layer "In9.Cu")
		(net "RST_CD_CPU1_POR_N")
	)
	(segment
		(start 340.6267 -126.8095)
		(end 340.01583 -127.42037)
		(width 0.089408)
		(layer "In9.Cu")
		(net "RST_CD_CPU1_POR_N")
	)
	(segment
		(start 372.389146 -123.418854)
		(end 374.4468 -121.3612)
		(width 0.089408)
		(layer "In9.Cu")
		(net "RST_CD_CPU1_POR_N")
	)
	(segment
		(start 326.053704 -137.146538)
		(end 325.819262 -136.912096)
		(width 0.089408)
		(layer "In9.Cu")
		(net "RST_CD_CPU1_POR_N")
	)
	(segment
		(start 329.858116 -137.16)
		(end 326.053704 -137.16)
		(width 0.089408)
		(layer "In9.Cu")
		(net "RST_CD_CPU1_POR_N")
	)
	(segment
		(start 340.01583 -127.42037)
		(end 338.40166 -127.42037)
		(width 0.089408)
		(layer "In9.Cu")
		(net "RST_CD_CPU1_POR_N")
	)
	(segment
		(start 337.446874 -128.375156)
		(end 337.446874 -130.089148)
		(width 0.089408)
		(layer "In9.Cu")
		(net "RST_CD_CPU1_POR_N")
	)
	(segment
		(start 326.053704 -137.16)
		(end 326.053704 -137.146538)
		(width 0.089408)
		(layer "In9.Cu")
		(net "RST_CD_CPU1_POR_N")
	)
	(segment
		(start 372.389146 -125.169168)
		(end 372.389146 -123.418854)
		(width 0.089408)
		(layer "In9.Cu")
		(net "RST_CD_CPU1_POR_N")
	)
	(segment
		(start 364.834932 -133.386068)
		(end 365.94542 -133.386068)
		(width 0.089408)
		(layer "In9.Cu")
		(net "RST_CD_CPU1_POR_N")
	)
	(segment
		(start 331.39253 -135.625586)
		(end 329.858116 -137.16)
		(width 0.089408)
		(layer "In9.Cu")
		(net "RST_CD_CPU1_POR_N")
	)
	(segment
		(start 371.606572 -125.951742)
		(end 372.389146 -125.169168)
		(width 0.089408)
		(layer "In9.Cu")
		(net "RST_CD_CPU1_POR_N")
	)
	(segment
		(start 371.606572 -127.724916)
		(end 371.606572 -125.951742)
		(width 0.089408)
		(layer "In9.Cu")
		(net "RST_CD_CPU1_POR_N")
	)
	(segment
		(start 338.40166 -127.42037)
		(end 337.446874 -128.375156)
		(width 0.089408)
		(layer "In9.Cu")
		(net "RST_CD_CPU1_POR_N")
	)
	(segment
		(start 334.46466 -131.8387)
		(end 331.39253 -134.91083)
		(width 0.089408)
		(layer "In9.Cu")
		(net "RST_CD_CPU1_POR_N")
	)
	(segment
		(start 337.446874 -130.089148)
		(end 335.697322 -131.8387)
		(width 0.089408)
		(layer "In9.Cu")
		(net "RST_CD_CPU1_POR_N")
	)
	(segment
		(start 324.428104 -136.912096)
		(end 324.4088 -136.9314)
		(width 0.089408)
		(layer "In9.Cu")
		(net "RST_CD_CPU1_POR_N")
	)
	(segment
		(start 377.92787 -112.881918)
		(end 377.92787 -112.462818)
		(width 0.089408)
		(layer "In11.Cu")
		(net "RST_CD_CPU1_POR_N")
	)
	(segment
		(start 127.3048 -89.154)
		(end 127.727456 -89.154)
		(width 0.089408)
		(layer "In11.Cu")
		(net "RST_CD_CPU1_POR_N")
	)
	(segment
		(start 122.245374 -86.214204)
		(end 122.60834 -86.214204)
		(width 0.089408)
		(layer "In11.Cu")
		(net "RST_CD_CPU1_POR_N")
	)
	(segment
		(start 379.708156 -100.579936)
		(end 381.463804 -100.579936)
		(width 0.089408)
		(layer "In11.Cu")
		(net "RST_CD_CPU1_POR_N")
	)
	(segment
		(start 375.1072 -92.969334)
		(end 375.1072 -92.023946)
		(width 0.089408)
		(layer "In11.Cu")
		(net "RST_CD_CPU1_POR_N")
	)
	(segment
		(start 377.92787 -112.462818)
		(end 377.43257 -111.967518)
		(width 0.089408)
		(layer "In11.Cu")
		(net "RST_CD_CPU1_POR_N")
	)
	(segment
		(start 141.0208 -99.947476)
		(end 142.567152 -101.493828)
		(width 0.089408)
		(layer "In11.Cu")
		(net "RST_CD_CPU1_POR_N")
	)
	(segment
		(start 377.414536 -113.395252)
		(end 377.92787 -112.881918)
		(width 0.089408)
		(layer "In11.Cu")
		(net "RST_CD_CPU1_POR_N")
	)
	(segment
		(start 132.052314 -91.662758)
		(end 132.35432 -91.964764)
		(width 0.089408)
		(layer "In11.Cu")
		(net "RST_CD_CPU1_POR_N")
	)
	(segment
		(start 379.41377 -104.68737)
		(end 379.41377 -104.17683)
		(width 0.089408)
		(layer "In11.Cu")
		(net "RST_CD_CPU1_POR_N")
	)
	(segment
		(start 379.3236 -106.25328)
		(end 379.3236 -105.9942)
		(width 0.089408)
		(layer "In11.Cu")
		(net "RST_CD_CPU1_POR_N")
	)
	(segment
		(start 379.349 -100.939092)
		(end 379.708156 -100.579936)
		(width 0.089408)
		(layer "In11.Cu")
		(net "RST_CD_CPU1_POR_N")
	)
	(segment
		(start 159.65932 -116.729002)
		(end 161.759138 -118.82882)
		(width 0.089408)
		(layer "In11.Cu")
		(net "RST_CD_CPU1_POR_N")
	)
	(segment
		(start 123.769374 -87.011764)
		(end 123.917964 -87.011764)
		(width 0.089408)
		(layer "In11.Cu")
		(net "RST_CD_CPU1_POR_N")
	)
	(segment
		(start 374.066816 -87.404702)
		(end 373.5959 -86.933786)
		(width 0.089408)
		(layer "In11.Cu")
		(net "RST_CD_CPU1_POR_N")
	)
	(segment
		(start 159.524446 -130.080258)
		(end 159.524192 -130.08102)
		(width 0.089408)
		(layer "In11.Cu")
		(net "RST_CD_CPU1_POR_N")
	)
	(segment
		(start 377.0376 -120.8024)
		(end 377.0376 -120.61698)
		(width 0.089408)
		(layer "In11.Cu")
		(net "RST_CD_CPU1_POR_N")
	)
	(segment
		(start 142.567152 -101.493828)
		(end 142.567152 -103.467408)
		(width 0.089408)
		(layer "In11.Cu")
		(net "RST_CD_CPU1_POR_N")
	)
	(segment
		(start 381.69723 -100.015802)
		(end 381.20193 -99.520502)
		(width 0.089408)
		(layer "In11.Cu")
		(net "RST_CD_CPU1_POR_N")
	)
	(segment
		(start 378.91847 -96.774762)
		(end 378.42317 -96.279462)
		(width 0.089408)
		(layer "In11.Cu")
		(net "RST_CD_CPU1_POR_N")
	)
	(segment
		(start 377.43257 -111.549942)
		(end 377.492768 -111.489744)
		(width 0.089408)
		(layer "In11.Cu")
		(net "RST_CD_CPU1_POR_N")
	)
	(segment
		(start 140.645134 -96.849184)
		(end 140.645134 -97.179892)
		(width 0.089408)
		(layer "In11.Cu")
		(net "RST_CD_CPU1_POR_N")
	)
	(segment
		(start 381.69723 -100.34651)
		(end 381.69723 -100.015802)
		(width 0.089408)
		(layer "In11.Cu")
		(net "RST_CD_CPU1_POR_N")
	)
	(segment
		(start 140.6398 -96.7486)
		(end 140.6398 -96.84385)
		(width 0.089408)
		(layer "In11.Cu")
		(net "RST_CD_CPU1_POR_N")
	)
	(segment
		(start 138.557254 -95.625158)
		(end 138.920474 -95.625158)
		(width 0.089408)
		(layer "In11.Cu")
		(net "RST_CD_CPU1_POR_N")
	)
	(segment
		(start 130.129788 -90.466418)
		(end 130.637534 -90.974164)
		(width 0.089408)
		(layer "In11.Cu")
		(net "RST_CD_CPU1_POR_N")
	)
	(segment
		(start 375.1072 -92.023946)
		(end 374.066816 -90.983562)
		(width 0.089408)
		(layer "In11.Cu")
		(net "RST_CD_CPU1_POR_N")
	)
	(segment
		(start 136.977628 -94.634304)
		(end 137.280142 -94.936818)
		(width 0.089408)
		(layer "In11.Cu")
		(net "RST_CD_CPU1_POR_N")
	)
	(segment
		(start 131.0005 -90.974164)
		(end 131.689094 -91.662758)
		(width 0.089408)
		(layer "In11.Cu")
		(net "RST_CD_CPU1_POR_N")
	)
	(segment
		(start 129.05613 -90.1192)
		(end 129.43713 -90.1192)
		(width 0.089408)
		(layer "In11.Cu")
		(net "RST_CD_CPU1_POR_N")
	)
	(segment
		(start 376.4788 -121.3612)
		(end 377.0376 -120.8024)
		(width 0.089408)
		(layer "In11.Cu")
		(net "RST_CD_CPU1_POR_N")
	)
	(segment
		(start 126.344934 -88.497918)
		(end 126.648718 -88.497918)
		(width 0.089408)
		(layer "In11.Cu")
		(net "RST_CD_CPU1_POR_N")
	)
	(segment
		(start 371.171724 -82.525362)
		(end 371.171724 -80.440276)
		(width 0.089408)
		(layer "In11.Cu")
		(net "RST_CD_CPU1_POR_N")
	)
	(segment
		(start 128.425448 -89.488518)
		(end 129.05613 -90.1192)
		(width 0.089408)
		(layer "In11.Cu")
		(net "RST_CD_CPU1_POR_N")
	)
	(segment
		(start 371.518688 -79.672434)
		(end 371.145308 -79.299054)
		(width 0.089408)
		(layer "In11.Cu")
		(net "RST_CD_CPU1_POR_N")
	)
	(segment
		(start 121.818908 -84.039964)
		(end 121.818908 -85.787738)
		(width 0.089408)
		(layer "In11.Cu")
		(net "RST_CD_CPU1_POR_N")
	)
	(segment
		(start 165.517576 -121.893076)
		(end 167.40378 -123.77928)
		(width 0.089408)
		(layer "In11.Cu")
		(net "RST_CD_CPU1_POR_N")
	)
	(segment
		(start 140.462 -96.5708)
		(end 140.6398 -96.7486)
		(width 0.089408)
		(layer "In11.Cu")
		(net "RST_CD_CPU1_POR_N")
	)
	(segment
		(start 129.784348 -90.466418)
		(end 130.129788 -90.466418)
		(width 0.089408)
		(layer "In11.Cu")
		(net "RST_CD_CPU1_POR_N")
	)
	(segment
		(start 140.0302 -96.5708)
		(end 140.462 -96.5708)
		(width 0.089408)
		(layer "In11.Cu")
		(net "RST_CD_CPU1_POR_N")
	)
	(segment
		(start 140.645134 -97.179892)
		(end 140.6398 -97.185226)
		(width 0.089408)
		(layer "In11.Cu")
		(net "RST_CD_CPU1_POR_N")
	)
	(segment
		(start 379.212856 -98.923856)
		(end 378.91847 -98.62947)
		(width 0.089408)
		(layer "In11.Cu")
		(net "RST_CD_CPU1_POR_N")
	)
	(segment
		(start 133.576314 -92.460318)
		(end 134.07136 -92.955364)
		(width 0.089408)
		(layer "In11.Cu")
		(net "RST_CD_CPU1_POR_N")
	)
	(segment
		(start 186.977782 -148.090636)
		(end 190.026036 -148.090636)
		(width 0.089408)
		(layer "In11.Cu")
		(net "RST_CD_CPU1_POR_N")
	)
	(segment
		(start 381.20193 -99.157282)
		(end 380.968504 -98.923856)
		(width 0.089408)
		(layer "In11.Cu")
		(net "RST_CD_CPU1_POR_N")
	)
	(segment
		(start 374.066816 -90.983562)
		(end 374.066816 -87.404702)
		(width 0.089408)
		(layer "In11.Cu")
		(net "RST_CD_CPU1_POR_N")
	)
	(segment
		(start 378.42317 -95.916242)
		(end 377.093988 -94.58706)
		(width 0.089408)
		(layer "In11.Cu")
		(net "RST_CD_CPU1_POR_N")
	)
	(segment
		(start 377.0376 -120.61698)
		(end 377.923298 -119.731282)
		(width 0.089408)
		(layer "In11.Cu")
		(net "RST_CD_CPU1_POR_N")
	)
	(segment
		(start 126.648718 -88.497918)
		(end 127.3048 -89.154)
		(width 0.089408)
		(layer "In11.Cu")
		(net "RST_CD_CPU1_POR_N")
	)
	(segment
		(start 379.3236 -105.9942)
		(end 379.71603 -105.60177)
		(width 0.089408)
		(layer "In11.Cu")
		(net "RST_CD_CPU1_POR_N")
	)
	(segment
		(start 371.145308 -79.299054)
		(end 371.145308 -79.094838)
		(width 0.089408)
		(layer "In11.Cu")
		(net "RST_CD_CPU1_POR_N")
	)
	(segment
		(start 137.280142 -94.936818)
		(end 137.868914 -94.936818)
		(width 0.089408)
		(layer "In11.Cu")
		(net "RST_CD_CPU1_POR_N")
	)
	(segment
		(start 127.727456 -89.154)
		(end 128.061974 -89.488518)
		(width 0.089408)
		(layer "In11.Cu")
		(net "RST_CD_CPU1_POR_N")
	)
	(segment
		(start 373.5959 -86.933786)
		(end 373.5959 -84.949538)
		(width 0.089408)
		(layer "In11.Cu")
		(net "RST_CD_CPU1_POR_N")
	)
	(segment
		(start 166.057072 -125.478794)
		(end 164.12591 -125.478794)
		(width 0.089408)
		(layer "In11.Cu")
		(net "RST_CD_CPU1_POR_N")
	)
	(segment
		(start 377.454922 -106.6292)
		(end 378.94768 -106.6292)
		(width 0.089408)
		(layer "In11.Cu")
		(net "RST_CD_CPU1_POR_N")
	)
	(segment
		(start 379.71603 -102.98303)
		(end 378.91847 -102.18547)
		(width 0.089408)
		(layer "In11.Cu")
		(net "RST_CD_CPU1_POR_N")
	)
	(segment
		(start 377.093988 -94.58706)
		(end 376.724926 -94.58706)
		(width 0.089408)
		(layer "In11.Cu")
		(net "RST_CD_CPU1_POR_N")
	)
	(segment
		(start 140.6398 -97.185226)
		(end 140.6398 -99.2886)
		(width 0.089408)
		(layer "In11.Cu")
		(net "RST_CD_CPU1_POR_N")
	)
	(segment
		(start 380.968504 -98.923856)
		(end 379.212856 -98.923856)
		(width 0.089408)
		(layer "In11.Cu")
		(net "RST_CD_CPU1_POR_N")
	)
	(segment
		(start 125.84938 -88.002364)
		(end 126.344934 -88.497918)
		(width 0.089408)
		(layer "In11.Cu")
		(net "RST_CD_CPU1_POR_N")
	)
	(segment
		(start 135.72363 -94.107)
		(end 136.2202 -94.107)
		(width 0.089408)
		(layer "In11.Cu")
		(net "RST_CD_CPU1_POR_N")
	)
	(segment
		(start 159.524192 -141.650212)
		(end 160.44418 -142.5702)
		(width 0.089408)
		(layer "In11.Cu")
		(net "RST_CD_CPU1_POR_N")
	)
	(segment
		(start 377.414536 -117.215666)
		(end 377.414536 -113.395252)
		(width 0.089408)
		(layer "In11.Cu")
		(net "RST_CD_CPU1_POR_N")
	)
	(segment
		(start 142.567152 -103.467408)
		(end 155.828746 -116.729002)
		(width 0.089408)
		(layer "In11.Cu")
		(net "RST_CD_CPU1_POR_N")
	)
	(segment
		(start 137.868914 -94.936818)
		(end 138.557254 -95.625158)
		(width 0.089408)
		(layer "In11.Cu")
		(net "RST_CD_CPU1_POR_N")
	)
	(segment
		(start 164.12591 -125.478794)
		(end 159.524446 -130.080258)
		(width 0.089408)
		(layer "In11.Cu")
		(net "RST_CD_CPU1_POR_N")
	)
	(segment
		(start 134.331964 -92.955364)
		(end 135.020558 -93.643958)
		(width 0.089408)
		(layer "In11.Cu")
		(net "RST_CD_CPU1_POR_N")
	)
	(segment
		(start 167.40378 -124.132086)
		(end 166.057072 -125.478794)
		(width 0.089408)
		(layer "In11.Cu")
		(net "RST_CD_CPU1_POR_N")
	)
	(segment
		(start 371.518688 -80.093312)
		(end 371.518688 -79.672434)
		(width 0.089408)
		(layer "In11.Cu")
		(net "RST_CD_CPU1_POR_N")
	)
	(segment
		(start 130.637534 -90.974164)
		(end 131.0005 -90.974164)
		(width 0.089408)
		(layer "In11.Cu")
		(net "RST_CD_CPU1_POR_N")
	)
	(segment
		(start 135.260588 -93.643958)
		(end 135.72363 -94.107)
		(width 0.089408)
		(layer "In11.Cu")
		(net "RST_CD_CPU1_POR_N")
	)
	(segment
		(start 132.35432 -91.964764)
		(end 132.717286 -91.964764)
		(width 0.089408)
		(layer "In11.Cu")
		(net "RST_CD_CPU1_POR_N")
	)
	(segment
		(start 160.44418 -142.5702)
		(end 162.306 -142.5702)
		(width 0.089408)
		(layer "In11.Cu")
		(net "RST_CD_CPU1_POR_N")
	)
	(segment
		(start 155.828746 -116.729002)
		(end 159.65932 -116.729002)
		(width 0.089408)
		(layer "In11.Cu")
		(net "RST_CD_CPU1_POR_N")
	)
	(segment
		(start 379.22073 -97.94367)
		(end 379.22073 -97.21469)
		(width 0.089408)
		(layer "In11.Cu")
		(net "RST_CD_CPU1_POR_N")
	)
	(segment
		(start 141.0208 -99.6696)
		(end 141.0208 -99.947476)
		(width 0.089408)
		(layer "In11.Cu")
		(net "RST_CD_CPU1_POR_N")
	)
	(segment
		(start 381.20193 -99.520502)
		(end 381.20193 -99.157282)
		(width 0.089408)
		(layer "In11.Cu")
		(net "RST_CD_CPU1_POR_N")
	)
	(segment
		(start 185.229754 -146.342608)
		(end 186.977782 -148.090636)
		(width 0.089408)
		(layer "In11.Cu")
		(net "RST_CD_CPU1_POR_N")
	)
	(segment
		(start 190.026036 -148.090636)
		(end 191.3382 -149.4028)
		(width 0.089408)
		(layer "In11.Cu")
		(net "RST_CD_CPU1_POR_N")
	)
	(segment
		(start 378.91847 -96.91243)
		(end 378.91847 -96.774762)
		(width 0.089408)
		(layer "In11.Cu")
		(net "RST_CD_CPU1_POR_N")
	)
	(segment
		(start 378.42317 -96.279462)
		(end 378.42317 -95.916242)
		(width 0.089408)
		(layer "In11.Cu")
		(net "RST_CD_CPU1_POR_N")
	)
	(segment
		(start 379.22073 -97.21469)
		(end 378.91847 -96.91243)
		(width 0.089408)
		(layer "In11.Cu")
		(net "RST_CD_CPU1_POR_N")
	)
	(segment
		(start 135.020558 -93.643958)
		(end 135.260588 -93.643958)
		(width 0.089408)
		(layer "In11.Cu")
		(net "RST_CD_CPU1_POR_N")
	)
	(segment
		(start 123.917964 -87.011764)
		(end 124.587 -87.6808)
		(width 0.089408)
		(layer "In11.Cu")
		(net "RST_CD_CPU1_POR_N")
	)
	(segment
		(start 121.818908 -85.787738)
		(end 122.245374 -86.214204)
		(width 0.089408)
		(layer "In11.Cu")
		(net "RST_CD_CPU1_POR_N")
	)
	(segment
		(start 122.217688 -83.641184)
		(end 121.818908 -84.039964)
		(width 0.089408)
		(layer "In11.Cu")
		(net "RST_CD_CPU1_POR_N")
	)
	(segment
		(start 379.71603 -105.60177)
		(end 379.71603 -104.98963)
		(width 0.089408)
		(layer "In11.Cu")
		(net "RST_CD_CPU1_POR_N")
	)
	(segment
		(start 378.91847 -98.62947)
		(end 378.91847 -98.24593)
		(width 0.089408)
		(layer "In11.Cu")
		(net "RST_CD_CPU1_POR_N")
	)
	(segment
		(start 379.71603 -103.87457)
		(end 379.71603 -102.98303)
		(width 0.089408)
		(layer "In11.Cu")
		(net "RST_CD_CPU1_POR_N")
	)
	(segment
		(start 376.91822 -107.632754)
		(end 376.91822 -107.165902)
		(width 0.089408)
		(layer "In11.Cu")
		(net "RST_CD_CPU1_POR_N")
	)
	(segment
		(start 132.717286 -91.964764)
		(end 133.21284 -92.460318)
		(width 0.089408)
		(layer "In11.Cu")
		(net "RST_CD_CPU1_POR_N")
	)
	(segment
		(start 161.759138 -118.82882)
		(end 163.051744 -118.82882)
		(width 0.089408)
		(layer "In11.Cu")
		(net "RST_CD_CPU1_POR_N")
	)
	(segment
		(start 377.492768 -108.207302)
		(end 376.91822 -107.632754)
		(width 0.089408)
		(layer "In11.Cu")
		(net "RST_CD_CPU1_POR_N")
	)
	(segment
		(start 377.923298 -119.731282)
		(end 377.923298 -117.724428)
		(width 0.089408)
		(layer "In11.Cu")
		(net "RST_CD_CPU1_POR_N")
	)
	(segment
		(start 162.306 -142.5702)
		(end 163.214304 -143.478504)
		(width 0.089408)
		(layer "In11.Cu")
		(net "RST_CD_CPU1_POR_N")
	)
	(segment
		(start 139.22248 -95.927164)
		(end 139.386564 -95.927164)
		(width 0.089408)
		(layer "In11.Cu")
		(net "RST_CD_CPU1_POR_N")
	)
	(segment
		(start 371.171724 -80.440276)
		(end 371.518688 -80.093312)
		(width 0.089408)
		(layer "In11.Cu")
		(net "RST_CD_CPU1_POR_N")
	)
	(segment
		(start 133.21284 -92.460318)
		(end 133.576314 -92.460318)
		(width 0.089408)
		(layer "In11.Cu")
		(net "RST_CD_CPU1_POR_N")
	)
	(segment
		(start 139.386564 -95.927164)
		(end 140.0302 -96.5708)
		(width 0.089408)
		(layer "In11.Cu")
		(net "RST_CD_CPU1_POR_N")
	)
	(segment
		(start 373.5959 -84.949538)
		(end 371.171724 -82.525362)
		(width 0.089408)
		(layer "In11.Cu")
		(net "RST_CD_CPU1_POR_N")
	)
	(segment
		(start 377.492768 -111.489744)
		(end 377.492768 -108.207302)
		(width 0.089408)
		(layer "In11.Cu")
		(net "RST_CD_CPU1_POR_N")
	)
	(segment
		(start 124.587 -87.6808)
		(end 125.16485 -87.6808)
		(width 0.089408)
		(layer "In11.Cu")
		(net "RST_CD_CPU1_POR_N")
	)
	(segment
		(start 381.463804 -100.579936)
		(end 381.69723 -100.34651)
		(width 0.089408)
		(layer "In11.Cu")
		(net "RST_CD_CPU1_POR_N")
	)
	(segment
		(start 378.91847 -102.18547)
		(end 378.91847 -101.64953)
		(width 0.089408)
		(layer "In11.Cu")
		(net "RST_CD_CPU1_POR_N")
	)
	(segment
		(start 165.517576 -121.294652)
		(end 165.517576 -121.893076)
		(width 0.089408)
		(layer "In11.Cu")
		(net "RST_CD_CPU1_POR_N")
	)
	(segment
		(start 123.274328 -86.516718)
		(end 123.769374 -87.011764)
		(width 0.089408)
		(layer "In11.Cu")
		(net "RST_CD_CPU1_POR_N")
	)
	(segment
		(start 376.724926 -94.58706)
		(end 375.1072 -92.969334)
		(width 0.089408)
		(layer "In11.Cu")
		(net "RST_CD_CPU1_POR_N")
	)
	(segment
		(start 191.3382 -149.4028)
		(end 191.3382 -150.7744)
		(width 0.089408)
		(layer "In11.Cu")
		(net "RST_CD_CPU1_POR_N")
	)
	(segment
		(start 128.061974 -89.488518)
		(end 128.425448 -89.488518)
		(width 0.089408)
		(layer "In11.Cu")
		(net "RST_CD_CPU1_POR_N")
	)
	(segment
		(start 136.2202 -94.107)
		(end 136.747504 -94.634304)
		(width 0.089408)
		(layer "In11.Cu")
		(net "RST_CD_CPU1_POR_N")
	)
	(segment
		(start 379.71603 -104.98963)
		(end 379.41377 -104.68737)
		(width 0.089408)
		(layer "In11.Cu")
		(net "RST_CD_CPU1_POR_N")
	)
	(segment
		(start 378.94768 -106.6292)
		(end 379.3236 -106.25328)
		(width 0.089408)
		(layer "In11.Cu")
		(net "RST_CD_CPU1_POR_N")
	)
	(segment
		(start 122.60834 -86.214204)
		(end 122.910854 -86.516718)
		(width 0.089408)
		(layer "In11.Cu")
		(net "RST_CD_CPU1_POR_N")
	)
	(segment
		(start 167.40378 -123.77928)
		(end 167.40378 -124.132086)
		(width 0.089408)
		(layer "In11.Cu")
		(net "RST_CD_CPU1_POR_N")
	)
	(segment
		(start 163.051744 -118.82882)
		(end 165.517576 -121.294652)
		(width 0.089408)
		(layer "In11.Cu")
		(net "RST_CD_CPU1_POR_N")
	)
	(segment
		(start 140.6398 -96.84385)
		(end 140.645134 -96.849184)
		(width 0.089408)
		(layer "In11.Cu")
		(net "RST_CD_CPU1_POR_N")
	)
	(segment
		(start 183.69407 -143.478504)
		(end 185.229754 -145.014188)
		(width 0.089408)
		(layer "In11.Cu")
		(net "RST_CD_CPU1_POR_N")
	)
	(segment
		(start 185.229754 -145.014188)
		(end 185.229754 -146.342608)
		(width 0.089408)
		(layer "In11.Cu")
		(net "RST_CD_CPU1_POR_N")
	)
	(segment
		(start 125.486414 -88.002364)
		(end 125.84938 -88.002364)
		(width 0.089408)
		(layer "In11.Cu")
		(net "RST_CD_CPU1_POR_N")
	)
	(segment
		(start 129.43713 -90.1192)
		(end 129.784348 -90.466418)
		(width 0.089408)
		(layer "In11.Cu")
		(net "RST_CD_CPU1_POR_N")
	)
	(segment
		(start 159.524192 -130.08102)
		(end 159.524192 -141.650212)
		(width 0.089408)
		(layer "In11.Cu")
		(net "RST_CD_CPU1_POR_N")
	)
	(segment
		(start 125.16485 -87.6808)
		(end 125.486414 -88.002364)
		(width 0.089408)
		(layer "In11.Cu")
		(net "RST_CD_CPU1_POR_N")
	)
	(segment
		(start 122.910854 -86.516718)
		(end 123.274328 -86.516718)
		(width 0.089408)
		(layer "In11.Cu")
		(net "RST_CD_CPU1_POR_N")
	)
	(segment
		(start 134.07136 -92.955364)
		(end 134.331964 -92.955364)
		(width 0.089408)
		(layer "In11.Cu")
		(net "RST_CD_CPU1_POR_N")
	)
	(segment
		(start 379.41377 -104.17683)
		(end 379.71603 -103.87457)
		(width 0.089408)
		(layer "In11.Cu")
		(net "RST_CD_CPU1_POR_N")
	)
	(segment
		(start 378.91847 -101.64953)
		(end 379.349 -101.219)
		(width 0.089408)
		(layer "In11.Cu")
		(net "RST_CD_CPU1_POR_N")
	)
	(segment
		(start 377.43257 -111.967518)
		(end 377.43257 -111.549942)
		(width 0.089408)
		(layer "In11.Cu")
		(net "RST_CD_CPU1_POR_N")
	)
	(segment
		(start 163.214304 -143.478504)
		(end 183.69407 -143.478504)
		(width 0.089408)
		(layer "In11.Cu")
		(net "RST_CD_CPU1_POR_N")
	)
	(segment
		(start 378.91847 -98.24593)
		(end 379.22073 -97.94367)
		(width 0.089408)
		(layer "In11.Cu")
		(net "RST_CD_CPU1_POR_N")
	)
	(segment
		(start 379.349 -101.219)
		(end 379.349 -100.939092)
		(width 0.089408)
		(layer "In11.Cu")
		(net "RST_CD_CPU1_POR_N")
	)
	(segment
		(start 131.689094 -91.662758)
		(end 132.052314 -91.662758)
		(width 0.089408)
		(layer "In11.Cu")
		(net "RST_CD_CPU1_POR_N")
	)
	(segment
		(start 377.923298 -117.724428)
		(end 377.414536 -117.215666)
		(width 0.089408)
		(layer "In11.Cu")
		(net "RST_CD_CPU1_POR_N")
	)
	(segment
		(start 376.91822 -107.165902)
		(end 377.454922 -106.6292)
		(width 0.089408)
		(layer "In11.Cu")
		(net "RST_CD_CPU1_POR_N")
	)
	(segment
		(start 136.747504 -94.634304)
		(end 136.977628 -94.634304)
		(width 0.089408)
		(layer "In11.Cu")
		(net "RST_CD_CPU1_POR_N")
	)
	(segment
		(start 140.6398 -99.2886)
		(end 141.0208 -99.6696)
		(width 0.089408)
		(layer "In11.Cu")
		(net "RST_CD_CPU1_POR_N")
	)
	(segment
		(start 138.920474 -95.625158)
		(end 139.22248 -95.927164)
		(width 0.089408)
		(layer "In11.Cu")
		(net "RST_CD_CPU1_POR_N")
	)
	(segment
		(start 287.21812 -83.641184)
		(end 286.64662 -83.641184)
		(width 0.1016)
		(layer "F.Cu")
		(net "RST_CD_CPU0_POR_N")
	)
	(segment
		(start 377.544838 -78.294738)
		(end 377.145042 -77.894942)
		(width 0.10795)
		(layer "F.Cu")
		(net "RST_CD_CPU0_POR_N")
	)
	(via
		(at 287.21812 -83.641184)
		(size 0.508)
		(drill 0.254)
		(layers "F.Cu" "B.Cu")
		(net "RST_CD_CPU0_POR_N")
	)
	(via
		(at 322.218304 -29.918152)
		(size 0.508)
		(drill 0.254)
		(layers "F.Cu" "B.Cu")
		(net "RST_CD_CPU0_POR_N")
	)
	(via
		(at 377.544838 -78.294738)
		(size 0.4572)
		(drill 0.2032)
		(layers "F.Cu" "B.Cu")
		(net "RST_CD_CPU0_POR_N")
	)
	(via
		(at 384.175 -50.758598)
		(size 0.508)
		(drill 0.254)
		(layers "F.Cu" "B.Cu")
		(net "RST_CD_CPU0_POR_N")
	)
	(via
		(at 366.903 -32.1564)
		(size 0.6604)
		(drill 0.3302)
		(layers "F.Cu" "B.Cu")
		(net "RST_CD_CPU0_POR_N")
	)
	(via
		(at 341.493348 -53.155088)
		(size 0.508)
		(drill 0.254)
		(layers "F.Cu" "B.Cu")
		(net "RST_CD_CPU0_POR_N")
	)
	(via
		(at 373.06377 -32.633412)
		(size 0.508)
		(drill 0.254)
		(layers "F.Cu" "B.Cu")
		(net "RST_CD_CPU0_POR_N")
	)
	(segment
		(start 358.325674 -39.86276)
		(end 358.325674 -45.318172)
		(width 0.10795)
		(layer "B.Cu")
		(net "RST_CD_CPU0_POR_N")
	)
	(segment
		(start 372.586758 -32.1564)
		(end 373.06377 -32.633412)
		(width 0.10795)
		(layer "B.Cu")
		(net "RST_CD_CPU0_POR_N")
	)
	(segment
		(start 322.323714 -29.812742)
		(end 322.218304 -29.918152)
		(width 0.10795)
		(layer "B.Cu")
		(net "RST_CD_CPU0_POR_N")
	)
	(segment
		(start 342.529668 -51.1683)
		(end 341.493348 -52.20462)
		(width 0.10795)
		(layer "B.Cu")
		(net "RST_CD_CPU0_POR_N")
	)
	(segment
		(start 341.493348 -52.20462)
		(end 341.493348 -53.155088)
		(width 0.10795)
		(layer "B.Cu")
		(net "RST_CD_CPU0_POR_N")
	)
	(segment
		(start 322.869306 -29.812742)
		(end 322.323714 -29.812742)
		(width 0.10795)
		(layer "B.Cu")
		(net "RST_CD_CPU0_POR_N")
	)
	(segment
		(start 366.903 -32.1564)
		(end 366.032034 -32.1564)
		(width 0.10795)
		(layer "B.Cu")
		(net "RST_CD_CPU0_POR_N")
	)
	(segment
		(start 352.475546 -51.1683)
		(end 342.529668 -51.1683)
		(width 0.10795)
		(layer "B.Cu")
		(net "RST_CD_CPU0_POR_N")
	)
	(segment
		(start 366.032034 -32.1564)
		(end 358.325674 -39.86276)
		(width 0.10795)
		(layer "B.Cu")
		(net "RST_CD_CPU0_POR_N")
	)
	(segment
		(start 358.325674 -45.318172)
		(end 352.475546 -51.1683)
		(width 0.10795)
		(layer "B.Cu")
		(net "RST_CD_CPU0_POR_N")
	)
	(segment
		(start 366.903 -32.1564)
		(end 372.586758 -32.1564)
		(width 0.10795)
		(layer "B.Cu")
		(net "RST_CD_CPU0_POR_N")
	)
	(segment
		(start 335.093564 -52.222908)
		(end 328.963274 -58.353198)
		(width 0.089408)
		(layer "In2.Cu")
		(net "RST_CD_CPU0_POR_N")
	)
	(segment
		(start 340.733888 -53.155088)
		(end 339.801708 -52.222908)
		(width 0.089408)
		(layer "In2.Cu")
		(net "RST_CD_CPU0_POR_N")
	)
	(segment
		(start 297.798236 -85.030564)
		(end 297.196764 -85.030564)
		(width 0.089408)
		(layer "In2.Cu")
		(net "RST_CD_CPU0_POR_N")
	)
	(segment
		(start 304.74666 -82.251804)
		(end 304.029872 -82.251804)
		(width 0.089408)
		(layer "In2.Cu")
		(net "RST_CD_CPU0_POR_N")
	)
	(segment
		(start 300.26102 -84.535518)
		(end 300.056042 -84.535518)
		(width 0.089408)
		(layer "In2.Cu")
		(net "RST_CD_CPU0_POR_N")
	)
	(segment
		(start 327.498202 -58.353198)
		(end 319.805558 -66.045842)
		(width 0.089408)
		(layer "In2.Cu")
		(net "RST_CD_CPU0_POR_N")
	)
	(segment
		(start 288.006028 -84.63026)
		(end 287.21812 -83.842352)
		(width 0.089408)
		(layer "In2.Cu")
		(net "RST_CD_CPU0_POR_N")
	)
	(segment
		(start 319.805558 -67.787774)
		(end 313.550808 -74.042524)
		(width 0.089408)
		(layer "In2.Cu")
		(net "RST_CD_CPU0_POR_N")
	)
	(segment
		(start 303.158652 -82.727292)
		(end 302.83658 -83.049364)
		(width 0.089408)
		(layer "In2.Cu")
		(net "RST_CD_CPU0_POR_N")
	)
	(segment
		(start 341.493348 -53.155088)
		(end 340.733888 -53.155088)
		(width 0.089408)
		(layer "In2.Cu")
		(net "RST_CD_CPU0_POR_N")
	)
	(segment
		(start 292.065964 -85.030564)
		(end 291.763958 -84.728558)
		(width 0.089408)
		(layer "In2.Cu")
		(net "RST_CD_CPU0_POR_N")
	)
	(segment
		(start 288.21126 -84.63026)
		(end 288.006028 -84.63026)
		(width 0.089408)
		(layer "In2.Cu")
		(net "RST_CD_CPU0_POR_N")
	)
	(segment
		(start 319.805558 -66.045842)
		(end 319.805558 -67.787774)
		(width 0.089408)
		(layer "In2.Cu")
		(net "RST_CD_CPU0_POR_N")
	)
	(segment
		(start 288.611564 -85.030564)
		(end 288.21126 -84.63026)
		(width 0.089408)
		(layer "In2.Cu")
		(net "RST_CD_CPU0_POR_N")
	)
	(segment
		(start 302.83658 -83.049364)
		(end 302.68418 -83.049364)
		(width 0.089408)
		(layer "In2.Cu")
		(net "RST_CD_CPU0_POR_N")
	)
	(segment
		(start 290.838636 -85.030564)
		(end 290.440364 -85.030564)
		(width 0.089408)
		(layer "In2.Cu")
		(net "RST_CD_CPU0_POR_N")
	)
	(segment
		(start 313.550808 -78.6257)
		(end 309.622444 -82.554064)
		(width 0.089408)
		(layer "In2.Cu")
		(net "RST_CD_CPU0_POR_N")
	)
	(segment
		(start 296.347642 -84.728558)
		(end 296.045636 -85.030564)
		(width 0.089408)
		(layer "In2.Cu")
		(net "RST_CD_CPU0_POR_N")
	)
	(segment
		(start 301.647352 -83.737958)
		(end 301.27575 -84.10956)
		(width 0.089408)
		(layer "In2.Cu")
		(net "RST_CD_CPU0_POR_N")
	)
	(segment
		(start 293.393114 -84.728558)
		(end 293.062406 -84.728558)
		(width 0.089408)
		(layer "In2.Cu")
		(net "RST_CD_CPU0_POR_N")
	)
	(segment
		(start 302.68418 -83.049364)
		(end 301.995586 -83.737958)
		(width 0.089408)
		(layer "In2.Cu")
		(net "RST_CD_CPU0_POR_N")
	)
	(segment
		(start 303.554384 -82.727292)
		(end 303.158652 -82.727292)
		(width 0.089408)
		(layer "In2.Cu")
		(net "RST_CD_CPU0_POR_N")
	)
	(segment
		(start 301.995586 -83.737958)
		(end 301.647352 -83.737958)
		(width 0.089408)
		(layer "In2.Cu")
		(net "RST_CD_CPU0_POR_N")
	)
	(segment
		(start 291.140642 -84.728558)
		(end 290.838636 -85.030564)
		(width 0.089408)
		(layer "In2.Cu")
		(net "RST_CD_CPU0_POR_N")
	)
	(segment
		(start 294.318436 -85.030564)
		(end 293.69512 -85.030564)
		(width 0.089408)
		(layer "In2.Cu")
		(net "RST_CD_CPU0_POR_N")
	)
	(segment
		(start 300.056042 -84.535518)
		(end 299.560996 -85.030564)
		(width 0.089408)
		(layer "In2.Cu")
		(net "RST_CD_CPU0_POR_N")
	)
	(segment
		(start 299.560996 -85.030564)
		(end 298.934124 -85.030564)
		(width 0.089408)
		(layer "In2.Cu")
		(net "RST_CD_CPU0_POR_N")
	)
	(segment
		(start 309.622444 -82.554064)
		(end 305.04892 -82.554064)
		(width 0.089408)
		(layer "In2.Cu")
		(net "RST_CD_CPU0_POR_N")
	)
	(segment
		(start 296.894758 -84.728558)
		(end 296.347642 -84.728558)
		(width 0.089408)
		(layer "In2.Cu")
		(net "RST_CD_CPU0_POR_N")
	)
	(segment
		(start 300.686978 -84.10956)
		(end 300.26102 -84.535518)
		(width 0.089408)
		(layer "In2.Cu")
		(net "RST_CD_CPU0_POR_N")
	)
	(segment
		(start 287.21812 -83.842352)
		(end 287.21812 -83.641184)
		(width 0.089408)
		(layer "In2.Cu")
		(net "RST_CD_CPU0_POR_N")
	)
	(segment
		(start 291.763958 -84.728558)
		(end 291.140642 -84.728558)
		(width 0.089408)
		(layer "In2.Cu")
		(net "RST_CD_CPU0_POR_N")
	)
	(segment
		(start 301.27575 -84.10956)
		(end 300.686978 -84.10956)
		(width 0.089408)
		(layer "In2.Cu")
		(net "RST_CD_CPU0_POR_N")
	)
	(segment
		(start 298.100242 -84.728558)
		(end 297.798236 -85.030564)
		(width 0.089408)
		(layer "In2.Cu")
		(net "RST_CD_CPU0_POR_N")
	)
	(segment
		(start 298.632118 -84.728558)
		(end 298.100242 -84.728558)
		(width 0.089408)
		(layer "In2.Cu")
		(net "RST_CD_CPU0_POR_N")
	)
	(segment
		(start 313.550808 -74.042524)
		(end 313.550808 -78.6257)
		(width 0.089408)
		(layer "In2.Cu")
		(net "RST_CD_CPU0_POR_N")
	)
	(segment
		(start 292.7604 -85.030564)
		(end 292.065964 -85.030564)
		(width 0.089408)
		(layer "In2.Cu")
		(net "RST_CD_CPU0_POR_N")
	)
	(segment
		(start 297.196764 -85.030564)
		(end 296.894758 -84.728558)
		(width 0.089408)
		(layer "In2.Cu")
		(net "RST_CD_CPU0_POR_N")
	)
	(segment
		(start 295.218358 -84.728558)
		(end 294.620442 -84.728558)
		(width 0.089408)
		(layer "In2.Cu")
		(net "RST_CD_CPU0_POR_N")
	)
	(segment
		(start 290.440364 -85.030564)
		(end 290.138358 -84.728558)
		(width 0.089408)
		(layer "In2.Cu")
		(net "RST_CD_CPU0_POR_N")
	)
	(segment
		(start 328.963274 -58.353198)
		(end 327.498202 -58.353198)
		(width 0.089408)
		(layer "In2.Cu")
		(net "RST_CD_CPU0_POR_N")
	)
	(segment
		(start 293.69512 -85.030564)
		(end 293.393114 -84.728558)
		(width 0.089408)
		(layer "In2.Cu")
		(net "RST_CD_CPU0_POR_N")
	)
	(segment
		(start 289.162236 -85.030564)
		(end 288.611564 -85.030564)
		(width 0.089408)
		(layer "In2.Cu")
		(net "RST_CD_CPU0_POR_N")
	)
	(segment
		(start 339.801708 -52.222908)
		(end 335.093564 -52.222908)
		(width 0.089408)
		(layer "In2.Cu")
		(net "RST_CD_CPU0_POR_N")
	)
	(segment
		(start 293.062406 -84.728558)
		(end 292.7604 -85.030564)
		(width 0.089408)
		(layer "In2.Cu")
		(net "RST_CD_CPU0_POR_N")
	)
	(segment
		(start 305.04892 -82.554064)
		(end 304.74666 -82.251804)
		(width 0.089408)
		(layer "In2.Cu")
		(net "RST_CD_CPU0_POR_N")
	)
	(segment
		(start 296.045636 -85.030564)
		(end 295.520364 -85.030564)
		(width 0.089408)
		(layer "In2.Cu")
		(net "RST_CD_CPU0_POR_N")
	)
	(segment
		(start 298.934124 -85.030564)
		(end 298.632118 -84.728558)
		(width 0.089408)
		(layer "In2.Cu")
		(net "RST_CD_CPU0_POR_N")
	)
	(segment
		(start 304.029872 -82.251804)
		(end 303.554384 -82.727292)
		(width 0.089408)
		(layer "In2.Cu")
		(net "RST_CD_CPU0_POR_N")
	)
	(segment
		(start 294.620442 -84.728558)
		(end 294.318436 -85.030564)
		(width 0.089408)
		(layer "In2.Cu")
		(net "RST_CD_CPU0_POR_N")
	)
	(segment
		(start 295.520364 -85.030564)
		(end 295.218358 -84.728558)
		(width 0.089408)
		(layer "In2.Cu")
		(net "RST_CD_CPU0_POR_N")
	)
	(segment
		(start 290.138358 -84.728558)
		(end 289.464242 -84.728558)
		(width 0.089408)
		(layer "In2.Cu")
		(net "RST_CD_CPU0_POR_N")
	)
	(segment
		(start 289.464242 -84.728558)
		(end 289.162236 -85.030564)
		(width 0.089408)
		(layer "In2.Cu")
		(net "RST_CD_CPU0_POR_N")
	)
	(segment
		(start 379.47092 -72.192134)
		(end 380.390146 -72.192134)
		(width 0.089408)
		(layer "In9.Cu")
		(net "RST_CD_CPU0_POR_N")
	)
	(segment
		(start 381.319278 -70.931278)
		(end 380.975616 -70.587616)
		(width 0.089408)
		(layer "In9.Cu")
		(net "RST_CD_CPU0_POR_N")
	)
	(segment
		(start 382.78689 -63.750952)
		(end 382.78689 -60.573158)
		(width 0.089408)
		(layer "In9.Cu")
		(net "RST_CD_CPU0_POR_N")
	)
	(segment
		(start 382.78689 -60.573158)
		(end 383.556764 -59.803284)
		(width 0.089408)
		(layer "In9.Cu")
		(net "RST_CD_CPU0_POR_N")
	)
	(segment
		(start 384.011424 -56.10225)
		(end 384.011424 -55.21833)
		(width 0.089408)
		(layer "In9.Cu")
		(net "RST_CD_CPU0_POR_N")
	)
	(segment
		(start 377.544838 -78.082394)
		(end 377.971304 -77.655928)
		(width 0.089408)
		(layer "In9.Cu")
		(net "RST_CD_CPU0_POR_N")
	)
	(segment
		(start 381.230632 -68.500752)
		(end 381.230632 -66.038476)
		(width 0.089408)
		(layer "In9.Cu")
		(net "RST_CD_CPU0_POR_N")
	)
	(segment
		(start 383.488438 -54.177692)
		(end 383.488438 -51.44516)
		(width 0.089408)
		(layer "In9.Cu")
		(net "RST_CD_CPU0_POR_N")
	)
	(segment
		(start 381.230632 -66.038476)
		(end 382.065784 -65.203324)
		(width 0.089408)
		(layer "In9.Cu")
		(net "RST_CD_CPU0_POR_N")
	)
	(segment
		(start 384.011678 -55.218076)
		(end 384.011678 -54.700932)
		(width 0.089408)
		(layer "In9.Cu")
		(net "RST_CD_CPU0_POR_N")
	)
	(segment
		(start 382.065784 -65.203324)
		(end 382.065784 -64.472058)
		(width 0.089408)
		(layer "In9.Cu")
		(net "RST_CD_CPU0_POR_N")
	)
	(segment
		(start 378.350526 -73.312528)
		(end 379.47092 -72.192134)
		(width 0.089408)
		(layer "In9.Cu")
		(net "RST_CD_CPU0_POR_N")
	)
	(segment
		(start 380.390146 -72.192134)
		(end 381.319278 -71.263002)
		(width 0.089408)
		(layer "In9.Cu")
		(net "RST_CD_CPU0_POR_N")
	)
	(segment
		(start 382.065784 -64.472058)
		(end 382.78689 -63.750952)
		(width 0.089408)
		(layer "In9.Cu")
		(net "RST_CD_CPU0_POR_N")
	)
	(segment
		(start 377.971304 -77.655928)
		(end 377.971304 -75.80757)
		(width 0.089408)
		(layer "In9.Cu")
		(net "RST_CD_CPU0_POR_N")
	)
	(segment
		(start 383.556764 -56.55691)
		(end 384.011424 -56.10225)
		(width 0.089408)
		(layer "In9.Cu")
		(net "RST_CD_CPU0_POR_N")
	)
	(segment
		(start 384.011424 -55.21833)
		(end 384.011678 -55.218076)
		(width 0.089408)
		(layer "In9.Cu")
		(net "RST_CD_CPU0_POR_N")
	)
	(segment
		(start 383.488438 -51.44516)
		(end 384.175 -50.758598)
		(width 0.089408)
		(layer "In9.Cu")
		(net "RST_CD_CPU0_POR_N")
	)
	(segment
		(start 380.975616 -70.587616)
		(end 380.975616 -68.755768)
		(width 0.089408)
		(layer "In9.Cu")
		(net "RST_CD_CPU0_POR_N")
	)
	(segment
		(start 377.544838 -78.294738)
		(end 377.544838 -78.082394)
		(width 0.089408)
		(layer "In9.Cu")
		(net "RST_CD_CPU0_POR_N")
	)
	(segment
		(start 381.319278 -71.263002)
		(end 381.319278 -70.931278)
		(width 0.089408)
		(layer "In9.Cu")
		(net "RST_CD_CPU0_POR_N")
	)
	(segment
		(start 377.971304 -75.80757)
		(end 378.350526 -75.428348)
		(width 0.089408)
		(layer "In9.Cu")
		(net "RST_CD_CPU0_POR_N")
	)
	(segment
		(start 378.350526 -75.428348)
		(end 378.350526 -73.312528)
		(width 0.089408)
		(layer "In9.Cu")
		(net "RST_CD_CPU0_POR_N")
	)
	(segment
		(start 380.975616 -68.755768)
		(end 381.230632 -68.500752)
		(width 0.089408)
		(layer "In9.Cu")
		(net "RST_CD_CPU0_POR_N")
	)
	(segment
		(start 383.556764 -59.803284)
		(end 383.556764 -56.55691)
		(width 0.089408)
		(layer "In9.Cu")
		(net "RST_CD_CPU0_POR_N")
	)
	(segment
		(start 384.011678 -54.700932)
		(end 383.488438 -54.177692)
		(width 0.089408)
		(layer "In9.Cu")
		(net "RST_CD_CPU0_POR_N")
	)
	(segment
		(start 374.63222 -42.48658)
		(end 374.63222 -37.70376)
		(width 0.089408)
		(layer "In11.Cu")
		(net "RST_CD_CPU0_POR_N")
	)
	(segment
		(start 380.7714 -49.1998)
		(end 377.603258 -49.1998)
		(width 0.089408)
		(layer "In11.Cu")
		(net "RST_CD_CPU0_POR_N")
	)
	(segment
		(start 317.720472 -35.170872)
		(end 320.819018 -32.072326)
		(width 0.089408)
		(layer "In11.Cu")
		(net "RST_CD_CPU0_POR_N")
	)
	(segment
		(start 317.42888 -44.373038)
		(end 317.49746 -44.304458)
		(width 0.089408)
		(layer "In11.Cu")
		(net "RST_CD_CPU0_POR_N")
	)
	(segment
		(start 321.366134 -30.33268)
		(end 321.803776 -30.33268)
		(width 0.089408)
		(layer "In11.Cu")
		(net "RST_CD_CPU0_POR_N")
	)
	(segment
		(start 316.806072 -35.717734)
		(end 316.806072 -35.559746)
		(width 0.089408)
		(layer "In11.Cu")
		(net "RST_CD_CPU0_POR_N")
	)
	(segment
		(start 384.175 -50.758598)
		(end 382.330198 -50.758598)
		(width 0.089408)
		(layer "In11.Cu")
		(net "RST_CD_CPU0_POR_N")
	)
	(segment
		(start 322.683886 -47.059088)
		(end 321.752976 -47.059088)
		(width 0.089408)
		(layer "In11.Cu")
		(net "RST_CD_CPU0_POR_N")
	)
	(segment
		(start 337.975194 -51.777138)
		(end 327.401936 -51.777138)
		(width 0.089408)
		(layer "In11.Cu")
		(net "RST_CD_CPU0_POR_N")
	)
	(segment
		(start 317.49746 -43.655742)
		(end 316.806326 -42.964608)
		(width 0.089408)
		(layer "In11.Cu")
		(net "RST_CD_CPU0_POR_N")
	)
	(segment
		(start 382.330198 -50.758598)
		(end 380.7714 -49.1998)
		(width 0.089408)
		(layer "In11.Cu")
		(net "RST_CD_CPU0_POR_N")
	)
	(segment
		(start 327.401936 -51.777138)
		(end 322.683886 -47.059088)
		(width 0.089408)
		(layer "In11.Cu")
		(net "RST_CD_CPU0_POR_N")
	)
	(segment
		(start 320.819018 -32.072326)
		(end 320.819018 -30.879796)
		(width 0.089408)
		(layer "In11.Cu")
		(net "RST_CD_CPU0_POR_N")
	)
	(segment
		(start 320.819018 -30.879796)
		(end 321.366134 -30.33268)
		(width 0.089408)
		(layer "In11.Cu")
		(net "RST_CD_CPU0_POR_N")
	)
	(segment
		(start 373.332248 -44.300902)
		(end 373.332248 -43.786552)
		(width 0.089408)
		(layer "In11.Cu")
		(net "RST_CD_CPU0_POR_N")
	)
	(segment
		(start 321.752976 -47.059088)
		(end 320.863468 -46.16958)
		(width 0.089408)
		(layer "In11.Cu")
		(net "RST_CD_CPU0_POR_N")
	)
	(segment
		(start 317.49746 -44.304458)
		(end 317.49746 -43.655742)
		(width 0.089408)
		(layer "In11.Cu")
		(net "RST_CD_CPU0_POR_N")
	)
	(segment
		(start 317.42888 -45.028358)
		(end 317.42888 -44.373038)
		(width 0.089408)
		(layer "In11.Cu")
		(net "RST_CD_CPU0_POR_N")
	)
	(segment
		(start 318.570102 -46.16958)
		(end 317.42888 -45.028358)
		(width 0.089408)
		(layer "In11.Cu")
		(net "RST_CD_CPU0_POR_N")
	)
	(segment
		(start 372.621556 -33.508442)
		(end 372.621556 -33.075626)
		(width 0.089408)
		(layer "In11.Cu")
		(net "RST_CD_CPU0_POR_N")
	)
	(segment
		(start 372.73611 -33.622996)
		(end 372.621556 -33.508442)
		(width 0.089408)
		(layer "In11.Cu")
		(net "RST_CD_CPU0_POR_N")
	)
	(segment
		(start 340.115144 -51.776884)
		(end 337.975448 -51.776884)
		(width 0.089408)
		(layer "In11.Cu")
		(net "RST_CD_CPU0_POR_N")
	)
	(segment
		(start 337.975448 -51.776884)
		(end 337.975194 -51.777138)
		(width 0.089408)
		(layer "In11.Cu")
		(net "RST_CD_CPU0_POR_N")
	)
	(segment
		(start 316.806072 -35.559746)
		(end 317.194946 -35.170872)
		(width 0.089408)
		(layer "In11.Cu")
		(net "RST_CD_CPU0_POR_N")
	)
	(segment
		(start 372.73611 -35.80765)
		(end 372.73611 -33.622996)
		(width 0.089408)
		(layer "In11.Cu")
		(net "RST_CD_CPU0_POR_N")
	)
	(segment
		(start 341.493348 -53.155088)
		(end 340.115144 -51.776884)
		(width 0.089408)
		(layer "In11.Cu")
		(net "RST_CD_CPU0_POR_N")
	)
	(segment
		(start 316.806326 -42.964608)
		(end 316.806326 -35.717988)
		(width 0.089408)
		(layer "In11.Cu")
		(net "RST_CD_CPU0_POR_N")
	)
	(segment
		(start 377.603258 -49.1998)
		(end 375.020586 -46.617128)
		(width 0.089408)
		(layer "In11.Cu")
		(net "RST_CD_CPU0_POR_N")
	)
	(segment
		(start 374.63222 -37.70376)
		(end 372.73611 -35.80765)
		(width 0.089408)
		(layer "In11.Cu")
		(net "RST_CD_CPU0_POR_N")
	)
	(segment
		(start 375.020586 -46.617128)
		(end 375.020586 -45.98924)
		(width 0.089408)
		(layer "In11.Cu")
		(net "RST_CD_CPU0_POR_N")
	)
	(segment
		(start 317.194946 -35.170872)
		(end 317.720472 -35.170872)
		(width 0.089408)
		(layer "In11.Cu")
		(net "RST_CD_CPU0_POR_N")
	)
	(segment
		(start 321.803776 -30.33268)
		(end 322.218304 -29.918152)
		(width 0.089408)
		(layer "In11.Cu")
		(net "RST_CD_CPU0_POR_N")
	)
	(segment
		(start 316.806326 -35.717988)
		(end 316.806072 -35.717734)
		(width 0.089408)
		(layer "In11.Cu")
		(net "RST_CD_CPU0_POR_N")
	)
	(segment
		(start 372.621556 -33.075626)
		(end 373.06377 -32.633412)
		(width 0.089408)
		(layer "In11.Cu")
		(net "RST_CD_CPU0_POR_N")
	)
	(segment
		(start 375.020586 -45.98924)
		(end 373.332248 -44.300902)
		(width 0.089408)
		(layer "In11.Cu")
		(net "RST_CD_CPU0_POR_N")
	)
	(segment
		(start 320.863468 -46.16958)
		(end 318.570102 -46.16958)
		(width 0.089408)
		(layer "In11.Cu")
		(net "RST_CD_CPU0_POR_N")
	)
	(segment
		(start 373.332248 -43.786552)
		(end 374.63222 -42.48658)
		(width 0.089408)
		(layer "In11.Cu")
		(net "RST_CD_CPU0_POR_N")
	)
	(segment
		(start 368.745262 -69.495162)
		(end 369.145058 -69.894958)
		(width 0.10795)
		(layer "F.Cu")
		(net "TP_CPLD1_PT24D_DONE")
	)
	(via
		(at 368.745262 -69.495162)
		(size 0.4572)
		(drill 0.2032)
		(layers "F.Cu" "B.Cu")
		(net "TP_CPLD1_PT24D_DONE")
	)
	(segment
		(start 368.745262 -67.895216)
		(end 369.145058 -68.295012)
		(width 0.10795)
		(layer "F.Cu")
		(net "TP_CPLD1_PT24C_INITN")
	)
	(via
		(at 368.745262 -67.895216)
		(size 0.4572)
		(drill 0.2032)
		(layers "F.Cu" "B.Cu")
		(net "TP_CPLD1_PT24C_INITN")
	)
	(segment
		(start 371.945154 -79.094838)
		(end 372.34495 -78.695042)
		(width 0.10795)
		(layer "F.Cu")
		(net "TP_CPLD1_PB16B_PCLKC2_1")
	)
	(via
		(at 371.945154 -79.094838)
		(size 0.4572)
		(drill 0.2032)
		(layers "F.Cu" "B.Cu")
		(net "TP_CPLD1_PB16B_PCLKC2_1")
	)
	(via
		(at 372.7958 -79.094838)
		(size 0.6604)
		(drill 0.3302)
		(layers "F.Cu" "B.Cu")
		(net "TP_CPLD1_PB16B_PCLKC2_1")
	)
	(segment
		(start 371.945154 -79.094838)
		(end 372.7958 -79.094838)
		(width 0.10795)
		(layer "B.Cu")
		(net "TP_CPLD1_PB16B_PCLKC2_1")
	)
	(segment
		(start 377.145042 -74.69505)
		(end 377.544838 -75.094846)
		(width 0.10795)
		(layer "F.Cu")
		(net "TP_CPLD1_PL7D_PCLKT4_0")
	)
	(via
		(at 377.544838 -75.094846)
		(size 0.4572)
		(drill 0.2032)
		(layers "F.Cu" "B.Cu")
		(net "TP_CPLD1_PL7D_PCLKT4_0")
	)
	(via
		(at 376.680984 -74.41184)
		(size 0.6604)
		(drill 0.3302)
		(layers "F.Cu" "B.Cu")
		(net "TP_CPLD1_PL7D_PCLKT4_0")
	)
	(segment
		(start 376.680984 -74.41184)
		(end 376.861832 -74.41184)
		(width 0.10795)
		(layer "B.Cu")
		(net "TP_CPLD1_PL7D_PCLKT4_0")
	)
	(segment
		(start 376.861832 -74.41184)
		(end 377.544838 -75.094846)
		(width 0.10795)
		(layer "B.Cu")
		(net "TP_CPLD1_PL7D_PCLKT4_0")
	)
	(segment
		(start 367.145316 -76.694792)
		(end 367.545112 -76.294996)
		(width 0.1016)
		(layer "F.Cu")
		(net "FM_THERMTRIP_DLY")
	)
	(via
		(at 375.257822 -80.373474)
		(size 0.6604)
		(drill 0.3302)
		(layers "F.Cu" "B.Cu")
		(net "FM_THERMTRIP_DLY")
	)
	(via
		(at 367.145316 -76.694792)
		(size 0.4572)
		(drill 0.2032)
		(layers "F.Cu" "B.Cu")
		(net "FM_THERMTRIP_DLY")
	)
	(via
		(at 373.450104 -84.016596)
		(size 0.508)
		(drill 0.254)
		(layers "F.Cu" "B.Cu")
		(net "FM_THERMTRIP_DLY")
	)
	(segment
		(start 375.158 -84.019136)
		(end 374.560338 -84.616798)
		(width 0.10795)
		(layer "B.Cu")
		(net "FM_THERMTRIP_DLY")
	)
	(segment
		(start 375.158 -80.473296)
		(end 375.158 -82.169)
		(width 0.10795)
		(layer "B.Cu")
		(net "FM_THERMTRIP_DLY")
	)
	(segment
		(start 374.560338 -84.616798)
		(end 373.611394 -84.616798)
		(width 0.10795)
		(layer "B.Cu")
		(net "FM_THERMTRIP_DLY")
	)
	(segment
		(start 375.158 -82.169)
		(end 375.158 -84.019136)
		(width 0.10795)
		(layer "B.Cu")
		(net "FM_THERMTRIP_DLY")
	)
	(segment
		(start 373.611394 -84.616798)
		(end 373.450104 -84.455508)
		(width 0.10795)
		(layer "B.Cu")
		(net "FM_THERMTRIP_DLY")
	)
	(segment
		(start 375.257822 -80.373474)
		(end 375.158 -80.473296)
		(width 0.10795)
		(layer "B.Cu")
		(net "FM_THERMTRIP_DLY")
	)
	(segment
		(start 373.450104 -84.455508)
		(end 373.450104 -84.016596)
		(width 0.10795)
		(layer "B.Cu")
		(net "FM_THERMTRIP_DLY")
	)
	(segment
		(start 367.569496 -80.90535)
		(end 368.09426 -81.430114)
		(width 0.089408)
		(layer "In9.Cu")
		(net "FM_THERMTRIP_DLY")
	)
	(segment
		(start 368.445034 -81.430114)
		(end 370.83492 -83.82)
		(width 0.089408)
		(layer "In9.Cu")
		(net "FM_THERMTRIP_DLY")
	)
	(segment
		(start 370.83492 -83.82)
		(end 373.253508 -83.82)
		(width 0.089408)
		(layer "In9.Cu")
		(net "FM_THERMTRIP_DLY")
	)
	(segment
		(start 367.569496 -77.118972)
		(end 367.569496 -79.454502)
		(width 0.089408)
		(layer "In9.Cu")
		(net "FM_THERMTRIP_DLY")
	)
	(segment
		(start 367.283492 -80.179418)
		(end 367.569496 -80.465422)
		(width 0.089408)
		(layer "In9.Cu")
		(net "FM_THERMTRIP_DLY")
	)
	(segment
		(start 368.09426 -81.430114)
		(end 368.445034 -81.430114)
		(width 0.089408)
		(layer "In9.Cu")
		(net "FM_THERMTRIP_DLY")
	)
	(segment
		(start 367.145316 -76.694792)
		(end 367.569496 -77.118972)
		(width 0.089408)
		(layer "In9.Cu")
		(net "FM_THERMTRIP_DLY")
	)
	(segment
		(start 367.283492 -79.740506)
		(end 367.283492 -80.179418)
		(width 0.089408)
		(layer "In9.Cu")
		(net "FM_THERMTRIP_DLY")
	)
	(segment
		(start 373.253508 -83.82)
		(end 373.450104 -84.016596)
		(width 0.089408)
		(layer "In9.Cu")
		(net "FM_THERMTRIP_DLY")
	)
	(segment
		(start 367.569496 -79.454502)
		(end 367.283492 -79.740506)
		(width 0.089408)
		(layer "In9.Cu")
		(net "FM_THERMTRIP_DLY")
	)
	(segment
		(start 367.569496 -80.465422)
		(end 367.569496 -80.90535)
		(width 0.089408)
		(layer "In9.Cu")
		(net "FM_THERMTRIP_DLY")
	)
	(segment
		(start 373.7102 -100.5078)
		(end 374.78589 -100.5078)
		(width 0.10795)
		(layer "F.Cu")
		(net "FM_SINT_PRSNT_N")
	)
	(segment
		(start 367.945162 -68.695316)
		(end 368.344958 -69.095112)
		(width 0.1016)
		(layer "F.Cu")
		(net "FM_SINT_PRSNT_N")
	)
	(segment
		(start 371.771926 -99.956874)
		(end 372.625874 -99.956874)
		(width 0.10795)
		(layer "F.Cu")
		(net "FM_SINT_PRSNT_N")
	)
	(segment
		(start 375.133108 -100.855018)
		(end 375.504964 -100.855018)
		(width 0.10795)
		(layer "F.Cu")
		(net "FM_SINT_PRSNT_N")
	)
	(segment
		(start 373.5832 -100.3808)
		(end 373.7102 -100.5078)
		(width 0.10795)
		(layer "F.Cu")
		(net "FM_SINT_PRSNT_N")
	)
	(segment
		(start 374.78589 -100.5078)
		(end 375.133108 -100.855018)
		(width 0.10795)
		(layer "F.Cu")
		(net "FM_SINT_PRSNT_N")
	)
	(segment
		(start 371.2718 -100.457)
		(end 371.771926 -99.956874)
		(width 0.10795)
		(layer "F.Cu")
		(net "FM_SINT_PRSNT_N")
	)
	(segment
		(start 372.625874 -99.956874)
		(end 373.0498 -100.3808)
		(width 0.10795)
		(layer "F.Cu")
		(net "FM_SINT_PRSNT_N")
	)
	(segment
		(start 373.0498 -100.3808)
		(end 373.5832 -100.3808)
		(width 0.10795)
		(layer "F.Cu")
		(net "FM_SINT_PRSNT_N")
	)
	(via
		(at 373.5832 -100.3808)
		(size 0.508)
		(drill 0.254)
		(layers "F.Cu" "B.Cu")
		(net "FM_SINT_PRSNT_N")
	)
	(via
		(at 367.945162 -68.695316)
		(size 0.4572)
		(drill 0.2032)
		(layers "F.Cu" "B.Cu")
		(net "FM_SINT_PRSNT_N")
	)
	(via
		(at 367.62563 -66.172842)
		(size 0.6604)
		(drill 0.3302)
		(layers "F.Cu" "B.Cu")
		(net "FM_SINT_PRSNT_N")
	)
	(segment
		(start 367.945162 -68.695316)
		(end 367.562384 -68.312538)
		(width 0.10795)
		(layer "B.Cu")
		(net "FM_SINT_PRSNT_N")
	)
	(segment
		(start 367.562384 -68.312538)
		(end 367.562384 -67.73672)
		(width 0.10795)
		(layer "B.Cu")
		(net "FM_SINT_PRSNT_N")
	)
	(segment
		(start 367.62563 -67.673474)
		(end 367.62563 -66.172842)
		(width 0.10795)
		(layer "B.Cu")
		(net "FM_SINT_PRSNT_N")
	)
	(segment
		(start 367.562384 -67.73672)
		(end 367.62563 -67.673474)
		(width 0.10795)
		(layer "B.Cu")
		(net "FM_SINT_PRSNT_N")
	)
	(segment
		(start 373.5832 -100.050346)
		(end 373.5832 -100.3808)
		(width 0.089408)
		(layer "In11.Cu")
		(net "FM_SINT_PRSNT_N")
	)
	(segment
		(start 365.233204 -79.84871)
		(end 365.233204 -83.039204)
		(width 0.089408)
		(layer "In11.Cu")
		(net "FM_SINT_PRSNT_N")
	)
	(segment
		(start 366.238028 -90.235024)
		(end 369.2144 -93.211396)
		(width 0.089408)
		(layer "In11.Cu")
		(net "FM_SINT_PRSNT_N")
	)
	(segment
		(start 367.945162 -68.695316)
		(end 367.571782 -68.321936)
		(width 0.089408)
		(layer "In11.Cu")
		(net "FM_SINT_PRSNT_N")
	)
	(segment
		(start 371.6909 -96.3168)
		(end 372.6053 -97.2312)
		(width 0.089408)
		(layer "In11.Cu")
		(net "FM_SINT_PRSNT_N")
	)
	(segment
		(start 372.6053 -97.2312)
		(end 372.6053 -97.95002)
		(width 0.089408)
		(layer "In11.Cu")
		(net "FM_SINT_PRSNT_N")
	)
	(segment
		(start 369.2144 -95.4786)
		(end 370.0526 -96.3168)
		(width 0.089408)
		(layer "In11.Cu")
		(net "FM_SINT_PRSNT_N")
	)
	(segment
		(start 365.722408 -72.739504)
		(end 365.722408 -77.40523)
		(width 0.089408)
		(layer "In11.Cu")
		(net "FM_SINT_PRSNT_N")
	)
	(segment
		(start 370.0526 -96.3168)
		(end 371.6909 -96.3168)
		(width 0.089408)
		(layer "In11.Cu")
		(net "FM_SINT_PRSNT_N")
	)
	(segment
		(start 367.571782 -68.321936)
		(end 366.190276 -68.321936)
		(width 0.089408)
		(layer "In11.Cu")
		(net "FM_SINT_PRSNT_N")
	)
	(segment
		(start 365.571278 -72.588374)
		(end 365.722408 -72.739504)
		(width 0.089408)
		(layer "In11.Cu")
		(net "FM_SINT_PRSNT_N")
	)
	(segment
		(start 373.80418 -99.1489)
		(end 373.80418 -99.829366)
		(width 0.089408)
		(layer "In11.Cu")
		(net "FM_SINT_PRSNT_N")
	)
	(segment
		(start 369.2144 -93.211396)
		(end 369.2144 -95.4786)
		(width 0.089408)
		(layer "In11.Cu")
		(net "FM_SINT_PRSNT_N")
	)
	(segment
		(start 366.238028 -84.044028)
		(end 366.238028 -90.235024)
		(width 0.089408)
		(layer "In11.Cu")
		(net "FM_SINT_PRSNT_N")
	)
	(segment
		(start 373.80418 -99.829366)
		(end 373.5832 -100.050346)
		(width 0.089408)
		(layer "In11.Cu")
		(net "FM_SINT_PRSNT_N")
	)
	(segment
		(start 366.190276 -68.321936)
		(end 365.571278 -68.940934)
		(width 0.089408)
		(layer "In11.Cu")
		(net "FM_SINT_PRSNT_N")
	)
	(segment
		(start 365.233204 -83.039204)
		(end 366.238028 -84.044028)
		(width 0.089408)
		(layer "In11.Cu")
		(net "FM_SINT_PRSNT_N")
	)
	(segment
		(start 365.722408 -77.40523)
		(end 365.233204 -79.84871)
		(width 0.089408)
		(layer "In11.Cu")
		(net "FM_SINT_PRSNT_N")
	)
	(segment
		(start 365.571278 -68.940934)
		(end 365.571278 -72.588374)
		(width 0.089408)
		(layer "In11.Cu")
		(net "FM_SINT_PRSNT_N")
	)
	(segment
		(start 372.6053 -97.95002)
		(end 373.80418 -99.1489)
		(width 0.089408)
		(layer "In11.Cu")
		(net "FM_SINT_PRSNT_N")
	)
	(segment
		(start 375.944892 -67.895216)
		(end 375.545096 -68.295012)
		(width 0.10795)
		(layer "F.Cu")
		(net "TP_CPLD1_PT11A")
	)
	(via
		(at 375.944892 -67.895216)
		(size 0.4572)
		(drill 0.2032)
		(layers "F.Cu" "B.Cu")
		(net "TP_CPLD1_PT11A")
	)
	(segment
		(start 375.144792 -68.695316)
		(end 374.744996 -69.095112)
		(width 0.10795)
		(layer "F.Cu")
		(net "TP_CPLD1_PT11B")
	)
	(via
		(at 375.144792 -68.695316)
		(size 0.4572)
		(drill 0.2032)
		(layers "F.Cu" "B.Cu")
		(net "TP_CPLD1_PT11B")
	)
	(segment
		(start 374.344692 -68.695316)
		(end 373.944896 -69.095112)
		(width 0.10795)
		(layer "F.Cu")
		(net "TP_CPLD1_PT13A")
	)
	(via
		(at 374.344692 -68.695316)
		(size 0.4572)
		(drill 0.2032)
		(layers "F.Cu" "B.Cu")
		(net "TP_CPLD1_PT13A")
	)
	(segment
		(start 373.14505 -68.295012)
		(end 373.14505 -67.986402)
		(width 0.10795)
		(layer "F.Cu")
		(net "TP_CPLD1_PT17B_PCLKC0_1")
	)
	(segment
		(start 373.14505 -67.986402)
		(end 373.336566 -67.794886)
		(width 0.10795)
		(layer "F.Cu")
		(net "TP_CPLD1_PT17B_PCLKC0_1")
	)
	(via
		(at 373.336566 -67.794886)
		(size 0.4572)
		(drill 0.2032)
		(layers "F.Cu" "B.Cu")
		(net "TP_CPLD1_PT17B_PCLKC0_1")
	)
	(segment
		(start 372.563898 -64.411606)
		(end 372.563898 -64.240664)
		(width 0.10795)
		(layer "F.Cu")
		(net "PU_RST_PERST_BIT1")
	)
	(segment
		(start 371.917468 -68.66763)
		(end 372.34495 -69.095112)
		(width 0.10795)
		(layer "F.Cu")
		(net "PU_RST_PERST_BIT1")
	)
	(segment
		(start 371.917468 -66.156332)
		(end 371.917468 -68.66763)
		(width 0.10795)
		(layer "F.Cu")
		(net "PU_RST_PERST_BIT1")
	)
	(segment
		(start 372.7958 -64.9986)
		(end 372.7958 -64.643508)
		(width 0.10795)
		(layer "F.Cu")
		(net "PU_RST_PERST_BIT1")
	)
	(segment
		(start 372.7958 -65.278)
		(end 371.917468 -66.156332)
		(width 0.10795)
		(layer "F.Cu")
		(net "PU_RST_PERST_BIT1")
	)
	(segment
		(start 371.950996 -63.977774)
		(end 371.815106 -64.113664)
		(width 0.10795)
		(layer "F.Cu")
		(net "PU_RST_PERST_BIT1")
	)
	(segment
		(start 372.563898 -64.240664)
		(end 372.301008 -63.977774)
		(width 0.10795)
		(layer "F.Cu")
		(net "PU_RST_PERST_BIT1")
	)
	(segment
		(start 372.7958 -64.9986)
		(end 372.7958 -65.278)
		(width 0.10795)
		(layer "F.Cu")
		(net "PU_RST_PERST_BIT1")
	)
	(segment
		(start 372.301008 -63.977774)
		(end 371.950996 -63.977774)
		(width 0.10795)
		(layer "F.Cu")
		(net "PU_RST_PERST_BIT1")
	)
	(segment
		(start 371.815106 -64.113664)
		(end 371.000274 -64.113664)
		(width 0.10795)
		(layer "F.Cu")
		(net "PU_RST_PERST_BIT1")
	)
	(segment
		(start 372.7958 -64.643508)
		(end 372.563898 -64.411606)
		(width 0.10795)
		(layer "F.Cu")
		(net "PU_RST_PERST_BIT1")
	)
	(via
		(at 372.7958 -64.9986)
		(size 0.762)
		(drill 0.381)
		(layers "F.Cu" "B.Cu")
		(net "PU_RST_PERST_BIT1")
	)
	(segment
		(start 376.744738 -71.895208)
		(end 376.344942 -72.295004)
		(width 0.10795)
		(layer "F.Cu")
		(net "PU_RST_PERST_BIT0")
	)
	(via
		(at 376.744738 -71.895208)
		(size 0.4572)
		(drill 0.2032)
		(layers "F.Cu" "B.Cu")
		(net "PU_RST_PERST_BIT0")
	)
	(via
		(at 377.16206 -68.23964)
		(size 0.508)
		(drill 0.254)
		(layers "F.Cu" "B.Cu")
		(net "PU_RST_PERST_BIT0")
	)
	(segment
		(start 376.936 -67.437)
		(end 376.936 -66.929)
		(width 0.10795)
		(layer "B.Cu")
		(net "PU_RST_PERST_BIT0")
	)
	(segment
		(start 377.52147 -70.559168)
		(end 377.927616 -70.153022)
		(width 0.10795)
		(layer "B.Cu")
		(net "PU_RST_PERST_BIT0")
	)
	(segment
		(start 377.16206 -68.853812)
		(end 377.16206 -68.23964)
		(width 0.10795)
		(layer "B.Cu")
		(net "PU_RST_PERST_BIT0")
	)
	(segment
		(start 376.744738 -71.895208)
		(end 377.52147 -71.118476)
		(width 0.10795)
		(layer "B.Cu")
		(net "PU_RST_PERST_BIT0")
	)
	(segment
		(start 377.16206 -68.23964)
		(end 377.16206 -67.66306)
		(width 0.10795)
		(layer "B.Cu")
		(net "PU_RST_PERST_BIT0")
	)
	(segment
		(start 377.52147 -71.118476)
		(end 377.52147 -70.559168)
		(width 0.10795)
		(layer "B.Cu")
		(net "PU_RST_PERST_BIT0")
	)
	(segment
		(start 377.669044 -69.078094)
		(end 377.386342 -69.078094)
		(width 0.10795)
		(layer "B.Cu")
		(net "PU_RST_PERST_BIT0")
	)
	(segment
		(start 377.927616 -69.336666)
		(end 377.669044 -69.078094)
		(width 0.10795)
		(layer "B.Cu")
		(net "PU_RST_PERST_BIT0")
	)
	(segment
		(start 377.16206 -67.66306)
		(end 376.936 -67.437)
		(width 0.10795)
		(layer "B.Cu")
		(net "PU_RST_PERST_BIT0")
	)
	(segment
		(start 377.927616 -70.153022)
		(end 377.927616 -69.336666)
		(width 0.10795)
		(layer "B.Cu")
		(net "PU_RST_PERST_BIT0")
	)
	(segment
		(start 377.386342 -69.078094)
		(end 377.16206 -68.853812)
		(width 0.10795)
		(layer "B.Cu")
		(net "PU_RST_PERST_BIT0")
	)
	(segment
		(start 189.13475 -113.01095)
		(end 189.9793 -112.1664)
		(width 0.10795)
		(layer "F.Cu")
		(net "FM_PVCCMCP_CPU1_EN")
	)
	(segment
		(start 373.544846 -77.494892)
		(end 373.14505 -77.095096)
		(width 0.1016)
		(layer "F.Cu")
		(net "FM_PVCCMCP_CPU1_EN")
	)
	(segment
		(start 188.745114 -113.01095)
		(end 189.13475 -113.01095)
		(width 0.10795)
		(layer "F.Cu")
		(net "FM_PVCCMCP_CPU1_EN")
	)
	(via
		(at 372.755668 -76.450698)
		(size 0.6604)
		(drill 0.3302)
		(layers "F.Cu" "B.Cu")
		(net "FM_PVCCMCP_CPU1_EN")
	)
	(via
		(at 189.9793 -112.1664)
		(size 0.508)
		(drill 0.254)
		(layers "F.Cu" "B.Cu")
		(net "FM_PVCCMCP_CPU1_EN")
	)
	(via
		(at 186.36996 -24.18842)
		(size 0.508)
		(drill 0.254)
		(layers "F.Cu" "B.Cu")
		(net "FM_PVCCMCP_CPU1_EN")
	)
	(via
		(at 321.8307 -43.1292)
		(size 0.508)
		(drill 0.254)
		(layers "F.Cu" "B.Cu")
		(net "FM_PVCCMCP_CPU1_EN")
	)
	(via
		(at 184.855104 -47.957994)
		(size 0.508)
		(drill 0.254)
		(layers "F.Cu" "B.Cu")
		(net "FM_PVCCMCP_CPU1_EN")
	)
	(via
		(at 373.544846 -77.494892)
		(size 0.4572)
		(drill 0.2032)
		(layers "F.Cu" "B.Cu")
		(net "FM_PVCCMCP_CPU1_EN")
	)
	(segment
		(start 373.544846 -77.494892)
		(end 372.755668 -76.705714)
		(width 0.10795)
		(layer "B.Cu")
		(net "FM_PVCCMCP_CPU1_EN")
	)
	(segment
		(start 372.755668 -76.705714)
		(end 372.755668 -76.450698)
		(width 0.10795)
		(layer "B.Cu")
		(net "FM_PVCCMCP_CPU1_EN")
	)
	(segment
		(start 184.591706 -46.390306)
		(end 184.591706 -47.732188)
		(width 0.089408)
		(layer "In2.Cu")
		(net "FM_PVCCMCP_CPU1_EN")
	)
	(segment
		(start 186.36996 -24.18842)
		(end 186.36996 -44.612052)
		(width 0.089408)
		(layer "In2.Cu")
		(net "FM_PVCCMCP_CPU1_EN")
	)
	(segment
		(start 184.817512 -47.957994)
		(end 184.855104 -47.957994)
		(width 0.089408)
		(layer "In2.Cu")
		(net "FM_PVCCMCP_CPU1_EN")
	)
	(segment
		(start 186.36996 -44.612052)
		(end 184.591706 -46.390306)
		(width 0.089408)
		(layer "In2.Cu")
		(net "FM_PVCCMCP_CPU1_EN")
	)
	(segment
		(start 184.591706 -47.732188)
		(end 184.817512 -47.957994)
		(width 0.089408)
		(layer "In2.Cu")
		(net "FM_PVCCMCP_CPU1_EN")
	)
	(segment
		(start 189.221618 -27.973274)
		(end 187.899802 -26.651458)
		(width 0.089408)
		(layer "In9.Cu")
		(net "FM_PVCCMCP_CPU1_EN")
	)
	(segment
		(start 318.434212 -43.161204)
		(end 317.868808 -42.5958)
		(width 0.089408)
		(layer "In9.Cu")
		(net "FM_PVCCMCP_CPU1_EN")
	)
	(segment
		(start 241.759232 -29.614876)
		(end 223.797114 -29.614876)
		(width 0.089408)
		(layer "In9.Cu")
		(net "FM_PVCCMCP_CPU1_EN")
	)
	(segment
		(start 259.948426 -28.827984)
		(end 242.546124 -28.827984)
		(width 0.089408)
		(layer "In9.Cu")
		(net "FM_PVCCMCP_CPU1_EN")
	)
	(segment
		(start 264.484104 -31.87573)
		(end 262.631682 -30.023308)
		(width 0.089408)
		(layer "In9.Cu")
		(net "FM_PVCCMCP_CPU1_EN")
	)
	(segment
		(start 222.155512 -27.973274)
		(end 189.221618 -27.973274)
		(width 0.089408)
		(layer "In9.Cu")
		(net "FM_PVCCMCP_CPU1_EN")
	)
	(segment
		(start 320.185796 -43.161204)
		(end 318.434212 -43.161204)
		(width 0.089408)
		(layer "In9.Cu")
		(net "FM_PVCCMCP_CPU1_EN")
	)
	(segment
		(start 186.682634 -24.18842)
		(end 186.36996 -24.18842)
		(width 0.089408)
		(layer "In9.Cu")
		(net "FM_PVCCMCP_CPU1_EN")
	)
	(segment
		(start 242.546124 -28.827984)
		(end 241.759232 -29.614876)
		(width 0.089408)
		(layer "In9.Cu")
		(net "FM_PVCCMCP_CPU1_EN")
	)
	(segment
		(start 223.797114 -29.614876)
		(end 222.155512 -27.973274)
		(width 0.089408)
		(layer "In9.Cu")
		(net "FM_PVCCMCP_CPU1_EN")
	)
	(segment
		(start 314.31992 -42.5958)
		(end 303.59985 -31.87573)
		(width 0.089408)
		(layer "In9.Cu")
		(net "FM_PVCCMCP_CPU1_EN")
	)
	(segment
		(start 262.631682 -30.023308)
		(end 261.14375 -30.023308)
		(width 0.089408)
		(layer "In9.Cu")
		(net "FM_PVCCMCP_CPU1_EN")
	)
	(segment
		(start 303.59985 -31.87573)
		(end 264.484104 -31.87573)
		(width 0.089408)
		(layer "In9.Cu")
		(net "FM_PVCCMCP_CPU1_EN")
	)
	(segment
		(start 317.868808 -42.5958)
		(end 314.31992 -42.5958)
		(width 0.089408)
		(layer "In9.Cu")
		(net "FM_PVCCMCP_CPU1_EN")
	)
	(segment
		(start 187.899802 -25.405588)
		(end 186.682634 -24.18842)
		(width 0.089408)
		(layer "In9.Cu")
		(net "FM_PVCCMCP_CPU1_EN")
	)
	(segment
		(start 320.707004 -42.639996)
		(end 320.185796 -43.161204)
		(width 0.089408)
		(layer "In9.Cu")
		(net "FM_PVCCMCP_CPU1_EN")
	)
	(segment
		(start 321.341496 -42.639996)
		(end 320.707004 -42.639996)
		(width 0.089408)
		(layer "In9.Cu")
		(net "FM_PVCCMCP_CPU1_EN")
	)
	(segment
		(start 321.8307 -43.1292)
		(end 321.341496 -42.639996)
		(width 0.089408)
		(layer "In9.Cu")
		(net "FM_PVCCMCP_CPU1_EN")
	)
	(segment
		(start 187.899802 -26.651458)
		(end 187.899802 -25.405588)
		(width 0.089408)
		(layer "In9.Cu")
		(net "FM_PVCCMCP_CPU1_EN")
	)
	(segment
		(start 261.14375 -30.023308)
		(end 259.948426 -28.827984)
		(width 0.089408)
		(layer "In9.Cu")
		(net "FM_PVCCMCP_CPU1_EN")
	)
	(segment
		(start 321.8307 -43.1292)
		(end 323.079618 -43.1292)
		(width 0.089408)
		(layer "In11.Cu")
		(net "FM_PVCCMCP_CPU1_EN")
	)
	(segment
		(start 359.758234 -51.26482)
		(end 360.997246 -51.26482)
		(width 0.089408)
		(layer "In11.Cu")
		(net "FM_PVCCMCP_CPU1_EN")
	)
	(segment
		(start 373.918226 -77.121512)
		(end 373.544846 -77.494892)
		(width 0.089408)
		(layer "In11.Cu")
		(net "FM_PVCCMCP_CPU1_EN")
	)
	(segment
		(start 182.866792 -87.980012)
		(end 182.866792 -104.279192)
		(width 0.089408)
		(layer "In11.Cu")
		(net "FM_PVCCMCP_CPU1_EN")
	)
	(segment
		(start 171.30522 -60.087764)
		(end 173.678596 -62.46114)
		(width 0.089408)
		(layer "In11.Cu")
		(net "FM_PVCCMCP_CPU1_EN")
	)
	(segment
		(start 173.192694 -69.50964)
		(end 173.449234 -69.76618)
		(width 0.089408)
		(layer "In11.Cu")
		(net "FM_PVCCMCP_CPU1_EN")
	)
	(segment
		(start 179.300632 -84.413852)
		(end 182.866792 -87.980012)
		(width 0.089408)
		(layer "In11.Cu")
		(net "FM_PVCCMCP_CPU1_EN")
	)
	(segment
		(start 176.3776 -73.1139)
		(end 175.542702 -73.948798)
		(width 0.089408)
		(layer "In11.Cu")
		(net "FM_PVCCMCP_CPU1_EN")
	)
	(segment
		(start 374.68302 -66.471546)
		(end 373.918226 -67.23634)
		(width 0.089408)
		(layer "In11.Cu")
		(net "FM_PVCCMCP_CPU1_EN")
	)
	(segment
		(start 364.802674 -55.070248)
		(end 366.540542 -55.070248)
		(width 0.089408)
		(layer "In11.Cu")
		(net "FM_PVCCMCP_CPU1_EN")
	)
	(segment
		(start 328.7522 -48.801782)
		(end 357.295196 -48.801782)
		(width 0.089408)
		(layer "In11.Cu")
		(net "FM_PVCCMCP_CPU1_EN")
	)
	(segment
		(start 173.449234 -69.76618)
		(end 175.52924 -69.76618)
		(width 0.089408)
		(layer "In11.Cu")
		(net "FM_PVCCMCP_CPU1_EN")
	)
	(segment
		(start 366.540542 -55.070248)
		(end 372.386606 -60.915804)
		(width 0.089408)
		(layer "In11.Cu")
		(net "FM_PVCCMCP_CPU1_EN")
	)
	(segment
		(start 184.855104 -47.957994)
		(end 184.817512 -47.957994)
		(width 0.089408)
		(layer "In11.Cu")
		(net "FM_PVCCMCP_CPU1_EN")
	)
	(segment
		(start 187.5028 -108.9152)
		(end 187.5028 -109.6899)
		(width 0.089408)
		(layer "In11.Cu")
		(net "FM_PVCCMCP_CPU1_EN")
	)
	(segment
		(start 179.300632 -81.792572)
		(end 179.300632 -84.413852)
		(width 0.089408)
		(layer "In11.Cu")
		(net "FM_PVCCMCP_CPU1_EN")
	)
	(segment
		(start 175.542702 -73.948798)
		(end 175.542702 -78.034642)
		(width 0.089408)
		(layer "In11.Cu")
		(net "FM_PVCCMCP_CPU1_EN")
	)
	(segment
		(start 173.678596 -62.46114)
		(end 173.678596 -63.754254)
		(width 0.089408)
		(layer "In11.Cu")
		(net "FM_PVCCMCP_CPU1_EN")
	)
	(segment
		(start 374.68302 -65.506854)
		(end 374.68302 -66.471546)
		(width 0.089408)
		(layer "In11.Cu")
		(net "FM_PVCCMCP_CPU1_EN")
	)
	(segment
		(start 169.201084 -60.087764)
		(end 171.30522 -60.087764)
		(width 0.089408)
		(layer "In11.Cu")
		(net "FM_PVCCMCP_CPU1_EN")
	)
	(segment
		(start 182.866792 -104.279192)
		(end 187.5028 -108.9152)
		(width 0.089408)
		(layer "In11.Cu")
		(net "FM_PVCCMCP_CPU1_EN")
	)
	(segment
		(start 175.52924 -69.76618)
		(end 176.3776 -70.61454)
		(width 0.089408)
		(layer "In11.Cu")
		(net "FM_PVCCMCP_CPU1_EN")
	)
	(segment
		(start 173.192694 -64.240156)
		(end 173.192694 -69.50964)
		(width 0.089408)
		(layer "In11.Cu")
		(net "FM_PVCCMCP_CPU1_EN")
	)
	(segment
		(start 168.62044 -59.50712)
		(end 169.201084 -60.087764)
		(width 0.089408)
		(layer "In11.Cu")
		(net "FM_PVCCMCP_CPU1_EN")
	)
	(segment
		(start 187.5028 -109.6899)
		(end 189.9793 -112.1664)
		(width 0.089408)
		(layer "In11.Cu")
		(net "FM_PVCCMCP_CPU1_EN")
	)
	(segment
		(start 375.05132 -64.24168)
		(end 374.820688 -64.472312)
		(width 0.089408)
		(layer "In11.Cu")
		(net "FM_PVCCMCP_CPU1_EN")
	)
	(segment
		(start 184.817512 -47.957994)
		(end 184.297574 -47.438056)
		(width 0.089408)
		(layer "In11.Cu")
		(net "FM_PVCCMCP_CPU1_EN")
	)
	(segment
		(start 168.62044 -51.049428)
		(end 168.62044 -59.50712)
		(width 0.089408)
		(layer "In11.Cu")
		(net "FM_PVCCMCP_CPU1_EN")
	)
	(segment
		(start 374.820688 -65.369186)
		(end 374.68302 -65.506854)
		(width 0.089408)
		(layer "In11.Cu")
		(net "FM_PVCCMCP_CPU1_EN")
	)
	(segment
		(start 172.231812 -47.438056)
		(end 168.62044 -51.049428)
		(width 0.089408)
		(layer "In11.Cu")
		(net "FM_PVCCMCP_CPU1_EN")
	)
	(segment
		(start 323.079618 -43.1292)
		(end 328.7522 -48.801782)
		(width 0.089408)
		(layer "In11.Cu")
		(net "FM_PVCCMCP_CPU1_EN")
	)
	(segment
		(start 176.3776 -70.61454)
		(end 176.3776 -73.1139)
		(width 0.089408)
		(layer "In11.Cu")
		(net "FM_PVCCMCP_CPU1_EN")
	)
	(segment
		(start 375.05132 -61.921898)
		(end 375.05132 -64.24168)
		(width 0.089408)
		(layer "In11.Cu")
		(net "FM_PVCCMCP_CPU1_EN")
	)
	(segment
		(start 373.918226 -67.23634)
		(end 373.918226 -77.121512)
		(width 0.089408)
		(layer "In11.Cu")
		(net "FM_PVCCMCP_CPU1_EN")
	)
	(segment
		(start 184.297574 -47.438056)
		(end 172.231812 -47.438056)
		(width 0.089408)
		(layer "In11.Cu")
		(net "FM_PVCCMCP_CPU1_EN")
	)
	(segment
		(start 372.386606 -60.915804)
		(end 374.045226 -60.915804)
		(width 0.089408)
		(layer "In11.Cu")
		(net "FM_PVCCMCP_CPU1_EN")
	)
	(segment
		(start 374.045226 -60.915804)
		(end 375.05132 -61.921898)
		(width 0.089408)
		(layer "In11.Cu")
		(net "FM_PVCCMCP_CPU1_EN")
	)
	(segment
		(start 374.820688 -64.472312)
		(end 374.820688 -65.369186)
		(width 0.089408)
		(layer "In11.Cu")
		(net "FM_PVCCMCP_CPU1_EN")
	)
	(segment
		(start 357.295196 -48.801782)
		(end 359.758234 -51.26482)
		(width 0.089408)
		(layer "In11.Cu")
		(net "FM_PVCCMCP_CPU1_EN")
	)
	(segment
		(start 173.678596 -63.754254)
		(end 173.192694 -64.240156)
		(width 0.089408)
		(layer "In11.Cu")
		(net "FM_PVCCMCP_CPU1_EN")
	)
	(segment
		(start 175.542702 -78.034642)
		(end 179.300632 -81.792572)
		(width 0.089408)
		(layer "In11.Cu")
		(net "FM_PVCCMCP_CPU1_EN")
	)
	(segment
		(start 360.997246 -51.26482)
		(end 364.802674 -55.070248)
		(width 0.089408)
		(layer "In11.Cu")
		(net "FM_PVCCMCP_CPU1_EN")
	)
	(segment
		(start 409.32862 -114.7826)
		(end 409.10002 -114.554)
		(width 0.10795)
		(layer "F.Cu")
		(net "FM_ADR_MODE_SEL")
	)
	(segment
		(start 378.344684 -80.694784)
		(end 377.944888 -80.294988)
		(width 0.10795)
		(layer "F.Cu")
		(net "FM_ADR_MODE_SEL")
	)
	(segment
		(start 409.10002 -114.554)
		(end 408.7495 -114.554)
		(width 0.10795)
		(layer "F.Cu")
		(net "FM_ADR_MODE_SEL")
	)
	(segment
		(start 411.245304 -116.12245)
		(end 409.905454 -114.7826)
		(width 0.10795)
		(layer "F.Cu")
		(net "FM_ADR_MODE_SEL")
	)
	(segment
		(start 414.0708 -116.12245)
		(end 411.245304 -116.12245)
		(width 0.10795)
		(layer "F.Cu")
		(net "FM_ADR_MODE_SEL")
	)
	(segment
		(start 409.905454 -114.7826)
		(end 409.32862 -114.7826)
		(width 0.10795)
		(layer "F.Cu")
		(net "FM_ADR_MODE_SEL")
	)
	(via
		(at 414.0708 -116.12245)
		(size 0.508)
		(drill 0.254)
		(layers "F.Cu" "B.Cu")
		(net "FM_ADR_MODE_SEL")
	)
	(via
		(at 413.997902 -117.602)
		(size 0.6604)
		(drill 0.3302)
		(layers "F.Cu" "B.Cu")
		(net "FM_ADR_MODE_SEL")
	)
	(via
		(at 415.717736 -70.43801)
		(size 0.508)
		(drill 0.254)
		(layers "F.Cu" "B.Cu")
		(net "FM_ADR_MODE_SEL")
	)
	(via
		(at 378.344684 -80.694784)
		(size 0.4572)
		(drill 0.2032)
		(layers "F.Cu" "B.Cu")
		(net "FM_ADR_MODE_SEL")
	)
	(segment
		(start 414.0708 -117.529102)
		(end 414.0708 -116.12245)
		(width 0.10795)
		(layer "B.Cu")
		(net "FM_ADR_MODE_SEL")
	)
	(segment
		(start 413.997902 -117.602)
		(end 414.0708 -117.529102)
		(width 0.10795)
		(layer "B.Cu")
		(net "FM_ADR_MODE_SEL")
	)
	(segment
		(start 414.801812 -98.241612)
		(end 413.02305 -96.46285)
		(width 0.089408)
		(layer "In2.Cu")
		(net "FM_ADR_MODE_SEL")
	)
	(segment
		(start 414.73882 -72.060054)
		(end 415.240216 -71.558658)
		(width 0.089408)
		(layer "In2.Cu")
		(net "FM_ADR_MODE_SEL")
	)
	(segment
		(start 414.496504 -115.696746)
		(end 414.496504 -112.875568)
		(width 0.089408)
		(layer "In2.Cu")
		(net "FM_ADR_MODE_SEL")
	)
	(segment
		(start 414.0708 -116.12245)
		(end 414.496504 -115.696746)
		(width 0.089408)
		(layer "In2.Cu")
		(net "FM_ADR_MODE_SEL")
	)
	(segment
		(start 414.801812 -103.256334)
		(end 414.801812 -98.241612)
		(width 0.089408)
		(layer "In2.Cu")
		(net "FM_ADR_MODE_SEL")
	)
	(segment
		(start 415.240216 -74.670158)
		(end 414.73882 -74.168762)
		(width 0.089408)
		(layer "In2.Cu")
		(net "FM_ADR_MODE_SEL")
	)
	(segment
		(start 415.780474 -82.519774)
		(end 415.780474 -82.18805)
		(width 0.089408)
		(layer "In2.Cu")
		(net "FM_ADR_MODE_SEL")
	)
	(segment
		(start 414.234884 -109.015784)
		(end 414.458404 -108.792264)
		(width 0.089408)
		(layer "In2.Cu")
		(net "FM_ADR_MODE_SEL")
	)
	(segment
		(start 415.780474 -82.18805)
		(end 415.240216 -81.647792)
		(width 0.089408)
		(layer "In2.Cu")
		(net "FM_ADR_MODE_SEL")
	)
	(segment
		(start 413.02305 -86.348062)
		(end 415.443416 -83.927696)
		(width 0.089408)
		(layer "In2.Cu")
		(net "FM_ADR_MODE_SEL")
	)
	(segment
		(start 414.73882 -74.168762)
		(end 414.73882 -72.060054)
		(width 0.089408)
		(layer "In2.Cu")
		(net "FM_ADR_MODE_SEL")
	)
	(segment
		(start 414.458404 -108.2167)
		(end 413.20339 -106.961686)
		(width 0.089408)
		(layer "In2.Cu")
		(net "FM_ADR_MODE_SEL")
	)
	(segment
		(start 415.443416 -82.856832)
		(end 415.780474 -82.519774)
		(width 0.089408)
		(layer "In2.Cu")
		(net "FM_ADR_MODE_SEL")
	)
	(segment
		(start 415.240216 -81.647792)
		(end 415.240216 -74.670158)
		(width 0.089408)
		(layer "In2.Cu")
		(net "FM_ADR_MODE_SEL")
	)
	(segment
		(start 415.240216 -71.558658)
		(end 415.240216 -70.91553)
		(width 0.089408)
		(layer "In2.Cu")
		(net "FM_ADR_MODE_SEL")
	)
	(segment
		(start 413.20339 -106.961686)
		(end 413.20339 -104.854756)
		(width 0.089408)
		(layer "In2.Cu")
		(net "FM_ADR_MODE_SEL")
	)
	(segment
		(start 414.458404 -108.792264)
		(end 414.458404 -108.2167)
		(width 0.089408)
		(layer "In2.Cu")
		(net "FM_ADR_MODE_SEL")
	)
	(segment
		(start 413.20339 -104.854756)
		(end 414.801812 -103.256334)
		(width 0.089408)
		(layer "In2.Cu")
		(net "FM_ADR_MODE_SEL")
	)
	(segment
		(start 413.02305 -96.46285)
		(end 413.02305 -86.348062)
		(width 0.089408)
		(layer "In2.Cu")
		(net "FM_ADR_MODE_SEL")
	)
	(segment
		(start 415.240216 -70.91553)
		(end 415.717736 -70.43801)
		(width 0.089408)
		(layer "In2.Cu")
		(net "FM_ADR_MODE_SEL")
	)
	(segment
		(start 415.443416 -83.927696)
		(end 415.443416 -82.856832)
		(width 0.089408)
		(layer "In2.Cu")
		(net "FM_ADR_MODE_SEL")
	)
	(segment
		(start 414.496504 -112.875568)
		(end 414.234884 -112.613948)
		(width 0.089408)
		(layer "In2.Cu")
		(net "FM_ADR_MODE_SEL")
	)
	(segment
		(start 414.234884 -112.613948)
		(end 414.234884 -109.015784)
		(width 0.089408)
		(layer "In2.Cu")
		(net "FM_ADR_MODE_SEL")
	)
	(segment
		(start 415.282126 -70.87362)
		(end 415.717736 -70.43801)
		(width 0.089408)
		(layer "In4.Cu")
		(net "FM_ADR_MODE_SEL")
	)
	(segment
		(start 390.807702 -78.45552)
		(end 391.74928 -77.513942)
		(width 0.089408)
		(layer "In4.Cu")
		(net "FM_ADR_MODE_SEL")
	)
	(segment
		(start 381.350266 -79.268574)
		(end 382.71831 -79.268574)
		(width 0.089408)
		(layer "In4.Cu")
		(net "FM_ADR_MODE_SEL")
	)
	(segment
		(start 397.697452 -77.697838)
		(end 398.810226 -76.585064)
		(width 0.089408)
		(layer "In4.Cu")
		(net "FM_ADR_MODE_SEL")
	)
	(segment
		(start 378.344684 -80.694784)
		(end 379.924056 -80.694784)
		(width 0.089408)
		(layer "In4.Cu")
		(net "FM_ADR_MODE_SEL")
	)
	(segment
		(start 394.948156 -77.386434)
		(end 395.391894 -76.942696)
		(width 0.089408)
		(layer "In4.Cu")
		(net "FM_ADR_MODE_SEL")
	)
	(segment
		(start 386.919216 -78.574138)
		(end 388.56666 -78.574138)
		(width 0.089408)
		(layer "In4.Cu")
		(net "FM_ADR_MODE_SEL")
	)
	(segment
		(start 403.892258 -73.762108)
		(end 406.883108 -73.762108)
		(width 0.089408)
		(layer "In4.Cu")
		(net "FM_ADR_MODE_SEL")
	)
	(segment
		(start 389.25627 -79.263748)
		(end 389.842502 -79.263748)
		(width 0.089408)
		(layer "In4.Cu")
		(net "FM_ADR_MODE_SEL")
	)
	(segment
		(start 389.842502 -79.263748)
		(end 390.65073 -78.45552)
		(width 0.089408)
		(layer "In4.Cu")
		(net "FM_ADR_MODE_SEL")
	)
	(segment
		(start 391.74928 -77.513942)
		(end 392.29157 -77.513942)
		(width 0.089408)
		(layer "In4.Cu")
		(net "FM_ADR_MODE_SEL")
	)
	(segment
		(start 392.419078 -77.386434)
		(end 394.948156 -77.386434)
		(width 0.089408)
		(layer "In4.Cu")
		(net "FM_ADR_MODE_SEL")
	)
	(segment
		(start 415.282126 -71.02602)
		(end 415.282126 -70.87362)
		(width 0.089408)
		(layer "In4.Cu")
		(net "FM_ADR_MODE_SEL")
	)
	(segment
		(start 388.56666 -78.574138)
		(end 389.25627 -79.263748)
		(width 0.089408)
		(layer "In4.Cu")
		(net "FM_ADR_MODE_SEL")
	)
	(segment
		(start 413.101282 -73.206864)
		(end 415.282126 -71.02602)
		(width 0.089408)
		(layer "In4.Cu")
		(net "FM_ADR_MODE_SEL")
	)
	(segment
		(start 407.438352 -73.206864)
		(end 413.101282 -73.206864)
		(width 0.089408)
		(layer "In4.Cu")
		(net "FM_ADR_MODE_SEL")
	)
	(segment
		(start 384.233166 -77.753718)
		(end 386.098796 -77.753718)
		(width 0.089408)
		(layer "In4.Cu")
		(net "FM_ADR_MODE_SEL")
	)
	(segment
		(start 390.65073 -78.45552)
		(end 390.807702 -78.45552)
		(width 0.089408)
		(layer "In4.Cu")
		(net "FM_ADR_MODE_SEL")
	)
	(segment
		(start 406.883108 -73.762108)
		(end 407.438352 -73.206864)
		(width 0.089408)
		(layer "In4.Cu")
		(net "FM_ADR_MODE_SEL")
	)
	(segment
		(start 396.780004 -76.942696)
		(end 397.535146 -77.697838)
		(width 0.089408)
		(layer "In4.Cu")
		(net "FM_ADR_MODE_SEL")
	)
	(segment
		(start 392.29157 -77.513942)
		(end 392.419078 -77.386434)
		(width 0.089408)
		(layer "In4.Cu")
		(net "FM_ADR_MODE_SEL")
	)
	(segment
		(start 386.098796 -77.753718)
		(end 386.919216 -78.574138)
		(width 0.089408)
		(layer "In4.Cu")
		(net "FM_ADR_MODE_SEL")
	)
	(segment
		(start 395.391894 -76.942696)
		(end 396.780004 -76.942696)
		(width 0.089408)
		(layer "In4.Cu")
		(net "FM_ADR_MODE_SEL")
	)
	(segment
		(start 401.069302 -76.585064)
		(end 403.892258 -73.762108)
		(width 0.089408)
		(layer "In4.Cu")
		(net "FM_ADR_MODE_SEL")
	)
	(segment
		(start 398.810226 -76.585064)
		(end 401.069302 -76.585064)
		(width 0.089408)
		(layer "In4.Cu")
		(net "FM_ADR_MODE_SEL")
	)
	(segment
		(start 397.535146 -77.697838)
		(end 397.697452 -77.697838)
		(width 0.089408)
		(layer "In4.Cu")
		(net "FM_ADR_MODE_SEL")
	)
	(segment
		(start 379.924056 -80.694784)
		(end 381.350266 -79.268574)
		(width 0.089408)
		(layer "In4.Cu")
		(net "FM_ADR_MODE_SEL")
	)
	(segment
		(start 382.71831 -79.268574)
		(end 384.233166 -77.753718)
		(width 0.089408)
		(layer "In4.Cu")
		(net "FM_ADR_MODE_SEL")
	)
	(segment
		(start 374.344692 -71.895208)
		(end 373.944896 -72.295004)
		(width 0.1016)
		(layer "F.Cu")
		(net "FM_PLD_DEBUG_MODE_N")
	)
	(via
		(at 374.097296 -67.849242)
		(size 0.6604)
		(drill 0.3302)
		(layers "F.Cu" "B.Cu")
		(net "FM_PLD_DEBUG_MODE_N")
	)
	(via
		(at 374.344692 -71.895208)
		(size 0.4572)
		(drill 0.2032)
		(layers "F.Cu" "B.Cu")
		(net "FM_PLD_DEBUG_MODE_N")
	)
	(segment
		(start 374.097296 -67.849242)
		(end 374.097296 -68.345304)
		(width 0.10795)
		(layer "B.Cu")
		(net "FM_PLD_DEBUG_MODE_N")
	)
	(segment
		(start 374.097296 -68.345304)
		(end 373.9515 -68.4911)
		(width 0.10795)
		(layer "B.Cu")
		(net "FM_PLD_DEBUG_MODE_N")
	)
	(segment
		(start 374.65 -67.296538)
		(end 374.097296 -67.849242)
		(width 0.10795)
		(layer "B.Cu")
		(net "FM_PLD_DEBUG_MODE_N")
	)
	(segment
		(start 374.65 -66.929)
		(end 374.65 -67.296538)
		(width 0.10795)
		(layer "B.Cu")
		(net "FM_PLD_DEBUG_MODE_N")
	)
	(segment
		(start 373.9515 -68.4911)
		(end 373.9515 -71.502016)
		(width 0.10795)
		(layer "B.Cu")
		(net "FM_PLD_DEBUG_MODE_N")
	)
	(segment
		(start 373.9515 -71.502016)
		(end 374.344692 -71.895208)
		(width 0.10795)
		(layer "B.Cu")
		(net "FM_PLD_DEBUG_MODE_N")
	)
	(segment
		(start 368.745262 -76.694792)
		(end 369.145058 -76.294996)
		(width 0.10795)
		(layer "F.Cu")
		(net "TP_CPLD1_PR12D")
	)
	(via
		(at 368.745262 -76.694792)
		(size 0.4572)
		(drill 0.2032)
		(layers "F.Cu" "B.Cu")
		(net "TP_CPLD1_PR12D")
	)
	(segment
		(start 367.945162 -67.895216)
		(end 368.344958 -68.295012)
		(width 0.10795)
		(layer "F.Cu")
		(net "TP_CPLD1_PT22D")
	)
	(via
		(at 368.172238 -67.187826)
		(size 0.6604)
		(drill 0.3302)
		(layers "F.Cu" "B.Cu")
		(net "TP_CPLD1_PT22D")
	)
	(via
		(at 367.945162 -67.895216)
		(size 0.4572)
		(drill 0.2032)
		(layers "F.Cu" "B.Cu")
		(net "TP_CPLD1_PT22D")
	)
	(segment
		(start 367.945162 -67.895216)
		(end 367.945162 -67.414902)
		(width 0.10795)
		(layer "B.Cu")
		(net "TP_CPLD1_PT22D")
	)
	(segment
		(start 367.945162 -67.414902)
		(end 368.172238 -67.187826)
		(width 0.10795)
		(layer "B.Cu")
		(net "TP_CPLD1_PT22D")
	)
	(segment
		(start 391.69975 -101.039676)
		(end 391.20445 -101.2698)
		(width 0.10795)
		(layer "F.Cu")
		(net "FM_CPU1_THERMTRIP_LATCH_LVT3_N")
	)
	(segment
		(start 375.944892 -69.495162)
		(end 375.545096 -69.894958)
		(width 0.1016)
		(layer "F.Cu")
		(net "FM_CPU1_THERMTRIP_LATCH_LVT3_N")
	)
	(segment
		(start 417.490148 -29.734764)
		(end 417.890198 -29.334714)
		(width 0.10795)
		(layer "F.Cu")
		(net "FM_CPU1_THERMTRIP_LATCH_LVT3_N")
	)
	(via
		(at 417.890198 -29.334714)
		(size 0.4572)
		(drill 0.2032)
		(layers "F.Cu" "B.Cu")
		(net "FM_CPU1_THERMTRIP_LATCH_LVT3_N")
	)
	(via
		(at 375.944892 -69.495162)
		(size 0.4572)
		(drill 0.2032)
		(layers "F.Cu" "B.Cu")
		(net "FM_CPU1_THERMTRIP_LATCH_LVT3_N")
	)
	(via
		(at 383.2098 -28.5496)
		(size 0.6604)
		(drill 0.3302)
		(layers "F.Cu" "B.Cu")
		(net "FM_CPU1_THERMTRIP_LATCH_LVT3_N")
	)
	(via
		(at 384.525266 -28.790646)
		(size 0.508)
		(drill 0.254)
		(layers "F.Cu" "B.Cu")
		(net "FM_CPU1_THERMTRIP_LATCH_LVT3_N")
	)
	(via
		(at 391.69975 -101.039676)
		(size 0.508)
		(drill 0.254)
		(layers "F.Cu" "B.Cu")
		(net "FM_CPU1_THERMTRIP_LATCH_LVT3_N")
	)
	(segment
		(start 384.28422 -28.5496)
		(end 384.525266 -28.790646)
		(width 0.10795)
		(layer "B.Cu")
		(net "FM_CPU1_THERMTRIP_LATCH_LVT3_N")
	)
	(segment
		(start 383.2098 -28.5496)
		(end 384.28422 -28.5496)
		(width 0.10795)
		(layer "B.Cu")
		(net "FM_CPU1_THERMTRIP_LATCH_LVT3_N")
	)
	(segment
		(start 370.9162 -81.37779)
		(end 370.9162 -80.738218)
		(width 0.089408)
		(layer "In2.Cu")
		(net "FM_CPU1_THERMTRIP_LATCH_LVT3_N")
	)
	(segment
		(start 373.646192 -93.191838)
		(end 373.646192 -89.4715)
		(width 0.089408)
		(layer "In2.Cu")
		(net "FM_CPU1_THERMTRIP_LATCH_LVT3_N")
	)
	(segment
		(start 372.07698 -73.891394)
		(end 372.872 -73.096374)
		(width 0.089408)
		(layer "In2.Cu")
		(net "FM_CPU1_THERMTRIP_LATCH_LVT3_N")
	)
	(segment
		(start 369.9383 -79.75981)
		(end 369.69319 -79.5147)
		(width 0.089408)
		(layer "In2.Cu")
		(net "FM_CPU1_THERMTRIP_LATCH_LVT3_N")
	)
	(segment
		(start 373.514366 -83.01736)
		(end 372.55577 -83.01736)
		(width 0.089408)
		(layer "In2.Cu")
		(net "FM_CPU1_THERMTRIP_LATCH_LVT3_N")
	)
	(segment
		(start 370.56441 -76.287376)
		(end 370.75745 -76.094336)
		(width 0.089408)
		(layer "In2.Cu")
		(net "FM_CPU1_THERMTRIP_LATCH_LVT3_N")
	)
	(segment
		(start 370.209318 -76.287376)
		(end 370.56441 -76.287376)
		(width 0.089408)
		(layer "In2.Cu")
		(net "FM_CPU1_THERMTRIP_LATCH_LVT3_N")
	)
	(segment
		(start 377.55068 -97.890584)
		(end 377.420886 -97.76079)
		(width 0.0889)
		(layer "In2.Cu")
		(net "FM_CPU1_THERMTRIP_LATCH_LVT3_N")
	)
	(segment
		(start 371.302026 -73.891394)
		(end 372.07698 -73.891394)
		(width 0.089408)
		(layer "In2.Cu")
		(net "FM_CPU1_THERMTRIP_LATCH_LVT3_N")
	)
	(segment
		(start 372.55577 -83.01736)
		(end 370.9162 -81.37779)
		(width 0.089408)
		(layer "In2.Cu")
		(net "FM_CPU1_THERMTRIP_LATCH_LVT3_N")
	)
	(segment
		(start 369.676426 -77.921358)
		(end 369.971828 -77.625956)
		(width 0.089408)
		(layer "In2.Cu")
		(net "FM_CPU1_THERMTRIP_LATCH_LVT3_N")
	)
	(segment
		(start 377.228862 -96.762062)
		(end 376.771408 -96.304608)
		(width 0.089408)
		(layer "In2.Cu")
		(net "FM_CPU1_THERMTRIP_LATCH_LVT3_N")
	)
	(segment
		(start 376.771408 -96.304608)
		(end 376.771408 -96.006666)
		(width 0.089408)
		(layer "In2.Cu")
		(net "FM_CPU1_THERMTRIP_LATCH_LVT3_N")
	)
	(segment
		(start 372.872 -73.096374)
		(end 372.872 -70.440042)
		(width 0.089408)
		(layer "In2.Cu")
		(net "FM_CPU1_THERMTRIP_LATCH_LVT3_N")
	)
	(segment
		(start 369.971828 -77.625956)
		(end 369.971828 -77.340206)
		(width 0.089408)
		(layer "In2.Cu")
		(net "FM_CPU1_THERMTRIP_LATCH_LVT3_N")
	)
	(segment
		(start 370.9162 -80.738218)
		(end 370.454682 -80.2767)
		(width 0.089408)
		(layer "In2.Cu")
		(net "FM_CPU1_THERMTRIP_LATCH_LVT3_N")
	)
	(segment
		(start 373.646192 -89.4715)
		(end 375.342658 -87.775034)
		(width 0.089408)
		(layer "In2.Cu")
		(net "FM_CPU1_THERMTRIP_LATCH_LVT3_N")
	)
	(segment
		(start 374.132856 -93.678502)
		(end 373.646192 -93.191838)
		(width 0.089408)
		(layer "In2.Cu")
		(net "FM_CPU1_THERMTRIP_LATCH_LVT3_N")
	)
	(segment
		(start 369.436904 -79.5147)
		(end 369.171728 -79.249524)
		(width 0.089408)
		(layer "In2.Cu")
		(net "FM_CPU1_THERMTRIP_LATCH_LVT3_N")
	)
	(segment
		(start 376.771154 -96.006412)
		(end 376.771154 -95.9739)
		(width 0.089408)
		(layer "In2.Cu")
		(net "FM_CPU1_THERMTRIP_LATCH_LVT3_N")
	)
	(segment
		(start 370.199158 -80.2767)
		(end 369.9383 -80.015842)
		(width 0.089408)
		(layer "In2.Cu")
		(net "FM_CPU1_THERMTRIP_LATCH_LVT3_N")
	)
	(segment
		(start 370.454682 -80.2767)
		(end 370.199158 -80.2767)
		(width 0.089408)
		(layer "In2.Cu")
		(net "FM_CPU1_THERMTRIP_LATCH_LVT3_N")
	)
	(segment
		(start 369.971574 -76.849732)
		(end 369.971574 -76.54036)
		(width 0.089408)
		(layer "In2.Cu")
		(net "FM_CPU1_THERMTRIP_LATCH_LVT3_N")
	)
	(segment
		(start 374.475756 -93.678502)
		(end 374.132856 -93.678502)
		(width 0.089408)
		(layer "In2.Cu")
		(net "FM_CPU1_THERMTRIP_LATCH_LVT3_N")
	)
	(segment
		(start 373.398542 -69.9135)
		(end 375.526554 -69.9135)
		(width 0.089408)
		(layer "In2.Cu")
		(net "FM_CPU1_THERMTRIP_LATCH_LVT3_N")
	)
	(segment
		(start 377.420886 -97.76079)
		(end 377.228608 -97.568512)
		(width 0.089408)
		(layer "In2.Cu")
		(net "FM_CPU1_THERMTRIP_LATCH_LVT3_N")
	)
	(segment
		(start 377.228608 -97.568512)
		(end 377.228608 -97.083118)
		(width 0.089408)
		(layer "In2.Cu")
		(net "FM_CPU1_THERMTRIP_LATCH_LVT3_N")
	)
	(segment
		(start 370.75745 -76.094336)
		(end 370.75745 -74.43597)
		(width 0.089408)
		(layer "In2.Cu")
		(net "FM_CPU1_THERMTRIP_LATCH_LVT3_N")
	)
	(segment
		(start 376.771154 -95.9739)
		(end 374.475756 -93.678502)
		(width 0.089408)
		(layer "In2.Cu")
		(net "FM_CPU1_THERMTRIP_LATCH_LVT3_N")
	)
	(segment
		(start 375.342658 -87.775034)
		(end 375.342658 -84.845652)
		(width 0.089408)
		(layer "In2.Cu")
		(net "FM_CPU1_THERMTRIP_LATCH_LVT3_N")
	)
	(segment
		(start 370.75745 -74.43597)
		(end 371.302026 -73.891394)
		(width 0.089408)
		(layer "In2.Cu")
		(net "FM_CPU1_THERMTRIP_LATCH_LVT3_N")
	)
	(segment
		(start 376.771408 -96.006666)
		(end 376.771154 -96.006412)
		(width 0.089408)
		(layer "In2.Cu")
		(net "FM_CPU1_THERMTRIP_LATCH_LVT3_N")
	)
	(segment
		(start 377.228862 -97.082864)
		(end 377.228862 -96.762062)
		(width 0.089408)
		(layer "In2.Cu")
		(net "FM_CPU1_THERMTRIP_LATCH_LVT3_N")
	)
	(segment
		(start 369.975892 -76.536042)
		(end 369.975892 -76.520802)
		(width 0.089408)
		(layer "In2.Cu")
		(net "FM_CPU1_THERMTRIP_LATCH_LVT3_N")
	)
	(segment
		(start 369.971574 -76.54036)
		(end 369.975892 -76.536042)
		(width 0.089408)
		(layer "In2.Cu")
		(net "FM_CPU1_THERMTRIP_LATCH_LVT3_N")
	)
	(segment
		(start 377.228608 -97.083118)
		(end 377.228862 -97.082864)
		(width 0.089408)
		(layer "In2.Cu")
		(net "FM_CPU1_THERMTRIP_LATCH_LVT3_N")
	)
	(segment
		(start 369.69319 -79.5147)
		(end 369.436904 -79.5147)
		(width 0.089408)
		(layer "In2.Cu")
		(net "FM_CPU1_THERMTRIP_LATCH_LVT3_N")
	)
	(segment
		(start 369.171728 -79.249524)
		(end 369.171728 -78.140052)
		(width 0.089408)
		(layer "In2.Cu")
		(net "FM_CPU1_THERMTRIP_LATCH_LVT3_N")
	)
	(segment
		(start 369.390422 -77.921358)
		(end 369.676426 -77.921358)
		(width 0.089408)
		(layer "In2.Cu")
		(net "FM_CPU1_THERMTRIP_LATCH_LVT3_N")
	)
	(segment
		(start 375.526554 -69.9135)
		(end 375.944892 -69.495162)
		(width 0.089408)
		(layer "In2.Cu")
		(net "FM_CPU1_THERMTRIP_LATCH_LVT3_N")
	)
	(segment
		(start 375.342658 -84.845652)
		(end 373.514366 -83.01736)
		(width 0.089408)
		(layer "In2.Cu")
		(net "FM_CPU1_THERMTRIP_LATCH_LVT3_N")
	)
	(segment
		(start 369.975892 -76.85405)
		(end 369.971574 -76.849732)
		(width 0.089408)
		(layer "In2.Cu")
		(net "FM_CPU1_THERMTRIP_LATCH_LVT3_N")
	)
	(segment
		(start 369.975892 -77.336142)
		(end 369.975892 -76.85405)
		(width 0.089408)
		(layer "In2.Cu")
		(net "FM_CPU1_THERMTRIP_LATCH_LVT3_N")
	)
	(segment
		(start 369.171728 -78.140052)
		(end 369.390422 -77.921358)
		(width 0.089408)
		(layer "In2.Cu")
		(net "FM_CPU1_THERMTRIP_LATCH_LVT3_N")
	)
	(segment
		(start 372.872 -70.440042)
		(end 373.398542 -69.9135)
		(width 0.089408)
		(layer "In2.Cu")
		(net "FM_CPU1_THERMTRIP_LATCH_LVT3_N")
	)
	(segment
		(start 369.975892 -76.520802)
		(end 370.209318 -76.287376)
		(width 0.089408)
		(layer "In2.Cu")
		(net "FM_CPU1_THERMTRIP_LATCH_LVT3_N")
	)
	(segment
		(start 388.8232 -98.475292)
		(end 388.8232 -98.442526)
		(width 0.0889)
		(layer "In2.Cu")
		(net "FM_CPU1_THERMTRIP_LATCH_LVT3_N")
	)
	(segment
		(start 390.80821 -100.266246)
		(end 390.8044 -100.159566)
		(width 0.0889)
		(layer "In2.Cu")
		(net "FM_CPU1_THERMTRIP_LATCH_LVT3_N")
	)
	(segment
		(start 369.971828 -77.340206)
		(end 369.975892 -77.336142)
		(width 0.089408)
		(layer "In2.Cu")
		(net "FM_CPU1_THERMTRIP_LATCH_LVT3_N")
	)
	(segment
		(start 369.9383 -80.015842)
		(end 369.9383 -79.75981)
		(width 0.089408)
		(layer "In2.Cu")
		(net "FM_CPU1_THERMTRIP_LATCH_LVT3_N")
	)
	(arc
		(start 390.8044 -100.159566)
		(mid 390.499957 -99.664089)
		(end 389.918448 -99.669346)
		(width 0.0889)
		(layer "In2.Cu")
		(net "FM_CPU1_THERMTRIP_LATCH_LVT3_N")
	)
	(arc
		(start 391.69975 -101.039676)
		(mid 391.085786 -100.846855)
		(end 390.80821 -100.266246)
		(width 0.0889)
		(layer "In2.Cu")
		(net "FM_CPU1_THERMTRIP_LATCH_LVT3_N")
	)
	(arc
		(start 385.556252 -97.952306)
		(mid 385.26085 -97.873175)
		(end 384.965448 -97.952306)
		(width 0.0889)
		(layer "In2.Cu")
		(net "FM_CPU1_THERMTRIP_LATCH_LVT3_N")
	)
	(arc
		(start 385.956048 -97.952306)
		(mid 385.75615 -98.005805)
		(end 385.556252 -97.952306)
		(width 0.0889)
		(layer "In2.Cu")
		(net "FM_CPU1_THERMTRIP_LATCH_LVT3_N")
	)
	(arc
		(start 384.565652 -97.952306)
		(mid 384.27025 -97.873175)
		(end 383.974848 -97.952306)
		(width 0.0889)
		(layer "In2.Cu")
		(net "FM_CPU1_THERMTRIP_LATCH_LVT3_N")
	)
	(arc
		(start 381.593852 -97.952306)
		(mid 381.29845 -97.873175)
		(end 381.003048 -97.952306)
		(width 0.0889)
		(layer "In2.Cu")
		(net "FM_CPU1_THERMTRIP_LATCH_LVT3_N")
	)
	(arc
		(start 382.584452 -97.952306)
		(mid 382.28905 -97.873175)
		(end 381.993648 -97.952306)
		(width 0.0889)
		(layer "In2.Cu")
		(net "FM_CPU1_THERMTRIP_LATCH_LVT3_N")
	)
	(arc
		(start 389.023352 -98.810826)
		(mid 388.879548 -98.669143)
		(end 388.8232 -98.475292)
		(width 0.0889)
		(layer "In2.Cu")
		(net "FM_CPU1_THERMTRIP_LATCH_LVT3_N")
	)
	(arc
		(start 379.021848 -97.952306)
		(mid 378.82195 -98.005805)
		(end 378.622052 -97.952306)
		(width 0.0889)
		(layer "In2.Cu")
		(net "FM_CPU1_THERMTRIP_LATCH_LVT3_N")
	)
	(arc
		(start 380.603252 -97.952306)
		(mid 380.30785 -97.873175)
		(end 380.012448 -97.952306)
		(width 0.0889)
		(layer "In2.Cu")
		(net "FM_CPU1_THERMTRIP_LATCH_LVT3_N")
	)
	(arc
		(start 388.8232 -98.442526)
		(mid 388.518757 -97.947049)
		(end 387.937248 -97.952306)
		(width 0.0889)
		(layer "In2.Cu")
		(net "FM_CPU1_THERMTRIP_LATCH_LVT3_N")
	)
	(arc
		(start 377.631452 -97.952306)
		(mid 377.589019 -97.924124)
		(end 377.55068 -97.890584)
		(width 0.0889)
		(layer "In2.Cu")
		(net "FM_CPU1_THERMTRIP_LATCH_LVT3_N")
	)
	(arc
		(start 384.965448 -97.952306)
		(mid 384.76555 -98.005805)
		(end 384.565652 -97.952306)
		(width 0.0889)
		(layer "In2.Cu")
		(net "FM_CPU1_THERMTRIP_LATCH_LVT3_N")
	)
	(arc
		(start 383.974848 -97.952306)
		(mid 383.77495 -98.005805)
		(end 383.575052 -97.952306)
		(width 0.0889)
		(layer "In2.Cu")
		(net "FM_CPU1_THERMTRIP_LATCH_LVT3_N")
	)
	(arc
		(start 387.537452 -97.952306)
		(mid 387.24205 -97.873175)
		(end 386.946648 -97.952306)
		(width 0.0889)
		(layer "In2.Cu")
		(net "FM_CPU1_THERMTRIP_LATCH_LVT3_N")
	)
	(arc
		(start 383.575052 -97.952306)
		(mid 383.27965 -97.873175)
		(end 382.984248 -97.952306)
		(width 0.0889)
		(layer "In2.Cu")
		(net "FM_CPU1_THERMTRIP_LATCH_LVT3_N")
	)
	(arc
		(start 389.315452 -99.257612)
		(mid 389.222744 -98.999342)
		(end 389.023352 -98.810826)
		(width 0.0889)
		(layer "In2.Cu")
		(net "FM_CPU1_THERMTRIP_LATCH_LVT3_N")
	)
	(arc
		(start 382.984248 -97.952306)
		(mid 382.78435 -98.005805)
		(end 382.584452 -97.952306)
		(width 0.0889)
		(layer "In2.Cu")
		(net "FM_CPU1_THERMTRIP_LATCH_LVT3_N")
	)
	(arc
		(start 378.622052 -97.952306)
		(mid 378.32665 -97.873175)
		(end 378.031248 -97.952306)
		(width 0.0889)
		(layer "In2.Cu")
		(net "FM_CPU1_THERMTRIP_LATCH_LVT3_N")
	)
	(arc
		(start 387.937248 -97.952306)
		(mid 387.73735 -98.005805)
		(end 387.537452 -97.952306)
		(width 0.0889)
		(layer "In2.Cu")
		(net "FM_CPU1_THERMTRIP_LATCH_LVT3_N")
	)
	(arc
		(start 386.946648 -97.952306)
		(mid 386.74675 -98.005805)
		(end 386.546852 -97.952306)
		(width 0.0889)
		(layer "In2.Cu")
		(net "FM_CPU1_THERMTRIP_LATCH_LVT3_N")
	)
	(arc
		(start 378.031248 -97.952306)
		(mid 377.83135 -98.005805)
		(end 377.631452 -97.952306)
		(width 0.0889)
		(layer "In2.Cu")
		(net "FM_CPU1_THERMTRIP_LATCH_LVT3_N")
	)
	(arc
		(start 381.993648 -97.952306)
		(mid 381.79375 -98.005805)
		(end 381.593852 -97.952306)
		(width 0.0889)
		(layer "In2.Cu")
		(net "FM_CPU1_THERMTRIP_LATCH_LVT3_N")
	)
	(arc
		(start 379.612652 -97.952306)
		(mid 379.31725 -97.873175)
		(end 379.021848 -97.952306)
		(width 0.0889)
		(layer "In2.Cu")
		(net "FM_CPU1_THERMTRIP_LATCH_LVT3_N")
	)
	(arc
		(start 389.518652 -99.669346)
		(mid 389.35452 -99.494325)
		(end 389.315452 -99.257612)
		(width 0.0889)
		(layer "In2.Cu")
		(net "FM_CPU1_THERMTRIP_LATCH_LVT3_N")
	)
	(arc
		(start 380.012448 -97.952306)
		(mid 379.81255 -98.005805)
		(end 379.612652 -97.952306)
		(width 0.0889)
		(layer "In2.Cu")
		(net "FM_CPU1_THERMTRIP_LATCH_LVT3_N")
	)
	(arc
		(start 381.003048 -97.952306)
		(mid 380.80315 -98.005805)
		(end 380.603252 -97.952306)
		(width 0.0889)
		(layer "In2.Cu")
		(net "FM_CPU1_THERMTRIP_LATCH_LVT3_N")
	)
	(arc
		(start 389.918448 -99.669346)
		(mid 389.71855 -99.722845)
		(end 389.518652 -99.669346)
		(width 0.0889)
		(layer "In2.Cu")
		(net "FM_CPU1_THERMTRIP_LATCH_LVT3_N")
	)
	(arc
		(start 386.546852 -97.952306)
		(mid 386.25145 -97.873175)
		(end 385.956048 -97.952306)
		(width 0.0889)
		(layer "In2.Cu")
		(net "FM_CPU1_THERMTRIP_LATCH_LVT3_N")
	)
	(segment
		(start 392.400028 -29.640276)
		(end 392.561826 -29.802074)
		(width 0.089408)
		(layer "In4.Cu")
		(net "FM_CPU1_THERMTRIP_LATCH_LVT3_N")
	)
	(segment
		(start 388.5692 -31.594806)
		(end 388.5692 -31.368238)
		(width 0.089408)
		(layer "In4.Cu")
		(net "FM_CPU1_THERMTRIP_LATCH_LVT3_N")
	)
	(segment
		(start 417.890198 -29.105098)
		(end 417.890198 -29.334714)
		(width 0.089408)
		(layer "In4.Cu")
		(net "FM_CPU1_THERMTRIP_LATCH_LVT3_N")
	)
	(segment
		(start 417.50742 -28.29052)
		(end 417.50742 -28.72232)
		(width 0.089408)
		(layer "In4.Cu")
		(net "FM_CPU1_THERMTRIP_LATCH_LVT3_N")
	)
	(segment
		(start 408.16022 -28.134564)
		(end 410.85643 -28.134564)
		(width 0.089408)
		(layer "In4.Cu")
		(net "FM_CPU1_THERMTRIP_LATCH_LVT3_N")
	)
	(segment
		(start 401.439888 -29.122116)
		(end 402.28266 -29.964888)
		(width 0.089408)
		(layer "In4.Cu")
		(net "FM_CPU1_THERMTRIP_LATCH_LVT3_N")
	)
	(segment
		(start 405.136604 -29.964888)
		(end 405.156924 -29.985208)
		(width 0.089408)
		(layer "In4.Cu")
		(net "FM_CPU1_THERMTRIP_LATCH_LVT3_N")
	)
	(segment
		(start 410.85643 -28.134564)
		(end 410.862526 -28.14066)
		(width 0.089408)
		(layer "In4.Cu")
		(net "FM_CPU1_THERMTRIP_LATCH_LVT3_N")
	)
	(segment
		(start 390.297162 -29.640276)
		(end 392.400028 -29.640276)
		(width 0.089408)
		(layer "In4.Cu")
		(net "FM_CPU1_THERMTRIP_LATCH_LVT3_N")
	)
	(segment
		(start 394.49756 -29.122116)
		(end 401.439888 -29.122116)
		(width 0.089408)
		(layer "In4.Cu")
		(net "FM_CPU1_THERMTRIP_LATCH_LVT3_N")
	)
	(segment
		(start 393.817602 -29.802074)
		(end 394.49756 -29.122116)
		(width 0.089408)
		(layer "In4.Cu")
		(net "FM_CPU1_THERMTRIP_LATCH_LVT3_N")
	)
	(segment
		(start 392.561826 -29.802074)
		(end 393.817602 -29.802074)
		(width 0.089408)
		(layer "In4.Cu")
		(net "FM_CPU1_THERMTRIP_LATCH_LVT3_N")
	)
	(segment
		(start 405.156924 -29.985208)
		(end 406.309576 -29.985208)
		(width 0.089408)
		(layer "In4.Cu")
		(net "FM_CPU1_THERMTRIP_LATCH_LVT3_N")
	)
	(segment
		(start 417.35756 -28.14066)
		(end 417.50742 -28.29052)
		(width 0.089408)
		(layer "In4.Cu")
		(net "FM_CPU1_THERMTRIP_LATCH_LVT3_N")
	)
	(segment
		(start 406.309576 -29.985208)
		(end 408.16022 -28.134564)
		(width 0.089408)
		(layer "In4.Cu")
		(net "FM_CPU1_THERMTRIP_LATCH_LVT3_N")
	)
	(segment
		(start 384.525266 -28.790646)
		(end 386.122926 -30.388306)
		(width 0.089408)
		(layer "In4.Cu")
		(net "FM_CPU1_THERMTRIP_LATCH_LVT3_N")
	)
	(segment
		(start 388.034022 -32.129984)
		(end 388.5692 -31.594806)
		(width 0.089408)
		(layer "In4.Cu")
		(net "FM_CPU1_THERMTRIP_LATCH_LVT3_N")
	)
	(segment
		(start 402.28266 -29.964888)
		(end 405.136604 -29.964888)
		(width 0.089408)
		(layer "In4.Cu")
		(net "FM_CPU1_THERMTRIP_LATCH_LVT3_N")
	)
	(segment
		(start 386.122926 -30.388306)
		(end 386.122926 -31.435548)
		(width 0.089408)
		(layer "In4.Cu")
		(net "FM_CPU1_THERMTRIP_LATCH_LVT3_N")
	)
	(segment
		(start 386.122926 -31.435548)
		(end 386.817362 -32.129984)
		(width 0.089408)
		(layer "In4.Cu")
		(net "FM_CPU1_THERMTRIP_LATCH_LVT3_N")
	)
	(segment
		(start 388.5692 -31.368238)
		(end 390.297162 -29.640276)
		(width 0.089408)
		(layer "In4.Cu")
		(net "FM_CPU1_THERMTRIP_LATCH_LVT3_N")
	)
	(segment
		(start 410.862526 -28.14066)
		(end 417.35756 -28.14066)
		(width 0.089408)
		(layer "In4.Cu")
		(net "FM_CPU1_THERMTRIP_LATCH_LVT3_N")
	)
	(segment
		(start 386.817362 -32.129984)
		(end 388.034022 -32.129984)
		(width 0.089408)
		(layer "In4.Cu")
		(net "FM_CPU1_THERMTRIP_LATCH_LVT3_N")
	)
	(segment
		(start 417.50742 -28.72232)
		(end 417.890198 -29.105098)
		(width 0.089408)
		(layer "In4.Cu")
		(net "FM_CPU1_THERMTRIP_LATCH_LVT3_N")
	)
	(segment
		(start 380.548896 -46.93031)
		(end 381.766318 -45.712888)
		(width 0.089408)
		(layer "In9.Cu")
		(net "FM_CPU1_THERMTRIP_LATCH_LVT3_N")
	)
	(segment
		(start 375.944892 -69.495162)
		(end 376.352054 -69.088)
		(width 0.089408)
		(layer "In9.Cu")
		(net "FM_CPU1_THERMTRIP_LATCH_LVT3_N")
	)
	(segment
		(start 379.81636 -61.835284)
		(end 379.816106 -61.835284)
		(width 0.089408)
		(layer "In9.Cu")
		(net "FM_CPU1_THERMTRIP_LATCH_LVT3_N")
	)
	(segment
		(start 381.44831 -56.753252)
		(end 381.280162 -56.585104)
		(width 0.089408)
		(layer "In9.Cu")
		(net "FM_CPU1_THERMTRIP_LATCH_LVT3_N")
	)
	(segment
		(start 378.953268 -63.211456)
		(end 378.953268 -62.700662)
		(width 0.089408)
		(layer "In9.Cu")
		(net "FM_CPU1_THERMTRIP_LATCH_LVT3_N")
	)
	(segment
		(start 380.553976 -36.980114)
		(end 380.553976 -36.269168)
		(width 0.089408)
		(layer "In9.Cu")
		(net "FM_CPU1_THERMTRIP_LATCH_LVT3_N")
	)
	(segment
		(start 379.933962 -41.914064)
		(end 379.933962 -40.931338)
		(width 0.089408)
		(layer "In9.Cu")
		(net "FM_CPU1_THERMTRIP_LATCH_LVT3_N")
	)
	(segment
		(start 383.7559 -28.6004)
		(end 384.33502 -28.6004)
		(width 0.089408)
		(layer "In9.Cu")
		(net "FM_CPU1_THERMTRIP_LATCH_LVT3_N")
	)
	(segment
		(start 381.594868 -39.202868)
		(end 381.563626 -39.171626)
		(width 0.089408)
		(layer "In9.Cu")
		(net "FM_CPU1_THERMTRIP_LATCH_LVT3_N")
	)
	(segment
		(start 376.88012 -69.088)
		(end 377.171458 -68.796662)
		(width 0.089408)
		(layer "In9.Cu")
		(net "FM_CPU1_THERMTRIP_LATCH_LVT3_N")
	)
	(segment
		(start 381.328676 -40.646096)
		(end 381.594868 -40.379904)
		(width 0.089408)
		(layer "In9.Cu")
		(net "FM_CPU1_THERMTRIP_LATCH_LVT3_N")
	)
	(segment
		(start 382.427734 -32.850836)
		(end 382.571498 -32.707072)
		(width 0.089408)
		(layer "In9.Cu")
		(net "FM_CPU1_THERMTRIP_LATCH_LVT3_N")
	)
	(segment
		(start 382.427734 -34.359088)
		(end 382.427734 -32.850836)
		(width 0.089408)
		(layer "In9.Cu")
		(net "FM_CPU1_THERMTRIP_LATCH_LVT3_N")
	)
	(segment
		(start 380.80442 -38.41242)
		(end 380.80442 -37.230558)
		(width 0.089408)
		(layer "In9.Cu")
		(net "FM_CPU1_THERMTRIP_LATCH_LVT3_N")
	)
	(segment
		(start 381.315722 -38.923722)
		(end 380.80442 -38.41242)
		(width 0.089408)
		(layer "In9.Cu")
		(net "FM_CPU1_THERMTRIP_LATCH_LVT3_N")
	)
	(segment
		(start 381.329184 -38.923722)
		(end 381.315722 -38.923722)
		(width 0.089408)
		(layer "In9.Cu")
		(net "FM_CPU1_THERMTRIP_LATCH_LVT3_N")
	)
	(segment
		(start 381.44831 -57.526174)
		(end 381.44831 -56.753252)
		(width 0.089408)
		(layer "In9.Cu")
		(net "FM_CPU1_THERMTRIP_LATCH_LVT3_N")
	)
	(segment
		(start 379.933962 -40.931338)
		(end 380.219204 -40.646096)
		(width 0.089408)
		(layer "In9.Cu")
		(net "FM_CPU1_THERMTRIP_LATCH_LVT3_N")
	)
	(segment
		(start 382.571498 -29.784802)
		(end 383.7559 -28.6004)
		(width 0.089408)
		(layer "In9.Cu")
		(net "FM_CPU1_THERMTRIP_LATCH_LVT3_N")
	)
	(segment
		(start 377.853956 -64.310768)
		(end 378.953268 -63.211456)
		(width 0.089408)
		(layer "In9.Cu")
		(net "FM_CPU1_THERMTRIP_LATCH_LVT3_N")
	)
	(segment
		(start 381.926592 -34.86023)
		(end 382.427734 -34.359088)
		(width 0.089408)
		(layer "In9.Cu")
		(net "FM_CPU1_THERMTRIP_LATCH_LVT3_N")
	)
	(segment
		(start 380.553976 -35.825684)
		(end 380.553976 -35.400488)
		(width 0.089408)
		(layer "In9.Cu")
		(net "FM_CPU1_THERMTRIP_LATCH_LVT3_N")
	)
	(segment
		(start 381.280162 -56.585104)
		(end 381.280162 -51.679856)
		(width 0.089408)
		(layer "In9.Cu")
		(net "FM_CPU1_THERMTRIP_LATCH_LVT3_N")
	)
	(segment
		(start 380.553976 -36.269168)
		(end 380.553722 -36.268914)
		(width 0.089408)
		(layer "In9.Cu")
		(net "FM_CPU1_THERMTRIP_LATCH_LVT3_N")
	)
	(segment
		(start 382.571498 -32.707072)
		(end 382.571498 -29.784802)
		(width 0.089408)
		(layer "In9.Cu")
		(net "FM_CPU1_THERMTRIP_LATCH_LVT3_N")
	)
	(segment
		(start 378.953268 -62.700662)
		(end 379.81636 -61.83757)
		(width 0.089408)
		(layer "In9.Cu")
		(net "FM_CPU1_THERMTRIP_LATCH_LVT3_N")
	)
	(segment
		(start 381.563626 -39.171626)
		(end 381.563626 -39.158164)
		(width 0.089408)
		(layer "In9.Cu")
		(net "FM_CPU1_THERMTRIP_LATCH_LVT3_N")
	)
	(segment
		(start 380.553722 -36.268914)
		(end 380.553722 -35.825938)
		(width 0.089408)
		(layer "In9.Cu")
		(net "FM_CPU1_THERMTRIP_LATCH_LVT3_N")
	)
	(segment
		(start 380.219204 -40.646096)
		(end 381.328676 -40.646096)
		(width 0.089408)
		(layer "In9.Cu")
		(net "FM_CPU1_THERMTRIP_LATCH_LVT3_N")
	)
	(segment
		(start 380.80442 -37.230558)
		(end 380.553976 -36.980114)
		(width 0.089408)
		(layer "In9.Cu")
		(net "FM_CPU1_THERMTRIP_LATCH_LVT3_N")
	)
	(segment
		(start 381.094234 -34.86023)
		(end 381.926592 -34.86023)
		(width 0.089408)
		(layer "In9.Cu")
		(net "FM_CPU1_THERMTRIP_LATCH_LVT3_N")
	)
	(segment
		(start 376.352054 -69.088)
		(end 376.88012 -69.088)
		(width 0.089408)
		(layer "In9.Cu")
		(net "FM_CPU1_THERMTRIP_LATCH_LVT3_N")
	)
	(segment
		(start 379.816106 -61.835284)
		(end 379.816106 -59.158378)
		(width 0.089408)
		(layer "In9.Cu")
		(net "FM_CPU1_THERMTRIP_LATCH_LVT3_N")
	)
	(segment
		(start 381.594868 -40.379904)
		(end 381.594868 -39.202868)
		(width 0.089408)
		(layer "In9.Cu")
		(net "FM_CPU1_THERMTRIP_LATCH_LVT3_N")
	)
	(segment
		(start 381.563626 -39.158164)
		(end 381.329184 -38.923722)
		(width 0.089408)
		(layer "In9.Cu")
		(net "FM_CPU1_THERMTRIP_LATCH_LVT3_N")
	)
	(segment
		(start 381.766318 -43.74642)
		(end 379.933962 -41.914064)
		(width 0.089408)
		(layer "In9.Cu")
		(net "FM_CPU1_THERMTRIP_LATCH_LVT3_N")
	)
	(segment
		(start 377.171458 -67.74053)
		(end 377.551188 -67.3608)
		(width 0.089408)
		(layer "In9.Cu")
		(net "FM_CPU1_THERMTRIP_LATCH_LVT3_N")
	)
	(segment
		(start 379.81636 -61.83757)
		(end 379.81636 -61.835284)
		(width 0.089408)
		(layer "In9.Cu")
		(net "FM_CPU1_THERMTRIP_LATCH_LVT3_N")
	)
	(segment
		(start 380.553722 -35.825938)
		(end 380.553976 -35.825684)
		(width 0.089408)
		(layer "In9.Cu")
		(net "FM_CPU1_THERMTRIP_LATCH_LVT3_N")
	)
	(segment
		(start 379.816106 -59.158378)
		(end 381.44831 -57.526174)
		(width 0.089408)
		(layer "In9.Cu")
		(net "FM_CPU1_THERMTRIP_LATCH_LVT3_N")
	)
	(segment
		(start 377.171458 -68.796662)
		(end 377.171458 -67.74053)
		(width 0.089408)
		(layer "In9.Cu")
		(net "FM_CPU1_THERMTRIP_LATCH_LVT3_N")
	)
	(segment
		(start 381.766318 -45.712888)
		(end 381.766318 -43.74642)
		(width 0.089408)
		(layer "In9.Cu")
		(net "FM_CPU1_THERMTRIP_LATCH_LVT3_N")
	)
	(segment
		(start 381.280162 -51.679856)
		(end 380.548896 -50.94859)
		(width 0.089408)
		(layer "In9.Cu")
		(net "FM_CPU1_THERMTRIP_LATCH_LVT3_N")
	)
	(segment
		(start 377.551188 -64.998346)
		(end 377.853956 -64.695578)
		(width 0.089408)
		(layer "In9.Cu")
		(net "FM_CPU1_THERMTRIP_LATCH_LVT3_N")
	)
	(segment
		(start 380.553976 -35.400488)
		(end 381.094234 -34.86023)
		(width 0.089408)
		(layer "In9.Cu")
		(net "FM_CPU1_THERMTRIP_LATCH_LVT3_N")
	)
	(segment
		(start 377.853956 -64.695578)
		(end 377.853956 -64.310768)
		(width 0.089408)
		(layer "In9.Cu")
		(net "FM_CPU1_THERMTRIP_LATCH_LVT3_N")
	)
	(segment
		(start 377.551188 -67.3608)
		(end 377.551188 -64.998346)
		(width 0.089408)
		(layer "In9.Cu")
		(net "FM_CPU1_THERMTRIP_LATCH_LVT3_N")
	)
	(segment
		(start 380.548896 -50.94859)
		(end 380.548896 -46.93031)
		(width 0.089408)
		(layer "In9.Cu")
		(net "FM_CPU1_THERMTRIP_LATCH_LVT3_N")
	)
	(segment
		(start 384.33502 -28.6004)
		(end 384.525266 -28.790646)
		(width 0.089408)
		(layer "In9.Cu")
		(net "FM_CPU1_THERMTRIP_LATCH_LVT3_N")
	)
	(segment
		(start 371.165628 -80.715612)
		(end 370.745004 -80.294988)
		(width 0.1016)
		(layer "F.Cu")
		(net "FM_CPU1_PKGID2")
	)
	(segment
		(start 79.768192 -89.27084)
		(end 79.196692 -89.27084)
		(width 0.10795)
		(layer "F.Cu")
		(net "FM_CPU1_PKGID2")
	)
	(segment
		(start 371.75694 -81.617566)
		(end 371.165628 -81.026254)
		(width 0.1016)
		(layer "F.Cu")
		(net "FM_CPU1_PKGID2")
	)
	(segment
		(start 371.165628 -81.026254)
		(end 371.165628 -80.715612)
		(width 0.1016)
		(layer "F.Cu")
		(net "FM_CPU1_PKGID2")
	)
	(via
		(at 65.1002 -91.1352)
		(size 0.6604)
		(drill 0.3302)
		(layers "F.Cu" "B.Cu")
		(net "FM_CPU1_PKGID2")
	)
	(via
		(at 178.7652 -128.8034)
		(size 0.508)
		(drill 0.254)
		(layers "F.Cu" "B.Cu")
		(net "FM_CPU1_PKGID2")
	)
	(via
		(at 373.521224 -65.2526)
		(size 0.508)
		(drill 0.254)
		(layers "F.Cu" "B.Cu")
		(net "FM_CPU1_PKGID2")
	)
	(via
		(at 164.27704 -150.619968)
		(size 0.508)
		(drill 0.254)
		(layers "F.Cu" "B.Cu")
		(net "FM_CPU1_PKGID2")
	)
	(via
		(at 371.75694 -81.617566)
		(size 0.4572)
		(drill 0.2032)
		(layers "F.Cu" "B.Cu")
		(net "FM_CPU1_PKGID2")
	)
	(via
		(at 79.196692 -89.27084)
		(size 0.508)
		(drill 0.254)
		(layers "F.Cu" "B.Cu")
		(net "FM_CPU1_PKGID2")
	)
	(segment
		(start 72.154034 -90.796364)
		(end 71.704708 -90.347038)
		(width 0.10795)
		(layer "B.Cu")
		(net "FM_CPU1_PKGID2")
	)
	(segment
		(start 79.196692 -89.27084)
		(end 78.74762 -89.719912)
		(width 0.10795)
		(layer "B.Cu")
		(net "FM_CPU1_PKGID2")
	)
	(segment
		(start 65.924684 -91.1352)
		(end 65.1002 -91.1352)
		(width 0.10795)
		(layer "B.Cu")
		(net "FM_CPU1_PKGID2")
	)
	(segment
		(start 78.74762 -89.719912)
		(end 78.74762 -89.935558)
		(width 0.10795)
		(layer "B.Cu")
		(net "FM_CPU1_PKGID2")
	)
	(segment
		(start 76.00061 -90.760296)
		(end 75.502008 -90.760296)
		(width 0.10795)
		(layer "B.Cu")
		(net "FM_CPU1_PKGID2")
	)
	(segment
		(start 78.507844 -90.175334)
		(end 78.306676 -90.175334)
		(width 0.10795)
		(layer "B.Cu")
		(net "FM_CPU1_PKGID2")
	)
	(segment
		(start 76.432156 -90.330274)
		(end 76.00061 -90.760296)
		(width 0.10795)
		(layer "B.Cu")
		(net "FM_CPU1_PKGID2")
	)
	(segment
		(start 66.376042 -90.683842)
		(end 65.924684 -91.1352)
		(width 0.10795)
		(layer "B.Cu")
		(net "FM_CPU1_PKGID2")
	)
	(segment
		(start 71.704708 -90.347038)
		(end 71.271638 -90.347038)
		(width 0.10795)
		(layer "B.Cu")
		(net "FM_CPU1_PKGID2")
	)
	(segment
		(start 78.74762 -89.935558)
		(end 78.507844 -90.175334)
		(width 0.10795)
		(layer "B.Cu")
		(net "FM_CPU1_PKGID2")
	)
	(segment
		(start 70.840346 -90.77833)
		(end 70.400926 -90.77833)
		(width 0.10795)
		(layer "B.Cu")
		(net "FM_CPU1_PKGID2")
	)
	(segment
		(start 77.718412 -90.763598)
		(end 77.207618 -90.763598)
		(width 0.10795)
		(layer "B.Cu")
		(net "FM_CPU1_PKGID2")
	)
	(segment
		(start 69.418962 -90.347038)
		(end 69.082158 -90.683842)
		(width 0.10795)
		(layer "B.Cu")
		(net "FM_CPU1_PKGID2")
	)
	(segment
		(start 74.21753 -90.670888)
		(end 73.680828 -90.670888)
		(width 0.10795)
		(layer "B.Cu")
		(net "FM_CPU1_PKGID2")
	)
	(segment
		(start 75.08875 -90.347038)
		(end 74.54138 -90.347038)
		(width 0.10795)
		(layer "B.Cu")
		(net "FM_CPU1_PKGID2")
	)
	(segment
		(start 74.54138 -90.347038)
		(end 74.21753 -90.670888)
		(width 0.10795)
		(layer "B.Cu")
		(net "FM_CPU1_PKGID2")
	)
	(segment
		(start 72.952864 -90.347038)
		(end 72.503538 -90.796364)
		(width 0.10795)
		(layer "B.Cu")
		(net "FM_CPU1_PKGID2")
	)
	(segment
		(start 72.503538 -90.796364)
		(end 72.154034 -90.796364)
		(width 0.10795)
		(layer "B.Cu")
		(net "FM_CPU1_PKGID2")
	)
	(segment
		(start 76.774294 -90.330274)
		(end 76.432156 -90.330274)
		(width 0.10795)
		(layer "B.Cu")
		(net "FM_CPU1_PKGID2")
	)
	(segment
		(start 73.680828 -90.670888)
		(end 73.356978 -90.347038)
		(width 0.10795)
		(layer "B.Cu")
		(net "FM_CPU1_PKGID2")
	)
	(segment
		(start 69.082158 -90.683842)
		(end 66.376042 -90.683842)
		(width 0.10795)
		(layer "B.Cu")
		(net "FM_CPU1_PKGID2")
	)
	(segment
		(start 71.271638 -90.347038)
		(end 70.840346 -90.77833)
		(width 0.10795)
		(layer "B.Cu")
		(net "FM_CPU1_PKGID2")
	)
	(segment
		(start 73.356978 -90.347038)
		(end 72.952864 -90.347038)
		(width 0.10795)
		(layer "B.Cu")
		(net "FM_CPU1_PKGID2")
	)
	(segment
		(start 69.967348 -90.347038)
		(end 69.418962 -90.347038)
		(width 0.10795)
		(layer "B.Cu")
		(net "FM_CPU1_PKGID2")
	)
	(segment
		(start 77.207618 -90.763598)
		(end 76.774294 -90.330274)
		(width 0.10795)
		(layer "B.Cu")
		(net "FM_CPU1_PKGID2")
	)
	(segment
		(start 78.306676 -90.175334)
		(end 77.718412 -90.763598)
		(width 0.10795)
		(layer "B.Cu")
		(net "FM_CPU1_PKGID2")
	)
	(segment
		(start 75.502008 -90.760296)
		(end 75.08875 -90.347038)
		(width 0.10795)
		(layer "B.Cu")
		(net "FM_CPU1_PKGID2")
	)
	(segment
		(start 70.400926 -90.77833)
		(end 69.967348 -90.347038)
		(width 0.10795)
		(layer "B.Cu")
		(net "FM_CPU1_PKGID2")
	)
	(segment
		(start 65.1002 -91.1352)
		(end 64.1858 -91.1352)
		(width 0.10795)
		(layer "B.Cu")
		(net "FM_CPU1_PKGID2")
	)
	(segment
		(start 165.99916 -147.01266)
		(end 164.93236 -147.01266)
		(width 0.089408)
		(layer "In2.Cu")
		(net "FM_CPU1_PKGID2")
	)
	(segment
		(start 164.01288 -147.93214)
		(end 164.01288 -150.355808)
		(width 0.089408)
		(layer "In2.Cu")
		(net "FM_CPU1_PKGID2")
	)
	(segment
		(start 166.56304 -142.61338)
		(end 166.56304 -146.44878)
		(width 0.089408)
		(layer "In2.Cu")
		(net "FM_CPU1_PKGID2")
	)
	(segment
		(start 164.01288 -150.355808)
		(end 164.27704 -150.619968)
		(width 0.089408)
		(layer "In2.Cu")
		(net "FM_CPU1_PKGID2")
	)
	(segment
		(start 165.18382 -141.28242)
		(end 165.23208 -141.28242)
		(width 0.089408)
		(layer "In2.Cu")
		(net "FM_CPU1_PKGID2")
	)
	(segment
		(start 178.7652 -128.8034)
		(end 166.37 -128.8034)
		(width 0.089408)
		(layer "In2.Cu")
		(net "FM_CPU1_PKGID2")
	)
	(segment
		(start 166.56304 -146.44878)
		(end 165.99916 -147.01266)
		(width 0.089408)
		(layer "In2.Cu")
		(net "FM_CPU1_PKGID2")
	)
	(segment
		(start 164.93236 -147.01266)
		(end 164.01288 -147.93214)
		(width 0.089408)
		(layer "In2.Cu")
		(net "FM_CPU1_PKGID2")
	)
	(segment
		(start 164.57422 -140.67282)
		(end 165.18382 -141.28242)
		(width 0.089408)
		(layer "In2.Cu")
		(net "FM_CPU1_PKGID2")
	)
	(segment
		(start 166.37 -128.8034)
		(end 164.57422 -130.59918)
		(width 0.089408)
		(layer "In2.Cu")
		(net "FM_CPU1_PKGID2")
	)
	(segment
		(start 165.23208 -141.28242)
		(end 166.56304 -142.61338)
		(width 0.089408)
		(layer "In2.Cu")
		(net "FM_CPU1_PKGID2")
	)
	(segment
		(start 164.57422 -130.59918)
		(end 164.57422 -140.67282)
		(width 0.089408)
		(layer "In2.Cu")
		(net "FM_CPU1_PKGID2")
	)
	(segment
		(start 371.87886 -67.126612)
		(end 371.87886 -67.559682)
		(width 0.089408)
		(layer "In9.Cu")
		(net "FM_CPU1_PKGID2")
	)
	(segment
		(start 372.537736 -80.83677)
		(end 371.75694 -81.617566)
		(width 0.089408)
		(layer "In9.Cu")
		(net "FM_CPU1_PKGID2")
	)
	(segment
		(start 372.537736 -68.808092)
		(end 372.537736 -80.83677)
		(width 0.089408)
		(layer "In9.Cu")
		(net "FM_CPU1_PKGID2")
	)
	(segment
		(start 372.252494 -67.933316)
		(end 372.252494 -68.52285)
		(width 0.089408)
		(layer "In9.Cu")
		(net "FM_CPU1_PKGID2")
	)
	(segment
		(start 372.876064 -66.874136)
		(end 372.131336 -66.874136)
		(width 0.089408)
		(layer "In9.Cu")
		(net "FM_CPU1_PKGID2")
	)
	(segment
		(start 373.521224 -66.228976)
		(end 372.876064 -66.874136)
		(width 0.089408)
		(layer "In9.Cu")
		(net "FM_CPU1_PKGID2")
	)
	(segment
		(start 372.131336 -66.874136)
		(end 371.87886 -67.126612)
		(width 0.089408)
		(layer "In9.Cu")
		(net "FM_CPU1_PKGID2")
	)
	(segment
		(start 373.521224 -65.2526)
		(end 373.521224 -66.228976)
		(width 0.089408)
		(layer "In9.Cu")
		(net "FM_CPU1_PKGID2")
	)
	(segment
		(start 371.87886 -67.559682)
		(end 372.252494 -67.933316)
		(width 0.089408)
		(layer "In9.Cu")
		(net "FM_CPU1_PKGID2")
	)
	(segment
		(start 372.252494 -68.52285)
		(end 372.537736 -68.808092)
		(width 0.089408)
		(layer "In9.Cu")
		(net "FM_CPU1_PKGID2")
	)
	(segment
		(start 340.8934 -53.950362)
		(end 340.8934 -53.095652)
		(width 0.089408)
		(layer "In11.Cu")
		(net "FM_CPU1_PKGID2")
	)
	(segment
		(start 29.843222 -113.9825)
		(end 29.843222 -129.998978)
		(width 0.089408)
		(layer "In11.Cu")
		(net "FM_CPU1_PKGID2")
	)
	(segment
		(start 70.622922 -83.72729)
		(end 70.590156 -83.72729)
		(width 0.0889)
		(layer "In11.Cu")
		(net "FM_CPU1_PKGID2")
	)
	(segment
		(start 50.262028 -94.116652)
		(end 44.800012 -99.578668)
		(width 0.089408)
		(layer "In11.Cu")
		(net "FM_CPU1_PKGID2")
	)
	(segment
		(start 373.521224 -65.278)
		(end 373.343424 -65.4558)
		(width 0.089408)
		(layer "In11.Cu")
		(net "FM_CPU1_PKGID2")
	)
	(segment
		(start 317.47841 -34.788602)
		(end 320.437002 -31.83001)
		(width 0.089408)
		(layer "In11.Cu")
		(net "FM_CPU1_PKGID2")
	)
	(segment
		(start 29.557472 -133.041136)
		(end 29.557472 -138.39444)
		(width 0.089408)
		(layer "In11.Cu")
		(net "FM_CPU1_PKGID2")
	)
	(segment
		(start 373.343424 -65.4558)
		(end 371.3988 -65.4558)
		(width 0.089408)
		(layer "In11.Cu")
		(net "FM_CPU1_PKGID2")
	)
	(segment
		(start 194.239896 0.291338)
		(end 194.944492 -0.413258)
		(width 0.089408)
		(layer "In11.Cu")
		(net "FM_CPU1_PKGID2")
	)
	(segment
		(start 68.905882 -84.71789)
		(end 68.873116 -84.71789)
		(width 0.0889)
		(layer "In11.Cu")
		(net "FM_CPU1_PKGID2")
	)
	(segment
		(start 29.557472 -152.914858)
		(end 29.557472 -155.267152)
		(width 0.089408)
		(layer "In11.Cu")
		(net "FM_CPU1_PKGID2")
	)
	(segment
		(start 77.991716 -84.612988)
		(end 78.000606 -84.597748)
		(width 0.0889)
		(layer "In11.Cu")
		(net "FM_CPU1_PKGID2")
	)
	(segment
		(start 184.484264 -30.62859)
		(end 161.080958 -54.031896)
		(width 0.089408)
		(layer "In11.Cu")
		(net "FM_CPU1_PKGID2")
	)
	(segment
		(start 44.800012 -99.578668)
		(end 41.090596 -99.578668)
		(width 0.089408)
		(layer "In11.Cu")
		(net "FM_CPU1_PKGID2")
	)
	(segment
		(start 326.31253 -52.159154)
		(end 320.705226 -46.55185)
		(width 0.089408)
		(layer "In11.Cu")
		(net "FM_CPU1_PKGID2")
	)
	(segment
		(start 181.990238 -127.428752)
		(end 182.480712 -127.919226)
		(width 0.089408)
		(layer "In11.Cu")
		(net "FM_CPU1_PKGID2")
	)
	(segment
		(start 179.4256 -129.4638)
		(end 178.7652 -128.8034)
		(width 0.089408)
		(layer "In11.Cu")
		(net "FM_CPU1_PKGID2")
	)
	(segment
		(start 370.935504 -64.536828)
		(end 369.632992 -63.234316)
		(width 0.089408)
		(layer "In11.Cu")
		(net "FM_CPU1_PKGID2")
	)
	(segment
		(start 66.952114 -84.935568)
		(end 61.760608 -84.935568)
		(width 0.089408)
		(layer "In11.Cu")
		(net "FM_CPU1_PKGID2")
	)
	(segment
		(start 67.760342 -85.212936)
		(end 67.456304 -84.908898)
		(width 0.0889)
		(layer "In11.Cu")
		(net "FM_CPU1_PKGID2")
	)
	(segment
		(start 156.940758 -155.859988)
		(end 156.940758 -155.134056)
		(width 0.089408)
		(layer "In11.Cu")
		(net "FM_CPU1_PKGID2")
	)
	(segment
		(start 373.521224 -65.2526)
		(end 373.521224 -65.278)
		(width 0.089408)
		(layer "In11.Cu")
		(net "FM_CPU1_PKGID2")
	)
	(segment
		(start 38.27272 -102.396544)
		(end 38.27272 -103.27894)
		(width 0.089408)
		(layer "In11.Cu")
		(net "FM_CPU1_PKGID2")
	)
	(segment
		(start 182.116222 -129.4638)
		(end 179.4256 -129.4638)
		(width 0.089408)
		(layer "In11.Cu")
		(net "FM_CPU1_PKGID2")
	)
	(segment
		(start 321.225672 -25.027128)
		(end 321.750182 -24.502618)
		(width 0.089408)
		(layer "In11.Cu")
		(net "FM_CPU1_PKGID2")
	)
	(segment
		(start 182.480712 -129.09931)
		(end 182.116222 -129.4638)
		(width 0.089408)
		(layer "In11.Cu")
		(net "FM_CPU1_PKGID2")
	)
	(segment
		(start 53.071776 -93.6244)
		(end 50.629566 -93.6244)
		(width 0.089408)
		(layer "In11.Cu")
		(net "FM_CPU1_PKGID2")
	)
	(segment
		(start 320.437002 -30.7213)
		(end 321.787012 -29.37129)
		(width 0.089408)
		(layer "In11.Cu")
		(net "FM_CPU1_PKGID2")
	)
	(segment
		(start 30.737302 -156.446982)
		(end 112.446816 -156.446982)
		(width 0.089408)
		(layer "In11.Cu")
		(net "FM_CPU1_PKGID2")
	)
	(segment
		(start 370.935504 -64.992504)
		(end 370.935504 -64.536828)
		(width 0.089408)
		(layer "In11.Cu")
		(net "FM_CPU1_PKGID2")
	)
	(segment
		(start 182.480712 -127.919226)
		(end 182.480712 -129.09931)
		(width 0.089408)
		(layer "In11.Cu")
		(net "FM_CPU1_PKGID2")
	)
	(segment
		(start 316.250066 -44.970192)
		(end 316.250066 -44.638468)
		(width 0.089408)
		(layer "In11.Cu")
		(net "FM_CPU1_PKGID2")
	)
	(segment
		(start 156.89707 -155.090368)
		(end 156.89707 -154.409902)
		(width 0.089408)
		(layer "In11.Cu")
		(net "FM_CPU1_PKGID2")
	)
	(segment
		(start 29.299154 -152.65654)
		(end 29.557472 -152.914858)
		(width 0.089408)
		(layer "In11.Cu")
		(net "FM_CPU1_PKGID2")
	)
	(segment
		(start 72.339962 -82.73669)
		(end 72.307196 -82.73669)
		(width 0.0889)
		(layer "In11.Cu")
		(net "FM_CPU1_PKGID2")
	)
	(segment
		(start 322.63842 -21.972016)
		(end 322.63842 -16.55318)
		(width 0.089408)
		(layer "In11.Cu")
		(net "FM_CPU1_PKGID2")
	)
	(segment
		(start 161.080958 -61.924438)
		(end 160.875472 -62.129924)
		(width 0.089408)
		(layer "In11.Cu")
		(net "FM_CPU1_PKGID2")
	)
	(segment
		(start 355.187758 -52.625752)
		(end 349.820992 -52.625752)
		(width 0.089408)
		(layer "In11.Cu")
		(net "FM_CPU1_PKGID2")
	)
	(segment
		(start 36.6903 -107.61726)
		(end 34.327592 -109.979968)
		(width 0.089408)
		(layer "In11.Cu")
		(net "FM_CPU1_PKGID2")
	)
	(segment
		(start 50.629566 -93.6244)
		(end 50.262028 -93.991938)
		(width 0.089408)
		(layer "In11.Cu")
		(net "FM_CPU1_PKGID2")
	)
	(segment
		(start 61.760608 -84.935568)
		(end 53.071776 -93.6244)
		(width 0.089408)
		(layer "In11.Cu")
		(net "FM_CPU1_PKGID2")
	)
	(segment
		(start 161.080958 -54.031896)
		(end 161.080958 -61.924438)
		(width 0.089408)
		(layer "In11.Cu")
		(net "FM_CPU1_PKGID2")
	)
	(segment
		(start 181.990238 -109.810042)
		(end 181.990238 -127.428752)
		(width 0.089408)
		(layer "In11.Cu")
		(net "FM_CPU1_PKGID2")
	)
	(segment
		(start 194.481704 -9.633204)
		(end 194.481704 -16.304006)
		(width 0.089408)
		(layer "In11.Cu")
		(net "FM_CPU1_PKGID2")
	)
	(segment
		(start 369.632992 -63.234316)
		(end 369.632992 -61.603382)
		(width 0.089408)
		(layer "In11.Cu")
		(net "FM_CPU1_PKGID2")
	)
	(segment
		(start 320.940176 -14.854936)
		(end 320.940176 -3.924554)
		(width 0.089408)
		(layer "In11.Cu")
		(net "FM_CPU1_PKGID2")
	)
	(segment
		(start 29.48559 -142.63751)
		(end 29.48559 -149.357842)
		(width 0.089408)
		(layer "In11.Cu")
		(net "FM_CPU1_PKGID2")
	)
	(segment
		(start 79.196692 -89.27084)
		(end 79.196692 -89.608914)
		(width 0.0889)
		(layer "In11.Cu")
		(net "FM_CPU1_PKGID2")
	)
	(segment
		(start 41.090596 -99.578668)
		(end 38.27272 -102.396544)
		(width 0.089408)
		(layer "In11.Cu")
		(net "FM_CPU1_PKGID2")
	)
	(segment
		(start 36.6903 -104.86136)
		(end 36.6903 -107.61726)
		(width 0.089408)
		(layer "In11.Cu")
		(net "FM_CPU1_PKGID2")
	)
	(segment
		(start 321.787012 -29.37129)
		(end 321.787012 -27.66568)
		(width 0.089408)
		(layer "In11.Cu")
		(net "FM_CPU1_PKGID2")
	)
	(segment
		(start 38.27272 -103.27894)
		(end 36.6903 -104.86136)
		(width 0.089408)
		(layer "In11.Cu")
		(net "FM_CPU1_PKGID2")
	)
	(segment
		(start 194.239896 0.623062)
		(end 194.239896 0.291338)
		(width 0.089408)
		(layer "In11.Cu")
		(net "FM_CPU1_PKGID2")
	)
	(segment
		(start 321.750182 -3.114548)
		(end 321.750182 2.680716)
		(width 0.089408)
		(layer "In11.Cu")
		(net "FM_CPU1_PKGID2")
	)
	(segment
		(start 316.85738 -44.404026)
		(end 317.115444 -44.145962)
		(width 0.089408)
		(layer "In11.Cu")
		(net "FM_CPU1_PKGID2")
	)
	(segment
		(start 321.225672 -27.10434)
		(end 321.225672 -25.027128)
		(width 0.089408)
		(layer "In11.Cu")
		(net "FM_CPU1_PKGID2")
	)
	(segment
		(start 320.940176 -3.924554)
		(end 321.750182 -3.114548)
		(width 0.089408)
		(layer "In11.Cu")
		(net "FM_CPU1_PKGID2")
	)
	(segment
		(start 33.845754 -109.979968)
		(end 29.843222 -113.9825)
		(width 0.089408)
		(layer "In11.Cu")
		(net "FM_CPU1_PKGID2")
	)
	(segment
		(start 321.787012 -27.66568)
		(end 321.225672 -27.10434)
		(width 0.089408)
		(layer "In11.Cu")
		(net "FM_CPU1_PKGID2")
	)
	(segment
		(start 29.108146 -132.59181)
		(end 29.557472 -133.041136)
		(width 0.089408)
		(layer "In11.Cu")
		(net "FM_CPU1_PKGID2")
	)
	(segment
		(start 158.279846 -66.617088)
		(end 158.279846 -83.499198)
		(width 0.089408)
		(layer "In11.Cu")
		(net "FM_CPU1_PKGID2")
	)
	(segment
		(start 321.750182 -22.860254)
		(end 322.63842 -21.972016)
		(width 0.089408)
		(layer "In11.Cu")
		(net "FM_CPU1_PKGID2")
	)
	(segment
		(start 163.630864 -151.666448)
		(end 164.27704 -151.020272)
		(width 0.089408)
		(layer "In11.Cu")
		(net "FM_CPU1_PKGID2")
	)
	(segment
		(start 76.639166 -83.231736)
		(end 76.603352 -83.231736)
		(width 0.0889)
		(layer "In11.Cu")
		(net "FM_CPU1_PKGID2")
	)
	(segment
		(start 77.995018 -88.981026)
		(end 77.991716 -88.975184)
		(width 0.0889)
		(layer "In11.Cu")
		(net "FM_CPU1_PKGID2")
	)
	(segment
		(start 159.640524 -151.666448)
		(end 163.630864 -151.666448)
		(width 0.089408)
		(layer "In11.Cu")
		(net "FM_CPU1_PKGID2")
	)
	(segment
		(start 340.8934 -53.095652)
		(end 339.956902 -52.159154)
		(width 0.089408)
		(layer "In11.Cu")
		(net "FM_CPU1_PKGID2")
	)
	(segment
		(start 164.27704 -151.020272)
		(end 164.27704 -150.619968)
		(width 0.089408)
		(layer "In11.Cu")
		(net "FM_CPU1_PKGID2")
	)
	(segment
		(start 321.750182 -24.502618)
		(end 321.750182 -22.860254)
		(width 0.089408)
		(layer "In11.Cu")
		(net "FM_CPU1_PKGID2")
	)
	(segment
		(start 77.991716 -87.584788)
		(end 78.000606 -87.569548)
		(width 0.0889)
		(layer "In11.Cu")
		(net "FM_CPU1_PKGID2")
	)
	(segment
		(start 359.944416 -53.448966)
		(end 356.010972 -53.448966)
		(width 0.089408)
		(layer "In11.Cu")
		(net "FM_CPU1_PKGID2")
	)
	(segment
		(start 175.174656 -99.236022)
		(end 175.343312 -99.404678)
		(width 0.089408)
		(layer "In11.Cu")
		(net "FM_CPU1_PKGID2")
	)
	(segment
		(start 178.3842 -106.204004)
		(end 181.990238 -109.810042)
		(width 0.089408)
		(layer "In11.Cu")
		(net "FM_CPU1_PKGID2")
	)
	(segment
		(start 172.68825 -89.912698)
		(end 175.304704 -92.529152)
		(width 0.089408)
		(layer "In11.Cu")
		(net "FM_CPU1_PKGID2")
	)
	(segment
		(start 29.557472 -138.39444)
		(end 29.033978 -138.917934)
		(width 0.089408)
		(layer "In11.Cu")
		(net "FM_CPU1_PKGID2")
	)
	(segment
		(start 175.343312 -101.50602)
		(end 178.3842 -104.546908)
		(width 0.089408)
		(layer "In11.Cu")
		(net "FM_CPU1_PKGID2")
	)
	(segment
		(start 349.820992 -52.625752)
		(end 348.141544 -54.3052)
		(width 0.089408)
		(layer "In11.Cu")
		(net "FM_CPU1_PKGID2")
	)
	(segment
		(start 321.033902 3.396996)
		(end 195.595494 3.396996)
		(width 0.089408)
		(layer "In11.Cu")
		(net "FM_CPU1_PKGID2")
	)
	(segment
		(start 348.141544 -54.3052)
		(end 341.248238 -54.3052)
		(width 0.089408)
		(layer "In11.Cu")
		(net "FM_CPU1_PKGID2")
	)
	(segment
		(start 194.944492 -8.102854)
		(end 194.138296 -8.90905)
		(width 0.089408)
		(layer "In11.Cu")
		(net "FM_CPU1_PKGID2")
	)
	(segment
		(start 317.831724 -46.55185)
		(end 316.250066 -44.970192)
		(width 0.089408)
		(layer "In11.Cu")
		(net "FM_CPU1_PKGID2")
	)
	(segment
		(start 29.843222 -129.998978)
		(end 29.108146 -130.734054)
		(width 0.089408)
		(layer "In11.Cu")
		(net "FM_CPU1_PKGID2")
	)
	(segment
		(start 50.262028 -93.991938)
		(end 50.262028 -94.116652)
		(width 0.089408)
		(layer "In11.Cu")
		(net "FM_CPU1_PKGID2")
	)
	(segment
		(start 77.991716 -88.575388)
		(end 78.000606 -88.560148)
		(width 0.0889)
		(layer "In11.Cu")
		(net "FM_CPU1_PKGID2")
	)
	(segment
		(start 184.484264 -21.780754)
		(end 184.484264 -30.62859)
		(width 0.089408)
		(layer "In11.Cu")
		(net "FM_CPU1_PKGID2")
	)
	(segment
		(start 365.325914 -57.296304)
		(end 363.791754 -57.296304)
		(width 0.089408)
		(layer "In11.Cu")
		(net "FM_CPU1_PKGID2")
	)
	(segment
		(start 69.768212 -84.222336)
		(end 69.735446 -84.222336)
		(width 0.0889)
		(layer "In11.Cu")
		(net "FM_CPU1_PKGID2")
	)
	(segment
		(start 316.250066 -44.638468)
		(end 316.484508 -44.404026)
		(width 0.089408)
		(layer "In11.Cu")
		(net "FM_CPU1_PKGID2")
	)
	(segment
		(start 317.036704 -34.788602)
		(end 317.47841 -34.788602)
		(width 0.089408)
		(layer "In11.Cu")
		(net "FM_CPU1_PKGID2")
	)
	(segment
		(start 194.138296 -9.289796)
		(end 194.481704 -9.633204)
		(width 0.089408)
		(layer "In11.Cu")
		(net "FM_CPU1_PKGID2")
	)
	(segment
		(start 67.007232 -84.918296)
		(end 66.952114 -84.935568)
		(width 0.089408)
		(layer "In11.Cu")
		(net "FM_CPU1_PKGID2")
	)
	(segment
		(start 321.750182 2.680716)
		(end 321.033902 3.396996)
		(width 0.089408)
		(layer "In11.Cu")
		(net "FM_CPU1_PKGID2")
	)
	(segment
		(start 34.327592 -109.979968)
		(end 33.845754 -109.979968)
		(width 0.089408)
		(layer "In11.Cu")
		(net "FM_CPU1_PKGID2")
	)
	(segment
		(start 322.63842 -16.55318)
		(end 320.940176 -14.854936)
		(width 0.089408)
		(layer "In11.Cu")
		(net "FM_CPU1_PKGID2")
	)
	(segment
		(start 356.010972 -53.448966)
		(end 355.187758 -52.625752)
		(width 0.089408)
		(layer "In11.Cu")
		(net "FM_CPU1_PKGID2")
	)
	(segment
		(start 194.481704 -16.304006)
		(end 190.504318 -20.281392)
		(width 0.089408)
		(layer "In11.Cu")
		(net "FM_CPU1_PKGID2")
	)
	(segment
		(start 175.304704 -93.681296)
		(end 175.174656 -93.811344)
		(width 0.089408)
		(layer "In11.Cu")
		(net "FM_CPU1_PKGID2")
	)
	(segment
		(start 178.3842 -104.546908)
		(end 178.3842 -106.204004)
		(width 0.089408)
		(layer "In11.Cu")
		(net "FM_CPU1_PKGID2")
	)
	(segment
		(start 194.944492 -0.413258)
		(end 194.944492 -8.102854)
		(width 0.089408)
		(layer "In11.Cu")
		(net "FM_CPU1_PKGID2")
	)
	(segment
		(start 317.115444 -43.814238)
		(end 316.424056 -43.12285)
		(width 0.089408)
		(layer "In11.Cu")
		(net "FM_CPU1_PKGID2")
	)
	(segment
		(start 68.051172 -85.212936)
		(end 67.760342 -85.212936)
		(width 0.0889)
		(layer "In11.Cu")
		(net "FM_CPU1_PKGID2")
	)
	(segment
		(start 316.424056 -43.12285)
		(end 316.424056 -35.40125)
		(width 0.089408)
		(layer "In11.Cu")
		(net "FM_CPU1_PKGID2")
	)
	(segment
		(start 164.693346 -89.912698)
		(end 172.68825 -89.912698)
		(width 0.089408)
		(layer "In11.Cu")
		(net "FM_CPU1_PKGID2")
	)
	(segment
		(start 29.033978 -138.917934)
		(end 29.033978 -142.185898)
		(width 0.089408)
		(layer "In11.Cu")
		(net "FM_CPU1_PKGID2")
	)
	(segment
		(start 185.983626 -20.281392)
		(end 184.484264 -21.780754)
		(width 0.089408)
		(layer "In11.Cu")
		(net "FM_CPU1_PKGID2")
	)
	(segment
		(start 71.4883 -83.231736)
		(end 71.452486 -83.231736)
		(width 0.0889)
		(layer "In11.Cu")
		(net "FM_CPU1_PKGID2")
	)
	(segment
		(start 159.670496 -65.226438)
		(end 158.279846 -66.617088)
		(width 0.089408)
		(layer "In11.Cu")
		(net "FM_CPU1_PKGID2")
	)
	(segment
		(start 156.57195 -156.228796)
		(end 156.940758 -155.859988)
		(width 0.089408)
		(layer "In11.Cu")
		(net "FM_CPU1_PKGID2")
	)
	(segment
		(start 316.484508 -44.404026)
		(end 316.85738 -44.404026)
		(width 0.089408)
		(layer "In11.Cu")
		(net "FM_CPU1_PKGID2")
	)
	(segment
		(start 112.446816 -156.446982)
		(end 112.665002 -156.228796)
		(width 0.089408)
		(layer "In11.Cu")
		(net "FM_CPU1_PKGID2")
	)
	(segment
		(start 159.670496 -62.750954)
		(end 159.670496 -65.226438)
		(width 0.089408)
		(layer "In11.Cu")
		(net "FM_CPU1_PKGID2")
	)
	(segment
		(start 160.291526 -62.129924)
		(end 159.670496 -62.750954)
		(width 0.089408)
		(layer "In11.Cu")
		(net "FM_CPU1_PKGID2")
	)
	(segment
		(start 112.665002 -156.228796)
		(end 156.57195 -156.228796)
		(width 0.089408)
		(layer "In11.Cu")
		(net "FM_CPU1_PKGID2")
	)
	(segment
		(start 194.944492 2.745994)
		(end 194.944492 1.327658)
		(width 0.089408)
		(layer "In11.Cu")
		(net "FM_CPU1_PKGID2")
	)
	(segment
		(start 67.068954 -84.908898)
		(end 67.007232 -84.918296)
		(width 0.0889)
		(layer "In11.Cu")
		(net "FM_CPU1_PKGID2")
	)
	(segment
		(start 317.115444 -44.145962)
		(end 317.115444 -43.814238)
		(width 0.089408)
		(layer "In11.Cu")
		(net "FM_CPU1_PKGID2")
	)
	(segment
		(start 190.504318 -20.281392)
		(end 185.983626 -20.281392)
		(width 0.089408)
		(layer "In11.Cu")
		(net "FM_CPU1_PKGID2")
	)
	(segment
		(start 156.940758 -155.134056)
		(end 156.89707 -155.090368)
		(width 0.089408)
		(layer "In11.Cu")
		(net "FM_CPU1_PKGID2")
	)
	(segment
		(start 67.456304 -84.908898)
		(end 67.068954 -84.908898)
		(width 0.0889)
		(layer "In11.Cu")
		(net "FM_CPU1_PKGID2")
	)
	(segment
		(start 175.174656 -93.811344)
		(end 175.174656 -99.236022)
		(width 0.089408)
		(layer "In11.Cu")
		(net "FM_CPU1_PKGID2")
	)
	(segment
		(start 320.437002 -31.83001)
		(end 320.437002 -30.7213)
		(width 0.089408)
		(layer "In11.Cu")
		(net "FM_CPU1_PKGID2")
	)
	(segment
		(start 29.033978 -142.185898)
		(end 29.48559 -142.63751)
		(width 0.089408)
		(layer "In11.Cu")
		(net "FM_CPU1_PKGID2")
	)
	(segment
		(start 156.89707 -154.409902)
		(end 159.640524 -151.666448)
		(width 0.089408)
		(layer "In11.Cu")
		(net "FM_CPU1_PKGID2")
	)
	(segment
		(start 339.956902 -52.159154)
		(end 326.31253 -52.159154)
		(width 0.089408)
		(layer "In11.Cu")
		(net "FM_CPU1_PKGID2")
	)
	(segment
		(start 371.3988 -65.4558)
		(end 370.935504 -64.992504)
		(width 0.089408)
		(layer "In11.Cu")
		(net "FM_CPU1_PKGID2")
	)
	(segment
		(start 75.784456 -82.73669)
		(end 75.75169 -82.73669)
		(width 0.0889)
		(layer "In11.Cu")
		(net "FM_CPU1_PKGID2")
	)
	(segment
		(start 158.279846 -83.499198)
		(end 164.693346 -89.912698)
		(width 0.089408)
		(layer "In11.Cu")
		(net "FM_CPU1_PKGID2")
	)
	(segment
		(start 194.944492 1.327658)
		(end 194.239896 0.623062)
		(width 0.089408)
		(layer "In11.Cu")
		(net "FM_CPU1_PKGID2")
	)
	(segment
		(start 29.108146 -130.734054)
		(end 29.108146 -132.59181)
		(width 0.089408)
		(layer "In11.Cu")
		(net "FM_CPU1_PKGID2")
	)
	(segment
		(start 320.705226 -46.55185)
		(end 317.831724 -46.55185)
		(width 0.089408)
		(layer "In11.Cu")
		(net "FM_CPU1_PKGID2")
	)
	(segment
		(start 73.202292 -82.241136)
		(end 73.174352 -82.241136)
		(width 0.0889)
		(layer "In11.Cu")
		(net "FM_CPU1_PKGID2")
	)
	(segment
		(start 78.355952 -89.175336)
		(end 78.338172 -89.175336)
		(width 0.0889)
		(layer "In11.Cu")
		(net "FM_CPU1_PKGID2")
	)
	(segment
		(start 77.991716 -86.594188)
		(end 78.000606 -86.578948)
		(width 0.0889)
		(layer "In11.Cu")
		(net "FM_CPU1_PKGID2")
	)
	(segment
		(start 175.343312 -99.404678)
		(end 175.343312 -101.50602)
		(width 0.089408)
		(layer "In11.Cu")
		(net "FM_CPU1_PKGID2")
	)
	(segment
		(start 175.304704 -92.529152)
		(end 175.304704 -93.681296)
		(width 0.089408)
		(layer "In11.Cu")
		(net "FM_CPU1_PKGID2")
	)
	(segment
		(start 29.48559 -149.357842)
		(end 29.299154 -149.544278)
		(width 0.089408)
		(layer "In11.Cu")
		(net "FM_CPU1_PKGID2")
	)
	(segment
		(start 29.299154 -149.544278)
		(end 29.299154 -152.65654)
		(width 0.089408)
		(layer "In11.Cu")
		(net "FM_CPU1_PKGID2")
	)
	(segment
		(start 74.9173 -82.241136)
		(end 74.88936 -82.241136)
		(width 0.0889)
		(layer "In11.Cu")
		(net "FM_CPU1_PKGID2")
	)
	(segment
		(start 316.424056 -35.40125)
		(end 317.036704 -34.788602)
		(width 0.089408)
		(layer "In11.Cu")
		(net "FM_CPU1_PKGID2")
	)
	(segment
		(start 195.595494 3.396996)
		(end 194.944492 2.745994)
		(width 0.089408)
		(layer "In11.Cu")
		(net "FM_CPU1_PKGID2")
	)
	(segment
		(start 29.557472 -155.267152)
		(end 30.737302 -156.446982)
		(width 0.089408)
		(layer "In11.Cu")
		(net "FM_CPU1_PKGID2")
	)
	(segment
		(start 363.791754 -57.296304)
		(end 359.944416 -53.448966)
		(width 0.089408)
		(layer "In11.Cu")
		(net "FM_CPU1_PKGID2")
	)
	(segment
		(start 74.067416 -81.74609)
		(end 74.024236 -81.74609)
		(width 0.0889)
		(layer "In11.Cu")
		(net "FM_CPU1_PKGID2")
	)
	(segment
		(start 77.504798 -83.72729)
		(end 77.46873 -83.72729)
		(width 0.0889)
		(layer "In11.Cu")
		(net "FM_CPU1_PKGID2")
	)
	(segment
		(start 160.875472 -62.129924)
		(end 160.291526 -62.129924)
		(width 0.089408)
		(layer "In11.Cu")
		(net "FM_CPU1_PKGID2")
	)
	(segment
		(start 79.196692 -89.608914)
		(end 79.13878 -89.666826)
		(width 0.0889)
		(layer "In11.Cu")
		(net "FM_CPU1_PKGID2")
	)
	(segment
		(start 369.632992 -61.603382)
		(end 365.325914 -57.296304)
		(width 0.089408)
		(layer "In11.Cu")
		(net "FM_CPU1_PKGID2")
	)
	(segment
		(start 341.248238 -54.3052)
		(end 340.8934 -53.950362)
		(width 0.089408)
		(layer "In11.Cu")
		(net "FM_CPU1_PKGID2")
	)
	(segment
		(start 194.138296 -8.90905)
		(end 194.138296 -9.289796)
		(width 0.089408)
		(layer "In11.Cu")
		(net "FM_CPU1_PKGID2")
	)
	(segment
		(start 77.991716 -85.603588)
		(end 78.000606 -85.588348)
		(width 0.0889)
		(layer "In11.Cu")
		(net "FM_CPU1_PKGID2")
	)
	(arc
		(start 71.452486 -83.231736)
		(mid 71.167062 -83.315203)
		(end 70.958456 -83.527138)
		(width 0.0889)
		(layer "In11.Cu")
		(net "FM_CPU1_PKGID2")
	)
	(arc
		(start 75.75169 -82.73669)
		(mid 75.55784 -82.68034)
		(end 75.416156 -82.536538)
		(width 0.0889)
		(layer "In11.Cu")
		(net "FM_CPU1_PKGID2")
	)
	(arc
		(start 78.000606 -87.569548)
		(mid 78.071003 -87.280597)
		(end 77.991716 -86.993984)
		(width 0.0889)
		(layer "In11.Cu")
		(net "FM_CPU1_PKGID2")
	)
	(arc
		(start 77.991716 -86.993984)
		(mid 77.938183 -86.794086)
		(end 77.991716 -86.594188)
		(width 0.0889)
		(layer "In11.Cu")
		(net "FM_CPU1_PKGID2")
	)
	(arc
		(start 74.557636 -82.041238)
		(mid 74.350632 -81.830374)
		(end 74.067416 -81.74609)
		(width 0.0889)
		(layer "In11.Cu")
		(net "FM_CPU1_PKGID2")
	)
	(arc
		(start 73.534016 -82.041238)
		(mid 73.393937 -82.183974)
		(end 73.202292 -82.241136)
		(width 0.0889)
		(layer "In11.Cu")
		(net "FM_CPU1_PKGID2")
	)
	(arc
		(start 70.958456 -83.527138)
		(mid 70.816773 -83.670942)
		(end 70.622922 -83.72729)
		(width 0.0889)
		(layer "In11.Cu")
		(net "FM_CPU1_PKGID2")
	)
	(arc
		(start 70.590156 -83.72729)
		(mid 70.306939 -83.811571)
		(end 70.099936 -84.022438)
		(width 0.0889)
		(layer "In11.Cu")
		(net "FM_CPU1_PKGID2")
	)
	(arc
		(start 75.416156 -82.536538)
		(mid 75.205443 -82.323459)
		(end 74.9173 -82.241136)
		(width 0.0889)
		(layer "In11.Cu")
		(net "FM_CPU1_PKGID2")
	)
	(arc
		(start 76.603352 -83.231736)
		(mid 76.413423 -83.173866)
		(end 76.274676 -83.031838)
		(width 0.0889)
		(layer "In11.Cu")
		(net "FM_CPU1_PKGID2")
	)
	(arc
		(start 77.133196 -83.527138)
		(mid 76.924588 -83.315206)
		(end 76.639166 -83.231736)
		(width 0.0889)
		(layer "In11.Cu")
		(net "FM_CPU1_PKGID2")
	)
	(arc
		(start 70.099936 -84.022438)
		(mid 69.959857 -84.165174)
		(end 69.768212 -84.222336)
		(width 0.0889)
		(layer "In11.Cu")
		(net "FM_CPU1_PKGID2")
	)
	(arc
		(start 74.024236 -81.74609)
		(mid 73.741019 -81.830371)
		(end 73.534016 -82.041238)
		(width 0.0889)
		(layer "In11.Cu")
		(net "FM_CPU1_PKGID2")
	)
	(arc
		(start 69.241416 -84.517738)
		(mid 69.099733 -84.661542)
		(end 68.905882 -84.71789)
		(width 0.0889)
		(layer "In11.Cu")
		(net "FM_CPU1_PKGID2")
	)
	(arc
		(start 68.382896 -85.013038)
		(mid 68.242817 -85.155774)
		(end 68.051172 -85.212936)
		(width 0.0889)
		(layer "In11.Cu")
		(net "FM_CPU1_PKGID2")
	)
	(arc
		(start 78.000606 -86.578948)
		(mid 78.071003 -86.289997)
		(end 77.991716 -86.003384)
		(width 0.0889)
		(layer "In11.Cu")
		(net "FM_CPU1_PKGID2")
	)
	(arc
		(start 72.675496 -82.536538)
		(mid 72.533813 -82.680342)
		(end 72.339962 -82.73669)
		(width 0.0889)
		(layer "In11.Cu")
		(net "FM_CPU1_PKGID2")
	)
	(arc
		(start 71.816976 -83.031838)
		(mid 71.678232 -83.173871)
		(end 71.4883 -83.231736)
		(width 0.0889)
		(layer "In11.Cu")
		(net "FM_CPU1_PKGID2")
	)
	(arc
		(start 68.873116 -84.71789)
		(mid 68.589899 -84.802171)
		(end 68.382896 -85.013038)
		(width 0.0889)
		(layer "In11.Cu")
		(net "FM_CPU1_PKGID2")
	)
	(arc
		(start 78.849982 -89.470738)
		(mid 78.641374 -89.258806)
		(end 78.355952 -89.175336)
		(width 0.0889)
		(layer "In11.Cu")
		(net "FM_CPU1_PKGID2")
	)
	(arc
		(start 76.274676 -83.031838)
		(mid 76.067672 -82.820974)
		(end 75.784456 -82.73669)
		(width 0.0889)
		(layer "In11.Cu")
		(net "FM_CPU1_PKGID2")
	)
	(arc
		(start 78.338172 -89.175336)
		(mid 78.141011 -89.123377)
		(end 77.995018 -88.981026)
		(width 0.0889)
		(layer "In11.Cu")
		(net "FM_CPU1_PKGID2")
	)
	(arc
		(start 78.000606 -84.597748)
		(mid 77.993601 -84.025275)
		(end 77.504798 -83.72729)
		(width 0.0889)
		(layer "In11.Cu")
		(net "FM_CPU1_PKGID2")
	)
	(arc
		(start 73.174352 -82.241136)
		(mid 72.886207 -82.323455)
		(end 72.675496 -82.536538)
		(width 0.0889)
		(layer "In11.Cu")
		(net "FM_CPU1_PKGID2")
	)
	(arc
		(start 77.991716 -87.984584)
		(mid 77.938183 -87.784686)
		(end 77.991716 -87.584788)
		(width 0.0889)
		(layer "In11.Cu")
		(net "FM_CPU1_PKGID2")
	)
	(arc
		(start 77.991716 -86.003384)
		(mid 77.938183 -85.803486)
		(end 77.991716 -85.603588)
		(width 0.0889)
		(layer "In11.Cu")
		(net "FM_CPU1_PKGID2")
	)
	(arc
		(start 72.307196 -82.73669)
		(mid 72.023979 -82.820971)
		(end 71.816976 -83.031838)
		(width 0.0889)
		(layer "In11.Cu")
		(net "FM_CPU1_PKGID2")
	)
	(arc
		(start 74.88936 -82.241136)
		(mid 74.697718 -82.18397)
		(end 74.557636 -82.041238)
		(width 0.0889)
		(layer "In11.Cu")
		(net "FM_CPU1_PKGID2")
	)
	(arc
		(start 78.000606 -85.588348)
		(mid 78.071003 -85.299397)
		(end 77.991716 -85.012784)
		(width 0.0889)
		(layer "In11.Cu")
		(net "FM_CPU1_PKGID2")
	)
	(arc
		(start 77.46873 -83.72729)
		(mid 77.27488 -83.67094)
		(end 77.133196 -83.527138)
		(width 0.0889)
		(layer "In11.Cu")
		(net "FM_CPU1_PKGID2")
	)
	(arc
		(start 77.991716 -88.975184)
		(mid 77.938183 -88.775286)
		(end 77.991716 -88.575388)
		(width 0.0889)
		(layer "In11.Cu")
		(net "FM_CPU1_PKGID2")
	)
	(arc
		(start 77.991716 -85.012784)
		(mid 77.938183 -84.812886)
		(end 77.991716 -84.612988)
		(width 0.0889)
		(layer "In11.Cu")
		(net "FM_CPU1_PKGID2")
	)
	(arc
		(start 69.735446 -84.222336)
		(mid 69.450022 -84.305803)
		(end 69.241416 -84.517738)
		(width 0.0889)
		(layer "In11.Cu")
		(net "FM_CPU1_PKGID2")
	)
	(arc
		(start 79.13878 -89.666826)
		(mid 78.971879 -89.601926)
		(end 78.849982 -89.470738)
		(width 0.0889)
		(layer "In11.Cu")
		(net "FM_CPU1_PKGID2")
	)
	(arc
		(start 78.000606 -88.560148)
		(mid 78.071003 -88.271197)
		(end 77.991716 -87.984584)
		(width 0.0889)
		(layer "In11.Cu")
		(net "FM_CPU1_PKGID2")
	)
	(segment
		(start 79.768192 -88.28024)
		(end 79.196692 -88.28024)
		(width 0.10795)
		(layer "F.Cu")
		(net "FM_CPU1_PKGID1")
	)
	(segment
		(start 369.545108 -79.094838)
		(end 369.944904 -78.695042)
		(width 0.1016)
		(layer "F.Cu")
		(net "FM_CPU1_PKGID1")
	)
	(via
		(at 369.545108 -79.094838)
		(size 0.4572)
		(drill 0.2032)
		(layers "F.Cu" "B.Cu")
		(net "FM_CPU1_PKGID1")
	)
	(via
		(at 65.1002 -88.8492)
		(size 0.6604)
		(drill 0.3302)
		(layers "F.Cu" "B.Cu")
		(net "FM_CPU1_PKGID1")
	)
	(via
		(at 180.503322 -128.395984)
		(size 0.508)
		(drill 0.254)
		(layers "F.Cu" "B.Cu")
		(net "FM_CPU1_PKGID1")
	)
	(via
		(at 167.3606 -129.3622)
		(size 0.508)
		(drill 0.254)
		(layers "F.Cu" "B.Cu")
		(net "FM_CPU1_PKGID1")
	)
	(via
		(at 79.196692 -88.28024)
		(size 0.508)
		(drill 0.254)
		(layers "F.Cu" "B.Cu")
		(net "FM_CPU1_PKGID1")
	)
	(via
		(at 164.63772 -150.038308)
		(size 0.508)
		(drill 0.254)
		(layers "F.Cu" "B.Cu")
		(net "FM_CPU1_PKGID1")
	)
	(via
		(at 372.126002 -64.400176)
		(size 0.508)
		(drill 0.254)
		(layers "F.Cu" "B.Cu")
		(net "FM_CPU1_PKGID1")
	)
	(segment
		(start 69.530976 -88.367108)
		(end 69.064886 -88.833198)
		(width 0.10795)
		(layer "B.Cu")
		(net "FM_CPU1_PKGID1")
	)
	(segment
		(start 77.113638 -88.688418)
		(end 76.792328 -88.367108)
		(width 0.10795)
		(layer "B.Cu")
		(net "FM_CPU1_PKGID1")
	)
	(segment
		(start 70.782688 -88.688418)
		(end 70.440804 -88.688418)
		(width 0.10795)
		(layer "B.Cu")
		(net "FM_CPU1_PKGID1")
	)
	(segment
		(start 74.312018 -88.5952)
		(end 74.216768 -88.688418)
		(width 0.10795)
		(layer "B.Cu")
		(net "FM_CPU1_PKGID1")
	)
	(segment
		(start 75.075288 -88.367108)
		(end 74.54011 -88.367108)
		(width 0.10795)
		(layer "B.Cu")
		(net "FM_CPU1_PKGID1")
	)
	(segment
		(start 167.8178 -128.905)
		(end 168.402 -128.905)
		(width 0.10795)
		(layer "B.Cu")
		(net "FM_CPU1_PKGID1")
	)
	(segment
		(start 77.650848 -88.688418)
		(end 77.113638 -88.688418)
		(width 0.10795)
		(layer "B.Cu")
		(net "FM_CPU1_PKGID1")
	)
	(segment
		(start 72.067674 -88.793574)
		(end 71.641208 -88.367108)
		(width 0.10795)
		(layer "B.Cu")
		(net "FM_CPU1_PKGID1")
	)
	(segment
		(start 76.792328 -88.367108)
		(end 76.450444 -88.367108)
		(width 0.10795)
		(layer "B.Cu")
		(net "FM_CPU1_PKGID1")
	)
	(segment
		(start 70.440804 -88.688418)
		(end 70.119494 -88.367108)
		(width 0.10795)
		(layer "B.Cu")
		(net "FM_CPU1_PKGID1")
	)
	(segment
		(start 75.522074 -88.813894)
		(end 75.075288 -88.367108)
		(width 0.10795)
		(layer "B.Cu")
		(net "FM_CPU1_PKGID1")
	)
	(segment
		(start 74.216768 -88.688418)
		(end 73.679558 -88.688418)
		(width 0.10795)
		(layer "B.Cu")
		(net "FM_CPU1_PKGID1")
	)
	(segment
		(start 73.016364 -88.367108)
		(end 72.589898 -88.793574)
		(width 0.10795)
		(layer "B.Cu")
		(net "FM_CPU1_PKGID1")
	)
	(segment
		(start 67.799966 -88.367108)
		(end 67.368928 -88.798146)
		(width 0.10795)
		(layer "B.Cu")
		(net "FM_CPU1_PKGID1")
	)
	(segment
		(start 65.1002 -88.8492)
		(end 64.1858 -88.8492)
		(width 0.10795)
		(layer "B.Cu")
		(net "FM_CPU1_PKGID1")
	)
	(segment
		(start 167.3606 -129.3622)
		(end 167.8178 -128.905)
		(width 0.10795)
		(layer "B.Cu")
		(net "FM_CPU1_PKGID1")
	)
	(segment
		(start 67.368928 -88.798146)
		(end 66.624454 -88.798146)
		(width 0.10795)
		(layer "B.Cu")
		(net "FM_CPU1_PKGID1")
	)
	(segment
		(start 73.358248 -88.367108)
		(end 73.016364 -88.367108)
		(width 0.10795)
		(layer "B.Cu")
		(net "FM_CPU1_PKGID1")
	)
	(segment
		(start 78.059026 -88.28024)
		(end 77.650848 -88.688418)
		(width 0.10795)
		(layer "B.Cu")
		(net "FM_CPU1_PKGID1")
	)
	(segment
		(start 70.119494 -88.367108)
		(end 69.530976 -88.367108)
		(width 0.10795)
		(layer "B.Cu")
		(net "FM_CPU1_PKGID1")
	)
	(segment
		(start 73.679558 -88.688418)
		(end 73.358248 -88.367108)
		(width 0.10795)
		(layer "B.Cu")
		(net "FM_CPU1_PKGID1")
	)
	(segment
		(start 66.624454 -88.798146)
		(end 66.5734 -88.8492)
		(width 0.10795)
		(layer "B.Cu")
		(net "FM_CPU1_PKGID1")
	)
	(segment
		(start 71.10603 -88.367108)
		(end 70.877938 -88.5952)
		(width 0.10795)
		(layer "B.Cu")
		(net "FM_CPU1_PKGID1")
	)
	(segment
		(start 79.196692 -88.28024)
		(end 78.059026 -88.28024)
		(width 0.10795)
		(layer "B.Cu")
		(net "FM_CPU1_PKGID1")
	)
	(segment
		(start 76.450444 -88.367108)
		(end 76.003658 -88.813894)
		(width 0.10795)
		(layer "B.Cu")
		(net "FM_CPU1_PKGID1")
	)
	(segment
		(start 74.54011 -88.367108)
		(end 74.312018 -88.5952)
		(width 0.10795)
		(layer "B.Cu")
		(net "FM_CPU1_PKGID1")
	)
	(segment
		(start 66.5734 -88.8492)
		(end 65.1002 -88.8492)
		(width 0.10795)
		(layer "B.Cu")
		(net "FM_CPU1_PKGID1")
	)
	(segment
		(start 68.249292 -88.367108)
		(end 67.799966 -88.367108)
		(width 0.10795)
		(layer "B.Cu")
		(net "FM_CPU1_PKGID1")
	)
	(segment
		(start 68.715382 -88.833198)
		(end 68.249292 -88.367108)
		(width 0.10795)
		(layer "B.Cu")
		(net "FM_CPU1_PKGID1")
	)
	(segment
		(start 71.641208 -88.367108)
		(end 71.10603 -88.367108)
		(width 0.10795)
		(layer "B.Cu")
		(net "FM_CPU1_PKGID1")
	)
	(segment
		(start 70.877938 -88.5952)
		(end 70.782688 -88.688418)
		(width 0.10795)
		(layer "B.Cu")
		(net "FM_CPU1_PKGID1")
	)
	(segment
		(start 76.003658 -88.813894)
		(end 75.522074 -88.813894)
		(width 0.10795)
		(layer "B.Cu")
		(net "FM_CPU1_PKGID1")
	)
	(segment
		(start 72.589898 -88.793574)
		(end 72.067674 -88.793574)
		(width 0.10795)
		(layer "B.Cu")
		(net "FM_CPU1_PKGID1")
	)
	(segment
		(start 69.064886 -88.833198)
		(end 68.715382 -88.833198)
		(width 0.10795)
		(layer "B.Cu")
		(net "FM_CPU1_PKGID1")
	)
	(segment
		(start 178.33086 -129.28346)
		(end 178.063398 -129.015998)
		(width 0.089408)
		(layer "In2.Cu")
		(net "FM_CPU1_PKGID1")
	)
	(segment
		(start 178.063398 -129.015998)
		(end 167.706802 -129.015998)
		(width 0.089408)
		(layer "In2.Cu")
		(net "FM_CPU1_PKGID1")
	)
	(segment
		(start 180.503322 -128.395984)
		(end 179.615846 -129.28346)
		(width 0.089408)
		(layer "In2.Cu")
		(net "FM_CPU1_PKGID1")
	)
	(segment
		(start 164.79266 -130.678174)
		(end 164.79266 -140.43406)
		(width 0.089408)
		(layer "In2.Cu")
		(net "FM_CPU1_PKGID1")
	)
	(segment
		(start 166.108634 -129.3622)
		(end 164.79266 -130.678174)
		(width 0.089408)
		(layer "In2.Cu")
		(net "FM_CPU1_PKGID1")
	)
	(segment
		(start 165.32098 -147.26158)
		(end 164.63772 -147.94484)
		(width 0.089408)
		(layer "In2.Cu")
		(net "FM_CPU1_PKGID1")
	)
	(segment
		(start 164.63772 -147.94484)
		(end 164.63772 -150.038308)
		(width 0.089408)
		(layer "In2.Cu")
		(net "FM_CPU1_PKGID1")
	)
	(segment
		(start 179.615846 -129.28346)
		(end 178.33086 -129.28346)
		(width 0.089408)
		(layer "In2.Cu")
		(net "FM_CPU1_PKGID1")
	)
	(segment
		(start 166.89832 -146.38528)
		(end 166.02202 -147.26158)
		(width 0.089408)
		(layer "In2.Cu")
		(net "FM_CPU1_PKGID1")
	)
	(segment
		(start 167.3606 -129.3622)
		(end 166.108634 -129.3622)
		(width 0.089408)
		(layer "In2.Cu")
		(net "FM_CPU1_PKGID1")
	)
	(segment
		(start 166.02202 -147.26158)
		(end 165.32098 -147.26158)
		(width 0.089408)
		(layer "In2.Cu")
		(net "FM_CPU1_PKGID1")
	)
	(segment
		(start 167.706802 -129.015998)
		(end 167.3606 -129.3622)
		(width 0.089408)
		(layer "In2.Cu")
		(net "FM_CPU1_PKGID1")
	)
	(segment
		(start 166.89832 -142.53972)
		(end 166.89832 -146.38528)
		(width 0.089408)
		(layer "In2.Cu")
		(net "FM_CPU1_PKGID1")
	)
	(segment
		(start 164.79266 -140.43406)
		(end 166.89832 -142.53972)
		(width 0.089408)
		(layer "In2.Cu")
		(net "FM_CPU1_PKGID1")
	)
	(segment
		(start 370.256816 -69.055488)
		(end 370.512594 -69.055488)
		(width 0.089408)
		(layer "In9.Cu")
		(net "FM_CPU1_PKGID1")
	)
	(segment
		(start 370.192046 -67.91833)
		(end 370.192046 -66.700146)
		(width 0.089408)
		(layer "In9.Cu")
		(net "FM_CPU1_PKGID1")
	)
	(segment
		(start 370.512594 -69.055488)
		(end 370.731288 -68.836794)
		(width 0.089408)
		(layer "In9.Cu")
		(net "FM_CPU1_PKGID1")
	)
	(segment
		(start 369.545108 -79.094838)
		(end 369.918488 -78.721458)
		(width 0.089408)
		(layer "In9.Cu")
		(net "FM_CPU1_PKGID1")
	)
	(segment
		(start 370.731288 -68.457572)
		(end 370.192046 -67.91833)
		(width 0.089408)
		(layer "In9.Cu")
		(net "FM_CPU1_PKGID1")
	)
	(segment
		(start 371.265704 -64.235076)
		(end 371.960902 -64.235076)
		(width 0.089408)
		(layer "In9.Cu")
		(net "FM_CPU1_PKGID1")
	)
	(segment
		(start 371.960902 -64.235076)
		(end 372.126002 -64.400176)
		(width 0.089408)
		(layer "In9.Cu")
		(net "FM_CPU1_PKGID1")
	)
	(segment
		(start 370.731288 -68.836794)
		(end 370.731288 -68.457572)
		(width 0.089408)
		(layer "In9.Cu")
		(net "FM_CPU1_PKGID1")
	)
	(segment
		(start 371.126512 -65.76568)
		(end 371.126512 -64.374268)
		(width 0.089408)
		(layer "In9.Cu")
		(net "FM_CPU1_PKGID1")
	)
	(segment
		(start 371.126512 -64.374268)
		(end 371.265704 -64.235076)
		(width 0.089408)
		(layer "In9.Cu")
		(net "FM_CPU1_PKGID1")
	)
	(segment
		(start 369.918488 -69.393816)
		(end 370.256816 -69.055488)
		(width 0.089408)
		(layer "In9.Cu")
		(net "FM_CPU1_PKGID1")
	)
	(segment
		(start 369.918488 -78.721458)
		(end 369.918488 -69.393816)
		(width 0.089408)
		(layer "In9.Cu")
		(net "FM_CPU1_PKGID1")
	)
	(segment
		(start 370.192046 -66.700146)
		(end 371.126512 -65.76568)
		(width 0.089408)
		(layer "In9.Cu")
		(net "FM_CPU1_PKGID1")
	)
	(segment
		(start 70.60057 -82.92719)
		(end 70.633336 -82.92719)
		(width 0.0889)
		(layer "In11.Cu")
		(net "FM_CPU1_PKGID1")
	)
	(segment
		(start 159.98317 -54.49443)
		(end 184.102248 -30.375352)
		(width 0.089408)
		(layer "In11.Cu")
		(net "FM_CPU1_PKGID1")
	)
	(segment
		(start 164.677344 -150.077932)
		(end 164.677344 -150.890224)
		(width 0.089408)
		(layer "In11.Cu")
		(net "FM_CPU1_PKGID1")
	)
	(segment
		(start 74.03084 -80.94599)
		(end 74.060812 -80.94599)
		(width 0.0889)
		(layer "In11.Cu")
		(net "FM_CPU1_PKGID1")
	)
	(segment
		(start 193.281808 -8.255)
		(end 194.4878 -7.049008)
		(width 0.089408)
		(layer "In11.Cu")
		(net "FM_CPU1_PKGID1")
	)
	(segment
		(start 159.719772 -151.857456)
		(end 157.088078 -154.48915)
		(width 0.089408)
		(layer "In11.Cu")
		(net "FM_CPU1_PKGID1")
	)
	(segment
		(start 61.70803 -84.71789)
		(end 67.039744 -84.71789)
		(width 0.089408)
		(layer "In11.Cu")
		(net "FM_CPU1_PKGID1")
	)
	(segment
		(start 174.28083 -93.69171)
		(end 174.28083 -92.04579)
		(width 0.089408)
		(layer "In11.Cu")
		(net "FM_CPU1_PKGID1")
	)
	(segment
		(start 370.772944 -63.047118)
		(end 372.126002 -64.400176)
		(width 0.089408)
		(layer "In11.Cu")
		(net "FM_CPU1_PKGID1")
	)
	(segment
		(start 365.44123 -56.72328)
		(end 366.008666 -56.72328)
		(width 0.089408)
		(layer "In11.Cu")
		(net "FM_CPU1_PKGID1")
	)
	(segment
		(start 174.28083 -92.04579)
		(end 172.592746 -90.357706)
		(width 0.089408)
		(layer "In11.Cu")
		(net "FM_CPU1_PKGID1")
	)
	(segment
		(start 78.678532 -84.60232)
		(end 78.74 -84.708746)
		(width 0.0889)
		(layer "In11.Cu")
		(net "FM_CPU1_PKGID1")
	)
	(segment
		(start 365.124238 -56.722772)
		(end 365.440722 -56.722772)
		(width 0.089408)
		(layer "In11.Cu")
		(net "FM_CPU1_PKGID1")
	)
	(segment
		(start 185.681366 -19.899376)
		(end 190.345822 -19.899376)
		(width 0.089408)
		(layer "In11.Cu")
		(net "FM_CPU1_PKGID1")
	)
	(segment
		(start 364.127542 -56.72328)
		(end 364.965742 -56.72328)
		(width 0.089408)
		(layer "In11.Cu")
		(net "FM_CPU1_PKGID1")
	)
	(segment
		(start 316.997334 -35.63874)
		(end 316.997334 -42.88536)
		(width 0.089408)
		(layer "In11.Cu")
		(net "FM_CPU1_PKGID1")
	)
	(segment
		(start 317.619888 -44.452286)
		(end 317.619888 -44.94911)
		(width 0.089408)
		(layer "In11.Cu")
		(net "FM_CPU1_PKGID1")
	)
	(segment
		(start 370.833904 -61.546994)
		(end 370.833904 -61.847222)
		(width 0.089408)
		(layer "In11.Cu")
		(net "FM_CPU1_PKGID1")
	)
	(segment
		(start 320.78422 -45.978572)
		(end 320.784474 -45.978318)
		(width 0.089408)
		(layer "In11.Cu")
		(net "FM_CPU1_PKGID1")
	)
	(segment
		(start 365.123984 -56.723026)
		(end 365.124238 -56.722772)
		(width 0.089408)
		(layer "In11.Cu")
		(net "FM_CPU1_PKGID1")
	)
	(segment
		(start 317.274194 -35.36188)
		(end 316.997334 -35.63874)
		(width 0.089408)
		(layer "In11.Cu")
		(net "FM_CPU1_PKGID1")
	)
	(segment
		(start 194.687444 3.779012)
		(end 321.606418 3.779012)
		(width 0.089408)
		(layer "In11.Cu")
		(net "FM_CPU1_PKGID1")
	)
	(segment
		(start 79.196692 -86.207092)
		(end 79.196692 -88.28024)
		(width 0.089408)
		(layer "In11.Cu")
		(net "FM_CPU1_PKGID1")
	)
	(segment
		(start 157.131766 -155.939236)
		(end 156.650944 -156.420058)
		(width 0.089408)
		(layer "In11.Cu")
		(net "FM_CPU1_PKGID1")
	)
	(segment
		(start 337.774788 -51.293268)
		(end 340.511384 -51.293268)
		(width 0.089408)
		(layer "In11.Cu")
		(net "FM_CPU1_PKGID1")
	)
	(segment
		(start 321.010026 -30.99562)
		(end 321.010026 -32.151574)
		(width 0.089408)
		(layer "In11.Cu")
		(net "FM_CPU1_PKGID1")
	)
	(segment
		(start 67.039744 -84.71789)
		(end 67.474084 -84.71789)
		(width 0.0889)
		(layer "In11.Cu")
		(net "FM_CPU1_PKGID1")
	)
	(segment
		(start 364.965742 -56.72328)
		(end 364.965996 -56.723026)
		(width 0.089408)
		(layer "In11.Cu")
		(net "FM_CPU1_PKGID1")
	)
	(segment
		(start 28.591764 -130.98018)
		(end 29.631894 -129.94005)
		(width 0.089408)
		(layer "In11.Cu")
		(net "FM_CPU1_PKGID1")
	)
	(segment
		(start 181.2417 -127.5715)
		(end 181.2417 -109.602016)
		(width 0.089408)
		(layer "In11.Cu")
		(net "FM_CPU1_PKGID1")
	)
	(segment
		(start 159.179514 -62.70117)
		(end 159.98317 -61.897514)
		(width 0.089408)
		(layer "In11.Cu")
		(net "FM_CPU1_PKGID1")
	)
	(segment
		(start 73.17613 -81.441036)
		(end 73.208896 -81.441036)
		(width 0.0889)
		(layer "In11.Cu")
		(net "FM_CPU1_PKGID1")
	)
	(segment
		(start 77.458316 -82.92719)
		(end 77.479906 -82.92719)
		(width 0.0889)
		(layer "In11.Cu")
		(net "FM_CPU1_PKGID1")
	)
	(segment
		(start 347.119194 -53.732176)
		(end 347.9038 -53.732176)
		(width 0.089408)
		(layer "In11.Cu")
		(net "FM_CPU1_PKGID1")
	)
	(segment
		(start 184.102248 -21.478494)
		(end 185.681366 -19.899376)
		(width 0.089408)
		(layer "In11.Cu")
		(net "FM_CPU1_PKGID1")
	)
	(segment
		(start 74.882756 -81.441036)
		(end 74.915522 -81.441036)
		(width 0.0889)
		(layer "In11.Cu")
		(net "FM_CPU1_PKGID1")
	)
	(segment
		(start 322.285868 -30.523942)
		(end 321.481704 -30.523942)
		(width 0.089408)
		(layer "In11.Cu")
		(net "FM_CPU1_PKGID1")
	)
	(segment
		(start 36.499038 -107.538266)
		(end 36.499038 -104.782366)
		(width 0.089408)
		(layer "In11.Cu")
		(net "FM_CPU1_PKGID1")
	)
	(segment
		(start 178.002184 -106.3625)
		(end 178.002184 -104.850692)
		(width 0.089408)
		(layer "In11.Cu")
		(net "FM_CPU1_PKGID1")
	)
	(segment
		(start 52.992528 -93.433392)
		(end 61.70803 -84.71789)
		(width 0.089408)
		(layer "In11.Cu")
		(net "FM_CPU1_PKGID1")
	)
	(segment
		(start 112.743996 -156.420058)
		(end 112.526064 -156.63799)
		(width 0.089408)
		(layer "In11.Cu")
		(net "FM_CPU1_PKGID1")
	)
	(segment
		(start 44.720764 -99.38766)
		(end 50.07102 -94.037404)
		(width 0.089408)
		(layer "In11.Cu")
		(net "FM_CPU1_PKGID1")
	)
	(segment
		(start 337.774534 -51.293522)
		(end 337.774788 -51.293268)
		(width 0.089408)
		(layer "In11.Cu")
		(net "FM_CPU1_PKGID1")
	)
	(segment
		(start 193.281808 0.367792)
		(end 193.281808 2.373376)
		(width 0.089408)
		(layer "In11.Cu")
		(net "FM_CPU1_PKGID1")
	)
	(segment
		(start 317.619888 -44.94911)
		(end 318.64935 -45.978572)
		(width 0.089408)
		(layer "In11.Cu")
		(net "FM_CPU1_PKGID1")
	)
	(segment
		(start 174.961296 -101.809804)
		(end 174.961296 -99.563174)
		(width 0.089408)
		(layer "In11.Cu")
		(net "FM_CPU1_PKGID1")
	)
	(segment
		(start 341.736172 -52.518056)
		(end 345.905074 -52.518056)
		(width 0.089408)
		(layer "In11.Cu")
		(net "FM_CPU1_PKGID1")
	)
	(segment
		(start 323.226176 -45.978318)
		(end 328.54138 -51.293522)
		(width 0.089408)
		(layer "In11.Cu")
		(net "FM_CPU1_PKGID1")
	)
	(segment
		(start 172.592746 -90.357706)
		(end 164.597842 -90.357706)
		(width 0.089408)
		(layer "In11.Cu")
		(net "FM_CPU1_PKGID1")
	)
	(segment
		(start 159.179514 -65.176654)
		(end 159.179514 -62.70117)
		(width 0.089408)
		(layer "In11.Cu")
		(net "FM_CPU1_PKGID1")
	)
	(segment
		(start 50.07102 -93.91269)
		(end 50.550318 -93.433392)
		(width 0.089408)
		(layer "In11.Cu")
		(net "FM_CPU1_PKGID1")
	)
	(segment
		(start 164.63772 -150.038308)
		(end 164.677344 -150.077932)
		(width 0.089408)
		(layer "In11.Cu")
		(net "FM_CPU1_PKGID1")
	)
	(segment
		(start 174.961296 -99.563174)
		(end 174.015146 -98.617024)
		(width 0.089408)
		(layer "In11.Cu")
		(net "FM_CPU1_PKGID1")
	)
	(segment
		(start 28.477464 -132.837936)
		(end 28.591764 -132.723636)
		(width 0.089408)
		(layer "In11.Cu")
		(net "FM_CPU1_PKGID1")
	)
	(segment
		(start 50.07102 -94.037404)
		(end 50.07102 -93.91269)
		(width 0.089408)
		(layer "In11.Cu")
		(net "FM_CPU1_PKGID1")
	)
	(segment
		(start 174.015146 -98.617024)
		(end 174.015146 -93.957394)
		(width 0.089408)
		(layer "In11.Cu")
		(net "FM_CPU1_PKGID1")
	)
	(segment
		(start 29.631894 -129.94005)
		(end 29.631894 -113.923572)
		(width 0.089408)
		(layer "In11.Cu")
		(net "FM_CPU1_PKGID1")
	)
	(segment
		(start 350.685354 -50.950622)
		(end 356.352094 -50.950622)
		(width 0.089408)
		(layer "In11.Cu")
		(net "FM_CPU1_PKGID1")
	)
	(segment
		(start 157.088078 -155.01112)
		(end 157.131766 -155.054808)
		(width 0.089408)
		(layer "In11.Cu")
		(net "FM_CPU1_PKGID1")
	)
	(segment
		(start 356.352094 -50.950622)
		(end 357.294434 -51.892962)
		(width 0.089408)
		(layer "In11.Cu")
		(net "FM_CPU1_PKGID1")
	)
	(segment
		(start 76.608432 -82.43189)
		(end 76.632562 -82.43189)
		(width 0.0889)
		(layer "In11.Cu")
		(net "FM_CPU1_PKGID1")
	)
	(segment
		(start 347.9038 -53.732176)
		(end 350.685354 -50.950622)
		(width 0.089408)
		(layer "In11.Cu")
		(net "FM_CPU1_PKGID1")
	)
	(segment
		(start 184.102248 -30.375352)
		(end 184.102248 -21.478494)
		(width 0.089408)
		(layer "In11.Cu")
		(net "FM_CPU1_PKGID1")
	)
	(segment
		(start 38.0746 -102.324408)
		(end 41.011348 -99.38766)
		(width 0.089408)
		(layer "In11.Cu")
		(net "FM_CPU1_PKGID1")
	)
	(segment
		(start 340.511384 -51.293268)
		(end 341.736172 -52.518056)
		(width 0.089408)
		(layer "In11.Cu")
		(net "FM_CPU1_PKGID1")
	)
	(segment
		(start 370.833904 -61.847222)
		(end 370.772944 -61.908182)
		(width 0.089408)
		(layer "In11.Cu")
		(net "FM_CPU1_PKGID1")
	)
	(segment
		(start 316.997334 -42.88536)
		(end 317.688468 -43.576494)
		(width 0.089408)
		(layer "In11.Cu")
		(net "FM_CPU1_PKGID1")
	)
	(segment
		(start 157.586934 -83.346798)
		(end 157.586934 -66.769234)
		(width 0.089408)
		(layer "In11.Cu")
		(net "FM_CPU1_PKGID1")
	)
	(segment
		(start 322.74637 -28.084526)
		(end 322.74637 -30.06344)
		(width 0.089408)
		(layer "In11.Cu")
		(net "FM_CPU1_PKGID1")
	)
	(segment
		(start 28.477464 -154.4574)
		(end 28.477464 -132.837936)
		(width 0.089408)
		(layer "In11.Cu")
		(net "FM_CPU1_PKGID1")
	)
	(segment
		(start 357.294434 -52.558442)
		(end 357.528876 -52.792884)
		(width 0.089408)
		(layer "In11.Cu")
		(net "FM_CPU1_PKGID1")
	)
	(segment
		(start 323.120512 2.264918)
		(end 323.120512 -23.6728)
		(width 0.089408)
		(layer "In11.Cu")
		(net "FM_CPU1_PKGID1")
	)
	(segment
		(start 34.248344 -109.78896)
		(end 36.499038 -107.538266)
		(width 0.089408)
		(layer "In11.Cu")
		(net "FM_CPU1_PKGID1")
	)
	(segment
		(start 321.607688 -26.945844)
		(end 322.74637 -28.084526)
		(width 0.089408)
		(layer "In11.Cu")
		(net "FM_CPU1_PKGID1")
	)
	(segment
		(start 164.597842 -90.357706)
		(end 157.586934 -83.346798)
		(width 0.089408)
		(layer "In11.Cu")
		(net "FM_CPU1_PKGID1")
	)
	(segment
		(start 29.631894 -113.923572)
		(end 33.766506 -109.78896)
		(width 0.089408)
		(layer "In11.Cu")
		(net "FM_CPU1_PKGID1")
	)
	(segment
		(start 50.550318 -93.433392)
		(end 52.992528 -93.433392)
		(width 0.089408)
		(layer "In11.Cu")
		(net "FM_CPU1_PKGID1")
	)
	(segment
		(start 323.120512 -23.6728)
		(end 321.607688 -25.185624)
		(width 0.089408)
		(layer "In11.Cu")
		(net "FM_CPU1_PKGID1")
	)
	(segment
		(start 30.658054 -156.63799)
		(end 28.477464 -154.4574)
		(width 0.089408)
		(layer "In11.Cu")
		(net "FM_CPU1_PKGID1")
	)
	(segment
		(start 364.965996 -56.723026)
		(end 365.123984 -56.723026)
		(width 0.089408)
		(layer "In11.Cu")
		(net "FM_CPU1_PKGID1")
	)
	(segment
		(start 174.015146 -93.957394)
		(end 174.28083 -93.69171)
		(width 0.089408)
		(layer "In11.Cu")
		(net "FM_CPU1_PKGID1")
	)
	(segment
		(start 317.688468 -44.383706)
		(end 317.619888 -44.452286)
		(width 0.089408)
		(layer "In11.Cu")
		(net "FM_CPU1_PKGID1")
	)
	(segment
		(start 317.79972 -35.36188)
		(end 317.274194 -35.36188)
		(width 0.089408)
		(layer "In11.Cu")
		(net "FM_CPU1_PKGID1")
	)
	(segment
		(start 159.98317 -61.897514)
		(end 159.98317 -54.49443)
		(width 0.089408)
		(layer "In11.Cu")
		(net "FM_CPU1_PKGID1")
	)
	(segment
		(start 190.345822 -19.899376)
		(end 193.281808 -16.96339)
		(width 0.089408)
		(layer "In11.Cu")
		(net "FM_CPU1_PKGID1")
	)
	(segment
		(start 321.606418 3.779012)
		(end 323.120512 2.264918)
		(width 0.089408)
		(layer "In11.Cu")
		(net "FM_CPU1_PKGID1")
	)
	(segment
		(start 357.528876 -52.792884)
		(end 360.197146 -52.792884)
		(width 0.089408)
		(layer "In11.Cu")
		(net "FM_CPU1_PKGID1")
	)
	(segment
		(start 321.010026 -32.151574)
		(end 317.79972 -35.36188)
		(width 0.089408)
		(layer "In11.Cu")
		(net "FM_CPU1_PKGID1")
	)
	(segment
		(start 366.008666 -56.72328)
		(end 370.833904 -61.546994)
		(width 0.089408)
		(layer "In11.Cu")
		(net "FM_CPU1_PKGID1")
	)
	(segment
		(start 318.64935 -45.978572)
		(end 320.78422 -45.978572)
		(width 0.089408)
		(layer "In11.Cu")
		(net "FM_CPU1_PKGID1")
	)
	(segment
		(start 67.869816 -84.412836)
		(end 68.057776 -84.412836)
		(width 0.0889)
		(layer "In11.Cu")
		(net "FM_CPU1_PKGID1")
	)
	(segment
		(start 365.440722 -56.722772)
		(end 365.44123 -56.72328)
		(width 0.089408)
		(layer "In11.Cu")
		(net "FM_CPU1_PKGID1")
	)
	(segment
		(start 78.74 -85.7504)
		(end 79.196692 -86.207092)
		(width 0.089408)
		(layer "In11.Cu")
		(net "FM_CPU1_PKGID1")
	)
	(segment
		(start 78.74 -84.708746)
		(end 78.74 -85.7504)
		(width 0.0889)
		(layer "In11.Cu")
		(net "FM_CPU1_PKGID1")
	)
	(segment
		(start 41.011348 -99.38766)
		(end 44.720764 -99.38766)
		(width 0.089408)
		(layer "In11.Cu")
		(net "FM_CPU1_PKGID1")
	)
	(segment
		(start 320.784474 -45.978318)
		(end 323.226176 -45.978318)
		(width 0.089408)
		(layer "In11.Cu")
		(net "FM_CPU1_PKGID1")
	)
	(segment
		(start 317.688468 -43.576494)
		(end 317.688468 -44.383706)
		(width 0.089408)
		(layer "In11.Cu")
		(net "FM_CPU1_PKGID1")
	)
	(segment
		(start 156.650944 -156.420058)
		(end 112.743996 -156.420058)
		(width 0.089408)
		(layer "In11.Cu")
		(net "FM_CPU1_PKGID1")
	)
	(segment
		(start 194.4878 -0.8382)
		(end 193.281808 0.367792)
		(width 0.089408)
		(layer "In11.Cu")
		(net "FM_CPU1_PKGID1")
	)
	(segment
		(start 33.766506 -109.78896)
		(end 34.248344 -109.78896)
		(width 0.089408)
		(layer "In11.Cu")
		(net "FM_CPU1_PKGID1")
	)
	(segment
		(start 360.197146 -52.792884)
		(end 364.127542 -56.72328)
		(width 0.089408)
		(layer "In11.Cu")
		(net "FM_CPU1_PKGID1")
	)
	(segment
		(start 181.2417 -109.602016)
		(end 178.002184 -106.3625)
		(width 0.089408)
		(layer "In11.Cu")
		(net "FM_CPU1_PKGID1")
	)
	(segment
		(start 77.82306 -83.1215)
		(end 77.826362 -83.127342)
		(width 0.0889)
		(layer "In11.Cu")
		(net "FM_CPU1_PKGID1")
	)
	(segment
		(start 36.499038 -104.782366)
		(end 38.0746 -103.206804)
		(width 0.089408)
		(layer "In11.Cu")
		(net "FM_CPU1_PKGID1")
	)
	(segment
		(start 75.745086 -81.93659)
		(end 75.777852 -81.93659)
		(width 0.0889)
		(layer "In11.Cu")
		(net "FM_CPU1_PKGID1")
	)
	(segment
		(start 78.316582 -83.42249)
		(end 78.356206 -83.42249)
		(width 0.0889)
		(layer "In11.Cu")
		(net "FM_CPU1_PKGID1")
	)
	(segment
		(start 69.735192 -83.42249)
		(end 69.774816 -83.42249)
		(width 0.0889)
		(layer "In11.Cu")
		(net "FM_CPU1_PKGID1")
	)
	(segment
		(start 357.294434 -51.892962)
		(end 357.294434 -52.558442)
		(width 0.089408)
		(layer "In11.Cu")
		(net "FM_CPU1_PKGID1")
	)
	(segment
		(start 193.281808 2.373376)
		(end 194.687444 3.779012)
		(width 0.089408)
		(layer "In11.Cu")
		(net "FM_CPU1_PKGID1")
	)
	(segment
		(start 328.54138 -51.293522)
		(end 337.774534 -51.293522)
		(width 0.089408)
		(layer "In11.Cu")
		(net "FM_CPU1_PKGID1")
	)
	(segment
		(start 180.503322 -128.309878)
		(end 181.2417 -127.5715)
		(width 0.089408)
		(layer "In11.Cu")
		(net "FM_CPU1_PKGID1")
	)
	(segment
		(start 68.87972 -83.91779)
		(end 68.912486 -83.91779)
		(width 0.0889)
		(layer "In11.Cu")
		(net "FM_CPU1_PKGID1")
	)
	(segment
		(start 193.281808 -16.96339)
		(end 193.281808 -8.255)
		(width 0.089408)
		(layer "In11.Cu")
		(net "FM_CPU1_PKGID1")
	)
	(segment
		(start 163.710112 -151.857456)
		(end 159.719772 -151.857456)
		(width 0.089408)
		(layer "In11.Cu")
		(net "FM_CPU1_PKGID1")
	)
	(segment
		(start 72.3138 -81.93659)
		(end 72.346566 -81.93659)
		(width 0.0889)
		(layer "In11.Cu")
		(net "FM_CPU1_PKGID1")
	)
	(segment
		(start 157.586934 -66.769234)
		(end 159.179514 -65.176654)
		(width 0.089408)
		(layer "In11.Cu")
		(net "FM_CPU1_PKGID1")
	)
	(segment
		(start 180.503322 -128.395984)
		(end 180.503322 -128.309878)
		(width 0.089408)
		(layer "In11.Cu")
		(net "FM_CPU1_PKGID1")
	)
	(segment
		(start 322.74637 -30.06344)
		(end 322.285868 -30.523942)
		(width 0.089408)
		(layer "In11.Cu")
		(net "FM_CPU1_PKGID1")
	)
	(segment
		(start 38.0746 -103.206804)
		(end 38.0746 -102.324408)
		(width 0.089408)
		(layer "In11.Cu")
		(net "FM_CPU1_PKGID1")
	)
	(segment
		(start 71.45909 -82.43189)
		(end 71.48322 -82.43189)
		(width 0.0889)
		(layer "In11.Cu")
		(net "FM_CPU1_PKGID1")
	)
	(segment
		(start 178.002184 -104.850692)
		(end 174.961296 -101.809804)
		(width 0.089408)
		(layer "In11.Cu")
		(net "FM_CPU1_PKGID1")
	)
	(segment
		(start 28.591764 -132.723636)
		(end 28.591764 -130.98018)
		(width 0.089408)
		(layer "In11.Cu")
		(net "FM_CPU1_PKGID1")
	)
	(segment
		(start 370.772944 -61.908182)
		(end 370.772944 -63.047118)
		(width 0.089408)
		(layer "In11.Cu")
		(net "FM_CPU1_PKGID1")
	)
	(segment
		(start 345.905074 -52.518056)
		(end 347.119194 -53.732176)
		(width 0.089408)
		(layer "In11.Cu")
		(net "FM_CPU1_PKGID1")
	)
	(segment
		(start 157.131766 -155.054808)
		(end 157.131766 -155.939236)
		(width 0.089408)
		(layer "In11.Cu")
		(net "FM_CPU1_PKGID1")
	)
	(segment
		(start 194.4878 -7.049008)
		(end 194.4878 -0.8382)
		(width 0.089408)
		(layer "In11.Cu")
		(net "FM_CPU1_PKGID1")
	)
	(segment
		(start 164.677344 -150.890224)
		(end 163.710112 -151.857456)
		(width 0.089408)
		(layer "In11.Cu")
		(net "FM_CPU1_PKGID1")
	)
	(segment
		(start 157.088078 -154.48915)
		(end 157.088078 -155.01112)
		(width 0.089408)
		(layer "In11.Cu")
		(net "FM_CPU1_PKGID1")
	)
	(segment
		(start 112.526064 -156.63799)
		(end 30.658054 -156.63799)
		(width 0.089408)
		(layer "In11.Cu")
		(net "FM_CPU1_PKGID1")
	)
	(segment
		(start 321.607688 -25.185624)
		(end 321.607688 -26.945844)
		(width 0.089408)
		(layer "In11.Cu")
		(net "FM_CPU1_PKGID1")
	)
	(segment
		(start 321.481704 -30.523942)
		(end 321.010026 -30.99562)
		(width 0.089408)
		(layer "In11.Cu")
		(net "FM_CPU1_PKGID1")
	)
	(arc
		(start 74.392536 -81.145888)
		(mid 74.59954 -81.356752)
		(end 74.882756 -81.441036)
		(width 0.0889)
		(layer "In11.Cu")
		(net "FM_CPU1_PKGID1")
	)
	(arc
		(start 73.208896 -81.441036)
		(mid 73.492113 -81.356755)
		(end 73.699116 -81.145888)
		(width 0.0889)
		(layer "In11.Cu")
		(net "FM_CPU1_PKGID1")
	)
	(arc
		(start 67.474084 -84.71789)
		(mid 67.578525 -84.688868)
		(end 67.653154 -84.610194)
		(width 0.0889)
		(layer "In11.Cu")
		(net "FM_CPU1_PKGID1")
	)
	(arc
		(start 69.774816 -83.42249)
		(mid 70.058033 -83.338209)
		(end 70.265036 -83.127342)
		(width 0.0889)
		(layer "In11.Cu")
		(net "FM_CPU1_PKGID1")
	)
	(arc
		(start 72.346566 -81.93659)
		(mid 72.63199 -81.853123)
		(end 72.840596 -81.641188)
		(width 0.0889)
		(layer "In11.Cu")
		(net "FM_CPU1_PKGID1")
	)
	(arc
		(start 69.406516 -83.622388)
		(mid 69.54526 -83.480355)
		(end 69.735192 -83.42249)
		(width 0.0889)
		(layer "In11.Cu")
		(net "FM_CPU1_PKGID1")
	)
	(arc
		(start 70.265036 -83.127342)
		(mid 70.406719 -82.983538)
		(end 70.60057 -82.92719)
		(width 0.0889)
		(layer "In11.Cu")
		(net "FM_CPU1_PKGID1")
	)
	(arc
		(start 68.912486 -83.91779)
		(mid 69.19791 -83.834323)
		(end 69.406516 -83.622388)
		(width 0.0889)
		(layer "In11.Cu")
		(net "FM_CPU1_PKGID1")
	)
	(arc
		(start 75.777852 -81.93659)
		(mid 75.969494 -81.993756)
		(end 76.109576 -82.136488)
		(width 0.0889)
		(layer "In11.Cu")
		(net "FM_CPU1_PKGID1")
	)
	(arc
		(start 71.48322 -82.43189)
		(mid 71.771365 -82.349571)
		(end 71.982076 -82.136488)
		(width 0.0889)
		(layer "In11.Cu")
		(net "FM_CPU1_PKGID1")
	)
	(arc
		(start 70.633336 -82.92719)
		(mid 70.916553 -82.842909)
		(end 71.123556 -82.632042)
		(width 0.0889)
		(layer "In11.Cu")
		(net "FM_CPU1_PKGID1")
	)
	(arc
		(start 72.840596 -81.641188)
		(mid 72.982279 -81.497384)
		(end 73.17613 -81.441036)
		(width 0.0889)
		(layer "In11.Cu")
		(net "FM_CPU1_PKGID1")
	)
	(arc
		(start 76.632562 -82.43189)
		(mid 76.826412 -82.48824)
		(end 76.968096 -82.632042)
		(width 0.0889)
		(layer "In11.Cu")
		(net "FM_CPU1_PKGID1")
	)
	(arc
		(start 76.109576 -82.136488)
		(mid 76.320289 -82.349567)
		(end 76.608432 -82.43189)
		(width 0.0889)
		(layer "In11.Cu")
		(net "FM_CPU1_PKGID1")
	)
	(arc
		(start 68.057776 -84.412836)
		(mid 68.340993 -84.328555)
		(end 68.547996 -84.117688)
		(width 0.0889)
		(layer "In11.Cu")
		(net "FM_CPU1_PKGID1")
	)
	(arc
		(start 77.479906 -82.92719)
		(mid 77.677067 -82.979149)
		(end 77.82306 -83.1215)
		(width 0.0889)
		(layer "In11.Cu")
		(net "FM_CPU1_PKGID1")
	)
	(arc
		(start 71.982076 -82.136488)
		(mid 72.122155 -81.993752)
		(end 72.3138 -81.93659)
		(width 0.0889)
		(layer "In11.Cu")
		(net "FM_CPU1_PKGID1")
	)
	(arc
		(start 73.699116 -81.145888)
		(mid 73.839195 -81.003152)
		(end 74.03084 -80.94599)
		(width 0.0889)
		(layer "In11.Cu")
		(net "FM_CPU1_PKGID1")
	)
	(arc
		(start 78.356206 -83.42249)
		(mid 78.689175 -83.630038)
		(end 78.684882 -84.022438)
		(width 0.0889)
		(layer "In11.Cu")
		(net "FM_CPU1_PKGID1")
	)
	(arc
		(start 71.123556 -82.632042)
		(mid 71.265239 -82.488238)
		(end 71.45909 -82.43189)
		(width 0.0889)
		(layer "In11.Cu")
		(net "FM_CPU1_PKGID1")
	)
	(arc
		(start 74.060812 -80.94599)
		(mid 74.252454 -81.003156)
		(end 74.392536 -81.145888)
		(width 0.0889)
		(layer "In11.Cu")
		(net "FM_CPU1_PKGID1")
	)
	(arc
		(start 78.684882 -84.022438)
		(mid 78.60566 -84.311556)
		(end 78.678532 -84.60232)
		(width 0.0889)
		(layer "In11.Cu")
		(net "FM_CPU1_PKGID1")
	)
	(arc
		(start 68.547996 -84.117688)
		(mid 68.688075 -83.974952)
		(end 68.87972 -83.91779)
		(width 0.0889)
		(layer "In11.Cu")
		(net "FM_CPU1_PKGID1")
	)
	(arc
		(start 67.653154 -84.610194)
		(mid 67.744268 -84.492602)
		(end 67.869816 -84.412836)
		(width 0.0889)
		(layer "In11.Cu")
		(net "FM_CPU1_PKGID1")
	)
	(arc
		(start 75.251056 -81.641188)
		(mid 75.459664 -81.85312)
		(end 75.745086 -81.93659)
		(width 0.0889)
		(layer "In11.Cu")
		(net "FM_CPU1_PKGID1")
	)
	(arc
		(start 74.915522 -81.441036)
		(mid 75.109372 -81.497386)
		(end 75.251056 -81.641188)
		(width 0.0889)
		(layer "In11.Cu")
		(net "FM_CPU1_PKGID1")
	)
	(arc
		(start 76.968096 -82.632042)
		(mid 77.1751 -82.842906)
		(end 77.458316 -82.92719)
		(width 0.0889)
		(layer "In11.Cu")
		(net "FM_CPU1_PKGID1")
	)
	(arc
		(start 77.826362 -83.127342)
		(mid 78.033366 -83.338206)
		(end 78.316582 -83.42249)
		(width 0.0889)
		(layer "In11.Cu")
		(net "FM_CPU1_PKGID1")
	)
	(segment
		(start 79.768192 -90.26144)
		(end 79.196692 -90.26144)
		(width 0.10795)
		(layer "F.Cu")
		(net "FM_CPU1_PKGID0")
	)
	(segment
		(start 369.545108 -79.894684)
		(end 369.944904 -79.494888)
		(width 0.1016)
		(layer "F.Cu")
		(net "FM_CPU1_PKGID0")
	)
	(via
		(at 79.196692 -90.26144)
		(size 0.508)
		(drill 0.254)
		(layers "F.Cu" "B.Cu")
		(net "FM_CPU1_PKGID0")
	)
	(via
		(at 372.0338 -65.0494)
		(size 0.508)
		(drill 0.254)
		(layers "F.Cu" "B.Cu")
		(net "FM_CPU1_PKGID0")
	)
	(via
		(at 369.545108 -79.894684)
		(size 0.4572)
		(drill 0.2032)
		(layers "F.Cu" "B.Cu")
		(net "FM_CPU1_PKGID0")
	)
	(via
		(at 163.703 -150.9776)
		(size 0.508)
		(drill 0.254)
		(layers "F.Cu" "B.Cu")
		(net "FM_CPU1_PKGID0")
	)
	(via
		(at 66.5988 -91.7448)
		(size 0.6604)
		(drill 0.3302)
		(layers "F.Cu" "B.Cu")
		(net "FM_CPU1_PKGID0")
	)
	(via
		(at 178.181 -128.397)
		(size 0.508)
		(drill 0.254)
		(layers "F.Cu" "B.Cu")
		(net "FM_CPU1_PKGID0")
	)
	(segment
		(start 74.215498 -91.661488)
		(end 74.657966 -91.21902)
		(width 0.10795)
		(layer "B.Cu")
		(net "FM_CPU1_PKGID0")
	)
	(segment
		(start 70.11416 -91.337638)
		(end 70.240144 -91.463622)
		(width 0.10795)
		(layer "B.Cu")
		(net "FM_CPU1_PKGID0")
	)
	(segment
		(start 72.498458 -91.661488)
		(end 72.822308 -91.337638)
		(width 0.10795)
		(layer "B.Cu")
		(net "FM_CPU1_PKGID0")
	)
	(segment
		(start 75.932538 -91.661488)
		(end 76.370688 -91.223338)
		(width 0.10795)
		(layer "B.Cu")
		(net "FM_CPU1_PKGID0")
	)
	(segment
		(start 73.876154 -91.661488)
		(end 74.215498 -91.661488)
		(width 0.10795)
		(layer "B.Cu")
		(net "FM_CPU1_PKGID0")
	)
	(segment
		(start 74.657966 -91.21902)
		(end 75.150726 -91.21902)
		(width 0.10795)
		(layer "B.Cu")
		(net "FM_CPU1_PKGID0")
	)
	(segment
		(start 71.674482 -91.18727)
		(end 72.159114 -91.661488)
		(width 0.10795)
		(layer "B.Cu")
		(net "FM_CPU1_PKGID0")
	)
	(segment
		(start 72.159114 -91.661488)
		(end 72.498458 -91.661488)
		(width 0.10795)
		(layer "B.Cu")
		(net "FM_CPU1_PKGID0")
	)
	(segment
		(start 64.1858 -92.1512)
		(end 66.1924 -92.1512)
		(width 0.10795)
		(layer "B.Cu")
		(net "FM_CPU1_PKGID0")
	)
	(segment
		(start 67.2084 -91.1352)
		(end 68.683124 -91.1352)
		(width 0.10795)
		(layer "B.Cu")
		(net "FM_CPU1_PKGID0")
	)
	(segment
		(start 71.255636 -91.18727)
		(end 71.674482 -91.18727)
		(width 0.10795)
		(layer "B.Cu")
		(net "FM_CPU1_PKGID0")
	)
	(segment
		(start 70.781418 -91.661488)
		(end 71.255636 -91.18727)
		(width 0.10795)
		(layer "B.Cu")
		(net "FM_CPU1_PKGID0")
	)
	(segment
		(start 76.370688 -91.223338)
		(end 76.872084 -91.223338)
		(width 0.10795)
		(layer "B.Cu")
		(net "FM_CPU1_PKGID0")
	)
	(segment
		(start 68.885562 -91.337638)
		(end 70.11416 -91.337638)
		(width 0.10795)
		(layer "B.Cu")
		(net "FM_CPU1_PKGID0")
	)
	(segment
		(start 66.1924 -92.1512)
		(end 66.5988 -91.7448)
		(width 0.10795)
		(layer "B.Cu")
		(net "FM_CPU1_PKGID0")
	)
	(segment
		(start 77.649578 -91.661488)
		(end 78.145132 -91.165934)
		(width 0.10795)
		(layer "B.Cu")
		(net "FM_CPU1_PKGID0")
	)
	(segment
		(start 68.683124 -91.1352)
		(end 68.885562 -91.337638)
		(width 0.10795)
		(layer "B.Cu")
		(net "FM_CPU1_PKGID0")
	)
	(segment
		(start 78.507844 -91.165934)
		(end 79.196692 -90.477086)
		(width 0.10795)
		(layer "B.Cu")
		(net "FM_CPU1_PKGID0")
	)
	(segment
		(start 70.240144 -91.463622)
		(end 70.442074 -91.661488)
		(width 0.10795)
		(layer "B.Cu")
		(net "FM_CPU1_PKGID0")
	)
	(segment
		(start 75.150726 -91.21902)
		(end 75.593194 -91.661488)
		(width 0.10795)
		(layer "B.Cu")
		(net "FM_CPU1_PKGID0")
	)
	(segment
		(start 76.872084 -91.223338)
		(end 77.310234 -91.661488)
		(width 0.10795)
		(layer "B.Cu")
		(net "FM_CPU1_PKGID0")
	)
	(segment
		(start 75.593194 -91.661488)
		(end 75.932538 -91.661488)
		(width 0.10795)
		(layer "B.Cu")
		(net "FM_CPU1_PKGID0")
	)
	(segment
		(start 78.145132 -91.165934)
		(end 78.507844 -91.165934)
		(width 0.10795)
		(layer "B.Cu")
		(net "FM_CPU1_PKGID0")
	)
	(segment
		(start 73.545446 -91.337638)
		(end 73.876154 -91.661488)
		(width 0.10795)
		(layer "B.Cu")
		(net "FM_CPU1_PKGID0")
	)
	(segment
		(start 70.442074 -91.661488)
		(end 70.781418 -91.661488)
		(width 0.10795)
		(layer "B.Cu")
		(net "FM_CPU1_PKGID0")
	)
	(segment
		(start 79.196692 -90.477086)
		(end 79.196692 -90.26144)
		(width 0.10795)
		(layer "B.Cu")
		(net "FM_CPU1_PKGID0")
	)
	(segment
		(start 77.310234 -91.661488)
		(end 77.649578 -91.661488)
		(width 0.10795)
		(layer "B.Cu")
		(net "FM_CPU1_PKGID0")
	)
	(segment
		(start 66.5988 -91.7448)
		(end 67.2084 -91.1352)
		(width 0.10795)
		(layer "B.Cu")
		(net "FM_CPU1_PKGID0")
	)
	(segment
		(start 72.822308 -91.337638)
		(end 73.545446 -91.337638)
		(width 0.10795)
		(layer "B.Cu")
		(net "FM_CPU1_PKGID0")
	)
	(segment
		(start 178.0794 -128.4986)
		(end 166.3954 -128.4986)
		(width 0.089408)
		(layer "In2.Cu")
		(net "FM_CPU1_PKGID0")
	)
	(segment
		(start 163.703 -148.9202)
		(end 163.703 -150.9776)
		(width 0.089408)
		(layer "In2.Cu")
		(net "FM_CPU1_PKGID0")
	)
	(segment
		(start 178.181 -128.397)
		(end 178.0794 -128.4986)
		(width 0.089408)
		(layer "In2.Cu")
		(net "FM_CPU1_PKGID0")
	)
	(segment
		(start 162.306 -147.5232)
		(end 163.703 -148.9202)
		(width 0.089408)
		(layer "In2.Cu")
		(net "FM_CPU1_PKGID0")
	)
	(segment
		(start 161.975546 -133.1468)
		(end 161.4932 -133.1468)
		(width 0.089408)
		(layer "In2.Cu")
		(net "FM_CPU1_PKGID0")
	)
	(segment
		(start 166.3954 -128.4986)
		(end 163.682426 -131.211574)
		(width 0.089408)
		(layer "In2.Cu")
		(net "FM_CPU1_PKGID0")
	)
	(segment
		(start 163.682426 -131.211574)
		(end 163.682426 -131.43992)
		(width 0.089408)
		(layer "In2.Cu")
		(net "FM_CPU1_PKGID0")
	)
	(segment
		(start 161.4932 -133.1468)
		(end 160.1978 -134.4422)
		(width 0.089408)
		(layer "In2.Cu")
		(net "FM_CPU1_PKGID0")
	)
	(segment
		(start 160.1978 -146.9136)
		(end 160.8074 -147.5232)
		(width 0.089408)
		(layer "In2.Cu")
		(net "FM_CPU1_PKGID0")
	)
	(segment
		(start 163.682426 -131.43992)
		(end 161.975546 -133.1468)
		(width 0.089408)
		(layer "In2.Cu")
		(net "FM_CPU1_PKGID0")
	)
	(segment
		(start 160.8074 -147.5232)
		(end 162.306 -147.5232)
		(width 0.089408)
		(layer "In2.Cu")
		(net "FM_CPU1_PKGID0")
	)
	(segment
		(start 160.1978 -134.4422)
		(end 160.1978 -146.9136)
		(width 0.089408)
		(layer "In2.Cu")
		(net "FM_CPU1_PKGID0")
	)
	(segment
		(start 371.057424 -69.05498)
		(end 370.7384 -69.374004)
		(width 0.089408)
		(layer "In9.Cu")
		(net "FM_CPU1_PKGID0")
	)
	(segment
		(start 369.9256 -78.98638)
		(end 369.9256 -79.514192)
		(width 0.089408)
		(layer "In9.Cu")
		(net "FM_CPU1_PKGID0")
	)
	(segment
		(start 371.54358 -68.836286)
		(end 371.324886 -69.05498)
		(width 0.089408)
		(layer "In9.Cu")
		(net "FM_CPU1_PKGID0")
	)
	(segment
		(start 370.417852 -66.744596)
		(end 370.417852 -67.707256)
		(width 0.089408)
		(layer "In9.Cu")
		(net "FM_CPU1_PKGID0")
	)
	(segment
		(start 372.0338 -65.128648)
		(end 370.417852 -66.744596)
		(width 0.089408)
		(layer "In9.Cu")
		(net "FM_CPU1_PKGID0")
	)
	(segment
		(start 372.0338 -65.0494)
		(end 372.0338 -65.128648)
		(width 0.089408)
		(layer "In9.Cu")
		(net "FM_CPU1_PKGID0")
	)
	(segment
		(start 370.7384 -69.374004)
		(end 370.7384 -78.429612)
		(width 0.089408)
		(layer "In9.Cu")
		(net "FM_CPU1_PKGID0")
	)
	(segment
		(start 371.324886 -69.05498)
		(end 371.057424 -69.05498)
		(width 0.089408)
		(layer "In9.Cu")
		(net "FM_CPU1_PKGID0")
	)
	(segment
		(start 370.417852 -67.707256)
		(end 370.882418 -68.171822)
		(width 0.089408)
		(layer "In9.Cu")
		(net "FM_CPU1_PKGID0")
	)
	(segment
		(start 370.446554 -78.721458)
		(end 370.190522 -78.721458)
		(width 0.089408)
		(layer "In9.Cu")
		(net "FM_CPU1_PKGID0")
	)
	(segment
		(start 370.7384 -78.429612)
		(end 370.446554 -78.721458)
		(width 0.089408)
		(layer "In9.Cu")
		(net "FM_CPU1_PKGID0")
	)
	(segment
		(start 370.882418 -68.171822)
		(end 371.238526 -68.171822)
		(width 0.089408)
		(layer "In9.Cu")
		(net "FM_CPU1_PKGID0")
	)
	(segment
		(start 369.9256 -79.514192)
		(end 369.545108 -79.894684)
		(width 0.089408)
		(layer "In9.Cu")
		(net "FM_CPU1_PKGID0")
	)
	(segment
		(start 370.190522 -78.721458)
		(end 369.9256 -78.98638)
		(width 0.089408)
		(layer "In9.Cu")
		(net "FM_CPU1_PKGID0")
	)
	(segment
		(start 371.54358 -68.476876)
		(end 371.54358 -68.836286)
		(width 0.089408)
		(layer "In9.Cu")
		(net "FM_CPU1_PKGID0")
	)
	(segment
		(start 371.238526 -68.171822)
		(end 371.54358 -68.476876)
		(width 0.089408)
		(layer "In9.Cu")
		(net "FM_CPU1_PKGID0")
	)
	(segment
		(start 321.818 -29.75229)
		(end 321.818 -29.754322)
		(width 0.089408)
		(layer "In11.Cu")
		(net "FM_CPU1_PKGID0")
	)
	(segment
		(start 156.492702 -156.037788)
		(end 112.585754 -156.037788)
		(width 0.089408)
		(layer "In11.Cu")
		(net "FM_CPU1_PKGID0")
	)
	(segment
		(start 320.62801 -30.800548)
		(end 320.62801 -31.993078)
		(width 0.089408)
		(layer "In11.Cu")
		(net "FM_CPU1_PKGID0")
	)
	(segment
		(start 320.62801 -31.993078)
		(end 317.641224 -34.979864)
		(width 0.089408)
		(layer "In11.Cu")
		(net "FM_CPU1_PKGID0")
	)
	(segment
		(start 174.471838 -93.770958)
		(end 174.471838 -91.966542)
		(width 0.089408)
		(layer "In11.Cu")
		(net "FM_CPU1_PKGID0")
	)
	(segment
		(start 73.17613 -82.43189)
		(end 73.20026 -82.43189)
		(width 0.0889)
		(layer "In11.Cu")
		(net "FM_CPU1_PKGID0")
	)
	(segment
		(start 157.777942 -83.26755)
		(end 157.777942 -66.848736)
		(width 0.089408)
		(layer "In11.Cu")
		(net "FM_CPU1_PKGID0")
	)
	(segment
		(start 317.306452 -43.73499)
		(end 317.306452 -44.22521)
		(width 0.089408)
		(layer "In11.Cu")
		(net "FM_CPU1_PKGID0")
	)
	(segment
		(start 33.925002 -110.170976)
		(end 34.40684 -110.170976)
		(width 0.089408)
		(layer "In11.Cu")
		(net "FM_CPU1_PKGID0")
	)
	(segment
		(start 190.42507 -20.090384)
		(end 193.490088 -17.025366)
		(width 0.089408)
		(layer "In11.Cu")
		(net "FM_CPU1_PKGID0")
	)
	(segment
		(start 160.210754 -61.94044)
		(end 160.210754 -54.597046)
		(width 0.089408)
		(layer "In11.Cu")
		(net "FM_CPU1_PKGID0")
	)
	(segment
		(start 38.510464 -102.429056)
		(end 41.169844 -99.769676)
		(width 0.089408)
		(layer "In11.Cu")
		(net "FM_CPU1_PKGID0")
	)
	(segment
		(start 320.78422 -46.360588)
		(end 326.391778 -51.968146)
		(width 0.089408)
		(layer "In11.Cu")
		(net "FM_CPU1_PKGID0")
	)
	(segment
		(start 160.210754 -54.597046)
		(end 184.293256 -30.514544)
		(width 0.089408)
		(layer "In11.Cu")
		(net "FM_CPU1_PKGID0")
	)
	(segment
		(start 70.59676 -83.91779)
		(end 70.629526 -83.91779)
		(width 0.0889)
		(layer "In11.Cu")
		(net "FM_CPU1_PKGID0")
	)
	(segment
		(start 193.490088 0.515112)
		(end 193.490088 2.3114)
		(width 0.089408)
		(layer "In11.Cu")
		(net "FM_CPU1_PKGID0")
	)
	(segment
		(start 317.237872 -45.107606)
		(end 318.490854 -46.360588)
		(width 0.089408)
		(layer "In11.Cu")
		(net "FM_CPU1_PKGID0")
	)
	(segment
		(start 31.489142 -156.255974)
		(end 30.9372 -155.704032)
		(width 0.089408)
		(layer "In11.Cu")
		(net "FM_CPU1_PKGID0")
	)
	(segment
		(start 163.703 -150.9776)
		(end 163.20516 -151.47544)
		(width 0.089408)
		(layer "In11.Cu")
		(net "FM_CPU1_PKGID0")
	)
	(segment
		(start 194.7418 -0.7366)
		(end 193.490088 0.515112)
		(width 0.089408)
		(layer "In11.Cu")
		(net "FM_CPU1_PKGID0")
	)
	(segment
		(start 29.834586 -132.553202)
		(end 29.299154 -132.01777)
		(width 0.089408)
		(layer "In11.Cu")
		(net "FM_CPU1_PKGID0")
	)
	(segment
		(start 52.777136 -94.189296)
		(end 61.839856 -85.126576)
		(width 0.089408)
		(layer "In11.Cu")
		(net "FM_CPU1_PKGID0")
	)
	(segment
		(start 365.282734 -57.105296)
		(end 365.405162 -57.105296)
		(width 0.089408)
		(layer "In11.Cu")
		(net "FM_CPU1_PKGID0")
	)
	(segment
		(start 34.40684 -110.170976)
		(end 36.9062 -107.671616)
		(width 0.089408)
		(layer "In11.Cu")
		(net "FM_CPU1_PKGID0")
	)
	(segment
		(start 194.7418 -7.409688)
		(end 194.7418 -0.7366)
		(width 0.089408)
		(layer "In11.Cu")
		(net "FM_CPU1_PKGID0")
	)
	(segment
		(start 30.9372 -155.2194)
		(end 30.103064 -154.385264)
		(width 0.089408)
		(layer "In11.Cu")
		(net "FM_CPU1_PKGID0")
	)
	(segment
		(start 38.510464 -103.708708)
		(end 38.510464 -102.429056)
		(width 0.089408)
		(layer "In11.Cu")
		(net "FM_CPU1_PKGID0")
	)
	(segment
		(start 371.262656 -65.0494)
		(end 372.0338 -65.0494)
		(width 0.089408)
		(layer "In11.Cu")
		(net "FM_CPU1_PKGID0")
	)
	(segment
		(start 178.181 -128.397)
		(end 178.943 -128.397)
		(width 0.089408)
		(layer "In11.Cu")
		(net "FM_CPU1_PKGID0")
	)
	(segment
		(start 321.43065 -30.141672)
		(end 321.286886 -30.141672)
		(width 0.089408)
		(layer "In11.Cu")
		(net "FM_CPU1_PKGID0")
	)
	(segment
		(start 363.941614 -57.105296)
		(end 365.124238 -57.105296)
		(width 0.089408)
		(layer "In11.Cu")
		(net "FM_CPU1_PKGID0")
	)
	(segment
		(start 341.327486 -54.114192)
		(end 348.062296 -54.114192)
		(width 0.089408)
		(layer "In11.Cu")
		(net "FM_CPU1_PKGID0")
	)
	(segment
		(start 112.585754 -156.037788)
		(end 112.367568 -156.255974)
		(width 0.089408)
		(layer "In11.Cu")
		(net "FM_CPU1_PKGID0")
	)
	(segment
		(start 30.03423 -114.061748)
		(end 33.925002 -110.170976)
		(width 0.089408)
		(layer "In11.Cu")
		(net "FM_CPU1_PKGID0")
	)
	(segment
		(start 67.869816 -85.403436)
		(end 68.057776 -85.403436)
		(width 0.0889)
		(layer "In11.Cu")
		(net "FM_CPU1_PKGID0")
	)
	(segment
		(start 316.615318 -35.797236)
		(end 316.615318 -43.043856)
		(width 0.089408)
		(layer "In11.Cu")
		(net "FM_CPU1_PKGID0")
	)
	(segment
		(start 365.124238 -57.105296)
		(end 365.124492 -57.105042)
		(width 0.089408)
		(layer "In11.Cu")
		(net "FM_CPU1_PKGID0")
	)
	(segment
		(start 182.049166 -129.2606)
		(end 182.289704 -129.020062)
		(width 0.089408)
		(layer "In11.Cu")
		(net "FM_CPU1_PKGID0")
	)
	(segment
		(start 156.74975 -155.78074)
		(end 156.492702 -156.037788)
		(width 0.089408)
		(layer "In11.Cu")
		(net "FM_CPU1_PKGID0")
	)
	(segment
		(start 322.929504 2.18567)
		(end 322.929504 -23.593552)
		(width 0.089408)
		(layer "In11.Cu")
		(net "FM_CPU1_PKGID0")
	)
	(segment
		(start 365.28248 -57.105042)
		(end 365.282734 -57.105296)
		(width 0.089408)
		(layer "In11.Cu")
		(net "FM_CPU1_PKGID0")
	)
	(segment
		(start 317.641224 -34.979864)
		(end 317.274194 -34.979864)
		(width 0.089408)
		(layer "In11.Cu")
		(net "FM_CPU1_PKGID0")
	)
	(segment
		(start 184.293256 -30.514544)
		(end 184.293256 -21.557742)
		(width 0.089408)
		(layer "In11.Cu")
		(net "FM_CPU1_PKGID0")
	)
	(segment
		(start 321.286886 -30.141672)
		(end 320.62801 -30.800548)
		(width 0.089408)
		(layer "In11.Cu")
		(net "FM_CPU1_PKGID0")
	)
	(segment
		(start 321.41668 -25.106376)
		(end 321.41668 -27.025092)
		(width 0.089408)
		(layer "In11.Cu")
		(net "FM_CPU1_PKGID0")
	)
	(segment
		(start 184.293256 -21.557742)
		(end 185.760614 -20.090384)
		(width 0.089408)
		(layer "In11.Cu")
		(net "FM_CPU1_PKGID0")
	)
	(segment
		(start 322.929504 -23.593552)
		(end 321.41668 -25.106376)
		(width 0.089408)
		(layer "In11.Cu")
		(net "FM_CPU1_PKGID0")
	)
	(segment
		(start 321.818 -29.754322)
		(end 321.43065 -30.141672)
		(width 0.089408)
		(layer "In11.Cu")
		(net "FM_CPU1_PKGID0")
	)
	(segment
		(start 29.299154 -130.82397)
		(end 30.023562 -130.099562)
		(width 0.089408)
		(layer "In11.Cu")
		(net "FM_CPU1_PKGID0")
	)
	(segment
		(start 178.193192 -104.6861)
		(end 175.152304 -101.645212)
		(width 0.089408)
		(layer "In11.Cu")
		(net "FM_CPU1_PKGID0")
	)
	(segment
		(start 77.826362 -88.480138)
		(end 77.817472 -88.495378)
		(width 0.0889)
		(layer "In11.Cu")
		(net "FM_CPU1_PKGID0")
	)
	(segment
		(start 316.615064 -35.480498)
		(end 316.615064 -35.796982)
		(width 0.089408)
		(layer "In11.Cu")
		(net "FM_CPU1_PKGID0")
	)
	(segment
		(start 156.706062 -155.169616)
		(end 156.74975 -155.213304)
		(width 0.089408)
		(layer "In11.Cu")
		(net "FM_CPU1_PKGID0")
	)
	(segment
		(start 318.490854 -46.360588)
		(end 320.78422 -46.360588)
		(width 0.089408)
		(layer "In11.Cu")
		(net "FM_CPU1_PKGID0")
	)
	(segment
		(start 163.20516 -151.47544)
		(end 159.561276 -151.47544)
		(width 0.089408)
		(layer "In11.Cu")
		(net "FM_CPU1_PKGID0")
	)
	(segment
		(start 29.834586 -139.517374)
		(end 29.834586 -132.553202)
		(width 0.089408)
		(layer "In11.Cu")
		(net "FM_CPU1_PKGID0")
	)
	(segment
		(start 178.193192 -106.283252)
		(end 178.193192 -104.6861)
		(width 0.089408)
		(layer "In11.Cu")
		(net "FM_CPU1_PKGID0")
	)
	(segment
		(start 29.7434 -149.193504)
		(end 29.7434 -142.048992)
		(width 0.089408)
		(layer "In11.Cu")
		(net "FM_CPU1_PKGID0")
	)
	(segment
		(start 79.196692 -89.923366)
		(end 79.196692 -90.26144)
		(width 0.0889)
		(layer "In11.Cu")
		(net "FM_CPU1_PKGID0")
	)
	(segment
		(start 66.342768 -85.126576)
		(end 66.946272 -85.73008)
		(width 0.089408)
		(layer "In11.Cu")
		(net "FM_CPU1_PKGID0")
	)
	(segment
		(start 371.126512 -64.913256)
		(end 371.262656 -65.0494)
		(width 0.089408)
		(layer "In11.Cu")
		(net "FM_CPU1_PKGID0")
	)
	(segment
		(start 357.37038 -53.1749)
		(end 360.011218 -53.1749)
		(width 0.089408)
		(layer "In11.Cu")
		(net "FM_CPU1_PKGID0")
	)
	(segment
		(start 317.237872 -44.29379)
		(end 317.237872 -45.107606)
		(width 0.089408)
		(layer "In11.Cu")
		(net "FM_CPU1_PKGID0")
	)
	(segment
		(start 159.561276 -151.47544)
		(end 156.706062 -154.330654)
		(width 0.089408)
		(layer "In11.Cu")
		(net "FM_CPU1_PKGID0")
	)
	(segment
		(start 164.614098 -90.103706)
		(end 157.777942 -83.26755)
		(width 0.089408)
		(layer "In11.Cu")
		(net "FM_CPU1_PKGID0")
	)
	(segment
		(start 38.402006 -104.5337)
		(end 38.665404 -104.270302)
		(width 0.089408)
		(layer "In11.Cu")
		(net "FM_CPU1_PKGID0")
	)
	(segment
		(start 79.131414 -89.858088)
		(end 79.196692 -89.923366)
		(width 0.0889)
		(layer "In11.Cu")
		(net "FM_CPU1_PKGID0")
	)
	(segment
		(start 77.462126 -83.91779)
		(end 77.479906 -83.91779)
		(width 0.0889)
		(layer "In11.Cu")
		(net "FM_CPU1_PKGID0")
	)
	(segment
		(start 182.289704 -129.020062)
		(end 182.289704 -128.01854)
		(width 0.089408)
		(layer "In11.Cu")
		(net "FM_CPU1_PKGID0")
	)
	(segment
		(start 48.40605 -98.46056)
		(end 52.076096 -94.790514)
		(width 0.089408)
		(layer "In11.Cu")
		(net "FM_CPU1_PKGID0")
	)
	(segment
		(start 159.435292 -65.191386)
		(end 159.435292 -62.715902)
		(width 0.089408)
		(layer "In11.Cu")
		(net "FM_CPU1_PKGID0")
	)
	(segment
		(start 30.103064 -152.853136)
		(end 30.116272 -152.839928)
		(width 0.089408)
		(layer "In11.Cu")
		(net "FM_CPU1_PKGID0")
	)
	(segment
		(start 322.07962 -27.846528)
		(end 322.07962 -29.49067)
		(width 0.089408)
		(layer "In11.Cu")
		(net "FM_CPU1_PKGID0")
	)
	(segment
		(start 175.152304 -99.483926)
		(end 174.206154 -98.537776)
		(width 0.089408)
		(layer "In11.Cu")
		(net "FM_CPU1_PKGID0")
	)
	(segment
		(start 181.79923 -127.528066)
		(end 181.79923 -109.88929)
		(width 0.089408)
		(layer "In11.Cu")
		(net "FM_CPU1_PKGID0")
	)
	(segment
		(start 30.103064 -154.385264)
		(end 30.103064 -152.853136)
		(width 0.089408)
		(layer "In11.Cu")
		(net "FM_CPU1_PKGID0")
	)
	(segment
		(start 178.943 -128.397)
		(end 179.8066 -129.2606)
		(width 0.089408)
		(layer "In11.Cu")
		(net "FM_CPU1_PKGID0")
	)
	(segment
		(start 317.115952 -34.97961)
		(end 316.615064 -35.480498)
		(width 0.089408)
		(layer "In11.Cu")
		(net "FM_CPU1_PKGID0")
	)
	(segment
		(start 193.490088 -17.025366)
		(end 193.490088 -8.6614)
		(width 0.089408)
		(layer "In11.Cu")
		(net "FM_CPU1_PKGID0")
	)
	(segment
		(start 38.665404 -104.270302)
		(end 38.665404 -103.863648)
		(width 0.089408)
		(layer "In11.Cu")
		(net "FM_CPU1_PKGID0")
	)
	(segment
		(start 369.824 -61.524134)
		(end 369.824 -63.155068)
		(width 0.089408)
		(layer "In11.Cu")
		(net "FM_CPU1_PKGID0")
	)
	(segment
		(start 179.8066 -129.2606)
		(end 182.049166 -129.2606)
		(width 0.089408)
		(layer "In11.Cu")
		(net "FM_CPU1_PKGID0")
	)
	(segment
		(start 340.03615 -51.968146)
		(end 341.084408 -53.016404)
		(width 0.089408)
		(layer "In11.Cu")
		(net "FM_CPU1_PKGID0")
	)
	(segment
		(start 365.405162 -57.105296)
		(end 369.824 -61.524134)
		(width 0.089408)
		(layer "In11.Cu")
		(net "FM_CPU1_PKGID0")
	)
	(segment
		(start 74.891392 -82.43189)
		(end 74.915522 -82.43189)
		(width 0.0889)
		(layer "In11.Cu")
		(net "FM_CPU1_PKGID0")
	)
	(segment
		(start 360.011218 -53.1749)
		(end 363.941614 -57.105296)
		(width 0.089408)
		(layer "In11.Cu")
		(net "FM_CPU1_PKGID0")
	)
	(segment
		(start 69.74205 -84.412836)
		(end 69.774816 -84.412836)
		(width 0.0889)
		(layer "In11.Cu")
		(net "FM_CPU1_PKGID0")
	)
	(segment
		(start 52.076096 -94.790514)
		(end 52.076096 -94.423738)
		(width 0.089408)
		(layer "In11.Cu")
		(net "FM_CPU1_PKGID0")
	)
	(segment
		(start 181.79923 -109.88929)
		(end 178.193192 -106.283252)
		(width 0.089408)
		(layer "In11.Cu")
		(net "FM_CPU1_PKGID0")
	)
	(segment
		(start 77.826362 -85.508338)
		(end 77.817472 -85.523578)
		(width 0.0889)
		(layer "In11.Cu")
		(net "FM_CPU1_PKGID0")
	)
	(segment
		(start 172.609002 -90.103706)
		(end 164.614098 -90.103706)
		(width 0.089408)
		(layer "In11.Cu")
		(net "FM_CPU1_PKGID0")
	)
	(segment
		(start 157.777942 -66.848736)
		(end 159.435292 -65.191386)
		(width 0.089408)
		(layer "In11.Cu")
		(net "FM_CPU1_PKGID0")
	)
	(segment
		(start 76.599796 -83.42249)
		(end 76.63942 -83.42249)
		(width 0.0889)
		(layer "In11.Cu")
		(net "FM_CPU1_PKGID0")
	)
	(segment
		(start 174.206154 -94.036642)
		(end 174.471838 -93.770958)
		(width 0.089408)
		(layer "In11.Cu")
		(net "FM_CPU1_PKGID0")
	)
	(segment
		(start 348.062296 -54.114192)
		(end 349.76562 -52.410868)
		(width 0.089408)
		(layer "In11.Cu")
		(net "FM_CPU1_PKGID0")
	)
	(segment
		(start 316.615318 -43.043856)
		(end 317.306452 -43.73499)
		(width 0.089408)
		(layer "In11.Cu")
		(net "FM_CPU1_PKGID0")
	)
	(segment
		(start 30.03423 -130.078226)
		(end 30.03423 -114.061748)
		(width 0.089408)
		(layer "In11.Cu")
		(net "FM_CPU1_PKGID0")
	)
	(segment
		(start 193.490088 -8.6614)
		(end 194.7418 -7.409688)
		(width 0.089408)
		(layer "In11.Cu")
		(net "FM_CPU1_PKGID0")
	)
	(segment
		(start 182.289704 -128.01854)
		(end 181.79923 -127.528066)
		(width 0.089408)
		(layer "In11.Cu")
		(net "FM_CPU1_PKGID0")
	)
	(segment
		(start 74.03084 -81.93659)
		(end 74.060812 -81.93659)
		(width 0.0889)
		(layer "In11.Cu")
		(net "FM_CPU1_PKGID0")
	)
	(segment
		(start 29.299154 -140.052806)
		(end 29.834586 -139.517374)
		(width 0.089408)
		(layer "In11.Cu")
		(net "FM_CPU1_PKGID0")
	)
	(segment
		(start 68.87972 -84.90839)
		(end 68.912486 -84.90839)
		(width 0.0889)
		(layer "In11.Cu")
		(net "FM_CPU1_PKGID0")
	)
	(segment
		(start 349.76562 -52.410868)
		(end 356.606348 -52.410868)
		(width 0.089408)
		(layer "In11.Cu")
		(net "FM_CPU1_PKGID0")
	)
	(segment
		(start 75.741276 -82.92719)
		(end 75.774042 -82.92719)
		(width 0.0889)
		(layer "In11.Cu")
		(net "FM_CPU1_PKGID0")
	)
	(segment
		(start 30.023562 -130.099562)
		(end 30.023562 -130.088894)
		(width 0.089408)
		(layer "In11.Cu")
		(net "FM_CPU1_PKGID0")
	)
	(segment
		(start 30.023562 -130.088894)
		(end 30.03423 -130.078226)
		(width 0.089408)
		(layer "In11.Cu")
		(net "FM_CPU1_PKGID0")
	)
	(segment
		(start 36.9062 -105.504234)
		(end 37.876734 -104.5337)
		(width 0.089408)
		(layer "In11.Cu")
		(net "FM_CPU1_PKGID0")
	)
	(segment
		(start 322.07962 -29.49067)
		(end 321.818 -29.75229)
		(width 0.089408)
		(layer "In11.Cu")
		(net "FM_CPU1_PKGID0")
	)
	(segment
		(start 174.471838 -91.966542)
		(end 172.609002 -90.103706)
		(width 0.089408)
		(layer "In11.Cu")
		(net "FM_CPU1_PKGID0")
	)
	(segment
		(start 61.839856 -85.126576)
		(end 66.342768 -85.126576)
		(width 0.089408)
		(layer "In11.Cu")
		(net "FM_CPU1_PKGID0")
	)
	(segment
		(start 78.31328 -89.365836)
		(end 78.349348 -89.365836)
		(width 0.0889)
		(layer "In11.Cu")
		(net "FM_CPU1_PKGID0")
	)
	(segment
		(start 365.124492 -57.105042)
		(end 365.28248 -57.105042)
		(width 0.089408)
		(layer "In11.Cu")
		(net "FM_CPU1_PKGID0")
	)
	(segment
		(start 66.946272 -85.73008)
		(end 67.43827 -85.73008)
		(width 0.0889)
		(layer "In11.Cu")
		(net "FM_CPU1_PKGID0")
	)
	(segment
		(start 174.206154 -98.537776)
		(end 174.206154 -94.036642)
		(width 0.089408)
		(layer "In11.Cu")
		(net "FM_CPU1_PKGID0")
	)
	(segment
		(start 38.665404 -103.863648)
		(end 38.510464 -103.708708)
		(width 0.089408)
		(layer "In11.Cu")
		(net "FM_CPU1_PKGID0")
	)
	(segment
		(start 317.306452 -44.22521)
		(end 317.237872 -44.29379)
		(width 0.089408)
		(layer "In11.Cu")
		(net "FM_CPU1_PKGID0")
	)
	(segment
		(start 41.169844 -99.769676)
		(end 45.919898 -99.769676)
		(width 0.089408)
		(layer "In11.Cu")
		(net "FM_CPU1_PKGID0")
	)
	(segment
		(start 156.706062 -154.330654)
		(end 156.706062 -155.169616)
		(width 0.089408)
		(layer "In11.Cu")
		(net "FM_CPU1_PKGID0")
	)
	(segment
		(start 30.116272 -152.839928)
		(end 30.116272 -149.566376)
		(width 0.089408)
		(layer "In11.Cu")
		(net "FM_CPU1_PKGID0")
	)
	(segment
		(start 194.766692 3.588004)
		(end 321.52717 3.588004)
		(width 0.089408)
		(layer "In11.Cu")
		(net "FM_CPU1_PKGID0")
	)
	(segment
		(start 321.52717 3.588004)
		(end 322.929504 2.18567)
		(width 0.089408)
		(layer "In11.Cu")
		(net "FM_CPU1_PKGID0")
	)
	(segment
		(start 193.490088 2.3114)
		(end 194.766692 3.588004)
		(width 0.089408)
		(layer "In11.Cu")
		(net "FM_CPU1_PKGID0")
	)
	(segment
		(start 316.615064 -35.796982)
		(end 316.615318 -35.797236)
		(width 0.089408)
		(layer "In11.Cu")
		(net "FM_CPU1_PKGID0")
	)
	(segment
		(start 29.299154 -141.604746)
		(end 29.299154 -140.052806)
		(width 0.089408)
		(layer "In11.Cu")
		(net "FM_CPU1_PKGID0")
	)
	(segment
		(start 29.7434 -142.048992)
		(end 29.299154 -141.604746)
		(width 0.089408)
		(layer "In11.Cu")
		(net "FM_CPU1_PKGID0")
	)
	(segment
		(start 52.310538 -94.189296)
		(end 52.777136 -94.189296)
		(width 0.089408)
		(layer "In11.Cu")
		(net "FM_CPU1_PKGID0")
	)
	(segment
		(start 322.079874 -27.846274)
		(end 322.07962 -27.846528)
		(width 0.089408)
		(layer "In11.Cu")
		(net "FM_CPU1_PKGID0")
	)
	(segment
		(start 47.234094 -98.45548)
		(end 48.40097 -98.45548)
		(width 0.089408)
		(layer "In11.Cu")
		(net "FM_CPU1_PKGID0")
	)
	(segment
		(start 30.9372 -155.704032)
		(end 30.9372 -155.2194)
		(width 0.089408)
		(layer "In11.Cu")
		(net "FM_CPU1_PKGID0")
	)
	(segment
		(start 317.274194 -34.979864)
		(end 317.27394 -34.97961)
		(width 0.089408)
		(layer "In11.Cu")
		(net "FM_CPU1_PKGID0")
	)
	(segment
		(start 77.826362 -86.498938)
		(end 77.817472 -86.514178)
		(width 0.0889)
		(layer "In11.Cu")
		(net "FM_CPU1_PKGID0")
	)
	(segment
		(start 371.126512 -64.45758)
		(end 371.126512 -64.913256)
		(width 0.089408)
		(layer "In11.Cu")
		(net "FM_CPU1_PKGID0")
	)
	(segment
		(start 45.919898 -99.769676)
		(end 47.234094 -98.45548)
		(width 0.089408)
		(layer "In11.Cu")
		(net "FM_CPU1_PKGID0")
	)
	(segment
		(start 77.826362 -87.489538)
		(end 77.817472 -87.504778)
		(width 0.0889)
		(layer "In11.Cu")
		(net "FM_CPU1_PKGID0")
	)
	(segment
		(start 37.876734 -104.5337)
		(end 38.402006 -104.5337)
		(width 0.089408)
		(layer "In11.Cu")
		(net "FM_CPU1_PKGID0")
	)
	(segment
		(start 156.74975 -155.213304)
		(end 156.74975 -155.78074)
		(width 0.089408)
		(layer "In11.Cu")
		(net "FM_CPU1_PKGID0")
	)
	(segment
		(start 175.152304 -101.645212)
		(end 175.152304 -99.483926)
		(width 0.089408)
		(layer "In11.Cu")
		(net "FM_CPU1_PKGID0")
	)
	(segment
		(start 326.391778 -51.968146)
		(end 340.03615 -51.968146)
		(width 0.089408)
		(layer "In11.Cu")
		(net "FM_CPU1_PKGID0")
	)
	(segment
		(start 52.076096 -94.423738)
		(end 52.310538 -94.189296)
		(width 0.089408)
		(layer "In11.Cu")
		(net "FM_CPU1_PKGID0")
	)
	(segment
		(start 29.299154 -132.01777)
		(end 29.299154 -130.82397)
		(width 0.089408)
		(layer "In11.Cu")
		(net "FM_CPU1_PKGID0")
	)
	(segment
		(start 112.367568 -156.255974)
		(end 31.489142 -156.255974)
		(width 0.089408)
		(layer "In11.Cu")
		(net "FM_CPU1_PKGID0")
	)
	(segment
		(start 48.40097 -98.45548)
		(end 48.40605 -98.46056)
		(width 0.089408)
		(layer "In11.Cu")
		(net "FM_CPU1_PKGID0")
	)
	(segment
		(start 71.452232 -83.42249)
		(end 71.491856 -83.42249)
		(width 0.0889)
		(layer "In11.Cu")
		(net "FM_CPU1_PKGID0")
	)
	(segment
		(start 321.41668 -27.025092)
		(end 322.079874 -27.688286)
		(width 0.089408)
		(layer "In11.Cu")
		(net "FM_CPU1_PKGID0")
	)
	(segment
		(start 72.31761 -82.92719)
		(end 72.350376 -82.92719)
		(width 0.0889)
		(layer "In11.Cu")
		(net "FM_CPU1_PKGID0")
	)
	(segment
		(start 341.084408 -53.871114)
		(end 341.327486 -54.114192)
		(width 0.089408)
		(layer "In11.Cu")
		(net "FM_CPU1_PKGID0")
	)
	(segment
		(start 369.824 -63.155068)
		(end 371.126512 -64.45758)
		(width 0.089408)
		(layer "In11.Cu")
		(net "FM_CPU1_PKGID0")
	)
	(segment
		(start 77.826362 -84.517738)
		(end 77.817472 -84.532978)
		(width 0.0889)
		(layer "In11.Cu")
		(net "FM_CPU1_PKGID0")
	)
	(segment
		(start 317.27394 -34.97961)
		(end 317.115952 -34.97961)
		(width 0.089408)
		(layer "In11.Cu")
		(net "FM_CPU1_PKGID0")
	)
	(segment
		(start 30.116272 -149.566376)
		(end 29.7434 -149.193504)
		(width 0.089408)
		(layer "In11.Cu")
		(net "FM_CPU1_PKGID0")
	)
	(segment
		(start 341.084408 -53.016404)
		(end 341.084408 -53.871114)
		(width 0.089408)
		(layer "In11.Cu")
		(net "FM_CPU1_PKGID0")
	)
	(segment
		(start 36.9062 -107.671616)
		(end 36.9062 -105.504234)
		(width 0.089408)
		(layer "In11.Cu")
		(net "FM_CPU1_PKGID0")
	)
	(segment
		(start 322.079874 -27.688286)
		(end 322.079874 -27.846274)
		(width 0.089408)
		(layer "In11.Cu")
		(net "FM_CPU1_PKGID0")
	)
	(segment
		(start 159.435292 -62.715902)
		(end 160.210754 -61.94044)
		(width 0.089408)
		(layer "In11.Cu")
		(net "FM_CPU1_PKGID0")
	)
	(segment
		(start 356.606348 -52.410868)
		(end 357.37038 -53.1749)
		(width 0.089408)
		(layer "In11.Cu")
		(net "FM_CPU1_PKGID0")
	)
	(segment
		(start 185.760614 -20.090384)
		(end 190.42507 -20.090384)
		(width 0.089408)
		(layer "In11.Cu")
		(net "FM_CPU1_PKGID0")
	)
	(arc
		(start 71.491856 -83.42249)
		(mid 71.775073 -83.338209)
		(end 71.982076 -83.127342)
		(width 0.0889)
		(layer "In11.Cu")
		(net "FM_CPU1_PKGID0")
	)
	(arc
		(start 71.982076 -83.127342)
		(mid 72.123759 -82.983538)
		(end 72.31761 -82.92719)
		(width 0.0889)
		(layer "In11.Cu")
		(net "FM_CPU1_PKGID0")
	)
	(arc
		(start 68.547996 -85.108288)
		(mid 68.688075 -84.965552)
		(end 68.87972 -84.90839)
		(width 0.0889)
		(layer "In11.Cu")
		(net "FM_CPU1_PKGID0")
	)
	(arc
		(start 71.123556 -83.622388)
		(mid 71.2623 -83.480355)
		(end 71.452232 -83.42249)
		(width 0.0889)
		(layer "In11.Cu")
		(net "FM_CPU1_PKGID0")
	)
	(arc
		(start 74.915522 -82.43189)
		(mid 75.109372 -82.48824)
		(end 75.251056 -82.632042)
		(width 0.0889)
		(layer "In11.Cu")
		(net "FM_CPU1_PKGID0")
	)
	(arc
		(start 77.817472 -84.532978)
		(mid 77.747075 -84.821929)
		(end 77.826362 -85.108542)
		(width 0.0889)
		(layer "In11.Cu")
		(net "FM_CPU1_PKGID0")
	)
	(arc
		(start 77.826362 -87.089742)
		(mid 77.879895 -87.28964)
		(end 77.826362 -87.489538)
		(width 0.0889)
		(layer "In11.Cu")
		(net "FM_CPU1_PKGID0")
	)
	(arc
		(start 72.350376 -82.92719)
		(mid 72.633593 -82.842909)
		(end 72.840596 -82.632042)
		(width 0.0889)
		(layer "In11.Cu")
		(net "FM_CPU1_PKGID0")
	)
	(arc
		(start 77.817472 -86.514178)
		(mid 77.747075 -86.803129)
		(end 77.826362 -87.089742)
		(width 0.0889)
		(layer "In11.Cu")
		(net "FM_CPU1_PKGID0")
	)
	(arc
		(start 69.774816 -84.412836)
		(mid 70.058033 -84.328555)
		(end 70.265036 -84.117688)
		(width 0.0889)
		(layer "In11.Cu")
		(net "FM_CPU1_PKGID0")
	)
	(arc
		(start 77.826362 -88.080342)
		(mid 77.879895 -88.28024)
		(end 77.826362 -88.480138)
		(width 0.0889)
		(layer "In11.Cu")
		(net "FM_CPU1_PKGID0")
	)
	(arc
		(start 70.629526 -83.91779)
		(mid 70.91495 -83.834323)
		(end 71.123556 -83.622388)
		(width 0.0889)
		(layer "In11.Cu")
		(net "FM_CPU1_PKGID0")
	)
	(arc
		(start 77.826362 -85.108542)
		(mid 77.879895 -85.30844)
		(end 77.826362 -85.508338)
		(width 0.0889)
		(layer "In11.Cu")
		(net "FM_CPU1_PKGID0")
	)
	(arc
		(start 68.912486 -84.90839)
		(mid 69.19791 -84.824923)
		(end 69.406516 -84.612988)
		(width 0.0889)
		(layer "In11.Cu")
		(net "FM_CPU1_PKGID0")
	)
	(arc
		(start 77.817472 -88.495378)
		(mid 77.747075 -88.784329)
		(end 77.826362 -89.070942)
		(width 0.0889)
		(layer "In11.Cu")
		(net "FM_CPU1_PKGID0")
	)
	(arc
		(start 77.817472 -87.504778)
		(mid 77.747075 -87.793729)
		(end 77.826362 -88.080342)
		(width 0.0889)
		(layer "In11.Cu")
		(net "FM_CPU1_PKGID0")
	)
	(arc
		(start 77.826362 -86.099142)
		(mid 77.879895 -86.29904)
		(end 77.826362 -86.498938)
		(width 0.0889)
		(layer "In11.Cu")
		(net "FM_CPU1_PKGID0")
	)
	(arc
		(start 77.479906 -83.91779)
		(mid 77.826332 -84.117767)
		(end 77.826362 -84.517738)
		(width 0.0889)
		(layer "In11.Cu")
		(net "FM_CPU1_PKGID0")
	)
	(arc
		(start 69.406516 -84.612988)
		(mid 69.548199 -84.469184)
		(end 69.74205 -84.412836)
		(width 0.0889)
		(layer "In11.Cu")
		(net "FM_CPU1_PKGID0")
	)
	(arc
		(start 78.684882 -89.565988)
		(mid 78.873305 -89.765292)
		(end 79.131414 -89.858088)
		(width 0.0889)
		(layer "In11.Cu")
		(net "FM_CPU1_PKGID0")
	)
	(arc
		(start 77.826362 -89.070942)
		(mid 78.031983 -89.280865)
		(end 78.31328 -89.365836)
		(width 0.0889)
		(layer "In11.Cu")
		(net "FM_CPU1_PKGID0")
	)
	(arc
		(start 72.840596 -82.632042)
		(mid 72.982279 -82.488238)
		(end 73.17613 -82.43189)
		(width 0.0889)
		(layer "In11.Cu")
		(net "FM_CPU1_PKGID0")
	)
	(arc
		(start 73.20026 -82.43189)
		(mid 73.488405 -82.349571)
		(end 73.699116 -82.136488)
		(width 0.0889)
		(layer "In11.Cu")
		(net "FM_CPU1_PKGID0")
	)
	(arc
		(start 70.265036 -84.117688)
		(mid 70.405115 -83.974952)
		(end 70.59676 -83.91779)
		(width 0.0889)
		(layer "In11.Cu")
		(net "FM_CPU1_PKGID0")
	)
	(arc
		(start 68.057776 -85.403436)
		(mid 68.340993 -85.319155)
		(end 68.547996 -85.108288)
		(width 0.0889)
		(layer "In11.Cu")
		(net "FM_CPU1_PKGID0")
	)
	(arc
		(start 78.349348 -89.365836)
		(mid 78.543198 -89.422186)
		(end 78.684882 -89.565988)
		(width 0.0889)
		(layer "In11.Cu")
		(net "FM_CPU1_PKGID0")
	)
	(arc
		(start 74.060812 -81.93659)
		(mid 74.252454 -81.993756)
		(end 74.392536 -82.136488)
		(width 0.0889)
		(layer "In11.Cu")
		(net "FM_CPU1_PKGID0")
	)
	(arc
		(start 75.251056 -82.632042)
		(mid 75.45806 -82.842906)
		(end 75.741276 -82.92719)
		(width 0.0889)
		(layer "In11.Cu")
		(net "FM_CPU1_PKGID0")
	)
	(arc
		(start 77.817472 -85.523578)
		(mid 77.747075 -85.812529)
		(end 77.826362 -86.099142)
		(width 0.0889)
		(layer "In11.Cu")
		(net "FM_CPU1_PKGID0")
	)
	(arc
		(start 67.653154 -85.600794)
		(mid 67.744268 -85.483202)
		(end 67.869816 -85.403436)
		(width 0.0889)
		(layer "In11.Cu")
		(net "FM_CPU1_PKGID0")
	)
	(arc
		(start 76.109576 -83.127342)
		(mid 76.31658 -83.338206)
		(end 76.599796 -83.42249)
		(width 0.0889)
		(layer "In11.Cu")
		(net "FM_CPU1_PKGID0")
	)
	(arc
		(start 74.392536 -82.136488)
		(mid 74.603249 -82.349567)
		(end 74.891392 -82.43189)
		(width 0.0889)
		(layer "In11.Cu")
		(net "FM_CPU1_PKGID0")
	)
	(arc
		(start 73.699116 -82.136488)
		(mid 73.839195 -81.993752)
		(end 74.03084 -81.93659)
		(width 0.0889)
		(layer "In11.Cu")
		(net "FM_CPU1_PKGID0")
	)
	(arc
		(start 76.968096 -83.622388)
		(mid 77.176704 -83.83432)
		(end 77.462126 -83.91779)
		(width 0.0889)
		(layer "In11.Cu")
		(net "FM_CPU1_PKGID0")
	)
	(arc
		(start 76.63942 -83.42249)
		(mid 76.829349 -83.48036)
		(end 76.968096 -83.622388)
		(width 0.0889)
		(layer "In11.Cu")
		(net "FM_CPU1_PKGID0")
	)
	(arc
		(start 67.43827 -85.73008)
		(mid 67.56364 -85.695255)
		(end 67.653154 -85.600794)
		(width 0.0889)
		(layer "In11.Cu")
		(net "FM_CPU1_PKGID0")
	)
	(arc
		(start 75.774042 -82.92719)
		(mid 75.967892 -82.98354)
		(end 76.109576 -83.127342)
		(width 0.0889)
		(layer "In11.Cu")
		(net "FM_CPU1_PKGID0")
	)
	(segment
		(start 398.347692 -113.386108)
		(end 398.63395 -113.519204)
		(width 0.10795)
		(layer "F.Cu")
		(net "FM_CPU0_THERMTRIP_LATCH_LVT3_N")
	)
	(segment
		(start 423.984166 -25.775412)
		(end 423.518584 -26.240994)
		(width 0.10795)
		(layer "F.Cu")
		(net "FM_CPU0_THERMTRIP_LATCH_LVT3_N")
	)
	(segment
		(start 426.645578 -24.053038)
		(end 426.71492 -24.12238)
		(width 0.10795)
		(layer "F.Cu")
		(net "FM_CPU0_THERMTRIP_LATCH_LVT3_N")
	)
	(segment
		(start 423.090086 -27.060144)
		(end 423.090086 -27.334718)
		(width 0.10795)
		(layer "F.Cu")
		(net "FM_CPU0_THERMTRIP_LATCH_LVT3_N")
	)
	(segment
		(start 423.518584 -26.631646)
		(end 423.090086 -27.060144)
		(width 0.10795)
		(layer "F.Cu")
		(net "FM_CPU0_THERMTRIP_LATCH_LVT3_N")
	)
	(segment
		(start 426.71492 -24.12238)
		(end 425.061888 -25.775412)
		(width 0.10795)
		(layer "F.Cu")
		(net "FM_CPU0_THERMTRIP_LATCH_LVT3_N")
	)
	(segment
		(start 425.061888 -25.775412)
		(end 423.984166 -25.775412)
		(width 0.10795)
		(layer "F.Cu")
		(net "FM_CPU0_THERMTRIP_LATCH_LVT3_N")
	)
	(segment
		(start 369.545108 -72.695308)
		(end 369.944904 -73.095104)
		(width 0.1016)
		(layer "F.Cu")
		(net "FM_CPU0_THERMTRIP_LATCH_LVT3_N")
	)
	(segment
		(start 423.518584 -26.240994)
		(end 423.518584 -26.631646)
		(width 0.10795)
		(layer "F.Cu")
		(net "FM_CPU0_THERMTRIP_LATCH_LVT3_N")
	)
	(segment
		(start 398.13865 -113.28908)
		(end 398.347692 -113.386108)
		(width 0.10795)
		(layer "F.Cu")
		(net "FM_CPU0_THERMTRIP_LATCH_LVT3_N")
	)
	(segment
		(start 426.103542 -22.08022)
		(end 426.645578 -22.622256)
		(width 0.10795)
		(layer "F.Cu")
		(net "FM_CPU0_THERMTRIP_LATCH_LVT3_N")
	)
	(segment
		(start 426.645578 -22.622256)
		(end 426.645578 -24.053038)
		(width 0.10795)
		(layer "F.Cu")
		(net "FM_CPU0_THERMTRIP_LATCH_LVT3_N")
	)
	(via
		(at 369.545108 -72.695308)
		(size 0.4572)
		(drill 0.2032)
		(layers "F.Cu" "B.Cu")
		(net "FM_CPU0_THERMTRIP_LATCH_LVT3_N")
	)
	(via
		(at 396.1892 -72.4662)
		(size 0.508)
		(drill 0.254)
		(layers "F.Cu" "B.Cu")
		(net "FM_CPU0_THERMTRIP_LATCH_LVT3_N")
	)
	(via
		(at 398.63395 -113.519204)
		(size 0.508)
		(drill 0.254)
		(layers "F.Cu" "B.Cu")
		(net "FM_CPU0_THERMTRIP_LATCH_LVT3_N")
	)
	(via
		(at 426.103542 -22.08022)
		(size 0.508)
		(drill 0.254)
		(layers "F.Cu" "B.Cu")
		(net "FM_CPU0_THERMTRIP_LATCH_LVT3_N")
	)
	(via
		(at 426.71492 -24.12238)
		(size 0.762)
		(drill 0.381)
		(layers "F.Cu" "B.Cu")
		(net "FM_CPU0_THERMTRIP_LATCH_LVT3_N")
	)
	(segment
		(start 425.982892 -22.08022)
		(end 425.227242 -22.83587)
		(width 0.089408)
		(layer "In2.Cu")
		(net "FM_CPU0_THERMTRIP_LATCH_LVT3_N")
	)
	(segment
		(start 386.2324 -29.013912)
		(end 386.2324 -31.5214)
		(width 0.089408)
		(layer "In2.Cu")
		(net "FM_CPU0_THERMTRIP_LATCH_LVT3_N")
	)
	(segment
		(start 381.066294 -57.243472)
		(end 380.0221 -58.287666)
		(width 0.089408)
		(layer "In2.Cu")
		(net "FM_CPU0_THERMTRIP_LATCH_LVT3_N")
	)
	(segment
		(start 380.357888 -50.95367)
		(end 380.897638 -51.49342)
		(width 0.089408)
		(layer "In2.Cu")
		(net "FM_CPU0_THERMTRIP_LATCH_LVT3_N")
	)
	(segment
		(start 426.103542 -22.08022)
		(end 425.982892 -22.08022)
		(width 0.089408)
		(layer "In2.Cu")
		(net "FM_CPU0_THERMTRIP_LATCH_LVT3_N")
	)
	(segment
		(start 371.393466 -69.05498)
		(end 371.057424 -69.05498)
		(width 0.089408)
		(layer "In2.Cu")
		(net "FM_CPU0_THERMTRIP_LATCH_LVT3_N")
	)
	(segment
		(start 406.925526 -26.556462)
		(end 406.603962 -26.878026)
		(width 0.089408)
		(layer "In2.Cu")
		(net "FM_CPU0_THERMTRIP_LATCH_LVT3_N")
	)
	(segment
		(start 389.124952 -27.901392)
		(end 388.476236 -28.550108)
		(width 0.089408)
		(layer "In2.Cu")
		(net "FM_CPU0_THERMTRIP_LATCH_LVT3_N")
	)
	(segment
		(start 382.786636 -42.122344)
		(end 382.651 -42.25798)
		(width 0.089408)
		(layer "In2.Cu")
		(net "FM_CPU0_THERMTRIP_LATCH_LVT3_N")
	)
	(segment
		(start 380.897892 -55.047388)
		(end 380.897892 -56.743346)
		(width 0.089408)
		(layer "In2.Cu")
		(net "FM_CPU0_THERMTRIP_LATCH_LVT3_N")
	)
	(segment
		(start 409.480004 -26.147014)
		(end 409.070556 -26.556462)
		(width 0.089408)
		(layer "In2.Cu")
		(net "FM_CPU0_THERMTRIP_LATCH_LVT3_N")
	)
	(segment
		(start 421.273732 -23.683214)
		(end 420.3827 -24.574246)
		(width 0.089408)
		(layer "In2.Cu")
		(net "FM_CPU0_THERMTRIP_LATCH_LVT3_N")
	)
	(segment
		(start 425.227242 -22.83587)
		(end 423.800778 -22.83587)
		(width 0.089408)
		(layer "In2.Cu")
		(net "FM_CPU0_THERMTRIP_LATCH_LVT3_N")
	)
	(segment
		(start 380.897638 -55.047134)
		(end 380.897892 -55.047388)
		(width 0.089408)
		(layer "In2.Cu")
		(net "FM_CPU0_THERMTRIP_LATCH_LVT3_N")
	)
	(segment
		(start 382.651 -44.5135)
		(end 380.357634 -46.806866)
		(width 0.089408)
		(layer "In2.Cu")
		(net "FM_CPU0_THERMTRIP_LATCH_LVT3_N")
	)
	(segment
		(start 421.893492 -23.930864)
		(end 421.645842 -23.683214)
		(width 0.089408)
		(layer "In2.Cu")
		(net "FM_CPU0_THERMTRIP_LATCH_LVT3_N")
	)
	(segment
		(start 396.597886 -27.65552)
		(end 392.040618 -27.65552)
		(width 0.089408)
		(layer "In2.Cu")
		(net "FM_CPU0_THERMTRIP_LATCH_LVT3_N")
	)
	(segment
		(start 386.5372 -31.8262)
		(end 386.5372 -33.02889)
		(width 0.089408)
		(layer "In2.Cu")
		(net "FM_CPU0_THERMTRIP_LATCH_LVT3_N")
	)
	(segment
		(start 380.357634 -46.964854)
		(end 380.357888 -46.965108)
		(width 0.089408)
		(layer "In2.Cu")
		(net "FM_CPU0_THERMTRIP_LATCH_LVT3_N")
	)
	(segment
		(start 378.34951 -64.985392)
		(end 378.34951 -66.178938)
		(width 0.089408)
		(layer "In2.Cu")
		(net "FM_CPU0_THERMTRIP_LATCH_LVT3_N")
	)
	(segment
		(start 369.951 -72.289416)
		(end 369.545108 -72.695308)
		(width 0.089408)
		(layer "In2.Cu")
		(net "FM_CPU0_THERMTRIP_LATCH_LVT3_N")
	)
	(segment
		(start 377.28525 -67.243198)
		(end 373.205248 -67.243198)
		(width 0.089408)
		(layer "In2.Cu")
		(net "FM_CPU0_THERMTRIP_LATCH_LVT3_N")
	)
	(segment
		(start 370.243354 -71.468488)
		(end 369.951 -71.760842)
		(width 0.089408)
		(layer "In2.Cu")
		(net "FM_CPU0_THERMTRIP_LATCH_LVT3_N")
	)
	(segment
		(start 417.982654 -24.574246)
		(end 416.811206 -25.745694)
		(width 0.089408)
		(layer "In2.Cu")
		(net "FM_CPU0_THERMTRIP_LATCH_LVT3_N")
	)
	(segment
		(start 370.7638 -69.348604)
		(end 370.7638 -71.204582)
		(width 0.089408)
		(layer "In2.Cu")
		(net "FM_CPU0_THERMTRIP_LATCH_LVT3_N")
	)
	(segment
		(start 404.577296 -26.592022)
		(end 403.644862 -27.524456)
		(width 0.089408)
		(layer "In2.Cu")
		(net "FM_CPU0_THERMTRIP_LATCH_LVT3_N")
	)
	(segment
		(start 370.499894 -71.468488)
		(end 370.243354 -71.468488)
		(width 0.089408)
		(layer "In2.Cu")
		(net "FM_CPU0_THERMTRIP_LATCH_LVT3_N")
	)
	(segment
		(start 391.794746 -27.901392)
		(end 389.124952 -27.901392)
		(width 0.089408)
		(layer "In2.Cu")
		(net "FM_CPU0_THERMTRIP_LATCH_LVT3_N")
	)
	(segment
		(start 387.002274 -28.244038)
		(end 386.2324 -29.013912)
		(width 0.089408)
		(layer "In2.Cu")
		(net "FM_CPU0_THERMTRIP_LATCH_LVT3_N")
	)
	(segment
		(start 388.476236 -28.550108)
		(end 387.776974 -28.550108)
		(width 0.089408)
		(layer "In2.Cu")
		(net "FM_CPU0_THERMTRIP_LATCH_LVT3_N")
	)
	(segment
		(start 421.645842 -23.683214)
		(end 421.273732 -23.683214)
		(width 0.089408)
		(layer "In2.Cu")
		(net "FM_CPU0_THERMTRIP_LATCH_LVT3_N")
	)
	(segment
		(start 413.37611 -25.745694)
		(end 412.97479 -26.147014)
		(width 0.089408)
		(layer "In2.Cu")
		(net "FM_CPU0_THERMTRIP_LATCH_LVT3_N")
	)
	(segment
		(start 405.885396 -26.592022)
		(end 404.577296 -26.592022)
		(width 0.089408)
		(layer "In2.Cu")
		(net "FM_CPU0_THERMTRIP_LATCH_LVT3_N")
	)
	(segment
		(start 403.644862 -27.524456)
		(end 402.622512 -27.524456)
		(width 0.089408)
		(layer "In2.Cu")
		(net "FM_CPU0_THERMTRIP_LATCH_LVT3_N")
	)
	(segment
		(start 369.951 -71.760842)
		(end 369.951 -72.289416)
		(width 0.089408)
		(layer "In2.Cu")
		(net "FM_CPU0_THERMTRIP_LATCH_LVT3_N")
	)
	(segment
		(start 387.776974 -28.550108)
		(end 387.470904 -28.244038)
		(width 0.089408)
		(layer "In2.Cu")
		(net "FM_CPU0_THERMTRIP_LATCH_LVT3_N")
	)
	(segment
		(start 412.97479 -26.147014)
		(end 409.480004 -26.147014)
		(width 0.089408)
		(layer "In2.Cu")
		(net "FM_CPU0_THERMTRIP_LATCH_LVT3_N")
	)
	(segment
		(start 380.897638 -51.49342)
		(end 380.897638 -55.047134)
		(width 0.089408)
		(layer "In2.Cu")
		(net "FM_CPU0_THERMTRIP_LATCH_LVT3_N")
	)
	(segment
		(start 420.3827 -24.574246)
		(end 417.982654 -24.574246)
		(width 0.089408)
		(layer "In2.Cu")
		(net "FM_CPU0_THERMTRIP_LATCH_LVT3_N")
	)
	(segment
		(start 380.0221 -58.287666)
		(end 380.0221 -63.312802)
		(width 0.089408)
		(layer "In2.Cu")
		(net "FM_CPU0_THERMTRIP_LATCH_LVT3_N")
	)
	(segment
		(start 385.592828 -35.621976)
		(end 382.479296 -38.735508)
		(width 0.089408)
		(layer "In2.Cu")
		(net "FM_CPU0_THERMTRIP_LATCH_LVT3_N")
	)
	(segment
		(start 380.897892 -56.743346)
		(end 381.066294 -56.911748)
		(width 0.089408)
		(layer "In2.Cu")
		(net "FM_CPU0_THERMTRIP_LATCH_LVT3_N")
	)
	(segment
		(start 371.057424 -69.05498)
		(end 370.7638 -69.348604)
		(width 0.089408)
		(layer "In2.Cu")
		(net "FM_CPU0_THERMTRIP_LATCH_LVT3_N")
	)
	(segment
		(start 392.040618 -27.65552)
		(end 391.794746 -27.901392)
		(width 0.089408)
		(layer "In2.Cu")
		(net "FM_CPU0_THERMTRIP_LATCH_LVT3_N")
	)
	(segment
		(start 397.011398 -27.242008)
		(end 396.597886 -27.65552)
		(width 0.089408)
		(layer "In2.Cu")
		(net "FM_CPU0_THERMTRIP_LATCH_LVT3_N")
	)
	(segment
		(start 378.34951 -66.178938)
		(end 377.28525 -67.243198)
		(width 0.089408)
		(layer "In2.Cu")
		(net "FM_CPU0_THERMTRIP_LATCH_LVT3_N")
	)
	(segment
		(start 382.479296 -38.735508)
		(end 382.479296 -40.924226)
		(width 0.089408)
		(layer "In2.Cu")
		(net "FM_CPU0_THERMTRIP_LATCH_LVT3_N")
	)
	(segment
		(start 422.705784 -23.930864)
		(end 421.893492 -23.930864)
		(width 0.089408)
		(layer "In2.Cu")
		(net "FM_CPU0_THERMTRIP_LATCH_LVT3_N")
	)
	(segment
		(start 416.811206 -25.745694)
		(end 413.37611 -25.745694)
		(width 0.089408)
		(layer "In2.Cu")
		(net "FM_CPU0_THERMTRIP_LATCH_LVT3_N")
	)
	(segment
		(start 381.066294 -56.911748)
		(end 381.066294 -57.243472)
		(width 0.089408)
		(layer "In2.Cu")
		(net "FM_CPU0_THERMTRIP_LATCH_LVT3_N")
	)
	(segment
		(start 380.0221 -63.312802)
		(end 378.34951 -64.985392)
		(width 0.089408)
		(layer "In2.Cu")
		(net "FM_CPU0_THERMTRIP_LATCH_LVT3_N")
	)
	(segment
		(start 406.1714 -26.878026)
		(end 405.885396 -26.592022)
		(width 0.089408)
		(layer "In2.Cu")
		(net "FM_CPU0_THERMTRIP_LATCH_LVT3_N")
	)
	(segment
		(start 382.479296 -40.924226)
		(end 382.786636 -41.231566)
		(width 0.089408)
		(layer "In2.Cu")
		(net "FM_CPU0_THERMTRIP_LATCH_LVT3_N")
	)
	(segment
		(start 386.5372 -33.02889)
		(end 385.592828 -33.973262)
		(width 0.089408)
		(layer "In2.Cu")
		(net "FM_CPU0_THERMTRIP_LATCH_LVT3_N")
	)
	(segment
		(start 406.603962 -26.878026)
		(end 406.1714 -26.878026)
		(width 0.089408)
		(layer "In2.Cu")
		(net "FM_CPU0_THERMTRIP_LATCH_LVT3_N")
	)
	(segment
		(start 386.2324 -31.5214)
		(end 386.5372 -31.8262)
		(width 0.089408)
		(layer "In2.Cu")
		(net "FM_CPU0_THERMTRIP_LATCH_LVT3_N")
	)
	(segment
		(start 382.786636 -41.231566)
		(end 382.786636 -42.122344)
		(width 0.089408)
		(layer "In2.Cu")
		(net "FM_CPU0_THERMTRIP_LATCH_LVT3_N")
	)
	(segment
		(start 387.470904 -28.244038)
		(end 387.002274 -28.244038)
		(width 0.089408)
		(layer "In2.Cu")
		(net "FM_CPU0_THERMTRIP_LATCH_LVT3_N")
	)
	(segment
		(start 385.592828 -33.973262)
		(end 385.592828 -35.621976)
		(width 0.089408)
		(layer "In2.Cu")
		(net "FM_CPU0_THERMTRIP_LATCH_LVT3_N")
	)
	(segment
		(start 370.7638 -71.204582)
		(end 370.499894 -71.468488)
		(width 0.089408)
		(layer "In2.Cu")
		(net "FM_CPU0_THERMTRIP_LATCH_LVT3_N")
	)
	(segment
		(start 409.070556 -26.556462)
		(end 406.925526 -26.556462)
		(width 0.089408)
		(layer "In2.Cu")
		(net "FM_CPU0_THERMTRIP_LATCH_LVT3_N")
	)
	(segment
		(start 402.340064 -27.242008)
		(end 397.011398 -27.242008)
		(width 0.089408)
		(layer "In2.Cu")
		(net "FM_CPU0_THERMTRIP_LATCH_LVT3_N")
	)
	(segment
		(start 380.357888 -46.965108)
		(end 380.357888 -50.95367)
		(width 0.089408)
		(layer "In2.Cu")
		(net "FM_CPU0_THERMTRIP_LATCH_LVT3_N")
	)
	(segment
		(start 423.800778 -22.83587)
		(end 422.705784 -23.930864)
		(width 0.089408)
		(layer "In2.Cu")
		(net "FM_CPU0_THERMTRIP_LATCH_LVT3_N")
	)
	(segment
		(start 402.622512 -27.524456)
		(end 402.340064 -27.242008)
		(width 0.089408)
		(layer "In2.Cu")
		(net "FM_CPU0_THERMTRIP_LATCH_LVT3_N")
	)
	(segment
		(start 373.205248 -67.243198)
		(end 371.393466 -69.05498)
		(width 0.089408)
		(layer "In2.Cu")
		(net "FM_CPU0_THERMTRIP_LATCH_LVT3_N")
	)
	(segment
		(start 380.357634 -46.806866)
		(end 380.357634 -46.964854)
		(width 0.089408)
		(layer "In2.Cu")
		(net "FM_CPU0_THERMTRIP_LATCH_LVT3_N")
	)
	(segment
		(start 382.651 -42.25798)
		(end 382.651 -44.5135)
		(width 0.089408)
		(layer "In2.Cu")
		(net "FM_CPU0_THERMTRIP_LATCH_LVT3_N")
	)
	(segment
		(start 395.950186 -72.705214)
		(end 394.37945 -72.705214)
		(width 0.089408)
		(layer "In4.Cu")
		(net "FM_CPU0_THERMTRIP_LATCH_LVT3_N")
	)
	(segment
		(start 375.571512 -71.996554)
		(end 375.299732 -72.268334)
		(width 0.089408)
		(layer "In4.Cu")
		(net "FM_CPU0_THERMTRIP_LATCH_LVT3_N")
	)
	(segment
		(start 375.299732 -72.268334)
		(end 375.0437 -72.268334)
		(width 0.089408)
		(layer "In4.Cu")
		(net "FM_CPU0_THERMTRIP_LATCH_LVT3_N")
	)
	(segment
		(start 375.0437 -72.268334)
		(end 374.734582 -72.577452)
		(width 0.089408)
		(layer "In4.Cu")
		(net "FM_CPU0_THERMTRIP_LATCH_LVT3_N")
	)
	(segment
		(start 377.80976 -71.521828)
		(end 375.790206 -71.521828)
		(width 0.089408)
		(layer "In4.Cu")
		(net "FM_CPU0_THERMTRIP_LATCH_LVT3_N")
	)
	(segment
		(start 394.37945 -72.705214)
		(end 393.649454 -71.975218)
		(width 0.089408)
		(layer "In4.Cu")
		(net "FM_CPU0_THERMTRIP_LATCH_LVT3_N")
	)
	(segment
		(start 375.571512 -71.740522)
		(end 375.571512 -71.996554)
		(width 0.089408)
		(layer "In4.Cu")
		(net "FM_CPU0_THERMTRIP_LATCH_LVT3_N")
	)
	(segment
		(start 393.649454 -71.975218)
		(end 380.982474 -71.975218)
		(width 0.089408)
		(layer "In4.Cu")
		(net "FM_CPU0_THERMTRIP_LATCH_LVT3_N")
	)
	(segment
		(start 375.790206 -71.521828)
		(end 375.571512 -71.740522)
		(width 0.089408)
		(layer "In4.Cu")
		(net "FM_CPU0_THERMTRIP_LATCH_LVT3_N")
	)
	(segment
		(start 374.499378 -73.068688)
		(end 370.121688 -73.068688)
		(width 0.089408)
		(layer "In4.Cu")
		(net "FM_CPU0_THERMTRIP_LATCH_LVT3_N")
	)
	(segment
		(start 374.734582 -72.833484)
		(end 374.499378 -73.068688)
		(width 0.089408)
		(layer "In4.Cu")
		(net "FM_CPU0_THERMTRIP_LATCH_LVT3_N")
	)
	(segment
		(start 396.1892 -72.4662)
		(end 395.950186 -72.705214)
		(width 0.089408)
		(layer "In4.Cu")
		(net "FM_CPU0_THERMTRIP_LATCH_LVT3_N")
	)
	(segment
		(start 370.121688 -73.068688)
		(end 369.748308 -72.695308)
		(width 0.089408)
		(layer "In4.Cu")
		(net "FM_CPU0_THERMTRIP_LATCH_LVT3_N")
	)
	(segment
		(start 380.873 -72.084692)
		(end 378.372624 -72.084692)
		(width 0.089408)
		(layer "In4.Cu")
		(net "FM_CPU0_THERMTRIP_LATCH_LVT3_N")
	)
	(segment
		(start 369.748308 -72.695308)
		(end 369.545108 -72.695308)
		(width 0.089408)
		(layer "In4.Cu")
		(net "FM_CPU0_THERMTRIP_LATCH_LVT3_N")
	)
	(segment
		(start 380.982474 -71.975218)
		(end 380.873 -72.084692)
		(width 0.089408)
		(layer "In4.Cu")
		(net "FM_CPU0_THERMTRIP_LATCH_LVT3_N")
	)
	(segment
		(start 378.372624 -72.084692)
		(end 377.80976 -71.521828)
		(width 0.089408)
		(layer "In4.Cu")
		(net "FM_CPU0_THERMTRIP_LATCH_LVT3_N")
	)
	(segment
		(start 374.734582 -72.577452)
		(end 374.734582 -72.833484)
		(width 0.089408)
		(layer "In4.Cu")
		(net "FM_CPU0_THERMTRIP_LATCH_LVT3_N")
	)
	(segment
		(start 396.601696 -84.867242)
		(end 396.601696 -86.992206)
		(width 0.089408)
		(layer "In11.Cu")
		(net "FM_CPU0_THERMTRIP_LATCH_LVT3_N")
	)
	(segment
		(start 396.578074 -81.219294)
		(end 396.741904 -81.383124)
		(width 0.089408)
		(layer "In11.Cu")
		(net "FM_CPU0_THERMTRIP_LATCH_LVT3_N")
	)
	(segment
		(start 397.014954 -93.103954)
		(end 397.954246 -94.043246)
		(width 0.089408)
		(layer "In11.Cu")
		(net "FM_CPU0_THERMTRIP_LATCH_LVT3_N")
	)
	(segment
		(start 395.712696 -76.956412)
		(end 396.741904 -77.98562)
		(width 0.089408)
		(layer "In11.Cu")
		(net "FM_CPU0_THERMTRIP_LATCH_LVT3_N")
	)
	(segment
		(start 400.322288 -96.28632)
		(end 400.322288 -111.545624)
		(width 0.089408)
		(layer "In11.Cu")
		(net "FM_CPU0_THERMTRIP_LATCH_LVT3_N")
	)
	(segment
		(start 396.1892 -72.4662)
		(end 395.712696 -72.942704)
		(width 0.089408)
		(layer "In11.Cu")
		(net "FM_CPU0_THERMTRIP_LATCH_LVT3_N")
	)
	(segment
		(start 397.954246 -94.043246)
		(end 398.079214 -94.043246)
		(width 0.089408)
		(layer "In11.Cu")
		(net "FM_CPU0_THERMTRIP_LATCH_LVT3_N")
	)
	(segment
		(start 400.322288 -111.545624)
		(end 399.7706 -112.097312)
		(width 0.089408)
		(layer "In11.Cu")
		(net "FM_CPU0_THERMTRIP_LATCH_LVT3_N")
	)
	(segment
		(start 398.079214 -94.043246)
		(end 400.322288 -96.28632)
		(width 0.089408)
		(layer "In11.Cu")
		(net "FM_CPU0_THERMTRIP_LATCH_LVT3_N")
	)
	(segment
		(start 396.741904 -79.549244)
		(end 396.578074 -79.713074)
		(width 0.089408)
		(layer "In11.Cu")
		(net "FM_CPU0_THERMTRIP_LATCH_LVT3_N")
	)
	(segment
		(start 399.7706 -112.097312)
		(end 399.7706 -112.583468)
		(width 0.089408)
		(layer "In11.Cu")
		(net "FM_CPU0_THERMTRIP_LATCH_LVT3_N")
	)
	(segment
		(start 398.93494 -113.218214)
		(end 398.63395 -113.519204)
		(width 0.089408)
		(layer "In11.Cu")
		(net "FM_CPU0_THERMTRIP_LATCH_LVT3_N")
	)
	(segment
		(start 397.543274 -87.933784)
		(end 397.543274 -90.154506)
		(width 0.089408)
		(layer "In11.Cu")
		(net "FM_CPU0_THERMTRIP_LATCH_LVT3_N")
	)
	(segment
		(start 395.712696 -72.942704)
		(end 395.712696 -76.956412)
		(width 0.089408)
		(layer "In11.Cu")
		(net "FM_CPU0_THERMTRIP_LATCH_LVT3_N")
	)
	(segment
		(start 396.578074 -79.713074)
		(end 396.578074 -81.219294)
		(width 0.089408)
		(layer "In11.Cu")
		(net "FM_CPU0_THERMTRIP_LATCH_LVT3_N")
	)
	(segment
		(start 396.741904 -84.727034)
		(end 396.601696 -84.867242)
		(width 0.089408)
		(layer "In11.Cu")
		(net "FM_CPU0_THERMTRIP_LATCH_LVT3_N")
	)
	(segment
		(start 396.741904 -81.383124)
		(end 396.741904 -84.727034)
		(width 0.089408)
		(layer "In11.Cu")
		(net "FM_CPU0_THERMTRIP_LATCH_LVT3_N")
	)
	(segment
		(start 396.741904 -77.98562)
		(end 396.741904 -79.549244)
		(width 0.089408)
		(layer "In11.Cu")
		(net "FM_CPU0_THERMTRIP_LATCH_LVT3_N")
	)
	(segment
		(start 397.014954 -90.682826)
		(end 397.014954 -93.103954)
		(width 0.089408)
		(layer "In11.Cu")
		(net "FM_CPU0_THERMTRIP_LATCH_LVT3_N")
	)
	(segment
		(start 397.543274 -90.154506)
		(end 397.014954 -90.682826)
		(width 0.089408)
		(layer "In11.Cu")
		(net "FM_CPU0_THERMTRIP_LATCH_LVT3_N")
	)
	(segment
		(start 399.7706 -112.583468)
		(end 399.135854 -113.218214)
		(width 0.089408)
		(layer "In11.Cu")
		(net "FM_CPU0_THERMTRIP_LATCH_LVT3_N")
	)
	(segment
		(start 396.601696 -86.992206)
		(end 397.543274 -87.933784)
		(width 0.089408)
		(layer "In11.Cu")
		(net "FM_CPU0_THERMTRIP_LATCH_LVT3_N")
	)
	(segment
		(start 399.135854 -113.218214)
		(end 398.93494 -113.218214)
		(width 0.089408)
		(layer "In11.Cu")
		(net "FM_CPU0_THERMTRIP_LATCH_LVT3_N")
	)
	(segment
		(start 244.768624 -89.27084)
		(end 244.197124 -89.27084)
		(width 0.10795)
		(layer "F.Cu")
		(net "FM_CPU0_PKGID2")
	)
	(segment
		(start 378.344684 -72.695308)
		(end 377.944888 -73.095104)
		(width 0.1016)
		(layer "F.Cu")
		(net "FM_CPU0_PKGID2")
	)
	(via
		(at 378.344684 -72.695308)
		(size 0.4572)
		(drill 0.2032)
		(layers "F.Cu" "B.Cu")
		(net "FM_CPU0_PKGID2")
	)
	(via
		(at 229.5144 -91.821)
		(size 0.6604)
		(drill 0.3302)
		(layers "F.Cu" "B.Cu")
		(net "FM_CPU0_PKGID2")
	)
	(via
		(at 244.197124 -89.27084)
		(size 0.508)
		(drill 0.254)
		(layers "F.Cu" "B.Cu")
		(net "FM_CPU0_PKGID2")
	)
	(via
		(at 332.755494 -41.96969)
		(size 0.508)
		(drill 0.254)
		(layers "F.Cu" "B.Cu")
		(net "FM_CPU0_PKGID2")
	)
	(segment
		(start 235.819696 -89.78138)
		(end 235.413296 -89.78138)
		(width 0.0889)
		(layer "B.Cu")
		(net "FM_CPU0_PKGID2")
	)
	(segment
		(start 235.413296 -89.78138)
		(end 234.909106 -90.28557)
		(width 0.0889)
		(layer "B.Cu")
		(net "FM_CPU0_PKGID2")
	)
	(segment
		(start 232.864406 -90.752422)
		(end 231.840278 -90.752422)
		(width 0.1016)
		(layer "B.Cu")
		(net "FM_CPU0_PKGID2")
	)
	(segment
		(start 240.172494 -90.198448)
		(end 239.678972 -90.198448)
		(width 0.0889)
		(layer "B.Cu")
		(net "FM_CPU0_PKGID2")
	)
	(segment
		(start 240.562638 -89.808304)
		(end 240.172494 -90.198448)
		(width 0.0889)
		(layer "B.Cu")
		(net "FM_CPU0_PKGID2")
	)
	(segment
		(start 240.969038 -89.808304)
		(end 240.562638 -89.808304)
		(width 0.0889)
		(layer "B.Cu")
		(net "FM_CPU0_PKGID2")
	)
	(segment
		(start 241.42446 -90.263726)
		(end 240.969038 -89.808304)
		(width 0.0889)
		(layer "B.Cu")
		(net "FM_CPU0_PKGID2")
	)
	(segment
		(start 237.98784 -90.225372)
		(end 237.518448 -89.75598)
		(width 0.0889)
		(layer "B.Cu")
		(net "FM_CPU0_PKGID2")
	)
	(segment
		(start 243.202714 -89.27084)
		(end 242.719606 -89.753948)
		(width 0.0889)
		(layer "B.Cu")
		(net "FM_CPU0_PKGID2")
	)
	(segment
		(start 236.296708 -90.258392)
		(end 235.819696 -89.78138)
		(width 0.0889)
		(layer "B.Cu")
		(net "FM_CPU0_PKGID2")
	)
	(segment
		(start 234.117134 -90.752422)
		(end 232.864406 -90.752422)
		(width 0.0889)
		(layer "B.Cu")
		(net "FM_CPU0_PKGID2")
	)
	(segment
		(start 241.848132 -90.263726)
		(end 241.42446 -90.263726)
		(width 0.0889)
		(layer "B.Cu")
		(net "FM_CPU0_PKGID2")
	)
	(segment
		(start 238.844328 -89.780872)
		(end 238.399828 -90.225372)
		(width 0.0889)
		(layer "B.Cu")
		(net "FM_CPU0_PKGID2")
	)
	(segment
		(start 244.197124 -89.27084)
		(end 243.202714 -89.27084)
		(width 0.0889)
		(layer "B.Cu")
		(net "FM_CPU0_PKGID2")
	)
	(segment
		(start 231.840278 -90.752422)
		(end 230.7717 -91.821)
		(width 0.1016)
		(layer "B.Cu")
		(net "FM_CPU0_PKGID2")
	)
	(segment
		(start 237.081568 -89.75598)
		(end 236.579156 -90.258392)
		(width 0.0889)
		(layer "B.Cu")
		(net "FM_CPU0_PKGID2")
	)
	(segment
		(start 234.909106 -90.28557)
		(end 234.583986 -90.28557)
		(width 0.0889)
		(layer "B.Cu")
		(net "FM_CPU0_PKGID2")
	)
	(segment
		(start 234.583986 -90.28557)
		(end 234.117134 -90.752422)
		(width 0.0889)
		(layer "B.Cu")
		(net "FM_CPU0_PKGID2")
	)
	(segment
		(start 236.579156 -90.258392)
		(end 236.296708 -90.258392)
		(width 0.0889)
		(layer "B.Cu")
		(net "FM_CPU0_PKGID2")
	)
	(segment
		(start 242.719606 -89.753948)
		(end 242.35791 -89.753948)
		(width 0.0889)
		(layer "B.Cu")
		(net "FM_CPU0_PKGID2")
	)
	(segment
		(start 242.35791 -89.753948)
		(end 241.848132 -90.263726)
		(width 0.0889)
		(layer "B.Cu")
		(net "FM_CPU0_PKGID2")
	)
	(segment
		(start 239.678972 -90.198448)
		(end 239.261396 -89.780872)
		(width 0.0889)
		(layer "B.Cu")
		(net "FM_CPU0_PKGID2")
	)
	(segment
		(start 230.7717 -91.821)
		(end 229.5144 -91.821)
		(width 0.1016)
		(layer "B.Cu")
		(net "FM_CPU0_PKGID2")
	)
	(segment
		(start 239.261396 -89.780872)
		(end 238.844328 -89.780872)
		(width 0.0889)
		(layer "B.Cu")
		(net "FM_CPU0_PKGID2")
	)
	(segment
		(start 237.518448 -89.75598)
		(end 237.081568 -89.75598)
		(width 0.0889)
		(layer "B.Cu")
		(net "FM_CPU0_PKGID2")
	)
	(segment
		(start 229.5144 -91.821)
		(end 228.473 -91.821)
		(width 0.1016)
		(layer "B.Cu")
		(net "FM_CPU0_PKGID2")
	)
	(segment
		(start 238.399828 -90.225372)
		(end 237.98784 -90.225372)
		(width 0.0889)
		(layer "B.Cu")
		(net "FM_CPU0_PKGID2")
	)
	(segment
		(start 314.857638 -62.788038)
		(end 314.857638 -65.98539)
		(width 0.089408)
		(layer "In2.Cu")
		(net "FM_CPU0_PKGID2")
	)
	(segment
		(start 248.022618 -86.697566)
		(end 247.23979 -86.697566)
		(width 0.0889)
		(layer "In2.Cu")
		(net "FM_CPU0_PKGID2")
	)
	(segment
		(start 265.677396 -89.175336)
		(end 265.641836 -89.175336)
		(width 0.0889)
		(layer "In2.Cu")
		(net "FM_CPU0_PKGID2")
	)
	(segment
		(start 294.284654 -75.317858)
		(end 293.899082 -75.317858)
		(width 0.0889)
		(layer "In2.Cu")
		(net "FM_CPU0_PKGID2")
	)
	(segment
		(start 249.183144 -86.697566)
		(end 248.881138 -86.39556)
		(width 0.0889)
		(layer "In2.Cu")
		(net "FM_CPU0_PKGID2")
	)
	(segment
		(start 287.233106 -80.078834)
		(end 287.20034 -80.078834)
		(width 0.0889)
		(layer "In2.Cu")
		(net "FM_CPU0_PKGID2")
	)
	(segment
		(start 332.704694 -44.940982)
		(end 314.857638 -62.788038)
		(width 0.089408)
		(layer "In2.Cu")
		(net "FM_CPU0_PKGID2")
	)
	(segment
		(start 289.098736 -76.116434)
		(end 288.91738 -76.116434)
		(width 0.0889)
		(layer "In2.Cu")
		(net "FM_CPU0_PKGID2")
	)
	(segment
		(start 298.627038 -73.831958)
		(end 298.213272 -73.831958)
		(width 0.0889)
		(layer "In2.Cu")
		(net "FM_CPU0_PKGID2")
	)
	(segment
		(start 332.704694 -42.02049)
		(end 332.704694 -44.940982)
		(width 0.089408)
		(layer "In2.Cu")
		(net "FM_CPU0_PKGID2")
	)
	(segment
		(start 285.21914 -81.460594)
		(end 285.21914 -81.745582)
		(width 0.0889)
		(layer "In2.Cu")
		(net "FM_CPU0_PKGID2")
	)
	(segment
		(start 293.403528 -75.813412)
		(end 292.956488 -75.813412)
		(width 0.0889)
		(layer "In2.Cu")
		(net "FM_CPU0_PKGID2")
	)
	(segment
		(start 255.37541 -87.194136)
		(end 255.342644 -87.194136)
		(width 0.0889)
		(layer "In2.Cu")
		(net "FM_CPU0_PKGID2")
	)
	(segment
		(start 272.782538 -89.470738)
		(end 271.131792 -89.470738)
		(width 0.0889)
		(layer "In2.Cu")
		(net "FM_CPU0_PKGID2")
	)
	(segment
		(start 290.29025 -76.11491)
		(end 289.988752 -75.813412)
		(width 0.0889)
		(layer "In2.Cu")
		(net "FM_CPU0_PKGID2")
	)
	(segment
		(start 303.547526 -71.849488)
		(end 303.51476 -71.849488)
		(width 0.0889)
		(layer "In2.Cu")
		(net "FM_CPU0_PKGID2")
	)
	(segment
		(start 250.900184 -86.697566)
		(end 250.598178 -86.39556)
		(width 0.0889)
		(layer "In2.Cu")
		(net "FM_CPU0_PKGID2")
	)
	(segment
		(start 305.261772 -71.849488)
		(end 305.229006 -71.849488)
		(width 0.0889)
		(layer "In2.Cu")
		(net "FM_CPU0_PKGID2")
	)
	(segment
		(start 254.000762 -86.39556)
		(end 253.475744 -86.39556)
		(width 0.0889)
		(layer "In2.Cu")
		(net "FM_CPU0_PKGID2")
	)
	(segment
		(start 288.087816 -76.611988)
		(end 288.05505 -76.611988)
		(width 0.0889)
		(layer "In2.Cu")
		(net "FM_CPU0_PKGID2")
	)
	(segment
		(start 251.456698 -86.697566)
		(end 250.900184 -86.697566)
		(width 0.0889)
		(layer "In2.Cu")
		(net "FM_CPU0_PKGID2")
	)
	(segment
		(start 285.21914 -81.745582)
		(end 283.4513 -83.515962)
		(width 0.0889)
		(layer "In2.Cu")
		(net "FM_CPU0_PKGID2")
	)
	(segment
		(start 295.818306 -75.125834)
		(end 295.412922 -75.125834)
		(width 0.0889)
		(layer "In2.Cu")
		(net "FM_CPU0_PKGID2")
	)
	(segment
		(start 296.825924 -74.630788)
		(end 296.64025 -74.630788)
		(width 0.0889)
		(layer "In2.Cu")
		(net "FM_CPU0_PKGID2")
	)
	(segment
		(start 292.956488 -75.813412)
		(end 292.65499 -76.11491)
		(width 0.0889)
		(layer "In2.Cu")
		(net "FM_CPU0_PKGID2")
	)
	(segment
		(start 246.937784 -86.39556)
		(end 245.518178 -86.39556)
		(width 0.0889)
		(layer "In2.Cu")
		(net "FM_CPU0_PKGID2")
	)
	(segment
		(start 245.518178 -86.39556)
		(end 243.798598 -88.11514)
		(width 0.0889)
		(layer "In2.Cu")
		(net "FM_CPU0_PKGID2")
	)
	(segment
		(start 281.628342 -88.297258)
		(end 281.426412 -88.499188)
		(width 0.0889)
		(layer "In2.Cu")
		(net "FM_CPU0_PKGID2")
	)
	(segment
		(start 252.617224 -86.697566)
		(end 252.315218 -86.39556)
		(width 0.0889)
		(layer "In2.Cu")
		(net "FM_CPU0_PKGID2")
	)
	(segment
		(start 283.4513 -85.47608)
		(end 281.628342 -87.299038)
		(width 0.0889)
		(layer "In2.Cu")
		(net "FM_CPU0_PKGID2")
	)
	(segment
		(start 291.244528 -75.813412)
		(end 290.94303 -76.11491)
		(width 0.0889)
		(layer "In2.Cu")
		(net "FM_CPU0_PKGID2")
	)
	(segment
		(start 283.4513 -83.515962)
		(end 283.4513 -85.47608)
		(width 0.0889)
		(layer "In2.Cu")
		(net "FM_CPU0_PKGID2")
	)
	(segment
		(start 243.798598 -88.11514)
		(end 243.798598 -88.872314)
		(width 0.0889)
		(layer "In2.Cu")
		(net "FM_CPU0_PKGID2")
	)
	(segment
		(start 262.24357 -89.175336)
		(end 262.210804 -89.175336)
		(width 0.0889)
		(layer "In2.Cu")
		(net "FM_CPU0_PKGID2")
	)
	(segment
		(start 300.975776 -73.335134)
		(end 300.689772 -73.335134)
		(width 0.0889)
		(layer "In2.Cu")
		(net "FM_CPU0_PKGID2")
	)
	(segment
		(start 291.977318 -76.11491)
		(end 291.67582 -75.813412)
		(width 0.0889)
		(layer "In2.Cu")
		(net "FM_CPU0_PKGID2")
	)
	(segment
		(start 286.374078 -80.574642)
		(end 286.105092 -80.574642)
		(width 0.0889)
		(layer "In2.Cu")
		(net "FM_CPU0_PKGID2")
	)
	(segment
		(start 251.758704 -86.39556)
		(end 251.456698 -86.697566)
		(width 0.0889)
		(layer "In2.Cu")
		(net "FM_CPU0_PKGID2")
	)
	(segment
		(start 307.061616 -71.849488)
		(end 306.873148 -71.849488)
		(width 0.0889)
		(layer "In2.Cu")
		(net "FM_CPU0_PKGID2")
	)
	(segment
		(start 247.23979 -86.697566)
		(end 246.937784 -86.39556)
		(width 0.0889)
		(layer "In2.Cu")
		(net "FM_CPU0_PKGID2")
	)
	(segment
		(start 292.65499 -76.11491)
		(end 291.977318 -76.11491)
		(width 0.0889)
		(layer "In2.Cu")
		(net "FM_CPU0_PKGID2")
	)
	(segment
		(start 261.38886 -88.68029)
		(end 261.34568 -88.68029)
		(width 0.0889)
		(layer "In2.Cu")
		(net "FM_CPU0_PKGID2")
	)
	(segment
		(start 250.041664 -86.39556)
		(end 249.739658 -86.697566)
		(width 0.0889)
		(layer "In2.Cu")
		(net "FM_CPU0_PKGID2")
	)
	(segment
		(start 286.105092 -80.574642)
		(end 285.21914 -81.460594)
		(width 0.0889)
		(layer "In2.Cu")
		(net "FM_CPU0_PKGID2")
	)
	(segment
		(start 252.315218 -86.39556)
		(end 251.758704 -86.39556)
		(width 0.0889)
		(layer "In2.Cu")
		(net "FM_CPU0_PKGID2")
	)
	(segment
		(start 243.798598 -88.872314)
		(end 244.197124 -89.27084)
		(width 0.0889)
		(layer "In2.Cu")
		(net "FM_CPU0_PKGID2")
	)
	(segment
		(start 293.899082 -75.317858)
		(end 293.403528 -75.813412)
		(width 0.0889)
		(layer "In2.Cu")
		(net "FM_CPU0_PKGID2")
	)
	(segment
		(start 248.881138 -86.39556)
		(end 248.324624 -86.39556)
		(width 0.0889)
		(layer "In2.Cu")
		(net "FM_CPU0_PKGID2")
	)
	(segment
		(start 302.692816 -72.344534)
		(end 302.66005 -72.344534)
		(width 0.0889)
		(layer "In2.Cu")
		(net "FM_CPU0_PKGID2")
	)
	(segment
		(start 287.55848 -79.468218)
		(end 287.56483 -79.478886)
		(width 0.0889)
		(layer "In2.Cu")
		(net "FM_CPU0_PKGID2")
	)
	(segment
		(start 257.09245 -88.184736)
		(end 257.059684 -88.184736)
		(width 0.0889)
		(layer "In2.Cu")
		(net "FM_CPU0_PKGID2")
	)
	(segment
		(start 275.545804 -89.784682)
		(end 275.537676 -89.798906)
		(width 0.0889)
		(layer "In2.Cu")
		(net "FM_CPU0_PKGID2")
	)
	(segment
		(start 297.82389 -74.22134)
		(end 297.235372 -74.22134)
		(width 0.0889)
		(layer "In2.Cu")
		(net "FM_CPU0_PKGID2")
	)
	(segment
		(start 314.857638 -65.98539)
		(end 309.377588 -71.46544)
		(width 0.089408)
		(layer "In2.Cu")
		(net "FM_CPU0_PKGID2")
	)
	(segment
		(start 258.806696 -89.175336)
		(end 258.776724 -89.175336)
		(width 0.0889)
		(layer "In2.Cu")
		(net "FM_CPU0_PKGID2")
	)
	(segment
		(start 248.324624 -86.39556)
		(end 248.022618 -86.697566)
		(width 0.0889)
		(layer "In2.Cu")
		(net "FM_CPU0_PKGID2")
	)
	(segment
		(start 291.67582 -75.813412)
		(end 291.244528 -75.813412)
		(width 0.0889)
		(layer "In2.Cu")
		(net "FM_CPU0_PKGID2")
	)
	(segment
		(start 250.598178 -86.39556)
		(end 250.041664 -86.39556)
		(width 0.0889)
		(layer "In2.Cu")
		(net "FM_CPU0_PKGID2")
	)
	(segment
		(start 300.385988 -73.638918)
		(end 299.992542 -73.638918)
		(width 0.0889)
		(layer "In2.Cu")
		(net "FM_CPU0_PKGID2")
	)
	(segment
		(start 309.377588 -71.46544)
		(end 307.70576 -71.46544)
		(width 0.089408)
		(layer "In2.Cu")
		(net "FM_CPU0_PKGID2")
	)
	(segment
		(start 278.64816 -89.984834)
		(end 278.618188 -89.984834)
		(width 0.0889)
		(layer "In2.Cu")
		(net "FM_CPU0_PKGID2")
	)
	(segment
		(start 253.173738 -86.697566)
		(end 252.617224 -86.697566)
		(width 0.0889)
		(layer "In2.Cu")
		(net "FM_CPU0_PKGID2")
	)
	(segment
		(start 289.401758 -75.813412)
		(end 289.098736 -76.116434)
		(width 0.0889)
		(layer "In2.Cu")
		(net "FM_CPU0_PKGID2")
	)
	(segment
		(start 254.304292 -86.69909)
		(end 254.000762 -86.39556)
		(width 0.0889)
		(layer "In2.Cu")
		(net "FM_CPU0_PKGID2")
	)
	(segment
		(start 287.56483 -77.497686)
		(end 287.569656 -77.506322)
		(width 0.0889)
		(layer "In2.Cu")
		(net "FM_CPU0_PKGID2")
	)
	(segment
		(start 269.098522 -89.670128)
		(end 268.60373 -89.175336)
		(width 0.0889)
		(layer "In2.Cu")
		(net "FM_CPU0_PKGID2")
	)
	(segment
		(start 332.755494 -41.96969)
		(end 332.704694 -42.02049)
		(width 0.089408)
		(layer "In2.Cu")
		(net "FM_CPU0_PKGID2")
	)
	(segment
		(start 254.5207 -86.69909)
		(end 254.304292 -86.69909)
		(width 0.0889)
		(layer "In2.Cu")
		(net "FM_CPU0_PKGID2")
	)
	(segment
		(start 289.988752 -75.813412)
		(end 289.401758 -75.813412)
		(width 0.0889)
		(layer "In2.Cu")
		(net "FM_CPU0_PKGID2")
	)
	(segment
		(start 273.135598 -89.784936)
		(end 273.040348 -89.619836)
		(width 0.0889)
		(layer "In2.Cu")
		(net "FM_CPU0_PKGID2")
	)
	(segment
		(start 264.457942 -89.47658)
		(end 264.45464 -89.470738)
		(width 0.0889)
		(layer "In2.Cu")
		(net "FM_CPU0_PKGID2")
	)
	(segment
		(start 279.50287 -89.489788)
		(end 279.470104 -89.489788)
		(width 0.0889)
		(layer "In2.Cu")
		(net "FM_CPU0_PKGID2")
	)
	(segment
		(start 295.412922 -75.125834)
		(end 295.1099 -74.822812)
		(width 0.0889)
		(layer "In2.Cu")
		(net "FM_CPU0_PKGID2")
	)
	(segment
		(start 253.475744 -86.39556)
		(end 253.173738 -86.697566)
		(width 0.0889)
		(layer "In2.Cu")
		(net "FM_CPU0_PKGID2")
	)
	(segment
		(start 271.131792 -89.470738)
		(end 270.932402 -89.670128)
		(width 0.0889)
		(layer "In2.Cu")
		(net "FM_CPU0_PKGID2")
	)
	(segment
		(start 270.932402 -89.670128)
		(end 269.098522 -89.670128)
		(width 0.0889)
		(layer "In2.Cu")
		(net "FM_CPU0_PKGID2")
	)
	(segment
		(start 287.56483 -79.478886)
		(end 287.569656 -79.487522)
		(width 0.0889)
		(layer "In2.Cu")
		(net "FM_CPU0_PKGID2")
	)
	(segment
		(start 297.235372 -74.22134)
		(end 296.825924 -74.630788)
		(width 0.0889)
		(layer "In2.Cu")
		(net "FM_CPU0_PKGID2")
	)
	(segment
		(start 256.23774 -87.68969)
		(end 256.204974 -87.68969)
		(width 0.0889)
		(layer "In2.Cu")
		(net "FM_CPU0_PKGID2")
	)
	(segment
		(start 295.1099 -74.822812)
		(end 294.7797 -74.822812)
		(width 0.0889)
		(layer "In2.Cu")
		(net "FM_CPU0_PKGID2")
	)
	(segment
		(start 281.426412 -88.499188)
		(end 281.187144 -88.499188)
		(width 0.0889)
		(layer "In2.Cu")
		(net "FM_CPU0_PKGID2")
	)
	(segment
		(start 299.497496 -74.133964)
		(end 298.929044 -74.133964)
		(width 0.0889)
		(layer "In2.Cu")
		(net "FM_CPU0_PKGID2")
	)
	(segment
		(start 299.992542 -73.638918)
		(end 299.497496 -74.133964)
		(width 0.0889)
		(layer "In2.Cu")
		(net "FM_CPU0_PKGID2")
	)
	(segment
		(start 268.60373 -89.175336)
		(end 267.376148 -89.175336)
		(width 0.0889)
		(layer "In2.Cu")
		(net "FM_CPU0_PKGID2")
	)
	(segment
		(start 276.569424 -89.784936)
		(end 276.563074 -89.774268)
		(width 0.0889)
		(layer "In2.Cu")
		(net "FM_CPU0_PKGID2")
	)
	(segment
		(start 259.67182 -88.68029)
		(end 259.62864 -88.68029)
		(width 0.0889)
		(layer "In2.Cu")
		(net "FM_CPU0_PKGID2")
	)
	(segment
		(start 298.929044 -74.133964)
		(end 298.627038 -73.831958)
		(width 0.0889)
		(layer "In2.Cu")
		(net "FM_CPU0_PKGID2")
	)
	(segment
		(start 281.628342 -87.299038)
		(end 281.628342 -88.297258)
		(width 0.0889)
		(layer "In2.Cu")
		(net "FM_CPU0_PKGID2")
	)
	(segment
		(start 304.399442 -71.353934)
		(end 304.37709 -71.353934)
		(width 0.0889)
		(layer "In2.Cu")
		(net "FM_CPU0_PKGID2")
	)
	(segment
		(start 298.213272 -73.831958)
		(end 297.82389 -74.22134)
		(width 0.0889)
		(layer "In2.Cu")
		(net "FM_CPU0_PKGID2")
	)
	(segment
		(start 260.523736 -89.175336)
		(end 260.493764 -89.175336)
		(width 0.0889)
		(layer "In2.Cu")
		(net "FM_CPU0_PKGID2")
	)
	(segment
		(start 300.689772 -73.335134)
		(end 300.385988 -73.638918)
		(width 0.0889)
		(layer "In2.Cu")
		(net "FM_CPU0_PKGID2")
	)
	(segment
		(start 257.95478 -88.68029)
		(end 257.922014 -88.68029)
		(width 0.0889)
		(layer "In2.Cu")
		(net "FM_CPU0_PKGID2")
	)
	(segment
		(start 273.040348 -89.619836)
		(end 272.782538 -89.470738)
		(width 0.0889)
		(layer "In2.Cu")
		(net "FM_CPU0_PKGID2")
	)
	(segment
		(start 290.94303 -76.11491)
		(end 290.29025 -76.11491)
		(width 0.0889)
		(layer "In2.Cu")
		(net "FM_CPU0_PKGID2")
	)
	(segment
		(start 280.3652 -88.994234)
		(end 280.332434 -88.994234)
		(width 0.0889)
		(layer "In2.Cu")
		(net "FM_CPU0_PKGID2")
	)
	(segment
		(start 249.739658 -86.697566)
		(end 249.183144 -86.697566)
		(width 0.0889)
		(layer "In2.Cu")
		(net "FM_CPU0_PKGID2")
	)
	(segment
		(start 301.830486 -72.840088)
		(end 301.79772 -72.840088)
		(width 0.0889)
		(layer "In2.Cu")
		(net "FM_CPU0_PKGID2")
	)
	(segment
		(start 263.96061 -89.175336)
		(end 263.92505 -89.175336)
		(width 0.0889)
		(layer "In2.Cu")
		(net "FM_CPU0_PKGID2")
	)
	(segment
		(start 287.55848 -77.487018)
		(end 287.56483 -77.497686)
		(width 0.0889)
		(layer "In2.Cu")
		(net "FM_CPU0_PKGID2")
	)
	(segment
		(start 294.7797 -74.822812)
		(end 294.284654 -75.317858)
		(width 0.0889)
		(layer "In2.Cu")
		(net "FM_CPU0_PKGID2")
	)
	(arc
		(start 287.569656 -77.506322)
		(mid 287.618411 -77.702674)
		(end 287.56483 -77.897736)
		(width 0.0889)
		(layer "In2.Cu")
		(net "FM_CPU0_PKGID2")
	)
	(arc
		(start 302.324516 -72.544686)
		(mid 302.115908 -72.756618)
		(end 301.830486 -72.840088)
		(width 0.0889)
		(layer "In2.Cu")
		(net "FM_CPU0_PKGID2")
	)
	(arc
		(start 304.37709 -71.353934)
		(mid 304.18324 -71.410284)
		(end 304.041556 -71.554086)
		(width 0.0889)
		(layer "In2.Cu")
		(net "FM_CPU0_PKGID2")
	)
	(arc
		(start 277.262844 -89.784936)
		(mid 276.916134 -89.98512)
		(end 276.569424 -89.784936)
		(width 0.0889)
		(layer "In2.Cu")
		(net "FM_CPU0_PKGID2")
	)
	(arc
		(start 281.187144 -88.499188)
		(mid 280.903927 -88.583469)
		(end 280.696924 -88.794336)
		(width 0.0889)
		(layer "In2.Cu")
		(net "FM_CPU0_PKGID2")
	)
	(arc
		(start 266.864846 -89.470738)
		(mid 266.518136 -89.671049)
		(end 266.171426 -89.470738)
		(width 0.0889)
		(layer "In2.Cu")
		(net "FM_CPU0_PKGID2")
	)
	(arc
		(start 262.210804 -89.175336)
		(mid 262.019162 -89.11817)
		(end 261.87908 -88.975438)
		(width 0.0889)
		(layer "In2.Cu")
		(net "FM_CPU0_PKGID2")
	)
	(arc
		(start 296.64025 -74.630788)
		(mid 296.357033 -74.715069)
		(end 296.15003 -74.925936)
		(width 0.0889)
		(layer "In2.Cu")
		(net "FM_CPU0_PKGID2")
	)
	(arc
		(start 278.286464 -89.784936)
		(mid 277.774654 -89.489397)
		(end 277.262844 -89.784936)
		(width 0.0889)
		(layer "In2.Cu")
		(net "FM_CPU0_PKGID2")
	)
	(arc
		(start 305.229006 -71.849488)
		(mid 304.943582 -71.766021)
		(end 304.734976 -71.554086)
		(width 0.0889)
		(layer "In2.Cu")
		(net "FM_CPU0_PKGID2")
	)
	(arc
		(start 301.465996 -73.039986)
		(mid 301.258992 -73.25085)
		(end 300.975776 -73.335134)
		(width 0.0889)
		(layer "In2.Cu")
		(net "FM_CPU0_PKGID2")
	)
	(arc
		(start 305.593496 -72.049386)
		(mid 305.453417 -71.90665)
		(end 305.261772 -71.849488)
		(width 0.0889)
		(layer "In2.Cu")
		(net "FM_CPU0_PKGID2")
	)
	(arc
		(start 287.56483 -78.48854)
		(mid 287.618329 -78.688438)
		(end 287.56483 -78.888336)
		(width 0.0889)
		(layer "In2.Cu")
		(net "FM_CPU0_PKGID2")
	)
	(arc
		(start 278.618188 -89.984834)
		(mid 278.426546 -89.927668)
		(end 278.286464 -89.784936)
		(width 0.0889)
		(layer "In2.Cu")
		(net "FM_CPU0_PKGID2")
	)
	(arc
		(start 280.696924 -88.794336)
		(mid 280.556845 -88.937072)
		(end 280.3652 -88.994234)
		(width 0.0889)
		(layer "In2.Cu")
		(net "FM_CPU0_PKGID2")
	)
	(arc
		(start 301.79772 -72.840088)
		(mid 301.606078 -72.897254)
		(end 301.465996 -73.039986)
		(width 0.0889)
		(layer "In2.Cu")
		(net "FM_CPU0_PKGID2")
	)
	(arc
		(start 257.922014 -88.68029)
		(mid 257.728164 -88.62394)
		(end 257.58648 -88.480138)
		(width 0.0889)
		(layer "In2.Cu")
		(net "FM_CPU0_PKGID2")
	)
	(arc
		(start 288.42335 -76.411836)
		(mid 288.281667 -76.55564)
		(end 288.087816 -76.611988)
		(width 0.0889)
		(layer "In2.Cu")
		(net "FM_CPU0_PKGID2")
	)
	(arc
		(start 261.87908 -88.975438)
		(mid 261.672076 -88.764574)
		(end 261.38886 -88.68029)
		(width 0.0889)
		(layer "In2.Cu")
		(net "FM_CPU0_PKGID2")
	)
	(arc
		(start 306.24272 -72.363076)
		(mid 305.863305 -72.319628)
		(end 305.593496 -72.049386)
		(width 0.0889)
		(layer "In2.Cu")
		(net "FM_CPU0_PKGID2")
	)
	(arc
		(start 264.45464 -89.470738)
		(mid 264.246032 -89.258806)
		(end 263.96061 -89.175336)
		(width 0.0889)
		(layer "In2.Cu")
		(net "FM_CPU0_PKGID2")
	)
	(arc
		(start 267.376148 -89.175336)
		(mid 267.080885 -89.254487)
		(end 266.864846 -89.470738)
		(width 0.0889)
		(layer "In2.Cu")
		(net "FM_CPU0_PKGID2")
	)
	(arc
		(start 296.15003 -74.925936)
		(mid 296.009951 -75.068672)
		(end 295.818306 -75.125834)
		(width 0.0889)
		(layer "In2.Cu")
		(net "FM_CPU0_PKGID2")
	)
	(arc
		(start 273.829018 -89.784936)
		(mid 273.482308 -89.98512)
		(end 273.135598 -89.784936)
		(width 0.0889)
		(layer "In2.Cu")
		(net "FM_CPU0_PKGID2")
	)
	(arc
		(start 257.059684 -88.184736)
		(mid 256.868042 -88.12757)
		(end 256.72796 -87.984838)
		(width 0.0889)
		(layer "In2.Cu")
		(net "FM_CPU0_PKGID2")
	)
	(arc
		(start 287.56483 -77.897736)
		(mid 287.485699 -78.193138)
		(end 287.56483 -78.48854)
		(width 0.0889)
		(layer "In2.Cu")
		(net "FM_CPU0_PKGID2")
	)
	(arc
		(start 304.041556 -71.554086)
		(mid 303.832948 -71.766018)
		(end 303.547526 -71.849488)
		(width 0.0889)
		(layer "In2.Cu")
		(net "FM_CPU0_PKGID2")
	)
	(arc
		(start 286.70631 -80.374236)
		(mid 286.566094 -80.517371)
		(end 286.374078 -80.574642)
		(width 0.0889)
		(layer "In2.Cu")
		(net "FM_CPU0_PKGID2")
	)
	(arc
		(start 307.551836 -71.55434)
		(mid 307.344832 -71.765204)
		(end 307.061616 -71.849488)
		(width 0.0889)
		(layer "In2.Cu")
		(net "FM_CPU0_PKGID2")
	)
	(arc
		(start 279.470104 -89.489788)
		(mid 279.186887 -89.574069)
		(end 278.979884 -89.784936)
		(width 0.0889)
		(layer "In2.Cu")
		(net "FM_CPU0_PKGID2")
	)
	(arc
		(start 260.16204 -88.975438)
		(mid 259.955036 -88.764574)
		(end 259.67182 -88.68029)
		(width 0.0889)
		(layer "In2.Cu")
		(net "FM_CPU0_PKGID2")
	)
	(arc
		(start 287.56483 -78.888336)
		(mid 287.485608 -79.177454)
		(end 287.55848 -79.468218)
		(width 0.0889)
		(layer "In2.Cu")
		(net "FM_CPU0_PKGID2")
	)
	(arc
		(start 274.852638 -89.784936)
		(mid 274.340828 -89.489397)
		(end 273.829018 -89.784936)
		(width 0.0889)
		(layer "In2.Cu")
		(net "FM_CPU0_PKGID2")
	)
	(arc
		(start 302.66005 -72.344534)
		(mid 302.4662 -72.400884)
		(end 302.324516 -72.544686)
		(width 0.0889)
		(layer "In2.Cu")
		(net "FM_CPU0_PKGID2")
	)
	(arc
		(start 259.62864 -88.68029)
		(mid 259.345423 -88.764571)
		(end 259.13842 -88.975438)
		(width 0.0889)
		(layer "In2.Cu")
		(net "FM_CPU0_PKGID2")
	)
	(arc
		(start 255.342644 -87.194136)
		(mid 255.151002 -87.13697)
		(end 255.01092 -86.994238)
		(width 0.0889)
		(layer "In2.Cu")
		(net "FM_CPU0_PKGID2")
	)
	(arc
		(start 259.13842 -88.975438)
		(mid 258.998341 -89.118174)
		(end 258.806696 -89.175336)
		(width 0.0889)
		(layer "In2.Cu")
		(net "FM_CPU0_PKGID2")
	)
	(arc
		(start 307.70576 -71.46544)
		(mid 307.616904 -71.489275)
		(end 307.551836 -71.55434)
		(width 0.0889)
		(layer "In2.Cu")
		(net "FM_CPU0_PKGID2")
	)
	(arc
		(start 261.34568 -88.68029)
		(mid 261.062463 -88.764571)
		(end 260.85546 -88.975438)
		(width 0.0889)
		(layer "In2.Cu")
		(net "FM_CPU0_PKGID2")
	)
	(arc
		(start 278.979884 -89.784936)
		(mid 278.839805 -89.927672)
		(end 278.64816 -89.984834)
		(width 0.0889)
		(layer "In2.Cu")
		(net "FM_CPU0_PKGID2")
	)
	(arc
		(start 288.05505 -76.611988)
		(mid 287.771833 -76.696269)
		(end 287.56483 -76.907136)
		(width 0.0889)
		(layer "In2.Cu")
		(net "FM_CPU0_PKGID2")
	)
	(arc
		(start 256.72796 -87.984838)
		(mid 256.520956 -87.773974)
		(end 256.23774 -87.68969)
		(width 0.0889)
		(layer "In2.Cu")
		(net "FM_CPU0_PKGID2")
	)
	(arc
		(start 303.183036 -72.049386)
		(mid 302.976032 -72.26025)
		(end 302.692816 -72.344534)
		(width 0.0889)
		(layer "In2.Cu")
		(net "FM_CPU0_PKGID2")
	)
	(arc
		(start 280.332434 -88.994234)
		(mid 280.04701 -89.077701)
		(end 279.838404 -89.289636)
		(width 0.0889)
		(layer "In2.Cu")
		(net "FM_CPU0_PKGID2")
	)
	(arc
		(start 255.01092 -86.994238)
		(mid 254.803916 -86.783374)
		(end 254.5207 -86.69909)
		(width 0.0889)
		(layer "In2.Cu")
		(net "FM_CPU0_PKGID2")
	)
	(arc
		(start 288.91738 -76.116434)
		(mid 288.631956 -76.199901)
		(end 288.42335 -76.411836)
		(width 0.0889)
		(layer "In2.Cu")
		(net "FM_CPU0_PKGID2")
	)
	(arc
		(start 306.873148 -71.849488)
		(mid 306.747947 -71.929259)
		(end 306.656994 -72.046592)
		(width 0.0889)
		(layer "In2.Cu")
		(net "FM_CPU0_PKGID2")
	)
	(arc
		(start 276.563074 -89.774268)
		(mid 276.051517 -89.489465)
		(end 275.545804 -89.784682)
		(width 0.0889)
		(layer "In2.Cu")
		(net "FM_CPU0_PKGID2")
	)
	(arc
		(start 287.56483 -76.907136)
		(mid 287.485608 -77.196254)
		(end 287.55848 -77.487018)
		(width 0.0889)
		(layer "In2.Cu")
		(net "FM_CPU0_PKGID2")
	)
	(arc
		(start 258.776724 -89.175336)
		(mid 258.585082 -89.11817)
		(end 258.445 -88.975438)
		(width 0.0889)
		(layer "In2.Cu")
		(net "FM_CPU0_PKGID2")
	)
	(arc
		(start 266.171426 -89.470738)
		(mid 265.962818 -89.258806)
		(end 265.677396 -89.175336)
		(width 0.0889)
		(layer "In2.Cu")
		(net "FM_CPU0_PKGID2")
	)
	(arc
		(start 265.147806 -89.470738)
		(mid 264.804516 -89.671034)
		(end 264.457942 -89.47658)
		(width 0.0889)
		(layer "In2.Cu")
		(net "FM_CPU0_PKGID2")
	)
	(arc
		(start 306.656994 -72.046592)
		(mid 306.484483 -72.250174)
		(end 306.24272 -72.363076)
		(width 0.0889)
		(layer "In2.Cu")
		(net "FM_CPU0_PKGID2")
	)
	(arc
		(start 258.445 -88.975438)
		(mid 258.237996 -88.764574)
		(end 257.95478 -88.68029)
		(width 0.0889)
		(layer "In2.Cu")
		(net "FM_CPU0_PKGID2")
	)
	(arc
		(start 255.86944 -87.489538)
		(mid 255.660832 -87.277606)
		(end 255.37541 -87.194136)
		(width 0.0889)
		(layer "In2.Cu")
		(net "FM_CPU0_PKGID2")
	)
	(arc
		(start 262.7376 -89.470738)
		(mid 262.528992 -89.258806)
		(end 262.24357 -89.175336)
		(width 0.0889)
		(layer "In2.Cu")
		(net "FM_CPU0_PKGID2")
	)
	(arc
		(start 257.58648 -88.480138)
		(mid 257.377872 -88.268206)
		(end 257.09245 -88.184736)
		(width 0.0889)
		(layer "In2.Cu")
		(net "FM_CPU0_PKGID2")
	)
	(arc
		(start 287.20034 -80.078834)
		(mid 286.914916 -80.162301)
		(end 286.70631 -80.374236)
		(width 0.0889)
		(layer "In2.Cu")
		(net "FM_CPU0_PKGID2")
	)
	(arc
		(start 287.56483 -79.878936)
		(mid 287.424751 -80.021672)
		(end 287.233106 -80.078834)
		(width 0.0889)
		(layer "In2.Cu")
		(net "FM_CPU0_PKGID2")
	)
	(arc
		(start 256.204974 -87.68969)
		(mid 256.011124 -87.63334)
		(end 255.86944 -87.489538)
		(width 0.0889)
		(layer "In2.Cu")
		(net "FM_CPU0_PKGID2")
	)
	(arc
		(start 260.85546 -88.975438)
		(mid 260.715381 -89.118174)
		(end 260.523736 -89.175336)
		(width 0.0889)
		(layer "In2.Cu")
		(net "FM_CPU0_PKGID2")
	)
	(arc
		(start 287.569656 -79.487522)
		(mid 287.618411 -79.683874)
		(end 287.56483 -79.878936)
		(width 0.0889)
		(layer "In2.Cu")
		(net "FM_CPU0_PKGID2")
	)
	(arc
		(start 303.51476 -71.849488)
		(mid 303.323118 -71.906654)
		(end 303.183036 -72.049386)
		(width 0.0889)
		(layer "In2.Cu")
		(net "FM_CPU0_PKGID2")
	)
	(arc
		(start 265.641836 -89.175336)
		(mid 265.356412 -89.258803)
		(end 265.147806 -89.470738)
		(width 0.0889)
		(layer "In2.Cu")
		(net "FM_CPU0_PKGID2")
	)
	(arc
		(start 263.43102 -89.470738)
		(mid 263.08431 -89.671049)
		(end 262.7376 -89.470738)
		(width 0.0889)
		(layer "In2.Cu")
		(net "FM_CPU0_PKGID2")
	)
	(arc
		(start 260.493764 -89.175336)
		(mid 260.302122 -89.11817)
		(end 260.16204 -88.975438)
		(width 0.0889)
		(layer "In2.Cu")
		(net "FM_CPU0_PKGID2")
	)
	(arc
		(start 304.734976 -71.554086)
		(mid 304.593293 -71.410282)
		(end 304.399442 -71.353934)
		(width 0.0889)
		(layer "In2.Cu")
		(net "FM_CPU0_PKGID2")
	)
	(arc
		(start 275.537676 -89.798906)
		(mid 275.191202 -89.985094)
		(end 274.852638 -89.784936)
		(width 0.0889)
		(layer "In2.Cu")
		(net "FM_CPU0_PKGID2")
	)
	(arc
		(start 279.838404 -89.289636)
		(mid 279.696721 -89.43344)
		(end 279.50287 -89.489788)
		(width 0.0889)
		(layer "In2.Cu")
		(net "FM_CPU0_PKGID2")
	)
	(arc
		(start 263.92505 -89.175336)
		(mid 263.639626 -89.258803)
		(end 263.43102 -89.470738)
		(width 0.0889)
		(layer "In2.Cu")
		(net "FM_CPU0_PKGID2")
	)
	(segment
		(start 331.347572 -41.450514)
		(end 332.236318 -41.450514)
		(width 0.089408)
		(layer "In11.Cu")
		(net "FM_CPU0_PKGID2")
	)
	(segment
		(start 378.707142 -67.655186)
		(end 377.514104 -66.462148)
		(width 0.089408)
		(layer "In11.Cu")
		(net "FM_CPU0_PKGID2")
	)
	(segment
		(start 357.999792 -45.23359)
		(end 357.999538 -45.233844)
		(width 0.089408)
		(layer "In11.Cu")
		(net "FM_CPU0_PKGID2")
	)
	(segment
		(start 373.658638 -57.29605)
		(end 368.638582 -52.275994)
		(width 0.089408)
		(layer "In11.Cu")
		(net "FM_CPU0_PKGID2")
	)
	(segment
		(start 378.344684 -72.695308)
		(end 378.734828 -72.305164)
		(width 0.089408)
		(layer "In11.Cu")
		(net "FM_CPU0_PKGID2")
	)
	(segment
		(start 331.11313 -41.684956)
		(end 331.347572 -41.450514)
		(width 0.089408)
		(layer "In11.Cu")
		(net "FM_CPU0_PKGID2")
	)
	(segment
		(start 377.01474 -63.27394)
		(end 377.01474 -62.469776)
		(width 0.089408)
		(layer "In11.Cu")
		(net "FM_CPU0_PKGID2")
	)
	(segment
		(start 378.734828 -69.116194)
		(end 378.970286 -68.880736)
		(width 0.089408)
		(layer "In11.Cu")
		(net "FM_CPU0_PKGID2")
	)
	(segment
		(start 331.471778 -42.251122)
		(end 331.347572 -42.251122)
		(width 0.089408)
		(layer "In11.Cu")
		(net "FM_CPU0_PKGID2")
	)
	(segment
		(start 334.299814 -45.233844)
		(end 332.216506 -43.150536)
		(width 0.089408)
		(layer "In11.Cu")
		(net "FM_CPU0_PKGID2")
	)
	(segment
		(start 357.999538 -45.233844)
		(end 334.299814 -45.233844)
		(width 0.089408)
		(layer "In11.Cu")
		(net "FM_CPU0_PKGID2")
	)
	(segment
		(start 331.347572 -42.251122)
		(end 331.11313 -42.01668)
		(width 0.089408)
		(layer "In11.Cu")
		(net "FM_CPU0_PKGID2")
	)
	(segment
		(start 331.11313 -42.01668)
		(end 331.11313 -41.684956)
		(width 0.089408)
		(layer "In11.Cu")
		(net "FM_CPU0_PKGID2")
	)
	(segment
		(start 377.01474 -60.19419)
		(end 374.1166 -57.29605)
		(width 0.089408)
		(layer "In11.Cu")
		(net "FM_CPU0_PKGID2")
	)
	(segment
		(start 364.665006 -51.181)
		(end 358.717596 -45.23359)
		(width 0.089408)
		(layer "In11.Cu")
		(net "FM_CPU0_PKGID2")
	)
	(segment
		(start 368.638582 -52.275994)
		(end 368.470434 -52.275994)
		(width 0.089408)
		(layer "In11.Cu")
		(net "FM_CPU0_PKGID2")
	)
	(segment
		(start 332.216506 -43.150536)
		(end 332.216506 -42.99585)
		(width 0.089408)
		(layer "In11.Cu")
		(net "FM_CPU0_PKGID2")
	)
	(segment
		(start 374.1166 -57.29605)
		(end 373.658638 -57.29605)
		(width 0.089408)
		(layer "In11.Cu")
		(net "FM_CPU0_PKGID2")
	)
	(segment
		(start 377.514104 -63.773304)
		(end 377.01474 -63.27394)
		(width 0.089408)
		(layer "In11.Cu")
		(net "FM_CPU0_PKGID2")
	)
	(segment
		(start 358.717596 -45.23359)
		(end 357.999792 -45.23359)
		(width 0.089408)
		(layer "In11.Cu")
		(net "FM_CPU0_PKGID2")
	)
	(segment
		(start 377.514104 -66.462148)
		(end 377.514104 -63.773304)
		(width 0.089408)
		(layer "In11.Cu")
		(net "FM_CPU0_PKGID2")
	)
	(segment
		(start 378.970286 -68.880736)
		(end 378.970286 -68.340986)
		(width 0.089408)
		(layer "In11.Cu")
		(net "FM_CPU0_PKGID2")
	)
	(segment
		(start 377.01474 -62.469776)
		(end 377.198382 -62.286134)
		(width 0.089408)
		(layer "In11.Cu")
		(net "FM_CPU0_PKGID2")
	)
	(segment
		(start 377.198382 -61.95441)
		(end 377.01474 -61.770768)
		(width 0.089408)
		(layer "In11.Cu")
		(net "FM_CPU0_PKGID2")
	)
	(segment
		(start 377.198382 -62.286134)
		(end 377.198382 -61.95441)
		(width 0.089408)
		(layer "In11.Cu")
		(net "FM_CPU0_PKGID2")
	)
	(segment
		(start 377.01474 -61.770768)
		(end 377.01474 -60.19419)
		(width 0.089408)
		(layer "In11.Cu")
		(net "FM_CPU0_PKGID2")
	)
	(segment
		(start 378.734828 -72.305164)
		(end 378.734828 -69.116194)
		(width 0.089408)
		(layer "In11.Cu")
		(net "FM_CPU0_PKGID2")
	)
	(segment
		(start 367.37544 -51.181)
		(end 364.665006 -51.181)
		(width 0.089408)
		(layer "In11.Cu")
		(net "FM_CPU0_PKGID2")
	)
	(segment
		(start 378.707142 -68.077842)
		(end 378.707142 -67.655186)
		(width 0.089408)
		(layer "In11.Cu")
		(net "FM_CPU0_PKGID2")
	)
	(segment
		(start 378.970286 -68.340986)
		(end 378.707142 -68.077842)
		(width 0.089408)
		(layer "In11.Cu")
		(net "FM_CPU0_PKGID2")
	)
	(segment
		(start 332.236318 -41.450514)
		(end 332.755494 -41.96969)
		(width 0.089408)
		(layer "In11.Cu")
		(net "FM_CPU0_PKGID2")
	)
	(segment
		(start 332.216506 -42.99585)
		(end 331.471778 -42.251122)
		(width 0.089408)
		(layer "In11.Cu")
		(net "FM_CPU0_PKGID2")
	)
	(segment
		(start 368.470434 -52.275994)
		(end 367.37544 -51.181)
		(width 0.089408)
		(layer "In11.Cu")
		(net "FM_CPU0_PKGID2")
	)
	(segment
		(start 377.544838 -72.695308)
		(end 377.145042 -73.095104)
		(width 0.1016)
		(layer "F.Cu")
		(net "FM_CPU0_PKGID1")
	)
	(segment
		(start 244.768624 -88.28024)
		(end 244.197124 -88.28024)
		(width 0.10795)
		(layer "F.Cu")
		(net "FM_CPU0_PKGID1")
	)
	(via
		(at 383.96164 -35.18154)
		(size 0.508)
		(drill 0.254)
		(layers "F.Cu" "B.Cu")
		(net "FM_CPU0_PKGID1")
	)
	(via
		(at 244.197124 -88.28024)
		(size 0.508)
		(drill 0.254)
		(layers "F.Cu" "B.Cu")
		(net "FM_CPU0_PKGID1")
	)
	(via
		(at 362.712 -31.6484)
		(size 0.6604)
		(drill 0.3302)
		(layers "F.Cu" "B.Cu")
		(net "FM_CPU0_PKGID1")
	)
	(via
		(at 327.3552 -59.4106)
		(size 0.508)
		(drill 0.254)
		(layers "F.Cu" "B.Cu")
		(net "FM_CPU0_PKGID1")
	)
	(via
		(at 377.544838 -72.695308)
		(size 0.4572)
		(drill 0.2032)
		(layers "F.Cu" "B.Cu")
		(net "FM_CPU0_PKGID1")
	)
	(segment
		(start 230.298244 -90.297)
		(end 228.473 -90.297)
		(width 0.10795)
		(layer "B.Cu")
		(net "FM_CPU0_PKGID1")
	)
	(segment
		(start 373.759984 -27.611578)
		(end 371.37721 -29.994352)
		(width 0.10795)
		(layer "B.Cu")
		(net "FM_CPU0_PKGID1")
	)
	(segment
		(start 239.632998 -88.190324)
		(end 239.266984 -87.82431)
		(width 0.0889)
		(layer "B.Cu")
		(net "FM_CPU0_PKGID1")
	)
	(segment
		(start 242.313206 -87.770208)
		(end 241.890296 -88.193118)
		(width 0.0889)
		(layer "B.Cu")
		(net "FM_CPU0_PKGID1")
	)
	(segment
		(start 233.20502 -88.36914)
		(end 232.81386 -88.36914)
		(width 0.1016)
		(layer "B.Cu")
		(net "FM_CPU0_PKGID1")
	)
	(segment
		(start 237.072424 -87.767922)
		(end 236.609382 -88.230964)
		(width 0.0889)
		(layer "B.Cu")
		(net "FM_CPU0_PKGID1")
	)
	(segment
		(start 235.369862 -87.835486)
		(end 234.829858 -88.37549)
		(width 0.0889)
		(layer "B.Cu")
		(net "FM_CPU0_PKGID1")
	)
	(segment
		(start 355.206554 -38.452552)
		(end 354.231956 -39.42715)
		(width 0.10795)
		(layer "B.Cu")
		(net "FM_CPU0_PKGID1")
	)
	(segment
		(start 232.738422 -88.444578)
		(end 232.423716 -88.759284)
		(width 0.10795)
		(layer "B.Cu")
		(net "FM_CPU0_PKGID1")
	)
	(segment
		(start 328.801222 -57.916318)
		(end 328.62012 -58.09742)
		(width 0.10795)
		(layer "B.Cu")
		(net "FM_CPU0_PKGID1")
	)
	(segment
		(start 234.103164 -88.680036)
		(end 233.515916 -88.680036)
		(width 0.0889)
		(layer "B.Cu")
		(net "FM_CPU0_PKGID1")
	)
	(segment
		(start 339.961982 -48.8569)
		(end 336.97545 -51.843432)
		(width 0.10795)
		(layer "B.Cu")
		(net "FM_CPU0_PKGID1")
	)
	(segment
		(start 365.33074 -29.994352)
		(end 363.941868 -31.383224)
		(width 0.10795)
		(layer "B.Cu")
		(net "FM_CPU0_PKGID1")
	)
	(segment
		(start 375.670572 -27.611578)
		(end 373.759984 -27.611578)
		(width 0.10795)
		(layer "B.Cu")
		(net "FM_CPU0_PKGID1")
	)
	(segment
		(start 362.46435 -31.89605)
		(end 362.46435 -32.74695)
		(width 0.10795)
		(layer "B.Cu")
		(net "FM_CPU0_PKGID1")
	)
	(segment
		(start 240.975388 -87.765636)
		(end 240.550446 -87.765636)
		(width 0.0889)
		(layer "B.Cu")
		(net "FM_CPU0_PKGID1")
	)
	(segment
		(start 238.478314 -88.211914)
		(end 237.995714 -88.211914)
		(width 0.0889)
		(layer "B.Cu")
		(net "FM_CPU0_PKGID1")
	)
	(segment
		(start 350.914462 -48.8569)
		(end 339.961982 -48.8569)
		(width 0.10795)
		(layer "B.Cu")
		(net "FM_CPU0_PKGID1")
	)
	(segment
		(start 330.962762 -57.916318)
		(end 329.356466 -57.916318)
		(width 0.10795)
		(layer "B.Cu")
		(net "FM_CPU0_PKGID1")
	)
	(segment
		(start 362.712 -31.6484)
		(end 362.46435 -31.89605)
		(width 0.10795)
		(layer "B.Cu")
		(net "FM_CPU0_PKGID1")
	)
	(segment
		(start 236.242606 -88.230964)
		(end 235.847128 -87.835486)
		(width 0.0889)
		(layer "B.Cu")
		(net "FM_CPU0_PKGID1")
	)
	(segment
		(start 231.83596 -88.759284)
		(end 230.298244 -90.297)
		(width 0.10795)
		(layer "B.Cu")
		(net "FM_CPU0_PKGID1")
	)
	(segment
		(start 354.231956 -39.42715)
		(end 354.231956 -45.539406)
		(width 0.10795)
		(layer "B.Cu")
		(net "FM_CPU0_PKGID1")
	)
	(segment
		(start 362.977176 -31.383224)
		(end 362.712 -31.6484)
		(width 0.10795)
		(layer "B.Cu")
		(net "FM_CPU0_PKGID1")
	)
	(segment
		(start 243.779548 -87.862664)
		(end 243.779548 -87.594186)
		(width 0.0889)
		(layer "B.Cu")
		(net "FM_CPU0_PKGID1")
	)
	(segment
		(start 234.40771 -88.37549)
		(end 234.103164 -88.680036)
		(width 0.0889)
		(layer "B.Cu")
		(net "FM_CPU0_PKGID1")
	)
	(segment
		(start 380.015242 -33.76168)
		(end 379.361954 -33.76168)
		(width 0.10795)
		(layer "B.Cu")
		(net "FM_CPU0_PKGID1")
	)
	(segment
		(start 234.829858 -88.37549)
		(end 234.40771 -88.37549)
		(width 0.0889)
		(layer "B.Cu")
		(net "FM_CPU0_PKGID1")
	)
	(segment
		(start 329.356466 -57.916318)
		(end 328.801222 -57.916318)
		(width 0.10795)
		(layer "B.Cu")
		(net "FM_CPU0_PKGID1")
	)
	(segment
		(start 381.070358 -34.816796)
		(end 380.015242 -33.76168)
		(width 0.10795)
		(layer "B.Cu")
		(net "FM_CPU0_PKGID1")
	)
	(segment
		(start 362.46435 -32.74695)
		(end 356.758748 -38.452552)
		(width 0.10795)
		(layer "B.Cu")
		(net "FM_CPU0_PKGID1")
	)
	(segment
		(start 332.075282 -56.803798)
		(end 330.962762 -57.916318)
		(width 0.10795)
		(layer "B.Cu")
		(net "FM_CPU0_PKGID1")
	)
	(segment
		(start 238.865918 -87.82431)
		(end 238.478314 -88.211914)
		(width 0.0889)
		(layer "B.Cu")
		(net "FM_CPU0_PKGID1")
	)
	(segment
		(start 233.515916 -88.680036)
		(end 233.30408 -88.4682)
		(width 0.0889)
		(layer "B.Cu")
		(net "FM_CPU0_PKGID1")
	)
	(segment
		(start 243.120926 -87.352886)
		(end 242.703604 -87.770208)
		(width 0.0889)
		(layer "B.Cu")
		(net "FM_CPU0_PKGID1")
	)
	(segment
		(start 328.62012 -58.91022)
		(end 328.11974 -59.4106)
		(width 0.10795)
		(layer "B.Cu")
		(net "FM_CPU0_PKGID1")
	)
	(segment
		(start 233.30408 -88.4682)
		(end 233.20502 -88.36914)
		(width 0.1016)
		(layer "B.Cu")
		(net "FM_CPU0_PKGID1")
	)
	(segment
		(start 377.43257 -31.832296)
		(end 377.43257 -29.373576)
		(width 0.10795)
		(layer "B.Cu")
		(net "FM_CPU0_PKGID1")
	)
	(segment
		(start 383.96164 -35.18154)
		(end 383.596896 -34.816796)
		(width 0.10795)
		(layer "B.Cu")
		(net "FM_CPU0_PKGID1")
	)
	(segment
		(start 379.361954 -33.76168)
		(end 377.43257 -31.832296)
		(width 0.10795)
		(layer "B.Cu")
		(net "FM_CPU0_PKGID1")
	)
	(segment
		(start 328.11974 -59.4106)
		(end 327.3552 -59.4106)
		(width 0.10795)
		(layer "B.Cu")
		(net "FM_CPU0_PKGID1")
	)
	(segment
		(start 243.779548 -87.594186)
		(end 243.538248 -87.352886)
		(width 0.0889)
		(layer "B.Cu")
		(net "FM_CPU0_PKGID1")
	)
	(segment
		(start 336.97545 -54.342538)
		(end 336.501994 -54.815994)
		(width 0.10795)
		(layer "B.Cu")
		(net "FM_CPU0_PKGID1")
	)
	(segment
		(start 328.62012 -58.09742)
		(end 328.62012 -58.91022)
		(width 0.10795)
		(layer "B.Cu")
		(net "FM_CPU0_PKGID1")
	)
	(segment
		(start 356.758748 -38.452552)
		(end 355.206554 -38.452552)
		(width 0.10795)
		(layer "B.Cu")
		(net "FM_CPU0_PKGID1")
	)
	(segment
		(start 237.551722 -87.767922)
		(end 237.072424 -87.767922)
		(width 0.0889)
		(layer "B.Cu")
		(net "FM_CPU0_PKGID1")
	)
	(segment
		(start 235.847128 -87.835486)
		(end 235.369862 -87.835486)
		(width 0.0889)
		(layer "B.Cu")
		(net "FM_CPU0_PKGID1")
	)
	(segment
		(start 354.231956 -45.539406)
		(end 350.914462 -48.8569)
		(width 0.10795)
		(layer "B.Cu")
		(net "FM_CPU0_PKGID1")
	)
	(segment
		(start 363.941868 -31.383224)
		(end 362.977176 -31.383224)
		(width 0.10795)
		(layer "B.Cu")
		(net "FM_CPU0_PKGID1")
	)
	(segment
		(start 241.890296 -88.193118)
		(end 241.40287 -88.193118)
		(width 0.0889)
		(layer "B.Cu")
		(net "FM_CPU0_PKGID1")
	)
	(segment
		(start 232.81386 -88.36914)
		(end 232.738422 -88.444578)
		(width 0.1016)
		(layer "B.Cu")
		(net "FM_CPU0_PKGID1")
	)
	(segment
		(start 243.538248 -87.352886)
		(end 243.120926 -87.352886)
		(width 0.0889)
		(layer "B.Cu")
		(net "FM_CPU0_PKGID1")
	)
	(segment
		(start 237.995714 -88.211914)
		(end 237.551722 -87.767922)
		(width 0.0889)
		(layer "B.Cu")
		(net "FM_CPU0_PKGID1")
	)
	(segment
		(start 335.86547 -56.803798)
		(end 332.075282 -56.803798)
		(width 0.10795)
		(layer "B.Cu")
		(net "FM_CPU0_PKGID1")
	)
	(segment
		(start 383.596896 -34.816796)
		(end 381.070358 -34.816796)
		(width 0.10795)
		(layer "B.Cu")
		(net "FM_CPU0_PKGID1")
	)
	(segment
		(start 336.501994 -56.167274)
		(end 335.86547 -56.803798)
		(width 0.10795)
		(layer "B.Cu")
		(net "FM_CPU0_PKGID1")
	)
	(segment
		(start 236.609382 -88.230964)
		(end 236.242606 -88.230964)
		(width 0.0889)
		(layer "B.Cu")
		(net "FM_CPU0_PKGID1")
	)
	(segment
		(start 232.423716 -88.759284)
		(end 231.83596 -88.759284)
		(width 0.10795)
		(layer "B.Cu")
		(net "FM_CPU0_PKGID1")
	)
	(segment
		(start 377.43257 -29.373576)
		(end 375.670572 -27.611578)
		(width 0.10795)
		(layer "B.Cu")
		(net "FM_CPU0_PKGID1")
	)
	(segment
		(start 240.125758 -88.190324)
		(end 239.632998 -88.190324)
		(width 0.0889)
		(layer "B.Cu")
		(net "FM_CPU0_PKGID1")
	)
	(segment
		(start 244.197124 -88.28024)
		(end 243.779548 -87.862664)
		(width 0.0889)
		(layer "B.Cu")
		(net "FM_CPU0_PKGID1")
	)
	(segment
		(start 240.550446 -87.765636)
		(end 240.125758 -88.190324)
		(width 0.0889)
		(layer "B.Cu")
		(net "FM_CPU0_PKGID1")
	)
	(segment
		(start 336.501994 -54.815994)
		(end 336.501994 -56.167274)
		(width 0.10795)
		(layer "B.Cu")
		(net "FM_CPU0_PKGID1")
	)
	(segment
		(start 241.40287 -88.193118)
		(end 240.975388 -87.765636)
		(width 0.0889)
		(layer "B.Cu")
		(net "FM_CPU0_PKGID1")
	)
	(segment
		(start 371.37721 -29.994352)
		(end 365.33074 -29.994352)
		(width 0.10795)
		(layer "B.Cu")
		(net "FM_CPU0_PKGID1")
	)
	(segment
		(start 336.97545 -51.843432)
		(end 336.97545 -54.342538)
		(width 0.10795)
		(layer "B.Cu")
		(net "FM_CPU0_PKGID1")
	)
	(segment
		(start 242.703604 -87.770208)
		(end 242.313206 -87.770208)
		(width 0.0889)
		(layer "B.Cu")
		(net "FM_CPU0_PKGID1")
	)
	(segment
		(start 239.266984 -87.82431)
		(end 238.865918 -87.82431)
		(width 0.0889)
		(layer "B.Cu")
		(net "FM_CPU0_PKGID1")
	)
	(segment
		(start 293.0144 -87.6173)
		(end 292.62959 -88.00211)
		(width 0.0889)
		(layer "In2.Cu")
		(net "FM_CPU0_PKGID1")
	)
	(segment
		(start 268.524482 -89.36609)
		(end 267.376656 -89.36609)
		(width 0.0889)
		(layer "In2.Cu")
		(net "FM_CPU0_PKGID1")
	)
	(segment
		(start 250.832112 -86.891114)
		(end 250.530614 -87.192612)
		(width 0.0889)
		(layer "In2.Cu")
		(net "FM_CPU0_PKGID1")
	)
	(segment
		(start 292.20414 -88.00211)
		(end 291.84473 -87.6427)
		(width 0.0889)
		(layer "In2.Cu")
		(net "FM_CPU0_PKGID1")
	)
	(segment
		(start 314.0202 -73.928732)
		(end 314.0202 -81.780888)
		(width 0.089408)
		(layer "In2.Cu")
		(net "FM_CPU0_PKGID1")
	)
	(segment
		(start 272.970498 -89.880186)
		(end 272.900648 -89.759282)
		(width 0.0889)
		(layer "In2.Cu")
		(net "FM_CPU0_PKGID1")
	)
	(segment
		(start 305.0286 -86.579456)
		(end 304.603658 -86.154514)
		(width 0.0889)
		(layer "In2.Cu")
		(net "FM_CPU0_PKGID1")
	)
	(segment
		(start 264.289286 -89.565988)
		(end 264.285984 -89.560146)
		(width 0.0889)
		(layer "In2.Cu")
		(net "FM_CPU0_PKGID1")
	)
	(segment
		(start 250.041664 -87.192612)
		(end 249.740166 -86.891114)
		(width 0.0889)
		(layer "In2.Cu")
		(net "FM_CPU0_PKGID1")
	)
	(segment
		(start 306.243482 -85.911182)
		(end 305.575208 -86.579456)
		(width 0.0889)
		(layer "In2.Cu")
		(net "FM_CPU0_PKGID1")
	)
	(segment
		(start 251.563124 -87.192612)
		(end 251.261626 -86.891114)
		(width 0.0889)
		(layer "In2.Cu")
		(net "FM_CPU0_PKGID1")
	)
	(segment
		(start 302.057562 -87.507064)
		(end 301.538894 -87.507064)
		(width 0.0889)
		(layer "In2.Cu")
		(net "FM_CPU0_PKGID1")
	)
	(segment
		(start 298.698412 -87.700612)
		(end 297.998388 -87.700612)
		(width 0.0889)
		(layer "In2.Cu")
		(net "FM_CPU0_PKGID1")
	)
	(segment
		(start 257.948176 -88.87079)
		(end 257.91541 -88.87079)
		(width 0.0889)
		(layer "In2.Cu")
		(net "FM_CPU0_PKGID1")
	)
	(segment
		(start 252.97892 -86.891114)
		(end 252.617224 -86.891114)
		(width 0.0889)
		(layer "In2.Cu")
		(net "FM_CPU0_PKGID1")
	)
	(segment
		(start 267.376402 -89.365836)
		(end 267.36548 -89.365836)
		(width 0.0889)
		(layer "In2.Cu")
		(net "FM_CPU0_PKGID1")
	)
	(segment
		(start 260.53034 -89.365836)
		(end 260.48716 -89.365836)
		(width 0.0889)
		(layer "In2.Cu")
		(net "FM_CPU0_PKGID1")
	)
	(segment
		(start 288.38525 -87.6173)
		(end 287.8201 -87.6173)
		(width 0.0889)
		(layer "In2.Cu")
		(net "FM_CPU0_PKGID1")
	)
	(segment
		(start 296.946066 -87.676736)
		(end 296.666412 -87.676736)
		(width 0.0889)
		(layer "In2.Cu")
		(net "FM_CPU0_PKGID1")
	)
	(segment
		(start 256.231136 -87.88019)
		(end 256.19837 -87.88019)
		(width 0.0889)
		(layer "In2.Cu")
		(net "FM_CPU0_PKGID1")
	)
	(segment
		(start 247.8278 -86.891114)
		(end 247.466104 -86.891114)
		(width 0.0889)
		(layer "In2.Cu")
		(net "FM_CPU0_PKGID1")
	)
	(segment
		(start 293.9796 -87.6173)
		(end 293.0144 -87.6173)
		(width 0.0889)
		(layer "In2.Cu")
		(net "FM_CPU0_PKGID1")
	)
	(segment
		(start 292.62959 -88.00211)
		(end 292.20414 -88.00211)
		(width 0.0889)
		(layer "In2.Cu")
		(net "FM_CPU0_PKGID1")
	)
	(segment
		(start 250.530614 -87.192612)
		(end 250.041664 -87.192612)
		(width 0.0889)
		(layer "In2.Cu")
		(net "FM_CPU0_PKGID1")
	)
	(segment
		(start 304.180494 -86.154514)
		(end 303.71796 -86.617048)
		(width 0.0889)
		(layer "In2.Cu")
		(net "FM_CPU0_PKGID1")
	)
	(segment
		(start 261.382256 -88.87079)
		(end 261.352284 -88.87079)
		(width 0.0889)
		(layer "In2.Cu")
		(net "FM_CPU0_PKGID1")
	)
	(segment
		(start 287.8201 -87.6173)
		(end 287.43529 -88.00211)
		(width 0.0889)
		(layer "In2.Cu")
		(net "FM_CPU0_PKGID1")
	)
	(segment
		(start 284.84068 -87.700612)
		(end 284.015688 -87.700612)
		(width 0.0889)
		(layer "In2.Cu")
		(net "FM_CPU0_PKGID1")
	)
	(segment
		(start 280.371804 -89.184734)
		(end 280.339038 -89.184734)
		(width 0.0889)
		(layer "In2.Cu")
		(net "FM_CPU0_PKGID1")
	)
	(segment
		(start 297.27144 -88.00211)
		(end 296.946066 -87.676736)
		(width 0.0889)
		(layer "In2.Cu")
		(net "FM_CPU0_PKGID1")
	)
	(segment
		(start 302.8442 -87.1093)
		(end 302.455834 -87.1093)
		(width 0.0889)
		(layer "In2.Cu")
		(net "FM_CPU0_PKGID1")
	)
	(segment
		(start 259.665216 -88.87079)
		(end 259.635244 -88.87079)
		(width 0.0889)
		(layer "In2.Cu")
		(net "FM_CPU0_PKGID1")
	)
	(segment
		(start 310.317388 -85.4837)
		(end 306.670964 -85.4837)
		(width 0.089408)
		(layer "In2.Cu")
		(net "FM_CPU0_PKGID1")
	)
	(segment
		(start 289.648392 -87.6808)
		(end 289.327082 -88.00211)
		(width 0.0889)
		(layer "In2.Cu")
		(net "FM_CPU0_PKGID1")
	)
	(segment
		(start 269.019274 -89.860882)
		(end 268.524482 -89.36609)
		(width 0.0889)
		(layer "In2.Cu")
		(net "FM_CPU0_PKGID1")
	)
	(segment
		(start 251.261626 -86.891114)
		(end 250.832112 -86.891114)
		(width 0.0889)
		(layer "In2.Cu")
		(net "FM_CPU0_PKGID1")
	)
	(segment
		(start 258.8133 -89.365836)
		(end 258.77012 -89.365836)
		(width 0.0889)
		(layer "In2.Cu")
		(net "FM_CPU0_PKGID1")
	)
	(segment
		(start 281.699208 -88.689688)
		(end 281.193748 -88.689688)
		(width 0.0889)
		(layer "In2.Cu")
		(net "FM_CPU0_PKGID1")
	)
	(segment
		(start 319.996566 -67.952366)
		(end 314.0202 -73.928732)
		(width 0.089408)
		(layer "In2.Cu")
		(net "FM_CPU0_PKGID1")
	)
	(segment
		(start 275.719286 -89.866216)
		(end 275.711158 -89.88044)
		(width 0.0889)
		(layer "In2.Cu")
		(net "FM_CPU0_PKGID1")
	)
	(segment
		(start 314.0202 -81.780888)
		(end 310.317388 -85.4837)
		(width 0.089408)
		(layer "In2.Cu")
		(net "FM_CPU0_PKGID1")
	)
	(segment
		(start 294.1574 -87.4395)
		(end 293.9796 -87.6173)
		(width 0.0889)
		(layer "In2.Cu")
		(net "FM_CPU0_PKGID1")
	)
	(segment
		(start 287.43529 -88.00211)
		(end 287.05302 -88.00211)
		(width 0.0889)
		(layer "In2.Cu")
		(net "FM_CPU0_PKGID1")
	)
	(segment
		(start 297.69689 -88.00211)
		(end 297.27144 -88.00211)
		(width 0.0889)
		(layer "In2.Cu")
		(net "FM_CPU0_PKGID1")
	)
	(segment
		(start 252.617224 -86.891114)
		(end 252.315726 -87.192612)
		(width 0.0889)
		(layer "In2.Cu")
		(net "FM_CPU0_PKGID1")
	)
	(segment
		(start 269.947644 -89.860628)
		(end 269.94739 -89.860882)
		(width 0.0889)
		(layer "In2.Cu")
		(net "FM_CPU0_PKGID1")
	)
	(segment
		(start 305.575208 -86.579456)
		(end 305.0286 -86.579456)
		(width 0.0889)
		(layer "In2.Cu")
		(net "FM_CPU0_PKGID1")
	)
	(segment
		(start 269.94739 -89.860882)
		(end 269.019274 -89.860882)
		(width 0.0889)
		(layer "In2.Cu")
		(net "FM_CPU0_PKGID1")
	)
	(segment
		(start 290.16579 -87.6808)
		(end 289.648392 -87.6808)
		(width 0.0889)
		(layer "In2.Cu")
		(net "FM_CPU0_PKGID1")
	)
	(segment
		(start 286.557974 -87.507064)
		(end 286.1945 -87.507064)
		(width 0.0889)
		(layer "In2.Cu")
		(net "FM_CPU0_PKGID1")
	)
	(segment
		(start 289.327082 -88.00211)
		(end 288.77006 -88.00211)
		(width 0.0889)
		(layer "In2.Cu")
		(net "FM_CPU0_PKGID1")
	)
	(segment
		(start 297.998388 -87.700612)
		(end 297.69689 -88.00211)
		(width 0.0889)
		(layer "In2.Cu")
		(net "FM_CPU0_PKGID1")
	)
	(segment
		(start 248.129298 -87.192612)
		(end 247.8278 -86.891114)
		(width 0.0889)
		(layer "In2.Cu")
		(net "FM_CPU0_PKGID1")
	)
	(segment
		(start 262.236966 -89.365836)
		(end 262.2042 -89.365836)
		(width 0.0889)
		(layer "In2.Cu")
		(net "FM_CPU0_PKGID1")
	)
	(segment
		(start 248.654824 -87.192612)
		(end 248.129298 -87.192612)
		(width 0.0889)
		(layer "In2.Cu")
		(net "FM_CPU0_PKGID1")
	)
	(segment
		(start 249.740166 -86.891114)
		(end 248.956322 -86.891114)
		(width 0.0889)
		(layer "In2.Cu")
		(net "FM_CPU0_PKGID1")
	)
	(segment
		(start 245.281704 -87.19566)
		(end 244.197124 -88.28024)
		(width 0.0889)
		(layer "In2.Cu")
		(net "FM_CPU0_PKGID1")
	)
	(segment
		(start 304.603658 -86.154514)
		(end 304.180494 -86.154514)
		(width 0.0889)
		(layer "In2.Cu")
		(net "FM_CPU0_PKGID1")
	)
	(segment
		(start 287.05302 -88.00211)
		(end 286.557974 -87.507064)
		(width 0.0889)
		(layer "In2.Cu")
		(net "FM_CPU0_PKGID1")
	)
	(segment
		(start 301.179992 -87.148162)
		(end 300.71822 -87.148162)
		(width 0.0889)
		(layer "In2.Cu")
		(net "FM_CPU0_PKGID1")
	)
	(segment
		(start 271.210786 -89.661238)
		(end 271.011396 -89.860628)
		(width 0.0889)
		(layer "In2.Cu")
		(net "FM_CPU0_PKGID1")
	)
	(segment
		(start 306.670964 -85.4837)
		(end 306.243482 -85.911182)
		(width 0.089408)
		(layer "In2.Cu")
		(net "FM_CPU0_PKGID1")
	)
	(segment
		(start 281.882596 -88.5063)
		(end 281.699208 -88.689688)
		(width 0.0889)
		(layer "In2.Cu")
		(net "FM_CPU0_PKGID1")
	)
	(segment
		(start 299.0342 -88.0364)
		(end 298.698412 -87.700612)
		(width 0.0889)
		(layer "In2.Cu")
		(net "FM_CPU0_PKGID1")
	)
	(segment
		(start 288.77006 -88.00211)
		(end 288.38525 -87.6173)
		(width 0.0889)
		(layer "In2.Cu")
		(net "FM_CPU0_PKGID1")
	)
	(segment
		(start 284.015688 -87.700612)
		(end 283.21 -88.5063)
		(width 0.0889)
		(layer "In2.Cu")
		(net "FM_CPU0_PKGID1")
	)
	(segment
		(start 290.4871 -88.00211)
		(end 290.16579 -87.6808)
		(width 0.0889)
		(layer "In2.Cu")
		(net "FM_CPU0_PKGID1")
	)
	(segment
		(start 303.336452 -86.617048)
		(end 302.8442 -87.1093)
		(width 0.0889)
		(layer "In2.Cu")
		(net "FM_CPU0_PKGID1")
	)
	(segment
		(start 271.011396 -89.860628)
		(end 269.947644 -89.860628)
		(width 0.0889)
		(layer "In2.Cu")
		(net "FM_CPU0_PKGID1")
	)
	(segment
		(start 266.535916 -89.86139)
		(end 266.500356 -89.86139)
		(width 0.0889)
		(layer "In2.Cu")
		(net "FM_CPU0_PKGID1")
	)
	(segment
		(start 319.996566 -66.287142)
		(end 319.996566 -67.952366)
		(width 0.089408)
		(layer "In2.Cu")
		(net "FM_CPU0_PKGID1")
	)
	(segment
		(start 299.875956 -87.5284)
		(end 299.367956 -88.0364)
		(width 0.0889)
		(layer "In2.Cu")
		(net "FM_CPU0_PKGID1")
	)
	(segment
		(start 247.466104 -86.891114)
		(end 247.161558 -87.19566)
		(width 0.0889)
		(layer "In2.Cu")
		(net "FM_CPU0_PKGID1")
	)
	(segment
		(start 283.21 -88.5063)
		(end 281.882596 -88.5063)
		(width 0.0889)
		(layer "In2.Cu")
		(net "FM_CPU0_PKGID1")
	)
	(segment
		(start 285.336234 -87.205058)
		(end 284.84068 -87.700612)
		(width 0.0889)
		(layer "In2.Cu")
		(net "FM_CPU0_PKGID1")
	)
	(segment
		(start 300.337982 -87.5284)
		(end 299.875956 -87.5284)
		(width 0.0889)
		(layer "In2.Cu")
		(net "FM_CPU0_PKGID1")
	)
	(segment
		(start 247.161558 -87.19566)
		(end 245.281704 -87.19566)
		(width 0.0889)
		(layer "In2.Cu")
		(net "FM_CPU0_PKGID1")
	)
	(segment
		(start 257.085846 -88.375236)
		(end 257.05308 -88.375236)
		(width 0.0889)
		(layer "In2.Cu")
		(net "FM_CPU0_PKGID1")
	)
	(segment
		(start 267.376656 -89.36609)
		(end 267.376402 -89.365836)
		(width 0.0889)
		(layer "In2.Cu")
		(net "FM_CPU0_PKGID1")
	)
	(segment
		(start 254.514096 -86.88959)
		(end 254.335534 -86.88959)
		(width 0.0889)
		(layer "In2.Cu")
		(net "FM_CPU0_PKGID1")
	)
	(segment
		(start 299.367956 -88.0364)
		(end 299.0342 -88.0364)
		(width 0.0889)
		(layer "In2.Cu")
		(net "FM_CPU0_PKGID1")
	)
	(segment
		(start 254.335534 -86.88959)
		(end 254.032512 -87.192612)
		(width 0.0889)
		(layer "In2.Cu")
		(net "FM_CPU0_PKGID1")
	)
	(segment
		(start 279.509474 -89.680288)
		(end 279.476708 -89.680288)
		(width 0.0889)
		(layer "In2.Cu")
		(net "FM_CPU0_PKGID1")
	)
	(segment
		(start 300.71822 -87.148162)
		(end 300.337982 -87.5284)
		(width 0.0889)
		(layer "In2.Cu")
		(net "FM_CPU0_PKGID1")
	)
	(segment
		(start 291.17671 -87.6427)
		(end 290.8173 -88.00211)
		(width 0.0889)
		(layer "In2.Cu")
		(net "FM_CPU0_PKGID1")
	)
	(segment
		(start 296.429176 -87.4395)
		(end 294.1574 -87.4395)
		(width 0.0889)
		(layer "In2.Cu")
		(net "FM_CPU0_PKGID1")
	)
	(segment
		(start 278.654764 -90.175334)
		(end 278.611584 -90.175334)
		(width 0.0889)
		(layer "In2.Cu")
		(net "FM_CPU0_PKGID1")
	)
	(segment
		(start 302.455834 -87.1093)
		(end 302.057562 -87.507064)
		(width 0.0889)
		(layer "In2.Cu")
		(net "FM_CPU0_PKGID1")
	)
	(segment
		(start 264.818876 -89.86139)
		(end 264.783316 -89.86139)
		(width 0.0889)
		(layer "In2.Cu")
		(net "FM_CPU0_PKGID1")
	)
	(segment
		(start 248.956322 -86.891114)
		(end 248.654824 -87.192612)
		(width 0.0889)
		(layer "In2.Cu")
		(net "FM_CPU0_PKGID1")
	)
	(segment
		(start 254.032512 -87.192612)
		(end 253.280418 -87.192612)
		(width 0.0889)
		(layer "In2.Cu")
		(net "FM_CPU0_PKGID1")
	)
	(segment
		(start 255.368806 -87.384636)
		(end 255.33604 -87.384636)
		(width 0.0889)
		(layer "In2.Cu")
		(net "FM_CPU0_PKGID1")
	)
	(segment
		(start 272.900648 -89.759282)
		(end 272.73123 -89.661238)
		(width 0.0889)
		(layer "In2.Cu")
		(net "FM_CPU0_PKGID1")
	)
	(segment
		(start 290.8173 -88.00211)
		(end 290.4871 -88.00211)
		(width 0.0889)
		(layer "In2.Cu")
		(net "FM_CPU0_PKGID1")
	)
	(segment
		(start 301.538894 -87.507064)
		(end 301.179992 -87.148162)
		(width 0.0889)
		(layer "In2.Cu")
		(net "FM_CPU0_PKGID1")
	)
	(segment
		(start 327.3552 -59.4106)
		(end 326.9996 -59.7662)
		(width 0.089408)
		(layer "In2.Cu")
		(net "FM_CPU0_PKGID1")
	)
	(segment
		(start 272.73123 -89.661238)
		(end 271.210786 -89.661238)
		(width 0.0889)
		(layer "In2.Cu")
		(net "FM_CPU0_PKGID1")
	)
	(segment
		(start 326.9996 -59.7662)
		(end 326.517508 -59.7662)
		(width 0.089408)
		(layer "In2.Cu")
		(net "FM_CPU0_PKGID1")
	)
	(segment
		(start 326.517508 -59.7662)
		(end 319.996566 -66.287142)
		(width 0.089408)
		(layer "In2.Cu")
		(net "FM_CPU0_PKGID1")
	)
	(segment
		(start 285.892494 -87.205058)
		(end 285.336234 -87.205058)
		(width 0.0889)
		(layer "In2.Cu")
		(net "FM_CPU0_PKGID1")
	)
	(segment
		(start 286.1945 -87.507064)
		(end 285.892494 -87.205058)
		(width 0.0889)
		(layer "In2.Cu")
		(net "FM_CPU0_PKGID1")
	)
	(segment
		(start 303.71796 -86.617048)
		(end 303.336452 -86.617048)
		(width 0.0889)
		(layer "In2.Cu")
		(net "FM_CPU0_PKGID1")
	)
	(segment
		(start 296.666412 -87.676736)
		(end 296.429176 -87.4395)
		(width 0.0889)
		(layer "In2.Cu")
		(net "FM_CPU0_PKGID1")
	)
	(segment
		(start 291.84473 -87.6427)
		(end 291.17671 -87.6427)
		(width 0.0889)
		(layer "In2.Cu")
		(net "FM_CPU0_PKGID1")
	)
	(segment
		(start 253.280418 -87.192612)
		(end 252.97892 -86.891114)
		(width 0.0889)
		(layer "In2.Cu")
		(net "FM_CPU0_PKGID1")
	)
	(segment
		(start 274.693888 -89.890854)
		(end 274.687538 -89.880186)
		(width 0.0889)
		(layer "In2.Cu")
		(net "FM_CPU0_PKGID1")
	)
	(segment
		(start 263.10209 -89.86139)
		(end 263.06653 -89.86139)
		(width 0.0889)
		(layer "In2.Cu")
		(net "FM_CPU0_PKGID1")
	)
	(segment
		(start 252.315726 -87.192612)
		(end 251.563124 -87.192612)
		(width 0.0889)
		(layer "In2.Cu")
		(net "FM_CPU0_PKGID1")
	)
	(arc
		(start 280.862024 -88.889586)
		(mid 280.65502 -89.10045)
		(end 280.371804 -89.184734)
		(width 0.0889)
		(layer "In2.Cu")
		(net "FM_CPU0_PKGID1")
	)
	(arc
		(start 266.006326 -89.565988)
		(mid 265.659616 -89.365677)
		(end 265.312906 -89.565988)
		(width 0.0889)
		(layer "In2.Cu")
		(net "FM_CPU0_PKGID1")
	)
	(arc
		(start 279.144984 -89.880186)
		(mid 278.93798 -90.09105)
		(end 278.654764 -90.175334)
		(width 0.0889)
		(layer "In2.Cu")
		(net "FM_CPU0_PKGID1")
	)
	(arc
		(start 257.91541 -88.87079)
		(mid 257.629986 -88.787323)
		(end 257.42138 -88.575388)
		(width 0.0889)
		(layer "In2.Cu")
		(net "FM_CPU0_PKGID1")
	)
	(arc
		(start 274.687538 -89.880186)
		(mid 274.340828 -89.680002)
		(end 273.994118 -89.880186)
		(width 0.0889)
		(layer "In2.Cu")
		(net "FM_CPU0_PKGID1")
	)
	(arc
		(start 261.352284 -88.87079)
		(mid 261.160642 -88.927956)
		(end 261.02056 -89.070688)
		(width 0.0889)
		(layer "In2.Cu")
		(net "FM_CPU0_PKGID1")
	)
	(arc
		(start 265.312906 -89.565988)
		(mid 265.104298 -89.77792)
		(end 264.818876 -89.86139)
		(width 0.0889)
		(layer "In2.Cu")
		(net "FM_CPU0_PKGID1")
	)
	(arc
		(start 258.2799 -89.070688)
		(mid 258.139821 -88.927952)
		(end 257.948176 -88.87079)
		(width 0.0889)
		(layer "In2.Cu")
		(net "FM_CPU0_PKGID1")
	)
	(arc
		(start 258.77012 -89.365836)
		(mid 258.486903 -89.281555)
		(end 258.2799 -89.070688)
		(width 0.0889)
		(layer "In2.Cu")
		(net "FM_CPU0_PKGID1")
	)
	(arc
		(start 262.5725 -89.565988)
		(mid 262.430817 -89.422184)
		(end 262.236966 -89.365836)
		(width 0.0889)
		(layer "In2.Cu")
		(net "FM_CPU0_PKGID1")
	)
	(arc
		(start 277.427944 -89.880186)
		(mid 276.916134 -90.175725)
		(end 276.404324 -89.880186)
		(width 0.0889)
		(layer "In2.Cu")
		(net "FM_CPU0_PKGID1")
	)
	(arc
		(start 255.70434 -87.584788)
		(mid 255.562657 -87.440984)
		(end 255.368806 -87.384636)
		(width 0.0889)
		(layer "In2.Cu")
		(net "FM_CPU0_PKGID1")
	)
	(arc
		(start 259.635244 -88.87079)
		(mid 259.443602 -88.927956)
		(end 259.30352 -89.070688)
		(width 0.0889)
		(layer "In2.Cu")
		(net "FM_CPU0_PKGID1")
	)
	(arc
		(start 260.48716 -89.365836)
		(mid 260.203943 -89.281555)
		(end 259.99694 -89.070688)
		(width 0.0889)
		(layer "In2.Cu")
		(net "FM_CPU0_PKGID1")
	)
	(arc
		(start 280.003504 -89.384886)
		(mid 279.794896 -89.596818)
		(end 279.509474 -89.680288)
		(width 0.0889)
		(layer "In2.Cu")
		(net "FM_CPU0_PKGID1")
	)
	(arc
		(start 259.30352 -89.070688)
		(mid 259.096516 -89.281552)
		(end 258.8133 -89.365836)
		(width 0.0889)
		(layer "In2.Cu")
		(net "FM_CPU0_PKGID1")
	)
	(arc
		(start 261.02056 -89.070688)
		(mid 260.813556 -89.281552)
		(end 260.53034 -89.365836)
		(width 0.0889)
		(layer "In2.Cu")
		(net "FM_CPU0_PKGID1")
	)
	(arc
		(start 256.56286 -88.080088)
		(mid 256.422781 -87.937352)
		(end 256.231136 -87.88019)
		(width 0.0889)
		(layer "In2.Cu")
		(net "FM_CPU0_PKGID1")
	)
	(arc
		(start 257.42138 -88.575388)
		(mid 257.279697 -88.431584)
		(end 257.085846 -88.375236)
		(width 0.0889)
		(layer "In2.Cu")
		(net "FM_CPU0_PKGID1")
	)
	(arc
		(start 256.19837 -87.88019)
		(mid 255.912946 -87.796723)
		(end 255.70434 -87.584788)
		(width 0.0889)
		(layer "In2.Cu")
		(net "FM_CPU0_PKGID1")
	)
	(arc
		(start 254.84582 -87.089488)
		(mid 254.705741 -86.946752)
		(end 254.514096 -86.88959)
		(width 0.0889)
		(layer "In2.Cu")
		(net "FM_CPU0_PKGID1")
	)
	(arc
		(start 255.33604 -87.384636)
		(mid 255.052823 -87.300355)
		(end 254.84582 -87.089488)
		(width 0.0889)
		(layer "In2.Cu")
		(net "FM_CPU0_PKGID1")
	)
	(arc
		(start 257.05308 -88.375236)
		(mid 256.769863 -88.290955)
		(end 256.56286 -88.080088)
		(width 0.0889)
		(layer "In2.Cu")
		(net "FM_CPU0_PKGID1")
	)
	(arc
		(start 263.06653 -89.86139)
		(mid 262.781106 -89.777923)
		(end 262.5725 -89.565988)
		(width 0.0889)
		(layer "In2.Cu")
		(net "FM_CPU0_PKGID1")
	)
	(arc
		(start 267.029946 -89.565988)
		(mid 266.821338 -89.77792)
		(end 266.535916 -89.86139)
		(width 0.0889)
		(layer "In2.Cu")
		(net "FM_CPU0_PKGID1")
	)
	(arc
		(start 279.476708 -89.680288)
		(mid 279.285066 -89.737454)
		(end 279.144984 -89.880186)
		(width 0.0889)
		(layer "In2.Cu")
		(net "FM_CPU0_PKGID1")
	)
	(arc
		(start 281.193748 -88.689688)
		(mid 281.002106 -88.746854)
		(end 280.862024 -88.889586)
		(width 0.0889)
		(layer "In2.Cu")
		(net "FM_CPU0_PKGID1")
	)
	(arc
		(start 266.500356 -89.86139)
		(mid 266.214932 -89.777923)
		(end 266.006326 -89.565988)
		(width 0.0889)
		(layer "In2.Cu")
		(net "FM_CPU0_PKGID1")
	)
	(arc
		(start 267.36548 -89.365836)
		(mid 267.17163 -89.422186)
		(end 267.029946 -89.565988)
		(width 0.0889)
		(layer "In2.Cu")
		(net "FM_CPU0_PKGID1")
	)
	(arc
		(start 264.783316 -89.86139)
		(mid 264.497892 -89.777923)
		(end 264.289286 -89.565988)
		(width 0.0889)
		(layer "In2.Cu")
		(net "FM_CPU0_PKGID1")
	)
	(arc
		(start 278.121364 -89.880186)
		(mid 277.774654 -89.680002)
		(end 277.427944 -89.880186)
		(width 0.0889)
		(layer "In2.Cu")
		(net "FM_CPU0_PKGID1")
	)
	(arc
		(start 263.59612 -89.565988)
		(mid 263.387512 -89.77792)
		(end 263.10209 -89.86139)
		(width 0.0889)
		(layer "In2.Cu")
		(net "FM_CPU0_PKGID1")
	)
	(arc
		(start 262.2042 -89.365836)
		(mid 261.920983 -89.281555)
		(end 261.71398 -89.070688)
		(width 0.0889)
		(layer "In2.Cu")
		(net "FM_CPU0_PKGID1")
	)
	(arc
		(start 259.99694 -89.070688)
		(mid 259.856861 -88.927952)
		(end 259.665216 -88.87079)
		(width 0.0889)
		(layer "In2.Cu")
		(net "FM_CPU0_PKGID1")
	)
	(arc
		(start 275.711158 -89.88044)
		(mid 275.205447 -90.175821)
		(end 274.693888 -89.890854)
		(width 0.0889)
		(layer "In2.Cu")
		(net "FM_CPU0_PKGID1")
	)
	(arc
		(start 276.404324 -89.880186)
		(mid 276.065759 -89.680085)
		(end 275.719286 -89.866216)
		(width 0.0889)
		(layer "In2.Cu")
		(net "FM_CPU0_PKGID1")
	)
	(arc
		(start 280.339038 -89.184734)
		(mid 280.145188 -89.241084)
		(end 280.003504 -89.384886)
		(width 0.0889)
		(layer "In2.Cu")
		(net "FM_CPU0_PKGID1")
	)
	(arc
		(start 278.611584 -90.175334)
		(mid 278.328367 -90.091053)
		(end 278.121364 -89.880186)
		(width 0.0889)
		(layer "In2.Cu")
		(net "FM_CPU0_PKGID1")
	)
	(arc
		(start 261.71398 -89.070688)
		(mid 261.573901 -88.927952)
		(end 261.382256 -88.87079)
		(width 0.0889)
		(layer "In2.Cu")
		(net "FM_CPU0_PKGID1")
	)
	(arc
		(start 273.994118 -89.880186)
		(mid 273.482308 -90.175725)
		(end 272.970498 -89.880186)
		(width 0.0889)
		(layer "In2.Cu")
		(net "FM_CPU0_PKGID1")
	)
	(arc
		(start 264.285984 -89.560146)
		(mid 263.939411 -89.365796)
		(end 263.59612 -89.565988)
		(width 0.0889)
		(layer "In2.Cu")
		(net "FM_CPU0_PKGID1")
	)
	(segment
		(start 380.0856 -70.0024)
		(end 378.3838 -71.7042)
		(width 0.089408)
		(layer "In9.Cu")
		(net "FM_CPU0_PKGID1")
	)
	(segment
		(start 383.580132 -38.580568)
		(end 383.452624 -38.708076)
		(width 0.089408)
		(layer "In9.Cu")
		(net "FM_CPU0_PKGID1")
	)
	(segment
		(start 383.629408 -55.059834)
		(end 383.629408 -55.795418)
		(width 0.089408)
		(layer "In9.Cu")
		(net "FM_CPU0_PKGID1")
	)
	(segment
		(start 381.683768 -65.044828)
		(end 380.848616 -65.87998)
		(width 0.089408)
		(layer "In9.Cu")
		(net "FM_CPU0_PKGID1")
	)
	(segment
		(start 384.114294 -45.864272)
		(end 383.106422 -46.872144)
		(width 0.089408)
		(layer "In9.Cu")
		(net "FM_CPU0_PKGID1")
	)
	(segment
		(start 378.3838 -71.7042)
		(end 378.3838 -72.057514)
		(width 0.089408)
		(layer "In9.Cu")
		(net "FM_CPU0_PKGID1")
	)
	(segment
		(start 383.629662 -55.05958)
		(end 383.629408 -55.059834)
		(width 0.089408)
		(layer "In9.Cu")
		(net "FM_CPU0_PKGID1")
	)
	(segment
		(start 380.848616 -68.342256)
		(end 380.5936 -68.597272)
		(width 0.089408)
		(layer "In9.Cu")
		(net "FM_CPU0_PKGID1")
	)
	(segment
		(start 378.3838 -72.057514)
		(end 377.746006 -72.695308)
		(width 0.089408)
		(layer "In9.Cu")
		(net "FM_CPU0_PKGID1")
	)
	(segment
		(start 381.683768 -64.313562)
		(end 381.683768 -65.044828)
		(width 0.089408)
		(layer "In9.Cu")
		(net "FM_CPU0_PKGID1")
	)
	(segment
		(start 382.404874 -63.592456)
		(end 381.683768 -64.313562)
		(width 0.089408)
		(layer "In9.Cu")
		(net "FM_CPU0_PKGID1")
	)
	(segment
		(start 383.452624 -38.708076)
		(end 383.452624 -40.917368)
		(width 0.089408)
		(layer "In9.Cu")
		(net "FM_CPU0_PKGID1")
	)
	(segment
		(start 383.186432 -36.389818)
		(end 383.580132 -36.783518)
		(width 0.089408)
		(layer "In9.Cu")
		(net "FM_CPU0_PKGID1")
	)
	(segment
		(start 383.629662 -54.859428)
		(end 383.629662 -55.05958)
		(width 0.089408)
		(layer "In9.Cu")
		(net "FM_CPU0_PKGID1")
	)
	(segment
		(start 383.629408 -55.795418)
		(end 383.171954 -56.252872)
		(width 0.089408)
		(layer "In9.Cu")
		(net "FM_CPU0_PKGID1")
	)
	(segment
		(start 380.5936 -68.597272)
		(end 380.5936 -69.7484)
		(width 0.089408)
		(layer "In9.Cu")
		(net "FM_CPU0_PKGID1")
	)
	(segment
		(start 380.848616 -65.87998)
		(end 380.848616 -68.342256)
		(width 0.089408)
		(layer "In9.Cu")
		(net "FM_CPU0_PKGID1")
	)
	(segment
		(start 383.96164 -35.18154)
		(end 383.765298 -35.18154)
		(width 0.089408)
		(layer "In9.Cu")
		(net "FM_CPU0_PKGID1")
	)
	(segment
		(start 383.580132 -36.783518)
		(end 383.580132 -38.580568)
		(width 0.089408)
		(layer "In9.Cu")
		(net "FM_CPU0_PKGID1")
	)
	(segment
		(start 382.404874 -60.335922)
		(end 382.404874 -63.592456)
		(width 0.089408)
		(layer "In9.Cu")
		(net "FM_CPU0_PKGID1")
	)
	(segment
		(start 377.746006 -72.695308)
		(end 377.544838 -72.695308)
		(width 0.089408)
		(layer "In9.Cu")
		(net "FM_CPU0_PKGID1")
	)
	(segment
		(start 384.114294 -41.579038)
		(end 384.114294 -45.864272)
		(width 0.089408)
		(layer "In9.Cu")
		(net "FM_CPU0_PKGID1")
	)
	(segment
		(start 383.171954 -59.568842)
		(end 382.404874 -60.335922)
		(width 0.089408)
		(layer "In9.Cu")
		(net "FM_CPU0_PKGID1")
	)
	(segment
		(start 380.5936 -69.7484)
		(end 380.3396 -70.0024)
		(width 0.089408)
		(layer "In9.Cu")
		(net "FM_CPU0_PKGID1")
	)
	(segment
		(start 383.106422 -54.336188)
		(end 383.629662 -54.859428)
		(width 0.089408)
		(layer "In9.Cu")
		(net "FM_CPU0_PKGID1")
	)
	(segment
		(start 380.3396 -70.0024)
		(end 380.0856 -70.0024)
		(width 0.089408)
		(layer "In9.Cu")
		(net "FM_CPU0_PKGID1")
	)
	(segment
		(start 383.765298 -35.18154)
		(end 383.186432 -35.760406)
		(width 0.089408)
		(layer "In9.Cu")
		(net "FM_CPU0_PKGID1")
	)
	(segment
		(start 383.452624 -40.917368)
		(end 384.114294 -41.579038)
		(width 0.089408)
		(layer "In9.Cu")
		(net "FM_CPU0_PKGID1")
	)
	(segment
		(start 383.171954 -56.252872)
		(end 383.171954 -59.568842)
		(width 0.089408)
		(layer "In9.Cu")
		(net "FM_CPU0_PKGID1")
	)
	(segment
		(start 383.106422 -46.872144)
		(end 383.106422 -54.336188)
		(width 0.089408)
		(layer "In9.Cu")
		(net "FM_CPU0_PKGID1")
	)
	(segment
		(start 383.186432 -35.760406)
		(end 383.186432 -36.389818)
		(width 0.089408)
		(layer "In9.Cu")
		(net "FM_CPU0_PKGID1")
	)
	(segment
		(start 244.768624 -90.26144)
		(end 244.197124 -90.26144)
		(width 0.10795)
		(layer "F.Cu")
		(net "FM_CPU0_PKGID0")
	)
	(segment
		(start 380.1364 -71.4756)
		(end 379.7046 -71.9074)
		(width 0.10795)
		(layer "F.Cu")
		(net "FM_CPU0_PKGID0")
	)
	(segment
		(start 379.7046 -71.9074)
		(end 378.332492 -71.9074)
		(width 0.10795)
		(layer "F.Cu")
		(net "FM_CPU0_PKGID0")
	)
	(segment
		(start 378.332492 -71.9074)
		(end 377.944888 -72.295004)
		(width 0.10795)
		(layer "F.Cu")
		(net "FM_CPU0_PKGID0")
	)
	(via
		(at 244.197124 -90.26144)
		(size 0.508)
		(drill 0.254)
		(layers "F.Cu" "B.Cu")
		(net "FM_CPU0_PKGID0")
	)
	(via
		(at 331.513434 -41.850818)
		(size 0.508)
		(drill 0.254)
		(layers "F.Cu" "B.Cu")
		(net "FM_CPU0_PKGID0")
	)
	(via
		(at 380.1364 -71.4756)
		(size 0.508)
		(drill 0.254)
		(layers "F.Cu" "B.Cu")
		(net "FM_CPU0_PKGID0")
	)
	(via
		(at 230.7082 -93.345)
		(size 0.6604)
		(drill 0.3302)
		(layers "F.Cu" "B.Cu")
		(net "FM_CPU0_PKGID0")
	)
	(segment
		(start 240.103152 -92.169996)
		(end 240.513616 -91.759532)
		(width 0.10795)
		(layer "B.Cu")
		(net "FM_CPU0_PKGID0")
	)
	(segment
		(start 228.473 -93.345)
		(end 230.7082 -93.345)
		(width 0.10795)
		(layer "B.Cu")
		(net "FM_CPU0_PKGID0")
	)
	(segment
		(start 243.237766 -91.250008)
		(end 243.500402 -91.250008)
		(width 0.10795)
		(layer "B.Cu")
		(net "FM_CPU0_PKGID0")
	)
	(segment
		(start 238.789972 -91.781122)
		(end 239.26673 -91.781122)
		(width 0.10795)
		(layer "B.Cu")
		(net "FM_CPU0_PKGID0")
	)
	(segment
		(start 232.117392 -92.307156)
		(end 234.882182 -92.307156)
		(width 0.10795)
		(layer "B.Cu")
		(net "FM_CPU0_PKGID0")
	)
	(segment
		(start 244.197124 -90.553286)
		(end 244.197124 -90.26144)
		(width 0.10795)
		(layer "B.Cu")
		(net "FM_CPU0_PKGID0")
	)
	(segment
		(start 234.882182 -92.307156)
		(end 235.408216 -91.781122)
		(width 0.10795)
		(layer "B.Cu")
		(net "FM_CPU0_PKGID0")
	)
	(segment
		(start 236.23143 -92.225622)
		(end 236.65434 -92.225622)
		(width 0.10795)
		(layer "B.Cu")
		(net "FM_CPU0_PKGID0")
	)
	(segment
		(start 235.78693 -91.781122)
		(end 236.23143 -92.225622)
		(width 0.10795)
		(layer "B.Cu")
		(net "FM_CPU0_PKGID0")
	)
	(segment
		(start 231.079548 -93.345)
		(end 232.117392 -92.307156)
		(width 0.10795)
		(layer "B.Cu")
		(net "FM_CPU0_PKGID0")
	)
	(segment
		(start 237.09884 -91.781122)
		(end 237.510574 -91.781122)
		(width 0.10795)
		(layer "B.Cu")
		(net "FM_CPU0_PKGID0")
	)
	(segment
		(start 242.313206 -91.770454)
		(end 242.71732 -91.770454)
		(width 0.10795)
		(layer "B.Cu")
		(net "FM_CPU0_PKGID0")
	)
	(segment
		(start 239.655604 -92.169996)
		(end 240.103152 -92.169996)
		(width 0.10795)
		(layer "B.Cu")
		(net "FM_CPU0_PKGID0")
	)
	(segment
		(start 236.65434 -92.225622)
		(end 237.09884 -91.781122)
		(width 0.10795)
		(layer "B.Cu")
		(net "FM_CPU0_PKGID0")
	)
	(segment
		(start 237.920022 -92.19057)
		(end 238.380524 -92.19057)
		(width 0.10795)
		(layer "B.Cu")
		(net "FM_CPU0_PKGID0")
	)
	(segment
		(start 241.901472 -92.182188)
		(end 242.313206 -91.770454)
		(width 0.10795)
		(layer "B.Cu")
		(net "FM_CPU0_PKGID0")
	)
	(segment
		(start 238.380524 -92.19057)
		(end 238.789972 -91.781122)
		(width 0.10795)
		(layer "B.Cu")
		(net "FM_CPU0_PKGID0")
	)
	(segment
		(start 241.435128 -92.182188)
		(end 241.901472 -92.182188)
		(width 0.10795)
		(layer "B.Cu")
		(net "FM_CPU0_PKGID0")
	)
	(segment
		(start 239.26673 -91.781122)
		(end 239.655604 -92.169996)
		(width 0.10795)
		(layer "B.Cu")
		(net "FM_CPU0_PKGID0")
	)
	(segment
		(start 241.012472 -91.759532)
		(end 241.435128 -92.182188)
		(width 0.10795)
		(layer "B.Cu")
		(net "FM_CPU0_PKGID0")
	)
	(segment
		(start 230.7082 -93.345)
		(end 231.079548 -93.345)
		(width 0.10795)
		(layer "B.Cu")
		(net "FM_CPU0_PKGID0")
	)
	(segment
		(start 235.408216 -91.781122)
		(end 235.78693 -91.781122)
		(width 0.10795)
		(layer "B.Cu")
		(net "FM_CPU0_PKGID0")
	)
	(segment
		(start 240.513616 -91.759532)
		(end 241.012472 -91.759532)
		(width 0.10795)
		(layer "B.Cu")
		(net "FM_CPU0_PKGID0")
	)
	(segment
		(start 243.500402 -91.250008)
		(end 244.197124 -90.553286)
		(width 0.10795)
		(layer "B.Cu")
		(net "FM_CPU0_PKGID0")
	)
	(segment
		(start 237.510574 -91.781122)
		(end 237.920022 -92.19057)
		(width 0.10795)
		(layer "B.Cu")
		(net "FM_CPU0_PKGID0")
	)
	(segment
		(start 242.71732 -91.770454)
		(end 243.237766 -91.250008)
		(width 0.10795)
		(layer "B.Cu")
		(net "FM_CPU0_PKGID0")
	)
	(segment
		(start 290.448746 -75.316334)
		(end 290.145216 -75.619864)
		(width 0.0889)
		(layer "In2.Cu")
		(net "FM_CPU0_PKGID0")
	)
	(segment
		(start 250.598686 -86.202012)
		(end 249.846338 -86.202012)
		(width 0.0889)
		(layer "In2.Cu")
		(net "FM_CPU0_PKGID0")
	)
	(segment
		(start 260.332474 -88.242902)
		(end 259.940298 -87.850726)
		(width 0.0889)
		(layer "In2.Cu")
		(net "FM_CPU0_PKGID0")
	)
	(segment
		(start 256.403094 -86.88959)
		(end 256.056384 -86.88959)
		(width 0.0889)
		(layer "In2.Cu")
		(net "FM_CPU0_PKGID0")
	)
	(segment
		(start 332.460854 -44.914566)
		(end 314.66663 -62.70879)
		(width 0.089408)
		(layer "In2.Cu")
		(net "FM_CPU0_PKGID0")
	)
	(segment
		(start 297.034712 -73.4314)
		(end 296.827448 -73.638664)
		(width 0.0889)
		(layer "In2.Cu")
		(net "FM_CPU0_PKGID0")
	)
	(segment
		(start 299.4025 -73.143364)
		(end 299.071792 -73.143364)
		(width 0.089408)
		(layer "In2.Cu")
		(net "FM_CPU0_PKGID0")
	)
	(segment
		(start 290.145216 -75.619864)
		(end 289.402266 -75.619864)
		(width 0.0889)
		(layer "In2.Cu")
		(net "FM_CPU0_PKGID0")
	)
	(segment
		(start 294.553386 -74.629264)
		(end 294.25138 -74.327258)
		(width 0.0889)
		(layer "In2.Cu")
		(net "FM_CPU0_PKGID0")
	)
	(segment
		(start 249.54484 -85.900514)
		(end 249.151648 -85.900514)
		(width 0.0889)
		(layer "In2.Cu")
		(net "FM_CPU0_PKGID0")
	)
	(segment
		(start 295.96842 -74.13371)
		(end 295.605454 -74.13371)
		(width 0.0889)
		(layer "In2.Cu")
		(net "FM_CPU0_PKGID0")
	)
	(segment
		(start 296.827448 -73.638664)
		(end 296.463466 -73.638664)
		(width 0.0889)
		(layer "In2.Cu")
		(net "FM_CPU0_PKGID0")
	)
	(segment
		(start 286.79648 -76.564998)
		(end 286.79648 -79.40548)
		(width 0.0889)
		(layer "In2.Cu")
		(net "FM_CPU0_PKGID0")
	)
	(segment
		(start 299.071792 -73.143364)
		(end 298.769786 -72.841358)
		(width 0.089408)
		(layer "In2.Cu")
		(net "FM_CPU0_PKGID0")
	)
	(segment
		(start 260.725666 -88.242902)
		(end 260.332474 -88.242902)
		(width 0.0889)
		(layer "In2.Cu")
		(net "FM_CPU0_PKGID0")
	)
	(segment
		(start 300.952662 -73.14311)
		(end 300.63567 -73.14311)
		(width 0.0889)
		(layer "In2.Cu")
		(net "FM_CPU0_PKGID0")
	)
	(segment
		(start 258.980178 -88.202262)
		(end 258.420616 -88.202262)
		(width 0.0889)
		(layer "In2.Cu")
		(net "FM_CPU0_PKGID0")
	)
	(segment
		(start 271.436084 -88.852502)
		(end 262.896096 -88.852502)
		(width 0.0889)
		(layer "In2.Cu")
		(net "FM_CPU0_PKGID0")
	)
	(segment
		(start 279.455118 -88.658446)
		(end 279.333198 -88.658446)
		(width 0.089408)
		(layer "In2.Cu")
		(net "FM_CPU0_PKGID0")
	)
	(segment
		(start 300.954186 -73.144634)
		(end 300.952662 -73.14311)
		(width 0.0889)
		(layer "In2.Cu")
		(net "FM_CPU0_PKGID0")
	)
	(segment
		(start 299.704506 -72.841358)
		(end 299.4025 -73.143364)
		(width 0.089408)
		(layer "In2.Cu")
		(net "FM_CPU0_PKGID0")
	)
	(segment
		(start 300.63567 -73.14311)
		(end 300.333918 -72.841358)
		(width 0.089408)
		(layer "In2.Cu")
		(net "FM_CPU0_PKGID0")
	)
	(segment
		(start 262.057642 -88.33612)
		(end 261.598664 -87.877142)
		(width 0.0889)
		(layer "In2.Cu")
		(net "FM_CPU0_PKGID0")
	)
	(segment
		(start 249.151648 -85.900514)
		(end 248.85015 -86.202012)
		(width 0.0889)
		(layer "In2.Cu")
		(net "FM_CPU0_PKGID0")
	)
	(segment
		(start 304.406046 -71.163434)
		(end 304.370486 -71.163434)
		(width 0.0889)
		(layer "In2.Cu")
		(net "FM_CPU0_PKGID0")
	)
	(segment
		(start 283.238702 -84.874862)
		(end 279.455118 -88.658446)
		(width 0.089408)
		(layer "In2.Cu")
		(net "FM_CPU0_PKGID0")
	)
	(segment
		(start 256.056384 -86.88959)
		(end 255.49479 -86.327996)
		(width 0.0889)
		(layer "In2.Cu")
		(net "FM_CPU0_PKGID0")
	)
	(segment
		(start 255.49479 -86.327996)
		(end 255.249426 -86.327996)
		(width 0.0889)
		(layer "In2.Cu")
		(net "FM_CPU0_PKGID0")
	)
	(segment
		(start 314.66663 -62.70879)
		(end 314.66663 -65.895982)
		(width 0.089408)
		(layer "In2.Cu")
		(net "FM_CPU0_PKGID0")
	)
	(segment
		(start 255.249426 -86.327996)
		(end 254.821944 -85.900514)
		(width 0.0889)
		(layer "In2.Cu")
		(net "FM_CPU0_PKGID0")
	)
	(segment
		(start 244.493288 -86.20506)
		(end 243.313458 -87.38489)
		(width 0.0889)
		(layer "In2.Cu")
		(net "FM_CPU0_PKGID0")
	)
	(segment
		(start 285.55442 -80.596994)
		(end 284.889956 -81.261458)
		(width 0.0889)
		(layer "In2.Cu")
		(net "FM_CPU0_PKGID0")
	)
	(segment
		(start 289.10026 -75.317858)
		(end 288.730182 -75.317858)
		(width 0.0889)
		(layer "In2.Cu")
		(net "FM_CPU0_PKGID0")
	)
	(segment
		(start 332.460854 -42.377614)
		(end 332.460854 -44.914566)
		(width 0.089408)
		(layer "In2.Cu")
		(net "FM_CPU0_PKGID0")
	)
	(segment
		(start 242.91544 -88.979756)
		(end 243.301774 -89.36609)
		(width 0.0889)
		(layer "In2.Cu")
		(net "FM_CPU0_PKGID0")
	)
	(segment
		(start 247.466104 -85.900514)
		(end 247.161558 -86.20506)
		(width 0.0889)
		(layer "In2.Cu")
		(net "FM_CPU0_PKGID0")
	)
	(segment
		(start 253.031244 -85.900514)
		(end 252.617224 -85.900514)
		(width 0.0889)
		(layer "In2.Cu")
		(net "FM_CPU0_PKGID0")
	)
	(segment
		(start 288.730182 -75.317858)
		(end 288.42208 -75.62596)
		(width 0.0889)
		(layer "In2.Cu")
		(net "FM_CPU0_PKGID0")
	)
	(segment
		(start 302.686212 -72.154034)
		(end 302.653446 -72.154034)
		(width 0.0889)
		(layer "In2.Cu")
		(net "FM_CPU0_PKGID0")
	)
	(segment
		(start 286.5374 -79.66456)
		(end 285.92526 -79.66456)
		(width 0.0889)
		(layer "In2.Cu")
		(net "FM_CPU0_PKGID0")
	)
	(segment
		(start 248.85015 -86.202012)
		(end 248.197878 -86.202012)
		(width 0.0889)
		(layer "In2.Cu")
		(net "FM_CPU0_PKGID0")
	)
	(segment
		(start 248.197878 -86.202012)
		(end 247.89638 -85.900514)
		(width 0.0889)
		(layer "In2.Cu")
		(net "FM_CPU0_PKGID0")
	)
	(segment
		(start 295.605454 -74.13371)
		(end 295.1099 -74.629264)
		(width 0.0889)
		(layer "In2.Cu")
		(net "FM_CPU0_PKGID0")
	)
	(segment
		(start 301.823882 -72.649588)
		(end 301.791116 -72.649588)
		(width 0.0889)
		(layer "In2.Cu")
		(net "FM_CPU0_PKGID0")
	)
	(segment
		(start 300.969172 -73.144634)
		(end 300.954186 -73.144634)
		(width 0.0889)
		(layer "In2.Cu")
		(net "FM_CPU0_PKGID0")
	)
	(segment
		(start 243.769642 -89.833958)
		(end 244.197124 -90.26144)
		(width 0.0889)
		(layer "In2.Cu")
		(net "FM_CPU0_PKGID0")
	)
	(segment
		(start 286.79648 -79.40548)
		(end 286.5374 -79.66456)
		(width 0.0889)
		(layer "In2.Cu")
		(net "FM_CPU0_PKGID0")
	)
	(segment
		(start 291.67582 -75.619864)
		(end 291.119306 -75.619864)
		(width 0.0889)
		(layer "In2.Cu")
		(net "FM_CPU0_PKGID0")
	)
	(segment
		(start 292.106604 -75.18908)
		(end 291.67582 -75.619864)
		(width 0.0889)
		(layer "In2.Cu")
		(net "FM_CPU0_PKGID0")
	)
	(segment
		(start 287.05302 -76.308458)
		(end 286.79648 -76.564998)
		(width 0.0889)
		(layer "In2.Cu")
		(net "FM_CPU0_PKGID0")
	)
	(segment
		(start 292.5572 -75.18908)
		(end 292.106604 -75.18908)
		(width 0.0889)
		(layer "In2.Cu")
		(net "FM_CPU0_PKGID0")
	)
	(segment
		(start 247.89638 -85.900514)
		(end 247.466104 -85.900514)
		(width 0.0889)
		(layer "In2.Cu")
		(net "FM_CPU0_PKGID0")
	)
	(segment
		(start 262.379714 -88.33612)
		(end 262.057642 -88.33612)
		(width 0.0889)
		(layer "In2.Cu")
		(net "FM_CPU0_PKGID0")
	)
	(segment
		(start 314.66663 -65.895982)
		(end 309.295292 -71.26732)
		(width 0.089408)
		(layer "In2.Cu")
		(net "FM_CPU0_PKGID0")
	)
	(segment
		(start 272.490946 -89.151206)
		(end 271.734788 -89.151206)
		(width 0.0889)
		(layer "In2.Cu")
		(net "FM_CPU0_PKGID0")
	)
	(segment
		(start 256.828036 -87.314532)
		(end 256.403094 -86.88959)
		(width 0.0889)
		(layer "In2.Cu")
		(net "FM_CPU0_PKGID0")
	)
	(segment
		(start 278.840438 -89.151206)
		(end 272.490946 -89.151206)
		(width 0.089408)
		(layer "In2.Cu")
		(net "FM_CPU0_PKGID0")
	)
	(segment
		(start 294.25138 -74.327258)
		(end 293.92118 -74.327258)
		(width 0.0889)
		(layer "In2.Cu")
		(net "FM_CPU0_PKGID0")
	)
	(segment
		(start 243.502434 -89.36609)
		(end 243.769642 -89.633298)
		(width 0.0889)
		(layer "In2.Cu")
		(net "FM_CPU0_PKGID0")
	)
	(segment
		(start 291.119306 -75.619864)
		(end 290.815776 -75.316334)
		(width 0.0889)
		(layer "In2.Cu")
		(net "FM_CPU0_PKGID0")
	)
	(segment
		(start 249.846338 -86.202012)
		(end 249.54484 -85.900514)
		(width 0.0889)
		(layer "In2.Cu")
		(net "FM_CPU0_PKGID0")
	)
	(segment
		(start 252.617224 -85.900514)
		(end 252.315726 -86.202012)
		(width 0.0889)
		(layer "In2.Cu")
		(net "FM_CPU0_PKGID0")
	)
	(segment
		(start 257.742436 -87.864442)
		(end 257.192526 -87.314532)
		(width 0.0889)
		(layer "In2.Cu")
		(net "FM_CPU0_PKGID0")
	)
	(segment
		(start 295.1099 -74.629264)
		(end 294.553386 -74.629264)
		(width 0.0889)
		(layer "In2.Cu")
		(net "FM_CPU0_PKGID0")
	)
	(segment
		(start 253.918212 -86.202012)
		(end 253.332742 -86.202012)
		(width 0.0889)
		(layer "In2.Cu")
		(net "FM_CPU0_PKGID0")
	)
	(segment
		(start 307.051202 -71.658988)
		(end 306.836826 -71.658988)
		(width 0.0889)
		(layer "In2.Cu")
		(net "FM_CPU0_PKGID0")
	)
	(segment
		(start 254.21971 -85.900514)
		(end 253.918212 -86.202012)
		(width 0.0889)
		(layer "In2.Cu")
		(net "FM_CPU0_PKGID0")
	)
	(segment
		(start 298.769786 -72.841358)
		(end 298.213272 -72.841358)
		(width 0.089408)
		(layer "In2.Cu")
		(net "FM_CPU0_PKGID0")
	)
	(segment
		(start 283.238702 -83.343242)
		(end 283.238702 -84.874862)
		(width 0.089408)
		(layer "In2.Cu")
		(net "FM_CPU0_PKGID0")
	)
	(segment
		(start 303.540922 -71.658988)
		(end 303.508156 -71.658988)
		(width 0.0889)
		(layer "In2.Cu")
		(net "FM_CPU0_PKGID0")
	)
	(segment
		(start 251.457206 -85.900514)
		(end 250.900184 -85.900514)
		(width 0.0889)
		(layer "In2.Cu")
		(net "FM_CPU0_PKGID0")
	)
	(segment
		(start 305.268376 -71.658988)
		(end 305.23561 -71.658988)
		(width 0.0889)
		(layer "In2.Cu")
		(net "FM_CPU0_PKGID0")
	)
	(segment
		(start 254.821944 -85.900514)
		(end 254.21971 -85.900514)
		(width 0.0889)
		(layer "In2.Cu")
		(net "FM_CPU0_PKGID0")
	)
	(segment
		(start 261.091426 -87.877142)
		(end 260.725666 -88.242902)
		(width 0.0889)
		(layer "In2.Cu")
		(net "FM_CPU0_PKGID0")
	)
	(segment
		(start 309.295292 -71.26732)
		(end 308.096666 -71.26732)
		(width 0.089408)
		(layer "In2.Cu")
		(net "FM_CPU0_PKGID0")
	)
	(segment
		(start 296.463466 -73.638664)
		(end 295.96842 -74.13371)
		(width 0.0889)
		(layer "In2.Cu")
		(net "FM_CPU0_PKGID0")
	)
	(segment
		(start 331.934058 -41.850818)
		(end 332.460854 -42.377614)
		(width 0.089408)
		(layer "In2.Cu")
		(net "FM_CPU0_PKGID0")
	)
	(segment
		(start 253.332742 -86.202012)
		(end 253.031244 -85.900514)
		(width 0.0889)
		(layer "In2.Cu")
		(net "FM_CPU0_PKGID0")
	)
	(segment
		(start 289.402266 -75.619864)
		(end 289.10026 -75.317858)
		(width 0.0889)
		(layer "In2.Cu")
		(net "FM_CPU0_PKGID0")
	)
	(segment
		(start 243.301774 -89.36609)
		(end 243.502434 -89.36609)
		(width 0.0889)
		(layer "In2.Cu")
		(net "FM_CPU0_PKGID0")
	)
	(segment
		(start 297.718226 -73.336404)
		(end 297.129708 -73.336404)
		(width 0.089408)
		(layer "In2.Cu")
		(net "FM_CPU0_PKGID0")
	)
	(segment
		(start 285.92526 -79.66456)
		(end 285.55442 -80.0354)
		(width 0.0889)
		(layer "In2.Cu")
		(net "FM_CPU0_PKGID0")
	)
	(segment
		(start 297.129708 -73.336404)
		(end 297.034712 -73.4314)
		(width 0.089408)
		(layer "In2.Cu")
		(net "FM_CPU0_PKGID0")
	)
	(segment
		(start 258.420616 -88.202262)
		(end 258.082796 -87.864442)
		(width 0.0889)
		(layer "In2.Cu")
		(net "FM_CPU0_PKGID0")
	)
	(segment
		(start 262.896096 -88.852502)
		(end 262.379714 -88.33612)
		(width 0.0889)
		(layer "In2.Cu")
		(net "FM_CPU0_PKGID0")
	)
	(segment
		(start 258.082796 -87.864442)
		(end 257.742436 -87.864442)
		(width 0.0889)
		(layer "In2.Cu")
		(net "FM_CPU0_PKGID0")
	)
	(segment
		(start 284.889956 -81.261458)
		(end 284.889956 -81.691988)
		(width 0.0889)
		(layer "In2.Cu")
		(net "FM_CPU0_PKGID0")
	)
	(segment
		(start 293.117016 -74.629264)
		(end 292.5572 -75.18908)
		(width 0.0889)
		(layer "In2.Cu")
		(net "FM_CPU0_PKGID0")
	)
	(segment
		(start 284.889956 -81.691988)
		(end 283.238702 -83.343242)
		(width 0.0889)
		(layer "In2.Cu")
		(net "FM_CPU0_PKGID0")
	)
	(segment
		(start 259.940298 -87.850726)
		(end 259.331714 -87.850726)
		(width 0.0889)
		(layer "In2.Cu")
		(net "FM_CPU0_PKGID0")
	)
	(segment
		(start 287.213802 -76.308458)
		(end 287.05302 -76.308458)
		(width 0.0889)
		(layer "In2.Cu")
		(net "FM_CPU0_PKGID0")
	)
	(segment
		(start 257.192526 -87.314532)
		(end 256.828036 -87.314532)
		(width 0.0889)
		(layer "In2.Cu")
		(net "FM_CPU0_PKGID0")
	)
	(segment
		(start 252.315726 -86.202012)
		(end 251.758704 -86.202012)
		(width 0.0889)
		(layer "In2.Cu")
		(net "FM_CPU0_PKGID0")
	)
	(segment
		(start 308.096666 -71.26732)
		(end 307.71846 -71.26732)
		(width 0.0889)
		(layer "In2.Cu")
		(net "FM_CPU0_PKGID0")
	)
	(segment
		(start 243.174774 -87.38489)
		(end 242.91544 -87.644224)
		(width 0.0889)
		(layer "In2.Cu")
		(net "FM_CPU0_PKGID0")
	)
	(segment
		(start 243.769642 -89.633298)
		(end 243.769642 -89.833958)
		(width 0.0889)
		(layer "In2.Cu")
		(net "FM_CPU0_PKGID0")
	)
	(segment
		(start 247.161558 -86.20506)
		(end 244.493288 -86.20506)
		(width 0.0889)
		(layer "In2.Cu")
		(net "FM_CPU0_PKGID0")
	)
	(segment
		(start 261.598664 -87.877142)
		(end 261.091426 -87.877142)
		(width 0.0889)
		(layer "In2.Cu")
		(net "FM_CPU0_PKGID0")
	)
	(segment
		(start 251.758704 -86.202012)
		(end 251.457206 -85.900514)
		(width 0.0889)
		(layer "In2.Cu")
		(net "FM_CPU0_PKGID0")
	)
	(segment
		(start 285.55442 -80.0354)
		(end 285.55442 -80.596994)
		(width 0.0889)
		(layer "In2.Cu")
		(net "FM_CPU0_PKGID0")
	)
	(segment
		(start 293.619174 -74.629264)
		(end 293.117016 -74.629264)
		(width 0.0889)
		(layer "In2.Cu")
		(net "FM_CPU0_PKGID0")
	)
	(segment
		(start 300.333918 -72.841358)
		(end 299.704506 -72.841358)
		(width 0.089408)
		(layer "In2.Cu")
		(net "FM_CPU0_PKGID0")
	)
	(segment
		(start 259.331714 -87.850726)
		(end 258.980178 -88.202262)
		(width 0.0889)
		(layer "In2.Cu")
		(net "FM_CPU0_PKGID0")
	)
	(segment
		(start 287.8963 -75.62596)
		(end 287.213802 -76.308458)
		(width 0.0889)
		(layer "In2.Cu")
		(net "FM_CPU0_PKGID0")
	)
	(segment
		(start 242.91544 -87.644224)
		(end 242.91544 -87.7062)
		(width 0.0889)
		(layer "In2.Cu")
		(net "FM_CPU0_PKGID0")
	)
	(segment
		(start 331.513434 -41.850818)
		(end 331.934058 -41.850818)
		(width 0.089408)
		(layer "In2.Cu")
		(net "FM_CPU0_PKGID0")
	)
	(segment
		(start 242.91544 -87.7062)
		(end 242.91544 -88.979756)
		(width 0.089408)
		(layer "In2.Cu")
		(net "FM_CPU0_PKGID0")
	)
	(segment
		(start 293.92118 -74.327258)
		(end 293.619174 -74.629264)
		(width 0.0889)
		(layer "In2.Cu")
		(net "FM_CPU0_PKGID0")
	)
	(segment
		(start 298.213272 -72.841358)
		(end 297.718226 -73.336404)
		(width 0.089408)
		(layer "In2.Cu")
		(net "FM_CPU0_PKGID0")
	)
	(segment
		(start 271.734788 -89.151206)
		(end 271.436084 -88.852502)
		(width 0.0889)
		(layer "In2.Cu")
		(net "FM_CPU0_PKGID0")
	)
	(segment
		(start 250.900184 -85.900514)
		(end 250.598686 -86.202012)
		(width 0.0889)
		(layer "In2.Cu")
		(net "FM_CPU0_PKGID0")
	)
	(segment
		(start 288.42208 -75.62596)
		(end 287.8963 -75.62596)
		(width 0.0889)
		(layer "In2.Cu")
		(net "FM_CPU0_PKGID0")
	)
	(segment
		(start 243.313458 -87.38489)
		(end 243.174774 -87.38489)
		(width 0.0889)
		(layer "In2.Cu")
		(net "FM_CPU0_PKGID0")
	)
	(segment
		(start 279.333198 -88.658446)
		(end 278.840438 -89.151206)
		(width 0.089408)
		(layer "In2.Cu")
		(net "FM_CPU0_PKGID0")
	)
	(segment
		(start 290.815776 -75.316334)
		(end 290.448746 -75.316334)
		(width 0.0889)
		(layer "In2.Cu")
		(net "FM_CPU0_PKGID0")
	)
	(arc
		(start 302.159416 -72.449436)
		(mid 302.017733 -72.59324)
		(end 301.823882 -72.649588)
		(width 0.0889)
		(layer "In2.Cu")
		(net "FM_CPU0_PKGID0")
	)
	(arc
		(start 304.900076 -71.458836)
		(mid 304.691468 -71.246904)
		(end 304.406046 -71.163434)
		(width 0.0889)
		(layer "In2.Cu")
		(net "FM_CPU0_PKGID0")
	)
	(arc
		(start 305.758596 -71.954136)
		(mid 305.551592 -71.743272)
		(end 305.268376 -71.658988)
		(width 0.0889)
		(layer "In2.Cu")
		(net "FM_CPU0_PKGID0")
	)
	(arc
		(start 307.71846 -71.26732)
		(mid 307.526942 -71.318638)
		(end 307.386736 -71.458836)
		(width 0.0889)
		(layer "In2.Cu")
		(net "FM_CPU0_PKGID0")
	)
	(arc
		(start 301.791116 -72.649588)
		(mid 301.507899 -72.733869)
		(end 301.300896 -72.944736)
		(width 0.0889)
		(layer "In2.Cu")
		(net "FM_CPU0_PKGID0")
	)
	(arc
		(start 306.213002 -72.173846)
		(mid 305.952005 -72.13388)
		(end 305.758596 -71.954136)
		(width 0.0889)
		(layer "In2.Cu")
		(net "FM_CPU0_PKGID0")
	)
	(arc
		(start 303.876456 -71.458836)
		(mid 303.734773 -71.60264)
		(end 303.540922 -71.658988)
		(width 0.0889)
		(layer "In2.Cu")
		(net "FM_CPU0_PKGID0")
	)
	(arc
		(start 301.300896 -72.944736)
		(mid 301.160817 -73.087472)
		(end 300.969172 -73.144634)
		(width 0.0889)
		(layer "In2.Cu")
		(net "FM_CPU0_PKGID0")
	)
	(arc
		(start 304.370486 -71.163434)
		(mid 304.085062 -71.246901)
		(end 303.876456 -71.458836)
		(width 0.0889)
		(layer "In2.Cu")
		(net "FM_CPU0_PKGID0")
	)
	(arc
		(start 306.488338 -71.95693)
		(mid 306.373578 -72.09447)
		(end 306.213002 -72.173846)
		(width 0.0889)
		(layer "In2.Cu")
		(net "FM_CPU0_PKGID0")
	)
	(arc
		(start 303.508156 -71.658988)
		(mid 303.224939 -71.743269)
		(end 303.017936 -71.954136)
		(width 0.0889)
		(layer "In2.Cu")
		(net "FM_CPU0_PKGID0")
	)
	(arc
		(start 305.23561 -71.658988)
		(mid 305.04176 -71.602638)
		(end 304.900076 -71.458836)
		(width 0.0889)
		(layer "In2.Cu")
		(net "FM_CPU0_PKGID0")
	)
	(arc
		(start 307.386736 -71.458836)
		(mid 307.245053 -71.60264)
		(end 307.051202 -71.658988)
		(width 0.0889)
		(layer "In2.Cu")
		(net "FM_CPU0_PKGID0")
	)
	(arc
		(start 306.836826 -71.658988)
		(mid 306.634232 -71.774806)
		(end 306.488338 -71.95693)
		(width 0.0889)
		(layer "In2.Cu")
		(net "FM_CPU0_PKGID0")
	)
	(arc
		(start 303.017936 -71.954136)
		(mid 302.877857 -72.096872)
		(end 302.686212 -72.154034)
		(width 0.0889)
		(layer "In2.Cu")
		(net "FM_CPU0_PKGID0")
	)
	(arc
		(start 302.653446 -72.154034)
		(mid 302.368022 -72.237501)
		(end 302.159416 -72.449436)
		(width 0.0889)
		(layer "In2.Cu")
		(net "FM_CPU0_PKGID0")
	)
	(segment
		(start 368.257074 -50.819558)
		(end 364.57382 -50.819558)
		(width 0.089408)
		(layer "In11.Cu")
		(net "FM_CPU0_PKGID0")
	)
	(segment
		(start 357.92029 -45.042836)
		(end 334.379062 -45.042836)
		(width 0.089408)
		(layer "In11.Cu")
		(net "FM_CPU0_PKGID0")
	)
	(segment
		(start 374.195594 -57.104788)
		(end 373.737632 -57.104788)
		(width 0.089408)
		(layer "In11.Cu")
		(net "FM_CPU0_PKGID0")
	)
	(segment
		(start 379.227842 -67.37731)
		(end 378.699522 -67.37731)
		(width 0.089408)
		(layer "In11.Cu")
		(net "FM_CPU0_PKGID0")
	)
	(segment
		(start 377.705112 -66.3829)
		(end 377.705112 -63.617856)
		(width 0.089408)
		(layer "In11.Cu")
		(net "FM_CPU0_PKGID0")
	)
	(segment
		(start 358.796844 -45.042582)
		(end 357.920544 -45.042582)
		(width 0.089408)
		(layer "In11.Cu")
		(net "FM_CPU0_PKGID0")
	)
	(segment
		(start 379.600714 -70.939914)
		(end 379.600714 -69.27977)
		(width 0.089408)
		(layer "In11.Cu")
		(net "FM_CPU0_PKGID0")
	)
	(segment
		(start 370.081302 -53.448458)
		(end 370.081302 -52.643786)
		(width 0.089408)
		(layer "In11.Cu")
		(net "FM_CPU0_PKGID0")
	)
	(segment
		(start 377.38939 -62.365382)
		(end 377.38939 -60.298584)
		(width 0.089408)
		(layer "In11.Cu")
		(net "FM_CPU0_PKGID0")
	)
	(segment
		(start 332.407514 -43.071288)
		(end 332.407514 -42.744898)
		(width 0.089408)
		(layer "In11.Cu")
		(net "FM_CPU0_PKGID0")
	)
	(segment
		(start 373.737632 -57.104788)
		(end 370.081302 -53.448458)
		(width 0.089408)
		(layer "In11.Cu")
		(net "FM_CPU0_PKGID0")
	)
	(segment
		(start 380.1364 -71.4756)
		(end 379.600714 -70.939914)
		(width 0.089408)
		(layer "In11.Cu")
		(net "FM_CPU0_PKGID0")
	)
	(segment
		(start 377.205748 -62.549024)
		(end 377.38939 -62.365382)
		(width 0.089408)
		(layer "In11.Cu")
		(net "FM_CPU0_PKGID0")
	)
	(segment
		(start 364.57382 -50.819558)
		(end 358.796844 -45.042582)
		(width 0.089408)
		(layer "In11.Cu")
		(net "FM_CPU0_PKGID0")
	)
	(segment
		(start 379.611636 -67.761104)
		(end 379.227842 -67.37731)
		(width 0.089408)
		(layer "In11.Cu")
		(net "FM_CPU0_PKGID0")
	)
	(segment
		(start 377.38939 -60.298584)
		(end 374.195594 -57.104788)
		(width 0.089408)
		(layer "In11.Cu")
		(net "FM_CPU0_PKGID0")
	)
	(segment
		(start 332.407514 -42.744898)
		(end 331.513434 -41.850818)
		(width 0.089408)
		(layer "In11.Cu")
		(net "FM_CPU0_PKGID0")
	)
	(segment
		(start 378.699522 -67.37731)
		(end 377.705112 -66.3829)
		(width 0.089408)
		(layer "In11.Cu")
		(net "FM_CPU0_PKGID0")
	)
	(segment
		(start 377.705112 -63.617856)
		(end 377.205748 -63.118492)
		(width 0.089408)
		(layer "In11.Cu")
		(net "FM_CPU0_PKGID0")
	)
	(segment
		(start 370.081302 -52.643786)
		(end 368.257074 -50.819558)
		(width 0.089408)
		(layer "In11.Cu")
		(net "FM_CPU0_PKGID0")
	)
	(segment
		(start 379.611636 -69.268848)
		(end 379.611636 -67.761104)
		(width 0.089408)
		(layer "In11.Cu")
		(net "FM_CPU0_PKGID0")
	)
	(segment
		(start 334.379062 -45.042836)
		(end 332.407514 -43.071288)
		(width 0.089408)
		(layer "In11.Cu")
		(net "FM_CPU0_PKGID0")
	)
	(segment
		(start 379.600714 -69.27977)
		(end 379.611636 -69.268848)
		(width 0.089408)
		(layer "In11.Cu")
		(net "FM_CPU0_PKGID0")
	)
	(segment
		(start 377.205748 -63.118492)
		(end 377.205748 -62.549024)
		(width 0.089408)
		(layer "In11.Cu")
		(net "FM_CPU0_PKGID0")
	)
	(segment
		(start 357.920544 -45.042582)
		(end 357.92029 -45.042836)
		(width 0.089408)
		(layer "In11.Cu")
		(net "FM_CPU0_PKGID0")
	)
	(segment
		(start 368.344958 -74.69505)
		(end 368.744754 -75.094846)
		(width 0.10795)
		(layer "F.Cu")
		(net "TP_CPLD1_PR7D")
	)
	(via
		(at 368.744754 -75.094846)
		(size 0.4572)
		(drill 0.2032)
		(layers "F.Cu" "B.Cu")
		(net "TP_CPLD1_PR7D")
	)
	(segment
		(start 367.545112 -74.69505)
		(end 367.938558 -75.088496)
		(width 0.10795)
		(layer "F.Cu")
		(net "TP_CPLD1_PR9A")
	)
	(via
		(at 367.938558 -75.088496)
		(size 0.4572)
		(drill 0.2032)
		(layers "F.Cu" "B.Cu")
		(net "TP_CPLD1_PR9A")
	)
	(segment
		(start 366.745012 -74.69505)
		(end 367.138458 -75.088496)
		(width 0.10795)
		(layer "F.Cu")
		(net "TP_CPLD1_PR7C")
	)
	(via
		(at 367.138458 -75.088496)
		(size 0.4572)
		(drill 0.2032)
		(layers "F.Cu" "B.Cu")
		(net "TP_CPLD1_PR7C")
	)
	(segment
		(start 369.506754 -74.333354)
		(end 369.145058 -74.69505)
		(width 0.10795)
		(layer "F.Cu")
		(net "TP_CPLD1_PR9D")
	)
	(via
		(at 369.506754 -74.333354)
		(size 0.4572)
		(drill 0.2032)
		(layers "F.Cu" "B.Cu")
		(net "TP_CPLD1_PR9D")
	)
	(segment
		(start 366.345216 -74.294746)
		(end 366.745012 -73.89495)
		(width 0.10795)
		(layer "F.Cu")
		(net "TP_CPLD1_PR7B_PCLKC1_0")
	)
	(via
		(at 366.345216 -74.294746)
		(size 0.4572)
		(drill 0.2032)
		(layers "F.Cu" "B.Cu")
		(net "TP_CPLD1_PR7B_PCLKC1_0")
	)
	(segment
		(start 367.945162 -73.495154)
		(end 368.344958 -73.89495)
		(width 0.10795)
		(layer "F.Cu")
		(net "TP_CPLD1_PR7A_PCLKT1_0")
	)
	(via
		(at 367.945162 -73.495154)
		(size 0.4572)
		(drill 0.2032)
		(layers "F.Cu" "B.Cu")
		(net "TP_CPLD1_PR7A_PCLKT1_0")
	)
	(via
		(at 366.6236 -72.5678)
		(size 0.6604)
		(drill 0.3302)
		(layers "F.Cu" "B.Cu")
		(net "TP_CPLD1_PR7A_PCLKT1_0")
	)
	(segment
		(start 366.6236 -72.5678)
		(end 366.8776 -72.5678)
		(width 0.10795)
		(layer "B.Cu")
		(net "TP_CPLD1_PR7A_PCLKT1_0")
	)
	(segment
		(start 367.804954 -73.495154)
		(end 367.945162 -73.495154)
		(width 0.10795)
		(layer "B.Cu")
		(net "TP_CPLD1_PR7A_PCLKT1_0")
	)
	(segment
		(start 366.8776 -72.5678)
		(end 367.804954 -73.495154)
		(width 0.10795)
		(layer "B.Cu")
		(net "TP_CPLD1_PR7A_PCLKT1_0")
	)
	(segment
		(start 370.345208 -73.495154)
		(end 370.745004 -73.89495)
		(width 0.10795)
		(layer "F.Cu")
		(net "TP_CPLD1_PR9C")
	)
	(via
		(at 370.345208 -73.495154)
		(size 0.4572)
		(drill 0.2032)
		(layers "F.Cu" "B.Cu")
		(net "TP_CPLD1_PR9C")
	)
	(segment
		(start 375.944892 -79.894684)
		(end 375.545096 -79.494888)
		(width 0.10795)
		(layer "F.Cu")
		(net "TP_CPLD1_PB5A_CSSPIN")
	)
	(via
		(at 375.944892 -79.894684)
		(size 0.4572)
		(drill 0.2032)
		(layers "F.Cu" "B.Cu")
		(net "TP_CPLD1_PB5A_CSSPIN")
	)
	(segment
		(start 375.144792 -79.094838)
		(end 374.744996 -78.695042)
		(width 0.10795)
		(layer "F.Cu")
		(net "TP_CPLD1_PB8A_MCLK_CCLK")
	)
	(via
		(at 375.144792 -79.094838)
		(size 0.4572)
		(drill 0.2032)
		(layers "F.Cu" "B.Cu")
		(net "TP_CPLD1_PB8A_MCLK_CCLK")
	)
	(segment
		(start 413.39135 -101.07295)
		(end 411.6578 -99.3394)
		(width 0.10795)
		(layer "F.Cu")
		(net "FM_ADR_SMI_GPIO_N")
	)
	(segment
		(start 415.1884 -113.665)
		(end 415.4932 -113.665)
		(width 0.10795)
		(layer "F.Cu")
		(net "FM_ADR_SMI_GPIO_N")
	)
	(segment
		(start 396.15745 -115.00612)
		(end 396.15745 -114.52225)
		(width 0.10795)
		(layer "F.Cu")
		(net "FM_ADR_SMI_GPIO_N")
	)
	(segment
		(start 415.4932 -113.665)
		(end 415.7218 -113.4364)
		(width 0.10795)
		(layer "F.Cu")
		(net "FM_ADR_SMI_GPIO_N")
	)
	(segment
		(start 414.8455 -114.0079)
		(end 415.1884 -113.665)
		(width 0.10795)
		(layer "F.Cu")
		(net "FM_ADR_SMI_GPIO_N")
	)
	(segment
		(start 396.1384 -114.5032)
		(end 396.1384 -114.460274)
		(width 0.10795)
		(layer "F.Cu")
		(net "FM_ADR_SMI_GPIO_N")
	)
	(segment
		(start 414.7566 -114.173)
		(end 414.8455 -114.173)
		(width 0.10795)
		(layer "F.Cu")
		(net "FM_ADR_SMI_GPIO_N")
	)
	(segment
		(start 414.8455 -114.173)
		(end 414.8455 -114.0079)
		(width 0.10795)
		(layer "F.Cu")
		(net "FM_ADR_SMI_GPIO_N")
	)
	(segment
		(start 396.15745 -114.52225)
		(end 396.1384 -114.5032)
		(width 0.10795)
		(layer "F.Cu")
		(net "FM_ADR_SMI_GPIO_N")
	)
	(segment
		(start 414.1597 -101.9302)
		(end 413.39135 -101.16185)
		(width 0.10795)
		(layer "F.Cu")
		(net "FM_ADR_SMI_GPIO_N")
	)
	(segment
		(start 396.1384 -114.460274)
		(end 396.13713 -114.460274)
		(width 0.10795)
		(layer "F.Cu")
		(net "FM_ADR_SMI_GPIO_N")
	)
	(segment
		(start 414.0962 -114.8334)
		(end 414.7566 -114.173)
		(width 0.10795)
		(layer "F.Cu")
		(net "FM_ADR_SMI_GPIO_N")
	)
	(segment
		(start 413.39135 -101.16185)
		(end 413.39135 -101.07295)
		(width 0.10795)
		(layer "F.Cu")
		(net "FM_ADR_SMI_GPIO_N")
	)
	(segment
		(start 415.7218 -113.4364)
		(end 415.7218 -113.2332)
		(width 0.10795)
		(layer "F.Cu")
		(net "FM_ADR_SMI_GPIO_N")
	)
	(via
		(at 414.1597 -101.9302)
		(size 0.508)
		(drill 0.254)
		(layers "F.Cu" "B.Cu")
		(net "FM_ADR_SMI_GPIO_N")
	)
	(via
		(at 413.623506 -111.7092)
		(size 0.6604)
		(drill 0.3302)
		(layers "F.Cu" "B.Cu")
		(net "FM_ADR_SMI_GPIO_N")
	)
	(via
		(at 414.0962 -114.8334)
		(size 0.508)
		(drill 0.254)
		(layers "F.Cu" "B.Cu")
		(net "FM_ADR_SMI_GPIO_N")
	)
	(via
		(at 396.13713 -114.460274)
		(size 0.508)
		(drill 0.254)
		(layers "F.Cu" "B.Cu")
		(net "FM_ADR_SMI_GPIO_N")
	)
	(via
		(at 380.76378 -65.007236)
		(size 0.508)
		(drill 0.254)
		(layers "F.Cu" "B.Cu")
		(net "FM_ADR_SMI_GPIO_N")
	)
	(segment
		(start 416.055302 -105.189528)
		(end 416.055302 -106.831384)
		(width 0.10795)
		(layer "B.Cu")
		(net "FM_ADR_SMI_GPIO_N")
	)
	(segment
		(start 378.117354 -65.061338)
		(end 378.738892 -64.4398)
		(width 0.10795)
		(layer "B.Cu")
		(net "FM_ADR_SMI_GPIO_N")
	)
	(segment
		(start 413.623506 -114.360706)
		(end 414.0962 -114.8334)
		(width 0.10795)
		(layer "B.Cu")
		(net "FM_ADR_SMI_GPIO_N")
	)
	(segment
		(start 414.424368 -103.558594)
		(end 416.055302 -105.189528)
		(width 0.10795)
		(layer "B.Cu")
		(net "FM_ADR_SMI_GPIO_N")
	)
	(segment
		(start 413.518604 -103.243888)
		(end 413.83331 -103.558594)
		(width 0.10795)
		(layer "B.Cu")
		(net "FM_ADR_SMI_GPIO_N")
	)
	(segment
		(start 376.598942 -64.9732)
		(end 377.345448 -64.9732)
		(width 0.10795)
		(layer "B.Cu")
		(net "FM_ADR_SMI_GPIO_N")
	)
	(segment
		(start 378.738892 -64.4398)
		(end 380.29134 -64.4398)
		(width 0.10795)
		(layer "B.Cu")
		(net "FM_ADR_SMI_GPIO_N")
	)
	(segment
		(start 413.623506 -109.658404)
		(end 413.623506 -111.7092)
		(width 0.10795)
		(layer "B.Cu")
		(net "FM_ADR_SMI_GPIO_N")
	)
	(segment
		(start 377.345448 -64.9732)
		(end 377.433586 -65.061338)
		(width 0.10795)
		(layer "B.Cu")
		(net "FM_ADR_SMI_GPIO_N")
	)
	(segment
		(start 380.76378 -64.91224)
		(end 380.76378 -65.007236)
		(width 0.10795)
		(layer "B.Cu")
		(net "FM_ADR_SMI_GPIO_N")
	)
	(segment
		(start 377.433586 -65.061338)
		(end 378.117354 -65.061338)
		(width 0.10795)
		(layer "B.Cu")
		(net "FM_ADR_SMI_GPIO_N")
	)
	(segment
		(start 413.83331 -103.558594)
		(end 414.424368 -103.558594)
		(width 0.10795)
		(layer "B.Cu")
		(net "FM_ADR_SMI_GPIO_N")
	)
	(segment
		(start 413.518604 -102.571296)
		(end 413.518604 -103.243888)
		(width 0.10795)
		(layer "B.Cu")
		(net "FM_ADR_SMI_GPIO_N")
	)
	(segment
		(start 413.623506 -111.7092)
		(end 413.623506 -114.360706)
		(width 0.10795)
		(layer "B.Cu")
		(net "FM_ADR_SMI_GPIO_N")
	)
	(segment
		(start 414.1597 -101.9302)
		(end 413.518604 -102.571296)
		(width 0.10795)
		(layer "B.Cu")
		(net "FM_ADR_SMI_GPIO_N")
	)
	(segment
		(start 376.174 -66.04)
		(end 376.174 -65.398142)
		(width 0.10795)
		(layer "B.Cu")
		(net "FM_ADR_SMI_GPIO_N")
	)
	(segment
		(start 414.480502 -108.406184)
		(end 414.480502 -108.801408)
		(width 0.10795)
		(layer "B.Cu")
		(net "FM_ADR_SMI_GPIO_N")
	)
	(segment
		(start 380.29134 -64.4398)
		(end 380.76378 -64.91224)
		(width 0.10795)
		(layer "B.Cu")
		(net "FM_ADR_SMI_GPIO_N")
	)
	(segment
		(start 416.055302 -106.831384)
		(end 414.480502 -108.406184)
		(width 0.10795)
		(layer "B.Cu")
		(net "FM_ADR_SMI_GPIO_N")
	)
	(segment
		(start 414.480502 -108.801408)
		(end 413.623506 -109.658404)
		(width 0.10795)
		(layer "B.Cu")
		(net "FM_ADR_SMI_GPIO_N")
	)
	(segment
		(start 376.174 -65.398142)
		(end 376.598942 -64.9732)
		(width 0.10795)
		(layer "B.Cu")
		(net "FM_ADR_SMI_GPIO_N")
	)
	(segment
		(start 405.8412 -118.1608)
		(end 407.0858 -116.9162)
		(width 0.089408)
		(layer "In9.Cu")
		(net "FM_ADR_SMI_GPIO_N")
	)
	(segment
		(start 410.76626 -114.963194)
		(end 411.454854 -114.2746)
		(width 0.089408)
		(layer "In9.Cu")
		(net "FM_ADR_SMI_GPIO_N")
	)
	(segment
		(start 401.2946 -118.1608)
		(end 405.8412 -118.1608)
		(width 0.089408)
		(layer "In9.Cu")
		(net "FM_ADR_SMI_GPIO_N")
	)
	(segment
		(start 396.13713 -114.460274)
		(end 396.553182 -114.876326)
		(width 0.089408)
		(layer "In9.Cu")
		(net "FM_ADR_SMI_GPIO_N")
	)
	(segment
		(start 410.76626 -116.62664)
		(end 410.76626 -114.963194)
		(width 0.089408)
		(layer "In9.Cu")
		(net "FM_ADR_SMI_GPIO_N")
	)
	(segment
		(start 411.454854 -114.2746)
		(end 413.5374 -114.2746)
		(width 0.089408)
		(layer "In9.Cu")
		(net "FM_ADR_SMI_GPIO_N")
	)
	(segment
		(start 413.5374 -114.2746)
		(end 414.0962 -114.8334)
		(width 0.089408)
		(layer "In9.Cu")
		(net "FM_ADR_SMI_GPIO_N")
	)
	(segment
		(start 397.371062 -114.876326)
		(end 397.409924 -114.837464)
		(width 0.089408)
		(layer "In9.Cu")
		(net "FM_ADR_SMI_GPIO_N")
	)
	(segment
		(start 399.98142 -115.59032)
		(end 399.98142 -116.84762)
		(width 0.089408)
		(layer "In9.Cu")
		(net "FM_ADR_SMI_GPIO_N")
	)
	(segment
		(start 399.98142 -116.84762)
		(end 401.2946 -118.1608)
		(width 0.089408)
		(layer "In9.Cu")
		(net "FM_ADR_SMI_GPIO_N")
	)
	(segment
		(start 410.4767 -116.9162)
		(end 410.76626 -116.62664)
		(width 0.089408)
		(layer "In9.Cu")
		(net "FM_ADR_SMI_GPIO_N")
	)
	(segment
		(start 407.0858 -116.9162)
		(end 410.4767 -116.9162)
		(width 0.089408)
		(layer "In9.Cu")
		(net "FM_ADR_SMI_GPIO_N")
	)
	(segment
		(start 397.409924 -114.837464)
		(end 399.228564 -114.837464)
		(width 0.089408)
		(layer "In9.Cu")
		(net "FM_ADR_SMI_GPIO_N")
	)
	(segment
		(start 399.228564 -114.837464)
		(end 399.98142 -115.59032)
		(width 0.089408)
		(layer "In9.Cu")
		(net "FM_ADR_SMI_GPIO_N")
	)
	(segment
		(start 396.553182 -114.876326)
		(end 397.371062 -114.876326)
		(width 0.089408)
		(layer "In9.Cu")
		(net "FM_ADR_SMI_GPIO_N")
	)
	(segment
		(start 383.096008 -78.682342)
		(end 383.096008 -76.798932)
		(width 0.089408)
		(layer "In11.Cu")
		(net "FM_ADR_SMI_GPIO_N")
	)
	(segment
		(start 395.15034 -109.663992)
		(end 395.15034 -109.33684)
		(width 0.089408)
		(layer "In11.Cu")
		(net "FM_ADR_SMI_GPIO_N")
	)
	(segment
		(start 389.32739 -101.438202)
		(end 388.56285 -101.438202)
		(width 0.0889)
		(layer "In11.Cu")
		(net "FM_ADR_SMI_GPIO_N")
	)
	(segment
		(start 390.12876 -102.37724)
		(end 389.73252 -101.981)
		(width 0.089408)
		(layer "In11.Cu")
		(net "FM_ADR_SMI_GPIO_N")
	)
	(segment
		(start 382.37414 -69.317362)
		(end 382.37414 -67.533012)
		(width 0.089408)
		(layer "In11.Cu")
		(net "FM_ADR_SMI_GPIO_N")
	)
	(segment
		(start 389.73252 -101.981)
		(end 389.73252 -101.843332)
		(width 0.089408)
		(layer "In11.Cu")
		(net "FM_ADR_SMI_GPIO_N")
	)
	(segment
		(start 388.13613 -97.440242)
		(end 387.902704 -97.206816)
		(width 0.089408)
		(layer "In11.Cu")
		(net "FM_ADR_SMI_GPIO_N")
	)
	(segment
		(start 382.37414 -67.533012)
		(end 381.048768 -66.20764)
		(width 0.089408)
		(layer "In11.Cu")
		(net "FM_ADR_SMI_GPIO_N")
	)
	(segment
		(start 388.135876 -99.487736)
		(end 388.135876 -98.940874)
		(width 0.0889)
		(layer "In11.Cu")
		(net "FM_ADR_SMI_GPIO_N")
	)
	(segment
		(start 388.13613 -97.77095)
		(end 388.13613 -97.440242)
		(width 0.089408)
		(layer "In11.Cu")
		(net "FM_ADR_SMI_GPIO_N")
	)
	(segment
		(start 392.9888 -103.998014)
		(end 392.907266 -103.91648)
		(width 0.089408)
		(layer "In11.Cu")
		(net "FM_ADR_SMI_GPIO_N")
	)
	(segment
		(start 386.715 -96.78416)
		(end 386.715 -96.5454)
		(width 0.089408)
		(layer "In11.Cu")
		(net "FM_ADR_SMI_GPIO_N")
	)
	(segment
		(start 382.82118 -73.899522)
		(end 382.54051 -73.618852)
		(width 0.089408)
		(layer "In11.Cu")
		(net "FM_ADR_SMI_GPIO_N")
	)
	(segment
		(start 381.048768 -65.292224)
		(end 380.76378 -65.007236)
		(width 0.089408)
		(layer "In11.Cu")
		(net "FM_ADR_SMI_GPIO_N")
	)
	(segment
		(start 387.731 -99.892612)
		(end 388.135876 -99.487736)
		(width 0.0889)
		(layer "In11.Cu")
		(net "FM_ADR_SMI_GPIO_N")
	)
	(segment
		(start 392.29157 -102.784402)
		(end 391.865104 -102.357936)
		(width 0.089408)
		(layer "In11.Cu")
		(net "FM_ADR_SMI_GPIO_N")
	)
	(segment
		(start 382.556258 -79.222092)
		(end 383.096008 -78.682342)
		(width 0.089408)
		(layer "In11.Cu")
		(net "FM_ADR_SMI_GPIO_N")
	)
	(segment
		(start 386.334 -96.1644)
		(end 386.334 -95.7072)
		(width 0.089408)
		(layer "In11.Cu")
		(net "FM_ADR_SMI_GPIO_N")
	)
	(segment
		(start 396.06093 -112.11687)
		(end 396.06093 -111.55553)
		(width 0.089408)
		(layer "In11.Cu")
		(net "FM_ADR_SMI_GPIO_N")
	)
	(segment
		(start 387.831584 -98.636582)
		(end 387.831584 -98.075496)
		(width 0.089408)
		(layer "In11.Cu")
		(net "FM_ADR_SMI_GPIO_N")
	)
	(segment
		(start 387.137656 -97.206816)
		(end 386.715 -96.78416)
		(width 0.089408)
		(layer "In11.Cu")
		(net "FM_ADR_SMI_GPIO_N")
	)
	(segment
		(start 383.6416 -93.0148)
		(end 383.6416 -90.40114)
		(width 0.089408)
		(layer "In11.Cu")
		(net "FM_ADR_SMI_GPIO_N")
	)
	(segment
		(start 394.61694 -107.29214)
		(end 394.61694 -106.714544)
		(width 0.089408)
		(layer "In11.Cu")
		(net "FM_ADR_SMI_GPIO_N")
	)
	(segment
		(start 382.82118 -76.524104)
		(end 382.82118 -73.899522)
		(width 0.089408)
		(layer "In11.Cu")
		(net "FM_ADR_SMI_GPIO_N")
	)
	(segment
		(start 381.048768 -66.20764)
		(end 381.048768 -65.292224)
		(width 0.089408)
		(layer "In11.Cu")
		(net "FM_ADR_SMI_GPIO_N")
	)
	(segment
		(start 395.75867 -112.98047)
		(end 395.75867 -112.41913)
		(width 0.089408)
		(layer "In11.Cu")
		(net "FM_ADR_SMI_GPIO_N")
	)
	(segment
		(start 395.15034 -109.33684)
		(end 394.63726 -108.82376)
		(width 0.089408)
		(layer "In11.Cu")
		(net "FM_ADR_SMI_GPIO_N")
	)
	(segment
		(start 392.29157 -102.92207)
		(end 392.29157 -102.784402)
		(width 0.089408)
		(layer "In11.Cu")
		(net "FM_ADR_SMI_GPIO_N")
	)
	(segment
		(start 386.334 -95.7072)
		(end 383.6416 -93.0148)
		(width 0.089408)
		(layer "In11.Cu")
		(net "FM_ADR_SMI_GPIO_N")
	)
	(segment
		(start 387.902704 -97.206816)
		(end 387.137656 -97.206816)
		(width 0.089408)
		(layer "In11.Cu")
		(net "FM_ADR_SMI_GPIO_N")
	)
	(segment
		(start 388.558532 -101.433884)
		(end 387.676644 -101.433884)
		(width 0.0889)
		(layer "In11.Cu")
		(net "FM_ADR_SMI_GPIO_N")
	)
	(segment
		(start 383.096008 -76.798932)
		(end 382.82118 -76.524104)
		(width 0.089408)
		(layer "In11.Cu")
		(net "FM_ADR_SMI_GPIO_N")
	)
	(segment
		(start 396.13713 -114.460274)
		(end 396.06093 -114.384074)
		(width 0.089408)
		(layer "In11.Cu")
		(net "FM_ADR_SMI_GPIO_N")
	)
	(segment
		(start 392.907266 -103.91648)
		(end 392.907266 -103.400098)
		(width 0.089408)
		(layer "In11.Cu")
		(net "FM_ADR_SMI_GPIO_N")
	)
	(segment
		(start 383.6416 -90.40114)
		(end 384.620008 -89.422732)
		(width 0.089408)
		(layer "In11.Cu")
		(net "FM_ADR_SMI_GPIO_N")
	)
	(segment
		(start 393.7508 -105.848404)
		(end 393.7508 -105.41)
		(width 0.089408)
		(layer "In11.Cu")
		(net "FM_ADR_SMI_GPIO_N")
	)
	(segment
		(start 387.731 -100.255832)
		(end 387.731 -99.892612)
		(width 0.0889)
		(layer "In11.Cu")
		(net "FM_ADR_SMI_GPIO_N")
	)
	(segment
		(start 394.63726 -108.82376)
		(end 394.63726 -108.54436)
		(width 0.089408)
		(layer "In11.Cu")
		(net "FM_ADR_SMI_GPIO_N")
	)
	(segment
		(start 387.676644 -101.433884)
		(end 387.597142 -101.354382)
		(width 0.0889)
		(layer "In11.Cu")
		(net "FM_ADR_SMI_GPIO_N")
	)
	(segment
		(start 382.556258 -79.757524)
		(end 382.556258 -79.222092)
		(width 0.089408)
		(layer "In11.Cu")
		(net "FM_ADR_SMI_GPIO_N")
	)
	(segment
		(start 387.597142 -101.354382)
		(end 387.596634 -101.354382)
		(width 0.0889)
		(layer "In11.Cu")
		(net "FM_ADR_SMI_GPIO_N")
	)
	(segment
		(start 395.7574 -110.271052)
		(end 395.15034 -109.663992)
		(width 0.089408)
		(layer "In11.Cu")
		(net "FM_ADR_SMI_GPIO_N")
	)
	(segment
		(start 390.524492 -102.37724)
		(end 390.12876 -102.37724)
		(width 0.089408)
		(layer "In11.Cu")
		(net "FM_ADR_SMI_GPIO_N")
	)
	(segment
		(start 395.75867 -112.41913)
		(end 396.06093 -112.11687)
		(width 0.089408)
		(layer "In11.Cu")
		(net "FM_ADR_SMI_GPIO_N")
	)
	(segment
		(start 392.662664 -103.155496)
		(end 392.524996 -103.155496)
		(width 0.089408)
		(layer "In11.Cu")
		(net "FM_ADR_SMI_GPIO_N")
	)
	(segment
		(start 395.7574 -111.252)
		(end 395.7574 -110.271052)
		(width 0.089408)
		(layer "In11.Cu")
		(net "FM_ADR_SMI_GPIO_N")
	)
	(segment
		(start 393.7508 -105.41)
		(end 392.9888 -104.648)
		(width 0.089408)
		(layer "In11.Cu")
		(net "FM_ADR_SMI_GPIO_N")
	)
	(segment
		(start 392.9888 -104.648)
		(end 392.9888 -103.998014)
		(width 0.089408)
		(layer "In11.Cu")
		(net "FM_ADR_SMI_GPIO_N")
	)
	(segment
		(start 396.06093 -114.384074)
		(end 396.06093 -113.28273)
		(width 0.089408)
		(layer "In11.Cu")
		(net "FM_ADR_SMI_GPIO_N")
	)
	(segment
		(start 389.73252 -101.843332)
		(end 389.32739 -101.438202)
		(width 0.089408)
		(layer "In11.Cu")
		(net "FM_ADR_SMI_GPIO_N")
	)
	(segment
		(start 392.907266 -103.400098)
		(end 392.662664 -103.155496)
		(width 0.089408)
		(layer "In11.Cu")
		(net "FM_ADR_SMI_GPIO_N")
	)
	(segment
		(start 384.620008 -87.011256)
		(end 385.7498 -85.881464)
		(width 0.089408)
		(layer "In11.Cu")
		(net "FM_ADR_SMI_GPIO_N")
	)
	(segment
		(start 382.54051 -73.618852)
		(end 382.54051 -69.483732)
		(width 0.089408)
		(layer "In11.Cu")
		(net "FM_ADR_SMI_GPIO_N")
	)
	(segment
		(start 394.2334 -108.1405)
		(end 394.2334 -107.67568)
		(width 0.089408)
		(layer "In11.Cu")
		(net "FM_ADR_SMI_GPIO_N")
	)
	(segment
		(start 387.35381 -100.633022)
		(end 387.731 -100.255832)
		(width 0.0889)
		(layer "In11.Cu")
		(net "FM_ADR_SMI_GPIO_N")
	)
	(segment
		(start 384.17754 -82.73542)
		(end 383.7686 -82.32648)
		(width 0.089408)
		(layer "In11.Cu")
		(net "FM_ADR_SMI_GPIO_N")
	)
	(segment
		(start 384.620008 -89.422732)
		(end 384.620008 -87.011256)
		(width 0.089408)
		(layer "In11.Cu")
		(net "FM_ADR_SMI_GPIO_N")
	)
	(segment
		(start 387.596634 -101.354382)
		(end 387.35381 -101.111558)
		(width 0.0889)
		(layer "In11.Cu")
		(net "FM_ADR_SMI_GPIO_N")
	)
	(segment
		(start 391.865104 -102.357936)
		(end 390.543796 -102.357936)
		(width 0.089408)
		(layer "In11.Cu")
		(net "FM_ADR_SMI_GPIO_N")
	)
	(segment
		(start 383.7686 -82.32648)
		(end 383.7686 -80.969866)
		(width 0.089408)
		(layer "In11.Cu")
		(net "FM_ADR_SMI_GPIO_N")
	)
	(segment
		(start 382.54051 -69.483732)
		(end 382.37414 -69.317362)
		(width 0.089408)
		(layer "In11.Cu")
		(net "FM_ADR_SMI_GPIO_N")
	)
	(segment
		(start 383.7686 -80.969866)
		(end 382.556258 -79.757524)
		(width 0.089408)
		(layer "In11.Cu")
		(net "FM_ADR_SMI_GPIO_N")
	)
	(segment
		(start 385.7498 -83.14436)
		(end 385.34086 -82.73542)
		(width 0.089408)
		(layer "In11.Cu")
		(net "FM_ADR_SMI_GPIO_N")
	)
	(segment
		(start 385.7498 -85.881464)
		(end 385.7498 -83.14436)
		(width 0.089408)
		(layer "In11.Cu")
		(net "FM_ADR_SMI_GPIO_N")
	)
	(segment
		(start 388.56285 -101.438202)
		(end 388.558532 -101.433884)
		(width 0.0889)
		(layer "In11.Cu")
		(net "FM_ADR_SMI_GPIO_N")
	)
	(segment
		(start 387.35381 -101.111558)
		(end 387.35381 -100.633022)
		(width 0.0889)
		(layer "In11.Cu")
		(net "FM_ADR_SMI_GPIO_N")
	)
	(segment
		(start 394.63726 -108.54436)
		(end 394.2334 -108.1405)
		(width 0.089408)
		(layer "In11.Cu")
		(net "FM_ADR_SMI_GPIO_N")
	)
	(segment
		(start 385.34086 -82.73542)
		(end 384.17754 -82.73542)
		(width 0.089408)
		(layer "In11.Cu")
		(net "FM_ADR_SMI_GPIO_N")
	)
	(segment
		(start 394.2334 -107.67568)
		(end 394.61694 -107.29214)
		(width 0.089408)
		(layer "In11.Cu")
		(net "FM_ADR_SMI_GPIO_N")
	)
	(segment
		(start 387.831584 -98.075496)
		(end 388.13613 -97.77095)
		(width 0.089408)
		(layer "In11.Cu")
		(net "FM_ADR_SMI_GPIO_N")
	)
	(segment
		(start 388.135876 -98.940874)
		(end 387.831584 -98.636582)
		(width 0.0889)
		(layer "In11.Cu")
		(net "FM_ADR_SMI_GPIO_N")
	)
	(segment
		(start 396.06093 -113.28273)
		(end 395.75867 -112.98047)
		(width 0.089408)
		(layer "In11.Cu")
		(net "FM_ADR_SMI_GPIO_N")
	)
	(segment
		(start 394.61694 -106.714544)
		(end 393.7508 -105.848404)
		(width 0.089408)
		(layer "In11.Cu")
		(net "FM_ADR_SMI_GPIO_N")
	)
	(segment
		(start 396.06093 -111.55553)
		(end 395.7574 -111.252)
		(width 0.089408)
		(layer "In11.Cu")
		(net "FM_ADR_SMI_GPIO_N")
	)
	(segment
		(start 392.524996 -103.155496)
		(end 392.29157 -102.92207)
		(width 0.089408)
		(layer "In11.Cu")
		(net "FM_ADR_SMI_GPIO_N")
	)
	(segment
		(start 386.715 -96.5454)
		(end 386.334 -96.1644)
		(width 0.089408)
		(layer "In11.Cu")
		(net "FM_ADR_SMI_GPIO_N")
	)
	(segment
		(start 390.543796 -102.357936)
		(end 390.524492 -102.37724)
		(width 0.089408)
		(layer "In11.Cu")
		(net "FM_ADR_SMI_GPIO_N")
	)
	(segment
		(start 484.242618 -29.28747)
		(end 483.56901 -29.28747)
		(width 0.10795)
		(layer "F.Cu")
		(net "CLK_32K_SUSCLK_PLD")
	)
	(segment
		(start 483.56901 -29.28747)
		(end 483.56266 -29.28112)
		(width 0.10795)
		(layer "F.Cu")
		(net "CLK_32K_SUSCLK_PLD")
	)
	(segment
		(start 379.3998 -71.494904)
		(end 378.744988 -71.494904)
		(width 0.10795)
		(layer "F.Cu")
		(net "CLK_32K_SUSCLK_PLD")
	)
	(via
		(at 379.3998 -71.494904)
		(size 0.508)
		(drill 0.254)
		(layers "F.Cu" "B.Cu")
		(net "CLK_32K_SUSCLK_PLD")
	)
	(via
		(at 478.4852 -45.4914)
		(size 0.508)
		(drill 0.254)
		(layers "F.Cu" "B.Cu")
		(net "CLK_32K_SUSCLK_PLD")
	)
	(via
		(at 392.0236 -70.5866)
		(size 0.6604)
		(drill 0.3302)
		(layers "F.Cu" "B.Cu")
		(net "CLK_32K_SUSCLK_PLD")
	)
	(via
		(at 484.242618 -29.28747)
		(size 0.508)
		(drill 0.254)
		(layers "F.Cu" "B.Cu")
		(net "CLK_32K_SUSCLK_PLD")
	)
	(via
		(at 405.689054 -60.499752)
		(size 0.508)
		(drill 0.254)
		(layers "F.Cu" "B.Cu")
		(net "CLK_32K_SUSCLK_PLD")
	)
	(via
		(at 403.225 -60.067444)
		(size 0.6604)
		(drill 0.3302)
		(layers "F.Cu" "B.Cu")
		(net "CLK_32K_SUSCLK_PLD")
	)
	(segment
		(start 400.387058 -63.818516)
		(end 400.387058 -62.63513)
		(width 0.10795)
		(layer "B.Cu")
		(net "CLK_32K_SUSCLK_PLD")
	)
	(segment
		(start 388.037832 -71.365872)
		(end 387.037072 -72.366632)
		(width 0.10795)
		(layer "B.Cu")
		(net "CLK_32K_SUSCLK_PLD")
	)
	(segment
		(start 399.388076 -65.593976)
		(end 399.803874 -65.178178)
		(width 0.10795)
		(layer "B.Cu")
		(net "CLK_32K_SUSCLK_PLD")
	)
	(segment
		(start 380.769622 -72.693022)
		(end 379.571504 -71.494904)
		(width 0.10795)
		(layer "B.Cu")
		(net "CLK_32K_SUSCLK_PLD")
	)
	(segment
		(start 396.264638 -68.390516)
		(end 396.729712 -67.925442)
		(width 0.10795)
		(layer "B.Cu")
		(net "CLK_32K_SUSCLK_PLD")
	)
	(segment
		(start 395.136116 -68.390516)
		(end 396.264638 -68.390516)
		(width 0.10795)
		(layer "B.Cu")
		(net "CLK_32K_SUSCLK_PLD")
	)
	(segment
		(start 392.53922 -70.5866)
		(end 394.734796 -68.391024)
		(width 0.10795)
		(layer "B.Cu")
		(net "CLK_32K_SUSCLK_PLD")
	)
	(segment
		(start 405.064976 -59.660282)
		(end 405.689054 -60.28436)
		(width 0.10795)
		(layer "B.Cu")
		(net "CLK_32K_SUSCLK_PLD")
	)
	(segment
		(start 402.954744 -60.067444)
		(end 403.225 -60.067444)
		(width 0.10795)
		(layer "B.Cu")
		(net "CLK_32K_SUSCLK_PLD")
	)
	(segment
		(start 388.069328 -71.365872)
		(end 388.037832 -71.365872)
		(width 0.10795)
		(layer "B.Cu")
		(net "CLK_32K_SUSCLK_PLD")
	)
	(segment
		(start 385.8514 -73.5838)
		(end 382.327658 -73.5838)
		(width 0.10795)
		(layer "B.Cu")
		(net "CLK_32K_SUSCLK_PLD")
	)
	(segment
		(start 381.43688 -72.693022)
		(end 380.769622 -72.693022)
		(width 0.10795)
		(layer "B.Cu")
		(net "CLK_32K_SUSCLK_PLD")
	)
	(segment
		(start 397.28267 -67.925442)
		(end 397.282924 -67.925188)
		(width 0.10795)
		(layer "B.Cu")
		(net "CLK_32K_SUSCLK_PLD")
	)
	(segment
		(start 382.327658 -73.5838)
		(end 381.43688 -72.693022)
		(width 0.10795)
		(layer "B.Cu")
		(net "CLK_32K_SUSCLK_PLD")
	)
	(segment
		(start 387.037072 -72.398128)
		(end 385.8514 -73.5838)
		(width 0.10795)
		(layer "B.Cu")
		(net "CLK_32K_SUSCLK_PLD")
	)
	(segment
		(start 392.0236 -70.5866)
		(end 391.327894 -70.5866)
		(width 0.10795)
		(layer "B.Cu")
		(net "CLK_32K_SUSCLK_PLD")
	)
	(segment
		(start 395.135608 -68.391024)
		(end 395.136116 -68.390516)
		(width 0.10795)
		(layer "B.Cu")
		(net "CLK_32K_SUSCLK_PLD")
	)
	(segment
		(start 397.282924 -67.925188)
		(end 397.547846 -67.925188)
		(width 0.10795)
		(layer "B.Cu")
		(net "CLK_32K_SUSCLK_PLD")
	)
	(segment
		(start 379.571504 -71.494904)
		(end 379.3998 -71.494904)
		(width 0.10795)
		(layer "B.Cu")
		(net "CLK_32K_SUSCLK_PLD")
	)
	(segment
		(start 399.388076 -66.084958)
		(end 399.388076 -65.593976)
		(width 0.10795)
		(layer "B.Cu")
		(net "CLK_32K_SUSCLK_PLD")
	)
	(segment
		(start 394.734796 -68.391024)
		(end 395.135608 -68.391024)
		(width 0.10795)
		(layer "B.Cu")
		(net "CLK_32K_SUSCLK_PLD")
	)
	(segment
		(start 392.0236 -70.5866)
		(end 392.53922 -70.5866)
		(width 0.10795)
		(layer "B.Cu")
		(net "CLK_32K_SUSCLK_PLD")
	)
	(segment
		(start 403.225 -60.067444)
		(end 403.632162 -59.660282)
		(width 0.10795)
		(layer "B.Cu")
		(net "CLK_32K_SUSCLK_PLD")
	)
	(segment
		(start 388.5946 -70.8406)
		(end 388.069328 -71.365872)
		(width 0.10795)
		(layer "B.Cu")
		(net "CLK_32K_SUSCLK_PLD")
	)
	(segment
		(start 391.073894 -70.8406)
		(end 388.5946 -70.8406)
		(width 0.10795)
		(layer "B.Cu")
		(net "CLK_32K_SUSCLK_PLD")
	)
	(segment
		(start 399.803874 -64.4017)
		(end 400.387058 -63.818516)
		(width 0.10795)
		(layer "B.Cu")
		(net "CLK_32K_SUSCLK_PLD")
	)
	(segment
		(start 399.803874 -65.178178)
		(end 399.803874 -64.4017)
		(width 0.10795)
		(layer "B.Cu")
		(net "CLK_32K_SUSCLK_PLD")
	)
	(segment
		(start 405.689054 -60.28436)
		(end 405.689054 -60.499752)
		(width 0.10795)
		(layer "B.Cu")
		(net "CLK_32K_SUSCLK_PLD")
	)
	(segment
		(start 403.632162 -59.660282)
		(end 405.064976 -59.660282)
		(width 0.10795)
		(layer "B.Cu")
		(net "CLK_32K_SUSCLK_PLD")
	)
	(segment
		(start 400.387058 -62.63513)
		(end 402.954744 -60.067444)
		(width 0.10795)
		(layer "B.Cu")
		(net "CLK_32K_SUSCLK_PLD")
	)
	(segment
		(start 387.037072 -72.366632)
		(end 387.037072 -72.398128)
		(width 0.10795)
		(layer "B.Cu")
		(net "CLK_32K_SUSCLK_PLD")
	)
	(segment
		(start 397.547846 -67.925188)
		(end 399.388076 -66.084958)
		(width 0.10795)
		(layer "B.Cu")
		(net "CLK_32K_SUSCLK_PLD")
	)
	(segment
		(start 396.729712 -67.925442)
		(end 397.28267 -67.925442)
		(width 0.10795)
		(layer "B.Cu")
		(net "CLK_32K_SUSCLK_PLD")
	)
	(segment
		(start 391.327894 -70.5866)
		(end 391.073894 -70.8406)
		(width 0.10795)
		(layer "B.Cu")
		(net "CLK_32K_SUSCLK_PLD")
	)
	(segment
		(start 430.510442 -52.15255)
		(end 430.510696 -52.152804)
		(width 0.089408)
		(layer "In2.Cu")
		(net "CLK_32K_SUSCLK_PLD")
	)
	(segment
		(start 425.60113 -50.671476)
		(end 427.082458 -52.152804)
		(width 0.089408)
		(layer "In2.Cu")
		(net "CLK_32K_SUSCLK_PLD")
	)
	(segment
		(start 473.054172 -47.745396)
		(end 476.693738 -47.745396)
		(width 0.089408)
		(layer "In2.Cu")
		(net "CLK_32K_SUSCLK_PLD")
	)
	(segment
		(start 432.18227 -52.152804)
		(end 432.182524 -52.15255)
		(width 0.089408)
		(layer "In2.Cu")
		(net "CLK_32K_SUSCLK_PLD")
	)
	(segment
		(start 420.358824 -50.2412)
		(end 424.261534 -50.2412)
		(width 0.089408)
		(layer "In2.Cu")
		(net "CLK_32K_SUSCLK_PLD")
	)
	(segment
		(start 406.57526 -58.140092)
		(end 406.57526 -53.585872)
		(width 0.089408)
		(layer "In2.Cu")
		(net "CLK_32K_SUSCLK_PLD")
	)
	(segment
		(start 419.068504 -51.53152)
		(end 420.358824 -50.2412)
		(width 0.089408)
		(layer "In2.Cu")
		(net "CLK_32K_SUSCLK_PLD")
	)
	(segment
		(start 406.57526 -53.585872)
		(end 408.629612 -51.53152)
		(width 0.089408)
		(layer "In2.Cu")
		(net "CLK_32K_SUSCLK_PLD")
	)
	(segment
		(start 408.629612 -51.53152)
		(end 419.068504 -51.53152)
		(width 0.089408)
		(layer "In2.Cu")
		(net "CLK_32K_SUSCLK_PLD")
	)
	(segment
		(start 424.69181 -50.671476)
		(end 425.60113 -50.671476)
		(width 0.089408)
		(layer "In2.Cu")
		(net "CLK_32K_SUSCLK_PLD")
	)
	(segment
		(start 424.261534 -50.2412)
		(end 424.69181 -50.671476)
		(width 0.089408)
		(layer "In2.Cu")
		(net "CLK_32K_SUSCLK_PLD")
	)
	(segment
		(start 477.879664 -46.096936)
		(end 478.4852 -45.4914)
		(width 0.089408)
		(layer "In2.Cu")
		(net "CLK_32K_SUSCLK_PLD")
	)
	(segment
		(start 432.182524 -52.15255)
		(end 434.664612 -52.15255)
		(width 0.089408)
		(layer "In2.Cu")
		(net "CLK_32K_SUSCLK_PLD")
	)
	(segment
		(start 428.820834 -52.15255)
		(end 430.510442 -52.15255)
		(width 0.089408)
		(layer "In2.Cu")
		(net "CLK_32K_SUSCLK_PLD")
	)
	(segment
		(start 471.993722 -48.805846)
		(end 473.054172 -47.745396)
		(width 0.089408)
		(layer "In2.Cu")
		(net "CLK_32K_SUSCLK_PLD")
	)
	(segment
		(start 436.492396 -52.152804)
		(end 439.392568 -49.252632)
		(width 0.089408)
		(layer "In2.Cu")
		(net "CLK_32K_SUSCLK_PLD")
	)
	(segment
		(start 470.6112 -48.805846)
		(end 471.993722 -48.805846)
		(width 0.089408)
		(layer "In2.Cu")
		(net "CLK_32K_SUSCLK_PLD")
	)
	(segment
		(start 405.6888 -60.499752)
		(end 405.6888 -59.026552)
		(width 0.089408)
		(layer "In2.Cu")
		(net "CLK_32K_SUSCLK_PLD")
	)
	(segment
		(start 405.6888 -59.026552)
		(end 406.57526 -58.140092)
		(width 0.089408)
		(layer "In2.Cu")
		(net "CLK_32K_SUSCLK_PLD")
	)
	(segment
		(start 470.164414 -49.252632)
		(end 470.6112 -48.805846)
		(width 0.089408)
		(layer "In2.Cu")
		(net "CLK_32K_SUSCLK_PLD")
	)
	(segment
		(start 434.664866 -52.152804)
		(end 436.492396 -52.152804)
		(width 0.089408)
		(layer "In2.Cu")
		(net "CLK_32K_SUSCLK_PLD")
	)
	(segment
		(start 476.693738 -47.745396)
		(end 477.879664 -46.55947)
		(width 0.089408)
		(layer "In2.Cu")
		(net "CLK_32K_SUSCLK_PLD")
	)
	(segment
		(start 405.689054 -60.499752)
		(end 405.6888 -60.499752)
		(width 0.089408)
		(layer "In2.Cu")
		(net "CLK_32K_SUSCLK_PLD")
	)
	(segment
		(start 427.082458 -52.152804)
		(end 428.82058 -52.152804)
		(width 0.089408)
		(layer "In2.Cu")
		(net "CLK_32K_SUSCLK_PLD")
	)
	(segment
		(start 477.879664 -46.55947)
		(end 477.879664 -46.096936)
		(width 0.089408)
		(layer "In2.Cu")
		(net "CLK_32K_SUSCLK_PLD")
	)
	(segment
		(start 434.664612 -52.15255)
		(end 434.664866 -52.152804)
		(width 0.089408)
		(layer "In2.Cu")
		(net "CLK_32K_SUSCLK_PLD")
	)
	(segment
		(start 428.82058 -52.152804)
		(end 428.820834 -52.15255)
		(width 0.089408)
		(layer "In2.Cu")
		(net "CLK_32K_SUSCLK_PLD")
	)
	(segment
		(start 439.392568 -49.252632)
		(end 470.164414 -49.252632)
		(width 0.089408)
		(layer "In2.Cu")
		(net "CLK_32K_SUSCLK_PLD")
	)
	(segment
		(start 430.510696 -52.152804)
		(end 432.18227 -52.152804)
		(width 0.089408)
		(layer "In2.Cu")
		(net "CLK_32K_SUSCLK_PLD")
	)
	(segment
		(start 481.955348 -40.42283)
		(end 481.955348 -37.457634)
		(width 0.089408)
		(layer "In9.Cu")
		(net "CLK_32K_SUSCLK_PLD")
	)
	(segment
		(start 481.5459 -33.801812)
		(end 481.5459 -30.2133)
		(width 0.089408)
		(layer "In9.Cu")
		(net "CLK_32K_SUSCLK_PLD")
	)
	(segment
		(start 480.398328 -41.97985)
		(end 481.955348 -40.42283)
		(width 0.089408)
		(layer "In9.Cu")
		(net "CLK_32K_SUSCLK_PLD")
	)
	(segment
		(start 481.955348 -37.457634)
		(end 480.83216 -36.334446)
		(width 0.089408)
		(layer "In9.Cu")
		(net "CLK_32K_SUSCLK_PLD")
	)
	(segment
		(start 482.47173 -29.28747)
		(end 484.242618 -29.28747)
		(width 0.089408)
		(layer "In9.Cu")
		(net "CLK_32K_SUSCLK_PLD")
	)
	(segment
		(start 478.8662 -45.8724)
		(end 479.4504 -45.8724)
		(width 0.089408)
		(layer "In9.Cu")
		(net "CLK_32K_SUSCLK_PLD")
	)
	(segment
		(start 478.4852 -45.4914)
		(end 478.8662 -45.8724)
		(width 0.089408)
		(layer "In9.Cu")
		(net "CLK_32K_SUSCLK_PLD")
	)
	(segment
		(start 480.398328 -44.924472)
		(end 480.398328 -41.97985)
		(width 0.089408)
		(layer "In9.Cu")
		(net "CLK_32K_SUSCLK_PLD")
	)
	(segment
		(start 480.83216 -34.515552)
		(end 481.5459 -33.801812)
		(width 0.089408)
		(layer "In9.Cu")
		(net "CLK_32K_SUSCLK_PLD")
	)
	(segment
		(start 479.4504 -45.8724)
		(end 480.398328 -44.924472)
		(width 0.089408)
		(layer "In9.Cu")
		(net "CLK_32K_SUSCLK_PLD")
	)
	(segment
		(start 481.5459 -30.2133)
		(end 482.47173 -29.28747)
		(width 0.089408)
		(layer "In9.Cu")
		(net "CLK_32K_SUSCLK_PLD")
	)
	(segment
		(start 480.83216 -36.334446)
		(end 480.83216 -34.515552)
		(width 0.089408)
		(layer "In9.Cu")
		(net "CLK_32K_SUSCLK_PLD")
	)
	(segment
		(start 116.208302 -89.089738)
		(end 115.636802 -89.089738)
		(width 0.254)
		(layer "F.Cu")
		(net "A_CPU1_MCP01_RBIAS")
	)
	(segment
		(start 112.649 -83.7692)
		(end 112.522 -83.8962)
		(width 0.2032)
		(layer "F.Cu")
		(net "A_CPU1_MCP01_RBIAS")
	)
	(segment
		(start 115.2398 -83.7692)
		(end 112.649 -83.7692)
		(width 0.2032)
		(layer "F.Cu")
		(net "A_CPU1_MCP01_RBIAS")
	)
	(segment
		(start 116.0526 -84.582)
		(end 115.2398 -83.7692)
		(width 0.2032)
		(layer "F.Cu")
		(net "A_CPU1_MCP01_RBIAS")
	)
	(segment
		(start 116.495322 -88.594184)
		(end 116.208302 -89.089738)
		(width 0.254)
		(layer "F.Cu")
		(net "A_CPU1_MCP01_RBIAS")
	)
	(segment
		(start 112.522 -83.8962)
		(end 112.2934 -83.8962)
		(width 0.2032)
		(layer "F.Cu")
		(net "A_CPU1_MCP01_RBIAS")
	)
	(via
		(at 116.0526 -84.582)
		(size 0.508)
		(drill 0.254)
		(layers "F.Cu" "B.Cu")
		(net "A_CPU1_MCP01_RBIAS")
	)
	(via
		(at 116.208302 -89.089738)
		(size 0.508)
		(drill 0.254)
		(layers "F.Cu" "B.Cu")
		(net "A_CPU1_MCP01_RBIAS")
	)
	(segment
		(start 116.520976 -87.76716)
		(end 116.663978 -87.910162)
		(width 0.2032)
		(layer "B.Cu")
		(net "A_CPU1_MCP01_RBIAS")
	)
	(segment
		(start 116.663978 -87.910162)
		(end 116.663978 -88.634062)
		(width 0.2032)
		(layer "B.Cu")
		(net "A_CPU1_MCP01_RBIAS")
	)
	(segment
		(start 116.0526 -84.582)
		(end 115.951 -84.6836)
		(width 0.2032)
		(layer "B.Cu")
		(net "A_CPU1_MCP01_RBIAS")
	)
	(segment
		(start 115.951 -86.141814)
		(end 116.520976 -86.71179)
		(width 0.2032)
		(layer "B.Cu")
		(net "A_CPU1_MCP01_RBIAS")
	)
	(segment
		(start 115.951 -84.6836)
		(end 115.951 -86.141814)
		(width 0.2032)
		(layer "B.Cu")
		(net "A_CPU1_MCP01_RBIAS")
	)
	(segment
		(start 116.520976 -86.71179)
		(end 116.520976 -87.76716)
		(width 0.2032)
		(layer "B.Cu")
		(net "A_CPU1_MCP01_RBIAS")
	)
	(segment
		(start 116.663978 -88.634062)
		(end 116.208302 -89.089738)
		(width 0.2032)
		(layer "B.Cu")
		(net "A_CPU1_MCP01_RBIAS")
	)
	(segment
		(start 169.037 -73.2028)
		(end 169.8498 -72.39)
		(width 0.254)
		(layer "F.Cu")
		(net "P3V3_DB1200_R")
	)
	(segment
		(start 169.037 -73.7108)
		(end 169.037 -73.2028)
		(width 0.254)
		(layer "F.Cu")
		(net "P3V3_DB1200_R")
	)
	(via
		(at 169.8498 -72.39)
		(size 0.762)
		(drill 0.381)
		(layers "F.Cu" "B.Cu")
		(net "P3V3_DB1200_R")
	)
	(via
		(at 168.723818 -74.337672)
		(size 0.508)
		(drill 0.254)
		(layers "F.Cu" "B.Cu")
		(net "P3V3_DB1200_R")
	)
	(segment
		(start 168.718484 -74.337672)
		(end 168.718484 -74.3712)
		(width 0.508)
		(layer "B.Cu")
		(net "P3V3_DB1200_R")
	)
	(segment
		(start 169.226484 -74.8792)
		(end 169.545 -74.8792)
		(width 0.508)
		(layer "B.Cu")
		(net "P3V3_DB1200_R")
	)
	(segment
		(start 168.723818 -74.337672)
		(end 168.718484 -74.337672)
		(width 0.508)
		(layer "B.Cu")
		(net "P3V3_DB1200_R")
	)
	(segment
		(start 168.718484 -74.3712)
		(end 169.226484 -74.8792)
		(width 0.508)
		(layer "B.Cu")
		(net "P3V3_DB1200_R")
	)
	(via
		(at 164.21608 -75.5396)
		(size 0.508)
		(drill 0.254)
		(layers "F.Cu" "B.Cu")
		(net "P3V3_DB1200_A")
	)
	(segment
		(start 169.673016 -86.079584)
		(end 169.6466 -86.106)
		(width 0.254)
		(layer "F.Cu")
		(net "P3V3_DB1200")
	)
	(segment
		(start 165.054026 -84.713064)
		(end 165.054026 -85.262974)
		(width 0.254)
		(layer "F.Cu")
		(net "P3V3_DB1200")
	)
	(segment
		(start 175.707548 -73.69556)
		(end 175.88738 -73.69556)
		(width 0.254)
		(layer "F.Cu")
		(net "P3V3_DB1200")
	)
	(segment
		(start 174.639224 -75.004168)
		(end 174.639224 -74.763884)
		(width 0.254)
		(layer "F.Cu")
		(net "P3V3_DB1200")
	)
	(segment
		(start 176.36744 -73.69556)
		(end 176.53 -73.533)
		(width 0.254)
		(layer "F.Cu")
		(net "P3V3_DB1200")
	)
	(segment
		(start 165.054026 -81.212182)
		(end 164.405818 -81.212182)
		(width 0.254)
		(layer "F.Cu")
		(net "P3V3_DB1200")
	)
	(segment
		(start 166.681404 -73.056242)
		(end 166.634668 -73.009506)
		(width 0.254)
		(layer "F.Cu")
		(net "P3V3_DB1200")
	)
	(segment
		(start 169.673016 -85.330792)
		(end 169.673016 -86.079584)
		(width 0.254)
		(layer "F.Cu")
		(net "P3V3_DB1200")
	)
	(segment
		(start 164.430456 -80.712056)
		(end 164.3126 -80.5942)
		(width 0.254)
		(layer "F.Cu")
		(net "P3V3_DB1200")
	)
	(segment
		(start 175.88738 -73.69556)
		(end 176.36744 -73.69556)
		(width 0.254)
		(layer "F.Cu")
		(net "P3V3_DB1200")
	)
	(segment
		(start 173.791626 -80.712056)
		(end 174.439834 -80.712056)
		(width 0.254)
		(layer "F.Cu")
		(net "P3V3_DB1200")
	)
	(segment
		(start 167.294052 -73.056242)
		(end 166.681404 -73.056242)
		(width 0.254)
		(layer "F.Cu")
		(net "P3V3_DB1200")
	)
	(segment
		(start 165.054026 -80.712056)
		(end 164.430456 -80.712056)
		(width 0.254)
		(layer "F.Cu")
		(net "P3V3_DB1200")
	)
	(segment
		(start 171.989496 -74.972672)
		(end 171.989496 -74.781664)
		(width 0.254)
		(layer "F.Cu")
		(net "P3V3_DB1200")
	)
	(segment
		(start 166.497 -73.147174)
		(end 166.497 -73.66)
		(width 0.254)
		(layer "F.Cu")
		(net "P3V3_DB1200")
	)
	(segment
		(start 174.439834 -80.712056)
		(end 174.533052 -80.618838)
		(width 0.254)
		(layer "F.Cu")
		(net "P3V3_DB1200")
	)
	(segment
		(start 174.639224 -74.763884)
		(end 175.707548 -73.69556)
		(width 0.254)
		(layer "F.Cu")
		(net "P3V3_DB1200")
	)
	(segment
		(start 166.634668 -73.009506)
		(end 166.497 -73.147174)
		(width 0.254)
		(layer "F.Cu")
		(net "P3V3_DB1200")
	)
	(segment
		(start 173.791626 -84.713064)
		(end 173.867064 -84.713064)
		(width 0.254)
		(layer "F.Cu")
		(net "P3V3_DB1200")
	)
	(segment
		(start 162.7886 -72.644)
		(end 162.975036 -72.830436)
		(width 0.254)
		(layer "F.Cu")
		(net "P3V3_DB1200")
	)
	(segment
		(start 173.867064 -84.713064)
		(end 174.3964 -85.2424)
		(width 0.254)
		(layer "F.Cu")
		(net "P3V3_DB1200")
	)
	(segment
		(start 164.405818 -81.212182)
		(end 164.3126 -81.3054)
		(width 0.254)
		(layer "F.Cu")
		(net "P3V3_DB1200")
	)
	(segment
		(start 165.054026 -85.262974)
		(end 164.8206 -85.4964)
		(width 0.254)
		(layer "F.Cu")
		(net "P3V3_DB1200")
	)
	(segment
		(start 174.5742 -81.212182)
		(end 174.5996 -81.237582)
		(width 0.254)
		(layer "F.Cu")
		(net "P3V3_DB1200")
	)
	(segment
		(start 173.791626 -81.212182)
		(end 174.5742 -81.212182)
		(width 0.254)
		(layer "F.Cu")
		(net "P3V3_DB1200")
	)
	(segment
		(start 161.124646 -74.9808)
		(end 162.0012 -74.9808)
		(width 0.254)
		(layer "F.Cu")
		(net "P3V3_DB1200")
	)
	(segment
		(start 160.748726 -74.60488)
		(end 161.124646 -74.9808)
		(width 0.254)
		(layer "F.Cu")
		(net "P3V3_DB1200")
	)
	(segment
		(start 170.3832 -74.3204)
		(end 170.6626 -74.041)
		(width 0.508)
		(layer "F.Cu")
		(net "P3V3_DB1200")
	)
	(segment
		(start 171.248832 -74.041)
		(end 171.069 -74.041)
		(width 0.254)
		(layer "F.Cu")
		(net "P3V3_DB1200")
	)
	(segment
		(start 171.989496 -74.781664)
		(end 171.248832 -74.041)
		(width 0.254)
		(layer "F.Cu")
		(net "P3V3_DB1200")
	)
	(segment
		(start 170.6626 -74.041)
		(end 171.069 -74.041)
		(width 0.508)
		(layer "F.Cu")
		(net "P3V3_DB1200")
	)
	(segment
		(start 162.975036 -74.006964)
		(end 162.0012 -74.9808)
		(width 0.254)
		(layer "F.Cu")
		(net "P3V3_DB1200")
	)
	(segment
		(start 162.975036 -72.830436)
		(end 162.975036 -74.006964)
		(width 0.254)
		(layer "F.Cu")
		(net "P3V3_DB1200")
	)
	(via
		(at 164.3126 -80.5942)
		(size 0.508)
		(drill 0.254)
		(layers "F.Cu" "B.Cu")
		(net "P3V3_DB1200")
	)
	(via
		(at 174.3964 -85.2424)
		(size 0.508)
		(drill 0.254)
		(layers "F.Cu" "B.Cu")
		(net "P3V3_DB1200")
	)
	(via
		(at 174.533052 -80.618838)
		(size 0.508)
		(drill 0.254)
		(layers "F.Cu" "B.Cu")
		(net "P3V3_DB1200")
	)
	(via
		(at 170.3832 -74.3204)
		(size 0.508)
		(drill 0.254)
		(layers "F.Cu" "B.Cu")
		(net "P3V3_DB1200")
	)
	(via
		(at 164.3126 -81.3054)
		(size 0.508)
		(drill 0.254)
		(layers "F.Cu" "B.Cu")
		(net "P3V3_DB1200")
	)
	(via
		(at 166.634668 -73.009506)
		(size 0.508)
		(drill 0.254)
		(layers "F.Cu" "B.Cu")
		(net "P3V3_DB1200")
	)
	(via
		(at 164.8206 -85.4964)
		(size 0.508)
		(drill 0.254)
		(layers "F.Cu" "B.Cu")
		(net "P3V3_DB1200")
	)
	(via
		(at 160.748726 -74.60488)
		(size 0.508)
		(drill 0.254)
		(layers "F.Cu" "B.Cu")
		(net "P3V3_DB1200")
	)
	(via
		(at 174.5996 -81.237582)
		(size 0.508)
		(drill 0.254)
		(layers "F.Cu" "B.Cu")
		(net "P3V3_DB1200")
	)
	(via
		(at 176.53 -73.533)
		(size 0.508)
		(drill 0.254)
		(layers "F.Cu" "B.Cu")
		(net "P3V3_DB1200")
	)
	(via
		(at 169.6466 -86.106)
		(size 0.508)
		(drill 0.254)
		(layers "F.Cu" "B.Cu")
		(net "P3V3_DB1200")
	)
	(segment
		(start 164.973 -80.391)
		(end 164.5158 -80.391)
		(width 0.4064)
		(layer "B.Cu")
		(net "P3V3_DB1200")
	)
	(segment
		(start 174.498508 -81.237582)
		(end 174.5996 -81.237582)
		(width 0.254)
		(layer "B.Cu")
		(net "P3V3_DB1200")
	)
	(segment
		(start 174.07509 -81.661)
		(end 174.498508 -81.237582)
		(width 0.254)
		(layer "B.Cu")
		(net "P3V3_DB1200")
	)
	(segment
		(start 164.5158 -80.391)
		(end 164.3126 -80.5942)
		(width 0.4064)
		(layer "B.Cu")
		(net "P3V3_DB1200")
	)
	(segment
		(start 174.533052 -80.618838)
		(end 174.50689 -80.645)
		(width 0.254)
		(layer "B.Cu")
		(net "P3V3_DB1200")
	)
	(segment
		(start 169.6466 -85.4964)
		(end 169.799 -85.344)
		(width 0.4064)
		(layer "B.Cu")
		(net "P3V3_DB1200")
	)
	(segment
		(start 174.50689 -80.645)
		(end 173.863 -80.645)
		(width 0.254)
		(layer "B.Cu")
		(net "P3V3_DB1200")
	)
	(segment
		(start 164.8206 -85.4964)
		(end 164.973 -85.344)
		(width 0.254)
		(layer "B.Cu")
		(net "P3V3_DB1200")
	)
	(segment
		(start 164.4142 -81.407)
		(end 164.3126 -81.3054)
		(width 0.4064)
		(layer "B.Cu")
		(net "P3V3_DB1200")
	)
	(segment
		(start 173.863 -81.661)
		(end 174.07509 -81.661)
		(width 0.254)
		(layer "B.Cu")
		(net "P3V3_DB1200")
	)
	(segment
		(start 174.3964 -85.2424)
		(end 173.863 -84.709)
		(width 0.254)
		(layer "B.Cu")
		(net "P3V3_DB1200")
	)
	(segment
		(start 164.973 -85.344)
		(end 164.973 -84.709)
		(width 0.254)
		(layer "B.Cu")
		(net "P3V3_DB1200")
	)
	(segment
		(start 169.6466 -86.106)
		(end 169.6466 -85.4964)
		(width 0.4064)
		(layer "B.Cu")
		(net "P3V3_DB1200")
	)
	(segment
		(start 173.863 -84.709)
		(end 173.863 -84.582)
		(width 0.254)
		(layer "B.Cu")
		(net "P3V3_DB1200")
	)
	(segment
		(start 164.973 -81.407)
		(end 164.4142 -81.407)
		(width 0.4064)
		(layer "B.Cu")
		(net "P3V3_DB1200")
	)
	(segment
		(start 167.672512 -76.593192)
		(end 167.672512 -75.39482)
		(width 0.10795)
		(layer "F.Cu")
		(net "FM_HBW_BYPASS_LOWBW_N")
	)
	(segment
		(start 167.294052 -73.945242)
		(end 167.294052 -74.69886)
		(width 0.10795)
		(layer "F.Cu")
		(net "FM_HBW_BYPASS_LOWBW_N")
	)
	(segment
		(start 167.672512 -75.07732)
		(end 167.672512 -75.39482)
		(width 0.10795)
		(layer "F.Cu")
		(net "FM_HBW_BYPASS_LOWBW_N")
	)
	(segment
		(start 167.294052 -74.69886)
		(end 167.348662 -74.75347)
		(width 0.10795)
		(layer "F.Cu")
		(net "FM_HBW_BYPASS_LOWBW_N")
	)
	(segment
		(start 167.348662 -74.75347)
		(end 167.672512 -75.07732)
		(width 0.10795)
		(layer "F.Cu")
		(net "FM_HBW_BYPASS_LOWBW_N")
	)
	(via
		(at 167.672512 -75.39482)
		(size 0.508)
		(drill 0.254)
		(layers "F.Cu" "B.Cu")
		(net "FM_HBW_BYPASS_LOWBW_N")
	)
	(via
		(at 167.348662 -74.75347)
		(size 0.508)
		(drill 0.254)
		(layers "F.Cu" "B.Cu")
		(net "FM_HBW_BYPASS_LOWBW_N")
	)
	(segment
		(start 167.288718 -74.693526)
		(end 167.348662 -74.75347)
		(width 0.10795)
		(layer "B.Cu")
		(net "FM_HBW_BYPASS_LOWBW_N")
	)
	(segment
		(start 167.288718 -74.135234)
		(end 167.288718 -74.693526)
		(width 0.10795)
		(layer "B.Cu")
		(net "FM_HBW_BYPASS_LOWBW_N")
	)
	(segment
		(start 173.5582 -75.635612)
		(end 174.157132 -75.635612)
		(width 0.10795)
		(layer "F.Cu")
		(net "FM_DB1200_SMB_SA1")
	)
	(segment
		(start 173.163992 -76.02982)
		(end 173.5582 -75.635612)
		(width 0.10795)
		(layer "F.Cu")
		(net "FM_DB1200_SMB_SA1")
	)
	(segment
		(start 175.88738 -74.58456)
		(end 174.7139 -75.75804)
		(width 0.10795)
		(layer "F.Cu")
		(net "FM_DB1200_SMB_SA1")
	)
	(segment
		(start 172.173646 -76.593192)
		(end 172.173646 -76.281534)
		(width 0.10795)
		(layer "F.Cu")
		(net "FM_DB1200_SMB_SA1")
	)
	(segment
		(start 174.7139 -75.75804)
		(end 174.27956 -75.75804)
		(width 0.10795)
		(layer "F.Cu")
		(net "FM_DB1200_SMB_SA1")
	)
	(segment
		(start 174.157132 -75.635612)
		(end 174.27956 -75.75804)
		(width 0.10795)
		(layer "F.Cu")
		(net "FM_DB1200_SMB_SA1")
	)
	(segment
		(start 172.42536 -76.02982)
		(end 173.163992 -76.02982)
		(width 0.10795)
		(layer "F.Cu")
		(net "FM_DB1200_SMB_SA1")
	)
	(segment
		(start 172.173646 -76.281534)
		(end 172.42536 -76.02982)
		(width 0.10795)
		(layer "F.Cu")
		(net "FM_DB1200_SMB_SA1")
	)
	(via
		(at 174.27956 -75.75804)
		(size 0.508)
		(drill 0.254)
		(layers "F.Cu" "B.Cu")
		(net "FM_DB1200_SMB_SA1")
	)
	(segment
		(start 173.482 -74.96048)
		(end 174.27956 -75.75804)
		(width 0.10795)
		(layer "B.Cu")
		(net "FM_DB1200_SMB_SA1")
	)
	(segment
		(start 173.482 -74.8792)
		(end 173.482 -74.96048)
		(width 0.10795)
		(layer "B.Cu")
		(net "FM_DB1200_SMB_SA1")
	)
	(segment
		(start 171.069 -74.93)
		(end 171.069 -75.604624)
		(width 0.10795)
		(layer "F.Cu")
		(net "FM_DB1200_SMB_SA0")
	)
	(segment
		(start 170.673268 -76.214732)
		(end 171.176188 -75.711812)
		(width 0.10795)
		(layer "F.Cu")
		(net "FM_DB1200_SMB_SA0")
	)
	(segment
		(start 170.673268 -76.593192)
		(end 170.673268 -76.214732)
		(width 0.10795)
		(layer "F.Cu")
		(net "FM_DB1200_SMB_SA0")
	)
	(segment
		(start 171.069 -75.604624)
		(end 171.176188 -75.711812)
		(width 0.10795)
		(layer "F.Cu")
		(net "FM_DB1200_SMB_SA0")
	)
	(via
		(at 171.176188 -75.711812)
		(size 0.508)
		(drill 0.254)
		(layers "F.Cu" "B.Cu")
		(net "FM_DB1200_SMB_SA0")
	)
	(segment
		(start 171.069 -75.604624)
		(end 171.176188 -75.711812)
		(width 0.10795)
		(layer "B.Cu")
		(net "FM_DB1200_SMB_SA0")
	)
	(segment
		(start 171.069 -74.93)
		(end 171.069 -75.604624)
		(width 0.10795)
		(layer "B.Cu")
		(net "FM_DB1200_SMB_SA0")
	)
	(segment
		(start 378.096526 -108.99648)
		(end 378.32665 -108.766356)
		(width 0.127)
		(layer "F.Cu")
		(net "CLK_100M_DB1200_DP")
	)
	(segment
		(start 169.800524 -75.922124)
		(end 169.672 -75.7936)
		(width 0.127)
		(layer "F.Cu")
		(net "CLK_100M_DB1200_DP")
	)
	(segment
		(start 169.673016 -76.344272)
		(end 169.800524 -76.216764)
		(width 0.127)
		(layer "F.Cu")
		(net "CLK_100M_DB1200_DP")
	)
	(segment
		(start 377.83135 -108.99648)
		(end 378.096526 -108.99648)
		(width 0.127)
		(layer "F.Cu")
		(net "CLK_100M_DB1200_DP")
	)
	(segment
		(start 169.800524 -76.216764)
		(end 169.800524 -75.922124)
		(width 0.127)
		(layer "F.Cu")
		(net "CLK_100M_DB1200_DP")
	)
	(segment
		(start 169.673016 -76.593192)
		(end 169.673016 -76.344272)
		(width 0.127)
		(layer "F.Cu")
		(net "CLK_100M_DB1200_DP")
	)
	(via
		(at 191.2366 -131.729734)
		(size 0.508)
		(drill 0.254)
		(layers "F.Cu" "B.Cu")
		(net "CLK_100M_DB1200_DP")
	)
	(via
		(at 378.32665 -108.766356)
		(size 0.508)
		(drill 0.254)
		(layers "F.Cu" "B.Cu")
		(net "CLK_100M_DB1200_DP")
	)
	(via
		(at 169.672 -75.7936)
		(size 0.508)
		(drill 0.254)
		(layers "F.Cu" "B.Cu")
		(net "CLK_100M_DB1200_DP")
	)
	(segment
		(start 175.102774 -75.54722)
		(end 176.670716 -79.329534)
		(width 0.1143)
		(layer "In4.Cu")
		(net "CLK_100M_DB1200_DP")
	)
	(segment
		(start 170.176698 -74.857102)
		(end 171.03344 -74.857102)
		(width 0.1143)
		(layer "In4.Cu")
		(net "CLK_100M_DB1200_DP")
	)
	(segment
		(start 174.142654 -74.5871)
		(end 175.102774 -75.54722)
		(width 0.1143)
		(layer "In4.Cu")
		(net "CLK_100M_DB1200_DP")
	)
	(segment
		(start 182.407052 -104.495854)
		(end 182.407052 -107.27309)
		(width 0.1143)
		(layer "In4.Cu")
		(net "CLK_100M_DB1200_DP")
	)
	(segment
		(start 182.211218 -97.487232)
		(end 182.211218 -104.30002)
		(width 0.1143)
		(layer "In4.Cu")
		(net "CLK_100M_DB1200_DP")
	)
	(segment
		(start 169.811446 -75.222354)
		(end 170.176698 -74.857102)
		(width 0.1143)
		(layer "In4.Cu")
		(net "CLK_100M_DB1200_DP")
	)
	(segment
		(start 171.03344 -74.857102)
		(end 171.303442 -74.5871)
		(width 0.1143)
		(layer "In4.Cu")
		(net "CLK_100M_DB1200_DP")
	)
	(segment
		(start 182.407052 -107.27309)
		(end 186.522614 -124.231654)
		(width 0.1143)
		(layer "In4.Cu")
		(net "CLK_100M_DB1200_DP")
	)
	(segment
		(start 182.211218 -104.30002)
		(end 182.407052 -104.495854)
		(width 0.1143)
		(layer "In4.Cu")
		(net "CLK_100M_DB1200_DP")
	)
	(segment
		(start 186.522614 -124.231654)
		(end 186.522614 -127.270002)
		(width 0.1143)
		(layer "In4.Cu")
		(net "CLK_100M_DB1200_DP")
	)
	(segment
		(start 180.509926 -89.812622)
		(end 182.211218 -97.487232)
		(width 0.1143)
		(layer "In4.Cu")
		(net "CLK_100M_DB1200_DP")
	)
	(segment
		(start 169.811446 -75.654154)
		(end 169.811446 -75.222354)
		(width 0.1143)
		(layer "In4.Cu")
		(net "CLK_100M_DB1200_DP")
	)
	(segment
		(start 191.06515 -131.901184)
		(end 191.2366 -131.729734)
		(width 0.1143)
		(layer "In4.Cu")
		(net "CLK_100M_DB1200_DP")
	)
	(segment
		(start 178.19497 -80.854042)
		(end 180.509926 -86.442296)
		(width 0.1143)
		(layer "In4.Cu")
		(net "CLK_100M_DB1200_DP")
	)
	(segment
		(start 180.509926 -86.442296)
		(end 180.509926 -89.812622)
		(width 0.1143)
		(layer "In4.Cu")
		(net "CLK_100M_DB1200_DP")
	)
	(segment
		(start 187.029344 -129.784348)
		(end 187.029344 -131.464558)
		(width 0.1143)
		(layer "In4.Cu")
		(net "CLK_100M_DB1200_DP")
	)
	(segment
		(start 189.554358 -132.566156)
		(end 190.21933 -131.901184)
		(width 0.1143)
		(layer "In4.Cu")
		(net "CLK_100M_DB1200_DP")
	)
	(segment
		(start 169.672 -75.7936)
		(end 169.811446 -75.654154)
		(width 0.1143)
		(layer "In4.Cu")
		(net "CLK_100M_DB1200_DP")
	)
	(segment
		(start 171.303442 -74.5871)
		(end 174.142654 -74.5871)
		(width 0.1143)
		(layer "In4.Cu")
		(net "CLK_100M_DB1200_DP")
	)
	(segment
		(start 190.21933 -131.901184)
		(end 191.06515 -131.901184)
		(width 0.1143)
		(layer "In4.Cu")
		(net "CLK_100M_DB1200_DP")
	)
	(segment
		(start 186.522614 -127.270002)
		(end 187.029344 -129.784348)
		(width 0.1143)
		(layer "In4.Cu")
		(net "CLK_100M_DB1200_DP")
	)
	(segment
		(start 188.130942 -132.566156)
		(end 189.554358 -132.566156)
		(width 0.1143)
		(layer "In4.Cu")
		(net "CLK_100M_DB1200_DP")
	)
	(segment
		(start 176.670716 -79.329534)
		(end 178.19497 -80.854042)
		(width 0.1143)
		(layer "In4.Cu")
		(net "CLK_100M_DB1200_DP")
	)
	(segment
		(start 187.029344 -131.464558)
		(end 188.130942 -132.566156)
		(width 0.1143)
		(layer "In4.Cu")
		(net "CLK_100M_DB1200_DP")
	)
	(segment
		(start 345.363292 -128.24079)
		(end 350.193102 -128.24079)
		(width 0.1143)
		(layer "In9.Cu")
		(net "CLK_100M_DB1200_DP")
	)
	(segment
		(start 192.2399 -130.14452)
		(end 192.2399 -129.78892)
		(width 0.1143)
		(layer "In9.Cu")
		(net "CLK_100M_DB1200_DP")
	)
	(segment
		(start 192.405 -130.30962)
		(end 192.2399 -130.14452)
		(width 0.1143)
		(layer "In9.Cu")
		(net "CLK_100M_DB1200_DP")
	)
	(segment
		(start 375.666 -112.48517)
		(end 375.7168 -112.43437)
		(width 0.0889)
		(layer "In9.Cu")
		(net "CLK_100M_DB1200_DP")
	)
	(segment
		(start 192.2399 -131.18592)
		(end 192.2399 -130.83032)
		(width 0.1143)
		(layer "In9.Cu")
		(net "CLK_100M_DB1200_DP")
	)
	(segment
		(start 192.2399 -128.74752)
		(end 192.405 -128.58242)
		(width 0.1143)
		(layer "In9.Cu")
		(net "CLK_100M_DB1200_DP")
	)
	(segment
		(start 369.268502 -122.823986)
		(end 370.159788 -121.9327)
		(width 0.1143)
		(layer "In9.Cu")
		(net "CLK_100M_DB1200_DP")
	)
	(segment
		(start 374.396 -116.459)
		(end 375.666 -115.189)
		(width 0.1143)
		(layer "In9.Cu")
		(net "CLK_100M_DB1200_DP")
	)
	(segment
		(start 365.520732 -127.259842)
		(end 366.348518 -126.942088)
		(width 0.1143)
		(layer "In9.Cu")
		(net "CLK_100M_DB1200_DP")
	)
	(segment
		(start 192.240408 -131.951984)
		(end 192.405 -131.787392)
		(width 0.1143)
		(layer "In9.Cu")
		(net "CLK_100M_DB1200_DP")
	)
	(segment
		(start 192.405 -128.22682)
		(end 193.060574 -127.570992)
		(width 0.1143)
		(layer "In9.Cu")
		(net "CLK_100M_DB1200_DP")
	)
	(segment
		(start 275.607018 -125.26772)
		(end 287.328864 -128.8542)
		(width 0.1143)
		(layer "In9.Cu")
		(net "CLK_100M_DB1200_DP")
	)
	(segment
		(start 192.405 -130.66522)
		(end 192.405 -130.30962)
		(width 0.1143)
		(layer "In9.Cu")
		(net "CLK_100M_DB1200_DP")
	)
	(segment
		(start 192.2399 -130.83032)
		(end 192.405 -130.66522)
		(width 0.1143)
		(layer "In9.Cu")
		(net "CLK_100M_DB1200_DP")
	)
	(segment
		(start 333.479394 -125.652276)
		(end 338.07273 -124.573538)
		(width 0.1143)
		(layer "In9.Cu")
		(net "CLK_100M_DB1200_DP")
	)
	(segment
		(start 192.405 -129.62382)
		(end 192.405 -129.26822)
		(width 0.1143)
		(layer "In9.Cu")
		(net "CLK_100M_DB1200_DP")
	)
	(segment
		(start 192.405 -131.35102)
		(end 192.2399 -131.18592)
		(width 0.1143)
		(layer "In9.Cu")
		(net "CLK_100M_DB1200_DP")
	)
	(segment
		(start 324.247256 -128.7399)
		(end 328.71283 -127.52578)
		(width 0.1143)
		(layer "In9.Cu")
		(net "CLK_100M_DB1200_DP")
	)
	(segment
		(start 344.309192 -126.289816)
		(end 344.309192 -127.18669)
		(width 0.1143)
		(layer "In9.Cu")
		(net "CLK_100M_DB1200_DP")
	)
	(segment
		(start 246.73179 -127.953008)
		(end 256.987548 -126.660402)
		(width 0.1143)
		(layer "In9.Cu")
		(net "CLK_100M_DB1200_DP")
	)
	(segment
		(start 338.07273 -124.573538)
		(end 342.592914 -124.573538)
		(width 0.1143)
		(layer "In9.Cu")
		(net "CLK_100M_DB1200_DP")
	)
	(segment
		(start 344.309192 -127.18669)
		(end 345.363292 -128.24079)
		(width 0.1143)
		(layer "In9.Cu")
		(net "CLK_100M_DB1200_DP")
	)
	(segment
		(start 323.161406 -128.8542)
		(end 323.275706 -128.7399)
		(width 0.1143)
		(layer "In9.Cu")
		(net "CLK_100M_DB1200_DP")
	)
	(segment
		(start 192.405 -129.26822)
		(end 192.2399 -129.10312)
		(width 0.1143)
		(layer "In9.Cu")
		(net "CLK_100M_DB1200_DP")
	)
	(segment
		(start 256.987548 -126.660402)
		(end 264.467086 -126.660402)
		(width 0.1143)
		(layer "In9.Cu")
		(net "CLK_100M_DB1200_DP")
	)
	(segment
		(start 191.2366 -131.729734)
		(end 191.45885 -131.951984)
		(width 0.1143)
		(layer "In9.Cu")
		(net "CLK_100M_DB1200_DP")
	)
	(segment
		(start 377.232926 -111.405416)
		(end 378.351288 -109.356398)
		(width 0.0889)
		(layer "In9.Cu")
		(net "CLK_100M_DB1200_DP")
	)
	(segment
		(start 328.71283 -127.52578)
		(end 331.929232 -125.652276)
		(width 0.1143)
		(layer "In9.Cu")
		(net "CLK_100M_DB1200_DP")
	)
	(segment
		(start 350.193102 -128.24079)
		(end 350.552512 -128.6002)
		(width 0.1143)
		(layer "In9.Cu")
		(net "CLK_100M_DB1200_DP")
	)
	(segment
		(start 374.396 -118.179342)
		(end 374.396 -116.459)
		(width 0.1143)
		(layer "In9.Cu")
		(net "CLK_100M_DB1200_DP")
	)
	(segment
		(start 358.599486 -127.259842)
		(end 365.520732 -127.259842)
		(width 0.1143)
		(layer "In9.Cu")
		(net "CLK_100M_DB1200_DP")
	)
	(segment
		(start 366.348518 -126.942088)
		(end 369.268502 -124.022104)
		(width 0.1143)
		(layer "In9.Cu")
		(net "CLK_100M_DB1200_DP")
	)
	(segment
		(start 370.642642 -121.9327)
		(end 374.396 -118.179342)
		(width 0.1143)
		(layer "In9.Cu")
		(net "CLK_100M_DB1200_DP")
	)
	(segment
		(start 245.957852 -128.726946)
		(end 246.73179 -127.953008)
		(width 0.1143)
		(layer "In9.Cu")
		(net "CLK_100M_DB1200_DP")
	)
	(segment
		(start 221.918022 -128.726946)
		(end 245.957852 -128.726946)
		(width 0.1143)
		(layer "In9.Cu")
		(net "CLK_100M_DB1200_DP")
	)
	(segment
		(start 375.666 -115.189)
		(end 375.666 -112.507268)
		(width 0.1143)
		(layer "In9.Cu")
		(net "CLK_100M_DB1200_DP")
	)
	(segment
		(start 274.445984 -125.26772)
		(end 275.607018 -125.26772)
		(width 0.1143)
		(layer "In9.Cu")
		(net "CLK_100M_DB1200_DP")
	)
	(segment
		(start 378.7267 -108.980986)
		(end 378.7267 -108.855256)
		(width 0.0889)
		(layer "In9.Cu")
		(net "CLK_100M_DB1200_DP")
	)
	(segment
		(start 378.351288 -109.356398)
		(end 378.7267 -108.980986)
		(width 0.0889)
		(layer "In9.Cu")
		(net "CLK_100M_DB1200_DP")
	)
	(segment
		(start 369.268502 -124.022104)
		(end 369.268502 -122.823986)
		(width 0.1143)
		(layer "In9.Cu")
		(net "CLK_100M_DB1200_DP")
	)
	(segment
		(start 264.467086 -126.660402)
		(end 274.445984 -125.26772)
		(width 0.1143)
		(layer "In9.Cu")
		(net "CLK_100M_DB1200_DP")
	)
	(segment
		(start 194.275202 -127.347472)
		(end 212.015324 -127.347472)
		(width 0.1143)
		(layer "In9.Cu")
		(net "CLK_100M_DB1200_DP")
	)
	(segment
		(start 191.45885 -131.951984)
		(end 192.240408 -131.951984)
		(width 0.1143)
		(layer "In9.Cu")
		(net "CLK_100M_DB1200_DP")
	)
	(segment
		(start 375.7168 -112.211612)
		(end 376.179334 -111.749078)
		(width 0.0889)
		(layer "In9.Cu")
		(net "CLK_100M_DB1200_DP")
	)
	(segment
		(start 370.159788 -121.9327)
		(end 370.642642 -121.9327)
		(width 0.1143)
		(layer "In9.Cu")
		(net "CLK_100M_DB1200_DP")
	)
	(segment
		(start 376.889264 -111.749078)
		(end 377.232926 -111.405416)
		(width 0.0889)
		(layer "In9.Cu")
		(net "CLK_100M_DB1200_DP")
	)
	(segment
		(start 192.2399 -129.10312)
		(end 192.2399 -128.74752)
		(width 0.1143)
		(layer "In9.Cu")
		(net "CLK_100M_DB1200_DP")
	)
	(segment
		(start 378.6378 -108.766356)
		(end 378.32665 -108.766356)
		(width 0.0889)
		(layer "In9.Cu")
		(net "CLK_100M_DB1200_DP")
	)
	(segment
		(start 350.552512 -128.6002)
		(end 353.582478 -128.6002)
		(width 0.1143)
		(layer "In9.Cu")
		(net "CLK_100M_DB1200_DP")
	)
	(segment
		(start 192.405 -128.58242)
		(end 192.405 -128.22682)
		(width 0.1143)
		(layer "In9.Cu")
		(net "CLK_100M_DB1200_DP")
	)
	(segment
		(start 287.328864 -128.8542)
		(end 323.161406 -128.8542)
		(width 0.1143)
		(layer "In9.Cu")
		(net "CLK_100M_DB1200_DP")
	)
	(segment
		(start 323.275706 -128.7399)
		(end 324.247256 -128.7399)
		(width 0.1143)
		(layer "In9.Cu")
		(net "CLK_100M_DB1200_DP")
	)
	(segment
		(start 331.929232 -125.652276)
		(end 333.479394 -125.652276)
		(width 0.1143)
		(layer "In9.Cu")
		(net "CLK_100M_DB1200_DP")
	)
	(segment
		(start 375.666 -112.507268)
		(end 375.666 -112.48517)
		(width 0.0889)
		(layer "In9.Cu")
		(net "CLK_100M_DB1200_DP")
	)
	(segment
		(start 192.2399 -129.78892)
		(end 192.405 -129.62382)
		(width 0.1143)
		(layer "In9.Cu")
		(net "CLK_100M_DB1200_DP")
	)
	(segment
		(start 193.060574 -127.570992)
		(end 194.275202 -127.347472)
		(width 0.1143)
		(layer "In9.Cu")
		(net "CLK_100M_DB1200_DP")
	)
	(segment
		(start 375.7168 -112.43437)
		(end 375.7168 -112.211612)
		(width 0.0889)
		(layer "In9.Cu")
		(net "CLK_100M_DB1200_DP")
	)
	(segment
		(start 192.405 -131.787392)
		(end 192.405 -131.35102)
		(width 0.1143)
		(layer "In9.Cu")
		(net "CLK_100M_DB1200_DP")
	)
	(segment
		(start 342.592914 -124.573538)
		(end 344.309192 -126.289816)
		(width 0.1143)
		(layer "In9.Cu")
		(net "CLK_100M_DB1200_DP")
	)
	(segment
		(start 353.582478 -128.6002)
		(end 358.599486 -127.259842)
		(width 0.1143)
		(layer "In9.Cu")
		(net "CLK_100M_DB1200_DP")
	)
	(segment
		(start 376.179334 -111.749078)
		(end 376.889264 -111.749078)
		(width 0.0889)
		(layer "In9.Cu")
		(net "CLK_100M_DB1200_DP")
	)
	(segment
		(start 378.7267 -108.855256)
		(end 378.6378 -108.766356)
		(width 0.0889)
		(layer "In9.Cu")
		(net "CLK_100M_DB1200_DP")
	)
	(segment
		(start 212.015324 -127.347472)
		(end 221.918022 -128.726946)
		(width 0.1143)
		(layer "In9.Cu")
		(net "CLK_100M_DB1200_DP")
	)
	(segment
		(start 170.173142 -76.593192)
		(end 170.173142 -76.269088)
		(width 0.127)
		(layer "F.Cu")
		(net "CLK_100M_DB1200_DN")
	)
	(segment
		(start 378.82195 -108.99648)
		(end 379.087126 -108.99648)
		(width 0.127)
		(layer "F.Cu")
		(net "CLK_100M_DB1200_DN")
	)
	(segment
		(start 170.307 -75.7936)
		(end 170.3832 -75.7936)
		(width 0.127)
		(layer "F.Cu")
		(net "CLK_100M_DB1200_DN")
	)
	(segment
		(start 170.105324 -75.995276)
		(end 170.307 -75.7936)
		(width 0.127)
		(layer "F.Cu")
		(net "CLK_100M_DB1200_DN")
	)
	(segment
		(start 379.087126 -108.99648)
		(end 379.31725 -108.766356)
		(width 0.127)
		(layer "F.Cu")
		(net "CLK_100M_DB1200_DN")
	)
	(segment
		(start 170.105324 -76.20127)
		(end 170.105324 -75.995276)
		(width 0.127)
		(layer "F.Cu")
		(net "CLK_100M_DB1200_DN")
	)
	(segment
		(start 170.173142 -76.269088)
		(end 170.105324 -76.20127)
		(width 0.127)
		(layer "F.Cu")
		(net "CLK_100M_DB1200_DN")
	)
	(via
		(at 170.3832 -75.7936)
		(size 0.508)
		(drill 0.254)
		(layers "F.Cu" "B.Cu")
		(net "CLK_100M_DB1200_DN")
	)
	(via
		(at 191.2366 -132.364734)
		(size 0.508)
		(drill 0.254)
		(layers "F.Cu" "B.Cu")
		(net "CLK_100M_DB1200_DN")
	)
	(via
		(at 379.31725 -108.766356)
		(size 0.508)
		(drill 0.254)
		(layers "F.Cu" "B.Cu")
		(net "CLK_100M_DB1200_DN")
	)
	(segment
		(start 176.422812 -79.495142)
		(end 177.947066 -81.01965)
		(width 0.1143)
		(layer "In4.Cu")
		(net "CLK_100M_DB1200_DN")
	)
	(segment
		(start 186.737244 -129.813558)
		(end 186.737244 -131.585716)
		(width 0.1143)
		(layer "In4.Cu")
		(net "CLK_100M_DB1200_DN")
	)
	(segment
		(start 182.690008 -109.677708)
		(end 182.568596 -109.877098)
		(width 0.1143)
		(layer "In4.Cu")
		(net "CLK_100M_DB1200_DN")
	)
	(segment
		(start 174.021496 -74.8792)
		(end 174.855124 -75.712828)
		(width 0.1143)
		(layer "In4.Cu")
		(net "CLK_100M_DB1200_DN")
	)
	(segment
		(start 182.652416 -110.222792)
		(end 182.851806 -110.344204)
		(width 0.1143)
		(layer "In4.Cu")
		(net "CLK_100M_DB1200_DN")
	)
	(segment
		(start 182.198772 -107.653836)
		(end 182.07736 -107.852972)
		(width 0.1143)
		(layer "In4.Cu")
		(net "CLK_100M_DB1200_DN")
	)
	(segment
		(start 182.44439 -108.665772)
		(end 182.322978 -108.865162)
		(width 0.1143)
		(layer "In4.Cu")
		(net "CLK_100M_DB1200_DN")
	)
	(segment
		(start 181.919118 -97.519236)
		(end 181.919118 -104.421178)
		(width 0.1143)
		(layer "In4.Cu")
		(net "CLK_100M_DB1200_DN")
	)
	(segment
		(start 182.36057 -108.320078)
		(end 182.44439 -108.665772)
		(width 0.1143)
		(layer "In4.Cu")
		(net "CLK_100M_DB1200_DN")
	)
	(segment
		(start 180.217826 -89.844626)
		(end 181.919118 -97.519236)
		(width 0.1143)
		(layer "In4.Cu")
		(net "CLK_100M_DB1200_DN")
	)
	(segment
		(start 182.114952 -107.308142)
		(end 182.198772 -107.653836)
		(width 0.1143)
		(layer "In4.Cu")
		(net "CLK_100M_DB1200_DN")
	)
	(segment
		(start 188.009784 -132.858256)
		(end 189.675516 -132.858256)
		(width 0.1143)
		(layer "In4.Cu")
		(net "CLK_100M_DB1200_DN")
	)
	(segment
		(start 182.568596 -109.877098)
		(end 182.652416 -110.222792)
		(width 0.1143)
		(layer "In4.Cu")
		(net "CLK_100M_DB1200_DN")
	)
	(segment
		(start 186.230514 -127.299212)
		(end 186.737244 -129.813558)
		(width 0.1143)
		(layer "In4.Cu")
		(net "CLK_100M_DB1200_DN")
	)
	(segment
		(start 190.340488 -132.193284)
		(end 191.06515 -132.193284)
		(width 0.1143)
		(layer "In4.Cu")
		(net "CLK_100M_DB1200_DN")
	)
	(segment
		(start 181.919118 -104.421178)
		(end 182.114952 -104.617012)
		(width 0.1143)
		(layer "In4.Cu")
		(net "CLK_100M_DB1200_DN")
	)
	(segment
		(start 182.406798 -109.210602)
		(end 182.606188 -109.332268)
		(width 0.1143)
		(layer "In4.Cu")
		(net "CLK_100M_DB1200_DN")
	)
	(segment
		(start 191.06515 -132.193284)
		(end 191.2366 -132.364734)
		(width 0.1143)
		(layer "In4.Cu")
		(net "CLK_100M_DB1200_DN")
	)
	(segment
		(start 182.322978 -108.865162)
		(end 182.406798 -109.210602)
		(width 0.1143)
		(layer "In4.Cu")
		(net "CLK_100M_DB1200_DN")
	)
	(segment
		(start 182.07736 -107.852972)
		(end 182.16118 -108.198666)
		(width 0.1143)
		(layer "In4.Cu")
		(net "CLK_100M_DB1200_DN")
	)
	(segment
		(start 174.855124 -75.712828)
		(end 176.422812 -79.495142)
		(width 0.1143)
		(layer "In4.Cu")
		(net "CLK_100M_DB1200_DN")
	)
	(segment
		(start 170.103546 -75.343512)
		(end 170.297856 -75.149202)
		(width 0.1143)
		(layer "In4.Cu")
		(net "CLK_100M_DB1200_DN")
	)
	(segment
		(start 180.217826 -86.500462)
		(end 180.217826 -89.844626)
		(width 0.1143)
		(layer "In4.Cu")
		(net "CLK_100M_DB1200_DN")
	)
	(segment
		(start 182.16118 -108.198666)
		(end 182.36057 -108.320078)
		(width 0.1143)
		(layer "In4.Cu")
		(net "CLK_100M_DB1200_DN")
	)
	(segment
		(start 171.154598 -75.149202)
		(end 171.4246 -74.8792)
		(width 0.1143)
		(layer "In4.Cu")
		(net "CLK_100M_DB1200_DN")
	)
	(segment
		(start 170.297856 -75.149202)
		(end 171.154598 -75.149202)
		(width 0.1143)
		(layer "In4.Cu")
		(net "CLK_100M_DB1200_DN")
	)
	(segment
		(start 182.606188 -109.332268)
		(end 182.690008 -109.677708)
		(width 0.1143)
		(layer "In4.Cu")
		(net "CLK_100M_DB1200_DN")
	)
	(segment
		(start 171.4246 -74.8792)
		(end 174.021496 -74.8792)
		(width 0.1143)
		(layer "In4.Cu")
		(net "CLK_100M_DB1200_DN")
	)
	(segment
		(start 189.675516 -132.858256)
		(end 190.340488 -132.193284)
		(width 0.1143)
		(layer "In4.Cu")
		(net "CLK_100M_DB1200_DN")
	)
	(segment
		(start 177.947066 -81.01965)
		(end 180.217826 -86.500462)
		(width 0.1143)
		(layer "In4.Cu")
		(net "CLK_100M_DB1200_DN")
	)
	(segment
		(start 186.230514 -124.266706)
		(end 186.230514 -127.299212)
		(width 0.1143)
		(layer "In4.Cu")
		(net "CLK_100M_DB1200_DN")
	)
	(segment
		(start 182.851806 -110.344204)
		(end 186.230514 -124.266706)
		(width 0.1143)
		(layer "In4.Cu")
		(net "CLK_100M_DB1200_DN")
	)
	(segment
		(start 170.3832 -75.7936)
		(end 170.103546 -75.513946)
		(width 0.1143)
		(layer "In4.Cu")
		(net "CLK_100M_DB1200_DN")
	)
	(segment
		(start 170.103546 -75.513946)
		(end 170.103546 -75.343512)
		(width 0.1143)
		(layer "In4.Cu")
		(net "CLK_100M_DB1200_DN")
	)
	(segment
		(start 182.114952 -104.617012)
		(end 182.114952 -107.308142)
		(width 0.1143)
		(layer "In4.Cu")
		(net "CLK_100M_DB1200_DN")
	)
	(segment
		(start 186.737244 -131.585716)
		(end 188.009784 -132.858256)
		(width 0.1143)
		(layer "In4.Cu")
		(net "CLK_100M_DB1200_DN")
	)
	(segment
		(start 375.9581 -112.507268)
		(end 375.9581 -112.48517)
		(width 0.0889)
		(layer "In9.Cu")
		(net "CLK_100M_DB1200_DN")
	)
	(segment
		(start 193.203068 -127.84201)
		(end 194.302126 -127.639572)
		(width 0.1143)
		(layer "In9.Cu")
		(net "CLK_100M_DB1200_DN")
	)
	(segment
		(start 350.071944 -128.53289)
		(end 350.431354 -128.8923)
		(width 0.1143)
		(layer "In9.Cu")
		(net "CLK_100M_DB1200_DN")
	)
	(segment
		(start 377.387104 -111.520732)
		(end 378.505466 -109.471714)
		(width 0.0889)
		(layer "In9.Cu")
		(net "CLK_100M_DB1200_DN")
	)
	(segment
		(start 353.620832 -128.8923)
		(end 358.63784 -127.551942)
		(width 0.1143)
		(layer "In9.Cu")
		(net "CLK_100M_DB1200_DN")
	)
	(segment
		(start 257.00609 -126.952502)
		(end 264.487406 -126.952502)
		(width 0.1143)
		(layer "In9.Cu")
		(net "CLK_100M_DB1200_DN")
	)
	(segment
		(start 275.56333 -125.55982)
		(end 287.285176 -129.1463)
		(width 0.1143)
		(layer "In9.Cu")
		(net "CLK_100M_DB1200_DN")
	)
	(segment
		(start 344.017092 -126.410974)
		(end 344.017092 -127.307848)
		(width 0.1143)
		(layer "In9.Cu")
		(net "CLK_100M_DB1200_DN")
	)
	(segment
		(start 350.431354 -128.8923)
		(end 353.620832 -128.8923)
		(width 0.1143)
		(layer "In9.Cu")
		(net "CLK_100M_DB1200_DN")
	)
	(segment
		(start 345.242134 -128.53289)
		(end 350.071944 -128.53289)
		(width 0.1143)
		(layer "In9.Cu")
		(net "CLK_100M_DB1200_DN")
	)
	(segment
		(start 375.9581 -115.310158)
		(end 375.9581 -112.507268)
		(width 0.1143)
		(layer "In9.Cu")
		(net "CLK_100M_DB1200_DN")
	)
	(segment
		(start 374.6881 -116.580158)
		(end 375.9581 -115.310158)
		(width 0.1143)
		(layer "In9.Cu")
		(net "CLK_100M_DB1200_DN")
	)
	(segment
		(start 366.511332 -127.192786)
		(end 369.560602 -124.143262)
		(width 0.1143)
		(layer "In9.Cu")
		(net "CLK_100M_DB1200_DN")
	)
	(segment
		(start 344.017092 -127.307848)
		(end 345.242134 -128.53289)
		(width 0.1143)
		(layer "In9.Cu")
		(net "CLK_100M_DB1200_DN")
	)
	(segment
		(start 192.361566 -132.244084)
		(end 192.6971 -131.90855)
		(width 0.1143)
		(layer "In9.Cu")
		(net "CLK_100M_DB1200_DN")
	)
	(segment
		(start 324.286372 -129.032)
		(end 328.826622 -127.79756)
		(width 0.1143)
		(layer "In9.Cu")
		(net "CLK_100M_DB1200_DN")
	)
	(segment
		(start 328.826622 -127.79756)
		(end 332.008226 -125.944376)
		(width 0.1143)
		(layer "In9.Cu")
		(net "CLK_100M_DB1200_DN")
	)
	(segment
		(start 376.258328 -111.939578)
		(end 376.968258 -111.939578)
		(width 0.0889)
		(layer "In9.Cu")
		(net "CLK_100M_DB1200_DN")
	)
	(segment
		(start 332.008226 -125.944376)
		(end 333.51343 -125.944376)
		(width 0.1143)
		(layer "In9.Cu")
		(net "CLK_100M_DB1200_DN")
	)
	(segment
		(start 375.9581 -112.48517)
		(end 375.9073 -112.43437)
		(width 0.0889)
		(layer "In9.Cu")
		(net "CLK_100M_DB1200_DN")
	)
	(segment
		(start 191.2366 -132.364734)
		(end 191.35725 -132.244084)
		(width 0.1143)
		(layer "In9.Cu")
		(net "CLK_100M_DB1200_DN")
	)
	(segment
		(start 338.106766 -124.865638)
		(end 342.471756 -124.865638)
		(width 0.1143)
		(layer "In9.Cu")
		(net "CLK_100M_DB1200_DN")
	)
	(segment
		(start 191.35725 -132.244084)
		(end 192.361566 -132.244084)
		(width 0.1143)
		(layer "In9.Cu")
		(net "CLK_100M_DB1200_DN")
	)
	(segment
		(start 358.63784 -127.551942)
		(end 365.575088 -127.551942)
		(width 0.1143)
		(layer "In9.Cu")
		(net "CLK_100M_DB1200_DN")
	)
	(segment
		(start 246.86768 -128.230376)
		(end 257.00609 -126.952502)
		(width 0.1143)
		(layer "In9.Cu")
		(net "CLK_100M_DB1200_DN")
	)
	(segment
		(start 375.9073 -112.290606)
		(end 376.258328 -111.939578)
		(width 0.0889)
		(layer "In9.Cu")
		(net "CLK_100M_DB1200_DN")
	)
	(segment
		(start 378.9172 -109.05998)
		(end 378.9172 -108.855256)
		(width 0.0889)
		(layer "In9.Cu")
		(net "CLK_100M_DB1200_DN")
	)
	(segment
		(start 264.487406 -126.952502)
		(end 274.466304 -125.55982)
		(width 0.1143)
		(layer "In9.Cu")
		(net "CLK_100M_DB1200_DN")
	)
	(segment
		(start 369.560602 -124.143262)
		(end 369.560602 -122.945144)
		(width 0.1143)
		(layer "In9.Cu")
		(net "CLK_100M_DB1200_DN")
	)
	(segment
		(start 378.9172 -108.855256)
		(end 379.0061 -108.766356)
		(width 0.0889)
		(layer "In9.Cu")
		(net "CLK_100M_DB1200_DN")
	)
	(segment
		(start 376.968258 -111.939578)
		(end 377.387104 -111.520732)
		(width 0.0889)
		(layer "In9.Cu")
		(net "CLK_100M_DB1200_DN")
	)
	(segment
		(start 274.466304 -125.55982)
		(end 275.56333 -125.55982)
		(width 0.1143)
		(layer "In9.Cu")
		(net "CLK_100M_DB1200_DN")
	)
	(segment
		(start 192.6971 -131.90855)
		(end 192.6971 -128.347978)
		(width 0.1143)
		(layer "In9.Cu")
		(net "CLK_100M_DB1200_DN")
	)
	(segment
		(start 374.6881 -118.3005)
		(end 374.6881 -116.580158)
		(width 0.1143)
		(layer "In9.Cu")
		(net "CLK_100M_DB1200_DN")
	)
	(segment
		(start 379.0061 -108.766356)
		(end 379.31725 -108.766356)
		(width 0.0889)
		(layer "In9.Cu")
		(net "CLK_100M_DB1200_DN")
	)
	(segment
		(start 378.505466 -109.471714)
		(end 378.9172 -109.05998)
		(width 0.0889)
		(layer "In9.Cu")
		(net "CLK_100M_DB1200_DN")
	)
	(segment
		(start 192.6971 -128.347978)
		(end 193.203068 -127.84201)
		(width 0.1143)
		(layer "In9.Cu")
		(net "CLK_100M_DB1200_DN")
	)
	(segment
		(start 221.897702 -129.019046)
		(end 246.07901 -129.019046)
		(width 0.1143)
		(layer "In9.Cu")
		(net "CLK_100M_DB1200_DN")
	)
	(segment
		(start 370.7638 -122.2248)
		(end 374.6881 -118.3005)
		(width 0.1143)
		(layer "In9.Cu")
		(net "CLK_100M_DB1200_DN")
	)
	(segment
		(start 194.302126 -127.639572)
		(end 211.995004 -127.639572)
		(width 0.1143)
		(layer "In9.Cu")
		(net "CLK_100M_DB1200_DN")
	)
	(segment
		(start 342.471756 -124.865638)
		(end 344.017092 -126.410974)
		(width 0.1143)
		(layer "In9.Cu")
		(net "CLK_100M_DB1200_DN")
	)
	(segment
		(start 323.282564 -129.1463)
		(end 323.396864 -129.032)
		(width 0.1143)
		(layer "In9.Cu")
		(net "CLK_100M_DB1200_DN")
	)
	(segment
		(start 365.575088 -127.551942)
		(end 366.511332 -127.192786)
		(width 0.1143)
		(layer "In9.Cu")
		(net "CLK_100M_DB1200_DN")
	)
	(segment
		(start 246.07901 -129.019046)
		(end 246.86768 -128.230376)
		(width 0.1143)
		(layer "In9.Cu")
		(net "CLK_100M_DB1200_DN")
	)
	(segment
		(start 333.51343 -125.944376)
		(end 338.106766 -124.865638)
		(width 0.1143)
		(layer "In9.Cu")
		(net "CLK_100M_DB1200_DN")
	)
	(segment
		(start 211.995004 -127.639572)
		(end 221.897702 -129.019046)
		(width 0.1143)
		(layer "In9.Cu")
		(net "CLK_100M_DB1200_DN")
	)
	(segment
		(start 375.9073 -112.43437)
		(end 375.9073 -112.290606)
		(width 0.0889)
		(layer "In9.Cu")
		(net "CLK_100M_DB1200_DN")
	)
	(segment
		(start 323.396864 -129.032)
		(end 324.286372 -129.032)
		(width 0.1143)
		(layer "In9.Cu")
		(net "CLK_100M_DB1200_DN")
	)
	(segment
		(start 287.285176 -129.1463)
		(end 323.282564 -129.1463)
		(width 0.1143)
		(layer "In9.Cu")
		(net "CLK_100M_DB1200_DN")
	)
	(segment
		(start 369.560602 -122.945144)
		(end 370.280946 -122.2248)
		(width 0.1143)
		(layer "In9.Cu")
		(net "CLK_100M_DB1200_DN")
	)
	(segment
		(start 370.280946 -122.2248)
		(end 370.7638 -122.2248)
		(width 0.1143)
		(layer "In9.Cu")
		(net "CLK_100M_DB1200_DN")
	)
	(segment
		(start 118.575328 -85.622384)
		(end 119.070882 -86.117938)
		(width 0.254)
		(layer "F.Cu")
		(net "A_CPU1_UPI2_RBIAS")
	)
	(segment
		(start 118.212362 -85.622384)
		(end 118.575328 -85.622384)
		(width 0.254)
		(layer "F.Cu")
		(net "A_CPU1_UPI2_RBIAS")
	)
	(segment
		(start 119.070882 -86.117938)
		(end 119.642382 -86.117938)
		(width 0.254)
		(layer "F.Cu")
		(net "A_CPU1_UPI2_RBIAS")
	)
	(via
		(at 119.642382 -86.117938)
		(size 0.508)
		(drill 0.254)
		(layers "F.Cu" "B.Cu")
		(net "A_CPU1_UPI2_RBIAS")
	)
	(segment
		(start 121.000012 -82.468212)
		(end 121.000012 -82.855308)
		(width 0.1778)
		(layer "B.Cu")
		(net "A_CPU1_UPI2_RBIAS")
	)
	(segment
		(start 119.156226 -76.251308)
		(end 119.720106 -76.251308)
		(width 0.2032)
		(layer "B.Cu")
		(net "A_CPU1_UPI2_RBIAS")
	)
	(segment
		(start 120.72112 -83.1342)
		(end 120.283986 -83.1342)
		(width 0.1778)
		(layer "B.Cu")
		(net "A_CPU1_UPI2_RBIAS")
	)
	(segment
		(start 118.191534 -77.216)
		(end 119.156226 -76.251308)
		(width 0.2032)
		(layer "B.Cu")
		(net "A_CPU1_UPI2_RBIAS")
	)
	(segment
		(start 120.916192 -77.447394)
		(end 120.916192 -82.384392)
		(width 0.1778)
		(layer "B.Cu")
		(net "A_CPU1_UPI2_RBIAS")
	)
	(segment
		(start 120.916192 -82.384392)
		(end 121.000012 -82.468212)
		(width 0.1778)
		(layer "B.Cu")
		(net "A_CPU1_UPI2_RBIAS")
	)
	(segment
		(start 121.000012 -82.855308)
		(end 120.72112 -83.1342)
		(width 0.1778)
		(layer "B.Cu")
		(net "A_CPU1_UPI2_RBIAS")
	)
	(segment
		(start 120.283986 -83.1342)
		(end 119.642382 -83.775804)
		(width 0.1778)
		(layer "B.Cu")
		(net "A_CPU1_UPI2_RBIAS")
	)
	(segment
		(start 117.221 -77.216)
		(end 118.191534 -77.216)
		(width 0.2032)
		(layer "B.Cu")
		(net "A_CPU1_UPI2_RBIAS")
	)
	(segment
		(start 119.642382 -83.775804)
		(end 119.642382 -86.117938)
		(width 0.1778)
		(layer "B.Cu")
		(net "A_CPU1_UPI2_RBIAS")
	)
	(segment
		(start 119.720106 -76.251308)
		(end 120.916192 -77.447394)
		(width 0.2032)
		(layer "B.Cu")
		(net "A_CPU1_UPI2_RBIAS")
	)
	(segment
		(start 117.95125 -68.521072)
		(end 118.212362 -68.782184)
		(width 0.254)
		(layer "F.Cu")
		(net "A_CPU1_UPI01_RBIAS")
	)
	(segment
		(start 117.029992 -71.460614)
		(end 117.2972 -71.193406)
		(width 0.254)
		(layer "F.Cu")
		(net "A_CPU1_UPI01_RBIAS")
	)
	(segment
		(start 118.212362 -67.791584)
		(end 117.95125 -68.052696)
		(width 0.254)
		(layer "F.Cu")
		(net "A_CPU1_UPI01_RBIAS")
	)
	(segment
		(start 117.2972 -71.193406)
		(end 117.2972 -69.697346)
		(width 0.254)
		(layer "F.Cu")
		(net "A_CPU1_UPI01_RBIAS")
	)
	(segment
		(start 117.95125 -68.052696)
		(end 117.95125 -68.521072)
		(width 0.254)
		(layer "F.Cu")
		(net "A_CPU1_UPI01_RBIAS")
	)
	(segment
		(start 117.2972 -69.697346)
		(end 118.212362 -68.782184)
		(width 0.254)
		(layer "F.Cu")
		(net "A_CPU1_UPI01_RBIAS")
	)
	(segment
		(start 117.353842 -87.108538)
		(end 117.925342 -87.108538)
		(width 0.254)
		(layer "F.Cu")
		(net "A_CPU1_PE012_RBIAS")
	)
	(segment
		(start 117.353842 -86.117938)
		(end 117.353842 -87.108538)
		(width 0.254)
		(layer "F.Cu")
		(net "A_CPU1_PE012_RBIAS")
	)
	(via
		(at 117.925342 -87.108538)
		(size 0.508)
		(drill 0.254)
		(layers "F.Cu" "B.Cu")
		(net "A_CPU1_PE012_RBIAS")
	)
	(segment
		(start 118.241572 -78.151482)
		(end 117.394482 -78.151482)
		(width 0.2032)
		(layer "B.Cu")
		(net "A_CPU1_PE012_RBIAS")
	)
	(segment
		(start 120.3706 -77.673454)
		(end 119.939054 -77.241908)
		(width 0.2032)
		(layer "B.Cu")
		(net "A_CPU1_PE012_RBIAS")
	)
	(segment
		(start 119.939054 -77.241908)
		(end 119.151146 -77.241908)
		(width 0.2032)
		(layer "B.Cu")
		(net "A_CPU1_PE012_RBIAS")
	)
	(segment
		(start 118.100094 -84.363306)
		(end 120.3706 -82.0928)
		(width 0.2032)
		(layer "B.Cu")
		(net "A_CPU1_PE012_RBIAS")
	)
	(segment
		(start 119.151146 -77.241908)
		(end 118.241572 -78.151482)
		(width 0.2032)
		(layer "B.Cu")
		(net "A_CPU1_PE012_RBIAS")
	)
	(segment
		(start 120.3706 -82.0928)
		(end 120.3706 -77.673454)
		(width 0.2032)
		(layer "B.Cu")
		(net "A_CPU1_PE012_RBIAS")
	)
	(segment
		(start 117.394482 -78.151482)
		(end 117.221 -77.978)
		(width 0.2032)
		(layer "B.Cu")
		(net "A_CPU1_PE012_RBIAS")
	)
	(segment
		(start 118.100094 -86.933786)
		(end 118.100094 -84.363306)
		(width 0.2032)
		(layer "B.Cu")
		(net "A_CPU1_PE012_RBIAS")
	)
	(segment
		(start 117.925342 -87.108538)
		(end 118.100094 -86.933786)
		(width 0.2032)
		(layer "B.Cu")
		(net "A_CPU1_PE012_RBIAS")
	)
	(segment
		(start 118.212362 -87.603584)
		(end 117.925342 -88.099138)
		(width 0.254)
		(layer "F.Cu")
		(net "A_CPU1_PE3_RBIAS")
	)
	(segment
		(start 117.925342 -88.099138)
		(end 117.353842 -88.099138)
		(width 0.254)
		(layer "F.Cu")
		(net "A_CPU1_PE3_RBIAS")
	)
	(via
		(at 117.3988 -84.3534)
		(size 0.6604)
		(drill 0.3302)
		(layers "F.Cu" "B.Cu")
		(net "A_CPU1_PE3_RBIAS")
	)
	(via
		(at 117.925342 -88.099138)
		(size 0.508)
		(drill 0.254)
		(layers "F.Cu" "B.Cu")
		(net "A_CPU1_PE3_RBIAS")
	)
	(segment
		(start 117.925342 -87.772748)
		(end 117.925342 -88.099138)
		(width 0.2032)
		(layer "B.Cu")
		(net "A_CPU1_PE3_RBIAS")
	)
	(segment
		(start 119.646192 -78.153768)
		(end 119.894604 -78.40218)
		(width 0.2032)
		(layer "B.Cu")
		(net "A_CPU1_PE3_RBIAS")
	)
	(segment
		(start 117.437408 -78.523592)
		(end 118.529608 -78.523592)
		(width 0.2032)
		(layer "B.Cu")
		(net "A_CPU1_PE3_RBIAS")
	)
	(segment
		(start 117.3988 -87.246206)
		(end 117.925342 -87.772748)
		(width 0.2032)
		(layer "B.Cu")
		(net "A_CPU1_PE3_RBIAS")
	)
	(segment
		(start 119.894604 -78.40218)
		(end 119.894604 -81.857596)
		(width 0.2032)
		(layer "B.Cu")
		(net "A_CPU1_PE3_RBIAS")
	)
	(segment
		(start 119.894604 -81.857596)
		(end 117.3988 -84.3534)
		(width 0.2032)
		(layer "B.Cu")
		(net "A_CPU1_PE3_RBIAS")
	)
	(segment
		(start 118.529608 -78.523592)
		(end 118.899432 -78.153768)
		(width 0.2032)
		(layer "B.Cu")
		(net "A_CPU1_PE3_RBIAS")
	)
	(segment
		(start 118.899432 -78.153768)
		(end 119.646192 -78.153768)
		(width 0.2032)
		(layer "B.Cu")
		(net "A_CPU1_PE3_RBIAS")
	)
	(segment
		(start 117.221 -78.74)
		(end 117.437408 -78.523592)
		(width 0.2032)
		(layer "B.Cu")
		(net "A_CPU1_PE3_RBIAS")
	)
	(segment
		(start 117.3988 -84.3534)
		(end 117.3988 -87.246206)
		(width 0.2032)
		(layer "B.Cu")
		(net "A_CPU1_PE3_RBIAS")
	)
	(segment
		(start 76.334366 -68.46824)
		(end 75.762866 -68.46824)
		(width 0.10795)
		(layer "F.Cu")
		(net "TP_CPU1_RSVD_183")
	)
	(via
		(at 75.762866 -68.46824)
		(size 0.508)
		(drill 0.254)
		(layers "F.Cu" "B.Cu")
		(net "TP_CPU1_RSVD_183")
	)
	(segment
		(start 84.060792 -68.963286)
		(end 83.489292 -68.963286)
		(width 0.10795)
		(layer "F.Cu")
		(net "TP_CPU1_RSVD_181")
	)
	(via
		(at 83.489292 -68.963286)
		(size 0.508)
		(drill 0.254)
		(layers "F.Cu" "B.Cu")
		(net "TP_CPU1_RSVD_181")
	)
	(segment
		(start 77.192886 -68.963286)
		(end 76.621386 -68.963286)
		(width 0.10795)
		(layer "F.Cu")
		(net "TP_CPU1_RSVD_180")
	)
	(via
		(at 76.621386 -68.963286)
		(size 0.508)
		(drill 0.254)
		(layers "F.Cu" "B.Cu")
		(net "TP_CPU1_RSVD_180")
	)
	(segment
		(start 129.372868 -71.258938)
		(end 129.944368 -71.258938)
		(width 0.10795)
		(layer "F.Cu")
		(net "TP_CPU1_RSVD_177")
	)
	(via
		(at 129.944368 -71.258938)
		(size 0.508)
		(drill 0.254)
		(layers "F.Cu" "B.Cu")
		(net "TP_CPU1_RSVD_177")
	)
	(segment
		(start 127.655828 -71.258938)
		(end 128.227328 -71.258938)
		(width 0.10795)
		(layer "F.Cu")
		(net "TP_CPU1_RSVD_176")
	)
	(via
		(at 128.227328 -71.258938)
		(size 0.508)
		(drill 0.254)
		(layers "F.Cu" "B.Cu")
		(net "TP_CPU1_RSVD_176")
	)
	(segment
		(start 306.605686 -53.834792)
		(end 305.533806 -53.923184)
		(width 0.10795)
		(layer "F.Cu")
		(net "TP_CPU0_RSVD_279")
	)
	(segment
		(start 311.60339 -53.442362)
		(end 311.21096 -53.834792)
		(width 0.10795)
		(layer "F.Cu")
		(net "TP_CPU0_RSVD_279")
	)
	(segment
		(start 311.21096 -53.834792)
		(end 306.605686 -53.834792)
		(width 0.10795)
		(layer "F.Cu")
		(net "TP_CPU0_RSVD_279")
	)
	(via
		(at 311.60339 -53.442362)
		(size 0.508)
		(drill 0.254)
		(layers "F.Cu" "B.Cu")
		(net "TP_CPU0_RSVD_279")
	)
	(segment
		(start 415.671 -23.114)
		(end 415.671 -23.533354)
		(width 0.10795)
		(layer "F.Cu")
		(net "SGPIO_BMC_LD_R_N")
	)
	(segment
		(start 415.284158 -24.60244)
		(end 415.284158 -25.893776)
		(width 0.10795)
		(layer "F.Cu")
		(net "SGPIO_BMC_LD_R_N")
	)
	(segment
		(start 415.544 -26.88082)
		(end 415.090102 -27.334718)
		(width 0.10795)
		(layer "F.Cu")
		(net "SGPIO_BMC_LD_R_N")
	)
	(segment
		(start 415.284158 -23.920196)
		(end 415.284158 -24.60244)
		(width 0.10795)
		(layer "F.Cu")
		(net "SGPIO_BMC_LD_R_N")
	)
	(segment
		(start 415.544 -26.153618)
		(end 415.544 -26.88082)
		(width 0.10795)
		(layer "F.Cu")
		(net "SGPIO_BMC_LD_R_N")
	)
	(segment
		(start 415.671 -23.533354)
		(end 415.284158 -23.920196)
		(width 0.10795)
		(layer "F.Cu")
		(net "SGPIO_BMC_LD_R_N")
	)
	(segment
		(start 415.284158 -25.893776)
		(end 415.544 -26.153618)
		(width 0.10795)
		(layer "F.Cu")
		(net "SGPIO_BMC_LD_R_N")
	)
	(via
		(at 415.284158 -24.60244)
		(size 0.508)
		(drill 0.254)
		(layers "F.Cu" "B.Cu")
		(net "SGPIO_BMC_LD_R_N")
	)
	(segment
		(start 416.690048 -28.134564)
		(end 417.029646 -27.794966)
		(width 0.089408)
		(layer "F.Cu")
		(net "SGPIO_BMC_DOUT_R")
	)
	(segment
		(start 417.029646 -25.228296)
		(end 417.443412 -24.81453)
		(width 0.089408)
		(layer "F.Cu")
		(net "SGPIO_BMC_DOUT_R")
	)
	(segment
		(start 417.443412 -23.234142)
		(end 417.481766 -23.195788)
		(width 0.10795)
		(layer "F.Cu")
		(net "SGPIO_BMC_DOUT_R")
	)
	(segment
		(start 417.029646 -27.794966)
		(end 417.029646 -25.228296)
		(width 0.089408)
		(layer "F.Cu")
		(net "SGPIO_BMC_DOUT_R")
	)
	(segment
		(start 417.443412 -24.81453)
		(end 417.443412 -23.234142)
		(width 0.089408)
		(layer "F.Cu")
		(net "SGPIO_BMC_DOUT_R")
	)
	(segment
		(start 417.481766 -23.195788)
		(end 417.481766 -22.049232)
		(width 0.10795)
		(layer "F.Cu")
		(net "SGPIO_BMC_DOUT_R")
	)
	(via
		(at 417.443412 -23.234142)
		(size 0.762)
		(drill 0.381)
		(layers "F.Cu" "B.Cu")
		(net "SGPIO_BMC_DOUT_R")
	)
	(segment
		(start 418.63645 -26.988516)
		(end 418.290248 -27.334718)
		(width 0.10795)
		(layer "F.Cu")
		(net "SGPIO_BMC_CLK_R")
	)
	(segment
		(start 420.751 -22.733)
		(end 420.751 -23.114)
		(width 0.10795)
		(layer "F.Cu")
		(net "SGPIO_BMC_CLK_R")
	)
	(segment
		(start 418.63645 -26.086308)
		(end 418.63645 -26.988516)
		(width 0.10795)
		(layer "F.Cu")
		(net "SGPIO_BMC_CLK_R")
	)
	(segment
		(start 420.219124 -23.645876)
		(end 420.219124 -23.902416)
		(width 0.10795)
		(layer "F.Cu")
		(net "SGPIO_BMC_CLK_R")
	)
	(segment
		(start 420.751 -23.114)
		(end 420.219124 -23.645876)
		(width 0.10795)
		(layer "F.Cu")
		(net "SGPIO_BMC_CLK_R")
	)
	(segment
		(start 420.219124 -23.902416)
		(end 420.219124 -24.503634)
		(width 0.10795)
		(layer "F.Cu")
		(net "SGPIO_BMC_CLK_R")
	)
	(segment
		(start 420.219124 -24.503634)
		(end 418.63645 -26.086308)
		(width 0.10795)
		(layer "F.Cu")
		(net "SGPIO_BMC_CLK_R")
	)
	(via
		(at 420.219124 -23.902416)
		(size 0.762)
		(drill 0.381)
		(layers "F.Cu" "B.Cu")
		(net "SGPIO_BMC_CLK_R")
	)
	(segment
		(start 294.3733 -71.258938)
		(end 294.9448 -71.258938)
		(width 0.10795)
		(layer "F.Cu")
		(net "TP_CPU0_RSVD_177")
	)
	(via
		(at 294.9448 -71.258938)
		(size 0.508)
		(drill 0.254)
		(layers "F.Cu" "B.Cu")
		(net "TP_CPU0_RSVD_177")
	)
	(segment
		(start 392.910568 -151.27097)
		(end 392.286744 -151.27097)
		(width 0.1778)
		(layer "F.Cu")
		(net "VR_PVNN_P1V05_PCH_VD12")
	)
	(segment
		(start 401.167346 -155.08224)
		(end 401.23872 -155.010866)
		(width 0.254)
		(layer "F.Cu")
		(net "VR_PVNN_P1V05_PCH_VD12")
	)
	(segment
		(start 393.3317 -151.692102)
		(end 392.910568 -151.27097)
		(width 0.1778)
		(layer "F.Cu")
		(net "VR_PVNN_P1V05_PCH_VD12")
	)
	(segment
		(start 400.55038 -155.08986)
		(end 400.558 -155.08224)
		(width 0.254)
		(layer "F.Cu")
		(net "VR_PVNN_P1V05_PCH_VD12")
	)
	(segment
		(start 389.881872 -151.706072)
		(end 390.351518 -151.236426)
		(width 0.254)
		(layer "F.Cu")
		(net "VR_PVNN_P1V05_PCH_VD12")
	)
	(segment
		(start 399.67408 -155.08986)
		(end 400.55038 -155.08986)
		(width 0.254)
		(layer "F.Cu")
		(net "VR_PVNN_P1V05_PCH_VD12")
	)
	(segment
		(start 391.795 -151.236426)
		(end 390.906 -151.236426)
		(width 0.254)
		(layer "F.Cu")
		(net "VR_PVNN_P1V05_PCH_VD12")
	)
	(segment
		(start 392.2522 -151.236426)
		(end 391.795 -151.236426)
		(width 0.1778)
		(layer "F.Cu")
		(net "VR_PVNN_P1V05_PCH_VD12")
	)
	(segment
		(start 390.351518 -151.236426)
		(end 390.906 -151.236426)
		(width 0.254)
		(layer "F.Cu")
		(net "VR_PVNN_P1V05_PCH_VD12")
	)
	(segment
		(start 400.558 -155.08224)
		(end 401.167346 -155.08224)
		(width 0.254)
		(layer "F.Cu")
		(net "VR_PVNN_P1V05_PCH_VD12")
	)
	(segment
		(start 392.286744 -151.27097)
		(end 392.2522 -151.236426)
		(width 0.1778)
		(layer "F.Cu")
		(net "VR_PVNN_P1V05_PCH_VD12")
	)
	(segment
		(start 393.3317 -151.996902)
		(end 393.3317 -151.692102)
		(width 0.1778)
		(layer "F.Cu")
		(net "VR_PVNN_P1V05_PCH_VD12")
	)
	(via
		(at 389.881872 -151.706072)
		(size 0.508)
		(drill 0.254)
		(layers "F.Cu" "B.Cu")
		(net "VR_PVNN_P1V05_PCH_VD12")
	)
	(via
		(at 401.23872 -155.010866)
		(size 0.508)
		(drill 0.254)
		(layers "F.Cu" "B.Cu")
		(net "VR_PVNN_P1V05_PCH_VD12")
	)
	(segment
		(start 393.573 -153.797)
		(end 393.573 -154.686)
		(width 0.254)
		(layer "In11.Cu")
		(net "VR_PVNN_P1V05_PCH_VD12")
	)
	(segment
		(start 401.236434 -154.985466)
		(end 401.23872 -154.985466)
		(width 0.254)
		(layer "In11.Cu")
		(net "VR_PVNN_P1V05_PCH_VD12")
	)
	(segment
		(start 396.113 -155.829)
		(end 400.3929 -155.829)
		(width 0.254)
		(layer "In11.Cu")
		(net "VR_PVNN_P1V05_PCH_VD12")
	)
	(segment
		(start 400.3929 -155.829)
		(end 401.236434 -154.985466)
		(width 0.254)
		(layer "In11.Cu")
		(net "VR_PVNN_P1V05_PCH_VD12")
	)
	(segment
		(start 394.184378 -153.185622)
		(end 393.573 -153.797)
		(width 0.254)
		(layer "In11.Cu")
		(net "VR_PVNN_P1V05_PCH_VD12")
	)
	(segment
		(start 393.573 -154.686)
		(end 394.081 -155.194)
		(width 0.254)
		(layer "In11.Cu")
		(net "VR_PVNN_P1V05_PCH_VD12")
	)
	(segment
		(start 394.081 -155.194)
		(end 395.478 -155.194)
		(width 0.254)
		(layer "In11.Cu")
		(net "VR_PVNN_P1V05_PCH_VD12")
	)
	(segment
		(start 393.123928 -151.315928)
		(end 394.184378 -152.376378)
		(width 0.254)
		(layer "In11.Cu")
		(net "VR_PVNN_P1V05_PCH_VD12")
	)
	(segment
		(start 401.23872 -154.985466)
		(end 401.23872 -155.010866)
		(width 0.254)
		(layer "In11.Cu")
		(net "VR_PVNN_P1V05_PCH_VD12")
	)
	(segment
		(start 390.359392 -151.315928)
		(end 393.123928 -151.315928)
		(width 0.254)
		(layer "In11.Cu")
		(net "VR_PVNN_P1V05_PCH_VD12")
	)
	(segment
		(start 394.184378 -152.376378)
		(end 394.184378 -153.185622)
		(width 0.254)
		(layer "In11.Cu")
		(net "VR_PVNN_P1V05_PCH_VD12")
	)
	(segment
		(start 389.881872 -151.706072)
		(end 389.969248 -151.706072)
		(width 0.254)
		(layer "In11.Cu")
		(net "VR_PVNN_P1V05_PCH_VD12")
	)
	(segment
		(start 395.478 -155.194)
		(end 396.113 -155.829)
		(width 0.254)
		(layer "In11.Cu")
		(net "VR_PVNN_P1V05_PCH_VD12")
	)
	(segment
		(start 389.969248 -151.706072)
		(end 390.359392 -151.315928)
		(width 0.254)
		(layer "In11.Cu")
		(net "VR_PVNN_P1V05_PCH_VD12")
	)
	(via
		(at 23.876 -78.8416)
		(size 0.508)
		(drill 0.254)
		(layers "F.Cu" "B.Cu")
		(net "A_HSC_TIMER_R")
	)
	(segment
		(start 25.009602 -79.4766)
		(end 24.2062 -79.4766)
		(width 0.254)
		(layer "B.Cu")
		(net "A_HSC_TIMER_R")
	)
	(segment
		(start 23.876 -78.8416)
		(end 23.876 -77.978)
		(width 0.254)
		(layer "B.Cu")
		(net "A_HSC_TIMER_R")
	)
	(segment
		(start 23.876 -77.978)
		(end 24.765 -77.978)
		(width 0.254)
		(layer "B.Cu")
		(net "A_HSC_TIMER_R")
	)
	(segment
		(start 23.876 -79.1464)
		(end 23.876 -78.8416)
		(width 0.254)
		(layer "B.Cu")
		(net "A_HSC_TIMER_R")
	)
	(segment
		(start 24.2062 -79.4766)
		(end 23.876 -79.1464)
		(width 0.254)
		(layer "B.Cu")
		(net "A_HSC_TIMER_R")
	)
	(segment
		(start 387.73735 -96.9772)
		(end 388.23265 -96.747076)
		(width 0.10795)
		(layer "F.Cu")
		(net "FM_HSC_TIMER_EXP_N")
	)
	(segment
		(start 419.890194 -25.96896)
		(end 419.890194 -26.534618)
		(width 0.10795)
		(layer "F.Cu")
		(net "FM_HSC_TIMER_EXP_N")
	)
	(segment
		(start 414.155636 -88.823292)
		(end 414.155636 -90.1446)
		(width 0.10795)
		(layer "F.Cu")
		(net "FM_HSC_TIMER_EXP_N")
	)
	(via
		(at 385.702556 -33.271714)
		(size 0.508)
		(drill 0.254)
		(layers "F.Cu" "B.Cu")
		(net "FM_HSC_TIMER_EXP_N")
	)
	(via
		(at 399.846038 -32.49041)
		(size 0.508)
		(drill 0.254)
		(layers "F.Cu" "B.Cu")
		(net "FM_HSC_TIMER_EXP_N")
	)
	(via
		(at 414.155636 -90.1446)
		(size 0.508)
		(drill 0.254)
		(layers "F.Cu" "B.Cu")
		(net "FM_HSC_TIMER_EXP_N")
	)
	(via
		(at 26.289 -78.359)
		(size 0.508)
		(drill 0.254)
		(layers "F.Cu" "B.Cu")
		(net "FM_HSC_TIMER_EXP_N")
	)
	(via
		(at 27.3558 -53.60416)
		(size 0.508)
		(drill 0.254)
		(layers "F.Cu" "B.Cu")
		(net "FM_HSC_TIMER_EXP_N")
	)
	(via
		(at 185.3184 -4.569714)
		(size 0.508)
		(drill 0.254)
		(layers "F.Cu" "B.Cu")
		(net "FM_HSC_TIMER_EXP_N")
	)
	(via
		(at 355.6762 -30.861)
		(size 0.508)
		(drill 0.254)
		(layers "F.Cu" "B.Cu")
		(net "FM_HSC_TIMER_EXP_N")
	)
	(via
		(at 388.23265 -96.747076)
		(size 0.508)
		(drill 0.254)
		(layers "F.Cu" "B.Cu")
		(net "FM_HSC_TIMER_EXP_N")
	)
	(via
		(at 419.890194 -25.96896)
		(size 0.4572)
		(drill 0.2032)
		(layers "F.Cu" "B.Cu")
		(net "FM_HSC_TIMER_EXP_N")
	)
	(via
		(at 364.383574 -29.742892)
		(size 0.6604)
		(drill 0.3302)
		(layers "F.Cu" "B.Cu")
		(net "FM_HSC_TIMER_EXP_N")
	)
	(segment
		(start 356.049834 -30.981904)
		(end 356.118668 -30.91307)
		(width 0.10795)
		(layer "B.Cu")
		(net "FM_HSC_TIMER_EXP_N")
	)
	(segment
		(start 373.527066 -27.141678)
		(end 373.564912 -27.141678)
		(width 0.10795)
		(layer "B.Cu")
		(net "FM_HSC_TIMER_EXP_N")
	)
	(segment
		(start 373.955056 -27.141678)
		(end 375.865644 -27.141678)
		(width 0.10795)
		(layer "B.Cu")
		(net "FM_HSC_TIMER_EXP_N")
	)
	(segment
		(start 377.92279 -31.61157)
		(end 379.433074 -33.121854)
		(width 0.10795)
		(layer "B.Cu")
		(net "FM_HSC_TIMER_EXP_N")
	)
	(segment
		(start 363.213142 -30.913324)
		(end 364.383574 -29.742892)
		(width 0.10795)
		(layer "B.Cu")
		(net "FM_HSC_TIMER_EXP_N")
	)
	(segment
		(start 377.92279 -29.198824)
		(end 377.92279 -31.61157)
		(width 0.10795)
		(layer "B.Cu")
		(net "FM_HSC_TIMER_EXP_N")
	)
	(segment
		(start 364.8837 -29.242766)
		(end 371.425978 -29.242766)
		(width 0.10795)
		(layer "B.Cu")
		(net "FM_HSC_TIMER_EXP_N")
	)
	(segment
		(start 364.383574 -29.742892)
		(end 364.8837 -29.242766)
		(width 0.10795)
		(layer "B.Cu")
		(net "FM_HSC_TIMER_EXP_N")
	)
	(segment
		(start 373.565166 -27.141424)
		(end 373.954802 -27.141424)
		(width 0.10795)
		(layer "B.Cu")
		(net "FM_HSC_TIMER_EXP_N")
	)
	(segment
		(start 371.425978 -29.242766)
		(end 373.527066 -27.141678)
		(width 0.10795)
		(layer "B.Cu")
		(net "FM_HSC_TIMER_EXP_N")
	)
	(segment
		(start 356.313486 -30.913324)
		(end 363.213142 -30.913324)
		(width 0.10795)
		(layer "B.Cu")
		(net "FM_HSC_TIMER_EXP_N")
	)
	(segment
		(start 355.6762 -30.861)
		(end 355.797104 -30.981904)
		(width 0.10795)
		(layer "B.Cu")
		(net "FM_HSC_TIMER_EXP_N")
	)
	(segment
		(start 26.0096 -78.6384)
		(end 26.289 -78.359)
		(width 0.10795)
		(layer "B.Cu")
		(net "FM_HSC_TIMER_EXP_N")
	)
	(segment
		(start 355.797104 -30.981904)
		(end 356.049834 -30.981904)
		(width 0.10795)
		(layer "B.Cu")
		(net "FM_HSC_TIMER_EXP_N")
	)
	(segment
		(start 375.865644 -27.141678)
		(end 377.92279 -29.198824)
		(width 0.10795)
		(layer "B.Cu")
		(net "FM_HSC_TIMER_EXP_N")
	)
	(segment
		(start 356.313232 -30.91307)
		(end 356.313486 -30.913324)
		(width 0.10795)
		(layer "B.Cu")
		(net "FM_HSC_TIMER_EXP_N")
	)
	(segment
		(start 373.564912 -27.141678)
		(end 373.565166 -27.141424)
		(width 0.10795)
		(layer "B.Cu")
		(net "FM_HSC_TIMER_EXP_N")
	)
	(segment
		(start 373.954802 -27.141424)
		(end 373.955056 -27.141678)
		(width 0.10795)
		(layer "B.Cu")
		(net "FM_HSC_TIMER_EXP_N")
	)
	(segment
		(start 379.433074 -33.121854)
		(end 381.514096 -33.121854)
		(width 0.10795)
		(layer "B.Cu")
		(net "FM_HSC_TIMER_EXP_N")
	)
	(segment
		(start 385.700524 -33.273746)
		(end 385.702556 -33.271714)
		(width 0.10795)
		(layer "B.Cu")
		(net "FM_HSC_TIMER_EXP_N")
	)
	(segment
		(start 381.665988 -33.273746)
		(end 385.700524 -33.273746)
		(width 0.10795)
		(layer "B.Cu")
		(net "FM_HSC_TIMER_EXP_N")
	)
	(segment
		(start 381.514096 -33.121854)
		(end 381.665988 -33.273746)
		(width 0.10795)
		(layer "B.Cu")
		(net "FM_HSC_TIMER_EXP_N")
	)
	(segment
		(start 26.6954 -78.359)
		(end 27.0764 -77.978)
		(width 0.10795)
		(layer "B.Cu")
		(net "FM_HSC_TIMER_EXP_N")
	)
	(segment
		(start 356.118668 -30.91307)
		(end 356.313232 -30.91307)
		(width 0.10795)
		(layer "B.Cu")
		(net "FM_HSC_TIMER_EXP_N")
	)
	(segment
		(start 26.289 -78.359)
		(end 26.6954 -78.359)
		(width 0.10795)
		(layer "B.Cu")
		(net "FM_HSC_TIMER_EXP_N")
	)
	(segment
		(start 26.0096 -79.502)
		(end 26.0096 -78.6384)
		(width 0.10795)
		(layer "B.Cu")
		(net "FM_HSC_TIMER_EXP_N")
	)
	(segment
		(start 389.562086 -32.848804)
		(end 394.140182 -32.848804)
		(width 0.089408)
		(layer "In4.Cu")
		(net "FM_HSC_TIMER_EXP_N")
	)
	(segment
		(start 394.140182 -32.848804)
		(end 394.680694 -33.389316)
		(width 0.089408)
		(layer "In4.Cu")
		(net "FM_HSC_TIMER_EXP_N")
	)
	(segment
		(start 386.725922 -32.716724)
		(end 389.430006 -32.716724)
		(width 0.089408)
		(layer "In4.Cu")
		(net "FM_HSC_TIMER_EXP_N")
	)
	(segment
		(start 399.778982 -32.49041)
		(end 399.846038 -32.49041)
		(width 0.089408)
		(layer "In4.Cu")
		(net "FM_HSC_TIMER_EXP_N")
	)
	(segment
		(start 412.905702 -90.1446)
		(end 414.155636 -90.1446)
		(width 0.089408)
		(layer "In4.Cu")
		(net "FM_HSC_TIMER_EXP_N")
	)
	(segment
		(start 394.680694 -33.389316)
		(end 396.51432 -33.389316)
		(width 0.089408)
		(layer "In4.Cu")
		(net "FM_HSC_TIMER_EXP_N")
	)
	(segment
		(start 398.959832 -88.309958)
		(end 399.397728 -88.747854)
		(width 0.089408)
		(layer "In4.Cu")
		(net "FM_HSC_TIMER_EXP_N")
	)
	(segment
		(start 399.757392 -32.46882)
		(end 399.778982 -32.49041)
		(width 0.089408)
		(layer "In4.Cu")
		(net "FM_HSC_TIMER_EXP_N")
	)
	(segment
		(start 410.861002 -90.965782)
		(end 412.08452 -90.965782)
		(width 0.089408)
		(layer "In4.Cu")
		(net "FM_HSC_TIMER_EXP_N")
	)
	(segment
		(start 392.320018 -87.757762)
		(end 392.320272 -87.758016)
		(width 0.089408)
		(layer "In4.Cu")
		(net "FM_HSC_TIMER_EXP_N")
	)
	(segment
		(start 389.430006 -32.716724)
		(end 389.562086 -32.848804)
		(width 0.089408)
		(layer "In4.Cu")
		(net "FM_HSC_TIMER_EXP_N")
	)
	(segment
		(start 396.51432 -33.389316)
		(end 397.434816 -32.46882)
		(width 0.089408)
		(layer "In4.Cu")
		(net "FM_HSC_TIMER_EXP_N")
	)
	(segment
		(start 399.397728 -88.747854)
		(end 402.370544 -88.747854)
		(width 0.089408)
		(layer "In4.Cu")
		(net "FM_HSC_TIMER_EXP_N")
	)
	(segment
		(start 388.23265 -96.747076)
		(end 388.139178 -96.653604)
		(width 0.089408)
		(layer "In4.Cu")
		(net "FM_HSC_TIMER_EXP_N")
	)
	(segment
		(start 392.320272 -87.758016)
		(end 394.760704 -87.758016)
		(width 0.089408)
		(layer "In4.Cu")
		(net "FM_HSC_TIMER_EXP_N")
	)
	(segment
		(start 394.760704 -87.758016)
		(end 395.312646 -88.309958)
		(width 0.089408)
		(layer "In4.Cu")
		(net "FM_HSC_TIMER_EXP_N")
	)
	(segment
		(start 385.702556 -33.271714)
		(end 386.170932 -33.271714)
		(width 0.089408)
		(layer "In4.Cu")
		(net "FM_HSC_TIMER_EXP_N")
	)
	(segment
		(start 402.765514 -88.352884)
		(end 404.241254 -88.352884)
		(width 0.089408)
		(layer "In4.Cu")
		(net "FM_HSC_TIMER_EXP_N")
	)
	(segment
		(start 391.845038 -87.757762)
		(end 392.320018 -87.757762)
		(width 0.089408)
		(layer "In4.Cu")
		(net "FM_HSC_TIMER_EXP_N")
	)
	(segment
		(start 395.312646 -88.309958)
		(end 398.959832 -88.309958)
		(width 0.089408)
		(layer "In4.Cu")
		(net "FM_HSC_TIMER_EXP_N")
	)
	(segment
		(start 402.370544 -88.747854)
		(end 402.765514 -88.352884)
		(width 0.089408)
		(layer "In4.Cu")
		(net "FM_HSC_TIMER_EXP_N")
	)
	(segment
		(start 397.434816 -32.46882)
		(end 399.757392 -32.46882)
		(width 0.089408)
		(layer "In4.Cu")
		(net "FM_HSC_TIMER_EXP_N")
	)
	(segment
		(start 388.139178 -96.653604)
		(end 388.139178 -89.896442)
		(width 0.089408)
		(layer "In4.Cu")
		(net "FM_HSC_TIMER_EXP_N")
	)
	(segment
		(start 390.277604 -87.758016)
		(end 391.844784 -87.758016)
		(width 0.089408)
		(layer "In4.Cu")
		(net "FM_HSC_TIMER_EXP_N")
	)
	(segment
		(start 391.844784 -87.758016)
		(end 391.845038 -87.757762)
		(width 0.089408)
		(layer "In4.Cu")
		(net "FM_HSC_TIMER_EXP_N")
	)
	(segment
		(start 404.241254 -88.352884)
		(end 405.727154 -89.838784)
		(width 0.089408)
		(layer "In4.Cu")
		(net "FM_HSC_TIMER_EXP_N")
	)
	(segment
		(start 405.727154 -89.838784)
		(end 409.734004 -89.838784)
		(width 0.089408)
		(layer "In4.Cu")
		(net "FM_HSC_TIMER_EXP_N")
	)
	(segment
		(start 409.734004 -89.838784)
		(end 410.861002 -90.965782)
		(width 0.089408)
		(layer "In4.Cu")
		(net "FM_HSC_TIMER_EXP_N")
	)
	(segment
		(start 388.139178 -89.896442)
		(end 390.277604 -87.758016)
		(width 0.089408)
		(layer "In4.Cu")
		(net "FM_HSC_TIMER_EXP_N")
	)
	(segment
		(start 412.08452 -90.965782)
		(end 412.905702 -90.1446)
		(width 0.089408)
		(layer "In4.Cu")
		(net "FM_HSC_TIMER_EXP_N")
	)
	(segment
		(start 386.170932 -33.271714)
		(end 386.725922 -32.716724)
		(width 0.089408)
		(layer "In4.Cu")
		(net "FM_HSC_TIMER_EXP_N")
	)
	(segment
		(start 410.591254 -31.303214)
		(end 413.323786 -31.303214)
		(width 0.089408)
		(layer "In9.Cu")
		(net "FM_HSC_TIMER_EXP_N")
	)
	(segment
		(start 26.9621 -74.157586)
		(end 26.9621 -77.6859)
		(width 0.089408)
		(layer "In9.Cu")
		(net "FM_HSC_TIMER_EXP_N")
	)
	(segment
		(start 391.91946 -84.342732)
		(end 391.814304 -84.447888)
		(width 0.089408)
		(layer "In9.Cu")
		(net "FM_HSC_TIMER_EXP_N")
	)
	(segment
		(start 28.2956 -59.348116)
		(end 28.0543 -59.589416)
		(width 0.089408)
		(layer "In9.Cu")
		(net "FM_HSC_TIMER_EXP_N")
	)
	(segment
		(start 332.204568 -9.931146)
		(end 337.053936 -9.931146)
		(width 0.089408)
		(layer "In9.Cu")
		(net "FM_HSC_TIMER_EXP_N")
	)
	(segment
		(start 413.323786 -31.303214)
		(end 414.267396 -30.359604)
		(width 0.089408)
		(layer "In9.Cu")
		(net "FM_HSC_TIMER_EXP_N")
	)
	(segment
		(start 397.87576 -61.679836)
		(end 397.517112 -62.038484)
		(width 0.089408)
		(layer "In9.Cu")
		(net "FM_HSC_TIMER_EXP_N")
	)
	(segment
		(start 399.395696 -37.280088)
		(end 399.395696 -40.793162)
		(width 0.089408)
		(layer "In9.Cu")
		(net "FM_HSC_TIMER_EXP_N")
	)
	(segment
		(start 325.900542 -6.176772)
		(end 327.749662 -6.176772)
		(width 0.089408)
		(layer "In9.Cu")
		(net "FM_HSC_TIMER_EXP_N")
	)
	(segment
		(start 414.9598 -29.718)
		(end 415.3281 -29.3497)
		(width 0.089408)
		(layer "In9.Cu")
		(net "FM_HSC_TIMER_EXP_N")
	)
	(segment
		(start 399.566892 -32.598868)
		(end 399.566892 -37.108892)
		(width 0.089408)
		(layer "In9.Cu")
		(net "FM_HSC_TIMER_EXP_N")
	)
	(segment
		(start 415.3281 -28.5369)
		(end 415.915602 -27.949398)
		(width 0.089408)
		(layer "In9.Cu")
		(net "FM_HSC_TIMER_EXP_N")
	)
	(segment
		(start 391.814304 -84.447888)
		(end 391.814304 -85.836506)
		(width 0.089408)
		(layer "In9.Cu")
		(net "FM_HSC_TIMER_EXP_N")
	)
	(segment
		(start 356.762558 -26.552144)
		(end 356.762558 -28.446476)
		(width 0.089408)
		(layer "In9.Cu")
		(net "FM_HSC_TIMER_EXP_N")
	)
	(segment
		(start 26.9621 -77.6859)
		(end 26.289 -78.359)
		(width 0.089408)
		(layer "In9.Cu")
		(net "FM_HSC_TIMER_EXP_N")
	)
	(segment
		(start 340.571836 -23.626318)
		(end 340.675214 -23.729696)
		(width 0.089408)
		(layer "In9.Cu")
		(net "FM_HSC_TIMER_EXP_N")
	)
	(segment
		(start 410.539692 -31.354776)
		(end 410.591254 -31.303214)
		(width 0.089408)
		(layer "In9.Cu")
		(net "FM_HSC_TIMER_EXP_N")
	)
	(segment
		(start 394.836904 -70.873874)
		(end 394.836904 -71.717662)
		(width 0.089408)
		(layer "In9.Cu")
		(net "FM_HSC_TIMER_EXP_N")
	)
	(segment
		(start 394.59789 -73.27392)
		(end 394.321538 -73.550272)
		(width 0.089408)
		(layer "In9.Cu")
		(net "FM_HSC_TIMER_EXP_N")
	)
	(segment
		(start 393.083288 -78.16596)
		(end 393.083288 -78.755494)
		(width 0.089408)
		(layer "In9.Cu")
		(net "FM_HSC_TIMER_EXP_N")
	)
	(segment
		(start 397.241268 -64.489584)
		(end 397.235934 -64.489584)
		(width 0.089408)
		(layer "In9.Cu")
		(net "FM_HSC_TIMER_EXP_N")
	)
	(segment
		(start 260.567424 -0.0254)
		(end 260.975856 -0.0254)
		(width 0.089408)
		(layer "In9.Cu")
		(net "FM_HSC_TIMER_EXP_N")
	)
	(segment
		(start 391.91946 -84.125308)
		(end 391.91946 -84.342732)
		(width 0.089408)
		(layer "In9.Cu")
		(net "FM_HSC_TIMER_EXP_N")
	)
	(segment
		(start 193.378328 -1.337056)
		(end 194.097656 -0.617728)
		(width 0.089408)
		(layer "In9.Cu")
		(net "FM_HSC_TIMER_EXP_N")
	)
	(segment
		(start 400.18716 -32.673544)
		(end 400.18716 -33.61436)
		(width 0.089408)
		(layer "In9.Cu")
		(net "FM_HSC_TIMER_EXP_N")
	)
	(segment
		(start 327.749662 -6.176772)
		(end 330.979272 -9.406382)
		(width 0.089408)
		(layer "In9.Cu")
		(net "FM_HSC_TIMER_EXP_N")
	)
	(segment
		(start 415.915602 -27.060398)
		(end 416.814 -26.162)
		(width 0.089408)
		(layer "In9.Cu")
		(net "FM_HSC_TIMER_EXP_N")
	)
	(segment
		(start 400.004026 -32.49041)
		(end 400.18716 -32.673544)
		(width 0.089408)
		(layer "In9.Cu")
		(net "FM_HSC_TIMER_EXP_N")
	)
	(segment
		(start 260.975856 -0.0254)
		(end 262.26643 -1.315974)
		(width 0.089408)
		(layer "In9.Cu")
		(net "FM_HSC_TIMER_EXP_N")
	)
	(segment
		(start 419.697154 -26.162)
		(end 419.890194 -25.96896)
		(width 0.089408)
		(layer "In9.Cu")
		(net "FM_HSC_TIMER_EXP_N")
	)
	(segment
		(start 397.87576 -61.60897)
		(end 397.87576 -61.679836)
		(width 0.089408)
		(layer "In9.Cu")
		(net "FM_HSC_TIMER_EXP_N")
	)
	(segment
		(start 397.876014 -60.816744)
		(end 397.876014 -61.608716)
		(width 0.089408)
		(layer "In9.Cu")
		(net "FM_HSC_TIMER_EXP_N")
	)
	(segment
		(start 262.26643 -1.315974)
		(end 323.042026 -1.315974)
		(width 0.089408)
		(layer "In9.Cu")
		(net "FM_HSC_TIMER_EXP_N")
	)
	(segment
		(start 331.67955 -9.406128)
		(end 332.204568 -9.931146)
		(width 0.089408)
		(layer "In9.Cu")
		(net "FM_HSC_TIMER_EXP_N")
	)
	(segment
		(start 393.265914 -77.983334)
		(end 393.083288 -78.16596)
		(width 0.089408)
		(layer "In9.Cu")
		(net "FM_HSC_TIMER_EXP_N")
	)
	(segment
		(start 397.517112 -64.21374)
		(end 397.241268 -64.489584)
		(width 0.089408)
		(layer "In9.Cu")
		(net "FM_HSC_TIMER_EXP_N")
	)
	(segment
		(start 388.138416 -96.652842)
		(end 388.23265 -96.747076)
		(width 0.089408)
		(layer "In9.Cu")
		(net "FM_HSC_TIMER_EXP_N")
	)
	(segment
		(start 323.042026 -1.315974)
		(end 323.989192 -2.26314)
		(width 0.089408)
		(layer "In9.Cu")
		(net "FM_HSC_TIMER_EXP_N")
	)
	(segment
		(start 397.233902 -64.487552)
		(end 397.075914 -64.487552)
		(width 0.089408)
		(layer "In9.Cu")
		(net "FM_HSC_TIMER_EXP_N")
	)
	(segment
		(start 187.779914 -1.528064)
		(end 187.781438 -1.528064)
		(width 0.089408)
		(layer "In9.Cu")
		(net "FM_HSC_TIMER_EXP_N")
	)
	(segment
		(start 399.395696 -40.793162)
		(end 400.08683 -41.484296)
		(width 0.089408)
		(layer "In9.Cu")
		(net "FM_HSC_TIMER_EXP_N")
	)
	(segment
		(start 397.235934 -64.489584)
		(end 397.233902 -64.487552)
		(width 0.089408)
		(layer "In9.Cu")
		(net "FM_HSC_TIMER_EXP_N")
	)
	(segment
		(start 27.89174 -55.444644)
		(end 28.2956 -55.848504)
		(width 0.089408)
		(layer "In9.Cu")
		(net "FM_HSC_TIMER_EXP_N")
	)
	(segment
		(start 28.0543 -59.589416)
		(end 28.0543 -61.812424)
		(width 0.089408)
		(layer "In9.Cu")
		(net "FM_HSC_TIMER_EXP_N")
	)
	(segment
		(start 337.053936 -9.931146)
		(end 338.247228 -11.124438)
		(width 0.089408)
		(layer "In9.Cu")
		(net "FM_HSC_TIMER_EXP_N")
	)
	(segment
		(start 400.08683 -41.484296)
		(end 400.08683 -43.40225)
		(width 0.089408)
		(layer "In9.Cu")
		(net "FM_HSC_TIMER_EXP_N")
	)
	(segment
		(start 415.915602 -27.949398)
		(end 415.915602 -27.060398)
		(width 0.089408)
		(layer "In9.Cu")
		(net "FM_HSC_TIMER_EXP_N")
	)
	(segment
		(start 399.846038 -32.49041)
		(end 399.67535 -32.49041)
		(width 0.089408)
		(layer "In9.Cu")
		(net "FM_HSC_TIMER_EXP_N")
	)
	(segment
		(start 403.887686 -31.354776)
		(end 410.539692 -31.354776)
		(width 0.089408)
		(layer "In9.Cu")
		(net "FM_HSC_TIMER_EXP_N")
	)
	(segment
		(start 414.267396 -30.359604)
		(end 414.267396 -29.9466)
		(width 0.089408)
		(layer "In9.Cu")
		(net "FM_HSC_TIMER_EXP_N")
	)
	(segment
		(start 339.35543 -23.626318)
		(end 340.571836 -23.626318)
		(width 0.089408)
		(layer "In9.Cu")
		(net "FM_HSC_TIMER_EXP_N")
	)
	(segment
		(start 391.814304 -85.836506)
		(end 389.22706 -88.42375)
		(width 0.089408)
		(layer "In9.Cu")
		(net "FM_HSC_TIMER_EXP_N")
	)
	(segment
		(start 397.07566 -64.487298)
		(end 396.917672 -64.487298)
		(width 0.089408)
		(layer "In9.Cu")
		(net "FM_HSC_TIMER_EXP_N")
	)
	(segment
		(start 392.761724 -83.283044)
		(end 391.91946 -84.125308)
		(width 0.089408)
		(layer "In9.Cu")
		(net "FM_HSC_TIMER_EXP_N")
	)
	(segment
		(start 414.267396 -29.9466)
		(end 414.495996 -29.718)
		(width 0.089408)
		(layer "In9.Cu")
		(net "FM_HSC_TIMER_EXP_N")
	)
	(segment
		(start 397.87576 -58.850276)
		(end 397.87576 -60.81649)
		(width 0.089408)
		(layer "In9.Cu")
		(net "FM_HSC_TIMER_EXP_N")
	)
	(segment
		(start 28.62707 -66.610484)
		(end 27.357324 -67.88023)
		(width 0.089408)
		(layer "In9.Cu")
		(net "FM_HSC_TIMER_EXP_N")
	)
	(segment
		(start 185.3184 -4.569714)
		(end 185.3184 -3.989578)
		(width 0.089408)
		(layer "In9.Cu")
		(net "FM_HSC_TIMER_EXP_N")
	)
	(segment
		(start 401.381214 -33.861248)
		(end 403.887686 -31.354776)
		(width 0.089408)
		(layer "In9.Cu")
		(net "FM_HSC_TIMER_EXP_N")
	)
	(segment
		(start 392.761724 -79.077058)
		(end 392.761724 -83.283044)
		(width 0.089408)
		(layer "In9.Cu")
		(net "FM_HSC_TIMER_EXP_N")
	)
	(segment
		(start 323.989192 -4.265422)
		(end 325.900542 -6.176772)
		(width 0.089408)
		(layer "In9.Cu")
		(net "FM_HSC_TIMER_EXP_N")
	)
	(segment
		(start 397.517112 -62.038484)
		(end 397.517112 -64.21374)
		(width 0.089408)
		(layer "In9.Cu")
		(net "FM_HSC_TIMER_EXP_N")
	)
	(segment
		(start 400.08683 -43.40225)
		(end 398.490694 -44.998386)
		(width 0.089408)
		(layer "In9.Cu")
		(net "FM_HSC_TIMER_EXP_N")
	)
	(segment
		(start 27.3939 -53.60416)
		(end 27.89174 -54.102)
		(width 0.089408)
		(layer "In9.Cu")
		(net "FM_HSC_TIMER_EXP_N")
	)
	(segment
		(start 388.138416 -90.877136)
		(end 388.138416 -96.652842)
		(width 0.089408)
		(layer "In9.Cu")
		(net "FM_HSC_TIMER_EXP_N")
	)
	(segment
		(start 397.876014 -61.608716)
		(end 397.87576 -61.60897)
		(width 0.089408)
		(layer "In9.Cu")
		(net "FM_HSC_TIMER_EXP_N")
	)
	(segment
		(start 399.846038 -32.49041)
		(end 400.004026 -32.49041)
		(width 0.089408)
		(layer "In9.Cu")
		(net "FM_HSC_TIMER_EXP_N")
	)
	(segment
		(start 416.814 -26.162)
		(end 419.697154 -26.162)
		(width 0.089408)
		(layer "In9.Cu")
		(net "FM_HSC_TIMER_EXP_N")
	)
	(segment
		(start 187.781438 -1.528064)
		(end 187.972446 -1.337056)
		(width 0.089408)
		(layer "In9.Cu")
		(net "FM_HSC_TIMER_EXP_N")
	)
	(segment
		(start 394.59789 -71.956676)
		(end 394.59789 -73.27392)
		(width 0.089408)
		(layer "In9.Cu")
		(net "FM_HSC_TIMER_EXP_N")
	)
	(segment
		(start 187.972446 -1.337056)
		(end 193.378328 -1.337056)
		(width 0.089408)
		(layer "In9.Cu")
		(net "FM_HSC_TIMER_EXP_N")
	)
	(segment
		(start 323.989192 -2.26314)
		(end 323.989192 -4.265422)
		(width 0.089408)
		(layer "In9.Cu")
		(net "FM_HSC_TIMER_EXP_N")
	)
	(segment
		(start 398.095216 -44.998386)
		(end 397.296132 -45.79747)
		(width 0.089408)
		(layer "In9.Cu")
		(net "FM_HSC_TIMER_EXP_N")
	)
	(segment
		(start 27.357324 -67.88023)
		(end 27.357324 -73.762362)
		(width 0.089408)
		(layer "In9.Cu")
		(net "FM_HSC_TIMER_EXP_N")
	)
	(segment
		(start 354.519992 -24.309578)
		(end 356.762558 -26.552144)
		(width 0.089408)
		(layer "In9.Cu")
		(net "FM_HSC_TIMER_EXP_N")
	)
	(segment
		(start 348.327472 -23.729696)
		(end 348.907354 -24.309578)
		(width 0.089408)
		(layer "In9.Cu")
		(net "FM_HSC_TIMER_EXP_N")
	)
	(segment
		(start 348.907354 -24.309578)
		(end 354.519992 -24.309578)
		(width 0.089408)
		(layer "In9.Cu")
		(net "FM_HSC_TIMER_EXP_N")
	)
	(segment
		(start 394.321538 -73.550272)
		(end 394.321538 -75.661266)
		(width 0.089408)
		(layer "In9.Cu")
		(net "FM_HSC_TIMER_EXP_N")
	)
	(segment
		(start 338.856066 -20.99183)
		(end 338.856066 -23.126954)
		(width 0.089408)
		(layer "In9.Cu")
		(net "FM_HSC_TIMER_EXP_N")
	)
	(segment
		(start 399.67535 -32.49041)
		(end 399.566892 -32.598868)
		(width 0.089408)
		(layer "In9.Cu")
		(net "FM_HSC_TIMER_EXP_N")
	)
	(segment
		(start 356.762558 -28.446476)
		(end 355.6762 -29.532834)
		(width 0.089408)
		(layer "In9.Cu")
		(net "FM_HSC_TIMER_EXP_N")
	)
	(segment
		(start 397.56207 -48.59401)
		(end 397.56207 -58.536586)
		(width 0.089408)
		(layer "In9.Cu")
		(net "FM_HSC_TIMER_EXP_N")
	)
	(segment
		(start 399.566892 -37.108892)
		(end 399.395696 -37.280088)
		(width 0.089408)
		(layer "In9.Cu")
		(net "FM_HSC_TIMER_EXP_N")
	)
	(segment
		(start 396.91564 -64.48933)
		(end 396.878302 -64.48933)
		(width 0.089408)
		(layer "In9.Cu")
		(net "FM_HSC_TIMER_EXP_N")
	)
	(segment
		(start 185.3184 -3.989578)
		(end 187.779914 -1.528064)
		(width 0.089408)
		(layer "In9.Cu")
		(net "FM_HSC_TIMER_EXP_N")
	)
	(segment
		(start 415.3281 -29.3497)
		(end 415.3281 -28.5369)
		(width 0.089408)
		(layer "In9.Cu")
		(net "FM_HSC_TIMER_EXP_N")
	)
	(segment
		(start 393.265914 -76.71689)
		(end 393.265914 -77.983334)
		(width 0.089408)
		(layer "In9.Cu")
		(net "FM_HSC_TIMER_EXP_N")
	)
	(segment
		(start 28.2956 -55.848504)
		(end 28.2956 -59.348116)
		(width 0.089408)
		(layer "In9.Cu")
		(net "FM_HSC_TIMER_EXP_N")
	)
	(segment
		(start 397.56207 -58.536586)
		(end 397.87576 -58.850276)
		(width 0.089408)
		(layer "In9.Cu")
		(net "FM_HSC_TIMER_EXP_N")
	)
	(segment
		(start 396.917672 -64.487298)
		(end 396.91564 -64.48933)
		(width 0.089408)
		(layer "In9.Cu")
		(net "FM_HSC_TIMER_EXP_N")
	)
	(segment
		(start 397.87576 -60.81649)
		(end 397.876014 -60.816744)
		(width 0.089408)
		(layer "In9.Cu")
		(net "FM_HSC_TIMER_EXP_N")
	)
	(segment
		(start 397.296132 -45.79747)
		(end 397.296132 -48.328072)
		(width 0.089408)
		(layer "In9.Cu")
		(net "FM_HSC_TIMER_EXP_N")
	)
	(segment
		(start 397.296132 -48.328072)
		(end 397.56207 -48.59401)
		(width 0.089408)
		(layer "In9.Cu")
		(net "FM_HSC_TIMER_EXP_N")
	)
	(segment
		(start 338.247228 -11.124438)
		(end 338.247228 -20.382992)
		(width 0.089408)
		(layer "In9.Cu")
		(net "FM_HSC_TIMER_EXP_N")
	)
	(segment
		(start 331.623162 -9.406128)
		(end 331.67955 -9.406128)
		(width 0.089408)
		(layer "In9.Cu")
		(net "FM_HSC_TIMER_EXP_N")
	)
	(segment
		(start 27.357324 -73.762362)
		(end 26.9621 -74.157586)
		(width 0.089408)
		(layer "In9.Cu")
		(net "FM_HSC_TIMER_EXP_N")
	)
	(segment
		(start 400.434048 -33.861248)
		(end 401.381214 -33.861248)
		(width 0.089408)
		(layer "In9.Cu")
		(net "FM_HSC_TIMER_EXP_N")
	)
	(segment
		(start 393.083288 -78.755494)
		(end 392.761724 -79.077058)
		(width 0.089408)
		(layer "In9.Cu")
		(net "FM_HSC_TIMER_EXP_N")
	)
	(segment
		(start 396.232126 -69.478652)
		(end 394.836904 -70.873874)
		(width 0.089408)
		(layer "In9.Cu")
		(net "FM_HSC_TIMER_EXP_N")
	)
	(segment
		(start 414.495996 -29.718)
		(end 414.9598 -29.718)
		(width 0.089408)
		(layer "In9.Cu")
		(net "FM_HSC_TIMER_EXP_N")
	)
	(segment
		(start 400.18716 -33.61436)
		(end 400.434048 -33.861248)
		(width 0.089408)
		(layer "In9.Cu")
		(net "FM_HSC_TIMER_EXP_N")
	)
	(segment
		(start 27.89174 -54.102)
		(end 27.89174 -55.444644)
		(width 0.089408)
		(layer "In9.Cu")
		(net "FM_HSC_TIMER_EXP_N")
	)
	(segment
		(start 259.975096 -0.617728)
		(end 260.567424 -0.0254)
		(width 0.089408)
		(layer "In9.Cu")
		(net "FM_HSC_TIMER_EXP_N")
	)
	(segment
		(start 27.3558 -53.60416)
		(end 27.3939 -53.60416)
		(width 0.089408)
		(layer "In9.Cu")
		(net "FM_HSC_TIMER_EXP_N")
	)
	(segment
		(start 28.62707 -62.385194)
		(end 28.62707 -66.610484)
		(width 0.089408)
		(layer "In9.Cu")
		(net "FM_HSC_TIMER_EXP_N")
	)
	(segment
		(start 396.878302 -64.48933)
		(end 396.232126 -65.135506)
		(width 0.089408)
		(layer "In9.Cu")
		(net "FM_HSC_TIMER_EXP_N")
	)
	(segment
		(start 355.6762 -29.532834)
		(end 355.6762 -30.861)
		(width 0.089408)
		(layer "In9.Cu")
		(net "FM_HSC_TIMER_EXP_N")
	)
	(segment
		(start 338.247228 -20.382992)
		(end 338.856066 -20.99183)
		(width 0.089408)
		(layer "In9.Cu")
		(net "FM_HSC_TIMER_EXP_N")
	)
	(segment
		(start 330.979272 -9.406382)
		(end 331.622908 -9.406382)
		(width 0.089408)
		(layer "In9.Cu")
		(net "FM_HSC_TIMER_EXP_N")
	)
	(segment
		(start 398.490694 -44.998386)
		(end 398.095216 -44.998386)
		(width 0.089408)
		(layer "In9.Cu")
		(net "FM_HSC_TIMER_EXP_N")
	)
	(segment
		(start 331.622908 -9.406382)
		(end 331.623162 -9.406128)
		(width 0.089408)
		(layer "In9.Cu")
		(net "FM_HSC_TIMER_EXP_N")
	)
	(segment
		(start 194.097656 -0.617728)
		(end 259.975096 -0.617728)
		(width 0.089408)
		(layer "In9.Cu")
		(net "FM_HSC_TIMER_EXP_N")
	)
	(segment
		(start 394.836904 -71.717662)
		(end 394.59789 -71.956676)
		(width 0.089408)
		(layer "In9.Cu")
		(net "FM_HSC_TIMER_EXP_N")
	)
	(segment
		(start 389.22706 -88.42375)
		(end 389.22706 -89.788492)
		(width 0.089408)
		(layer "In9.Cu")
		(net "FM_HSC_TIMER_EXP_N")
	)
	(segment
		(start 340.675214 -23.729696)
		(end 348.327472 -23.729696)
		(width 0.089408)
		(layer "In9.Cu")
		(net "FM_HSC_TIMER_EXP_N")
	)
	(segment
		(start 338.856066 -23.126954)
		(end 339.35543 -23.626318)
		(width 0.089408)
		(layer "In9.Cu")
		(net "FM_HSC_TIMER_EXP_N")
	)
	(segment
		(start 389.22706 -89.788492)
		(end 388.138416 -90.877136)
		(width 0.089408)
		(layer "In9.Cu")
		(net "FM_HSC_TIMER_EXP_N")
	)
	(segment
		(start 396.232126 -65.135506)
		(end 396.232126 -69.478652)
		(width 0.089408)
		(layer "In9.Cu")
		(net "FM_HSC_TIMER_EXP_N")
	)
	(segment
		(start 394.321538 -75.661266)
		(end 393.265914 -76.71689)
		(width 0.089408)
		(layer "In9.Cu")
		(net "FM_HSC_TIMER_EXP_N")
	)
	(segment
		(start 28.0543 -61.812424)
		(end 28.62707 -62.385194)
		(width 0.089408)
		(layer "In9.Cu")
		(net "FM_HSC_TIMER_EXP_N")
	)
	(segment
		(start 397.075914 -64.487552)
		(end 397.07566 -64.487298)
		(width 0.089408)
		(layer "In9.Cu")
		(net "FM_HSC_TIMER_EXP_N")
	)
	(segment
		(start 171.96816 -5.5753)
		(end 170.447208 -4.054348)
		(width 0.089408)
		(layer "In11.Cu")
		(net "FM_HSC_TIMER_EXP_N")
	)
	(segment
		(start 160.48736 -0.23876)
		(end 156.6164 3.6322)
		(width 0.089408)
		(layer "In11.Cu")
		(net "FM_HSC_TIMER_EXP_N")
	)
	(segment
		(start 177.7873 -6.108954)
		(end 175.565054 -8.3312)
		(width 0.089408)
		(layer "In11.Cu")
		(net "FM_HSC_TIMER_EXP_N")
	)
	(segment
		(start 27.559508 -47.736252)
		(end 28.461462 -48.638206)
		(width 0.089408)
		(layer "In11.Cu")
		(net "FM_HSC_TIMER_EXP_N")
	)
	(segment
		(start 173.14418 -8.3312)
		(end 171.96816 -7.15518)
		(width 0.089408)
		(layer "In11.Cu")
		(net "FM_HSC_TIMER_EXP_N")
	)
	(segment
		(start 27.565858 1.447292)
		(end 27.565858 -20.18157)
		(width 0.089408)
		(layer "In11.Cu")
		(net "FM_HSC_TIMER_EXP_N")
	)
	(segment
		(start 166.66972 -2.273554)
		(end 164.634926 -0.23876)
		(width 0.089408)
		(layer "In11.Cu")
		(net "FM_HSC_TIMER_EXP_N")
	)
	(segment
		(start 185.3184 -4.569714)
		(end 180.757068 -4.569714)
		(width 0.089408)
		(layer "In11.Cu")
		(net "FM_HSC_TIMER_EXP_N")
	)
	(segment
		(start 118.807992 3.6322)
		(end 118.380764 3.204972)
		(width 0.089408)
		(layer "In11.Cu")
		(net "FM_HSC_TIMER_EXP_N")
	)
	(segment
		(start 156.6164 3.6322)
		(end 118.807992 3.6322)
		(width 0.089408)
		(layer "In11.Cu")
		(net "FM_HSC_TIMER_EXP_N")
	)
	(segment
		(start 167.614854 -4.054348)
		(end 166.66972 -3.109214)
		(width 0.089408)
		(layer "In11.Cu")
		(net "FM_HSC_TIMER_EXP_N")
	)
	(segment
		(start 28.461462 -52.498498)
		(end 27.3558 -53.60416)
		(width 0.089408)
		(layer "In11.Cu")
		(net "FM_HSC_TIMER_EXP_N")
	)
	(segment
		(start 103.169466 3.204972)
		(end 102.558088 3.81635)
		(width 0.089408)
		(layer "In11.Cu")
		(net "FM_HSC_TIMER_EXP_N")
	)
	(segment
		(start 170.447208 -4.054348)
		(end 167.614854 -4.054348)
		(width 0.089408)
		(layer "In11.Cu")
		(net "FM_HSC_TIMER_EXP_N")
	)
	(segment
		(start 179.217828 -6.108954)
		(end 177.7873 -6.108954)
		(width 0.089408)
		(layer "In11.Cu")
		(net "FM_HSC_TIMER_EXP_N")
	)
	(segment
		(start 27.559508 -44.258992)
		(end 27.559508 -47.736252)
		(width 0.089408)
		(layer "In11.Cu")
		(net "FM_HSC_TIMER_EXP_N")
	)
	(segment
		(start 166.66972 -3.109214)
		(end 166.66972 -2.273554)
		(width 0.089408)
		(layer "In11.Cu")
		(net "FM_HSC_TIMER_EXP_N")
	)
	(segment
		(start 118.380764 3.204972)
		(end 103.169466 3.204972)
		(width 0.089408)
		(layer "In11.Cu")
		(net "FM_HSC_TIMER_EXP_N")
	)
	(segment
		(start 29.223462 -29.221938)
		(end 29.147008 -29.298392)
		(width 0.089408)
		(layer "In11.Cu")
		(net "FM_HSC_TIMER_EXP_N")
	)
	(segment
		(start 102.558088 3.81635)
		(end 29.934916 3.81635)
		(width 0.089408)
		(layer "In11.Cu")
		(net "FM_HSC_TIMER_EXP_N")
	)
	(segment
		(start 171.96816 -7.15518)
		(end 171.96816 -5.5753)
		(width 0.089408)
		(layer "In11.Cu")
		(net "FM_HSC_TIMER_EXP_N")
	)
	(segment
		(start 164.634926 -0.23876)
		(end 160.48736 -0.23876)
		(width 0.089408)
		(layer "In11.Cu")
		(net "FM_HSC_TIMER_EXP_N")
	)
	(segment
		(start 29.934916 3.81635)
		(end 27.565858 1.447292)
		(width 0.089408)
		(layer "In11.Cu")
		(net "FM_HSC_TIMER_EXP_N")
	)
	(segment
		(start 29.147008 -42.671492)
		(end 27.559508 -44.258992)
		(width 0.089408)
		(layer "In11.Cu")
		(net "FM_HSC_TIMER_EXP_N")
	)
	(segment
		(start 28.461462 -48.638206)
		(end 28.461462 -52.498498)
		(width 0.089408)
		(layer "In11.Cu")
		(net "FM_HSC_TIMER_EXP_N")
	)
	(segment
		(start 180.757068 -4.569714)
		(end 179.217828 -6.108954)
		(width 0.089408)
		(layer "In11.Cu")
		(net "FM_HSC_TIMER_EXP_N")
	)
	(segment
		(start 175.565054 -8.3312)
		(end 173.14418 -8.3312)
		(width 0.089408)
		(layer "In11.Cu")
		(net "FM_HSC_TIMER_EXP_N")
	)
	(segment
		(start 27.565858 -20.18157)
		(end 29.223462 -21.839174)
		(width 0.089408)
		(layer "In11.Cu")
		(net "FM_HSC_TIMER_EXP_N")
	)
	(segment
		(start 29.223462 -21.839174)
		(end 29.223462 -29.221938)
		(width 0.089408)
		(layer "In11.Cu")
		(net "FM_HSC_TIMER_EXP_N")
	)
	(segment
		(start 29.147008 -29.298392)
		(end 29.147008 -42.671492)
		(width 0.089408)
		(layer "In11.Cu")
		(net "FM_HSC_TIMER_EXP_N")
	)
	(segment
		(start 415.9123 -83.087718)
		(end 415.9123 -84.1502)
		(width 0.10795)
		(layer "F.Cu")
		(net "FM_FAST_PROCHOT_AND_OUT_1_N")
	)
	(segment
		(start 415.65576 -84.85124)
		(end 415.65576 -85.494876)
		(width 0.10795)
		(layer "F.Cu")
		(net "FM_FAST_PROCHOT_AND_OUT_1_N")
	)
	(segment
		(start 414.105598 -91.430856)
		(end 413.960056 -91.430856)
		(width 0.10795)
		(layer "F.Cu")
		(net "FM_FAST_PROCHOT_AND_OUT_1_N")
	)
	(segment
		(start 415.9123 -84.1502)
		(end 415.9123 -84.5947)
		(width 0.10795)
		(layer "F.Cu")
		(net "FM_FAST_PROCHOT_AND_OUT_1_N")
	)
	(segment
		(start 414.140904 -91.466162)
		(end 414.105598 -91.430856)
		(width 0.10795)
		(layer "F.Cu")
		(net "FM_FAST_PROCHOT_AND_OUT_1_N")
	)
	(segment
		(start 416.068002 -82.932016)
		(end 415.9123 -83.087718)
		(width 0.10795)
		(layer "F.Cu")
		(net "FM_FAST_PROCHOT_AND_OUT_1_N")
	)
	(segment
		(start 413.960056 -91.430856)
		(end 413.655764 -91.126564)
		(width 0.10795)
		(layer "F.Cu")
		(net "FM_FAST_PROCHOT_AND_OUT_1_N")
	)
	(segment
		(start 413.655764 -91.126564)
		(end 413.655764 -88.823292)
		(width 0.10795)
		(layer "F.Cu")
		(net "FM_FAST_PROCHOT_AND_OUT_1_N")
	)
	(segment
		(start 415.9123 -84.5947)
		(end 415.65576 -84.85124)
		(width 0.10795)
		(layer "F.Cu")
		(net "FM_FAST_PROCHOT_AND_OUT_1_N")
	)
	(via
		(at 415.9123 -84.1502)
		(size 0.762)
		(drill 0.381)
		(layers "F.Cu" "B.Cu")
		(net "FM_FAST_PROCHOT_AND_OUT_1_N")
	)
	(via
		(at 416.068002 -82.932016)
		(size 0.508)
		(drill 0.254)
		(layers "F.Cu" "B.Cu")
		(net "FM_FAST_PROCHOT_AND_OUT_1_N")
	)
	(via
		(at 414.140904 -91.466162)
		(size 0.508)
		(drill 0.254)
		(layers "F.Cu" "B.Cu")
		(net "FM_FAST_PROCHOT_AND_OUT_1_N")
	)
	(segment
		(start 413.493458 -86.14791)
		(end 413.493458 -90.818716)
		(width 0.089408)
		(layer "In2.Cu")
		(net "FM_FAST_PROCHOT_AND_OUT_1_N")
	)
	(segment
		(start 416.068002 -83.573366)
		(end 413.493458 -86.14791)
		(width 0.089408)
		(layer "In2.Cu")
		(net "FM_FAST_PROCHOT_AND_OUT_1_N")
	)
	(segment
		(start 416.068002 -82.932016)
		(end 416.068002 -83.573366)
		(width 0.089408)
		(layer "In2.Cu")
		(net "FM_FAST_PROCHOT_AND_OUT_1_N")
	)
	(segment
		(start 413.493458 -90.818716)
		(end 414.140904 -91.466162)
		(width 0.089408)
		(layer "In2.Cu")
		(net "FM_FAST_PROCHOT_AND_OUT_1_N")
	)
	(segment
		(start 395.485112 -94.427802)
		(end 395.485112 -94.790006)
		(width 0.0889)
		(layer "F.Cu")
		(net "FM_SSATA_PCIE_M2_SEL")
	)
	(segment
		(start 395.689582 -93.258132)
		(end 395.689582 -93.724222)
		(width 0.0889)
		(layer "F.Cu")
		(net "FM_SSATA_PCIE_M2_SEL")
	)
	(segment
		(start 395.853158 -90.863928)
		(end 395.555978 -91.161108)
		(width 0.0889)
		(layer "F.Cu")
		(net "FM_SSATA_PCIE_M2_SEL")
	)
	(segment
		(start 400.431 -86.7156)
		(end 398.9197 -88.2269)
		(width 0.10795)
		(layer "F.Cu")
		(net "FM_SSATA_PCIE_M2_SEL")
	)
	(segment
		(start 395.689582 -93.724222)
		(end 395.807946 -93.842586)
		(width 0.0889)
		(layer "F.Cu")
		(net "FM_SSATA_PCIE_M2_SEL")
	)
	(segment
		(start 398.490186 -88.2269)
		(end 395.853158 -90.863928)
		(width 0.10795)
		(layer "F.Cu")
		(net "FM_SSATA_PCIE_M2_SEL")
	)
	(segment
		(start 400.685 -86.4616)
		(end 400.431 -86.7156)
		(width 0.10795)
		(layer "F.Cu")
		(net "FM_SSATA_PCIE_M2_SEL")
	)
	(segment
		(start 395.807946 -94.104968)
		(end 395.485112 -94.427802)
		(width 0.0889)
		(layer "F.Cu")
		(net "FM_SSATA_PCIE_M2_SEL")
	)
	(segment
		(start 400.685 -84.8995)
		(end 400.685 -86.4616)
		(width 0.10795)
		(layer "F.Cu")
		(net "FM_SSATA_PCIE_M2_SEL")
	)
	(segment
		(start 395.555978 -93.124528)
		(end 395.689582 -93.258132)
		(width 0.0889)
		(layer "F.Cu")
		(net "FM_SSATA_PCIE_M2_SEL")
	)
	(segment
		(start 395.807946 -93.842586)
		(end 395.807946 -94.104968)
		(width 0.0889)
		(layer "F.Cu")
		(net "FM_SSATA_PCIE_M2_SEL")
	)
	(segment
		(start 398.9197 -88.2269)
		(end 398.490186 -88.2269)
		(width 0.10795)
		(layer "F.Cu")
		(net "FM_SSATA_PCIE_M2_SEL")
	)
	(segment
		(start 395.555978 -91.161108)
		(end 395.555978 -93.124528)
		(width 0.0889)
		(layer "F.Cu")
		(net "FM_SSATA_PCIE_M2_SEL")
	)
	(via
		(at 400.431 -86.7156)
		(size 0.762)
		(drill 0.381)
		(layers "F.Cu" "B.Cu")
		(net "FM_SSATA_PCIE_M2_SEL")
	)
	(segment
		(start 380.136908 -40.688006)
		(end 380.136908 -40.329612)
		(width 0.10795)
		(layer "F.Cu")
		(net "FM_M2_SSD_PEDET")
	)
	(segment
		(start 402.463 -85.82025)
		(end 402.463 -84.582)
		(width 0.10795)
		(layer "F.Cu")
		(net "FM_M2_SSD_PEDET")
	)
	(segment
		(start 379.2728 -41.3258)
		(end 379.499114 -41.3258)
		(width 0.10795)
		(layer "F.Cu")
		(net "FM_M2_SSD_PEDET")
	)
	(segment
		(start 381.667004 -39.454328)
		(end 381.667004 -38.378892)
		(width 0.10795)
		(layer "F.Cu")
		(net "FM_M2_SSD_PEDET")
	)
	(segment
		(start 402.391372 -85.891878)
		(end 402.463 -85.82025)
		(width 0.10795)
		(layer "F.Cu")
		(net "FM_M2_SSD_PEDET")
	)
	(segment
		(start 404.241 -83.6295)
		(end 402.6535 -83.6295)
		(width 0.10795)
		(layer "F.Cu")
		(net "FM_M2_SSD_PEDET")
	)
	(segment
		(start 380.136908 -40.329612)
		(end 380.712218 -39.754302)
		(width 0.10795)
		(layer "F.Cu")
		(net "FM_M2_SSD_PEDET")
	)
	(segment
		(start 402.391372 -85.961982)
		(end 402.391372 -85.891878)
		(width 0.10795)
		(layer "F.Cu")
		(net "FM_M2_SSD_PEDET")
	)
	(segment
		(start 381.667004 -38.378892)
		(end 381.774954 -38.270942)
		(width 0.10795)
		(layer "F.Cu")
		(net "FM_M2_SSD_PEDET")
	)
	(segment
		(start 402.306536 -86.046818)
		(end 402.391372 -85.961982)
		(width 0.10795)
		(layer "F.Cu")
		(net "FM_M2_SSD_PEDET")
	)
	(segment
		(start 381.774954 -38.270942)
		(end 382.797304 -38.270942)
		(width 0.10795)
		(layer "F.Cu")
		(net "FM_M2_SSD_PEDET")
	)
	(segment
		(start 402.283676 -86.046818)
		(end 402.306536 -86.046818)
		(width 0.10795)
		(layer "F.Cu")
		(net "FM_M2_SSD_PEDET")
	)
	(segment
		(start 381.36703 -39.754302)
		(end 381.667004 -39.454328)
		(width 0.10795)
		(layer "F.Cu")
		(net "FM_M2_SSD_PEDET")
	)
	(segment
		(start 402.463 -83.82)
		(end 402.463 -84.582)
		(width 0.10795)
		(layer "F.Cu")
		(net "FM_M2_SSD_PEDET")
	)
	(segment
		(start 380.712218 -39.754302)
		(end 381.36703 -39.754302)
		(width 0.10795)
		(layer "F.Cu")
		(net "FM_M2_SSD_PEDET")
	)
	(segment
		(start 402.6535 -83.6295)
		(end 402.463 -83.82)
		(width 0.10795)
		(layer "F.Cu")
		(net "FM_M2_SSD_PEDET")
	)
	(segment
		(start 379.499114 -41.3258)
		(end 380.136908 -40.688006)
		(width 0.10795)
		(layer "F.Cu")
		(net "FM_M2_SSD_PEDET")
	)
	(via
		(at 379.2728 -41.3258)
		(size 0.508)
		(drill 0.254)
		(layers "F.Cu" "B.Cu")
		(net "FM_M2_SSD_PEDET")
	)
	(via
		(at 403.1742 -85.9536)
		(size 0.6604)
		(drill 0.3302)
		(layers "F.Cu" "B.Cu")
		(net "FM_M2_SSD_PEDET")
	)
	(via
		(at 402.283676 -86.046818)
		(size 0.508)
		(drill 0.254)
		(layers "F.Cu" "B.Cu")
		(net "FM_M2_SSD_PEDET")
	)
	(segment
		(start 402.376894 -85.9536)
		(end 402.283676 -86.046818)
		(width 0.10795)
		(layer "B.Cu")
		(net "FM_M2_SSD_PEDET")
	)
	(segment
		(start 403.1742 -85.9536)
		(end 402.376894 -85.9536)
		(width 0.10795)
		(layer "B.Cu")
		(net "FM_M2_SSD_PEDET")
	)
	(segment
		(start 396.475458 -70.148704)
		(end 398.13103 -71.804276)
		(width 0.089408)
		(layer "In11.Cu")
		(net "FM_M2_SSD_PEDET")
	)
	(segment
		(start 400.37258 -84.135722)
		(end 402.283676 -86.046818)
		(width 0.089408)
		(layer "In11.Cu")
		(net "FM_M2_SSD_PEDET")
	)
	(segment
		(start 398.13103 -72.849232)
		(end 399.464784 -74.182986)
		(width 0.089408)
		(layer "In11.Cu")
		(net "FM_M2_SSD_PEDET")
	)
	(segment
		(start 396.475458 -65.500758)
		(end 396.475458 -70.148704)
		(width 0.089408)
		(layer "In11.Cu")
		(net "FM_M2_SSD_PEDET")
	)
	(segment
		(start 394.973302 -63.998602)
		(end 396.475458 -65.500758)
		(width 0.089408)
		(layer "In11.Cu")
		(net "FM_M2_SSD_PEDET")
	)
	(segment
		(start 399.813526 -80.493362)
		(end 399.813526 -82.953098)
		(width 0.089408)
		(layer "In11.Cu")
		(net "FM_M2_SSD_PEDET")
	)
	(segment
		(start 394.973302 -57.107582)
		(end 394.973302 -63.998602)
		(width 0.089408)
		(layer "In11.Cu")
		(net "FM_M2_SSD_PEDET")
	)
	(segment
		(start 379.2728 -41.3258)
		(end 382.790192 -44.843192)
		(width 0.089408)
		(layer "In11.Cu")
		(net "FM_M2_SSD_PEDET")
	)
	(segment
		(start 399.80108 -76.12888)
		(end 399.80108 -77.153262)
		(width 0.089408)
		(layer "In11.Cu")
		(net "FM_M2_SSD_PEDET")
	)
	(segment
		(start 398.13103 -72.11441)
		(end 398.13103 -72.849232)
		(width 0.089408)
		(layer "In11.Cu")
		(net "FM_M2_SSD_PEDET")
	)
	(segment
		(start 400.087592 -78.666848)
		(end 400.12366 -78.702916)
		(width 0.089408)
		(layer "In11.Cu")
		(net "FM_M2_SSD_PEDET")
	)
	(segment
		(start 399.80108 -77.153262)
		(end 400.087592 -77.439774)
		(width 0.089408)
		(layer "In11.Cu")
		(net "FM_M2_SSD_PEDET")
	)
	(segment
		(start 399.464784 -75.792584)
		(end 399.80108 -76.12888)
		(width 0.089408)
		(layer "In11.Cu")
		(net "FM_M2_SSD_PEDET")
	)
	(segment
		(start 400.37258 -83.512152)
		(end 400.37258 -84.135722)
		(width 0.089408)
		(layer "In11.Cu")
		(net "FM_M2_SSD_PEDET")
	)
	(segment
		(start 399.813526 -82.953098)
		(end 400.37258 -83.512152)
		(width 0.089408)
		(layer "In11.Cu")
		(net "FM_M2_SSD_PEDET")
	)
	(segment
		(start 389.133334 -50.50282)
		(end 389.133334 -51.267614)
		(width 0.089408)
		(layer "In11.Cu")
		(net "FM_M2_SSD_PEDET")
	)
	(segment
		(start 389.133334 -51.267614)
		(end 394.973302 -57.107582)
		(width 0.089408)
		(layer "In11.Cu")
		(net "FM_M2_SSD_PEDET")
	)
	(segment
		(start 387.828028 -49.197514)
		(end 389.133334 -50.50282)
		(width 0.089408)
		(layer "In11.Cu")
		(net "FM_M2_SSD_PEDET")
	)
	(segment
		(start 384.478276 -44.843192)
		(end 387.828028 -48.192944)
		(width 0.089408)
		(layer "In11.Cu")
		(net "FM_M2_SSD_PEDET")
	)
	(segment
		(start 400.12366 -80.183228)
		(end 399.813526 -80.493362)
		(width 0.089408)
		(layer "In11.Cu")
		(net "FM_M2_SSD_PEDET")
	)
	(segment
		(start 400.12366 -78.702916)
		(end 400.12366 -80.183228)
		(width 0.089408)
		(layer "In11.Cu")
		(net "FM_M2_SSD_PEDET")
	)
	(segment
		(start 400.087592 -77.439774)
		(end 400.087592 -78.666848)
		(width 0.089408)
		(layer "In11.Cu")
		(net "FM_M2_SSD_PEDET")
	)
	(segment
		(start 398.13103 -71.91375)
		(end 398.131284 -71.914004)
		(width 0.089408)
		(layer "In11.Cu")
		(net "FM_M2_SSD_PEDET")
	)
	(segment
		(start 398.131284 -71.914004)
		(end 398.131284 -72.114156)
		(width 0.089408)
		(layer "In11.Cu")
		(net "FM_M2_SSD_PEDET")
	)
	(segment
		(start 399.464784 -74.182986)
		(end 399.464784 -75.792584)
		(width 0.089408)
		(layer "In11.Cu")
		(net "FM_M2_SSD_PEDET")
	)
	(segment
		(start 398.13103 -71.804276)
		(end 398.13103 -71.91375)
		(width 0.089408)
		(layer "In11.Cu")
		(net "FM_M2_SSD_PEDET")
	)
	(segment
		(start 382.790192 -44.843192)
		(end 384.478276 -44.843192)
		(width 0.089408)
		(layer "In11.Cu")
		(net "FM_M2_SSD_PEDET")
	)
	(segment
		(start 387.828028 -48.192944)
		(end 387.828028 -49.197514)
		(width 0.089408)
		(layer "In11.Cu")
		(net "FM_M2_SSD_PEDET")
	)
	(segment
		(start 398.131284 -72.114156)
		(end 398.13103 -72.11441)
		(width 0.089408)
		(layer "In11.Cu")
		(net "FM_M2_SSD_PEDET")
	)
	(segment
		(start 401.1295 -83.2485)
		(end 401.574 -82.804)
		(width 0.10795)
		(layer "F.Cu")
		(net "FM_M2_DET_LVC3")
	)
	(segment
		(start 399.437352 -81.791556)
		(end 399.437352 -82.230468)
		(width 0.10795)
		(layer "F.Cu")
		(net "FM_M2_DET_LVC3")
	)
	(segment
		(start 400.455384 -83.2485)
		(end 400.685 -83.2485)
		(width 0.10795)
		(layer "F.Cu")
		(net "FM_M2_DET_LVC3")
	)
	(segment
		(start 400.685 -83.2485)
		(end 401.1295 -83.2485)
		(width 0.10795)
		(layer "F.Cu")
		(net "FM_M2_DET_LVC3")
	)
	(segment
		(start 401.574 -82.804)
		(end 401.813014 -82.804)
		(width 0.10795)
		(layer "F.Cu")
		(net "FM_M2_DET_LVC3")
	)
	(segment
		(start 400.685 -84.0105)
		(end 400.685 -83.2485)
		(width 0.10795)
		(layer "F.Cu")
		(net "FM_M2_DET_LVC3")
	)
	(segment
		(start 399.437352 -82.230468)
		(end 400.455384 -83.2485)
		(width 0.10795)
		(layer "F.Cu")
		(net "FM_M2_DET_LVC3")
	)
	(via
		(at 399.437352 -81.791556)
		(size 0.762)
		(drill 0.381)
		(layers "F.Cu" "B.Cu")
		(net "FM_M2_DET_LVC3")
	)
	(segment
		(start 410.290264 -36.143184)
		(end 410.290264 -36.134548)
		(width 0.10795)
		(layer "F.Cu")
		(net "FM_BMC_SYS_THROTTLE_R_N")
	)
	(segment
		(start 410.6926 -36.54552)
		(end 410.290264 -36.143184)
		(width 0.10795)
		(layer "F.Cu")
		(net "FM_BMC_SYS_THROTTLE_R_N")
	)
	(via
		(at 407.366216 -37.108384)
		(size 0.6604)
		(drill 0.3302)
		(layers "F.Cu" "B.Cu")
		(net "FM_BMC_SYS_THROTTLE_R_N")
	)
	(via
		(at 410.6926 -36.54552)
		(size 0.4572)
		(drill 0.2032)
		(layers "F.Cu" "B.Cu")
		(net "FM_BMC_SYS_THROTTLE_R_N")
	)
	(segment
		(start 407.520648 -37.108384)
		(end 407.366216 -37.108384)
		(width 0.10795)
		(layer "B.Cu")
		(net "FM_BMC_SYS_THROTTLE_R_N")
	)
	(segment
		(start 408.663902 -37.182298)
		(end 408.663902 -37.537898)
		(width 0.10795)
		(layer "B.Cu")
		(net "FM_BMC_SYS_THROTTLE_R_N")
	)
	(segment
		(start 409.495498 -36.929314)
		(end 408.916886 -36.929314)
		(width 0.10795)
		(layer "B.Cu")
		(net "FM_BMC_SYS_THROTTLE_R_N")
	)
	(segment
		(start 406.23363 -37.328856)
		(end 406.720294 -37.328856)
		(width 0.10795)
		(layer "B.Cu")
		(net "FM_BMC_SYS_THROTTLE_R_N")
	)
	(segment
		(start 409.925012 -36.4998)
		(end 409.495498 -36.929314)
		(width 0.10795)
		(layer "B.Cu")
		(net "FM_BMC_SYS_THROTTLE_R_N")
	)
	(segment
		(start 405.60371 -37.051234)
		(end 405.956008 -37.051234)
		(width 0.10795)
		(layer "B.Cu")
		(net "FM_BMC_SYS_THROTTLE_R_N")
	)
	(segment
		(start 408.663902 -37.537898)
		(end 408.493214 -37.708586)
		(width 0.10795)
		(layer "B.Cu")
		(net "FM_BMC_SYS_THROTTLE_R_N")
	)
	(segment
		(start 405.956008 -37.051234)
		(end 406.23363 -37.328856)
		(width 0.10795)
		(layer "B.Cu")
		(net "FM_BMC_SYS_THROTTLE_R_N")
	)
	(segment
		(start 410.64688 -36.4998)
		(end 409.925012 -36.4998)
		(width 0.10795)
		(layer "B.Cu")
		(net "FM_BMC_SYS_THROTTLE_R_N")
	)
	(segment
		(start 408.493214 -37.708586)
		(end 408.12085 -37.708586)
		(width 0.10795)
		(layer "B.Cu")
		(net "FM_BMC_SYS_THROTTLE_R_N")
	)
	(segment
		(start 408.916886 -36.929314)
		(end 408.663902 -37.182298)
		(width 0.10795)
		(layer "B.Cu")
		(net "FM_BMC_SYS_THROTTLE_R_N")
	)
	(segment
		(start 408.12085 -37.708586)
		(end 407.520648 -37.108384)
		(width 0.10795)
		(layer "B.Cu")
		(net "FM_BMC_SYS_THROTTLE_R_N")
	)
	(segment
		(start 406.940766 -37.108384)
		(end 407.366216 -37.108384)
		(width 0.10795)
		(layer "B.Cu")
		(net "FM_BMC_SYS_THROTTLE_R_N")
	)
	(segment
		(start 406.720294 -37.328856)
		(end 406.940766 -37.108384)
		(width 0.10795)
		(layer "B.Cu")
		(net "FM_BMC_SYS_THROTTLE_R_N")
	)
	(segment
		(start 410.6926 -36.54552)
		(end 410.64688 -36.4998)
		(width 0.10795)
		(layer "B.Cu")
		(net "FM_BMC_SYS_THROTTLE_R_N")
	)
	(segment
		(start 9.228582 -39.237158)
		(end 10.936224 -40.9448)
		(width 0.10795)
		(layer "F.Cu")
		(net "FM_ENABLE_FAN_POWER")
	)
	(segment
		(start 18.943828 -42.701972)
		(end 18.5166 -42.701972)
		(width 0.1016)
		(layer "F.Cu")
		(net "FM_ENABLE_FAN_POWER")
	)
	(segment
		(start 16.303498 -44.788328)
		(end 17.467072 -44.788328)
		(width 0.10795)
		(layer "F.Cu")
		(net "FM_ENABLE_FAN_POWER")
	)
	(segment
		(start 18.2626 -40.9448)
		(end 19.177 -40.9448)
		(width 0.1016)
		(layer "F.Cu")
		(net "FM_ENABLE_FAN_POWER")
	)
	(segment
		(start 19.3294 -42.3164)
		(end 18.943828 -42.701972)
		(width 0.1016)
		(layer "F.Cu")
		(net "FM_ENABLE_FAN_POWER")
	)
	(segment
		(start 18.5166 -43.6118)
		(end 18.4658 -43.6626)
		(width 0.10795)
		(layer "F.Cu")
		(net "FM_ENABLE_FAN_POWER")
	)
	(segment
		(start 19.177 -40.9448)
		(end 19.3294 -41.0972)
		(width 0.1016)
		(layer "F.Cu")
		(net "FM_ENABLE_FAN_POWER")
	)
	(segment
		(start 10.936224 -40.9448)
		(end 18.2626 -40.9448)
		(width 0.10795)
		(layer "F.Cu")
		(net "FM_ENABLE_FAN_POWER")
	)
	(segment
		(start 9.228582 -37.409882)
		(end 9.228582 -39.237158)
		(width 0.10795)
		(layer "F.Cu")
		(net "FM_ENABLE_FAN_POWER")
	)
	(segment
		(start 7.29996 -35.710114)
		(end 7.528814 -35.710114)
		(width 0.10795)
		(layer "F.Cu")
		(net "FM_ENABLE_FAN_POWER")
	)
	(segment
		(start 7.528814 -35.710114)
		(end 9.228582 -37.409882)
		(width 0.10795)
		(layer "F.Cu")
		(net "FM_ENABLE_FAN_POWER")
	)
	(segment
		(start 18.4658 -43.7896)
		(end 18.4658 -43.6626)
		(width 0.10795)
		(layer "F.Cu")
		(net "FM_ENABLE_FAN_POWER")
	)
	(segment
		(start 19.3294 -41.0972)
		(end 19.3294 -42.3164)
		(width 0.1016)
		(layer "F.Cu")
		(net "FM_ENABLE_FAN_POWER")
	)
	(segment
		(start 18.5166 -42.701972)
		(end 18.5166 -43.6118)
		(width 0.10795)
		(layer "F.Cu")
		(net "FM_ENABLE_FAN_POWER")
	)
	(segment
		(start 17.467072 -44.788328)
		(end 18.4658 -43.7896)
		(width 0.10795)
		(layer "F.Cu")
		(net "FM_ENABLE_FAN_POWER")
	)
	(via
		(at 7.995158 -122.628152)
		(size 0.508)
		(drill 0.254)
		(layers "F.Cu" "B.Cu")
		(net "FM_ENABLE_FAN_POWER")
	)
	(via
		(at 16.303498 -44.788328)
		(size 0.508)
		(drill 0.254)
		(layers "F.Cu" "B.Cu")
		(net "FM_ENABLE_FAN_POWER")
	)
	(segment
		(start 7.995158 -122.628152)
		(end 7.995158 -122.595386)
		(width 0.10795)
		(layer "B.Cu")
		(net "FM_ENABLE_FAN_POWER")
	)
	(segment
		(start 7.8359 -122.436128)
		(end 7.2898 -122.436128)
		(width 0.10795)
		(layer "B.Cu")
		(net "FM_ENABLE_FAN_POWER")
	)
	(segment
		(start 7.995158 -122.595386)
		(end 7.8359 -122.436128)
		(width 0.10795)
		(layer "B.Cu")
		(net "FM_ENABLE_FAN_POWER")
	)
	(segment
		(start 11.449304 -51.192684)
		(end 11.449304 -67.123818)
		(width 0.089408)
		(layer "In11.Cu")
		(net "FM_ENABLE_FAN_POWER")
	)
	(segment
		(start 16.303752 -119.066818)
		(end 15.75689 -119.61368)
		(width 0.089408)
		(layer "In11.Cu")
		(net "FM_ENABLE_FAN_POWER")
	)
	(segment
		(start 16.36776 -118.96979)
		(end 16.303752 -119.033798)
		(width 0.089408)
		(layer "In11.Cu")
		(net "FM_ENABLE_FAN_POWER")
	)
	(segment
		(start 13.207238 -109.71022)
		(end 13.207238 -111.362998)
		(width 0.089408)
		(layer "In11.Cu")
		(net "FM_ENABLE_FAN_POWER")
	)
	(segment
		(start 16.303498 -44.788328)
		(end 16.199104 -44.683934)
		(width 0.089408)
		(layer "In11.Cu")
		(net "FM_ENABLE_FAN_POWER")
	)
	(segment
		(start 14.998954 -44.880784)
		(end 14.998954 -47.643034)
		(width 0.089408)
		(layer "In11.Cu")
		(net "FM_ENABLE_FAN_POWER")
	)
	(segment
		(start 11.604498 -80.835754)
		(end 11.604498 -82.850736)
		(width 0.089408)
		(layer "In11.Cu")
		(net "FM_ENABLE_FAN_POWER")
	)
	(segment
		(start 11.947652 -70.739508)
		(end 11.219688 -71.467472)
		(width 0.089408)
		(layer "In11.Cu")
		(net "FM_ENABLE_FAN_POWER")
	)
	(segment
		(start 11.219688 -71.467472)
		(end 11.219688 -80.450944)
		(width 0.089408)
		(layer "In11.Cu")
		(net "FM_ENABLE_FAN_POWER")
	)
	(segment
		(start 11.604498 -82.850736)
		(end 10.953496 -83.501738)
		(width 0.089408)
		(layer "In11.Cu")
		(net "FM_ENABLE_FAN_POWER")
	)
	(segment
		(start 13.207238 -111.362998)
		(end 16.36776 -114.52352)
		(width 0.089408)
		(layer "In11.Cu")
		(net "FM_ENABLE_FAN_POWER")
	)
	(segment
		(start 10.953496 -107.456478)
		(end 13.207238 -109.71022)
		(width 0.089408)
		(layer "In11.Cu")
		(net "FM_ENABLE_FAN_POWER")
	)
	(segment
		(start 11.947652 -67.622166)
		(end 11.947652 -70.739508)
		(width 0.089408)
		(layer "In11.Cu")
		(net "FM_ENABLE_FAN_POWER")
	)
	(segment
		(start 16.199104 -44.683934)
		(end 15.195804 -44.683934)
		(width 0.089408)
		(layer "In11.Cu")
		(net "FM_ENABLE_FAN_POWER")
	)
	(segment
		(start 16.36776 -114.52352)
		(end 16.36776 -118.96979)
		(width 0.089408)
		(layer "In11.Cu")
		(net "FM_ENABLE_FAN_POWER")
	)
	(segment
		(start 16.303752 -119.033798)
		(end 16.303752 -119.066818)
		(width 0.089408)
		(layer "In11.Cu")
		(net "FM_ENABLE_FAN_POWER")
	)
	(segment
		(start 15.72387 -119.61368)
		(end 14.961108 -120.376442)
		(width 0.089408)
		(layer "In11.Cu")
		(net "FM_ENABLE_FAN_POWER")
	)
	(segment
		(start 10.246868 -120.376442)
		(end 7.995158 -122.628152)
		(width 0.089408)
		(layer "In11.Cu")
		(net "FM_ENABLE_FAN_POWER")
	)
	(segment
		(start 11.449304 -67.123818)
		(end 11.947652 -67.622166)
		(width 0.089408)
		(layer "In11.Cu")
		(net "FM_ENABLE_FAN_POWER")
	)
	(segment
		(start 15.75689 -119.61368)
		(end 15.72387 -119.61368)
		(width 0.089408)
		(layer "In11.Cu")
		(net "FM_ENABLE_FAN_POWER")
	)
	(segment
		(start 10.953496 -83.501738)
		(end 10.953496 -107.456478)
		(width 0.089408)
		(layer "In11.Cu")
		(net "FM_ENABLE_FAN_POWER")
	)
	(segment
		(start 14.998954 -47.643034)
		(end 11.449304 -51.192684)
		(width 0.089408)
		(layer "In11.Cu")
		(net "FM_ENABLE_FAN_POWER")
	)
	(segment
		(start 14.961108 -120.376442)
		(end 10.246868 -120.376442)
		(width 0.089408)
		(layer "In11.Cu")
		(net "FM_ENABLE_FAN_POWER")
	)
	(segment
		(start 15.195804 -44.683934)
		(end 14.998954 -44.880784)
		(width 0.089408)
		(layer "In11.Cu")
		(net "FM_ENABLE_FAN_POWER")
	)
	(segment
		(start 11.219688 -80.450944)
		(end 11.604498 -80.835754)
		(width 0.089408)
		(layer "In11.Cu")
		(net "FM_ENABLE_FAN_POWER")
	)
	(segment
		(start 21.24329 -42.24909)
		(end 21.046186 -42.051986)
		(width 0.10795)
		(layer "F.Cu")
		(net "FM_DISABLE_FAN_N")
	)
	(segment
		(start 22.029674 -48.043592)
		(end 21.128736 -47.142654)
		(width 0.10795)
		(layer "F.Cu")
		(net "FM_DISABLE_FAN_N")
	)
	(segment
		(start 21.24329 -43.462448)
		(end 21.24329 -42.24909)
		(width 0.10795)
		(layer "F.Cu")
		(net "FM_DISABLE_FAN_N")
	)
	(segment
		(start 21.046186 -42.051986)
		(end 20.2946 -42.051986)
		(width 0.10795)
		(layer "F.Cu")
		(net "FM_DISABLE_FAN_N")
	)
	(segment
		(start 21.128736 -43.577002)
		(end 21.24329 -43.462448)
		(width 0.10795)
		(layer "F.Cu")
		(net "FM_DISABLE_FAN_N")
	)
	(segment
		(start 21.128736 -47.142654)
		(end 21.128736 -43.577002)
		(width 0.10795)
		(layer "F.Cu")
		(net "FM_DISABLE_FAN_N")
	)
	(via
		(at 22.029674 -48.043592)
		(size 0.508)
		(drill 0.254)
		(layers "F.Cu" "B.Cu")
		(net "FM_DISABLE_FAN_N")
	)
	(via
		(at 25.5397 -85.12556)
		(size 0.508)
		(drill 0.254)
		(layers "F.Cu" "B.Cu")
		(net "FM_DISABLE_FAN_N")
	)
	(segment
		(start 26.52522 -87.24138)
		(end 26.16454 -87.24138)
		(width 0.10795)
		(layer "B.Cu")
		(net "FM_DISABLE_FAN_N")
	)
	(segment
		(start 26.3906 -84.5312)
		(end 26.13406 -84.5312)
		(width 0.10795)
		(layer "B.Cu")
		(net "FM_DISABLE_FAN_N")
	)
	(segment
		(start 26.8732 -86.8934)
		(end 26.52522 -87.24138)
		(width 0.10795)
		(layer "B.Cu")
		(net "FM_DISABLE_FAN_N")
	)
	(segment
		(start 26.8732 -85.9028)
		(end 26.8732 -86.8934)
		(width 0.10795)
		(layer "B.Cu")
		(net "FM_DISABLE_FAN_N")
	)
	(segment
		(start 26.8732 -85.9028)
		(end 26.8732 -84.734146)
		(width 0.10795)
		(layer "B.Cu")
		(net "FM_DISABLE_FAN_N")
	)
	(segment
		(start 26.8732 -84.734146)
		(end 26.670254 -84.5312)
		(width 0.10795)
		(layer "B.Cu")
		(net "FM_DISABLE_FAN_N")
	)
	(segment
		(start 26.13406 -84.5312)
		(end 25.5397 -85.12556)
		(width 0.10795)
		(layer "B.Cu")
		(net "FM_DISABLE_FAN_N")
	)
	(segment
		(start 26.670254 -84.5312)
		(end 26.3906 -84.5312)
		(width 0.10795)
		(layer "B.Cu")
		(net "FM_DISABLE_FAN_N")
	)
	(segment
		(start 25.5397 -85.12556)
		(end 24.83358 -84.41944)
		(width 0.089408)
		(layer "In11.Cu")
		(net "FM_DISABLE_FAN_N")
	)
	(segment
		(start 24.83358 -84.41944)
		(end 23.276306 -84.41944)
		(width 0.089408)
		(layer "In11.Cu")
		(net "FM_DISABLE_FAN_N")
	)
	(segment
		(start 23.2156 -49.229518)
		(end 22.029674 -48.043592)
		(width 0.089408)
		(layer "In11.Cu")
		(net "FM_DISABLE_FAN_N")
	)
	(segment
		(start 23.2156 -51.59629)
		(end 23.2156 -49.229518)
		(width 0.089408)
		(layer "In11.Cu")
		(net "FM_DISABLE_FAN_N")
	)
	(segment
		(start 22.1361 -81.48828)
		(end 25.019 -78.60538)
		(width 0.089408)
		(layer "In11.Cu")
		(net "FM_DISABLE_FAN_N")
	)
	(segment
		(start 25.019 -74.361548)
		(end 26.86558 -72.514968)
		(width 0.089408)
		(layer "In11.Cu")
		(net "FM_DISABLE_FAN_N")
	)
	(segment
		(start 25.019 -78.60538)
		(end 25.019 -74.361548)
		(width 0.089408)
		(layer "In11.Cu")
		(net "FM_DISABLE_FAN_N")
	)
	(segment
		(start 22.1361 -83.279234)
		(end 22.1361 -81.48828)
		(width 0.089408)
		(layer "In11.Cu")
		(net "FM_DISABLE_FAN_N")
	)
	(segment
		(start 26.86558 -72.514968)
		(end 26.86558 -55.24627)
		(width 0.089408)
		(layer "In11.Cu")
		(net "FM_DISABLE_FAN_N")
	)
	(segment
		(start 23.276306 -84.41944)
		(end 22.1361 -83.279234)
		(width 0.089408)
		(layer "In11.Cu")
		(net "FM_DISABLE_FAN_N")
	)
	(segment
		(start 26.86558 -55.24627)
		(end 23.2156 -51.59629)
		(width 0.089408)
		(layer "In11.Cu")
		(net "FM_DISABLE_FAN_N")
	)
	(segment
		(start 371.9449 -78.294738)
		(end 371.545104 -77.894942)
		(width 0.1016)
		(layer "F.Cu")
		(net "RST_CPU1_LVC3_R1_N")
	)
	(via
		(at 371.9449 -78.294738)
		(size 0.4572)
		(drill 0.2032)
		(layers "F.Cu" "B.Cu")
		(net "RST_CPU1_LVC3_R1_N")
	)
	(via
		(at 371.976904 -80.137)
		(size 0.6604)
		(drill 0.3302)
		(layers "F.Cu" "B.Cu")
		(net "RST_CPU1_LVC3_R1_N")
	)
	(segment
		(start 362.992162 -76.38034)
		(end 362.992162 -80.69707)
		(width 0.10795)
		(layer "B.Cu")
		(net "RST_CPU1_LVC3_R1_N")
	)
	(segment
		(start 371.5512 -79.3242)
		(end 371.5512 -78.688438)
		(width 0.10795)
		(layer "B.Cu")
		(net "RST_CPU1_LVC3_R1_N")
	)
	(segment
		(start 371.543834 -81.234788)
		(end 371.67439 -81.234788)
		(width 0.10795)
		(layer "B.Cu")
		(net "RST_CPU1_LVC3_R1_N")
	)
	(segment
		(start 371.976904 -80.137)
		(end 371.976904 -79.749904)
		(width 0.10795)
		(layer "B.Cu")
		(net "RST_CPU1_LVC3_R1_N")
	)
	(segment
		(start 363.855762 -81.56067)
		(end 371.217952 -81.56067)
		(width 0.10795)
		(layer "B.Cu")
		(net "RST_CPU1_LVC3_R1_N")
	)
	(segment
		(start 353.6315 -74.549)
		(end 353.774756 -74.405744)
		(width 0.10795)
		(layer "B.Cu")
		(net "RST_CPU1_LVC3_R1_N")
	)
	(segment
		(start 371.67439 -81.234788)
		(end 371.976904 -80.932274)
		(width 0.10795)
		(layer "B.Cu")
		(net "RST_CPU1_LVC3_R1_N")
	)
	(segment
		(start 371.976904 -79.749904)
		(end 371.5512 -79.3242)
		(width 0.10795)
		(layer "B.Cu")
		(net "RST_CPU1_LVC3_R1_N")
	)
	(segment
		(start 371.217952 -81.56067)
		(end 371.543834 -81.234788)
		(width 0.10795)
		(layer "B.Cu")
		(net "RST_CPU1_LVC3_R1_N")
	)
	(segment
		(start 371.5512 -78.688438)
		(end 371.9449 -78.294738)
		(width 0.10795)
		(layer "B.Cu")
		(net "RST_CPU1_LVC3_R1_N")
	)
	(segment
		(start 361.017566 -74.405744)
		(end 362.992162 -76.38034)
		(width 0.10795)
		(layer "B.Cu")
		(net "RST_CPU1_LVC3_R1_N")
	)
	(segment
		(start 362.992162 -80.69707)
		(end 363.855762 -81.56067)
		(width 0.10795)
		(layer "B.Cu")
		(net "RST_CPU1_LVC3_R1_N")
	)
	(segment
		(start 353.774756 -74.405744)
		(end 361.017566 -74.405744)
		(width 0.10795)
		(layer "B.Cu")
		(net "RST_CPU1_LVC3_R1_N")
	)
	(segment
		(start 371.976904 -80.932274)
		(end 371.976904 -80.137)
		(width 0.10795)
		(layer "B.Cu")
		(net "RST_CPU1_LVC3_R1_N")
	)
	(segment
		(start 371.145308 -79.894684)
		(end 371.545104 -79.494888)
		(width 0.10795)
		(layer "F.Cu")
		(net "RST_CPU0_LVC3_R1_N")
	)
	(via
		(at 371.145308 -79.894684)
		(size 0.4572)
		(drill 0.2032)
		(layers "F.Cu" "B.Cu")
		(net "RST_CPU0_LVC3_R1_N")
	)
	(via
		(at 366.5601 -80.03032)
		(size 0.6604)
		(drill 0.3302)
		(layers "F.Cu" "B.Cu")
		(net "RST_CPU0_LVC3_R1_N")
	)
	(segment
		(start 366.55502 -80.0354)
		(end 365.3028 -80.0354)
		(width 0.10795)
		(layer "B.Cu")
		(net "RST_CPU0_LVC3_R1_N")
	)
	(segment
		(start 369.12804 -79.676244)
		(end 368.941096 -79.4893)
		(width 0.10795)
		(layer "B.Cu")
		(net "RST_CPU0_LVC3_R1_N")
	)
	(segment
		(start 371.145308 -79.894684)
		(end 370.929916 -79.894684)
		(width 0.10795)
		(layer "B.Cu")
		(net "RST_CPU0_LVC3_R1_N")
	)
	(segment
		(start 366.5601 -80.03032)
		(end 366.55502 -80.0354)
		(width 0.10795)
		(layer "B.Cu")
		(net "RST_CPU0_LVC3_R1_N")
	)
	(segment
		(start 369.320572 -80.2894)
		(end 369.12804 -80.096868)
		(width 0.10795)
		(layer "B.Cu")
		(net "RST_CPU0_LVC3_R1_N")
	)
	(segment
		(start 367.252504 -80.03032)
		(end 366.5601 -80.03032)
		(width 0.10795)
		(layer "B.Cu")
		(net "RST_CPU0_LVC3_R1_N")
	)
	(segment
		(start 367.793524 -79.4893)
		(end 367.252504 -80.03032)
		(width 0.10795)
		(layer "B.Cu")
		(net "RST_CPU0_LVC3_R1_N")
	)
	(segment
		(start 369.12804 -80.096868)
		(end 369.12804 -79.676244)
		(width 0.10795)
		(layer "B.Cu")
		(net "RST_CPU0_LVC3_R1_N")
	)
	(segment
		(start 370.5352 -80.2894)
		(end 369.320572 -80.2894)
		(width 0.10795)
		(layer "B.Cu")
		(net "RST_CPU0_LVC3_R1_N")
	)
	(segment
		(start 370.929916 -79.894684)
		(end 370.5352 -80.2894)
		(width 0.10795)
		(layer "B.Cu")
		(net "RST_CPU0_LVC3_R1_N")
	)
	(segment
		(start 368.941096 -79.4893)
		(end 367.793524 -79.4893)
		(width 0.10795)
		(layer "B.Cu")
		(net "RST_CPU0_LVC3_R1_N")
	)
	(segment
		(start 413.655764 -84.636864)
		(end 413.655764 -85.494876)
		(width 0.10795)
		(layer "F.Cu")
		(net "FM_PS_EN")
	)
	(segment
		(start 413.5374 -84.5185)
		(end 413.655764 -84.636864)
		(width 0.10795)
		(layer "F.Cu")
		(net "FM_PS_EN")
	)
	(segment
		(start 411.520386 -84.329016)
		(end 411.70987 -84.5185)
		(width 0.10795)
		(layer "F.Cu")
		(net "FM_PS_EN")
	)
	(segment
		(start 412.853124 -85.494876)
		(end 413.655764 -85.494876)
		(width 0.10795)
		(layer "F.Cu")
		(net "FM_PS_EN")
	)
	(segment
		(start 411.70987 -84.5185)
		(end 413.5374 -84.5185)
		(width 0.10795)
		(layer "F.Cu")
		(net "FM_PS_EN")
	)
	(segment
		(start 412.2293 -86.1187)
		(end 412.853124 -85.494876)
		(width 0.10795)
		(layer "F.Cu")
		(net "FM_PS_EN")
	)
	(segment
		(start 371.945154 -71.895208)
		(end 372.34495 -72.295004)
		(width 0.1016)
		(layer "F.Cu")
		(net "FM_PS_EN")
	)
	(segment
		(start 412.2293 -86.6521)
		(end 412.2293 -86.1187)
		(width 0.10795)
		(layer "F.Cu")
		(net "FM_PS_EN")
	)
	(segment
		(start 411.48 -87.8205)
		(end 411.48 -87.4014)
		(width 0.10795)
		(layer "F.Cu")
		(net "FM_PS_EN")
	)
	(segment
		(start 411.48 -87.4014)
		(end 412.2293 -86.6521)
		(width 0.10795)
		(layer "F.Cu")
		(net "FM_PS_EN")
	)
	(via
		(at 371.945154 -71.895208)
		(size 0.4572)
		(drill 0.2032)
		(layers "F.Cu" "B.Cu")
		(net "FM_PS_EN")
	)
	(via
		(at 413.077914 -69.420486)
		(size 0.508)
		(drill 0.254)
		(layers "F.Cu" "B.Cu")
		(net "FM_PS_EN")
	)
	(via
		(at 411.520386 -84.329016)
		(size 0.508)
		(drill 0.254)
		(layers "F.Cu" "B.Cu")
		(net "FM_PS_EN")
	)
	(segment
		(start 412.803848 -70.58025)
		(end 412.803848 -71.228966)
		(width 0.089408)
		(layer "In2.Cu")
		(net "FM_PS_EN")
	)
	(segment
		(start 412.803848 -71.228966)
		(end 412.803594 -71.22922)
		(width 0.089408)
		(layer "In2.Cu")
		(net "FM_PS_EN")
	)
	(segment
		(start 412.451296 -81.049368)
		(end 412.451296 -83.39709)
		(width 0.089408)
		(layer "In2.Cu")
		(net "FM_PS_EN")
	)
	(segment
		(start 413.711898 -77.210158)
		(end 413.711898 -77.843634)
		(width 0.089408)
		(layer "In2.Cu")
		(net "FM_PS_EN")
	)
	(segment
		(start 412.803594 -71.479918)
		(end 412.56458 -71.718932)
		(width 0.089408)
		(layer "In2.Cu")
		(net "FM_PS_EN")
	)
	(segment
		(start 413.712152 -75.837288)
		(end 413.712152 -77.209904)
		(width 0.089408)
		(layer "In2.Cu")
		(net "FM_PS_EN")
	)
	(segment
		(start 413.077914 -70.306184)
		(end 412.803848 -70.58025)
		(width 0.089408)
		(layer "In2.Cu")
		(net "FM_PS_EN")
	)
	(segment
		(start 413.077914 -69.420486)
		(end 413.077914 -70.306184)
		(width 0.089408)
		(layer "In2.Cu")
		(net "FM_PS_EN")
	)
	(segment
		(start 413.712152 -78.867)
		(end 413.711898 -78.867254)
		(width 0.089408)
		(layer "In2.Cu")
		(net "FM_PS_EN")
	)
	(segment
		(start 413.711898 -77.843634)
		(end 413.712152 -77.843888)
		(width 0.089408)
		(layer "In2.Cu")
		(net "FM_PS_EN")
	)
	(segment
		(start 413.712152 -77.843888)
		(end 413.712152 -78.867)
		(width 0.089408)
		(layer "In2.Cu")
		(net "FM_PS_EN")
	)
	(segment
		(start 413.712152 -79.342488)
		(end 413.712152 -79.788512)
		(width 0.089408)
		(layer "In2.Cu")
		(net "FM_PS_EN")
	)
	(segment
		(start 412.56458 -71.718932)
		(end 412.56458 -74.17816)
		(width 0.089408)
		(layer "In2.Cu")
		(net "FM_PS_EN")
	)
	(segment
		(start 411.520386 -84.328)
		(end 411.520386 -84.329016)
		(width 0.089408)
		(layer "In2.Cu")
		(net "FM_PS_EN")
	)
	(segment
		(start 413.711898 -75.325478)
		(end 413.711898 -75.837034)
		(width 0.089408)
		(layer "In2.Cu")
		(net "FM_PS_EN")
	)
	(segment
		(start 413.711898 -78.867254)
		(end 413.711898 -79.342234)
		(width 0.089408)
		(layer "In2.Cu")
		(net "FM_PS_EN")
	)
	(segment
		(start 413.711898 -75.837034)
		(end 413.712152 -75.837288)
		(width 0.089408)
		(layer "In2.Cu")
		(net "FM_PS_EN")
	)
	(segment
		(start 412.56458 -74.17816)
		(end 413.711898 -75.325478)
		(width 0.089408)
		(layer "In2.Cu")
		(net "FM_PS_EN")
	)
	(segment
		(start 412.803594 -71.22922)
		(end 412.803594 -71.479918)
		(width 0.089408)
		(layer "In2.Cu")
		(net "FM_PS_EN")
	)
	(segment
		(start 412.451296 -83.39709)
		(end 411.520386 -84.328)
		(width 0.089408)
		(layer "In2.Cu")
		(net "FM_PS_EN")
	)
	(segment
		(start 413.711898 -79.342234)
		(end 413.712152 -79.342488)
		(width 0.089408)
		(layer "In2.Cu")
		(net "FM_PS_EN")
	)
	(segment
		(start 413.712152 -79.788512)
		(end 412.451296 -81.049368)
		(width 0.089408)
		(layer "In2.Cu")
		(net "FM_PS_EN")
	)
	(segment
		(start 413.712152 -77.209904)
		(end 413.711898 -77.210158)
		(width 0.089408)
		(layer "In2.Cu")
		(net "FM_PS_EN")
	)
	(segment
		(start 385.517898 -70.696836)
		(end 380.753112 -70.696836)
		(width 0.089408)
		(layer "In4.Cu")
		(net "FM_PS_EN")
	)
	(segment
		(start 374.499378 -72.268588)
		(end 372.318534 -72.268588)
		(width 0.089408)
		(layer "In4.Cu")
		(net "FM_PS_EN")
	)
	(segment
		(start 380.753112 -70.696836)
		(end 380.748032 -70.701916)
		(width 0.089408)
		(layer "In4.Cu")
		(net "FM_PS_EN")
	)
	(segment
		(start 375.978674 -71.305674)
		(end 375.462292 -71.305674)
		(width 0.089408)
		(layer "In4.Cu")
		(net "FM_PS_EN")
	)
	(segment
		(start 413.077914 -69.420486)
		(end 412.59125 -69.90715)
		(width 0.089408)
		(layer "In4.Cu")
		(net "FM_PS_EN")
	)
	(segment
		(start 409.14574 -70.418706)
		(end 408.731466 -70.83298)
		(width 0.089408)
		(layer "In4.Cu")
		(net "FM_PS_EN")
	)
	(segment
		(start 376.56262 -70.721728)
		(end 375.978674 -71.305674)
		(width 0.089408)
		(layer "In4.Cu")
		(net "FM_PS_EN")
	)
	(segment
		(start 411.711648 -69.90715)
		(end 411.200092 -70.418706)
		(width 0.089408)
		(layer "In4.Cu")
		(net "FM_PS_EN")
	)
	(segment
		(start 379.81763 -71.009002)
		(end 379.530356 -70.721728)
		(width 0.089408)
		(layer "In4.Cu")
		(net "FM_PS_EN")
	)
	(segment
		(start 375.255282 -71.512684)
		(end 374.99925 -71.512684)
		(width 0.089408)
		(layer "In4.Cu")
		(net "FM_PS_EN")
	)
	(segment
		(start 412.59125 -69.90715)
		(end 411.711648 -69.90715)
		(width 0.089408)
		(layer "In4.Cu")
		(net "FM_PS_EN")
	)
	(segment
		(start 372.318534 -72.268588)
		(end 371.945154 -71.895208)
		(width 0.089408)
		(layer "In4.Cu")
		(net "FM_PS_EN")
	)
	(segment
		(start 395.94409 -71.874888)
		(end 395.49578 -72.323198)
		(width 0.089408)
		(layer "In4.Cu")
		(net "FM_PS_EN")
	)
	(segment
		(start 397.080232 -70.832726)
		(end 396.03807 -71.874888)
		(width 0.089408)
		(layer "In4.Cu")
		(net "FM_PS_EN")
	)
	(segment
		(start 374.99925 -71.512684)
		(end 374.720612 -71.791322)
		(width 0.089408)
		(layer "In4.Cu")
		(net "FM_PS_EN")
	)
	(segment
		(start 375.462292 -71.305674)
		(end 375.255282 -71.512684)
		(width 0.089408)
		(layer "In4.Cu")
		(net "FM_PS_EN")
	)
	(segment
		(start 397.238474 -70.83298)
		(end 397.23822 -70.832726)
		(width 0.089408)
		(layer "In4.Cu")
		(net "FM_PS_EN")
	)
	(segment
		(start 408.731466 -70.83298)
		(end 397.238474 -70.83298)
		(width 0.089408)
		(layer "In4.Cu")
		(net "FM_PS_EN")
	)
	(segment
		(start 397.23822 -70.832726)
		(end 397.080232 -70.832726)
		(width 0.089408)
		(layer "In4.Cu")
		(net "FM_PS_EN")
	)
	(segment
		(start 380.748032 -70.701916)
		(end 380.731776 -70.701916)
		(width 0.089408)
		(layer "In4.Cu")
		(net "FM_PS_EN")
	)
	(segment
		(start 394.575284 -72.323198)
		(end 393.781534 -71.529448)
		(width 0.089408)
		(layer "In4.Cu")
		(net "FM_PS_EN")
	)
	(segment
		(start 395.49578 -72.323198)
		(end 394.575284 -72.323198)
		(width 0.089408)
		(layer "In4.Cu")
		(net "FM_PS_EN")
	)
	(segment
		(start 386.35051 -71.529448)
		(end 385.517898 -70.696836)
		(width 0.089408)
		(layer "In4.Cu")
		(net "FM_PS_EN")
	)
	(segment
		(start 380.42469 -71.009002)
		(end 379.81763 -71.009002)
		(width 0.089408)
		(layer "In4.Cu")
		(net "FM_PS_EN")
	)
	(segment
		(start 393.781534 -71.529448)
		(end 386.35051 -71.529448)
		(width 0.089408)
		(layer "In4.Cu")
		(net "FM_PS_EN")
	)
	(segment
		(start 379.530356 -70.721728)
		(end 376.56262 -70.721728)
		(width 0.089408)
		(layer "In4.Cu")
		(net "FM_PS_EN")
	)
	(segment
		(start 374.720612 -72.047354)
		(end 374.499378 -72.268588)
		(width 0.089408)
		(layer "In4.Cu")
		(net "FM_PS_EN")
	)
	(segment
		(start 380.731776 -70.701916)
		(end 380.42469 -71.009002)
		(width 0.089408)
		(layer "In4.Cu")
		(net "FM_PS_EN")
	)
	(segment
		(start 374.720612 -71.791322)
		(end 374.720612 -72.047354)
		(width 0.089408)
		(layer "In4.Cu")
		(net "FM_PS_EN")
	)
	(segment
		(start 411.200092 -70.418706)
		(end 409.14574 -70.418706)
		(width 0.089408)
		(layer "In4.Cu")
		(net "FM_PS_EN")
	)
	(segment
		(start 396.03807 -71.874888)
		(end 395.94409 -71.874888)
		(width 0.089408)
		(layer "In4.Cu")
		(net "FM_PS_EN")
	)
	(segment
		(start 412.991554 -86.409022)
		(end 412.904178 -86.409022)
		(width 0.10795)
		(layer "F.Cu")
		(net "FM_CTNR_PS_ON_R")
	)
	(segment
		(start 412.8516 -90.3224)
		(end 412.623 -90.0938)
		(width 0.10795)
		(layer "F.Cu")
		(net "FM_CTNR_PS_ON_R")
	)
	(segment
		(start 412.904178 -86.409022)
		(end 411.9118 -87.4014)
		(width 0.10795)
		(layer "F.Cu")
		(net "FM_CTNR_PS_ON_R")
	)
	(segment
		(start 411.9118 -89.8779)
		(end 412.1277 -90.0938)
		(width 0.10795)
		(layer "F.Cu")
		(net "FM_CTNR_PS_ON_R")
	)
	(segment
		(start 412.88589 -91.90609)
		(end 412.8516 -91.8718)
		(width 0.10795)
		(layer "F.Cu")
		(net "FM_CTNR_PS_ON_R")
	)
	(segment
		(start 412.8516 -91.8718)
		(end 412.8516 -90.3224)
		(width 0.10795)
		(layer "F.Cu")
		(net "FM_CTNR_PS_ON_R")
	)
	(segment
		(start 411.9118 -87.4014)
		(end 411.9118 -89.8779)
		(width 0.10795)
		(layer "F.Cu")
		(net "FM_CTNR_PS_ON_R")
	)
	(segment
		(start 412.623 -90.0938)
		(end 412.1277 -90.0938)
		(width 0.10795)
		(layer "F.Cu")
		(net "FM_CTNR_PS_ON_R")
	)
	(via
		(at 412.88589 -91.90609)
		(size 0.762)
		(drill 0.381)
		(layers "F.Cu" "B.Cu")
		(net "FM_CTNR_PS_ON_R")
	)
	(via
		(at 401.2438 -52.3748)
		(size 0.6604)
		(drill 0.3302)
		(layers "F.Cu" "B.Cu")
		(net "PU_SPI1_RST")
	)
	(segment
		(start 399.891758 -53.36286)
		(end 400.31416 -53.36286)
		(width 0.10795)
		(layer "B.Cu")
		(net "PU_SPI1_RST")
	)
	(segment
		(start 398.093946 -53.57368)
		(end 399.680938 -53.57368)
		(width 0.10795)
		(layer "B.Cu")
		(net "PU_SPI1_RST")
	)
	(segment
		(start 399.680938 -53.57368)
		(end 399.891758 -53.36286)
		(width 0.10795)
		(layer "B.Cu")
		(net "PU_SPI1_RST")
	)
	(segment
		(start 401.2438 -52.3748)
		(end 401.2438 -52.43322)
		(width 0.10795)
		(layer "B.Cu")
		(net "PU_SPI1_RST")
	)
	(segment
		(start 401.2438 -52.43322)
		(end 400.31416 -53.36286)
		(width 0.10795)
		(layer "B.Cu")
		(net "PU_SPI1_RST")
	)
	(segment
		(start 234.466638 -51.62804)
		(end 233.895138 -51.62804)
		(width 0.10795)
		(layer "F.Cu")
		(net "TP_CPU0_RSVD_280")
	)
	(via
		(at 233.895138 -51.62804)
		(size 0.508)
		(drill 0.254)
		(layers "F.Cu" "B.Cu")
		(net "TP_CPU0_RSVD_280")
	)
	(via
		(at 231.3686 -51.62804)
		(size 0.6604)
		(drill 0.3302)
		(layers "F.Cu" "B.Cu")
		(net "TP_CPU0_RSVD_280")
	)
	(segment
		(start 231.3686 -51.62804)
		(end 233.895138 -51.62804)
		(width 0.10795)
		(layer "B.Cu")
		(net "TP_CPU0_RSVD_280")
	)
	(segment
		(start 378.812044 -36.34232)
		(end 376.639328 -36.34232)
		(width 0.10795)
		(layer "F.Cu")
		(net "PU_SPI_BMC_BT_WP_N")
	)
	(segment
		(start 379.4125 -36.5506)
		(end 379.020324 -36.5506)
		(width 0.10795)
		(layer "F.Cu")
		(net "PU_SPI_BMC_BT_WP_N")
	)
	(segment
		(start 380.74219 -36.33851)
		(end 380.22403 -36.33851)
		(width 0.10795)
		(layer "F.Cu")
		(net "PU_SPI_BMC_BT_WP_N")
	)
	(segment
		(start 380.01194 -36.5506)
		(end 379.4125 -36.5506)
		(width 0.10795)
		(layer "F.Cu")
		(net "PU_SPI_BMC_BT_WP_N")
	)
	(segment
		(start 379.020324 -36.5506)
		(end 378.812044 -36.34232)
		(width 0.10795)
		(layer "F.Cu")
		(net "PU_SPI_BMC_BT_WP_N")
	)
	(segment
		(start 380.22403 -36.33851)
		(end 380.01194 -36.5506)
		(width 0.10795)
		(layer "F.Cu")
		(net "PU_SPI_BMC_BT_WP_N")
	)
	(segment
		(start 368.219228 -44.877736)
		(end 368.219228 -44.501562)
		(width 0.10795)
		(layer "F.Cu")
		(net "PU_SPI_BMC_BT_HOLD_N")
	)
	(segment
		(start 368.219228 -44.501562)
		(end 368.652044 -44.068746)
		(width 0.10795)
		(layer "F.Cu")
		(net "PU_SPI_BMC_BT_HOLD_N")
	)
	(segment
		(start 367.088928 -45.23232)
		(end 367.864644 -45.23232)
		(width 0.10795)
		(layer "F.Cu")
		(net "PU_SPI_BMC_BT_HOLD_N")
	)
	(segment
		(start 367.864644 -45.23232)
		(end 368.219228 -44.877736)
		(width 0.10795)
		(layer "F.Cu")
		(net "PU_SPI_BMC_BT_HOLD_N")
	)
	(via
		(at 368.652044 -44.068746)
		(size 0.508)
		(drill 0.254)
		(layers "F.Cu" "B.Cu")
		(net "PU_SPI_BMC_BT_HOLD_N")
	)
	(segment
		(start 368.652044 -44.068746)
		(end 368.627406 -44.068746)
		(width 0.10795)
		(layer "B.Cu")
		(net "PU_SPI_BMC_BT_HOLD_N")
	)
	(segment
		(start 368.627406 -44.044108)
		(end 367.157 -42.573702)
		(width 0.10795)
		(layer "B.Cu")
		(net "PU_SPI_BMC_BT_HOLD_N")
	)
	(segment
		(start 367.157 -42.573702)
		(end 367.157 -41.4782)
		(width 0.10795)
		(layer "B.Cu")
		(net "PU_SPI_BMC_BT_HOLD_N")
	)
	(segment
		(start 368.627406 -44.068746)
		(end 368.627406 -44.044108)
		(width 0.10795)
		(layer "B.Cu")
		(net "PU_SPI_BMC_BT_HOLD_N")
	)
	(segment
		(start 240.476278 -68.963286)
		(end 239.904778 -68.963286)
		(width 0.10795)
		(layer "F.Cu")
		(net "TP_CPU0_RSVD_179")
	)
	(via
		(at 239.904778 -68.963286)
		(size 0.508)
		(drill 0.254)
		(layers "F.Cu" "B.Cu")
		(net "TP_CPU0_RSVD_179")
	)
	(segment
		(start 484.882444 -29.973016)
		(end 484.229156 -29.973016)
		(width 0.10795)
		(layer "F.Cu")
		(net "CLK_25M_BMC")
	)
	(segment
		(start 428.763684 -44.309538)
		(end 429.220122 -44.765976)
		(width 0.10795)
		(layer "F.Cu")
		(net "CLK_25M_BMC")
	)
	(segment
		(start 483.90048 -30.29712)
		(end 484.16972 -30.56636)
		(width 0.10795)
		(layer "F.Cu")
		(net "CLK_25M_BMC")
	)
	(segment
		(start 483.56266 -30.29712)
		(end 483.90048 -30.29712)
		(width 0.10795)
		(layer "F.Cu")
		(net "CLK_25M_BMC")
	)
	(segment
		(start 485.04348 -29.81198)
		(end 484.882444 -29.973016)
		(width 0.10795)
		(layer "F.Cu")
		(net "CLK_25M_BMC")
	)
	(segment
		(start 429.220122 -44.765976)
		(end 429.220122 -45.054774)
		(width 0.10795)
		(layer "F.Cu")
		(net "CLK_25M_BMC")
	)
	(segment
		(start 485.04348 -30.226)
		(end 485.04348 -29.81198)
		(width 0.10795)
		(layer "F.Cu")
		(net "CLK_25M_BMC")
	)
	(segment
		(start 484.16972 -30.56636)
		(end 484.70312 -30.56636)
		(width 0.10795)
		(layer "F.Cu")
		(net "CLK_25M_BMC")
	)
	(segment
		(start 484.70312 -30.56636)
		(end 485.04348 -30.226)
		(width 0.10795)
		(layer "F.Cu")
		(net "CLK_25M_BMC")
	)
	(via
		(at 428.763684 -44.309538)
		(size 0.508)
		(drill 0.254)
		(layers "F.Cu" "B.Cu")
		(net "CLK_25M_BMC")
	)
	(via
		(at 484.229156 -29.973016)
		(size 0.508)
		(drill 0.254)
		(layers "F.Cu" "B.Cu")
		(net "CLK_25M_BMC")
	)
	(via
		(at 485.04348 -29.81198)
		(size 0.762)
		(drill 0.381)
		(layers "F.Cu" "B.Cu")
		(net "CLK_25M_BMC")
	)
	(via
		(at 451.314312 -39.423594)
		(size 0.508)
		(drill 0.254)
		(layers "F.Cu" "B.Cu")
		(net "CLK_25M_BMC")
	)
	(via
		(at 483.36708 -57.347104)
		(size 0.508)
		(drill 0.254)
		(layers "F.Cu" "B.Cu")
		(net "CLK_25M_BMC")
	)
	(segment
		(start 482.519482 -30.74035)
		(end 483.286816 -29.973016)
		(width 0.089408)
		(layer "In9.Cu")
		(net "CLK_25M_BMC")
	)
	(segment
		(start 482.999796 -55.552086)
		(end 482.999796 -49.844452)
		(width 0.089408)
		(layer "In9.Cu")
		(net "CLK_25M_BMC")
	)
	(segment
		(start 483.286816 -29.973016)
		(end 484.229156 -29.973016)
		(width 0.089408)
		(layer "In9.Cu")
		(net "CLK_25M_BMC")
	)
	(segment
		(start 482.519482 -34.6456)
		(end 482.519482 -30.74035)
		(width 0.089408)
		(layer "In9.Cu")
		(net "CLK_25M_BMC")
	)
	(segment
		(start 436.081932 -42.00652)
		(end 449.507864 -42.00652)
		(width 0.089408)
		(layer "In9.Cu")
		(net "CLK_25M_BMC")
	)
	(segment
		(start 480.75596 -45.575982)
		(end 480.75596 -42.072052)
		(width 0.089408)
		(layer "In9.Cu")
		(net "CLK_25M_BMC")
	)
	(segment
		(start 451.314312 -40.200072)
		(end 451.314312 -39.423594)
		(width 0.089408)
		(layer "In9.Cu")
		(net "CLK_25M_BMC")
	)
	(segment
		(start 449.507864 -42.00652)
		(end 451.314312 -40.200072)
		(width 0.089408)
		(layer "In9.Cu")
		(net "CLK_25M_BMC")
	)
	(segment
		(start 481.838 -35.327082)
		(end 482.519482 -34.6456)
		(width 0.089408)
		(layer "In9.Cu")
		(net "CLK_25M_BMC")
	)
	(segment
		(start 433.175918 -43.096688)
		(end 434.991764 -43.096688)
		(width 0.089408)
		(layer "In9.Cu")
		(net "CLK_25M_BMC")
	)
	(segment
		(start 432.46802 -43.804586)
		(end 433.175918 -43.096688)
		(width 0.089408)
		(layer "In9.Cu")
		(net "CLK_25M_BMC")
	)
	(segment
		(start 428.763684 -44.309538)
		(end 429.268636 -43.804586)
		(width 0.089408)
		(layer "In9.Cu")
		(net "CLK_25M_BMC")
	)
	(segment
		(start 482.999796 -49.844452)
		(end 483.330504 -49.513744)
		(width 0.089408)
		(layer "In9.Cu")
		(net "CLK_25M_BMC")
	)
	(segment
		(start 483.330504 -49.513744)
		(end 483.330504 -48.150526)
		(width 0.089408)
		(layer "In9.Cu")
		(net "CLK_25M_BMC")
	)
	(segment
		(start 429.268636 -43.804586)
		(end 432.46802 -43.804586)
		(width 0.089408)
		(layer "In9.Cu")
		(net "CLK_25M_BMC")
	)
	(segment
		(start 481.838 -36.6776)
		(end 481.838 -35.327082)
		(width 0.089408)
		(layer "In9.Cu")
		(net "CLK_25M_BMC")
	)
	(segment
		(start 483.36708 -57.347104)
		(end 483.441756 -57.347104)
		(width 0.089408)
		(layer "In9.Cu")
		(net "CLK_25M_BMC")
	)
	(segment
		(start 483.73919 -56.29148)
		(end 482.999796 -55.552086)
		(width 0.089408)
		(layer "In9.Cu")
		(net "CLK_25M_BMC")
	)
	(segment
		(start 482.273356 -40.554656)
		(end 482.273356 -37.112956)
		(width 0.089408)
		(layer "In9.Cu")
		(net "CLK_25M_BMC")
	)
	(segment
		(start 480.75596 -42.072052)
		(end 482.273356 -40.554656)
		(width 0.089408)
		(layer "In9.Cu")
		(net "CLK_25M_BMC")
	)
	(segment
		(start 483.441756 -57.347104)
		(end 483.73919 -57.04967)
		(width 0.089408)
		(layer "In9.Cu")
		(net "CLK_25M_BMC")
	)
	(segment
		(start 483.330504 -48.150526)
		(end 480.75596 -45.575982)
		(width 0.089408)
		(layer "In9.Cu")
		(net "CLK_25M_BMC")
	)
	(segment
		(start 482.273356 -37.112956)
		(end 481.838 -36.6776)
		(width 0.089408)
		(layer "In9.Cu")
		(net "CLK_25M_BMC")
	)
	(segment
		(start 434.991764 -43.096688)
		(end 436.081932 -42.00652)
		(width 0.089408)
		(layer "In9.Cu")
		(net "CLK_25M_BMC")
	)
	(segment
		(start 483.73919 -57.04967)
		(end 483.73919 -56.29148)
		(width 0.089408)
		(layer "In9.Cu")
		(net "CLK_25M_BMC")
	)
	(segment
		(start 465.695284 -46.721014)
		(end 470.385648 -46.721014)
		(width 0.089408)
		(layer "In11.Cu")
		(net "CLK_25M_BMC")
	)
	(segment
		(start 477.991678 -56.17718)
		(end 478.053146 -56.17718)
		(width 0.089408)
		(layer "In11.Cu")
		(net "CLK_25M_BMC")
	)
	(segment
		(start 482.802438 -56.782462)
		(end 483.36708 -57.347104)
		(width 0.089408)
		(layer "In11.Cu")
		(net "CLK_25M_BMC")
	)
	(segment
		(start 460.728568 -41.178226)
		(end 460.728568 -41.50614)
		(width 0.089408)
		(layer "In11.Cu")
		(net "CLK_25M_BMC")
	)
	(segment
		(start 481.325428 -56.782462)
		(end 482.802438 -56.782462)
		(width 0.089408)
		(layer "In11.Cu")
		(net "CLK_25M_BMC")
	)
	(segment
		(start 459.634336 -40.083994)
		(end 460.728568 -41.178226)
		(width 0.089408)
		(layer "In11.Cu")
		(net "CLK_25M_BMC")
	)
	(segment
		(start 474.285818 -53.020722)
		(end 474.605096 -53.34)
		(width 0.089408)
		(layer "In11.Cu")
		(net "CLK_25M_BMC")
	)
	(segment
		(start 464.790536 -44.465494)
		(end 464.790536 -45.816266)
		(width 0.089408)
		(layer "In11.Cu")
		(net "CLK_25M_BMC")
	)
	(segment
		(start 451.974712 -40.083994)
		(end 459.634336 -40.083994)
		(width 0.089408)
		(layer "In11.Cu")
		(net "CLK_25M_BMC")
	)
	(segment
		(start 464.790536 -45.816266)
		(end 465.695284 -46.721014)
		(width 0.089408)
		(layer "In11.Cu")
		(net "CLK_25M_BMC")
	)
	(segment
		(start 470.970356 -47.305722)
		(end 471.035888 -47.305722)
		(width 0.089408)
		(layer "In11.Cu")
		(net "CLK_25M_BMC")
	)
	(segment
		(start 478.053146 -56.17718)
		(end 478.069402 -56.193436)
		(width 0.089408)
		(layer "In11.Cu")
		(net "CLK_25M_BMC")
	)
	(segment
		(start 462.546192 -42.22115)
		(end 464.790536 -44.465494)
		(width 0.089408)
		(layer "In11.Cu")
		(net "CLK_25M_BMC")
	)
	(segment
		(start 475.65691 -53.34)
		(end 476.468948 -54.152038)
		(width 0.089408)
		(layer "In11.Cu")
		(net "CLK_25M_BMC")
	)
	(segment
		(start 476.468948 -54.193694)
		(end 477.354138 -55.078884)
		(width 0.089408)
		(layer "In11.Cu")
		(net "CLK_25M_BMC")
	)
	(segment
		(start 461.443578 -42.22115)
		(end 462.546192 -42.22115)
		(width 0.089408)
		(layer "In11.Cu")
		(net "CLK_25M_BMC")
	)
	(segment
		(start 477.354138 -55.078884)
		(end 477.354138 -55.53964)
		(width 0.089408)
		(layer "In11.Cu")
		(net "CLK_25M_BMC")
	)
	(segment
		(start 474.605096 -53.34)
		(end 475.65691 -53.34)
		(width 0.089408)
		(layer "In11.Cu")
		(net "CLK_25M_BMC")
	)
	(segment
		(start 478.069402 -56.193436)
		(end 480.736402 -56.193436)
		(width 0.089408)
		(layer "In11.Cu")
		(net "CLK_25M_BMC")
	)
	(segment
		(start 476.468948 -54.152038)
		(end 476.468948 -54.193694)
		(width 0.089408)
		(layer "In11.Cu")
		(net "CLK_25M_BMC")
	)
	(segment
		(start 460.728568 -41.50614)
		(end 461.443578 -42.22115)
		(width 0.089408)
		(layer "In11.Cu")
		(net "CLK_25M_BMC")
	)
	(segment
		(start 474.285818 -50.555652)
		(end 474.285818 -53.020722)
		(width 0.089408)
		(layer "In11.Cu")
		(net "CLK_25M_BMC")
	)
	(segment
		(start 471.035888 -47.305722)
		(end 474.285818 -50.555652)
		(width 0.089408)
		(layer "In11.Cu")
		(net "CLK_25M_BMC")
	)
	(segment
		(start 451.314312 -39.423594)
		(end 451.974712 -40.083994)
		(width 0.089408)
		(layer "In11.Cu")
		(net "CLK_25M_BMC")
	)
	(segment
		(start 470.385648 -46.721014)
		(end 470.970356 -47.305722)
		(width 0.089408)
		(layer "In11.Cu")
		(net "CLK_25M_BMC")
	)
	(segment
		(start 477.354138 -55.53964)
		(end 477.991678 -56.17718)
		(width 0.089408)
		(layer "In11.Cu")
		(net "CLK_25M_BMC")
	)
	(segment
		(start 480.736402 -56.193436)
		(end 481.325428 -56.782462)
		(width 0.089408)
		(layer "In11.Cu")
		(net "CLK_25M_BMC")
	)
	(segment
		(start 412.085282 -125.863604)
		(end 411.339792 -125.863604)
		(width 0.127)
		(layer "F.Cu")
		(net "VSENSE_P1V05_PCH_STBY_AVSP")
	)
	(segment
		(start 411.841442 -126.648718)
		(end 411.327092 -126.134368)
		(width 0.127)
		(layer "F.Cu")
		(net "VSENSE_P1V05_PCH_STBY_AVSP")
	)
	(segment
		(start 411.932882 -126.648718)
		(end 411.841442 -126.648718)
		(width 0.127)
		(layer "F.Cu")
		(net "VSENSE_P1V05_PCH_STBY_AVSP")
	)
	(segment
		(start 411.327092 -126.134368)
		(end 411.327092 -125.850904)
		(width 0.127)
		(layer "F.Cu")
		(net "VSENSE_P1V05_PCH_STBY_AVSP")
	)
	(segment
		(start 411.339792 -125.863604)
		(end 411.327092 -125.850904)
		(width 0.127)
		(layer "F.Cu")
		(net "VSENSE_P1V05_PCH_STBY_AVSP")
	)
	(via
		(at 411.48762 -133.366764)
		(size 0.508)
		(drill 0.254)
		(layers "F.Cu" "B.Cu")
		(net "VSENSE_P1V05_PCH_STBY_AVSP")
	)
	(via
		(at 413.385 -127.508)
		(size 0.6604)
		(drill 0.3302)
		(layers "F.Cu" "B.Cu")
		(net "VSENSE_P1V05_PCH_STBY_AVSP")
	)
	(via
		(at 411.932882 -126.648718)
		(size 0.508)
		(drill 0.254)
		(layers "F.Cu" "B.Cu")
		(net "VSENSE_P1V05_PCH_STBY_AVSP")
	)
	(via
		(at 401.75942 -136.44118)
		(size 0.508)
		(drill 0.254)
		(layers "F.Cu" "B.Cu")
		(net "VSENSE_P1V05_PCH_STBY_AVSP")
	)
	(via
		(at 392.1887 -156.285184)
		(size 0.508)
		(drill 0.254)
		(layers "F.Cu" "B.Cu")
		(net "VSENSE_P1V05_PCH_STBY_AVSP")
	)
	(segment
		(start 413.385 -129.032)
		(end 413.792924 -129.439924)
		(width 0.127)
		(layer "B.Cu")
		(net "VSENSE_P1V05_PCH_STBY_AVSP")
	)
	(segment
		(start 412.621222 -126.648718)
		(end 413.385 -127.412496)
		(width 0.127)
		(layer "B.Cu")
		(net "VSENSE_P1V05_PCH_STBY_AVSP")
	)
	(segment
		(start 411.988 -132.387848)
		(end 411.988 -132.866384)
		(width 0.127)
		(layer "B.Cu")
		(net "VSENSE_P1V05_PCH_STBY_AVSP")
	)
	(segment
		(start 392.1887 -156.285184)
		(end 392.939016 -156.285184)
		(width 0.127)
		(layer "B.Cu")
		(net "VSENSE_P1V05_PCH_STBY_AVSP")
	)
	(segment
		(start 413.385 -127.412496)
		(end 413.385 -127.508)
		(width 0.127)
		(layer "B.Cu")
		(net "VSENSE_P1V05_PCH_STBY_AVSP")
	)
	(segment
		(start 411.988 -132.866384)
		(end 411.48762 -133.366764)
		(width 0.127)
		(layer "B.Cu")
		(net "VSENSE_P1V05_PCH_STBY_AVSP")
	)
	(segment
		(start 413.385 -127.508)
		(end 413.385 -129.032)
		(width 0.127)
		(layer "B.Cu")
		(net "VSENSE_P1V05_PCH_STBY_AVSP")
	)
	(segment
		(start 411.932882 -126.648718)
		(end 412.621222 -126.648718)
		(width 0.127)
		(layer "B.Cu")
		(net "VSENSE_P1V05_PCH_STBY_AVSP")
	)
	(segment
		(start 413.792924 -129.439924)
		(end 413.792924 -130.582924)
		(width 0.127)
		(layer "B.Cu")
		(net "VSENSE_P1V05_PCH_STBY_AVSP")
	)
	(segment
		(start 413.792924 -130.582924)
		(end 411.988 -132.387848)
		(width 0.127)
		(layer "B.Cu")
		(net "VSENSE_P1V05_PCH_STBY_AVSP")
	)
	(segment
		(start 392.939016 -156.285184)
		(end 393.1412 -156.083)
		(width 0.127)
		(layer "B.Cu")
		(net "VSENSE_P1V05_PCH_STBY_AVSP")
	)
	(segment
		(start 408.986482 -134.294118)
		(end 407.3398 -135.9408)
		(width 0.127)
		(layer "In4.Cu")
		(net "VSENSE_P1V05_PCH_STBY_AVSP")
	)
	(segment
		(start 411.48762 -133.366764)
		(end 411.691328 -133.366764)
		(width 0.127)
		(layer "In4.Cu")
		(net "VSENSE_P1V05_PCH_STBY_AVSP")
	)
	(segment
		(start 411.691328 -133.366764)
		(end 411.810454 -133.48589)
		(width 0.127)
		(layer "In4.Cu")
		(net "VSENSE_P1V05_PCH_STBY_AVSP")
	)
	(segment
		(start 411.810454 -133.48589)
		(end 411.810454 -133.91007)
		(width 0.127)
		(layer "In4.Cu")
		(net "VSENSE_P1V05_PCH_STBY_AVSP")
	)
	(segment
		(start 411.426406 -134.294118)
		(end 408.986482 -134.294118)
		(width 0.127)
		(layer "In4.Cu")
		(net "VSENSE_P1V05_PCH_STBY_AVSP")
	)
	(segment
		(start 411.810454 -133.91007)
		(end 411.426406 -134.294118)
		(width 0.127)
		(layer "In4.Cu")
		(net "VSENSE_P1V05_PCH_STBY_AVSP")
	)
	(segment
		(start 402.2598 -135.9408)
		(end 401.75942 -136.44118)
		(width 0.127)
		(layer "In4.Cu")
		(net "VSENSE_P1V05_PCH_STBY_AVSP")
	)
	(segment
		(start 407.3398 -135.9408)
		(end 402.2598 -135.9408)
		(width 0.127)
		(layer "In4.Cu")
		(net "VSENSE_P1V05_PCH_STBY_AVSP")
	)
	(segment
		(start 395.431518 -155.0416)
		(end 396.035784 -154.437334)
		(width 0.127)
		(layer "In9.Cu")
		(net "VSENSE_P1V05_PCH_STBY_AVSP")
	)
	(segment
		(start 396.035784 -154.437334)
		(end 397.47317 -154.437334)
		(width 0.127)
		(layer "In9.Cu")
		(net "VSENSE_P1V05_PCH_STBY_AVSP")
	)
	(segment
		(start 392.216894 -156.285184)
		(end 392.216894 -156.0957)
		(width 0.127)
		(layer "In9.Cu")
		(net "VSENSE_P1V05_PCH_STBY_AVSP")
	)
	(segment
		(start 399.455132 -151.736044)
		(end 400.159728 -151.031448)
		(width 0.127)
		(layer "In9.Cu")
		(net "VSENSE_P1V05_PCH_STBY_AVSP")
	)
	(segment
		(start 393.270994 -155.0416)
		(end 395.431518 -155.0416)
		(width 0.127)
		(layer "In9.Cu")
		(net "VSENSE_P1V05_PCH_STBY_AVSP")
	)
	(segment
		(start 401.75942 -137.308336)
		(end 401.75942 -136.44118)
		(width 0.127)
		(layer "In9.Cu")
		(net "VSENSE_P1V05_PCH_STBY_AVSP")
	)
	(segment
		(start 398.028668 -152.372568)
		(end 398.665192 -151.736044)
		(width 0.127)
		(layer "In9.Cu")
		(net "VSENSE_P1V05_PCH_STBY_AVSP")
	)
	(segment
		(start 398.665192 -151.736044)
		(end 399.455132 -151.736044)
		(width 0.127)
		(layer "In9.Cu")
		(net "VSENSE_P1V05_PCH_STBY_AVSP")
	)
	(segment
		(start 392.216894 -156.0957)
		(end 393.270994 -155.0416)
		(width 0.127)
		(layer "In9.Cu")
		(net "VSENSE_P1V05_PCH_STBY_AVSP")
	)
	(segment
		(start 398.028668 -153.881836)
		(end 398.028668 -152.372568)
		(width 0.127)
		(layer "In9.Cu")
		(net "VSENSE_P1V05_PCH_STBY_AVSP")
	)
	(segment
		(start 400.159728 -151.031448)
		(end 400.159728 -138.908028)
		(width 0.127)
		(layer "In9.Cu")
		(net "VSENSE_P1V05_PCH_STBY_AVSP")
	)
	(segment
		(start 400.159728 -138.908028)
		(end 401.75942 -137.308336)
		(width 0.127)
		(layer "In9.Cu")
		(net "VSENSE_P1V05_PCH_STBY_AVSP")
	)
	(segment
		(start 392.1887 -156.285184)
		(end 392.216894 -156.285184)
		(width 0.127)
		(layer "In9.Cu")
		(net "VSENSE_P1V05_PCH_STBY_AVSP")
	)
	(segment
		(start 397.47317 -154.437334)
		(end 398.028668 -153.881836)
		(width 0.127)
		(layer "In9.Cu")
		(net "VSENSE_P1V05_PCH_STBY_AVSP")
	)
	(segment
		(start 411.587442 -125.088904)
		(end 411.327092 -125.088904)
		(width 0.127)
		(layer "F.Cu")
		(net "VSENSE_P1V05_PCH_STBY_AVSN")
	)
	(segment
		(start 393.982702 -156.2481)
		(end 393.57808 -156.2481)
		(width 0.127)
		(layer "F.Cu")
		(net "VSENSE_P1V05_PCH_STBY_AVSN")
	)
	(segment
		(start 411.701742 -124.974604)
		(end 411.587442 -125.088904)
		(width 0.127)
		(layer "F.Cu")
		(net "VSENSE_P1V05_PCH_STBY_AVSN")
	)
	(segment
		(start 392.710416 -157.001464)
		(end 392.710416 -157.00883)
		(width 0.127)
		(layer "F.Cu")
		(net "VSENSE_P1V05_PCH_STBY_AVSN")
	)
	(segment
		(start 393.57808 -156.2481)
		(end 392.824716 -157.001464)
		(width 0.127)
		(layer "F.Cu")
		(net "VSENSE_P1V05_PCH_STBY_AVSN")
	)
	(segment
		(start 412.085282 -124.974604)
		(end 411.701742 -124.974604)
		(width 0.127)
		(layer "F.Cu")
		(net "VSENSE_P1V05_PCH_STBY_AVSN")
	)
	(segment
		(start 392.824716 -157.001464)
		(end 392.710416 -157.001464)
		(width 0.127)
		(layer "F.Cu")
		(net "VSENSE_P1V05_PCH_STBY_AVSN")
	)
	(segment
		(start 412.87319 -125.523752)
		(end 412.324042 -124.974604)
		(width 0.127)
		(layer "F.Cu")
		(net "VSENSE_P1V05_PCH_STBY_AVSN")
	)
	(segment
		(start 412.324042 -124.974604)
		(end 412.085282 -124.974604)
		(width 0.127)
		(layer "F.Cu")
		(net "VSENSE_P1V05_PCH_STBY_AVSN")
	)
	(segment
		(start 392.710416 -157.00883)
		(end 392.70305 -157.00883)
		(width 0.127)
		(layer "F.Cu")
		(net "VSENSE_P1V05_PCH_STBY_AVSN")
	)
	(via
		(at 412.87319 -125.523752)
		(size 0.508)
		(drill 0.254)
		(layers "F.Cu" "B.Cu")
		(net "VSENSE_P1V05_PCH_STBY_AVSN")
	)
	(via
		(at 412.381954 -133.35381)
		(size 0.508)
		(drill 0.254)
		(layers "F.Cu" "B.Cu")
		(net "VSENSE_P1V05_PCH_STBY_AVSN")
	)
	(via
		(at 414.721548 -127.751078)
		(size 0.6604)
		(drill 0.3302)
		(layers "F.Cu" "B.Cu")
		(net "VSENSE_P1V05_PCH_STBY_AVSN")
	)
	(via
		(at 392.70305 -157.00883)
		(size 0.508)
		(drill 0.254)
		(layers "F.Cu" "B.Cu")
		(net "VSENSE_P1V05_PCH_STBY_AVSN")
	)
	(via
		(at 402.62937 -136.797796)
		(size 0.508)
		(drill 0.254)
		(layers "F.Cu" "B.Cu")
		(net "VSENSE_P1V05_PCH_STBY_AVSN")
	)
	(segment
		(start 393.46505 -157.226)
		(end 392.92022 -157.226)
		(width 0.127)
		(layer "B.Cu")
		(net "VSENSE_P1V05_PCH_STBY_AVSN")
	)
	(segment
		(start 412.87319 -125.523752)
		(end 412.87319 -125.807216)
		(width 0.127)
		(layer "B.Cu")
		(net "VSENSE_P1V05_PCH_STBY_AVSN")
	)
	(segment
		(start 414.721548 -127.655574)
		(end 414.721548 -127.751078)
		(width 0.127)
		(layer "B.Cu")
		(net "VSENSE_P1V05_PCH_STBY_AVSN")
	)
	(segment
		(start 412.381954 -132.353304)
		(end 412.381954 -133.35381)
		(width 0.127)
		(layer "B.Cu")
		(net "VSENSE_P1V05_PCH_STBY_AVSN")
	)
	(segment
		(start 414.537906 -127.93472)
		(end 414.537906 -129.3622)
		(width 0.127)
		(layer "B.Cu")
		(net "VSENSE_P1V05_PCH_STBY_AVSN")
	)
	(segment
		(start 414.0962 -129.803906)
		(end 414.0962 -130.639058)
		(width 0.127)
		(layer "B.Cu")
		(net "VSENSE_P1V05_PCH_STBY_AVSN")
	)
	(segment
		(start 414.537906 -129.3622)
		(end 414.0962 -129.803906)
		(width 0.127)
		(layer "B.Cu")
		(net "VSENSE_P1V05_PCH_STBY_AVSN")
	)
	(segment
		(start 414.721548 -127.751078)
		(end 414.537906 -127.93472)
		(width 0.127)
		(layer "B.Cu")
		(net "VSENSE_P1V05_PCH_STBY_AVSN")
	)
	(segment
		(start 414.0962 -130.639058)
		(end 412.381954 -132.353304)
		(width 0.127)
		(layer "B.Cu")
		(net "VSENSE_P1V05_PCH_STBY_AVSN")
	)
	(segment
		(start 412.87319 -125.807216)
		(end 414.721548 -127.655574)
		(width 0.127)
		(layer "B.Cu")
		(net "VSENSE_P1V05_PCH_STBY_AVSN")
	)
	(segment
		(start 392.92022 -157.226)
		(end 392.70305 -157.00883)
		(width 0.127)
		(layer "B.Cu")
		(net "VSENSE_P1V05_PCH_STBY_AVSN")
	)
	(segment
		(start 407.444956 -136.195054)
		(end 407.234644 -136.195054)
		(width 0.127)
		(layer "In4.Cu")
		(net "VSENSE_P1V05_PCH_STBY_AVSN")
	)
	(segment
		(start 409.091892 -134.548118)
		(end 407.444956 -136.195054)
		(width 0.127)
		(layer "In4.Cu")
		(net "VSENSE_P1V05_PCH_STBY_AVSN")
	)
	(segment
		(start 412.069026 -133.51637)
		(end 412.069026 -134.010908)
		(width 0.127)
		(layer "In4.Cu")
		(net "VSENSE_P1V05_PCH_STBY_AVSN")
	)
	(segment
		(start 411.531816 -134.548118)
		(end 409.091892 -134.548118)
		(width 0.127)
		(layer "In4.Cu")
		(net "VSENSE_P1V05_PCH_STBY_AVSN")
	)
	(segment
		(start 412.381954 -133.35381)
		(end 412.231586 -133.35381)
		(width 0.127)
		(layer "In4.Cu")
		(net "VSENSE_P1V05_PCH_STBY_AVSN")
	)
	(segment
		(start 407.234644 -136.195054)
		(end 407.23439 -136.1948)
		(width 0.127)
		(layer "In4.Cu")
		(net "VSENSE_P1V05_PCH_STBY_AVSN")
	)
	(segment
		(start 403.232366 -136.1948)
		(end 402.62937 -136.797796)
		(width 0.127)
		(layer "In4.Cu")
		(net "VSENSE_P1V05_PCH_STBY_AVSN")
	)
	(segment
		(start 407.23439 -136.1948)
		(end 403.232366 -136.1948)
		(width 0.127)
		(layer "In4.Cu")
		(net "VSENSE_P1V05_PCH_STBY_AVSN")
	)
	(segment
		(start 412.231586 -133.35381)
		(end 412.069026 -133.51637)
		(width 0.127)
		(layer "In4.Cu")
		(net "VSENSE_P1V05_PCH_STBY_AVSN")
	)
	(segment
		(start 412.069026 -134.010908)
		(end 411.531816 -134.548118)
		(width 0.127)
		(layer "In4.Cu")
		(net "VSENSE_P1V05_PCH_STBY_AVSN")
	)
	(segment
		(start 398.770602 -151.990044)
		(end 399.560542 -151.990044)
		(width 0.127)
		(layer "In9.Cu")
		(net "VSENSE_P1V05_PCH_STBY_AVSN")
	)
	(segment
		(start 392.710416 -157.00883)
		(end 392.710416 -157.001464)
		(width 0.127)
		(layer "In9.Cu")
		(net "VSENSE_P1V05_PCH_STBY_AVSN")
	)
	(segment
		(start 396.141194 -154.691334)
		(end 397.57858 -154.691334)
		(width 0.127)
		(layer "In9.Cu")
		(net "VSENSE_P1V05_PCH_STBY_AVSN")
	)
	(segment
		(start 398.282668 -152.477978)
		(end 398.770602 -151.990044)
		(width 0.127)
		(layer "In9.Cu")
		(net "VSENSE_P1V05_PCH_STBY_AVSN")
	)
	(segment
		(start 392.710416 -157.001464)
		(end 392.7602 -156.95168)
		(width 0.127)
		(layer "In9.Cu")
		(net "VSENSE_P1V05_PCH_STBY_AVSN")
	)
	(segment
		(start 400.413728 -139.013438)
		(end 402.62937 -136.797796)
		(width 0.127)
		(layer "In9.Cu")
		(net "VSENSE_P1V05_PCH_STBY_AVSN")
	)
	(segment
		(start 400.413728 -151.136858)
		(end 400.413728 -139.013438)
		(width 0.127)
		(layer "In9.Cu")
		(net "VSENSE_P1V05_PCH_STBY_AVSN")
	)
	(segment
		(start 397.57858 -154.691334)
		(end 398.282668 -153.987246)
		(width 0.127)
		(layer "In9.Cu")
		(net "VSENSE_P1V05_PCH_STBY_AVSN")
	)
	(segment
		(start 393.701778 -155.296362)
		(end 395.536166 -155.296362)
		(width 0.127)
		(layer "In9.Cu")
		(net "VSENSE_P1V05_PCH_STBY_AVSN")
	)
	(segment
		(start 392.70305 -157.00883)
		(end 392.710416 -157.00883)
		(width 0.127)
		(layer "In9.Cu")
		(net "VSENSE_P1V05_PCH_STBY_AVSN")
	)
	(segment
		(start 399.560542 -151.990044)
		(end 400.413728 -151.136858)
		(width 0.127)
		(layer "In9.Cu")
		(net "VSENSE_P1V05_PCH_STBY_AVSN")
	)
	(segment
		(start 392.7602 -156.23794)
		(end 393.701778 -155.296362)
		(width 0.127)
		(layer "In9.Cu")
		(net "VSENSE_P1V05_PCH_STBY_AVSN")
	)
	(segment
		(start 398.282668 -153.987246)
		(end 398.282668 -152.477978)
		(width 0.127)
		(layer "In9.Cu")
		(net "VSENSE_P1V05_PCH_STBY_AVSN")
	)
	(segment
		(start 395.536166 -155.296362)
		(end 396.141194 -154.691334)
		(width 0.127)
		(layer "In9.Cu")
		(net "VSENSE_P1V05_PCH_STBY_AVSN")
	)
	(segment
		(start 392.7602 -156.95168)
		(end 392.7602 -156.23794)
		(width 0.127)
		(layer "In9.Cu")
		(net "VSENSE_P1V05_PCH_STBY_AVSN")
	)
	(segment
		(start 392.330686 -153.154126)
		(end 392.060176 -153.424636)
		(width 0.1778)
		(layer "F.Cu")
		(net "VR_PVNN_PCH_VINSEN")
	)
	(segment
		(start 392.830558 -153.145998)
		(end 392.362182 -153.145998)
		(width 0.1778)
		(layer "F.Cu")
		(net "VR_PVNN_PCH_VINSEN")
	)
	(segment
		(start 391.467594 -152.76449)
		(end 391.511536 -152.720548)
		(width 0.254)
		(layer "F.Cu")
		(net "VR_PVNN_PCH_VINSEN")
	)
	(segment
		(start 391.55624 -152.675844)
		(end 391.55624 -152.008586)
		(width 0.254)
		(layer "F.Cu")
		(net "VR_PVNN_PCH_VINSEN")
	)
	(segment
		(start 392.009122 -153.47569)
		(end 391.467594 -153.47569)
		(width 0.254)
		(layer "F.Cu")
		(net "VR_PVNN_PCH_VINSEN")
	)
	(segment
		(start 392.881612 -153.197052)
		(end 392.830558 -153.145998)
		(width 0.1778)
		(layer "F.Cu")
		(net "VR_PVNN_PCH_VINSEN")
	)
	(segment
		(start 391.511536 -152.720548)
		(end 391.55624 -152.675844)
		(width 0.254)
		(layer "F.Cu")
		(net "VR_PVNN_PCH_VINSEN")
	)
	(segment
		(start 392.060176 -153.424636)
		(end 392.009122 -153.47569)
		(width 0.254)
		(layer "F.Cu")
		(net "VR_PVNN_PCH_VINSEN")
	)
	(segment
		(start 392.362182 -153.145998)
		(end 392.354054 -153.154126)
		(width 0.1778)
		(layer "F.Cu")
		(net "VR_PVNN_PCH_VINSEN")
	)
	(segment
		(start 392.354054 -153.154126)
		(end 392.330686 -153.154126)
		(width 0.1778)
		(layer "F.Cu")
		(net "VR_PVNN_PCH_VINSEN")
	)
	(segment
		(start 393.3317 -153.197052)
		(end 392.881612 -153.197052)
		(width 0.1778)
		(layer "F.Cu")
		(net "VR_PVNN_PCH_VINSEN")
	)
	(segment
		(start 391.467594 -153.47569)
		(end 391.467594 -152.76449)
		(width 0.254)
		(layer "F.Cu")
		(net "VR_PVNN_PCH_VINSEN")
	)
	(via
		(at 391.56894 -150.7998)
		(size 0.6604)
		(drill 0.3302)
		(layers "F.Cu" "B.Cu")
		(net "VR_PVNN_PCH_VINSEN")
	)
	(via
		(at 391.511536 -152.720548)
		(size 0.508)
		(drill 0.254)
		(layers "F.Cu" "B.Cu")
		(net "VR_PVNN_PCH_VINSEN")
	)
	(segment
		(start 391.56894 -152.663144)
		(end 391.511536 -152.720548)
		(width 0.254)
		(layer "B.Cu")
		(net "VR_PVNN_PCH_VINSEN")
	)
	(segment
		(start 391.56894 -152.00122)
		(end 391.56894 -152.663144)
		(width 0.254)
		(layer "B.Cu")
		(net "VR_PVNN_PCH_VINSEN")
	)
	(segment
		(start 391.56894 -152.00122)
		(end 391.56894 -150.7998)
		(width 0.254)
		(layer "B.Cu")
		(net "VR_PVNN_PCH_VINSEN")
	)
	(segment
		(start 395.582902 -151.3459)
		(end 395.582902 -150.599902)
		(width 0.1778)
		(layer "F.Cu")
		(net "VR_PVNN_PCH_PWM1")
	)
	(segment
		(start 376.752866 -157.205934)
		(end 376.617484 -157.070552)
		(width 0.254)
		(layer "F.Cu")
		(net "VR_PVNN_PCH_PWM1")
	)
	(segment
		(start 395.582902 -150.599902)
		(end 395.1224 -150.1394)
		(width 0.1778)
		(layer "F.Cu")
		(net "VR_PVNN_PCH_PWM1")
	)
	(segment
		(start 376.752866 -157.2514)
		(end 376.752866 -157.205934)
		(width 0.254)
		(layer "F.Cu")
		(net "VR_PVNN_PCH_PWM1")
	)
	(segment
		(start 376.617484 -157.070552)
		(end 376.617484 -156.24302)
		(width 0.254)
		(layer "F.Cu")
		(net "VR_PVNN_PCH_PWM1")
	)
	(via
		(at 395.1224 -150.1394)
		(size 0.508)
		(drill 0.254)
		(layers "F.Cu" "B.Cu")
		(net "VR_PVNN_PCH_PWM1")
	)
	(via
		(at 376.752866 -157.2514)
		(size 0.508)
		(drill 0.254)
		(layers "F.Cu" "B.Cu")
		(net "VR_PVNN_PCH_PWM1")
	)
	(segment
		(start 395.351 -150.792688)
		(end 395.351 -150.368)
		(width 0.254)
		(layer "In4.Cu")
		(net "VR_PVNN_PCH_PWM1")
	)
	(segment
		(start 394.396214 -157.293564)
		(end 394.396214 -155.53436)
		(width 0.254)
		(layer "In4.Cu")
		(net "VR_PVNN_PCH_PWM1")
	)
	(segment
		(start 376.752866 -157.2514)
		(end 376.752866 -158.00832)
		(width 0.254)
		(layer "In4.Cu")
		(net "VR_PVNN_PCH_PWM1")
	)
	(segment
		(start 393.825984 -154.059636)
		(end 394.315442 -153.570178)
		(width 0.254)
		(layer "In4.Cu")
		(net "VR_PVNN_PCH_PWM1")
	)
	(segment
		(start 395.351 -150.368)
		(end 395.1224 -150.1394)
		(width 0.254)
		(layer "In4.Cu")
		(net "VR_PVNN_PCH_PWM1")
	)
	(segment
		(start 394.396214 -155.53436)
		(end 393.825984 -154.96413)
		(width 0.254)
		(layer "In4.Cu")
		(net "VR_PVNN_PCH_PWM1")
	)
	(segment
		(start 377.207526 -158.46298)
		(end 393.226798 -158.46298)
		(width 0.254)
		(layer "In4.Cu")
		(net "VR_PVNN_PCH_PWM1")
	)
	(segment
		(start 393.226798 -158.46298)
		(end 394.396214 -157.293564)
		(width 0.254)
		(layer "In4.Cu")
		(net "VR_PVNN_PCH_PWM1")
	)
	(segment
		(start 394.315442 -153.570178)
		(end 394.315442 -151.828246)
		(width 0.254)
		(layer "In4.Cu")
		(net "VR_PVNN_PCH_PWM1")
	)
	(segment
		(start 394.315442 -151.828246)
		(end 395.351 -150.792688)
		(width 0.254)
		(layer "In4.Cu")
		(net "VR_PVNN_PCH_PWM1")
	)
	(segment
		(start 393.825984 -154.96413)
		(end 393.825984 -154.059636)
		(width 0.254)
		(layer "In4.Cu")
		(net "VR_PVNN_PCH_PWM1")
	)
	(segment
		(start 376.752866 -158.00832)
		(end 377.207526 -158.46298)
		(width 0.254)
		(layer "In4.Cu")
		(net "VR_PVNN_PCH_PWM1")
	)
	(segment
		(start 373.972328 -154.72791)
		(end 373.576596 -154.72791)
		(width 0.254)
		(layer "F.Cu")
		(net "VR_PVNN_PCH_PH1_VCIN")
	)
	(segment
		(start 373.1768 -155.127706)
		(end 372.872 -155.127706)
		(width 0.4064)
		(layer "F.Cu")
		(net "VR_PVNN_PCH_PH1_VCIN")
	)
	(segment
		(start 372.872 -155.127706)
		(end 372.5672 -155.432506)
		(width 0.4064)
		(layer "F.Cu")
		(net "VR_PVNN_PCH_PH1_VCIN")
	)
	(segment
		(start 373.576596 -154.72791)
		(end 373.1768 -155.127706)
		(width 0.254)
		(layer "F.Cu")
		(net "VR_PVNN_PCH_PH1_VCIN")
	)
	(via
		(at 372.3513 -155.52166)
		(size 0.6604)
		(drill 0.3302)
		(layers "F.Cu" "B.Cu")
		(net "VR_PVNN_PCH_PH1_VCIN")
	)
	(via
		(at 373.1768 -155.127706)
		(size 0.508)
		(drill 0.254)
		(layers "F.Cu" "B.Cu")
		(net "VR_PVNN_PCH_PH1_VCIN")
	)
	(segment
		(start 372.745254 -155.127706)
		(end 372.3513 -155.52166)
		(width 0.4064)
		(layer "B.Cu")
		(net "VR_PVNN_PCH_PH1_VCIN")
	)
	(segment
		(start 373.9642 -155.432506)
		(end 373.648224 -155.432506)
		(width 0.4064)
		(layer "B.Cu")
		(net "VR_PVNN_PCH_PH1_VCIN")
	)
	(segment
		(start 373.343424 -155.127706)
		(end 373.1768 -155.127706)
		(width 0.4064)
		(layer "B.Cu")
		(net "VR_PVNN_PCH_PH1_VCIN")
	)
	(segment
		(start 373.1768 -155.127706)
		(end 372.745254 -155.127706)
		(width 0.4064)
		(layer "B.Cu")
		(net "VR_PVNN_PCH_PH1_VCIN")
	)
	(segment
		(start 373.648224 -155.432506)
		(end 373.343424 -155.127706)
		(width 0.4064)
		(layer "B.Cu")
		(net "VR_PVNN_PCH_PH1_VCIN")
	)
	(segment
		(start 377.51766 -156.623004)
		(end 377.934728 -157.040072)
		(width 0.254)
		(layer "F.Cu")
		(net "VR_PVNN_PCH_PH1_PHASE")
	)
	(segment
		(start 377.51766 -156.24302)
		(end 377.51766 -156.623004)
		(width 0.254)
		(layer "F.Cu")
		(net "VR_PVNN_PCH_PH1_PHASE")
	)
	(segment
		(start 378.095256 -157.2006)
		(end 379.5522 -157.2006)
		(width 0.508)
		(layer "F.Cu")
		(net "VR_PVNN_PCH_PH1_PHASE")
	)
	(segment
		(start 377.934728 -157.040072)
		(end 378.095256 -157.2006)
		(width 0.508)
		(layer "F.Cu")
		(net "VR_PVNN_PCH_PH1_PHASE")
	)
	(segment
		(start 378.6378 -158.0896)
		(end 379.5522 -158.0896)
		(width 0.508)
		(layer "F.Cu")
		(net "VR_PVNN_PCH_PH1_BOOT")
	)
	(segment
		(start 378.587 -158.1404)
		(end 378.6378 -158.0896)
		(width 0.508)
		(layer "F.Cu")
		(net "VR_PVNN_PCH_PH1_BOOT")
	)
	(segment
		(start 398.978628 -155.197048)
		(end 399.20418 -155.4226)
		(width 0.2032)
		(layer "F.Cu")
		(net "VR_PVNN_PCH_AVSP")
	)
	(segment
		(start 398.2339 -155.197048)
		(end 398.978628 -155.197048)
		(width 0.2032)
		(layer "F.Cu")
		(net "VR_PVNN_PCH_AVSP")
	)
	(segment
		(start 399.330418 -155.55976)
		(end 399.34134 -155.55976)
		(width 0.2032)
		(layer "F.Cu")
		(net "VR_PVNN_PCH_AVSP")
	)
	(segment
		(start 399.20418 -155.433522)
		(end 399.330418 -155.55976)
		(width 0.2032)
		(layer "F.Cu")
		(net "VR_PVNN_PCH_AVSP")
	)
	(segment
		(start 401.726654 -155.829)
		(end 400.558 -155.829)
		(width 0.254)
		(layer "F.Cu")
		(net "VR_PVNN_PCH_AVSP")
	)
	(segment
		(start 401.916138 -155.639516)
		(end 401.726654 -155.829)
		(width 0.254)
		(layer "F.Cu")
		(net "VR_PVNN_PCH_AVSP")
	)
	(segment
		(start 399.61058 -155.829)
		(end 399.669 -155.829)
		(width 0.2032)
		(layer "F.Cu")
		(net "VR_PVNN_PCH_AVSP")
	)
	(segment
		(start 399.20418 -155.4226)
		(end 399.20418 -155.433522)
		(width 0.2032)
		(layer "F.Cu")
		(net "VR_PVNN_PCH_AVSP")
	)
	(segment
		(start 399.34134 -155.55976)
		(end 399.61058 -155.829)
		(width 0.2032)
		(layer "F.Cu")
		(net "VR_PVNN_PCH_AVSP")
	)
	(segment
		(start 399.669 -155.829)
		(end 400.558 -155.829)
		(width 0.254)
		(layer "F.Cu")
		(net "VR_PVNN_PCH_AVSP")
	)
	(via
		(at 401.916138 -155.639516)
		(size 0.762)
		(drill 0.381)
		(layers "F.Cu" "B.Cu")
		(net "VR_PVNN_PCH_AVSP")
	)
	(segment
		(start 385.644136 -157.120336)
		(end 385.8006 -157.2768)
		(width 0.254)
		(layer "F.Cu")
		(net "VR_P1V05_PCH_STBY_PWM1")
	)
	(segment
		(start 394.782802 -151.3459)
		(end 394.782802 -150.791926)
		(width 0.2032)
		(layer "F.Cu")
		(net "VR_P1V05_PCH_STBY_PWM1")
	)
	(segment
		(start 394.462 -150.471124)
		(end 394.462 -150.1394)
		(width 0.2032)
		(layer "F.Cu")
		(net "VR_P1V05_PCH_STBY_PWM1")
	)
	(segment
		(start 385.8006 -157.2768)
		(end 385.8006 -157.4292)
		(width 0.254)
		(layer "F.Cu")
		(net "VR_P1V05_PCH_STBY_PWM1")
	)
	(segment
		(start 394.782802 -150.791926)
		(end 394.462 -150.471124)
		(width 0.2032)
		(layer "F.Cu")
		(net "VR_P1V05_PCH_STBY_PWM1")
	)
	(segment
		(start 385.644136 -156.565092)
		(end 385.644136 -157.120336)
		(width 0.254)
		(layer "F.Cu")
		(net "VR_P1V05_PCH_STBY_PWM1")
	)
	(via
		(at 394.462 -150.1394)
		(size 0.508)
		(drill 0.254)
		(layers "F.Cu" "B.Cu")
		(net "VR_P1V05_PCH_STBY_PWM1")
	)
	(via
		(at 385.8006 -157.4292)
		(size 0.508)
		(drill 0.254)
		(layers "F.Cu" "B.Cu")
		(net "VR_P1V05_PCH_STBY_PWM1")
	)
	(segment
		(start 386.004562 -157.633162)
		(end 385.8006 -157.4292)
		(width 0.254)
		(layer "In4.Cu")
		(net "VR_P1V05_PCH_STBY_PWM1")
	)
	(segment
		(start 394.462 -150.1394)
		(end 394.462 -150.554944)
		(width 0.254)
		(layer "In4.Cu")
		(net "VR_P1V05_PCH_STBY_PWM1")
	)
	(segment
		(start 392.497056 -157.70098)
		(end 391.671302 -156.875226)
		(width 0.254)
		(layer "In4.Cu")
		(net "VR_P1V05_PCH_STBY_PWM1")
	)
	(segment
		(start 393.020296 -155.447492)
		(end 393.3952 -155.822396)
		(width 0.254)
		(layer "In4.Cu")
		(net "VR_P1V05_PCH_STBY_PWM1")
	)
	(segment
		(start 389.876538 -157.633162)
		(end 386.004562 -157.633162)
		(width 0.254)
		(layer "In4.Cu")
		(net "VR_P1V05_PCH_STBY_PWM1")
	)
	(segment
		(start 394.462 -150.554944)
		(end 393.531852 -151.485092)
		(width 0.254)
		(layer "In4.Cu")
		(net "VR_P1V05_PCH_STBY_PWM1")
	)
	(segment
		(start 390.634474 -156.875226)
		(end 389.876538 -157.633162)
		(width 0.254)
		(layer "In4.Cu")
		(net "VR_P1V05_PCH_STBY_PWM1")
	)
	(segment
		(start 393.020296 -153.77668)
		(end 393.020296 -155.447492)
		(width 0.254)
		(layer "In4.Cu")
		(net "VR_P1V05_PCH_STBY_PWM1")
	)
	(segment
		(start 393.3952 -157.216856)
		(end 392.911076 -157.70098)
		(width 0.254)
		(layer "In4.Cu")
		(net "VR_P1V05_PCH_STBY_PWM1")
	)
	(segment
		(start 393.531852 -151.485092)
		(end 393.531852 -153.265124)
		(width 0.254)
		(layer "In4.Cu")
		(net "VR_P1V05_PCH_STBY_PWM1")
	)
	(segment
		(start 392.911076 -157.70098)
		(end 392.497056 -157.70098)
		(width 0.254)
		(layer "In4.Cu")
		(net "VR_P1V05_PCH_STBY_PWM1")
	)
	(segment
		(start 391.671302 -156.875226)
		(end 390.634474 -156.875226)
		(width 0.254)
		(layer "In4.Cu")
		(net "VR_P1V05_PCH_STBY_PWM1")
	)
	(segment
		(start 393.3952 -155.822396)
		(end 393.3952 -157.216856)
		(width 0.254)
		(layer "In4.Cu")
		(net "VR_P1V05_PCH_STBY_PWM1")
	)
	(segment
		(start 393.531852 -153.265124)
		(end 393.020296 -153.77668)
		(width 0.254)
		(layer "In4.Cu")
		(net "VR_P1V05_PCH_STBY_PWM1")
	)
	(segment
		(start 381.789178 -155.2194)
		(end 382.1938 -155.2194)
		(width 0.4064)
		(layer "F.Cu")
		(net "VR_P1V05_PCH_STBY_PH1_VCIN")
	)
	(segment
		(start 381.576072 -155.432506)
		(end 381.789178 -155.2194)
		(width 0.4064)
		(layer "F.Cu")
		(net "VR_P1V05_PCH_STBY_PH1_VCIN")
	)
	(segment
		(start 382.1938 -155.2194)
		(end 382.285494 -155.127706)
		(width 0.254)
		(layer "F.Cu")
		(net "VR_P1V05_PCH_STBY_PH1_VCIN")
	)
	(segment
		(start 382.49225 -155.049982)
		(end 382.99898 -155.049982)
		(width 0.254)
		(layer "F.Cu")
		(net "VR_P1V05_PCH_STBY_PH1_VCIN")
	)
	(segment
		(start 382.285494 -155.127706)
		(end 382.414526 -155.127706)
		(width 0.254)
		(layer "F.Cu")
		(net "VR_P1V05_PCH_STBY_PH1_VCIN")
	)
	(segment
		(start 382.414526 -155.127706)
		(end 382.49225 -155.049982)
		(width 0.254)
		(layer "F.Cu")
		(net "VR_P1V05_PCH_STBY_PH1_VCIN")
	)
	(via
		(at 382.1938 -155.2194)
		(size 0.508)
		(drill 0.254)
		(layers "F.Cu" "B.Cu")
		(net "VR_P1V05_PCH_STBY_PH1_VCIN")
	)
	(segment
		(start 382.657096 -155.432506)
		(end 383.019808 -155.432506)
		(width 0.4064)
		(layer "B.Cu")
		(net "VR_P1V05_PCH_STBY_PH1_VCIN")
	)
	(segment
		(start 382.1938 -155.2194)
		(end 382.44399 -155.2194)
		(width 0.4064)
		(layer "B.Cu")
		(net "VR_P1V05_PCH_STBY_PH1_VCIN")
	)
	(segment
		(start 382.44399 -155.2194)
		(end 382.657096 -155.432506)
		(width 0.4064)
		(layer "B.Cu")
		(net "VR_P1V05_PCH_STBY_PH1_VCIN")
	)
	(segment
		(start 386.8674 -157.296104)
		(end 388.520432 -157.296104)
		(width 0.508)
		(layer "F.Cu")
		(net "VR_P1V05_PCH_STBY_PH1_PHASE")
	)
	(segment
		(start 388.520432 -157.296104)
		(end 388.71779 -157.493462)
		(width 0.508)
		(layer "F.Cu")
		(net "VR_P1V05_PCH_STBY_PH1_PHASE")
	)
	(segment
		(start 386.544312 -156.973016)
		(end 386.8674 -157.296104)
		(width 0.254)
		(layer "F.Cu")
		(net "VR_P1V05_PCH_STBY_PH1_PHASE")
	)
	(segment
		(start 386.544312 -156.565092)
		(end 386.544312 -156.973016)
		(width 0.254)
		(layer "F.Cu")
		(net "VR_P1V05_PCH_STBY_PH1_PHASE")
	)
	(segment
		(start 394.382752 -156.752544)
		(end 394.382752 -156.2481)
		(width 0.127)
		(layer "F.Cu")
		(net "VR_P1V05_PCH_STBY_AVSP")
	)
	(segment
		(start 394.258292 -158.363666)
		(end 393.920726 -158.0261)
		(width 0.127)
		(layer "F.Cu")
		(net "VR_P1V05_PCH_STBY_AVSP")
	)
	(segment
		(start 393.920726 -157.21457)
		(end 394.382752 -156.752544)
		(width 0.127)
		(layer "F.Cu")
		(net "VR_P1V05_PCH_STBY_AVSP")
	)
	(segment
		(start 393.920726 -158.0261)
		(end 393.920726 -157.21457)
		(width 0.127)
		(layer "F.Cu")
		(net "VR_P1V05_PCH_STBY_AVSP")
	)
	(via
		(at 394.258292 -158.363666)
		(size 0.508)
		(drill 0.254)
		(layers "F.Cu" "B.Cu")
		(net "VR_P1V05_PCH_STBY_AVSP")
	)
	(segment
		(start 394.35405 -156.825696)
		(end 394.35405 -157.226)
		(width 0.127)
		(layer "B.Cu")
		(net "VR_P1V05_PCH_STBY_AVSP")
	)
	(segment
		(start 394.5382 -156.083)
		(end 394.5382 -156.641546)
		(width 0.127)
		(layer "B.Cu")
		(net "VR_P1V05_PCH_STBY_AVSP")
	)
	(segment
		(start 394.35405 -158.267908)
		(end 394.258292 -158.363666)
		(width 0.127)
		(layer "B.Cu")
		(net "VR_P1V05_PCH_STBY_AVSP")
	)
	(segment
		(start 394.35405 -157.226)
		(end 394.35405 -158.267908)
		(width 0.127)
		(layer "B.Cu")
		(net "VR_P1V05_PCH_STBY_AVSP")
	)
	(segment
		(start 394.5382 -156.641546)
		(end 394.35405 -156.825696)
		(width 0.127)
		(layer "B.Cu")
		(net "VR_P1V05_PCH_STBY_AVSP")
	)
	(segment
		(start 392.533378 -153.597102)
		(end 393.3317 -153.597102)
		(width 0.1778)
		(layer "F.Cu")
		(net "VR_PVNN_PCH_XADDR1")
	)
	(via
		(at 392.533378 -153.597102)
		(size 0.508)
		(drill 0.254)
		(layers "F.Cu" "B.Cu")
		(net "VR_PVNN_PCH_XADDR1")
	)
	(segment
		(start 392.533378 -153.597102)
		(end 392.578336 -153.552144)
		(width 0.254)
		(layer "B.Cu")
		(net "VR_PVNN_PCH_XADDR1")
	)
	(segment
		(start 392.578336 -153.552144)
		(end 393.362688 -153.552144)
		(width 0.254)
		(layer "B.Cu")
		(net "VR_PVNN_PCH_XADDR1")
	)
	(segment
		(start 392.938508 -152.396952)
		(end 393.3317 -152.396952)
		(width 0.2032)
		(layer "F.Cu")
		(net "VR_PVNN_PCH_VDD")
	)
	(segment
		(start 392.533378 -151.991822)
		(end 392.938508 -152.396952)
		(width 0.2032)
		(layer "F.Cu")
		(net "VR_PVNN_PCH_VDD")
	)
	(via
		(at 392.533378 -151.991822)
		(size 0.508)
		(drill 0.254)
		(layers "F.Cu" "B.Cu")
		(net "VR_PVNN_PCH_VDD")
	)
	(segment
		(start 498.409976 -150.302976)
		(end 498.289834 -150.302976)
		(width 0.10795)
		(layer "F.Cu")
		(net "FP_ID_LED_XOR_R")
	)
	(segment
		(start 499.872 -151.765)
		(end 498.409976 -150.302976)
		(width 0.10795)
		(layer "F.Cu")
		(net "FP_ID_LED_XOR_R")
	)
	(via
		(at 498.289834 -150.302976)
		(size 0.508)
		(drill 0.254)
		(layers "F.Cu" "B.Cu")
		(net "FP_ID_LED_XOR_R")
	)
	(segment
		(start 498.6528 -150.665942)
		(end 498.289834 -150.302976)
		(width 0.10795)
		(layer "B.Cu")
		(net "FP_ID_LED_XOR_R")
	)
	(segment
		(start 498.6528 -151.0284)
		(end 498.6528 -150.665942)
		(width 0.10795)
		(layer "B.Cu")
		(net "FP_ID_LED_XOR_R")
	)
	(segment
		(start 475.7928 -148.4122)
		(end 475.2594 -148.9456)
		(width 0.10795)
		(layer "F.Cu")
		(net "RST_SYSTEM_BTN_BUF_N")
	)
	(segment
		(start 478.8154 -148.4122)
		(end 475.7928 -148.4122)
		(width 0.10795)
		(layer "F.Cu")
		(net "RST_SYSTEM_BTN_BUF_N")
	)
	(segment
		(start 479.425 -147.8026)
		(end 480.2124 -147.8026)
		(width 0.10795)
		(layer "F.Cu")
		(net "RST_SYSTEM_BTN_BUF_N")
	)
	(segment
		(start 480.45624 -147.55876)
		(end 480.45624 -146.2278)
		(width 0.10795)
		(layer "F.Cu")
		(net "RST_SYSTEM_BTN_BUF_N")
	)
	(segment
		(start 420.19855 -101.2698)
		(end 418.3634 -101.2698)
		(width 0.10795)
		(layer "F.Cu")
		(net "RST_SYSTEM_BTN_BUF_N")
	)
	(segment
		(start 418.3634 -101.2698)
		(end 416.179 -101.2698)
		(width 0.10795)
		(layer "F.Cu")
		(net "RST_SYSTEM_BTN_BUF_N")
	)
	(segment
		(start 478.8154 -148.4122)
		(end 479.425 -147.8026)
		(width 0.10795)
		(layer "F.Cu")
		(net "RST_SYSTEM_BTN_BUF_N")
	)
	(segment
		(start 480.2124 -147.8026)
		(end 480.45624 -147.55876)
		(width 0.10795)
		(layer "F.Cu")
		(net "RST_SYSTEM_BTN_BUF_N")
	)
	(segment
		(start 420.31158 -101.38283)
		(end 420.19855 -101.2698)
		(width 0.10795)
		(layer "F.Cu")
		(net "RST_SYSTEM_BTN_BUF_N")
	)
	(via
		(at 478.8154 -148.4122)
		(size 0.508)
		(drill 0.254)
		(layers "F.Cu" "B.Cu")
		(net "RST_SYSTEM_BTN_BUF_N")
	)
	(via
		(at 418.3634 -101.2698)
		(size 0.762)
		(drill 0.381)
		(layers "F.Cu" "B.Cu")
		(net "RST_SYSTEM_BTN_BUF_N")
	)
	(via
		(at 420.31158 -101.38283)
		(size 0.508)
		(drill 0.254)
		(layers "F.Cu" "B.Cu")
		(net "RST_SYSTEM_BTN_BUF_N")
	)
	(segment
		(start 423.588434 -106.750104)
		(end 423.531538 -106.750104)
		(width 0.089408)
		(layer "In9.Cu")
		(net "RST_SYSTEM_BTN_BUF_N")
	)
	(segment
		(start 489.612686 -138.381994)
		(end 489.612686 -138.139678)
		(width 0.089408)
		(layer "In9.Cu")
		(net "RST_SYSTEM_BTN_BUF_N")
	)
	(segment
		(start 489.612686 -138.139678)
		(end 492.852964 -134.8994)
		(width 0.089408)
		(layer "In9.Cu")
		(net "RST_SYSTEM_BTN_BUF_N")
	)
	(segment
		(start 420.34333 -101.38283)
		(end 420.31158 -101.38283)
		(width 0.089408)
		(layer "In9.Cu")
		(net "RST_SYSTEM_BTN_BUF_N")
	)
	(segment
		(start 425.438824 -109.318044)
		(end 425.438824 -108.600494)
		(width 0.089408)
		(layer "In9.Cu")
		(net "RST_SYSTEM_BTN_BUF_N")
	)
	(segment
		(start 500.424704 -128.893824)
		(end 498.84076 -127.30988)
		(width 0.089408)
		(layer "In9.Cu")
		(net "RST_SYSTEM_BTN_BUF_N")
	)
	(segment
		(start 421.019732 -104.238298)
		(end 421.019732 -102.059232)
		(width 0.089408)
		(layer "In9.Cu")
		(net "RST_SYSTEM_BTN_BUF_N")
	)
	(segment
		(start 487.599482 -143.131286)
		(end 489.61294 -141.117828)
		(width 0.089408)
		(layer "In9.Cu")
		(net "RST_SYSTEM_BTN_BUF_N")
	)
	(segment
		(start 500.424704 -114.36858)
		(end 497.424202 -111.368078)
		(width 0.089408)
		(layer "In9.Cu")
		(net "RST_SYSTEM_BTN_BUF_N")
	)
	(segment
		(start 496.758468 -133.294628)
		(end 499.696232 -133.294628)
		(width 0.089408)
		(layer "In9.Cu")
		(net "RST_SYSTEM_BTN_BUF_N")
	)
	(segment
		(start 500.424704 -118.63832)
		(end 500.424704 -114.36858)
		(width 0.089408)
		(layer "In9.Cu")
		(net "RST_SYSTEM_BTN_BUF_N")
	)
	(segment
		(start 478.8154 -147.087082)
		(end 482.771196 -143.131286)
		(width 0.089408)
		(layer "In9.Cu")
		(net "RST_SYSTEM_BTN_BUF_N")
	)
	(segment
		(start 492.852964 -134.8994)
		(end 495.153696 -134.8994)
		(width 0.089408)
		(layer "In9.Cu")
		(net "RST_SYSTEM_BTN_BUF_N")
	)
	(segment
		(start 491.563914 -112.472724)
		(end 482.5111 -112.472724)
		(width 0.089408)
		(layer "In9.Cu")
		(net "RST_SYSTEM_BTN_BUF_N")
	)
	(segment
		(start 492.66856 -111.368078)
		(end 491.563914 -112.472724)
		(width 0.089408)
		(layer "In9.Cu")
		(net "RST_SYSTEM_BTN_BUF_N")
	)
	(segment
		(start 425.438824 -108.600494)
		(end 423.588434 -106.750104)
		(width 0.089408)
		(layer "In9.Cu")
		(net "RST_SYSTEM_BTN_BUF_N")
	)
	(segment
		(start 489.61294 -138.382248)
		(end 489.612686 -138.381994)
		(width 0.089408)
		(layer "In9.Cu")
		(net "RST_SYSTEM_BTN_BUF_N")
	)
	(segment
		(start 498.84076 -127.30988)
		(end 498.84076 -120.222264)
		(width 0.089408)
		(layer "In9.Cu")
		(net "RST_SYSTEM_BTN_BUF_N")
	)
	(segment
		(start 482.771196 -143.131286)
		(end 487.599482 -143.131286)
		(width 0.089408)
		(layer "In9.Cu")
		(net "RST_SYSTEM_BTN_BUF_N")
	)
	(segment
		(start 498.84076 -120.222264)
		(end 500.424704 -118.63832)
		(width 0.089408)
		(layer "In9.Cu")
		(net "RST_SYSTEM_BTN_BUF_N")
	)
	(segment
		(start 489.61294 -141.117828)
		(end 489.61294 -138.382248)
		(width 0.089408)
		(layer "In9.Cu")
		(net "RST_SYSTEM_BTN_BUF_N")
	)
	(segment
		(start 423.531538 -106.750104)
		(end 421.019732 -104.238298)
		(width 0.089408)
		(layer "In9.Cu")
		(net "RST_SYSTEM_BTN_BUF_N")
	)
	(segment
		(start 421.019732 -102.059232)
		(end 420.34333 -101.38283)
		(width 0.089408)
		(layer "In9.Cu")
		(net "RST_SYSTEM_BTN_BUF_N")
	)
	(segment
		(start 482.5111 -112.472724)
		(end 481.190808 -111.152432)
		(width 0.089408)
		(layer "In9.Cu")
		(net "RST_SYSTEM_BTN_BUF_N")
	)
	(segment
		(start 478.8154 -148.4122)
		(end 478.8154 -147.087082)
		(width 0.089408)
		(layer "In9.Cu")
		(net "RST_SYSTEM_BTN_BUF_N")
	)
	(segment
		(start 495.153696 -134.8994)
		(end 496.758468 -133.294628)
		(width 0.089408)
		(layer "In9.Cu")
		(net "RST_SYSTEM_BTN_BUF_N")
	)
	(segment
		(start 427.273212 -111.152432)
		(end 425.438824 -109.318044)
		(width 0.089408)
		(layer "In9.Cu")
		(net "RST_SYSTEM_BTN_BUF_N")
	)
	(segment
		(start 497.424202 -111.368078)
		(end 492.66856 -111.368078)
		(width 0.089408)
		(layer "In9.Cu")
		(net "RST_SYSTEM_BTN_BUF_N")
	)
	(segment
		(start 481.190808 -111.152432)
		(end 427.273212 -111.152432)
		(width 0.089408)
		(layer "In9.Cu")
		(net "RST_SYSTEM_BTN_BUF_N")
	)
	(segment
		(start 499.696232 -133.294628)
		(end 500.424704 -132.566156)
		(width 0.089408)
		(layer "In9.Cu")
		(net "RST_SYSTEM_BTN_BUF_N")
	)
	(segment
		(start 500.424704 -132.566156)
		(end 500.424704 -128.893824)
		(width 0.089408)
		(layer "In9.Cu")
		(net "RST_SYSTEM_BTN_BUF_N")
	)
	(segment
		(start 398.325848 -150.071074)
		(end 399.116296 -150.071074)
		(width 0.10795)
		(layer "F.Cu")
		(net "PWRGD_PVNN_PCH_R")
	)
	(segment
		(start 397.256 -149.0472)
		(end 396.875 -149.0472)
		(width 0.10795)
		(layer "F.Cu")
		(net "PWRGD_PVNN_PCH_R")
	)
	(segment
		(start 397.182848 -149.948646)
		(end 397.182848 -151.3459)
		(width 0.10795)
		(layer "F.Cu")
		(net "PWRGD_PVNN_PCH_R")
	)
	(segment
		(start 397.637 -149.4282)
		(end 397.256 -149.0472)
		(width 0.10795)
		(layer "F.Cu")
		(net "PWRGD_PVNN_PCH_R")
	)
	(segment
		(start 396.875 -149.2758)
		(end 396.875 -149.0472)
		(width 0.10795)
		(layer "F.Cu")
		(net "PWRGD_PVNN_PCH_R")
	)
	(segment
		(start 397.182848 -149.948646)
		(end 397.182848 -149.583648)
		(width 0.10795)
		(layer "F.Cu")
		(net "PWRGD_PVNN_PCH_R")
	)
	(segment
		(start 398.325848 -150.071074)
		(end 397.924274 -150.071074)
		(width 0.10795)
		(layer "F.Cu")
		(net "PWRGD_PVNN_PCH_R")
	)
	(segment
		(start 397.924274 -150.071074)
		(end 397.637 -149.7838)
		(width 0.10795)
		(layer "F.Cu")
		(net "PWRGD_PVNN_PCH_R")
	)
	(segment
		(start 399.116296 -150.071074)
		(end 399.159222 -150.114)
		(width 0.10795)
		(layer "F.Cu")
		(net "PWRGD_PVNN_PCH_R")
	)
	(segment
		(start 397.637 -149.7838)
		(end 397.637 -149.4282)
		(width 0.10795)
		(layer "F.Cu")
		(net "PWRGD_PVNN_PCH_R")
	)
	(segment
		(start 397.182848 -149.583648)
		(end 396.875 -149.2758)
		(width 0.10795)
		(layer "F.Cu")
		(net "PWRGD_PVNN_PCH_R")
	)
	(via
		(at 397.182848 -149.948646)
		(size 0.508)
		(drill 0.254)
		(layers "F.Cu" "B.Cu")
		(net "PWRGD_PVNN_PCH_R")
	)
	(via
		(at 488.1118 -155.829)
		(size 0.6604)
		(drill 0.3302)
		(layers "F.Cu" "B.Cu")
		(net "PWRGD_P3V3_R")
	)
	(segment
		(start 488.1118 -155.829)
		(end 488.9754 -155.829)
		(width 0.10795)
		(layer "B.Cu")
		(net "PWRGD_P3V3_R")
	)
	(segment
		(start 489.189014 -153.924)
		(end 489.189014 -154.874214)
		(width 0.10795)
		(layer "B.Cu")
		(net "PWRGD_P3V3_R")
	)
	(segment
		(start 489.4707 -155.3337)
		(end 489.6485 -155.3337)
		(width 0.10795)
		(layer "B.Cu")
		(net "PWRGD_P3V3_R")
	)
	(segment
		(start 489.189014 -154.874214)
		(end 489.6485 -155.3337)
		(width 0.10795)
		(layer "B.Cu")
		(net "PWRGD_P3V3_R")
	)
	(segment
		(start 488.9754 -155.829)
		(end 489.4707 -155.3337)
		(width 0.10795)
		(layer "B.Cu")
		(net "PWRGD_P3V3_R")
	)
	(segment
		(start 393.3317 -155.197048)
		(end 392.985752 -155.197048)
		(width 0.10795)
		(layer "F.Cu")
		(net "PU_VR_PVNN_PCH_FAULT1")
	)
	(segment
		(start 392.985752 -155.197048)
		(end 392.585702 -155.597098)
		(width 0.10795)
		(layer "F.Cu")
		(net "PU_VR_PVNN_PCH_FAULT1")
	)
	(segment
		(start 392.585702 -155.597098)
		(end 391.620502 -155.597098)
		(width 0.10795)
		(layer "F.Cu")
		(net "PU_VR_PVNN_PCH_FAULT1")
	)
	(segment
		(start 391.620502 -155.597098)
		(end 391.3378 -155.8798)
		(width 0.10795)
		(layer "F.Cu")
		(net "PU_VR_PVNN_PCH_FAULT1")
	)
	(via
		(at 391.3378 -155.8798)
		(size 0.508)
		(drill 0.254)
		(layers "F.Cu" "B.Cu")
		(net "PU_VR_PVNN_PCH_FAULT1")
	)
	(via
		(at 395.38402 -154.95778)
		(size 0.6604)
		(drill 0.3302)
		(layers "F.Cu" "B.Cu")
		(net "PU_VR_PVNN_PCH_FAULT1")
	)
	(segment
		(start 395.487906 -155.061666)
		(end 395.487906 -156.115258)
		(width 0.10795)
		(layer "B.Cu")
		(net "PU_VR_PVNN_PCH_FAULT1")
	)
	(segment
		(start 395.23924 -154.813)
		(end 395.38402 -154.95778)
		(width 0.10795)
		(layer "B.Cu")
		(net "PU_VR_PVNN_PCH_FAULT1")
	)
	(segment
		(start 392.4046 -154.813)
		(end 395.23924 -154.813)
		(width 0.10795)
		(layer "B.Cu")
		(net "PU_VR_PVNN_PCH_FAULT1")
	)
	(segment
		(start 395.38402 -154.95778)
		(end 395.487906 -155.061666)
		(width 0.10795)
		(layer "B.Cu")
		(net "PU_VR_PVNN_PCH_FAULT1")
	)
	(segment
		(start 391.3378 -155.8798)
		(end 392.4046 -154.813)
		(width 0.10795)
		(layer "B.Cu")
		(net "PU_VR_PVNN_PCH_FAULT1")
	)
	(segment
		(start 391.20445 -118.4402)
		(end 391.696448 -118.6688)
		(width 0.10795)
		(layer "F.Cu")
		(net "LED_PCH_SATA_HDD_N")
	)
	(segment
		(start 391.696448 -118.6688)
		(end 391.69975 -118.670324)
		(width 0.10795)
		(layer "F.Cu")
		(net "LED_PCH_SATA_HDD_N")
	)
	(via
		(at 495.7572 -121.3866)
		(size 0.6604)
		(drill 0.3302)
		(layers "F.Cu" "B.Cu")
		(net "LED_PCH_SATA_HDD_N")
	)
	(via
		(at 391.69975 -118.670324)
		(size 0.508)
		(drill 0.254)
		(layers "F.Cu" "B.Cu")
		(net "LED_PCH_SATA_HDD_N")
	)
	(via
		(at 492.506 -121.0564)
		(size 0.508)
		(drill 0.254)
		(layers "F.Cu" "B.Cu")
		(net "LED_PCH_SATA_HDD_N")
	)
	(segment
		(start 492.7854 -121.3358)
		(end 492.506 -121.0564)
		(width 0.10795)
		(layer "B.Cu")
		(net "LED_PCH_SATA_HDD_N")
	)
	(segment
		(start 496.17376 -121.80316)
		(end 495.7572 -121.3866)
		(width 0.10795)
		(layer "B.Cu")
		(net "LED_PCH_SATA_HDD_N")
	)
	(segment
		(start 496.17376 -124.0663)
		(end 496.17376 -121.80316)
		(width 0.10795)
		(layer "B.Cu")
		(net "LED_PCH_SATA_HDD_N")
	)
	(segment
		(start 495.7572 -121.3866)
		(end 495.7064 -121.3358)
		(width 0.10795)
		(layer "B.Cu")
		(net "LED_PCH_SATA_HDD_N")
	)
	(segment
		(start 495.7064 -121.3358)
		(end 492.7854 -121.3358)
		(width 0.10795)
		(layer "B.Cu")
		(net "LED_PCH_SATA_HDD_N")
	)
	(segment
		(start 448.1576 -132.5372)
		(end 448.1576 -132.207254)
		(width 0.089408)
		(layer "In2.Cu")
		(net "LED_PCH_SATA_HDD_N")
	)
	(segment
		(start 493.121696 -127.804672)
		(end 493.121696 -121.672096)
		(width 0.089408)
		(layer "In2.Cu")
		(net "LED_PCH_SATA_HDD_N")
	)
	(segment
		(start 391.795 -119.507254)
		(end 391.795 -119.54002)
		(width 0.0889)
		(layer "In2.Cu")
		(net "LED_PCH_SATA_HDD_N")
	)
	(segment
		(start 470.955624 -141.674596)
		(end 470.986612 -141.643608)
		(width 0.089408)
		(layer "In2.Cu")
		(net "LED_PCH_SATA_HDD_N")
	)
	(segment
		(start 494.41735 -140.201904)
		(end 495.046 -139.573254)
		(width 0.089408)
		(layer "In2.Cu")
		(net "LED_PCH_SATA_HDD_N")
	)
	(segment
		(start 413.678116 -131.335526)
		(end 415.524188 -129.489454)
		(width 0.089408)
		(layer "In2.Cu")
		(net "LED_PCH_SATA_HDD_N")
	)
	(segment
		(start 452.896478 -134.202678)
		(end 452.896478 -134.999984)
		(width 0.089408)
		(layer "In2.Cu")
		(net "LED_PCH_SATA_HDD_N")
	)
	(segment
		(start 400.543522 -129.782824)
		(end 401.618958 -128.707388)
		(width 0.089408)
		(layer "In2.Cu")
		(net "LED_PCH_SATA_HDD_N")
	)
	(segment
		(start 433.325016 -130.524504)
		(end 433.502816 -130.702304)
		(width 0.089408)
		(layer "In2.Cu")
		(net "LED_PCH_SATA_HDD_N")
	)
	(segment
		(start 496.182904 -134.730744)
		(end 494.3856 -132.93344)
		(width 0.089408)
		(layer "In2.Cu")
		(net "LED_PCH_SATA_HDD_N")
	)
	(segment
		(start 415.524188 -129.489454)
		(end 416.933634 -129.489454)
		(width 0.089408)
		(layer "In2.Cu")
		(net "LED_PCH_SATA_HDD_N")
	)
	(segment
		(start 484.408988 -149.415246)
		(end 484.408988 -150.389844)
		(width 0.089408)
		(layer "In2.Cu")
		(net "LED_PCH_SATA_HDD_N")
	)
	(segment
		(start 479.71583 -144.722088)
		(end 484.408988 -149.415246)
		(width 0.089408)
		(layer "In2.Cu")
		(net "LED_PCH_SATA_HDD_N")
	)
	(segment
		(start 489.653326 -143.226536)
		(end 490.799374 -142.080488)
		(width 0.089408)
		(layer "In2.Cu")
		(net "LED_PCH_SATA_HDD_N")
	)
	(segment
		(start 443.251336 -132.047996)
		(end 446.855596 -132.047996)
		(width 0.089408)
		(layer "In2.Cu")
		(net "LED_PCH_SATA_HDD_N")
	)
	(segment
		(start 494.3856 -132.93344)
		(end 494.3856 -129.068576)
		(width 0.089408)
		(layer "In2.Cu")
		(net "LED_PCH_SATA_HDD_N")
	)
	(segment
		(start 495.046 -138.6078)
		(end 496.182904 -137.470896)
		(width 0.089408)
		(layer "In2.Cu")
		(net "LED_PCH_SATA_HDD_N")
	)
	(segment
		(start 401.618958 -128.707388)
		(end 410.51734 -128.707388)
		(width 0.089408)
		(layer "In2.Cu")
		(net "LED_PCH_SATA_HDD_N")
	)
	(segment
		(start 469.697816 -141.926564)
		(end 469.949784 -141.674596)
		(width 0.089408)
		(layer "In2.Cu")
		(net "LED_PCH_SATA_HDD_N")
	)
	(segment
		(start 396.10792 -126.3777)
		(end 396.10792 -129.311654)
		(width 0.089408)
		(layer "In2.Cu")
		(net "LED_PCH_SATA_HDD_N")
	)
	(segment
		(start 464.105498 -142.802102)
		(end 464.981036 -141.926564)
		(width 0.089408)
		(layer "In2.Cu")
		(net "LED_PCH_SATA_HDD_N")
	)
	(segment
		(start 410.51734 -128.707388)
		(end 413.145478 -131.335526)
		(width 0.089408)
		(layer "In2.Cu")
		(net "LED_PCH_SATA_HDD_N")
	)
	(segment
		(start 421.642032 -130.214624)
		(end 431.20691 -130.214624)
		(width 0.089408)
		(layer "In2.Cu")
		(net "LED_PCH_SATA_HDD_N")
	)
	(segment
		(start 431.20691 -130.214624)
		(end 431.51679 -130.524504)
		(width 0.089408)
		(layer "In2.Cu")
		(net "LED_PCH_SATA_HDD_N")
	)
	(segment
		(start 393.2809 -123.799854)
		(end 393.2809 -124.190252)
		(width 0.0889)
		(layer "In2.Cu")
		(net "LED_PCH_SATA_HDD_N")
	)
	(segment
		(start 392.7856 -121.224294)
		(end 392.7856 -121.25706)
		(width 0.0889)
		(layer "In2.Cu")
		(net "LED_PCH_SATA_HDD_N")
	)
	(segment
		(start 484.408988 -150.389844)
		(end 485.447848 -151.428704)
		(width 0.089408)
		(layer "In2.Cu")
		(net "LED_PCH_SATA_HDD_N")
	)
	(segment
		(start 392.2903 -120.365774)
		(end 392.2903 -120.39854)
		(width 0.0889)
		(layer "In2.Cu")
		(net "LED_PCH_SATA_HDD_N")
	)
	(segment
		(start 448.1576 -132.207254)
		(end 448.64147 -131.723384)
		(width 0.089408)
		(layer "In2.Cu")
		(net "LED_PCH_SATA_HDD_N")
	)
	(segment
		(start 488.202478 -151.428704)
		(end 489.628434 -150.002748)
		(width 0.089408)
		(layer "In2.Cu")
		(net "LED_PCH_SATA_HDD_N")
	)
	(segment
		(start 494.3856 -129.068576)
		(end 493.121696 -127.804672)
		(width 0.089408)
		(layer "In2.Cu")
		(net "LED_PCH_SATA_HDD_N")
	)
	(segment
		(start 447.929 -132.7658)
		(end 448.1576 -132.5372)
		(width 0.089408)
		(layer "In2.Cu")
		(net "LED_PCH_SATA_HDD_N")
	)
	(segment
		(start 470.988136 -141.643608)
		(end 471.6526 -140.979144)
		(width 0.089408)
		(layer "In2.Cu")
		(net "LED_PCH_SATA_HDD_N")
	)
	(segment
		(start 485.447848 -151.428704)
		(end 488.202478 -151.428704)
		(width 0.089408)
		(layer "In2.Cu")
		(net "LED_PCH_SATA_HDD_N")
	)
	(segment
		(start 491.513622 -142.080488)
		(end 493.392206 -140.201904)
		(width 0.089408)
		(layer "In2.Cu")
		(net "LED_PCH_SATA_HDD_N")
	)
	(segment
		(start 457.169774 -141.018768)
		(end 458.953108 -142.802102)
		(width 0.089408)
		(layer "In2.Cu")
		(net "LED_PCH_SATA_HDD_N")
	)
	(segment
		(start 420.383716 -128.956308)
		(end 421.642032 -130.214624)
		(width 0.089408)
		(layer "In2.Cu")
		(net "LED_PCH_SATA_HDD_N")
	)
	(segment
		(start 450.417184 -131.723384)
		(end 452.896478 -134.202678)
		(width 0.089408)
		(layer "In2.Cu")
		(net "LED_PCH_SATA_HDD_N")
	)
	(segment
		(start 471.6526 -140.979144)
		(end 471.950542 -140.979144)
		(width 0.089408)
		(layer "In2.Cu")
		(net "LED_PCH_SATA_HDD_N")
	)
	(segment
		(start 393.2809 -122.082814)
		(end 393.2809 -122.125994)
		(width 0.0889)
		(layer "In2.Cu")
		(net "LED_PCH_SATA_HDD_N")
	)
	(segment
		(start 471.950542 -140.979144)
		(end 471.95359 -140.976096)
		(width 0.089408)
		(layer "In2.Cu")
		(net "LED_PCH_SATA_HDD_N")
	)
	(segment
		(start 446.855596 -132.047996)
		(end 447.5734 -132.7658)
		(width 0.089408)
		(layer "In2.Cu")
		(net "LED_PCH_SATA_HDD_N")
	)
	(segment
		(start 396.57909 -129.782824)
		(end 400.543522 -129.782824)
		(width 0.089408)
		(layer "In2.Cu")
		(net "LED_PCH_SATA_HDD_N")
	)
	(segment
		(start 452.896478 -134.999984)
		(end 457.169774 -139.27328)
		(width 0.089408)
		(layer "In2.Cu")
		(net "LED_PCH_SATA_HDD_N")
	)
	(segment
		(start 395.237716 -125.507496)
		(end 396.10792 -126.3777)
		(width 0.089408)
		(layer "In2.Cu")
		(net "LED_PCH_SATA_HDD_N")
	)
	(segment
		(start 393.539472 -124.448824)
		(end 394.598144 -125.507496)
		(width 0.089408)
		(layer "In2.Cu")
		(net "LED_PCH_SATA_HDD_N")
	)
	(segment
		(start 489.628434 -149.086316)
		(end 489.653326 -149.061424)
		(width 0.089408)
		(layer "In2.Cu")
		(net "LED_PCH_SATA_HDD_N")
	)
	(segment
		(start 475.850204 -144.722088)
		(end 479.71583 -144.722088)
		(width 0.089408)
		(layer "In2.Cu")
		(net "LED_PCH_SATA_HDD_N")
	)
	(segment
		(start 457.169774 -139.27328)
		(end 457.169774 -141.018768)
		(width 0.089408)
		(layer "In2.Cu")
		(net "LED_PCH_SATA_HDD_N")
	)
	(segment
		(start 416.933634 -129.489454)
		(end 417.400232 -129.022856)
		(width 0.089408)
		(layer "In2.Cu")
		(net "LED_PCH_SATA_HDD_N")
	)
	(segment
		(start 393.2809 -124.190252)
		(end 393.539472 -124.448824)
		(width 0.0889)
		(layer "In2.Cu")
		(net "LED_PCH_SATA_HDD_N")
	)
	(segment
		(start 417.475924 -128.956308)
		(end 420.383716 -128.956308)
		(width 0.089408)
		(layer "In2.Cu")
		(net "LED_PCH_SATA_HDD_N")
	)
	(segment
		(start 470.986612 -141.643608)
		(end 470.988136 -141.643608)
		(width 0.089408)
		(layer "In2.Cu")
		(net "LED_PCH_SATA_HDD_N")
	)
	(segment
		(start 413.145478 -131.335526)
		(end 413.678116 -131.335526)
		(width 0.089408)
		(layer "In2.Cu")
		(net "LED_PCH_SATA_HDD_N")
	)
	(segment
		(start 417.409376 -129.022856)
		(end 417.475924 -128.956308)
		(width 0.089408)
		(layer "In2.Cu")
		(net "LED_PCH_SATA_HDD_N")
	)
	(segment
		(start 433.502816 -130.702304)
		(end 441.905644 -130.702304)
		(width 0.089408)
		(layer "In2.Cu")
		(net "LED_PCH_SATA_HDD_N")
	)
	(segment
		(start 496.182904 -137.470896)
		(end 496.182904 -134.730744)
		(width 0.089408)
		(layer "In2.Cu")
		(net "LED_PCH_SATA_HDD_N")
	)
	(segment
		(start 441.905644 -130.702304)
		(end 443.251336 -132.047996)
		(width 0.089408)
		(layer "In2.Cu")
		(net "LED_PCH_SATA_HDD_N")
	)
	(segment
		(start 471.95359 -140.976096)
		(end 471.985848 -140.976096)
		(width 0.089408)
		(layer "In2.Cu")
		(net "LED_PCH_SATA_HDD_N")
	)
	(segment
		(start 493.121696 -121.672096)
		(end 492.506 -121.0564)
		(width 0.089408)
		(layer "In2.Cu")
		(net "LED_PCH_SATA_HDD_N")
	)
	(segment
		(start 448.64147 -131.723384)
		(end 450.417184 -131.723384)
		(width 0.089408)
		(layer "In2.Cu")
		(net "LED_PCH_SATA_HDD_N")
	)
	(segment
		(start 396.10792 -129.311654)
		(end 396.57909 -129.782824)
		(width 0.089408)
		(layer "In2.Cu")
		(net "LED_PCH_SATA_HDD_N")
	)
	(segment
		(start 490.799374 -142.080488)
		(end 491.513622 -142.080488)
		(width 0.089408)
		(layer "In2.Cu")
		(net "LED_PCH_SATA_HDD_N")
	)
	(segment
		(start 489.653326 -149.061424)
		(end 489.653326 -143.226536)
		(width 0.089408)
		(layer "In2.Cu")
		(net "LED_PCH_SATA_HDD_N")
	)
	(segment
		(start 472.802712 -141.674596)
		(end 475.850204 -144.722088)
		(width 0.089408)
		(layer "In2.Cu")
		(net "LED_PCH_SATA_HDD_N")
	)
	(segment
		(start 394.598144 -125.507496)
		(end 395.237716 -125.507496)
		(width 0.089408)
		(layer "In2.Cu")
		(net "LED_PCH_SATA_HDD_N")
	)
	(segment
		(start 469.949784 -141.674596)
		(end 470.955624 -141.674596)
		(width 0.089408)
		(layer "In2.Cu")
		(net "LED_PCH_SATA_HDD_N")
	)
	(segment
		(start 464.981036 -141.926564)
		(end 469.697816 -141.926564)
		(width 0.089408)
		(layer "In2.Cu")
		(net "LED_PCH_SATA_HDD_N")
	)
	(segment
		(start 489.628434 -150.002748)
		(end 489.628434 -149.086316)
		(width 0.089408)
		(layer "In2.Cu")
		(net "LED_PCH_SATA_HDD_N")
	)
	(segment
		(start 431.51679 -130.524504)
		(end 433.325016 -130.524504)
		(width 0.089408)
		(layer "In2.Cu")
		(net "LED_PCH_SATA_HDD_N")
	)
	(segment
		(start 417.400232 -129.022856)
		(end 417.409376 -129.022856)
		(width 0.089408)
		(layer "In2.Cu")
		(net "LED_PCH_SATA_HDD_N")
	)
	(segment
		(start 471.985848 -140.976096)
		(end 472.684348 -141.674596)
		(width 0.089408)
		(layer "In2.Cu")
		(net "LED_PCH_SATA_HDD_N")
	)
	(segment
		(start 458.953108 -142.802102)
		(end 464.105498 -142.802102)
		(width 0.089408)
		(layer "In2.Cu")
		(net "LED_PCH_SATA_HDD_N")
	)
	(segment
		(start 493.392206 -140.201904)
		(end 494.41735 -140.201904)
		(width 0.089408)
		(layer "In2.Cu")
		(net "LED_PCH_SATA_HDD_N")
	)
	(segment
		(start 495.046 -139.573254)
		(end 495.046 -138.6078)
		(width 0.089408)
		(layer "In2.Cu")
		(net "LED_PCH_SATA_HDD_N")
	)
	(segment
		(start 447.5734 -132.7658)
		(end 447.929 -132.7658)
		(width 0.089408)
		(layer "In2.Cu")
		(net "LED_PCH_SATA_HDD_N")
	)
	(segment
		(start 472.684348 -141.674596)
		(end 472.802712 -141.674596)
		(width 0.089408)
		(layer "In2.Cu")
		(net "LED_PCH_SATA_HDD_N")
	)
	(arc
		(start 392.7856 -121.25706)
		(mid 392.84195 -121.45091)
		(end 392.985752 -121.592594)
		(width 0.0889)
		(layer "In2.Cu")
		(net "LED_PCH_SATA_HDD_N")
	)
	(arc
		(start 392.985752 -121.592594)
		(mid 393.196616 -121.799598)
		(end 393.2809 -122.082814)
		(width 0.0889)
		(layer "In2.Cu")
		(net "LED_PCH_SATA_HDD_N")
	)
	(arc
		(start 391.66165 -119.154448)
		(mid 391.757223 -119.319928)
		(end 391.795 -119.507254)
		(width 0.0889)
		(layer "In2.Cu")
		(net "LED_PCH_SATA_HDD_N")
	)
	(arc
		(start 392.2903 -120.39854)
		(mid 392.34665 -120.59239)
		(end 392.490452 -120.734074)
		(width 0.0889)
		(layer "In2.Cu")
		(net "LED_PCH_SATA_HDD_N")
	)
	(arc
		(start 392.985752 -122.616214)
		(mid 392.785441 -122.962924)
		(end 392.985752 -123.309634)
		(width 0.0889)
		(layer "In2.Cu")
		(net "LED_PCH_SATA_HDD_N")
	)
	(arc
		(start 391.69975 -118.670324)
		(mid 391.583362 -118.904715)
		(end 391.66165 -119.154448)
		(width 0.0889)
		(layer "In2.Cu")
		(net "LED_PCH_SATA_HDD_N")
	)
	(arc
		(start 393.2809 -122.125994)
		(mid 393.196619 -122.409211)
		(end 392.985752 -122.616214)
		(width 0.0889)
		(layer "In2.Cu")
		(net "LED_PCH_SATA_HDD_N")
	)
	(arc
		(start 392.985752 -123.309634)
		(mid 393.196616 -123.516638)
		(end 393.2809 -123.799854)
		(width 0.0889)
		(layer "In2.Cu")
		(net "LED_PCH_SATA_HDD_N")
	)
	(arc
		(start 392.490452 -120.734074)
		(mid 392.701316 -120.941078)
		(end 392.7856 -121.224294)
		(width 0.0889)
		(layer "In2.Cu")
		(net "LED_PCH_SATA_HDD_N")
	)
	(arc
		(start 391.995152 -119.875554)
		(mid 392.206016 -120.082558)
		(end 392.2903 -120.365774)
		(width 0.0889)
		(layer "In2.Cu")
		(net "LED_PCH_SATA_HDD_N")
	)
	(arc
		(start 391.795 -119.54002)
		(mid 391.85135 -119.73387)
		(end 391.995152 -119.875554)
		(width 0.0889)
		(layer "In2.Cu")
		(net "LED_PCH_SATA_HDD_N")
	)
	(segment
		(start 478.8027 -144.3482)
		(end 479.15576 -144.3482)
		(width 0.10795)
		(layer "F.Cu")
		(net "FP_RST_BTN_R_N")
	)
	(segment
		(start 479.15576 -144.3482)
		(end 479.15576 -142.98295)
		(width 0.10795)
		(layer "F.Cu")
		(net "FP_RST_BTN_R_N")
	)
	(segment
		(start 479.26371 -142.875)
		(end 479.6155 -142.875)
		(width 0.10795)
		(layer "F.Cu")
		(net "FP_RST_BTN_R_N")
	)
	(segment
		(start 478.1042 -143.6497)
		(end 478.8027 -144.3482)
		(width 0.10795)
		(layer "F.Cu")
		(net "FP_RST_BTN_R_N")
	)
	(segment
		(start 479.15576 -142.98295)
		(end 479.26371 -142.875)
		(width 0.10795)
		(layer "F.Cu")
		(net "FP_RST_BTN_R_N")
	)
	(via
		(at 478.1042 -143.6497)
		(size 0.508)
		(drill 0.254)
		(layers "F.Cu" "B.Cu")
		(net "FP_RST_BTN_R_N")
	)
	(via
		(at 487.39552 -148.96084)
		(size 0.508)
		(drill 0.254)
		(layers "F.Cu" "B.Cu")
		(net "FP_RST_BTN_R_N")
	)
	(segment
		(start 489.26496 -150.18004)
		(end 488.50042 -149.4155)
		(width 0.10795)
		(layer "B.Cu")
		(net "FP_RST_BTN_R_N")
	)
	(segment
		(start 488.50042 -149.4155)
		(end 487.85018 -149.4155)
		(width 0.10795)
		(layer "B.Cu")
		(net "FP_RST_BTN_R_N")
	)
	(segment
		(start 487.85018 -149.4155)
		(end 487.39552 -148.96084)
		(width 0.10795)
		(layer "B.Cu")
		(net "FP_RST_BTN_R_N")
	)
	(segment
		(start 478.413318 -143.958818)
		(end 478.1042 -143.6497)
		(width 0.089408)
		(layer "In2.Cu")
		(net "FP_RST_BTN_R_N")
	)
	(segment
		(start 487.39552 -148.96084)
		(end 484.76535 -148.96084)
		(width 0.089408)
		(layer "In2.Cu")
		(net "FP_RST_BTN_R_N")
	)
	(segment
		(start 484.76535 -148.96084)
		(end 479.763328 -143.958818)
		(width 0.089408)
		(layer "In2.Cu")
		(net "FP_RST_BTN_R_N")
	)
	(segment
		(start 479.763328 -143.958818)
		(end 478.413318 -143.958818)
		(width 0.089408)
		(layer "In2.Cu")
		(net "FP_RST_BTN_R_N")
	)
	(segment
		(start 480.314 -145.288)
		(end 480.45624 -145.14576)
		(width 0.10795)
		(layer "F.Cu")
		(net "FP_RST_BTN_BUF1_N")
	)
	(segment
		(start 479.15576 -145.55724)
		(end 479.425 -145.288)
		(width 0.10795)
		(layer "F.Cu")
		(net "FP_RST_BTN_BUF1_N")
	)
	(segment
		(start 479.425 -145.288)
		(end 480.314 -145.288)
		(width 0.10795)
		(layer "F.Cu")
		(net "FP_RST_BTN_BUF1_N")
	)
	(segment
		(start 480.45624 -145.14576)
		(end 480.45624 -144.3482)
		(width 0.10795)
		(layer "F.Cu")
		(net "FP_RST_BTN_BUF1_N")
	)
	(segment
		(start 479.15576 -146.2278)
		(end 479.15576 -145.55724)
		(width 0.10795)
		(layer "F.Cu")
		(net "FP_RST_BTN_BUF1_N")
	)
	(segment
		(start 483.080822 -141.682978)
		(end 483.058216 -141.682978)
		(width 0.10795)
		(layer "F.Cu")
		(net "FP_PWR_BTN_R_N")
	)
	(segment
		(start 483.4636 -145.0086)
		(end 483.058216 -145.413984)
		(width 0.10795)
		(layer "F.Cu")
		(net "FP_PWR_BTN_R_N")
	)
	(segment
		(start 483.058216 -143.942816)
		(end 483.4636 -144.3482)
		(width 0.10795)
		(layer "F.Cu")
		(net "FP_PWR_BTN_R_N")
	)
	(segment
		(start 484.0732 -140.6906)
		(end 483.080822 -141.682978)
		(width 0.10795)
		(layer "F.Cu")
		(net "FP_PWR_BTN_R_N")
	)
	(segment
		(start 483.058216 -145.413984)
		(end 483.058216 -146.508978)
		(width 0.10795)
		(layer "F.Cu")
		(net "FP_PWR_BTN_R_N")
	)
	(segment
		(start 483.058216 -141.682978)
		(end 483.058216 -143.942816)
		(width 0.10795)
		(layer "F.Cu")
		(net "FP_PWR_BTN_R_N")
	)
	(segment
		(start 485.394 -141.4018)
		(end 484.6828 -140.6906)
		(width 0.10795)
		(layer "F.Cu")
		(net "FP_PWR_BTN_R_N")
	)
	(segment
		(start 484.6828 -140.6906)
		(end 484.0732 -140.6906)
		(width 0.10795)
		(layer "F.Cu")
		(net "FP_PWR_BTN_R_N")
	)
	(segment
		(start 483.4636 -144.3482)
		(end 483.4636 -145.0086)
		(width 0.10795)
		(layer "F.Cu")
		(net "FP_PWR_BTN_R_N")
	)
	(via
		(at 485.394 -141.4018)
		(size 0.508)
		(drill 0.254)
		(layers "F.Cu" "B.Cu")
		(net "FP_PWR_BTN_R_N")
	)
	(via
		(at 471.3605 -139.192)
		(size 0.508)
		(drill 0.254)
		(layers "F.Cu" "B.Cu")
		(net "FP_PWR_BTN_R_N")
	)
	(via
		(at 470.45626 -136.59104)
		(size 0.6604)
		(drill 0.3302)
		(layers "F.Cu" "B.Cu")
		(net "FP_PWR_BTN_R_N")
	)
	(segment
		(start 471.3605 -138.557)
		(end 471.3605 -137.795)
		(width 0.10795)
		(layer "B.Cu")
		(net "FP_PWR_BTN_R_N")
	)
	(segment
		(start 470.45626 -136.59104)
		(end 471.3605 -137.49528)
		(width 0.1016)
		(layer "B.Cu")
		(net "FP_PWR_BTN_R_N")
	)
	(segment
		(start 471.3605 -138.557)
		(end 471.3605 -139.192)
		(width 0.10795)
		(layer "B.Cu")
		(net "FP_PWR_BTN_R_N")
	)
	(segment
		(start 471.3605 -137.795)
		(end 471.368628 -137.786872)
		(width 0.10795)
		(layer "B.Cu")
		(net "FP_PWR_BTN_R_N")
	)
	(segment
		(start 471.3605 -137.49528)
		(end 471.3605 -137.795)
		(width 0.1016)
		(layer "B.Cu")
		(net "FP_PWR_BTN_R_N")
	)
	(segment
		(start 471.368628 -137.786872)
		(end 473.660216 -137.786872)
		(width 0.10795)
		(layer "B.Cu")
		(net "FP_PWR_BTN_R_N")
	)
	(segment
		(start 474.847412 -140.042392)
		(end 473.323412 -140.042392)
		(width 0.089408)
		(layer "In9.Cu")
		(net "FP_PWR_BTN_R_N")
	)
	(segment
		(start 485.145588 -142.201392)
		(end 477.006412 -142.201392)
		(width 0.089408)
		(layer "In9.Cu")
		(net "FP_PWR_BTN_R_N")
	)
	(segment
		(start 472.313 -139.192)
		(end 471.3605 -139.192)
		(width 0.089408)
		(layer "In9.Cu")
		(net "FP_PWR_BTN_R_N")
	)
	(segment
		(start 485.394 -141.95298)
		(end 485.145588 -142.201392)
		(width 0.089408)
		(layer "In9.Cu")
		(net "FP_PWR_BTN_R_N")
	)
	(segment
		(start 472.715844 -139.434824)
		(end 472.555824 -139.434824)
		(width 0.089408)
		(layer "In9.Cu")
		(net "FP_PWR_BTN_R_N")
	)
	(segment
		(start 485.394 -141.4018)
		(end 485.394 -141.95298)
		(width 0.089408)
		(layer "In9.Cu")
		(net "FP_PWR_BTN_R_N")
	)
	(segment
		(start 472.555824 -139.434824)
		(end 472.313 -139.192)
		(width 0.089408)
		(layer "In9.Cu")
		(net "FP_PWR_BTN_R_N")
	)
	(segment
		(start 477.006412 -142.201392)
		(end 474.847412 -140.042392)
		(width 0.089408)
		(layer "In9.Cu")
		(net "FP_PWR_BTN_R_N")
	)
	(segment
		(start 473.323412 -140.042392)
		(end 472.715844 -139.434824)
		(width 0.089408)
		(layer "In9.Cu")
		(net "FP_PWR_BTN_R_N")
	)
	(segment
		(start 481.09124 -140.21816)
		(end 480.1616 -140.21816)
		(width 0.10795)
		(layer "F.Cu")
		(net "FP_PWR_BTN_R1_N")
	)
	(segment
		(start 481.9142 -139.3952)
		(end 481.09124 -140.21816)
		(width 0.10795)
		(layer "F.Cu")
		(net "FP_PWR_BTN_R1_N")
	)
	(via
		(at 481.9142 -139.3952)
		(size 0.508)
		(drill 0.254)
		(layers "F.Cu" "B.Cu")
		(net "FP_PWR_BTN_R1_N")
	)
	(via
		(at 469.15578 -136.55294)
		(size 0.508)
		(drill 0.254)
		(layers "F.Cu" "B.Cu")
		(net "FP_PWR_BTN_R1_N")
	)
	(segment
		(start 469.63838 -137.72388)
		(end 469.7095 -137.795)
		(width 0.10795)
		(layer "B.Cu")
		(net "FP_PWR_BTN_R1_N")
	)
	(segment
		(start 469.63838 -137.03554)
		(end 469.63838 -137.72388)
		(width 0.10795)
		(layer "B.Cu")
		(net "FP_PWR_BTN_R1_N")
	)
	(segment
		(start 469.15578 -136.55294)
		(end 469.63838 -137.03554)
		(width 0.10795)
		(layer "B.Cu")
		(net "FP_PWR_BTN_R1_N")
	)
	(segment
		(start 470.4715 -137.795)
		(end 469.7095 -137.795)
		(width 0.10795)
		(layer "B.Cu")
		(net "FP_PWR_BTN_R1_N")
	)
	(segment
		(start 480.4918 -140.0556)
		(end 474.388434 -140.0556)
		(width 0.089408)
		(layer "In2.Cu")
		(net "FP_PWR_BTN_R1_N")
	)
	(segment
		(start 481.1522 -139.3952)
		(end 480.4918 -140.0556)
		(width 0.089408)
		(layer "In2.Cu")
		(net "FP_PWR_BTN_R1_N")
	)
	(segment
		(start 474.388434 -140.0556)
		(end 470.885774 -136.55294)
		(width 0.089408)
		(layer "In2.Cu")
		(net "FP_PWR_BTN_R1_N")
	)
	(segment
		(start 481.9142 -139.3952)
		(end 481.1522 -139.3952)
		(width 0.089408)
		(layer "In2.Cu")
		(net "FP_PWR_BTN_R1_N")
	)
	(segment
		(start 470.885774 -136.55294)
		(end 469.15578 -136.55294)
		(width 0.089408)
		(layer "In2.Cu")
		(net "FP_PWR_BTN_R1_N")
	)
	(segment
		(start 478.282 -140.21816)
		(end 478.990406 -140.21816)
		(width 0.10795)
		(layer "F.Cu")
		(net "FP_PWR_BTN_BUF1_N")
	)
	(segment
		(start 479.2472 -140.474954)
		(end 479.2472 -141.3002)
		(width 0.10795)
		(layer "F.Cu")
		(net "FP_PWR_BTN_BUF1_N")
	)
	(segment
		(start 478.990406 -140.21816)
		(end 479.2472 -140.474954)
		(width 0.10795)
		(layer "F.Cu")
		(net "FP_PWR_BTN_BUF1_N")
	)
	(segment
		(start 479.2472 -141.3002)
		(end 479.46564 -141.51864)
		(width 0.10795)
		(layer "F.Cu")
		(net "FP_PWR_BTN_BUF1_N")
	)
	(segment
		(start 479.46564 -141.51864)
		(end 480.1616 -141.51864)
		(width 0.10795)
		(layer "F.Cu")
		(net "FP_PWR_BTN_BUF1_N")
	)
	(segment
		(start 478.282 -141.9733)
		(end 478.282 -141.51864)
		(width 0.10795)
		(layer "F.Cu")
		(net "FM_PWR_BTN_R_N")
	)
	(segment
		(start 478.5995 -142.2908)
		(end 478.282 -141.9733)
		(width 0.10795)
		(layer "F.Cu")
		(net "FM_PWR_BTN_R_N")
	)
	(segment
		(start 478.5995 -142.875)
		(end 478.5995 -142.2908)
		(width 0.10795)
		(layer "F.Cu")
		(net "FM_PWR_BTN_R_N")
	)
	(segment
		(start 477.23425 -142.98295)
		(end 477.23425 -143.63065)
		(width 0.10795)
		(layer "F.Cu")
		(net "FM_PWR_BTN_N")
	)
	(segment
		(start 477.3422 -142.875)
		(end 477.23425 -142.98295)
		(width 0.10795)
		(layer "F.Cu")
		(net "FM_PWR_BTN_N")
	)
	(segment
		(start 395.66215 -102.12832)
		(end 396.15745 -101.898196)
		(width 0.10795)
		(layer "F.Cu")
		(net "FM_PWR_BTN_N")
	)
	(segment
		(start 477.7105 -142.875)
		(end 477.3422 -142.875)
		(width 0.10795)
		(layer "F.Cu")
		(net "FM_PWR_BTN_N")
	)
	(via
		(at 477.23425 -143.63065)
		(size 0.508)
		(drill 0.254)
		(layers "F.Cu" "B.Cu")
		(net "FM_PWR_BTN_N")
	)
	(via
		(at 413.24149 -55.31485)
		(size 0.508)
		(drill 0.254)
		(layers "F.Cu" "B.Cu")
		(net "FM_PWR_BTN_N")
	)
	(via
		(at 396.15745 -101.898196)
		(size 0.508)
		(drill 0.254)
		(layers "F.Cu" "B.Cu")
		(net "FM_PWR_BTN_N")
	)
	(via
		(at 404.2029 -113.1062)
		(size 0.508)
		(drill 0.254)
		(layers "F.Cu" "B.Cu")
		(net "FM_PWR_BTN_N")
	)
	(via
		(at 375.567448 -91.86418)
		(size 0.508)
		(drill 0.254)
		(layers "F.Cu" "B.Cu")
		(net "FM_PWR_BTN_N")
	)
	(via
		(at 407.498804 -51.644804)
		(size 0.6604)
		(drill 0.3302)
		(layers "F.Cu" "B.Cu")
		(net "FM_PWR_BTN_N")
	)
	(via
		(at 401.785836 -80.922114)
		(size 0.508)
		(drill 0.254)
		(layers "F.Cu" "B.Cu")
		(net "FM_PWR_BTN_N")
	)
	(segment
		(start 376.215656 -92.173298)
		(end 375.876566 -92.173298)
		(width 0.10795)
		(layer "B.Cu")
		(net "FM_PWR_BTN_N")
	)
	(segment
		(start 408.71902 -55.05196)
		(end 408.71902 -52.6034)
		(width 0.10795)
		(layer "B.Cu")
		(net "FM_PWR_BTN_N")
	)
	(segment
		(start 409.192222 -55.525162)
		(end 408.71902 -55.05196)
		(width 0.10795)
		(layer "B.Cu")
		(net "FM_PWR_BTN_N")
	)
	(segment
		(start 413.24149 -55.31485)
		(end 412.537402 -54.610762)
		(width 0.10795)
		(layer "B.Cu")
		(net "FM_PWR_BTN_N")
	)
	(segment
		(start 407.498804 -51.644804)
		(end 406.7937 -50.9397)
		(width 0.10795)
		(layer "B.Cu")
		(net "FM_PWR_BTN_N")
	)
	(segment
		(start 407.760932 -51.906932)
		(end 407.498804 -51.644804)
		(width 0.10795)
		(layer "B.Cu")
		(net "FM_PWR_BTN_N")
	)
	(segment
		(start 406.7937 -50.9397)
		(end 406.33396 -50.9397)
		(width 0.10795)
		(layer "B.Cu")
		(net "FM_PWR_BTN_N")
	)
	(segment
		(start 408.022552 -51.906932)
		(end 407.760932 -51.906932)
		(width 0.10795)
		(layer "B.Cu")
		(net "FM_PWR_BTN_N")
	)
	(segment
		(start 410.714698 -54.610762)
		(end 409.800298 -55.525162)
		(width 0.10795)
		(layer "B.Cu")
		(net "FM_PWR_BTN_N")
	)
	(segment
		(start 408.71902 -52.6034)
		(end 408.022552 -51.906932)
		(width 0.10795)
		(layer "B.Cu")
		(net "FM_PWR_BTN_N")
	)
	(segment
		(start 412.537402 -54.610762)
		(end 410.714698 -54.610762)
		(width 0.10795)
		(layer "B.Cu")
		(net "FM_PWR_BTN_N")
	)
	(segment
		(start 375.876566 -92.173298)
		(end 375.567448 -91.86418)
		(width 0.10795)
		(layer "B.Cu")
		(net "FM_PWR_BTN_N")
	)
	(segment
		(start 409.800298 -55.525162)
		(end 409.192222 -55.525162)
		(width 0.10795)
		(layer "B.Cu")
		(net "FM_PWR_BTN_N")
	)
	(segment
		(start 433.807616 -120.537478)
		(end 437.0324 -117.312694)
		(width 0.089408)
		(layer "In2.Cu")
		(net "FM_PWR_BTN_N")
	)
	(segment
		(start 396.15745 -100.75545)
		(end 395.986 -100.584)
		(width 0.089408)
		(layer "In2.Cu")
		(net "FM_PWR_BTN_N")
	)
	(segment
		(start 476.885 -120.9548)
		(end 477.4184 -121.4882)
		(width 0.089408)
		(layer "In2.Cu")
		(net "FM_PWR_BTN_N")
	)
	(segment
		(start 377.731274 -94.916752)
		(end 375.975626 -93.161104)
		(width 0.089408)
		(layer "In2.Cu")
		(net "FM_PWR_BTN_N")
	)
	(segment
		(start 395.605 -99.949)
		(end 395.224 -99.568)
		(width 0.089408)
		(layer "In2.Cu")
		(net "FM_PWR_BTN_N")
	)
	(segment
		(start 472.93022 -118.161054)
		(end 475.723966 -120.9548)
		(width 0.089408)
		(layer "In2.Cu")
		(net "FM_PWR_BTN_N")
	)
	(segment
		(start 418.268912 -120.4468)
		(end 420.957756 -120.4468)
		(width 0.089408)
		(layer "In2.Cu")
		(net "FM_PWR_BTN_N")
	)
	(segment
		(start 411.127194 -121.7803)
		(end 411.260798 -121.913904)
		(width 0.089408)
		(layer "In2.Cu")
		(net "FM_PWR_BTN_N")
	)
	(segment
		(start 487.27233 -132.473192)
		(end 490.729524 -132.473192)
		(width 0.089408)
		(layer "In2.Cu")
		(net "FM_PWR_BTN_N")
	)
	(segment
		(start 410.996892 -121.780554)
		(end 410.996892 -121.7803)
		(width 0.089408)
		(layer "In2.Cu")
		(net "FM_PWR_BTN_N")
	)
	(segment
		(start 395.262354 -97.370646)
		(end 395.605 -97.028)
		(width 0.089408)
		(layer "In2.Cu")
		(net "FM_PWR_BTN_N")
	)
	(segment
		(start 491.740952 -136.426702)
		(end 487.605832 -140.561822)
		(width 0.089408)
		(layer "In2.Cu")
		(net "FM_PWR_BTN_N")
	)
	(segment
		(start 411.260798 -121.913904)
		(end 416.801808 -121.913904)
		(width 0.089408)
		(layer "In2.Cu")
		(net "FM_PWR_BTN_N")
	)
	(segment
		(start 375.975626 -93.161104)
		(end 375.975626 -92.272358)
		(width 0.089408)
		(layer "In2.Cu")
		(net "FM_PWR_BTN_N")
	)
	(segment
		(start 375.975626 -92.272358)
		(end 375.567448 -91.86418)
		(width 0.089408)
		(layer "In2.Cu")
		(net "FM_PWR_BTN_N")
	)
	(segment
		(start 490.729524 -132.473192)
		(end 491.740952 -133.48462)
		(width 0.089408)
		(layer "In2.Cu")
		(net "FM_PWR_BTN_N")
	)
	(segment
		(start 466.116416 -117.680994)
		(end 469.224106 -117.680994)
		(width 0.089408)
		(layer "In2.Cu")
		(net "FM_PWR_BTN_N")
	)
	(segment
		(start 395.986 -100.584)
		(end 395.859 -100.584)
		(width 0.089408)
		(layer "In2.Cu")
		(net "FM_PWR_BTN_N")
	)
	(segment
		(start 409.392374 -121.780554)
		(end 410.996892 -121.780554)
		(width 0.089408)
		(layer "In2.Cu")
		(net "FM_PWR_BTN_N")
	)
	(segment
		(start 395.224 -99.568)
		(end 395.224 -99.06)
		(width 0.089408)
		(layer "In2.Cu")
		(net "FM_PWR_BTN_N")
	)
	(segment
		(start 395.605 -96.52)
		(end 395.224 -96.139)
		(width 0.089408)
		(layer "In2.Cu")
		(net "FM_PWR_BTN_N")
	)
	(segment
		(start 395.859 -100.584)
		(end 395.605 -100.33)
		(width 0.089408)
		(layer "In2.Cu")
		(net "FM_PWR_BTN_N")
	)
	(segment
		(start 475.723966 -120.9548)
		(end 476.885 -120.9548)
		(width 0.089408)
		(layer "In2.Cu")
		(net "FM_PWR_BTN_N")
	)
	(segment
		(start 395.224 -99.06)
		(end 395.605 -98.679)
		(width 0.089408)
		(layer "In2.Cu")
		(net "FM_PWR_BTN_N")
	)
	(segment
		(start 395.224 -96.139)
		(end 395.224 -95.25)
		(width 0.089408)
		(layer "In2.Cu")
		(net "FM_PWR_BTN_N")
	)
	(segment
		(start 479.298 -127.368554)
		(end 479.298 -127.37084)
		(width 0.089408)
		(layer "In2.Cu")
		(net "FM_PWR_BTN_N")
	)
	(segment
		(start 469.224106 -117.680994)
		(end 469.704166 -118.161054)
		(width 0.089408)
		(layer "In2.Cu")
		(net "FM_PWR_BTN_N")
	)
	(segment
		(start 477.4184 -121.4882)
		(end 477.4184 -125.488954)
		(width 0.089408)
		(layer "In2.Cu")
		(net "FM_PWR_BTN_N")
	)
	(segment
		(start 481.06076 -129.1336)
		(end 485.927146 -129.1336)
		(width 0.089408)
		(layer "In2.Cu")
		(net "FM_PWR_BTN_N")
	)
	(segment
		(start 483.912926 -140.561822)
		(end 481.288852 -143.185896)
		(width 0.089408)
		(layer "In2.Cu")
		(net "FM_PWR_BTN_N")
	)
	(segment
		(start 395.224 -95.25)
		(end 394.890752 -94.916752)
		(width 0.089408)
		(layer "In2.Cu")
		(net "FM_PWR_BTN_N")
	)
	(segment
		(start 437.0324 -117.312694)
		(end 465.748116 -117.312694)
		(width 0.089408)
		(layer "In2.Cu")
		(net "FM_PWR_BTN_N")
	)
	(segment
		(start 481.288852 -143.185896)
		(end 477.679004 -143.185896)
		(width 0.089408)
		(layer "In2.Cu")
		(net "FM_PWR_BTN_N")
	)
	(segment
		(start 465.748116 -117.312694)
		(end 466.116416 -117.680994)
		(width 0.089408)
		(layer "In2.Cu")
		(net "FM_PWR_BTN_N")
	)
	(segment
		(start 428.000668 -120.537478)
		(end 433.807616 -120.537478)
		(width 0.089408)
		(layer "In2.Cu")
		(net "FM_PWR_BTN_N")
	)
	(segment
		(start 469.704166 -118.161054)
		(end 472.93022 -118.161054)
		(width 0.089408)
		(layer "In2.Cu")
		(net "FM_PWR_BTN_N")
	)
	(segment
		(start 486.778808 -131.97967)
		(end 487.27233 -132.473192)
		(width 0.089408)
		(layer "In2.Cu")
		(net "FM_PWR_BTN_N")
	)
	(segment
		(start 410.996892 -121.7803)
		(end 411.127194 -121.7803)
		(width 0.089408)
		(layer "In2.Cu")
		(net "FM_PWR_BTN_N")
	)
	(segment
		(start 487.605832 -140.561822)
		(end 483.912926 -140.561822)
		(width 0.089408)
		(layer "In2.Cu")
		(net "FM_PWR_BTN_N")
	)
	(segment
		(start 408.51963 -117.996462)
		(end 408.51963 -120.90781)
		(width 0.089408)
		(layer "In2.Cu")
		(net "FM_PWR_BTN_N")
	)
	(segment
		(start 479.298 -127.37084)
		(end 481.06076 -129.1336)
		(width 0.089408)
		(layer "In2.Cu")
		(net "FM_PWR_BTN_N")
	)
	(segment
		(start 395.605 -97.028)
		(end 395.605 -96.52)
		(width 0.089408)
		(layer "In2.Cu")
		(net "FM_PWR_BTN_N")
	)
	(segment
		(start 406.508966 -115.985798)
		(end 408.51963 -117.996462)
		(width 0.089408)
		(layer "In2.Cu")
		(net "FM_PWR_BTN_N")
	)
	(segment
		(start 408.51963 -120.90781)
		(end 409.392374 -121.780554)
		(width 0.089408)
		(layer "In2.Cu")
		(net "FM_PWR_BTN_N")
	)
	(segment
		(start 395.262354 -97.828354)
		(end 395.262354 -97.370646)
		(width 0.089408)
		(layer "In2.Cu")
		(net "FM_PWR_BTN_N")
	)
	(segment
		(start 395.605 -100.33)
		(end 395.605 -99.949)
		(width 0.089408)
		(layer "In2.Cu")
		(net "FM_PWR_BTN_N")
	)
	(segment
		(start 406.508966 -115.412266)
		(end 406.508966 -115.985798)
		(width 0.089408)
		(layer "In2.Cu")
		(net "FM_PWR_BTN_N")
	)
	(segment
		(start 477.4184 -125.488954)
		(end 479.298 -127.368554)
		(width 0.089408)
		(layer "In2.Cu")
		(net "FM_PWR_BTN_N")
	)
	(segment
		(start 395.605 -98.171)
		(end 395.262354 -97.828354)
		(width 0.089408)
		(layer "In2.Cu")
		(net "FM_PWR_BTN_N")
	)
	(segment
		(start 420.957756 -120.4468)
		(end 421.285924 -120.774968)
		(width 0.089408)
		(layer "In2.Cu")
		(net "FM_PWR_BTN_N")
	)
	(segment
		(start 421.285924 -120.774968)
		(end 427.763178 -120.774968)
		(width 0.089408)
		(layer "In2.Cu")
		(net "FM_PWR_BTN_N")
	)
	(segment
		(start 394.890752 -94.916752)
		(end 377.731274 -94.916752)
		(width 0.089408)
		(layer "In2.Cu")
		(net "FM_PWR_BTN_N")
	)
	(segment
		(start 477.679004 -143.185896)
		(end 477.23425 -143.63065)
		(width 0.089408)
		(layer "In2.Cu")
		(net "FM_PWR_BTN_N")
	)
	(segment
		(start 395.605 -98.679)
		(end 395.605 -98.171)
		(width 0.089408)
		(layer "In2.Cu")
		(net "FM_PWR_BTN_N")
	)
	(segment
		(start 485.927146 -129.1336)
		(end 486.778808 -129.985262)
		(width 0.089408)
		(layer "In2.Cu")
		(net "FM_PWR_BTN_N")
	)
	(segment
		(start 396.15745 -101.898196)
		(end 396.15745 -100.75545)
		(width 0.089408)
		(layer "In2.Cu")
		(net "FM_PWR_BTN_N")
	)
	(segment
		(start 416.801808 -121.913904)
		(end 418.268912 -120.4468)
		(width 0.089408)
		(layer "In2.Cu")
		(net "FM_PWR_BTN_N")
	)
	(segment
		(start 491.740952 -133.48462)
		(end 491.740952 -136.426702)
		(width 0.089408)
		(layer "In2.Cu")
		(net "FM_PWR_BTN_N")
	)
	(segment
		(start 404.2029 -113.1062)
		(end 406.508966 -115.412266)
		(width 0.089408)
		(layer "In2.Cu")
		(net "FM_PWR_BTN_N")
	)
	(segment
		(start 427.763178 -120.774968)
		(end 428.000668 -120.537478)
		(width 0.089408)
		(layer "In2.Cu")
		(net "FM_PWR_BTN_N")
	)
	(segment
		(start 486.778808 -129.985262)
		(end 486.778808 -131.97967)
		(width 0.089408)
		(layer "In2.Cu")
		(net "FM_PWR_BTN_N")
	)
	(segment
		(start 388.13613 -84.57692)
		(end 388.858506 -83.854544)
		(width 0.089408)
		(layer "In4.Cu")
		(net "FM_PWR_BTN_N")
	)
	(segment
		(start 381.88646 -86.35746)
		(end 381.88646 -85.72246)
		(width 0.089408)
		(layer "In4.Cu")
		(net "FM_PWR_BTN_N")
	)
	(segment
		(start 378.829062 -87.541608)
		(end 380.702312 -87.541608)
		(width 0.089408)
		(layer "In4.Cu")
		(net "FM_PWR_BTN_N")
	)
	(segment
		(start 389.784336 -83.854544)
		(end 390.563862 -83.075018)
		(width 0.089408)
		(layer "In4.Cu")
		(net "FM_PWR_BTN_N")
	)
	(segment
		(start 396.608554 -102.3493)
		(end 399.6055 -102.3493)
		(width 0.089408)
		(layer "In4.Cu")
		(net "FM_PWR_BTN_N")
	)
	(segment
		(start 396.15745 -101.898196)
		(end 396.608554 -102.3493)
		(width 0.089408)
		(layer "In4.Cu")
		(net "FM_PWR_BTN_N")
	)
	(segment
		(start 403.5679 -108.7628)
		(end 404.7236 -108.7628)
		(width 0.089408)
		(layer "In4.Cu")
		(net "FM_PWR_BTN_N")
	)
	(segment
		(start 388.858506 -83.854544)
		(end 389.784336 -83.854544)
		(width 0.089408)
		(layer "In4.Cu")
		(net "FM_PWR_BTN_N")
	)
	(segment
		(start 391.975086 -83.075018)
		(end 392.818874 -82.23123)
		(width 0.089408)
		(layer "In4.Cu")
		(net "FM_PWR_BTN_N")
	)
	(segment
		(start 375.705624 -91.726004)
		(end 377.097798 -91.726004)
		(width 0.089408)
		(layer "In4.Cu")
		(net "FM_PWR_BTN_N")
	)
	(segment
		(start 400.9136 -106.1085)
		(end 403.5679 -108.7628)
		(width 0.089408)
		(layer "In4.Cu")
		(net "FM_PWR_BTN_N")
	)
	(segment
		(start 383.945638 -84.95284)
		(end 384.321558 -84.57692)
		(width 0.089408)
		(layer "In4.Cu")
		(net "FM_PWR_BTN_N")
	)
	(segment
		(start 375.567448 -91.86418)
		(end 375.705624 -91.726004)
		(width 0.089408)
		(layer "In4.Cu")
		(net "FM_PWR_BTN_N")
	)
	(segment
		(start 382.65608 -84.95284)
		(end 383.945638 -84.95284)
		(width 0.089408)
		(layer "In4.Cu")
		(net "FM_PWR_BTN_N")
	)
	(segment
		(start 407.4922 -112.6236)
		(end 407.4922 -113.3856)
		(width 0.089408)
		(layer "In4.Cu")
		(net "FM_PWR_BTN_N")
	)
	(segment
		(start 405.0919 -113.9952)
		(end 404.2029 -113.1062)
		(width 0.089408)
		(layer "In4.Cu")
		(net "FM_PWR_BTN_N")
	)
	(segment
		(start 377.413266 -91.410536)
		(end 377.413266 -88.957404)
		(width 0.089408)
		(layer "In4.Cu")
		(net "FM_PWR_BTN_N")
	)
	(segment
		(start 399.6055 -102.3493)
		(end 400.9136 -103.6574)
		(width 0.089408)
		(layer "In4.Cu")
		(net "FM_PWR_BTN_N")
	)
	(segment
		(start 380.702312 -87.541608)
		(end 381.88646 -86.35746)
		(width 0.089408)
		(layer "In4.Cu")
		(net "FM_PWR_BTN_N")
	)
	(segment
		(start 377.413266 -88.957404)
		(end 378.829062 -87.541608)
		(width 0.089408)
		(layer "In4.Cu")
		(net "FM_PWR_BTN_N")
	)
	(segment
		(start 392.818874 -82.23123)
		(end 394.112242 -82.23123)
		(width 0.089408)
		(layer "In4.Cu")
		(net "FM_PWR_BTN_N")
	)
	(segment
		(start 406.8826 -113.9952)
		(end 405.0919 -113.9952)
		(width 0.089408)
		(layer "In4.Cu")
		(net "FM_PWR_BTN_N")
	)
	(segment
		(start 407.4922 -113.3856)
		(end 406.8826 -113.9952)
		(width 0.089408)
		(layer "In4.Cu")
		(net "FM_PWR_BTN_N")
	)
	(segment
		(start 401.716494 -80.852772)
		(end 401.785836 -80.922114)
		(width 0.089408)
		(layer "In4.Cu")
		(net "FM_PWR_BTN_N")
	)
	(segment
		(start 400.9136 -103.6574)
		(end 400.9136 -106.1085)
		(width 0.089408)
		(layer "In4.Cu")
		(net "FM_PWR_BTN_N")
	)
	(segment
		(start 400.204178 -80.852772)
		(end 401.716494 -80.852772)
		(width 0.089408)
		(layer "In4.Cu")
		(net "FM_PWR_BTN_N")
	)
	(segment
		(start 394.701268 -81.642204)
		(end 399.07591 -81.642204)
		(width 0.089408)
		(layer "In4.Cu")
		(net "FM_PWR_BTN_N")
	)
	(segment
		(start 377.097798 -91.726004)
		(end 377.413266 -91.410536)
		(width 0.089408)
		(layer "In4.Cu")
		(net "FM_PWR_BTN_N")
	)
	(segment
		(start 384.321558 -84.57692)
		(end 388.13613 -84.57692)
		(width 0.089408)
		(layer "In4.Cu")
		(net "FM_PWR_BTN_N")
	)
	(segment
		(start 399.07591 -81.642204)
		(end 399.387822 -81.330292)
		(width 0.089408)
		(layer "In4.Cu")
		(net "FM_PWR_BTN_N")
	)
	(segment
		(start 404.7236 -108.7628)
		(end 405.4221 -109.4613)
		(width 0.089408)
		(layer "In4.Cu")
		(net "FM_PWR_BTN_N")
	)
	(segment
		(start 405.4221 -109.4613)
		(end 405.4221 -109.470444)
		(width 0.089408)
		(layer "In4.Cu")
		(net "FM_PWR_BTN_N")
	)
	(segment
		(start 405.4221 -109.470444)
		(end 405.549608 -109.597952)
		(width 0.089408)
		(layer "In4.Cu")
		(net "FM_PWR_BTN_N")
	)
	(segment
		(start 399.726658 -81.330292)
		(end 400.204178 -80.852772)
		(width 0.089408)
		(layer "In4.Cu")
		(net "FM_PWR_BTN_N")
	)
	(segment
		(start 381.88646 -85.72246)
		(end 382.65608 -84.95284)
		(width 0.089408)
		(layer "In4.Cu")
		(net "FM_PWR_BTN_N")
	)
	(segment
		(start 399.387822 -81.330292)
		(end 399.726658 -81.330292)
		(width 0.089408)
		(layer "In4.Cu")
		(net "FM_PWR_BTN_N")
	)
	(segment
		(start 405.549608 -109.597952)
		(end 405.549608 -110.681008)
		(width 0.089408)
		(layer "In4.Cu")
		(net "FM_PWR_BTN_N")
	)
	(segment
		(start 405.549608 -110.681008)
		(end 407.4922 -112.6236)
		(width 0.089408)
		(layer "In4.Cu")
		(net "FM_PWR_BTN_N")
	)
	(segment
		(start 394.112242 -82.23123)
		(end 394.701268 -81.642204)
		(width 0.089408)
		(layer "In4.Cu")
		(net "FM_PWR_BTN_N")
	)
	(segment
		(start 390.563862 -83.075018)
		(end 391.975086 -83.075018)
		(width 0.089408)
		(layer "In4.Cu")
		(net "FM_PWR_BTN_N")
	)
	(segment
		(start 410.75229 -60.696856)
		(end 410.75229 -67.578224)
		(width 0.089408)
		(layer "In9.Cu")
		(net "FM_PWR_BTN_N")
	)
	(segment
		(start 404.065486 -80.518254)
		(end 403.55266 -81.03108)
		(width 0.089408)
		(layer "In9.Cu")
		(net "FM_PWR_BTN_N")
	)
	(segment
		(start 404.092664 -79.7306)
		(end 404.314152 -79.952088)
		(width 0.089408)
		(layer "In9.Cu")
		(net "FM_PWR_BTN_N")
	)
	(segment
		(start 404.314152 -79.952088)
		(end 404.314152 -80.283812)
		(width 0.089408)
		(layer "In9.Cu")
		(net "FM_PWR_BTN_N")
	)
	(segment
		(start 411.525974 -55.408068)
		(end 410.601922 -56.33212)
		(width 0.089408)
		(layer "In9.Cu")
		(net "FM_PWR_BTN_N")
	)
	(segment
		(start 410.602176 -56.607964)
		(end 410.602176 -60.546742)
		(width 0.089408)
		(layer "In9.Cu")
		(net "FM_PWR_BTN_N")
	)
	(segment
		(start 410.602176 -60.546742)
		(end 410.75229 -60.696856)
		(width 0.089408)
		(layer "In9.Cu")
		(net "FM_PWR_BTN_N")
	)
	(segment
		(start 413.24149 -55.31485)
		(end 413.148272 -55.408068)
		(width 0.089408)
		(layer "In9.Cu")
		(net "FM_PWR_BTN_N")
	)
	(segment
		(start 410.601922 -56.60771)
		(end 410.602176 -56.607964)
		(width 0.089408)
		(layer "In9.Cu")
		(net "FM_PWR_BTN_N")
	)
	(segment
		(start 403.55266 -81.03108)
		(end 401.894802 -81.03108)
		(width 0.089408)
		(layer "In9.Cu")
		(net "FM_PWR_BTN_N")
	)
	(segment
		(start 404.092664 -74.505058)
		(end 404.092664 -79.7306)
		(width 0.089408)
		(layer "In9.Cu")
		(net "FM_PWR_BTN_N")
	)
	(segment
		(start 410.601922 -56.33212)
		(end 410.601922 -56.60771)
		(width 0.089408)
		(layer "In9.Cu")
		(net "FM_PWR_BTN_N")
	)
	(segment
		(start 408.034236 -70.296278)
		(end 408.034236 -70.563486)
		(width 0.089408)
		(layer "In9.Cu")
		(net "FM_PWR_BTN_N")
	)
	(segment
		(start 413.148272 -55.408068)
		(end 411.525974 -55.408068)
		(width 0.089408)
		(layer "In9.Cu")
		(net "FM_PWR_BTN_N")
	)
	(segment
		(start 401.894802 -81.03108)
		(end 401.785836 -80.922114)
		(width 0.089408)
		(layer "In9.Cu")
		(net "FM_PWR_BTN_N")
	)
	(segment
		(start 408.034236 -70.563486)
		(end 404.092664 -74.505058)
		(width 0.089408)
		(layer "In9.Cu")
		(net "FM_PWR_BTN_N")
	)
	(segment
		(start 410.75229 -67.578224)
		(end 408.034236 -70.296278)
		(width 0.089408)
		(layer "In9.Cu")
		(net "FM_PWR_BTN_N")
	)
	(segment
		(start 404.07971 -80.518254)
		(end 404.065486 -80.518254)
		(width 0.089408)
		(layer "In9.Cu")
		(net "FM_PWR_BTN_N")
	)
	(segment
		(start 404.314152 -80.283812)
		(end 404.07971 -80.518254)
		(width 0.089408)
		(layer "In9.Cu")
		(net "FM_PWR_BTN_N")
	)
	(segment
		(start 18.950432 -78.5876)
		(end 19.209004 -78.846172)
		(width 0.1016)
		(layer "F.Cu")
		(net "FM_P12V_HOTSWAP0_EN")
	)
	(segment
		(start 18.41119 -78.30439)
		(end 18.6944 -78.5876)
		(width 0.1016)
		(layer "F.Cu")
		(net "FM_P12V_HOTSWAP0_EN")
	)
	(segment
		(start 18.923 -79.629)
		(end 18.923 -79.317088)
		(width 0.1016)
		(layer "F.Cu")
		(net "FM_P12V_HOTSWAP0_EN")
	)
	(segment
		(start 19.2278 -79.012288)
		(end 19.2278 -78.846172)
		(width 0.1016)
		(layer "F.Cu")
		(net "FM_P12V_HOTSWAP0_EN")
	)
	(segment
		(start 18.923 -79.317088)
		(end 19.2278 -79.012288)
		(width 0.1016)
		(layer "F.Cu")
		(net "FM_P12V_HOTSWAP0_EN")
	)
	(segment
		(start 18.6944 -78.5876)
		(end 18.950432 -78.5876)
		(width 0.1016)
		(layer "F.Cu")
		(net "FM_P12V_HOTSWAP0_EN")
	)
	(segment
		(start 18.41119 -78.0415)
		(end 18.41119 -78.30439)
		(width 0.1016)
		(layer "F.Cu")
		(net "FM_P12V_HOTSWAP0_EN")
	)
	(segment
		(start 19.2278 -78.846172)
		(end 19.209004 -78.846172)
		(width 0.1016)
		(layer "F.Cu")
		(net "FM_P12V_HOTSWAP0_EN")
	)
	(via
		(at 19.209004 -78.846172)
		(size 0.508)
		(drill 0.254)
		(layers "F.Cu" "B.Cu")
		(net "FM_P12V_HOTSWAP0_EN")
	)
	(via
		(at 23.191724 -39.927276)
		(size 0.508)
		(drill 0.254)
		(layers "F.Cu" "B.Cu")
		(net "FM_P12V_HOTSWAP0_EN")
	)
	(segment
		(start 24.888952 -31.4833)
		(end 24.692356 -31.679896)
		(width 0.10795)
		(layer "B.Cu")
		(net "FM_P12V_HOTSWAP0_EN")
	)
	(segment
		(start 26.5557 -32.1564)
		(end 25.8826 -31.4833)
		(width 0.10795)
		(layer "B.Cu")
		(net "FM_P12V_HOTSWAP0_EN")
	)
	(segment
		(start 26.5557 -32.385)
		(end 26.5557 -32.1564)
		(width 0.10795)
		(layer "B.Cu")
		(net "FM_P12V_HOTSWAP0_EN")
	)
	(segment
		(start 23.876 -30.58922)
		(end 24.692356 -31.405576)
		(width 0.10795)
		(layer "B.Cu")
		(net "FM_P12V_HOTSWAP0_EN")
	)
	(segment
		(start 26.7462 -37.7698)
		(end 26.7462 -32.5755)
		(width 0.10795)
		(layer "B.Cu")
		(net "FM_P12V_HOTSWAP0_EN")
	)
	(segment
		(start 22.101302 -29.5148)
		(end 21.6789 -29.5148)
		(width 0.10795)
		(layer "B.Cu")
		(net "FM_P12V_HOTSWAP0_EN")
	)
	(segment
		(start 23.191724 -39.927276)
		(end 24.0665 -39.0525)
		(width 0.10795)
		(layer "B.Cu")
		(net "FM_P12V_HOTSWAP0_EN")
	)
	(segment
		(start 25.4635 -39.0525)
		(end 26.7462 -37.7698)
		(width 0.10795)
		(layer "B.Cu")
		(net "FM_P12V_HOTSWAP0_EN")
	)
	(segment
		(start 23.876 -30.099)
		(end 22.685502 -30.099)
		(width 0.10795)
		(layer "B.Cu")
		(net "FM_P12V_HOTSWAP0_EN")
	)
	(segment
		(start 26.7462 -32.5755)
		(end 26.5557 -32.385)
		(width 0.10795)
		(layer "B.Cu")
		(net "FM_P12V_HOTSWAP0_EN")
	)
	(segment
		(start 25.8826 -31.4833)
		(end 24.888952 -31.4833)
		(width 0.10795)
		(layer "B.Cu")
		(net "FM_P12V_HOTSWAP0_EN")
	)
	(segment
		(start 24.0665 -39.0525)
		(end 25.4635 -39.0525)
		(width 0.10795)
		(layer "B.Cu")
		(net "FM_P12V_HOTSWAP0_EN")
	)
	(segment
		(start 23.876 -30.099)
		(end 23.876 -30.58922)
		(width 0.10795)
		(layer "B.Cu")
		(net "FM_P12V_HOTSWAP0_EN")
	)
	(segment
		(start 22.685502 -30.099)
		(end 22.101302 -29.5148)
		(width 0.10795)
		(layer "B.Cu")
		(net "FM_P12V_HOTSWAP0_EN")
	)
	(segment
		(start 24.692356 -31.405576)
		(end 24.692356 -31.679896)
		(width 0.10795)
		(layer "B.Cu")
		(net "FM_P12V_HOTSWAP0_EN")
	)
	(segment
		(start 26.290016 -55.576216)
		(end 22.73681 -52.02301)
		(width 0.089408)
		(layer "In4.Cu")
		(net "FM_P12V_HOTSWAP0_EN")
	)
	(segment
		(start 23.716742 -76.289916)
		(end 23.18639 -75.759564)
		(width 0.089408)
		(layer "In4.Cu")
		(net "FM_P12V_HOTSWAP0_EN")
	)
	(segment
		(start 23.716742 -77.272642)
		(end 23.716742 -76.289916)
		(width 0.089408)
		(layer "In4.Cu")
		(net "FM_P12V_HOTSWAP0_EN")
	)
	(segment
		(start 22.681184 -78.3082)
		(end 23.716742 -77.272642)
		(width 0.089408)
		(layer "In4.Cu")
		(net "FM_P12V_HOTSWAP0_EN")
	)
	(segment
		(start 23.18639 -75.759564)
		(end 23.18639 -73.032112)
		(width 0.089408)
		(layer "In4.Cu")
		(net "FM_P12V_HOTSWAP0_EN")
	)
	(segment
		(start 19.209004 -78.846172)
		(end 19.746976 -78.3082)
		(width 0.089408)
		(layer "In4.Cu")
		(net "FM_P12V_HOTSWAP0_EN")
	)
	(segment
		(start 26.290016 -66.707004)
		(end 26.290016 -55.576216)
		(width 0.089408)
		(layer "In4.Cu")
		(net "FM_P12V_HOTSWAP0_EN")
	)
	(segment
		(start 22.73681 -52.02301)
		(end 22.73681 -49.73701)
		(width 0.089408)
		(layer "In4.Cu")
		(net "FM_P12V_HOTSWAP0_EN")
	)
	(segment
		(start 22.314408 -72.16013)
		(end 22.314408 -70.682612)
		(width 0.089408)
		(layer "In4.Cu")
		(net "FM_P12V_HOTSWAP0_EN")
	)
	(segment
		(start 21.545296 -48.545496)
		(end 21.545296 -41.573704)
		(width 0.089408)
		(layer "In4.Cu")
		(net "FM_P12V_HOTSWAP0_EN")
	)
	(segment
		(start 21.545296 -41.573704)
		(end 23.191724 -39.927276)
		(width 0.089408)
		(layer "In4.Cu")
		(net "FM_P12V_HOTSWAP0_EN")
	)
	(segment
		(start 19.746976 -78.3082)
		(end 22.681184 -78.3082)
		(width 0.089408)
		(layer "In4.Cu")
		(net "FM_P12V_HOTSWAP0_EN")
	)
	(segment
		(start 23.18639 -73.032112)
		(end 22.314408 -72.16013)
		(width 0.089408)
		(layer "In4.Cu")
		(net "FM_P12V_HOTSWAP0_EN")
	)
	(segment
		(start 22.314408 -70.682612)
		(end 26.290016 -66.707004)
		(width 0.089408)
		(layer "In4.Cu")
		(net "FM_P12V_HOTSWAP0_EN")
	)
	(segment
		(start 22.73681 -49.73701)
		(end 21.545296 -48.545496)
		(width 0.089408)
		(layer "In4.Cu")
		(net "FM_P12V_HOTSWAP0_EN")
	)
	(segment
		(start 486.485946 -150.876254)
		(end 486.3338 -151.0284)
		(width 0.10795)
		(layer "F.Cu")
		(net "FM_DEBUG_RST_BTN_N")
	)
	(segment
		(start 488.037378 -157.888178)
		(end 487.554016 -157.404816)
		(width 0.10795)
		(layer "F.Cu")
		(net "FM_DEBUG_RST_BTN_N")
	)
	(segment
		(start 487.554016 -150.876254)
		(end 486.485946 -150.876254)
		(width 0.10795)
		(layer "F.Cu")
		(net "FM_DEBUG_RST_BTN_N")
	)
	(segment
		(start 487.554016 -154.10307)
		(end 487.172 -153.721054)
		(width 0.10795)
		(layer "F.Cu")
		(net "FM_DEBUG_RST_BTN_N")
	)
	(segment
		(start 487.554016 -155.702254)
		(end 487.554016 -154.10307)
		(width 0.10795)
		(layer "F.Cu")
		(net "FM_DEBUG_RST_BTN_N")
	)
	(segment
		(start 375.944892 -72.695308)
		(end 375.545096 -73.095104)
		(width 0.1016)
		(layer "F.Cu")
		(net "FM_DEBUG_RST_BTN_N")
	)
	(segment
		(start 487.172 -152.8572)
		(end 487.554016 -152.475184)
		(width 0.10795)
		(layer "F.Cu")
		(net "FM_DEBUG_RST_BTN_N")
	)
	(segment
		(start 487.554016 -157.404816)
		(end 487.554016 -155.702254)
		(width 0.10795)
		(layer "F.Cu")
		(net "FM_DEBUG_RST_BTN_N")
	)
	(segment
		(start 496.000024 -151.849836)
		(end 497.0018 -152.851612)
		(width 0.10795)
		(layer "F.Cu")
		(net "FM_DEBUG_RST_BTN_N")
	)
	(segment
		(start 487.554016 -152.475184)
		(end 487.554016 -150.876254)
		(width 0.10795)
		(layer "F.Cu")
		(net "FM_DEBUG_RST_BTN_N")
	)
	(segment
		(start 497.0018 -152.851612)
		(end 497.0018 -157.780228)
		(width 0.10795)
		(layer "F.Cu")
		(net "FM_DEBUG_RST_BTN_N")
	)
	(segment
		(start 497.0018 -157.780228)
		(end 496.89385 -157.888178)
		(width 0.10795)
		(layer "F.Cu")
		(net "FM_DEBUG_RST_BTN_N")
	)
	(segment
		(start 496.89385 -157.888178)
		(end 488.037378 -157.888178)
		(width 0.10795)
		(layer "F.Cu")
		(net "FM_DEBUG_RST_BTN_N")
	)
	(segment
		(start 487.172 -153.721054)
		(end 487.172 -152.8572)
		(width 0.10795)
		(layer "F.Cu")
		(net "FM_DEBUG_RST_BTN_N")
	)
	(via
		(at 486.3338 -151.0284)
		(size 0.508)
		(drill 0.254)
		(layers "F.Cu" "B.Cu")
		(net "FM_DEBUG_RST_BTN_N")
	)
	(via
		(at 459.564486 -141.151102)
		(size 0.508)
		(drill 0.254)
		(layers "F.Cu" "B.Cu")
		(net "FM_DEBUG_RST_BTN_N")
	)
	(via
		(at 474.9292 -141.5034)
		(size 0.508)
		(drill 0.254)
		(layers "F.Cu" "B.Cu")
		(net "FM_DEBUG_RST_BTN_N")
	)
	(via
		(at 375.944892 -72.695308)
		(size 0.4572)
		(drill 0.2032)
		(layers "F.Cu" "B.Cu")
		(net "FM_DEBUG_RST_BTN_N")
	)
	(via
		(at 422.738296 -62.992508)
		(size 0.508)
		(drill 0.254)
		(layers "F.Cu" "B.Cu")
		(net "FM_DEBUG_RST_BTN_N")
	)
	(via
		(at 426.288962 -112.46231)
		(size 0.508)
		(drill 0.254)
		(layers "F.Cu" "B.Cu")
		(net "FM_DEBUG_RST_BTN_N")
	)
	(via
		(at 422.91 -64.516)
		(size 0.6604)
		(drill 0.3302)
		(layers "F.Cu" "B.Cu")
		(net "FM_DEBUG_RST_BTN_N")
	)
	(segment
		(start 422.91 -70.776592)
		(end 422.91 -64.516)
		(width 0.10795)
		(layer "B.Cu")
		(net "FM_DEBUG_RST_BTN_N")
	)
	(segment
		(start 491.22584 -151.06904)
		(end 490.15396 -151.06904)
		(width 0.10795)
		(layer "B.Cu")
		(net "FM_DEBUG_RST_BTN_N")
	)
	(segment
		(start 494.97488 -150.8252)
		(end 493.43056 -150.8252)
		(width 0.10795)
		(layer "B.Cu")
		(net "FM_DEBUG_RST_BTN_N")
	)
	(segment
		(start 476.5294 -137.3632)
		(end 476.302832 -137.136632)
		(width 0.10795)
		(layer "B.Cu")
		(net "FM_DEBUG_RST_BTN_N")
	)
	(segment
		(start 474.9292 -141.5034)
		(end 476.5294 -139.9032)
		(width 0.10795)
		(layer "B.Cu")
		(net "FM_DEBUG_RST_BTN_N")
	)
	(segment
		(start 426.288962 -111.717582)
		(end 424.74261 -110.17123)
		(width 0.10795)
		(layer "B.Cu")
		(net "FM_DEBUG_RST_BTN_N")
	)
	(segment
		(start 490.15396 -151.06904)
		(end 490.15396 -150.18004)
		(width 0.10795)
		(layer "B.Cu")
		(net "FM_DEBUG_RST_BTN_N")
	)
	(segment
		(start 476.5294 -139.9032)
		(end 476.5294 -137.3632)
		(width 0.10795)
		(layer "B.Cu")
		(net "FM_DEBUG_RST_BTN_N")
	)
	(segment
		(start 493.116362 -150.511002)
		(end 491.783878 -150.511002)
		(width 0.10795)
		(layer "B.Cu")
		(net "FM_DEBUG_RST_BTN_N")
	)
	(segment
		(start 491.783878 -150.511002)
		(end 491.22584 -151.06904)
		(width 0.10795)
		(layer "B.Cu")
		(net "FM_DEBUG_RST_BTN_N")
	)
	(segment
		(start 424.2308 -72.097392)
		(end 422.91 -70.776592)
		(width 0.10795)
		(layer "B.Cu")
		(net "FM_DEBUG_RST_BTN_N")
	)
	(segment
		(start 424.74261 -110.17123)
		(end 424.74261 -80.54721)
		(width 0.10795)
		(layer "B.Cu")
		(net "FM_DEBUG_RST_BTN_N")
	)
	(segment
		(start 424.513248 -80.317848)
		(end 424.513248 -73.688448)
		(width 0.10795)
		(layer "B.Cu")
		(net "FM_DEBUG_RST_BTN_N")
	)
	(segment
		(start 476.302832 -137.136632)
		(end 473.660216 -137.136632)
		(width 0.10795)
		(layer "B.Cu")
		(net "FM_DEBUG_RST_BTN_N")
	)
	(segment
		(start 457.653898 -141.151102)
		(end 456.7936 -142.0114)
		(width 0.10795)
		(layer "B.Cu")
		(net "FM_DEBUG_RST_BTN_N")
	)
	(segment
		(start 424.74261 -80.54721)
		(end 424.513248 -80.317848)
		(width 0.10795)
		(layer "B.Cu")
		(net "FM_DEBUG_RST_BTN_N")
	)
	(segment
		(start 493.43056 -150.8252)
		(end 493.116362 -150.511002)
		(width 0.10795)
		(layer "B.Cu")
		(net "FM_DEBUG_RST_BTN_N")
	)
	(segment
		(start 426.288962 -112.46231)
		(end 426.288962 -111.717582)
		(width 0.10795)
		(layer "B.Cu")
		(net "FM_DEBUG_RST_BTN_N")
	)
	(segment
		(start 424.513248 -73.688448)
		(end 424.2308 -73.406)
		(width 0.10795)
		(layer "B.Cu")
		(net "FM_DEBUG_RST_BTN_N")
	)
	(segment
		(start 496.000024 -151.849836)
		(end 495.999516 -151.849836)
		(width 0.10795)
		(layer "B.Cu")
		(net "FM_DEBUG_RST_BTN_N")
	)
	(segment
		(start 422.91 -63.164212)
		(end 422.738296 -62.992508)
		(width 0.10795)
		(layer "B.Cu")
		(net "FM_DEBUG_RST_BTN_N")
	)
	(segment
		(start 459.564486 -141.151102)
		(end 457.653898 -141.151102)
		(width 0.10795)
		(layer "B.Cu")
		(net "FM_DEBUG_RST_BTN_N")
	)
	(segment
		(start 495.999516 -151.849836)
		(end 494.97488 -150.8252)
		(width 0.10795)
		(layer "B.Cu")
		(net "FM_DEBUG_RST_BTN_N")
	)
	(segment
		(start 424.2308 -73.406)
		(end 424.2308 -72.097392)
		(width 0.10795)
		(layer "B.Cu")
		(net "FM_DEBUG_RST_BTN_N")
	)
	(segment
		(start 422.91 -64.516)
		(end 422.91 -63.164212)
		(width 0.10795)
		(layer "B.Cu")
		(net "FM_DEBUG_RST_BTN_N")
	)
	(segment
		(start 471.871294 -140.788136)
		(end 471.874342 -140.785088)
		(width 0.089408)
		(layer "In2.Cu")
		(net "FM_DEBUG_RST_BTN_N")
	)
	(segment
		(start 471.874342 -140.785088)
		(end 472.065096 -140.785088)
		(width 0.089408)
		(layer "In2.Cu")
		(net "FM_DEBUG_RST_BTN_N")
	)
	(segment
		(start 468.487252 -141.4526)
		(end 470.908888 -141.4526)
		(width 0.089408)
		(layer "In2.Cu")
		(net "FM_DEBUG_RST_BTN_N")
	)
	(segment
		(start 474.3323 -142.722854)
		(end 476.140526 -144.53108)
		(width 0.089408)
		(layer "In2.Cu")
		(net "FM_DEBUG_RST_BTN_N")
	)
	(segment
		(start 484.650034 -150.360634)
		(end 485.3178 -151.0284)
		(width 0.089408)
		(layer "In2.Cu")
		(net "FM_DEBUG_RST_BTN_N")
	)
	(segment
		(start 459.564486 -141.151102)
		(end 459.834488 -141.421104)
		(width 0.089408)
		(layer "In2.Cu")
		(net "FM_DEBUG_RST_BTN_N")
	)
	(segment
		(start 470.908888 -141.4526)
		(end 471.573352 -140.788136)
		(width 0.089408)
		(layer "In2.Cu")
		(net "FM_DEBUG_RST_BTN_N")
	)
	(segment
		(start 471.573352 -140.788136)
		(end 471.871294 -140.788136)
		(width 0.089408)
		(layer "In2.Cu")
		(net "FM_DEBUG_RST_BTN_N")
	)
	(segment
		(start 474.3323 -142.1003)
		(end 474.3323 -142.722854)
		(width 0.089408)
		(layer "In2.Cu")
		(net "FM_DEBUG_RST_BTN_N")
	)
	(segment
		(start 476.140526 -144.53108)
		(end 479.795078 -144.53108)
		(width 0.089408)
		(layer "In2.Cu")
		(net "FM_DEBUG_RST_BTN_N")
	)
	(segment
		(start 459.834488 -141.421104)
		(end 462.09204 -141.421104)
		(width 0.089408)
		(layer "In2.Cu")
		(net "FM_DEBUG_RST_BTN_N")
	)
	(segment
		(start 485.3178 -151.0284)
		(end 486.3338 -151.0284)
		(width 0.089408)
		(layer "In2.Cu")
		(net "FM_DEBUG_RST_BTN_N")
	)
	(segment
		(start 467.9696 -140.934948)
		(end 468.487252 -141.4526)
		(width 0.089408)
		(layer "In2.Cu")
		(net "FM_DEBUG_RST_BTN_N")
	)
	(segment
		(start 479.795078 -144.53108)
		(end 484.650034 -149.386036)
		(width 0.089408)
		(layer "In2.Cu")
		(net "FM_DEBUG_RST_BTN_N")
	)
	(segment
		(start 472.732608 -141.4526)
		(end 474.8784 -141.4526)
		(width 0.089408)
		(layer "In2.Cu")
		(net "FM_DEBUG_RST_BTN_N")
	)
	(segment
		(start 472.065096 -140.785088)
		(end 472.732608 -141.4526)
		(width 0.089408)
		(layer "In2.Cu")
		(net "FM_DEBUG_RST_BTN_N")
	)
	(segment
		(start 462.578196 -140.934948)
		(end 467.9696 -140.934948)
		(width 0.089408)
		(layer "In2.Cu")
		(net "FM_DEBUG_RST_BTN_N")
	)
	(segment
		(start 462.09204 -141.421104)
		(end 462.578196 -140.934948)
		(width 0.089408)
		(layer "In2.Cu")
		(net "FM_DEBUG_RST_BTN_N")
	)
	(segment
		(start 484.650034 -149.386036)
		(end 484.650034 -150.360634)
		(width 0.089408)
		(layer "In2.Cu")
		(net "FM_DEBUG_RST_BTN_N")
	)
	(segment
		(start 474.8784 -141.4526)
		(end 474.9292 -141.5034)
		(width 0.089408)
		(layer "In2.Cu")
		(net "FM_DEBUG_RST_BTN_N")
	)
	(segment
		(start 474.9292 -141.5034)
		(end 474.3323 -142.1003)
		(width 0.089408)
		(layer "In2.Cu")
		(net "FM_DEBUG_RST_BTN_N")
	)
	(segment
		(start 415.845244 -68.342002)
		(end 415.66719 -68.342002)
		(width 0.089408)
		(layer "In4.Cu")
		(net "FM_DEBUG_RST_BTN_N")
	)
	(segment
		(start 413.733234 -69.633592)
		(end 413.04718 -70.319646)
		(width 0.089408)
		(layer "In4.Cu")
		(net "FM_DEBUG_RST_BTN_N")
	)
	(segment
		(start 395.902434 -73.144888)
		(end 395.653768 -72.896222)
		(width 0.089408)
		(layer "In4.Cu")
		(net "FM_DEBUG_RST_BTN_N")
	)
	(segment
		(start 416.85591 -67.331336)
		(end 415.845244 -68.342002)
		(width 0.089408)
		(layer "In4.Cu")
		(net "FM_DEBUG_RST_BTN_N")
	)
	(segment
		(start 396.489936 -73.144888)
		(end 395.902434 -73.144888)
		(width 0.089408)
		(layer "In4.Cu")
		(net "FM_DEBUG_RST_BTN_N")
	)
	(segment
		(start 411.494224 -70.800722)
		(end 409.319476 -70.800722)
		(width 0.089408)
		(layer "In4.Cu")
		(net "FM_DEBUG_RST_BTN_N")
	)
	(segment
		(start 406.033478 -71.86041)
		(end 402.220938 -71.86041)
		(width 0.089408)
		(layer "In4.Cu")
		(net "FM_DEBUG_RST_BTN_N")
	)
	(segment
		(start 422.629076 -63.101728)
		(end 420.869618 -63.101728)
		(width 0.089408)
		(layer "In4.Cu")
		(net "FM_DEBUG_RST_BTN_N")
	)
	(segment
		(start 414.375854 -69.633338)
		(end 414.287462 -69.633338)
		(width 0.089408)
		(layer "In4.Cu")
		(net "FM_DEBUG_RST_BTN_N")
	)
	(segment
		(start 395.653768 -72.896222)
		(end 394.300202 -72.896222)
		(width 0.089408)
		(layer "In4.Cu")
		(net "FM_DEBUG_RST_BTN_N")
	)
	(segment
		(start 402.220938 -71.86041)
		(end 401.83816 -71.477632)
		(width 0.089408)
		(layer "In4.Cu")
		(net "FM_DEBUG_RST_BTN_N")
	)
	(segment
		(start 398.157192 -71.477632)
		(end 396.489936 -73.144888)
		(width 0.089408)
		(layer "In4.Cu")
		(net "FM_DEBUG_RST_BTN_N")
	)
	(segment
		(start 422.738296 -62.992508)
		(end 422.629076 -63.101728)
		(width 0.089408)
		(layer "In4.Cu")
		(net "FM_DEBUG_RST_BTN_N")
	)
	(segment
		(start 406.4254 -71.468488)
		(end 406.033478 -71.86041)
		(width 0.089408)
		(layer "In4.Cu")
		(net "FM_DEBUG_RST_BTN_N")
	)
	(segment
		(start 414.287208 -69.633592)
		(end 413.733234 -69.633592)
		(width 0.089408)
		(layer "In4.Cu")
		(net "FM_DEBUG_RST_BTN_N")
	)
	(segment
		(start 413.04718 -70.319646)
		(end 411.975808 -70.319646)
		(width 0.089408)
		(layer "In4.Cu")
		(net "FM_DEBUG_RST_BTN_N")
	)
	(segment
		(start 408.65171 -71.468488)
		(end 406.4254 -71.468488)
		(width 0.089408)
		(layer "In4.Cu")
		(net "FM_DEBUG_RST_BTN_N")
	)
	(segment
		(start 420.869618 -63.101728)
		(end 416.85591 -67.115436)
		(width 0.089408)
		(layer "In4.Cu")
		(net "FM_DEBUG_RST_BTN_N")
	)
	(segment
		(start 411.975808 -70.319646)
		(end 411.494224 -70.800722)
		(width 0.089408)
		(layer "In4.Cu")
		(net "FM_DEBUG_RST_BTN_N")
	)
	(segment
		(start 409.319476 -70.800722)
		(end 408.65171 -71.468488)
		(width 0.089408)
		(layer "In4.Cu")
		(net "FM_DEBUG_RST_BTN_N")
	)
	(segment
		(start 414.287462 -69.633338)
		(end 414.287208 -69.633592)
		(width 0.089408)
		(layer "In4.Cu")
		(net "FM_DEBUG_RST_BTN_N")
	)
	(segment
		(start 416.85591 -67.115436)
		(end 416.85591 -67.331336)
		(width 0.089408)
		(layer "In4.Cu")
		(net "FM_DEBUG_RST_BTN_N")
	)
	(segment
		(start 394.300202 -72.896222)
		(end 393.570206 -72.166226)
		(width 0.089408)
		(layer "In4.Cu")
		(net "FM_DEBUG_RST_BTN_N")
	)
	(segment
		(start 381.112522 -72.166226)
		(end 380.95682 -72.321928)
		(width 0.089408)
		(layer "In4.Cu")
		(net "FM_DEBUG_RST_BTN_N")
	)
	(segment
		(start 401.83816 -71.477632)
		(end 398.157192 -71.477632)
		(width 0.089408)
		(layer "In4.Cu")
		(net "FM_DEBUG_RST_BTN_N")
	)
	(segment
		(start 415.66719 -68.342002)
		(end 414.375854 -69.633338)
		(width 0.089408)
		(layer "In4.Cu")
		(net "FM_DEBUG_RST_BTN_N")
	)
	(segment
		(start 393.570206 -72.166226)
		(end 381.112522 -72.166226)
		(width 0.089408)
		(layer "In4.Cu")
		(net "FM_DEBUG_RST_BTN_N")
	)
	(segment
		(start 376.318272 -72.321928)
		(end 375.944892 -72.695308)
		(width 0.089408)
		(layer "In4.Cu")
		(net "FM_DEBUG_RST_BTN_N")
	)
	(segment
		(start 380.95682 -72.321928)
		(end 376.318272 -72.321928)
		(width 0.089408)
		(layer "In4.Cu")
		(net "FM_DEBUG_RST_BTN_N")
	)
	(segment
		(start 462.906618 -133.64972)
		(end 461.712056 -132.455158)
		(width 0.089408)
		(layer "In9.Cu")
		(net "FM_DEBUG_RST_BTN_N")
	)
	(segment
		(start 454.287128 -130.015488)
		(end 450.928486 -126.656846)
		(width 0.089408)
		(layer "In9.Cu")
		(net "FM_DEBUG_RST_BTN_N")
	)
	(segment
		(start 440.464956 -121.957592)
		(end 437.947054 -119.43969)
		(width 0.089408)
		(layer "In9.Cu")
		(net "FM_DEBUG_RST_BTN_N")
	)
	(segment
		(start 428.23511 -119.197882)
		(end 428.23511 -118.20271)
		(width 0.089408)
		(layer "In9.Cu")
		(net "FM_DEBUG_RST_BTN_N")
	)
	(segment
		(start 437.947054 -119.43969)
		(end 436.557166 -119.43969)
		(width 0.089408)
		(layer "In9.Cu")
		(net "FM_DEBUG_RST_BTN_N")
	)
	(segment
		(start 426.961554 -112.46231)
		(end 426.288962 -112.46231)
		(width 0.089408)
		(layer "In9.Cu")
		(net "FM_DEBUG_RST_BTN_N")
	)
	(segment
		(start 462.906618 -139.583668)
		(end 462.906618 -133.64972)
		(width 0.089408)
		(layer "In9.Cu")
		(net "FM_DEBUG_RST_BTN_N")
	)
	(segment
		(start 429.06315 -114.563906)
		(end 426.961554 -112.46231)
		(width 0.089408)
		(layer "In9.Cu")
		(net "FM_DEBUG_RST_BTN_N")
	)
	(segment
		(start 435.27345 -120.723406)
		(end 434.513482 -120.723406)
		(width 0.089408)
		(layer "In9.Cu")
		(net "FM_DEBUG_RST_BTN_N")
	)
	(segment
		(start 450.928486 -126.656846)
		(end 450.928486 -124.416058)
		(width 0.089408)
		(layer "In9.Cu")
		(net "FM_DEBUG_RST_BTN_N")
	)
	(segment
		(start 461.712056 -132.455158)
		(end 460.67345 -132.455158)
		(width 0.089408)
		(layer "In9.Cu")
		(net "FM_DEBUG_RST_BTN_N")
	)
	(segment
		(start 428.23511 -118.20271)
		(end 429.06315 -117.37467)
		(width 0.089408)
		(layer "In9.Cu")
		(net "FM_DEBUG_RST_BTN_N")
	)
	(segment
		(start 432.37658 -123.007628)
		(end 432.044856 -123.007628)
		(width 0.089408)
		(layer "In9.Cu")
		(net "FM_DEBUG_RST_BTN_N")
	)
	(segment
		(start 461.287368 -141.202918)
		(end 462.906618 -139.583668)
		(width 0.089408)
		(layer "In9.Cu")
		(net "FM_DEBUG_RST_BTN_N")
	)
	(segment
		(start 450.928486 -124.416058)
		(end 448.47002 -121.957592)
		(width 0.089408)
		(layer "In9.Cu")
		(net "FM_DEBUG_RST_BTN_N")
	)
	(segment
		(start 434.513482 -120.723406)
		(end 432.611022 -122.625866)
		(width 0.089408)
		(layer "In9.Cu")
		(net "FM_DEBUG_RST_BTN_N")
	)
	(segment
		(start 432.044856 -123.007628)
		(end 428.23511 -119.197882)
		(width 0.089408)
		(layer "In9.Cu")
		(net "FM_DEBUG_RST_BTN_N")
	)
	(segment
		(start 459.616302 -141.202918)
		(end 461.287368 -141.202918)
		(width 0.089408)
		(layer "In9.Cu")
		(net "FM_DEBUG_RST_BTN_N")
	)
	(segment
		(start 436.557166 -119.43969)
		(end 435.27345 -120.723406)
		(width 0.089408)
		(layer "In9.Cu")
		(net "FM_DEBUG_RST_BTN_N")
	)
	(segment
		(start 432.611022 -122.625866)
		(end 432.611022 -122.773186)
		(width 0.089408)
		(layer "In9.Cu")
		(net "FM_DEBUG_RST_BTN_N")
	)
	(segment
		(start 429.06315 -117.37467)
		(end 429.06315 -114.563906)
		(width 0.089408)
		(layer "In9.Cu")
		(net "FM_DEBUG_RST_BTN_N")
	)
	(segment
		(start 460.67345 -132.455158)
		(end 458.23378 -130.015488)
		(width 0.089408)
		(layer "In9.Cu")
		(net "FM_DEBUG_RST_BTN_N")
	)
	(segment
		(start 458.23378 -130.015488)
		(end 454.287128 -130.015488)
		(width 0.089408)
		(layer "In9.Cu")
		(net "FM_DEBUG_RST_BTN_N")
	)
	(segment
		(start 432.611022 -122.773186)
		(end 432.37658 -123.007628)
		(width 0.089408)
		(layer "In9.Cu")
		(net "FM_DEBUG_RST_BTN_N")
	)
	(segment
		(start 459.564486 -141.151102)
		(end 459.616302 -141.202918)
		(width 0.089408)
		(layer "In9.Cu")
		(net "FM_DEBUG_RST_BTN_N")
	)
	(segment
		(start 448.47002 -121.957592)
		(end 440.464956 -121.957592)
		(width 0.089408)
		(layer "In9.Cu")
		(net "FM_DEBUG_RST_BTN_N")
	)
	(segment
		(start 498.729254 -141.132306)
		(end 499.01856 -140.843)
		(width 0.10795)
		(layer "F.Cu")
		(net "FM_BEEP_LED_P")
	)
	(segment
		(start 498.27561 -141.132306)
		(end 498.729254 -141.132306)
		(width 0.10795)
		(layer "F.Cu")
		(net "FM_BEEP_LED_P")
	)
	(segment
		(start 499.01856 -140.843)
		(end 499.872 -140.843)
		(width 0.10795)
		(layer "F.Cu")
		(net "FM_BEEP_LED_P")
	)
	(via
		(at 498.27561 -141.132306)
		(size 0.508)
		(drill 0.254)
		(layers "F.Cu" "B.Cu")
		(net "FM_BEEP_LED_P")
	)
	(segment
		(start 499.01856 -140.843)
		(end 499.3894 -140.843)
		(width 0.10795)
		(layer "B.Cu")
		(net "FM_BEEP_LED_P")
	)
	(segment
		(start 498.27561 -141.132306)
		(end 498.729254 -141.132306)
		(width 0.10795)
		(layer "B.Cu")
		(net "FM_BEEP_LED_P")
	)
	(segment
		(start 498.729254 -141.132306)
		(end 499.01856 -140.843)
		(width 0.10795)
		(layer "B.Cu")
		(net "FM_BEEP_LED_P")
	)
	(segment
		(start 3.490468 -119.832374)
		(end 3.490468 -119.838978)
		(width 0.254)
		(layer "F.Cu")
		(net "P12V_FAN_SWITCH_G")
	)
	(segment
		(start 3.254248 -116.655596)
		(end 4.035552 -117.4369)
		(width 0.254)
		(layer "F.Cu")
		(net "P12V_FAN_SWITCH_G")
	)
	(segment
		(start 3.490468 -119.838978)
		(end 3.040888 -120.288558)
		(width 0.254)
		(layer "F.Cu")
		(net "P12V_FAN_SWITCH_G")
	)
	(segment
		(start 3.040888 -120.288558)
		(end 3.040888 -120.755918)
		(width 0.254)
		(layer "F.Cu")
		(net "P12V_FAN_SWITCH_G")
	)
	(segment
		(start 3.254248 -113.769648)
		(end 3.254248 -116.655596)
		(width 0.254)
		(layer "F.Cu")
		(net "P12V_FAN_SWITCH_G")
	)
	(segment
		(start 4.035552 -117.4369)
		(end 4.035552 -119.28729)
		(width 0.254)
		(layer "F.Cu")
		(net "P12V_FAN_SWITCH_G")
	)
	(segment
		(start 4.035552 -119.28729)
		(end 3.490468 -119.832374)
		(width 0.254)
		(layer "F.Cu")
		(net "P12V_FAN_SWITCH_G")
	)
	(segment
		(start 2.8194 -113.3348)
		(end 3.254248 -113.769648)
		(width 0.254)
		(layer "F.Cu")
		(net "P12V_FAN_SWITCH_G")
	)
	(via
		(at 3.040888 -120.755918)
		(size 0.508)
		(drill 0.254)
		(layers "F.Cu" "B.Cu")
		(net "P12V_FAN_SWITCH_G")
	)
	(via
		(at 2.8194 -113.3348)
		(size 0.508)
		(drill 0.254)
		(layers "F.Cu" "B.Cu")
		(net "P12V_FAN_SWITCH_G")
	)
	(via
		(at 3.103118 -121.984516)
		(size 0.6604)
		(drill 0.3302)
		(layers "F.Cu" "B.Cu")
		(net "P12V_FAN_SWITCH_G")
	)
	(segment
		(start 3.55473 -122.436128)
		(end 3.103118 -121.984516)
		(width 0.254)
		(layer "B.Cu")
		(net "P12V_FAN_SWITCH_G")
	)
	(segment
		(start 3.413252 -113.928652)
		(end 3.9751 -113.928652)
		(width 0.254)
		(layer "B.Cu")
		(net "P12V_FAN_SWITCH_G")
	)
	(segment
		(start 2.8194 -113.3348)
		(end 3.413252 -113.928652)
		(width 0.254)
		(layer "B.Cu")
		(net "P12V_FAN_SWITCH_G")
	)
	(segment
		(start 5.2324 -122.436128)
		(end 3.55473 -122.436128)
		(width 0.254)
		(layer "B.Cu")
		(net "P12V_FAN_SWITCH_G")
	)
	(segment
		(start 3.040888 -121.922286)
		(end 3.040888 -120.755918)
		(width 0.254)
		(layer "B.Cu")
		(net "P12V_FAN_SWITCH_G")
	)
	(segment
		(start 4.3942 -114.347752)
		(end 4.3942 -114.35334)
		(width 0.254)
		(layer "B.Cu")
		(net "P12V_FAN_SWITCH_G")
	)
	(segment
		(start 3.103118 -121.984516)
		(end 3.040888 -121.922286)
		(width 0.254)
		(layer "B.Cu")
		(net "P12V_FAN_SWITCH_G")
	)
	(segment
		(start 3.9751 -113.928652)
		(end 4.3942 -114.347752)
		(width 0.254)
		(layer "B.Cu")
		(net "P12V_FAN_SWITCH_G")
	)
	(segment
		(start 6.226048 -117.319806)
		(end 6.226048 -119.62257)
		(width 0.254)
		(layer "F.Cu")
		(net "P12V_FAN")
	)
	(segment
		(start 4.166616 -119.874792)
		(end 3.998468 -120.04294)
		(width 0.254)
		(layer "F.Cu")
		(net "P12V_FAN")
	)
	(segment
		(start 6.226048 -119.62257)
		(end 5.973826 -119.874792)
		(width 0.254)
		(layer "F.Cu")
		(net "P12V_FAN")
	)
	(segment
		(start 3.998468 -120.04294)
		(end 3.998468 -120.049544)
		(width 0.254)
		(layer "F.Cu")
		(net "P12V_FAN")
	)
	(segment
		(start 5.973826 -119.874792)
		(end 4.166616 -119.874792)
		(width 0.254)
		(layer "F.Cu")
		(net "P12V_FAN")
	)
	(segment
		(start 6.024372 -117.11813)
		(end 6.226048 -117.319806)
		(width 0.254)
		(layer "F.Cu")
		(net "P12V_FAN")
	)
	(segment
		(start 3.683 -120.365012)
		(end 3.683 -120.777)
		(width 0.254)
		(layer "F.Cu")
		(net "P12V_FAN")
	)
	(segment
		(start 3.998468 -120.049544)
		(end 3.683 -120.365012)
		(width 0.254)
		(layer "F.Cu")
		(net "P12V_FAN")
	)
	(segment
		(start 6.024372 -117.059964)
		(end 6.024372 -117.11813)
		(width 0.254)
		(layer "F.Cu")
		(net "P12V_FAN")
	)
	(via
		(at 3.683 -120.777)
		(size 0.508)
		(drill 0.254)
		(layers "F.Cu" "B.Cu")
		(net "P12V_FAN")
	)
	(via
		(at 30.1244 -40.513)
		(size 0.6604)
		(drill 0.3302)
		(layers "F.Cu" "B.Cu")
		(net "P12V_FAN")
	)
	(via
		(at 6.684772 -117.059964)
		(size 0.5588)
		(drill 0.3048)
		(layers "F.Cu" "B.Cu")
		(net "P12V_FAN")
	)
	(via
		(at 5.333492 -115.459764)
		(size 0.5588)
		(drill 0.3048)
		(layers "F.Cu" "B.Cu")
		(net "P12V_FAN")
	)
	(via
		(at 5.333492 -116.221764)
		(size 0.5588)
		(drill 0.3048)
		(layers "F.Cu" "B.Cu")
		(net "P12V_FAN")
	)
	(via
		(at 7.362952 -117.062504)
		(size 0.5588)
		(drill 0.3048)
		(layers "F.Cu" "B.Cu")
		(net "P12V_FAN")
	)
	(via
		(at 6.024372 -117.059964)
		(size 0.5588)
		(drill 0.3048)
		(layers "F.Cu" "B.Cu")
		(net "P12V_FAN")
	)
	(via
		(at 5.363972 -117.059964)
		(size 0.5588)
		(drill 0.3048)
		(layers "F.Cu" "B.Cu")
		(net "P12V_FAN")
	)
	(via
		(at 7.332472 -115.462304)
		(size 0.5588)
		(drill 0.3048)
		(layers "F.Cu" "B.Cu")
		(net "P12V_FAN")
	)
	(via
		(at 5.993892 -115.459764)
		(size 0.5588)
		(drill 0.3048)
		(layers "F.Cu" "B.Cu")
		(net "P12V_FAN")
	)
	(via
		(at 31.400496 -41.8084)
		(size 0.5588)
		(drill 0.3048)
		(layers "F.Cu" "B.Cu")
		(net "P12V_FAN")
	)
	(via
		(at 6.654292 -116.221764)
		(size 0.5588)
		(drill 0.3048)
		(layers "F.Cu" "B.Cu")
		(net "P12V_FAN")
	)
	(via
		(at 7.332472 -116.224304)
		(size 0.5588)
		(drill 0.3048)
		(layers "F.Cu" "B.Cu")
		(net "P12V_FAN")
	)
	(via
		(at 5.993892 -116.221764)
		(size 0.5588)
		(drill 0.3048)
		(layers "F.Cu" "B.Cu")
		(net "P12V_FAN")
	)
	(via
		(at 6.654292 -115.459764)
		(size 0.5588)
		(drill 0.3048)
		(layers "F.Cu" "B.Cu")
		(net "P12V_FAN")
	)
	(via
		(at 27.476196 -41.688258)
		(size 0.5588)
		(drill 0.3048)
		(layers "F.Cu" "B.Cu")
		(net "P12V_FAN")
	)
	(segment
		(start 3.683 -121.4882)
		(end 4.064 -121.8692)
		(width 0.254)
		(layer "B.Cu")
		(net "P12V_FAN")
	)
	(segment
		(start 4.461256 -121.936256)
		(end 5.2324 -121.936256)
		(width 0.254)
		(layer "B.Cu")
		(net "P12V_FAN")
	)
	(segment
		(start 3.683 -120.777)
		(end 3.683 -121.4882)
		(width 0.254)
		(layer "B.Cu")
		(net "P12V_FAN")
	)
	(segment
		(start 4.064 -121.8692)
		(end 4.3942 -121.8692)
		(width 0.254)
		(layer "B.Cu")
		(net "P12V_FAN")
	)
	(segment
		(start 4.3942 -121.8692)
		(end 4.461256 -121.936256)
		(width 0.254)
		(layer "B.Cu")
		(net "P12V_FAN")
	)
	(segment
		(start 481.321872 -56.090058)
		(end 481.321872 -56.40832)
		(width 0.10795)
		(layer "B.Cu")
		(net "PU_TRI_STATE_EN")
	)
	(segment
		(start 481.057458 -56.672734)
		(end 480.26193 -56.672734)
		(width 0.10795)
		(layer "B.Cu")
		(net "PU_TRI_STATE_EN")
	)
	(segment
		(start 481.321872 -56.40832)
		(end 481.057458 -56.672734)
		(width 0.10795)
		(layer "B.Cu")
		(net "PU_TRI_STATE_EN")
	)
	(segment
		(start 480.037902 -56.448706)
		(end 480.037902 -55.990998)
		(width 0.10795)
		(layer "B.Cu")
		(net "PU_TRI_STATE_EN")
	)
	(segment
		(start 480.26193 -56.672734)
		(end 480.037902 -56.448706)
		(width 0.10795)
		(layer "B.Cu")
		(net "PU_TRI_STATE_EN")
	)
	(via
		(at 482.65842 -51.943)
		(size 0.6604)
		(drill 0.3302)
		(layers "F.Cu" "B.Cu")
		(net "IRQ_LVC3_WAKE_R_N")
	)
	(segment
		(start 482.621844 -53.699156)
		(end 482.621844 -54.312058)
		(width 0.10795)
		(layer "B.Cu")
		(net "IRQ_LVC3_WAKE_R_N")
	)
	(segment
		(start 482.727 -52.01158)
		(end 482.65842 -51.943)
		(width 0.10795)
		(layer "B.Cu")
		(net "IRQ_LVC3_WAKE_R_N")
	)
	(segment
		(start 482.727 -53.594)
		(end 482.621844 -53.699156)
		(width 0.10795)
		(layer "B.Cu")
		(net "IRQ_LVC3_WAKE_R_N")
	)
	(segment
		(start 482.727 -53.1368)
		(end 482.727 -52.01158)
		(width 0.10795)
		(layer "B.Cu")
		(net "IRQ_LVC3_WAKE_R_N")
	)
	(segment
		(start 482.727 -53.1368)
		(end 482.727 -53.594)
		(width 0.10795)
		(layer "B.Cu")
		(net "IRQ_LVC3_WAKE_R_N")
	)
	(segment
		(start 488.6198 -48.4378)
		(end 488.95 -48.768)
		(width 0.10795)
		(layer "F.Cu")
		(net "FM_PE_SPRV_WAKE_N")
	)
	(segment
		(start 488.6198 -47.717456)
		(end 488.6198 -48.4378)
		(width 0.10795)
		(layer "F.Cu")
		(net "FM_PE_SPRV_WAKE_N")
	)
	(via
		(at 488.95 -48.768)
		(size 0.508)
		(drill 0.254)
		(layers "F.Cu" "B.Cu")
		(net "FM_PE_SPRV_WAKE_N")
	)
	(via
		(at 478.79 -57.785)
		(size 0.508)
		(drill 0.254)
		(layers "F.Cu" "B.Cu")
		(net "FM_PE_SPRV_WAKE_N")
	)
	(segment
		(start 479.015298 -58.010298)
		(end 479.923602 -58.010298)
		(width 0.10795)
		(layer "B.Cu")
		(net "FM_PE_SPRV_WAKE_N")
	)
	(segment
		(start 478.79 -57.785)
		(end 479.015298 -58.010298)
		(width 0.10795)
		(layer "B.Cu")
		(net "FM_PE_SPRV_WAKE_N")
	)
	(segment
		(start 486.728008 -52.58816)
		(end 486.126536 -53.189632)
		(width 0.089408)
		(layer "In9.Cu")
		(net "FM_PE_SPRV_WAKE_N")
	)
	(segment
		(start 486.728008 -52.11064)
		(end 486.728008 -52.58816)
		(width 0.089408)
		(layer "In9.Cu")
		(net "FM_PE_SPRV_WAKE_N")
	)
	(segment
		(start 488.95 -48.768)
		(end 488.95 -48.851566)
		(width 0.089408)
		(layer "In9.Cu")
		(net "FM_PE_SPRV_WAKE_N")
	)
	(segment
		(start 486.126536 -53.189632)
		(end 486.126536 -58.424064)
		(width 0.089408)
		(layer "In9.Cu")
		(net "FM_PE_SPRV_WAKE_N")
	)
	(segment
		(start 485.315006 -59.235594)
		(end 479.838258 -59.235594)
		(width 0.089408)
		(layer "In9.Cu")
		(net "FM_PE_SPRV_WAKE_N")
	)
	(segment
		(start 488.155234 -49.646332)
		(end 488.155234 -50.683414)
		(width 0.089408)
		(layer "In9.Cu")
		(net "FM_PE_SPRV_WAKE_N")
	)
	(segment
		(start 479.071432 -58.066432)
		(end 478.79 -57.785)
		(width 0.089408)
		(layer "In9.Cu")
		(net "FM_PE_SPRV_WAKE_N")
	)
	(segment
		(start 488.95 -48.851566)
		(end 488.155234 -49.646332)
		(width 0.089408)
		(layer "In9.Cu")
		(net "FM_PE_SPRV_WAKE_N")
	)
	(segment
		(start 479.071432 -58.468768)
		(end 479.071432 -58.066432)
		(width 0.089408)
		(layer "In9.Cu")
		(net "FM_PE_SPRV_WAKE_N")
	)
	(segment
		(start 488.155234 -50.683414)
		(end 486.728008 -52.11064)
		(width 0.089408)
		(layer "In9.Cu")
		(net "FM_PE_SPRV_WAKE_N")
	)
	(segment
		(start 479.838258 -59.235594)
		(end 479.071432 -58.468768)
		(width 0.089408)
		(layer "In9.Cu")
		(net "FM_PE_SPRV_WAKE_N")
	)
	(segment
		(start 486.126536 -58.424064)
		(end 485.315006 -59.235594)
		(width 0.089408)
		(layer "In9.Cu")
		(net "FM_PE_SPRV_WAKE_N")
	)
	(segment
		(start 463.678778 -5.390896)
		(end 463.77098 -5.483098)
		(width 0.10795)
		(layer "F.Cu")
		(net "FM_PE_SLOTX24_WAKE_N")
	)
	(segment
		(start 482.369368 -58.748676)
		(end 483.338378 -58.748676)
		(width 0.10795)
		(layer "F.Cu")
		(net "FM_PE_SLOTX24_WAKE_N")
	)
	(segment
		(start 463.678778 -4.386072)
		(end 463.678778 -5.390896)
		(width 0.10795)
		(layer "F.Cu")
		(net "FM_PE_SLOTX24_WAKE_N")
	)
	(via
		(at 482.369368 -58.748676)
		(size 0.762)
		(drill 0.381)
		(layers "F.Cu" "B.Cu")
		(net "FM_PE_SLOTX24_WAKE_N")
	)
	(via
		(at 463.77098 -5.483098)
		(size 0.508)
		(drill 0.254)
		(layers "F.Cu" "B.Cu")
		(net "FM_PE_SLOTX24_WAKE_N")
	)
	(via
		(at 483.338378 -58.748676)
		(size 0.508)
		(drill 0.254)
		(layers "F.Cu" "B.Cu")
		(net "FM_PE_SLOTX24_WAKE_N")
	)
	(segment
		(start 463.77098 -5.483098)
		(end 463.7278 -5.526278)
		(width 0.10795)
		(layer "B.Cu")
		(net "FM_PE_SLOTX24_WAKE_N")
	)
	(segment
		(start 483.338378 -58.748676)
		(end 482.65969 -58.069988)
		(width 0.10795)
		(layer "B.Cu")
		(net "FM_PE_SLOTX24_WAKE_N")
	)
	(segment
		(start 463.7278 -5.526278)
		(end 463.7278 -6.6675)
		(width 0.10795)
		(layer "B.Cu")
		(net "FM_PE_SLOTX24_WAKE_N")
	)
	(segment
		(start 477.918272 -37.6301)
		(end 478.638616 -38.350444)
		(width 0.089408)
		(layer "In9.Cu")
		(net "FM_PE_SLOTX24_WAKE_N")
	)
	(segment
		(start 477.457008 -48.91786)
		(end 477.19742 -49.177448)
		(width 0.089408)
		(layer "In9.Cu")
		(net "FM_PE_SLOTX24_WAKE_N")
	)
	(segment
		(start 478.4979 -52.5399)
		(end 479.3107 -52.5399)
		(width 0.089408)
		(layer "In9.Cu")
		(net "FM_PE_SLOTX24_WAKE_N")
	)
	(segment
		(start 478.638616 -38.350444)
		(end 478.638616 -39.939722)
		(width 0.089408)
		(layer "In9.Cu")
		(net "FM_PE_SLOTX24_WAKE_N")
	)
	(segment
		(start 483.236778 -58.748676)
		(end 483.338378 -58.748676)
		(width 0.089408)
		(layer "In9.Cu")
		(net "FM_PE_SLOTX24_WAKE_N")
	)
	(segment
		(start 469.070944 -13.142976)
		(end 470.965784 -13.142976)
		(width 0.089408)
		(layer "In9.Cu")
		(net "FM_PE_SLOTX24_WAKE_N")
	)
	(segment
		(start 480.464876 -28.763468)
		(end 480.464876 -33.510982)
		(width 0.089408)
		(layer "In9.Cu")
		(net "FM_PE_SLOTX24_WAKE_N")
	)
	(segment
		(start 482.940868 -59.044586)
		(end 483.236778 -58.748676)
		(width 0.089408)
		(layer "In9.Cu")
		(net "FM_PE_SLOTX24_WAKE_N")
	)
	(segment
		(start 478.638616 -39.939722)
		(end 477.903286 -40.675052)
		(width 0.089408)
		(layer "In9.Cu")
		(net "FM_PE_SLOTX24_WAKE_N")
	)
	(segment
		(start 468.432388 -11.312652)
		(end 468.432388 -12.50442)
		(width 0.089408)
		(layer "In9.Cu")
		(net "FM_PE_SLOTX24_WAKE_N")
	)
	(segment
		(start 482.040184 -27.913838)
		(end 481.314506 -27.913838)
		(width 0.089408)
		(layer "In9.Cu")
		(net "FM_PE_SLOTX24_WAKE_N")
	)
	(segment
		(start 475.806008 -17.9832)
		(end 475.806008 -20.92706)
		(width 0.089408)
		(layer "In9.Cu")
		(net "FM_PE_SLOTX24_WAKE_N")
	)
	(segment
		(start 481.314506 -27.913838)
		(end 480.464876 -28.763468)
		(width 0.089408)
		(layer "In9.Cu")
		(net "FM_PE_SLOTX24_WAKE_N")
	)
	(segment
		(start 468.432388 -12.50442)
		(end 469.070944 -13.142976)
		(width 0.089408)
		(layer "In9.Cu")
		(net "FM_PE_SLOTX24_WAKE_N")
	)
	(segment
		(start 466.9028 -6.0198)
		(end 468.43823 -7.55523)
		(width 0.089408)
		(layer "In9.Cu")
		(net "FM_PE_SLOTX24_WAKE_N")
	)
	(segment
		(start 464.307682 -6.0198)
		(end 466.9028 -6.0198)
		(width 0.089408)
		(layer "In9.Cu")
		(net "FM_PE_SLOTX24_WAKE_N")
	)
	(segment
		(start 468.43823 -11.30681)
		(end 468.432388 -11.312652)
		(width 0.089408)
		(layer "In9.Cu")
		(net "FM_PE_SLOTX24_WAKE_N")
	)
	(segment
		(start 470.965784 -13.142976)
		(end 475.806008 -17.9832)
		(width 0.089408)
		(layer "In9.Cu")
		(net "FM_PE_SLOTX24_WAKE_N")
	)
	(segment
		(start 477.19742 -51.23942)
		(end 478.4979 -52.5399)
		(width 0.089408)
		(layer "In9.Cu")
		(net "FM_PE_SLOTX24_WAKE_N")
	)
	(segment
		(start 480.187 -58.3692)
		(end 480.862386 -59.044586)
		(width 0.089408)
		(layer "In9.Cu")
		(net "FM_PE_SLOTX24_WAKE_N")
	)
	(segment
		(start 477.903286 -44.063666)
		(end 477.457008 -44.509944)
		(width 0.089408)
		(layer "In9.Cu")
		(net "FM_PE_SLOTX24_WAKE_N")
	)
	(segment
		(start 463.77098 -5.483098)
		(end 464.307682 -6.0198)
		(width 0.089408)
		(layer "In9.Cu")
		(net "FM_PE_SLOTX24_WAKE_N")
	)
	(segment
		(start 480.464876 -33.510982)
		(end 477.918272 -36.057586)
		(width 0.089408)
		(layer "In9.Cu")
		(net "FM_PE_SLOTX24_WAKE_N")
	)
	(segment
		(start 477.19742 -49.177448)
		(end 477.19742 -51.23942)
		(width 0.089408)
		(layer "In9.Cu")
		(net "FM_PE_SLOTX24_WAKE_N")
	)
	(segment
		(start 477.457008 -44.509944)
		(end 477.457008 -48.91786)
		(width 0.089408)
		(layer "In9.Cu")
		(net "FM_PE_SLOTX24_WAKE_N")
	)
	(segment
		(start 480.862386 -59.044586)
		(end 482.940868 -59.044586)
		(width 0.089408)
		(layer "In9.Cu")
		(net "FM_PE_SLOTX24_WAKE_N")
	)
	(segment
		(start 477.903286 -40.675052)
		(end 477.903286 -44.063666)
		(width 0.089408)
		(layer "In9.Cu")
		(net "FM_PE_SLOTX24_WAKE_N")
	)
	(segment
		(start 482.567742 -26.947368)
		(end 482.567742 -27.38628)
		(width 0.089408)
		(layer "In9.Cu")
		(net "FM_PE_SLOTX24_WAKE_N")
	)
	(segment
		(start 477.918272 -36.057586)
		(end 477.918272 -37.6301)
		(width 0.089408)
		(layer "In9.Cu")
		(net "FM_PE_SLOTX24_WAKE_N")
	)
	(segment
		(start 482.567742 -27.38628)
		(end 482.040184 -27.913838)
		(width 0.089408)
		(layer "In9.Cu")
		(net "FM_PE_SLOTX24_WAKE_N")
	)
	(segment
		(start 468.43823 -7.55523)
		(end 468.43823 -11.30681)
		(width 0.089408)
		(layer "In9.Cu")
		(net "FM_PE_SLOTX24_WAKE_N")
	)
	(segment
		(start 479.3107 -52.5399)
		(end 480.187 -53.4162)
		(width 0.089408)
		(layer "In9.Cu")
		(net "FM_PE_SLOTX24_WAKE_N")
	)
	(segment
		(start 475.806008 -20.92706)
		(end 477.180148 -22.3012)
		(width 0.089408)
		(layer "In9.Cu")
		(net "FM_PE_SLOTX24_WAKE_N")
	)
	(segment
		(start 480.187 -53.4162)
		(end 480.187 -58.3692)
		(width 0.089408)
		(layer "In9.Cu")
		(net "FM_PE_SLOTX24_WAKE_N")
	)
	(segment
		(start 477.921574 -22.3012)
		(end 482.567742 -26.947368)
		(width 0.089408)
		(layer "In9.Cu")
		(net "FM_PE_SLOTX24_WAKE_N")
	)
	(segment
		(start 477.180148 -22.3012)
		(end 477.921574 -22.3012)
		(width 0.089408)
		(layer "In9.Cu")
		(net "FM_PE_SLOTX24_WAKE_N")
	)
	(segment
		(start 475.000828 -114.881406)
		(end 475.000828 -112.205516)
		(width 0.10795)
		(layer "F.Cu")
		(net "FM_PE_OCP_WAKE_N")
	)
	(segment
		(start 475.18701 -115.067588)
		(end 475.000828 -114.881406)
		(width 0.10795)
		(layer "F.Cu")
		(net "FM_PE_OCP_WAKE_N")
	)
	(via
		(at 478.0026 -56.9214)
		(size 0.508)
		(drill 0.254)
		(layers "F.Cu" "B.Cu")
		(net "FM_PE_OCP_WAKE_N")
	)
	(via
		(at 475.18701 -115.067588)
		(size 0.508)
		(drill 0.254)
		(layers "F.Cu" "B.Cu")
		(net "FM_PE_OCP_WAKE_N")
	)
	(via
		(at 478.972626 -59.026044)
		(size 0.6604)
		(drill 0.3302)
		(layers "F.Cu" "B.Cu")
		(net "FM_PE_OCP_WAKE_N")
	)
	(segment
		(start 477.9772 -56.9468)
		(end 478.0026 -56.9214)
		(width 0.10795)
		(layer "B.Cu")
		(net "FM_PE_OCP_WAKE_N")
	)
	(segment
		(start 480.829874 -59.219338)
		(end 480.878388 -59.267852)
		(width 0.10795)
		(layer "B.Cu")
		(net "FM_PE_OCP_WAKE_N")
	)
	(segment
		(start 478.972626 -59.026044)
		(end 479.16592 -59.219338)
		(width 0.10795)
		(layer "B.Cu")
		(net "FM_PE_OCP_WAKE_N")
	)
	(segment
		(start 482.55174 -59.267852)
		(end 482.65969 -59.159902)
		(width 0.10795)
		(layer "B.Cu")
		(net "FM_PE_OCP_WAKE_N")
	)
	(segment
		(start 478.972626 -59.026044)
		(end 477.9772 -58.030618)
		(width 0.10795)
		(layer "B.Cu")
		(net "FM_PE_OCP_WAKE_N")
	)
	(segment
		(start 480.878388 -59.267852)
		(end 482.55174 -59.267852)
		(width 0.10795)
		(layer "B.Cu")
		(net "FM_PE_OCP_WAKE_N")
	)
	(segment
		(start 479.16592 -59.219338)
		(end 480.829874 -59.219338)
		(width 0.10795)
		(layer "B.Cu")
		(net "FM_PE_OCP_WAKE_N")
	)
	(segment
		(start 482.65969 -59.159902)
		(end 482.65969 -58.831988)
		(width 0.10795)
		(layer "B.Cu")
		(net "FM_PE_OCP_WAKE_N")
	)
	(segment
		(start 477.9772 -58.030618)
		(end 477.9772 -56.9468)
		(width 0.10795)
		(layer "B.Cu")
		(net "FM_PE_OCP_WAKE_N")
	)
	(segment
		(start 472.905582 -111.761016)
		(end 439.785506 -111.761016)
		(width 0.089408)
		(layer "In11.Cu")
		(net "FM_PE_OCP_WAKE_N")
	)
	(segment
		(start 425.748704 -77.667104)
		(end 425.748704 -68.18249)
		(width 0.089408)
		(layer "In11.Cu")
		(net "FM_PE_OCP_WAKE_N")
	)
	(segment
		(start 474.755464 -114.636042)
		(end 474.755464 -113.610898)
		(width 0.089408)
		(layer "In11.Cu")
		(net "FM_PE_OCP_WAKE_N")
	)
	(segment
		(start 439.785506 -111.761016)
		(end 438.808368 -110.783878)
		(width 0.089408)
		(layer "In11.Cu")
		(net "FM_PE_OCP_WAKE_N")
	)
	(segment
		(start 474.755464 -113.610898)
		(end 472.905582 -111.761016)
		(width 0.089408)
		(layer "In11.Cu")
		(net "FM_PE_OCP_WAKE_N")
	)
	(segment
		(start 425.748704 -68.18249)
		(end 429.211486 -64.719708)
		(width 0.089408)
		(layer "In11.Cu")
		(net "FM_PE_OCP_WAKE_N")
	)
	(segment
		(start 429.211486 -64.719708)
		(end 466.25256 -64.719708)
		(width 0.089408)
		(layer "In11.Cu")
		(net "FM_PE_OCP_WAKE_N")
	)
	(segment
		(start 475.469204 -55.248556)
		(end 477.142048 -56.9214)
		(width 0.089408)
		(layer "In11.Cu")
		(net "FM_PE_OCP_WAKE_N")
	)
	(segment
		(start 426.390054 -78.308454)
		(end 425.748704 -77.667104)
		(width 0.089408)
		(layer "In11.Cu")
		(net "FM_PE_OCP_WAKE_N")
	)
	(segment
		(start 426.390054 -109.666278)
		(end 426.390054 -78.308454)
		(width 0.089408)
		(layer "In11.Cu")
		(net "FM_PE_OCP_WAKE_N")
	)
	(segment
		(start 475.18701 -115.067588)
		(end 474.755464 -114.636042)
		(width 0.089408)
		(layer "In11.Cu")
		(net "FM_PE_OCP_WAKE_N")
	)
	(segment
		(start 468.870538 -59.340242)
		(end 472.962224 -55.248556)
		(width 0.089408)
		(layer "In11.Cu")
		(net "FM_PE_OCP_WAKE_N")
	)
	(segment
		(start 477.142048 -56.9214)
		(end 478.0026 -56.9214)
		(width 0.089408)
		(layer "In11.Cu")
		(net "FM_PE_OCP_WAKE_N")
	)
	(segment
		(start 427.507654 -110.783878)
		(end 426.390054 -109.666278)
		(width 0.089408)
		(layer "In11.Cu")
		(net "FM_PE_OCP_WAKE_N")
	)
	(segment
		(start 438.808368 -110.783878)
		(end 427.507654 -110.783878)
		(width 0.089408)
		(layer "In11.Cu")
		(net "FM_PE_OCP_WAKE_N")
	)
	(segment
		(start 466.25256 -64.719708)
		(end 468.870538 -62.10173)
		(width 0.089408)
		(layer "In11.Cu")
		(net "FM_PE_OCP_WAKE_N")
	)
	(segment
		(start 468.870538 -62.10173)
		(end 468.870538 -59.340242)
		(width 0.089408)
		(layer "In11.Cu")
		(net "FM_PE_OCP_WAKE_N")
	)
	(segment
		(start 472.962224 -55.248556)
		(end 475.469204 -55.248556)
		(width 0.089408)
		(layer "In11.Cu")
		(net "FM_PE_OCP_WAKE_N")
	)
	(segment
		(start 391.36828 -34.183574)
		(end 391.030968 -34.520886)
		(width 0.10795)
		(layer "F.Cu")
		(net "FM_PE_M2_WAKE_N")
	)
	(segment
		(start 391.36828 -34.024316)
		(end 391.36828 -34.183574)
		(width 0.10795)
		(layer "F.Cu")
		(net "FM_PE_M2_WAKE_N")
	)
	(segment
		(start 391.030968 -34.520886)
		(end 390.347454 -34.520886)
		(width 0.10795)
		(layer "F.Cu")
		(net "FM_PE_M2_WAKE_N")
	)
	(segment
		(start 391.529062 -33.863534)
		(end 391.36828 -34.024316)
		(width 0.10795)
		(layer "F.Cu")
		(net "FM_PE_M2_WAKE_N")
	)
	(segment
		(start 391.84199 -33.863534)
		(end 391.529062 -33.863534)
		(width 0.10795)
		(layer "F.Cu")
		(net "FM_PE_M2_WAKE_N")
	)
	(via
		(at 434.3146 -47.5742)
		(size 0.508)
		(drill 0.254)
		(layers "F.Cu" "B.Cu")
		(net "FM_PE_M2_WAKE_N")
	)
	(via
		(at 391.84199 -33.863534)
		(size 0.508)
		(drill 0.254)
		(layers "F.Cu" "B.Cu")
		(net "FM_PE_M2_WAKE_N")
	)
	(via
		(at 483.370128 -58.005472)
		(size 0.508)
		(drill 0.254)
		(layers "F.Cu" "B.Cu")
		(net "FM_PE_M2_WAKE_N")
	)
	(via
		(at 433.9844 -46.4312)
		(size 0.6604)
		(drill 0.3302)
		(layers "F.Cu" "B.Cu")
		(net "FM_PE_M2_WAKE_N")
	)
	(via
		(at 391.9474 -46.768512)
		(size 0.508)
		(drill 0.254)
		(layers "F.Cu" "B.Cu")
		(net "FM_PE_M2_WAKE_N")
	)
	(segment
		(start 483.357174 -58.005472)
		(end 483.370128 -58.005472)
		(width 0.10795)
		(layer "B.Cu")
		(net "FM_PE_M2_WAKE_N")
	)
	(segment
		(start 482.65969 -57.307988)
		(end 483.357174 -58.005472)
		(width 0.10795)
		(layer "B.Cu")
		(net "FM_PE_M2_WAKE_N")
	)
	(segment
		(start 433.9844 -46.4312)
		(end 434.3146 -46.7614)
		(width 0.10795)
		(layer "B.Cu")
		(net "FM_PE_M2_WAKE_N")
	)
	(segment
		(start 434.3146 -46.7614)
		(end 434.3146 -47.5742)
		(width 0.10795)
		(layer "B.Cu")
		(net "FM_PE_M2_WAKE_N")
	)
	(segment
		(start 432.317906 -50.064416)
		(end 429.27016 -50.064416)
		(width 0.089408)
		(layer "In2.Cu")
		(net "FM_PE_M2_WAKE_N")
	)
	(segment
		(start 424.78198 -46.855634)
		(end 424.774614 -46.863)
		(width 0.089408)
		(layer "In2.Cu")
		(net "FM_PE_M2_WAKE_N")
	)
	(segment
		(start 402.314156 -46.722792)
		(end 391.99312 -46.722792)
		(width 0.089408)
		(layer "In2.Cu")
		(net "FM_PE_M2_WAKE_N")
	)
	(segment
		(start 411.393132 -44.776136)
		(end 411.008068 -44.776136)
		(width 0.089408)
		(layer "In2.Cu")
		(net "FM_PE_M2_WAKE_N")
	)
	(segment
		(start 391.99312 -46.722792)
		(end 391.9474 -46.768512)
		(width 0.089408)
		(layer "In2.Cu")
		(net "FM_PE_M2_WAKE_N")
	)
	(segment
		(start 427.548802 -47.9806)
		(end 427.425612 -48.10379)
		(width 0.089408)
		(layer "In2.Cu")
		(net "FM_PE_M2_WAKE_N")
	)
	(segment
		(start 428.390304 -47.9806)
		(end 427.548802 -47.9806)
		(width 0.089408)
		(layer "In2.Cu")
		(net "FM_PE_M2_WAKE_N")
	)
	(segment
		(start 418.91077 -44.775882)
		(end 418.910516 -44.776136)
		(width 0.089408)
		(layer "In2.Cu")
		(net "FM_PE_M2_WAKE_N")
	)
	(segment
		(start 420.762938 -44.776136)
		(end 420.762684 -44.775882)
		(width 0.089408)
		(layer "In2.Cu")
		(net "FM_PE_M2_WAKE_N")
	)
	(segment
		(start 421.191436 -46.47184)
		(end 421.191436 -45.093636)
		(width 0.089408)
		(layer "In2.Cu")
		(net "FM_PE_M2_WAKE_N")
	)
	(segment
		(start 426.029882 -48.103536)
		(end 424.78198 -46.855634)
		(width 0.089408)
		(layer "In2.Cu")
		(net "FM_PE_M2_WAKE_N")
	)
	(segment
		(start 420.873936 -44.776136)
		(end 420.762938 -44.776136)
		(width 0.089408)
		(layer "In2.Cu")
		(net "FM_PE_M2_WAKE_N")
	)
	(segment
		(start 429.27016 -50.064416)
		(end 428.9171 -49.711356)
		(width 0.089408)
		(layer "In2.Cu")
		(net "FM_PE_M2_WAKE_N")
	)
	(segment
		(start 418.910516 -44.776136)
		(end 418.188902 -44.776136)
		(width 0.089408)
		(layer "In2.Cu")
		(net "FM_PE_M2_WAKE_N")
	)
	(segment
		(start 427.312074 -48.10379)
		(end 427.31182 -48.103536)
		(width 0.089408)
		(layer "In2.Cu")
		(net "FM_PE_M2_WAKE_N")
	)
	(segment
		(start 411.008068 -44.776136)
		(end 410.692092 -44.46016)
		(width 0.089408)
		(layer "In2.Cu")
		(net "FM_PE_M2_WAKE_N")
	)
	(segment
		(start 428.9171 -48.507396)
		(end 428.390304 -47.9806)
		(width 0.089408)
		(layer "In2.Cu")
		(net "FM_PE_M2_WAKE_N")
	)
	(segment
		(start 410.136848 -44.704508)
		(end 404.33244 -44.704508)
		(width 0.089408)
		(layer "In2.Cu")
		(net "FM_PE_M2_WAKE_N")
	)
	(segment
		(start 433.4256 -47.371)
		(end 433.155852 -47.640748)
		(width 0.089408)
		(layer "In2.Cu")
		(net "FM_PE_M2_WAKE_N")
	)
	(segment
		(start 410.692092 -44.46016)
		(end 410.381196 -44.46016)
		(width 0.089408)
		(layer "In2.Cu")
		(net "FM_PE_M2_WAKE_N")
	)
	(segment
		(start 428.9171 -49.711356)
		(end 428.9171 -48.507396)
		(width 0.089408)
		(layer "In2.Cu")
		(net "FM_PE_M2_WAKE_N")
	)
	(segment
		(start 411.397704 -44.780708)
		(end 411.393132 -44.776136)
		(width 0.089408)
		(layer "In2.Cu")
		(net "FM_PE_M2_WAKE_N")
	)
	(segment
		(start 424.774614 -46.863)
		(end 421.582596 -46.863)
		(width 0.089408)
		(layer "In2.Cu")
		(net "FM_PE_M2_WAKE_N")
	)
	(segment
		(start 410.381196 -44.46016)
		(end 410.136848 -44.704508)
		(width 0.089408)
		(layer "In2.Cu")
		(net "FM_PE_M2_WAKE_N")
	)
	(segment
		(start 427.31182 -48.103536)
		(end 426.029882 -48.103536)
		(width 0.089408)
		(layer "In2.Cu")
		(net "FM_PE_M2_WAKE_N")
	)
	(segment
		(start 427.425612 -48.10379)
		(end 427.312074 -48.10379)
		(width 0.089408)
		(layer "In2.Cu")
		(net "FM_PE_M2_WAKE_N")
	)
	(segment
		(start 421.191436 -45.093636)
		(end 420.873936 -44.776136)
		(width 0.089408)
		(layer "In2.Cu")
		(net "FM_PE_M2_WAKE_N")
	)
	(segment
		(start 404.33244 -44.704508)
		(end 402.314156 -46.722792)
		(width 0.089408)
		(layer "In2.Cu")
		(net "FM_PE_M2_WAKE_N")
	)
	(segment
		(start 433.155852 -49.22647)
		(end 432.317906 -50.064416)
		(width 0.089408)
		(layer "In2.Cu")
		(net "FM_PE_M2_WAKE_N")
	)
	(segment
		(start 421.582596 -46.863)
		(end 421.191436 -46.47184)
		(width 0.089408)
		(layer "In2.Cu")
		(net "FM_PE_M2_WAKE_N")
	)
	(segment
		(start 420.762684 -44.775882)
		(end 418.91077 -44.775882)
		(width 0.089408)
		(layer "In2.Cu")
		(net "FM_PE_M2_WAKE_N")
	)
	(segment
		(start 418.188902 -44.776136)
		(end 418.18433 -44.780708)
		(width 0.089408)
		(layer "In2.Cu")
		(net "FM_PE_M2_WAKE_N")
	)
	(segment
		(start 434.1114 -47.371)
		(end 433.4256 -47.371)
		(width 0.089408)
		(layer "In2.Cu")
		(net "FM_PE_M2_WAKE_N")
	)
	(segment
		(start 434.3146 -47.5742)
		(end 434.1114 -47.371)
		(width 0.089408)
		(layer "In2.Cu")
		(net "FM_PE_M2_WAKE_N")
	)
	(segment
		(start 433.155852 -47.640748)
		(end 433.155852 -49.22647)
		(width 0.089408)
		(layer "In2.Cu")
		(net "FM_PE_M2_WAKE_N")
	)
	(segment
		(start 418.18433 -44.780708)
		(end 411.397704 -44.780708)
		(width 0.089408)
		(layer "In2.Cu")
		(net "FM_PE_M2_WAKE_N")
	)
	(segment
		(start 393.12342 -37.110924)
		(end 392.119866 -36.10737)
		(width 0.089408)
		(layer "In9.Cu")
		(net "FM_PE_M2_WAKE_N")
	)
	(segment
		(start 391.9474 -46.768512)
		(end 392.280394 -46.435518)
		(width 0.089408)
		(layer "In9.Cu")
		(net "FM_PE_M2_WAKE_N")
	)
	(segment
		(start 392.280394 -42.896536)
		(end 393.407392 -41.768776)
		(width 0.089408)
		(layer "In9.Cu")
		(net "FM_PE_M2_WAKE_N")
	)
	(segment
		(start 393.51077 -41.665398)
		(end 393.51077 -40.572436)
		(width 0.089408)
		(layer "In9.Cu")
		(net "FM_PE_M2_WAKE_N")
	)
	(segment
		(start 393.51077 -40.572436)
		(end 393.12342 -40.185086)
		(width 0.089408)
		(layer "In9.Cu")
		(net "FM_PE_M2_WAKE_N")
	)
	(segment
		(start 393.407392 -41.768776)
		(end 393.51077 -41.665398)
		(width 0.089408)
		(layer "In9.Cu")
		(net "FM_PE_M2_WAKE_N")
	)
	(segment
		(start 393.12342 -40.185086)
		(end 393.12342 -37.110924)
		(width 0.089408)
		(layer "In9.Cu")
		(net "FM_PE_M2_WAKE_N")
	)
	(segment
		(start 392.119866 -34.14141)
		(end 391.84199 -33.863534)
		(width 0.089408)
		(layer "In9.Cu")
		(net "FM_PE_M2_WAKE_N")
	)
	(segment
		(start 392.119866 -36.10737)
		(end 392.119866 -34.14141)
		(width 0.089408)
		(layer "In9.Cu")
		(net "FM_PE_M2_WAKE_N")
	)
	(segment
		(start 392.280394 -46.435518)
		(end 392.280394 -42.896536)
		(width 0.089408)
		(layer "In9.Cu")
		(net "FM_PE_M2_WAKE_N")
	)
	(segment
		(start 436.27929 -49.0982)
		(end 435.092348 -48.60671)
		(width 0.089408)
		(layer "In11.Cu")
		(net "FM_PE_M2_WAKE_N")
	)
	(segment
		(start 469.3158 -49.0982)
		(end 436.27929 -49.0982)
		(width 0.089408)
		(layer "In11.Cu")
		(net "FM_PE_M2_WAKE_N")
	)
	(segment
		(start 482.4984 -57.1246)
		(end 481.217732 -57.1246)
		(width 0.089408)
		(layer "In11.Cu")
		(net "FM_PE_M2_WAKE_N")
	)
	(segment
		(start 483.370128 -58.005472)
		(end 483.370128 -57.996328)
		(width 0.089408)
		(layer "In11.Cu")
		(net "FM_PE_M2_WAKE_N")
	)
	(segment
		(start 474.317568 -53.857398)
		(end 473.6084 -53.14823)
		(width 0.089408)
		(layer "In11.Cu")
		(net "FM_PE_M2_WAKE_N")
	)
	(segment
		(start 469.8746 -48.5394)
		(end 469.3158 -49.0982)
		(width 0.089408)
		(layer "In11.Cu")
		(net "FM_PE_M2_WAKE_N")
	)
	(segment
		(start 472.966288 -50.953924)
		(end 472.966034 -50.95367)
		(width 0.089408)
		(layer "In11.Cu")
		(net "FM_PE_M2_WAKE_N")
	)
	(segment
		(start 477.084136 -56.521096)
		(end 474.420438 -53.857398)
		(width 0.089408)
		(layer "In11.Cu")
		(net "FM_PE_M2_WAKE_N")
	)
	(segment
		(start 483.370128 -57.996328)
		(end 482.4984 -57.1246)
		(width 0.089408)
		(layer "In11.Cu")
		(net "FM_PE_M2_WAKE_N")
	)
	(segment
		(start 473.6084 -52.363878)
		(end 472.966288 -51.721766)
		(width 0.089408)
		(layer "In11.Cu")
		(net "FM_PE_M2_WAKE_N")
	)
	(segment
		(start 473.6084 -53.14823)
		(end 473.6084 -52.363878)
		(width 0.089408)
		(layer "In11.Cu")
		(net "FM_PE_M2_WAKE_N")
	)
	(segment
		(start 480.614228 -56.521096)
		(end 477.084136 -56.521096)
		(width 0.089408)
		(layer "In11.Cu")
		(net "FM_PE_M2_WAKE_N")
	)
	(segment
		(start 472.966034 -50.95367)
		(end 472.966034 -50.795682)
		(width 0.089408)
		(layer "In11.Cu")
		(net "FM_PE_M2_WAKE_N")
	)
	(segment
		(start 472.966288 -51.721766)
		(end 472.966288 -50.953924)
		(width 0.089408)
		(layer "In11.Cu")
		(net "FM_PE_M2_WAKE_N")
	)
	(segment
		(start 472.966034 -50.795682)
		(end 472.966288 -50.795428)
		(width 0.089408)
		(layer "In11.Cu")
		(net "FM_PE_M2_WAKE_N")
	)
	(segment
		(start 434.3146 -47.828962)
		(end 434.3146 -47.5742)
		(width 0.089408)
		(layer "In11.Cu")
		(net "FM_PE_M2_WAKE_N")
	)
	(segment
		(start 472.966288 -50.16881)
		(end 471.336878 -48.5394)
		(width 0.089408)
		(layer "In11.Cu")
		(net "FM_PE_M2_WAKE_N")
	)
	(segment
		(start 435.092348 -48.60671)
		(end 434.3146 -47.828962)
		(width 0.089408)
		(layer "In11.Cu")
		(net "FM_PE_M2_WAKE_N")
	)
	(segment
		(start 481.217732 -57.1246)
		(end 480.614228 -56.521096)
		(width 0.089408)
		(layer "In11.Cu")
		(net "FM_PE_M2_WAKE_N")
	)
	(segment
		(start 472.966288 -50.795428)
		(end 472.966288 -50.16881)
		(width 0.089408)
		(layer "In11.Cu")
		(net "FM_PE_M2_WAKE_N")
	)
	(segment
		(start 474.420438 -53.857398)
		(end 474.317568 -53.857398)
		(width 0.089408)
		(layer "In11.Cu")
		(net "FM_PE_M2_WAKE_N")
	)
	(segment
		(start 471.336878 -48.5394)
		(end 469.8746 -48.5394)
		(width 0.089408)
		(layer "In11.Cu")
		(net "FM_PE_M2_WAKE_N")
	)
	(segment
		(start 368.431318 -36.34232)
		(end 368.604292 -36.515294)
		(width 0.10795)
		(layer "F.Cu")
		(net "SPI_BMC_BT_DI_R")
	)
	(segment
		(start 367.088928 -36.34232)
		(end 368.431318 -36.34232)
		(width 0.10795)
		(layer "F.Cu")
		(net "SPI_BMC_BT_DI_R")
	)
	(via
		(at 366.1664 -37.1856)
		(size 0.6604)
		(drill 0.3302)
		(layers "F.Cu" "B.Cu")
		(net "SPI_BMC_BT_DI_R")
	)
	(via
		(at 368.604292 -36.515294)
		(size 0.508)
		(drill 0.254)
		(layers "F.Cu" "B.Cu")
		(net "SPI_BMC_BT_DI_R")
	)
	(segment
		(start 368.342164 -36.253166)
		(end 368.604292 -36.515294)
		(width 0.10795)
		(layer "B.Cu")
		(net "SPI_BMC_BT_DI_R")
	)
	(segment
		(start 367.637314 -36.253166)
		(end 368.342164 -36.253166)
		(width 0.10795)
		(layer "B.Cu")
		(net "SPI_BMC_BT_DI_R")
	)
	(segment
		(start 367.098834 -36.253166)
		(end 366.1664 -37.1856)
		(width 0.10795)
		(layer "B.Cu")
		(net "SPI_BMC_BT_DI_R")
	)
	(segment
		(start 367.637314 -36.253166)
		(end 367.098834 -36.253166)
		(width 0.10795)
		(layer "B.Cu")
		(net "SPI_BMC_BT_DI_R")
	)
	(segment
		(start 368.646964 -41.985184)
		(end 367.939828 -42.69232)
		(width 0.10795)
		(layer "F.Cu")
		(net "PU_SPI_FLASH_RESET_2_N")
	)
	(segment
		(start 367.939828 -42.69232)
		(end 367.088928 -42.69232)
		(width 0.10795)
		(layer "F.Cu")
		(net "PU_SPI_FLASH_RESET_2_N")
	)
	(via
		(at 368.646964 -41.985184)
		(size 0.508)
		(drill 0.254)
		(layers "F.Cu" "B.Cu")
		(net "PU_SPI_FLASH_RESET_2_N")
	)
	(via
		(at 368.3635 -40.97782)
		(size 0.6604)
		(drill 0.3302)
		(layers "F.Cu" "B.Cu")
		(net "PU_SPI_FLASH_RESET_2_N")
	)
	(segment
		(start 368.646964 -41.261284)
		(end 368.3635 -40.97782)
		(width 0.10795)
		(layer "B.Cu")
		(net "PU_SPI_FLASH_RESET_2_N")
	)
	(segment
		(start 368.3635 -40.97782)
		(end 368.3635 -39.871396)
		(width 0.10795)
		(layer "B.Cu")
		(net "PU_SPI_FLASH_RESET_2_N")
	)
	(segment
		(start 367.430304 -38.9382)
		(end 367.157 -38.9382)
		(width 0.10795)
		(layer "B.Cu")
		(net "PU_SPI_FLASH_RESET_2_N")
	)
	(segment
		(start 368.3635 -39.871396)
		(end 367.430304 -38.9382)
		(width 0.10795)
		(layer "B.Cu")
		(net "PU_SPI_FLASH_RESET_2_N")
	)
	(segment
		(start 368.646964 -41.985184)
		(end 368.646964 -41.261284)
		(width 0.10795)
		(layer "B.Cu")
		(net "PU_SPI_FLASH_RESET_2_N")
	)
	(via
		(at 400.0246 -49.784)
		(size 0.6604)
		(drill 0.3302)
		(layers "F.Cu" "B.Cu")
		(net "TP_SPI_1_4")
	)
	(segment
		(start 400.00428 -49.76368)
		(end 400.0246 -49.784)
		(width 0.10795)
		(layer "B.Cu")
		(net "TP_SPI_1_4")
	)
	(segment
		(start 398.093946 -49.76368)
		(end 400.00428 -49.76368)
		(width 0.10795)
		(layer "B.Cu")
		(net "TP_SPI_1_4")
	)
	(via
		(at 399.9738 -51.0794)
		(size 0.6604)
		(drill 0.3302)
		(layers "F.Cu" "B.Cu")
		(net "TP_SPI_1_5")
	)
	(segment
		(start 399.92808 -51.03368)
		(end 399.9738 -51.0794)
		(width 0.10795)
		(layer "B.Cu")
		(net "TP_SPI_1_5")
	)
	(segment
		(start 398.093946 -51.03368)
		(end 399.92808 -51.03368)
		(width 0.10795)
		(layer "B.Cu")
		(net "TP_SPI_1_5")
	)
	(via
		(at 399.923 -52.3494)
		(size 0.6604)
		(drill 0.3302)
		(layers "F.Cu" "B.Cu")
		(net "TP_SPI_1_6")
	)
	(segment
		(start 399.87728 -52.30368)
		(end 399.923 -52.3494)
		(width 0.10795)
		(layer "B.Cu")
		(net "TP_SPI_1_6")
	)
	(segment
		(start 398.093946 -52.30368)
		(end 399.87728 -52.30368)
		(width 0.10795)
		(layer "B.Cu")
		(net "TP_SPI_1_6")
	)
	(segment
		(start 384.007868 -54.15915)
		(end 385.51485 -54.15915)
		(width 0.10795)
		(layer "F.Cu")
		(net "TP_SPI_0_2")
	)
	(segment
		(start 387.37032 -52.30368)
		(end 388.543546 -52.30368)
		(width 0.10795)
		(layer "F.Cu")
		(net "TP_SPI_0_2")
	)
	(segment
		(start 382.27 -53.086)
		(end 382.934718 -53.086)
		(width 0.10795)
		(layer "F.Cu")
		(net "TP_SPI_0_2")
	)
	(segment
		(start 382.934718 -53.086)
		(end 384.007868 -54.15915)
		(width 0.10795)
		(layer "F.Cu")
		(net "TP_SPI_0_2")
	)
	(segment
		(start 385.51485 -54.15915)
		(end 387.37032 -52.30368)
		(width 0.10795)
		(layer "F.Cu")
		(net "TP_SPI_0_2")
	)
	(via
		(at 382.27 -53.086)
		(size 0.762)
		(drill 0.381)
		(layers "F.Cu" "B.Cu")
		(net "TP_SPI_0_2")
	)
	(segment
		(start 383.634742 -54.6608)
		(end 386.1562 -54.6608)
		(width 0.10795)
		(layer "F.Cu")
		(net "TP_SPI_0_3")
	)
	(segment
		(start 382.27 -54.356)
		(end 383.329942 -54.356)
		(width 0.10795)
		(layer "F.Cu")
		(net "TP_SPI_0_3")
	)
	(segment
		(start 386.1562 -54.6608)
		(end 387.24332 -53.57368)
		(width 0.10795)
		(layer "F.Cu")
		(net "TP_SPI_0_3")
	)
	(segment
		(start 387.24332 -53.57368)
		(end 388.543546 -53.57368)
		(width 0.10795)
		(layer "F.Cu")
		(net "TP_SPI_0_3")
	)
	(segment
		(start 383.329942 -54.356)
		(end 383.634742 -54.6608)
		(width 0.10795)
		(layer "F.Cu")
		(net "TP_SPI_0_3")
	)
	(via
		(at 382.27 -54.356)
		(size 0.762)
		(drill 0.381)
		(layers "F.Cu" "B.Cu")
		(net "TP_SPI_0_3")
	)
	(segment
		(start 385.8768 -51.6128)
		(end 385.257294 -51.6128)
		(width 0.10795)
		(layer "F.Cu")
		(net "SPI_SWITCH_MOSI")
	)
	(segment
		(start 385.257294 -51.6128)
		(end 385.215892 -51.571398)
		(width 0.10795)
		(layer "F.Cu")
		(net "SPI_SWITCH_MOSI")
	)
	(via
		(at 385.472432 -56.188864)
		(size 0.6604)
		(drill 0.3302)
		(layers "F.Cu" "B.Cu")
		(net "SPI_SWITCH_MOSI")
	)
	(via
		(at 385.215892 -51.571398)
		(size 0.508)
		(drill 0.254)
		(layers "F.Cu" "B.Cu")
		(net "SPI_SWITCH_MOSI")
	)
	(segment
		(start 385.215892 -51.571398)
		(end 384.952494 -51.308)
		(width 0.10795)
		(layer "B.Cu")
		(net "SPI_SWITCH_MOSI")
	)
	(segment
		(start 381.4445 -50.9905)
		(end 381.1778 -51.2572)
		(width 0.10795)
		(layer "B.Cu")
		(net "SPI_SWITCH_MOSI")
	)
	(segment
		(start 384.9878 -56.4134)
		(end 385.212336 -56.188864)
		(width 0.10795)
		(layer "B.Cu")
		(net "SPI_SWITCH_MOSI")
	)
	(segment
		(start 386.59181 -57.61101)
		(end 385.472432 -56.491632)
		(width 0.10795)
		(layer "B.Cu")
		(net "SPI_SWITCH_MOSI")
	)
	(segment
		(start 381.1778 -52.6034)
		(end 380.873 -52.9082)
		(width 0.10795)
		(layer "B.Cu")
		(net "SPI_SWITCH_MOSI")
	)
	(segment
		(start 381.1778 -51.2572)
		(end 381.1778 -52.6034)
		(width 0.10795)
		(layer "B.Cu")
		(net "SPI_SWITCH_MOSI")
	)
	(segment
		(start 380.873 -55.10911)
		(end 382.17729 -56.4134)
		(width 0.10795)
		(layer "B.Cu")
		(net "SPI_SWITCH_MOSI")
	)
	(segment
		(start 383.9591 -51.308)
		(end 383.6416 -50.9905)
		(width 0.10795)
		(layer "B.Cu")
		(net "SPI_SWITCH_MOSI")
	)
	(segment
		(start 385.212336 -56.188864)
		(end 385.472432 -56.188864)
		(width 0.10795)
		(layer "B.Cu")
		(net "SPI_SWITCH_MOSI")
	)
	(segment
		(start 383.6416 -50.9905)
		(end 382.5875 -50.9905)
		(width 0.10795)
		(layer "B.Cu")
		(net "SPI_SWITCH_MOSI")
	)
	(segment
		(start 386.59181 -58.007504)
		(end 386.59181 -57.61101)
		(width 0.10795)
		(layer "B.Cu")
		(net "SPI_SWITCH_MOSI")
	)
	(segment
		(start 387.163056 -58.57875)
		(end 386.59181 -58.007504)
		(width 0.10795)
		(layer "B.Cu")
		(net "SPI_SWITCH_MOSI")
	)
	(segment
		(start 385.472432 -56.491632)
		(end 385.472432 -56.188864)
		(width 0.10795)
		(layer "B.Cu")
		(net "SPI_SWITCH_MOSI")
	)
	(segment
		(start 382.5875 -50.9905)
		(end 381.4445 -50.9905)
		(width 0.10795)
		(layer "B.Cu")
		(net "SPI_SWITCH_MOSI")
	)
	(segment
		(start 384.952494 -51.308)
		(end 383.9591 -51.308)
		(width 0.10795)
		(layer "B.Cu")
		(net "SPI_SWITCH_MOSI")
	)
	(segment
		(start 382.17729 -56.4134)
		(end 384.9878 -56.4134)
		(width 0.10795)
		(layer "B.Cu")
		(net "SPI_SWITCH_MOSI")
	)
	(segment
		(start 380.873 -52.9082)
		(end 380.873 -55.10911)
		(width 0.10795)
		(layer "B.Cu")
		(net "SPI_SWITCH_MOSI")
	)
	(segment
		(start 387.457188 -58.57875)
		(end 387.163056 -58.57875)
		(width 0.10795)
		(layer "B.Cu")
		(net "SPI_SWITCH_MOSI")
	)
	(segment
		(start 389.769096 -58.665364)
		(end 391.52576 -56.9087)
		(width 0.10795)
		(layer "F.Cu")
		(net "SPI_SWITCH_MISO")
	)
	(segment
		(start 401.64385 -55.25008)
		(end 401.7518 -55.14213)
		(width 0.10795)
		(layer "F.Cu")
		(net "SPI_SWITCH_MISO")
	)
	(segment
		(start 380.613412 -59.35345)
		(end 381.960882 -59.35345)
		(width 0.10795)
		(layer "F.Cu")
		(net "SPI_SWITCH_MISO")
	)
	(segment
		(start 401.7518 -55.14213)
		(end 401.7518 -54.80558)
		(width 0.10795)
		(layer "F.Cu")
		(net "SPI_SWITCH_MISO")
	)
	(segment
		(start 399.35023 -56.47563)
		(end 399.356834 -56.47563)
		(width 0.10795)
		(layer "F.Cu")
		(net "SPI_SWITCH_MISO")
	)
	(segment
		(start 399.356834 -56.47563)
		(end 400.582384 -55.25008)
		(width 0.10795)
		(layer "F.Cu")
		(net "SPI_SWITCH_MISO")
	)
	(segment
		(start 382.648968 -58.665364)
		(end 389.769096 -58.665364)
		(width 0.10795)
		(layer "F.Cu")
		(net "SPI_SWITCH_MISO")
	)
	(segment
		(start 400.582384 -55.25008)
		(end 401.64385 -55.25008)
		(width 0.10795)
		(layer "F.Cu")
		(net "SPI_SWITCH_MISO")
	)
	(segment
		(start 391.52576 -56.9087)
		(end 398.91716 -56.9087)
		(width 0.10795)
		(layer "F.Cu")
		(net "SPI_SWITCH_MISO")
	)
	(segment
		(start 381.960882 -59.35345)
		(end 382.648968 -58.665364)
		(width 0.10795)
		(layer "F.Cu")
		(net "SPI_SWITCH_MISO")
	)
	(segment
		(start 398.91716 -56.9087)
		(end 399.35023 -56.47563)
		(width 0.10795)
		(layer "F.Cu")
		(net "SPI_SWITCH_MISO")
	)
	(via
		(at 380.613412 -59.35345)
		(size 0.508)
		(drill 0.254)
		(layers "F.Cu" "B.Cu")
		(net "SPI_SWITCH_MISO")
	)
	(via
		(at 374.793256 -50.83302)
		(size 0.6604)
		(drill 0.3302)
		(layers "F.Cu" "B.Cu")
		(net "SPI_SWITCH_MISO")
	)
	(segment
		(start 375.2342 -52.1716)
		(end 375.8057 -52.1716)
		(width 0.10795)
		(layer "B.Cu")
		(net "SPI_SWITCH_MISO")
	)
	(segment
		(start 375.8946 -52.2605)
		(end 377.1265 -52.2605)
		(width 0.10795)
		(layer "B.Cu")
		(net "SPI_SWITCH_MISO")
	)
	(segment
		(start 380.145798 -57.696354)
		(end 380.145798 -57.667144)
		(width 0.10795)
		(layer "B.Cu")
		(net "SPI_SWITCH_MISO")
	)
	(segment
		(start 374.793256 -51.730656)
		(end 375.2342 -52.1716)
		(width 0.10795)
		(layer "B.Cu")
		(net "SPI_SWITCH_MISO")
	)
	(segment
		(start 377.335288 -49.911)
		(end 375.031 -49.911)
		(width 0.10795)
		(layer "B.Cu")
		(net "SPI_SWITCH_MISO")
	)
	(segment
		(start 374.793256 -50.148744)
		(end 374.793256 -50.83302)
		(width 0.10795)
		(layer "B.Cu")
		(net "SPI_SWITCH_MISO")
	)
	(segment
		(start 380.150624 -58.890662)
		(end 380.150624 -57.70118)
		(width 0.10795)
		(layer "B.Cu")
		(net "SPI_SWITCH_MISO")
	)
	(segment
		(start 379.44044 -55.00624)
		(end 378.7394 -54.3052)
		(width 0.10795)
		(layer "B.Cu")
		(net "SPI_SWITCH_MISO")
	)
	(segment
		(start 378.7394 -52.7812)
		(end 378.2187 -52.2605)
		(width 0.10795)
		(layer "B.Cu")
		(net "SPI_SWITCH_MISO")
	)
	(segment
		(start 378.587 -49.276)
		(end 377.970288 -49.276)
		(width 0.10795)
		(layer "B.Cu")
		(net "SPI_SWITCH_MISO")
	)
	(segment
		(start 375.031 -49.911)
		(end 374.793256 -50.148744)
		(width 0.10795)
		(layer "B.Cu")
		(net "SPI_SWITCH_MISO")
	)
	(segment
		(start 380.145798 -57.667144)
		(end 379.44044 -56.961786)
		(width 0.10795)
		(layer "B.Cu")
		(net "SPI_SWITCH_MISO")
	)
	(segment
		(start 378.7394 -54.3052)
		(end 378.7394 -52.7812)
		(width 0.10795)
		(layer "B.Cu")
		(net "SPI_SWITCH_MISO")
	)
	(segment
		(start 378.2187 -52.2605)
		(end 377.1265 -52.2605)
		(width 0.10795)
		(layer "B.Cu")
		(net "SPI_SWITCH_MISO")
	)
	(segment
		(start 374.793256 -50.83302)
		(end 374.793256 -51.730656)
		(width 0.10795)
		(layer "B.Cu")
		(net "SPI_SWITCH_MISO")
	)
	(segment
		(start 379.44044 -56.961786)
		(end 379.44044 -55.00624)
		(width 0.10795)
		(layer "B.Cu")
		(net "SPI_SWITCH_MISO")
	)
	(segment
		(start 377.970288 -49.276)
		(end 377.335288 -49.911)
		(width 0.10795)
		(layer "B.Cu")
		(net "SPI_SWITCH_MISO")
	)
	(segment
		(start 375.8057 -52.1716)
		(end 375.8946 -52.2605)
		(width 0.10795)
		(layer "B.Cu")
		(net "SPI_SWITCH_MISO")
	)
	(segment
		(start 380.613412 -59.35345)
		(end 380.150624 -58.890662)
		(width 0.10795)
		(layer "B.Cu")
		(net "SPI_SWITCH_MISO")
	)
	(segment
		(start 380.150624 -57.70118)
		(end 380.145798 -57.696354)
		(width 0.10795)
		(layer "B.Cu")
		(net "SPI_SWITCH_MISO")
	)
	(via
		(at 385.9022 -62.279784)
		(size 0.508)
		(drill 0.254)
		(layers "F.Cu" "B.Cu")
		(net "SPI_SWITCH_CS0_N")
	)
	(via
		(at 390.764522 -67.404234)
		(size 0.6604)
		(drill 0.3302)
		(layers "F.Cu" "B.Cu")
		(net "SPI_SWITCH_CS0_N")
	)
	(via
		(at 379.002544 -50.57775)
		(size 0.508)
		(drill 0.254)
		(layers "F.Cu" "B.Cu")
		(net "SPI_SWITCH_CS0_N")
	)
	(segment
		(start 389.2931 -63.862458)
		(end 389.293608 -63.862966)
		(width 0.10795)
		(layer "B.Cu")
		(net "SPI_SWITCH_CS0_N")
	)
	(segment
		(start 389.2931 -64.443102)
		(end 388.87146 -64.443102)
		(width 0.10795)
		(layer "B.Cu")
		(net "SPI_SWITCH_CS0_N")
	)
	(segment
		(start 377.1265 -50.3555)
		(end 378.780294 -50.3555)
		(width 0.10795)
		(layer "B.Cu")
		(net "SPI_SWITCH_CS0_N")
	)
	(segment
		(start 390.707118 -65.031874)
		(end 390.602724 -65.136268)
		(width 0.10795)
		(layer "B.Cu")
		(net "SPI_SWITCH_CS0_N")
	)
	(segment
		(start 390.75233 -66.442844)
		(end 390.75233 -67.392042)
		(width 0.10795)
		(layer "B.Cu")
		(net "SPI_SWITCH_CS0_N")
	)
	(segment
		(start 386.1562 -71.2724)
		(end 386.715 -71.2724)
		(width 0.10795)
		(layer "B.Cu")
		(net "SPI_SWITCH_CS0_N")
	)
	(segment
		(start 390.75233 -67.392042)
		(end 390.764522 -67.404234)
		(width 0.10795)
		(layer "B.Cu")
		(net "SPI_SWITCH_CS0_N")
	)
	(segment
		(start 392.573002 -68.005198)
		(end 393.741402 -68.005198)
		(width 0.10795)
		(layer "B.Cu")
		(net "SPI_SWITCH_CS0_N")
	)
	(segment
		(start 389.40105 -63.754508)
		(end 389.2931 -63.862458)
		(width 0.10795)
		(layer "B.Cu")
		(net "SPI_SWITCH_CS0_N")
	)
	(segment
		(start 386.634736 -64.062102)
		(end 386.301742 -63.729108)
		(width 0.10795)
		(layer "B.Cu")
		(net "SPI_SWITCH_CS0_N")
	)
	(segment
		(start 385.0386 -70.1548)
		(end 386.1562 -71.2724)
		(width 0.10795)
		(layer "B.Cu")
		(net "SPI_SWITCH_CS0_N")
	)
	(segment
		(start 390.730232 -63.754508)
		(end 389.40105 -63.754508)
		(width 0.10795)
		(layer "B.Cu")
		(net "SPI_SWITCH_CS0_N")
	)
	(segment
		(start 391.3251 -65.031874)
		(end 390.707118 -65.031874)
		(width 0.10795)
		(layer "B.Cu")
		(net "SPI_SWITCH_CS0_N")
	)
	(segment
		(start 393.741402 -68.005198)
		(end 394.335 -67.4116)
		(width 0.10795)
		(layer "B.Cu")
		(net "SPI_SWITCH_CS0_N")
	)
	(segment
		(start 394.335 -67.4116)
		(end 394.335 -67.056)
		(width 0.10795)
		(layer "B.Cu")
		(net "SPI_SWITCH_CS0_N")
	)
	(segment
		(start 387.0198 -70.3834)
		(end 387.510782 -69.892418)
		(width 0.10795)
		(layer "B.Cu")
		(net "SPI_SWITCH_CS0_N")
	)
	(segment
		(start 390.602724 -66.293238)
		(end 390.75233 -66.442844)
		(width 0.10795)
		(layer "B.Cu")
		(net "SPI_SWITCH_CS0_N")
	)
	(segment
		(start 390.602724 -65.136268)
		(end 390.602724 -66.293238)
		(width 0.10795)
		(layer "B.Cu")
		(net "SPI_SWITCH_CS0_N")
	)
	(segment
		(start 389.284464 -64.756284)
		(end 389.46328 -64.9351)
		(width 0.10795)
		(layer "B.Cu")
		(net "SPI_SWITCH_CS0_N")
	)
	(segment
		(start 386.715 -71.2724)
		(end 387.0198 -70.9676)
		(width 0.10795)
		(layer "B.Cu")
		(net "SPI_SWITCH_CS0_N")
	)
	(segment
		(start 390.610344 -64.9351)
		(end 390.707118 -65.031874)
		(width 0.10795)
		(layer "B.Cu")
		(net "SPI_SWITCH_CS0_N")
	)
	(segment
		(start 387.0198 -70.9676)
		(end 387.0198 -70.3834)
		(width 0.10795)
		(layer "B.Cu")
		(net "SPI_SWITCH_CS0_N")
	)
	(segment
		(start 385.9022 -63.7032)
		(end 385.0386 -64.5668)
		(width 0.10795)
		(layer "B.Cu")
		(net "SPI_SWITCH_CS0_N")
	)
	(segment
		(start 385.0386 -64.5668)
		(end 385.0386 -70.1548)
		(width 0.10795)
		(layer "B.Cu")
		(net "SPI_SWITCH_CS0_N")
	)
	(segment
		(start 391.17016 -63.31458)
		(end 390.730232 -63.754508)
		(width 0.10795)
		(layer "B.Cu")
		(net "SPI_SWITCH_CS0_N")
	)
	(segment
		(start 389.2931 -64.443102)
		(end 389.284464 -64.451738)
		(width 0.10795)
		(layer "B.Cu")
		(net "SPI_SWITCH_CS0_N")
	)
	(segment
		(start 389.293608 -63.862966)
		(end 389.293608 -64.442594)
		(width 0.10795)
		(layer "B.Cu")
		(net "SPI_SWITCH_CS0_N")
	)
	(segment
		(start 387.510782 -69.892418)
		(end 390.685782 -69.892418)
		(width 0.10795)
		(layer "B.Cu")
		(net "SPI_SWITCH_CS0_N")
	)
	(segment
		(start 388.49046 -64.062102)
		(end 386.634736 -64.062102)
		(width 0.10795)
		(layer "B.Cu")
		(net "SPI_SWITCH_CS0_N")
	)
	(segment
		(start 390.685782 -69.892418)
		(end 392.573002 -68.005198)
		(width 0.10795)
		(layer "B.Cu")
		(net "SPI_SWITCH_CS0_N")
	)
	(segment
		(start 388.87146 -64.443102)
		(end 388.49046 -64.062102)
		(width 0.10795)
		(layer "B.Cu")
		(net "SPI_SWITCH_CS0_N")
	)
	(segment
		(start 391.17016 -62.73038)
		(end 391.17016 -63.31458)
		(width 0.10795)
		(layer "B.Cu")
		(net "SPI_SWITCH_CS0_N")
	)
	(segment
		(start 378.780294 -50.3555)
		(end 379.002544 -50.57775)
		(width 0.10795)
		(layer "B.Cu")
		(net "SPI_SWITCH_CS0_N")
	)
	(segment
		(start 389.46328 -64.9351)
		(end 390.610344 -64.9351)
		(width 0.10795)
		(layer "B.Cu")
		(net "SPI_SWITCH_CS0_N")
	)
	(segment
		(start 385.9022 -62.279784)
		(end 385.9022 -63.7032)
		(width 0.10795)
		(layer "B.Cu")
		(net "SPI_SWITCH_CS0_N")
	)
	(segment
		(start 390.4742 -62.422786)
		(end 390.862566 -62.422786)
		(width 0.10795)
		(layer "B.Cu")
		(net "SPI_SWITCH_CS0_N")
	)
	(segment
		(start 386.301742 -62.679326)
		(end 385.9022 -62.279784)
		(width 0.10795)
		(layer "B.Cu")
		(net "SPI_SWITCH_CS0_N")
	)
	(segment
		(start 386.301742 -63.729108)
		(end 386.301742 -62.679326)
		(width 0.10795)
		(layer "B.Cu")
		(net "SPI_SWITCH_CS0_N")
	)
	(segment
		(start 389.284464 -64.451738)
		(end 389.284464 -64.756284)
		(width 0.10795)
		(layer "B.Cu")
		(net "SPI_SWITCH_CS0_N")
	)
	(segment
		(start 389.293608 -64.442594)
		(end 389.2931 -64.443102)
		(width 0.10795)
		(layer "B.Cu")
		(net "SPI_SWITCH_CS0_N")
	)
	(segment
		(start 390.862566 -62.422786)
		(end 391.17016 -62.73038)
		(width 0.10795)
		(layer "B.Cu")
		(net "SPI_SWITCH_CS0_N")
	)
	(segment
		(start 385.7244 -60.770008)
		(end 385.7244 -61.2648)
		(width 0.089408)
		(layer "In11.Cu")
		(net "SPI_SWITCH_CS0_N")
	)
	(segment
		(start 379.002544 -50.57775)
		(end 379.57379 -50.57775)
		(width 0.089408)
		(layer "In11.Cu")
		(net "SPI_SWITCH_CS0_N")
	)
	(segment
		(start 379.57379 -50.57775)
		(end 380.743968 -51.747928)
		(width 0.089408)
		(layer "In11.Cu")
		(net "SPI_SWITCH_CS0_N")
	)
	(segment
		(start 385.9022 -61.4426)
		(end 385.9022 -62.279784)
		(width 0.089408)
		(layer "In11.Cu")
		(net "SPI_SWITCH_CS0_N")
	)
	(segment
		(start 380.743968 -51.747928)
		(end 381.169418 -51.747928)
		(width 0.089408)
		(layer "In11.Cu")
		(net "SPI_SWITCH_CS0_N")
	)
	(segment
		(start 381.169418 -51.747928)
		(end 383.903474 -54.481984)
		(width 0.089408)
		(layer "In11.Cu")
		(net "SPI_SWITCH_CS0_N")
	)
	(segment
		(start 385.7244 -61.2648)
		(end 385.9022 -61.4426)
		(width 0.089408)
		(layer "In11.Cu")
		(net "SPI_SWITCH_CS0_N")
	)
	(segment
		(start 384.62077 -54.481984)
		(end 385.223512 -55.084726)
		(width 0.089408)
		(layer "In11.Cu")
		(net "SPI_SWITCH_CS0_N")
	)
	(segment
		(start 384.799332 -58.928254)
		(end 384.799332 -59.84494)
		(width 0.089408)
		(layer "In11.Cu")
		(net "SPI_SWITCH_CS0_N")
	)
	(segment
		(start 384.799332 -59.84494)
		(end 385.7244 -60.770008)
		(width 0.089408)
		(layer "In11.Cu")
		(net "SPI_SWITCH_CS0_N")
	)
	(segment
		(start 385.223512 -55.084726)
		(end 385.223512 -58.504074)
		(width 0.089408)
		(layer "In11.Cu")
		(net "SPI_SWITCH_CS0_N")
	)
	(segment
		(start 385.223512 -58.504074)
		(end 384.799332 -58.928254)
		(width 0.089408)
		(layer "In11.Cu")
		(net "SPI_SWITCH_CS0_N")
	)
	(segment
		(start 383.903474 -54.481984)
		(end 384.62077 -54.481984)
		(width 0.089408)
		(layer "In11.Cu")
		(net "SPI_SWITCH_CS0_N")
	)
	(segment
		(start 384.105404 -53.9242)
		(end 383.9972 -53.815996)
		(width 0.10795)
		(layer "F.Cu")
		(net "SPI_SWITCH_CLK")
	)
	(segment
		(start 384.62585 -53.9242)
		(end 384.105404 -53.9242)
		(width 0.10795)
		(layer "F.Cu")
		(net "SPI_SWITCH_CLK")
	)
	(segment
		(start 383.9972 -53.255926)
		(end 384.18135 -53.071776)
		(width 0.10795)
		(layer "F.Cu")
		(net "SPI_SWITCH_CLK")
	)
	(segment
		(start 385.2164 -50.8508)
		(end 384.8862 -50.8508)
		(width 0.10795)
		(layer "F.Cu")
		(net "SPI_SWITCH_CLK")
	)
	(segment
		(start 384.8862 -50.8508)
		(end 384.7338 -51.0032)
		(width 0.10795)
		(layer "F.Cu")
		(net "SPI_SWITCH_CLK")
	)
	(segment
		(start 384.7338 -53.81625)
		(end 384.62585 -53.9242)
		(width 0.10795)
		(layer "F.Cu")
		(net "SPI_SWITCH_CLK")
	)
	(segment
		(start 384.7338 -51.0032)
		(end 384.7338 -53.81625)
		(width 0.10795)
		(layer "F.Cu")
		(net "SPI_SWITCH_CLK")
	)
	(segment
		(start 383.9972 -53.815996)
		(end 383.9972 -53.255926)
		(width 0.10795)
		(layer "F.Cu")
		(net "SPI_SWITCH_CLK")
	)
	(via
		(at 384.18135 -53.071776)
		(size 0.508)
		(drill 0.254)
		(layers "F.Cu" "B.Cu")
		(net "SPI_SWITCH_CLK")
	)
	(via
		(at 386.770118 -56.140858)
		(size 0.6604)
		(drill 0.3302)
		(layers "F.Cu" "B.Cu")
		(net "SPI_SWITCH_CLK")
	)
	(segment
		(start 387.457188 -57.81675)
		(end 387.457188 -57.460388)
		(width 0.10795)
		(layer "B.Cu")
		(net "SPI_SWITCH_CLK")
	)
	(segment
		(start 384.005074 -52.8955)
		(end 384.18135 -53.071776)
		(width 0.10795)
		(layer "B.Cu")
		(net "SPI_SWITCH_CLK")
	)
	(segment
		(start 381.254 -54.978046)
		(end 381.254 -53.060092)
		(width 0.10795)
		(layer "B.Cu")
		(net "SPI_SWITCH_CLK")
	)
	(segment
		(start 381.418592 -52.8955)
		(end 382.5875 -52.8955)
		(width 0.10795)
		(layer "B.Cu")
		(net "SPI_SWITCH_CLK")
	)
	(segment
		(start 385.167886 -55.6768)
		(end 384.812286 -56.0324)
		(width 0.10795)
		(layer "B.Cu")
		(net "SPI_SWITCH_CLK")
	)
	(segment
		(start 381.254 -53.060092)
		(end 381.418592 -52.8955)
		(width 0.10795)
		(layer "B.Cu")
		(net "SPI_SWITCH_CLK")
	)
	(segment
		(start 386.30606 -55.6768)
		(end 385.167886 -55.6768)
		(width 0.10795)
		(layer "B.Cu")
		(net "SPI_SWITCH_CLK")
	)
	(segment
		(start 386.770118 -56.773318)
		(end 386.770118 -56.140858)
		(width 0.10795)
		(layer "B.Cu")
		(net "SPI_SWITCH_CLK")
	)
	(segment
		(start 384.812286 -56.0324)
		(end 382.308354 -56.0324)
		(width 0.10795)
		(layer "B.Cu")
		(net "SPI_SWITCH_CLK")
	)
	(segment
		(start 386.770118 -56.140858)
		(end 386.30606 -55.6768)
		(width 0.10795)
		(layer "B.Cu")
		(net "SPI_SWITCH_CLK")
	)
	(segment
		(start 382.5875 -52.8955)
		(end 384.005074 -52.8955)
		(width 0.10795)
		(layer "B.Cu")
		(net "SPI_SWITCH_CLK")
	)
	(segment
		(start 382.308354 -56.0324)
		(end 381.254 -54.978046)
		(width 0.10795)
		(layer "B.Cu")
		(net "SPI_SWITCH_CLK")
	)
	(segment
		(start 387.457188 -57.460388)
		(end 386.770118 -56.773318)
		(width 0.10795)
		(layer "B.Cu")
		(net "SPI_SWITCH_CLK")
	)
	(via
		(at 399.9484 -47.0916)
		(size 0.6604)
		(drill 0.3302)
		(layers "F.Cu" "B.Cu")
		(net "SPI_MISO_R1")
	)
	(segment
		(start 385.144772 -46.34611)
		(end 396.386812 -46.34611)
		(width 0.10795)
		(layer "B.Cu")
		(net "SPI_MISO_R1")
	)
	(segment
		(start 399.81632 -47.22368)
		(end 398.093946 -47.22368)
		(width 0.10795)
		(layer "B.Cu")
		(net "SPI_MISO_R1")
	)
	(segment
		(start 392.84275 -47.42561)
		(end 396.74419 -47.42561)
		(width 0.10795)
		(layer "B.Cu")
		(net "SPI_MISO_R1")
	)
	(segment
		(start 384.146298 -48.16602)
		(end 384.61696 -47.695358)
		(width 0.10795)
		(layer "B.Cu")
		(net "SPI_MISO_R1")
	)
	(segment
		(start 396.386812 -46.88586)
		(end 392.84275 -46.88586)
		(width 0.10795)
		(layer "B.Cu")
		(net "SPI_MISO_R1")
	)
	(segment
		(start 392.7348 -46.99381)
		(end 392.7348 -47.31766)
		(width 0.10795)
		(layer "B.Cu")
		(net "SPI_MISO_R1")
	)
	(segment
		(start 379.7427 -49.276)
		(end 380.1491 -48.8696)
		(width 0.10795)
		(layer "B.Cu")
		(net "SPI_MISO_R1")
	)
	(segment
		(start 382.4224 -48.8696)
		(end 383.12598 -48.16602)
		(width 0.10795)
		(layer "B.Cu")
		(net "SPI_MISO_R1")
	)
	(segment
		(start 384.61696 -47.695358)
		(end 384.61696 -46.873922)
		(width 0.10795)
		(layer "B.Cu")
		(net "SPI_MISO_R1")
	)
	(segment
		(start 380.1491 -48.8696)
		(end 382.4224 -48.8696)
		(width 0.10795)
		(layer "B.Cu")
		(net "SPI_MISO_R1")
	)
	(segment
		(start 384.61696 -46.873922)
		(end 385.144772 -46.34611)
		(width 0.10795)
		(layer "B.Cu")
		(net "SPI_MISO_R1")
	)
	(segment
		(start 392.84275 -46.88586)
		(end 392.7348 -46.99381)
		(width 0.10795)
		(layer "B.Cu")
		(net "SPI_MISO_R1")
	)
	(segment
		(start 396.94612 -47.22368)
		(end 398.093946 -47.22368)
		(width 0.10795)
		(layer "B.Cu")
		(net "SPI_MISO_R1")
	)
	(segment
		(start 383.12598 -48.16602)
		(end 384.146298 -48.16602)
		(width 0.10795)
		(layer "B.Cu")
		(net "SPI_MISO_R1")
	)
	(segment
		(start 396.74419 -47.42561)
		(end 396.94612 -47.22368)
		(width 0.10795)
		(layer "B.Cu")
		(net "SPI_MISO_R1")
	)
	(segment
		(start 399.9484 -47.0916)
		(end 399.81632 -47.22368)
		(width 0.10795)
		(layer "B.Cu")
		(net "SPI_MISO_R1")
	)
	(segment
		(start 396.5448 -46.727872)
		(end 396.386812 -46.88586)
		(width 0.10795)
		(layer "B.Cu")
		(net "SPI_MISO_R1")
	)
	(segment
		(start 392.7348 -47.31766)
		(end 392.84275 -47.42561)
		(width 0.10795)
		(layer "B.Cu")
		(net "SPI_MISO_R1")
	)
	(segment
		(start 379.476 -49.276)
		(end 379.7427 -49.276)
		(width 0.10795)
		(layer "B.Cu")
		(net "SPI_MISO_R1")
	)
	(segment
		(start 396.386812 -46.34611)
		(end 396.5448 -46.504098)
		(width 0.10795)
		(layer "B.Cu")
		(net "SPI_MISO_R1")
	)
	(segment
		(start 396.5448 -46.504098)
		(end 396.5448 -46.727872)
		(width 0.10795)
		(layer "B.Cu")
		(net "SPI_MISO_R1")
	)
	(segment
		(start 400.8628 -54.80558)
		(end 400.51482 -54.80558)
		(width 0.10795)
		(layer "F.Cu")
		(net "SPI_MISO_R0")
	)
	(segment
		(start 400.51482 -54.80558)
		(end 399.20672 -56.11368)
		(width 0.10795)
		(layer "F.Cu")
		(net "SPI_MISO_R0")
	)
	(segment
		(start 399.20672 -56.11368)
		(end 398.093946 -56.11368)
		(width 0.10795)
		(layer "F.Cu")
		(net "SPI_MISO_R0")
	)
	(via
		(at 401.987258 -50.448718)
		(size 0.6604)
		(drill 0.3302)
		(layers "F.Cu" "B.Cu")
		(net "SPI_CS0_SECONDARY_R_N")
	)
	(segment
		(start 396.523972 -65.3415)
		(end 395.224 -65.3415)
		(width 0.10795)
		(layer "B.Cu")
		(net "SPI_CS0_SECONDARY_R_N")
	)
	(segment
		(start 401.34413 -58.61939)
		(end 398.444466 -58.61939)
		(width 0.10795)
		(layer "B.Cu")
		(net "SPI_CS0_SECONDARY_R_N")
	)
	(segment
		(start 401.987258 -50.448718)
		(end 402.726398 -51.187858)
		(width 0.10795)
		(layer "B.Cu")
		(net "SPI_CS0_SECONDARY_R_N")
	)
	(segment
		(start 396.477998 -60.585858)
		(end 396.477998 -62.225428)
		(width 0.10795)
		(layer "B.Cu")
		(net "SPI_CS0_SECONDARY_R_N")
	)
	(segment
		(start 397.662654 -64.202818)
		(end 396.523972 -65.3415)
		(width 0.10795)
		(layer "B.Cu")
		(net "SPI_CS0_SECONDARY_R_N")
	)
	(segment
		(start 400.15668 -48.61814)
		(end 401.987258 -50.448718)
		(width 0.10795)
		(layer "B.Cu")
		(net "SPI_CS0_SECONDARY_R_N")
	)
	(segment
		(start 402.726398 -57.237122)
		(end 401.34413 -58.61939)
		(width 0.10795)
		(layer "B.Cu")
		(net "SPI_CS0_SECONDARY_R_N")
	)
	(segment
		(start 396.477998 -62.225428)
		(end 397.662654 -63.410084)
		(width 0.10795)
		(layer "B.Cu")
		(net "SPI_CS0_SECONDARY_R_N")
	)
	(segment
		(start 398.093946 -48.49368)
		(end 400.15668 -48.49368)
		(width 0.10795)
		(layer "B.Cu")
		(net "SPI_CS0_SECONDARY_R_N")
	)
	(segment
		(start 397.662654 -63.410084)
		(end 397.662654 -64.202818)
		(width 0.10795)
		(layer "B.Cu")
		(net "SPI_CS0_SECONDARY_R_N")
	)
	(segment
		(start 398.444466 -58.61939)
		(end 396.477998 -60.585858)
		(width 0.10795)
		(layer "B.Cu")
		(net "SPI_CS0_SECONDARY_R_N")
	)
	(segment
		(start 402.726398 -51.187858)
		(end 402.726398 -57.237122)
		(width 0.10795)
		(layer "B.Cu")
		(net "SPI_CS0_SECONDARY_R_N")
	)
	(segment
		(start 400.15668 -48.49368)
		(end 400.15668 -48.61814)
		(width 0.10795)
		(layer "B.Cu")
		(net "SPI_CS0_SECONDARY_R_N")
	)
	(via
		(at 396.0749 -64.7827)
		(size 0.6604)
		(drill 0.3302)
		(layers "F.Cu" "B.Cu")
		(net "SPI_CS0_SECONDARY_N")
	)
	(segment
		(start 394.335 -64.9605)
		(end 394.4239 -64.8716)
		(width 0.10795)
		(layer "B.Cu")
		(net "SPI_CS0_SECONDARY_N")
	)
	(segment
		(start 395.986 -64.8716)
		(end 396.0749 -64.7827)
		(width 0.10795)
		(layer "B.Cu")
		(net "SPI_CS0_SECONDARY_N")
	)
	(segment
		(start 394.335 -65.3415)
		(end 394.335 -64.9605)
		(width 0.10795)
		(layer "B.Cu")
		(net "SPI_CS0_SECONDARY_N")
	)
	(segment
		(start 393.739624 -65.68186)
		(end 394.079984 -65.3415)
		(width 0.10795)
		(layer "B.Cu")
		(net "SPI_CS0_SECONDARY_N")
	)
	(segment
		(start 393.1031 -65.68186)
		(end 393.739624 -65.68186)
		(width 0.10795)
		(layer "B.Cu")
		(net "SPI_CS0_SECONDARY_N")
	)
	(segment
		(start 394.079984 -65.3415)
		(end 394.335 -65.3415)
		(width 0.10795)
		(layer "B.Cu")
		(net "SPI_CS0_SECONDARY_N")
	)
	(segment
		(start 394.4239 -64.8716)
		(end 395.986 -64.8716)
		(width 0.10795)
		(layer "B.Cu")
		(net "SPI_CS0_SECONDARY_N")
	)
	(segment
		(start 400.304 -56.132222)
		(end 400.640042 -55.79618)
		(width 0.10795)
		(layer "F.Cu")
		(net "SPI_CS0_PRIMARY_R_N")
	)
	(segment
		(start 401.591272 -52.281328)
		(end 400.8628 -53.0098)
		(width 0.10795)
		(layer "F.Cu")
		(net "SPI_CS0_PRIMARY_R_N")
	)
	(segment
		(start 400.640042 -55.79618)
		(end 402.493734 -55.79618)
		(width 0.10795)
		(layer "F.Cu")
		(net "SPI_CS0_PRIMARY_R_N")
	)
	(segment
		(start 400.35861 -57.334658)
		(end 399.903188 -57.334658)
		(width 0.10795)
		(layer "F.Cu")
		(net "SPI_CS0_PRIMARY_R_N")
	)
	(segment
		(start 399.511012 -58.414158)
		(end 399.3642 -58.267346)
		(width 0.10795)
		(layer "F.Cu")
		(net "SPI_CS0_PRIMARY_R_N")
	)
	(segment
		(start 399.7452 -57.17667)
		(end 399.7452 -56.952896)
		(width 0.10795)
		(layer "F.Cu")
		(net "SPI_CS0_PRIMARY_R_N")
	)
	(segment
		(start 399.903188 -56.794908)
		(end 400.204432 -56.794908)
		(width 0.10795)
		(layer "F.Cu")
		(net "SPI_CS0_PRIMARY_R_N")
	)
	(segment
		(start 399.903188 -57.334658)
		(end 399.7452 -57.17667)
		(width 0.10795)
		(layer "F.Cu")
		(net "SPI_CS0_PRIMARY_R_N")
	)
	(segment
		(start 398.72412 -54.84368)
		(end 398.093946 -54.84368)
		(width 0.10795)
		(layer "F.Cu")
		(net "SPI_CS0_PRIMARY_R_N")
	)
	(segment
		(start 400.304 -56.69534)
		(end 400.304 -56.132222)
		(width 0.10795)
		(layer "F.Cu")
		(net "SPI_CS0_PRIMARY_R_N")
	)
	(segment
		(start 400.45132 -60.76188)
		(end 400.45132 -58.522108)
		(width 0.10795)
		(layer "F.Cu")
		(net "SPI_CS0_PRIMARY_R_N")
	)
	(segment
		(start 399.3642 -58.267346)
		(end 399.3642 -58.006996)
		(width 0.10795)
		(layer "F.Cu")
		(net "SPI_CS0_PRIMARY_R_N")
	)
	(segment
		(start 400.516598 -57.492646)
		(end 400.35861 -57.334658)
		(width 0.10795)
		(layer "F.Cu")
		(net "SPI_CS0_PRIMARY_R_N")
	)
	(segment
		(start 403.352 -54.937914)
		(end 403.352 -53.1368)
		(width 0.10795)
		(layer "F.Cu")
		(net "SPI_CS0_PRIMARY_R_N")
	)
	(segment
		(start 400.03222 -53.53558)
		(end 398.72412 -54.84368)
		(width 0.10795)
		(layer "F.Cu")
		(net "SPI_CS0_PRIMARY_R_N")
	)
	(segment
		(start 400.34337 -58.414158)
		(end 399.511012 -58.414158)
		(width 0.10795)
		(layer "F.Cu")
		(net "SPI_CS0_PRIMARY_R_N")
	)
	(segment
		(start 402.493734 -55.79618)
		(end 403.352 -54.937914)
		(width 0.10795)
		(layer "F.Cu")
		(net "SPI_CS0_PRIMARY_R_N")
	)
	(segment
		(start 402.496528 -52.281328)
		(end 401.591272 -52.281328)
		(width 0.10795)
		(layer "F.Cu")
		(net "SPI_CS0_PRIMARY_R_N")
	)
	(segment
		(start 400.8628 -53.0098)
		(end 400.8628 -53.53558)
		(width 0.10795)
		(layer "F.Cu")
		(net "SPI_CS0_PRIMARY_R_N")
	)
	(segment
		(start 403.352 -53.1368)
		(end 402.496528 -52.281328)
		(width 0.10795)
		(layer "F.Cu")
		(net "SPI_CS0_PRIMARY_R_N")
	)
	(segment
		(start 400.35861 -57.874408)
		(end 400.516598 -57.71642)
		(width 0.10795)
		(layer "F.Cu")
		(net "SPI_CS0_PRIMARY_R_N")
	)
	(segment
		(start 399.7452 -56.952896)
		(end 399.903188 -56.794908)
		(width 0.10795)
		(layer "F.Cu")
		(net "SPI_CS0_PRIMARY_R_N")
	)
	(segment
		(start 399.3642 -58.006996)
		(end 399.496788 -57.874408)
		(width 0.10795)
		(layer "F.Cu")
		(net "SPI_CS0_PRIMARY_R_N")
	)
	(segment
		(start 400.516598 -57.71642)
		(end 400.516598 -57.492646)
		(width 0.10795)
		(layer "F.Cu")
		(net "SPI_CS0_PRIMARY_R_N")
	)
	(segment
		(start 400.204432 -56.794908)
		(end 400.304 -56.69534)
		(width 0.10795)
		(layer "F.Cu")
		(net "SPI_CS0_PRIMARY_R_N")
	)
	(segment
		(start 400.45132 -58.522108)
		(end 400.34337 -58.414158)
		(width 0.10795)
		(layer "F.Cu")
		(net "SPI_CS0_PRIMARY_R_N")
	)
	(segment
		(start 399.496788 -57.874408)
		(end 400.35861 -57.874408)
		(width 0.10795)
		(layer "F.Cu")
		(net "SPI_CS0_PRIMARY_R_N")
	)
	(segment
		(start 400.8628 -53.53558)
		(end 400.03222 -53.53558)
		(width 0.10795)
		(layer "F.Cu")
		(net "SPI_CS0_PRIMARY_R_N")
	)
	(segment
		(start 400.0246 -61.1886)
		(end 400.45132 -60.76188)
		(width 0.10795)
		(layer "F.Cu")
		(net "SPI_CS0_PRIMARY_R_N")
	)
	(via
		(at 400.0246 -61.1886)
		(size 0.508)
		(drill 0.254)
		(layers "F.Cu" "B.Cu")
		(net "SPI_CS0_PRIMARY_R_N")
	)
	(via
		(at 397.83004 -65.03416)
		(size 0.6604)
		(drill 0.3302)
		(layers "F.Cu" "B.Cu")
		(net "SPI_CS0_PRIMARY_R_N")
	)
	(segment
		(start 396.997428 -66.273172)
		(end 395.226032 -66.273172)
		(width 0.10795)
		(layer "B.Cu")
		(net "SPI_CS0_PRIMARY_R_N")
	)
	(segment
		(start 395.224 -66.275204)
		(end 395.226032 -66.273172)
		(width 0.10795)
		(layer "B.Cu")
		(net "SPI_CS0_PRIMARY_R_N")
	)
	(segment
		(start 398.859248 -64.260984)
		(end 398.477232 -64.643)
		(width 0.10795)
		(layer "B.Cu")
		(net "SPI_CS0_PRIMARY_R_N")
	)
	(segment
		(start 398.2212 -64.643)
		(end 397.83004 -65.03416)
		(width 0.10795)
		(layer "B.Cu")
		(net "SPI_CS0_PRIMARY_R_N")
	)
	(segment
		(start 399.4404 -63.42888)
		(end 398.859248 -64.010032)
		(width 0.10795)
		(layer "B.Cu")
		(net "SPI_CS0_PRIMARY_R_N")
	)
	(segment
		(start 397.83004 -65.03416)
		(end 397.595598 -65.268602)
		(width 0.10795)
		(layer "B.Cu")
		(net "SPI_CS0_PRIMARY_R_N")
	)
	(segment
		(start 398.859248 -64.010032)
		(end 398.859248 -64.260984)
		(width 0.10795)
		(layer "B.Cu")
		(net "SPI_CS0_PRIMARY_R_N")
	)
	(segment
		(start 400.0246 -61.1886)
		(end 399.4404 -61.7728)
		(width 0.10795)
		(layer "B.Cu")
		(net "SPI_CS0_PRIMARY_R_N")
	)
	(segment
		(start 397.595598 -65.675002)
		(end 396.997428 -66.273172)
		(width 0.10795)
		(layer "B.Cu")
		(net "SPI_CS0_PRIMARY_R_N")
	)
	(segment
		(start 399.4404 -61.7728)
		(end 399.4404 -63.42888)
		(width 0.10795)
		(layer "B.Cu")
		(net "SPI_CS0_PRIMARY_R_N")
	)
	(segment
		(start 398.477232 -64.643)
		(end 398.2212 -64.643)
		(width 0.10795)
		(layer "B.Cu")
		(net "SPI_CS0_PRIMARY_R_N")
	)
	(segment
		(start 395.224 -67.056)
		(end 395.224 -66.275204)
		(width 0.10795)
		(layer "B.Cu")
		(net "SPI_CS0_PRIMARY_R_N")
	)
	(segment
		(start 397.595598 -65.268602)
		(end 397.595598 -65.675002)
		(width 0.10795)
		(layer "B.Cu")
		(net "SPI_CS0_PRIMARY_R_N")
	)
	(via
		(at 393.444984 -67.4878)
		(size 0.6604)
		(drill 0.3302)
		(layers "F.Cu" "B.Cu")
		(net "SPI_CS0_PRIMARY_N")
	)
	(segment
		(start 393.444984 -67.16522)
		(end 394.337032 -66.273172)
		(width 0.10795)
		(layer "B.Cu")
		(net "SPI_CS0_PRIMARY_N")
	)
	(segment
		(start 392.55954 -66.273172)
		(end 394.337032 -66.273172)
		(width 0.10795)
		(layer "B.Cu")
		(net "SPI_CS0_PRIMARY_N")
	)
	(segment
		(start 393.444984 -67.4878)
		(end 393.444984 -67.16522)
		(width 0.10795)
		(layer "B.Cu")
		(net "SPI_CS0_PRIMARY_N")
	)
	(segment
		(start 392.426698 -63.24727)
		(end 392.426698 -66.14033)
		(width 0.10795)
		(layer "B.Cu")
		(net "SPI_CS0_PRIMARY_N")
	)
	(segment
		(start 392.426698 -66.14033)
		(end 392.55954 -66.273172)
		(width 0.10795)
		(layer "B.Cu")
		(net "SPI_CS0_PRIMARY_N")
	)
	(segment
		(start 392.2522 -63.072772)
		(end 392.426698 -63.24727)
		(width 0.10795)
		(layer "B.Cu")
		(net "SPI_CS0_PRIMARY_N")
	)
	(segment
		(start 400.302984 -45.4025)
		(end 401.066 -45.4025)
		(width 0.10795)
		(layer "F.Cu")
		(net "SPI_BIOS_SOCKET_IO3")
	)
	(segment
		(start 399.215864 -46.48962)
		(end 400.302984 -45.4025)
		(width 0.10795)
		(layer "F.Cu")
		(net "SPI_BIOS_SOCKET_IO3")
	)
	(segment
		(start 395.726666 -47.966376)
		(end 395.77264 -47.920402)
		(width 0.10795)
		(layer "F.Cu")
		(net "SPI_BIOS_SOCKET_IO3")
	)
	(segment
		(start 397.16202 -46.48962)
		(end 399.215864 -46.48962)
		(width 0.10795)
		(layer "F.Cu")
		(net "SPI_BIOS_SOCKET_IO3")
	)
	(segment
		(start 395.77264 -47.920402)
		(end 395.77264 -47.879)
		(width 0.10795)
		(layer "F.Cu")
		(net "SPI_BIOS_SOCKET_IO3")
	)
	(segment
		(start 395.77264 -47.879)
		(end 397.16202 -46.48962)
		(width 0.10795)
		(layer "F.Cu")
		(net "SPI_BIOS_SOCKET_IO3")
	)
	(via
		(at 394.597128 -58.905902)
		(size 0.6604)
		(drill 0.3302)
		(layers "F.Cu" "B.Cu")
		(net "SPI_BIOS_SOCKET_IO3")
	)
	(via
		(at 395.726666 -47.966376)
		(size 0.508)
		(drill 0.254)
		(layers "F.Cu" "B.Cu")
		(net "SPI_BIOS_SOCKET_IO3")
	)
	(segment
		(start 392.47318 -53.594)
		(end 392.696954 -53.594)
		(width 0.10795)
		(layer "B.Cu")
		(net "SPI_BIOS_SOCKET_IO3")
	)
	(segment
		(start 390.941052 -59.042554)
		(end 391.235692 -58.747914)
		(width 0.10795)
		(layer "B.Cu")
		(net "SPI_BIOS_SOCKET_IO3")
	)
	(segment
		(start 397.254476 -58.589926)
		(end 397.608044 -58.236358)
		(width 0.10795)
		(layer "B.Cu")
		(net "SPI_BIOS_SOCKET_IO3")
	)
	(segment
		(start 392.696954 -53.594)
		(end 392.854942 -53.751988)
		(width 0.10795)
		(layer "B.Cu")
		(net "SPI_BIOS_SOCKET_IO3")
	)
	(segment
		(start 391.39368 -53.594)
		(end 391.617454 -53.594)
		(width 0.10795)
		(layer "B.Cu")
		(net "SPI_BIOS_SOCKET_IO3")
	)
	(segment
		(start 399.923 -58.128408)
		(end 399.923 -57.658)
		(width 0.10795)
		(layer "B.Cu")
		(net "SPI_BIOS_SOCKET_IO3")
	)
	(segment
		(start 393.934442 -53.751988)
		(end 393.934442 -58.747914)
		(width 0.10795)
		(layer "B.Cu")
		(net "SPI_BIOS_SOCKET_IO3")
	)
	(segment
		(start 393.01293 -58.905902)
		(end 393.236704 -58.905902)
		(width 0.10795)
		(layer "B.Cu")
		(net "SPI_BIOS_SOCKET_IO3")
	)
	(segment
		(start 391.775442 -58.747914)
		(end 391.93343 -58.905902)
		(width 0.10795)
		(layer "B.Cu")
		(net "SPI_BIOS_SOCKET_IO3")
	)
	(segment
		(start 386.22986 -58.157618)
		(end 387.114796 -59.042554)
		(width 0.10795)
		(layer "B.Cu")
		(net "SPI_BIOS_SOCKET_IO3")
	)
	(segment
		(start 384.613404 -56.95188)
		(end 385.17449 -56.95188)
		(width 0.10795)
		(layer "B.Cu")
		(net "SPI_BIOS_SOCKET_IO3")
	)
	(segment
		(start 397.608044 -58.236358)
		(end 399.81505 -58.236358)
		(width 0.10795)
		(layer "B.Cu")
		(net "SPI_BIOS_SOCKET_IO3")
	)
	(segment
		(start 399.81505 -58.236358)
		(end 399.923 -58.128408)
		(width 0.10795)
		(layer "B.Cu")
		(net "SPI_BIOS_SOCKET_IO3")
	)
	(segment
		(start 385.17449 -56.95188)
		(end 386.22986 -58.00725)
		(width 0.10795)
		(layer "B.Cu")
		(net "SPI_BIOS_SOCKET_IO3")
	)
	(segment
		(start 393.394692 -53.751988)
		(end 393.55268 -53.594)
		(width 0.10795)
		(layer "B.Cu")
		(net "SPI_BIOS_SOCKET_IO3")
	)
	(segment
		(start 394.09243 -58.905902)
		(end 394.597128 -58.905902)
		(width 0.10795)
		(layer "B.Cu")
		(net "SPI_BIOS_SOCKET_IO3")
	)
	(segment
		(start 391.235692 -53.751988)
		(end 391.39368 -53.594)
		(width 0.10795)
		(layer "B.Cu")
		(net "SPI_BIOS_SOCKET_IO3")
	)
	(segment
		(start 392.157204 -58.905902)
		(end 392.315192 -58.747914)
		(width 0.10795)
		(layer "B.Cu")
		(net "SPI_BIOS_SOCKET_IO3")
	)
	(segment
		(start 393.55268 -53.594)
		(end 393.776454 -53.594)
		(width 0.10795)
		(layer "B.Cu")
		(net "SPI_BIOS_SOCKET_IO3")
	)
	(segment
		(start 395.726666 -47.966376)
		(end 395.100556 -48.592486)
		(width 0.10795)
		(layer "B.Cu")
		(net "SPI_BIOS_SOCKET_IO3")
	)
	(segment
		(start 393.934442 -58.747914)
		(end 394.09243 -58.905902)
		(width 0.10795)
		(layer "B.Cu")
		(net "SPI_BIOS_SOCKET_IO3")
	)
	(segment
		(start 391.93343 -58.905902)
		(end 392.157204 -58.905902)
		(width 0.10795)
		(layer "B.Cu")
		(net "SPI_BIOS_SOCKET_IO3")
	)
	(segment
		(start 396.787878 -57.658)
		(end 399.923 -57.658)
		(width 0.10795)
		(layer "B.Cu")
		(net "SPI_BIOS_SOCKET_IO3")
	)
	(segment
		(start 392.315192 -53.751988)
		(end 392.47318 -53.594)
		(width 0.10795)
		(layer "B.Cu")
		(net "SPI_BIOS_SOCKET_IO3")
	)
	(segment
		(start 391.775442 -53.751988)
		(end 391.775442 -58.747914)
		(width 0.10795)
		(layer "B.Cu")
		(net "SPI_BIOS_SOCKET_IO3")
	)
	(segment
		(start 394.597128 -58.905902)
		(end 394.913104 -58.589926)
		(width 0.10795)
		(layer "B.Cu")
		(net "SPI_BIOS_SOCKET_IO3")
	)
	(segment
		(start 391.235692 -58.747914)
		(end 391.235692 -53.751988)
		(width 0.10795)
		(layer "B.Cu")
		(net "SPI_BIOS_SOCKET_IO3")
	)
	(segment
		(start 387.114796 -59.042554)
		(end 390.941052 -59.042554)
		(width 0.10795)
		(layer "B.Cu")
		(net "SPI_BIOS_SOCKET_IO3")
	)
	(segment
		(start 394.913104 -58.589926)
		(end 397.254476 -58.589926)
		(width 0.10795)
		(layer "B.Cu")
		(net "SPI_BIOS_SOCKET_IO3")
	)
	(segment
		(start 383.843784 -57.7215)
		(end 384.613404 -56.95188)
		(width 0.10795)
		(layer "B.Cu")
		(net "SPI_BIOS_SOCKET_IO3")
	)
	(segment
		(start 393.394692 -58.747914)
		(end 393.394692 -53.751988)
		(width 0.10795)
		(layer "B.Cu")
		(net "SPI_BIOS_SOCKET_IO3")
	)
	(segment
		(start 392.854942 -58.747914)
		(end 393.01293 -58.905902)
		(width 0.10795)
		(layer "B.Cu")
		(net "SPI_BIOS_SOCKET_IO3")
	)
	(segment
		(start 395.100556 -48.592486)
		(end 395.100556 -55.970678)
		(width 0.10795)
		(layer "B.Cu")
		(net "SPI_BIOS_SOCKET_IO3")
	)
	(segment
		(start 392.854942 -53.751988)
		(end 392.854942 -58.747914)
		(width 0.10795)
		(layer "B.Cu")
		(net "SPI_BIOS_SOCKET_IO3")
	)
	(segment
		(start 393.776454 -53.594)
		(end 393.934442 -53.751988)
		(width 0.10795)
		(layer "B.Cu")
		(net "SPI_BIOS_SOCKET_IO3")
	)
	(segment
		(start 395.100556 -55.970678)
		(end 396.787878 -57.658)
		(width 0.10795)
		(layer "B.Cu")
		(net "SPI_BIOS_SOCKET_IO3")
	)
	(segment
		(start 392.315192 -58.747914)
		(end 392.315192 -53.751988)
		(width 0.10795)
		(layer "B.Cu")
		(net "SPI_BIOS_SOCKET_IO3")
	)
	(segment
		(start 391.617454 -53.594)
		(end 391.775442 -53.751988)
		(width 0.10795)
		(layer "B.Cu")
		(net "SPI_BIOS_SOCKET_IO3")
	)
	(segment
		(start 382.7653 -57.7215)
		(end 383.843784 -57.7215)
		(width 0.10795)
		(layer "B.Cu")
		(net "SPI_BIOS_SOCKET_IO3")
	)
	(segment
		(start 393.236704 -58.905902)
		(end 393.394692 -58.747914)
		(width 0.10795)
		(layer "B.Cu")
		(net "SPI_BIOS_SOCKET_IO3")
	)
	(segment
		(start 386.22986 -58.00725)
		(end 386.22986 -58.157618)
		(width 0.10795)
		(layer "B.Cu")
		(net "SPI_BIOS_SOCKET_IO3")
	)
	(segment
		(start 381.170688 -55.6895)
		(end 381.087884 -55.772304)
		(width 0.10795)
		(layer "F.Cu")
		(net "SPI_BIOS_SOCKET_IO2")
	)
	(segment
		(start 381.7239 -55.6895)
		(end 381.170688 -55.6895)
		(width 0.10795)
		(layer "F.Cu")
		(net "SPI_BIOS_SOCKET_IO2")
	)
	(segment
		(start 382.002284 -56.32958)
		(end 382.002284 -55.967884)
		(width 0.10795)
		(layer "F.Cu")
		(net "SPI_BIOS_SOCKET_IO2")
	)
	(segment
		(start 382.002284 -55.967884)
		(end 381.7239 -55.6895)
		(width 0.10795)
		(layer "F.Cu")
		(net "SPI_BIOS_SOCKET_IO2")
	)
	(segment
		(start 381.087884 -55.772304)
		(end 380.497588 -56.3626)
		(width 0.10795)
		(layer "F.Cu")
		(net "SPI_BIOS_SOCKET_IO2")
	)
	(via
		(at 381.087884 -55.772304)
		(size 0.762)
		(drill 0.381)
		(layers "F.Cu" "B.Cu")
		(net "SPI_BIOS_SOCKET_IO2")
	)
	(via
		(at 380.497588 -56.3626)
		(size 0.508)
		(drill 0.254)
		(layers "F.Cu" "B.Cu")
		(net "SPI_BIOS_SOCKET_IO2")
	)
	(segment
		(start 381.625602 -59.6265)
		(end 381.3556 -59.356498)
		(width 0.10795)
		(layer "B.Cu")
		(net "SPI_BIOS_SOCKET_IO2")
	)
	(segment
		(start 380.5047 -53.429154)
		(end 380.346712 -53.271166)
		(width 0.10795)
		(layer "B.Cu")
		(net "SPI_BIOS_SOCKET_IO2")
	)
	(segment
		(start 380.346712 -53.271166)
		(end 379.303788 -53.271166)
		(width 0.10795)
		(layer "B.Cu")
		(net "SPI_BIOS_SOCKET_IO2")
	)
	(segment
		(start 380.004828 -57.01411)
		(end 380.004828 -56.658256)
		(width 0.10795)
		(layer "B.Cu")
		(net "SPI_BIOS_SOCKET_IO2")
	)
	(segment
		(start 379.1458 -52.889404)
		(end 379.303788 -52.731416)
		(width 0.10795)
		(layer "B.Cu")
		(net "SPI_BIOS_SOCKET_IO2")
	)
	(segment
		(start 379.303788 -53.271166)
		(end 379.1458 -53.113178)
		(width 0.10795)
		(layer "B.Cu")
		(net "SPI_BIOS_SOCKET_IO2")
	)
	(segment
		(start 385.6736 -52.07)
		(end 386.600446 -52.996846)
		(width 0.10795)
		(layer "B.Cu")
		(net "SPI_BIOS_SOCKET_IO2")
	)
	(segment
		(start 379.303788 -53.810916)
		(end 380.346712 -53.810916)
		(width 0.10795)
		(layer "B.Cu")
		(net "SPI_BIOS_SOCKET_IO2")
	)
	(segment
		(start 380.497588 -56.3626)
		(end 380.329186 -56.194198)
		(width 0.10795)
		(layer "B.Cu")
		(net "SPI_BIOS_SOCKET_IO2")
	)
	(segment
		(start 380.329186 -56.194198)
		(end 379.994414 -56.194198)
		(width 0.10795)
		(layer "B.Cu")
		(net "SPI_BIOS_SOCKET_IO2")
	)
	(segment
		(start 386.753354 -52.996846)
		(end 387.197346 -52.552854)
		(width 0.10795)
		(layer "B.Cu")
		(net "SPI_BIOS_SOCKET_IO2")
	)
	(segment
		(start 385.572 -50.165)
		(end 385.572 -49.403)
		(width 0.10795)
		(layer "B.Cu")
		(net "SPI_BIOS_SOCKET_IO2")
	)
	(segment
		(start 380.5047 -52.573428)
		(end 380.5047 -50.469292)
		(width 0.10795)
		(layer "B.Cu")
		(net "SPI_BIOS_SOCKET_IO2")
	)
	(segment
		(start 380.004828 -56.658256)
		(end 380.300484 -56.3626)
		(width 0.10795)
		(layer "B.Cu")
		(net "SPI_BIOS_SOCKET_IO2")
	)
	(segment
		(start 386.5626 -51.1556)
		(end 385.572 -50.165)
		(width 0.10795)
		(layer "B.Cu")
		(net "SPI_BIOS_SOCKET_IO2")
	)
	(segment
		(start 387.197346 -52.552854)
		(end 387.197346 -52.399946)
		(width 0.10795)
		(layer "B.Cu")
		(net "SPI_BIOS_SOCKET_IO2")
	)
	(segment
		(start 381.3556 -59.356498)
		(end 381.3556 -58.364882)
		(width 0.10795)
		(layer "B.Cu")
		(net "SPI_BIOS_SOCKET_IO2")
	)
	(segment
		(start 380.5047 -53.652928)
		(end 380.5047 -53.429154)
		(width 0.10795)
		(layer "B.Cu")
		(net "SPI_BIOS_SOCKET_IO2")
	)
	(segment
		(start 379.303788 -54.350666)
		(end 379.1458 -54.192678)
		(width 0.10795)
		(layer "B.Cu")
		(net "SPI_BIOS_SOCKET_IO2")
	)
	(segment
		(start 384.311398 -49.996598)
		(end 385.6736 -51.3588)
		(width 0.10795)
		(layer "B.Cu")
		(net "SPI_BIOS_SOCKET_IO2")
	)
	(segment
		(start 379.1458 -54.192678)
		(end 379.1458 -53.968904)
		(width 0.10795)
		(layer "B.Cu")
		(net "SPI_BIOS_SOCKET_IO2")
	)
	(segment
		(start 379.833124 -56.032908)
		(end 379.833124 -54.458616)
		(width 0.10795)
		(layer "B.Cu")
		(net "SPI_BIOS_SOCKET_IO2")
	)
	(segment
		(start 380.346712 -52.731416)
		(end 380.5047 -52.573428)
		(width 0.10795)
		(layer "B.Cu")
		(net "SPI_BIOS_SOCKET_IO2")
	)
	(segment
		(start 380.300484 -56.3626)
		(end 380.497588 -56.3626)
		(width 0.10795)
		(layer "B.Cu")
		(net "SPI_BIOS_SOCKET_IO2")
	)
	(segment
		(start 382.7653 -59.6265)
		(end 381.625602 -59.6265)
		(width 0.10795)
		(layer "B.Cu")
		(net "SPI_BIOS_SOCKET_IO2")
	)
	(segment
		(start 379.725174 -54.350666)
		(end 379.303788 -54.350666)
		(width 0.10795)
		(layer "B.Cu")
		(net "SPI_BIOS_SOCKET_IO2")
	)
	(segment
		(start 380.346712 -53.810916)
		(end 380.5047 -53.652928)
		(width 0.10795)
		(layer "B.Cu")
		(net "SPI_BIOS_SOCKET_IO2")
	)
	(segment
		(start 386.600446 -52.996846)
		(end 386.753354 -52.996846)
		(width 0.10795)
		(layer "B.Cu")
		(net "SPI_BIOS_SOCKET_IO2")
	)
	(segment
		(start 379.1458 -53.968904)
		(end 379.303788 -53.810916)
		(width 0.10795)
		(layer "B.Cu")
		(net "SPI_BIOS_SOCKET_IO2")
	)
	(segment
		(start 380.977394 -49.996598)
		(end 384.311398 -49.996598)
		(width 0.10795)
		(layer "B.Cu")
		(net "SPI_BIOS_SOCKET_IO2")
	)
	(segment
		(start 379.833124 -54.458616)
		(end 379.725174 -54.350666)
		(width 0.10795)
		(layer "B.Cu")
		(net "SPI_BIOS_SOCKET_IO2")
	)
	(segment
		(start 379.303788 -52.731416)
		(end 380.346712 -52.731416)
		(width 0.10795)
		(layer "B.Cu")
		(net "SPI_BIOS_SOCKET_IO2")
	)
	(segment
		(start 385.6736 -51.3588)
		(end 385.6736 -52.07)
		(width 0.10795)
		(layer "B.Cu")
		(net "SPI_BIOS_SOCKET_IO2")
	)
	(segment
		(start 387.197346 -52.399946)
		(end 386.5626 -51.7652)
		(width 0.10795)
		(layer "B.Cu")
		(net "SPI_BIOS_SOCKET_IO2")
	)
	(segment
		(start 379.994414 -56.194198)
		(end 379.833124 -56.032908)
		(width 0.10795)
		(layer "B.Cu")
		(net "SPI_BIOS_SOCKET_IO2")
	)
	(segment
		(start 379.1458 -53.113178)
		(end 379.1458 -52.889404)
		(width 0.10795)
		(layer "B.Cu")
		(net "SPI_BIOS_SOCKET_IO2")
	)
	(segment
		(start 380.5047 -50.469292)
		(end 380.977394 -49.996598)
		(width 0.10795)
		(layer "B.Cu")
		(net "SPI_BIOS_SOCKET_IO2")
	)
	(segment
		(start 386.5626 -51.7652)
		(end 386.5626 -51.1556)
		(width 0.10795)
		(layer "B.Cu")
		(net "SPI_BIOS_SOCKET_IO2")
	)
	(segment
		(start 381.3556 -58.364882)
		(end 380.004828 -57.01411)
		(width 0.10795)
		(layer "B.Cu")
		(net "SPI_BIOS_SOCKET_IO2")
	)
	(segment
		(start 399.52168 -49.76368)
		(end 398.093946 -49.76368)
		(width 0.10795)
		(layer "F.Cu")
		(net "PU_SPI0_RST")
	)
	(segment
		(start 399.7325 -49.9745)
		(end 399.52168 -49.76368)
		(width 0.10795)
		(layer "F.Cu")
		(net "PU_SPI0_RST")
	)
	(segment
		(start 401.066 -49.9745)
		(end 399.7325 -49.9745)
		(width 0.10795)
		(layer "F.Cu")
		(net "PU_SPI0_RST")
	)
	(via
		(at 387.494018 -61.274198)
		(size 0.508)
		(drill 0.254)
		(layers "F.Cu" "B.Cu")
		(net "FM_DUAL_BIOS_SEL_N")
	)
	(segment
		(start 387.217666 -61.274198)
		(end 387.494018 -61.274198)
		(width 0.10795)
		(layer "B.Cu")
		(net "FM_DUAL_BIOS_SEL_N")
	)
	(segment
		(start 389.375142 -61.7728)
		(end 390.4742 -61.7728)
		(width 0.10795)
		(layer "B.Cu")
		(net "FM_DUAL_BIOS_SEL_N")
	)
	(segment
		(start 388.3025 -61.341)
		(end 388.3025 -61.42101)
		(width 0.10795)
		(layer "B.Cu")
		(net "FM_DUAL_BIOS_SEL_N")
	)
	(segment
		(start 386.786374 -61.192918)
		(end 387.136386 -61.192918)
		(width 0.10795)
		(layer "B.Cu")
		(net "FM_DUAL_BIOS_SEL_N")
	)
	(segment
		(start 388.657846 -61.776356)
		(end 389.371586 -61.776356)
		(width 0.10795)
		(layer "B.Cu")
		(net "FM_DUAL_BIOS_SEL_N")
	)
	(segment
		(start 388.3025 -61.42101)
		(end 388.657846 -61.776356)
		(width 0.10795)
		(layer "B.Cu")
		(net "FM_DUAL_BIOS_SEL_N")
	)
	(segment
		(start 389.371586 -61.776356)
		(end 389.375142 -61.7728)
		(width 0.10795)
		(layer "B.Cu")
		(net "FM_DUAL_BIOS_SEL_N")
	)
	(segment
		(start 386.538978 -61.440314)
		(end 386.786374 -61.192918)
		(width 0.10795)
		(layer "B.Cu")
		(net "FM_DUAL_BIOS_SEL_N")
	)
	(segment
		(start 386.8801 -63.1698)
		(end 386.8801 -62.632844)
		(width 0.10795)
		(layer "B.Cu")
		(net "FM_DUAL_BIOS_SEL_N")
	)
	(segment
		(start 386.8801 -62.632844)
		(end 386.538978 -62.291722)
		(width 0.10795)
		(layer "B.Cu")
		(net "FM_DUAL_BIOS_SEL_N")
	)
	(segment
		(start 386.538978 -62.291722)
		(end 386.538978 -61.440314)
		(width 0.10795)
		(layer "B.Cu")
		(net "FM_DUAL_BIOS_SEL_N")
	)
	(segment
		(start 387.136386 -61.192918)
		(end 387.217666 -61.274198)
		(width 0.10795)
		(layer "B.Cu")
		(net "FM_DUAL_BIOS_SEL_N")
	)
	(segment
		(start 387.79196 -61.274198)
		(end 387.494018 -61.274198)
		(width 0.10795)
		(layer "B.Cu")
		(net "FM_DUAL_BIOS_SEL_N")
	)
	(segment
		(start 387.858762 -61.341)
		(end 387.79196 -61.274198)
		(width 0.10795)
		(layer "B.Cu")
		(net "FM_DUAL_BIOS_SEL_N")
	)
	(segment
		(start 388.3025 -61.341)
		(end 387.858762 -61.341)
		(width 0.10795)
		(layer "B.Cu")
		(net "FM_DUAL_BIOS_SEL_N")
	)
	(segment
		(start 173.420786 -67.945)
		(end 173.9265 -67.945)
		(width 0.2032)
		(layer "F.Cu")
		(net "VR_PVCCIO_CPU1_VINSEN")
	)
	(segment
		(start 172.956728 -67.480942)
		(end 173.420786 -67.945)
		(width 0.2032)
		(layer "F.Cu")
		(net "VR_PVCCIO_CPU1_VINSEN")
	)
	(segment
		(start 173.9265 -67.056)
		(end 173.9265 -67.945)
		(width 0.2032)
		(layer "F.Cu")
		(net "VR_PVCCIO_CPU1_VINSEN")
	)
	(segment
		(start 171.6405 -67.401948)
		(end 172.877734 -67.401948)
		(width 0.2032)
		(layer "F.Cu")
		(net "VR_PVCCIO_CPU1_VINSEN")
	)
	(segment
		(start 173.7487 -66.8782)
		(end 173.9265 -67.056)
		(width 0.2032)
		(layer "F.Cu")
		(net "VR_PVCCIO_CPU1_VINSEN")
	)
	(segment
		(start 173.7487 -66.191638)
		(end 173.7487 -66.8782)
		(width 0.2032)
		(layer "F.Cu")
		(net "VR_PVCCIO_CPU1_VINSEN")
	)
	(segment
		(start 172.877734 -67.401948)
		(end 172.956728 -67.480942)
		(width 0.2032)
		(layer "F.Cu")
		(net "VR_PVCCIO_CPU1_VINSEN")
	)
	(via
		(at 172.956728 -67.480942)
		(size 0.762)
		(drill 0.381)
		(layers "F.Cu" "B.Cu")
		(net "VR_PVCCIO_CPU1_VINSEN")
	)
	(segment
		(start 170.119548 -70.6374)
		(end 170.815 -70.6374)
		(width 0.508)
		(layer "F.Cu")
		(net "VR_PVCCIO_CPU1_VD12")
	)
	(segment
		(start 169.902886 -70.854062)
		(end 170.119548 -70.6374)
		(width 0.508)
		(layer "F.Cu")
		(net "VR_PVCCIO_CPU1_VD12")
	)
	(segment
		(start 171.704 -69.6214)
		(end 171.6405 -69.5579)
		(width 0.508)
		(layer "F.Cu")
		(net "VR_PVCCIO_CPU1_VD12")
	)
	(segment
		(start 171.6405 -68.924678)
		(end 171.6405 -68.602098)
		(width 0.2032)
		(layer "F.Cu")
		(net "VR_PVCCIO_CPU1_VD12")
	)
	(segment
		(start 171.6405 -69.5579)
		(end 171.6405 -68.924678)
		(width 0.508)
		(layer "F.Cu")
		(net "VR_PVCCIO_CPU1_VD12")
	)
	(segment
		(start 171.704 -70.6374)
		(end 171.704 -69.6214)
		(width 0.508)
		(layer "F.Cu")
		(net "VR_PVCCIO_CPU1_VD12")
	)
	(segment
		(start 169.579036 -70.854062)
		(end 169.902886 -70.854062)
		(width 0.508)
		(layer "F.Cu")
		(net "VR_PVCCIO_CPU1_VD12")
	)
	(segment
		(start 170.815 -70.6374)
		(end 171.704 -70.6374)
		(width 0.508)
		(layer "F.Cu")
		(net "VR_PVCCIO_CPU1_VD12")
	)
	(via
		(at 169.579036 -70.854062)
		(size 0.762)
		(drill 0.381)
		(layers "F.Cu" "B.Cu")
		(net "VR_PVCCIO_CPU1_VD12")
	)
	(segment
		(start 181.543706 -54.097682)
		(end 181.6354 -54.189376)
		(width 0.254)
		(layer "F.Cu")
		(net "VR_PVCCIO_CPU1_PWM1")
	)
	(segment
		(start 169.389298 -69.795898)
		(end 169.5958 -70.0024)
		(width 0.2032)
		(layer "F.Cu")
		(net "VR_PVCCIO_CPU1_PWM1")
	)
	(segment
		(start 180.329586 -54.097682)
		(end 181.543706 -54.097682)
		(width 0.254)
		(layer "F.Cu")
		(net "VR_PVCCIO_CPU1_PWM1")
	)
	(segment
		(start 169.389298 -69.2531)
		(end 169.389298 -69.795898)
		(width 0.2032)
		(layer "F.Cu")
		(net "VR_PVCCIO_CPU1_PWM1")
	)
	(via
		(at 181.6354 -54.189376)
		(size 0.508)
		(drill 0.254)
		(layers "F.Cu" "B.Cu")
		(net "VR_PVCCIO_CPU1_PWM1")
	)
	(via
		(at 169.5958 -70.0024)
		(size 0.508)
		(drill 0.254)
		(layers "F.Cu" "B.Cu")
		(net "VR_PVCCIO_CPU1_PWM1")
	)
	(segment
		(start 169.5958 -70.0024)
		(end 169.5958 -68.18884)
		(width 0.254)
		(layer "In9.Cu")
		(net "VR_PVCCIO_CPU1_PWM1")
	)
	(segment
		(start 174.80788 -62.28588)
		(end 176.9872 -60.10656)
		(width 0.254)
		(layer "In9.Cu")
		(net "VR_PVCCIO_CPU1_PWM1")
	)
	(segment
		(start 181.83479 -57.52719)
		(end 182.5117 -56.85028)
		(width 0.254)
		(layer "In9.Cu")
		(net "VR_PVCCIO_CPU1_PWM1")
	)
	(segment
		(start 178.28768 -60.10656)
		(end 178.88712 -59.50712)
		(width 0.254)
		(layer "In9.Cu")
		(net "VR_PVCCIO_CPU1_PWM1")
	)
	(segment
		(start 174.80788 -65.491868)
		(end 174.80788 -62.28588)
		(width 0.254)
		(layer "In9.Cu")
		(net "VR_PVCCIO_CPU1_PWM1")
	)
	(segment
		(start 176.9872 -60.10656)
		(end 178.28768 -60.10656)
		(width 0.254)
		(layer "In9.Cu")
		(net "VR_PVCCIO_CPU1_PWM1")
	)
	(segment
		(start 182.5117 -56.85028)
		(end 182.5117 -55.065676)
		(width 0.254)
		(layer "In9.Cu")
		(net "VR_PVCCIO_CPU1_PWM1")
	)
	(segment
		(start 178.88712 -59.50712)
		(end 180.88102 -59.50712)
		(width 0.254)
		(layer "In9.Cu")
		(net "VR_PVCCIO_CPU1_PWM1")
	)
	(segment
		(start 169.5958 -68.18884)
		(end 170.004486 -67.780154)
		(width 0.254)
		(layer "In9.Cu")
		(net "VR_PVCCIO_CPU1_PWM1")
	)
	(segment
		(start 170.004486 -67.780154)
		(end 172.519594 -67.780154)
		(width 0.254)
		(layer "In9.Cu")
		(net "VR_PVCCIO_CPU1_PWM1")
	)
	(segment
		(start 180.88102 -59.50712)
		(end 181.83479 -58.55335)
		(width 0.254)
		(layer "In9.Cu")
		(net "VR_PVCCIO_CPU1_PWM1")
	)
	(segment
		(start 172.519594 -67.780154)
		(end 174.80788 -65.491868)
		(width 0.254)
		(layer "In9.Cu")
		(net "VR_PVCCIO_CPU1_PWM1")
	)
	(segment
		(start 182.5117 -55.065676)
		(end 181.6354 -54.189376)
		(width 0.254)
		(layer "In9.Cu")
		(net "VR_PVCCIO_CPU1_PWM1")
	)
	(segment
		(start 181.83479 -58.55335)
		(end 181.83479 -57.52719)
		(width 0.254)
		(layer "In9.Cu")
		(net "VR_PVCCIO_CPU1_PWM1")
	)
	(segment
		(start 178.852576 -57.478676)
		(end 178.9303 -57.5564)
		(width 0.254)
		(layer "F.Cu")
		(net "VR_PVCCIO_CPU1_PH1_VCIN")
	)
	(segment
		(start 178.852576 -57.160922)
		(end 178.852576 -57.478676)
		(width 0.254)
		(layer "F.Cu")
		(net "VR_PVCCIO_CPU1_PH1_VCIN")
	)
	(segment
		(start 178.814476 -56.742838)
		(end 178.814476 -57.122822)
		(width 0.254)
		(layer "F.Cu")
		(net "VR_PVCCIO_CPU1_PH1_VCIN")
	)
	(segment
		(start 178.9303 -57.5564)
		(end 178.9303 -57.8993)
		(width 0.4064)
		(layer "F.Cu")
		(net "VR_PVCCIO_CPU1_PH1_VCIN")
	)
	(segment
		(start 178.814476 -57.122822)
		(end 178.852576 -57.160922)
		(width 0.254)
		(layer "F.Cu")
		(net "VR_PVCCIO_CPU1_PH1_VCIN")
	)
	(segment
		(start 178.9303 -57.8993)
		(end 179.197 -58.166)
		(width 0.4064)
		(layer "F.Cu")
		(net "VR_PVCCIO_CPU1_PH1_VCIN")
	)
	(via
		(at 178.9303 -57.5564)
		(size 0.508)
		(drill 0.254)
		(layers "F.Cu" "B.Cu")
		(net "VR_PVCCIO_CPU1_PH1_VCIN")
	)
	(via
		(at 180.13045 -56.35625)
		(size 0.6604)
		(drill 0.3302)
		(layers "F.Cu" "B.Cu")
		(net "VR_PVCCIO_CPU1_PH1_VCIN")
	)
	(segment
		(start 179.7177 -56.769)
		(end 179.197 -56.769)
		(width 0.1143)
		(layer "B.Cu")
		(net "VR_PVCCIO_CPU1_PH1_VCIN")
	)
	(segment
		(start 179.197 -56.769)
		(end 179.20335 -56.77535)
		(width 0.127)
		(layer "B.Cu")
		(net "VR_PVCCIO_CPU1_PH1_VCIN")
	)
	(segment
		(start 179.20335 -57.28335)
		(end 178.9303 -57.5564)
		(width 0.127)
		(layer "B.Cu")
		(net "VR_PVCCIO_CPU1_PH1_VCIN")
	)
	(segment
		(start 179.20335 -56.77535)
		(end 179.20335 -57.28335)
		(width 0.127)
		(layer "B.Cu")
		(net "VR_PVCCIO_CPU1_PH1_VCIN")
	)
	(segment
		(start 180.13045 -56.35625)
		(end 179.7177 -56.769)
		(width 0.127)
		(layer "B.Cu")
		(net "VR_PVCCIO_CPU1_PH1_VCIN")
	)
	(segment
		(start 180.329586 -53.197506)
		(end 180.850794 -53.197506)
		(width 0.254)
		(layer "F.Cu")
		(net "VR_PVCCIO_CPU1_PH1_PHASE")
	)
	(segment
		(start 181.14645 -52.90185)
		(end 181.4576 -52.5907)
		(width 0.508)
		(layer "F.Cu")
		(net "VR_PVCCIO_CPU1_PH1_PHASE")
	)
	(segment
		(start 180.850794 -53.197506)
		(end 181.14645 -52.90185)
		(width 0.254)
		(layer "F.Cu")
		(net "VR_PVCCIO_CPU1_PH1_PHASE")
	)
	(segment
		(start 182.5498 -52.7939)
		(end 182.3466 -52.5907)
		(width 0.508)
		(layer "F.Cu")
		(net "VR_PVCCIO_CPU1_PH1_BOOT")
	)
	(segment
		(start 183.769 -53.3019)
		(end 183.261 -52.7939)
		(width 0.508)
		(layer "F.Cu")
		(net "VR_PVCCIO_CPU1_PH1_BOOT")
	)
	(segment
		(start 183.769 -53.594)
		(end 183.769 -53.3019)
		(width 0.508)
		(layer "F.Cu")
		(net "VR_PVCCIO_CPU1_PH1_BOOT")
	)
	(segment
		(start 183.261 -52.7939)
		(end 182.5498 -52.7939)
		(width 0.508)
		(layer "F.Cu")
		(net "VR_PVCCIO_CPU1_PH1_BOOT")
	)
	(segment
		(start 165.814248 -65.401952)
		(end 165.4048 -65.8114)
		(width 0.127)
		(layer "F.Cu")
		(net "VR_PVCCIO_CPU1_AVSP")
	)
	(segment
		(start 164.084 -65.8114)
		(end 164.084 -66.0908)
		(width 0.127)
		(layer "F.Cu")
		(net "VR_PVCCIO_CPU1_AVSP")
	)
	(segment
		(start 163.8554 -66.3194)
		(end 163.2712 -66.3194)
		(width 0.127)
		(layer "F.Cu")
		(net "VR_PVCCIO_CPU1_AVSP")
	)
	(segment
		(start 165.4048 -65.8114)
		(end 164.973 -65.8114)
		(width 0.127)
		(layer "F.Cu")
		(net "VR_PVCCIO_CPU1_AVSP")
	)
	(segment
		(start 164.973 -65.8114)
		(end 164.084 -65.8114)
		(width 0.127)
		(layer "F.Cu")
		(net "VR_PVCCIO_CPU1_AVSP")
	)
	(segment
		(start 166.7383 -65.401952)
		(end 165.814248 -65.401952)
		(width 0.127)
		(layer "F.Cu")
		(net "VR_PVCCIO_CPU1_AVSP")
	)
	(segment
		(start 164.084 -66.0908)
		(end 163.8554 -66.3194)
		(width 0.127)
		(layer "F.Cu")
		(net "VR_PVCCIO_CPU1_AVSP")
	)
	(via
		(at 162.306 -66.3194)
		(size 0.6604)
		(drill 0.3302)
		(layers "F.Cu" "B.Cu")
		(net "VR_PVCCIO_CPU1_AVSP")
	)
	(via
		(at 163.2712 -66.3194)
		(size 0.508)
		(drill 0.254)
		(layers "F.Cu" "B.Cu")
		(net "VR_PVCCIO_CPU1_AVSP")
	)
	(segment
		(start 162.306 -66.3194)
		(end 163.2712 -66.3194)
		(width 0.254)
		(layer "B.Cu")
		(net "VR_PVCCIO_CPU1_AVSP")
	)
	(via
		(at 350.2406 -86.614)
		(size 0.6604)
		(drill 0.3302)
		(layers "F.Cu" "B.Cu")
		(net "VR_PVCCIO_CPU0_VINSEN")
	)
	(segment
		(start 351.2312 -85.9536)
		(end 351.2312 -86.2838)
		(width 0.254)
		(layer "B.Cu")
		(net "VR_PVCCIO_CPU0_VINSEN")
	)
	(segment
		(start 351.2312 -85.9536)
		(end 350.7232 -85.9536)
		(width 0.254)
		(layer "B.Cu")
		(net "VR_PVCCIO_CPU0_VINSEN")
	)
	(segment
		(start 350.002348 -86.852252)
		(end 350.2406 -86.614)
		(width 0.254)
		(layer "B.Cu")
		(net "VR_PVCCIO_CPU0_VINSEN")
	)
	(segment
		(start 350.9772 -86.5378)
		(end 350.9772 -86.741)
		(width 0.254)
		(layer "B.Cu")
		(net "VR_PVCCIO_CPU0_VINSEN")
	)
	(segment
		(start 350.7232 -85.9536)
		(end 350.2406 -86.4362)
		(width 0.254)
		(layer "B.Cu")
		(net "VR_PVCCIO_CPU0_VINSEN")
	)
	(segment
		(start 350.9772 -87.503)
		(end 350.9772 -86.741)
		(width 0.254)
		(layer "B.Cu")
		(net "VR_PVCCIO_CPU0_VINSEN")
	)
	(segment
		(start 351.2312 -86.2838)
		(end 350.9772 -86.5378)
		(width 0.254)
		(layer "B.Cu")
		(net "VR_PVCCIO_CPU0_VINSEN")
	)
	(segment
		(start 348.9833 -86.852252)
		(end 349.6056 -86.852252)
		(width 0.1778)
		(layer "B.Cu")
		(net "VR_PVCCIO_CPU0_VINSEN")
	)
	(segment
		(start 349.6056 -86.852252)
		(end 350.002348 -86.852252)
		(width 0.254)
		(layer "B.Cu")
		(net "VR_PVCCIO_CPU0_VINSEN")
	)
	(segment
		(start 350.2406 -86.4362)
		(end 350.2406 -86.614)
		(width 0.254)
		(layer "B.Cu")
		(net "VR_PVCCIO_CPU0_VINSEN")
	)
	(via
		(at 350.003364 -84.526882)
		(size 0.6604)
		(drill 0.3302)
		(layers "F.Cu" "B.Cu")
		(net "VR_PVCCIO_CPU0_VD12")
	)
	(segment
		(start 349.631 -84.899246)
		(end 349.631 -85.385402)
		(width 0.1778)
		(layer "B.Cu")
		(net "VR_PVCCIO_CPU0_VD12")
	)
	(segment
		(start 349.3643 -85.652102)
		(end 348.9833 -85.652102)
		(width 0.1778)
		(layer "B.Cu")
		(net "VR_PVCCIO_CPU0_VD12")
	)
	(segment
		(start 350.003364 -84.526882)
		(end 349.631 -84.899246)
		(width 0.1778)
		(layer "B.Cu")
		(net "VR_PVCCIO_CPU0_VD12")
	)
	(segment
		(start 349.631 -85.385402)
		(end 349.3643 -85.652102)
		(width 0.1778)
		(layer "B.Cu")
		(net "VR_PVCCIO_CPU0_VD12")
	)
	(segment
		(start 349.123 -83.5406)
		(end 348.234 -83.5406)
		(width 0.1778)
		(layer "B.Cu")
		(net "VR_PVCCIO_CPU0_VD12")
	)
	(segment
		(start 350.0374 -84.492846)
		(end 350.003364 -84.526882)
		(width 0.1778)
		(layer "B.Cu")
		(net "VR_PVCCIO_CPU0_VD12")
	)
	(segment
		(start 349.7326 -83.5406)
		(end 350.0374 -83.8454)
		(width 0.1778)
		(layer "B.Cu")
		(net "VR_PVCCIO_CPU0_VD12")
	)
	(segment
		(start 349.123 -83.5406)
		(end 349.7326 -83.5406)
		(width 0.1778)
		(layer "B.Cu")
		(net "VR_PVCCIO_CPU0_VD12")
	)
	(segment
		(start 350.0374 -83.8454)
		(end 350.0374 -84.492846)
		(width 0.1778)
		(layer "B.Cu")
		(net "VR_PVCCIO_CPU0_VD12")
	)
	(segment
		(start 350.719898 -97.294954)
		(end 349.927164 -97.294954)
		(width 0.254)
		(layer "F.Cu")
		(net "VR_PVCCIO_CPU0_PWM1")
	)
	(segment
		(start 350.7486 -97.323656)
		(end 350.719898 -97.294954)
		(width 0.254)
		(layer "F.Cu")
		(net "VR_PVCCIO_CPU0_PWM1")
	)
	(via
		(at 346.52204 -84.231226)
		(size 0.508)
		(drill 0.254)
		(layers "F.Cu" "B.Cu")
		(net "VR_PVCCIO_CPU0_PWM1")
	)
	(via
		(at 350.7486 -97.323656)
		(size 0.508)
		(drill 0.254)
		(layers "F.Cu" "B.Cu")
		(net "VR_PVCCIO_CPU0_PWM1")
	)
	(segment
		(start 346.732098 -84.58962)
		(end 346.732098 -85.0011)
		(width 0.1778)
		(layer "B.Cu")
		(net "VR_PVCCIO_CPU0_PWM1")
	)
	(segment
		(start 346.52204 -84.379562)
		(end 346.732098 -84.58962)
		(width 0.1778)
		(layer "B.Cu")
		(net "VR_PVCCIO_CPU0_PWM1")
	)
	(segment
		(start 346.52204 -84.231226)
		(end 346.52204 -84.379562)
		(width 0.1778)
		(layer "B.Cu")
		(net "VR_PVCCIO_CPU0_PWM1")
	)
	(segment
		(start 351.0661 -92.20962)
		(end 351.85858 -93.0021)
		(width 0.254)
		(layer "In9.Cu")
		(net "VR_PVCCIO_CPU0_PWM1")
	)
	(segment
		(start 350.9899 -85.6615)
		(end 352.8187 -85.6615)
		(width 0.254)
		(layer "In9.Cu")
		(net "VR_PVCCIO_CPU0_PWM1")
	)
	(segment
		(start 351.85858 -96.213676)
		(end 350.7486 -97.323656)
		(width 0.254)
		(layer "In9.Cu")
		(net "VR_PVCCIO_CPU0_PWM1")
	)
	(segment
		(start 346.52204 -85.20684)
		(end 347.93174 -86.61654)
		(width 0.254)
		(layer "In9.Cu")
		(net "VR_PVCCIO_CPU0_PWM1")
	)
	(segment
		(start 351.85858 -93.0021)
		(end 351.85858 -96.213676)
		(width 0.254)
		(layer "In9.Cu")
		(net "VR_PVCCIO_CPU0_PWM1")
	)
	(segment
		(start 347.93174 -86.61654)
		(end 350.03486 -86.61654)
		(width 0.254)
		(layer "In9.Cu")
		(net "VR_PVCCIO_CPU0_PWM1")
	)
	(segment
		(start 355.092 -87.9348)
		(end 355.092 -89.281)
		(width 0.254)
		(layer "In9.Cu")
		(net "VR_PVCCIO_CPU0_PWM1")
	)
	(segment
		(start 350.03486 -86.61654)
		(end 350.9899 -85.6615)
		(width 0.254)
		(layer "In9.Cu")
		(net "VR_PVCCIO_CPU0_PWM1")
	)
	(segment
		(start 352.8187 -85.6615)
		(end 355.092 -87.9348)
		(width 0.254)
		(layer "In9.Cu")
		(net "VR_PVCCIO_CPU0_PWM1")
	)
	(segment
		(start 351.0661 -91.20124)
		(end 351.0661 -92.20962)
		(width 0.254)
		(layer "In9.Cu")
		(net "VR_PVCCIO_CPU0_PWM1")
	)
	(segment
		(start 355.092 -89.281)
		(end 354.3554 -90.0176)
		(width 0.254)
		(layer "In9.Cu")
		(net "VR_PVCCIO_CPU0_PWM1")
	)
	(segment
		(start 354.3554 -90.0176)
		(end 352.24974 -90.0176)
		(width 0.254)
		(layer "In9.Cu")
		(net "VR_PVCCIO_CPU0_PWM1")
	)
	(segment
		(start 346.52204 -84.231226)
		(end 346.52204 -85.20684)
		(width 0.254)
		(layer "In9.Cu")
		(net "VR_PVCCIO_CPU0_PWM1")
	)
	(segment
		(start 352.24974 -90.0176)
		(end 351.0661 -91.20124)
		(width 0.254)
		(layer "In9.Cu")
		(net "VR_PVCCIO_CPU0_PWM1")
	)
	(segment
		(start 348.6658 -101.3714)
		(end 348.6658 -100.929694)
		(width 0.381)
		(layer "F.Cu")
		(net "VR_PVCCIO_CPU0_PH1_VCIN")
	)
	(segment
		(start 348.6658 -100.929694)
		(end 348.489778 -100.753672)
		(width 0.381)
		(layer "F.Cu")
		(net "VR_PVCCIO_CPU0_PH1_VCIN")
	)
	(segment
		(start 348.412054 -99.94011)
		(end 348.412054 -100.675948)
		(width 0.254)
		(layer "F.Cu")
		(net "VR_PVCCIO_CPU0_PH1_VCIN")
	)
	(segment
		(start 348.412054 -100.675948)
		(end 348.489778 -100.753672)
		(width 0.254)
		(layer "F.Cu")
		(net "VR_PVCCIO_CPU0_PH1_VCIN")
	)
	(via
		(at 348.489778 -100.753672)
		(size 0.508)
		(drill 0.254)
		(layers "F.Cu" "B.Cu")
		(net "VR_PVCCIO_CPU0_PH1_VCIN")
	)
	(via
		(at 348.95282 -101.33076)
		(size 0.6604)
		(drill 0.3302)
		(layers "F.Cu" "B.Cu")
		(net "VR_PVCCIO_CPU0_PH1_VCIN")
	)
	(segment
		(start 348.95282 -101.216714)
		(end 348.489778 -100.753672)
		(width 0.254)
		(layer "B.Cu")
		(net "VR_PVCCIO_CPU0_PH1_VCIN")
	)
	(segment
		(start 348.794578 -100.277168)
		(end 348.489778 -100.581968)
		(width 0.4064)
		(layer "B.Cu")
		(net "VR_PVCCIO_CPU0_PH1_VCIN")
	)
	(segment
		(start 348.489778 -100.581968)
		(end 348.489778 -100.753672)
		(width 0.4064)
		(layer "B.Cu")
		(net "VR_PVCCIO_CPU0_PH1_VCIN")
	)
	(segment
		(start 348.95282 -101.33076)
		(end 348.95282 -101.216714)
		(width 0.254)
		(layer "B.Cu")
		(net "VR_PVCCIO_CPU0_PH1_VCIN")
	)
	(segment
		(start 348.794578 -99.966272)
		(end 348.794578 -100.277168)
		(width 0.4064)
		(layer "B.Cu")
		(net "VR_PVCCIO_CPU0_PH1_VCIN")
	)
	(segment
		(start 351.264982 -95.497904)
		(end 350.741488 -96.021398)
		(width 0.508)
		(layer "F.Cu")
		(net "VR_PVCCIO_CPU0_PH1_PHASE")
	)
	(segment
		(start 350.741488 -96.021398)
		(end 350.741488 -96.036892)
		(width 0.508)
		(layer "F.Cu")
		(net "VR_PVCCIO_CPU0_PH1_PHASE")
	)
	(segment
		(start 350.383602 -96.394778)
		(end 349.927164 -96.394778)
		(width 0.254)
		(layer "F.Cu")
		(net "VR_PVCCIO_CPU0_PH1_PHASE")
	)
	(segment
		(start 350.741488 -96.036892)
		(end 350.383602 -96.394778)
		(width 0.254)
		(layer "F.Cu")
		(net "VR_PVCCIO_CPU0_PH1_PHASE")
	)
	(via
		(at 350.741488 -96.036892)
		(size 0.508)
		(drill 0.254)
		(layers "F.Cu" "B.Cu")
		(net "VR_PVCCIO_CPU0_PH1_PHASE")
	)
	(segment
		(start 353.17684 -95.497904)
		(end 353.953572 -94.721172)
		(width 0.508)
		(layer "F.Cu")
		(net "VR_PVCCIO_CPU0_PH1_BOOT")
	)
	(segment
		(start 352.153982 -95.497904)
		(end 353.17684 -95.497904)
		(width 0.508)
		(layer "F.Cu")
		(net "VR_PVCCIO_CPU0_PH1_BOOT")
	)
	(segment
		(start 353.953572 -95.974916)
		(end 353.953572 -94.721172)
		(width 0.508)
		(layer "F.Cu")
		(net "VR_PVCCIO_CPU0_PH1_BOOT")
	)
	(segment
		(start 353.427284 -96.501204)
		(end 353.953572 -95.974916)
		(width 0.508)
		(layer "F.Cu")
		(net "VR_PVCCIO_CPU0_PH1_BOOT")
	)
	(via
		(at 353.953572 -94.721172)
		(size 0.762)
		(drill 0.381)
		(layers "F.Cu" "B.Cu")
		(net "VR_PVCCIO_CPU0_PH1_BOOT")
	)
	(via
		(at 341.440262 -89.977468)
		(size 0.6604)
		(drill 0.3302)
		(layers "F.Cu" "B.Cu")
		(net "VR_PVCCIO_CPU0_AVSP")
	)
	(segment
		(start 342.117172 -89.300558)
		(end 342.642952 -89.300558)
		(width 0.254)
		(layer "B.Cu")
		(net "VR_PVCCIO_CPU0_AVSP")
	)
	(segment
		(start 341.368126 -90.049604)
		(end 341.440262 -89.977468)
		(width 0.254)
		(layer "B.Cu")
		(net "VR_PVCCIO_CPU0_AVSP")
	)
	(segment
		(start 344.0811 -88.852248)
		(end 343.5096 -88.852248)
		(width 0.2032)
		(layer "B.Cu")
		(net "VR_PVCCIO_CPU0_AVSP")
	)
	(segment
		(start 343.5096 -88.852248)
		(end 343.06129 -89.300558)
		(width 0.2032)
		(layer "B.Cu")
		(net "VR_PVCCIO_CPU0_AVSP")
	)
	(segment
		(start 341.440262 -89.977468)
		(end 342.117172 -89.300558)
		(width 0.254)
		(layer "B.Cu")
		(net "VR_PVCCIO_CPU0_AVSP")
	)
	(segment
		(start 343.06129 -89.300558)
		(end 342.642952 -89.300558)
		(width 0.2032)
		(layer "B.Cu")
		(net "VR_PVCCIO_CPU0_AVSP")
	)
	(segment
		(start 340.606126 -90.049604)
		(end 341.368126 -90.049604)
		(width 0.254)
		(layer "B.Cu")
		(net "VR_PVCCIO_CPU0_AVSP")
	)
	(via
		(at 350.5708 -94.0816)
		(size 0.508)
		(drill 0.254)
		(layers "F.Cu" "B.Cu")
		(net "VR_FET_SW_P12V_STBY_PVCCIO_CPU0")
	)
	(via
		(at 351.486724 -94.639638)
		(size 0.6604)
		(drill 0.3302)
		(layers "F.Cu" "B.Cu")
		(net "VR_FET_SW_P12V_STBY_PVCCIO_CPU0")
	)
	(via
		(at 350.9772 -101.3206)
		(size 0.508)
		(drill 0.254)
		(layers "F.Cu" "B.Cu")
		(net "VR_FET_SW_P12V_STBY_PVCCIO_CPU0")
	)
	(via
		(at 350.965008 -101.941122)
		(size 0.508)
		(drill 0.254)
		(layers "F.Cu" "B.Cu")
		(net "VR_FET_SW_P12V_STBY_PVCCIO_CPU0")
	)
	(via
		(at 352.6282 -87.9348)
		(size 0.508)
		(drill 0.254)
		(layers "F.Cu" "B.Cu")
		(net "VR_FET_SW_P12V_STBY_PVCCIO_CPU0")
	)
	(via
		(at 349.0722 -102.121462)
		(size 0.508)
		(drill 0.254)
		(layers "F.Cu" "B.Cu")
		(net "VR_FET_SW_P12V_STBY_PVCCIO_CPU0")
	)
	(via
		(at 349.7072 -102.121462)
		(size 0.508)
		(drill 0.254)
		(layers "F.Cu" "B.Cu")
		(net "VR_FET_SW_P12V_STBY_PVCCIO_CPU0")
	)
	(via
		(at 349.0722 -95.98279)
		(size 0.508)
		(drill 0.254)
		(layers "F.Cu" "B.Cu")
		(net "VR_FET_SW_P12V_STBY_PVCCIO_CPU0")
	)
	(via
		(at 351.600008 -101.941122)
		(size 0.508)
		(drill 0.254)
		(layers "F.Cu" "B.Cu")
		(net "VR_FET_SW_P12V_STBY_PVCCIO_CPU0")
	)
	(via
		(at 349.064072 -95.06839)
		(size 0.508)
		(drill 0.254)
		(layers "F.Cu" "B.Cu")
		(net "VR_FET_SW_P12V_STBY_PVCCIO_CPU0")
	)
	(via
		(at 350.5708 -94.7674)
		(size 0.508)
		(drill 0.254)
		(layers "F.Cu" "B.Cu")
		(net "VR_FET_SW_P12V_STBY_PVCCIO_CPU0")
	)
	(via
		(at 349.0722 -96.89719)
		(size 0.508)
		(drill 0.254)
		(layers "F.Cu" "B.Cu")
		(net "VR_FET_SW_P12V_STBY_PVCCIO_CPU0")
	)
	(via
		(at 352.235008 -101.941122)
		(size 0.508)
		(drill 0.254)
		(layers "F.Cu" "B.Cu")
		(net "VR_FET_SW_P12V_STBY_PVCCIO_CPU0")
	)
	(via
		(at 351.6122 -101.3206)
		(size 0.508)
		(drill 0.254)
		(layers "F.Cu" "B.Cu")
		(net "VR_FET_SW_P12V_STBY_PVCCIO_CPU0")
	)
	(via
		(at 350.030034 -98.0948)
		(size 0.6604)
		(drill 0.3302)
		(layers "F.Cu" "B.Cu")
		(net "VR_FET_SW_P12V_STBY_PVCCIO_CPU0")
	)
	(via
		(at 349.784162 -94.850712)
		(size 0.508)
		(drill 0.254)
		(layers "F.Cu" "B.Cu")
		(net "VR_FET_SW_P12V_STBY_PVCCIO_CPU0")
	)
	(via
		(at 352.2472 -101.3206)
		(size 0.508)
		(drill 0.254)
		(layers "F.Cu" "B.Cu")
		(net "VR_FET_SW_P12V_STBY_PVCCIO_CPU0")
	)
	(via
		(at 352.245168 -96.22917)
		(size 0.6604)
		(drill 0.3302)
		(layers "F.Cu" "B.Cu")
		(net "VR_FET_SW_P12V_STBY_PVCCIO_CPU0")
	)
	(via
		(at 355.58984 -99.434904)
		(size 0.6604)
		(drill 0.3302)
		(layers "F.Cu" "B.Cu")
		(net "VR_FET_SW_P12V_STBY_PVCCIO_CPU0")
	)
	(via
		(at 348.3864 -93.6498)
		(size 0.508)
		(drill 0.254)
		(layers "F.Cu" "B.Cu")
		(net "VR_FET_SW_P12V_STBY_PVCCIO_CPU0")
	)
	(via
		(at 349.083376 -94.343474)
		(size 0.508)
		(drill 0.254)
		(layers "F.Cu" "B.Cu")
		(net "VR_FET_SW_P12V_STBY_PVCCIO_CPU0")
	)
	(via
		(at 349.752666 -94.116144)
		(size 0.508)
		(drill 0.254)
		(layers "F.Cu" "B.Cu")
		(net "VR_FET_SW_P12V_STBY_PVCCIO_CPU0")
	)
	(via
		(at 350.330008 -101.941122)
		(size 0.508)
		(drill 0.254)
		(layers "F.Cu" "B.Cu")
		(net "VR_FET_SW_P12V_STBY_PVCCIO_CPU0")
	)
	(segment
		(start 352.6282 -87.757)
		(end 352.6282 -87.9348)
		(width 0.254)
		(layer "B.Cu")
		(net "VR_FET_SW_P12V_STBY_PVCCIO_CPU0")
	)
	(segment
		(start 351.8662 -87.503)
		(end 352.3742 -87.503)
		(width 0.254)
		(layer "B.Cu")
		(net "VR_FET_SW_P12V_STBY_PVCCIO_CPU0")
	)
	(segment
		(start 352.3742 -87.503)
		(end 352.6282 -87.757)
		(width 0.254)
		(layer "B.Cu")
		(net "VR_FET_SW_P12V_STBY_PVCCIO_CPU0")
	)
	(segment
		(start 352.6282 -87.9348)
		(end 348.3864 -92.1766)
		(width 0.508)
		(layer "In9.Cu")
		(net "VR_FET_SW_P12V_STBY_PVCCIO_CPU0")
	)
	(segment
		(start 348.3864 -92.1766)
		(end 348.3864 -93.6498)
		(width 0.508)
		(layer "In9.Cu")
		(net "VR_FET_SW_P12V_STBY_PVCCIO_CPU0")
	)
	(segment
		(start 173.101 -66.59118)
		(end 173.101 -66.102992)
		(width 0.2032)
		(layer "F.Cu")
		(net "VR_PVCCIO_CPU1_XADDR1")
	)
	(segment
		(start 172.81779 -66.87439)
		(end 173.101 -66.59118)
		(width 0.2032)
		(layer "F.Cu")
		(net "VR_PVCCIO_CPU1_XADDR1")
	)
	(segment
		(start 173.101 -65.7479)
		(end 173.42612 -65.42278)
		(width 0.2032)
		(layer "F.Cu")
		(net "VR_PVCCIO_CPU1_XADDR1")
	)
	(segment
		(start 173.101 -66.102992)
		(end 173.101 -65.7479)
		(width 0.2032)
		(layer "F.Cu")
		(net "VR_PVCCIO_CPU1_XADDR1")
	)
	(segment
		(start 171.6405 -67.001898)
		(end 172.509942 -67.001898)
		(width 0.2032)
		(layer "F.Cu")
		(net "VR_PVCCIO_CPU1_XADDR1")
	)
	(segment
		(start 172.509942 -67.001898)
		(end 172.81779 -66.87439)
		(width 0.2032)
		(layer "F.Cu")
		(net "VR_PVCCIO_CPU1_XADDR1")
	)
	(segment
		(start 173.42612 -65.42278)
		(end 173.74108 -65.42278)
		(width 0.2032)
		(layer "F.Cu")
		(net "VR_PVCCIO_CPU1_XADDR1")
	)
	(via
		(at 173.101 -66.102992)
		(size 0.1016)
		(drill 0.0508)
		(layers "F.Cu" "B.Cu")
		(net "VR_PVCCIO_CPU1_XADDR1")
	)
	(segment
		(start 172.94352 -68.834)
		(end 172.311568 -68.202048)
		(width 0.2032)
		(layer "F.Cu")
		(net "VR_PVCCIO_CPU1_VDD")
	)
	(segment
		(start 172.311568 -68.202048)
		(end 171.6405 -68.202048)
		(width 0.2032)
		(layer "F.Cu")
		(net "VR_PVCCIO_CPU1_VDD")
	)
	(segment
		(start 173.9265 -69.215)
		(end 173.9265 -68.834)
		(width 0.2032)
		(layer "F.Cu")
		(net "VR_PVCCIO_CPU1_VDD")
	)
	(segment
		(start 173.7487 -70.612)
		(end 173.7487 -69.723)
		(width 0.2032)
		(layer "F.Cu")
		(net "VR_PVCCIO_CPU1_VDD")
	)
	(segment
		(start 172.94352 -68.834)
		(end 173.9265 -68.834)
		(width 0.2032)
		(layer "F.Cu")
		(net "VR_PVCCIO_CPU1_VDD")
	)
	(segment
		(start 173.7487 -69.723)
		(end 173.7487 -69.3928)
		(width 0.2032)
		(layer "F.Cu")
		(net "VR_PVCCIO_CPU1_VDD")
	)
	(segment
		(start 173.7487 -69.3928)
		(end 173.9265 -69.215)
		(width 0.2032)
		(layer "F.Cu")
		(net "VR_PVCCIO_CPU1_VDD")
	)
	(via
		(at 172.94352 -68.834)
		(size 0.762)
		(drill 0.381)
		(layers "F.Cu" "B.Cu")
		(net "VR_PVCCIO_CPU1_VDD")
	)
	(via
		(at 350.1517 -87.5157)
		(size 0.508)
		(drill 0.254)
		(layers "F.Cu" "B.Cu")
		(net "VR_PVCCIO_CPU0_XADDR1")
	)
	(segment
		(start 350.6851 -88.269572)
		(end 350.5708 -88.155272)
		(width 0.1143)
		(layer "B.Cu")
		(net "VR_PVCCIO_CPU0_XADDR1")
	)
	(segment
		(start 350.1517 -87.5157)
		(end 349.888302 -87.252302)
		(width 0.1143)
		(layer "B.Cu")
		(net "VR_PVCCIO_CPU0_XADDR1")
	)
	(segment
		(start 350.5708 -87.9348)
		(end 350.1517 -87.5157)
		(width 0.1143)
		(layer "B.Cu")
		(net "VR_PVCCIO_CPU0_XADDR1")
	)
	(segment
		(start 349.888302 -87.252302)
		(end 348.9833 -87.252302)
		(width 0.1143)
		(layer "B.Cu")
		(net "VR_PVCCIO_CPU0_XADDR1")
	)
	(segment
		(start 350.5708 -88.155272)
		(end 350.5708 -87.9348)
		(width 0.1143)
		(layer "B.Cu")
		(net "VR_PVCCIO_CPU0_XADDR1")
	)
	(segment
		(start 350.9772 -88.269572)
		(end 350.6851 -88.269572)
		(width 0.1143)
		(layer "B.Cu")
		(net "VR_PVCCIO_CPU0_XADDR1")
	)
	(via
		(at 350.2406 -85.4964)
		(size 0.6604)
		(drill 0.3302)
		(layers "F.Cu" "B.Cu")
		(net "VR_PVCCIO_CPU0_VDD")
	)
	(segment
		(start 165.7096 -67.779646)
		(end 165.7096 -68.039996)
		(width 0.10795)
		(layer "F.Cu")
		(net "SVID_VDIO_PVCCIO_CPU1")
	)
	(segment
		(start 166.163498 -66.602102)
		(end 165.7096 -67.056)
		(width 0.10795)
		(layer "F.Cu")
		(net "SVID_VDIO_PVCCIO_CPU1")
	)
	(segment
		(start 165.601396 -68.1482)
		(end 165.1 -68.1482)
		(width 0.10795)
		(layer "F.Cu")
		(net "SVID_VDIO_PVCCIO_CPU1")
	)
	(segment
		(start 165.7096 -68.039996)
		(end 165.601396 -68.1482)
		(width 0.10795)
		(layer "F.Cu")
		(net "SVID_VDIO_PVCCIO_CPU1")
	)
	(segment
		(start 166.7383 -66.602102)
		(end 166.163498 -66.602102)
		(width 0.10795)
		(layer "F.Cu")
		(net "SVID_VDIO_PVCCIO_CPU1")
	)
	(segment
		(start 165.7096 -67.056)
		(end 165.7096 -67.779646)
		(width 0.10795)
		(layer "F.Cu")
		(net "SVID_VDIO_PVCCIO_CPU1")
	)
	(via
		(at 165.7096 -67.779646)
		(size 0.1016)
		(drill 0.0508)
		(layers "F.Cu" "B.Cu")
		(net "SVID_VDIO_PVCCIO_CPU1")
	)
	(via
		(at 342.83142 -87.5157)
		(size 0.508)
		(drill 0.254)
		(layers "F.Cu" "B.Cu")
		(net "SVID_VDIO_PVCCIO_CPU0")
	)
	(segment
		(start 343.460578 -87.652098)
		(end 344.0811 -87.652098)
		(width 0.1016)
		(layer "B.Cu")
		(net "SVID_VDIO_PVCCIO_CPU0")
	)
	(segment
		(start 342.35644 -87.4522)
		(end 342.41994 -87.5157)
		(width 0.1016)
		(layer "B.Cu")
		(net "SVID_VDIO_PVCCIO_CPU0")
	)
	(segment
		(start 342.41994 -87.5157)
		(end 342.83142 -87.5157)
		(width 0.1016)
		(layer "B.Cu")
		(net "SVID_VDIO_PVCCIO_CPU0")
	)
	(segment
		(start 342.83142 -87.5157)
		(end 343.32418 -87.5157)
		(width 0.1016)
		(layer "B.Cu")
		(net "SVID_VDIO_PVCCIO_CPU0")
	)
	(segment
		(start 342.0872 -87.4522)
		(end 342.35644 -87.4522)
		(width 0.1016)
		(layer "B.Cu")
		(net "SVID_VDIO_PVCCIO_CPU0")
	)
	(segment
		(start 343.32418 -87.5157)
		(end 343.460578 -87.652098)
		(width 0.1016)
		(layer "B.Cu")
		(net "SVID_VDIO_PVCCIO_CPU0")
	)
	(segment
		(start 164.973 -69.088)
		(end 165.4302 -69.088)
		(width 0.10795)
		(layer "F.Cu")
		(net "SVID_CLK_PVCCIO_CPU1")
	)
	(segment
		(start 166.347902 -67.001898)
		(end 166.1414 -67.2084)
		(width 0.10795)
		(layer "F.Cu")
		(net "SVID_CLK_PVCCIO_CPU1")
	)
	(segment
		(start 166.1414 -67.2084)
		(end 166.1414 -68.3768)
		(width 0.10795)
		(layer "F.Cu")
		(net "SVID_CLK_PVCCIO_CPU1")
	)
	(segment
		(start 165.4302 -69.088)
		(end 165.7858 -68.7324)
		(width 0.10795)
		(layer "F.Cu")
		(net "SVID_CLK_PVCCIO_CPU1")
	)
	(segment
		(start 166.7383 -67.001898)
		(end 166.347902 -67.001898)
		(width 0.10795)
		(layer "F.Cu")
		(net "SVID_CLK_PVCCIO_CPU1")
	)
	(segment
		(start 166.1414 -68.3768)
		(end 165.7858 -68.7324)
		(width 0.10795)
		(layer "F.Cu")
		(net "SVID_CLK_PVCCIO_CPU1")
	)
	(via
		(at 165.7858 -68.7324)
		(size 0.508)
		(drill 0.254)
		(layers "F.Cu" "B.Cu")
		(net "SVID_CLK_PVCCIO_CPU1")
	)
	(via
		(at 342.8238 -86.741)
		(size 0.6604)
		(drill 0.3302)
		(layers "F.Cu" "B.Cu")
		(net "SVID_CLK_PVCCIO_CPU0")
	)
	(segment
		(start 344.0811 -87.252302)
		(end 343.335102 -87.252302)
		(width 0.1016)
		(layer "B.Cu")
		(net "SVID_CLK_PVCCIO_CPU0")
	)
	(segment
		(start 343.335102 -87.252302)
		(end 342.8238 -86.741)
		(width 0.1016)
		(layer "B.Cu")
		(net "SVID_CLK_PVCCIO_CPU0")
	)
	(segment
		(start 342.0872 -86.5632)
		(end 342.646 -86.5632)
		(width 0.1016)
		(layer "B.Cu")
		(net "SVID_CLK_PVCCIO_CPU0")
	)
	(segment
		(start 342.646 -86.5632)
		(end 342.8238 -86.741)
		(width 0.1016)
		(layer "B.Cu")
		(net "SVID_CLK_PVCCIO_CPU0")
	)
	(segment
		(start 165.5953 -66.4845)
		(end 165.877748 -66.202052)
		(width 0.10795)
		(layer "F.Cu")
		(net "SVID_ALERT_PVCCIO_CPU1")
	)
	(segment
		(start 164.973 -67.1068)
		(end 165.5953 -66.4845)
		(width 0.10795)
		(layer "F.Cu")
		(net "SVID_ALERT_PVCCIO_CPU1")
	)
	(segment
		(start 164.973 -67.31)
		(end 164.973 -67.1068)
		(width 0.10795)
		(layer "F.Cu")
		(net "SVID_ALERT_PVCCIO_CPU1")
	)
	(segment
		(start 165.877748 -66.202052)
		(end 166.7383 -66.202052)
		(width 0.10795)
		(layer "F.Cu")
		(net "SVID_ALERT_PVCCIO_CPU1")
	)
	(via
		(at 165.5953 -66.4845)
		(size 0.1016)
		(drill 0.0508)
		(layers "F.Cu" "B.Cu")
		(net "SVID_ALERT_PVCCIO_CPU1")
	)
	(via
		(at 342.8238 -88.3412)
		(size 0.6604)
		(drill 0.3302)
		(layers "F.Cu" "B.Cu")
		(net "SVID_ALERT_PVCCIO_CPU0")
	)
	(segment
		(start 344.0811 -88.052148)
		(end 343.403936 -88.052148)
		(width 0.1016)
		(layer "B.Cu")
		(net "SVID_ALERT_PVCCIO_CPU0")
	)
	(segment
		(start 343.114884 -88.3412)
		(end 342.8238 -88.3412)
		(width 0.1016)
		(layer "B.Cu")
		(net "SVID_ALERT_PVCCIO_CPU0")
	)
	(segment
		(start 342.0872 -88.3412)
		(end 342.8238 -88.3412)
		(width 0.10795)
		(layer "B.Cu")
		(net "SVID_ALERT_PVCCIO_CPU0")
	)
	(segment
		(start 343.403936 -88.052148)
		(end 343.114884 -88.3412)
		(width 0.1016)
		(layer "B.Cu")
		(net "SVID_ALERT_PVCCIO_CPU0")
	)
	(segment
		(start 402.1709 -101.1555)
		(end 402.378926 -100.947474)
		(width 0.0889)
		(layer "F.Cu")
		(net "RST_BMC_SYSRST_BTN_OUT_B_N")
	)
	(segment
		(start 400.05 -101.35489)
		(end 400.42211 -101.35489)
		(width 0.0889)
		(layer "F.Cu")
		(net "RST_BMC_SYSRST_BTN_OUT_B_N")
	)
	(segment
		(start 400.42211 -101.35489)
		(end 400.734784 -101.042216)
		(width 0.0889)
		(layer "F.Cu")
		(net "RST_BMC_SYSRST_BTN_OUT_B_N")
	)
	(segment
		(start 401.029932 -101.042216)
		(end 401.143216 -101.1555)
		(width 0.0889)
		(layer "F.Cu")
		(net "RST_BMC_SYSRST_BTN_OUT_B_N")
	)
	(segment
		(start 400.734784 -101.042216)
		(end 401.029932 -101.042216)
		(width 0.0889)
		(layer "F.Cu")
		(net "RST_BMC_SYSRST_BTN_OUT_B_N")
	)
	(segment
		(start 401.143216 -101.1555)
		(end 402.1709 -101.1555)
		(width 0.0889)
		(layer "F.Cu")
		(net "RST_BMC_SYSRST_BTN_OUT_B_N")
	)
	(segment
		(start 402.6281 -100.947474)
		(end 402.6281 -100.9396)
		(width 0.0889)
		(layer "F.Cu")
		(net "RST_BMC_SYSRST_BTN_OUT_B_N")
	)
	(segment
		(start 402.378926 -100.947474)
		(end 402.6281 -100.947474)
		(width 0.0889)
		(layer "F.Cu")
		(net "RST_BMC_SYSRST_BTN_OUT_B_N")
	)
	(segment
		(start 414.1216 -101.2698)
		(end 415.29 -101.2698)
		(width 0.10795)
		(layer "F.Cu")
		(net "RST_BMC_SYSRST_BTN_OUT_B_N")
	)
	(via
		(at 398.30248 -63.93434)
		(size 0.508)
		(drill 0.254)
		(layers "F.Cu" "B.Cu")
		(net "RST_BMC_SYSRST_BTN_OUT_B_N")
	)
	(via
		(at 396.494 -42.799)
		(size 0.6604)
		(drill 0.3302)
		(layers "F.Cu" "B.Cu")
		(net "RST_BMC_SYSRST_BTN_OUT_B_N")
	)
	(via
		(at 402.6281 -100.9396)
		(size 0.508)
		(drill 0.254)
		(layers "F.Cu" "B.Cu")
		(net "RST_BMC_SYSRST_BTN_OUT_B_N")
	)
	(via
		(at 414.1216 -101.2698)
		(size 0.508)
		(drill 0.254)
		(layers "F.Cu" "B.Cu")
		(net "RST_BMC_SYSRST_BTN_OUT_B_N")
	)
	(segment
		(start 398.30756 -59.313572)
		(end 398.606772 -59.01436)
		(width 0.10795)
		(layer "B.Cu")
		(net "RST_BMC_SYSRST_BTN_OUT_B_N")
	)
	(segment
		(start 391.815574 -40.873426)
		(end 393.0396 -39.6494)
		(width 0.10795)
		(layer "B.Cu")
		(net "RST_BMC_SYSRST_BTN_OUT_B_N")
	)
	(segment
		(start 397.327882 -44.521882)
		(end 397.327882 -44.047664)
		(width 0.10795)
		(layer "B.Cu")
		(net "RST_BMC_SYSRST_BTN_OUT_B_N")
	)
	(segment
		(start 393.974574 -41.832022)
		(end 392.356086 -41.832022)
		(width 0.10795)
		(layer "B.Cu")
		(net "RST_BMC_SYSRST_BTN_OUT_B_N")
	)
	(segment
		(start 392.356086 -41.832022)
		(end 391.818114 -41.29405)
		(width 0.10795)
		(layer "B.Cu")
		(net "RST_BMC_SYSRST_BTN_OUT_B_N")
	)
	(segment
		(start 395.007592 -41.439846)
		(end 394.36675 -41.439846)
		(width 0.10795)
		(layer "B.Cu")
		(net "RST_BMC_SYSRST_BTN_OUT_B_N")
	)
	(segment
		(start 402.456904 -48.296322)
		(end 400.536664 -46.376082)
		(width 0.10795)
		(layer "B.Cu")
		(net "RST_BMC_SYSRST_BTN_OUT_B_N")
	)
	(segment
		(start 403.088348 -50.536348)
		(end 402.456904 -49.904904)
		(width 0.10795)
		(layer "B.Cu")
		(net "RST_BMC_SYSRST_BTN_OUT_B_N")
	)
	(segment
		(start 398.30248 -63.93434)
		(end 398.860518 -63.376302)
		(width 0.10795)
		(layer "B.Cu")
		(net "RST_BMC_SYSRST_BTN_OUT_B_N")
	)
	(segment
		(start 396.621 -43.340782)
		(end 396.621 -42.926)
		(width 0.10795)
		(layer "B.Cu")
		(net "RST_BMC_SYSRST_BTN_OUT_B_N")
	)
	(segment
		(start 403.088348 -57.493916)
		(end 403.088348 -50.536348)
		(width 0.10795)
		(layer "B.Cu")
		(net "RST_BMC_SYSRST_BTN_OUT_B_N")
	)
	(segment
		(start 396.248636 -42.553636)
		(end 396.121382 -42.553636)
		(width 0.10795)
		(layer "B.Cu")
		(net "RST_BMC_SYSRST_BTN_OUT_B_N")
	)
	(segment
		(start 401.567904 -59.01436)
		(end 403.088348 -57.493916)
		(width 0.10795)
		(layer "B.Cu")
		(net "RST_BMC_SYSRST_BTN_OUT_B_N")
	)
	(segment
		(start 398.860518 -61.205872)
		(end 398.30756 -60.652914)
		(width 0.10795)
		(layer "B.Cu")
		(net "RST_BMC_SYSRST_BTN_OUT_B_N")
	)
	(segment
		(start 398.860518 -63.376302)
		(end 398.860518 -61.894974)
		(width 0.10795)
		(layer "B.Cu")
		(net "RST_BMC_SYSRST_BTN_OUT_B_N")
	)
	(segment
		(start 402.456904 -49.904904)
		(end 402.456904 -48.296322)
		(width 0.10795)
		(layer "B.Cu")
		(net "RST_BMC_SYSRST_BTN_OUT_B_N")
	)
	(segment
		(start 396.121382 -42.553636)
		(end 395.007592 -41.439846)
		(width 0.10795)
		(layer "B.Cu")
		(net "RST_BMC_SYSRST_BTN_OUT_B_N")
	)
	(segment
		(start 398.30756 -60.652914)
		(end 398.30756 -59.313572)
		(width 0.10795)
		(layer "B.Cu")
		(net "RST_BMC_SYSRST_BTN_OUT_B_N")
	)
	(segment
		(start 398.860518 -61.894974)
		(end 398.860518 -61.205872)
		(width 0.10795)
		(layer "B.Cu")
		(net "RST_BMC_SYSRST_BTN_OUT_B_N")
	)
	(segment
		(start 396.494 -42.799)
		(end 396.248636 -42.553636)
		(width 0.10795)
		(layer "B.Cu")
		(net "RST_BMC_SYSRST_BTN_OUT_B_N")
	)
	(segment
		(start 396.621 -42.926)
		(end 396.494 -42.799)
		(width 0.10795)
		(layer "B.Cu")
		(net "RST_BMC_SYSRST_BTN_OUT_B_N")
	)
	(segment
		(start 398.606772 -59.01436)
		(end 401.567904 -59.01436)
		(width 0.10795)
		(layer "B.Cu")
		(net "RST_BMC_SYSRST_BTN_OUT_B_N")
	)
	(segment
		(start 391.815574 -41.29405)
		(end 391.815574 -40.873426)
		(width 0.10795)
		(layer "B.Cu")
		(net "RST_BMC_SYSRST_BTN_OUT_B_N")
	)
	(segment
		(start 393.0396 -39.6494)
		(end 393.0396 -38.0238)
		(width 0.10795)
		(layer "B.Cu")
		(net "RST_BMC_SYSRST_BTN_OUT_B_N")
	)
	(segment
		(start 394.36675 -41.439846)
		(end 393.974574 -41.832022)
		(width 0.10795)
		(layer "B.Cu")
		(net "RST_BMC_SYSRST_BTN_OUT_B_N")
	)
	(segment
		(start 391.818114 -41.29405)
		(end 391.815574 -41.29405)
		(width 0.10795)
		(layer "B.Cu")
		(net "RST_BMC_SYSRST_BTN_OUT_B_N")
	)
	(segment
		(start 400.536664 -46.376082)
		(end 399.182082 -46.376082)
		(width 0.10795)
		(layer "B.Cu")
		(net "RST_BMC_SYSRST_BTN_OUT_B_N")
	)
	(segment
		(start 397.327882 -44.047664)
		(end 396.621 -43.340782)
		(width 0.10795)
		(layer "B.Cu")
		(net "RST_BMC_SYSRST_BTN_OUT_B_N")
	)
	(segment
		(start 399.182082 -46.376082)
		(end 397.327882 -44.521882)
		(width 0.10795)
		(layer "B.Cu")
		(net "RST_BMC_SYSRST_BTN_OUT_B_N")
	)
	(segment
		(start 402.6281 -101.245924)
		(end 402.6281 -100.9396)
		(width 0.089408)
		(layer "In4.Cu")
		(net "RST_BMC_SYSRST_BTN_OUT_B_N")
	)
	(segment
		(start 405.982678 -102.74935)
		(end 404.840186 -101.606858)
		(width 0.089408)
		(layer "In4.Cu")
		(net "RST_BMC_SYSRST_BTN_OUT_B_N")
	)
	(segment
		(start 402.989034 -101.606858)
		(end 402.6281 -101.245924)
		(width 0.089408)
		(layer "In4.Cu")
		(net "RST_BMC_SYSRST_BTN_OUT_B_N")
	)
	(segment
		(start 404.840186 -101.606858)
		(end 402.989034 -101.606858)
		(width 0.089408)
		(layer "In4.Cu")
		(net "RST_BMC_SYSRST_BTN_OUT_B_N")
	)
	(segment
		(start 408.517598 -102.74935)
		(end 405.982678 -102.74935)
		(width 0.089408)
		(layer "In4.Cu")
		(net "RST_BMC_SYSRST_BTN_OUT_B_N")
	)
	(segment
		(start 414.1216 -101.2698)
		(end 409.997148 -101.2698)
		(width 0.089408)
		(layer "In4.Cu")
		(net "RST_BMC_SYSRST_BTN_OUT_B_N")
	)
	(segment
		(start 409.997148 -101.2698)
		(end 408.517598 -102.74935)
		(width 0.089408)
		(layer "In4.Cu")
		(net "RST_BMC_SYSRST_BTN_OUT_B_N")
	)
	(segment
		(start 400.41322 -77.22489)
		(end 401.089368 -77.901038)
		(width 0.089408)
		(layer "In11.Cu")
		(net "RST_BMC_SYSRST_BTN_OUT_B_N")
	)
	(segment
		(start 402.058632 -83.727036)
		(end 402.058632 -84.808568)
		(width 0.089408)
		(layer "In11.Cu")
		(net "RST_BMC_SYSRST_BTN_OUT_B_N")
	)
	(segment
		(start 402.874988 -87.759032)
		(end 402.570696 -88.063324)
		(width 0.089408)
		(layer "In11.Cu")
		(net "RST_BMC_SYSRST_BTN_OUT_B_N")
	)
	(segment
		(start 400.901662 -78.810358)
		(end 400.901662 -82.570066)
		(width 0.089408)
		(layer "In11.Cu")
		(net "RST_BMC_SYSRST_BTN_OUT_B_N")
	)
	(segment
		(start 397.129 -66.6242)
		(end 397.129 -70.261734)
		(width 0.089408)
		(layer "In11.Cu")
		(net "RST_BMC_SYSRST_BTN_OUT_B_N")
	)
	(segment
		(start 402.058632 -84.808568)
		(end 402.874988 -85.624924)
		(width 0.089408)
		(layer "In11.Cu")
		(net "RST_BMC_SYSRST_BTN_OUT_B_N")
	)
	(segment
		(start 397.6116 -66.1416)
		(end 397.129 -66.6242)
		(width 0.089408)
		(layer "In11.Cu")
		(net "RST_BMC_SYSRST_BTN_OUT_B_N")
	)
	(segment
		(start 402.209 -100.1268)
		(end 402.6281 -100.5459)
		(width 0.089408)
		(layer "In11.Cu")
		(net "RST_BMC_SYSRST_BTN_OUT_B_N")
	)
	(segment
		(start 397.129 -70.261734)
		(end 398.51711 -71.649844)
		(width 0.089408)
		(layer "In11.Cu")
		(net "RST_BMC_SYSRST_BTN_OUT_B_N")
	)
	(segment
		(start 398.30248 -63.93434)
		(end 398.30248 -64.010032)
		(width 0.089408)
		(layer "In11.Cu")
		(net "RST_BMC_SYSRST_BTN_OUT_B_N")
	)
	(segment
		(start 398.51711 -72.6948)
		(end 399.8468 -74.02449)
		(width 0.089408)
		(layer "In11.Cu")
		(net "RST_BMC_SYSRST_BTN_OUT_B_N")
	)
	(segment
		(start 401.089368 -77.901038)
		(end 401.089368 -78.622652)
		(width 0.089408)
		(layer "In11.Cu")
		(net "RST_BMC_SYSRST_BTN_OUT_B_N")
	)
	(segment
		(start 402.874988 -85.624924)
		(end 402.874988 -87.759032)
		(width 0.089408)
		(layer "In11.Cu")
		(net "RST_BMC_SYSRST_BTN_OUT_B_N")
	)
	(segment
		(start 397.6116 -64.700912)
		(end 397.6116 -66.1416)
		(width 0.089408)
		(layer "In11.Cu")
		(net "RST_BMC_SYSRST_BTN_OUT_B_N")
	)
	(segment
		(start 402.6281 -99.1743)
		(end 402.209 -99.5934)
		(width 0.089408)
		(layer "In11.Cu")
		(net "RST_BMC_SYSRST_BTN_OUT_B_N")
	)
	(segment
		(start 402.209 -99.5934)
		(end 402.209 -100.1268)
		(width 0.089408)
		(layer "In11.Cu")
		(net "RST_BMC_SYSRST_BTN_OUT_B_N")
	)
	(segment
		(start 402.6281 -100.5459)
		(end 402.6281 -100.9396)
		(width 0.089408)
		(layer "In11.Cu")
		(net "RST_BMC_SYSRST_BTN_OUT_B_N")
	)
	(segment
		(start 402.570696 -92.461842)
		(end 402.6281 -92.519246)
		(width 0.089408)
		(layer "In11.Cu")
		(net "RST_BMC_SYSRST_BTN_OUT_B_N")
	)
	(segment
		(start 398.51711 -71.649844)
		(end 398.51711 -72.6948)
		(width 0.089408)
		(layer "In11.Cu")
		(net "RST_BMC_SYSRST_BTN_OUT_B_N")
	)
	(segment
		(start 402.6281 -92.519246)
		(end 402.6281 -99.1743)
		(width 0.089408)
		(layer "In11.Cu")
		(net "RST_BMC_SYSRST_BTN_OUT_B_N")
	)
	(segment
		(start 399.8468 -75.282806)
		(end 400.41322 -75.849226)
		(width 0.089408)
		(layer "In11.Cu")
		(net "RST_BMC_SYSRST_BTN_OUT_B_N")
	)
	(segment
		(start 399.8468 -74.02449)
		(end 399.8468 -75.282806)
		(width 0.089408)
		(layer "In11.Cu")
		(net "RST_BMC_SYSRST_BTN_OUT_B_N")
	)
	(segment
		(start 402.570696 -88.063324)
		(end 402.570696 -92.461842)
		(width 0.089408)
		(layer "In11.Cu")
		(net "RST_BMC_SYSRST_BTN_OUT_B_N")
	)
	(segment
		(start 400.901662 -82.570066)
		(end 402.058632 -83.727036)
		(width 0.089408)
		(layer "In11.Cu")
		(net "RST_BMC_SYSRST_BTN_OUT_B_N")
	)
	(segment
		(start 401.089368 -78.622652)
		(end 400.901662 -78.810358)
		(width 0.089408)
		(layer "In11.Cu")
		(net "RST_BMC_SYSRST_BTN_OUT_B_N")
	)
	(segment
		(start 398.30248 -64.010032)
		(end 397.6116 -64.700912)
		(width 0.089408)
		(layer "In11.Cu")
		(net "RST_BMC_SYSRST_BTN_OUT_B_N")
	)
	(segment
		(start 400.41322 -75.849226)
		(end 400.41322 -77.22489)
		(width 0.089408)
		(layer "In11.Cu")
		(net "RST_BMC_SYSRST_BTN_OUT_B_N")
	)
	(segment
		(start 165.481 -70.6374)
		(end 166.37 -70.6374)
		(width 0.10795)
		(layer "F.Cu")
		(net "PWRGD_PVCCIO_CPU1_R")
	)
	(segment
		(start 167.573706 -70.322694)
		(end 167.259 -70.6374)
		(width 0.10795)
		(layer "F.Cu")
		(net "PWRGD_PVCCIO_CPU1_R")
	)
	(segment
		(start 167.789352 -69.2531)
		(end 167.789352 -69.723)
		(width 0.10795)
		(layer "F.Cu")
		(net "PWRGD_PVCCIO_CPU1_R")
	)
	(segment
		(start 167.573706 -69.938646)
		(end 167.573706 -70.322694)
		(width 0.10795)
		(layer "F.Cu")
		(net "PWRGD_PVCCIO_CPU1_R")
	)
	(segment
		(start 166.37 -70.6374)
		(end 167.259 -70.6374)
		(width 0.10795)
		(layer "F.Cu")
		(net "PWRGD_PVCCIO_CPU1_R")
	)
	(segment
		(start 167.789352 -69.723)
		(end 167.573706 -69.938646)
		(width 0.10795)
		(layer "F.Cu")
		(net "PWRGD_PVCCIO_CPU1_R")
	)
	(via
		(at 343.48039 -81.743296)
		(size 0.6604)
		(drill 0.3302)
		(layers "F.Cu" "B.Cu")
		(net "PWRGD_PVCCIO_CPU0_R")
	)
	(segment
		(start 343.339166 -81.88452)
		(end 343.48039 -81.743296)
		(width 0.10795)
		(layer "B.Cu")
		(net "PWRGD_PVCCIO_CPU0_R")
	)
	(segment
		(start 343.789 -83.566)
		(end 343.621868 -83.566)
		(width 0.10795)
		(layer "B.Cu")
		(net "PWRGD_PVCCIO_CPU0_R")
	)
	(segment
		(start 342.9 -83.566)
		(end 343.069164 -83.566)
		(width 0.10795)
		(layer "B.Cu")
		(net "PWRGD_PVCCIO_CPU0_R")
	)
	(segment
		(start 343.069164 -83.566)
		(end 343.339166 -83.295998)
		(width 0.10795)
		(layer "B.Cu")
		(net "PWRGD_PVCCIO_CPU0_R")
	)
	(segment
		(start 343.074498 -83.740498)
		(end 342.9 -83.566)
		(width 0.10795)
		(layer "B.Cu")
		(net "PWRGD_PVCCIO_CPU0_R")
	)
	(segment
		(start 343.621868 -83.566)
		(end 343.44737 -83.740498)
		(width 0.10795)
		(layer "B.Cu")
		(net "PWRGD_PVCCIO_CPU0_R")
	)
	(segment
		(start 343.44737 -83.740498)
		(end 343.074498 -83.740498)
		(width 0.10795)
		(layer "B.Cu")
		(net "PWRGD_PVCCIO_CPU0_R")
	)
	(segment
		(start 345.132152 -85.0011)
		(end 345.132152 -84.705952)
		(width 0.10795)
		(layer "B.Cu")
		(net "PWRGD_PVCCIO_CPU0_R")
	)
	(segment
		(start 345.132152 -84.705952)
		(end 344.678 -84.2518)
		(width 0.10795)
		(layer "B.Cu")
		(net "PWRGD_PVCCIO_CPU0_R")
	)
	(segment
		(start 343.339166 -83.295998)
		(end 343.339166 -81.88452)
		(width 0.10795)
		(layer "B.Cu")
		(net "PWRGD_PVCCIO_CPU0_R")
	)
	(segment
		(start 343.789 -83.566)
		(end 344.678 -83.566)
		(width 0.10795)
		(layer "B.Cu")
		(net "PWRGD_PVCCIO_CPU0_R")
	)
	(segment
		(start 344.678 -84.2518)
		(end 344.678 -83.566)
		(width 0.10795)
		(layer "B.Cu")
		(net "PWRGD_PVCCIO_CPU0_R")
	)
	(segment
		(start 172.011848 -65.401952)
		(end 172.3136 -65.1002)
		(width 0.10795)
		(layer "F.Cu")
		(net "PU_VR_PVCCIO_CPU1_FAULT1")
	)
	(segment
		(start 172.3136 -64.6938)
		(end 172.1612 -64.5414)
		(width 0.10795)
		(layer "F.Cu")
		(net "PU_VR_PVCCIO_CPU1_FAULT1")
	)
	(segment
		(start 172.3136 -65.1002)
		(end 172.3136 -64.6938)
		(width 0.10795)
		(layer "F.Cu")
		(net "PU_VR_PVCCIO_CPU1_FAULT1")
	)
	(segment
		(start 171.6405 -65.401952)
		(end 172.011848 -65.401952)
		(width 0.10795)
		(layer "F.Cu")
		(net "PU_VR_PVCCIO_CPU1_FAULT1")
	)
	(via
		(at 172.1612 -64.5414)
		(size 0.508)
		(drill 0.254)
		(layers "F.Cu" "B.Cu")
		(net "PU_VR_PVCCIO_CPU1_FAULT1")
	)
	(segment
		(start 173.482 -65.024)
		(end 172.6438 -65.024)
		(width 0.10795)
		(layer "B.Cu")
		(net "PU_VR_PVCCIO_CPU1_FAULT1")
	)
	(segment
		(start 172.6438 -65.024)
		(end 172.1612 -64.5414)
		(width 0.10795)
		(layer "B.Cu")
		(net "PU_VR_PVCCIO_CPU1_FAULT1")
	)
	(via
		(at 352.1456 -91.9861)
		(size 0.6604)
		(drill 0.3302)
		(layers "F.Cu" "B.Cu")
		(net "PU_VR_PVCCIO_CPU0_FAULT1")
	)
	(segment
		(start 349.510858 -88.987884)
		(end 349.375222 -88.852248)
		(width 0.1016)
		(layer "B.Cu")
		(net "PU_VR_PVCCIO_CPU0_FAULT1")
	)
	(segment
		(start 349.510858 -89.605612)
		(end 349.510858 -88.987884)
		(width 0.1016)
		(layer "B.Cu")
		(net "PU_VR_PVCCIO_CPU0_FAULT1")
	)
	(segment
		(start 350.97212 -90.639392)
		(end 350.97212 -91.33332)
		(width 0.10795)
		(layer "B.Cu")
		(net "PU_VR_PVCCIO_CPU0_FAULT1")
	)
	(segment
		(start 349.375222 -88.852248)
		(end 348.9833 -88.852248)
		(width 0.1016)
		(layer "B.Cu")
		(net "PU_VR_PVCCIO_CPU0_FAULT1")
	)
	(segment
		(start 350.544638 -90.639392)
		(end 349.510858 -89.605612)
		(width 0.10795)
		(layer "B.Cu")
		(net "PU_VR_PVCCIO_CPU0_FAULT1")
	)
	(segment
		(start 351.6249 -91.9861)
		(end 352.1456 -91.9861)
		(width 0.10795)
		(layer "B.Cu")
		(net "PU_VR_PVCCIO_CPU0_FAULT1")
	)
	(segment
		(start 350.97212 -90.639392)
		(end 350.544638 -90.639392)
		(width 0.10795)
		(layer "B.Cu")
		(net "PU_VR_PVCCIO_CPU0_FAULT1")
	)
	(segment
		(start 350.97212 -91.33332)
		(end 351.6249 -91.9861)
		(width 0.10795)
		(layer "B.Cu")
		(net "PU_VR_PVCCIO_CPU0_FAULT1")
	)
	(via
		(at 442.225176 -16.636492)
		(size 0.6604)
		(drill 0.3302)
		(layers "F.Cu" "B.Cu")
		(net "PD_DIR_2")
	)
	(segment
		(start 440.21502 -15.92072)
		(end 440.458606 -16.164306)
		(width 0.10795)
		(layer "B.Cu")
		(net "PD_DIR_2")
	)
	(segment
		(start 442.225176 -16.636492)
		(end 440.679078 -16.636492)
		(width 0.10795)
		(layer "B.Cu")
		(net "PD_DIR_2")
	)
	(segment
		(start 438.5945 -15.92072)
		(end 440.21502 -15.92072)
		(width 0.10795)
		(layer "B.Cu")
		(net "PD_DIR_2")
	)
	(segment
		(start 440.458606 -16.41602)
		(end 440.458606 -16.164306)
		(width 0.10795)
		(layer "B.Cu")
		(net "PD_DIR_2")
	)
	(segment
		(start 440.679078 -16.636492)
		(end 440.458606 -16.41602)
		(width 0.10795)
		(layer "B.Cu")
		(net "PD_DIR_2")
	)
	(via
		(at 440.8932 -13.8811)
		(size 0.6604)
		(drill 0.3302)
		(layers "F.Cu" "B.Cu")
		(net "P0V7_GTL2014_2")
	)
	(via
		(at 432.746658 -18.834608)
		(size 0.6604)
		(drill 0.3302)
		(layers "F.Cu" "B.Cu")
		(net "H_CPU1_KLM_MEMHOT_LVT3_R_N")
	)
	(segment
		(start 430.948338 -19.049238)
		(end 430.68367 -18.78457)
		(width 0.10795)
		(layer "B.Cu")
		(net "H_CPU1_KLM_MEMHOT_LVT3_R_N")
	)
	(segment
		(start 430.68367 -17.09547)
		(end 431.264314 -16.514826)
		(width 0.10795)
		(layer "B.Cu")
		(net "H_CPU1_KLM_MEMHOT_LVT3_R_N")
	)
	(segment
		(start 431.48377 -15.27048)
		(end 432.6255 -15.27048)
		(width 0.10795)
		(layer "B.Cu")
		(net "H_CPU1_KLM_MEMHOT_LVT3_R_N")
	)
	(segment
		(start 433.251356 -17.399)
		(end 433.7685 -17.399)
		(width 0.10795)
		(layer "B.Cu")
		(net "H_CPU1_KLM_MEMHOT_LVT3_R_N")
	)
	(segment
		(start 432.957732 -17.692624)
		(end 433.251356 -17.399)
		(width 0.10795)
		(layer "B.Cu")
		(net "H_CPU1_KLM_MEMHOT_LVT3_R_N")
	)
	(segment
		(start 432.957732 -18.623534)
		(end 432.957732 -17.692624)
		(width 0.10795)
		(layer "B.Cu")
		(net "H_CPU1_KLM_MEMHOT_LVT3_R_N")
	)
	(segment
		(start 432.746658 -18.834608)
		(end 432.957732 -18.623534)
		(width 0.10795)
		(layer "B.Cu")
		(net "H_CPU1_KLM_MEMHOT_LVT3_R_N")
	)
	(segment
		(start 431.264314 -15.489936)
		(end 431.48377 -15.27048)
		(width 0.10795)
		(layer "B.Cu")
		(net "H_CPU1_KLM_MEMHOT_LVT3_R_N")
	)
	(segment
		(start 432.746658 -18.834608)
		(end 432.532028 -19.049238)
		(width 0.10795)
		(layer "B.Cu")
		(net "H_CPU1_KLM_MEMHOT_LVT3_R_N")
	)
	(segment
		(start 430.68367 -18.78457)
		(end 430.68367 -17.09547)
		(width 0.10795)
		(layer "B.Cu")
		(net "H_CPU1_KLM_MEMHOT_LVT3_R_N")
	)
	(segment
		(start 432.532028 -19.049238)
		(end 430.948338 -19.049238)
		(width 0.10795)
		(layer "B.Cu")
		(net "H_CPU1_KLM_MEMHOT_LVT3_R_N")
	)
	(segment
		(start 431.264314 -16.514826)
		(end 431.264314 -15.489936)
		(width 0.10795)
		(layer "B.Cu")
		(net "H_CPU1_KLM_MEMHOT_LVT3_R_N")
	)
	(via
		(at 430.29378 -16.4592)
		(size 0.6604)
		(drill 0.3302)
		(layers "F.Cu" "B.Cu")
		(net "H_CPU1_GHJ_MEMHOT_LVT3_R_N")
	)
	(segment
		(start 430.29378 -16.12392)
		(end 430.726088 -15.691612)
		(width 0.10795)
		(layer "B.Cu")
		(net "H_CPU1_GHJ_MEMHOT_LVT3_R_N")
	)
	(segment
		(start 430.726088 -15.691612)
		(end 430.726088 -15.280894)
		(width 0.10795)
		(layer "B.Cu")
		(net "H_CPU1_GHJ_MEMHOT_LVT3_R_N")
	)
	(segment
		(start 431.386742 -14.62024)
		(end 430.726088 -15.280894)
		(width 0.10795)
		(layer "B.Cu")
		(net "H_CPU1_GHJ_MEMHOT_LVT3_R_N")
	)
	(segment
		(start 430.29378 -16.4592)
		(end 430.29378 -16.12392)
		(width 0.10795)
		(layer "B.Cu")
		(net "H_CPU1_GHJ_MEMHOT_LVT3_R_N")
	)
	(segment
		(start 432.6255 -14.62024)
		(end 431.386742 -14.62024)
		(width 0.10795)
		(layer "B.Cu")
		(net "H_CPU1_GHJ_MEMHOT_LVT3_R_N")
	)
	(segment
		(start 432.6255 -13.31976)
		(end 431.165 -13.31976)
		(width 0.10795)
		(layer "B.Cu")
		(net "H_CPU0_DEF_MEMHOT_LVT3_R_N")
	)
	(segment
		(start 431.165 -13.31976)
		(end 430.76876 -13.716)
		(width 0.10795)
		(layer "B.Cu")
		(net "H_CPU0_DEF_MEMHOT_LVT3_R_N")
	)
	(segment
		(start 430.76876 -13.716)
		(end 430.0855 -13.716)
		(width 0.10795)
		(layer "B.Cu")
		(net "H_CPU0_DEF_MEMHOT_LVT3_R_N")
	)
	(via
		(at 430.3268 -11.303)
		(size 0.6604)
		(drill 0.3302)
		(layers "F.Cu" "B.Cu")
		(net "H_CPU0_ABC_MEMHOT_LVT3_R_N")
	)
	(segment
		(start 430.43602 -12.66952)
		(end 430.2125 -12.446)
		(width 0.10795)
		(layer "B.Cu")
		(net "H_CPU0_ABC_MEMHOT_LVT3_R_N")
	)
	(segment
		(start 430.1871 -11.4427)
		(end 430.3268 -11.303)
		(width 0.10795)
		(layer "B.Cu")
		(net "H_CPU0_ABC_MEMHOT_LVT3_R_N")
	)
	(segment
		(start 430.2125 -12.446)
		(end 430.1871 -12.4206)
		(width 0.10795)
		(layer "B.Cu")
		(net "H_CPU0_ABC_MEMHOT_LVT3_R_N")
	)
	(segment
		(start 432.6255 -12.66952)
		(end 430.43602 -12.66952)
		(width 0.10795)
		(layer "B.Cu")
		(net "H_CPU0_ABC_MEMHOT_LVT3_R_N")
	)
	(segment
		(start 430.1871 -12.4206)
		(end 430.1871 -11.4427)
		(width 0.10795)
		(layer "B.Cu")
		(net "H_CPU0_ABC_MEMHOT_LVT3_R_N")
	)
	(segment
		(start 409.511754 -111.14024)
		(end 409.361894 -111.2901)
		(width 0.10795)
		(layer "F.Cu")
		(net "FM_CPU_CATERR_DLY_LVT3_R_N")
	)
	(segment
		(start 401.386548 -109.94644)
		(end 402.648928 -109.94644)
		(width 0.10795)
		(layer "F.Cu")
		(net "FM_CPU_CATERR_DLY_LVT3_R_N")
	)
	(segment
		(start 401.295108 -109.855)
		(end 401.386548 -109.94644)
		(width 0.10795)
		(layer "F.Cu")
		(net "FM_CPU_CATERR_DLY_LVT3_R_N")
	)
	(segment
		(start 405.444452 -110.293912)
		(end 405.87422 -110.72368)
		(width 0.10795)
		(layer "F.Cu")
		(net "FM_CPU_CATERR_DLY_LVT3_R_N")
	)
	(segment
		(start 409.361894 -111.2901)
		(end 406.44064 -111.2901)
		(width 0.10795)
		(layer "F.Cu")
		(net "FM_CPU_CATERR_DLY_LVT3_R_N")
	)
	(segment
		(start 402.648928 -109.94644)
		(end 402.989288 -110.2868)
		(width 0.10795)
		(layer "F.Cu")
		(net "FM_CPU_CATERR_DLY_LVT3_R_N")
	)
	(segment
		(start 417.43122 -111.19612)
		(end 417.37534 -111.14024)
		(width 0.10795)
		(layer "F.Cu")
		(net "FM_CPU_CATERR_DLY_LVT3_R_N")
	)
	(segment
		(start 403.003258 -110.293912)
		(end 405.444452 -110.293912)
		(width 0.10795)
		(layer "F.Cu")
		(net "FM_CPU_CATERR_DLY_LVT3_R_N")
	)
	(segment
		(start 402.989288 -110.2868)
		(end 402.996146 -110.2868)
		(width 0.10795)
		(layer "F.Cu")
		(net "FM_CPU_CATERR_DLY_LVT3_R_N")
	)
	(segment
		(start 406.44064 -111.2901)
		(end 405.92502 -110.77448)
		(width 0.10795)
		(layer "F.Cu")
		(net "FM_CPU_CATERR_DLY_LVT3_R_N")
	)
	(segment
		(start 402.996146 -110.2868)
		(end 403.003258 -110.293912)
		(width 0.10795)
		(layer "F.Cu")
		(net "FM_CPU_CATERR_DLY_LVT3_R_N")
	)
	(segment
		(start 405.92502 -110.77448)
		(end 405.92502 -110.72368)
		(width 0.10795)
		(layer "F.Cu")
		(net "FM_CPU_CATERR_DLY_LVT3_R_N")
	)
	(segment
		(start 405.87422 -110.72368)
		(end 405.92502 -110.72368)
		(width 0.10795)
		(layer "F.Cu")
		(net "FM_CPU_CATERR_DLY_LVT3_R_N")
	)
	(segment
		(start 417.37534 -111.14024)
		(end 409.511754 -111.14024)
		(width 0.10795)
		(layer "F.Cu")
		(net "FM_CPU_CATERR_DLY_LVT3_R_N")
	)
	(via
		(at 405.92502 -110.72368)
		(size 0.762)
		(drill 0.381)
		(layers "F.Cu" "B.Cu")
		(net "FM_CPU_CATERR_DLY_LVT3_R_N")
	)
	(via
		(at 402.082254 2.7178)
		(size 0.6604)
		(drill 0.3302)
		(layers "F.Cu" "B.Cu")
		(net "FAN_PWM_OUT_SYS1_BUF")
	)
	(segment
		(start 403.8854 3.1496)
		(end 403.691598 2.955798)
		(width 0.10795)
		(layer "B.Cu")
		(net "FAN_PWM_OUT_SYS1_BUF")
	)
	(segment
		(start 403.691598 2.955798)
		(end 402.320252 2.955798)
		(width 0.10795)
		(layer "B.Cu")
		(net "FAN_PWM_OUT_SYS1_BUF")
	)
	(segment
		(start 404.4696 3.6322)
		(end 405.0284 3.6322)
		(width 0.10795)
		(layer "B.Cu")
		(net "FAN_PWM_OUT_SYS1_BUF")
	)
	(segment
		(start 402.320252 2.955798)
		(end 402.082254 2.7178)
		(width 0.10795)
		(layer "B.Cu")
		(net "FAN_PWM_OUT_SYS1_BUF")
	)
	(segment
		(start 403.8854 3.3782)
		(end 404.2156 3.3782)
		(width 0.10795)
		(layer "B.Cu")
		(net "FAN_PWM_OUT_SYS1_BUF")
	)
	(segment
		(start 404.2156 3.3782)
		(end 404.4696 3.6322)
		(width 0.10795)
		(layer "B.Cu")
		(net "FAN_PWM_OUT_SYS1_BUF")
	)
	(segment
		(start 403.8854 3.3782)
		(end 403.8854 3.1496)
		(width 0.10795)
		(layer "B.Cu")
		(net "FAN_PWM_OUT_SYS1_BUF")
	)
	(via
		(at 408.559 3.2512)
		(size 0.6604)
		(drill 0.3302)
		(layers "F.Cu" "B.Cu")
		(net "FAN_PWM_OUT_SYS0_BUF")
	)
	(segment
		(start 409.702 1.579372)
		(end 409.702 2.722372)
		(width 0.10795)
		(layer "B.Cu")
		(net "FAN_PWM_OUT_SYS0_BUF")
	)
	(segment
		(start 409.702 2.722372)
		(end 409.087828 2.722372)
		(width 0.10795)
		(layer "B.Cu")
		(net "FAN_PWM_OUT_SYS0_BUF")
	)
	(segment
		(start 409.087828 2.722372)
		(end 408.559 3.2512)
		(width 0.10795)
		(layer "B.Cu")
		(net "FAN_PWM_OUT_SYS0_BUF")
	)
	(segment
		(start 205.036928 -78.087728)
		(end 204.4192 -77.47)
		(width 0.508)
		(layer "F.Cu")
		(net "VR_PVCCIN_CPU0_PHASE4")
	)
	(segment
		(start 205.036928 -81.415382)
		(end 205.036928 -78.087728)
		(width 0.508)
		(layer "F.Cu")
		(net "VR_PVCCIN_CPU0_PHASE4")
	)
	(segment
		(start 205.036928 -69.756528)
		(end 204.6224 -69.342)
		(width 0.508)
		(layer "F.Cu")
		(net "VR_PVCCIN_CPU0_PHASE3")
	)
	(segment
		(start 205.036928 -73.287382)
		(end 205.036928 -69.756528)
		(width 0.508)
		(layer "F.Cu")
		(net "VR_PVCCIN_CPU0_PHASE3")
	)
	(segment
		(start 197.19798 -77.216)
		(end 197.19798 -77.978)
		(width 0.508)
		(layer "F.Cu")
		(net "VR_PVCCIN_CPU0_PH4_VCIN")
	)
	(segment
		(start 197.17258 -78.19898)
		(end 197.17258 -78.0034)
		(width 0.254)
		(layer "F.Cu")
		(net "VR_PVCCIN_CPU0_PH4_VCIN")
	)
	(segment
		(start 197.545452 -78.571852)
		(end 197.17258 -78.19898)
		(width 0.254)
		(layer "F.Cu")
		(net "VR_PVCCIN_CPU0_PH4_VCIN")
	)
	(segment
		(start 197.19798 -77.978)
		(end 197.17258 -78.0034)
		(width 0.508)
		(layer "F.Cu")
		(net "VR_PVCCIN_CPU0_PH4_VCIN")
	)
	(segment
		(start 197.545452 -79.028544)
		(end 197.545452 -78.571852)
		(width 0.254)
		(layer "F.Cu")
		(net "VR_PVCCIN_CPU0_PH4_VCIN")
	)
	(via
		(at 197.17258 -78.0034)
		(size 0.508)
		(drill 0.254)
		(layers "F.Cu" "B.Cu")
		(net "VR_PVCCIN_CPU0_PH4_VCIN")
	)
	(via
		(at 196.48932 -77.52842)
		(size 0.6604)
		(drill 0.3302)
		(layers "F.Cu" "B.Cu")
		(net "VR_PVCCIN_CPU0_PH4_VCIN")
	)
	(segment
		(start 197.239128 -78.82509)
		(end 197.08495 -78.670912)
		(width 0.4064)
		(layer "B.Cu")
		(net "VR_PVCCIN_CPU0_PH4_VCIN")
	)
	(segment
		(start 196.9389 -77.978)
		(end 196.48932 -77.52842)
		(width 0.254)
		(layer "B.Cu")
		(net "VR_PVCCIN_CPU0_PH4_VCIN")
	)
	(segment
		(start 197.14718 -77.978)
		(end 196.9389 -77.978)
		(width 0.254)
		(layer "B.Cu")
		(net "VR_PVCCIN_CPU0_PH4_VCIN")
	)
	(segment
		(start 197.08495 -78.09103)
		(end 197.17258 -78.0034)
		(width 0.4064)
		(layer "B.Cu")
		(net "VR_PVCCIN_CPU0_PH4_VCIN")
	)
	(segment
		(start 197.08495 -78.670912)
		(end 197.08495 -78.09103)
		(width 0.4064)
		(layer "B.Cu")
		(net "VR_PVCCIN_CPU0_PH4_VCIN")
	)
	(segment
		(start 197.239128 -78.915006)
		(end 197.239128 -78.82509)
		(width 0.4064)
		(layer "B.Cu")
		(net "VR_PVCCIN_CPU0_PH4_VCIN")
	)
	(segment
		(start 197.17258 -78.0034)
		(end 197.14718 -77.978)
		(width 0.254)
		(layer "B.Cu")
		(net "VR_PVCCIN_CPU0_PH4_VCIN")
	)
	(segment
		(start 194.6275 -83.212432)
		(end 194.917568 -83.212432)
		(width 0.508)
		(layer "F.Cu")
		(net "VR_PVCCIN_CPU0_PH4_PHASE")
	)
	(segment
		(start 195.556124 -82.573876)
		(end 196.030342 -82.573876)
		(width 0.254)
		(layer "F.Cu")
		(net "VR_PVCCIN_CPU0_PH4_PHASE")
	)
	(segment
		(start 195.245228 -82.884772)
		(end 195.556124 -82.573876)
		(width 0.254)
		(layer "F.Cu")
		(net "VR_PVCCIN_CPU0_PH4_PHASE")
	)
	(segment
		(start 194.917568 -83.212432)
		(end 195.245228 -82.884772)
		(width 0.508)
		(layer "F.Cu")
		(net "VR_PVCCIN_CPU0_PH4_PHASE")
	)
	(segment
		(start 193.7385 -83.212432)
		(end 193.090546 -83.212432)
		(width 0.508)
		(layer "F.Cu")
		(net "VR_PVCCIN_CPU0_PH4_BOOT")
	)
	(segment
		(start 192.571624 -82.561176)
		(end 192.6463 -82.4865)
		(width 0.508)
		(layer "F.Cu")
		(net "VR_PVCCIN_CPU0_PH4_BOOT")
	)
	(segment
		(start 192.571624 -83.28533)
		(end 192.571624 -82.561176)
		(width 0.508)
		(layer "F.Cu")
		(net "VR_PVCCIN_CPU0_PH4_BOOT")
	)
	(segment
		(start 193.090546 -83.212432)
		(end 192.966848 -83.33613)
		(width 0.508)
		(layer "F.Cu")
		(net "VR_PVCCIN_CPU0_PH4_BOOT")
	)
	(segment
		(start 192.520824 -83.33613)
		(end 192.571624 -83.28533)
		(width 0.508)
		(layer "F.Cu")
		(net "VR_PVCCIN_CPU0_PH4_BOOT")
	)
	(segment
		(start 192.6463 -82.4865)
		(end 192.6463 -82.209132)
		(width 0.508)
		(layer "F.Cu")
		(net "VR_PVCCIN_CPU0_PH4_BOOT")
	)
	(segment
		(start 192.966848 -83.33613)
		(end 192.520824 -83.33613)
		(width 0.508)
		(layer "F.Cu")
		(net "VR_PVCCIN_CPU0_PH4_BOOT")
	)
	(via
		(at 192.520824 -83.33613)
		(size 0.508)
		(drill 0.254)
		(layers "F.Cu" "B.Cu")
		(net "VR_PVCCIN_CPU0_PH4_BOOT")
	)
	(segment
		(start 197.545452 -70.900544)
		(end 197.545452 -70.393052)
		(width 0.254)
		(layer "F.Cu")
		(net "VR_PVCCIN_CPU0_PH3_VCIN")
	)
	(segment
		(start 197.545452 -70.393052)
		(end 197.2818 -70.1294)
		(width 0.254)
		(layer "F.Cu")
		(net "VR_PVCCIN_CPU0_PH3_VCIN")
	)
	(segment
		(start 197.108826 -69.804026)
		(end 197.2818 -69.977)
		(width 0.254)
		(layer "F.Cu")
		(net "VR_PVCCIN_CPU0_PH3_VCIN")
	)
	(segment
		(start 197.108826 -69.324474)
		(end 197.108826 -69.804026)
		(width 0.254)
		(layer "F.Cu")
		(net "VR_PVCCIN_CPU0_PH3_VCIN")
	)
	(segment
		(start 197.2818 -70.1294)
		(end 197.2818 -69.977)
		(width 0.254)
		(layer "F.Cu")
		(net "VR_PVCCIN_CPU0_PH3_VCIN")
	)
	(via
		(at 196.0372 -69.8119)
		(size 0.6604)
		(drill 0.3302)
		(layers "F.Cu" "B.Cu")
		(net "VR_PVCCIN_CPU0_PH3_VCIN")
	)
	(via
		(at 197.2818 -69.977)
		(size 0.508)
		(drill 0.254)
		(layers "F.Cu" "B.Cu")
		(net "VR_PVCCIN_CPU0_PH3_VCIN")
	)
	(segment
		(start 197.239128 -70.787006)
		(end 197.239128 -70.019672)
		(width 0.4064)
		(layer "B.Cu")
		(net "VR_PVCCIN_CPU0_PH3_VCIN")
	)
	(segment
		(start 197.104 -69.977)
		(end 197.0659 -70.0151)
		(width 0.254)
		(layer "B.Cu")
		(net "VR_PVCCIN_CPU0_PH3_VCIN")
	)
	(segment
		(start 196.2404 -70.0151)
		(end 196.0372 -69.8119)
		(width 0.254)
		(layer "B.Cu")
		(net "VR_PVCCIN_CPU0_PH3_VCIN")
	)
	(segment
		(start 197.239128 -70.019672)
		(end 197.2818 -69.977)
		(width 0.4064)
		(layer "B.Cu")
		(net "VR_PVCCIN_CPU0_PH3_VCIN")
	)
	(segment
		(start 197.2818 -69.977)
		(end 197.104 -69.977)
		(width 0.254)
		(layer "B.Cu")
		(net "VR_PVCCIN_CPU0_PH3_VCIN")
	)
	(segment
		(start 197.0659 -70.0151)
		(end 196.2404 -70.0151)
		(width 0.254)
		(layer "B.Cu")
		(net "VR_PVCCIN_CPU0_PH3_VCIN")
	)
	(segment
		(start 194.7926 -75.1332)
		(end 195.275962 -74.649838)
		(width 0.508)
		(layer "F.Cu")
		(net "VR_PVCCIN_CPU0_PH3_PHASE")
	)
	(segment
		(start 195.275962 -74.649838)
		(end 195.479924 -74.445876)
		(width 0.254)
		(layer "F.Cu")
		(net "VR_PVCCIN_CPU0_PH3_PHASE")
	)
	(segment
		(start 195.479924 -74.445876)
		(end 196.030342 -74.445876)
		(width 0.254)
		(layer "F.Cu")
		(net "VR_PVCCIN_CPU0_PH3_PHASE")
	)
	(segment
		(start 193.5988 -75.1332)
		(end 193.9036 -75.1332)
		(width 0.508)
		(layer "F.Cu")
		(net "VR_PVCCIN_CPU0_PH3_BOOT")
	)
	(segment
		(start 191.9732 -74.2696)
		(end 191.9732 -75.6666)
		(width 0.508)
		(layer "F.Cu")
		(net "VR_PVCCIN_CPU0_PH3_BOOT")
	)
	(segment
		(start 192.0748 -74.168)
		(end 191.9732 -74.2696)
		(width 0.508)
		(layer "F.Cu")
		(net "VR_PVCCIN_CPU0_PH3_BOOT")
	)
	(segment
		(start 192.50787 -76.0476)
		(end 192.6844 -76.0476)
		(width 0.508)
		(layer "F.Cu")
		(net "VR_PVCCIN_CPU0_PH3_BOOT")
	)
	(segment
		(start 191.9732 -75.6666)
		(end 192.3542 -76.0476)
		(width 0.508)
		(layer "F.Cu")
		(net "VR_PVCCIN_CPU0_PH3_BOOT")
	)
	(segment
		(start 192.3542 -76.0476)
		(end 192.50787 -76.0476)
		(width 0.508)
		(layer "F.Cu")
		(net "VR_PVCCIN_CPU0_PH3_BOOT")
	)
	(segment
		(start 192.6844 -76.0476)
		(end 193.5988 -75.1332)
		(width 0.508)
		(layer "F.Cu")
		(net "VR_PVCCIN_CPU0_PH3_BOOT")
	)
	(via
		(at 192.50787 -76.0476)
		(size 0.762)
		(drill 0.381)
		(layers "F.Cu" "B.Cu")
		(net "VR_PVCCIN_CPU0_PH3_BOOT")
	)
	(via
		(at 349.494094 -144.646142)
		(size 0.508)
		(drill 0.254)
		(layers "F.Cu" "B.Cu")
		(net "VR_FET_SW_P12V_STBY_PVDDQ_DEF")
	)
	(via
		(at 369.221512 -153.255472)
		(size 0.508)
		(drill 0.254)
		(layers "F.Cu" "B.Cu")
		(net "VR_FET_SW_P12V_STBY_PVDDQ_DEF")
	)
	(via
		(at 353.158806 -148.643594)
		(size 0.6604)
		(drill 0.3302)
		(layers "F.Cu" "B.Cu")
		(net "VR_FET_SW_P12V_STBY_PVDDQ_DEF")
	)
	(via
		(at 389.19658 -155.134056)
		(size 0.508)
		(drill 0.254)
		(layers "F.Cu" "B.Cu")
		(net "VR_FET_SW_P12V_STBY_PVDDQ_DEF")
	)
	(via
		(at 349.494094 -150.742142)
		(size 0.508)
		(drill 0.254)
		(layers "F.Cu" "B.Cu")
		(net "VR_FET_SW_P12V_STBY_PVDDQ_DEF")
	)
	(via
		(at 387.8707 -155.702)
		(size 0.508)
		(drill 0.254)
		(layers "F.Cu" "B.Cu")
		(net "VR_FET_SW_P12V_STBY_PVDDQ_DEF")
	)
	(via
		(at 349.494094 -152.570942)
		(size 0.508)
		(drill 0.254)
		(layers "F.Cu" "B.Cu")
		(net "VR_FET_SW_P12V_STBY_PVDDQ_DEF")
	)
	(via
		(at 377.929648 -155.354528)
		(size 0.508)
		(drill 0.254)
		(layers "F.Cu" "B.Cu")
		(net "VR_FET_SW_P12V_STBY_PVDDQ_DEF")
	)
	(via
		(at 364.0074 -147.76958)
		(size 0.508)
		(drill 0.254)
		(layers "F.Cu" "B.Cu")
		(net "VR_FET_SW_P12V_STBY_PVDDQ_DEF")
	)
	(via
		(at 377.015248 -155.379928)
		(size 0.508)
		(drill 0.254)
		(layers "F.Cu" "B.Cu")
		(net "VR_FET_SW_P12V_STBY_PVDDQ_DEF")
	)
	(via
		(at 350.266 -142.621)
		(size 0.508)
		(drill 0.254)
		(layers "F.Cu" "B.Cu")
		(net "VR_FET_SW_P12V_STBY_PVDDQ_DEF")
	)
	(via
		(at 367.06683 -153.854658)
		(size 0.508)
		(drill 0.254)
		(layers "F.Cu" "B.Cu")
		(net "VR_FET_SW_P12V_STBY_PVDDQ_DEF")
	)
	(via
		(at 366.688116 -151.066246)
		(size 0.508)
		(drill 0.254)
		(layers "F.Cu" "B.Cu")
		(net "VR_FET_SW_P12V_STBY_PVDDQ_DEF")
	)
	(via
		(at 355.08692 -149.119844)
		(size 0.508)
		(drill 0.254)
		(layers "F.Cu" "B.Cu")
		(net "VR_FET_SW_P12V_STBY_PVDDQ_DEF")
	)
	(via
		(at 368.48288 -153.941018)
		(size 0.508)
		(drill 0.254)
		(layers "F.Cu" "B.Cu")
		(net "VR_FET_SW_P12V_STBY_PVDDQ_DEF")
	)
	(via
		(at 386.9563 -155.6766)
		(size 0.508)
		(drill 0.254)
		(layers "F.Cu" "B.Cu")
		(net "VR_FET_SW_P12V_STBY_PVDDQ_DEF")
	)
	(via
		(at 378.844048 -155.379928)
		(size 0.508)
		(drill 0.254)
		(layers "F.Cu" "B.Cu")
		(net "VR_FET_SW_P12V_STBY_PVDDQ_DEF")
	)
	(via
		(at 355.84892 -149.754844)
		(size 0.508)
		(drill 0.254)
		(layers "F.Cu" "B.Cu")
		(net "VR_FET_SW_P12V_STBY_PVDDQ_DEF")
	)
	(via
		(at 380.4412 -154.94)
		(size 0.508)
		(drill 0.254)
		(layers "F.Cu" "B.Cu")
		(net "VR_FET_SW_P12V_STBY_PVDDQ_DEF")
	)
	(via
		(at 358.818942 -148.928328)
		(size 0.508)
		(drill 0.254)
		(layers "F.Cu" "B.Cu")
		(net "VR_FET_SW_P12V_STBY_PVDDQ_DEF")
	)
	(via
		(at 388.543038 -155.799536)
		(size 0.508)
		(drill 0.254)
		(layers "F.Cu" "B.Cu")
		(net "VR_FET_SW_P12V_STBY_PVDDQ_DEF")
	)
	(via
		(at 358.3813 -149.77618)
		(size 0.508)
		(drill 0.254)
		(layers "F.Cu" "B.Cu")
		(net "VR_FET_SW_P12V_STBY_PVDDQ_DEF")
	)
	(via
		(at 360.15168 -148.9075)
		(size 0.508)
		(drill 0.254)
		(layers "F.Cu" "B.Cu")
		(net "VR_FET_SW_P12V_STBY_PVDDQ_DEF")
	)
	(via
		(at 351.0788 -142.9258)
		(size 0.508)
		(drill 0.254)
		(layers "F.Cu" "B.Cu")
		(net "VR_FET_SW_P12V_STBY_PVDDQ_DEF")
	)
	(via
		(at 379.5014 -155.77312)
		(size 0.508)
		(drill 0.254)
		(layers "F.Cu" "B.Cu")
		(net "VR_FET_SW_P12V_STBY_PVDDQ_DEF")
	)
	(via
		(at 369.8494 -153.9748)
		(size 0.508)
		(drill 0.254)
		(layers "F.Cu" "B.Cu")
		(net "VR_FET_SW_P12V_STBY_PVDDQ_DEF")
	)
	(via
		(at 349.504 -143.6878)
		(size 0.508)
		(drill 0.254)
		(layers "F.Cu" "B.Cu")
		(net "VR_FET_SW_P12V_STBY_PVDDQ_DEF")
	)
	(via
		(at 380.262638 -155.712922)
		(size 0.508)
		(drill 0.254)
		(layers "F.Cu" "B.Cu")
		(net "VR_FET_SW_P12V_STBY_PVDDQ_DEF")
	)
	(via
		(at 386.0419 -155.702)
		(size 0.508)
		(drill 0.254)
		(layers "F.Cu" "B.Cu")
		(net "VR_FET_SW_P12V_STBY_PVDDQ_DEF")
	)
	(via
		(at 366.40135 -151.708866)
		(size 0.508)
		(drill 0.254)
		(layers "F.Cu" "B.Cu")
		(net "VR_FET_SW_P12V_STBY_PVDDQ_DEF")
	)
	(via
		(at 367.810034 -153.919174)
		(size 0.508)
		(drill 0.254)
		(layers "F.Cu" "B.Cu")
		(net "VR_FET_SW_P12V_STBY_PVDDQ_DEF")
	)
	(via
		(at 359.453942 -148.928328)
		(size 0.508)
		(drill 0.254)
		(layers "F.Cu" "B.Cu")
		(net "VR_FET_SW_P12V_STBY_PVDDQ_DEF")
	)
	(via
		(at 349.494094 -142.817342)
		(size 0.508)
		(drill 0.254)
		(layers "F.Cu" "B.Cu")
		(net "VR_FET_SW_P12V_STBY_PVDDQ_DEF")
	)
	(via
		(at 355.09454 -149.87016)
		(size 0.508)
		(drill 0.254)
		(layers "F.Cu" "B.Cu")
		(net "VR_FET_SW_P12V_STBY_PVDDQ_DEF")
	)
	(via
		(at 354.34524 -150.02002)
		(size 0.508)
		(drill 0.254)
		(layers "F.Cu" "B.Cu")
		(net "VR_FET_SW_P12V_STBY_PVDDQ_DEF")
	)
	(via
		(at 366.642142 -152.385776)
		(size 0.508)
		(drill 0.254)
		(layers "F.Cu" "B.Cu")
		(net "VR_FET_SW_P12V_STBY_PVDDQ_DEF")
	)
	(via
		(at 379.1585 -156.439362)
		(size 0.508)
		(drill 0.254)
		(layers "F.Cu" "B.Cu")
		(net "VR_FET_SW_P12V_STBY_PVDDQ_DEF")
	)
	(via
		(at 349.4024 -149.7838)
		(size 0.508)
		(drill 0.254)
		(layers "F.Cu" "B.Cu")
		(net "VR_FET_SW_P12V_STBY_PVDDQ_DEF")
	)
	(via
		(at 360.78668 -148.9075)
		(size 0.508)
		(drill 0.254)
		(layers "F.Cu" "B.Cu")
		(net "VR_FET_SW_P12V_STBY_PVDDQ_DEF")
	)
	(via
		(at 389.16864 -155.805632)
		(size 0.508)
		(drill 0.254)
		(layers "F.Cu" "B.Cu")
		(net "VR_FET_SW_P12V_STBY_PVDDQ_DEF")
	)
	(via
		(at 370.8908 -153.9748)
		(size 0.508)
		(drill 0.254)
		(layers "F.Cu" "B.Cu")
		(net "VR_FET_SW_P12V_STBY_PVDDQ_DEF")
	)
	(via
		(at 349.52178 -142.17904)
		(size 0.508)
		(drill 0.254)
		(layers "F.Cu" "B.Cu")
		(net "VR_FET_SW_P12V_STBY_PVDDQ_DEF")
	)
	(via
		(at 362.585 -147.5994)
		(size 0.508)
		(drill 0.254)
		(layers "F.Cu" "B.Cu")
		(net "VR_FET_SW_P12V_STBY_PVDDQ_DEF")
	)
	(via
		(at 361.42168 -148.9075)
		(size 0.508)
		(drill 0.254)
		(layers "F.Cu" "B.Cu")
		(net "VR_FET_SW_P12V_STBY_PVDDQ_DEF")
	)
	(via
		(at 351.036128 -142.276322)
		(size 0.508)
		(drill 0.254)
		(layers "F.Cu" "B.Cu")
		(net "VR_FET_SW_P12V_STBY_PVDDQ_DEF")
	)
	(via
		(at 351.028 -149.733)
		(size 0.508)
		(drill 0.254)
		(layers "F.Cu" "B.Cu")
		(net "VR_FET_SW_P12V_STBY_PVDDQ_DEF")
	)
	(via
		(at 355.84892 -149.119844)
		(size 0.508)
		(drill 0.254)
		(layers "F.Cu" "B.Cu")
		(net "VR_FET_SW_P12V_STBY_PVDDQ_DEF")
	)
	(via
		(at 351.0534 -150.5712)
		(size 0.508)
		(drill 0.254)
		(layers "F.Cu" "B.Cu")
		(net "VR_FET_SW_P12V_STBY_PVDDQ_DEF")
	)
	(via
		(at 388.383018 -156.409136)
		(size 0.508)
		(drill 0.254)
		(layers "F.Cu" "B.Cu")
		(net "VR_FET_SW_P12V_STBY_PVDDQ_DEF")
	)
	(via
		(at 349.468694 -151.656542)
		(size 0.508)
		(drill 0.254)
		(layers "F.Cu" "B.Cu")
		(net "VR_FET_SW_P12V_STBY_PVDDQ_DEF")
	)
	(via
		(at 363.36478 -147.54606)
		(size 0.508)
		(drill 0.254)
		(layers "F.Cu" "B.Cu")
		(net "VR_FET_SW_P12V_STBY_PVDDQ_DEF")
	)
	(via
		(at 369.894358 -153.277316)
		(size 0.508)
		(drill 0.254)
		(layers "F.Cu" "B.Cu")
		(net "VR_FET_SW_P12V_STBY_PVDDQ_DEF")
	)
	(via
		(at 363.87786 -148.4757)
		(size 0.508)
		(drill 0.254)
		(layers "F.Cu" "B.Cu")
		(net "VR_FET_SW_P12V_STBY_PVDDQ_DEF")
	)
	(via
		(at 369.176554 -153.952956)
		(size 0.508)
		(drill 0.254)
		(layers "F.Cu" "B.Cu")
		(net "VR_FET_SW_P12V_STBY_PVDDQ_DEF")
	)
	(via
		(at 354.9396 -20.0152)
		(size 0.508)
		(drill 0.254)
		(layers "F.Cu" "B.Cu")
		(net "VR_FET_SW_P12V_STBY_PVDDQ_ABC")
	)
	(via
		(at 354.9777 -17.286986)
		(size 0.508)
		(drill 0.254)
		(layers "F.Cu" "B.Cu")
		(net "VR_FET_SW_P12V_STBY_PVDDQ_ABC")
	)
	(via
		(at 353.716336 -20.014692)
		(size 0.508)
		(drill 0.254)
		(layers "F.Cu" "B.Cu")
		(net "VR_FET_SW_P12V_STBY_PVDDQ_ABC")
	)
	(via
		(at 349.105474 -3.85318)
		(size 0.508)
		(drill 0.254)
		(layers "F.Cu" "B.Cu")
		(net "VR_FET_SW_P12V_STBY_PVDDQ_ABC")
	)
	(via
		(at 354.9396 -19.3548)
		(size 0.508)
		(drill 0.254)
		(layers "F.Cu" "B.Cu")
		(net "VR_FET_SW_P12V_STBY_PVDDQ_ABC")
	)
	(via
		(at 348.4753 -5.1308)
		(size 0.508)
		(drill 0.254)
		(layers "F.Cu" "B.Cu")
		(net "VR_FET_SW_P12V_STBY_PVDDQ_ABC")
	)
	(via
		(at 354.2157 -14.111986)
		(size 0.508)
		(drill 0.254)
		(layers "F.Cu" "B.Cu")
		(net "VR_FET_SW_P12V_STBY_PVDDQ_ABC")
	)
	(via
		(at 353.5807 -14.873986)
		(size 0.508)
		(drill 0.254)
		(layers "F.Cu" "B.Cu")
		(net "VR_FET_SW_P12V_STBY_PVDDQ_ABC")
	)
	(via
		(at 348.4626 -3.9116)
		(size 0.508)
		(drill 0.254)
		(layers "F.Cu" "B.Cu")
		(net "VR_FET_SW_P12V_STBY_PVDDQ_ABC")
	)
	(via
		(at 354.974906 -16.534892)
		(size 0.508)
		(drill 0.254)
		(layers "F.Cu" "B.Cu")
		(net "VR_FET_SW_P12V_STBY_PVDDQ_ABC")
	)
	(via
		(at 354.33 -20.0152)
		(size 0.508)
		(drill 0.254)
		(layers "F.Cu" "B.Cu")
		(net "VR_FET_SW_P12V_STBY_PVDDQ_ABC")
	)
	(via
		(at 349.686626 4.267708)
		(size 0.508)
		(drill 0.254)
		(layers "F.Cu" "B.Cu")
		(net "VR_FET_SW_P12V_STBY_PVDDQ_ABC")
	)
	(via
		(at 348.38767 3.573526)
		(size 0.508)
		(drill 0.254)
		(layers "F.Cu" "B.Cu")
		(net "VR_FET_SW_P12V_STBY_PVDDQ_ABC")
	)
	(via
		(at 348.399862 4.230116)
		(size 0.508)
		(drill 0.254)
		(layers "F.Cu" "B.Cu")
		(net "VR_FET_SW_P12V_STBY_PVDDQ_ABC")
	)
	(via
		(at 354.3427 -17.286986)
		(size 0.508)
		(drill 0.254)
		(layers "F.Cu" "B.Cu")
		(net "VR_FET_SW_P12V_STBY_PVDDQ_ABC")
	)
	(via
		(at 354.8507 -14.111986)
		(size 0.508)
		(drill 0.254)
		(layers "F.Cu" "B.Cu")
		(net "VR_FET_SW_P12V_STBY_PVDDQ_ABC")
	)
	(via
		(at 348.385892 2.954782)
		(size 0.508)
		(drill 0.254)
		(layers "F.Cu" "B.Cu")
		(net "VR_FET_SW_P12V_STBY_PVDDQ_ABC")
	)
	(via
		(at 353.716336 -19.3548)
		(size 0.508)
		(drill 0.254)
		(layers "F.Cu" "B.Cu")
		(net "VR_FET_SW_P12V_STBY_PVDDQ_ABC")
	)
	(via
		(at 354.33 -19.3548)
		(size 0.508)
		(drill 0.254)
		(layers "F.Cu" "B.Cu")
		(net "VR_FET_SW_P12V_STBY_PVDDQ_ABC")
	)
	(via
		(at 349.717868 -3.85699)
		(size 0.508)
		(drill 0.254)
		(layers "F.Cu" "B.Cu")
		(net "VR_FET_SW_P12V_STBY_PVDDQ_ABC")
	)
	(via
		(at 354.2157 -14.873986)
		(size 0.508)
		(drill 0.254)
		(layers "F.Cu" "B.Cu")
		(net "VR_FET_SW_P12V_STBY_PVDDQ_ABC")
	)
	(via
		(at 349.0214 4.2926)
		(size 0.508)
		(drill 0.254)
		(layers "F.Cu" "B.Cu")
		(net "VR_FET_SW_P12V_STBY_PVDDQ_ABC")
	)
	(via
		(at 353.605846 -17.273524)
		(size 0.508)
		(drill 0.254)
		(layers "F.Cu" "B.Cu")
		(net "VR_FET_SW_P12V_STBY_PVDDQ_ABC")
	)
	(via
		(at 348.4626 -4.5212)
		(size 0.508)
		(drill 0.254)
		(layers "F.Cu" "B.Cu")
		(net "VR_FET_SW_P12V_STBY_PVDDQ_ABC")
	)
	(via
		(at 348.394528 2.334514)
		(size 0.508)
		(drill 0.254)
		(layers "F.Cu" "B.Cu")
		(net "VR_FET_SW_P12V_STBY_PVDDQ_ABC")
	)
	(via
		(at 353.5807 -14.111986)
		(size 0.508)
		(drill 0.254)
		(layers "F.Cu" "B.Cu")
		(net "VR_FET_SW_P12V_STBY_PVDDQ_ABC")
	)
	(via
		(at 354.314506 -16.534892)
		(size 0.508)
		(drill 0.254)
		(layers "F.Cu" "B.Cu")
		(net "VR_FET_SW_P12V_STBY_PVDDQ_ABC")
	)
	(via
		(at 348.473014 -5.744718)
		(size 0.508)
		(drill 0.254)
		(layers "F.Cu" "B.Cu")
		(net "VR_FET_SW_P12V_STBY_PVDDQ_ABC")
	)
	(via
		(at 354.8507 -14.873986)
		(size 0.508)
		(drill 0.254)
		(layers "F.Cu" "B.Cu")
		(net "VR_FET_SW_P12V_STBY_PVDDQ_ABC")
	)
	(via
		(at 353.654106 -16.534892)
		(size 0.508)
		(drill 0.254)
		(layers "F.Cu" "B.Cu")
		(net "VR_FET_SW_P12V_STBY_PVDDQ_ABC")
	)
	(segment
		(start 182.3466 -79.4258)
		(end 182.3466 -80.238346)
		(width 0.508)
		(layer "F.Cu")
		(net "VR_FET_SW_P12V_STBY_PVCCIN_CPU0")
	)
	(segment
		(start 198.37908 -99.977702)
		(end 197.629526 -99.228148)
		(width 0.508)
		(layer "F.Cu")
		(net "VR_FET_SW_P12V_STBY_PVCCIN_CPU0")
	)
	(segment
		(start 175.225202 -66.191638)
		(end 175.24984 -66.167)
		(width 0.508)
		(layer "F.Cu")
		(net "VR_FET_SW_P12V_STBY_PVCCIN_CPU0")
	)
	(segment
		(start 198.37908 -101.221286)
		(end 198.37908 -99.977702)
		(width 0.508)
		(layer "F.Cu")
		(net "VR_FET_SW_P12V_STBY_PVCCIN_CPU0")
	)
	(segment
		(start 187.413646 -83.781646)
		(end 188.853064 -85.221064)
		(width 0.508)
		(layer "F.Cu")
		(net "VR_FET_SW_P12V_STBY_PVCCIN_CPU0")
	)
	(segment
		(start 185.8899 -83.781646)
		(end 187.413646 -83.781646)
		(width 0.508)
		(layer "F.Cu")
		(net "VR_FET_SW_P12V_STBY_PVCCIN_CPU0")
	)
	(segment
		(start 174.6377 -66.191638)
		(end 175.225202 -66.191638)
		(width 0.508)
		(layer "F.Cu")
		(net "VR_FET_SW_P12V_STBY_PVCCIN_CPU0")
	)
	(segment
		(start 188.853064 -85.221064)
		(end 189.153292 -85.221064)
		(width 0.508)
		(layer "F.Cu")
		(net "VR_FET_SW_P12V_STBY_PVCCIN_CPU0")
	)
	(segment
		(start 198.370444 -101.229922)
		(end 198.370444 -102.053136)
		(width 0.508)
		(layer "F.Cu")
		(net "VR_FET_SW_P12V_STBY_PVCCIN_CPU0")
	)
	(segment
		(start 198.37908 -101.221286)
		(end 198.370444 -101.229922)
		(width 0.508)
		(layer "F.Cu")
		(net "VR_FET_SW_P12V_STBY_PVCCIN_CPU0")
	)
	(segment
		(start 182.3466 -80.238346)
		(end 185.8899 -83.781646)
		(width 0.508)
		(layer "F.Cu")
		(net "VR_FET_SW_P12V_STBY_PVCCIN_CPU0")
	)
	(via
		(at 195.43776 -92.40774)
		(size 0.5588)
		(drill 0.3048)
		(layers "F.Cu" "B.Cu")
		(net "VR_FET_SW_P12V_STBY_PVCCIN_CPU0")
	)
	(via
		(at 196.880734 -100.156264)
		(size 0.508)
		(drill 0.254)
		(layers "F.Cu" "B.Cu")
		(net "VR_FET_SW_P12V_STBY_PVCCIN_CPU0")
	)
	(via
		(at 195.52158 -100.60178)
		(size 0.5588)
		(drill 0.3048)
		(layers "F.Cu" "B.Cu")
		(net "VR_FET_SW_P12V_STBY_PVCCIN_CPU0")
	)
	(via
		(at 180.1368 -51.1302)
		(size 0.508)
		(drill 0.254)
		(layers "F.Cu" "B.Cu")
		(net "VR_FET_SW_P12V_STBY_PVCCIN_CPU0")
	)
	(via
		(at 190.575692 -85.221064)
		(size 0.5588)
		(drill 0.3048)
		(layers "F.Cu" "B.Cu")
		(net "VR_FET_SW_P12V_STBY_PVCCIN_CPU0")
	)
	(via
		(at 191.516 -94.996)
		(size 0.5588)
		(drill 0.3048)
		(layers "F.Cu" "B.Cu")
		(net "VR_FET_SW_P12V_STBY_PVCCIN_CPU0")
	)
	(via
		(at 188.070998 -56.480456)
		(size 0.508)
		(drill 0.254)
		(layers "F.Cu" "B.Cu")
		(net "VR_FET_SW_P12V_STBY_PVCCIN_CPU0")
	)
	(via
		(at 189.883542 -93.194886)
		(size 0.5588)
		(drill 0.3048)
		(layers "F.Cu" "B.Cu")
		(net "VR_FET_SW_P12V_STBY_PVCCIN_CPU0")
	)
	(via
		(at 179.451 -52.7812)
		(size 0.508)
		(drill 0.254)
		(layers "F.Cu" "B.Cu")
		(net "VR_FET_SW_P12V_STBY_PVCCIN_CPU0")
	)
	(via
		(at 189.864492 -87.587582)
		(size 0.5588)
		(drill 0.3048)
		(layers "F.Cu" "B.Cu")
		(net "VR_FET_SW_P12V_STBY_PVCCIN_CPU0")
	)
	(via
		(at 195.8086 -76.6572)
		(size 0.5588)
		(drill 0.3048)
		(layers "F.Cu" "B.Cu")
		(net "VR_FET_SW_P12V_STBY_PVCCIN_CPU0")
	)
	(via
		(at 188.705998 -56.178196)
		(size 0.508)
		(drill 0.254)
		(layers "F.Cu" "B.Cu")
		(net "VR_FET_SW_P12V_STBY_PVCCIN_CPU0")
	)
	(via
		(at 195.487798 -67.728338)
		(size 0.5588)
		(drill 0.3048)
		(layers "F.Cu" "B.Cu")
		(net "VR_FET_SW_P12V_STBY_PVCCIN_CPU0")
	)
	(via
		(at 196.906134 -99.241864)
		(size 0.508)
		(drill 0.254)
		(layers "F.Cu" "B.Cu")
		(net "VR_FET_SW_P12V_STBY_PVCCIN_CPU0")
	)
	(via
		(at 187.410598 -57.140856)
		(size 0.508)
		(drill 0.254)
		(layers "F.Cu" "B.Cu")
		(net "VR_FET_SW_P12V_STBY_PVCCIN_CPU0")
	)
	(via
		(at 190.543942 -93.194886)
		(size 0.5588)
		(drill 0.3048)
		(layers "F.Cu" "B.Cu")
		(net "VR_FET_SW_P12V_STBY_PVCCIN_CPU0")
	)
	(via
		(at 197.035928 -84.579206)
		(size 0.5588)
		(drill 0.3048)
		(layers "F.Cu" "B.Cu")
		(net "VR_FET_SW_P12V_STBY_PVCCIN_CPU0")
	)
	(via
		(at 180.7972 -51.5874)
		(size 0.508)
		(drill 0.254)
		(layers "F.Cu" "B.Cu")
		(net "VR_FET_SW_P12V_STBY_PVCCIN_CPU0")
	)
	(via
		(at 196.5452 -60.3758)
		(size 0.5588)
		(drill 0.3048)
		(layers "F.Cu" "B.Cu")
		(net "VR_FET_SW_P12V_STBY_PVCCIN_CPU0")
	)
	(via
		(at 180.5686 -58.84164)
		(size 0.508)
		(drill 0.254)
		(layers "F.Cu" "B.Cu")
		(net "VR_FET_SW_P12V_STBY_PVCCIN_CPU0")
	)
	(via
		(at 190.575692 -87.587582)
		(size 0.5588)
		(drill 0.3048)
		(layers "F.Cu" "B.Cu")
		(net "VR_FET_SW_P12V_STBY_PVCCIN_CPU0")
	)
	(via
		(at 196.893434 -59.516264)
		(size 0.508)
		(drill 0.254)
		(layers "F.Cu" "B.Cu")
		(net "VR_FET_SW_P12V_STBY_PVCCIN_CPU0")
	)
	(via
		(at 189.153292 -85.932264)
		(size 0.5588)
		(drill 0.3048)
		(layers "F.Cu" "B.Cu")
		(net "VR_FET_SW_P12V_STBY_PVCCIN_CPU0")
	)
	(via
		(at 196.893434 -65.815464)
		(size 0.508)
		(drill 0.254)
		(layers "F.Cu" "B.Cu")
		(net "VR_FET_SW_P12V_STBY_PVCCIN_CPU0")
	)
	(via
		(at 196.893434 -90.199464)
		(size 0.508)
		(drill 0.254)
		(layers "F.Cu" "B.Cu")
		(net "VR_FET_SW_P12V_STBY_PVCCIN_CPU0")
	)
	(via
		(at 196.918834 -82.985864)
		(size 0.508)
		(drill 0.254)
		(layers "F.Cu" "B.Cu")
		(net "VR_FET_SW_P12V_STBY_PVCCIN_CPU0")
	)
	(via
		(at 196.1896 -76.0476)
		(size 0.5588)
		(drill 0.3048)
		(layers "F.Cu" "B.Cu")
		(net "VR_FET_SW_P12V_STBY_PVCCIN_CPU0")
	)
	(via
		(at 195.740528 -59.647582)
		(size 0.5588)
		(drill 0.3048)
		(layers "F.Cu" "B.Cu")
		(net "VR_FET_SW_P12V_STBY_PVCCIN_CPU0")
	)
	(via
		(at 195.70319 -68.450206)
		(size 0.5588)
		(drill 0.3048)
		(layers "F.Cu" "B.Cu")
		(net "VR_FET_SW_P12V_STBY_PVCCIN_CPU0")
	)
	(via
		(at 196.01942 -83.98891)
		(size 0.5588)
		(drill 0.3048)
		(layers "F.Cu" "B.Cu")
		(net "VR_FET_SW_P12V_STBY_PVCCIN_CPU0")
	)
	(via
		(at 195.14566 -76.65212)
		(size 0.5588)
		(drill 0.3048)
		(layers "F.Cu" "B.Cu")
		(net "VR_FET_SW_P12V_STBY_PVCCIN_CPU0")
	)
	(via
		(at 188.849 -94.996)
		(size 0.5588)
		(drill 0.3048)
		(layers "F.Cu" "B.Cu")
		(net "VR_FET_SW_P12V_STBY_PVCCIN_CPU0")
	)
	(via
		(at 196.16166 -92.71508)
		(size 0.5588)
		(drill 0.3048)
		(layers "F.Cu" "B.Cu")
		(net "VR_FET_SW_P12V_STBY_PVCCIN_CPU0")
	)
	(via
		(at 196.86778 -92.72778)
		(size 0.5588)
		(drill 0.3048)
		(layers "F.Cu" "B.Cu")
		(net "VR_FET_SW_P12V_STBY_PVCCIN_CPU0")
	)
	(via
		(at 190.627 -96.52)
		(size 0.5588)
		(drill 0.3048)
		(layers "F.Cu" "B.Cu")
		(net "VR_FET_SW_P12V_STBY_PVCCIN_CPU0")
	)
	(via
		(at 179.4764 -51.1302)
		(size 0.508)
		(drill 0.254)
		(layers "F.Cu" "B.Cu")
		(net "VR_FET_SW_P12V_STBY_PVCCIN_CPU0")
	)
	(via
		(at 196.24802 -67.76974)
		(size 0.5588)
		(drill 0.3048)
		(layers "F.Cu" "B.Cu")
		(net "VR_FET_SW_P12V_STBY_PVCCIN_CPU0")
	)
	(via
		(at 188.705998 -56.838596)
		(size 0.508)
		(drill 0.254)
		(layers "F.Cu" "B.Cu")
		(net "VR_FET_SW_P12V_STBY_PVCCIN_CPU0")
	)
	(via
		(at 191.516 -98.044)
		(size 0.5588)
		(drill 0.3048)
		(layers "F.Cu" "B.Cu")
		(net "VR_FET_SW_P12V_STBY_PVCCIN_CPU0")
	)
	(via
		(at 188.849 -98.044)
		(size 0.5588)
		(drill 0.3048)
		(layers "F.Cu" "B.Cu")
		(net "VR_FET_SW_P12V_STBY_PVCCIN_CPU0")
	)
	(via
		(at 189.153292 -87.587582)
		(size 0.5588)
		(drill 0.3048)
		(layers "F.Cu" "B.Cu")
		(net "VR_FET_SW_P12V_STBY_PVCCIN_CPU0")
	)
	(via
		(at 190.575692 -88.349582)
		(size 0.5588)
		(drill 0.3048)
		(layers "F.Cu" "B.Cu")
		(net "VR_FET_SW_P12V_STBY_PVCCIN_CPU0")
	)
	(via
		(at 196.893434 -73.943464)
		(size 0.508)
		(drill 0.254)
		(layers "F.Cu" "B.Cu")
		(net "VR_FET_SW_P12V_STBY_PVCCIN_CPU0")
	)
	(via
		(at 196.893434 -75.772264)
		(size 0.508)
		(drill 0.254)
		(layers "F.Cu" "B.Cu")
		(net "VR_FET_SW_P12V_STBY_PVCCIN_CPU0")
	)
	(via
		(at 190.627 -98.044)
		(size 0.5588)
		(drill 0.3048)
		(layers "F.Cu" "B.Cu")
		(net "VR_FET_SW_P12V_STBY_PVCCIN_CPU0")
	)
	(via
		(at 188.849 -96.52)
		(size 0.5588)
		(drill 0.3048)
		(layers "F.Cu" "B.Cu")
		(net "VR_FET_SW_P12V_STBY_PVCCIN_CPU0")
	)
	(via
		(at 196.918834 -66.729864)
		(size 0.508)
		(drill 0.254)
		(layers "F.Cu" "B.Cu")
		(net "VR_FET_SW_P12V_STBY_PVCCIN_CPU0")
	)
	(via
		(at 189.908942 -92.458286)
		(size 0.5588)
		(drill 0.3048)
		(layers "F.Cu" "B.Cu")
		(net "VR_FET_SW_P12V_STBY_PVCCIN_CPU0")
	)
	(via
		(at 189.248542 -92.458286)
		(size 0.5588)
		(drill 0.3048)
		(layers "F.Cu" "B.Cu")
		(net "VR_FET_SW_P12V_STBY_PVCCIN_CPU0")
	)
	(via
		(at 189.864492 -85.932264)
		(size 0.5588)
		(drill 0.3048)
		(layers "F.Cu" "B.Cu")
		(net "VR_FET_SW_P12V_STBY_PVCCIN_CPU0")
	)
	(via
		(at 196.329046 -84.584286)
		(size 0.5588)
		(drill 0.3048)
		(layers "F.Cu" "B.Cu")
		(net "VR_FET_SW_P12V_STBY_PVCCIN_CPU0")
	)
	(via
		(at 177.8 -59.3598)
		(size 0.508)
		(drill 0.254)
		(layers "F.Cu" "B.Cu")
		(net "VR_FET_SW_P12V_STBY_PVCCIN_CPU0")
	)
	(via
		(at 190.278004 -56.094122)
		(size 0.508)
		(drill 0.254)
		(layers "F.Cu" "B.Cu")
		(net "VR_FET_SW_P12V_STBY_PVCCIN_CPU0")
	)
	(via
		(at 180.132228 -51.802792)
		(size 0.508)
		(drill 0.254)
		(layers "F.Cu" "B.Cu")
		(net "VR_FET_SW_P12V_STBY_PVCCIN_CPU0")
	)
	(via
		(at 196.276468 -100.891086)
		(size 0.5588)
		(drill 0.3048)
		(layers "F.Cu" "B.Cu")
		(net "VR_FET_SW_P12V_STBY_PVCCIN_CPU0")
	)
	(via
		(at 195.43776 -75.87869)
		(size 0.5588)
		(drill 0.3048)
		(layers "F.Cu" "B.Cu")
		(net "VR_FET_SW_P12V_STBY_PVCCIN_CPU0")
	)
	(via
		(at 196.918834 -91.113864)
		(size 0.508)
		(drill 0.254)
		(layers "F.Cu" "B.Cu")
		(net "VR_FET_SW_P12V_STBY_PVCCIN_CPU0")
	)
	(via
		(at 196.893434 -67.644264)
		(size 0.508)
		(drill 0.254)
		(layers "F.Cu" "B.Cu")
		(net "VR_FET_SW_P12V_STBY_PVCCIN_CPU0")
	)
	(via
		(at 189.738 -96.52)
		(size 0.5588)
		(drill 0.3048)
		(layers "F.Cu" "B.Cu")
		(net "VR_FET_SW_P12V_STBY_PVCCIN_CPU0")
	)
	(via
		(at 196.893434 -57.687464)
		(size 0.508)
		(drill 0.254)
		(layers "F.Cu" "B.Cu")
		(net "VR_FET_SW_P12V_STBY_PVCCIN_CPU0")
	)
	(via
		(at 188.070998 -57.140856)
		(size 0.508)
		(drill 0.254)
		(layers "F.Cu" "B.Cu")
		(net "VR_FET_SW_P12V_STBY_PVCCIN_CPU0")
	)
	(via
		(at 190.569342 -92.458286)
		(size 0.5588)
		(drill 0.3048)
		(layers "F.Cu" "B.Cu")
		(net "VR_FET_SW_P12V_STBY_PVCCIN_CPU0")
	)
	(via
		(at 196.880734 -98.327464)
		(size 0.508)
		(drill 0.254)
		(layers "F.Cu" "B.Cu")
		(net "VR_FET_SW_P12V_STBY_PVCCIN_CPU0")
	)
	(via
		(at 188.0362 -57.9374)
		(size 0.508)
		(drill 0.254)
		(layers "F.Cu" "B.Cu")
		(net "VR_FET_SW_P12V_STBY_PVCCIN_CPU0")
	)
	(via
		(at 189.153292 -85.221064)
		(size 0.5588)
		(drill 0.3048)
		(layers "F.Cu" "B.Cu")
		(net "VR_FET_SW_P12V_STBY_PVCCIN_CPU0")
	)
	(via
		(at 196.9008 -76.5048)
		(size 0.5588)
		(drill 0.3048)
		(layers "F.Cu" "B.Cu")
		(net "VR_FET_SW_P12V_STBY_PVCCIN_CPU0")
	)
	(via
		(at 189.153292 -88.349582)
		(size 0.5588)
		(drill 0.3048)
		(layers "F.Cu" "B.Cu")
		(net "VR_FET_SW_P12V_STBY_PVCCIN_CPU0")
	)
	(via
		(at 196.95668 -100.86594)
		(size 0.5588)
		(drill 0.3048)
		(layers "F.Cu" "B.Cu")
		(net "VR_FET_SW_P12V_STBY_PVCCIN_CPU0")
	)
	(via
		(at 188.695838 -57.600342)
		(size 0.508)
		(drill 0.254)
		(layers "F.Cu" "B.Cu")
		(net "VR_FET_SW_P12V_STBY_PVCCIN_CPU0")
	)
	(via
		(at 189.864492 -88.349582)
		(size 0.5588)
		(drill 0.3048)
		(layers "F.Cu" "B.Cu")
		(net "VR_FET_SW_P12V_STBY_PVCCIN_CPU0")
	)
	(via
		(at 196.9008 -58.547)
		(size 0.508)
		(drill 0.254)
		(layers "F.Cu" "B.Cu")
		(net "VR_FET_SW_P12V_STBY_PVCCIN_CPU0")
	)
	(via
		(at 189.738 -94.996)
		(size 0.5588)
		(drill 0.3048)
		(layers "F.Cu" "B.Cu")
		(net "VR_FET_SW_P12V_STBY_PVCCIN_CPU0")
	)
	(via
		(at 195.650612 -84.651088)
		(size 0.5588)
		(drill 0.3048)
		(layers "F.Cu" "B.Cu")
		(net "VR_FET_SW_P12V_STBY_PVCCIN_CPU0")
	)
	(via
		(at 191.483996 -96.485202)
		(size 0.5588)
		(drill 0.3048)
		(layers "F.Cu" "B.Cu")
		(net "VR_FET_SW_P12V_STBY_PVCCIN_CPU0")
	)
	(via
		(at 187.410598 -56.480456)
		(size 0.508)
		(drill 0.254)
		(layers "F.Cu" "B.Cu")
		(net "VR_FET_SW_P12V_STBY_PVCCIN_CPU0")
	)
	(via
		(at 195.42252 -93.07576)
		(size 0.5588)
		(drill 0.3048)
		(layers "F.Cu" "B.Cu")
		(net "VR_FET_SW_P12V_STBY_PVCCIN_CPU0")
	)
	(via
		(at 196.918834 -74.857864)
		(size 0.508)
		(drill 0.254)
		(layers "F.Cu" "B.Cu")
		(net "VR_FET_SW_P12V_STBY_PVCCIN_CPU0")
	)
	(via
		(at 189.864492 -85.221064)
		(size 0.5588)
		(drill 0.3048)
		(layers "F.Cu" "B.Cu")
		(net "VR_FET_SW_P12V_STBY_PVCCIN_CPU0")
	)
	(via
		(at 190.627 -94.996)
		(size 0.5588)
		(drill 0.3048)
		(layers "F.Cu" "B.Cu")
		(net "VR_FET_SW_P12V_STBY_PVCCIN_CPU0")
	)
	(via
		(at 195.82511 -60.329826)
		(size 0.5588)
		(drill 0.3048)
		(layers "F.Cu" "B.Cu")
		(net "VR_FET_SW_P12V_STBY_PVCCIN_CPU0")
	)
	(via
		(at 195.169028 -60.416694)
		(size 0.5588)
		(drill 0.3048)
		(layers "F.Cu" "B.Cu")
		(net "VR_FET_SW_P12V_STBY_PVCCIN_CPU0")
	)
	(via
		(at 175.24984 -66.167)
		(size 0.508)
		(drill 0.254)
		(layers "F.Cu" "B.Cu")
		(net "VR_FET_SW_P12V_STBY_PVCCIN_CPU0")
	)
	(via
		(at 196.893434 -82.071464)
		(size 0.508)
		(drill 0.254)
		(layers "F.Cu" "B.Cu")
		(net "VR_FET_SW_P12V_STBY_PVCCIN_CPU0")
	)
	(via
		(at 189.223142 -93.194886)
		(size 0.5588)
		(drill 0.3048)
		(layers "F.Cu" "B.Cu")
		(net "VR_FET_SW_P12V_STBY_PVCCIN_CPU0")
	)
	(via
		(at 196.893434 -83.900264)
		(size 0.508)
		(drill 0.254)
		(layers "F.Cu" "B.Cu")
		(net "VR_FET_SW_P12V_STBY_PVCCIN_CPU0")
	)
	(via
		(at 179.466494 -51.871118)
		(size 0.508)
		(drill 0.254)
		(layers "F.Cu" "B.Cu")
		(net "VR_FET_SW_P12V_STBY_PVCCIN_CPU0")
	)
	(via
		(at 190.575692 -85.932264)
		(size 0.5588)
		(drill 0.3048)
		(layers "F.Cu" "B.Cu")
		(net "VR_FET_SW_P12V_STBY_PVCCIN_CPU0")
	)
	(via
		(at 194.78244 -100.64496)
		(size 0.5588)
		(drill 0.3048)
		(layers "F.Cu" "B.Cu")
		(net "VR_FET_SW_P12V_STBY_PVCCIN_CPU0")
	)
	(via
		(at 196.893434 -92.028264)
		(size 0.508)
		(drill 0.254)
		(layers "F.Cu" "B.Cu")
		(net "VR_FET_SW_P12V_STBY_PVCCIN_CPU0")
	)
	(via
		(at 189.738 -98.044)
		(size 0.5588)
		(drill 0.3048)
		(layers "F.Cu" "B.Cu")
		(net "VR_FET_SW_P12V_STBY_PVCCIN_CPU0")
	)
	(via
		(at 179.466494 -53.699918)
		(size 0.508)
		(drill 0.254)
		(layers "F.Cu" "B.Cu")
		(net "VR_FET_SW_P12V_STBY_PVCCIN_CPU0")
	)
	(segment
		(start 176.87036 -60.41644)
		(end 176.87036 -63.70066)
		(width 0.508)
		(layer "In2.Cu")
		(net "VR_FET_SW_P12V_STBY_PVCCIN_CPU0")
	)
	(segment
		(start 177.5714 -59.5884)
		(end 177.5714 -59.7154)
		(width 0.508)
		(layer "In2.Cu")
		(net "VR_FET_SW_P12V_STBY_PVCCIN_CPU0")
	)
	(segment
		(start 177.8 -59.3598)
		(end 177.5714 -59.5884)
		(width 0.508)
		(layer "In2.Cu")
		(net "VR_FET_SW_P12V_STBY_PVCCIN_CPU0")
	)
	(segment
		(start 176.87036 -63.70066)
		(end 175.24984 -65.32118)
		(width 0.508)
		(layer "In2.Cu")
		(net "VR_FET_SW_P12V_STBY_PVCCIN_CPU0")
	)
	(segment
		(start 177.5714 -59.7154)
		(end 176.87036 -60.41644)
		(width 0.508)
		(layer "In2.Cu")
		(net "VR_FET_SW_P12V_STBY_PVCCIN_CPU0")
	)
	(segment
		(start 175.24984 -65.32118)
		(end 175.24984 -66.167)
		(width 0.508)
		(layer "In2.Cu")
		(net "VR_FET_SW_P12V_STBY_PVCCIN_CPU0")
	)
	(segment
		(start 380.032768 -33.7185)
		(end 381.055118 -33.7185)
		(width 0.1143)
		(layer "F.Cu")
		(net "P3E_PCH_TX_0_DP")
	)
	(segment
		(start 381.055118 -33.7185)
		(end 381.204724 -33.868106)
		(width 0.1143)
		(layer "F.Cu")
		(net "P3E_PCH_TX_0_DP")
	)
	(segment
		(start 398.13865 -121.87428)
		(end 398.63395 -122.104404)
		(width 0.1143)
		(layer "F.Cu")
		(net "P3E_PCH_TX_0_DP")
	)
	(via
		(at 381.204724 -33.868106)
		(size 0.508)
		(drill 0.254)
		(layers "F.Cu" "B.Cu")
		(net "P3E_PCH_TX_0_DP")
	)
	(via
		(at 398.63395 -122.104404)
		(size 0.508)
		(drill 0.254)
		(layers "F.Cu" "B.Cu")
		(net "P3E_PCH_TX_0_DP")
	)
	(segment
		(start 385.672584 -37.615368)
		(end 385.672584 -37.272468)
		(width 0.1143)
		(layer "In11.Cu")
		(net "P3E_PCH_TX_0_DP")
	)
	(segment
		(start 399.622772 -56.415178)
		(end 399.622772 -56.181752)
		(width 0.1143)
		(layer "In11.Cu")
		(net "P3E_PCH_TX_0_DP")
	)
	(segment
		(start 381.204724 -33.511744)
		(end 381.204724 -33.868106)
		(width 0.1143)
		(layer "In11.Cu")
		(net "P3E_PCH_TX_0_DP")
	)
	(segment
		(start 400.81708 -57.37606)
		(end 400.583654 -57.37606)
		(width 0.1143)
		(layer "In11.Cu")
		(net "P3E_PCH_TX_0_DP")
	)
	(segment
		(start 396.0622 -120.39854)
		(end 396.0622 -120.365774)
		(width 0.0889)
		(layer "In11.Cu")
		(net "P3E_PCH_TX_0_DP")
	)
	(segment
		(start 400.943826 -115.219988)
		(end 400.943826 -114.949986)
		(width 0.1143)
		(layer "In11.Cu")
		(net "P3E_PCH_TX_0_DP")
	)
	(segment
		(start 398.0434 -118.6815)
		(end 398.0434 -118.648734)
		(width 0.0889)
		(layer "In11.Cu")
		(net "P3E_PCH_TX_0_DP")
	)
	(segment
		(start 409.5115 -67.149726)
		(end 409.1686 -66.806826)
		(width 0.1143)
		(layer "In11.Cu")
		(net "P3E_PCH_TX_0_DP")
	)
	(segment
		(start 407.79065 -107.141264)
		(end 408.708098 -106.223816)
		(width 0.1143)
		(layer "In11.Cu")
		(net "P3E_PCH_TX_0_DP")
	)
	(segment
		(start 407.847292 -80.66532)
		(end 406.323546 -79.141574)
		(width 0.1143)
		(layer "In11.Cu")
		(net "P3E_PCH_TX_0_DP")
	)
	(segment
		(start 385.837684 -37.780468)
		(end 385.672584 -37.615368)
		(width 0.1143)
		(layer "In11.Cu")
		(net "P3E_PCH_TX_0_DP")
	)
	(segment
		(start 389.801862 -43.481752)
		(end 389.534654 -43.077892)
		(width 0.1143)
		(layer "In11.Cu")
		(net "P3E_PCH_TX_0_DP")
	)
	(segment
		(start 393.1793 -47.420022)
		(end 393.1793 -47.273972)
		(width 0.1143)
		(layer "In11.Cu")
		(net "P3E_PCH_TX_0_DP")
	)
	(segment
		(start 408.01544 -88.770206)
		(end 407.847292 -87.944706)
		(width 0.1143)
		(layer "In11.Cu")
		(net "P3E_PCH_TX_0_DP")
	)
	(segment
		(start 409.7147 -97.377504)
		(end 409.7147 -90.469466)
		(width 0.1143)
		(layer "In11.Cu")
		(net "P3E_PCH_TX_0_DP")
	)
	(segment
		(start 406.339548 -74.5236)
		(end 408.637486 -72.225916)
		(width 0.1143)
		(layer "In11.Cu")
		(net "P3E_PCH_TX_0_DP")
	)
	(segment
		(start 385.672584 -39.304468)
		(end 385.837684 -39.139368)
		(width 0.1143)
		(layer "In11.Cu")
		(net "P3E_PCH_TX_0_DP")
	)
	(segment
		(start 385.837684 -38.123368)
		(end 385.837684 -37.780468)
		(width 0.1143)
		(layer "In11.Cu")
		(net "P3E_PCH_TX_0_DP")
	)
	(segment
		(start 408.708098 -106.223816)
		(end 408.708098 -102.833424)
		(width 0.1143)
		(layer "In11.Cu")
		(net "P3E_PCH_TX_0_DP")
	)
	(segment
		(start 409.8163 -101.725222)
		(end 409.8163 -100.2665)
		(width 0.1143)
		(layer "In11.Cu")
		(net "P3E_PCH_TX_0_DP")
	)
	(segment
		(start 399.622772 -56.181752)
		(end 399.380202 -55.939182)
		(width 0.1143)
		(layer "In11.Cu")
		(net "P3E_PCH_TX_0_DP")
	)
	(segment
		(start 410.29382 -99.78898)
		(end 410.29382 -98.868992)
		(width 0.1143)
		(layer "In11.Cu")
		(net "P3E_PCH_TX_0_DP")
	)
	(segment
		(start 381.319024 -33.397444)
		(end 381.204724 -33.511744)
		(width 0.1143)
		(layer "In11.Cu")
		(net "P3E_PCH_TX_0_DP")
	)
	(segment
		(start 385.672584 -39.647368)
		(end 385.672584 -39.304468)
		(width 0.1143)
		(layer "In11.Cu")
		(net "P3E_PCH_TX_0_DP")
	)
	(segment
		(start 385.837684 -40.708326)
		(end 385.837684 -39.812468)
		(width 0.1143)
		(layer "In11.Cu")
		(net "P3E_PCH_TX_0_DP")
	)
	(segment
		(start 399.146776 -55.939182)
		(end 398.90446 -55.696866)
		(width 0.1143)
		(layer "In11.Cu")
		(net "P3E_PCH_TX_0_DP")
	)
	(segment
		(start 410.29382 -98.626676)
		(end 410.29382 -97.956624)
		(width 0.1143)
		(layer "In11.Cu")
		(net "P3E_PCH_TX_0_DP")
	)
	(segment
		(start 398.5387 -117.82298)
		(end 398.5387 -117.813074)
		(width 0.0889)
		(layer "In11.Cu")
		(net "P3E_PCH_TX_0_DP")
	)
	(segment
		(start 385.837684 -39.812468)
		(end 385.672584 -39.647368)
		(width 0.1143)
		(layer "In11.Cu")
		(net "P3E_PCH_TX_0_DP")
	)
	(segment
		(start 388.502398 -42.045636)
		(end 387.174994 -42.045636)
		(width 0.1143)
		(layer "In11.Cu")
		(net "P3E_PCH_TX_0_DP")
	)
	(segment
		(start 385.26974 -33.958784)
		(end 384.7084 -33.397444)
		(width 0.1143)
		(layer "In11.Cu")
		(net "P3E_PCH_TX_0_DP")
	)
	(segment
		(start 409.1686 -61.449712)
		(end 406.774396 -59.055508)
		(width 0.1143)
		(layer "In11.Cu")
		(net "P3E_PCH_TX_0_DP")
	)
	(segment
		(start 385.672584 -37.272468)
		(end 385.837684 -37.107368)
		(width 0.1143)
		(layer "In11.Cu")
		(net "P3E_PCH_TX_0_DP")
	)
	(segment
		(start 387.174994 -42.045636)
		(end 385.837684 -40.708326)
		(width 0.1143)
		(layer "In11.Cu")
		(net "P3E_PCH_TX_0_DP")
	)
	(segment
		(start 410.293566 -98.62693)
		(end 410.29382 -98.626676)
		(width 0.1143)
		(layer "In11.Cu")
		(net "P3E_PCH_TX_0_DP")
	)
	(segment
		(start 398.620742 -117.615208)
		(end 400.20875 -116.026946)
		(width 0.0889)
		(layer "In11.Cu")
		(net "P3E_PCH_TX_0_DP")
	)
	(segment
		(start 409.5115 -68.271898)
		(end 409.5115 -67.149726)
		(width 0.1143)
		(layer "In11.Cu")
		(net "P3E_PCH_TX_0_DP")
	)
	(segment
		(start 393.1793 -47.273972)
		(end 393.054078 -47.149004)
		(width 0.1143)
		(layer "In11.Cu")
		(net "P3E_PCH_TX_0_DP")
	)
	(segment
		(start 409.274264 -68.509134)
		(end 409.5115 -68.271898)
		(width 0.1143)
		(layer "In11.Cu")
		(net "P3E_PCH_TX_0_DP")
	)
	(segment
		(start 389.802878 -43.482006)
		(end 389.801862 -43.481752)
		(width 0.1143)
		(layer "In11.Cu")
		(net "P3E_PCH_TX_0_DP")
	)
	(segment
		(start 400.341338 -57.133744)
		(end 400.341338 -56.900318)
		(width 0.1143)
		(layer "In11.Cu")
		(net "P3E_PCH_TX_0_DP")
	)
	(segment
		(start 409.8163 -100.2665)
		(end 410.29382 -99.78898)
		(width 0.1143)
		(layer "In11.Cu")
		(net "P3E_PCH_TX_0_DP")
	)
	(segment
		(start 395.5669 -121.267474)
		(end 395.5669 -121.224294)
		(width 0.0889)
		(layer "In11.Cu")
		(net "P3E_PCH_TX_0_DP")
	)
	(segment
		(start 385.837684 -38.796468)
		(end 385.672584 -38.631368)
		(width 0.1143)
		(layer "In11.Cu")
		(net "P3E_PCH_TX_0_DP")
	)
	(segment
		(start 400.31797 -115.845844)
		(end 400.333464 -115.83035)
		(width 0.0889)
		(layer "In11.Cu")
		(net "P3E_PCH_TX_0_DP")
	)
	(segment
		(start 393.054078 -47.149004)
		(end 390.616694 -44.71162)
		(width 0.1143)
		(layer "In11.Cu")
		(net "P3E_PCH_TX_0_DP")
	)
	(segment
		(start 385.672584 -38.288468)
		(end 385.837684 -38.123368)
		(width 0.1143)
		(layer "In11.Cu")
		(net "P3E_PCH_TX_0_DP")
	)
	(segment
		(start 407.79065 -110.895384)
		(end 407.79065 -107.141264)
		(width 0.1143)
		(layer "In11.Cu")
		(net "P3E_PCH_TX_0_DP")
	)
	(segment
		(start 406.323546 -79.141574)
		(end 405.73452 -77.949806)
		(width 0.1143)
		(layer "In11.Cu")
		(net "P3E_PCH_TX_0_DP")
	)
	(segment
		(start 384.7084 -33.397444)
		(end 381.319024 -33.397444)
		(width 0.1143)
		(layer "In11.Cu")
		(net "P3E_PCH_TX_0_DP")
	)
	(segment
		(start 402.496528 -59.055508)
		(end 400.81708 -57.37606)
		(width 0.1143)
		(layer "In11.Cu")
		(net "P3E_PCH_TX_0_DP")
	)
	(segment
		(start 385.837684 -39.139368)
		(end 385.837684 -38.796468)
		(width 0.1143)
		(layer "In11.Cu")
		(net "P3E_PCH_TX_0_DP")
	)
	(segment
		(start 408.637486 -72.225916)
		(end 408.637486 -70.169786)
		(width 0.1143)
		(layer "In11.Cu")
		(net "P3E_PCH_TX_0_DP")
	)
	(segment
		(start 409.1686 -66.806826)
		(end 409.1686 -61.449712)
		(width 0.1143)
		(layer "In11.Cu")
		(net "P3E_PCH_TX_0_DP")
	)
	(segment
		(start 400.583654 -57.37606)
		(end 400.341338 -57.133744)
		(width 0.1143)
		(layer "In11.Cu")
		(net "P3E_PCH_TX_0_DP")
	)
	(segment
		(start 398.765268 -121.876566)
		(end 398.735042 -121.752868)
		(width 0.0889)
		(layer "In11.Cu")
		(net "P3E_PCH_TX_0_DP")
	)
	(segment
		(start 410.293566 -98.868738)
		(end 410.293566 -98.62693)
		(width 0.1143)
		(layer "In11.Cu")
		(net "P3E_PCH_TX_0_DP")
	)
	(segment
		(start 400.31797 -115.91798)
		(end 400.31797 -115.845844)
		(width 0.0889)
		(layer "In11.Cu")
		(net "P3E_PCH_TX_0_DP")
	)
	(segment
		(start 408.637486 -70.169786)
		(end 409.274264 -69.533008)
		(width 0.1143)
		(layer "In11.Cu")
		(net "P3E_PCH_TX_0_DP")
	)
	(segment
		(start 400.20875 -116.026946)
		(end 400.31797 -115.91798)
		(width 0.0889)
		(layer "In11.Cu")
		(net "P3E_PCH_TX_0_DP")
	)
	(segment
		(start 408.708098 -102.833424)
		(end 409.8163 -101.725222)
		(width 0.1143)
		(layer "In11.Cu")
		(net "P3E_PCH_TX_0_DP")
	)
	(segment
		(start 385.26974 -36.034726)
		(end 385.26974 -33.958784)
		(width 0.1143)
		(layer "In11.Cu")
		(net "P3E_PCH_TX_0_DP")
	)
	(segment
		(start 398.90446 -55.46344)
		(end 396.26794 -52.82692)
		(width 0.1143)
		(layer "In11.Cu")
		(net "P3E_PCH_TX_0_DP")
	)
	(segment
		(start 400.333464 -115.83035)
		(end 400.943826 -115.219988)
		(width 0.1143)
		(layer "In11.Cu")
		(net "P3E_PCH_TX_0_DP")
	)
	(segment
		(start 401.96516 -113.928652)
		(end 404.757382 -113.928652)
		(width 0.1143)
		(layer "In11.Cu")
		(net "P3E_PCH_TX_0_DP")
	)
	(segment
		(start 406.774396 -59.055508)
		(end 402.496528 -59.055508)
		(width 0.1143)
		(layer "In11.Cu")
		(net "P3E_PCH_TX_0_DP")
	)
	(segment
		(start 404.757382 -113.928652)
		(end 407.79065 -110.895384)
		(width 0.1143)
		(layer "In11.Cu")
		(net "P3E_PCH_TX_0_DP")
	)
	(segment
		(start 410.29382 -97.956624)
		(end 409.7147 -97.377504)
		(width 0.1143)
		(layer "In11.Cu")
		(net "P3E_PCH_TX_0_DP")
	)
	(segment
		(start 397.5481 -119.54002)
		(end 397.5481 -119.507254)
		(width 0.0889)
		(layer "In11.Cu")
		(net "P3E_PCH_TX_0_DP")
	)
	(segment
		(start 398.90446 -55.696866)
		(end 398.90446 -55.46344)
		(width 0.1143)
		(layer "In11.Cu")
		(net "P3E_PCH_TX_0_DP")
	)
	(segment
		(start 409.274264 -69.533008)
		(end 409.274264 -68.509134)
		(width 0.1143)
		(layer "In11.Cu")
		(net "P3E_PCH_TX_0_DP")
	)
	(segment
		(start 385.837684 -36.60267)
		(end 385.26974 -36.034726)
		(width 0.1143)
		(layer "In11.Cu")
		(net "P3E_PCH_TX_0_DP")
	)
	(segment
		(start 396.26794 -52.82692)
		(end 396.26794 -50.508662)
		(width 0.1143)
		(layer "In11.Cu")
		(net "P3E_PCH_TX_0_DP")
	)
	(segment
		(start 409.7147 -90.469466)
		(end 408.01544 -88.770206)
		(width 0.1143)
		(layer "In11.Cu")
		(net "P3E_PCH_TX_0_DP")
	)
	(segment
		(start 398.63395 -122.104404)
		(end 398.765268 -121.876566)
		(width 0.0889)
		(layer "In11.Cu")
		(net "P3E_PCH_TX_0_DP")
	)
	(segment
		(start 400.943826 -114.949986)
		(end 401.96516 -113.928652)
		(width 0.1143)
		(layer "In11.Cu")
		(net "P3E_PCH_TX_0_DP")
	)
	(segment
		(start 385.837684 -37.107368)
		(end 385.837684 -36.60267)
		(width 0.1143)
		(layer "In11.Cu")
		(net "P3E_PCH_TX_0_DP")
	)
	(segment
		(start 390.616694 -44.71162)
		(end 389.802878 -43.482006)
		(width 0.1143)
		(layer "In11.Cu")
		(net "P3E_PCH_TX_0_DP")
	)
	(segment
		(start 399.380202 -55.939182)
		(end 399.146776 -55.939182)
		(width 0.1143)
		(layer "In11.Cu")
		(net "P3E_PCH_TX_0_DP")
	)
	(segment
		(start 400.098768 -56.657748)
		(end 399.865342 -56.657748)
		(width 0.1143)
		(layer "In11.Cu")
		(net "P3E_PCH_TX_0_DP")
	)
	(segment
		(start 405.73452 -77.949806)
		(end 405.73452 -76.060046)
		(width 0.1143)
		(layer "In11.Cu")
		(net "P3E_PCH_TX_0_DP")
	)
	(segment
		(start 396.26794 -50.508662)
		(end 393.1793 -47.420022)
		(width 0.1143)
		(layer "In11.Cu")
		(net "P3E_PCH_TX_0_DP")
	)
	(segment
		(start 410.29382 -98.868992)
		(end 410.293566 -98.868738)
		(width 0.1143)
		(layer "In11.Cu")
		(net "P3E_PCH_TX_0_DP")
	)
	(segment
		(start 400.341338 -56.900318)
		(end 400.098768 -56.657748)
		(width 0.1143)
		(layer "In11.Cu")
		(net "P3E_PCH_TX_0_DP")
	)
	(segment
		(start 399.865342 -56.657748)
		(end 399.622772 -56.415178)
		(width 0.1143)
		(layer "In11.Cu")
		(net "P3E_PCH_TX_0_DP")
	)
	(segment
		(start 389.534654 -43.077892)
		(end 388.502398 -42.045636)
		(width 0.1143)
		(layer "In11.Cu")
		(net "P3E_PCH_TX_0_DP")
	)
	(segment
		(start 405.73452 -76.060046)
		(end 406.339548 -74.5236)
		(width 0.1143)
		(layer "In11.Cu")
		(net "P3E_PCH_TX_0_DP")
	)
	(segment
		(start 385.672584 -38.631368)
		(end 385.672584 -38.288468)
		(width 0.1143)
		(layer "In11.Cu")
		(net "P3E_PCH_TX_0_DP")
	)
	(segment
		(start 407.847292 -87.944706)
		(end 407.847292 -80.66532)
		(width 0.1143)
		(layer "In11.Cu")
		(net "P3E_PCH_TX_0_DP")
	)
	(arc
		(start 398.5387 -117.813074)
		(mid 398.560022 -117.705972)
		(end 398.620742 -117.615208)
		(width 0.0889)
		(layer "In11.Cu")
		(net "P3E_PCH_TX_0_DP")
	)
	(arc
		(start 397.443452 -121.757694)
		(mid 397.14805 -121.836825)
		(end 396.852648 -121.757694)
		(width 0.0889)
		(layer "In11.Cu")
		(net "P3E_PCH_TX_0_DP")
	)
	(arc
		(start 395.862048 -121.757694)
		(mid 395.651184 -121.55069)
		(end 395.5669 -121.267474)
		(width 0.0889)
		(layer "In11.Cu")
		(net "P3E_PCH_TX_0_DP")
	)
	(arc
		(start 398.338548 -118.158514)
		(mid 398.482352 -118.016831)
		(end 398.5387 -117.82298)
		(width 0.0889)
		(layer "In11.Cu")
		(net "P3E_PCH_TX_0_DP")
	)
	(arc
		(start 397.843248 -119.017034)
		(mid 397.987052 -118.875351)
		(end 398.0434 -118.6815)
		(width 0.0889)
		(layer "In11.Cu")
		(net "P3E_PCH_TX_0_DP")
	)
	(arc
		(start 398.434052 -121.757694)
		(mid 398.13865 -121.836825)
		(end 397.843248 -121.757694)
		(width 0.0889)
		(layer "In11.Cu")
		(net "P3E_PCH_TX_0_DP")
	)
	(arc
		(start 398.735042 -121.752868)
		(mid 398.583935 -121.716303)
		(end 398.434052 -121.757694)
		(width 0.0889)
		(layer "In11.Cu")
		(net "P3E_PCH_TX_0_DP")
	)
	(arc
		(start 398.0434 -118.648734)
		(mid 398.127681 -118.365517)
		(end 398.338548 -118.158514)
		(width 0.0889)
		(layer "In11.Cu")
		(net "P3E_PCH_TX_0_DP")
	)
	(arc
		(start 396.852648 -121.757694)
		(mid 396.65275 -121.704195)
		(end 396.452852 -121.757694)
		(width 0.0889)
		(layer "In11.Cu")
		(net "P3E_PCH_TX_0_DP")
	)
	(arc
		(start 396.0622 -120.365774)
		(mid 396.366643 -119.870297)
		(end 396.948152 -119.875554)
		(width 0.0889)
		(layer "In11.Cu")
		(net "P3E_PCH_TX_0_DP")
	)
	(arc
		(start 397.5481 -119.507254)
		(mid 397.632381 -119.224037)
		(end 397.843248 -119.017034)
		(width 0.0889)
		(layer "In11.Cu")
		(net "P3E_PCH_TX_0_DP")
	)
	(arc
		(start 395.5669 -121.224294)
		(mid 395.651181 -120.941077)
		(end 395.862048 -120.734074)
		(width 0.0889)
		(layer "In11.Cu")
		(net "P3E_PCH_TX_0_DP")
	)
	(arc
		(start 395.862048 -120.734074)
		(mid 396.005852 -120.592391)
		(end 396.0622 -120.39854)
		(width 0.0889)
		(layer "In11.Cu")
		(net "P3E_PCH_TX_0_DP")
	)
	(arc
		(start 396.452852 -121.757694)
		(mid 396.15745 -121.836825)
		(end 395.862048 -121.757694)
		(width 0.0889)
		(layer "In11.Cu")
		(net "P3E_PCH_TX_0_DP")
	)
	(arc
		(start 396.948152 -119.875554)
		(mid 397.343399 -119.878137)
		(end 397.5481 -119.54002)
		(width 0.0889)
		(layer "In11.Cu")
		(net "P3E_PCH_TX_0_DP")
	)
	(arc
		(start 397.843248 -121.757694)
		(mid 397.64335 -121.704195)
		(end 397.443452 -121.757694)
		(width 0.0889)
		(layer "In11.Cu")
		(net "P3E_PCH_TX_0_DP")
	)
	(segment
		(start 398.63395 -121.01576)
		(end 399.12925 -121.245884)
		(width 0.1143)
		(layer "F.Cu")
		(net "P3E_PCH_TX_0_DN")
	)
	(segment
		(start 380.032768 -32.3215)
		(end 380.28245 -32.3215)
		(width 0.1143)
		(layer "F.Cu")
		(net "P3E_PCH_TX_0_DN")
	)
	(segment
		(start 380.28245 -32.3215)
		(end 380.380494 -32.223456)
		(width 0.1143)
		(layer "F.Cu")
		(net "P3E_PCH_TX_0_DN")
	)
	(segment
		(start 381.079756 -32.223456)
		(end 381.1778 -32.3215)
		(width 0.1143)
		(layer "F.Cu")
		(net "P3E_PCH_TX_0_DN")
	)
	(segment
		(start 380.380494 -32.223456)
		(end 381.079756 -32.223456)
		(width 0.1143)
		(layer "F.Cu")
		(net "P3E_PCH_TX_0_DN")
	)
	(via
		(at 399.12925 -121.245884)
		(size 0.508)
		(drill 0.254)
		(layers "F.Cu" "B.Cu")
		(net "P3E_PCH_TX_0_DN")
	)
	(via
		(at 381.1778 -32.3215)
		(size 0.508)
		(drill 0.254)
		(layers "F.Cu" "B.Cu")
		(net "P3E_PCH_TX_0_DN")
	)
	(segment
		(start 396.56004 -50.387504)
		(end 393.4714 -47.298864)
		(width 0.1143)
		(layer "In11.Cu")
		(net "P3E_PCH_TX_0_DN")
	)
	(segment
		(start 404.87854 -114.220752)
		(end 408.08275 -111.016542)
		(width 0.1143)
		(layer "In11.Cu")
		(net "P3E_PCH_TX_0_DN")
	)
	(segment
		(start 398.96034 -121.539)
		(end 398.870932 -121.562876)
		(width 0.0889)
		(layer "In11.Cu")
		(net "P3E_PCH_TX_0_DN")
	)
	(segment
		(start 407.628598 -80.033114)
		(end 406.564338 -78.968854)
		(width 0.1143)
		(layer "In11.Cu")
		(net "P3E_PCH_TX_0_DN")
	)
	(segment
		(start 387.296152 -41.753536)
		(end 386.129784 -40.587168)
		(width 0.1143)
		(layer "In11.Cu")
		(net "P3E_PCH_TX_0_DN")
	)
	(segment
		(start 398.7292 -117.82552)
		(end 398.7292 -117.813074)
		(width 0.0889)
		(layer "In11.Cu")
		(net "P3E_PCH_TX_0_DN")
	)
	(segment
		(start 409.566364 -69.654166)
		(end 409.566364 -68.630292)
		(width 0.1143)
		(layer "In11.Cu")
		(net "P3E_PCH_TX_0_DN")
	)
	(segment
		(start 410.58592 -99.910138)
		(end 410.58592 -97.835466)
		(width 0.1143)
		(layer "In11.Cu")
		(net "P3E_PCH_TX_0_DN")
	)
	(segment
		(start 389.912098 -43.118532)
		(end 389.911844 -43.118532)
		(width 0.1143)
		(layer "In11.Cu")
		(net "P3E_PCH_TX_0_DN")
	)
	(segment
		(start 406.564338 -78.968854)
		(end 406.02662 -77.88148)
		(width 0.1143)
		(layer "In11.Cu")
		(net "P3E_PCH_TX_0_DN")
	)
	(segment
		(start 399.258536 -117.372638)
		(end 399.258536 -117.246908)
		(width 0.0889)
		(layer "In11.Cu")
		(net "P3E_PCH_TX_0_DN")
	)
	(segment
		(start 410.0068 -90.348308)
		(end 408.284172 -88.62568)
		(width 0.1143)
		(layer "In11.Cu")
		(net "P3E_PCH_TX_0_DN")
	)
	(segment
		(start 385.56184 -35.913568)
		(end 385.56184 -33.837626)
		(width 0.1143)
		(layer "In11.Cu")
		(net "P3E_PCH_TX_0_DN")
	)
	(segment
		(start 399.949924 -116.55552)
		(end 400.075654 -116.55552)
		(width 0.0889)
		(layer "In11.Cu")
		(net "P3E_PCH_TX_0_DN")
	)
	(segment
		(start 409.4607 -66.685668)
		(end 409.4607 -61.328554)
		(width 0.1143)
		(layer "In11.Cu")
		(net "P3E_PCH_TX_0_DN")
	)
	(segment
		(start 388.623556 -41.753536)
		(end 387.296152 -41.753536)
		(width 0.1143)
		(layer "In11.Cu")
		(net "P3E_PCH_TX_0_DN")
	)
	(segment
		(start 410.1084 -100.387658)
		(end 410.58592 -99.910138)
		(width 0.1143)
		(layer "In11.Cu")
		(net "P3E_PCH_TX_0_DN")
	)
	(segment
		(start 399.447004 -117.05844)
		(end 399.572734 -117.05844)
		(width 0.0889)
		(layer "In11.Cu")
		(net "P3E_PCH_TX_0_DN")
	)
	(segment
		(start 401.235926 -115.341146)
		(end 401.235926 -115.071144)
		(width 0.1143)
		(layer "In11.Cu")
		(net "P3E_PCH_TX_0_DN")
	)
	(segment
		(start 393.4714 -47.152814)
		(end 390.844278 -44.525692)
		(width 0.1143)
		(layer "In11.Cu")
		(net "P3E_PCH_TX_0_DN")
	)
	(segment
		(start 390.844278 -44.525692)
		(end 389.98398 -43.225974)
		(width 0.1143)
		(layer "In11.Cu")
		(net "P3E_PCH_TX_0_DN")
	)
	(segment
		(start 406.02662 -76.115672)
		(end 406.58923 -74.68743)
		(width 0.1143)
		(layer "In11.Cu")
		(net "P3E_PCH_TX_0_DN")
	)
	(segment
		(start 399.761456 -116.869718)
		(end 399.761456 -116.743988)
		(width 0.0889)
		(layer "In11.Cu")
		(net "P3E_PCH_TX_0_DN")
	)
	(segment
		(start 408.08275 -107.262422)
		(end 409.000198 -106.344974)
		(width 0.1143)
		(layer "In11.Cu")
		(net "P3E_PCH_TX_0_DN")
	)
	(segment
		(start 400.264376 -116.366798)
		(end 400.264376 -116.241068)
		(width 0.0889)
		(layer "In11.Cu")
		(net "P3E_PCH_TX_0_DN")
	)
	(segment
		(start 409.4607 -61.328554)
		(end 406.895554 -58.763408)
		(width 0.1143)
		(layer "In11.Cu")
		(net "P3E_PCH_TX_0_DN")
	)
	(segment
		(start 400.741896 -115.834922)
		(end 401.235926 -115.341146)
		(width 0.1143)
		(layer "In11.Cu")
		(net "P3E_PCH_TX_0_DN")
	)
	(segment
		(start 399.572734 -117.05844)
		(end 399.761456 -116.869718)
		(width 0.0889)
		(layer "In11.Cu")
		(net "P3E_PCH_TX_0_DN")
	)
	(segment
		(start 389.982964 -43.22572)
		(end 389.912098 -43.118532)
		(width 0.1143)
		(layer "In11.Cu")
		(net "P3E_PCH_TX_0_DN")
	)
	(segment
		(start 409.000198 -106.344974)
		(end 409.000198 -102.954582)
		(width 0.1143)
		(layer "In11.Cu")
		(net "P3E_PCH_TX_0_DN")
	)
	(segment
		(start 400.452844 -116.0526)
		(end 400.524472 -116.0526)
		(width 0.0889)
		(layer "In11.Cu")
		(net "P3E_PCH_TX_0_DN")
	)
	(segment
		(start 384.829558 -33.105344)
		(end 381.672338 -33.105344)
		(width 0.1143)
		(layer "In11.Cu")
		(net "P3E_PCH_TX_0_DN")
	)
	(segment
		(start 399.761456 -116.743988)
		(end 399.949924 -116.55552)
		(width 0.0889)
		(layer "In11.Cu")
		(net "P3E_PCH_TX_0_DN")
	)
	(segment
		(start 400.075654 -116.55552)
		(end 400.264376 -116.366798)
		(width 0.0889)
		(layer "In11.Cu")
		(net "P3E_PCH_TX_0_DN")
	)
	(segment
		(start 398.944084 -117.56136)
		(end 399.069814 -117.56136)
		(width 0.0889)
		(layer "In11.Cu")
		(net "P3E_PCH_TX_0_DN")
	)
	(segment
		(start 401.235926 -115.071144)
		(end 402.086318 -114.220752)
		(width 0.1143)
		(layer "In11.Cu")
		(net "P3E_PCH_TX_0_DN")
	)
	(segment
		(start 408.08275 -111.016542)
		(end 408.08275 -107.262422)
		(width 0.1143)
		(layer "In11.Cu")
		(net "P3E_PCH_TX_0_DN")
	)
	(segment
		(start 396.2527 -120.40108)
		(end 396.2527 -120.369838)
		(width 0.0889)
		(layer "In11.Cu")
		(net "P3E_PCH_TX_0_DN")
	)
	(segment
		(start 409.8036 -68.393056)
		(end 409.8036 -67.028568)
		(width 0.1143)
		(layer "In11.Cu")
		(net "P3E_PCH_TX_0_DN")
	)
	(segment
		(start 408.929586 -72.347836)
		(end 408.929586 -70.290944)
		(width 0.1143)
		(layer "In11.Cu")
		(net "P3E_PCH_TX_0_DN")
	)
	(segment
		(start 400.524472 -116.0526)
		(end 400.539966 -116.037106)
		(width 0.0889)
		(layer "In11.Cu")
		(net "P3E_PCH_TX_0_DN")
	)
	(segment
		(start 408.139392 -80.544162)
		(end 407.628344 -80.033114)
		(width 0.1143)
		(layer "In11.Cu")
		(net "P3E_PCH_TX_0_DN")
	)
	(segment
		(start 408.929586 -70.290944)
		(end 409.566364 -69.654166)
		(width 0.1143)
		(layer "In11.Cu")
		(net "P3E_PCH_TX_0_DN")
	)
	(segment
		(start 389.911844 -43.118532)
		(end 389.762238 -42.891964)
		(width 0.1143)
		(layer "In11.Cu")
		(net "P3E_PCH_TX_0_DN")
	)
	(segment
		(start 381.1778 -32.610806)
		(end 381.1778 -32.3215)
		(width 0.1143)
		(layer "In11.Cu")
		(net "P3E_PCH_TX_0_DN")
	)
	(segment
		(start 400.264376 -116.241068)
		(end 400.452844 -116.0526)
		(width 0.0889)
		(layer "In11.Cu")
		(net "P3E_PCH_TX_0_DN")
	)
	(segment
		(start 410.1084 -101.84638)
		(end 410.1084 -100.387658)
		(width 0.1143)
		(layer "In11.Cu")
		(net "P3E_PCH_TX_0_DN")
	)
	(segment
		(start 406.02662 -77.88148)
		(end 406.02662 -76.115672)
		(width 0.1143)
		(layer "In11.Cu")
		(net "P3E_PCH_TX_0_DN")
	)
	(segment
		(start 406.58923 -74.68743)
		(end 408.929586 -72.347836)
		(width 0.1143)
		(layer "In11.Cu")
		(net "P3E_PCH_TX_0_DN")
	)
	(segment
		(start 409.566364 -68.630292)
		(end 409.8036 -68.393056)
		(width 0.1143)
		(layer "In11.Cu")
		(net "P3E_PCH_TX_0_DN")
	)
	(segment
		(start 395.7574 -121.26341)
		(end 395.7574 -121.228358)
		(width 0.0889)
		(layer "In11.Cu")
		(net "P3E_PCH_TX_0_DN")
	)
	(segment
		(start 398.755362 -117.750082)
		(end 398.944084 -117.56136)
		(width 0.0889)
		(layer "In11.Cu")
		(net "P3E_PCH_TX_0_DN")
	)
	(segment
		(start 409.000198 -102.954582)
		(end 410.1084 -101.84638)
		(width 0.1143)
		(layer "In11.Cu")
		(net "P3E_PCH_TX_0_DN")
	)
	(segment
		(start 386.129784 -40.587168)
		(end 386.129784 -36.481512)
		(width 0.1143)
		(layer "In11.Cu")
		(net "P3E_PCH_TX_0_DN")
	)
	(segment
		(start 400.539966 -116.037106)
		(end 400.741896 -115.834922)
		(width 0.1143)
		(layer "In11.Cu")
		(net "P3E_PCH_TX_0_DN")
	)
	(segment
		(start 402.086318 -114.220752)
		(end 404.87854 -114.220752)
		(width 0.1143)
		(layer "In11.Cu")
		(net "P3E_PCH_TX_0_DN")
	)
	(segment
		(start 409.8036 -67.028568)
		(end 409.4607 -66.685668)
		(width 0.1143)
		(layer "In11.Cu")
		(net "P3E_PCH_TX_0_DN")
	)
	(segment
		(start 399.12925 -121.245884)
		(end 398.96034 -121.539)
		(width 0.0889)
		(layer "In11.Cu")
		(net "P3E_PCH_TX_0_DN")
	)
	(segment
		(start 410.0068 -97.256346)
		(end 410.0068 -90.348308)
		(width 0.1143)
		(layer "In11.Cu")
		(net "P3E_PCH_TX_0_DN")
	)
	(segment
		(start 399.258536 -117.246908)
		(end 399.447004 -117.05844)
		(width 0.0889)
		(layer "In11.Cu")
		(net "P3E_PCH_TX_0_DN")
	)
	(segment
		(start 393.4714 -47.298864)
		(end 393.4714 -47.152814)
		(width 0.1143)
		(layer "In11.Cu")
		(net "P3E_PCH_TX_0_DN")
	)
	(segment
		(start 402.617686 -58.763408)
		(end 396.56004 -52.705762)
		(width 0.1143)
		(layer "In11.Cu")
		(net "P3E_PCH_TX_0_DN")
	)
	(segment
		(start 399.069814 -117.56136)
		(end 399.258536 -117.372638)
		(width 0.0889)
		(layer "In11.Cu")
		(net "P3E_PCH_TX_0_DN")
	)
	(segment
		(start 397.7386 -119.54256)
		(end 397.7386 -119.511318)
		(width 0.0889)
		(layer "In11.Cu")
		(net "P3E_PCH_TX_0_DN")
	)
	(segment
		(start 386.129784 -36.481512)
		(end 385.56184 -35.913568)
		(width 0.1143)
		(layer "In11.Cu")
		(net "P3E_PCH_TX_0_DN")
	)
	(segment
		(start 398.2339 -118.68404)
		(end 398.2339 -118.652798)
		(width 0.0889)
		(layer "In11.Cu")
		(net "P3E_PCH_TX_0_DN")
	)
	(segment
		(start 410.58592 -97.835466)
		(end 410.0068 -97.256346)
		(width 0.1143)
		(layer "In11.Cu")
		(net "P3E_PCH_TX_0_DN")
	)
	(segment
		(start 385.56184 -33.837626)
		(end 384.829558 -33.105344)
		(width 0.1143)
		(layer "In11.Cu")
		(net "P3E_PCH_TX_0_DN")
	)
	(segment
		(start 389.98398 -43.225974)
		(end 389.982964 -43.22572)
		(width 0.1143)
		(layer "In11.Cu")
		(net "P3E_PCH_TX_0_DN")
	)
	(segment
		(start 407.628344 -80.033114)
		(end 407.628598 -80.033114)
		(width 0.1143)
		(layer "In11.Cu")
		(net "P3E_PCH_TX_0_DN")
	)
	(segment
		(start 396.56004 -52.705762)
		(end 396.56004 -50.387504)
		(width 0.1143)
		(layer "In11.Cu")
		(net "P3E_PCH_TX_0_DN")
	)
	(segment
		(start 408.284172 -88.62568)
		(end 408.139392 -87.915242)
		(width 0.1143)
		(layer "In11.Cu")
		(net "P3E_PCH_TX_0_DN")
	)
	(segment
		(start 406.895554 -58.763408)
		(end 402.617686 -58.763408)
		(width 0.1143)
		(layer "In11.Cu")
		(net "P3E_PCH_TX_0_DN")
	)
	(segment
		(start 408.139392 -87.915242)
		(end 408.139392 -80.544162)
		(width 0.1143)
		(layer "In11.Cu")
		(net "P3E_PCH_TX_0_DN")
	)
	(segment
		(start 381.672338 -33.105344)
		(end 381.1778 -32.610806)
		(width 0.1143)
		(layer "In11.Cu")
		(net "P3E_PCH_TX_0_DN")
	)
	(segment
		(start 389.762238 -42.891964)
		(end 388.623556 -41.753536)
		(width 0.1143)
		(layer "In11.Cu")
		(net "P3E_PCH_TX_0_DN")
	)
	(arc
		(start 396.947898 -121.592594)
		(mid 396.65275 -121.513589)
		(end 396.357602 -121.592594)
		(width 0.0889)
		(layer "In11.Cu")
		(net "P3E_PCH_TX_0_DN")
	)
	(arc
		(start 396.357602 -121.592594)
		(mid 396.15745 -121.64622)
		(end 395.957298 -121.592594)
		(width 0.0889)
		(layer "In11.Cu")
		(net "P3E_PCH_TX_0_DN")
	)
	(arc
		(start 395.957298 -120.899174)
		(mid 396.17027 -120.688821)
		(end 396.2527 -120.40108)
		(width 0.0889)
		(layer "In11.Cu")
		(net "P3E_PCH_TX_0_DN")
	)
	(arc
		(start 396.2527 -120.369838)
		(mid 396.460164 -120.036283)
		(end 396.852902 -120.040654)
		(width 0.0889)
		(layer "In11.Cu")
		(net "P3E_PCH_TX_0_DN")
	)
	(arc
		(start 397.347948 -121.592594)
		(mid 397.14794 -121.646059)
		(end 396.947898 -121.592594)
		(width 0.0889)
		(layer "In11.Cu")
		(net "P3E_PCH_TX_0_DN")
	)
	(arc
		(start 397.938752 -121.592594)
		(mid 397.64335 -121.513463)
		(end 397.347948 -121.592594)
		(width 0.0889)
		(layer "In11.Cu")
		(net "P3E_PCH_TX_0_DN")
	)
	(arc
		(start 395.957298 -121.592594)
		(mid 395.815218 -121.453601)
		(end 395.7574 -121.26341)
		(width 0.0889)
		(layer "In11.Cu")
		(net "P3E_PCH_TX_0_DN")
	)
	(arc
		(start 397.938498 -119.182134)
		(mid 398.15147 -118.971781)
		(end 398.2339 -118.68404)
		(width 0.0889)
		(layer "In11.Cu")
		(net "P3E_PCH_TX_0_DN")
	)
	(arc
		(start 395.7574 -121.228358)
		(mid 395.815135 -121.038116)
		(end 395.957298 -120.899174)
		(width 0.0889)
		(layer "In11.Cu")
		(net "P3E_PCH_TX_0_DN")
	)
	(arc
		(start 398.870932 -121.562876)
		(mid 398.601207 -121.514316)
		(end 398.338548 -121.592594)
		(width 0.0889)
		(layer "In11.Cu")
		(net "P3E_PCH_TX_0_DN")
	)
	(arc
		(start 398.7292 -117.813074)
		(mid 398.736002 -117.77897)
		(end 398.755362 -117.750082)
		(width 0.0889)
		(layer "In11.Cu")
		(net "P3E_PCH_TX_0_DN")
	)
	(arc
		(start 398.433798 -118.323614)
		(mid 398.64677 -118.113261)
		(end 398.7292 -117.82552)
		(width 0.0889)
		(layer "In11.Cu")
		(net "P3E_PCH_TX_0_DN")
	)
	(arc
		(start 396.852902 -120.040654)
		(mid 397.437627 -120.043826)
		(end 397.7386 -119.54256)
		(width 0.0889)
		(layer "In11.Cu")
		(net "P3E_PCH_TX_0_DN")
	)
	(arc
		(start 398.2339 -118.652798)
		(mid 398.291635 -118.462556)
		(end 398.433798 -118.323614)
		(width 0.0889)
		(layer "In11.Cu")
		(net "P3E_PCH_TX_0_DN")
	)
	(arc
		(start 398.338548 -121.592594)
		(mid 398.13865 -121.646093)
		(end 397.938752 -121.592594)
		(width 0.0889)
		(layer "In11.Cu")
		(net "P3E_PCH_TX_0_DN")
	)
	(arc
		(start 397.7386 -119.511318)
		(mid 397.796335 -119.321076)
		(end 397.938498 -119.182134)
		(width 0.0889)
		(layer "In11.Cu")
		(net "P3E_PCH_TX_0_DN")
	)
	(segment
		(start 392.85926 -126.499112)
		(end 392.85926 -127.39116)
		(width 0.0889)
		(layer "F.Cu")
		(net "P3E_PCH_RX_0_DP")
	)
	(segment
		(start 392.693652 -126.333504)
		(end 392.85926 -126.499112)
		(width 0.0889)
		(layer "F.Cu")
		(net "P3E_PCH_RX_0_DP")
	)
	(segment
		(start 393.16406 -127.48514)
		(end 393.2682 -127.381)
		(width 0.0889)
		(layer "F.Cu")
		(net "P3E_PCH_RX_0_DP")
	)
	(segment
		(start 379.2982 -29.232352)
		(end 380.151132 -29.232352)
		(width 0.1143)
		(layer "F.Cu")
		(net "P3E_PCH_RX_0_DP")
	)
	(segment
		(start 392.703558 -125.485652)
		(end 392.799062 -125.681486)
		(width 0.0889)
		(layer "F.Cu")
		(net "P3E_PCH_RX_0_DP")
	)
	(segment
		(start 392.95324 -127.48514)
		(end 393.16406 -127.48514)
		(width 0.0889)
		(layer "F.Cu")
		(net "P3E_PCH_RX_0_DP")
	)
	(segment
		(start 392.799062 -125.681486)
		(end 392.799062 -125.848872)
		(width 0.0889)
		(layer "F.Cu")
		(net "P3E_PCH_RX_0_DP")
	)
	(segment
		(start 392.694922 -125.468126)
		(end 392.703558 -125.485652)
		(width 0.0889)
		(layer "F.Cu")
		(net "P3E_PCH_RX_0_DP")
	)
	(segment
		(start 392.485118 -124.919994)
		(end 392.661394 -125.38075)
		(width 0.0889)
		(layer "F.Cu")
		(net "P3E_PCH_RX_0_DP")
	)
	(segment
		(start 392.693652 -126.063502)
		(end 392.693652 -126.333504)
		(width 0.0889)
		(layer "F.Cu")
		(net "P3E_PCH_RX_0_DP")
	)
	(segment
		(start 392.799062 -125.848872)
		(end 392.693652 -126.063502)
		(width 0.0889)
		(layer "F.Cu")
		(net "P3E_PCH_RX_0_DP")
	)
	(segment
		(start 392.661394 -125.38075)
		(end 392.694922 -125.468126)
		(width 0.0889)
		(layer "F.Cu")
		(net "P3E_PCH_RX_0_DP")
	)
	(segment
		(start 392.85926 -127.39116)
		(end 392.95324 -127.48514)
		(width 0.0889)
		(layer "F.Cu")
		(net "P3E_PCH_RX_0_DP")
	)
	(via
		(at 380.151132 -29.232352)
		(size 0.508)
		(drill 0.254)
		(layers "F.Cu" "B.Cu")
		(net "P3E_PCH_RX_0_DP")
	)
	(via
		(at 393.2682 -127.381)
		(size 0.508)
		(drill 0.254)
		(layers "F.Cu" "B.Cu")
		(net "P3E_PCH_RX_0_DP")
	)
	(segment
		(start 395.594332 -125.134878)
		(end 395.861032 -125.134878)
		(width 0.0889)
		(layer "In11.Cu")
		(net "P3E_PCH_RX_0_DP")
	)
	(segment
		(start 406.17521 -50.369216)
		(end 404.134066 -50.369216)
		(width 0.1143)
		(layer "In11.Cu")
		(net "P3E_PCH_RX_0_DP")
	)
	(segment
		(start 397.4973 -31.4579)
		(end 397.4973 -30.3149)
		(width 0.1143)
		(layer "In11.Cu")
		(net "P3E_PCH_RX_0_DP")
	)
	(segment
		(start 396.34922 -125.096778)
		(end 396.371318 -125.096778)
		(width 0.0889)
		(layer "In11.Cu")
		(net "P3E_PCH_RX_0_DP")
	)
	(segment
		(start 398.7673 -40.958262)
		(end 398.7673 -40.442388)
		(width 0.1143)
		(layer "In11.Cu")
		(net "P3E_PCH_RX_0_DP")
	)
	(segment
		(start 393.351512 -125.045978)
		(end 393.440412 -125.134878)
		(width 0.0889)
		(layer "In11.Cu")
		(net "P3E_PCH_RX_0_DP")
	)
	(segment
		(start 392.7983 -125.545342)
		(end 392.7983 -125.33249)
		(width 0.0889)
		(layer "In11.Cu")
		(net "P3E_PCH_RX_0_DP")
	)
	(segment
		(start 380.3142 -29.781246)
		(end 380.151132 -29.618178)
		(width 0.1143)
		(layer "In11.Cu")
		(net "P3E_PCH_RX_0_DP")
	)
	(segment
		(start 419.110414 -90.106246)
		(end 419.110414 -85.786976)
		(width 0.1143)
		(layer "In11.Cu")
		(net "P3E_PCH_RX_0_DP")
	)
	(segment
		(start 380.151132 -29.618178)
		(end 380.151132 -29.232352)
		(width 0.1143)
		(layer "In11.Cu")
		(net "P3E_PCH_RX_0_DP")
	)
	(segment
		(start 411.610556 -121.752106)
		(end 413.274256 -120.088406)
		(width 0.1143)
		(layer "In11.Cu")
		(net "P3E_PCH_RX_0_DP")
	)
	(segment
		(start 409.306776 -122.5042)
		(end 410.05887 -121.752106)
		(width 0.1143)
		(layer "In11.Cu")
		(net "P3E_PCH_RX_0_DP")
	)
	(segment
		(start 392.8872 -126.612142)
		(end 392.8872 -126.345442)
		(width 0.0889)
		(layer "In11.Cu")
		(net "P3E_PCH_RX_0_DP")
	)
	(segment
		(start 395.238732 -125.045978)
		(end 395.505432 -125.045978)
		(width 0.0889)
		(layer "In11.Cu")
		(net "P3E_PCH_RX_0_DP")
	)
	(segment
		(start 383.032 -20.991068)
		(end 383.032 -25.786588)
		(width 0.1143)
		(layer "In11.Cu")
		(net "P3E_PCH_RX_0_DP")
	)
	(segment
		(start 410.05887 -121.752106)
		(end 411.610556 -121.752106)
		(width 0.1143)
		(layer "In11.Cu")
		(net "P3E_PCH_RX_0_DP")
	)
	(segment
		(start 413.274256 -120.088406)
		(end 413.274256 -119.181372)
		(width 0.1143)
		(layer "In11.Cu")
		(net "P3E_PCH_RX_0_DP")
	)
	(segment
		(start 392.7983 -125.989842)
		(end 392.8872 -125.900942)
		(width 0.0889)
		(layer "In11.Cu")
		(net "P3E_PCH_RX_0_DP")
	)
	(segment
		(start 394.527532 -125.045978)
		(end 394.794232 -125.045978)
		(width 0.0889)
		(layer "In11.Cu")
		(net "P3E_PCH_RX_0_DP")
	)
	(segment
		(start 392.8872 -126.345442)
		(end 392.7983 -126.256542)
		(width 0.0889)
		(layer "In11.Cu")
		(net "P3E_PCH_RX_0_DP")
	)
	(segment
		(start 414.132776 -54.448964)
		(end 413.07004 -54.448964)
		(width 0.1143)
		(layer "In11.Cu")
		(net "P3E_PCH_RX_0_DP")
	)
	(segment
		(start 395.149832 -125.134878)
		(end 395.238732 -125.045978)
		(width 0.0889)
		(layer "In11.Cu")
		(net "P3E_PCH_RX_0_DP")
	)
	(segment
		(start 393.707112 -125.134878)
		(end 393.796012 -125.045978)
		(width 0.0889)
		(layer "In11.Cu")
		(net "P3E_PCH_RX_0_DP")
	)
	(segment
		(start 419.110414 -85.786976)
		(end 418.626798 -85.30336)
		(width 0.1143)
		(layer "In11.Cu")
		(net "P3E_PCH_RX_0_DP")
	)
	(segment
		(start 417.4871 -113.423446)
		(end 417.4871 -109.264958)
		(width 0.1143)
		(layer "In11.Cu")
		(net "P3E_PCH_RX_0_DP")
	)
	(segment
		(start 395.949932 -125.045978)
		(end 396.29842 -125.045978)
		(width 0.0889)
		(layer "In11.Cu")
		(net "P3E_PCH_RX_0_DP")
	)
	(segment
		(start 417.4871 -109.264958)
		(end 417.9697 -108.782358)
		(width 0.1143)
		(layer "In11.Cu")
		(net "P3E_PCH_RX_0_DP")
	)
	(segment
		(start 399.732754 -125.096778)
		(end 402.325332 -122.5042)
		(width 0.1143)
		(layer "In11.Cu")
		(net "P3E_PCH_RX_0_DP")
	)
	(segment
		(start 397.4973 -30.3149)
		(end 396.554198 -29.371798)
		(width 0.1143)
		(layer "In11.Cu")
		(net "P3E_PCH_RX_0_DP")
	)
	(segment
		(start 384.843782 -19.179286)
		(end 383.032 -20.991068)
		(width 0.1143)
		(layer "In11.Cu")
		(net "P3E_PCH_RX_0_DP")
	)
	(segment
		(start 392.8872 -125.900942)
		(end 392.8872 -125.634242)
		(width 0.0889)
		(layer "In11.Cu")
		(net "P3E_PCH_RX_0_DP")
	)
	(segment
		(start 400.718528 -42.90949)
		(end 398.7673 -40.958262)
		(width 0.1143)
		(layer "In11.Cu")
		(net "P3E_PCH_RX_0_DP")
	)
	(segment
		(start 392.7983 -126.256542)
		(end 392.7983 -125.989842)
		(width 0.0889)
		(layer "In11.Cu")
		(net "P3E_PCH_RX_0_DP")
	)
	(segment
		(start 393.2682 -127.51054)
		(end 393.146026 -127.632714)
		(width 0.0889)
		(layer "In11.Cu")
		(net "P3E_PCH_RX_0_DP")
	)
	(segment
		(start 398.7673 -40.442388)
		(end 397.637 -39.312088)
		(width 0.1143)
		(layer "In11.Cu")
		(net "P3E_PCH_RX_0_DP")
	)
	(segment
		(start 418.921438 -81.32445)
		(end 418.921438 -70.716648)
		(width 0.1143)
		(layer "In11.Cu")
		(net "P3E_PCH_RX_0_DP")
	)
	(segment
		(start 407.329894 -51.5239)
		(end 406.17521 -50.369216)
		(width 0.1143)
		(layer "In11.Cu")
		(net "P3E_PCH_RX_0_DP")
	)
	(segment
		(start 413.07004 -54.448964)
		(end 410.144976 -51.5239)
		(width 0.1143)
		(layer "In11.Cu")
		(net "P3E_PCH_RX_0_DP")
	)
	(segment
		(start 394.062712 -125.045978)
		(end 394.161772 -125.145038)
		(width 0.0889)
		(layer "In11.Cu")
		(net "P3E_PCH_RX_0_DP")
	)
	(segment
		(start 397.637 -32.766)
		(end 397.891 -32.512)
		(width 0.1143)
		(layer "In11.Cu")
		(net "P3E_PCH_RX_0_DP")
	)
	(segment
		(start 392.949684 -127.632714)
		(end 392.7983 -127.48133)
		(width 0.0889)
		(layer "In11.Cu")
		(net "P3E_PCH_RX_0_DP")
	)
	(segment
		(start 400.718528 -43.904916)
		(end 400.718528 -42.90949)
		(width 0.1143)
		(layer "In11.Cu")
		(net "P3E_PCH_RX_0_DP")
	)
	(segment
		(start 392.7983 -125.33249)
		(end 393.084812 -125.045978)
		(width 0.0889)
		(layer "In11.Cu")
		(net "P3E_PCH_RX_0_DP")
	)
	(segment
		(start 418.704268 -90.512392)
		(end 419.110414 -90.106246)
		(width 0.1143)
		(layer "In11.Cu")
		(net "P3E_PCH_RX_0_DP")
	)
	(segment
		(start 417.9697 -95.021146)
		(end 418.704268 -94.286578)
		(width 0.1143)
		(layer "In11.Cu")
		(net "P3E_PCH_RX_0_DP")
	)
	(segment
		(start 397.891 -32.512)
		(end 397.891 -31.8516)
		(width 0.1143)
		(layer "In11.Cu")
		(net "P3E_PCH_RX_0_DP")
	)
	(segment
		(start 382.810258 -28.343352)
		(end 381.372364 -29.781246)
		(width 0.1143)
		(layer "In11.Cu")
		(net "P3E_PCH_RX_0_DP")
	)
	(segment
		(start 394.883132 -125.134878)
		(end 395.149832 -125.134878)
		(width 0.0889)
		(layer "In11.Cu")
		(net "P3E_PCH_RX_0_DP")
	)
	(segment
		(start 418.704268 -94.286578)
		(end 418.704268 -90.512392)
		(width 0.1143)
		(layer "In11.Cu")
		(net "P3E_PCH_RX_0_DP")
	)
	(segment
		(start 404.134066 -50.369216)
		(end 402.7043 -48.93945)
		(width 0.1143)
		(layer "In11.Cu")
		(net "P3E_PCH_RX_0_DP")
	)
	(segment
		(start 416.0139 -114.896646)
		(end 417.4871 -113.423446)
		(width 0.1143)
		(layer "In11.Cu")
		(net "P3E_PCH_RX_0_DP")
	)
	(segment
		(start 396.29842 -125.045978)
		(end 396.34922 -125.096778)
		(width 0.0889)
		(layer "In11.Cu")
		(net "P3E_PCH_RX_0_DP")
	)
	(segment
		(start 397.637 -39.312088)
		(end 397.637 -32.766)
		(width 0.1143)
		(layer "In11.Cu")
		(net "P3E_PCH_RX_0_DP")
	)
	(segment
		(start 393.2682 -127.381)
		(end 393.2682 -127.51054)
		(width 0.0889)
		(layer "In11.Cu")
		(net "P3E_PCH_RX_0_DP")
	)
	(segment
		(start 393.796012 -125.045978)
		(end 394.062712 -125.045978)
		(width 0.0889)
		(layer "In11.Cu")
		(net "P3E_PCH_RX_0_DP")
	)
	(segment
		(start 394.161772 -125.145038)
		(end 394.428472 -125.145038)
		(width 0.0889)
		(layer "In11.Cu")
		(net "P3E_PCH_RX_0_DP")
	)
	(segment
		(start 416.0139 -117.008656)
		(end 416.0139 -114.896646)
		(width 0.1143)
		(layer "In11.Cu")
		(net "P3E_PCH_RX_0_DP")
	)
	(segment
		(start 418.626798 -81.61909)
		(end 418.921438 -81.32445)
		(width 0.1143)
		(layer "In11.Cu")
		(net "P3E_PCH_RX_0_DP")
	)
	(segment
		(start 397.891 -31.8516)
		(end 397.4973 -31.4579)
		(width 0.1143)
		(layer "In11.Cu")
		(net "P3E_PCH_RX_0_DP")
	)
	(segment
		(start 393.440412 -125.134878)
		(end 393.707112 -125.134878)
		(width 0.0889)
		(layer "In11.Cu")
		(net "P3E_PCH_RX_0_DP")
	)
	(segment
		(start 383.032 -25.786588)
		(end 382.810258 -26.00833)
		(width 0.1143)
		(layer "In11.Cu")
		(net "P3E_PCH_RX_0_DP")
	)
	(segment
		(start 393.084812 -125.045978)
		(end 393.351512 -125.045978)
		(width 0.0889)
		(layer "In11.Cu")
		(net "P3E_PCH_RX_0_DP")
	)
	(segment
		(start 418.3126 -58.628788)
		(end 414.132776 -54.448964)
		(width 0.1143)
		(layer "In11.Cu")
		(net "P3E_PCH_RX_0_DP")
	)
	(segment
		(start 395.505432 -125.045978)
		(end 395.594332 -125.134878)
		(width 0.0889)
		(layer "In11.Cu")
		(net "P3E_PCH_RX_0_DP")
	)
	(segment
		(start 402.7043 -45.890688)
		(end 400.718528 -43.904916)
		(width 0.1143)
		(layer "In11.Cu")
		(net "P3E_PCH_RX_0_DP")
	)
	(segment
		(start 402.325332 -122.5042)
		(end 409.306776 -122.5042)
		(width 0.1143)
		(layer "In11.Cu")
		(net "P3E_PCH_RX_0_DP")
	)
	(segment
		(start 410.144976 -51.5239)
		(end 407.329894 -51.5239)
		(width 0.1143)
		(layer "In11.Cu")
		(net "P3E_PCH_RX_0_DP")
	)
	(segment
		(start 395.861032 -125.134878)
		(end 395.949932 -125.045978)
		(width 0.0889)
		(layer "In11.Cu")
		(net "P3E_PCH_RX_0_DP")
	)
	(segment
		(start 392.7983 -126.701042)
		(end 392.8872 -126.612142)
		(width 0.0889)
		(layer "In11.Cu")
		(net "P3E_PCH_RX_0_DP")
	)
	(segment
		(start 381.372364 -29.781246)
		(end 380.3142 -29.781246)
		(width 0.1143)
		(layer "In11.Cu")
		(net "P3E_PCH_RX_0_DP")
	)
	(segment
		(start 418.921438 -70.716648)
		(end 418.430456 -70.225666)
		(width 0.1143)
		(layer "In11.Cu")
		(net "P3E_PCH_RX_0_DP")
	)
	(segment
		(start 413.274256 -119.181372)
		(end 414.409128 -118.0465)
		(width 0.1143)
		(layer "In11.Cu")
		(net "P3E_PCH_RX_0_DP")
	)
	(segment
		(start 394.794232 -125.045978)
		(end 394.883132 -125.134878)
		(width 0.0889)
		(layer "In11.Cu")
		(net "P3E_PCH_RX_0_DP")
	)
	(segment
		(start 414.976056 -118.0465)
		(end 416.0139 -117.008656)
		(width 0.1143)
		(layer "In11.Cu")
		(net "P3E_PCH_RX_0_DP")
	)
	(segment
		(start 418.626798 -85.30336)
		(end 418.626798 -81.61909)
		(width 0.1143)
		(layer "In11.Cu")
		(net "P3E_PCH_RX_0_DP")
	)
	(segment
		(start 394.428472 -125.145038)
		(end 394.527532 -125.045978)
		(width 0.0889)
		(layer "In11.Cu")
		(net "P3E_PCH_RX_0_DP")
	)
	(segment
		(start 418.430202 -70.225666)
		(end 418.3126 -70.108064)
		(width 0.1143)
		(layer "In11.Cu")
		(net "P3E_PCH_RX_0_DP")
	)
	(segment
		(start 392.7983 -127.48133)
		(end 392.7983 -126.701042)
		(width 0.0889)
		(layer "In11.Cu")
		(net "P3E_PCH_RX_0_DP")
	)
	(segment
		(start 396.371318 -125.096778)
		(end 399.732754 -125.096778)
		(width 0.1143)
		(layer "In11.Cu")
		(net "P3E_PCH_RX_0_DP")
	)
	(segment
		(start 414.409128 -118.0465)
		(end 414.976056 -118.0465)
		(width 0.1143)
		(layer "In11.Cu")
		(net "P3E_PCH_RX_0_DP")
	)
	(segment
		(start 392.8872 -125.634242)
		(end 392.7983 -125.545342)
		(width 0.0889)
		(layer "In11.Cu")
		(net "P3E_PCH_RX_0_DP")
	)
	(segment
		(start 391.648696 -19.179286)
		(end 384.843782 -19.179286)
		(width 0.1143)
		(layer "In11.Cu")
		(net "P3E_PCH_RX_0_DP")
	)
	(segment
		(start 417.9697 -108.782358)
		(end 417.9697 -95.021146)
		(width 0.1143)
		(layer "In11.Cu")
		(net "P3E_PCH_RX_0_DP")
	)
	(segment
		(start 396.554198 -24.084788)
		(end 391.648696 -19.179286)
		(width 0.1143)
		(layer "In11.Cu")
		(net "P3E_PCH_RX_0_DP")
	)
	(segment
		(start 402.7043 -48.93945)
		(end 402.7043 -45.890688)
		(width 0.1143)
		(layer "In11.Cu")
		(net "P3E_PCH_RX_0_DP")
	)
	(segment
		(start 418.430456 -70.225666)
		(end 418.430202 -70.225666)
		(width 0.1143)
		(layer "In11.Cu")
		(net "P3E_PCH_RX_0_DP")
	)
	(segment
		(start 418.3126 -70.108064)
		(end 418.3126 -58.628788)
		(width 0.1143)
		(layer "In11.Cu")
		(net "P3E_PCH_RX_0_DP")
	)
	(segment
		(start 382.810258 -26.00833)
		(end 382.810258 -28.343352)
		(width 0.1143)
		(layer "In11.Cu")
		(net "P3E_PCH_RX_0_DP")
	)
	(segment
		(start 396.554198 -29.371798)
		(end 396.554198 -24.084788)
		(width 0.1143)
		(layer "In11.Cu")
		(net "P3E_PCH_RX_0_DP")
	)
	(segment
		(start 393.146026 -127.632714)
		(end 392.949684 -127.632714)
		(width 0.0889)
		(layer "In11.Cu")
		(net "P3E_PCH_RX_0_DP")
	)
	(segment
		(start 392.784076 -128.052576)
		(end 392.8872 -128.1557)
		(width 0.0889)
		(layer "F.Cu")
		(net "P3E_PCH_RX_0_DN")
	)
	(segment
		(start 392.66876 -126.578106)
		(end 392.66876 -127.470154)
		(width 0.0889)
		(layer "F.Cu")
		(net "P3E_PCH_RX_0_DN")
	)
	(segment
		(start 392.503152 -126.412498)
		(end 392.66876 -126.578106)
		(width 0.0889)
		(layer "F.Cu")
		(net "P3E_PCH_RX_0_DN")
	)
	(segment
		(start 392.8872 -128.1557)
		(end 393.1285 -128.1557)
		(width 0.0889)
		(layer "F.Cu")
		(net "P3E_PCH_RX_0_DN")
	)
	(segment
		(start 393.1285 -128.1557)
		(end 393.2682 -128.016)
		(width 0.0889)
		(layer "F.Cu")
		(net "P3E_PCH_RX_0_DN")
	)
	(segment
		(start 392.784076 -127.58547)
		(end 392.784076 -128.052576)
		(width 0.0889)
		(layer "F.Cu")
		(net "P3E_PCH_RX_0_DN")
	)
	(segment
		(start 392.66876 -127.470154)
		(end 392.784076 -127.58547)
		(width 0.0889)
		(layer "F.Cu")
		(net "P3E_PCH_RX_0_DN")
	)
	(segment
		(start 392.485118 -125.750066)
		(end 392.503152 -125.7681)
		(width 0.0889)
		(layer "F.Cu")
		(net "P3E_PCH_RX_0_DN")
	)
	(segment
		(start 392.503152 -125.7681)
		(end 392.503152 -126.412498)
		(width 0.0889)
		(layer "F.Cu")
		(net "P3E_PCH_RX_0_DN")
	)
	(segment
		(start 379.2982 -30.629352)
		(end 380.168404 -30.629352)
		(width 0.1143)
		(layer "F.Cu")
		(net "P3E_PCH_RX_0_DN")
	)
	(via
		(at 380.168404 -30.629352)
		(size 0.508)
		(drill 0.254)
		(layers "F.Cu" "B.Cu")
		(net "P3E_PCH_RX_0_DN")
	)
	(via
		(at 393.2682 -128.016)
		(size 0.508)
		(drill 0.254)
		(layers "F.Cu" "B.Cu")
		(net "P3E_PCH_RX_0_DN")
	)
	(segment
		(start 397.2052 -31.579058)
		(end 397.2052 -30.436058)
		(width 0.1143)
		(layer "In11.Cu")
		(net "P3E_PCH_RX_0_DN")
	)
	(segment
		(start 411.489398 -121.460006)
		(end 412.982156 -119.967248)
		(width 0.1143)
		(layer "In11.Cu")
		(net "P3E_PCH_RX_0_DN")
	)
	(segment
		(start 395.201394 -23.378922)
		(end 394.959078 -23.136352)
		(width 0.1143)
		(layer "In11.Cu")
		(net "P3E_PCH_RX_0_DN")
	)
	(segment
		(start 380.385574 -30.073346)
		(end 380.27483 -30.185868)
		(width 0.1143)
		(layer "In11.Cu")
		(net "P3E_PCH_RX_0_DN")
	)
	(segment
		(start 400.426428 -43.030648)
		(end 398.4752 -41.07942)
		(width 0.1143)
		(layer "In11.Cu")
		(net "P3E_PCH_RX_0_DN")
	)
	(segment
		(start 402.4122 -46.011846)
		(end 400.426428 -44.026074)
		(width 0.1143)
		(layer "In11.Cu")
		(net "P3E_PCH_RX_0_DN")
	)
	(segment
		(start 408.236166 -122.047)
		(end 408.401266 -122.2121)
		(width 0.1143)
		(layer "In11.Cu")
		(net "P3E_PCH_RX_0_DN")
	)
	(segment
		(start 394.483082 -22.660356)
		(end 394.240766 -22.41804)
		(width 0.1143)
		(layer "In11.Cu")
		(net "P3E_PCH_RX_0_DN")
	)
	(segment
		(start 407.208736 -51.816)
		(end 406.054052 -50.661316)
		(width 0.1143)
		(layer "In11.Cu")
		(net "P3E_PCH_RX_0_DN")
	)
	(segment
		(start 407.893266 -122.047)
		(end 408.236166 -122.047)
		(width 0.1143)
		(layer "In11.Cu")
		(net "P3E_PCH_RX_0_DN")
	)
	(segment
		(start 400.426428 -44.026074)
		(end 400.426428 -43.030648)
		(width 0.1143)
		(layer "In11.Cu")
		(net "P3E_PCH_RX_0_DN")
	)
	(segment
		(start 393.2682 -128.016)
		(end 393.14628 -127.89408)
		(width 0.0889)
		(layer "In11.Cu")
		(net "P3E_PCH_RX_0_DN")
	)
	(segment
		(start 417.6776 -102.80269)
		(end 417.5125 -102.63759)
		(width 0.1143)
		(layer "In11.Cu")
		(net "P3E_PCH_RX_0_DN")
	)
	(segment
		(start 394.959078 -22.902926)
		(end 394.716508 -22.660356)
		(width 0.1143)
		(layer "In11.Cu")
		(net "P3E_PCH_RX_0_DN")
	)
	(segment
		(start 396.29842 -124.855478)
		(end 396.34922 -124.804678)
		(width 0.0889)
		(layer "In11.Cu")
		(net "P3E_PCH_RX_0_DN")
	)
	(segment
		(start 406.054052 -50.661316)
		(end 404.012908 -50.661316)
		(width 0.1143)
		(layer "In11.Cu")
		(net "P3E_PCH_RX_0_DN")
	)
	(segment
		(start 418.412168 -94.16542)
		(end 418.412168 -90.391234)
		(width 0.1143)
		(layer "In11.Cu")
		(net "P3E_PCH_RX_0_DN")
	)
	(segment
		(start 418.334698 -81.497932)
		(end 418.629338 -81.203292)
		(width 0.1143)
		(layer "In11.Cu")
		(net "P3E_PCH_RX_0_DN")
	)
	(segment
		(start 417.6776 -100.77069)
		(end 417.5125 -100.60559)
		(width 0.1143)
		(layer "In11.Cu")
		(net "P3E_PCH_RX_0_DN")
	)
	(segment
		(start 414.28797 -117.7544)
		(end 414.854898 -117.7544)
		(width 0.1143)
		(layer "In11.Cu")
		(net "P3E_PCH_RX_0_DN")
	)
	(segment
		(start 417.6776 -102.12959)
		(end 417.6776 -101.78669)
		(width 0.1143)
		(layer "In11.Cu")
		(net "P3E_PCH_RX_0_DN")
	)
	(segment
		(start 418.629338 -70.837806)
		(end 418.0205 -70.229222)
		(width 0.1143)
		(layer "In11.Cu")
		(net "P3E_PCH_RX_0_DN")
	)
	(segment
		(start 396.262098 -29.492956)
		(end 396.262098 -24.205946)
		(width 0.1143)
		(layer "In11.Cu")
		(net "P3E_PCH_RX_0_DN")
	)
	(segment
		(start 394.240766 -22.41804)
		(end 394.240766 -22.184614)
		(width 0.1143)
		(layer "In11.Cu")
		(net "P3E_PCH_RX_0_DN")
	)
	(segment
		(start 417.6776 -108.6612)
		(end 417.6776 -102.80269)
		(width 0.1143)
		(layer "In11.Cu")
		(net "P3E_PCH_RX_0_DN")
	)
	(segment
		(start 417.5125 -99.58959)
		(end 417.5125 -99.24669)
		(width 0.1143)
		(layer "In11.Cu")
		(net "P3E_PCH_RX_0_DN")
	)
	(segment
		(start 394.716508 -22.660356)
		(end 394.483082 -22.660356)
		(width 0.1143)
		(layer "In11.Cu")
		(net "P3E_PCH_RX_0_DN")
	)
	(segment
		(start 418.818314 -89.985088)
		(end 418.818314 -85.908134)
		(width 0.1143)
		(layer "In11.Cu")
		(net "P3E_PCH_RX_0_DN")
	)
	(segment
		(start 412.982156 -119.060214)
		(end 414.28797 -117.7544)
		(width 0.1143)
		(layer "In11.Cu")
		(net "P3E_PCH_RX_0_DN")
	)
	(segment
		(start 417.5125 -99.24669)
		(end 417.6776 -99.08159)
		(width 0.1143)
		(layer "In11.Cu")
		(net "P3E_PCH_RX_0_DN")
	)
	(segment
		(start 417.195 -109.1438)
		(end 417.6776 -108.6612)
		(width 0.1143)
		(layer "In11.Cu")
		(net "P3E_PCH_RX_0_DN")
	)
	(segment
		(start 417.195 -113.302288)
		(end 417.195 -112.36833)
		(width 0.1143)
		(layer "In11.Cu")
		(net "P3E_PCH_RX_0_DN")
	)
	(segment
		(start 414.011618 -54.741064)
		(end 412.948882 -54.741064)
		(width 0.1143)
		(layer "In11.Cu")
		(net "P3E_PCH_RX_0_DN")
	)
	(segment
		(start 383.102358 -26.129488)
		(end 383.102358 -28.46451)
		(width 0.1143)
		(layer "In11.Cu")
		(net "P3E_PCH_RX_0_DN")
	)
	(segment
		(start 415.7218 -116.887498)
		(end 415.7218 -114.775488)
		(width 0.1143)
		(layer "In11.Cu")
		(net "P3E_PCH_RX_0_DN")
	)
	(segment
		(start 392.941556 -127.89408)
		(end 392.6078 -127.560324)
		(width 0.0889)
		(layer "In11.Cu")
		(net "P3E_PCH_RX_0_DN")
	)
	(segment
		(start 415.7218 -114.775488)
		(end 417.195 -113.302288)
		(width 0.1143)
		(layer "In11.Cu")
		(net "P3E_PCH_RX_0_DN")
	)
	(segment
		(start 398.4752 -41.07942)
		(end 398.4752 -40.563546)
		(width 0.1143)
		(layer "In11.Cu")
		(net "P3E_PCH_RX_0_DN")
	)
	(segment
		(start 408.401266 -122.2121)
		(end 409.185618 -122.2121)
		(width 0.1143)
		(layer "In11.Cu")
		(net "P3E_PCH_RX_0_DN")
	)
	(segment
		(start 418.0205 -58.749946)
		(end 414.011618 -54.741064)
		(width 0.1143)
		(layer "In11.Cu")
		(net "P3E_PCH_RX_0_DN")
	)
	(segment
		(start 412.948882 -54.741064)
		(end 410.023818 -51.816)
		(width 0.1143)
		(layer "In11.Cu")
		(net "P3E_PCH_RX_0_DN")
	)
	(segment
		(start 417.5125 -102.63759)
		(end 417.5125 -102.29469)
		(width 0.1143)
		(layer "In11.Cu")
		(net "P3E_PCH_RX_0_DN")
	)
	(segment
		(start 381.493522 -30.073346)
		(end 380.385574 -30.073346)
		(width 0.1143)
		(layer "In11.Cu")
		(net "P3E_PCH_RX_0_DN")
	)
	(segment
		(start 397.2052 -30.436058)
		(end 396.262098 -29.492956)
		(width 0.1143)
		(layer "In11.Cu")
		(net "P3E_PCH_RX_0_DN")
	)
	(segment
		(start 409.185618 -122.2121)
		(end 409.937712 -121.460006)
		(width 0.1143)
		(layer "In11.Cu")
		(net "P3E_PCH_RX_0_DN")
	)
	(segment
		(start 417.195 -111.69523)
		(end 417.195 -109.1438)
		(width 0.1143)
		(layer "In11.Cu")
		(net "P3E_PCH_RX_0_DN")
	)
	(segment
		(start 410.023818 -51.816)
		(end 407.208736 -51.816)
		(width 0.1143)
		(layer "In11.Cu")
		(net "P3E_PCH_RX_0_DN")
	)
	(segment
		(start 399.611596 -124.804678)
		(end 402.204174 -122.2121)
		(width 0.1143)
		(layer "In11.Cu")
		(net "P3E_PCH_RX_0_DN")
	)
	(segment
		(start 417.5125 -100.60559)
		(end 417.5125 -100.26269)
		(width 0.1143)
		(layer "In11.Cu")
		(net "P3E_PCH_RX_0_DN")
	)
	(segment
		(start 397.3449 -32.644842)
		(end 397.5989 -32.390842)
		(width 0.1143)
		(layer "In11.Cu")
		(net "P3E_PCH_RX_0_DN")
	)
	(segment
		(start 418.412168 -90.391234)
		(end 418.818314 -89.985088)
		(width 0.1143)
		(layer "In11.Cu")
		(net "P3E_PCH_RX_0_DN")
	)
	(segment
		(start 394.240766 -22.184614)
		(end 391.527538 -19.471386)
		(width 0.1143)
		(layer "In11.Cu")
		(net "P3E_PCH_RX_0_DN")
	)
	(segment
		(start 414.854898 -117.7544)
		(end 415.7218 -116.887498)
		(width 0.1143)
		(layer "In11.Cu")
		(net "P3E_PCH_RX_0_DN")
	)
	(segment
		(start 396.34922 -124.804678)
		(end 396.371318 -124.804678)
		(width 0.0889)
		(layer "In11.Cu")
		(net "P3E_PCH_RX_0_DN")
	)
	(segment
		(start 418.0205 -70.229222)
		(end 418.0205 -58.749946)
		(width 0.1143)
		(layer "In11.Cu")
		(net "P3E_PCH_RX_0_DN")
	)
	(segment
		(start 417.0299 -111.86033)
		(end 417.195 -111.69523)
		(width 0.1143)
		(layer "In11.Cu")
		(net "P3E_PCH_RX_0_DN")
	)
	(segment
		(start 417.0299 -112.20323)
		(end 417.0299 -111.86033)
		(width 0.1143)
		(layer "In11.Cu")
		(net "P3E_PCH_RX_0_DN")
	)
	(segment
		(start 397.3449 -39.433246)
		(end 397.3449 -32.644842)
		(width 0.1143)
		(layer "In11.Cu")
		(net "P3E_PCH_RX_0_DN")
	)
	(segment
		(start 417.6776 -100.09759)
		(end 417.6776 -99.75469)
		(width 0.1143)
		(layer "In11.Cu")
		(net "P3E_PCH_RX_0_DN")
	)
	(segment
		(start 412.982156 -119.967248)
		(end 412.982156 -119.060214)
		(width 0.1143)
		(layer "In11.Cu")
		(net "P3E_PCH_RX_0_DN")
	)
	(segment
		(start 418.629338 -81.203292)
		(end 418.629338 -70.837806)
		(width 0.1143)
		(layer "In11.Cu")
		(net "P3E_PCH_RX_0_DN")
	)
	(segment
		(start 417.6776 -99.08159)
		(end 417.6776 -94.899988)
		(width 0.1143)
		(layer "In11.Cu")
		(net "P3E_PCH_RX_0_DN")
	)
	(segment
		(start 396.262098 -24.205946)
		(end 395.435074 -23.378922)
		(width 0.1143)
		(layer "In11.Cu")
		(net "P3E_PCH_RX_0_DN")
	)
	(segment
		(start 383.102358 -28.46451)
		(end 381.493522 -30.073346)
		(width 0.1143)
		(layer "In11.Cu")
		(net "P3E_PCH_RX_0_DN")
	)
	(segment
		(start 417.5125 -100.26269)
		(end 417.6776 -100.09759)
		(width 0.1143)
		(layer "In11.Cu")
		(net "P3E_PCH_RX_0_DN")
	)
	(segment
		(start 380.27483 -30.185868)
		(end 380.168404 -30.292294)
		(width 0.1143)
		(layer "In11.Cu")
		(net "P3E_PCH_RX_0_DN")
	)
	(segment
		(start 393.005818 -124.855478)
		(end 396.29842 -124.855478)
		(width 0.0889)
		(layer "In11.Cu")
		(net "P3E_PCH_RX_0_DN")
	)
	(segment
		(start 417.6776 -101.78669)
		(end 417.5125 -101.62159)
		(width 0.1143)
		(layer "In11.Cu")
		(net "P3E_PCH_RX_0_DN")
	)
	(segment
		(start 417.5125 -102.29469)
		(end 417.6776 -102.12959)
		(width 0.1143)
		(layer "In11.Cu")
		(net "P3E_PCH_RX_0_DN")
	)
	(segment
		(start 398.4752 -40.563546)
		(end 397.3449 -39.433246)
		(width 0.1143)
		(layer "In11.Cu")
		(net "P3E_PCH_RX_0_DN")
	)
	(segment
		(start 397.5989 -31.972758)
		(end 397.2052 -31.579058)
		(width 0.1143)
		(layer "In11.Cu")
		(net "P3E_PCH_RX_0_DN")
	)
	(segment
		(start 417.5125 -101.27869)
		(end 417.6776 -101.11359)
		(width 0.1143)
		(layer "In11.Cu")
		(net "P3E_PCH_RX_0_DN")
	)
	(segment
		(start 417.6776 -101.11359)
		(end 417.6776 -100.77069)
		(width 0.1143)
		(layer "In11.Cu")
		(net "P3E_PCH_RX_0_DN")
	)
	(segment
		(start 417.5125 -101.62159)
		(end 417.5125 -101.27869)
		(width 0.1143)
		(layer "In11.Cu")
		(net "P3E_PCH_RX_0_DN")
	)
	(segment
		(start 402.204174 -122.2121)
		(end 407.728166 -122.2121)
		(width 0.1143)
		(layer "In11.Cu")
		(net "P3E_PCH_RX_0_DN")
	)
	(segment
		(start 417.6776 -94.899988)
		(end 418.412168 -94.16542)
		(width 0.1143)
		(layer "In11.Cu")
		(net "P3E_PCH_RX_0_DN")
	)
	(segment
		(start 409.937712 -121.460006)
		(end 411.489398 -121.460006)
		(width 0.1143)
		(layer "In11.Cu")
		(net "P3E_PCH_RX_0_DN")
	)
	(segment
		(start 394.959078 -23.136352)
		(end 394.959078 -22.902926)
		(width 0.1143)
		(layer "In11.Cu")
		(net "P3E_PCH_RX_0_DN")
	)
	(segment
		(start 393.14628 -127.89408)
		(end 392.941556 -127.89408)
		(width 0.0889)
		(layer "In11.Cu")
		(net "P3E_PCH_RX_0_DN")
	)
	(segment
		(start 383.3241 -21.112226)
		(end 383.3241 -25.907746)
		(width 0.1143)
		(layer "In11.Cu")
		(net "P3E_PCH_RX_0_DN")
	)
	(segment
		(start 397.5989 -32.390842)
		(end 397.5989 -31.972758)
		(width 0.1143)
		(layer "In11.Cu")
		(net "P3E_PCH_RX_0_DN")
	)
	(segment
		(start 418.334698 -85.424518)
		(end 418.334698 -81.497932)
		(width 0.1143)
		(layer "In11.Cu")
		(net "P3E_PCH_RX_0_DN")
	)
	(segment
		(start 392.6078 -127.560324)
		(end 392.6078 -125.253496)
		(width 0.0889)
		(layer "In11.Cu")
		(net "P3E_PCH_RX_0_DN")
	)
	(segment
		(start 404.012908 -50.661316)
		(end 402.4122 -49.060608)
		(width 0.1143)
		(layer "In11.Cu")
		(net "P3E_PCH_RX_0_DN")
	)
	(segment
		(start 395.435074 -23.378922)
		(end 395.201394 -23.378922)
		(width 0.1143)
		(layer "In11.Cu")
		(net "P3E_PCH_RX_0_DN")
	)
	(segment
		(start 407.728166 -122.2121)
		(end 407.893266 -122.047)
		(width 0.1143)
		(layer "In11.Cu")
		(net "P3E_PCH_RX_0_DN")
	)
	(segment
		(start 380.168404 -30.292294)
		(end 380.168404 -30.629352)
		(width 0.1143)
		(layer "In11.Cu")
		(net "P3E_PCH_RX_0_DN")
	)
	(segment
		(start 418.818314 -85.908134)
		(end 418.334698 -85.424518)
		(width 0.1143)
		(layer "In11.Cu")
		(net "P3E_PCH_RX_0_DN")
	)
	(segment
		(start 391.527538 -19.471386)
		(end 384.96494 -19.471386)
		(width 0.1143)
		(layer "In11.Cu")
		(net "P3E_PCH_RX_0_DN")
	)
	(segment
		(start 392.6078 -125.253496)
		(end 393.005818 -124.855478)
		(width 0.0889)
		(layer "In11.Cu")
		(net "P3E_PCH_RX_0_DN")
	)
	(segment
		(start 396.371318 -124.804678)
		(end 399.611596 -124.804678)
		(width 0.1143)
		(layer "In11.Cu")
		(net "P3E_PCH_RX_0_DN")
	)
	(segment
		(start 383.3241 -25.907746)
		(end 383.102358 -26.129488)
		(width 0.1143)
		(layer "In11.Cu")
		(net "P3E_PCH_RX_0_DN")
	)
	(segment
		(start 417.195 -112.36833)
		(end 417.0299 -112.20323)
		(width 0.1143)
		(layer "In11.Cu")
		(net "P3E_PCH_RX_0_DN")
	)
	(segment
		(start 384.96494 -19.471386)
		(end 383.3241 -21.112226)
		(width 0.1143)
		(layer "In11.Cu")
		(net "P3E_PCH_RX_0_DN")
	)
	(segment
		(start 402.4122 -49.060608)
		(end 402.4122 -46.011846)
		(width 0.1143)
		(layer "In11.Cu")
		(net "P3E_PCH_RX_0_DN")
	)
	(segment
		(start 417.6776 -99.75469)
		(end 417.5125 -99.58959)
		(width 0.1143)
		(layer "In11.Cu")
		(net "P3E_PCH_RX_0_DN")
	)
	(segment
		(start 396.65275 -121.01576)
		(end 397.14805 -121.245884)
		(width 0.1143)
		(layer "F.Cu")
		(net "P3E_PCH_M2_TX_DP<3>")
	)
	(via
		(at 397.14805 -121.245884)
		(size 0.508)
		(drill 0.254)
		(layers "F.Cu" "B.Cu")
		(net "P3E_PCH_M2_TX_DP<3>")
	)
	(via
		(at 387.792976 -24.95931)
		(size 0.508)
		(drill 0.254)
		(layers "F.Cu" "B.Cu")
		(net "P3E_PCH_M2_TX_DP<3>")
	)
	(segment
		(start 386.106924 -24.885904)
		(end 386.468874 -24.523954)
		(width 0.1143)
		(layer "B.Cu")
		(net "P3E_PCH_M2_TX_DP<3>")
	)
	(segment
		(start 386.468874 -24.523954)
		(end 387.35762 -24.523954)
		(width 0.1143)
		(layer "B.Cu")
		(net "P3E_PCH_M2_TX_DP<3>")
	)
	(segment
		(start 387.35762 -24.523954)
		(end 387.792976 -24.95931)
		(width 0.1143)
		(layer "B.Cu")
		(net "P3E_PCH_M2_TX_DP<3>")
	)
	(segment
		(start 407.98369 -113.502694)
		(end 407.750264 -113.502694)
		(width 0.1143)
		(layer "In11.Cu")
		(net "P3E_PCH_M2_TX_DP<3>")
	)
	(segment
		(start 406.455118 -114.79784)
		(end 405.636984 -114.79784)
		(width 0.1143)
		(layer "In11.Cu")
		(net "P3E_PCH_M2_TX_DP<3>")
	)
	(segment
		(start 390.306814 -39.396416)
		(end 390.306814 -40.05961)
		(width 0.1143)
		(layer "In11.Cu")
		(net "P3E_PCH_M2_TX_DP<3>")
	)
	(segment
		(start 410.353764 -68.956682)
		(end 410.353764 -70.24878)
		(width 0.1143)
		(layer "In11.Cu")
		(net "P3E_PCH_M2_TX_DP<3>")
	)
	(segment
		(start 405.636984 -114.79784)
		(end 404.422864 -116.01196)
		(width 0.1143)
		(layer "In11.Cu")
		(net "P3E_PCH_M2_TX_DP<3>")
	)
	(segment
		(start 410.86405 -96.819974)
		(end 411.3911 -97.347024)
		(width 0.1143)
		(layer "In11.Cu")
		(net "P3E_PCH_M2_TX_DP<3>")
	)
	(segment
		(start 410.3243 -66.429382)
		(end 410.6926 -66.797682)
		(width 0.1143)
		(layer "In11.Cu")
		(net "P3E_PCH_M2_TX_DP<3>")
	)
	(segment
		(start 403.472904 -117.707918)
		(end 403.081998 -118.098824)
		(width 0.0889)
		(layer "In11.Cu")
		(net "P3E_PCH_M2_TX_DP<3>")
	)
	(segment
		(start 386.45846 -31.671006)
		(end 386.939028 -32.151574)
		(width 0.1143)
		(layer "In11.Cu")
		(net "P3E_PCH_M2_TX_DP<3>")
	)
	(segment
		(start 399.9611 -120.24868)
		(end 399.364454 -120.845326)
		(width 0.0889)
		(layer "In11.Cu")
		(net "P3E_PCH_M2_TX_DP<3>")
	)
	(segment
		(start 401.289012 -118.098824)
		(end 400.951954 -118.435882)
		(width 0.0889)
		(layer "In11.Cu")
		(net "P3E_PCH_M2_TX_DP<3>")
	)
	(segment
		(start 413.7533 -79.133446)
		(end 409.744164 -83.142582)
		(width 0.1143)
		(layer "In11.Cu")
		(net "P3E_PCH_M2_TX_DP<3>")
	)
	(segment
		(start 397.55826 -52.50815)
		(end 402.9837 -57.93359)
		(width 0.1143)
		(layer "In11.Cu")
		(net "P3E_PCH_M2_TX_DP<3>")
	)
	(segment
		(start 408.22626 -113.026698)
		(end 408.22626 -113.260124)
		(width 0.1143)
		(layer "In11.Cu")
		(net "P3E_PCH_M2_TX_DP<3>")
	)
	(segment
		(start 404.422864 -116.01196)
		(end 404.422864 -116.82984)
		(width 0.1143)
		(layer "In11.Cu")
		(net "P3E_PCH_M2_TX_DP<3>")
	)
	(segment
		(start 387.792976 -24.58466)
		(end 387.678676 -24.47036)
		(width 0.1143)
		(layer "In11.Cu")
		(net "P3E_PCH_M2_TX_DP<3>")
	)
	(segment
		(start 410.3243 -61.078364)
		(end 410.3243 -66.429382)
		(width 0.1143)
		(layer "In11.Cu")
		(net "P3E_PCH_M2_TX_DP<3>")
	)
	(segment
		(start 391.210292 -43.651678)
		(end 391.306558 -43.796712)
		(width 0.1143)
		(layer "In11.Cu")
		(net "P3E_PCH_M2_TX_DP<3>")
	)
	(segment
		(start 394.590778 -47.081186)
		(end 395.959838 -47.081186)
		(width 0.1143)
		(layer "In11.Cu")
		(net "P3E_PCH_M2_TX_DP<3>")
	)
	(segment
		(start 402.9837 -57.93359)
		(end 407.179526 -57.93359)
		(width 0.1143)
		(layer "In11.Cu")
		(net "P3E_PCH_M2_TX_DP<3>")
	)
	(segment
		(start 407.179526 -57.93359)
		(end 410.3243 -61.078364)
		(width 0.1143)
		(layer "In11.Cu")
		(net "P3E_PCH_M2_TX_DP<3>")
	)
	(segment
		(start 396.809976 -121.245884)
		(end 397.14805 -121.245884)
		(width 0.0889)
		(layer "In11.Cu")
		(net "P3E_PCH_M2_TX_DP<3>")
	)
	(segment
		(start 386.540756 -35.630358)
		(end 390.306814 -39.396416)
		(width 0.1143)
		(layer "In11.Cu")
		(net "P3E_PCH_M2_TX_DP<3>")
	)
	(segment
		(start 409.744164 -88.166956)
		(end 410.86405 -89.286842)
		(width 0.1143)
		(layer "In11.Cu")
		(net "P3E_PCH_M2_TX_DP<3>")
	)
	(segment
		(start 390.306814 -40.05961)
		(end 391.210292 -40.963088)
		(width 0.1143)
		(layer "In11.Cu")
		(net "P3E_PCH_M2_TX_DP<3>")
	)
	(segment
		(start 407.750264 -113.502694)
		(end 407.507694 -113.745264)
		(width 0.1143)
		(layer "In11.Cu")
		(net "P3E_PCH_M2_TX_DP<3>")
	)
	(segment
		(start 387.678676 -24.47036)
		(end 386.656326 -24.47036)
		(width 0.1143)
		(layer "In11.Cu")
		(net "P3E_PCH_M2_TX_DP<3>")
	)
	(segment
		(start 399.9611 -119.426736)
		(end 399.9611 -120.24868)
		(width 0.0889)
		(layer "In11.Cu")
		(net "P3E_PCH_M2_TX_DP<3>")
	)
	(segment
		(start 407.265378 -114.235484)
		(end 407.017474 -114.235484)
		(width 0.1143)
		(layer "In11.Cu")
		(net "P3E_PCH_M2_TX_DP<3>")
	)
	(segment
		(start 386.939028 -32.151574)
		(end 386.939028 -33.378902)
		(width 0.1143)
		(layer "In11.Cu")
		(net "P3E_PCH_M2_TX_DP<3>")
	)
	(segment
		(start 387.792976 -24.95931)
		(end 387.792976 -24.58466)
		(width 0.1143)
		(layer "In11.Cu")
		(net "P3E_PCH_M2_TX_DP<3>")
	)
	(segment
		(start 400.951954 -118.435882)
		(end 400.951954 -118.575836)
		(width 0.0889)
		(layer "In11.Cu")
		(net "P3E_PCH_M2_TX_DP<3>")
	)
	(segment
		(start 410.457396 -107.597702)
		(end 409.687014 -108.368084)
		(width 0.1143)
		(layer "In11.Cu")
		(net "P3E_PCH_M2_TX_DP<3>")
	)
	(segment
		(start 409.744164 -83.142582)
		(end 409.744164 -88.166956)
		(width 0.1143)
		(layer "In11.Cu")
		(net "P3E_PCH_M2_TX_DP<3>")
	)
	(segment
		(start 386.656326 -24.47036)
		(end 386.45846 -24.668226)
		(width 0.1143)
		(layer "In11.Cu")
		(net "P3E_PCH_M2_TX_DP<3>")
	)
	(segment
		(start 403.544786 -117.707918)
		(end 403.472904 -117.707918)
		(width 0.0889)
		(layer "In11.Cu")
		(net "P3E_PCH_M2_TX_DP<3>")
	)
	(segment
		(start 399.364454 -120.845326)
		(end 399.129504 -120.845326)
		(width 0.0889)
		(layer "In11.Cu")
		(net "P3E_PCH_M2_TX_DP<3>")
	)
	(segment
		(start 386.939028 -33.378902)
		(end 386.540756 -33.777174)
		(width 0.1143)
		(layer "In11.Cu")
		(net "P3E_PCH_M2_TX_DP<3>")
	)
	(segment
		(start 410.457396 -102.611174)
		(end 410.457396 -107.597702)
		(width 0.1143)
		(layer "In11.Cu")
		(net "P3E_PCH_M2_TX_DP<3>")
	)
	(segment
		(start 407.507694 -113.992914)
		(end 407.265378 -114.235484)
		(width 0.1143)
		(layer "In11.Cu")
		(net "P3E_PCH_M2_TX_DP<3>")
	)
	(segment
		(start 403.081998 -118.098824)
		(end 401.289012 -118.098824)
		(width 0.0889)
		(layer "In11.Cu")
		(net "P3E_PCH_M2_TX_DP<3>")
	)
	(segment
		(start 396.752064 -121.187972)
		(end 396.809976 -121.245884)
		(width 0.0889)
		(layer "In11.Cu")
		(net "P3E_PCH_M2_TX_DP<3>")
	)
	(segment
		(start 409.448762 -108.368084)
		(end 408.87015 -108.946696)
		(width 0.1143)
		(layer "In11.Cu")
		(net "P3E_PCH_M2_TX_DP<3>")
	)
	(segment
		(start 410.86405 -89.286842)
		(end 410.86405 -96.819974)
		(width 0.1143)
		(layer "In11.Cu")
		(net "P3E_PCH_M2_TX_DP<3>")
	)
	(segment
		(start 400.951954 -118.575836)
		(end 400.763486 -118.764558)
		(width 0.0889)
		(layer "In11.Cu")
		(net "P3E_PCH_M2_TX_DP<3>")
	)
	(segment
		(start 391.210292 -40.963088)
		(end 391.210292 -43.651678)
		(width 0.1143)
		(layer "In11.Cu")
		(net "P3E_PCH_M2_TX_DP<3>")
	)
	(segment
		(start 386.45846 -24.668226)
		(end 386.45846 -31.671006)
		(width 0.1143)
		(layer "In11.Cu")
		(net "P3E_PCH_M2_TX_DP<3>")
	)
	(segment
		(start 411.3911 -97.347024)
		(end 411.3911 -100.476558)
		(width 0.1143)
		(layer "In11.Cu")
		(net "P3E_PCH_M2_TX_DP<3>")
	)
	(segment
		(start 410.6926 -68.617846)
		(end 410.353764 -68.956682)
		(width 0.1143)
		(layer "In11.Cu")
		(net "P3E_PCH_M2_TX_DP<3>")
	)
	(segment
		(start 408.87015 -108.946696)
		(end 408.87015 -112.382808)
		(width 0.1143)
		(layer "In11.Cu")
		(net "P3E_PCH_M2_TX_DP<3>")
	)
	(segment
		(start 407.507694 -113.745264)
		(end 407.507694 -113.992914)
		(width 0.1143)
		(layer "In11.Cu")
		(net "P3E_PCH_M2_TX_DP<3>")
	)
	(segment
		(start 408.22626 -113.260124)
		(end 407.98369 -113.502694)
		(width 0.1143)
		(layer "In11.Cu")
		(net "P3E_PCH_M2_TX_DP<3>")
	)
	(segment
		(start 413.7533 -74.95794)
		(end 413.7533 -79.133446)
		(width 0.1143)
		(layer "In11.Cu")
		(net "P3E_PCH_M2_TX_DP<3>")
	)
	(segment
		(start 395.959838 -47.081186)
		(end 397.55826 -48.679608)
		(width 0.1143)
		(layer "In11.Cu")
		(net "P3E_PCH_M2_TX_DP<3>")
	)
	(segment
		(start 397.55826 -48.679608)
		(end 397.55826 -52.50815)
		(width 0.1143)
		(layer "In11.Cu")
		(net "P3E_PCH_M2_TX_DP<3>")
	)
	(segment
		(start 400.763486 -118.764558)
		(end 400.623278 -118.764558)
		(width 0.0889)
		(layer "In11.Cu")
		(net "P3E_PCH_M2_TX_DP<3>")
	)
	(segment
		(start 410.6926 -66.797682)
		(end 410.6926 -68.617846)
		(width 0.1143)
		(layer "In11.Cu")
		(net "P3E_PCH_M2_TX_DP<3>")
	)
	(segment
		(start 411.7594 -71.654416)
		(end 411.7594 -72.96404)
		(width 0.1143)
		(layer "In11.Cu")
		(net "P3E_PCH_M2_TX_DP<3>")
	)
	(segment
		(start 404.422864 -116.82984)
		(end 403.544786 -117.707918)
		(width 0.1143)
		(layer "In11.Cu")
		(net "P3E_PCH_M2_TX_DP<3>")
	)
	(segment
		(start 411.3911 -100.476558)
		(end 410.8958 -100.971858)
		(width 0.1143)
		(layer "In11.Cu")
		(net "P3E_PCH_M2_TX_DP<3>")
	)
	(segment
		(start 410.8958 -102.17277)
		(end 410.457396 -102.611174)
		(width 0.1143)
		(layer "In11.Cu")
		(net "P3E_PCH_M2_TX_DP<3>")
	)
	(segment
		(start 409.687014 -108.368084)
		(end 409.448762 -108.368084)
		(width 0.1143)
		(layer "In11.Cu")
		(net "P3E_PCH_M2_TX_DP<3>")
	)
	(segment
		(start 386.540756 -33.777174)
		(end 386.540756 -35.630358)
		(width 0.1143)
		(layer "In11.Cu")
		(net "P3E_PCH_M2_TX_DP<3>")
	)
	(segment
		(start 410.353764 -70.24878)
		(end 411.7594 -71.654416)
		(width 0.1143)
		(layer "In11.Cu")
		(net "P3E_PCH_M2_TX_DP<3>")
	)
	(segment
		(start 410.8958 -100.971858)
		(end 410.8958 -102.17277)
		(width 0.1143)
		(layer "In11.Cu")
		(net "P3E_PCH_M2_TX_DP<3>")
	)
	(segment
		(start 400.623278 -118.764558)
		(end 399.9611 -119.426736)
		(width 0.0889)
		(layer "In11.Cu")
		(net "P3E_PCH_M2_TX_DP<3>")
	)
	(segment
		(start 411.7594 -72.96404)
		(end 413.7533 -74.95794)
		(width 0.1143)
		(layer "In11.Cu")
		(net "P3E_PCH_M2_TX_DP<3>")
	)
	(segment
		(start 391.306558 -43.796712)
		(end 394.590778 -47.081186)
		(width 0.1143)
		(layer "In11.Cu")
		(net "P3E_PCH_M2_TX_DP<3>")
	)
	(segment
		(start 407.017474 -114.235484)
		(end 406.455118 -114.79784)
		(width 0.1143)
		(layer "In11.Cu")
		(net "P3E_PCH_M2_TX_DP<3>")
	)
	(segment
		(start 408.87015 -112.382808)
		(end 408.22626 -113.026698)
		(width 0.1143)
		(layer "In11.Cu")
		(net "P3E_PCH_M2_TX_DP<3>")
	)
	(arc
		(start 398.929352 -120.899174)
		(mid 398.63395 -120.978305)
		(end 398.338548 -120.899174)
		(width 0.0889)
		(layer "In11.Cu")
		(net "P3E_PCH_M2_TX_DP<3>")
	)
	(arc
		(start 396.755112 -121.170446)
		(mid 396.753493 -121.179192)
		(end 396.752064 -121.187972)
		(width 0.0889)
		(layer "In11.Cu")
		(net "P3E_PCH_M2_TX_DP<3>")
	)
	(arc
		(start 398.338548 -120.899174)
		(mid 398.13865 -120.845675)
		(end 397.938752 -120.899174)
		(width 0.0889)
		(layer "In11.Cu")
		(net "P3E_PCH_M2_TX_DP<3>")
	)
	(arc
		(start 397.938752 -120.899174)
		(mid 397.64335 -120.978305)
		(end 397.347948 -120.899174)
		(width 0.0889)
		(layer "In11.Cu")
		(net "P3E_PCH_M2_TX_DP<3>")
	)
	(arc
		(start 397.347948 -120.899174)
		(mid 397.14805 -120.845675)
		(end 396.948152 -120.899174)
		(width 0.0889)
		(layer "In11.Cu")
		(net "P3E_PCH_M2_TX_DP<3>")
	)
	(arc
		(start 396.948152 -120.899174)
		(mid 396.822035 -121.013761)
		(end 396.755112 -121.170446)
		(width 0.0889)
		(layer "In11.Cu")
		(net "P3E_PCH_M2_TX_DP<3>")
	)
	(arc
		(start 399.129504 -120.845326)
		(mid 399.025895 -120.859103)
		(end 398.929352 -120.899174)
		(width 0.0889)
		(layer "In11.Cu")
		(net "P3E_PCH_M2_TX_DP<3>")
	)
	(segment
		(start 397.558768 -123.782074)
		(end 397.64335 -123.821444)
		(width 0.1143)
		(layer "F.Cu")
		(net "P3E_PCH_M2_TX_DP<2>")
	)
	(segment
		(start 397.470376 -123.74118)
		(end 397.558768 -123.782074)
		(width 0.1143)
		(layer "F.Cu")
		(net "P3E_PCH_M2_TX_DP<2>")
	)
	(segment
		(start 397.14805 -123.59132)
		(end 397.470376 -123.74118)
		(width 0.1143)
		(layer "F.Cu")
		(net "P3E_PCH_M2_TX_DP<2>")
	)
	(via
		(at 397.64335 -123.821444)
		(size 0.508)
		(drill 0.254)
		(layers "F.Cu" "B.Cu")
		(net "P3E_PCH_M2_TX_DP<2>")
	)
	(via
		(at 387.810502 -27.675332)
		(size 0.508)
		(drill 0.254)
		(layers "F.Cu" "B.Cu")
		(net "P3E_PCH_M2_TX_DP<2>")
	)
	(segment
		(start 386.73659 -27.138376)
		(end 387.273546 -27.138376)
		(width 0.1143)
		(layer "B.Cu")
		(net "P3E_PCH_M2_TX_DP<2>")
	)
	(segment
		(start 387.273546 -27.138376)
		(end 387.810502 -27.675332)
		(width 0.1143)
		(layer "B.Cu")
		(net "P3E_PCH_M2_TX_DP<2>")
	)
	(segment
		(start 386.352034 -27.522932)
		(end 386.73659 -27.138376)
		(width 0.1143)
		(layer "B.Cu")
		(net "P3E_PCH_M2_TX_DP<2>")
	)
	(segment
		(start 408.368246 -115.713256)
		(end 407.90876 -116.172742)
		(width 0.1143)
		(layer "In11.Cu")
		(net "P3E_PCH_M2_TX_DP<2>")
	)
	(segment
		(start 401.785836 -119.50573)
		(end 401.785836 -119.63146)
		(width 0.0889)
		(layer "In11.Cu")
		(net "P3E_PCH_M2_TX_DP<2>")
	)
	(segment
		(start 402.997924 -119.046498)
		(end 402.947124 -119.097298)
		(width 0.0889)
		(layer "In11.Cu")
		(net "P3E_PCH_M2_TX_DP<2>")
	)
	(segment
		(start 414.77311 -74.470768)
		(end 414.77311 -80.14589)
		(width 0.1143)
		(layer "In11.Cu")
		(net "P3E_PCH_M2_TX_DP<2>")
	)
	(segment
		(start 414.1343 -72.104758)
		(end 414.1343 -73.831958)
		(width 0.1143)
		(layer "In11.Cu")
		(net "P3E_PCH_M2_TX_DP<2>")
	)
	(segment
		(start 410.796486 -109.601)
		(end 410.796486 -109.842808)
		(width 0.1143)
		(layer "In11.Cu")
		(net "P3E_PCH_M2_TX_DP<2>")
	)
	(segment
		(start 400.41957 -123.027694)
		(end 400.231102 -123.216162)
		(width 0.0889)
		(layer "In11.Cu")
		(net "P3E_PCH_M2_TX_DP<2>")
	)
	(segment
		(start 399.91665 -123.404884)
		(end 399.91665 -123.530614)
		(width 0.0889)
		(layer "In11.Cu")
		(net "P3E_PCH_M2_TX_DP<2>")
	)
	(segment
		(start 406.714198 -117.133624)
		(end 406.714198 -117.367304)
		(width 0.1143)
		(layer "In11.Cu")
		(net "P3E_PCH_M2_TX_DP<2>")
	)
	(segment
		(start 410.796486 -109.842808)
		(end 410.79674 -109.843062)
		(width 0.1143)
		(layer "In11.Cu")
		(net "P3E_PCH_M2_TX_DP<2>")
	)
	(segment
		(start 392.951716 -43.530774)
		(end 395.138148 -45.717206)
		(width 0.1143)
		(layer "In11.Cu")
		(net "P3E_PCH_M2_TX_DP<2>")
	)
	(segment
		(start 401.271486 -120.753378)
		(end 401.182586 -120.842278)
		(width 0.0889)
		(layer "In11.Cu")
		(net "P3E_PCH_M2_TX_DP<2>")
	)
	(segment
		(start 412.642558 -67.916806)
		(end 412.642558 -68.020438)
		(width 0.1143)
		(layer "In11.Cu")
		(net "P3E_PCH_M2_TX_DP<2>")
	)
	(segment
		(start 398.653 -48.083724)
		(end 398.653 -51.558698)
		(width 0.1143)
		(layer "In11.Cu")
		(net "P3E_PCH_M2_TX_DP<2>")
	)
	(segment
		(start 412.115508 -64.94907)
		(end 412.280608 -65.11417)
		(width 0.1143)
		(layer "In11.Cu")
		(net "P3E_PCH_M2_TX_DP<2>")
	)
	(segment
		(start 391.836402 -36.326318)
		(end 392.951716 -37.441632)
		(width 0.1143)
		(layer "In11.Cu")
		(net "P3E_PCH_M2_TX_DP<2>")
	)
	(segment
		(start 411.258004 -109.139482)
		(end 410.796486 -109.601)
		(width 0.1143)
		(layer "In11.Cu")
		(net "P3E_PCH_M2_TX_DP<2>")
	)
	(segment
		(start 401.785836 -119.63146)
		(end 401.271486 -120.14581)
		(width 0.0889)
		(layer "In11.Cu")
		(net "P3E_PCH_M2_TX_DP<2>")
	)
	(segment
		(start 402.947124 -119.097298)
		(end 402.319998 -119.097298)
		(width 0.0889)
		(layer "In11.Cu")
		(net "P3E_PCH_M2_TX_DP<2>")
	)
	(segment
		(start 412.481268 -103.8225)
		(end 412.481268 -108.713778)
		(width 0.1143)
		(layer "In11.Cu")
		(net "P3E_PCH_M2_TX_DP<2>")
	)
	(segment
		(start 413.111188 -68.280788)
		(end 413.5882 -68.7578)
		(width 0.1143)
		(layer "In11.Cu")
		(net "P3E_PCH_M2_TX_DP<2>")
	)
	(segment
		(start 412.058104 -85.36686)
		(end 412.058104 -88.49487)
		(width 0.1143)
		(layer "In11.Cu")
		(net "P3E_PCH_M2_TX_DP<2>")
	)
	(segment
		(start 401.42033 -54.326028)
		(end 403.22373 -54.326028)
		(width 0.1143)
		(layer "In11.Cu")
		(net "P3E_PCH_M2_TX_DP<2>")
	)
	(segment
		(start 408.368246 -115.102386)
		(end 408.368246 -115.713256)
		(width 0.1143)
		(layer "In11.Cu")
		(net "P3E_PCH_M2_TX_DP<2>")
	)
	(segment
		(start 413.5882 -68.7578)
		(end 413.5882 -71.558658)
		(width 0.1143)
		(layer "In11.Cu")
		(net "P3E_PCH_M2_TX_DP<2>")
	)
	(segment
		(start 396.286482 -45.717206)
		(end 398.653 -48.083724)
		(width 0.1143)
		(layer "In11.Cu")
		(net "P3E_PCH_M2_TX_DP<2>")
	)
	(segment
		(start 412.643066 -67.916298)
		(end 412.642558 -67.916806)
		(width 0.1143)
		(layer "In11.Cu")
		(net "P3E_PCH_M2_TX_DP<2>")
	)
	(segment
		(start 411.40634 -62.267084)
		(end 412.280608 -63.141352)
		(width 0.1143)
		(layer "In11.Cu")
		(net "P3E_PCH_M2_TX_DP<2>")
	)
	(segment
		(start 387.810502 -27.675332)
		(end 387.810502 -27.43581)
		(width 0.1143)
		(layer "In11.Cu")
		(net "P3E_PCH_M2_TX_DP<2>")
	)
	(segment
		(start 410.79674 -113.766092)
		(end 410.002482 -114.56035)
		(width 0.1143)
		(layer "In11.Cu")
		(net "P3E_PCH_M2_TX_DP<2>")
	)
	(segment
		(start 400.41957 -122.901964)
		(end 400.41957 -123.027694)
		(width 0.0889)
		(layer "In11.Cu")
		(net "P3E_PCH_M2_TX_DP<2>")
	)
	(segment
		(start 405.035004 -119.046498)
		(end 403.020022 -119.046498)
		(width 0.1143)
		(layer "In11.Cu")
		(net "P3E_PCH_M2_TX_DP<2>")
	)
	(segment
		(start 412.280608 -64.44107)
		(end 412.115508 -64.60617)
		(width 0.1143)
		(layer "In11.Cu")
		(net "P3E_PCH_M2_TX_DP<2>")
	)
	(segment
		(start 387.810502 -27.43581)
		(end 388.05612 -27.190192)
		(width 0.1143)
		(layer "In11.Cu")
		(net "P3E_PCH_M2_TX_DP<2>")
	)
	(segment
		(start 401.271486 -121.909078)
		(end 401.271486 -122.175778)
		(width 0.0889)
		(layer "In11.Cu")
		(net "P3E_PCH_M2_TX_DP<2>")
	)
	(segment
		(start 406.714198 -117.367304)
		(end 406.471882 -117.60962)
		(width 0.1143)
		(layer "In11.Cu")
		(net "P3E_PCH_M2_TX_DP<2>")
	)
	(segment
		(start 412.115508 -63.93307)
		(end 412.280608 -64.09817)
		(width 0.1143)
		(layer "In11.Cu")
		(net "P3E_PCH_M2_TX_DP<2>")
	)
	(segment
		(start 413.48152 -83.943444)
		(end 412.058104 -85.36686)
		(width 0.1143)
		(layer "In11.Cu")
		(net "P3E_PCH_M2_TX_DP<2>")
	)
	(segment
		(start 412.481268 -108.713778)
		(end 412.055564 -109.139482)
		(width 0.1143)
		(layer "In11.Cu")
		(net "P3E_PCH_M2_TX_DP<2>")
	)
	(segment
		(start 403.701758 -53.848)
		(end 404.545546 -53.848)
		(width 0.1143)
		(layer "In11.Cu")
		(net "P3E_PCH_M2_TX_DP<2>")
	)
	(segment
		(start 405.277574 -118.803928)
		(end 405.035004 -119.046498)
		(width 0.1143)
		(layer "In11.Cu")
		(net "P3E_PCH_M2_TX_DP<2>")
	)
	(segment
		(start 401.271486 -120.14581)
		(end 401.271486 -120.753378)
		(width 0.0889)
		(layer "In11.Cu")
		(net "P3E_PCH_M2_TX_DP<2>")
	)
	(segment
		(start 413.5882 -71.558658)
		(end 414.1343 -72.104758)
		(width 0.1143)
		(layer "In11.Cu")
		(net "P3E_PCH_M2_TX_DP<2>")
	)
	(segment
		(start 397.3957 -123.507246)
		(end 397.470376 -123.527312)
		(width 0.0889)
		(layer "In11.Cu")
		(net "P3E_PCH_M2_TX_DP<2>")
	)
	(segment
		(start 391.205212 -36.326318)
		(end 391.836402 -36.326318)
		(width 0.1143)
		(layer "In11.Cu")
		(net "P3E_PCH_M2_TX_DP<2>")
	)
	(segment
		(start 397.243554 -123.853448)
		(end 397.243554 -123.806966)
		(width 0.0889)
		(layer "In11.Cu")
		(net "P3E_PCH_M2_TX_DP<2>")
	)
	(segment
		(start 401.182586 -120.842278)
		(end 401.182586 -121.108978)
		(width 0.0889)
		(layer "In11.Cu")
		(net "P3E_PCH_M2_TX_DP<2>")
	)
	(segment
		(start 414.1343 -73.831958)
		(end 414.77311 -74.470768)
		(width 0.1143)
		(layer "In11.Cu")
		(net "P3E_PCH_M2_TX_DP<2>")
	)
	(segment
		(start 397.47444 -123.528328)
		(end 397.558768 -123.674632)
		(width 0.0889)
		(layer "In11.Cu")
		(net "P3E_PCH_M2_TX_DP<2>")
	)
	(segment
		(start 413.28975 -103.014018)
		(end 412.481268 -103.8225)
		(width 0.1143)
		(layer "In11.Cu")
		(net "P3E_PCH_M2_TX_DP<2>")
	)
	(segment
		(start 412.679642 -91.705938)
		(end 413.083248 -92.109544)
		(width 0.1143)
		(layer "In11.Cu")
		(net "P3E_PCH_M2_TX_DP<2>")
	)
	(segment
		(start 412.280608 -63.42507)
		(end 412.115508 -63.59017)
		(width 0.1143)
		(layer "In11.Cu")
		(net "P3E_PCH_M2_TX_DP<2>")
	)
	(segment
		(start 412.058104 -88.49487)
		(end 412.679642 -89.116408)
		(width 0.1143)
		(layer "In11.Cu")
		(net "P3E_PCH_M2_TX_DP<2>")
	)
	(segment
		(start 399.602452 -123.719082)
		(end 399.41373 -123.907804)
		(width 0.0889)
		(layer "In11.Cu")
		(net "P3E_PCH_M2_TX_DP<2>")
	)
	(segment
		(start 412.115508 -63.59017)
		(end 412.115508 -63.93307)
		(width 0.1143)
		(layer "In11.Cu")
		(net "P3E_PCH_M2_TX_DP<2>")
	)
	(segment
		(start 399.225262 -124.222002)
		(end 397.612108 -124.222002)
		(width 0.0889)
		(layer "In11.Cu")
		(net "P3E_PCH_M2_TX_DP<2>")
	)
	(segment
		(start 413.007048 -68.281296)
		(end 413.007556 -68.280788)
		(width 0.1143)
		(layer "In11.Cu")
		(net "P3E_PCH_M2_TX_DP<2>")
	)
	(segment
		(start 412.280608 -65.11417)
		(end 412.280608 -67.450208)
		(width 0.1143)
		(layer "In11.Cu")
		(net "P3E_PCH_M2_TX_DP<2>")
	)
	(segment
		(start 412.903416 -68.281296)
		(end 413.007048 -68.281296)
		(width 0.1143)
		(layer "In11.Cu")
		(net "P3E_PCH_M2_TX_DP<2>")
	)
	(segment
		(start 401.271486 -121.197878)
		(end 401.271486 -121.464578)
		(width 0.0889)
		(layer "In11.Cu")
		(net "P3E_PCH_M2_TX_DP<2>")
	)
	(segment
		(start 407.432764 -116.415312)
		(end 407.432764 -116.648738)
		(width 0.1143)
		(layer "In11.Cu")
		(net "P3E_PCH_M2_TX_DP<2>")
	)
	(segment
		(start 401.271486 -121.464578)
		(end 401.182586 -121.553478)
		(width 0.0889)
		(layer "In11.Cu")
		(net "P3E_PCH_M2_TX_DP<2>")
	)
	(segment
		(start 401.182586 -121.820178)
		(end 401.271486 -121.909078)
		(width 0.0889)
		(layer "In11.Cu")
		(net "P3E_PCH_M2_TX_DP<2>")
	)
	(segment
		(start 390.451848 -35.572954)
		(end 391.205212 -36.326318)
		(width 0.1143)
		(layer "In11.Cu")
		(net "P3E_PCH_M2_TX_DP<2>")
	)
	(segment
		(start 404.545546 -53.848)
		(end 411.40634 -60.708794)
		(width 0.1143)
		(layer "In11.Cu")
		(net "P3E_PCH_M2_TX_DP<2>")
	)
	(segment
		(start 412.055564 -109.139482)
		(end 411.258004 -109.139482)
		(width 0.1143)
		(layer "In11.Cu")
		(net "P3E_PCH_M2_TX_DP<2>")
	)
	(segment
		(start 413.28975 -101.223318)
		(end 413.28975 -103.014018)
		(width 0.1143)
		(layer "In11.Cu")
		(net "P3E_PCH_M2_TX_DP<2>")
	)
	(segment
		(start 412.280608 -63.141352)
		(end 412.280608 -63.42507)
		(width 0.1143)
		(layer "In11.Cu")
		(net "P3E_PCH_M2_TX_DP<2>")
	)
	(segment
		(start 400.608292 -122.713242)
		(end 400.41957 -122.901964)
		(width 0.0889)
		(layer "In11.Cu")
		(net "P3E_PCH_M2_TX_DP<2>")
	)
	(segment
		(start 399.41373 -124.033534)
		(end 399.225262 -124.222002)
		(width 0.0889)
		(layer "In11.Cu")
		(net "P3E_PCH_M2_TX_DP<2>")
	)
	(segment
		(start 411.40634 -60.708794)
		(end 411.40634 -62.267084)
		(width 0.1143)
		(layer "In11.Cu")
		(net "P3E_PCH_M2_TX_DP<2>")
	)
	(segment
		(start 390.451848 -28.868116)
		(end 390.451848 -35.572954)
		(width 0.1143)
		(layer "In11.Cu")
		(net "P3E_PCH_M2_TX_DP<2>")
	)
	(segment
		(start 406.238456 -117.60962)
		(end 405.995886 -117.85219)
		(width 0.1143)
		(layer "In11.Cu")
		(net "P3E_PCH_M2_TX_DP<2>")
	)
	(segment
		(start 412.643066 -67.812666)
		(end 412.643066 -67.916298)
		(width 0.1143)
		(layer "In11.Cu")
		(net "P3E_PCH_M2_TX_DP<2>")
	)
	(segment
		(start 402.100034 -119.317262)
		(end 401.974304 -119.317262)
		(width 0.0889)
		(layer "In11.Cu")
		(net "P3E_PCH_M2_TX_DP<2>")
	)
	(segment
		(start 413.083248 -92.109544)
		(end 413.083248 -101.016816)
		(width 0.1143)
		(layer "In11.Cu")
		(net "P3E_PCH_M2_TX_DP<2>")
	)
	(segment
		(start 413.083248 -101.016816)
		(end 413.28975 -101.223318)
		(width 0.1143)
		(layer "In11.Cu")
		(net "P3E_PCH_M2_TX_DP<2>")
	)
	(segment
		(start 406.956768 -116.891308)
		(end 406.714198 -117.133624)
		(width 0.1143)
		(layer "In11.Cu")
		(net "P3E_PCH_M2_TX_DP<2>")
	)
	(segment
		(start 400.105372 -123.216162)
		(end 399.91665 -123.404884)
		(width 0.0889)
		(layer "In11.Cu")
		(net "P3E_PCH_M2_TX_DP<2>")
	)
	(segment
		(start 410.79674 -109.843062)
		(end 410.79674 -113.766092)
		(width 0.1143)
		(layer "In11.Cu")
		(net "P3E_PCH_M2_TX_DP<2>")
	)
	(segment
		(start 412.280608 -64.09817)
		(end 412.280608 -64.44107)
		(width 0.1143)
		(layer "In11.Cu")
		(net "P3E_PCH_M2_TX_DP<2>")
	)
	(segment
		(start 403.22373 -54.326028)
		(end 403.701758 -53.848)
		(width 0.1143)
		(layer "In11.Cu")
		(net "P3E_PCH_M2_TX_DP<2>")
	)
	(segment
		(start 408.910536 -114.56035)
		(end 408.368246 -115.102386)
		(width 0.1143)
		(layer "In11.Cu")
		(net "P3E_PCH_M2_TX_DP<2>")
	)
	(segment
		(start 407.432764 -116.648738)
		(end 407.190194 -116.891308)
		(width 0.1143)
		(layer "In11.Cu")
		(net "P3E_PCH_M2_TX_DP<2>")
	)
	(segment
		(start 392.951716 -37.441632)
		(end 392.951716 -43.530774)
		(width 0.1143)
		(layer "In11.Cu")
		(net "P3E_PCH_M2_TX_DP<2>")
	)
	(segment
		(start 398.653 -51.558698)
		(end 401.42033 -54.326028)
		(width 0.1143)
		(layer "In11.Cu")
		(net "P3E_PCH_M2_TX_DP<2>")
	)
	(segment
		(start 405.51989 -118.328186)
		(end 405.277574 -118.570502)
		(width 0.1143)
		(layer "In11.Cu")
		(net "P3E_PCH_M2_TX_DP<2>")
	)
	(segment
		(start 399.728182 -123.719082)
		(end 399.602452 -123.719082)
		(width 0.0889)
		(layer "In11.Cu")
		(net "P3E_PCH_M2_TX_DP<2>")
	)
	(segment
		(start 414.77311 -80.14589)
		(end 413.48152 -81.43748)
		(width 0.1143)
		(layer "In11.Cu")
		(net "P3E_PCH_M2_TX_DP<2>")
	)
	(segment
		(start 395.138148 -45.717206)
		(end 396.286482 -45.717206)
		(width 0.1143)
		(layer "In11.Cu")
		(net "P3E_PCH_M2_TX_DP<2>")
	)
	(segment
		(start 402.319998 -119.097298)
		(end 402.100034 -119.317262)
		(width 0.0889)
		(layer "In11.Cu")
		(net "P3E_PCH_M2_TX_DP<2>")
	)
	(segment
		(start 407.90876 -116.172742)
		(end 407.67508 -116.172742)
		(width 0.1143)
		(layer "In11.Cu")
		(net "P3E_PCH_M2_TX_DP<2>")
	)
	(segment
		(start 399.91665 -123.530614)
		(end 399.728182 -123.719082)
		(width 0.0889)
		(layer "In11.Cu")
		(net "P3E_PCH_M2_TX_DP<2>")
	)
	(segment
		(start 412.642558 -68.020438)
		(end 412.903416 -68.281296)
		(width 0.1143)
		(layer "In11.Cu")
		(net "P3E_PCH_M2_TX_DP<2>")
	)
	(segment
		(start 388.773924 -27.190192)
		(end 390.451848 -28.868116)
		(width 0.1143)
		(layer "In11.Cu")
		(net "P3E_PCH_M2_TX_DP<2>")
	)
	(segment
		(start 388.05612 -27.190192)
		(end 388.773924 -27.190192)
		(width 0.1143)
		(layer "In11.Cu")
		(net "P3E_PCH_M2_TX_DP<2>")
	)
	(segment
		(start 412.115508 -64.60617)
		(end 412.115508 -64.94907)
		(width 0.1143)
		(layer "In11.Cu")
		(net "P3E_PCH_M2_TX_DP<2>")
	)
	(segment
		(start 400.734022 -122.713242)
		(end 400.608292 -122.713242)
		(width 0.0889)
		(layer "In11.Cu")
		(net "P3E_PCH_M2_TX_DP<2>")
	)
	(segment
		(start 413.007556 -68.280788)
		(end 413.111188 -68.280788)
		(width 0.1143)
		(layer "In11.Cu")
		(net "P3E_PCH_M2_TX_DP<2>")
	)
	(segment
		(start 401.182586 -121.553478)
		(end 401.182586 -121.820178)
		(width 0.0889)
		(layer "In11.Cu")
		(net "P3E_PCH_M2_TX_DP<2>")
	)
	(segment
		(start 405.753316 -118.328186)
		(end 405.51989 -118.328186)
		(width 0.1143)
		(layer "In11.Cu")
		(net "P3E_PCH_M2_TX_DP<2>")
	)
	(segment
		(start 401.974304 -119.317262)
		(end 401.785836 -119.50573)
		(width 0.0889)
		(layer "In11.Cu")
		(net "P3E_PCH_M2_TX_DP<2>")
	)
	(segment
		(start 400.231102 -123.216162)
		(end 400.105372 -123.216162)
		(width 0.0889)
		(layer "In11.Cu")
		(net "P3E_PCH_M2_TX_DP<2>")
	)
	(segment
		(start 397.558768 -123.674632)
		(end 397.64335 -123.821444)
		(width 0.0889)
		(layer "In11.Cu")
		(net "P3E_PCH_M2_TX_DP<2>")
	)
	(segment
		(start 405.995886 -117.85219)
		(end 405.995886 -118.085616)
		(width 0.1143)
		(layer "In11.Cu")
		(net "P3E_PCH_M2_TX_DP<2>")
	)
	(segment
		(start 407.67508 -116.172742)
		(end 407.432764 -116.415312)
		(width 0.1143)
		(layer "In11.Cu")
		(net "P3E_PCH_M2_TX_DP<2>")
	)
	(segment
		(start 403.020022 -119.046498)
		(end 402.997924 -119.046498)
		(width 0.0889)
		(layer "In11.Cu")
		(net "P3E_PCH_M2_TX_DP<2>")
	)
	(segment
		(start 401.271486 -122.175778)
		(end 400.734022 -122.713242)
		(width 0.0889)
		(layer "In11.Cu")
		(net "P3E_PCH_M2_TX_DP<2>")
	)
	(segment
		(start 401.182586 -121.108978)
		(end 401.271486 -121.197878)
		(width 0.0889)
		(layer "In11.Cu")
		(net "P3E_PCH_M2_TX_DP<2>")
	)
	(segment
		(start 407.190194 -116.891308)
		(end 406.956768 -116.891308)
		(width 0.1143)
		(layer "In11.Cu")
		(net "P3E_PCH_M2_TX_DP<2>")
	)
	(segment
		(start 410.002482 -114.56035)
		(end 408.910536 -114.56035)
		(width 0.1143)
		(layer "In11.Cu")
		(net "P3E_PCH_M2_TX_DP<2>")
	)
	(segment
		(start 412.679642 -89.116408)
		(end 412.679642 -91.705938)
		(width 0.1143)
		(layer "In11.Cu")
		(net "P3E_PCH_M2_TX_DP<2>")
	)
	(segment
		(start 399.41373 -123.907804)
		(end 399.41373 -124.033534)
		(width 0.0889)
		(layer "In11.Cu")
		(net "P3E_PCH_M2_TX_DP<2>")
	)
	(segment
		(start 413.48152 -81.43748)
		(end 413.48152 -83.943444)
		(width 0.1143)
		(layer "In11.Cu")
		(net "P3E_PCH_M2_TX_DP<2>")
	)
	(segment
		(start 397.470376 -123.527312)
		(end 397.47444 -123.528328)
		(width 0.0889)
		(layer "In11.Cu")
		(net "P3E_PCH_M2_TX_DP<2>")
	)
	(segment
		(start 405.277574 -118.570502)
		(end 405.277574 -118.803928)
		(width 0.1143)
		(layer "In11.Cu")
		(net "P3E_PCH_M2_TX_DP<2>")
	)
	(segment
		(start 406.471882 -117.60962)
		(end 406.238456 -117.60962)
		(width 0.1143)
		(layer "In11.Cu")
		(net "P3E_PCH_M2_TX_DP<2>")
	)
	(segment
		(start 405.995886 -118.085616)
		(end 405.753316 -118.328186)
		(width 0.1143)
		(layer "In11.Cu")
		(net "P3E_PCH_M2_TX_DP<2>")
	)
	(segment
		(start 412.280608 -67.450208)
		(end 412.643066 -67.812666)
		(width 0.1143)
		(layer "In11.Cu")
		(net "P3E_PCH_M2_TX_DP<2>")
	)
	(arc
		(start 397.612108 -124.222002)
		(mid 397.351501 -124.114055)
		(end 397.243554 -123.853448)
		(width 0.0889)
		(layer "In11.Cu")
		(net "P3E_PCH_M2_TX_DP<2>")
	)
	(arc
		(start 397.243554 -123.806966)
		(mid 397.286625 -123.640354)
		(end 397.3957 -123.507246)
		(width 0.0889)
		(layer "In11.Cu")
		(net "P3E_PCH_M2_TX_DP<2>")
	)
	(segment
		(start 399.17243 -122.641868)
		(end 398.63395 -122.7328)
		(width 0.1143)
		(layer "F.Cu")
		(net "P3E_PCH_M2_TX_DP<1>")
	)
	(via
		(at 399.17243 -122.641868)
		(size 0.508)
		(drill 0.254)
		(layers "F.Cu" "B.Cu")
		(net "P3E_PCH_M2_TX_DP<1>")
	)
	(via
		(at 387.734302 -30.675326)
		(size 0.508)
		(drill 0.254)
		(layers "F.Cu" "B.Cu")
		(net "P3E_PCH_M2_TX_DP<1>")
	)
	(segment
		(start 387.246114 -30.187138)
		(end 387.734302 -30.675326)
		(width 0.1143)
		(layer "B.Cu")
		(net "P3E_PCH_M2_TX_DP<1>")
	)
	(segment
		(start 386.23494 -30.571694)
		(end 386.619496 -30.187138)
		(width 0.1143)
		(layer "B.Cu")
		(net "P3E_PCH_M2_TX_DP<1>")
	)
	(segment
		(start 386.619496 -30.187138)
		(end 387.246114 -30.187138)
		(width 0.1143)
		(layer "B.Cu")
		(net "P3E_PCH_M2_TX_DP<1>")
	)
	(segment
		(start 400.927824 -119.383302)
		(end 400.927824 -119.509032)
		(width 0.0889)
		(layer "In11.Cu")
		(net "P3E_PCH_M2_TX_DP<1>")
	)
	(segment
		(start 414.13811 -74.76871)
		(end 414.13811 -79.787496)
		(width 0.1143)
		(layer "In11.Cu")
		(net "P3E_PCH_M2_TX_DP<1>")
	)
	(segment
		(start 400.26717 -121.414286)
		(end 400.35607 -121.503186)
		(width 0.0889)
		(layer "In11.Cu")
		(net "P3E_PCH_M2_TX_DP<1>")
	)
	(segment
		(start 400.26717 -120.436386)
		(end 400.26717 -120.703086)
		(width 0.0889)
		(layer "In11.Cu")
		(net "P3E_PCH_M2_TX_DP<1>")
	)
	(segment
		(start 400.35607 -120.347486)
		(end 400.26717 -120.436386)
		(width 0.0889)
		(layer "In11.Cu")
		(net "P3E_PCH_M2_TX_DP<1>")
	)
	(segment
		(start 407.284682 -114.899948)
		(end 407.042366 -115.142518)
		(width 0.1143)
		(layer "In11.Cu")
		(net "P3E_PCH_M2_TX_DP<1>")
	)
	(segment
		(start 412.439104 -92.82811)
		(end 412.439104 -101.27107)
		(width 0.1143)
		(layer "In11.Cu")
		(net "P3E_PCH_M2_TX_DP<1>")
	)
	(segment
		(start 412.701486 -80.990694)
		(end 412.701486 -81.22412)
		(width 0.1143)
		(layer "In11.Cu")
		(net "P3E_PCH_M2_TX_DP<1>")
	)
	(segment
		(start 400.041872 -122.284998)
		(end 399.85315 -122.47372)
		(width 0.0889)
		(layer "In11.Cu")
		(net "P3E_PCH_M2_TX_DP<1>")
	)
	(segment
		(start 399.85315 -122.59945)
		(end 399.384012 -123.068588)
		(width 0.0889)
		(layer "In11.Cu")
		(net "P3E_PCH_M2_TX_DP<1>")
	)
	(segment
		(start 401.619466 -118.69166)
		(end 401.430744 -118.880382)
		(width 0.0889)
		(layer "In11.Cu")
		(net "P3E_PCH_M2_TX_DP<1>")
	)
	(segment
		(start 400.167602 -122.284998)
		(end 400.041872 -122.284998)
		(width 0.0889)
		(layer "In11.Cu")
		(net "P3E_PCH_M2_TX_DP<1>")
	)
	(segment
		(start 413.49168 -74.12228)
		(end 414.13811 -74.76871)
		(width 0.1143)
		(layer "In11.Cu")
		(net "P3E_PCH_M2_TX_DP<1>")
	)
	(segment
		(start 411.7467 -104.196642)
		(end 410.800296 -105.143046)
		(width 0.1143)
		(layer "In11.Cu")
		(net "P3E_PCH_M2_TX_DP<1>")
	)
	(segment
		(start 398.899126 -123.068588)
		(end 398.810734 -122.980196)
		(width 0.0889)
		(layer "In11.Cu")
		(net "P3E_PCH_M2_TX_DP<1>")
	)
	(segment
		(start 411.325822 -66.630296)
		(end 411.325822 -69.712586)
		(width 0.1143)
		(layer "In11.Cu")
		(net "P3E_PCH_M2_TX_DP<1>")
	)
	(segment
		(start 406.3238 -115.86083)
		(end 406.3238 -116.09451)
		(width 0.1143)
		(layer "In11.Cu")
		(net "P3E_PCH_M2_TX_DP<1>")
	)
	(segment
		(start 405.605488 -116.812822)
		(end 404.175214 -118.243096)
		(width 0.1143)
		(layer "In11.Cu")
		(net "P3E_PCH_M2_TX_DP<1>")
	)
	(segment
		(start 407.518362 -114.899948)
		(end 407.284682 -114.899948)
		(width 0.1143)
		(layer "In11.Cu")
		(net "P3E_PCH_M2_TX_DP<1>")
	)
	(segment
		(start 394.897864 -46.516798)
		(end 395.9987 -46.516798)
		(width 0.1143)
		(layer "In11.Cu")
		(net "P3E_PCH_M2_TX_DP<1>")
	)
	(segment
		(start 413.419798 -80.272382)
		(end 413.419798 -80.505808)
		(width 0.1143)
		(layer "In11.Cu")
		(net "P3E_PCH_M2_TX_DP<1>")
	)
	(segment
		(start 395.9987 -46.516798)
		(end 398.018 -48.536098)
		(width 0.1143)
		(layer "In11.Cu")
		(net "P3E_PCH_M2_TX_DP<1>")
	)
	(segment
		(start 408.236674 -114.181636)
		(end 408.003248 -114.181636)
		(width 0.1143)
		(layer "In11.Cu")
		(net "P3E_PCH_M2_TX_DP<1>")
	)
	(segment
		(start 410.800296 -105.143046)
		(end 410.800296 -107.739942)
		(width 0.1143)
		(layer "In11.Cu")
		(net "P3E_PCH_M2_TX_DP<1>")
	)
	(segment
		(start 401.430744 -118.880382)
		(end 401.430744 -119.006112)
		(width 0.0889)
		(layer "In11.Cu")
		(net "P3E_PCH_M2_TX_DP<1>")
	)
	(segment
		(start 406.24125 -56.50865)
		(end 410.718 -60.9854)
		(width 0.1143)
		(layer "In11.Cu")
		(net "P3E_PCH_M2_TX_DP<1>")
	)
	(segment
		(start 394.89761 -46.516544)
		(end 394.897864 -46.516798)
		(width 0.1143)
		(layer "In11.Cu")
		(net "P3E_PCH_M2_TX_DP<1>")
	)
	(segment
		(start 412.65475 -101.486716)
		(end 412.65475 -102.64013)
		(width 0.1143)
		(layer "In11.Cu")
		(net "P3E_PCH_M2_TX_DP<1>")
	)
	(segment
		(start 401.430744 -119.006112)
		(end 401.242276 -119.19458)
		(width 0.0889)
		(layer "In11.Cu")
		(net "P3E_PCH_M2_TX_DP<1>")
	)
	(segment
		(start 405.848058 -116.336826)
		(end 405.605488 -116.579396)
		(width 0.1143)
		(layer "In11.Cu")
		(net "P3E_PCH_M2_TX_DP<1>")
	)
	(segment
		(start 407.760678 -114.657632)
		(end 407.518362 -114.899948)
		(width 0.1143)
		(layer "In11.Cu")
		(net "P3E_PCH_M2_TX_DP<1>")
	)
	(segment
		(start 400.35607 -120.791986)
		(end 400.35607 -121.058686)
		(width 0.0889)
		(layer "In11.Cu")
		(net "P3E_PCH_M2_TX_DP<1>")
	)
	(segment
		(start 388.667752 -30.186376)
		(end 389.521954 -31.040578)
		(width 0.1143)
		(layer "In11.Cu")
		(net "P3E_PCH_M2_TX_DP<1>")
	)
	(segment
		(start 408.003248 -114.181636)
		(end 407.760678 -114.423952)
		(width 0.1143)
		(layer "In11.Cu")
		(net "P3E_PCH_M2_TX_DP<1>")
	)
	(segment
		(start 404.15972 -118.25859)
		(end 404.15972 -118.330218)
		(width 0.0889)
		(layer "In11.Cu")
		(net "P3E_PCH_M2_TX_DP<1>")
	)
	(segment
		(start 410.718 -60.9854)
		(end 410.718 -66.022474)
		(width 0.1143)
		(layer "In11.Cu")
		(net "P3E_PCH_M2_TX_DP<1>")
	)
	(segment
		(start 401.116546 -119.19458)
		(end 400.927824 -119.383302)
		(width 0.0889)
		(layer "In11.Cu")
		(net "P3E_PCH_M2_TX_DP<1>")
	)
	(segment
		(start 410.15285 -108.387388)
		(end 410.15285 -113.511584)
		(width 0.1143)
		(layer "In11.Cu")
		(net "P3E_PCH_M2_TX_DP<1>")
	)
	(segment
		(start 412.396686 -70.237858)
		(end 412.7754 -70.616572)
		(width 0.1143)
		(layer "In11.Cu")
		(net "P3E_PCH_M2_TX_DP<1>")
	)
	(segment
		(start 413.419798 -80.505808)
		(end 413.177228 -80.748378)
		(width 0.1143)
		(layer "In11.Cu")
		(net "P3E_PCH_M2_TX_DP<1>")
	)
	(segment
		(start 410.718 -66.022474)
		(end 411.325822 -66.630296)
		(width 0.1143)
		(layer "In11.Cu")
		(net "P3E_PCH_M2_TX_DP<1>")
	)
	(segment
		(start 391.663428 -40.66159)
		(end 391.663428 -43.463972)
		(width 0.1143)
		(layer "In11.Cu")
		(net "P3E_PCH_M2_TX_DP<1>")
	)
	(segment
		(start 411.851094 -70.237858)
		(end 412.396686 -70.237858)
		(width 0.1143)
		(layer "In11.Cu")
		(net "P3E_PCH_M2_TX_DP<1>")
	)
	(segment
		(start 410.15285 -113.511584)
		(end 409.739084 -113.92535)
		(width 0.1143)
		(layer "In11.Cu")
		(net "P3E_PCH_M2_TX_DP<1>")
	)
	(segment
		(start 413.89554 -80.030066)
		(end 413.662114 -80.030066)
		(width 0.1143)
		(layer "In11.Cu")
		(net "P3E_PCH_M2_TX_DP<1>")
	)
	(segment
		(start 404.175214 -118.243096)
		(end 404.15972 -118.25859)
		(width 0.0889)
		(layer "In11.Cu")
		(net "P3E_PCH_M2_TX_DP<1>")
	)
	(segment
		(start 406.3238 -116.09451)
		(end 406.081484 -116.336826)
		(width 0.1143)
		(layer "In11.Cu")
		(net "P3E_PCH_M2_TX_DP<1>")
	)
	(segment
		(start 398.810734 -122.980196)
		(end 398.772888 -122.859546)
		(width 0.0889)
		(layer "In11.Cu")
		(net "P3E_PCH_M2_TX_DP<1>")
	)
	(segment
		(start 413.662114 -80.030066)
		(end 413.419798 -80.272382)
		(width 0.1143)
		(layer "In11.Cu")
		(net "P3E_PCH_M2_TX_DP<1>")
	)
	(segment
		(start 387.734302 -30.675326)
		(end 387.734302 -30.300676)
		(width 0.1143)
		(layer "In11.Cu")
		(net "P3E_PCH_M2_TX_DP<1>")
	)
	(segment
		(start 398.018 -52.370736)
		(end 402.155914 -56.50865)
		(width 0.1143)
		(layer "In11.Cu")
		(net "P3E_PCH_M2_TX_DP<1>")
	)
	(segment
		(start 400.26717 -121.147586)
		(end 400.26717 -121.414286)
		(width 0.0889)
		(layer "In11.Cu")
		(net "P3E_PCH_M2_TX_DP<1>")
	)
	(segment
		(start 411.7467 -103.54818)
		(end 411.7467 -104.196642)
		(width 0.1143)
		(layer "In11.Cu")
		(net "P3E_PCH_M2_TX_DP<1>")
	)
	(segment
		(start 412.65475 -102.64013)
		(end 411.7467 -103.54818)
		(width 0.1143)
		(layer "In11.Cu")
		(net "P3E_PCH_M2_TX_DP<1>")
	)
	(segment
		(start 410.457396 -87.79256)
		(end 412.044642 -89.379806)
		(width 0.1143)
		(layer "In11.Cu")
		(net "P3E_PCH_M2_TX_DP<1>")
	)
	(segment
		(start 402.155914 -56.50865)
		(end 406.24125 -56.50865)
		(width 0.1143)
		(layer "In11.Cu")
		(net "P3E_PCH_M2_TX_DP<1>")
	)
	(segment
		(start 412.7754 -70.616572)
		(end 412.7754 -71.837804)
		(width 0.1143)
		(layer "In11.Cu")
		(net "P3E_PCH_M2_TX_DP<1>")
	)
	(segment
		(start 410.457396 -83.46821)
		(end 410.457396 -87.79256)
		(width 0.1143)
		(layer "In11.Cu")
		(net "P3E_PCH_M2_TX_DP<1>")
	)
	(segment
		(start 409.739084 -113.92535)
		(end 408.49296 -113.92535)
		(width 0.1143)
		(layer "In11.Cu")
		(net "P3E_PCH_M2_TX_DP<1>")
	)
	(segment
		(start 407.760678 -114.423952)
		(end 407.760678 -114.657632)
		(width 0.1143)
		(layer "In11.Cu")
		(net "P3E_PCH_M2_TX_DP<1>")
	)
	(segment
		(start 389.521954 -31.040578)
		(end 389.521954 -35.984434)
		(width 0.1143)
		(layer "In11.Cu")
		(net "P3E_PCH_M2_TX_DP<1>")
	)
	(segment
		(start 410.800296 -107.739942)
		(end 410.15285 -108.387388)
		(width 0.1143)
		(layer "In11.Cu")
		(net "P3E_PCH_M2_TX_DP<1>")
	)
	(segment
		(start 400.35607 -122.09653)
		(end 400.167602 -122.284998)
		(width 0.0889)
		(layer "In11.Cu")
		(net "P3E_PCH_M2_TX_DP<1>")
	)
	(segment
		(start 400.26717 -120.703086)
		(end 400.35607 -120.791986)
		(width 0.0889)
		(layer "In11.Cu")
		(net "P3E_PCH_M2_TX_DP<1>")
	)
	(segment
		(start 413.49168 -72.554084)
		(end 413.49168 -74.12228)
		(width 0.1143)
		(layer "In11.Cu")
		(net "P3E_PCH_M2_TX_DP<1>")
	)
	(segment
		(start 390.619996 -37.082476)
		(end 391.694162 -37.082476)
		(width 0.1143)
		(layer "In11.Cu")
		(net "P3E_PCH_M2_TX_DP<1>")
	)
	(segment
		(start 398.018 -48.536098)
		(end 398.018 -52.370736)
		(width 0.1143)
		(layer "In11.Cu")
		(net "P3E_PCH_M2_TX_DP<1>")
	)
	(segment
		(start 412.7754 -71.837804)
		(end 413.49168 -72.554084)
		(width 0.1143)
		(layer "In11.Cu")
		(net "P3E_PCH_M2_TX_DP<1>")
	)
	(segment
		(start 406.799796 -115.618514)
		(end 406.56637 -115.618514)
		(width 0.1143)
		(layer "In11.Cu")
		(net "P3E_PCH_M2_TX_DP<1>")
	)
	(segment
		(start 400.927824 -119.509032)
		(end 400.35607 -120.080786)
		(width 0.0889)
		(layer "In11.Cu")
		(net "P3E_PCH_M2_TX_DP<1>")
	)
	(segment
		(start 398.831308 -122.74804)
		(end 399.17243 -122.641868)
		(width 0.0889)
		(layer "In11.Cu")
		(net "P3E_PCH_M2_TX_DP<1>")
	)
	(segment
		(start 389.521954 -35.984434)
		(end 390.619996 -37.082476)
		(width 0.1143)
		(layer "In11.Cu")
		(net "P3E_PCH_M2_TX_DP<1>")
	)
	(segment
		(start 399.85315 -122.47372)
		(end 399.85315 -122.59945)
		(width 0.0889)
		(layer "In11.Cu")
		(net "P3E_PCH_M2_TX_DP<1>")
	)
	(segment
		(start 398.772888 -122.859546)
		(end 398.831308 -122.74804)
		(width 0.0889)
		(layer "In11.Cu")
		(net "P3E_PCH_M2_TX_DP<1>")
	)
	(segment
		(start 403.986746 -118.503192)
		(end 401.933664 -118.503192)
		(width 0.0889)
		(layer "In11.Cu")
		(net "P3E_PCH_M2_TX_DP<1>")
	)
	(segment
		(start 412.701486 -81.22412)
		(end 410.457396 -83.46821)
		(width 0.1143)
		(layer "In11.Cu")
		(net "P3E_PCH_M2_TX_DP<1>")
	)
	(segment
		(start 413.177228 -80.748378)
		(end 412.943802 -80.748378)
		(width 0.1143)
		(layer "In11.Cu")
		(net "P3E_PCH_M2_TX_DP<1>")
	)
	(segment
		(start 401.745196 -118.69166)
		(end 401.619466 -118.69166)
		(width 0.0889)
		(layer "In11.Cu")
		(net "P3E_PCH_M2_TX_DP<1>")
	)
	(segment
		(start 387.734302 -30.300676)
		(end 387.848602 -30.186376)
		(width 0.1143)
		(layer "In11.Cu")
		(net "P3E_PCH_M2_TX_DP<1>")
	)
	(segment
		(start 412.044642 -89.379806)
		(end 412.044642 -92.433648)
		(width 0.1143)
		(layer "In11.Cu")
		(net "P3E_PCH_M2_TX_DP<1>")
	)
	(segment
		(start 394.716 -46.516544)
		(end 394.89761 -46.516544)
		(width 0.1143)
		(layer "In11.Cu")
		(net "P3E_PCH_M2_TX_DP<1>")
	)
	(segment
		(start 405.605488 -116.579396)
		(end 405.605488 -116.812822)
		(width 0.1143)
		(layer "In11.Cu")
		(net "P3E_PCH_M2_TX_DP<1>")
	)
	(segment
		(start 392.200892 -37.589206)
		(end 392.200892 -40.124126)
		(width 0.1143)
		(layer "In11.Cu")
		(net "P3E_PCH_M2_TX_DP<1>")
	)
	(segment
		(start 411.325822 -69.712586)
		(end 411.851094 -70.237858)
		(width 0.1143)
		(layer "In11.Cu")
		(net "P3E_PCH_M2_TX_DP<1>")
	)
	(segment
		(start 407.042366 -115.142518)
		(end 407.042366 -115.375944)
		(width 0.1143)
		(layer "In11.Cu")
		(net "P3E_PCH_M2_TX_DP<1>")
	)
	(segment
		(start 400.35607 -121.503186)
		(end 400.35607 -122.09653)
		(width 0.0889)
		(layer "In11.Cu")
		(net "P3E_PCH_M2_TX_DP<1>")
	)
	(segment
		(start 400.35607 -121.058686)
		(end 400.26717 -121.147586)
		(width 0.0889)
		(layer "In11.Cu")
		(net "P3E_PCH_M2_TX_DP<1>")
	)
	(segment
		(start 406.081484 -116.336826)
		(end 405.848058 -116.336826)
		(width 0.1143)
		(layer "In11.Cu")
		(net "P3E_PCH_M2_TX_DP<1>")
	)
	(segment
		(start 412.044642 -92.433648)
		(end 412.439104 -92.82811)
		(width 0.1143)
		(layer "In11.Cu")
		(net "P3E_PCH_M2_TX_DP<1>")
	)
	(segment
		(start 391.694162 -37.082476)
		(end 392.200892 -37.589206)
		(width 0.1143)
		(layer "In11.Cu")
		(net "P3E_PCH_M2_TX_DP<1>")
	)
	(segment
		(start 399.384012 -123.068588)
		(end 398.899126 -123.068588)
		(width 0.0889)
		(layer "In11.Cu")
		(net "P3E_PCH_M2_TX_DP<1>")
	)
	(segment
		(start 414.13811 -79.787496)
		(end 413.89554 -80.030066)
		(width 0.1143)
		(layer "In11.Cu")
		(net "P3E_PCH_M2_TX_DP<1>")
	)
	(segment
		(start 412.943802 -80.748378)
		(end 412.701486 -80.990694)
		(width 0.1143)
		(layer "In11.Cu")
		(net "P3E_PCH_M2_TX_DP<1>")
	)
	(segment
		(start 401.933664 -118.503192)
		(end 401.745196 -118.69166)
		(width 0.0889)
		(layer "In11.Cu")
		(net "P3E_PCH_M2_TX_DP<1>")
	)
	(segment
		(start 404.15972 -118.330218)
		(end 403.986746 -118.503192)
		(width 0.0889)
		(layer "In11.Cu")
		(net "P3E_PCH_M2_TX_DP<1>")
	)
	(segment
		(start 400.35607 -120.080786)
		(end 400.35607 -120.347486)
		(width 0.0889)
		(layer "In11.Cu")
		(net "P3E_PCH_M2_TX_DP<1>")
	)
	(segment
		(start 412.439104 -101.27107)
		(end 412.65475 -101.486716)
		(width 0.1143)
		(layer "In11.Cu")
		(net "P3E_PCH_M2_TX_DP<1>")
	)
	(segment
		(start 406.56637 -115.618514)
		(end 406.3238 -115.86083)
		(width 0.1143)
		(layer "In11.Cu")
		(net "P3E_PCH_M2_TX_DP<1>")
	)
	(segment
		(start 391.663428 -43.463972)
		(end 394.716 -46.516544)
		(width 0.1143)
		(layer "In11.Cu")
		(net "P3E_PCH_M2_TX_DP<1>")
	)
	(segment
		(start 407.042366 -115.375944)
		(end 406.799796 -115.618514)
		(width 0.1143)
		(layer "In11.Cu")
		(net "P3E_PCH_M2_TX_DP<1>")
	)
	(segment
		(start 408.49296 -113.92535)
		(end 408.236674 -114.181636)
		(width 0.1143)
		(layer "In11.Cu")
		(net "P3E_PCH_M2_TX_DP<1>")
	)
	(segment
		(start 387.848602 -30.186376)
		(end 388.667752 -30.186376)
		(width 0.1143)
		(layer "In11.Cu")
		(net "P3E_PCH_M2_TX_DP<1>")
	)
	(segment
		(start 401.242276 -119.19458)
		(end 401.116546 -119.19458)
		(width 0.0889)
		(layer "In11.Cu")
		(net "P3E_PCH_M2_TX_DP<1>")
	)
	(segment
		(start 392.200892 -40.124126)
		(end 391.663428 -40.66159)
		(width 0.1143)
		(layer "In11.Cu")
		(net "P3E_PCH_M2_TX_DP<1>")
	)
	(segment
		(start 395.66215 -121.01576)
		(end 396.15745 -121.245884)
		(width 0.1143)
		(layer "F.Cu")
		(net "P3E_PCH_M2_TX_DN<3>")
	)
	(via
		(at 396.15745 -121.245884)
		(size 0.508)
		(drill 0.254)
		(layers "F.Cu" "B.Cu")
		(net "P3E_PCH_M2_TX_DN<3>")
	)
	(via
		(at 387.792976 -23.68931)
		(size 0.508)
		(drill 0.254)
		(layers "F.Cu" "B.Cu")
		(net "P3E_PCH_M2_TX_DN<3>")
	)
	(segment
		(start 387.199632 -24.282654)
		(end 387.792976 -23.68931)
		(width 0.1143)
		(layer "B.Cu")
		(net "P3E_PCH_M2_TX_DN<3>")
	)
	(segment
		(start 386.519674 -24.282654)
		(end 387.199632 -24.282654)
		(width 0.1143)
		(layer "B.Cu")
		(net "P3E_PCH_M2_TX_DN<3>")
	)
	(segment
		(start 386.106924 -23.869904)
		(end 386.519674 -24.282654)
		(width 0.1143)
		(layer "B.Cu")
		(net "P3E_PCH_M2_TX_DN<3>")
	)
	(segment
		(start 394.46962 -47.373286)
		(end 395.83868 -47.373286)
		(width 0.1143)
		(layer "In11.Cu")
		(net "P3E_PCH_M2_TX_DN<3>")
	)
	(segment
		(start 397.26616 -52.629308)
		(end 402.862542 -58.22569)
		(width 0.1143)
		(layer "In11.Cu")
		(net "P3E_PCH_M2_TX_DN<3>")
	)
	(segment
		(start 411.099 -97.468182)
		(end 411.099 -100.3554)
		(width 0.1143)
		(layer "In11.Cu")
		(net "P3E_PCH_M2_TX_DN<3>")
	)
	(segment
		(start 386.16636 -24.547068)
		(end 386.16636 -31.792164)
		(width 0.1143)
		(layer "In11.Cu")
		(net "P3E_PCH_M2_TX_DN<3>")
	)
	(segment
		(start 409.452064 -88.288114)
		(end 410.57195 -89.408)
		(width 0.1143)
		(layer "In11.Cu")
		(net "P3E_PCH_M2_TX_DN<3>")
	)
	(segment
		(start 403.003004 -117.908324)
		(end 401.210018 -117.908324)
		(width 0.0889)
		(layer "In11.Cu")
		(net "P3E_PCH_M2_TX_DN<3>")
	)
	(segment
		(start 403.338284 -117.501162)
		(end 403.32279 -117.516656)
		(width 0.0889)
		(layer "In11.Cu")
		(net "P3E_PCH_M2_TX_DN<3>")
	)
	(segment
		(start 411.099 -100.3554)
		(end 410.6037 -100.8507)
		(width 0.1143)
		(layer "In11.Cu")
		(net "P3E_PCH_M2_TX_DN<3>")
	)
	(segment
		(start 409.565856 -108.075984)
		(end 409.327604 -108.075984)
		(width 0.1143)
		(layer "In11.Cu")
		(net "P3E_PCH_M2_TX_DN<3>")
	)
	(segment
		(start 387.678676 -24.17826)
		(end 386.535168 -24.17826)
		(width 0.1143)
		(layer "In11.Cu")
		(net "P3E_PCH_M2_TX_DN<3>")
	)
	(segment
		(start 386.248656 -35.751516)
		(end 390.014714 -39.517574)
		(width 0.1143)
		(layer "In11.Cu")
		(net "P3E_PCH_M2_TX_DN<3>")
	)
	(segment
		(start 395.83868 -47.373286)
		(end 397.26616 -48.800766)
		(width 0.1143)
		(layer "In11.Cu")
		(net "P3E_PCH_M2_TX_DN<3>")
	)
	(segment
		(start 386.16636 -31.792164)
		(end 386.646928 -32.272732)
		(width 0.1143)
		(layer "In11.Cu")
		(net "P3E_PCH_M2_TX_DN<3>")
	)
	(segment
		(start 386.535168 -24.17826)
		(end 386.16636 -24.547068)
		(width 0.1143)
		(layer "In11.Cu")
		(net "P3E_PCH_M2_TX_DN<3>")
	)
	(segment
		(start 410.6037 -102.051612)
		(end 410.165296 -102.490016)
		(width 0.1143)
		(layer "In11.Cu")
		(net "P3E_PCH_M2_TX_DN<3>")
	)
	(segment
		(start 396.56766 -121.134378)
		(end 396.456154 -121.245884)
		(width 0.0889)
		(layer "In11.Cu")
		(net "P3E_PCH_M2_TX_DN<3>")
	)
	(segment
		(start 390.918192 -43.739562)
		(end 391.078974 -43.98264)
		(width 0.1143)
		(layer "In11.Cu")
		(net "P3E_PCH_M2_TX_DN<3>")
	)
	(segment
		(start 408.57805 -112.261396)
		(end 406.333706 -114.50574)
		(width 0.1143)
		(layer "In11.Cu")
		(net "P3E_PCH_M2_TX_DN<3>")
	)
	(segment
		(start 401.210018 -117.908324)
		(end 399.7706 -119.347742)
		(width 0.0889)
		(layer "In11.Cu")
		(net "P3E_PCH_M2_TX_DN<3>")
	)
	(segment
		(start 406.333706 -114.50574)
		(end 405.515826 -114.50574)
		(width 0.1143)
		(layer "In11.Cu")
		(net "P3E_PCH_M2_TX_DN<3>")
	)
	(segment
		(start 410.165296 -107.476544)
		(end 409.565856 -108.075984)
		(width 0.1143)
		(layer "In11.Cu")
		(net "P3E_PCH_M2_TX_DN<3>")
	)
	(segment
		(start 399.7706 -119.347742)
		(end 399.7706 -120.169686)
		(width 0.0889)
		(layer "In11.Cu")
		(net "P3E_PCH_M2_TX_DN<3>")
	)
	(segment
		(start 410.6037 -100.8507)
		(end 410.6037 -102.051612)
		(width 0.1143)
		(layer "In11.Cu")
		(net "P3E_PCH_M2_TX_DN<3>")
	)
	(segment
		(start 410.0322 -66.55054)
		(end 410.4005 -66.91884)
		(width 0.1143)
		(layer "In11.Cu")
		(net "P3E_PCH_M2_TX_DN<3>")
	)
	(segment
		(start 411.4673 -71.775574)
		(end 411.4673 -73.085198)
		(width 0.1143)
		(layer "In11.Cu")
		(net "P3E_PCH_M2_TX_DN<3>")
	)
	(segment
		(start 390.918192 -41.084246)
		(end 390.918192 -43.739562)
		(width 0.1143)
		(layer "In11.Cu")
		(net "P3E_PCH_M2_TX_DN<3>")
	)
	(segment
		(start 410.4005 -66.91884)
		(end 410.4005 -68.496688)
		(width 0.1143)
		(layer "In11.Cu")
		(net "P3E_PCH_M2_TX_DN<3>")
	)
	(segment
		(start 407.058368 -58.22569)
		(end 410.0322 -61.199522)
		(width 0.1143)
		(layer "In11.Cu")
		(net "P3E_PCH_M2_TX_DN<3>")
	)
	(segment
		(start 397.26616 -48.800766)
		(end 397.26616 -52.629308)
		(width 0.1143)
		(layer "In11.Cu")
		(net "P3E_PCH_M2_TX_DN<3>")
	)
	(segment
		(start 404.130764 -116.708682)
		(end 403.338284 -117.501162)
		(width 0.1143)
		(layer "In11.Cu")
		(net "P3E_PCH_M2_TX_DN<3>")
	)
	(segment
		(start 405.515826 -114.50574)
		(end 404.130764 -115.890802)
		(width 0.1143)
		(layer "In11.Cu")
		(net "P3E_PCH_M2_TX_DN<3>")
	)
	(segment
		(start 404.130764 -115.890802)
		(end 404.130764 -116.708682)
		(width 0.1143)
		(layer "In11.Cu")
		(net "P3E_PCH_M2_TX_DN<3>")
	)
	(segment
		(start 387.792976 -23.68931)
		(end 387.792976 -24.06396)
		(width 0.1143)
		(layer "In11.Cu")
		(net "P3E_PCH_M2_TX_DN<3>")
	)
	(segment
		(start 410.4005 -68.496688)
		(end 410.061664 -68.835524)
		(width 0.1143)
		(layer "In11.Cu")
		(net "P3E_PCH_M2_TX_DN<3>")
	)
	(segment
		(start 403.323044 -117.588284)
		(end 403.003004 -117.908324)
		(width 0.0889)
		(layer "In11.Cu")
		(net "P3E_PCH_M2_TX_DN<3>")
	)
	(segment
		(start 410.57195 -89.408)
		(end 410.57195 -96.941132)
		(width 0.1143)
		(layer "In11.Cu")
		(net "P3E_PCH_M2_TX_DN<3>")
	)
	(segment
		(start 387.792976 -24.06396)
		(end 387.678676 -24.17826)
		(width 0.1143)
		(layer "In11.Cu")
		(net "P3E_PCH_M2_TX_DN<3>")
	)
	(segment
		(start 386.646928 -32.272732)
		(end 386.646928 -33.257744)
		(width 0.1143)
		(layer "In11.Cu")
		(net "P3E_PCH_M2_TX_DN<3>")
	)
	(segment
		(start 403.32279 -117.516656)
		(end 403.323044 -117.588284)
		(width 0.0889)
		(layer "In11.Cu")
		(net "P3E_PCH_M2_TX_DN<3>")
	)
	(segment
		(start 413.4612 -75.079098)
		(end 413.4612 -79.012288)
		(width 0.1143)
		(layer "In11.Cu")
		(net "P3E_PCH_M2_TX_DN<3>")
	)
	(segment
		(start 411.4673 -73.085198)
		(end 413.4612 -75.079098)
		(width 0.1143)
		(layer "In11.Cu")
		(net "P3E_PCH_M2_TX_DN<3>")
	)
	(segment
		(start 409.327604 -108.075984)
		(end 408.57805 -108.825538)
		(width 0.1143)
		(layer "In11.Cu")
		(net "P3E_PCH_M2_TX_DN<3>")
	)
	(segment
		(start 410.57195 -96.941132)
		(end 411.099 -97.468182)
		(width 0.1143)
		(layer "In11.Cu")
		(net "P3E_PCH_M2_TX_DN<3>")
	)
	(segment
		(start 390.014714 -39.517574)
		(end 390.014714 -40.180768)
		(width 0.1143)
		(layer "In11.Cu")
		(net "P3E_PCH_M2_TX_DN<3>")
	)
	(segment
		(start 402.862542 -58.22569)
		(end 407.058368 -58.22569)
		(width 0.1143)
		(layer "In11.Cu")
		(net "P3E_PCH_M2_TX_DN<3>")
	)
	(segment
		(start 409.452064 -83.021424)
		(end 409.452064 -88.288114)
		(width 0.1143)
		(layer "In11.Cu")
		(net "P3E_PCH_M2_TX_DN<3>")
	)
	(segment
		(start 398.833848 -120.734328)
		(end 398.833848 -120.734074)
		(width 0.0889)
		(layer "In11.Cu")
		(net "P3E_PCH_M2_TX_DN<3>")
	)
	(segment
		(start 391.078974 -43.98264)
		(end 394.46962 -47.373286)
		(width 0.1143)
		(layer "In11.Cu")
		(net "P3E_PCH_M2_TX_DN<3>")
	)
	(segment
		(start 399.28546 -120.654826)
		(end 399.12925 -120.654826)
		(width 0.0889)
		(layer "In11.Cu")
		(net "P3E_PCH_M2_TX_DN<3>")
	)
	(segment
		(start 410.0322 -61.199522)
		(end 410.0322 -66.55054)
		(width 0.1143)
		(layer "In11.Cu")
		(net "P3E_PCH_M2_TX_DN<3>")
	)
	(segment
		(start 396.456154 -121.245884)
		(end 396.15745 -121.245884)
		(width 0.0889)
		(layer "In11.Cu")
		(net "P3E_PCH_M2_TX_DN<3>")
	)
	(segment
		(start 386.646928 -33.257744)
		(end 386.248656 -33.656016)
		(width 0.1143)
		(layer "In11.Cu")
		(net "P3E_PCH_M2_TX_DN<3>")
	)
	(segment
		(start 408.57805 -108.825538)
		(end 408.57805 -112.261396)
		(width 0.1143)
		(layer "In11.Cu")
		(net "P3E_PCH_M2_TX_DN<3>")
	)
	(segment
		(start 410.165296 -102.490016)
		(end 410.165296 -107.476544)
		(width 0.1143)
		(layer "In11.Cu")
		(net "P3E_PCH_M2_TX_DN<3>")
	)
	(segment
		(start 386.248656 -33.656016)
		(end 386.248656 -35.751516)
		(width 0.1143)
		(layer "In11.Cu")
		(net "P3E_PCH_M2_TX_DN<3>")
	)
	(segment
		(start 410.061664 -68.835524)
		(end 410.061664 -70.369938)
		(width 0.1143)
		(layer "In11.Cu")
		(net "P3E_PCH_M2_TX_DN<3>")
	)
	(segment
		(start 413.4612 -79.012288)
		(end 409.452064 -83.021424)
		(width 0.1143)
		(layer "In11.Cu")
		(net "P3E_PCH_M2_TX_DN<3>")
	)
	(segment
		(start 410.061664 -70.369938)
		(end 411.4673 -71.775574)
		(width 0.1143)
		(layer "In11.Cu")
		(net "P3E_PCH_M2_TX_DN<3>")
	)
	(segment
		(start 399.7706 -120.169686)
		(end 399.28546 -120.654826)
		(width 0.0889)
		(layer "In11.Cu")
		(net "P3E_PCH_M2_TX_DN<3>")
	)
	(segment
		(start 390.014714 -40.180768)
		(end 390.918192 -41.084246)
		(width 0.1143)
		(layer "In11.Cu")
		(net "P3E_PCH_M2_TX_DN<3>")
	)
	(arc
		(start 399.12925 -120.654826)
		(mid 398.976304 -120.675102)
		(end 398.833848 -120.734328)
		(width 0.0889)
		(layer "In11.Cu")
		(net "P3E_PCH_M2_TX_DN<3>")
	)
	(arc
		(start 396.852902 -120.73382)
		(mid 396.66663 -120.903019)
		(end 396.56766 -121.134378)
		(width 0.0889)
		(layer "In11.Cu")
		(net "P3E_PCH_M2_TX_DN<3>")
	)
	(arc
		(start 397.843248 -120.734074)
		(mid 397.64335 -120.787573)
		(end 397.443452 -120.734074)
		(width 0.0889)
		(layer "In11.Cu")
		(net "P3E_PCH_M2_TX_DN<3>")
	)
	(arc
		(start 398.434052 -120.734074)
		(mid 398.13865 -120.654943)
		(end 397.843248 -120.734074)
		(width 0.0889)
		(layer "In11.Cu")
		(net "P3E_PCH_M2_TX_DN<3>")
	)
	(arc
		(start 397.443452 -120.734074)
		(mid 397.148223 -120.654943)
		(end 396.852902 -120.73382)
		(width 0.0889)
		(layer "In11.Cu")
		(net "P3E_PCH_M2_TX_DN<3>")
	)
	(arc
		(start 398.833848 -120.734074)
		(mid 398.63395 -120.787573)
		(end 398.434052 -120.734074)
		(width 0.0889)
		(layer "In11.Cu")
		(net "P3E_PCH_M2_TX_DN<3>")
	)
	(segment
		(start 396.65275 -122.7328)
		(end 397.14805 -122.962924)
		(width 0.1143)
		(layer "F.Cu")
		(net "P3E_PCH_M2_TX_DN<2>")
	)
	(via
		(at 387.734302 -26.405332)
		(size 0.508)
		(drill 0.254)
		(layers "F.Cu" "B.Cu")
		(net "P3E_PCH_M2_TX_DN<2>")
	)
	(via
		(at 397.14805 -122.962924)
		(size 0.508)
		(drill 0.254)
		(layers "F.Cu" "B.Cu")
		(net "P3E_PCH_M2_TX_DN<2>")
	)
	(segment
		(start 386.720334 -26.875232)
		(end 387.264402 -26.875232)
		(width 0.1143)
		(layer "B.Cu")
		(net "P3E_PCH_M2_TX_DN<2>")
	)
	(segment
		(start 387.264402 -26.875232)
		(end 387.734302 -26.405332)
		(width 0.1143)
		(layer "B.Cu")
		(net "P3E_PCH_M2_TX_DN<2>")
	)
	(segment
		(start 386.352034 -26.506932)
		(end 386.720334 -26.875232)
		(width 0.1143)
		(layer "B.Cu")
		(net "P3E_PCH_M2_TX_DN<2>")
	)
	(segment
		(start 390.743948 -28.746958)
		(end 390.743948 -35.451796)
		(width 0.1143)
		(layer "In11.Cu")
		(net "P3E_PCH_M2_TX_DN<2>")
	)
	(segment
		(start 387.734302 -26.405332)
		(end 387.734302 -26.633678)
		(width 0.1143)
		(layer "In11.Cu")
		(net "P3E_PCH_M2_TX_DN<2>")
	)
	(segment
		(start 401.541488 -54.033928)
		(end 403.102572 -54.033928)
		(width 0.1143)
		(layer "In11.Cu")
		(net "P3E_PCH_M2_TX_DN<2>")
	)
	(segment
		(start 412.572708 -67.32905)
		(end 413.8803 -68.636642)
		(width 0.1143)
		(layer "In11.Cu")
		(net "P3E_PCH_M2_TX_DN<2>")
	)
	(segment
		(start 409.031694 -114.85245)
		(end 408.660346 -115.223798)
		(width 0.1143)
		(layer "In11.Cu")
		(net "P3E_PCH_M2_TX_DN<2>")
	)
	(segment
		(start 412.176722 -109.431582)
		(end 411.379162 -109.431582)
		(width 0.1143)
		(layer "In11.Cu")
		(net "P3E_PCH_M2_TX_DN<2>")
	)
	(segment
		(start 403.5806 -53.5559)
		(end 404.666704 -53.5559)
		(width 0.1143)
		(layer "In11.Cu")
		(net "P3E_PCH_M2_TX_DN<2>")
	)
	(segment
		(start 397.29283 -123.345448)
		(end 397.29283 -123.21413)
		(width 0.0889)
		(layer "In11.Cu")
		(net "P3E_PCH_M2_TX_DN<2>")
	)
	(segment
		(start 401.461986 -120.224804)
		(end 401.461986 -122.254772)
		(width 0.0889)
		(layer "In11.Cu")
		(net "P3E_PCH_M2_TX_DN<2>")
	)
	(segment
		(start 403.102572 -54.033928)
		(end 403.5806 -53.5559)
		(width 0.1143)
		(layer "In11.Cu")
		(net "P3E_PCH_M2_TX_DN<2>")
	)
	(segment
		(start 399.304256 -124.412502)
		(end 397.612108 -124.412502)
		(width 0.0889)
		(layer "In11.Cu")
		(net "P3E_PCH_M2_TX_DN<2>")
	)
	(segment
		(start 414.4264 -73.7108)
		(end 415.06521 -74.34961)
		(width 0.1143)
		(layer "In11.Cu")
		(net "P3E_PCH_M2_TX_DN<2>")
	)
	(segment
		(start 412.971742 -88.99525)
		(end 412.971742 -91.58478)
		(width 0.1143)
		(layer "In11.Cu")
		(net "P3E_PCH_M2_TX_DN<2>")
	)
	(segment
		(start 395.259306 -45.425106)
		(end 396.40764 -45.425106)
		(width 0.1143)
		(layer "In11.Cu")
		(net "P3E_PCH_M2_TX_DN<2>")
	)
	(segment
		(start 408.660346 -115.223798)
		(end 408.660346 -115.834414)
		(width 0.1143)
		(layer "In11.Cu")
		(net "P3E_PCH_M2_TX_DN<2>")
	)
	(segment
		(start 408.660346 -115.834414)
		(end 405.156162 -119.338598)
		(width 0.1143)
		(layer "In11.Cu")
		(net "P3E_PCH_M2_TX_DN<2>")
	)
	(segment
		(start 413.375348 -100.895658)
		(end 413.58185 -101.10216)
		(width 0.1143)
		(layer "In11.Cu")
		(net "P3E_PCH_M2_TX_DN<2>")
	)
	(segment
		(start 413.58185 -101.10216)
		(end 413.58185 -103.135176)
		(width 0.1143)
		(layer "In11.Cu")
		(net "P3E_PCH_M2_TX_DN<2>")
	)
	(segment
		(start 412.350204 -85.488018)
		(end 412.350204 -88.373712)
		(width 0.1143)
		(layer "In11.Cu")
		(net "P3E_PCH_M2_TX_DN<2>")
	)
	(segment
		(start 402.997924 -119.338598)
		(end 402.947124 -119.287798)
		(width 0.0889)
		(layer "In11.Cu")
		(net "P3E_PCH_M2_TX_DN<2>")
	)
	(segment
		(start 396.40764 -45.425106)
		(end 398.9451 -47.962566)
		(width 0.1143)
		(layer "In11.Cu")
		(net "P3E_PCH_M2_TX_DN<2>")
	)
	(segment
		(start 412.773368 -108.834936)
		(end 412.176722 -109.431582)
		(width 0.1143)
		(layer "In11.Cu")
		(net "P3E_PCH_M2_TX_DN<2>")
	)
	(segment
		(start 391.32637 -36.034218)
		(end 391.95756 -36.034218)
		(width 0.1143)
		(layer "In11.Cu")
		(net "P3E_PCH_M2_TX_DN<2>")
	)
	(segment
		(start 414.4264 -71.9836)
		(end 414.4264 -73.7108)
		(width 0.1143)
		(layer "In11.Cu")
		(net "P3E_PCH_M2_TX_DN<2>")
	)
	(segment
		(start 410.12364 -114.85245)
		(end 409.031694 -114.85245)
		(width 0.1143)
		(layer "In11.Cu")
		(net "P3E_PCH_M2_TX_DN<2>")
	)
	(segment
		(start 411.08884 -113.88725)
		(end 410.12364 -114.85245)
		(width 0.1143)
		(layer "In11.Cu")
		(net "P3E_PCH_M2_TX_DN<2>")
	)
	(segment
		(start 412.971742 -91.58478)
		(end 413.375348 -91.988386)
		(width 0.1143)
		(layer "In11.Cu")
		(net "P3E_PCH_M2_TX_DN<2>")
	)
	(segment
		(start 397.29283 -123.21413)
		(end 397.14805 -122.962924)
		(width 0.0889)
		(layer "In11.Cu")
		(net "P3E_PCH_M2_TX_DN<2>")
	)
	(segment
		(start 411.379162 -109.431582)
		(end 411.08884 -109.721904)
		(width 0.1143)
		(layer "In11.Cu")
		(net "P3E_PCH_M2_TX_DN<2>")
	)
	(segment
		(start 402.947124 -119.287798)
		(end 402.398992 -119.287798)
		(width 0.0889)
		(layer "In11.Cu")
		(net "P3E_PCH_M2_TX_DN<2>")
	)
	(segment
		(start 405.156162 -119.338598)
		(end 403.020022 -119.338598)
		(width 0.1143)
		(layer "In11.Cu")
		(net "P3E_PCH_M2_TX_DN<2>")
	)
	(segment
		(start 388.895082 -26.898092)
		(end 390.743948 -28.746958)
		(width 0.1143)
		(layer "In11.Cu")
		(net "P3E_PCH_M2_TX_DN<2>")
	)
	(segment
		(start 393.243816 -37.320474)
		(end 393.243816 -43.409616)
		(width 0.1143)
		(layer "In11.Cu")
		(net "P3E_PCH_M2_TX_DN<2>")
	)
	(segment
		(start 404.666704 -53.5559)
		(end 411.69844 -60.587636)
		(width 0.1143)
		(layer "In11.Cu")
		(net "P3E_PCH_M2_TX_DN<2>")
	)
	(segment
		(start 390.743948 -35.451796)
		(end 391.32637 -36.034218)
		(width 0.1143)
		(layer "In11.Cu")
		(net "P3E_PCH_M2_TX_DN<2>")
	)
	(segment
		(start 398.9451 -51.43754)
		(end 401.541488 -54.033928)
		(width 0.1143)
		(layer "In11.Cu")
		(net "P3E_PCH_M2_TX_DN<2>")
	)
	(segment
		(start 391.95756 -36.034218)
		(end 393.243816 -37.320474)
		(width 0.1143)
		(layer "In11.Cu")
		(net "P3E_PCH_M2_TX_DN<2>")
	)
	(segment
		(start 412.350204 -88.373712)
		(end 412.971742 -88.99525)
		(width 0.1143)
		(layer "In11.Cu")
		(net "P3E_PCH_M2_TX_DN<2>")
	)
	(segment
		(start 413.8803 -68.636642)
		(end 413.8803 -71.4375)
		(width 0.1143)
		(layer "In11.Cu")
		(net "P3E_PCH_M2_TX_DN<2>")
	)
	(segment
		(start 402.398992 -119.287798)
		(end 401.461986 -120.224804)
		(width 0.0889)
		(layer "In11.Cu")
		(net "P3E_PCH_M2_TX_DN<2>")
	)
	(segment
		(start 397.053054 -123.806966)
		(end 397.0528 -123.799854)
		(width 0.0889)
		(layer "In11.Cu")
		(net "P3E_PCH_M2_TX_DN<2>")
	)
	(segment
		(start 411.08884 -109.721904)
		(end 411.08884 -113.88725)
		(width 0.1143)
		(layer "In11.Cu")
		(net "P3E_PCH_M2_TX_DN<2>")
	)
	(segment
		(start 413.77362 -84.064602)
		(end 412.350204 -85.488018)
		(width 0.1143)
		(layer "In11.Cu")
		(net "P3E_PCH_M2_TX_DN<2>")
	)
	(segment
		(start 398.9451 -47.962566)
		(end 398.9451 -51.43754)
		(width 0.1143)
		(layer "In11.Cu")
		(net "P3E_PCH_M2_TX_DN<2>")
	)
	(segment
		(start 403.020022 -119.338598)
		(end 402.997924 -119.338598)
		(width 0.0889)
		(layer "In11.Cu")
		(net "P3E_PCH_M2_TX_DN<2>")
	)
	(segment
		(start 413.8803 -71.4375)
		(end 414.4264 -71.9836)
		(width 0.1143)
		(layer "In11.Cu")
		(net "P3E_PCH_M2_TX_DN<2>")
	)
	(segment
		(start 411.69844 -60.587636)
		(end 411.69844 -62.145926)
		(width 0.1143)
		(layer "In11.Cu")
		(net "P3E_PCH_M2_TX_DN<2>")
	)
	(segment
		(start 411.69844 -62.145926)
		(end 412.572708 -63.020194)
		(width 0.1143)
		(layer "In11.Cu")
		(net "P3E_PCH_M2_TX_DN<2>")
	)
	(segment
		(start 413.58185 -103.135176)
		(end 412.773368 -103.943658)
		(width 0.1143)
		(layer "In11.Cu")
		(net "P3E_PCH_M2_TX_DN<2>")
	)
	(segment
		(start 397.053054 -123.853448)
		(end 397.053054 -123.806966)
		(width 0.0889)
		(layer "In11.Cu")
		(net "P3E_PCH_M2_TX_DN<2>")
	)
	(segment
		(start 412.572708 -63.020194)
		(end 412.572708 -67.32905)
		(width 0.1143)
		(layer "In11.Cu")
		(net "P3E_PCH_M2_TX_DN<2>")
	)
	(segment
		(start 412.773368 -103.943658)
		(end 412.773368 -108.834936)
		(width 0.1143)
		(layer "In11.Cu")
		(net "P3E_PCH_M2_TX_DN<2>")
	)
	(segment
		(start 387.734302 -26.633678)
		(end 387.998716 -26.898092)
		(width 0.1143)
		(layer "In11.Cu")
		(net "P3E_PCH_M2_TX_DN<2>")
	)
	(segment
		(start 387.998716 -26.898092)
		(end 388.895082 -26.898092)
		(width 0.1143)
		(layer "In11.Cu")
		(net "P3E_PCH_M2_TX_DN<2>")
	)
	(segment
		(start 415.06521 -80.267048)
		(end 413.77362 -81.558638)
		(width 0.1143)
		(layer "In11.Cu")
		(net "P3E_PCH_M2_TX_DN<2>")
	)
	(segment
		(start 413.375348 -91.988386)
		(end 413.375348 -100.895658)
		(width 0.1143)
		(layer "In11.Cu")
		(net "P3E_PCH_M2_TX_DN<2>")
	)
	(segment
		(start 401.461986 -122.254772)
		(end 399.304256 -124.412502)
		(width 0.0889)
		(layer "In11.Cu")
		(net "P3E_PCH_M2_TX_DN<2>")
	)
	(segment
		(start 393.243816 -43.409616)
		(end 395.259306 -45.425106)
		(width 0.1143)
		(layer "In11.Cu")
		(net "P3E_PCH_M2_TX_DN<2>")
	)
	(segment
		(start 415.06521 -74.34961)
		(end 415.06521 -80.267048)
		(width 0.1143)
		(layer "In11.Cu")
		(net "P3E_PCH_M2_TX_DN<2>")
	)
	(segment
		(start 413.77362 -81.558638)
		(end 413.77362 -84.064602)
		(width 0.1143)
		(layer "In11.Cu")
		(net "P3E_PCH_M2_TX_DN<2>")
	)
	(arc
		(start 397.0528 -123.799854)
		(mid 397.120829 -123.545189)
		(end 397.29283 -123.345448)
		(width 0.0889)
		(layer "In11.Cu")
		(net "P3E_PCH_M2_TX_DN<2>")
	)
	(arc
		(start 397.612108 -124.412502)
		(mid 397.216797 -124.248759)
		(end 397.053054 -123.853448)
		(width 0.0889)
		(layer "In11.Cu")
		(net "P3E_PCH_M2_TX_DN<2>")
	)
	(segment
		(start 397.7894 -122.800618)
		(end 398.13865 -122.962924)
		(width 0.1143)
		(layer "F.Cu")
		(net "P3E_PCH_M2_TX_DN<1>")
	)
	(segment
		(start 397.64335 -122.7328)
		(end 397.7894 -122.800618)
		(width 0.1143)
		(layer "F.Cu")
		(net "P3E_PCH_M2_TX_DN<1>")
	)
	(via
		(at 398.13865 -122.962924)
		(size 0.508)
		(drill 0.254)
		(layers "F.Cu" "B.Cu")
		(net "P3E_PCH_M2_TX_DN<1>")
	)
	(via
		(at 387.734302 -29.405326)
		(size 0.508)
		(drill 0.254)
		(layers "F.Cu" "B.Cu")
		(net "P3E_PCH_M2_TX_DN<1>")
	)
	(segment
		(start 387.19379 -29.945838)
		(end 387.263894 -29.875734)
		(width 0.1143)
		(layer "B.Cu")
		(net "P3E_PCH_M2_TX_DN<1>")
	)
	(segment
		(start 386.23494 -29.555694)
		(end 386.625084 -29.945838)
		(width 0.1143)
		(layer "B.Cu")
		(net "P3E_PCH_M2_TX_DN<1>")
	)
	(segment
		(start 386.625084 -29.945838)
		(end 387.19379 -29.945838)
		(width 0.1143)
		(layer "B.Cu")
		(net "P3E_PCH_M2_TX_DN<1>")
	)
	(segment
		(start 387.524752 -29.614876)
		(end 387.734302 -29.405326)
		(width 0.1143)
		(layer "B.Cu")
		(net "P3E_PCH_M2_TX_DN<1>")
	)
	(segment
		(start 387.524752 -29.62656)
		(end 387.524752 -29.614876)
		(width 0.1143)
		(layer "B.Cu")
		(net "P3E_PCH_M2_TX_DN<1>")
	)
	(segment
		(start 387.275578 -29.875734)
		(end 387.524752 -29.62656)
		(width 0.1143)
		(layer "B.Cu")
		(net "P3E_PCH_M2_TX_DN<1>")
	)
	(segment
		(start 387.263894 -29.875734)
		(end 387.275578 -29.875734)
		(width 0.1143)
		(layer "B.Cu")
		(net "P3E_PCH_M2_TX_DN<1>")
	)
	(segment
		(start 411.617922 -69.591428)
		(end 411.972252 -69.945758)
		(width 0.1143)
		(layer "In11.Cu")
		(net "P3E_PCH_M2_TX_DN<1>")
	)
	(segment
		(start 400.54657 -122.175524)
		(end 399.463006 -123.259088)
		(width 0.0889)
		(layer "In11.Cu")
		(net "P3E_PCH_M2_TX_DN<1>")
	)
	(segment
		(start 387.734302 -29.779976)
		(end 387.848602 -29.894276)
		(width 0.1143)
		(layer "In11.Cu")
		(net "P3E_PCH_M2_TX_DN<1>")
	)
	(segment
		(start 400.54657 -120.15978)
		(end 400.54657 -122.175524)
		(width 0.0889)
		(layer "In11.Cu")
		(net "P3E_PCH_M2_TX_DN<1>")
	)
	(segment
		(start 414.43021 -79.908654)
		(end 410.749496 -83.589368)
		(width 0.1143)
		(layer "In11.Cu")
		(net "P3E_PCH_M2_TX_DN<1>")
	)
	(segment
		(start 409.860242 -114.21745)
		(end 408.614118 -114.21745)
		(width 0.1143)
		(layer "In11.Cu")
		(net "P3E_PCH_M2_TX_DN<1>")
	)
	(segment
		(start 413.78378 -74.001122)
		(end 414.43021 -74.647552)
		(width 0.1143)
		(layer "In11.Cu")
		(net "P3E_PCH_M2_TX_DN<1>")
	)
	(segment
		(start 413.78378 -72.432926)
		(end 413.78378 -74.001122)
		(width 0.1143)
		(layer "In11.Cu")
		(net "P3E_PCH_M2_TX_DN<1>")
	)
	(segment
		(start 414.43021 -74.647552)
		(end 414.43021 -79.908654)
		(width 0.1143)
		(layer "In11.Cu")
		(net "P3E_PCH_M2_TX_DN<1>")
	)
	(segment
		(start 398.3101 -48.41494)
		(end 398.3101 -52.249578)
		(width 0.1143)
		(layer "In11.Cu")
		(net "P3E_PCH_M2_TX_DN<1>")
	)
	(segment
		(start 398.3101 -52.249578)
		(end 402.277072 -56.21655)
		(width 0.1143)
		(layer "In11.Cu")
		(net "P3E_PCH_M2_TX_DN<1>")
	)
	(segment
		(start 399.463006 -123.259088)
		(end 398.820132 -123.259088)
		(width 0.0889)
		(layer "In11.Cu")
		(net "P3E_PCH_M2_TX_DN<1>")
	)
	(segment
		(start 398.59077 -122.91568)
		(end 398.479518 -122.856752)
		(width 0.0889)
		(layer "In11.Cu")
		(net "P3E_PCH_M2_TX_DN<1>")
	)
	(segment
		(start 412.0388 -103.669338)
		(end 412.0388 -104.3178)
		(width 0.1143)
		(layer "In11.Cu")
		(net "P3E_PCH_M2_TX_DN<1>")
	)
	(segment
		(start 412.731204 -92.706952)
		(end 412.731204 -101.149912)
		(width 0.1143)
		(layer "In11.Cu")
		(net "P3E_PCH_M2_TX_DN<1>")
	)
	(segment
		(start 412.517844 -69.945758)
		(end 413.0675 -70.495414)
		(width 0.1143)
		(layer "In11.Cu")
		(net "P3E_PCH_M2_TX_DN<1>")
	)
	(segment
		(start 410.749496 -87.671402)
		(end 412.336742 -89.258648)
		(width 0.1143)
		(layer "In11.Cu")
		(net "P3E_PCH_M2_TX_DN<1>")
	)
	(segment
		(start 392.492992 -40.245284)
		(end 391.955528 -40.782748)
		(width 0.1143)
		(layer "In11.Cu")
		(net "P3E_PCH_M2_TX_DN<1>")
	)
	(segment
		(start 390.741154 -36.790376)
		(end 391.81532 -36.790376)
		(width 0.1143)
		(layer "In11.Cu")
		(net "P3E_PCH_M2_TX_DN<1>")
	)
	(segment
		(start 411.0101 -65.901316)
		(end 411.617922 -66.509138)
		(width 0.1143)
		(layer "In11.Cu")
		(net "P3E_PCH_M2_TX_DN<1>")
	)
	(segment
		(start 404.301452 -118.45798)
		(end 404.06574 -118.693692)
		(width 0.0889)
		(layer "In11.Cu")
		(net "P3E_PCH_M2_TX_DN<1>")
	)
	(segment
		(start 410.749496 -83.589368)
		(end 410.749496 -87.671402)
		(width 0.1143)
		(layer "In11.Cu")
		(net "P3E_PCH_M2_TX_DN<1>")
	)
	(segment
		(start 388.78891 -29.894276)
		(end 389.814054 -30.91942)
		(width 0.1143)
		(layer "In11.Cu")
		(net "P3E_PCH_M2_TX_DN<1>")
	)
	(segment
		(start 389.814054 -35.863276)
		(end 390.741154 -36.790376)
		(width 0.1143)
		(layer "In11.Cu")
		(net "P3E_PCH_M2_TX_DN<1>")
	)
	(segment
		(start 412.94685 -102.761288)
		(end 412.0388 -103.669338)
		(width 0.1143)
		(layer "In11.Cu")
		(net "P3E_PCH_M2_TX_DN<1>")
	)
	(segment
		(start 412.0388 -104.3178)
		(end 411.092396 -105.264204)
		(width 0.1143)
		(layer "In11.Cu")
		(net "P3E_PCH_M2_TX_DN<1>")
	)
	(segment
		(start 398.820132 -123.259088)
		(end 398.642078 -123.081034)
		(width 0.0889)
		(layer "In11.Cu")
		(net "P3E_PCH_M2_TX_DN<1>")
	)
	(segment
		(start 402.277072 -56.21655)
		(end 406.362408 -56.21655)
		(width 0.1143)
		(layer "In11.Cu")
		(net "P3E_PCH_M2_TX_DN<1>")
	)
	(segment
		(start 396.119858 -46.224698)
		(end 398.3101 -48.41494)
		(width 0.1143)
		(layer "In11.Cu")
		(net "P3E_PCH_M2_TX_DN<1>")
	)
	(segment
		(start 391.81532 -36.790376)
		(end 392.492992 -37.468048)
		(width 0.1143)
		(layer "In11.Cu")
		(net "P3E_PCH_M2_TX_DN<1>")
	)
	(segment
		(start 387.848602 -29.894276)
		(end 388.78891 -29.894276)
		(width 0.1143)
		(layer "In11.Cu")
		(net "P3E_PCH_M2_TX_DN<1>")
	)
	(segment
		(start 410.44495 -108.508546)
		(end 410.44495 -113.632742)
		(width 0.1143)
		(layer "In11.Cu")
		(net "P3E_PCH_M2_TX_DN<1>")
	)
	(segment
		(start 391.955528 -43.342814)
		(end 394.837158 -46.224444)
		(width 0.1143)
		(layer "In11.Cu")
		(net "P3E_PCH_M2_TX_DN<1>")
	)
	(segment
		(start 410.44495 -113.632742)
		(end 409.860242 -114.21745)
		(width 0.1143)
		(layer "In11.Cu")
		(net "P3E_PCH_M2_TX_DN<1>")
	)
	(segment
		(start 402.012658 -118.693692)
		(end 400.54657 -120.15978)
		(width 0.0889)
		(layer "In11.Cu")
		(net "P3E_PCH_M2_TX_DN<1>")
	)
	(segment
		(start 412.336742 -92.31249)
		(end 412.731204 -92.706952)
		(width 0.1143)
		(layer "In11.Cu")
		(net "P3E_PCH_M2_TX_DN<1>")
	)
	(segment
		(start 408.614118 -114.21745)
		(end 404.381716 -118.449852)
		(width 0.1143)
		(layer "In11.Cu")
		(net "P3E_PCH_M2_TX_DN<1>")
	)
	(segment
		(start 387.734302 -29.405326)
		(end 387.734302 -29.779976)
		(width 0.1143)
		(layer "In11.Cu")
		(net "P3E_PCH_M2_TX_DN<1>")
	)
	(segment
		(start 412.336742 -89.258648)
		(end 412.336742 -92.31249)
		(width 0.1143)
		(layer "In11.Cu")
		(net "P3E_PCH_M2_TX_DN<1>")
	)
	(segment
		(start 404.373588 -118.45798)
		(end 404.301452 -118.45798)
		(width 0.0889)
		(layer "In11.Cu")
		(net "P3E_PCH_M2_TX_DN<1>")
	)
	(segment
		(start 411.0101 -60.864242)
		(end 411.0101 -65.901316)
		(width 0.1143)
		(layer "In11.Cu")
		(net "P3E_PCH_M2_TX_DN<1>")
	)
	(segment
		(start 404.06574 -118.693692)
		(end 402.012658 -118.693692)
		(width 0.0889)
		(layer "In11.Cu")
		(net "P3E_PCH_M2_TX_DN<1>")
	)
	(segment
		(start 404.381716 -118.449852)
		(end 404.373588 -118.45798)
		(width 0.0889)
		(layer "In11.Cu")
		(net "P3E_PCH_M2_TX_DN<1>")
	)
	(segment
		(start 413.0675 -70.495414)
		(end 413.0675 -71.716646)
		(width 0.1143)
		(layer "In11.Cu")
		(net "P3E_PCH_M2_TX_DN<1>")
	)
	(segment
		(start 394.89761 -46.224444)
		(end 394.897864 -46.224698)
		(width 0.1143)
		(layer "In11.Cu")
		(net "P3E_PCH_M2_TX_DN<1>")
	)
	(segment
		(start 412.94685 -101.365558)
		(end 412.94685 -102.761288)
		(width 0.1143)
		(layer "In11.Cu")
		(net "P3E_PCH_M2_TX_DN<1>")
	)
	(segment
		(start 398.642078 -123.081034)
		(end 398.59077 -122.91568)
		(width 0.0889)
		(layer "In11.Cu")
		(net "P3E_PCH_M2_TX_DN<1>")
	)
	(segment
		(start 394.897864 -46.224698)
		(end 396.119858 -46.224698)
		(width 0.1143)
		(layer "In11.Cu")
		(net "P3E_PCH_M2_TX_DN<1>")
	)
	(segment
		(start 406.362408 -56.21655)
		(end 411.0101 -60.864242)
		(width 0.1143)
		(layer "In11.Cu")
		(net "P3E_PCH_M2_TX_DN<1>")
	)
	(segment
		(start 398.479518 -122.856752)
		(end 398.13865 -122.962924)
		(width 0.0889)
		(layer "In11.Cu")
		(net "P3E_PCH_M2_TX_DN<1>")
	)
	(segment
		(start 392.492992 -37.468048)
		(end 392.492992 -40.245284)
		(width 0.1143)
		(layer "In11.Cu")
		(net "P3E_PCH_M2_TX_DN<1>")
	)
	(segment
		(start 411.617922 -66.509138)
		(end 411.617922 -69.591428)
		(width 0.1143)
		(layer "In11.Cu")
		(net "P3E_PCH_M2_TX_DN<1>")
	)
	(segment
		(start 412.731204 -101.149912)
		(end 412.94685 -101.365558)
		(width 0.1143)
		(layer "In11.Cu")
		(net "P3E_PCH_M2_TX_DN<1>")
	)
	(segment
		(start 394.837158 -46.224444)
		(end 394.89761 -46.224444)
		(width 0.1143)
		(layer "In11.Cu")
		(net "P3E_PCH_M2_TX_DN<1>")
	)
	(segment
		(start 391.955528 -40.782748)
		(end 391.955528 -43.342814)
		(width 0.1143)
		(layer "In11.Cu")
		(net "P3E_PCH_M2_TX_DN<1>")
	)
	(segment
		(start 389.814054 -30.91942)
		(end 389.814054 -35.863276)
		(width 0.1143)
		(layer "In11.Cu")
		(net "P3E_PCH_M2_TX_DN<1>")
	)
	(segment
		(start 411.972252 -69.945758)
		(end 412.517844 -69.945758)
		(width 0.1143)
		(layer "In11.Cu")
		(net "P3E_PCH_M2_TX_DN<1>")
	)
	(segment
		(start 413.0675 -71.716646)
		(end 413.78378 -72.432926)
		(width 0.1143)
		(layer "In11.Cu")
		(net "P3E_PCH_M2_TX_DN<1>")
	)
	(segment
		(start 411.092396 -105.264204)
		(end 411.092396 -107.8611)
		(width 0.1143)
		(layer "In11.Cu")
		(net "P3E_PCH_M2_TX_DN<1>")
	)
	(segment
		(start 411.092396 -107.8611)
		(end 410.44495 -108.508546)
		(width 0.1143)
		(layer "In11.Cu")
		(net "P3E_PCH_M2_TX_DN<1>")
	)
	(segment
		(start 383.587752 -24.184356)
		(end 383.501138 -24.27097)
		(width 0.1143)
		(layer "F.Cu")
		(net "P3E_PCH_M2_TX_C_DP<3>")
	)
	(segment
		(start 384.305302 -24.522684)
		(end 383.966974 -24.184356)
		(width 0.1143)
		(layer "F.Cu")
		(net "P3E_PCH_M2_TX_C_DP<3>")
	)
	(segment
		(start 383.966974 -24.184356)
		(end 383.587752 -24.184356)
		(width 0.1143)
		(layer "F.Cu")
		(net "P3E_PCH_M2_TX_C_DP<3>")
	)
	(segment
		(start 383.501138 -24.27097)
		(end 382.797304 -24.27097)
		(width 0.1143)
		(layer "F.Cu")
		(net "P3E_PCH_M2_TX_C_DP<3>")
	)
	(via
		(at 384.305302 -24.522684)
		(size 0.508)
		(drill 0.254)
		(layers "F.Cu" "B.Cu")
		(net "P3E_PCH_M2_TX_C_DP<3>")
	)
	(segment
		(start 384.305302 -24.522684)
		(end 384.668522 -24.885904)
		(width 0.1143)
		(layer "B.Cu")
		(net "P3E_PCH_M2_TX_C_DP<3>")
	)
	(segment
		(start 384.668522 -24.885904)
		(end 385.217924 -24.885904)
		(width 0.1143)
		(layer "B.Cu")
		(net "P3E_PCH_M2_TX_C_DP<3>")
	)
	(segment
		(start 384.183636 -27.160474)
		(end 383.611628 -27.160474)
		(width 0.1143)
		(layer "F.Cu")
		(net "P3E_PCH_M2_TX_C_DP<2>")
	)
	(segment
		(start 383.611628 -27.160474)
		(end 383.501138 -27.270964)
		(width 0.1143)
		(layer "F.Cu")
		(net "P3E_PCH_M2_TX_C_DP<2>")
	)
	(segment
		(start 383.501138 -27.270964)
		(end 382.797304 -27.270964)
		(width 0.1143)
		(layer "F.Cu")
		(net "P3E_PCH_M2_TX_C_DP<2>")
	)
	(segment
		(start 384.53949 -27.516328)
		(end 384.183636 -27.160474)
		(width 0.1143)
		(layer "F.Cu")
		(net "P3E_PCH_M2_TX_C_DP<2>")
	)
	(via
		(at 384.53949 -27.516328)
		(size 0.508)
		(drill 0.254)
		(layers "F.Cu" "B.Cu")
		(net "P3E_PCH_M2_TX_C_DP<2>")
	)
	(segment
		(start 385.09448 -27.154378)
		(end 385.463034 -27.522932)
		(width 0.1143)
		(layer "B.Cu")
		(net "P3E_PCH_M2_TX_C_DP<2>")
	)
	(segment
		(start 384.90144 -27.154378)
		(end 385.09448 -27.154378)
		(width 0.1143)
		(layer "B.Cu")
		(net "P3E_PCH_M2_TX_C_DP<2>")
	)
	(segment
		(start 384.53949 -27.516328)
		(end 384.90144 -27.154378)
		(width 0.1143)
		(layer "B.Cu")
		(net "P3E_PCH_M2_TX_C_DP<2>")
	)
	(segment
		(start 383.630424 -30.141672)
		(end 383.501138 -30.270958)
		(width 0.1143)
		(layer "F.Cu")
		(net "P3E_PCH_M2_TX_C_DP<1>")
	)
	(segment
		(start 384.16484 -30.141672)
		(end 383.630424 -30.141672)
		(width 0.1143)
		(layer "F.Cu")
		(net "P3E_PCH_M2_TX_C_DP<1>")
	)
	(segment
		(start 384.53949 -30.516322)
		(end 384.16484 -30.141672)
		(width 0.1143)
		(layer "F.Cu")
		(net "P3E_PCH_M2_TX_C_DP<1>")
	)
	(segment
		(start 383.501138 -30.270958)
		(end 382.797304 -30.270958)
		(width 0.1143)
		(layer "F.Cu")
		(net "P3E_PCH_M2_TX_C_DP<1>")
	)
	(via
		(at 384.53949 -30.516322)
		(size 0.508)
		(drill 0.254)
		(layers "F.Cu" "B.Cu")
		(net "P3E_PCH_M2_TX_C_DP<1>")
	)
	(segment
		(start 385.063238 -30.154372)
		(end 385.34594 -30.437074)
		(width 0.1143)
		(layer "B.Cu")
		(net "P3E_PCH_M2_TX_C_DP<1>")
	)
	(segment
		(start 384.53949 -30.516322)
		(end 384.90144 -30.154372)
		(width 0.1143)
		(layer "B.Cu")
		(net "P3E_PCH_M2_TX_C_DP<1>")
	)
	(segment
		(start 385.34594 -30.437074)
		(end 385.34594 -30.571694)
		(width 0.1143)
		(layer "B.Cu")
		(net "P3E_PCH_M2_TX_C_DP<1>")
	)
	(segment
		(start 384.90144 -30.154372)
		(end 385.063238 -30.154372)
		(width 0.1143)
		(layer "B.Cu")
		(net "P3E_PCH_M2_TX_C_DP<1>")
	)
	(segment
		(start 384.38709 -23.601934)
		(end 384.045968 -23.943056)
		(width 0.1143)
		(layer "F.Cu")
		(net "P3E_PCH_M2_TX_C_DN<3>")
	)
	(segment
		(start 383.500884 -23.770844)
		(end 382.797304 -23.770844)
		(width 0.1143)
		(layer "F.Cu")
		(net "P3E_PCH_M2_TX_C_DN<3>")
	)
	(segment
		(start 383.673096 -23.943056)
		(end 383.500884 -23.770844)
		(width 0.1143)
		(layer "F.Cu")
		(net "P3E_PCH_M2_TX_C_DN<3>")
	)
	(segment
		(start 384.045968 -23.943056)
		(end 383.673096 -23.943056)
		(width 0.1143)
		(layer "F.Cu")
		(net "P3E_PCH_M2_TX_C_DN<3>")
	)
	(via
		(at 384.38709 -23.601934)
		(size 0.508)
		(drill 0.254)
		(layers "F.Cu" "B.Cu")
		(net "P3E_PCH_M2_TX_C_DN<3>")
	)
	(segment
		(start 384.38709 -23.601934)
		(end 384.65506 -23.869904)
		(width 0.1143)
		(layer "B.Cu")
		(net "P3E_PCH_M2_TX_C_DN<3>")
	)
	(segment
		(start 384.65506 -23.869904)
		(end 385.217924 -23.869904)
		(width 0.1143)
		(layer "B.Cu")
		(net "P3E_PCH_M2_TX_C_DN<3>")
	)
	(segment
		(start 383.64922 -26.919174)
		(end 383.500884 -26.770838)
		(width 0.1143)
		(layer "F.Cu")
		(net "P3E_PCH_M2_TX_C_DN<2>")
	)
	(segment
		(start 383.500884 -26.770838)
		(end 382.797304 -26.770838)
		(width 0.1143)
		(layer "F.Cu")
		(net "P3E_PCH_M2_TX_C_DN<2>")
	)
	(segment
		(start 384.171444 -26.919174)
		(end 383.64922 -26.919174)
		(width 0.1143)
		(layer "F.Cu")
		(net "P3E_PCH_M2_TX_C_DN<2>")
	)
	(segment
		(start 384.53949 -26.551128)
		(end 384.171444 -26.919174)
		(width 0.1143)
		(layer "F.Cu")
		(net "P3E_PCH_M2_TX_C_DN<2>")
	)
	(via
		(at 384.53949 -26.551128)
		(size 0.508)
		(drill 0.254)
		(layers "F.Cu" "B.Cu")
		(net "P3E_PCH_M2_TX_C_DN<2>")
	)
	(segment
		(start 384.53949 -26.551128)
		(end 384.90144 -26.913078)
		(width 0.1143)
		(layer "B.Cu")
		(net "P3E_PCH_M2_TX_C_DN<2>")
	)
	(segment
		(start 384.90144 -26.913078)
		(end 385.056888 -26.913078)
		(width 0.1143)
		(layer "B.Cu")
		(net "P3E_PCH_M2_TX_C_DN<2>")
	)
	(segment
		(start 385.056888 -26.913078)
		(end 385.463034 -26.506932)
		(width 0.1143)
		(layer "B.Cu")
		(net "P3E_PCH_M2_TX_C_DN<2>")
	)
	(segment
		(start 383.630424 -29.900372)
		(end 384.19024 -29.900372)
		(width 0.1143)
		(layer "F.Cu")
		(net "P3E_PCH_M2_TX_C_DN<1>")
	)
	(segment
		(start 384.19024 -29.900372)
		(end 384.53949 -29.551122)
		(width 0.1143)
		(layer "F.Cu")
		(net "P3E_PCH_M2_TX_C_DN<1>")
	)
	(segment
		(start 383.500884 -29.770832)
		(end 383.630424 -29.900372)
		(width 0.1143)
		(layer "F.Cu")
		(net "P3E_PCH_M2_TX_C_DN<1>")
	)
	(segment
		(start 382.797304 -29.770832)
		(end 383.500884 -29.770832)
		(width 0.1143)
		(layer "F.Cu")
		(net "P3E_PCH_M2_TX_C_DN<1>")
	)
	(via
		(at 384.53949 -29.551122)
		(size 0.508)
		(drill 0.254)
		(layers "F.Cu" "B.Cu")
		(net "P3E_PCH_M2_TX_C_DN<1>")
	)
	(segment
		(start 385.34594 -29.63037)
		(end 385.34594 -29.555694)
		(width 0.1143)
		(layer "B.Cu")
		(net "P3E_PCH_M2_TX_C_DN<1>")
	)
	(segment
		(start 384.53949 -29.551122)
		(end 384.90144 -29.913072)
		(width 0.1143)
		(layer "B.Cu")
		(net "P3E_PCH_M2_TX_C_DN<1>")
	)
	(segment
		(start 385.063238 -29.913072)
		(end 385.34594 -29.63037)
		(width 0.1143)
		(layer "B.Cu")
		(net "P3E_PCH_M2_TX_C_DN<1>")
	)
	(segment
		(start 384.90144 -29.913072)
		(end 385.063238 -29.913072)
		(width 0.1143)
		(layer "B.Cu")
		(net "P3E_PCH_M2_TX_C_DN<1>")
	)
	(segment
		(start 381.5207 -33.141666)
		(end 379.376178 -33.141666)
		(width 0.1143)
		(layer "F.Cu")
		(net "P3E_PCH_M2_SATA6G_TX_R_DP")
	)
	(segment
		(start 379.376178 -33.141666)
		(end 379.143768 -33.374076)
		(width 0.1143)
		(layer "F.Cu")
		(net "P3E_PCH_M2_SATA6G_TX_R_DP")
	)
	(segment
		(start 382.797304 -33.270952)
		(end 381.649986 -33.270952)
		(width 0.1143)
		(layer "F.Cu")
		(net "P3E_PCH_M2_SATA6G_TX_R_DP")
	)
	(segment
		(start 379.143768 -33.374076)
		(end 379.143768 -33.7185)
		(width 0.1143)
		(layer "F.Cu")
		(net "P3E_PCH_M2_SATA6G_TX_R_DP")
	)
	(segment
		(start 381.649986 -33.270952)
		(end 381.5207 -33.141666)
		(width 0.1143)
		(layer "F.Cu")
		(net "P3E_PCH_M2_SATA6G_TX_R_DP")
	)
	(segment
		(start 382.797304 -32.770826)
		(end 381.65024 -32.770826)
		(width 0.1143)
		(layer "F.Cu")
		(net "P3E_PCH_M2_SATA6G_TX_R_DN")
	)
	(segment
		(start 379.143768 -32.667956)
		(end 379.143768 -32.3215)
		(width 0.1143)
		(layer "F.Cu")
		(net "P3E_PCH_M2_SATA6G_TX_R_DN")
	)
	(segment
		(start 381.5207 -32.900366)
		(end 379.376178 -32.900366)
		(width 0.1143)
		(layer "F.Cu")
		(net "P3E_PCH_M2_SATA6G_TX_R_DN")
	)
	(segment
		(start 379.376178 -32.900366)
		(end 379.143768 -32.667956)
		(width 0.1143)
		(layer "F.Cu")
		(net "P3E_PCH_M2_SATA6G_TX_R_DN")
	)
	(segment
		(start 381.65024 -32.770826)
		(end 381.5207 -32.900366)
		(width 0.1143)
		(layer "F.Cu")
		(net "P3E_PCH_M2_SATA6G_TX_R_DN")
	)
	(segment
		(start 381.772668 -31.270956)
		(end 381.385572 -30.88386)
		(width 0.1143)
		(layer "F.Cu")
		(net "P3E_PCH_M2_SATA6G_RX_R_DP")
	)
	(segment
		(start 378.572268 -29.867606)
		(end 378.4092 -29.704538)
		(width 0.1143)
		(layer "F.Cu")
		(net "P3E_PCH_M2_SATA6G_RX_R_DP")
	)
	(segment
		(start 382.797304 -31.270956)
		(end 381.772668 -31.270956)
		(width 0.1143)
		(layer "F.Cu")
		(net "P3E_PCH_M2_SATA6G_RX_R_DP")
	)
	(segment
		(start 378.4092 -29.704538)
		(end 378.4092 -29.232352)
		(width 0.1143)
		(layer "F.Cu")
		(net "P3E_PCH_M2_SATA6G_RX_R_DP")
	)
	(segment
		(start 381.385572 -30.39999)
		(end 380.853188 -29.867606)
		(width 0.1143)
		(layer "F.Cu")
		(net "P3E_PCH_M2_SATA6G_RX_R_DP")
	)
	(segment
		(start 381.385572 -30.88386)
		(end 381.385572 -30.39999)
		(width 0.1143)
		(layer "F.Cu")
		(net "P3E_PCH_M2_SATA6G_RX_R_DP")
	)
	(segment
		(start 380.853188 -29.867606)
		(end 378.572268 -29.867606)
		(width 0.1143)
		(layer "F.Cu")
		(net "P3E_PCH_M2_SATA6G_RX_R_DP")
	)
	(segment
		(start 382.797304 -31.770828)
		(end 381.931164 -31.770828)
		(width 0.1143)
		(layer "F.Cu")
		(net "P3E_PCH_M2_SATA6G_RX_R_DN")
	)
	(segment
		(start 380.753112 -30.108906)
		(end 378.541788 -30.108906)
		(width 0.1143)
		(layer "F.Cu")
		(net "P3E_PCH_M2_SATA6G_RX_R_DN")
	)
	(segment
		(start 381.931164 -31.770828)
		(end 381.144272 -30.983936)
		(width 0.1143)
		(layer "F.Cu")
		(net "P3E_PCH_M2_SATA6G_RX_R_DN")
	)
	(segment
		(start 381.144272 -30.983936)
		(end 381.144272 -30.500066)
		(width 0.1143)
		(layer "F.Cu")
		(net "P3E_PCH_M2_SATA6G_RX_R_DN")
	)
	(segment
		(start 381.144272 -30.500066)
		(end 380.753112 -30.108906)
		(width 0.1143)
		(layer "F.Cu")
		(net "P3E_PCH_M2_SATA6G_RX_R_DN")
	)
	(segment
		(start 378.4092 -30.241494)
		(end 378.4092 -30.629352)
		(width 0.1143)
		(layer "F.Cu")
		(net "P3E_PCH_M2_SATA6G_RX_R_DN")
	)
	(segment
		(start 378.541788 -30.108906)
		(end 378.4092 -30.241494)
		(width 0.1143)
		(layer "F.Cu")
		(net "P3E_PCH_M2_SATA6G_RX_R_DN")
	)
	(segment
		(start 391.3632 -128.9812)
		(end 391.58545 -128.9812)
		(width 0.0889)
		(layer "F.Cu")
		(net "P3E_PCH_M2_RX_DP<3>")
	)
	(segment
		(start 391.175494 -128.793494)
		(end 391.3632 -128.9812)
		(width 0.0889)
		(layer "F.Cu")
		(net "P3E_PCH_M2_RX_DP<3>")
	)
	(segment
		(start 390.984994 -125.33503)
		(end 390.984994 -125.707394)
		(width 0.0889)
		(layer "F.Cu")
		(net "P3E_PCH_M2_RX_DP<3>")
	)
	(segment
		(start 391.58545 -128.9812)
		(end 391.78865 -128.778)
		(width 0.0889)
		(layer "F.Cu")
		(net "P3E_PCH_M2_RX_DP<3>")
	)
	(segment
		(start 391.175494 -126.453138)
		(end 391.175494 -128.793494)
		(width 0.0889)
		(layer "F.Cu")
		(net "P3E_PCH_M2_RX_DP<3>")
	)
	(segment
		(start 391.287 -126.0094)
		(end 391.287 -126.341632)
		(width 0.0889)
		(layer "F.Cu")
		(net "P3E_PCH_M2_RX_DP<3>")
	)
	(segment
		(start 381.301244 -22.64918)
		(end 380.96825 -22.982174)
		(width 0.1143)
		(layer "F.Cu")
		(net "P3E_PCH_M2_RX_DP<3>")
	)
	(segment
		(start 381.824992 -22.7711)
		(end 381.703072 -22.64918)
		(width 0.1143)
		(layer "F.Cu")
		(net "P3E_PCH_M2_RX_DP<3>")
	)
	(segment
		(start 390.984994 -125.707394)
		(end 391.287 -126.0094)
		(width 0.0889)
		(layer "F.Cu")
		(net "P3E_PCH_M2_RX_DP<3>")
	)
	(segment
		(start 382.797304 -22.770846)
		(end 381.825246 -22.770846)
		(width 0.1143)
		(layer "F.Cu")
		(net "P3E_PCH_M2_RX_DP<3>")
	)
	(segment
		(start 381.825246 -22.770846)
		(end 381.824992 -22.7711)
		(width 0.1143)
		(layer "F.Cu")
		(net "P3E_PCH_M2_RX_DP<3>")
	)
	(segment
		(start 391.287 -126.341632)
		(end 391.175494 -126.453138)
		(width 0.0889)
		(layer "F.Cu")
		(net "P3E_PCH_M2_RX_DP<3>")
	)
	(segment
		(start 381.703072 -22.64918)
		(end 381.301244 -22.64918)
		(width 0.1143)
		(layer "F.Cu")
		(net "P3E_PCH_M2_RX_DP<3>")
	)
	(via
		(at 391.78865 -128.778)
		(size 0.508)
		(drill 0.254)
		(layers "F.Cu" "B.Cu")
		(net "P3E_PCH_M2_RX_DP<3>")
	)
	(via
		(at 380.96825 -22.982174)
		(size 0.508)
		(drill 0.254)
		(layers "F.Cu" "B.Cu")
		(net "P3E_PCH_M2_RX_DP<3>")
	)
	(segment
		(start 412.209488 -50.235866)
		(end 412.209488 -48.938688)
		(width 0.1143)
		(layer "In11.Cu")
		(net "P3E_PCH_M2_RX_DP<3>")
	)
	(segment
		(start 402.953474 -127.480314)
		(end 402.953474 -125.782578)
		(width 0.1143)
		(layer "In11.Cu")
		(net "P3E_PCH_M2_RX_DP<3>")
	)
	(segment
		(start 379.96622 -22.2631)
		(end 380.348744 -22.645624)
		(width 0.1143)
		(layer "In11.Cu")
		(net "P3E_PCH_M2_RX_DP<3>")
	)
	(segment
		(start 398.8435 -28.4607)
		(end 398.8435 -23.004526)
		(width 0.1143)
		(layer "In11.Cu")
		(net "P3E_PCH_M2_RX_DP<3>")
	)
	(segment
		(start 417.089844 -120.551956)
		(end 420.6494 -116.9924)
		(width 0.1143)
		(layer "In11.Cu")
		(net "P3E_PCH_M2_RX_DP<3>")
	)
	(segment
		(start 411.161992 -125.226318)
		(end 414.26511 -122.1232)
		(width 0.1143)
		(layer "In11.Cu")
		(net "P3E_PCH_M2_RX_DP<3>")
	)
	(segment
		(start 404.821136 -46.166532)
		(end 404.821136 -45.076872)
		(width 0.1143)
		(layer "In11.Cu")
		(net "P3E_PCH_M2_RX_DP<3>")
	)
	(segment
		(start 393.16406 -131.410202)
		(end 393.21486 -131.461002)
		(width 0.0889)
		(layer "In11.Cu")
		(net "P3E_PCH_M2_RX_DP<3>")
	)
	(segment
		(start 412.209488 -48.938688)
		(end 411.6324 -48.3616)
		(width 0.1143)
		(layer "In11.Cu")
		(net "P3E_PCH_M2_RX_DP<3>")
	)
	(segment
		(start 411.6324 -48.3616)
		(end 407.59253 -48.3616)
		(width 0.1143)
		(layer "In11.Cu")
		(net "P3E_PCH_M2_RX_DP<3>")
	)
	(segment
		(start 391.040874 -129.034032)
		(end 391.040874 -130.508248)
		(width 0.0889)
		(layer "In11.Cu")
		(net "P3E_PCH_M2_RX_DP<3>")
	)
	(segment
		(start 420.761668 -99.701604)
		(end 420.761668 -94.823026)
		(width 0.1143)
		(layer "In11.Cu")
		(net "P3E_PCH_M2_RX_DP<3>")
	)
	(segment
		(start 391.296906 -128.778)
		(end 391.040874 -129.034032)
		(width 0.0889)
		(layer "In11.Cu")
		(net "P3E_PCH_M2_RX_DP<3>")
	)
	(segment
		(start 421.763952 -75.563984)
		(end 421.951658 -75.376278)
		(width 0.1143)
		(layer "In11.Cu")
		(net "P3E_PCH_M2_RX_DP<3>")
	)
	(segment
		(start 421.2336 -109.258354)
		(end 421.2336 -100.173536)
		(width 0.1143)
		(layer "In11.Cu")
		(net "P3E_PCH_M2_RX_DP<3>")
	)
	(segment
		(start 422.147746 -80.405986)
		(end 421.040306 -79.298546)
		(width 0.1143)
		(layer "In11.Cu")
		(net "P3E_PCH_M2_RX_DP<3>")
	)
	(segment
		(start 420.6494 -109.842554)
		(end 421.2336 -109.258354)
		(width 0.1143)
		(layer "In11.Cu")
		(net "P3E_PCH_M2_RX_DP<3>")
	)
	(segment
		(start 404.3807 -125.3363)
		(end 404.490682 -125.226318)
		(width 0.1143)
		(layer "In11.Cu")
		(net "P3E_PCH_M2_RX_DP<3>")
	)
	(segment
		(start 380.706884 -18.640044)
		(end 380.706884 -20.246594)
		(width 0.1143)
		(layer "In11.Cu")
		(net "P3E_PCH_M2_RX_DP<3>")
	)
	(segment
		(start 421.951658 -65.09258)
		(end 420.37 -63.510922)
		(width 0.1143)
		(layer "In11.Cu")
		(net "P3E_PCH_M2_RX_DP<3>")
	)
	(segment
		(start 391.995914 -16.15694)
		(end 383.189988 -16.15694)
		(width 0.1143)
		(layer "In11.Cu")
		(net "P3E_PCH_M2_RX_DP<3>")
	)
	(segment
		(start 404.821136 -45.076872)
		(end 402.775928 -43.031664)
		(width 0.1143)
		(layer "In11.Cu")
		(net "P3E_PCH_M2_RX_DP<3>")
	)
	(segment
		(start 417.089844 -121.477278)
		(end 417.089844 -120.551956)
		(width 0.1143)
		(layer "In11.Cu")
		(net "P3E_PCH_M2_RX_DP<3>")
	)
	(segment
		(start 402.775928 -42.056304)
		(end 401.673822 -40.954198)
		(width 0.1143)
		(layer "In11.Cu")
		(net "P3E_PCH_M2_RX_DP<3>")
	)
	(segment
		(start 421.951658 -75.376278)
		(end 421.951658 -65.09258)
		(width 0.1143)
		(layer "In11.Cu")
		(net "P3E_PCH_M2_RX_DP<3>")
	)
	(segment
		(start 416.443922 -122.1232)
		(end 417.089844 -121.477278)
		(width 0.1143)
		(layer "In11.Cu")
		(net "P3E_PCH_M2_RX_DP<3>")
	)
	(segment
		(start 391.040874 -130.508248)
		(end 391.942828 -131.410202)
		(width 0.0889)
		(layer "In11.Cu")
		(net "P3E_PCH_M2_RX_DP<3>")
	)
	(segment
		(start 420.37 -57.676542)
		(end 417.2966 -54.603142)
		(width 0.1143)
		(layer "In11.Cu")
		(net "P3E_PCH_M2_RX_DP<3>")
	)
	(segment
		(start 405.727154 -47.07255)
		(end 404.821136 -46.166532)
		(width 0.1143)
		(layer "In11.Cu")
		(net "P3E_PCH_M2_RX_DP<3>")
	)
	(segment
		(start 399.758916 -130.674872)
		(end 402.953474 -127.480314)
		(width 0.1143)
		(layer "In11.Cu")
		(net "P3E_PCH_M2_RX_DP<3>")
	)
	(segment
		(start 420.6494 -116.9924)
		(end 420.6494 -109.842554)
		(width 0.1143)
		(layer "In11.Cu")
		(net "P3E_PCH_M2_RX_DP<3>")
	)
	(segment
		(start 406.30348 -47.07255)
		(end 405.727154 -47.07255)
		(width 0.1143)
		(layer "In11.Cu")
		(net "P3E_PCH_M2_RX_DP<3>")
	)
	(segment
		(start 401.673822 -40.954198)
		(end 401.673822 -34.914332)
		(width 0.1143)
		(layer "In11.Cu")
		(net "P3E_PCH_M2_RX_DP<3>")
	)
	(segment
		(start 403.399752 -125.3363)
		(end 404.3807 -125.3363)
		(width 0.1143)
		(layer "In11.Cu")
		(net "P3E_PCH_M2_RX_DP<3>")
	)
	(segment
		(start 420.761668 -94.823026)
		(end 422.147746 -93.436948)
		(width 0.1143)
		(layer "In11.Cu")
		(net "P3E_PCH_M2_RX_DP<3>")
	)
	(segment
		(start 400.6723 -33.91281)
		(end 400.6723 -30.2895)
		(width 0.1143)
		(layer "In11.Cu")
		(net "P3E_PCH_M2_RX_DP<3>")
	)
	(segment
		(start 422.147746 -93.436948)
		(end 422.147746 -80.405986)
		(width 0.1143)
		(layer "In11.Cu")
		(net "P3E_PCH_M2_RX_DP<3>")
	)
	(segment
		(start 391.78865 -128.778)
		(end 391.296906 -128.778)
		(width 0.0889)
		(layer "In11.Cu")
		(net "P3E_PCH_M2_RX_DP<3>")
	)
	(segment
		(start 398.8435 -23.004526)
		(end 391.995914 -16.15694)
		(width 0.1143)
		(layer "In11.Cu")
		(net "P3E_PCH_M2_RX_DP<3>")
	)
	(segment
		(start 400.6723 -30.2895)
		(end 398.8435 -28.4607)
		(width 0.1143)
		(layer "In11.Cu")
		(net "P3E_PCH_M2_RX_DP<3>")
	)
	(segment
		(start 407.59253 -48.3616)
		(end 406.30348 -47.07255)
		(width 0.1143)
		(layer "In11.Cu")
		(net "P3E_PCH_M2_RX_DP<3>")
	)
	(segment
		(start 417.2966 -53.256942)
		(end 416.020758 -51.9811)
		(width 0.1143)
		(layer "In11.Cu")
		(net "P3E_PCH_M2_RX_DP<3>")
	)
	(segment
		(start 380.706884 -20.246594)
		(end 379.96622 -20.987258)
		(width 0.1143)
		(layer "In11.Cu")
		(net "P3E_PCH_M2_RX_DP<3>")
	)
	(segment
		(start 380.348744 -22.645624)
		(end 380.6317 -22.645624)
		(width 0.1143)
		(layer "In11.Cu")
		(net "P3E_PCH_M2_RX_DP<3>")
	)
	(segment
		(start 420.37 -63.510922)
		(end 420.37 -57.676542)
		(width 0.1143)
		(layer "In11.Cu")
		(net "P3E_PCH_M2_RX_DP<3>")
	)
	(segment
		(start 383.189988 -16.15694)
		(end 380.706884 -18.640044)
		(width 0.1143)
		(layer "In11.Cu")
		(net "P3E_PCH_M2_RX_DP<3>")
	)
	(segment
		(start 414.26511 -122.1232)
		(end 416.443922 -122.1232)
		(width 0.1143)
		(layer "In11.Cu")
		(net "P3E_PCH_M2_RX_DP<3>")
	)
	(segment
		(start 395.918944 -131.461002)
		(end 396.705074 -130.674872)
		(width 0.1143)
		(layer "In11.Cu")
		(net "P3E_PCH_M2_RX_DP<3>")
	)
	(segment
		(start 393.236958 -131.461002)
		(end 395.918944 -131.461002)
		(width 0.1143)
		(layer "In11.Cu")
		(net "P3E_PCH_M2_RX_DP<3>")
	)
	(segment
		(start 396.705074 -130.674872)
		(end 399.758916 -130.674872)
		(width 0.1143)
		(layer "In11.Cu")
		(net "P3E_PCH_M2_RX_DP<3>")
	)
	(segment
		(start 402.775928 -43.031664)
		(end 402.775928 -42.056304)
		(width 0.1143)
		(layer "In11.Cu")
		(net "P3E_PCH_M2_RX_DP<3>")
	)
	(segment
		(start 417.2966 -54.603142)
		(end 417.2966 -53.256942)
		(width 0.1143)
		(layer "In11.Cu")
		(net "P3E_PCH_M2_RX_DP<3>")
	)
	(segment
		(start 421.2336 -100.173536)
		(end 420.761668 -99.701604)
		(width 0.1143)
		(layer "In11.Cu")
		(net "P3E_PCH_M2_RX_DP<3>")
	)
	(segment
		(start 421.040306 -78.334616)
		(end 421.763952 -77.61097)
		(width 0.1143)
		(layer "In11.Cu")
		(net "P3E_PCH_M2_RX_DP<3>")
	)
	(segment
		(start 402.953474 -125.782578)
		(end 403.399752 -125.3363)
		(width 0.1143)
		(layer "In11.Cu")
		(net "P3E_PCH_M2_RX_DP<3>")
	)
	(segment
		(start 393.21486 -131.461002)
		(end 393.236958 -131.461002)
		(width 0.0889)
		(layer "In11.Cu")
		(net "P3E_PCH_M2_RX_DP<3>")
	)
	(segment
		(start 421.040306 -79.298546)
		(end 421.040306 -78.334616)
		(width 0.1143)
		(layer "In11.Cu")
		(net "P3E_PCH_M2_RX_DP<3>")
	)
	(segment
		(start 421.763952 -77.61097)
		(end 421.763952 -75.563984)
		(width 0.1143)
		(layer "In11.Cu")
		(net "P3E_PCH_M2_RX_DP<3>")
	)
	(segment
		(start 380.6317 -22.645624)
		(end 380.96825 -22.982174)
		(width 0.1143)
		(layer "In11.Cu")
		(net "P3E_PCH_M2_RX_DP<3>")
	)
	(segment
		(start 391.942828 -131.410202)
		(end 393.16406 -131.410202)
		(width 0.0889)
		(layer "In11.Cu")
		(net "P3E_PCH_M2_RX_DP<3>")
	)
	(segment
		(start 416.020758 -51.9811)
		(end 413.954722 -51.9811)
		(width 0.1143)
		(layer "In11.Cu")
		(net "P3E_PCH_M2_RX_DP<3>")
	)
	(segment
		(start 401.673822 -34.914332)
		(end 400.6723 -33.91281)
		(width 0.1143)
		(layer "In11.Cu")
		(net "P3E_PCH_M2_RX_DP<3>")
	)
	(segment
		(start 413.954722 -51.9811)
		(end 412.209488 -50.235866)
		(width 0.1143)
		(layer "In11.Cu")
		(net "P3E_PCH_M2_RX_DP<3>")
	)
	(segment
		(start 379.96622 -20.987258)
		(end 379.96622 -22.2631)
		(width 0.1143)
		(layer "In11.Cu")
		(net "P3E_PCH_M2_RX_DP<3>")
	)
	(segment
		(start 404.490682 -125.226318)
		(end 411.161992 -125.226318)
		(width 0.1143)
		(layer "In11.Cu")
		(net "P3E_PCH_M2_RX_DP<3>")
	)
	(segment
		(start 391.79881 -125.60681)
		(end 391.79881 -125.816868)
		(width 0.0889)
		(layer "F.Cu")
		(net "P3E_PCH_M2_RX_DP<2>")
	)
	(segment
		(start 391.6934 -126.071376)
		(end 391.6934 -126.75235)
		(width 0.0889)
		(layer "F.Cu")
		(net "P3E_PCH_M2_RX_DP<2>")
	)
	(segment
		(start 391.79881 -125.816868)
		(end 391.6934 -126.071376)
		(width 0.0889)
		(layer "F.Cu")
		(net "P3E_PCH_M2_RX_DP<2>")
	)
	(segment
		(start 381.824992 -25.771094)
		(end 381.779526 -25.725628)
		(width 0.1143)
		(layer "F.Cu")
		(net "P3E_PCH_M2_RX_DP<2>")
	)
	(segment
		(start 381.09525 -25.725628)
		(end 380.723394 -26.097484)
		(width 0.1143)
		(layer "F.Cu")
		(net "P3E_PCH_M2_RX_DP<2>")
	)
	(segment
		(start 391.622534 -125.38075)
		(end 391.64387 -125.45187)
		(width 0.0889)
		(layer "F.Cu")
		(net "P3E_PCH_M2_RX_DP<2>")
	)
	(segment
		(start 391.48512 -124.919994)
		(end 391.622534 -125.38075)
		(width 0.0889)
		(layer "F.Cu")
		(net "P3E_PCH_M2_RX_DP<2>")
	)
	(segment
		(start 381.779526 -25.725628)
		(end 381.09525 -25.725628)
		(width 0.1143)
		(layer "F.Cu")
		(net "P3E_PCH_M2_RX_DP<2>")
	)
	(segment
		(start 391.6934 -126.75235)
		(end 391.78865 -126.8476)
		(width 0.0889)
		(layer "F.Cu")
		(net "P3E_PCH_M2_RX_DP<2>")
	)
	(segment
		(start 391.64387 -125.45187)
		(end 391.79881 -125.60681)
		(width 0.0889)
		(layer "F.Cu")
		(net "P3E_PCH_M2_RX_DP<2>")
	)
	(segment
		(start 382.797304 -25.77084)
		(end 381.825246 -25.77084)
		(width 0.1143)
		(layer "F.Cu")
		(net "P3E_PCH_M2_RX_DP<2>")
	)
	(segment
		(start 381.825246 -25.77084)
		(end 381.824992 -25.771094)
		(width 0.1143)
		(layer "F.Cu")
		(net "P3E_PCH_M2_RX_DP<2>")
	)
	(segment
		(start 380.723394 -26.097484)
		(end 380.65964 -26.097484)
		(width 0.1143)
		(layer "F.Cu")
		(net "P3E_PCH_M2_RX_DP<2>")
	)
	(via
		(at 380.65964 -26.097484)
		(size 0.508)
		(drill 0.254)
		(layers "F.Cu" "B.Cu")
		(net "P3E_PCH_M2_RX_DP<2>")
	)
	(via
		(at 391.78865 -126.8476)
		(size 0.508)
		(drill 0.254)
		(layers "F.Cu" "B.Cu")
		(net "P3E_PCH_M2_RX_DP<2>")
	)
	(segment
		(start 418.927534 -116.47424)
		(end 419.16096 -116.47424)
		(width 0.1143)
		(layer "In11.Cu")
		(net "P3E_PCH_M2_RX_DP<2>")
	)
	(segment
		(start 399.669 -37.020246)
		(end 399.669 -33.462722)
		(width 0.1143)
		(layer "In11.Cu")
		(net "P3E_PCH_M2_RX_DP<2>")
	)
	(segment
		(start 384.320288 -17.322038)
		(end 383.581402 -17.322038)
		(width 0.1143)
		(layer "In11.Cu")
		(net "P3E_PCH_M2_RX_DP<2>")
	)
	(segment
		(start 392.180318 -127.02159)
		(end 392.405108 -127.24638)
		(width 0.0889)
		(layer "In11.Cu")
		(net "P3E_PCH_M2_RX_DP<2>")
	)
	(segment
		(start 397.733266 -28.767024)
		(end 397.733266 -23.61438)
		(width 0.1143)
		(layer "In11.Cu")
		(net "P3E_PCH_M2_RX_DP<2>")
	)
	(segment
		(start 418.685218 -116.949982)
		(end 418.685218 -116.716556)
		(width 0.1143)
		(layer "In11.Cu")
		(net "P3E_PCH_M2_RX_DP<2>")
	)
	(segment
		(start 401.848828 -42.44086)
		(end 399.9992 -40.591232)
		(width 0.1143)
		(layer "In11.Cu")
		(net "P3E_PCH_M2_RX_DP<2>")
	)
	(segment
		(start 383.581402 -17.322038)
		(end 381.9017 -19.00174)
		(width 0.1143)
		(layer "In11.Cu")
		(net "P3E_PCH_M2_RX_DP<2>")
	)
	(segment
		(start 394.653008 -130.368802)
		(end 394.818108 -130.533902)
		(width 0.1143)
		(layer "In11.Cu")
		(net "P3E_PCH_M2_RX_DP<2>")
	)
	(segment
		(start 398.63395 -30.983428)
		(end 398.63395 -29.667708)
		(width 0.1143)
		(layer "In11.Cu")
		(net "P3E_PCH_M2_RX_DP<2>")
	)
	(segment
		(start 400.587464 -127.61341)
		(end 400.587464 -127.05334)
		(width 0.1143)
		(layer "In11.Cu")
		(net "P3E_PCH_M2_RX_DP<2>")
	)
	(segment
		(start 399.669 -33.462722)
		(end 399.0848 -32.878522)
		(width 0.1143)
		(layer "In11.Cu")
		(net "P3E_PCH_M2_RX_DP<2>")
	)
	(segment
		(start 404.177246 -124.1679)
		(end 408.158442 -124.1679)
		(width 0.1143)
		(layer "In11.Cu")
		(net "P3E_PCH_M2_RX_DP<2>")
	)
	(segment
		(start 417.49091 -117.910864)
		(end 417.724336 -117.910864)
		(width 0.1143)
		(layer "In11.Cu")
		(net "P3E_PCH_M2_RX_DP<2>")
	)
	(segment
		(start 419.4429 -58.160158)
		(end 414.575244 -53.292502)
		(width 0.1143)
		(layer "In11.Cu")
		(net "P3E_PCH_M2_RX_DP<2>")
	)
	(segment
		(start 399.37182 -129.747772)
		(end 400.587464 -128.532128)
		(width 0.1143)
		(layer "In11.Cu")
		(net "P3E_PCH_M2_RX_DP<2>")
	)
	(segment
		(start 392.68527 -130.015742)
		(end 392.68527 -130.273044)
		(width 0.1143)
		(layer "In11.Cu")
		(net "P3E_PCH_M2_RX_DP<2>")
	)
	(segment
		(start 392.405108 -127.24638)
		(end 392.405108 -127.482854)
		(width 0.0889)
		(layer "In11.Cu")
		(net "P3E_PCH_M2_RX_DP<2>")
	)
	(segment
		(start 415.811716 -119.823484)
		(end 415.811716 -119.590058)
		(width 0.1143)
		(layer "In11.Cu")
		(net "P3E_PCH_M2_RX_DP<2>")
	)
	(segment
		(start 418.209222 -117.192552)
		(end 418.442648 -117.192552)
		(width 0.1143)
		(layer "In11.Cu")
		(net "P3E_PCH_M2_RX_DP<2>")
	)
	(segment
		(start 391.78865 -126.8476)
		(end 391.96264 -127.02159)
		(width 0.0889)
		(layer "In11.Cu")
		(net "P3E_PCH_M2_RX_DP<2>")
	)
	(segment
		(start 392.4046 -127.483362)
		(end 392.4046 -127.686308)
		(width 0.0889)
		(layer "In11.Cu")
		(net "P3E_PCH_M2_RX_DP<2>")
	)
	(segment
		(start 398.63395 -29.667708)
		(end 397.733266 -28.767024)
		(width 0.1143)
		(layer "In11.Cu")
		(net "P3E_PCH_M2_RX_DP<2>")
	)
	(segment
		(start 397.733266 -23.61438)
		(end 391.440924 -17.322038)
		(width 0.1143)
		(layer "In11.Cu")
		(net "P3E_PCH_M2_RX_DP<2>")
	)
	(segment
		(start 400.587464 -126.38024)
		(end 400.587464 -126.122938)
		(width 0.1143)
		(layer "In11.Cu")
		(net "P3E_PCH_M2_RX_DP<2>")
	)
	(segment
		(start 408.657044 -123.669298)
		(end 411.367224 -123.669298)
		(width 0.1143)
		(layer "In11.Cu")
		(net "P3E_PCH_M2_RX_DP<2>")
	)
	(segment
		(start 416.772598 -118.629176)
		(end 417.006024 -118.629176)
		(width 0.1143)
		(layer "In11.Cu")
		(net "P3E_PCH_M2_RX_DP<2>")
	)
	(segment
		(start 400.587464 -128.28651)
		(end 400.422364 -128.12141)
		(width 0.1143)
		(layer "In11.Cu")
		(net "P3E_PCH_M2_RX_DP<2>")
	)
	(segment
		(start 403.871938 -45.459396)
		(end 401.848828 -43.436286)
		(width 0.1143)
		(layer "In11.Cu")
		(net "P3E_PCH_M2_RX_DP<2>")
	)
	(segment
		(start 419.834568 -94.43847)
		(end 421.1828 -93.090238)
		(width 0.1143)
		(layer "In11.Cu")
		(net "P3E_PCH_M2_RX_DP<2>")
	)
	(segment
		(start 405.918924 -47.99965)
		(end 405.342598 -47.99965)
		(width 0.1143)
		(layer "In11.Cu")
		(net "P3E_PCH_M2_RX_DP<2>")
	)
	(segment
		(start 381.9017 -19.00174)
		(end 381.9017 -25.256236)
		(width 0.1143)
		(layer "In11.Cu")
		(net "P3E_PCH_M2_RX_DP<2>")
	)
	(segment
		(start 394.818108 -130.533902)
		(end 395.51864 -130.533902)
		(width 0.1143)
		(layer "In11.Cu")
		(net "P3E_PCH_M2_RX_DP<2>")
	)
	(segment
		(start 399.9992 -40.060372)
		(end 398.9197 -38.980872)
		(width 0.1143)
		(layer "In11.Cu")
		(net "P3E_PCH_M2_RX_DP<2>")
	)
	(segment
		(start 400.422364 -128.12141)
		(end 400.422364 -127.77851)
		(width 0.1143)
		(layer "In11.Cu")
		(net "P3E_PCH_M2_RX_DP<2>")
	)
	(segment
		(start 418.442648 -117.192552)
		(end 418.685218 -116.949982)
		(width 0.1143)
		(layer "In11.Cu")
		(net "P3E_PCH_M2_RX_DP<2>")
	)
	(segment
		(start 398.9197 -38.980872)
		(end 398.9197 -37.769546)
		(width 0.1143)
		(layer "In11.Cu")
		(net "P3E_PCH_M2_RX_DP<2>")
	)
	(segment
		(start 394.145008 -130.533902)
		(end 394.310108 -130.368802)
		(width 0.1143)
		(layer "In11.Cu")
		(net "P3E_PCH_M2_RX_DP<2>")
	)
	(segment
		(start 417.724336 -117.910864)
		(end 417.966906 -117.668294)
		(width 0.1143)
		(layer "In11.Cu")
		(net "P3E_PCH_M2_RX_DP<2>")
	)
	(segment
		(start 417.006024 -118.629176)
		(end 417.248594 -118.386606)
		(width 0.1143)
		(layer "In11.Cu")
		(net "P3E_PCH_M2_RX_DP<2>")
	)
	(segment
		(start 400.587464 -126.122938)
		(end 402.847302 -123.8631)
		(width 0.1143)
		(layer "In11.Cu")
		(net "P3E_PCH_M2_RX_DP<2>")
	)
	(segment
		(start 417.248594 -118.386606)
		(end 417.248594 -118.15318)
		(width 0.1143)
		(layer "In11.Cu")
		(net "P3E_PCH_M2_RX_DP<2>")
	)
	(segment
		(start 384.828288 -17.487138)
		(end 384.485388 -17.487138)
		(width 0.1143)
		(layer "In11.Cu")
		(net "P3E_PCH_M2_RX_DP<2>")
	)
	(segment
		(start 419.16096 -116.47424)
		(end 419.6207 -116.0145)
		(width 0.1143)
		(layer "In11.Cu")
		(net "P3E_PCH_M2_RX_DP<2>")
	)
	(segment
		(start 399.0848 -32.878522)
		(end 399.0848 -31.434278)
		(width 0.1143)
		(layer "In11.Cu")
		(net "P3E_PCH_M2_RX_DP<2>")
	)
	(segment
		(start 416.054286 -119.347488)
		(end 416.287712 -119.347488)
		(width 0.1143)
		(layer "In11.Cu")
		(net "P3E_PCH_M2_RX_DP<2>")
	)
	(segment
		(start 407.290778 -49.371504)
		(end 405.918924 -47.99965)
		(width 0.1143)
		(layer "In11.Cu")
		(net "P3E_PCH_M2_RX_DP<2>")
	)
	(segment
		(start 414.575244 -53.292502)
		(end 413.512508 -53.292502)
		(width 0.1143)
		(layer "In11.Cu")
		(net "P3E_PCH_M2_RX_DP<2>")
	)
	(segment
		(start 402.847302 -123.8631)
		(end 403.872446 -123.8631)
		(width 0.1143)
		(layer "In11.Cu")
		(net "P3E_PCH_M2_RX_DP<2>")
	)
	(segment
		(start 384.485388 -17.487138)
		(end 384.320288 -17.322038)
		(width 0.1143)
		(layer "In11.Cu")
		(net "P3E_PCH_M2_RX_DP<2>")
	)
	(segment
		(start 399.0848 -31.434278)
		(end 398.63395 -30.983428)
		(width 0.1143)
		(layer "In11.Cu")
		(net "P3E_PCH_M2_RX_DP<2>")
	)
	(segment
		(start 385.501388 -17.487138)
		(end 385.336288 -17.322038)
		(width 0.1143)
		(layer "In11.Cu")
		(net "P3E_PCH_M2_RX_DP<2>")
	)
	(segment
		(start 403.871938 -46.52899)
		(end 403.871938 -45.459396)
		(width 0.1143)
		(layer "In11.Cu")
		(net "P3E_PCH_M2_RX_DP<2>")
	)
	(segment
		(start 400.422364 -126.88824)
		(end 400.422364 -126.54534)
		(width 0.1143)
		(layer "In11.Cu")
		(net "P3E_PCH_M2_RX_DP<2>")
	)
	(segment
		(start 391.96264 -127.02159)
		(end 392.180318 -127.02159)
		(width 0.0889)
		(layer "In11.Cu")
		(net "P3E_PCH_M2_RX_DP<2>")
	)
	(segment
		(start 400.587464 -128.532128)
		(end 400.587464 -128.28651)
		(width 0.1143)
		(layer "In11.Cu")
		(net "P3E_PCH_M2_RX_DP<2>")
	)
	(segment
		(start 405.342598 -47.99965)
		(end 403.871938 -46.52899)
		(width 0.1143)
		(layer "In11.Cu")
		(net "P3E_PCH_M2_RX_DP<2>")
	)
	(segment
		(start 392.63447 -129.942844)
		(end 392.68527 -129.993644)
		(width 0.0889)
		(layer "In11.Cu")
		(net "P3E_PCH_M2_RX_DP<2>")
	)
	(segment
		(start 392.68527 -130.273044)
		(end 392.946128 -130.533902)
		(width 0.1143)
		(layer "In11.Cu")
		(net "P3E_PCH_M2_RX_DP<2>")
	)
	(segment
		(start 421.1828 -80.752696)
		(end 420.051738 -79.621634)
		(width 0.1143)
		(layer "In11.Cu")
		(net "P3E_PCH_M2_RX_DP<2>")
	)
	(segment
		(start 419.6207 -116.0145)
		(end 419.6207 -109.39526)
		(width 0.1143)
		(layer "In11.Cu")
		(net "P3E_PCH_M2_RX_DP<2>")
	)
	(segment
		(start 384.993388 -17.322038)
		(end 384.828288 -17.487138)
		(width 0.1143)
		(layer "In11.Cu")
		(net "P3E_PCH_M2_RX_DP<2>")
	)
	(segment
		(start 380.985522 -25.840182)
		(end 380.72822 -26.097484)
		(width 0.1143)
		(layer "In11.Cu")
		(net "P3E_PCH_M2_RX_DP<2>")
	)
	(segment
		(start 380.72822 -26.097484)
		(end 380.65964 -26.097484)
		(width 0.1143)
		(layer "In11.Cu")
		(net "P3E_PCH_M2_RX_DP<2>")
	)
	(segment
		(start 392.4046 -127.686308)
		(end 392.63447 -127.916178)
		(width 0.0889)
		(layer "In11.Cu")
		(net "P3E_PCH_M2_RX_DP<2>")
	)
	(segment
		(start 417.966906 -117.668294)
		(end 417.966906 -117.434868)
		(width 0.1143)
		(layer "In11.Cu")
		(net "P3E_PCH_M2_RX_DP<2>")
	)
	(segment
		(start 400.422364 -126.54534)
		(end 400.587464 -126.38024)
		(width 0.1143)
		(layer "In11.Cu")
		(net "P3E_PCH_M2_RX_DP<2>")
	)
	(segment
		(start 421.1828 -93.090238)
		(end 421.1828 -80.752696)
		(width 0.1143)
		(layer "In11.Cu")
		(net "P3E_PCH_M2_RX_DP<2>")
	)
	(segment
		(start 413.512508 -53.292502)
		(end 409.59151 -49.371504)
		(width 0.1143)
		(layer "In11.Cu")
		(net "P3E_PCH_M2_RX_DP<2>")
	)
	(segment
		(start 386.009388 -17.322038)
		(end 385.844288 -17.487138)
		(width 0.1143)
		(layer "In11.Cu")
		(net "P3E_PCH_M2_RX_DP<2>")
	)
	(segment
		(start 385.336288 -17.322038)
		(end 384.993388 -17.322038)
		(width 0.1143)
		(layer "In11.Cu")
		(net "P3E_PCH_M2_RX_DP<2>")
	)
	(segment
		(start 392.405108 -127.482854)
		(end 392.4046 -127.483362)
		(width 0.0889)
		(layer "In11.Cu")
		(net "P3E_PCH_M2_RX_DP<2>")
	)
	(segment
		(start 419.4429 -69.310758)
		(end 419.4429 -58.160158)
		(width 0.1143)
		(layer "In11.Cu")
		(net "P3E_PCH_M2_RX_DP<2>")
	)
	(segment
		(start 420.051738 -79.621634)
		(end 420.051738 -69.919596)
		(width 0.1143)
		(layer "In11.Cu")
		(net "P3E_PCH_M2_RX_DP<2>")
	)
	(segment
		(start 403.872446 -123.8631)
		(end 404.177246 -124.1679)
		(width 0.1143)
		(layer "In11.Cu")
		(net "P3E_PCH_M2_RX_DP<2>")
	)
	(segment
		(start 392.63447 -127.916178)
		(end 392.63447 -129.942844)
		(width 0.0889)
		(layer "In11.Cu")
		(net "P3E_PCH_M2_RX_DP<2>")
	)
	(segment
		(start 381.317754 -25.840182)
		(end 380.985522 -25.840182)
		(width 0.1143)
		(layer "In11.Cu")
		(net "P3E_PCH_M2_RX_DP<2>")
	)
	(segment
		(start 401.848828 -43.436286)
		(end 401.848828 -42.44086)
		(width 0.1143)
		(layer "In11.Cu")
		(net "P3E_PCH_M2_RX_DP<2>")
	)
	(segment
		(start 408.158442 -124.1679)
		(end 408.657044 -123.669298)
		(width 0.1143)
		(layer "In11.Cu")
		(net "P3E_PCH_M2_RX_DP<2>")
	)
	(segment
		(start 417.248594 -118.15318)
		(end 417.49091 -117.910864)
		(width 0.1143)
		(layer "In11.Cu")
		(net "P3E_PCH_M2_RX_DP<2>")
	)
	(segment
		(start 415.811716 -119.590058)
		(end 416.054286 -119.347488)
		(width 0.1143)
		(layer "In11.Cu")
		(net "P3E_PCH_M2_RX_DP<2>")
	)
	(segment
		(start 398.9197 -37.769546)
		(end 399.669 -37.020246)
		(width 0.1143)
		(layer "In11.Cu")
		(net "P3E_PCH_M2_RX_DP<2>")
	)
	(segment
		(start 419.834568 -94.755208)
		(end 419.834568 -94.43847)
		(width 0.1143)
		(layer "In11.Cu")
		(net "P3E_PCH_M2_RX_DP<2>")
	)
	(segment
		(start 420.2049 -103.321358)
		(end 419.2905 -102.406958)
		(width 0.1143)
		(layer "In11.Cu")
		(net "P3E_PCH_M2_RX_DP<2>")
	)
	(segment
		(start 394.310108 -130.368802)
		(end 394.653008 -130.368802)
		(width 0.1143)
		(layer "In11.Cu")
		(net "P3E_PCH_M2_RX_DP<2>")
	)
	(segment
		(start 420.2049 -108.81106)
		(end 420.2049 -103.321358)
		(width 0.1143)
		(layer "In11.Cu")
		(net "P3E_PCH_M2_RX_DP<2>")
	)
	(segment
		(start 417.966906 -117.434868)
		(end 418.209222 -117.192552)
		(width 0.1143)
		(layer "In11.Cu")
		(net "P3E_PCH_M2_RX_DP<2>")
	)
	(segment
		(start 400.422364 -127.77851)
		(end 400.587464 -127.61341)
		(width 0.1143)
		(layer "In11.Cu")
		(net "P3E_PCH_M2_RX_DP<2>")
	)
	(segment
		(start 391.440924 -17.322038)
		(end 386.009388 -17.322038)
		(width 0.1143)
		(layer "In11.Cu")
		(net "P3E_PCH_M2_RX_DP<2>")
	)
	(segment
		(start 419.2905 -102.406958)
		(end 419.2905 -95.299276)
		(width 0.1143)
		(layer "In11.Cu")
		(net "P3E_PCH_M2_RX_DP<2>")
	)
	(segment
		(start 392.946128 -130.533902)
		(end 394.145008 -130.533902)
		(width 0.1143)
		(layer "In11.Cu")
		(net "P3E_PCH_M2_RX_DP<2>")
	)
	(segment
		(start 419.6207 -109.39526)
		(end 420.2049 -108.81106)
		(width 0.1143)
		(layer "In11.Cu")
		(net "P3E_PCH_M2_RX_DP<2>")
	)
	(segment
		(start 399.9992 -40.591232)
		(end 399.9992 -40.060372)
		(width 0.1143)
		(layer "In11.Cu")
		(net "P3E_PCH_M2_RX_DP<2>")
	)
	(segment
		(start 411.367224 -123.669298)
		(end 413.949896 -121.086626)
		(width 0.1143)
		(layer "In11.Cu")
		(net "P3E_PCH_M2_RX_DP<2>")
	)
	(segment
		(start 400.587464 -127.05334)
		(end 400.422364 -126.88824)
		(width 0.1143)
		(layer "In11.Cu")
		(net "P3E_PCH_M2_RX_DP<2>")
	)
	(segment
		(start 385.844288 -17.487138)
		(end 385.501388 -17.487138)
		(width 0.1143)
		(layer "In11.Cu")
		(net "P3E_PCH_M2_RX_DP<2>")
	)
	(segment
		(start 395.51864 -130.533902)
		(end 396.30477 -129.747772)
		(width 0.1143)
		(layer "In11.Cu")
		(net "P3E_PCH_M2_RX_DP<2>")
	)
	(segment
		(start 392.68527 -129.993644)
		(end 392.68527 -130.015742)
		(width 0.0889)
		(layer "In11.Cu")
		(net "P3E_PCH_M2_RX_DP<2>")
	)
	(segment
		(start 414.548574 -121.086626)
		(end 415.811716 -119.823484)
		(width 0.1143)
		(layer "In11.Cu")
		(net "P3E_PCH_M2_RX_DP<2>")
	)
	(segment
		(start 396.30477 -129.747772)
		(end 399.37182 -129.747772)
		(width 0.1143)
		(layer "In11.Cu")
		(net "P3E_PCH_M2_RX_DP<2>")
	)
	(segment
		(start 418.685218 -116.716556)
		(end 418.927534 -116.47424)
		(width 0.1143)
		(layer "In11.Cu")
		(net "P3E_PCH_M2_RX_DP<2>")
	)
	(segment
		(start 381.9017 -25.256236)
		(end 381.317754 -25.840182)
		(width 0.1143)
		(layer "In11.Cu")
		(net "P3E_PCH_M2_RX_DP<2>")
	)
	(segment
		(start 413.949896 -121.086626)
		(end 414.548574 -121.086626)
		(width 0.1143)
		(layer "In11.Cu")
		(net "P3E_PCH_M2_RX_DP<2>")
	)
	(segment
		(start 416.530282 -118.871492)
		(end 416.772598 -118.629176)
		(width 0.1143)
		(layer "In11.Cu")
		(net "P3E_PCH_M2_RX_DP<2>")
	)
	(segment
		(start 419.2905 -95.299276)
		(end 419.834568 -94.755208)
		(width 0.1143)
		(layer "In11.Cu")
		(net "P3E_PCH_M2_RX_DP<2>")
	)
	(segment
		(start 416.530282 -119.104918)
		(end 416.530282 -118.871492)
		(width 0.1143)
		(layer "In11.Cu")
		(net "P3E_PCH_M2_RX_DP<2>")
	)
	(segment
		(start 416.287712 -119.347488)
		(end 416.530282 -119.104918)
		(width 0.1143)
		(layer "In11.Cu")
		(net "P3E_PCH_M2_RX_DP<2>")
	)
	(segment
		(start 420.051738 -69.919596)
		(end 419.4429 -69.310758)
		(width 0.1143)
		(layer "In11.Cu")
		(net "P3E_PCH_M2_RX_DP<2>")
	)
	(segment
		(start 409.59151 -49.371504)
		(end 407.290778 -49.371504)
		(width 0.1143)
		(layer "In11.Cu")
		(net "P3E_PCH_M2_RX_DP<2>")
	)
	(segment
		(start 392.270742 -125.9967)
		(end 392.270742 -126.469902)
		(width 0.0889)
		(layer "F.Cu")
		(net "P3E_PCH_M2_RX_DP<1>")
	)
	(segment
		(start 392.46556 -127.926846)
		(end 392.46556 -129.4257)
		(width 0.0889)
		(layer "F.Cu")
		(net "P3E_PCH_M2_RX_DP<1>")
	)
	(segment
		(start 391.984992 -125.33503)
		(end 392.001756 -125.38075)
		(width 0.0889)
		(layer "F.Cu")
		(net "P3E_PCH_M2_RX_DP<1>")
	)
	(segment
		(start 392.3919 -126.59106)
		(end 392.3919 -127.853186)
		(width 0.0889)
		(layer "F.Cu")
		(net "P3E_PCH_M2_RX_DP<1>")
	)
	(segment
		(start 381.726948 -28.673044)
		(end 381.824992 -28.771088)
		(width 0.1143)
		(layer "F.Cu")
		(net "P3E_PCH_M2_RX_DP<1>")
	)
	(segment
		(start 392.270742 -126.469902)
		(end 392.3919 -126.59106)
		(width 0.0889)
		(layer "F.Cu")
		(net "P3E_PCH_M2_RX_DP<1>")
	)
	(segment
		(start 392.3919 -127.853186)
		(end 392.46556 -127.926846)
		(width 0.0889)
		(layer "F.Cu")
		(net "P3E_PCH_M2_RX_DP<1>")
	)
	(segment
		(start 393.0904 -129.5146)
		(end 393.2682 -129.3368)
		(width 0.0889)
		(layer "F.Cu")
		(net "P3E_PCH_M2_RX_DP<1>")
	)
	(segment
		(start 381.825246 -28.770834)
		(end 382.797304 -28.770834)
		(width 0.1143)
		(layer "F.Cu")
		(net "P3E_PCH_M2_RX_DP<1>")
	)
	(segment
		(start 381.497078 -28.673044)
		(end 381.726948 -28.673044)
		(width 0.1143)
		(layer "F.Cu")
		(net "P3E_PCH_M2_RX_DP<1>")
	)
	(segment
		(start 392.001756 -125.38075)
		(end 392.04011 -125.485652)
		(width 0.0889)
		(layer "F.Cu")
		(net "P3E_PCH_M2_RX_DP<1>")
	)
	(segment
		(start 392.04011 -125.485652)
		(end 392.202416 -125.928374)
		(width 0.0889)
		(layer "F.Cu")
		(net "P3E_PCH_M2_RX_DP<1>")
	)
	(segment
		(start 381.824992 -28.771088)
		(end 381.825246 -28.770834)
		(width 0.1143)
		(layer "F.Cu")
		(net "P3E_PCH_M2_RX_DP<1>")
	)
	(segment
		(start 392.202416 -125.928374)
		(end 392.270742 -125.9967)
		(width 0.0889)
		(layer "F.Cu")
		(net "P3E_PCH_M2_RX_DP<1>")
	)
	(segment
		(start 381.11557 -29.054552)
		(end 381.497078 -28.673044)
		(width 0.1143)
		(layer "F.Cu")
		(net "P3E_PCH_M2_RX_DP<1>")
	)
	(segment
		(start 392.46556 -129.4257)
		(end 392.55446 -129.5146)
		(width 0.0889)
		(layer "F.Cu")
		(net "P3E_PCH_M2_RX_DP<1>")
	)
	(segment
		(start 392.55446 -129.5146)
		(end 393.0904 -129.5146)
		(width 0.0889)
		(layer "F.Cu")
		(net "P3E_PCH_M2_RX_DP<1>")
	)
	(via
		(at 393.2682 -129.3368)
		(size 0.508)
		(drill 0.254)
		(layers "F.Cu" "B.Cu")
		(net "P3E_PCH_M2_RX_DP<1>")
	)
	(via
		(at 381.11557 -29.054552)
		(size 0.508)
		(drill 0.254)
		(layers "F.Cu" "B.Cu")
		(net "P3E_PCH_M2_RX_DP<1>")
	)
	(segment
		(start 417.657534 -116.3701)
		(end 417.414964 -116.612416)
		(width 0.1143)
		(layer "In11.Cu")
		(net "P3E_PCH_M2_RX_DP<1>")
	)
	(segment
		(start 394.738606 -126.0983)
		(end 394.1953 -126.641606)
		(width 0.0889)
		(layer "In11.Cu")
		(net "P3E_PCH_M2_RX_DP<1>")
	)
	(segment
		(start 420.501064 -86.365842)
		(end 420.501064 -86.708742)
		(width 0.1143)
		(layer "In11.Cu")
		(net "P3E_PCH_M2_RX_DP<1>")
	)
	(segment
		(start 413.806132 -120.257062)
		(end 411.063694 -122.9995)
		(width 0.1143)
		(layer "In11.Cu")
		(net "P3E_PCH_M2_RX_DP<1>")
	)
	(segment
		(start 414.61436 -118.5418)
		(end 413.806132 -119.350028)
		(width 0.1143)
		(layer "In11.Cu")
		(net "P3E_PCH_M2_RX_DP<1>")
	)
	(segment
		(start 383.826766 -18.51406)
		(end 391.68578 -18.51406)
		(width 0.1143)
		(layer "In11.Cu")
		(net "P3E_PCH_M2_RX_DP<1>")
	)
	(segment
		(start 418.375846 -115.651788)
		(end 418.13353 -115.894104)
		(width 0.1143)
		(layer "In11.Cu")
		(net "P3E_PCH_M2_RX_DP<1>")
	)
	(segment
		(start 420.335964 -87.889842)
		(end 420.335964 -88.232742)
		(width 0.1143)
		(layer "In11.Cu")
		(net "P3E_PCH_M2_RX_DP<1>")
	)
	(segment
		(start 391.68578 -18.51406)
		(end 397.098266 -23.926546)
		(width 0.1143)
		(layer "In11.Cu")
		(net "P3E_PCH_M2_RX_DP<1>")
	)
	(segment
		(start 398.3863 -31.646368)
		(end 398.3863 -33.177226)
		(width 0.1143)
		(layer "In11.Cu")
		(net "P3E_PCH_M2_RX_DP<1>")
	)
	(segment
		(start 403.231604 -46.836584)
		(end 403.7457 -47.35068)
		(width 0.1143)
		(layer "In11.Cu")
		(net "P3E_PCH_M2_RX_DP<1>")
	)
	(segment
		(start 381.691388 -28.76169)
		(end 382.314958 -28.13812)
		(width 0.1143)
		(layer "In11.Cu")
		(net "P3E_PCH_M2_RX_DP<1>")
	)
	(segment
		(start 420.335964 -87.216742)
		(end 420.501064 -87.381842)
		(width 0.1143)
		(layer "In11.Cu")
		(net "P3E_PCH_M2_RX_DP<1>")
	)
	(segment
		(start 398.2847 -39.250112)
		(end 399.288 -40.253412)
		(width 0.1143)
		(layer "In11.Cu")
		(net "P3E_PCH_M2_RX_DP<1>")
	)
	(segment
		(start 420.335964 -88.905842)
		(end 420.335964 -89.248742)
		(width 0.1143)
		(layer "In11.Cu")
		(net "P3E_PCH_M2_RX_DP<1>")
	)
	(segment
		(start 401.213828 -43.699684)
		(end 403.231604 -45.71746)
		(width 0.1143)
		(layer "In11.Cu")
		(net "P3E_PCH_M2_RX_DP<1>")
	)
	(segment
		(start 382.314958 -28.13812)
		(end 382.314958 -25.760934)
		(width 0.1143)
		(layer "In11.Cu")
		(net "P3E_PCH_M2_RX_DP<1>")
	)
	(segment
		(start 414.337754 -53.95341)
		(end 418.8079 -58.423556)
		(width 0.1143)
		(layer "In11.Cu")
		(net "P3E_PCH_M2_RX_DP<1>")
	)
	(segment
		(start 397.664686 -125.8824)
		(end 397.321786 -125.8824)
		(width 0.1143)
		(layer "In11.Cu")
		(net "P3E_PCH_M2_RX_DP<1>")
	)
	(segment
		(start 411.063694 -122.9995)
		(end 402.536914 -122.9995)
		(width 0.1143)
		(layer "In11.Cu")
		(net "P3E_PCH_M2_RX_DP<1>")
	)
	(segment
		(start 420.501064 -80.99933)
		(end 420.501064 -85.692742)
		(width 0.1143)
		(layer "In11.Cu")
		(net "P3E_PCH_M2_RX_DP<1>")
	)
	(segment
		(start 398.9959 -36.772342)
		(end 398.2847 -37.483542)
		(width 0.1143)
		(layer "In11.Cu")
		(net "P3E_PCH_M2_RX_DP<1>")
	)
	(segment
		(start 420.501064 -88.740742)
		(end 420.335964 -88.905842)
		(width 0.1143)
		(layer "In11.Cu")
		(net "P3E_PCH_M2_RX_DP<1>")
	)
	(segment
		(start 399.288 -40.77843)
		(end 401.213828 -42.704258)
		(width 0.1143)
		(layer "In11.Cu")
		(net "P3E_PCH_M2_RX_DP<1>")
	)
	(segment
		(start 397.321786 -125.8824)
		(end 397.156686 -126.0475)
		(width 0.1143)
		(layer "In11.Cu")
		(net "P3E_PCH_M2_RX_DP<1>")
	)
	(segment
		(start 420.335964 -89.248742)
		(end 420.501064 -89.413842)
		(width 0.1143)
		(layer "In11.Cu")
		(net "P3E_PCH_M2_RX_DP<1>")
	)
	(segment
		(start 420.501064 -92.873576)
		(end 419.199568 -94.175072)
		(width 0.1143)
		(layer "In11.Cu")
		(net "P3E_PCH_M2_RX_DP<1>")
	)
	(segment
		(start 420.501064 -86.708742)
		(end 420.335964 -86.873842)
		(width 0.1143)
		(layer "In11.Cu")
		(net "P3E_PCH_M2_RX_DP<1>")
	)
	(segment
		(start 393.50315 -129.57175)
		(end 393.2682 -129.3368)
		(width 0.0889)
		(layer "In11.Cu")
		(net "P3E_PCH_M2_RX_DP<1>")
	)
	(segment
		(start 420.501064 -87.381842)
		(end 420.501064 -87.724742)
		(width 0.1143)
		(layer "In11.Cu")
		(net "P3E_PCH_M2_RX_DP<1>")
	)
	(segment
		(start 381.408432 -28.76169)
		(end 381.691388 -28.76169)
		(width 0.1143)
		(layer "In11.Cu")
		(net "P3E_PCH_M2_RX_DP<1>")
	)
	(segment
		(start 398.3863 -33.177226)
		(end 398.9959 -33.786826)
		(width 0.1143)
		(layer "In11.Cu")
		(net "P3E_PCH_M2_RX_DP<1>")
	)
	(segment
		(start 402.536914 -122.9995)
		(end 399.488914 -126.0475)
		(width 0.1143)
		(layer "In11.Cu")
		(net "P3E_PCH_M2_RX_DP<1>")
	)
	(segment
		(start 419.199568 -94.49181)
		(end 418.465 -95.226378)
		(width 0.1143)
		(layer "In11.Cu")
		(net "P3E_PCH_M2_RX_DP<1>")
	)
	(segment
		(start 420.335964 -85.857842)
		(end 420.335964 -86.200742)
		(width 0.1143)
		(layer "In11.Cu")
		(net "P3E_PCH_M2_RX_DP<1>")
	)
	(segment
		(start 399.288 -40.253412)
		(end 399.288 -40.77843)
		(width 0.1143)
		(layer "In11.Cu")
		(net "P3E_PCH_M2_RX_DP<1>")
	)
	(segment
		(start 407.535126 -51.0286)
		(end 410.350208 -51.0286)
		(width 0.1143)
		(layer "In11.Cu")
		(net "P3E_PCH_M2_RX_DP<1>")
	)
	(segment
		(start 396.5956 -126.0475)
		(end 396.573502 -126.0475)
		(width 0.0889)
		(layer "In11.Cu")
		(net "P3E_PCH_M2_RX_DP<1>")
	)
	(segment
		(start 381.11557 -29.054552)
		(end 381.408432 -28.76169)
		(width 0.1143)
		(layer "In11.Cu")
		(net "P3E_PCH_M2_RX_DP<1>")
	)
	(segment
		(start 420.335964 -86.200742)
		(end 420.501064 -86.365842)
		(width 0.1143)
		(layer "In11.Cu")
		(net "P3E_PCH_M2_RX_DP<1>")
	)
	(segment
		(start 397.098266 -23.926546)
		(end 397.098266 -29.186378)
		(width 0.1143)
		(layer "In11.Cu")
		(net "P3E_PCH_M2_RX_DP<1>")
	)
	(segment
		(start 418.609272 -115.651788)
		(end 418.375846 -115.651788)
		(width 0.1143)
		(layer "In11.Cu")
		(net "P3E_PCH_M2_RX_DP<1>")
	)
	(segment
		(start 393.62888 -129.57175)
		(end 393.50315 -129.57175)
		(width 0.0889)
		(layer "In11.Cu")
		(net "P3E_PCH_M2_RX_DP<1>")
	)
	(segment
		(start 418.8079 -58.423556)
		(end 418.8079 -69.742304)
		(width 0.1143)
		(layer "In11.Cu")
		(net "P3E_PCH_M2_RX_DP<1>")
	)
	(segment
		(start 404.516336 -49.771808)
		(end 406.278334 -49.771808)
		(width 0.1143)
		(layer "In11.Cu")
		(net "P3E_PCH_M2_RX_DP<1>")
	)
	(segment
		(start 420.501064 -85.692742)
		(end 420.335964 -85.857842)
		(width 0.1143)
		(layer "In11.Cu")
		(net "P3E_PCH_M2_RX_DP<1>")
	)
	(segment
		(start 399.488914 -126.0475)
		(end 397.829786 -126.0475)
		(width 0.1143)
		(layer "In11.Cu")
		(net "P3E_PCH_M2_RX_DP<1>")
	)
	(segment
		(start 397.9926 -31.252668)
		(end 398.3863 -31.646368)
		(width 0.1143)
		(layer "In11.Cu")
		(net "P3E_PCH_M2_RX_DP<1>")
	)
	(segment
		(start 394.1953 -126.641606)
		(end 394.1953 -129.00533)
		(width 0.0889)
		(layer "In11.Cu")
		(net "P3E_PCH_M2_RX_DP<1>")
	)
	(segment
		(start 382.5367 -19.804126)
		(end 383.826766 -18.51406)
		(width 0.1143)
		(layer "In11.Cu")
		(net "P3E_PCH_M2_RX_DP<1>")
	)
	(segment
		(start 419.416738 -70.351142)
		(end 419.416738 -79.915004)
		(width 0.1143)
		(layer "In11.Cu")
		(net "P3E_PCH_M2_RX_DP<1>")
	)
	(segment
		(start 418.465 -95.226378)
		(end 418.465 -107.957874)
		(width 0.1143)
		(layer "In11.Cu")
		(net "P3E_PCH_M2_RX_DP<1>")
	)
	(segment
		(start 413.927544 -53.953664)
		(end 413.927798 -53.95341)
		(width 0.1143)
		(layer "In11.Cu")
		(net "P3E_PCH_M2_RX_DP<1>")
	)
	(segment
		(start 420.501064 -87.724742)
		(end 420.335964 -87.889842)
		(width 0.1143)
		(layer "In11.Cu")
		(net "P3E_PCH_M2_RX_DP<1>")
	)
	(segment
		(start 418.8587 -108.351574)
		(end 418.8587 -115.40236)
		(width 0.1143)
		(layer "In11.Cu")
		(net "P3E_PCH_M2_RX_DP<1>")
	)
	(segment
		(start 410.350208 -51.0286)
		(end 413.275272 -53.953664)
		(width 0.1143)
		(layer "In11.Cu")
		(net "P3E_PCH_M2_RX_DP<1>")
	)
	(segment
		(start 403.7457 -49.001172)
		(end 404.516336 -49.771808)
		(width 0.1143)
		(layer "In11.Cu")
		(net "P3E_PCH_M2_RX_DP<1>")
	)
	(segment
		(start 403.7457 -47.35068)
		(end 403.7457 -49.001172)
		(width 0.1143)
		(layer "In11.Cu")
		(net "P3E_PCH_M2_RX_DP<1>")
	)
	(segment
		(start 420.335964 -88.232742)
		(end 420.501064 -88.397842)
		(width 0.1143)
		(layer "In11.Cu")
		(net "P3E_PCH_M2_RX_DP<1>")
	)
	(segment
		(start 417.89096 -116.3701)
		(end 417.657534 -116.3701)
		(width 0.1143)
		(layer "In11.Cu")
		(net "P3E_PCH_M2_RX_DP<1>")
	)
	(segment
		(start 417.414964 -116.846096)
		(end 415.71926 -118.5418)
		(width 0.1143)
		(layer "In11.Cu")
		(net "P3E_PCH_M2_RX_DP<1>")
	)
	(segment
		(start 382.5367 -25.539192)
		(end 382.5367 -19.804126)
		(width 0.1143)
		(layer "In11.Cu")
		(net "P3E_PCH_M2_RX_DP<1>")
	)
	(segment
		(start 420.501064 -89.413842)
		(end 420.501064 -92.873576)
		(width 0.1143)
		(layer "In11.Cu")
		(net "P3E_PCH_M2_RX_DP<1>")
	)
	(segment
		(start 398.2847 -37.483542)
		(end 398.2847 -39.250112)
		(width 0.1143)
		(layer "In11.Cu")
		(net "P3E_PCH_M2_RX_DP<1>")
	)
	(segment
		(start 403.231604 -45.71746)
		(end 403.231604 -46.836584)
		(width 0.1143)
		(layer "In11.Cu")
		(net "P3E_PCH_M2_RX_DP<1>")
	)
	(segment
		(start 415.71926 -118.5418)
		(end 414.61436 -118.5418)
		(width 0.1143)
		(layer "In11.Cu")
		(net "P3E_PCH_M2_RX_DP<1>")
	)
	(segment
		(start 420.335964 -86.873842)
		(end 420.335964 -87.216742)
		(width 0.1143)
		(layer "In11.Cu")
		(net "P3E_PCH_M2_RX_DP<1>")
	)
	(segment
		(start 417.414964 -116.612416)
		(end 417.414964 -116.846096)
		(width 0.1143)
		(layer "In11.Cu")
		(net "P3E_PCH_M2_RX_DP<1>")
	)
	(segment
		(start 401.213828 -42.704258)
		(end 401.213828 -43.699684)
		(width 0.1143)
		(layer "In11.Cu")
		(net "P3E_PCH_M2_RX_DP<1>")
	)
	(segment
		(start 413.927798 -53.95341)
		(end 414.337754 -53.95341)
		(width 0.1143)
		(layer "In11.Cu")
		(net "P3E_PCH_M2_RX_DP<1>")
	)
	(segment
		(start 396.522702 -126.0983)
		(end 394.738606 -126.0983)
		(width 0.0889)
		(layer "In11.Cu")
		(net "P3E_PCH_M2_RX_DP<1>")
	)
	(segment
		(start 397.098266 -29.186378)
		(end 397.9926 -30.080712)
		(width 0.1143)
		(layer "In11.Cu")
		(net "P3E_PCH_M2_RX_DP<1>")
	)
	(segment
		(start 419.199568 -94.175072)
		(end 419.199568 -94.49181)
		(width 0.1143)
		(layer "In11.Cu")
		(net "P3E_PCH_M2_RX_DP<1>")
	)
	(segment
		(start 413.275272 -53.953664)
		(end 413.927544 -53.953664)
		(width 0.1143)
		(layer "In11.Cu")
		(net "P3E_PCH_M2_RX_DP<1>")
	)
	(segment
		(start 418.8079 -69.742304)
		(end 419.416738 -70.351142)
		(width 0.1143)
		(layer "In11.Cu")
		(net "P3E_PCH_M2_RX_DP<1>")
	)
	(segment
		(start 398.9959 -33.786826)
		(end 398.9959 -36.772342)
		(width 0.1143)
		(layer "In11.Cu")
		(net "P3E_PCH_M2_RX_DP<1>")
	)
	(segment
		(start 419.416738 -79.915004)
		(end 420.501064 -80.99933)
		(width 0.1143)
		(layer "In11.Cu")
		(net "P3E_PCH_M2_RX_DP<1>")
	)
	(segment
		(start 418.13353 -116.12753)
		(end 417.89096 -116.3701)
		(width 0.1143)
		(layer "In11.Cu")
		(net "P3E_PCH_M2_RX_DP<1>")
	)
	(segment
		(start 397.9926 -30.080712)
		(end 397.9926 -31.252668)
		(width 0.1143)
		(layer "In11.Cu")
		(net "P3E_PCH_M2_RX_DP<1>")
	)
	(segment
		(start 396.573502 -126.0475)
		(end 396.522702 -126.0983)
		(width 0.0889)
		(layer "In11.Cu")
		(net "P3E_PCH_M2_RX_DP<1>")
	)
	(segment
		(start 397.156686 -126.0475)
		(end 396.5956 -126.0475)
		(width 0.1143)
		(layer "In11.Cu")
		(net "P3E_PCH_M2_RX_DP<1>")
	)
	(segment
		(start 382.314958 -25.760934)
		(end 382.5367 -25.539192)
		(width 0.1143)
		(layer "In11.Cu")
		(net "P3E_PCH_M2_RX_DP<1>")
	)
	(segment
		(start 418.13353 -115.894104)
		(end 418.13353 -116.12753)
		(width 0.1143)
		(layer "In11.Cu")
		(net "P3E_PCH_M2_RX_DP<1>")
	)
	(segment
		(start 406.278334 -49.771808)
		(end 407.535126 -51.0286)
		(width 0.1143)
		(layer "In11.Cu")
		(net "P3E_PCH_M2_RX_DP<1>")
	)
	(segment
		(start 397.829786 -126.0475)
		(end 397.664686 -125.8824)
		(width 0.1143)
		(layer "In11.Cu")
		(net "P3E_PCH_M2_RX_DP<1>")
	)
	(segment
		(start 418.465 -107.957874)
		(end 418.8587 -108.351574)
		(width 0.1143)
		(layer "In11.Cu")
		(net "P3E_PCH_M2_RX_DP<1>")
	)
	(segment
		(start 413.806132 -119.350028)
		(end 413.806132 -120.257062)
		(width 0.1143)
		(layer "In11.Cu")
		(net "P3E_PCH_M2_RX_DP<1>")
	)
	(segment
		(start 418.8587 -115.40236)
		(end 418.609272 -115.651788)
		(width 0.1143)
		(layer "In11.Cu")
		(net "P3E_PCH_M2_RX_DP<1>")
	)
	(segment
		(start 420.501064 -88.397842)
		(end 420.501064 -88.740742)
		(width 0.1143)
		(layer "In11.Cu")
		(net "P3E_PCH_M2_RX_DP<1>")
	)
	(segment
		(start 394.1953 -129.00533)
		(end 393.62888 -129.57175)
		(width 0.0889)
		(layer "In11.Cu")
		(net "P3E_PCH_M2_RX_DP<1>")
	)
	(segment
		(start 382.797304 -22.270974)
		(end 381.839978 -22.270974)
		(width 0.1143)
		(layer "F.Cu")
		(net "P3E_PCH_M2_RX_DN<3>")
	)
	(segment
		(start 390.984994 -126.165102)
		(end 390.816338 -126.165102)
		(width 0.0889)
		(layer "F.Cu")
		(net "P3E_PCH_M2_RX_DN<3>")
	)
	(segment
		(start 381.839978 -22.270974)
		(end 381.703072 -22.40788)
		(width 0.1143)
		(layer "F.Cu")
		(net "P3E_PCH_M2_RX_DN<3>")
	)
	(segment
		(start 390.821926 -126.4793)
		(end 390.881616 -126.4793)
		(width 0.0889)
		(layer "F.Cu")
		(net "P3E_PCH_M2_RX_DN<3>")
	)
	(segment
		(start 390.896094 -128.250188)
		(end 390.896094 -128.516888)
		(width 0.0889)
		(layer "F.Cu")
		(net "P3E_PCH_M2_RX_DN<3>")
	)
	(segment
		(start 390.984994 -127.183388)
		(end 390.984994 -127.450088)
		(width 0.0889)
		(layer "F.Cu")
		(net "P3E_PCH_M2_RX_DN<3>")
	)
	(segment
		(start 391.78865 -129.2606)
		(end 391.78865 -129.4384)
		(width 0.0889)
		(layer "F.Cu")
		(net "P3E_PCH_M2_RX_DN<3>")
	)
	(segment
		(start 390.7409 -126.398274)
		(end 390.821926 -126.4793)
		(width 0.0889)
		(layer "F.Cu")
		(net "P3E_PCH_M2_RX_DN<3>")
	)
	(segment
		(start 390.984994 -127.450088)
		(end 390.896094 -127.538988)
		(width 0.0889)
		(layer "F.Cu")
		(net "P3E_PCH_M2_RX_DN<3>")
	)
	(segment
		(start 390.881616 -126.4793)
		(end 390.98474 -126.582424)
		(width 0.0889)
		(layer "F.Cu")
		(net "P3E_PCH_M2_RX_DN<3>")
	)
	(segment
		(start 390.896094 -127.805688)
		(end 390.984994 -127.894588)
		(width 0.0889)
		(layer "F.Cu")
		(net "P3E_PCH_M2_RX_DN<3>")
	)
	(segment
		(start 390.984994 -128.161288)
		(end 390.896094 -128.250188)
		(width 0.0889)
		(layer "F.Cu")
		(net "P3E_PCH_M2_RX_DN<3>")
	)
	(segment
		(start 391.69975 -129.1717)
		(end 391.78865 -129.2606)
		(width 0.0889)
		(layer "F.Cu")
		(net "P3E_PCH_M2_RX_DN<3>")
	)
	(segment
		(start 381.703072 -22.40788)
		(end 381.359156 -22.40788)
		(width 0.1143)
		(layer "F.Cu")
		(net "P3E_PCH_M2_RX_DN<3>")
	)
	(segment
		(start 390.984994 -128.605788)
		(end 390.984994 -128.872488)
		(width 0.0889)
		(layer "F.Cu")
		(net "P3E_PCH_M2_RX_DN<3>")
	)
	(segment
		(start 390.7409 -126.24054)
		(end 390.7409 -126.398274)
		(width 0.0889)
		(layer "F.Cu")
		(net "P3E_PCH_M2_RX_DN<3>")
	)
	(segment
		(start 381.359156 -22.40788)
		(end 380.96825 -22.016974)
		(width 0.1143)
		(layer "F.Cu")
		(net "P3E_PCH_M2_RX_DN<3>")
	)
	(segment
		(start 390.896094 -127.094488)
		(end 390.984994 -127.183388)
		(width 0.0889)
		(layer "F.Cu")
		(net "P3E_PCH_M2_RX_DN<3>")
	)
	(segment
		(start 390.98474 -126.582424)
		(end 390.98474 -126.739142)
		(width 0.0889)
		(layer "F.Cu")
		(net "P3E_PCH_M2_RX_DN<3>")
	)
	(segment
		(start 390.896094 -127.538988)
		(end 390.896094 -127.805688)
		(width 0.0889)
		(layer "F.Cu")
		(net "P3E_PCH_M2_RX_DN<3>")
	)
	(segment
		(start 390.98474 -126.739142)
		(end 390.896094 -126.827788)
		(width 0.0889)
		(layer "F.Cu")
		(net "P3E_PCH_M2_RX_DN<3>")
	)
	(segment
		(start 390.896094 -126.827788)
		(end 390.896094 -127.094488)
		(width 0.0889)
		(layer "F.Cu")
		(net "P3E_PCH_M2_RX_DN<3>")
	)
	(segment
		(start 390.816338 -126.165102)
		(end 390.7409 -126.24054)
		(width 0.0889)
		(layer "F.Cu")
		(net "P3E_PCH_M2_RX_DN<3>")
	)
	(segment
		(start 391.284206 -129.1717)
		(end 391.69975 -129.1717)
		(width 0.0889)
		(layer "F.Cu")
		(net "P3E_PCH_M2_RX_DN<3>")
	)
	(segment
		(start 390.984994 -128.872488)
		(end 391.284206 -129.1717)
		(width 0.0889)
		(layer "F.Cu")
		(net "P3E_PCH_M2_RX_DN<3>")
	)
	(segment
		(start 390.896094 -128.516888)
		(end 390.984994 -128.605788)
		(width 0.0889)
		(layer "F.Cu")
		(net "P3E_PCH_M2_RX_DN<3>")
	)
	(segment
		(start 390.984994 -127.894588)
		(end 390.984994 -128.161288)
		(width 0.0889)
		(layer "F.Cu")
		(net "P3E_PCH_M2_RX_DN<3>")
	)
	(via
		(at 391.78865 -129.4384)
		(size 0.508)
		(drill 0.254)
		(layers "F.Cu" "B.Cu")
		(net "P3E_PCH_M2_RX_DN<3>")
	)
	(via
		(at 380.96825 -22.016974)
		(size 0.508)
		(drill 0.254)
		(layers "F.Cu" "B.Cu")
		(net "P3E_PCH_M2_RX_DN<3>")
	)
	(segment
		(start 396.583916 -130.382772)
		(end 399.637758 -130.382772)
		(width 0.1143)
		(layer "In11.Cu")
		(net "P3E_PCH_M2_RX_DN<3>")
	)
	(segment
		(start 406.182322 -47.36465)
		(end 405.605996 -47.36465)
		(width 0.1143)
		(layer "In11.Cu")
		(net "P3E_PCH_M2_RX_DN<3>")
	)
	(segment
		(start 391.545572 -130.617722)
		(end 391.734294 -130.806444)
		(width 0.0889)
		(layer "In11.Cu")
		(net "P3E_PCH_M2_RX_DN<3>")
	)
	(segment
		(start 395.920468 -20.728178)
		(end 395.678152 -20.485862)
		(width 0.1143)
		(layer "In11.Cu")
		(net "P3E_PCH_M2_RX_DN<3>")
	)
	(segment
		(start 393.21486 -131.168902)
		(end 393.236958 -131.168902)
		(width 0.0889)
		(layer "In11.Cu")
		(net "P3E_PCH_M2_RX_DN<3>")
	)
	(segment
		(start 419.881304 -117.113812)
		(end 420.11473 -117.113812)
		(width 0.1143)
		(layer "In11.Cu")
		(net "P3E_PCH_M2_RX_DN<3>")
	)
	(segment
		(start 402.483828 -43.152822)
		(end 402.483828 -42.177462)
		(width 0.1143)
		(layer "In11.Cu")
		(net "P3E_PCH_M2_RX_DN<3>")
	)
	(segment
		(start 391.231374 -129.897378)
		(end 391.231374 -130.429254)
		(width 0.0889)
		(layer "In11.Cu")
		(net "P3E_PCH_M2_RX_DN<3>")
	)
	(segment
		(start 396.396464 -20.970748)
		(end 396.153894 -20.728178)
		(width 0.1143)
		(layer "In11.Cu")
		(net "P3E_PCH_M2_RX_DN<3>")
	)
	(segment
		(start 391.78865 -129.23647)
		(end 391.728706 -129.176526)
		(width 0.0889)
		(layer "In11.Cu")
		(net "P3E_PCH_M2_RX_DN<3>")
	)
	(segment
		(start 391.419842 -130.617722)
		(end 391.545572 -130.617722)
		(width 0.0889)
		(layer "In11.Cu")
		(net "P3E_PCH_M2_RX_DN<3>")
	)
	(segment
		(start 420.469568 -99.822762)
		(end 420.469568 -94.701868)
		(width 0.1143)
		(layer "In11.Cu")
		(net "P3E_PCH_M2_RX_DN<3>")
	)
	(segment
		(start 419.396418 -117.832124)
		(end 419.638988 -117.589554)
		(width 0.1143)
		(layer "In11.Cu")
		(net "P3E_PCH_M2_RX_DN<3>")
	)
	(segment
		(start 397.114776 -21.68906)
		(end 396.872206 -21.44649)
		(width 0.1143)
		(layer "In11.Cu")
		(net "P3E_PCH_M2_RX_DN<3>")
	)
	(segment
		(start 392.377422 -131.130802)
		(end 392.644122 -131.130802)
		(width 0.0889)
		(layer "In11.Cu")
		(net "P3E_PCH_M2_RX_DN<3>")
	)
	(segment
		(start 404.529036 -45.19803)
		(end 402.483828 -43.152822)
		(width 0.1143)
		(layer "In11.Cu")
		(net "P3E_PCH_M2_RX_DN<3>")
	)
	(segment
		(start 420.0779 -63.63208)
		(end 420.0779 -57.7977)
		(width 0.1143)
		(layer "In11.Cu")
		(net "P3E_PCH_M2_RX_DN<3>")
	)
	(segment
		(start 413.833564 -52.2732)
		(end 411.917388 -50.357024)
		(width 0.1143)
		(layer "In11.Cu")
		(net "P3E_PCH_M2_RX_DN<3>")
	)
	(segment
		(start 395.678152 -20.485862)
		(end 395.678152 -20.252436)
		(width 0.1143)
		(layer "In11.Cu")
		(net "P3E_PCH_M2_RX_DN<3>")
	)
	(segment
		(start 392.021822 -131.219702)
		(end 392.288522 -131.219702)
		(width 0.0889)
		(layer "In11.Cu")
		(net "P3E_PCH_M2_RX_DN<3>")
	)
	(segment
		(start 397.833088 -22.640798)
		(end 397.833088 -22.407372)
		(width 0.1143)
		(layer "In11.Cu")
		(net "P3E_PCH_M2_RX_DN<3>")
	)
	(segment
		(start 392.288522 -131.219702)
		(end 392.377422 -131.130802)
		(width 0.0889)
		(layer "In11.Cu")
		(net "P3E_PCH_M2_RX_DN<3>")
	)
	(segment
		(start 393.16406 -131.219702)
		(end 393.21486 -131.168902)
		(width 0.0889)
		(layer "In11.Cu")
		(net "P3E_PCH_M2_RX_DN<3>")
	)
	(segment
		(start 415.8996 -52.2732)
		(end 413.833564 -52.2732)
		(width 0.1143)
		(layer "In11.Cu")
		(net "P3E_PCH_M2_RX_DN<3>")
	)
	(segment
		(start 420.3573 -109.721396)
		(end 420.9415 -109.137196)
		(width 0.1143)
		(layer "In11.Cu")
		(net "P3E_PCH_M2_RX_DN<3>")
	)
	(segment
		(start 420.9415 -109.137196)
		(end 420.9415 -100.294694)
		(width 0.1143)
		(layer "In11.Cu")
		(net "P3E_PCH_M2_RX_DN<3>")
	)
	(segment
		(start 393.236958 -131.168902)
		(end 395.797786 -131.168902)
		(width 0.1143)
		(layer "In11.Cu")
		(net "P3E_PCH_M2_RX_DN<3>")
	)
	(segment
		(start 400.3802 -34.033968)
		(end 400.3802 -30.410658)
		(width 0.1143)
		(layer "In11.Cu")
		(net "P3E_PCH_M2_RX_DN<3>")
	)
	(segment
		(start 388.582154 -16.61414)
		(end 388.417054 -16.44904)
		(width 0.1143)
		(layer "In11.Cu")
		(net "P3E_PCH_M2_RX_DN<3>")
	)
	(segment
		(start 398.3863 -26.714958)
		(end 398.5514 -26.549858)
		(width 0.1143)
		(layer "In11.Cu")
		(net "P3E_PCH_M2_RX_DN<3>")
	)
	(segment
		(start 402.483828 -42.177462)
		(end 401.381722 -41.075356)
		(width 0.1143)
		(layer "In11.Cu")
		(net "P3E_PCH_M2_RX_DN<3>")
	)
	(segment
		(start 398.5514 -27.565858)
		(end 398.5514 -27.222958)
		(width 0.1143)
		(layer "In11.Cu")
		(net "P3E_PCH_M2_RX_DN<3>")
	)
	(segment
		(start 398.30883 -22.883114)
		(end 398.075404 -22.883114)
		(width 0.1143)
		(layer "In11.Cu")
		(net "P3E_PCH_M2_RX_DN<3>")
	)
	(segment
		(start 398.3863 -25.698958)
		(end 398.5514 -25.533858)
		(width 0.1143)
		(layer "In11.Cu")
		(net "P3E_PCH_M2_RX_DN<3>")
	)
	(segment
		(start 380.6317 -22.353524)
		(end 380.96825 -22.016974)
		(width 0.1143)
		(layer "In11.Cu")
		(net "P3E_PCH_M2_RX_DN<3>")
	)
	(segment
		(start 398.5514 -27.222958)
		(end 398.3863 -27.057858)
		(width 0.1143)
		(layer "In11.Cu")
		(net "P3E_PCH_M2_RX_DN<3>")
	)
	(segment
		(start 411.917388 -50.357024)
		(end 411.917388 -49.059846)
		(width 0.1143)
		(layer "In11.Cu")
		(net "P3E_PCH_M2_RX_DN<3>")
	)
	(segment
		(start 401.381722 -41.075356)
		(end 401.381722 -35.03549)
		(width 0.1143)
		(layer "In11.Cu")
		(net "P3E_PCH_M2_RX_DN<3>")
	)
	(segment
		(start 398.5514 -28.238958)
		(end 398.3863 -28.073858)
		(width 0.1143)
		(layer "In11.Cu")
		(net "P3E_PCH_M2_RX_DN<3>")
	)
	(segment
		(start 391.231374 -129.452878)
		(end 391.320274 -129.541778)
		(width 0.0889)
		(layer "In11.Cu")
		(net "P3E_PCH_M2_RX_DN<3>")
	)
	(segment
		(start 395.678152 -20.252436)
		(end 391.874756 -16.44904)
		(width 0.1143)
		(layer "In11.Cu")
		(net "P3E_PCH_M2_RX_DN<3>")
	)
	(segment
		(start 387.566154 -16.61414)
		(end 387.401054 -16.44904)
		(width 0.1143)
		(layer "In11.Cu")
		(net "P3E_PCH_M2_RX_DN<3>")
	)
	(segment
		(start 387.401054 -16.44904)
		(end 383.311146 -16.44904)
		(width 0.1143)
		(layer "In11.Cu")
		(net "P3E_PCH_M2_RX_DN<3>")
	)
	(segment
		(start 400.3802 -30.410658)
		(end 398.5514 -28.581858)
		(width 0.1143)
		(layer "In11.Cu")
		(net "P3E_PCH_M2_RX_DN<3>")
	)
	(segment
		(start 397.833088 -22.407372)
		(end 397.590518 -22.164802)
		(width 0.1143)
		(layer "In11.Cu")
		(net "P3E_PCH_M2_RX_DN<3>")
	)
	(segment
		(start 398.3863 -27.057858)
		(end 398.3863 -26.714958)
		(width 0.1143)
		(layer "In11.Cu")
		(net "P3E_PCH_M2_RX_DN<3>")
	)
	(segment
		(start 411.040834 -124.934218)
		(end 414.143952 -121.8311)
		(width 0.1143)
		(layer "In11.Cu")
		(net "P3E_PCH_M2_RX_DN<3>")
	)
	(segment
		(start 380.25832 -21.108416)
		(end 380.25832 -22.141942)
		(width 0.1143)
		(layer "In11.Cu")
		(net "P3E_PCH_M2_RX_DN<3>")
	)
	(segment
		(start 392.644122 -131.130802)
		(end 392.733022 -131.219702)
		(width 0.0889)
		(layer "In11.Cu")
		(net "P3E_PCH_M2_RX_DN<3>")
	)
	(segment
		(start 398.5514 -25.533858)
		(end 398.5514 -23.125684)
		(width 0.1143)
		(layer "In11.Cu")
		(net "P3E_PCH_M2_RX_DN<3>")
	)
	(segment
		(start 398.3863 -28.073858)
		(end 398.3863 -27.730958)
		(width 0.1143)
		(layer "In11.Cu")
		(net "P3E_PCH_M2_RX_DN<3>")
	)
	(segment
		(start 402.661374 -125.66142)
		(end 403.278594 -125.0442)
		(width 0.1143)
		(layer "In11.Cu")
		(net "P3E_PCH_M2_RX_DN<3>")
	)
	(segment
		(start 389.941054 -16.61414)
		(end 389.598154 -16.61414)
		(width 0.1143)
		(layer "In11.Cu")
		(net "P3E_PCH_M2_RX_DN<3>")
	)
	(segment
		(start 390.106154 -16.44904)
		(end 389.941054 -16.61414)
		(width 0.1143)
		(layer "In11.Cu")
		(net "P3E_PCH_M2_RX_DN<3>")
	)
	(segment
		(start 421.659558 -65.213738)
		(end 420.0779 -63.63208)
		(width 0.1143)
		(layer "In11.Cu")
		(net "P3E_PCH_M2_RX_DN<3>")
	)
	(segment
		(start 380.469902 -22.353524)
		(end 380.6317 -22.353524)
		(width 0.1143)
		(layer "In11.Cu")
		(net "P3E_PCH_M2_RX_DN<3>")
	)
	(segment
		(start 411.511242 -48.6537)
		(end 407.471372 -48.6537)
		(width 0.1143)
		(layer "In11.Cu")
		(net "P3E_PCH_M2_RX_DN<3>")
	)
	(segment
		(start 421.471852 -77.489812)
		(end 421.471852 -75.442826)
		(width 0.1143)
		(layer "In11.Cu")
		(net "P3E_PCH_M2_RX_DN<3>")
	)
	(segment
		(start 417.0045 -53.3781)
		(end 415.8996 -52.2732)
		(width 0.1143)
		(layer "In11.Cu")
		(net "P3E_PCH_M2_RX_DN<3>")
	)
	(segment
		(start 383.311146 -16.44904)
		(end 380.998984 -18.761202)
		(width 0.1143)
		(layer "In11.Cu")
		(net "P3E_PCH_M2_RX_DN<3>")
	)
	(segment
		(start 414.143952 -121.8311)
		(end 416.322764 -121.8311)
		(width 0.1143)
		(layer "In11.Cu")
		(net "P3E_PCH_M2_RX_DN<3>")
	)
	(segment
		(start 398.5514 -26.549858)
		(end 398.5514 -26.206958)
		(width 0.1143)
		(layer "In11.Cu")
		(net "P3E_PCH_M2_RX_DN<3>")
	)
	(segment
		(start 380.998984 -20.367752)
		(end 380.25832 -21.108416)
		(width 0.1143)
		(layer "In11.Cu")
		(net "P3E_PCH_M2_RX_DN<3>")
	)
	(segment
		(start 391.320274 -129.808478)
		(end 391.231374 -129.897378)
		(width 0.0889)
		(layer "In11.Cu")
		(net "P3E_PCH_M2_RX_DN<3>")
	)
	(segment
		(start 391.62355 -129.176526)
		(end 391.439654 -128.99263)
		(width 0.0889)
		(layer "In11.Cu")
		(net "P3E_PCH_M2_RX_DN<3>")
	)
	(segment
		(start 395.797786 -131.168902)
		(end 396.583916 -130.382772)
		(width 0.1143)
		(layer "In11.Cu")
		(net "P3E_PCH_M2_RX_DN<3>")
	)
	(segment
		(start 396.872206 -21.44649)
		(end 396.63878 -21.44649)
		(width 0.1143)
		(layer "In11.Cu")
		(net "P3E_PCH_M2_RX_DN<3>")
	)
	(segment
		(start 398.5514 -23.125684)
		(end 398.30883 -22.883114)
		(width 0.1143)
		(layer "In11.Cu")
		(net "P3E_PCH_M2_RX_DN<3>")
	)
	(segment
		(start 398.5514 -28.581858)
		(end 398.5514 -28.238958)
		(width 0.1143)
		(layer "In11.Cu")
		(net "P3E_PCH_M2_RX_DN<3>")
	)
	(segment
		(start 403.278594 -125.0442)
		(end 404.259542 -125.0442)
		(width 0.1143)
		(layer "In11.Cu")
		(net "P3E_PCH_M2_RX_DN<3>")
	)
	(segment
		(start 419.638988 -117.589554)
		(end 419.638988 -117.356128)
		(width 0.1143)
		(layer "In11.Cu")
		(net "P3E_PCH_M2_RX_DN<3>")
	)
	(segment
		(start 420.0779 -57.7977)
		(end 417.0045 -54.7243)
		(width 0.1143)
		(layer "In11.Cu")
		(net "P3E_PCH_M2_RX_DN<3>")
	)
	(segment
		(start 417.483544 -119.511572)
		(end 417.726114 -119.269002)
		(width 0.1143)
		(layer "In11.Cu")
		(net "P3E_PCH_M2_RX_DN<3>")
	)
	(segment
		(start 404.259542 -125.0442)
		(end 404.369524 -124.934218)
		(width 0.1143)
		(layer "In11.Cu")
		(net "P3E_PCH_M2_RX_DN<3>")
	)
	(segment
		(start 417.483544 -119.744998)
		(end 417.483544 -119.511572)
		(width 0.1143)
		(layer "In11.Cu")
		(net "P3E_PCH_M2_RX_DN<3>")
	)
	(segment
		(start 387.909054 -16.61414)
		(end 387.566154 -16.61414)
		(width 0.1143)
		(layer "In11.Cu")
		(net "P3E_PCH_M2_RX_DN<3>")
	)
	(segment
		(start 397.357092 -22.164802)
		(end 397.114776 -21.922486)
		(width 0.1143)
		(layer "In11.Cu")
		(net "P3E_PCH_M2_RX_DN<3>")
	)
	(segment
		(start 391.231374 -130.429254)
		(end 391.419842 -130.617722)
		(width 0.0889)
		(layer "In11.Cu")
		(net "P3E_PCH_M2_RX_DN<3>")
	)
	(segment
		(start 391.122154 -16.44904)
		(end 390.957054 -16.61414)
		(width 0.1143)
		(layer "In11.Cu")
		(net "P3E_PCH_M2_RX_DN<3>")
	)
	(segment
		(start 416.797744 -120.430798)
		(end 417.483544 -119.744998)
		(width 0.1143)
		(layer "In11.Cu")
		(net "P3E_PCH_M2_RX_DN<3>")
	)
	(segment
		(start 391.874756 -16.44904)
		(end 391.122154 -16.44904)
		(width 0.1143)
		(layer "In11.Cu")
		(net "P3E_PCH_M2_RX_DN<3>")
	)
	(segment
		(start 416.797744 -121.35612)
		(end 416.797744 -120.430798)
		(width 0.1143)
		(layer "In11.Cu")
		(net "P3E_PCH_M2_RX_DN<3>")
	)
	(segment
		(start 419.162992 -117.832124)
		(end 419.396418 -117.832124)
		(width 0.1143)
		(layer "In11.Cu")
		(net "P3E_PCH_M2_RX_DN<3>")
	)
	(segment
		(start 420.3573 -116.871242)
		(end 420.3573 -109.721396)
		(width 0.1143)
		(layer "In11.Cu")
		(net "P3E_PCH_M2_RX_DN<3>")
	)
	(segment
		(start 420.9415 -100.294694)
		(end 420.469568 -99.822762)
		(width 0.1143)
		(layer "In11.Cu")
		(net "P3E_PCH_M2_RX_DN<3>")
	)
	(segment
		(start 417.95954 -119.269002)
		(end 418.20211 -119.026432)
		(width 0.1143)
		(layer "In11.Cu")
		(net "P3E_PCH_M2_RX_DN<3>")
	)
	(segment
		(start 418.20211 -118.793006)
		(end 418.444426 -118.55069)
		(width 0.1143)
		(layer "In11.Cu")
		(net "P3E_PCH_M2_RX_DN<3>")
	)
	(segment
		(start 421.471852 -75.442826)
		(end 421.659558 -75.25512)
		(width 0.1143)
		(layer "In11.Cu")
		(net "P3E_PCH_M2_RX_DN<3>")
	)
	(segment
		(start 401.381722 -35.03549)
		(end 400.3802 -34.033968)
		(width 0.1143)
		(layer "In11.Cu")
		(net "P3E_PCH_M2_RX_DN<3>")
	)
	(segment
		(start 391.231374 -129.113026)
		(end 391.231374 -129.452878)
		(width 0.0889)
		(layer "In11.Cu")
		(net "P3E_PCH_M2_RX_DN<3>")
	)
	(segment
		(start 421.659558 -75.25512)
		(end 421.659558 -65.213738)
		(width 0.1143)
		(layer "In11.Cu")
		(net "P3E_PCH_M2_RX_DN<3>")
	)
	(segment
		(start 418.920422 -118.30812)
		(end 418.920422 -118.074694)
		(width 0.1143)
		(layer "In11.Cu")
		(net "P3E_PCH_M2_RX_DN<3>")
	)
	(segment
		(start 402.661374 -127.359156)
		(end 402.661374 -125.66142)
		(width 0.1143)
		(layer "In11.Cu")
		(net "P3E_PCH_M2_RX_DN<3>")
	)
	(segment
		(start 398.3863 -27.730958)
		(end 398.5514 -27.565858)
		(width 0.1143)
		(layer "In11.Cu")
		(net "P3E_PCH_M2_RX_DN<3>")
	)
	(segment
		(start 396.153894 -20.728178)
		(end 395.920468 -20.728178)
		(width 0.1143)
		(layer "In11.Cu")
		(net "P3E_PCH_M2_RX_DN<3>")
	)
	(segment
		(start 391.439654 -128.99263)
		(end 391.35177 -128.99263)
		(width 0.0889)
		(layer "In11.Cu")
		(net "P3E_PCH_M2_RX_DN<3>")
	)
	(segment
		(start 390.449054 -16.44904)
		(end 390.106154 -16.44904)
		(width 0.1143)
		(layer "In11.Cu")
		(net "P3E_PCH_M2_RX_DN<3>")
	)
	(segment
		(start 411.917388 -49.059846)
		(end 411.511242 -48.6537)
		(width 0.1143)
		(layer "In11.Cu")
		(net "P3E_PCH_M2_RX_DN<3>")
	)
	(segment
		(start 388.925054 -16.61414)
		(end 388.582154 -16.61414)
		(width 0.1143)
		(layer "In11.Cu")
		(net "P3E_PCH_M2_RX_DN<3>")
	)
	(segment
		(start 392.733022 -131.219702)
		(end 393.16406 -131.219702)
		(width 0.0889)
		(layer "In11.Cu")
		(net "P3E_PCH_M2_RX_DN<3>")
	)
	(segment
		(start 407.471372 -48.6537)
		(end 406.182322 -47.36465)
		(width 0.1143)
		(layer "In11.Cu")
		(net "P3E_PCH_M2_RX_DN<3>")
	)
	(segment
		(start 399.637758 -130.382772)
		(end 402.661374 -127.359156)
		(width 0.1143)
		(layer "In11.Cu")
		(net "P3E_PCH_M2_RX_DN<3>")
	)
	(segment
		(start 404.369524 -124.934218)
		(end 411.040834 -124.934218)
		(width 0.1143)
		(layer "In11.Cu")
		(net "P3E_PCH_M2_RX_DN<3>")
	)
	(segment
		(start 417.726114 -119.269002)
		(end 417.95954 -119.269002)
		(width 0.1143)
		(layer "In11.Cu")
		(net "P3E_PCH_M2_RX_DN<3>")
	)
	(segment
		(start 416.322764 -121.8311)
		(end 416.797744 -121.35612)
		(width 0.1143)
		(layer "In11.Cu")
		(net "P3E_PCH_M2_RX_DN<3>")
	)
	(segment
		(start 390.957054 -16.61414)
		(end 390.614154 -16.61414)
		(width 0.1143)
		(layer "In11.Cu")
		(net "P3E_PCH_M2_RX_DN<3>")
	)
	(segment
		(start 391.734294 -130.806444)
		(end 391.734294 -130.932174)
		(width 0.0889)
		(layer "In11.Cu")
		(net "P3E_PCH_M2_RX_DN<3>")
	)
	(segment
		(start 390.614154 -16.61414)
		(end 390.449054 -16.44904)
		(width 0.1143)
		(layer "In11.Cu")
		(net "P3E_PCH_M2_RX_DN<3>")
	)
	(segment
		(start 398.5514 -26.206958)
		(end 398.3863 -26.041858)
		(width 0.1143)
		(layer "In11.Cu")
		(net "P3E_PCH_M2_RX_DN<3>")
	)
	(segment
		(start 388.074154 -16.44904)
		(end 387.909054 -16.61414)
		(width 0.1143)
		(layer "In11.Cu")
		(net "P3E_PCH_M2_RX_DN<3>")
	)
	(segment
		(start 391.35177 -128.99263)
		(end 391.231374 -129.113026)
		(width 0.0889)
		(layer "In11.Cu")
		(net "P3E_PCH_M2_RX_DN<3>")
	)
	(segment
		(start 389.433054 -16.44904)
		(end 389.090154 -16.44904)
		(width 0.1143)
		(layer "In11.Cu")
		(net "P3E_PCH_M2_RX_DN<3>")
	)
	(segment
		(start 405.605996 -47.36465)
		(end 404.529036 -46.28769)
		(width 0.1143)
		(layer "In11.Cu")
		(net "P3E_PCH_M2_RX_DN<3>")
	)
	(segment
		(start 421.855646 -93.31579)
		(end 421.855646 -80.527144)
		(width 0.1143)
		(layer "In11.Cu")
		(net "P3E_PCH_M2_RX_DN<3>")
	)
	(segment
		(start 391.320274 -129.541778)
		(end 391.320274 -129.808478)
		(width 0.0889)
		(layer "In11.Cu")
		(net "P3E_PCH_M2_RX_DN<3>")
	)
	(segment
		(start 418.444426 -118.55069)
		(end 418.677852 -118.55069)
		(width 0.1143)
		(layer "In11.Cu")
		(net "P3E_PCH_M2_RX_DN<3>")
	)
	(segment
		(start 397.590518 -22.164802)
		(end 397.357092 -22.164802)
		(width 0.1143)
		(layer "In11.Cu")
		(net "P3E_PCH_M2_RX_DN<3>")
	)
	(segment
		(start 389.598154 -16.61414)
		(end 389.433054 -16.44904)
		(width 0.1143)
		(layer "In11.Cu")
		(net "P3E_PCH_M2_RX_DN<3>")
	)
	(segment
		(start 388.417054 -16.44904)
		(end 388.074154 -16.44904)
		(width 0.1143)
		(layer "In11.Cu")
		(net "P3E_PCH_M2_RX_DN<3>")
	)
	(segment
		(start 420.11473 -117.113812)
		(end 420.3573 -116.871242)
		(width 0.1143)
		(layer "In11.Cu")
		(net "P3E_PCH_M2_RX_DN<3>")
	)
	(segment
		(start 391.728706 -129.176526)
		(end 391.62355 -129.176526)
		(width 0.0889)
		(layer "In11.Cu")
		(net "P3E_PCH_M2_RX_DN<3>")
	)
	(segment
		(start 420.469568 -94.701868)
		(end 421.855646 -93.31579)
		(width 0.1143)
		(layer "In11.Cu")
		(net "P3E_PCH_M2_RX_DN<3>")
	)
	(segment
		(start 421.855646 -80.527144)
		(end 420.748206 -79.419704)
		(width 0.1143)
		(layer "In11.Cu")
		(net "P3E_PCH_M2_RX_DN<3>")
	)
	(segment
		(start 397.114776 -21.922486)
		(end 397.114776 -21.68906)
		(width 0.1143)
		(layer "In11.Cu")
		(net "P3E_PCH_M2_RX_DN<3>")
	)
	(segment
		(start 420.748206 -78.213458)
		(end 421.471852 -77.489812)
		(width 0.1143)
		(layer "In11.Cu")
		(net "P3E_PCH_M2_RX_DN<3>")
	)
	(segment
		(start 418.920422 -118.074694)
		(end 419.162992 -117.832124)
		(width 0.1143)
		(layer "In11.Cu")
		(net "P3E_PCH_M2_RX_DN<3>")
	)
	(segment
		(start 418.20211 -119.026432)
		(end 418.20211 -118.793006)
		(width 0.1143)
		(layer "In11.Cu")
		(net "P3E_PCH_M2_RX_DN<3>")
	)
	(segment
		(start 419.638988 -117.356128)
		(end 419.881304 -117.113812)
		(width 0.1143)
		(layer "In11.Cu")
		(net "P3E_PCH_M2_RX_DN<3>")
	)
	(segment
		(start 389.090154 -16.44904)
		(end 388.925054 -16.61414)
		(width 0.1143)
		(layer "In11.Cu")
		(net "P3E_PCH_M2_RX_DN<3>")
	)
	(segment
		(start 417.0045 -54.7243)
		(end 417.0045 -53.3781)
		(width 0.1143)
		(layer "In11.Cu")
		(net "P3E_PCH_M2_RX_DN<3>")
	)
	(segment
		(start 420.748206 -79.419704)
		(end 420.748206 -78.213458)
		(width 0.1143)
		(layer "In11.Cu")
		(net "P3E_PCH_M2_RX_DN<3>")
	)
	(segment
		(start 391.78865 -129.4384)
		(end 391.78865 -129.23647)
		(width 0.0889)
		(layer "In11.Cu")
		(net "P3E_PCH_M2_RX_DN<3>")
	)
	(segment
		(start 396.63878 -21.44649)
		(end 396.396464 -21.204174)
		(width 0.1143)
		(layer "In11.Cu")
		(net "P3E_PCH_M2_RX_DN<3>")
	)
	(segment
		(start 398.3863 -26.041858)
		(end 398.3863 -25.698958)
		(width 0.1143)
		(layer "In11.Cu")
		(net "P3E_PCH_M2_RX_DN<3>")
	)
	(segment
		(start 396.396464 -21.204174)
		(end 396.396464 -20.970748)
		(width 0.1143)
		(layer "In11.Cu")
		(net "P3E_PCH_M2_RX_DN<3>")
	)
	(segment
		(start 380.25832 -22.141942)
		(end 380.469902 -22.353524)
		(width 0.1143)
		(layer "In11.Cu")
		(net "P3E_PCH_M2_RX_DN<3>")
	)
	(segment
		(start 391.734294 -130.932174)
		(end 392.021822 -131.219702)
		(width 0.0889)
		(layer "In11.Cu")
		(net "P3E_PCH_M2_RX_DN<3>")
	)
	(segment
		(start 418.677852 -118.55069)
		(end 418.920422 -118.30812)
		(width 0.1143)
		(layer "In11.Cu")
		(net "P3E_PCH_M2_RX_DN<3>")
	)
	(segment
		(start 380.998984 -18.761202)
		(end 380.998984 -20.367752)
		(width 0.1143)
		(layer "In11.Cu")
		(net "P3E_PCH_M2_RX_DN<3>")
	)
	(segment
		(start 398.075404 -22.883114)
		(end 397.833088 -22.640798)
		(width 0.1143)
		(layer "In11.Cu")
		(net "P3E_PCH_M2_RX_DN<3>")
	)
	(segment
		(start 404.529036 -46.28769)
		(end 404.529036 -45.19803)
		(width 0.1143)
		(layer "In11.Cu")
		(net "P3E_PCH_M2_RX_DN<3>")
	)
	(segment
		(start 391.3886 -126.669546)
		(end 391.3886 -127.393446)
		(width 0.0889)
		(layer "F.Cu")
		(net "P3E_PCH_M2_RX_DN<2>")
	)
	(segment
		(start 380.87681 -25.484328)
		(end 380.67107 -25.278588)
		(width 0.1143)
		(layer "F.Cu")
		(net "P3E_PCH_M2_RX_DN<2>")
	)
	(segment
		(start 391.48512 -125.750066)
		(end 391.48512 -125.953774)
		(width 0.0889)
		(layer "F.Cu")
		(net "P3E_PCH_M2_RX_DN<2>")
	)
	(segment
		(start 391.477754 -127.4826)
		(end 391.78865 -127.4826)
		(width 0.0889)
		(layer "F.Cu")
		(net "P3E_PCH_M2_RX_DN<2>")
	)
	(segment
		(start 391.48512 -125.953774)
		(end 391.5029 -125.971554)
		(width 0.0889)
		(layer "F.Cu")
		(net "P3E_PCH_M2_RX_DN<2>")
	)
	(segment
		(start 381.839978 -25.270968)
		(end 381.626618 -25.484328)
		(width 0.1143)
		(layer "F.Cu")
		(net "P3E_PCH_M2_RX_DN<2>")
	)
	(segment
		(start 381.626618 -25.484328)
		(end 380.87681 -25.484328)
		(width 0.1143)
		(layer "F.Cu")
		(net "P3E_PCH_M2_RX_DN<2>")
	)
	(segment
		(start 391.5029 -125.971554)
		(end 391.5029 -126.555246)
		(width 0.0889)
		(layer "F.Cu")
		(net "P3E_PCH_M2_RX_DN<2>")
	)
	(segment
		(start 391.5029 -126.555246)
		(end 391.3886 -126.669546)
		(width 0.0889)
		(layer "F.Cu")
		(net "P3E_PCH_M2_RX_DN<2>")
	)
	(segment
		(start 382.797304 -25.270968)
		(end 381.839978 -25.270968)
		(width 0.1143)
		(layer "F.Cu")
		(net "P3E_PCH_M2_RX_DN<2>")
	)
	(segment
		(start 391.3886 -127.393446)
		(end 391.477754 -127.4826)
		(width 0.0889)
		(layer "F.Cu")
		(net "P3E_PCH_M2_RX_DN<2>")
	)
	(via
		(at 380.67107 -25.278588)
		(size 0.508)
		(drill 0.254)
		(layers "F.Cu" "B.Cu")
		(net "P3E_PCH_M2_RX_DN<2>")
	)
	(via
		(at 391.78865 -127.4826)
		(size 0.508)
		(drill 0.254)
		(layers "F.Cu" "B.Cu")
		(net "P3E_PCH_M2_RX_DN<2>")
	)
	(segment
		(start 396.425928 -130.039872)
		(end 399.492978 -130.039872)
		(width 0.1143)
		(layer "In11.Cu")
		(net "P3E_PCH_M2_RX_DN<2>")
	)
	(segment
		(start 420.126668 -94.559628)
		(end 421.4749 -93.211396)
		(width 0.1143)
		(layer "In11.Cu")
		(net "P3E_PCH_M2_RX_DN<2>")
	)
	(segment
		(start 392.35507 -129.598166)
		(end 392.44397 -129.687066)
		(width 0.0889)
		(layer "In11.Cu")
		(net "P3E_PCH_M2_RX_DN<2>")
	)
	(segment
		(start 414.696402 -53.000402)
		(end 413.633666 -53.000402)
		(width 0.1143)
		(layer "In11.Cu")
		(net "P3E_PCH_M2_RX_DN<2>")
	)
	(segment
		(start 392.44397 -128.531366)
		(end 392.35507 -128.620266)
		(width 0.0889)
		(layer "In11.Cu")
		(net "P3E_PCH_M2_RX_DN<2>")
	)
	(segment
		(start 392.35507 -129.331466)
		(end 392.35507 -129.598166)
		(width 0.0889)
		(layer "In11.Cu")
		(net "P3E_PCH_M2_RX_DN<2>")
	)
	(segment
		(start 391.78865 -127.411226)
		(end 391.987786 -127.21209)
		(width 0.0889)
		(layer "In11.Cu")
		(net "P3E_PCH_M2_RX_DN<2>")
	)
	(segment
		(start 409.712668 -49.079404)
		(end 407.411936 -49.079404)
		(width 0.1143)
		(layer "In11.Cu")
		(net "P3E_PCH_M2_RX_DN<2>")
	)
	(segment
		(start 391.78865 -127.4826)
		(end 391.78865 -127.411226)
		(width 0.0889)
		(layer "In11.Cu")
		(net "P3E_PCH_M2_RX_DN<2>")
	)
	(segment
		(start 392.35507 -128.886966)
		(end 392.44397 -128.975866)
		(width 0.0889)
		(layer "In11.Cu")
		(net "P3E_PCH_M2_RX_DN<2>")
	)
	(segment
		(start 402.140928 -42.319702)
		(end 400.2913 -40.470074)
		(width 0.1143)
		(layer "In11.Cu")
		(net "P3E_PCH_M2_RX_DN<2>")
	)
	(segment
		(start 392.214608 -127.40386)
		(end 392.2141 -127.404368)
		(width 0.0889)
		(layer "In11.Cu")
		(net "P3E_PCH_M2_RX_DN<2>")
	)
	(segment
		(start 420.343838 -79.500476)
		(end 420.343838 -69.798438)
		(width 0.1143)
		(layer "In11.Cu")
		(net "P3E_PCH_M2_RX_DN<2>")
	)
	(segment
		(start 391.987786 -127.21209)
		(end 392.101324 -127.21209)
		(width 0.0889)
		(layer "In11.Cu")
		(net "P3E_PCH_M2_RX_DN<2>")
	)
	(segment
		(start 404.056088 -124.46)
		(end 408.2796 -124.46)
		(width 0.1143)
		(layer "In11.Cu")
		(net "P3E_PCH_M2_RX_DN<2>")
	)
	(segment
		(start 383.460244 -17.029938)
		(end 381.6096 -18.880582)
		(width 0.1143)
		(layer "In11.Cu")
		(net "P3E_PCH_M2_RX_DN<2>")
	)
	(segment
		(start 399.9611 -33.341564)
		(end 399.3769 -32.757364)
		(width 0.1143)
		(layer "In11.Cu")
		(net "P3E_PCH_M2_RX_DN<2>")
	)
	(segment
		(start 402.96846 -124.1552)
		(end 403.751288 -124.1552)
		(width 0.1143)
		(layer "In11.Cu")
		(net "P3E_PCH_M2_RX_DN<2>")
	)
	(segment
		(start 404.164038 -45.338238)
		(end 402.140928 -43.315128)
		(width 0.1143)
		(layer "In11.Cu")
		(net "P3E_PCH_M2_RX_DN<2>")
	)
	(segment
		(start 405.463756 -47.70755)
		(end 404.164038 -46.407832)
		(width 0.1143)
		(layer "In11.Cu")
		(net "P3E_PCH_M2_RX_DN<2>")
	)
	(segment
		(start 392.39317 -130.004566)
		(end 392.39317 -130.015742)
		(width 0.0889)
		(layer "In11.Cu")
		(net "P3E_PCH_M2_RX_DN<2>")
	)
	(segment
		(start 404.164038 -46.407832)
		(end 404.164038 -45.338238)
		(width 0.1143)
		(layer "In11.Cu")
		(net "P3E_PCH_M2_RX_DN<2>")
	)
	(segment
		(start 392.214608 -127.325374)
		(end 392.214608 -127.40386)
		(width 0.0889)
		(layer "In11.Cu")
		(net "P3E_PCH_M2_RX_DN<2>")
	)
	(segment
		(start 392.2141 -127.765302)
		(end 392.44397 -127.995172)
		(width 0.0889)
		(layer "In11.Cu")
		(net "P3E_PCH_M2_RX_DN<2>")
	)
	(segment
		(start 398.025366 -28.645866)
		(end 398.025366 -23.493222)
		(width 0.1143)
		(layer "In11.Cu")
		(net "P3E_PCH_M2_RX_DN<2>")
	)
	(segment
		(start 399.3769 -31.31312)
		(end 398.92605 -30.86227)
		(width 0.1143)
		(layer "In11.Cu")
		(net "P3E_PCH_M2_RX_DN<2>")
	)
	(segment
		(start 392.2141 -127.404368)
		(end 392.2141 -127.765302)
		(width 0.0889)
		(layer "In11.Cu")
		(net "P3E_PCH_M2_RX_DN<2>")
	)
	(segment
		(start 421.4749 -93.211396)
		(end 421.4749 -80.631538)
		(width 0.1143)
		(layer "In11.Cu")
		(net "P3E_PCH_M2_RX_DN<2>")
	)
	(segment
		(start 400.879564 -126.244096)
		(end 402.96846 -124.1552)
		(width 0.1143)
		(layer "In11.Cu")
		(net "P3E_PCH_M2_RX_DN<2>")
	)
	(segment
		(start 414.071054 -121.378726)
		(end 414.669732 -121.378726)
		(width 0.1143)
		(layer "In11.Cu")
		(net "P3E_PCH_M2_RX_DN<2>")
	)
	(segment
		(start 399.9611 -37.141404)
		(end 399.9611 -33.341564)
		(width 0.1143)
		(layer "In11.Cu")
		(net "P3E_PCH_M2_RX_DN<2>")
	)
	(segment
		(start 400.2913 -39.939214)
		(end 399.2118 -38.859714)
		(width 0.1143)
		(layer "In11.Cu")
		(net "P3E_PCH_M2_RX_DN<2>")
	)
	(segment
		(start 399.3769 -32.757364)
		(end 399.3769 -31.31312)
		(width 0.1143)
		(layer "In11.Cu")
		(net "P3E_PCH_M2_RX_DN<2>")
	)
	(segment
		(start 419.9128 -109.516418)
		(end 420.497 -108.932218)
		(width 0.1143)
		(layer "In11.Cu")
		(net "P3E_PCH_M2_RX_DN<2>")
	)
	(segment
		(start 399.492978 -130.039872)
		(end 400.879564 -128.653286)
		(width 0.1143)
		(layer "In11.Cu")
		(net "P3E_PCH_M2_RX_DN<2>")
	)
	(segment
		(start 381.6096 -25.135078)
		(end 381.196596 -25.548082)
		(width 0.1143)
		(layer "In11.Cu")
		(net "P3E_PCH_M2_RX_DN<2>")
	)
	(segment
		(start 421.4749 -80.631538)
		(end 420.343838 -79.500476)
		(width 0.1143)
		(layer "In11.Cu")
		(net "P3E_PCH_M2_RX_DN<2>")
	)
	(segment
		(start 392.44397 -128.975866)
		(end 392.44397 -129.242566)
		(width 0.0889)
		(layer "In11.Cu")
		(net "P3E_PCH_M2_RX_DN<2>")
	)
	(segment
		(start 419.5826 -95.420434)
		(end 420.126668 -94.876366)
		(width 0.1143)
		(layer "In11.Cu")
		(net "P3E_PCH_M2_RX_DN<2>")
	)
	(segment
		(start 408.778202 -123.961398)
		(end 411.488382 -123.961398)
		(width 0.1143)
		(layer "In11.Cu")
		(net "P3E_PCH_M2_RX_DN<2>")
	)
	(segment
		(start 395.639798 -130.826002)
		(end 396.425928 -130.039872)
		(width 0.1143)
		(layer "In11.Cu")
		(net "P3E_PCH_M2_RX_DN<2>")
	)
	(segment
		(start 381.6096 -18.880582)
		(end 381.6096 -25.135078)
		(width 0.1143)
		(layer "In11.Cu")
		(net "P3E_PCH_M2_RX_DN<2>")
	)
	(segment
		(start 381.196596 -25.548082)
		(end 381.001524 -25.548082)
		(width 0.1143)
		(layer "In11.Cu")
		(net "P3E_PCH_M2_RX_DN<2>")
	)
	(segment
		(start 398.025366 -23.493222)
		(end 391.562082 -17.029938)
		(width 0.1143)
		(layer "In11.Cu")
		(net "P3E_PCH_M2_RX_DN<2>")
	)
	(segment
		(start 413.633666 -53.000402)
		(end 409.712668 -49.079404)
		(width 0.1143)
		(layer "In11.Cu")
		(net "P3E_PCH_M2_RX_DN<2>")
	)
	(segment
		(start 420.497 -103.2002)
		(end 419.5826 -102.2858)
		(width 0.1143)
		(layer "In11.Cu")
		(net "P3E_PCH_M2_RX_DN<2>")
	)
	(segment
		(start 411.488382 -123.961398)
		(end 414.071054 -121.378726)
		(width 0.1143)
		(layer "In11.Cu")
		(net "P3E_PCH_M2_RX_DN<2>")
	)
	(segment
		(start 420.343838 -69.798438)
		(end 419.735 -69.1896)
		(width 0.1143)
		(layer "In11.Cu")
		(net "P3E_PCH_M2_RX_DN<2>")
	)
	(segment
		(start 420.126668 -94.876366)
		(end 420.126668 -94.559628)
		(width 0.1143)
		(layer "In11.Cu")
		(net "P3E_PCH_M2_RX_DN<2>")
	)
	(segment
		(start 392.39317 -130.015742)
		(end 392.39317 -130.394202)
		(width 0.1143)
		(layer "In11.Cu")
		(net "P3E_PCH_M2_RX_DN<2>")
	)
	(segment
		(start 408.2796 -124.46)
		(end 408.778202 -123.961398)
		(width 0.1143)
		(layer "In11.Cu")
		(net "P3E_PCH_M2_RX_DN<2>")
	)
	(segment
		(start 392.82497 -130.826002)
		(end 395.639798 -130.826002)
		(width 0.1143)
		(layer "In11.Cu")
		(net "P3E_PCH_M2_RX_DN<2>")
	)
	(segment
		(start 400.2913 -40.470074)
		(end 400.2913 -39.939214)
		(width 0.1143)
		(layer "In11.Cu")
		(net "P3E_PCH_M2_RX_DN<2>")
	)
	(segment
		(start 392.44397 -129.953766)
		(end 392.39317 -130.004566)
		(width 0.0889)
		(layer "In11.Cu")
		(net "P3E_PCH_M2_RX_DN<2>")
	)
	(segment
		(start 419.5826 -102.2858)
		(end 419.5826 -95.420434)
		(width 0.1143)
		(layer "In11.Cu")
		(net "P3E_PCH_M2_RX_DN<2>")
	)
	(segment
		(start 419.735 -58.039)
		(end 414.696402 -53.000402)
		(width 0.1143)
		(layer "In11.Cu")
		(net "P3E_PCH_M2_RX_DN<2>")
	)
	(segment
		(start 402.140928 -43.315128)
		(end 402.140928 -42.319702)
		(width 0.1143)
		(layer "In11.Cu")
		(net "P3E_PCH_M2_RX_DN<2>")
	)
	(segment
		(start 419.9128 -116.135658)
		(end 419.9128 -109.516418)
		(width 0.1143)
		(layer "In11.Cu")
		(net "P3E_PCH_M2_RX_DN<2>")
	)
	(segment
		(start 380.73203 -25.278588)
		(end 380.67107 -25.278588)
		(width 0.1143)
		(layer "In11.Cu")
		(net "P3E_PCH_M2_RX_DN<2>")
	)
	(segment
		(start 381.001524 -25.548082)
		(end 380.73203 -25.278588)
		(width 0.1143)
		(layer "In11.Cu")
		(net "P3E_PCH_M2_RX_DN<2>")
	)
	(segment
		(start 391.562082 -17.029938)
		(end 383.460244 -17.029938)
		(width 0.1143)
		(layer "In11.Cu")
		(net "P3E_PCH_M2_RX_DN<2>")
	)
	(segment
		(start 392.44397 -129.242566)
		(end 392.35507 -129.331466)
		(width 0.0889)
		(layer "In11.Cu")
		(net "P3E_PCH_M2_RX_DN<2>")
	)
	(segment
		(start 407.411936 -49.079404)
		(end 406.040082 -47.70755)
		(width 0.1143)
		(layer "In11.Cu")
		(net "P3E_PCH_M2_RX_DN<2>")
	)
	(segment
		(start 392.39317 -130.394202)
		(end 392.82497 -130.826002)
		(width 0.1143)
		(layer "In11.Cu")
		(net "P3E_PCH_M2_RX_DN<2>")
	)
	(segment
		(start 419.735 -69.1896)
		(end 419.735 -58.039)
		(width 0.1143)
		(layer "In11.Cu")
		(net "P3E_PCH_M2_RX_DN<2>")
	)
	(segment
		(start 399.2118 -37.890704)
		(end 399.9611 -37.141404)
		(width 0.1143)
		(layer "In11.Cu")
		(net "P3E_PCH_M2_RX_DN<2>")
	)
	(segment
		(start 400.879564 -128.653286)
		(end 400.879564 -126.244096)
		(width 0.1143)
		(layer "In11.Cu")
		(net "P3E_PCH_M2_RX_DN<2>")
	)
	(segment
		(start 392.44397 -129.687066)
		(end 392.44397 -129.953766)
		(width 0.0889)
		(layer "In11.Cu")
		(net "P3E_PCH_M2_RX_DN<2>")
	)
	(segment
		(start 414.669732 -121.378726)
		(end 419.9128 -116.135658)
		(width 0.1143)
		(layer "In11.Cu")
		(net "P3E_PCH_M2_RX_DN<2>")
	)
	(segment
		(start 392.44397 -127.995172)
		(end 392.44397 -128.531366)
		(width 0.0889)
		(layer "In11.Cu")
		(net "P3E_PCH_M2_RX_DN<2>")
	)
	(segment
		(start 392.35507 -128.620266)
		(end 392.35507 -128.886966)
		(width 0.0889)
		(layer "In11.Cu")
		(net "P3E_PCH_M2_RX_DN<2>")
	)
	(segment
		(start 406.040082 -47.70755)
		(end 405.463756 -47.70755)
		(width 0.1143)
		(layer "In11.Cu")
		(net "P3E_PCH_M2_RX_DN<2>")
	)
	(segment
		(start 392.101324 -127.21209)
		(end 392.214608 -127.325374)
		(width 0.0889)
		(layer "In11.Cu")
		(net "P3E_PCH_M2_RX_DN<2>")
	)
	(segment
		(start 398.92605 -30.86227)
		(end 398.92605 -29.54655)
		(width 0.1143)
		(layer "In11.Cu")
		(net "P3E_PCH_M2_RX_DN<2>")
	)
	(segment
		(start 420.497 -108.932218)
		(end 420.497 -103.2002)
		(width 0.1143)
		(layer "In11.Cu")
		(net "P3E_PCH_M2_RX_DN<2>")
	)
	(segment
		(start 398.92605 -29.54655)
		(end 398.025366 -28.645866)
		(width 0.1143)
		(layer "In11.Cu")
		(net "P3E_PCH_M2_RX_DN<2>")
	)
	(segment
		(start 399.2118 -38.859714)
		(end 399.2118 -37.890704)
		(width 0.1143)
		(layer "In11.Cu")
		(net "P3E_PCH_M2_RX_DN<2>")
	)
	(segment
		(start 403.751288 -124.1552)
		(end 404.056088 -124.46)
		(width 0.1143)
		(layer "In11.Cu")
		(net "P3E_PCH_M2_RX_DN<2>")
	)
	(segment
		(start 392.5951 -129.7051)
		(end 392.68908 -129.79908)
		(width 0.0889)
		(layer "F.Cu")
		(net "P3E_PCH_M2_RX_DN<1>")
	)
	(segment
		(start 392.27506 -128.91135)
		(end 392.174984 -129.011426)
		(width 0.0889)
		(layer "F.Cu")
		(net "P3E_PCH_M2_RX_DN<1>")
	)
	(segment
		(start 382.797304 -28.270962)
		(end 381.84963 -28.270962)
		(width 0.1143)
		(layer "F.Cu")
		(net "P3E_PCH_M2_RX_DN<1>")
	)
	(segment
		(start 392.68908 -129.79908)
		(end 392.86434 -129.79908)
		(width 0.0889)
		(layer "F.Cu")
		(net "P3E_PCH_M2_RX_DN<1>")
	)
	(segment
		(start 392.475466 -129.7051)
		(end 392.5951 -129.7051)
		(width 0.0889)
		(layer "F.Cu")
		(net "P3E_PCH_M2_RX_DN<1>")
	)
	(segment
		(start 393.10564 -129.7051)
		(end 393.2682 -129.86766)
		(width 0.0889)
		(layer "F.Cu")
		(net "P3E_PCH_M2_RX_DN<1>")
	)
	(segment
		(start 392.95832 -129.7051)
		(end 393.10564 -129.7051)
		(width 0.0889)
		(layer "F.Cu")
		(net "P3E_PCH_M2_RX_DN<1>")
	)
	(segment
		(start 391.984992 -126.165102)
		(end 391.9093 -126.240794)
		(width 0.0889)
		(layer "F.Cu")
		(net "P3E_PCH_M2_RX_DN<1>")
	)
	(segment
		(start 392.2014 -126.989586)
		(end 392.119866 -127.07112)
		(width 0.0889)
		(layer "F.Cu")
		(net "P3E_PCH_M2_RX_DN<1>")
	)
	(segment
		(start 392.174984 -129.011426)
		(end 392.174984 -129.189226)
		(width 0.0889)
		(layer "F.Cu")
		(net "P3E_PCH_M2_RX_DN<1>")
	)
	(segment
		(start 391.9093 -126.240794)
		(end 391.9093 -126.377954)
		(width 0.0889)
		(layer "F.Cu")
		(net "P3E_PCH_M2_RX_DN<1>")
	)
	(segment
		(start 392.176 -128.508252)
		(end 392.27506 -128.607312)
		(width 0.0889)
		(layer "F.Cu")
		(net "P3E_PCH_M2_RX_DN<1>")
	)
	(segment
		(start 381.688848 -28.431744)
		(end 381.370332 -28.431744)
		(width 0.1143)
		(layer "F.Cu")
		(net "P3E_PCH_M2_RX_DN<1>")
	)
	(segment
		(start 392.176 -128.330452)
		(end 392.176 -128.508252)
		(width 0.0889)
		(layer "F.Cu")
		(net "P3E_PCH_M2_RX_DN<1>")
	)
	(segment
		(start 392.2014 -126.670054)
		(end 392.2014 -126.989586)
		(width 0.0889)
		(layer "F.Cu")
		(net "P3E_PCH_M2_RX_DN<1>")
	)
	(segment
		(start 392.27506 -129.504694)
		(end 392.475466 -129.7051)
		(width 0.0889)
		(layer "F.Cu")
		(net "P3E_PCH_M2_RX_DN<1>")
	)
	(segment
		(start 391.9093 -126.377954)
		(end 392.2014 -126.670054)
		(width 0.0889)
		(layer "F.Cu")
		(net "P3E_PCH_M2_RX_DN<1>")
	)
	(segment
		(start 392.2014 -127.332994)
		(end 392.2014 -127.93218)
		(width 0.0889)
		(layer "F.Cu")
		(net "P3E_PCH_M2_RX_DN<1>")
	)
	(segment
		(start 393.2682 -129.86766)
		(end 393.2682 -129.9972)
		(width 0.0889)
		(layer "F.Cu")
		(net "P3E_PCH_M2_RX_DN<1>")
	)
	(segment
		(start 392.27506 -129.289302)
		(end 392.27506 -129.504694)
		(width 0.0889)
		(layer "F.Cu")
		(net "P3E_PCH_M2_RX_DN<1>")
	)
	(segment
		(start 381.370332 -28.431744)
		(end 381.11557 -28.176982)
		(width 0.1143)
		(layer "F.Cu")
		(net "P3E_PCH_M2_RX_DN<1>")
	)
	(segment
		(start 392.119866 -127.25146)
		(end 392.2014 -127.332994)
		(width 0.0889)
		(layer "F.Cu")
		(net "P3E_PCH_M2_RX_DN<1>")
	)
	(segment
		(start 392.86434 -129.79908)
		(end 392.95832 -129.7051)
		(width 0.0889)
		(layer "F.Cu")
		(net "P3E_PCH_M2_RX_DN<1>")
	)
	(segment
		(start 392.27506 -128.607312)
		(end 392.27506 -128.91135)
		(width 0.0889)
		(layer "F.Cu")
		(net "P3E_PCH_M2_RX_DN<1>")
	)
	(segment
		(start 392.27506 -128.231392)
		(end 392.176 -128.330452)
		(width 0.0889)
		(layer "F.Cu")
		(net "P3E_PCH_M2_RX_DN<1>")
	)
	(segment
		(start 392.119866 -127.07112)
		(end 392.119866 -127.25146)
		(width 0.0889)
		(layer "F.Cu")
		(net "P3E_PCH_M2_RX_DN<1>")
	)
	(segment
		(start 381.84963 -28.270962)
		(end 381.688848 -28.431744)
		(width 0.1143)
		(layer "F.Cu")
		(net "P3E_PCH_M2_RX_DN<1>")
	)
	(segment
		(start 392.174984 -129.189226)
		(end 392.27506 -129.289302)
		(width 0.0889)
		(layer "F.Cu")
		(net "P3E_PCH_M2_RX_DN<1>")
	)
	(segment
		(start 392.27506 -128.00584)
		(end 392.27506 -128.231392)
		(width 0.0889)
		(layer "F.Cu")
		(net "P3E_PCH_M2_RX_DN<1>")
	)
	(segment
		(start 392.2014 -127.93218)
		(end 392.27506 -128.00584)
		(width 0.0889)
		(layer "F.Cu")
		(net "P3E_PCH_M2_RX_DN<1>")
	)
	(via
		(at 381.11557 -28.176982)
		(size 0.508)
		(drill 0.254)
		(layers "F.Cu" "B.Cu")
		(net "P3E_PCH_M2_RX_DN<1>")
	)
	(via
		(at 393.2682 -129.9972)
		(size 0.508)
		(drill 0.254)
		(layers "F.Cu" "B.Cu")
		(net "P3E_PCH_M2_RX_DN<1>")
	)
	(segment
		(start 419.708838 -79.793846)
		(end 420.793164 -80.878172)
		(width 0.1143)
		(layer "In11.Cu")
		(net "P3E_PCH_M2_RX_DN<1>")
	)
	(segment
		(start 381.57023 -28.46959)
		(end 382.022858 -28.016962)
		(width 0.1143)
		(layer "In11.Cu")
		(net "P3E_PCH_M2_RX_DN<1>")
	)
	(segment
		(start 383.705608 -18.22196)
		(end 391.806938 -18.22196)
		(width 0.1143)
		(layer "In11.Cu")
		(net "P3E_PCH_M2_RX_DN<1>")
	)
	(segment
		(start 419.151054 -115.523264)
		(end 415.840418 -118.8339)
		(width 0.1143)
		(layer "In11.Cu")
		(net "P3E_PCH_M2_RX_DN<1>")
	)
	(segment
		(start 410.471366 -50.7365)
		(end 413.39643 -53.661564)
		(width 0.1143)
		(layer "In11.Cu")
		(net "P3E_PCH_M2_RX_DN<1>")
	)
	(segment
		(start 381.408178 -28.46959)
		(end 381.57023 -28.46959)
		(width 0.1143)
		(layer "In11.Cu")
		(net "P3E_PCH_M2_RX_DN<1>")
	)
	(segment
		(start 398.2847 -31.13151)
		(end 398.6784 -31.52521)
		(width 0.1143)
		(layer "In11.Cu")
		(net "P3E_PCH_M2_RX_DN<1>")
	)
	(segment
		(start 403.523704 -46.715426)
		(end 404.0378 -47.229522)
		(width 0.1143)
		(layer "In11.Cu")
		(net "P3E_PCH_M2_RX_DN<1>")
	)
	(segment
		(start 419.1508 -108.230416)
		(end 419.1508 -115.281202)
		(width 0.1143)
		(layer "In11.Cu")
		(net "P3E_PCH_M2_RX_DN<1>")
	)
	(segment
		(start 404.0378 -48.880014)
		(end 404.637494 -49.479708)
		(width 0.1143)
		(layer "In11.Cu")
		(net "P3E_PCH_M2_RX_DN<1>")
	)
	(segment
		(start 398.5768 -39.128954)
		(end 399.5801 -40.132254)
		(width 0.1143)
		(layer "In11.Cu")
		(net "P3E_PCH_M2_RX_DN<1>")
	)
	(segment
		(start 398.5768 -37.6047)
		(end 398.5768 -39.128954)
		(width 0.1143)
		(layer "In11.Cu")
		(net "P3E_PCH_M2_RX_DN<1>")
	)
	(segment
		(start 414.098232 -119.471186)
		(end 414.098232 -120.37822)
		(width 0.1143)
		(layer "In11.Cu")
		(net "P3E_PCH_M2_RX_DN<1>")
	)
	(segment
		(start 397.390366 -23.805388)
		(end 397.390366 -29.06522)
		(width 0.1143)
		(layer "In11.Cu")
		(net "P3E_PCH_M2_RX_DN<1>")
	)
	(segment
		(start 399.5801 -40.132254)
		(end 399.5801 -40.657272)
		(width 0.1143)
		(layer "In11.Cu")
		(net "P3E_PCH_M2_RX_DN<1>")
	)
	(segment
		(start 399.610072 -126.3396)
		(end 396.5956 -126.3396)
		(width 0.1143)
		(layer "In11.Cu")
		(net "P3E_PCH_M2_RX_DN<1>")
	)
	(segment
		(start 419.151054 -115.281456)
		(end 419.151054 -115.523264)
		(width 0.1143)
		(layer "In11.Cu")
		(net "P3E_PCH_M2_RX_DN<1>")
	)
	(segment
		(start 396.573502 -126.3396)
		(end 396.522702 -126.2888)
		(width 0.0889)
		(layer "In11.Cu")
		(net "P3E_PCH_M2_RX_DN<1>")
	)
	(segment
		(start 404.0378 -47.229522)
		(end 404.0378 -48.880014)
		(width 0.1143)
		(layer "In11.Cu")
		(net "P3E_PCH_M2_RX_DN<1>")
	)
	(segment
		(start 404.637494 -49.479708)
		(end 406.399492 -49.479708)
		(width 0.1143)
		(layer "In11.Cu")
		(net "P3E_PCH_M2_RX_DN<1>")
	)
	(segment
		(start 419.491668 -94.612968)
		(end 418.7571 -95.347536)
		(width 0.1143)
		(layer "In11.Cu")
		(net "P3E_PCH_M2_RX_DN<1>")
	)
	(segment
		(start 401.505928 -42.5831)
		(end 401.505928 -43.578526)
		(width 0.1143)
		(layer "In11.Cu")
		(net "P3E_PCH_M2_RX_DN<1>")
	)
	(segment
		(start 407.656284 -50.7365)
		(end 410.471366 -50.7365)
		(width 0.1143)
		(layer "In11.Cu")
		(net "P3E_PCH_M2_RX_DN<1>")
	)
	(segment
		(start 398.2847 -29.959554)
		(end 398.2847 -31.13151)
		(width 0.1143)
		(layer "In11.Cu")
		(net "P3E_PCH_M2_RX_DN<1>")
	)
	(segment
		(start 406.399492 -49.479708)
		(end 407.656284 -50.7365)
		(width 0.1143)
		(layer "In11.Cu")
		(net "P3E_PCH_M2_RX_DN<1>")
	)
	(segment
		(start 381.11557 -28.176982)
		(end 381.408178 -28.46959)
		(width 0.1143)
		(layer "In11.Cu")
		(net "P3E_PCH_M2_RX_DN<1>")
	)
	(segment
		(start 393.707874 -129.76225)
		(end 393.50315 -129.76225)
		(width 0.0889)
		(layer "In11.Cu")
		(net "P3E_PCH_M2_RX_DN<1>")
	)
	(segment
		(start 396.5956 -126.3396)
		(end 396.573502 -126.3396)
		(width 0.0889)
		(layer "In11.Cu")
		(net "P3E_PCH_M2_RX_DN<1>")
	)
	(segment
		(start 414.098232 -120.37822)
		(end 411.184852 -123.2916)
		(width 0.1143)
		(layer "In11.Cu")
		(net "P3E_PCH_M2_RX_DN<1>")
	)
	(segment
		(start 413.39643 -53.661564)
		(end 413.806386 -53.661564)
		(width 0.1143)
		(layer "In11.Cu")
		(net "P3E_PCH_M2_RX_DN<1>")
	)
	(segment
		(start 396.522702 -126.2888)
		(end 394.8176 -126.2888)
		(width 0.0889)
		(layer "In11.Cu")
		(net "P3E_PCH_M2_RX_DN<1>")
	)
	(segment
		(start 419.491668 -94.29623)
		(end 419.491668 -94.612968)
		(width 0.1143)
		(layer "In11.Cu")
		(net "P3E_PCH_M2_RX_DN<1>")
	)
	(segment
		(start 398.6784 -33.056068)
		(end 399.288 -33.665668)
		(width 0.1143)
		(layer "In11.Cu")
		(net "P3E_PCH_M2_RX_DN<1>")
	)
	(segment
		(start 399.5801 -40.657272)
		(end 401.505928 -42.5831)
		(width 0.1143)
		(layer "In11.Cu")
		(net "P3E_PCH_M2_RX_DN<1>")
	)
	(segment
		(start 419.708838 -70.229984)
		(end 419.708838 -79.793846)
		(width 0.1143)
		(layer "In11.Cu")
		(net "P3E_PCH_M2_RX_DN<1>")
	)
	(segment
		(start 411.184852 -123.2916)
		(end 402.658072 -123.2916)
		(width 0.1143)
		(layer "In11.Cu")
		(net "P3E_PCH_M2_RX_DN<1>")
	)
	(segment
		(start 401.505928 -43.578526)
		(end 403.523704 -45.596302)
		(width 0.1143)
		(layer "In11.Cu")
		(net "P3E_PCH_M2_RX_DN<1>")
	)
	(segment
		(start 413.80664 -53.66131)
		(end 414.458912 -53.66131)
		(width 0.1143)
		(layer "In11.Cu")
		(net "P3E_PCH_M2_RX_DN<1>")
	)
	(segment
		(start 393.50315 -129.76225)
		(end 393.2682 -129.9972)
		(width 0.0889)
		(layer "In11.Cu")
		(net "P3E_PCH_M2_RX_DN<1>")
	)
	(segment
		(start 413.806386 -53.661564)
		(end 413.80664 -53.66131)
		(width 0.1143)
		(layer "In11.Cu")
		(net "P3E_PCH_M2_RX_DN<1>")
	)
	(segment
		(start 391.806938 -18.22196)
		(end 397.390366 -23.805388)
		(width 0.1143)
		(layer "In11.Cu")
		(net "P3E_PCH_M2_RX_DN<1>")
	)
	(segment
		(start 399.288 -33.665668)
		(end 399.288 -36.8935)
		(width 0.1143)
		(layer "In11.Cu")
		(net "P3E_PCH_M2_RX_DN<1>")
	)
	(segment
		(start 394.8176 -126.2888)
		(end 394.3858 -126.7206)
		(width 0.0889)
		(layer "In11.Cu")
		(net "P3E_PCH_M2_RX_DN<1>")
	)
	(segment
		(start 397.390366 -29.06522)
		(end 398.2847 -29.959554)
		(width 0.1143)
		(layer "In11.Cu")
		(net "P3E_PCH_M2_RX_DN<1>")
	)
	(segment
		(start 419.1 -69.621146)
		(end 419.708838 -70.229984)
		(width 0.1143)
		(layer "In11.Cu")
		(net "P3E_PCH_M2_RX_DN<1>")
	)
	(segment
		(start 394.3858 -126.7206)
		(end 394.3858 -129.084324)
		(width 0.0889)
		(layer "In11.Cu")
		(net "P3E_PCH_M2_RX_DN<1>")
	)
	(segment
		(start 418.7571 -107.836716)
		(end 419.1508 -108.230416)
		(width 0.1143)
		(layer "In11.Cu")
		(net "P3E_PCH_M2_RX_DN<1>")
	)
	(segment
		(start 414.458912 -53.66131)
		(end 419.1 -58.302398)
		(width 0.1143)
		(layer "In11.Cu")
		(net "P3E_PCH_M2_RX_DN<1>")
	)
	(segment
		(start 399.288 -36.8935)
		(end 398.5768 -37.6047)
		(width 0.1143)
		(layer "In11.Cu")
		(net "P3E_PCH_M2_RX_DN<1>")
	)
	(segment
		(start 402.658072 -123.2916)
		(end 399.610072 -126.3396)
		(width 0.1143)
		(layer "In11.Cu")
		(net "P3E_PCH_M2_RX_DN<1>")
	)
	(segment
		(start 382.2446 -19.682968)
		(end 383.705608 -18.22196)
		(width 0.1143)
		(layer "In11.Cu")
		(net "P3E_PCH_M2_RX_DN<1>")
	)
	(segment
		(start 420.793164 -92.994734)
		(end 419.491668 -94.29623)
		(width 0.1143)
		(layer "In11.Cu")
		(net "P3E_PCH_M2_RX_DN<1>")
	)
	(segment
		(start 420.793164 -80.878172)
		(end 420.793164 -92.994734)
		(width 0.1143)
		(layer "In11.Cu")
		(net "P3E_PCH_M2_RX_DN<1>")
	)
	(segment
		(start 419.1 -58.302398)
		(end 419.1 -69.621146)
		(width 0.1143)
		(layer "In11.Cu")
		(net "P3E_PCH_M2_RX_DN<1>")
	)
	(segment
		(start 403.523704 -45.596302)
		(end 403.523704 -46.715426)
		(width 0.1143)
		(layer "In11.Cu")
		(net "P3E_PCH_M2_RX_DN<1>")
	)
	(segment
		(start 398.6784 -31.52521)
		(end 398.6784 -33.056068)
		(width 0.1143)
		(layer "In11.Cu")
		(net "P3E_PCH_M2_RX_DN<1>")
	)
	(segment
		(start 415.840418 -118.8339)
		(end 414.735518 -118.8339)
		(width 0.1143)
		(layer "In11.Cu")
		(net "P3E_PCH_M2_RX_DN<1>")
	)
	(segment
		(start 419.1508 -115.281202)
		(end 419.151054 -115.281456)
		(width 0.1143)
		(layer "In11.Cu")
		(net "P3E_PCH_M2_RX_DN<1>")
	)
	(segment
		(start 418.7571 -95.347536)
		(end 418.7571 -107.836716)
		(width 0.1143)
		(layer "In11.Cu")
		(net "P3E_PCH_M2_RX_DN<1>")
	)
	(segment
		(start 382.022858 -25.639776)
		(end 382.2446 -25.418034)
		(width 0.1143)
		(layer "In11.Cu")
		(net "P3E_PCH_M2_RX_DN<1>")
	)
	(segment
		(start 394.3858 -129.084324)
		(end 393.707874 -129.76225)
		(width 0.0889)
		(layer "In11.Cu")
		(net "P3E_PCH_M2_RX_DN<1>")
	)
	(segment
		(start 382.2446 -25.418034)
		(end 382.2446 -19.682968)
		(width 0.1143)
		(layer "In11.Cu")
		(net "P3E_PCH_M2_RX_DN<1>")
	)
	(segment
		(start 414.735518 -118.8339)
		(end 414.098232 -119.471186)
		(width 0.1143)
		(layer "In11.Cu")
		(net "P3E_PCH_M2_RX_DN<1>")
	)
	(segment
		(start 382.022858 -28.016962)
		(end 382.022858 -25.639776)
		(width 0.1143)
		(layer "In11.Cu")
		(net "P3E_PCH_M2_RX_DN<1>")
	)
	(segment
		(start 474.472 -148.3995)
		(end 474.472 -149.0472)
		(width 0.10795)
		(layer "F.Cu")
		(net "PWRGD_P3V3")
	)
	(segment
		(start 375.144792 -73.495154)
		(end 374.744996 -73.89495)
		(width 0.10795)
		(layer "F.Cu")
		(net "PWRGD_P3V3")
	)
	(segment
		(start 387.067298 -82.573622)
		(end 386.464302 -82.573622)
		(width 0.10795)
		(layer "F.Cu")
		(net "PWRGD_P3V3")
	)
	(segment
		(start 385.791456 -80.854296)
		(end 385.91744 -80.854296)
		(width 0.10795)
		(layer "F.Cu")
		(net "PWRGD_P3V3")
	)
	(segment
		(start 474.472 -149.0472)
		(end 474.1672 -149.352)
		(width 0.10795)
		(layer "F.Cu")
		(net "PWRGD_P3V3")
	)
	(segment
		(start 386.531612 -81.468468)
		(end 387.048248 -81.468468)
		(width 0.10795)
		(layer "F.Cu")
		(net "PWRGD_P3V3")
	)
	(segment
		(start 387.048248 -81.468468)
		(end 387.27634 -81.69656)
		(width 0.10795)
		(layer "F.Cu")
		(net "PWRGD_P3V3")
	)
	(segment
		(start 387.27634 -82.36458)
		(end 387.067298 -82.573622)
		(width 0.10795)
		(layer "F.Cu")
		(net "PWRGD_P3V3")
	)
	(segment
		(start 387.27634 -81.69656)
		(end 387.27634 -82.36458)
		(width 0.10795)
		(layer "F.Cu")
		(net "PWRGD_P3V3")
	)
	(segment
		(start 385.58724 -80.65008)
		(end 385.791456 -80.854296)
		(width 0.10795)
		(layer "F.Cu")
		(net "PWRGD_P3V3")
	)
	(segment
		(start 385.91744 -80.854296)
		(end 386.531612 -81.468468)
		(width 0.10795)
		(layer "F.Cu")
		(net "PWRGD_P3V3")
	)
	(via
		(at 489.458 -156.083)
		(size 0.508)
		(drill 0.254)
		(layers "F.Cu" "B.Cu")
		(net "PWRGD_P3V3")
	)
	(via
		(at 375.144792 -73.495154)
		(size 0.4572)
		(drill 0.2032)
		(layers "F.Cu" "B.Cu")
		(net "PWRGD_P3V3")
	)
	(via
		(at 474.1672 -149.352)
		(size 0.508)
		(drill 0.254)
		(layers "F.Cu" "B.Cu")
		(net "PWRGD_P3V3")
	)
	(via
		(at 390.525 -74.3712)
		(size 0.508)
		(drill 0.254)
		(layers "F.Cu" "B.Cu")
		(net "PWRGD_P3V3")
	)
	(via
		(at 385.58724 -80.65008)
		(size 0.508)
		(drill 0.254)
		(layers "F.Cu" "B.Cu")
		(net "PWRGD_P3V3")
	)
	(via
		(at 423.6974 -106.3498)
		(size 0.508)
		(drill 0.254)
		(layers "F.Cu" "B.Cu")
		(net "PWRGD_P3V3")
	)
	(via
		(at 423.85869 -87.447628)
		(size 0.6604)
		(drill 0.3302)
		(layers "F.Cu" "B.Cu")
		(net "PWRGD_P3V3")
	)
	(segment
		(start 422.187878 -65.167002)
		(end 421.486584 -64.465708)
		(width 0.10795)
		(layer "B.Cu")
		(net "PWRGD_P3V3")
	)
	(segment
		(start 415.500058 -65.514474)
		(end 414.71723 -66.297302)
		(width 0.10795)
		(layer "B.Cu")
		(net "PWRGD_P3V3")
	)
	(segment
		(start 390.831578 -74.830178)
		(end 390.525 -74.5236)
		(width 0.10795)
		(layer "B.Cu")
		(net "PWRGD_P3V3")
	)
	(segment
		(start 424.10126 -91.116658)
		(end 424.10126 -105.94594)
		(width 0.10795)
		(layer "B.Cu")
		(net "PWRGD_P3V3")
	)
	(segment
		(start 410.322776 -68.55714)
		(end 409.530804 -69.349112)
		(width 0.10795)
		(layer "B.Cu")
		(net "PWRGD_P3V3")
	)
	(segment
		(start 423.85869 -73.941178)
		(end 423.58945 -73.671938)
		(width 0.10795)
		(layer "B.Cu")
		(net "PWRGD_P3V3")
	)
	(segment
		(start 490.5375 -155.3337)
		(end 490.5375 -155.600146)
		(width 0.10795)
		(layer "B.Cu")
		(net "PWRGD_P3V3")
	)
	(segment
		(start 421.486584 -64.465708)
		(end 417.489132 -64.465708)
		(width 0.10795)
		(layer "B.Cu")
		(net "PWRGD_P3V3")
	)
	(segment
		(start 424.10126 -105.94594)
		(end 423.6974 -106.3498)
		(width 0.10795)
		(layer "B.Cu")
		(net "PWRGD_P3V3")
	)
	(segment
		(start 385.58724 -80.35036)
		(end 386.64388 -79.29372)
		(width 0.10795)
		(layer "B.Cu")
		(net "PWRGD_P3V3")
	)
	(segment
		(start 412.036514 -68.24472)
		(end 412.036514 -68.26504)
		(width 0.10795)
		(layer "B.Cu")
		(net "PWRGD_P3V3")
	)
	(segment
		(start 392.95451 -74.830178)
		(end 392.954256 -74.830432)
		(width 0.10795)
		(layer "B.Cu")
		(net "PWRGD_P3V3")
	)
	(segment
		(start 395.690598 -73.650602)
		(end 395.084808 -74.256392)
		(width 0.10795)
		(layer "B.Cu")
		(net "PWRGD_P3V3")
	)
	(segment
		(start 412.036514 -68.26504)
		(end 411.887924 -68.26504)
		(width 0.10795)
		(layer "B.Cu")
		(net "PWRGD_P3V3")
	)
	(segment
		(start 422.187878 -70.961758)
		(end 422.187878 -65.167002)
		(width 0.10795)
		(layer "B.Cu")
		(net "PWRGD_P3V3")
	)
	(segment
		(start 417.489132 -64.465708)
		(end 416.440366 -65.514474)
		(width 0.10795)
		(layer "B.Cu")
		(net "PWRGD_P3V3")
	)
	(segment
		(start 423.85869 -87.447628)
		(end 423.85869 -90.874088)
		(width 0.10795)
		(layer "B.Cu")
		(net "PWRGD_P3V3")
	)
	(segment
		(start 396.015464 -73.140316)
		(end 395.690598 -73.465182)
		(width 0.10795)
		(layer "B.Cu")
		(net "PWRGD_P3V3")
	)
	(segment
		(start 411.887924 -68.26504)
		(end 411.573726 -68.55714)
		(width 0.10795)
		(layer "B.Cu")
		(net "PWRGD_P3V3")
	)
	(segment
		(start 388.907528 -75.937364)
		(end 389.024622 -75.82027)
		(width 0.10795)
		(layer "B.Cu")
		(net "PWRGD_P3V3")
	)
	(segment
		(start 395.690598 -73.465182)
		(end 395.690598 -73.650602)
		(width 0.10795)
		(layer "B.Cu")
		(net "PWRGD_P3V3")
	)
	(segment
		(start 490.5375 -155.600146)
		(end 490.054646 -156.083)
		(width 0.10795)
		(layer "B.Cu")
		(net "PWRGD_P3V3")
	)
	(segment
		(start 388.907274 -75.937364)
		(end 388.907528 -75.937364)
		(width 0.10795)
		(layer "B.Cu")
		(net "PWRGD_P3V3")
	)
	(segment
		(start 396.378684 -73.140316)
		(end 396.015464 -73.140316)
		(width 0.10795)
		(layer "B.Cu")
		(net "PWRGD_P3V3")
	)
	(segment
		(start 396.691866 -72.827134)
		(end 396.378684 -73.140316)
		(width 0.10795)
		(layer "B.Cu")
		(net "PWRGD_P3V3")
	)
	(segment
		(start 411.573726 -68.55714)
		(end 410.322776 -68.55714)
		(width 0.10795)
		(layer "B.Cu")
		(net "PWRGD_P3V3")
	)
	(segment
		(start 392.954256 -74.830432)
		(end 391.784078 -74.830432)
		(width 0.10795)
		(layer "B.Cu")
		(net "PWRGD_P3V3")
	)
	(segment
		(start 393.601702 -74.830432)
		(end 393.065254 -74.830432)
		(width 0.10795)
		(layer "B.Cu")
		(net "PWRGD_P3V3")
	)
	(segment
		(start 389.891016 -75.82027)
		(end 390.438132 -75.273154)
		(width 0.10795)
		(layer "B.Cu")
		(net "PWRGD_P3V3")
	)
	(segment
		(start 393.647422 -74.830178)
		(end 393.601956 -74.830178)
		(width 0.10795)
		(layer "B.Cu")
		(net "PWRGD_P3V3")
	)
	(segment
		(start 409.530804 -69.349112)
		(end 400.39798 -69.349112)
		(width 0.10795)
		(layer "B.Cu")
		(net "PWRGD_P3V3")
	)
	(segment
		(start 390.438132 -74.458068)
		(end 390.525 -74.3712)
		(width 0.10795)
		(layer "B.Cu")
		(net "PWRGD_P3V3")
	)
	(segment
		(start 397.982694 -70.946518)
		(end 396.691612 -72.2376)
		(width 0.10795)
		(layer "B.Cu")
		(net "PWRGD_P3V3")
	)
	(segment
		(start 398.800574 -70.946518)
		(end 397.982694 -70.946518)
		(width 0.10795)
		(layer "B.Cu")
		(net "PWRGD_P3V3")
	)
	(segment
		(start 423.58945 -73.671938)
		(end 423.58945 -72.36333)
		(width 0.10795)
		(layer "B.Cu")
		(net "PWRGD_P3V3")
	)
	(segment
		(start 423.85869 -90.874088)
		(end 424.10126 -91.116658)
		(width 0.10795)
		(layer "B.Cu")
		(net "PWRGD_P3V3")
	)
	(segment
		(start 390.525 -74.5236)
		(end 390.525 -74.3712)
		(width 0.10795)
		(layer "B.Cu")
		(net "PWRGD_P3V3")
	)
	(segment
		(start 396.691866 -72.537574)
		(end 396.691866 -72.827134)
		(width 0.10795)
		(layer "B.Cu")
		(net "PWRGD_P3V3")
	)
	(segment
		(start 490.054646 -156.083)
		(end 489.458 -156.083)
		(width 0.10795)
		(layer "B.Cu")
		(net "PWRGD_P3V3")
	)
	(segment
		(start 414.71723 -66.297302)
		(end 414.71723 -67.702684)
		(width 0.10795)
		(layer "B.Cu")
		(net "PWRGD_P3V3")
	)
	(segment
		(start 393.065 -74.830178)
		(end 392.95451 -74.830178)
		(width 0.10795)
		(layer "B.Cu")
		(net "PWRGD_P3V3")
	)
	(segment
		(start 423.58945 -72.36333)
		(end 422.187878 -70.961758)
		(width 0.10795)
		(layer "B.Cu")
		(net "PWRGD_P3V3")
	)
	(segment
		(start 389.024622 -75.82027)
		(end 389.891016 -75.82027)
		(width 0.10795)
		(layer "B.Cu")
		(net "PWRGD_P3V3")
	)
	(segment
		(start 391.783824 -74.830178)
		(end 390.831578 -74.830178)
		(width 0.10795)
		(layer "B.Cu")
		(net "PWRGD_P3V3")
	)
	(segment
		(start 395.084808 -74.256392)
		(end 394.221208 -74.256392)
		(width 0.10795)
		(layer "B.Cu")
		(net "PWRGD_P3V3")
	)
	(segment
		(start 386.64388 -79.29372)
		(end 386.64388 -78.200758)
		(width 0.10795)
		(layer "B.Cu")
		(net "PWRGD_P3V3")
	)
	(segment
		(start 396.691612 -72.53732)
		(end 396.691866 -72.537574)
		(width 0.10795)
		(layer "B.Cu")
		(net "PWRGD_P3V3")
	)
	(segment
		(start 391.784078 -74.830432)
		(end 391.783824 -74.830178)
		(width 0.10795)
		(layer "B.Cu")
		(net "PWRGD_P3V3")
	)
	(segment
		(start 393.065254 -74.830432)
		(end 393.065 -74.830178)
		(width 0.10795)
		(layer "B.Cu")
		(net "PWRGD_P3V3")
	)
	(segment
		(start 396.691612 -72.2376)
		(end 396.691612 -72.53732)
		(width 0.10795)
		(layer "B.Cu")
		(net "PWRGD_P3V3")
	)
	(segment
		(start 414.71723 -67.702684)
		(end 414.175194 -68.24472)
		(width 0.10795)
		(layer "B.Cu")
		(net "PWRGD_P3V3")
	)
	(segment
		(start 400.39798 -69.349112)
		(end 398.800574 -70.946518)
		(width 0.10795)
		(layer "B.Cu")
		(net "PWRGD_P3V3")
	)
	(segment
		(start 393.601956 -74.830178)
		(end 393.601702 -74.830432)
		(width 0.10795)
		(layer "B.Cu")
		(net "PWRGD_P3V3")
	)
	(segment
		(start 423.85869 -87.447628)
		(end 423.85869 -73.941178)
		(width 0.10795)
		(layer "B.Cu")
		(net "PWRGD_P3V3")
	)
	(segment
		(start 394.221208 -74.256392)
		(end 393.647422 -74.830178)
		(width 0.10795)
		(layer "B.Cu")
		(net "PWRGD_P3V3")
	)
	(segment
		(start 385.58724 -80.65008)
		(end 385.58724 -80.35036)
		(width 0.10795)
		(layer "B.Cu")
		(net "PWRGD_P3V3")
	)
	(segment
		(start 390.438132 -75.273154)
		(end 390.438132 -74.458068)
		(width 0.10795)
		(layer "B.Cu")
		(net "PWRGD_P3V3")
	)
	(segment
		(start 416.440366 -65.514474)
		(end 415.500058 -65.514474)
		(width 0.10795)
		(layer "B.Cu")
		(net "PWRGD_P3V3")
	)
	(segment
		(start 414.175194 -68.24472)
		(end 412.036514 -68.24472)
		(width 0.10795)
		(layer "B.Cu")
		(net "PWRGD_P3V3")
	)
	(segment
		(start 386.64388 -78.200758)
		(end 388.907274 -75.937364)
		(width 0.10795)
		(layer "B.Cu")
		(net "PWRGD_P3V3")
	)
	(segment
		(start 388.057898 -73.317354)
		(end 386.22859 -73.317354)
		(width 0.089408)
		(layer "In4.Cu")
		(net "PWRGD_P3V3")
	)
	(segment
		(start 381.805434 -73.7108)
		(end 381.602234 -73.914)
		(width 0.089408)
		(layer "In4.Cu")
		(net "PWRGD_P3V3")
	)
	(segment
		(start 484.0351 -151.7269)
		(end 488.3912 -156.083)
		(width 0.089408)
		(layer "In4.Cu")
		(net "PWRGD_P3V3")
	)
	(segment
		(start 389.010144 -74.2696)
		(end 388.057898 -73.317354)
		(width 0.089408)
		(layer "In4.Cu")
		(net "PWRGD_P3V3")
	)
	(segment
		(start 378.2314 -73.914)
		(end 378.079 -74.0664)
		(width 0.089408)
		(layer "In4.Cu")
		(net "PWRGD_P3V3")
	)
	(segment
		(start 475.257368 -149.502368)
		(end 477.4819 -151.7269)
		(width 0.089408)
		(layer "In4.Cu")
		(net "PWRGD_P3V3")
	)
	(segment
		(start 390.4234 -74.2696)
		(end 389.010144 -74.2696)
		(width 0.089408)
		(layer "In4.Cu")
		(net "PWRGD_P3V3")
	)
	(segment
		(start 477.4819 -151.7269)
		(end 484.0351 -151.7269)
		(width 0.089408)
		(layer "In4.Cu")
		(net "PWRGD_P3V3")
	)
	(segment
		(start 385.835144 -73.7108)
		(end 381.805434 -73.7108)
		(width 0.089408)
		(layer "In4.Cu")
		(net "PWRGD_P3V3")
	)
	(segment
		(start 474.1672 -149.352)
		(end 474.317568 -149.502368)
		(width 0.089408)
		(layer "In4.Cu")
		(net "PWRGD_P3V3")
	)
	(segment
		(start 474.317568 -149.502368)
		(end 475.257368 -149.502368)
		(width 0.089408)
		(layer "In4.Cu")
		(net "PWRGD_P3V3")
	)
	(segment
		(start 378.079 -74.0664)
		(end 375.716038 -74.0664)
		(width 0.089408)
		(layer "In4.Cu")
		(net "PWRGD_P3V3")
	)
	(segment
		(start 390.525 -74.3712)
		(end 390.4234 -74.2696)
		(width 0.089408)
		(layer "In4.Cu")
		(net "PWRGD_P3V3")
	)
	(segment
		(start 488.3912 -156.083)
		(end 489.458 -156.083)
		(width 0.089408)
		(layer "In4.Cu")
		(net "PWRGD_P3V3")
	)
	(segment
		(start 381.602234 -73.914)
		(end 378.2314 -73.914)
		(width 0.089408)
		(layer "In4.Cu")
		(net "PWRGD_P3V3")
	)
	(segment
		(start 386.22859 -73.317354)
		(end 385.835144 -73.7108)
		(width 0.089408)
		(layer "In4.Cu")
		(net "PWRGD_P3V3")
	)
	(segment
		(start 375.716038 -74.0664)
		(end 375.144792 -73.495154)
		(width 0.089408)
		(layer "In4.Cu")
		(net "PWRGD_P3V3")
	)
	(segment
		(start 481.270056 -110.961424)
		(end 482.590348 -112.281716)
		(width 0.089408)
		(layer "In9.Cu")
		(net "PWRGD_P3V3")
	)
	(segment
		(start 425.629832 -109.238796)
		(end 427.35246 -110.961424)
		(width 0.089408)
		(layer "In9.Cu")
		(net "PWRGD_P3V3")
	)
	(segment
		(start 423.6974 -106.3498)
		(end 423.878248 -106.3498)
		(width 0.089408)
		(layer "In9.Cu")
		(net "PWRGD_P3V3")
	)
	(segment
		(start 499.06174 -120.4341)
		(end 499.06174 -127.20066)
		(width 0.089408)
		(layer "In9.Cu")
		(net "PWRGD_P3V3")
	)
	(segment
		(start 500.627904 -128.766824)
		(end 500.627904 -132.78866)
		(width 0.089408)
		(layer "In9.Cu")
		(net "PWRGD_P3V3")
	)
	(segment
		(start 492.589312 -111.17707)
		(end 497.50345 -111.17707)
		(width 0.089408)
		(layer "In9.Cu")
		(net "PWRGD_P3V3")
	)
	(segment
		(start 494.99774 -156.083)
		(end 489.458 -156.083)
		(width 0.089408)
		(layer "In9.Cu")
		(net "PWRGD_P3V3")
	)
	(segment
		(start 482.590348 -112.281716)
		(end 491.484666 -112.281716)
		(width 0.089408)
		(layer "In9.Cu")
		(net "PWRGD_P3V3")
	)
	(segment
		(start 499.06174 -127.20066)
		(end 500.627904 -128.766824)
		(width 0.089408)
		(layer "In9.Cu")
		(net "PWRGD_P3V3")
	)
	(segment
		(start 427.35246 -110.961424)
		(end 481.270056 -110.961424)
		(width 0.089408)
		(layer "In9.Cu")
		(net "PWRGD_P3V3")
	)
	(segment
		(start 500.627904 -114.301524)
		(end 500.627904 -118.867936)
		(width 0.089408)
		(layer "In9.Cu")
		(net "PWRGD_P3V3")
	)
	(segment
		(start 499.611904 -151.468836)
		(end 494.99774 -156.083)
		(width 0.089408)
		(layer "In9.Cu")
		(net "PWRGD_P3V3")
	)
	(segment
		(start 500.627904 -132.78866)
		(end 499.611904 -133.80466)
		(width 0.089408)
		(layer "In9.Cu")
		(net "PWRGD_P3V3")
	)
	(segment
		(start 491.484666 -112.281716)
		(end 492.589312 -111.17707)
		(width 0.089408)
		(layer "In9.Cu")
		(net "PWRGD_P3V3")
	)
	(segment
		(start 423.878248 -106.3498)
		(end 425.629832 -108.101384)
		(width 0.089408)
		(layer "In9.Cu")
		(net "PWRGD_P3V3")
	)
	(segment
		(start 500.627904 -118.867936)
		(end 499.06174 -120.4341)
		(width 0.089408)
		(layer "In9.Cu")
		(net "PWRGD_P3V3")
	)
	(segment
		(start 425.629832 -108.101384)
		(end 425.629832 -109.238796)
		(width 0.089408)
		(layer "In9.Cu")
		(net "PWRGD_P3V3")
	)
	(segment
		(start 497.50345 -111.17707)
		(end 500.627904 -114.301524)
		(width 0.089408)
		(layer "In9.Cu")
		(net "PWRGD_P3V3")
	)
	(segment
		(start 499.611904 -133.80466)
		(end 499.611904 -151.468836)
		(width 0.089408)
		(layer "In9.Cu")
		(net "PWRGD_P3V3")
	)
	(segment
		(start 428.3456 -134.874)
		(end 428.3456 -131.958842)
		(width 0.10795)
		(layer "F.Cu")
		(net "FM_CTNR_PS_ON")
	)
	(segment
		(start 426.753782 -135.848852)
		(end 427.322234 -135.2804)
		(width 0.10795)
		(layer "F.Cu")
		(net "FM_CTNR_PS_ON")
	)
	(segment
		(start 434.990748 -132.170424)
		(end 434.990748 -131.3053)
		(width 0.10795)
		(layer "F.Cu")
		(net "FM_CTNR_PS_ON")
	)
	(segment
		(start 427.322234 -135.2804)
		(end 427.9392 -135.2804)
		(width 0.10795)
		(layer "F.Cu")
		(net "FM_CTNR_PS_ON")
	)
	(segment
		(start 429.26 -131.6355)
		(end 430.026318 -131.6355)
		(width 0.10795)
		(layer "F.Cu")
		(net "FM_CTNR_PS_ON")
	)
	(segment
		(start 434.67147 -132.489702)
		(end 434.990748 -132.170424)
		(width 0.10795)
		(layer "F.Cu")
		(net "FM_CTNR_PS_ON")
	)
	(segment
		(start 430.026826 -131.636008)
		(end 430.026826 -132.068316)
		(width 0.10795)
		(layer "F.Cu")
		(net "FM_CTNR_PS_ON")
	)
	(segment
		(start 427.9392 -135.2804)
		(end 428.3456 -134.874)
		(width 0.10795)
		(layer "F.Cu")
		(net "FM_CTNR_PS_ON")
	)
	(segment
		(start 432.127914 -154.895042)
		(end 432.127914 -152.976072)
		(width 0.10795)
		(layer "F.Cu")
		(net "FM_CTNR_PS_ON")
	)
	(segment
		(start 433.04206 -132.917438)
		(end 433.469796 -132.489702)
		(width 0.10795)
		(layer "F.Cu")
		(net "FM_CTNR_PS_ON")
	)
	(segment
		(start 430.026318 -131.6355)
		(end 430.026826 -131.636008)
		(width 0.10795)
		(layer "F.Cu")
		(net "FM_CTNR_PS_ON")
	)
	(segment
		(start 413.8422 -97.8916)
		(end 412.922974 -96.972374)
		(width 0.10795)
		(layer "F.Cu")
		(net "FM_CTNR_PS_ON")
	)
	(segment
		(start 21.6281 -43.18254)
		(end 21.6281 -42.0243)
		(width 0.1016)
		(layer "F.Cu")
		(net "FM_CTNR_PS_ON")
	)
	(segment
		(start 21.0058 -41.402)
		(end 20.2946 -41.402)
		(width 0.1016)
		(layer "F.Cu")
		(net "FM_CTNR_PS_ON")
	)
	(segment
		(start 412.1277 -90.9828)
		(end 412.1277 -93.871288)
		(width 0.10795)
		(layer "F.Cu")
		(net "FM_CTNR_PS_ON")
	)
	(segment
		(start 428.668942 -131.6355)
		(end 429.26 -131.6355)
		(width 0.10795)
		(layer "F.Cu")
		(net "FM_CTNR_PS_ON")
	)
	(segment
		(start 377.544838 -68.695316)
		(end 377.145042 -69.095112)
		(width 0.10795)
		(layer "F.Cu")
		(net "FM_CTNR_PS_ON")
	)
	(segment
		(start 23.071074 -46.985428)
		(end 23.071074 -44.625514)
		(width 0.1016)
		(layer "F.Cu")
		(net "FM_CTNR_PS_ON")
	)
	(segment
		(start 412.1277 -93.871288)
		(end 412.922974 -94.666562)
		(width 0.10795)
		(layer "F.Cu")
		(net "FM_CTNR_PS_ON")
	)
	(segment
		(start 23.071074 -44.625514)
		(end 21.6281 -43.18254)
		(width 0.1016)
		(layer "F.Cu")
		(net "FM_CTNR_PS_ON")
	)
	(segment
		(start 428.3456 -131.958842)
		(end 428.668942 -131.6355)
		(width 0.10795)
		(layer "F.Cu")
		(net "FM_CTNR_PS_ON")
	)
	(segment
		(start 412.922974 -96.972374)
		(end 412.922974 -94.666562)
		(width 0.10795)
		(layer "F.Cu")
		(net "FM_CTNR_PS_ON")
	)
	(segment
		(start 431.572924 -155.450032)
		(end 432.127914 -154.895042)
		(width 0.10795)
		(layer "F.Cu")
		(net "FM_CTNR_PS_ON")
	)
	(segment
		(start 430.026826 -132.068316)
		(end 430.875948 -132.917438)
		(width 0.10795)
		(layer "F.Cu")
		(net "FM_CTNR_PS_ON")
	)
	(segment
		(start 21.6281 -42.0243)
		(end 21.0058 -41.402)
		(width 0.1016)
		(layer "F.Cu")
		(net "FM_CTNR_PS_ON")
	)
	(segment
		(start 426.753782 -136.014206)
		(end 426.753782 -135.848852)
		(width 0.10795)
		(layer "F.Cu")
		(net "FM_CTNR_PS_ON")
	)
	(segment
		(start 433.469796 -132.489702)
		(end 434.67147 -132.489702)
		(width 0.10795)
		(layer "F.Cu")
		(net "FM_CTNR_PS_ON")
	)
	(segment
		(start 431.572924 -156.976572)
		(end 431.572924 -155.450032)
		(width 0.10795)
		(layer "F.Cu")
		(net "FM_CTNR_PS_ON")
	)
	(segment
		(start 430.875948 -132.917438)
		(end 433.04206 -132.917438)
		(width 0.10795)
		(layer "F.Cu")
		(net "FM_CTNR_PS_ON")
	)
	(via
		(at 403.0218 -157.5054)
		(size 0.508)
		(drill 0.254)
		(layers "F.Cu" "B.Cu")
		(net "FM_CTNR_PS_ON")
	)
	(via
		(at 431.572924 -156.976572)
		(size 0.508)
		(drill 0.254)
		(layers "F.Cu" "B.Cu")
		(net "FM_CTNR_PS_ON")
	)
	(via
		(at 377.544838 -68.695316)
		(size 0.4572)
		(drill 0.2032)
		(layers "F.Cu" "B.Cu")
		(net "FM_CTNR_PS_ON")
	)
	(via
		(at 23.071074 -46.985428)
		(size 0.508)
		(drill 0.254)
		(layers "F.Cu" "B.Cu")
		(net "FM_CTNR_PS_ON")
	)
	(via
		(at 417.058602 -125.974856)
		(size 0.508)
		(drill 0.254)
		(layers "F.Cu" "B.Cu")
		(net "FM_CTNR_PS_ON")
	)
	(via
		(at 432.127914 -152.976072)
		(size 0.508)
		(drill 0.254)
		(layers "F.Cu" "B.Cu")
		(net "FM_CTNR_PS_ON")
	)
	(via
		(at 353.21113 -139.529312)
		(size 0.508)
		(drill 0.254)
		(layers "F.Cu" "B.Cu")
		(net "FM_CTNR_PS_ON")
	)
	(via
		(at 426.753782 -136.014206)
		(size 0.508)
		(drill 0.254)
		(layers "F.Cu" "B.Cu")
		(net "FM_CTNR_PS_ON")
	)
	(via
		(at 391.281158 -157.558232)
		(size 0.508)
		(drill 0.254)
		(layers "F.Cu" "B.Cu")
		(net "FM_CTNR_PS_ON")
	)
	(via
		(at 415.869374 -66.274188)
		(size 0.508)
		(drill 0.254)
		(layers "F.Cu" "B.Cu")
		(net "FM_CTNR_PS_ON")
	)
	(via
		(at 327.8886 -143.0782)
		(size 0.508)
		(drill 0.254)
		(layers "F.Cu" "B.Cu")
		(net "FM_CTNR_PS_ON")
	)
	(via
		(at 412.922974 -94.666562)
		(size 0.762)
		(drill 0.381)
		(layers "F.Cu" "B.Cu")
		(net "FM_CTNR_PS_ON")
	)
	(via
		(at 413.8422 -97.8916)
		(size 0.508)
		(drill 0.254)
		(layers "F.Cu" "B.Cu")
		(net "FM_CTNR_PS_ON")
	)
	(segment
		(start 347.626432 -137.8966)
		(end 348.665292 -138.93546)
		(width 0.10795)
		(layer "B.Cu")
		(net "FM_CTNR_PS_ON")
	)
	(segment
		(start 413.8422 -97.8916)
		(end 414.632902 -98.682302)
		(width 0.10795)
		(layer "B.Cu")
		(net "FM_CTNR_PS_ON")
	)
	(segment
		(start 414.632902 -102.206298)
		(end 414.4518 -102.3874)
		(width 0.10795)
		(layer "B.Cu")
		(net "FM_CTNR_PS_ON")
	)
	(segment
		(start 414.034986 -103.349044)
		(end 414.607756 -103.349044)
		(width 0.10795)
		(layer "B.Cu")
		(net "FM_CTNR_PS_ON")
	)
	(segment
		(start 415.434272 -119.318532)
		(end 415.434272 -124.477018)
		(width 0.10795)
		(layer "B.Cu")
		(net "FM_CTNR_PS_ON")
	)
	(segment
		(start 352.617278 -138.93546)
		(end 353.21113 -139.529312)
		(width 0.10795)
		(layer "B.Cu")
		(net "FM_CTNR_PS_ON")
	)
	(segment
		(start 327.8886 -141.9225)
		(end 328.708258 -141.102842)
		(width 0.10795)
		(layer "B.Cu")
		(net "FM_CTNR_PS_ON")
	)
	(segment
		(start 416.264852 -106.918252)
		(end 414.690052 -108.493052)
		(width 0.10795)
		(layer "B.Cu")
		(net "FM_CTNR_PS_ON")
	)
	(segment
		(start 328.708258 -139.210542)
		(end 329.340718 -138.578082)
		(width 0.10795)
		(layer "B.Cu")
		(net "FM_CTNR_PS_ON")
	)
	(segment
		(start 414.690052 -108.493052)
		(end 414.690052 -118.574312)
		(width 0.10795)
		(layer "B.Cu")
		(net "FM_CTNR_PS_ON")
	)
	(segment
		(start 416.264852 -105.00614)
		(end 416.264852 -106.918252)
		(width 0.10795)
		(layer "B.Cu")
		(net "FM_CTNR_PS_ON")
	)
	(segment
		(start 414.02 -102.3874)
		(end 413.766 -102.6414)
		(width 0.10795)
		(layer "B.Cu")
		(net "FM_CTNR_PS_ON")
	)
	(segment
		(start 414.607756 -103.349044)
		(end 416.264852 -105.00614)
		(width 0.10795)
		(layer "B.Cu")
		(net "FM_CTNR_PS_ON")
	)
	(segment
		(start 413.766 -102.6414)
		(end 413.766 -103.080058)
		(width 0.10795)
		(layer "B.Cu")
		(net "FM_CTNR_PS_ON")
	)
	(segment
		(start 328.708258 -141.102842)
		(end 328.708258 -139.210542)
		(width 0.10795)
		(layer "B.Cu")
		(net "FM_CTNR_PS_ON")
	)
	(segment
		(start 414.632902 -98.682302)
		(end 414.632902 -102.206298)
		(width 0.10795)
		(layer "B.Cu")
		(net "FM_CTNR_PS_ON")
	)
	(segment
		(start 327.8886 -143.0782)
		(end 327.8886 -141.9225)
		(width 0.10795)
		(layer "B.Cu")
		(net "FM_CTNR_PS_ON")
	)
	(segment
		(start 348.665292 -138.93546)
		(end 352.617278 -138.93546)
		(width 0.10795)
		(layer "B.Cu")
		(net "FM_CTNR_PS_ON")
	)
	(segment
		(start 329.340718 -138.578082)
		(end 334.808322 -138.578082)
		(width 0.10795)
		(layer "B.Cu")
		(net "FM_CTNR_PS_ON")
	)
	(segment
		(start 334.808322 -138.578082)
		(end 336.110072 -137.276332)
		(width 0.10795)
		(layer "B.Cu")
		(net "FM_CTNR_PS_ON")
	)
	(segment
		(start 340.487 -137.8966)
		(end 347.626432 -137.8966)
		(width 0.10795)
		(layer "B.Cu")
		(net "FM_CTNR_PS_ON")
	)
	(segment
		(start 339.866732 -137.276332)
		(end 340.487 -137.8966)
		(width 0.10795)
		(layer "B.Cu")
		(net "FM_CTNR_PS_ON")
	)
	(segment
		(start 415.434272 -124.477018)
		(end 416.93211 -125.974856)
		(width 0.10795)
		(layer "B.Cu")
		(net "FM_CTNR_PS_ON")
	)
	(segment
		(start 416.93211 -125.974856)
		(end 417.058602 -125.974856)
		(width 0.10795)
		(layer "B.Cu")
		(net "FM_CTNR_PS_ON")
	)
	(segment
		(start 413.766 -103.080058)
		(end 414.034986 -103.349044)
		(width 0.10795)
		(layer "B.Cu")
		(net "FM_CTNR_PS_ON")
	)
	(segment
		(start 414.4518 -102.3874)
		(end 414.02 -102.3874)
		(width 0.10795)
		(layer "B.Cu")
		(net "FM_CTNR_PS_ON")
	)
	(segment
		(start 336.110072 -137.276332)
		(end 339.866732 -137.276332)
		(width 0.10795)
		(layer "B.Cu")
		(net "FM_CTNR_PS_ON")
	)
	(segment
		(start 414.690052 -118.574312)
		(end 415.434272 -119.318532)
		(width 0.10795)
		(layer "B.Cu")
		(net "FM_CTNR_PS_ON")
	)
	(segment
		(start 416.05962 -69.29882)
		(end 416.28568 -69.07276)
		(width 0.089408)
		(layer "In2.Cu")
		(net "FM_CTNR_PS_ON")
	)
	(segment
		(start 355.12883 -136.361424)
		(end 355.12883 -138.679174)
		(width 0.089408)
		(layer "In2.Cu")
		(net "FM_CTNR_PS_ON")
	)
	(segment
		(start 360.744262 -134.600696)
		(end 360.448352 -134.600696)
		(width 0.089408)
		(layer "In2.Cu")
		(net "FM_CTNR_PS_ON")
	)
	(segment
		(start 354.278692 -139.529312)
		(end 353.21113 -139.529312)
		(width 0.089408)
		(layer "In2.Cu")
		(net "FM_CTNR_PS_ON")
	)
	(segment
		(start 414.547812 -74.24801)
		(end 414.547812 -71.980806)
		(width 0.089408)
		(layer "In2.Cu")
		(net "FM_CTNR_PS_ON")
	)
	(segment
		(start 389.696452 -158.496)
		(end 372.745 -158.496)
		(width 0.089408)
		(layer "In2.Cu")
		(net "FM_CTNR_PS_ON")
	)
	(segment
		(start 415.049208 -71.47941)
		(end 415.049208 -70.836282)
		(width 0.089408)
		(layer "In2.Cu")
		(net "FM_CTNR_PS_ON")
	)
	(segment
		(start 416.28568 -66.690494)
		(end 415.869374 -66.274188)
		(width 0.089408)
		(layer "In2.Cu")
		(net "FM_CTNR_PS_ON")
	)
	(segment
		(start 365.717582 -142.981934)
		(end 365.717582 -140.997432)
		(width 0.089408)
		(layer "In2.Cu")
		(net "FM_CTNR_PS_ON")
	)
	(segment
		(start 391.281158 -157.558232)
		(end 390.63422 -157.558232)
		(width 0.089408)
		(layer "In2.Cu")
		(net "FM_CTNR_PS_ON")
	)
	(segment
		(start 415.252408 -69.52742)
		(end 415.481008 -69.29882)
		(width 0.089408)
		(layer "In2.Cu")
		(net "FM_CTNR_PS_ON")
	)
	(segment
		(start 355.80574 -135.684514)
		(end 355.12883 -136.361424)
		(width 0.089408)
		(layer "In2.Cu")
		(net "FM_CTNR_PS_ON")
	)
	(segment
		(start 390.63422 -157.558232)
		(end 389.696452 -158.496)
		(width 0.089408)
		(layer "In2.Cu")
		(net "FM_CTNR_PS_ON")
	)
	(segment
		(start 366.481868 -143.74622)
		(end 365.717582 -142.981934)
		(width 0.089408)
		(layer "In2.Cu")
		(net "FM_CTNR_PS_ON")
	)
	(segment
		(start 360.978704 -136.258554)
		(end 360.978704 -134.835138)
		(width 0.089408)
		(layer "In2.Cu")
		(net "FM_CTNR_PS_ON")
	)
	(segment
		(start 355.12883 -138.679174)
		(end 354.278692 -139.529312)
		(width 0.089408)
		(layer "In2.Cu")
		(net "FM_CTNR_PS_ON")
	)
	(segment
		(start 367.351564 -157.639258)
		(end 365.368586 -155.65628)
		(width 0.089408)
		(layer "In2.Cu")
		(net "FM_CTNR_PS_ON")
	)
	(segment
		(start 357.309928 -133.143752)
		(end 355.80574 -134.64794)
		(width 0.089408)
		(layer "In2.Cu")
		(net "FM_CTNR_PS_ON")
	)
	(segment
		(start 412.832042 -96.881442)
		(end 412.832042 -86.268814)
		(width 0.089408)
		(layer "In2.Cu")
		(net "FM_CTNR_PS_ON")
	)
	(segment
		(start 415.049208 -80.343248)
		(end 415.049208 -74.749406)
		(width 0.089408)
		(layer "In2.Cu")
		(net "FM_CTNR_PS_ON")
	)
	(segment
		(start 365.368586 -150.692866)
		(end 366.403382 -149.65807)
		(width 0.089408)
		(layer "In2.Cu")
		(net "FM_CTNR_PS_ON")
	)
	(segment
		(start 413.8422 -97.8916)
		(end 412.832042 -96.881442)
		(width 0.089408)
		(layer "In2.Cu")
		(net "FM_CTNR_PS_ON")
	)
	(segment
		(start 414.668208 -80.724248)
		(end 415.049208 -80.343248)
		(width 0.089408)
		(layer "In2.Cu")
		(net "FM_CTNR_PS_ON")
	)
	(segment
		(start 366.403382 -149.65807)
		(end 366.403382 -148.790914)
		(width 0.089408)
		(layer "In2.Cu")
		(net "FM_CTNR_PS_ON")
	)
	(segment
		(start 414.547812 -71.980806)
		(end 415.049208 -71.47941)
		(width 0.089408)
		(layer "In2.Cu")
		(net "FM_CTNR_PS_ON")
	)
	(segment
		(start 412.832042 -86.268814)
		(end 415.252408 -83.848448)
		(width 0.089408)
		(layer "In2.Cu")
		(net "FM_CTNR_PS_ON")
	)
	(segment
		(start 360.448352 -134.600696)
		(end 358.991408 -133.143752)
		(width 0.089408)
		(layer "In2.Cu")
		(net "FM_CTNR_PS_ON")
	)
	(segment
		(start 414.668208 -82.318352)
		(end 414.668208 -80.724248)
		(width 0.089408)
		(layer "In2.Cu")
		(net "FM_CTNR_PS_ON")
	)
	(segment
		(start 368.74704 -143.74622)
		(end 366.481868 -143.74622)
		(width 0.089408)
		(layer "In2.Cu")
		(net "FM_CTNR_PS_ON")
	)
	(segment
		(start 369.217702 -144.216882)
		(end 368.74704 -143.74622)
		(width 0.089408)
		(layer "In2.Cu")
		(net "FM_CTNR_PS_ON")
	)
	(segment
		(start 355.80574 -134.64794)
		(end 355.80574 -135.684514)
		(width 0.089408)
		(layer "In2.Cu")
		(net "FM_CTNR_PS_ON")
	)
	(segment
		(start 360.978704 -134.835138)
		(end 360.744262 -134.600696)
		(width 0.089408)
		(layer "In2.Cu")
		(net "FM_CTNR_PS_ON")
	)
	(segment
		(start 415.481008 -69.29882)
		(end 416.05962 -69.29882)
		(width 0.089408)
		(layer "In2.Cu")
		(net "FM_CTNR_PS_ON")
	)
	(segment
		(start 365.717582 -140.997432)
		(end 360.978704 -136.258554)
		(width 0.089408)
		(layer "In2.Cu")
		(net "FM_CTNR_PS_ON")
	)
	(segment
		(start 366.403382 -148.790914)
		(end 369.217702 -145.976594)
		(width 0.089408)
		(layer "In2.Cu")
		(net "FM_CTNR_PS_ON")
	)
	(segment
		(start 415.252408 -70.633082)
		(end 415.252408 -69.52742)
		(width 0.089408)
		(layer "In2.Cu")
		(net "FM_CTNR_PS_ON")
	)
	(segment
		(start 372.745 -158.496)
		(end 371.888258 -157.639258)
		(width 0.089408)
		(layer "In2.Cu")
		(net "FM_CTNR_PS_ON")
	)
	(segment
		(start 415.252408 -82.902552)
		(end 414.668208 -82.318352)
		(width 0.089408)
		(layer "In2.Cu")
		(net "FM_CTNR_PS_ON")
	)
	(segment
		(start 369.217702 -145.976594)
		(end 369.217702 -144.216882)
		(width 0.089408)
		(layer "In2.Cu")
		(net "FM_CTNR_PS_ON")
	)
	(segment
		(start 365.368586 -155.65628)
		(end 365.368586 -150.692866)
		(width 0.089408)
		(layer "In2.Cu")
		(net "FM_CTNR_PS_ON")
	)
	(segment
		(start 415.252408 -83.848448)
		(end 415.252408 -82.902552)
		(width 0.089408)
		(layer "In2.Cu")
		(net "FM_CTNR_PS_ON")
	)
	(segment
		(start 371.888258 -157.639258)
		(end 367.351564 -157.639258)
		(width 0.089408)
		(layer "In2.Cu")
		(net "FM_CTNR_PS_ON")
	)
	(segment
		(start 415.049208 -70.836282)
		(end 415.252408 -70.633082)
		(width 0.089408)
		(layer "In2.Cu")
		(net "FM_CTNR_PS_ON")
	)
	(segment
		(start 415.049208 -74.749406)
		(end 414.547812 -74.24801)
		(width 0.089408)
		(layer "In2.Cu")
		(net "FM_CTNR_PS_ON")
	)
	(segment
		(start 358.991408 -133.143752)
		(end 357.309928 -133.143752)
		(width 0.089408)
		(layer "In2.Cu")
		(net "FM_CTNR_PS_ON")
	)
	(segment
		(start 416.28568 -69.07276)
		(end 416.28568 -66.690494)
		(width 0.089408)
		(layer "In2.Cu")
		(net "FM_CTNR_PS_ON")
	)
	(segment
		(start 389.034528 -68.742306)
		(end 391.248138 -66.528696)
		(width 0.089408)
		(layer "In4.Cu")
		(net "FM_CTNR_PS_ON")
	)
	(segment
		(start 378.944632 -69.068696)
		(end 379.271022 -68.742306)
		(width 0.089408)
		(layer "In4.Cu")
		(net "FM_CTNR_PS_ON")
	)
	(segment
		(start 415.38398 -66.274188)
		(end 415.869374 -66.274188)
		(width 0.089408)
		(layer "In4.Cu")
		(net "FM_CTNR_PS_ON")
	)
	(segment
		(start 407.725372 -69.510656)
		(end 408.641296 -68.594732)
		(width 0.089408)
		(layer "In4.Cu")
		(net "FM_CTNR_PS_ON")
	)
	(segment
		(start 414.245552 -68.594224)
		(end 414.333944 -68.594224)
		(width 0.089408)
		(layer "In4.Cu")
		(net "FM_CTNR_PS_ON")
	)
	(segment
		(start 406.051766 -69.168772)
		(end 406.39365 -69.510656)
		(width 0.089408)
		(layer "In4.Cu")
		(net "FM_CTNR_PS_ON")
	)
	(segment
		(start 414.245044 -68.594732)
		(end 414.245552 -68.594224)
		(width 0.089408)
		(layer "In4.Cu")
		(net "FM_CTNR_PS_ON")
	)
	(segment
		(start 415.055304 -66.602864)
		(end 415.38398 -66.274188)
		(width 0.089408)
		(layer "In4.Cu")
		(net "FM_CTNR_PS_ON")
	)
	(segment
		(start 377.544838 -68.695316)
		(end 377.918218 -69.068696)
		(width 0.089408)
		(layer "In4.Cu")
		(net "FM_CTNR_PS_ON")
	)
	(segment
		(start 397.102076 -69.168772)
		(end 406.051766 -69.168772)
		(width 0.089408)
		(layer "In4.Cu")
		(net "FM_CTNR_PS_ON")
	)
	(segment
		(start 394.462 -66.528696)
		(end 397.102076 -69.168772)
		(width 0.089408)
		(layer "In4.Cu")
		(net "FM_CTNR_PS_ON")
	)
	(segment
		(start 414.333944 -68.594224)
		(end 415.055304 -67.872864)
		(width 0.089408)
		(layer "In4.Cu")
		(net "FM_CTNR_PS_ON")
	)
	(segment
		(start 379.271022 -68.742306)
		(end 389.034528 -68.742306)
		(width 0.089408)
		(layer "In4.Cu")
		(net "FM_CTNR_PS_ON")
	)
	(segment
		(start 408.641296 -68.594732)
		(end 414.245044 -68.594732)
		(width 0.089408)
		(layer "In4.Cu")
		(net "FM_CTNR_PS_ON")
	)
	(segment
		(start 377.918218 -69.068696)
		(end 378.944632 -69.068696)
		(width 0.089408)
		(layer "In4.Cu")
		(net "FM_CTNR_PS_ON")
	)
	(segment
		(start 391.248138 -66.528696)
		(end 394.462 -66.528696)
		(width 0.089408)
		(layer "In4.Cu")
		(net "FM_CTNR_PS_ON")
	)
	(segment
		(start 415.055304 -67.872864)
		(end 415.055304 -66.602864)
		(width 0.089408)
		(layer "In4.Cu")
		(net "FM_CTNR_PS_ON")
	)
	(segment
		(start 406.39365 -69.510656)
		(end 407.725372 -69.510656)
		(width 0.089408)
		(layer "In4.Cu")
		(net "FM_CTNR_PS_ON")
	)
	(segment
		(start 13.803884 -83.96986)
		(end 12.876276 -83.96986)
		(width 0.089408)
		(layer "In9.Cu")
		(net "FM_CTNR_PS_ON")
	)
	(segment
		(start 28.603956 -127.369062)
		(end 28.625292 -127.347726)
		(width 0.089408)
		(layer "In9.Cu")
		(net "FM_CTNR_PS_ON")
	)
	(segment
		(start 24.999442 -124.08662)
		(end 28.03779 -127.124968)
		(width 0.089408)
		(layer "In9.Cu")
		(net "FM_CTNR_PS_ON")
	)
	(segment
		(start 418.765482 -130.321812)
		(end 418.237416 -129.793746)
		(width 0.089408)
		(layer "In9.Cu")
		(net "FM_CTNR_PS_ON")
	)
	(segment
		(start 12.459208 -71.1454)
		(end 12.3698 -71.234808)
		(width 0.089408)
		(layer "In9.Cu")
		(net "FM_CTNR_PS_ON")
	)
	(segment
		(start 11.632184 -87.039958)
		(end 11.632184 -89.167208)
		(width 0.089408)
		(layer "In9.Cu")
		(net "FM_CTNR_PS_ON")
	)
	(segment
		(start 418.237416 -127.612902)
		(end 417.058602 -126.434088)
		(width 0.089408)
		(layer "In9.Cu")
		(net "FM_CTNR_PS_ON")
	)
	(segment
		(start 426.753782 -136.014206)
		(end 426.42155 -136.346438)
		(width 0.089408)
		(layer "In9.Cu")
		(net "FM_CTNR_PS_ON")
	)
	(segment
		(start 14.370812 -83.402932)
		(end 13.803884 -83.96986)
		(width 0.089408)
		(layer "In9.Cu")
		(net "FM_CTNR_PS_ON")
	)
	(segment
		(start 10.883392 -93.534992)
		(end 11.857228 -94.508828)
		(width 0.089408)
		(layer "In9.Cu")
		(net "FM_CTNR_PS_ON")
	)
	(segment
		(start 28.625292 -127.347726)
		(end 85.511386 -127.347726)
		(width 0.089408)
		(layer "In9.Cu")
		(net "FM_CTNR_PS_ON")
	)
	(segment
		(start 188.362844 -146.671538)
		(end 192.997836 -146.671538)
		(width 0.089408)
		(layer "In9.Cu")
		(net "FM_CTNR_PS_ON")
	)
	(segment
		(start 17.613376 -106.13009)
		(end 17.613376 -109.706156)
		(width 0.089408)
		(layer "In9.Cu")
		(net "FM_CTNR_PS_ON")
	)
	(segment
		(start 321.761612 -146.893788)
		(end 323.146928 -148.279104)
		(width 0.089408)
		(layer "In9.Cu")
		(net "FM_CTNR_PS_ON")
	)
	(segment
		(start 260.210808 -145.680938)
		(end 261.955026 -145.680938)
		(width 0.089408)
		(layer "In9.Cu")
		(net "FM_CTNR_PS_ON")
	)
	(segment
		(start 159.4358 -140.737844)
		(end 161.083244 -142.385288)
		(width 0.089408)
		(layer "In9.Cu")
		(net "FM_CTNR_PS_ON")
	)
	(segment
		(start 404.114508 -158.598108)
		(end 429.951388 -158.598108)
		(width 0.089408)
		(layer "In9.Cu")
		(net "FM_CTNR_PS_ON")
	)
	(segment
		(start 12.876276 -83.96986)
		(end 11.899392 -84.946744)
		(width 0.089408)
		(layer "In9.Cu")
		(net "FM_CTNR_PS_ON")
	)
	(segment
		(start 11.857228 -94.508828)
		(end 11.857228 -102.466394)
		(width 0.089408)
		(layer "In9.Cu")
		(net "FM_CTNR_PS_ON")
	)
	(segment
		(start 14.370812 -82.230468)
		(end 14.370812 -83.402932)
		(width 0.089408)
		(layer "In9.Cu")
		(net "FM_CTNR_PS_ON")
	)
	(segment
		(start 432.127914 -152.976072)
		(end 432.127914 -150.554182)
		(width 0.089408)
		(layer "In9.Cu")
		(net "FM_CTNR_PS_ON")
	)
	(segment
		(start 28.03779 -127.13462)
		(end 28.272232 -127.369062)
		(width 0.089408)
		(layer "In9.Cu")
		(net "FM_CTNR_PS_ON")
	)
	(segment
		(start 11.875008 -79.734664)
		(end 14.370812 -82.230468)
		(width 0.089408)
		(layer "In9.Cu")
		(net "FM_CTNR_PS_ON")
	)
	(segment
		(start 429.212502 -137.710418)
		(end 427.712124 -137.710418)
		(width 0.089408)
		(layer "In9.Cu")
		(net "FM_CTNR_PS_ON")
	)
	(segment
		(start 18.835878 -69.396102)
		(end 15.72387 -69.396102)
		(width 0.089408)
		(layer "In9.Cu")
		(net "FM_CTNR_PS_ON")
	)
	(segment
		(start 157.19552 -128.66624)
		(end 159.4358 -130.90652)
		(width 0.089408)
		(layer "In9.Cu")
		(net "FM_CTNR_PS_ON")
	)
	(segment
		(start 166.956994 -142.989808)
		(end 184.681114 -142.989808)
		(width 0.089408)
		(layer "In9.Cu")
		(net "FM_CTNR_PS_ON")
	)
	(segment
		(start 11.875008 -71.734426)
		(end 11.875008 -79.734664)
		(width 0.089408)
		(layer "In9.Cu")
		(net "FM_CTNR_PS_ON")
	)
	(segment
		(start 28.272232 -127.369062)
		(end 28.603956 -127.369062)
		(width 0.089408)
		(layer "In9.Cu")
		(net "FM_CTNR_PS_ON")
	)
	(segment
		(start 14.181074 -104.79024)
		(end 16.273526 -104.79024)
		(width 0.089408)
		(layer "In9.Cu")
		(net "FM_CTNR_PS_ON")
	)
	(segment
		(start 11.857228 -102.466394)
		(end 14.181074 -104.79024)
		(width 0.089408)
		(layer "In9.Cu")
		(net "FM_CTNR_PS_ON")
	)
	(segment
		(start 151.672036 -128.66624)
		(end 157.19552 -128.66624)
		(width 0.089408)
		(layer "In9.Cu")
		(net "FM_CTNR_PS_ON")
	)
	(segment
		(start 425.03852 -136.346438)
		(end 419.013894 -130.321812)
		(width 0.089408)
		(layer "In9.Cu")
		(net "FM_CTNR_PS_ON")
	)
	(segment
		(start 161.083244 -142.385288)
		(end 166.352474 -142.385288)
		(width 0.089408)
		(layer "In9.Cu")
		(net "FM_CTNR_PS_ON")
	)
	(segment
		(start 431.552858 -139.808458)
		(end 431.310542 -139.808458)
		(width 0.089408)
		(layer "In9.Cu")
		(net "FM_CTNR_PS_ON")
	)
	(segment
		(start 432.127914 -150.554182)
		(end 436.312056 -146.37004)
		(width 0.089408)
		(layer "In9.Cu")
		(net "FM_CTNR_PS_ON")
	)
	(segment
		(start 23.071074 -51.259994)
		(end 20.19427 -54.136798)
		(width 0.089408)
		(layer "In9.Cu")
		(net "FM_CTNR_PS_ON")
	)
	(segment
		(start 431.310542 -139.808458)
		(end 429.212502 -137.710418)
		(width 0.089408)
		(layer "In9.Cu")
		(net "FM_CTNR_PS_ON")
	)
	(segment
		(start 263.167876 -146.893788)
		(end 321.761612 -146.893788)
		(width 0.089408)
		(layer "In9.Cu")
		(net "FM_CTNR_PS_ON")
	)
	(segment
		(start 28.03779 -127.124968)
		(end 28.03779 -127.13462)
		(width 0.089408)
		(layer "In9.Cu")
		(net "FM_CTNR_PS_ON")
	)
	(segment
		(start 431.553112 -139.808204)
		(end 431.552858 -139.808458)
		(width 0.089408)
		(layer "In9.Cu")
		(net "FM_CTNR_PS_ON")
	)
	(segment
		(start 436.312056 -146.37004)
		(end 436.312056 -142.46352)
		(width 0.089408)
		(layer "In9.Cu")
		(net "FM_CTNR_PS_ON")
	)
	(segment
		(start 192.997836 -146.671538)
		(end 193.292476 -146.966178)
		(width 0.089408)
		(layer "In9.Cu")
		(net "FM_CTNR_PS_ON")
	)
	(segment
		(start 323.146928 -148.279104)
		(end 323.558662 -148.279104)
		(width 0.089408)
		(layer "In9.Cu")
		(net "FM_CTNR_PS_ON")
	)
	(segment
		(start 11.632184 -89.167208)
		(end 10.883392 -89.916)
		(width 0.089408)
		(layer "In9.Cu")
		(net "FM_CTNR_PS_ON")
	)
	(segment
		(start 417.058602 -126.434088)
		(end 417.058602 -125.974856)
		(width 0.089408)
		(layer "In9.Cu")
		(net "FM_CTNR_PS_ON")
	)
	(segment
		(start 20.19427 -54.136798)
		(end 20.19427 -68.03771)
		(width 0.089408)
		(layer "In9.Cu")
		(net "FM_CTNR_PS_ON")
	)
	(segment
		(start 13.974572 -71.1454)
		(end 12.459208 -71.1454)
		(width 0.089408)
		(layer "In9.Cu")
		(net "FM_CTNR_PS_ON")
	)
	(segment
		(start 85.511386 -127.347726)
		(end 88.64473 -124.214382)
		(width 0.089408)
		(layer "In9.Cu")
		(net "FM_CTNR_PS_ON")
	)
	(segment
		(start 88.64473 -124.214382)
		(end 147.220178 -124.214382)
		(width 0.089408)
		(layer "In9.Cu")
		(net "FM_CTNR_PS_ON")
	)
	(segment
		(start 10.883392 -89.916)
		(end 10.883392 -93.534992)
		(width 0.089408)
		(layer "In9.Cu")
		(net "FM_CTNR_PS_ON")
	)
	(segment
		(start 433.65674 -139.808204)
		(end 431.553112 -139.808204)
		(width 0.089408)
		(layer "In9.Cu")
		(net "FM_CTNR_PS_ON")
	)
	(segment
		(start 429.951388 -158.598108)
		(end 431.572924 -156.976572)
		(width 0.089408)
		(layer "In9.Cu")
		(net "FM_CTNR_PS_ON")
	)
	(segment
		(start 20.19427 -68.03771)
		(end 18.835878 -69.396102)
		(width 0.089408)
		(layer "In9.Cu")
		(net "FM_CTNR_PS_ON")
	)
	(segment
		(start 21.854414 -122.029982)
		(end 23.911052 -124.08662)
		(width 0.089408)
		(layer "In9.Cu")
		(net "FM_CTNR_PS_ON")
	)
	(segment
		(start 16.273526 -104.79024)
		(end 17.613376 -106.13009)
		(width 0.089408)
		(layer "In9.Cu")
		(net "FM_CTNR_PS_ON")
	)
	(segment
		(start 426.753782 -136.752076)
		(end 426.753782 -136.014206)
		(width 0.089408)
		(layer "In9.Cu")
		(net "FM_CTNR_PS_ON")
	)
	(segment
		(start 258.925568 -146.966178)
		(end 260.210808 -145.680938)
		(width 0.089408)
		(layer "In9.Cu")
		(net "FM_CTNR_PS_ON")
	)
	(segment
		(start 193.292476 -146.966178)
		(end 258.925568 -146.966178)
		(width 0.089408)
		(layer "In9.Cu")
		(net "FM_CTNR_PS_ON")
	)
	(segment
		(start 419.013894 -130.321812)
		(end 418.765482 -130.321812)
		(width 0.089408)
		(layer "In9.Cu")
		(net "FM_CTNR_PS_ON")
	)
	(segment
		(start 426.42155 -136.346438)
		(end 425.03852 -136.346438)
		(width 0.089408)
		(layer "In9.Cu")
		(net "FM_CTNR_PS_ON")
	)
	(segment
		(start 325.12 -146.717766)
		(end 325.12 -143.891)
		(width 0.089408)
		(layer "In9.Cu")
		(net "FM_CTNR_PS_ON")
	)
	(segment
		(start 427.712124 -137.710418)
		(end 426.753782 -136.752076)
		(width 0.089408)
		(layer "In9.Cu")
		(net "FM_CTNR_PS_ON")
	)
	(segment
		(start 159.4358 -130.90652)
		(end 159.4358 -140.737844)
		(width 0.089408)
		(layer "In9.Cu")
		(net "FM_CTNR_PS_ON")
	)
	(segment
		(start 21.854414 -113.947194)
		(end 21.854414 -122.029982)
		(width 0.089408)
		(layer "In9.Cu")
		(net "FM_CTNR_PS_ON")
	)
	(segment
		(start 403.0218 -157.5054)
		(end 404.114508 -158.598108)
		(width 0.089408)
		(layer "In9.Cu")
		(net "FM_CTNR_PS_ON")
	)
	(segment
		(start 23.071074 -46.985428)
		(end 23.071074 -51.259994)
		(width 0.089408)
		(layer "In9.Cu")
		(net "FM_CTNR_PS_ON")
	)
	(segment
		(start 327.7108 -143.0782)
		(end 327.8886 -143.0782)
		(width 0.089408)
		(layer "In9.Cu")
		(net "FM_CTNR_PS_ON")
	)
	(segment
		(start 436.312056 -142.46352)
		(end 433.65674 -139.808204)
		(width 0.089408)
		(layer "In9.Cu")
		(net "FM_CTNR_PS_ON")
	)
	(segment
		(start 12.3698 -71.239634)
		(end 11.875008 -71.734426)
		(width 0.089408)
		(layer "In9.Cu")
		(net "FM_CTNR_PS_ON")
	)
	(segment
		(start 418.237416 -129.793746)
		(end 418.237416 -127.612902)
		(width 0.089408)
		(layer "In9.Cu")
		(net "FM_CTNR_PS_ON")
	)
	(segment
		(start 12.3698 -71.234808)
		(end 12.3698 -71.239634)
		(width 0.089408)
		(layer "In9.Cu")
		(net "FM_CTNR_PS_ON")
	)
	(segment
		(start 147.220178 -124.214382)
		(end 151.672036 -128.66624)
		(width 0.089408)
		(layer "In9.Cu")
		(net "FM_CTNR_PS_ON")
	)
	(segment
		(start 325.722234 -143.288766)
		(end 327.500234 -143.288766)
		(width 0.089408)
		(layer "In9.Cu")
		(net "FM_CTNR_PS_ON")
	)
	(segment
		(start 11.899392 -84.946744)
		(end 11.899392 -86.77275)
		(width 0.089408)
		(layer "In9.Cu")
		(net "FM_CTNR_PS_ON")
	)
	(segment
		(start 327.500234 -143.288766)
		(end 327.7108 -143.0782)
		(width 0.089408)
		(layer "In9.Cu")
		(net "FM_CTNR_PS_ON")
	)
	(segment
		(start 166.352474 -142.385288)
		(end 166.956994 -142.989808)
		(width 0.089408)
		(layer "In9.Cu")
		(net "FM_CTNR_PS_ON")
	)
	(segment
		(start 17.613376 -109.706156)
		(end 21.854414 -113.947194)
		(width 0.089408)
		(layer "In9.Cu")
		(net "FM_CTNR_PS_ON")
	)
	(segment
		(start 184.681114 -142.989808)
		(end 188.362844 -146.671538)
		(width 0.089408)
		(layer "In9.Cu")
		(net "FM_CTNR_PS_ON")
	)
	(segment
		(start 15.72387 -69.396102)
		(end 13.974572 -71.1454)
		(width 0.089408)
		(layer "In9.Cu")
		(net "FM_CTNR_PS_ON")
	)
	(segment
		(start 23.911052 -124.08662)
		(end 24.999442 -124.08662)
		(width 0.089408)
		(layer "In9.Cu")
		(net "FM_CTNR_PS_ON")
	)
	(segment
		(start 323.558662 -148.279104)
		(end 325.12 -146.717766)
		(width 0.089408)
		(layer "In9.Cu")
		(net "FM_CTNR_PS_ON")
	)
	(segment
		(start 325.12 -143.891)
		(end 325.722234 -143.288766)
		(width 0.089408)
		(layer "In9.Cu")
		(net "FM_CTNR_PS_ON")
	)
	(segment
		(start 261.955026 -145.680938)
		(end 263.167876 -146.893788)
		(width 0.089408)
		(layer "In9.Cu")
		(net "FM_CTNR_PS_ON")
	)
	(segment
		(start 11.899392 -86.77275)
		(end 11.632184 -87.039958)
		(width 0.089408)
		(layer "In9.Cu")
		(net "FM_CTNR_PS_ON")
	)
	(segment
		(start 391.281158 -157.558232)
		(end 391.34161 -157.618684)
		(width 0.089408)
		(layer "In11.Cu")
		(net "FM_CTNR_PS_ON")
	)
	(segment
		(start 393.940792 -156.6672)
		(end 400.8628 -156.6672)
		(width 0.089408)
		(layer "In11.Cu")
		(net "FM_CTNR_PS_ON")
	)
	(segment
		(start 401.701 -157.5054)
		(end 403.0218 -157.5054)
		(width 0.089408)
		(layer "In11.Cu")
		(net "FM_CTNR_PS_ON")
	)
	(segment
		(start 400.8628 -156.6672)
		(end 401.701 -157.5054)
		(width 0.089408)
		(layer "In11.Cu")
		(net "FM_CTNR_PS_ON")
	)
	(segment
		(start 392.989308 -157.618684)
		(end 393.940792 -156.6672)
		(width 0.089408)
		(layer "In11.Cu")
		(net "FM_CTNR_PS_ON")
	)
	(segment
		(start 391.34161 -157.618684)
		(end 392.989308 -157.618684)
		(width 0.089408)
		(layer "In11.Cu")
		(net "FM_CTNR_PS_ON")
	)
	(segment
		(start 19.9898 -117.5004)
		(end 19.9898 -116.8908)
		(width 0.10795)
		(layer "F.Cu")
		(net "FAN_TACH2_CPU1_D2")
	)
	(segment
		(start 19.52371 -119.62765)
		(end 19.52371 -118.975886)
		(width 0.10795)
		(layer "F.Cu")
		(net "FAN_TACH2_CPU1_D2")
	)
	(segment
		(start 19.8374 -117.6528)
		(end 19.9898 -117.5004)
		(width 0.10795)
		(layer "F.Cu")
		(net "FAN_TACH2_CPU1_D2")
	)
	(segment
		(start 19.8374 -118.239794)
		(end 19.8374 -117.6528)
		(width 0.10795)
		(layer "F.Cu")
		(net "FAN_TACH2_CPU1_D2")
	)
	(segment
		(start 19.52371 -118.975886)
		(end 19.8374 -118.662196)
		(width 0.10795)
		(layer "F.Cu")
		(net "FAN_TACH2_CPU1_D2")
	)
	(segment
		(start 19.8374 -118.662196)
		(end 19.8374 -118.239794)
		(width 0.10795)
		(layer "F.Cu")
		(net "FAN_TACH2_CPU1_D2")
	)
	(via
		(at 19.9898 -116.8908)
		(size 0.762)
		(drill 0.381)
		(layers "F.Cu" "B.Cu")
		(net "FAN_TACH2_CPU1_D2")
	)
	(segment
		(start 1.739646 -118.592346)
		(end 1.739646 -121.04116)
		(width 0.10795)
		(layer "F.Cu")
		(net "FAN_TACH2_CPU1_D1")
	)
	(segment
		(start 3.4036 -123.9393)
		(end 3.8608 -123.9393)
		(width 0.10795)
		(layer "F.Cu")
		(net "FAN_TACH2_CPU1_D1")
	)
	(segment
		(start -1.139952 -110.259876)
		(end -0.598932 -110.800896)
		(width 0.10795)
		(layer "F.Cu")
		(net "FAN_TACH2_CPU1_D1")
	)
	(segment
		(start 18.903188 -122.639836)
		(end 20.694904 -120.84812)
		(width 0.10795)
		(layer "F.Cu")
		(net "FAN_TACH2_CPU1_D1")
	)
	(segment
		(start 21.80971 -120.000776)
		(end 21.80971 -119.62765)
		(width 0.10795)
		(layer "F.Cu")
		(net "FAN_TACH2_CPU1_D1")
	)
	(segment
		(start 20.962366 -120.84812)
		(end 21.80971 -120.000776)
		(width 0.10795)
		(layer "F.Cu")
		(net "FAN_TACH2_CPU1_D1")
	)
	(segment
		(start 4.6355 -123.9393)
		(end 6.876796 -121.698004)
		(width 0.10795)
		(layer "F.Cu")
		(net "FAN_TACH2_CPU1_D1")
	)
	(segment
		(start 3.8608 -123.9393)
		(end 4.6355 -123.9393)
		(width 0.10795)
		(layer "F.Cu")
		(net "FAN_TACH2_CPU1_D1")
	)
	(segment
		(start -0.598932 -110.800896)
		(end -0.598932 -115.546124)
		(width 0.10795)
		(layer "F.Cu")
		(net "FAN_TACH2_CPU1_D1")
	)
	(segment
		(start 1.739646 -121.04116)
		(end 2.605786 -121.9073)
		(width 0.10795)
		(layer "F.Cu")
		(net "FAN_TACH2_CPU1_D1")
	)
	(segment
		(start 2.605786 -121.9073)
		(end 2.605786 -123.141486)
		(width 0.10795)
		(layer "F.Cu")
		(net "FAN_TACH2_CPU1_D1")
	)
	(segment
		(start 6.876796 -121.698004)
		(end 12.847574 -121.698004)
		(width 0.10795)
		(layer "F.Cu")
		(net "FAN_TACH2_CPU1_D1")
	)
	(segment
		(start 13.789406 -122.639836)
		(end 18.903188 -122.639836)
		(width 0.10795)
		(layer "F.Cu")
		(net "FAN_TACH2_CPU1_D1")
	)
	(segment
		(start 2.605786 -123.141486)
		(end 3.4036 -123.9393)
		(width 0.10795)
		(layer "F.Cu")
		(net "FAN_TACH2_CPU1_D1")
	)
	(segment
		(start 12.847574 -121.698004)
		(end 13.789406 -122.639836)
		(width 0.10795)
		(layer "F.Cu")
		(net "FAN_TACH2_CPU1_D1")
	)
	(segment
		(start 0.199898 -116.344954)
		(end 0.199898 -117.052598)
		(width 0.10795)
		(layer "F.Cu")
		(net "FAN_TACH2_CPU1_D1")
	)
	(segment
		(start 20.694904 -120.84812)
		(end 20.962366 -120.84812)
		(width 0.10795)
		(layer "F.Cu")
		(net "FAN_TACH2_CPU1_D1")
	)
	(segment
		(start -0.598932 -115.546124)
		(end 0.199898 -116.344954)
		(width 0.10795)
		(layer "F.Cu")
		(net "FAN_TACH2_CPU1_D1")
	)
	(segment
		(start 0.199898 -117.052598)
		(end 1.739646 -118.592346)
		(width 0.10795)
		(layer "F.Cu")
		(net "FAN_TACH2_CPU1_D1")
	)
	(via
		(at 3.8608 -123.9393)
		(size 0.762)
		(drill 0.381)
		(layers "F.Cu" "B.Cu")
		(net "FAN_TACH2_CPU1_D1")
	)
	(segment
		(start 24.99614 -30.099)
		(end 25.12314 -29.972)
		(width 0.10795)
		(layer "F.Cu")
		(net "FAN_TACH0_CPU0_D2")
	)
	(segment
		(start 24.257 -30.099)
		(end 24.99614 -30.099)
		(width 0.10795)
		(layer "F.Cu")
		(net "FAN_TACH0_CPU0_D2")
	)
	(segment
		(start 25.12314 -29.972)
		(end 25.654 -29.972)
		(width 0.10795)
		(layer "F.Cu")
		(net "FAN_TACH0_CPU0_D2")
	)
	(segment
		(start 24.257 -35.826954)
		(end 25.39492 -36.964874)
		(width 0.10795)
		(layer "F.Cu")
		(net "FAN_TACH0_CPU0_D1")
	)
	(segment
		(start 24.257 -32.385)
		(end 24.257 -35.826954)
		(width 0.10795)
		(layer "F.Cu")
		(net "FAN_TACH0_CPU0_D1")
	)
	(via
		(at 24.327358 -32.866584)
		(size 0.6604)
		(drill 0.3302)
		(layers "F.Cu" "B.Cu")
		(net "FAN_TACH0_CPU0_D1")
	)
	(segment
		(start 25.39492 -36.155376)
		(end 25.39492 -36.964874)
		(width 0.10795)
		(layer "B.Cu")
		(net "FAN_TACH0_CPU0_D1")
	)
	(segment
		(start 24.327358 -35.087814)
		(end 25.39492 -36.155376)
		(width 0.10795)
		(layer "B.Cu")
		(net "FAN_TACH0_CPU0_D1")
	)
	(segment
		(start 24.327358 -32.866584)
		(end 24.327358 -35.087814)
		(width 0.10795)
		(layer "B.Cu")
		(net "FAN_TACH0_CPU0_D1")
	)
	(segment
		(start 18.19656 -121.43232)
		(end 19.00428 -121.43232)
		(width 0.10795)
		(layer "F.Cu")
		(net "FAN_PWM_OUT_SYS1_R")
	)
	(segment
		(start 334.615536 -21.467064)
		(end 334.5942 -21.4884)
		(width 0.10795)
		(layer "F.Cu")
		(net "FAN_PWM_OUT_SYS1_R")
	)
	(segment
		(start 18.0467 -121.58218)
		(end 18.19656 -121.43232)
		(width 0.10795)
		(layer "F.Cu")
		(net "FAN_PWM_OUT_SYS1_R")
	)
	(segment
		(start 334.615536 -20.801584)
		(end 334.615536 -21.467064)
		(width 0.10795)
		(layer "F.Cu")
		(net "FAN_PWM_OUT_SYS1_R")
	)
	(via
		(at 334.5942 -21.4884)
		(size 0.508)
		(drill 0.254)
		(layers "F.Cu" "B.Cu")
		(net "FAN_PWM_OUT_SYS1_R")
	)
	(via
		(at 402.336 4.0894)
		(size 0.508)
		(drill 0.254)
		(layers "F.Cu" "B.Cu")
		(net "FAN_PWM_OUT_SYS1_R")
	)
	(via
		(at 18.0467 -121.58218)
		(size 0.508)
		(drill 0.254)
		(layers "F.Cu" "B.Cu")
		(net "FAN_PWM_OUT_SYS1_R")
	)
	(segment
		(start 402.5138 3.3782)
		(end 402.336 3.556)
		(width 0.10795)
		(layer "B.Cu")
		(net "FAN_PWM_OUT_SYS1_R")
	)
	(segment
		(start 402.9964 3.3782)
		(end 402.5138 3.3782)
		(width 0.10795)
		(layer "B.Cu")
		(net "FAN_PWM_OUT_SYS1_R")
	)
	(segment
		(start 402.336 3.556)
		(end 402.336 4.0894)
		(width 0.10795)
		(layer "B.Cu")
		(net "FAN_PWM_OUT_SYS1_R")
	)
	(segment
		(start 352.470974 -23.06066)
		(end 352.470974 -21.128482)
		(width 0.089408)
		(layer "In2.Cu")
		(net "FAN_PWM_OUT_SYS1_R")
	)
	(segment
		(start 356.86238 -12.3698)
		(end 356.86238 -19.210274)
		(width 0.089408)
		(layer "In2.Cu")
		(net "FAN_PWM_OUT_SYS1_R")
	)
	(segment
		(start 340.5632 -20.0914)
		(end 338.9884 -21.6662)
		(width 0.089408)
		(layer "In2.Cu")
		(net "FAN_PWM_OUT_SYS1_R")
	)
	(segment
		(start 381.577088 0.018288)
		(end 376.370088 0.018288)
		(width 0.089408)
		(layer "In2.Cu")
		(net "FAN_PWM_OUT_SYS1_R")
	)
	(segment
		(start 376.370088 0.018288)
		(end 375.783856 -0.567944)
		(width 0.089408)
		(layer "In2.Cu")
		(net "FAN_PWM_OUT_SYS1_R")
	)
	(segment
		(start 375.771918 -1.96596)
		(end 375.771918 -2.041652)
		(width 0.089408)
		(layer "In2.Cu")
		(net "FAN_PWM_OUT_SYS1_R")
	)
	(segment
		(start 382.27508 0.71628)
		(end 381.577088 0.018288)
		(width 0.089408)
		(layer "In2.Cu")
		(net "FAN_PWM_OUT_SYS1_R")
	)
	(segment
		(start 375.7676 -2.131822)
		(end 373.205756 -4.693666)
		(width 0.089408)
		(layer "In2.Cu")
		(net "FAN_PWM_OUT_SYS1_R")
	)
	(segment
		(start 398.0815 0.71628)
		(end 382.27508 0.71628)
		(width 0.089408)
		(layer "In2.Cu")
		(net "FAN_PWM_OUT_SYS1_R")
	)
	(segment
		(start 398.942052 1.576832)
		(end 398.0815 0.71628)
		(width 0.089408)
		(layer "In2.Cu")
		(net "FAN_PWM_OUT_SYS1_R")
	)
	(segment
		(start 345.059 -20.0914)
		(end 340.5632 -20.0914)
		(width 0.089408)
		(layer "In2.Cu")
		(net "FAN_PWM_OUT_SYS1_R")
	)
	(segment
		(start 338.9884 -21.6662)
		(end 335.9404 -21.6662)
		(width 0.089408)
		(layer "In2.Cu")
		(net "FAN_PWM_OUT_SYS1_R")
	)
	(segment
		(start 355.708458 -23.325836)
		(end 355.476556 -23.557738)
		(width 0.089408)
		(layer "In2.Cu")
		(net "FAN_PWM_OUT_SYS1_R")
	)
	(segment
		(start 359.080054 -7.022338)
		(end 356.52456 -9.577832)
		(width 0.089408)
		(layer "In2.Cu")
		(net "FAN_PWM_OUT_SYS1_R")
	)
	(segment
		(start 356.86238 -19.210274)
		(end 355.708458 -20.364196)
		(width 0.089408)
		(layer "In2.Cu")
		(net "FAN_PWM_OUT_SYS1_R")
	)
	(segment
		(start 369.034314 -7.022338)
		(end 359.080054 -7.022338)
		(width 0.089408)
		(layer "In2.Cu")
		(net "FAN_PWM_OUT_SYS1_R")
	)
	(segment
		(start 335.9404 -21.6662)
		(end 335.527904 -21.253704)
		(width 0.089408)
		(layer "In2.Cu")
		(net "FAN_PWM_OUT_SYS1_R")
	)
	(segment
		(start 375.783856 -1.954022)
		(end 375.771918 -1.96596)
		(width 0.089408)
		(layer "In2.Cu")
		(net "FAN_PWM_OUT_SYS1_R")
	)
	(segment
		(start 334.828896 -21.253704)
		(end 334.5942 -21.4884)
		(width 0.089408)
		(layer "In2.Cu")
		(net "FAN_PWM_OUT_SYS1_R")
	)
	(segment
		(start 356.52456 -9.577832)
		(end 356.52456 -12.03198)
		(width 0.089408)
		(layer "In2.Cu")
		(net "FAN_PWM_OUT_SYS1_R")
	)
	(segment
		(start 335.527904 -21.253704)
		(end 334.828896 -21.253704)
		(width 0.089408)
		(layer "In2.Cu")
		(net "FAN_PWM_OUT_SYS1_R")
	)
	(segment
		(start 355.708458 -20.364196)
		(end 355.708458 -23.325836)
		(width 0.089408)
		(layer "In2.Cu")
		(net "FAN_PWM_OUT_SYS1_R")
	)
	(segment
		(start 399.823432 1.576832)
		(end 398.942052 1.576832)
		(width 0.089408)
		(layer "In2.Cu")
		(net "FAN_PWM_OUT_SYS1_R")
	)
	(segment
		(start 352.470974 -21.128482)
		(end 352.116136 -20.773644)
		(width 0.089408)
		(layer "In2.Cu")
		(net "FAN_PWM_OUT_SYS1_R")
	)
	(segment
		(start 375.7676 -2.04597)
		(end 375.7676 -2.131822)
		(width 0.089408)
		(layer "In2.Cu")
		(net "FAN_PWM_OUT_SYS1_R")
	)
	(segment
		(start 375.771918 -2.041652)
		(end 375.7676 -2.04597)
		(width 0.089408)
		(layer "In2.Cu")
		(net "FAN_PWM_OUT_SYS1_R")
	)
	(segment
		(start 375.783856 -0.567944)
		(end 375.783856 -1.954022)
		(width 0.089408)
		(layer "In2.Cu")
		(net "FAN_PWM_OUT_SYS1_R")
	)
	(segment
		(start 352.116136 -20.773644)
		(end 349.029274 -20.773644)
		(width 0.089408)
		(layer "In2.Cu")
		(net "FAN_PWM_OUT_SYS1_R")
	)
	(segment
		(start 355.476556 -23.557738)
		(end 352.968052 -23.557738)
		(width 0.089408)
		(layer "In2.Cu")
		(net "FAN_PWM_OUT_SYS1_R")
	)
	(segment
		(start 346.456 -21.4884)
		(end 345.059 -20.0914)
		(width 0.089408)
		(layer "In2.Cu")
		(net "FAN_PWM_OUT_SYS1_R")
	)
	(segment
		(start 402.336 4.0894)
		(end 399.823432 1.576832)
		(width 0.089408)
		(layer "In2.Cu")
		(net "FAN_PWM_OUT_SYS1_R")
	)
	(segment
		(start 349.029274 -20.773644)
		(end 348.314518 -21.4884)
		(width 0.089408)
		(layer "In2.Cu")
		(net "FAN_PWM_OUT_SYS1_R")
	)
	(segment
		(start 356.52456 -12.03198)
		(end 356.86238 -12.3698)
		(width 0.089408)
		(layer "In2.Cu")
		(net "FAN_PWM_OUT_SYS1_R")
	)
	(segment
		(start 348.314518 -21.4884)
		(end 346.456 -21.4884)
		(width 0.089408)
		(layer "In2.Cu")
		(net "FAN_PWM_OUT_SYS1_R")
	)
	(segment
		(start 352.968052 -23.557738)
		(end 352.470974 -23.06066)
		(width 0.089408)
		(layer "In2.Cu")
		(net "FAN_PWM_OUT_SYS1_R")
	)
	(segment
		(start 373.205756 -4.693666)
		(end 371.362986 -4.693666)
		(width 0.089408)
		(layer "In2.Cu")
		(net "FAN_PWM_OUT_SYS1_R")
	)
	(segment
		(start 371.362986 -4.693666)
		(end 369.034314 -7.022338)
		(width 0.089408)
		(layer "In2.Cu")
		(net "FAN_PWM_OUT_SYS1_R")
	)
	(segment
		(start 19.929348 -38.3159)
		(end 19.119088 -37.50564)
		(width 0.089408)
		(layer "In4.Cu")
		(net "FAN_PWM_OUT_SYS1_R")
	)
	(segment
		(start -0.104902 -116.366798)
		(end 0.688848 -116.366798)
		(width 0.089408)
		(layer "In4.Cu")
		(net "FAN_PWM_OUT_SYS1_R")
	)
	(segment
		(start 183.33847 -1.706626)
		(end 183.33847 -0.84963)
		(width 0.089408)
		(layer "In4.Cu")
		(net "FAN_PWM_OUT_SYS1_R")
	)
	(segment
		(start 2.943606 -114.11204)
		(end 16.287242 -114.11204)
		(width 0.089408)
		(layer "In4.Cu")
		(net "FAN_PWM_OUT_SYS1_R")
	)
	(segment
		(start -1.220724 -115.250976)
		(end -0.104902 -116.366798)
		(width 0.089408)
		(layer "In4.Cu")
		(net "FAN_PWM_OUT_SYS1_R")
	)
	(segment
		(start 13.081 -80.30464)
		(end 13.081 -79.8068)
		(width 0.089408)
		(layer "In4.Cu")
		(net "FAN_PWM_OUT_SYS1_R")
	)
	(segment
		(start 20.453604 -49.104804)
		(end 20.453604 -38.647878)
		(width 0.089408)
		(layer "In4.Cu")
		(net "FAN_PWM_OUT_SYS1_R")
	)
	(segment
		(start 13.7922 -79.0956)
		(end 14.358366 -79.0956)
		(width 0.089408)
		(layer "In4.Cu")
		(net "FAN_PWM_OUT_SYS1_R")
	)
	(segment
		(start 13.6652 -92.88526)
		(end 14.700504 -91.849956)
		(width 0.089408)
		(layer "In4.Cu")
		(net "FAN_PWM_OUT_SYS1_R")
	)
	(segment
		(start -3.679952 -110.51413)
		(end -1.220724 -112.973358)
		(width 0.089408)
		(layer "In4.Cu")
		(net "FAN_PWM_OUT_SYS1_R")
	)
	(segment
		(start 21.8948 -100.5078)
		(end 21.11502 -99.72802)
		(width 0.089408)
		(layer "In4.Cu")
		(net "FAN_PWM_OUT_SYS1_R")
	)
	(segment
		(start 21.11502 -99.72802)
		(end 21.11502 -95.22968)
		(width 0.089408)
		(layer "In4.Cu")
		(net "FAN_PWM_OUT_SYS1_R")
	)
	(segment
		(start 17.644618 -94.724982)
		(end 16.3068 -96.0628)
		(width 0.089408)
		(layer "In4.Cu")
		(net "FAN_PWM_OUT_SYS1_R")
	)
	(segment
		(start 168.190926 -3.232912)
		(end 172.041312 -3.232912)
		(width 0.089408)
		(layer "In4.Cu")
		(net "FAN_PWM_OUT_SYS1_R")
	)
	(segment
		(start 172.041312 -3.232912)
		(end 172.56252 -3.75412)
		(width 0.089408)
		(layer "In4.Cu")
		(net "FAN_PWM_OUT_SYS1_R")
	)
	(segment
		(start 165.521132 3.284474)
		(end 165.521132 0.507746)
		(width 0.089408)
		(layer "In4.Cu")
		(net "FAN_PWM_OUT_SYS1_R")
	)
	(segment
		(start 13.6652 -94.948248)
		(end 13.6652 -92.88526)
		(width 0.089408)
		(layer "In4.Cu")
		(net "FAN_PWM_OUT_SYS1_R")
	)
	(segment
		(start 330.760578 -21.337778)
		(end 332.132178 -21.337778)
		(width 0.089408)
		(layer "In4.Cu")
		(net "FAN_PWM_OUT_SYS1_R")
	)
	(segment
		(start 21.6662 -69.766434)
		(end 24.808434 -66.6242)
		(width 0.089408)
		(layer "In4.Cu")
		(net "FAN_PWM_OUT_SYS1_R")
	)
	(segment
		(start 116.321078 3.825494)
		(end 116.989352 4.493768)
		(width 0.089408)
		(layer "In4.Cu")
		(net "FAN_PWM_OUT_SYS1_R")
	)
	(segment
		(start 183.33847 -0.84963)
		(end 183.7944 -0.3937)
		(width 0.089408)
		(layer "In4.Cu")
		(net "FAN_PWM_OUT_SYS1_R")
	)
	(segment
		(start 174.825914 -3.75412)
		(end 175.174402 -3.405632)
		(width 0.089408)
		(layer "In4.Cu")
		(net "FAN_PWM_OUT_SYS1_R")
	)
	(segment
		(start 183.7944 -0.3937)
		(end 183.7944 1.27)
		(width 0.089408)
		(layer "In4.Cu")
		(net "FAN_PWM_OUT_SYS1_R")
	)
	(segment
		(start 21.8948 -108.504482)
		(end 21.8948 -100.5078)
		(width 0.089408)
		(layer "In4.Cu")
		(net "FAN_PWM_OUT_SYS1_R")
	)
	(segment
		(start 324.395846 3.027934)
		(end 324.612 2.81178)
		(width 0.089408)
		(layer "In4.Cu")
		(net "FAN_PWM_OUT_SYS1_R")
	)
	(segment
		(start 328.7268 -16.9926)
		(end 328.7268 -19.304)
		(width 0.089408)
		(layer "In4.Cu")
		(net "FAN_PWM_OUT_SYS1_R")
	)
	(segment
		(start 22.0726 -52.2732)
		(end 22.0726 -50.7238)
		(width 0.089408)
		(layer "In4.Cu")
		(net "FAN_PWM_OUT_SYS1_R")
	)
	(segment
		(start 328.7268 -19.304)
		(end 330.760578 -21.337778)
		(width 0.089408)
		(layer "In4.Cu")
		(net "FAN_PWM_OUT_SYS1_R")
	)
	(segment
		(start 175.174402 -3.405632)
		(end 181.639464 -3.405632)
		(width 0.089408)
		(layer "In4.Cu")
		(net "FAN_PWM_OUT_SYS1_R")
	)
	(segment
		(start 19.119088 -36.45916)
		(end 24.32685 -31.251398)
		(width 0.089408)
		(layer "In4.Cu")
		(net "FAN_PWM_OUT_SYS1_R")
	)
	(segment
		(start 324.612 2.81178)
		(end 324.612 0.52578)
		(width 0.089408)
		(layer "In4.Cu")
		(net "FAN_PWM_OUT_SYS1_R")
	)
	(segment
		(start 0.688848 -116.366798)
		(end 2.943606 -114.11204)
		(width 0.089408)
		(layer "In4.Cu")
		(net "FAN_PWM_OUT_SYS1_R")
	)
	(segment
		(start -1.220724 -112.973358)
		(end -1.220724 -115.250976)
		(width 0.089408)
		(layer "In4.Cu")
		(net "FAN_PWM_OUT_SYS1_R")
	)
	(segment
		(start 334.2894 -21.7932)
		(end 334.5942 -21.4884)
		(width 0.089408)
		(layer "In4.Cu")
		(net "FAN_PWM_OUT_SYS1_R")
	)
	(segment
		(start 25.5016 -66.6242)
		(end 25.8064 -66.3194)
		(width 0.089408)
		(layer "In4.Cu")
		(net "FAN_PWM_OUT_SYS1_R")
	)
	(segment
		(start 25.8064 -66.3194)
		(end 25.8064 -56.007)
		(width 0.089408)
		(layer "In4.Cu")
		(net "FAN_PWM_OUT_SYS1_R")
	)
	(segment
		(start 322.19646 4.417568)
		(end 323.586094 3.027934)
		(width 0.089408)
		(layer "In4.Cu")
		(net "FAN_PWM_OUT_SYS1_R")
	)
	(segment
		(start 27.583638 0.029718)
		(end 27.583638 3.133598)
		(width 0.089408)
		(layer "In4.Cu")
		(net "FAN_PWM_OUT_SYS1_R")
	)
	(segment
		(start 14.700504 -91.849956)
		(end 14.700504 -81.924144)
		(width 0.089408)
		(layer "In4.Cu")
		(net "FAN_PWM_OUT_SYS1_R")
	)
	(segment
		(start 21.11502 -95.22968)
		(end 20.610322 -94.724982)
		(width 0.089408)
		(layer "In4.Cu")
		(net "FAN_PWM_OUT_SYS1_R")
	)
	(segment
		(start 20.482814 -77.597)
		(end 21.964904 -76.11491)
		(width 0.089408)
		(layer "In4.Cu")
		(net "FAN_PWM_OUT_SYS1_R")
	)
	(segment
		(start 16.3068 -96.0628)
		(end 14.351 -96.0628)
		(width 0.089408)
		(layer "In4.Cu")
		(net "FAN_PWM_OUT_SYS1_R")
	)
	(segment
		(start 164.311838 4.493768)
		(end 165.521132 3.284474)
		(width 0.089408)
		(layer "In4.Cu")
		(net "FAN_PWM_OUT_SYS1_R")
	)
	(segment
		(start 24.808434 -66.6242)
		(end 25.5016 -66.6242)
		(width 0.089408)
		(layer "In4.Cu")
		(net "FAN_PWM_OUT_SYS1_R")
	)
	(segment
		(start 20.453604 -38.647878)
		(end 20.121626 -38.3159)
		(width 0.089408)
		(layer "In4.Cu")
		(net "FAN_PWM_OUT_SYS1_R")
	)
	(segment
		(start 327.66 -15.9258)
		(end 328.7268 -16.9926)
		(width 0.089408)
		(layer "In4.Cu")
		(net "FAN_PWM_OUT_SYS1_R")
	)
	(segment
		(start 324.612 0.52578)
		(end 325.259954 -0.122174)
		(width 0.089408)
		(layer "In4.Cu")
		(net "FAN_PWM_OUT_SYS1_R")
	)
	(segment
		(start 323.586094 3.027934)
		(end 324.395846 3.027934)
		(width 0.089408)
		(layer "In4.Cu")
		(net "FAN_PWM_OUT_SYS1_R")
	)
	(segment
		(start 325.259954 -0.122174)
		(end 325.259954 -14.922754)
		(width 0.089408)
		(layer "In4.Cu")
		(net "FAN_PWM_OUT_SYS1_R")
	)
	(segment
		(start 167.242744 -2.28473)
		(end 168.190926 -3.232912)
		(width 0.089408)
		(layer "In4.Cu")
		(net "FAN_PWM_OUT_SYS1_R")
	)
	(segment
		(start 19.119088 -37.50564)
		(end 19.119088 -36.45916)
		(width 0.089408)
		(layer "In4.Cu")
		(net "FAN_PWM_OUT_SYS1_R")
	)
	(segment
		(start 14.351 -96.0628)
		(end 13.96873 -95.68053)
		(width 0.089408)
		(layer "In4.Cu")
		(net "FAN_PWM_OUT_SYS1_R")
	)
	(segment
		(start 26.474166 -1.079754)
		(end 27.583638 0.029718)
		(width 0.089408)
		(layer "In4.Cu")
		(net "FAN_PWM_OUT_SYS1_R")
	)
	(segment
		(start 21.964904 -76.11491)
		(end 21.964904 -72.638666)
		(width 0.089408)
		(layer "In4.Cu")
		(net "FAN_PWM_OUT_SYS1_R")
	)
	(segment
		(start 165.521132 0.507746)
		(end 167.242744 -1.213866)
		(width 0.089408)
		(layer "In4.Cu")
		(net "FAN_PWM_OUT_SYS1_R")
	)
	(segment
		(start -3.679952 -110.259876)
		(end -3.679952 -110.51413)
		(width 0.089408)
		(layer "In4.Cu")
		(net "FAN_PWM_OUT_SYS1_R")
	)
	(segment
		(start 25.598882 -31.251398)
		(end 28.334208 -28.516072)
		(width 0.089408)
		(layer "In4.Cu")
		(net "FAN_PWM_OUT_SYS1_R")
	)
	(segment
		(start 28.334208 -28.516072)
		(end 28.334208 -25.22982)
		(width 0.089408)
		(layer "In4.Cu")
		(net "FAN_PWM_OUT_SYS1_R")
	)
	(segment
		(start 116.989352 4.493768)
		(end 164.311838 4.493768)
		(width 0.089408)
		(layer "In4.Cu")
		(net "FAN_PWM_OUT_SYS1_R")
	)
	(segment
		(start 325.259954 -14.922754)
		(end 326.263 -15.9258)
		(width 0.089408)
		(layer "In4.Cu")
		(net "FAN_PWM_OUT_SYS1_R")
	)
	(segment
		(start 20.610322 -94.724982)
		(end 17.644618 -94.724982)
		(width 0.089408)
		(layer "In4.Cu")
		(net "FAN_PWM_OUT_SYS1_R")
	)
	(segment
		(start 15.856966 -77.597)
		(end 20.482814 -77.597)
		(width 0.089408)
		(layer "In4.Cu")
		(net "FAN_PWM_OUT_SYS1_R")
	)
	(segment
		(start 28.832048 4.382008)
		(end 102.500176 4.382008)
		(width 0.089408)
		(layer "In4.Cu")
		(net "FAN_PWM_OUT_SYS1_R")
	)
	(segment
		(start 28.334208 -25.22982)
		(end 26.474166 -23.369778)
		(width 0.089408)
		(layer "In4.Cu")
		(net "FAN_PWM_OUT_SYS1_R")
	)
	(segment
		(start 27.583638 3.133598)
		(end 28.832048 4.382008)
		(width 0.089408)
		(layer "In4.Cu")
		(net "FAN_PWM_OUT_SYS1_R")
	)
	(segment
		(start 13.96873 -95.68053)
		(end 13.6652 -94.948248)
		(width 0.089408)
		(layer "In4.Cu")
		(net "FAN_PWM_OUT_SYS1_R")
	)
	(segment
		(start 102.500176 4.382008)
		(end 103.05669 3.825494)
		(width 0.089408)
		(layer "In4.Cu")
		(net "FAN_PWM_OUT_SYS1_R")
	)
	(segment
		(start 167.242744 -1.213866)
		(end 167.242744 -2.28473)
		(width 0.089408)
		(layer "In4.Cu")
		(net "FAN_PWM_OUT_SYS1_R")
	)
	(segment
		(start 20.121626 -38.3159)
		(end 19.929348 -38.3159)
		(width 0.089408)
		(layer "In4.Cu")
		(net "FAN_PWM_OUT_SYS1_R")
	)
	(segment
		(start 13.081 -79.8068)
		(end 13.7922 -79.0956)
		(width 0.089408)
		(layer "In4.Cu")
		(net "FAN_PWM_OUT_SYS1_R")
	)
	(segment
		(start 326.263 -15.9258)
		(end 327.66 -15.9258)
		(width 0.089408)
		(layer "In4.Cu")
		(net "FAN_PWM_OUT_SYS1_R")
	)
	(segment
		(start 14.358366 -79.0956)
		(end 15.856966 -77.597)
		(width 0.089408)
		(layer "In4.Cu")
		(net "FAN_PWM_OUT_SYS1_R")
	)
	(segment
		(start 14.700504 -81.924144)
		(end 13.081 -80.30464)
		(width 0.089408)
		(layer "In4.Cu")
		(net "FAN_PWM_OUT_SYS1_R")
	)
	(segment
		(start 183.7944 1.27)
		(end 186.941968 4.417568)
		(width 0.089408)
		(layer "In4.Cu")
		(net "FAN_PWM_OUT_SYS1_R")
	)
	(segment
		(start 16.287242 -114.11204)
		(end 21.8948 -108.504482)
		(width 0.089408)
		(layer "In4.Cu")
		(net "FAN_PWM_OUT_SYS1_R")
	)
	(segment
		(start 22.0726 -50.7238)
		(end 20.453604 -49.104804)
		(width 0.089408)
		(layer "In4.Cu")
		(net "FAN_PWM_OUT_SYS1_R")
	)
	(segment
		(start 24.32685 -31.251398)
		(end 25.598882 -31.251398)
		(width 0.089408)
		(layer "In4.Cu")
		(net "FAN_PWM_OUT_SYS1_R")
	)
	(segment
		(start 181.639464 -3.405632)
		(end 183.33847 -1.706626)
		(width 0.089408)
		(layer "In4.Cu")
		(net "FAN_PWM_OUT_SYS1_R")
	)
	(segment
		(start 25.8064 -56.007)
		(end 22.0726 -52.2732)
		(width 0.089408)
		(layer "In4.Cu")
		(net "FAN_PWM_OUT_SYS1_R")
	)
	(segment
		(start 26.474166 -23.369778)
		(end 26.474166 -1.079754)
		(width 0.089408)
		(layer "In4.Cu")
		(net "FAN_PWM_OUT_SYS1_R")
	)
	(segment
		(start 103.05669 3.825494)
		(end 116.321078 3.825494)
		(width 0.089408)
		(layer "In4.Cu")
		(net "FAN_PWM_OUT_SYS1_R")
	)
	(segment
		(start 172.56252 -3.75412)
		(end 174.825914 -3.75412)
		(width 0.089408)
		(layer "In4.Cu")
		(net "FAN_PWM_OUT_SYS1_R")
	)
	(segment
		(start 332.132178 -21.337778)
		(end 332.5876 -21.7932)
		(width 0.089408)
		(layer "In4.Cu")
		(net "FAN_PWM_OUT_SYS1_R")
	)
	(segment
		(start 21.6662 -72.339962)
		(end 21.6662 -69.766434)
		(width 0.089408)
		(layer "In4.Cu")
		(net "FAN_PWM_OUT_SYS1_R")
	)
	(segment
		(start 186.941968 4.417568)
		(end 322.19646 4.417568)
		(width 0.089408)
		(layer "In4.Cu")
		(net "FAN_PWM_OUT_SYS1_R")
	)
	(segment
		(start 21.964904 -72.638666)
		(end 21.6662 -72.339962)
		(width 0.089408)
		(layer "In4.Cu")
		(net "FAN_PWM_OUT_SYS1_R")
	)
	(segment
		(start 332.5876 -21.7932)
		(end 334.2894 -21.7932)
		(width 0.089408)
		(layer "In4.Cu")
		(net "FAN_PWM_OUT_SYS1_R")
	)
	(segment
		(start 17.07388 -119.95658)
		(end 17.84604 -120.72874)
		(width 0.089408)
		(layer "In9.Cu")
		(net "FAN_PWM_OUT_SYS1_R")
	)
	(segment
		(start 17.84604 -121.38152)
		(end 18.0467 -121.58218)
		(width 0.089408)
		(layer "In9.Cu")
		(net "FAN_PWM_OUT_SYS1_R")
	)
	(segment
		(start -4.797044 -115.986052)
		(end -2.35712 -118.425976)
		(width 0.089408)
		(layer "In9.Cu")
		(net "FAN_PWM_OUT_SYS1_R")
	)
	(segment
		(start 7.759954 -119.697754)
		(end 8.01878 -119.95658)
		(width 0.089408)
		(layer "In9.Cu")
		(net "FAN_PWM_OUT_SYS1_R")
	)
	(segment
		(start 8.01878 -119.95658)
		(end 17.07388 -119.95658)
		(width 0.089408)
		(layer "In9.Cu")
		(net "FAN_PWM_OUT_SYS1_R")
	)
	(segment
		(start -3.679952 -110.259876)
		(end -4.797044 -111.376968)
		(width 0.089408)
		(layer "In9.Cu")
		(net "FAN_PWM_OUT_SYS1_R")
	)
	(segment
		(start -1.735074 -119.697754)
		(end 7.759954 -119.697754)
		(width 0.089408)
		(layer "In9.Cu")
		(net "FAN_PWM_OUT_SYS1_R")
	)
	(segment
		(start -4.797044 -111.376968)
		(end -4.797044 -115.986052)
		(width 0.089408)
		(layer "In9.Cu")
		(net "FAN_PWM_OUT_SYS1_R")
	)
	(segment
		(start -2.35712 -118.425976)
		(end -2.35712 -119.075708)
		(width 0.089408)
		(layer "In9.Cu")
		(net "FAN_PWM_OUT_SYS1_R")
	)
	(segment
		(start 17.84604 -120.72874)
		(end 17.84604 -121.38152)
		(width 0.089408)
		(layer "In9.Cu")
		(net "FAN_PWM_OUT_SYS1_R")
	)
	(segment
		(start -2.35712 -119.075708)
		(end -1.735074 -119.697754)
		(width 0.089408)
		(layer "In9.Cu")
		(net "FAN_PWM_OUT_SYS1_R")
	)
	(segment
		(start 24.17826 -38.288214)
		(end 24.17826 -39.98214)
		(width 0.10795)
		(layer "F.Cu")
		(net "FAN_PWM_OUT_SYS0_R")
	)
	(segment
		(start 22.85492 -36.964874)
		(end 24.17826 -38.288214)
		(width 0.10795)
		(layer "F.Cu")
		(net "FAN_PWM_OUT_SYS0_R")
	)
	(segment
		(start 23.2664 -40.894)
		(end 23.2664 -41.2242)
		(width 0.10795)
		(layer "F.Cu")
		(net "FAN_PWM_OUT_SYS0_R")
	)
	(segment
		(start 23.2664 -41.2242)
		(end 23.2664 -42.455846)
		(width 0.10795)
		(layer "F.Cu")
		(net "FAN_PWM_OUT_SYS0_R")
	)
	(segment
		(start 23.101046 -42.6212)
		(end 22.5044 -42.6212)
		(width 0.10795)
		(layer "F.Cu")
		(net "FAN_PWM_OUT_SYS0_R")
	)
	(segment
		(start 24.17826 -39.98214)
		(end 23.2664 -40.894)
		(width 0.10795)
		(layer "F.Cu")
		(net "FAN_PWM_OUT_SYS0_R")
	)
	(segment
		(start 23.2664 -42.455846)
		(end 23.101046 -42.6212)
		(width 0.10795)
		(layer "F.Cu")
		(net "FAN_PWM_OUT_SYS0_R")
	)
	(via
		(at 408.941016 4.405884)
		(size 0.508)
		(drill 0.254)
		(layers "F.Cu" "B.Cu")
		(net "FAN_PWM_OUT_SYS0_R")
	)
	(via
		(at 28.9814 -1.55448)
		(size 0.508)
		(drill 0.254)
		(layers "F.Cu" "B.Cu")
		(net "FAN_PWM_OUT_SYS0_R")
	)
	(via
		(at 15.423642 -39.844726)
		(size 0.6604)
		(drill 0.3302)
		(layers "F.Cu" "B.Cu")
		(net "FAN_PWM_OUT_SYS0_R")
	)
	(via
		(at 158.69158 0.16256)
		(size 0.508)
		(drill 0.254)
		(layers "F.Cu" "B.Cu")
		(net "FAN_PWM_OUT_SYS0_R")
	)
	(via
		(at 261.274306 1.68021)
		(size 0.508)
		(drill 0.254)
		(layers "F.Cu" "B.Cu")
		(net "FAN_PWM_OUT_SYS0_R")
	)
	(segment
		(start 20.488402 -39.331392)
		(end 15.936976 -39.331392)
		(width 0.10795)
		(layer "B.Cu")
		(net "FAN_PWM_OUT_SYS0_R")
	)
	(segment
		(start 409.164028 3.611372)
		(end 408.941016 3.834384)
		(width 0.10795)
		(layer "B.Cu")
		(net "FAN_PWM_OUT_SYS0_R")
	)
	(segment
		(start 15.936976 -39.331392)
		(end 15.423642 -39.844726)
		(width 0.10795)
		(layer "B.Cu")
		(net "FAN_PWM_OUT_SYS0_R")
	)
	(segment
		(start 408.941016 3.834384)
		(end 408.941016 4.405884)
		(width 0.10795)
		(layer "B.Cu")
		(net "FAN_PWM_OUT_SYS0_R")
	)
	(segment
		(start 409.702 3.611372)
		(end 409.164028 3.611372)
		(width 0.10795)
		(layer "B.Cu")
		(net "FAN_PWM_OUT_SYS0_R")
	)
	(segment
		(start 14.755368 -40.513)
		(end 13.97 -40.513)
		(width 0.10795)
		(layer "B.Cu")
		(net "FAN_PWM_OUT_SYS0_R")
	)
	(segment
		(start 22.85492 -36.964874)
		(end 20.488402 -39.331392)
		(width 0.10795)
		(layer "B.Cu")
		(net "FAN_PWM_OUT_SYS0_R")
	)
	(segment
		(start 15.423642 -39.844726)
		(end 14.755368 -40.513)
		(width 0.10795)
		(layer "B.Cu")
		(net "FAN_PWM_OUT_SYS0_R")
	)
	(segment
		(start 22.85492 -36.964874)
		(end 24.047704 -35.77209)
		(width 0.089408)
		(layer "In4.Cu")
		(net "FAN_PWM_OUT_SYS0_R")
	)
	(segment
		(start 170.814746 -4.9276)
		(end 172.628814 -6.741668)
		(width 0.089408)
		(layer "In4.Cu")
		(net "FAN_PWM_OUT_SYS0_R")
	)
	(segment
		(start 179.557172 -4.910328)
		(end 183.773064 -4.910328)
		(width 0.089408)
		(layer "In4.Cu")
		(net "FAN_PWM_OUT_SYS0_R")
	)
	(segment
		(start 175.546766 -6.741668)
		(end 176.510442 -5.777992)
		(width 0.089408)
		(layer "In4.Cu")
		(net "FAN_PWM_OUT_SYS0_R")
	)
	(segment
		(start 255.5367 2.0828)
		(end 259.041646 2.0828)
		(width 0.089408)
		(layer "In4.Cu")
		(net "FAN_PWM_OUT_SYS0_R")
	)
	(segment
		(start 192.913 1.2954)
		(end 195.7705 1.2954)
		(width 0.089408)
		(layer "In4.Cu")
		(net "FAN_PWM_OUT_SYS0_R")
	)
	(segment
		(start 187.833 -0.318008)
		(end 188.048392 -0.5334)
		(width 0.089408)
		(layer "In4.Cu")
		(net "FAN_PWM_OUT_SYS0_R")
	)
	(segment
		(start 178.689508 -5.777992)
		(end 179.557172 -4.910328)
		(width 0.089408)
		(layer "In4.Cu")
		(net "FAN_PWM_OUT_SYS0_R")
	)
	(segment
		(start 165.779704 -1.820926)
		(end 165.779704 -3.071876)
		(width 0.089408)
		(layer "In4.Cu")
		(net "FAN_PWM_OUT_SYS0_R")
	)
	(segment
		(start 197.390766 2.915666)
		(end 254.703834 2.915666)
		(width 0.089408)
		(layer "In4.Cu")
		(net "FAN_PWM_OUT_SYS0_R")
	)
	(segment
		(start 24.047704 -35.77209)
		(end 26.30551 -35.77209)
		(width 0.089408)
		(layer "In4.Cu")
		(net "FAN_PWM_OUT_SYS0_R")
	)
	(segment
		(start 165.779704 -3.071876)
		(end 167.635428 -4.9276)
		(width 0.089408)
		(layer "In4.Cu")
		(net "FAN_PWM_OUT_SYS0_R")
	)
	(segment
		(start 259.041646 2.0828)
		(end 259.201412 1.923034)
		(width 0.089408)
		(layer "In4.Cu")
		(net "FAN_PWM_OUT_SYS0_R")
	)
	(segment
		(start 183.773064 -4.910328)
		(end 184.8104 -3.872992)
		(width 0.089408)
		(layer "In4.Cu")
		(net "FAN_PWM_OUT_SYS0_R")
	)
	(segment
		(start 254.703834 2.915666)
		(end 255.5367 2.0828)
		(width 0.089408)
		(layer "In4.Cu")
		(net "FAN_PWM_OUT_SYS0_R")
	)
	(segment
		(start 190.88989 0.371856)
		(end 191.067944 0.371856)
		(width 0.089408)
		(layer "In4.Cu")
		(net "FAN_PWM_OUT_SYS0_R")
	)
	(segment
		(start 165.000178 -1.0414)
		(end 165.779704 -1.820926)
		(width 0.089408)
		(layer "In4.Cu")
		(net "FAN_PWM_OUT_SYS0_R")
	)
	(segment
		(start 191.3128 0.616712)
		(end 192.234312 0.616712)
		(width 0.089408)
		(layer "In4.Cu")
		(net "FAN_PWM_OUT_SYS0_R")
	)
	(segment
		(start 259.222748 1.923034)
		(end 259.465572 1.68021)
		(width 0.089408)
		(layer "In4.Cu")
		(net "FAN_PWM_OUT_SYS0_R")
	)
	(segment
		(start 191.067944 0.371856)
		(end 191.3128 0.616712)
		(width 0.089408)
		(layer "In4.Cu")
		(net "FAN_PWM_OUT_SYS0_R")
	)
	(segment
		(start 189.984634 -0.5334)
		(end 190.88989 0.371856)
		(width 0.089408)
		(layer "In4.Cu")
		(net "FAN_PWM_OUT_SYS0_R")
	)
	(segment
		(start 159.89554 -1.0414)
		(end 165.000178 -1.0414)
		(width 0.089408)
		(layer "In4.Cu")
		(net "FAN_PWM_OUT_SYS0_R")
	)
	(segment
		(start 184.8104 -3.872992)
		(end 184.8104 -1.4478)
		(width 0.089408)
		(layer "In4.Cu")
		(net "FAN_PWM_OUT_SYS0_R")
	)
	(segment
		(start 192.234312 0.616712)
		(end 192.913 1.2954)
		(width 0.089408)
		(layer "In4.Cu")
		(net "FAN_PWM_OUT_SYS0_R")
	)
	(segment
		(start 28.048712 -17.003268)
		(end 29.9212 -15.13078)
		(width 0.089408)
		(layer "In4.Cu")
		(net "FAN_PWM_OUT_SYS0_R")
	)
	(segment
		(start 195.7705 1.2954)
		(end 197.390766 2.915666)
		(width 0.089408)
		(layer "In4.Cu")
		(net "FAN_PWM_OUT_SYS0_R")
	)
	(segment
		(start 30.061408 -32.016192)
		(end 30.061408 -21.651722)
		(width 0.089408)
		(layer "In4.Cu")
		(net "FAN_PWM_OUT_SYS0_R")
	)
	(segment
		(start 29.9212 -15.13078)
		(end 29.9212 -2.49428)
		(width 0.089408)
		(layer "In4.Cu")
		(net "FAN_PWM_OUT_SYS0_R")
	)
	(segment
		(start 172.628814 -6.741668)
		(end 175.546766 -6.741668)
		(width 0.089408)
		(layer "In4.Cu")
		(net "FAN_PWM_OUT_SYS0_R")
	)
	(segment
		(start 30.061408 -21.651722)
		(end 28.048712 -19.639026)
		(width 0.089408)
		(layer "In4.Cu")
		(net "FAN_PWM_OUT_SYS0_R")
	)
	(segment
		(start 29.9212 -2.49428)
		(end 28.9814 -1.55448)
		(width 0.089408)
		(layer "In4.Cu")
		(net "FAN_PWM_OUT_SYS0_R")
	)
	(segment
		(start 158.69158 0.16256)
		(end 159.89554 -1.0414)
		(width 0.089408)
		(layer "In4.Cu")
		(net "FAN_PWM_OUT_SYS0_R")
	)
	(segment
		(start 259.465572 1.68021)
		(end 261.274306 1.68021)
		(width 0.089408)
		(layer "In4.Cu")
		(net "FAN_PWM_OUT_SYS0_R")
	)
	(segment
		(start 28.048712 -19.639026)
		(end 28.048712 -17.003268)
		(width 0.089408)
		(layer "In4.Cu")
		(net "FAN_PWM_OUT_SYS0_R")
	)
	(segment
		(start 26.30551 -35.77209)
		(end 30.061408 -32.016192)
		(width 0.089408)
		(layer "In4.Cu")
		(net "FAN_PWM_OUT_SYS0_R")
	)
	(segment
		(start 188.048392 -0.5334)
		(end 189.984634 -0.5334)
		(width 0.089408)
		(layer "In4.Cu")
		(net "FAN_PWM_OUT_SYS0_R")
	)
	(segment
		(start 184.8104 -1.4478)
		(end 185.940192 -0.318008)
		(width 0.089408)
		(layer "In4.Cu")
		(net "FAN_PWM_OUT_SYS0_R")
	)
	(segment
		(start 185.940192 -0.318008)
		(end 187.833 -0.318008)
		(width 0.089408)
		(layer "In4.Cu")
		(net "FAN_PWM_OUT_SYS0_R")
	)
	(segment
		(start 167.635428 -4.9276)
		(end 170.814746 -4.9276)
		(width 0.089408)
		(layer "In4.Cu")
		(net "FAN_PWM_OUT_SYS0_R")
	)
	(segment
		(start 176.510442 -5.777992)
		(end 178.689508 -5.777992)
		(width 0.089408)
		(layer "In4.Cu")
		(net "FAN_PWM_OUT_SYS0_R")
	)
	(segment
		(start 259.201412 1.923034)
		(end 259.222748 1.923034)
		(width 0.089408)
		(layer "In4.Cu")
		(net "FAN_PWM_OUT_SYS0_R")
	)
	(segment
		(start 325.080884 -3.825748)
		(end 325.080884 -1.705864)
		(width 0.089408)
		(layer "In9.Cu")
		(net "FAN_PWM_OUT_SYS0_R")
	)
	(segment
		(start 408.014932 3.4798)
		(end 403.7584 3.4798)
		(width 0.089408)
		(layer "In9.Cu")
		(net "FAN_PWM_OUT_SYS0_R")
	)
	(segment
		(start 339.502242 -13.8684)
		(end 339.502242 -10.867136)
		(width 0.089408)
		(layer "In9.Cu")
		(net "FAN_PWM_OUT_SYS0_R")
	)
	(segment
		(start 332.697836 -8.862314)
		(end 331.37221 -7.536688)
		(width 0.089408)
		(layer "In9.Cu")
		(net "FAN_PWM_OUT_SYS0_R")
	)
	(segment
		(start 361.345988 -18.846292)
		(end 360.581194 -19.611086)
		(width 0.089408)
		(layer "In9.Cu")
		(net "FAN_PWM_OUT_SYS0_R")
	)
	(segment
		(start 354.99802 -23.240746)
		(end 351.69475 -23.240746)
		(width 0.089408)
		(layer "In9.Cu")
		(net "FAN_PWM_OUT_SYS0_R")
	)
	(segment
		(start 362.540296 -11.852148)
		(end 361.786424 -11.852148)
		(width 0.089408)
		(layer "In9.Cu")
		(net "FAN_PWM_OUT_SYS0_R")
	)
	(segment
		(start 360.581194 -19.611086)
		(end 360.581194 -22.034246)
		(width 0.089408)
		(layer "In9.Cu")
		(net "FAN_PWM_OUT_SYS0_R")
	)
	(segment
		(start 351.69475 -23.240746)
		(end 351.08134 -22.627336)
		(width 0.089408)
		(layer "In9.Cu")
		(net "FAN_PWM_OUT_SYS0_R")
	)
	(segment
		(start 331.37221 -7.536688)
		(end 330.621894 -7.536688)
		(width 0.089408)
		(layer "In9.Cu")
		(net "FAN_PWM_OUT_SYS0_R")
	)
	(segment
		(start 325.080884 -1.705864)
		(end 323.622162 -0.247142)
		(width 0.089408)
		(layer "In9.Cu")
		(net "FAN_PWM_OUT_SYS0_R")
	)
	(segment
		(start 323.622162 -0.247142)
		(end 263.037828 -0.247142)
		(width 0.089408)
		(layer "In9.Cu")
		(net "FAN_PWM_OUT_SYS0_R")
	)
	(segment
		(start 380.417578 -2.309622)
		(end 377.527566 -5.199634)
		(width 0.089408)
		(layer "In9.Cu")
		(net "FAN_PWM_OUT_SYS0_R")
	)
	(segment
		(start 393.065 1.8288)
		(end 392.7856 2.1082)
		(width 0.089408)
		(layer "In9.Cu")
		(net "FAN_PWM_OUT_SYS0_R")
	)
	(segment
		(start 158.014924 -0.514096)
		(end 30.021784 -0.514096)
		(width 0.089408)
		(layer "In9.Cu")
		(net "FAN_PWM_OUT_SYS0_R")
	)
	(segment
		(start 158.69158 0.16256)
		(end 158.014924 -0.514096)
		(width 0.089408)
		(layer "In9.Cu")
		(net "FAN_PWM_OUT_SYS0_R")
	)
	(segment
		(start 340.233 -14.599158)
		(end 339.502242 -13.8684)
		(width 0.089408)
		(layer "In9.Cu")
		(net "FAN_PWM_OUT_SYS0_R")
	)
	(segment
		(start 392.7856 2.1336)
		(end 392.6586 2.2606)
		(width 0.089408)
		(layer "In9.Cu")
		(net "FAN_PWM_OUT_SYS0_R")
	)
	(segment
		(start 364.694978 -7.338314)
		(end 364.694978 -9.697466)
		(width 0.089408)
		(layer "In9.Cu")
		(net "FAN_PWM_OUT_SYS0_R")
	)
	(segment
		(start 339.502242 -10.867136)
		(end 337.49742 -8.862314)
		(width 0.089408)
		(layer "In9.Cu")
		(net "FAN_PWM_OUT_SYS0_R")
	)
	(segment
		(start 337.49742 -8.862314)
		(end 332.697836 -8.862314)
		(width 0.089408)
		(layer "In9.Cu")
		(net "FAN_PWM_OUT_SYS0_R")
	)
	(segment
		(start 401.4724 3.1496)
		(end 400.1516 1.8288)
		(width 0.089408)
		(layer "In9.Cu")
		(net "FAN_PWM_OUT_SYS0_R")
	)
	(segment
		(start 340.762082 -19.322034)
		(end 340.233 -18.792952)
		(width 0.089408)
		(layer "In9.Cu")
		(net "FAN_PWM_OUT_SYS0_R")
	)
	(segment
		(start 326.363076 -5.10794)
		(end 325.080884 -3.825748)
		(width 0.089408)
		(layer "In9.Cu")
		(net "FAN_PWM_OUT_SYS0_R")
	)
	(segment
		(start 361.345988 -12.292584)
		(end 361.345988 -18.846292)
		(width 0.089408)
		(layer "In9.Cu")
		(net "FAN_PWM_OUT_SYS0_R")
	)
	(segment
		(start 30.021784 -0.514096)
		(end 28.9814 -1.55448)
		(width 0.089408)
		(layer "In9.Cu")
		(net "FAN_PWM_OUT_SYS0_R")
	)
	(segment
		(start 261.274306 1.51638)
		(end 261.274306 1.68021)
		(width 0.089408)
		(layer "In9.Cu")
		(net "FAN_PWM_OUT_SYS0_R")
	)
	(segment
		(start 377.527566 -5.199634)
		(end 366.833658 -5.199634)
		(width 0.089408)
		(layer "In9.Cu")
		(net "FAN_PWM_OUT_SYS0_R")
	)
	(segment
		(start 357.96474 -24.6507)
		(end 356.407974 -24.6507)
		(width 0.089408)
		(layer "In9.Cu")
		(net "FAN_PWM_OUT_SYS0_R")
	)
	(segment
		(start 340.233 -18.792952)
		(end 340.233 -14.599158)
		(width 0.089408)
		(layer "In9.Cu")
		(net "FAN_PWM_OUT_SYS0_R")
	)
	(segment
		(start 330.621894 -7.536688)
		(end 328.193146 -5.10794)
		(width 0.089408)
		(layer "In9.Cu")
		(net "FAN_PWM_OUT_SYS0_R")
	)
	(segment
		(start 351.08134 -22.627336)
		(end 341.08517 -22.627336)
		(width 0.089408)
		(layer "In9.Cu")
		(net "FAN_PWM_OUT_SYS0_R")
	)
	(segment
		(start 392.6586 2.2606)
		(end 382.505966 2.2606)
		(width 0.089408)
		(layer "In9.Cu")
		(net "FAN_PWM_OUT_SYS0_R")
	)
	(segment
		(start 356.407974 -24.6507)
		(end 354.99802 -23.240746)
		(width 0.089408)
		(layer "In9.Cu")
		(net "FAN_PWM_OUT_SYS0_R")
	)
	(segment
		(start 328.193146 -5.10794)
		(end 326.363076 -5.10794)
		(width 0.089408)
		(layer "In9.Cu")
		(net "FAN_PWM_OUT_SYS0_R")
	)
	(segment
		(start 366.833658 -5.199634)
		(end 364.694978 -7.338314)
		(width 0.089408)
		(layer "In9.Cu")
		(net "FAN_PWM_OUT_SYS0_R")
	)
	(segment
		(start 380.417578 0.172212)
		(end 380.417578 -2.309622)
		(width 0.089408)
		(layer "In9.Cu")
		(net "FAN_PWM_OUT_SYS0_R")
	)
	(segment
		(start 263.037828 -0.247142)
		(end 261.274306 1.51638)
		(width 0.089408)
		(layer "In9.Cu")
		(net "FAN_PWM_OUT_SYS0_R")
	)
	(segment
		(start 364.694978 -9.697466)
		(end 362.540296 -11.852148)
		(width 0.089408)
		(layer "In9.Cu")
		(net "FAN_PWM_OUT_SYS0_R")
	)
	(segment
		(start 382.505966 2.2606)
		(end 380.417578 0.172212)
		(width 0.089408)
		(layer "In9.Cu")
		(net "FAN_PWM_OUT_SYS0_R")
	)
	(segment
		(start 341.08517 -22.627336)
		(end 340.762082 -22.304248)
		(width 0.089408)
		(layer "In9.Cu")
		(net "FAN_PWM_OUT_SYS0_R")
	)
	(segment
		(start 361.786424 -11.852148)
		(end 361.345988 -12.292584)
		(width 0.089408)
		(layer "In9.Cu")
		(net "FAN_PWM_OUT_SYS0_R")
	)
	(segment
		(start 392.7856 2.1082)
		(end 392.7856 2.1336)
		(width 0.089408)
		(layer "In9.Cu")
		(net "FAN_PWM_OUT_SYS0_R")
	)
	(segment
		(start 360.581194 -22.034246)
		(end 357.96474 -24.6507)
		(width 0.089408)
		(layer "In9.Cu")
		(net "FAN_PWM_OUT_SYS0_R")
	)
	(segment
		(start 408.941016 4.405884)
		(end 408.014932 3.4798)
		(width 0.089408)
		(layer "In9.Cu")
		(net "FAN_PWM_OUT_SYS0_R")
	)
	(segment
		(start 340.762082 -22.304248)
		(end 340.762082 -19.322034)
		(width 0.089408)
		(layer "In9.Cu")
		(net "FAN_PWM_OUT_SYS0_R")
	)
	(segment
		(start 403.7584 3.4798)
		(end 403.4282 3.1496)
		(width 0.089408)
		(layer "In9.Cu")
		(net "FAN_PWM_OUT_SYS0_R")
	)
	(segment
		(start 403.4282 3.1496)
		(end 401.4724 3.1496)
		(width 0.089408)
		(layer "In9.Cu")
		(net "FAN_PWM_OUT_SYS0_R")
	)
	(segment
		(start 400.1516 1.8288)
		(end 393.065 1.8288)
		(width 0.089408)
		(layer "In9.Cu")
		(net "FAN_PWM_OUT_SYS0_R")
	)
	(segment
		(start 382.407414 -58.082688)
		(end 389.527542 -58.082688)
		(width 0.10795)
		(layer "F.Cu")
		(net "CLK_24M_BMC_LPC")
	)
	(segment
		(start 381.77216 -58.717942)
		(end 382.407414 -58.082688)
		(width 0.10795)
		(layer "F.Cu")
		(net "CLK_24M_BMC_LPC")
	)
	(segment
		(start 407.399236 -47.578518)
		(end 407.399236 -47.889414)
		(width 0.10795)
		(layer "F.Cu")
		(net "CLK_24M_BMC_LPC")
	)
	(segment
		(start 394.136372 -47.679356)
		(end 397.777462 -44.038266)
		(width 0.10795)
		(layer "F.Cu")
		(net "CLK_24M_BMC_LPC")
	)
	(segment
		(start 394.855192 -49.879504)
		(end 394.136372 -49.160684)
		(width 0.10795)
		(layer "F.Cu")
		(net "CLK_24M_BMC_LPC")
	)
	(segment
		(start 401.826222 -45.213524)
		(end 402.845524 -45.213524)
		(width 0.10795)
		(layer "F.Cu")
		(net "CLK_24M_BMC_LPC")
	)
	(segment
		(start 397.777462 -44.038266)
		(end 398.172686 -44.038266)
		(width 0.10795)
		(layer "F.Cu")
		(net "CLK_24M_BMC_LPC")
	)
	(segment
		(start 408.690064 -43.334686)
		(end 408.690064 -43.43273)
		(width 0.10795)
		(layer "F.Cu")
		(net "CLK_24M_BMC_LPC")
	)
	(segment
		(start 408.318208 -44.617132)
		(end 408.147266 -44.788074)
		(width 0.10795)
		(layer "F.Cu")
		(net "CLK_24M_BMC_LPC")
	)
	(segment
		(start 399.458434 -44.820078)
		(end 399.458688 -44.819824)
		(width 0.10795)
		(layer "F.Cu")
		(net "CLK_24M_BMC_LPC")
	)
	(segment
		(start 404.86584 -48.28286)
		(end 404.9649 -48.38192)
		(width 0.10795)
		(layer "F.Cu")
		(net "CLK_24M_BMC_LPC")
	)
	(segment
		(start 389.527542 -58.082688)
		(end 394.855192 -52.755038)
		(width 0.10795)
		(layer "F.Cu")
		(net "CLK_24M_BMC_LPC")
	)
	(segment
		(start 404.9649 -48.38192)
		(end 406.79751 -48.38192)
		(width 0.10795)
		(layer "F.Cu")
		(net "CLK_24M_BMC_LPC")
	)
	(segment
		(start 406.79751 -48.38192)
		(end 407.290016 -47.889414)
		(width 0.10795)
		(layer "F.Cu")
		(net "CLK_24M_BMC_LPC")
	)
	(segment
		(start 404.205694 -48.28286)
		(end 404.86584 -48.28286)
		(width 0.10795)
		(layer "F.Cu")
		(net "CLK_24M_BMC_LPC")
	)
	(segment
		(start 403.479 -47.556166)
		(end 404.205694 -48.28286)
		(width 0.10795)
		(layer "F.Cu")
		(net "CLK_24M_BMC_LPC")
	)
	(segment
		(start 394.136372 -49.160684)
		(end 394.136372 -47.679356)
		(width 0.10795)
		(layer "F.Cu")
		(net "CLK_24M_BMC_LPC")
	)
	(segment
		(start 403.479 -45.847)
		(end 403.479 -47.556166)
		(width 0.10795)
		(layer "F.Cu")
		(net "CLK_24M_BMC_LPC")
	)
	(segment
		(start 399.458688 -44.819824)
		(end 401.432522 -44.819824)
		(width 0.10795)
		(layer "F.Cu")
		(net "CLK_24M_BMC_LPC")
	)
	(segment
		(start 408.147266 -46.51121)
		(end 408.02306 -46.635416)
		(width 0.10795)
		(layer "F.Cu")
		(net "CLK_24M_BMC_LPC")
	)
	(segment
		(start 398.172686 -44.038266)
		(end 398.954498 -44.820078)
		(width 0.10795)
		(layer "F.Cu")
		(net "CLK_24M_BMC_LPC")
	)
	(segment
		(start 402.845524 -45.213524)
		(end 403.479 -45.847)
		(width 0.10795)
		(layer "F.Cu")
		(net "CLK_24M_BMC_LPC")
	)
	(segment
		(start 408.02306 -46.635416)
		(end 408.02306 -46.954694)
		(width 0.10795)
		(layer "F.Cu")
		(net "CLK_24M_BMC_LPC")
	)
	(segment
		(start 407.290016 -47.889414)
		(end 407.399236 -47.889414)
		(width 0.10795)
		(layer "F.Cu")
		(net "CLK_24M_BMC_LPC")
	)
	(segment
		(start 401.432522 -44.819824)
		(end 401.826222 -45.213524)
		(width 0.10795)
		(layer "F.Cu")
		(net "CLK_24M_BMC_LPC")
	)
	(segment
		(start 408.02306 -46.954694)
		(end 407.399236 -47.578518)
		(width 0.10795)
		(layer "F.Cu")
		(net "CLK_24M_BMC_LPC")
	)
	(segment
		(start 380.887986 -58.717942)
		(end 381.77216 -58.717942)
		(width 0.10795)
		(layer "F.Cu")
		(net "CLK_24M_BMC_LPC")
	)
	(segment
		(start 394.855192 -52.755038)
		(end 394.855192 -49.879504)
		(width 0.10795)
		(layer "F.Cu")
		(net "CLK_24M_BMC_LPC")
	)
	(segment
		(start 408.318208 -43.804586)
		(end 408.318208 -44.617132)
		(width 0.10795)
		(layer "F.Cu")
		(net "CLK_24M_BMC_LPC")
	)
	(segment
		(start 398.954498 -44.820078)
		(end 399.458434 -44.820078)
		(width 0.10795)
		(layer "F.Cu")
		(net "CLK_24M_BMC_LPC")
	)
	(segment
		(start 408.147266 -44.788074)
		(end 408.147266 -46.51121)
		(width 0.10795)
		(layer "F.Cu")
		(net "CLK_24M_BMC_LPC")
	)
	(segment
		(start 408.690064 -43.43273)
		(end 408.318208 -43.804586)
		(width 0.10795)
		(layer "F.Cu")
		(net "CLK_24M_BMC_LPC")
	)
	(via
		(at 379.3744 -89.92108)
		(size 0.6604)
		(drill 0.3302)
		(layers "F.Cu" "B.Cu")
		(net "CLK_24M_BMC_LPC")
	)
	(via
		(at 382.10998 -84.06638)
		(size 0.508)
		(drill 0.254)
		(layers "F.Cu" "B.Cu")
		(net "CLK_24M_BMC_LPC")
	)
	(via
		(at 380.887986 -58.717942)
		(size 0.508)
		(drill 0.254)
		(layers "F.Cu" "B.Cu")
		(net "CLK_24M_BMC_LPC")
	)
	(segment
		(start 378.8918 -88.69553)
		(end 378.566172 -88.369902)
		(width 0.10795)
		(layer "B.Cu")
		(net "CLK_24M_BMC_LPC")
	)
	(segment
		(start 379.26772 -85.656166)
		(end 380.616206 -84.30768)
		(width 0.10795)
		(layer "B.Cu")
		(net "CLK_24M_BMC_LPC")
	)
	(segment
		(start 381.16764 -84.30768)
		(end 381.40894 -84.06638)
		(width 0.10795)
		(layer "B.Cu")
		(net "CLK_24M_BMC_LPC")
	)
	(segment
		(start 378.8918 -89.43848)
		(end 378.8918 -88.69553)
		(width 0.10795)
		(layer "B.Cu")
		(net "CLK_24M_BMC_LPC")
	)
	(segment
		(start 379.26772 -86.480142)
		(end 379.26772 -85.656166)
		(width 0.10795)
		(layer "B.Cu")
		(net "CLK_24M_BMC_LPC")
	)
	(segment
		(start 380.616206 -84.30768)
		(end 381.16764 -84.30768)
		(width 0.10795)
		(layer "B.Cu")
		(net "CLK_24M_BMC_LPC")
	)
	(segment
		(start 381.40894 -84.06638)
		(end 382.10998 -84.06638)
		(width 0.10795)
		(layer "B.Cu")
		(net "CLK_24M_BMC_LPC")
	)
	(segment
		(start 379.3744 -89.92108)
		(end 378.8918 -89.43848)
		(width 0.10795)
		(layer "B.Cu")
		(net "CLK_24M_BMC_LPC")
	)
	(segment
		(start 379.3744 -89.92108)
		(end 379.481842 -90.028522)
		(width 0.10795)
		(layer "B.Cu")
		(net "CLK_24M_BMC_LPC")
	)
	(segment
		(start 378.566172 -87.18169)
		(end 379.26772 -86.480142)
		(width 0.10795)
		(layer "B.Cu")
		(net "CLK_24M_BMC_LPC")
	)
	(segment
		(start 379.481842 -90.028522)
		(end 379.481842 -91.021662)
		(width 0.10795)
		(layer "B.Cu")
		(net "CLK_24M_BMC_LPC")
	)
	(segment
		(start 378.566172 -88.369902)
		(end 378.566172 -87.18169)
		(width 0.10795)
		(layer "B.Cu")
		(net "CLK_24M_BMC_LPC")
	)
	(segment
		(start 382.222502 -70.419214)
		(end 382.222502 -76.582016)
		(width 0.089408)
		(layer "In11.Cu")
		(net "CLK_24M_BMC_LPC")
	)
	(segment
		(start 380.39294 -60.273692)
		(end 380.39294 -62.176914)
		(width 0.089408)
		(layer "In11.Cu")
		(net "CLK_24M_BMC_LPC")
	)
	(segment
		(start 381.762 -77.042518)
		(end 381.762 -79.58328)
		(width 0.089408)
		(layer "In11.Cu")
		(net "CLK_24M_BMC_LPC")
	)
	(segment
		(start 381.049784 -59.616848)
		(end 380.39294 -60.273692)
		(width 0.089408)
		(layer "In11.Cu")
		(net "CLK_24M_BMC_LPC")
	)
	(segment
		(start 380.330202 -65.938908)
		(end 381.678688 -67.287394)
		(width 0.089408)
		(layer "In11.Cu")
		(net "CLK_24M_BMC_LPC")
	)
	(segment
		(start 380.386336 -62.183518)
		(end 380.386336 -62.196472)
		(width 0.089408)
		(layer "In11.Cu")
		(net "CLK_24M_BMC_LPC")
	)
	(segment
		(start 380.386336 -62.196472)
		(end 379.561344 -63.021464)
		(width 0.089408)
		(layer "In11.Cu")
		(net "CLK_24M_BMC_LPC")
	)
	(segment
		(start 382.80086 -80.62214)
		(end 382.80086 -83.3755)
		(width 0.089408)
		(layer "In11.Cu")
		(net "CLK_24M_BMC_LPC")
	)
	(segment
		(start 380.39294 -62.176914)
		(end 380.386336 -62.183518)
		(width 0.089408)
		(layer "In11.Cu")
		(net "CLK_24M_BMC_LPC")
	)
	(segment
		(start 379.561344 -64.080644)
		(end 380.330202 -64.849502)
		(width 0.089408)
		(layer "In11.Cu")
		(net "CLK_24M_BMC_LPC")
	)
	(segment
		(start 380.887986 -58.717942)
		(end 381.049784 -58.87974)
		(width 0.089408)
		(layer "In11.Cu")
		(net "CLK_24M_BMC_LPC")
	)
	(segment
		(start 379.561344 -63.021464)
		(end 379.561344 -64.080644)
		(width 0.089408)
		(layer "In11.Cu")
		(net "CLK_24M_BMC_LPC")
	)
	(segment
		(start 381.049784 -58.87974)
		(end 381.049784 -59.616848)
		(width 0.089408)
		(layer "In11.Cu")
		(net "CLK_24M_BMC_LPC")
	)
	(segment
		(start 382.80086 -83.3755)
		(end 382.10998 -84.06638)
		(width 0.089408)
		(layer "In11.Cu")
		(net "CLK_24M_BMC_LPC")
	)
	(segment
		(start 381.678688 -69.8754)
		(end 382.222502 -70.419214)
		(width 0.089408)
		(layer "In11.Cu")
		(net "CLK_24M_BMC_LPC")
	)
	(segment
		(start 381.678688 -67.287394)
		(end 381.678688 -69.8754)
		(width 0.089408)
		(layer "In11.Cu")
		(net "CLK_24M_BMC_LPC")
	)
	(segment
		(start 380.330202 -64.849502)
		(end 380.330202 -65.938908)
		(width 0.089408)
		(layer "In11.Cu")
		(net "CLK_24M_BMC_LPC")
	)
	(segment
		(start 381.762 -79.58328)
		(end 382.80086 -80.62214)
		(width 0.089408)
		(layer "In11.Cu")
		(net "CLK_24M_BMC_LPC")
	)
	(segment
		(start 382.222502 -76.582016)
		(end 381.762 -77.042518)
		(width 0.089408)
		(layer "In11.Cu")
		(net "CLK_24M_BMC_LPC")
	)
	(via
		(at 374.2817 -3.5941)
		(size 0.6604)
		(drill 0.3302)
		(layers "F.Cu" "B.Cu")
		(net "PU_BIOS_RECOVER_BOOT")
	)
	(segment
		(start 372.5672 0.404876)
		(end 372.5672 1.766062)
		(width 0.10795)
		(layer "B.Cu")
		(net "PU_BIOS_RECOVER_BOOT")
	)
	(segment
		(start 372.467124 -1.60147)
		(end 372.467124 0.3048)
		(width 0.10795)
		(layer "B.Cu")
		(net "PU_BIOS_RECOVER_BOOT")
	)
	(segment
		(start 377.783344 2.454656)
		(end 378.968 1.27)
		(width 0.10795)
		(layer "B.Cu")
		(net "PU_BIOS_RECOVER_BOOT")
	)
	(segment
		(start 373.255794 2.454656)
		(end 377.783344 2.454656)
		(width 0.10795)
		(layer "B.Cu")
		(net "PU_BIOS_RECOVER_BOOT")
	)
	(segment
		(start 374.2817 -4.335526)
		(end 374.2817 -3.5941)
		(width 0.10795)
		(layer "B.Cu")
		(net "PU_BIOS_RECOVER_BOOT")
	)
	(segment
		(start 372.467124 0.3048)
		(end 372.5672 0.404876)
		(width 0.10795)
		(layer "B.Cu")
		(net "PU_BIOS_RECOVER_BOOT")
	)
	(segment
		(start 373.761 -4.856226)
		(end 374.2817 -4.335526)
		(width 0.10795)
		(layer "B.Cu")
		(net "PU_BIOS_RECOVER_BOOT")
	)
	(segment
		(start 374.2817 -3.5941)
		(end 374.2817 -3.416046)
		(width 0.10795)
		(layer "B.Cu")
		(net "PU_BIOS_RECOVER_BOOT")
	)
	(segment
		(start 372.5672 1.766062)
		(end 373.255794 2.454656)
		(width 0.10795)
		(layer "B.Cu")
		(net "PU_BIOS_RECOVER_BOOT")
	)
	(segment
		(start 374.2817 -3.416046)
		(end 372.467124 -1.60147)
		(width 0.10795)
		(layer "B.Cu")
		(net "PU_BIOS_RECOVER_BOOT")
	)
	(segment
		(start 373.761 -5.2705)
		(end 373.761 -4.856226)
		(width 0.10795)
		(layer "B.Cu")
		(net "PU_BIOS_RECOVER_BOOT")
	)
	(segment
		(start 475.516702 -54.67096)
		(end 469.775032 -54.67096)
		(width 0.127)
		(layer "F.Cu")
		(net "CLK_100M_SPRV_DP")
	)
	(segment
		(start 374.396 -101.6762)
		(end 374.30202 -101.77018)
		(width 0.0889)
		(layer "F.Cu")
		(net "CLK_100M_SPRV_DP")
	)
	(segment
		(start 447.662046 -55.86222)
		(end 447.09842 -55.298594)
		(width 0.127)
		(layer "F.Cu")
		(net "CLK_100M_SPRV_DP")
	)
	(segment
		(start 482.5746 -55.333392)
		(end 481.977192 -55.9308)
		(width 0.127)
		(layer "F.Cu")
		(net "CLK_100M_SPRV_DP")
	)
	(segment
		(start 424.308016 -60.35167)
		(end 424.308016 -60.353956)
		(width 0.127)
		(layer "F.Cu")
		(net "CLK_100M_SPRV_DP")
	)
	(segment
		(start 480.721162 -55.7657)
		(end 480.556062 -55.9308)
		(width 0.127)
		(layer "F.Cu")
		(net "CLK_100M_SPRV_DP")
	)
	(segment
		(start 372.9609 -101.475794)
		(end 372.9609 -101.100636)
		(width 0.0889)
		(layer "F.Cu")
		(net "CLK_100M_SPRV_DP")
	)
	(segment
		(start 424.055032 -63.256922)
		(end 422.665906 -64.646048)
		(width 0.127)
		(layer "F.Cu")
		(net "CLK_100M_SPRV_DP")
	)
	(segment
		(start 430.073308 -54.9656)
		(end 425.599098 -59.43981)
		(width 0.127)
		(layer "F.Cu")
		(net "CLK_100M_SPRV_DP")
	)
	(segment
		(start 435.5592 -54.9656)
		(end 430.073308 -54.9656)
		(width 0.127)
		(layer "F.Cu")
		(net "CLK_100M_SPRV_DP")
	)
	(segment
		(start 374.10898 -101.77018)
		(end 374.015 -101.6762)
		(width 0.0889)
		(layer "F.Cu")
		(net "CLK_100M_SPRV_DP")
	)
	(segment
		(start 425.599098 -59.43981)
		(end 425.222162 -59.43981)
		(width 0.127)
		(layer "F.Cu")
		(net "CLK_100M_SPRV_DP")
	)
	(segment
		(start 424.312334 -60.349638)
		(end 424.310048 -60.349638)
		(width 0.127)
		(layer "F.Cu")
		(net "CLK_100M_SPRV_DP")
	)
	(segment
		(start 480.556062 -55.9308)
		(end 480.111308 -55.9308)
		(width 0.127)
		(layer "F.Cu")
		(net "CLK_100M_SPRV_DP")
	)
	(segment
		(start 372.862856 -101.002592)
		(end 372.585742 -101.002592)
		(width 0.0889)
		(layer "F.Cu")
		(net "CLK_100M_SPRV_DP")
	)
	(segment
		(start 482.5746 -50.515266)
		(end 482.5746 -52.5526)
		(width 0.127)
		(layer "F.Cu")
		(net "CLK_100M_SPRV_DP")
	)
	(segment
		(start 425.222162 -59.43981)
		(end 424.312334 -60.349638)
		(width 0.127)
		(layer "F.Cu")
		(net "CLK_100M_SPRV_DP")
	)
	(segment
		(start 476.776542 -55.9308)
		(end 475.516702 -54.67096)
		(width 0.127)
		(layer "F.Cu")
		(net "CLK_100M_SPRV_DP")
	)
	(segment
		(start 482.5746 -52.5526)
		(end 482.5746 -55.333392)
		(width 0.127)
		(layer "F.Cu")
		(net "CLK_100M_SPRV_DP")
	)
	(segment
		(start 373.85498 -101.6762)
		(end 373.766334 -101.764846)
		(width 0.0889)
		(layer "F.Cu")
		(net "CLK_100M_SPRV_DP")
	)
	(segment
		(start 374.015 -101.6762)
		(end 373.85498 -101.6762)
		(width 0.0889)
		(layer "F.Cu")
		(net "CLK_100M_SPRV_DP")
	)
	(segment
		(start 421.942006 -71.102474)
		(end 421.46728 -71.5772)
		(width 0.127)
		(layer "F.Cu")
		(net "CLK_100M_SPRV_DP")
	)
	(segment
		(start 481.102162 -55.7657)
		(end 480.721162 -55.7657)
		(width 0.127)
		(layer "F.Cu")
		(net "CLK_100M_SPRV_DP")
	)
	(segment
		(start 422.665906 -69.3166)
		(end 421.942006 -70.0405)
		(width 0.127)
		(layer "F.Cu")
		(net "CLK_100M_SPRV_DP")
	)
	(segment
		(start 424.310048 -60.349638)
		(end 424.308016 -60.35167)
		(width 0.127)
		(layer "F.Cu")
		(net "CLK_100M_SPRV_DP")
	)
	(segment
		(start 483.501192 -48.90008)
		(end 483.59568 -48.994568)
		(width 0.127)
		(layer "F.Cu")
		(net "CLK_100M_SPRV_DP")
	)
	(segment
		(start 483.59568 -49.494186)
		(end 482.5746 -50.515266)
		(width 0.127)
		(layer "F.Cu")
		(net "CLK_100M_SPRV_DP")
	)
	(segment
		(start 422.665906 -64.646048)
		(end 422.665906 -69.3166)
		(width 0.127)
		(layer "F.Cu")
		(net "CLK_100M_SPRV_DP")
	)
	(segment
		(start 436.1688 -55.5752)
		(end 435.5592 -54.9656)
		(width 0.127)
		(layer "F.Cu")
		(net "CLK_100M_SPRV_DP")
	)
	(segment
		(start 374.30202 -101.77018)
		(end 374.10898 -101.77018)
		(width 0.0889)
		(layer "F.Cu")
		(net "CLK_100M_SPRV_DP")
	)
	(segment
		(start 479.565208 -55.7657)
		(end 479.400108 -55.9308)
		(width 0.127)
		(layer "F.Cu")
		(net "CLK_100M_SPRV_DP")
	)
	(segment
		(start 374.674892 -101.855016)
		(end 374.674892 -101.73462)
		(width 0.0889)
		(layer "F.Cu")
		(net "CLK_100M_SPRV_DP")
	)
	(segment
		(start 421.942006 -70.0405)
		(end 421.942006 -71.102474)
		(width 0.127)
		(layer "F.Cu")
		(net "CLK_100M_SPRV_DP")
	)
	(segment
		(start 374.674892 -101.73462)
		(end 374.616472 -101.6762)
		(width 0.0889)
		(layer "F.Cu")
		(net "CLK_100M_SPRV_DP")
	)
	(segment
		(start 424.055032 -60.60694)
		(end 424.055032 -63.256922)
		(width 0.127)
		(layer "F.Cu")
		(net "CLK_100M_SPRV_DP")
	)
	(segment
		(start 424.308016 -60.353956)
		(end 424.055032 -60.60694)
		(width 0.127)
		(layer "F.Cu")
		(net "CLK_100M_SPRV_DP")
	)
	(segment
		(start 373.766334 -101.764846)
		(end 373.580914 -101.764846)
		(width 0.0889)
		(layer "F.Cu")
		(net "CLK_100M_SPRV_DP")
	)
	(segment
		(start 447.09842 -55.298594)
		(end 439.799222 -55.298594)
		(width 0.127)
		(layer "F.Cu")
		(net "CLK_100M_SPRV_DP")
	)
	(segment
		(start 483.59568 -48.994568)
		(end 483.59568 -49.494186)
		(width 0.127)
		(layer "F.Cu")
		(net "CLK_100M_SPRV_DP")
	)
	(segment
		(start 479.946208 -55.7657)
		(end 479.565208 -55.7657)
		(width 0.127)
		(layer "F.Cu")
		(net "CLK_100M_SPRV_DP")
	)
	(segment
		(start 421.131492 -71.5772)
		(end 421.004492 -71.4502)
		(width 0.127)
		(layer "F.Cu")
		(net "CLK_100M_SPRV_DP")
	)
	(segment
		(start 479.400108 -55.9308)
		(end 476.776542 -55.9308)
		(width 0.127)
		(layer "F.Cu")
		(net "CLK_100M_SPRV_DP")
	)
	(segment
		(start 373.161306 -101.6762)
		(end 372.9609 -101.475794)
		(width 0.0889)
		(layer "F.Cu")
		(net "CLK_100M_SPRV_DP")
	)
	(segment
		(start 483.501192 -48.3362)
		(end 483.501192 -48.90008)
		(width 0.127)
		(layer "F.Cu")
		(net "CLK_100M_SPRV_DP")
	)
	(segment
		(start 421.46728 -71.5772)
		(end 421.131492 -71.5772)
		(width 0.127)
		(layer "F.Cu")
		(net "CLK_100M_SPRV_DP")
	)
	(segment
		(start 439.522616 -55.5752)
		(end 436.1688 -55.5752)
		(width 0.127)
		(layer "F.Cu")
		(net "CLK_100M_SPRV_DP")
	)
	(segment
		(start 374.616472 -101.6762)
		(end 374.396 -101.6762)
		(width 0.0889)
		(layer "F.Cu")
		(net "CLK_100M_SPRV_DP")
	)
	(segment
		(start 372.9609 -101.100636)
		(end 372.862856 -101.002592)
		(width 0.0889)
		(layer "F.Cu")
		(net "CLK_100M_SPRV_DP")
	)
	(segment
		(start 469.775032 -54.67096)
		(end 468.583772 -55.86222)
		(width 0.127)
		(layer "F.Cu")
		(net "CLK_100M_SPRV_DP")
	)
	(segment
		(start 373.580914 -101.764846)
		(end 373.492268 -101.6762)
		(width 0.0889)
		(layer "F.Cu")
		(net "CLK_100M_SPRV_DP")
	)
	(segment
		(start 480.111308 -55.9308)
		(end 479.946208 -55.7657)
		(width 0.127)
		(layer "F.Cu")
		(net "CLK_100M_SPRV_DP")
	)
	(segment
		(start 481.267262 -55.9308)
		(end 481.102162 -55.7657)
		(width 0.127)
		(layer "F.Cu")
		(net "CLK_100M_SPRV_DP")
	)
	(segment
		(start 468.583772 -55.86222)
		(end 447.662046 -55.86222)
		(width 0.127)
		(layer "F.Cu")
		(net "CLK_100M_SPRV_DP")
	)
	(segment
		(start 481.977192 -55.9308)
		(end 481.267262 -55.9308)
		(width 0.127)
		(layer "F.Cu")
		(net "CLK_100M_SPRV_DP")
	)
	(segment
		(start 373.492268 -101.6762)
		(end 373.161306 -101.6762)
		(width 0.0889)
		(layer "F.Cu")
		(net "CLK_100M_SPRV_DP")
	)
	(segment
		(start 439.799222 -55.298594)
		(end 439.522616 -55.5752)
		(width 0.127)
		(layer "F.Cu")
		(net "CLK_100M_SPRV_DP")
	)
	(segment
		(start 421.004492 -71.4502)
		(end 421.004492 -71.0946)
		(width 0.127)
		(layer "F.Cu")
		(net "CLK_100M_SPRV_DP")
	)
	(via
		(at 372.585742 -101.002592)
		(size 0.508)
		(drill 0.254)
		(layers "F.Cu" "B.Cu")
		(net "CLK_100M_SPRV_DP")
	)
	(via
		(at 482.5746 -52.5526)
		(size 0.508)
		(drill 0.254)
		(layers "F.Cu" "B.Cu")
		(net "CLK_100M_SPRV_DP")
	)
	(via
		(at 421.004492 -71.0946)
		(size 0.508)
		(drill 0.254)
		(layers "F.Cu" "B.Cu")
		(net "CLK_100M_SPRV_DP")
	)
	(segment
		(start 418.216588 -81.712054)
		(end 416.574732 -83.35391)
		(width 0.1143)
		(layer "In4.Cu")
		(net "CLK_100M_SPRV_DP")
	)
	(segment
		(start 383.281428 -88.369902)
		(end 383.12598 -88.369902)
		(width 0.1143)
		(layer "In4.Cu")
		(net "CLK_100M_SPRV_DP")
	)
	(segment
		(start 388.966202 -85.4456)
		(end 388.616952 -85.79485)
		(width 0.1143)
		(layer "In4.Cu")
		(net "CLK_100M_SPRV_DP")
	)
	(segment
		(start 376.555 -95.789242)
		(end 375.412 -96.932242)
		(width 0.1143)
		(layer "In4.Cu")
		(net "CLK_100M_SPRV_DP")
	)
	(segment
		(start 421.004492 -71.40829)
		(end 420.890192 -71.52259)
		(width 0.1143)
		(layer "In4.Cu")
		(net "CLK_100M_SPRV_DP")
	)
	(segment
		(start 394.106908 -84.703666)
		(end 393.364974 -85.4456)
		(width 0.1143)
		(layer "In4.Cu")
		(net "CLK_100M_SPRV_DP")
	)
	(segment
		(start 372.820692 -100.431092)
		(end 372.820692 -100.767642)
		(width 0.1143)
		(layer "In4.Cu")
		(net "CLK_100M_SPRV_DP")
	)
	(segment
		(start 414.401254 -82.513424)
		(end 412.501334 -82.513424)
		(width 0.1143)
		(layer "In4.Cu")
		(net "CLK_100M_SPRV_DP")
	)
	(segment
		(start 412.03753 -82.977228)
		(end 405.906986 -82.977228)
		(width 0.1143)
		(layer "In4.Cu")
		(net "CLK_100M_SPRV_DP")
	)
	(segment
		(start 381.1397 -90.356182)
		(end 381.1397 -93.173042)
		(width 0.1143)
		(layer "In4.Cu")
		(net "CLK_100M_SPRV_DP")
	)
	(segment
		(start 405.906986 -82.977228)
		(end 405.750776 -82.821018)
		(width 0.1143)
		(layer "In4.Cu")
		(net "CLK_100M_SPRV_DP")
	)
	(segment
		(start 412.501334 -82.513424)
		(end 412.03753 -82.977228)
		(width 0.1143)
		(layer "In4.Cu")
		(net "CLK_100M_SPRV_DP")
	)
	(segment
		(start 388.616952 -85.79485)
		(end 385.856734 -85.79485)
		(width 0.1143)
		(layer "In4.Cu")
		(net "CLK_100M_SPRV_DP")
	)
	(segment
		(start 405.750776 -82.821018)
		(end 395.451076 -82.821018)
		(width 0.1143)
		(layer "In4.Cu")
		(net "CLK_100M_SPRV_DP")
	)
	(segment
		(start 372.820692 -100.767642)
		(end 372.585742 -101.002592)
		(width 0.1143)
		(layer "In4.Cu")
		(net "CLK_100M_SPRV_DP")
	)
	(segment
		(start 415.24174 -83.35391)
		(end 414.401254 -82.513424)
		(width 0.1143)
		(layer "In4.Cu")
		(net "CLK_100M_SPRV_DP")
	)
	(segment
		(start 394.106908 -84.165186)
		(end 394.106908 -84.703666)
		(width 0.1143)
		(layer "In4.Cu")
		(net "CLK_100M_SPRV_DP")
	)
	(segment
		(start 375.412 -96.932242)
		(end 375.412 -98.6028)
		(width 0.1143)
		(layer "In4.Cu")
		(net "CLK_100M_SPRV_DP")
	)
	(segment
		(start 418.216588 -73.179178)
		(end 418.216588 -81.712054)
		(width 0.1143)
		(layer "In4.Cu")
		(net "CLK_100M_SPRV_DP")
	)
	(segment
		(start 419.873176 -71.52259)
		(end 418.216588 -73.179178)
		(width 0.1143)
		(layer "In4.Cu")
		(net "CLK_100M_SPRV_DP")
	)
	(segment
		(start 421.004492 -71.0946)
		(end 421.004492 -71.40829)
		(width 0.1143)
		(layer "In4.Cu")
		(net "CLK_100M_SPRV_DP")
	)
	(segment
		(start 373.1006 -98.8314)
		(end 372.5926 -99.3394)
		(width 0.1143)
		(layer "In4.Cu")
		(net "CLK_100M_SPRV_DP")
	)
	(segment
		(start 375.412 -98.6028)
		(end 375.1834 -98.8314)
		(width 0.1143)
		(layer "In4.Cu")
		(net "CLK_100M_SPRV_DP")
	)
	(segment
		(start 395.451076 -82.821018)
		(end 394.106908 -84.165186)
		(width 0.1143)
		(layer "In4.Cu")
		(net "CLK_100M_SPRV_DP")
	)
	(segment
		(start 377.513342 -94.3737)
		(end 376.555 -95.332042)
		(width 0.1143)
		(layer "In4.Cu")
		(net "CLK_100M_SPRV_DP")
	)
	(segment
		(start 385.856734 -85.79485)
		(end 383.281682 -88.369902)
		(width 0.1143)
		(layer "In4.Cu")
		(net "CLK_100M_SPRV_DP")
	)
	(segment
		(start 372.5926 -99.3394)
		(end 372.5926 -100.203)
		(width 0.1143)
		(layer "In4.Cu")
		(net "CLK_100M_SPRV_DP")
	)
	(segment
		(start 420.890192 -71.52259)
		(end 419.873176 -71.52259)
		(width 0.1143)
		(layer "In4.Cu")
		(net "CLK_100M_SPRV_DP")
	)
	(segment
		(start 383.281682 -88.369902)
		(end 383.281682 -88.369648)
		(width 0.1143)
		(layer "In4.Cu")
		(net "CLK_100M_SPRV_DP")
	)
	(segment
		(start 383.281682 -88.369648)
		(end 383.281428 -88.369902)
		(width 0.1143)
		(layer "In4.Cu")
		(net "CLK_100M_SPRV_DP")
	)
	(segment
		(start 416.574732 -83.35391)
		(end 415.24174 -83.35391)
		(width 0.1143)
		(layer "In4.Cu")
		(net "CLK_100M_SPRV_DP")
	)
	(segment
		(start 372.5926 -100.203)
		(end 372.820692 -100.431092)
		(width 0.1143)
		(layer "In4.Cu")
		(net "CLK_100M_SPRV_DP")
	)
	(segment
		(start 376.555 -95.332042)
		(end 376.555 -95.789242)
		(width 0.1143)
		(layer "In4.Cu")
		(net "CLK_100M_SPRV_DP")
	)
	(segment
		(start 381.1397 -93.173042)
		(end 379.939042 -94.3737)
		(width 0.1143)
		(layer "In4.Cu")
		(net "CLK_100M_SPRV_DP")
	)
	(segment
		(start 383.12598 -88.369902)
		(end 381.1397 -90.356182)
		(width 0.1143)
		(layer "In4.Cu")
		(net "CLK_100M_SPRV_DP")
	)
	(segment
		(start 375.1834 -98.8314)
		(end 373.1006 -98.8314)
		(width 0.1143)
		(layer "In4.Cu")
		(net "CLK_100M_SPRV_DP")
	)
	(segment
		(start 379.939042 -94.3737)
		(end 377.513342 -94.3737)
		(width 0.1143)
		(layer "In4.Cu")
		(net "CLK_100M_SPRV_DP")
	)
	(segment
		(start 393.364974 -85.4456)
		(end 388.966202 -85.4456)
		(width 0.1143)
		(layer "In4.Cu")
		(net "CLK_100M_SPRV_DP")
	)
	(segment
		(start 422.970706 -69.443092)
		(end 422.246806 -70.166992)
		(width 0.127)
		(layer "F.Cu")
		(net "CLK_100M_SPRV_DN")
	)
	(segment
		(start 430.1998 -55.2704)
		(end 425.72559 -59.74461)
		(width 0.127)
		(layer "F.Cu")
		(net "CLK_100M_SPRV_DN")
	)
	(segment
		(start 374.897142 -101.635052)
		(end 374.74779 -101.4857)
		(width 0.0889)
		(layer "F.Cu")
		(net "CLK_100M_SPRV_DN")
	)
	(segment
		(start 483.90048 -49.620932)
		(end 483.238302 -50.28311)
		(width 0.127)
		(layer "F.Cu")
		(net "CLK_100M_SPRV_DN")
	)
	(segment
		(start 484.001064 -48.3362)
		(end 484.001064 -48.865536)
		(width 0.127)
		(layer "F.Cu")
		(net "CLK_100M_SPRV_DN")
	)
	(segment
		(start 482.879654 -50.641758)
		(end 482.8794 -50.641758)
		(width 0.127)
		(layer "F.Cu")
		(net "CLK_100M_SPRV_DN")
	)
	(segment
		(start 483.238302 -50.28311)
		(end 483.231952 -50.28946)
		(width 0.127)
		(layer "F.Cu")
		(net "CLK_100M_SPRV_DN")
	)
	(segment
		(start 425.72559 -59.74461)
		(end 425.348654 -59.74461)
		(width 0.127)
		(layer "F.Cu")
		(net "CLK_100M_SPRV_DN")
	)
	(segment
		(start 446.971928 -55.603394)
		(end 439.925714 -55.603394)
		(width 0.127)
		(layer "F.Cu")
		(net "CLK_100M_SPRV_DN")
	)
	(segment
		(start 469.901524 -54.97576)
		(end 468.710264 -56.16702)
		(width 0.127)
		(layer "F.Cu")
		(net "CLK_100M_SPRV_DN")
	)
	(segment
		(start 482.8794 -50.641758)
		(end 482.8794 -55.459884)
		(width 0.127)
		(layer "F.Cu")
		(net "CLK_100M_SPRV_DN")
	)
	(segment
		(start 375.504964 -101.855016)
		(end 374.897142 -101.635052)
		(width 0.0889)
		(layer "F.Cu")
		(net "CLK_100M_SPRV_DN")
	)
	(segment
		(start 421.004492 -72.009)
		(end 421.004492 -72.3646)
		(width 0.127)
		(layer "F.Cu")
		(net "CLK_100M_SPRV_DN")
	)
	(segment
		(start 424.359832 -60.733432)
		(end 424.359832 -63.383414)
		(width 0.127)
		(layer "F.Cu")
		(net "CLK_100M_SPRV_DN")
	)
	(segment
		(start 447.535554 -56.16702)
		(end 446.971928 -55.603394)
		(width 0.127)
		(layer "F.Cu")
		(net "CLK_100M_SPRV_DN")
	)
	(segment
		(start 483.90048 -48.96612)
		(end 483.90048 -49.620932)
		(width 0.127)
		(layer "F.Cu")
		(net "CLK_100M_SPRV_DN")
	)
	(segment
		(start 425.348654 -59.74461)
		(end 424.359832 -60.733432)
		(width 0.127)
		(layer "F.Cu")
		(net "CLK_100M_SPRV_DN")
	)
	(segment
		(start 422.970706 -64.77254)
		(end 422.970706 -69.443092)
		(width 0.127)
		(layer "F.Cu")
		(net "CLK_100M_SPRV_DN")
	)
	(segment
		(start 483.231698 -50.28946)
		(end 482.879654 -50.641758)
		(width 0.127)
		(layer "F.Cu")
		(net "CLK_100M_SPRV_DN")
	)
	(segment
		(start 373.2403 -101.4857)
		(end 373.1514 -101.3968)
		(width 0.0889)
		(layer "F.Cu")
		(net "CLK_100M_SPRV_DN")
	)
	(segment
		(start 373.1514 -101.198934)
		(end 373.347742 -101.002592)
		(width 0.0889)
		(layer "F.Cu")
		(net "CLK_100M_SPRV_DN")
	)
	(segment
		(start 439.649108 -55.88)
		(end 436.042308 -55.88)
		(width 0.127)
		(layer "F.Cu")
		(net "CLK_100M_SPRV_DN")
	)
	(segment
		(start 422.246806 -70.166992)
		(end 422.246806 -71.228966)
		(width 0.127)
		(layer "F.Cu")
		(net "CLK_100M_SPRV_DN")
	)
	(segment
		(start 468.710264 -56.16702)
		(end 447.535554 -56.16702)
		(width 0.127)
		(layer "F.Cu")
		(net "CLK_100M_SPRV_DN")
	)
	(segment
		(start 482.8794 -55.459884)
		(end 482.103684 -56.2356)
		(width 0.127)
		(layer "F.Cu")
		(net "CLK_100M_SPRV_DN")
	)
	(segment
		(start 482.103684 -56.2356)
		(end 476.65005 -56.2356)
		(width 0.127)
		(layer "F.Cu")
		(net "CLK_100M_SPRV_DN")
	)
	(segment
		(start 424.359832 -63.383414)
		(end 422.970706 -64.77254)
		(width 0.127)
		(layer "F.Cu")
		(net "CLK_100M_SPRV_DN")
	)
	(segment
		(start 421.131492 -71.882)
		(end 421.004492 -72.009)
		(width 0.127)
		(layer "F.Cu")
		(net "CLK_100M_SPRV_DN")
	)
	(segment
		(start 374.74779 -101.4857)
		(end 373.2403 -101.4857)
		(width 0.0889)
		(layer "F.Cu")
		(net "CLK_100M_SPRV_DN")
	)
	(segment
		(start 422.246806 -71.228966)
		(end 421.593772 -71.882)
		(width 0.127)
		(layer "F.Cu")
		(net "CLK_100M_SPRV_DN")
	)
	(segment
		(start 483.231952 -50.28946)
		(end 483.231698 -50.28946)
		(width 0.127)
		(layer "F.Cu")
		(net "CLK_100M_SPRV_DN")
	)
	(segment
		(start 421.593772 -71.882)
		(end 421.131492 -71.882)
		(width 0.127)
		(layer "F.Cu")
		(net "CLK_100M_SPRV_DN")
	)
	(segment
		(start 435.432708 -55.2704)
		(end 430.1998 -55.2704)
		(width 0.127)
		(layer "F.Cu")
		(net "CLK_100M_SPRV_DN")
	)
	(segment
		(start 476.65005 -56.2356)
		(end 475.39021 -54.97576)
		(width 0.127)
		(layer "F.Cu")
		(net "CLK_100M_SPRV_DN")
	)
	(segment
		(start 484.001064 -48.865536)
		(end 483.90048 -48.96612)
		(width 0.127)
		(layer "F.Cu")
		(net "CLK_100M_SPRV_DN")
	)
	(segment
		(start 475.39021 -54.97576)
		(end 469.901524 -54.97576)
		(width 0.127)
		(layer "F.Cu")
		(net "CLK_100M_SPRV_DN")
	)
	(segment
		(start 373.1514 -101.3968)
		(end 373.1514 -101.198934)
		(width 0.0889)
		(layer "F.Cu")
		(net "CLK_100M_SPRV_DN")
	)
	(segment
		(start 436.042308 -55.88)
		(end 435.432708 -55.2704)
		(width 0.127)
		(layer "F.Cu")
		(net "CLK_100M_SPRV_DN")
	)
	(segment
		(start 439.925714 -55.603394)
		(end 439.649108 -55.88)
		(width 0.127)
		(layer "F.Cu")
		(net "CLK_100M_SPRV_DN")
	)
	(via
		(at 483.238302 -50.28311)
		(size 0.508)
		(drill 0.254)
		(layers "F.Cu" "B.Cu")
		(net "CLK_100M_SPRV_DN")
	)
	(via
		(at 373.347742 -101.002592)
		(size 0.508)
		(drill 0.254)
		(layers "F.Cu" "B.Cu")
		(net "CLK_100M_SPRV_DN")
	)
	(via
		(at 421.004492 -72.3646)
		(size 0.508)
		(drill 0.254)
		(layers "F.Cu" "B.Cu")
		(net "CLK_100M_SPRV_DN")
	)
	(segment
		(start 393.486132 -85.7377)
		(end 389.08736 -85.7377)
		(width 0.1143)
		(layer "In4.Cu")
		(net "CLK_100M_SPRV_DN")
	)
	(segment
		(start 412.158688 -83.269328)
		(end 405.785828 -83.269328)
		(width 0.1143)
		(layer "In4.Cu")
		(net "CLK_100M_SPRV_DN")
	)
	(segment
		(start 412.622492 -82.805524)
		(end 412.158688 -83.269328)
		(width 0.1143)
		(layer "In4.Cu")
		(net "CLK_100M_SPRV_DN")
	)
	(segment
		(start 383.402586 -88.662002)
		(end 383.247138 -88.662002)
		(width 0.1143)
		(layer "In4.Cu")
		(net "CLK_100M_SPRV_DN")
	)
	(segment
		(start 376.8471 -95.9104)
		(end 375.7041 -97.0534)
		(width 0.1143)
		(layer "In4.Cu")
		(net "CLK_100M_SPRV_DN")
	)
	(segment
		(start 419.994334 -71.81469)
		(end 418.508688 -73.300336)
		(width 0.1143)
		(layer "In4.Cu")
		(net "CLK_100M_SPRV_DN")
	)
	(segment
		(start 418.508688 -73.300336)
		(end 418.508688 -81.833212)
		(width 0.1143)
		(layer "In4.Cu")
		(net "CLK_100M_SPRV_DN")
	)
	(segment
		(start 416.69589 -83.64601)
		(end 415.120582 -83.64601)
		(width 0.1143)
		(layer "In4.Cu")
		(net "CLK_100M_SPRV_DN")
	)
	(segment
		(start 373.221758 -99.1235)
		(end 372.8847 -99.460558)
		(width 0.1143)
		(layer "In4.Cu")
		(net "CLK_100M_SPRV_DN")
	)
	(segment
		(start 385.977892 -86.08695)
		(end 383.488184 -88.576404)
		(width 0.1143)
		(layer "In4.Cu")
		(net "CLK_100M_SPRV_DN")
	)
	(segment
		(start 373.112792 -100.309934)
		(end 373.112792 -100.767642)
		(width 0.1143)
		(layer "In4.Cu")
		(net "CLK_100M_SPRV_DN")
	)
	(segment
		(start 418.508688 -81.833212)
		(end 416.69589 -83.64601)
		(width 0.1143)
		(layer "In4.Cu")
		(net "CLK_100M_SPRV_DN")
	)
	(segment
		(start 394.399008 -84.824824)
		(end 393.486132 -85.7377)
		(width 0.1143)
		(layer "In4.Cu")
		(net "CLK_100M_SPRV_DN")
	)
	(segment
		(start 394.399008 -84.286344)
		(end 394.399008 -84.824824)
		(width 0.1143)
		(layer "In4.Cu")
		(net "CLK_100M_SPRV_DN")
	)
	(segment
		(start 381.4318 -93.2942)
		(end 380.0602 -94.6658)
		(width 0.1143)
		(layer "In4.Cu")
		(net "CLK_100M_SPRV_DN")
	)
	(segment
		(start 383.247138 -88.662002)
		(end 381.4318 -90.47734)
		(width 0.1143)
		(layer "In4.Cu")
		(net "CLK_100M_SPRV_DN")
	)
	(segment
		(start 421.004492 -72.3646)
		(end 421.004492 -71.92899)
		(width 0.1143)
		(layer "In4.Cu")
		(net "CLK_100M_SPRV_DN")
	)
	(segment
		(start 375.304558 -99.1235)
		(end 373.221758 -99.1235)
		(width 0.1143)
		(layer "In4.Cu")
		(net "CLK_100M_SPRV_DN")
	)
	(segment
		(start 380.0602 -94.6658)
		(end 377.6345 -94.6658)
		(width 0.1143)
		(layer "In4.Cu")
		(net "CLK_100M_SPRV_DN")
	)
	(segment
		(start 377.6345 -94.6658)
		(end 376.8471 -95.4532)
		(width 0.1143)
		(layer "In4.Cu")
		(net "CLK_100M_SPRV_DN")
	)
	(segment
		(start 421.004492 -71.92899)
		(end 420.890192 -71.81469)
		(width 0.1143)
		(layer "In4.Cu")
		(net "CLK_100M_SPRV_DN")
	)
	(segment
		(start 373.112792 -100.767642)
		(end 373.347742 -101.002592)
		(width 0.1143)
		(layer "In4.Cu")
		(net "CLK_100M_SPRV_DN")
	)
	(segment
		(start 405.785828 -83.269328)
		(end 405.629618 -83.113118)
		(width 0.1143)
		(layer "In4.Cu")
		(net "CLK_100M_SPRV_DN")
	)
	(segment
		(start 395.572234 -83.113118)
		(end 394.399008 -84.286344)
		(width 0.1143)
		(layer "In4.Cu")
		(net "CLK_100M_SPRV_DN")
	)
	(segment
		(start 388.73811 -86.08695)
		(end 385.977892 -86.08695)
		(width 0.1143)
		(layer "In4.Cu")
		(net "CLK_100M_SPRV_DN")
	)
	(segment
		(start 376.8471 -95.4532)
		(end 376.8471 -95.9104)
		(width 0.1143)
		(layer "In4.Cu")
		(net "CLK_100M_SPRV_DN")
	)
	(segment
		(start 375.7041 -98.723958)
		(end 375.304558 -99.1235)
		(width 0.1143)
		(layer "In4.Cu")
		(net "CLK_100M_SPRV_DN")
	)
	(segment
		(start 420.890192 -71.81469)
		(end 419.994334 -71.81469)
		(width 0.1143)
		(layer "In4.Cu")
		(net "CLK_100M_SPRV_DN")
	)
	(segment
		(start 414.280096 -82.805524)
		(end 412.622492 -82.805524)
		(width 0.1143)
		(layer "In4.Cu")
		(net "CLK_100M_SPRV_DN")
	)
	(segment
		(start 415.120582 -83.64601)
		(end 414.280096 -82.805524)
		(width 0.1143)
		(layer "In4.Cu")
		(net "CLK_100M_SPRV_DN")
	)
	(segment
		(start 381.4318 -90.47734)
		(end 381.4318 -93.2942)
		(width 0.1143)
		(layer "In4.Cu")
		(net "CLK_100M_SPRV_DN")
	)
	(segment
		(start 372.8847 -99.460558)
		(end 372.8847 -100.081842)
		(width 0.1143)
		(layer "In4.Cu")
		(net "CLK_100M_SPRV_DN")
	)
	(segment
		(start 383.488184 -88.576404)
		(end 383.402586 -88.662002)
		(width 0.1143)
		(layer "In4.Cu")
		(net "CLK_100M_SPRV_DN")
	)
	(segment
		(start 405.629618 -83.113118)
		(end 395.572234 -83.113118)
		(width 0.1143)
		(layer "In4.Cu")
		(net "CLK_100M_SPRV_DN")
	)
	(segment
		(start 375.7041 -97.0534)
		(end 375.7041 -98.723958)
		(width 0.1143)
		(layer "In4.Cu")
		(net "CLK_100M_SPRV_DN")
	)
	(segment
		(start 389.08736 -85.7377)
		(end 388.73811 -86.08695)
		(width 0.1143)
		(layer "In4.Cu")
		(net "CLK_100M_SPRV_DN")
	)
	(segment
		(start 372.8847 -100.081842)
		(end 373.112792 -100.309934)
		(width 0.1143)
		(layer "In4.Cu")
		(net "CLK_100M_SPRV_DN")
	)
	(segment
		(start 491.1471 -47.215298)
		(end 491.1471 -46.7614)
		(width 0.10795)
		(layer "F.Cu")
		(net "SPI_NIC_SCLK")
	)
	(segment
		(start 490.940598 -47.4218)
		(end 491.1471 -47.215298)
		(width 0.10795)
		(layer "F.Cu")
		(net "SPI_NIC_SCLK")
	)
	(via
		(at 491.301024 -25.262586)
		(size 0.508)
		(drill 0.254)
		(layers "F.Cu" "B.Cu")
		(net "SPI_NIC_SCLK")
	)
	(via
		(at 490.940598 -47.4218)
		(size 0.508)
		(drill 0.254)
		(layers "F.Cu" "B.Cu")
		(net "SPI_NIC_SCLK")
	)
	(segment
		(start 489.179616 -25.262586)
		(end 488.538266 -25.903936)
		(width 0.10795)
		(layer "B.Cu")
		(net "SPI_NIC_SCLK")
	)
	(segment
		(start 488.538266 -25.903936)
		(end 488.538266 -26.76398)
		(width 0.10795)
		(layer "B.Cu")
		(net "SPI_NIC_SCLK")
	)
	(segment
		(start 491.301024 -25.262586)
		(end 489.179616 -25.262586)
		(width 0.10795)
		(layer "B.Cu")
		(net "SPI_NIC_SCLK")
	)
	(segment
		(start 490.940598 -45.797978)
		(end 490.940598 -47.4218)
		(width 0.089408)
		(layer "In11.Cu")
		(net "SPI_NIC_SCLK")
	)
	(segment
		(start 491.236 -39.979346)
		(end 491.236 -45.502576)
		(width 0.089408)
		(layer "In11.Cu")
		(net "SPI_NIC_SCLK")
	)
	(segment
		(start 489.911898 -38.655244)
		(end 491.236 -39.979346)
		(width 0.089408)
		(layer "In11.Cu")
		(net "SPI_NIC_SCLK")
	)
	(segment
		(start 491.857538 -26.54427)
		(end 491.857538 -27.829002)
		(width 0.089408)
		(layer "In11.Cu")
		(net "SPI_NIC_SCLK")
	)
	(segment
		(start 491.301024 -25.262586)
		(end 491.49 -25.451562)
		(width 0.089408)
		(layer "In11.Cu")
		(net "SPI_NIC_SCLK")
	)
	(segment
		(start 491.236 -45.502576)
		(end 490.940598 -45.797978)
		(width 0.089408)
		(layer "In11.Cu")
		(net "SPI_NIC_SCLK")
	)
	(segment
		(start 490.674406 -34.935922)
		(end 489.911898 -35.69843)
		(width 0.089408)
		(layer "In11.Cu")
		(net "SPI_NIC_SCLK")
	)
	(segment
		(start 491.49 -26.176732)
		(end 491.857538 -26.54427)
		(width 0.089408)
		(layer "In11.Cu")
		(net "SPI_NIC_SCLK")
	)
	(segment
		(start 490.18698 -29.49956)
		(end 490.18698 -31.252414)
		(width 0.089408)
		(layer "In11.Cu")
		(net "SPI_NIC_SCLK")
	)
	(segment
		(start 489.911898 -35.69843)
		(end 489.911898 -38.655244)
		(width 0.089408)
		(layer "In11.Cu")
		(net "SPI_NIC_SCLK")
	)
	(segment
		(start 490.18698 -31.252414)
		(end 490.674406 -31.73984)
		(width 0.089408)
		(layer "In11.Cu")
		(net "SPI_NIC_SCLK")
	)
	(segment
		(start 491.49 -25.451562)
		(end 491.49 -26.176732)
		(width 0.089408)
		(layer "In11.Cu")
		(net "SPI_NIC_SCLK")
	)
	(segment
		(start 490.674406 -31.73984)
		(end 490.674406 -34.935922)
		(width 0.089408)
		(layer "In11.Cu")
		(net "SPI_NIC_SCLK")
	)
	(segment
		(start 491.857538 -27.829002)
		(end 490.18698 -29.49956)
		(width 0.089408)
		(layer "In11.Cu")
		(net "SPI_NIC_SCLK")
	)
	(segment
		(start 491.3376 -45.085)
		(end 491.6424 -44.7802)
		(width 0.10795)
		(layer "F.Cu")
		(net "SPI_NIC_MOSI")
	)
	(segment
		(start 491.1471 -45.670724)
		(end 491.3376 -45.480224)
		(width 0.10795)
		(layer "F.Cu")
		(net "SPI_NIC_MOSI")
	)
	(segment
		(start 491.1471 -45.9994)
		(end 491.1471 -45.670724)
		(width 0.10795)
		(layer "F.Cu")
		(net "SPI_NIC_MOSI")
	)
	(segment
		(start 491.3376 -45.480224)
		(end 491.3376 -45.085)
		(width 0.10795)
		(layer "F.Cu")
		(net "SPI_NIC_MOSI")
	)
	(via
		(at 491.214156 -24.39416)
		(size 0.508)
		(drill 0.254)
		(layers "F.Cu" "B.Cu")
		(net "SPI_NIC_MOSI")
	)
	(via
		(at 491.6424 -44.7802)
		(size 0.508)
		(drill 0.254)
		(layers "F.Cu" "B.Cu")
		(net "SPI_NIC_MOSI")
	)
	(via
		(at 491.5662 -43.8404)
		(size 0.6604)
		(drill 0.3302)
		(layers "F.Cu" "B.Cu")
		(net "SPI_NIC_MOSI")
	)
	(segment
		(start 488.09148 -28.4226)
		(end 487.160062 -28.4226)
		(width 0.10795)
		(layer "B.Cu")
		(net "SPI_NIC_MOSI")
	)
	(segment
		(start 487.160062 -28.079192)
		(end 487.268266 -27.970988)
		(width 0.10795)
		(layer "B.Cu")
		(net "SPI_NIC_MOSI")
	)
	(segment
		(start 487.160062 -28.4226)
		(end 487.160062 -28.079192)
		(width 0.10795)
		(layer "B.Cu")
		(net "SPI_NIC_MOSI")
	)
	(segment
		(start 488.24134 -24.78786)
		(end 488.604306 -24.78786)
		(width 0.10795)
		(layer "B.Cu")
		(net "SPI_NIC_MOSI")
	)
	(segment
		(start 488.998006 -24.39416)
		(end 491.214156 -24.39416)
		(width 0.10795)
		(layer "B.Cu")
		(net "SPI_NIC_MOSI")
	)
	(segment
		(start 488.604306 -24.78786)
		(end 488.998006 -24.39416)
		(width 0.10795)
		(layer "B.Cu")
		(net "SPI_NIC_MOSI")
	)
	(segment
		(start 487.268266 -27.970988)
		(end 487.268266 -26.76398)
		(width 0.10795)
		(layer "B.Cu")
		(net "SPI_NIC_MOSI")
	)
	(segment
		(start 487.268266 -26.76398)
		(end 487.268266 -25.760934)
		(width 0.10795)
		(layer "B.Cu")
		(net "SPI_NIC_MOSI")
	)
	(segment
		(start 491.5662 -44.704)
		(end 491.5662 -43.8404)
		(width 0.10795)
		(layer "B.Cu")
		(net "SPI_NIC_MOSI")
	)
	(segment
		(start 487.268266 -25.760934)
		(end 488.24134 -24.78786)
		(width 0.10795)
		(layer "B.Cu")
		(net "SPI_NIC_MOSI")
	)
	(segment
		(start 491.6424 -44.7802)
		(end 491.5662 -44.704)
		(width 0.10795)
		(layer "B.Cu")
		(net "SPI_NIC_MOSI")
	)
	(segment
		(start 492.150146 -26.422858)
		(end 491.782608 -26.05532)
		(width 0.089408)
		(layer "In11.Cu")
		(net "SPI_NIC_MOSI")
	)
	(segment
		(start 491.782608 -26.05532)
		(end 491.782608 -24.962612)
		(width 0.089408)
		(layer "In11.Cu")
		(net "SPI_NIC_MOSI")
	)
	(segment
		(start 490.967014 -35.093656)
		(end 490.967014 -31.618428)
		(width 0.089408)
		(layer "In11.Cu")
		(net "SPI_NIC_MOSI")
	)
	(segment
		(start 491.6424 -39.9034)
		(end 490.204506 -38.465506)
		(width 0.089408)
		(layer "In11.Cu")
		(net "SPI_NIC_MOSI")
	)
	(segment
		(start 492.150146 -27.950414)
		(end 492.150146 -26.422858)
		(width 0.089408)
		(layer "In11.Cu")
		(net "SPI_NIC_MOSI")
	)
	(segment
		(start 491.6424 -44.7802)
		(end 491.6424 -39.9034)
		(width 0.089408)
		(layer "In11.Cu")
		(net "SPI_NIC_MOSI")
	)
	(segment
		(start 490.967014 -31.618428)
		(end 490.479588 -31.131002)
		(width 0.089408)
		(layer "In11.Cu")
		(net "SPI_NIC_MOSI")
	)
	(segment
		(start 490.204506 -38.465506)
		(end 490.204506 -35.856164)
		(width 0.089408)
		(layer "In11.Cu")
		(net "SPI_NIC_MOSI")
	)
	(segment
		(start 491.782608 -24.962612)
		(end 491.214156 -24.39416)
		(width 0.089408)
		(layer "In11.Cu")
		(net "SPI_NIC_MOSI")
	)
	(segment
		(start 490.479588 -29.620972)
		(end 492.150146 -27.950414)
		(width 0.089408)
		(layer "In11.Cu")
		(net "SPI_NIC_MOSI")
	)
	(segment
		(start 490.479588 -31.131002)
		(end 490.479588 -29.620972)
		(width 0.089408)
		(layer "In11.Cu")
		(net "SPI_NIC_MOSI")
	)
	(segment
		(start 490.204506 -35.856164)
		(end 490.967014 -35.093656)
		(width 0.089408)
		(layer "In11.Cu")
		(net "SPI_NIC_MOSI")
	)
	(segment
		(start 491.1471 -49.0093)
		(end 491.1471 -48.2854)
		(width 0.10795)
		(layer "F.Cu")
		(net "SPI_NIC_MISO_R")
	)
	(segment
		(start 491.2614 -49.1236)
		(end 491.1471 -49.0093)
		(width 0.10795)
		(layer "F.Cu")
		(net "SPI_NIC_MISO_R")
	)
	(via
		(at 493.68964 -24.93772)
		(size 0.508)
		(drill 0.254)
		(layers "F.Cu" "B.Cu")
		(net "SPI_NIC_MISO_R")
	)
	(via
		(at 491.2614 -49.1236)
		(size 0.508)
		(drill 0.254)
		(layers "F.Cu" "B.Cu")
		(net "SPI_NIC_MISO_R")
	)
	(segment
		(start 493.035336 -24.283416)
		(end 493.68964 -24.93772)
		(width 0.10795)
		(layer "B.Cu")
		(net "SPI_NIC_MISO_R")
	)
	(segment
		(start 489.808266 -22.163532)
		(end 491.92815 -24.283416)
		(width 0.10795)
		(layer "B.Cu")
		(net "SPI_NIC_MISO_R")
	)
	(segment
		(start 491.92815 -24.283416)
		(end 493.035336 -24.283416)
		(width 0.10795)
		(layer "B.Cu")
		(net "SPI_NIC_MISO_R")
	)
	(segment
		(start 489.808266 -20.00758)
		(end 489.808266 -22.163532)
		(width 0.10795)
		(layer "B.Cu")
		(net "SPI_NIC_MISO_R")
	)
	(segment
		(start 499.702074 -28.751276)
		(end 500.596662 -29.645864)
		(width 0.089408)
		(layer "In2.Cu")
		(net "SPI_NIC_MISO_R")
	)
	(segment
		(start 491.2614 -49.1236)
		(end 491.2614 -48.730662)
		(width 0.089408)
		(layer "In2.Cu")
		(net "SPI_NIC_MISO_R")
	)
	(segment
		(start 496.395502 -25.72512)
		(end 496.48491 -25.814528)
		(width 0.089408)
		(layer "In2.Cu")
		(net "SPI_NIC_MISO_R")
	)
	(segment
		(start 496.48491 -25.814528)
		(end 496.48491 -26.52395)
		(width 0.089408)
		(layer "In2.Cu")
		(net "SPI_NIC_MISO_R")
	)
	(segment
		(start 500.596662 -32.893)
		(end 499.080282 -34.40938)
		(width 0.089408)
		(layer "In2.Cu")
		(net "SPI_NIC_MISO_R")
	)
	(segment
		(start 496.620292 -44.501308)
		(end 494.9952 -46.1264)
		(width 0.089408)
		(layer "In2.Cu")
		(net "SPI_NIC_MISO_R")
	)
	(segment
		(start 498.712236 -28.751276)
		(end 499.702074 -28.751276)
		(width 0.089408)
		(layer "In2.Cu")
		(net "SPI_NIC_MISO_R")
	)
	(segment
		(start 491.2614 -48.730662)
		(end 493.865662 -46.1264)
		(width 0.089408)
		(layer "In2.Cu")
		(net "SPI_NIC_MISO_R")
	)
	(segment
		(start 496.620292 -36.179506)
		(end 496.620292 -44.501308)
		(width 0.089408)
		(layer "In2.Cu")
		(net "SPI_NIC_MISO_R")
	)
	(segment
		(start 494.47704 -25.72512)
		(end 496.395502 -25.72512)
		(width 0.089408)
		(layer "In2.Cu")
		(net "SPI_NIC_MISO_R")
	)
	(segment
		(start 496.48491 -26.52395)
		(end 498.712236 -28.751276)
		(width 0.089408)
		(layer "In2.Cu")
		(net "SPI_NIC_MISO_R")
	)
	(segment
		(start 493.68964 -24.93772)
		(end 494.47704 -25.72512)
		(width 0.089408)
		(layer "In2.Cu")
		(net "SPI_NIC_MISO_R")
	)
	(segment
		(start 500.596662 -29.645864)
		(end 500.596662 -32.893)
		(width 0.089408)
		(layer "In2.Cu")
		(net "SPI_NIC_MISO_R")
	)
	(segment
		(start 493.865662 -46.1264)
		(end 494.9952 -46.1264)
		(width 0.089408)
		(layer "In2.Cu")
		(net "SPI_NIC_MISO_R")
	)
	(segment
		(start 499.080282 -34.40938)
		(end 498.390418 -34.40938)
		(width 0.089408)
		(layer "In2.Cu")
		(net "SPI_NIC_MISO_R")
	)
	(segment
		(start 498.390418 -34.40938)
		(end 496.620292 -36.179506)
		(width 0.089408)
		(layer "In2.Cu")
		(net "SPI_NIC_MISO_R")
	)
	(segment
		(start 491.6043 -49.8094)
		(end 492.0234 -49.8094)
		(width 0.10795)
		(layer "F.Cu")
		(net "SPI_NIC_CS_N")
	)
	(segment
		(start 492.0234 -49.8094)
		(end 492.6076 -50.3936)
		(width 0.10795)
		(layer "F.Cu")
		(net "SPI_NIC_CS_N")
	)
	(via
		(at 494.47958 -24.9301)
		(size 0.508)
		(drill 0.254)
		(layers "F.Cu" "B.Cu")
		(net "SPI_NIC_CS_N")
	)
	(via
		(at 492.6076 -50.3936)
		(size 0.508)
		(drill 0.254)
		(layers "F.Cu" "B.Cu")
		(net "SPI_NIC_CS_N")
	)
	(segment
		(start 494.410746 -24.9301)
		(end 494.47958 -24.9301)
		(width 0.10795)
		(layer "B.Cu")
		(net "SPI_NIC_CS_N")
	)
	(segment
		(start 491.078266 -20.00758)
		(end 491.078266 -22.921468)
		(width 0.10795)
		(layer "B.Cu")
		(net "SPI_NIC_CS_N")
	)
	(segment
		(start 492.078264 -23.921466)
		(end 493.402112 -23.921466)
		(width 0.10795)
		(layer "B.Cu")
		(net "SPI_NIC_CS_N")
	)
	(segment
		(start 493.402112 -23.921466)
		(end 494.410746 -24.9301)
		(width 0.10795)
		(layer "B.Cu")
		(net "SPI_NIC_CS_N")
	)
	(segment
		(start 491.078266 -22.921468)
		(end 492.078264 -23.921466)
		(width 0.10795)
		(layer "B.Cu")
		(net "SPI_NIC_CS_N")
	)
	(segment
		(start 492.105696 -49.891696)
		(end 492.6076 -50.3936)
		(width 0.089408)
		(layer "In2.Cu")
		(net "SPI_NIC_CS_N")
	)
	(segment
		(start 496.777518 -26.402538)
		(end 498.833648 -28.458668)
		(width 0.089408)
		(layer "In2.Cu")
		(net "SPI_NIC_CS_N")
	)
	(segment
		(start 496.9129 -44.7675)
		(end 493.9792 -47.7012)
		(width 0.089408)
		(layer "In2.Cu")
		(net "SPI_NIC_CS_N")
	)
	(segment
		(start 499.823486 -28.458668)
		(end 500.88927 -29.524452)
		(width 0.089408)
		(layer "In2.Cu")
		(net "SPI_NIC_CS_N")
	)
	(segment
		(start 494.981992 -25.432512)
		(end 496.516914 -25.432512)
		(width 0.089408)
		(layer "In2.Cu")
		(net "SPI_NIC_CS_N")
	)
	(segment
		(start 499.114572 -34.818828)
		(end 498.482366 -34.818828)
		(width 0.089408)
		(layer "In2.Cu")
		(net "SPI_NIC_CS_N")
	)
	(segment
		(start 500.88927 -33.04413)
		(end 499.114572 -34.818828)
		(width 0.089408)
		(layer "In2.Cu")
		(net "SPI_NIC_CS_N")
	)
	(segment
		(start 493.9792 -47.7012)
		(end 493.141 -47.7012)
		(width 0.089408)
		(layer "In2.Cu")
		(net "SPI_NIC_CS_N")
	)
	(segment
		(start 492.105696 -48.736504)
		(end 492.105696 -49.891696)
		(width 0.089408)
		(layer "In2.Cu")
		(net "SPI_NIC_CS_N")
	)
	(segment
		(start 500.88927 -29.524452)
		(end 500.88927 -33.04413)
		(width 0.089408)
		(layer "In2.Cu")
		(net "SPI_NIC_CS_N")
	)
	(segment
		(start 494.47958 -24.9301)
		(end 494.981992 -25.432512)
		(width 0.089408)
		(layer "In2.Cu")
		(net "SPI_NIC_CS_N")
	)
	(segment
		(start 493.141 -47.7012)
		(end 492.105696 -48.736504)
		(width 0.089408)
		(layer "In2.Cu")
		(net "SPI_NIC_CS_N")
	)
	(segment
		(start 496.516914 -25.432512)
		(end 496.777518 -25.693116)
		(width 0.089408)
		(layer "In2.Cu")
		(net "SPI_NIC_CS_N")
	)
	(segment
		(start 498.482366 -34.818828)
		(end 496.9129 -36.388294)
		(width 0.089408)
		(layer "In2.Cu")
		(net "SPI_NIC_CS_N")
	)
	(segment
		(start 498.833648 -28.458668)
		(end 499.823486 -28.458668)
		(width 0.089408)
		(layer "In2.Cu")
		(net "SPI_NIC_CS_N")
	)
	(segment
		(start 496.777518 -25.693116)
		(end 496.777518 -26.402538)
		(width 0.089408)
		(layer "In2.Cu")
		(net "SPI_NIC_CS_N")
	)
	(segment
		(start 496.9129 -36.388294)
		(end 496.9129 -44.7675)
		(width 0.089408)
		(layer "In2.Cu")
		(net "SPI_NIC_CS_N")
	)
	(segment
		(start 491.413546 -153.68016)
		(end 492.169704 -153.68016)
		(width 0.10795)
		(layer "F.Cu")
		(net "FM_UART_SWITCH_N")
	)
	(segment
		(start 492.169704 -153.68016)
		(end 494.000028 -151.849836)
		(width 0.10795)
		(layer "F.Cu")
		(net "FM_UART_SWITCH_N")
	)
	(via
		(at 471.884248 -141.54023)
		(size 0.508)
		(drill 0.254)
		(layers "F.Cu" "B.Cu")
		(net "FM_UART_SWITCH_N")
	)
	(via
		(at 485.1781 -151.8666)
		(size 0.6604)
		(drill 0.3302)
		(layers "F.Cu" "B.Cu")
		(net "FM_UART_SWITCH_N")
	)
	(via
		(at 485.5845 -150.5712)
		(size 0.508)
		(drill 0.254)
		(layers "F.Cu" "B.Cu")
		(net "FM_UART_SWITCH_N")
	)
	(via
		(at 481.462842 -148.93671)
		(size 0.508)
		(drill 0.254)
		(layers "F.Cu" "B.Cu")
		(net "FM_UART_SWITCH_N")
	)
	(segment
		(start 482.4857 -148.93671)
		(end 481.462842 -148.93671)
		(width 0.10795)
		(layer "B.Cu")
		(net "FM_UART_SWITCH_N")
	)
	(segment
		(start 484.9368 -151.2189)
		(end 485.5845 -150.5712)
		(width 0.10795)
		(layer "B.Cu")
		(net "FM_UART_SWITCH_N")
	)
	(segment
		(start 486.4227 -152.0571)
		(end 486.8672 -151.6126)
		(width 0.10795)
		(layer "B.Cu")
		(net "FM_UART_SWITCH_N")
	)
	(segment
		(start 471.884248 -141.54023)
		(end 472.524328 -141.54023)
		(width 0.10795)
		(layer "B.Cu")
		(net "FM_UART_SWITCH_N")
	)
	(segment
		(start 485.3686 -152.0571)
		(end 486.4227 -152.0571)
		(width 0.10795)
		(layer "B.Cu")
		(net "FM_UART_SWITCH_N")
	)
	(segment
		(start 472.67241 -141.688312)
		(end 473.660216 -141.688312)
		(width 0.10795)
		(layer "B.Cu")
		(net "FM_UART_SWITCH_N")
	)
	(segment
		(start 485.1781 -151.8666)
		(end 485.3686 -152.0571)
		(width 0.10795)
		(layer "B.Cu")
		(net "FM_UART_SWITCH_N")
	)
	(segment
		(start 472.524328 -141.54023)
		(end 472.67241 -141.688312)
		(width 0.10795)
		(layer "B.Cu")
		(net "FM_UART_SWITCH_N")
	)
	(segment
		(start 485.1781 -151.8666)
		(end 484.9368 -151.6253)
		(width 0.10795)
		(layer "B.Cu")
		(net "FM_UART_SWITCH_N")
	)
	(segment
		(start 484.9368 -151.6253)
		(end 484.9368 -151.2189)
		(width 0.10795)
		(layer "B.Cu")
		(net "FM_UART_SWITCH_N")
	)
	(segment
		(start 486.8672 -151.6126)
		(end 487.1085 -151.6126)
		(width 0.10795)
		(layer "B.Cu")
		(net "FM_UART_SWITCH_N")
	)
	(segment
		(start 488.3023 -151.7269)
		(end 487.1466 -150.5712)
		(width 0.089408)
		(layer "In4.Cu")
		(net "FM_UART_SWITCH_N")
	)
	(segment
		(start 491.29188 -150.5839)
		(end 490.14888 -151.7269)
		(width 0.089408)
		(layer "In4.Cu")
		(net "FM_UART_SWITCH_N")
	)
	(segment
		(start 487.1466 -150.5712)
		(end 485.5845 -150.5712)
		(width 0.089408)
		(layer "In4.Cu")
		(net "FM_UART_SWITCH_N")
	)
	(segment
		(start 490.14888 -151.7269)
		(end 488.3023 -151.7269)
		(width 0.089408)
		(layer "In4.Cu")
		(net "FM_UART_SWITCH_N")
	)
	(segment
		(start 481.462842 -148.93671)
		(end 483.95001 -148.93671)
		(width 0.089408)
		(layer "In4.Cu")
		(net "FM_UART_SWITCH_N")
	)
	(segment
		(start 483.95001 -148.93671)
		(end 485.5845 -150.5712)
		(width 0.089408)
		(layer "In4.Cu")
		(net "FM_UART_SWITCH_N")
	)
	(segment
		(start 494.000028 -151.849836)
		(end 492.734092 -150.5839)
		(width 0.089408)
		(layer "In4.Cu")
		(net "FM_UART_SWITCH_N")
	)
	(segment
		(start 492.734092 -150.5839)
		(end 491.29188 -150.5839)
		(width 0.089408)
		(layer "In4.Cu")
		(net "FM_UART_SWITCH_N")
	)
	(segment
		(start 472.709748 -141.54023)
		(end 477.065848 -145.89633)
		(width 0.089408)
		(layer "In11.Cu")
		(net "FM_UART_SWITCH_N")
	)
	(segment
		(start 477.065848 -145.89633)
		(end 477.52381 -145.89633)
		(width 0.089408)
		(layer "In11.Cu")
		(net "FM_UART_SWITCH_N")
	)
	(segment
		(start 471.884248 -141.54023)
		(end 472.709748 -141.54023)
		(width 0.089408)
		(layer "In11.Cu")
		(net "FM_UART_SWITCH_N")
	)
	(segment
		(start 477.52381 -145.89633)
		(end 480.56419 -148.93671)
		(width 0.089408)
		(layer "In11.Cu")
		(net "FM_UART_SWITCH_N")
	)
	(segment
		(start 480.56419 -148.93671)
		(end 481.462842 -148.93671)
		(width 0.089408)
		(layer "In11.Cu")
		(net "FM_UART_SWITCH_N")
	)
	(via
		(at 483.81666 -148.90496)
		(size 0.6604)
		(drill 0.3302)
		(layers "F.Cu" "B.Cu")
		(net "FM_UART_SEL_N")
	)
	(segment
		(start 482.4857 -148.04771)
		(end 481.984812 -148.04771)
		(width 0.10795)
		(layer "B.Cu")
		(net "FM_UART_SEL_N")
	)
	(segment
		(start 481.984812 -148.04771)
		(end 481.9142 -147.977098)
		(width 0.10795)
		(layer "B.Cu")
		(net "FM_UART_SEL_N")
	)
	(segment
		(start 481.9142 -147.977098)
		(end 481.0379 -147.977098)
		(width 0.10795)
		(layer "B.Cu")
		(net "FM_UART_SEL_N")
	)
	(segment
		(start 482.95941 -148.04771)
		(end 482.4857 -148.04771)
		(width 0.10795)
		(layer "B.Cu")
		(net "FM_UART_SEL_N")
	)
	(segment
		(start 483.81666 -148.90496)
		(end 482.95941 -148.04771)
		(width 0.10795)
		(layer "B.Cu")
		(net "FM_UART_SEL_N")
	)
	(via
		(at 481.7872 -140.1826)
		(size 0.6604)
		(drill 0.3302)
		(layers "F.Cu" "B.Cu")
		(net "FM_DB_UART_SEL4_N")
	)
	(segment
		(start 481.7872 -140.4874)
		(end 482.939598 -141.639798)
		(width 0.10795)
		(layer "B.Cu")
		(net "FM_DB_UART_SEL4_N")
	)
	(segment
		(start 482.939598 -141.868398)
		(end 483.3874 -142.3162)
		(width 0.10795)
		(layer "B.Cu")
		(net "FM_DB_UART_SEL4_N")
	)
	(segment
		(start 482.9556 -139.5095)
		(end 483.6795 -139.5095)
		(width 0.10795)
		(layer "B.Cu")
		(net "FM_DB_UART_SEL4_N")
	)
	(segment
		(start 483.3874 -142.3162)
		(end 483.9462 -142.3162)
		(width 0.10795)
		(layer "B.Cu")
		(net "FM_DB_UART_SEL4_N")
	)
	(segment
		(start 481.7872 -140.1826)
		(end 481.7872 -140.4874)
		(width 0.10795)
		(layer "B.Cu")
		(net "FM_DB_UART_SEL4_N")
	)
	(segment
		(start 482.8159 -139.6492)
		(end 482.9556 -139.5095)
		(width 0.10795)
		(layer "B.Cu")
		(net "FM_DB_UART_SEL4_N")
	)
	(segment
		(start 482.939598 -141.639798)
		(end 482.939598 -141.868398)
		(width 0.10795)
		(layer "B.Cu")
		(net "FM_DB_UART_SEL4_N")
	)
	(segment
		(start 482.2698 -139.6492)
		(end 482.8159 -139.6492)
		(width 0.10795)
		(layer "B.Cu")
		(net "FM_DB_UART_SEL4_N")
	)
	(segment
		(start 483.9462 -142.3162)
		(end 484.124 -142.494)
		(width 0.10795)
		(layer "B.Cu")
		(net "FM_DB_UART_SEL4_N")
	)
	(segment
		(start 481.7872 -140.1826)
		(end 481.7872 -140.1318)
		(width 0.10795)
		(layer "B.Cu")
		(net "FM_DB_UART_SEL4_N")
	)
	(segment
		(start 481.7872 -140.1318)
		(end 482.2698 -139.6492)
		(width 0.10795)
		(layer "B.Cu")
		(net "FM_DB_UART_SEL4_N")
	)
	(segment
		(start 484.124 -142.494)
		(end 484.124 -143.4084)
		(width 0.10795)
		(layer "B.Cu")
		(net "FM_DB_UART_SEL4_N")
	)
	(via
		(at 487.553 -141.9606)
		(size 0.6604)
		(drill 0.3302)
		(layers "F.Cu" "B.Cu")
		(net "FM_DB_UART_SEL3_N")
	)
	(segment
		(start 484.124 -145.6182)
		(end 484.9622 -145.6182)
		(width 0.10795)
		(layer "B.Cu")
		(net "FM_DB_UART_SEL3_N")
	)
	(segment
		(start 484.9622 -145.6182)
		(end 487.172 -143.4084)
		(width 0.10795)
		(layer "B.Cu")
		(net "FM_DB_UART_SEL3_N")
	)
	(segment
		(start 487.553 -141.9606)
		(end 487.172 -142.3416)
		(width 0.10795)
		(layer "B.Cu")
		(net "FM_DB_UART_SEL3_N")
	)
	(segment
		(start 487.172 -142.3416)
		(end 487.172 -143.4084)
		(width 0.10795)
		(layer "B.Cu")
		(net "FM_DB_UART_SEL3_N")
	)
	(via
		(at 483.8192 -146.7358)
		(size 0.6604)
		(drill 0.3302)
		(layers "F.Cu" "B.Cu")
		(net "FM_DB_UART_SEL2_N")
	)
	(segment
		(start 483.8192 -146.7358)
		(end 483.8192 -147.5232)
		(width 0.10795)
		(layer "B.Cu")
		(net "FM_DB_UART_SEL2_N")
	)
	(segment
		(start 486.4354 -145.6182)
		(end 487.172 -145.6182)
		(width 0.10795)
		(layer "B.Cu")
		(net "FM_DB_UART_SEL2_N")
	)
	(segment
		(start 484.124 -147.828)
		(end 484.2256 -147.828)
		(width 0.10795)
		(layer "B.Cu")
		(net "FM_DB_UART_SEL2_N")
	)
	(segment
		(start 484.2256 -147.828)
		(end 486.4354 -145.6182)
		(width 0.10795)
		(layer "B.Cu")
		(net "FM_DB_UART_SEL2_N")
	)
	(segment
		(start 483.8192 -147.5232)
		(end 484.124 -147.828)
		(width 0.10795)
		(layer "B.Cu")
		(net "FM_DB_UART_SEL2_N")
	)
	(via
		(at 484.3526 -153.2128)
		(size 0.6604)
		(drill 0.3302)
		(layers "F.Cu" "B.Cu")
		(net "FM_DB_UART_SEL1_N")
	)
	(segment
		(start 484.124 -152.9842)
		(end 484.124 -150.0378)
		(width 0.10795)
		(layer "B.Cu")
		(net "FM_DB_UART_SEL1_N")
	)
	(segment
		(start 484.3526 -153.2128)
		(end 484.124 -152.9842)
		(width 0.10795)
		(layer "B.Cu")
		(net "FM_DB_UART_SEL1_N")
	)
	(segment
		(start 487.172 -148.39188)
		(end 485.52608 -150.0378)
		(width 0.10795)
		(layer "B.Cu")
		(net "FM_DB_UART_SEL1_N")
	)
	(segment
		(start 487.172 -147.828)
		(end 487.172 -148.39188)
		(width 0.10795)
		(layer "B.Cu")
		(net "FM_DB_UART_SEL1_N")
	)
	(segment
		(start 485.52608 -150.0378)
		(end 484.124 -150.0378)
		(width 0.10795)
		(layer "B.Cu")
		(net "FM_DB_UART_SEL1_N")
	)
	(via
		(at 485.94772 -152.888442)
		(size 0.6604)
		(drill 0.3302)
		(layers "F.Cu" "B.Cu")
		(net "FM_DB_UART_SEL0_N")
	)
	(segment
		(start 487.9975 -151.2189)
		(end 487.172 -150.3934)
		(width 0.10795)
		(layer "B.Cu")
		(net "FM_DB_UART_SEL0_N")
	)
	(segment
		(start 487.741468 -152.06091)
		(end 487.9975 -151.804878)
		(width 0.10795)
		(layer "B.Cu")
		(net "FM_DB_UART_SEL0_N")
	)
	(segment
		(start 487.9975 -151.6126)
		(end 487.9975 -151.2189)
		(width 0.10795)
		(layer "B.Cu")
		(net "FM_DB_UART_SEL0_N")
	)
	(segment
		(start 487.172 -150.3934)
		(end 487.172 -150.0378)
		(width 0.10795)
		(layer "B.Cu")
		(net "FM_DB_UART_SEL0_N")
	)
	(segment
		(start 487.9975 -151.804878)
		(end 487.9975 -151.6126)
		(width 0.10795)
		(layer "B.Cu")
		(net "FM_DB_UART_SEL0_N")
	)
	(segment
		(start 486.775252 -152.06091)
		(end 487.741468 -152.06091)
		(width 0.10795)
		(layer "B.Cu")
		(net "FM_DB_UART_SEL0_N")
	)
	(segment
		(start 485.94772 -152.888442)
		(end 486.775252 -152.06091)
		(width 0.10795)
		(layer "B.Cu")
		(net "FM_DB_UART_SEL0_N")
	)
	(via
		(at 489.155232 -142.874492)
		(size 0.6604)
		(drill 0.3302)
		(layers "F.Cu" "B.Cu")
		(net "FM_DB_PRESENT")
	)
	(segment
		(start 489.6104 -141.5034)
		(end 489.839 -141.2748)
		(width 0.10795)
		(layer "B.Cu")
		(net "FM_DB_PRESENT")
	)
	(segment
		(start 488.806998 -141.792198)
		(end 489.095796 -141.5034)
		(width 0.10795)
		(layer "B.Cu")
		(net "FM_DB_PRESENT")
	)
	(segment
		(start 488.806998 -142.526258)
		(end 488.806998 -141.792198)
		(width 0.10795)
		(layer "B.Cu")
		(net "FM_DB_PRESENT")
	)
	(segment
		(start 487.934 -140.8176)
		(end 487.934 -140.4874)
		(width 0.10795)
		(layer "B.Cu")
		(net "FM_DB_PRESENT")
	)
	(segment
		(start 487.934 -140.4874)
		(end 487.807 -140.3604)
		(width 0.10795)
		(layer "B.Cu")
		(net "FM_DB_PRESENT")
	)
	(segment
		(start 488.578398 -141.792198)
		(end 487.934 -141.1478)
		(width 0.10795)
		(layer "B.Cu")
		(net "FM_DB_PRESENT")
	)
	(segment
		(start 489.155232 -142.874492)
		(end 488.806998 -142.526258)
		(width 0.10795)
		(layer "B.Cu")
		(net "FM_DB_PRESENT")
	)
	(segment
		(start 487.807 -140.3604)
		(end 486.756202 -140.3604)
		(width 0.10795)
		(layer "B.Cu")
		(net "FM_DB_PRESENT")
	)
	(segment
		(start 486.654602 -140.462)
		(end 485.8385 -140.462)
		(width 0.10795)
		(layer "B.Cu")
		(net "FM_DB_PRESENT")
	)
	(segment
		(start 486.756202 -140.3604)
		(end 486.654602 -140.462)
		(width 0.10795)
		(layer "B.Cu")
		(net "FM_DB_PRESENT")
	)
	(segment
		(start 487.934 -141.1478)
		(end 487.934 -140.8176)
		(width 0.10795)
		(layer "B.Cu")
		(net "FM_DB_PRESENT")
	)
	(segment
		(start 489.839 -141.2748)
		(end 489.839 -140.589)
		(width 0.10795)
		(layer "B.Cu")
		(net "FM_DB_PRESENT")
	)
	(segment
		(start 489.095796 -141.5034)
		(end 489.6104 -141.5034)
		(width 0.10795)
		(layer "B.Cu")
		(net "FM_DB_PRESENT")
	)
	(segment
		(start 488.806998 -141.792198)
		(end 488.578398 -141.792198)
		(width 0.10795)
		(layer "B.Cu")
		(net "FM_DB_PRESENT")
	)
	(segment
		(start 490.646466 -150.3934)
		(end 491.037626 -150.3934)
		(width 0.254)
		(layer "F.Cu")
		(net "SPA_5V_SIN_SW")
	)
	(segment
		(start 489.77804 -152.86736)
		(end 489.77804 -151.261826)
		(width 0.254)
		(layer "F.Cu")
		(net "SPA_5V_SIN_SW")
	)
	(segment
		(start 491.037626 -150.3934)
		(end 491.581186 -149.84984)
		(width 0.254)
		(layer "F.Cu")
		(net "SPA_5V_SIN_SW")
	)
	(segment
		(start 491.581186 -149.84984)
		(end 494.000028 -149.84984)
		(width 0.254)
		(layer "F.Cu")
		(net "SPA_5V_SIN_SW")
	)
	(segment
		(start 489.3056 -153.3398)
		(end 489.77804 -152.86736)
		(width 0.254)
		(layer "F.Cu")
		(net "SPA_5V_SIN_SW")
	)
	(segment
		(start 489.77804 -151.261826)
		(end 490.646466 -150.3934)
		(width 0.254)
		(layer "F.Cu")
		(net "SPA_5V_SIN_SW")
	)
	(via
		(at 491.99038 -150.0124)
		(size 0.6604)
		(drill 0.3302)
		(layers "F.Cu" "B.Cu")
		(net "SPA_5V_SIN_SW")
	)
	(segment
		(start 494.000028 -149.84984)
		(end 492.15294 -149.84984)
		(width 0.254)
		(layer "B.Cu")
		(net "SPA_5V_SIN_SW")
	)
	(segment
		(start 492.15294 -149.84984)
		(end 491.99038 -150.0124)
		(width 0.254)
		(layer "B.Cu")
		(net "SPA_5V_SIN_SW")
	)
	(segment
		(start 176.109884 -94.2848)
		(end 176.444148 -93.950536)
		(width 0.10795)
		(layer "F.Cu")
		(net "PD_GTL2014_2_VREF")
	)
	(segment
		(start 174.631858 -94.887542)
		(end 175.2346 -94.2848)
		(width 0.10795)
		(layer "F.Cu")
		(net "PD_GTL2014_2_VREF")
	)
	(segment
		(start 175.2346 -94.2848)
		(end 176.109884 -94.2848)
		(width 0.10795)
		(layer "F.Cu")
		(net "PD_GTL2014_2_VREF")
	)
	(segment
		(start 174.631858 -96.310704)
		(end 174.631858 -94.887542)
		(width 0.10795)
		(layer "F.Cu")
		(net "PD_GTL2014_2_VREF")
	)
	(via
		(at 176.444148 -93.950536)
		(size 0.762)
		(drill 0.381)
		(layers "F.Cu" "B.Cu")
		(net "PD_GTL2014_2_VREF")
	)
	(via
		(at 372.2751 -53.1749)
		(size 0.6604)
		(drill 0.3302)
		(layers "F.Cu" "B.Cu")
		(net "PD_GTL2014_1_VREF")
	)
	(segment
		(start 371.8306 -52.2097)
		(end 371.8306 -52.5272)
		(width 0.10795)
		(layer "B.Cu")
		(net "PD_GTL2014_1_VREF")
	)
	(segment
		(start 371.5639 -53.213)
		(end 369.8875 -53.213)
		(width 0.10795)
		(layer "B.Cu")
		(net "PD_GTL2014_1_VREF")
	)
	(segment
		(start 372.2751 -53.1749)
		(end 371.602 -53.1749)
		(width 0.10795)
		(layer "B.Cu")
		(net "PD_GTL2014_1_VREF")
	)
	(segment
		(start 372.2751 -52.9717)
		(end 372.2751 -53.1749)
		(width 0.10795)
		(layer "B.Cu")
		(net "PD_GTL2014_1_VREF")
	)
	(segment
		(start 371.602 -53.1749)
		(end 371.5639 -53.213)
		(width 0.10795)
		(layer "B.Cu")
		(net "PD_GTL2014_1_VREF")
	)
	(segment
		(start 371.8306 -52.5272)
		(end 372.2751 -52.9717)
		(width 0.10795)
		(layer "B.Cu")
		(net "PD_GTL2014_1_VREF")
	)
	(segment
		(start 379.7173 -89.662)
		(end 379.7173 -89.1667)
		(width 0.10795)
		(layer "F.Cu")
		(net "LPC_LFRAME_N_CS0_R_N")
	)
	(segment
		(start 410.71038 -43.61942)
		(end 410.71038 -42.914316)
		(width 0.10795)
		(layer "F.Cu")
		(net "LPC_LFRAME_N_CS0_R_N")
	)
	(segment
		(start 410.4386 -43.8912)
		(end 410.71038 -43.61942)
		(width 0.10795)
		(layer "F.Cu")
		(net "LPC_LFRAME_N_CS0_R_N")
	)
	(segment
		(start 379.7173 -89.1667)
		(end 379.984 -88.9)
		(width 0.10795)
		(layer "F.Cu")
		(net "LPC_LFRAME_N_CS0_R_N")
	)
	(segment
		(start 410.71038 -42.914316)
		(end 411.09011 -42.534586)
		(width 0.10795)
		(layer "F.Cu")
		(net "LPC_LFRAME_N_CS0_R_N")
	)
	(via
		(at 408.617674 -45.928026)
		(size 0.4572)
		(drill 0.2032)
		(layers "F.Cu" "B.Cu")
		(net "LPC_LFRAME_N_CS0_R_N")
	)
	(via
		(at 410.4386 -43.8912)
		(size 0.4572)
		(drill 0.2032)
		(layers "F.Cu" "B.Cu")
		(net "LPC_LFRAME_N_CS0_R_N")
	)
	(via
		(at 379.984 -88.9)
		(size 0.508)
		(drill 0.254)
		(layers "F.Cu" "B.Cu")
		(net "LPC_LFRAME_N_CS0_R_N")
	)
	(via
		(at 391.503154 -38.5826)
		(size 0.508)
		(drill 0.254)
		(layers "F.Cu" "B.Cu")
		(net "LPC_LFRAME_N_CS0_R_N")
	)
	(via
		(at 408.060652 -43.965114)
		(size 0.6604)
		(drill 0.3302)
		(layers "F.Cu" "B.Cu")
		(net "LPC_LFRAME_N_CS0_R_N")
	)
	(segment
		(start 408.517852 -42.70502)
		(end 408.23896 -42.983912)
		(width 0.089408)
		(layer "B.Cu")
		(net "LPC_LFRAME_N_CS0_R_N")
	)
	(segment
		(start 408.23896 -42.98442)
		(end 408.060652 -43.162728)
		(width 0.089408)
		(layer "B.Cu")
		(net "LPC_LFRAME_N_CS0_R_N")
	)
	(segment
		(start 408.060652 -43.162728)
		(end 408.060652 -43.965114)
		(width 0.089408)
		(layer "B.Cu")
		(net "LPC_LFRAME_N_CS0_R_N")
	)
	(segment
		(start 409.543504 -43.6118)
		(end 409.2194 -43.287696)
		(width 0.089408)
		(layer "B.Cu")
		(net "LPC_LFRAME_N_CS0_R_N")
	)
	(segment
		(start 408.83459 -42.70502)
		(end 408.517852 -42.70502)
		(width 0.089408)
		(layer "B.Cu")
		(net "LPC_LFRAME_N_CS0_R_N")
	)
	(segment
		(start 408.94635 -42.71899)
		(end 408.84856 -42.71899)
		(width 0.089408)
		(layer "B.Cu")
		(net "LPC_LFRAME_N_CS0_R_N")
	)
	(segment
		(start 410.4386 -43.8912)
		(end 410.1592 -43.6118)
		(width 0.089408)
		(layer "B.Cu")
		(net "LPC_LFRAME_N_CS0_R_N")
	)
	(segment
		(start 408.617674 -45.928026)
		(end 408.060652 -45.371004)
		(width 0.10795)
		(layer "B.Cu")
		(net "LPC_LFRAME_N_CS0_R_N")
	)
	(segment
		(start 408.060652 -45.371004)
		(end 408.060652 -43.965114)
		(width 0.10795)
		(layer "B.Cu")
		(net "LPC_LFRAME_N_CS0_R_N")
	)
	(segment
		(start 409.2194 -43.287696)
		(end 409.2194 -42.99204)
		(width 0.089408)
		(layer "B.Cu")
		(net "LPC_LFRAME_N_CS0_R_N")
	)
	(segment
		(start 408.23896 -42.983912)
		(end 408.23896 -42.98442)
		(width 0.089408)
		(layer "B.Cu")
		(net "LPC_LFRAME_N_CS0_R_N")
	)
	(segment
		(start 408.84856 -42.71899)
		(end 408.83459 -42.70502)
		(width 0.089408)
		(layer "B.Cu")
		(net "LPC_LFRAME_N_CS0_R_N")
	)
	(segment
		(start 409.2194 -42.99204)
		(end 408.94635 -42.71899)
		(width 0.089408)
		(layer "B.Cu")
		(net "LPC_LFRAME_N_CS0_R_N")
	)
	(segment
		(start 410.1592 -43.6118)
		(end 409.543504 -43.6118)
		(width 0.089408)
		(layer "B.Cu")
		(net "LPC_LFRAME_N_CS0_R_N")
	)
	(segment
		(start 404.67915 -43.265852)
		(end 402.312632 -43.265852)
		(width 0.089408)
		(layer "In4.Cu")
		(net "LPC_LFRAME_N_CS0_R_N")
	)
	(segment
		(start 393.346432 -39.477696)
		(end 392.451336 -38.5826)
		(width 0.089408)
		(layer "In4.Cu")
		(net "LPC_LFRAME_N_CS0_R_N")
	)
	(segment
		(start 392.451336 -38.5826)
		(end 391.503154 -38.5826)
		(width 0.089408)
		(layer "In4.Cu")
		(net "LPC_LFRAME_N_CS0_R_N")
	)
	(segment
		(start 406.904952 -43.2943)
		(end 406.214072 -43.2943)
		(width 0.089408)
		(layer "In4.Cu")
		(net "LPC_LFRAME_N_CS0_R_N")
	)
	(segment
		(start 406.210516 -43.290998)
		(end 406.083262 -43.163744)
		(width 0.089408)
		(layer "In4.Cu")
		(net "LPC_LFRAME_N_CS0_R_N")
	)
	(segment
		(start 406.083262 -43.163744)
		(end 404.781258 -43.163744)
		(width 0.089408)
		(layer "In4.Cu")
		(net "LPC_LFRAME_N_CS0_R_N")
	)
	(segment
		(start 402.312632 -43.265852)
		(end 401.352512 -42.305732)
		(width 0.089408)
		(layer "In4.Cu")
		(net "LPC_LFRAME_N_CS0_R_N")
	)
	(segment
		(start 401.352512 -42.305732)
		(end 400.277838 -42.305732)
		(width 0.089408)
		(layer "In4.Cu")
		(net "LPC_LFRAME_N_CS0_R_N")
	)
	(segment
		(start 400.277838 -42.305732)
		(end 397.449802 -39.477696)
		(width 0.089408)
		(layer "In4.Cu")
		(net "LPC_LFRAME_N_CS0_R_N")
	)
	(segment
		(start 408.617674 -45.928026)
		(end 408.617674 -45.007022)
		(width 0.089408)
		(layer "In4.Cu")
		(net "LPC_LFRAME_N_CS0_R_N")
	)
	(segment
		(start 406.21077 -43.290998)
		(end 406.210516 -43.290998)
		(width 0.089408)
		(layer "In4.Cu")
		(net "LPC_LFRAME_N_CS0_R_N")
	)
	(segment
		(start 404.781258 -43.163744)
		(end 404.67915 -43.265852)
		(width 0.089408)
		(layer "In4.Cu")
		(net "LPC_LFRAME_N_CS0_R_N")
	)
	(segment
		(start 406.214072 -43.2943)
		(end 406.21077 -43.290998)
		(width 0.089408)
		(layer "In4.Cu")
		(net "LPC_LFRAME_N_CS0_R_N")
	)
	(segment
		(start 397.449802 -39.477696)
		(end 393.346432 -39.477696)
		(width 0.089408)
		(layer "In4.Cu")
		(net "LPC_LFRAME_N_CS0_R_N")
	)
	(segment
		(start 408.617674 -45.007022)
		(end 406.904952 -43.2943)
		(width 0.089408)
		(layer "In4.Cu")
		(net "LPC_LFRAME_N_CS0_R_N")
	)
	(segment
		(start 387.60273 -72.354186)
		(end 389.032496 -70.92442)
		(width 0.089408)
		(layer "In9.Cu")
		(net "LPC_LFRAME_N_CS0_R_N")
	)
	(segment
		(start 383.974086 -84.91982)
		(end 384.21564 -84.91982)
		(width 0.089408)
		(layer "In9.Cu")
		(net "LPC_LFRAME_N_CS0_R_N")
	)
	(segment
		(start 388.62508 -66.473578)
		(end 390.230614 -64.868044)
		(width 0.089408)
		(layer "In9.Cu")
		(net "LPC_LFRAME_N_CS0_R_N")
	)
	(segment
		(start 384.91922 -84.21624)
		(end 384.91922 -83.65998)
		(width 0.089408)
		(layer "In9.Cu")
		(net "LPC_LFRAME_N_CS0_R_N")
	)
	(segment
		(start 379.984 -88.9)
		(end 379.984 -88.53678)
		(width 0.089408)
		(layer "In9.Cu")
		(net "LPC_LFRAME_N_CS0_R_N")
	)
	(segment
		(start 387.04774 -73.98131)
		(end 387.60273 -73.42632)
		(width 0.089408)
		(layer "In9.Cu")
		(net "LPC_LFRAME_N_CS0_R_N")
	)
	(segment
		(start 385.682744 -77.330046)
		(end 387.04774 -75.96505)
		(width 0.089408)
		(layer "In9.Cu")
		(net "LPC_LFRAME_N_CS0_R_N")
	)
	(segment
		(start 389.032496 -70.268338)
		(end 388.62508 -69.860922)
		(width 0.089408)
		(layer "In9.Cu")
		(net "LPC_LFRAME_N_CS0_R_N")
	)
	(segment
		(start 384.91922 -83.65998)
		(end 385.987544 -82.591656)
		(width 0.089408)
		(layer "In9.Cu")
		(net "LPC_LFRAME_N_CS0_R_N")
	)
	(segment
		(start 385.987544 -80.484218)
		(end 385.682744 -80.179418)
		(width 0.089408)
		(layer "In9.Cu")
		(net "LPC_LFRAME_N_CS0_R_N")
	)
	(segment
		(start 382.7526 -86.141306)
		(end 383.974086 -84.91982)
		(width 0.089408)
		(layer "In9.Cu")
		(net "LPC_LFRAME_N_CS0_R_N")
	)
	(segment
		(start 391.036302 -39.049452)
		(end 391.503154 -38.5826)
		(width 0.089408)
		(layer "In9.Cu")
		(net "LPC_LFRAME_N_CS0_R_N")
	)
	(segment
		(start 382.369314 -87.11438)
		(end 382.7526 -86.731094)
		(width 0.089408)
		(layer "In9.Cu")
		(net "LPC_LFRAME_N_CS0_R_N")
	)
	(segment
		(start 385.682744 -80.179418)
		(end 385.682744 -77.330046)
		(width 0.089408)
		(layer "In9.Cu")
		(net "LPC_LFRAME_N_CS0_R_N")
	)
	(segment
		(start 389.527288 -45.955712)
		(end 390.463532 -45.019468)
		(width 0.089408)
		(layer "In9.Cu")
		(net "LPC_LFRAME_N_CS0_R_N")
	)
	(segment
		(start 388.62508 -69.860922)
		(end 388.62508 -66.473578)
		(width 0.089408)
		(layer "In9.Cu")
		(net "LPC_LFRAME_N_CS0_R_N")
	)
	(segment
		(start 385.987544 -82.591656)
		(end 385.987544 -80.484218)
		(width 0.089408)
		(layer "In9.Cu")
		(net "LPC_LFRAME_N_CS0_R_N")
	)
	(segment
		(start 390.230614 -64.868044)
		(end 390.230614 -59.681872)
		(width 0.089408)
		(layer "In9.Cu")
		(net "LPC_LFRAME_N_CS0_R_N")
	)
	(segment
		(start 387.04774 -75.96505)
		(end 387.04774 -73.98131)
		(width 0.089408)
		(layer "In9.Cu")
		(net "LPC_LFRAME_N_CS0_R_N")
	)
	(segment
		(start 391.035794 -52.9717)
		(end 389.527288 -51.463194)
		(width 0.089408)
		(layer "In9.Cu")
		(net "LPC_LFRAME_N_CS0_R_N")
	)
	(segment
		(start 391.036302 -41.436798)
		(end 391.036302 -39.049452)
		(width 0.089408)
		(layer "In9.Cu")
		(net "LPC_LFRAME_N_CS0_R_N")
	)
	(segment
		(start 389.032496 -70.92442)
		(end 389.032496 -70.268338)
		(width 0.089408)
		(layer "In9.Cu")
		(net "LPC_LFRAME_N_CS0_R_N")
	)
	(segment
		(start 381.4064 -87.11438)
		(end 382.369314 -87.11438)
		(width 0.089408)
		(layer "In9.Cu")
		(net "LPC_LFRAME_N_CS0_R_N")
	)
	(segment
		(start 382.7526 -86.731094)
		(end 382.7526 -86.141306)
		(width 0.089408)
		(layer "In9.Cu")
		(net "LPC_LFRAME_N_CS0_R_N")
	)
	(segment
		(start 379.984 -88.53678)
		(end 381.4064 -87.11438)
		(width 0.089408)
		(layer "In9.Cu")
		(net "LPC_LFRAME_N_CS0_R_N")
	)
	(segment
		(start 390.463532 -42.009568)
		(end 391.036302 -41.436798)
		(width 0.089408)
		(layer "In9.Cu")
		(net "LPC_LFRAME_N_CS0_R_N")
	)
	(segment
		(start 387.60273 -73.42632)
		(end 387.60273 -72.354186)
		(width 0.089408)
		(layer "In9.Cu")
		(net "LPC_LFRAME_N_CS0_R_N")
	)
	(segment
		(start 390.463532 -45.019468)
		(end 390.463532 -42.009568)
		(width 0.089408)
		(layer "In9.Cu")
		(net "LPC_LFRAME_N_CS0_R_N")
	)
	(segment
		(start 384.21564 -84.91982)
		(end 384.91922 -84.21624)
		(width 0.089408)
		(layer "In9.Cu")
		(net "LPC_LFRAME_N_CS0_R_N")
	)
	(segment
		(start 391.035794 -58.876692)
		(end 391.035794 -52.9717)
		(width 0.089408)
		(layer "In9.Cu")
		(net "LPC_LFRAME_N_CS0_R_N")
	)
	(segment
		(start 389.527288 -51.463194)
		(end 389.527288 -45.955712)
		(width 0.089408)
		(layer "In9.Cu")
		(net "LPC_LFRAME_N_CS0_R_N")
	)
	(segment
		(start 390.230614 -59.681872)
		(end 391.035794 -58.876692)
		(width 0.089408)
		(layer "In9.Cu")
		(net "LPC_LFRAME_N_CS0_R_N")
	)
	(segment
		(start 411.09011 -43.334686)
		(end 411.09011 -44.281344)
		(width 0.10795)
		(layer "F.Cu")
		(net "IRQ_LPC_SERIRQ_R")
	)
	(segment
		(start 410.536644 -45.896276)
		(end 410.32176 -46.11116)
		(width 0.254)
		(layer "F.Cu")
		(net "IRQ_LPC_SERIRQ_R")
	)
	(segment
		(start 411.09011 -44.281344)
		(end 410.536644 -44.83481)
		(width 0.10795)
		(layer "F.Cu")
		(net "IRQ_LPC_SERIRQ_R")
	)
	(segment
		(start 410.536644 -44.83481)
		(end 410.536644 -45.896276)
		(width 0.254)
		(layer "F.Cu")
		(net "IRQ_LPC_SERIRQ_R")
	)
	(via
		(at 410.32176 -46.11116)
		(size 0.762)
		(drill 0.381)
		(layers "F.Cu" "B.Cu")
		(net "IRQ_LPC_SERIRQ_R")
	)
	(via
		(at 410.536644 -44.83481)
		(size 0.4572)
		(drill 0.2032)
		(layers "F.Cu" "B.Cu")
		(net "IRQ_LPC_SERIRQ_R")
	)
	(segment
		(start 410.723334 -44.64812)
		(end 411.21076 -44.64812)
		(width 0.10795)
		(layer "B.Cu")
		(net "IRQ_LPC_SERIRQ_R")
	)
	(segment
		(start 410.536644 -44.83481)
		(end 410.723334 -44.64812)
		(width 0.10795)
		(layer "B.Cu")
		(net "IRQ_LPC_SERIRQ_R")
	)
	(segment
		(start 416.690048 -41.73474)
		(end 416.290252 -42.134536)
		(width 0.10795)
		(layer "F.Cu")
		(net "FM_PE_BMC_WAKE_N")
	)
	(via
		(at 416.90925 -43.184318)
		(size 0.6604)
		(drill 0.3302)
		(layers "F.Cu" "B.Cu")
		(net "FM_PE_BMC_WAKE_N")
	)
	(via
		(at 416.290252 -42.134536)
		(size 0.4572)
		(drill 0.2032)
		(layers "F.Cu" "B.Cu")
		(net "FM_PE_BMC_WAKE_N")
	)
	(via
		(at 478.6376 -56.9214)
		(size 0.508)
		(drill 0.254)
		(layers "F.Cu" "B.Cu")
		(net "FM_PE_BMC_WAKE_N")
	)
	(via
		(at 476.4278 -46.9392)
		(size 0.508)
		(drill 0.254)
		(layers "F.Cu" "B.Cu")
		(net "FM_PE_BMC_WAKE_N")
	)
	(segment
		(start 478.18675 -57.94375)
		(end 478.7392 -58.4962)
		(width 0.10795)
		(layer "B.Cu")
		(net "FM_PE_BMC_WAKE_N")
	)
	(segment
		(start 478.18675 -57.37225)
		(end 478.18675 -57.94375)
		(width 0.10795)
		(layer "B.Cu")
		(net "FM_PE_BMC_WAKE_N")
	)
	(segment
		(start 416.90925 -44.326556)
		(end 416.90925 -43.184318)
		(width 0.10795)
		(layer "B.Cu")
		(net "FM_PE_BMC_WAKE_N")
	)
	(segment
		(start 416.290252 -42.56532)
		(end 416.290252 -42.134536)
		(width 0.10795)
		(layer "B.Cu")
		(net "FM_PE_BMC_WAKE_N")
	)
	(segment
		(start 478.6376 -56.9214)
		(end 478.18675 -57.37225)
		(width 0.10795)
		(layer "B.Cu")
		(net "FM_PE_BMC_WAKE_N")
	)
	(segment
		(start 416.90925 -43.184318)
		(end 416.290252 -42.56532)
		(width 0.10795)
		(layer "B.Cu")
		(net "FM_PE_BMC_WAKE_N")
	)
	(segment
		(start 478.7392 -58.4962)
		(end 479.647504 -58.4962)
		(width 0.10795)
		(layer "B.Cu")
		(net "FM_PE_BMC_WAKE_N")
	)
	(segment
		(start 479.647504 -58.4962)
		(end 479.923602 -58.772298)
		(width 0.10795)
		(layer "B.Cu")
		(net "FM_PE_BMC_WAKE_N")
	)
	(segment
		(start 417.232846 -44.650152)
		(end 416.90925 -44.326556)
		(width 0.10795)
		(layer "B.Cu")
		(net "FM_PE_BMC_WAKE_N")
	)
	(segment
		(start 426.5422 -47.72152)
		(end 425.93133 -47.11065)
		(width 0.089408)
		(layer "In2.Cu")
		(net "FM_PE_BMC_WAKE_N")
	)
	(segment
		(start 421.649398 -42.625264)
		(end 421.45839 -42.434256)
		(width 0.089408)
		(layer "In2.Cu")
		(net "FM_PE_BMC_WAKE_N")
	)
	(segment
		(start 416.935158 -41.759886)
		(end 416.560508 -42.134536)
		(width 0.089408)
		(layer "In2.Cu")
		(net "FM_PE_BMC_WAKE_N")
	)
	(segment
		(start 423.520616 -42.836846)
		(end 423.250614 -42.836846)
		(width 0.089408)
		(layer "In2.Cu")
		(net "FM_PE_BMC_WAKE_N")
	)
	(segment
		(start 425.93133 -46.41977)
		(end 424.291506 -44.779946)
		(width 0.089408)
		(layer "In2.Cu")
		(net "FM_PE_BMC_WAKE_N")
	)
	(segment
		(start 416.560508 -42.134536)
		(end 416.290252 -42.134536)
		(width 0.089408)
		(layer "In2.Cu")
		(net "FM_PE_BMC_WAKE_N")
	)
	(segment
		(start 432.914552 -46.504606)
		(end 432.273964 -45.864018)
		(width 0.089408)
		(layer "In2.Cu")
		(net "FM_PE_BMC_WAKE_N")
	)
	(segment
		(start 425.93133 -47.11065)
		(end 425.93133 -46.41977)
		(width 0.089408)
		(layer "In2.Cu")
		(net "FM_PE_BMC_WAKE_N")
	)
	(segment
		(start 432.273964 -45.864018)
		(end 429.124872 -45.864018)
		(width 0.089408)
		(layer "In2.Cu")
		(net "FM_PE_BMC_WAKE_N")
	)
	(segment
		(start 435.404768 -46.504606)
		(end 432.914552 -46.504606)
		(width 0.089408)
		(layer "In2.Cu")
		(net "FM_PE_BMC_WAKE_N")
	)
	(segment
		(start 424.291506 -43.607736)
		(end 423.520616 -42.836846)
		(width 0.089408)
		(layer "In2.Cu")
		(net "FM_PE_BMC_WAKE_N")
	)
	(segment
		(start 472.23172 -44.278296)
		(end 470.978738 -44.278296)
		(width 0.089408)
		(layer "In2.Cu")
		(net "FM_PE_BMC_WAKE_N")
	)
	(segment
		(start 421.45839 -42.296334)
		(end 421.46474 -42.289984)
		(width 0.089408)
		(layer "In2.Cu")
		(net "FM_PE_BMC_WAKE_N")
	)
	(segment
		(start 421.46474 -42.289984)
		(end 421.46474 -41.965626)
		(width 0.089408)
		(layer "In2.Cu")
		(net "FM_PE_BMC_WAKE_N")
	)
	(segment
		(start 421.45839 -42.434256)
		(end 421.45839 -42.296334)
		(width 0.089408)
		(layer "In2.Cu")
		(net "FM_PE_BMC_WAKE_N")
	)
	(segment
		(start 473.058744 -44.577)
		(end 472.530424 -44.577)
		(width 0.089408)
		(layer "In2.Cu")
		(net "FM_PE_BMC_WAKE_N")
	)
	(segment
		(start 476.4278 -46.9392)
		(end 475.420944 -46.9392)
		(width 0.089408)
		(layer "In2.Cu")
		(net "FM_PE_BMC_WAKE_N")
	)
	(segment
		(start 427.26737 -47.72152)
		(end 426.5422 -47.72152)
		(width 0.089408)
		(layer "In2.Cu")
		(net "FM_PE_BMC_WAKE_N")
	)
	(segment
		(start 468.03945 -47.217584)
		(end 436.117746 -47.217584)
		(width 0.089408)
		(layer "In2.Cu")
		(net "FM_PE_BMC_WAKE_N")
	)
	(segment
		(start 470.978738 -44.278296)
		(end 468.03945 -47.217584)
		(width 0.089408)
		(layer "In2.Cu")
		(net "FM_PE_BMC_WAKE_N")
	)
	(segment
		(start 424.291506 -44.779946)
		(end 424.291506 -43.607736)
		(width 0.089408)
		(layer "In2.Cu")
		(net "FM_PE_BMC_WAKE_N")
	)
	(segment
		(start 421.259 -41.759886)
		(end 416.935158 -41.759886)
		(width 0.089408)
		(layer "In2.Cu")
		(net "FM_PE_BMC_WAKE_N")
	)
	(segment
		(start 436.117746 -47.217584)
		(end 435.404768 -46.504606)
		(width 0.089408)
		(layer "In2.Cu")
		(net "FM_PE_BMC_WAKE_N")
	)
	(segment
		(start 429.124872 -45.864018)
		(end 427.26737 -47.72152)
		(width 0.089408)
		(layer "In2.Cu")
		(net "FM_PE_BMC_WAKE_N")
	)
	(segment
		(start 475.420944 -46.9392)
		(end 473.058744 -44.577)
		(width 0.089408)
		(layer "In2.Cu")
		(net "FM_PE_BMC_WAKE_N")
	)
	(segment
		(start 421.46474 -41.965626)
		(end 421.259 -41.759886)
		(width 0.089408)
		(layer "In2.Cu")
		(net "FM_PE_BMC_WAKE_N")
	)
	(segment
		(start 423.039032 -42.625264)
		(end 421.649398 -42.625264)
		(width 0.089408)
		(layer "In2.Cu")
		(net "FM_PE_BMC_WAKE_N")
	)
	(segment
		(start 423.250614 -42.836846)
		(end 423.039032 -42.625264)
		(width 0.089408)
		(layer "In2.Cu")
		(net "FM_PE_BMC_WAKE_N")
	)
	(segment
		(start 472.530424 -44.577)
		(end 472.23172 -44.278296)
		(width 0.089408)
		(layer "In2.Cu")
		(net "FM_PE_BMC_WAKE_N")
	)
	(segment
		(start 476.515938 -53.130704)
		(end 476.847662 -53.130704)
		(width 0.089408)
		(layer "In9.Cu")
		(net "FM_PE_BMC_WAKE_N")
	)
	(segment
		(start 479.907854 -55.752746)
		(end 478.7392 -56.9214)
		(width 0.089408)
		(layer "In9.Cu")
		(net "FM_PE_BMC_WAKE_N")
	)
	(segment
		(start 478.7392 -56.9214)
		(end 478.6376 -56.9214)
		(width 0.089408)
		(layer "In9.Cu")
		(net "FM_PE_BMC_WAKE_N")
	)
	(segment
		(start 476.212408 -52.90566)
		(end 476.290894 -52.90566)
		(width 0.089408)
		(layer "In9.Cu")
		(net "FM_PE_BMC_WAKE_N")
	)
	(segment
		(start 476.4278 -48.76546)
		(end 476.123 -49.07026)
		(width 0.089408)
		(layer "In9.Cu")
		(net "FM_PE_BMC_WAKE_N")
	)
	(segment
		(start 476.290894 -52.90566)
		(end 476.515938 -53.130704)
		(width 0.089408)
		(layer "In9.Cu")
		(net "FM_PE_BMC_WAKE_N")
	)
	(segment
		(start 477.072706 -52.90566)
		(end 479.318828 -52.90566)
		(width 0.089408)
		(layer "In9.Cu")
		(net "FM_PE_BMC_WAKE_N")
	)
	(segment
		(start 476.847662 -53.130704)
		(end 477.072706 -52.90566)
		(width 0.089408)
		(layer "In9.Cu")
		(net "FM_PE_BMC_WAKE_N")
	)
	(segment
		(start 476.123 -49.07026)
		(end 476.123 -52.816252)
		(width 0.089408)
		(layer "In9.Cu")
		(net "FM_PE_BMC_WAKE_N")
	)
	(segment
		(start 479.907854 -53.494686)
		(end 479.907854 -55.752746)
		(width 0.089408)
		(layer "In9.Cu")
		(net "FM_PE_BMC_WAKE_N")
	)
	(segment
		(start 476.4278 -46.9392)
		(end 476.4278 -48.76546)
		(width 0.089408)
		(layer "In9.Cu")
		(net "FM_PE_BMC_WAKE_N")
	)
	(segment
		(start 479.318828 -52.90566)
		(end 479.907854 -53.494686)
		(width 0.089408)
		(layer "In9.Cu")
		(net "FM_PE_BMC_WAKE_N")
	)
	(segment
		(start 476.123 -52.816252)
		(end 476.212408 -52.90566)
		(width 0.089408)
		(layer "In9.Cu")
		(net "FM_PE_BMC_WAKE_N")
	)
	(segment
		(start 396.15745 -123.59132)
		(end 396.65275 -123.821444)
		(width 0.1143)
		(layer "F.Cu")
		(net "P2E_SSB_BMC_TX_DP")
	)
	(via
		(at 396.65275 -123.821444)
		(size 0.508)
		(drill 0.254)
		(layers "F.Cu" "B.Cu")
		(net "P2E_SSB_BMC_TX_DP")
	)
	(segment
		(start 399.160238 -125.10897)
		(end 399.530824 -124.738384)
		(width 0.0889)
		(layer "B.Cu")
		(net "P2E_SSB_BMC_TX_DP")
	)
	(segment
		(start 397.821404 -124.978668)
		(end 397.999204 -124.978668)
		(width 0.0889)
		(layer "B.Cu")
		(net "P2E_SSB_BMC_TX_DP")
	)
	(segment
		(start 398.278604 -124.877068)
		(end 398.380204 -124.978668)
		(width 0.0889)
		(layer "B.Cu")
		(net "P2E_SSB_BMC_TX_DP")
	)
	(segment
		(start 397.999204 -124.978668)
		(end 398.100804 -124.877068)
		(width 0.0889)
		(layer "B.Cu")
		(net "P2E_SSB_BMC_TX_DP")
	)
	(segment
		(start 396.65275 -123.821444)
		(end 396.273274 -123.821444)
		(width 0.0889)
		(layer "B.Cu")
		(net "P2E_SSB_BMC_TX_DP")
	)
	(segment
		(start 397.542004 -124.877068)
		(end 397.719804 -124.877068)
		(width 0.0889)
		(layer "B.Cu")
		(net "P2E_SSB_BMC_TX_DP")
	)
	(segment
		(start 396.194026 -123.900692)
		(end 396.194026 -124.068586)
		(width 0.0889)
		(layer "B.Cu")
		(net "P2E_SSB_BMC_TX_DP")
	)
	(segment
		(start 398.742916 -124.978668)
		(end 398.873218 -125.10897)
		(width 0.0889)
		(layer "B.Cu")
		(net "P2E_SSB_BMC_TX_DP")
	)
	(segment
		(start 398.100804 -124.877068)
		(end 398.278604 -124.877068)
		(width 0.0889)
		(layer "B.Cu")
		(net "P2E_SSB_BMC_TX_DP")
	)
	(segment
		(start 396.273274 -123.821444)
		(end 396.194026 -123.900692)
		(width 0.0889)
		(layer "B.Cu")
		(net "P2E_SSB_BMC_TX_DP")
	)
	(segment
		(start 397.440404 -124.978668)
		(end 397.542004 -124.877068)
		(width 0.0889)
		(layer "B.Cu")
		(net "P2E_SSB_BMC_TX_DP")
	)
	(segment
		(start 398.873218 -125.10897)
		(end 399.160238 -125.10897)
		(width 0.0889)
		(layer "B.Cu")
		(net "P2E_SSB_BMC_TX_DP")
	)
	(segment
		(start 397.719804 -124.877068)
		(end 397.821404 -124.978668)
		(width 0.0889)
		(layer "B.Cu")
		(net "P2E_SSB_BMC_TX_DP")
	)
	(segment
		(start 398.380204 -124.978668)
		(end 398.742916 -124.978668)
		(width 0.0889)
		(layer "B.Cu")
		(net "P2E_SSB_BMC_TX_DP")
	)
	(segment
		(start 396.194026 -124.068586)
		(end 397.104108 -124.978668)
		(width 0.0889)
		(layer "B.Cu")
		(net "P2E_SSB_BMC_TX_DP")
	)
	(segment
		(start 397.104108 -124.978668)
		(end 397.440404 -124.978668)
		(width 0.0889)
		(layer "B.Cu")
		(net "P2E_SSB_BMC_TX_DP")
	)
	(segment
		(start 395.16685 -123.59132)
		(end 395.224 -123.61799)
		(width 0.1143)
		(layer "F.Cu")
		(net "P2E_SSB_BMC_TX_DN")
	)
	(segment
		(start 395.224 -123.61799)
		(end 395.66215 -123.821444)
		(width 0.1143)
		(layer "F.Cu")
		(net "P2E_SSB_BMC_TX_DN")
	)
	(via
		(at 395.66215 -123.821444)
		(size 0.508)
		(drill 0.254)
		(layers "F.Cu" "B.Cu")
		(net "P2E_SSB_BMC_TX_DN")
	)
	(segment
		(start 396.003526 -124.14758)
		(end 397.025114 -125.169168)
		(width 0.0889)
		(layer "B.Cu")
		(net "P2E_SSB_BMC_TX_DN")
	)
	(segment
		(start 395.66215 -123.821444)
		(end 395.887702 -123.821444)
		(width 0.0889)
		(layer "B.Cu")
		(net "P2E_SSB_BMC_TX_DN")
	)
	(segment
		(start 398.663922 -125.169168)
		(end 398.794224 -125.29947)
		(width 0.0889)
		(layer "B.Cu")
		(net "P2E_SSB_BMC_TX_DN")
	)
	(segment
		(start 395.887702 -123.821444)
		(end 396.003526 -123.937268)
		(width 0.0889)
		(layer "B.Cu")
		(net "P2E_SSB_BMC_TX_DN")
	)
	(segment
		(start 399.20291 -125.29947)
		(end 399.530824 -125.627384)
		(width 0.0889)
		(layer "B.Cu")
		(net "P2E_SSB_BMC_TX_DN")
	)
	(segment
		(start 396.003526 -123.937268)
		(end 396.003526 -124.14758)
		(width 0.0889)
		(layer "B.Cu")
		(net "P2E_SSB_BMC_TX_DN")
	)
	(segment
		(start 397.025114 -125.169168)
		(end 398.663922 -125.169168)
		(width 0.0889)
		(layer "B.Cu")
		(net "P2E_SSB_BMC_TX_DN")
	)
	(segment
		(start 398.794224 -125.29947)
		(end 399.20291 -125.29947)
		(width 0.0889)
		(layer "B.Cu")
		(net "P2E_SSB_BMC_TX_DN")
	)
	(segment
		(start 416.17011 -46.946058)
		(end 416.371532 -47.14748)
		(width 0.0889)
		(layer "F.Cu")
		(net "P2E_SSB_BMC_TX_C_DP")
	)
	(segment
		(start 416.348164 -43.303952)
		(end 416.348164 -46.401736)
		(width 0.0889)
		(layer "F.Cu")
		(net "P2E_SSB_BMC_TX_C_DP")
	)
	(segment
		(start 416.348164 -46.401736)
		(end 416.17011 -46.57979)
		(width 0.0889)
		(layer "F.Cu")
		(net "P2E_SSB_BMC_TX_C_DP")
	)
	(segment
		(start 415.890202 -42.534586)
		(end 416.348164 -43.303952)
		(width 0.0889)
		(layer "F.Cu")
		(net "P2E_SSB_BMC_TX_C_DP")
	)
	(segment
		(start 416.17011 -46.57979)
		(end 416.17011 -46.946058)
		(width 0.0889)
		(layer "F.Cu")
		(net "P2E_SSB_BMC_TX_C_DP")
	)
	(segment
		(start 416.371532 -47.6885)
		(end 416.371532 -47.14748)
		(width 0.1143)
		(layer "F.Cu")
		(net "P2E_SSB_BMC_TX_C_DP")
	)
	(segment
		(start 416.511994 -47.828962)
		(end 416.371532 -47.6885)
		(width 0.1143)
		(layer "F.Cu")
		(net "P2E_SSB_BMC_TX_C_DP")
	)
	(via
		(at 404.37435 -125.97765)
		(size 0.508)
		(drill 0.254)
		(layers "F.Cu" "B.Cu")
		(net "P2E_SSB_BMC_TX_C_DP")
	)
	(via
		(at 416.371532 -47.14748)
		(size 0.508)
		(drill 0.254)
		(layers "F.Cu" "B.Cu")
		(net "P2E_SSB_BMC_TX_C_DP")
	)
	(segment
		(start 404.37435 -125.97765)
		(end 404.21814 -125.82144)
		(width 0.1143)
		(layer "B.Cu")
		(net "P2E_SSB_BMC_TX_C_DP")
	)
	(segment
		(start 404.21814 -125.82144)
		(end 404.21814 -125.3871)
		(width 0.1143)
		(layer "B.Cu")
		(net "P2E_SSB_BMC_TX_C_DP")
	)
	(segment
		(start 403.889972 -125.058932)
		(end 400.740372 -125.058932)
		(width 0.1143)
		(layer "B.Cu")
		(net "P2E_SSB_BMC_TX_C_DP")
	)
	(segment
		(start 400.740372 -125.058932)
		(end 400.419824 -124.738384)
		(width 0.1143)
		(layer "B.Cu")
		(net "P2E_SSB_BMC_TX_C_DP")
	)
	(segment
		(start 404.21814 -125.3871)
		(end 403.889972 -125.058932)
		(width 0.1143)
		(layer "B.Cu")
		(net "P2E_SSB_BMC_TX_C_DP")
	)
	(segment
		(start 408.361388 -125.742954)
		(end 407.586942 -126.5174)
		(width 0.1143)
		(layer "In11.Cu")
		(net "P2E_SSB_BMC_TX_C_DP")
	)
	(segment
		(start 421.920416 -78.155038)
		(end 421.920416 -79.360776)
		(width 0.1143)
		(layer "In11.Cu")
		(net "P2E_SSB_BMC_TX_C_DP")
	)
	(segment
		(start 419.1254 -55.73141)
		(end 420.8653 -57.471056)
		(width 0.1143)
		(layer "In11.Cu")
		(net "P2E_SSB_BMC_TX_C_DP")
	)
	(segment
		(start 422.488614 -98.357182)
		(end 422.488614 -103.487474)
		(width 0.1143)
		(layer "In11.Cu")
		(net "P2E_SSB_BMC_TX_C_DP")
	)
	(segment
		(start 419.1254 -54.168802)
		(end 419.1254 -55.73141)
		(width 0.1143)
		(layer "In11.Cu")
		(net "P2E_SSB_BMC_TX_C_DP")
	)
	(segment
		(start 416.052 -46.1518)
		(end 415.573972 -45.673772)
		(width 0.1143)
		(layer "In11.Cu")
		(net "P2E_SSB_BMC_TX_C_DP")
	)
	(segment
		(start 412.706566 -50.032412)
		(end 414.121854 -51.4477)
		(width 0.1143)
		(layer "In11.Cu")
		(net "P2E_SSB_BMC_TX_C_DP")
	)
	(segment
		(start 421.11803 -117.224302)
		(end 421.11803 -117.27561)
		(width 0.1143)
		(layer "In11.Cu")
		(net "P2E_SSB_BMC_TX_C_DP")
	)
	(segment
		(start 421.11803 -117.27561)
		(end 417.585144 -120.808496)
		(width 0.1143)
		(layer "In11.Cu")
		(net "P2E_SSB_BMC_TX_C_DP")
	)
	(segment
		(start 421.268398 -97.136966)
		(end 422.488614 -98.357182)
		(width 0.1143)
		(layer "In11.Cu")
		(net "P2E_SSB_BMC_TX_C_DP")
	)
	(segment
		(start 421.920416 -79.360776)
		(end 422.649396 -80.089756)
		(width 0.1143)
		(layer "In11.Cu")
		(net "P2E_SSB_BMC_TX_C_DP")
	)
	(segment
		(start 421.1447 -117.197632)
		(end 421.11803 -117.224302)
		(width 0.1143)
		(layer "In11.Cu")
		(net "P2E_SSB_BMC_TX_C_DP")
	)
	(segment
		(start 421.268398 -95.016828)
		(end 421.268398 -97.136966)
		(width 0.1143)
		(layer "In11.Cu")
		(net "P2E_SSB_BMC_TX_C_DP")
	)
	(segment
		(start 421.801798 -104.17429)
		(end 421.801798 -109.473492)
		(width 0.1143)
		(layer "In11.Cu")
		(net "P2E_SSB_BMC_TX_C_DP")
	)
	(segment
		(start 421.1447 -110.13059)
		(end 421.1447 -117.197632)
		(width 0.1143)
		(layer "In11.Cu")
		(net "P2E_SSB_BMC_TX_C_DP")
	)
	(segment
		(start 412.706566 -49.06391)
		(end 412.706566 -50.032412)
		(width 0.1143)
		(layer "In11.Cu")
		(net "P2E_SSB_BMC_TX_C_DP")
	)
	(segment
		(start 414.296606 -46.364398)
		(end 414.296606 -47.47387)
		(width 0.1143)
		(layer "In11.Cu")
		(net "P2E_SSB_BMC_TX_C_DP")
	)
	(segment
		(start 417.585144 -121.68251)
		(end 416.643058 -122.624596)
		(width 0.1143)
		(layer "In11.Cu")
		(net "P2E_SSB_BMC_TX_C_DP")
	)
	(segment
		(start 404.37435 -126.122684)
		(end 404.37435 -125.97765)
		(width 0.1143)
		(layer "In11.Cu")
		(net "P2E_SSB_BMC_TX_C_DP")
	)
	(segment
		(start 416.404298 -51.4477)
		(end 419.1254 -54.168802)
		(width 0.1143)
		(layer "In11.Cu")
		(net "P2E_SSB_BMC_TX_C_DP")
	)
	(segment
		(start 404.23084 -126.5174)
		(end 404.1394 -126.42596)
		(width 0.1143)
		(layer "In11.Cu")
		(net "P2E_SSB_BMC_TX_C_DP")
	)
	(segment
		(start 421.801798 -109.473492)
		(end 421.1447 -110.13059)
		(width 0.1143)
		(layer "In11.Cu")
		(net "P2E_SSB_BMC_TX_C_DP")
	)
	(segment
		(start 407.586942 -126.5174)
		(end 404.23084 -126.5174)
		(width 0.1143)
		(layer "In11.Cu")
		(net "P2E_SSB_BMC_TX_C_DP")
	)
	(segment
		(start 422.446958 -64.887348)
		(end 422.446958 -77.628496)
		(width 0.1143)
		(layer "In11.Cu")
		(net "P2E_SSB_BMC_TX_C_DP")
	)
	(segment
		(start 422.446958 -77.628496)
		(end 421.920416 -78.155038)
		(width 0.1143)
		(layer "In11.Cu")
		(net "P2E_SSB_BMC_TX_C_DP")
	)
	(segment
		(start 414.296606 -47.47387)
		(end 412.706566 -49.06391)
		(width 0.1143)
		(layer "In11.Cu")
		(net "P2E_SSB_BMC_TX_C_DP")
	)
	(segment
		(start 422.488614 -103.487474)
		(end 421.801798 -104.17429)
		(width 0.1143)
		(layer "In11.Cu")
		(net "P2E_SSB_BMC_TX_C_DP")
	)
	(segment
		(start 416.643058 -122.624596)
		(end 414.479994 -122.624596)
		(width 0.1143)
		(layer "In11.Cu")
		(net "P2E_SSB_BMC_TX_C_DP")
	)
	(segment
		(start 422.649396 -80.089756)
		(end 422.649396 -93.63583)
		(width 0.1143)
		(layer "In11.Cu")
		(net "P2E_SSB_BMC_TX_C_DP")
	)
	(segment
		(start 416.052 -46.827948)
		(end 416.052 -46.1518)
		(width 0.1143)
		(layer "In11.Cu")
		(net "P2E_SSB_BMC_TX_C_DP")
	)
	(segment
		(start 414.121854 -51.4477)
		(end 416.404298 -51.4477)
		(width 0.1143)
		(layer "In11.Cu")
		(net "P2E_SSB_BMC_TX_C_DP")
	)
	(segment
		(start 411.361636 -125.742954)
		(end 408.361388 -125.742954)
		(width 0.1143)
		(layer "In11.Cu")
		(net "P2E_SSB_BMC_TX_C_DP")
	)
	(segment
		(start 417.585144 -120.808496)
		(end 417.585144 -121.68251)
		(width 0.1143)
		(layer "In11.Cu")
		(net "P2E_SSB_BMC_TX_C_DP")
	)
	(segment
		(start 415.573972 -45.673772)
		(end 414.987232 -45.673772)
		(width 0.1143)
		(layer "In11.Cu")
		(net "P2E_SSB_BMC_TX_C_DP")
	)
	(segment
		(start 422.649396 -93.63583)
		(end 421.268398 -95.016828)
		(width 0.1143)
		(layer "In11.Cu")
		(net "P2E_SSB_BMC_TX_C_DP")
	)
	(segment
		(start 404.1394 -126.42596)
		(end 404.1394 -126.357634)
		(width 0.1143)
		(layer "In11.Cu")
		(net "P2E_SSB_BMC_TX_C_DP")
	)
	(segment
		(start 420.8653 -57.471056)
		(end 420.8653 -63.30569)
		(width 0.1143)
		(layer "In11.Cu")
		(net "P2E_SSB_BMC_TX_C_DP")
	)
	(segment
		(start 414.987232 -45.673772)
		(end 414.296606 -46.364398)
		(width 0.1143)
		(layer "In11.Cu")
		(net "P2E_SSB_BMC_TX_C_DP")
	)
	(segment
		(start 414.479994 -122.624596)
		(end 411.361636 -125.742954)
		(width 0.1143)
		(layer "In11.Cu")
		(net "P2E_SSB_BMC_TX_C_DP")
	)
	(segment
		(start 416.371532 -47.14748)
		(end 416.052 -46.827948)
		(width 0.1143)
		(layer "In11.Cu")
		(net "P2E_SSB_BMC_TX_C_DP")
	)
	(segment
		(start 404.1394 -126.357634)
		(end 404.37435 -126.122684)
		(width 0.1143)
		(layer "In11.Cu")
		(net "P2E_SSB_BMC_TX_C_DP")
	)
	(segment
		(start 420.8653 -63.30569)
		(end 422.446958 -64.887348)
		(width 0.1143)
		(layer "In11.Cu")
		(net "P2E_SSB_BMC_TX_C_DP")
	)
	(segment
		(start 416.068764 -43.959272)
		(end 416.157664 -44.048172)
		(width 0.0889)
		(layer "F.Cu")
		(net "P2E_SSB_BMC_TX_C_DN")
	)
	(segment
		(start 416.157664 -43.603672)
		(end 416.068764 -43.692572)
		(width 0.0889)
		(layer "F.Cu")
		(net "P2E_SSB_BMC_TX_C_DN")
	)
	(segment
		(start 416.068764 -46.092872)
		(end 416.132264 -46.156372)
		(width 0.0889)
		(layer "F.Cu")
		(net "P2E_SSB_BMC_TX_C_DN")
	)
	(segment
		(start 416.157664 -45.470572)
		(end 416.157664 -45.737272)
		(width 0.0889)
		(layer "F.Cu")
		(net "P2E_SSB_BMC_TX_C_DN")
	)
	(segment
		(start 416.068764 -43.334686)
		(end 416.157664 -43.423586)
		(width 0.0889)
		(layer "F.Cu")
		(net "P2E_SSB_BMC_TX_C_DN")
	)
	(segment
		(start 416.068764 -45.826172)
		(end 416.068764 -46.092872)
		(width 0.0889)
		(layer "F.Cu")
		(net "P2E_SSB_BMC_TX_C_DN")
	)
	(segment
		(start 416.068764 -44.403772)
		(end 416.068764 -44.670472)
		(width 0.0889)
		(layer "F.Cu")
		(net "P2E_SSB_BMC_TX_C_DN")
	)
	(segment
		(start 415.863278 -47.102776)
		(end 415.379154 -47.102776)
		(width 0.0889)
		(layer "F.Cu")
		(net "P2E_SSB_BMC_TX_C_DN")
	)
	(segment
		(start 415.97961 -46.986444)
		(end 415.863278 -47.102776)
		(width 0.0889)
		(layer "F.Cu")
		(net "P2E_SSB_BMC_TX_C_DN")
	)
	(segment
		(start 415.8234 -47.755556)
		(end 415.749994 -47.828962)
		(width 0.1143)
		(layer "F.Cu")
		(net "P2E_SSB_BMC_TX_C_DN")
	)
	(segment
		(start 416.068764 -44.670472)
		(end 416.157664 -44.759372)
		(width 0.0889)
		(layer "F.Cu")
		(net "P2E_SSB_BMC_TX_C_DN")
	)
	(segment
		(start 416.068764 -45.381672)
		(end 416.157664 -45.470572)
		(width 0.0889)
		(layer "F.Cu")
		(net "P2E_SSB_BMC_TX_C_DN")
	)
	(segment
		(start 415.8234 -47.547022)
		(end 415.8234 -47.755556)
		(width 0.1143)
		(layer "F.Cu")
		(net "P2E_SSB_BMC_TX_C_DN")
	)
	(segment
		(start 415.97961 -46.464728)
		(end 415.97961 -46.986444)
		(width 0.0889)
		(layer "F.Cu")
		(net "P2E_SSB_BMC_TX_C_DN")
	)
	(segment
		(start 416.157664 -44.759372)
		(end 416.157664 -45.026072)
		(width 0.0889)
		(layer "F.Cu")
		(net "P2E_SSB_BMC_TX_C_DN")
	)
	(segment
		(start 416.157664 -45.737272)
		(end 416.068764 -45.826172)
		(width 0.0889)
		(layer "F.Cu")
		(net "P2E_SSB_BMC_TX_C_DN")
	)
	(segment
		(start 416.157664 -44.048172)
		(end 416.157664 -44.314872)
		(width 0.0889)
		(layer "F.Cu")
		(net "P2E_SSB_BMC_TX_C_DN")
	)
	(segment
		(start 415.890202 -43.334686)
		(end 416.068764 -43.334686)
		(width 0.0889)
		(layer "F.Cu")
		(net "P2E_SSB_BMC_TX_C_DN")
	)
	(segment
		(start 416.157664 -45.026072)
		(end 416.068764 -45.114972)
		(width 0.0889)
		(layer "F.Cu")
		(net "P2E_SSB_BMC_TX_C_DN")
	)
	(segment
		(start 416.068764 -43.692572)
		(end 416.068764 -43.959272)
		(width 0.0889)
		(layer "F.Cu")
		(net "P2E_SSB_BMC_TX_C_DN")
	)
	(segment
		(start 416.132264 -46.156372)
		(end 416.132264 -46.312074)
		(width 0.0889)
		(layer "F.Cu")
		(net "P2E_SSB_BMC_TX_C_DN")
	)
	(segment
		(start 416.157664 -44.314872)
		(end 416.068764 -44.403772)
		(width 0.0889)
		(layer "F.Cu")
		(net "P2E_SSB_BMC_TX_C_DN")
	)
	(segment
		(start 416.157664 -43.423586)
		(end 416.157664 -43.603672)
		(width 0.0889)
		(layer "F.Cu")
		(net "P2E_SSB_BMC_TX_C_DN")
	)
	(segment
		(start 416.068764 -45.114972)
		(end 416.068764 -45.381672)
		(width 0.0889)
		(layer "F.Cu")
		(net "P2E_SSB_BMC_TX_C_DN")
	)
	(segment
		(start 416.132264 -46.312074)
		(end 415.97961 -46.464728)
		(width 0.0889)
		(layer "F.Cu")
		(net "P2E_SSB_BMC_TX_C_DN")
	)
	(segment
		(start 415.379154 -47.102776)
		(end 415.8234 -47.547022)
		(width 0.1143)
		(layer "F.Cu")
		(net "P2E_SSB_BMC_TX_C_DN")
	)
	(via
		(at 403.30501 -125.300232)
		(size 0.508)
		(drill 0.254)
		(layers "F.Cu" "B.Cu")
		(net "P2E_SSB_BMC_TX_C_DN")
	)
	(via
		(at 403.61235 -125.97765)
		(size 0.508)
		(drill 0.254)
		(layers "F.Cu" "B.Cu")
		(net "P2E_SSB_BMC_TX_C_DN")
	)
	(via
		(at 415.379154 -47.102776)
		(size 0.508)
		(drill 0.254)
		(layers "F.Cu" "B.Cu")
		(net "P2E_SSB_BMC_TX_C_DN")
	)
	(segment
		(start 402.252434 -125.300232)
		(end 402.366734 -125.414532)
		(width 0.1143)
		(layer "B.Cu")
		(net "P2E_SSB_BMC_TX_C_DN")
	)
	(segment
		(start 401.661376 -125.300232)
		(end 402.252434 -125.300232)
		(width 0.1143)
		(layer "B.Cu")
		(net "P2E_SSB_BMC_TX_C_DN")
	)
	(segment
		(start 403.97684 -125.61316)
		(end 403.61235 -125.97765)
		(width 0.1143)
		(layer "B.Cu")
		(net "P2E_SSB_BMC_TX_C_DN")
	)
	(segment
		(start 403.30501 -125.300232)
		(end 403.789896 -125.300232)
		(width 0.1143)
		(layer "B.Cu")
		(net "P2E_SSB_BMC_TX_C_DN")
	)
	(segment
		(start 401.204176 -125.414532)
		(end 401.547076 -125.414532)
		(width 0.1143)
		(layer "B.Cu")
		(net "P2E_SSB_BMC_TX_C_DN")
	)
	(segment
		(start 402.366734 -125.414532)
		(end 402.709634 -125.414532)
		(width 0.1143)
		(layer "B.Cu")
		(net "P2E_SSB_BMC_TX_C_DN")
	)
	(segment
		(start 401.089876 -125.300232)
		(end 401.204176 -125.414532)
		(width 0.1143)
		(layer "B.Cu")
		(net "P2E_SSB_BMC_TX_C_DN")
	)
	(segment
		(start 402.709634 -125.414532)
		(end 402.823934 -125.300232)
		(width 0.1143)
		(layer "B.Cu")
		(net "P2E_SSB_BMC_TX_C_DN")
	)
	(segment
		(start 400.419824 -125.627384)
		(end 400.746976 -125.300232)
		(width 0.1143)
		(layer "B.Cu")
		(net "P2E_SSB_BMC_TX_C_DN")
	)
	(segment
		(start 403.789896 -125.300232)
		(end 403.97684 -125.487176)
		(width 0.1143)
		(layer "B.Cu")
		(net "P2E_SSB_BMC_TX_C_DN")
	)
	(segment
		(start 403.97684 -125.487176)
		(end 403.97684 -125.61316)
		(width 0.1143)
		(layer "B.Cu")
		(net "P2E_SSB_BMC_TX_C_DN")
	)
	(segment
		(start 402.823934 -125.300232)
		(end 403.30501 -125.300232)
		(width 0.1143)
		(layer "B.Cu")
		(net "P2E_SSB_BMC_TX_C_DN")
	)
	(segment
		(start 401.547076 -125.414532)
		(end 401.661376 -125.300232)
		(width 0.1143)
		(layer "B.Cu")
		(net "P2E_SSB_BMC_TX_C_DN")
	)
	(segment
		(start 400.746976 -125.300232)
		(end 401.089876 -125.300232)
		(width 0.1143)
		(layer "B.Cu")
		(net "P2E_SSB_BMC_TX_C_DN")
	)
	(segment
		(start 414.601152 -122.916696)
		(end 411.482794 -126.035054)
		(width 0.1143)
		(layer "In11.Cu")
		(net "P2E_SSB_BMC_TX_C_DN")
	)
	(segment
		(start 422.212516 -79.239618)
		(end 422.941496 -79.968598)
		(width 0.1143)
		(layer "In11.Cu")
		(net "P2E_SSB_BMC_TX_C_DN")
	)
	(segment
		(start 417.877244 -120.929654)
		(end 417.877244 -121.803668)
		(width 0.1143)
		(layer "In11.Cu")
		(net "P2E_SSB_BMC_TX_C_DN")
	)
	(segment
		(start 414.588706 -47.595028)
		(end 412.998666 -49.185068)
		(width 0.1143)
		(layer "In11.Cu")
		(net "P2E_SSB_BMC_TX_C_DN")
	)
	(segment
		(start 421.560498 -97.015808)
		(end 422.780714 -98.236024)
		(width 0.1143)
		(layer "In11.Cu")
		(net "P2E_SSB_BMC_TX_C_DN")
	)
	(segment
		(start 422.739058 -64.76619)
		(end 422.739058 -77.749654)
		(width 0.1143)
		(layer "In11.Cu")
		(net "P2E_SSB_BMC_TX_C_DN")
	)
	(segment
		(start 421.1574 -63.184532)
		(end 422.739058 -64.76619)
		(width 0.1143)
		(layer "In11.Cu")
		(net "P2E_SSB_BMC_TX_C_DN")
	)
	(segment
		(start 403.61235 -126.14021)
		(end 403.61235 -125.97765)
		(width 0.1143)
		(layer "In11.Cu")
		(net "P2E_SSB_BMC_TX_C_DN")
	)
	(segment
		(start 404.109682 -126.8095)
		(end 403.8473 -126.547118)
		(width 0.1143)
		(layer "In11.Cu")
		(net "P2E_SSB_BMC_TX_C_DN")
	)
	(segment
		(start 422.212516 -78.276196)
		(end 422.212516 -79.239618)
		(width 0.1143)
		(layer "In11.Cu")
		(net "P2E_SSB_BMC_TX_C_DN")
	)
	(segment
		(start 421.560498 -95.137986)
		(end 421.560498 -97.015808)
		(width 0.1143)
		(layer "In11.Cu")
		(net "P2E_SSB_BMC_TX_C_DN")
	)
	(segment
		(start 412.998666 -49.185068)
		(end 412.998666 -49.911254)
		(width 0.1143)
		(layer "In11.Cu")
		(net "P2E_SSB_BMC_TX_C_DN")
	)
	(segment
		(start 419.4175 -54.047644)
		(end 419.4175 -55.610252)
		(width 0.1143)
		(layer "In11.Cu")
		(net "P2E_SSB_BMC_TX_C_DN")
	)
	(segment
		(start 417.877244 -121.803668)
		(end 416.764216 -122.916696)
		(width 0.1143)
		(layer "In11.Cu")
		(net "P2E_SSB_BMC_TX_C_DN")
	)
	(segment
		(start 415.7599 -46.72203)
		(end 415.7599 -46.272958)
		(width 0.1143)
		(layer "In11.Cu")
		(net "P2E_SSB_BMC_TX_C_DN")
	)
	(segment
		(start 415.7599 -46.272958)
		(end 415.452814 -45.965872)
		(width 0.1143)
		(layer "In11.Cu")
		(net "P2E_SSB_BMC_TX_C_DN")
	)
	(segment
		(start 412.998666 -49.911254)
		(end 414.243012 -51.1556)
		(width 0.1143)
		(layer "In11.Cu")
		(net "P2E_SSB_BMC_TX_C_DN")
	)
	(segment
		(start 422.780714 -103.608632)
		(end 422.093898 -104.295448)
		(width 0.1143)
		(layer "In11.Cu")
		(net "P2E_SSB_BMC_TX_C_DN")
	)
	(segment
		(start 421.41013 -117.396768)
		(end 417.877244 -120.929654)
		(width 0.1143)
		(layer "In11.Cu")
		(net "P2E_SSB_BMC_TX_C_DN")
	)
	(segment
		(start 415.379154 -47.102776)
		(end 415.7599 -46.72203)
		(width 0.1143)
		(layer "In11.Cu")
		(net "P2E_SSB_BMC_TX_C_DN")
	)
	(segment
		(start 403.8473 -126.37516)
		(end 403.61235 -126.14021)
		(width 0.1143)
		(layer "In11.Cu")
		(net "P2E_SSB_BMC_TX_C_DN")
	)
	(segment
		(start 422.093898 -109.59465)
		(end 421.4368 -110.251748)
		(width 0.1143)
		(layer "In11.Cu")
		(net "P2E_SSB_BMC_TX_C_DN")
	)
	(segment
		(start 421.4368 -110.251748)
		(end 421.4368 -117.31879)
		(width 0.1143)
		(layer "In11.Cu")
		(net "P2E_SSB_BMC_TX_C_DN")
	)
	(segment
		(start 414.588706 -46.485556)
		(end 414.588706 -47.595028)
		(width 0.1143)
		(layer "In11.Cu")
		(net "P2E_SSB_BMC_TX_C_DN")
	)
	(segment
		(start 419.4175 -55.610252)
		(end 421.1574 -57.349898)
		(width 0.1143)
		(layer "In11.Cu")
		(net "P2E_SSB_BMC_TX_C_DN")
	)
	(segment
		(start 422.941496 -79.968598)
		(end 422.941496 -93.756988)
		(width 0.1143)
		(layer "In11.Cu")
		(net "P2E_SSB_BMC_TX_C_DN")
	)
	(segment
		(start 422.941496 -93.756988)
		(end 421.560498 -95.137986)
		(width 0.1143)
		(layer "In11.Cu")
		(net "P2E_SSB_BMC_TX_C_DN")
	)
	(segment
		(start 409.333446 -126.200154)
		(end 408.990546 -126.200154)
		(width 0.1143)
		(layer "In11.Cu")
		(net "P2E_SSB_BMC_TX_C_DN")
	)
	(segment
		(start 422.739058 -77.749654)
		(end 422.212516 -78.276196)
		(width 0.1143)
		(layer "In11.Cu")
		(net "P2E_SSB_BMC_TX_C_DN")
	)
	(segment
		(start 415.10839 -45.965872)
		(end 414.588706 -46.485556)
		(width 0.1143)
		(layer "In11.Cu")
		(net "P2E_SSB_BMC_TX_C_DN")
	)
	(segment
		(start 416.525456 -51.1556)
		(end 419.4175 -54.047644)
		(width 0.1143)
		(layer "In11.Cu")
		(net "P2E_SSB_BMC_TX_C_DN")
	)
	(segment
		(start 411.482794 -126.035054)
		(end 409.498546 -126.035054)
		(width 0.1143)
		(layer "In11.Cu")
		(net "P2E_SSB_BMC_TX_C_DN")
	)
	(segment
		(start 408.482546 -126.035054)
		(end 407.7081 -126.8095)
		(width 0.1143)
		(layer "In11.Cu")
		(net "P2E_SSB_BMC_TX_C_DN")
	)
	(segment
		(start 408.825446 -126.035054)
		(end 408.482546 -126.035054)
		(width 0.1143)
		(layer "In11.Cu")
		(net "P2E_SSB_BMC_TX_C_DN")
	)
	(segment
		(start 421.4368 -117.31879)
		(end 421.41013 -117.34546)
		(width 0.1143)
		(layer "In11.Cu")
		(net "P2E_SSB_BMC_TX_C_DN")
	)
	(segment
		(start 416.764216 -122.916696)
		(end 414.601152 -122.916696)
		(width 0.1143)
		(layer "In11.Cu")
		(net "P2E_SSB_BMC_TX_C_DN")
	)
	(segment
		(start 409.498546 -126.035054)
		(end 409.333446 -126.200154)
		(width 0.1143)
		(layer "In11.Cu")
		(net "P2E_SSB_BMC_TX_C_DN")
	)
	(segment
		(start 415.452814 -45.965872)
		(end 415.10839 -45.965872)
		(width 0.1143)
		(layer "In11.Cu")
		(net "P2E_SSB_BMC_TX_C_DN")
	)
	(segment
		(start 408.990546 -126.200154)
		(end 408.825446 -126.035054)
		(width 0.1143)
		(layer "In11.Cu")
		(net "P2E_SSB_BMC_TX_C_DN")
	)
	(segment
		(start 422.780714 -98.236024)
		(end 422.780714 -103.608632)
		(width 0.1143)
		(layer "In11.Cu")
		(net "P2E_SSB_BMC_TX_C_DN")
	)
	(segment
		(start 421.1574 -57.349898)
		(end 421.1574 -63.184532)
		(width 0.1143)
		(layer "In11.Cu")
		(net "P2E_SSB_BMC_TX_C_DN")
	)
	(segment
		(start 421.41013 -117.34546)
		(end 421.41013 -117.396768)
		(width 0.1143)
		(layer "In11.Cu")
		(net "P2E_SSB_BMC_TX_C_DN")
	)
	(segment
		(start 414.243012 -51.1556)
		(end 416.525456 -51.1556)
		(width 0.1143)
		(layer "In11.Cu")
		(net "P2E_SSB_BMC_TX_C_DN")
	)
	(segment
		(start 407.7081 -126.8095)
		(end 404.109682 -126.8095)
		(width 0.1143)
		(layer "In11.Cu")
		(net "P2E_SSB_BMC_TX_C_DN")
	)
	(segment
		(start 422.093898 -104.295448)
		(end 422.093898 -109.59465)
		(width 0.1143)
		(layer "In11.Cu")
		(net "P2E_SSB_BMC_TX_C_DN")
	)
	(segment
		(start 403.8473 -126.547118)
		(end 403.8473 -126.37516)
		(width 0.1143)
		(layer "In11.Cu")
		(net "P2E_SSB_BMC_TX_C_DN")
	)
	(segment
		(start 414.962594 -48.083216)
		(end 414.705292 -47.825914)
		(width 0.0889)
		(layer "F.Cu")
		(net "P2E_SSB_BMC_RX_DP")
	)
	(segment
		(start 414.705292 -47.825914)
		(end 414.705292 -46.00702)
		(width 0.0889)
		(layer "F.Cu")
		(net "P2E_SSB_BMC_RX_DP")
	)
	(segment
		(start 415.548064 -45.653452)
		(end 415.548064 -43.368976)
		(width 0.0889)
		(layer "F.Cu")
		(net "P2E_SSB_BMC_RX_DP")
	)
	(segment
		(start 415.548064 -43.368976)
		(end 415.090102 -42.534586)
		(width 0.0889)
		(layer "F.Cu")
		(net "P2E_SSB_BMC_RX_DP")
	)
	(segment
		(start 415.126932 -45.853858)
		(end 415.347658 -45.853858)
		(width 0.0889)
		(layer "F.Cu")
		(net "P2E_SSB_BMC_RX_DP")
	)
	(segment
		(start 415.347658 -45.853858)
		(end 415.548064 -45.653452)
		(width 0.0889)
		(layer "F.Cu")
		(net "P2E_SSB_BMC_RX_DP")
	)
	(segment
		(start 414.858454 -45.853858)
		(end 415.126932 -45.853858)
		(width 0.0889)
		(layer "F.Cu")
		(net "P2E_SSB_BMC_RX_DP")
	)
	(segment
		(start 414.705292 -46.00702)
		(end 414.858454 -45.853858)
		(width 0.0889)
		(layer "F.Cu")
		(net "P2E_SSB_BMC_RX_DP")
	)
	(via
		(at 415.126932 -45.853858)
		(size 0.508)
		(drill 0.254)
		(layers "F.Cu" "B.Cu")
		(net "P2E_SSB_BMC_RX_DP")
	)
	(segment
		(start 414.425892 -46.44771)
		(end 414.425892 -46.18101)
		(width 0.0889)
		(layer "F.Cu")
		(net "P2E_SSB_BMC_RX_DN")
	)
	(segment
		(start 414.425892 -46.89221)
		(end 414.514792 -46.80331)
		(width 0.0889)
		(layer "F.Cu")
		(net "P2E_SSB_BMC_RX_DN")
	)
	(segment
		(start 415.257996 -45.637958)
		(end 415.332164 -45.56379)
		(width 0.0889)
		(layer "F.Cu")
		(net "P2E_SSB_BMC_RX_DN")
	)
	(segment
		(start 414.514792 -46.53661)
		(end 414.425892 -46.44771)
		(width 0.0889)
		(layer "F.Cu")
		(net "P2E_SSB_BMC_RX_DN")
	)
	(segment
		(start 415.357564 -43.603672)
		(end 415.357564 -43.423586)
		(width 0.0889)
		(layer "F.Cu")
		(net "P2E_SSB_BMC_RX_DN")
	)
	(segment
		(start 414.514792 -46.09211)
		(end 414.514792 -45.891958)
		(width 0.0889)
		(layer "F.Cu")
		(net "P2E_SSB_BMC_RX_DN")
	)
	(segment
		(start 414.514792 -45.891958)
		(end 414.768792 -45.637958)
		(width 0.0889)
		(layer "F.Cu")
		(net "P2E_SSB_BMC_RX_DN")
	)
	(segment
		(start 414.514792 -47.24781)
		(end 414.425892 -47.15891)
		(width 0.0889)
		(layer "F.Cu")
		(net "P2E_SSB_BMC_RX_DN")
	)
	(segment
		(start 415.357564 -43.423586)
		(end 415.268664 -43.334686)
		(width 0.0889)
		(layer "F.Cu")
		(net "P2E_SSB_BMC_RX_DN")
	)
	(segment
		(start 414.514792 -47.58182)
		(end 414.514792 -47.24781)
		(width 0.0889)
		(layer "F.Cu")
		(net "P2E_SSB_BMC_RX_DN")
	)
	(segment
		(start 414.057592 -48.015398)
		(end 414.057592 -47.759874)
		(width 0.0889)
		(layer "F.Cu")
		(net "P2E_SSB_BMC_RX_DN")
	)
	(segment
		(start 415.357564 -44.759372)
		(end 415.268664 -44.670472)
		(width 0.0889)
		(layer "F.Cu")
		(net "P2E_SSB_BMC_RX_DN")
	)
	(segment
		(start 415.268664 -44.403772)
		(end 415.357564 -44.314872)
		(width 0.0889)
		(layer "F.Cu")
		(net "P2E_SSB_BMC_RX_DN")
	)
	(segment
		(start 415.357564 -44.314872)
		(end 415.357564 -44.048172)
		(width 0.0889)
		(layer "F.Cu")
		(net "P2E_SSB_BMC_RX_DN")
	)
	(segment
		(start 414.768792 -45.637958)
		(end 415.257996 -45.637958)
		(width 0.0889)
		(layer "F.Cu")
		(net "P2E_SSB_BMC_RX_DN")
	)
	(segment
		(start 415.357564 -45.026072)
		(end 415.357564 -44.759372)
		(width 0.0889)
		(layer "F.Cu")
		(net "P2E_SSB_BMC_RX_DN")
	)
	(segment
		(start 414.425892 -46.18101)
		(end 414.514792 -46.09211)
		(width 0.0889)
		(layer "F.Cu")
		(net "P2E_SSB_BMC_RX_DN")
	)
	(segment
		(start 414.514792 -46.80331)
		(end 414.514792 -46.53661)
		(width 0.0889)
		(layer "F.Cu")
		(net "P2E_SSB_BMC_RX_DN")
	)
	(segment
		(start 414.425892 -47.15891)
		(end 414.425892 -46.89221)
		(width 0.0889)
		(layer "F.Cu")
		(net "P2E_SSB_BMC_RX_DN")
	)
	(segment
		(start 415.332164 -45.56379)
		(end 415.332164 -45.445172)
		(width 0.0889)
		(layer "F.Cu")
		(net "P2E_SSB_BMC_RX_DN")
	)
	(segment
		(start 414.425892 -47.67072)
		(end 414.514792 -47.58182)
		(width 0.0889)
		(layer "F.Cu")
		(net "P2E_SSB_BMC_RX_DN")
	)
	(segment
		(start 414.146746 -47.67072)
		(end 414.425892 -47.67072)
		(width 0.0889)
		(layer "F.Cu")
		(net "P2E_SSB_BMC_RX_DN")
	)
	(segment
		(start 415.268664 -45.114972)
		(end 415.357564 -45.026072)
		(width 0.0889)
		(layer "F.Cu")
		(net "P2E_SSB_BMC_RX_DN")
	)
	(segment
		(start 414.057592 -47.759874)
		(end 414.146746 -47.67072)
		(width 0.0889)
		(layer "F.Cu")
		(net "P2E_SSB_BMC_RX_DN")
	)
	(segment
		(start 415.268664 -43.959272)
		(end 415.268664 -43.692572)
		(width 0.0889)
		(layer "F.Cu")
		(net "P2E_SSB_BMC_RX_DN")
	)
	(segment
		(start 415.268664 -43.692572)
		(end 415.357564 -43.603672)
		(width 0.0889)
		(layer "F.Cu")
		(net "P2E_SSB_BMC_RX_DN")
	)
	(segment
		(start 415.268664 -45.381672)
		(end 415.268664 -45.114972)
		(width 0.0889)
		(layer "F.Cu")
		(net "P2E_SSB_BMC_RX_DN")
	)
	(segment
		(start 414.126172 -48.083978)
		(end 414.057592 -48.015398)
		(width 0.0889)
		(layer "F.Cu")
		(net "P2E_SSB_BMC_RX_DN")
	)
	(segment
		(start 415.357564 -44.048172)
		(end 415.268664 -43.959272)
		(width 0.0889)
		(layer "F.Cu")
		(net "P2E_SSB_BMC_RX_DN")
	)
	(segment
		(start 415.332164 -45.445172)
		(end 415.268664 -45.381672)
		(width 0.0889)
		(layer "F.Cu")
		(net "P2E_SSB_BMC_RX_DN")
	)
	(segment
		(start 415.268664 -44.670472)
		(end 415.268664 -44.403772)
		(width 0.0889)
		(layer "F.Cu")
		(net "P2E_SSB_BMC_RX_DN")
	)
	(segment
		(start 415.268664 -43.334686)
		(end 415.090102 -43.334686)
		(width 0.0889)
		(layer "F.Cu")
		(net "P2E_SSB_BMC_RX_DN")
	)
	(segment
		(start 388.984998 -126.165102)
		(end 388.984998 -126.332234)
		(width 0.0889)
		(layer "F.Cu")
		(net "P2E_SSB_BMC_RX_C_DP")
	)
	(segment
		(start 388.6454 -126.671832)
		(end 388.6454 -127.11557)
		(width 0.0889)
		(layer "F.Cu")
		(net "P2E_SSB_BMC_RX_C_DP")
	)
	(segment
		(start 414.962594 -49.332642)
		(end 414.67786 -49.617376)
		(width 0.1143)
		(layer "F.Cu")
		(net "P2E_SSB_BMC_RX_C_DP")
	)
	(segment
		(start 414.962594 -48.972216)
		(end 414.962594 -49.332642)
		(width 0.1143)
		(layer "F.Cu")
		(net "P2E_SSB_BMC_RX_C_DP")
	)
	(segment
		(start 388.984998 -126.332234)
		(end 388.6454 -126.671832)
		(width 0.0889)
		(layer "F.Cu")
		(net "P2E_SSB_BMC_RX_C_DP")
	)
	(segment
		(start 388.6454 -127.11557)
		(end 389.04799 -127.51816)
		(width 0.0889)
		(layer "F.Cu")
		(net "P2E_SSB_BMC_RX_C_DP")
	)
	(via
		(at 388.205472 -129.167128)
		(size 0.508)
		(drill 0.254)
		(layers "F.Cu" "B.Cu")
		(net "P2E_SSB_BMC_RX_C_DP")
	)
	(via
		(at 389.04799 -127.51816)
		(size 0.508)
		(drill 0.254)
		(layers "F.Cu" "B.Cu")
		(net "P2E_SSB_BMC_RX_C_DP")
	)
	(via
		(at 414.67786 -49.617376)
		(size 0.508)
		(drill 0.254)
		(layers "F.Cu" "B.Cu")
		(net "P2E_SSB_BMC_RX_C_DP")
	)
	(segment
		(start 388.201154 -129.16281)
		(end 388.205472 -129.167128)
		(width 0.1143)
		(layer "B.Cu")
		(net "P2E_SSB_BMC_RX_C_DP")
	)
	(segment
		(start 388.5692 -128.45161)
		(end 388.4549 -128.56591)
		(width 0.1143)
		(layer "B.Cu")
		(net "P2E_SSB_BMC_RX_C_DP")
	)
	(segment
		(start 389.04799 -127.51816)
		(end 388.837678 -127.307848)
		(width 0.1143)
		(layer "B.Cu")
		(net "P2E_SSB_BMC_RX_C_DP")
	)
	(segment
		(start 387.962902 -129.400808)
		(end 387.962902 -129.87147)
		(width 0.1143)
		(layer "B.Cu")
		(net "P2E_SSB_BMC_RX_C_DP")
	)
	(segment
		(start 387.962902 -129.87147)
		(end 388.091172 -129.99974)
		(width 0.1143)
		(layer "B.Cu")
		(net "P2E_SSB_BMC_RX_C_DP")
	)
	(segment
		(start 388.196582 -129.167128)
		(end 387.962902 -129.400808)
		(width 0.1143)
		(layer "B.Cu")
		(net "P2E_SSB_BMC_RX_C_DP")
	)
	(segment
		(start 388.46125 -127.965454)
		(end 388.4549 -127.971804)
		(width 0.1143)
		(layer "B.Cu")
		(net "P2E_SSB_BMC_RX_C_DP")
	)
	(segment
		(start 388.4549 -127.971804)
		(end 388.4549 -127.99441)
		(width 0.1143)
		(layer "B.Cu")
		(net "P2E_SSB_BMC_RX_C_DP")
	)
	(segment
		(start 388.46125 -127.428498)
		(end 388.46125 -127.965454)
		(width 0.1143)
		(layer "B.Cu")
		(net "P2E_SSB_BMC_RX_C_DP")
	)
	(segment
		(start 388.837678 -127.307848)
		(end 388.5819 -127.307848)
		(width 0.1143)
		(layer "B.Cu")
		(net "P2E_SSB_BMC_RX_C_DP")
	)
	(segment
		(start 388.4549 -127.99441)
		(end 388.5692 -128.10871)
		(width 0.1143)
		(layer "B.Cu")
		(net "P2E_SSB_BMC_RX_C_DP")
	)
	(segment
		(start 388.5819 -127.307848)
		(end 388.46125 -127.428498)
		(width 0.1143)
		(layer "B.Cu")
		(net "P2E_SSB_BMC_RX_C_DP")
	)
	(segment
		(start 388.4549 -128.56591)
		(end 388.4549 -128.90881)
		(width 0.1143)
		(layer "B.Cu")
		(net "P2E_SSB_BMC_RX_C_DP")
	)
	(segment
		(start 388.2009 -129.16281)
		(end 388.201154 -129.16281)
		(width 0.1143)
		(layer "B.Cu")
		(net "P2E_SSB_BMC_RX_C_DP")
	)
	(segment
		(start 388.4549 -128.90881)
		(end 388.2009 -129.16281)
		(width 0.1143)
		(layer "B.Cu")
		(net "P2E_SSB_BMC_RX_C_DP")
	)
	(segment
		(start 388.5692 -128.10871)
		(end 388.5692 -128.45161)
		(width 0.1143)
		(layer "B.Cu")
		(net "P2E_SSB_BMC_RX_C_DP")
	)
	(segment
		(start 388.205472 -129.167128)
		(end 388.196582 -129.167128)
		(width 0.1143)
		(layer "B.Cu")
		(net "P2E_SSB_BMC_RX_C_DP")
	)
	(segment
		(start 388.091172 -129.99974)
		(end 388.366 -129.99974)
		(width 0.1143)
		(layer "B.Cu")
		(net "P2E_SSB_BMC_RX_C_DP")
	)
	(segment
		(start 420.669212 -53.999638)
		(end 419.61435 -52.944776)
		(width 0.1143)
		(layer "In11.Cu")
		(net "P2E_SSB_BMC_RX_C_DP")
	)
	(segment
		(start 421.9321 -110.594394)
		(end 422.659048 -109.867446)
		(width 0.1143)
		(layer "In11.Cu")
		(net "P2E_SSB_BMC_RX_C_DP")
	)
	(segment
		(start 388.19201 -126.296674)
		(end 388.631684 -125.857)
		(width 0.1143)
		(layer "In11.Cu")
		(net "P2E_SSB_BMC_RX_C_DP")
	)
	(segment
		(start 424.854116 -65.531238)
		(end 424.854116 -64.47536)
		(width 0.1143)
		(layer "In11.Cu")
		(net "P2E_SSB_BMC_RX_C_DP")
	)
	(segment
		(start 423.71518 -61.329824)
		(end 423.71518 -61.254132)
		(width 0.1143)
		(layer "In11.Cu")
		(net "P2E_SSB_BMC_RX_C_DP")
	)
	(segment
		(start 423.443146 -79.755238)
		(end 423.239184 -79.551276)
		(width 0.1143)
		(layer "In11.Cu")
		(net "P2E_SSB_BMC_RX_C_DP")
	)
	(segment
		(start 415.596832 -125.390656)
		(end 416.39998 -125.390656)
		(width 0.1143)
		(layer "In11.Cu")
		(net "P2E_SSB_BMC_RX_C_DP")
	)
	(segment
		(start 418.177726 -51.508152)
		(end 417.9443 -51.508152)
		(width 0.1143)
		(layer "In11.Cu")
		(net "P2E_SSB_BMC_RX_C_DP")
	)
	(segment
		(start 423.90695 -61.521594)
		(end 423.71518 -61.329824)
		(width 0.1143)
		(layer "In11.Cu")
		(net "P2E_SSB_BMC_RX_C_DP")
	)
	(segment
		(start 388.19201 -127.09017)
		(end 388.19201 -126.296674)
		(width 0.1143)
		(layer "In11.Cu")
		(net "P2E_SSB_BMC_RX_C_DP")
	)
	(segment
		(start 418.896038 -52.226464)
		(end 418.662612 -52.226464)
		(width 0.1143)
		(layer "In11.Cu")
		(net "P2E_SSB_BMC_RX_C_DP")
	)
	(segment
		(start 412.46679 -127.3048)
		(end 413.218884 -126.552706)
		(width 0.1143)
		(layer "In11.Cu")
		(net "P2E_SSB_BMC_RX_C_DP")
	)
	(segment
		(start 396.169642 -131.956302)
		(end 396.955772 -131.170172)
		(width 0.1143)
		(layer "In11.Cu")
		(net "P2E_SSB_BMC_RX_C_DP")
	)
	(segment
		(start 418.420296 -51.750722)
		(end 418.177726 -51.508152)
		(width 0.1143)
		(layer "In11.Cu")
		(net "P2E_SSB_BMC_RX_C_DP")
	)
	(segment
		(start 423.71518 -61.254132)
		(end 423.443908 -60.98286)
		(width 0.1143)
		(layer "In11.Cu")
		(net "P2E_SSB_BMC_RX_C_DP")
	)
	(segment
		(start 416.594544 -125.196092)
		(end 417.754562 -125.196092)
		(width 0.1143)
		(layer "In11.Cu")
		(net "P2E_SSB_BMC_RX_C_DP")
	)
	(segment
		(start 416.983672 -50.547524)
		(end 416.983672 -50.314098)
		(width 0.1143)
		(layer "In11.Cu")
		(net "P2E_SSB_BMC_RX_C_DP")
	)
	(segment
		(start 414.434782 -126.552706)
		(end 415.596832 -125.390656)
		(width 0.1143)
		(layer "In11.Cu")
		(net "P2E_SSB_BMC_RX_C_DP")
	)
	(segment
		(start 388.905242 -127.375412)
		(end 388.477252 -127.375412)
		(width 0.1143)
		(layer "In11.Cu")
		(net "P2E_SSB_BMC_RX_C_DP")
	)
	(segment
		(start 388.477252 -127.375412)
		(end 388.19201 -127.09017)
		(width 0.1143)
		(layer "In11.Cu")
		(net "P2E_SSB_BMC_RX_C_DP")
	)
	(segment
		(start 422.363392 -59.978036)
		(end 422.363392 -56.293004)
		(width 0.1143)
		(layer "In11.Cu")
		(net "P2E_SSB_BMC_RX_C_DP")
	)
	(segment
		(start 418.229796 -122.663458)
		(end 418.73932 -122.153934)
		(width 0.1143)
		(layer "In11.Cu")
		(net "P2E_SSB_BMC_RX_C_DP")
	)
	(segment
		(start 389.04799 -127.51816)
		(end 388.905242 -127.375412)
		(width 0.1143)
		(layer "In11.Cu")
		(net "P2E_SSB_BMC_RX_C_DP")
	)
	(segment
		(start 416.294062 -48.9712)
		(end 414.529778 -48.9712)
		(width 0.1143)
		(layer "In11.Cu")
		(net "P2E_SSB_BMC_RX_C_DP")
	)
	(segment
		(start 419.138608 -52.70246)
		(end 419.138608 -52.469034)
		(width 0.1143)
		(layer "In11.Cu")
		(net "P2E_SSB_BMC_RX_C_DP")
	)
	(segment
		(start 422.659048 -104.48544)
		(end 423.443146 -103.701342)
		(width 0.1143)
		(layer "In11.Cu")
		(net "P2E_SSB_BMC_RX_C_DP")
	)
	(segment
		(start 388.631684 -125.857)
		(end 390.009888 -125.857)
		(width 0.1143)
		(layer "In11.Cu")
		(net "P2E_SSB_BMC_RX_C_DP")
	)
	(segment
		(start 417.701984 -51.265836)
		(end 417.701984 -51.03241)
		(width 0.1143)
		(layer "In11.Cu")
		(net "P2E_SSB_BMC_RX_C_DP")
	)
	(segment
		(start 399.966688 -131.170172)
		(end 403.83206 -127.3048)
		(width 0.1143)
		(layer "In11.Cu")
		(net "P2E_SSB_BMC_RX_C_DP")
	)
	(segment
		(start 403.83206 -127.3048)
		(end 412.46679 -127.3048)
		(width 0.1143)
		(layer "In11.Cu")
		(net "P2E_SSB_BMC_RX_C_DP")
	)
	(segment
		(start 419.138608 -52.469034)
		(end 418.896038 -52.226464)
		(width 0.1143)
		(layer "In11.Cu")
		(net "P2E_SSB_BMC_RX_C_DP")
	)
	(segment
		(start 417.225988 -50.78984)
		(end 416.983672 -50.547524)
		(width 0.1143)
		(layer "In11.Cu")
		(net "P2E_SSB_BMC_RX_C_DP")
	)
	(segment
		(start 391.746994 -131.956302)
		(end 396.169642 -131.956302)
		(width 0.1143)
		(layer "In11.Cu")
		(net "P2E_SSB_BMC_RX_C_DP")
	)
	(segment
		(start 417.459414 -50.78984)
		(end 417.225988 -50.78984)
		(width 0.1143)
		(layer "In11.Cu")
		(net "P2E_SSB_BMC_RX_C_DP")
	)
	(segment
		(start 414.529778 -48.9712)
		(end 414.36163 -49.139348)
		(width 0.1143)
		(layer "In11.Cu")
		(net "P2E_SSB_BMC_RX_C_DP")
	)
	(segment
		(start 419.380924 -52.944776)
		(end 419.138608 -52.70246)
		(width 0.1143)
		(layer "In11.Cu")
		(net "P2E_SSB_BMC_RX_C_DP")
	)
	(segment
		(start 418.229796 -124.720858)
		(end 418.229796 -122.663458)
		(width 0.1143)
		(layer "In11.Cu")
		(net "P2E_SSB_BMC_RX_C_DP")
	)
	(segment
		(start 417.754562 -125.196092)
		(end 418.229796 -124.720858)
		(width 0.1143)
		(layer "In11.Cu")
		(net "P2E_SSB_BMC_RX_C_DP")
	)
	(segment
		(start 422.659048 -109.867446)
		(end 422.659048 -104.48544)
		(width 0.1143)
		(layer "In11.Cu")
		(net "P2E_SSB_BMC_RX_C_DP")
	)
	(segment
		(start 390.009888 -125.857)
		(end 390.539732 -126.386844)
		(width 0.1143)
		(layer "In11.Cu")
		(net "P2E_SSB_BMC_RX_C_DP")
	)
	(segment
		(start 414.36163 -49.301146)
		(end 414.67786 -49.617376)
		(width 0.1143)
		(layer "In11.Cu")
		(net "P2E_SSB_BMC_RX_C_DP")
	)
	(segment
		(start 424.854116 -64.47536)
		(end 423.90695 -63.528194)
		(width 0.1143)
		(layer "In11.Cu")
		(net "P2E_SSB_BMC_RX_C_DP")
	)
	(segment
		(start 423.129456 -116.655596)
		(end 423.129456 -114.30889)
		(width 0.1143)
		(layer "In11.Cu")
		(net "P2E_SSB_BMC_RX_C_DP")
	)
	(segment
		(start 423.443146 -103.701342)
		(end 423.443146 -79.755238)
		(width 0.1143)
		(layer "In11.Cu")
		(net "P2E_SSB_BMC_RX_C_DP")
	)
	(segment
		(start 416.983672 -50.314098)
		(end 416.741102 -50.071528)
		(width 0.1143)
		(layer "In11.Cu")
		(net "P2E_SSB_BMC_RX_C_DP")
	)
	(segment
		(start 423.368216 -60.98286)
		(end 422.363392 -59.978036)
		(width 0.1143)
		(layer "In11.Cu")
		(net "P2E_SSB_BMC_RX_C_DP")
	)
	(segment
		(start 423.129456 -114.30889)
		(end 421.9321 -113.111534)
		(width 0.1143)
		(layer "In11.Cu")
		(net "P2E_SSB_BMC_RX_C_DP")
	)
	(segment
		(start 421.9321 -113.111534)
		(end 421.9321 -110.594394)
		(width 0.1143)
		(layer "In11.Cu")
		(net "P2E_SSB_BMC_RX_C_DP")
	)
	(segment
		(start 416.39998 -125.390656)
		(end 416.594544 -125.196092)
		(width 0.1143)
		(layer "In11.Cu")
		(net "P2E_SSB_BMC_RX_C_DP")
	)
	(segment
		(start 396.955772 -131.170172)
		(end 399.966688 -131.170172)
		(width 0.1143)
		(layer "In11.Cu")
		(net "P2E_SSB_BMC_RX_C_DP")
	)
	(segment
		(start 418.73932 -121.045732)
		(end 423.129456 -116.655596)
		(width 0.1143)
		(layer "In11.Cu")
		(net "P2E_SSB_BMC_RX_C_DP")
	)
	(segment
		(start 414.36163 -49.139348)
		(end 414.36163 -49.301146)
		(width 0.1143)
		(layer "In11.Cu")
		(net "P2E_SSB_BMC_RX_C_DP")
	)
	(segment
		(start 413.218884 -126.552706)
		(end 414.434782 -126.552706)
		(width 0.1143)
		(layer "In11.Cu")
		(net "P2E_SSB_BMC_RX_C_DP")
	)
	(segment
		(start 417.701984 -51.03241)
		(end 417.459414 -50.78984)
		(width 0.1143)
		(layer "In11.Cu")
		(net "P2E_SSB_BMC_RX_C_DP")
	)
	(segment
		(start 418.420296 -51.984148)
		(end 418.420296 -51.750722)
		(width 0.1143)
		(layer "In11.Cu")
		(net "P2E_SSB_BMC_RX_C_DP")
	)
	(segment
		(start 422.363392 -56.293004)
		(end 420.669212 -54.598824)
		(width 0.1143)
		(layer "In11.Cu")
		(net "P2E_SSB_BMC_RX_C_DP")
	)
	(segment
		(start 416.741102 -49.41824)
		(end 416.294062 -48.9712)
		(width 0.1143)
		(layer "In11.Cu")
		(net "P2E_SSB_BMC_RX_C_DP")
	)
	(segment
		(start 418.662612 -52.226464)
		(end 418.420296 -51.984148)
		(width 0.1143)
		(layer "In11.Cu")
		(net "P2E_SSB_BMC_RX_C_DP")
	)
	(segment
		(start 419.61435 -52.944776)
		(end 419.380924 -52.944776)
		(width 0.1143)
		(layer "In11.Cu")
		(net "P2E_SSB_BMC_RX_C_DP")
	)
	(segment
		(start 423.90695 -63.528194)
		(end 423.90695 -61.521594)
		(width 0.1143)
		(layer "In11.Cu")
		(net "P2E_SSB_BMC_RX_C_DP")
	)
	(segment
		(start 416.741102 -50.071528)
		(end 416.741102 -49.41824)
		(width 0.1143)
		(layer "In11.Cu")
		(net "P2E_SSB_BMC_RX_C_DP")
	)
	(segment
		(start 423.239184 -67.14617)
		(end 424.854116 -65.531238)
		(width 0.1143)
		(layer "In11.Cu")
		(net "P2E_SSB_BMC_RX_C_DP")
	)
	(segment
		(start 423.239184 -79.551276)
		(end 423.239184 -67.14617)
		(width 0.1143)
		(layer "In11.Cu")
		(net "P2E_SSB_BMC_RX_C_DP")
	)
	(segment
		(start 423.443908 -60.98286)
		(end 423.368216 -60.98286)
		(width 0.1143)
		(layer "In11.Cu")
		(net "P2E_SSB_BMC_RX_C_DP")
	)
	(segment
		(start 390.539732 -126.386844)
		(end 390.539732 -130.74904)
		(width 0.1143)
		(layer "In11.Cu")
		(net "P2E_SSB_BMC_RX_C_DP")
	)
	(segment
		(start 417.9443 -51.508152)
		(end 417.701984 -51.265836)
		(width 0.1143)
		(layer "In11.Cu")
		(net "P2E_SSB_BMC_RX_C_DP")
	)
	(segment
		(start 390.539732 -130.74904)
		(end 391.746994 -131.956302)
		(width 0.1143)
		(layer "In11.Cu")
		(net "P2E_SSB_BMC_RX_C_DP")
	)
	(segment
		(start 418.73932 -122.153934)
		(end 418.73932 -121.045732)
		(width 0.1143)
		(layer "In11.Cu")
		(net "P2E_SSB_BMC_RX_C_DP")
	)
	(segment
		(start 420.669212 -54.598824)
		(end 420.669212 -53.999638)
		(width 0.1143)
		(layer "In11.Cu")
		(net "P2E_SSB_BMC_RX_C_DP")
	)
	(segment
		(start 389.044434 -125.485652)
		(end 389.2804 -126.084838)
		(width 0.0889)
		(layer "F.Cu")
		(net "P2E_SSB_BMC_RX_C_DN")
	)
	(segment
		(start 388.984998 -125.33503)
		(end 389.003032 -125.38075)
		(width 0.0889)
		(layer "F.Cu")
		(net "P2E_SSB_BMC_RX_C_DN")
	)
	(segment
		(start 388.96925 -126.80442)
		(end 389.04799 -126.88316)
		(width 0.0889)
		(layer "F.Cu")
		(net "P2E_SSB_BMC_RX_C_DN")
	)
	(segment
		(start 389.2804 -126.084838)
		(end 389.2804 -126.314454)
		(width 0.0889)
		(layer "F.Cu")
		(net "P2E_SSB_BMC_RX_C_DN")
	)
	(segment
		(start 414.126172 -48.972978)
		(end 414.126172 -49.244504)
		(width 0.1143)
		(layer "F.Cu")
		(net "P2E_SSB_BMC_RX_C_DN")
	)
	(segment
		(start 389.003032 -125.38075)
		(end 389.044434 -125.485652)
		(width 0.0889)
		(layer "F.Cu")
		(net "P2E_SSB_BMC_RX_C_DN")
	)
	(segment
		(start 389.2804 -126.314454)
		(end 388.96925 -126.625604)
		(width 0.0889)
		(layer "F.Cu")
		(net "P2E_SSB_BMC_RX_C_DN")
	)
	(segment
		(start 414.126172 -49.244504)
		(end 413.7533 -49.617376)
		(width 0.1143)
		(layer "F.Cu")
		(net "P2E_SSB_BMC_RX_C_DN")
	)
	(segment
		(start 388.96925 -126.625604)
		(end 388.96925 -126.80442)
		(width 0.0889)
		(layer "F.Cu")
		(net "P2E_SSB_BMC_RX_C_DN")
	)
	(via
		(at 388.2136 -127.635)
		(size 0.508)
		(drill 0.254)
		(layers "F.Cu" "B.Cu")
		(net "P2E_SSB_BMC_RX_C_DN")
	)
	(via
		(at 413.7533 -49.617376)
		(size 0.508)
		(drill 0.254)
		(layers "F.Cu" "B.Cu")
		(net "P2E_SSB_BMC_RX_C_DN")
	)
	(via
		(at 389.04799 -126.88316)
		(size 0.508)
		(drill 0.254)
		(layers "F.Cu" "B.Cu")
		(net "P2E_SSB_BMC_RX_C_DN")
	)
	(segment
		(start 388.2136 -127.334772)
		(end 388.481824 -127.066548)
		(width 0.1143)
		(layer "B.Cu")
		(net "P2E_SSB_BMC_RX_C_DN")
	)
	(segment
		(start 388.2136 -128.808734)
		(end 388.2136 -127.635)
		(width 0.1143)
		(layer "B.Cu")
		(net "P2E_SSB_BMC_RX_C_DN")
	)
	(segment
		(start 388.864602 -127.066548)
		(end 389.04799 -126.88316)
		(width 0.1143)
		(layer "B.Cu")
		(net "P2E_SSB_BMC_RX_C_DN")
	)
	(segment
		(start 388.481824 -127.066548)
		(end 388.864602 -127.066548)
		(width 0.1143)
		(layer "B.Cu")
		(net "P2E_SSB_BMC_RX_C_DN")
	)
	(segment
		(start 387.721602 -129.300732)
		(end 388.2136 -128.808734)
		(width 0.1143)
		(layer "B.Cu")
		(net "P2E_SSB_BMC_RX_C_DN")
	)
	(segment
		(start 388.2136 -127.635)
		(end 388.2136 -127.334772)
		(width 0.1143)
		(layer "B.Cu")
		(net "P2E_SSB_BMC_RX_C_DN")
	)
	(segment
		(start 387.721602 -129.805938)
		(end 387.721602 -129.300732)
		(width 0.1143)
		(layer "B.Cu")
		(net "P2E_SSB_BMC_RX_C_DN")
	)
	(segment
		(start 387.5278 -129.99974)
		(end 387.721602 -129.805938)
		(width 0.1143)
		(layer "B.Cu")
		(net "P2E_SSB_BMC_RX_C_DN")
	)
	(segment
		(start 388.59841 -127.083312)
		(end 388.48411 -126.969012)
		(width 0.1143)
		(layer "In11.Cu")
		(net "P2E_SSB_BMC_RX_C_DN")
	)
	(segment
		(start 391.625836 -132.248402)
		(end 396.2908 -132.248402)
		(width 0.1143)
		(layer "In11.Cu")
		(net "P2E_SSB_BMC_RX_C_DN")
	)
	(segment
		(start 423.489374 -60.69076)
		(end 422.655492 -59.856878)
		(width 0.1143)
		(layer "In11.Cu")
		(net "P2E_SSB_BMC_RX_C_DN")
	)
	(segment
		(start 389.88873 -126.1491)
		(end 390.247632 -126.508002)
		(width 0.1143)
		(layer "In11.Cu")
		(net "P2E_SSB_BMC_RX_C_DN")
	)
	(segment
		(start 423.531284 -79.430118)
		(end 423.531284 -67.267328)
		(width 0.1143)
		(layer "In11.Cu")
		(net "P2E_SSB_BMC_RX_C_DN")
	)
	(segment
		(start 413.340042 -126.844806)
		(end 414.55594 -126.844806)
		(width 0.1143)
		(layer "In11.Cu")
		(net "P2E_SSB_BMC_RX_C_DN")
	)
	(segment
		(start 423.421556 -114.187732)
		(end 422.2242 -112.990376)
		(width 0.1143)
		(layer "In11.Cu")
		(net "P2E_SSB_BMC_RX_C_DN")
	)
	(segment
		(start 423.531284 -67.267328)
		(end 425.146216 -65.652396)
		(width 0.1143)
		(layer "In11.Cu")
		(net "P2E_SSB_BMC_RX_C_DN")
	)
	(segment
		(start 412.587948 -127.5969)
		(end 413.340042 -126.844806)
		(width 0.1143)
		(layer "In11.Cu")
		(net "P2E_SSB_BMC_RX_C_DN")
	)
	(segment
		(start 422.655492 -59.856878)
		(end 422.655492 -56.171846)
		(width 0.1143)
		(layer "In11.Cu")
		(net "P2E_SSB_BMC_RX_C_DN")
	)
	(segment
		(start 390.247632 -126.508002)
		(end 390.247632 -130.870198)
		(width 0.1143)
		(layer "In11.Cu")
		(net "P2E_SSB_BMC_RX_C_DN")
	)
	(segment
		(start 389.04799 -126.88316)
		(end 388.847838 -127.083312)
		(width 0.1143)
		(layer "In11.Cu")
		(net "P2E_SSB_BMC_RX_C_DN")
	)
	(segment
		(start 414.40862 -48.6791)
		(end 414.06953 -49.01819)
		(width 0.1143)
		(layer "In11.Cu")
		(net "P2E_SSB_BMC_RX_C_DN")
	)
	(segment
		(start 422.951148 -109.988604)
		(end 422.951148 -104.606598)
		(width 0.1143)
		(layer "In11.Cu")
		(net "P2E_SSB_BMC_RX_C_DN")
	)
	(segment
		(start 422.2242 -112.990376)
		(end 422.2242 -110.715552)
		(width 0.1143)
		(layer "In11.Cu")
		(net "P2E_SSB_BMC_RX_C_DN")
	)
	(segment
		(start 425.146216 -64.354202)
		(end 424.19905 -63.407036)
		(width 0.1143)
		(layer "In11.Cu")
		(net "P2E_SSB_BMC_RX_C_DN")
	)
	(segment
		(start 388.48411 -126.969012)
		(end 388.48411 -126.417832)
		(width 0.1143)
		(layer "In11.Cu")
		(net "P2E_SSB_BMC_RX_C_DN")
	)
	(segment
		(start 420.961312 -53.87848)
		(end 417.033202 -49.95037)
		(width 0.1143)
		(layer "In11.Cu")
		(net "P2E_SSB_BMC_RX_C_DN")
	)
	(segment
		(start 414.06953 -49.01819)
		(end 414.06953 -49.301146)
		(width 0.1143)
		(layer "In11.Cu")
		(net "P2E_SSB_BMC_RX_C_DN")
	)
	(segment
		(start 423.735246 -79.63408)
		(end 423.531284 -79.430118)
		(width 0.1143)
		(layer "In11.Cu")
		(net "P2E_SSB_BMC_RX_C_DN")
	)
	(segment
		(start 420.961312 -54.477666)
		(end 420.961312 -53.87848)
		(width 0.1143)
		(layer "In11.Cu")
		(net "P2E_SSB_BMC_RX_C_DN")
	)
	(segment
		(start 396.2908 -132.248402)
		(end 397.07693 -131.462272)
		(width 0.1143)
		(layer "In11.Cu")
		(net "P2E_SSB_BMC_RX_C_DN")
	)
	(segment
		(start 424.19905 -63.407036)
		(end 424.19905 -61.400436)
		(width 0.1143)
		(layer "In11.Cu")
		(net "P2E_SSB_BMC_RX_C_DN")
	)
	(segment
		(start 415.71799 -125.682756)
		(end 416.521138 -125.682756)
		(width 0.1143)
		(layer "In11.Cu")
		(net "P2E_SSB_BMC_RX_C_DN")
	)
	(segment
		(start 388.48411 -126.417832)
		(end 388.752842 -126.1491)
		(width 0.1143)
		(layer "In11.Cu")
		(net "P2E_SSB_BMC_RX_C_DN")
	)
	(segment
		(start 388.752842 -126.1491)
		(end 389.88873 -126.1491)
		(width 0.1143)
		(layer "In11.Cu")
		(net "P2E_SSB_BMC_RX_C_DN")
	)
	(segment
		(start 419.03142 -122.275092)
		(end 419.03142 -121.16689)
		(width 0.1143)
		(layer "In11.Cu")
		(net "P2E_SSB_BMC_RX_C_DN")
	)
	(segment
		(start 422.2242 -110.715552)
		(end 422.951148 -109.988604)
		(width 0.1143)
		(layer "In11.Cu")
		(net "P2E_SSB_BMC_RX_C_DN")
	)
	(segment
		(start 425.146216 -65.652396)
		(end 425.146216 -64.354202)
		(width 0.1143)
		(layer "In11.Cu")
		(net "P2E_SSB_BMC_RX_C_DN")
	)
	(segment
		(start 414.06953 -49.301146)
		(end 413.7533 -49.617376)
		(width 0.1143)
		(layer "In11.Cu")
		(net "P2E_SSB_BMC_RX_C_DN")
	)
	(segment
		(start 416.715702 -125.488192)
		(end 417.87572 -125.488192)
		(width 0.1143)
		(layer "In11.Cu")
		(net "P2E_SSB_BMC_RX_C_DN")
	)
	(segment
		(start 423.565066 -60.69076)
		(end 423.489374 -60.69076)
		(width 0.1143)
		(layer "In11.Cu")
		(net "P2E_SSB_BMC_RX_C_DN")
	)
	(segment
		(start 417.87572 -125.488192)
		(end 418.521896 -124.842016)
		(width 0.1143)
		(layer "In11.Cu")
		(net "P2E_SSB_BMC_RX_C_DN")
	)
	(segment
		(start 400.087846 -131.462272)
		(end 403.953218 -127.5969)
		(width 0.1143)
		(layer "In11.Cu")
		(net "P2E_SSB_BMC_RX_C_DN")
	)
	(segment
		(start 423.421556 -116.776754)
		(end 423.421556 -114.187732)
		(width 0.1143)
		(layer "In11.Cu")
		(net "P2E_SSB_BMC_RX_C_DN")
	)
	(segment
		(start 424.00728 -61.208666)
		(end 424.00728 -61.132974)
		(width 0.1143)
		(layer "In11.Cu")
		(net "P2E_SSB_BMC_RX_C_DN")
	)
	(segment
		(start 416.41522 -48.6791)
		(end 414.40862 -48.6791)
		(width 0.1143)
		(layer "In11.Cu")
		(net "P2E_SSB_BMC_RX_C_DN")
	)
	(segment
		(start 417.033202 -49.95037)
		(end 417.033202 -49.297082)
		(width 0.1143)
		(layer "In11.Cu")
		(net "P2E_SSB_BMC_RX_C_DN")
	)
	(segment
		(start 418.521896 -122.784616)
		(end 419.03142 -122.275092)
		(width 0.1143)
		(layer "In11.Cu")
		(net "P2E_SSB_BMC_RX_C_DN")
	)
	(segment
		(start 424.00728 -61.132974)
		(end 423.565066 -60.69076)
		(width 0.1143)
		(layer "In11.Cu")
		(net "P2E_SSB_BMC_RX_C_DN")
	)
	(segment
		(start 417.033202 -49.297082)
		(end 416.41522 -48.6791)
		(width 0.1143)
		(layer "In11.Cu")
		(net "P2E_SSB_BMC_RX_C_DN")
	)
	(segment
		(start 423.735246 -103.8225)
		(end 423.735246 -79.63408)
		(width 0.1143)
		(layer "In11.Cu")
		(net "P2E_SSB_BMC_RX_C_DN")
	)
	(segment
		(start 422.655492 -56.171846)
		(end 420.961312 -54.477666)
		(width 0.1143)
		(layer "In11.Cu")
		(net "P2E_SSB_BMC_RX_C_DN")
	)
	(segment
		(start 418.521896 -124.842016)
		(end 418.521896 -122.784616)
		(width 0.1143)
		(layer "In11.Cu")
		(net "P2E_SSB_BMC_RX_C_DN")
	)
	(segment
		(start 424.19905 -61.400436)
		(end 424.00728 -61.208666)
		(width 0.1143)
		(layer "In11.Cu")
		(net "P2E_SSB_BMC_RX_C_DN")
	)
	(segment
		(start 416.521138 -125.682756)
		(end 416.715702 -125.488192)
		(width 0.1143)
		(layer "In11.Cu")
		(net "P2E_SSB_BMC_RX_C_DN")
	)
	(segment
		(start 419.03142 -121.16689)
		(end 423.421556 -116.776754)
		(width 0.1143)
		(layer "In11.Cu")
		(net "P2E_SSB_BMC_RX_C_DN")
	)
	(segment
		(start 390.247632 -130.870198)
		(end 391.625836 -132.248402)
		(width 0.1143)
		(layer "In11.Cu")
		(net "P2E_SSB_BMC_RX_C_DN")
	)
	(segment
		(start 397.07693 -131.462272)
		(end 400.087846 -131.462272)
		(width 0.1143)
		(layer "In11.Cu")
		(net "P2E_SSB_BMC_RX_C_DN")
	)
	(segment
		(start 403.953218 -127.5969)
		(end 412.587948 -127.5969)
		(width 0.1143)
		(layer "In11.Cu")
		(net "P2E_SSB_BMC_RX_C_DN")
	)
	(segment
		(start 422.951148 -104.606598)
		(end 423.735246 -103.8225)
		(width 0.1143)
		(layer "In11.Cu")
		(net "P2E_SSB_BMC_RX_C_DN")
	)
	(segment
		(start 388.847838 -127.083312)
		(end 388.59841 -127.083312)
		(width 0.1143)
		(layer "In11.Cu")
		(net "P2E_SSB_BMC_RX_C_DN")
	)
	(segment
		(start 414.55594 -126.844806)
		(end 415.71799 -125.682756)
		(width 0.1143)
		(layer "In11.Cu")
		(net "P2E_SSB_BMC_RX_C_DN")
	)
	(segment
		(start 370.955824 -104.558846)
		(end 370.472208 -104.558846)
		(width 0.0889)
		(layer "F.Cu")
		(net "CLK_100M_BMC_PE_DP")
	)
	(segment
		(start 374.504458 -106.145076)
		(end 374.238266 -105.878884)
		(width 0.0889)
		(layer "F.Cu")
		(net "CLK_100M_BMC_PE_DP")
	)
	(segment
		(start 371.261386 -105.136696)
		(end 371.261386 -104.864408)
		(width 0.0889)
		(layer "F.Cu")
		(net "CLK_100M_BMC_PE_DP")
	)
	(segment
		(start 374.762268 -106.145076)
		(end 374.504458 -106.145076)
		(width 0.0889)
		(layer "F.Cu")
		(net "CLK_100M_BMC_PE_DP")
	)
	(segment
		(start 375.353326 -106.129836)
		(end 375.280936 -106.083862)
		(width 0.0889)
		(layer "F.Cu")
		(net "CLK_100M_BMC_PE_DP")
	)
	(segment
		(start 370.472208 -104.558846)
		(end 370.222526 -104.309164)
		(width 0.0889)
		(layer "F.Cu")
		(net "CLK_100M_BMC_PE_DP")
	)
	(segment
		(start 372.003574 -105.878884)
		(end 371.261386 -105.136696)
		(width 0.0889)
		(layer "F.Cu")
		(net "CLK_100M_BMC_PE_DP")
	)
	(segment
		(start 375.92 -106.35488)
		(end 375.353326 -106.129836)
		(width 0.0889)
		(layer "F.Cu")
		(net "CLK_100M_BMC_PE_DP")
	)
	(segment
		(start 374.238266 -105.878884)
		(end 372.003574 -105.878884)
		(width 0.0889)
		(layer "F.Cu")
		(net "CLK_100M_BMC_PE_DP")
	)
	(segment
		(start 375.280936 -106.083862)
		(end 375.119138 -106.03992)
		(width 0.0889)
		(layer "F.Cu")
		(net "CLK_100M_BMC_PE_DP")
	)
	(segment
		(start 371.261386 -104.864408)
		(end 370.955824 -104.558846)
		(width 0.0889)
		(layer "F.Cu")
		(net "CLK_100M_BMC_PE_DP")
	)
	(segment
		(start 375.119138 -106.03992)
		(end 375.016268 -106.03992)
		(width 0.0889)
		(layer "F.Cu")
		(net "CLK_100M_BMC_PE_DP")
	)
	(segment
		(start 375.016268 -106.03992)
		(end 374.762268 -106.145076)
		(width 0.0889)
		(layer "F.Cu")
		(net "CLK_100M_BMC_PE_DP")
	)
	(segment
		(start 371.66804 -105.956354)
		(end 371.55501 -105.84307)
		(width 0.0889)
		(layer "F.Cu")
		(net "CLK_100M_BMC_PE_DN")
	)
	(segment
		(start 371.92458 -106.069384)
		(end 371.81155 -105.956354)
		(width 0.0889)
		(layer "F.Cu")
		(net "CLK_100M_BMC_PE_DN")
	)
	(segment
		(start 371.070886 -105.21569)
		(end 371.070886 -104.943402)
		(width 0.0889)
		(layer "F.Cu")
		(net "CLK_100M_BMC_PE_DN")
	)
	(segment
		(start 373.796814 -106.17073)
		(end 373.695468 -106.069384)
		(width 0.0889)
		(layer "F.Cu")
		(net "CLK_100M_BMC_PE_DN")
	)
	(segment
		(start 375.089928 -106.35488)
		(end 375.030238 -106.29519)
		(width 0.0889)
		(layer "F.Cu")
		(net "CLK_100M_BMC_PE_DN")
	)
	(segment
		(start 373.434102 -106.17073)
		(end 373.274082 -106.17073)
		(width 0.0889)
		(layer "F.Cu")
		(net "CLK_100M_BMC_PE_DN")
	)
	(segment
		(start 373.695468 -106.069384)
		(end 373.535448 -106.069384)
		(width 0.0889)
		(layer "F.Cu")
		(net "CLK_100M_BMC_PE_DN")
	)
	(segment
		(start 375.030238 -106.29519)
		(end 374.899174 -106.29519)
		(width 0.0889)
		(layer "F.Cu")
		(net "CLK_100M_BMC_PE_DN")
	)
	(segment
		(start 374.425464 -106.335576)
		(end 374.159272 -106.069384)
		(width 0.0889)
		(layer "F.Cu")
		(net "CLK_100M_BMC_PE_DN")
	)
	(segment
		(start 374.858788 -106.335576)
		(end 374.425464 -106.335576)
		(width 0.0889)
		(layer "F.Cu")
		(net "CLK_100M_BMC_PE_DN")
	)
	(segment
		(start 373.274082 -106.17073)
		(end 373.172736 -106.069384)
		(width 0.0889)
		(layer "F.Cu")
		(net "CLK_100M_BMC_PE_DN")
	)
	(segment
		(start 372.388638 -106.17073)
		(end 372.228618 -106.17073)
		(width 0.0889)
		(layer "F.Cu")
		(net "CLK_100M_BMC_PE_DN")
	)
	(segment
		(start 372.650004 -106.069384)
		(end 372.489984 -106.069384)
		(width 0.0889)
		(layer "F.Cu")
		(net "CLK_100M_BMC_PE_DN")
	)
	(segment
		(start 370.222526 -104.857296)
		(end 370.222526 -105.198164)
		(width 0.0889)
		(layer "F.Cu")
		(net "CLK_100M_BMC_PE_DN")
	)
	(segment
		(start 370.87683 -104.749346)
		(end 370.330476 -104.749346)
		(width 0.0889)
		(layer "F.Cu")
		(net "CLK_100M_BMC_PE_DN")
	)
	(segment
		(start 371.55501 -105.699814)
		(end 371.441726 -105.58653)
		(width 0.0889)
		(layer "F.Cu")
		(net "CLK_100M_BMC_PE_DN")
	)
	(segment
		(start 373.012716 -106.069384)
		(end 372.91137 -106.17073)
		(width 0.0889)
		(layer "F.Cu")
		(net "CLK_100M_BMC_PE_DN")
	)
	(segment
		(start 373.956834 -106.17073)
		(end 373.796814 -106.17073)
		(width 0.0889)
		(layer "F.Cu")
		(net "CLK_100M_BMC_PE_DN")
	)
	(segment
		(start 372.228618 -106.17073)
		(end 372.127272 -106.069384)
		(width 0.0889)
		(layer "F.Cu")
		(net "CLK_100M_BMC_PE_DN")
	)
	(segment
		(start 371.55501 -105.84307)
		(end 371.55501 -105.699814)
		(width 0.0889)
		(layer "F.Cu")
		(net "CLK_100M_BMC_PE_DN")
	)
	(segment
		(start 372.75135 -106.17073)
		(end 372.650004 -106.069384)
		(width 0.0889)
		(layer "F.Cu")
		(net "CLK_100M_BMC_PE_DN")
	)
	(segment
		(start 372.127272 -106.069384)
		(end 371.92458 -106.069384)
		(width 0.0889)
		(layer "F.Cu")
		(net "CLK_100M_BMC_PE_DN")
	)
	(segment
		(start 372.489984 -106.069384)
		(end 372.388638 -106.17073)
		(width 0.0889)
		(layer "F.Cu")
		(net "CLK_100M_BMC_PE_DN")
	)
	(segment
		(start 374.05818 -106.069384)
		(end 373.956834 -106.17073)
		(width 0.0889)
		(layer "F.Cu")
		(net "CLK_100M_BMC_PE_DN")
	)
	(segment
		(start 371.18544 -105.330244)
		(end 371.070886 -105.21569)
		(width 0.0889)
		(layer "F.Cu")
		(net "CLK_100M_BMC_PE_DN")
	)
	(segment
		(start 371.070886 -104.943402)
		(end 370.87683 -104.749346)
		(width 0.0889)
		(layer "F.Cu")
		(net "CLK_100M_BMC_PE_DN")
	)
	(segment
		(start 372.91137 -106.17073)
		(end 372.75135 -106.17073)
		(width 0.0889)
		(layer "F.Cu")
		(net "CLK_100M_BMC_PE_DN")
	)
	(segment
		(start 374.159272 -106.069384)
		(end 374.05818 -106.069384)
		(width 0.0889)
		(layer "F.Cu")
		(net "CLK_100M_BMC_PE_DN")
	)
	(segment
		(start 371.18544 -105.4735)
		(end 371.18544 -105.330244)
		(width 0.0889)
		(layer "F.Cu")
		(net "CLK_100M_BMC_PE_DN")
	)
	(segment
		(start 373.172736 -106.069384)
		(end 373.012716 -106.069384)
		(width 0.0889)
		(layer "F.Cu")
		(net "CLK_100M_BMC_PE_DN")
	)
	(segment
		(start 370.330476 -104.749346)
		(end 370.222526 -104.857296)
		(width 0.0889)
		(layer "F.Cu")
		(net "CLK_100M_BMC_PE_DN")
	)
	(segment
		(start 373.535448 -106.069384)
		(end 373.434102 -106.17073)
		(width 0.0889)
		(layer "F.Cu")
		(net "CLK_100M_BMC_PE_DN")
	)
	(segment
		(start 371.81155 -105.956354)
		(end 371.66804 -105.956354)
		(width 0.0889)
		(layer "F.Cu")
		(net "CLK_100M_BMC_PE_DN")
	)
	(segment
		(start 371.441726 -105.58653)
		(end 371.29847 -105.58653)
		(width 0.0889)
		(layer "F.Cu")
		(net "CLK_100M_BMC_PE_DN")
	)
	(segment
		(start 371.29847 -105.58653)
		(end 371.18544 -105.4735)
		(width 0.0889)
		(layer "F.Cu")
		(net "CLK_100M_BMC_PE_DN")
	)
	(segment
		(start 374.899174 -106.29519)
		(end 374.858788 -106.335576)
		(width 0.0889)
		(layer "F.Cu")
		(net "CLK_100M_BMC_PE_DN")
	)
	(segment
		(start 376.162824 -3.051556)
		(end 376.04827 -2.937002)
		(width 0.1143)
		(layer "F.Cu")
		(net "P3E_CPU0_PE2_SS_RXP<9>")
	)
	(segment
		(start 376.036586 -3.557016)
		(end 376.162824 -3.430524)
		(width 0.1143)
		(layer "F.Cu")
		(net "P3E_CPU0_PE2_SS_RXP<9>")
	)
	(segment
		(start 301.241206 -80.174338)
		(end 301.812706 -80.174338)
		(width 0.1143)
		(layer "F.Cu")
		(net "P3E_CPU0_PE2_SS_RXP<9>")
	)
	(segment
		(start 376.04827 -2.937002)
		(end 375.70029 -2.937002)
		(width 0.1143)
		(layer "F.Cu")
		(net "P3E_CPU0_PE2_SS_RXP<9>")
	)
	(segment
		(start 375.885202 -3.708146)
		(end 376.036586 -3.557016)
		(width 0.1143)
		(layer "F.Cu")
		(net "P3E_CPU0_PE2_SS_RXP<9>")
	)
	(segment
		(start 375.885202 -4.389882)
		(end 375.885202 -3.708146)
		(width 0.1143)
		(layer "F.Cu")
		(net "P3E_CPU0_PE2_SS_RXP<9>")
	)
	(segment
		(start 376.162824 -3.430524)
		(end 376.162824 -3.051556)
		(width 0.1143)
		(layer "F.Cu")
		(net "P3E_CPU0_PE2_SS_RXP<9>")
	)
	(via
		(at 301.812706 -80.174338)
		(size 0.508)
		(drill 0.254)
		(layers "F.Cu" "B.Cu")
		(net "P3E_CPU0_PE2_SS_RXP<9>")
	)
	(via
		(at 375.70029 -2.937002)
		(size 0.508)
		(drill 0.254)
		(layers "F.Cu" "B.Cu")
		(net "P3E_CPU0_PE2_SS_RXP<9>")
	)
	(segment
		(start 358.950006 -35.33521)
		(end 364.522258 -26.97734)
		(width 0.1143)
		(layer "In4.Cu")
		(net "P3E_CPU0_PE2_SS_RXP<9>")
	)
	(segment
		(start 307.02631 -79.680308)
		(end 307.048408 -79.680308)
		(width 0.0889)
		(layer "In4.Cu")
		(net "P3E_CPU0_PE2_SS_RXP<9>")
	)
	(segment
		(start 316.545468 -62.60719)
		(end 316.54623 -62.605666)
		(width 0.1143)
		(layer "In4.Cu")
		(net "P3E_CPU0_PE2_SS_RXP<9>")
	)
	(segment
		(start 339.289898 -46.162214)
		(end 341.492586 -45.713904)
		(width 0.1143)
		(layer "In4.Cu")
		(net "P3E_CPU0_PE2_SS_RXP<9>")
	)
	(segment
		(start 356.444296 -42.769536)
		(end 357.31704 -42.191686)
		(width 0.1143)
		(layer "In4.Cu")
		(net "P3E_CPU0_PE2_SS_RXP<9>")
	)
	(segment
		(start 306.97551 -79.731108)
		(end 307.02631 -79.680308)
		(width 0.0889)
		(layer "In4.Cu")
		(net "P3E_CPU0_PE2_SS_RXP<9>")
	)
	(segment
		(start 374.276366 -5.350256)
		(end 374.510046 -5.350256)
		(width 0.1143)
		(layer "In4.Cu")
		(net "P3E_CPU0_PE2_SS_RXP<9>")
	)
	(segment
		(start 301.812706 -80.174338)
		(end 302.105822 -80.343248)
		(width 0.0889)
		(layer "In4.Cu")
		(net "P3E_CPU0_PE2_SS_RXP<9>")
	)
	(segment
		(start 323.042534 -53.161184)
		(end 323.043296 -53.160676)
		(width 0.1143)
		(layer "In4.Cu")
		(net "P3E_CPU0_PE2_SS_RXP<9>")
	)
	(segment
		(start 304.51806 -80.1751)
		(end 304.962052 -79.731108)
		(width 0.0889)
		(layer "In4.Cu")
		(net "P3E_CPU0_PE2_SS_RXP<9>")
	)
	(segment
		(start 375.713244 -3.913632)
		(end 375.94667 -3.913632)
		(width 0.1143)
		(layer "In4.Cu")
		(net "P3E_CPU0_PE2_SS_RXP<9>")
	)
	(segment
		(start 376.18924 -3.671062)
		(end 376.18924 -3.051302)
		(width 0.1143)
		(layer "In4.Cu")
		(net "P3E_CPU0_PE2_SS_RXP<9>")
	)
	(segment
		(start 304.962052 -79.731108)
		(end 306.97551 -79.731108)
		(width 0.0889)
		(layer "In4.Cu")
		(net "P3E_CPU0_PE2_SS_RXP<9>")
	)
	(segment
		(start 337.201256 -45.736002)
		(end 339.289898 -46.162214)
		(width 0.1143)
		(layer "In4.Cu")
		(net "P3E_CPU0_PE2_SS_RXP<9>")
	)
	(segment
		(start 303.515268 -80.574388)
		(end 303.788318 -80.574388)
		(width 0.0889)
		(layer "In4.Cu")
		(net "P3E_CPU0_PE2_SS_RXP<9>")
	)
	(segment
		(start 374.03405 -5.826252)
		(end 374.03405 -5.592826)
		(width 0.1143)
		(layer "In4.Cu")
		(net "P3E_CPU0_PE2_SS_RXP<9>")
	)
	(segment
		(start 364.522258 -26.97734)
		(end 367.543334 -12.85494)
		(width 0.1143)
		(layer "In4.Cu")
		(net "P3E_CPU0_PE2_SS_RXP<9>")
	)
	(segment
		(start 374.03405 -5.592826)
		(end 374.276366 -5.350256)
		(width 0.1143)
		(layer "In4.Cu")
		(net "P3E_CPU0_PE2_SS_RXP<9>")
	)
	(segment
		(start 302.653446 -80.078834)
		(end 302.66132 -80.078834)
		(width 0.0889)
		(layer "In4.Cu")
		(net "P3E_CPU0_PE2_SS_RXP<9>")
	)
	(segment
		(start 374.994932 -4.631944)
		(end 375.228358 -4.631944)
		(width 0.1143)
		(layer "In4.Cu")
		(net "P3E_CPU0_PE2_SS_RXP<9>")
	)
	(segment
		(start 325.276464 -50.86731)
		(end 329.376278 -48.211486)
		(width 0.1143)
		(layer "In4.Cu")
		(net "P3E_CPU0_PE2_SS_RXP<9>")
	)
	(segment
		(start 370.9162 -10.338054)
		(end 371.216936 -10.113772)
		(width 0.1143)
		(layer "In4.Cu")
		(net "P3E_CPU0_PE2_SS_RXP<9>")
	)
	(segment
		(start 304.187606 -80.1751)
		(end 304.51806 -80.1751)
		(width 0.0889)
		(layer "In4.Cu")
		(net "P3E_CPU0_PE2_SS_RXP<9>")
	)
	(segment
		(start 373.558054 -6.068822)
		(end 373.79148 -6.068822)
		(width 0.1143)
		(layer "In4.Cu")
		(net "P3E_CPU0_PE2_SS_RXP<9>")
	)
	(segment
		(start 372.147338 -7.712964)
		(end 373.315484 -6.544818)
		(width 0.1143)
		(layer "In4.Cu")
		(net "P3E_CPU0_PE2_SS_RXP<9>")
	)
	(segment
		(start 323.043296 -53.160676)
		(end 323.954902 -52.789582)
		(width 0.1143)
		(layer "In4.Cu")
		(net "P3E_CPU0_PE2_SS_RXP<9>")
	)
	(segment
		(start 374.752362 -4.874514)
		(end 374.994932 -4.631944)
		(width 0.1143)
		(layer "In4.Cu")
		(net "P3E_CPU0_PE2_SS_RXP<9>")
	)
	(segment
		(start 316.54623 -62.605666)
		(end 323.042534 -53.161184)
		(width 0.1143)
		(layer "In4.Cu")
		(net "P3E_CPU0_PE2_SS_RXP<9>")
	)
	(segment
		(start 373.315484 -6.311138)
		(end 373.558054 -6.068822)
		(width 0.1143)
		(layer "In4.Cu")
		(net "P3E_CPU0_PE2_SS_RXP<9>")
	)
	(segment
		(start 371.216936 -10.113772)
		(end 372.147338 -7.712964)
		(width 0.1143)
		(layer "In4.Cu")
		(net "P3E_CPU0_PE2_SS_RXP<9>")
	)
	(segment
		(start 370.84 -10.39495)
		(end 370.9162 -10.338054)
		(width 0.1143)
		(layer "In4.Cu")
		(net "P3E_CPU0_PE2_SS_RXP<9>")
	)
	(segment
		(start 341.492586 -45.713904)
		(end 343.748614 -46.172628)
		(width 0.1143)
		(layer "In4.Cu")
		(net "P3E_CPU0_PE2_SS_RXP<9>")
	)
	(segment
		(start 310.980328 -76.044298)
		(end 316.545722 -62.60719)
		(width 0.1143)
		(layer "In4.Cu")
		(net "P3E_CPU0_PE2_SS_RXP<9>")
	)
	(segment
		(start 375.470928 -4.389374)
		(end 375.470928 -4.155948)
		(width 0.1143)
		(layer "In4.Cu")
		(net "P3E_CPU0_PE2_SS_RXP<9>")
	)
	(segment
		(start 376.18924 -3.051302)
		(end 376.07494 -2.937002)
		(width 0.1143)
		(layer "In4.Cu")
		(net "P3E_CPU0_PE2_SS_RXP<9>")
	)
	(segment
		(start 307.796184 -79.50454)
		(end 309.142892 -78.283816)
		(width 0.1143)
		(layer "In4.Cu")
		(net "P3E_CPU0_PE2_SS_RXP<9>")
	)
	(segment
		(start 309.142892 -78.283816)
		(end 310.980328 -76.044298)
		(width 0.1143)
		(layer "In4.Cu")
		(net "P3E_CPU0_PE2_SS_RXP<9>")
	)
	(segment
		(start 303.788318 -80.574388)
		(end 304.187606 -80.1751)
		(width 0.0889)
		(layer "In4.Cu")
		(net "P3E_CPU0_PE2_SS_RXP<9>")
	)
	(segment
		(start 302.105822 -80.343248)
		(end 302.19523 -80.319118)
		(width 0.0889)
		(layer "In4.Cu")
		(net "P3E_CPU0_PE2_SS_RXP<9>")
	)
	(segment
		(start 307.048408 -79.680308)
		(end 307.533294 -79.680308)
		(width 0.1143)
		(layer "In4.Cu")
		(net "P3E_CPU0_PE2_SS_RXP<9>")
	)
	(segment
		(start 373.315484 -6.544818)
		(end 373.315484 -6.311138)
		(width 0.1143)
		(layer "In4.Cu")
		(net "P3E_CPU0_PE2_SS_RXP<9>")
	)
	(segment
		(start 374.752362 -5.10794)
		(end 374.752362 -4.874514)
		(width 0.1143)
		(layer "In4.Cu")
		(net "P3E_CPU0_PE2_SS_RXP<9>")
	)
	(segment
		(start 367.543334 -12.85494)
		(end 370.84 -10.39495)
		(width 0.1143)
		(layer "In4.Cu")
		(net "P3E_CPU0_PE2_SS_RXP<9>")
	)
	(segment
		(start 302.681386 -80.078834)
		(end 302.686212 -80.078834)
		(width 0.0889)
		(layer "In4.Cu")
		(net "P3E_CPU0_PE2_SS_RXP<9>")
	)
	(segment
		(start 316.545722 -62.60719)
		(end 316.545468 -62.60719)
		(width 0.1143)
		(layer "In4.Cu")
		(net "P3E_CPU0_PE2_SS_RXP<9>")
	)
	(segment
		(start 376.07494 -2.937002)
		(end 375.70029 -2.937002)
		(width 0.1143)
		(layer "In4.Cu")
		(net "P3E_CPU0_PE2_SS_RXP<9>")
	)
	(segment
		(start 329.376278 -48.211486)
		(end 337.201256 -45.736002)
		(width 0.1143)
		(layer "In4.Cu")
		(net "P3E_CPU0_PE2_SS_RXP<9>")
	)
	(segment
		(start 323.954902 -52.789582)
		(end 325.276464 -50.86731)
		(width 0.1143)
		(layer "In4.Cu")
		(net "P3E_CPU0_PE2_SS_RXP<9>")
	)
	(segment
		(start 357.680514 -41.6433)
		(end 358.950006 -35.33521)
		(width 0.1143)
		(layer "In4.Cu")
		(net "P3E_CPU0_PE2_SS_RXP<9>")
	)
	(segment
		(start 357.31704 -42.191686)
		(end 357.680514 -41.6433)
		(width 0.1143)
		(layer "In4.Cu")
		(net "P3E_CPU0_PE2_SS_RXP<9>")
	)
	(segment
		(start 343.748614 -46.172628)
		(end 356.444296 -42.769536)
		(width 0.1143)
		(layer "In4.Cu")
		(net "P3E_CPU0_PE2_SS_RXP<9>")
	)
	(segment
		(start 373.79148 -6.068822)
		(end 374.03405 -5.826252)
		(width 0.1143)
		(layer "In4.Cu")
		(net "P3E_CPU0_PE2_SS_RXP<9>")
	)
	(segment
		(start 307.533294 -79.680308)
		(end 307.796184 -79.50454)
		(width 0.1143)
		(layer "In4.Cu")
		(net "P3E_CPU0_PE2_SS_RXP<9>")
	)
	(segment
		(start 375.228358 -4.631944)
		(end 375.470928 -4.389374)
		(width 0.1143)
		(layer "In4.Cu")
		(net "P3E_CPU0_PE2_SS_RXP<9>")
	)
	(segment
		(start 374.510046 -5.350256)
		(end 374.752362 -5.10794)
		(width 0.1143)
		(layer "In4.Cu")
		(net "P3E_CPU0_PE2_SS_RXP<9>")
	)
	(segment
		(start 375.94667 -3.913632)
		(end 376.18924 -3.671062)
		(width 0.1143)
		(layer "In4.Cu")
		(net "P3E_CPU0_PE2_SS_RXP<9>")
	)
	(segment
		(start 375.470928 -4.155948)
		(end 375.713244 -3.913632)
		(width 0.1143)
		(layer "In4.Cu")
		(net "P3E_CPU0_PE2_SS_RXP<9>")
	)
	(arc
		(start 303.183036 -80.374236)
		(mid 303.323304 -80.517192)
		(end 303.515268 -80.574388)
		(width 0.0889)
		(layer "In4.Cu")
		(net "P3E_CPU0_PE2_SS_RXP<9>")
	)
	(arc
		(start 302.19523 -80.319118)
		(mid 302.39664 -80.146165)
		(end 302.653446 -80.078834)
		(width 0.0889)
		(layer "In4.Cu")
		(net "P3E_CPU0_PE2_SS_RXP<9>")
	)
	(arc
		(start 302.66132 -80.078834)
		(mid 302.671353 -80.078716)
		(end 302.681386 -80.078834)
		(width 0.0889)
		(layer "In4.Cu")
		(net "P3E_CPU0_PE2_SS_RXP<9>")
	)
	(arc
		(start 302.686212 -80.078834)
		(mid 302.973245 -80.161583)
		(end 303.183036 -80.374236)
		(width 0.0889)
		(layer "In4.Cu")
		(net "P3E_CPU0_PE2_SS_RXP<9>")
	)
	(segment
		(start 378.14758 -1.754886)
		(end 378.564902 -1.754886)
		(width 0.1143)
		(layer "F.Cu")
		(net "P3E_CPU0_PE2_SS_RXP<8>")
	)
	(segment
		(start 378.679202 -1.869186)
		(end 378.679202 -2.589022)
		(width 0.1143)
		(layer "F.Cu")
		(net "P3E_CPU0_PE2_SS_RXP<8>")
	)
	(segment
		(start 378.589794 -3.337306)
		(end 378.284994 -3.642106)
		(width 0.1143)
		(layer "F.Cu")
		(net "P3E_CPU0_PE2_SS_RXP<8>")
	)
	(segment
		(start 378.679202 -2.589022)
		(end 378.589794 -2.67843)
		(width 0.1143)
		(layer "F.Cu")
		(net "P3E_CPU0_PE2_SS_RXP<8>")
	)
	(segment
		(start 378.284994 -3.642106)
		(end 378.284994 -4.389882)
		(width 0.1143)
		(layer "F.Cu")
		(net "P3E_CPU0_PE2_SS_RXP<8>")
	)
	(segment
		(start 378.564902 -1.754886)
		(end 378.679202 -1.869186)
		(width 0.1143)
		(layer "F.Cu")
		(net "P3E_CPU0_PE2_SS_RXP<8>")
	)
	(segment
		(start 378.589794 -2.67843)
		(end 378.589794 -3.337306)
		(width 0.1143)
		(layer "F.Cu")
		(net "P3E_CPU0_PE2_SS_RXP<8>")
	)
	(segment
		(start 300.382686 -79.678784)
		(end 300.954186 -79.678784)
		(width 0.1143)
		(layer "F.Cu")
		(net "P3E_CPU0_PE2_SS_RXP<8>")
	)
	(via
		(at 300.954186 -79.678784)
		(size 0.508)
		(drill 0.254)
		(layers "F.Cu" "B.Cu")
		(net "P3E_CPU0_PE2_SS_RXP<8>")
	)
	(via
		(at 378.14758 -1.754886)
		(size 0.508)
		(drill 0.254)
		(layers "F.Cu" "B.Cu")
		(net "P3E_CPU0_PE2_SS_RXP<8>")
	)
	(segment
		(start 311.413398 -76.69911)
		(end 317.1444 -62.861444)
		(width 0.1143)
		(layer "In4.Cu")
		(net "P3E_CPU0_PE2_SS_RXP<8>")
	)
	(segment
		(start 304.37074 -81.069688)
		(end 304.715672 -81.069688)
		(width 0.0889)
		(layer "In4.Cu")
		(net "P3E_CPU0_PE2_SS_RXP<8>")
	)
	(segment
		(start 323.462142 -53.676296)
		(end 324.391528 -53.297836)
		(width 0.1143)
		(layer "In4.Cu")
		(net "P3E_CPU0_PE2_SS_RXP<8>")
	)
	(segment
		(start 305.353212 -80.432148)
		(end 307.094636 -80.432148)
		(width 0.0889)
		(layer "In4.Cu")
		(net "P3E_CPU0_PE2_SS_RXP<8>")
	)
	(segment
		(start 378.52223 -1.754886)
		(end 378.14758 -1.754886)
		(width 0.1143)
		(layer "In4.Cu")
		(net "P3E_CPU0_PE2_SS_RXP<8>")
	)
	(segment
		(start 300.954186 -80.016858)
		(end 301.019464 -80.082136)
		(width 0.0889)
		(layer "In4.Cu")
		(net "P3E_CPU0_PE2_SS_RXP<8>")
	)
	(segment
		(start 375.64949 -6.07568)
		(end 375.64949 -5.842)
		(width 0.1143)
		(layer "In4.Cu")
		(net "P3E_CPU0_PE2_SS_RXP<8>")
	)
	(segment
		(start 374.688608 -7.036562)
		(end 374.931178 -6.793992)
		(width 0.1143)
		(layer "In4.Cu")
		(net "P3E_CPU0_PE2_SS_RXP<8>")
	)
	(segment
		(start 376.125486 -5.599684)
		(end 378.63653 -3.08864)
		(width 0.1143)
		(layer "In4.Cu")
		(net "P3E_CPU0_PE2_SS_RXP<8>")
	)
	(segment
		(start 304.370486 -81.069434)
		(end 304.37074 -81.069688)
		(width 0.0889)
		(layer "In4.Cu")
		(net "P3E_CPU0_PE2_SS_RXP<8>")
	)
	(segment
		(start 307.167534 -80.381348)
		(end 307.819552 -80.381348)
		(width 0.1143)
		(layer "In4.Cu")
		(net "P3E_CPU0_PE2_SS_RXP<8>")
	)
	(segment
		(start 329.659234 -48.791114)
		(end 337.238594 -46.393862)
		(width 0.1143)
		(layer "In4.Cu")
		(net "P3E_CPU0_PE2_SS_RXP<8>")
	)
	(segment
		(start 365.236252 -27.074622)
		(end 368.208052 -13.18387)
		(width 0.1143)
		(layer "In4.Cu")
		(net "P3E_CPU0_PE2_SS_RXP<8>")
	)
	(segment
		(start 356.638352 -43.414442)
		(end 357.806752 -42.641266)
		(width 0.1143)
		(layer "In4.Cu")
		(net "P3E_CPU0_PE2_SS_RXP<8>")
	)
	(segment
		(start 339.3821 -46.830234)
		(end 341.551006 -46.388782)
		(width 0.1143)
		(layer "In4.Cu")
		(net "P3E_CPU0_PE2_SS_RXP<8>")
	)
	(segment
		(start 378.63653 -1.869186)
		(end 378.52223 -1.754886)
		(width 0.1143)
		(layer "In4.Cu")
		(net "P3E_CPU0_PE2_SS_RXP<8>")
	)
	(segment
		(start 368.296444 -13.118338)
		(end 372.036594 -10.34034)
		(width 0.1143)
		(layer "In4.Cu")
		(net "P3E_CPU0_PE2_SS_RXP<8>")
	)
	(segment
		(start 307.094636 -80.432148)
		(end 307.145436 -80.381348)
		(width 0.0889)
		(layer "In4.Cu")
		(net "P3E_CPU0_PE2_SS_RXP<8>")
	)
	(segment
		(start 375.173748 -6.317996)
		(end 375.407174 -6.317996)
		(width 0.1143)
		(layer "In4.Cu")
		(net "P3E_CPU0_PE2_SS_RXP<8>")
	)
	(segment
		(start 374.212866 -7.512304)
		(end 374.212866 -7.278878)
		(width 0.1143)
		(layer "In4.Cu")
		(net "P3E_CPU0_PE2_SS_RXP<8>")
	)
	(segment
		(start 300.954186 -79.678784)
		(end 300.954186 -80.016858)
		(width 0.0889)
		(layer "In4.Cu")
		(net "P3E_CPU0_PE2_SS_RXP<8>")
	)
	(segment
		(start 374.931178 -6.793992)
		(end 374.931178 -6.560566)
		(width 0.1143)
		(layer "In4.Cu")
		(net "P3E_CPU0_PE2_SS_RXP<8>")
	)
	(segment
		(start 317.1444 -62.861444)
		(end 323.462142 -53.676296)
		(width 0.1143)
		(layer "In4.Cu")
		(net "P3E_CPU0_PE2_SS_RXP<8>")
	)
	(segment
		(start 324.391528 -53.297836)
		(end 325.747126 -51.32578)
		(width 0.1143)
		(layer "In4.Cu")
		(net "P3E_CPU0_PE2_SS_RXP<8>")
	)
	(segment
		(start 337.238594 -46.393862)
		(end 339.3821 -46.830234)
		(width 0.1143)
		(layer "In4.Cu")
		(net "P3E_CPU0_PE2_SS_RXP<8>")
	)
	(segment
		(start 302.65624 -81.069434)
		(end 302.689006 -81.069434)
		(width 0.0889)
		(layer "In4.Cu")
		(net "P3E_CPU0_PE2_SS_RXP<8>")
	)
	(segment
		(start 372.779544 -8.47979)
		(end 373.504714 -7.754874)
		(width 0.1143)
		(layer "In4.Cu")
		(net "P3E_CPU0_PE2_SS_RXP<8>")
	)
	(segment
		(start 307.145436 -80.381348)
		(end 307.167534 -80.381348)
		(width 0.0889)
		(layer "In4.Cu")
		(net "P3E_CPU0_PE2_SS_RXP<8>")
	)
	(segment
		(start 374.931178 -6.560566)
		(end 375.173748 -6.317996)
		(width 0.1143)
		(layer "In4.Cu")
		(net "P3E_CPU0_PE2_SS_RXP<8>")
	)
	(segment
		(start 358.28986 -41.911524)
		(end 359.572306 -35.570922)
		(width 0.1143)
		(layer "In4.Cu")
		(net "P3E_CPU0_PE2_SS_RXP<8>")
	)
	(segment
		(start 375.89206 -5.599684)
		(end 376.125486 -5.599684)
		(width 0.1143)
		(layer "In4.Cu")
		(net "P3E_CPU0_PE2_SS_RXP<8>")
	)
	(segment
		(start 375.64949 -5.842)
		(end 375.89206 -5.599684)
		(width 0.1143)
		(layer "In4.Cu")
		(net "P3E_CPU0_PE2_SS_RXP<8>")
	)
	(segment
		(start 368.29619 -13.118338)
		(end 368.296444 -13.118338)
		(width 0.1143)
		(layer "In4.Cu")
		(net "P3E_CPU0_PE2_SS_RXP<8>")
	)
	(segment
		(start 375.407174 -6.317996)
		(end 375.64949 -6.07568)
		(width 0.1143)
		(layer "In4.Cu")
		(net "P3E_CPU0_PE2_SS_RXP<8>")
	)
	(segment
		(start 373.504714 -7.754874)
		(end 373.970296 -7.754874)
		(width 0.1143)
		(layer "In4.Cu")
		(net "P3E_CPU0_PE2_SS_RXP<8>")
	)
	(segment
		(start 303.511712 -81.564734)
		(end 303.54778 -81.564734)
		(width 0.0889)
		(layer "In4.Cu")
		(net "P3E_CPU0_PE2_SS_RXP<8>")
	)
	(segment
		(start 357.806752 -42.641266)
		(end 358.28986 -41.911524)
		(width 0.1143)
		(layer "In4.Cu")
		(net "P3E_CPU0_PE2_SS_RXP<8>")
	)
	(segment
		(start 372.036594 -10.34034)
		(end 372.779544 -8.47979)
		(width 0.1143)
		(layer "In4.Cu")
		(net "P3E_CPU0_PE2_SS_RXP<8>")
	)
	(segment
		(start 378.63653 -3.08864)
		(end 378.63653 -1.869186)
		(width 0.1143)
		(layer "In4.Cu")
		(net "P3E_CPU0_PE2_SS_RXP<8>")
	)
	(segment
		(start 310.050688 -78.359762)
		(end 311.413398 -76.69911)
		(width 0.1143)
		(layer "In4.Cu")
		(net "P3E_CPU0_PE2_SS_RXP<8>")
	)
	(segment
		(start 374.212866 -7.278878)
		(end 374.455182 -7.036562)
		(width 0.1143)
		(layer "In4.Cu")
		(net "P3E_CPU0_PE2_SS_RXP<8>")
	)
	(segment
		(start 325.747126 -51.32578)
		(end 329.659234 -48.791114)
		(width 0.1143)
		(layer "In4.Cu")
		(net "P3E_CPU0_PE2_SS_RXP<8>")
	)
	(segment
		(start 301.80153 -80.574388)
		(end 301.834296 -80.574388)
		(width 0.0889)
		(layer "In4.Cu")
		(net "P3E_CPU0_PE2_SS_RXP<8>")
	)
	(segment
		(start 373.970296 -7.754874)
		(end 374.212866 -7.512304)
		(width 0.1143)
		(layer "In4.Cu")
		(net "P3E_CPU0_PE2_SS_RXP<8>")
	)
	(segment
		(start 307.819552 -80.381348)
		(end 310.050688 -78.359762)
		(width 0.1143)
		(layer "In4.Cu")
		(net "P3E_CPU0_PE2_SS_RXP<8>")
	)
	(segment
		(start 374.455182 -7.036562)
		(end 374.688608 -7.036562)
		(width 0.1143)
		(layer "In4.Cu")
		(net "P3E_CPU0_PE2_SS_RXP<8>")
	)
	(segment
		(start 304.715672 -81.069688)
		(end 305.353212 -80.432148)
		(width 0.0889)
		(layer "In4.Cu")
		(net "P3E_CPU0_PE2_SS_RXP<8>")
	)
	(segment
		(start 368.208052 -13.18387)
		(end 368.29619 -13.118338)
		(width 0.1143)
		(layer "In4.Cu")
		(net "P3E_CPU0_PE2_SS_RXP<8>")
	)
	(segment
		(start 341.551006 -46.388782)
		(end 343.819988 -46.8503)
		(width 0.1143)
		(layer "In4.Cu")
		(net "P3E_CPU0_PE2_SS_RXP<8>")
	)
	(segment
		(start 343.819988 -46.8503)
		(end 356.638352 -43.414442)
		(width 0.1143)
		(layer "In4.Cu")
		(net "P3E_CPU0_PE2_SS_RXP<8>")
	)
	(segment
		(start 359.572306 -35.570922)
		(end 365.236252 -27.074622)
		(width 0.1143)
		(layer "In4.Cu")
		(net "P3E_CPU0_PE2_SS_RXP<8>")
	)
	(arc
		(start 303.54778 -81.564734)
		(mid 303.737709 -81.506864)
		(end 303.876456 -81.364836)
		(width 0.0889)
		(layer "In4.Cu")
		(net "P3E_CPU0_PE2_SS_RXP<8>")
	)
	(arc
		(start 303.183036 -81.364836)
		(mid 303.32178 -81.506869)
		(end 303.511712 -81.564734)
		(width 0.0889)
		(layer "In4.Cu")
		(net "P3E_CPU0_PE2_SS_RXP<8>")
	)
	(arc
		(start 303.876456 -81.364836)
		(mid 304.085064 -81.152904)
		(end 304.370486 -81.069434)
		(width 0.0889)
		(layer "In4.Cu")
		(net "P3E_CPU0_PE2_SS_RXP<8>")
	)
	(arc
		(start 301.834296 -80.574388)
		(mid 302.117513 -80.658669)
		(end 302.324516 -80.869536)
		(width 0.0889)
		(layer "In4.Cu")
		(net "P3E_CPU0_PE2_SS_RXP<8>")
	)
	(arc
		(start 301.465996 -80.374236)
		(mid 301.607679 -80.51804)
		(end 301.80153 -80.574388)
		(width 0.0889)
		(layer "In4.Cu")
		(net "P3E_CPU0_PE2_SS_RXP<8>")
	)
	(arc
		(start 302.689006 -81.069434)
		(mid 302.97443 -81.152901)
		(end 303.183036 -81.364836)
		(width 0.0889)
		(layer "In4.Cu")
		(net "P3E_CPU0_PE2_SS_RXP<8>")
	)
	(arc
		(start 302.324516 -80.869536)
		(mid 302.464595 -81.012272)
		(end 302.65624 -81.069434)
		(width 0.0889)
		(layer "In4.Cu")
		(net "P3E_CPU0_PE2_SS_RXP<8>")
	)
	(arc
		(start 301.019464 -80.082136)
		(mid 301.277601 -80.17489)
		(end 301.465996 -80.374236)
		(width 0.0889)
		(layer "In4.Cu")
		(net "P3E_CPU0_PE2_SS_RXP<8>")
	)
	(segment
		(start 392.749786 -3.316986)
		(end 392.749786 -3.478784)
		(width 0.1143)
		(layer "F.Cu")
		(net "P3E_CPU0_PE2_SS_RXP<7>")
	)
	(segment
		(start 392.470386 -3.758184)
		(end 392.470386 -4.386072)
		(width 0.1143)
		(layer "F.Cu")
		(net "P3E_CPU0_PE2_SS_RXP<7>")
	)
	(segment
		(start 301.241206 -82.155284)
		(end 301.812706 -82.155284)
		(width 0.1143)
		(layer "F.Cu")
		(net "P3E_CPU0_PE2_SS_RXP<7>")
	)
	(segment
		(start 392.609324 -3.176524)
		(end 392.749786 -3.316986)
		(width 0.1143)
		(layer "F.Cu")
		(net "P3E_CPU0_PE2_SS_RXP<7>")
	)
	(segment
		(start 392.353292 -3.176524)
		(end 392.609324 -3.176524)
		(width 0.1143)
		(layer "F.Cu")
		(net "P3E_CPU0_PE2_SS_RXP<7>")
	)
	(segment
		(start 392.749786 -3.478784)
		(end 392.470386 -3.758184)
		(width 0.1143)
		(layer "F.Cu")
		(net "P3E_CPU0_PE2_SS_RXP<7>")
	)
	(via
		(at 301.812706 -82.155284)
		(size 0.508)
		(drill 0.254)
		(layers "F.Cu" "B.Cu")
		(net "P3E_CPU0_PE2_SS_RXP<7>")
	)
	(via
		(at 392.353292 -3.176524)
		(size 0.508)
		(drill 0.254)
		(layers "F.Cu" "B.Cu")
		(net "P3E_CPU0_PE2_SS_RXP<7>")
	)
	(segment
		(start 304.399442 -82.060034)
		(end 304.366676 -82.060034)
		(width 0.0889)
		(layer "In4.Cu")
		(net "P3E_CPU0_PE2_SS_RXP<7>")
	)
	(segment
		(start 366.00638 -27.126184)
		(end 360.183938 -35.859212)
		(width 0.1143)
		(layer "In4.Cu")
		(net "P3E_CPU0_PE2_SS_RXP<7>")
	)
	(segment
		(start 304.735484 -81.859374)
		(end 304.734976 -81.859882)
		(width 0.0889)
		(layer "In4.Cu")
		(net "P3E_CPU0_PE2_SS_RXP<7>")
	)
	(segment
		(start 384.558794 -3.678174)
		(end 384.36296 -3.805428)
		(width 0.1143)
		(layer "In4.Cu")
		(net "P3E_CPU0_PE2_SS_RXP<7>")
	)
	(segment
		(start 317.71971 -63.150496)
		(end 311.85358 -77.30998)
		(width 0.1143)
		(layer "In4.Cu")
		(net "P3E_CPU0_PE2_SS_RXP<7>")
	)
	(segment
		(start 384.894328 -3.749294)
		(end 384.558794 -3.678174)
		(width 0.1143)
		(layer "In4.Cu")
		(net "P3E_CPU0_PE2_SS_RXP<7>")
	)
	(segment
		(start 388.737856 -3.670046)
		(end 388.402322 -3.598926)
		(width 0.1143)
		(layer "In4.Cu")
		(net "P3E_CPU0_PE2_SS_RXP<7>")
	)
	(segment
		(start 307.364384 -81.51368)
		(end 307.342286 -81.51368)
		(width 0.0889)
		(layer "In4.Cu")
		(net "P3E_CPU0_PE2_SS_RXP<7>")
	)
	(segment
		(start 383.033778 -3.523234)
		(end 382.906524 -3.3274)
		(width 0.1143)
		(layer "In4.Cu")
		(net "P3E_CPU0_PE2_SS_RXP<7>")
	)
	(segment
		(start 307.59781 -81.51368)
		(end 307.364384 -81.51368)
		(width 0.1143)
		(layer "In4.Cu")
		(net "P3E_CPU0_PE2_SS_RXP<7>")
	)
	(segment
		(start 391.296398 -4.213606)
		(end 389.396224 -3.81)
		(width 0.1143)
		(layer "In4.Cu")
		(net "P3E_CPU0_PE2_SS_RXP<7>")
	)
	(segment
		(start 356.924864 -44.015406)
		(end 343.869264 -47.51451)
		(width 0.1143)
		(layer "In4.Cu")
		(net "P3E_CPU0_PE2_SS_RXP<7>")
	)
	(segment
		(start 329.939396 -49.375314)
		(end 326.220582 -51.780694)
		(width 0.1143)
		(layer "In4.Cu")
		(net "P3E_CPU0_PE2_SS_RXP<7>")
	)
	(segment
		(start 337.269582 -47.058834)
		(end 329.939396 -49.375314)
		(width 0.1143)
		(layer "In4.Cu")
		(net "P3E_CPU0_PE2_SS_RXP<7>")
	)
	(segment
		(start 385.021328 -3.945128)
		(end 384.894328 -3.749294)
		(width 0.1143)
		(layer "In4.Cu")
		(net "P3E_CPU0_PE2_SS_RXP<7>")
	)
	(segment
		(start 326.220582 -51.780694)
		(end 324.828662 -53.805582)
		(width 0.1143)
		(layer "In4.Cu")
		(net "P3E_CPU0_PE2_SS_RXP<7>")
	)
	(segment
		(start 384.36296 -3.805428)
		(end 384.02768 -3.734054)
		(width 0.1143)
		(layer "In4.Cu")
		(net "P3E_CPU0_PE2_SS_RXP<7>")
	)
	(segment
		(start 389.396224 -3.81)
		(end 389.26897 -3.614166)
		(width 0.1143)
		(layer "In4.Cu")
		(net "P3E_CPU0_PE2_SS_RXP<7>")
	)
	(segment
		(start 341.631016 -47.059342)
		(end 339.45068 -47.50308)
		(width 0.1143)
		(layer "In4.Cu")
		(net "P3E_CPU0_PE2_SS_RXP<7>")
	)
	(segment
		(start 392.503914 -3.956558)
		(end 391.296398 -4.213606)
		(width 0.1143)
		(layer "In4.Cu")
		(net "P3E_CPU0_PE2_SS_RXP<7>")
	)
	(segment
		(start 301.812706 -82.493358)
		(end 301.812706 -82.155284)
		(width 0.0889)
		(layer "In4.Cu")
		(net "P3E_CPU0_PE2_SS_RXP<7>")
	)
	(segment
		(start 343.869264 -47.51451)
		(end 341.631016 -47.059342)
		(width 0.1143)
		(layer "In4.Cu")
		(net "P3E_CPU0_PE2_SS_RXP<7>")
	)
	(segment
		(start 311.85358 -77.30998)
		(end 310.74741 -78.658466)
		(width 0.1143)
		(layer "In4.Cu")
		(net "P3E_CPU0_PE2_SS_RXP<7>")
	)
	(segment
		(start 307.291486 -81.56448)
		(end 305.246786 -81.56448)
		(width 0.0889)
		(layer "In4.Cu")
		(net "P3E_CPU0_PE2_SS_RXP<7>")
	)
	(segment
		(start 323.882004 -54.191662)
		(end 323.881242 -54.19217)
		(width 0.1143)
		(layer "In4.Cu")
		(net "P3E_CPU0_PE2_SS_RXP<7>")
	)
	(segment
		(start 385.897374 -4.131056)
		(end 385.021328 -3.945128)
		(width 0.1143)
		(layer "In4.Cu")
		(net "P3E_CPU0_PE2_SS_RXP<7>")
	)
	(segment
		(start 388.933436 -3.543046)
		(end 388.737856 -3.670046)
		(width 0.1143)
		(layer "In4.Cu")
		(net "P3E_CPU0_PE2_SS_RXP<7>")
	)
	(segment
		(start 368.735356 -14.207236)
		(end 366.00638 -27.126184)
		(width 0.1143)
		(layer "In4.Cu")
		(net "P3E_CPU0_PE2_SS_RXP<7>")
	)
	(segment
		(start 392.6967 -3.35534)
		(end 392.6967 -3.76428)
		(width 0.1143)
		(layer "In4.Cu")
		(net "P3E_CPU0_PE2_SS_RXP<7>")
	)
	(segment
		(start 339.45068 -47.50308)
		(end 337.269582 -47.058834)
		(width 0.1143)
		(layer "In4.Cu")
		(net "P3E_CPU0_PE2_SS_RXP<7>")
	)
	(segment
		(start 307.342286 -81.51368)
		(end 307.291486 -81.56448)
		(width 0.0889)
		(layer "In4.Cu")
		(net "P3E_CPU0_PE2_SS_RXP<7>")
	)
	(segment
		(start 383.369058 -3.594354)
		(end 383.033778 -3.523234)
		(width 0.1143)
		(layer "In4.Cu")
		(net "P3E_CPU0_PE2_SS_RXP<7>")
	)
	(segment
		(start 392.517884 -3.176524)
		(end 392.6967 -3.35534)
		(width 0.1143)
		(layer "In4.Cu")
		(net "P3E_CPU0_PE2_SS_RXP<7>")
	)
	(segment
		(start 374.029986 -10.091674)
		(end 368.735356 -14.207236)
		(width 0.1143)
		(layer "In4.Cu")
		(net "P3E_CPU0_PE2_SS_RXP<7>")
	)
	(segment
		(start 310.74741 -78.658466)
		(end 307.59781 -81.51368)
		(width 0.1143)
		(layer "In4.Cu")
		(net "P3E_CPU0_PE2_SS_RXP<7>")
	)
	(segment
		(start 301.870618 -82.55127)
		(end 301.812706 -82.493358)
		(width 0.0889)
		(layer "In4.Cu")
		(net "P3E_CPU0_PE2_SS_RXP<7>")
	)
	(segment
		(start 383.564892 -3.4671)
		(end 383.369058 -3.594354)
		(width 0.1143)
		(layer "In4.Cu")
		(net "P3E_CPU0_PE2_SS_RXP<7>")
	)
	(segment
		(start 358.244394 -43.1419)
		(end 356.924864 -44.015406)
		(width 0.1143)
		(layer "In4.Cu")
		(net "P3E_CPU0_PE2_SS_RXP<7>")
	)
	(segment
		(start 382.57099 -3.256026)
		(end 382.37541 -3.38328)
		(width 0.1143)
		(layer "In4.Cu")
		(net "P3E_CPU0_PE2_SS_RXP<7>")
	)
	(segment
		(start 388.402322 -3.598926)
		(end 385.897374 -4.131056)
		(width 0.1143)
		(layer "In4.Cu")
		(net "P3E_CPU0_PE2_SS_RXP<7>")
	)
	(segment
		(start 382.37541 -3.38328)
		(end 382.039876 -3.31216)
		(width 0.1143)
		(layer "In4.Cu")
		(net "P3E_CPU0_PE2_SS_RXP<7>")
	)
	(segment
		(start 392.353292 -3.176524)
		(end 392.517884 -3.176524)
		(width 0.1143)
		(layer "In4.Cu")
		(net "P3E_CPU0_PE2_SS_RXP<7>")
	)
	(segment
		(start 323.881242 -54.19217)
		(end 317.720218 -63.148972)
		(width 0.1143)
		(layer "In4.Cu")
		(net "P3E_CPU0_PE2_SS_RXP<7>")
	)
	(segment
		(start 377.443238 -5.325872)
		(end 374.029986 -10.091674)
		(width 0.1143)
		(layer "In4.Cu")
		(net "P3E_CPU0_PE2_SS_RXP<7>")
	)
	(segment
		(start 392.6967 -3.76428)
		(end 392.503914 -3.956558)
		(width 0.1143)
		(layer "In4.Cu")
		(net "P3E_CPU0_PE2_SS_RXP<7>")
	)
	(segment
		(start 304.740564 -81.850738)
		(end 304.735484 -81.859374)
		(width 0.0889)
		(layer "In4.Cu")
		(net "P3E_CPU0_PE2_SS_RXP<7>")
	)
	(segment
		(start 317.719456 -63.150496)
		(end 317.71971 -63.150496)
		(width 0.1143)
		(layer "In4.Cu")
		(net "P3E_CPU0_PE2_SS_RXP<7>")
	)
	(segment
		(start 360.183938 -35.859212)
		(end 358.90581 -42.142664)
		(width 0.1143)
		(layer "In4.Cu")
		(net "P3E_CPU0_PE2_SS_RXP<7>")
	)
	(segment
		(start 358.90581 -42.142664)
		(end 358.244394 -43.1419)
		(width 0.1143)
		(layer "In4.Cu")
		(net "P3E_CPU0_PE2_SS_RXP<7>")
	)
	(segment
		(start 383.900426 -3.53822)
		(end 383.564892 -3.4671)
		(width 0.1143)
		(layer "In4.Cu")
		(net "P3E_CPU0_PE2_SS_RXP<7>")
	)
	(segment
		(start 317.720218 -63.148972)
		(end 317.719456 -63.150496)
		(width 0.1143)
		(layer "In4.Cu")
		(net "P3E_CPU0_PE2_SS_RXP<7>")
	)
	(segment
		(start 384.02768 -3.734054)
		(end 383.900426 -3.53822)
		(width 0.1143)
		(layer "In4.Cu")
		(net "P3E_CPU0_PE2_SS_RXP<7>")
	)
	(segment
		(start 324.828662 -53.805582)
		(end 323.882004 -54.191662)
		(width 0.1143)
		(layer "In4.Cu")
		(net "P3E_CPU0_PE2_SS_RXP<7>")
	)
	(segment
		(start 382.906524 -3.3274)
		(end 382.57099 -3.256026)
		(width 0.1143)
		(layer "In4.Cu")
		(net "P3E_CPU0_PE2_SS_RXP<7>")
	)
	(segment
		(start 389.26897 -3.614166)
		(end 388.933436 -3.543046)
		(width 0.1143)
		(layer "In4.Cu")
		(net "P3E_CPU0_PE2_SS_RXP<7>")
	)
	(segment
		(start 382.039876 -3.31216)
		(end 377.443238 -5.325872)
		(width 0.1143)
		(layer "In4.Cu")
		(net "P3E_CPU0_PE2_SS_RXP<7>")
	)
	(arc
		(start 302.159416 -82.355182)
		(mid 302.037525 -82.486378)
		(end 301.870618 -82.55127)
		(width 0.0889)
		(layer "In4.Cu")
		(net "P3E_CPU0_PE2_SS_RXP<7>")
	)
	(arc
		(start 305.246786 -81.56448)
		(mid 304.956001 -81.640995)
		(end 304.740564 -81.850738)
		(width 0.0889)
		(layer "In4.Cu")
		(net "P3E_CPU0_PE2_SS_RXP<7>")
	)
	(arc
		(start 303.183036 -82.355182)
		(mid 302.671226 -82.059515)
		(end 302.159416 -82.355182)
		(width 0.0889)
		(layer "In4.Cu")
		(net "P3E_CPU0_PE2_SS_RXP<7>")
	)
	(arc
		(start 303.876456 -82.355182)
		(mid 303.529746 -82.555493)
		(end 303.183036 -82.355182)
		(width 0.0889)
		(layer "In4.Cu")
		(net "P3E_CPU0_PE2_SS_RXP<7>")
	)
	(arc
		(start 304.366676 -82.060034)
		(mid 304.083459 -82.144315)
		(end 303.876456 -82.355182)
		(width 0.0889)
		(layer "In4.Cu")
		(net "P3E_CPU0_PE2_SS_RXP<7>")
	)
	(arc
		(start 304.734976 -81.859882)
		(mid 304.593293 -82.003686)
		(end 304.399442 -82.060034)
		(width 0.0889)
		(layer "In4.Cu")
		(net "P3E_CPU0_PE2_SS_RXP<7>")
	)
	(segment
		(start 395.391386 -3.478784)
		(end 395.391386 -3.261614)
		(width 0.1143)
		(layer "F.Cu")
		(net "P3E_CPU0_PE2_SS_RXP<6>")
	)
	(segment
		(start 302.099726 -82.650584)
		(end 302.671226 -82.650584)
		(width 0.1143)
		(layer "F.Cu")
		(net "P3E_CPU0_PE2_SS_RXP<6>")
	)
	(segment
		(start 395.527276 -3.125724)
		(end 395.769592 -3.125724)
		(width 0.1143)
		(layer "F.Cu")
		(net "P3E_CPU0_PE2_SS_RXP<6>")
	)
	(segment
		(start 395.670786 -3.758184)
		(end 395.391386 -3.478784)
		(width 0.1143)
		(layer "F.Cu")
		(net "P3E_CPU0_PE2_SS_RXP<6>")
	)
	(segment
		(start 395.391386 -3.261614)
		(end 395.527276 -3.125724)
		(width 0.1143)
		(layer "F.Cu")
		(net "P3E_CPU0_PE2_SS_RXP<6>")
	)
	(segment
		(start 395.670786 -4.386072)
		(end 395.670786 -3.758184)
		(width 0.1143)
		(layer "F.Cu")
		(net "P3E_CPU0_PE2_SS_RXP<6>")
	)
	(via
		(at 395.769592 -3.125724)
		(size 0.508)
		(drill 0.254)
		(layers "F.Cu" "B.Cu")
		(net "P3E_CPU0_PE2_SS_RXP<6>")
	)
	(via
		(at 302.671226 -82.650584)
		(size 0.508)
		(drill 0.254)
		(layers "F.Cu" "B.Cu")
		(net "P3E_CPU0_PE2_SS_RXP<6>")
	)
	(segment
		(start 343.919302 -48.47463)
		(end 357.386382 -44.864782)
		(width 0.1143)
		(layer "In4.Cu")
		(net "P3E_CPU0_PE2_SS_RXP<6>")
	)
	(segment
		(start 395.431264 -3.294888)
		(end 395.600428 -3.125724)
		(width 0.1143)
		(layer "In4.Cu")
		(net "P3E_CPU0_PE2_SS_RXP<6>")
	)
	(segment
		(start 391.296398 -5.200396)
		(end 392.015218 -5.047742)
		(width 0.1143)
		(layer "In4.Cu")
		(net "P3E_CPU0_PE2_SS_RXP<6>")
	)
	(segment
		(start 337.312762 -48.019462)
		(end 339.533484 -48.471328)
		(width 0.1143)
		(layer "In4.Cu")
		(net "P3E_CPU0_PE2_SS_RXP<6>")
	)
	(segment
		(start 305.447954 -82.8167)
		(end 305.711606 -82.553048)
		(width 0.0889)
		(layer "In4.Cu")
		(net "P3E_CPU0_PE2_SS_RXP<6>")
	)
	(segment
		(start 311.599834 -79.229712)
		(end 312.55843 -78.061058)
		(width 0.1143)
		(layer "In4.Cu")
		(net "P3E_CPU0_PE2_SS_RXP<6>")
	)
	(segment
		(start 388.40283 -4.585716)
		(end 391.296398 -5.200396)
		(width 0.1143)
		(layer "In4.Cu")
		(net "P3E_CPU0_PE2_SS_RXP<6>")
	)
	(segment
		(start 305.711606 -82.553048)
		(end 307.493416 -82.553048)
		(width 0.0889)
		(layer "In4.Cu")
		(net "P3E_CPU0_PE2_SS_RXP<6>")
	)
	(segment
		(start 357.386382 -44.864782)
		(end 358.905556 -43.85945)
		(width 0.1143)
		(layer "In4.Cu")
		(net "P3E_CPU0_PE2_SS_RXP<6>")
	)
	(segment
		(start 367.574068 -24.887936)
		(end 368.56035 -23.410164)
		(width 0.1143)
		(layer "In4.Cu")
		(net "P3E_CPU0_PE2_SS_RXP<6>")
	)
	(segment
		(start 393.88161 -5.171694)
		(end 393.88161 -5.17144)
		(width 0.1143)
		(layer "In4.Cu")
		(net "P3E_CPU0_PE2_SS_RXP<6>")
	)
	(segment
		(start 324.492112 -54.944772)
		(end 325.440548 -54.557676)
		(width 0.1143)
		(layer "In4.Cu")
		(net "P3E_CPU0_PE2_SS_RXP<6>")
	)
	(segment
		(start 307.493416 -82.553048)
		(end 307.542184 -82.601816)
		(width 0.0889)
		(layer "In4.Cu")
		(net "P3E_CPU0_PE2_SS_RXP<6>")
	)
	(segment
		(start 385.986274 -5.09905)
		(end 388.40283 -4.585716)
		(width 0.1143)
		(layer "In4.Cu")
		(net "P3E_CPU0_PE2_SS_RXP<6>")
	)
	(segment
		(start 307.878988 -82.601816)
		(end 311.599834 -79.229712)
		(width 0.1143)
		(layer "In4.Cu")
		(net "P3E_CPU0_PE2_SS_RXP<6>")
	)
	(segment
		(start 307.542184 -82.601816)
		(end 307.564282 -82.601816)
		(width 0.0889)
		(layer "In4.Cu")
		(net "P3E_CPU0_PE2_SS_RXP<6>")
	)
	(segment
		(start 304.402998 -83.241134)
		(end 304.642266 -83.241134)
		(width 0.0889)
		(layer "In4.Cu")
		(net "P3E_CPU0_PE2_SS_RXP<6>")
	)
	(segment
		(start 382.200912 -4.294378)
		(end 385.986274 -5.09905)
		(width 0.1143)
		(layer "In4.Cu")
		(net "P3E_CPU0_PE2_SS_RXP<6>")
	)
	(segment
		(start 341.718392 -48.026828)
		(end 343.919302 -48.47463)
		(width 0.1143)
		(layer "In4.Cu")
		(net "P3E_CPU0_PE2_SS_RXP<6>")
	)
	(segment
		(start 339.533484 -48.471328)
		(end 341.718392 -48.026828)
		(width 0.1143)
		(layer "In4.Cu")
		(net "P3E_CPU0_PE2_SS_RXP<6>")
	)
	(segment
		(start 361.070906 -36.220654)
		(end 367.123472 -27.141678)
		(width 0.1143)
		(layer "In4.Cu")
		(net "P3E_CPU0_PE2_SS_RXP<6>")
	)
	(segment
		(start 393.240006 -5.307838)
		(end 393.88161 -5.171694)
		(width 0.1143)
		(layer "In4.Cu")
		(net "P3E_CPU0_PE2_SS_RXP<6>")
	)
	(segment
		(start 307.564282 -82.601816)
		(end 307.878988 -82.601816)
		(width 0.1143)
		(layer "In4.Cu")
		(net "P3E_CPU0_PE2_SS_RXP<6>")
	)
	(segment
		(start 318.563244 -63.564008)
		(end 324.492112 -54.944772)
		(width 0.1143)
		(layer "In4.Cu")
		(net "P3E_CPU0_PE2_SS_RXP<6>")
	)
	(segment
		(start 325.440548 -54.557676)
		(end 326.87895 -52.46624)
		(width 0.1143)
		(layer "In4.Cu")
		(net "P3E_CPU0_PE2_SS_RXP<6>")
	)
	(segment
		(start 304.402998 -83.241388)
		(end 304.402998 -83.241134)
		(width 0.0889)
		(layer "In4.Cu")
		(net "P3E_CPU0_PE2_SS_RXP<6>")
	)
	(segment
		(start 392.015218 -5.047742)
		(end 393.240006 -5.307838)
		(width 0.1143)
		(layer "In4.Cu")
		(net "P3E_CPU0_PE2_SS_RXP<6>")
	)
	(segment
		(start 326.87895 -52.46624)
		(end 330.347574 -50.219864)
		(width 0.1143)
		(layer "In4.Cu")
		(net "P3E_CPU0_PE2_SS_RXP<6>")
	)
	(segment
		(start 372.758462 -14.81455)
		(end 380.97841 -4.82981)
		(width 0.1143)
		(layer "In4.Cu")
		(net "P3E_CPU0_PE2_SS_RXP<6>")
	)
	(segment
		(start 359.79481 -42.515282)
		(end 361.070906 -36.220654)
		(width 0.1143)
		(layer "In4.Cu")
		(net "P3E_CPU0_PE2_SS_RXP<6>")
	)
	(segment
		(start 330.347574 -50.219864)
		(end 337.312762 -48.019462)
		(width 0.1143)
		(layer "In4.Cu")
		(net "P3E_CPU0_PE2_SS_RXP<6>")
	)
	(segment
		(start 394.547344 -5.030216)
		(end 395.431264 -4.146042)
		(width 0.1143)
		(layer "In4.Cu")
		(net "P3E_CPU0_PE2_SS_RXP<6>")
	)
	(segment
		(start 368.56035 -23.410164)
		(end 371.158516 -21.678138)
		(width 0.1143)
		(layer "In4.Cu")
		(net "P3E_CPU0_PE2_SS_RXP<6>")
	)
	(segment
		(start 371.158516 -21.678138)
		(end 372.758462 -14.81455)
		(width 0.1143)
		(layer "In4.Cu")
		(net "P3E_CPU0_PE2_SS_RXP<6>")
	)
	(segment
		(start 380.97841 -4.82981)
		(end 382.200912 -4.294378)
		(width 0.1143)
		(layer "In4.Cu")
		(net "P3E_CPU0_PE2_SS_RXP<6>")
	)
	(segment
		(start 305.0667 -82.8167)
		(end 305.447954 -82.8167)
		(width 0.0889)
		(layer "In4.Cu")
		(net "P3E_CPU0_PE2_SS_RXP<6>")
	)
	(segment
		(start 395.431264 -4.146042)
		(end 395.431264 -3.294888)
		(width 0.1143)
		(layer "In4.Cu")
		(net "P3E_CPU0_PE2_SS_RXP<6>")
	)
	(segment
		(start 393.88161 -5.17144)
		(end 394.547344 -5.030216)
		(width 0.1143)
		(layer "In4.Cu")
		(net "P3E_CPU0_PE2_SS_RXP<6>")
	)
	(segment
		(start 367.123472 -27.141678)
		(end 367.574068 -24.887936)
		(width 0.1143)
		(layer "In4.Cu")
		(net "P3E_CPU0_PE2_SS_RXP<6>")
	)
	(segment
		(start 358.905556 -43.85945)
		(end 359.79481 -42.515282)
		(width 0.1143)
		(layer "In4.Cu")
		(net "P3E_CPU0_PE2_SS_RXP<6>")
	)
	(segment
		(start 304.642266 -83.241134)
		(end 305.0667 -82.8167)
		(width 0.0889)
		(layer "In4.Cu")
		(net "P3E_CPU0_PE2_SS_RXP<6>")
	)
	(segment
		(start 303.511966 -83.736688)
		(end 303.547526 -83.736688)
		(width 0.0889)
		(layer "In4.Cu")
		(net "P3E_CPU0_PE2_SS_RXP<6>")
	)
	(segment
		(start 395.600428 -3.125724)
		(end 395.769592 -3.125724)
		(width 0.1143)
		(layer "In4.Cu")
		(net "P3E_CPU0_PE2_SS_RXP<6>")
	)
	(segment
		(start 312.55843 -78.061058)
		(end 318.563244 -63.564008)
		(width 0.1143)
		(layer "In4.Cu")
		(net "P3E_CPU0_PE2_SS_RXP<6>")
	)
	(arc
		(start 304.041556 -83.441286)
		(mid 304.182855 -83.297922)
		(end 304.376074 -83.241388)
		(width 0.0889)
		(layer "In4.Cu")
		(net "P3E_CPU0_PE2_SS_RXP<6>")
	)
	(arc
		(start 304.376074 -83.241388)
		(mid 304.389536 -83.241161)
		(end 304.402998 -83.241388)
		(width 0.0889)
		(layer "In4.Cu")
		(net "P3E_CPU0_PE2_SS_RXP<6>")
	)
	(arc
		(start 303.547526 -83.736688)
		(mid 303.83295 -83.653221)
		(end 304.041556 -83.441286)
		(width 0.0889)
		(layer "In4.Cu")
		(net "P3E_CPU0_PE2_SS_RXP<6>")
	)
	(arc
		(start 302.977804 -83.357466)
		(mid 303.18754 -83.627861)
		(end 303.511966 -83.736688)
		(width 0.0889)
		(layer "In4.Cu")
		(net "P3E_CPU0_PE2_SS_RXP<6>")
	)
	(arc
		(start 302.671226 -82.650584)
		(mid 302.832147 -83.000715)
		(end 302.977804 -83.357466)
		(width 0.0889)
		(layer "In4.Cu")
		(net "P3E_CPU0_PE2_SS_RXP<6>")
	)
	(segment
		(start 397.409924 -3.176524)
		(end 397.524986 -3.291586)
		(width 0.1143)
		(layer "F.Cu")
		(net "P3E_CPU0_PE2_SS_RXP<5>")
	)
	(segment
		(start 397.270986 -3.758184)
		(end 397.270986 -4.386072)
		(width 0.1143)
		(layer "F.Cu")
		(net "P3E_CPU0_PE2_SS_RXP<5>")
	)
	(segment
		(start 397.128492 -3.176524)
		(end 397.409924 -3.176524)
		(width 0.1143)
		(layer "F.Cu")
		(net "P3E_CPU0_PE2_SS_RXP<5>")
	)
	(segment
		(start 397.524986 -3.291586)
		(end 397.524986 -3.504184)
		(width 0.1143)
		(layer "F.Cu")
		(net "P3E_CPU0_PE2_SS_RXP<5>")
	)
	(segment
		(start 302.099726 -83.641184)
		(end 302.671226 -83.641184)
		(width 0.1143)
		(layer "F.Cu")
		(net "P3E_CPU0_PE2_SS_RXP<5>")
	)
	(segment
		(start 397.524986 -3.504184)
		(end 397.270986 -3.758184)
		(width 0.1143)
		(layer "F.Cu")
		(net "P3E_CPU0_PE2_SS_RXP<5>")
	)
	(via
		(at 397.128492 -3.176524)
		(size 0.508)
		(drill 0.254)
		(layers "F.Cu" "B.Cu")
		(net "P3E_CPU0_PE2_SS_RXP<5>")
	)
	(via
		(at 302.671226 -83.641184)
		(size 0.508)
		(drill 0.254)
		(layers "F.Cu" "B.Cu")
		(net "P3E_CPU0_PE2_SS_RXP<5>")
	)
	(segment
		(start 327.137776 -52.711604)
		(end 330.471018 -50.552858)
		(width 0.1143)
		(layer "In4.Cu")
		(net "P3E_CPU0_PE2_SS_RXP<5>")
	)
	(segment
		(start 308.01691 -83.0199)
		(end 308.360572 -82.79003)
		(width 0.1143)
		(layer "In4.Cu")
		(net "P3E_CPU0_PE2_SS_RXP<5>")
	)
	(segment
		(start 343.93505 -48.834802)
		(end 357.567992 -45.180758)
		(width 0.1143)
		(layer "In4.Cu")
		(net "P3E_CPU0_PE2_SS_RXP<5>")
	)
	(segment
		(start 318.900302 -63.683896)
		(end 318.901572 -63.681356)
		(width 0.1143)
		(layer "In4.Cu")
		(net "P3E_CPU0_PE2_SS_RXP<5>")
	)
	(segment
		(start 384.574034 -7.27583)
		(end 385.072128 -7.381494)
		(width 0.1143)
		(layer "In4.Cu")
		(net "P3E_CPU0_PE2_SS_RXP<5>")
	)
	(segment
		(start 382.742948 -6.134608)
		(end 384.574034 -7.27583)
		(width 0.1143)
		(layer "In4.Cu")
		(net "P3E_CPU0_PE2_SS_RXP<5>")
	)
	(segment
		(start 318.901572 -63.681356)
		(end 324.720204 -55.22214)
		(width 0.1143)
		(layer "In4.Cu")
		(net "P3E_CPU0_PE2_SS_RXP<5>")
	)
	(segment
		(start 397.364966 -3.176524)
		(end 397.128492 -3.176524)
		(width 0.1143)
		(layer "In4.Cu")
		(net "P3E_CPU0_PE2_SS_RXP<5>")
	)
	(segment
		(start 306.392326 -83.0707)
		(end 306.570126 -83.0707)
		(width 0.0889)
		(layer "In4.Cu")
		(net "P3E_CPU0_PE2_SS_RXP<5>")
	)
	(segment
		(start 304.908966 -83.552792)
		(end 305.187858 -83.2739)
		(width 0.0889)
		(layer "In4.Cu")
		(net "P3E_CPU0_PE2_SS_RXP<5>")
	)
	(segment
		(start 385.072128 -7.381494)
		(end 385.267962 -7.25424)
		(width 0.1143)
		(layer "In4.Cu")
		(net "P3E_CPU0_PE2_SS_RXP<5>")
	)
	(segment
		(start 324.720712 -55.221886)
		(end 325.68134 -54.829964)
		(width 0.1143)
		(layer "In4.Cu")
		(net "P3E_CPU0_PE2_SS_RXP<5>")
	)
	(segment
		(start 306.669186 -82.97164)
		(end 306.846986 -82.97164)
		(width 0.0889)
		(layer "In4.Cu")
		(net "P3E_CPU0_PE2_SS_RXP<5>")
	)
	(segment
		(start 304.891186 -83.570318)
		(end 304.908712 -83.552792)
		(width 0.0889)
		(layer "In4.Cu")
		(net "P3E_CPU0_PE2_SS_RXP<5>")
	)
	(segment
		(start 324.720204 -55.22214)
		(end 324.720712 -55.221886)
		(width 0.1143)
		(layer "In4.Cu")
		(net "P3E_CPU0_PE2_SS_RXP<5>")
	)
	(segment
		(start 397.504666 -4.240276)
		(end 397.504666 -3.316224)
		(width 0.1143)
		(layer "In4.Cu")
		(net "P3E_CPU0_PE2_SS_RXP<5>")
	)
	(segment
		(start 385.730496 -7.521194)
		(end 389.829802 -8.391652)
		(width 0.1143)
		(layer "In4.Cu")
		(net "P3E_CPU0_PE2_SS_RXP<5>")
	)
	(segment
		(start 385.603242 -7.325614)
		(end 385.730496 -7.521448)
		(width 0.1143)
		(layer "In4.Cu")
		(net "P3E_CPU0_PE2_SS_RXP<5>")
	)
	(segment
		(start 306.846986 -82.97164)
		(end 306.946046 -83.0707)
		(width 0.0889)
		(layer "In4.Cu")
		(net "P3E_CPU0_PE2_SS_RXP<5>")
	)
	(segment
		(start 341.797132 -48.399446)
		(end 343.93505 -48.834802)
		(width 0.1143)
		(layer "In4.Cu")
		(net "P3E_CPU0_PE2_SS_RXP<5>")
	)
	(segment
		(start 307.365654 -83.0199)
		(end 307.387752 -83.0199)
		(width 0.0889)
		(layer "In4.Cu")
		(net "P3E_CPU0_PE2_SS_RXP<5>")
	)
	(segment
		(start 371.115844 -23.715218)
		(end 372.299738 -18.636996)
		(width 0.1143)
		(layer "In4.Cu")
		(net "P3E_CPU0_PE2_SS_RXP<5>")
	)
	(segment
		(start 303.51603 -84.536788)
		(end 303.517808 -84.536788)
		(width 0.0889)
		(layer "In4.Cu")
		(net "P3E_CPU0_PE2_SS_RXP<5>")
	)
	(segment
		(start 306.570126 -83.0707)
		(end 306.669186 -82.97164)
		(width 0.0889)
		(layer "In4.Cu")
		(net "P3E_CPU0_PE2_SS_RXP<5>")
	)
	(segment
		(start 330.471018 -50.552858)
		(end 337.353402 -48.38192)
		(width 0.1143)
		(layer "In4.Cu")
		(net "P3E_CPU0_PE2_SS_RXP<5>")
	)
	(segment
		(start 372.299738 -18.636996)
		(end 373.13108 -15.070836)
		(width 0.1143)
		(layer "In4.Cu")
		(net "P3E_CPU0_PE2_SS_RXP<5>")
	)
	(segment
		(start 304.908712 -83.552792)
		(end 304.908966 -83.552792)
		(width 0.0889)
		(layer "In4.Cu")
		(net "P3E_CPU0_PE2_SS_RXP<5>")
	)
	(segment
		(start 305.635406 -83.2739)
		(end 305.838606 -83.0707)
		(width 0.0889)
		(layer "In4.Cu")
		(net "P3E_CPU0_PE2_SS_RXP<5>")
	)
	(segment
		(start 337.353402 -48.38192)
		(end 339.616034 -48.843184)
		(width 0.1143)
		(layer "In4.Cu")
		(net "P3E_CPU0_PE2_SS_RXP<5>")
	)
	(segment
		(start 397.504666 -3.316224)
		(end 397.364966 -3.176524)
		(width 0.1143)
		(layer "In4.Cu")
		(net "P3E_CPU0_PE2_SS_RXP<5>")
	)
	(segment
		(start 302.65624 -84.041234)
		(end 302.689006 -84.041234)
		(width 0.0889)
		(layer "In4.Cu")
		(net "P3E_CPU0_PE2_SS_RXP<5>")
	)
	(segment
		(start 379.25883 -8.764524)
		(end 379.220476 -8.534146)
		(width 0.1143)
		(layer "In4.Cu")
		(net "P3E_CPU0_PE2_SS_RXP<5>")
	)
	(segment
		(start 302.37811 -83.810348)
		(end 302.357028 -83.889088)
		(width 0.0889)
		(layer "In4.Cu")
		(net "P3E_CPU0_PE2_SS_RXP<5>")
	)
	(segment
		(start 325.68134 -54.829964)
		(end 327.137776 -52.711604)
		(width 0.1143)
		(layer "In4.Cu")
		(net "P3E_CPU0_PE2_SS_RXP<5>")
	)
	(segment
		(start 367.50752 -27.201876)
		(end 367.857786 -25.49906)
		(width 0.1143)
		(layer "In4.Cu")
		(net "P3E_CPU0_PE2_SS_RXP<5>")
	)
	(segment
		(start 379.64999 -8.216646)
		(end 379.84938 -7.937754)
		(width 0.1143)
		(layer "In4.Cu")
		(net "P3E_CPU0_PE2_SS_RXP<5>")
	)
	(segment
		(start 379.84938 -7.937754)
		(end 379.811026 -7.707376)
		(width 0.1143)
		(layer "In4.Cu")
		(net "P3E_CPU0_PE2_SS_RXP<5>")
	)
	(segment
		(start 373.13108 -15.070836)
		(end 376.700796 -10.734802)
		(width 0.1143)
		(layer "In4.Cu")
		(net "P3E_CPU0_PE2_SS_RXP<5>")
	)
	(segment
		(start 306.016406 -83.0707)
		(end 306.115466 -82.97164)
		(width 0.0889)
		(layer "In4.Cu")
		(net "P3E_CPU0_PE2_SS_RXP<5>")
	)
	(segment
		(start 357.567992 -45.180758)
		(end 359.164636 -44.124372)
		(width 0.1143)
		(layer "In4.Cu")
		(net "P3E_CPU0_PE2_SS_RXP<5>")
	)
	(segment
		(start 385.730496 -7.521448)
		(end 385.730496 -7.521194)
		(width 0.1143)
		(layer "In4.Cu")
		(net "P3E_CPU0_PE2_SS_RXP<5>")
	)
	(segment
		(start 308.360572 -82.79003)
		(end 311.746138 -79.721456)
		(width 0.1143)
		(layer "In4.Cu")
		(net "P3E_CPU0_PE2_SS_RXP<5>")
	)
	(segment
		(start 307.314854 -83.0707)
		(end 307.365654 -83.0199)
		(width 0.0889)
		(layer "In4.Cu")
		(net "P3E_CPU0_PE2_SS_RXP<5>")
	)
	(segment
		(start 311.746138 -79.721456)
		(end 312.7756 -78.466696)
		(width 0.1143)
		(layer "In4.Cu")
		(net "P3E_CPU0_PE2_SS_RXP<5>")
	)
	(segment
		(start 312.7756 -78.466696)
		(end 318.900302 -63.683896)
		(width 0.1143)
		(layer "In4.Cu")
		(net "P3E_CPU0_PE2_SS_RXP<5>")
	)
	(segment
		(start 376.700796 -10.734802)
		(end 378.561854 -9.739884)
		(width 0.1143)
		(layer "In4.Cu")
		(net "P3E_CPU0_PE2_SS_RXP<5>")
	)
	(segment
		(start 359.164636 -44.124372)
		(end 360.139488 -42.650918)
		(width 0.1143)
		(layer "In4.Cu")
		(net "P3E_CPU0_PE2_SS_RXP<5>")
	)
	(segment
		(start 339.616034 -48.843184)
		(end 341.797132 -48.399446)
		(width 0.1143)
		(layer "In4.Cu")
		(net "P3E_CPU0_PE2_SS_RXP<5>")
	)
	(segment
		(start 360.139488 -42.650918)
		(end 361.424728 -36.31311)
		(width 0.1143)
		(layer "In4.Cu")
		(net "P3E_CPU0_PE2_SS_RXP<5>")
	)
	(segment
		(start 305.187858 -83.2739)
		(end 305.635406 -83.2739)
		(width 0.0889)
		(layer "In4.Cu")
		(net "P3E_CPU0_PE2_SS_RXP<5>")
	)
	(segment
		(start 379.419612 -8.255)
		(end 379.64999 -8.216646)
		(width 0.1143)
		(layer "In4.Cu")
		(net "P3E_CPU0_PE2_SS_RXP<5>")
	)
	(segment
		(start 361.424728 -36.312856)
		(end 367.50752 -27.201876)
		(width 0.1143)
		(layer "In4.Cu")
		(net "P3E_CPU0_PE2_SS_RXP<5>")
	)
	(segment
		(start 302.671226 -83.641184)
		(end 302.37811 -83.810348)
		(width 0.0889)
		(layer "In4.Cu")
		(net "P3E_CPU0_PE2_SS_RXP<5>")
	)
	(segment
		(start 395.183868 -6.561074)
		(end 397.504666 -4.240276)
		(width 0.1143)
		(layer "In4.Cu")
		(net "P3E_CPU0_PE2_SS_RXP<5>")
	)
	(segment
		(start 307.387752 -83.0199)
		(end 308.01691 -83.0199)
		(width 0.1143)
		(layer "In4.Cu")
		(net "P3E_CPU0_PE2_SS_RXP<5>")
	)
	(segment
		(start 303.183036 -84.336636)
		(end 303.183544 -84.337398)
		(width 0.0889)
		(layer "In4.Cu")
		(net "P3E_CPU0_PE2_SS_RXP<5>")
	)
	(segment
		(start 304.370486 -84.041234)
		(end 304.405792 -84.041234)
		(width 0.0889)
		(layer "In4.Cu")
		(net "P3E_CPU0_PE2_SS_RXP<5>")
	)
	(segment
		(start 304.734976 -83.841336)
		(end 304.891186 -83.570318)
		(width 0.0889)
		(layer "In4.Cu")
		(net "P3E_CPU0_PE2_SS_RXP<5>")
	)
	(segment
		(start 306.293266 -82.97164)
		(end 306.392326 -83.0707)
		(width 0.0889)
		(layer "In4.Cu")
		(net "P3E_CPU0_PE2_SS_RXP<5>")
	)
	(segment
		(start 380.010416 -7.428484)
		(end 380.24054 -7.389876)
		(width 0.1143)
		(layer "In4.Cu")
		(net "P3E_CPU0_PE2_SS_RXP<5>")
	)
	(segment
		(start 361.424728 -36.31311)
		(end 361.424728 -36.312856)
		(width 0.1143)
		(layer "In4.Cu")
		(net "P3E_CPU0_PE2_SS_RXP<5>")
	)
	(segment
		(start 385.267962 -7.25424)
		(end 385.603242 -7.325614)
		(width 0.1143)
		(layer "In4.Cu")
		(net "P3E_CPU0_PE2_SS_RXP<5>")
	)
	(segment
		(start 378.561854 -9.739884)
		(end 379.25883 -8.764524)
		(width 0.1143)
		(layer "In4.Cu")
		(net "P3E_CPU0_PE2_SS_RXP<5>")
	)
	(segment
		(start 389.829802 -8.391652)
		(end 395.183868 -6.561074)
		(width 0.1143)
		(layer "In4.Cu")
		(net "P3E_CPU0_PE2_SS_RXP<5>")
	)
	(segment
		(start 379.811026 -7.707376)
		(end 380.010416 -7.428484)
		(width 0.1143)
		(layer "In4.Cu")
		(net "P3E_CPU0_PE2_SS_RXP<5>")
	)
	(segment
		(start 306.115466 -82.97164)
		(end 306.293266 -82.97164)
		(width 0.0889)
		(layer "In4.Cu")
		(net "P3E_CPU0_PE2_SS_RXP<5>")
	)
	(segment
		(start 380.864872 -6.516116)
		(end 382.742948 -6.134608)
		(width 0.1143)
		(layer "In4.Cu")
		(net "P3E_CPU0_PE2_SS_RXP<5>")
	)
	(segment
		(start 367.857786 -25.49906)
		(end 371.115844 -23.715218)
		(width 0.1143)
		(layer "In4.Cu")
		(net "P3E_CPU0_PE2_SS_RXP<5>")
	)
	(segment
		(start 305.838606 -83.0707)
		(end 306.016406 -83.0707)
		(width 0.0889)
		(layer "In4.Cu")
		(net "P3E_CPU0_PE2_SS_RXP<5>")
	)
	(segment
		(start 380.24054 -7.389876)
		(end 380.864872 -6.516116)
		(width 0.1143)
		(layer "In4.Cu")
		(net "P3E_CPU0_PE2_SS_RXP<5>")
	)
	(segment
		(start 306.946046 -83.0707)
		(end 307.314854 -83.0707)
		(width 0.0889)
		(layer "In4.Cu")
		(net "P3E_CPU0_PE2_SS_RXP<5>")
	)
	(segment
		(start 379.220476 -8.534146)
		(end 379.419612 -8.255)
		(width 0.1143)
		(layer "In4.Cu")
		(net "P3E_CPU0_PE2_SS_RXP<5>")
	)
	(arc
		(start 303.541684 -84.536788)
		(mid 303.73511 -84.480261)
		(end 303.876456 -84.336636)
		(width 0.0889)
		(layer "In4.Cu")
		(net "P3E_CPU0_PE2_SS_RXP<5>")
	)
	(arc
		(start 303.183544 -84.337398)
		(mid 303.323881 -84.480301)
		(end 303.51603 -84.536788)
		(width 0.0889)
		(layer "In4.Cu")
		(net "P3E_CPU0_PE2_SS_RXP<5>")
	)
	(arc
		(start 304.405792 -84.041234)
		(mid 304.596034 -83.983499)
		(end 304.734976 -83.841336)
		(width 0.0889)
		(layer "In4.Cu")
		(net "P3E_CPU0_PE2_SS_RXP<5>")
	)
	(arc
		(start 302.689006 -84.041234)
		(mid 302.97443 -84.124701)
		(end 303.183036 -84.336636)
		(width 0.0889)
		(layer "In4.Cu")
		(net "P3E_CPU0_PE2_SS_RXP<5>")
	)
	(arc
		(start 303.876456 -84.336636)
		(mid 304.085064 -84.124704)
		(end 304.370486 -84.041234)
		(width 0.0889)
		(layer "In4.Cu")
		(net "P3E_CPU0_PE2_SS_RXP<5>")
	)
	(arc
		(start 303.517808 -84.536788)
		(mid 303.529746 -84.536966)
		(end 303.541684 -84.536788)
		(width 0.0889)
		(layer "In4.Cu")
		(net "P3E_CPU0_PE2_SS_RXP<5>")
	)
	(arc
		(start 302.357028 -83.889088)
		(mid 302.489909 -83.998071)
		(end 302.65624 -84.041234)
		(width 0.0889)
		(layer "In4.Cu")
		(net "P3E_CPU0_PE2_SS_RXP<5>")
	)
	(segment
		(start 399.554192 -3.176524)
		(end 399.873724 -3.176524)
		(width 0.1143)
		(layer "F.Cu")
		(net "P3E_CPU0_PE2_SS_RXP<4>")
	)
	(segment
		(start 399.671286 -3.758184)
		(end 399.671286 -4.386072)
		(width 0.1143)
		(layer "F.Cu")
		(net "P3E_CPU0_PE2_SS_RXP<4>")
	)
	(segment
		(start 399.950686 -3.253486)
		(end 399.950686 -3.478784)
		(width 0.1143)
		(layer "F.Cu")
		(net "P3E_CPU0_PE2_SS_RXP<4>")
	)
	(segment
		(start 399.950686 -3.478784)
		(end 399.671286 -3.758184)
		(width 0.1143)
		(layer "F.Cu")
		(net "P3E_CPU0_PE2_SS_RXP<4>")
	)
	(segment
		(start 302.099726 -84.631784)
		(end 302.671226 -84.631784)
		(width 0.1143)
		(layer "F.Cu")
		(net "P3E_CPU0_PE2_SS_RXP<4>")
	)
	(segment
		(start 399.873724 -3.176524)
		(end 399.950686 -3.253486)
		(width 0.1143)
		(layer "F.Cu")
		(net "P3E_CPU0_PE2_SS_RXP<4>")
	)
	(via
		(at 302.671226 -84.631784)
		(size 0.508)
		(drill 0.254)
		(layers "F.Cu" "B.Cu")
		(net "P3E_CPU0_PE2_SS_RXP<4>")
	)
	(via
		(at 399.554192 -3.176524)
		(size 0.508)
		(drill 0.254)
		(layers "F.Cu" "B.Cu")
		(net "P3E_CPU0_PE2_SS_RXP<4>")
	)
	(segment
		(start 319.458594 -63.997332)
		(end 319.45961 -63.997078)
		(width 0.1143)
		(layer "In4.Cu")
		(net "P3E_CPU0_PE2_SS_RXP<4>")
	)
	(segment
		(start 309.190136 -83.064604)
		(end 311.939432 -80.572356)
		(width 0.1143)
		(layer "In4.Cu")
		(net "P3E_CPU0_PE2_SS_RXP<4>")
	)
	(segment
		(start 383.203958 -8.747252)
		(end 383.399538 -8.874506)
		(width 0.1143)
		(layer "In4.Cu")
		(net "P3E_CPU0_PE2_SS_RXP<4>")
	)
	(segment
		(start 305.225196 -84.536788)
		(end 305.261264 -84.536788)
		(width 0.0889)
		(layer "In4.Cu")
		(net "P3E_CPU0_PE2_SS_RXP<4>")
	)
	(segment
		(start 319.45961 -63.997078)
		(end 319.461642 -63.992252)
		(width 0.1143)
		(layer "In4.Cu")
		(net "P3E_CPU0_PE2_SS_RXP<4>")
	)
	(segment
		(start 339.671914 -49.51857)
		(end 341.866474 -49.072292)
		(width 0.1143)
		(layer "In4.Cu")
		(net "P3E_CPU0_PE2_SS_RXP<4>")
	)
	(segment
		(start 389.747506 -9.106916)
		(end 397.794988 -6.355842)
		(width 0.1143)
		(layer "In4.Cu")
		(net "P3E_CPU0_PE2_SS_RXP<4>")
	)
	(segment
		(start 326.111108 -55.340758)
		(end 327.599294 -53.177186)
		(width 0.1143)
		(layer "In4.Cu")
		(net "P3E_CPU0_PE2_SS_RXP<4>")
	)
	(segment
		(start 399.890742 -4.260342)
		(end 399.890742 -3.290824)
		(width 0.1143)
		(layer "In4.Cu")
		(net "P3E_CPU0_PE2_SS_RXP<4>")
	)
	(segment
		(start 341.866474 -49.072292)
		(end 343.936066 -49.493424)
		(width 0.1143)
		(layer "In4.Cu")
		(net "P3E_CPU0_PE2_SS_RXP<4>")
	)
	(segment
		(start 398.842992 -5.308092)
		(end 399.890742 -4.260342)
		(width 0.1143)
		(layer "In4.Cu")
		(net "P3E_CPU0_PE2_SS_RXP<4>")
	)
	(segment
		(start 303.183036 -85.327236)
		(end 303.183544 -85.327744)
		(width 0.0889)
		(layer "In4.Cu")
		(net "P3E_CPU0_PE2_SS_RXP<4>")
	)
	(segment
		(start 306.14366 -83.746848)
		(end 306.56403 -83.746848)
		(width 0.0889)
		(layer "In4.Cu")
		(net "P3E_CPU0_PE2_SS_RXP<4>")
	)
	(segment
		(start 306.56403 -83.746848)
		(end 306.61483 -83.696048)
		(width 0.0889)
		(layer "In4.Cu")
		(net "P3E_CPU0_PE2_SS_RXP<4>")
	)
	(segment
		(start 313.259724 -78.963774)
		(end 319.458594 -63.997332)
		(width 0.1143)
		(layer "In4.Cu")
		(net "P3E_CPU0_PE2_SS_RXP<4>")
	)
	(segment
		(start 337.433666 -49.062894)
		(end 339.671914 -49.51857)
		(width 0.1143)
		(layer "In4.Cu")
		(net "P3E_CPU0_PE2_SS_RXP<4>")
	)
	(segment
		(start 305.593496 -84.336636)
		(end 305.648106 -84.24164)
		(width 0.0889)
		(layer "In4.Cu")
		(net "P3E_CPU0_PE2_SS_RXP<4>")
	)
	(segment
		(start 302.671226 -84.969858)
		(end 302.736504 -85.035136)
		(width 0.0889)
		(layer "In4.Cu")
		(net "P3E_CPU0_PE2_SS_RXP<4>")
	)
	(segment
		(start 304.370486 -85.031834)
		(end 304.403252 -85.031834)
		(width 0.0889)
		(layer "In4.Cu")
		(net "P3E_CPU0_PE2_SS_RXP<4>")
	)
	(segment
		(start 362.019342 -36.602162)
		(end 366.445038 -29.96057)
		(width 0.1143)
		(layer "In4.Cu")
		(net "P3E_CPU0_PE2_SS_RXP<4>")
	)
	(segment
		(start 383.862072 -8.607298)
		(end 384.197606 -8.536178)
		(width 0.1143)
		(layer "In4.Cu")
		(net "P3E_CPU0_PE2_SS_RXP<4>")
	)
	(segment
		(start 366.445038 -29.96057)
		(end 369.1763 -29.414724)
		(width 0.1143)
		(layer "In4.Cu")
		(net "P3E_CPU0_PE2_SS_RXP<4>")
	)
	(segment
		(start 306.61483 -83.696048)
		(end 306.636928 -83.696048)
		(width 0.0889)
		(layer "In4.Cu")
		(net "P3E_CPU0_PE2_SS_RXP<4>")
	)
	(segment
		(start 308.245002 -83.696048)
		(end 309.190136 -83.064604)
		(width 0.1143)
		(layer "In4.Cu")
		(net "P3E_CPU0_PE2_SS_RXP<4>")
	)
	(segment
		(start 385.387088 -8.452104)
		(end 386.024374 -8.316976)
		(width 0.1143)
		(layer "In4.Cu")
		(net "P3E_CPU0_PE2_SS_RXP<4>")
	)
	(segment
		(start 369.389406 -29.272484)
		(end 370.386102 -24.86152)
		(width 0.1143)
		(layer "In4.Cu")
		(net "P3E_CPU0_PE2_SS_RXP<4>")
	)
	(segment
		(start 305.648106 -84.24164)
		(end 306.14366 -83.746848)
		(width 0.0889)
		(layer "In4.Cu")
		(net "P3E_CPU0_PE2_SS_RXP<4>")
	)
	(segment
		(start 327.599294 -53.177186)
		(end 330.651358 -51.20005)
		(width 0.1143)
		(layer "In4.Cu")
		(net "P3E_CPU0_PE2_SS_RXP<4>")
	)
	(segment
		(start 360.737658 -42.90695)
		(end 362.019342 -36.602162)
		(width 0.1143)
		(layer "In4.Cu")
		(net "P3E_CPU0_PE2_SS_RXP<4>")
	)
	(segment
		(start 397.794988 -6.355842)
		(end 398.842738 -5.308092)
		(width 0.1143)
		(layer "In4.Cu")
		(net "P3E_CPU0_PE2_SS_RXP<4>")
	)
	(segment
		(start 357.954834 -45.735748)
		(end 357.9622 -45.730922)
		(width 0.1143)
		(layer "In4.Cu")
		(net "P3E_CPU0_PE2_SS_RXP<4>")
	)
	(segment
		(start 302.671226 -84.631784)
		(end 302.671226 -84.969858)
		(width 0.0889)
		(layer "In4.Cu")
		(net "P3E_CPU0_PE2_SS_RXP<4>")
	)
	(segment
		(start 343.936066 -49.493424)
		(end 357.954834 -45.735748)
		(width 0.1143)
		(layer "In4.Cu")
		(net "P3E_CPU0_PE2_SS_RXP<4>")
	)
	(segment
		(start 398.842738 -5.308092)
		(end 398.842992 -5.308092)
		(width 0.1143)
		(layer "In4.Cu")
		(net "P3E_CPU0_PE2_SS_RXP<4>")
	)
	(segment
		(start 311.939432 -80.572356)
		(end 313.259724 -78.963774)
		(width 0.1143)
		(layer "In4.Cu")
		(net "P3E_CPU0_PE2_SS_RXP<4>")
	)
	(segment
		(start 369.1763 -29.414724)
		(end 369.389406 -29.272484)
		(width 0.1143)
		(layer "In4.Cu")
		(net "P3E_CPU0_PE2_SS_RXP<4>")
	)
	(segment
		(start 386.024374 -8.316976)
		(end 389.747506 -9.106916)
		(width 0.1143)
		(layer "In4.Cu")
		(net "P3E_CPU0_PE2_SS_RXP<4>")
	)
	(segment
		(start 330.651358 -51.20005)
		(end 337.433666 -49.062894)
		(width 0.1143)
		(layer "In4.Cu")
		(net "P3E_CPU0_PE2_SS_RXP<4>")
	)
	(segment
		(start 383.735072 -8.803132)
		(end 383.862072 -8.607298)
		(width 0.1143)
		(layer "In4.Cu")
		(net "P3E_CPU0_PE2_SS_RXP<4>")
	)
	(segment
		(start 377.128532 -11.27506)
		(end 380.423166 -9.506712)
		(width 0.1143)
		(layer "In4.Cu")
		(net "P3E_CPU0_PE2_SS_RXP<4>")
	)
	(segment
		(start 325.139558 -55.737252)
		(end 326.111108 -55.340758)
		(width 0.1143)
		(layer "In4.Cu")
		(net "P3E_CPU0_PE2_SS_RXP<4>")
	)
	(segment
		(start 399.890742 -3.290824)
		(end 399.776442 -3.176524)
		(width 0.1143)
		(layer "In4.Cu")
		(net "P3E_CPU0_PE2_SS_RXP<4>")
	)
	(segment
		(start 384.39344 -8.663432)
		(end 384.72872 -8.592058)
		(width 0.1143)
		(layer "In4.Cu")
		(net "P3E_CPU0_PE2_SS_RXP<4>")
	)
	(segment
		(start 319.461642 -63.992252)
		(end 325.139558 -55.737252)
		(width 0.1143)
		(layer "In4.Cu")
		(net "P3E_CPU0_PE2_SS_RXP<4>")
	)
	(segment
		(start 385.191508 -8.325104)
		(end 385.387088 -8.452104)
		(width 0.1143)
		(layer "In4.Cu")
		(net "P3E_CPU0_PE2_SS_RXP<4>")
	)
	(segment
		(start 382.868424 -8.818372)
		(end 383.203958 -8.747252)
		(width 0.1143)
		(layer "In4.Cu")
		(net "P3E_CPU0_PE2_SS_RXP<4>")
	)
	(segment
		(start 384.197606 -8.536178)
		(end 384.39344 -8.663432)
		(width 0.1143)
		(layer "In4.Cu")
		(net "P3E_CPU0_PE2_SS_RXP<4>")
	)
	(segment
		(start 306.636928 -83.696048)
		(end 308.245002 -83.696048)
		(width 0.1143)
		(layer "In4.Cu")
		(net "P3E_CPU0_PE2_SS_RXP<4>")
	)
	(segment
		(start 370.386102 -24.86152)
		(end 371.7036 -24.162004)
		(width 0.1143)
		(layer "In4.Cu")
		(net "P3E_CPU0_PE2_SS_RXP<4>")
	)
	(segment
		(start 380.423166 -9.506712)
		(end 382.74117 -9.014206)
		(width 0.1143)
		(layer "In4.Cu")
		(net "P3E_CPU0_PE2_SS_RXP<4>")
	)
	(segment
		(start 383.399538 -8.874506)
		(end 383.735072 -8.803132)
		(width 0.1143)
		(layer "In4.Cu")
		(net "P3E_CPU0_PE2_SS_RXP<4>")
	)
	(segment
		(start 303.5173 -85.527388)
		(end 303.517808 -85.527388)
		(width 0.0889)
		(layer "In4.Cu")
		(net "P3E_CPU0_PE2_SS_RXP<4>")
	)
	(segment
		(start 384.855974 -8.396224)
		(end 385.191508 -8.325104)
		(width 0.1143)
		(layer "In4.Cu")
		(net "P3E_CPU0_PE2_SS_RXP<4>")
	)
	(segment
		(start 359.574846 -44.663614)
		(end 360.737658 -42.90695)
		(width 0.1143)
		(layer "In4.Cu")
		(net "P3E_CPU0_PE2_SS_RXP<4>")
	)
	(segment
		(start 399.776442 -3.176524)
		(end 399.554192 -3.176524)
		(width 0.1143)
		(layer "In4.Cu")
		(net "P3E_CPU0_PE2_SS_RXP<4>")
	)
	(segment
		(start 371.7036 -24.162004)
		(end 373.751348 -15.376398)
		(width 0.1143)
		(layer "In4.Cu")
		(net "P3E_CPU0_PE2_SS_RXP<4>")
	)
	(segment
		(start 357.9622 -45.730922)
		(end 359.574846 -44.663614)
		(width 0.1143)
		(layer "In4.Cu")
		(net "P3E_CPU0_PE2_SS_RXP<4>")
	)
	(segment
		(start 382.74117 -9.014206)
		(end 382.868424 -8.818372)
		(width 0.1143)
		(layer "In4.Cu")
		(net "P3E_CPU0_PE2_SS_RXP<4>")
	)
	(segment
		(start 384.72872 -8.592058)
		(end 384.855974 -8.396224)
		(width 0.1143)
		(layer "In4.Cu")
		(net "P3E_CPU0_PE2_SS_RXP<4>")
	)
	(segment
		(start 373.751348 -15.376398)
		(end 377.128532 -11.27506)
		(width 0.1143)
		(layer "In4.Cu")
		(net "P3E_CPU0_PE2_SS_RXP<4>")
	)
	(arc
		(start 303.517808 -85.527388)
		(mid 303.529746 -85.527566)
		(end 303.541684 -85.527388)
		(width 0.0889)
		(layer "In4.Cu")
		(net "P3E_CPU0_PE2_SS_RXP<4>")
	)
	(arc
		(start 303.183544 -85.327744)
		(mid 303.188277 -85.335801)
		(end 303.193196 -85.343746)
		(width 0.0889)
		(layer "In4.Cu")
		(net "P3E_CPU0_PE2_SS_RXP<4>")
	)
	(arc
		(start 303.193196 -85.343746)
		(mid 303.332493 -85.475739)
		(end 303.5173 -85.527388)
		(width 0.0889)
		(layer "In4.Cu")
		(net "P3E_CPU0_PE2_SS_RXP<4>")
	)
	(arc
		(start 303.876456 -85.327236)
		(mid 304.085064 -85.115304)
		(end 304.370486 -85.031834)
		(width 0.0889)
		(layer "In4.Cu")
		(net "P3E_CPU0_PE2_SS_RXP<4>")
	)
	(arc
		(start 304.734976 -84.831936)
		(mid 304.94198 -84.621072)
		(end 305.225196 -84.536788)
		(width 0.0889)
		(layer "In4.Cu")
		(net "P3E_CPU0_PE2_SS_RXP<4>")
	)
	(arc
		(start 304.403252 -85.031834)
		(mid 304.594894 -84.974668)
		(end 304.734976 -84.831936)
		(width 0.0889)
		(layer "In4.Cu")
		(net "P3E_CPU0_PE2_SS_RXP<4>")
	)
	(arc
		(start 303.541684 -85.527388)
		(mid 303.73511 -85.470861)
		(end 303.876456 -85.327236)
		(width 0.0889)
		(layer "In4.Cu")
		(net "P3E_CPU0_PE2_SS_RXP<4>")
	)
	(arc
		(start 305.261264 -84.536788)
		(mid 305.453281 -84.47968)
		(end 305.593496 -84.336636)
		(width 0.0889)
		(layer "In4.Cu")
		(net "P3E_CPU0_PE2_SS_RXP<4>")
	)
	(arc
		(start 302.736504 -85.035136)
		(mid 302.994641 -85.12789)
		(end 303.183036 -85.327236)
		(width 0.0889)
		(layer "In4.Cu")
		(net "P3E_CPU0_PE2_SS_RXP<4>")
	)
	(segment
		(start 402.071586 -4.386072)
		(end 402.071586 -3.758184)
		(width 0.1143)
		(layer "F.Cu")
		(net "P3E_CPU0_PE2_SS_RXP<3>")
	)
	(segment
		(start 402.071586 -3.758184)
		(end 402.350986 -3.478784)
		(width 0.1143)
		(layer "F.Cu")
		(net "P3E_CPU0_PE2_SS_RXP<3>")
	)
	(segment
		(start 303.529746 -86.117938)
		(end 302.958246 -86.117938)
		(width 0.1143)
		(layer "F.Cu")
		(net "P3E_CPU0_PE2_SS_RXP<3>")
	)
	(segment
		(start 402.192744 -2.88417)
		(end 401.827492 -2.88417)
		(width 0.1143)
		(layer "F.Cu")
		(net "P3E_CPU0_PE2_SS_RXP<3>")
	)
	(segment
		(start 402.350986 -3.042412)
		(end 402.192744 -2.88417)
		(width 0.1143)
		(layer "F.Cu")
		(net "P3E_CPU0_PE2_SS_RXP<3>")
	)
	(segment
		(start 402.350986 -3.478784)
		(end 402.350986 -3.042412)
		(width 0.1143)
		(layer "F.Cu")
		(net "P3E_CPU0_PE2_SS_RXP<3>")
	)
	(via
		(at 303.529746 -86.117938)
		(size 0.508)
		(drill 0.254)
		(layers "F.Cu" "B.Cu")
		(net "P3E_CPU0_PE2_SS_RXP<3>")
	)
	(via
		(at 401.827492 -2.88417)
		(size 0.508)
		(drill 0.254)
		(layers "F.Cu" "B.Cu")
		(net "P3E_CPU0_PE2_SS_RXP<3>")
	)
	(segment
		(start 328.059796 -53.644292)
		(end 330.932536 -51.783488)
		(width 0.1143)
		(layer "In4.Cu")
		(net "P3E_CPU0_PE2_SS_RXP<3>")
	)
	(segment
		(start 313.770772 -79.40294)
		(end 320.031364 -64.289432)
		(width 0.1143)
		(layer "In4.Cu")
		(net "P3E_CPU0_PE2_SS_RXP<3>")
	)
	(segment
		(start 310.432704 -82.822542)
		(end 312.514996 -80.93583)
		(width 0.1143)
		(layer "In4.Cu")
		(net "P3E_CPU0_PE2_SS_RXP<3>")
	)
	(segment
		(start 308.519576 -84.82838)
		(end 308.648862 -84.734146)
		(width 0.1143)
		(layer "In4.Cu")
		(net "P3E_CPU0_PE2_SS_RXP<3>")
	)
	(segment
		(start 306.396136 -84.932266)
		(end 306.573936 -84.932266)
		(width 0.0889)
		(layer "In4.Cu")
		(net "P3E_CPU0_PE2_SS_RXP<3>")
	)
	(segment
		(start 402.202142 -2.88417)
		(end 401.827492 -2.88417)
		(width 0.1143)
		(layer "In4.Cu")
		(net "P3E_CPU0_PE2_SS_RXP<3>")
	)
	(segment
		(start 305.500532 -85.527388)
		(end 305.994562 -85.033358)
		(width 0.0889)
		(layer "In4.Cu")
		(net "P3E_CPU0_PE2_SS_RXP<3>")
	)
	(segment
		(start 305.225196 -85.527388)
		(end 305.500532 -85.527388)
		(width 0.0889)
		(layer "In4.Cu")
		(net "P3E_CPU0_PE2_SS_RXP<3>")
	)
	(segment
		(start 380.649734 -10.148824)
		(end 385.75234 -9.064244)
		(width 0.1143)
		(layer "In4.Cu")
		(net "P3E_CPU0_PE2_SS_RXP<3>")
	)
	(segment
		(start 303.381918 -86.489794)
		(end 303.382934 -86.490302)
		(width 0.0889)
		(layer "In4.Cu")
		(net "P3E_CPU0_PE2_SS_RXP<3>")
	)
	(segment
		(start 307.748432 -85.033358)
		(end 308.323742 -85.033358)
		(width 0.0889)
		(layer "In4.Cu")
		(net "P3E_CPU0_PE2_SS_RXP<3>")
	)
	(segment
		(start 330.932536 -51.783488)
		(end 337.447636 -49.730152)
		(width 0.1143)
		(layer "In4.Cu")
		(net "P3E_CPU0_PE2_SS_RXP<3>")
	)
	(segment
		(start 360.08818 -45.09008)
		(end 361.351322 -43.181524)
		(width 0.1143)
		(layer "In4.Cu")
		(net "P3E_CPU0_PE2_SS_RXP<3>")
	)
	(segment
		(start 400.854164 -4.427474)
		(end 401.096734 -4.184904)
		(width 0.1143)
		(layer "In4.Cu")
		(net "P3E_CPU0_PE2_SS_RXP<3>")
	)
	(segment
		(start 400.378168 -4.90347)
		(end 400.611594 -4.90347)
		(width 0.1143)
		(layer "In4.Cu")
		(net "P3E_CPU0_PE2_SS_RXP<3>")
	)
	(segment
		(start 402.316442 -3.198876)
		(end 402.316442 -2.99847)
		(width 0.1143)
		(layer "In4.Cu")
		(net "P3E_CPU0_PE2_SS_RXP<3>")
	)
	(segment
		(start 307.254656 -85.033358)
		(end 307.45938 -85.033358)
		(width 0.0889)
		(layer "In4.Cu")
		(net "P3E_CPU0_PE2_SS_RXP<3>")
	)
	(segment
		(start 307.45938 -85.033358)
		(end 307.515006 -84.977732)
		(width 0.0889)
		(layer "In4.Cu")
		(net "P3E_CPU0_PE2_SS_RXP<3>")
	)
	(segment
		(start 372.29669 -24.58212)
		(end 374.371362 -15.683484)
		(width 0.1143)
		(layer "In4.Cu")
		(net "P3E_CPU0_PE2_SS_RXP<3>")
	)
	(segment
		(start 398.845532 -6.669532)
		(end 400.135852 -5.379212)
		(width 0.1143)
		(layer "In4.Cu")
		(net "P3E_CPU0_PE2_SS_RXP<3>")
	)
	(segment
		(start 308.323742 -85.033358)
		(end 308.490874 -84.911692)
		(width 0.0889)
		(layer "In4.Cu")
		(net "P3E_CPU0_PE2_SS_RXP<3>")
	)
	(segment
		(start 306.975764 -84.932266)
		(end 307.153564 -84.932266)
		(width 0.0889)
		(layer "In4.Cu")
		(net "P3E_CPU0_PE2_SS_RXP<3>")
	)
	(segment
		(start 306.675028 -85.033358)
		(end 306.874672 -85.033358)
		(width 0.0889)
		(layer "In4.Cu")
		(net "P3E_CPU0_PE2_SS_RXP<3>")
	)
	(segment
		(start 305.994562 -85.033358)
		(end 306.295044 -85.033358)
		(width 0.0889)
		(layer "In4.Cu")
		(net "P3E_CPU0_PE2_SS_RXP<3>")
	)
	(segment
		(start 309.503064 -83.752436)
		(end 310.432704 -82.822542)
		(width 0.1143)
		(layer "In4.Cu")
		(net "P3E_CPU0_PE2_SS_RXP<3>")
	)
	(segment
		(start 304.370486 -86.022434)
		(end 304.403252 -86.022434)
		(width 0.0889)
		(layer "In4.Cu")
		(net "P3E_CPU0_PE2_SS_RXP<3>")
	)
	(segment
		(start 308.648862 -84.734146)
		(end 309.273702 -84.10956)
		(width 0.1143)
		(layer "In4.Cu")
		(net "P3E_CPU0_PE2_SS_RXP<3>")
	)
	(segment
		(start 306.295044 -85.033358)
		(end 306.396136 -84.932266)
		(width 0.0889)
		(layer "In4.Cu")
		(net "P3E_CPU0_PE2_SS_RXP<3>")
	)
	(segment
		(start 303.49952 -86.51748)
		(end 303.517808 -86.517988)
		(width 0.0889)
		(layer "In4.Cu")
		(net "P3E_CPU0_PE2_SS_RXP<3>")
	)
	(segment
		(start 312.514996 -80.93583)
		(end 313.770772 -79.40294)
		(width 0.1143)
		(layer "In4.Cu")
		(net "P3E_CPU0_PE2_SS_RXP<3>")
	)
	(segment
		(start 308.501796 -84.841334)
		(end 308.519576 -84.82838)
		(width 0.0889)
		(layer "In4.Cu")
		(net "P3E_CPU0_PE2_SS_RXP<3>")
	)
	(segment
		(start 400.135852 -5.145786)
		(end 400.378168 -4.90347)
		(width 0.1143)
		(layer "In4.Cu")
		(net "P3E_CPU0_PE2_SS_RXP<3>")
	)
	(segment
		(start 358.199182 -46.340776)
		(end 360.08818 -45.09008)
		(width 0.1143)
		(layer "In4.Cu")
		(net "P3E_CPU0_PE2_SS_RXP<3>")
	)
	(segment
		(start 307.692806 -84.977732)
		(end 307.748432 -85.033358)
		(width 0.0889)
		(layer "In4.Cu")
		(net "P3E_CPU0_PE2_SS_RXP<3>")
	)
	(segment
		(start 303.43602 -86.17204)
		(end 303.23663 -86.286848)
		(width 0.0889)
		(layer "In4.Cu")
		(net "P3E_CPU0_PE2_SS_RXP<3>")
	)
	(segment
		(start 308.490874 -84.911692)
		(end 308.501796 -84.841334)
		(width 0.0889)
		(layer "In4.Cu")
		(net "P3E_CPU0_PE2_SS_RXP<3>")
	)
	(segment
		(start 362.63707 -36.840668)
		(end 366.82807 -30.543246)
		(width 0.1143)
		(layer "In4.Cu")
		(net "P3E_CPU0_PE2_SS_RXP<3>")
	)
	(segment
		(start 306.573936 -84.932266)
		(end 306.675028 -85.033358)
		(width 0.0889)
		(layer "In4.Cu")
		(net "P3E_CPU0_PE2_SS_RXP<3>")
	)
	(segment
		(start 306.874672 -85.033358)
		(end 306.975764 -84.932266)
		(width 0.0889)
		(layer "In4.Cu")
		(net "P3E_CPU0_PE2_SS_RXP<3>")
	)
	(segment
		(start 400.611594 -4.90347)
		(end 400.854164 -4.6609)
		(width 0.1143)
		(layer "In4.Cu")
		(net "P3E_CPU0_PE2_SS_RXP<3>")
	)
	(segment
		(start 309.273702 -84.10956)
		(end 309.503064 -83.752436)
		(width 0.1143)
		(layer "In4.Cu")
		(net "P3E_CPU0_PE2_SS_RXP<3>")
	)
	(segment
		(start 402.316188 -3.198876)
		(end 402.316442 -3.198876)
		(width 0.1143)
		(layer "In4.Cu")
		(net "P3E_CPU0_PE2_SS_RXP<3>")
	)
	(segment
		(start 361.351322 -43.181524)
		(end 362.63707 -36.840668)
		(width 0.1143)
		(layer "In4.Cu")
		(net "P3E_CPU0_PE2_SS_RXP<3>")
	)
	(segment
		(start 341.943182 -49.74336)
		(end 343.966546 -50.155348)
		(width 0.1143)
		(layer "In4.Cu")
		(net "P3E_CPU0_PE2_SS_RXP<3>")
	)
	(segment
		(start 343.966546 -50.155348)
		(end 358.199182 -46.340776)
		(width 0.1143)
		(layer "In4.Cu")
		(net "P3E_CPU0_PE2_SS_RXP<3>")
	)
	(segment
		(start 374.371362 -15.683484)
		(end 377.563888 -11.805158)
		(width 0.1143)
		(layer "In4.Cu")
		(net "P3E_CPU0_PE2_SS_RXP<3>")
	)
	(segment
		(start 370.975128 -25.29459)
		(end 372.29669 -24.58212)
		(width 0.1143)
		(layer "In4.Cu")
		(net "P3E_CPU0_PE2_SS_RXP<3>")
	)
	(segment
		(start 401.096734 -4.184904)
		(end 401.33016 -4.184904)
		(width 0.1143)
		(layer "In4.Cu")
		(net "P3E_CPU0_PE2_SS_RXP<3>")
	)
	(segment
		(start 339.727032 -50.19421)
		(end 341.943182 -49.74336)
		(width 0.1143)
		(layer "In4.Cu")
		(net "P3E_CPU0_PE2_SS_RXP<3>")
	)
	(segment
		(start 400.135852 -5.379212)
		(end 400.135852 -5.145786)
		(width 0.1143)
		(layer "In4.Cu")
		(net "P3E_CPU0_PE2_SS_RXP<3>")
	)
	(segment
		(start 400.854164 -4.6609)
		(end 400.854164 -4.427474)
		(width 0.1143)
		(layer "In4.Cu")
		(net "P3E_CPU0_PE2_SS_RXP<3>")
	)
	(segment
		(start 303.382934 -86.490302)
		(end 303.398936 -86.496652)
		(width 0.0889)
		(layer "In4.Cu")
		(net "P3E_CPU0_PE2_SS_RXP<3>")
	)
	(segment
		(start 366.82807 -30.543246)
		(end 369.522502 -29.995876)
		(width 0.1143)
		(layer "In4.Cu")
		(net "P3E_CPU0_PE2_SS_RXP<3>")
	)
	(segment
		(start 401.33016 -4.184904)
		(end 402.316188 -3.198876)
		(width 0.1143)
		(layer "In4.Cu")
		(net "P3E_CPU0_PE2_SS_RXP<3>")
	)
	(segment
		(start 303.23663 -86.286848)
		(end 303.215548 -86.365588)
		(width 0.0889)
		(layer "In4.Cu")
		(net "P3E_CPU0_PE2_SS_RXP<3>")
	)
	(segment
		(start 303.529746 -86.117938)
		(end 303.43602 -86.17204)
		(width 0.0889)
		(layer "In4.Cu")
		(net "P3E_CPU0_PE2_SS_RXP<3>")
	)
	(segment
		(start 369.522502 -29.995876)
		(end 370.002308 -29.666438)
		(width 0.1143)
		(layer "In4.Cu")
		(net "P3E_CPU0_PE2_SS_RXP<3>")
	)
	(segment
		(start 370.002308 -29.666438)
		(end 370.975128 -25.29459)
		(width 0.1143)
		(layer "In4.Cu")
		(net "P3E_CPU0_PE2_SS_RXP<3>")
	)
	(segment
		(start 325.559674 -56.251856)
		(end 326.542654 -55.85079)
		(width 0.1143)
		(layer "In4.Cu")
		(net "P3E_CPU0_PE2_SS_RXP<3>")
	)
	(segment
		(start 307.515006 -84.977732)
		(end 307.692806 -84.977732)
		(width 0.0889)
		(layer "In4.Cu")
		(net "P3E_CPU0_PE2_SS_RXP<3>")
	)
	(segment
		(start 385.75234 -9.064244)
		(end 389.506714 -9.862312)
		(width 0.1143)
		(layer "In4.Cu")
		(net "P3E_CPU0_PE2_SS_RXP<3>")
	)
	(segment
		(start 326.542654 -55.85079)
		(end 328.059796 -53.644292)
		(width 0.1143)
		(layer "In4.Cu")
		(net "P3E_CPU0_PE2_SS_RXP<3>")
	)
	(segment
		(start 389.506714 -9.862312)
		(end 398.845532 -6.669532)
		(width 0.1143)
		(layer "In4.Cu")
		(net "P3E_CPU0_PE2_SS_RXP<3>")
	)
	(segment
		(start 307.153564 -84.932266)
		(end 307.254656 -85.033358)
		(width 0.0889)
		(layer "In4.Cu")
		(net "P3E_CPU0_PE2_SS_RXP<3>")
	)
	(segment
		(start 402.316442 -2.99847)
		(end 402.202142 -2.88417)
		(width 0.1143)
		(layer "In4.Cu")
		(net "P3E_CPU0_PE2_SS_RXP<3>")
	)
	(segment
		(start 377.563888 -11.805158)
		(end 380.649734 -10.148824)
		(width 0.1143)
		(layer "In4.Cu")
		(net "P3E_CPU0_PE2_SS_RXP<3>")
	)
	(segment
		(start 320.031364 -64.289432)
		(end 325.559674 -56.251856)
		(width 0.1143)
		(layer "In4.Cu")
		(net "P3E_CPU0_PE2_SS_RXP<3>")
	)
	(segment
		(start 337.447636 -49.730152)
		(end 339.727032 -50.19421)
		(width 0.1143)
		(layer "In4.Cu")
		(net "P3E_CPU0_PE2_SS_RXP<3>")
	)
	(arc
		(start 303.876456 -86.317836)
		(mid 304.085064 -86.105904)
		(end 304.370486 -86.022434)
		(width 0.0889)
		(layer "In4.Cu")
		(net "P3E_CPU0_PE2_SS_RXP<3>")
	)
	(arc
		(start 303.541938 -86.517988)
		(mid 303.73519 -86.46138)
		(end 303.876456 -86.317836)
		(width 0.0889)
		(layer "In4.Cu")
		(net "P3E_CPU0_PE2_SS_RXP<3>")
	)
	(arc
		(start 304.403252 -86.022434)
		(mid 304.594894 -85.965268)
		(end 304.734976 -85.822536)
		(width 0.0889)
		(layer "In4.Cu")
		(net "P3E_CPU0_PE2_SS_RXP<3>")
	)
	(arc
		(start 303.517808 -86.517988)
		(mid 303.529873 -86.518174)
		(end 303.541938 -86.517988)
		(width 0.0889)
		(layer "In4.Cu")
		(net "P3E_CPU0_PE2_SS_RXP<3>")
	)
	(arc
		(start 304.734976 -85.822536)
		(mid 304.94198 -85.611672)
		(end 305.225196 -85.527388)
		(width 0.0889)
		(layer "In4.Cu")
		(net "P3E_CPU0_PE2_SS_RXP<3>")
	)
	(arc
		(start 303.215548 -86.365588)
		(mid 303.290537 -86.438667)
		(end 303.381918 -86.489794)
		(width 0.0889)
		(layer "In4.Cu")
		(net "P3E_CPU0_PE2_SS_RXP<3>")
	)
	(arc
		(start 303.398936 -86.496652)
		(mid 303.448317 -86.511472)
		(end 303.49952 -86.51748)
		(width 0.0889)
		(layer "In4.Cu")
		(net "P3E_CPU0_PE2_SS_RXP<3>")
	)
	(segment
		(start 404.329392 -2.897124)
		(end 404.5966 -2.897124)
		(width 0.1143)
		(layer "F.Cu")
		(net "P3E_CPU0_PE2_SS_RXP<2>")
	)
	(segment
		(start 301.241206 -87.108538)
		(end 301.812706 -87.108538)
		(width 0.1143)
		(layer "F.Cu")
		(net "P3E_CPU0_PE2_SS_RXP<2>")
	)
	(segment
		(start 404.725886 -3.02641)
		(end 404.725886 -3.504184)
		(width 0.1143)
		(layer "F.Cu")
		(net "P3E_CPU0_PE2_SS_RXP<2>")
	)
	(segment
		(start 404.725886 -3.504184)
		(end 404.471886 -3.758184)
		(width 0.1143)
		(layer "F.Cu")
		(net "P3E_CPU0_PE2_SS_RXP<2>")
	)
	(segment
		(start 404.471886 -3.758184)
		(end 404.471886 -4.386072)
		(width 0.1143)
		(layer "F.Cu")
		(net "P3E_CPU0_PE2_SS_RXP<2>")
	)
	(segment
		(start 404.5966 -2.897124)
		(end 404.725886 -3.02641)
		(width 0.1143)
		(layer "F.Cu")
		(net "P3E_CPU0_PE2_SS_RXP<2>")
	)
	(via
		(at 404.329392 -2.897124)
		(size 0.508)
		(drill 0.254)
		(layers "F.Cu" "B.Cu")
		(net "P3E_CPU0_PE2_SS_RXP<2>")
	)
	(via
		(at 301.812706 -87.108538)
		(size 0.508)
		(drill 0.254)
		(layers "F.Cu" "B.Cu")
		(net "P3E_CPU0_PE2_SS_RXP<2>")
	)
	(segment
		(start 339.796882 -50.86731)
		(end 341.999062 -50.419)
		(width 0.1143)
		(layer "In4.Cu")
		(net "P3E_CPU0_PE2_SS_RXP<2>")
	)
	(segment
		(start 391.004298 -10.986262)
		(end 394.735558 -10.239756)
		(width 0.1143)
		(layer "In4.Cu")
		(net "P3E_CPU0_PE2_SS_RXP<2>")
	)
	(segment
		(start 385.308856 -9.847326)
		(end 386.664708 -10.118344)
		(width 0.1143)
		(layer "In4.Cu")
		(net "P3E_CPU0_PE2_SS_RXP<2>")
	)
	(segment
		(start 309.338726 -85.123528)
		(end 309.804816 -84.407756)
		(width 0.1143)
		(layer "In4.Cu")
		(net "P3E_CPU0_PE2_SS_RXP<2>")
	)
	(segment
		(start 377.99899 -12.335256)
		(end 380.882398 -10.787634)
		(width 0.1143)
		(layer "In4.Cu")
		(net "P3E_CPU0_PE2_SS_RXP<2>")
	)
	(segment
		(start 388.191248 -10.25525)
		(end 388.320788 -10.44956)
		(width 0.1143)
		(layer "In4.Cu")
		(net "P3E_CPU0_PE2_SS_RXP<2>")
	)
	(segment
		(start 358.560116 -46.905418)
		(end 360.56951 -45.575728)
		(width 0.1143)
		(layer "In4.Cu")
		(net "P3E_CPU0_PE2_SS_RXP<2>")
	)
	(segment
		(start 303.5173 -87.508588)
		(end 303.517808 -87.508588)
		(width 0.0889)
		(layer "In4.Cu")
		(net "P3E_CPU0_PE2_SS_RXP<2>")
	)
	(segment
		(start 308.863492 -85.528912)
		(end 309.014876 -85.414358)
		(width 0.0889)
		(layer "In4.Cu")
		(net "P3E_CPU0_PE2_SS_RXP<2>")
	)
	(segment
		(start 387.3246 -10.250424)
		(end 387.660896 -10.317734)
		(width 0.1143)
		(layer "In4.Cu")
		(net "P3E_CPU0_PE2_SS_RXP<2>")
	)
	(segment
		(start 394.735558 -10.239756)
		(end 395.1986 -9.9314)
		(width 0.1143)
		(layer "In4.Cu")
		(net "P3E_CPU0_PE2_SS_RXP<2>")
	)
	(segment
		(start 368.8207 -31.342076)
		(end 370.586508 -30.12059)
		(width 0.1143)
		(layer "In4.Cu")
		(net "P3E_CPU0_PE2_SS_RXP<2>")
	)
	(segment
		(start 303.183036 -87.308436)
		(end 303.183544 -87.308944)
		(width 0.0889)
		(layer "In4.Cu")
		(net "P3E_CPU0_PE2_SS_RXP<2>")
	)
	(segment
		(start 309.804816 -84.407756)
		(end 311.199276 -83.013296)
		(width 0.1143)
		(layer "In4.Cu")
		(net "P3E_CPU0_PE2_SS_RXP<2>")
	)
	(segment
		(start 389.163814 -10.618216)
		(end 391.004298 -10.986262)
		(width 0.1143)
		(layer "In4.Cu")
		(net "P3E_CPU0_PE2_SS_RXP<2>")
	)
	(segment
		(start 387.660896 -10.317734)
		(end 387.855206 -10.188194)
		(width 0.1143)
		(layer "In4.Cu")
		(net "P3E_CPU0_PE2_SS_RXP<2>")
	)
	(segment
		(start 371.549422 -25.731724)
		(end 372.890034 -25.002998)
		(width 0.1143)
		(layer "In4.Cu")
		(net "P3E_CPU0_PE2_SS_RXP<2>")
	)
	(segment
		(start 302.063912 -87.253318)
		(end 302.19523 -87.253318)
		(width 0.0889)
		(layer "In4.Cu")
		(net "P3E_CPU0_PE2_SS_RXP<2>")
	)
	(segment
		(start 388.320788 -10.44956)
		(end 389.164068 -10.618216)
		(width 0.1143)
		(layer "In4.Cu")
		(net "P3E_CPU0_PE2_SS_RXP<2>")
	)
	(segment
		(start 395.635226 -9.276334)
		(end 397.205454 -8.229346)
		(width 0.1143)
		(layer "In4.Cu")
		(net "P3E_CPU0_PE2_SS_RXP<2>")
	)
	(segment
		(start 319.50279 -67.244214)
		(end 328.553826 -54.085744)
		(width 0.1143)
		(layer "In4.Cu")
		(net "P3E_CPU0_PE2_SS_RXP<2>")
	)
	(segment
		(start 404.564342 -2.897124)
		(end 404.329392 -2.897124)
		(width 0.1143)
		(layer "In4.Cu")
		(net "P3E_CPU0_PE2_SS_RXP<2>")
	)
	(segment
		(start 404.678642 -3.348736)
		(end 404.678642 -3.011424)
		(width 0.1143)
		(layer "In4.Cu")
		(net "P3E_CPU0_PE2_SS_RXP<2>")
	)
	(segment
		(start 365.993934 -33.549844)
		(end 368.447066 -31.91637)
		(width 0.1143)
		(layer "In4.Cu")
		(net "P3E_CPU0_PE2_SS_RXP<2>")
	)
	(segment
		(start 304.370486 -87.013034)
		(end 304.403252 -87.013034)
		(width 0.0889)
		(layer "In4.Cu")
		(net "P3E_CPU0_PE2_SS_RXP<2>")
	)
	(segment
		(start 360.56951 -45.575728)
		(end 361.944666 -43.4975)
		(width 0.1143)
		(layer "In4.Cu")
		(net "P3E_CPU0_PE2_SS_RXP<2>")
	)
	(segment
		(start 397.949166 -8.080502)
		(end 399.32356 -7.164578)
		(width 0.1143)
		(layer "In4.Cu")
		(net "P3E_CPU0_PE2_SS_RXP<2>")
	)
	(segment
		(start 370.586508 -30.12059)
		(end 371.549422 -25.731724)
		(width 0.1143)
		(layer "In4.Cu")
		(net "P3E_CPU0_PE2_SS_RXP<2>")
	)
	(segment
		(start 387.855206 -10.188194)
		(end 388.191248 -10.25525)
		(width 0.1143)
		(layer "In4.Cu")
		(net "P3E_CPU0_PE2_SS_RXP<2>")
	)
	(segment
		(start 301.812706 -87.108538)
		(end 302.063912 -87.253318)
		(width 0.0889)
		(layer "In4.Cu")
		(net "P3E_CPU0_PE2_SS_RXP<2>")
	)
	(segment
		(start 341.999062 -50.419)
		(end 343.963498 -50.818542)
		(width 0.1143)
		(layer "In4.Cu")
		(net "P3E_CPU0_PE2_SS_RXP<2>")
	)
	(segment
		(start 404.453344 -3.574034)
		(end 404.678642 -3.348736)
		(width 0.1143)
		(layer "In4.Cu")
		(net "P3E_CPU0_PE2_SS_RXP<2>")
	)
	(segment
		(start 309.02148 -85.364066)
		(end 309.039006 -85.350858)
		(width 0.0889)
		(layer "In4.Cu")
		(net "P3E_CPU0_PE2_SS_RXP<2>")
	)
	(segment
		(start 380.882398 -10.787634)
		(end 385.308856 -9.847326)
		(width 0.1143)
		(layer "In4.Cu")
		(net "P3E_CPU0_PE2_SS_RXP<2>")
	)
	(segment
		(start 363.077252 -37.933884)
		(end 365.993934 -33.549844)
		(width 0.1143)
		(layer "In4.Cu")
		(net "P3E_CPU0_PE2_SS_RXP<2>")
	)
	(segment
		(start 309.039006 -85.350858)
		(end 309.338726 -85.123528)
		(width 0.1143)
		(layer "In4.Cu")
		(net "P3E_CPU0_PE2_SS_RXP<2>")
	)
	(segment
		(start 404.678642 -3.011424)
		(end 404.564342 -2.897124)
		(width 0.1143)
		(layer "In4.Cu")
		(net "P3E_CPU0_PE2_SS_RXP<2>")
	)
	(segment
		(start 331.200506 -52.37099)
		(end 337.476084 -50.394362)
		(width 0.1143)
		(layer "In4.Cu")
		(net "P3E_CPU0_PE2_SS_RXP<2>")
	)
	(segment
		(start 386.664708 -10.118344)
		(end 386.859018 -9.989058)
		(width 0.1143)
		(layer "In4.Cu")
		(net "P3E_CPU0_PE2_SS_RXP<2>")
	)
	(segment
		(start 337.476084 -50.394362)
		(end 339.796882 -50.86731)
		(width 0.1143)
		(layer "In4.Cu")
		(net "P3E_CPU0_PE2_SS_RXP<2>")
	)
	(segment
		(start 314.285376 -79.837788)
		(end 319.50279 -67.244214)
		(width 0.1143)
		(layer "In4.Cu")
		(net "P3E_CPU0_PE2_SS_RXP<2>")
	)
	(segment
		(start 305.593496 -86.317582)
		(end 305.629564 -86.255606)
		(width 0.0889)
		(layer "In4.Cu")
		(net "P3E_CPU0_PE2_SS_RXP<2>")
	)
	(segment
		(start 387.19506 -10.056114)
		(end 387.3246 -10.250424)
		(width 0.1143)
		(layer "In4.Cu")
		(net "P3E_CPU0_PE2_SS_RXP<2>")
	)
	(segment
		(start 311.199276 -83.013296)
		(end 313.081416 -81.308194)
		(width 0.1143)
		(layer "In4.Cu")
		(net "P3E_CPU0_PE2_SS_RXP<2>")
	)
	(segment
		(start 313.081416 -81.308194)
		(end 314.285376 -79.837788)
		(width 0.1143)
		(layer "In4.Cu")
		(net "P3E_CPU0_PE2_SS_RXP<2>")
	)
	(segment
		(start 306.356258 -85.528912)
		(end 308.863492 -85.528912)
		(width 0.0889)
		(layer "In4.Cu")
		(net "P3E_CPU0_PE2_SS_RXP<2>")
	)
	(segment
		(start 386.859018 -9.989058)
		(end 387.19506 -10.056114)
		(width 0.1143)
		(layer "In4.Cu")
		(net "P3E_CPU0_PE2_SS_RXP<2>")
	)
	(segment
		(start 305.629564 -86.255606)
		(end 306.356258 -85.528912)
		(width 0.0889)
		(layer "In4.Cu")
		(net "P3E_CPU0_PE2_SS_RXP<2>")
	)
	(segment
		(start 397.205454 -8.229346)
		(end 397.205454 -8.229092)
		(width 0.1143)
		(layer "In4.Cu")
		(net "P3E_CPU0_PE2_SS_RXP<2>")
	)
	(segment
		(start 309.014876 -85.414358)
		(end 309.02148 -85.364066)
		(width 0.0889)
		(layer "In4.Cu")
		(net "P3E_CPU0_PE2_SS_RXP<2>")
	)
	(segment
		(start 305.593496 -86.317836)
		(end 305.593496 -86.317582)
		(width 0.0889)
		(layer "In4.Cu")
		(net "P3E_CPU0_PE2_SS_RXP<2>")
	)
	(segment
		(start 302.653446 -87.013034)
		(end 302.689006 -87.013034)
		(width 0.0889)
		(layer "In4.Cu")
		(net "P3E_CPU0_PE2_SS_RXP<2>")
	)
	(segment
		(start 328.553826 -54.085744)
		(end 331.200506 -52.37099)
		(width 0.1143)
		(layer "In4.Cu")
		(net "P3E_CPU0_PE2_SS_RXP<2>")
	)
	(segment
		(start 389.164068 -10.618216)
		(end 389.163814 -10.618216)
		(width 0.1143)
		(layer "In4.Cu")
		(net "P3E_CPU0_PE2_SS_RXP<2>")
	)
	(segment
		(start 395.1986 -9.9314)
		(end 395.635226 -9.276334)
		(width 0.1143)
		(layer "In4.Cu")
		(net "P3E_CPU0_PE2_SS_RXP<2>")
	)
	(segment
		(start 399.32356 -7.164578)
		(end 402.913088 -3.574034)
		(width 0.1143)
		(layer "In4.Cu")
		(net "P3E_CPU0_PE2_SS_RXP<2>")
	)
	(segment
		(start 305.225196 -86.517988)
		(end 305.261264 -86.517988)
		(width 0.0889)
		(layer "In4.Cu")
		(net "P3E_CPU0_PE2_SS_RXP<2>")
	)
	(segment
		(start 368.447066 -31.91637)
		(end 368.8207 -31.342076)
		(width 0.1143)
		(layer "In4.Cu")
		(net "P3E_CPU0_PE2_SS_RXP<2>")
	)
	(segment
		(start 397.205454 -8.229092)
		(end 397.949166 -8.080502)
		(width 0.1143)
		(layer "In4.Cu")
		(net "P3E_CPU0_PE2_SS_RXP<2>")
	)
	(segment
		(start 374.992138 -15.987522)
		(end 377.99899 -12.335256)
		(width 0.1143)
		(layer "In4.Cu")
		(net "P3E_CPU0_PE2_SS_RXP<2>")
	)
	(segment
		(start 402.913088 -3.574034)
		(end 404.453344 -3.574034)
		(width 0.1143)
		(layer "In4.Cu")
		(net "P3E_CPU0_PE2_SS_RXP<2>")
	)
	(segment
		(start 343.963498 -50.818542)
		(end 358.560116 -46.905418)
		(width 0.1143)
		(layer "In4.Cu")
		(net "P3E_CPU0_PE2_SS_RXP<2>")
	)
	(segment
		(start 361.944666 -43.4975)
		(end 363.077252 -37.933884)
		(width 0.1143)
		(layer "In4.Cu")
		(net "P3E_CPU0_PE2_SS_RXP<2>")
	)
	(segment
		(start 372.890034 -25.002998)
		(end 374.992138 -15.987522)
		(width 0.1143)
		(layer "In4.Cu")
		(net "P3E_CPU0_PE2_SS_RXP<2>")
	)
	(arc
		(start 303.183544 -87.308944)
		(mid 303.188277 -87.317001)
		(end 303.193196 -87.324946)
		(width 0.0889)
		(layer "In4.Cu")
		(net "P3E_CPU0_PE2_SS_RXP<2>")
	)
	(arc
		(start 303.541684 -87.508588)
		(mid 303.73511 -87.452061)
		(end 303.876456 -87.308436)
		(width 0.0889)
		(layer "In4.Cu")
		(net "P3E_CPU0_PE2_SS_RXP<2>")
	)
	(arc
		(start 303.193196 -87.324946)
		(mid 303.332493 -87.456939)
		(end 303.5173 -87.508588)
		(width 0.0889)
		(layer "In4.Cu")
		(net "P3E_CPU0_PE2_SS_RXP<2>")
	)
	(arc
		(start 302.689006 -87.013034)
		(mid 302.97443 -87.096501)
		(end 303.183036 -87.308436)
		(width 0.0889)
		(layer "In4.Cu")
		(net "P3E_CPU0_PE2_SS_RXP<2>")
	)
	(arc
		(start 304.734976 -86.813136)
		(mid 304.94198 -86.602272)
		(end 305.225196 -86.517988)
		(width 0.0889)
		(layer "In4.Cu")
		(net "P3E_CPU0_PE2_SS_RXP<2>")
	)
	(arc
		(start 303.517808 -87.508588)
		(mid 303.529746 -87.508766)
		(end 303.541684 -87.508588)
		(width 0.0889)
		(layer "In4.Cu")
		(net "P3E_CPU0_PE2_SS_RXP<2>")
	)
	(arc
		(start 302.19523 -87.253318)
		(mid 302.39664 -87.080365)
		(end 302.653446 -87.013034)
		(width 0.0889)
		(layer "In4.Cu")
		(net "P3E_CPU0_PE2_SS_RXP<2>")
	)
	(arc
		(start 303.876456 -87.308436)
		(mid 304.085064 -87.096504)
		(end 304.370486 -87.013034)
		(width 0.0889)
		(layer "In4.Cu")
		(net "P3E_CPU0_PE2_SS_RXP<2>")
	)
	(arc
		(start 305.261264 -86.517988)
		(mid 305.453281 -86.46088)
		(end 305.593496 -86.317836)
		(width 0.0889)
		(layer "In4.Cu")
		(net "P3E_CPU0_PE2_SS_RXP<2>")
	)
	(arc
		(start 304.403252 -87.013034)
		(mid 304.594894 -86.955868)
		(end 304.734976 -86.813136)
		(width 0.0889)
		(layer "In4.Cu")
		(net "P3E_CPU0_PE2_SS_RXP<2>")
	)
	(segment
		(start 407.028142 -2.88417)
		(end 406.628092 -2.88417)
		(width 0.1143)
		(layer "F.Cu")
		(net "P3E_CPU0_PE2_SS_RXP<1>")
	)
	(segment
		(start 407.142442 -2.99847)
		(end 407.028142 -2.88417)
		(width 0.1143)
		(layer "F.Cu")
		(net "P3E_CPU0_PE2_SS_RXP<1>")
	)
	(segment
		(start 300.382686 -86.612984)
		(end 300.954186 -86.612984)
		(width 0.1143)
		(layer "F.Cu")
		(net "P3E_CPU0_PE2_SS_RXP<1>")
	)
	(segment
		(start 406.872186 -4.386072)
		(end 406.872186 -3.758184)
		(width 0.1143)
		(layer "F.Cu")
		(net "P3E_CPU0_PE2_SS_RXP<1>")
	)
	(segment
		(start 407.142442 -3.487928)
		(end 407.142442 -2.99847)
		(width 0.1143)
		(layer "F.Cu")
		(net "P3E_CPU0_PE2_SS_RXP<1>")
	)
	(segment
		(start 406.872186 -3.758184)
		(end 407.142442 -3.487928)
		(width 0.1143)
		(layer "F.Cu")
		(net "P3E_CPU0_PE2_SS_RXP<1>")
	)
	(via
		(at 406.628092 -2.88417)
		(size 0.508)
		(drill 0.254)
		(layers "F.Cu" "B.Cu")
		(net "P3E_CPU0_PE2_SS_RXP<1>")
	)
	(via
		(at 300.954186 -86.612984)
		(size 0.508)
		(drill 0.254)
		(layers "F.Cu" "B.Cu")
		(net "P3E_CPU0_PE2_SS_RXP<1>")
	)
	(segment
		(start 307.29936 -86.36)
		(end 307.7972 -86.36)
		(width 0.0889)
		(layer "In4.Cu")
		(net "P3E_CPU0_PE2_SS_RXP<1>")
	)
	(segment
		(start 358.897428 -47.481744)
		(end 361.011978 -46.082712)
		(width 0.1143)
		(layer "In4.Cu")
		(net "P3E_CPU0_PE2_SS_RXP<1>")
	)
	(segment
		(start 390.267444 -11.80846)
		(end 395.78153 -10.732008)
		(width 0.1143)
		(layer "In4.Cu")
		(net "P3E_CPU0_PE2_SS_RXP<1>")
	)
	(segment
		(start 362.618782 -43.654472)
		(end 363.730794 -38.098222)
		(width 0.1143)
		(layer "In4.Cu")
		(net "P3E_CPU0_PE2_SS_RXP<1>")
	)
	(segment
		(start 304.370486 -88.003634)
		(end 304.403252 -88.003634)
		(width 0.0889)
		(layer "In4.Cu")
		(net "P3E_CPU0_PE2_SS_RXP<1>")
	)
	(segment
		(start 314.846208 -80.188308)
		(end 320.111882 -67.479926)
		(width 0.1143)
		(layer "In4.Cu")
		(net "P3E_CPU0_PE2_SS_RXP<1>")
	)
	(segment
		(start 301.80153 -87.508588)
		(end 301.834296 -87.508588)
		(width 0.0889)
		(layer "In4.Cu")
		(net "P3E_CPU0_PE2_SS_RXP<1>")
	)
	(segment
		(start 397.558768 -10.017506)
		(end 397.764 -9.8806)
		(width 0.1143)
		(layer "In4.Cu")
		(net "P3E_CPU0_PE2_SS_RXP<1>")
	)
	(segment
		(start 307.848 -86.3092)
		(end 307.870098 -86.3092)
		(width 0.0889)
		(layer "In4.Cu")
		(net "P3E_CPU0_PE2_SS_RXP<1>")
	)
	(segment
		(start 396.778734 -10.537444)
		(end 397.558768 -10.017506)
		(width 0.1143)
		(layer "In4.Cu")
		(net "P3E_CPU0_PE2_SS_RXP<1>")
	)
	(segment
		(start 386.825998 -11.08964)
		(end 387.161532 -11.159744)
		(width 0.1143)
		(layer "In4.Cu")
		(net "P3E_CPU0_PE2_SS_RXP<1>")
	)
	(segment
		(start 300.954186 -86.612984)
		(end 300.954186 -86.951058)
		(width 0.0889)
		(layer "In4.Cu")
		(net "P3E_CPU0_PE2_SS_RXP<1>")
	)
	(segment
		(start 386.698236 -10.89406)
		(end 386.825998 -11.08964)
		(width 0.1143)
		(layer "In4.Cu")
		(net "P3E_CPU0_PE2_SS_RXP<1>")
	)
	(segment
		(start 310.375554 -84.717382)
		(end 310.376062 -84.716874)
		(width 0.1143)
		(layer "In4.Cu")
		(net "P3E_CPU0_PE2_SS_RXP<1>")
	)
	(segment
		(start 309.7022 -85.708236)
		(end 310.375554 -84.717382)
		(width 0.1143)
		(layer "In4.Cu")
		(net "P3E_CPU0_PE2_SS_RXP<1>")
	)
	(segment
		(start 385.368038 -10.616184)
		(end 385.703572 -10.686288)
		(width 0.1143)
		(layer "In4.Cu")
		(net "P3E_CPU0_PE2_SS_RXP<1>")
	)
	(segment
		(start 396.442184 -10.60323)
		(end 396.778734 -10.537444)
		(width 0.1143)
		(layer "In4.Cu")
		(net "P3E_CPU0_PE2_SS_RXP<1>")
	)
	(segment
		(start 395.78153 -10.732008)
		(end 395.912086 -10.53846)
		(width 0.1143)
		(layer "In4.Cu")
		(net "P3E_CPU0_PE2_SS_RXP<1>")
	)
	(segment
		(start 398.4752 -8.8138)
		(end 398.523714 -8.781288)
		(width 0.1143)
		(layer "In4.Cu")
		(net "P3E_CPU0_PE2_SS_RXP<1>")
	)
	(segment
		(start 369.28044 -31.89097)
		(end 371.170454 -30.582362)
		(width 0.1143)
		(layer "In4.Cu")
		(net "P3E_CPU0_PE2_SS_RXP<1>")
	)
	(segment
		(start 303.5173 -88.499188)
		(end 303.517808 -88.499188)
		(width 0.0889)
		(layer "In4.Cu")
		(net "P3E_CPU0_PE2_SS_RXP<1>")
	)
	(segment
		(start 386.362448 -10.823956)
		(end 386.698236 -10.89406)
		(width 0.1143)
		(layer "In4.Cu")
		(net "P3E_CPU0_PE2_SS_RXP<1>")
	)
	(segment
		(start 401.04695 -7.099554)
		(end 402.527516 -4.969256)
		(width 0.1143)
		(layer "In4.Cu")
		(net "P3E_CPU0_PE2_SS_RXP<1>")
	)
	(segment
		(start 406.977342 -2.88417)
		(end 406.628092 -2.88417)
		(width 0.1143)
		(layer "In4.Cu")
		(net "P3E_CPU0_PE2_SS_RXP<1>")
	)
	(segment
		(start 300.954186 -86.951058)
		(end 301.019464 -87.016336)
		(width 0.0889)
		(layer "In4.Cu")
		(net "P3E_CPU0_PE2_SS_RXP<1>")
	)
	(segment
		(start 307.870098 -86.3092)
		(end 308.880002 -86.3092)
		(width 0.1143)
		(layer "In4.Cu")
		(net "P3E_CPU0_PE2_SS_RXP<1>")
	)
	(segment
		(start 386.167122 -10.951972)
		(end 386.362448 -10.823956)
		(width 0.1143)
		(layer "In4.Cu")
		(net "P3E_CPU0_PE2_SS_RXP<1>")
	)
	(segment
		(start 306.150772 -87.508588)
		(end 307.29936 -86.36)
		(width 0.0889)
		(layer "In4.Cu")
		(net "P3E_CPU0_PE2_SS_RXP<1>")
	)
	(segment
		(start 363.730794 -38.098222)
		(end 366.437418 -34.030158)
		(width 0.1143)
		(layer "In4.Cu")
		(net "P3E_CPU0_PE2_SS_RXP<1>")
	)
	(segment
		(start 337.50885 -51.074574)
		(end 339.829648 -51.547014)
		(width 0.1143)
		(layer "In4.Cu")
		(net "P3E_CPU0_PE2_SS_RXP<1>")
	)
	(segment
		(start 378.435362 -12.864846)
		(end 381.119126 -11.424412)
		(width 0.1143)
		(layer "In4.Cu")
		(net "P3E_CPU0_PE2_SS_RXP<1>")
	)
	(segment
		(start 307.7972 -86.36)
		(end 307.848 -86.3092)
		(width 0.0889)
		(layer "In4.Cu")
		(net "P3E_CPU0_PE2_SS_RXP<1>")
	)
	(segment
		(start 369.244626 -31.94431)
		(end 369.28044 -31.89097)
		(width 0.1143)
		(layer "In4.Cu")
		(net "P3E_CPU0_PE2_SS_RXP<1>")
	)
	(segment
		(start 313.320684 -82.047588)
		(end 314.846462 -80.188562)
		(width 0.1143)
		(layer "In4.Cu")
		(net "P3E_CPU0_PE2_SS_RXP<1>")
	)
	(segment
		(start 366.437418 -34.030158)
		(end 368.982752 -32.333184)
		(width 0.1143)
		(layer "In4.Cu")
		(net "P3E_CPU0_PE2_SS_RXP<1>")
	)
	(segment
		(start 396.248636 -10.472674)
		(end 396.442184 -10.60323)
		(width 0.1143)
		(layer "In4.Cu")
		(net "P3E_CPU0_PE2_SS_RXP<1>")
	)
	(segment
		(start 387.161532 -11.159744)
		(end 387.357112 -11.031728)
		(width 0.1143)
		(layer "In4.Cu")
		(net "P3E_CPU0_PE2_SS_RXP<1>")
	)
	(segment
		(start 328.950574 -54.63032)
		(end 331.46492 -52.97678)
		(width 0.1143)
		(layer "In4.Cu")
		(net "P3E_CPU0_PE2_SS_RXP<1>")
	)
	(segment
		(start 302.65624 -88.003634)
		(end 302.689006 -88.003634)
		(width 0.0889)
		(layer "In4.Cu")
		(net "P3E_CPU0_PE2_SS_RXP<1>")
	)
	(segment
		(start 397.764 -9.8806)
		(end 398.4752 -8.8138)
		(width 0.1143)
		(layer "In4.Cu")
		(net "P3E_CPU0_PE2_SS_RXP<1>")
	)
	(segment
		(start 385.831334 -10.881868)
		(end 386.167122 -10.951972)
		(width 0.1143)
		(layer "In4.Cu")
		(net "P3E_CPU0_PE2_SS_RXP<1>")
	)
	(segment
		(start 398.523714 -8.781288)
		(end 398.523968 -8.781542)
		(width 0.1143)
		(layer "In4.Cu")
		(net "P3E_CPU0_PE2_SS_RXP<1>")
	)
	(segment
		(start 385.172458 -10.7442)
		(end 385.368038 -10.616184)
		(width 0.1143)
		(layer "In4.Cu")
		(net "P3E_CPU0_PE2_SS_RXP<1>")
	)
	(segment
		(start 361.011978 -46.082712)
		(end 362.618782 -43.654472)
		(width 0.1143)
		(layer "In4.Cu")
		(net "P3E_CPU0_PE2_SS_RXP<1>")
	)
	(segment
		(start 385.703572 -10.686288)
		(end 385.831334 -10.881868)
		(width 0.1143)
		(layer "In4.Cu")
		(net "P3E_CPU0_PE2_SS_RXP<1>")
	)
	(segment
		(start 308.880002 -86.3092)
		(end 309.65648 -85.775546)
		(width 0.1143)
		(layer "In4.Cu")
		(net "P3E_CPU0_PE2_SS_RXP<1>")
	)
	(segment
		(start 407.091642 -2.99847)
		(end 406.977342 -2.88417)
		(width 0.1143)
		(layer "In4.Cu")
		(net "P3E_CPU0_PE2_SS_RXP<1>")
	)
	(segment
		(start 407.091642 -3.275584)
		(end 407.091642 -2.99847)
		(width 0.1143)
		(layer "In4.Cu")
		(net "P3E_CPU0_PE2_SS_RXP<1>")
	)
	(segment
		(start 384.744976 -10.654792)
		(end 385.172458 -10.7442)
		(width 0.1143)
		(layer "In4.Cu")
		(net "P3E_CPU0_PE2_SS_RXP<1>")
	)
	(segment
		(start 368.982752 -32.333184)
		(end 369.242848 -31.947104)
		(width 0.1143)
		(layer "In4.Cu")
		(net "P3E_CPU0_PE2_SS_RXP<1>")
	)
	(segment
		(start 373.471948 -25.470358)
		(end 375.611898 -16.295116)
		(width 0.1143)
		(layer "In4.Cu")
		(net "P3E_CPU0_PE2_SS_RXP<1>")
	)
	(segment
		(start 398.523968 -8.781542)
		(end 401.04695 -7.099554)
		(width 0.1143)
		(layer "In4.Cu")
		(net "P3E_CPU0_PE2_SS_RXP<1>")
	)
	(segment
		(start 309.65648 -85.775546)
		(end 309.7022 -85.708236)
		(width 0.1143)
		(layer "In4.Cu")
		(net "P3E_CPU0_PE2_SS_RXP<1>")
	)
	(segment
		(start 387.692646 -11.101832)
		(end 387.820408 -11.297412)
		(width 0.1143)
		(layer "In4.Cu")
		(net "P3E_CPU0_PE2_SS_RXP<1>")
	)
	(segment
		(start 305.228498 -87.508588)
		(end 306.150772 -87.508588)
		(width 0.0889)
		(layer "In4.Cu")
		(net "P3E_CPU0_PE2_SS_RXP<1>")
	)
	(segment
		(start 303.183036 -88.299036)
		(end 303.183544 -88.299544)
		(width 0.0889)
		(layer "In4.Cu")
		(net "P3E_CPU0_PE2_SS_RXP<1>")
	)
	(segment
		(start 371.170454 -30.582362)
		(end 372.093236 -26.22423)
		(width 0.1143)
		(layer "In4.Cu")
		(net "P3E_CPU0_PE2_SS_RXP<1>")
	)
	(segment
		(start 342.07958 -51.089306)
		(end 343.991438 -51.478434)
		(width 0.1143)
		(layer "In4.Cu")
		(net "P3E_CPU0_PE2_SS_RXP<1>")
	)
	(segment
		(start 372.093236 -26.22423)
		(end 373.471948 -25.470358)
		(width 0.1143)
		(layer "In4.Cu")
		(net "P3E_CPU0_PE2_SS_RXP<1>")
	)
	(segment
		(start 369.242848 -31.94685)
		(end 369.244626 -31.94431)
		(width 0.1143)
		(layer "In4.Cu")
		(net "P3E_CPU0_PE2_SS_RXP<1>")
	)
	(segment
		(start 387.357112 -11.031728)
		(end 387.692646 -11.101832)
		(width 0.1143)
		(layer "In4.Cu")
		(net "P3E_CPU0_PE2_SS_RXP<1>")
	)
	(segment
		(start 314.846462 -80.188562)
		(end 314.846208 -80.188308)
		(width 0.1143)
		(layer "In4.Cu")
		(net "P3E_CPU0_PE2_SS_RXP<1>")
	)
	(segment
		(start 320.111882 -67.479926)
		(end 328.950574 -54.63032)
		(width 0.1143)
		(layer "In4.Cu")
		(net "P3E_CPU0_PE2_SS_RXP<1>")
	)
	(segment
		(start 310.376062 -84.716874)
		(end 313.320684 -82.047588)
		(width 0.1143)
		(layer "In4.Cu")
		(net "P3E_CPU0_PE2_SS_RXP<1>")
	)
	(segment
		(start 343.991438 -51.478434)
		(end 358.897428 -47.481744)
		(width 0.1143)
		(layer "In4.Cu")
		(net "P3E_CPU0_PE2_SS_RXP<1>")
	)
	(segment
		(start 381.119126 -11.424412)
		(end 384.744976 -10.654792)
		(width 0.1143)
		(layer "In4.Cu")
		(net "P3E_CPU0_PE2_SS_RXP<1>")
	)
	(segment
		(start 331.46492 -52.97678)
		(end 337.50885 -51.074574)
		(width 0.1143)
		(layer "In4.Cu")
		(net "P3E_CPU0_PE2_SS_RXP<1>")
	)
	(segment
		(start 339.829648 -51.547014)
		(end 342.07958 -51.089306)
		(width 0.1143)
		(layer "In4.Cu")
		(net "P3E_CPU0_PE2_SS_RXP<1>")
	)
	(segment
		(start 406.965912 -3.451606)
		(end 407.091642 -3.275584)
		(width 0.1143)
		(layer "In4.Cu")
		(net "P3E_CPU0_PE2_SS_RXP<1>")
	)
	(segment
		(start 402.527516 -4.969256)
		(end 406.965912 -3.451606)
		(width 0.1143)
		(layer "In4.Cu")
		(net "P3E_CPU0_PE2_SS_RXP<1>")
	)
	(segment
		(start 375.611898 -16.295116)
		(end 378.435362 -12.864846)
		(width 0.1143)
		(layer "In4.Cu")
		(net "P3E_CPU0_PE2_SS_RXP<1>")
	)
	(segment
		(start 387.820408 -11.297412)
		(end 390.267444 -11.80846)
		(width 0.1143)
		(layer "In4.Cu")
		(net "P3E_CPU0_PE2_SS_RXP<1>")
	)
	(segment
		(start 369.242848 -31.947104)
		(end 369.242848 -31.94685)
		(width 0.1143)
		(layer "In4.Cu")
		(net "P3E_CPU0_PE2_SS_RXP<1>")
	)
	(segment
		(start 395.912086 -10.53846)
		(end 396.248636 -10.472674)
		(width 0.1143)
		(layer "In4.Cu")
		(net "P3E_CPU0_PE2_SS_RXP<1>")
	)
	(arc
		(start 303.517808 -88.499188)
		(mid 303.529746 -88.499366)
		(end 303.541684 -88.499188)
		(width 0.0889)
		(layer "In4.Cu")
		(net "P3E_CPU0_PE2_SS_RXP<1>")
	)
	(arc
		(start 303.876456 -88.299036)
		(mid 304.085064 -88.087104)
		(end 304.370486 -88.003634)
		(width 0.0889)
		(layer "In4.Cu")
		(net "P3E_CPU0_PE2_SS_RXP<1>")
	)
	(arc
		(start 304.403252 -88.003634)
		(mid 304.594894 -87.946468)
		(end 304.734976 -87.803736)
		(width 0.0889)
		(layer "In4.Cu")
		(net "P3E_CPU0_PE2_SS_RXP<1>")
	)
	(arc
		(start 301.465996 -87.308436)
		(mid 301.607679 -87.45224)
		(end 301.80153 -87.508588)
		(width 0.0889)
		(layer "In4.Cu")
		(net "P3E_CPU0_PE2_SS_RXP<1>")
	)
	(arc
		(start 303.541684 -88.499188)
		(mid 303.73511 -88.442661)
		(end 303.876456 -88.299036)
		(width 0.0889)
		(layer "In4.Cu")
		(net "P3E_CPU0_PE2_SS_RXP<1>")
	)
	(arc
		(start 301.019464 -87.016336)
		(mid 301.277601 -87.10909)
		(end 301.465996 -87.308436)
		(width 0.0889)
		(layer "In4.Cu")
		(net "P3E_CPU0_PE2_SS_RXP<1>")
	)
	(arc
		(start 301.834296 -87.508588)
		(mid 302.117513 -87.592869)
		(end 302.324516 -87.803736)
		(width 0.0889)
		(layer "In4.Cu")
		(net "P3E_CPU0_PE2_SS_RXP<1>")
	)
	(arc
		(start 302.324516 -87.803736)
		(mid 302.464595 -87.946472)
		(end 302.65624 -88.003634)
		(width 0.0889)
		(layer "In4.Cu")
		(net "P3E_CPU0_PE2_SS_RXP<1>")
	)
	(arc
		(start 304.734976 -87.803736)
		(mid 304.943395 -87.592023)
		(end 305.228498 -87.508588)
		(width 0.0889)
		(layer "In4.Cu")
		(net "P3E_CPU0_PE2_SS_RXP<1>")
	)
	(arc
		(start 303.193196 -88.315546)
		(mid 303.332493 -88.447539)
		(end 303.5173 -88.499188)
		(width 0.0889)
		(layer "In4.Cu")
		(net "P3E_CPU0_PE2_SS_RXP<1>")
	)
	(arc
		(start 303.183544 -88.299544)
		(mid 303.188277 -88.307601)
		(end 303.193196 -88.315546)
		(width 0.0889)
		(layer "In4.Cu")
		(net "P3E_CPU0_PE2_SS_RXP<1>")
	)
	(arc
		(start 302.689006 -88.003634)
		(mid 302.97443 -88.087101)
		(end 303.183036 -88.299036)
		(width 0.0889)
		(layer "In4.Cu")
		(net "P3E_CPU0_PE2_SS_RXP<1>")
	)
	(segment
		(start 361.648248 -2.937002)
		(end 361.300268 -2.937002)
		(width 0.1143)
		(layer "F.Cu")
		(net "P3E_CPU0_PE2_SS_RXP<15>")
	)
	(segment
		(start 361.48518 -3.708146)
		(end 361.762802 -3.430524)
		(width 0.1143)
		(layer "F.Cu")
		(net "P3E_CPU0_PE2_SS_RXP<15>")
	)
	(segment
		(start 300.095666 -75.221338)
		(end 299.524166 -75.221338)
		(width 0.1143)
		(layer "F.Cu")
		(net "P3E_CPU0_PE2_SS_RXP<15>")
	)
	(segment
		(start 361.762802 -3.051556)
		(end 361.648248 -2.937002)
		(width 0.1143)
		(layer "F.Cu")
		(net "P3E_CPU0_PE2_SS_RXP<15>")
	)
	(segment
		(start 361.48518 -4.389882)
		(end 361.48518 -3.708146)
		(width 0.1143)
		(layer "F.Cu")
		(net "P3E_CPU0_PE2_SS_RXP<15>")
	)
	(segment
		(start 361.762802 -3.430524)
		(end 361.762802 -3.051556)
		(width 0.1143)
		(layer "F.Cu")
		(net "P3E_CPU0_PE2_SS_RXP<15>")
	)
	(via
		(at 361.300268 -2.937002)
		(size 0.508)
		(drill 0.254)
		(layers "F.Cu" "B.Cu")
		(net "P3E_CPU0_PE2_SS_RXP<15>")
	)
	(via
		(at 300.095666 -75.221338)
		(size 0.508)
		(drill 0.254)
		(layers "F.Cu" "B.Cu")
		(net "P3E_CPU0_PE2_SS_RXP<15>")
	)
	(segment
		(start 306.014628 -74.135234)
		(end 306.47132 -74.135234)
		(width 0.0889)
		(layer "In4.Cu")
		(net "P3E_CPU0_PE2_SS_RXP<15>")
	)
	(segment
		(start 309.977282 -57.597548)
		(end 309.18912 -56.426862)
		(width 0.1143)
		(layer "In4.Cu")
		(net "P3E_CPU0_PE2_SS_RXP<15>")
	)
	(segment
		(start 362.227876 -7.482332)
		(end 362.226352 -7.474712)
		(width 0.1143)
		(layer "In4.Cu")
		(net "P3E_CPU0_PE2_SS_RXP<15>")
	)
	(segment
		(start 314.70727 -46.154086)
		(end 319.977262 -45.145452)
		(width 0.1143)
		(layer "In4.Cu")
		(net "P3E_CPU0_PE2_SS_RXP<15>")
	)
	(segment
		(start 309.255668 -50.55362)
		(end 314.70727 -46.154086)
		(width 0.1143)
		(layer "In4.Cu")
		(net "P3E_CPU0_PE2_SS_RXP<15>")
	)
	(segment
		(start 308.732936 -70.541642)
		(end 308.565804 -69.704966)
		(width 0.1143)
		(layer "In4.Cu")
		(net "P3E_CPU0_PE2_SS_RXP<15>")
	)
	(segment
		(start 361.862878 -5.824982)
		(end 361.789218 -5.49021)
		(width 0.1143)
		(layer "In4.Cu")
		(net "P3E_CPU0_PE2_SS_RXP<15>")
	)
	(segment
		(start 306.52212 -74.084434)
		(end 306.544218 -74.084434)
		(width 0.0889)
		(layer "In4.Cu")
		(net "P3E_CPU0_PE2_SS_RXP<15>")
	)
	(segment
		(start 304.37455 -74.135234)
		(end 304.403252 -74.135234)
		(width 0.0889)
		(layer "In4.Cu")
		(net "P3E_CPU0_PE2_SS_RXP<15>")
	)
	(segment
		(start 324.719188 -45.600366)
		(end 328.21245 -44.493942)
		(width 0.1143)
		(layer "In4.Cu")
		(net "P3E_CPU0_PE2_SS_RXP<15>")
	)
	(segment
		(start 362.300266 -7.809484)
		(end 362.227876 -7.482332)
		(width 0.1143)
		(layer "In4.Cu")
		(net "P3E_CPU0_PE2_SS_RXP<15>")
	)
	(segment
		(start 363.298994 -12.343384)
		(end 362.66501 -9.46658)
		(width 0.1143)
		(layer "In4.Cu")
		(net "P3E_CPU0_PE2_SS_RXP<15>")
	)
	(segment
		(start 308.539134 -52.272692)
		(end 308.539388 -52.272692)
		(width 0.1143)
		(layer "In4.Cu")
		(net "P3E_CPU0_PE2_SS_RXP<15>")
	)
	(segment
		(start 341.259922 -34.62909)
		(end 345.096846 -34.62909)
		(width 0.1143)
		(layer "In4.Cu")
		(net "P3E_CPU0_PE2_SS_RXP<15>")
	)
	(segment
		(start 361.789218 -5.49021)
		(end 361.789218 -3.051302)
		(width 0.1143)
		(layer "In4.Cu")
		(net "P3E_CPU0_PE2_SS_RXP<15>")
	)
	(segment
		(start 310.736742 -59.250072)
		(end 309.977282 -57.597548)
		(width 0.1143)
		(layer "In4.Cu")
		(net "P3E_CPU0_PE2_SS_RXP<15>")
	)
	(segment
		(start 362.226352 -7.474712)
		(end 362.029756 -7.348982)
		(width 0.1143)
		(layer "In4.Cu")
		(net "P3E_CPU0_PE2_SS_RXP<15>")
	)
	(segment
		(start 301.791116 -74.630788)
		(end 301.823882 -74.630788)
		(width 0.0889)
		(layer "In4.Cu")
		(net "P3E_CPU0_PE2_SS_RXP<15>")
	)
	(segment
		(start 333.096108 -40.446706)
		(end 335.854294 -38.619176)
		(width 0.1143)
		(layer "In4.Cu")
		(net "P3E_CPU0_PE2_SS_RXP<15>")
	)
	(segment
		(start 307.45938 -67.141852)
		(end 307.856382 -65.863216)
		(width 0.1143)
		(layer "In4.Cu")
		(net "P3E_CPU0_PE2_SS_RXP<15>")
	)
	(segment
		(start 308.84114 -51.18481)
		(end 309.255668 -50.55362)
		(width 0.1143)
		(layer "In4.Cu")
		(net "P3E_CPU0_PE2_SS_RXP<15>")
	)
	(segment
		(start 300.936406 -75.125834)
		(end 300.969172 -75.125834)
		(width 0.0889)
		(layer "In4.Cu")
		(net "P3E_CPU0_PE2_SS_RXP<15>")
	)
	(segment
		(start 305.225196 -73.640188)
		(end 305.449986 -73.640188)
		(width 0.0889)
		(layer "In4.Cu")
		(net "P3E_CPU0_PE2_SS_RXP<15>")
	)
	(segment
		(start 339.58784 -38.272466)
		(end 339.58784 -36.301172)
		(width 0.1143)
		(layer "In4.Cu")
		(net "P3E_CPU0_PE2_SS_RXP<15>")
	)
	(segment
		(start 310.199278 -63.548768)
		(end 311.078626 -60.957714)
		(width 0.1143)
		(layer "In4.Cu")
		(net "P3E_CPU0_PE2_SS_RXP<15>")
	)
	(segment
		(start 331.368908 -40.791892)
		(end 333.096108 -40.446706)
		(width 0.1143)
		(layer "In4.Cu")
		(net "P3E_CPU0_PE2_SS_RXP<15>")
	)
	(segment
		(start 360.334814 -26.19756)
		(end 363.298994 -12.343384)
		(width 0.1143)
		(layer "In4.Cu")
		(net "P3E_CPU0_PE2_SS_RXP<15>")
	)
	(segment
		(start 339.58784 -36.301172)
		(end 341.259922 -34.62909)
		(width 0.1143)
		(layer "In4.Cu")
		(net "P3E_CPU0_PE2_SS_RXP<15>")
	)
	(segment
		(start 345.096846 -34.62909)
		(end 346.824808 -34.995358)
		(width 0.1143)
		(layer "In4.Cu")
		(net "P3E_CPU0_PE2_SS_RXP<15>")
	)
	(segment
		(start 308.324504 -55.151528)
		(end 308.542182 -52.92598)
		(width 0.1143)
		(layer "In4.Cu")
		(net "P3E_CPU0_PE2_SS_RXP<15>")
	)
	(segment
		(start 362.081572 -6.81736)
		(end 362.007912 -6.482334)
		(width 0.1143)
		(layer "In4.Cu")
		(net "P3E_CPU0_PE2_SS_RXP<15>")
	)
	(segment
		(start 308.542182 -52.92598)
		(end 308.527704 -52.314602)
		(width 0.1143)
		(layer "In4.Cu")
		(net "P3E_CPU0_PE2_SS_RXP<15>")
	)
	(segment
		(start 319.977262 -45.145452)
		(end 324.719188 -45.600366)
		(width 0.1143)
		(layer "In4.Cu")
		(net "P3E_CPU0_PE2_SS_RXP<15>")
	)
	(segment
		(start 308.527704 -52.314602)
		(end 308.539134 -52.272692)
		(width 0.1143)
		(layer "In4.Cu")
		(net "P3E_CPU0_PE2_SS_RXP<15>")
	)
	(segment
		(start 339.24113 -38.619176)
		(end 339.58784 -38.272466)
		(width 0.1143)
		(layer "In4.Cu")
		(net "P3E_CPU0_PE2_SS_RXP<15>")
	)
	(segment
		(start 362.007912 -6.482334)
		(end 361.811062 -6.356604)
		(width 0.1143)
		(layer "In4.Cu")
		(net "P3E_CPU0_PE2_SS_RXP<15>")
	)
	(segment
		(start 362.66501 -9.46658)
		(end 362.663486 -9.45896)
		(width 0.1143)
		(layer "In4.Cu")
		(net "P3E_CPU0_PE2_SS_RXP<15>")
	)
	(segment
		(start 303.529492 -74.630788)
		(end 303.53 -74.630788)
		(width 0.0889)
		(layer "In4.Cu")
		(net "P3E_CPU0_PE2_SS_RXP<15>")
	)
	(segment
		(start 346.824808 -34.995358)
		(end 354.555044 -33.58134)
		(width 0.1143)
		(layer "In4.Cu")
		(net "P3E_CPU0_PE2_SS_RXP<15>")
	)
	(segment
		(start 307.856382 -65.863216)
		(end 310.199278 -63.548768)
		(width 0.1143)
		(layer "In4.Cu")
		(net "P3E_CPU0_PE2_SS_RXP<15>")
	)
	(segment
		(start 362.029756 -7.348982)
		(end 361.955842 -7.013956)
		(width 0.1143)
		(layer "In4.Cu")
		(net "P3E_CPU0_PE2_SS_RXP<15>")
	)
	(segment
		(start 362.392976 -8.998458)
		(end 362.518706 -8.801608)
		(width 0.1143)
		(layer "In4.Cu")
		(net "P3E_CPU0_PE2_SS_RXP<15>")
	)
	(segment
		(start 356.098094 -32.552386)
		(end 360.334814 -26.19756)
		(width 0.1143)
		(layer "In4.Cu")
		(net "P3E_CPU0_PE2_SS_RXP<15>")
	)
	(segment
		(start 362.248196 -8.341106)
		(end 362.174536 -8.006334)
		(width 0.1143)
		(layer "In4.Cu")
		(net "P3E_CPU0_PE2_SS_RXP<15>")
	)
	(segment
		(start 361.811062 -6.356604)
		(end 361.737402 -6.021832)
		(width 0.1143)
		(layer "In4.Cu")
		(net "P3E_CPU0_PE2_SS_RXP<15>")
	)
	(segment
		(start 362.46689 -9.33323)
		(end 362.392976 -8.998458)
		(width 0.1143)
		(layer "In4.Cu")
		(net "P3E_CPU0_PE2_SS_RXP<15>")
	)
	(segment
		(start 311.078626 -60.957714)
		(end 310.736742 -59.250072)
		(width 0.1143)
		(layer "In4.Cu")
		(net "P3E_CPU0_PE2_SS_RXP<15>")
	)
	(segment
		(start 328.21245 -44.493942)
		(end 330.13015 -41.617646)
		(width 0.1143)
		(layer "In4.Cu")
		(net "P3E_CPU0_PE2_SS_RXP<15>")
	)
	(segment
		(start 362.663486 -9.45896)
		(end 362.46689 -9.33323)
		(width 0.1143)
		(layer "In4.Cu")
		(net "P3E_CPU0_PE2_SS_RXP<15>")
	)
	(segment
		(start 361.737402 -6.021832)
		(end 361.862878 -5.824982)
		(width 0.1143)
		(layer "In4.Cu")
		(net "P3E_CPU0_PE2_SS_RXP<15>")
	)
	(segment
		(start 306.544218 -74.084434)
		(end 306.818538 -74.084434)
		(width 0.1143)
		(layer "In4.Cu")
		(net "P3E_CPU0_PE2_SS_RXP<15>")
	)
	(segment
		(start 361.955842 -7.013956)
		(end 362.081572 -6.81736)
		(width 0.1143)
		(layer "In4.Cu")
		(net "P3E_CPU0_PE2_SS_RXP<15>")
	)
	(segment
		(start 361.674918 -2.937002)
		(end 361.300268 -2.937002)
		(width 0.1143)
		(layer "In4.Cu")
		(net "P3E_CPU0_PE2_SS_RXP<15>")
	)
	(segment
		(start 361.789218 -3.051302)
		(end 361.674918 -2.937002)
		(width 0.1143)
		(layer "In4.Cu")
		(net "P3E_CPU0_PE2_SS_RXP<15>")
	)
	(segment
		(start 362.518706 -8.801608)
		(end 362.445046 -8.466836)
		(width 0.1143)
		(layer "In4.Cu")
		(net "P3E_CPU0_PE2_SS_RXP<15>")
	)
	(segment
		(start 362.445046 -8.466836)
		(end 362.248196 -8.341106)
		(width 0.1143)
		(layer "In4.Cu")
		(net "P3E_CPU0_PE2_SS_RXP<15>")
	)
	(segment
		(start 306.818538 -74.084434)
		(end 307.596032 -73.286366)
		(width 0.1143)
		(layer "In4.Cu")
		(net "P3E_CPU0_PE2_SS_RXP<15>")
	)
	(segment
		(start 307.599334 -68.284344)
		(end 307.45938 -67.141852)
		(width 0.1143)
		(layer "In4.Cu")
		(net "P3E_CPU0_PE2_SS_RXP<15>")
	)
	(segment
		(start 306.47132 -74.135234)
		(end 306.52212 -74.084434)
		(width 0.0889)
		(layer "In4.Cu")
		(net "P3E_CPU0_PE2_SS_RXP<15>")
	)
	(segment
		(start 308.539388 -52.272692)
		(end 308.84114 -51.18481)
		(width 0.1143)
		(layer "In4.Cu")
		(net "P3E_CPU0_PE2_SS_RXP<15>")
	)
	(segment
		(start 307.596032 -73.286366)
		(end 308.732936 -70.541642)
		(width 0.1143)
		(layer "In4.Cu")
		(net "P3E_CPU0_PE2_SS_RXP<15>")
	)
	(segment
		(start 308.565804 -69.704966)
		(end 307.599334 -68.284344)
		(width 0.1143)
		(layer "In4.Cu")
		(net "P3E_CPU0_PE2_SS_RXP<15>")
	)
	(segment
		(start 335.854294 -38.619176)
		(end 339.24113 -38.619176)
		(width 0.1143)
		(layer "In4.Cu")
		(net "P3E_CPU0_PE2_SS_RXP<15>")
	)
	(segment
		(start 308.61762 -55.909972)
		(end 308.324504 -55.151528)
		(width 0.1143)
		(layer "In4.Cu")
		(net "P3E_CPU0_PE2_SS_RXP<15>")
	)
	(segment
		(start 362.174536 -8.006334)
		(end 362.300266 -7.809484)
		(width 0.1143)
		(layer "In4.Cu")
		(net "P3E_CPU0_PE2_SS_RXP<15>")
	)
	(segment
		(start 330.13015 -41.617646)
		(end 331.368908 -40.791892)
		(width 0.1143)
		(layer "In4.Cu")
		(net "P3E_CPU0_PE2_SS_RXP<15>")
	)
	(segment
		(start 309.18912 -56.426862)
		(end 308.61762 -55.909972)
		(width 0.1143)
		(layer "In4.Cu")
		(net "P3E_CPU0_PE2_SS_RXP<15>")
	)
	(segment
		(start 354.555044 -33.58134)
		(end 356.098094 -32.552386)
		(width 0.1143)
		(layer "In4.Cu")
		(net "P3E_CPU0_PE2_SS_RXP<15>")
	)
	(arc
		(start 303.183036 -74.430636)
		(mid 303.329418 -74.5772)
		(end 303.529492 -74.630788)
		(width 0.0889)
		(layer "In4.Cu")
		(net "P3E_CPU0_PE2_SS_RXP<15>")
	)
	(arc
		(start 303.876456 -74.430636)
		(mid 304.086809 -74.217664)
		(end 304.37455 -74.135234)
		(width 0.0889)
		(layer "In4.Cu")
		(net "P3E_CPU0_PE2_SS_RXP<15>")
	)
	(arc
		(start 304.403252 -74.135234)
		(mid 304.594894 -74.078068)
		(end 304.734976 -73.935336)
		(width 0.0889)
		(layer "In4.Cu")
		(net "P3E_CPU0_PE2_SS_RXP<15>")
	)
	(arc
		(start 300.095666 -75.221338)
		(mid 300.405453 -75.256385)
		(end 300.707552 -75.179428)
		(width 0.0889)
		(layer "In4.Cu")
		(net "P3E_CPU0_PE2_SS_RXP<15>")
	)
	(arc
		(start 302.159416 -74.430636)
		(mid 302.671226 -74.134969)
		(end 303.183036 -74.430636)
		(width 0.0889)
		(layer "In4.Cu")
		(net "P3E_CPU0_PE2_SS_RXP<15>")
	)
	(arc
		(start 304.734976 -73.935336)
		(mid 304.94198 -73.724472)
		(end 305.225196 -73.640188)
		(width 0.0889)
		(layer "In4.Cu")
		(net "P3E_CPU0_PE2_SS_RXP<15>")
	)
	(arc
		(start 301.823882 -74.630788)
		(mid 302.017732 -74.574438)
		(end 302.159416 -74.430636)
		(width 0.0889)
		(layer "In4.Cu")
		(net "P3E_CPU0_PE2_SS_RXP<15>")
	)
	(arc
		(start 305.798474 -73.93813)
		(mid 305.889418 -74.055473)
		(end 306.014628 -74.135234)
		(width 0.0889)
		(layer "In4.Cu")
		(net "P3E_CPU0_PE2_SS_RXP<15>")
	)
	(arc
		(start 300.707552 -75.179428)
		(mid 300.819289 -75.141148)
		(end 300.936406 -75.125834)
		(width 0.0889)
		(layer "In4.Cu")
		(net "P3E_CPU0_PE2_SS_RXP<15>")
	)
	(arc
		(start 300.969172 -75.125834)
		(mid 301.160814 -75.068668)
		(end 301.300896 -74.925936)
		(width 0.0889)
		(layer "In4.Cu")
		(net "P3E_CPU0_PE2_SS_RXP<15>")
	)
	(arc
		(start 303.53 -74.630788)
		(mid 303.730041 -74.577143)
		(end 303.876456 -74.430636)
		(width 0.0889)
		(layer "In4.Cu")
		(net "P3E_CPU0_PE2_SS_RXP<15>")
	)
	(arc
		(start 305.449986 -73.640188)
		(mid 305.65258 -73.756006)
		(end 305.798474 -73.93813)
		(width 0.0889)
		(layer "In4.Cu")
		(net "P3E_CPU0_PE2_SS_RXP<15>")
	)
	(arc
		(start 301.300896 -74.925936)
		(mid 301.5079 -74.715072)
		(end 301.791116 -74.630788)
		(width 0.0889)
		(layer "In4.Cu")
		(net "P3E_CPU0_PE2_SS_RXP<15>")
	)
	(segment
		(start 364.138972 -3.448304)
		(end 364.138972 -3.002026)
		(width 0.1143)
		(layer "F.Cu")
		(net "P3E_CPU0_PE2_SS_RXP<14>")
	)
	(segment
		(start 301.241206 -75.221338)
		(end 301.812706 -75.221338)
		(width 0.1143)
		(layer "F.Cu")
		(net "P3E_CPU0_PE2_SS_RXP<14>")
	)
	(segment
		(start 363.885226 -3.70205)
		(end 364.138972 -3.448304)
		(width 0.1143)
		(layer "F.Cu")
		(net "P3E_CPU0_PE2_SS_RXP<14>")
	)
	(segment
		(start 363.9693 -2.832354)
		(end 363.9693 -2.192528)
		(width 0.1143)
		(layer "F.Cu")
		(net "P3E_CPU0_PE2_SS_RXP<14>")
	)
	(segment
		(start 363.9693 -2.192528)
		(end 363.746796 -1.970024)
		(width 0.1143)
		(layer "F.Cu")
		(net "P3E_CPU0_PE2_SS_RXP<14>")
	)
	(segment
		(start 364.138972 -3.002026)
		(end 363.9693 -2.832354)
		(width 0.1143)
		(layer "F.Cu")
		(net "P3E_CPU0_PE2_SS_RXP<14>")
	)
	(segment
		(start 363.885226 -4.389882)
		(end 363.885226 -3.70205)
		(width 0.1143)
		(layer "F.Cu")
		(net "P3E_CPU0_PE2_SS_RXP<14>")
	)
	(segment
		(start 363.746796 -1.970024)
		(end 363.48035 -1.970024)
		(width 0.1143)
		(layer "F.Cu")
		(net "P3E_CPU0_PE2_SS_RXP<14>")
	)
	(via
		(at 363.48035 -1.970024)
		(size 0.508)
		(drill 0.254)
		(layers "F.Cu" "B.Cu")
		(net "P3E_CPU0_PE2_SS_RXP<14>")
	)
	(via
		(at 301.812706 -75.221338)
		(size 0.508)
		(drill 0.254)
		(layers "F.Cu" "B.Cu")
		(net "P3E_CPU0_PE2_SS_RXP<14>")
	)
	(segment
		(start 364.36935 -8.26135)
		(end 364.53445 -8.42645)
		(width 0.1143)
		(layer "In4.Cu")
		(net "P3E_CPU0_PE2_SS_RXP<14>")
	)
	(segment
		(start 310.845962 -64.232282)
		(end 310.295544 -64.575436)
		(width 0.1143)
		(layer "In4.Cu")
		(net "P3E_CPU0_PE2_SS_RXP<14>")
	)
	(segment
		(start 309.436516 -51.443382)
		(end 309.253636 -52.085748)
		(width 0.1143)
		(layer "In4.Cu")
		(net "P3E_CPU0_PE2_SS_RXP<14>")
	)
	(segment
		(start 364.53445 -7.75335)
		(end 364.36935 -7.91845)
		(width 0.1143)
		(layer "In4.Cu")
		(net "P3E_CPU0_PE2_SS_RXP<14>")
	)
	(segment
		(start 364.53445 -6.39445)
		(end 364.53445 -6.73735)
		(width 0.1143)
		(layer "In4.Cu")
		(net "P3E_CPU0_PE2_SS_RXP<14>")
	)
	(segment
		(start 364.53445 -6.73735)
		(end 364.36935 -6.90245)
		(width 0.1143)
		(layer "In4.Cu")
		(net "P3E_CPU0_PE2_SS_RXP<14>")
	)
	(segment
		(start 310.463946 -54.524656)
		(end 311.966102 -59.806078)
		(width 0.1143)
		(layer "In4.Cu")
		(net "P3E_CPU0_PE2_SS_RXP<14>")
	)
	(segment
		(start 320.04889 -45.80128)
		(end 314.942728 -46.782228)
		(width 0.1143)
		(layer "In4.Cu")
		(net "P3E_CPU0_PE2_SS_RXP<14>")
	)
	(segment
		(start 364.36935 -7.24535)
		(end 364.53445 -7.41045)
		(width 0.1143)
		(layer "In4.Cu")
		(net "P3E_CPU0_PE2_SS_RXP<14>")
	)
	(segment
		(start 333.2607 -41.256966)
		(end 333.2607 -42.23893)
		(width 0.1143)
		(layer "In4.Cu")
		(net "P3E_CPU0_PE2_SS_RXP<14>")
	)
	(segment
		(start 364.36935 -7.91845)
		(end 364.36935 -8.26135)
		(width 0.1143)
		(layer "In4.Cu")
		(net "P3E_CPU0_PE2_SS_RXP<14>")
	)
	(segment
		(start 332.883002 -43.367706)
		(end 331.81798 -44.077636)
		(width 0.1143)
		(layer "In4.Cu")
		(net "P3E_CPU0_PE2_SS_RXP<14>")
	)
	(segment
		(start 364.53445 -10.459974)
		(end 361.19181 -26.078942)
		(width 0.1143)
		(layer "In4.Cu")
		(net "P3E_CPU0_PE2_SS_RXP<14>")
	)
	(segment
		(start 333.2607 -42.23893)
		(end 333.099664 -43.04284)
		(width 0.1143)
		(layer "In4.Cu")
		(net "P3E_CPU0_PE2_SS_RXP<14>")
	)
	(segment
		(start 309.253636 -52.085748)
		(end 309.240174 -52.753514)
		(width 0.1143)
		(layer "In4.Cu")
		(net "P3E_CPU0_PE2_SS_RXP<14>")
	)
	(segment
		(start 364.53445 -4.36245)
		(end 364.53445 -4.70535)
		(width 0.1143)
		(layer "In4.Cu")
		(net "P3E_CPU0_PE2_SS_RXP<14>")
	)
	(segment
		(start 340.855808 -39.56558)
		(end 340.519512 -39.901876)
		(width 0.1143)
		(layer "In4.Cu")
		(net "P3E_CPU0_PE2_SS_RXP<14>")
	)
	(segment
		(start 310.03494 -68.886832)
		(end 307.956712 -73.903586)
		(width 0.1143)
		(layer "In4.Cu")
		(net "P3E_CPU0_PE2_SS_RXP<14>")
	)
	(segment
		(start 306.743354 -75.075034)
		(end 306.692554 -75.125834)
		(width 0.0889)
		(layer "In4.Cu")
		(net "P3E_CPU0_PE2_SS_RXP<14>")
	)
	(segment
		(start 340.519512 -39.901876)
		(end 335.305654 -39.901876)
		(width 0.1143)
		(layer "In4.Cu")
		(net "P3E_CPU0_PE2_SS_RXP<14>")
	)
	(segment
		(start 333.099664 -43.04284)
		(end 332.883002 -43.367706)
		(width 0.1143)
		(layer "In4.Cu")
		(net "P3E_CPU0_PE2_SS_RXP<14>")
	)
	(segment
		(start 356.56393 -33.021016)
		(end 354.805996 -34.192972)
		(width 0.1143)
		(layer "In4.Cu")
		(net "P3E_CPU0_PE2_SS_RXP<14>")
	)
	(segment
		(start 306.97551 -75.075034)
		(end 306.765452 -75.075034)
		(width 0.1143)
		(layer "In4.Cu")
		(net "P3E_CPU0_PE2_SS_RXP<14>")
	)
	(segment
		(start 309.743856 -50.978816)
		(end 309.436516 -51.443382)
		(width 0.1143)
		(layer "In4.Cu")
		(net "P3E_CPU0_PE2_SS_RXP<14>")
	)
	(segment
		(start 354.805996 -34.192972)
		(end 346.766388 -35.67811)
		(width 0.1143)
		(layer "In4.Cu")
		(net "P3E_CPU0_PE2_SS_RXP<14>")
	)
	(segment
		(start 314.942728 -46.782228)
		(end 309.743856 -50.978816)
		(width 0.1143)
		(layer "In4.Cu")
		(net "P3E_CPU0_PE2_SS_RXP<14>")
	)
	(segment
		(start 364.36935 -5.21335)
		(end 364.53445 -5.37845)
		(width 0.1143)
		(layer "In4.Cu")
		(net "P3E_CPU0_PE2_SS_RXP<14>")
	)
	(segment
		(start 344.93327 -35.291268)
		(end 341.700612 -35.291268)
		(width 0.1143)
		(layer "In4.Cu")
		(net "P3E_CPU0_PE2_SS_RXP<14>")
	)
	(segment
		(start 364.53445 -8.42645)
		(end 364.53445 -10.459974)
		(width 0.1143)
		(layer "In4.Cu")
		(net "P3E_CPU0_PE2_SS_RXP<14>")
	)
	(segment
		(start 363.855 -1.970024)
		(end 363.9693 -2.084324)
		(width 0.1143)
		(layer "In4.Cu")
		(net "P3E_CPU0_PE2_SS_RXP<14>")
	)
	(segment
		(start 364.53445 -5.37845)
		(end 364.53445 -5.72135)
		(width 0.1143)
		(layer "In4.Cu")
		(net "P3E_CPU0_PE2_SS_RXP<14>")
	)
	(segment
		(start 346.766388 -35.67811)
		(end 344.93327 -35.291268)
		(width 0.1143)
		(layer "In4.Cu")
		(net "P3E_CPU0_PE2_SS_RXP<14>")
	)
	(segment
		(start 305.388772 -75.621388)
		(end 303.51857 -75.621388)
		(width 0.0889)
		(layer "In4.Cu")
		(net "P3E_CPU0_PE2_SS_RXP<14>")
	)
	(segment
		(start 361.19181 -26.078942)
		(end 356.56393 -33.021016)
		(width 0.1143)
		(layer "In4.Cu")
		(net "P3E_CPU0_PE2_SS_RXP<14>")
	)
	(segment
		(start 306.692554 -75.125834)
		(end 305.884326 -75.125834)
		(width 0.0889)
		(layer "In4.Cu")
		(net "P3E_CPU0_PE2_SS_RXP<14>")
	)
	(segment
		(start 364.36935 -6.90245)
		(end 364.36935 -7.24535)
		(width 0.1143)
		(layer "In4.Cu")
		(net "P3E_CPU0_PE2_SS_RXP<14>")
	)
	(segment
		(start 340.855808 -36.136072)
		(end 340.855808 -39.56558)
		(width 0.1143)
		(layer "In4.Cu")
		(net "P3E_CPU0_PE2_SS_RXP<14>")
	)
	(segment
		(start 341.700612 -35.291268)
		(end 340.855808 -36.136072)
		(width 0.1143)
		(layer "In4.Cu")
		(net "P3E_CPU0_PE2_SS_RXP<14>")
	)
	(segment
		(start 364.36935 -6.22935)
		(end 364.53445 -6.39445)
		(width 0.1143)
		(layer "In4.Cu")
		(net "P3E_CPU0_PE2_SS_RXP<14>")
	)
	(segment
		(start 310.295544 -64.575436)
		(end 309.556404 -66.123058)
		(width 0.1143)
		(layer "In4.Cu")
		(net "P3E_CPU0_PE2_SS_RXP<14>")
	)
	(segment
		(start 309.240174 -52.753514)
		(end 309.240174 -52.776628)
		(width 0.1143)
		(layer "In4.Cu")
		(net "P3E_CPU0_PE2_SS_RXP<14>")
	)
	(segment
		(start 307.956712 -73.903586)
		(end 306.97551 -75.075034)
		(width 0.1143)
		(layer "In4.Cu")
		(net "P3E_CPU0_PE2_SS_RXP<14>")
	)
	(segment
		(start 301.870618 -75.617324)
		(end 301.812706 -75.559412)
		(width 0.0889)
		(layer "In4.Cu")
		(net "P3E_CPU0_PE2_SS_RXP<14>")
	)
	(segment
		(start 311.966102 -59.806078)
		(end 311.752234 -62.088014)
		(width 0.1143)
		(layer "In4.Cu")
		(net "P3E_CPU0_PE2_SS_RXP<14>")
	)
	(segment
		(start 364.36935 -5.88645)
		(end 364.36935 -6.22935)
		(width 0.1143)
		(layer "In4.Cu")
		(net "P3E_CPU0_PE2_SS_RXP<14>")
	)
	(segment
		(start 364.53445 -5.72135)
		(end 364.36935 -5.88645)
		(width 0.1143)
		(layer "In4.Cu")
		(net "P3E_CPU0_PE2_SS_RXP<14>")
	)
	(segment
		(start 306.765452 -75.075034)
		(end 306.743354 -75.075034)
		(width 0.0889)
		(layer "In4.Cu")
		(net "P3E_CPU0_PE2_SS_RXP<14>")
	)
	(segment
		(start 324.820534 -46.293278)
		(end 320.04889 -45.80128)
		(width 0.1143)
		(layer "In4.Cu")
		(net "P3E_CPU0_PE2_SS_RXP<14>")
	)
	(segment
		(start 309.556404 -66.123058)
		(end 310.03494 -68.886832)
		(width 0.1143)
		(layer "In4.Cu")
		(net "P3E_CPU0_PE2_SS_RXP<14>")
	)
	(segment
		(start 364.36935 -4.87045)
		(end 364.36935 -5.21335)
		(width 0.1143)
		(layer "In4.Cu")
		(net "P3E_CPU0_PE2_SS_RXP<14>")
	)
	(segment
		(start 363.9693 -3.7973)
		(end 364.53445 -4.36245)
		(width 0.1143)
		(layer "In4.Cu")
		(net "P3E_CPU0_PE2_SS_RXP<14>")
	)
	(segment
		(start 311.752234 -62.088014)
		(end 310.845962 -64.232282)
		(width 0.1143)
		(layer "In4.Cu")
		(net "P3E_CPU0_PE2_SS_RXP<14>")
	)
	(segment
		(start 363.48035 -1.970024)
		(end 363.855 -1.970024)
		(width 0.1143)
		(layer "In4.Cu")
		(net "P3E_CPU0_PE2_SS_RXP<14>")
	)
	(segment
		(start 363.9693 -2.084324)
		(end 363.9693 -3.7973)
		(width 0.1143)
		(layer "In4.Cu")
		(net "P3E_CPU0_PE2_SS_RXP<14>")
	)
	(segment
		(start 305.884326 -75.125834)
		(end 305.388772 -75.621388)
		(width 0.0889)
		(layer "In4.Cu")
		(net "P3E_CPU0_PE2_SS_RXP<14>")
	)
	(segment
		(start 301.812706 -75.559412)
		(end 301.812706 -75.221338)
		(width 0.0889)
		(layer "In4.Cu")
		(net "P3E_CPU0_PE2_SS_RXP<14>")
	)
	(segment
		(start 364.53445 -7.41045)
		(end 364.53445 -7.75335)
		(width 0.1143)
		(layer "In4.Cu")
		(net "P3E_CPU0_PE2_SS_RXP<14>")
	)
	(segment
		(start 309.240174 -52.776628)
		(end 309.29453 -53.278786)
		(width 0.1143)
		(layer "In4.Cu")
		(net "P3E_CPU0_PE2_SS_RXP<14>")
	)
	(segment
		(start 309.29453 -53.278786)
		(end 310.463946 -54.524656)
		(width 0.1143)
		(layer "In4.Cu")
		(net "P3E_CPU0_PE2_SS_RXP<14>")
	)
	(segment
		(start 335.305654 -39.901876)
		(end 333.2607 -41.256966)
		(width 0.1143)
		(layer "In4.Cu")
		(net "P3E_CPU0_PE2_SS_RXP<14>")
	)
	(segment
		(start 364.53445 -4.70535)
		(end 364.36935 -4.87045)
		(width 0.1143)
		(layer "In4.Cu")
		(net "P3E_CPU0_PE2_SS_RXP<14>")
	)
	(segment
		(start 331.81798 -44.077636)
		(end 324.820534 -46.293278)
		(width 0.1143)
		(layer "In4.Cu")
		(net "P3E_CPU0_PE2_SS_RXP<14>")
	)
	(arc
		(start 302.159416 -75.421236)
		(mid 302.037525 -75.552432)
		(end 301.870618 -75.617324)
		(width 0.0889)
		(layer "In4.Cu")
		(net "P3E_CPU0_PE2_SS_RXP<14>")
	)
	(arc
		(start 303.51857 -75.621388)
		(mid 303.32472 -75.565038)
		(end 303.183036 -75.421236)
		(width 0.0889)
		(layer "In4.Cu")
		(net "P3E_CPU0_PE2_SS_RXP<14>")
	)
	(arc
		(start 303.183036 -75.421236)
		(mid 302.671226 -75.125569)
		(end 302.159416 -75.421236)
		(width 0.0889)
		(layer "In4.Cu")
		(net "P3E_CPU0_PE2_SS_RXP<14>")
	)
	(segment
		(start 367.085118 -3.72364)
		(end 366.804194 -3.442716)
		(width 0.1143)
		(layer "F.Cu")
		(net "P3E_CPU0_PE2_SS_RXP<13>")
	)
	(segment
		(start 366.942624 -2.937002)
		(end 367.37036 -2.937002)
		(width 0.1143)
		(layer "F.Cu")
		(net "P3E_CPU0_PE2_SS_RXP<13>")
	)
	(segment
		(start 366.804194 -3.075432)
		(end 366.942624 -2.937002)
		(width 0.1143)
		(layer "F.Cu")
		(net "P3E_CPU0_PE2_SS_RXP<13>")
	)
	(segment
		(start 366.804194 -3.442716)
		(end 366.804194 -3.075432)
		(width 0.1143)
		(layer "F.Cu")
		(net "P3E_CPU0_PE2_SS_RXP<13>")
	)
	(segment
		(start 367.085118 -4.389882)
		(end 367.085118 -3.72364)
		(width 0.1143)
		(layer "F.Cu")
		(net "P3E_CPU0_PE2_SS_RXP<13>")
	)
	(segment
		(start 302.099726 -76.706984)
		(end 302.671226 -76.706984)
		(width 0.1143)
		(layer "F.Cu")
		(net "P3E_CPU0_PE2_SS_RXP<13>")
	)
	(via
		(at 367.37036 -2.937002)
		(size 0.508)
		(drill 0.254)
		(layers "F.Cu" "B.Cu")
		(net "P3E_CPU0_PE2_SS_RXP<13>")
	)
	(via
		(at 302.671226 -76.706984)
		(size 0.508)
		(drill 0.254)
		(layers "F.Cu" "B.Cu")
		(net "P3E_CPU0_PE2_SS_RXP<13>")
	)
	(segment
		(start 313.013344 -65.019936)
		(end 309.264812 -74.069194)
		(width 0.1143)
		(layer "In4.Cu")
		(net "P3E_CPU0_PE2_SS_RXP<13>")
	)
	(segment
		(start 314.125102 -49.672494)
		(end 312.772552 -52.689506)
		(width 0.1143)
		(layer "In4.Cu")
		(net "P3E_CPU0_PE2_SS_RXP<13>")
	)
	(segment
		(start 303.864264 -76.753466)
		(end 303.641506 -76.792328)
		(width 0.0889)
		(layer "In4.Cu")
		(net "P3E_CPU0_PE2_SS_RXP<13>")
	)
	(segment
		(start 336.053684 -43.448732)
		(end 335.663286 -43.83913)
		(width 0.1143)
		(layer "In4.Cu")
		(net "P3E_CPU0_PE2_SS_RXP<13>")
	)
	(segment
		(start 312.992262 -53.919374)
		(end 312.784744 -54.962298)
		(width 0.1143)
		(layer "In4.Cu")
		(net "P3E_CPU0_PE2_SS_RXP<13>")
	)
	(segment
		(start 366.99571 -2.937002)
		(end 366.88141 -3.051302)
		(width 0.1143)
		(layer "In4.Cu")
		(net "P3E_CPU0_PE2_SS_RXP<13>")
	)
	(segment
		(start 309.264812 -74.069194)
		(end 307.453538 -76.123292)
		(width 0.1143)
		(layer "In4.Cu")
		(net "P3E_CPU0_PE2_SS_RXP<13>")
	)
	(segment
		(start 313.406282 -60.824364)
		(end 313.013344 -65.019936)
		(width 0.1143)
		(layer "In4.Cu")
		(net "P3E_CPU0_PE2_SS_RXP<13>")
	)
	(segment
		(start 305.307238 -76.428346)
		(end 305.129438 -76.428346)
		(width 0.0889)
		(layer "In4.Cu")
		(net "P3E_CPU0_PE2_SS_RXP<13>")
	)
	(segment
		(start 302.29937 -76.854812)
		(end 302.37811 -76.876148)
		(width 0.0889)
		(layer "In4.Cu")
		(net "P3E_CPU0_PE2_SS_RXP<13>")
	)
	(segment
		(start 351.843848 -37.61105)
		(end 342.528144 -37.61105)
		(width 0.1143)
		(layer "In4.Cu")
		(net "P3E_CPU0_PE2_SS_RXP<13>")
	)
	(segment
		(start 366.88141 -4.274566)
		(end 366.832388 -4.323588)
		(width 0.1143)
		(layer "In4.Cu")
		(net "P3E_CPU0_PE2_SS_RXP<13>")
	)
	(segment
		(start 306.144676 -76.327)
		(end 305.966876 -76.327)
		(width 0.0889)
		(layer "In4.Cu")
		(net "P3E_CPU0_PE2_SS_RXP<13>")
	)
	(segment
		(start 303.551336 -76.802488)
		(end 303.511966 -76.802488)
		(width 0.0889)
		(layer "In4.Cu")
		(net "P3E_CPU0_PE2_SS_RXP<13>")
	)
	(segment
		(start 342.413844 -37.72535)
		(end 342.413844 -41.078658)
		(width 0.1143)
		(layer "In4.Cu")
		(net "P3E_CPU0_PE2_SS_RXP<13>")
	)
	(segment
		(start 312.772552 -52.689506)
		(end 312.992262 -53.919374)
		(width 0.1143)
		(layer "In4.Cu")
		(net "P3E_CPU0_PE2_SS_RXP<13>")
	)
	(segment
		(start 357.247952 -33.70326)
		(end 353.10318 -36.46678)
		(width 0.1143)
		(layer "In4.Cu")
		(net "P3E_CPU0_PE2_SS_RXP<13>")
	)
	(segment
		(start 353.10318 -36.46678)
		(end 352.389186 -37.385752)
		(width 0.1143)
		(layer "In4.Cu")
		(net "P3E_CPU0_PE2_SS_RXP<13>")
	)
	(segment
		(start 366.88141 -3.051302)
		(end 366.88141 -4.274566)
		(width 0.1143)
		(layer "In4.Cu")
		(net "P3E_CPU0_PE2_SS_RXP<13>")
	)
	(segment
		(start 312.973212 -55.715154)
		(end 312.802778 -56.39054)
		(width 0.1143)
		(layer "In4.Cu")
		(net "P3E_CPU0_PE2_SS_RXP<13>")
	)
	(segment
		(start 306.83835 -76.3778)
		(end 306.816252 -76.3778)
		(width 0.0889)
		(layer "In4.Cu")
		(net "P3E_CPU0_PE2_SS_RXP<13>")
	)
	(segment
		(start 306.421536 -76.42606)
		(end 306.243736 -76.42606)
		(width 0.0889)
		(layer "In4.Cu")
		(net "P3E_CPU0_PE2_SS_RXP<13>")
	)
	(segment
		(start 365.818928 -9.403334)
		(end 362.250736 -26.199592)
		(width 0.1143)
		(layer "In4.Cu")
		(net "P3E_CPU0_PE2_SS_RXP<13>")
	)
	(segment
		(start 320.035174 -46.756066)
		(end 317.025782 -47.330614)
		(width 0.1143)
		(layer "In4.Cu")
		(net "P3E_CPU0_PE2_SS_RXP<13>")
	)
	(segment
		(start 362.250736 -26.199592)
		(end 357.247952 -33.70326)
		(width 0.1143)
		(layer "In4.Cu")
		(net "P3E_CPU0_PE2_SS_RXP<13>")
	)
	(segment
		(start 336.053684 -41.61917)
		(end 336.053684 -43.448732)
		(width 0.1143)
		(layer "In4.Cu")
		(net "P3E_CPU0_PE2_SS_RXP<13>")
	)
	(segment
		(start 307.453538 -76.123292)
		(end 307.00726 -76.3778)
		(width 0.1143)
		(layer "In4.Cu")
		(net "P3E_CPU0_PE2_SS_RXP<13>")
	)
	(segment
		(start 306.765452 -76.327)
		(end 306.520596 -76.327)
		(width 0.0889)
		(layer "In4.Cu")
		(net "P3E_CPU0_PE2_SS_RXP<13>")
	)
	(segment
		(start 304.292 -76.327)
		(end 303.866042 -76.753212)
		(width 0.0889)
		(layer "In4.Cu")
		(net "P3E_CPU0_PE2_SS_RXP<13>")
	)
	(segment
		(start 342.128602 -41.3639)
		(end 336.308954 -41.3639)
		(width 0.1143)
		(layer "In4.Cu")
		(net "P3E_CPU0_PE2_SS_RXP<13>")
	)
	(segment
		(start 367.37036 -2.937002)
		(end 366.99571 -2.937002)
		(width 0.1143)
		(layer "In4.Cu")
		(net "P3E_CPU0_PE2_SS_RXP<13>")
	)
	(segment
		(start 304.571146 -76.428346)
		(end 304.4698 -76.327)
		(width 0.0889)
		(layer "In4.Cu")
		(net "P3E_CPU0_PE2_SS_RXP<13>")
	)
	(segment
		(start 305.028092 -76.327)
		(end 304.850292 -76.327)
		(width 0.0889)
		(layer "In4.Cu")
		(net "P3E_CPU0_PE2_SS_RXP<13>")
	)
	(segment
		(start 366.49787 -4.825492)
		(end 365.700564 -8.811768)
		(width 0.1143)
		(layer "In4.Cu")
		(net "P3E_CPU0_PE2_SS_RXP<13>")
	)
	(segment
		(start 306.816252 -76.3778)
		(end 306.765452 -76.327)
		(width 0.0889)
		(layer "In4.Cu")
		(net "P3E_CPU0_PE2_SS_RXP<13>")
	)
	(segment
		(start 305.129438 -76.428346)
		(end 305.028092 -76.327)
		(width 0.0889)
		(layer "In4.Cu")
		(net "P3E_CPU0_PE2_SS_RXP<13>")
	)
	(segment
		(start 342.413844 -41.078658)
		(end 342.128602 -41.3639)
		(width 0.1143)
		(layer "In4.Cu")
		(net "P3E_CPU0_PE2_SS_RXP<13>")
	)
	(segment
		(start 306.243736 -76.42606)
		(end 306.144676 -76.327)
		(width 0.0889)
		(layer "In4.Cu")
		(net "P3E_CPU0_PE2_SS_RXP<13>")
	)
	(segment
		(start 302.37811 -76.876148)
		(end 302.671226 -76.706984)
		(width 0.0889)
		(layer "In4.Cu")
		(net "P3E_CPU0_PE2_SS_RXP<13>")
	)
	(segment
		(start 304.4698 -76.327)
		(end 304.292 -76.327)
		(width 0.0889)
		(layer "In4.Cu")
		(net "P3E_CPU0_PE2_SS_RXP<13>")
	)
	(segment
		(start 352.389186 -37.385752)
		(end 351.843848 -37.61105)
		(width 0.1143)
		(layer "In4.Cu")
		(net "P3E_CPU0_PE2_SS_RXP<13>")
	)
	(segment
		(start 317.025782 -47.330614)
		(end 314.125102 -49.672494)
		(width 0.1143)
		(layer "In4.Cu")
		(net "P3E_CPU0_PE2_SS_RXP<13>")
	)
	(segment
		(start 365.700564 -8.811768)
		(end 365.818928 -9.403334)
		(width 0.1143)
		(layer "In4.Cu")
		(net "P3E_CPU0_PE2_SS_RXP<13>")
	)
	(segment
		(start 305.68773 -76.428346)
		(end 305.586384 -76.327)
		(width 0.0889)
		(layer "In4.Cu")
		(net "P3E_CPU0_PE2_SS_RXP<13>")
	)
	(segment
		(start 304.850292 -76.327)
		(end 304.748946 -76.428346)
		(width 0.0889)
		(layer "In4.Cu")
		(net "P3E_CPU0_PE2_SS_RXP<13>")
	)
	(segment
		(start 366.832388 -4.323588)
		(end 366.49787 -4.825492)
		(width 0.1143)
		(layer "In4.Cu")
		(net "P3E_CPU0_PE2_SS_RXP<13>")
	)
	(segment
		(start 307.00726 -76.3778)
		(end 306.83835 -76.3778)
		(width 0.1143)
		(layer "In4.Cu")
		(net "P3E_CPU0_PE2_SS_RXP<13>")
	)
	(segment
		(start 335.663286 -43.83913)
		(end 324.87997 -47.253144)
		(width 0.1143)
		(layer "In4.Cu")
		(net "P3E_CPU0_PE2_SS_RXP<13>")
	)
	(segment
		(start 342.528144 -37.61105)
		(end 342.413844 -37.72535)
		(width 0.1143)
		(layer "In4.Cu")
		(net "P3E_CPU0_PE2_SS_RXP<13>")
	)
	(segment
		(start 303.641506 -76.792328)
		(end 303.639474 -76.792582)
		(width 0.0889)
		(layer "In4.Cu")
		(net "P3E_CPU0_PE2_SS_RXP<13>")
	)
	(segment
		(start 304.748946 -76.428346)
		(end 304.571146 -76.428346)
		(width 0.0889)
		(layer "In4.Cu")
		(net "P3E_CPU0_PE2_SS_RXP<13>")
	)
	(segment
		(start 324.87997 -47.253144)
		(end 320.035174 -46.756066)
		(width 0.1143)
		(layer "In4.Cu")
		(net "P3E_CPU0_PE2_SS_RXP<13>")
	)
	(segment
		(start 312.802778 -56.39054)
		(end 313.406282 -60.824364)
		(width 0.1143)
		(layer "In4.Cu")
		(net "P3E_CPU0_PE2_SS_RXP<13>")
	)
	(segment
		(start 305.408584 -76.327)
		(end 305.307238 -76.428346)
		(width 0.0889)
		(layer "In4.Cu")
		(net "P3E_CPU0_PE2_SS_RXP<13>")
	)
	(segment
		(start 336.308954 -41.3639)
		(end 336.053684 -41.61917)
		(width 0.1143)
		(layer "In4.Cu")
		(net "P3E_CPU0_PE2_SS_RXP<13>")
	)
	(segment
		(start 305.966876 -76.327)
		(end 305.86553 -76.428346)
		(width 0.0889)
		(layer "In4.Cu")
		(net "P3E_CPU0_PE2_SS_RXP<13>")
	)
	(segment
		(start 305.86553 -76.428346)
		(end 305.68773 -76.428346)
		(width 0.0889)
		(layer "In4.Cu")
		(net "P3E_CPU0_PE2_SS_RXP<13>")
	)
	(segment
		(start 312.784744 -54.962298)
		(end 312.973212 -55.715154)
		(width 0.1143)
		(layer "In4.Cu")
		(net "P3E_CPU0_PE2_SS_RXP<13>")
	)
	(segment
		(start 306.520596 -76.327)
		(end 306.421536 -76.42606)
		(width 0.0889)
		(layer "In4.Cu")
		(net "P3E_CPU0_PE2_SS_RXP<13>")
	)
	(segment
		(start 303.866042 -76.753212)
		(end 303.864264 -76.753466)
		(width 0.0889)
		(layer "In4.Cu")
		(net "P3E_CPU0_PE2_SS_RXP<13>")
	)
	(segment
		(start 305.586384 -76.327)
		(end 305.408584 -76.327)
		(width 0.0889)
		(layer "In4.Cu")
		(net "P3E_CPU0_PE2_SS_RXP<13>")
	)
	(arc
		(start 302.659288 -76.307188)
		(mid 302.336798 -76.487373)
		(end 302.29937 -76.854812)
		(width 0.0889)
		(layer "In4.Cu")
		(net "P3E_CPU0_PE2_SS_RXP<13>")
	)
	(arc
		(start 302.683418 -76.307188)
		(mid 302.671353 -76.30701)
		(end 302.659288 -76.307188)
		(width 0.0889)
		(layer "In4.Cu")
		(net "P3E_CPU0_PE2_SS_RXP<13>")
	)
	(arc
		(start 303.639474 -76.792582)
		(mid 303.595592 -76.799198)
		(end 303.551336 -76.802488)
		(width 0.0889)
		(layer "In4.Cu")
		(net "P3E_CPU0_PE2_SS_RXP<13>")
	)
	(arc
		(start 303.511966 -76.802488)
		(mid 303.226542 -76.719021)
		(end 303.017936 -76.507086)
		(width 0.0889)
		(layer "In4.Cu")
		(net "P3E_CPU0_PE2_SS_RXP<13>")
	)
	(arc
		(start 303.017936 -76.507086)
		(mid 302.876637 -76.363722)
		(end 302.683418 -76.307188)
		(width 0.0889)
		(layer "In4.Cu")
		(net "P3E_CPU0_PE2_SS_RXP<13>")
	)
	(segment
		(start 369.010692 -3.427984)
		(end 369.010692 -2.75336)
		(width 0.1143)
		(layer "F.Cu")
		(net "P3E_CPU0_PE2_SS_RXP<12>")
	)
	(segment
		(start 369.010692 -2.75336)
		(end 368.812064 -2.554732)
		(width 0.1143)
		(layer "F.Cu")
		(net "P3E_CPU0_PE2_SS_RXP<12>")
	)
	(segment
		(start 368.812064 -1.533906)
		(end 368.697764 -1.419606)
		(width 0.1143)
		(layer "F.Cu")
		(net "P3E_CPU0_PE2_SS_RXP<12>")
	)
	(segment
		(start 368.812064 -2.554732)
		(end 368.812064 -1.533906)
		(width 0.1143)
		(layer "F.Cu")
		(net "P3E_CPU0_PE2_SS_RXP<12>")
	)
	(segment
		(start 368.697764 -1.419606)
		(end 368.297714 -1.419606)
		(width 0.1143)
		(layer "F.Cu")
		(net "P3E_CPU0_PE2_SS_RXP<12>")
	)
	(segment
		(start 300.382686 -77.697584)
		(end 300.954186 -77.697584)
		(width 0.1143)
		(layer "F.Cu")
		(net "P3E_CPU0_PE2_SS_RXP<12>")
	)
	(segment
		(start 368.685064 -4.389882)
		(end 368.685064 -3.753612)
		(width 0.1143)
		(layer "F.Cu")
		(net "P3E_CPU0_PE2_SS_RXP<12>")
	)
	(segment
		(start 368.685064 -3.753612)
		(end 369.010692 -3.427984)
		(width 0.1143)
		(layer "F.Cu")
		(net "P3E_CPU0_PE2_SS_RXP<12>")
	)
	(via
		(at 300.954186 -77.697584)
		(size 0.508)
		(drill 0.254)
		(layers "F.Cu" "B.Cu")
		(net "P3E_CPU0_PE2_SS_RXP<12>")
	)
	(via
		(at 368.297714 -1.419606)
		(size 0.508)
		(drill 0.254)
		(layers "F.Cu" "B.Cu")
		(net "P3E_CPU0_PE2_SS_RXP<12>")
	)
	(segment
		(start 353.752404 -36.478464)
		(end 352.13417 -38.52164)
		(width 0.1143)
		(layer "In4.Cu")
		(net "P3E_CPU0_PE2_SS_RXP<12>")
	)
	(segment
		(start 367.959132 -7.225792)
		(end 367.868962 -7.5565)
		(width 0.1143)
		(layer "In4.Cu")
		(net "P3E_CPU0_PE2_SS_RXP<12>")
	)
	(segment
		(start 352.13417 -38.52164)
		(end 351.971864 -38.58895)
		(width 0.1143)
		(layer "In4.Cu")
		(net "P3E_CPU0_PE2_SS_RXP<12>")
	)
	(segment
		(start 368.13617 -6.576314)
		(end 368.252248 -6.779006)
		(width 0.1143)
		(layer "In4.Cu")
		(net "P3E_CPU0_PE2_SS_RXP<12>")
	)
	(segment
		(start 339.211158 -44.117006)
		(end 337.2231 -43.711876)
		(width 0.1143)
		(layer "In4.Cu")
		(net "P3E_CPU0_PE2_SS_RXP<12>")
	)
	(segment
		(start 309.353712 -74.753724)
		(end 307.64861 -76.593446)
		(width 0.1143)
		(layer "In4.Cu")
		(net "P3E_CPU0_PE2_SS_RXP<12>")
	)
	(segment
		(start 340.868 -43.710606)
		(end 340.780878 -43.797728)
		(width 0.1143)
		(layer "In4.Cu")
		(net "P3E_CPU0_PE2_SS_RXP<12>")
	)
	(segment
		(start 313.19089 -56.35752)
		(end 313.813444 -60.627006)
		(width 0.1143)
		(layer "In4.Cu")
		(net "P3E_CPU0_PE2_SS_RXP<12>")
	)
	(segment
		(start 307.64861 -76.593446)
		(end 306.8955 -76.9747)
		(width 0.1143)
		(layer "In4.Cu")
		(net "P3E_CPU0_PE2_SS_RXP<12>")
	)
	(segment
		(start 368.786664 -1.523746)
		(end 368.786664 -4.818634)
		(width 0.1143)
		(layer "In4.Cu")
		(net "P3E_CPU0_PE2_SS_RXP<12>")
	)
	(segment
		(start 368.696494 -5.149342)
		(end 368.493802 -5.26542)
		(width 0.1143)
		(layer "In4.Cu")
		(net "P3E_CPU0_PE2_SS_RXP<12>")
	)
	(segment
		(start 368.162078 -7.109968)
		(end 367.959132 -7.225792)
		(width 0.1143)
		(layer "In4.Cu")
		(net "P3E_CPU0_PE2_SS_RXP<12>")
	)
	(segment
		(start 366.00384 -10.453116)
		(end 362.610908 -26.313384)
		(width 0.1143)
		(layer "In4.Cu")
		(net "P3E_CPU0_PE2_SS_RXP<12>")
	)
	(segment
		(start 313.813444 -60.627006)
		(end 313.406536 -64.967612)
		(width 0.1143)
		(layer "In4.Cu")
		(net "P3E_CPU0_PE2_SS_RXP<12>")
	)
	(segment
		(start 313.135264 -52.755038)
		(end 313.34329 -53.922676)
		(width 0.1143)
		(layer "In4.Cu")
		(net "P3E_CPU0_PE2_SS_RXP<12>")
	)
	(segment
		(start 362.610908 -26.313384)
		(end 357.499666 -33.980374)
		(width 0.1143)
		(layer "In4.Cu")
		(net "P3E_CPU0_PE2_SS_RXP<12>")
	)
	(segment
		(start 317.39205 -47.61484)
		(end 314.332874 -50.083466)
		(width 0.1143)
		(layer "In4.Cu")
		(net "P3E_CPU0_PE2_SS_RXP<12>")
	)
	(segment
		(start 367.868962 -7.5565)
		(end 367.984786 -7.759192)
		(width 0.1143)
		(layer "In4.Cu")
		(net "P3E_CPU0_PE2_SS_RXP<12>")
	)
	(segment
		(start 340.868 -42.7482)
		(end 340.868 -43.710606)
		(width 0.1143)
		(layer "In4.Cu")
		(net "P3E_CPU0_PE2_SS_RXP<12>")
	)
	(segment
		(start 313.34329 -55.751222)
		(end 313.19089 -56.35752)
		(width 0.1143)
		(layer "In4.Cu")
		(net "P3E_CPU0_PE2_SS_RXP<12>")
	)
	(segment
		(start 303.547526 -77.602588)
		(end 303.517808 -77.602588)
		(width 0.0889)
		(layer "In4.Cu")
		(net "P3E_CPU0_PE2_SS_RXP<12>")
	)
	(segment
		(start 368.403632 -5.596128)
		(end 368.519456 -5.79882)
		(width 0.1143)
		(layer "In4.Cu")
		(net "P3E_CPU0_PE2_SS_RXP<12>")
	)
	(segment
		(start 343.827608 -38.58895)
		(end 343.468198 -38.94836)
		(width 0.1143)
		(layer "In4.Cu")
		(net "P3E_CPU0_PE2_SS_RXP<12>")
	)
	(segment
		(start 357.499666 -33.980374)
		(end 353.752404 -36.478464)
		(width 0.1143)
		(layer "In4.Cu")
		(net "P3E_CPU0_PE2_SS_RXP<12>")
	)
	(segment
		(start 324.92569 -47.604172)
		(end 320.058034 -47.104808)
		(width 0.1143)
		(layer "In4.Cu")
		(net "P3E_CPU0_PE2_SS_RXP<12>")
	)
	(segment
		(start 313.406536 -64.967612)
		(end 309.353712 -74.753724)
		(width 0.1143)
		(layer "In4.Cu")
		(net "P3E_CPU0_PE2_SS_RXP<12>")
	)
	(segment
		(start 337.2231 -43.711876)
		(end 324.92569 -47.604172)
		(width 0.1143)
		(layer "In4.Cu")
		(net "P3E_CPU0_PE2_SS_RXP<12>")
	)
	(segment
		(start 313.34329 -53.922676)
		(end 313.140598 -54.94401)
		(width 0.1143)
		(layer "In4.Cu")
		(net "P3E_CPU0_PE2_SS_RXP<12>")
	)
	(segment
		(start 368.297714 -1.419606)
		(end 368.300762 -1.422654)
		(width 0.1143)
		(layer "In4.Cu")
		(net "P3E_CPU0_PE2_SS_RXP<12>")
	)
	(segment
		(start 306.8955 -76.9747)
		(end 306.621434 -76.9747)
		(width 0.1143)
		(layer "In4.Cu")
		(net "P3E_CPU0_PE2_SS_RXP<12>")
	)
	(segment
		(start 343.468198 -38.94836)
		(end 343.468198 -42.154602)
		(width 0.1143)
		(layer "In4.Cu")
		(net "P3E_CPU0_PE2_SS_RXP<12>")
	)
	(segment
		(start 303.931574 -77.433932)
		(end 303.931574 -77.433678)
		(width 0.0889)
		(layer "In4.Cu")
		(net "P3E_CPU0_PE2_SS_RXP<12>")
	)
	(segment
		(start 368.519456 -5.79882)
		(end 368.429286 -6.129782)
		(width 0.1143)
		(layer "In4.Cu")
		(net "P3E_CPU0_PE2_SS_RXP<12>")
	)
	(segment
		(start 367.984786 -7.759192)
		(end 367.583212 -9.232392)
		(width 0.1143)
		(layer "In4.Cu")
		(net "P3E_CPU0_PE2_SS_RXP<12>")
	)
	(segment
		(start 368.226594 -6.245606)
		(end 368.13617 -6.576314)
		(width 0.1143)
		(layer "In4.Cu")
		(net "P3E_CPU0_PE2_SS_RXP<12>")
	)
	(segment
		(start 368.252248 -6.779006)
		(end 368.162078 -7.109968)
		(width 0.1143)
		(layer "In4.Cu")
		(net "P3E_CPU0_PE2_SS_RXP<12>")
	)
	(segment
		(start 367.583212 -9.232392)
		(end 366.00384 -10.453116)
		(width 0.1143)
		(layer "In4.Cu")
		(net "P3E_CPU0_PE2_SS_RXP<12>")
	)
	(segment
		(start 340.780878 -43.797728)
		(end 339.211158 -44.117006)
		(width 0.1143)
		(layer "In4.Cu")
		(net "P3E_CPU0_PE2_SS_RXP<12>")
	)
	(segment
		(start 343.468198 -42.154602)
		(end 343.2048 -42.418)
		(width 0.1143)
		(layer "In4.Cu")
		(net "P3E_CPU0_PE2_SS_RXP<12>")
	)
	(segment
		(start 368.685572 -1.422654)
		(end 368.786664 -1.523746)
		(width 0.1143)
		(layer "In4.Cu")
		(net "P3E_CPU0_PE2_SS_RXP<12>")
	)
	(segment
		(start 368.493802 -5.26542)
		(end 368.403632 -5.596128)
		(width 0.1143)
		(layer "In4.Cu")
		(net "P3E_CPU0_PE2_SS_RXP<12>")
	)
	(segment
		(start 306.599336 -76.9747)
		(end 306.548536 -77.0255)
		(width 0.0889)
		(layer "In4.Cu")
		(net "P3E_CPU0_PE2_SS_RXP<12>")
	)
	(segment
		(start 320.058034 -47.104808)
		(end 317.39205 -47.61484)
		(width 0.1143)
		(layer "In4.Cu")
		(net "P3E_CPU0_PE2_SS_RXP<12>")
	)
	(segment
		(start 343.2048 -42.418)
		(end 341.1982 -42.418)
		(width 0.1143)
		(layer "In4.Cu")
		(net "P3E_CPU0_PE2_SS_RXP<12>")
	)
	(segment
		(start 301.33671 -77.842618)
		(end 301.247302 -77.866748)
		(width 0.0889)
		(layer "In4.Cu")
		(net "P3E_CPU0_PE2_SS_RXP<12>")
	)
	(segment
		(start 301.823882 -77.602588)
		(end 301.791116 -77.602588)
		(width 0.0889)
		(layer "In4.Cu")
		(net "P3E_CPU0_PE2_SS_RXP<12>")
	)
	(segment
		(start 306.548536 -77.0255)
		(end 304.340006 -77.0255)
		(width 0.0889)
		(layer "In4.Cu")
		(net "P3E_CPU0_PE2_SS_RXP<12>")
	)
	(segment
		(start 301.247302 -77.866748)
		(end 300.954186 -77.697584)
		(width 0.0889)
		(layer "In4.Cu")
		(net "P3E_CPU0_PE2_SS_RXP<12>")
	)
	(segment
		(start 313.140598 -54.94401)
		(end 313.34329 -55.751222)
		(width 0.1143)
		(layer "In4.Cu")
		(net "P3E_CPU0_PE2_SS_RXP<12>")
	)
	(segment
		(start 304.340006 -77.0255)
		(end 303.931574 -77.433932)
		(width 0.0889)
		(layer "In4.Cu")
		(net "P3E_CPU0_PE2_SS_RXP<12>")
	)
	(segment
		(start 306.621434 -76.9747)
		(end 306.599336 -76.9747)
		(width 0.0889)
		(layer "In4.Cu")
		(net "P3E_CPU0_PE2_SS_RXP<12>")
	)
	(segment
		(start 368.429286 -6.129782)
		(end 368.226594 -6.245606)
		(width 0.1143)
		(layer "In4.Cu")
		(net "P3E_CPU0_PE2_SS_RXP<12>")
	)
	(segment
		(start 351.971864 -38.58895)
		(end 343.827608 -38.58895)
		(width 0.1143)
		(layer "In4.Cu")
		(net "P3E_CPU0_PE2_SS_RXP<12>")
	)
	(segment
		(start 314.332874 -50.083466)
		(end 313.135264 -52.755038)
		(width 0.1143)
		(layer "In4.Cu")
		(net "P3E_CPU0_PE2_SS_RXP<12>")
	)
	(segment
		(start 368.300762 -1.422654)
		(end 368.685572 -1.422654)
		(width 0.1143)
		(layer "In4.Cu")
		(net "P3E_CPU0_PE2_SS_RXP<12>")
	)
	(segment
		(start 368.786664 -4.818634)
		(end 368.696494 -5.149342)
		(width 0.1143)
		(layer "In4.Cu")
		(net "P3E_CPU0_PE2_SS_RXP<12>")
	)
	(segment
		(start 341.1982 -42.418)
		(end 340.868 -42.7482)
		(width 0.1143)
		(layer "In4.Cu")
		(net "P3E_CPU0_PE2_SS_RXP<12>")
	)
	(arc
		(start 301.791116 -77.602588)
		(mid 301.536451 -77.670617)
		(end 301.33671 -77.842618)
		(width 0.0889)
		(layer "In4.Cu")
		(net "P3E_CPU0_PE2_SS_RXP<12>")
	)
	(arc
		(start 303.517808 -77.602588)
		(mid 303.324382 -77.546061)
		(end 303.183036 -77.402436)
		(width 0.0889)
		(layer "In4.Cu")
		(net "P3E_CPU0_PE2_SS_RXP<12>")
	)
	(arc
		(start 302.159416 -77.402436)
		(mid 302.017733 -77.54624)
		(end 301.823882 -77.602588)
		(width 0.0889)
		(layer "In4.Cu")
		(net "P3E_CPU0_PE2_SS_RXP<12>")
	)
	(arc
		(start 303.183036 -77.402436)
		(mid 302.671226 -77.106769)
		(end 302.159416 -77.402436)
		(width 0.0889)
		(layer "In4.Cu")
		(net "P3E_CPU0_PE2_SS_RXP<12>")
	)
	(arc
		(start 303.931574 -77.433678)
		(mid 303.755443 -77.554285)
		(end 303.547526 -77.602588)
		(width 0.0889)
		(layer "In4.Cu")
		(net "P3E_CPU0_PE2_SS_RXP<12>")
	)
	(segment
		(start 371.362732 -3.051556)
		(end 371.248178 -2.937002)
		(width 0.1143)
		(layer "F.Cu")
		(net "P3E_CPU0_PE2_SS_RXP<11>")
	)
	(segment
		(start 371.248178 -2.937002)
		(end 370.900198 -2.937002)
		(width 0.1143)
		(layer "F.Cu")
		(net "P3E_CPU0_PE2_SS_RXP<11>")
	)
	(segment
		(start 371.08511 -3.708146)
		(end 371.362732 -3.430524)
		(width 0.1143)
		(layer "F.Cu")
		(net "P3E_CPU0_PE2_SS_RXP<11>")
	)
	(segment
		(start 371.362732 -3.430524)
		(end 371.362732 -3.051556)
		(width 0.1143)
		(layer "F.Cu")
		(net "P3E_CPU0_PE2_SS_RXP<11>")
	)
	(segment
		(start 371.08511 -4.389882)
		(end 371.08511 -3.708146)
		(width 0.1143)
		(layer "F.Cu")
		(net "P3E_CPU0_PE2_SS_RXP<11>")
	)
	(segment
		(start 302.099726 -77.697584)
		(end 302.671226 -77.697584)
		(width 0.1143)
		(layer "F.Cu")
		(net "P3E_CPU0_PE2_SS_RXP<11>")
	)
	(via
		(at 302.671226 -77.697584)
		(size 0.508)
		(drill 0.254)
		(layers "F.Cu" "B.Cu")
		(net "P3E_CPU0_PE2_SS_RXP<11>")
	)
	(via
		(at 370.900198 -2.937002)
		(size 0.508)
		(drill 0.254)
		(layers "F.Cu" "B.Cu")
		(net "P3E_CPU0_PE2_SS_RXP<11>")
	)
	(segment
		(start 367.983516 -10.65022)
		(end 367.95202 -10.881614)
		(width 0.1143)
		(layer "In4.Cu")
		(net "P3E_CPU0_PE2_SS_RXP<11>")
	)
	(segment
		(start 302.736504 -78.100936)
		(end 302.671226 -78.035658)
		(width 0.0889)
		(layer "In4.Cu")
		(net "P3E_CPU0_PE2_SS_RXP<11>")
	)
	(segment
		(start 370.55044 -5.281168)
		(end 370.643404 -5.49529)
		(width 0.1143)
		(layer "In4.Cu")
		(net "P3E_CPU0_PE2_SS_RXP<11>")
	)
	(segment
		(start 303.526444 -78.593696)
		(end 303.515014 -78.593188)
		(width 0.0889)
		(layer "In4.Cu")
		(net "P3E_CPU0_PE2_SS_RXP<11>")
	)
	(segment
		(start 363.26826 -26.495756)
		(end 357.980234 -34.428176)
		(width 0.1143)
		(layer "In4.Cu")
		(net "P3E_CPU0_PE2_SS_RXP<11>")
	)
	(segment
		(start 314.471558 -60.413138)
		(end 314.006992 -65.370202)
		(width 0.1143)
		(layer "In4.Cu")
		(net "P3E_CPU0_PE2_SS_RXP<11>")
	)
	(segment
		(start 370.643404 -5.49529)
		(end 370.638324 -5.51053)
		(width 0.1143)
		(layer "In4.Cu")
		(net "P3E_CPU0_PE2_SS_RXP<11>")
	)
	(segment
		(start 371.263418 -3.924046)
		(end 371.049042 -4.01701)
		(width 0.1143)
		(layer "In4.Cu")
		(net "P3E_CPU0_PE2_SS_RXP<11>")
	)
	(segment
		(start 357.980234 -34.428176)
		(end 354.510848 -36.740846)
		(width 0.1143)
		(layer "In4.Cu")
		(net "P3E_CPU0_PE2_SS_RXP<11>")
	)
	(segment
		(start 371.049042 -4.01701)
		(end 370.923312 -4.336034)
		(width 0.1143)
		(layer "In4.Cu")
		(net "P3E_CPU0_PE2_SS_RXP<11>")
	)
	(segment
		(start 345.147646 -39.85895)
		(end 344.712036 -40.29456)
		(width 0.1143)
		(layer "In4.Cu")
		(net "P3E_CPU0_PE2_SS_RXP<11>")
	)
	(segment
		(start 314.006738 -55.745888)
		(end 313.84875 -56.372252)
		(width 0.1143)
		(layer "In4.Cu")
		(net "P3E_CPU0_PE2_SS_RXP<11>")
	)
	(segment
		(start 371.274848 -2.937002)
		(end 371.389148 -3.051302)
		(width 0.1143)
		(layer "In4.Cu")
		(net "P3E_CPU0_PE2_SS_RXP<11>")
	)
	(segment
		(start 306.5018 -78.097888)
		(end 304.366676 -78.097888)
		(width 0.0889)
		(layer "In4.Cu")
		(net "P3E_CPU0_PE2_SS_RXP<11>")
	)
	(segment
		(start 351.888298 -39.85895)
		(end 345.147646 -39.85895)
		(width 0.1143)
		(layer "In4.Cu")
		(net "P3E_CPU0_PE2_SS_RXP<11>")
	)
	(segment
		(start 370.890546 -4.86918)
		(end 370.676424 -4.962144)
		(width 0.1143)
		(layer "In4.Cu")
		(net "P3E_CPU0_PE2_SS_RXP<11>")
	)
	(segment
		(start 344.549476 -44.181014)
		(end 344.289634 -44.573444)
		(width 0.1143)
		(layer "In4.Cu")
		(net "P3E_CPU0_PE2_SS_RXP<11>")
	)
	(segment
		(start 371.016276 -4.550156)
		(end 370.890546 -4.86918)
		(width 0.1143)
		(layer "In4.Cu")
		(net "P3E_CPU0_PE2_SS_RXP<11>")
	)
	(segment
		(start 344.712036 -40.29456)
		(end 344.712036 -43.3832)
		(width 0.1143)
		(layer "In4.Cu")
		(net "P3E_CPU0_PE2_SS_RXP<11>")
	)
	(segment
		(start 337.198462 -44.393866)
		(end 331.032358 -46.34484)
		(width 0.1143)
		(layer "In4.Cu")
		(net "P3E_CPU0_PE2_SS_RXP<11>")
	)
	(segment
		(start 370.900198 -2.937002)
		(end 371.274848 -2.937002)
		(width 0.1143)
		(layer "In4.Cu")
		(net "P3E_CPU0_PE2_SS_RXP<11>")
	)
	(segment
		(start 344.712036 -43.3832)
		(end 344.549476 -44.181014)
		(width 0.1143)
		(layer "In4.Cu")
		(net "P3E_CPU0_PE2_SS_RXP<11>")
	)
	(segment
		(start 370.923312 -4.336034)
		(end 371.016276 -4.550156)
		(width 0.1143)
		(layer "In4.Cu")
		(net "P3E_CPU0_PE2_SS_RXP<11>")
	)
	(segment
		(start 324.99554 -48.255682)
		(end 320.079116 -47.752254)
		(width 0.1143)
		(layer "In4.Cu")
		(net "P3E_CPU0_PE2_SS_RXP<11>")
	)
	(segment
		(start 331.032358 -46.345348)
		(end 324.99554 -48.255682)
		(width 0.1143)
		(layer "In4.Cu")
		(net "P3E_CPU0_PE2_SS_RXP<11>")
	)
	(segment
		(start 313.798204 -52.840382)
		(end 313.992514 -53.92928)
		(width 0.1143)
		(layer "In4.Cu")
		(net "P3E_CPU0_PE2_SS_RXP<11>")
	)
	(segment
		(start 313.84875 -56.372252)
		(end 314.471558 -60.413138)
		(width 0.1143)
		(layer "In4.Cu")
		(net "P3E_CPU0_PE2_SS_RXP<11>")
	)
	(segment
		(start 368.48796 -10.474452)
		(end 368.256566 -10.442702)
		(width 0.1143)
		(layer "In4.Cu")
		(net "P3E_CPU0_PE2_SS_RXP<11>")
	)
	(segment
		(start 367.447576 -11.057382)
		(end 367.174526 -11.2649)
		(width 0.1143)
		(layer "In4.Cu")
		(net "P3E_CPU0_PE2_SS_RXP<11>")
	)
	(segment
		(start 367.14303 -11.496294)
		(end 366.347756 -12.100306)
		(width 0.1143)
		(layer "In4.Cu")
		(net "P3E_CPU0_PE2_SS_RXP<11>")
	)
	(segment
		(start 306.5526 -78.047088)
		(end 306.5018 -78.097888)
		(width 0.0889)
		(layer "In4.Cu")
		(net "P3E_CPU0_PE2_SS_RXP<11>")
	)
	(segment
		(start 341.489538 -44.34078)
		(end 339.210904 -44.804076)
		(width 0.1143)
		(layer "In4.Cu")
		(net "P3E_CPU0_PE2_SS_RXP<11>")
	)
	(segment
		(start 352.10623 -39.76116)
		(end 351.888298 -39.85895)
		(width 0.1143)
		(layer "In4.Cu")
		(net "P3E_CPU0_PE2_SS_RXP<11>")
	)
	(segment
		(start 314.006992 -65.370202)
		(end 309.992014 -75.063096)
		(width 0.1143)
		(layer "In4.Cu")
		(net "P3E_CPU0_PE2_SS_RXP<11>")
	)
	(segment
		(start 320.079116 -47.752254)
		(end 317.816738 -48.185324)
		(width 0.1143)
		(layer "In4.Cu")
		(net "P3E_CPU0_PE2_SS_RXP<11>")
	)
	(segment
		(start 371.389148 -3.051302)
		(end 371.389148 -3.605022)
		(width 0.1143)
		(layer "In4.Cu")
		(net "P3E_CPU0_PE2_SS_RXP<11>")
	)
	(segment
		(start 344.289634 -44.573444)
		(end 343.575386 -44.76496)
		(width 0.1143)
		(layer "In4.Cu")
		(net "P3E_CPU0_PE2_SS_RXP<11>")
	)
	(segment
		(start 343.575386 -44.76496)
		(end 341.489538 -44.34078)
		(width 0.1143)
		(layer "In4.Cu")
		(net "P3E_CPU0_PE2_SS_RXP<11>")
	)
	(segment
		(start 366.347756 -12.100306)
		(end 363.26826 -26.495756)
		(width 0.1143)
		(layer "In4.Cu")
		(net "P3E_CPU0_PE2_SS_RXP<11>")
	)
	(segment
		(start 368.76101 -10.266934)
		(end 368.48796 -10.474452)
		(width 0.1143)
		(layer "In4.Cu")
		(net "P3E_CPU0_PE2_SS_RXP<11>")
	)
	(segment
		(start 314.78982 -50.629058)
		(end 313.798204 -52.840382)
		(width 0.1143)
		(layer "In4.Cu")
		(net "P3E_CPU0_PE2_SS_RXP<11>")
	)
	(segment
		(start 370.638324 -5.51053)
		(end 368.761264 -10.266172)
		(width 0.1143)
		(layer "In4.Cu")
		(net "P3E_CPU0_PE2_SS_RXP<11>")
	)
	(segment
		(start 370.676424 -4.962144)
		(end 370.55044 -5.281168)
		(width 0.1143)
		(layer "In4.Cu")
		(net "P3E_CPU0_PE2_SS_RXP<11>")
	)
	(segment
		(start 302.671226 -78.035658)
		(end 302.671226 -77.697584)
		(width 0.0889)
		(layer "In4.Cu")
		(net "P3E_CPU0_PE2_SS_RXP<11>")
	)
	(segment
		(start 368.256566 -10.442702)
		(end 367.983516 -10.65022)
		(width 0.1143)
		(layer "In4.Cu")
		(net "P3E_CPU0_PE2_SS_RXP<11>")
	)
	(segment
		(start 317.816738 -48.185324)
		(end 314.78982 -50.629058)
		(width 0.1143)
		(layer "In4.Cu")
		(net "P3E_CPU0_PE2_SS_RXP<11>")
	)
	(segment
		(start 331.032358 -46.34484)
		(end 331.032358 -46.345348)
		(width 0.1143)
		(layer "In4.Cu")
		(net "P3E_CPU0_PE2_SS_RXP<11>")
	)
	(segment
		(start 339.210904 -44.804076)
		(end 337.198462 -44.393866)
		(width 0.1143)
		(layer "In4.Cu")
		(net "P3E_CPU0_PE2_SS_RXP<11>")
	)
	(segment
		(start 303.544478 -78.593188)
		(end 303.533048 -78.593696)
		(width 0.0889)
		(layer "In4.Cu")
		(net "P3E_CPU0_PE2_SS_RXP<11>")
	)
	(segment
		(start 313.79668 -54.913022)
		(end 314.006738 -55.745888)
		(width 0.1143)
		(layer "In4.Cu")
		(net "P3E_CPU0_PE2_SS_RXP<11>")
	)
	(segment
		(start 368.761264 -10.266172)
		(end 368.76101 -10.266934)
		(width 0.1143)
		(layer "In4.Cu")
		(net "P3E_CPU0_PE2_SS_RXP<11>")
	)
	(segment
		(start 308.100222 -77.368146)
		(end 307.084476 -78.047088)
		(width 0.1143)
		(layer "In4.Cu")
		(net "P3E_CPU0_PE2_SS_RXP<11>")
	)
	(segment
		(start 309.992014 -75.063096)
		(end 308.100222 -77.368146)
		(width 0.1143)
		(layer "In4.Cu")
		(net "P3E_CPU0_PE2_SS_RXP<11>")
	)
	(segment
		(start 367.95202 -10.881614)
		(end 367.67897 -11.089132)
		(width 0.1143)
		(layer "In4.Cu")
		(net "P3E_CPU0_PE2_SS_RXP<11>")
	)
	(segment
		(start 306.574698 -78.047088)
		(end 306.5526 -78.047088)
		(width 0.0889)
		(layer "In4.Cu")
		(net "P3E_CPU0_PE2_SS_RXP<11>")
	)
	(segment
		(start 307.084476 -78.047088)
		(end 306.574698 -78.047088)
		(width 0.1143)
		(layer "In4.Cu")
		(net "P3E_CPU0_PE2_SS_RXP<11>")
	)
	(segment
		(start 354.510848 -36.740846)
		(end 352.10623 -39.76116)
		(width 0.1143)
		(layer "In4.Cu")
		(net "P3E_CPU0_PE2_SS_RXP<11>")
	)
	(segment
		(start 367.174526 -11.2649)
		(end 367.14303 -11.496294)
		(width 0.1143)
		(layer "In4.Cu")
		(net "P3E_CPU0_PE2_SS_RXP<11>")
	)
	(segment
		(start 313.992514 -53.92928)
		(end 313.79668 -54.913022)
		(width 0.1143)
		(layer "In4.Cu")
		(net "P3E_CPU0_PE2_SS_RXP<11>")
	)
	(segment
		(start 371.389148 -3.605022)
		(end 371.263418 -3.924046)
		(width 0.1143)
		(layer "In4.Cu")
		(net "P3E_CPU0_PE2_SS_RXP<11>")
	)
	(segment
		(start 367.67897 -11.089132)
		(end 367.447576 -11.057382)
		(width 0.1143)
		(layer "In4.Cu")
		(net "P3E_CPU0_PE2_SS_RXP<11>")
	)
	(arc
		(start 303.876456 -78.393036)
		(mid 303.73633 -78.536012)
		(end 303.544478 -78.593188)
		(width 0.0889)
		(layer "In4.Cu")
		(net "P3E_CPU0_PE2_SS_RXP<11>")
	)
	(arc
		(start 303.515014 -78.593188)
		(mid 303.32317 -78.536)
		(end 303.183036 -78.393036)
		(width 0.0889)
		(layer "In4.Cu")
		(net "P3E_CPU0_PE2_SS_RXP<11>")
	)
	(arc
		(start 303.183036 -78.393036)
		(mid 302.994613 -78.193732)
		(end 302.736504 -78.100936)
		(width 0.0889)
		(layer "In4.Cu")
		(net "P3E_CPU0_PE2_SS_RXP<11>")
	)
	(arc
		(start 304.366676 -78.097888)
		(mid 304.083459 -78.182169)
		(end 303.876456 -78.393036)
		(width 0.0889)
		(layer "In4.Cu")
		(net "P3E_CPU0_PE2_SS_RXP<11>")
	)
	(arc
		(start 303.533048 -78.593696)
		(mid 303.529746 -78.593757)
		(end 303.526444 -78.593696)
		(width 0.0889)
		(layer "In4.Cu")
		(net "P3E_CPU0_PE2_SS_RXP<11>")
	)
	(segment
		(start 373.738902 -3.448304)
		(end 373.738902 -1.533906)
		(width 0.1143)
		(layer "F.Cu")
		(net "P3E_CPU0_PE2_SS_RXP<10>")
	)
	(segment
		(start 373.624602 -1.419606)
		(end 373.224552 -1.419606)
		(width 0.1143)
		(layer "F.Cu")
		(net "P3E_CPU0_PE2_SS_RXP<10>")
	)
	(segment
		(start 373.738902 -1.533906)
		(end 373.624602 -1.419606)
		(width 0.1143)
		(layer "F.Cu")
		(net "P3E_CPU0_PE2_SS_RXP<10>")
	)
	(segment
		(start 373.485156 -4.389882)
		(end 373.485156 -3.70205)
		(width 0.1143)
		(layer "F.Cu")
		(net "P3E_CPU0_PE2_SS_RXP<10>")
	)
	(segment
		(start 303.529746 -79.183738)
		(end 302.958246 -79.183738)
		(width 0.1143)
		(layer "F.Cu")
		(net "P3E_CPU0_PE2_SS_RXP<10>")
	)
	(segment
		(start 373.485156 -3.70205)
		(end 373.738902 -3.448304)
		(width 0.1143)
		(layer "F.Cu")
		(net "P3E_CPU0_PE2_SS_RXP<10>")
	)
	(via
		(at 303.529746 -79.183738)
		(size 0.508)
		(drill 0.254)
		(layers "F.Cu" "B.Cu")
		(net "P3E_CPU0_PE2_SS_RXP<10>")
	)
	(via
		(at 373.224552 -1.419606)
		(size 0.508)
		(drill 0.254)
		(layers "F.Cu" "B.Cu")
		(net "P3E_CPU0_PE2_SS_RXP<10>")
	)
	(segment
		(start 366.94364 -12.512548)
		(end 363.91088 -26.687526)
		(width 0.1143)
		(layer "In4.Cu")
		(net "P3E_CPU0_PE2_SS_RXP<10>")
	)
	(segment
		(start 322.624704 -52.643786)
		(end 315.957712 -62.33668)
		(width 0.1143)
		(layer "In4.Cu")
		(net "P3E_CPU0_PE2_SS_RXP<10>")
	)
	(segment
		(start 345.28379 -45.064172)
		(end 343.670382 -45.496734)
		(width 0.1143)
		(layer "In4.Cu")
		(net "P3E_CPU0_PE2_SS_RXP<10>")
	)
	(segment
		(start 314.92063 -64.83858)
		(end 310.463692 -75.599544)
		(width 0.1143)
		(layer "In4.Cu")
		(net "P3E_CPU0_PE2_SS_RXP<10>")
	)
	(segment
		(start 372.99519 -5.159248)
		(end 372.994936 -5.392674)
		(width 0.1143)
		(layer "In4.Cu")
		(net "P3E_CPU0_PE2_SS_RXP<10>")
	)
	(segment
		(start 373.237506 -4.916932)
		(end 372.99519 -5.159248)
		(width 0.1143)
		(layer "In4.Cu")
		(net "P3E_CPU0_PE2_SS_RXP<10>")
	)
	(segment
		(start 310.463692 -75.599544)
		(end 308.83225 -77.587602)
		(width 0.1143)
		(layer "In4.Cu")
		(net "P3E_CPU0_PE2_SS_RXP<10>")
	)
	(segment
		(start 373.224552 -1.419606)
		(end 373.599202 -1.419606)
		(width 0.1143)
		(layer "In4.Cu")
		(net "P3E_CPU0_PE2_SS_RXP<10>")
	)
	(segment
		(start 373.713502 -1.533906)
		(end 373.713502 -4.674362)
		(width 0.1143)
		(layer "In4.Cu")
		(net "P3E_CPU0_PE2_SS_RXP<10>")
	)
	(segment
		(start 370.374418 -8.013192)
		(end 369.349274 -10.644632)
		(width 0.1143)
		(layer "In4.Cu")
		(net "P3E_CPU0_PE2_SS_RXP<10>")
	)
	(segment
		(start 305.338734 -78.986888)
		(end 305.237388 -79.088234)
		(width 0.0889)
		(layer "In4.Cu")
		(net "P3E_CPU0_PE2_SS_RXP<10>")
	)
	(segment
		(start 337.209384 -45.06341)
		(end 329.107038 -47.62627)
		(width 0.1143)
		(layer "In4.Cu")
		(net "P3E_CPU0_PE2_SS_RXP<10>")
	)
	(segment
		(start 355.24567 -37.051234)
		(end 354.017834 -38.59403)
		(width 0.1143)
		(layer "In4.Cu")
		(net "P3E_CPU0_PE2_SS_RXP<10>")
	)
	(segment
		(start 304.780442 -78.986888)
		(end 304.679096 -79.088234)
		(width 0.0889)
		(layer "In4.Cu")
		(net "P3E_CPU0_PE2_SS_RXP<10>")
	)
	(segment
		(start 343.670382 -45.496734)
		(end 341.427054 -45.040296)
		(width 0.1143)
		(layer "In4.Cu")
		(net "P3E_CPU0_PE2_SS_RXP<10>")
	)
	(segment
		(start 315.957712 -62.33668)
		(end 315.957458 -62.337188)
		(width 0.1143)
		(layer "In4.Cu")
		(net "P3E_CPU0_PE2_SS_RXP<10>")
	)
	(segment
		(start 373.713502 -4.674362)
		(end 373.470932 -4.916932)
		(width 0.1143)
		(layer "In4.Cu")
		(net "P3E_CPU0_PE2_SS_RXP<10>")
	)
	(segment
		(start 345.985084 -41.531032)
		(end 345.985084 -43.330876)
		(width 0.1143)
		(layer "In4.Cu")
		(net "P3E_CPU0_PE2_SS_RXP<10>")
	)
	(segment
		(start 314.96254 -64.305942)
		(end 314.831222 -64.62268)
		(width 0.1143)
		(layer "In4.Cu")
		(net "P3E_CPU0_PE2_SS_RXP<10>")
	)
	(segment
		(start 314.831222 -64.62268)
		(end 314.92063 -64.83858)
		(width 0.1143)
		(layer "In4.Cu")
		(net "P3E_CPU0_PE2_SS_RXP<10>")
	)
	(segment
		(start 373.470932 -4.916932)
		(end 373.237506 -4.916932)
		(width 0.1143)
		(layer "In4.Cu")
		(net "P3E_CPU0_PE2_SS_RXP<10>")
	)
	(segment
		(start 353.586288 -40.75303)
		(end 353.513644 -40.861996)
		(width 0.1143)
		(layer "In4.Cu")
		(net "P3E_CPU0_PE2_SS_RXP<10>")
	)
	(segment
		(start 306.682902 -78.964028)
		(end 306.5018 -79.088234)
		(width 0.0889)
		(layer "In4.Cu")
		(net "P3E_CPU0_PE2_SS_RXP<10>")
	)
	(segment
		(start 307.600858 -78.70444)
		(end 307.288438 -78.913228)
		(width 0.1143)
		(layer "In4.Cu")
		(net "P3E_CPU0_PE2_SS_RXP<10>")
	)
	(segment
		(start 307.054504 -78.913228)
		(end 307.003704 -78.964028)
		(width 0.0889)
		(layer "In4.Cu")
		(net "P3E_CPU0_PE2_SS_RXP<10>")
	)
	(segment
		(start 371.558058 -6.829552)
		(end 370.374418 -8.013192)
		(width 0.1143)
		(layer "In4.Cu")
		(net "P3E_CPU0_PE2_SS_RXP<10>")
	)
	(segment
		(start 354.017834 -38.59403)
		(end 353.586288 -40.75303)
		(width 0.1143)
		(layer "In4.Cu")
		(net "P3E_CPU0_PE2_SS_RXP<10>")
	)
	(segment
		(start 372.994936 -5.392674)
		(end 372.75262 -5.635244)
		(width 0.1143)
		(layer "In4.Cu")
		(net "P3E_CPU0_PE2_SS_RXP<10>")
	)
	(segment
		(start 345.985084 -43.330876)
		(end 345.786964 -44.30395)
		(width 0.1143)
		(layer "In4.Cu")
		(net "P3E_CPU0_PE2_SS_RXP<10>")
	)
	(segment
		(start 315.957458 -62.337188)
		(end 315.179456 -64.216026)
		(width 0.1143)
		(layer "In4.Cu")
		(net "P3E_CPU0_PE2_SS_RXP<10>")
	)
	(segment
		(start 304.679096 -79.088234)
		(end 304.370486 -79.088234)
		(width 0.0889)
		(layer "In4.Cu")
		(net "P3E_CPU0_PE2_SS_RXP<10>")
	)
	(segment
		(start 305.61788 -79.088234)
		(end 305.516534 -78.986888)
		(width 0.0889)
		(layer "In4.Cu")
		(net "P3E_CPU0_PE2_SS_RXP<10>")
	)
	(segment
		(start 303.23663 -79.352648)
		(end 303.529746 -79.183738)
		(width 0.0889)
		(layer "In4.Cu")
		(net "P3E_CPU0_PE2_SS_RXP<10>")
	)
	(segment
		(start 307.076602 -78.913228)
		(end 307.054504 -78.913228)
		(width 0.0889)
		(layer "In4.Cu")
		(net "P3E_CPU0_PE2_SS_RXP<10>")
	)
	(segment
		(start 305.059588 -79.088234)
		(end 304.958242 -78.986888)
		(width 0.0889)
		(layer "In4.Cu")
		(net "P3E_CPU0_PE2_SS_RXP<10>")
	)
	(segment
		(start 308.83225 -77.587602)
		(end 307.600858 -78.70444)
		(width 0.1143)
		(layer "In4.Cu")
		(net "P3E_CPU0_PE2_SS_RXP<10>")
	)
	(segment
		(start 324.803262 -50.411888)
		(end 323.520562 -52.278788)
		(width 0.1143)
		(layer "In4.Cu")
		(net "P3E_CPU0_PE2_SS_RXP<10>")
	)
	(segment
		(start 307.003704 -78.964028)
		(end 306.682902 -78.964028)
		(width 0.0889)
		(layer "In4.Cu")
		(net "P3E_CPU0_PE2_SS_RXP<10>")
	)
	(segment
		(start 305.237388 -79.088234)
		(end 305.059588 -79.088234)
		(width 0.0889)
		(layer "In4.Cu")
		(net "P3E_CPU0_PE2_SS_RXP<10>")
	)
	(segment
		(start 304.958242 -78.986888)
		(end 304.780442 -78.986888)
		(width 0.0889)
		(layer "In4.Cu")
		(net "P3E_CPU0_PE2_SS_RXP<10>")
	)
	(segment
		(start 353.513644 -40.861996)
		(end 353.181412 -41.0718)
		(width 0.1143)
		(layer "In4.Cu")
		(net "P3E_CPU0_PE2_SS_RXP<10>")
	)
	(segment
		(start 372.276624 -6.11124)
		(end 372.034054 -6.353556)
		(width 0.1143)
		(layer "In4.Cu")
		(net "P3E_CPU0_PE2_SS_RXP<10>")
	)
	(segment
		(start 323.520562 -52.278788)
		(end 322.624704 -52.643786)
		(width 0.1143)
		(layer "In4.Cu")
		(net "P3E_CPU0_PE2_SS_RXP<10>")
	)
	(segment
		(start 306.5018 -79.088234)
		(end 305.61788 -79.088234)
		(width 0.0889)
		(layer "In4.Cu")
		(net "P3E_CPU0_PE2_SS_RXP<10>")
	)
	(segment
		(start 305.516534 -78.986888)
		(end 305.338734 -78.986888)
		(width 0.0889)
		(layer "In4.Cu")
		(net "P3E_CPU0_PE2_SS_RXP<10>")
	)
	(segment
		(start 372.519194 -5.635244)
		(end 372.276624 -5.87756)
		(width 0.1143)
		(layer "In4.Cu")
		(net "P3E_CPU0_PE2_SS_RXP<10>")
	)
	(segment
		(start 369.349274 -10.644632)
		(end 366.94364 -12.512548)
		(width 0.1143)
		(layer "In4.Cu")
		(net "P3E_CPU0_PE2_SS_RXP<10>")
	)
	(segment
		(start 341.427054 -45.040296)
		(end 339.259672 -45.48124)
		(width 0.1143)
		(layer "In4.Cu")
		(net "P3E_CPU0_PE2_SS_RXP<10>")
	)
	(segment
		(start 307.288438 -78.913228)
		(end 307.076602 -78.913228)
		(width 0.1143)
		(layer "In4.Cu")
		(net "P3E_CPU0_PE2_SS_RXP<10>")
	)
	(segment
		(start 315.179456 -64.216026)
		(end 314.96254 -64.305942)
		(width 0.1143)
		(layer "In4.Cu")
		(net "P3E_CPU0_PE2_SS_RXP<10>")
	)
	(segment
		(start 346.444316 -41.0718)
		(end 345.985084 -41.531032)
		(width 0.1143)
		(layer "In4.Cu")
		(net "P3E_CPU0_PE2_SS_RXP<10>")
	)
	(segment
		(start 358.409748 -34.939224)
		(end 355.24567 -37.051234)
		(width 0.1143)
		(layer "In4.Cu")
		(net "P3E_CPU0_PE2_SS_RXP<10>")
	)
	(segment
		(start 339.259672 -45.48124)
		(end 337.209384 -45.06341)
		(width 0.1143)
		(layer "In4.Cu")
		(net "P3E_CPU0_PE2_SS_RXP<10>")
	)
	(segment
		(start 371.558058 -6.596126)
		(end 371.558058 -6.829552)
		(width 0.1143)
		(layer "In4.Cu")
		(net "P3E_CPU0_PE2_SS_RXP<10>")
	)
	(segment
		(start 373.599202 -1.419606)
		(end 373.713502 -1.533906)
		(width 0.1143)
		(layer "In4.Cu")
		(net "P3E_CPU0_PE2_SS_RXP<10>")
	)
	(segment
		(start 353.181412 -41.0718)
		(end 346.444316 -41.0718)
		(width 0.1143)
		(layer "In4.Cu")
		(net "P3E_CPU0_PE2_SS_RXP<10>")
	)
	(segment
		(start 372.034054 -6.353556)
		(end 371.800628 -6.353556)
		(width 0.1143)
		(layer "In4.Cu")
		(net "P3E_CPU0_PE2_SS_RXP<10>")
	)
	(segment
		(start 329.107038 -47.62627)
		(end 324.803262 -50.411888)
		(width 0.1143)
		(layer "In4.Cu")
		(net "P3E_CPU0_PE2_SS_RXP<10>")
	)
	(segment
		(start 371.800628 -6.353556)
		(end 371.558058 -6.596126)
		(width 0.1143)
		(layer "In4.Cu")
		(net "P3E_CPU0_PE2_SS_RXP<10>")
	)
	(segment
		(start 372.75262 -5.635244)
		(end 372.519194 -5.635244)
		(width 0.1143)
		(layer "In4.Cu")
		(net "P3E_CPU0_PE2_SS_RXP<10>")
	)
	(segment
		(start 363.91088 -26.687526)
		(end 358.409748 -34.939224)
		(width 0.1143)
		(layer "In4.Cu")
		(net "P3E_CPU0_PE2_SS_RXP<10>")
	)
	(segment
		(start 345.786964 -44.30395)
		(end 345.28379 -45.064172)
		(width 0.1143)
		(layer "In4.Cu")
		(net "P3E_CPU0_PE2_SS_RXP<10>")
	)
	(segment
		(start 303.215548 -79.431388)
		(end 303.23663 -79.352648)
		(width 0.0889)
		(layer "In4.Cu")
		(net "P3E_CPU0_PE2_SS_RXP<10>")
	)
	(segment
		(start 372.276624 -5.87756)
		(end 372.276624 -6.11124)
		(width 0.1143)
		(layer "In4.Cu")
		(net "P3E_CPU0_PE2_SS_RXP<10>")
	)
	(arc
		(start 304.370486 -79.088234)
		(mid 304.085062 -79.171701)
		(end 303.876456 -79.383636)
		(width 0.0889)
		(layer "In4.Cu")
		(net "P3E_CPU0_PE2_SS_RXP<10>")
	)
	(arc
		(start 303.876456 -79.383636)
		(mid 303.558636 -79.582903)
		(end 303.215548 -79.431388)
		(width 0.0889)
		(layer "In4.Cu")
		(net "P3E_CPU0_PE2_SS_RXP<10>")
	)
	(segment
		(start 409.551886 -2.298446)
		(end 409.411932 -2.158492)
		(width 0.1143)
		(layer "F.Cu")
		(net "P3E_CPU0_PE2_SS_RXP<0>")
	)
	(segment
		(start 301.241206 -88.099138)
		(end 301.812706 -88.099138)
		(width 0.1143)
		(layer "F.Cu")
		(net "P3E_CPU0_PE2_SS_RXP<0>")
	)
	(segment
		(start 409.551886 -3.478784)
		(end 409.551886 -2.298446)
		(width 0.1143)
		(layer "F.Cu")
		(net "P3E_CPU0_PE2_SS_RXP<0>")
	)
	(segment
		(start 409.272486 -4.386072)
		(end 409.272486 -3.758184)
		(width 0.1143)
		(layer "F.Cu")
		(net "P3E_CPU0_PE2_SS_RXP<0>")
	)
	(segment
		(start 409.411932 -1.49225)
		(end 409.297632 -1.37795)
		(width 0.1143)
		(layer "F.Cu")
		(net "P3E_CPU0_PE2_SS_RXP<0>")
	)
	(segment
		(start 409.272486 -3.758184)
		(end 409.551886 -3.478784)
		(width 0.1143)
		(layer "F.Cu")
		(net "P3E_CPU0_PE2_SS_RXP<0>")
	)
	(segment
		(start 409.411932 -2.158492)
		(end 409.411932 -1.49225)
		(width 0.1143)
		(layer "F.Cu")
		(net "P3E_CPU0_PE2_SS_RXP<0>")
	)
	(segment
		(start 409.297632 -1.37795)
		(end 408.897582 -1.37795)
		(width 0.1143)
		(layer "F.Cu")
		(net "P3E_CPU0_PE2_SS_RXP<0>")
	)
	(via
		(at 301.812706 -88.099138)
		(size 0.508)
		(drill 0.254)
		(layers "F.Cu" "B.Cu")
		(net "P3E_CPU0_PE2_SS_RXP<0>")
	)
	(via
		(at 408.897582 -1.37795)
		(size 0.508)
		(drill 0.254)
		(layers "F.Cu" "B.Cu")
		(net "P3E_CPU0_PE2_SS_RXP<0>")
	)
	(segment
		(start 385.165092 -11.672824)
		(end 385.50088 -11.743182)
		(width 0.1143)
		(layer "In4.Cu")
		(net "P3E_CPU0_PE2_SS_RXP<0>")
	)
	(segment
		(start 306.34178 -88.10752)
		(end 306.467256 -87.982044)
		(width 0.0889)
		(layer "In4.Cu")
		(net "P3E_CPU0_PE2_SS_RXP<0>")
	)
	(segment
		(start 400.473926 -9.23925)
		(end 400.663918 -8.954008)
		(width 0.1143)
		(layer "In4.Cu")
		(net "P3E_CPU0_PE2_SS_RXP<0>")
	)
	(segment
		(start 301.80153 -88.499188)
		(end 301.834296 -88.499188)
		(width 0.0889)
		(layer "In4.Cu")
		(net "P3E_CPU0_PE2_SS_RXP<0>")
	)
	(segment
		(start 386.690616 -11.823192)
		(end 387.026404 -11.893296)
		(width 0.1143)
		(layer "In4.Cu")
		(net "P3E_CPU0_PE2_SS_RXP<0>")
	)
	(segment
		(start 369.812824 -32.385254)
		(end 369.904264 -32.24784)
		(width 0.1143)
		(layer "In4.Cu")
		(net "P3E_CPU0_PE2_SS_RXP<0>")
	)
	(segment
		(start 369.81257 -32.385254)
		(end 369.812824 -32.385254)
		(width 0.1143)
		(layer "In4.Cu")
		(net "P3E_CPU0_PE2_SS_RXP<0>")
	)
	(segment
		(start 369.904264 -32.24784)
		(end 371.771418 -30.960822)
		(width 0.1143)
		(layer "In4.Cu")
		(net "P3E_CPU0_PE2_SS_RXP<0>")
	)
	(segment
		(start 387.026404 -11.893296)
		(end 387.154166 -12.088622)
		(width 0.1143)
		(layer "In4.Cu")
		(net "P3E_CPU0_PE2_SS_RXP<0>")
	)
	(segment
		(start 387.154166 -12.088622)
		(end 389.713216 -12.623546)
		(width 0.1143)
		(layer "In4.Cu")
		(net "P3E_CPU0_PE2_SS_RXP<0>")
	)
	(segment
		(start 301.51959 -88.268048)
		(end 301.498508 -88.346788)
		(width 0.0889)
		(layer "In4.Cu")
		(net "P3E_CPU0_PE2_SS_RXP<0>")
	)
	(segment
		(start 385.03733 -11.477498)
		(end 385.165092 -11.672824)
		(width 0.1143)
		(layer "In4.Cu")
		(net "P3E_CPU0_PE2_SS_RXP<0>")
	)
	(segment
		(start 307.4543 -86.995)
		(end 308.212998 -86.995)
		(width 0.0889)
		(layer "In4.Cu")
		(net "P3E_CPU0_PE2_SS_RXP<0>")
	)
	(segment
		(start 329.359006 -55.161688)
		(end 331.7367 -53.59654)
		(width 0.1143)
		(layer "In4.Cu")
		(net "P3E_CPU0_PE2_SS_RXP<0>")
	)
	(segment
		(start 339.89518 -52.220876)
		(end 342.160606 -51.759866)
		(width 0.1143)
		(layer "In4.Cu")
		(net "P3E_CPU0_PE2_SS_RXP<0>")
	)
	(segment
		(start 342.160606 -51.759866)
		(end 344.175334 -52.169822)
		(width 0.1143)
		(layer "In4.Cu")
		(net "P3E_CPU0_PE2_SS_RXP<0>")
	)
	(segment
		(start 306.733448 -87.715852)
		(end 307.4543 -86.995)
		(width 0.0889)
		(layer "In4.Cu")
		(net "P3E_CPU0_PE2_SS_RXP<0>")
	)
	(segment
		(start 371.771418 -30.960822)
		(end 372.665244 -26.646632)
		(width 0.1143)
		(layer "In4.Cu")
		(net "P3E_CPU0_PE2_SS_RXP<0>")
	)
	(segment
		(start 310.899048 -85.1281)
		(end 313.667648 -82.628486)
		(width 0.1143)
		(layer "In4.Cu")
		(net "P3E_CPU0_PE2_SS_RXP<0>")
	)
	(segment
		(start 369.597178 -32.709104)
		(end 369.81257 -32.385254)
		(width 0.1143)
		(layer "In4.Cu")
		(net "P3E_CPU0_PE2_SS_RXP<0>")
	)
	(segment
		(start 303.183036 -89.289636)
		(end 303.183544 -89.290144)
		(width 0.0889)
		(layer "In4.Cu")
		(net "P3E_CPU0_PE2_SS_RXP<0>")
	)
	(segment
		(start 378.869448 -13.39596)
		(end 381.35306 -12.06373)
		(width 0.1143)
		(layer "In4.Cu")
		(net "P3E_CPU0_PE2_SS_RXP<0>")
	)
	(segment
		(start 308.285896 -86.9442)
		(end 309.06593 -86.9442)
		(width 0.1143)
		(layer "In4.Cu")
		(net "P3E_CPU0_PE2_SS_RXP<0>")
	)
	(segment
		(start 385.696206 -11.615166)
		(end 386.031994 -11.685524)
		(width 0.1143)
		(layer "In4.Cu")
		(net "P3E_CPU0_PE2_SS_RXP<0>")
	)
	(segment
		(start 400.519646 -9.468358)
		(end 400.473926 -9.23925)
		(width 0.1143)
		(layer "In4.Cu")
		(net "P3E_CPU0_PE2_SS_RXP<0>")
	)
	(segment
		(start 386.49529 -11.950954)
		(end 386.690616 -11.823192)
		(width 0.1143)
		(layer "In4.Cu")
		(net "P3E_CPU0_PE2_SS_RXP<0>")
	)
	(segment
		(start 376.197876 -16.641826)
		(end 378.869448 -13.39596)
		(width 0.1143)
		(layer "In4.Cu")
		(net "P3E_CPU0_PE2_SS_RXP<0>")
	)
	(segment
		(start 384.701796 -11.407394)
		(end 385.03733 -11.477498)
		(width 0.1143)
		(layer "In4.Cu")
		(net "P3E_CPU0_PE2_SS_RXP<0>")
	)
	(segment
		(start 386.031994 -11.685524)
		(end 386.159756 -11.88085)
		(width 0.1143)
		(layer "In4.Cu")
		(net "P3E_CPU0_PE2_SS_RXP<0>")
	)
	(segment
		(start 302.65624 -88.994234)
		(end 302.689006 -88.994234)
		(width 0.0889)
		(layer "In4.Cu")
		(net "P3E_CPU0_PE2_SS_RXP<0>")
	)
	(segment
		(start 301.812706 -88.099138)
		(end 301.51959 -88.268048)
		(width 0.0889)
		(layer "In4.Cu")
		(net "P3E_CPU0_PE2_SS_RXP<0>")
	)
	(segment
		(start 403.190964 -5.461)
		(end 409.045664 -3.662172)
		(width 0.1143)
		(layer "In4.Cu")
		(net "P3E_CPU0_PE2_SS_RXP<0>")
	)
	(segment
		(start 304.370486 -88.994234)
		(end 304.403252 -88.994234)
		(width 0.0889)
		(layer "In4.Cu")
		(net "P3E_CPU0_PE2_SS_RXP<0>")
	)
	(segment
		(start 331.7367 -53.59654)
		(end 337.597496 -51.753008)
		(width 0.1143)
		(layer "In4.Cu")
		(net "P3E_CPU0_PE2_SS_RXP<0>")
	)
	(segment
		(start 305.950112 -88.499188)
		(end 306.075588 -88.373712)
		(width 0.0889)
		(layer "In4.Cu")
		(net "P3E_CPU0_PE2_SS_RXP<0>")
	)
	(segment
		(start 400.893026 -8.908288)
		(end 403.190964 -5.461)
		(width 0.1143)
		(layer "In4.Cu")
		(net "P3E_CPU0_PE2_SS_RXP<0>")
	)
	(segment
		(start 364.30966 -38.448742)
		(end 366.956086 -34.47034)
		(width 0.1143)
		(layer "In4.Cu")
		(net "P3E_CPU0_PE2_SS_RXP<0>")
	)
	(segment
		(start 309.06593 -86.9442)
		(end 309.7022 -86.52637)
		(width 0.1143)
		(layer "In4.Cu")
		(net "P3E_CPU0_PE2_SS_RXP<0>")
	)
	(segment
		(start 384.506216 -11.535156)
		(end 384.701796 -11.407394)
		(width 0.1143)
		(layer "In4.Cu")
		(net "P3E_CPU0_PE2_SS_RXP<0>")
	)
	(segment
		(start 306.592986 -87.715852)
		(end 306.733448 -87.715852)
		(width 0.0889)
		(layer "In4.Cu")
		(net "P3E_CPU0_PE2_SS_RXP<0>")
	)
	(segment
		(start 337.597496 -51.753008)
		(end 339.89518 -52.220876)
		(width 0.1143)
		(layer "In4.Cu")
		(net "P3E_CPU0_PE2_SS_RXP<0>")
	)
	(segment
		(start 400.3294 -9.7536)
		(end 400.519646 -9.468358)
		(width 0.1143)
		(layer "In4.Cu")
		(net "P3E_CPU0_PE2_SS_RXP<0>")
	)
	(segment
		(start 409.045664 -3.662172)
		(end 409.345384 -3.362452)
		(width 0.1143)
		(layer "In4.Cu")
		(net "P3E_CPU0_PE2_SS_RXP<0>")
	)
	(segment
		(start 372.665244 -26.646632)
		(end 374.041416 -25.889966)
		(width 0.1143)
		(layer "In4.Cu")
		(net "P3E_CPU0_PE2_SS_RXP<0>")
	)
	(segment
		(start 381.35306 -12.06373)
		(end 384.170682 -11.465052)
		(width 0.1143)
		(layer "In4.Cu")
		(net "P3E_CPU0_PE2_SS_RXP<0>")
	)
	(segment
		(start 306.467256 -87.982044)
		(end 306.467256 -87.841582)
		(width 0.0889)
		(layer "In4.Cu")
		(net "P3E_CPU0_PE2_SS_RXP<0>")
	)
	(segment
		(start 306.201318 -88.10752)
		(end 306.34178 -88.10752)
		(width 0.0889)
		(layer "In4.Cu")
		(net "P3E_CPU0_PE2_SS_RXP<0>")
	)
	(segment
		(start 359.16362 -48.080422)
		(end 361.526582 -46.517052)
		(width 0.1143)
		(layer "In4.Cu")
		(net "P3E_CPU0_PE2_SS_RXP<0>")
	)
	(segment
		(start 389.713216 -12.623546)
		(end 398.7292 -10.8204)
		(width 0.1143)
		(layer "In4.Cu")
		(net "P3E_CPU0_PE2_SS_RXP<0>")
	)
	(segment
		(start 366.956086 -34.47034)
		(end 369.597178 -32.709104)
		(width 0.1143)
		(layer "In4.Cu")
		(net "P3E_CPU0_PE2_SS_RXP<0>")
	)
	(segment
		(start 310.26608 -86.156292)
		(end 310.899048 -85.1281)
		(width 0.1143)
		(layer "In4.Cu")
		(net "P3E_CPU0_PE2_SS_RXP<0>")
	)
	(segment
		(start 385.50088 -11.743182)
		(end 385.696206 -11.615166)
		(width 0.1143)
		(layer "In4.Cu")
		(net "P3E_CPU0_PE2_SS_RXP<0>")
	)
	(segment
		(start 344.175334 -52.169822)
		(end 359.16362 -48.080422)
		(width 0.1143)
		(layer "In4.Cu")
		(net "P3E_CPU0_PE2_SS_RXP<0>")
	)
	(segment
		(start 305.228498 -88.499188)
		(end 305.950112 -88.499188)
		(width 0.0889)
		(layer "In4.Cu")
		(net "P3E_CPU0_PE2_SS_RXP<0>")
	)
	(segment
		(start 306.075588 -88.373712)
		(end 306.075588 -88.23325)
		(width 0.0889)
		(layer "In4.Cu")
		(net "P3E_CPU0_PE2_SS_RXP<0>")
	)
	(segment
		(start 361.526582 -46.517052)
		(end 363.20222 -43.98518)
		(width 0.1143)
		(layer "In4.Cu")
		(net "P3E_CPU0_PE2_SS_RXP<0>")
	)
	(segment
		(start 308.212998 -86.995)
		(end 308.263798 -86.9442)
		(width 0.0889)
		(layer "In4.Cu")
		(net "P3E_CPU0_PE2_SS_RXP<0>")
	)
	(segment
		(start 363.20222 -43.98518)
		(end 364.30966 -38.448742)
		(width 0.1143)
		(layer "In4.Cu")
		(net "P3E_CPU0_PE2_SS_RXP<0>")
	)
	(segment
		(start 398.7292 -10.8204)
		(end 400.3294 -9.7536)
		(width 0.1143)
		(layer "In4.Cu")
		(net "P3E_CPU0_PE2_SS_RXP<0>")
	)
	(segment
		(start 409.096972 -1.378204)
		(end 409.096972 -1.37795)
		(width 0.1143)
		(layer "In4.Cu")
		(net "P3E_CPU0_PE2_SS_RXP<0>")
	)
	(segment
		(start 313.667648 -82.628486)
		(end 315.448188 -80.459072)
		(width 0.1143)
		(layer "In4.Cu")
		(net "P3E_CPU0_PE2_SS_RXP<0>")
	)
	(segment
		(start 303.5173 -89.489788)
		(end 303.517808 -89.489788)
		(width 0.0889)
		(layer "In4.Cu")
		(net "P3E_CPU0_PE2_SS_RXP<0>")
	)
	(segment
		(start 306.467256 -87.841582)
		(end 306.592986 -87.715852)
		(width 0.0889)
		(layer "In4.Cu")
		(net "P3E_CPU0_PE2_SS_RXP<0>")
	)
	(segment
		(start 315.448188 -80.459072)
		(end 315.447934 -80.459072)
		(width 0.1143)
		(layer "In4.Cu")
		(net "P3E_CPU0_PE2_SS_RXP<0>")
	)
	(segment
		(start 374.041416 -25.889966)
		(end 376.197876 -16.641826)
		(width 0.1143)
		(layer "In4.Cu")
		(net "P3E_CPU0_PE2_SS_RXP<0>")
	)
	(segment
		(start 400.663918 -8.954008)
		(end 400.893026 -8.908288)
		(width 0.1143)
		(layer "In4.Cu")
		(net "P3E_CPU0_PE2_SS_RXP<0>")
	)
	(segment
		(start 306.075588 -88.23325)
		(end 306.201318 -88.10752)
		(width 0.0889)
		(layer "In4.Cu")
		(net "P3E_CPU0_PE2_SS_RXP<0>")
	)
	(segment
		(start 309.7022 -86.52637)
		(end 310.26608 -86.156292)
		(width 0.1143)
		(layer "In4.Cu")
		(net "P3E_CPU0_PE2_SS_RXP<0>")
	)
	(segment
		(start 386.159756 -11.88085)
		(end 386.49529 -11.950954)
		(width 0.1143)
		(layer "In4.Cu")
		(net "P3E_CPU0_PE2_SS_RXP<0>")
	)
	(segment
		(start 409.345384 -3.362452)
		(end 409.345384 -1.626616)
		(width 0.1143)
		(layer "In4.Cu")
		(net "P3E_CPU0_PE2_SS_RXP<0>")
	)
	(segment
		(start 409.096972 -1.37795)
		(end 408.897582 -1.37795)
		(width 0.1143)
		(layer "In4.Cu")
		(net "P3E_CPU0_PE2_SS_RXP<0>")
	)
	(segment
		(start 409.345384 -1.626616)
		(end 409.096972 -1.378204)
		(width 0.1143)
		(layer "In4.Cu")
		(net "P3E_CPU0_PE2_SS_RXP<0>")
	)
	(segment
		(start 308.263798 -86.9442)
		(end 308.285896 -86.9442)
		(width 0.0889)
		(layer "In4.Cu")
		(net "P3E_CPU0_PE2_SS_RXP<0>")
	)
	(segment
		(start 315.447934 -80.459072)
		(end 320.729356 -67.709034)
		(width 0.1143)
		(layer "In4.Cu")
		(net "P3E_CPU0_PE2_SS_RXP<0>")
	)
	(segment
		(start 320.729356 -67.709034)
		(end 329.359006 -55.161688)
		(width 0.1143)
		(layer "In4.Cu")
		(net "P3E_CPU0_PE2_SS_RXP<0>")
	)
	(segment
		(start 384.170682 -11.465052)
		(end 384.506216 -11.535156)
		(width 0.1143)
		(layer "In4.Cu")
		(net "P3E_CPU0_PE2_SS_RXP<0>")
	)
	(arc
		(start 303.193196 -89.306146)
		(mid 303.332493 -89.438139)
		(end 303.5173 -89.489788)
		(width 0.0889)
		(layer "In4.Cu")
		(net "P3E_CPU0_PE2_SS_RXP<0>")
	)
	(arc
		(start 303.541684 -89.489788)
		(mid 303.73511 -89.433261)
		(end 303.876456 -89.289636)
		(width 0.0889)
		(layer "In4.Cu")
		(net "P3E_CPU0_PE2_SS_RXP<0>")
	)
	(arc
		(start 304.403252 -88.994234)
		(mid 304.594894 -88.937068)
		(end 304.734976 -88.794336)
		(width 0.0889)
		(layer "In4.Cu")
		(net "P3E_CPU0_PE2_SS_RXP<0>")
	)
	(arc
		(start 303.517808 -89.489788)
		(mid 303.529746 -89.489966)
		(end 303.541684 -89.489788)
		(width 0.0889)
		(layer "In4.Cu")
		(net "P3E_CPU0_PE2_SS_RXP<0>")
	)
	(arc
		(start 302.324516 -88.794336)
		(mid 302.464595 -88.937072)
		(end 302.65624 -88.994234)
		(width 0.0889)
		(layer "In4.Cu")
		(net "P3E_CPU0_PE2_SS_RXP<0>")
	)
	(arc
		(start 302.689006 -88.994234)
		(mid 302.97443 -89.077701)
		(end 303.183036 -89.289636)
		(width 0.0889)
		(layer "In4.Cu")
		(net "P3E_CPU0_PE2_SS_RXP<0>")
	)
	(arc
		(start 301.834296 -88.499188)
		(mid 302.117513 -88.583469)
		(end 302.324516 -88.794336)
		(width 0.0889)
		(layer "In4.Cu")
		(net "P3E_CPU0_PE2_SS_RXP<0>")
	)
	(arc
		(start 303.876456 -89.289636)
		(mid 304.085064 -89.077704)
		(end 304.370486 -88.994234)
		(width 0.0889)
		(layer "In4.Cu")
		(net "P3E_CPU0_PE2_SS_RXP<0>")
	)
	(arc
		(start 304.734976 -88.794336)
		(mid 304.943395 -88.582623)
		(end 305.228498 -88.499188)
		(width 0.0889)
		(layer "In4.Cu")
		(net "P3E_CPU0_PE2_SS_RXP<0>")
	)
	(arc
		(start 301.498508 -88.346788)
		(mid 301.63307 -88.4567)
		(end 301.80153 -88.499188)
		(width 0.0889)
		(layer "In4.Cu")
		(net "P3E_CPU0_PE2_SS_RXP<0>")
	)
	(arc
		(start 303.183544 -89.290144)
		(mid 303.188277 -89.298201)
		(end 303.193196 -89.306146)
		(width 0.0889)
		(layer "In4.Cu")
		(net "P3E_CPU0_PE2_SS_RXP<0>")
	)
	(segment
		(start 376.404124 -3.075432)
		(end 376.542554 -2.937002)
		(width 0.1143)
		(layer "F.Cu")
		(net "P3E_CPU0_PE2_SS_RXN<9>")
	)
	(segment
		(start 302.099726 -80.669384)
		(end 302.671226 -80.669384)
		(width 0.1143)
		(layer "F.Cu")
		(net "P3E_CPU0_PE2_SS_RXN<9>")
	)
	(segment
		(start 376.685048 -3.72364)
		(end 376.404124 -3.442716)
		(width 0.1143)
		(layer "F.Cu")
		(net "P3E_CPU0_PE2_SS_RXN<9>")
	)
	(segment
		(start 376.404124 -3.442716)
		(end 376.404124 -3.075432)
		(width 0.1143)
		(layer "F.Cu")
		(net "P3E_CPU0_PE2_SS_RXN<9>")
	)
	(segment
		(start 376.685048 -4.389882)
		(end 376.685048 -3.72364)
		(width 0.1143)
		(layer "F.Cu")
		(net "P3E_CPU0_PE2_SS_RXN<9>")
	)
	(segment
		(start 376.542554 -2.937002)
		(end 376.97029 -2.937002)
		(width 0.1143)
		(layer "F.Cu")
		(net "P3E_CPU0_PE2_SS_RXN<9>")
	)
	(via
		(at 302.671226 -80.669384)
		(size 0.508)
		(drill 0.254)
		(layers "F.Cu" "B.Cu")
		(net "P3E_CPU0_PE2_SS_RXN<9>")
	)
	(via
		(at 376.97029 -2.937002)
		(size 0.508)
		(drill 0.254)
		(layers "F.Cu" "B.Cu")
		(net "P3E_CPU0_PE2_SS_RXN<9>")
	)
	(segment
		(start 359.225088 -35.449256)
		(end 364.796324 -27.09291)
		(width 0.1143)
		(layer "In4.Cu")
		(net "P3E_CPU0_PE2_SS_RXN<9>")
	)
	(segment
		(start 341.492586 -46.0121)
		(end 343.757758 -46.472602)
		(width 0.1143)
		(layer "In4.Cu")
		(net "P3E_CPU0_PE2_SS_RXN<9>")
	)
	(segment
		(start 303.511966 -80.764888)
		(end 303.867312 -80.764888)
		(width 0.0889)
		(layer "In4.Cu")
		(net "P3E_CPU0_PE2_SS_RXN<9>")
	)
	(segment
		(start 367.806224 -13.023596)
		(end 371.458998 -10.297668)
		(width 0.1143)
		(layer "In4.Cu")
		(net "P3E_CPU0_PE2_SS_RXN<9>")
	)
	(segment
		(start 376.48134 -3.051302)
		(end 376.59564 -2.937002)
		(width 0.1143)
		(layer "In4.Cu")
		(net "P3E_CPU0_PE2_SS_RXN<9>")
	)
	(segment
		(start 307.976524 -79.735426)
		(end 309.355236 -78.486)
		(width 0.1143)
		(layer "In4.Cu")
		(net "P3E_CPU0_PE2_SS_RXN<9>")
	)
	(segment
		(start 302.671226 -80.669384)
		(end 302.37811 -80.500474)
		(width 0.0889)
		(layer "In4.Cu")
		(net "P3E_CPU0_PE2_SS_RXN<9>")
	)
	(segment
		(start 306.056284 -80.022954)
		(end 306.15763 -79.921608)
		(width 0.0889)
		(layer "In4.Cu")
		(net "P3E_CPU0_PE2_SS_RXN<9>")
	)
	(segment
		(start 371.458998 -10.297668)
		(end 372.397528 -7.876032)
		(width 0.1143)
		(layer "In4.Cu")
		(net "P3E_CPU0_PE2_SS_RXN<9>")
	)
	(segment
		(start 343.757758 -46.472602)
		(end 356.565962 -43.039538)
		(width 0.1143)
		(layer "In4.Cu")
		(net "P3E_CPU0_PE2_SS_RXN<9>")
	)
	(segment
		(start 357.52786 -42.402506)
		(end 357.955596 -41.757346)
		(width 0.1143)
		(layer "In4.Cu")
		(net "P3E_CPU0_PE2_SS_RXN<9>")
	)
	(segment
		(start 339.289898 -46.46041)
		(end 341.492586 -46.0121)
		(width 0.1143)
		(layer "In4.Cu")
		(net "P3E_CPU0_PE2_SS_RXN<9>")
	)
	(segment
		(start 302.659288 -80.269334)
		(end 302.66386 -80.269334)
		(width 0.0889)
		(layer "In4.Cu")
		(net "P3E_CPU0_PE2_SS_RXN<9>")
	)
	(segment
		(start 305.777138 -79.921608)
		(end 305.878484 -80.022954)
		(width 0.0889)
		(layer "In4.Cu")
		(net "P3E_CPU0_PE2_SS_RXN<9>")
	)
	(segment
		(start 316.804548 -62.745874)
		(end 323.233796 -53.398928)
		(width 0.1143)
		(layer "In4.Cu")
		(net "P3E_CPU0_PE2_SS_RXN<9>")
	)
	(segment
		(start 305.041046 -79.921608)
		(end 305.218846 -79.921608)
		(width 0.0889)
		(layer "In4.Cu")
		(net "P3E_CPU0_PE2_SS_RXN<9>")
	)
	(segment
		(start 305.497992 -80.022954)
		(end 305.599338 -79.921608)
		(width 0.0889)
		(layer "In4.Cu")
		(net "P3E_CPU0_PE2_SS_RXN<9>")
	)
	(segment
		(start 309.355236 -78.486)
		(end 311.23382 -76.19619)
		(width 0.1143)
		(layer "In4.Cu")
		(net "P3E_CPU0_PE2_SS_RXN<9>")
	)
	(segment
		(start 306.15763 -79.921608)
		(end 306.97551 -79.921608)
		(width 0.0889)
		(layer "In4.Cu")
		(net "P3E_CPU0_PE2_SS_RXN<9>")
	)
	(segment
		(start 337.217004 -46.0375)
		(end 339.289898 -46.46041)
		(width 0.1143)
		(layer "In4.Cu")
		(net "P3E_CPU0_PE2_SS_RXN<9>")
	)
	(segment
		(start 305.218846 -79.921608)
		(end 305.320192 -80.022954)
		(width 0.0889)
		(layer "In4.Cu")
		(net "P3E_CPU0_PE2_SS_RXN<9>")
	)
	(segment
		(start 324.146164 -53.027326)
		(end 324.231 -52.903882)
		(width 0.1143)
		(layer "In4.Cu")
		(net "P3E_CPU0_PE2_SS_RXN<9>")
	)
	(segment
		(start 302.37811 -80.500474)
		(end 302.357028 -80.421734)
		(width 0.0889)
		(layer "In4.Cu")
		(net "P3E_CPU0_PE2_SS_RXN<9>")
	)
	(segment
		(start 372.397528 -7.876032)
		(end 376.48134 -3.79222)
		(width 0.1143)
		(layer "In4.Cu")
		(net "P3E_CPU0_PE2_SS_RXN<9>")
	)
	(segment
		(start 376.59564 -2.937002)
		(end 376.97029 -2.937002)
		(width 0.1143)
		(layer "In4.Cu")
		(net "P3E_CPU0_PE2_SS_RXN<9>")
	)
	(segment
		(start 324.231 -52.903882)
		(end 325.484236 -51.080924)
		(width 0.1143)
		(layer "In4.Cu")
		(net "P3E_CPU0_PE2_SS_RXN<9>")
	)
	(segment
		(start 302.678846 -80.269334)
		(end 302.683418 -80.269334)
		(width 0.0889)
		(layer "In4.Cu")
		(net "P3E_CPU0_PE2_SS_RXN<9>")
	)
	(segment
		(start 329.50277 -48.477932)
		(end 337.217004 -46.0375)
		(width 0.1143)
		(layer "In4.Cu")
		(net "P3E_CPU0_PE2_SS_RXN<9>")
	)
	(segment
		(start 303.867312 -80.764888)
		(end 304.2666 -80.3656)
		(width 0.0889)
		(layer "In4.Cu")
		(net "P3E_CPU0_PE2_SS_RXN<9>")
	)
	(segment
		(start 307.048408 -79.972408)
		(end 307.622194 -79.972408)
		(width 0.1143)
		(layer "In4.Cu")
		(net "P3E_CPU0_PE2_SS_RXN<9>")
	)
	(segment
		(start 364.796324 -27.09291)
		(end 367.806224 -13.023596)
		(width 0.1143)
		(layer "In4.Cu")
		(net "P3E_CPU0_PE2_SS_RXN<9>")
	)
	(segment
		(start 307.622194 -79.972408)
		(end 307.976524 -79.735426)
		(width 0.1143)
		(layer "In4.Cu")
		(net "P3E_CPU0_PE2_SS_RXN<9>")
	)
	(segment
		(start 357.955596 -41.757346)
		(end 357.955596 -41.757092)
		(width 0.1143)
		(layer "In4.Cu")
		(net "P3E_CPU0_PE2_SS_RXN<9>")
	)
	(segment
		(start 376.48134 -3.79222)
		(end 376.48134 -3.051302)
		(width 0.1143)
		(layer "In4.Cu")
		(net "P3E_CPU0_PE2_SS_RXN<9>")
	)
	(segment
		(start 306.97551 -79.921608)
		(end 307.02631 -79.972408)
		(width 0.0889)
		(layer "In4.Cu")
		(net "P3E_CPU0_PE2_SS_RXN<9>")
	)
	(segment
		(start 305.320192 -80.022954)
		(end 305.497992 -80.022954)
		(width 0.0889)
		(layer "In4.Cu")
		(net "P3E_CPU0_PE2_SS_RXN<9>")
	)
	(segment
		(start 307.02631 -79.972408)
		(end 307.048408 -79.972408)
		(width 0.0889)
		(layer "In4.Cu")
		(net "P3E_CPU0_PE2_SS_RXN<9>")
	)
	(segment
		(start 304.2666 -80.3656)
		(end 304.597054 -80.3656)
		(width 0.0889)
		(layer "In4.Cu")
		(net "P3E_CPU0_PE2_SS_RXN<9>")
	)
	(segment
		(start 304.597054 -80.3656)
		(end 305.041046 -79.921608)
		(width 0.0889)
		(layer "In4.Cu")
		(net "P3E_CPU0_PE2_SS_RXN<9>")
	)
	(segment
		(start 323.233796 -53.398928)
		(end 324.146164 -53.027326)
		(width 0.1143)
		(layer "In4.Cu")
		(net "P3E_CPU0_PE2_SS_RXN<9>")
	)
	(segment
		(start 311.23382 -76.19619)
		(end 316.804548 -62.745874)
		(width 0.1143)
		(layer "In4.Cu")
		(net "P3E_CPU0_PE2_SS_RXN<9>")
	)
	(segment
		(start 305.599338 -79.921608)
		(end 305.777138 -79.921608)
		(width 0.0889)
		(layer "In4.Cu")
		(net "P3E_CPU0_PE2_SS_RXN<9>")
	)
	(segment
		(start 305.878484 -80.022954)
		(end 306.056284 -80.022954)
		(width 0.0889)
		(layer "In4.Cu")
		(net "P3E_CPU0_PE2_SS_RXN<9>")
	)
	(segment
		(start 325.484236 -51.080924)
		(end 329.50277 -48.477932)
		(width 0.1143)
		(layer "In4.Cu")
		(net "P3E_CPU0_PE2_SS_RXN<9>")
	)
	(segment
		(start 356.565962 -43.039538)
		(end 357.52786 -42.402506)
		(width 0.1143)
		(layer "In4.Cu")
		(net "P3E_CPU0_PE2_SS_RXN<9>")
	)
	(segment
		(start 357.955596 -41.757092)
		(end 359.225088 -35.449256)
		(width 0.1143)
		(layer "In4.Cu")
		(net "P3E_CPU0_PE2_SS_RXN<9>")
	)
	(arc
		(start 302.357028 -80.421734)
		(mid 302.491248 -80.312012)
		(end 302.659288 -80.269334)
		(width 0.0889)
		(layer "In4.Cu")
		(net "P3E_CPU0_PE2_SS_RXN<9>")
	)
	(arc
		(start 303.017936 -80.469486)
		(mid 303.226544 -80.681418)
		(end 303.511966 -80.764888)
		(width 0.0889)
		(layer "In4.Cu")
		(net "P3E_CPU0_PE2_SS_RXN<9>")
	)
	(arc
		(start 302.683418 -80.269334)
		(mid 302.87667 -80.325942)
		(end 303.017936 -80.469486)
		(width 0.0889)
		(layer "In4.Cu")
		(net "P3E_CPU0_PE2_SS_RXN<9>")
	)
	(arc
		(start 302.66386 -80.269334)
		(mid 302.671353 -80.269217)
		(end 302.678846 -80.269334)
		(width 0.0889)
		(layer "In4.Cu")
		(net "P3E_CPU0_PE2_SS_RXN<9>")
	)
	(segment
		(start 379.41758 -1.754886)
		(end 379.034802 -1.754886)
		(width 0.1143)
		(layer "F.Cu")
		(net "P3E_CPU0_PE2_SS_RXN<8>")
	)
	(segment
		(start 378.831094 -3.388106)
		(end 379.085094 -3.642106)
		(width 0.1143)
		(layer "F.Cu")
		(net "P3E_CPU0_PE2_SS_RXN<8>")
	)
	(segment
		(start 378.920502 -2.689098)
		(end 378.831094 -2.778506)
		(width 0.1143)
		(layer "F.Cu")
		(net "P3E_CPU0_PE2_SS_RXN<8>")
	)
	(segment
		(start 379.085094 -3.642106)
		(end 379.085094 -4.389882)
		(width 0.1143)
		(layer "F.Cu")
		(net "P3E_CPU0_PE2_SS_RXN<8>")
	)
	(segment
		(start 378.831094 -2.778506)
		(end 378.831094 -3.388106)
		(width 0.1143)
		(layer "F.Cu")
		(net "P3E_CPU0_PE2_SS_RXN<8>")
	)
	(segment
		(start 300.382686 -80.669384)
		(end 300.954186 -80.669384)
		(width 0.1143)
		(layer "F.Cu")
		(net "P3E_CPU0_PE2_SS_RXN<8>")
	)
	(segment
		(start 379.034802 -1.754886)
		(end 378.920502 -1.869186)
		(width 0.1143)
		(layer "F.Cu")
		(net "P3E_CPU0_PE2_SS_RXN<8>")
	)
	(segment
		(start 378.920502 -1.869186)
		(end 378.920502 -2.689098)
		(width 0.1143)
		(layer "F.Cu")
		(net "P3E_CPU0_PE2_SS_RXN<8>")
	)
	(via
		(at 379.41758 -1.754886)
		(size 0.508)
		(drill 0.254)
		(layers "F.Cu" "B.Cu")
		(net "P3E_CPU0_PE2_SS_RXN<8>")
	)
	(via
		(at 300.954186 -80.669384)
		(size 0.508)
		(drill 0.254)
		(layers "F.Cu" "B.Cu")
		(net "P3E_CPU0_PE2_SS_RXN<8>")
	)
	(segment
		(start 368.470688 -13.35278)
		(end 372.277386 -10.52576)
		(width 0.1143)
		(layer "In4.Cu")
		(net "P3E_CPU0_PE2_SS_RXN<8>")
	)
	(segment
		(start 341.551006 -46.686978)
		(end 343.829132 -47.150274)
		(width 0.1143)
		(layer "In4.Cu")
		(net "P3E_CPU0_PE2_SS_RXN<8>")
	)
	(segment
		(start 307.932582 -80.673448)
		(end 308.015894 -80.59801)
		(width 0.1143)
		(layer "In4.Cu")
		(net "P3E_CPU0_PE2_SS_RXN<8>")
	)
	(segment
		(start 311.66689 -76.851002)
		(end 317.403226 -63.00089)
		(width 0.1143)
		(layer "In4.Cu")
		(net "P3E_CPU0_PE2_SS_RXN<8>")
	)
	(segment
		(start 323.653404 -53.91404)
		(end 324.58279 -53.535326)
		(width 0.1143)
		(layer "In4.Cu")
		(net "P3E_CPU0_PE2_SS_RXN<8>")
	)
	(segment
		(start 374.091454 -8.046974)
		(end 378.92863 -3.209798)
		(width 0.1143)
		(layer "In4.Cu")
		(net "P3E_CPU0_PE2_SS_RXN<8>")
	)
	(segment
		(start 308.015894 -80.597756)
		(end 310.26354 -78.561692)
		(width 0.1143)
		(layer "In4.Cu")
		(net "P3E_CPU0_PE2_SS_RXN<8>")
	)
	(segment
		(start 307.094636 -80.622648)
		(end 307.145436 -80.673448)
		(width 0.0889)
		(layer "In4.Cu")
		(net "P3E_CPU0_PE2_SS_RXN<8>")
	)
	(segment
		(start 329.786234 -49.057306)
		(end 337.254596 -46.69536)
		(width 0.1143)
		(layer "In4.Cu")
		(net "P3E_CPU0_PE2_SS_RXN<8>")
	)
	(segment
		(start 308.015894 -80.59801)
		(end 308.015894 -80.597756)
		(width 0.1143)
		(layer "In4.Cu")
		(net "P3E_CPU0_PE2_SS_RXN<8>")
	)
	(segment
		(start 358.564942 -42.025316)
		(end 359.847388 -35.685222)
		(width 0.1143)
		(layer "In4.Cu")
		(net "P3E_CPU0_PE2_SS_RXN<8>")
	)
	(segment
		(start 302.649636 -81.259934)
		(end 302.682402 -81.259934)
		(width 0.0889)
		(layer "In4.Cu")
		(net "P3E_CPU0_PE2_SS_RXN<8>")
	)
	(segment
		(start 372.277386 -10.52576)
		(end 373.028718 -8.644128)
		(width 0.1143)
		(layer "In4.Cu")
		(net "P3E_CPU0_PE2_SS_RXN<8>")
	)
	(segment
		(start 307.167534 -80.673448)
		(end 307.932582 -80.673448)
		(width 0.1143)
		(layer "In4.Cu")
		(net "P3E_CPU0_PE2_SS_RXN<8>")
	)
	(segment
		(start 365.510318 -27.190192)
		(end 368.470688 -13.35278)
		(width 0.1143)
		(layer "In4.Cu")
		(net "P3E_CPU0_PE2_SS_RXN<8>")
	)
	(segment
		(start 359.847388 -35.685222)
		(end 365.510318 -27.190192)
		(width 0.1143)
		(layer "In4.Cu")
		(net "P3E_CPU0_PE2_SS_RXN<8>")
	)
	(segment
		(start 300.954186 -80.33131)
		(end 301.012098 -80.273398)
		(width 0.0889)
		(layer "In4.Cu")
		(net "P3E_CPU0_PE2_SS_RXN<8>")
	)
	(segment
		(start 310.26354 -78.561692)
		(end 311.66689 -76.851002)
		(width 0.1143)
		(layer "In4.Cu")
		(net "P3E_CPU0_PE2_SS_RXN<8>")
	)
	(segment
		(start 339.3821 -47.12843)
		(end 341.551006 -46.686978)
		(width 0.1143)
		(layer "In4.Cu")
		(net "P3E_CPU0_PE2_SS_RXN<8>")
	)
	(segment
		(start 378.92863 -3.209798)
		(end 378.92863 -1.869186)
		(width 0.1143)
		(layer "In4.Cu")
		(net "P3E_CPU0_PE2_SS_RXN<8>")
	)
	(segment
		(start 301.794926 -80.764888)
		(end 301.827692 -80.764888)
		(width 0.0889)
		(layer "In4.Cu")
		(net "P3E_CPU0_PE2_SS_RXN<8>")
	)
	(segment
		(start 300.954186 -80.669384)
		(end 300.954186 -80.33131)
		(width 0.0889)
		(layer "In4.Cu")
		(net "P3E_CPU0_PE2_SS_RXN<8>")
	)
	(segment
		(start 303.511966 -81.755488)
		(end 303.547526 -81.755488)
		(width 0.0889)
		(layer "In4.Cu")
		(net "P3E_CPU0_PE2_SS_RXN<8>")
	)
	(segment
		(start 337.254596 -46.69536)
		(end 339.3821 -47.12843)
		(width 0.1143)
		(layer "In4.Cu")
		(net "P3E_CPU0_PE2_SS_RXN<8>")
	)
	(segment
		(start 373.028718 -8.644128)
		(end 373.625872 -8.046974)
		(width 0.1143)
		(layer "In4.Cu")
		(net "P3E_CPU0_PE2_SS_RXN<8>")
	)
	(segment
		(start 305.432206 -80.622648)
		(end 307.094636 -80.622648)
		(width 0.0889)
		(layer "In4.Cu")
		(net "P3E_CPU0_PE2_SS_RXN<8>")
	)
	(segment
		(start 307.145436 -80.673448)
		(end 307.167534 -80.673448)
		(width 0.0889)
		(layer "In4.Cu")
		(net "P3E_CPU0_PE2_SS_RXN<8>")
	)
	(segment
		(start 343.829132 -47.150274)
		(end 356.760018 -43.684444)
		(width 0.1143)
		(layer "In4.Cu")
		(net "P3E_CPU0_PE2_SS_RXN<8>")
	)
	(segment
		(start 378.92863 -1.869186)
		(end 379.04293 -1.754886)
		(width 0.1143)
		(layer "In4.Cu")
		(net "P3E_CPU0_PE2_SS_RXN<8>")
	)
	(segment
		(start 317.403226 -63.00089)
		(end 323.653404 -53.91404)
		(width 0.1143)
		(layer "In4.Cu")
		(net "P3E_CPU0_PE2_SS_RXN<8>")
	)
	(segment
		(start 358.017572 -42.852086)
		(end 358.564942 -42.025316)
		(width 0.1143)
		(layer "In4.Cu")
		(net "P3E_CPU0_PE2_SS_RXN<8>")
	)
	(segment
		(start 373.625872 -8.046974)
		(end 374.091454 -8.046974)
		(width 0.1143)
		(layer "In4.Cu")
		(net "P3E_CPU0_PE2_SS_RXN<8>")
	)
	(segment
		(start 356.760018 -43.684444)
		(end 358.017572 -42.852086)
		(width 0.1143)
		(layer "In4.Cu")
		(net "P3E_CPU0_PE2_SS_RXN<8>")
	)
	(segment
		(start 379.04293 -1.754886)
		(end 379.41758 -1.754886)
		(width 0.1143)
		(layer "In4.Cu")
		(net "P3E_CPU0_PE2_SS_RXN<8>")
	)
	(segment
		(start 324.58279 -53.535326)
		(end 325.954898 -51.539394)
		(width 0.1143)
		(layer "In4.Cu")
		(net "P3E_CPU0_PE2_SS_RXN<8>")
	)
	(segment
		(start 325.954898 -51.539394)
		(end 329.786234 -49.057306)
		(width 0.1143)
		(layer "In4.Cu")
		(net "P3E_CPU0_PE2_SS_RXN<8>")
	)
	(segment
		(start 304.794666 -81.260188)
		(end 305.432206 -80.622648)
		(width 0.0889)
		(layer "In4.Cu")
		(net "P3E_CPU0_PE2_SS_RXN<8>")
	)
	(segment
		(start 304.370232 -81.260188)
		(end 304.794666 -81.260188)
		(width 0.0889)
		(layer "In4.Cu")
		(net "P3E_CPU0_PE2_SS_RXN<8>")
	)
	(arc
		(start 302.159416 -80.964786)
		(mid 302.36642 -81.17565)
		(end 302.649636 -81.259934)
		(width 0.0889)
		(layer "In4.Cu")
		(net "P3E_CPU0_PE2_SS_RXN<8>")
	)
	(arc
		(start 301.300896 -80.469486)
		(mid 301.509504 -80.681418)
		(end 301.794926 -80.764888)
		(width 0.0889)
		(layer "In4.Cu")
		(net "P3E_CPU0_PE2_SS_RXN<8>")
	)
	(arc
		(start 301.827692 -80.764888)
		(mid 302.019334 -80.822054)
		(end 302.159416 -80.964786)
		(width 0.0889)
		(layer "In4.Cu")
		(net "P3E_CPU0_PE2_SS_RXN<8>")
	)
	(arc
		(start 304.041556 -81.460086)
		(mid 304.1803 -81.318053)
		(end 304.370232 -81.260188)
		(width 0.0889)
		(layer "In4.Cu")
		(net "P3E_CPU0_PE2_SS_RXN<8>")
	)
	(arc
		(start 303.547526 -81.755488)
		(mid 303.83295 -81.672021)
		(end 304.041556 -81.460086)
		(width 0.0889)
		(layer "In4.Cu")
		(net "P3E_CPU0_PE2_SS_RXN<8>")
	)
	(arc
		(start 301.012098 -80.273398)
		(mid 301.178999 -80.338298)
		(end 301.300896 -80.469486)
		(width 0.0889)
		(layer "In4.Cu")
		(net "P3E_CPU0_PE2_SS_RXN<8>")
	)
	(arc
		(start 302.682402 -81.259934)
		(mid 302.876252 -81.316284)
		(end 303.017936 -81.460086)
		(width 0.0889)
		(layer "In4.Cu")
		(net "P3E_CPU0_PE2_SS_RXN<8>")
	)
	(arc
		(start 303.017936 -81.460086)
		(mid 303.226544 -81.672018)
		(end 303.511966 -81.755488)
		(width 0.0889)
		(layer "In4.Cu")
		(net "P3E_CPU0_PE2_SS_RXN<8>")
	)
	(segment
		(start 393.369292 -3.176524)
		(end 393.131548 -3.176524)
		(width 0.1143)
		(layer "F.Cu")
		(net "P3E_CPU0_PE2_SS_RXN<7>")
	)
	(segment
		(start 392.991086 -3.478784)
		(end 393.270486 -3.758184)
		(width 0.1143)
		(layer "F.Cu")
		(net "P3E_CPU0_PE2_SS_RXN<7>")
	)
	(segment
		(start 393.131548 -3.176524)
		(end 392.991086 -3.316986)
		(width 0.1143)
		(layer "F.Cu")
		(net "P3E_CPU0_PE2_SS_RXN<7>")
	)
	(segment
		(start 392.991086 -3.316986)
		(end 392.991086 -3.478784)
		(width 0.1143)
		(layer "F.Cu")
		(net "P3E_CPU0_PE2_SS_RXN<7>")
	)
	(segment
		(start 393.270486 -3.758184)
		(end 393.270486 -4.386072)
		(width 0.1143)
		(layer "F.Cu")
		(net "P3E_CPU0_PE2_SS_RXN<7>")
	)
	(segment
		(start 301.241206 -83.146138)
		(end 301.812706 -83.146138)
		(width 0.1143)
		(layer "F.Cu")
		(net "P3E_CPU0_PE2_SS_RXN<7>")
	)
	(via
		(at 393.369292 -3.176524)
		(size 0.508)
		(drill 0.254)
		(layers "F.Cu" "B.Cu")
		(net "P3E_CPU0_PE2_SS_RXN<7>")
	)
	(via
		(at 301.812706 -83.146138)
		(size 0.508)
		(drill 0.254)
		(layers "F.Cu" "B.Cu")
		(net "P3E_CPU0_PE2_SS_RXN<7>")
	)
	(segment
		(start 307.342286 -81.80578)
		(end 307.291486 -81.75498)
		(width 0.0889)
		(layer "In4.Cu")
		(net "P3E_CPU0_PE2_SS_RXN<7>")
	)
	(segment
		(start 307.291486 -81.75498)
		(end 305.246786 -81.75498)
		(width 0.0889)
		(layer "In4.Cu")
		(net "P3E_CPU0_PE2_SS_RXN<7>")
	)
	(segment
		(start 366.2807 -27.2415)
		(end 360.45902 -35.973766)
		(width 0.1143)
		(layer "In4.Cu")
		(net "P3E_CPU0_PE2_SS_RXN<7>")
	)
	(segment
		(start 325.019924 -54.043072)
		(end 324.072504 -54.42966)
		(width 0.1143)
		(layer "In4.Cu")
		(net "P3E_CPU0_PE2_SS_RXN<7>")
	)
	(segment
		(start 312.107072 -77.461872)
		(end 310.959754 -78.860904)
		(width 0.1143)
		(layer "In4.Cu")
		(net "P3E_CPU0_PE2_SS_RXN<7>")
	)
	(segment
		(start 357.04653 -44.285408)
		(end 343.878408 -47.814484)
		(width 0.1143)
		(layer "In4.Cu")
		(net "P3E_CPU0_PE2_SS_RXN<7>")
	)
	(segment
		(start 304.409856 -82.250534)
		(end 304.37709 -82.250534)
		(width 0.0889)
		(layer "In4.Cu")
		(net "P3E_CPU0_PE2_SS_RXN<7>")
	)
	(segment
		(start 301.812706 -82.808064)
		(end 301.812706 -83.146138)
		(width 0.0889)
		(layer "In4.Cu")
		(net "P3E_CPU0_PE2_SS_RXN<7>")
	)
	(segment
		(start 392.9888 -3.36296)
		(end 392.9888 -3.885438)
		(width 0.1143)
		(layer "In4.Cu")
		(net "P3E_CPU0_PE2_SS_RXN<7>")
	)
	(segment
		(start 374.242838 -10.296398)
		(end 368.999262 -14.372336)
		(width 0.1143)
		(layer "In4.Cu")
		(net "P3E_CPU0_PE2_SS_RXN<7>")
	)
	(segment
		(start 326.428354 -51.994562)
		(end 325.019924 -54.043072)
		(width 0.1143)
		(layer "In4.Cu")
		(net "P3E_CPU0_PE2_SS_RXN<7>")
	)
	(segment
		(start 382.071118 -3.617468)
		(end 377.633992 -5.56133)
		(width 0.1143)
		(layer "In4.Cu")
		(net "P3E_CPU0_PE2_SS_RXN<7>")
	)
	(segment
		(start 343.878408 -47.814484)
		(end 341.631016 -47.357538)
		(width 0.1143)
		(layer "In4.Cu")
		(net "P3E_CPU0_PE2_SS_RXN<7>")
	)
	(segment
		(start 341.631016 -47.357538)
		(end 339.45068 -47.801276)
		(width 0.1143)
		(layer "In4.Cu")
		(net "P3E_CPU0_PE2_SS_RXN<7>")
	)
	(segment
		(start 359.192068 -42.20083)
		(end 359.192322 -42.20083)
		(width 0.1143)
		(layer "In4.Cu")
		(net "P3E_CPU0_PE2_SS_RXN<7>")
	)
	(segment
		(start 392.649456 -4.224528)
		(end 391.296398 -4.51231)
		(width 0.1143)
		(layer "In4.Cu")
		(net "P3E_CPU0_PE2_SS_RXN<7>")
	)
	(segment
		(start 368.999262 -14.372336)
		(end 366.2807 -27.2415)
		(width 0.1143)
		(layer "In4.Cu")
		(net "P3E_CPU0_PE2_SS_RXN<7>")
	)
	(segment
		(start 392.9888 -3.885438)
		(end 392.649456 -4.224528)
		(width 0.1143)
		(layer "In4.Cu")
		(net "P3E_CPU0_PE2_SS_RXN<7>")
	)
	(segment
		(start 360.45902 -35.973766)
		(end 359.192068 -42.20083)
		(width 0.1143)
		(layer "In4.Cu")
		(net "P3E_CPU0_PE2_SS_RXN<7>")
	)
	(segment
		(start 310.959754 -78.860904)
		(end 307.710586 -81.80578)
		(width 0.1143)
		(layer "In4.Cu")
		(net "P3E_CPU0_PE2_SS_RXN<7>")
	)
	(segment
		(start 359.192322 -42.20083)
		(end 359.180892 -42.25671)
		(width 0.1143)
		(layer "In4.Cu")
		(net "P3E_CPU0_PE2_SS_RXN<7>")
	)
	(segment
		(start 385.897374 -4.42976)
		(end 382.071118 -3.617468)
		(width 0.1143)
		(layer "In4.Cu")
		(net "P3E_CPU0_PE2_SS_RXN<7>")
	)
	(segment
		(start 358.455214 -43.35272)
		(end 357.04653 -44.285408)
		(width 0.1143)
		(layer "In4.Cu")
		(net "P3E_CPU0_PE2_SS_RXN<7>")
	)
	(segment
		(start 359.180892 -42.25671)
		(end 358.455214 -43.35272)
		(width 0.1143)
		(layer "In4.Cu")
		(net "P3E_CPU0_PE2_SS_RXN<7>")
	)
	(segment
		(start 393.369292 -3.176524)
		(end 393.175236 -3.176524)
		(width 0.1143)
		(layer "In4.Cu")
		(net "P3E_CPU0_PE2_SS_RXN<7>")
	)
	(segment
		(start 304.904394 -81.94802)
		(end 304.900076 -81.955386)
		(width 0.0889)
		(layer "In4.Cu")
		(net "P3E_CPU0_PE2_SS_RXN<7>")
	)
	(segment
		(start 301.877984 -82.742786)
		(end 301.812706 -82.808064)
		(width 0.0889)
		(layer "In4.Cu")
		(net "P3E_CPU0_PE2_SS_RXN<7>")
	)
	(segment
		(start 388.402322 -3.89763)
		(end 385.897374 -4.42976)
		(width 0.1143)
		(layer "In4.Cu")
		(net "P3E_CPU0_PE2_SS_RXN<7>")
	)
	(segment
		(start 330.065126 -49.642268)
		(end 326.428354 -51.994562)
		(width 0.1143)
		(layer "In4.Cu")
		(net "P3E_CPU0_PE2_SS_RXN<7>")
	)
	(segment
		(start 317.978536 -63.28918)
		(end 312.107072 -77.461872)
		(width 0.1143)
		(layer "In4.Cu")
		(net "P3E_CPU0_PE2_SS_RXN<7>")
	)
	(segment
		(start 391.296398 -4.51231)
		(end 388.402322 -3.89763)
		(width 0.1143)
		(layer "In4.Cu")
		(net "P3E_CPU0_PE2_SS_RXN<7>")
	)
	(segment
		(start 339.45068 -47.801276)
		(end 337.285584 -47.360332)
		(width 0.1143)
		(layer "In4.Cu")
		(net "P3E_CPU0_PE2_SS_RXN<7>")
	)
	(segment
		(start 337.285584 -47.360332)
		(end 330.065126 -49.642268)
		(width 0.1143)
		(layer "In4.Cu")
		(net "P3E_CPU0_PE2_SS_RXN<7>")
	)
	(segment
		(start 393.175236 -3.176524)
		(end 392.9888 -3.36296)
		(width 0.1143)
		(layer "In4.Cu")
		(net "P3E_CPU0_PE2_SS_RXN<7>")
	)
	(segment
		(start 307.710586 -81.80578)
		(end 307.364384 -81.80578)
		(width 0.1143)
		(layer "In4.Cu")
		(net "P3E_CPU0_PE2_SS_RXN<7>")
	)
	(segment
		(start 324.072504 -54.42966)
		(end 317.978536 -63.28918)
		(width 0.1143)
		(layer "In4.Cu")
		(net "P3E_CPU0_PE2_SS_RXN<7>")
	)
	(segment
		(start 377.633992 -5.56133)
		(end 374.242838 -10.296398)
		(width 0.1143)
		(layer "In4.Cu")
		(net "P3E_CPU0_PE2_SS_RXN<7>")
	)
	(segment
		(start 307.364384 -81.80578)
		(end 307.342286 -81.80578)
		(width 0.0889)
		(layer "In4.Cu")
		(net "P3E_CPU0_PE2_SS_RXN<7>")
	)
	(arc
		(start 303.017936 -82.450686)
		(mid 302.671226 -82.250375)
		(end 302.324516 -82.450686)
		(width 0.0889)
		(layer "In4.Cu")
		(net "P3E_CPU0_PE2_SS_RXN<7>")
	)
	(arc
		(start 304.900076 -81.955386)
		(mid 304.693072 -82.16625)
		(end 304.409856 -82.250534)
		(width 0.0889)
		(layer "In4.Cu")
		(net "P3E_CPU0_PE2_SS_RXN<7>")
	)
	(arc
		(start 305.246786 -81.75498)
		(mid 305.05027 -81.806574)
		(end 304.904394 -81.94802)
		(width 0.0889)
		(layer "In4.Cu")
		(net "P3E_CPU0_PE2_SS_RXN<7>")
	)
	(arc
		(start 302.324516 -82.450686)
		(mid 302.136093 -82.64999)
		(end 301.877984 -82.742786)
		(width 0.0889)
		(layer "In4.Cu")
		(net "P3E_CPU0_PE2_SS_RXN<7>")
	)
	(arc
		(start 304.37709 -82.250534)
		(mid 304.18324 -82.306884)
		(end 304.041556 -82.450686)
		(width 0.0889)
		(layer "In4.Cu")
		(net "P3E_CPU0_PE2_SS_RXN<7>")
	)
	(arc
		(start 304.041556 -82.450686)
		(mid 303.529746 -82.746225)
		(end 303.017936 -82.450686)
		(width 0.0889)
		(layer "In4.Cu")
		(net "P3E_CPU0_PE2_SS_RXN<7>")
	)
	(segment
		(start 394.870686 -4.386072)
		(end 394.870686 -3.758184)
		(width 0.1143)
		(layer "F.Cu")
		(net "P3E_CPU0_PE2_SS_RXN<6>")
	)
	(segment
		(start 303.529746 -83.146138)
		(end 302.958246 -83.146138)
		(width 0.1143)
		(layer "F.Cu")
		(net "P3E_CPU0_PE2_SS_RXN<6>")
	)
	(segment
		(start 395.150086 -3.253486)
		(end 395.022324 -3.125724)
		(width 0.1143)
		(layer "F.Cu")
		(net "P3E_CPU0_PE2_SS_RXN<6>")
	)
	(segment
		(start 394.870686 -3.758184)
		(end 395.150086 -3.478784)
		(width 0.1143)
		(layer "F.Cu")
		(net "P3E_CPU0_PE2_SS_RXN<6>")
	)
	(segment
		(start 395.150086 -3.478784)
		(end 395.150086 -3.253486)
		(width 0.1143)
		(layer "F.Cu")
		(net "P3E_CPU0_PE2_SS_RXN<6>")
	)
	(segment
		(start 395.022324 -3.125724)
		(end 394.753592 -3.125724)
		(width 0.1143)
		(layer "F.Cu")
		(net "P3E_CPU0_PE2_SS_RXN<6>")
	)
	(via
		(at 394.753592 -3.125724)
		(size 0.508)
		(drill 0.254)
		(layers "F.Cu" "B.Cu")
		(net "P3E_CPU0_PE2_SS_RXN<6>")
	)
	(via
		(at 303.529746 -83.146138)
		(size 0.508)
		(drill 0.254)
		(layers "F.Cu" "B.Cu")
		(net "P3E_CPU0_PE2_SS_RXN<6>")
	)
	(segment
		(start 305.36896 -82.6262)
		(end 304.987706 -82.6262)
		(width 0.0889)
		(layer "In4.Cu")
		(net "P3E_CPU0_PE2_SS_RXN<6>")
	)
	(segment
		(start 311.386728 -79.028544)
		(end 307.766212 -82.309716)
		(width 0.1143)
		(layer "In4.Cu")
		(net "P3E_CPU0_PE2_SS_RXN<6>")
	)
	(segment
		(start 357.264716 -44.59478)
		(end 343.910158 -48.174656)
		(width 0.1143)
		(layer "In4.Cu")
		(net "P3E_CPU0_PE2_SS_RXN<6>")
	)
	(segment
		(start 379.483112 -5.926328)
		(end 379.505464 -6.158738)
		(width 0.1143)
		(layer "In4.Cu")
		(net "P3E_CPU0_PE2_SS_RXN<6>")
	)
	(segment
		(start 337.297014 -47.717964)
		(end 330.221844 -49.953164)
		(width 0.1143)
		(layer "In4.Cu")
		(net "P3E_CPU0_PE2_SS_RXN<6>")
	)
	(segment
		(start 307.766212 -82.309716)
		(end 307.564282 -82.309716)
		(width 0.1143)
		(layer "In4.Cu")
		(net "P3E_CPU0_PE2_SS_RXN<6>")
	)
	(segment
		(start 341.718392 -47.728632)
		(end 339.533484 -48.173132)
		(width 0.1143)
		(layer "In4.Cu")
		(net "P3E_CPU0_PE2_SS_RXN<6>")
	)
	(segment
		(start 394.401802 -4.762246)
		(end 393.240006 -5.009134)
		(width 0.1143)
		(layer "In4.Cu")
		(net "P3E_CPU0_PE2_SS_RXN<6>")
	)
	(segment
		(start 372.489476 -14.681708)
		(end 370.9162 -21.430488)
		(width 0.1143)
		(layer "In4.Cu")
		(net "P3E_CPU0_PE2_SS_RXN<6>")
	)
	(segment
		(start 312.304938 -77.909166)
		(end 311.386728 -79.028544)
		(width 0.1143)
		(layer "In4.Cu")
		(net "P3E_CPU0_PE2_SS_RXN<6>")
	)
	(segment
		(start 380.797054 -4.590034)
		(end 379.933454 -5.639054)
		(width 0.1143)
		(layer "In4.Cu")
		(net "P3E_CPU0_PE2_SS_RXN<6>")
	)
	(segment
		(start 358.694736 -43.64863)
		(end 357.264716 -44.59478)
		(width 0.1143)
		(layer "In4.Cu")
		(net "P3E_CPU0_PE2_SS_RXN<6>")
	)
	(segment
		(start 395.139164 -3.278632)
		(end 395.139164 -4.024884)
		(width 0.1143)
		(layer "In4.Cu")
		(net "P3E_CPU0_PE2_SS_RXN<6>")
	)
	(segment
		(start 305.911758 -82.261202)
		(end 305.810412 -82.362548)
		(width 0.0889)
		(layer "In4.Cu")
		(net "P3E_CPU0_PE2_SS_RXN<6>")
	)
	(segment
		(start 369.624864 -22.34946)
		(end 368.34953 -23.199344)
		(width 0.1143)
		(layer "In4.Cu")
		(net "P3E_CPU0_PE2_SS_RXN<6>")
	)
	(segment
		(start 378.409454 -7.230618)
		(end 378.191522 -7.495286)
		(width 0.1143)
		(layer "In4.Cu")
		(net "P3E_CPU0_PE2_SS_RXN<6>")
	)
	(segment
		(start 379.287532 -6.42366)
		(end 379.055376 -6.446012)
		(width 0.1143)
		(layer "In4.Cu")
		(net "P3E_CPU0_PE2_SS_RXN<6>")
	)
	(segment
		(start 379.701044 -5.66166)
		(end 379.483112 -5.926328)
		(width 0.1143)
		(layer "In4.Cu")
		(net "P3E_CPU0_PE2_SS_RXN<6>")
	)
	(segment
		(start 370.900198 -21.499068)
		(end 369.624864 -22.349206)
		(width 0.1143)
		(layer "In4.Cu")
		(net "P3E_CPU0_PE2_SS_RXN<6>")
	)
	(segment
		(start 324.30085 -54.707282)
		(end 318.304926 -63.4238)
		(width 0.1143)
		(layer "In4.Cu")
		(net "P3E_CPU0_PE2_SS_RXN<6>")
	)
	(segment
		(start 307.028342 -82.261202)
		(end 306.926996 -82.362548)
		(width 0.0889)
		(layer "In4.Cu")
		(net "P3E_CPU0_PE2_SS_RXN<6>")
	)
	(segment
		(start 306.190904 -82.362548)
		(end 306.089558 -82.261202)
		(width 0.0889)
		(layer "In4.Cu")
		(net "P3E_CPU0_PE2_SS_RXN<6>")
	)
	(segment
		(start 378.859796 -6.943344)
		(end 378.641864 -7.208012)
		(width 0.1143)
		(layer "In4.Cu")
		(net "P3E_CPU0_PE2_SS_RXN<6>")
	)
	(segment
		(start 359.519728 -42.40149)
		(end 358.694736 -43.64863)
		(width 0.1143)
		(layer "In4.Cu")
		(net "P3E_CPU0_PE2_SS_RXN<6>")
	)
	(segment
		(start 394.753592 -3.125724)
		(end 394.986256 -3.125724)
		(width 0.1143)
		(layer "In4.Cu")
		(net "P3E_CPU0_PE2_SS_RXN<6>")
	)
	(segment
		(start 307.206142 -82.261202)
		(end 307.028342 -82.261202)
		(width 0.0889)
		(layer "In4.Cu")
		(net "P3E_CPU0_PE2_SS_RXN<6>")
	)
	(segment
		(start 378.214128 -7.727696)
		(end 372.489476 -14.681708)
		(width 0.1143)
		(layer "In4.Cu")
		(net "P3E_CPU0_PE2_SS_RXN<6>")
	)
	(segment
		(start 378.83719 -6.710934)
		(end 378.859796 -6.943344)
		(width 0.1143)
		(layer "In4.Cu")
		(net "P3E_CPU0_PE2_SS_RXN<6>")
	)
	(segment
		(start 318.304926 -63.4238)
		(end 318.30391 -63.426086)
		(width 0.1143)
		(layer "In4.Cu")
		(net "P3E_CPU0_PE2_SS_RXN<6>")
	)
	(segment
		(start 382.16967 -3.98907)
		(end 380.797054 -4.590034)
		(width 0.1143)
		(layer "In4.Cu")
		(net "P3E_CPU0_PE2_SS_RXN<6>")
	)
	(segment
		(start 324.301358 -54.707028)
		(end 324.30085 -54.707282)
		(width 0.1143)
		(layer "In4.Cu")
		(net "P3E_CPU0_PE2_SS_RXN<6>")
	)
	(segment
		(start 324.301358 -54.706774)
		(end 324.301358 -54.707028)
		(width 0.1143)
		(layer "In4.Cu")
		(net "P3E_CPU0_PE2_SS_RXN<6>")
	)
	(segment
		(start 305.632612 -82.362548)
		(end 305.36896 -82.6262)
		(width 0.0889)
		(layer "In4.Cu")
		(net "P3E_CPU0_PE2_SS_RXN<6>")
	)
	(segment
		(start 391.296398 -4.901692)
		(end 388.40283 -4.287012)
		(width 0.1143)
		(layer "In4.Cu")
		(net "P3E_CPU0_PE2_SS_RXN<6>")
	)
	(segment
		(start 307.542184 -82.309716)
		(end 307.491384 -82.360516)
		(width 0.0889)
		(layer "In4.Cu")
		(net "P3E_CPU0_PE2_SS_RXN<6>")
	)
	(segment
		(start 306.64785 -82.261202)
		(end 306.47005 -82.261202)
		(width 0.0889)
		(layer "In4.Cu")
		(net "P3E_CPU0_PE2_SS_RXN<6>")
	)
	(segment
		(start 378.191522 -7.495286)
		(end 378.214128 -7.727696)
		(width 0.1143)
		(layer "In4.Cu")
		(net "P3E_CPU0_PE2_SS_RXN<6>")
	)
	(segment
		(start 307.564282 -82.309716)
		(end 307.542184 -82.309716)
		(width 0.0889)
		(layer "In4.Cu")
		(net "P3E_CPU0_PE2_SS_RXN<6>")
	)
	(segment
		(start 388.40283 -4.287012)
		(end 385.986274 -4.800346)
		(width 0.1143)
		(layer "In4.Cu")
		(net "P3E_CPU0_PE2_SS_RXN<6>")
	)
	(segment
		(start 379.933454 -5.639054)
		(end 379.701044 -5.66166)
		(width 0.1143)
		(layer "In4.Cu")
		(net "P3E_CPU0_PE2_SS_RXN<6>")
	)
	(segment
		(start 379.055376 -6.446012)
		(end 378.83719 -6.710934)
		(width 0.1143)
		(layer "In4.Cu")
		(net "P3E_CPU0_PE2_SS_RXN<6>")
	)
	(segment
		(start 392.015218 -4.749038)
		(end 391.296398 -4.901692)
		(width 0.1143)
		(layer "In4.Cu")
		(net "P3E_CPU0_PE2_SS_RXN<6>")
	)
	(segment
		(start 385.986274 -4.800346)
		(end 382.16967 -3.98907)
		(width 0.1143)
		(layer "In4.Cu")
		(net "P3E_CPU0_PE2_SS_RXN<6>")
	)
	(segment
		(start 304.563272 -83.050634)
		(end 304.370486 -83.050634)
		(width 0.0889)
		(layer "In4.Cu")
		(net "P3E_CPU0_PE2_SS_RXN<6>")
	)
	(segment
		(start 394.986256 -3.125724)
		(end 395.139164 -3.278632)
		(width 0.1143)
		(layer "In4.Cu")
		(net "P3E_CPU0_PE2_SS_RXN<6>")
	)
	(segment
		(start 366.84839 -27.027632)
		(end 360.795824 -36.106354)
		(width 0.1143)
		(layer "In4.Cu")
		(net "P3E_CPU0_PE2_SS_RXN<6>")
	)
	(segment
		(start 367.298986 -24.77389)
		(end 366.84839 -27.027632)
		(width 0.1143)
		(layer "In4.Cu")
		(net "P3E_CPU0_PE2_SS_RXN<6>")
	)
	(segment
		(start 378.641864 -7.208012)
		(end 378.409454 -7.230618)
		(width 0.1143)
		(layer "In4.Cu")
		(net "P3E_CPU0_PE2_SS_RXN<6>")
	)
	(segment
		(start 368.34953 -23.199344)
		(end 367.298986 -24.77389)
		(width 0.1143)
		(layer "In4.Cu")
		(net "P3E_CPU0_PE2_SS_RXN<6>")
	)
	(segment
		(start 306.47005 -82.261202)
		(end 306.368704 -82.362548)
		(width 0.0889)
		(layer "In4.Cu")
		(net "P3E_CPU0_PE2_SS_RXN<6>")
	)
	(segment
		(start 325.249286 -54.320186)
		(end 324.301358 -54.706774)
		(width 0.1143)
		(layer "In4.Cu")
		(net "P3E_CPU0_PE2_SS_RXN<6>")
	)
	(segment
		(start 307.305456 -82.360516)
		(end 307.206142 -82.261202)
		(width 0.0889)
		(layer "In4.Cu")
		(net "P3E_CPU0_PE2_SS_RXN<6>")
	)
	(segment
		(start 306.749196 -82.362548)
		(end 306.64785 -82.261202)
		(width 0.0889)
		(layer "In4.Cu")
		(net "P3E_CPU0_PE2_SS_RXN<6>")
	)
	(segment
		(start 370.9162 -21.430488)
		(end 370.900198 -21.499068)
		(width 0.1143)
		(layer "In4.Cu")
		(net "P3E_CPU0_PE2_SS_RXN<6>")
	)
	(segment
		(start 330.221844 -49.953164)
		(end 326.671178 -52.252626)
		(width 0.1143)
		(layer "In4.Cu")
		(net "P3E_CPU0_PE2_SS_RXN<6>")
	)
	(segment
		(start 306.089558 -82.261202)
		(end 305.911758 -82.261202)
		(width 0.0889)
		(layer "In4.Cu")
		(net "P3E_CPU0_PE2_SS_RXN<6>")
	)
	(segment
		(start 305.810412 -82.362548)
		(end 305.632612 -82.362548)
		(width 0.0889)
		(layer "In4.Cu")
		(net "P3E_CPU0_PE2_SS_RXN<6>")
	)
	(segment
		(start 318.30391 -63.426086)
		(end 312.304938 -77.909166)
		(width 0.1143)
		(layer "In4.Cu")
		(net "P3E_CPU0_PE2_SS_RXN<6>")
	)
	(segment
		(start 379.505464 -6.158738)
		(end 379.287532 -6.42366)
		(width 0.1143)
		(layer "In4.Cu")
		(net "P3E_CPU0_PE2_SS_RXN<6>")
	)
	(segment
		(start 369.624864 -22.349206)
		(end 369.624864 -22.34946)
		(width 0.1143)
		(layer "In4.Cu")
		(net "P3E_CPU0_PE2_SS_RXN<6>")
	)
	(segment
		(start 395.139164 -4.024884)
		(end 394.401802 -4.762246)
		(width 0.1143)
		(layer "In4.Cu")
		(net "P3E_CPU0_PE2_SS_RXN<6>")
	)
	(segment
		(start 343.910158 -48.174656)
		(end 341.718392 -47.728632)
		(width 0.1143)
		(layer "In4.Cu")
		(net "P3E_CPU0_PE2_SS_RXN<6>")
	)
	(segment
		(start 339.533484 -48.173132)
		(end 337.297014 -47.717964)
		(width 0.1143)
		(layer "In4.Cu")
		(net "P3E_CPU0_PE2_SS_RXN<6>")
	)
	(segment
		(start 307.491384 -82.360516)
		(end 307.305456 -82.360516)
		(width 0.0889)
		(layer "In4.Cu")
		(net "P3E_CPU0_PE2_SS_RXN<6>")
	)
	(segment
		(start 306.926996 -82.362548)
		(end 306.749196 -82.362548)
		(width 0.0889)
		(layer "In4.Cu")
		(net "P3E_CPU0_PE2_SS_RXN<6>")
	)
	(segment
		(start 306.368704 -82.362548)
		(end 306.190904 -82.362548)
		(width 0.0889)
		(layer "In4.Cu")
		(net "P3E_CPU0_PE2_SS_RXN<6>")
	)
	(segment
		(start 326.671178 -52.252626)
		(end 325.249286 -54.320186)
		(width 0.1143)
		(layer "In4.Cu")
		(net "P3E_CPU0_PE2_SS_RXN<6>")
	)
	(segment
		(start 393.240006 -5.009134)
		(end 392.015218 -4.749038)
		(width 0.1143)
		(layer "In4.Cu")
		(net "P3E_CPU0_PE2_SS_RXN<6>")
	)
	(segment
		(start 303.23663 -82.976974)
		(end 303.529746 -83.146138)
		(width 0.0889)
		(layer "In4.Cu")
		(net "P3E_CPU0_PE2_SS_RXN<6>")
	)
	(segment
		(start 304.987706 -82.6262)
		(end 304.563272 -83.050634)
		(width 0.0889)
		(layer "In4.Cu")
		(net "P3E_CPU0_PE2_SS_RXN<6>")
	)
	(segment
		(start 303.15789 -82.99831)
		(end 303.23663 -82.976974)
		(width 0.0889)
		(layer "In4.Cu")
		(net "P3E_CPU0_PE2_SS_RXN<6>")
	)
	(segment
		(start 360.795824 -36.106354)
		(end 359.519728 -42.40149)
		(width 0.1143)
		(layer "In4.Cu")
		(net "P3E_CPU0_PE2_SS_RXN<6>")
	)
	(arc
		(start 303.156112 -83.28914)
		(mid 303.129597 -83.143549)
		(end 303.15789 -82.99831)
		(width 0.0889)
		(layer "In4.Cu")
		(net "P3E_CPU0_PE2_SS_RXN<6>")
	)
	(arc
		(start 304.370486 -83.050634)
		(mid 304.085062 -83.134101)
		(end 303.876456 -83.346036)
		(width 0.0889)
		(layer "In4.Cu")
		(net "P3E_CPU0_PE2_SS_RXN<6>")
	)
	(arc
		(start 303.517808 -83.545934)
		(mid 303.298096 -83.472259)
		(end 303.156112 -83.28914)
		(width 0.0889)
		(layer "In4.Cu")
		(net "P3E_CPU0_PE2_SS_RXN<6>")
	)
	(arc
		(start 303.876456 -83.346036)
		(mid 303.735157 -83.4894)
		(end 303.541938 -83.545934)
		(width 0.0889)
		(layer "In4.Cu")
		(net "P3E_CPU0_PE2_SS_RXN<6>")
	)
	(arc
		(start 303.541938 -83.545934)
		(mid 303.529873 -83.546112)
		(end 303.517808 -83.545934)
		(width 0.0889)
		(layer "In4.Cu")
		(net "P3E_CPU0_PE2_SS_RXN<6>")
	)
	(segment
		(start 397.864076 -3.176524)
		(end 397.766286 -3.274314)
		(width 0.1143)
		(layer "F.Cu")
		(net "P3E_CPU0_PE2_SS_RXN<5>")
	)
	(segment
		(start 397.766286 -3.274314)
		(end 397.766286 -3.453384)
		(width 0.1143)
		(layer "F.Cu")
		(net "P3E_CPU0_PE2_SS_RXN<5>")
	)
	(segment
		(start 398.071086 -3.758184)
		(end 398.071086 -4.386072)
		(width 0.1143)
		(layer "F.Cu")
		(net "P3E_CPU0_PE2_SS_RXN<5>")
	)
	(segment
		(start 398.144492 -3.176524)
		(end 397.864076 -3.176524)
		(width 0.1143)
		(layer "F.Cu")
		(net "P3E_CPU0_PE2_SS_RXN<5>")
	)
	(segment
		(start 301.241206 -84.136738)
		(end 301.812706 -84.136738)
		(width 0.1143)
		(layer "F.Cu")
		(net "P3E_CPU0_PE2_SS_RXN<5>")
	)
	(segment
		(start 397.766286 -3.453384)
		(end 398.071086 -3.758184)
		(width 0.1143)
		(layer "F.Cu")
		(net "P3E_CPU0_PE2_SS_RXN<5>")
	)
	(via
		(at 301.812706 -84.136738)
		(size 0.508)
		(drill 0.254)
		(layers "F.Cu" "B.Cu")
		(net "P3E_CPU0_PE2_SS_RXN<5>")
	)
	(via
		(at 398.144492 -3.176524)
		(size 0.508)
		(drill 0.254)
		(layers "F.Cu" "B.Cu")
		(net "P3E_CPU0_PE2_SS_RXN<5>")
	)
	(segment
		(start 305.04384 -83.687412)
		(end 305.266852 -83.4644)
		(width 0.0889)
		(layer "In4.Cu")
		(net "P3E_CPU0_PE2_SS_RXN<5>")
	)
	(segment
		(start 361.69981 -36.42741)
		(end 361.69981 -36.426902)
		(width 0.1143)
		(layer "In4.Cu")
		(net "P3E_CPU0_PE2_SS_RXN<5>")
	)
	(segment
		(start 337.36915 -48.683418)
		(end 339.616034 -49.14138)
		(width 0.1143)
		(layer "In4.Cu")
		(net "P3E_CPU0_PE2_SS_RXN<5>")
	)
	(segment
		(start 305.7144 -83.4644)
		(end 305.9176 -83.2612)
		(width 0.0889)
		(layer "In4.Cu")
		(net "P3E_CPU0_PE2_SS_RXN<5>")
	)
	(segment
		(start 313.029092 -78.618588)
		(end 319.15989 -63.821564)
		(width 0.1143)
		(layer "In4.Cu")
		(net "P3E_CPU0_PE2_SS_RXN<5>")
	)
	(segment
		(start 308.540658 -83.02117)
		(end 311.956704 -79.925418)
		(width 0.1143)
		(layer "In4.Cu")
		(net "P3E_CPU0_PE2_SS_RXN<5>")
	)
	(segment
		(start 305.9176 -83.2612)
		(end 307.314854 -83.2612)
		(width 0.0889)
		(layer "In4.Cu")
		(net "P3E_CPU0_PE2_SS_RXN<5>")
	)
	(segment
		(start 357.689658 -45.45076)
		(end 359.375456 -44.335192)
		(width 0.1143)
		(layer "In4.Cu")
		(net "P3E_CPU0_PE2_SS_RXN<5>")
	)
	(segment
		(start 307.365654 -83.312)
		(end 307.387752 -83.312)
		(width 0.0889)
		(layer "In4.Cu")
		(net "P3E_CPU0_PE2_SS_RXN<5>")
	)
	(segment
		(start 367.782348 -27.316684)
		(end 368.116866 -25.690576)
		(width 0.1143)
		(layer "In4.Cu")
		(net "P3E_CPU0_PE2_SS_RXN<5>")
	)
	(segment
		(start 384.463036 -7.550912)
		(end 389.84809 -8.694166)
		(width 0.1143)
		(layer "In4.Cu")
		(net "P3E_CPU0_PE2_SS_RXN<5>")
	)
	(segment
		(start 302.105822 -83.967574)
		(end 302.19523 -83.991704)
		(width 0.0889)
		(layer "In4.Cu")
		(net "P3E_CPU0_PE2_SS_RXN<5>")
	)
	(segment
		(start 368.116866 -25.690576)
		(end 371.37086 -23.90902)
		(width 0.1143)
		(layer "In4.Cu")
		(net "P3E_CPU0_PE2_SS_RXN<5>")
	)
	(segment
		(start 397.796766 -4.361434)
		(end 397.796766 -3.379724)
		(width 0.1143)
		(layer "In4.Cu")
		(net "P3E_CPU0_PE2_SS_RXN<5>")
	)
	(segment
		(start 325.872602 -55.067454)
		(end 327.345548 -52.925218)
		(width 0.1143)
		(layer "In4.Cu")
		(net "P3E_CPU0_PE2_SS_RXN<5>")
	)
	(segment
		(start 303.017936 -84.431886)
		(end 303.020984 -84.43722)
		(width 0.0889)
		(layer "In4.Cu")
		(net "P3E_CPU0_PE2_SS_RXN<5>")
	)
	(segment
		(start 341.797132 -48.697642)
		(end 343.944194 -49.134776)
		(width 0.1143)
		(layer "In4.Cu")
		(net "P3E_CPU0_PE2_SS_RXN<5>")
	)
	(segment
		(start 303.513236 -84.727288)
		(end 303.515014 -84.727288)
		(width 0.0889)
		(layer "In4.Cu")
		(net "P3E_CPU0_PE2_SS_RXN<5>")
	)
	(segment
		(start 360.41457 -42.76471)
		(end 361.69981 -36.42741)
		(width 0.1143)
		(layer "In4.Cu")
		(net "P3E_CPU0_PE2_SS_RXN<5>")
	)
	(segment
		(start 304.900076 -83.936586)
		(end 305.04384 -83.687412)
		(width 0.0889)
		(layer "In4.Cu")
		(net "P3E_CPU0_PE2_SS_RXN<5>")
	)
	(segment
		(start 324.911466 -55.45963)
		(end 325.872602 -55.067454)
		(width 0.1143)
		(layer "In4.Cu")
		(net "P3E_CPU0_PE2_SS_RXN<5>")
	)
	(segment
		(start 305.266852 -83.4644)
		(end 305.7144 -83.4644)
		(width 0.0889)
		(layer "In4.Cu")
		(net "P3E_CPU0_PE2_SS_RXN<5>")
	)
	(segment
		(start 378.759974 -9.965436)
		(end 381.035814 -6.779514)
		(width 0.1143)
		(layer "In4.Cu")
		(net "P3E_CPU0_PE2_SS_RXN<5>")
	)
	(segment
		(start 303.020984 -84.43722)
		(end 303.021746 -84.43849)
		(width 0.0889)
		(layer "In4.Cu")
		(net "P3E_CPU0_PE2_SS_RXN<5>")
	)
	(segment
		(start 373.40032 -15.203932)
		(end 376.889518 -10.96518)
		(width 0.1143)
		(layer "In4.Cu")
		(net "P3E_CPU0_PE2_SS_RXN<5>")
	)
	(segment
		(start 376.889518 -10.96518)
		(end 378.759974 -9.965436)
		(width 0.1143)
		(layer "In4.Cu")
		(net "P3E_CPU0_PE2_SS_RXN<5>")
	)
	(segment
		(start 330.596494 -50.819812)
		(end 337.36915 -48.683418)
		(width 0.1143)
		(layer "In4.Cu")
		(net "P3E_CPU0_PE2_SS_RXN<5>")
	)
	(segment
		(start 301.812706 -84.136738)
		(end 302.105822 -83.967574)
		(width 0.0889)
		(layer "In4.Cu")
		(net "P3E_CPU0_PE2_SS_RXN<5>")
	)
	(segment
		(start 343.944194 -49.134776)
		(end 357.689658 -45.45076)
		(width 0.1143)
		(layer "In4.Cu")
		(net "P3E_CPU0_PE2_SS_RXN<5>")
	)
	(segment
		(start 382.687068 -6.444234)
		(end 384.463036 -7.550912)
		(width 0.1143)
		(layer "In4.Cu")
		(net "P3E_CPU0_PE2_SS_RXN<5>")
	)
	(segment
		(start 339.616034 -49.14138)
		(end 341.797132 -48.697642)
		(width 0.1143)
		(layer "In4.Cu")
		(net "P3E_CPU0_PE2_SS_RXN<5>")
	)
	(segment
		(start 308.10581 -83.312)
		(end 308.540658 -83.02117)
		(width 0.1143)
		(layer "In4.Cu")
		(net "P3E_CPU0_PE2_SS_RXN<5>")
	)
	(segment
		(start 311.956704 -79.925418)
		(end 313.029092 -78.618588)
		(width 0.1143)
		(layer "In4.Cu")
		(net "P3E_CPU0_PE2_SS_RXN<5>")
	)
	(segment
		(start 397.999966 -3.176524)
		(end 398.144492 -3.176524)
		(width 0.1143)
		(layer "In4.Cu")
		(net "P3E_CPU0_PE2_SS_RXN<5>")
	)
	(segment
		(start 372.584472 -18.70329)
		(end 373.40032 -15.203932)
		(width 0.1143)
		(layer "In4.Cu")
		(net "P3E_CPU0_PE2_SS_RXN<5>")
	)
	(segment
		(start 327.345548 -52.925218)
		(end 330.596494 -50.819812)
		(width 0.1143)
		(layer "In4.Cu")
		(net "P3E_CPU0_PE2_SS_RXN<5>")
	)
	(segment
		(start 307.387752 -83.312)
		(end 308.10581 -83.312)
		(width 0.1143)
		(layer "In4.Cu")
		(net "P3E_CPU0_PE2_SS_RXN<5>")
	)
	(segment
		(start 304.37709 -84.231734)
		(end 304.409856 -84.231734)
		(width 0.0889)
		(layer "In4.Cu")
		(net "P3E_CPU0_PE2_SS_RXN<5>")
	)
	(segment
		(start 397.796766 -3.379724)
		(end 397.999966 -3.176524)
		(width 0.1143)
		(layer "In4.Cu")
		(net "P3E_CPU0_PE2_SS_RXN<5>")
	)
	(segment
		(start 359.375456 -44.335192)
		(end 360.41457 -42.76471)
		(width 0.1143)
		(layer "In4.Cu")
		(net "P3E_CPU0_PE2_SS_RXN<5>")
	)
	(segment
		(start 319.15989 -63.821564)
		(end 324.911466 -55.45963)
		(width 0.1143)
		(layer "In4.Cu")
		(net "P3E_CPU0_PE2_SS_RXN<5>")
	)
	(segment
		(start 302.652938 -84.231734)
		(end 302.685704 -84.231734)
		(width 0.0889)
		(layer "In4.Cu")
		(net "P3E_CPU0_PE2_SS_RXN<5>")
	)
	(segment
		(start 371.37086 -23.90902)
		(end 372.584472 -18.70329)
		(width 0.1143)
		(layer "In4.Cu")
		(net "P3E_CPU0_PE2_SS_RXN<5>")
	)
	(segment
		(start 395.342618 -6.815582)
		(end 397.796766 -4.361434)
		(width 0.1143)
		(layer "In4.Cu")
		(net "P3E_CPU0_PE2_SS_RXN<5>")
	)
	(segment
		(start 307.314854 -83.2612)
		(end 307.365654 -83.312)
		(width 0.0889)
		(layer "In4.Cu")
		(net "P3E_CPU0_PE2_SS_RXN<5>")
	)
	(segment
		(start 381.035814 -6.779514)
		(end 382.687068 -6.444234)
		(width 0.1143)
		(layer "In4.Cu")
		(net "P3E_CPU0_PE2_SS_RXN<5>")
	)
	(segment
		(start 389.84809 -8.694166)
		(end 395.342618 -6.815582)
		(width 0.1143)
		(layer "In4.Cu")
		(net "P3E_CPU0_PE2_SS_RXN<5>")
	)
	(segment
		(start 361.69981 -36.426902)
		(end 367.782348 -27.316684)
		(width 0.1143)
		(layer "In4.Cu")
		(net "P3E_CPU0_PE2_SS_RXN<5>")
	)
	(arc
		(start 302.685704 -84.231734)
		(mid 302.877721 -84.288842)
		(end 303.017936 -84.431886)
		(width 0.0889)
		(layer "In4.Cu")
		(net "P3E_CPU0_PE2_SS_RXN<5>")
	)
	(arc
		(start 304.409856 -84.231734)
		(mid 304.693073 -84.147453)
		(end 304.900076 -83.936586)
		(width 0.0889)
		(layer "In4.Cu")
		(net "P3E_CPU0_PE2_SS_RXN<5>")
	)
	(arc
		(start 303.547272 -84.727288)
		(mid 303.832837 -84.643879)
		(end 304.041556 -84.431886)
		(width 0.0889)
		(layer "In4.Cu")
		(net "P3E_CPU0_PE2_SS_RXN<5>")
	)
	(arc
		(start 303.515014 -84.727288)
		(mid 303.531143 -84.727512)
		(end 303.547272 -84.727288)
		(width 0.0889)
		(layer "In4.Cu")
		(net "P3E_CPU0_PE2_SS_RXN<5>")
	)
	(arc
		(start 304.041556 -84.431886)
		(mid 304.183239 -84.288082)
		(end 304.37709 -84.231734)
		(width 0.0889)
		(layer "In4.Cu")
		(net "P3E_CPU0_PE2_SS_RXN<5>")
	)
	(arc
		(start 302.19523 -83.991704)
		(mid 302.394975 -84.163698)
		(end 302.649636 -84.231734)
		(width 0.0889)
		(layer "In4.Cu")
		(net "P3E_CPU0_PE2_SS_RXN<5>")
	)
	(arc
		(start 302.649636 -84.231734)
		(mid 302.651287 -84.231737)
		(end 302.652938 -84.231734)
		(width 0.0889)
		(layer "In4.Cu")
		(net "P3E_CPU0_PE2_SS_RXN<5>")
	)
	(arc
		(start 303.021746 -84.43849)
		(mid 303.230203 -84.646353)
		(end 303.513236 -84.727288)
		(width 0.0889)
		(layer "In4.Cu")
		(net "P3E_CPU0_PE2_SS_RXN<5>")
	)
	(segment
		(start 400.191986 -3.478784)
		(end 400.471386 -3.758184)
		(width 0.1143)
		(layer "F.Cu")
		(net "P3E_CPU0_PE2_SS_RXN<4>")
	)
	(segment
		(start 400.471386 -3.758184)
		(end 400.471386 -4.386072)
		(width 0.1143)
		(layer "F.Cu")
		(net "P3E_CPU0_PE2_SS_RXN<4>")
	)
	(segment
		(start 400.570192 -3.176524)
		(end 400.251676 -3.176524)
		(width 0.1143)
		(layer "F.Cu")
		(net "P3E_CPU0_PE2_SS_RXN<4>")
	)
	(segment
		(start 302.099726 -85.622384)
		(end 302.671226 -85.622384)
		(width 0.1143)
		(layer "F.Cu")
		(net "P3E_CPU0_PE2_SS_RXN<4>")
	)
	(segment
		(start 400.191986 -3.236214)
		(end 400.191986 -3.478784)
		(width 0.1143)
		(layer "F.Cu")
		(net "P3E_CPU0_PE2_SS_RXN<4>")
	)
	(segment
		(start 400.251676 -3.176524)
		(end 400.191986 -3.236214)
		(width 0.1143)
		(layer "F.Cu")
		(net "P3E_CPU0_PE2_SS_RXN<4>")
	)
	(via
		(at 302.671226 -85.622384)
		(size 0.508)
		(drill 0.254)
		(layers "F.Cu" "B.Cu")
		(net "P3E_CPU0_PE2_SS_RXN<4>")
	)
	(via
		(at 400.570192 -3.176524)
		(size 0.508)
		(drill 0.254)
		(layers "F.Cu" "B.Cu")
		(net "P3E_CPU0_PE2_SS_RXN<4>")
	)
	(segment
		(start 306.222654 -83.937348)
		(end 306.56403 -83.937348)
		(width 0.0889)
		(layer "In4.Cu")
		(net "P3E_CPU0_PE2_SS_RXN<4>")
	)
	(segment
		(start 302.671226 -85.28431)
		(end 302.729138 -85.226398)
		(width 0.0889)
		(layer "In4.Cu")
		(net "P3E_CPU0_PE2_SS_RXN<4>")
	)
	(segment
		(start 357.9622 -46.03623)
		(end 358.076246 -46.00575)
		(width 0.1143)
		(layer "In4.Cu")
		(net "P3E_CPU0_PE2_SS_RXN<4>")
	)
	(segment
		(start 377.317508 -11.505184)
		(end 380.524766 -9.78408)
		(width 0.1143)
		(layer "In4.Cu")
		(net "P3E_CPU0_PE2_SS_RXN<4>")
	)
	(segment
		(start 305.2318 -84.727288)
		(end 305.264566 -84.727288)
		(width 0.0889)
		(layer "In4.Cu")
		(net "P3E_CPU0_PE2_SS_RXN<4>")
	)
	(segment
		(start 305.80076 -84.358734)
		(end 306.222654 -83.937348)
		(width 0.0889)
		(layer "In4.Cu")
		(net "P3E_CPU0_PE2_SS_RXN<4>")
	)
	(segment
		(start 369.290346 -29.69006)
		(end 369.64874 -29.450792)
		(width 0.1143)
		(layer "In4.Cu")
		(net "P3E_CPU0_PE2_SS_RXN<4>")
	)
	(segment
		(start 306.56403 -83.937348)
		(end 306.61483 -83.988148)
		(width 0.0889)
		(layer "In4.Cu")
		(net "P3E_CPU0_PE2_SS_RXN<4>")
	)
	(segment
		(start 400.182842 -4.3815)
		(end 400.182842 -3.346704)
		(width 0.1143)
		(layer "In4.Cu")
		(net "P3E_CPU0_PE2_SS_RXN<4>")
	)
	(segment
		(start 358.076246 -46.00575)
		(end 359.785666 -44.874434)
		(width 0.1143)
		(layer "In4.Cu")
		(net "P3E_CPU0_PE2_SS_RXN<4>")
	)
	(segment
		(start 312.1533 -80.77327)
		(end 313.513216 -79.115666)
		(width 0.1143)
		(layer "In4.Cu")
		(net "P3E_CPU0_PE2_SS_RXN<4>")
	)
	(segment
		(start 303.017936 -85.422486)
		(end 303.030382 -85.44433)
		(width 0.0889)
		(layer "In4.Cu")
		(net "P3E_CPU0_PE2_SS_RXN<4>")
	)
	(segment
		(start 309.370476 -83.29549)
		(end 312.1533 -80.77327)
		(width 0.1143)
		(layer "In4.Cu")
		(net "P3E_CPU0_PE2_SS_RXN<4>")
	)
	(segment
		(start 337.449414 -49.364392)
		(end 339.671914 -49.816766)
		(width 0.1143)
		(layer "In4.Cu")
		(net "P3E_CPU0_PE2_SS_RXN<4>")
	)
	(segment
		(start 374.020588 -15.509494)
		(end 377.317508 -11.505184)
		(width 0.1143)
		(layer "In4.Cu")
		(net "P3E_CPU0_PE2_SS_RXN<4>")
	)
	(segment
		(start 306.61483 -83.988148)
		(end 306.636928 -83.988148)
		(width 0.0889)
		(layer "In4.Cu")
		(net "P3E_CPU0_PE2_SS_RXN<4>")
	)
	(segment
		(start 359.785666 -44.874434)
		(end 361.01274 -43.020996)
		(width 0.1143)
		(layer "In4.Cu")
		(net "P3E_CPU0_PE2_SS_RXN<4>")
	)
	(segment
		(start 369.64874 -29.450792)
		(end 370.641626 -25.056846)
		(width 0.1143)
		(layer "In4.Cu")
		(net "P3E_CPU0_PE2_SS_RXN<4>")
	)
	(segment
		(start 303.514506 -85.717888)
		(end 303.515014 -85.717888)
		(width 0.0889)
		(layer "In4.Cu")
		(net "P3E_CPU0_PE2_SS_RXN<4>")
	)
	(segment
		(start 303.030382 -85.44433)
		(end 303.032668 -85.446616)
		(width 0.0889)
		(layer "In4.Cu")
		(net "P3E_CPU0_PE2_SS_RXN<4>")
	)
	(segment
		(start 302.671226 -85.622384)
		(end 302.671226 -85.28431)
		(width 0.0889)
		(layer "In4.Cu")
		(net "P3E_CPU0_PE2_SS_RXN<4>")
	)
	(segment
		(start 319.71996 -64.13246)
		(end 325.33082 -55.974742)
		(width 0.1143)
		(layer "In4.Cu")
		(net "P3E_CPU0_PE2_SS_RXN<4>")
	)
	(segment
		(start 361.01274 -43.020996)
		(end 362.294424 -36.716462)
		(width 0.1143)
		(layer "In4.Cu")
		(net "P3E_CPU0_PE2_SS_RXN<4>")
	)
	(segment
		(start 326.30237 -55.578248)
		(end 327.807066 -53.3908)
		(width 0.1143)
		(layer "In4.Cu")
		(net "P3E_CPU0_PE2_SS_RXN<4>")
	)
	(segment
		(start 386.024374 -8.61568)
		(end 389.765794 -9.40943)
		(width 0.1143)
		(layer "In4.Cu")
		(net "P3E_CPU0_PE2_SS_RXN<4>")
	)
	(segment
		(start 343.94521 -49.793398)
		(end 357.9622 -46.03623)
		(width 0.1143)
		(layer "In4.Cu")
		(net "P3E_CPU0_PE2_SS_RXN<4>")
	)
	(segment
		(start 380.524766 -9.78408)
		(end 386.024374 -8.61568)
		(width 0.1143)
		(layer "In4.Cu")
		(net "P3E_CPU0_PE2_SS_RXN<4>")
	)
	(segment
		(start 366.62106 -30.22346)
		(end 369.290346 -29.69006)
		(width 0.1143)
		(layer "In4.Cu")
		(net "P3E_CPU0_PE2_SS_RXN<4>")
	)
	(segment
		(start 400.182842 -3.346704)
		(end 400.353022 -3.176524)
		(width 0.1143)
		(layer "In4.Cu")
		(net "P3E_CPU0_PE2_SS_RXN<4>")
	)
	(segment
		(start 371.958108 -24.357838)
		(end 374.020588 -15.509494)
		(width 0.1143)
		(layer "In4.Cu")
		(net "P3E_CPU0_PE2_SS_RXN<4>")
	)
	(segment
		(start 327.807066 -53.3908)
		(end 330.777088 -51.467004)
		(width 0.1143)
		(layer "In4.Cu")
		(net "P3E_CPU0_PE2_SS_RXN<4>")
	)
	(segment
		(start 339.671914 -49.816766)
		(end 341.866474 -49.370488)
		(width 0.1143)
		(layer "In4.Cu")
		(net "P3E_CPU0_PE2_SS_RXN<4>")
	)
	(segment
		(start 341.866474 -49.370488)
		(end 343.94521 -49.793398)
		(width 0.1143)
		(layer "In4.Cu")
		(net "P3E_CPU0_PE2_SS_RXN<4>")
	)
	(segment
		(start 400.353022 -3.176524)
		(end 400.570192 -3.176524)
		(width 0.1143)
		(layer "In4.Cu")
		(net "P3E_CPU0_PE2_SS_RXN<4>")
	)
	(segment
		(start 325.33082 -55.974742)
		(end 326.30237 -55.578248)
		(width 0.1143)
		(layer "In4.Cu")
		(net "P3E_CPU0_PE2_SS_RXN<4>")
	)
	(segment
		(start 308.333648 -83.988148)
		(end 309.370476 -83.29549)
		(width 0.1143)
		(layer "In4.Cu")
		(net "P3E_CPU0_PE2_SS_RXN<4>")
	)
	(segment
		(start 306.636928 -83.988148)
		(end 308.333648 -83.988148)
		(width 0.1143)
		(layer "In4.Cu")
		(net "P3E_CPU0_PE2_SS_RXN<4>")
	)
	(segment
		(start 362.294424 -36.716462)
		(end 366.62106 -30.22346)
		(width 0.1143)
		(layer "In4.Cu")
		(net "P3E_CPU0_PE2_SS_RXN<4>")
	)
	(segment
		(start 397.953738 -6.610604)
		(end 400.182842 -4.3815)
		(width 0.1143)
		(layer "In4.Cu")
		(net "P3E_CPU0_PE2_SS_RXN<4>")
	)
	(segment
		(start 370.641626 -25.056846)
		(end 371.958108 -24.357838)
		(width 0.1143)
		(layer "In4.Cu")
		(net "P3E_CPU0_PE2_SS_RXN<4>")
	)
	(segment
		(start 304.37709 -85.222334)
		(end 304.409856 -85.222334)
		(width 0.0889)
		(layer "In4.Cu")
		(net "P3E_CPU0_PE2_SS_RXN<4>")
	)
	(segment
		(start 389.765794 -9.40943)
		(end 397.953738 -6.610604)
		(width 0.1143)
		(layer "In4.Cu")
		(net "P3E_CPU0_PE2_SS_RXN<4>")
	)
	(segment
		(start 313.513216 -79.115666)
		(end 319.71996 -64.13246)
		(width 0.1143)
		(layer "In4.Cu")
		(net "P3E_CPU0_PE2_SS_RXN<4>")
	)
	(segment
		(start 305.75885 -84.431886)
		(end 305.80076 -84.358734)
		(width 0.0889)
		(layer "In4.Cu")
		(net "P3E_CPU0_PE2_SS_RXN<4>")
	)
	(segment
		(start 330.777088 -51.467004)
		(end 337.449414 -49.364392)
		(width 0.1143)
		(layer "In4.Cu")
		(net "P3E_CPU0_PE2_SS_RXN<4>")
	)
	(arc
		(start 304.041556 -85.422486)
		(mid 304.183239 -85.278682)
		(end 304.37709 -85.222334)
		(width 0.0889)
		(layer "In4.Cu")
		(net "P3E_CPU0_PE2_SS_RXN<4>")
	)
	(arc
		(start 303.515014 -85.717888)
		(mid 303.531143 -85.718112)
		(end 303.547272 -85.717888)
		(width 0.0889)
		(layer "In4.Cu")
		(net "P3E_CPU0_PE2_SS_RXN<4>")
	)
	(arc
		(start 304.409856 -85.222334)
		(mid 304.693073 -85.138053)
		(end 304.900076 -84.927186)
		(width 0.0889)
		(layer "In4.Cu")
		(net "P3E_CPU0_PE2_SS_RXN<4>")
	)
	(arc
		(start 305.264566 -84.727288)
		(mid 305.550131 -84.643879)
		(end 305.75885 -84.431886)
		(width 0.0889)
		(layer "In4.Cu")
		(net "P3E_CPU0_PE2_SS_RXN<4>")
	)
	(arc
		(start 303.547272 -85.717888)
		(mid 303.832837 -85.634479)
		(end 304.041556 -85.422486)
		(width 0.0889)
		(layer "In4.Cu")
		(net "P3E_CPU0_PE2_SS_RXN<4>")
	)
	(arc
		(start 303.032668 -85.446616)
		(mid 303.239834 -85.642175)
		(end 303.514506 -85.717888)
		(width 0.0889)
		(layer "In4.Cu")
		(net "P3E_CPU0_PE2_SS_RXN<4>")
	)
	(arc
		(start 302.729138 -85.226398)
		(mid 302.896039 -85.291298)
		(end 303.017936 -85.422486)
		(width 0.0889)
		(layer "In4.Cu")
		(net "P3E_CPU0_PE2_SS_RXN<4>")
	)
	(arc
		(start 304.900076 -84.927186)
		(mid 305.040155 -84.78445)
		(end 305.2318 -84.727288)
		(width 0.0889)
		(layer "In4.Cu")
		(net "P3E_CPU0_PE2_SS_RXN<4>")
	)
	(segment
		(start 402.871686 -3.758184)
		(end 402.592286 -3.478784)
		(width 0.1143)
		(layer "F.Cu")
		(net "P3E_CPU0_PE2_SS_RXN<3>")
	)
	(segment
		(start 302.099726 -86.612984)
		(end 302.671226 -86.612984)
		(width 0.1143)
		(layer "F.Cu")
		(net "P3E_CPU0_PE2_SS_RXN<3>")
	)
	(segment
		(start 402.592286 -3.064256)
		(end 402.772372 -2.88417)
		(width 0.1143)
		(layer "F.Cu")
		(net "P3E_CPU0_PE2_SS_RXN<3>")
	)
	(segment
		(start 402.871686 -4.386072)
		(end 402.871686 -3.758184)
		(width 0.1143)
		(layer "F.Cu")
		(net "P3E_CPU0_PE2_SS_RXN<3>")
	)
	(segment
		(start 402.772372 -2.88417)
		(end 403.097492 -2.88417)
		(width 0.1143)
		(layer "F.Cu")
		(net "P3E_CPU0_PE2_SS_RXN<3>")
	)
	(segment
		(start 402.592286 -3.478784)
		(end 402.592286 -3.064256)
		(width 0.1143)
		(layer "F.Cu")
		(net "P3E_CPU0_PE2_SS_RXN<3>")
	)
	(via
		(at 302.671226 -86.612984)
		(size 0.508)
		(drill 0.254)
		(layers "F.Cu" "B.Cu")
		(net "P3E_CPU0_PE2_SS_RXN<3>")
	)
	(via
		(at 403.097492 -2.88417)
		(size 0.508)
		(drill 0.254)
		(layers "F.Cu" "B.Cu")
		(net "P3E_CPU0_PE2_SS_RXN<3>")
	)
	(segment
		(start 308.689502 -85.066124)
		(end 308.691534 -85.0646)
		(width 0.0889)
		(layer "In4.Cu")
		(net "P3E_CPU0_PE2_SS_RXN<3>")
	)
	(segment
		(start 372.551452 -24.776938)
		(end 374.640348 -15.816326)
		(width 0.1143)
		(layer "In4.Cu")
		(net "P3E_CPU0_PE2_SS_RXN<3>")
	)
	(segment
		(start 303.31156 -86.667086)
		(end 303.32807 -86.67369)
		(width 0.0889)
		(layer "In4.Cu")
		(net "P3E_CPU0_PE2_SS_RXN<3>")
	)
	(segment
		(start 331.057758 -52.050696)
		(end 337.463384 -50.03165)
		(width 0.1143)
		(layer "In4.Cu")
		(net "P3E_CPU0_PE2_SS_RXN<3>")
	)
	(segment
		(start 401.060666 -4.867656)
		(end 401.06092 -4.867656)
		(width 0.1143)
		(layer "In4.Cu")
		(net "P3E_CPU0_PE2_SS_RXN<3>")
	)
	(segment
		(start 369.639088 -30.27045)
		(end 370.262658 -29.842206)
		(width 0.1143)
		(layer "In4.Cu")
		(net "P3E_CPU0_PE2_SS_RXN<3>")
	)
	(segment
		(start 341.943182 -50.041556)
		(end 343.97569 -50.455322)
		(width 0.1143)
		(layer "In4.Cu")
		(net "P3E_CPU0_PE2_SS_RXN<3>")
	)
	(segment
		(start 367.0046 -30.805628)
		(end 369.639088 -30.27045)
		(width 0.1143)
		(layer "In4.Cu")
		(net "P3E_CPU0_PE2_SS_RXN<3>")
	)
	(segment
		(start 385.75234 -9.362948)
		(end 389.525002 -10.164826)
		(width 0.1143)
		(layer "In4.Cu")
		(net "P3E_CPU0_PE2_SS_RXN<3>")
	)
	(segment
		(start 377.752864 -12.035282)
		(end 380.751334 -10.426192)
		(width 0.1143)
		(layer "In4.Cu")
		(net "P3E_CPU0_PE2_SS_RXN<3>")
	)
	(segment
		(start 302.671226 -86.612984)
		(end 303.028604 -86.612984)
		(width 0.0889)
		(layer "In4.Cu")
		(net "P3E_CPU0_PE2_SS_RXN<3>")
	)
	(segment
		(start 309.502556 -84.293964)
		(end 309.7022 -83.983068)
		(width 0.1143)
		(layer "In4.Cu")
		(net "P3E_CPU0_PE2_SS_RXN<3>")
	)
	(segment
		(start 306.073556 -85.223858)
		(end 308.385718 -85.223858)
		(width 0.0889)
		(layer "In4.Cu")
		(net "P3E_CPU0_PE2_SS_RXN<3>")
	)
	(segment
		(start 328.267568 -53.857906)
		(end 331.057758 -52.050696)
		(width 0.1143)
		(layer "In4.Cu")
		(net "P3E_CPU0_PE2_SS_RXN<3>")
	)
	(segment
		(start 399.004282 -6.92404)
		(end 401.060666 -4.867656)
		(width 0.1143)
		(layer "In4.Cu")
		(net "P3E_CPU0_PE2_SS_RXN<3>")
	)
	(segment
		(start 312.72734 -81.138014)
		(end 314.024264 -79.554832)
		(width 0.1143)
		(layer "In4.Cu")
		(net "P3E_CPU0_PE2_SS_RXN<3>")
	)
	(segment
		(start 320.289682 -64.42964)
		(end 325.750936 -56.489346)
		(width 0.1143)
		(layer "In4.Cu")
		(net "P3E_CPU0_PE2_SS_RXN<3>")
	)
	(segment
		(start 309.731918 -83.93684)
		(end 310.63438 -83.034378)
		(width 0.1143)
		(layer "In4.Cu")
		(net "P3E_CPU0_PE2_SS_RXN<3>")
	)
	(segment
		(start 308.839362 -84.957158)
		(end 309.502556 -84.293964)
		(width 0.1143)
		(layer "In4.Cu")
		(net "P3E_CPU0_PE2_SS_RXN<3>")
	)
	(segment
		(start 304.37709 -86.212934)
		(end 304.409856 -86.212934)
		(width 0.0889)
		(layer "In4.Cu")
		(net "P3E_CPU0_PE2_SS_RXN<3>")
	)
	(segment
		(start 309.7022 -83.983068)
		(end 309.731918 -83.93684)
		(width 0.1143)
		(layer "In4.Cu")
		(net "P3E_CPU0_PE2_SS_RXN<3>")
	)
	(segment
		(start 361.626404 -43.295316)
		(end 362.912152 -36.954968)
		(width 0.1143)
		(layer "In4.Cu")
		(net "P3E_CPU0_PE2_SS_RXN<3>")
	)
	(segment
		(start 343.97569 -50.455322)
		(end 358.320848 -46.610778)
		(width 0.1143)
		(layer "In4.Cu")
		(net "P3E_CPU0_PE2_SS_RXN<3>")
	)
	(segment
		(start 305.22926 -85.717888)
		(end 305.579526 -85.717888)
		(width 0.0889)
		(layer "In4.Cu")
		(net "P3E_CPU0_PE2_SS_RXN<3>")
	)
	(segment
		(start 380.751334 -10.426192)
		(end 385.75234 -9.362948)
		(width 0.1143)
		(layer "In4.Cu")
		(net "P3E_CPU0_PE2_SS_RXN<3>")
	)
	(segment
		(start 362.912152 -36.954968)
		(end 367.0046 -30.805628)
		(width 0.1143)
		(layer "In4.Cu")
		(net "P3E_CPU0_PE2_SS_RXN<3>")
	)
	(segment
		(start 358.320848 -46.610778)
		(end 360.299 -45.3009)
		(width 0.1143)
		(layer "In4.Cu")
		(net "P3E_CPU0_PE2_SS_RXN<3>")
	)
	(segment
		(start 303.493932 -86.70798)
		(end 303.51222 -86.708488)
		(width 0.0889)
		(layer "In4.Cu")
		(net "P3E_CPU0_PE2_SS_RXN<3>")
	)
	(segment
		(start 305.579526 -85.717888)
		(end 306.073556 -85.223858)
		(width 0.0889)
		(layer "In4.Cu")
		(net "P3E_CPU0_PE2_SS_RXN<3>")
	)
	(segment
		(start 402.608542 -2.99847)
		(end 402.722842 -2.88417)
		(width 0.1143)
		(layer "In4.Cu")
		(net "P3E_CPU0_PE2_SS_RXN<3>")
	)
	(segment
		(start 360.299 -45.3009)
		(end 361.626404 -43.295316)
		(width 0.1143)
		(layer "In4.Cu")
		(net "P3E_CPU0_PE2_SS_RXN<3>")
	)
	(segment
		(start 401.06092 -4.867656)
		(end 402.608542 -3.320034)
		(width 0.1143)
		(layer "In4.Cu")
		(net "P3E_CPU0_PE2_SS_RXN<3>")
	)
	(segment
		(start 371.231414 -25.488392)
		(end 372.551452 -24.776938)
		(width 0.1143)
		(layer "In4.Cu")
		(net "P3E_CPU0_PE2_SS_RXN<3>")
	)
	(segment
		(start 314.024264 -79.554832)
		(end 320.289682 -64.42964)
		(width 0.1143)
		(layer "In4.Cu")
		(net "P3E_CPU0_PE2_SS_RXN<3>")
	)
	(segment
		(start 326.733916 -56.08828)
		(end 328.267568 -53.857906)
		(width 0.1143)
		(layer "In4.Cu")
		(net "P3E_CPU0_PE2_SS_RXN<3>")
	)
	(segment
		(start 374.640348 -15.81658)
		(end 377.752864 -12.035282)
		(width 0.1143)
		(layer "In4.Cu")
		(net "P3E_CPU0_PE2_SS_RXN<3>")
	)
	(segment
		(start 389.525002 -10.164826)
		(end 399.004282 -6.92404)
		(width 0.1143)
		(layer "In4.Cu")
		(net "P3E_CPU0_PE2_SS_RXN<3>")
	)
	(segment
		(start 308.691534 -85.0646)
		(end 308.839362 -84.957158)
		(width 0.1143)
		(layer "In4.Cu")
		(net "P3E_CPU0_PE2_SS_RXN<3>")
	)
	(segment
		(start 339.727032 -50.492406)
		(end 341.943182 -50.041556)
		(width 0.1143)
		(layer "In4.Cu")
		(net "P3E_CPU0_PE2_SS_RXN<3>")
	)
	(segment
		(start 337.463384 -50.03165)
		(end 339.727032 -50.492406)
		(width 0.1143)
		(layer "In4.Cu")
		(net "P3E_CPU0_PE2_SS_RXN<3>")
	)
	(segment
		(start 308.602888 -85.066124)
		(end 308.689502 -85.066124)
		(width 0.0889)
		(layer "In4.Cu")
		(net "P3E_CPU0_PE2_SS_RXN<3>")
	)
	(segment
		(start 402.722842 -2.88417)
		(end 403.097492 -2.88417)
		(width 0.1143)
		(layer "In4.Cu")
		(net "P3E_CPU0_PE2_SS_RXN<3>")
	)
	(segment
		(start 374.640348 -15.816326)
		(end 374.640348 -15.81658)
		(width 0.1143)
		(layer "In4.Cu")
		(net "P3E_CPU0_PE2_SS_RXN<3>")
	)
	(segment
		(start 310.63438 -83.034378)
		(end 312.72734 -81.138014)
		(width 0.1143)
		(layer "In4.Cu")
		(net "P3E_CPU0_PE2_SS_RXN<3>")
	)
	(segment
		(start 308.385718 -85.223858)
		(end 308.602888 -85.066124)
		(width 0.0889)
		(layer "In4.Cu")
		(net "P3E_CPU0_PE2_SS_RXN<3>")
	)
	(segment
		(start 370.262658 -29.842206)
		(end 371.231414 -25.488392)
		(width 0.1143)
		(layer "In4.Cu")
		(net "P3E_CPU0_PE2_SS_RXN<3>")
	)
	(segment
		(start 325.750936 -56.489346)
		(end 326.733916 -56.08828)
		(width 0.1143)
		(layer "In4.Cu")
		(net "P3E_CPU0_PE2_SS_RXN<3>")
	)
	(segment
		(start 402.608542 -3.320034)
		(end 402.608542 -2.99847)
		(width 0.1143)
		(layer "In4.Cu")
		(net "P3E_CPU0_PE2_SS_RXN<3>")
	)
	(arc
		(start 303.32807 -86.67369)
		(mid 303.409495 -86.69813)
		(end 303.493932 -86.70798)
		(width 0.0889)
		(layer "In4.Cu")
		(net "P3E_CPU0_PE2_SS_RXN<3>")
	)
	(arc
		(start 303.028604 -86.612984)
		(mid 303.172646 -86.626629)
		(end 303.31156 -86.667086)
		(width 0.0889)
		(layer "In4.Cu")
		(net "P3E_CPU0_PE2_SS_RXN<3>")
	)
	(arc
		(start 303.54778 -86.708488)
		(mid 303.83303 -86.62494)
		(end 304.041556 -86.413086)
		(width 0.0889)
		(layer "In4.Cu")
		(net "P3E_CPU0_PE2_SS_RXN<3>")
	)
	(arc
		(start 304.409856 -86.212934)
		(mid 304.693073 -86.128653)
		(end 304.900076 -85.917786)
		(width 0.0889)
		(layer "In4.Cu")
		(net "P3E_CPU0_PE2_SS_RXN<3>")
	)
	(arc
		(start 304.900076 -85.917786)
		(mid 305.039069 -85.775706)
		(end 305.22926 -85.717888)
		(width 0.0889)
		(layer "In4.Cu")
		(net "P3E_CPU0_PE2_SS_RXN<3>")
	)
	(arc
		(start 303.51222 -86.708488)
		(mid 303.53 -86.708756)
		(end 303.54778 -86.708488)
		(width 0.0889)
		(layer "In4.Cu")
		(net "P3E_CPU0_PE2_SS_RXN<3>")
	)
	(arc
		(start 304.041556 -86.413086)
		(mid 304.183239 -86.269282)
		(end 304.37709 -86.212934)
		(width 0.0889)
		(layer "In4.Cu")
		(net "P3E_CPU0_PE2_SS_RXN<3>")
	)
	(segment
		(start 405.271986 -3.758184)
		(end 405.271986 -4.386072)
		(width 0.1143)
		(layer "F.Cu")
		(net "P3E_CPU0_PE2_SS_RXN<2>")
	)
	(segment
		(start 302.099726 -87.603584)
		(end 302.671226 -87.603584)
		(width 0.1143)
		(layer "F.Cu")
		(net "P3E_CPU0_PE2_SS_RXN<2>")
	)
	(segment
		(start 405.345392 -2.897124)
		(end 405.0792 -2.897124)
		(width 0.1143)
		(layer "F.Cu")
		(net "P3E_CPU0_PE2_SS_RXN<2>")
	)
	(segment
		(start 405.0792 -2.897124)
		(end 404.967186 -3.009138)
		(width 0.1143)
		(layer "F.Cu")
		(net "P3E_CPU0_PE2_SS_RXN<2>")
	)
	(segment
		(start 404.967186 -3.453384)
		(end 405.271986 -3.758184)
		(width 0.1143)
		(layer "F.Cu")
		(net "P3E_CPU0_PE2_SS_RXN<2>")
	)
	(segment
		(start 404.967186 -3.009138)
		(end 404.967186 -3.453384)
		(width 0.1143)
		(layer "F.Cu")
		(net "P3E_CPU0_PE2_SS_RXN<2>")
	)
	(via
		(at 405.345392 -2.897124)
		(size 0.508)
		(drill 0.254)
		(layers "F.Cu" "B.Cu")
		(net "P3E_CPU0_PE2_SS_RXN<2>")
	)
	(via
		(at 302.671226 -87.603584)
		(size 0.508)
		(drill 0.254)
		(layers "F.Cu" "B.Cu")
		(net "P3E_CPU0_PE2_SS_RXN<2>")
	)
	(segment
		(start 314.538868 -79.989934)
		(end 319.762124 -67.382898)
		(width 0.1143)
		(layer "In4.Cu")
		(net "P3E_CPU0_PE2_SS_RXN<2>")
	)
	(segment
		(start 358.681782 -47.17542)
		(end 360.78033 -45.786548)
		(width 0.1143)
		(layer "In4.Cu")
		(net "P3E_CPU0_PE2_SS_RXN<2>")
	)
	(segment
		(start 308.9275 -85.719412)
		(end 309.10657 -85.58403)
		(width 0.0889)
		(layer "In4.Cu")
		(net "P3E_CPU0_PE2_SS_RXN<2>")
	)
	(segment
		(start 305.77028 -86.392766)
		(end 305.781964 -86.3727)
		(width 0.0889)
		(layer "In4.Cu")
		(net "P3E_CPU0_PE2_SS_RXN<2>")
	)
	(segment
		(start 302.671226 -87.603584)
		(end 302.37811 -87.434674)
		(width 0.0889)
		(layer "In4.Cu")
		(net "P3E_CPU0_PE2_SS_RXN<2>")
	)
	(segment
		(start 404.574502 -3.866134)
		(end 404.970742 -3.469894)
		(width 0.1143)
		(layer "In4.Cu")
		(net "P3E_CPU0_PE2_SS_RXN<2>")
	)
	(segment
		(start 344.038936 -51.100736)
		(end 358.681782 -47.17542)
		(width 0.1143)
		(layer "In4.Cu")
		(net "P3E_CPU0_PE2_SS_RXN<2>")
	)
	(segment
		(start 368.659156 -32.126174)
		(end 369.034314 -31.549848)
		(width 0.1143)
		(layer "In4.Cu")
		(net "P3E_CPU0_PE2_SS_RXN<2>")
	)
	(segment
		(start 391.004298 -11.284204)
		(end 394.849604 -10.515092)
		(width 0.1143)
		(layer "In4.Cu")
		(net "P3E_CPU0_PE2_SS_RXN<2>")
	)
	(segment
		(start 303.514506 -87.699088)
		(end 303.515014 -87.699088)
		(width 0.0889)
		(layer "In4.Cu")
		(net "P3E_CPU0_PE2_SS_RXN<2>")
	)
	(segment
		(start 385.310634 -10.145776)
		(end 391.004298 -11.284204)
		(width 0.1143)
		(layer "In4.Cu")
		(net "P3E_CPU0_PE2_SS_RXN<2>")
	)
	(segment
		(start 309.10657 -85.58403)
		(end 309.19801 -85.596984)
		(width 0.0889)
		(layer "In4.Cu")
		(net "P3E_CPU0_PE2_SS_RXN<2>")
	)
	(segment
		(start 328.761598 -54.299358)
		(end 331.326236 -52.637944)
		(width 0.1143)
		(layer "In4.Cu")
		(net "P3E_CPU0_PE2_SS_RXN<2>")
	)
	(segment
		(start 302.37811 -87.434674)
		(end 302.357028 -87.355934)
		(width 0.0889)
		(layer "In4.Cu")
		(net "P3E_CPU0_PE2_SS_RXN<2>")
	)
	(segment
		(start 366.204754 -33.76041)
		(end 368.659156 -32.126174)
		(width 0.1143)
		(layer "In4.Cu")
		(net "P3E_CPU0_PE2_SS_RXN<2>")
	)
	(segment
		(start 304.37709 -87.203534)
		(end 304.409856 -87.203534)
		(width 0.0889)
		(layer "In4.Cu")
		(net "P3E_CPU0_PE2_SS_RXN<2>")
	)
	(segment
		(start 404.970742 -3.011424)
		(end 405.085042 -2.897124)
		(width 0.1143)
		(layer "In4.Cu")
		(net "P3E_CPU0_PE2_SS_RXN<2>")
	)
	(segment
		(start 395.40942 -10.14222)
		(end 395.846046 -9.487154)
		(width 0.1143)
		(layer "In4.Cu")
		(net "P3E_CPU0_PE2_SS_RXN<2>")
	)
	(segment
		(start 339.796882 -51.165506)
		(end 341.999062 -50.717196)
		(width 0.1143)
		(layer "In4.Cu")
		(net "P3E_CPU0_PE2_SS_RXN<2>")
	)
	(segment
		(start 398.063212 -8.355838)
		(end 399.509742 -7.391654)
		(width 0.1143)
		(layer "In4.Cu")
		(net "P3E_CPU0_PE2_SS_RXN<2>")
	)
	(segment
		(start 360.78033 -45.786548)
		(end 362.219748 -43.611546)
		(width 0.1143)
		(layer "In4.Cu")
		(net "P3E_CPU0_PE2_SS_RXN<2>")
	)
	(segment
		(start 309.19801 -85.596984)
		(end 309.215536 -85.583776)
		(width 0.0889)
		(layer "In4.Cu")
		(net "P3E_CPU0_PE2_SS_RXN<2>")
	)
	(segment
		(start 307.529484 -85.719412)
		(end 307.618384 -85.808312)
		(width 0.0889)
		(layer "In4.Cu")
		(net "P3E_CPU0_PE2_SS_RXN<2>")
	)
	(segment
		(start 371.80647 -25.924764)
		(end 373.144796 -25.197054)
		(width 0.1143)
		(layer "In4.Cu")
		(net "P3E_CPU0_PE2_SS_RXN<2>")
	)
	(segment
		(start 305.2318 -86.708488)
		(end 305.264566 -86.708488)
		(width 0.0889)
		(layer "In4.Cu")
		(net "P3E_CPU0_PE2_SS_RXN<2>")
	)
	(segment
		(start 344.038936 -51.10099)
		(end 344.038936 -51.100736)
		(width 0.1143)
		(layer "In4.Cu")
		(net "P3E_CPU0_PE2_SS_RXN<2>")
	)
	(segment
		(start 305.781964 -86.3727)
		(end 306.435252 -85.719412)
		(width 0.0889)
		(layer "In4.Cu")
		(net "P3E_CPU0_PE2_SS_RXN<2>")
	)
	(segment
		(start 403.034246 -3.866134)
		(end 404.574502 -3.866134)
		(width 0.1143)
		(layer "In4.Cu")
		(net "P3E_CPU0_PE2_SS_RXN<2>")
	)
	(segment
		(start 395.846046 -9.487154)
		(end 397.3195 -8.504428)
		(width 0.1143)
		(layer "In4.Cu")
		(net "P3E_CPU0_PE2_SS_RXN<2>")
	)
	(segment
		(start 380.983998 -11.065002)
		(end 385.310634 -10.145776)
		(width 0.1143)
		(layer "In4.Cu")
		(net "P3E_CPU0_PE2_SS_RXN<2>")
	)
	(segment
		(start 362.219748 -43.611546)
		(end 363.35208 -38.048184)
		(width 0.1143)
		(layer "In4.Cu")
		(net "P3E_CPU0_PE2_SS_RXN<2>")
	)
	(segment
		(start 363.35208 -38.048184)
		(end 366.204754 -33.76041)
		(width 0.1143)
		(layer "In4.Cu")
		(net "P3E_CPU0_PE2_SS_RXN<2>")
	)
	(segment
		(start 369.034314 -31.549848)
		(end 370.84762 -30.295342)
		(width 0.1143)
		(layer "In4.Cu")
		(net "P3E_CPU0_PE2_SS_RXN<2>")
	)
	(segment
		(start 309.555642 -85.325712)
		(end 310.033162 -84.592922)
		(width 0.1143)
		(layer "In4.Cu")
		(net "P3E_CPU0_PE2_SS_RXN<2>")
	)
	(segment
		(start 303.030382 -87.42553)
		(end 303.032668 -87.427816)
		(width 0.0889)
		(layer "In4.Cu")
		(net "P3E_CPU0_PE2_SS_RXN<2>")
	)
	(segment
		(start 337.491832 -50.69586)
		(end 339.796882 -51.165506)
		(width 0.1143)
		(layer "In4.Cu")
		(net "P3E_CPU0_PE2_SS_RXN<2>")
	)
	(segment
		(start 307.973984 -85.719412)
		(end 308.9275 -85.719412)
		(width 0.0889)
		(layer "In4.Cu")
		(net "P3E_CPU0_PE2_SS_RXN<2>")
	)
	(segment
		(start 313.29376 -81.510124)
		(end 314.538868 -79.989934)
		(width 0.1143)
		(layer "In4.Cu")
		(net "P3E_CPU0_PE2_SS_RXN<2>")
	)
	(segment
		(start 373.144796 -25.197054)
		(end 375.261378 -16.120618)
		(width 0.1143)
		(layer "In4.Cu")
		(net "P3E_CPU0_PE2_SS_RXN<2>")
	)
	(segment
		(start 397.3195 -8.504428)
		(end 398.063212 -8.355838)
		(width 0.1143)
		(layer "In4.Cu")
		(net "P3E_CPU0_PE2_SS_RXN<2>")
	)
	(segment
		(start 370.84762 -30.295342)
		(end 371.80647 -25.924764)
		(width 0.1143)
		(layer "In4.Cu")
		(net "P3E_CPU0_PE2_SS_RXN<2>")
	)
	(segment
		(start 399.509742 -7.391654)
		(end 403.034246 -3.866134)
		(width 0.1143)
		(layer "In4.Cu")
		(net "P3E_CPU0_PE2_SS_RXN<2>")
	)
	(segment
		(start 306.435252 -85.719412)
		(end 307.529484 -85.719412)
		(width 0.0889)
		(layer "In4.Cu")
		(net "P3E_CPU0_PE2_SS_RXN<2>")
	)
	(segment
		(start 307.885084 -85.808312)
		(end 307.973984 -85.719412)
		(width 0.0889)
		(layer "In4.Cu")
		(net "P3E_CPU0_PE2_SS_RXN<2>")
	)
	(segment
		(start 343.972642 -51.118516)
		(end 344.038936 -51.10099)
		(width 0.1143)
		(layer "In4.Cu")
		(net "P3E_CPU0_PE2_SS_RXN<2>")
	)
	(segment
		(start 303.017936 -87.403686)
		(end 303.030382 -87.42553)
		(width 0.0889)
		(layer "In4.Cu")
		(net "P3E_CPU0_PE2_SS_RXN<2>")
	)
	(segment
		(start 319.762124 -67.382898)
		(end 328.761598 -54.299358)
		(width 0.1143)
		(layer "In4.Cu")
		(net "P3E_CPU0_PE2_SS_RXN<2>")
	)
	(segment
		(start 394.849604 -10.515092)
		(end 395.40942 -10.14222)
		(width 0.1143)
		(layer "In4.Cu")
		(net "P3E_CPU0_PE2_SS_RXN<2>")
	)
	(segment
		(start 307.618384 -85.808312)
		(end 307.885084 -85.808312)
		(width 0.0889)
		(layer "In4.Cu")
		(net "P3E_CPU0_PE2_SS_RXN<2>")
	)
	(segment
		(start 331.326236 -52.637944)
		(end 337.491832 -50.69586)
		(width 0.1143)
		(layer "In4.Cu")
		(net "P3E_CPU0_PE2_SS_RXN<2>")
	)
	(segment
		(start 341.999062 -50.717196)
		(end 343.972642 -51.118516)
		(width 0.1143)
		(layer "In4.Cu")
		(net "P3E_CPU0_PE2_SS_RXN<2>")
	)
	(segment
		(start 378.187966 -12.56538)
		(end 380.983998 -11.065002)
		(width 0.1143)
		(layer "In4.Cu")
		(net "P3E_CPU0_PE2_SS_RXN<2>")
	)
	(segment
		(start 404.970742 -3.469894)
		(end 404.970742 -3.011424)
		(width 0.1143)
		(layer "In4.Cu")
		(net "P3E_CPU0_PE2_SS_RXN<2>")
	)
	(segment
		(start 405.085042 -2.897124)
		(end 405.345392 -2.897124)
		(width 0.1143)
		(layer "In4.Cu")
		(net "P3E_CPU0_PE2_SS_RXN<2>")
	)
	(segment
		(start 375.261378 -16.120618)
		(end 378.187966 -12.56538)
		(width 0.1143)
		(layer "In4.Cu")
		(net "P3E_CPU0_PE2_SS_RXN<2>")
	)
	(segment
		(start 305.758596 -86.413086)
		(end 305.77028 -86.392766)
		(width 0.0889)
		(layer "In4.Cu")
		(net "P3E_CPU0_PE2_SS_RXN<2>")
	)
	(segment
		(start 310.033162 -84.592922)
		(end 311.400952 -83.225132)
		(width 0.1143)
		(layer "In4.Cu")
		(net "P3E_CPU0_PE2_SS_RXN<2>")
	)
	(segment
		(start 311.400952 -83.225132)
		(end 313.29376 -81.510124)
		(width 0.1143)
		(layer "In4.Cu")
		(net "P3E_CPU0_PE2_SS_RXN<2>")
	)
	(segment
		(start 309.215536 -85.583776)
		(end 309.555642 -85.325712)
		(width 0.1143)
		(layer "In4.Cu")
		(net "P3E_CPU0_PE2_SS_RXN<2>")
	)
	(arc
		(start 302.659288 -87.203788)
		(mid 302.671353 -87.203602)
		(end 302.683418 -87.203788)
		(width 0.0889)
		(layer "In4.Cu")
		(net "P3E_CPU0_PE2_SS_RXN<2>")
	)
	(arc
		(start 305.264566 -86.708488)
		(mid 305.54999 -86.625021)
		(end 305.758596 -86.413086)
		(width 0.0889)
		(layer "In4.Cu")
		(net "P3E_CPU0_PE2_SS_RXN<2>")
	)
	(arc
		(start 303.515014 -87.699088)
		(mid 303.531143 -87.699312)
		(end 303.547272 -87.699088)
		(width 0.0889)
		(layer "In4.Cu")
		(net "P3E_CPU0_PE2_SS_RXN<2>")
	)
	(arc
		(start 303.032668 -87.427816)
		(mid 303.239834 -87.623375)
		(end 303.514506 -87.699088)
		(width 0.0889)
		(layer "In4.Cu")
		(net "P3E_CPU0_PE2_SS_RXN<2>")
	)
	(arc
		(start 303.547272 -87.699088)
		(mid 303.832837 -87.615679)
		(end 304.041556 -87.403686)
		(width 0.0889)
		(layer "In4.Cu")
		(net "P3E_CPU0_PE2_SS_RXN<2>")
	)
	(arc
		(start 304.409856 -87.203534)
		(mid 304.693073 -87.119253)
		(end 304.900076 -86.908386)
		(width 0.0889)
		(layer "In4.Cu")
		(net "P3E_CPU0_PE2_SS_RXN<2>")
	)
	(arc
		(start 304.900076 -86.908386)
		(mid 305.040155 -86.76565)
		(end 305.2318 -86.708488)
		(width 0.0889)
		(layer "In4.Cu")
		(net "P3E_CPU0_PE2_SS_RXN<2>")
	)
	(arc
		(start 304.041556 -87.403686)
		(mid 304.183239 -87.259882)
		(end 304.37709 -87.203534)
		(width 0.0889)
		(layer "In4.Cu")
		(net "P3E_CPU0_PE2_SS_RXN<2>")
	)
	(arc
		(start 302.683418 -87.203788)
		(mid 302.876695 -87.260226)
		(end 303.017936 -87.403686)
		(width 0.0889)
		(layer "In4.Cu")
		(net "P3E_CPU0_PE2_SS_RXN<2>")
	)
	(arc
		(start 302.357028 -87.355934)
		(mid 302.491288 -87.246348)
		(end 302.659288 -87.203788)
		(width 0.0889)
		(layer "In4.Cu")
		(net "P3E_CPU0_PE2_SS_RXN<2>")
	)
	(segment
		(start 407.383742 -3.46964)
		(end 407.383742 -2.99847)
		(width 0.1143)
		(layer "F.Cu")
		(net "P3E_CPU0_PE2_SS_RXN<1>")
	)
	(segment
		(start 407.383742 -2.99847)
		(end 407.498042 -2.88417)
		(width 0.1143)
		(layer "F.Cu")
		(net "P3E_CPU0_PE2_SS_RXN<1>")
	)
	(segment
		(start 407.672286 -4.386072)
		(end 407.672286 -3.758184)
		(width 0.1143)
		(layer "F.Cu")
		(net "P3E_CPU0_PE2_SS_RXN<1>")
	)
	(segment
		(start 300.382686 -87.603584)
		(end 300.954186 -87.603584)
		(width 0.1143)
		(layer "F.Cu")
		(net "P3E_CPU0_PE2_SS_RXN<1>")
	)
	(segment
		(start 407.498042 -2.88417)
		(end 407.898092 -2.88417)
		(width 0.1143)
		(layer "F.Cu")
		(net "P3E_CPU0_PE2_SS_RXN<1>")
	)
	(segment
		(start 407.672286 -3.758184)
		(end 407.383742 -3.46964)
		(width 0.1143)
		(layer "F.Cu")
		(net "P3E_CPU0_PE2_SS_RXN<1>")
	)
	(via
		(at 407.898092 -2.88417)
		(size 0.508)
		(drill 0.254)
		(layers "F.Cu" "B.Cu")
		(net "P3E_CPU0_PE2_SS_RXN<1>")
	)
	(via
		(at 300.954186 -87.603584)
		(size 0.508)
		(drill 0.254)
		(layers "F.Cu" "B.Cu")
		(net "P3E_CPU0_PE2_SS_RXN<1>")
	)
	(segment
		(start 366.648238 -34.240724)
		(end 369.19281 -32.544258)
		(width 0.1143)
		(layer "In4.Cu")
		(net "P3E_CPU0_PE2_SS_RXN<1>")
	)
	(segment
		(start 401.25523 -7.311898)
		(end 402.712936 -5.214874)
		(width 0.1143)
		(layer "In4.Cu")
		(net "P3E_CPU0_PE2_SS_RXN<1>")
	)
	(segment
		(start 371.432328 -30.756606)
		(end 372.3513 -26.416254)
		(width 0.1143)
		(layer "In4.Cu")
		(net "P3E_CPU0_PE2_SS_RXN<1>")
	)
	(segment
		(start 407.149046 -3.697732)
		(end 407.383742 -3.36931)
		(width 0.1143)
		(layer "In4.Cu")
		(net "P3E_CPU0_PE2_SS_RXN<1>")
	)
	(segment
		(start 320.3702 -67.620134)
		(end 329.159108 -54.843172)
		(width 0.1143)
		(layer "In4.Cu")
		(net "P3E_CPU0_PE2_SS_RXN<1>")
	)
	(segment
		(start 339.829648 -51.84521)
		(end 342.07958 -51.387502)
		(width 0.1143)
		(layer "In4.Cu")
		(net "P3E_CPU0_PE2_SS_RXN<1>")
	)
	(segment
		(start 307.870098 -86.6013)
		(end 308.970934 -86.6013)
		(width 0.1143)
		(layer "In4.Cu")
		(net "P3E_CPU0_PE2_SS_RXN<1>")
	)
	(segment
		(start 373.726964 -25.66416)
		(end 375.880884 -16.427958)
		(width 0.1143)
		(layer "In4.Cu")
		(net "P3E_CPU0_PE2_SS_RXN<1>")
	)
	(segment
		(start 313.533028 -82.249772)
		(end 315.099446 -80.340962)
		(width 0.1143)
		(layer "In4.Cu")
		(net "P3E_CPU0_PE2_SS_RXN<1>")
	)
	(segment
		(start 390.265412 -12.106656)
		(end 396.892018 -10.813034)
		(width 0.1143)
		(layer "In4.Cu")
		(net "P3E_CPU0_PE2_SS_RXN<1>")
	)
	(segment
		(start 301.794926 -87.699088)
		(end 301.827692 -87.699088)
		(width 0.0889)
		(layer "In4.Cu")
		(net "P3E_CPU0_PE2_SS_RXN<1>")
	)
	(segment
		(start 384.745484 -10.953496)
		(end 390.265412 -12.106656)
		(width 0.1143)
		(layer "In4.Cu")
		(net "P3E_CPU0_PE2_SS_RXN<1>")
	)
	(segment
		(start 307.848 -86.6013)
		(end 307.870098 -86.6013)
		(width 0.0889)
		(layer "In4.Cu")
		(net "P3E_CPU0_PE2_SS_RXN<1>")
	)
	(segment
		(start 315.099446 -80.340962)
		(end 320.3702 -67.620134)
		(width 0.1143)
		(layer "In4.Cu")
		(net "P3E_CPU0_PE2_SS_RXN<1>")
	)
	(segment
		(start 307.7972 -86.5505)
		(end 307.848 -86.6013)
		(width 0.0889)
		(layer "In4.Cu")
		(net "P3E_CPU0_PE2_SS_RXN<1>")
	)
	(segment
		(start 369.49253 -32.099504)
		(end 371.432328 -30.756606)
		(width 0.1143)
		(layer "In4.Cu")
		(net "P3E_CPU0_PE2_SS_RXN<1>")
	)
	(segment
		(start 396.892018 -10.813034)
		(end 397.558768 -10.368788)
		(width 0.1143)
		(layer "In4.Cu")
		(net "P3E_CPU0_PE2_SS_RXN<1>")
	)
	(segment
		(start 407.383742 -3.36931)
		(end 407.383742 -3.019044)
		(width 0.1143)
		(layer "In4.Cu")
		(net "P3E_CPU0_PE2_SS_RXN<1>")
	)
	(segment
		(start 361.222798 -46.293532)
		(end 362.894118 -43.76801)
		(width 0.1143)
		(layer "In4.Cu")
		(net "P3E_CPU0_PE2_SS_RXN<1>")
	)
	(segment
		(start 359.019094 -47.751746)
		(end 361.222798 -46.293532)
		(width 0.1143)
		(layer "In4.Cu")
		(net "P3E_CPU0_PE2_SS_RXN<1>")
	)
	(segment
		(start 303.514506 -88.689688)
		(end 303.515014 -88.689688)
		(width 0.0889)
		(layer "In4.Cu")
		(net "P3E_CPU0_PE2_SS_RXN<1>")
	)
	(segment
		(start 329.159108 -54.843172)
		(end 331.591412 -53.243226)
		(width 0.1143)
		(layer "In4.Cu")
		(net "P3E_CPU0_PE2_SS_RXN<1>")
	)
	(segment
		(start 331.591412 -53.24348)
		(end 337.524598 -51.376072)
		(width 0.1143)
		(layer "In4.Cu")
		(net "P3E_CPU0_PE2_SS_RXN<1>")
	)
	(segment
		(start 369.485418 -32.110172)
		(end 369.48618 -32.109156)
		(width 0.1143)
		(layer "In4.Cu")
		(net "P3E_CPU0_PE2_SS_RXN<1>")
	)
	(segment
		(start 407.518616 -2.88417)
		(end 407.898092 -2.88417)
		(width 0.1143)
		(layer "In4.Cu")
		(net "P3E_CPU0_PE2_SS_RXN<1>")
	)
	(segment
		(start 300.954186 -87.603584)
		(end 300.954186 -87.26551)
		(width 0.0889)
		(layer "In4.Cu")
		(net "P3E_CPU0_PE2_SS_RXN<1>")
	)
	(segment
		(start 305.2318 -87.699088)
		(end 306.229766 -87.699088)
		(width 0.0889)
		(layer "In4.Cu")
		(net "P3E_CPU0_PE2_SS_RXN<1>")
	)
	(segment
		(start 303.017936 -88.394286)
		(end 303.030382 -88.41613)
		(width 0.0889)
		(layer "In4.Cu")
		(net "P3E_CPU0_PE2_SS_RXN<1>")
	)
	(segment
		(start 372.3513 -26.416254)
		(end 373.726964 -25.66416)
		(width 0.1143)
		(layer "In4.Cu")
		(net "P3E_CPU0_PE2_SS_RXN<1>")
	)
	(segment
		(start 407.383742 -3.019044)
		(end 407.518616 -2.88417)
		(width 0.1143)
		(layer "In4.Cu")
		(net "P3E_CPU0_PE2_SS_RXN<1>")
	)
	(segment
		(start 300.954186 -87.26551)
		(end 301.012098 -87.207598)
		(width 0.0889)
		(layer "In4.Cu")
		(net "P3E_CPU0_PE2_SS_RXN<1>")
	)
	(segment
		(start 397.97482 -10.09142)
		(end 398.68602 -9.02462)
		(width 0.1143)
		(layer "In4.Cu")
		(net "P3E_CPU0_PE2_SS_RXN<1>")
	)
	(segment
		(start 381.220726 -11.70178)
		(end 384.745484 -10.953496)
		(width 0.1143)
		(layer "In4.Cu")
		(net "P3E_CPU0_PE2_SS_RXN<1>")
	)
	(segment
		(start 369.19281 -32.544258)
		(end 369.485418 -32.110172)
		(width 0.1143)
		(layer "In4.Cu")
		(net "P3E_CPU0_PE2_SS_RXN<1>")
	)
	(segment
		(start 337.524598 -51.376072)
		(end 339.829648 -51.84521)
		(width 0.1143)
		(layer "In4.Cu")
		(net "P3E_CPU0_PE2_SS_RXN<1>")
	)
	(segment
		(start 369.48618 -32.109156)
		(end 369.49253 -32.099504)
		(width 0.1143)
		(layer "In4.Cu")
		(net "P3E_CPU0_PE2_SS_RXN<1>")
	)
	(segment
		(start 398.68602 -9.02462)
		(end 401.25523 -7.311898)
		(width 0.1143)
		(layer "In4.Cu")
		(net "P3E_CPU0_PE2_SS_RXN<1>")
	)
	(segment
		(start 397.558768 -10.368788)
		(end 397.97482 -10.09142)
		(width 0.1143)
		(layer "In4.Cu")
		(net "P3E_CPU0_PE2_SS_RXN<1>")
	)
	(segment
		(start 344.000582 -51.778408)
		(end 359.019094 -47.751746)
		(width 0.1143)
		(layer "In4.Cu")
		(net "P3E_CPU0_PE2_SS_RXN<1>")
	)
	(segment
		(start 308.970934 -86.6013)
		(end 309.8673 -85.985096)
		(width 0.1143)
		(layer "In4.Cu")
		(net "P3E_CPU0_PE2_SS_RXN<1>")
	)
	(segment
		(start 304.37709 -88.194134)
		(end 304.409856 -88.194134)
		(width 0.0889)
		(layer "In4.Cu")
		(net "P3E_CPU0_PE2_SS_RXN<1>")
	)
	(segment
		(start 362.894118 -43.76801)
		(end 364.00613 -38.212268)
		(width 0.1143)
		(layer "In4.Cu")
		(net "P3E_CPU0_PE2_SS_RXN<1>")
	)
	(segment
		(start 303.030382 -88.41613)
		(end 303.032668 -88.418416)
		(width 0.0889)
		(layer "In4.Cu")
		(net "P3E_CPU0_PE2_SS_RXN<1>")
	)
	(segment
		(start 375.880884 -16.427958)
		(end 378.624338 -13.09497)
		(width 0.1143)
		(layer "In4.Cu")
		(net "P3E_CPU0_PE2_SS_RXN<1>")
	)
	(segment
		(start 378.624338 -13.09497)
		(end 381.220726 -11.70178)
		(width 0.1143)
		(layer "In4.Cu")
		(net "P3E_CPU0_PE2_SS_RXN<1>")
	)
	(segment
		(start 342.07958 -51.387502)
		(end 344.000582 -51.778408)
		(width 0.1143)
		(layer "In4.Cu")
		(net "P3E_CPU0_PE2_SS_RXN<1>")
	)
	(segment
		(start 307.378354 -86.5505)
		(end 307.7972 -86.5505)
		(width 0.0889)
		(layer "In4.Cu")
		(net "P3E_CPU0_PE2_SS_RXN<1>")
	)
	(segment
		(start 306.229766 -87.699088)
		(end 307.378354 -86.5505)
		(width 0.0889)
		(layer "In4.Cu")
		(net "P3E_CPU0_PE2_SS_RXN<1>")
	)
	(segment
		(start 364.00613 -38.212268)
		(end 366.648238 -34.240724)
		(width 0.1143)
		(layer "In4.Cu")
		(net "P3E_CPU0_PE2_SS_RXN<1>")
	)
	(segment
		(start 302.649636 -88.194134)
		(end 302.685704 -88.194134)
		(width 0.0889)
		(layer "In4.Cu")
		(net "P3E_CPU0_PE2_SS_RXN<1>")
	)
	(segment
		(start 402.712936 -5.214874)
		(end 407.149046 -3.697732)
		(width 0.1143)
		(layer "In4.Cu")
		(net "P3E_CPU0_PE2_SS_RXN<1>")
	)
	(segment
		(start 331.591412 -53.243226)
		(end 331.591412 -53.24348)
		(width 0.1143)
		(layer "In4.Cu")
		(net "P3E_CPU0_PE2_SS_RXN<1>")
	)
	(segment
		(start 310.598058 -84.909914)
		(end 313.533028 -82.249772)
		(width 0.1143)
		(layer "In4.Cu")
		(net "P3E_CPU0_PE2_SS_RXN<1>")
	)
	(segment
		(start 309.8673 -85.985096)
		(end 310.598058 -84.909914)
		(width 0.1143)
		(layer "In4.Cu")
		(net "P3E_CPU0_PE2_SS_RXN<1>")
	)
	(arc
		(start 304.900076 -87.898986)
		(mid 305.040155 -87.75625)
		(end 305.2318 -87.699088)
		(width 0.0889)
		(layer "In4.Cu")
		(net "P3E_CPU0_PE2_SS_RXN<1>")
	)
	(arc
		(start 303.515014 -88.689688)
		(mid 303.531143 -88.689912)
		(end 303.547272 -88.689688)
		(width 0.0889)
		(layer "In4.Cu")
		(net "P3E_CPU0_PE2_SS_RXN<1>")
	)
	(arc
		(start 302.159416 -87.898986)
		(mid 302.36642 -88.10985)
		(end 302.649636 -88.194134)
		(width 0.0889)
		(layer "In4.Cu")
		(net "P3E_CPU0_PE2_SS_RXN<1>")
	)
	(arc
		(start 304.409856 -88.194134)
		(mid 304.693073 -88.109853)
		(end 304.900076 -87.898986)
		(width 0.0889)
		(layer "In4.Cu")
		(net "P3E_CPU0_PE2_SS_RXN<1>")
	)
	(arc
		(start 303.032668 -88.418416)
		(mid 303.239834 -88.613975)
		(end 303.514506 -88.689688)
		(width 0.0889)
		(layer "In4.Cu")
		(net "P3E_CPU0_PE2_SS_RXN<1>")
	)
	(arc
		(start 302.685704 -88.194134)
		(mid 302.877721 -88.251242)
		(end 303.017936 -88.394286)
		(width 0.0889)
		(layer "In4.Cu")
		(net "P3E_CPU0_PE2_SS_RXN<1>")
	)
	(arc
		(start 301.827692 -87.699088)
		(mid 302.019334 -87.756254)
		(end 302.159416 -87.898986)
		(width 0.0889)
		(layer "In4.Cu")
		(net "P3E_CPU0_PE2_SS_RXN<1>")
	)
	(arc
		(start 304.041556 -88.394286)
		(mid 304.183239 -88.250482)
		(end 304.37709 -88.194134)
		(width 0.0889)
		(layer "In4.Cu")
		(net "P3E_CPU0_PE2_SS_RXN<1>")
	)
	(arc
		(start 301.300896 -87.403686)
		(mid 301.509504 -87.615618)
		(end 301.794926 -87.699088)
		(width 0.0889)
		(layer "In4.Cu")
		(net "P3E_CPU0_PE2_SS_RXN<1>")
	)
	(arc
		(start 301.012098 -87.207598)
		(mid 301.178999 -87.272498)
		(end 301.300896 -87.403686)
		(width 0.0889)
		(layer "In4.Cu")
		(net "P3E_CPU0_PE2_SS_RXN<1>")
	)
	(arc
		(start 303.547272 -88.689688)
		(mid 303.832837 -88.606279)
		(end 304.041556 -88.394286)
		(width 0.0889)
		(layer "In4.Cu")
		(net "P3E_CPU0_PE2_SS_RXN<1>")
	)
	(segment
		(start 362.285026 -3.72364)
		(end 362.004102 -3.442716)
		(width 0.1143)
		(layer "F.Cu")
		(net "P3E_CPU0_PE2_SS_RXN<15>")
	)
	(segment
		(start 362.004102 -3.442716)
		(end 362.004102 -3.075432)
		(width 0.1143)
		(layer "F.Cu")
		(net "P3E_CPU0_PE2_SS_RXN<15>")
	)
	(segment
		(start 362.285026 -4.389882)
		(end 362.285026 -3.72364)
		(width 0.1143)
		(layer "F.Cu")
		(net "P3E_CPU0_PE2_SS_RXN<15>")
	)
	(segment
		(start 300.382686 -75.716384)
		(end 300.954186 -75.716384)
		(width 0.1143)
		(layer "F.Cu")
		(net "P3E_CPU0_PE2_SS_RXN<15>")
	)
	(segment
		(start 362.142532 -2.937002)
		(end 362.570268 -2.937002)
		(width 0.1143)
		(layer "F.Cu")
		(net "P3E_CPU0_PE2_SS_RXN<15>")
	)
	(segment
		(start 362.004102 -3.075432)
		(end 362.142532 -2.937002)
		(width 0.1143)
		(layer "F.Cu")
		(net "P3E_CPU0_PE2_SS_RXN<15>")
	)
	(via
		(at 300.954186 -75.716384)
		(size 0.508)
		(drill 0.254)
		(layers "F.Cu" "B.Cu")
		(net "P3E_CPU0_PE2_SS_RXN<15>")
	)
	(via
		(at 362.570268 -2.937002)
		(size 0.508)
		(drill 0.254)
		(layers "F.Cu" "B.Cu")
		(net "P3E_CPU0_PE2_SS_RXN<15>")
	)
	(segment
		(start 306.941982 -74.376534)
		(end 306.544218 -74.376534)
		(width 0.1143)
		(layer "In4.Cu")
		(net "P3E_CPU0_PE2_SS_RXN<15>")
	)
	(segment
		(start 309.47487 -50.752248)
		(end 309.110634 -51.306984)
		(width 0.1143)
		(layer "In4.Cu")
		(net "P3E_CPU0_PE2_SS_RXN<15>")
	)
	(segment
		(start 362.195618 -2.937002)
		(end 362.081318 -3.051302)
		(width 0.1143)
		(layer "In4.Cu")
		(net "P3E_CPU0_PE2_SS_RXN<15>")
	)
	(segment
		(start 308.865016 -55.739792)
		(end 309.411624 -56.234076)
		(width 0.1143)
		(layer "In4.Cu")
		(net "P3E_CPU0_PE2_SS_RXN<15>")
	)
	(segment
		(start 304.409856 -74.325734)
		(end 304.37709 -74.325734)
		(width 0.0889)
		(layer "In4.Cu")
		(net "P3E_CPU0_PE2_SS_RXN<15>")
	)
	(segment
		(start 310.453786 -63.708026)
		(end 308.113684 -66.01968)
		(width 0.1143)
		(layer "In4.Cu")
		(net "P3E_CPU0_PE2_SS_RXN<15>")
	)
	(segment
		(start 301.830486 -74.821288)
		(end 301.79772 -74.821288)
		(width 0.0889)
		(layer "In4.Cu")
		(net "P3E_CPU0_PE2_SS_RXN<15>")
	)
	(segment
		(start 339.87994 -38.393624)
		(end 339.362288 -38.911276)
		(width 0.1143)
		(layer "In4.Cu")
		(net "P3E_CPU0_PE2_SS_RXN<15>")
	)
	(segment
		(start 311.01665 -59.15914)
		(end 311.380632 -60.977272)
		(width 0.1143)
		(layer "In4.Cu")
		(net "P3E_CPU0_PE2_SS_RXN<15>")
	)
	(segment
		(start 345.065858 -34.92119)
		(end 341.38108 -34.92119)
		(width 0.1143)
		(layer "In4.Cu")
		(net "P3E_CPU0_PE2_SS_RXN<15>")
	)
	(segment
		(start 362.081318 -5.458206)
		(end 363.597952 -12.342368)
		(width 0.1143)
		(layer "In4.Cu")
		(net "P3E_CPU0_PE2_SS_RXN<15>")
	)
	(segment
		(start 308.840886 -69.58965)
		(end 309.036974 -70.57136)
		(width 0.1143)
		(layer "In4.Cu")
		(net "P3E_CPU0_PE2_SS_RXN<15>")
	)
	(segment
		(start 309.110634 -51.306984)
		(end 308.82082 -52.350924)
		(width 0.1143)
		(layer "In4.Cu")
		(net "P3E_CPU0_PE2_SS_RXN<15>")
	)
	(segment
		(start 308.82082 -52.350924)
		(end 308.83479 -52.936648)
		(width 0.1143)
		(layer "In4.Cu")
		(net "P3E_CPU0_PE2_SS_RXN<15>")
	)
	(segment
		(start 307.757068 -67.168522)
		(end 307.880766 -68.178426)
		(width 0.1143)
		(layer "In4.Cu")
		(net "P3E_CPU0_PE2_SS_RXN<15>")
	)
	(segment
		(start 308.622192 -55.110888)
		(end 308.865016 -55.739792)
		(width 0.1143)
		(layer "In4.Cu")
		(net "P3E_CPU0_PE2_SS_RXN<15>")
	)
	(segment
		(start 335.942432 -38.911276)
		(end 333.209646 -40.722042)
		(width 0.1143)
		(layer "In4.Cu")
		(net "P3E_CPU0_PE2_SS_RXN<15>")
	)
	(segment
		(start 308.83479 -52.936648)
		(end 308.622192 -55.110888)
		(width 0.1143)
		(layer "In4.Cu")
		(net "P3E_CPU0_PE2_SS_RXN<15>")
	)
	(segment
		(start 339.87994 -36.42233)
		(end 339.87994 -38.393624)
		(width 0.1143)
		(layer "In4.Cu")
		(net "P3E_CPU0_PE2_SS_RXN<15>")
	)
	(segment
		(start 314.834016 -46.42739)
		(end 309.47487 -50.752248)
		(width 0.1143)
		(layer "In4.Cu")
		(net "P3E_CPU0_PE2_SS_RXN<15>")
	)
	(segment
		(start 360.60888 -26.31313)
		(end 356.308914 -32.763206)
		(width 0.1143)
		(layer "In4.Cu")
		(net "P3E_CPU0_PE2_SS_RXN<15>")
	)
	(segment
		(start 341.38108 -34.92119)
		(end 339.87994 -36.42233)
		(width 0.1143)
		(layer "In4.Cu")
		(net "P3E_CPU0_PE2_SS_RXN<15>")
	)
	(segment
		(start 331.482954 -41.067228)
		(end 330.34097 -41.828466)
		(width 0.1143)
		(layer "In4.Cu")
		(net "P3E_CPU0_PE2_SS_RXN<15>")
	)
	(segment
		(start 307.880766 -68.178426)
		(end 308.840886 -69.58965)
		(width 0.1143)
		(layer "In4.Cu")
		(net "P3E_CPU0_PE2_SS_RXN<15>")
	)
	(segment
		(start 306.544218 -74.376534)
		(end 306.52212 -74.376534)
		(width 0.0889)
		(layer "In4.Cu")
		(net "P3E_CPU0_PE2_SS_RXN<15>")
	)
	(segment
		(start 339.362288 -38.911276)
		(end 335.942432 -38.911276)
		(width 0.1143)
		(layer "In4.Cu")
		(net "P3E_CPU0_PE2_SS_RXN<15>")
	)
	(segment
		(start 356.308914 -32.763206)
		(end 354.666804 -33.857946)
		(width 0.1143)
		(layer "In4.Cu")
		(net "P3E_CPU0_PE2_SS_RXN<15>")
	)
	(segment
		(start 309.411624 -56.234076)
		(end 310.232806 -57.454038)
		(width 0.1143)
		(layer "In4.Cu")
		(net "P3E_CPU0_PE2_SS_RXN<15>")
	)
	(segment
		(start 328.398632 -44.741592)
		(end 324.750684 -45.897038)
		(width 0.1143)
		(layer "In4.Cu")
		(net "P3E_CPU0_PE2_SS_RXN<15>")
	)
	(segment
		(start 306.52212 -74.376534)
		(end 306.47132 -74.325734)
		(width 0.0889)
		(layer "In4.Cu")
		(net "P3E_CPU0_PE2_SS_RXN<15>")
	)
	(segment
		(start 330.34097 -41.828466)
		(end 328.398632 -44.741592)
		(width 0.1143)
		(layer "In4.Cu")
		(net "P3E_CPU0_PE2_SS_RXN<15>")
	)
	(segment
		(start 307.844698 -73.450196)
		(end 306.941982 -74.376534)
		(width 0.1143)
		(layer "In4.Cu")
		(net "P3E_CPU0_PE2_SS_RXN<15>")
	)
	(segment
		(start 324.750684 -45.897038)
		(end 319.990978 -45.440346)
		(width 0.1143)
		(layer "In4.Cu")
		(net "P3E_CPU0_PE2_SS_RXN<15>")
	)
	(segment
		(start 362.081318 -3.051302)
		(end 362.081318 -5.458206)
		(width 0.1143)
		(layer "In4.Cu")
		(net "P3E_CPU0_PE2_SS_RXN<15>")
	)
	(segment
		(start 300.975776 -75.316334)
		(end 300.94301 -75.316334)
		(width 0.0889)
		(layer "In4.Cu")
		(net "P3E_CPU0_PE2_SS_RXN<15>")
	)
	(segment
		(start 300.639988 -75.468734)
		(end 300.66107 -75.547474)
		(width 0.0889)
		(layer "In4.Cu")
		(net "P3E_CPU0_PE2_SS_RXN<15>")
	)
	(segment
		(start 309.036974 -70.57136)
		(end 307.844698 -73.450196)
		(width 0.1143)
		(layer "In4.Cu")
		(net "P3E_CPU0_PE2_SS_RXN<15>")
	)
	(segment
		(start 303.530254 -74.821288)
		(end 303.529238 -74.821288)
		(width 0.0889)
		(layer "In4.Cu")
		(net "P3E_CPU0_PE2_SS_RXN<15>")
	)
	(segment
		(start 362.570268 -2.937002)
		(end 362.195618 -2.937002)
		(width 0.1143)
		(layer "In4.Cu")
		(net "P3E_CPU0_PE2_SS_RXN<15>")
	)
	(segment
		(start 346.820744 -35.2933)
		(end 345.065858 -34.92119)
		(width 0.1143)
		(layer "In4.Cu")
		(net "P3E_CPU0_PE2_SS_RXN<15>")
	)
	(segment
		(start 305.413664 -73.830688)
		(end 305.2318 -73.830688)
		(width 0.0889)
		(layer "In4.Cu")
		(net "P3E_CPU0_PE2_SS_RXN<15>")
	)
	(segment
		(start 319.990978 -45.440346)
		(end 314.834016 -46.42739)
		(width 0.1143)
		(layer "In4.Cu")
		(net "P3E_CPU0_PE2_SS_RXN<15>")
	)
	(segment
		(start 310.232806 -57.454038)
		(end 311.01665 -59.15914)
		(width 0.1143)
		(layer "In4.Cu")
		(net "P3E_CPU0_PE2_SS_RXN<15>")
	)
	(segment
		(start 363.597952 -12.342368)
		(end 360.60888 -26.31313)
		(width 0.1143)
		(layer "In4.Cu")
		(net "P3E_CPU0_PE2_SS_RXN<15>")
	)
	(segment
		(start 354.666804 -33.857946)
		(end 346.820744 -35.2933)
		(width 0.1143)
		(layer "In4.Cu")
		(net "P3E_CPU0_PE2_SS_RXN<15>")
	)
	(segment
		(start 333.209646 -40.722042)
		(end 331.482954 -41.067228)
		(width 0.1143)
		(layer "In4.Cu")
		(net "P3E_CPU0_PE2_SS_RXN<15>")
	)
	(segment
		(start 306.47132 -74.325734)
		(end 305.978306 -74.325734)
		(width 0.0889)
		(layer "In4.Cu")
		(net "P3E_CPU0_PE2_SS_RXN<15>")
	)
	(segment
		(start 311.380632 -60.977272)
		(end 310.453786 -63.708026)
		(width 0.1143)
		(layer "In4.Cu")
		(net "P3E_CPU0_PE2_SS_RXN<15>")
	)
	(segment
		(start 308.113684 -66.01968)
		(end 307.757068 -67.168522)
		(width 0.1143)
		(layer "In4.Cu")
		(net "P3E_CPU0_PE2_SS_RXN<15>")
	)
	(segment
		(start 300.66107 -75.547474)
		(end 300.954186 -75.716384)
		(width 0.0889)
		(layer "In4.Cu")
		(net "P3E_CPU0_PE2_SS_RXN<15>")
	)
	(arc
		(start 305.629818 -74.027792)
		(mid 305.538874 -73.910449)
		(end 305.413664 -73.830688)
		(width 0.0889)
		(layer "In4.Cu")
		(net "P3E_CPU0_PE2_SS_RXN<15>")
	)
	(arc
		(start 300.787308 -75.352656)
		(mid 300.706767 -75.401957)
		(end 300.639988 -75.468734)
		(width 0.0889)
		(layer "In4.Cu")
		(net "P3E_CPU0_PE2_SS_RXN<15>")
	)
	(arc
		(start 304.900076 -74.030586)
		(mid 304.693072 -74.24145)
		(end 304.409856 -74.325734)
		(width 0.0889)
		(layer "In4.Cu")
		(net "P3E_CPU0_PE2_SS_RXN<15>")
	)
	(arc
		(start 304.37709 -74.325734)
		(mid 304.18324 -74.382084)
		(end 304.041556 -74.525886)
		(width 0.0889)
		(layer "In4.Cu")
		(net "P3E_CPU0_PE2_SS_RXN<15>")
	)
	(arc
		(start 301.79772 -74.821288)
		(mid 301.606078 -74.878454)
		(end 301.465996 -75.021186)
		(width 0.0889)
		(layer "In4.Cu")
		(net "P3E_CPU0_PE2_SS_RXN<15>")
	)
	(arc
		(start 302.324516 -74.525886)
		(mid 302.115908 -74.737818)
		(end 301.830486 -74.821288)
		(width 0.0889)
		(layer "In4.Cu")
		(net "P3E_CPU0_PE2_SS_RXN<15>")
	)
	(arc
		(start 305.978306 -74.325734)
		(mid 305.775712 -74.209916)
		(end 305.629818 -74.027792)
		(width 0.0889)
		(layer "In4.Cu")
		(net "P3E_CPU0_PE2_SS_RXN<15>")
	)
	(arc
		(start 303.529238 -74.821288)
		(mid 303.233975 -74.742137)
		(end 303.017936 -74.525886)
		(width 0.0889)
		(layer "In4.Cu")
		(net "P3E_CPU0_PE2_SS_RXN<15>")
	)
	(arc
		(start 304.041556 -74.525886)
		(mid 303.825493 -74.742095)
		(end 303.530254 -74.821288)
		(width 0.0889)
		(layer "In4.Cu")
		(net "P3E_CPU0_PE2_SS_RXN<15>")
	)
	(arc
		(start 303.017936 -74.525886)
		(mid 302.671226 -74.325575)
		(end 302.324516 -74.525886)
		(width 0.0889)
		(layer "In4.Cu")
		(net "P3E_CPU0_PE2_SS_RXN<15>")
	)
	(arc
		(start 301.465996 -75.021186)
		(mid 301.258992 -75.23205)
		(end 300.975776 -75.316334)
		(width 0.0889)
		(layer "In4.Cu")
		(net "P3E_CPU0_PE2_SS_RXN<15>")
	)
	(arc
		(start 305.2318 -73.830688)
		(mid 305.040158 -73.887854)
		(end 304.900076 -74.030586)
		(width 0.0889)
		(layer "In4.Cu")
		(net "P3E_CPU0_PE2_SS_RXN<15>")
	)
	(arc
		(start 300.94301 -75.316334)
		(mid 300.863323 -75.326629)
		(end 300.787308 -75.352656)
		(width 0.0889)
		(layer "In4.Cu")
		(net "P3E_CPU0_PE2_SS_RXN<15>")
	)
	(segment
		(start 364.685072 -4.389882)
		(end 364.685072 -3.762248)
		(width 0.1143)
		(layer "F.Cu")
		(net "P3E_CPU0_PE2_SS_RXN<14>")
	)
	(segment
		(start 364.380272 -3.457448)
		(end 364.380272 -2.90195)
		(width 0.1143)
		(layer "F.Cu")
		(net "P3E_CPU0_PE2_SS_RXN<14>")
	)
	(segment
		(start 364.2106 -2.2098)
		(end 364.450376 -1.970024)
		(width 0.1143)
		(layer "F.Cu")
		(net "P3E_CPU0_PE2_SS_RXN<14>")
	)
	(segment
		(start 364.450376 -1.970024)
		(end 364.75035 -1.970024)
		(width 0.1143)
		(layer "F.Cu")
		(net "P3E_CPU0_PE2_SS_RXN<14>")
	)
	(segment
		(start 301.241206 -76.211938)
		(end 301.812706 -76.211938)
		(width 0.1143)
		(layer "F.Cu")
		(net "P3E_CPU0_PE2_SS_RXN<14>")
	)
	(segment
		(start 364.380272 -2.90195)
		(end 364.2106 -2.732278)
		(width 0.1143)
		(layer "F.Cu")
		(net "P3E_CPU0_PE2_SS_RXN<14>")
	)
	(segment
		(start 364.2106 -2.732278)
		(end 364.2106 -2.2098)
		(width 0.1143)
		(layer "F.Cu")
		(net "P3E_CPU0_PE2_SS_RXN<14>")
	)
	(segment
		(start 364.685072 -3.762248)
		(end 364.380272 -3.457448)
		(width 0.1143)
		(layer "F.Cu")
		(net "P3E_CPU0_PE2_SS_RXN<14>")
	)
	(via
		(at 301.812706 -76.211938)
		(size 0.508)
		(drill 0.254)
		(layers "F.Cu" "B.Cu")
		(net "P3E_CPU0_PE2_SS_RXN<14>")
	)
	(via
		(at 364.75035 -1.970024)
		(size 0.508)
		(drill 0.254)
		(layers "F.Cu" "B.Cu")
		(net "P3E_CPU0_PE2_SS_RXN<14>")
	)
	(segment
		(start 333.5528 -42.26814)
		(end 333.374746 -43.156886)
		(width 0.1143)
		(layer "In4.Cu")
		(net "P3E_CPU0_PE2_SS_RXN<14>")
	)
	(segment
		(start 315.069474 -47.055532)
		(end 309.96255 -51.177698)
		(width 0.1143)
		(layer "In4.Cu")
		(net "P3E_CPU0_PE2_SS_RXN<14>")
	)
	(segment
		(start 301.877984 -75.808586)
		(end 301.812706 -75.873864)
		(width 0.0889)
		(layer "In4.Cu")
		(net "P3E_CPU0_PE2_SS_RXN<14>")
	)
	(segment
		(start 364.75035 -1.970024)
		(end 364.3757 -1.970024)
		(width 0.1143)
		(layer "In4.Cu")
		(net "P3E_CPU0_PE2_SS_RXN<14>")
	)
	(segment
		(start 364.3757 -1.970024)
		(end 364.2614 -2.084324)
		(width 0.1143)
		(layer "In4.Cu")
		(net "P3E_CPU0_PE2_SS_RXN<14>")
	)
	(segment
		(start 364.2614 -2.084324)
		(end 364.2614 -3.676142)
		(width 0.1143)
		(layer "In4.Cu")
		(net "P3E_CPU0_PE2_SS_RXN<14>")
	)
	(segment
		(start 310.72582 -54.37632)
		(end 312.262266 -59.7789)
		(width 0.1143)
		(layer "In4.Cu")
		(net "P3E_CPU0_PE2_SS_RXN<14>")
	)
	(segment
		(start 305.467766 -75.811888)
		(end 303.51603 -75.811888)
		(width 0.0889)
		(layer "In4.Cu")
		(net "P3E_CPU0_PE2_SS_RXN<14>")
	)
	(segment
		(start 341.147908 -36.25723)
		(end 341.147908 -39.686738)
		(width 0.1143)
		(layer "In4.Cu")
		(net "P3E_CPU0_PE2_SS_RXN<14>")
	)
	(segment
		(start 312.039 -62.16015)
		(end 311.079134 -64.431418)
		(width 0.1143)
		(layer "In4.Cu")
		(net "P3E_CPU0_PE2_SS_RXN<14>")
	)
	(segment
		(start 312.262266 -59.7789)
		(end 312.039 -62.16015)
		(width 0.1143)
		(layer "In4.Cu")
		(net "P3E_CPU0_PE2_SS_RXN<14>")
	)
	(segment
		(start 361.465876 -26.194512)
		(end 356.77475 -33.231836)
		(width 0.1143)
		(layer "In4.Cu")
		(net "P3E_CPU0_PE2_SS_RXN<14>")
	)
	(segment
		(start 306.765452 -75.367134)
		(end 306.743354 -75.367134)
		(width 0.0889)
		(layer "In4.Cu")
		(net "P3E_CPU0_PE2_SS_RXN<14>")
	)
	(segment
		(start 320.061844 -46.096428)
		(end 315.069474 -47.055532)
		(width 0.1143)
		(layer "In4.Cu")
		(net "P3E_CPU0_PE2_SS_RXN<14>")
	)
	(segment
		(start 309.532274 -52.756816)
		(end 309.532274 -52.760626)
		(width 0.1143)
		(layer "In4.Cu")
		(net "P3E_CPU0_PE2_SS_RXN<14>")
	)
	(segment
		(start 311.079134 -64.431418)
		(end 310.52262 -64.778382)
		(width 0.1143)
		(layer "In4.Cu")
		(net "P3E_CPU0_PE2_SS_RXN<14>")
	)
	(segment
		(start 341.147908 -39.686738)
		(end 340.64067 -40.193976)
		(width 0.1143)
		(layer "In4.Cu")
		(net "P3E_CPU0_PE2_SS_RXN<14>")
	)
	(segment
		(start 301.812706 -75.873864)
		(end 301.812706 -76.211938)
		(width 0.0889)
		(layer "In4.Cu")
		(net "P3E_CPU0_PE2_SS_RXN<14>")
	)
	(segment
		(start 356.77475 -33.231836)
		(end 354.918264 -34.469578)
		(width 0.1143)
		(layer "In4.Cu")
		(net "P3E_CPU0_PE2_SS_RXN<14>")
	)
	(segment
		(start 364.82655 -10.490962)
		(end 361.465876 -26.194512)
		(width 0.1143)
		(layer "In4.Cu")
		(net "P3E_CPU0_PE2_SS_RXN<14>")
	)
	(segment
		(start 333.374746 -43.156886)
		(end 333.093822 -43.578526)
		(width 0.1143)
		(layer "In4.Cu")
		(net "P3E_CPU0_PE2_SS_RXN<14>")
	)
	(segment
		(start 309.544974 -52.129436)
		(end 309.532274 -52.756816)
		(width 0.1143)
		(layer "In4.Cu")
		(net "P3E_CPU0_PE2_SS_RXN<14>")
	)
	(segment
		(start 310.52262 -64.778382)
		(end 309.860188 -66.164968)
		(width 0.1143)
		(layer "In4.Cu")
		(net "P3E_CPU0_PE2_SS_RXN<14>")
	)
	(segment
		(start 307.111908 -75.367134)
		(end 306.765452 -75.367134)
		(width 0.1143)
		(layer "In4.Cu")
		(net "P3E_CPU0_PE2_SS_RXN<14>")
	)
	(segment
		(start 346.762578 -35.976052)
		(end 344.90279 -35.583368)
		(width 0.1143)
		(layer "In4.Cu")
		(net "P3E_CPU0_PE2_SS_RXN<14>")
	)
	(segment
		(start 309.532274 -52.760626)
		(end 309.574692 -53.150008)
		(width 0.1143)
		(layer "In4.Cu")
		(net "P3E_CPU0_PE2_SS_RXN<14>")
	)
	(segment
		(start 354.918264 -34.469578)
		(end 346.762578 -35.976052)
		(width 0.1143)
		(layer "In4.Cu")
		(net "P3E_CPU0_PE2_SS_RXN<14>")
	)
	(segment
		(start 364.2614 -3.676142)
		(end 364.82655 -4.241292)
		(width 0.1143)
		(layer "In4.Cu")
		(net "P3E_CPU0_PE2_SS_RXN<14>")
	)
	(segment
		(start 335.393792 -40.193976)
		(end 333.5528 -41.413938)
		(width 0.1143)
		(layer "In4.Cu")
		(net "P3E_CPU0_PE2_SS_RXN<14>")
	)
	(segment
		(start 310.337454 -68.92036)
		(end 308.209696 -74.057002)
		(width 0.1143)
		(layer "In4.Cu")
		(net "P3E_CPU0_PE2_SS_RXN<14>")
	)
	(segment
		(start 308.209696 -74.057002)
		(end 307.111908 -75.367134)
		(width 0.1143)
		(layer "In4.Cu")
		(net "P3E_CPU0_PE2_SS_RXN<14>")
	)
	(segment
		(start 306.743354 -75.367134)
		(end 306.692554 -75.316334)
		(width 0.0889)
		(layer "In4.Cu")
		(net "P3E_CPU0_PE2_SS_RXN<14>")
	)
	(segment
		(start 340.64067 -40.193976)
		(end 335.393792 -40.193976)
		(width 0.1143)
		(layer "In4.Cu")
		(net "P3E_CPU0_PE2_SS_RXN<14>")
	)
	(segment
		(start 324.851014 -46.590204)
		(end 320.061844 -46.096428)
		(width 0.1143)
		(layer "In4.Cu")
		(net "P3E_CPU0_PE2_SS_RXN<14>")
	)
	(segment
		(start 333.5528 -41.413938)
		(end 333.5528 -42.26814)
		(width 0.1143)
		(layer "In4.Cu")
		(net "P3E_CPU0_PE2_SS_RXN<14>")
	)
	(segment
		(start 309.574692 -53.150008)
		(end 310.72582 -54.37632)
		(width 0.1143)
		(layer "In4.Cu")
		(net "P3E_CPU0_PE2_SS_RXN<14>")
	)
	(segment
		(start 344.90279 -35.583368)
		(end 341.82177 -35.583368)
		(width 0.1143)
		(layer "In4.Cu")
		(net "P3E_CPU0_PE2_SS_RXN<14>")
	)
	(segment
		(start 309.96255 -51.177698)
		(end 309.705248 -51.566826)
		(width 0.1143)
		(layer "In4.Cu")
		(net "P3E_CPU0_PE2_SS_RXN<14>")
	)
	(segment
		(start 305.96332 -75.316334)
		(end 305.467766 -75.811888)
		(width 0.0889)
		(layer "In4.Cu")
		(net "P3E_CPU0_PE2_SS_RXN<14>")
	)
	(segment
		(start 309.705248 -51.566826)
		(end 309.544974 -52.129436)
		(width 0.1143)
		(layer "In4.Cu")
		(net "P3E_CPU0_PE2_SS_RXN<14>")
	)
	(segment
		(start 333.093822 -43.578526)
		(end 331.945742 -44.343828)
		(width 0.1143)
		(layer "In4.Cu")
		(net "P3E_CPU0_PE2_SS_RXN<14>")
	)
	(segment
		(start 306.692554 -75.316334)
		(end 305.96332 -75.316334)
		(width 0.0889)
		(layer "In4.Cu")
		(net "P3E_CPU0_PE2_SS_RXN<14>")
	)
	(segment
		(start 309.860188 -66.164968)
		(end 310.337454 -68.92036)
		(width 0.1143)
		(layer "In4.Cu")
		(net "P3E_CPU0_PE2_SS_RXN<14>")
	)
	(segment
		(start 331.945742 -44.343828)
		(end 324.851014 -46.590204)
		(width 0.1143)
		(layer "In4.Cu")
		(net "P3E_CPU0_PE2_SS_RXN<14>")
	)
	(segment
		(start 341.82177 -35.583368)
		(end 341.147908 -36.25723)
		(width 0.1143)
		(layer "In4.Cu")
		(net "P3E_CPU0_PE2_SS_RXN<14>")
	)
	(segment
		(start 364.82655 -4.241292)
		(end 364.82655 -10.490962)
		(width 0.1143)
		(layer "In4.Cu")
		(net "P3E_CPU0_PE2_SS_RXN<14>")
	)
	(arc
		(start 303.017936 -75.516486)
		(mid 302.671226 -75.316175)
		(end 302.324516 -75.516486)
		(width 0.0889)
		(layer "In4.Cu")
		(net "P3E_CPU0_PE2_SS_RXN<14>")
	)
	(arc
		(start 303.51603 -75.811888)
		(mid 303.228343 -75.729367)
		(end 303.017936 -75.516486)
		(width 0.0889)
		(layer "In4.Cu")
		(net "P3E_CPU0_PE2_SS_RXN<14>")
	)
	(arc
		(start 302.324516 -75.516486)
		(mid 302.136093 -75.71579)
		(end 301.877984 -75.808586)
		(width 0.0889)
		(layer "In4.Cu")
		(net "P3E_CPU0_PE2_SS_RXN<14>")
	)
	(segment
		(start 301.241206 -77.202538)
		(end 301.812706 -77.202538)
		(width 0.1143)
		(layer "F.Cu")
		(net "P3E_CPU0_PE2_SS_RXN<13>")
	)
	(segment
		(start 366.562894 -3.051556)
		(end 366.44834 -2.937002)
		(width 0.1143)
		(layer "F.Cu")
		(net "P3E_CPU0_PE2_SS_RXN<13>")
	)
	(segment
		(start 366.285018 -3.7084)
		(end 366.562894 -3.430524)
		(width 0.1143)
		(layer "F.Cu")
		(net "P3E_CPU0_PE2_SS_RXN<13>")
	)
	(segment
		(start 366.44834 -2.937002)
		(end 366.10036 -2.937002)
		(width 0.1143)
		(layer "F.Cu")
		(net "P3E_CPU0_PE2_SS_RXN<13>")
	)
	(segment
		(start 366.562894 -3.430524)
		(end 366.562894 -3.051556)
		(width 0.1143)
		(layer "F.Cu")
		(net "P3E_CPU0_PE2_SS_RXN<13>")
	)
	(segment
		(start 366.285018 -4.389882)
		(end 366.285018 -3.7084)
		(width 0.1143)
		(layer "F.Cu")
		(net "P3E_CPU0_PE2_SS_RXN<13>")
	)
	(via
		(at 301.812706 -77.202538)
		(size 0.508)
		(drill 0.254)
		(layers "F.Cu" "B.Cu")
		(net "P3E_CPU0_PE2_SS_RXN<13>")
	)
	(via
		(at 366.10036 -2.937002)
		(size 0.508)
		(drill 0.254)
		(layers "F.Cu" "B.Cu")
		(net "P3E_CPU0_PE2_SS_RXN<13>")
	)
	(segment
		(start 352.901504 -36.249864)
		(end 352.205798 -37.145214)
		(width 0.1143)
		(layer "In4.Cu")
		(net "P3E_CPU0_PE2_SS_RXN<13>")
	)
	(segment
		(start 312.485278 -54.969664)
		(end 312.671968 -55.7149)
		(width 0.1143)
		(layer "In4.Cu")
		(net "P3E_CPU0_PE2_SS_RXN<13>")
	)
	(segment
		(start 365.624872 -7.700264)
		(end 365.402622 -8.811768)
		(width 0.1143)
		(layer "In4.Cu")
		(net "P3E_CPU0_PE2_SS_RXN<13>")
	)
	(segment
		(start 312.694828 -53.91658)
		(end 312.485278 -54.969664)
		(width 0.1143)
		(layer "In4.Cu")
		(net "P3E_CPU0_PE2_SS_RXN<13>")
	)
	(segment
		(start 312.469022 -52.652168)
		(end 312.694828 -53.91658)
		(width 0.1143)
		(layer "In4.Cu")
		(net "P3E_CPU0_PE2_SS_RXN<13>")
	)
	(segment
		(start 342.121744 -40.9575)
		(end 342.007444 -41.0718)
		(width 0.1143)
		(layer "In4.Cu")
		(net "P3E_CPU0_PE2_SS_RXN<13>")
	)
	(segment
		(start 312.657998 -65.114424)
		(end 309.013352 -73.912222)
		(width 0.1143)
		(layer "In4.Cu")
		(net "P3E_CPU0_PE2_SS_RXN<13>")
	)
	(segment
		(start 303.547272 -76.611988)
		(end 303.51857 -76.611988)
		(width 0.0889)
		(layer "In4.Cu")
		(net "P3E_CPU0_PE2_SS_RXN<13>")
	)
	(segment
		(start 366.10036 -2.937002)
		(end 366.47501 -2.937002)
		(width 0.1143)
		(layer "In4.Cu")
		(net "P3E_CPU0_PE2_SS_RXN<13>")
	)
	(segment
		(start 306.816252 -76.0857)
		(end 306.765452 -76.1365)
		(width 0.0889)
		(layer "In4.Cu")
		(net "P3E_CPU0_PE2_SS_RXN<13>")
	)
	(segment
		(start 312.658252 -65.113662)
		(end 312.657998 -65.114424)
		(width 0.1143)
		(layer "In4.Cu")
		(net "P3E_CPU0_PE2_SS_RXN<13>")
	)
	(segment
		(start 342.406986 -37.31895)
		(end 342.121744 -37.604192)
		(width 0.1143)
		(layer "In4.Cu")
		(net "P3E_CPU0_PE2_SS_RXN<13>")
	)
	(segment
		(start 342.121744 -37.604192)
		(end 342.121744 -40.9575)
		(width 0.1143)
		(layer "In4.Cu")
		(net "P3E_CPU0_PE2_SS_RXN<13>")
	)
	(segment
		(start 366.155478 -5.047742)
		(end 365.961168 -5.177282)
		(width 0.1143)
		(layer "In4.Cu")
		(net "P3E_CPU0_PE2_SS_RXN<13>")
	)
	(segment
		(start 365.956342 -6.04393)
		(end 365.762032 -6.17347)
		(width 0.1143)
		(layer "In4.Cu")
		(net "P3E_CPU0_PE2_SS_RXN<13>")
	)
	(segment
		(start 357.037132 -33.49244)
		(end 353.746816 -35.686238)
		(width 0.1143)
		(layer "In4.Cu")
		(net "P3E_CPU0_PE2_SS_RXN<13>")
	)
	(segment
		(start 351.785682 -37.31895)
		(end 342.406986 -37.31895)
		(width 0.1143)
		(layer "In4.Cu")
		(net "P3E_CPU0_PE2_SS_RXN<13>")
	)
	(segment
		(start 313.11215 -60.83046)
		(end 312.726578 -64.948816)
		(width 0.1143)
		(layer "In4.Cu")
		(net "P3E_CPU0_PE2_SS_RXN<13>")
	)
	(segment
		(start 353.517962 -35.640518)
		(end 353.232466 -35.830764)
		(width 0.1143)
		(layer "In4.Cu")
		(net "P3E_CPU0_PE2_SS_RXN<13>")
	)
	(segment
		(start 336.187796 -41.0718)
		(end 335.761584 -41.498012)
		(width 0.1143)
		(layer "In4.Cu")
		(net "P3E_CPU0_PE2_SS_RXN<13>")
	)
	(segment
		(start 306.929536 -76.0857)
		(end 306.83835 -76.0857)
		(width 0.1143)
		(layer "In4.Cu")
		(net "P3E_CPU0_PE2_SS_RXN<13>")
	)
	(segment
		(start 365.762032 -6.17347)
		(end 365.694722 -6.509766)
		(width 0.1143)
		(layer "In4.Cu")
		(net "P3E_CPU0_PE2_SS_RXN<13>")
	)
	(segment
		(start 303.60874 -76.604368)
		(end 303.603914 -76.60513)
		(width 0.0889)
		(layer "In4.Cu")
		(net "P3E_CPU0_PE2_SS_RXN<13>")
	)
	(segment
		(start 302.105822 -77.033374)
		(end 301.812706 -77.202538)
		(width 0.0889)
		(layer "In4.Cu")
		(net "P3E_CPU0_PE2_SS_RXN<13>")
	)
	(segment
		(start 353.232466 -35.830764)
		(end 353.186746 -36.059618)
		(width 0.1143)
		(layer "In4.Cu")
		(net "P3E_CPU0_PE2_SS_RXN<13>")
	)
	(segment
		(start 307.26634 -75.893422)
		(end 306.929536 -76.0857)
		(width 0.1143)
		(layer "In4.Cu")
		(net "P3E_CPU0_PE2_SS_RXN<13>")
	)
	(segment
		(start 366.222788 -4.711446)
		(end 366.155478 -5.047742)
		(width 0.1143)
		(layer "In4.Cu")
		(net "P3E_CPU0_PE2_SS_RXN<13>")
	)
	(segment
		(start 361.976416 -26.084022)
		(end 359.506774 -29.788358)
		(width 0.1143)
		(layer "In4.Cu")
		(net "P3E_CPU0_PE2_SS_RXN<13>")
	)
	(segment
		(start 302.689006 -76.116434)
		(end 302.653446 -76.116434)
		(width 0.0889)
		(layer "In4.Cu")
		(net "P3E_CPU0_PE2_SS_RXN<13>")
	)
	(segment
		(start 353.186746 -36.059618)
		(end 352.901504 -36.249864)
		(width 0.1143)
		(layer "In4.Cu")
		(net "P3E_CPU0_PE2_SS_RXN<13>")
	)
	(segment
		(start 366.023398 -5.707634)
		(end 365.956342 -6.04393)
		(width 0.1143)
		(layer "In4.Cu")
		(net "P3E_CPU0_PE2_SS_RXN<13>")
	)
	(segment
		(start 313.887104 -49.489106)
		(end 312.469022 -52.652168)
		(width 0.1143)
		(layer "In4.Cu")
		(net "P3E_CPU0_PE2_SS_RXN<13>")
	)
	(segment
		(start 353.746816 -35.686238)
		(end 353.517962 -35.640518)
		(width 0.1143)
		(layer "In4.Cu")
		(net "P3E_CPU0_PE2_SS_RXN<13>")
	)
	(segment
		(start 335.761584 -43.327574)
		(end 335.507076 -43.582082)
		(width 0.1143)
		(layer "In4.Cu")
		(net "P3E_CPU0_PE2_SS_RXN<13>")
	)
	(segment
		(start 352.205798 -37.145214)
		(end 351.785682 -37.31895)
		(width 0.1143)
		(layer "In4.Cu")
		(net "P3E_CPU0_PE2_SS_RXN<13>")
	)
	(segment
		(start 312.505598 -56.373776)
		(end 313.11215 -60.83046)
		(width 0.1143)
		(layer "In4.Cu")
		(net "P3E_CPU0_PE2_SS_RXN<13>")
	)
	(segment
		(start 366.47501 -2.937002)
		(end 366.58931 -3.051302)
		(width 0.1143)
		(layer "In4.Cu")
		(net "P3E_CPU0_PE2_SS_RXN<13>")
	)
	(segment
		(start 320.022474 -46.460918)
		(end 316.89929 -47.05731)
		(width 0.1143)
		(layer "In4.Cu")
		(net "P3E_CPU0_PE2_SS_RXN<13>")
	)
	(segment
		(start 365.894112 -5.513324)
		(end 366.023398 -5.707634)
		(width 0.1143)
		(layer "In4.Cu")
		(net "P3E_CPU0_PE2_SS_RXN<13>")
	)
	(segment
		(start 316.89929 -47.05731)
		(end 313.887104 -49.489106)
		(width 0.1143)
		(layer "In4.Cu")
		(net "P3E_CPU0_PE2_SS_RXN<13>")
	)
	(segment
		(start 366.58931 -4.161536)
		(end 366.222788 -4.711446)
		(width 0.1143)
		(layer "In4.Cu")
		(net "P3E_CPU0_PE2_SS_RXN<13>")
	)
	(segment
		(start 309.013352 -73.912222)
		(end 307.26634 -75.893422)
		(width 0.1143)
		(layer "In4.Cu")
		(net "P3E_CPU0_PE2_SS_RXN<13>")
	)
	(segment
		(start 366.58931 -3.051302)
		(end 366.58931 -4.161536)
		(width 0.1143)
		(layer "In4.Cu")
		(net "P3E_CPU0_PE2_SS_RXN<13>")
	)
	(segment
		(start 302.129698 -76.943966)
		(end 302.105822 -77.033374)
		(width 0.0889)
		(layer "In4.Cu")
		(net "P3E_CPU0_PE2_SS_RXN<13>")
	)
	(segment
		(start 365.756952 -7.040118)
		(end 365.562642 -7.169658)
		(width 0.1143)
		(layer "In4.Cu")
		(net "P3E_CPU0_PE2_SS_RXN<13>")
	)
	(segment
		(start 335.507076 -43.582082)
		(end 324.84949 -46.956218)
		(width 0.1143)
		(layer "In4.Cu")
		(net "P3E_CPU0_PE2_SS_RXN<13>")
	)
	(segment
		(start 303.77384 -76.575666)
		(end 303.60874 -76.604368)
		(width 0.0889)
		(layer "In4.Cu")
		(net "P3E_CPU0_PE2_SS_RXN<13>")
	)
	(segment
		(start 306.765452 -76.1365)
		(end 304.213006 -76.1365)
		(width 0.0889)
		(layer "In4.Cu")
		(net "P3E_CPU0_PE2_SS_RXN<13>")
	)
	(segment
		(start 365.402622 -8.811768)
		(end 365.520478 -9.401556)
		(width 0.1143)
		(layer "In4.Cu")
		(net "P3E_CPU0_PE2_SS_RXN<13>")
	)
	(segment
		(start 324.84949 -46.956218)
		(end 320.022474 -46.460918)
		(width 0.1143)
		(layer "In4.Cu")
		(net "P3E_CPU0_PE2_SS_RXN<13>")
	)
	(segment
		(start 365.495332 -7.505954)
		(end 365.624872 -7.700264)
		(width 0.1143)
		(layer "In4.Cu")
		(net "P3E_CPU0_PE2_SS_RXN<13>")
	)
	(segment
		(start 312.671968 -55.7149)
		(end 312.505598 -56.373776)
		(width 0.1143)
		(layer "In4.Cu")
		(net "P3E_CPU0_PE2_SS_RXN<13>")
	)
	(segment
		(start 365.824262 -6.704076)
		(end 365.756952 -7.040118)
		(width 0.1143)
		(layer "In4.Cu")
		(net "P3E_CPU0_PE2_SS_RXN<13>")
	)
	(segment
		(start 365.520478 -9.401556)
		(end 361.976416 -26.084022)
		(width 0.1143)
		(layer "In4.Cu")
		(net "P3E_CPU0_PE2_SS_RXN<13>")
	)
	(segment
		(start 365.961168 -5.177282)
		(end 365.894112 -5.513324)
		(width 0.1143)
		(layer "In4.Cu")
		(net "P3E_CPU0_PE2_SS_RXN<13>")
	)
	(segment
		(start 312.726578 -64.948816)
		(end 312.658252 -65.113662)
		(width 0.1143)
		(layer "In4.Cu")
		(net "P3E_CPU0_PE2_SS_RXN<13>")
	)
	(segment
		(start 342.007444 -41.0718)
		(end 336.187796 -41.0718)
		(width 0.1143)
		(layer "In4.Cu")
		(net "P3E_CPU0_PE2_SS_RXN<13>")
	)
	(segment
		(start 359.506774 -29.788358)
		(end 357.037132 -33.49244)
		(width 0.1143)
		(layer "In4.Cu")
		(net "P3E_CPU0_PE2_SS_RXN<13>")
	)
	(segment
		(start 335.761584 -41.498012)
		(end 335.761584 -43.327574)
		(width 0.1143)
		(layer "In4.Cu")
		(net "P3E_CPU0_PE2_SS_RXN<13>")
	)
	(segment
		(start 306.83835 -76.0857)
		(end 306.816252 -76.0857)
		(width 0.0889)
		(layer "In4.Cu")
		(net "P3E_CPU0_PE2_SS_RXN<13>")
	)
	(segment
		(start 304.213006 -76.1365)
		(end 303.77384 -76.575666)
		(width 0.0889)
		(layer "In4.Cu")
		(net "P3E_CPU0_PE2_SS_RXN<13>")
	)
	(segment
		(start 365.694722 -6.509766)
		(end 365.824262 -6.704076)
		(width 0.1143)
		(layer "In4.Cu")
		(net "P3E_CPU0_PE2_SS_RXN<13>")
	)
	(segment
		(start 365.562642 -7.169658)
		(end 365.495332 -7.505954)
		(width 0.1143)
		(layer "In4.Cu")
		(net "P3E_CPU0_PE2_SS_RXN<13>")
	)
	(arc
		(start 303.183036 -76.411836)
		(mid 302.974428 -76.199904)
		(end 302.689006 -76.116434)
		(width 0.0889)
		(layer "In4.Cu")
		(net "P3E_CPU0_PE2_SS_RXN<13>")
	)
	(arc
		(start 303.603914 -76.60513)
		(mid 303.575715 -76.609562)
		(end 303.547272 -76.611988)
		(width 0.0889)
		(layer "In4.Cu")
		(net "P3E_CPU0_PE2_SS_RXN<13>")
	)
	(arc
		(start 302.653446 -76.116434)
		(mid 302.171735 -76.391043)
		(end 302.129698 -76.943966)
		(width 0.0889)
		(layer "In4.Cu")
		(net "P3E_CPU0_PE2_SS_RXN<13>")
	)
	(arc
		(start 303.51857 -76.611988)
		(mid 303.32472 -76.555638)
		(end 303.183036 -76.411836)
		(width 0.0889)
		(layer "In4.Cu")
		(net "P3E_CPU0_PE2_SS_RXN<13>")
	)
	(segment
		(start 369.167664 -1.419606)
		(end 369.567714 -1.419606)
		(width 0.1143)
		(layer "F.Cu")
		(net "P3E_CPU0_PE2_SS_RXN<12>")
	)
	(segment
		(start 369.251992 -2.653284)
		(end 369.053364 -2.454656)
		(width 0.1143)
		(layer "F.Cu")
		(net "P3E_CPU0_PE2_SS_RXN<12>")
	)
	(segment
		(start 369.053364 -2.454656)
		(end 369.053364 -1.533906)
		(width 0.1143)
		(layer "F.Cu")
		(net "P3E_CPU0_PE2_SS_RXN<12>")
	)
	(segment
		(start 369.053364 -1.533906)
		(end 369.167664 -1.419606)
		(width 0.1143)
		(layer "F.Cu")
		(net "P3E_CPU0_PE2_SS_RXN<12>")
	)
	(segment
		(start 369.251992 -3.457448)
		(end 369.251992 -2.653284)
		(width 0.1143)
		(layer "F.Cu")
		(net "P3E_CPU0_PE2_SS_RXN<12>")
	)
	(segment
		(start 301.241206 -78.193138)
		(end 301.812706 -78.193138)
		(width 0.1143)
		(layer "F.Cu")
		(net "P3E_CPU0_PE2_SS_RXN<12>")
	)
	(segment
		(start 369.485164 -3.69062)
		(end 369.251992 -3.457448)
		(width 0.1143)
		(layer "F.Cu")
		(net "P3E_CPU0_PE2_SS_RXN<12>")
	)
	(segment
		(start 369.485164 -4.389882)
		(end 369.485164 -3.69062)
		(width 0.1143)
		(layer "F.Cu")
		(net "P3E_CPU0_PE2_SS_RXN<12>")
	)
	(via
		(at 369.567714 -1.419606)
		(size 0.508)
		(drill 0.254)
		(layers "F.Cu" "B.Cu")
		(net "P3E_CPU0_PE2_SS_RXN<12>")
	)
	(via
		(at 301.812706 -78.193138)
		(size 0.508)
		(drill 0.254)
		(layers "F.Cu" "B.Cu")
		(net "P3E_CPU0_PE2_SS_RXN<12>")
	)
	(segment
		(start 306.548536 -77.216)
		(end 305.535584 -77.216)
		(width 0.0889)
		(layer "In4.Cu")
		(net "P3E_CPU0_PE2_SS_RXN<12>")
	)
	(segment
		(start 341.1601 -43.831764)
		(end 340.946486 -44.045378)
		(width 0.1143)
		(layer "In4.Cu")
		(net "P3E_CPU0_PE2_SS_RXN<12>")
	)
	(segment
		(start 314.110116 -60.592208)
		(end 313.693302 -65.038986)
		(width 0.1143)
		(layer "In4.Cu")
		(net "P3E_CPU0_PE2_SS_RXN<12>")
	)
	(segment
		(start 301.498508 -77.945234)
		(end 301.51959 -78.023974)
		(width 0.0889)
		(layer "In4.Cu")
		(net "P3E_CPU0_PE2_SS_RXN<12>")
	)
	(segment
		(start 343.948766 -38.88105)
		(end 343.760298 -39.069518)
		(width 0.1143)
		(layer "In4.Cu")
		(net "P3E_CPU0_PE2_SS_RXN<12>")
	)
	(segment
		(start 313.693302 -65.038986)
		(end 309.603648 -74.913998)
		(width 0.1143)
		(layer "In4.Cu")
		(net "P3E_CPU0_PE2_SS_RXN<12>")
	)
	(segment
		(start 313.488324 -56.372506)
		(end 314.098432 -60.556394)
		(width 0.1143)
		(layer "In4.Cu")
		(net "P3E_CPU0_PE2_SS_RXN<12>")
	)
	(segment
		(start 353.953064 -36.696142)
		(end 352.316288 -38.762686)
		(width 0.1143)
		(layer "In4.Cu")
		(net "P3E_CPU0_PE2_SS_RXN<12>")
	)
	(segment
		(start 304.698146 -77.317346)
		(end 304.5968 -77.216)
		(width 0.0889)
		(layer "In4.Cu")
		(net "P3E_CPU0_PE2_SS_RXN<12>")
	)
	(segment
		(start 306.599336 -77.2668)
		(end 306.548536 -77.216)
		(width 0.0889)
		(layer "In4.Cu")
		(net "P3E_CPU0_PE2_SS_RXN<12>")
	)
	(segment
		(start 309.603648 -74.913998)
		(end 307.827172 -76.830936)
		(width 0.1143)
		(layer "In4.Cu")
		(net "P3E_CPU0_PE2_SS_RXN<12>")
	)
	(segment
		(start 305.535584 -77.216)
		(end 305.434238 -77.317346)
		(width 0.0889)
		(layer "In4.Cu")
		(net "P3E_CPU0_PE2_SS_RXN<12>")
	)
	(segment
		(start 337.239102 -44.013374)
		(end 324.95617 -47.901098)
		(width 0.1143)
		(layer "In4.Cu")
		(net "P3E_CPU0_PE2_SS_RXN<12>")
	)
	(segment
		(start 303.551336 -77.793088)
		(end 303.515014 -77.793088)
		(width 0.0889)
		(layer "In4.Cu")
		(net "P3E_CPU0_PE2_SS_RXN<12>")
	)
	(segment
		(start 317.518796 -47.888144)
		(end 314.570872 -50.266854)
		(width 0.1143)
		(layer "In4.Cu")
		(net "P3E_CPU0_PE2_SS_RXN<12>")
	)
	(segment
		(start 340.946486 -44.062142)
		(end 339.211158 -44.415202)
		(width 0.1143)
		(layer "In4.Cu")
		(net "P3E_CPU0_PE2_SS_RXN<12>")
	)
	(segment
		(start 301.51959 -78.023974)
		(end 301.812706 -78.193138)
		(width 0.0889)
		(layer "In4.Cu")
		(net "P3E_CPU0_PE2_SS_RXN<12>")
	)
	(segment
		(start 313.438794 -52.792376)
		(end 313.640724 -53.92547)
		(width 0.1143)
		(layer "In4.Cu")
		(net "P3E_CPU0_PE2_SS_RXN<12>")
	)
	(segment
		(start 314.570872 -50.266854)
		(end 313.438794 -52.792376)
		(width 0.1143)
		(layer "In4.Cu")
		(net "P3E_CPU0_PE2_SS_RXN<12>")
	)
	(segment
		(start 301.830486 -77.793088)
		(end 301.79772 -77.793088)
		(width 0.0889)
		(layer "In4.Cu")
		(net "P3E_CPU0_PE2_SS_RXN<12>")
	)
	(segment
		(start 314.098686 -60.55741)
		(end 314.110116 -60.592208)
		(width 0.1143)
		(layer "In4.Cu")
		(net "P3E_CPU0_PE2_SS_RXN<12>")
	)
	(segment
		(start 304.5968 -77.216)
		(end 304.419 -77.216)
		(width 0.0889)
		(layer "In4.Cu")
		(net "P3E_CPU0_PE2_SS_RXN<12>")
	)
	(segment
		(start 366.267238 -10.618978)
		(end 362.884974 -26.428954)
		(width 0.1143)
		(layer "In4.Cu")
		(net "P3E_CPU0_PE2_SS_RXN<12>")
	)
	(segment
		(start 305.434238 -77.317346)
		(end 305.256438 -77.317346)
		(width 0.0889)
		(layer "In4.Cu")
		(net "P3E_CPU0_PE2_SS_RXN<12>")
	)
	(segment
		(start 369.18011 -1.419606)
		(end 369.078764 -1.520952)
		(width 0.1143)
		(layer "In4.Cu")
		(net "P3E_CPU0_PE2_SS_RXN<12>")
	)
	(segment
		(start 341.319358 -42.7101)
		(end 341.1601 -42.869358)
		(width 0.1143)
		(layer "In4.Cu")
		(net "P3E_CPU0_PE2_SS_RXN<12>")
	)
	(segment
		(start 313.440064 -54.936644)
		(end 313.644534 -55.751222)
		(width 0.1143)
		(layer "In4.Cu")
		(net "P3E_CPU0_PE2_SS_RXN<12>")
	)
	(segment
		(start 305.256438 -77.317346)
		(end 305.155092 -77.216)
		(width 0.0889)
		(layer "In4.Cu")
		(net "P3E_CPU0_PE2_SS_RXN<12>")
	)
	(segment
		(start 307.827172 -76.830936)
		(end 306.96535 -77.2668)
		(width 0.1143)
		(layer "In4.Cu")
		(net "P3E_CPU0_PE2_SS_RXN<12>")
	)
	(segment
		(start 343.760298 -42.27576)
		(end 343.325958 -42.7101)
		(width 0.1143)
		(layer "In4.Cu")
		(net "P3E_CPU0_PE2_SS_RXN<12>")
	)
	(segment
		(start 304.977292 -77.216)
		(end 304.875946 -77.317346)
		(width 0.0889)
		(layer "In4.Cu")
		(net "P3E_CPU0_PE2_SS_RXN<12>")
	)
	(segment
		(start 369.078764 -1.520952)
		(end 369.078764 -4.85775)
		(width 0.1143)
		(layer "In4.Cu")
		(net "P3E_CPU0_PE2_SS_RXN<12>")
	)
	(segment
		(start 340.946486 -44.045378)
		(end 340.946486 -44.062142)
		(width 0.1143)
		(layer "In4.Cu")
		(net "P3E_CPU0_PE2_SS_RXN<12>")
	)
	(segment
		(start 341.1601 -42.869358)
		(end 341.1601 -43.831764)
		(width 0.1143)
		(layer "In4.Cu")
		(net "P3E_CPU0_PE2_SS_RXN<12>")
	)
	(segment
		(start 343.325958 -42.7101)
		(end 341.319358 -42.7101)
		(width 0.1143)
		(layer "In4.Cu")
		(net "P3E_CPU0_PE2_SS_RXN<12>")
	)
	(segment
		(start 313.640724 -53.92547)
		(end 313.440064 -54.936644)
		(width 0.1143)
		(layer "In4.Cu")
		(net "P3E_CPU0_PE2_SS_RXN<12>")
	)
	(segment
		(start 339.211158 -44.415202)
		(end 337.239102 -44.013374)
		(width 0.1143)
		(layer "In4.Cu")
		(net "P3E_CPU0_PE2_SS_RXN<12>")
	)
	(segment
		(start 306.621434 -77.2668)
		(end 306.599336 -77.2668)
		(width 0.0889)
		(layer "In4.Cu")
		(net "P3E_CPU0_PE2_SS_RXN<12>")
	)
	(segment
		(start 304.875946 -77.317346)
		(end 304.698146 -77.317346)
		(width 0.0889)
		(layer "In4.Cu")
		(net "P3E_CPU0_PE2_SS_RXN<12>")
	)
	(segment
		(start 352.316288 -38.762686)
		(end 352.03003 -38.88105)
		(width 0.1143)
		(layer "In4.Cu")
		(net "P3E_CPU0_PE2_SS_RXN<12>")
	)
	(segment
		(start 324.95617 -47.901098)
		(end 320.070734 -47.399956)
		(width 0.1143)
		(layer "In4.Cu")
		(net "P3E_CPU0_PE2_SS_RXN<12>")
	)
	(segment
		(start 367.839498 -9.403842)
		(end 366.267238 -10.618978)
		(width 0.1143)
		(layer "In4.Cu")
		(net "P3E_CPU0_PE2_SS_RXN<12>")
	)
	(segment
		(start 305.155092 -77.216)
		(end 304.977292 -77.216)
		(width 0.0889)
		(layer "In4.Cu")
		(net "P3E_CPU0_PE2_SS_RXN<12>")
	)
	(segment
		(start 314.098432 -60.556394)
		(end 314.098686 -60.55741)
		(width 0.1143)
		(layer "In4.Cu")
		(net "P3E_CPU0_PE2_SS_RXN<12>")
	)
	(segment
		(start 320.070734 -47.399956)
		(end 317.518796 -47.888144)
		(width 0.1143)
		(layer "In4.Cu")
		(net "P3E_CPU0_PE2_SS_RXN<12>")
	)
	(segment
		(start 343.760298 -39.069518)
		(end 343.760298 -42.27576)
		(width 0.1143)
		(layer "In4.Cu")
		(net "P3E_CPU0_PE2_SS_RXN<12>")
	)
	(segment
		(start 352.03003 -38.88105)
		(end 343.948766 -38.88105)
		(width 0.1143)
		(layer "In4.Cu")
		(net "P3E_CPU0_PE2_SS_RXN<12>")
	)
	(segment
		(start 362.884974 -26.428954)
		(end 357.710486 -34.191194)
		(width 0.1143)
		(layer "In4.Cu")
		(net "P3E_CPU0_PE2_SS_RXN<12>")
	)
	(segment
		(start 304.419 -77.216)
		(end 304.066448 -77.568552)
		(width 0.0889)
		(layer "In4.Cu")
		(net "P3E_CPU0_PE2_SS_RXN<12>")
	)
	(segment
		(start 369.567714 -1.419606)
		(end 369.18011 -1.419606)
		(width 0.1143)
		(layer "In4.Cu")
		(net "P3E_CPU0_PE2_SS_RXN<12>")
	)
	(segment
		(start 313.644534 -55.751222)
		(end 313.488324 -56.372506)
		(width 0.1143)
		(layer "In4.Cu")
		(net "P3E_CPU0_PE2_SS_RXN<12>")
	)
	(segment
		(start 357.710486 -34.191194)
		(end 353.953064 -36.696142)
		(width 0.1143)
		(layer "In4.Cu")
		(net "P3E_CPU0_PE2_SS_RXN<12>")
	)
	(segment
		(start 306.96535 -77.2668)
		(end 306.621434 -77.2668)
		(width 0.1143)
		(layer "In4.Cu")
		(net "P3E_CPU0_PE2_SS_RXN<12>")
	)
	(segment
		(start 369.078764 -4.85775)
		(end 367.839498 -9.403842)
		(width 0.1143)
		(layer "In4.Cu")
		(net "P3E_CPU0_PE2_SS_RXN<12>")
	)
	(arc
		(start 302.324516 -77.497686)
		(mid 302.115908 -77.709618)
		(end 301.830486 -77.793088)
		(width 0.0889)
		(layer "In4.Cu")
		(net "P3E_CPU0_PE2_SS_RXN<12>")
	)
	(arc
		(start 303.017936 -77.497686)
		(mid 302.671226 -77.297375)
		(end 302.324516 -77.497686)
		(width 0.0889)
		(layer "In4.Cu")
		(net "P3E_CPU0_PE2_SS_RXN<12>")
	)
	(arc
		(start 304.066448 -77.568552)
		(mid 303.830152 -77.729568)
		(end 303.551336 -77.793088)
		(width 0.0889)
		(layer "In4.Cu")
		(net "P3E_CPU0_PE2_SS_RXN<12>")
	)
	(arc
		(start 303.515014 -77.793088)
		(mid 303.227894 -77.710329)
		(end 303.017936 -77.497686)
		(width 0.0889)
		(layer "In4.Cu")
		(net "P3E_CPU0_PE2_SS_RXN<12>")
	)
	(arc
		(start 301.79772 -77.793088)
		(mid 301.631426 -77.836322)
		(end 301.498508 -77.945234)
		(width 0.0889)
		(layer "In4.Cu")
		(net "P3E_CPU0_PE2_SS_RXN<12>")
	)
	(segment
		(start 371.604032 -3.075432)
		(end 371.742462 -2.937002)
		(width 0.1143)
		(layer "F.Cu")
		(net "P3E_CPU0_PE2_SS_RXN<11>")
	)
	(segment
		(start 371.88521 -3.723894)
		(end 371.604032 -3.442716)
		(width 0.1143)
		(layer "F.Cu")
		(net "P3E_CPU0_PE2_SS_RXN<11>")
	)
	(segment
		(start 302.099726 -78.688438)
		(end 302.671226 -78.688438)
		(width 0.1143)
		(layer "F.Cu")
		(net "P3E_CPU0_PE2_SS_RXN<11>")
	)
	(segment
		(start 371.742462 -2.937002)
		(end 372.170198 -2.937002)
		(width 0.1143)
		(layer "F.Cu")
		(net "P3E_CPU0_PE2_SS_RXN<11>")
	)
	(segment
		(start 371.604032 -3.442716)
		(end 371.604032 -3.075432)
		(width 0.1143)
		(layer "F.Cu")
		(net "P3E_CPU0_PE2_SS_RXN<11>")
	)
	(segment
		(start 371.88521 -4.389882)
		(end 371.88521 -3.723894)
		(width 0.1143)
		(layer "F.Cu")
		(net "P3E_CPU0_PE2_SS_RXN<11>")
	)
	(via
		(at 372.170198 -2.937002)
		(size 0.508)
		(drill 0.254)
		(layers "F.Cu" "B.Cu")
		(net "P3E_CPU0_PE2_SS_RXN<11>")
	)
	(via
		(at 302.671226 -78.688438)
		(size 0.508)
		(drill 0.254)
		(layers "F.Cu" "B.Cu")
		(net "P3E_CPU0_PE2_SS_RXN<11>")
	)
	(segment
		(start 371.681248 -3.660648)
		(end 370.915438 -5.602224)
		(width 0.1143)
		(layer "In4.Cu")
		(net "P3E_CPU0_PE2_SS_RXN<11>")
	)
	(segment
		(start 308.29885 -77.58684)
		(end 307.173122 -78.339188)
		(width 0.1143)
		(layer "In4.Cu")
		(net "P3E_CPU0_PE2_SS_RXN<11>")
	)
	(segment
		(start 351.951036 -40.15105)
		(end 345.268804 -40.15105)
		(width 0.1143)
		(layer "In4.Cu")
		(net "P3E_CPU0_PE2_SS_RXN<11>")
	)
	(segment
		(start 314.293758 -65.441322)
		(end 310.245506 -75.214988)
		(width 0.1143)
		(layer "In4.Cu")
		(net "P3E_CPU0_PE2_SS_RXN<11>")
	)
	(segment
		(start 345.004136 -40.415718)
		(end 345.004136 -43.412664)
		(width 0.1143)
		(layer "In4.Cu")
		(net "P3E_CPU0_PE2_SS_RXN<11>")
	)
	(segment
		(start 352.290634 -39.998904)
		(end 351.951036 -40.15105)
		(width 0.1143)
		(layer "In4.Cu")
		(net "P3E_CPU0_PE2_SS_RXN<11>")
	)
	(segment
		(start 344.47226 -44.82719)
		(end 343.58453 -45.064934)
		(width 0.1143)
		(layer "In4.Cu")
		(net "P3E_CPU0_PE2_SS_RXN<11>")
	)
	(segment
		(start 314.096146 -54.905402)
		(end 314.308236 -55.746142)
		(width 0.1143)
		(layer "In4.Cu")
		(net "P3E_CPU0_PE2_SS_RXN<11>")
	)
	(segment
		(start 302.729138 -78.292452)
		(end 302.671226 -78.350364)
		(width 0.0889)
		(layer "In4.Cu")
		(net "P3E_CPU0_PE2_SS_RXN<11>")
	)
	(segment
		(start 315.027818 -50.812446)
		(end 314.101734 -52.87772)
		(width 0.1143)
		(layer "In4.Cu")
		(net "P3E_CPU0_PE2_SS_RXN<11>")
	)
	(segment
		(start 354.711 -36.958524)
		(end 352.290634 -39.998904)
		(width 0.1143)
		(layer "In4.Cu")
		(net "P3E_CPU0_PE2_SS_RXN<11>")
	)
	(segment
		(start 372.170198 -2.937002)
		(end 371.795548 -2.937002)
		(width 0.1143)
		(layer "In4.Cu")
		(net "P3E_CPU0_PE2_SS_RXN<11>")
	)
	(segment
		(start 343.58453 -45.064934)
		(end 341.489538 -44.638976)
		(width 0.1143)
		(layer "In4.Cu")
		(net "P3E_CPU0_PE2_SS_RXN<11>")
	)
	(segment
		(start 314.765944 -60.404502)
		(end 314.293758 -65.441322)
		(width 0.1143)
		(layer "In4.Cu")
		(net "P3E_CPU0_PE2_SS_RXN<11>")
	)
	(segment
		(start 369.002564 -10.450576)
		(end 366.6109 -12.267438)
		(width 0.1143)
		(layer "In4.Cu")
		(net "P3E_CPU0_PE2_SS_RXN<11>")
	)
	(segment
		(start 306.574698 -78.339188)
		(end 306.5526 -78.339188)
		(width 0.0889)
		(layer "In4.Cu")
		(net "P3E_CPU0_PE2_SS_RXN<11>")
	)
	(segment
		(start 306.5018 -78.288388)
		(end 304.37074 -78.288388)
		(width 0.0889)
		(layer "In4.Cu")
		(net "P3E_CPU0_PE2_SS_RXN<11>")
	)
	(segment
		(start 370.910358 -5.617464)
		(end 369.002818 -10.450576)
		(width 0.1143)
		(layer "In4.Cu")
		(net "P3E_CPU0_PE2_SS_RXN<11>")
	)
	(segment
		(start 314.308236 -55.746142)
		(end 314.146692 -56.385714)
		(width 0.1143)
		(layer "In4.Cu")
		(net "P3E_CPU0_PE2_SS_RXN<11>")
	)
	(segment
		(start 370.915438 -5.602224)
		(end 370.910358 -5.617464)
		(width 0.1143)
		(layer "In4.Cu")
		(net "P3E_CPU0_PE2_SS_RXN<11>")
	)
	(segment
		(start 371.795548 -2.937002)
		(end 371.681248 -3.051302)
		(width 0.1143)
		(layer "In4.Cu")
		(net "P3E_CPU0_PE2_SS_RXN<11>")
	)
	(segment
		(start 302.671226 -78.350364)
		(end 302.671226 -78.688438)
		(width 0.0889)
		(layer "In4.Cu")
		(net "P3E_CPU0_PE2_SS_RXN<11>")
	)
	(segment
		(start 314.146692 -56.385714)
		(end 314.765944 -60.404502)
		(width 0.1143)
		(layer "In4.Cu")
		(net "P3E_CPU0_PE2_SS_RXN<11>")
	)
	(segment
		(start 339.210904 -45.102272)
		(end 337.214464 -44.695364)
		(width 0.1143)
		(layer "In4.Cu")
		(net "P3E_CPU0_PE2_SS_RXN<11>")
	)
	(segment
		(start 344.824558 -44.29506)
		(end 344.47226 -44.82719)
		(width 0.1143)
		(layer "In4.Cu")
		(net "P3E_CPU0_PE2_SS_RXN<11>")
	)
	(segment
		(start 358.191054 -34.638996)
		(end 354.711 -36.958524)
		(width 0.1143)
		(layer "In4.Cu")
		(net "P3E_CPU0_PE2_SS_RXN<11>")
	)
	(segment
		(start 303.51857 -78.784196)
		(end 303.50714 -78.783688)
		(width 0.0889)
		(layer "In4.Cu")
		(net "P3E_CPU0_PE2_SS_RXN<11>")
	)
	(segment
		(start 337.214464 -44.695364)
		(end 325.02602 -48.552608)
		(width 0.1143)
		(layer "In4.Cu")
		(net "P3E_CPU0_PE2_SS_RXN<11>")
	)
	(segment
		(start 307.173122 -78.339188)
		(end 306.574698 -78.339188)
		(width 0.1143)
		(layer "In4.Cu")
		(net "P3E_CPU0_PE2_SS_RXN<11>")
	)
	(segment
		(start 317.94323 -48.458882)
		(end 315.027818 -50.812446)
		(width 0.1143)
		(layer "In4.Cu")
		(net "P3E_CPU0_PE2_SS_RXN<11>")
	)
	(segment
		(start 345.268804 -40.15105)
		(end 345.004136 -40.415718)
		(width 0.1143)
		(layer "In4.Cu")
		(net "P3E_CPU0_PE2_SS_RXN<11>")
	)
	(segment
		(start 366.6109 -12.267438)
		(end 363.542326 -26.611326)
		(width 0.1143)
		(layer "In4.Cu")
		(net "P3E_CPU0_PE2_SS_RXN<11>")
	)
	(segment
		(start 363.542326 -26.611326)
		(end 358.191054 -34.638996)
		(width 0.1143)
		(layer "In4.Cu")
		(net "P3E_CPU0_PE2_SS_RXN<11>")
	)
	(segment
		(start 303.552352 -78.783688)
		(end 303.541176 -78.784196)
		(width 0.0889)
		(layer "In4.Cu")
		(net "P3E_CPU0_PE2_SS_RXN<11>")
	)
	(segment
		(start 369.002818 -10.450576)
		(end 369.002564 -10.450576)
		(width 0.1143)
		(layer "In4.Cu")
		(net "P3E_CPU0_PE2_SS_RXN<11>")
	)
	(segment
		(start 325.02602 -48.552608)
		(end 320.09207 -48.047402)
		(width 0.1143)
		(layer "In4.Cu")
		(net "P3E_CPU0_PE2_SS_RXN<11>")
	)
	(segment
		(start 345.004136 -43.412664)
		(end 344.824558 -44.29506)
		(width 0.1143)
		(layer "In4.Cu")
		(net "P3E_CPU0_PE2_SS_RXN<11>")
	)
	(segment
		(start 306.5526 -78.339188)
		(end 306.5018 -78.288388)
		(width 0.0889)
		(layer "In4.Cu")
		(net "P3E_CPU0_PE2_SS_RXN<11>")
	)
	(segment
		(start 371.681248 -3.051302)
		(end 371.681248 -3.660648)
		(width 0.1143)
		(layer "In4.Cu")
		(net "P3E_CPU0_PE2_SS_RXN<11>")
	)
	(segment
		(start 314.101734 -52.87772)
		(end 314.289948 -53.932328)
		(width 0.1143)
		(layer "In4.Cu")
		(net "P3E_CPU0_PE2_SS_RXN<11>")
	)
	(segment
		(start 341.489538 -44.638976)
		(end 339.210904 -45.102272)
		(width 0.1143)
		(layer "In4.Cu")
		(net "P3E_CPU0_PE2_SS_RXN<11>")
	)
	(segment
		(start 320.09207 -48.047402)
		(end 317.94323 -48.458882)
		(width 0.1143)
		(layer "In4.Cu")
		(net "P3E_CPU0_PE2_SS_RXN<11>")
	)
	(segment
		(start 310.245506 -75.214988)
		(end 308.29885 -77.58684)
		(width 0.1143)
		(layer "In4.Cu")
		(net "P3E_CPU0_PE2_SS_RXN<11>")
	)
	(segment
		(start 314.289948 -53.932328)
		(end 314.096146 -54.905402)
		(width 0.1143)
		(layer "In4.Cu")
		(net "P3E_CPU0_PE2_SS_RXN<11>")
	)
	(arc
		(start 303.017936 -78.48854)
		(mid 302.896045 -78.357344)
		(end 302.729138 -78.292452)
		(width 0.0889)
		(layer "In4.Cu")
		(net "P3E_CPU0_PE2_SS_RXN<11>")
	)
	(arc
		(start 303.50714 -78.783688)
		(mid 303.224517 -78.699155)
		(end 303.017936 -78.48854)
		(width 0.0889)
		(layer "In4.Cu")
		(net "P3E_CPU0_PE2_SS_RXN<11>")
	)
	(arc
		(start 303.541176 -78.784196)
		(mid 303.529873 -78.784419)
		(end 303.51857 -78.784196)
		(width 0.0889)
		(layer "In4.Cu")
		(net "P3E_CPU0_PE2_SS_RXN<11>")
	)
	(arc
		(start 304.041556 -78.488286)
		(mid 303.835048 -78.699063)
		(end 303.552352 -78.783688)
		(width 0.0889)
		(layer "In4.Cu")
		(net "P3E_CPU0_PE2_SS_RXN<11>")
	)
	(arc
		(start 304.37074 -78.288388)
		(mid 304.180498 -78.346123)
		(end 304.041556 -78.488286)
		(width 0.0889)
		(layer "In4.Cu")
		(net "P3E_CPU0_PE2_SS_RXN<11>")
	)
	(segment
		(start 373.980202 -3.457448)
		(end 373.980202 -1.533906)
		(width 0.1143)
		(layer "F.Cu")
		(net "P3E_CPU0_PE2_SS_RXN<10>")
	)
	(segment
		(start 374.094502 -1.419606)
		(end 374.494552 -1.419606)
		(width 0.1143)
		(layer "F.Cu")
		(net "P3E_CPU0_PE2_SS_RXN<10>")
	)
	(segment
		(start 374.285002 -3.762248)
		(end 373.980202 -3.457448)
		(width 0.1143)
		(layer "F.Cu")
		(net "P3E_CPU0_PE2_SS_RXN<10>")
	)
	(segment
		(start 302.099726 -79.678784)
		(end 302.671226 -79.678784)
		(width 0.1143)
		(layer "F.Cu")
		(net "P3E_CPU0_PE2_SS_RXN<10>")
	)
	(segment
		(start 373.980202 -1.533906)
		(end 374.094502 -1.419606)
		(width 0.1143)
		(layer "F.Cu")
		(net "P3E_CPU0_PE2_SS_RXN<10>")
	)
	(segment
		(start 374.285002 -4.389882)
		(end 374.285002 -3.762248)
		(width 0.1143)
		(layer "F.Cu")
		(net "P3E_CPU0_PE2_SS_RXN<10>")
	)
	(via
		(at 302.671226 -79.678784)
		(size 0.508)
		(drill 0.254)
		(layers "F.Cu" "B.Cu")
		(net "P3E_CPU0_PE2_SS_RXN<10>")
	)
	(via
		(at 374.494552 -1.419606)
		(size 0.508)
		(drill 0.254)
		(layers "F.Cu" "B.Cu")
		(net "P3E_CPU0_PE2_SS_RXN<10>")
	)
	(segment
		(start 346.565474 -41.3639)
		(end 346.277184 -41.65219)
		(width 0.1143)
		(layer "In4.Cu")
		(net "P3E_CPU0_PE2_SS_RXN<10>")
	)
	(segment
		(start 346.277184 -43.36034)
		(end 346.062046 -44.417996)
		(width 0.1143)
		(layer "In4.Cu")
		(net "P3E_CPU0_PE2_SS_RXN<10>")
	)
	(segment
		(start 307.076602 -79.205328)
		(end 307.054504 -79.205328)
		(width 0.0889)
		(layer "In4.Cu")
		(net "P3E_CPU0_PE2_SS_RXN<10>")
	)
	(segment
		(start 354.29063 -38.720776)
		(end 353.8728 -40.81018)
		(width 0.1143)
		(layer "In4.Cu")
		(net "P3E_CPU0_PE2_SS_RXN<10>")
	)
	(segment
		(start 306.742084 -79.154528)
		(end 306.560982 -79.278734)
		(width 0.0889)
		(layer "In4.Cu")
		(net "P3E_CPU0_PE2_SS_RXN<10>")
	)
	(segment
		(start 307.054504 -79.205328)
		(end 307.003704 -79.154528)
		(width 0.0889)
		(layer "In4.Cu")
		(net "P3E_CPU0_PE2_SS_RXN<10>")
	)
	(segment
		(start 306.560982 -79.278734)
		(end 304.373788 -79.278734)
		(width 0.0889)
		(layer "In4.Cu")
		(net "P3E_CPU0_PE2_SS_RXN<10>")
	)
	(segment
		(start 343.679526 -45.796708)
		(end 341.427054 -45.338492)
		(width 0.1143)
		(layer "In4.Cu")
		(net "P3E_CPU0_PE2_SS_RXN<10>")
	)
	(segment
		(start 370.624608 -8.176514)
		(end 369.592352 -10.825988)
		(width 0.1143)
		(layer "In4.Cu")
		(net "P3E_CPU0_PE2_SS_RXN<10>")
	)
	(segment
		(start 346.062046 -44.417996)
		(end 345.466416 -45.317664)
		(width 0.1143)
		(layer "In4.Cu")
		(net "P3E_CPU0_PE2_SS_RXN<10>")
	)
	(segment
		(start 374.113044 -1.419606)
		(end 374.005602 -1.527048)
		(width 0.1143)
		(layer "In4.Cu")
		(net "P3E_CPU0_PE2_SS_RXN<10>")
	)
	(segment
		(start 302.964342 -79.509874)
		(end 302.671226 -79.678784)
		(width 0.0889)
		(layer "In4.Cu")
		(net "P3E_CPU0_PE2_SS_RXN<10>")
	)
	(segment
		(start 374.005602 -4.79552)
		(end 370.624608 -8.176514)
		(width 0.1143)
		(layer "In4.Cu")
		(net "P3E_CPU0_PE2_SS_RXN<10>")
	)
	(segment
		(start 307.781198 -78.93558)
		(end 307.377084 -79.205328)
		(width 0.1143)
		(layer "In4.Cu")
		(net "P3E_CPU0_PE2_SS_RXN<10>")
	)
	(segment
		(start 309.043832 -77.790802)
		(end 307.781198 -78.93558)
		(width 0.1143)
		(layer "In4.Cu")
		(net "P3E_CPU0_PE2_SS_RXN<10>")
	)
	(segment
		(start 341.427054 -45.338492)
		(end 339.259672 -45.779436)
		(width 0.1143)
		(layer "In4.Cu")
		(net "P3E_CPU0_PE2_SS_RXN<10>")
	)
	(segment
		(start 353.8728 -40.81018)
		(end 353.873054 -40.81018)
		(width 0.1143)
		(layer "In4.Cu")
		(net "P3E_CPU0_PE2_SS_RXN<10>")
	)
	(segment
		(start 353.873054 -40.81018)
		(end 353.861624 -40.86733)
		(width 0.1143)
		(layer "In4.Cu")
		(net "P3E_CPU0_PE2_SS_RXN<10>")
	)
	(segment
		(start 345.466416 -45.317664)
		(end 343.679526 -45.796708)
		(width 0.1143)
		(layer "In4.Cu")
		(net "P3E_CPU0_PE2_SS_RXN<10>")
	)
	(segment
		(start 353.722178 -41.075864)
		(end 353.265994 -41.3639)
		(width 0.1143)
		(layer "In4.Cu")
		(net "P3E_CPU0_PE2_SS_RXN<10>")
	)
	(segment
		(start 364.184946 -26.803096)
		(end 358.620568 -35.150044)
		(width 0.1143)
		(layer "In4.Cu")
		(net "P3E_CPU0_PE2_SS_RXN<10>")
	)
	(segment
		(start 307.003704 -79.154528)
		(end 306.742084 -79.154528)
		(width 0.0889)
		(layer "In4.Cu")
		(net "P3E_CPU0_PE2_SS_RXN<10>")
	)
	(segment
		(start 353.861624 -40.86733)
		(end 353.756976 -41.023794)
		(width 0.1143)
		(layer "In4.Cu")
		(net "P3E_CPU0_PE2_SS_RXN<10>")
	)
	(segment
		(start 355.445822 -37.268912)
		(end 354.29063 -38.720776)
		(width 0.1143)
		(layer "In4.Cu")
		(net "P3E_CPU0_PE2_SS_RXN<10>")
	)
	(segment
		(start 303.05375 -79.534004)
		(end 302.964342 -79.509874)
		(width 0.0889)
		(layer "In4.Cu")
		(net "P3E_CPU0_PE2_SS_RXN<10>")
	)
	(segment
		(start 316.21603 -62.476888)
		(end 310.717184 -75.751436)
		(width 0.1143)
		(layer "In4.Cu")
		(net "P3E_CPU0_PE2_SS_RXN<10>")
	)
	(segment
		(start 322.815966 -52.88153)
		(end 316.21603 -62.476888)
		(width 0.1143)
		(layer "In4.Cu")
		(net "P3E_CPU0_PE2_SS_RXN<10>")
	)
	(segment
		(start 353.756976 -41.024048)
		(end 353.722178 -41.075864)
		(width 0.1143)
		(layer "In4.Cu")
		(net "P3E_CPU0_PE2_SS_RXN<10>")
	)
	(segment
		(start 367.207038 -12.677902)
		(end 364.184946 -26.803096)
		(width 0.1143)
		(layer "In4.Cu")
		(net "P3E_CPU0_PE2_SS_RXN<10>")
	)
	(segment
		(start 353.265994 -41.3639)
		(end 346.565474 -41.3639)
		(width 0.1143)
		(layer "In4.Cu")
		(net "P3E_CPU0_PE2_SS_RXN<10>")
	)
	(segment
		(start 353.756976 -41.023794)
		(end 353.756976 -41.024048)
		(width 0.1143)
		(layer "In4.Cu")
		(net "P3E_CPU0_PE2_SS_RXN<10>")
	)
	(segment
		(start 374.494552 -1.419606)
		(end 374.113044 -1.419606)
		(width 0.1143)
		(layer "In4.Cu")
		(net "P3E_CPU0_PE2_SS_RXN<10>")
	)
	(segment
		(start 337.225386 -45.364908)
		(end 329.232768 -47.89297)
		(width 0.1143)
		(layer "In4.Cu")
		(net "P3E_CPU0_PE2_SS_RXN<10>")
	)
	(segment
		(start 374.005602 -1.527048)
		(end 374.005602 -4.79552)
		(width 0.1143)
		(layer "In4.Cu")
		(net "P3E_CPU0_PE2_SS_RXN<10>")
	)
	(segment
		(start 339.259672 -45.779436)
		(end 337.225386 -45.364908)
		(width 0.1143)
		(layer "In4.Cu")
		(net "P3E_CPU0_PE2_SS_RXN<10>")
	)
	(segment
		(start 323.711824 -52.516278)
		(end 322.815966 -52.88153)
		(width 0.1143)
		(layer "In4.Cu")
		(net "P3E_CPU0_PE2_SS_RXN<10>")
	)
	(segment
		(start 358.620568 -35.150044)
		(end 355.445822 -37.268912)
		(width 0.1143)
		(layer "In4.Cu")
		(net "P3E_CPU0_PE2_SS_RXN<10>")
	)
	(segment
		(start 325.011034 -50.625502)
		(end 323.711824 -52.516278)
		(width 0.1143)
		(layer "In4.Cu")
		(net "P3E_CPU0_PE2_SS_RXN<10>")
	)
	(segment
		(start 310.717184 -75.751436)
		(end 309.043832 -77.790802)
		(width 0.1143)
		(layer "In4.Cu")
		(net "P3E_CPU0_PE2_SS_RXN<10>")
	)
	(segment
		(start 329.232768 -47.89297)
		(end 325.011034 -50.625502)
		(width 0.1143)
		(layer "In4.Cu")
		(net "P3E_CPU0_PE2_SS_RXN<10>")
	)
	(segment
		(start 307.377084 -79.205328)
		(end 307.076602 -79.205328)
		(width 0.1143)
		(layer "In4.Cu")
		(net "P3E_CPU0_PE2_SS_RXN<10>")
	)
	(segment
		(start 369.592352 -10.825988)
		(end 367.207038 -12.677902)
		(width 0.1143)
		(layer "In4.Cu")
		(net "P3E_CPU0_PE2_SS_RXN<10>")
	)
	(segment
		(start 346.277184 -41.65219)
		(end 346.277184 -43.36034)
		(width 0.1143)
		(layer "In4.Cu")
		(net "P3E_CPU0_PE2_SS_RXN<10>")
	)
	(arc
		(start 304.041556 -79.478886)
		(mid 303.562607 -79.773638)
		(end 303.05375 -79.534004)
		(width 0.0889)
		(layer "In4.Cu")
		(net "P3E_CPU0_PE2_SS_RXN<10>")
	)
	(arc
		(start 304.373788 -79.278734)
		(mid 304.37201 -79.278857)
		(end 304.370232 -79.278988)
		(width 0.0889)
		(layer "In4.Cu")
		(net "P3E_CPU0_PE2_SS_RXN<10>")
	)
	(arc
		(start 304.370232 -79.278988)
		(mid 304.180303 -79.336858)
		(end 304.041556 -79.478886)
		(width 0.0889)
		(layer "In4.Cu")
		(net "P3E_CPU0_PE2_SS_RXN<10>")
	)
	(segment
		(start 409.793186 -3.478784)
		(end 409.793186 -2.19837)
		(width 0.1143)
		(layer "F.Cu")
		(net "P3E_CPU0_PE2_SS_RXN<0>")
	)
	(segment
		(start 409.653232 -1.49225)
		(end 409.767532 -1.37795)
		(width 0.1143)
		(layer "F.Cu")
		(net "P3E_CPU0_PE2_SS_RXN<0>")
	)
	(segment
		(start 409.653232 -2.058416)
		(end 409.653232 -1.49225)
		(width 0.1143)
		(layer "F.Cu")
		(net "P3E_CPU0_PE2_SS_RXN<0>")
	)
	(segment
		(start 300.382686 -88.594184)
		(end 300.954186 -88.594184)
		(width 0.1143)
		(layer "F.Cu")
		(net "P3E_CPU0_PE2_SS_RXN<0>")
	)
	(segment
		(start 409.767532 -1.37795)
		(end 410.167582 -1.37795)
		(width 0.1143)
		(layer "F.Cu")
		(net "P3E_CPU0_PE2_SS_RXN<0>")
	)
	(segment
		(start 410.072586 -4.386072)
		(end 410.072586 -3.758184)
		(width 0.1143)
		(layer "F.Cu")
		(net "P3E_CPU0_PE2_SS_RXN<0>")
	)
	(segment
		(start 410.072586 -3.758184)
		(end 409.793186 -3.478784)
		(width 0.1143)
		(layer "F.Cu")
		(net "P3E_CPU0_PE2_SS_RXN<0>")
	)
	(segment
		(start 409.793186 -2.19837)
		(end 409.653232 -2.058416)
		(width 0.1143)
		(layer "F.Cu")
		(net "P3E_CPU0_PE2_SS_RXN<0>")
	)
	(via
		(at 300.954186 -88.594184)
		(size 0.508)
		(drill 0.254)
		(layers "F.Cu" "B.Cu")
		(net "P3E_CPU0_PE2_SS_RXN<0>")
	)
	(via
		(at 410.167582 -1.37795)
		(size 0.508)
		(drill 0.254)
		(layers "F.Cu" "B.Cu")
		(net "P3E_CPU0_PE2_SS_RXN<0>")
	)
	(segment
		(start 310.480964 -86.36508)
		(end 311.126124 -85.317076)
		(width 0.1143)
		(layer "In4.Cu")
		(net "P3E_CPU0_PE2_SS_RXN<0>")
	)
	(segment
		(start 307.533294 -87.1855)
		(end 308.212998 -87.1855)
		(width 0.0889)
		(layer "In4.Cu")
		(net "P3E_CPU0_PE2_SS_RXN<0>")
	)
	(segment
		(start 379.058424 -13.626084)
		(end 381.454406 -12.340844)
		(width 0.1143)
		(layer "In4.Cu")
		(net "P3E_CPU0_PE2_SS_RXN<0>")
	)
	(segment
		(start 315.701426 -80.610964)
		(end 320.987674 -67.849242)
		(width 0.1143)
		(layer "In4.Cu")
		(net "P3E_CPU0_PE2_SS_RXN<0>")
	)
	(segment
		(start 300.954186 -88.594184)
		(end 301.205392 -88.449404)
		(width 0.0889)
		(layer "In4.Cu")
		(net "P3E_CPU0_PE2_SS_RXN<0>")
	)
	(segment
		(start 372.0338 -31.135066)
		(end 372.92407 -26.837894)
		(width 0.1143)
		(layer "In4.Cu")
		(net "P3E_CPU0_PE2_SS_RXN<0>")
	)
	(segment
		(start 303.017936 -89.384886)
		(end 303.030382 -89.40673)
		(width 0.0889)
		(layer "In4.Cu")
		(net "P3E_CPU0_PE2_SS_RXN<0>")
	)
	(segment
		(start 359.285794 -48.349916)
		(end 361.737402 -46.727872)
		(width 0.1143)
		(layer "In4.Cu")
		(net "P3E_CPU0_PE2_SS_RXN<0>")
	)
	(segment
		(start 370.101622 -32.478726)
		(end 370.101876 -32.478472)
		(width 0.1143)
		(layer "In4.Cu")
		(net "P3E_CPU0_PE2_SS_RXN<0>")
	)
	(segment
		(start 339.89518 -52.519072)
		(end 342.160606 -52.058062)
		(width 0.1143)
		(layer "In4.Cu")
		(net "P3E_CPU0_PE2_SS_RXN<0>")
	)
	(segment
		(start 409.637484 -1.626616)
		(end 409.88615 -1.37795)
		(width 0.1143)
		(layer "In4.Cu")
		(net "P3E_CPU0_PE2_SS_RXN<0>")
	)
	(segment
		(start 302.649636 -89.184734)
		(end 302.685704 -89.184734)
		(width 0.0889)
		(layer "In4.Cu")
		(net "P3E_CPU0_PE2_SS_RXN<0>")
	)
	(segment
		(start 306.029106 -88.689688)
		(end 307.214524 -87.504524)
		(width 0.0889)
		(layer "In4.Cu")
		(net "P3E_CPU0_PE2_SS_RXN<0>")
	)
	(segment
		(start 342.160606 -52.058062)
		(end 344.18524 -52.47005)
		(width 0.1143)
		(layer "In4.Cu")
		(net "P3E_CPU0_PE2_SS_RXN<0>")
	)
	(segment
		(start 313.879738 -82.830924)
		(end 315.701426 -80.610964)
		(width 0.1143)
		(layer "In4.Cu")
		(net "P3E_CPU0_PE2_SS_RXN<0>")
	)
	(segment
		(start 309.153306 -87.2363)
		(end 310.480964 -86.36508)
		(width 0.1143)
		(layer "In4.Cu")
		(net "P3E_CPU0_PE2_SS_RXN<0>")
	)
	(segment
		(start 373.60987 -26.460704)
		(end 373.610124 -26.460704)
		(width 0.1143)
		(layer "In4.Cu")
		(net "P3E_CPU0_PE2_SS_RXN<0>")
	)
	(segment
		(start 361.737402 -46.727872)
		(end 363.477556 -44.098718)
		(width 0.1143)
		(layer "In4.Cu")
		(net "P3E_CPU0_PE2_SS_RXN<0>")
	)
	(segment
		(start 311.126124 -85.317076)
		(end 313.879738 -82.830924)
		(width 0.1143)
		(layer "In4.Cu")
		(net "P3E_CPU0_PE2_SS_RXN<0>")
	)
	(segment
		(start 374.296432 -26.08326)
		(end 376.466862 -16.774668)
		(width 0.1143)
		(layer "In4.Cu")
		(net "P3E_CPU0_PE2_SS_RXN<0>")
	)
	(segment
		(start 363.477556 -44.098718)
		(end 364.584996 -38.562534)
		(width 0.1143)
		(layer "In4.Cu")
		(net "P3E_CPU0_PE2_SS_RXN<0>")
	)
	(segment
		(start 301.794926 -88.689688)
		(end 301.827692 -88.689688)
		(width 0.0889)
		(layer "In4.Cu")
		(net "P3E_CPU0_PE2_SS_RXN<0>")
	)
	(segment
		(start 308.263798 -87.2363)
		(end 308.285896 -87.2363)
		(width 0.0889)
		(layer "In4.Cu")
		(net "P3E_CPU0_PE2_SS_RXN<0>")
	)
	(segment
		(start 331.863192 -53.862986)
		(end 337.613244 -52.054506)
		(width 0.1143)
		(layer "In4.Cu")
		(net "P3E_CPU0_PE2_SS_RXN<0>")
	)
	(segment
		(start 369.807998 -32.91967)
		(end 370.101622 -32.478726)
		(width 0.1143)
		(layer "In4.Cu")
		(net "P3E_CPU0_PE2_SS_RXN<0>")
	)
	(segment
		(start 364.584996 -38.562534)
		(end 367.166906 -34.680906)
		(width 0.1143)
		(layer "In4.Cu")
		(net "P3E_CPU0_PE2_SS_RXN<0>")
	)
	(segment
		(start 370.101876 -32.478472)
		(end 370.116608 -32.456628)
		(width 0.1143)
		(layer "In4.Cu")
		(net "P3E_CPU0_PE2_SS_RXN<0>")
	)
	(segment
		(start 308.212998 -87.1855)
		(end 308.263798 -87.2363)
		(width 0.0889)
		(layer "In4.Cu")
		(net "P3E_CPU0_PE2_SS_RXN<0>")
	)
	(segment
		(start 376.466862 -16.774668)
		(end 379.058424 -13.626084)
		(width 0.1143)
		(layer "In4.Cu")
		(net "P3E_CPU0_PE2_SS_RXN<0>")
	)
	(segment
		(start 400.54022 -9.96442)
		(end 403.376384 -5.709666)
		(width 0.1143)
		(layer "In4.Cu")
		(net "P3E_CPU0_PE2_SS_RXN<0>")
	)
	(segment
		(start 409.201112 -3.920236)
		(end 409.637484 -3.48361)
		(width 0.1143)
		(layer "In4.Cu")
		(net "P3E_CPU0_PE2_SS_RXN<0>")
	)
	(segment
		(start 372.92407 -26.837894)
		(end 373.60987 -26.460704)
		(width 0.1143)
		(layer "In4.Cu")
		(net "P3E_CPU0_PE2_SS_RXN<0>")
	)
	(segment
		(start 373.610124 -26.460704)
		(end 374.296432 -26.08326)
		(width 0.1143)
		(layer "In4.Cu")
		(net "P3E_CPU0_PE2_SS_RXN<0>")
	)
	(segment
		(start 329.56754 -55.37454)
		(end 331.863192 -53.862986)
		(width 0.1143)
		(layer "In4.Cu")
		(net "P3E_CPU0_PE2_SS_RXN<0>")
	)
	(segment
		(start 337.613244 -52.054506)
		(end 339.89518 -52.519072)
		(width 0.1143)
		(layer "In4.Cu")
		(net "P3E_CPU0_PE2_SS_RXN<0>")
	)
	(segment
		(start 367.166906 -34.680906)
		(end 369.807998 -32.91967)
		(width 0.1143)
		(layer "In4.Cu")
		(net "P3E_CPU0_PE2_SS_RXN<0>")
	)
	(segment
		(start 305.2318 -88.689688)
		(end 306.029106 -88.689688)
		(width 0.0889)
		(layer "In4.Cu")
		(net "P3E_CPU0_PE2_SS_RXN<0>")
	)
	(segment
		(start 320.987674 -67.849242)
		(end 329.56754 -55.37454)
		(width 0.1143)
		(layer "In4.Cu")
		(net "P3E_CPU0_PE2_SS_RXN<0>")
	)
	(segment
		(start 304.37709 -89.184734)
		(end 304.409856 -89.184734)
		(width 0.0889)
		(layer "In4.Cu")
		(net "P3E_CPU0_PE2_SS_RXN<0>")
	)
	(segment
		(start 308.285896 -87.2363)
		(end 309.153306 -87.2363)
		(width 0.1143)
		(layer "In4.Cu")
		(net "P3E_CPU0_PE2_SS_RXN<0>")
	)
	(segment
		(start 303.514506 -89.680288)
		(end 303.515014 -89.680288)
		(width 0.0889)
		(layer "In4.Cu")
		(net "P3E_CPU0_PE2_SS_RXN<0>")
	)
	(segment
		(start 389.711946 -12.921742)
		(end 398.843246 -11.095482)
		(width 0.1143)
		(layer "In4.Cu")
		(net "P3E_CPU0_PE2_SS_RXN<0>")
	)
	(segment
		(start 307.214524 -87.504524)
		(end 307.533294 -87.1855)
		(width 0.0889)
		(layer "In4.Cu")
		(net "P3E_CPU0_PE2_SS_RXN<0>")
	)
	(segment
		(start 301.205392 -88.449404)
		(end 301.33671 -88.449404)
		(width 0.0889)
		(layer "In4.Cu")
		(net "P3E_CPU0_PE2_SS_RXN<0>")
	)
	(segment
		(start 409.88615 -1.37795)
		(end 410.167582 -1.37795)
		(width 0.1143)
		(layer "In4.Cu")
		(net "P3E_CPU0_PE2_SS_RXN<0>")
	)
	(segment
		(start 344.18524 -52.47005)
		(end 359.285794 -48.349916)
		(width 0.1143)
		(layer "In4.Cu")
		(net "P3E_CPU0_PE2_SS_RXN<0>")
	)
	(segment
		(start 409.637484 -3.48361)
		(end 409.637484 -1.626616)
		(width 0.1143)
		(layer "In4.Cu")
		(net "P3E_CPU0_PE2_SS_RXN<0>")
	)
	(segment
		(start 403.376384 -5.709666)
		(end 409.201112 -3.920236)
		(width 0.1143)
		(layer "In4.Cu")
		(net "P3E_CPU0_PE2_SS_RXN<0>")
	)
	(segment
		(start 384.17119 -11.763756)
		(end 389.711946 -12.921742)
		(width 0.1143)
		(layer "In4.Cu")
		(net "P3E_CPU0_PE2_SS_RXN<0>")
	)
	(segment
		(start 398.843246 -11.095482)
		(end 400.54022 -9.96442)
		(width 0.1143)
		(layer "In4.Cu")
		(net "P3E_CPU0_PE2_SS_RXN<0>")
	)
	(segment
		(start 381.454406 -12.340844)
		(end 384.17119 -11.763756)
		(width 0.1143)
		(layer "In4.Cu")
		(net "P3E_CPU0_PE2_SS_RXN<0>")
	)
	(segment
		(start 370.116608 -32.456628)
		(end 372.0338 -31.135066)
		(width 0.1143)
		(layer "In4.Cu")
		(net "P3E_CPU0_PE2_SS_RXN<0>")
	)
	(segment
		(start 303.030382 -89.40673)
		(end 303.032668 -89.409016)
		(width 0.0889)
		(layer "In4.Cu")
		(net "P3E_CPU0_PE2_SS_RXN<0>")
	)
	(arc
		(start 301.827692 -88.689688)
		(mid 302.019334 -88.746854)
		(end 302.159416 -88.889586)
		(width 0.0889)
		(layer "In4.Cu")
		(net "P3E_CPU0_PE2_SS_RXN<0>")
	)
	(arc
		(start 302.159416 -88.889586)
		(mid 302.36642 -89.10045)
		(end 302.649636 -89.184734)
		(width 0.0889)
		(layer "In4.Cu")
		(net "P3E_CPU0_PE2_SS_RXN<0>")
	)
	(arc
		(start 304.041556 -89.384886)
		(mid 304.183239 -89.241082)
		(end 304.37709 -89.184734)
		(width 0.0889)
		(layer "In4.Cu")
		(net "P3E_CPU0_PE2_SS_RXN<0>")
	)
	(arc
		(start 303.032668 -89.409016)
		(mid 303.239834 -89.604575)
		(end 303.514506 -89.680288)
		(width 0.0889)
		(layer "In4.Cu")
		(net "P3E_CPU0_PE2_SS_RXN<0>")
	)
	(arc
		(start 304.409856 -89.184734)
		(mid 304.693073 -89.100453)
		(end 304.900076 -88.889586)
		(width 0.0889)
		(layer "In4.Cu")
		(net "P3E_CPU0_PE2_SS_RXN<0>")
	)
	(arc
		(start 304.900076 -88.889586)
		(mid 305.040155 -88.74685)
		(end 305.2318 -88.689688)
		(width 0.0889)
		(layer "In4.Cu")
		(net "P3E_CPU0_PE2_SS_RXN<0>")
	)
	(arc
		(start 303.515014 -89.680288)
		(mid 303.531143 -89.680512)
		(end 303.547272 -89.680288)
		(width 0.0889)
		(layer "In4.Cu")
		(net "P3E_CPU0_PE2_SS_RXN<0>")
	)
	(arc
		(start 302.685704 -89.184734)
		(mid 302.877721 -89.241842)
		(end 303.017936 -89.384886)
		(width 0.0889)
		(layer "In4.Cu")
		(net "P3E_CPU0_PE2_SS_RXN<0>")
	)
	(arc
		(start 301.33671 -88.449404)
		(mid 301.53812 -88.622357)
		(end 301.794926 -88.689688)
		(width 0.0889)
		(layer "In4.Cu")
		(net "P3E_CPU0_PE2_SS_RXN<0>")
	)
	(arc
		(start 303.547272 -89.680288)
		(mid 303.832837 -89.596879)
		(end 304.041556 -89.384886)
		(width 0.0889)
		(layer "In4.Cu")
		(net "P3E_CPU0_PE2_SS_RXN<0>")
	)
	(segment
		(start 393.984988 -93.237304)
		(end 393.805918 -93.058234)
		(width 0.0889)
		(layer "F.Cu")
		(net "SMB_VR_STBY_LVC3_SDA_R1")
	)
	(segment
		(start 393.805918 -93.058234)
		(end 393.805918 -92.102178)
		(width 0.0889)
		(layer "F.Cu")
		(net "SMB_VR_STBY_LVC3_SDA_R1")
	)
	(segment
		(start 393.984988 -93.544898)
		(end 393.984988 -93.237304)
		(width 0.0889)
		(layer "F.Cu")
		(net "SMB_VR_STBY_LVC3_SDA_R1")
	)
	(via
		(at 393.805918 -92.102178)
		(size 0.508)
		(drill 0.254)
		(layers "F.Cu" "B.Cu")
		(net "SMB_VR_STBY_LVC3_SDA_R1")
	)
	(via
		(at 397.557752 -89.405714)
		(size 0.6604)
		(drill 0.3302)
		(layers "F.Cu" "B.Cu")
		(net "SMB_VR_STBY_LVC3_SDA_R1")
	)
	(segment
		(start 398.868392 -88.3412)
		(end 399.2372 -88.3412)
		(width 0.10795)
		(layer "B.Cu")
		(net "SMB_VR_STBY_LVC3_SDA_R1")
	)
	(segment
		(start 396.79626 -89.91854)
		(end 394.612622 -92.102178)
		(width 0.10795)
		(layer "B.Cu")
		(net "SMB_VR_STBY_LVC3_SDA_R1")
	)
	(segment
		(start 398.4244 -88.543384)
		(end 398.4244 -88.2777)
		(width 0.10795)
		(layer "B.Cu")
		(net "SMB_VR_STBY_LVC3_SDA_R1")
	)
	(segment
		(start 397.557752 -89.405714)
		(end 397.044926 -89.91854)
		(width 0.10795)
		(layer "B.Cu")
		(net "SMB_VR_STBY_LVC3_SDA_R1")
	)
	(segment
		(start 398.4244 -88.2777)
		(end 398.804892 -88.2777)
		(width 0.10795)
		(layer "B.Cu")
		(net "SMB_VR_STBY_LVC3_SDA_R1")
	)
	(segment
		(start 397.557752 -89.405714)
		(end 397.56207 -89.405714)
		(width 0.10795)
		(layer "B.Cu")
		(net "SMB_VR_STBY_LVC3_SDA_R1")
	)
	(segment
		(start 394.612622 -92.102178)
		(end 393.805918 -92.102178)
		(width 0.10795)
		(layer "B.Cu")
		(net "SMB_VR_STBY_LVC3_SDA_R1")
	)
	(segment
		(start 398.804892 -88.2777)
		(end 398.868392 -88.3412)
		(width 0.10795)
		(layer "B.Cu")
		(net "SMB_VR_STBY_LVC3_SDA_R1")
	)
	(segment
		(start 397.044926 -89.91854)
		(end 396.79626 -89.91854)
		(width 0.10795)
		(layer "B.Cu")
		(net "SMB_VR_STBY_LVC3_SDA_R1")
	)
	(segment
		(start 397.56207 -89.405714)
		(end 398.4244 -88.543384)
		(width 0.10795)
		(layer "B.Cu")
		(net "SMB_VR_STBY_LVC3_SDA_R1")
	)
	(segment
		(start 392.485118 -94.790006)
		(end 392.485118 -94.400116)
		(width 0.0889)
		(layer "F.Cu")
		(net "SMB_VR_STBY_LVC3_SCL_R1")
	)
	(segment
		(start 392.270742 -93.734128)
		(end 392.270742 -92.576142)
		(width 0.0889)
		(layer "F.Cu")
		(net "SMB_VR_STBY_LVC3_SCL_R1")
	)
	(segment
		(start 392.270742 -92.576142)
		(end 391.9982 -92.3036)
		(width 0.0889)
		(layer "F.Cu")
		(net "SMB_VR_STBY_LVC3_SCL_R1")
	)
	(segment
		(start 392.173968 -93.830902)
		(end 392.270742 -93.734128)
		(width 0.0889)
		(layer "F.Cu")
		(net "SMB_VR_STBY_LVC3_SCL_R1")
	)
	(segment
		(start 392.173968 -94.088966)
		(end 392.173968 -93.830902)
		(width 0.0889)
		(layer "F.Cu")
		(net "SMB_VR_STBY_LVC3_SCL_R1")
	)
	(segment
		(start 392.485118 -94.400116)
		(end 392.173968 -94.088966)
		(width 0.0889)
		(layer "F.Cu")
		(net "SMB_VR_STBY_LVC3_SCL_R1")
	)
	(via
		(at 392.7729 -92.3036)
		(size 0.6604)
		(drill 0.3302)
		(layers "F.Cu" "B.Cu")
		(net "SMB_VR_STBY_LVC3_SCL_R1")
	)
	(via
		(at 391.9982 -92.3036)
		(size 0.508)
		(drill 0.254)
		(layers "F.Cu" "B.Cu")
		(net "SMB_VR_STBY_LVC3_SCL_R1")
	)
	(segment
		(start 397.637 -88.519)
		(end 394.4874 -91.6686)
		(width 0.10795)
		(layer "B.Cu")
		(net "SMB_VR_STBY_LVC3_SCL_R1")
	)
	(segment
		(start 392.7729 -92.3036)
		(end 391.9982 -92.3036)
		(width 0.10795)
		(layer "B.Cu")
		(net "SMB_VR_STBY_LVC3_SCL_R1")
	)
	(segment
		(start 392.9634 -92.3036)
		(end 392.7729 -92.3036)
		(width 0.10795)
		(layer "B.Cu")
		(net "SMB_VR_STBY_LVC3_SCL_R1")
	)
	(segment
		(start 394.4874 -91.6686)
		(end 393.5984 -91.6686)
		(width 0.10795)
		(layer "B.Cu")
		(net "SMB_VR_STBY_LVC3_SCL_R1")
	)
	(segment
		(start 397.637 -88.2142)
		(end 397.637 -88.519)
		(width 0.10795)
		(layer "B.Cu")
		(net "SMB_VR_STBY_LVC3_SCL_R1")
	)
	(segment
		(start 396.875 -88.2142)
		(end 397.637 -88.2142)
		(width 0.10795)
		(layer "B.Cu")
		(net "SMB_VR_STBY_LVC3_SCL_R1")
	)
	(segment
		(start 393.5984 -91.6686)
		(end 392.9634 -92.3036)
		(width 0.10795)
		(layer "B.Cu")
		(net "SMB_VR_STBY_LVC3_SCL_R1")
	)
	(segment
		(start 394.589 -88.2015)
		(end 394.589 -88.302338)
		(width 0.10795)
		(layer "F.Cu")
		(net "SMB_LAN_STBY_LVC3_SDA_R1")
	)
	(segment
		(start 394.3096 -88.581738)
		(end 394.3096 -89.027)
		(width 0.10795)
		(layer "F.Cu")
		(net "SMB_LAN_STBY_LVC3_SDA_R1")
	)
	(segment
		(start 394.3096 -89.027)
		(end 394.3096 -89.7636)
		(width 0.10795)
		(layer "F.Cu")
		(net "SMB_LAN_STBY_LVC3_SDA_R1")
	)
	(segment
		(start 394.804392 -93.815916)
		(end 394.804392 -94.108524)
		(width 0.0889)
		(layer "F.Cu")
		(net "SMB_LAN_STBY_LVC3_SDA_R1")
	)
	(segment
		(start 394.3096 -89.7636)
		(end 394.733526 -90.187526)
		(width 0.10795)
		(layer "F.Cu")
		(net "SMB_LAN_STBY_LVC3_SDA_R1")
	)
	(segment
		(start 394.804392 -94.108524)
		(end 394.485114 -94.427802)
		(width 0.0889)
		(layer "F.Cu")
		(net "SMB_LAN_STBY_LVC3_SDA_R1")
	)
	(segment
		(start 394.72108 -91.236546)
		(end 394.72108 -93.325442)
		(width 0.0889)
		(layer "F.Cu")
		(net "SMB_LAN_STBY_LVC3_SDA_R1")
	)
	(segment
		(start 394.68933 -93.357192)
		(end 394.68933 -93.700854)
		(width 0.0889)
		(layer "F.Cu")
		(net "SMB_LAN_STBY_LVC3_SDA_R1")
	)
	(segment
		(start 394.589 -88.302338)
		(end 394.3096 -88.581738)
		(width 0.10795)
		(layer "F.Cu")
		(net "SMB_LAN_STBY_LVC3_SDA_R1")
	)
	(segment
		(start 394.72108 -93.325442)
		(end 394.68933 -93.357192)
		(width 0.0889)
		(layer "F.Cu")
		(net "SMB_LAN_STBY_LVC3_SDA_R1")
	)
	(segment
		(start 394.485114 -94.427802)
		(end 394.485114 -94.790006)
		(width 0.0889)
		(layer "F.Cu")
		(net "SMB_LAN_STBY_LVC3_SDA_R1")
	)
	(segment
		(start 394.68933 -93.700854)
		(end 394.804392 -93.815916)
		(width 0.0889)
		(layer "F.Cu")
		(net "SMB_LAN_STBY_LVC3_SDA_R1")
	)
	(segment
		(start 394.733526 -91.2241)
		(end 394.72108 -91.236546)
		(width 0.0889)
		(layer "F.Cu")
		(net "SMB_LAN_STBY_LVC3_SDA_R1")
	)
	(segment
		(start 394.733526 -90.187526)
		(end 394.733526 -91.2241)
		(width 0.0889)
		(layer "F.Cu")
		(net "SMB_LAN_STBY_LVC3_SDA_R1")
	)
	(via
		(at 394.3096 -89.027)
		(size 0.508)
		(drill 0.254)
		(layers "F.Cu" "B.Cu")
		(net "SMB_LAN_STBY_LVC3_SDA_R1")
	)
	(segment
		(start 395.605 -89.027)
		(end 395.605 -88.7476)
		(width 0.10795)
		(layer "F.Cu")
		(net "SMB_LAN_STBY_LVC3_SCL_R1")
	)
	(segment
		(start 395.605 -88.7476)
		(end 395.351 -88.4936)
		(width 0.10795)
		(layer "F.Cu")
		(net "SMB_LAN_STBY_LVC3_SCL_R1")
	)
	(segment
		(start 395.116558 -90.206068)
		(end 394.934186 -90.38844)
		(width 0.0889)
		(layer "F.Cu")
		(net "SMB_LAN_STBY_LVC3_SCL_R1")
	)
	(segment
		(start 394.934186 -90.38844)
		(end 394.934186 -93.494098)
		(width 0.0889)
		(layer "F.Cu")
		(net "SMB_LAN_STBY_LVC3_SCL_R1")
	)
	(segment
		(start 394.934186 -93.494098)
		(end 394.984986 -93.544898)
		(width 0.0889)
		(layer "F.Cu")
		(net "SMB_LAN_STBY_LVC3_SCL_R1")
	)
	(segment
		(start 395.116558 -89.642696)
		(end 395.116558 -90.206068)
		(width 0.10795)
		(layer "F.Cu")
		(net "SMB_LAN_STBY_LVC3_SCL_R1")
	)
	(segment
		(start 395.351 -88.4936)
		(end 395.351 -88.2015)
		(width 0.10795)
		(layer "F.Cu")
		(net "SMB_LAN_STBY_LVC3_SCL_R1")
	)
	(segment
		(start 395.605 -89.154254)
		(end 395.116558 -89.642696)
		(width 0.10795)
		(layer "F.Cu")
		(net "SMB_LAN_STBY_LVC3_SCL_R1")
	)
	(segment
		(start 395.605 -89.027)
		(end 395.605 -89.154254)
		(width 0.10795)
		(layer "F.Cu")
		(net "SMB_LAN_STBY_LVC3_SCL_R1")
	)
	(via
		(at 395.605 -89.027)
		(size 0.508)
		(drill 0.254)
		(layers "F.Cu" "B.Cu")
		(net "SMB_LAN_STBY_LVC3_SCL_R1")
	)
	(segment
		(start 417.490148 -41.73474)
		(end 417.090352 -42.13479)
		(width 0.10795)
		(layer "F.Cu")
		(net "SMB_SLOTX24_STBY_LVC3_SDA_R")
	)
	(via
		(at 417.090352 -42.13479)
		(size 0.4572)
		(drill 0.2032)
		(layers "F.Cu" "B.Cu")
		(net "SMB_SLOTX24_STBY_LVC3_SDA_R")
	)
	(via
		(at 417.93033 -42.974768)
		(size 0.6604)
		(drill 0.3302)
		(layers "F.Cu" "B.Cu")
		(net "SMB_SLOTX24_STBY_LVC3_SDA_R")
	)
	(segment
		(start 418.496496 -46.779942)
		(end 418.2364 -46.519846)
		(width 0.10795)
		(layer "B.Cu")
		(net "SMB_SLOTX24_STBY_LVC3_SDA_R")
	)
	(segment
		(start 418.2364 -46.519846)
		(end 418.2364 -43.280838)
		(width 0.10795)
		(layer "B.Cu")
		(net "SMB_SLOTX24_STBY_LVC3_SDA_R")
	)
	(segment
		(start 418.2364 -43.280838)
		(end 417.93033 -42.974768)
		(width 0.10795)
		(layer "B.Cu")
		(net "SMB_SLOTX24_STBY_LVC3_SDA_R")
	)
	(segment
		(start 417.93033 -42.974768)
		(end 417.090352 -42.13479)
		(width 0.10795)
		(layer "B.Cu")
		(net "SMB_SLOTX24_STBY_LVC3_SDA_R")
	)
	(segment
		(start 420.097204 -47.36592)
		(end 419.511226 -46.779942)
		(width 0.10795)
		(layer "B.Cu")
		(net "SMB_SLOTX24_STBY_LVC3_SDA_R")
	)
	(segment
		(start 419.511226 -46.779942)
		(end 418.496496 -46.779942)
		(width 0.10795)
		(layer "B.Cu")
		(net "SMB_SLOTX24_STBY_LVC3_SDA_R")
	)
	(segment
		(start 420.515796 -47.36592)
		(end 420.097204 -47.36592)
		(width 0.10795)
		(layer "B.Cu")
		(net "SMB_SLOTX24_STBY_LVC3_SDA_R")
	)
	(segment
		(start 420.776146 -47.62627)
		(end 420.515796 -47.36592)
		(width 0.10795)
		(layer "B.Cu")
		(net "SMB_SLOTX24_STBY_LVC3_SDA_R")
	)
	(segment
		(start 420.776146 -48.922432)
		(end 420.776146 -48.160432)
		(width 0.10795)
		(layer "B.Cu")
		(net "SMB_SLOTX24_STBY_LVC3_SDA_R")
	)
	(segment
		(start 420.776146 -48.160432)
		(end 420.776146 -47.62627)
		(width 0.10795)
		(layer "B.Cu")
		(net "SMB_SLOTX24_STBY_LVC3_SDA_R")
	)
	(segment
		(start 415.490152 -42.13479)
		(end 415.890202 -41.73474)
		(width 0.10795)
		(layer "F.Cu")
		(net "SMB_SLOTX24_STBY_LVC3_SCL_R")
	)
	(via
		(at 415.490152 -42.13479)
		(size 0.4572)
		(drill 0.2032)
		(layers "F.Cu" "B.Cu")
		(net "SMB_SLOTX24_STBY_LVC3_SCL_R")
	)
	(via
		(at 416.79114 -48.9204)
		(size 0.6604)
		(drill 0.3302)
		(layers "F.Cu" "B.Cu")
		(net "SMB_SLOTX24_STBY_LVC3_SCL_R")
	)
	(segment
		(start 415.490152 -42.13479)
		(end 415.490152 -41.925494)
		(width 0.10795)
		(layer "B.Cu")
		(net "SMB_SLOTX24_STBY_LVC3_SCL_R")
	)
	(segment
		(start 416.687 -42.431208)
		(end 416.842956 -42.587164)
		(width 0.10795)
		(layer "B.Cu")
		(net "SMB_SLOTX24_STBY_LVC3_SCL_R")
	)
	(segment
		(start 415.490152 -41.925494)
		(end 415.904934 -41.510712)
		(width 0.10795)
		(layer "B.Cu")
		(net "SMB_SLOTX24_STBY_LVC3_SCL_R")
	)
	(segment
		(start 416.687 -41.139618)
		(end 416.687 -42.431208)
		(width 0.10795)
		(layer "B.Cu")
		(net "SMB_SLOTX24_STBY_LVC3_SCL_R")
	)
	(segment
		(start 418.1094 -47.4218)
		(end 417.8173 -47.7139)
		(width 0.10795)
		(layer "B.Cu")
		(net "SMB_SLOTX24_STBY_LVC3_SCL_R")
	)
	(segment
		(start 417.395152 -42.98315)
		(end 417.395152 -43.202606)
		(width 0.10795)
		(layer "B.Cu")
		(net "SMB_SLOTX24_STBY_LVC3_SCL_R")
	)
	(segment
		(start 417.395152 -43.202606)
		(end 417.983924 -43.791378)
		(width 0.10795)
		(layer "B.Cu")
		(net "SMB_SLOTX24_STBY_LVC3_SCL_R")
	)
	(segment
		(start 416.842956 -42.587164)
		(end 416.999674 -42.587164)
		(width 0.10795)
		(layer "B.Cu")
		(net "SMB_SLOTX24_STBY_LVC3_SCL_R")
	)
	(segment
		(start 416.79114 -48.9204)
		(end 417.8173 -48.9204)
		(width 0.10795)
		(layer "B.Cu")
		(net "SMB_SLOTX24_STBY_LVC3_SCL_R")
	)
	(segment
		(start 417.983924 -43.791378)
		(end 417.983924 -46.63567)
		(width 0.10795)
		(layer "B.Cu")
		(net "SMB_SLOTX24_STBY_LVC3_SCL_R")
	)
	(segment
		(start 417.179506 -42.767504)
		(end 417.395152 -42.98315)
		(width 0.10795)
		(layer "B.Cu")
		(net "SMB_SLOTX24_STBY_LVC3_SCL_R")
	)
	(segment
		(start 417.983924 -46.63567)
		(end 418.1094 -46.761146)
		(width 0.10795)
		(layer "B.Cu")
		(net "SMB_SLOTX24_STBY_LVC3_SCL_R")
	)
	(segment
		(start 415.904934 -41.117266)
		(end 416.081972 -40.940228)
		(width 0.10795)
		(layer "B.Cu")
		(net "SMB_SLOTX24_STBY_LVC3_SCL_R")
	)
	(segment
		(start 417.8173 -48.9204)
		(end 417.8173 -48.1584)
		(width 0.10795)
		(layer "B.Cu")
		(net "SMB_SLOTX24_STBY_LVC3_SCL_R")
	)
	(segment
		(start 417.8173 -47.7139)
		(end 417.8173 -48.1584)
		(width 0.10795)
		(layer "B.Cu")
		(net "SMB_SLOTX24_STBY_LVC3_SCL_R")
	)
	(segment
		(start 418.1094 -46.761146)
		(end 418.1094 -47.4218)
		(width 0.10795)
		(layer "B.Cu")
		(net "SMB_SLOTX24_STBY_LVC3_SCL_R")
	)
	(segment
		(start 417.179506 -42.766996)
		(end 417.179506 -42.767504)
		(width 0.10795)
		(layer "B.Cu")
		(net "SMB_SLOTX24_STBY_LVC3_SCL_R")
	)
	(segment
		(start 416.081972 -40.940228)
		(end 416.48761 -40.940228)
		(width 0.10795)
		(layer "B.Cu")
		(net "SMB_SLOTX24_STBY_LVC3_SCL_R")
	)
	(segment
		(start 415.904934 -41.510712)
		(end 415.904934 -41.117266)
		(width 0.10795)
		(layer "B.Cu")
		(net "SMB_SLOTX24_STBY_LVC3_SCL_R")
	)
	(segment
		(start 416.48761 -40.940228)
		(end 416.687 -41.139618)
		(width 0.10795)
		(layer "B.Cu")
		(net "SMB_SLOTX24_STBY_LVC3_SCL_R")
	)
	(segment
		(start 416.999674 -42.587164)
		(end 417.179506 -42.766996)
		(width 0.10795)
		(layer "B.Cu")
		(net "SMB_SLOTX24_STBY_LVC3_SCL_R")
	)
	(segment
		(start 415.890202 -40.93464)
		(end 416.290252 -41.33469)
		(width 0.10795)
		(layer "F.Cu")
		(net "SMB_LAN_STBY_LVC3_SDA_R")
	)
	(via
		(at 416.290252 -41.33469)
		(size 0.4572)
		(drill 0.2032)
		(layers "F.Cu" "B.Cu")
		(net "SMB_LAN_STBY_LVC3_SDA_R")
	)
	(via
		(at 416.00755 -43.604688)
		(size 0.6604)
		(drill 0.3302)
		(layers "F.Cu" "B.Cu")
		(net "SMB_LAN_STBY_LVC3_SDA_R")
	)
	(segment
		(start 415.898584 -43.495722)
		(end 416.00755 -43.604688)
		(width 0.10795)
		(layer "B.Cu")
		(net "SMB_LAN_STBY_LVC3_SDA_R")
	)
	(segment
		(start 416.290252 -41.33469)
		(end 416.290252 -41.468548)
		(width 0.10795)
		(layer "B.Cu")
		(net "SMB_LAN_STBY_LVC3_SDA_R")
	)
	(segment
		(start 416.470846 -44.067984)
		(end 416.470846 -44.650152)
		(width 0.10795)
		(layer "B.Cu")
		(net "SMB_LAN_STBY_LVC3_SDA_R")
	)
	(segment
		(start 416.290252 -41.468548)
		(end 415.898584 -41.860216)
		(width 0.10795)
		(layer "B.Cu")
		(net "SMB_LAN_STBY_LVC3_SDA_R")
	)
	(segment
		(start 415.898584 -41.860216)
		(end 415.898584 -43.495722)
		(width 0.10795)
		(layer "B.Cu")
		(net "SMB_LAN_STBY_LVC3_SDA_R")
	)
	(segment
		(start 416.00755 -43.604688)
		(end 416.470846 -44.067984)
		(width 0.10795)
		(layer "B.Cu")
		(net "SMB_LAN_STBY_LVC3_SDA_R")
	)
	(segment
		(start 415.890202 -40.13454)
		(end 416.290252 -40.53459)
		(width 0.10795)
		(layer "F.Cu")
		(net "SMB_LAN_STBY_LVC3_SCL_R")
	)
	(via
		(at 415.07918 -42.9006)
		(size 0.6604)
		(drill 0.3302)
		(layers "F.Cu" "B.Cu")
		(net "SMB_LAN_STBY_LVC3_SCL_R")
	)
	(via
		(at 416.290252 -40.53459)
		(size 0.4572)
		(drill 0.2032)
		(layers "F.Cu" "B.Cu")
		(net "SMB_LAN_STBY_LVC3_SCL_R")
	)
	(segment
		(start 415.07918 -43.56989)
		(end 415.07918 -42.9006)
		(width 0.10795)
		(layer "B.Cu")
		(net "SMB_LAN_STBY_LVC3_SCL_R")
	)
	(segment
		(start 415.7218 -40.943276)
		(end 416.130486 -40.53459)
		(width 0.10795)
		(layer "B.Cu")
		(net "SMB_LAN_STBY_LVC3_SCL_R")
	)
	(segment
		(start 415.07918 -41.152318)
		(end 415.288222 -40.943276)
		(width 0.10795)
		(layer "B.Cu")
		(net "SMB_LAN_STBY_LVC3_SCL_R")
	)
	(segment
		(start 416.130486 -40.53459)
		(end 416.290252 -40.53459)
		(width 0.10795)
		(layer "B.Cu")
		(net "SMB_LAN_STBY_LVC3_SCL_R")
	)
	(segment
		(start 415.708846 -44.199556)
		(end 415.07918 -43.56989)
		(width 0.10795)
		(layer "B.Cu")
		(net "SMB_LAN_STBY_LVC3_SCL_R")
	)
	(segment
		(start 415.708846 -44.650152)
		(end 415.708846 -44.199556)
		(width 0.10795)
		(layer "B.Cu")
		(net "SMB_LAN_STBY_LVC3_SCL_R")
	)
	(segment
		(start 415.288222 -40.943276)
		(end 415.7218 -40.943276)
		(width 0.10795)
		(layer "B.Cu")
		(net "SMB_LAN_STBY_LVC3_SCL_R")
	)
	(segment
		(start 415.07918 -42.9006)
		(end 415.07918 -41.152318)
		(width 0.10795)
		(layer "B.Cu")
		(net "SMB_LAN_STBY_LVC3_SCL_R")
	)
	(segment
		(start 497.971318 -137.278618)
		(end 497.57076 -136.87806)
		(width 0.10795)
		(layer "F.Cu")
		(net "FM_UARTSW_MSB_R_N")
	)
	(segment
		(start 498.620034 -137.278618)
		(end 497.971318 -137.278618)
		(width 0.10795)
		(layer "F.Cu")
		(net "FM_UARTSW_MSB_R_N")
	)
	(via
		(at 496.8494 -136.525)
		(size 0.6604)
		(drill 0.3302)
		(layers "F.Cu" "B.Cu")
		(net "FM_UARTSW_MSB_R_N")
	)
	(via
		(at 497.57076 -136.87806)
		(size 0.508)
		(drill 0.254)
		(layers "F.Cu" "B.Cu")
		(net "FM_UARTSW_MSB_R_N")
	)
	(segment
		(start 497.9797 -137.287)
		(end 498.602 -137.287)
		(width 0.10795)
		(layer "B.Cu")
		(net "FM_UARTSW_MSB_R_N")
	)
	(segment
		(start 496.8494 -136.525)
		(end 497.2177 -136.525)
		(width 0.10795)
		(layer "B.Cu")
		(net "FM_UARTSW_MSB_R_N")
	)
	(segment
		(start 497.2177 -136.525)
		(end 497.57076 -136.87806)
		(width 0.10795)
		(layer "B.Cu")
		(net "FM_UARTSW_MSB_R_N")
	)
	(segment
		(start 497.57076 -136.87806)
		(end 497.9797 -137.287)
		(width 0.10795)
		(layer "B.Cu")
		(net "FM_UARTSW_MSB_R_N")
	)
	(segment
		(start 497.888514 -138.678666)
		(end 497.61648 -138.9507)
		(width 0.10795)
		(layer "F.Cu")
		(net "FM_UARTSW_LSB_R_N")
	)
	(segment
		(start 498.620034 -138.678666)
		(end 497.888514 -138.678666)
		(width 0.10795)
		(layer "F.Cu")
		(net "FM_UARTSW_LSB_R_N")
	)
	(via
		(at 497.61648 -138.9507)
		(size 0.508)
		(drill 0.254)
		(layers "F.Cu" "B.Cu")
		(net "FM_UARTSW_LSB_R_N")
	)
	(via
		(at 497.859812 -139.901422)
		(size 0.6604)
		(drill 0.3302)
		(layers "F.Cu" "B.Cu")
		(net "FM_UARTSW_LSB_R_N")
	)
	(segment
		(start 497.9162 -138.9507)
		(end 497.61648 -138.9507)
		(width 0.10795)
		(layer "B.Cu")
		(net "FM_UARTSW_LSB_R_N")
	)
	(segment
		(start 498.602 -138.557)
		(end 498.3099 -138.557)
		(width 0.10795)
		(layer "B.Cu")
		(net "FM_UARTSW_LSB_R_N")
	)
	(segment
		(start 498.3099 -138.557)
		(end 497.9162 -138.9507)
		(width 0.10795)
		(layer "B.Cu")
		(net "FM_UARTSW_LSB_R_N")
	)
	(segment
		(start 497.61648 -139.65809)
		(end 497.859812 -139.901422)
		(width 0.10795)
		(layer "B.Cu")
		(net "FM_UARTSW_LSB_R_N")
	)
	(segment
		(start 497.61648 -138.9507)
		(end 497.61648 -139.65809)
		(width 0.10795)
		(layer "B.Cu")
		(net "FM_UARTSW_LSB_R_N")
	)
	(segment
		(start 490.826806 -150.828502)
		(end 491.217966 -150.828502)
		(width 0.10795)
		(layer "F.Cu")
		(net "SPA_SIN_SW_R")
	)
	(segment
		(start 490.88294 -148.209508)
		(end 490.425232 -147.7518)
		(width 0.10795)
		(layer "F.Cu")
		(net "SPA_SIN_SW_R")
	)
	(segment
		(start 490.537246 -151.3967)
		(end 490.534706 -151.39416)
		(width 0.10795)
		(layer "F.Cu")
		(net "SPA_SIN_SW_R")
	)
	(segment
		(start 491.2741 -148.85416)
		(end 490.88294 -148.463)
		(width 0.10795)
		(layer "F.Cu")
		(net "SPA_SIN_SW_R")
	)
	(segment
		(start 494.60912 -148.85416)
		(end 491.2741 -148.85416)
		(width 0.10795)
		(layer "F.Cu")
		(net "SPA_SIN_SW_R")
	)
	(segment
		(start 489.153962 -147.600162)
		(end 489.153962 -146.939)
		(width 0.10795)
		(layer "F.Cu")
		(net "SPA_SIN_SW_R")
	)
	(segment
		(start 493.088168 -150.531068)
		(end 493.43564 -150.87854)
		(width 0.10795)
		(layer "F.Cu")
		(net "SPA_SIN_SW_R")
	)
	(segment
		(start 490.425232 -147.7518)
		(end 489.3056 -147.7518)
		(width 0.10795)
		(layer "F.Cu")
		(net "SPA_SIN_SW_R")
	)
	(segment
		(start 490.534706 -151.39416)
		(end 490.534706 -151.120602)
		(width 0.10795)
		(layer "F.Cu")
		(net "SPA_SIN_SW_R")
	)
	(segment
		(start 490.88294 -148.463)
		(end 490.88294 -148.209508)
		(width 0.10795)
		(layer "F.Cu")
		(net "SPA_SIN_SW_R")
	)
	(segment
		(start 490.524546 -152.91816)
		(end 490.524546 -152.16886)
		(width 0.10795)
		(layer "F.Cu")
		(net "SPA_SIN_SW_R")
	)
	(segment
		(start 495.03584 -150.21052)
		(end 495.03584 -149.28088)
		(width 0.10795)
		(layer "F.Cu")
		(net "SPA_SIN_SW_R")
	)
	(segment
		(start 490.524546 -152.16886)
		(end 490.537246 -152.15616)
		(width 0.10795)
		(layer "F.Cu")
		(net "SPA_SIN_SW_R")
	)
	(segment
		(start 489.3056 -147.7518)
		(end 489.153962 -147.600162)
		(width 0.10795)
		(layer "F.Cu")
		(net "SPA_SIN_SW_R")
	)
	(segment
		(start 495.03584 -149.28088)
		(end 494.60912 -148.85416)
		(width 0.10795)
		(layer "F.Cu")
		(net "SPA_SIN_SW_R")
	)
	(segment
		(start 493.43564 -150.87854)
		(end 494.36782 -150.87854)
		(width 0.10795)
		(layer "F.Cu")
		(net "SPA_SIN_SW_R")
	)
	(segment
		(start 491.217966 -150.828502)
		(end 491.5154 -150.531068)
		(width 0.10795)
		(layer "F.Cu")
		(net "SPA_SIN_SW_R")
	)
	(segment
		(start 490.534706 -151.120602)
		(end 490.826806 -150.828502)
		(width 0.10795)
		(layer "F.Cu")
		(net "SPA_SIN_SW_R")
	)
	(segment
		(start 491.5154 -150.531068)
		(end 493.088168 -150.531068)
		(width 0.10795)
		(layer "F.Cu")
		(net "SPA_SIN_SW_R")
	)
	(segment
		(start 494.36782 -150.87854)
		(end 495.03584 -150.21052)
		(width 0.10795)
		(layer "F.Cu")
		(net "SPA_SIN_SW_R")
	)
	(segment
		(start 490.537246 -152.15616)
		(end 490.537246 -151.3967)
		(width 0.10795)
		(layer "F.Cu")
		(net "SPA_SIN_SW_R")
	)
	(segment
		(start 403.0853 -25.986232)
		(end 403.352 -25.719532)
		(width 0.254)
		(layer "F.Cu")
		(net "A_P5V_STBY_SCALED")
	)
	(segment
		(start 411.49016 -30.134814)
		(end 411.89021 -29.734764)
		(width 0.089408)
		(layer "F.Cu")
		(net "A_P5V_STBY_SCALED")
	)
	(segment
		(start 402.89734 -26.47696)
		(end 403.0853 -26.289)
		(width 0.254)
		(layer "F.Cu")
		(net "A_P5V_STBY_SCALED")
	)
	(segment
		(start 410.69006 -30.134814)
		(end 411.49016 -30.134814)
		(width 0.089408)
		(layer "F.Cu")
		(net "A_P5V_STBY_SCALED")
	)
	(segment
		(start 403.352 -25.719532)
		(end 403.352 -25.527)
		(width 0.254)
		(layer "F.Cu")
		(net "A_P5V_STBY_SCALED")
	)
	(segment
		(start 403.0853 -26.289)
		(end 403.0853 -25.986232)
		(width 0.254)
		(layer "F.Cu")
		(net "A_P5V_STBY_SCALED")
	)
	(via
		(at 403.352 -25.527)
		(size 0.508)
		(drill 0.254)
		(layers "F.Cu" "B.Cu")
		(net "A_P5V_STBY_SCALED")
	)
	(via
		(at 402.89734 -26.47696)
		(size 0.762)
		(drill 0.381)
		(layers "F.Cu" "B.Cu")
		(net "A_P5V_STBY_SCALED")
	)
	(via
		(at 410.69006 -30.134814)
		(size 0.4572)
		(drill 0.2032)
		(layers "F.Cu" "B.Cu")
		(net "A_P5V_STBY_SCALED")
	)
	(segment
		(start 403.352 -25.527)
		(end 403.352 -25.308306)
		(width 0.254)
		(layer "B.Cu")
		(net "A_P5V_STBY_SCALED")
	)
	(segment
		(start 401.561554 -25.115012)
		(end 401.729194 -25.282652)
		(width 0.254)
		(layer "B.Cu")
		(net "A_P5V_STBY_SCALED")
	)
	(segment
		(start 401.729194 -25.282652)
		(end 402.043646 -25.282652)
		(width 0.254)
		(layer "B.Cu")
		(net "A_P5V_STBY_SCALED")
	)
	(segment
		(start 401.20189 -25.115012)
		(end 401.561554 -25.115012)
		(width 0.254)
		(layer "B.Cu")
		(net "A_P5V_STBY_SCALED")
	)
	(segment
		(start 400.626834 -25.690068)
		(end 401.20189 -25.115012)
		(width 0.254)
		(layer "B.Cu")
		(net "A_P5V_STBY_SCALED")
	)
	(segment
		(start 402.488146 -24.838152)
		(end 402.881846 -24.838152)
		(width 0.254)
		(layer "B.Cu")
		(net "A_P5V_STBY_SCALED")
	)
	(segment
		(start 403.352 -25.308306)
		(end 402.881846 -24.838152)
		(width 0.254)
		(layer "B.Cu")
		(net "A_P5V_STBY_SCALED")
	)
	(segment
		(start 402.043646 -25.282652)
		(end 402.488146 -24.838152)
		(width 0.254)
		(layer "B.Cu")
		(net "A_P5V_STBY_SCALED")
	)
	(segment
		(start 411.94736 -26.745438)
		(end 411.94736 -26.745184)
		(width 0.254)
		(layer "In9.Cu")
		(net "A_P5V_STBY_SCALED")
	)
	(segment
		(start 412.007304 -28.81757)
		(end 412.007304 -26.805382)
		(width 0.254)
		(layer "In9.Cu")
		(net "A_P5V_STBY_SCALED")
	)
	(segment
		(start 410.471366 -25.721056)
		(end 408.220418 -25.721056)
		(width 0.254)
		(layer "In9.Cu")
		(net "A_P5V_STBY_SCALED")
	)
	(segment
		(start 405.601424 -25.868376)
		(end 403.693376 -25.868376)
		(width 0.254)
		(layer "In9.Cu")
		(net "A_P5V_STBY_SCALED")
	)
	(segment
		(start 403.693376 -25.868376)
		(end 403.352 -25.527)
		(width 0.254)
		(layer "In9.Cu")
		(net "A_P5V_STBY_SCALED")
	)
	(segment
		(start 407.516584 -25.017222)
		(end 406.452578 -25.017222)
		(width 0.254)
		(layer "In9.Cu")
		(net "A_P5V_STBY_SCALED")
	)
	(segment
		(start 406.452578 -25.017222)
		(end 405.601424 -25.868376)
		(width 0.254)
		(layer "In9.Cu")
		(net "A_P5V_STBY_SCALED")
	)
	(segment
		(start 411.679644 -26.477468)
		(end 411.227778 -26.477468)
		(width 0.254)
		(layer "In9.Cu")
		(net "A_P5V_STBY_SCALED")
	)
	(segment
		(start 411.94736 -26.745184)
		(end 411.679644 -26.477468)
		(width 0.254)
		(layer "In9.Cu")
		(net "A_P5V_STBY_SCALED")
	)
	(segment
		(start 412.007304 -26.805382)
		(end 411.94736 -26.745438)
		(width 0.254)
		(layer "In9.Cu")
		(net "A_P5V_STBY_SCALED")
	)
	(segment
		(start 408.220418 -25.721056)
		(end 407.516584 -25.017222)
		(width 0.254)
		(layer "In9.Cu")
		(net "A_P5V_STBY_SCALED")
	)
	(segment
		(start 411.227778 -26.477468)
		(end 410.471366 -25.721056)
		(width 0.254)
		(layer "In9.Cu")
		(net "A_P5V_STBY_SCALED")
	)
	(segment
		(start 410.69006 -30.134814)
		(end 412.007304 -28.81757)
		(width 0.254)
		(layer "In9.Cu")
		(net "A_P5V_STBY_SCALED")
	)
	(segment
		(start 466.311996 1.1684)
		(end 466.311996 1.51892)
		(width 0.254)
		(layer "F.Cu")
		(net "P3V_BAT_SOURCE_R")
	)
	(segment
		(start 466.565996 0.9144)
		(end 466.311996 1.1684)
		(width 0.254)
		(layer "F.Cu")
		(net "P3V_BAT_SOURCE_R")
	)
	(segment
		(start 466.8012 0.9144)
		(end 466.565996 0.9144)
		(width 0.254)
		(layer "F.Cu")
		(net "P3V_BAT_SOURCE_R")
	)
	(via
		(at 466.8012 0.9144)
		(size 0.508)
		(drill 0.254)
		(layers "F.Cu" "B.Cu")
		(net "P3V_BAT_SOURCE_R")
	)
	(via
		(at 465.63534 0.99314)
		(size 0.6604)
		(drill 0.3302)
		(layers "F.Cu" "B.Cu")
		(net "P3V_BAT_SOURCE_R")
	)
	(segment
		(start 460.432912 0.032512)
		(end 462.425288 0.032512)
		(width 0.254)
		(layer "B.Cu")
		(net "P3V_BAT_SOURCE_R")
	)
	(segment
		(start 462.425288 0.032512)
		(end 463.246978 0.854202)
		(width 0.254)
		(layer "B.Cu")
		(net "P3V_BAT_SOURCE_R")
	)
	(segment
		(start 463.246978 0.95631)
		(end 463.636868 1.3462)
		(width 0.254)
		(layer "B.Cu")
		(net "P3V_BAT_SOURCE_R")
	)
	(segment
		(start 463.246978 0.854202)
		(end 463.246978 0.95631)
		(width 0.254)
		(layer "B.Cu")
		(net "P3V_BAT_SOURCE_R")
	)
	(segment
		(start 466.72246 0.99314)
		(end 466.8012 0.9144)
		(width 0.254)
		(layer "B.Cu")
		(net "P3V_BAT_SOURCE_R")
	)
	(segment
		(start 459.7146 -1.1684)
		(end 459.7146 -0.6858)
		(width 0.254)
		(layer "B.Cu")
		(net "P3V_BAT_SOURCE_R")
	)
	(segment
		(start 464.3628 1.3462)
		(end 464.71586 0.99314)
		(width 0.254)
		(layer "B.Cu")
		(net "P3V_BAT_SOURCE_R")
	)
	(segment
		(start 458.851 -2.032)
		(end 459.7146 -1.1684)
		(width 0.254)
		(layer "B.Cu")
		(net "P3V_BAT_SOURCE_R")
	)
	(segment
		(start 458.851 -3.302)
		(end 458.851 -2.032)
		(width 0.254)
		(layer "B.Cu")
		(net "P3V_BAT_SOURCE_R")
	)
	(segment
		(start 463.636868 1.3462)
		(end 464.3628 1.3462)
		(width 0.254)
		(layer "B.Cu")
		(net "P3V_BAT_SOURCE_R")
	)
	(segment
		(start 459.7146 -0.6858)
		(end 460.432912 0.032512)
		(width 0.254)
		(layer "B.Cu")
		(net "P3V_BAT_SOURCE_R")
	)
	(segment
		(start 464.71586 0.99314)
		(end 465.63534 0.99314)
		(width 0.254)
		(layer "B.Cu")
		(net "P3V_BAT_SOURCE_R")
	)
	(segment
		(start 458.343 -4.2164)
		(end 458.343 -3.81)
		(width 0.254)
		(layer "B.Cu")
		(net "P3V_BAT_SOURCE_R")
	)
	(segment
		(start 458.343 -3.81)
		(end 458.851 -3.302)
		(width 0.254)
		(layer "B.Cu")
		(net "P3V_BAT_SOURCE_R")
	)
	(segment
		(start 465.63534 0.99314)
		(end 466.72246 0.99314)
		(width 0.254)
		(layer "B.Cu")
		(net "P3V_BAT_SOURCE_R")
	)
	(segment
		(start 410.290264 -28.134564)
		(end 409.890214 -27.734514)
		(width 0.10795)
		(layer "F.Cu")
		(net "A_P3V3_STBY_SCALED")
	)
	(via
		(at 409.890214 -27.734514)
		(size 0.4572)
		(drill 0.2032)
		(layers "F.Cu" "B.Cu")
		(net "A_P3V3_STBY_SCALED")
	)
	(via
		(at 404.206964 -27.495754)
		(size 0.6604)
		(drill 0.3302)
		(layers "F.Cu" "B.Cu")
		(net "A_P3V3_STBY_SCALED")
	)
	(via
		(at 406.4 -26.477722)
		(size 0.508)
		(drill 0.254)
		(layers "F.Cu" "B.Cu")
		(net "A_P3V3_STBY_SCALED")
	)
	(segment
		(start 405.726646 -26.489152)
		(end 406.38857 -26.489152)
		(width 0.254)
		(layer "B.Cu")
		(net "A_P3V3_STBY_SCALED")
	)
	(segment
		(start 406.38857 -26.489152)
		(end 406.4 -26.477722)
		(width 0.254)
		(layer "B.Cu")
		(net "A_P3V3_STBY_SCALED")
	)
	(segment
		(start 404.206964 -27.495754)
		(end 404.101046 -27.389836)
		(width 0.254)
		(layer "B.Cu")
		(net "A_P3V3_STBY_SCALED")
	)
	(segment
		(start 404.101046 -27.389836)
		(end 404.101046 -26.489152)
		(width 0.254)
		(layer "B.Cu")
		(net "A_P3V3_STBY_SCALED")
	)
	(segment
		(start 404.913846 -26.489152)
		(end 404.101046 -26.489152)
		(width 0.254)
		(layer "B.Cu")
		(net "A_P3V3_STBY_SCALED")
	)
	(segment
		(start 404.913846 -26.489152)
		(end 405.726646 -26.489152)
		(width 0.254)
		(layer "B.Cu")
		(net "A_P3V3_STBY_SCALED")
	)
	(segment
		(start 406.400254 -26.477468)
		(end 410.079698 -26.477468)
		(width 0.254)
		(layer "In9.Cu")
		(net "A_P3V3_STBY_SCALED")
	)
	(segment
		(start 410.347414 -27.277314)
		(end 409.890214 -27.734514)
		(width 0.254)
		(layer "In9.Cu")
		(net "A_P3V3_STBY_SCALED")
	)
	(segment
		(start 410.347414 -26.745184)
		(end 410.347414 -27.277314)
		(width 0.254)
		(layer "In9.Cu")
		(net "A_P3V3_STBY_SCALED")
	)
	(segment
		(start 410.079698 -26.477468)
		(end 410.347414 -26.745184)
		(width 0.254)
		(layer "In9.Cu")
		(net "A_P3V3_STBY_SCALED")
	)
	(segment
		(start 406.4 -26.477722)
		(end 406.400254 -26.477468)
		(width 0.254)
		(layer "In9.Cu")
		(net "A_P3V3_STBY_SCALED")
	)
	(segment
		(start 412.3182 -25.6032)
		(end 411.9118 -25.1968)
		(width 0.1143)
		(layer "F.Cu")
		(net "P3V3_STBY_BMC_ADCVREFP")
	)
	(segment
		(start 411.690058 -24.168862)
		(end 411.690058 -23.877524)
		(width 0.254)
		(layer "F.Cu")
		(net "P3V3_STBY_BMC_ADCVREFP")
	)
	(segment
		(start 410.997146 -23.184612)
		(end 410.997146 -22.996652)
		(width 0.254)
		(layer "F.Cu")
		(net "P3V3_STBY_BMC_ADCVREFP")
	)
	(segment
		(start 412.3182 -26.962862)
		(end 412.3182 -25.6032)
		(width 0.1143)
		(layer "F.Cu")
		(net "P3V3_STBY_BMC_ADCVREFP")
	)
	(segment
		(start 411.9118 -25.1968)
		(end 411.690058 -24.975058)
		(width 0.254)
		(layer "F.Cu")
		(net "P3V3_STBY_BMC_ADCVREFP")
	)
	(segment
		(start 411.690058 -23.877524)
		(end 410.997146 -23.184612)
		(width 0.254)
		(layer "F.Cu")
		(net "P3V3_STBY_BMC_ADCVREFP")
	)
	(segment
		(start 411.086046 -22.907752)
		(end 410.997146 -22.996652)
		(width 0.254)
		(layer "F.Cu")
		(net "P3V3_STBY_BMC_ADCVREFP")
	)
	(segment
		(start 411.690058 -24.975058)
		(end 411.690058 -24.168862)
		(width 0.254)
		(layer "F.Cu")
		(net "P3V3_STBY_BMC_ADCVREFP")
	)
	(segment
		(start 412.690056 -27.334718)
		(end 412.3182 -26.962862)
		(width 0.1143)
		(layer "F.Cu")
		(net "P3V3_STBY_BMC_ADCVREFP")
	)
	(segment
		(start 411.086046 -22.196552)
		(end 411.086046 -22.907752)
		(width 0.254)
		(layer "F.Cu")
		(net "P3V3_STBY_BMC_ADCVREFP")
	)
	(via
		(at 411.690058 -24.168862)
		(size 0.508)
		(drill 0.254)
		(layers "F.Cu" "B.Cu")
		(net "P3V3_STBY_BMC_ADCVREFP")
	)
	(segment
		(start 412.5468 -23.83155)
		(end 411.886146 -23.170896)
		(width 0.254)
		(layer "F.Cu")
		(net "P3V3_STBY_BMC_ADCVREFN")
	)
	(segment
		(start 411.975046 -22.907752)
		(end 411.886146 -22.996652)
		(width 0.254)
		(layer "F.Cu")
		(net "P3V3_STBY_BMC_ADCVREFN")
	)
	(segment
		(start 412.5468 -24.841454)
		(end 412.690056 -24.98471)
		(width 0.254)
		(layer "F.Cu")
		(net "P3V3_STBY_BMC_ADCVREFN")
	)
	(segment
		(start 412.690056 -24.98471)
		(end 412.690056 -26.534618)
		(width 0.254)
		(layer "F.Cu")
		(net "P3V3_STBY_BMC_ADCVREFN")
	)
	(segment
		(start 412.5468 -24.5618)
		(end 412.543752 -24.5618)
		(width 0.254)
		(layer "F.Cu")
		(net "P3V3_STBY_BMC_ADCVREFN")
	)
	(segment
		(start 412.5468 -24.5618)
		(end 412.5468 -23.83155)
		(width 0.254)
		(layer "F.Cu")
		(net "P3V3_STBY_BMC_ADCVREFN")
	)
	(segment
		(start 412.5468 -24.5618)
		(end 412.5468 -24.841454)
		(width 0.254)
		(layer "F.Cu")
		(net "P3V3_STBY_BMC_ADCVREFN")
	)
	(segment
		(start 411.975046 -22.196552)
		(end 411.975046 -22.907752)
		(width 0.254)
		(layer "F.Cu")
		(net "P3V3_STBY_BMC_ADCVREFN")
	)
	(segment
		(start 411.886146 -23.170896)
		(end 411.886146 -22.996652)
		(width 0.254)
		(layer "F.Cu")
		(net "P3V3_STBY_BMC_ADCVREFN")
	)
	(via
		(at 412.543752 -24.5618)
		(size 0.508)
		(drill 0.254)
		(layers "F.Cu" "B.Cu")
		(net "P3V3_STBY_BMC_ADCVREFN")
	)
	(segment
		(start 410.290264 -27.334718)
		(end 409.890214 -26.934668)
		(width 0.254)
		(layer "F.Cu")
		(net "A_P12V_STBY_SCALED")
	)
	(via
		(at 403.479 -27.124152)
		(size 0.508)
		(drill 0.254)
		(layers "F.Cu" "B.Cu")
		(net "A_P12V_STBY_SCALED")
	)
	(via
		(at 409.890214 -26.934668)
		(size 0.4572)
		(drill 0.2032)
		(layers "F.Cu" "B.Cu")
		(net "A_P12V_STBY_SCALED")
	)
	(via
		(at 399.96491 -27.029918)
		(size 0.6604)
		(drill 0.3302)
		(layers "F.Cu" "B.Cu")
		(net "A_P12V_STBY_SCALED")
	)
	(segment
		(start 401.992846 -27.124152)
		(end 402.361146 -27.124152)
		(width 0.254)
		(layer "B.Cu")
		(net "A_P12V_STBY_SCALED")
	)
	(segment
		(start 401.718018 -27.124152)
		(end 401.481798 -27.360372)
		(width 0.254)
		(layer "B.Cu")
		(net "A_P12V_STBY_SCALED")
	)
	(segment
		(start 402.361146 -27.124152)
		(end 402.805646 -27.568652)
		(width 0.254)
		(layer "B.Cu")
		(net "A_P12V_STBY_SCALED")
	)
	(segment
		(start 401.108418 -27.360372)
		(end 400.295364 -27.360372)
		(width 0.254)
		(layer "B.Cu")
		(net "A_P12V_STBY_SCALED")
	)
	(segment
		(start 401.481798 -27.360372)
		(end 401.108418 -27.360372)
		(width 0.254)
		(layer "B.Cu")
		(net "A_P12V_STBY_SCALED")
	)
	(segment
		(start 401.992846 -27.124152)
		(end 401.718018 -27.124152)
		(width 0.254)
		(layer "B.Cu")
		(net "A_P12V_STBY_SCALED")
	)
	(segment
		(start 400.295364 -27.360372)
		(end 399.96491 -27.029918)
		(width 0.254)
		(layer "B.Cu")
		(net "A_P12V_STBY_SCALED")
	)
	(segment
		(start 403.0345 -27.568652)
		(end 403.479 -27.124152)
		(width 0.254)
		(layer "B.Cu")
		(net "A_P12V_STBY_SCALED")
	)
	(segment
		(start 402.805646 -27.568652)
		(end 403.0345 -27.568652)
		(width 0.254)
		(layer "B.Cu")
		(net "A_P12V_STBY_SCALED")
	)
	(segment
		(start 408.606752 -27.435048)
		(end 407.571448 -27.435048)
		(width 0.254)
		(layer "In9.Cu")
		(net "A_P12V_STBY_SCALED")
	)
	(segment
		(start 407.571448 -27.435048)
		(end 407.260552 -27.124152)
		(width 0.254)
		(layer "In9.Cu")
		(net "A_P12V_STBY_SCALED")
	)
	(segment
		(start 407.260552 -27.124152)
		(end 403.479 -27.124152)
		(width 0.254)
		(layer "In9.Cu")
		(net "A_P12V_STBY_SCALED")
	)
	(segment
		(start 409.107132 -26.934668)
		(end 408.606752 -27.435048)
		(width 0.254)
		(layer "In9.Cu")
		(net "A_P12V_STBY_SCALED")
	)
	(segment
		(start 409.890214 -26.934668)
		(end 409.107132 -26.934668)
		(width 0.254)
		(layer "In9.Cu")
		(net "A_P12V_STBY_SCALED")
	)
	(segment
		(start 464.533996 2.8194)
		(end 464.533996 3.43408)
		(width 0.10795)
		(layer "F.Cu")
		(net "FM_BATTERY_SENSE_EN")
	)
	(segment
		(start 464.533996 3.43408)
		(end 464.412076 3.556)
		(width 0.10795)
		(layer "F.Cu")
		(net "FM_BATTERY_SENSE_EN")
	)
	(segment
		(start 463.742024 3.253994)
		(end 463.742024 2.50063)
		(width 0.10795)
		(layer "F.Cu")
		(net "FM_BATTERY_SENSE_EN")
	)
	(segment
		(start 464.073494 2.16916)
		(end 464.533996 2.16916)
		(width 0.10795)
		(layer "F.Cu")
		(net "FM_BATTERY_SENSE_EN")
	)
	(segment
		(start 464.04403 3.556)
		(end 463.742024 3.253994)
		(width 0.10795)
		(layer "F.Cu")
		(net "FM_BATTERY_SENSE_EN")
	)
	(segment
		(start 464.412076 3.556)
		(end 464.04403 3.556)
		(width 0.10795)
		(layer "F.Cu")
		(net "FM_BATTERY_SENSE_EN")
	)
	(segment
		(start 463.742024 2.50063)
		(end 464.073494 2.16916)
		(width 0.10795)
		(layer "F.Cu")
		(net "FM_BATTERY_SENSE_EN")
	)
	(via
		(at 464.533996 3.43408)
		(size 0.508)
		(drill 0.254)
		(layers "F.Cu" "B.Cu")
		(net "FM_BATTERY_SENSE_EN")
	)
	(segment
		(start 459.0034 -0.762)
		(end 460.832454 1.067054)
		(width 0.10795)
		(layer "B.Cu")
		(net "FM_BATTERY_SENSE_EN")
	)
	(segment
		(start 460.832454 1.067054)
		(end 460.832454 1.8542)
		(width 0.10795)
		(layer "B.Cu")
		(net "FM_BATTERY_SENSE_EN")
	)
	(segment
		(start 460.832454 1.8542)
		(end 461.39227 2.414016)
		(width 0.10795)
		(layer "B.Cu")
		(net "FM_BATTERY_SENSE_EN")
	)
	(segment
		(start 457.5048 -0.762)
		(end 459.0034 -0.762)
		(width 0.10795)
		(layer "B.Cu")
		(net "FM_BATTERY_SENSE_EN")
	)
	(segment
		(start 456.438 -1.8288)
		(end 457.5048 -0.762)
		(width 0.10795)
		(layer "B.Cu")
		(net "FM_BATTERY_SENSE_EN")
	)
	(segment
		(start 461.39227 2.414016)
		(end 463.513932 2.414016)
		(width 0.10795)
		(layer "B.Cu")
		(net "FM_BATTERY_SENSE_EN")
	)
	(segment
		(start 463.513932 2.414016)
		(end 464.533996 3.43408)
		(width 0.10795)
		(layer "B.Cu")
		(net "FM_BATTERY_SENSE_EN")
	)
	(segment
		(start 456.438 -4.2164)
		(end 456.438 -1.8288)
		(width 0.10795)
		(layer "B.Cu")
		(net "FM_BATTERY_SENSE_EN")
	)
	(segment
		(start 314.376816 -37.699442)
		(end 314.299092 -37.699442)
		(width 0.10795)
		(layer "F.Cu")
		(net "IRQ_DIMM_SAVE_N")
	)
	(segment
		(start 319.494916 -36.028122)
		(end 320.51752 -36.028122)
		(width 0.10795)
		(layer "F.Cu")
		(net "IRQ_DIMM_SAVE_N")
	)
	(segment
		(start 310.14035 -35.975036)
		(end 310.14035 -34.651696)
		(width 0.10795)
		(layer "F.Cu")
		(net "IRQ_DIMM_SAVE_N")
	)
	(segment
		(start 323.723 -36.250372)
		(end 323.723 -35.814)
		(width 0.10795)
		(layer "F.Cu")
		(net "IRQ_DIMM_SAVE_N")
	)
	(segment
		(start 320.798444 -36.309046)
		(end 320.803016 -36.309046)
		(width 0.10795)
		(layer "F.Cu")
		(net "IRQ_DIMM_SAVE_N")
	)
	(segment
		(start 318.571626 -36.400994)
		(end 318.944498 -36.028122)
		(width 0.10795)
		(layer "F.Cu")
		(net "IRQ_DIMM_SAVE_N")
	)
	(segment
		(start 320.803016 -36.309046)
		(end 321.380358 -36.886388)
		(width 0.10795)
		(layer "F.Cu")
		(net "IRQ_DIMM_SAVE_N")
	)
	(segment
		(start 317.354966 -36.400994)
		(end 318.571626 -36.400994)
		(width 0.10795)
		(layer "F.Cu")
		(net "IRQ_DIMM_SAVE_N")
	)
	(segment
		(start 323.086984 -36.886388)
		(end 323.723 -36.250372)
		(width 0.10795)
		(layer "F.Cu")
		(net "IRQ_DIMM_SAVE_N")
	)
	(segment
		(start 316.056518 -37.699442)
		(end 317.354966 -36.400994)
		(width 0.10795)
		(layer "F.Cu")
		(net "IRQ_DIMM_SAVE_N")
	)
	(segment
		(start 313.676538 -38.321996)
		(end 312.48731 -38.321996)
		(width 0.10795)
		(layer "F.Cu")
		(net "IRQ_DIMM_SAVE_N")
	)
	(segment
		(start 312.48731 -38.321996)
		(end 310.14035 -35.975036)
		(width 0.10795)
		(layer "F.Cu")
		(net "IRQ_DIMM_SAVE_N")
	)
	(segment
		(start 314.299092 -37.699442)
		(end 313.676538 -38.321996)
		(width 0.10795)
		(layer "F.Cu")
		(net "IRQ_DIMM_SAVE_N")
	)
	(segment
		(start 321.380358 -36.886388)
		(end 323.086984 -36.886388)
		(width 0.10795)
		(layer "F.Cu")
		(net "IRQ_DIMM_SAVE_N")
	)
	(segment
		(start 318.944498 -36.028122)
		(end 319.494916 -36.028122)
		(width 0.10795)
		(layer "F.Cu")
		(net "IRQ_DIMM_SAVE_N")
	)
	(segment
		(start 320.51752 -36.028122)
		(end 320.798444 -36.309046)
		(width 0.10795)
		(layer "F.Cu")
		(net "IRQ_DIMM_SAVE_N")
	)
	(segment
		(start 323.723 -35.052)
		(end 323.723 -34.163)
		(width 0.10795)
		(layer "F.Cu")
		(net "IRQ_DIMM_SAVE_N")
	)
	(segment
		(start 314.376816 -37.699442)
		(end 316.056518 -37.699442)
		(width 0.10795)
		(layer "F.Cu")
		(net "IRQ_DIMM_SAVE_N")
	)
	(segment
		(start 323.723 -35.814)
		(end 323.723 -35.052)
		(width 0.10795)
		(layer "F.Cu")
		(net "IRQ_DIMM_SAVE_N")
	)
	(via
		(at 314.376816 -37.699442)
		(size 0.508)
		(drill 0.254)
		(layers "F.Cu" "B.Cu")
		(net "IRQ_DIMM_SAVE_N")
	)
	(via
		(at 319.494916 -36.028122)
		(size 0.762)
		(drill 0.381)
		(layers "F.Cu" "B.Cu")
		(net "IRQ_DIMM_SAVE_N")
	)
	(segment
		(start 312.786268 -31.69285)
		(end 313.1058 -32.012382)
		(width 0.10795)
		(layer "B.Cu")
		(net "IRQ_DIMM_SAVE_N")
	)
	(segment
		(start 313.1058 -32.012382)
		(end 313.1058 -36.428426)
		(width 0.10795)
		(layer "B.Cu")
		(net "IRQ_DIMM_SAVE_N")
	)
	(segment
		(start 313.1058 -36.428426)
		(end 314.376816 -37.699442)
		(width 0.10795)
		(layer "B.Cu")
		(net "IRQ_DIMM_SAVE_N")
	)
	(segment
		(start 376.744738 -67.895216)
		(end 376.344942 -68.295012)
		(width 0.1016)
		(layer "F.Cu")
		(net "FM_P3V3_CPLD_EN")
	)
	(via
		(at 428.272702 -63.653416)
		(size 0.508)
		(drill 0.254)
		(layers "F.Cu" "B.Cu")
		(net "FM_P3V3_CPLD_EN")
	)
	(via
		(at 475.984824 -15.315946)
		(size 0.508)
		(drill 0.254)
		(layers "F.Cu" "B.Cu")
		(net "FM_P3V3_CPLD_EN")
	)
	(via
		(at 437.045354 -62.519814)
		(size 0.508)
		(drill 0.254)
		(layers "F.Cu" "B.Cu")
		(net "FM_P3V3_CPLD_EN")
	)
	(via
		(at 429.010826 -64.39154)
		(size 0.6604)
		(drill 0.3302)
		(layers "F.Cu" "B.Cu")
		(net "FM_P3V3_CPLD_EN")
	)
	(via
		(at 479.119946 -39.097712)
		(size 0.508)
		(drill 0.254)
		(layers "F.Cu" "B.Cu")
		(net "FM_P3V3_CPLD_EN")
	)
	(via
		(at 376.744738 -67.895216)
		(size 0.4572)
		(drill 0.2032)
		(layers "F.Cu" "B.Cu")
		(net "FM_P3V3_CPLD_EN")
	)
	(segment
		(start 436.611268 -62.085728)
		(end 435.64937 -62.085728)
		(width 0.10795)
		(layer "B.Cu")
		(net "FM_P3V3_CPLD_EN")
	)
	(segment
		(start 435.321964 -63.269114)
		(end 434.082444 -64.508634)
		(width 0.10795)
		(layer "B.Cu")
		(net "FM_P3V3_CPLD_EN")
	)
	(segment
		(start 429.010826 -64.39154)
		(end 428.272702 -63.653416)
		(width 0.10795)
		(layer "B.Cu")
		(net "FM_P3V3_CPLD_EN")
	)
	(segment
		(start 434.082444 -64.508634)
		(end 429.12792 -64.508634)
		(width 0.10795)
		(layer "B.Cu")
		(net "FM_P3V3_CPLD_EN")
	)
	(segment
		(start 437.045354 -62.519814)
		(end 436.611268 -62.085728)
		(width 0.10795)
		(layer "B.Cu")
		(net "FM_P3V3_CPLD_EN")
	)
	(segment
		(start 475.984824 -15.315946)
		(end 475.984824 -14.0589)
		(width 0.10795)
		(layer "B.Cu")
		(net "FM_P3V3_CPLD_EN")
	)
	(segment
		(start 429.12792 -64.508634)
		(end 429.010826 -64.39154)
		(width 0.10795)
		(layer "B.Cu")
		(net "FM_P3V3_CPLD_EN")
	)
	(segment
		(start 435.321964 -62.413134)
		(end 435.321964 -63.269114)
		(width 0.10795)
		(layer "B.Cu")
		(net "FM_P3V3_CPLD_EN")
	)
	(segment
		(start 435.64937 -62.085728)
		(end 435.321964 -62.413134)
		(width 0.10795)
		(layer "B.Cu")
		(net "FM_P3V3_CPLD_EN")
	)
	(segment
		(start 437.57596 -63.05042)
		(end 437.045354 -62.519814)
		(width 0.089408)
		(layer "In4.Cu")
		(net "FM_P3V3_CPLD_EN")
	)
	(segment
		(start 422.203118 -61.44641)
		(end 422.667176 -61.44641)
		(width 0.089408)
		(layer "In4.Cu")
		(net "FM_P3V3_CPLD_EN")
	)
	(segment
		(start 422.667176 -61.44641)
		(end 423.085768 -61.865002)
		(width 0.089408)
		(layer "In4.Cu")
		(net "FM_P3V3_CPLD_EN")
	)
	(segment
		(start 427.794928 -63.175642)
		(end 428.272702 -63.653416)
		(width 0.089408)
		(layer "In4.Cu")
		(net "FM_P3V3_CPLD_EN")
	)
	(segment
		(start 407.64968 -69.316092)
		(end 408.562048 -68.403724)
		(width 0.089408)
		(layer "In4.Cu")
		(net "FM_P3V3_CPLD_EN")
	)
	(segment
		(start 408.562048 -68.403724)
		(end 414.165796 -68.403724)
		(width 0.089408)
		(layer "In4.Cu")
		(net "FM_P3V3_CPLD_EN")
	)
	(segment
		(start 466.166962 -53.915818)
		(end 465.44992 -53.915818)
		(width 0.089408)
		(layer "In4.Cu")
		(net "FM_P3V3_CPLD_EN")
	)
	(segment
		(start 421.266874 -61.623448)
		(end 422.02608 -61.623448)
		(width 0.089408)
		(layer "In4.Cu")
		(net "FM_P3V3_CPLD_EN")
	)
	(segment
		(start 467.865714 -55.61457)
		(end 466.166962 -53.915818)
		(width 0.089408)
		(layer "In4.Cu")
		(net "FM_P3V3_CPLD_EN")
	)
	(segment
		(start 440.097926 -62.545468)
		(end 439.592974 -63.05042)
		(width 0.089408)
		(layer "In4.Cu")
		(net "FM_P3V3_CPLD_EN")
	)
	(segment
		(start 423.085768 -61.865002)
		(end 424.866054 -61.865002)
		(width 0.089408)
		(layer "In4.Cu")
		(net "FM_P3V3_CPLD_EN")
	)
	(segment
		(start 478.643696 -40.622728)
		(end 477.52127 -41.745154)
		(width 0.089408)
		(layer "In4.Cu")
		(net "FM_P3V3_CPLD_EN")
	)
	(segment
		(start 377.171458 -68.321936)
		(end 378.737876 -68.321936)
		(width 0.089408)
		(layer "In4.Cu")
		(net "FM_P3V3_CPLD_EN")
	)
	(segment
		(start 378.966984 -68.551044)
		(end 380.031498 -68.551044)
		(width 0.089408)
		(layer "In4.Cu")
		(net "FM_P3V3_CPLD_EN")
	)
	(segment
		(start 464.464908 -55.251096)
		(end 464.465162 -55.25135)
		(width 0.089408)
		(layer "In4.Cu")
		(net "FM_P3V3_CPLD_EN")
	)
	(segment
		(start 397.229076 -68.977764)
		(end 406.131014 -68.977764)
		(width 0.089408)
		(layer "In4.Cu")
		(net "FM_P3V3_CPLD_EN")
	)
	(segment
		(start 414.166558 -68.402962)
		(end 414.25495 -68.402962)
		(width 0.089408)
		(layer "In4.Cu")
		(net "FM_P3V3_CPLD_EN")
	)
	(segment
		(start 406.470866 -69.317616)
		(end 406.472644 -69.315838)
		(width 0.089408)
		(layer "In4.Cu")
		(net "FM_P3V3_CPLD_EN")
	)
	(segment
		(start 422.02608 -61.623448)
		(end 422.203118 -61.44641)
		(width 0.089408)
		(layer "In4.Cu")
		(net "FM_P3V3_CPLD_EN")
	)
	(segment
		(start 475.231206 -53.206904)
		(end 474.63329 -53.80482)
		(width 0.089408)
		(layer "In4.Cu")
		(net "FM_P3V3_CPLD_EN")
	)
	(segment
		(start 414.165796 -68.403724)
		(end 414.166558 -68.402962)
		(width 0.089408)
		(layer "In4.Cu")
		(net "FM_P3V3_CPLD_EN")
	)
	(segment
		(start 426.176694 -63.175642)
		(end 427.794928 -63.175642)
		(width 0.089408)
		(layer "In4.Cu")
		(net "FM_P3V3_CPLD_EN")
	)
	(segment
		(start 477.049592 -47.839884)
		(end 475.913704 -48.975772)
		(width 0.089408)
		(layer "In4.Cu")
		(net "FM_P3V3_CPLD_EN")
	)
	(segment
		(start 469.146382 -55.61457)
		(end 467.865714 -55.61457)
		(width 0.089408)
		(layer "In4.Cu")
		(net "FM_P3V3_CPLD_EN")
	)
	(segment
		(start 474.63329 -53.80482)
		(end 474.63329 -53.888132)
		(width 0.089408)
		(layer "In4.Cu")
		(net "FM_P3V3_CPLD_EN")
	)
	(segment
		(start 464.465162 -55.25135)
		(end 464.465162 -60.631578)
		(width 0.089408)
		(layer "In4.Cu")
		(net "FM_P3V3_CPLD_EN")
	)
	(segment
		(start 465.44992 -53.915818)
		(end 464.464908 -54.90083)
		(width 0.089408)
		(layer "In4.Cu")
		(net "FM_P3V3_CPLD_EN")
	)
	(segment
		(start 407.491438 -69.315838)
		(end 407.491692 -69.316092)
		(width 0.089408)
		(layer "In4.Cu")
		(net "FM_P3V3_CPLD_EN")
	)
	(segment
		(start 394.589 -66.337688)
		(end 397.229076 -68.977764)
		(width 0.089408)
		(layer "In4.Cu")
		(net "FM_P3V3_CPLD_EN")
	)
	(segment
		(start 414.25495 -68.402962)
		(end 414.864296 -67.793616)
		(width 0.089408)
		(layer "In4.Cu")
		(net "FM_P3V3_CPLD_EN")
	)
	(segment
		(start 475.679262 -53.206904)
		(end 475.231206 -53.206904)
		(width 0.089408)
		(layer "In4.Cu")
		(net "FM_P3V3_CPLD_EN")
	)
	(segment
		(start 474.631512 -55.702962)
		(end 473.922598 -56.411876)
		(width 0.089408)
		(layer "In4.Cu")
		(net "FM_P3V3_CPLD_EN")
	)
	(segment
		(start 469.943688 -56.411876)
		(end 469.146382 -55.61457)
		(width 0.089408)
		(layer "In4.Cu")
		(net "FM_P3V3_CPLD_EN")
	)
	(segment
		(start 391.16889 -66.337688)
		(end 394.589 -66.337688)
		(width 0.089408)
		(layer "In4.Cu")
		(net "FM_P3V3_CPLD_EN")
	)
	(segment
		(start 424.866054 -61.865002)
		(end 426.176694 -63.175642)
		(width 0.089408)
		(layer "In4.Cu")
		(net "FM_P3V3_CPLD_EN")
	)
	(segment
		(start 439.592974 -63.05042)
		(end 437.57596 -63.05042)
		(width 0.089408)
		(layer "In4.Cu")
		(net "FM_P3V3_CPLD_EN")
	)
	(segment
		(start 376.744738 -67.895216)
		(end 377.171458 -68.321936)
		(width 0.089408)
		(layer "In4.Cu")
		(net "FM_P3V3_CPLD_EN")
	)
	(segment
		(start 477.52127 -43.969178)
		(end 477.049592 -44.440856)
		(width 0.089408)
		(layer "In4.Cu")
		(net "FM_P3V3_CPLD_EN")
	)
	(segment
		(start 464.464908 -54.90083)
		(end 464.464908 -55.251096)
		(width 0.089408)
		(layer "In4.Cu")
		(net "FM_P3V3_CPLD_EN")
	)
	(segment
		(start 380.031752 -68.551298)
		(end 388.95528 -68.551298)
		(width 0.089408)
		(layer "In4.Cu")
		(net "FM_P3V3_CPLD_EN")
	)
	(segment
		(start 475.913704 -48.975772)
		(end 475.913704 -52.972462)
		(width 0.089408)
		(layer "In4.Cu")
		(net "FM_P3V3_CPLD_EN")
	)
	(segment
		(start 478.643696 -39.635938)
		(end 478.643696 -40.622728)
		(width 0.089408)
		(layer "In4.Cu")
		(net "FM_P3V3_CPLD_EN")
	)
	(segment
		(start 380.031498 -68.551044)
		(end 380.031752 -68.551298)
		(width 0.089408)
		(layer "In4.Cu")
		(net "FM_P3V3_CPLD_EN")
	)
	(segment
		(start 407.491692 -69.316092)
		(end 407.64968 -69.316092)
		(width 0.089408)
		(layer "In4.Cu")
		(net "FM_P3V3_CPLD_EN")
	)
	(segment
		(start 474.63329 -53.888132)
		(end 474.631512 -53.88991)
		(width 0.089408)
		(layer "In4.Cu")
		(net "FM_P3V3_CPLD_EN")
	)
	(segment
		(start 473.922598 -56.411876)
		(end 469.943688 -56.411876)
		(width 0.089408)
		(layer "In4.Cu")
		(net "FM_P3V3_CPLD_EN")
	)
	(segment
		(start 406.131014 -68.977764)
		(end 406.470866 -69.317616)
		(width 0.089408)
		(layer "In4.Cu")
		(net "FM_P3V3_CPLD_EN")
	)
	(segment
		(start 464.465162 -60.631578)
		(end 462.953608 -62.143132)
		(width 0.089408)
		(layer "In4.Cu")
		(net "FM_P3V3_CPLD_EN")
	)
	(segment
		(start 474.631512 -53.88991)
		(end 474.631512 -55.702962)
		(width 0.089408)
		(layer "In4.Cu")
		(net "FM_P3V3_CPLD_EN")
	)
	(segment
		(start 462.953608 -62.143132)
		(end 457.460858 -62.143132)
		(width 0.089408)
		(layer "In4.Cu")
		(net "FM_P3V3_CPLD_EN")
	)
	(segment
		(start 457.460858 -62.143132)
		(end 457.058522 -62.545468)
		(width 0.089408)
		(layer "In4.Cu")
		(net "FM_P3V3_CPLD_EN")
	)
	(segment
		(start 477.52127 -41.745154)
		(end 477.52127 -43.969178)
		(width 0.089408)
		(layer "In4.Cu")
		(net "FM_P3V3_CPLD_EN")
	)
	(segment
		(start 417.053522 -65.8368)
		(end 421.266874 -61.623448)
		(width 0.089408)
		(layer "In4.Cu")
		(net "FM_P3V3_CPLD_EN")
	)
	(segment
		(start 414.864296 -67.793616)
		(end 414.864296 -66.523616)
		(width 0.089408)
		(layer "In4.Cu")
		(net "FM_P3V3_CPLD_EN")
	)
	(segment
		(start 479.119946 -39.097712)
		(end 479.119946 -39.159688)
		(width 0.089408)
		(layer "In4.Cu")
		(net "FM_P3V3_CPLD_EN")
	)
	(segment
		(start 475.913704 -52.972462)
		(end 475.679262 -53.206904)
		(width 0.089408)
		(layer "In4.Cu")
		(net "FM_P3V3_CPLD_EN")
	)
	(segment
		(start 378.737876 -68.321936)
		(end 378.966984 -68.551044)
		(width 0.089408)
		(layer "In4.Cu")
		(net "FM_P3V3_CPLD_EN")
	)
	(segment
		(start 414.864296 -66.523616)
		(end 415.551112 -65.8368)
		(width 0.089408)
		(layer "In4.Cu")
		(net "FM_P3V3_CPLD_EN")
	)
	(segment
		(start 415.551112 -65.8368)
		(end 417.053522 -65.8368)
		(width 0.089408)
		(layer "In4.Cu")
		(net "FM_P3V3_CPLD_EN")
	)
	(segment
		(start 477.049592 -44.440856)
		(end 477.049592 -47.839884)
		(width 0.089408)
		(layer "In4.Cu")
		(net "FM_P3V3_CPLD_EN")
	)
	(segment
		(start 457.058522 -62.545468)
		(end 440.097926 -62.545468)
		(width 0.089408)
		(layer "In4.Cu")
		(net "FM_P3V3_CPLD_EN")
	)
	(segment
		(start 406.472644 -69.315838)
		(end 407.491438 -69.315838)
		(width 0.089408)
		(layer "In4.Cu")
		(net "FM_P3V3_CPLD_EN")
	)
	(segment
		(start 479.119946 -39.159688)
		(end 478.643696 -39.635938)
		(width 0.089408)
		(layer "In4.Cu")
		(net "FM_P3V3_CPLD_EN")
	)
	(segment
		(start 388.95528 -68.551298)
		(end 391.16889 -66.337688)
		(width 0.089408)
		(layer "In4.Cu")
		(net "FM_P3V3_CPLD_EN")
	)
	(segment
		(start 480.655884 -28.842716)
		(end 481.3935 -28.1051)
		(width 0.089408)
		(layer "In9.Cu")
		(net "FM_P3V3_CPLD_EN")
	)
	(segment
		(start 476.067882 -20.918678)
		(end 476.067882 -15.399004)
		(width 0.089408)
		(layer "In9.Cu")
		(net "FM_P3V3_CPLD_EN")
	)
	(segment
		(start 478.536254 -37.88537)
		(end 478.109534 -37.45865)
		(width 0.089408)
		(layer "In9.Cu")
		(net "FM_P3V3_CPLD_EN")
	)
	(segment
		(start 479.119946 -39.097712)
		(end 479.481388 -38.73627)
		(width 0.089408)
		(layer "In9.Cu")
		(net "FM_P3V3_CPLD_EN")
	)
	(segment
		(start 481.3935 -28.1051)
		(end 482.119178 -28.1051)
		(width 0.089408)
		(layer "In9.Cu")
		(net "FM_P3V3_CPLD_EN")
	)
	(segment
		(start 478.109534 -36.13658)
		(end 480.655884 -33.59023)
		(width 0.089408)
		(layer "In9.Cu")
		(net "FM_P3V3_CPLD_EN")
	)
	(segment
		(start 477.259396 -22.110192)
		(end 476.067882 -20.918678)
		(width 0.089408)
		(layer "In9.Cu")
		(net "FM_P3V3_CPLD_EN")
	)
	(segment
		(start 479.481388 -38.177216)
		(end 479.189542 -37.88537)
		(width 0.089408)
		(layer "In9.Cu")
		(net "FM_P3V3_CPLD_EN")
	)
	(segment
		(start 476.067882 -15.399004)
		(end 475.984824 -15.315946)
		(width 0.089408)
		(layer "In9.Cu")
		(net "FM_P3V3_CPLD_EN")
	)
	(segment
		(start 480.655884 -33.59023)
		(end 480.655884 -28.842716)
		(width 0.089408)
		(layer "In9.Cu")
		(net "FM_P3V3_CPLD_EN")
	)
	(segment
		(start 482.75875 -27.465528)
		(end 482.75875 -26.86812)
		(width 0.089408)
		(layer "In9.Cu")
		(net "FM_P3V3_CPLD_EN")
	)
	(segment
		(start 478.000822 -22.110192)
		(end 477.259396 -22.110192)
		(width 0.089408)
		(layer "In9.Cu")
		(net "FM_P3V3_CPLD_EN")
	)
	(segment
		(start 478.109534 -37.45865)
		(end 478.109534 -36.13658)
		(width 0.089408)
		(layer "In9.Cu")
		(net "FM_P3V3_CPLD_EN")
	)
	(segment
		(start 482.75875 -26.86812)
		(end 478.000822 -22.110192)
		(width 0.089408)
		(layer "In9.Cu")
		(net "FM_P3V3_CPLD_EN")
	)
	(segment
		(start 479.481388 -38.73627)
		(end 479.481388 -38.177216)
		(width 0.089408)
		(layer "In9.Cu")
		(net "FM_P3V3_CPLD_EN")
	)
	(segment
		(start 479.189542 -37.88537)
		(end 478.536254 -37.88537)
		(width 0.089408)
		(layer "In9.Cu")
		(net "FM_P3V3_CPLD_EN")
	)
	(segment
		(start 482.119178 -28.1051)
		(end 482.75875 -27.465528)
		(width 0.089408)
		(layer "In9.Cu")
		(net "FM_P3V3_CPLD_EN")
	)
	(segment
		(start 407.630122 -42.534586)
		(end 407.890218 -42.534586)
		(width 0.10795)
		(layer "F.Cu")
		(net "IRQ_PVCCIN_CPU1_VRHOT_LVC3_N")
	)
	(segment
		(start 406.580848 -42.954956)
		(end 407.209752 -42.954956)
		(width 0.10795)
		(layer "F.Cu")
		(net "IRQ_PVCCIN_CPU1_VRHOT_LVC3_N")
	)
	(segment
		(start 407.209752 -42.954956)
		(end 407.630122 -42.534586)
		(width 0.10795)
		(layer "F.Cu")
		(net "IRQ_PVCCIN_CPU1_VRHOT_LVC3_N")
	)
	(segment
		(start 405.801068 -43.734736)
		(end 406.580848 -42.954956)
		(width 0.10795)
		(layer "F.Cu")
		(net "IRQ_PVCCIN_CPU1_VRHOT_LVC3_N")
	)
	(via
		(at 405.801068 -43.734736)
		(size 0.4572)
		(drill 0.2032)
		(layers "F.Cu" "B.Cu")
		(net "IRQ_PVCCIN_CPU1_VRHOT_LVC3_N")
	)
	(via
		(at 378.82195 -113.519204)
		(size 0.508)
		(drill 0.254)
		(layers "F.Cu" "B.Cu")
		(net "IRQ_PVCCIN_CPU1_VRHOT_LVC3_N")
	)
	(via
		(at 404.7236 -109.7788)
		(size 0.508)
		(drill 0.254)
		(layers "F.Cu" "B.Cu")
		(net "IRQ_PVCCIN_CPU1_VRHOT_LVC3_N")
	)
	(via
		(at 359.183178 -113.605818)
		(size 0.508)
		(drill 0.254)
		(layers "F.Cu" "B.Cu")
		(net "IRQ_PVCCIN_CPU1_VRHOT_LVC3_N")
	)
	(via
		(at 14.3002 -85.979)
		(size 0.508)
		(drill 0.254)
		(layers "F.Cu" "B.Cu")
		(net "IRQ_PVCCIN_CPU1_VRHOT_LVC3_N")
	)
	(via
		(at 378.0282 -41.0718)
		(size 0.508)
		(drill 0.254)
		(layers "F.Cu" "B.Cu")
		(net "IRQ_PVCCIN_CPU1_VRHOT_LVC3_N")
	)
	(via
		(at 451.8406 -42.1132)
		(size 0.508)
		(drill 0.254)
		(layers "F.Cu" "B.Cu")
		(net "IRQ_PVCCIN_CPU1_VRHOT_LVC3_N")
	)
	(via
		(at 370.4082 -112.43945)
		(size 0.508)
		(drill 0.254)
		(layers "F.Cu" "B.Cu")
		(net "IRQ_PVCCIN_CPU1_VRHOT_LVC3_N")
	)
	(segment
		(start 378.0282 -41.251632)
		(end 377.1138 -42.166032)
		(width 0.10795)
		(layer "B.Cu")
		(net "IRQ_PVCCIN_CPU1_VRHOT_LVC3_N")
	)
	(segment
		(start 377.1138 -42.166032)
		(end 377.1138 -43.2308)
		(width 0.10795)
		(layer "B.Cu")
		(net "IRQ_PVCCIN_CPU1_VRHOT_LVC3_N")
	)
	(segment
		(start 377.758198 -44.00931)
		(end 377.7742 -44.025312)
		(width 0.10795)
		(layer "B.Cu")
		(net "IRQ_PVCCIN_CPU1_VRHOT_LVC3_N")
	)
	(segment
		(start 378.0282 -41.0718)
		(end 378.0282 -41.251632)
		(width 0.10795)
		(layer "B.Cu")
		(net "IRQ_PVCCIN_CPU1_VRHOT_LVC3_N")
	)
	(segment
		(start 377.1138 -43.2308)
		(end 377.758198 -43.875198)
		(width 0.10795)
		(layer "B.Cu")
		(net "IRQ_PVCCIN_CPU1_VRHOT_LVC3_N")
	)
	(segment
		(start 377.758198 -43.875198)
		(end 377.758198 -44.00931)
		(width 0.10795)
		(layer "B.Cu")
		(net "IRQ_PVCCIN_CPU1_VRHOT_LVC3_N")
	)
	(segment
		(start 377.317 -47.3583)
		(end 377.018296 -47.657004)
		(width 0.10795)
		(layer "B.Cu")
		(net "IRQ_PVCCIN_CPU1_VRHOT_LVC3_N")
	)
	(segment
		(start 377.7742 -46.482)
		(end 377.317 -46.9392)
		(width 0.10795)
		(layer "B.Cu")
		(net "IRQ_PVCCIN_CPU1_VRHOT_LVC3_N")
	)
	(segment
		(start 14.478 -86.741)
		(end 14.3002 -86.5632)
		(width 0.10795)
		(layer "B.Cu")
		(net "IRQ_PVCCIN_CPU1_VRHOT_LVC3_N")
	)
	(segment
		(start 377.7742 -44.025312)
		(end 377.7742 -46.482)
		(width 0.10795)
		(layer "B.Cu")
		(net "IRQ_PVCCIN_CPU1_VRHOT_LVC3_N")
	)
	(segment
		(start 377.317 -46.9392)
		(end 377.317 -47.3583)
		(width 0.10795)
		(layer "B.Cu")
		(net "IRQ_PVCCIN_CPU1_VRHOT_LVC3_N")
	)
	(segment
		(start 14.3002 -86.5632)
		(end 14.3002 -85.979)
		(width 0.10795)
		(layer "B.Cu")
		(net "IRQ_PVCCIN_CPU1_VRHOT_LVC3_N")
	)
	(segment
		(start 377.018296 -47.657004)
		(end 376.418348 -47.657004)
		(width 0.10795)
		(layer "B.Cu")
		(net "IRQ_PVCCIN_CPU1_VRHOT_LVC3_N")
	)
	(segment
		(start 378.4346 -113.792)
		(end 375.9454 -113.792)
		(width 0.089408)
		(layer "In2.Cu")
		(net "IRQ_PVCCIN_CPU1_VRHOT_LVC3_N")
	)
	(segment
		(start 378.82195 -113.519204)
		(end 378.707396 -113.519204)
		(width 0.089408)
		(layer "In2.Cu")
		(net "IRQ_PVCCIN_CPU1_VRHOT_LVC3_N")
	)
	(segment
		(start 374.59285 -112.43945)
		(end 370.4082 -112.43945)
		(width 0.089408)
		(layer "In2.Cu")
		(net "IRQ_PVCCIN_CPU1_VRHOT_LVC3_N")
	)
	(segment
		(start 378.707396 -113.519204)
		(end 378.4346 -113.792)
		(width 0.089408)
		(layer "In2.Cu")
		(net "IRQ_PVCCIN_CPU1_VRHOT_LVC3_N")
	)
	(segment
		(start 375.9454 -113.792)
		(end 374.59285 -112.43945)
		(width 0.089408)
		(layer "In2.Cu")
		(net "IRQ_PVCCIN_CPU1_VRHOT_LVC3_N")
	)
	(segment
		(start 384.666236 -115.006628)
		(end 385.109974 -115.450366)
		(width 0.089408)
		(layer "In4.Cu")
		(net "IRQ_PVCCIN_CPU1_VRHOT_LVC3_N")
	)
	(segment
		(start 405.323294 -44.109386)
		(end 405.697944 -43.734736)
		(width 0.089408)
		(layer "In4.Cu")
		(net "IRQ_PVCCIN_CPU1_VRHOT_LVC3_N")
	)
	(segment
		(start 385.109974 -115.450366)
		(end 387.43001 -115.450366)
		(width 0.089408)
		(layer "In4.Cu")
		(net "IRQ_PVCCIN_CPU1_VRHOT_LVC3_N")
	)
	(segment
		(start 378.82195 -113.519204)
		(end 378.732542 -113.608612)
		(width 0.089408)
		(layer "In4.Cu")
		(net "IRQ_PVCCIN_CPU1_VRHOT_LVC3_N")
	)
	(segment
		(start 393.37869 -113.978944)
		(end 394.420344 -113.978944)
		(width 0.089408)
		(layer "In4.Cu")
		(net "IRQ_PVCCIN_CPU1_VRHOT_LVC3_N")
	)
	(segment
		(start 378.0282 -41.0718)
		(end 378.0282 -40.8178)
		(width 0.089408)
		(layer "In4.Cu")
		(net "IRQ_PVCCIN_CPU1_VRHOT_LVC3_N")
	)
	(segment
		(start 413.365442 -45.10151)
		(end 412.720536 -45.746416)
		(width 0.089408)
		(layer "In4.Cu")
		(net "IRQ_PVCCIN_CPU1_VRHOT_LVC3_N")
	)
	(segment
		(start 377.627896 -36.719256)
		(end 377.968256 -36.378896)
		(width 0.089408)
		(layer "In4.Cu")
		(net "IRQ_PVCCIN_CPU1_VRHOT_LVC3_N")
	)
	(segment
		(start 378.732542 -114.584734)
		(end 378.985272 -114.837464)
		(width 0.089408)
		(layer "In4.Cu")
		(net "IRQ_PVCCIN_CPU1_VRHOT_LVC3_N")
	)
	(segment
		(start 434.23078 -41.49598)
		(end 433.47767 -41.49598)
		(width 0.089408)
		(layer "In4.Cu")
		(net "IRQ_PVCCIN_CPU1_VRHOT_LVC3_N")
	)
	(segment
		(start 393.511278 -40.367712)
		(end 395.961108 -40.367712)
		(width 0.089408)
		(layer "In4.Cu")
		(net "IRQ_PVCCIN_CPU1_VRHOT_LVC3_N")
	)
	(segment
		(start 430.6062 -40.8813)
		(end 430.13503 -40.8813)
		(width 0.089408)
		(layer "In4.Cu")
		(net "IRQ_PVCCIN_CPU1_VRHOT_LVC3_N")
	)
	(segment
		(start 423.838624 -44.272454)
		(end 423.29608 -44.272454)
		(width 0.089408)
		(layer "In4.Cu")
		(net "IRQ_PVCCIN_CPU1_VRHOT_LVC3_N")
	)
	(segment
		(start 377.968256 -36.378896)
		(end 378.397262 -36.378896)
		(width 0.089408)
		(layer "In4.Cu")
		(net "IRQ_PVCCIN_CPU1_VRHOT_LVC3_N")
	)
	(segment
		(start 424.126152 -43.984926)
		(end 423.838624 -44.272454)
		(width 0.089408)
		(layer "In4.Cu")
		(net "IRQ_PVCCIN_CPU1_VRHOT_LVC3_N")
	)
	(segment
		(start 404.98522 -44.10964)
		(end 405.296116 -44.10964)
		(width 0.089408)
		(layer "In4.Cu")
		(net "IRQ_PVCCIN_CPU1_VRHOT_LVC3_N")
	)
	(segment
		(start 428.294546 -40.427148)
		(end 426.223176 -42.498518)
		(width 0.089408)
		(layer "In4.Cu")
		(net "IRQ_PVCCIN_CPU1_VRHOT_LVC3_N")
	)
	(segment
		(start 418.775134 -45.10151)
		(end 413.365442 -45.10151)
		(width 0.089408)
		(layer "In4.Cu")
		(net "IRQ_PVCCIN_CPU1_VRHOT_LVC3_N")
	)
	(segment
		(start 382.074166 -38.128702)
		(end 383.196592 -37.006276)
		(width 0.089408)
		(layer "In4.Cu")
		(net "IRQ_PVCCIN_CPU1_VRHOT_LVC3_N")
	)
	(segment
		(start 404.7236 -110.1598)
		(end 404.7236 -109.7788)
		(width 0.089408)
		(layer "In4.Cu")
		(net "IRQ_PVCCIN_CPU1_VRHOT_LVC3_N")
	)
	(segment
		(start 408.383232 -46.49343)
		(end 407.990548 -46.100746)
		(width 0.089408)
		(layer "In4.Cu")
		(net "IRQ_PVCCIN_CPU1_VRHOT_LVC3_N")
	)
	(segment
		(start 379.64745 -38.652704)
		(end 380.123446 -38.652704)
		(width 0.089408)
		(layer "In4.Cu")
		(net "IRQ_PVCCIN_CPU1_VRHOT_LVC3_N")
	)
	(segment
		(start 402.603716 -44.109386)
		(end 404.984966 -44.109386)
		(width 0.089408)
		(layer "In4.Cu")
		(net "IRQ_PVCCIN_CPU1_VRHOT_LVC3_N")
	)
	(segment
		(start 387.813804 -115.066572)
		(end 387.995668 -115.066572)
		(width 0.089408)
		(layer "In4.Cu")
		(net "IRQ_PVCCIN_CPU1_VRHOT_LVC3_N")
	)
	(segment
		(start 423.160698 -44.407836)
		(end 420.396162 -44.407836)
		(width 0.089408)
		(layer "In4.Cu")
		(net "IRQ_PVCCIN_CPU1_VRHOT_LVC3_N")
	)
	(segment
		(start 378.397262 -36.378896)
		(end 379.178058 -37.159692)
		(width 0.089408)
		(layer "In4.Cu")
		(net "IRQ_PVCCIN_CPU1_VRHOT_LVC3_N")
	)
	(segment
		(start 387.43001 -115.450366)
		(end 387.813804 -115.066572)
		(width 0.089408)
		(layer "In4.Cu")
		(net "IRQ_PVCCIN_CPU1_VRHOT_LVC3_N")
	)
	(segment
		(start 423.29608 -44.272454)
		(end 423.160698 -44.407836)
		(width 0.089408)
		(layer "In4.Cu")
		(net "IRQ_PVCCIN_CPU1_VRHOT_LVC3_N")
	)
	(segment
		(start 404.984966 -44.109386)
		(end 404.98522 -44.10964)
		(width 0.089408)
		(layer "In4.Cu")
		(net "IRQ_PVCCIN_CPU1_VRHOT_LVC3_N")
	)
	(segment
		(start 401.2438 -42.74947)
		(end 402.603716 -44.109386)
		(width 0.089408)
		(layer "In4.Cu")
		(net "IRQ_PVCCIN_CPU1_VRHOT_LVC3_N")
	)
	(segment
		(start 406.521666 -44.455334)
		(end 405.801068 -43.734736)
		(width 0.089408)
		(layer "In4.Cu")
		(net "IRQ_PVCCIN_CPU1_VRHOT_LVC3_N")
	)
	(segment
		(start 391.3378 -38.989)
		(end 392.132566 -38.989)
		(width 0.089408)
		(layer "In4.Cu")
		(net "IRQ_PVCCIN_CPU1_VRHOT_LVC3_N")
	)
	(segment
		(start 405.697944 -43.734736)
		(end 405.801068 -43.734736)
		(width 0.089408)
		(layer "In4.Cu")
		(net "IRQ_PVCCIN_CPU1_VRHOT_LVC3_N")
	)
	(segment
		(start 420.045134 -44.758864)
		(end 419.11778 -44.758864)
		(width 0.089408)
		(layer "In4.Cu")
		(net "IRQ_PVCCIN_CPU1_VRHOT_LVC3_N")
	)
	(segment
		(start 396.32382 -40.005)
		(end 397.563086 -40.005)
		(width 0.089408)
		(layer "In4.Cu")
		(net "IRQ_PVCCIN_CPU1_VRHOT_LVC3_N")
	)
	(segment
		(start 419.11778 -44.758864)
		(end 418.775134 -45.10151)
		(width 0.089408)
		(layer "In4.Cu")
		(net "IRQ_PVCCIN_CPU1_VRHOT_LVC3_N")
	)
	(segment
		(start 397.563086 -40.005)
		(end 400.307556 -42.74947)
		(width 0.089408)
		(layer "In4.Cu")
		(net "IRQ_PVCCIN_CPU1_VRHOT_LVC3_N")
	)
	(segment
		(start 380.647448 -38.128702)
		(end 382.074166 -38.128702)
		(width 0.089408)
		(layer "In4.Cu")
		(net "IRQ_PVCCIN_CPU1_VRHOT_LVC3_N")
	)
	(segment
		(start 430.13503 -40.8813)
		(end 429.680878 -40.427148)
		(width 0.089408)
		(layer "In4.Cu")
		(net "IRQ_PVCCIN_CPU1_VRHOT_LVC3_N")
	)
	(segment
		(start 410.66593 -45.746416)
		(end 409.918916 -46.49343)
		(width 0.089408)
		(layer "In4.Cu")
		(net "IRQ_PVCCIN_CPU1_VRHOT_LVC3_N")
	)
	(segment
		(start 420.396162 -44.407836)
		(end 420.045134 -44.758864)
		(width 0.089408)
		(layer "In4.Cu")
		(net "IRQ_PVCCIN_CPU1_VRHOT_LVC3_N")
	)
	(segment
		(start 429.680878 -40.427148)
		(end 428.294546 -40.427148)
		(width 0.089408)
		(layer "In4.Cu")
		(net "IRQ_PVCCIN_CPU1_VRHOT_LVC3_N")
	)
	(segment
		(start 405.29637 -44.109386)
		(end 405.323294 -44.109386)
		(width 0.089408)
		(layer "In4.Cu")
		(net "IRQ_PVCCIN_CPU1_VRHOT_LVC3_N")
	)
	(segment
		(start 383.062988 -114.854736)
		(end 383.21488 -115.006628)
		(width 0.089408)
		(layer "In4.Cu")
		(net "IRQ_PVCCIN_CPU1_VRHOT_LVC3_N")
	)
	(segment
		(start 402.043138 -113.925604)
		(end 402.42109 -113.547652)
		(width 0.089408)
		(layer "In4.Cu")
		(net "IRQ_PVCCIN_CPU1_VRHOT_LVC3_N")
	)
	(segment
		(start 409.918916 -46.49343)
		(end 408.383232 -46.49343)
		(width 0.089408)
		(layer "In4.Cu")
		(net "IRQ_PVCCIN_CPU1_VRHOT_LVC3_N")
	)
	(segment
		(start 379.178058 -37.159692)
		(end 379.178058 -38.183312)
		(width 0.089408)
		(layer "In4.Cu")
		(net "IRQ_PVCCIN_CPU1_VRHOT_LVC3_N")
	)
	(segment
		(start 402.42109 -112.46231)
		(end 404.7236 -110.1598)
		(width 0.089408)
		(layer "In4.Cu")
		(net "IRQ_PVCCIN_CPU1_VRHOT_LVC3_N")
	)
	(segment
		(start 451.8406 -42.1132)
		(end 451.608444 -41.881044)
		(width 0.089408)
		(layer "In4.Cu")
		(net "IRQ_PVCCIN_CPU1_VRHOT_LVC3_N")
	)
	(segment
		(start 383.196592 -37.006276)
		(end 383.911094 -37.006276)
		(width 0.089408)
		(layer "In4.Cu")
		(net "IRQ_PVCCIN_CPU1_VRHOT_LVC3_N")
	)
	(segment
		(start 424.126152 -42.9133)
		(end 424.126152 -43.984926)
		(width 0.089408)
		(layer "In4.Cu")
		(net "IRQ_PVCCIN_CPU1_VRHOT_LVC3_N")
	)
	(segment
		(start 378.985272 -114.837464)
		(end 380.968504 -114.837464)
		(width 0.089408)
		(layer "In4.Cu")
		(net "IRQ_PVCCIN_CPU1_VRHOT_LVC3_N")
	)
	(segment
		(start 380.123446 -38.652704)
		(end 380.647448 -38.128702)
		(width 0.089408)
		(layer "In4.Cu")
		(net "IRQ_PVCCIN_CPU1_VRHOT_LVC3_N")
	)
	(segment
		(start 390.087104 -37.738304)
		(end 391.3378 -38.989)
		(width 0.089408)
		(layer "In4.Cu")
		(net "IRQ_PVCCIN_CPU1_VRHOT_LVC3_N")
	)
	(segment
		(start 426.223176 -42.498518)
		(end 424.540934 -42.498518)
		(width 0.089408)
		(layer "In4.Cu")
		(net "IRQ_PVCCIN_CPU1_VRHOT_LVC3_N")
	)
	(segment
		(start 383.21488 -115.006628)
		(end 384.666236 -115.006628)
		(width 0.089408)
		(layer "In4.Cu")
		(net "IRQ_PVCCIN_CPU1_VRHOT_LVC3_N")
	)
	(segment
		(start 388.32536 -115.066572)
		(end 392.291062 -115.066572)
		(width 0.089408)
		(layer "In4.Cu")
		(net "IRQ_PVCCIN_CPU1_VRHOT_LVC3_N")
	)
	(segment
		(start 383.911094 -37.006276)
		(end 384.142488 -36.774882)
		(width 0.089408)
		(layer "In4.Cu")
		(net "IRQ_PVCCIN_CPU1_VRHOT_LVC3_N")
	)
	(segment
		(start 395.4272 -114.4778)
		(end 395.979396 -113.925604)
		(width 0.089408)
		(layer "In4.Cu")
		(net "IRQ_PVCCIN_CPU1_VRHOT_LVC3_N")
	)
	(segment
		(start 407.990548 -45.482256)
		(end 406.963626 -44.455334)
		(width 0.089408)
		(layer "In4.Cu")
		(net "IRQ_PVCCIN_CPU1_VRHOT_LVC3_N")
	)
	(segment
		(start 380.985776 -114.854736)
		(end 383.062988 -114.854736)
		(width 0.089408)
		(layer "In4.Cu")
		(net "IRQ_PVCCIN_CPU1_VRHOT_LVC3_N")
	)
	(segment
		(start 405.296116 -44.10964)
		(end 405.29637 -44.109386)
		(width 0.089408)
		(layer "In4.Cu")
		(net "IRQ_PVCCIN_CPU1_VRHOT_LVC3_N")
	)
	(segment
		(start 388.958328 -37.738304)
		(end 390.087104 -37.738304)
		(width 0.089408)
		(layer "In4.Cu")
		(net "IRQ_PVCCIN_CPU1_VRHOT_LVC3_N")
	)
	(segment
		(start 412.720536 -45.746416)
		(end 410.66593 -45.746416)
		(width 0.089408)
		(layer "In4.Cu")
		(net "IRQ_PVCCIN_CPU1_VRHOT_LVC3_N")
	)
	(segment
		(start 433.051966 -41.921684)
		(end 431.646584 -41.921684)
		(width 0.089408)
		(layer "In4.Cu")
		(net "IRQ_PVCCIN_CPU1_VRHOT_LVC3_N")
	)
	(segment
		(start 392.291062 -115.066572)
		(end 393.37869 -113.978944)
		(width 0.089408)
		(layer "In4.Cu")
		(net "IRQ_PVCCIN_CPU1_VRHOT_LVC3_N")
	)
	(segment
		(start 400.307556 -42.74947)
		(end 401.2438 -42.74947)
		(width 0.089408)
		(layer "In4.Cu")
		(net "IRQ_PVCCIN_CPU1_VRHOT_LVC3_N")
	)
	(segment
		(start 377.627896 -40.417496)
		(end 377.627896 -36.719256)
		(width 0.089408)
		(layer "In4.Cu")
		(net "IRQ_PVCCIN_CPU1_VRHOT_LVC3_N")
	)
	(segment
		(start 433.47767 -41.49598)
		(end 433.051966 -41.921684)
		(width 0.089408)
		(layer "In4.Cu")
		(net "IRQ_PVCCIN_CPU1_VRHOT_LVC3_N")
	)
	(segment
		(start 388.314692 -115.055904)
		(end 388.32536 -115.066572)
		(width 0.089408)
		(layer "In4.Cu")
		(net "IRQ_PVCCIN_CPU1_VRHOT_LVC3_N")
	)
	(segment
		(start 424.540934 -42.498518)
		(end 424.126152 -42.9133)
		(width 0.089408)
		(layer "In4.Cu")
		(net "IRQ_PVCCIN_CPU1_VRHOT_LVC3_N")
	)
	(segment
		(start 406.963626 -44.455334)
		(end 406.521666 -44.455334)
		(width 0.089408)
		(layer "In4.Cu")
		(net "IRQ_PVCCIN_CPU1_VRHOT_LVC3_N")
	)
	(segment
		(start 394.9192 -114.4778)
		(end 395.4272 -114.4778)
		(width 0.089408)
		(layer "In4.Cu")
		(net "IRQ_PVCCIN_CPU1_VRHOT_LVC3_N")
	)
	(segment
		(start 451.608444 -41.881044)
		(end 434.615844 -41.881044)
		(width 0.089408)
		(layer "In4.Cu")
		(net "IRQ_PVCCIN_CPU1_VRHOT_LVC3_N")
	)
	(segment
		(start 378.0282 -40.8178)
		(end 377.627896 -40.417496)
		(width 0.089408)
		(layer "In4.Cu")
		(net "IRQ_PVCCIN_CPU1_VRHOT_LVC3_N")
	)
	(segment
		(start 431.646584 -41.921684)
		(end 430.6062 -40.8813)
		(width 0.089408)
		(layer "In4.Cu")
		(net "IRQ_PVCCIN_CPU1_VRHOT_LVC3_N")
	)
	(segment
		(start 379.178058 -38.183312)
		(end 379.64745 -38.652704)
		(width 0.089408)
		(layer "In4.Cu")
		(net "IRQ_PVCCIN_CPU1_VRHOT_LVC3_N")
	)
	(segment
		(start 387.995668 -115.066572)
		(end 388.006336 -115.055904)
		(width 0.089408)
		(layer "In4.Cu")
		(net "IRQ_PVCCIN_CPU1_VRHOT_LVC3_N")
	)
	(segment
		(start 392.132566 -38.989)
		(end 393.511278 -40.367712)
		(width 0.089408)
		(layer "In4.Cu")
		(net "IRQ_PVCCIN_CPU1_VRHOT_LVC3_N")
	)
	(segment
		(start 378.732542 -113.608612)
		(end 378.732542 -114.584734)
		(width 0.089408)
		(layer "In4.Cu")
		(net "IRQ_PVCCIN_CPU1_VRHOT_LVC3_N")
	)
	(segment
		(start 394.420344 -113.978944)
		(end 394.9192 -114.4778)
		(width 0.089408)
		(layer "In4.Cu")
		(net "IRQ_PVCCIN_CPU1_VRHOT_LVC3_N")
	)
	(segment
		(start 434.615844 -41.881044)
		(end 434.23078 -41.49598)
		(width 0.089408)
		(layer "In4.Cu")
		(net "IRQ_PVCCIN_CPU1_VRHOT_LVC3_N")
	)
	(segment
		(start 395.961108 -40.367712)
		(end 396.32382 -40.005)
		(width 0.089408)
		(layer "In4.Cu")
		(net "IRQ_PVCCIN_CPU1_VRHOT_LVC3_N")
	)
	(segment
		(start 407.990548 -46.100746)
		(end 407.990548 -45.482256)
		(width 0.089408)
		(layer "In4.Cu")
		(net "IRQ_PVCCIN_CPU1_VRHOT_LVC3_N")
	)
	(segment
		(start 402.42109 -113.547652)
		(end 402.42109 -112.46231)
		(width 0.089408)
		(layer "In4.Cu")
		(net "IRQ_PVCCIN_CPU1_VRHOT_LVC3_N")
	)
	(segment
		(start 380.968504 -114.837464)
		(end 380.985776 -114.854736)
		(width 0.089408)
		(layer "In4.Cu")
		(net "IRQ_PVCCIN_CPU1_VRHOT_LVC3_N")
	)
	(segment
		(start 388.006336 -115.055904)
		(end 388.314692 -115.055904)
		(width 0.089408)
		(layer "In4.Cu")
		(net "IRQ_PVCCIN_CPU1_VRHOT_LVC3_N")
	)
	(segment
		(start 387.994906 -36.774882)
		(end 388.958328 -37.738304)
		(width 0.089408)
		(layer "In4.Cu")
		(net "IRQ_PVCCIN_CPU1_VRHOT_LVC3_N")
	)
	(segment
		(start 395.979396 -113.925604)
		(end 402.043138 -113.925604)
		(width 0.089408)
		(layer "In4.Cu")
		(net "IRQ_PVCCIN_CPU1_VRHOT_LVC3_N")
	)
	(segment
		(start 384.142488 -36.774882)
		(end 387.994906 -36.774882)
		(width 0.089408)
		(layer "In4.Cu")
		(net "IRQ_PVCCIN_CPU1_VRHOT_LVC3_N")
	)
	(segment
		(start 325.10603 -123.406916)
		(end 323.511164 -125.001782)
		(width 0.089408)
		(layer "In9.Cu")
		(net "IRQ_PVCCIN_CPU1_VRHOT_LVC3_N")
	)
	(segment
		(start 357.11511 -114.551206)
		(end 356.06863 -114.551206)
		(width 0.089408)
		(layer "In9.Cu")
		(net "IRQ_PVCCIN_CPU1_VRHOT_LVC3_N")
	)
	(segment
		(start 433.45735 -43.609006)
		(end 432.114706 -44.95165)
		(width 0.089408)
		(layer "In9.Cu")
		(net "IRQ_PVCCIN_CPU1_VRHOT_LVC3_N")
	)
	(segment
		(start 414.57499 -51.278028)
		(end 409.78328 -56.069738)
		(width 0.089408)
		(layer "In9.Cu")
		(net "IRQ_PVCCIN_CPU1_VRHOT_LVC3_N")
	)
	(segment
		(start 347.43644 -119.151908)
		(end 340.752938 -119.151908)
		(width 0.089408)
		(layer "In9.Cu")
		(net "IRQ_PVCCIN_CPU1_VRHOT_LVC3_N")
	)
	(segment
		(start 398.526 -86.418166)
		(end 397.288766 -87.6554)
		(width 0.089408)
		(layer "In9.Cu")
		(net "IRQ_PVCCIN_CPU1_VRHOT_LVC3_N")
	)
	(segment
		(start 358.060498 -113.605818)
		(end 357.11511 -114.551206)
		(width 0.089408)
		(layer "In9.Cu")
		(net "IRQ_PVCCIN_CPU1_VRHOT_LVC3_N")
	)
	(segment
		(start 400.812508 -82.371692)
		(end 399.542 -83.6422)
		(width 0.089408)
		(layer "In9.Cu")
		(net "IRQ_PVCCIN_CPU1_VRHOT_LVC3_N")
	)
	(segment
		(start 436.721758 -42.573194)
		(end 435.685946 -43.609006)
		(width 0.089408)
		(layer "In9.Cu")
		(net "IRQ_PVCCIN_CPU1_VRHOT_LVC3_N")
	)
	(segment
		(start 165.947852 -125.616208)
		(end 163.284916 -125.616208)
		(width 0.089408)
		(layer "In9.Cu")
		(net "IRQ_PVCCIN_CPU1_VRHOT_LVC3_N")
	)
	(segment
		(start 403.2377 -77.4319)
		(end 402.431504 -78.238096)
		(width 0.089408)
		(layer "In9.Cu")
		(net "IRQ_PVCCIN_CPU1_VRHOT_LVC3_N")
	)
	(segment
		(start 390.61263 -98.58883)
		(end 391.60323 -99.57943)
		(width 0.089408)
		(layer "In9.Cu")
		(net "IRQ_PVCCIN_CPU1_VRHOT_LVC3_N")
	)
	(segment
		(start 152.570688 -127.512064)
		(end 147.491196 -122.432572)
		(width 0.089408)
		(layer "In9.Cu")
		(net "IRQ_PVCCIN_CPU1_VRHOT_LVC3_N")
	)
	(segment
		(start 394.723366 -106.816652)
		(end 394.723366 -107.754166)
		(width 0.089408)
		(layer "In9.Cu")
		(net "IRQ_PVCCIN_CPU1_VRHOT_LVC3_N")
	)
	(segment
		(start 402.326094 -109.458506)
		(end 404.403306 -109.458506)
		(width 0.089408)
		(layer "In9.Cu")
		(net "IRQ_PVCCIN_CPU1_VRHOT_LVC3_N")
	)
	(segment
		(start 393.77747 -105.870756)
		(end 394.723366 -106.816652)
		(width 0.089408)
		(layer "In9.Cu")
		(net "IRQ_PVCCIN_CPU1_VRHOT_LVC3_N")
	)
	(segment
		(start 435.685946 -43.609006)
		(end 433.45735 -43.609006)
		(width 0.089408)
		(layer "In9.Cu")
		(net "IRQ_PVCCIN_CPU1_VRHOT_LVC3_N")
	)
	(segment
		(start 166.058596 -125.726952)
		(end 165.947852 -125.616208)
		(width 0.089408)
		(layer "In9.Cu")
		(net "IRQ_PVCCIN_CPU1_VRHOT_LVC3_N")
	)
	(segment
		(start 397.045434 -87.6554)
		(end 392.9888 -91.712034)
		(width 0.089408)
		(layer "In9.Cu")
		(net "IRQ_PVCCIN_CPU1_VRHOT_LVC3_N")
	)
	(segment
		(start 399.542 -84.963)
		(end 398.526 -85.979)
		(width 0.089408)
		(layer "In9.Cu")
		(net "IRQ_PVCCIN_CPU1_VRHOT_LVC3_N")
	)
	(segment
		(start 355.6 -115.019836)
		(end 355.6 -116.6114)
		(width 0.089408)
		(layer "In9.Cu")
		(net "IRQ_PVCCIN_CPU1_VRHOT_LVC3_N")
	)
	(segment
		(start 328.996802 -122.749056)
		(end 328.338942 -123.406916)
		(width 0.089408)
		(layer "In9.Cu")
		(net "IRQ_PVCCIN_CPU1_VRHOT_LVC3_N")
	)
	(segment
		(start 402.08073 -79.790036)
		(end 401.54098 -79.790036)
		(width 0.089408)
		(layer "In9.Cu")
		(net "IRQ_PVCCIN_CPU1_VRHOT_LVC3_N")
	)
	(segment
		(start 394.145008 -104.677972)
		(end 393.77747 -105.04551)
		(width 0.089408)
		(layer "In9.Cu")
		(net "IRQ_PVCCIN_CPU1_VRHOT_LVC3_N")
	)
	(segment
		(start 166.897558 -126.402592)
		(end 166.221918 -125.726952)
		(width 0.089408)
		(layer "In9.Cu")
		(net "IRQ_PVCCIN_CPU1_VRHOT_LVC3_N")
	)
	(segment
		(start 166.221918 -125.726952)
		(end 166.058596 -125.726952)
		(width 0.089408)
		(layer "In9.Cu")
		(net "IRQ_PVCCIN_CPU1_VRHOT_LVC3_N")
	)
	(segment
		(start 421.5638 -47.7774)
		(end 418.063172 -51.278028)
		(width 0.089408)
		(layer "In9.Cu")
		(net "IRQ_PVCCIN_CPU1_VRHOT_LVC3_N")
	)
	(segment
		(start 355.6 -116.6114)
		(end 355.45268 -116.75872)
		(width 0.089408)
		(layer "In9.Cu")
		(net "IRQ_PVCCIN_CPU1_VRHOT_LVC3_N")
	)
	(segment
		(start 223.938084 -123.056396)
		(end 222.480632 -124.513848)
		(width 0.089408)
		(layer "In9.Cu")
		(net "IRQ_PVCCIN_CPU1_VRHOT_LVC3_N")
	)
	(segment
		(start 13.166344 -96.34855)
		(end 13.166344 -91.877642)
		(width 0.089408)
		(layer "In9.Cu")
		(net "IRQ_PVCCIN_CPU1_VRHOT_LVC3_N")
	)
	(segment
		(start 401.760944 -110.023656)
		(end 402.326094 -109.458506)
		(width 0.089408)
		(layer "In9.Cu")
		(net "IRQ_PVCCIN_CPU1_VRHOT_LVC3_N")
	)
	(segment
		(start 24.279352 -114.653568)
		(end 18.424144 -108.79836)
		(width 0.089408)
		(layer "In9.Cu")
		(net "IRQ_PVCCIN_CPU1_VRHOT_LVC3_N")
	)
	(segment
		(start 356.06863 -114.551206)
		(end 355.6 -115.019836)
		(width 0.089408)
		(layer "In9.Cu")
		(net "IRQ_PVCCIN_CPU1_VRHOT_LVC3_N")
	)
	(segment
		(start 395.67866 -108.70946)
		(end 395.67866 -109.21492)
		(width 0.089408)
		(layer "In9.Cu")
		(net "IRQ_PVCCIN_CPU1_VRHOT_LVC3_N")
	)
	(segment
		(start 244.61978 -123.786392)
		(end 243.889784 -123.056396)
		(width 0.089408)
		(layer "In9.Cu")
		(net "IRQ_PVCCIN_CPU1_VRHOT_LVC3_N")
	)
	(segment
		(start 422.6814 -47.7774)
		(end 421.5638 -47.7774)
		(width 0.089408)
		(layer "In9.Cu")
		(net "IRQ_PVCCIN_CPU1_VRHOT_LVC3_N")
	)
	(segment
		(start 13.858494 -86.961472)
		(end 14.3002 -86.519766)
		(width 0.089408)
		(layer "In9.Cu")
		(net "IRQ_PVCCIN_CPU1_VRHOT_LVC3_N")
	)
	(segment
		(start 13.858494 -91.185492)
		(end 13.858494 -86.961472)
		(width 0.089408)
		(layer "In9.Cu")
		(net "IRQ_PVCCIN_CPU1_VRHOT_LVC3_N")
	)
	(segment
		(start 409.988258 -67.261232)
		(end 407.270204 -69.979286)
		(width 0.089408)
		(layer "In9.Cu")
		(net "IRQ_PVCCIN_CPU1_VRHOT_LVC3_N")
	)
	(segment
		(start 16.892524 -98.696018)
		(end 15.513812 -98.696018)
		(width 0.089408)
		(layer "In9.Cu")
		(net "IRQ_PVCCIN_CPU1_VRHOT_LVC3_N")
	)
	(segment
		(start 392.9888 -91.712034)
		(end 392.9888 -93.0148)
		(width 0.089408)
		(layer "In9.Cu")
		(net "IRQ_PVCCIN_CPU1_VRHOT_LVC3_N")
	)
	(segment
		(start 13.166344 -91.877642)
		(end 13.858494 -91.185492)
		(width 0.089408)
		(layer "In9.Cu")
		(net "IRQ_PVCCIN_CPU1_VRHOT_LVC3_N")
	)
	(segment
		(start 409.78328 -60.80887)
		(end 409.988258 -61.013848)
		(width 0.089408)
		(layer "In9.Cu")
		(net "IRQ_PVCCIN_CPU1_VRHOT_LVC3_N")
	)
	(segment
		(start 451.8406 -42.1132)
		(end 451.380606 -42.573194)
		(width 0.089408)
		(layer "In9.Cu")
		(net "IRQ_PVCCIN_CPU1_VRHOT_LVC3_N")
	)
	(segment
		(start 337.15579 -122.749056)
		(end 328.996802 -122.749056)
		(width 0.089408)
		(layer "In9.Cu")
		(net "IRQ_PVCCIN_CPU1_VRHOT_LVC3_N")
	)
	(segment
		(start 426.19041 -46.060614)
		(end 424.398186 -46.060614)
		(width 0.089408)
		(layer "In9.Cu")
		(net "IRQ_PVCCIN_CPU1_VRHOT_LVC3_N")
	)
	(segment
		(start 390.31037 -97.440242)
		(end 390.31037 -97.996502)
		(width 0.089408)
		(layer "In9.Cu")
		(net "IRQ_PVCCIN_CPU1_VRHOT_LVC3_N")
	)
	(segment
		(start 351.95002 -118.24208)
		(end 348.346268 -118.24208)
		(width 0.089408)
		(layer "In9.Cu")
		(net "IRQ_PVCCIN_CPU1_VRHOT_LVC3_N")
	)
	(segment
		(start 264.72388 -122.853704)
		(end 263.791192 -123.786392)
		(width 0.089408)
		(layer "In9.Cu")
		(net "IRQ_PVCCIN_CPU1_VRHOT_LVC3_N")
	)
	(segment
		(start 399.542 -83.6422)
		(end 399.542 -84.963)
		(width 0.089408)
		(layer "In9.Cu")
		(net "IRQ_PVCCIN_CPU1_VRHOT_LVC3_N")
	)
	(segment
		(start 172.523658 -126.402592)
		(end 166.897558 -126.402592)
		(width 0.089408)
		(layer "In9.Cu")
		(net "IRQ_PVCCIN_CPU1_VRHOT_LVC3_N")
	)
	(segment
		(start 263.791192 -123.786392)
		(end 244.61978 -123.786392)
		(width 0.089408)
		(layer "In9.Cu")
		(net "IRQ_PVCCIN_CPU1_VRHOT_LVC3_N")
	)
	(segment
		(start 306.470304 -122.853704)
		(end 264.72388 -122.853704)
		(width 0.089408)
		(layer "In9.Cu")
		(net "IRQ_PVCCIN_CPU1_VRHOT_LVC3_N")
	)
	(segment
		(start 394.57503 -101.732842)
		(end 394.57503 -103.824024)
		(width 0.089408)
		(layer "In9.Cu")
		(net "IRQ_PVCCIN_CPU1_VRHOT_LVC3_N")
	)
	(segment
		(start 390.31037 -95.69323)
		(end 390.31037 -96.279462)
		(width 0.089408)
		(layer "In9.Cu")
		(net "IRQ_PVCCIN_CPU1_VRHOT_LVC3_N")
	)
	(segment
		(start 391.60323 -99.57943)
		(end 391.60323 -100.27285)
		(width 0.089408)
		(layer "In9.Cu")
		(net "IRQ_PVCCIN_CPU1_VRHOT_LVC3_N")
	)
	(segment
		(start 396.487396 -110.023656)
		(end 401.760944 -110.023656)
		(width 0.089408)
		(layer "In9.Cu")
		(net "IRQ_PVCCIN_CPU1_VRHOT_LVC3_N")
	)
	(segment
		(start 392.57478 -101.48824)
		(end 394.330428 -101.48824)
		(width 0.089408)
		(layer "In9.Cu")
		(net "IRQ_PVCCIN_CPU1_VRHOT_LVC3_N")
	)
	(segment
		(start 394.57503 -103.824024)
		(end 394.145008 -104.254046)
		(width 0.089408)
		(layer "In9.Cu")
		(net "IRQ_PVCCIN_CPU1_VRHOT_LVC3_N")
	)
	(segment
		(start 14.3002 -86.519766)
		(end 14.3002 -85.979)
		(width 0.089408)
		(layer "In9.Cu")
		(net "IRQ_PVCCIN_CPU1_VRHOT_LVC3_N")
	)
	(segment
		(start 394.723366 -107.754166)
		(end 395.67866 -108.70946)
		(width 0.089408)
		(layer "In9.Cu")
		(net "IRQ_PVCCIN_CPU1_VRHOT_LVC3_N")
	)
	(segment
		(start 323.511164 -125.001782)
		(end 321.524884 -125.001782)
		(width 0.089408)
		(layer "In9.Cu")
		(net "IRQ_PVCCIN_CPU1_VRHOT_LVC3_N")
	)
	(segment
		(start 328.338942 -123.406916)
		(end 325.10603 -123.406916)
		(width 0.089408)
		(layer "In9.Cu")
		(net "IRQ_PVCCIN_CPU1_VRHOT_LVC3_N")
	)
	(segment
		(start 392.18616 -100.85578)
		(end 392.18616 -101.09962)
		(width 0.089408)
		(layer "In9.Cu")
		(net "IRQ_PVCCIN_CPU1_VRHOT_LVC3_N")
	)
	(segment
		(start 394.330428 -101.48824)
		(end 394.57503 -101.732842)
		(width 0.089408)
		(layer "In9.Cu")
		(net "IRQ_PVCCIN_CPU1_VRHOT_LVC3_N")
	)
	(segment
		(start 400.812508 -80.518508)
		(end 400.812508 -82.371692)
		(width 0.089408)
		(layer "In9.Cu")
		(net "IRQ_PVCCIN_CPU1_VRHOT_LVC3_N")
	)
	(segment
		(start 26.10866 -114.653568)
		(end 24.279352 -114.653568)
		(width 0.089408)
		(layer "In9.Cu")
		(net "IRQ_PVCCIN_CPU1_VRHOT_LVC3_N")
	)
	(segment
		(start 174.877476 -124.048774)
		(end 172.523658 -126.402592)
		(width 0.089408)
		(layer "In9.Cu")
		(net "IRQ_PVCCIN_CPU1_VRHOT_LVC3_N")
	)
	(segment
		(start 348.346268 -118.24208)
		(end 347.43644 -119.151908)
		(width 0.089408)
		(layer "In9.Cu")
		(net "IRQ_PVCCIN_CPU1_VRHOT_LVC3_N")
	)
	(segment
		(start 430.54905 -44.95165)
		(end 430.548796 -44.951396)
		(width 0.089408)
		(layer "In9.Cu")
		(net "IRQ_PVCCIN_CPU1_VRHOT_LVC3_N")
	)
	(segment
		(start 451.380606 -42.573194)
		(end 436.721758 -42.573194)
		(width 0.089408)
		(layer "In9.Cu")
		(net "IRQ_PVCCIN_CPU1_VRHOT_LVC3_N")
	)
	(segment
		(start 394.145008 -104.254046)
		(end 394.145008 -104.677972)
		(width 0.089408)
		(layer "In9.Cu")
		(net "IRQ_PVCCIN_CPU1_VRHOT_LVC3_N")
	)
	(segment
		(start 398.526 -85.979)
		(end 398.526 -86.418166)
		(width 0.089408)
		(layer "In9.Cu")
		(net "IRQ_PVCCIN_CPU1_VRHOT_LVC3_N")
	)
	(segment
		(start 181.300882 -125.5268)
		(end 179.822856 -124.048774)
		(width 0.089408)
		(layer "In9.Cu")
		(net "IRQ_PVCCIN_CPU1_VRHOT_LVC3_N")
	)
	(segment
		(start 402.431504 -79.439262)
		(end 402.08073 -79.790036)
		(width 0.089408)
		(layer "In9.Cu")
		(net "IRQ_PVCCIN_CPU1_VRHOT_LVC3_N")
	)
	(segment
		(start 418.063172 -51.278028)
		(end 414.57499 -51.278028)
		(width 0.089408)
		(layer "In9.Cu")
		(net "IRQ_PVCCIN_CPU1_VRHOT_LVC3_N")
	)
	(segment
		(start 390.61263 -96.581722)
		(end 390.61263 -97.137982)
		(width 0.089408)
		(layer "In9.Cu")
		(net "IRQ_PVCCIN_CPU1_VRHOT_LVC3_N")
	)
	(segment
		(start 407.270204 -70.246494)
		(end 403.2377 -74.278998)
		(width 0.089408)
		(layer "In9.Cu")
		(net "IRQ_PVCCIN_CPU1_VRHOT_LVC3_N")
	)
	(segment
		(start 243.889784 -123.056396)
		(end 223.938084 -123.056396)
		(width 0.089408)
		(layer "In9.Cu")
		(net "IRQ_PVCCIN_CPU1_VRHOT_LVC3_N")
	)
	(segment
		(start 395.67866 -109.21492)
		(end 396.487396 -110.023656)
		(width 0.089408)
		(layer "In9.Cu")
		(net "IRQ_PVCCIN_CPU1_VRHOT_LVC3_N")
	)
	(segment
		(start 147.491196 -122.432572)
		(end 33.887664 -122.432572)
		(width 0.089408)
		(layer "In9.Cu")
		(net "IRQ_PVCCIN_CPU1_VRHOT_LVC3_N")
	)
	(segment
		(start 392.9888 -93.0148)
		(end 390.31037 -95.69323)
		(width 0.089408)
		(layer "In9.Cu")
		(net "IRQ_PVCCIN_CPU1_VRHOT_LVC3_N")
	)
	(segment
		(start 426.323252 -45.927772)
		(end 426.19041 -46.060614)
		(width 0.089408)
		(layer "In9.Cu")
		(net "IRQ_PVCCIN_CPU1_VRHOT_LVC3_N")
	)
	(segment
		(start 402.431504 -78.238096)
		(end 402.431504 -79.439262)
		(width 0.089408)
		(layer "In9.Cu")
		(net "IRQ_PVCCIN_CPU1_VRHOT_LVC3_N")
	)
	(segment
		(start 401.54098 -79.790036)
		(end 400.812508 -80.518508)
		(width 0.089408)
		(layer "In9.Cu")
		(net "IRQ_PVCCIN_CPU1_VRHOT_LVC3_N")
	)
	(segment
		(start 18.424144 -100.227638)
		(end 16.892524 -98.696018)
		(width 0.089408)
		(layer "In9.Cu")
		(net "IRQ_PVCCIN_CPU1_VRHOT_LVC3_N")
	)
	(segment
		(start 391.60323 -100.27285)
		(end 392.18616 -100.85578)
		(width 0.089408)
		(layer "In9.Cu")
		(net "IRQ_PVCCIN_CPU1_VRHOT_LVC3_N")
	)
	(segment
		(start 187.445904 -124.513848)
		(end 186.432952 -125.5268)
		(width 0.089408)
		(layer "In9.Cu")
		(net "IRQ_PVCCIN_CPU1_VRHOT_LVC3_N")
	)
	(segment
		(start 428.120048 -44.951396)
		(end 427.143672 -45.927772)
		(width 0.089408)
		(layer "In9.Cu")
		(net "IRQ_PVCCIN_CPU1_VRHOT_LVC3_N")
	)
	(segment
		(start 409.78328 -56.069738)
		(end 409.78328 -60.80887)
		(width 0.089408)
		(layer "In9.Cu")
		(net "IRQ_PVCCIN_CPU1_VRHOT_LVC3_N")
	)
	(segment
		(start 392.18616 -101.09962)
		(end 392.57478 -101.48824)
		(width 0.089408)
		(layer "In9.Cu")
		(net "IRQ_PVCCIN_CPU1_VRHOT_LVC3_N")
	)
	(segment
		(start 427.143672 -45.927772)
		(end 426.323252 -45.927772)
		(width 0.089408)
		(layer "In9.Cu")
		(net "IRQ_PVCCIN_CPU1_VRHOT_LVC3_N")
	)
	(segment
		(start 340.752938 -119.151908)
		(end 337.15579 -122.749056)
		(width 0.089408)
		(layer "In9.Cu")
		(net "IRQ_PVCCIN_CPU1_VRHOT_LVC3_N")
	)
	(segment
		(start 404.403306 -109.458506)
		(end 404.7236 -109.7788)
		(width 0.089408)
		(layer "In9.Cu")
		(net "IRQ_PVCCIN_CPU1_VRHOT_LVC3_N")
	)
	(segment
		(start 393.77747 -105.04551)
		(end 393.77747 -105.870756)
		(width 0.089408)
		(layer "In9.Cu")
		(net "IRQ_PVCCIN_CPU1_VRHOT_LVC3_N")
	)
	(segment
		(start 321.524884 -125.001782)
		(end 320.019934 -126.506732)
		(width 0.089408)
		(layer "In9.Cu")
		(net "IRQ_PVCCIN_CPU1_VRHOT_LVC3_N")
	)
	(segment
		(start 390.31037 -96.279462)
		(end 390.61263 -96.581722)
		(width 0.089408)
		(layer "In9.Cu")
		(net "IRQ_PVCCIN_CPU1_VRHOT_LVC3_N")
	)
	(segment
		(start 163.284916 -125.616208)
		(end 161.38906 -127.512064)
		(width 0.089408)
		(layer "In9.Cu")
		(net "IRQ_PVCCIN_CPU1_VRHOT_LVC3_N")
	)
	(segment
		(start 33.887664 -122.432572)
		(end 26.10866 -114.653568)
		(width 0.089408)
		(layer "In9.Cu")
		(net "IRQ_PVCCIN_CPU1_VRHOT_LVC3_N")
	)
	(segment
		(start 310.123332 -126.506732)
		(end 306.470304 -122.853704)
		(width 0.089408)
		(layer "In9.Cu")
		(net "IRQ_PVCCIN_CPU1_VRHOT_LVC3_N")
	)
	(segment
		(start 355.45268 -116.75872)
		(end 353.43338 -116.75872)
		(width 0.089408)
		(layer "In9.Cu")
		(net "IRQ_PVCCIN_CPU1_VRHOT_LVC3_N")
	)
	(segment
		(start 407.270204 -69.979286)
		(end 407.270204 -70.246494)
		(width 0.089408)
		(layer "In9.Cu")
		(net "IRQ_PVCCIN_CPU1_VRHOT_LVC3_N")
	)
	(segment
		(start 397.288766 -87.6554)
		(end 397.045434 -87.6554)
		(width 0.089408)
		(layer "In9.Cu")
		(net "IRQ_PVCCIN_CPU1_VRHOT_LVC3_N")
	)
	(segment
		(start 222.480632 -124.513848)
		(end 187.445904 -124.513848)
		(width 0.089408)
		(layer "In9.Cu")
		(net "IRQ_PVCCIN_CPU1_VRHOT_LVC3_N")
	)
	(segment
		(start 353.43338 -116.75872)
		(end 351.95002 -118.24208)
		(width 0.089408)
		(layer "In9.Cu")
		(net "IRQ_PVCCIN_CPU1_VRHOT_LVC3_N")
	)
	(segment
		(start 161.38906 -127.512064)
		(end 152.570688 -127.512064)
		(width 0.089408)
		(layer "In9.Cu")
		(net "IRQ_PVCCIN_CPU1_VRHOT_LVC3_N")
	)
	(segment
		(start 430.548796 -44.951396)
		(end 428.120048 -44.951396)
		(width 0.089408)
		(layer "In9.Cu")
		(net "IRQ_PVCCIN_CPU1_VRHOT_LVC3_N")
	)
	(segment
		(start 390.31037 -97.996502)
		(end 390.61263 -98.298762)
		(width 0.089408)
		(layer "In9.Cu")
		(net "IRQ_PVCCIN_CPU1_VRHOT_LVC3_N")
	)
	(segment
		(start 390.61263 -97.137982)
		(end 390.31037 -97.440242)
		(width 0.089408)
		(layer "In9.Cu")
		(net "IRQ_PVCCIN_CPU1_VRHOT_LVC3_N")
	)
	(segment
		(start 390.61263 -98.298762)
		(end 390.61263 -98.58883)
		(width 0.089408)
		(layer "In9.Cu")
		(net "IRQ_PVCCIN_CPU1_VRHOT_LVC3_N")
	)
	(segment
		(start 18.424144 -108.79836)
		(end 18.424144 -100.227638)
		(width 0.089408)
		(layer "In9.Cu")
		(net "IRQ_PVCCIN_CPU1_VRHOT_LVC3_N")
	)
	(segment
		(start 320.019934 -126.506732)
		(end 310.123332 -126.506732)
		(width 0.089408)
		(layer "In9.Cu")
		(net "IRQ_PVCCIN_CPU1_VRHOT_LVC3_N")
	)
	(segment
		(start 403.2377 -74.278998)
		(end 403.2377 -77.4319)
		(width 0.089408)
		(layer "In9.Cu")
		(net "IRQ_PVCCIN_CPU1_VRHOT_LVC3_N")
	)
	(segment
		(start 432.114706 -44.95165)
		(end 430.54905 -44.95165)
		(width 0.089408)
		(layer "In9.Cu")
		(net "IRQ_PVCCIN_CPU1_VRHOT_LVC3_N")
	)
	(segment
		(start 186.432952 -125.5268)
		(end 181.300882 -125.5268)
		(width 0.089408)
		(layer "In9.Cu")
		(net "IRQ_PVCCIN_CPU1_VRHOT_LVC3_N")
	)
	(segment
		(start 409.988258 -61.013848)
		(end 409.988258 -67.261232)
		(width 0.089408)
		(layer "In9.Cu")
		(net "IRQ_PVCCIN_CPU1_VRHOT_LVC3_N")
	)
	(segment
		(start 15.513812 -98.696018)
		(end 13.166344 -96.34855)
		(width 0.089408)
		(layer "In9.Cu")
		(net "IRQ_PVCCIN_CPU1_VRHOT_LVC3_N")
	)
	(segment
		(start 359.183178 -113.605818)
		(end 358.060498 -113.605818)
		(width 0.089408)
		(layer "In9.Cu")
		(net "IRQ_PVCCIN_CPU1_VRHOT_LVC3_N")
	)
	(segment
		(start 424.398186 -46.060614)
		(end 422.6814 -47.7774)
		(width 0.089408)
		(layer "In9.Cu")
		(net "IRQ_PVCCIN_CPU1_VRHOT_LVC3_N")
	)
	(segment
		(start 179.822856 -124.048774)
		(end 174.877476 -124.048774)
		(width 0.089408)
		(layer "In9.Cu")
		(net "IRQ_PVCCIN_CPU1_VRHOT_LVC3_N")
	)
	(segment
		(start 369.0366 -113.792)
		(end 370.4082 -112.4204)
		(width 0.089408)
		(layer "In11.Cu")
		(net "IRQ_PVCCIN_CPU1_VRHOT_LVC3_N")
	)
	(segment
		(start 368.554508 -113.792)
		(end 369.0366 -113.792)
		(width 0.089408)
		(layer "In11.Cu")
		(net "IRQ_PVCCIN_CPU1_VRHOT_LVC3_N")
	)
	(segment
		(start 361.461304 -115.817904)
		(end 366.528604 -115.817904)
		(width 0.089408)
		(layer "In11.Cu")
		(net "IRQ_PVCCIN_CPU1_VRHOT_LVC3_N")
	)
	(segment
		(start 366.528604 -115.817904)
		(end 368.554508 -113.792)
		(width 0.089408)
		(layer "In11.Cu")
		(net "IRQ_PVCCIN_CPU1_VRHOT_LVC3_N")
	)
	(segment
		(start 359.249218 -113.605818)
		(end 361.461304 -115.817904)
		(width 0.089408)
		(layer "In11.Cu")
		(net "IRQ_PVCCIN_CPU1_VRHOT_LVC3_N")
	)
	(segment
		(start 359.183178 -113.605818)
		(end 359.249218 -113.605818)
		(width 0.089408)
		(layer "In11.Cu")
		(net "IRQ_PVCCIN_CPU1_VRHOT_LVC3_N")
	)
	(segment
		(start 370.4082 -112.4204)
		(end 370.4082 -112.43945)
		(width 0.089408)
		(layer "In11.Cu")
		(net "IRQ_PVCCIN_CPU1_VRHOT_LVC3_N")
	)
	(segment
		(start 406.95499 -44.771564)
		(end 406.95499 -45.900086)
		(width 0.10795)
		(layer "F.Cu")
		(net "IRQ_PVCCIN_CPU0_VRHOT_LVC3_N")
	)
	(segment
		(start 407.852626 -43.372278)
		(end 407.852626 -43.873928)
		(width 0.10795)
		(layer "F.Cu")
		(net "IRQ_PVCCIN_CPU0_VRHOT_LVC3_N")
	)
	(segment
		(start 407.852626 -43.873928)
		(end 406.95499 -44.771564)
		(width 0.10795)
		(layer "F.Cu")
		(net "IRQ_PVCCIN_CPU0_VRHOT_LVC3_N")
	)
	(segment
		(start 407.890218 -43.334686)
		(end 407.852626 -43.372278)
		(width 0.10795)
		(layer "F.Cu")
		(net "IRQ_PVCCIN_CPU0_VRHOT_LVC3_N")
	)
	(via
		(at 315.038486 -41.1226)
		(size 0.508)
		(drill 0.254)
		(layers "F.Cu" "B.Cu")
		(net "IRQ_PVCCIN_CPU0_VRHOT_LVC3_N")
	)
	(via
		(at 406.95499 -45.900086)
		(size 0.508)
		(drill 0.254)
		(layers "F.Cu" "B.Cu")
		(net "IRQ_PVCCIN_CPU0_VRHOT_LVC3_N")
	)
	(via
		(at 339.3694 -50.8762)
		(size 0.6604)
		(drill 0.3302)
		(layers "F.Cu" "B.Cu")
		(net "IRQ_PVCCIN_CPU0_VRHOT_LVC3_N")
	)
	(via
		(at 189.6364 -26.3906)
		(size 0.508)
		(drill 0.254)
		(layers "F.Cu" "B.Cu")
		(net "IRQ_PVCCIN_CPU0_VRHOT_LVC3_N")
	)
	(via
		(at 178.83886 -65.04432)
		(size 0.508)
		(drill 0.254)
		(layers "F.Cu" "B.Cu")
		(net "IRQ_PVCCIN_CPU0_VRHOT_LVC3_N")
	)
	(via
		(at 337.648296 -53.073554)
		(size 0.508)
		(drill 0.254)
		(layers "F.Cu" "B.Cu")
		(net "IRQ_PVCCIN_CPU0_VRHOT_LVC3_N")
	)
	(via
		(at 384.336544 -39.898574)
		(size 0.508)
		(drill 0.254)
		(layers "F.Cu" "B.Cu")
		(net "IRQ_PVCCIN_CPU0_VRHOT_LVC3_N")
	)
	(segment
		(start 385.339844 -38.93693)
		(end 385.339844 -37.66185)
		(width 0.10795)
		(layer "B.Cu")
		(net "IRQ_PVCCIN_CPU0_VRHOT_LVC3_N")
	)
	(segment
		(start 379.27026 -34.002472)
		(end 377.170696 -31.902908)
		(width 0.10795)
		(layer "B.Cu")
		(net "IRQ_PVCCIN_CPU0_VRHOT_LVC3_N")
	)
	(segment
		(start 383.336038 -39.898574)
		(end 384.336544 -39.898574)
		(width 0.10795)
		(layer "B.Cu")
		(net "IRQ_PVCCIN_CPU0_VRHOT_LVC3_N")
	)
	(segment
		(start 337.648296 -52.597304)
		(end 339.3694 -50.8762)
		(width 0.10795)
		(layer "B.Cu")
		(net "IRQ_PVCCIN_CPU0_VRHOT_LVC3_N")
	)
	(segment
		(start 371.606318 -36.283646)
		(end 372.218712 -35.671252)
		(width 0.10795)
		(layer "B.Cu")
		(net "IRQ_PVCCIN_CPU0_VRHOT_LVC3_N")
	)
	(segment
		(start 372.218712 -35.671252)
		(end 375.186448 -35.671252)
		(width 0.10795)
		(layer "B.Cu")
		(net "IRQ_PVCCIN_CPU0_VRHOT_LVC3_N")
	)
	(segment
		(start 375.88444 -36.369244)
		(end 378.713492 -36.369244)
		(width 0.10795)
		(layer "B.Cu")
		(net "IRQ_PVCCIN_CPU0_VRHOT_LVC3_N")
	)
	(segment
		(start 384.336544 -39.898574)
		(end 384.3782 -39.898574)
		(width 0.10795)
		(layer "B.Cu")
		(net "IRQ_PVCCIN_CPU0_VRHOT_LVC3_N")
	)
	(segment
		(start 384.3782 -39.898574)
		(end 385.339844 -38.93693)
		(width 0.10795)
		(layer "B.Cu")
		(net "IRQ_PVCCIN_CPU0_VRHOT_LVC3_N")
	)
	(segment
		(start 382.6256 -35.119564)
		(end 381.038862 -35.119564)
		(width 0.10795)
		(layer "B.Cu")
		(net "IRQ_PVCCIN_CPU0_VRHOT_LVC3_N")
	)
	(segment
		(start 357.003096 -39.157402)
		(end 357.002842 -39.157656)
		(width 0.10795)
		(layer "B.Cu")
		(net "IRQ_PVCCIN_CPU0_VRHOT_LVC3_N")
	)
	(segment
		(start 375.186448 -35.671252)
		(end 375.88444 -36.369244)
		(width 0.10795)
		(layer "B.Cu")
		(net "IRQ_PVCCIN_CPU0_VRHOT_LVC3_N")
	)
	(segment
		(start 377.170696 -31.436056)
		(end 376.864626 -31.129986)
		(width 0.10795)
		(layer "B.Cu")
		(net "IRQ_PVCCIN_CPU0_VRHOT_LVC3_N")
	)
	(segment
		(start 382.172464 -38.735)
		(end 383.336038 -39.898574)
		(width 0.10795)
		(layer "B.Cu")
		(net "IRQ_PVCCIN_CPU0_VRHOT_LVC3_N")
	)
	(segment
		(start 371.62486 -30.591252)
		(end 365.57839 -30.591252)
		(width 0.10795)
		(layer "B.Cu")
		(net "IRQ_PVCCIN_CPU0_VRHOT_LVC3_N")
	)
	(segment
		(start 382.142492 -38.723062)
		(end 382.15443 -38.735)
		(width 0.10795)
		(layer "B.Cu")
		(net "IRQ_PVCCIN_CPU0_VRHOT_LVC3_N")
	)
	(segment
		(start 370.929916 -37.736526)
		(end 371.408452 -37.736526)
		(width 0.10795)
		(layer "B.Cu")
		(net "IRQ_PVCCIN_CPU0_VRHOT_LVC3_N")
	)
	(segment
		(start 377.170696 -31.902908)
		(end 377.170696 -31.436056)
		(width 0.10795)
		(layer "B.Cu")
		(net "IRQ_PVCCIN_CPU0_VRHOT_LVC3_N")
	)
	(segment
		(start 374.43283 -28.978606)
		(end 373.237506 -28.978606)
		(width 0.10795)
		(layer "B.Cu")
		(net "IRQ_PVCCIN_CPU0_VRHOT_LVC3_N")
	)
	(segment
		(start 376.864626 -31.129986)
		(end 376.58421 -31.129986)
		(width 0.10795)
		(layer "B.Cu")
		(net "IRQ_PVCCIN_CPU0_VRHOT_LVC3_N")
	)
	(segment
		(start 385.339844 -37.66185)
		(end 384.009138 -36.331144)
		(width 0.10795)
		(layer "B.Cu")
		(net "IRQ_PVCCIN_CPU0_VRHOT_LVC3_N")
	)
	(segment
		(start 376.58421 -31.129986)
		(end 374.43283 -28.978606)
		(width 0.10795)
		(layer "B.Cu")
		(net "IRQ_PVCCIN_CPU0_VRHOT_LVC3_N")
	)
	(segment
		(start 371.408452 -37.736526)
		(end 371.606318 -37.53866)
		(width 0.10795)
		(layer "B.Cu")
		(net "IRQ_PVCCIN_CPU0_VRHOT_LVC3_N")
	)
	(segment
		(start 371.606318 -37.53866)
		(end 371.606318 -36.283646)
		(width 0.10795)
		(layer "B.Cu")
		(net "IRQ_PVCCIN_CPU0_VRHOT_LVC3_N")
	)
	(segment
		(start 355.482398 -39.157402)
		(end 354.942902 -39.696898)
		(width 0.10795)
		(layer "B.Cu")
		(net "IRQ_PVCCIN_CPU0_VRHOT_LVC3_N")
	)
	(segment
		(start 382.15443 -38.735)
		(end 382.172464 -38.735)
		(width 0.10795)
		(layer "B.Cu")
		(net "IRQ_PVCCIN_CPU0_VRHOT_LVC3_N")
	)
	(segment
		(start 356.702868 -39.157402)
		(end 355.482398 -39.157402)
		(width 0.10795)
		(layer "B.Cu")
		(net "IRQ_PVCCIN_CPU0_VRHOT_LVC3_N")
	)
	(segment
		(start 337.648296 -53.073554)
		(end 337.648296 -52.597304)
		(width 0.10795)
		(layer "B.Cu")
		(net "IRQ_PVCCIN_CPU0_VRHOT_LVC3_N")
	)
	(segment
		(start 354.942902 -39.696898)
		(end 354.942902 -45.823886)
		(width 0.10795)
		(layer "B.Cu")
		(net "IRQ_PVCCIN_CPU0_VRHOT_LVC3_N")
	)
	(segment
		(start 384.009138 -36.331144)
		(end 384.009138 -36.04895)
		(width 0.10795)
		(layer "B.Cu")
		(net "IRQ_PVCCIN_CPU0_VRHOT_LVC3_N")
	)
	(segment
		(start 180.467 -64.135)
		(end 180.26126 -64.135)
		(width 0.10795)
		(layer "B.Cu")
		(net "IRQ_PVCCIN_CPU0_VRHOT_LVC3_N")
	)
	(segment
		(start 354.942902 -45.823886)
		(end 351.275142 -49.491646)
		(width 0.10795)
		(layer "B.Cu")
		(net "IRQ_PVCCIN_CPU0_VRHOT_LVC3_N")
	)
	(segment
		(start 379.7808 -38.735)
		(end 380.400052 -38.735)
		(width 0.10795)
		(layer "B.Cu")
		(net "IRQ_PVCCIN_CPU0_VRHOT_LVC3_N")
	)
	(segment
		(start 380.400052 -38.735)
		(end 380.41199 -38.723062)
		(width 0.10795)
		(layer "B.Cu")
		(net "IRQ_PVCCIN_CPU0_VRHOT_LVC3_N")
	)
	(segment
		(start 379.92177 -34.002472)
		(end 379.27026 -34.002472)
		(width 0.10795)
		(layer "B.Cu")
		(net "IRQ_PVCCIN_CPU0_VRHOT_LVC3_N")
	)
	(segment
		(start 180.26126 -64.135)
		(end 179.35194 -65.04432)
		(width 0.10795)
		(layer "B.Cu")
		(net "IRQ_PVCCIN_CPU0_VRHOT_LVC3_N")
	)
	(segment
		(start 380.41199 -38.723062)
		(end 382.142492 -38.723062)
		(width 0.10795)
		(layer "B.Cu")
		(net "IRQ_PVCCIN_CPU0_VRHOT_LVC3_N")
	)
	(segment
		(start 384.009138 -36.04895)
		(end 383.695194 -35.735006)
		(width 0.10795)
		(layer "B.Cu")
		(net "IRQ_PVCCIN_CPU0_VRHOT_LVC3_N")
	)
	(segment
		(start 379.2474 -36.903152)
		(end 379.2474 -38.2016)
		(width 0.10795)
		(layer "B.Cu")
		(net "IRQ_PVCCIN_CPU0_VRHOT_LVC3_N")
	)
	(segment
		(start 179.35194 -65.04432)
		(end 178.83886 -65.04432)
		(width 0.10795)
		(layer "B.Cu")
		(net "IRQ_PVCCIN_CPU0_VRHOT_LVC3_N")
	)
	(segment
		(start 356.703122 -39.157656)
		(end 356.702868 -39.157402)
		(width 0.10795)
		(layer "B.Cu")
		(net "IRQ_PVCCIN_CPU0_VRHOT_LVC3_N")
	)
	(segment
		(start 383.695194 -35.735006)
		(end 383.241042 -35.735006)
		(width 0.10795)
		(layer "B.Cu")
		(net "IRQ_PVCCIN_CPU0_VRHOT_LVC3_N")
	)
	(segment
		(start 351.275142 -49.491646)
		(end 340.753954 -49.491646)
		(width 0.10795)
		(layer "B.Cu")
		(net "IRQ_PVCCIN_CPU0_VRHOT_LVC3_N")
	)
	(segment
		(start 373.237506 -28.978606)
		(end 371.62486 -30.591252)
		(width 0.10795)
		(layer "B.Cu")
		(net "IRQ_PVCCIN_CPU0_VRHOT_LVC3_N")
	)
	(segment
		(start 383.241042 -35.735006)
		(end 382.6256 -35.119564)
		(width 0.10795)
		(layer "B.Cu")
		(net "IRQ_PVCCIN_CPU0_VRHOT_LVC3_N")
	)
	(segment
		(start 340.753954 -49.491646)
		(end 339.3694 -50.8762)
		(width 0.10795)
		(layer "B.Cu")
		(net "IRQ_PVCCIN_CPU0_VRHOT_LVC3_N")
	)
	(segment
		(start 378.713492 -36.369244)
		(end 379.2474 -36.903152)
		(width 0.10795)
		(layer "B.Cu")
		(net "IRQ_PVCCIN_CPU0_VRHOT_LVC3_N")
	)
	(segment
		(start 357.01224 -39.157402)
		(end 357.003096 -39.157402)
		(width 0.10795)
		(layer "B.Cu")
		(net "IRQ_PVCCIN_CPU0_VRHOT_LVC3_N")
	)
	(segment
		(start 381.038862 -35.119564)
		(end 379.92177 -34.002472)
		(width 0.10795)
		(layer "B.Cu")
		(net "IRQ_PVCCIN_CPU0_VRHOT_LVC3_N")
	)
	(segment
		(start 365.57839 -30.591252)
		(end 357.01224 -39.157402)
		(width 0.10795)
		(layer "B.Cu")
		(net "IRQ_PVCCIN_CPU0_VRHOT_LVC3_N")
	)
	(segment
		(start 379.2474 -38.2016)
		(end 379.7808 -38.735)
		(width 0.10795)
		(layer "B.Cu")
		(net "IRQ_PVCCIN_CPU0_VRHOT_LVC3_N")
	)
	(segment
		(start 357.002842 -39.157656)
		(end 356.703122 -39.157656)
		(width 0.10795)
		(layer "B.Cu")
		(net "IRQ_PVCCIN_CPU0_VRHOT_LVC3_N")
	)
	(segment
		(start 389.540496 -42.875962)
		(end 391.439908 -42.875962)
		(width 0.089408)
		(layer "In4.Cu")
		(net "IRQ_PVCCIN_CPU0_VRHOT_LVC3_N")
	)
	(segment
		(start 388.535164 -41.861486)
		(end 388.89432 -42.220642)
		(width 0.089408)
		(layer "In4.Cu")
		(net "IRQ_PVCCIN_CPU0_VRHOT_LVC3_N")
	)
	(segment
		(start 406.418542 -46.436534)
		(end 406.95499 -45.900086)
		(width 0.089408)
		(layer "In4.Cu")
		(net "IRQ_PVCCIN_CPU0_VRHOT_LVC3_N")
	)
	(segment
		(start 402.230844 -46.261782)
		(end 404.54834 -46.261782)
		(width 0.089408)
		(layer "In4.Cu")
		(net "IRQ_PVCCIN_CPU0_VRHOT_LVC3_N")
	)
	(segment
		(start 385.211574 -39.898574)
		(end 387.174486 -41.861486)
		(width 0.089408)
		(layer "In4.Cu")
		(net "IRQ_PVCCIN_CPU0_VRHOT_LVC3_N")
	)
	(segment
		(start 391.629138 -43.065192)
		(end 396.014448 -43.065192)
		(width 0.089408)
		(layer "In4.Cu")
		(net "IRQ_PVCCIN_CPU0_VRHOT_LVC3_N")
	)
	(segment
		(start 404.723092 -46.436534)
		(end 406.418542 -46.436534)
		(width 0.089408)
		(layer "In4.Cu")
		(net "IRQ_PVCCIN_CPU0_VRHOT_LVC3_N")
	)
	(segment
		(start 396.014448 -43.065192)
		(end 396.71879 -43.769534)
		(width 0.089408)
		(layer "In4.Cu")
		(net "IRQ_PVCCIN_CPU0_VRHOT_LVC3_N")
	)
	(segment
		(start 384.336544 -39.898574)
		(end 385.211574 -39.898574)
		(width 0.089408)
		(layer "In4.Cu")
		(net "IRQ_PVCCIN_CPU0_VRHOT_LVC3_N")
	)
	(segment
		(start 396.71879 -43.769534)
		(end 398.14119 -43.769534)
		(width 0.089408)
		(layer "In4.Cu")
		(net "IRQ_PVCCIN_CPU0_VRHOT_LVC3_N")
	)
	(segment
		(start 391.439908 -42.875962)
		(end 391.629138 -43.065192)
		(width 0.089408)
		(layer "In4.Cu")
		(net "IRQ_PVCCIN_CPU0_VRHOT_LVC3_N")
	)
	(segment
		(start 388.89432 -42.220642)
		(end 388.89432 -42.229786)
		(width 0.089408)
		(layer "In4.Cu")
		(net "IRQ_PVCCIN_CPU0_VRHOT_LVC3_N")
	)
	(segment
		(start 404.54834 -46.261782)
		(end 404.723092 -46.436534)
		(width 0.089408)
		(layer "In4.Cu")
		(net "IRQ_PVCCIN_CPU0_VRHOT_LVC3_N")
	)
	(segment
		(start 387.174486 -41.861486)
		(end 388.535164 -41.861486)
		(width 0.089408)
		(layer "In4.Cu")
		(net "IRQ_PVCCIN_CPU0_VRHOT_LVC3_N")
	)
	(segment
		(start 398.618456 -44.2468)
		(end 400.215862 -44.2468)
		(width 0.089408)
		(layer "In4.Cu")
		(net "IRQ_PVCCIN_CPU0_VRHOT_LVC3_N")
	)
	(segment
		(start 400.215862 -44.2468)
		(end 402.230844 -46.261782)
		(width 0.089408)
		(layer "In4.Cu")
		(net "IRQ_PVCCIN_CPU0_VRHOT_LVC3_N")
	)
	(segment
		(start 398.14119 -43.769534)
		(end 398.618456 -44.2468)
		(width 0.089408)
		(layer "In4.Cu")
		(net "IRQ_PVCCIN_CPU0_VRHOT_LVC3_N")
	)
	(segment
		(start 388.89432 -42.229786)
		(end 389.540496 -42.875962)
		(width 0.089408)
		(layer "In4.Cu")
		(net "IRQ_PVCCIN_CPU0_VRHOT_LVC3_N")
	)
	(segment
		(start 304.125122 -31.302706)
		(end 313.945016 -41.1226)
		(width 0.089408)
		(layer "In9.Cu")
		(net "IRQ_PVCCIN_CPU0_VRHOT_LVC3_N")
	)
	(segment
		(start 242.826032 -26.087832)
		(end 244.780816 -28.042616)
		(width 0.089408)
		(layer "In9.Cu")
		(net "IRQ_PVCCIN_CPU0_VRHOT_LVC3_N")
	)
	(segment
		(start 189.6364 -26.3906)
		(end 190.100458 -26.854658)
		(width 0.089408)
		(layer "In9.Cu")
		(net "IRQ_PVCCIN_CPU0_VRHOT_LVC3_N")
	)
	(segment
		(start 262.953754 -29.247084)
		(end 265.009376 -31.302706)
		(width 0.089408)
		(layer "In9.Cu")
		(net "IRQ_PVCCIN_CPU0_VRHOT_LVC3_N")
	)
	(segment
		(start 244.780816 -28.042616)
		(end 260.261354 -28.042616)
		(width 0.089408)
		(layer "In9.Cu")
		(net "IRQ_PVCCIN_CPU0_VRHOT_LVC3_N")
	)
	(segment
		(start 261.465822 -29.247084)
		(end 262.953754 -29.247084)
		(width 0.089408)
		(layer "In9.Cu")
		(net "IRQ_PVCCIN_CPU0_VRHOT_LVC3_N")
	)
	(segment
		(start 313.945016 -41.1226)
		(end 315.038486 -41.1226)
		(width 0.089408)
		(layer "In9.Cu")
		(net "IRQ_PVCCIN_CPU0_VRHOT_LVC3_N")
	)
	(segment
		(start 197.555104 -26.087832)
		(end 242.826032 -26.087832)
		(width 0.089408)
		(layer "In9.Cu")
		(net "IRQ_PVCCIN_CPU0_VRHOT_LVC3_N")
	)
	(segment
		(start 265.009376 -31.302706)
		(end 304.125122 -31.302706)
		(width 0.089408)
		(layer "In9.Cu")
		(net "IRQ_PVCCIN_CPU0_VRHOT_LVC3_N")
	)
	(segment
		(start 190.100458 -26.854658)
		(end 196.788278 -26.854658)
		(width 0.089408)
		(layer "In9.Cu")
		(net "IRQ_PVCCIN_CPU0_VRHOT_LVC3_N")
	)
	(segment
		(start 260.261354 -28.042616)
		(end 261.465822 -29.247084)
		(width 0.089408)
		(layer "In9.Cu")
		(net "IRQ_PVCCIN_CPU0_VRHOT_LVC3_N")
	)
	(segment
		(start 196.788278 -26.854658)
		(end 197.555104 -26.087832)
		(width 0.089408)
		(layer "In9.Cu")
		(net "IRQ_PVCCIN_CPU0_VRHOT_LVC3_N")
	)
	(segment
		(start 321.004946 -47.759366)
		(end 317.53556 -47.759366)
		(width 0.089408)
		(layer "In11.Cu")
		(net "IRQ_PVCCIN_CPU0_VRHOT_LVC3_N")
	)
	(segment
		(start 195.6054 -49.376584)
		(end 189.196472 -49.376584)
		(width 0.089408)
		(layer "In11.Cu")
		(net "IRQ_PVCCIN_CPU0_VRHOT_LVC3_N")
	)
	(segment
		(start 184.887616 -62.467236)
		(end 184.887616 -63.660528)
		(width 0.089408)
		(layer "In11.Cu")
		(net "IRQ_PVCCIN_CPU0_VRHOT_LVC3_N")
	)
	(segment
		(start 189.196472 -49.376584)
		(end 184.9628 -53.610256)
		(width 0.089408)
		(layer "In11.Cu")
		(net "IRQ_PVCCIN_CPU0_VRHOT_LVC3_N")
	)
	(segment
		(start 189.6364 -26.3906)
		(end 189.6364 -27.6098)
		(width 0.089408)
		(layer "In11.Cu")
		(net "IRQ_PVCCIN_CPU0_VRHOT_LVC3_N")
	)
	(segment
		(start 184.12206 -64.44234)
		(end 180.24348 -64.44234)
		(width 0.089408)
		(layer "In11.Cu")
		(net "IRQ_PVCCIN_CPU0_VRHOT_LVC3_N")
	)
	(segment
		(start 184.9628 -59.195716)
		(end 185.463688 -59.696604)
		(width 0.089408)
		(layer "In11.Cu")
		(net "IRQ_PVCCIN_CPU0_VRHOT_LVC3_N")
	)
	(segment
		(start 314.617862 -44.841668)
		(end 314.617862 -41.543224)
		(width 0.089408)
		(layer "In11.Cu")
		(net "IRQ_PVCCIN_CPU0_VRHOT_LVC3_N")
	)
	(segment
		(start 317.53556 -47.759366)
		(end 314.617862 -44.841668)
		(width 0.089408)
		(layer "In11.Cu")
		(net "IRQ_PVCCIN_CPU0_VRHOT_LVC3_N")
	)
	(segment
		(start 180.24348 -64.44234)
		(end 179.6415 -65.04432)
		(width 0.089408)
		(layer "In11.Cu")
		(net "IRQ_PVCCIN_CPU0_VRHOT_LVC3_N")
	)
	(segment
		(start 184.887616 -63.660528)
		(end 184.6326 -63.915544)
		(width 0.089408)
		(layer "In11.Cu")
		(net "IRQ_PVCCIN_CPU0_VRHOT_LVC3_N")
	)
	(segment
		(start 184.6326 -63.915544)
		(end 184.6326 -63.9318)
		(width 0.089408)
		(layer "In11.Cu")
		(net "IRQ_PVCCIN_CPU0_VRHOT_LVC3_N")
	)
	(segment
		(start 179.6415 -65.04432)
		(end 178.83886 -65.04432)
		(width 0.089408)
		(layer "In11.Cu")
		(net "IRQ_PVCCIN_CPU0_VRHOT_LVC3_N")
	)
	(segment
		(start 185.463688 -61.891164)
		(end 184.887616 -62.467236)
		(width 0.089408)
		(layer "In11.Cu")
		(net "IRQ_PVCCIN_CPU0_VRHOT_LVC3_N")
	)
	(segment
		(start 196.088 -46.7106)
		(end 196.088 -48.893984)
		(width 0.089408)
		(layer "In11.Cu")
		(net "IRQ_PVCCIN_CPU0_VRHOT_LVC3_N")
	)
	(segment
		(start 196.088 -48.893984)
		(end 195.6054 -49.376584)
		(width 0.089408)
		(layer "In11.Cu")
		(net "IRQ_PVCCIN_CPU0_VRHOT_LVC3_N")
	)
	(segment
		(start 193.383408 -44.006008)
		(end 196.088 -46.7106)
		(width 0.089408)
		(layer "In11.Cu")
		(net "IRQ_PVCCIN_CPU0_VRHOT_LVC3_N")
	)
	(segment
		(start 184.6326 -63.9318)
		(end 184.12206 -64.44234)
		(width 0.089408)
		(layer "In11.Cu")
		(net "IRQ_PVCCIN_CPU0_VRHOT_LVC3_N")
	)
	(segment
		(start 337.30692 -52.732178)
		(end 325.977758 -52.732178)
		(width 0.089408)
		(layer "In11.Cu")
		(net "IRQ_PVCCIN_CPU0_VRHOT_LVC3_N")
	)
	(segment
		(start 325.977758 -52.732178)
		(end 321.004946 -47.759366)
		(width 0.089408)
		(layer "In11.Cu")
		(net "IRQ_PVCCIN_CPU0_VRHOT_LVC3_N")
	)
	(segment
		(start 184.9628 -53.610256)
		(end 184.9628 -59.195716)
		(width 0.089408)
		(layer "In11.Cu")
		(net "IRQ_PVCCIN_CPU0_VRHOT_LVC3_N")
	)
	(segment
		(start 314.617862 -41.543224)
		(end 315.038486 -41.1226)
		(width 0.089408)
		(layer "In11.Cu")
		(net "IRQ_PVCCIN_CPU0_VRHOT_LVC3_N")
	)
	(segment
		(start 193.383408 -31.356808)
		(end 193.383408 -44.006008)
		(width 0.089408)
		(layer "In11.Cu")
		(net "IRQ_PVCCIN_CPU0_VRHOT_LVC3_N")
	)
	(segment
		(start 337.648296 -53.073554)
		(end 337.30692 -52.732178)
		(width 0.089408)
		(layer "In11.Cu")
		(net "IRQ_PVCCIN_CPU0_VRHOT_LVC3_N")
	)
	(segment
		(start 189.6364 -27.6098)
		(end 193.383408 -31.356808)
		(width 0.089408)
		(layer "In11.Cu")
		(net "IRQ_PVCCIN_CPU0_VRHOT_LVC3_N")
	)
	(segment
		(start 185.463688 -59.696604)
		(end 185.463688 -61.891164)
		(width 0.089408)
		(layer "In11.Cu")
		(net "IRQ_PVCCIN_CPU0_VRHOT_LVC3_N")
	)
	(segment
		(start 383.159 -46.228)
		(end 383.159 -46.609)
		(width 0.10795)
		(layer "B.Cu")
		(net "IRQ_CPU1_VRHOT")
	)
	(segment
		(start 382.524 -45.9105)
		(end 382.524 -46.0883)
		(width 0.10795)
		(layer "B.Cu")
		(net "IRQ_CPU1_VRHOT")
	)
	(segment
		(start 383.02946 -46.73854)
		(end 382.524 -46.73854)
		(width 0.10795)
		(layer "B.Cu")
		(net "IRQ_CPU1_VRHOT")
	)
	(segment
		(start 383.2225 -45.212)
		(end 382.524 -45.9105)
		(width 0.10795)
		(layer "B.Cu")
		(net "IRQ_CPU1_VRHOT")
	)
	(segment
		(start 383.0193 -46.0883)
		(end 383.159 -46.228)
		(width 0.10795)
		(layer "B.Cu")
		(net "IRQ_CPU1_VRHOT")
	)
	(segment
		(start 382.524 -46.0883)
		(end 383.0193 -46.0883)
		(width 0.10795)
		(layer "B.Cu")
		(net "IRQ_CPU1_VRHOT")
	)
	(segment
		(start 383.2225 -44.958)
		(end 383.2225 -45.212)
		(width 0.10795)
		(layer "B.Cu")
		(net "IRQ_CPU1_VRHOT")
	)
	(segment
		(start 383.159 -46.609)
		(end 383.02946 -46.73854)
		(width 0.10795)
		(layer "B.Cu")
		(net "IRQ_CPU1_VRHOT")
	)
	(via
		(at 378.270008 -38.636194)
		(size 0.6604)
		(drill 0.3302)
		(layers "F.Cu" "B.Cu")
		(net "IRQ_CPU0_VRHOT")
	)
	(segment
		(start 377.2281 -38.087808)
		(end 377.529852 -38.38956)
		(width 0.10795)
		(layer "B.Cu")
		(net "IRQ_CPU0_VRHOT")
	)
	(segment
		(start 377.529852 -38.38956)
		(end 378.023374 -38.38956)
		(width 0.10795)
		(layer "B.Cu")
		(net "IRQ_CPU0_VRHOT")
	)
	(segment
		(start 376.009916 -37.713666)
		(end 376.578114 -37.713666)
		(width 0.10795)
		(layer "B.Cu")
		(net "IRQ_CPU0_VRHOT")
	)
	(segment
		(start 377.149868 -39.045896)
		(end 378.009404 -39.045896)
		(width 0.10795)
		(layer "B.Cu")
		(net "IRQ_CPU0_VRHOT")
	)
	(segment
		(start 376.686318 -38.582346)
		(end 377.149868 -39.045896)
		(width 0.10795)
		(layer "B.Cu")
		(net "IRQ_CPU0_VRHOT")
	)
	(segment
		(start 376.578114 -37.713666)
		(end 376.686318 -37.82187)
		(width 0.10795)
		(layer "B.Cu")
		(net "IRQ_CPU0_VRHOT")
	)
	(segment
		(start 376.686318 -37.82187)
		(end 376.686318 -38.582346)
		(width 0.10795)
		(layer "B.Cu")
		(net "IRQ_CPU0_VRHOT")
	)
	(segment
		(start 377.2281 -37.719)
		(end 377.2281 -38.087808)
		(width 0.10795)
		(layer "B.Cu")
		(net "IRQ_CPU0_VRHOT")
	)
	(segment
		(start 376.009916 -37.713666)
		(end 376.009916 -37.063426)
		(width 0.10795)
		(layer "B.Cu")
		(net "IRQ_CPU0_VRHOT")
	)
	(segment
		(start 378.270008 -38.785292)
		(end 378.270008 -38.636194)
		(width 0.10795)
		(layer "B.Cu")
		(net "IRQ_CPU0_VRHOT")
	)
	(segment
		(start 378.023374 -38.38956)
		(end 378.270008 -38.636194)
		(width 0.10795)
		(layer "B.Cu")
		(net "IRQ_CPU0_VRHOT")
	)
	(segment
		(start 378.009404 -39.045896)
		(end 378.270008 -38.785292)
		(width 0.10795)
		(layer "B.Cu")
		(net "IRQ_CPU0_VRHOT")
	)
	(segment
		(start 15.24 -87.63)
		(end 15.77848 -88.16848)
		(width 0.10795)
		(layer "F.Cu")
		(net "FM_PVCCIN_CPU1_PWR_IN_ALERT_N")
	)
	(segment
		(start 15.82928 -88.16848)
		(end 16.2052 -88.5444)
		(width 0.10795)
		(layer "F.Cu")
		(net "FM_PVCCIN_CPU1_PWR_IN_ALERT_N")
	)
	(segment
		(start 17.630902 -89.5604)
		(end 17.630902 -89.258902)
		(width 0.10795)
		(layer "F.Cu")
		(net "FM_PVCCIN_CPU1_PWR_IN_ALERT_N")
	)
	(segment
		(start 17.2466 -88.8746)
		(end 16.5354 -88.8746)
		(width 0.10795)
		(layer "F.Cu")
		(net "FM_PVCCIN_CPU1_PWR_IN_ALERT_N")
	)
	(segment
		(start 15.77848 -88.16848)
		(end 15.82928 -88.16848)
		(width 0.10795)
		(layer "F.Cu")
		(net "FM_PVCCIN_CPU1_PWR_IN_ALERT_N")
	)
	(segment
		(start 17.630902 -89.258902)
		(end 17.2466 -88.8746)
		(width 0.10795)
		(layer "F.Cu")
		(net "FM_PVCCIN_CPU1_PWR_IN_ALERT_N")
	)
	(segment
		(start 16.5354 -88.8746)
		(end 16.2052 -88.5444)
		(width 0.10795)
		(layer "F.Cu")
		(net "FM_PVCCIN_CPU1_PWR_IN_ALERT_N")
	)
	(via
		(at 351.112074 -138.129772)
		(size 0.508)
		(drill 0.254)
		(layers "F.Cu" "B.Cu")
		(net "FM_PVCCIN_CPU1_PWR_IN_ALERT_N")
	)
	(via
		(at 16.2052 -88.5444)
		(size 0.508)
		(drill 0.254)
		(layers "F.Cu" "B.Cu")
		(net "FM_PVCCIN_CPU1_PWR_IN_ALERT_N")
	)
	(via
		(at 357.1367 -51.0159)
		(size 0.6604)
		(drill 0.3302)
		(layers "F.Cu" "B.Cu")
		(net "FM_PVCCIN_CPU1_PWR_IN_ALERT_N")
	)
	(via
		(at 356.4636 -52.010564)
		(size 0.508)
		(drill 0.254)
		(layers "F.Cu" "B.Cu")
		(net "FM_PVCCIN_CPU1_PWR_IN_ALERT_N")
	)
	(via
		(at 357.720392 -85.454744)
		(size 0.508)
		(drill 0.254)
		(layers "F.Cu" "B.Cu")
		(net "FM_PVCCIN_CPU1_PWR_IN_ALERT_N")
	)
	(segment
		(start 357.1367 -51.0159)
		(end 356.4636 -51.689)
		(width 0.10795)
		(layer "B.Cu")
		(net "FM_PVCCIN_CPU1_PWR_IN_ALERT_N")
	)
	(segment
		(start 356.4636 -51.689)
		(end 356.4636 -52.010564)
		(width 0.10795)
		(layer "B.Cu")
		(net "FM_PVCCIN_CPU1_PWR_IN_ALERT_N")
	)
	(segment
		(start 365.630968 -50.171604)
		(end 361.474004 -50.171604)
		(width 0.10795)
		(layer "B.Cu")
		(net "FM_PVCCIN_CPU1_PWR_IN_ALERT_N")
	)
	(segment
		(start 375.722388 -48.7045)
		(end 375.112788 -49.3141)
		(width 0.10795)
		(layer "B.Cu")
		(net "FM_PVCCIN_CPU1_PWR_IN_ALERT_N")
	)
	(segment
		(start 367.031524 -49.42967)
		(end 366.850676 -49.610518)
		(width 0.10795)
		(layer "B.Cu")
		(net "FM_PVCCIN_CPU1_PWR_IN_ALERT_N")
	)
	(segment
		(start 376.004582 -47.007018)
		(end 375.722388 -47.289212)
		(width 0.10795)
		(layer "B.Cu")
		(net "FM_PVCCIN_CPU1_PWR_IN_ALERT_N")
	)
	(segment
		(start 375.722388 -47.289212)
		(end 375.722388 -48.7045)
		(width 0.10795)
		(layer "B.Cu")
		(net "FM_PVCCIN_CPU1_PWR_IN_ALERT_N")
	)
	(segment
		(start 368.35207 -50.128424)
		(end 367.653316 -49.42967)
		(width 0.10795)
		(layer "B.Cu")
		(net "FM_PVCCIN_CPU1_PWR_IN_ALERT_N")
	)
	(segment
		(start 366.845342 -49.610518)
		(end 366.282478 -50.173382)
		(width 0.10795)
		(layer "B.Cu")
		(net "FM_PVCCIN_CPU1_PWR_IN_ALERT_N")
	)
	(segment
		(start 360.912664 -49.610264)
		(end 358.542336 -49.610264)
		(width 0.10795)
		(layer "B.Cu")
		(net "FM_PVCCIN_CPU1_PWR_IN_ALERT_N")
	)
	(segment
		(start 358.542336 -49.610264)
		(end 357.1367 -51.0159)
		(width 0.10795)
		(layer "B.Cu")
		(net "FM_PVCCIN_CPU1_PWR_IN_ALERT_N")
	)
	(segment
		(start 365.632746 -50.173382)
		(end 365.630968 -50.171604)
		(width 0.10795)
		(layer "B.Cu")
		(net "FM_PVCCIN_CPU1_PWR_IN_ALERT_N")
	)
	(segment
		(start 373.5197 -49.3141)
		(end 372.705376 -50.128424)
		(width 0.10795)
		(layer "B.Cu")
		(net "FM_PVCCIN_CPU1_PWR_IN_ALERT_N")
	)
	(segment
		(start 361.474004 -50.171604)
		(end 360.912664 -49.610264)
		(width 0.10795)
		(layer "B.Cu")
		(net "FM_PVCCIN_CPU1_PWR_IN_ALERT_N")
	)
	(segment
		(start 367.653316 -49.42967)
		(end 367.031524 -49.42967)
		(width 0.10795)
		(layer "B.Cu")
		(net "FM_PVCCIN_CPU1_PWR_IN_ALERT_N")
	)
	(segment
		(start 366.850676 -49.610518)
		(end 366.845342 -49.610518)
		(width 0.10795)
		(layer "B.Cu")
		(net "FM_PVCCIN_CPU1_PWR_IN_ALERT_N")
	)
	(segment
		(start 372.705376 -50.128424)
		(end 368.35207 -50.128424)
		(width 0.10795)
		(layer "B.Cu")
		(net "FM_PVCCIN_CPU1_PWR_IN_ALERT_N")
	)
	(segment
		(start 376.418348 -47.007018)
		(end 376.004582 -47.007018)
		(width 0.10795)
		(layer "B.Cu")
		(net "FM_PVCCIN_CPU1_PWR_IN_ALERT_N")
	)
	(segment
		(start 375.112788 -49.3141)
		(end 373.5197 -49.3141)
		(width 0.10795)
		(layer "B.Cu")
		(net "FM_PVCCIN_CPU1_PWR_IN_ALERT_N")
	)
	(segment
		(start 366.282478 -50.173382)
		(end 365.632746 -50.173382)
		(width 0.10795)
		(layer "B.Cu")
		(net "FM_PVCCIN_CPU1_PWR_IN_ALERT_N")
	)
	(segment
		(start 342.821514 -115.39728)
		(end 343.257886 -115.39728)
		(width 0.089408)
		(layer "In4.Cu")
		(net "FM_PVCCIN_CPU1_PWR_IN_ALERT_N")
	)
	(segment
		(start 333.439516 -96.235774)
		(end 333.43977 -96.236028)
		(width 0.089408)
		(layer "In4.Cu")
		(net "FM_PVCCIN_CPU1_PWR_IN_ALERT_N")
	)
	(segment
		(start 342.348312 -106.331258)
		(end 342.348312 -114.924078)
		(width 0.089408)
		(layer "In4.Cu")
		(net "FM_PVCCIN_CPU1_PWR_IN_ALERT_N")
	)
	(segment
		(start 340.968584 -90.602816)
		(end 340.233 -91.3384)
		(width 0.089408)
		(layer "In4.Cu")
		(net "FM_PVCCIN_CPU1_PWR_IN_ALERT_N")
	)
	(segment
		(start 354.7872 -85.539834)
		(end 354.7872 -89.333832)
		(width 0.089408)
		(layer "In4.Cu")
		(net "FM_PVCCIN_CPU1_PWR_IN_ALERT_N")
	)
	(segment
		(start 343.931494 -116.675662)
		(end 344.433652 -117.17782)
		(width 0.089408)
		(layer "In4.Cu")
		(net "FM_PVCCIN_CPU1_PWR_IN_ALERT_N")
	)
	(segment
		(start 343.81567 -127.858266)
		(end 344.894408 -128.937004)
		(width 0.089408)
		(layer "In4.Cu")
		(net "FM_PVCCIN_CPU1_PWR_IN_ALERT_N")
	)
	(segment
		(start 344.433652 -120.991122)
		(end 343.81567 -121.609104)
		(width 0.089408)
		(layer "In4.Cu")
		(net "FM_PVCCIN_CPU1_PWR_IN_ALERT_N")
	)
	(segment
		(start 342.348312 -114.924078)
		(end 342.821514 -115.39728)
		(width 0.089408)
		(layer "In4.Cu")
		(net "FM_PVCCIN_CPU1_PWR_IN_ALERT_N")
	)
	(segment
		(start 340.233 -91.3384)
		(end 338.094574 -91.3384)
		(width 0.089408)
		(layer "In4.Cu")
		(net "FM_PVCCIN_CPU1_PWR_IN_ALERT_N")
	)
	(segment
		(start 344.894408 -133.063488)
		(end 346.494608 -134.663688)
		(width 0.089408)
		(layer "In4.Cu")
		(net "FM_PVCCIN_CPU1_PWR_IN_ALERT_N")
	)
	(segment
		(start 354.7872 -89.333832)
		(end 354.354892 -89.76614)
		(width 0.089408)
		(layer "In4.Cu")
		(net "FM_PVCCIN_CPU1_PWR_IN_ALERT_N")
	)
	(segment
		(start 343.931494 -116.070888)
		(end 343.931494 -116.675662)
		(width 0.089408)
		(layer "In4.Cu")
		(net "FM_PVCCIN_CPU1_PWR_IN_ALERT_N")
	)
	(segment
		(start 333.43977 -96.236028)
		(end 333.43977 -102.780592)
		(width 0.089408)
		(layer "In4.Cu")
		(net "FM_PVCCIN_CPU1_PWR_IN_ALERT_N")
	)
	(segment
		(start 346.494608 -134.663688)
		(end 349.339662 -134.663688)
		(width 0.089408)
		(layer "In4.Cu")
		(net "FM_PVCCIN_CPU1_PWR_IN_ALERT_N")
	)
	(segment
		(start 344.894408 -128.937004)
		(end 344.894408 -133.063488)
		(width 0.089408)
		(layer "In4.Cu")
		(net "FM_PVCCIN_CPU1_PWR_IN_ALERT_N")
	)
	(segment
		(start 350.769936 -90.602816)
		(end 340.968584 -90.602816)
		(width 0.089408)
		(layer "In4.Cu")
		(net "FM_PVCCIN_CPU1_PWR_IN_ALERT_N")
	)
	(segment
		(start 333.439516 -95.993458)
		(end 333.439516 -96.235774)
		(width 0.089408)
		(layer "In4.Cu")
		(net "FM_PVCCIN_CPU1_PWR_IN_ALERT_N")
	)
	(segment
		(start 340.623398 -104.606344)
		(end 342.348312 -106.331258)
		(width 0.089408)
		(layer "In4.Cu")
		(net "FM_PVCCIN_CPU1_PWR_IN_ALERT_N")
	)
	(segment
		(start 349.339662 -134.663688)
		(end 349.813372 -135.137398)
		(width 0.089408)
		(layer "In4.Cu")
		(net "FM_PVCCIN_CPU1_PWR_IN_ALERT_N")
	)
	(segment
		(start 338.094574 -91.3384)
		(end 333.439516 -95.993458)
		(width 0.089408)
		(layer "In4.Cu")
		(net "FM_PVCCIN_CPU1_PWR_IN_ALERT_N")
	)
	(segment
		(start 354.354892 -89.76614)
		(end 351.606612 -89.76614)
		(width 0.089408)
		(layer "In4.Cu")
		(net "FM_PVCCIN_CPU1_PWR_IN_ALERT_N")
	)
	(segment
		(start 335.265522 -104.606344)
		(end 340.623398 -104.606344)
		(width 0.089408)
		(layer "In4.Cu")
		(net "FM_PVCCIN_CPU1_PWR_IN_ALERT_N")
	)
	(segment
		(start 333.43977 -102.780592)
		(end 335.265522 -104.606344)
		(width 0.089408)
		(layer "In4.Cu")
		(net "FM_PVCCIN_CPU1_PWR_IN_ALERT_N")
	)
	(segment
		(start 343.257886 -115.39728)
		(end 343.931494 -116.070888)
		(width 0.089408)
		(layer "In4.Cu")
		(net "FM_PVCCIN_CPU1_PWR_IN_ALERT_N")
	)
	(segment
		(start 357.720392 -85.454744)
		(end 357.178864 -85.454744)
		(width 0.089408)
		(layer "In4.Cu")
		(net "FM_PVCCIN_CPU1_PWR_IN_ALERT_N")
	)
	(segment
		(start 343.81567 -121.609104)
		(end 343.81567 -127.858266)
		(width 0.089408)
		(layer "In4.Cu")
		(net "FM_PVCCIN_CPU1_PWR_IN_ALERT_N")
	)
	(segment
		(start 356.515416 -84.791296)
		(end 355.535738 -84.791296)
		(width 0.089408)
		(layer "In4.Cu")
		(net "FM_PVCCIN_CPU1_PWR_IN_ALERT_N")
	)
	(segment
		(start 357.178864 -85.454744)
		(end 356.515416 -84.791296)
		(width 0.089408)
		(layer "In4.Cu")
		(net "FM_PVCCIN_CPU1_PWR_IN_ALERT_N")
	)
	(segment
		(start 351.606612 -89.76614)
		(end 350.769936 -90.602816)
		(width 0.089408)
		(layer "In4.Cu")
		(net "FM_PVCCIN_CPU1_PWR_IN_ALERT_N")
	)
	(segment
		(start 351.112074 -135.85571)
		(end 351.112074 -138.129772)
		(width 0.089408)
		(layer "In4.Cu")
		(net "FM_PVCCIN_CPU1_PWR_IN_ALERT_N")
	)
	(segment
		(start 349.813372 -135.137398)
		(end 350.393762 -135.137398)
		(width 0.089408)
		(layer "In4.Cu")
		(net "FM_PVCCIN_CPU1_PWR_IN_ALERT_N")
	)
	(segment
		(start 350.393762 -135.137398)
		(end 351.112074 -135.85571)
		(width 0.089408)
		(layer "In4.Cu")
		(net "FM_PVCCIN_CPU1_PWR_IN_ALERT_N")
	)
	(segment
		(start 344.433652 -117.17782)
		(end 344.433652 -120.991122)
		(width 0.089408)
		(layer "In4.Cu")
		(net "FM_PVCCIN_CPU1_PWR_IN_ALERT_N")
	)
	(segment
		(start 355.535738 -84.791296)
		(end 354.7872 -85.539834)
		(width 0.089408)
		(layer "In4.Cu")
		(net "FM_PVCCIN_CPU1_PWR_IN_ALERT_N")
	)
	(segment
		(start 358.18826 -84.986876)
		(end 357.720392 -85.454744)
		(width 0.089408)
		(layer "In9.Cu")
		(net "FM_PVCCIN_CPU1_PWR_IN_ALERT_N")
	)
	(segment
		(start 355.920294 -76.53274)
		(end 355.920294 -79.636874)
		(width 0.089408)
		(layer "In9.Cu")
		(net "FM_PVCCIN_CPU1_PWR_IN_ALERT_N")
	)
	(segment
		(start 357.646478 -56.750458)
		(end 358.18445 -57.28843)
		(width 0.089408)
		(layer "In9.Cu")
		(net "FM_PVCCIN_CPU1_PWR_IN_ALERT_N")
	)
	(segment
		(start 357.28275 -64.737488)
		(end 355.7397 -66.281554)
		(width 0.089408)
		(layer "In9.Cu")
		(net "FM_PVCCIN_CPU1_PWR_IN_ALERT_N")
	)
	(segment
		(start 357.28275 -63.528956)
		(end 357.28275 -64.737488)
		(width 0.089408)
		(layer "In9.Cu")
		(net "FM_PVCCIN_CPU1_PWR_IN_ALERT_N")
	)
	(segment
		(start 356.80142 -82.92465)
		(end 358.18826 -84.31149)
		(width 0.089408)
		(layer "In9.Cu")
		(net "FM_PVCCIN_CPU1_PWR_IN_ALERT_N")
	)
	(segment
		(start 357.770684 -63.041022)
		(end 357.28275 -63.528956)
		(width 0.089408)
		(layer "In9.Cu")
		(net "FM_PVCCIN_CPU1_PWR_IN_ALERT_N")
	)
	(segment
		(start 358.016048 -61.886592)
		(end 357.770684 -63.041022)
		(width 0.089408)
		(layer "In9.Cu")
		(net "FM_PVCCIN_CPU1_PWR_IN_ALERT_N")
	)
	(segment
		(start 355.731064 -72.828404)
		(end 356.87 -73.96734)
		(width 0.089408)
		(layer "In9.Cu")
		(net "FM_PVCCIN_CPU1_PWR_IN_ALERT_N")
	)
	(segment
		(start 357.646478 -56.297322)
		(end 357.646478 -56.750458)
		(width 0.089408)
		(layer "In9.Cu")
		(net "FM_PVCCIN_CPU1_PWR_IN_ALERT_N")
	)
	(segment
		(start 355.920294 -79.636874)
		(end 356.80142 -80.518)
		(width 0.089408)
		(layer "In9.Cu")
		(net "FM_PVCCIN_CPU1_PWR_IN_ALERT_N")
	)
	(segment
		(start 355.7397 -66.281554)
		(end 355.7397 -71.817738)
		(width 0.089408)
		(layer "In9.Cu")
		(net "FM_PVCCIN_CPU1_PWR_IN_ALERT_N")
	)
	(segment
		(start 355.7397 -71.817738)
		(end 355.731064 -71.826374)
		(width 0.089408)
		(layer "In9.Cu")
		(net "FM_PVCCIN_CPU1_PWR_IN_ALERT_N")
	)
	(segment
		(start 358.18445 -57.28843)
		(end 358.18445 -60.953142)
		(width 0.089408)
		(layer "In9.Cu")
		(net "FM_PVCCIN_CPU1_PWR_IN_ALERT_N")
	)
	(segment
		(start 356.87 -73.96734)
		(end 356.87 -75.583034)
		(width 0.089408)
		(layer "In9.Cu")
		(net "FM_PVCCIN_CPU1_PWR_IN_ALERT_N")
	)
	(segment
		(start 355.731064 -71.826374)
		(end 355.731064 -72.828404)
		(width 0.089408)
		(layer "In9.Cu")
		(net "FM_PVCCIN_CPU1_PWR_IN_ALERT_N")
	)
	(segment
		(start 357.366062 -52.913026)
		(end 357.366062 -56.016906)
		(width 0.089408)
		(layer "In9.Cu")
		(net "FM_PVCCIN_CPU1_PWR_IN_ALERT_N")
	)
	(segment
		(start 356.4636 -52.010564)
		(end 357.366062 -52.913026)
		(width 0.089408)
		(layer "In9.Cu")
		(net "FM_PVCCIN_CPU1_PWR_IN_ALERT_N")
	)
	(segment
		(start 356.80142 -80.518)
		(end 356.80142 -82.92465)
		(width 0.089408)
		(layer "In9.Cu")
		(net "FM_PVCCIN_CPU1_PWR_IN_ALERT_N")
	)
	(segment
		(start 358.18826 -84.31149)
		(end 358.18826 -84.986876)
		(width 0.089408)
		(layer "In9.Cu")
		(net "FM_PVCCIN_CPU1_PWR_IN_ALERT_N")
	)
	(segment
		(start 357.366062 -56.016906)
		(end 357.646478 -56.297322)
		(width 0.089408)
		(layer "In9.Cu")
		(net "FM_PVCCIN_CPU1_PWR_IN_ALERT_N")
	)
	(segment
		(start 356.87 -75.583034)
		(end 355.920294 -76.53274)
		(width 0.089408)
		(layer "In9.Cu")
		(net "FM_PVCCIN_CPU1_PWR_IN_ALERT_N")
	)
	(segment
		(start 358.18445 -60.953142)
		(end 358.016048 -61.121544)
		(width 0.089408)
		(layer "In9.Cu")
		(net "FM_PVCCIN_CPU1_PWR_IN_ALERT_N")
	)
	(segment
		(start 358.016048 -61.121544)
		(end 358.016048 -61.886592)
		(width 0.089408)
		(layer "In9.Cu")
		(net "FM_PVCCIN_CPU1_PWR_IN_ALERT_N")
	)
	(segment
		(start 157.27426 -157.827726)
		(end 157.26791 -157.827726)
		(width 0.089408)
		(layer "In11.Cu")
		(net "FM_PVCCIN_CPU1_PWR_IN_ALERT_N")
	)
	(segment
		(start 188.123322 -157.998668)
		(end 185.826654 -155.702)
		(width 0.089408)
		(layer "In11.Cu")
		(net "FM_PVCCIN_CPU1_PWR_IN_ALERT_N")
	)
	(segment
		(start 329.7936 -141.2494)
		(end 329.1332 -141.9098)
		(width 0.089408)
		(layer "In11.Cu")
		(net "FM_PVCCIN_CPU1_PWR_IN_ALERT_N")
	)
	(segment
		(start 20.52828 -129.71018)
		(end 21.31314 -128.92532)
		(width 0.089408)
		(layer "In11.Cu")
		(net "FM_PVCCIN_CPU1_PWR_IN_ALERT_N")
	)
	(segment
		(start 329.7936 -139.921234)
		(end 329.7936 -141.2494)
		(width 0.089408)
		(layer "In11.Cu")
		(net "FM_PVCCIN_CPU1_PWR_IN_ALERT_N")
	)
	(segment
		(start 18.18386 -110.42396)
		(end 16.826992 -109.067092)
		(width 0.089408)
		(layer "In11.Cu")
		(net "FM_PVCCIN_CPU1_PWR_IN_ALERT_N")
	)
	(segment
		(start 329.1332 -146.4056)
		(end 327.787 -147.7518)
		(width 0.089408)
		(layer "In11.Cu")
		(net "FM_PVCCIN_CPU1_PWR_IN_ALERT_N")
	)
	(segment
		(start 160.734502 -156.1084)
		(end 160.733994 -156.1084)
		(width 0.089408)
		(layer "In11.Cu")
		(net "FM_PVCCIN_CPU1_PWR_IN_ALERT_N")
	)
	(segment
		(start 335.904078 -138.10996)
		(end 335.609438 -138.4046)
		(width 0.089408)
		(layer "In11.Cu")
		(net "FM_PVCCIN_CPU1_PWR_IN_ALERT_N")
	)
	(segment
		(start 160.628076 -156.002482)
		(end 160.296352 -156.002482)
		(width 0.089408)
		(layer "In11.Cu")
		(net "FM_PVCCIN_CPU1_PWR_IN_ALERT_N")
	)
	(segment
		(start 78.765908 -157.9372)
		(end 78.105 -158.598108)
		(width 0.089408)
		(layer "In11.Cu")
		(net "FM_PVCCIN_CPU1_PWR_IN_ALERT_N")
	)
	(segment
		(start 326.5424 -147.7518)
		(end 325.9328 -147.1422)
		(width 0.089408)
		(layer "In11.Cu")
		(net "FM_PVCCIN_CPU1_PWR_IN_ALERT_N")
	)
	(segment
		(start 265.667998 -157.88386)
		(end 265.661902 -157.88386)
		(width 0.089408)
		(layer "In11.Cu")
		(net "FM_PVCCIN_CPU1_PWR_IN_ALERT_N")
	)
	(segment
		(start 112.937544 -157.9372)
		(end 78.765908 -157.9372)
		(width 0.089408)
		(layer "In11.Cu")
		(net "FM_PVCCIN_CPU1_PWR_IN_ALERT_N")
	)
	(segment
		(start 158.326328 -157.776926)
		(end 157.32506 -157.776926)
		(width 0.089408)
		(layer "In11.Cu")
		(net "FM_PVCCIN_CPU1_PWR_IN_ALERT_N")
	)
	(segment
		(start 16.826992 -107.225592)
		(end 13.92428 -104.32288)
		(width 0.089408)
		(layer "In11.Cu")
		(net "FM_PVCCIN_CPU1_PWR_IN_ALERT_N")
	)
	(segment
		(start 20.826984 -126.697994)
		(end 20.826984 -114.630708)
		(width 0.089408)
		(layer "In11.Cu")
		(net "FM_PVCCIN_CPU1_PWR_IN_ALERT_N")
	)
	(segment
		(start 168.491408 -153.758392)
		(end 165.638226 -153.758392)
		(width 0.089408)
		(layer "In11.Cu")
		(net "FM_PVCCIN_CPU1_PWR_IN_ALERT_N")
	)
	(segment
		(start 265.644376 -157.8991)
		(end 265.544808 -157.998668)
		(width 0.089408)
		(layer "In11.Cu")
		(net "FM_PVCCIN_CPU1_PWR_IN_ALERT_N")
	)
	(segment
		(start 350.96831 -138.273536)
		(end 337.589622 -138.273536)
		(width 0.089408)
		(layer "In11.Cu")
		(net "FM_PVCCIN_CPU1_PWR_IN_ALERT_N")
	)
	(segment
		(start 265.646662 -157.8991)
		(end 265.644376 -157.8991)
		(width 0.089408)
		(layer "In11.Cu")
		(net "FM_PVCCIN_CPU1_PWR_IN_ALERT_N")
	)
	(segment
		(start 162.842194 -156.554424)
		(end 161.180526 -156.554424)
		(width 0.089408)
		(layer "In11.Cu")
		(net "FM_PVCCIN_CPU1_PWR_IN_ALERT_N")
	)
	(segment
		(start 321.955668 -157.850078)
		(end 265.70178 -157.850078)
		(width 0.089408)
		(layer "In11.Cu")
		(net "FM_PVCCIN_CPU1_PWR_IN_ALERT_N")
	)
	(segment
		(start 337.589622 -138.273536)
		(end 337.426046 -138.10996)
		(width 0.089408)
		(layer "In11.Cu")
		(net "FM_PVCCIN_CPU1_PWR_IN_ALERT_N")
	)
	(segment
		(start 174.054008 -150.202392)
		(end 172.9232 -151.3332)
		(width 0.089408)
		(layer "In11.Cu")
		(net "FM_PVCCIN_CPU1_PWR_IN_ALERT_N")
	)
	(segment
		(start 21.34616 -156.88564)
		(end 21.181822 -156.721302)
		(width 0.089408)
		(layer "In11.Cu")
		(net "FM_PVCCIN_CPU1_PWR_IN_ALERT_N")
	)
	(segment
		(start 325.9328 -147.1422)
		(end 325.5772 -147.1422)
		(width 0.089408)
		(layer "In11.Cu")
		(net "FM_PVCCIN_CPU1_PWR_IN_ALERT_N")
	)
	(segment
		(start 335.609438 -138.4046)
		(end 334.826864 -138.4046)
		(width 0.089408)
		(layer "In11.Cu")
		(net "FM_PVCCIN_CPU1_PWR_IN_ALERT_N")
	)
	(segment
		(start 329.1332 -141.9098)
		(end 329.1332 -146.4056)
		(width 0.089408)
		(layer "In11.Cu")
		(net "FM_PVCCIN_CPU1_PWR_IN_ALERT_N")
	)
	(segment
		(start 330.421234 -139.2936)
		(end 329.7936 -139.921234)
		(width 0.089408)
		(layer "In11.Cu")
		(net "FM_PVCCIN_CPU1_PWR_IN_ALERT_N")
	)
	(segment
		(start 13.76807 -90.877898)
		(end 13.76807 -90.00363)
		(width 0.089408)
		(layer "In11.Cu")
		(net "FM_PVCCIN_CPU1_PWR_IN_ALERT_N")
	)
	(segment
		(start 78.105 -158.598108)
		(end 22.116288 -158.598108)
		(width 0.089408)
		(layer "In11.Cu")
		(net "FM_PVCCIN_CPU1_PWR_IN_ALERT_N")
	)
	(segment
		(start 177.015648 -150.202392)
		(end 174.054008 -150.202392)
		(width 0.089408)
		(layer "In11.Cu")
		(net "FM_PVCCIN_CPU1_PWR_IN_ALERT_N")
	)
	(segment
		(start 185.826654 -155.702)
		(end 181.507638 -155.702)
		(width 0.089408)
		(layer "In11.Cu")
		(net "FM_PVCCIN_CPU1_PWR_IN_ALERT_N")
	)
	(segment
		(start 172.9232 -151.3332)
		(end 170.9166 -151.3332)
		(width 0.089408)
		(layer "In11.Cu")
		(net "FM_PVCCIN_CPU1_PWR_IN_ALERT_N")
	)
	(segment
		(start 325.2724 -149.6822)
		(end 324.712584 -150.242016)
		(width 0.089408)
		(layer "In11.Cu")
		(net "FM_PVCCIN_CPU1_PWR_IN_ALERT_N")
	)
	(segment
		(start 157.32506 -157.776926)
		(end 157.27426 -157.827726)
		(width 0.089408)
		(layer "In11.Cu")
		(net "FM_PVCCIN_CPU1_PWR_IN_ALERT_N")
	)
	(segment
		(start 351.112074 -138.129772)
		(end 350.96831 -138.273536)
		(width 0.089408)
		(layer "In11.Cu")
		(net "FM_PVCCIN_CPU1_PWR_IN_ALERT_N")
	)
	(segment
		(start 324.712584 -150.242016)
		(end 324.712584 -155.093162)
		(width 0.089408)
		(layer "In11.Cu")
		(net "FM_PVCCIN_CPU1_PWR_IN_ALERT_N")
	)
	(segment
		(start 21.181822 -135.392922)
		(end 20.52828 -134.73938)
		(width 0.089408)
		(layer "In11.Cu")
		(net "FM_PVCCIN_CPU1_PWR_IN_ALERT_N")
	)
	(segment
		(start 159.994854 -156.1084)
		(end 158.326328 -157.776926)
		(width 0.089408)
		(layer "In11.Cu")
		(net "FM_PVCCIN_CPU1_PWR_IN_ALERT_N")
	)
	(segment
		(start 16.826992 -109.067092)
		(end 16.826992 -107.225592)
		(width 0.089408)
		(layer "In11.Cu")
		(net "FM_PVCCIN_CPU1_PWR_IN_ALERT_N")
	)
	(segment
		(start 157.26791 -157.827726)
		(end 157.260036 -157.8356)
		(width 0.089408)
		(layer "In11.Cu")
		(net "FM_PVCCIN_CPU1_PWR_IN_ALERT_N")
	)
	(segment
		(start 160.733994 -156.1084)
		(end 160.628076 -156.002482)
		(width 0.089408)
		(layer "In11.Cu")
		(net "FM_PVCCIN_CPU1_PWR_IN_ALERT_N")
	)
	(segment
		(start 161.180526 -156.554424)
		(end 160.734502 -156.1084)
		(width 0.089408)
		(layer "In11.Cu")
		(net "FM_PVCCIN_CPU1_PWR_IN_ALERT_N")
	)
	(segment
		(start 324.712584 -155.093162)
		(end 321.955668 -157.850078)
		(width 0.089408)
		(layer "In11.Cu")
		(net "FM_PVCCIN_CPU1_PWR_IN_ALERT_N")
	)
	(segment
		(start 20.826984 -114.630708)
		(end 18.18386 -111.987584)
		(width 0.089408)
		(layer "In11.Cu")
		(net "FM_PVCCIN_CPU1_PWR_IN_ALERT_N")
	)
	(segment
		(start 160.190434 -156.1084)
		(end 159.994854 -156.1084)
		(width 0.089408)
		(layer "In11.Cu")
		(net "FM_PVCCIN_CPU1_PWR_IN_ALERT_N")
	)
	(segment
		(start 113.039144 -157.8356)
		(end 112.937544 -157.9372)
		(width 0.089408)
		(layer "In11.Cu")
		(net "FM_PVCCIN_CPU1_PWR_IN_ALERT_N")
	)
	(segment
		(start 15.850362 -88.899238)
		(end 16.2052 -88.5444)
		(width 0.089408)
		(layer "In11.Cu")
		(net "FM_PVCCIN_CPU1_PWR_IN_ALERT_N")
	)
	(segment
		(start 20.52828 -134.73938)
		(end 20.52828 -129.71018)
		(width 0.089408)
		(layer "In11.Cu")
		(net "FM_PVCCIN_CPU1_PWR_IN_ALERT_N")
	)
	(segment
		(start 13.92428 -104.32288)
		(end 13.713714 -104.32288)
		(width 0.089408)
		(layer "In11.Cu")
		(net "FM_PVCCIN_CPU1_PWR_IN_ALERT_N")
	)
	(segment
		(start 265.661902 -157.88386)
		(end 265.646662 -157.8991)
		(width 0.089408)
		(layer "In11.Cu")
		(net "FM_PVCCIN_CPU1_PWR_IN_ALERT_N")
	)
	(segment
		(start 325.5772 -147.1422)
		(end 325.2724 -147.447)
		(width 0.089408)
		(layer "In11.Cu")
		(net "FM_PVCCIN_CPU1_PWR_IN_ALERT_N")
	)
	(segment
		(start 180.3654 -153.552144)
		(end 177.015648 -150.202392)
		(width 0.089408)
		(layer "In11.Cu")
		(net "FM_PVCCIN_CPU1_PWR_IN_ALERT_N")
	)
	(segment
		(start 165.638226 -153.758392)
		(end 162.842194 -156.554424)
		(width 0.089408)
		(layer "In11.Cu")
		(net "FM_PVCCIN_CPU1_PWR_IN_ALERT_N")
	)
	(segment
		(start 13.713714 -104.32288)
		(end 11.881104 -102.49027)
		(width 0.089408)
		(layer "In11.Cu")
		(net "FM_PVCCIN_CPU1_PWR_IN_ALERT_N")
	)
	(segment
		(start 337.426046 -138.10996)
		(end 335.904078 -138.10996)
		(width 0.089408)
		(layer "In11.Cu")
		(net "FM_PVCCIN_CPU1_PWR_IN_ALERT_N")
	)
	(segment
		(start 21.181822 -156.721302)
		(end 21.181822 -135.392922)
		(width 0.089408)
		(layer "In11.Cu")
		(net "FM_PVCCIN_CPU1_PWR_IN_ALERT_N")
	)
	(segment
		(start 334.826864 -138.4046)
		(end 333.937864 -139.2936)
		(width 0.089408)
		(layer "In11.Cu")
		(net "FM_PVCCIN_CPU1_PWR_IN_ALERT_N")
	)
	(segment
		(start 265.544808 -157.998668)
		(end 188.123322 -157.998668)
		(width 0.089408)
		(layer "In11.Cu")
		(net "FM_PVCCIN_CPU1_PWR_IN_ALERT_N")
	)
	(segment
		(start 170.9166 -151.3332)
		(end 168.491408 -153.758392)
		(width 0.089408)
		(layer "In11.Cu")
		(net "FM_PVCCIN_CPU1_PWR_IN_ALERT_N")
	)
	(segment
		(start 13.76807 -90.00363)
		(end 14.872462 -88.899238)
		(width 0.089408)
		(layer "In11.Cu")
		(net "FM_PVCCIN_CPU1_PWR_IN_ALERT_N")
	)
	(segment
		(start 333.937864 -139.2936)
		(end 330.421234 -139.2936)
		(width 0.089408)
		(layer "In11.Cu")
		(net "FM_PVCCIN_CPU1_PWR_IN_ALERT_N")
	)
	(segment
		(start 18.18386 -111.987584)
		(end 18.18386 -110.42396)
		(width 0.089408)
		(layer "In11.Cu")
		(net "FM_PVCCIN_CPU1_PWR_IN_ALERT_N")
	)
	(segment
		(start 181.507638 -155.702)
		(end 180.3654 -154.559762)
		(width 0.089408)
		(layer "In11.Cu")
		(net "FM_PVCCIN_CPU1_PWR_IN_ALERT_N")
	)
	(segment
		(start 11.881104 -92.764864)
		(end 13.76807 -90.877898)
		(width 0.089408)
		(layer "In11.Cu")
		(net "FM_PVCCIN_CPU1_PWR_IN_ALERT_N")
	)
	(segment
		(start 265.70178 -157.850078)
		(end 265.667998 -157.88386)
		(width 0.089408)
		(layer "In11.Cu")
		(net "FM_PVCCIN_CPU1_PWR_IN_ALERT_N")
	)
	(segment
		(start 11.881104 -102.49027)
		(end 11.881104 -92.764864)
		(width 0.089408)
		(layer "In11.Cu")
		(net "FM_PVCCIN_CPU1_PWR_IN_ALERT_N")
	)
	(segment
		(start 160.296352 -156.002482)
		(end 160.190434 -156.1084)
		(width 0.089408)
		(layer "In11.Cu")
		(net "FM_PVCCIN_CPU1_PWR_IN_ALERT_N")
	)
	(segment
		(start 325.2724 -147.447)
		(end 325.2724 -149.6822)
		(width 0.089408)
		(layer "In11.Cu")
		(net "FM_PVCCIN_CPU1_PWR_IN_ALERT_N")
	)
	(segment
		(start 22.116288 -158.598108)
		(end 21.34616 -157.82798)
		(width 0.089408)
		(layer "In11.Cu")
		(net "FM_PVCCIN_CPU1_PWR_IN_ALERT_N")
	)
	(segment
		(start 21.31314 -127.18415)
		(end 20.826984 -126.697994)
		(width 0.089408)
		(layer "In11.Cu")
		(net "FM_PVCCIN_CPU1_PWR_IN_ALERT_N")
	)
	(segment
		(start 21.31314 -128.92532)
		(end 21.31314 -127.18415)
		(width 0.089408)
		(layer "In11.Cu")
		(net "FM_PVCCIN_CPU1_PWR_IN_ALERT_N")
	)
	(segment
		(start 21.34616 -157.82798)
		(end 21.34616 -156.88564)
		(width 0.089408)
		(layer "In11.Cu")
		(net "FM_PVCCIN_CPU1_PWR_IN_ALERT_N")
	)
	(segment
		(start 327.787 -147.7518)
		(end 326.5424 -147.7518)
		(width 0.089408)
		(layer "In11.Cu")
		(net "FM_PVCCIN_CPU1_PWR_IN_ALERT_N")
	)
	(segment
		(start 180.3654 -154.559762)
		(end 180.3654 -153.552144)
		(width 0.089408)
		(layer "In11.Cu")
		(net "FM_PVCCIN_CPU1_PWR_IN_ALERT_N")
	)
	(segment
		(start 157.260036 -157.8356)
		(end 113.039144 -157.8356)
		(width 0.089408)
		(layer "In11.Cu")
		(net "FM_PVCCIN_CPU1_PWR_IN_ALERT_N")
	)
	(segment
		(start 14.872462 -88.899238)
		(end 15.850362 -88.899238)
		(width 0.089408)
		(layer "In11.Cu")
		(net "FM_PVCCIN_CPU1_PWR_IN_ALERT_N")
	)
	(segment
		(start 182.476902 -66.576702)
		(end 181.6608 -65.7606)
		(width 0.10795)
		(layer "F.Cu")
		(net "FM_PVCCIN_CPU0_PWR_IN_ALERT_N")
	)
	(segment
		(start 181.3306 -65.7606)
		(end 181.6608 -65.7606)
		(width 0.10795)
		(layer "F.Cu")
		(net "FM_PVCCIN_CPU0_PWR_IN_ALERT_N")
	)
	(segment
		(start 182.476902 -66.9544)
		(end 182.476902 -66.576702)
		(width 0.10795)
		(layer "F.Cu")
		(net "FM_PVCCIN_CPU0_PWR_IN_ALERT_N")
	)
	(segment
		(start 180.594 -65.024)
		(end 181.3306 -65.7606)
		(width 0.10795)
		(layer "F.Cu")
		(net "FM_PVCCIN_CPU0_PWR_IN_ALERT_N")
	)
	(via
		(at 181.6608 -65.7606)
		(size 0.508)
		(drill 0.254)
		(layers "F.Cu" "B.Cu")
		(net "FM_PVCCIN_CPU0_PWR_IN_ALERT_N")
	)
	(via
		(at 337.2866 -36.301172)
		(size 0.508)
		(drill 0.254)
		(layers "F.Cu" "B.Cu")
		(net "FM_PVCCIN_CPU0_PWR_IN_ALERT_N")
	)
	(via
		(at 320.4972 -39.363142)
		(size 0.508)
		(drill 0.254)
		(layers "F.Cu" "B.Cu")
		(net "FM_PVCCIN_CPU0_PWR_IN_ALERT_N")
	)
	(via
		(at 368.70386 -35.2425)
		(size 0.508)
		(drill 0.254)
		(layers "F.Cu" "B.Cu")
		(net "FM_PVCCIN_CPU0_PWR_IN_ALERT_N")
	)
	(via
		(at 192.2272 -25.2476)
		(size 0.508)
		(drill 0.254)
		(layers "F.Cu" "B.Cu")
		(net "FM_PVCCIN_CPU0_PWR_IN_ALERT_N")
	)
	(segment
		(start 370.5479 -37.08654)
		(end 370.929916 -37.08654)
		(width 0.10795)
		(layer "B.Cu")
		(net "FM_PVCCIN_CPU0_PWR_IN_ALERT_N")
	)
	(segment
		(start 368.70386 -35.2425)
		(end 370.5479 -37.08654)
		(width 0.10795)
		(layer "B.Cu")
		(net "FM_PVCCIN_CPU0_PWR_IN_ALERT_N")
	)
	(segment
		(start 333.044038 -37.669216)
		(end 331.872336 -37.669216)
		(width 0.089408)
		(layer "In2.Cu")
		(net "FM_PVCCIN_CPU0_PWR_IN_ALERT_N")
	)
	(segment
		(start 325.685404 -38.823392)
		(end 323.808852 -38.823392)
		(width 0.089408)
		(layer "In2.Cu")
		(net "FM_PVCCIN_CPU0_PWR_IN_ALERT_N")
	)
	(segment
		(start 331.872336 -37.669216)
		(end 330.37653 -36.17341)
		(width 0.089408)
		(layer "In2.Cu")
		(net "FM_PVCCIN_CPU0_PWR_IN_ALERT_N")
	)
	(segment
		(start 320.691764 -39.363142)
		(end 320.4972 -39.363142)
		(width 0.089408)
		(layer "In2.Cu")
		(net "FM_PVCCIN_CPU0_PWR_IN_ALERT_N")
	)
	(segment
		(start 333.430626 -38.055804)
		(end 333.044038 -37.669216)
		(width 0.089408)
		(layer "In2.Cu")
		(net "FM_PVCCIN_CPU0_PWR_IN_ALERT_N")
	)
	(segment
		(start 337.2866 -36.301172)
		(end 337.2866 -37.225224)
		(width 0.089408)
		(layer "In2.Cu")
		(net "FM_PVCCIN_CPU0_PWR_IN_ALERT_N")
	)
	(segment
		(start 330.37653 -36.17341)
		(end 328.335386 -36.17341)
		(width 0.089408)
		(layer "In2.Cu")
		(net "FM_PVCCIN_CPU0_PWR_IN_ALERT_N")
	)
	(segment
		(start 321.3862 -40.057578)
		(end 320.691764 -39.363142)
		(width 0.089408)
		(layer "In2.Cu")
		(net "FM_PVCCIN_CPU0_PWR_IN_ALERT_N")
	)
	(segment
		(start 323.808852 -38.823392)
		(end 322.574666 -40.057578)
		(width 0.089408)
		(layer "In2.Cu")
		(net "FM_PVCCIN_CPU0_PWR_IN_ALERT_N")
	)
	(segment
		(start 322.574666 -40.057578)
		(end 321.3862 -40.057578)
		(width 0.089408)
		(layer "In2.Cu")
		(net "FM_PVCCIN_CPU0_PWR_IN_ALERT_N")
	)
	(segment
		(start 336.45602 -38.055804)
		(end 333.430626 -38.055804)
		(width 0.089408)
		(layer "In2.Cu")
		(net "FM_PVCCIN_CPU0_PWR_IN_ALERT_N")
	)
	(segment
		(start 337.2866 -37.225224)
		(end 336.45602 -38.055804)
		(width 0.089408)
		(layer "In2.Cu")
		(net "FM_PVCCIN_CPU0_PWR_IN_ALERT_N")
	)
	(segment
		(start 328.335386 -36.17341)
		(end 325.685404 -38.823392)
		(width 0.089408)
		(layer "In2.Cu")
		(net "FM_PVCCIN_CPU0_PWR_IN_ALERT_N")
	)
	(segment
		(start 320.085974 -39.774368)
		(end 313.69508 -39.774368)
		(width 0.089408)
		(layer "In9.Cu")
		(net "FM_PVCCIN_CPU0_PWR_IN_ALERT_N")
	)
	(segment
		(start 304.567082 -30.64637)
		(end 265.451336 -30.64637)
		(width 0.089408)
		(layer "In9.Cu")
		(net "FM_PVCCIN_CPU0_PWR_IN_ALERT_N")
	)
	(segment
		(start 265.451336 -30.64637)
		(end 263.275826 -28.47086)
		(width 0.089408)
		(layer "In9.Cu")
		(net "FM_PVCCIN_CPU0_PWR_IN_ALERT_N")
	)
	(segment
		(start 246.490236 -27.2288)
		(end 244.977412 -25.715976)
		(width 0.089408)
		(layer "In9.Cu")
		(net "FM_PVCCIN_CPU0_PWR_IN_ALERT_N")
	)
	(segment
		(start 244.977412 -25.715976)
		(end 243.896896 -25.715976)
		(width 0.089408)
		(layer "In9.Cu")
		(net "FM_PVCCIN_CPU0_PWR_IN_ALERT_N")
	)
	(segment
		(start 243.896896 -25.715976)
		(end 243.42852 -25.2476)
		(width 0.089408)
		(layer "In9.Cu")
		(net "FM_PVCCIN_CPU0_PWR_IN_ALERT_N")
	)
	(segment
		(start 313.69508 -39.774368)
		(end 304.567082 -30.64637)
		(width 0.089408)
		(layer "In9.Cu")
		(net "FM_PVCCIN_CPU0_PWR_IN_ALERT_N")
	)
	(segment
		(start 243.42852 -25.2476)
		(end 192.2272 -25.2476)
		(width 0.089408)
		(layer "In9.Cu")
		(net "FM_PVCCIN_CPU0_PWR_IN_ALERT_N")
	)
	(segment
		(start 261.787894 -28.47086)
		(end 260.545834 -27.2288)
		(width 0.089408)
		(layer "In9.Cu")
		(net "FM_PVCCIN_CPU0_PWR_IN_ALERT_N")
	)
	(segment
		(start 263.275826 -28.47086)
		(end 261.787894 -28.47086)
		(width 0.089408)
		(layer "In9.Cu")
		(net "FM_PVCCIN_CPU0_PWR_IN_ALERT_N")
	)
	(segment
		(start 320.4972 -39.363142)
		(end 320.085974 -39.774368)
		(width 0.089408)
		(layer "In9.Cu")
		(net "FM_PVCCIN_CPU0_PWR_IN_ALERT_N")
	)
	(segment
		(start 260.545834 -27.2288)
		(end 246.490236 -27.2288)
		(width 0.089408)
		(layer "In9.Cu")
		(net "FM_PVCCIN_CPU0_PWR_IN_ALERT_N")
	)
	(segment
		(start 186.242452 -59.424062)
		(end 186.242452 -63.085726)
		(width 0.089408)
		(layer "In11.Cu")
		(net "FM_PVCCIN_CPU0_PWR_IN_ALERT_N")
	)
	(segment
		(start 196.9008 -49.3268)
		(end 196.074792 -50.152808)
		(width 0.089408)
		(layer "In11.Cu")
		(net "FM_PVCCIN_CPU0_PWR_IN_ALERT_N")
	)
	(segment
		(start 358.53243 -36.33724)
		(end 359.62717 -35.2425)
		(width 0.089408)
		(layer "In11.Cu")
		(net "FM_PVCCIN_CPU0_PWR_IN_ALERT_N")
	)
	(segment
		(start 186.242452 -63.085726)
		(end 185.907426 -63.420752)
		(width 0.089408)
		(layer "In11.Cu")
		(net "FM_PVCCIN_CPU0_PWR_IN_ALERT_N")
	)
	(segment
		(start 185.907426 -63.420752)
		(end 185.907426 -65.136268)
		(width 0.089408)
		(layer "In11.Cu")
		(net "FM_PVCCIN_CPU0_PWR_IN_ALERT_N")
	)
	(segment
		(start 337.322668 -36.33724)
		(end 358.53243 -36.33724)
		(width 0.089408)
		(layer "In11.Cu")
		(net "FM_PVCCIN_CPU0_PWR_IN_ALERT_N")
	)
	(segment
		(start 181.9529 -65.4685)
		(end 181.6608 -65.7606)
		(width 0.089408)
		(layer "In11.Cu")
		(net "FM_PVCCIN_CPU0_PWR_IN_ALERT_N")
	)
	(segment
		(start 189.343792 -50.152808)
		(end 185.674762 -53.821838)
		(width 0.089408)
		(layer "In11.Cu")
		(net "FM_PVCCIN_CPU0_PWR_IN_ALERT_N")
	)
	(segment
		(start 192.2272 -25.2476)
		(end 192.532 -25.2476)
		(width 0.089408)
		(layer "In11.Cu")
		(net "FM_PVCCIN_CPU0_PWR_IN_ALERT_N")
	)
	(segment
		(start 359.62717 -35.2425)
		(end 368.70386 -35.2425)
		(width 0.089408)
		(layer "In11.Cu")
		(net "FM_PVCCIN_CPU0_PWR_IN_ALERT_N")
	)
	(segment
		(start 185.575194 -65.4685)
		(end 181.9529 -65.4685)
		(width 0.089408)
		(layer "In11.Cu")
		(net "FM_PVCCIN_CPU0_PWR_IN_ALERT_N")
	)
	(segment
		(start 196.074792 -50.152808)
		(end 189.343792 -50.152808)
		(width 0.089408)
		(layer "In11.Cu")
		(net "FM_PVCCIN_CPU0_PWR_IN_ALERT_N")
	)
	(segment
		(start 185.674762 -58.856372)
		(end 186.242452 -59.424062)
		(width 0.089408)
		(layer "In11.Cu")
		(net "FM_PVCCIN_CPU0_PWR_IN_ALERT_N")
	)
	(segment
		(start 192.9003 -27.6479)
		(end 194.2592 -29.0068)
		(width 0.089408)
		(layer "In11.Cu")
		(net "FM_PVCCIN_CPU0_PWR_IN_ALERT_N")
	)
	(segment
		(start 192.9003 -25.6159)
		(end 192.9003 -27.6479)
		(width 0.089408)
		(layer "In11.Cu")
		(net "FM_PVCCIN_CPU0_PWR_IN_ALERT_N")
	)
	(segment
		(start 196.9008 -46.228)
		(end 196.9008 -49.3268)
		(width 0.089408)
		(layer "In11.Cu")
		(net "FM_PVCCIN_CPU0_PWR_IN_ALERT_N")
	)
	(segment
		(start 185.674762 -53.821838)
		(end 185.674762 -58.856372)
		(width 0.089408)
		(layer "In11.Cu")
		(net "FM_PVCCIN_CPU0_PWR_IN_ALERT_N")
	)
	(segment
		(start 337.2866 -36.301172)
		(end 337.322668 -36.33724)
		(width 0.089408)
		(layer "In11.Cu")
		(net "FM_PVCCIN_CPU0_PWR_IN_ALERT_N")
	)
	(segment
		(start 185.907426 -65.136268)
		(end 185.575194 -65.4685)
		(width 0.089408)
		(layer "In11.Cu")
		(net "FM_PVCCIN_CPU0_PWR_IN_ALERT_N")
	)
	(segment
		(start 194.2592 -43.5864)
		(end 196.9008 -46.228)
		(width 0.089408)
		(layer "In11.Cu")
		(net "FM_PVCCIN_CPU0_PWR_IN_ALERT_N")
	)
	(segment
		(start 194.2592 -29.0068)
		(end 194.2592 -43.5864)
		(width 0.089408)
		(layer "In11.Cu")
		(net "FM_PVCCIN_CPU0_PWR_IN_ALERT_N")
	)
	(segment
		(start 192.532 -25.2476)
		(end 192.9003 -25.6159)
		(width 0.089408)
		(layer "In11.Cu")
		(net "FM_PVCCIN_CPU0_PWR_IN_ALERT_N")
	)
	(segment
		(start 435.23662 -128.62814)
		(end 434.990748 -128.874012)
		(width 0.254)
		(layer "F.Cu")
		(net "P5V_SWITCH_G")
	)
	(segment
		(start 434.990748 -128.874012)
		(end 434.990748 -129.2479)
		(width 0.254)
		(layer "F.Cu")
		(net "P5V_SWITCH_G")
	)
	(segment
		(start 435.84622 -128.62814)
		(end 435.23662 -128.62814)
		(width 0.254)
		(layer "F.Cu")
		(net "P5V_SWITCH_G")
	)
	(segment
		(start 435.98846 -128.77038)
		(end 435.84622 -128.62814)
		(width 0.254)
		(layer "F.Cu")
		(net "P5V_SWITCH_G")
	)
	(via
		(at 436.76824 -127.44958)
		(size 0.508)
		(drill 0.254)
		(layers "F.Cu" "B.Cu")
		(net "P5V_SWITCH_G")
	)
	(via
		(at 435.98846 -128.77038)
		(size 0.508)
		(drill 0.254)
		(layers "F.Cu" "B.Cu")
		(net "P5V_SWITCH_G")
	)
	(segment
		(start 436.76824 -127.9906)
		(end 435.98846 -128.77038)
		(width 0.508)
		(layer "In11.Cu")
		(net "P5V_SWITCH_G")
	)
	(segment
		(start 436.76824 -127.44958)
		(end 436.76824 -127.9906)
		(width 0.508)
		(layer "In11.Cu")
		(net "P5V_SWITCH_G")
	)
	(via
		(at 472.1098 -12.6238)
		(size 0.6604)
		(drill 0.3302)
		(layers "F.Cu" "B.Cu")
		(net "P3V3_SWITCH_G")
	)
	(segment
		(start 467.20506 -14.127734)
		(end 467.20506 -15.091664)
		(width 0.254)
		(layer "B.Cu")
		(net "P3V3_SWITCH_G")
	)
	(segment
		(start 475.730824 -11.399774)
		(end 474.530928 -11.399774)
		(width 0.254)
		(layer "B.Cu")
		(net "P3V3_SWITCH_G")
	)
	(segment
		(start 475.984824 -12.0015)
		(end 475.984824 -11.653774)
		(width 0.254)
		(layer "B.Cu")
		(net "P3V3_SWITCH_G")
	)
	(segment
		(start 470.340944 -13.335)
		(end 467.997794 -13.335)
		(width 0.254)
		(layer "B.Cu")
		(net "P3V3_SWITCH_G")
	)
	(segment
		(start 472.1098 -12.6238)
		(end 471.052144 -12.6238)
		(width 0.254)
		(layer "B.Cu")
		(net "P3V3_SWITCH_G")
	)
	(segment
		(start 471.052144 -12.6238)
		(end 470.340944 -13.335)
		(width 0.254)
		(layer "B.Cu")
		(net "P3V3_SWITCH_G")
	)
	(segment
		(start 467.997794 -13.335)
		(end 467.20506 -14.127734)
		(width 0.254)
		(layer "B.Cu")
		(net "P3V3_SWITCH_G")
	)
	(segment
		(start 474.530928 -11.399774)
		(end 473.306902 -12.6238)
		(width 0.254)
		(layer "B.Cu")
		(net "P3V3_SWITCH_G")
	)
	(segment
		(start 473.306902 -12.6238)
		(end 472.1098 -12.6238)
		(width 0.254)
		(layer "B.Cu")
		(net "P3V3_SWITCH_G")
	)
	(segment
		(start 475.984824 -11.653774)
		(end 475.730824 -11.399774)
		(width 0.254)
		(layer "B.Cu")
		(net "P3V3_SWITCH_G")
	)
	(segment
		(start 499.76532 -26.599134)
		(end 499.221506 -26.05532)
		(width 0.3048)
		(layer "F.Cu")
		(net "P12V_SWITCH_G")
	)
	(segment
		(start 499.221506 -26.05532)
		(end 498.735604 -26.05532)
		(width 0.3048)
		(layer "F.Cu")
		(net "P12V_SWITCH_G")
	)
	(segment
		(start 493.615726 -20.549108)
		(end 494.774728 -20.549108)
		(width 0.3302)
		(layer "F.Cu")
		(net "P12V_SWITCH_G")
	)
	(segment
		(start 494.774728 -20.549108)
		(end 494.911888 -20.411948)
		(width 0.3302)
		(layer "F.Cu")
		(net "P12V_SWITCH_G")
	)
	(via
		(at 499.76532 -26.599134)
		(size 0.508)
		(drill 0.254)
		(layers "F.Cu" "B.Cu")
		(net "P12V_SWITCH_G")
	)
	(via
		(at 493.96396 -20.77974)
		(size 0.6604)
		(drill 0.3302)
		(layers "F.Cu" "B.Cu")
		(net "P12V_SWITCH_G")
	)
	(via
		(at 494.911888 -20.411948)
		(size 0.508)
		(drill 0.254)
		(layers "F.Cu" "B.Cu")
		(net "P12V_SWITCH_G")
	)
	(segment
		(start 493.96396 -20.77974)
		(end 494.544096 -20.77974)
		(width 0.254)
		(layer "B.Cu")
		(net "P12V_SWITCH_G")
	)
	(segment
		(start 494.544096 -20.77974)
		(end 494.911888 -20.411948)
		(width 0.254)
		(layer "B.Cu")
		(net "P12V_SWITCH_G")
	)
	(segment
		(start 499.76532 -26.599134)
		(end 499.47957 -26.599134)
		(width 0.508)
		(layer "In4.Cu")
		(net "P12V_SWITCH_G")
	)
	(segment
		(start 498.252242 -20.281392)
		(end 497.340382 -19.369532)
		(width 0.508)
		(layer "In4.Cu")
		(net "P12V_SWITCH_G")
	)
	(segment
		(start 497.340382 -19.369532)
		(end 495.975894 -19.369532)
		(width 0.508)
		(layer "In4.Cu")
		(net "P12V_SWITCH_G")
	)
	(segment
		(start 495.975894 -19.369532)
		(end 494.933478 -20.411948)
		(width 0.508)
		(layer "In4.Cu")
		(net "P12V_SWITCH_G")
	)
	(segment
		(start 499.47957 -26.599134)
		(end 498.252242 -25.371806)
		(width 0.508)
		(layer "In4.Cu")
		(net "P12V_SWITCH_G")
	)
	(segment
		(start 494.933478 -20.411948)
		(end 494.911888 -20.411948)
		(width 0.508)
		(layer "In4.Cu")
		(net "P12V_SWITCH_G")
	)
	(segment
		(start 498.252242 -25.371806)
		(end 498.252242 -20.281392)
		(width 0.508)
		(layer "In4.Cu")
		(net "P12V_SWITCH_G")
	)
	(segment
		(start 312.133996 -35.615626)
		(end 311.34685 -35.615626)
		(width 0.10795)
		(layer "F.Cu")
		(net "FM_ADR_COMPLETE_R")
	)
	(segment
		(start 312.142124 -35.623754)
		(end 312.133996 -35.615626)
		(width 0.10795)
		(layer "F.Cu")
		(net "FM_ADR_COMPLETE_R")
	)
	(segment
		(start 313.365642 -37.373814)
		(end 314.400438 -36.339018)
		(width 0.10795)
		(layer "F.Cu")
		(net "FM_ADR_COMPLETE_R")
	)
	(segment
		(start 315.720222 -34.652458)
		(end 316.383162 -33.989518)
		(width 0.10795)
		(layer "F.Cu")
		(net "FM_ADR_COMPLETE_R")
	)
	(segment
		(start 314.400438 -36.339018)
		(end 314.400438 -35.880802)
		(width 0.10795)
		(layer "F.Cu")
		(net "FM_ADR_COMPLETE_R")
	)
	(segment
		(start 312.142124 -35.623754)
		(end 312.142124 -36.704016)
		(width 0.10795)
		(layer "F.Cu")
		(net "FM_ADR_COMPLETE_R")
	)
	(segment
		(start 312.811922 -37.373814)
		(end 313.365642 -37.373814)
		(width 0.10795)
		(layer "F.Cu")
		(net "FM_ADR_COMPLETE_R")
	)
	(segment
		(start 316.383162 -33.989518)
		(end 317.148464 -33.989518)
		(width 0.10795)
		(layer "F.Cu")
		(net "FM_ADR_COMPLETE_R")
	)
	(segment
		(start 314.400438 -35.880802)
		(end 315.628782 -34.652458)
		(width 0.10795)
		(layer "F.Cu")
		(net "FM_ADR_COMPLETE_R")
	)
	(segment
		(start 315.628782 -34.652458)
		(end 315.720222 -34.652458)
		(width 0.10795)
		(layer "F.Cu")
		(net "FM_ADR_COMPLETE_R")
	)
	(segment
		(start 312.142124 -36.704016)
		(end 312.811922 -37.373814)
		(width 0.10795)
		(layer "F.Cu")
		(net "FM_ADR_COMPLETE_R")
	)
	(via
		(at 317.148464 -33.989518)
		(size 0.508)
		(drill 0.254)
		(layers "F.Cu" "B.Cu")
		(net "FM_ADR_COMPLETE_R")
	)
	(segment
		(start 318.0842 -34.2138)
		(end 318.0842 -33.1978)
		(width 0.10795)
		(layer "B.Cu")
		(net "FM_ADR_COMPLETE_R")
	)
	(segment
		(start 317.148464 -33.989518)
		(end 317.519812 -33.989518)
		(width 0.10795)
		(layer "B.Cu")
		(net "FM_ADR_COMPLETE_R")
	)
	(segment
		(start 317.519812 -33.989518)
		(end 317.744094 -34.2138)
		(width 0.10795)
		(layer "B.Cu")
		(net "FM_ADR_COMPLETE_R")
	)
	(segment
		(start 317.744094 -34.2138)
		(end 318.0842 -34.2138)
		(width 0.10795)
		(layer "B.Cu")
		(net "FM_ADR_COMPLETE_R")
	)
	(segment
		(start 410.26969 -109.40669)
		(end 411.729428 -109.40669)
		(width 0.10795)
		(layer "F.Cu")
		(net "SMB_SMLINK0_STBY_LVC3_SDA")
	)
	(segment
		(start 410.1465 -109.2835)
		(end 410.26969 -109.40669)
		(width 0.10795)
		(layer "F.Cu")
		(net "SMB_SMLINK0_STBY_LVC3_SDA")
	)
	(segment
		(start 422.41216 -109.44606)
		(end 422.94175 -109.97565)
		(width 0.10795)
		(layer "F.Cu")
		(net "SMB_SMLINK0_STBY_LVC3_SDA")
	)
	(segment
		(start 408.7495 -108.966)
		(end 409.047442 -108.668058)
		(width 0.10795)
		(layer "F.Cu")
		(net "SMB_SMLINK0_STBY_LVC3_SDA")
	)
	(segment
		(start 417.754054 -107.8992)
		(end 419.300914 -109.44606)
		(width 0.10795)
		(layer "F.Cu")
		(net "SMB_SMLINK0_STBY_LVC3_SDA")
	)
	(segment
		(start 411.729428 -109.40669)
		(end 411.84322 -109.292898)
		(width 0.10795)
		(layer "F.Cu")
		(net "SMB_SMLINK0_STBY_LVC3_SDA")
	)
	(segment
		(start 417.19881 -107.8992)
		(end 417.754054 -107.8992)
		(width 0.10795)
		(layer "F.Cu")
		(net "SMB_SMLINK0_STBY_LVC3_SDA")
	)
	(segment
		(start 409.047442 -108.668058)
		(end 409.848558 -108.668058)
		(width 0.10795)
		(layer "F.Cu")
		(net "SMB_SMLINK0_STBY_LVC3_SDA")
	)
	(segment
		(start 423.269156 -109.97565)
		(end 423.567352 -110.273846)
		(width 0.10795)
		(layer "F.Cu")
		(net "SMB_SMLINK0_STBY_LVC3_SDA")
	)
	(segment
		(start 414.324546 -108.204)
		(end 414.629346 -107.8992)
		(width 0.10795)
		(layer "F.Cu")
		(net "SMB_SMLINK0_STBY_LVC3_SDA")
	)
	(segment
		(start 409.848558 -108.668058)
		(end 410.1465 -108.966)
		(width 0.10795)
		(layer "F.Cu")
		(net "SMB_SMLINK0_STBY_LVC3_SDA")
	)
	(segment
		(start 414.629346 -107.8992)
		(end 417.19881 -107.8992)
		(width 0.10795)
		(layer "F.Cu")
		(net "SMB_SMLINK0_STBY_LVC3_SDA")
	)
	(segment
		(start 412.933896 -108.204)
		(end 414.324546 -108.204)
		(width 0.10795)
		(layer "F.Cu")
		(net "SMB_SMLINK0_STBY_LVC3_SDA")
	)
	(segment
		(start 422.94175 -109.97565)
		(end 423.269156 -109.97565)
		(width 0.10795)
		(layer "F.Cu")
		(net "SMB_SMLINK0_STBY_LVC3_SDA")
	)
	(segment
		(start 411.84322 -109.292898)
		(end 411.844998 -109.292898)
		(width 0.10795)
		(layer "F.Cu")
		(net "SMB_SMLINK0_STBY_LVC3_SDA")
	)
	(segment
		(start 419.300914 -109.44606)
		(end 422.41216 -109.44606)
		(width 0.10795)
		(layer "F.Cu")
		(net "SMB_SMLINK0_STBY_LVC3_SDA")
	)
	(segment
		(start 410.1465 -108.966)
		(end 410.1465 -109.2835)
		(width 0.10795)
		(layer "F.Cu")
		(net "SMB_SMLINK0_STBY_LVC3_SDA")
	)
	(segment
		(start 411.844998 -109.292898)
		(end 412.933896 -108.204)
		(width 0.10795)
		(layer "F.Cu")
		(net "SMB_SMLINK0_STBY_LVC3_SDA")
	)
	(via
		(at 417.19881 -107.8992)
		(size 0.508)
		(drill 0.254)
		(layers "F.Cu" "B.Cu")
		(net "SMB_SMLINK0_STBY_LVC3_SDA")
	)
	(via
		(at 423.567352 -110.273846)
		(size 0.508)
		(drill 0.254)
		(layers "F.Cu" "B.Cu")
		(net "SMB_SMLINK0_STBY_LVC3_SDA")
	)
	(via
		(at 422.866566 -96.315276)
		(size 0.508)
		(drill 0.254)
		(layers "F.Cu" "B.Cu")
		(net "SMB_SMLINK0_STBY_LVC3_SDA")
	)
	(via
		(at 424.388788 -64.691514)
		(size 0.508)
		(drill 0.254)
		(layers "F.Cu" "B.Cu")
		(net "SMB_SMLINK0_STBY_LVC3_SDA")
	)
	(via
		(at 430.31537 -19.809714)
		(size 0.508)
		(drill 0.254)
		(layers "F.Cu" "B.Cu")
		(net "SMB_SMLINK0_STBY_LVC3_SDA")
	)
	(segment
		(start 482.117654 -123.926854)
		(end 482.117654 -123.70435)
		(width 0.10795)
		(layer "B.Cu")
		(net "SMB_SMLINK0_STBY_LVC3_SDA")
	)
	(segment
		(start 429.1838 -21.082)
		(end 428.3075 -21.082)
		(width 0.10795)
		(layer "B.Cu")
		(net "SMB_SMLINK0_STBY_LVC3_SDA")
	)
	(segment
		(start 485.18445 -128.11125)
		(end 485.0892 -128.2065)
		(width 0.10795)
		(layer "B.Cu")
		(net "SMB_SMLINK0_STBY_LVC3_SDA")
	)
	(segment
		(start 482.244654 -123.57735)
		(end 484.405178 -123.57735)
		(width 0.10795)
		(layer "B.Cu")
		(net "SMB_SMLINK0_STBY_LVC3_SDA")
	)
	(segment
		(start 483.4128 -125.222)
		(end 482.117654 -123.926854)
		(width 0.10795)
		(layer "B.Cu")
		(net "SMB_SMLINK0_STBY_LVC3_SDA")
	)
	(segment
		(start 483.6414 -125.222)
		(end 483.4128 -125.222)
		(width 0.10795)
		(layer "B.Cu")
		(net "SMB_SMLINK0_STBY_LVC3_SDA")
	)
	(segment
		(start 430.31537 -19.809714)
		(end 430.31537 -19.95043)
		(width 0.10795)
		(layer "B.Cu")
		(net "SMB_SMLINK0_STBY_LVC3_SDA")
	)
	(segment
		(start 485.18445 -124.356622)
		(end 485.18445 -128.11125)
		(width 0.10795)
		(layer "B.Cu")
		(net "SMB_SMLINK0_STBY_LVC3_SDA")
	)
	(segment
		(start 484.405178 -123.57735)
		(end 485.18445 -124.356622)
		(width 0.10795)
		(layer "B.Cu")
		(net "SMB_SMLINK0_STBY_LVC3_SDA")
	)
	(segment
		(start 430.31537 -19.95043)
		(end 429.1838 -21.082)
		(width 0.10795)
		(layer "B.Cu")
		(net "SMB_SMLINK0_STBY_LVC3_SDA")
	)
	(segment
		(start 482.117654 -123.70435)
		(end 482.244654 -123.57735)
		(width 0.10795)
		(layer "B.Cu")
		(net "SMB_SMLINK0_STBY_LVC3_SDA")
	)
	(segment
		(start 423.269156 -109.97565)
		(end 423.567352 -110.273846)
		(width 0.089408)
		(layer "In2.Cu")
		(net "SMB_SMLINK0_STBY_LVC3_SDA")
	)
	(segment
		(start 424.104562 -96.9518)
		(end 424.104562 -103.560372)
		(width 0.089408)
		(layer "In2.Cu")
		(net "SMB_SMLINK0_STBY_LVC3_SDA")
	)
	(segment
		(start 422.866566 -96.315276)
		(end 423.063162 -96.11868)
		(width 0.089408)
		(layer "In2.Cu")
		(net "SMB_SMLINK0_STBY_LVC3_SDA")
	)
	(segment
		(start 424.104562 -103.560372)
		(end 422.489376 -105.175558)
		(width 0.089408)
		(layer "In2.Cu")
		(net "SMB_SMLINK0_STBY_LVC3_SDA")
	)
	(segment
		(start 422.489376 -105.175558)
		(end 422.489376 -109.464094)
		(width 0.089408)
		(layer "In2.Cu")
		(net "SMB_SMLINK0_STBY_LVC3_SDA")
	)
	(segment
		(start 423.063162 -96.11868)
		(end 423.271442 -96.11868)
		(width 0.089408)
		(layer "In2.Cu")
		(net "SMB_SMLINK0_STBY_LVC3_SDA")
	)
	(segment
		(start 423.000932 -109.97565)
		(end 423.269156 -109.97565)
		(width 0.089408)
		(layer "In2.Cu")
		(net "SMB_SMLINK0_STBY_LVC3_SDA")
	)
	(segment
		(start 422.489376 -109.464094)
		(end 423.000932 -109.97565)
		(width 0.089408)
		(layer "In2.Cu")
		(net "SMB_SMLINK0_STBY_LVC3_SDA")
	)
	(segment
		(start 423.271442 -96.11868)
		(end 424.104562 -96.9518)
		(width 0.089408)
		(layer "In2.Cu")
		(net "SMB_SMLINK0_STBY_LVC3_SDA")
	)
	(segment
		(start 472.186762 -31.55823)
		(end 472.467686 -31.839154)
		(width 0.089408)
		(layer "In4.Cu")
		(net "SMB_SMLINK0_STBY_LVC3_SDA")
	)
	(segment
		(start 472.186762 -30.526482)
		(end 472.186762 -31.55823)
		(width 0.089408)
		(layer "In4.Cu")
		(net "SMB_SMLINK0_STBY_LVC3_SDA")
	)
	(segment
		(start 439.663586 -17.921478)
		(end 447.583306 -17.921478)
		(width 0.089408)
		(layer "In4.Cu")
		(net "SMB_SMLINK0_STBY_LVC3_SDA")
	)
	(segment
		(start 480.7458 -41.4528)
		(end 480.7458 -48.49241)
		(width 0.089408)
		(layer "In4.Cu")
		(net "SMB_SMLINK0_STBY_LVC3_SDA")
	)
	(segment
		(start 474.092524 -33.85058)
		(end 478.762314 -33.85058)
		(width 0.089408)
		(layer "In4.Cu")
		(net "SMB_SMLINK0_STBY_LVC3_SDA")
	)
	(segment
		(start 478.159318 -52.747926)
		(end 477.68637 -53.220874)
		(width 0.089408)
		(layer "In4.Cu")
		(net "SMB_SMLINK0_STBY_LVC3_SDA")
	)
	(segment
		(start 425.737274 -64.996568)
		(end 424.693842 -64.996568)
		(width 0.089408)
		(layer "In4.Cu")
		(net "SMB_SMLINK0_STBY_LVC3_SDA")
	)
	(segment
		(start 477.68637 -53.220874)
		(end 477.68637 -55.552086)
		(width 0.089408)
		(layer "In4.Cu")
		(net "SMB_SMLINK0_STBY_LVC3_SDA")
	)
	(segment
		(start 455.02957 -24.77897)
		(end 458.25283 -24.77897)
		(width 0.089408)
		(layer "In4.Cu")
		(net "SMB_SMLINK0_STBY_LVC3_SDA")
	)
	(segment
		(start 460.883 -25.6286)
		(end 462.76006 -27.50566)
		(width 0.089408)
		(layer "In4.Cu")
		(net "SMB_SMLINK0_STBY_LVC3_SDA")
	)
	(segment
		(start 469.16594 -27.50566)
		(end 472.186762 -30.526482)
		(width 0.089408)
		(layer "In4.Cu")
		(net "SMB_SMLINK0_STBY_LVC3_SDA")
	)
	(segment
		(start 477.68637 -55.552086)
		(end 477.019112 -56.219344)
		(width 0.089408)
		(layer "In4.Cu")
		(net "SMB_SMLINK0_STBY_LVC3_SDA")
	)
	(segment
		(start 462.76006 -27.50566)
		(end 469.16594 -27.50566)
		(width 0.089408)
		(layer "In4.Cu")
		(net "SMB_SMLINK0_STBY_LVC3_SDA")
	)
	(segment
		(start 479.982784 -35.07105)
		(end 479.982784 -35.628326)
		(width 0.089408)
		(layer "In4.Cu")
		(net "SMB_SMLINK0_STBY_LVC3_SDA")
	)
	(segment
		(start 452.374 -21.853144)
		(end 452.374 -23.5458)
		(width 0.089408)
		(layer "In4.Cu")
		(net "SMB_SMLINK0_STBY_LVC3_SDA")
	)
	(segment
		(start 432.45659 -19.223482)
		(end 432.859688 -18.820384)
		(width 0.089408)
		(layer "In4.Cu")
		(net "SMB_SMLINK0_STBY_LVC3_SDA")
	)
	(segment
		(start 466.024976 -65.014094)
		(end 425.7548 -65.014094)
		(width 0.089408)
		(layer "In4.Cu")
		(net "SMB_SMLINK0_STBY_LVC3_SDA")
	)
	(segment
		(start 453.2122 -24.384)
		(end 454.6346 -24.384)
		(width 0.089408)
		(layer "In4.Cu")
		(net "SMB_SMLINK0_STBY_LVC3_SDA")
	)
	(segment
		(start 430.31537 -19.809714)
		(end 430.31537 -19.629882)
		(width 0.089408)
		(layer "In4.Cu")
		(net "SMB_SMLINK0_STBY_LVC3_SDA")
	)
	(segment
		(start 475.421706 -63.30442)
		(end 472.6305 -63.30442)
		(width 0.089408)
		(layer "In4.Cu")
		(net "SMB_SMLINK0_STBY_LVC3_SDA")
	)
	(segment
		(start 438.76468 -18.820384)
		(end 439.663586 -17.921478)
		(width 0.089408)
		(layer "In4.Cu")
		(net "SMB_SMLINK0_STBY_LVC3_SDA")
	)
	(segment
		(start 449.41617 -18.895314)
		(end 452.374 -21.853144)
		(width 0.089408)
		(layer "In4.Cu")
		(net "SMB_SMLINK0_STBY_LVC3_SDA")
	)
	(segment
		(start 478.731834 -52.747926)
		(end 478.159318 -52.747926)
		(width 0.089408)
		(layer "In4.Cu")
		(net "SMB_SMLINK0_STBY_LVC3_SDA")
	)
	(segment
		(start 454.6346 -24.384)
		(end 455.02957 -24.77897)
		(width 0.089408)
		(layer "In4.Cu")
		(net "SMB_SMLINK0_STBY_LVC3_SDA")
	)
	(segment
		(start 477.019112 -56.219344)
		(end 477.019112 -61.707014)
		(width 0.089408)
		(layer "In4.Cu")
		(net "SMB_SMLINK0_STBY_LVC3_SDA")
	)
	(segment
		(start 481.933504 -40.265096)
		(end 480.7458 -41.4528)
		(width 0.089408)
		(layer "In4.Cu")
		(net "SMB_SMLINK0_STBY_LVC3_SDA")
	)
	(segment
		(start 458.25283 -24.77897)
		(end 459.10246 -25.6286)
		(width 0.089408)
		(layer "In4.Cu")
		(net "SMB_SMLINK0_STBY_LVC3_SDA")
	)
	(segment
		(start 472.467686 -32.225742)
		(end 474.092524 -33.85058)
		(width 0.089408)
		(layer "In4.Cu")
		(net "SMB_SMLINK0_STBY_LVC3_SDA")
	)
	(segment
		(start 448.557142 -18.895314)
		(end 449.41617 -18.895314)
		(width 0.089408)
		(layer "In4.Cu")
		(net "SMB_SMLINK0_STBY_LVC3_SDA")
	)
	(segment
		(start 452.374 -23.5458)
		(end 453.2122 -24.384)
		(width 0.089408)
		(layer "In4.Cu")
		(net "SMB_SMLINK0_STBY_LVC3_SDA")
	)
	(segment
		(start 479.982784 -35.628326)
		(end 481.933504 -37.579046)
		(width 0.089408)
		(layer "In4.Cu")
		(net "SMB_SMLINK0_STBY_LVC3_SDA")
	)
	(segment
		(start 430.72177 -19.223482)
		(end 432.45659 -19.223482)
		(width 0.089408)
		(layer "In4.Cu")
		(net "SMB_SMLINK0_STBY_LVC3_SDA")
	)
	(segment
		(start 477.019112 -61.707014)
		(end 475.421706 -63.30442)
		(width 0.089408)
		(layer "In4.Cu")
		(net "SMB_SMLINK0_STBY_LVC3_SDA")
	)
	(segment
		(start 479.835718 -49.402492)
		(end 479.835718 -51.644042)
		(width 0.089408)
		(layer "In4.Cu")
		(net "SMB_SMLINK0_STBY_LVC3_SDA")
	)
	(segment
		(start 481.933504 -37.579046)
		(end 481.933504 -40.265096)
		(width 0.089408)
		(layer "In4.Cu")
		(net "SMB_SMLINK0_STBY_LVC3_SDA")
	)
	(segment
		(start 459.10246 -25.6286)
		(end 460.883 -25.6286)
		(width 0.089408)
		(layer "In4.Cu")
		(net "SMB_SMLINK0_STBY_LVC3_SDA")
	)
	(segment
		(start 430.31537 -19.629882)
		(end 430.72177 -19.223482)
		(width 0.089408)
		(layer "In4.Cu")
		(net "SMB_SMLINK0_STBY_LVC3_SDA")
	)
	(segment
		(start 472.6305 -63.30442)
		(end 471.805762 -62.479682)
		(width 0.089408)
		(layer "In4.Cu")
		(net "SMB_SMLINK0_STBY_LVC3_SDA")
	)
	(segment
		(start 472.467686 -31.839154)
		(end 472.467686 -32.225742)
		(width 0.089408)
		(layer "In4.Cu")
		(net "SMB_SMLINK0_STBY_LVC3_SDA")
	)
	(segment
		(start 478.762314 -33.85058)
		(end 479.982784 -35.07105)
		(width 0.089408)
		(layer "In4.Cu")
		(net "SMB_SMLINK0_STBY_LVC3_SDA")
	)
	(segment
		(start 425.7548 -65.014094)
		(end 425.737274 -64.996568)
		(width 0.089408)
		(layer "In4.Cu")
		(net "SMB_SMLINK0_STBY_LVC3_SDA")
	)
	(segment
		(start 479.835718 -51.644042)
		(end 478.731834 -52.747926)
		(width 0.089408)
		(layer "In4.Cu")
		(net "SMB_SMLINK0_STBY_LVC3_SDA")
	)
	(segment
		(start 447.583306 -17.921478)
		(end 448.557142 -18.895314)
		(width 0.089408)
		(layer "In4.Cu")
		(net "SMB_SMLINK0_STBY_LVC3_SDA")
	)
	(segment
		(start 424.693842 -64.996568)
		(end 424.388788 -64.691514)
		(width 0.089408)
		(layer "In4.Cu")
		(net "SMB_SMLINK0_STBY_LVC3_SDA")
	)
	(segment
		(start 471.805762 -62.479682)
		(end 468.559388 -62.479682)
		(width 0.089408)
		(layer "In4.Cu")
		(net "SMB_SMLINK0_STBY_LVC3_SDA")
	)
	(segment
		(start 480.7458 -48.49241)
		(end 479.835718 -49.402492)
		(width 0.089408)
		(layer "In4.Cu")
		(net "SMB_SMLINK0_STBY_LVC3_SDA")
	)
	(segment
		(start 432.859688 -18.820384)
		(end 438.76468 -18.820384)
		(width 0.089408)
		(layer "In4.Cu")
		(net "SMB_SMLINK0_STBY_LVC3_SDA")
	)
	(segment
		(start 468.559388 -62.479682)
		(end 466.024976 -65.014094)
		(width 0.089408)
		(layer "In4.Cu")
		(net "SMB_SMLINK0_STBY_LVC3_SDA")
	)
	(segment
		(start 422.659302 -94.556326)
		(end 422.082214 -95.133414)
		(width 0.089408)
		(layer "In9.Cu")
		(net "SMB_SMLINK0_STBY_LVC3_SDA")
	)
	(segment
		(start 422.659302 -81.236312)
		(end 422.659302 -94.556326)
		(width 0.089408)
		(layer "In9.Cu")
		(net "SMB_SMLINK0_STBY_LVC3_SDA")
	)
	(segment
		(start 424.388788 -64.691514)
		(end 424.387264 -64.693038)
		(width 0.089408)
		(layer "In9.Cu")
		(net "SMB_SMLINK0_STBY_LVC3_SDA")
	)
	(segment
		(start 429.35271 -118.501668)
		(end 429.35271 -114.58321)
		(width 0.089408)
		(layer "In9.Cu")
		(net "SMB_SMLINK0_STBY_LVC3_SDA")
	)
	(segment
		(start 482.1682 -126.6952)
		(end 477.375982 -126.6952)
		(width 0.089408)
		(layer "In9.Cu")
		(net "SMB_SMLINK0_STBY_LVC3_SDA")
	)
	(segment
		(start 424.387264 -64.698118)
		(end 424.297856 -64.787526)
		(width 0.089408)
		(layer "In9.Cu")
		(net "SMB_SMLINK0_STBY_LVC3_SDA")
	)
	(segment
		(start 424.131994 -64.731392)
		(end 422.974008 -64.731392)
		(width 0.089408)
		(layer "In9.Cu")
		(net "SMB_SMLINK0_STBY_LVC3_SDA")
	)
	(segment
		(start 423.277792 -78.627732)
		(end 422.659302 -81.236312)
		(width 0.089408)
		(layer "In9.Cu")
		(net "SMB_SMLINK0_STBY_LVC3_SDA")
	)
	(segment
		(start 473.768928 -123.088146)
		(end 468.063326 -123.088146)
		(width 0.089408)
		(layer "In9.Cu")
		(net "SMB_SMLINK0_STBY_LVC3_SDA")
	)
	(segment
		(start 423.852594 -109.988604)
		(end 423.567352 -110.273846)
		(width 0.089408)
		(layer "In9.Cu")
		(net "SMB_SMLINK0_STBY_LVC3_SDA")
	)
	(segment
		(start 422.66489 -96.1136)
		(end 422.866566 -96.315276)
		(width 0.089408)
		(layer "In9.Cu")
		(net "SMB_SMLINK0_STBY_LVC3_SDA")
	)
	(segment
		(start 422.659302 -76.666344)
		(end 423.277792 -78.627732)
		(width 0.089408)
		(layer "In9.Cu")
		(net "SMB_SMLINK0_STBY_LVC3_SDA")
	)
	(segment
		(start 462.260188 -117.285008)
		(end 436.815992 -117.285008)
		(width 0.089408)
		(layer "In9.Cu")
		(net "SMB_SMLINK0_STBY_LVC3_SDA")
	)
	(segment
		(start 424.387264 -64.693038)
		(end 424.387264 -64.698118)
		(width 0.089408)
		(layer "In9.Cu")
		(net "SMB_SMLINK0_STBY_LVC3_SDA")
	)
	(segment
		(start 430.499774 -119.40667)
		(end 430.257712 -119.40667)
		(width 0.089408)
		(layer "In9.Cu")
		(net "SMB_SMLINK0_STBY_LVC3_SDA")
	)
	(segment
		(start 436.815992 -117.285008)
		(end 434.694584 -119.406416)
		(width 0.089408)
		(layer "In9.Cu")
		(net "SMB_SMLINK0_STBY_LVC3_SDA")
	)
	(segment
		(start 422.974008 -64.731392)
		(end 422.659302 -65.046098)
		(width 0.089408)
		(layer "In9.Cu")
		(net "SMB_SMLINK0_STBY_LVC3_SDA")
	)
	(segment
		(start 429.35271 -114.58321)
		(end 424.758104 -109.988604)
		(width 0.089408)
		(layer "In9.Cu")
		(net "SMB_SMLINK0_STBY_LVC3_SDA")
	)
	(segment
		(start 430.500028 -119.406924)
		(end 430.499774 -119.40667)
		(width 0.089408)
		(layer "In9.Cu")
		(net "SMB_SMLINK0_STBY_LVC3_SDA")
	)
	(segment
		(start 422.333928 -96.1136)
		(end 422.66489 -96.1136)
		(width 0.089408)
		(layer "In9.Cu")
		(net "SMB_SMLINK0_STBY_LVC3_SDA")
	)
	(segment
		(start 430.534572 -119.40667)
		(end 430.534318 -119.406924)
		(width 0.089408)
		(layer "In9.Cu")
		(net "SMB_SMLINK0_STBY_LVC3_SDA")
	)
	(segment
		(start 434.694584 -119.406416)
		(end 430.777142 -119.406416)
		(width 0.089408)
		(layer "In9.Cu")
		(net "SMB_SMLINK0_STBY_LVC3_SDA")
	)
	(segment
		(start 430.776888 -119.40667)
		(end 430.534572 -119.40667)
		(width 0.089408)
		(layer "In9.Cu")
		(net "SMB_SMLINK0_STBY_LVC3_SDA")
	)
	(segment
		(start 424.188128 -64.787526)
		(end 424.131994 -64.731392)
		(width 0.089408)
		(layer "In9.Cu")
		(net "SMB_SMLINK0_STBY_LVC3_SDA")
	)
	(segment
		(start 422.082214 -95.861886)
		(end 422.333928 -96.1136)
		(width 0.089408)
		(layer "In9.Cu")
		(net "SMB_SMLINK0_STBY_LVC3_SDA")
	)
	(segment
		(start 430.257712 -119.40667)
		(end 429.35271 -118.501668)
		(width 0.089408)
		(layer "In9.Cu")
		(net "SMB_SMLINK0_STBY_LVC3_SDA")
	)
	(segment
		(start 424.297856 -64.787526)
		(end 424.188128 -64.787526)
		(width 0.089408)
		(layer "In9.Cu")
		(net "SMB_SMLINK0_STBY_LVC3_SDA")
	)
	(segment
		(start 483.6414 -125.222)
		(end 482.1682 -126.6952)
		(width 0.089408)
		(layer "In9.Cu")
		(net "SMB_SMLINK0_STBY_LVC3_SDA")
	)
	(segment
		(start 477.375982 -126.6952)
		(end 473.768928 -123.088146)
		(width 0.089408)
		(layer "In9.Cu")
		(net "SMB_SMLINK0_STBY_LVC3_SDA")
	)
	(segment
		(start 424.758104 -109.988604)
		(end 423.852594 -109.988604)
		(width 0.089408)
		(layer "In9.Cu")
		(net "SMB_SMLINK0_STBY_LVC3_SDA")
	)
	(segment
		(start 422.659302 -65.046098)
		(end 422.659302 -76.666344)
		(width 0.089408)
		(layer "In9.Cu")
		(net "SMB_SMLINK0_STBY_LVC3_SDA")
	)
	(segment
		(start 468.063326 -123.088146)
		(end 462.260188 -117.285008)
		(width 0.089408)
		(layer "In9.Cu")
		(net "SMB_SMLINK0_STBY_LVC3_SDA")
	)
	(segment
		(start 430.534318 -119.406924)
		(end 430.500028 -119.406924)
		(width 0.089408)
		(layer "In9.Cu")
		(net "SMB_SMLINK0_STBY_LVC3_SDA")
	)
	(segment
		(start 422.082214 -95.133414)
		(end 422.082214 -95.861886)
		(width 0.089408)
		(layer "In9.Cu")
		(net "SMB_SMLINK0_STBY_LVC3_SDA")
	)
	(segment
		(start 430.777142 -119.406416)
		(end 430.776888 -119.40667)
		(width 0.089408)
		(layer "In9.Cu")
		(net "SMB_SMLINK0_STBY_LVC3_SDA")
	)
	(segment
		(start 414.165542 -107.8992)
		(end 414.495742 -107.569)
		(width 0.10795)
		(layer "F.Cu")
		(net "SMB_SMLINK0_STBY_LVC3_SCL")
	)
	(segment
		(start 410.1465 -107.7595)
		(end 410.337 -107.569)
		(width 0.10795)
		(layer "F.Cu")
		(net "SMB_SMLINK0_STBY_LVC3_SCL")
	)
	(segment
		(start 409.926028 -108.424472)
		(end 410.1465 -108.204)
		(width 0.10795)
		(layer "F.Cu")
		(net "SMB_SMLINK0_STBY_LVC3_SCL")
	)
	(segment
		(start 422.9989 -109.6645)
		(end 423.353992 -109.6645)
		(width 0.10795)
		(layer "F.Cu")
		(net "SMB_SMLINK0_STBY_LVC3_SCL")
	)
	(segment
		(start 413.67837 -107.8992)
		(end 414.165542 -107.8992)
		(width 0.10795)
		(layer "F.Cu")
		(net "SMB_SMLINK0_STBY_LVC3_SCL")
	)
	(segment
		(start 412.1912 -107.8992)
		(end 413.67837 -107.8992)
		(width 0.10795)
		(layer "F.Cu")
		(net "SMB_SMLINK0_STBY_LVC3_SCL")
	)
	(segment
		(start 410.337 -107.569)
		(end 411.861 -107.569)
		(width 0.10795)
		(layer "F.Cu")
		(net "SMB_SMLINK0_STBY_LVC3_SCL")
	)
	(segment
		(start 414.495742 -107.569)
		(end 417.898834 -107.569)
		(width 0.10795)
		(layer "F.Cu")
		(net "SMB_SMLINK0_STBY_LVC3_SCL")
	)
	(segment
		(start 408.7495 -108.204)
		(end 408.969972 -108.424472)
		(width 0.10795)
		(layer "F.Cu")
		(net "SMB_SMLINK0_STBY_LVC3_SCL")
	)
	(segment
		(start 423.353992 -109.6645)
		(end 423.582846 -109.435646)
		(width 0.10795)
		(layer "F.Cu")
		(net "SMB_SMLINK0_STBY_LVC3_SCL")
	)
	(segment
		(start 422.52011 -109.18571)
		(end 422.9989 -109.6645)
		(width 0.10795)
		(layer "F.Cu")
		(net "SMB_SMLINK0_STBY_LVC3_SCL")
	)
	(segment
		(start 419.515544 -109.18571)
		(end 422.52011 -109.18571)
		(width 0.10795)
		(layer "F.Cu")
		(net "SMB_SMLINK0_STBY_LVC3_SCL")
	)
	(segment
		(start 410.1465 -108.204)
		(end 410.1465 -107.7595)
		(width 0.10795)
		(layer "F.Cu")
		(net "SMB_SMLINK0_STBY_LVC3_SCL")
	)
	(segment
		(start 411.861 -107.569)
		(end 412.1912 -107.8992)
		(width 0.10795)
		(layer "F.Cu")
		(net "SMB_SMLINK0_STBY_LVC3_SCL")
	)
	(segment
		(start 408.969972 -108.424472)
		(end 409.926028 -108.424472)
		(width 0.10795)
		(layer "F.Cu")
		(net "SMB_SMLINK0_STBY_LVC3_SCL")
	)
	(segment
		(start 417.898834 -107.569)
		(end 419.515544 -109.18571)
		(width 0.10795)
		(layer "F.Cu")
		(net "SMB_SMLINK0_STBY_LVC3_SCL")
	)
	(via
		(at 429.68037 -19.809714)
		(size 0.508)
		(drill 0.254)
		(layers "F.Cu" "B.Cu")
		(net "SMB_SMLINK0_STBY_LVC3_SCL")
	)
	(via
		(at 424.21556 -65.416938)
		(size 0.508)
		(drill 0.254)
		(layers "F.Cu" "B.Cu")
		(net "SMB_SMLINK0_STBY_LVC3_SCL")
	)
	(via
		(at 422.88587 -95.68053)
		(size 0.508)
		(drill 0.254)
		(layers "F.Cu" "B.Cu")
		(net "SMB_SMLINK0_STBY_LVC3_SCL")
	)
	(via
		(at 413.67837 -107.8992)
		(size 0.508)
		(drill 0.254)
		(layers "F.Cu" "B.Cu")
		(net "SMB_SMLINK0_STBY_LVC3_SCL")
	)
	(via
		(at 423.582846 -109.435646)
		(size 0.508)
		(drill 0.254)
		(layers "F.Cu" "B.Cu")
		(net "SMB_SMLINK0_STBY_LVC3_SCL")
	)
	(segment
		(start 485.4194 -124.259086)
		(end 485.4194 -127.7747)
		(width 0.10795)
		(layer "B.Cu")
		(net "SMB_SMLINK0_STBY_LVC3_SCL")
	)
	(segment
		(start 481.33 -124.079)
		(end 482.0666 -123.3424)
		(width 0.10795)
		(layer "B.Cu")
		(net "SMB_SMLINK0_STBY_LVC3_SCL")
	)
	(segment
		(start 484.502714 -123.3424)
		(end 485.4194 -124.259086)
		(width 0.10795)
		(layer "B.Cu")
		(net "SMB_SMLINK0_STBY_LVC3_SCL")
	)
	(segment
		(start 485.4194 -127.7747)
		(end 485.8512 -128.2065)
		(width 0.10795)
		(layer "B.Cu")
		(net "SMB_SMLINK0_STBY_LVC3_SCL")
	)
	(segment
		(start 482.0666 -123.3424)
		(end 484.502714 -123.3424)
		(width 0.10795)
		(layer "B.Cu")
		(net "SMB_SMLINK0_STBY_LVC3_SCL")
	)
	(segment
		(start 428.6885 -20.701)
		(end 428.3075 -20.32)
		(width 0.10795)
		(layer "B.Cu")
		(net "SMB_SMLINK0_STBY_LVC3_SCL")
	)
	(segment
		(start 429.68037 -19.809714)
		(end 429.68037 -19.95043)
		(width 0.10795)
		(layer "B.Cu")
		(net "SMB_SMLINK0_STBY_LVC3_SCL")
	)
	(segment
		(start 428.9298 -20.701)
		(end 428.6885 -20.701)
		(width 0.10795)
		(layer "B.Cu")
		(net "SMB_SMLINK0_STBY_LVC3_SCL")
	)
	(segment
		(start 479.7044 -124.079)
		(end 481.33 -124.079)
		(width 0.10795)
		(layer "B.Cu")
		(net "SMB_SMLINK0_STBY_LVC3_SCL")
	)
	(segment
		(start 478.5614 -125.222)
		(end 479.7044 -124.079)
		(width 0.10795)
		(layer "B.Cu")
		(net "SMB_SMLINK0_STBY_LVC3_SCL")
	)
	(segment
		(start 429.68037 -19.95043)
		(end 428.9298 -20.701)
		(width 0.10795)
		(layer "B.Cu")
		(net "SMB_SMLINK0_STBY_LVC3_SCL")
	)
	(segment
		(start 423.269156 -109.733842)
		(end 423.567352 -109.435646)
		(width 0.089408)
		(layer "In2.Cu")
		(net "SMB_SMLINK0_STBY_LVC3_SCL")
	)
	(segment
		(start 424.29557 -96.80067)
		(end 424.29557 -103.63962)
		(width 0.089408)
		(layer "In2.Cu")
		(net "SMB_SMLINK0_STBY_LVC3_SCL")
	)
	(segment
		(start 423.082212 -95.876872)
		(end 423.371772 -95.876872)
		(width 0.089408)
		(layer "In2.Cu")
		(net "SMB_SMLINK0_STBY_LVC3_SCL")
	)
	(segment
		(start 422.88587 -95.68053)
		(end 423.082212 -95.876872)
		(width 0.089408)
		(layer "In2.Cu")
		(net "SMB_SMLINK0_STBY_LVC3_SCL")
	)
	(segment
		(start 422.680384 -105.254806)
		(end 422.680384 -109.384846)
		(width 0.089408)
		(layer "In2.Cu")
		(net "SMB_SMLINK0_STBY_LVC3_SCL")
	)
	(segment
		(start 424.29557 -103.63962)
		(end 422.680384 -105.254806)
		(width 0.089408)
		(layer "In2.Cu")
		(net "SMB_SMLINK0_STBY_LVC3_SCL")
	)
	(segment
		(start 422.680384 -109.384846)
		(end 423.02938 -109.733842)
		(width 0.089408)
		(layer "In2.Cu")
		(net "SMB_SMLINK0_STBY_LVC3_SCL")
	)
	(segment
		(start 423.567352 -109.435646)
		(end 423.582846 -109.435646)
		(width 0.089408)
		(layer "In2.Cu")
		(net "SMB_SMLINK0_STBY_LVC3_SCL")
	)
	(segment
		(start 423.02938 -109.733842)
		(end 423.269156 -109.733842)
		(width 0.089408)
		(layer "In2.Cu")
		(net "SMB_SMLINK0_STBY_LVC3_SCL")
	)
	(segment
		(start 423.371772 -95.876872)
		(end 424.29557 -96.80067)
		(width 0.089408)
		(layer "In2.Cu")
		(net "SMB_SMLINK0_STBY_LVC3_SCL")
	)
	(segment
		(start 448.714368 -18.653506)
		(end 449.5165 -18.653506)
		(width 0.089408)
		(layer "In4.Cu")
		(net "SMB_SMLINK0_STBY_LVC3_SCL")
	)
	(segment
		(start 439.512456 -17.73047)
		(end 447.791332 -17.73047)
		(width 0.089408)
		(layer "In4.Cu")
		(net "SMB_SMLINK0_STBY_LVC3_SCL")
	)
	(segment
		(start 475.500954 -63.495428)
		(end 472.551252 -63.495428)
		(width 0.089408)
		(layer "In4.Cu")
		(net "SMB_SMLINK0_STBY_LVC3_SCL")
	)
	(segment
		(start 454.6854 -24.13)
		(end 455.1172 -24.5618)
		(width 0.089408)
		(layer "In4.Cu")
		(net "SMB_SMLINK0_STBY_LVC3_SCL")
	)
	(segment
		(start 482.210364 -37.58565)
		(end 482.210364 -40.32377)
		(width 0.089408)
		(layer "In4.Cu")
		(net "SMB_SMLINK0_STBY_LVC3_SCL")
	)
	(segment
		(start 425.675552 -65.205102)
		(end 425.658026 -65.187576)
		(width 0.089408)
		(layer "In4.Cu")
		(net "SMB_SMLINK0_STBY_LVC3_SCL")
	)
	(segment
		(start 469.277192 -27.314652)
		(end 472.37777 -30.41523)
		(width 0.089408)
		(layer "In4.Cu")
		(net "SMB_SMLINK0_STBY_LVC3_SCL")
	)
	(segment
		(start 480.02698 -51.723036)
		(end 478.760282 -52.989734)
		(width 0.089408)
		(layer "In4.Cu")
		(net "SMB_SMLINK0_STBY_LVC3_SCL")
	)
	(segment
		(start 472.658694 -31.759906)
		(end 472.658694 -32.146494)
		(width 0.089408)
		(layer "In4.Cu")
		(net "SMB_SMLINK0_STBY_LVC3_SCL")
	)
	(segment
		(start 459.215998 -25.4)
		(end 461.009746 -25.4)
		(width 0.089408)
		(layer "In4.Cu")
		(net "SMB_SMLINK0_STBY_LVC3_SCL")
	)
	(segment
		(start 482.210364 -40.32377)
		(end 480.9871 -41.547034)
		(width 0.089408)
		(layer "In4.Cu")
		(net "SMB_SMLINK0_STBY_LVC3_SCL")
	)
	(segment
		(start 438.613804 -18.629122)
		(end 439.512456 -17.73047)
		(width 0.089408)
		(layer "In4.Cu")
		(net "SMB_SMLINK0_STBY_LVC3_SCL")
	)
	(segment
		(start 447.791332 -17.73047)
		(end 448.714368 -18.653506)
		(width 0.089408)
		(layer "In4.Cu")
		(net "SMB_SMLINK0_STBY_LVC3_SCL")
	)
	(segment
		(start 472.658694 -32.146494)
		(end 474.171772 -33.659572)
		(width 0.089408)
		(layer "In4.Cu")
		(net "SMB_SMLINK0_STBY_LVC3_SCL")
	)
	(segment
		(start 461.009746 -25.4)
		(end 462.924398 -27.314652)
		(width 0.089408)
		(layer "In4.Cu")
		(net "SMB_SMLINK0_STBY_LVC3_SCL")
	)
	(segment
		(start 478.841562 -33.659572)
		(end 480.173792 -34.991802)
		(width 0.089408)
		(layer "In4.Cu")
		(net "SMB_SMLINK0_STBY_LVC3_SCL")
	)
	(segment
		(start 474.171772 -33.659572)
		(end 478.841562 -33.659572)
		(width 0.089408)
		(layer "In4.Cu")
		(net "SMB_SMLINK0_STBY_LVC3_SCL")
	)
	(segment
		(start 458.377798 -24.5618)
		(end 459.215998 -25.4)
		(width 0.089408)
		(layer "In4.Cu")
		(net "SMB_SMLINK0_STBY_LVC3_SCL")
	)
	(segment
		(start 477.973136 -55.535576)
		(end 477.226884 -56.281828)
		(width 0.089408)
		(layer "In4.Cu")
		(net "SMB_SMLINK0_STBY_LVC3_SCL")
	)
	(segment
		(start 472.37777 -30.41523)
		(end 472.37777 -31.478982)
		(width 0.089408)
		(layer "In4.Cu")
		(net "SMB_SMLINK0_STBY_LVC3_SCL")
	)
	(segment
		(start 466.104224 -65.205102)
		(end 425.675552 -65.205102)
		(width 0.089408)
		(layer "In4.Cu")
		(net "SMB_SMLINK0_STBY_LVC3_SCL")
	)
	(segment
		(start 478.760282 -52.989734)
		(end 478.213928 -52.989734)
		(width 0.089408)
		(layer "In4.Cu")
		(net "SMB_SMLINK0_STBY_LVC3_SCL")
	)
	(segment
		(start 480.02698 -49.557686)
		(end 480.02698 -51.723036)
		(width 0.089408)
		(layer "In4.Cu")
		(net "SMB_SMLINK0_STBY_LVC3_SCL")
	)
	(segment
		(start 477.226884 -56.281828)
		(end 477.226884 -61.769498)
		(width 0.089408)
		(layer "In4.Cu")
		(net "SMB_SMLINK0_STBY_LVC3_SCL")
	)
	(segment
		(start 480.9871 -48.597566)
		(end 480.02698 -49.557686)
		(width 0.089408)
		(layer "In4.Cu")
		(net "SMB_SMLINK0_STBY_LVC3_SCL")
	)
	(segment
		(start 452.628 -23.4188)
		(end 453.3392 -24.13)
		(width 0.089408)
		(layer "In4.Cu")
		(net "SMB_SMLINK0_STBY_LVC3_SCL")
	)
	(segment
		(start 430.45761 -19.032474)
		(end 432.249326 -19.032474)
		(width 0.089408)
		(layer "In4.Cu")
		(net "SMB_SMLINK0_STBY_LVC3_SCL")
	)
	(segment
		(start 468.51697 -62.792356)
		(end 466.104224 -65.205102)
		(width 0.089408)
		(layer "In4.Cu")
		(net "SMB_SMLINK0_STBY_LVC3_SCL")
	)
	(segment
		(start 472.37777 -31.478982)
		(end 472.658694 -31.759906)
		(width 0.089408)
		(layer "In4.Cu")
		(net "SMB_SMLINK0_STBY_LVC3_SCL")
	)
	(segment
		(start 462.924398 -27.314652)
		(end 469.277192 -27.314652)
		(width 0.089408)
		(layer "In4.Cu")
		(net "SMB_SMLINK0_STBY_LVC3_SCL")
	)
	(segment
		(start 480.9871 -41.547034)
		(end 480.9871 -48.597566)
		(width 0.089408)
		(layer "In4.Cu")
		(net "SMB_SMLINK0_STBY_LVC3_SCL")
	)
	(segment
		(start 471.84818 -62.792356)
		(end 468.51697 -62.792356)
		(width 0.089408)
		(layer "In4.Cu")
		(net "SMB_SMLINK0_STBY_LVC3_SCL")
	)
	(segment
		(start 429.68037 -19.809714)
		(end 430.45761 -19.032474)
		(width 0.089408)
		(layer "In4.Cu")
		(net "SMB_SMLINK0_STBY_LVC3_SCL")
	)
	(segment
		(start 478.213928 -52.989734)
		(end 477.973136 -53.230526)
		(width 0.089408)
		(layer "In4.Cu")
		(net "SMB_SMLINK0_STBY_LVC3_SCL")
	)
	(segment
		(start 452.628 -21.765006)
		(end 452.628 -23.4188)
		(width 0.089408)
		(layer "In4.Cu")
		(net "SMB_SMLINK0_STBY_LVC3_SCL")
	)
	(segment
		(start 477.973136 -53.230526)
		(end 477.973136 -55.535576)
		(width 0.089408)
		(layer "In4.Cu")
		(net "SMB_SMLINK0_STBY_LVC3_SCL")
	)
	(segment
		(start 432.249326 -19.032474)
		(end 432.652678 -18.629122)
		(width 0.089408)
		(layer "In4.Cu")
		(net "SMB_SMLINK0_STBY_LVC3_SCL")
	)
	(segment
		(start 480.173792 -34.991802)
		(end 480.173792 -35.549078)
		(width 0.089408)
		(layer "In4.Cu")
		(net "SMB_SMLINK0_STBY_LVC3_SCL")
	)
	(segment
		(start 455.1172 -24.5618)
		(end 458.377798 -24.5618)
		(width 0.089408)
		(layer "In4.Cu")
		(net "SMB_SMLINK0_STBY_LVC3_SCL")
	)
	(segment
		(start 472.551252 -63.495428)
		(end 471.84818 -62.792356)
		(width 0.089408)
		(layer "In4.Cu")
		(net "SMB_SMLINK0_STBY_LVC3_SCL")
	)
	(segment
		(start 453.3392 -24.13)
		(end 454.6854 -24.13)
		(width 0.089408)
		(layer "In4.Cu")
		(net "SMB_SMLINK0_STBY_LVC3_SCL")
	)
	(segment
		(start 424.444922 -65.187576)
		(end 424.21556 -65.416938)
		(width 0.089408)
		(layer "In4.Cu")
		(net "SMB_SMLINK0_STBY_LVC3_SCL")
	)
	(segment
		(start 477.226884 -61.769498)
		(end 475.500954 -63.495428)
		(width 0.089408)
		(layer "In4.Cu")
		(net "SMB_SMLINK0_STBY_LVC3_SCL")
	)
	(segment
		(start 449.5165 -18.653506)
		(end 452.628 -21.765006)
		(width 0.089408)
		(layer "In4.Cu")
		(net "SMB_SMLINK0_STBY_LVC3_SCL")
	)
	(segment
		(start 425.658026 -65.187576)
		(end 424.444922 -65.187576)
		(width 0.089408)
		(layer "In4.Cu")
		(net "SMB_SMLINK0_STBY_LVC3_SCL")
	)
	(segment
		(start 480.173792 -35.549078)
		(end 482.210364 -37.58565)
		(width 0.089408)
		(layer "In4.Cu")
		(net "SMB_SMLINK0_STBY_LVC3_SCL")
	)
	(segment
		(start 432.652678 -18.629122)
		(end 438.613804 -18.629122)
		(width 0.089408)
		(layer "In4.Cu")
		(net "SMB_SMLINK0_STBY_LVC3_SCL")
	)
	(segment
		(start 474.85427 -123.776232)
		(end 474.84919 -123.776232)
		(width 0.089408)
		(layer "In9.Cu")
		(net "SMB_SMLINK0_STBY_LVC3_SCL")
	)
	(segment
		(start 462.360518 -117.0432)
		(end 436.715662 -117.0432)
		(width 0.089408)
		(layer "In9.Cu")
		(net "SMB_SMLINK0_STBY_LVC3_SCL")
	)
	(segment
		(start 423.893996 -109.746796)
		(end 423.582846 -109.435646)
		(width 0.089408)
		(layer "In9.Cu")
		(net "SMB_SMLINK0_STBY_LVC3_SCL")
	)
	(segment
		(start 478.5614 -126.238)
		(end 478.409 -126.3904)
		(width 0.089408)
		(layer "In9.Cu")
		(net "SMB_SMLINK0_STBY_LVC3_SCL")
	)
	(segment
		(start 424.786552 -109.746796)
		(end 423.893996 -109.746796)
		(width 0.089408)
		(layer "In9.Cu")
		(net "SMB_SMLINK0_STBY_LVC3_SCL")
	)
	(segment
		(start 430.676812 -119.164608)
		(end 430.676558 -119.164862)
		(width 0.089408)
		(layer "In9.Cu")
		(net "SMB_SMLINK0_STBY_LVC3_SCL")
	)
	(segment
		(start 474.614748 -123.53671)
		(end 473.887038 -122.809)
		(width 0.089408)
		(layer "In9.Cu")
		(net "SMB_SMLINK0_STBY_LVC3_SCL")
	)
	(segment
		(start 424.052746 -64.9224)
		(end 423.053256 -64.9224)
		(width 0.089408)
		(layer "In9.Cu")
		(net "SMB_SMLINK0_STBY_LVC3_SCL")
	)
	(segment
		(start 478.409 -126.3904)
		(end 477.468438 -126.3904)
		(width 0.089408)
		(layer "In9.Cu")
		(net "SMB_SMLINK0_STBY_LVC3_SCL")
	)
	(segment
		(start 422.643808 -95.922592)
		(end 422.88587 -95.68053)
		(width 0.089408)
		(layer "In9.Cu")
		(net "SMB_SMLINK0_STBY_LVC3_SCL")
	)
	(segment
		(start 468.126318 -122.809)
		(end 462.360518 -117.0432)
		(width 0.089408)
		(layer "In9.Cu")
		(net "SMB_SMLINK0_STBY_LVC3_SCL")
	)
	(segment
		(start 473.887038 -122.809)
		(end 468.126318 -122.809)
		(width 0.089408)
		(layer "In9.Cu")
		(net "SMB_SMLINK0_STBY_LVC3_SCL")
	)
	(segment
		(start 474.84919 -123.776232)
		(end 474.614748 -123.54179)
		(width 0.089408)
		(layer "In9.Cu")
		(net "SMB_SMLINK0_STBY_LVC3_SCL")
	)
	(segment
		(start 424.21556 -65.085214)
		(end 424.052746 -64.9224)
		(width 0.089408)
		(layer "In9.Cu")
		(net "SMB_SMLINK0_STBY_LVC3_SCL")
	)
	(segment
		(start 434.594254 -119.164608)
		(end 430.676812 -119.164608)
		(width 0.089408)
		(layer "In9.Cu")
		(net "SMB_SMLINK0_STBY_LVC3_SCL")
	)
	(segment
		(start 430.676558 -119.164862)
		(end 430.358042 -119.164862)
		(width 0.089408)
		(layer "In9.Cu")
		(net "SMB_SMLINK0_STBY_LVC3_SCL")
	)
	(segment
		(start 477.468438 -126.3904)
		(end 474.85427 -123.776232)
		(width 0.089408)
		(layer "In9.Cu")
		(net "SMB_SMLINK0_STBY_LVC3_SCL")
	)
	(segment
		(start 422.85031 -65.125346)
		(end 422.85031 -76.636118)
		(width 0.089408)
		(layer "In9.Cu")
		(net "SMB_SMLINK0_STBY_LVC3_SCL")
	)
	(segment
		(start 422.85031 -81.263236)
		(end 422.85031 -94.635574)
		(width 0.089408)
		(layer "In9.Cu")
		(net "SMB_SMLINK0_STBY_LVC3_SCL")
	)
	(segment
		(start 422.85031 -76.636118)
		(end 423.4688 -78.597506)
		(width 0.089408)
		(layer "In9.Cu")
		(net "SMB_SMLINK0_STBY_LVC3_SCL")
	)
	(segment
		(start 429.594518 -118.401338)
		(end 429.594518 -114.554762)
		(width 0.089408)
		(layer "In9.Cu")
		(net "SMB_SMLINK0_STBY_LVC3_SCL")
	)
	(segment
		(start 436.715662 -117.0432)
		(end 434.594254 -119.164608)
		(width 0.089408)
		(layer "In9.Cu")
		(net "SMB_SMLINK0_STBY_LVC3_SCL")
	)
	(segment
		(start 423.4688 -78.597506)
		(end 423.4688 -78.650338)
		(width 0.089408)
		(layer "In9.Cu")
		(net "SMB_SMLINK0_STBY_LVC3_SCL")
	)
	(segment
		(start 422.279064 -95.20682)
		(end 422.279064 -95.76816)
		(width 0.089408)
		(layer "In9.Cu")
		(net "SMB_SMLINK0_STBY_LVC3_SCL")
	)
	(segment
		(start 478.5614 -125.222)
		(end 478.5614 -126.238)
		(width 0.089408)
		(layer "In9.Cu")
		(net "SMB_SMLINK0_STBY_LVC3_SCL")
	)
	(segment
		(start 423.053256 -64.9224)
		(end 422.85031 -65.125346)
		(width 0.089408)
		(layer "In9.Cu")
		(net "SMB_SMLINK0_STBY_LVC3_SCL")
	)
	(segment
		(start 474.614748 -123.54179)
		(end 474.614748 -123.53671)
		(width 0.089408)
		(layer "In9.Cu")
		(net "SMB_SMLINK0_STBY_LVC3_SCL")
	)
	(segment
		(start 424.21556 -65.416938)
		(end 424.21556 -65.085214)
		(width 0.089408)
		(layer "In9.Cu")
		(net "SMB_SMLINK0_STBY_LVC3_SCL")
	)
	(segment
		(start 429.594518 -114.554762)
		(end 424.786552 -109.746796)
		(width 0.089408)
		(layer "In9.Cu")
		(net "SMB_SMLINK0_STBY_LVC3_SCL")
	)
	(segment
		(start 430.358042 -119.164862)
		(end 429.594518 -118.401338)
		(width 0.089408)
		(layer "In9.Cu")
		(net "SMB_SMLINK0_STBY_LVC3_SCL")
	)
	(segment
		(start 422.279064 -95.76816)
		(end 422.433496 -95.922592)
		(width 0.089408)
		(layer "In9.Cu")
		(net "SMB_SMLINK0_STBY_LVC3_SCL")
	)
	(segment
		(start 423.4688 -78.650338)
		(end 422.85031 -81.263236)
		(width 0.089408)
		(layer "In9.Cu")
		(net "SMB_SMLINK0_STBY_LVC3_SCL")
	)
	(segment
		(start 422.85031 -94.635574)
		(end 422.279064 -95.20682)
		(width 0.089408)
		(layer "In9.Cu")
		(net "SMB_SMLINK0_STBY_LVC3_SCL")
	)
	(segment
		(start 422.433496 -95.922592)
		(end 422.643808 -95.922592)
		(width 0.089408)
		(layer "In9.Cu")
		(net "SMB_SMLINK0_STBY_LVC3_SCL")
	)
	(segment
		(start 403.009354 -109.729524)
		(end 401.6121 -109.729524)
		(width 0.0889)
		(layer "F.Cu")
		(net "SMB_PMBUS_BMC_STBY_LVC3_SDA_R1")
	)
	(segment
		(start 401.451826 -109.56925)
		(end 401.13839 -109.56925)
		(width 0.0889)
		(layer "F.Cu")
		(net "SMB_PMBUS_BMC_STBY_LVC3_SDA_R1")
	)
	(segment
		(start 403.158452 -109.878622)
		(end 403.009354 -109.729524)
		(width 0.0889)
		(layer "F.Cu")
		(net "SMB_PMBUS_BMC_STBY_LVC3_SDA_R1")
	)
	(segment
		(start 401.13839 -109.56925)
		(end 401.023582 -109.684058)
		(width 0.0889)
		(layer "F.Cu")
		(net "SMB_PMBUS_BMC_STBY_LVC3_SDA_R1")
	)
	(segment
		(start 401.023582 -109.684058)
		(end 400.751294 -109.684058)
		(width 0.0889)
		(layer "F.Cu")
		(net "SMB_PMBUS_BMC_STBY_LVC3_SDA_R1")
	)
	(segment
		(start 401.6121 -109.729524)
		(end 401.451826 -109.56925)
		(width 0.0889)
		(layer "F.Cu")
		(net "SMB_PMBUS_BMC_STBY_LVC3_SDA_R1")
	)
	(segment
		(start 400.751294 -109.684058)
		(end 400.42211 -109.354874)
		(width 0.0889)
		(layer "F.Cu")
		(net "SMB_PMBUS_BMC_STBY_LVC3_SDA_R1")
	)
	(segment
		(start 400.42211 -109.354874)
		(end 400.05 -109.354874)
		(width 0.0889)
		(layer "F.Cu")
		(net "SMB_PMBUS_BMC_STBY_LVC3_SDA_R1")
	)
	(via
		(at 397.56969 -77.148436)
		(size 0.508)
		(drill 0.254)
		(layers "F.Cu" "B.Cu")
		(net "SMB_PMBUS_BMC_STBY_LVC3_SDA_R1")
	)
	(via
		(at 403.158452 -109.878622)
		(size 0.508)
		(drill 0.254)
		(layers "F.Cu" "B.Cu")
		(net "SMB_PMBUS_BMC_STBY_LVC3_SDA_R1")
	)
	(via
		(at 405.5872 -109.347)
		(size 0.6604)
		(drill 0.3302)
		(layers "F.Cu" "B.Cu")
		(net "SMB_PMBUS_BMC_STBY_LVC3_SDA_R1")
	)
	(segment
		(start 403.686518 -109.347)
		(end 405.5872 -109.347)
		(width 0.10795)
		(layer "B.Cu")
		(net "SMB_PMBUS_BMC_STBY_LVC3_SDA_R1")
	)
	(segment
		(start 403.370796 -109.666278)
		(end 403.370796 -109.662722)
		(width 0.10795)
		(layer "B.Cu")
		(net "SMB_PMBUS_BMC_STBY_LVC3_SDA_R1")
	)
	(segment
		(start 405.5872 -109.347)
		(end 406.908 -109.347)
		(width 0.10795)
		(layer "B.Cu")
		(net "SMB_PMBUS_BMC_STBY_LVC3_SDA_R1")
	)
	(segment
		(start 403.370796 -109.662722)
		(end 403.686518 -109.347)
		(width 0.10795)
		(layer "B.Cu")
		(net "SMB_PMBUS_BMC_STBY_LVC3_SDA_R1")
	)
	(segment
		(start 397.725646 -76.99248)
		(end 397.56969 -77.148436)
		(width 0.10795)
		(layer "B.Cu")
		(net "SMB_PMBUS_BMC_STBY_LVC3_SDA_R1")
	)
	(segment
		(start 407.035 -109.22)
		(end 407.7335 -109.22)
		(width 0.10795)
		(layer "B.Cu")
		(net "SMB_PMBUS_BMC_STBY_LVC3_SDA_R1")
	)
	(segment
		(start 399.49628 -76.99248)
		(end 397.725646 -76.99248)
		(width 0.10795)
		(layer "B.Cu")
		(net "SMB_PMBUS_BMC_STBY_LVC3_SDA_R1")
	)
	(segment
		(start 403.158452 -109.878622)
		(end 403.370796 -109.666278)
		(width 0.10795)
		(layer "B.Cu")
		(net "SMB_PMBUS_BMC_STBY_LVC3_SDA_R1")
	)
	(segment
		(start 406.908 -109.347)
		(end 407.035 -109.22)
		(width 0.10795)
		(layer "B.Cu")
		(net "SMB_PMBUS_BMC_STBY_LVC3_SDA_R1")
	)
	(segment
		(start 396.94866 -79.612744)
		(end 396.94866 -78.0161)
		(width 0.089408)
		(layer "In11.Cu")
		(net "SMB_PMBUS_BMC_STBY_LVC3_SDA_R1")
	)
	(segment
		(start 398.2085 -90.018362)
		(end 398.2085 -86.3092)
		(width 0.089408)
		(layer "In11.Cu")
		(net "SMB_PMBUS_BMC_STBY_LVC3_SDA_R1")
	)
	(segment
		(start 398.2085 -86.3092)
		(end 397.764 -85.8647)
		(width 0.089408)
		(layer "In11.Cu")
		(net "SMB_PMBUS_BMC_STBY_LVC3_SDA_R1")
	)
	(segment
		(start 396.769082 -79.792322)
		(end 396.94866 -79.612744)
		(width 0.089408)
		(layer "In11.Cu")
		(net "SMB_PMBUS_BMC_STBY_LVC3_SDA_R1")
	)
	(segment
		(start 396.94866 -78.0161)
		(end 397.56969 -77.39507)
		(width 0.089408)
		(layer "In11.Cu")
		(net "SMB_PMBUS_BMC_STBY_LVC3_SDA_R1")
	)
	(segment
		(start 397.764 -82.134964)
		(end 396.769082 -81.140046)
		(width 0.089408)
		(layer "In11.Cu")
		(net "SMB_PMBUS_BMC_STBY_LVC3_SDA_R1")
	)
	(segment
		(start 400.513042 -96.018604)
		(end 398.34693 -93.852492)
		(width 0.089408)
		(layer "In11.Cu")
		(net "SMB_PMBUS_BMC_STBY_LVC3_SDA_R1")
	)
	(segment
		(start 398.34693 -93.852492)
		(end 398.033494 -93.852492)
		(width 0.089408)
		(layer "In11.Cu")
		(net "SMB_PMBUS_BMC_STBY_LVC3_SDA_R1")
	)
	(segment
		(start 400.513042 -105.644442)
		(end 400.513042 -96.018604)
		(width 0.089408)
		(layer "In11.Cu")
		(net "SMB_PMBUS_BMC_STBY_LVC3_SDA_R1")
	)
	(segment
		(start 403.158452 -108.289852)
		(end 400.513042 -105.644442)
		(width 0.089408)
		(layer "In11.Cu")
		(net "SMB_PMBUS_BMC_STBY_LVC3_SDA_R1")
	)
	(segment
		(start 397.56969 -77.39507)
		(end 397.56969 -77.148436)
		(width 0.089408)
		(layer "In11.Cu")
		(net "SMB_PMBUS_BMC_STBY_LVC3_SDA_R1")
	)
	(segment
		(start 397.205962 -91.0209)
		(end 398.2085 -90.018362)
		(width 0.089408)
		(layer "In11.Cu")
		(net "SMB_PMBUS_BMC_STBY_LVC3_SDA_R1")
	)
	(segment
		(start 403.158452 -109.878622)
		(end 403.158452 -108.289852)
		(width 0.089408)
		(layer "In11.Cu")
		(net "SMB_PMBUS_BMC_STBY_LVC3_SDA_R1")
	)
	(segment
		(start 396.769082 -81.140046)
		(end 396.769082 -79.792322)
		(width 0.089408)
		(layer "In11.Cu")
		(net "SMB_PMBUS_BMC_STBY_LVC3_SDA_R1")
	)
	(segment
		(start 398.033494 -93.852492)
		(end 397.205962 -93.02496)
		(width 0.089408)
		(layer "In11.Cu")
		(net "SMB_PMBUS_BMC_STBY_LVC3_SDA_R1")
	)
	(segment
		(start 397.764 -85.8647)
		(end 397.764 -82.134964)
		(width 0.089408)
		(layer "In11.Cu")
		(net "SMB_PMBUS_BMC_STBY_LVC3_SDA_R1")
	)
	(segment
		(start 397.205962 -93.02496)
		(end 397.205962 -91.0209)
		(width 0.089408)
		(layer "In11.Cu")
		(net "SMB_PMBUS_BMC_STBY_LVC3_SDA_R1")
	)
	(segment
		(start 401.295108 -105.855008)
		(end 402.134832 -105.855008)
		(width 0.10795)
		(layer "F.Cu")
		(net "SMB_PMBUS_BMC_STBY_LVC3_SCL_R1")
	)
	(via
		(at 402.134832 -105.855008)
		(size 0.508)
		(drill 0.254)
		(layers "F.Cu" "B.Cu")
		(net "SMB_PMBUS_BMC_STBY_LVC3_SCL_R1")
	)
	(via
		(at 397.571976 -76.437236)
		(size 0.508)
		(drill 0.254)
		(layers "F.Cu" "B.Cu")
		(net "SMB_PMBUS_BMC_STBY_LVC3_SCL_R1")
	)
	(segment
		(start 401.6375 -104.9655)
		(end 402.134832 -105.462832)
		(width 0.10795)
		(layer "B.Cu")
		(net "SMB_PMBUS_BMC_STBY_LVC3_SCL_R1")
	)
	(segment
		(start 399.49628 -76.34224)
		(end 397.666972 -76.34224)
		(width 0.10795)
		(layer "B.Cu")
		(net "SMB_PMBUS_BMC_STBY_LVC3_SCL_R1")
	)
	(segment
		(start 397.666972 -76.34224)
		(end 397.571976 -76.437236)
		(width 0.10795)
		(layer "B.Cu")
		(net "SMB_PMBUS_BMC_STBY_LVC3_SCL_R1")
	)
	(segment
		(start 402.134832 -105.462832)
		(end 402.134832 -105.855008)
		(width 0.10795)
		(layer "B.Cu")
		(net "SMB_PMBUS_BMC_STBY_LVC3_SCL_R1")
	)
	(segment
		(start 401.066 -104.9655)
		(end 401.6375 -104.9655)
		(width 0.10795)
		(layer "B.Cu")
		(net "SMB_PMBUS_BMC_STBY_LVC3_SCL_R1")
	)
	(segment
		(start 398.450308 -90.118692)
		(end 397.44777 -91.12123)
		(width 0.089408)
		(layer "In11.Cu")
		(net "SMB_PMBUS_BMC_STBY_LVC3_SCL_R1")
	)
	(segment
		(start 397.44777 -91.12123)
		(end 397.44777 -92.92463)
		(width 0.089408)
		(layer "In11.Cu")
		(net "SMB_PMBUS_BMC_STBY_LVC3_SCL_R1")
	)
	(segment
		(start 397.40586 -79.57312)
		(end 397.25854 -79.57312)
		(width 0.089408)
		(layer "In11.Cu")
		(net "SMB_PMBUS_BMC_STBY_LVC3_SCL_R1")
	)
	(segment
		(start 398.004792 -82.1055)
		(end 398.004792 -85.763354)
		(width 0.089408)
		(layer "In11.Cu")
		(net "SMB_PMBUS_BMC_STBY_LVC3_SCL_R1")
	)
	(segment
		(start 397.25854 -79.57312)
		(end 396.96009 -79.87157)
		(width 0.089408)
		(layer "In11.Cu")
		(net "SMB_PMBUS_BMC_STBY_LVC3_SCL_R1")
	)
	(segment
		(start 397.775684 -79.203296)
		(end 397.40586 -79.57312)
		(width 0.089408)
		(layer "In11.Cu")
		(net "SMB_PMBUS_BMC_STBY_LVC3_SCL_R1")
	)
	(segment
		(start 401.065746 -105.855008)
		(end 402.134832 -105.855008)
		(width 0.089408)
		(layer "In11.Cu")
		(net "SMB_PMBUS_BMC_STBY_LVC3_SCL_R1")
	)
	(segment
		(start 397.969994 -76.835254)
		(end 397.969994 -77.314298)
		(width 0.089408)
		(layer "In11.Cu")
		(net "SMB_PMBUS_BMC_STBY_LVC3_SCL_R1")
	)
	(segment
		(start 397.44777 -92.92463)
		(end 398.133824 -93.610684)
		(width 0.089408)
		(layer "In11.Cu")
		(net "SMB_PMBUS_BMC_STBY_LVC3_SCL_R1")
	)
	(segment
		(start 396.96009 -79.87157)
		(end 396.96009 -81.060798)
		(width 0.089408)
		(layer "In11.Cu")
		(net "SMB_PMBUS_BMC_STBY_LVC3_SCL_R1")
	)
	(segment
		(start 396.96009 -81.060798)
		(end 398.004792 -82.1055)
		(width 0.089408)
		(layer "In11.Cu")
		(net "SMB_PMBUS_BMC_STBY_LVC3_SCL_R1")
	)
	(segment
		(start 400.75485 -105.544112)
		(end 401.065746 -105.855008)
		(width 0.089408)
		(layer "In11.Cu")
		(net "SMB_PMBUS_BMC_STBY_LVC3_SCL_R1")
	)
	(segment
		(start 398.133824 -93.610684)
		(end 398.44726 -93.610684)
		(width 0.089408)
		(layer "In11.Cu")
		(net "SMB_PMBUS_BMC_STBY_LVC3_SCL_R1")
	)
	(segment
		(start 398.44726 -93.610684)
		(end 400.75485 -95.918274)
		(width 0.089408)
		(layer "In11.Cu")
		(net "SMB_PMBUS_BMC_STBY_LVC3_SCL_R1")
	)
	(segment
		(start 397.571976 -76.437236)
		(end 397.969994 -76.835254)
		(width 0.089408)
		(layer "In11.Cu")
		(net "SMB_PMBUS_BMC_STBY_LVC3_SCL_R1")
	)
	(segment
		(start 397.775684 -77.508608)
		(end 397.775684 -79.203296)
		(width 0.089408)
		(layer "In11.Cu")
		(net "SMB_PMBUS_BMC_STBY_LVC3_SCL_R1")
	)
	(segment
		(start 398.004792 -85.763354)
		(end 398.450308 -86.20887)
		(width 0.089408)
		(layer "In11.Cu")
		(net "SMB_PMBUS_BMC_STBY_LVC3_SCL_R1")
	)
	(segment
		(start 398.450308 -86.20887)
		(end 398.450308 -90.118692)
		(width 0.089408)
		(layer "In11.Cu")
		(net "SMB_PMBUS_BMC_STBY_LVC3_SCL_R1")
	)
	(segment
		(start 397.969994 -77.314298)
		(end 397.775684 -77.508608)
		(width 0.089408)
		(layer "In11.Cu")
		(net "SMB_PMBUS_BMC_STBY_LVC3_SCL_R1")
	)
	(segment
		(start 400.75485 -95.918274)
		(end 400.75485 -105.544112)
		(width 0.089408)
		(layer "In11.Cu")
		(net "SMB_PMBUS_BMC_STBY_LVC3_SCL_R1")
	)
	(segment
		(start 472.3384 -121.852436)
		(end 472.3384 -120.9548)
		(width 0.10795)
		(layer "F.Cu")
		(net "SMB_OCP_LAN_STBY_LVC3_SDA")
	)
	(segment
		(start 472.3384 -120.9548)
		(end 472.792552 -120.9548)
		(width 0.10795)
		(layer "F.Cu")
		(net "SMB_OCP_LAN_STBY_LVC3_SDA")
	)
	(segment
		(start 398.263872 -34.717228)
		(end 398.58823 -35.041586)
		(width 0.10795)
		(layer "F.Cu")
		(net "SMB_OCP_LAN_STBY_LVC3_SDA")
	)
	(segment
		(start 484.163878 -122.601482)
		(end 473.087446 -122.601482)
		(width 0.10795)
		(layer "F.Cu")
		(net "SMB_OCP_LAN_STBY_LVC3_SDA")
	)
	(segment
		(start 473.029788 -119.171466)
		(end 473.400882 -118.800372)
		(width 0.10795)
		(layer "F.Cu")
		(net "SMB_OCP_LAN_STBY_LVC3_SDA")
	)
	(segment
		(start 473.400882 -118.800372)
		(end 473.400882 -116.993162)
		(width 0.10795)
		(layer "F.Cu")
		(net "SMB_OCP_LAN_STBY_LVC3_SDA")
	)
	(segment
		(start 473.087446 -122.601482)
		(end 472.3384 -121.852436)
		(width 0.10795)
		(layer "F.Cu")
		(net "SMB_OCP_LAN_STBY_LVC3_SDA")
	)
	(segment
		(start 487.55554 -121.7168)
		(end 487.163364 -121.324624)
		(width 0.10795)
		(layer "F.Cu")
		(net "SMB_OCP_LAN_STBY_LVC3_SDA")
	)
	(segment
		(start 472.792552 -120.9548)
		(end 473.029788 -120.717564)
		(width 0.10795)
		(layer "F.Cu")
		(net "SMB_OCP_LAN_STBY_LVC3_SDA")
	)
	(segment
		(start 473.029788 -120.717564)
		(end 473.029788 -119.171466)
		(width 0.10795)
		(layer "F.Cu")
		(net "SMB_OCP_LAN_STBY_LVC3_SDA")
	)
	(segment
		(start 485.440736 -121.324624)
		(end 484.163878 -122.601482)
		(width 0.10795)
		(layer "F.Cu")
		(net "SMB_OCP_LAN_STBY_LVC3_SDA")
	)
	(segment
		(start 398.58823 -35.041586)
		(end 398.869916 -35.041586)
		(width 0.10795)
		(layer "F.Cu")
		(net "SMB_OCP_LAN_STBY_LVC3_SDA")
	)
	(segment
		(start 487.163364 -121.324624)
		(end 485.440736 -121.324624)
		(width 0.10795)
		(layer "F.Cu")
		(net "SMB_OCP_LAN_STBY_LVC3_SDA")
	)
	(via
		(at 461.872584 -13.907008)
		(size 0.508)
		(drill 0.254)
		(layers "F.Cu" "B.Cu")
		(net "SMB_OCP_LAN_STBY_LVC3_SDA")
	)
	(via
		(at 472.3384 -120.9548)
		(size 0.508)
		(drill 0.254)
		(layers "F.Cu" "B.Cu")
		(net "SMB_OCP_LAN_STBY_LVC3_SDA")
	)
	(via
		(at 426.4914 -77.3938)
		(size 0.508)
		(drill 0.254)
		(layers "F.Cu" "B.Cu")
		(net "SMB_OCP_LAN_STBY_LVC3_SDA")
	)
	(via
		(at 472.686126 -33.977326)
		(size 0.508)
		(drill 0.254)
		(layers "F.Cu" "B.Cu")
		(net "SMB_OCP_LAN_STBY_LVC3_SDA")
	)
	(via
		(at 487.55554 -121.7168)
		(size 0.508)
		(drill 0.254)
		(layers "F.Cu" "B.Cu")
		(net "SMB_OCP_LAN_STBY_LVC3_SDA")
	)
	(via
		(at 398.263872 -34.717228)
		(size 0.508)
		(drill 0.254)
		(layers "F.Cu" "B.Cu")
		(net "SMB_OCP_LAN_STBY_LVC3_SDA")
	)
	(segment
		(start 427.625764 -110.520734)
		(end 426.698664 -109.593634)
		(width 0.10795)
		(layer "B.Cu")
		(net "SMB_OCP_LAN_STBY_LVC3_SDA")
	)
	(segment
		(start 440.88558 -112.404398)
		(end 439.089546 -114.200432)
		(width 0.10795)
		(layer "B.Cu")
		(net "SMB_OCP_LAN_STBY_LVC3_SDA")
	)
	(segment
		(start 394.632434 -19.348958)
		(end 392.680698 -17.397222)
		(width 0.10795)
		(layer "B.Cu")
		(net "SMB_OCP_LAN_STBY_LVC3_SDA")
	)
	(segment
		(start 433.426108 -110.520734)
		(end 427.625764 -110.520734)
		(width 0.10795)
		(layer "B.Cu")
		(net "SMB_OCP_LAN_STBY_LVC3_SDA")
	)
	(segment
		(start 395.443456 -19.348958)
		(end 394.632434 -19.348958)
		(width 0.10795)
		(layer "B.Cu")
		(net "SMB_OCP_LAN_STBY_LVC3_SDA")
	)
	(segment
		(start 397.41856 -25.781)
		(end 397.41856 -21.324062)
		(width 0.10795)
		(layer "B.Cu")
		(net "SMB_OCP_LAN_STBY_LVC3_SDA")
	)
	(segment
		(start 472.3384 -120.9548)
		(end 471.73388 -120.9548)
		(width 0.10795)
		(layer "B.Cu")
		(net "SMB_OCP_LAN_STBY_LVC3_SDA")
	)
	(segment
		(start 487.55554 -121.7168)
		(end 487.98988 -121.28246)
		(width 0.10795)
		(layer "B.Cu")
		(net "SMB_OCP_LAN_STBY_LVC3_SDA")
	)
	(segment
		(start 471.73388 -120.9548)
		(end 470.239598 -119.460518)
		(width 0.10795)
		(layer "B.Cu")
		(net "SMB_OCP_LAN_STBY_LVC3_SDA")
	)
	(segment
		(start 426.698664 -109.593634)
		(end 426.698664 -79.785718)
		(width 0.10795)
		(layer "B.Cu")
		(net "SMB_OCP_LAN_STBY_LVC3_SDA")
	)
	(segment
		(start 398.820132 -33.570418)
		(end 398.699736 -33.450022)
		(width 0.10795)
		(layer "B.Cu")
		(net "SMB_OCP_LAN_STBY_LVC3_SDA")
	)
	(segment
		(start 435.633876 -114.962686)
		(end 435.633876 -113.273586)
		(width 0.10795)
		(layer "B.Cu")
		(net "SMB_OCP_LAN_STBY_LVC3_SDA")
	)
	(segment
		(start 469.764872 -113.9317)
		(end 468.949786 -113.9317)
		(width 0.10795)
		(layer "B.Cu")
		(net "SMB_OCP_LAN_STBY_LVC3_SDA")
	)
	(segment
		(start 470.541096 -114.707924)
		(end 469.764872 -113.9317)
		(width 0.10795)
		(layer "B.Cu")
		(net "SMB_OCP_LAN_STBY_LVC3_SDA")
	)
	(segment
		(start 439.0898 -115.172998)
		(end 438.353708 -115.90909)
		(width 0.10795)
		(layer "B.Cu")
		(net "SMB_OCP_LAN_STBY_LVC3_SDA")
	)
	(segment
		(start 439.089546 -114.590068)
		(end 439.0898 -114.590322)
		(width 0.10795)
		(layer "B.Cu")
		(net "SMB_OCP_LAN_STBY_LVC3_SDA")
	)
	(segment
		(start 470.239598 -119.460518)
		(end 470.239598 -116.27358)
		(width 0.10795)
		(layer "B.Cu")
		(net "SMB_OCP_LAN_STBY_LVC3_SDA")
	)
	(segment
		(start 490.15396 -121.28246)
		(end 490.3851 -121.5136)
		(width 0.10795)
		(layer "B.Cu")
		(net "SMB_OCP_LAN_STBY_LVC3_SDA")
	)
	(segment
		(start 435.450996 -112.545622)
		(end 433.426108 -110.520734)
		(width 0.10795)
		(layer "B.Cu")
		(net "SMB_OCP_LAN_STBY_LVC3_SDA")
	)
	(segment
		(start 439.089546 -114.200432)
		(end 439.089546 -114.590068)
		(width 0.10795)
		(layer "B.Cu")
		(net "SMB_OCP_LAN_STBY_LVC3_SDA")
	)
	(segment
		(start 438.353708 -115.90909)
		(end 436.58028 -115.90909)
		(width 0.10795)
		(layer "B.Cu")
		(net "SMB_OCP_LAN_STBY_LVC3_SDA")
	)
	(segment
		(start 426.698664 -79.785718)
		(end 426.33646 -79.423514)
		(width 0.10795)
		(layer "B.Cu")
		(net "SMB_OCP_LAN_STBY_LVC3_SDA")
	)
	(segment
		(start 398.126458 -31.460694)
		(end 398.126458 -30.096714)
		(width 0.10795)
		(layer "B.Cu")
		(net "SMB_OCP_LAN_STBY_LVC3_SDA")
	)
	(segment
		(start 398.724882 -29.49829)
		(end 398.724882 -27.087322)
		(width 0.10795)
		(layer "B.Cu")
		(net "SMB_OCP_LAN_STBY_LVC3_SDA")
	)
	(segment
		(start 398.724882 -27.087322)
		(end 397.41856 -25.781)
		(width 0.10795)
		(layer "B.Cu")
		(net "SMB_OCP_LAN_STBY_LVC3_SDA")
	)
	(segment
		(start 426.33646 -79.423514)
		(end 426.33646 -77.54874)
		(width 0.10795)
		(layer "B.Cu")
		(net "SMB_OCP_LAN_STBY_LVC3_SDA")
	)
	(segment
		(start 439.0898 -114.590322)
		(end 439.0898 -115.172998)
		(width 0.10795)
		(layer "B.Cu")
		(net "SMB_OCP_LAN_STBY_LVC3_SDA")
	)
	(segment
		(start 467.422484 -112.404398)
		(end 440.88558 -112.404398)
		(width 0.10795)
		(layer "B.Cu")
		(net "SMB_OCP_LAN_STBY_LVC3_SDA")
	)
	(segment
		(start 397.41856 -21.324062)
		(end 395.443456 -19.348958)
		(width 0.10795)
		(layer "B.Cu")
		(net "SMB_OCP_LAN_STBY_LVC3_SDA")
	)
	(segment
		(start 487.98988 -121.28246)
		(end 490.15396 -121.28246)
		(width 0.10795)
		(layer "B.Cu")
		(net "SMB_OCP_LAN_STBY_LVC3_SDA")
	)
	(segment
		(start 398.699736 -33.450022)
		(end 398.699736 -32.033972)
		(width 0.10795)
		(layer "B.Cu")
		(net "SMB_OCP_LAN_STBY_LVC3_SDA")
	)
	(segment
		(start 468.949786 -113.9317)
		(end 467.422484 -112.404398)
		(width 0.10795)
		(layer "B.Cu")
		(net "SMB_OCP_LAN_STBY_LVC3_SDA")
	)
	(segment
		(start 392.680698 -17.397222)
		(end 392.680698 -16.691864)
		(width 0.10795)
		(layer "B.Cu")
		(net "SMB_OCP_LAN_STBY_LVC3_SDA")
	)
	(segment
		(start 435.633876 -113.273586)
		(end 435.450996 -113.090706)
		(width 0.10795)
		(layer "B.Cu")
		(net "SMB_OCP_LAN_STBY_LVC3_SDA")
	)
	(segment
		(start 435.450996 -113.090706)
		(end 435.450996 -112.545622)
		(width 0.10795)
		(layer "B.Cu")
		(net "SMB_OCP_LAN_STBY_LVC3_SDA")
	)
	(segment
		(start 426.33646 -77.54874)
		(end 426.4914 -77.3938)
		(width 0.10795)
		(layer "B.Cu")
		(net "SMB_OCP_LAN_STBY_LVC3_SDA")
	)
	(segment
		(start 398.699736 -32.033972)
		(end 398.126458 -31.460694)
		(width 0.10795)
		(layer "B.Cu")
		(net "SMB_OCP_LAN_STBY_LVC3_SDA")
	)
	(segment
		(start 398.263872 -34.717228)
		(end 398.820132 -34.160968)
		(width 0.10795)
		(layer "B.Cu")
		(net "SMB_OCP_LAN_STBY_LVC3_SDA")
	)
	(segment
		(start 470.541096 -115.972082)
		(end 470.541096 -114.707924)
		(width 0.10795)
		(layer "B.Cu")
		(net "SMB_OCP_LAN_STBY_LVC3_SDA")
	)
	(segment
		(start 398.820132 -34.160968)
		(end 398.820132 -33.570418)
		(width 0.10795)
		(layer "B.Cu")
		(net "SMB_OCP_LAN_STBY_LVC3_SDA")
	)
	(segment
		(start 470.239598 -116.27358)
		(end 470.541096 -115.972082)
		(width 0.10795)
		(layer "B.Cu")
		(net "SMB_OCP_LAN_STBY_LVC3_SDA")
	)
	(segment
		(start 436.58028 -115.90909)
		(end 435.633876 -114.962686)
		(width 0.10795)
		(layer "B.Cu")
		(net "SMB_OCP_LAN_STBY_LVC3_SDA")
	)
	(segment
		(start 398.126458 -30.096714)
		(end 398.724882 -29.49829)
		(width 0.10795)
		(layer "B.Cu")
		(net "SMB_OCP_LAN_STBY_LVC3_SDA")
	)
	(segment
		(start 405.458168 -24.603456)
		(end 406.017984 -24.603456)
		(width 0.089408)
		(layer "In9.Cu")
		(net "SMB_OCP_LAN_STBY_LVC3_SDA")
	)
	(segment
		(start 433.502308 -20.75688)
		(end 434.531262 -20.75688)
		(width 0.089408)
		(layer "In9.Cu")
		(net "SMB_OCP_LAN_STBY_LVC3_SDA")
	)
	(segment
		(start 401.40509 -23.968964)
		(end 401.563078 -23.968964)
		(width 0.089408)
		(layer "In9.Cu")
		(net "SMB_OCP_LAN_STBY_LVC3_SDA")
	)
	(segment
		(start 420.507414 -21.082508)
		(end 421.43172 -20.158202)
		(width 0.089408)
		(layer "In9.Cu")
		(net "SMB_OCP_LAN_STBY_LVC3_SDA")
	)
	(segment
		(start 400.381216 -23.626064)
		(end 401.06219 -23.626064)
		(width 0.089408)
		(layer "In9.Cu")
		(net "SMB_OCP_LAN_STBY_LVC3_SDA")
	)
	(segment
		(start 471.841322 -66.780664)
		(end 476.352616 -62.26937)
		(width 0.089408)
		(layer "In9.Cu")
		(net "SMB_OCP_LAN_STBY_LVC3_SDA")
	)
	(segment
		(start 403.761448 -24.627332)
		(end 403.935184 -24.453596)
		(width 0.089408)
		(layer "In9.Cu")
		(net "SMB_OCP_LAN_STBY_LVC3_SDA")
	)
	(segment
		(start 453.925432 -21.181568)
		(end 455.75093 -21.181568)
		(width 0.089408)
		(layer "In9.Cu")
		(net "SMB_OCP_LAN_STBY_LVC3_SDA")
	)
	(segment
		(start 436.12943 -21.638514)
		(end 436.129684 -21.63826)
		(width 0.089408)
		(layer "In9.Cu")
		(net "SMB_OCP_LAN_STBY_LVC3_SDA")
	)
	(segment
		(start 476.352616 -58.106564)
		(end 474.594428 -56.348376)
		(width 0.089408)
		(layer "In9.Cu")
		(net "SMB_OCP_LAN_STBY_LVC3_SDA")
	)
	(segment
		(start 398.103598 -24.289258)
		(end 398.689576 -23.70328)
		(width 0.089408)
		(layer "In9.Cu")
		(net "SMB_OCP_LAN_STBY_LVC3_SDA")
	)
	(segment
		(start 401.06219 -23.626064)
		(end 401.40509 -23.968964)
		(width 0.089408)
		(layer "In9.Cu")
		(net "SMB_OCP_LAN_STBY_LVC3_SDA")
	)
	(segment
		(start 472.3892 -43.942)
		(end 472.3892 -39.1414)
		(width 0.089408)
		(layer "In9.Cu")
		(net "SMB_OCP_LAN_STBY_LVC3_SDA")
	)
	(segment
		(start 471.803476 -54.850538)
		(end 471.803476 -54.831488)
		(width 0.089408)
		(layer "In9.Cu")
		(net "SMB_OCP_LAN_STBY_LVC3_SDA")
	)
	(segment
		(start 402.760942 -24.627332)
		(end 403.761448 -24.627332)
		(width 0.089408)
		(layer "In9.Cu")
		(net "SMB_OCP_LAN_STBY_LVC3_SDA")
	)
	(segment
		(start 401.563332 -23.969218)
		(end 402.038312 -23.969218)
		(width 0.089408)
		(layer "In9.Cu")
		(net "SMB_OCP_LAN_STBY_LVC3_SDA")
	)
	(segment
		(start 437.172862 -21.63826)
		(end 437.835802 -22.3012)
		(width 0.089408)
		(layer "In9.Cu")
		(net "SMB_OCP_LAN_STBY_LVC3_SDA")
	)
	(segment
		(start 437.835802 -22.3012)
		(end 440.526932 -22.3012)
		(width 0.089408)
		(layer "In9.Cu")
		(net "SMB_OCP_LAN_STBY_LVC3_SDA")
	)
	(segment
		(start 474.94444 -46.49724)
		(end 472.3892 -43.942)
		(width 0.089408)
		(layer "In9.Cu")
		(net "SMB_OCP_LAN_STBY_LVC3_SDA")
	)
	(segment
		(start 472.275408 -34.388044)
		(end 472.686126 -33.977326)
		(width 0.089408)
		(layer "In9.Cu")
		(net "SMB_OCP_LAN_STBY_LVC3_SDA")
	)
	(segment
		(start 426.476922 -20.093432)
		(end 427.708314 -21.324824)
		(width 0.089408)
		(layer "In9.Cu")
		(net "SMB_OCP_LAN_STBY_LVC3_SDA")
	)
	(segment
		(start 401.563078 -23.968964)
		(end 401.563332 -23.969218)
		(width 0.089408)
		(layer "In9.Cu")
		(net "SMB_OCP_LAN_STBY_LVC3_SDA")
	)
	(segment
		(start 413.691324 -21.958808)
		(end 414.089342 -21.56079)
		(width 0.089408)
		(layer "In9.Cu")
		(net "SMB_OCP_LAN_STBY_LVC3_SDA")
	)
	(segment
		(start 455.75093 -21.181568)
		(end 457.008992 -19.923506)
		(width 0.089408)
		(layer "In9.Cu")
		(net "SMB_OCP_LAN_STBY_LVC3_SDA")
	)
	(segment
		(start 421.95242 -20.158202)
		(end 422.01719 -20.093432)
		(width 0.089408)
		(layer "In9.Cu")
		(net "SMB_OCP_LAN_STBY_LVC3_SDA")
	)
	(segment
		(start 425.095416 -68.795646)
		(end 427.110398 -66.780664)
		(width 0.089408)
		(layer "In9.Cu")
		(net "SMB_OCP_LAN_STBY_LVC3_SDA")
	)
	(segment
		(start 411.843982 -24.127206)
		(end 411.843982 -23.80615)
		(width 0.089408)
		(layer "In9.Cu")
		(net "SMB_OCP_LAN_STBY_LVC3_SDA")
	)
	(segment
		(start 436.129684 -21.63826)
		(end 437.172862 -21.63826)
		(width 0.089408)
		(layer "In9.Cu")
		(net "SMB_OCP_LAN_STBY_LVC3_SDA")
	)
	(segment
		(start 435.971188 -21.63826)
		(end 435.971442 -21.638514)
		(width 0.089408)
		(layer "In9.Cu")
		(net "SMB_OCP_LAN_STBY_LVC3_SDA")
	)
	(segment
		(start 421.43172 -20.158202)
		(end 421.95242 -20.158202)
		(width 0.089408)
		(layer "In9.Cu")
		(net "SMB_OCP_LAN_STBY_LVC3_SDA")
	)
	(segment
		(start 402.03882 -23.96871)
		(end 402.10232 -23.96871)
		(width 0.089408)
		(layer "In9.Cu")
		(net "SMB_OCP_LAN_STBY_LVC3_SDA")
	)
	(segment
		(start 471.739976 -54.767988)
		(end 471.739976 -53.750464)
		(width 0.089408)
		(layer "In9.Cu")
		(net "SMB_OCP_LAN_STBY_LVC3_SDA")
	)
	(segment
		(start 416.941508 -21.082508)
		(end 420.507414 -21.082508)
		(width 0.089408)
		(layer "In9.Cu")
		(net "SMB_OCP_LAN_STBY_LVC3_SDA")
	)
	(segment
		(start 473.333826 -36.621466)
		(end 472.275408 -35.563048)
		(width 0.089408)
		(layer "In9.Cu")
		(net "SMB_OCP_LAN_STBY_LVC3_SDA")
	)
	(segment
		(start 449.1863 -25.9207)
		(end 453.925432 -21.181568)
		(width 0.089408)
		(layer "In9.Cu")
		(net "SMB_OCP_LAN_STBY_LVC3_SDA")
	)
	(segment
		(start 457.008992 -19.912076)
		(end 457.53782 -19.912076)
		(width 0.089408)
		(layer "In9.Cu")
		(net "SMB_OCP_LAN_STBY_LVC3_SDA")
	)
	(segment
		(start 472.275408 -35.563048)
		(end 472.275408 -34.388044)
		(width 0.089408)
		(layer "In9.Cu")
		(net "SMB_OCP_LAN_STBY_LVC3_SDA")
	)
	(segment
		(start 432.934364 -21.324824)
		(end 433.502308 -20.75688)
		(width 0.089408)
		(layer "In9.Cu")
		(net "SMB_OCP_LAN_STBY_LVC3_SDA")
	)
	(segment
		(start 473.301314 -56.348376)
		(end 471.803476 -54.850538)
		(width 0.089408)
		(layer "In9.Cu")
		(net "SMB_OCP_LAN_STBY_LVC3_SDA")
	)
	(segment
		(start 398.263872 -34.717228)
		(end 397.987774 -34.993326)
		(width 0.089408)
		(layer "In9.Cu")
		(net "SMB_OCP_LAN_STBY_LVC3_SDA")
	)
	(segment
		(start 446.4558 -24.819102)
		(end 446.456054 -24.819102)
		(width 0.089408)
		(layer "In9.Cu")
		(net "SMB_OCP_LAN_STBY_LVC3_SDA")
	)
	(segment
		(start 411.843982 -23.80615)
		(end 412.033974 -23.616158)
		(width 0.089408)
		(layer "In9.Cu")
		(net "SMB_OCP_LAN_STBY_LVC3_SDA")
	)
	(segment
		(start 441.403994 -23.178262)
		(end 441.404248 -23.178262)
		(width 0.089408)
		(layer "In9.Cu")
		(net "SMB_OCP_LAN_STBY_LVC3_SDA")
	)
	(segment
		(start 473.333826 -38.196774)
		(end 473.333826 -36.621466)
		(width 0.089408)
		(layer "In9.Cu")
		(net "SMB_OCP_LAN_STBY_LVC3_SDA")
	)
	(segment
		(start 413.691324 -21.959062)
		(end 413.691324 -21.958808)
		(width 0.089408)
		(layer "In9.Cu")
		(net "SMB_OCP_LAN_STBY_LVC3_SDA")
	)
	(segment
		(start 427.110398 -66.780664)
		(end 471.841322 -66.780664)
		(width 0.089408)
		(layer "In9.Cu")
		(net "SMB_OCP_LAN_STBY_LVC3_SDA")
	)
	(segment
		(start 409.514548 -24.72182)
		(end 411.407864 -24.72182)
		(width 0.089408)
		(layer "In9.Cu")
		(net "SMB_OCP_LAN_STBY_LVC3_SDA")
	)
	(segment
		(start 398.659858 -32.795972)
		(end 398.659858 -31.2293)
		(width 0.089408)
		(layer "In9.Cu")
		(net "SMB_OCP_LAN_STBY_LVC3_SDA")
	)
	(segment
		(start 476.352616 -62.26937)
		(end 476.352616 -58.106564)
		(width 0.089408)
		(layer "In9.Cu")
		(net "SMB_OCP_LAN_STBY_LVC3_SDA")
	)
	(segment
		(start 441.457588 -23.231602)
		(end 444.8683 -23.231602)
		(width 0.089408)
		(layer "In9.Cu")
		(net "SMB_OCP_LAN_STBY_LVC3_SDA")
	)
	(segment
		(start 435.971442 -21.638514)
		(end 436.12943 -21.638514)
		(width 0.089408)
		(layer "In9.Cu")
		(net "SMB_OCP_LAN_STBY_LVC3_SDA")
	)
	(segment
		(start 471.739976 -53.750464)
		(end 472.493848 -52.996592)
		(width 0.089408)
		(layer "In9.Cu")
		(net "SMB_OCP_LAN_STBY_LVC3_SDA")
	)
	(segment
		(start 406.017984 -24.603456)
		(end 406.199086 -24.422354)
		(width 0.089408)
		(layer "In9.Cu")
		(net "SMB_OCP_LAN_STBY_LVC3_SDA")
	)
	(segment
		(start 412.033974 -23.616158)
		(end 412.034228 -23.616158)
		(width 0.089408)
		(layer "In9.Cu")
		(net "SMB_OCP_LAN_STBY_LVC3_SDA")
	)
	(segment
		(start 434.531262 -20.75688)
		(end 435.412642 -21.63826)
		(width 0.089408)
		(layer "In9.Cu")
		(net "SMB_OCP_LAN_STBY_LVC3_SDA")
	)
	(segment
		(start 397.749776 -34.88182)
		(end 397.749776 -33.706054)
		(width 0.089408)
		(layer "In9.Cu")
		(net "SMB_OCP_LAN_STBY_LVC3_SDA")
	)
	(segment
		(start 426.4914 -77.3938)
		(end 425.095416 -75.997816)
		(width 0.089408)
		(layer "In9.Cu")
		(net "SMB_OCP_LAN_STBY_LVC3_SDA")
	)
	(segment
		(start 398.659858 -31.2293)
		(end 398.103598 -30.67304)
		(width 0.089408)
		(layer "In9.Cu")
		(net "SMB_OCP_LAN_STBY_LVC3_SDA")
	)
	(segment
		(start 414.089342 -20.894548)
		(end 414.424876 -20.559014)
		(width 0.089408)
		(layer "In9.Cu")
		(net "SMB_OCP_LAN_STBY_LVC3_SDA")
	)
	(segment
		(start 397.861282 -34.993326)
		(end 397.749776 -34.88182)
		(width 0.089408)
		(layer "In9.Cu")
		(net "SMB_OCP_LAN_STBY_LVC3_SDA")
	)
	(segment
		(start 411.844236 -24.12746)
		(end 411.843982 -24.127206)
		(width 0.089408)
		(layer "In9.Cu")
		(net "SMB_OCP_LAN_STBY_LVC3_SDA")
	)
	(segment
		(start 461.689958 -14.089634)
		(end 461.872584 -13.907008)
		(width 0.089408)
		(layer "In9.Cu")
		(net "SMB_OCP_LAN_STBY_LVC3_SDA")
	)
	(segment
		(start 425.095416 -75.997816)
		(end 425.095416 -68.795646)
		(width 0.089408)
		(layer "In9.Cu")
		(net "SMB_OCP_LAN_STBY_LVC3_SDA")
	)
	(segment
		(start 416.418014 -20.559014)
		(end 416.941508 -21.082508)
		(width 0.089408)
		(layer "In9.Cu")
		(net "SMB_OCP_LAN_STBY_LVC3_SDA")
	)
	(segment
		(start 398.103598 -30.67304)
		(end 398.103598 -24.289258)
		(width 0.089408)
		(layer "In9.Cu")
		(net "SMB_OCP_LAN_STBY_LVC3_SDA")
	)
	(segment
		(start 444.8683 -23.231602)
		(end 446.4558 -24.819102)
		(width 0.089408)
		(layer "In9.Cu")
		(net "SMB_OCP_LAN_STBY_LVC3_SDA")
	)
	(segment
		(start 411.844236 -24.285448)
		(end 411.844236 -24.12746)
		(width 0.089408)
		(layer "In9.Cu")
		(net "SMB_OCP_LAN_STBY_LVC3_SDA")
	)
	(segment
		(start 411.407864 -24.72182)
		(end 411.844236 -24.285448)
		(width 0.089408)
		(layer "In9.Cu")
		(net "SMB_OCP_LAN_STBY_LVC3_SDA")
	)
	(segment
		(start 474.94444 -50.76063)
		(end 474.94444 -46.49724)
		(width 0.089408)
		(layer "In9.Cu")
		(net "SMB_OCP_LAN_STBY_LVC3_SDA")
	)
	(segment
		(start 447.557652 -25.9207)
		(end 449.1863 -25.9207)
		(width 0.089408)
		(layer "In9.Cu")
		(net "SMB_OCP_LAN_STBY_LVC3_SDA")
	)
	(segment
		(start 440.526932 -22.3012)
		(end 441.403994 -23.178262)
		(width 0.089408)
		(layer "In9.Cu")
		(net "SMB_OCP_LAN_STBY_LVC3_SDA")
	)
	(segment
		(start 472.493848 -52.996592)
		(end 472.708478 -52.996592)
		(width 0.089408)
		(layer "In9.Cu")
		(net "SMB_OCP_LAN_STBY_LVC3_SDA")
	)
	(segment
		(start 403.935184 -24.453596)
		(end 405.308308 -24.453596)
		(width 0.089408)
		(layer "In9.Cu")
		(net "SMB_OCP_LAN_STBY_LVC3_SDA")
	)
	(segment
		(start 472.708478 -52.996592)
		(end 474.94444 -50.76063)
		(width 0.089408)
		(layer "In9.Cu")
		(net "SMB_OCP_LAN_STBY_LVC3_SDA")
	)
	(segment
		(start 457.008992 -19.923506)
		(end 457.008992 -19.912076)
		(width 0.089408)
		(layer "In9.Cu")
		(net "SMB_OCP_LAN_STBY_LVC3_SDA")
	)
	(segment
		(start 398.689576 -23.70328)
		(end 400.304 -23.70328)
		(width 0.089408)
		(layer "In9.Cu")
		(net "SMB_OCP_LAN_STBY_LVC3_SDA")
	)
	(segment
		(start 427.708314 -21.324824)
		(end 432.934364 -21.324824)
		(width 0.089408)
		(layer "In9.Cu")
		(net "SMB_OCP_LAN_STBY_LVC3_SDA")
	)
	(segment
		(start 461.689958 -15.759938)
		(end 461.689958 -14.089634)
		(width 0.089408)
		(layer "In9.Cu")
		(net "SMB_OCP_LAN_STBY_LVC3_SDA")
	)
	(segment
		(start 400.304 -23.70328)
		(end 400.381216 -23.626064)
		(width 0.089408)
		(layer "In9.Cu")
		(net "SMB_OCP_LAN_STBY_LVC3_SDA")
	)
	(segment
		(start 446.456054 -24.819102)
		(end 447.557652 -25.9207)
		(width 0.089408)
		(layer "In9.Cu")
		(net "SMB_OCP_LAN_STBY_LVC3_SDA")
	)
	(segment
		(start 422.01719 -20.093432)
		(end 426.476922 -20.093432)
		(width 0.089408)
		(layer "In9.Cu")
		(net "SMB_OCP_LAN_STBY_LVC3_SDA")
	)
	(segment
		(start 406.199086 -24.422354)
		(end 409.215082 -24.422354)
		(width 0.089408)
		(layer "In9.Cu")
		(net "SMB_OCP_LAN_STBY_LVC3_SDA")
	)
	(segment
		(start 397.749776 -33.706054)
		(end 398.659858 -32.795972)
		(width 0.089408)
		(layer "In9.Cu")
		(net "SMB_OCP_LAN_STBY_LVC3_SDA")
	)
	(segment
		(start 472.3892 -39.1414)
		(end 473.333826 -38.196774)
		(width 0.089408)
		(layer "In9.Cu")
		(net "SMB_OCP_LAN_STBY_LVC3_SDA")
	)
	(segment
		(start 435.412642 -21.63826)
		(end 435.971188 -21.63826)
		(width 0.089408)
		(layer "In9.Cu")
		(net "SMB_OCP_LAN_STBY_LVC3_SDA")
	)
	(segment
		(start 412.034228 -23.616158)
		(end 413.691324 -21.959062)
		(width 0.089408)
		(layer "In9.Cu")
		(net "SMB_OCP_LAN_STBY_LVC3_SDA")
	)
	(segment
		(start 457.53782 -19.912076)
		(end 461.689958 -15.759938)
		(width 0.089408)
		(layer "In9.Cu")
		(net "SMB_OCP_LAN_STBY_LVC3_SDA")
	)
	(segment
		(start 409.215082 -24.422354)
		(end 409.514548 -24.72182)
		(width 0.089408)
		(layer "In9.Cu")
		(net "SMB_OCP_LAN_STBY_LVC3_SDA")
	)
	(segment
		(start 414.424876 -20.559014)
		(end 416.418014 -20.559014)
		(width 0.089408)
		(layer "In9.Cu")
		(net "SMB_OCP_LAN_STBY_LVC3_SDA")
	)
	(segment
		(start 405.308308 -24.453596)
		(end 405.458168 -24.603456)
		(width 0.089408)
		(layer "In9.Cu")
		(net "SMB_OCP_LAN_STBY_LVC3_SDA")
	)
	(segment
		(start 414.089342 -21.56079)
		(end 414.089342 -20.894548)
		(width 0.089408)
		(layer "In9.Cu")
		(net "SMB_OCP_LAN_STBY_LVC3_SDA")
	)
	(segment
		(start 471.803476 -54.831488)
		(end 471.739976 -54.767988)
		(width 0.089408)
		(layer "In9.Cu")
		(net "SMB_OCP_LAN_STBY_LVC3_SDA")
	)
	(segment
		(start 397.987774 -34.993326)
		(end 397.861282 -34.993326)
		(width 0.089408)
		(layer "In9.Cu")
		(net "SMB_OCP_LAN_STBY_LVC3_SDA")
	)
	(segment
		(start 402.038312 -23.969218)
		(end 402.03882 -23.96871)
		(width 0.089408)
		(layer "In9.Cu")
		(net "SMB_OCP_LAN_STBY_LVC3_SDA")
	)
	(segment
		(start 402.10232 -23.96871)
		(end 402.760942 -24.627332)
		(width 0.089408)
		(layer "In9.Cu")
		(net "SMB_OCP_LAN_STBY_LVC3_SDA")
	)
	(segment
		(start 441.404248 -23.178262)
		(end 441.457588 -23.231602)
		(width 0.089408)
		(layer "In9.Cu")
		(net "SMB_OCP_LAN_STBY_LVC3_SDA")
	)
	(segment
		(start 474.594428 -56.348376)
		(end 473.301314 -56.348376)
		(width 0.089408)
		(layer "In9.Cu")
		(net "SMB_OCP_LAN_STBY_LVC3_SDA")
	)
	(segment
		(start 461.68437 -20.653502)
		(end 472.293442 -31.262574)
		(width 0.089408)
		(layer "In11.Cu")
		(net "SMB_OCP_LAN_STBY_LVC3_SDA")
	)
	(segment
		(start 461.68437 -14.095222)
		(end 461.68437 -20.653502)
		(width 0.089408)
		(layer "In11.Cu")
		(net "SMB_OCP_LAN_STBY_LVC3_SDA")
	)
	(segment
		(start 472.293442 -31.262574)
		(end 472.293442 -33.584642)
		(width 0.089408)
		(layer "In11.Cu")
		(net "SMB_OCP_LAN_STBY_LVC3_SDA")
	)
	(segment
		(start 461.872584 -13.907008)
		(end 461.68437 -14.095222)
		(width 0.089408)
		(layer "In11.Cu")
		(net "SMB_OCP_LAN_STBY_LVC3_SDA")
	)
	(segment
		(start 472.293442 -33.584642)
		(end 472.686126 -33.977326)
		(width 0.089408)
		(layer "In11.Cu")
		(net "SMB_OCP_LAN_STBY_LVC3_SDA")
	)
	(segment
		(start 487.55554 -120.6754)
		(end 487.15549 -121.07545)
		(width 0.10795)
		(layer "F.Cu")
		(net "SMB_OCP_LAN_STBY_LVC3_SCL")
	)
	(segment
		(start 398.610582 -35.803586)
		(end 398.267174 -35.460178)
		(width 0.10795)
		(layer "F.Cu")
		(net "SMB_OCP_LAN_STBY_LVC3_SCL")
	)
	(segment
		(start 473.073984 -121.791984)
		(end 473.073984 -121.005854)
		(width 0.10795)
		(layer "F.Cu")
		(net "SMB_OCP_LAN_STBY_LVC3_SCL")
	)
	(segment
		(start 474.200982 -118.351554)
		(end 474.200982 -116.993162)
		(width 0.10795)
		(layer "F.Cu")
		(net "SMB_OCP_LAN_STBY_LVC3_SCL")
	)
	(segment
		(start 485.357424 -121.07545)
		(end 484.091742 -122.341132)
		(width 0.10795)
		(layer "F.Cu")
		(net "SMB_OCP_LAN_STBY_LVC3_SCL")
	)
	(segment
		(start 473.264738 -120.8151)
		(end 473.264738 -119.287798)
		(width 0.10795)
		(layer "F.Cu")
		(net "SMB_OCP_LAN_STBY_LVC3_SCL")
	)
	(segment
		(start 473.264738 -119.287798)
		(end 474.200982 -118.351554)
		(width 0.10795)
		(layer "F.Cu")
		(net "SMB_OCP_LAN_STBY_LVC3_SCL")
	)
	(segment
		(start 484.091742 -122.341132)
		(end 473.623132 -122.341132)
		(width 0.10795)
		(layer "F.Cu")
		(net "SMB_OCP_LAN_STBY_LVC3_SCL")
	)
	(segment
		(start 473.073984 -121.005854)
		(end 473.264738 -120.8151)
		(width 0.10795)
		(layer "F.Cu")
		(net "SMB_OCP_LAN_STBY_LVC3_SCL")
	)
	(segment
		(start 473.623132 -122.341132)
		(end 473.202 -121.92)
		(width 0.10795)
		(layer "F.Cu")
		(net "SMB_OCP_LAN_STBY_LVC3_SCL")
	)
	(segment
		(start 398.874996 -35.803586)
		(end 398.610582 -35.803586)
		(width 0.10795)
		(layer "F.Cu")
		(net "SMB_OCP_LAN_STBY_LVC3_SCL")
	)
	(segment
		(start 487.15549 -121.07545)
		(end 485.357424 -121.07545)
		(width 0.10795)
		(layer "F.Cu")
		(net "SMB_OCP_LAN_STBY_LVC3_SCL")
	)
	(segment
		(start 473.202 -121.92)
		(end 473.073984 -121.791984)
		(width 0.10795)
		(layer "F.Cu")
		(net "SMB_OCP_LAN_STBY_LVC3_SCL")
	)
	(via
		(at 461.171798 -13.91285)
		(size 0.508)
		(drill 0.254)
		(layers "F.Cu" "B.Cu")
		(net "SMB_OCP_LAN_STBY_LVC3_SCL")
	)
	(via
		(at 472.686126 -34.637726)
		(size 0.508)
		(drill 0.254)
		(layers "F.Cu" "B.Cu")
		(net "SMB_OCP_LAN_STBY_LVC3_SCL")
	)
	(via
		(at 426.4914 -76.7334)
		(size 0.508)
		(drill 0.254)
		(layers "F.Cu" "B.Cu")
		(net "SMB_OCP_LAN_STBY_LVC3_SCL")
	)
	(via
		(at 473.202 -121.92)
		(size 0.508)
		(drill 0.254)
		(layers "F.Cu" "B.Cu")
		(net "SMB_OCP_LAN_STBY_LVC3_SCL")
	)
	(via
		(at 398.267174 -35.460178)
		(size 0.508)
		(drill 0.254)
		(layers "F.Cu" "B.Cu")
		(net "SMB_OCP_LAN_STBY_LVC3_SCL")
	)
	(via
		(at 487.55554 -120.6754)
		(size 0.508)
		(drill 0.254)
		(layers "F.Cu" "B.Cu")
		(net "SMB_OCP_LAN_STBY_LVC3_SCL")
	)
	(segment
		(start 470.306146 -114.80546)
		(end 470.306146 -115.874546)
		(width 0.10795)
		(layer "B.Cu")
		(net "SMB_OCP_LAN_STBY_LVC3_SCL")
	)
	(segment
		(start 427.528228 -110.755684)
		(end 433.328572 -110.755684)
		(width 0.10795)
		(layer "B.Cu")
		(net "SMB_OCP_LAN_STBY_LVC3_SCL")
	)
	(segment
		(start 426.068998 -79.638398)
		(end 426.438314 -80.007714)
		(width 0.10795)
		(layer "B.Cu")
		(net "SMB_OCP_LAN_STBY_LVC3_SCL")
	)
	(segment
		(start 426.438314 -80.007714)
		(end 426.438314 -109.66577)
		(width 0.10795)
		(layer "B.Cu")
		(net "SMB_OCP_LAN_STBY_LVC3_SCL")
	)
	(segment
		(start 433.328572 -110.755684)
		(end 435.216046 -112.643158)
		(width 0.10795)
		(layer "B.Cu")
		(net "SMB_OCP_LAN_STBY_LVC3_SCL")
	)
	(segment
		(start 487.55554 -120.6754)
		(end 487.9213 -121.04116)
		(width 0.10795)
		(layer "B.Cu")
		(net "SMB_OCP_LAN_STBY_LVC3_SCL")
	)
	(segment
		(start 426.4914 -76.7334)
		(end 426.068998 -77.155802)
		(width 0.10795)
		(layer "B.Cu")
		(net "SMB_OCP_LAN_STBY_LVC3_SCL")
	)
	(segment
		(start 487.9213 -121.04116)
		(end 490.09554 -121.04116)
		(width 0.10795)
		(layer "B.Cu")
		(net "SMB_OCP_LAN_STBY_LVC3_SCL")
	)
	(segment
		(start 472.366594 -121.92)
		(end 473.202 -121.92)
		(width 0.10795)
		(layer "B.Cu")
		(net "SMB_OCP_LAN_STBY_LVC3_SCL")
	)
	(segment
		(start 398.361408 -30.19425)
		(end 398.361408 -31.363158)
		(width 0.10795)
		(layer "B.Cu")
		(net "SMB_OCP_LAN_STBY_LVC3_SCL")
	)
	(segment
		(start 394.72997 -19.114008)
		(end 395.540992 -19.114008)
		(width 0.10795)
		(layer "B.Cu")
		(net "SMB_OCP_LAN_STBY_LVC3_SCL")
	)
	(segment
		(start 393.330938 -17.714976)
		(end 394.72997 -19.114008)
		(width 0.10795)
		(layer "B.Cu")
		(net "SMB_OCP_LAN_STBY_LVC3_SCL")
	)
	(segment
		(start 398.361408 -31.363158)
		(end 398.93494 -31.93669)
		(width 0.10795)
		(layer "B.Cu")
		(net "SMB_OCP_LAN_STBY_LVC3_SCL")
	)
	(segment
		(start 435.216046 -112.643158)
		(end 435.216046 -113.188242)
		(width 0.10795)
		(layer "B.Cu")
		(net "SMB_OCP_LAN_STBY_LVC3_SCL")
	)
	(segment
		(start 468.85225 -114.16665)
		(end 469.667336 -114.16665)
		(width 0.10795)
		(layer "B.Cu")
		(net "SMB_OCP_LAN_STBY_LVC3_SCL")
	)
	(segment
		(start 470.004648 -116.176044)
		(end 470.004648 -119.558054)
		(width 0.10795)
		(layer "B.Cu")
		(net "SMB_OCP_LAN_STBY_LVC3_SCL")
	)
	(segment
		(start 435.398926 -115.060222)
		(end 436.482744 -116.14404)
		(width 0.10795)
		(layer "B.Cu")
		(net "SMB_OCP_LAN_STBY_LVC3_SCL")
	)
	(segment
		(start 426.068998 -77.155802)
		(end 426.068998 -79.638398)
		(width 0.10795)
		(layer "B.Cu")
		(net "SMB_OCP_LAN_STBY_LVC3_SCL")
	)
	(segment
		(start 426.438314 -109.66577)
		(end 427.528228 -110.755684)
		(width 0.10795)
		(layer "B.Cu")
		(net "SMB_OCP_LAN_STBY_LVC3_SCL")
	)
	(segment
		(start 435.398926 -113.371122)
		(end 435.398926 -115.060222)
		(width 0.10795)
		(layer "B.Cu")
		(net "SMB_OCP_LAN_STBY_LVC3_SCL")
	)
	(segment
		(start 397.65351 -25.683464)
		(end 398.959832 -26.989786)
		(width 0.10795)
		(layer "B.Cu")
		(net "SMB_OCP_LAN_STBY_LVC3_SCL")
	)
	(segment
		(start 439.32475 -114.297714)
		(end 440.983116 -112.639348)
		(width 0.10795)
		(layer "B.Cu")
		(net "SMB_OCP_LAN_STBY_LVC3_SCL")
	)
	(segment
		(start 435.216046 -113.188242)
		(end 435.398926 -113.371122)
		(width 0.10795)
		(layer "B.Cu")
		(net "SMB_OCP_LAN_STBY_LVC3_SCL")
	)
	(segment
		(start 395.540992 -19.114008)
		(end 397.65351 -21.226526)
		(width 0.10795)
		(layer "B.Cu")
		(net "SMB_OCP_LAN_STBY_LVC3_SCL")
	)
	(segment
		(start 470.004648 -119.558054)
		(end 472.366594 -121.92)
		(width 0.10795)
		(layer "B.Cu")
		(net "SMB_OCP_LAN_STBY_LVC3_SCL")
	)
	(segment
		(start 398.93494 -33.35274)
		(end 399.055082 -33.472882)
		(width 0.10795)
		(layer "B.Cu")
		(net "SMB_OCP_LAN_STBY_LVC3_SCL")
	)
	(segment
		(start 438.451244 -116.14404)
		(end 439.32475 -115.270534)
		(width 0.10795)
		(layer "B.Cu")
		(net "SMB_OCP_LAN_STBY_LVC3_SCL")
	)
	(segment
		(start 399.055082 -34.67227)
		(end 398.267174 -35.460178)
		(width 0.10795)
		(layer "B.Cu")
		(net "SMB_OCP_LAN_STBY_LVC3_SCL")
	)
	(segment
		(start 398.959832 -26.989786)
		(end 398.959832 -29.595826)
		(width 0.10795)
		(layer "B.Cu")
		(net "SMB_OCP_LAN_STBY_LVC3_SCL")
	)
	(segment
		(start 439.32475 -115.270534)
		(end 439.32475 -114.297714)
		(width 0.10795)
		(layer "B.Cu")
		(net "SMB_OCP_LAN_STBY_LVC3_SCL")
	)
	(segment
		(start 436.482744 -116.14404)
		(end 438.451244 -116.14404)
		(width 0.10795)
		(layer "B.Cu")
		(net "SMB_OCP_LAN_STBY_LVC3_SCL")
	)
	(segment
		(start 398.93494 -31.93669)
		(end 398.93494 -33.35274)
		(width 0.10795)
		(layer "B.Cu")
		(net "SMB_OCP_LAN_STBY_LVC3_SCL")
	)
	(segment
		(start 398.959832 -29.595826)
		(end 398.361408 -30.19425)
		(width 0.10795)
		(layer "B.Cu")
		(net "SMB_OCP_LAN_STBY_LVC3_SCL")
	)
	(segment
		(start 469.667336 -114.16665)
		(end 470.306146 -114.80546)
		(width 0.10795)
		(layer "B.Cu")
		(net "SMB_OCP_LAN_STBY_LVC3_SCL")
	)
	(segment
		(start 467.324948 -112.639348)
		(end 468.85225 -114.16665)
		(width 0.10795)
		(layer "B.Cu")
		(net "SMB_OCP_LAN_STBY_LVC3_SCL")
	)
	(segment
		(start 399.055082 -33.472882)
		(end 399.055082 -34.67227)
		(width 0.10795)
		(layer "B.Cu")
		(net "SMB_OCP_LAN_STBY_LVC3_SCL")
	)
	(segment
		(start 490.09554 -121.04116)
		(end 490.3851 -120.7516)
		(width 0.10795)
		(layer "B.Cu")
		(net "SMB_OCP_LAN_STBY_LVC3_SCL")
	)
	(segment
		(start 440.983116 -112.639348)
		(end 467.324948 -112.639348)
		(width 0.10795)
		(layer "B.Cu")
		(net "SMB_OCP_LAN_STBY_LVC3_SCL")
	)
	(segment
		(start 397.65351 -21.226526)
		(end 397.65351 -25.683464)
		(width 0.10795)
		(layer "B.Cu")
		(net "SMB_OCP_LAN_STBY_LVC3_SCL")
	)
	(segment
		(start 393.330938 -16.691864)
		(end 393.330938 -17.714976)
		(width 0.10795)
		(layer "B.Cu")
		(net "SMB_OCP_LAN_STBY_LVC3_SCL")
	)
	(segment
		(start 470.306146 -115.874546)
		(end 470.004648 -116.176044)
		(width 0.10795)
		(layer "B.Cu")
		(net "SMB_OCP_LAN_STBY_LVC3_SCL")
	)
	(segment
		(start 417.0553 -20.8915)
		(end 420.428166 -20.8915)
		(width 0.089408)
		(layer "In9.Cu")
		(net "SMB_OCP_LAN_STBY_LVC3_SCL")
	)
	(segment
		(start 472.859608 -53.1876)
		(end 472.573096 -53.1876)
		(width 0.089408)
		(layer "In9.Cu")
		(net "SMB_OCP_LAN_STBY_LVC3_SCL")
	)
	(segment
		(start 398.00022 -35.193224)
		(end 397.790924 -35.193224)
		(width 0.089408)
		(layer "In9.Cu")
		(net "SMB_OCP_LAN_STBY_LVC3_SCL")
	)
	(segment
		(start 475.186248 -46.39691)
		(end 475.186248 -50.86096)
		(width 0.089408)
		(layer "In9.Cu")
		(net "SMB_OCP_LAN_STBY_LVC3_SCL")
	)
	(segment
		(start 440.581034 -22.085046)
		(end 441.536836 -23.040848)
		(width 0.089408)
		(layer "In9.Cu")
		(net "SMB_OCP_LAN_STBY_LVC3_SCL")
	)
	(segment
		(start 421.937942 -19.902424)
		(end 426.55617 -19.902424)
		(width 0.089408)
		(layer "In9.Cu")
		(net "SMB_OCP_LAN_STBY_LVC3_SCL")
	)
	(segment
		(start 400.301968 -23.435056)
		(end 401.141438 -23.435056)
		(width 0.089408)
		(layer "In9.Cu")
		(net "SMB_OCP_LAN_STBY_LVC3_SCL")
	)
	(segment
		(start 401.959572 -23.777702)
		(end 402.181568 -23.777702)
		(width 0.089408)
		(layer "In9.Cu")
		(net "SMB_OCP_LAN_STBY_LVC3_SCL")
	)
	(segment
		(start 397.859504 -30.699202)
		(end 397.859504 -24.263096)
		(width 0.089408)
		(layer "In9.Cu")
		(net "SMB_OCP_LAN_STBY_LVC3_SCL")
	)
	(segment
		(start 474.694758 -56.106568)
		(end 476.594424 -58.006234)
		(width 0.089408)
		(layer "In9.Cu")
		(net "SMB_OCP_LAN_STBY_LVC3_SCL")
	)
	(segment
		(start 472.519248 -35.46475)
		(end 473.575634 -36.521136)
		(width 0.089408)
		(layer "In9.Cu")
		(net "SMB_OCP_LAN_STBY_LVC3_SCL")
	)
	(segment
		(start 438.206642 -22.0853)
		(end 438.206896 -22.085046)
		(width 0.089408)
		(layer "In9.Cu")
		(net "SMB_OCP_LAN_STBY_LVC3_SCL")
	)
	(segment
		(start 397.790924 -35.193224)
		(end 397.558768 -34.961068)
		(width 0.089408)
		(layer "In9.Cu")
		(net "SMB_OCP_LAN_STBY_LVC3_SCL")
	)
	(segment
		(start 399.112486 -23.509986)
		(end 399.761202 -23.509986)
		(width 0.089408)
		(layer "In9.Cu")
		(net "SMB_OCP_LAN_STBY_LVC3_SCL")
	)
	(segment
		(start 444.986156 -23.040848)
		(end 447.6242 -25.678892)
		(width 0.089408)
		(layer "In9.Cu")
		(net "SMB_OCP_LAN_STBY_LVC3_SCL")
	)
	(segment
		(start 435.49189 -21.447252)
		(end 437.25211 -21.447252)
		(width 0.089408)
		(layer "In9.Cu")
		(net "SMB_OCP_LAN_STBY_LVC3_SCL")
	)
	(segment
		(start 401.484338 -23.777956)
		(end 401.642326 -23.777956)
		(width 0.089408)
		(layer "In9.Cu")
		(net "SMB_OCP_LAN_STBY_LVC3_SCL")
	)
	(segment
		(start 403.855936 -24.262588)
		(end 405.387302 -24.262588)
		(width 0.089408)
		(layer "In9.Cu")
		(net "SMB_OCP_LAN_STBY_LVC3_SCL")
	)
	(segment
		(start 413.898334 -20.8153)
		(end 414.345882 -20.367752)
		(width 0.089408)
		(layer "In9.Cu")
		(net "SMB_OCP_LAN_STBY_LVC3_SCL")
	)
	(segment
		(start 473.348812 -56.106568)
		(end 474.694758 -56.106568)
		(width 0.089408)
		(layer "In9.Cu")
		(net "SMB_OCP_LAN_STBY_LVC3_SCL")
	)
	(segment
		(start 476.594424 -62.3697)
		(end 471.992452 -66.971672)
		(width 0.089408)
		(layer "In9.Cu")
		(net "SMB_OCP_LAN_STBY_LVC3_SCL")
	)
	(segment
		(start 406.119838 -24.2316)
		(end 409.29433 -24.2316)
		(width 0.089408)
		(layer "In9.Cu")
		(net "SMB_OCP_LAN_STBY_LVC3_SCL")
	)
	(segment
		(start 433.581556 -20.565872)
		(end 434.61051 -20.565872)
		(width 0.089408)
		(layer "In9.Cu")
		(net "SMB_OCP_LAN_STBY_LVC3_SCL")
	)
	(segment
		(start 473.575634 -36.521136)
		(end 473.575634 -38.29685)
		(width 0.089408)
		(layer "In9.Cu")
		(net "SMB_OCP_LAN_STBY_LVC3_SCL")
	)
	(segment
		(start 397.558768 -33.626806)
		(end 398.46885 -32.716724)
		(width 0.089408)
		(layer "In9.Cu")
		(net "SMB_OCP_LAN_STBY_LVC3_SCL")
	)
	(segment
		(start 453.859392 -20.90547)
		(end 455.716132 -20.90547)
		(width 0.089408)
		(layer "In9.Cu")
		(net "SMB_OCP_LAN_STBY_LVC3_SCL")
	)
	(segment
		(start 398.46885 -32.716724)
		(end 398.46885 -31.308548)
		(width 0.089408)
		(layer "In9.Cu")
		(net "SMB_OCP_LAN_STBY_LVC3_SCL")
	)
	(segment
		(start 426.173138 -76.7334)
		(end 426.4914 -76.7334)
		(width 0.089408)
		(layer "In9.Cu")
		(net "SMB_OCP_LAN_STBY_LVC3_SCL")
	)
	(segment
		(start 398.46885 -31.308548)
		(end 397.859504 -30.699202)
		(width 0.089408)
		(layer "In9.Cu")
		(net "SMB_OCP_LAN_STBY_LVC3_SCL")
	)
	(segment
		(start 411.328616 -24.531066)
		(end 411.653228 -24.206454)
		(width 0.089408)
		(layer "In9.Cu")
		(net "SMB_OCP_LAN_STBY_LVC3_SCL")
	)
	(segment
		(start 433.423314 -20.565618)
		(end 433.581302 -20.565618)
		(width 0.089408)
		(layer "In9.Cu")
		(net "SMB_OCP_LAN_STBY_LVC3_SCL")
	)
	(segment
		(start 472.573096 -53.1876)
		(end 471.930984 -53.829712)
		(width 0.089408)
		(layer "In9.Cu")
		(net "SMB_OCP_LAN_STBY_LVC3_SCL")
	)
	(segment
		(start 414.345882 -20.367752)
		(end 414.50387 -20.367752)
		(width 0.089408)
		(layer "In9.Cu")
		(net "SMB_OCP_LAN_STBY_LVC3_SCL")
	)
	(segment
		(start 411.653228 -24.206454)
		(end 411.653228 -23.726902)
		(width 0.089408)
		(layer "In9.Cu")
		(net "SMB_OCP_LAN_STBY_LVC3_SCL")
	)
	(segment
		(start 437.25211 -21.447252)
		(end 437.890158 -22.0853)
		(width 0.089408)
		(layer "In9.Cu")
		(net "SMB_OCP_LAN_STBY_LVC3_SCL")
	)
	(segment
		(start 414.504124 -20.368006)
		(end 416.531806 -20.368006)
		(width 0.089408)
		(layer "In9.Cu")
		(net "SMB_OCP_LAN_STBY_LVC3_SCL")
	)
	(segment
		(start 471.930984 -53.829712)
		(end 471.930984 -54.68874)
		(width 0.089408)
		(layer "In9.Cu")
		(net "SMB_OCP_LAN_STBY_LVC3_SCL")
	)
	(segment
		(start 401.642326 -23.777956)
		(end 401.64258 -23.77821)
		(width 0.089408)
		(layer "In9.Cu")
		(net "SMB_OCP_LAN_STBY_LVC3_SCL")
	)
	(segment
		(start 401.64258 -23.77821)
		(end 401.959064 -23.77821)
		(width 0.089408)
		(layer "In9.Cu")
		(net "SMB_OCP_LAN_STBY_LVC3_SCL")
	)
	(segment
		(start 441.536836 -23.040848)
		(end 444.986156 -23.040848)
		(width 0.089408)
		(layer "In9.Cu")
		(net "SMB_OCP_LAN_STBY_LVC3_SCL")
	)
	(segment
		(start 471.930984 -54.68874)
		(end 473.348812 -56.106568)
		(width 0.089408)
		(layer "In9.Cu")
		(net "SMB_OCP_LAN_STBY_LVC3_SCL")
	)
	(segment
		(start 414.50387 -20.367752)
		(end 414.504124 -20.368006)
		(width 0.089408)
		(layer "In9.Cu")
		(net "SMB_OCP_LAN_STBY_LVC3_SCL")
	)
	(segment
		(start 402.84019 -24.436324)
		(end 403.6822 -24.436324)
		(width 0.089408)
		(layer "In9.Cu")
		(net "SMB_OCP_LAN_STBY_LVC3_SCL")
	)
	(segment
		(start 401.959064 -23.77821)
		(end 401.959572 -23.777702)
		(width 0.089408)
		(layer "In9.Cu")
		(net "SMB_OCP_LAN_STBY_LVC3_SCL")
	)
	(segment
		(start 449.08597 -25.678892)
		(end 453.859392 -20.90547)
		(width 0.089408)
		(layer "In9.Cu")
		(net "SMB_OCP_LAN_STBY_LVC3_SCL")
	)
	(segment
		(start 421.352472 -19.967194)
		(end 421.873172 -19.967194)
		(width 0.089408)
		(layer "In9.Cu")
		(net "SMB_OCP_LAN_STBY_LVC3_SCL")
	)
	(segment
		(start 416.531806 -20.368006)
		(end 417.0553 -20.8915)
		(width 0.089408)
		(layer "In9.Cu")
		(net "SMB_OCP_LAN_STBY_LVC3_SCL")
	)
	(segment
		(start 457.38669 -19.721068)
		(end 461.44815 -15.659608)
		(width 0.089408)
		(layer "In9.Cu")
		(net "SMB_OCP_LAN_STBY_LVC3_SCL")
	)
	(segment
		(start 413.50057 -21.87956)
		(end 413.50057 -21.879306)
		(width 0.089408)
		(layer "In9.Cu")
		(net "SMB_OCP_LAN_STBY_LVC3_SCL")
	)
	(segment
		(start 405.537416 -24.412702)
		(end 405.938736 -24.412702)
		(width 0.089408)
		(layer "In9.Cu")
		(net "SMB_OCP_LAN_STBY_LVC3_SCL")
	)
	(segment
		(start 434.61051 -20.565872)
		(end 435.49189 -21.447252)
		(width 0.089408)
		(layer "In9.Cu")
		(net "SMB_OCP_LAN_STBY_LVC3_SCL")
	)
	(segment
		(start 433.581302 -20.565618)
		(end 433.581556 -20.565872)
		(width 0.089408)
		(layer "In9.Cu")
		(net "SMB_OCP_LAN_STBY_LVC3_SCL")
	)
	(segment
		(start 399.763488 -23.512272)
		(end 400.224752 -23.512272)
		(width 0.089408)
		(layer "In9.Cu")
		(net "SMB_OCP_LAN_STBY_LVC3_SCL")
	)
	(segment
		(start 397.859504 -24.263096)
		(end 398.610328 -23.512272)
		(width 0.089408)
		(layer "In9.Cu")
		(net "SMB_OCP_LAN_STBY_LVC3_SCL")
	)
	(segment
		(start 437.890158 -22.0853)
		(end 438.206642 -22.0853)
		(width 0.089408)
		(layer "In9.Cu")
		(net "SMB_OCP_LAN_STBY_LVC3_SCL")
	)
	(segment
		(start 397.558768 -34.961068)
		(end 397.558768 -33.626806)
		(width 0.089408)
		(layer "In9.Cu")
		(net "SMB_OCP_LAN_STBY_LVC3_SCL")
	)
	(segment
		(start 461.44815 -14.189202)
		(end 461.171798 -13.91285)
		(width 0.089408)
		(layer "In9.Cu")
		(net "SMB_OCP_LAN_STBY_LVC3_SCL")
	)
	(segment
		(start 399.761202 -23.509986)
		(end 399.763488 -23.512272)
		(width 0.089408)
		(layer "In9.Cu")
		(net "SMB_OCP_LAN_STBY_LVC3_SCL")
	)
	(segment
		(start 471.992452 -66.971672)
		(end 427.189646 -66.971672)
		(width 0.089408)
		(layer "In9.Cu")
		(net "SMB_OCP_LAN_STBY_LVC3_SCL")
	)
	(segment
		(start 402.181568 -23.777702)
		(end 402.84019 -24.436324)
		(width 0.089408)
		(layer "In9.Cu")
		(net "SMB_OCP_LAN_STBY_LVC3_SCL")
	)
	(segment
		(start 425.337224 -75.897486)
		(end 426.173138 -76.7334)
		(width 0.089408)
		(layer "In9.Cu")
		(net "SMB_OCP_LAN_STBY_LVC3_SCL")
	)
	(segment
		(start 447.6242 -25.678892)
		(end 449.08597 -25.678892)
		(width 0.089408)
		(layer "In9.Cu")
		(net "SMB_OCP_LAN_STBY_LVC3_SCL")
	)
	(segment
		(start 411.653228 -23.726902)
		(end 413.50057 -21.87956)
		(width 0.089408)
		(layer "In9.Cu")
		(net "SMB_OCP_LAN_STBY_LVC3_SCL")
	)
	(segment
		(start 473.575634 -38.29685)
		(end 472.580208 -39.292276)
		(width 0.089408)
		(layer "In9.Cu")
		(net "SMB_OCP_LAN_STBY_LVC3_SCL")
	)
	(segment
		(start 455.716132 -20.90547)
		(end 456.900534 -19.721068)
		(width 0.089408)
		(layer "In9.Cu")
		(net "SMB_OCP_LAN_STBY_LVC3_SCL")
	)
	(segment
		(start 476.594424 -58.006234)
		(end 476.594424 -62.3697)
		(width 0.089408)
		(layer "In9.Cu")
		(net "SMB_OCP_LAN_STBY_LVC3_SCL")
	)
	(segment
		(start 427.787562 -21.133816)
		(end 432.855116 -21.133816)
		(width 0.089408)
		(layer "In9.Cu")
		(net "SMB_OCP_LAN_STBY_LVC3_SCL")
	)
	(segment
		(start 432.855116 -21.133816)
		(end 433.423314 -20.565618)
		(width 0.089408)
		(layer "In9.Cu")
		(net "SMB_OCP_LAN_STBY_LVC3_SCL")
	)
	(segment
		(start 472.519248 -34.804604)
		(end 472.519248 -35.46475)
		(width 0.089408)
		(layer "In9.Cu")
		(net "SMB_OCP_LAN_STBY_LVC3_SCL")
	)
	(segment
		(start 409.29433 -24.2316)
		(end 409.593796 -24.531066)
		(width 0.089408)
		(layer "In9.Cu")
		(net "SMB_OCP_LAN_STBY_LVC3_SCL")
	)
	(segment
		(start 472.686126 -34.637726)
		(end 472.519248 -34.804604)
		(width 0.089408)
		(layer "In9.Cu")
		(net "SMB_OCP_LAN_STBY_LVC3_SCL")
	)
	(segment
		(start 413.898334 -21.481542)
		(end 413.898334 -20.8153)
		(width 0.089408)
		(layer "In9.Cu")
		(net "SMB_OCP_LAN_STBY_LVC3_SCL")
	)
	(segment
		(start 398.267174 -35.460178)
		(end 398.00022 -35.193224)
		(width 0.089408)
		(layer "In9.Cu")
		(net "SMB_OCP_LAN_STBY_LVC3_SCL")
	)
	(segment
		(start 461.44815 -15.659608)
		(end 461.44815 -14.189202)
		(width 0.089408)
		(layer "In9.Cu")
		(net "SMB_OCP_LAN_STBY_LVC3_SCL")
	)
	(segment
		(start 472.580208 -43.79087)
		(end 475.186248 -46.39691)
		(width 0.089408)
		(layer "In9.Cu")
		(net "SMB_OCP_LAN_STBY_LVC3_SCL")
	)
	(segment
		(start 413.50057 -21.879306)
		(end 413.898334 -21.481542)
		(width 0.089408)
		(layer "In9.Cu")
		(net "SMB_OCP_LAN_STBY_LVC3_SCL")
	)
	(segment
		(start 472.580208 -39.292276)
		(end 472.580208 -43.79087)
		(width 0.089408)
		(layer "In9.Cu")
		(net "SMB_OCP_LAN_STBY_LVC3_SCL")
	)
	(segment
		(start 405.387302 -24.262588)
		(end 405.537416 -24.412702)
		(width 0.089408)
		(layer "In9.Cu")
		(net "SMB_OCP_LAN_STBY_LVC3_SCL")
	)
	(segment
		(start 427.189646 -66.971672)
		(end 425.337224 -68.824094)
		(width 0.089408)
		(layer "In9.Cu")
		(net "SMB_OCP_LAN_STBY_LVC3_SCL")
	)
	(segment
		(start 401.141438 -23.435056)
		(end 401.484338 -23.777956)
		(width 0.089408)
		(layer "In9.Cu")
		(net "SMB_OCP_LAN_STBY_LVC3_SCL")
	)
	(segment
		(start 426.55617 -19.902424)
		(end 427.787562 -21.133816)
		(width 0.089408)
		(layer "In9.Cu")
		(net "SMB_OCP_LAN_STBY_LVC3_SCL")
	)
	(segment
		(start 403.6822 -24.436324)
		(end 403.855936 -24.262588)
		(width 0.089408)
		(layer "In9.Cu")
		(net "SMB_OCP_LAN_STBY_LVC3_SCL")
	)
	(segment
		(start 421.873172 -19.967194)
		(end 421.937942 -19.902424)
		(width 0.089408)
		(layer "In9.Cu")
		(net "SMB_OCP_LAN_STBY_LVC3_SCL")
	)
	(segment
		(start 456.900534 -19.721068)
		(end 457.38669 -19.721068)
		(width 0.089408)
		(layer "In9.Cu")
		(net "SMB_OCP_LAN_STBY_LVC3_SCL")
	)
	(segment
		(start 400.224752 -23.512272)
		(end 400.301968 -23.435056)
		(width 0.089408)
		(layer "In9.Cu")
		(net "SMB_OCP_LAN_STBY_LVC3_SCL")
	)
	(segment
		(start 398.610328 -23.512272)
		(end 399.1102 -23.512272)
		(width 0.089408)
		(layer "In9.Cu")
		(net "SMB_OCP_LAN_STBY_LVC3_SCL")
	)
	(segment
		(start 405.938736 -24.412702)
		(end 406.119838 -24.2316)
		(width 0.089408)
		(layer "In9.Cu")
		(net "SMB_OCP_LAN_STBY_LVC3_SCL")
	)
	(segment
		(start 425.337224 -68.824094)
		(end 425.337224 -75.897486)
		(width 0.089408)
		(layer "In9.Cu")
		(net "SMB_OCP_LAN_STBY_LVC3_SCL")
	)
	(segment
		(start 475.186248 -50.86096)
		(end 472.859608 -53.1876)
		(width 0.089408)
		(layer "In9.Cu")
		(net "SMB_OCP_LAN_STBY_LVC3_SCL")
	)
	(segment
		(start 438.206896 -22.085046)
		(end 440.581034 -22.085046)
		(width 0.089408)
		(layer "In9.Cu")
		(net "SMB_OCP_LAN_STBY_LVC3_SCL")
	)
	(segment
		(start 399.1102 -23.512272)
		(end 399.112486 -23.509986)
		(width 0.089408)
		(layer "In9.Cu")
		(net "SMB_OCP_LAN_STBY_LVC3_SCL")
	)
	(segment
		(start 409.593796 -24.531066)
		(end 411.328616 -24.531066)
		(width 0.089408)
		(layer "In9.Cu")
		(net "SMB_OCP_LAN_STBY_LVC3_SCL")
	)
	(segment
		(start 420.428166 -20.8915)
		(end 421.352472 -19.967194)
		(width 0.089408)
		(layer "In9.Cu")
		(net "SMB_OCP_LAN_STBY_LVC3_SCL")
	)
	(segment
		(start 472.102434 -31.361634)
		(end 472.102434 -34.054034)
		(width 0.089408)
		(layer "In11.Cu")
		(net "SMB_OCP_LAN_STBY_LVC3_SCL")
	)
	(segment
		(start 461.391 -14.132052)
		(end 461.391 -20.6502)
		(width 0.089408)
		(layer "In11.Cu")
		(net "SMB_OCP_LAN_STBY_LVC3_SCL")
	)
	(segment
		(start 461.171798 -13.91285)
		(end 461.391 -14.132052)
		(width 0.089408)
		(layer "In11.Cu")
		(net "SMB_OCP_LAN_STBY_LVC3_SCL")
	)
	(segment
		(start 461.391 -20.6502)
		(end 472.102434 -31.361634)
		(width 0.089408)
		(layer "In11.Cu")
		(net "SMB_OCP_LAN_STBY_LVC3_SCL")
	)
	(segment
		(start 472.102434 -34.054034)
		(end 472.686126 -34.637726)
		(width 0.089408)
		(layer "In11.Cu")
		(net "SMB_OCP_LAN_STBY_LVC3_SCL")
	)
	(segment
		(start 327.547986 -147.7645)
		(end 326.37984 -147.7645)
		(width 0.10795)
		(layer "F.Cu")
		(net "SMB_LAN_STBY_LVC3_SDA")
	)
	(segment
		(start 394.589 -86.9696)
		(end 394.589 -87.3125)
		(width 0.10795)
		(layer "F.Cu")
		(net "SMB_LAN_STBY_LVC3_SDA")
	)
	(segment
		(start 332.012798 -156.905198)
		(end 331.664818 -156.557218)
		(width 0.10795)
		(layer "F.Cu")
		(net "SMB_LAN_STBY_LVC3_SDA")
	)
	(segment
		(start 14.472158 -105.33253)
		(end 13.520674 -105.33253)
		(width 0.10795)
		(layer "F.Cu")
		(net "SMB_LAN_STBY_LVC3_SDA")
	)
	(segment
		(start 333.060548 -156.905198)
		(end 332.012798 -156.905198)
		(width 0.10795)
		(layer "F.Cu")
		(net "SMB_LAN_STBY_LVC3_SDA")
	)
	(segment
		(start 333.2861 -157.283658)
		(end 333.2861 -157.13075)
		(width 0.10795)
		(layer "F.Cu")
		(net "SMB_LAN_STBY_LVC3_SDA")
	)
	(segment
		(start 328.9808 -155.472892)
		(end 328.9808 -155.437078)
		(width 0.10795)
		(layer "F.Cu")
		(net "SMB_LAN_STBY_LVC3_SDA")
	)
	(segment
		(start 328.972418 -148.936964)
		(end 328.344022 -148.308568)
		(width 0.10795)
		(layer "F.Cu")
		(net "SMB_LAN_STBY_LVC3_SDA")
	)
	(segment
		(start 13.520674 -105.33253)
		(end 13.11783 -105.735374)
		(width 0.10795)
		(layer "F.Cu")
		(net "SMB_LAN_STBY_LVC3_SDA")
	)
	(segment
		(start 326.37984 -147.7645)
		(end 326.17918 -147.96516)
		(width 0.10795)
		(layer "F.Cu")
		(net "SMB_LAN_STBY_LVC3_SDA")
	)
	(segment
		(start 15.03934 -104.765348)
		(end 14.472158 -105.33253)
		(width 0.10795)
		(layer "F.Cu")
		(net "SMB_LAN_STBY_LVC3_SDA")
	)
	(segment
		(start 333.2861 -157.13075)
		(end 333.060548 -156.905198)
		(width 0.10795)
		(layer "F.Cu")
		(net "SMB_LAN_STBY_LVC3_SDA")
	)
	(segment
		(start 328.9808 -155.437078)
		(end 328.972418 -155.428696)
		(width 0.10795)
		(layer "F.Cu")
		(net "SMB_LAN_STBY_LVC3_SDA")
	)
	(segment
		(start 326.17918 -147.96516)
		(end 326.04964 -147.96516)
		(width 0.10795)
		(layer "F.Cu")
		(net "SMB_LAN_STBY_LVC3_SDA")
	)
	(segment
		(start 330.065126 -156.557218)
		(end 328.9808 -155.472892)
		(width 0.10795)
		(layer "F.Cu")
		(net "SMB_LAN_STBY_LVC3_SDA")
	)
	(segment
		(start 333.216504 -157.353254)
		(end 333.2861 -157.283658)
		(width 0.10795)
		(layer "F.Cu")
		(net "SMB_LAN_STBY_LVC3_SDA")
	)
	(segment
		(start 328.344022 -148.308568)
		(end 327.547986 -147.7645)
		(width 0.10795)
		(layer "F.Cu")
		(net "SMB_LAN_STBY_LVC3_SDA")
	)
	(segment
		(start 178.308 -145.1356)
		(end 178.444652 -144.998948)
		(width 0.10795)
		(layer "F.Cu")
		(net "SMB_LAN_STBY_LVC3_SDA")
	)
	(segment
		(start 394.589 -85.9155)
		(end 394.589 -86.3092)
		(width 0.10795)
		(layer "F.Cu")
		(net "SMB_LAN_STBY_LVC3_SDA")
	)
	(segment
		(start 14.224 -101.981)
		(end 14.224 -102.5652)
		(width 0.10795)
		(layer "F.Cu")
		(net "SMB_LAN_STBY_LVC3_SDA")
	)
	(segment
		(start 328.972418 -155.428696)
		(end 328.972418 -148.936964)
		(width 0.10795)
		(layer "F.Cu")
		(net "SMB_LAN_STBY_LVC3_SDA")
	)
	(segment
		(start 394.589 -86.3092)
		(end 394.9192 -86.6394)
		(width 0.10795)
		(layer "F.Cu")
		(net "SMB_LAN_STBY_LVC3_SDA")
	)
	(segment
		(start 331.664818 -156.557218)
		(end 330.065126 -156.557218)
		(width 0.10795)
		(layer "F.Cu")
		(net "SMB_LAN_STBY_LVC3_SDA")
	)
	(segment
		(start 15.03934 -103.38054)
		(end 15.03934 -104.765348)
		(width 0.10795)
		(layer "F.Cu")
		(net "SMB_LAN_STBY_LVC3_SDA")
	)
	(segment
		(start 14.224 -102.5652)
		(end 15.03934 -103.38054)
		(width 0.10795)
		(layer "F.Cu")
		(net "SMB_LAN_STBY_LVC3_SDA")
	)
	(segment
		(start 178.444652 -144.998948)
		(end 178.981862 -144.998948)
		(width 0.10795)
		(layer "F.Cu")
		(net "SMB_LAN_STBY_LVC3_SDA")
	)
	(segment
		(start 326.04964 -147.96516)
		(end 325.7804 -148.2344)
		(width 0.10795)
		(layer "F.Cu")
		(net "SMB_LAN_STBY_LVC3_SDA")
	)
	(segment
		(start 394.9192 -86.6394)
		(end 394.589 -86.9696)
		(width 0.10795)
		(layer "F.Cu")
		(net "SMB_LAN_STBY_LVC3_SDA")
	)
	(via
		(at 178.308 -145.1356)
		(size 0.508)
		(drill 0.254)
		(layers "F.Cu" "B.Cu")
		(net "SMB_LAN_STBY_LVC3_SDA")
	)
	(via
		(at 394.9192 -86.6394)
		(size 0.508)
		(drill 0.254)
		(layers "F.Cu" "B.Cu")
		(net "SMB_LAN_STBY_LVC3_SDA")
	)
	(via
		(at 22.56917 -132.679186)
		(size 0.508)
		(drill 0.254)
		(layers "F.Cu" "B.Cu")
		(net "SMB_LAN_STBY_LVC3_SDA")
	)
	(via
		(at 13.11783 -105.735374)
		(size 0.508)
		(drill 0.254)
		(layers "F.Cu" "B.Cu")
		(net "SMB_LAN_STBY_LVC3_SDA")
	)
	(via
		(at 417.685982 -47.09541)
		(size 0.508)
		(drill 0.254)
		(layers "F.Cu" "B.Cu")
		(net "SMB_LAN_STBY_LVC3_SDA")
	)
	(via
		(at 333.216504 -157.353254)
		(size 0.508)
		(drill 0.254)
		(layers "F.Cu" "B.Cu")
		(net "SMB_LAN_STBY_LVC3_SDA")
	)
	(via
		(at 417.4998 -89.323418)
		(size 0.508)
		(drill 0.254)
		(layers "F.Cu" "B.Cu")
		(net "SMB_LAN_STBY_LVC3_SDA")
	)
	(via
		(at 325.7804 -148.2344)
		(size 0.508)
		(drill 0.254)
		(layers "F.Cu" "B.Cu")
		(net "SMB_LAN_STBY_LVC3_SDA")
	)
	(via
		(at 425.714414 -116.556536)
		(size 0.508)
		(drill 0.254)
		(layers "F.Cu" "B.Cu")
		(net "SMB_LAN_STBY_LVC3_SDA")
	)
	(segment
		(start 394.589 -85.9155)
		(end 394.589 -86.3092)
		(width 0.10795)
		(layer "B.Cu")
		(net "SMB_LAN_STBY_LVC3_SDA")
	)
	(segment
		(start 21.058378 -134.189978)
		(end 22.56917 -132.679186)
		(width 0.10795)
		(layer "B.Cu")
		(net "SMB_LAN_STBY_LVC3_SDA")
	)
	(segment
		(start 394.9192 -86.6394)
		(end 394.589 -86.9696)
		(width 0.10795)
		(layer "B.Cu")
		(net "SMB_LAN_STBY_LVC3_SDA")
	)
	(segment
		(start 394.589 -86.3092)
		(end 394.9192 -86.6394)
		(width 0.10795)
		(layer "B.Cu")
		(net "SMB_LAN_STBY_LVC3_SDA")
	)
	(segment
		(start 416.470846 -45.707046)
		(end 417.685982 -46.922182)
		(width 0.10795)
		(layer "B.Cu")
		(net "SMB_LAN_STBY_LVC3_SDA")
	)
	(segment
		(start 20.153884 -134.189978)
		(end 21.058378 -134.189978)
		(width 0.10795)
		(layer "B.Cu")
		(net "SMB_LAN_STBY_LVC3_SDA")
	)
	(segment
		(start 416.470846 -45.539152)
		(end 416.470846 -45.707046)
		(width 0.10795)
		(layer "B.Cu")
		(net "SMB_LAN_STBY_LVC3_SDA")
	)
	(segment
		(start 394.589 -86.9696)
		(end 394.589 -87.3125)
		(width 0.10795)
		(layer "B.Cu")
		(net "SMB_LAN_STBY_LVC3_SDA")
	)
	(segment
		(start 417.685982 -46.922182)
		(end 417.685982 -47.09541)
		(width 0.10795)
		(layer "B.Cu")
		(net "SMB_LAN_STBY_LVC3_SDA")
	)
	(segment
		(start 418.783262 -116.777262)
		(end 417.416234 -115.410234)
		(width 0.089408)
		(layer "In2.Cu")
		(net "SMB_LAN_STBY_LVC3_SDA")
	)
	(segment
		(start 425.099734 -115.946682)
		(end 423.074338 -115.946682)
		(width 0.089408)
		(layer "In2.Cu")
		(net "SMB_LAN_STBY_LVC3_SDA")
	)
	(segment
		(start 418.911532 -116.777516)
		(end 418.911278 -116.777262)
		(width 0.089408)
		(layer "In2.Cu")
		(net "SMB_LAN_STBY_LVC3_SDA")
	)
	(segment
		(start 417.66363 -103.404162)
		(end 417.108132 -102.848664)
		(width 0.089408)
		(layer "In2.Cu")
		(net "SMB_LAN_STBY_LVC3_SDA")
	)
	(segment
		(start 419.228016 -116.777516)
		(end 418.911532 -116.777516)
		(width 0.089408)
		(layer "In2.Cu")
		(net "SMB_LAN_STBY_LVC3_SDA")
	)
	(segment
		(start 417.303458 -91.334082)
		(end 418.135562 -90.501978)
		(width 0.089408)
		(layer "In2.Cu")
		(net "SMB_LAN_STBY_LVC3_SDA")
	)
	(segment
		(start 417.108132 -95.017336)
		(end 417.681918 -94.44355)
		(width 0.089408)
		(layer "In2.Cu")
		(net "SMB_LAN_STBY_LVC3_SDA")
	)
	(segment
		(start 423.074338 -115.946682)
		(end 422.243758 -116.777262)
		(width 0.089408)
		(layer "In2.Cu")
		(net "SMB_LAN_STBY_LVC3_SDA")
	)
	(segment
		(start 417.939474 -88.993218)
		(end 417.752276 -88.993218)
		(width 0.089408)
		(layer "In2.Cu")
		(net "SMB_LAN_STBY_LVC3_SDA")
	)
	(segment
		(start 418.135562 -90.501978)
		(end 418.135562 -89.189306)
		(width 0.089408)
		(layer "In2.Cu")
		(net "SMB_LAN_STBY_LVC3_SDA")
	)
	(segment
		(start 422.243758 -116.777262)
		(end 419.22827 -116.777262)
		(width 0.089408)
		(layer "In2.Cu")
		(net "SMB_LAN_STBY_LVC3_SDA")
	)
	(segment
		(start 425.478702 -116.32565)
		(end 425.099734 -115.946682)
		(width 0.089408)
		(layer "In2.Cu")
		(net "SMB_LAN_STBY_LVC3_SDA")
	)
	(segment
		(start 417.681918 -93.450156)
		(end 417.303458 -93.071696)
		(width 0.089408)
		(layer "In2.Cu")
		(net "SMB_LAN_STBY_LVC3_SDA")
	)
	(segment
		(start 417.752276 -88.993218)
		(end 417.4998 -89.245694)
		(width 0.089408)
		(layer "In2.Cu")
		(net "SMB_LAN_STBY_LVC3_SDA")
	)
	(segment
		(start 417.4998 -89.245694)
		(end 417.4998 -89.323418)
		(width 0.089408)
		(layer "In2.Cu")
		(net "SMB_LAN_STBY_LVC3_SDA")
	)
	(segment
		(start 418.135562 -89.189306)
		(end 417.939474 -88.993218)
		(width 0.089408)
		(layer "In2.Cu")
		(net "SMB_LAN_STBY_LVC3_SDA")
	)
	(segment
		(start 417.66363 -103.56215)
		(end 417.66363 -103.404162)
		(width 0.089408)
		(layer "In2.Cu")
		(net "SMB_LAN_STBY_LVC3_SDA")
	)
	(segment
		(start 418.911278 -116.777262)
		(end 418.783262 -116.777262)
		(width 0.089408)
		(layer "In2.Cu")
		(net "SMB_LAN_STBY_LVC3_SDA")
	)
	(segment
		(start 419.22827 -116.777262)
		(end 419.228016 -116.777516)
		(width 0.089408)
		(layer "In2.Cu")
		(net "SMB_LAN_STBY_LVC3_SDA")
	)
	(segment
		(start 417.663376 -103.562404)
		(end 417.66363 -103.56215)
		(width 0.089408)
		(layer "In2.Cu")
		(net "SMB_LAN_STBY_LVC3_SDA")
	)
	(segment
		(start 417.663376 -106.781092)
		(end 417.663376 -103.562404)
		(width 0.089408)
		(layer "In2.Cu")
		(net "SMB_LAN_STBY_LVC3_SDA")
	)
	(segment
		(start 425.714414 -116.556536)
		(end 425.483528 -116.32565)
		(width 0.089408)
		(layer "In2.Cu")
		(net "SMB_LAN_STBY_LVC3_SDA")
	)
	(segment
		(start 417.303458 -93.071696)
		(end 417.303458 -91.334082)
		(width 0.089408)
		(layer "In2.Cu")
		(net "SMB_LAN_STBY_LVC3_SDA")
	)
	(segment
		(start 417.681918 -94.44355)
		(end 417.681918 -93.450156)
		(width 0.089408)
		(layer "In2.Cu")
		(net "SMB_LAN_STBY_LVC3_SDA")
	)
	(segment
		(start 417.108132 -102.848664)
		(end 417.108132 -95.017336)
		(width 0.089408)
		(layer "In2.Cu")
		(net "SMB_LAN_STBY_LVC3_SDA")
	)
	(segment
		(start 417.416234 -107.028234)
		(end 417.663376 -106.781092)
		(width 0.089408)
		(layer "In2.Cu")
		(net "SMB_LAN_STBY_LVC3_SDA")
	)
	(segment
		(start 425.483528 -116.32565)
		(end 425.478702 -116.32565)
		(width 0.089408)
		(layer "In2.Cu")
		(net "SMB_LAN_STBY_LVC3_SDA")
	)
	(segment
		(start 417.416234 -115.410234)
		(end 417.416234 -107.028234)
		(width 0.089408)
		(layer "In2.Cu")
		(net "SMB_LAN_STBY_LVC3_SDA")
	)
	(segment
		(start 410.070554 -89.247726)
		(end 411.09392 -90.263726)
		(width 0.089408)
		(layer "In4.Cu")
		(net "SMB_LAN_STBY_LVC3_SDA")
	)
	(segment
		(start 394.9192 -86.6394)
		(end 395.915134 -87.635334)
		(width 0.089408)
		(layer "In4.Cu")
		(net "SMB_LAN_STBY_LVC3_SDA")
	)
	(segment
		(start 417.039298 -88.862916)
		(end 417.4998 -89.323418)
		(width 0.089408)
		(layer "In4.Cu")
		(net "SMB_LAN_STBY_LVC3_SDA")
	)
	(segment
		(start 406.216612 -89.247726)
		(end 410.070554 -89.247726)
		(width 0.089408)
		(layer "In4.Cu")
		(net "SMB_LAN_STBY_LVC3_SDA")
	)
	(segment
		(start 412.79953 -89.26068)
		(end 415.76879 -89.26068)
		(width 0.089408)
		(layer "In4.Cu")
		(net "SMB_LAN_STBY_LVC3_SDA")
	)
	(segment
		(start 402.107146 -88.055704)
		(end 402.484844 -87.678006)
		(width 0.089408)
		(layer "In4.Cu")
		(net "SMB_LAN_STBY_LVC3_SDA")
	)
	(segment
		(start 404.646892 -87.678006)
		(end 406.216612 -89.247726)
		(width 0.089408)
		(layer "In4.Cu")
		(net "SMB_LAN_STBY_LVC3_SDA")
	)
	(segment
		(start 416.166554 -88.862916)
		(end 417.039298 -88.862916)
		(width 0.089408)
		(layer "In4.Cu")
		(net "SMB_LAN_STBY_LVC3_SDA")
	)
	(segment
		(start 399.703036 -88.055704)
		(end 402.107146 -88.055704)
		(width 0.089408)
		(layer "In4.Cu")
		(net "SMB_LAN_STBY_LVC3_SDA")
	)
	(segment
		(start 411.796484 -90.263726)
		(end 412.79953 -89.26068)
		(width 0.089408)
		(layer "In4.Cu")
		(net "SMB_LAN_STBY_LVC3_SDA")
	)
	(segment
		(start 402.484844 -87.678006)
		(end 404.646892 -87.678006)
		(width 0.089408)
		(layer "In4.Cu")
		(net "SMB_LAN_STBY_LVC3_SDA")
	)
	(segment
		(start 411.09392 -90.263726)
		(end 411.796484 -90.263726)
		(width 0.089408)
		(layer "In4.Cu")
		(net "SMB_LAN_STBY_LVC3_SDA")
	)
	(segment
		(start 415.76879 -89.26068)
		(end 416.166554 -88.862916)
		(width 0.089408)
		(layer "In4.Cu")
		(net "SMB_LAN_STBY_LVC3_SDA")
	)
	(segment
		(start 399.282666 -87.635334)
		(end 399.703036 -88.055704)
		(width 0.089408)
		(layer "In4.Cu")
		(net "SMB_LAN_STBY_LVC3_SDA")
	)
	(segment
		(start 395.915134 -87.635334)
		(end 399.282666 -87.635334)
		(width 0.089408)
		(layer "In4.Cu")
		(net "SMB_LAN_STBY_LVC3_SDA")
	)
	(segment
		(start 157.865064 -147.562062)
		(end 157.664912 -147.562062)
		(width 0.089408)
		(layer "In9.Cu")
		(net "SMB_LAN_STBY_LVC3_SDA")
	)
	(segment
		(start 449.06692 -151.274272)
		(end 449.069206 -151.274272)
		(width 0.089408)
		(layer "In9.Cu")
		(net "SMB_LAN_STBY_LVC3_SDA")
	)
	(segment
		(start 446.69456 -155.73629)
		(end 446.222882 -155.73629)
		(width 0.089408)
		(layer "In9.Cu")
		(net "SMB_LAN_STBY_LVC3_SDA")
	)
	(segment
		(start 397.337788 -81.912968)
		(end 397.337788 -84.221828)
		(width 0.089408)
		(layer "In9.Cu")
		(net "SMB_LAN_STBY_LVC3_SDA")
	)
	(segment
		(start 20.644104 -116.576602)
		(end 20.644104 -126.65837)
		(width 0.089408)
		(layer "In9.Cu")
		(net "SMB_LAN_STBY_LVC3_SDA")
	)
	(segment
		(start 411.736794 -48.070262)
		(end 410.323538 -49.483518)
		(width 0.089408)
		(layer "In9.Cu")
		(net "SMB_LAN_STBY_LVC3_SDA")
	)
	(segment
		(start 9.8298 -102.145084)
		(end 13.11783 -105.433114)
		(width 0.089408)
		(layer "In9.Cu")
		(net "SMB_LAN_STBY_LVC3_SDA")
	)
	(segment
		(start 94.677992 -146.0754)
		(end 93.445584 -147.307808)
		(width 0.089408)
		(layer "In9.Cu")
		(net "SMB_LAN_STBY_LVC3_SDA")
	)
	(segment
		(start 449.07327 -140.291312)
		(end 448.31 -141.054582)
		(width 0.089408)
		(layer "In9.Cu")
		(net "SMB_LAN_STBY_LVC3_SDA")
	)
	(segment
		(start 164.857938 -145.2372)
		(end 162.939476 -147.155662)
		(width 0.089408)
		(layer "In9.Cu")
		(net "SMB_LAN_STBY_LVC3_SDA")
	)
	(segment
		(start 28.042616 -146.545554)
		(end 28.042616 -136.035288)
		(width 0.089408)
		(layer "In9.Cu")
		(net "SMB_LAN_STBY_LVC3_SDA")
	)
	(segment
		(start 447.2432 -146.76628)
		(end 449.06692 -148.59)
		(width 0.089408)
		(layer "In9.Cu")
		(net "SMB_LAN_STBY_LVC3_SDA")
	)
	(segment
		(start 392.91895 -158.439866)
		(end 392.729466 -158.439866)
		(width 0.089408)
		(layer "In9.Cu")
		(net "SMB_LAN_STBY_LVC3_SDA")
	)
	(segment
		(start 262.45058 -148.06422)
		(end 262.027162 -148.487638)
		(width 0.089408)
		(layer "In9.Cu")
		(net "SMB_LAN_STBY_LVC3_SDA")
	)
	(segment
		(start 364.363 -153.416)
		(end 364.363 -153.00706)
		(width 0.089408)
		(layer "In9.Cu")
		(net "SMB_LAN_STBY_LVC3_SDA")
	)
	(segment
		(start 21.129752 -127.144018)
		(end 21.129752 -128.86309)
		(width 0.089408)
		(layer "In9.Cu")
		(net "SMB_LAN_STBY_LVC3_SDA")
	)
	(segment
		(start 428.028862 -125.217682)
		(end 433.801774 -125.217682)
		(width 0.089408)
		(layer "In9.Cu")
		(net "SMB_LAN_STBY_LVC3_SDA")
	)
	(segment
		(start 392.729466 -158.439866)
		(end 392.571224 -158.598108)
		(width 0.089408)
		(layer "In9.Cu")
		(net "SMB_LAN_STBY_LVC3_SDA")
	)
	(segment
		(start 19.622008 -114.528092)
		(end 19.622008 -115.554506)
		(width 0.089408)
		(layer "In9.Cu")
		(net "SMB_LAN_STBY_LVC3_SDA")
	)
	(segment
		(start 162.739324 -147.155662)
		(end 162.73907 -147.155408)
		(width 0.089408)
		(layer "In9.Cu")
		(net "SMB_LAN_STBY_LVC3_SDA")
	)
	(segment
		(start 20.644104 -126.65837)
		(end 21.129752 -127.144018)
		(width 0.089408)
		(layer "In9.Cu")
		(net "SMB_LAN_STBY_LVC3_SDA")
	)
	(segment
		(start 184.97931 -146.0754)
		(end 180.404262 -146.0754)
		(width 0.089408)
		(layer "In9.Cu")
		(net "SMB_LAN_STBY_LVC3_SDA")
	)
	(segment
		(start 322.69049 -149.5044)
		(end 321.25031 -148.06422)
		(width 0.089408)
		(layer "In9.Cu")
		(net "SMB_LAN_STBY_LVC3_SDA")
	)
	(segment
		(start 8.792972 -97.9424)
		(end 9.8298 -98.979228)
		(width 0.089408)
		(layer "In9.Cu")
		(net "SMB_LAN_STBY_LVC3_SDA")
	)
	(segment
		(start 425.714414 -120.663208)
		(end 426.591476 -121.54027)
		(width 0.089408)
		(layer "In9.Cu")
		(net "SMB_LAN_STBY_LVC3_SDA")
	)
	(segment
		(start 325.5518 -148.2344)
		(end 324.2818 -149.5044)
		(width 0.089408)
		(layer "In9.Cu")
		(net "SMB_LAN_STBY_LVC3_SDA")
	)
	(segment
		(start 436.722774 -126.7968)
		(end 437.89473 -127.968756)
		(width 0.089408)
		(layer "In9.Cu")
		(net "SMB_LAN_STBY_LVC3_SDA")
	)
	(segment
		(start 416.591242 -45.802042)
		(end 414.84296 -45.802042)
		(width 0.089408)
		(layer "In9.Cu")
		(net "SMB_LAN_STBY_LVC3_SDA")
	)
	(segment
		(start 433.801774 -125.217682)
		(end 435.380892 -126.7968)
		(width 0.089408)
		(layer "In9.Cu")
		(net "SMB_LAN_STBY_LVC3_SDA")
	)
	(segment
		(start 177.16627 -144.945608)
		(end 176.330102 -144.10944)
		(width 0.089408)
		(layer "In9.Cu")
		(net "SMB_LAN_STBY_LVC3_SDA")
	)
	(segment
		(start 437.89981 -127.969772)
		(end 437.979312 -127.969772)
		(width 0.089408)
		(layer "In9.Cu")
		(net "SMB_LAN_STBY_LVC3_SDA")
	)
	(segment
		(start 440.454796 -129.834132)
		(end 445.260476 -134.639812)
		(width 0.089408)
		(layer "In9.Cu")
		(net "SMB_LAN_STBY_LVC3_SDA")
	)
	(segment
		(start 437.979312 -127.969772)
		(end 439.843672 -129.834132)
		(width 0.089408)
		(layer "In9.Cu")
		(net "SMB_LAN_STBY_LVC3_SDA")
	)
	(segment
		(start 407.470356 -66.19494)
		(end 406.779476 -66.88582)
		(width 0.089408)
		(layer "In9.Cu")
		(net "SMB_LAN_STBY_LVC3_SDA")
	)
	(segment
		(start 410.323538 -50.394362)
		(end 407.93035 -52.78755)
		(width 0.089408)
		(layer "In9.Cu")
		(net "SMB_LAN_STBY_LVC3_SDA")
	)
	(segment
		(start 192.806828 -148.13661)
		(end 192.536826 -147.866608)
		(width 0.089408)
		(layer "In9.Cu")
		(net "SMB_LAN_STBY_LVC3_SDA")
	)
	(segment
		(start 414.123124 -46.521878)
		(end 414.123124 -47.089822)
		(width 0.089408)
		(layer "In9.Cu")
		(net "SMB_LAN_STBY_LVC3_SDA")
	)
	(segment
		(start 192.536826 -147.866608)
		(end 186.770518 -147.866608)
		(width 0.089408)
		(layer "In9.Cu")
		(net "SMB_LAN_STBY_LVC3_SDA")
	)
	(segment
		(start 449.07327 -136.11225)
		(end 449.07327 -140.291312)
		(width 0.089408)
		(layer "In9.Cu")
		(net "SMB_LAN_STBY_LVC3_SDA")
	)
	(segment
		(start 362.264706 -150.908766)
		(end 358.648 -150.908766)
		(width 0.089408)
		(layer "In9.Cu")
		(net "SMB_LAN_STBY_LVC3_SDA")
	)
	(segment
		(start 400.91614 -75.198478)
		(end 400.91614 -76.797154)
		(width 0.089408)
		(layer "In9.Cu")
		(net "SMB_LAN_STBY_LVC3_SDA")
	)
	(segment
		(start 259.153152 -148.13661)
		(end 192.806828 -148.13661)
		(width 0.089408)
		(layer "In9.Cu")
		(net "SMB_LAN_STBY_LVC3_SDA")
	)
	(segment
		(start 397.226028 -84.333588)
		(end 397.225012 -84.333588)
		(width 0.089408)
		(layer "In9.Cu")
		(net "SMB_LAN_STBY_LVC3_SDA")
	)
	(segment
		(start 448.31 -141.054582)
		(end 448.31 -144.0434)
		(width 0.089408)
		(layer "In9.Cu")
		(net "SMB_LAN_STBY_LVC3_SDA")
	)
	(segment
		(start 25.027128 -133.0198)
		(end 22.909784 -133.0198)
		(width 0.089408)
		(layer "In9.Cu")
		(net "SMB_LAN_STBY_LVC3_SDA")
	)
	(segment
		(start 446.222882 -155.73629)
		(end 446.222628 -155.736544)
		(width 0.089408)
		(layer "In9.Cu")
		(net "SMB_LAN_STBY_LVC3_SDA")
	)
	(segment
		(start 1.472438 -97.9424)
		(end 8.792972 -97.9424)
		(width 0.089408)
		(layer "In9.Cu")
		(net "SMB_LAN_STBY_LVC3_SDA")
	)
	(segment
		(start 21.129752 -128.86309)
		(end 20.644104 -129.348738)
		(width 0.089408)
		(layer "In9.Cu")
		(net "SMB_LAN_STBY_LVC3_SDA")
	)
	(segment
		(start 28.042616 -136.035288)
		(end 25.027128 -133.0198)
		(width 0.089408)
		(layer "In9.Cu")
		(net "SMB_LAN_STBY_LVC3_SDA")
	)
	(segment
		(start 13.11783 -105.735374)
		(end 13.829792 -106.447336)
		(width 0.089408)
		(layer "In9.Cu")
		(net "SMB_LAN_STBY_LVC3_SDA")
	)
	(segment
		(start 20.644104 -130.75412)
		(end 22.56917 -132.679186)
		(width 0.089408)
		(layer "In9.Cu")
		(net "SMB_LAN_STBY_LVC3_SDA")
	)
	(segment
		(start 412.660846 -48.070262)
		(end 411.736794 -48.070262)
		(width 0.089408)
		(layer "In9.Cu")
		(net "SMB_LAN_STBY_LVC3_SDA")
	)
	(segment
		(start 445.906144 -155.736544)
		(end 445.90589 -155.73629)
		(width 0.089408)
		(layer "In9.Cu")
		(net "SMB_LAN_STBY_LVC3_SDA")
	)
	(segment
		(start 400.086576 -156.021024)
		(end 398.865344 -157.242256)
		(width 0.089408)
		(layer "In9.Cu")
		(net "SMB_LAN_STBY_LVC3_SDA")
	)
	(segment
		(start 406.355042 -66.88582)
		(end 405.930354 -67.310508)
		(width 0.089408)
		(layer "In9.Cu")
		(net "SMB_LAN_STBY_LVC3_SDA")
	)
	(segment
		(start 437.89473 -127.968756)
		(end 437.898794 -127.968756)
		(width 0.089408)
		(layer "In9.Cu")
		(net "SMB_LAN_STBY_LVC3_SDA")
	)
	(segment
		(start 407.06929 -62.212728)
		(end 407.470356 -62.613794)
		(width 0.089408)
		(layer "In9.Cu")
		(net "SMB_LAN_STBY_LVC3_SDA")
	)
	(segment
		(start 402.671788 -156.737812)
		(end 401.955 -156.021024)
		(width 0.089408)
		(layer "In9.Cu")
		(net "SMB_LAN_STBY_LVC3_SDA")
	)
	(segment
		(start 445.260476 -134.639812)
		(end 447.600832 -134.639812)
		(width 0.089408)
		(layer "In9.Cu")
		(net "SMB_LAN_STBY_LVC3_SDA")
	)
	(segment
		(start 157.664658 -147.561808)
		(end 98.324924 -147.561808)
		(width 0.089408)
		(layer "In9.Cu")
		(net "SMB_LAN_STBY_LVC3_SDA")
	)
	(segment
		(start 178.118008 -144.945608)
		(end 177.16627 -144.945608)
		(width 0.089408)
		(layer "In9.Cu")
		(net "SMB_LAN_STBY_LVC3_SDA")
	)
	(segment
		(start 399.814542 -77.898752)
		(end 399.814542 -79.436214)
		(width 0.089408)
		(layer "In9.Cu")
		(net "SMB_LAN_STBY_LVC3_SDA")
	)
	(segment
		(start 13.829792 -108.735876)
		(end 19.622008 -114.528092)
		(width 0.089408)
		(layer "In9.Cu")
		(net "SMB_LAN_STBY_LVC3_SDA")
	)
	(segment
		(start 449.256912 -153.173938)
		(end 446.69456 -155.73629)
		(width 0.089408)
		(layer "In9.Cu")
		(net "SMB_LAN_STBY_LVC3_SDA")
	)
	(segment
		(start 162.73907 -147.155408)
		(end 158.271718 -147.155408)
		(width 0.089408)
		(layer "In9.Cu")
		(net "SMB_LAN_STBY_LVC3_SDA")
	)
	(segment
		(start 321.25031 -148.06422)
		(end 262.45058 -148.06422)
		(width 0.089408)
		(layer "In9.Cu")
		(net "SMB_LAN_STBY_LVC3_SDA")
	)
	(segment
		(start 435.50205 -155.73629)
		(end 434.567838 -154.802078)
		(width 0.089408)
		(layer "In9.Cu")
		(net "SMB_LAN_STBY_LVC3_SDA")
	)
	(segment
		(start 432.498754 -154.802078)
		(end 431.163984 -156.136848)
		(width 0.089408)
		(layer "In9.Cu")
		(net "SMB_LAN_STBY_LVC3_SDA")
	)
	(segment
		(start 449.069206 -151.274272)
		(end 449.256912 -151.461978)
		(width 0.089408)
		(layer "In9.Cu")
		(net "SMB_LAN_STBY_LVC3_SDA")
	)
	(segment
		(start 414.123124 -47.089822)
		(end 413.939736 -47.27321)
		(width 0.089408)
		(layer "In9.Cu")
		(net "SMB_LAN_STBY_LVC3_SDA")
	)
	(segment
		(start 401.4724 -74.642218)
		(end 400.91614 -75.198478)
		(width 0.089408)
		(layer "In9.Cu")
		(net "SMB_LAN_STBY_LVC3_SDA")
	)
	(segment
		(start 406.779476 -66.88582)
		(end 406.355042 -66.88582)
		(width 0.089408)
		(layer "In9.Cu")
		(net "SMB_LAN_STBY_LVC3_SDA")
	)
	(segment
		(start 364.707932 -153.760932)
		(end 364.363 -153.416)
		(width 0.089408)
		(layer "In9.Cu")
		(net "SMB_LAN_STBY_LVC3_SDA")
	)
	(segment
		(start 429.4505 -158.3817)
		(end 406.7302 -158.3817)
		(width 0.089408)
		(layer "In9.Cu")
		(net "SMB_LAN_STBY_LVC3_SDA")
	)
	(segment
		(start 437.898794 -127.968756)
		(end 437.89981 -127.969772)
		(width 0.089408)
		(layer "In9.Cu")
		(net "SMB_LAN_STBY_LVC3_SDA")
	)
	(segment
		(start 158.271718 -147.155408)
		(end 157.865064 -147.562062)
		(width 0.089408)
		(layer "In9.Cu")
		(net "SMB_LAN_STBY_LVC3_SDA")
	)
	(segment
		(start 448.31 -144.0434)
		(end 447.2432 -145.1102)
		(width 0.089408)
		(layer "In9.Cu")
		(net "SMB_LAN_STBY_LVC3_SDA")
	)
	(segment
		(start 98.324924 -147.561808)
		(end 96.838516 -146.0754)
		(width 0.089408)
		(layer "In9.Cu")
		(net "SMB_LAN_STBY_LVC3_SDA")
	)
	(segment
		(start 93.445584 -147.307808)
		(end 28.80487 -147.307808)
		(width 0.089408)
		(layer "In9.Cu")
		(net "SMB_LAN_STBY_LVC3_SDA")
	)
	(segment
		(start 364.707932 -156.836618)
		(end 364.707932 -153.760932)
		(width 0.089408)
		(layer "In9.Cu")
		(net "SMB_LAN_STBY_LVC3_SDA")
	)
	(segment
		(start 176.330102 -144.10944)
		(end 166.925498 -144.10944)
		(width 0.089408)
		(layer "In9.Cu")
		(net "SMB_LAN_STBY_LVC3_SDA")
	)
	(segment
		(start 400.91614 -76.797154)
		(end 399.814542 -77.898752)
		(width 0.089408)
		(layer "In9.Cu")
		(net "SMB_LAN_STBY_LVC3_SDA")
	)
	(segment
		(start 431.163984 -156.668216)
		(end 429.4505 -158.3817)
		(width 0.089408)
		(layer "In9.Cu")
		(net "SMB_LAN_STBY_LVC3_SDA")
	)
	(segment
		(start 372.12397 -158.598108)
		(end 371.09908 -157.573218)
		(width 0.089408)
		(layer "In9.Cu")
		(net "SMB_LAN_STBY_LVC3_SDA")
	)
	(segment
		(start 413.505904 -47.706788)
		(end 413.02432 -47.706788)
		(width 0.089408)
		(layer "In9.Cu")
		(net "SMB_LAN_STBY_LVC3_SDA")
	)
	(segment
		(start 353.74072 -153.708608)
		(end 353.74072 -156.034994)
		(width 0.089408)
		(layer "In9.Cu")
		(net "SMB_LAN_STBY_LVC3_SDA")
	)
	(segment
		(start 405.086312 -156.737812)
		(end 402.671788 -156.737812)
		(width 0.089408)
		(layer "In9.Cu")
		(net "SMB_LAN_STBY_LVC3_SDA")
	)
	(segment
		(start 28.80487 -147.307808)
		(end 28.042616 -146.545554)
		(width 0.089408)
		(layer "In9.Cu")
		(net "SMB_LAN_STBY_LVC3_SDA")
	)
	(segment
		(start 401.4724 -74.422762)
		(end 401.4724 -74.642218)
		(width 0.089408)
		(layer "In9.Cu")
		(net "SMB_LAN_STBY_LVC3_SDA")
	)
	(segment
		(start 355.912928 -151.5364)
		(end 353.74072 -153.708608)
		(width 0.089408)
		(layer "In9.Cu")
		(net "SMB_LAN_STBY_LVC3_SDA")
	)
	(segment
		(start 407.93035 -54.391814)
		(end 407.06929 -55.252874)
		(width 0.089408)
		(layer "In9.Cu")
		(net "SMB_LAN_STBY_LVC3_SDA")
	)
	(segment
		(start 397.337788 -84.221828)
		(end 397.226028 -84.333588)
		(width 0.089408)
		(layer "In9.Cu")
		(net "SMB_LAN_STBY_LVC3_SDA")
	)
	(segment
		(start 333.616808 -157.753558)
		(end 333.216504 -157.353254)
		(width 0.089408)
		(layer "In9.Cu")
		(net "SMB_LAN_STBY_LVC3_SDA")
	)
	(segment
		(start 449.06692 -148.59)
		(end 449.06692 -151.274272)
		(width 0.089408)
		(layer "In9.Cu")
		(net "SMB_LAN_STBY_LVC3_SDA")
	)
	(segment
		(start 352.683318 -157.092396)
		(end 351.584768 -157.092396)
		(width 0.089408)
		(layer "In9.Cu")
		(net "SMB_LAN_STBY_LVC3_SDA")
	)
	(segment
		(start 353.74072 -156.034994)
		(end 352.683318 -157.092396)
		(width 0.089408)
		(layer "In9.Cu")
		(net "SMB_LAN_STBY_LVC3_SDA")
	)
	(segment
		(start 426.591476 -121.54027)
		(end 426.591476 -122.484642)
		(width 0.089408)
		(layer "In9.Cu")
		(net "SMB_LAN_STBY_LVC3_SDA")
	)
	(segment
		(start 392.571224 -158.598108)
		(end 372.12397 -158.598108)
		(width 0.089408)
		(layer "In9.Cu")
		(net "SMB_LAN_STBY_LVC3_SDA")
	)
	(segment
		(start 365.444532 -157.573218)
		(end 364.707932 -156.836618)
		(width 0.089408)
		(layer "In9.Cu")
		(net "SMB_LAN_STBY_LVC3_SDA")
	)
	(segment
		(start 157.664912 -147.562062)
		(end 157.664658 -147.561808)
		(width 0.089408)
		(layer "In9.Cu")
		(net "SMB_LAN_STBY_LVC3_SDA")
	)
	(segment
		(start 259.50418 -148.487638)
		(end 259.153152 -148.13661)
		(width 0.089408)
		(layer "In9.Cu")
		(net "SMB_LAN_STBY_LVC3_SDA")
	)
	(segment
		(start 431.163984 -156.136848)
		(end 431.163984 -156.668216)
		(width 0.089408)
		(layer "In9.Cu")
		(net "SMB_LAN_STBY_LVC3_SDA")
	)
	(segment
		(start 447.600832 -134.639812)
		(end 449.07327 -136.11225)
		(width 0.089408)
		(layer "In9.Cu")
		(net "SMB_LAN_STBY_LVC3_SDA")
	)
	(segment
		(start 449.256912 -151.461978)
		(end 449.256912 -153.173938)
		(width 0.089408)
		(layer "In9.Cu")
		(net "SMB_LAN_STBY_LVC3_SDA")
	)
	(segment
		(start 434.567838 -154.802078)
		(end 432.498754 -154.802078)
		(width 0.089408)
		(layer "In9.Cu")
		(net "SMB_LAN_STBY_LVC3_SDA")
	)
	(segment
		(start 407.06929 -55.252874)
		(end 407.06929 -62.212728)
		(width 0.089408)
		(layer "In9.Cu")
		(net "SMB_LAN_STBY_LVC3_SDA")
	)
	(segment
		(start 13.829792 -106.447336)
		(end 13.829792 -108.735876)
		(width 0.089408)
		(layer "In9.Cu")
		(net "SMB_LAN_STBY_LVC3_SDA")
	)
	(segment
		(start 425.714414 -116.556536)
		(end 425.714414 -120.663208)
		(width 0.089408)
		(layer "In9.Cu")
		(net "SMB_LAN_STBY_LVC3_SDA")
	)
	(segment
		(start 398.865344 -157.242256)
		(end 394.11656 -157.242256)
		(width 0.089408)
		(layer "In9.Cu")
		(net "SMB_LAN_STBY_LVC3_SDA")
	)
	(segment
		(start 358.648 -150.908766)
		(end 358.020366 -151.5364)
		(width 0.089408)
		(layer "In9.Cu")
		(net "SMB_LAN_STBY_LVC3_SDA")
	)
	(segment
		(start 96.838516 -146.0754)
		(end 94.677992 -146.0754)
		(width 0.089408)
		(layer "In9.Cu")
		(net "SMB_LAN_STBY_LVC3_SDA")
	)
	(segment
		(start 22.909784 -133.0198)
		(end 22.56917 -132.679186)
		(width 0.089408)
		(layer "In9.Cu")
		(net "SMB_LAN_STBY_LVC3_SDA")
	)
	(segment
		(start 351.584768 -157.092396)
		(end 351.003362 -157.673802)
		(width 0.089408)
		(layer "In9.Cu")
		(net "SMB_LAN_STBY_LVC3_SDA")
	)
	(segment
		(start 405.930354 -69.964808)
		(end 401.4724 -74.422762)
		(width 0.089408)
		(layer "In9.Cu")
		(net "SMB_LAN_STBY_LVC3_SDA")
	)
	(segment
		(start 406.7302 -158.3817)
		(end 405.086312 -156.737812)
		(width 0.089408)
		(layer "In9.Cu")
		(net "SMB_LAN_STBY_LVC3_SDA")
	)
	(segment
		(start 179.312062 -144.9832)
		(end 178.4604 -144.9832)
		(width 0.089408)
		(layer "In9.Cu")
		(net "SMB_LAN_STBY_LVC3_SDA")
	)
	(segment
		(start 358.020366 -151.5364)
		(end 355.912928 -151.5364)
		(width 0.089408)
		(layer "In9.Cu")
		(net "SMB_LAN_STBY_LVC3_SDA")
	)
	(segment
		(start 186.770518 -147.866608)
		(end 184.97931 -146.0754)
		(width 0.089408)
		(layer "In9.Cu")
		(net "SMB_LAN_STBY_LVC3_SDA")
	)
	(segment
		(start 324.2818 -149.5044)
		(end 322.69049 -149.5044)
		(width 0.089408)
		(layer "In9.Cu")
		(net "SMB_LAN_STBY_LVC3_SDA")
	)
	(segment
		(start 405.930354 -67.310508)
		(end 405.930354 -69.964808)
		(width 0.089408)
		(layer "In9.Cu")
		(net "SMB_LAN_STBY_LVC3_SDA")
	)
	(segment
		(start 397.225012 -84.333588)
		(end 394.9192 -86.6394)
		(width 0.089408)
		(layer "In9.Cu")
		(net "SMB_LAN_STBY_LVC3_SDA")
	)
	(segment
		(start 407.470356 -62.613794)
		(end 407.470356 -66.19494)
		(width 0.089408)
		(layer "In9.Cu")
		(net "SMB_LAN_STBY_LVC3_SDA")
	)
	(segment
		(start 427.100746 -122.993912)
		(end 427.100746 -124.289566)
		(width 0.089408)
		(layer "In9.Cu")
		(net "SMB_LAN_STBY_LVC3_SDA")
	)
	(segment
		(start 439.843672 -129.834132)
		(end 440.454796 -129.834132)
		(width 0.089408)
		(layer "In9.Cu")
		(net "SMB_LAN_STBY_LVC3_SDA")
	)
	(segment
		(start 325.7804 -148.2344)
		(end 325.5518 -148.2344)
		(width 0.089408)
		(layer "In9.Cu")
		(net "SMB_LAN_STBY_LVC3_SDA")
	)
	(segment
		(start 417.685982 -46.896782)
		(end 416.591242 -45.802042)
		(width 0.089408)
		(layer "In9.Cu")
		(net "SMB_LAN_STBY_LVC3_SDA")
	)
	(segment
		(start 334.042766 -157.753558)
		(end 333.616808 -157.753558)
		(width 0.089408)
		(layer "In9.Cu")
		(net "SMB_LAN_STBY_LVC3_SDA")
	)
	(segment
		(start 20.644104 -129.348738)
		(end 20.644104 -130.75412)
		(width 0.089408)
		(layer "In9.Cu")
		(net "SMB_LAN_STBY_LVC3_SDA")
	)
	(segment
		(start 165.797738 -145.2372)
		(end 164.857938 -145.2372)
		(width 0.089408)
		(layer "In9.Cu")
		(net "SMB_LAN_STBY_LVC3_SDA")
	)
	(segment
		(start 413.939736 -47.27321)
		(end 413.939482 -47.27321)
		(width 0.089408)
		(layer "In9.Cu")
		(net "SMB_LAN_STBY_LVC3_SDA")
	)
	(segment
		(start 262.027162 -148.487638)
		(end 259.50418 -148.487638)
		(width 0.089408)
		(layer "In9.Cu")
		(net "SMB_LAN_STBY_LVC3_SDA")
	)
	(segment
		(start 371.09908 -157.573218)
		(end 365.444532 -157.573218)
		(width 0.089408)
		(layer "In9.Cu")
		(net "SMB_LAN_STBY_LVC3_SDA")
	)
	(segment
		(start 364.363 -153.00706)
		(end 362.264706 -150.908766)
		(width 0.089408)
		(layer "In9.Cu")
		(net "SMB_LAN_STBY_LVC3_SDA")
	)
	(segment
		(start 407.93035 -52.78755)
		(end 407.93035 -54.391814)
		(width 0.089408)
		(layer "In9.Cu")
		(net "SMB_LAN_STBY_LVC3_SDA")
	)
	(segment
		(start 410.323538 -49.483518)
		(end 410.323538 -50.394362)
		(width 0.089408)
		(layer "In9.Cu")
		(net "SMB_LAN_STBY_LVC3_SDA")
	)
	(segment
		(start 414.84296 -45.802042)
		(end 414.123124 -46.521878)
		(width 0.089408)
		(layer "In9.Cu")
		(net "SMB_LAN_STBY_LVC3_SDA")
	)
	(segment
		(start 399.814542 -79.436214)
		(end 397.337788 -81.912968)
		(width 0.089408)
		(layer "In9.Cu")
		(net "SMB_LAN_STBY_LVC3_SDA")
	)
	(segment
		(start 401.955 -156.021024)
		(end 400.086576 -156.021024)
		(width 0.089408)
		(layer "In9.Cu")
		(net "SMB_LAN_STBY_LVC3_SDA")
	)
	(segment
		(start 178.4604 -144.9832)
		(end 178.308 -145.1356)
		(width 0.089408)
		(layer "In9.Cu")
		(net "SMB_LAN_STBY_LVC3_SDA")
	)
	(segment
		(start 178.308 -145.1356)
		(end 178.118008 -144.945608)
		(width 0.089408)
		(layer "In9.Cu")
		(net "SMB_LAN_STBY_LVC3_SDA")
	)
	(segment
		(start 351.003362 -157.673802)
		(end 334.122522 -157.673802)
		(width 0.089408)
		(layer "In9.Cu")
		(net "SMB_LAN_STBY_LVC3_SDA")
	)
	(segment
		(start 413.939482 -47.27321)
		(end 413.505904 -47.706788)
		(width 0.089408)
		(layer "In9.Cu")
		(net "SMB_LAN_STBY_LVC3_SDA")
	)
	(segment
		(start 426.591476 -122.484642)
		(end 427.100746 -122.993912)
		(width 0.089408)
		(layer "In9.Cu")
		(net "SMB_LAN_STBY_LVC3_SDA")
	)
	(segment
		(start 417.685982 -47.09541)
		(end 417.685982 -46.896782)
		(width 0.089408)
		(layer "In9.Cu")
		(net "SMB_LAN_STBY_LVC3_SDA")
	)
	(segment
		(start 9.8298 -98.979228)
		(end 9.8298 -102.145084)
		(width 0.089408)
		(layer "In9.Cu")
		(net "SMB_LAN_STBY_LVC3_SDA")
	)
	(segment
		(start 334.122522 -157.673802)
		(end 334.042766 -157.753558)
		(width 0.089408)
		(layer "In9.Cu")
		(net "SMB_LAN_STBY_LVC3_SDA")
	)
	(segment
		(start 180.404262 -146.0754)
		(end 179.312062 -144.9832)
		(width 0.089408)
		(layer "In9.Cu")
		(net "SMB_LAN_STBY_LVC3_SDA")
	)
	(segment
		(start 446.222628 -155.736544)
		(end 445.906144 -155.736544)
		(width 0.089408)
		(layer "In9.Cu")
		(net "SMB_LAN_STBY_LVC3_SDA")
	)
	(segment
		(start 413.02432 -47.706788)
		(end 412.660846 -48.070262)
		(width 0.089408)
		(layer "In9.Cu")
		(net "SMB_LAN_STBY_LVC3_SDA")
	)
	(segment
		(start 166.925498 -144.10944)
		(end 165.797738 -145.2372)
		(width 0.089408)
		(layer "In9.Cu")
		(net "SMB_LAN_STBY_LVC3_SDA")
	)
	(segment
		(start 435.380892 -126.7968)
		(end 436.722774 -126.7968)
		(width 0.089408)
		(layer "In9.Cu")
		(net "SMB_LAN_STBY_LVC3_SDA")
	)
	(segment
		(start 162.939476 -147.155662)
		(end 162.739324 -147.155662)
		(width 0.089408)
		(layer "In9.Cu")
		(net "SMB_LAN_STBY_LVC3_SDA")
	)
	(segment
		(start 445.90589 -155.73629)
		(end 435.50205 -155.73629)
		(width 0.089408)
		(layer "In9.Cu")
		(net "SMB_LAN_STBY_LVC3_SDA")
	)
	(segment
		(start 0.299974 -96.769936)
		(end 1.472438 -97.9424)
		(width 0.089408)
		(layer "In9.Cu")
		(net "SMB_LAN_STBY_LVC3_SDA")
	)
	(segment
		(start 394.11656 -157.242256)
		(end 392.91895 -158.439866)
		(width 0.089408)
		(layer "In9.Cu")
		(net "SMB_LAN_STBY_LVC3_SDA")
	)
	(segment
		(start 427.100746 -124.289566)
		(end 428.028862 -125.217682)
		(width 0.089408)
		(layer "In9.Cu")
		(net "SMB_LAN_STBY_LVC3_SDA")
	)
	(segment
		(start 447.2432 -145.1102)
		(end 447.2432 -146.76628)
		(width 0.089408)
		(layer "In9.Cu")
		(net "SMB_LAN_STBY_LVC3_SDA")
	)
	(segment
		(start 13.11783 -105.433114)
		(end 13.11783 -105.735374)
		(width 0.089408)
		(layer "In9.Cu")
		(net "SMB_LAN_STBY_LVC3_SDA")
	)
	(segment
		(start 19.622008 -115.554506)
		(end 20.644104 -116.576602)
		(width 0.089408)
		(layer "In9.Cu")
		(net "SMB_LAN_STBY_LVC3_SDA")
	)
	(segment
		(start 330.173076 -156.296868)
		(end 329.207368 -155.33116)
		(width 0.10795)
		(layer "F.Cu")
		(net "SMB_LAN_STBY_LVC3_SCL")
	)
	(segment
		(start 395.351 -85.9155)
		(end 395.351 -86.3727)
		(width 0.10795)
		(layer "F.Cu")
		(net "SMB_LAN_STBY_LVC3_SCL")
	)
	(segment
		(start 178.649376 -144.159224)
		(end 178.3334 -144.4752)
		(width 0.10795)
		(layer "F.Cu")
		(net "SMB_LAN_STBY_LVC3_SCL")
	)
	(segment
		(start 326.282304 -147.52955)
		(end 326.081644 -147.73021)
		(width 0.10795)
		(layer "F.Cu")
		(net "SMB_LAN_STBY_LVC3_SCL")
	)
	(segment
		(start 328.494898 -148.126704)
		(end 327.62063 -147.52955)
		(width 0.10795)
		(layer "F.Cu")
		(net "SMB_LAN_STBY_LVC3_SCL")
	)
	(segment
		(start 327.62063 -147.52955)
		(end 326.282304 -147.52955)
		(width 0.10795)
		(layer "F.Cu")
		(net "SMB_LAN_STBY_LVC3_SCL")
	)
	(segment
		(start 178.98237 -144.159224)
		(end 178.649376 -144.159224)
		(width 0.10795)
		(layer "F.Cu")
		(net "SMB_LAN_STBY_LVC3_SCL")
	)
	(segment
		(start 15.113 -102.9208)
		(end 15.40129 -103.20909)
		(width 0.10795)
		(layer "F.Cu")
		(net "SMB_LAN_STBY_LVC3_SCL")
	)
	(segment
		(start 395.351 -86.9061)
		(end 395.351 -87.3125)
		(width 0.10795)
		(layer "F.Cu")
		(net "SMB_LAN_STBY_LVC3_SCL")
	)
	(segment
		(start 332.110334 -156.670248)
		(end 331.736954 -156.296868)
		(width 0.10795)
		(layer "F.Cu")
		(net "SMB_LAN_STBY_LVC3_SCL")
	)
	(segment
		(start 329.207368 -148.839174)
		(end 328.494898 -148.126704)
		(width 0.10795)
		(layer "F.Cu")
		(net "SMB_LAN_STBY_LVC3_SCL")
	)
	(segment
		(start 15.40129 -104.771698)
		(end 14.387576 -105.785412)
		(width 0.10795)
		(layer "F.Cu")
		(net "SMB_LAN_STBY_LVC3_SCL")
	)
	(segment
		(start 325.93661 -147.73021)
		(end 325.7804 -147.574)
		(width 0.10795)
		(layer "F.Cu")
		(net "SMB_LAN_STBY_LVC3_SCL")
	)
	(segment
		(start 331.736954 -156.296868)
		(end 330.173076 -156.296868)
		(width 0.10795)
		(layer "F.Cu")
		(net "SMB_LAN_STBY_LVC3_SCL")
	)
	(segment
		(start 326.081644 -147.73021)
		(end 325.93661 -147.73021)
		(width 0.10795)
		(layer "F.Cu")
		(net "SMB_LAN_STBY_LVC3_SCL")
	)
	(segment
		(start 15.40129 -103.20909)
		(end 15.40129 -104.771698)
		(width 0.10795)
		(layer "F.Cu")
		(net "SMB_LAN_STBY_LVC3_SCL")
	)
	(segment
		(start 395.6177 -86.6394)
		(end 395.351 -86.9061)
		(width 0.10795)
		(layer "F.Cu")
		(net "SMB_LAN_STBY_LVC3_SCL")
	)
	(segment
		(start 333.876904 -157.353254)
		(end 333.193898 -156.670248)
		(width 0.10795)
		(layer "F.Cu")
		(net "SMB_LAN_STBY_LVC3_SCL")
	)
	(segment
		(start 329.207368 -155.33116)
		(end 329.207368 -148.839174)
		(width 0.10795)
		(layer "F.Cu")
		(net "SMB_LAN_STBY_LVC3_SCL")
	)
	(segment
		(start 14.387576 -105.785412)
		(end 13.884148 -105.785412)
		(width 0.10795)
		(layer "F.Cu")
		(net "SMB_LAN_STBY_LVC3_SCL")
	)
	(segment
		(start 15.113 -101.981)
		(end 15.113 -102.9208)
		(width 0.10795)
		(layer "F.Cu")
		(net "SMB_LAN_STBY_LVC3_SCL")
	)
	(segment
		(start 333.193898 -156.670248)
		(end 332.110334 -156.670248)
		(width 0.10795)
		(layer "F.Cu")
		(net "SMB_LAN_STBY_LVC3_SCL")
	)
	(segment
		(start 395.351 -86.3727)
		(end 395.6177 -86.6394)
		(width 0.10795)
		(layer "F.Cu")
		(net "SMB_LAN_STBY_LVC3_SCL")
	)
	(via
		(at 425.638976 -115.8748)
		(size 0.508)
		(drill 0.254)
		(layers "F.Cu" "B.Cu")
		(net "SMB_LAN_STBY_LVC3_SCL")
	)
	(via
		(at 395.6177 -86.6394)
		(size 0.508)
		(drill 0.254)
		(layers "F.Cu" "B.Cu")
		(net "SMB_LAN_STBY_LVC3_SCL")
	)
	(via
		(at 417.3601 -88.567768)
		(size 0.508)
		(drill 0.254)
		(layers "F.Cu" "B.Cu")
		(net "SMB_LAN_STBY_LVC3_SCL")
	)
	(via
		(at 416.56 -88.5952)
		(size 0.6604)
		(drill 0.3302)
		(layers "F.Cu" "B.Cu")
		(net "SMB_LAN_STBY_LVC3_SCL")
	)
	(via
		(at 417.0172 -46.8376)
		(size 0.508)
		(drill 0.254)
		(layers "F.Cu" "B.Cu")
		(net "SMB_LAN_STBY_LVC3_SCL")
	)
	(via
		(at 333.876904 -157.353254)
		(size 0.508)
		(drill 0.254)
		(layers "F.Cu" "B.Cu")
		(net "SMB_LAN_STBY_LVC3_SCL")
	)
	(via
		(at 13.884148 -105.785412)
		(size 0.508)
		(drill 0.254)
		(layers "F.Cu" "B.Cu")
		(net "SMB_LAN_STBY_LVC3_SCL")
	)
	(via
		(at 178.3334 -144.4752)
		(size 0.508)
		(drill 0.254)
		(layers "F.Cu" "B.Cu")
		(net "SMB_LAN_STBY_LVC3_SCL")
	)
	(via
		(at 23.2791 -132.588)
		(size 0.508)
		(drill 0.254)
		(layers "F.Cu" "B.Cu")
		(net "SMB_LAN_STBY_LVC3_SCL")
	)
	(via
		(at 325.7804 -147.574)
		(size 0.508)
		(drill 0.254)
		(layers "F.Cu" "B.Cu")
		(net "SMB_LAN_STBY_LVC3_SCL")
	)
	(segment
		(start 395.351 -85.9155)
		(end 395.351 -86.36)
		(width 0.10795)
		(layer "B.Cu")
		(net "SMB_LAN_STBY_LVC3_SCL")
	)
	(segment
		(start 417.3601 -88.567768)
		(end 417.32073 -88.567768)
		(width 0.10795)
		(layer "B.Cu")
		(net "SMB_LAN_STBY_LVC3_SCL")
	)
	(segment
		(start 20.971764 -134.965694)
		(end 23.2791 -132.658358)
		(width 0.10795)
		(layer "B.Cu")
		(net "SMB_LAN_STBY_LVC3_SCL")
	)
	(segment
		(start 417.293298 -88.5952)
		(end 416.56 -88.5952)
		(width 0.10795)
		(layer "B.Cu")
		(net "SMB_LAN_STBY_LVC3_SCL")
	)
	(segment
		(start 395.351 -86.9188)
		(end 395.6304 -86.6394)
		(width 0.10795)
		(layer "B.Cu")
		(net "SMB_LAN_STBY_LVC3_SCL")
	)
	(segment
		(start 416.6108 -46.4312)
		(end 415.925 -46.4312)
		(width 0.10795)
		(layer "B.Cu")
		(net "SMB_LAN_STBY_LVC3_SCL")
	)
	(segment
		(start 395.351 -86.36)
		(end 395.6304 -86.6394)
		(width 0.10795)
		(layer "B.Cu")
		(net "SMB_LAN_STBY_LVC3_SCL")
	)
	(segment
		(start 23.2791 -132.658358)
		(end 23.2791 -132.588)
		(width 0.10795)
		(layer "B.Cu")
		(net "SMB_LAN_STBY_LVC3_SCL")
	)
	(segment
		(start 415.925 -46.4312)
		(end 415.708846 -46.215046)
		(width 0.10795)
		(layer "B.Cu")
		(net "SMB_LAN_STBY_LVC3_SCL")
	)
	(segment
		(start 415.708846 -46.215046)
		(end 415.708846 -45.539152)
		(width 0.10795)
		(layer "B.Cu")
		(net "SMB_LAN_STBY_LVC3_SCL")
	)
	(segment
		(start 417.0172 -46.8376)
		(end 416.6108 -46.4312)
		(width 0.10795)
		(layer "B.Cu")
		(net "SMB_LAN_STBY_LVC3_SCL")
	)
	(segment
		(start 395.6304 -86.6394)
		(end 395.6177 -86.6394)
		(width 0.10795)
		(layer "B.Cu")
		(net "SMB_LAN_STBY_LVC3_SCL")
	)
	(segment
		(start 417.32073 -88.567768)
		(end 417.293298 -88.5952)
		(width 0.10795)
		(layer "B.Cu")
		(net "SMB_LAN_STBY_LVC3_SCL")
	)
	(segment
		(start 20.14982 -134.965694)
		(end 20.971764 -134.965694)
		(width 0.10795)
		(layer "B.Cu")
		(net "SMB_LAN_STBY_LVC3_SCL")
	)
	(segment
		(start 395.351 -87.3125)
		(end 395.351 -86.9188)
		(width 0.10795)
		(layer "B.Cu")
		(net "SMB_LAN_STBY_LVC3_SCL")
	)
	(segment
		(start 418.99078 -116.586508)
		(end 419.148768 -116.586508)
		(width 0.089408)
		(layer "In2.Cu")
		(net "SMB_LAN_STBY_LVC3_SCL")
	)
	(segment
		(start 417.607242 -115.310158)
		(end 418.883338 -116.586254)
		(width 0.089408)
		(layer "In2.Cu")
		(net "SMB_LAN_STBY_LVC3_SCL")
	)
	(segment
		(start 417.494466 -91.41333)
		(end 417.494466 -92.992448)
		(width 0.089408)
		(layer "In2.Cu")
		(net "SMB_LAN_STBY_LVC3_SCL")
	)
	(segment
		(start 417.872926 -94.364302)
		(end 417.87318 -94.364556)
		(width 0.089408)
		(layer "In2.Cu")
		(net "SMB_LAN_STBY_LVC3_SCL")
	)
	(segment
		(start 417.854892 -103.483156)
		(end 417.854638 -103.48341)
		(width 0.089408)
		(layer "In2.Cu")
		(net "SMB_LAN_STBY_LVC3_SCL")
	)
	(segment
		(start 421.505634 -116.586)
		(end 421.663622 -116.586)
		(width 0.089408)
		(layer "In2.Cu")
		(net "SMB_LAN_STBY_LVC3_SCL")
	)
	(segment
		(start 417.854638 -103.48341)
		(end 417.854638 -103.641398)
		(width 0.089408)
		(layer "In2.Cu")
		(net "SMB_LAN_STBY_LVC3_SCL")
	)
	(segment
		(start 423.008806 -115.741958)
		(end 425.506134 -115.741958)
		(width 0.089408)
		(layer "In2.Cu")
		(net "SMB_LAN_STBY_LVC3_SCL")
	)
	(segment
		(start 419.149022 -116.586254)
		(end 421.50538 -116.586254)
		(width 0.089408)
		(layer "In2.Cu")
		(net "SMB_LAN_STBY_LVC3_SCL")
	)
	(segment
		(start 417.87318 -94.364556)
		(end 417.87318 -94.522544)
		(width 0.089408)
		(layer "In2.Cu")
		(net "SMB_LAN_STBY_LVC3_SCL")
	)
	(segment
		(start 417.854892 -103.325168)
		(end 417.854892 -103.483156)
		(width 0.089408)
		(layer "In2.Cu")
		(net "SMB_LAN_STBY_LVC3_SCL")
	)
	(segment
		(start 417.29914 -95.096584)
		(end 417.29914 -102.769416)
		(width 0.089408)
		(layer "In2.Cu")
		(net "SMB_LAN_STBY_LVC3_SCL")
	)
	(segment
		(start 418.018722 -88.80221)
		(end 418.32657 -89.110058)
		(width 0.089408)
		(layer "In2.Cu")
		(net "SMB_LAN_STBY_LVC3_SCL")
	)
	(segment
		(start 425.506134 -115.741958)
		(end 425.638976 -115.8748)
		(width 0.089408)
		(layer "In2.Cu")
		(net "SMB_LAN_STBY_LVC3_SCL")
	)
	(segment
		(start 417.854384 -106.86034)
		(end 417.607242 -107.107482)
		(width 0.089408)
		(layer "In2.Cu")
		(net "SMB_LAN_STBY_LVC3_SCL")
	)
	(segment
		(start 417.872926 -93.370908)
		(end 417.872926 -94.364302)
		(width 0.089408)
		(layer "In2.Cu")
		(net "SMB_LAN_STBY_LVC3_SCL")
	)
	(segment
		(start 421.663622 -116.586)
		(end 421.663876 -116.586254)
		(width 0.089408)
		(layer "In2.Cu")
		(net "SMB_LAN_STBY_LVC3_SCL")
	)
	(segment
		(start 421.50538 -116.586254)
		(end 421.505634 -116.586)
		(width 0.089408)
		(layer "In2.Cu")
		(net "SMB_LAN_STBY_LVC3_SCL")
	)
	(segment
		(start 417.3601 -88.567768)
		(end 417.594542 -88.80221)
		(width 0.089408)
		(layer "In2.Cu")
		(net "SMB_LAN_STBY_LVC3_SCL")
	)
	(segment
		(start 417.607242 -107.107482)
		(end 417.607242 -115.310158)
		(width 0.089408)
		(layer "In2.Cu")
		(net "SMB_LAN_STBY_LVC3_SCL")
	)
	(segment
		(start 418.990526 -116.586254)
		(end 418.99078 -116.586508)
		(width 0.089408)
		(layer "In2.Cu")
		(net "SMB_LAN_STBY_LVC3_SCL")
	)
	(segment
		(start 417.87318 -94.522544)
		(end 417.29914 -95.096584)
		(width 0.089408)
		(layer "In2.Cu")
		(net "SMB_LAN_STBY_LVC3_SCL")
	)
	(segment
		(start 418.32657 -90.581226)
		(end 417.494466 -91.41333)
		(width 0.089408)
		(layer "In2.Cu")
		(net "SMB_LAN_STBY_LVC3_SCL")
	)
	(segment
		(start 419.148768 -116.586508)
		(end 419.149022 -116.586254)
		(width 0.089408)
		(layer "In2.Cu")
		(net "SMB_LAN_STBY_LVC3_SCL")
	)
	(segment
		(start 417.494466 -92.992448)
		(end 417.872926 -93.370908)
		(width 0.089408)
		(layer "In2.Cu")
		(net "SMB_LAN_STBY_LVC3_SCL")
	)
	(segment
		(start 421.663876 -116.586254)
		(end 422.16451 -116.586254)
		(width 0.089408)
		(layer "In2.Cu")
		(net "SMB_LAN_STBY_LVC3_SCL")
	)
	(segment
		(start 417.594542 -88.80221)
		(end 418.018722 -88.80221)
		(width 0.089408)
		(layer "In2.Cu")
		(net "SMB_LAN_STBY_LVC3_SCL")
	)
	(segment
		(start 417.29914 -102.769416)
		(end 417.854892 -103.325168)
		(width 0.089408)
		(layer "In2.Cu")
		(net "SMB_LAN_STBY_LVC3_SCL")
	)
	(segment
		(start 418.883338 -116.586254)
		(end 418.990526 -116.586254)
		(width 0.089408)
		(layer "In2.Cu")
		(net "SMB_LAN_STBY_LVC3_SCL")
	)
	(segment
		(start 422.16451 -116.586254)
		(end 423.008806 -115.741958)
		(width 0.089408)
		(layer "In2.Cu")
		(net "SMB_LAN_STBY_LVC3_SCL")
	)
	(segment
		(start 417.854384 -103.641652)
		(end 417.854384 -106.86034)
		(width 0.089408)
		(layer "In2.Cu")
		(net "SMB_LAN_STBY_LVC3_SCL")
	)
	(segment
		(start 417.854638 -103.641398)
		(end 417.854384 -103.641652)
		(width 0.089408)
		(layer "In2.Cu")
		(net "SMB_LAN_STBY_LVC3_SCL")
	)
	(segment
		(start 418.32657 -89.110058)
		(end 418.32657 -90.581226)
		(width 0.089408)
		(layer "In2.Cu")
		(net "SMB_LAN_STBY_LVC3_SCL")
	)
	(segment
		(start 399.382996 -87.393526)
		(end 396.015464 -87.393526)
		(width 0.089408)
		(layer "In4.Cu")
		(net "SMB_LAN_STBY_LVC3_SCL")
	)
	(segment
		(start 396.015464 -87.393526)
		(end 395.6177 -86.995762)
		(width 0.089408)
		(layer "In4.Cu")
		(net "SMB_LAN_STBY_LVC3_SCL")
	)
	(segment
		(start 415.740342 -89.018872)
		(end 412.6992 -89.018872)
		(width 0.089408)
		(layer "In4.Cu")
		(net "SMB_LAN_STBY_LVC3_SCL")
	)
	(segment
		(start 411.696154 -90.021918)
		(end 411.193996 -90.021918)
		(width 0.089408)
		(layer "In4.Cu")
		(net "SMB_LAN_STBY_LVC3_SCL")
	)
	(segment
		(start 417.3601 -88.567768)
		(end 417.32073 -88.567768)
		(width 0.089408)
		(layer "In4.Cu")
		(net "SMB_LAN_STBY_LVC3_SCL")
	)
	(segment
		(start 417.26739 -88.621108)
		(end 416.138106 -88.621108)
		(width 0.089408)
		(layer "In4.Cu")
		(net "SMB_LAN_STBY_LVC3_SCL")
	)
	(segment
		(start 417.32073 -88.567768)
		(end 417.26739 -88.621108)
		(width 0.089408)
		(layer "In4.Cu")
		(net "SMB_LAN_STBY_LVC3_SCL")
	)
	(segment
		(start 402.456396 -87.436198)
		(end 402.078698 -87.813896)
		(width 0.089408)
		(layer "In4.Cu")
		(net "SMB_LAN_STBY_LVC3_SCL")
	)
	(segment
		(start 402.078698 -87.813896)
		(end 399.803366 -87.813896)
		(width 0.089408)
		(layer "In4.Cu")
		(net "SMB_LAN_STBY_LVC3_SCL")
	)
	(segment
		(start 410.203396 -89.038938)
		(end 406.349962 -89.038938)
		(width 0.089408)
		(layer "In4.Cu")
		(net "SMB_LAN_STBY_LVC3_SCL")
	)
	(segment
		(start 399.803366 -87.813896)
		(end 399.382996 -87.393526)
		(width 0.089408)
		(layer "In4.Cu")
		(net "SMB_LAN_STBY_LVC3_SCL")
	)
	(segment
		(start 416.138106 -88.621108)
		(end 415.740342 -89.018872)
		(width 0.089408)
		(layer "In4.Cu")
		(net "SMB_LAN_STBY_LVC3_SCL")
	)
	(segment
		(start 406.349962 -89.038938)
		(end 404.747222 -87.436198)
		(width 0.089408)
		(layer "In4.Cu")
		(net "SMB_LAN_STBY_LVC3_SCL")
	)
	(segment
		(start 395.6177 -86.995762)
		(end 395.6177 -86.6394)
		(width 0.089408)
		(layer "In4.Cu")
		(net "SMB_LAN_STBY_LVC3_SCL")
	)
	(segment
		(start 404.747222 -87.436198)
		(end 402.456396 -87.436198)
		(width 0.089408)
		(layer "In4.Cu")
		(net "SMB_LAN_STBY_LVC3_SCL")
	)
	(segment
		(start 412.6992 -89.018872)
		(end 411.696154 -90.021918)
		(width 0.089408)
		(layer "In4.Cu")
		(net "SMB_LAN_STBY_LVC3_SCL")
	)
	(segment
		(start 411.193996 -90.021918)
		(end 410.203396 -89.038938)
		(width 0.089408)
		(layer "In4.Cu")
		(net "SMB_LAN_STBY_LVC3_SCL")
	)
	(segment
		(start 353.549712 -155.819602)
		(end 353.549712 -153.62936)
		(width 0.089408)
		(layer "In9.Cu")
		(net "SMB_LAN_STBY_LVC3_SCL")
	)
	(segment
		(start 402.05533 -155.779216)
		(end 402.772118 -156.496004)
		(width 0.089408)
		(layer "In9.Cu")
		(net "SMB_LAN_STBY_LVC3_SCL")
	)
	(segment
		(start 10.1346 -98.806)
		(end 10.1346 -102.035864)
		(width 0.089408)
		(layer "In9.Cu")
		(net "SMB_LAN_STBY_LVC3_SCL")
	)
	(segment
		(start 401.701 -74.683874)
		(end 401.157948 -75.226926)
		(width 0.089408)
		(layer "In9.Cu")
		(net "SMB_LAN_STBY_LVC3_SCL")
	)
	(segment
		(start 407.260298 -55.42407)
		(end 407.260298 -61.97473)
		(width 0.089408)
		(layer "In9.Cu")
		(net "SMB_LAN_STBY_LVC3_SCL")
	)
	(segment
		(start 437.595518 -127.9398)
		(end 436.253636 -127.9398)
		(width 0.089408)
		(layer "In9.Cu")
		(net "SMB_LAN_STBY_LVC3_SCL")
	)
	(segment
		(start 19.912838 -114.476784)
		(end 19.912838 -115.476782)
		(width 0.089408)
		(layer "In9.Cu")
		(net "SMB_LAN_STBY_LVC3_SCL")
	)
	(segment
		(start 425.31411 -116.722398)
		(end 425.31411 -116.199666)
		(width 0.089408)
		(layer "In9.Cu")
		(net "SMB_LAN_STBY_LVC3_SCL")
	)
	(segment
		(start 23.469092 -132.777992)
		(end 23.2791 -132.588)
		(width 0.089408)
		(layer "In9.Cu")
		(net "SMB_LAN_STBY_LVC3_SCL")
	)
	(segment
		(start 177.2666 -144.7038)
		(end 176.430432 -143.867632)
		(width 0.089408)
		(layer "In9.Cu")
		(net "SMB_LAN_STBY_LVC3_SCL")
	)
	(segment
		(start 413.585152 -47.897796)
		(end 413.103568 -47.897796)
		(width 0.089408)
		(layer "In9.Cu")
		(net "SMB_LAN_STBY_LVC3_SCL")
	)
	(segment
		(start 427.949614 -125.40869)
		(end 426.909738 -124.368814)
		(width 0.089408)
		(layer "In9.Cu")
		(net "SMB_LAN_STBY_LVC3_SCL")
	)
	(segment
		(start 449.065904 -153.09469)
		(end 449.065904 -151.655272)
		(width 0.089408)
		(layer "In9.Cu")
		(net "SMB_LAN_STBY_LVC3_SCL")
	)
	(segment
		(start 429.35017 -158.139892)
		(end 430.922176 -156.567886)
		(width 0.089408)
		(layer "In9.Cu")
		(net "SMB_LAN_STBY_LVC3_SCL")
	)
	(segment
		(start 411.948122 -48.26127)
		(end 410.610558 -49.598834)
		(width 0.089408)
		(layer "In9.Cu")
		(net "SMB_LAN_STBY_LVC3_SCL")
	)
	(segment
		(start 433.722526 -125.40869)
		(end 427.949614 -125.40869)
		(width 0.089408)
		(layer "In9.Cu")
		(net "SMB_LAN_STBY_LVC3_SCL")
	)
	(segment
		(start 440.303666 -130.02514)
		(end 439.764424 -130.02514)
		(width 0.089408)
		(layer "In9.Cu")
		(net "SMB_LAN_STBY_LVC3_SCL")
	)
	(segment
		(start 406.145746 -67.365372)
		(end 406.145746 -70.019672)
		(width 0.089408)
		(layer "In9.Cu")
		(net "SMB_LAN_STBY_LVC3_SCL")
	)
	(segment
		(start 14.0716 -105.972864)
		(end 14.0716 -108.635546)
		(width 0.089408)
		(layer "In9.Cu")
		(net "SMB_LAN_STBY_LVC3_SCL")
	)
	(segment
		(start 22.5298 -132.2324)
		(end 22.9235 -132.2324)
		(width 0.089408)
		(layer "In9.Cu")
		(net "SMB_LAN_STBY_LVC3_SCL")
	)
	(segment
		(start 410.610558 -49.598834)
		(end 410.610558 -50.495708)
		(width 0.089408)
		(layer "In9.Cu")
		(net "SMB_LAN_STBY_LVC3_SCL")
	)
	(segment
		(start 412.740094 -48.26127)
		(end 411.948122 -48.26127)
		(width 0.089408)
		(layer "In9.Cu")
		(net "SMB_LAN_STBY_LVC3_SCL")
	)
	(segment
		(start 350.882966 -157.413452)
		(end 351.477072 -156.819346)
		(width 0.089408)
		(layer "In9.Cu")
		(net "SMB_LAN_STBY_LVC3_SCL")
	)
	(segment
		(start 447.052192 -145.021808)
		(end 448.056 -144.018)
		(width 0.089408)
		(layer "In9.Cu")
		(net "SMB_LAN_STBY_LVC3_SCL")
	)
	(segment
		(start 20.885912 -130.588512)
		(end 22.5298 -132.2324)
		(width 0.089408)
		(layer "In9.Cu")
		(net "SMB_LAN_STBY_LVC3_SCL")
	)
	(segment
		(start 408.121358 -52.984908)
		(end 408.121358 -54.56301)
		(width 0.089408)
		(layer "In9.Cu")
		(net "SMB_LAN_STBY_LVC3_SCL")
	)
	(segment
		(start 426.339 -122.555)
		(end 426.339 -121.55805)
		(width 0.089408)
		(layer "In9.Cu")
		(net "SMB_LAN_STBY_LVC3_SCL")
	)
	(segment
		(start 399.986246 -155.779216)
		(end 402.05533 -155.779216)
		(width 0.089408)
		(layer "In9.Cu")
		(net "SMB_LAN_STBY_LVC3_SCL")
	)
	(segment
		(start 449.065904 -151.655272)
		(end 448.875912 -151.46528)
		(width 0.089408)
		(layer "In9.Cu")
		(net "SMB_LAN_STBY_LVC3_SCL")
	)
	(segment
		(start 426.897292 -123.113292)
		(end 426.339 -122.555)
		(width 0.089408)
		(layer "In9.Cu")
		(net "SMB_LAN_STBY_LVC3_SCL")
	)
	(segment
		(start 185.07964 -145.833592)
		(end 180.504592 -145.833592)
		(width 0.089408)
		(layer "In9.Cu")
		(net "SMB_LAN_STBY_LVC3_SCL")
	)
	(segment
		(start 414.34639 -47.136558)
		(end 413.585152 -47.897796)
		(width 0.089408)
		(layer "In9.Cu")
		(net "SMB_LAN_STBY_LVC3_SCL")
	)
	(segment
		(start 176.430432 -143.867632)
		(end 166.825168 -143.867632)
		(width 0.089408)
		(layer "In9.Cu")
		(net "SMB_LAN_STBY_LVC3_SCL")
	)
	(segment
		(start 21.37156 -127.043688)
		(end 21.37156 -128.96342)
		(width 0.089408)
		(layer "In9.Cu")
		(net "SMB_LAN_STBY_LVC3_SCL")
	)
	(segment
		(start 448.831462 -136.140698)
		(end 447.570606 -134.879842)
		(width 0.089408)
		(layer "In9.Cu")
		(net "SMB_LAN_STBY_LVC3_SCL")
	)
	(segment
		(start 397.528796 -82.064098)
		(end 397.528796 -84.371688)
		(width 0.089408)
		(layer "In9.Cu")
		(net "SMB_LAN_STBY_LVC3_SCL")
	)
	(segment
		(start 408.121358 -54.56301)
		(end 407.260298 -55.42407)
		(width 0.089408)
		(layer "In9.Cu")
		(net "SMB_LAN_STBY_LVC3_SCL")
	)
	(segment
		(start 2.0574 -97.6376)
		(end 8.9662 -97.6376)
		(width 0.089408)
		(layer "In9.Cu")
		(net "SMB_LAN_STBY_LVC3_SCL")
	)
	(segment
		(start 98.425254 -147.32)
		(end 96.938846 -145.833592)
		(width 0.089408)
		(layer "In9.Cu")
		(net "SMB_LAN_STBY_LVC3_SCL")
	)
	(segment
		(start 426.909738 -124.368814)
		(end 426.909738 -123.113292)
		(width 0.089408)
		(layer "In9.Cu")
		(net "SMB_LAN_STBY_LVC3_SCL")
	)
	(segment
		(start 8.9662 -97.6376)
		(end 10.1346 -98.806)
		(width 0.089408)
		(layer "In9.Cu")
		(net "SMB_LAN_STBY_LVC3_SCL")
	)
	(segment
		(start 397.38427 -84.516468)
		(end 395.6177 -86.283038)
		(width 0.089408)
		(layer "In9.Cu")
		(net "SMB_LAN_STBY_LVC3_SCL")
	)
	(segment
		(start 410.610558 -50.495708)
		(end 408.121358 -52.984908)
		(width 0.089408)
		(layer "In9.Cu")
		(net "SMB_LAN_STBY_LVC3_SCL")
	)
	(segment
		(start 259.625592 -148.19503)
		(end 259.274564 -147.844002)
		(width 0.089408)
		(layer "In9.Cu")
		(net "SMB_LAN_STBY_LVC3_SCL")
	)
	(segment
		(start 21.37156 -128.96342)
		(end 20.885912 -129.449068)
		(width 0.089408)
		(layer "In9.Cu")
		(net "SMB_LAN_STBY_LVC3_SCL")
	)
	(segment
		(start 322.845176 -149.219412)
		(end 321.397376 -147.771612)
		(width 0.089408)
		(layer "In9.Cu")
		(net "SMB_LAN_STBY_LVC3_SCL")
	)
	(segment
		(start 448.875912 -151.46528)
		(end 448.875912 -148.7424)
		(width 0.089408)
		(layer "In9.Cu")
		(net "SMB_LAN_STBY_LVC3_SCL")
	)
	(segment
		(start 259.274564 -147.844002)
		(end 192.92824 -147.844002)
		(width 0.089408)
		(layer "In9.Cu")
		(net "SMB_LAN_STBY_LVC3_SCL")
	)
	(segment
		(start 417.0172 -46.77664)
		(end 416.27171 -46.03115)
		(width 0.089408)
		(layer "In9.Cu")
		(net "SMB_LAN_STBY_LVC3_SCL")
	)
	(segment
		(start 357.95331 -151.3332)
		(end 358.568752 -150.717758)
		(width 0.089408)
		(layer "In9.Cu")
		(net "SMB_LAN_STBY_LVC3_SCL")
	)
	(segment
		(start 434.700426 -154.56027)
		(end 435.685438 -155.545282)
		(width 0.089408)
		(layer "In9.Cu")
		(net "SMB_LAN_STBY_LVC3_SCL")
	)
	(segment
		(start 448.831462 -140.190982)
		(end 448.831462 -136.140698)
		(width 0.089408)
		(layer "In9.Cu")
		(net "SMB_LAN_STBY_LVC3_SCL")
	)
	(segment
		(start 425.521882 -120.740932)
		(end 425.521882 -116.93017)
		(width 0.089408)
		(layer "In9.Cu")
		(net "SMB_LAN_STBY_LVC3_SCL")
	)
	(segment
		(start 28.9052 -147.066)
		(end 28.284424 -146.445224)
		(width 0.089408)
		(layer "In9.Cu")
		(net "SMB_LAN_STBY_LVC3_SCL")
	)
	(segment
		(start 402.772118 -156.496004)
		(end 405.186642 -156.496004)
		(width 0.089408)
		(layer "In9.Cu")
		(net "SMB_LAN_STBY_LVC3_SCL")
	)
	(segment
		(start 355.845872 -151.3332)
		(end 357.95331 -151.3332)
		(width 0.089408)
		(layer "In9.Cu")
		(net "SMB_LAN_STBY_LVC3_SCL")
	)
	(segment
		(start 439.764424 -130.02514)
		(end 437.900064 -128.16078)
		(width 0.089408)
		(layer "In9.Cu")
		(net "SMB_LAN_STBY_LVC3_SCL")
	)
	(segment
		(start 13.884148 -105.785412)
		(end 14.0716 -105.972864)
		(width 0.089408)
		(layer "In9.Cu")
		(net "SMB_LAN_STBY_LVC3_SCL")
	)
	(segment
		(start 393.98702 -157.000448)
		(end 398.765014 -157.000448)
		(width 0.089408)
		(layer "In9.Cu")
		(net "SMB_LAN_STBY_LVC3_SCL")
	)
	(segment
		(start 372.2751 -158.4071)
		(end 392.491976 -158.4071)
		(width 0.089408)
		(layer "In9.Cu")
		(net "SMB_LAN_STBY_LVC3_SCL")
	)
	(segment
		(start 10.1346 -102.035864)
		(end 13.884148 -105.785412)
		(width 0.089408)
		(layer "In9.Cu")
		(net "SMB_LAN_STBY_LVC3_SCL")
	)
	(segment
		(start 447.570606 -134.879842)
		(end 445.158368 -134.879842)
		(width 0.089408)
		(layer "In9.Cu")
		(net "SMB_LAN_STBY_LVC3_SCL")
	)
	(segment
		(start 325.7804 -147.574)
		(end 324.134988 -149.219412)
		(width 0.089408)
		(layer "In9.Cu")
		(net "SMB_LAN_STBY_LVC3_SCL")
	)
	(segment
		(start 20.885912 -129.449068)
		(end 20.885912 -130.588512)
		(width 0.089408)
		(layer "In9.Cu")
		(net "SMB_LAN_STBY_LVC3_SCL")
	)
	(segment
		(start 398.765014 -157.000448)
		(end 399.986246 -155.779216)
		(width 0.089408)
		(layer "In9.Cu")
		(net "SMB_LAN_STBY_LVC3_SCL")
	)
	(segment
		(start 165.697408 -144.995392)
		(end 164.757608 -144.995392)
		(width 0.089408)
		(layer "In9.Cu")
		(net "SMB_LAN_STBY_LVC3_SCL")
	)
	(segment
		(start 333.876904 -157.353254)
		(end 333.937102 -157.413452)
		(width 0.089408)
		(layer "In9.Cu")
		(net "SMB_LAN_STBY_LVC3_SCL")
	)
	(segment
		(start 371.19941 -157.33141)
		(end 372.2751 -158.4071)
		(width 0.089408)
		(layer "In9.Cu")
		(net "SMB_LAN_STBY_LVC3_SCL")
	)
	(segment
		(start 392.764518 -158.22295)
		(end 393.98702 -157.000448)
		(width 0.089408)
		(layer "In9.Cu")
		(net "SMB_LAN_STBY_LVC3_SCL")
	)
	(segment
		(start 166.825168 -143.867632)
		(end 165.697408 -144.995392)
		(width 0.089408)
		(layer "In9.Cu")
		(net "SMB_LAN_STBY_LVC3_SCL")
	)
	(segment
		(start 400.08048 -77.995526)
		(end 400.08048 -79.512414)
		(width 0.089408)
		(layer "In9.Cu")
		(net "SMB_LAN_STBY_LVC3_SCL")
	)
	(segment
		(start 19.912838 -115.476782)
		(end 20.885912 -116.449856)
		(width 0.089408)
		(layer "In9.Cu")
		(net "SMB_LAN_STBY_LVC3_SCL")
	)
	(segment
		(start 395.6177 -86.283038)
		(end 395.6177 -86.6394)
		(width 0.089408)
		(layer "In9.Cu")
		(net "SMB_LAN_STBY_LVC3_SCL")
	)
	(segment
		(start 321.397376 -147.771612)
		(end 262.230108 -147.771612)
		(width 0.089408)
		(layer "In9.Cu")
		(net "SMB_LAN_STBY_LVC3_SCL")
	)
	(segment
		(start 25.127458 -132.777992)
		(end 23.469092 -132.777992)
		(width 0.089408)
		(layer "In9.Cu")
		(net "SMB_LAN_STBY_LVC3_SCL")
	)
	(segment
		(start 432.382676 -154.56027)
		(end 434.700426 -154.56027)
		(width 0.089408)
		(layer "In9.Cu")
		(net "SMB_LAN_STBY_LVC3_SCL")
	)
	(segment
		(start 14.0716 -108.635546)
		(end 19.912838 -114.476784)
		(width 0.089408)
		(layer "In9.Cu")
		(net "SMB_LAN_STBY_LVC3_SCL")
	)
	(segment
		(start 446.14338 -155.545536)
		(end 446.143634 -155.545282)
		(width 0.089408)
		(layer "In9.Cu")
		(net "SMB_LAN_STBY_LVC3_SCL")
	)
	(segment
		(start 353.549712 -153.62936)
		(end 355.845872 -151.3332)
		(width 0.089408)
		(layer "In9.Cu")
		(net "SMB_LAN_STBY_LVC3_SCL")
	)
	(segment
		(start 178.1048 -144.7038)
		(end 177.2666 -144.7038)
		(width 0.089408)
		(layer "In9.Cu")
		(net "SMB_LAN_STBY_LVC3_SCL")
	)
	(segment
		(start 401.157948 -75.226926)
		(end 401.157948 -76.918058)
		(width 0.089408)
		(layer "In9.Cu")
		(net "SMB_LAN_STBY_LVC3_SCL")
	)
	(segment
		(start 414.969706 -46.03115)
		(end 414.34639 -46.654466)
		(width 0.089408)
		(layer "In9.Cu")
		(net "SMB_LAN_STBY_LVC3_SCL")
	)
	(segment
		(start 435.685438 -155.545282)
		(end 445.985138 -155.545282)
		(width 0.089408)
		(layer "In9.Cu")
		(net "SMB_LAN_STBY_LVC3_SCL")
	)
	(segment
		(start 426.339 -121.55805)
		(end 425.521882 -120.740932)
		(width 0.089408)
		(layer "In9.Cu")
		(net "SMB_LAN_STBY_LVC3_SCL")
	)
	(segment
		(start 406.410922 -67.100196)
		(end 406.145746 -67.365372)
		(width 0.089408)
		(layer "In9.Cu")
		(net "SMB_LAN_STBY_LVC3_SCL")
	)
	(segment
		(start 406.145746 -70.019672)
		(end 401.701 -74.464418)
		(width 0.089408)
		(layer "In9.Cu")
		(net "SMB_LAN_STBY_LVC3_SCL")
	)
	(segment
		(start 407.661364 -62.376812)
		(end 407.661364 -66.274188)
		(width 0.089408)
		(layer "In9.Cu")
		(net "SMB_LAN_STBY_LVC3_SCL")
	)
	(segment
		(start 437.819546 -128.159764)
		(end 437.815482 -128.159764)
		(width 0.089408)
		(layer "In9.Cu")
		(net "SMB_LAN_STBY_LVC3_SCL")
	)
	(segment
		(start 28.284424 -135.934958)
		(end 25.127458 -132.777992)
		(width 0.089408)
		(layer "In9.Cu")
		(net "SMB_LAN_STBY_LVC3_SCL")
	)
	(segment
		(start 414.34639 -46.654466)
		(end 414.34639 -47.136558)
		(width 0.089408)
		(layer "In9.Cu")
		(net "SMB_LAN_STBY_LVC3_SCL")
	)
	(segment
		(start 157.764988 -147.32)
		(end 98.425254 -147.32)
		(width 0.089408)
		(layer "In9.Cu")
		(net "SMB_LAN_STBY_LVC3_SCL")
	)
	(segment
		(start 262.230108 -147.771612)
		(end 261.80669 -148.19503)
		(width 0.089408)
		(layer "In9.Cu")
		(net "SMB_LAN_STBY_LVC3_SCL")
	)
	(segment
		(start 416.27171 -46.03115)
		(end 414.969706 -46.03115)
		(width 0.089408)
		(layer "In9.Cu")
		(net "SMB_LAN_STBY_LVC3_SCL")
	)
	(segment
		(start 400.08048 -79.512414)
		(end 397.528796 -82.064098)
		(width 0.089408)
		(layer "In9.Cu")
		(net "SMB_LAN_STBY_LVC3_SCL")
	)
	(segment
		(start 365.58347 -157.33141)
		(end 371.19941 -157.33141)
		(width 0.089408)
		(layer "In9.Cu")
		(net "SMB_LAN_STBY_LVC3_SCL")
	)
	(segment
		(start 158.171388 -146.9136)
		(end 157.764988 -147.32)
		(width 0.089408)
		(layer "In9.Cu")
		(net "SMB_LAN_STBY_LVC3_SCL")
	)
	(segment
		(start 417.0172 -46.8376)
		(end 417.0172 -46.77664)
		(width 0.089408)
		(layer "In9.Cu")
		(net "SMB_LAN_STBY_LVC3_SCL")
	)
	(segment
		(start 178.3334 -144.4752)
		(end 178.1048 -144.7038)
		(width 0.089408)
		(layer "In9.Cu")
		(net "SMB_LAN_STBY_LVC3_SCL")
	)
	(segment
		(start 445.985392 -155.545536)
		(end 446.14338 -155.545536)
		(width 0.089408)
		(layer "In9.Cu")
		(net "SMB_LAN_STBY_LVC3_SCL")
	)
	(segment
		(start 352.549968 -156.819346)
		(end 353.549712 -155.819602)
		(width 0.089408)
		(layer "In9.Cu")
		(net "SMB_LAN_STBY_LVC3_SCL")
	)
	(segment
		(start 401.157948 -76.918058)
		(end 400.08048 -77.995526)
		(width 0.089408)
		(layer "In9.Cu")
		(net "SMB_LAN_STBY_LVC3_SCL")
	)
	(segment
		(start 413.103568 -47.897796)
		(end 412.740094 -48.26127)
		(width 0.089408)
		(layer "In9.Cu")
		(net "SMB_LAN_STBY_LVC3_SCL")
	)
	(segment
		(start 20.885912 -116.449856)
		(end 20.885912 -126.55804)
		(width 0.089408)
		(layer "In9.Cu")
		(net "SMB_LAN_STBY_LVC3_SCL")
	)
	(segment
		(start 96.938846 -145.833592)
		(end 94.577662 -145.833592)
		(width 0.089408)
		(layer "In9.Cu")
		(net "SMB_LAN_STBY_LVC3_SCL")
	)
	(segment
		(start 22.9235 -132.2324)
		(end 23.2791 -132.588)
		(width 0.089408)
		(layer "In9.Cu")
		(net "SMB_LAN_STBY_LVC3_SCL")
	)
	(segment
		(start 437.815482 -128.159764)
		(end 437.595518 -127.9398)
		(width 0.089408)
		(layer "In9.Cu")
		(net "SMB_LAN_STBY_LVC3_SCL")
	)
	(segment
		(start 392.491976 -158.4071)
		(end 392.676126 -158.22295)
		(width 0.089408)
		(layer "In9.Cu")
		(net "SMB_LAN_STBY_LVC3_SCL")
	)
	(segment
		(start 425.521882 -116.93017)
		(end 425.31411 -116.722398)
		(width 0.089408)
		(layer "In9.Cu")
		(net "SMB_LAN_STBY_LVC3_SCL")
	)
	(segment
		(start 20.885912 -126.55804)
		(end 21.37156 -127.043688)
		(width 0.089408)
		(layer "In9.Cu")
		(net "SMB_LAN_STBY_LVC3_SCL")
	)
	(segment
		(start 448.056 -144.018)
		(end 448.056 -140.966444)
		(width 0.089408)
		(layer "In9.Cu")
		(net "SMB_LAN_STBY_LVC3_SCL")
	)
	(segment
		(start 162.8394 -146.9136)
		(end 158.171388 -146.9136)
		(width 0.089408)
		(layer "In9.Cu")
		(net "SMB_LAN_STBY_LVC3_SCL")
	)
	(segment
		(start 1.700022 -97.280222)
		(end 2.0574 -97.6376)
		(width 0.089408)
		(layer "In9.Cu")
		(net "SMB_LAN_STBY_LVC3_SCL")
	)
	(segment
		(start 426.909738 -123.113292)
		(end 426.897292 -123.113292)
		(width 0.089408)
		(layer "In9.Cu")
		(net "SMB_LAN_STBY_LVC3_SCL")
	)
	(segment
		(start 446.143634 -155.545282)
		(end 446.615312 -155.545282)
		(width 0.089408)
		(layer "In9.Cu")
		(net "SMB_LAN_STBY_LVC3_SCL")
	)
	(segment
		(start 448.056 -140.966444)
		(end 448.831462 -140.190982)
		(width 0.089408)
		(layer "In9.Cu")
		(net "SMB_LAN_STBY_LVC3_SCL")
	)
	(segment
		(start 430.922176 -156.567886)
		(end 430.922176 -156.02077)
		(width 0.089408)
		(layer "In9.Cu")
		(net "SMB_LAN_STBY_LVC3_SCL")
	)
	(segment
		(start 358.568752 -150.717758)
		(end 362.343954 -150.717758)
		(width 0.089408)
		(layer "In9.Cu")
		(net "SMB_LAN_STBY_LVC3_SCL")
	)
	(segment
		(start 178.5874 -144.7292)
		(end 178.3334 -144.4752)
		(width 0.089408)
		(layer "In9.Cu")
		(net "SMB_LAN_STBY_LVC3_SCL")
	)
	(segment
		(start 351.477072 -156.819346)
		(end 352.549968 -156.819346)
		(width 0.089408)
		(layer "In9.Cu")
		(net "SMB_LAN_STBY_LVC3_SCL")
	)
	(segment
		(start 324.134988 -149.219412)
		(end 322.845176 -149.219412)
		(width 0.089408)
		(layer "In9.Cu")
		(net "SMB_LAN_STBY_LVC3_SCL")
	)
	(segment
		(start 364.968282 -153.342086)
		(end 364.968282 -156.716222)
		(width 0.089408)
		(layer "In9.Cu")
		(net "SMB_LAN_STBY_LVC3_SCL")
	)
	(segment
		(start 364.968282 -156.716222)
		(end 365.58347 -157.33141)
		(width 0.089408)
		(layer "In9.Cu")
		(net "SMB_LAN_STBY_LVC3_SCL")
	)
	(segment
		(start 333.937102 -157.413452)
		(end 350.882966 -157.413452)
		(width 0.089408)
		(layer "In9.Cu")
		(net "SMB_LAN_STBY_LVC3_SCL")
	)
	(segment
		(start 448.875912 -148.7424)
		(end 447.052192 -146.91868)
		(width 0.089408)
		(layer "In9.Cu")
		(net "SMB_LAN_STBY_LVC3_SCL")
	)
	(segment
		(start 447.052192 -146.91868)
		(end 447.052192 -145.021808)
		(width 0.089408)
		(layer "In9.Cu")
		(net "SMB_LAN_STBY_LVC3_SCL")
	)
	(segment
		(start 186.870848 -147.6248)
		(end 185.07964 -145.833592)
		(width 0.089408)
		(layer "In9.Cu")
		(net "SMB_LAN_STBY_LVC3_SCL")
	)
	(segment
		(start 192.709038 -147.6248)
		(end 186.870848 -147.6248)
		(width 0.089408)
		(layer "In9.Cu")
		(net "SMB_LAN_STBY_LVC3_SCL")
	)
	(segment
		(start 392.676126 -158.22295)
		(end 392.764518 -158.22295)
		(width 0.089408)
		(layer "In9.Cu")
		(net "SMB_LAN_STBY_LVC3_SCL")
	)
	(segment
		(start 407.260298 -61.97473)
		(end 407.661364 -62.376812)
		(width 0.089408)
		(layer "In9.Cu")
		(net "SMB_LAN_STBY_LVC3_SCL")
	)
	(segment
		(start 406.835356 -67.100196)
		(end 406.410922 -67.100196)
		(width 0.089408)
		(layer "In9.Cu")
		(net "SMB_LAN_STBY_LVC3_SCL")
	)
	(segment
		(start 401.701 -74.464418)
		(end 401.701 -74.683874)
		(width 0.089408)
		(layer "In9.Cu")
		(net "SMB_LAN_STBY_LVC3_SCL")
	)
	(segment
		(start 425.31411 -116.199666)
		(end 425.638976 -115.8748)
		(width 0.089408)
		(layer "In9.Cu")
		(net "SMB_LAN_STBY_LVC3_SCL")
	)
	(segment
		(start 445.985138 -155.545282)
		(end 445.985392 -155.545536)
		(width 0.089408)
		(layer "In9.Cu")
		(net "SMB_LAN_STBY_LVC3_SCL")
	)
	(segment
		(start 437.820562 -128.16078)
		(end 437.819546 -128.159764)
		(width 0.089408)
		(layer "In9.Cu")
		(net "SMB_LAN_STBY_LVC3_SCL")
	)
	(segment
		(start 437.900064 -128.16078)
		(end 437.820562 -128.16078)
		(width 0.089408)
		(layer "In9.Cu")
		(net "SMB_LAN_STBY_LVC3_SCL")
	)
	(segment
		(start 93.345254 -147.066)
		(end 28.9052 -147.066)
		(width 0.089408)
		(layer "In9.Cu")
		(net "SMB_LAN_STBY_LVC3_SCL")
	)
	(segment
		(start 261.80669 -148.19503)
		(end 259.625592 -148.19503)
		(width 0.089408)
		(layer "In9.Cu")
		(net "SMB_LAN_STBY_LVC3_SCL")
	)
	(segment
		(start 445.158368 -134.879842)
		(end 440.303666 -130.02514)
		(width 0.089408)
		(layer "In9.Cu")
		(net "SMB_LAN_STBY_LVC3_SCL")
	)
	(segment
		(start 436.253636 -127.9398)
		(end 433.722526 -125.40869)
		(width 0.089408)
		(layer "In9.Cu")
		(net "SMB_LAN_STBY_LVC3_SCL")
	)
	(segment
		(start 28.284424 -146.445224)
		(end 28.284424 -135.934958)
		(width 0.089408)
		(layer "In9.Cu")
		(net "SMB_LAN_STBY_LVC3_SCL")
	)
	(segment
		(start 430.922176 -156.02077)
		(end 432.382676 -154.56027)
		(width 0.089408)
		(layer "In9.Cu")
		(net "SMB_LAN_STBY_LVC3_SCL")
	)
	(segment
		(start 94.577662 -145.833592)
		(end 93.345254 -147.066)
		(width 0.089408)
		(layer "In9.Cu")
		(net "SMB_LAN_STBY_LVC3_SCL")
	)
	(segment
		(start 180.504592 -145.833592)
		(end 179.4002 -144.7292)
		(width 0.089408)
		(layer "In9.Cu")
		(net "SMB_LAN_STBY_LVC3_SCL")
	)
	(segment
		(start 406.83053 -158.139892)
		(end 429.35017 -158.139892)
		(width 0.089408)
		(layer "In9.Cu")
		(net "SMB_LAN_STBY_LVC3_SCL")
	)
	(segment
		(start 1.700022 -96.769936)
		(end 1.700022 -97.280222)
		(width 0.089408)
		(layer "In9.Cu")
		(net "SMB_LAN_STBY_LVC3_SCL")
	)
	(segment
		(start 362.343954 -150.717758)
		(end 364.968282 -153.342086)
		(width 0.089408)
		(layer "In9.Cu")
		(net "SMB_LAN_STBY_LVC3_SCL")
	)
	(segment
		(start 164.757608 -144.995392)
		(end 162.8394 -146.9136)
		(width 0.089408)
		(layer "In9.Cu")
		(net "SMB_LAN_STBY_LVC3_SCL")
	)
	(segment
		(start 179.4002 -144.7292)
		(end 178.5874 -144.7292)
		(width 0.089408)
		(layer "In9.Cu")
		(net "SMB_LAN_STBY_LVC3_SCL")
	)
	(segment
		(start 397.528796 -84.371688)
		(end 397.38427 -84.516468)
		(width 0.089408)
		(layer "In9.Cu")
		(net "SMB_LAN_STBY_LVC3_SCL")
	)
	(segment
		(start 405.186642 -156.496004)
		(end 406.83053 -158.139892)
		(width 0.089408)
		(layer "In9.Cu")
		(net "SMB_LAN_STBY_LVC3_SCL")
	)
	(segment
		(start 192.92824 -147.844002)
		(end 192.709038 -147.6248)
		(width 0.089408)
		(layer "In9.Cu")
		(net "SMB_LAN_STBY_LVC3_SCL")
	)
	(segment
		(start 407.661364 -66.274188)
		(end 406.835356 -67.100196)
		(width 0.089408)
		(layer "In9.Cu")
		(net "SMB_LAN_STBY_LVC3_SCL")
	)
	(segment
		(start 446.615312 -155.545282)
		(end 449.065904 -153.09469)
		(width 0.089408)
		(layer "In9.Cu")
		(net "SMB_LAN_STBY_LVC3_SCL")
	)
	(via
		(at 362.069126 -60.916566)
		(size 0.6604)
		(drill 0.3302)
		(layers "F.Cu" "B.Cu")
		(net "PWRGD_CPUPWRGD_R1")
	)
	(segment
		(start 362.069126 -60.916566)
		(end 362.757212 -60.22848)
		(width 0.10795)
		(layer "B.Cu")
		(net "PWRGD_CPUPWRGD_R1")
	)
	(segment
		(start 365.76 -62.2935)
		(end 365.76 -60.59678)
		(width 0.10795)
		(layer "B.Cu")
		(net "PWRGD_CPUPWRGD_R1")
	)
	(segment
		(start 365.3917 -60.22848)
		(end 364.4265 -60.22848)
		(width 0.10795)
		(layer "B.Cu")
		(net "PWRGD_CPUPWRGD_R1")
	)
	(segment
		(start 365.76 -60.59678)
		(end 365.3917 -60.22848)
		(width 0.10795)
		(layer "B.Cu")
		(net "PWRGD_CPUPWRGD_R1")
	)
	(segment
		(start 362.757212 -60.22848)
		(end 364.4265 -60.22848)
		(width 0.10795)
		(layer "B.Cu")
		(net "PWRGD_CPUPWRGD_R1")
	)
	(segment
		(start 379.414024 -93.42501)
		(end 379.414024 -91.39555)
		(width 0.10795)
		(layer "F.Cu")
		(net "PU_FM_RCIN_N")
	)
	(segment
		(start 379.86208 -93.873066)
		(end 379.598174 -93.60916)
		(width 0.0889)
		(layer "F.Cu")
		(net "PU_FM_RCIN_N")
	)
	(segment
		(start 379.86208 -94.252034)
		(end 379.86208 -93.873066)
		(width 0.0889)
		(layer "F.Cu")
		(net "PU_FM_RCIN_N")
	)
	(segment
		(start 379.598174 -93.60916)
		(end 379.414024 -93.42501)
		(width 0.10795)
		(layer "F.Cu")
		(net "PU_FM_RCIN_N")
	)
	(segment
		(start 378.46 -88.319356)
		(end 378.46 -88.2015)
		(width 0.10795)
		(layer "F.Cu")
		(net "PU_FM_RCIN_N")
	)
	(segment
		(start 379.985016 -94.37497)
		(end 379.86208 -94.252034)
		(width 0.0889)
		(layer "F.Cu")
		(net "PU_FM_RCIN_N")
	)
	(segment
		(start 378.920756 -90.902282)
		(end 378.920756 -88.780112)
		(width 0.10795)
		(layer "F.Cu")
		(net "PU_FM_RCIN_N")
	)
	(segment
		(start 378.920756 -88.780112)
		(end 378.46 -88.319356)
		(width 0.10795)
		(layer "F.Cu")
		(net "PU_FM_RCIN_N")
	)
	(segment
		(start 379.414024 -91.39555)
		(end 378.920756 -90.902282)
		(width 0.10795)
		(layer "F.Cu")
		(net "PU_FM_RCIN_N")
	)
	(segment
		(start 370.290852 -47.14748)
		(end 370.290852 -46.788578)
		(width 0.10795)
		(layer "B.Cu")
		(net "PD_GTL2104_4_DIR")
	)
	(segment
		(start 369.864386 -47.827184)
		(end 369.864386 -47.573946)
		(width 0.10795)
		(layer "B.Cu")
		(net "PD_GTL2104_4_DIR")
	)
	(segment
		(start 369.864386 -47.573946)
		(end 370.290852 -47.14748)
		(width 0.10795)
		(layer "B.Cu")
		(net "PD_GTL2104_4_DIR")
	)
	(segment
		(start 373.8753 -44.8818)
		(end 373.3419 -45.4152)
		(width 0.254)
		(layer "B.Cu")
		(net "P0V7_GTL2104_5_VREF")
	)
	(segment
		(start 375.0945 -44.701968)
		(end 375.0945 -44.9072)
		(width 0.254)
		(layer "B.Cu")
		(net "P0V7_GTL2104_5_VREF")
	)
	(segment
		(start 375.575068 -44.433236)
		(end 375.363232 -44.433236)
		(width 0.254)
		(layer "B.Cu")
		(net "P0V7_GTL2104_5_VREF")
	)
	(segment
		(start 375.363232 -44.433236)
		(end 375.0945 -44.701968)
		(width 0.254)
		(layer "B.Cu")
		(net "P0V7_GTL2104_5_VREF")
	)
	(segment
		(start 372.5418 -45.4152)
		(end 371.964458 -44.837858)
		(width 0.254)
		(layer "B.Cu")
		(net "P0V7_GTL2104_5_VREF")
	)
	(segment
		(start 375.761504 -44.2468)
		(end 375.575068 -44.433236)
		(width 0.254)
		(layer "B.Cu")
		(net "P0V7_GTL2104_5_VREF")
	)
	(segment
		(start 373.3419 -45.4152)
		(end 372.5418 -45.4152)
		(width 0.254)
		(layer "B.Cu")
		(net "P0V7_GTL2104_5_VREF")
	)
	(segment
		(start 376.9614 -44.2468)
		(end 375.761504 -44.2468)
		(width 0.254)
		(layer "B.Cu")
		(net "P0V7_GTL2104_5_VREF")
	)
	(segment
		(start 371.964458 -44.837858)
		(end 370.290852 -44.837858)
		(width 0.254)
		(layer "B.Cu")
		(net "P0V7_GTL2104_5_VREF")
	)
	(segment
		(start 375.0945 -45.72)
		(end 374.7135 -45.72)
		(width 0.254)
		(layer "B.Cu")
		(net "P0V7_GTL2104_5_VREF")
	)
	(segment
		(start 375.0945 -45.72)
		(end 375.0945 -44.9072)
		(width 0.254)
		(layer "B.Cu")
		(net "P0V7_GTL2104_5_VREF")
	)
	(segment
		(start 374.7135 -45.72)
		(end 373.8753 -44.8818)
		(width 0.254)
		(layer "B.Cu")
		(net "P0V7_GTL2104_5_VREF")
	)
	(segment
		(start 481.336604 -52.01539)
		(end 479.485198 -50.163984)
		(width 0.10795)
		(layer "F.Cu")
		(net "LED_LAN_2_N")
	)
	(segment
		(start 479.8822 -47.717456)
		(end 479.8822 -47.938944)
		(width 0.10795)
		(layer "F.Cu")
		(net "LED_LAN_2_N")
	)
	(segment
		(start 479.485198 -50.163984)
		(end 479.485198 -49.9364)
		(width 0.10795)
		(layer "F.Cu")
		(net "LED_LAN_2_N")
	)
	(segment
		(start 481.485956 -52.01539)
		(end 481.336604 -52.01539)
		(width 0.10795)
		(layer "F.Cu")
		(net "LED_LAN_2_N")
	)
	(segment
		(start 479.485198 -48.335946)
		(end 479.485198 -49.9364)
		(width 0.10795)
		(layer "F.Cu")
		(net "LED_LAN_2_N")
	)
	(segment
		(start 479.8822 -47.938944)
		(end 479.485198 -48.335946)
		(width 0.10795)
		(layer "F.Cu")
		(net "LED_LAN_2_N")
	)
	(via
		(at 487.0704 -16.764)
		(size 0.508)
		(drill 0.254)
		(layers "F.Cu" "B.Cu")
		(net "LED_LAN_2_N")
	)
	(via
		(at 479.485198 -49.9364)
		(size 0.762)
		(drill 0.381)
		(layers "F.Cu" "B.Cu")
		(net "LED_LAN_2_N")
	)
	(via
		(at 481.485956 -52.01539)
		(size 0.508)
		(drill 0.254)
		(layers "F.Cu" "B.Cu")
		(net "LED_LAN_2_N")
	)
	(segment
		(start 486.08488 -16.764)
		(end 484.914702 -17.934178)
		(width 0.10795)
		(layer "B.Cu")
		(net "LED_LAN_2_N")
	)
	(segment
		(start 484.691944 -17.934178)
		(end 484.691944 -17.054322)
		(width 0.10795)
		(layer "B.Cu")
		(net "LED_LAN_2_N")
	)
	(segment
		(start 484.914702 -17.934178)
		(end 484.691944 -17.934178)
		(width 0.10795)
		(layer "B.Cu")
		(net "LED_LAN_2_N")
	)
	(segment
		(start 487.0704 -16.764)
		(end 486.08488 -16.764)
		(width 0.10795)
		(layer "B.Cu")
		(net "LED_LAN_2_N")
	)
	(segment
		(start 484.691944 -17.054322)
		(end 484.674164 -17.036542)
		(width 0.10795)
		(layer "B.Cu")
		(net "LED_LAN_2_N")
	)
	(segment
		(start 498.042184 -27.126438)
		(end 493.9284 -27.126438)
		(width 0.089408)
		(layer "In4.Cu")
		(net "LED_LAN_2_N")
	)
	(segment
		(start 492.684562 -25.8826)
		(end 490.982 -25.8826)
		(width 0.089408)
		(layer "In4.Cu")
		(net "LED_LAN_2_N")
	)
	(segment
		(start 488.779312 -17.364456)
		(end 488.064048 -16.649192)
		(width 0.089408)
		(layer "In4.Cu")
		(net "LED_LAN_2_N")
	)
	(segment
		(start 500.412258 -37.896292)
		(end 500.412258 -29.496512)
		(width 0.089408)
		(layer "In4.Cu")
		(net "LED_LAN_2_N")
	)
	(segment
		(start 488.779312 -21.9964)
		(end 488.779312 -17.364456)
		(width 0.089408)
		(layer "In4.Cu")
		(net "LED_LAN_2_N")
	)
	(segment
		(start 490.557566 -25.458166)
		(end 490.557566 -23.774654)
		(width 0.089408)
		(layer "In4.Cu")
		(net "LED_LAN_2_N")
	)
	(segment
		(start 493.9284 -27.126438)
		(end 492.684562 -25.8826)
		(width 0.089408)
		(layer "In4.Cu")
		(net "LED_LAN_2_N")
	)
	(segment
		(start 501.085104 -40.323262)
		(end 501.085104 -38.569138)
		(width 0.089408)
		(layer "In4.Cu")
		(net "LED_LAN_2_N")
	)
	(segment
		(start 492.81207 -48.367696)
		(end 494.867946 -46.31182)
		(width 0.089408)
		(layer "In4.Cu")
		(net "LED_LAN_2_N")
	)
	(segment
		(start 487.185208 -16.649192)
		(end 487.0704 -16.764)
		(width 0.089408)
		(layer "In4.Cu")
		(net "LED_LAN_2_N")
	)
	(segment
		(start 500.412258 -29.496512)
		(end 498.042184 -27.126438)
		(width 0.089408)
		(layer "In4.Cu")
		(net "LED_LAN_2_N")
	)
	(segment
		(start 490.557566 -23.774654)
		(end 488.779312 -21.9964)
		(width 0.089408)
		(layer "In4.Cu")
		(net "LED_LAN_2_N")
	)
	(segment
		(start 494.867946 -42.561764)
		(end 495.811302 -41.618408)
		(width 0.089408)
		(layer "In4.Cu")
		(net "LED_LAN_2_N")
	)
	(segment
		(start 481.485956 -52.01539)
		(end 485.13365 -48.367696)
		(width 0.089408)
		(layer "In4.Cu")
		(net "LED_LAN_2_N")
	)
	(segment
		(start 499.789958 -41.618408)
		(end 501.085104 -40.323262)
		(width 0.089408)
		(layer "In4.Cu")
		(net "LED_LAN_2_N")
	)
	(segment
		(start 495.811302 -41.618408)
		(end 499.789958 -41.618408)
		(width 0.089408)
		(layer "In4.Cu")
		(net "LED_LAN_2_N")
	)
	(segment
		(start 501.085104 -38.569138)
		(end 500.412258 -37.896292)
		(width 0.089408)
		(layer "In4.Cu")
		(net "LED_LAN_2_N")
	)
	(segment
		(start 488.064048 -16.649192)
		(end 487.185208 -16.649192)
		(width 0.089408)
		(layer "In4.Cu")
		(net "LED_LAN_2_N")
	)
	(segment
		(start 494.867946 -46.31182)
		(end 494.867946 -42.561764)
		(width 0.089408)
		(layer "In4.Cu")
		(net "LED_LAN_2_N")
	)
	(segment
		(start 485.13365 -48.367696)
		(end 492.81207 -48.367696)
		(width 0.089408)
		(layer "In4.Cu")
		(net "LED_LAN_2_N")
	)
	(segment
		(start 490.982 -25.8826)
		(end 490.557566 -25.458166)
		(width 0.089408)
		(layer "In4.Cu")
		(net "LED_LAN_2_N")
	)
	(segment
		(start 480.970844 -50.420524)
		(end 480.970844 -49.92878)
		(width 0.10795)
		(layer "F.Cu")
		(net "LED_LAN_1_N")
	)
	(segment
		(start 481.500942 -48.3362)
		(end 481.500942 -48.813212)
		(width 0.10795)
		(layer "F.Cu")
		(net "LED_LAN_1_N")
	)
	(segment
		(start 480.970844 -49.34331)
		(end 480.970844 -49.92878)
		(width 0.10795)
		(layer "F.Cu")
		(net "LED_LAN_1_N")
	)
	(segment
		(start 481.3554 -51.24958)
		(end 481.3554 -50.80508)
		(width 0.10795)
		(layer "F.Cu")
		(net "LED_LAN_1_N")
	)
	(segment
		(start 481.500942 -48.813212)
		(end 480.970844 -49.34331)
		(width 0.10795)
		(layer "F.Cu")
		(net "LED_LAN_1_N")
	)
	(segment
		(start 481.3554 -50.80508)
		(end 480.970844 -50.420524)
		(width 0.10795)
		(layer "F.Cu")
		(net "LED_LAN_1_N")
	)
	(via
		(at 480.970844 -49.92878)
		(size 0.762)
		(drill 0.381)
		(layers "F.Cu" "B.Cu")
		(net "LED_LAN_1_N")
	)
	(via
		(at 481.3554 -51.24958)
		(size 0.508)
		(drill 0.254)
		(layers "F.Cu" "B.Cu")
		(net "LED_LAN_1_N")
	)
	(via
		(at 483.40264 4.931664)
		(size 0.508)
		(drill 0.254)
		(layers "F.Cu" "B.Cu")
		(net "LED_LAN_1_N")
	)
	(segment
		(start 481.957888 5.288534)
		(end 483.04577 5.288534)
		(width 0.10795)
		(layer "B.Cu")
		(net "LED_LAN_1_N")
	)
	(segment
		(start 479.95205 4.714748)
		(end 479.950526 4.716272)
		(width 0.10795)
		(layer "B.Cu")
		(net "LED_LAN_1_N")
	)
	(segment
		(start 479.950526 4.716272)
		(end 479.16211 4.716272)
		(width 0.10795)
		(layer "B.Cu")
		(net "LED_LAN_1_N")
	)
	(segment
		(start 479.95205 4.714748)
		(end 481.384102 4.714748)
		(width 0.10795)
		(layer "B.Cu")
		(net "LED_LAN_1_N")
	)
	(segment
		(start 483.04577 5.288534)
		(end 483.40264 4.931664)
		(width 0.10795)
		(layer "B.Cu")
		(net "LED_LAN_1_N")
	)
	(segment
		(start 481.384102 4.714748)
		(end 481.957888 5.288534)
		(width 0.10795)
		(layer "B.Cu")
		(net "LED_LAN_1_N")
	)
	(segment
		(start 500.183912 -40.877744)
		(end 500.183912 -29.538422)
		(width 0.089408)
		(layer "In4.Cu")
		(net "LED_LAN_1_N")
	)
	(segment
		(start 481.957126 -51.24958)
		(end 485.055164 -48.151542)
		(width 0.089408)
		(layer "In4.Cu")
		(net "LED_LAN_1_N")
	)
	(segment
		(start 497.962936 -27.317446)
		(end 491.898686 -27.317446)
		(width 0.089408)
		(layer "In4.Cu")
		(net "LED_LAN_1_N")
	)
	(segment
		(start 483.40264 3.825748)
		(end 483.40264 4.931664)
		(width 0.089408)
		(layer "In4.Cu")
		(net "LED_LAN_1_N")
	)
	(segment
		(start 487.3244 -17.1704)
		(end 484.44912 -17.1704)
		(width 0.089408)
		(layer "In4.Cu")
		(net "LED_LAN_1_N")
	)
	(segment
		(start 481.3554 -51.24958)
		(end 481.957126 -51.24958)
		(width 0.089408)
		(layer "In4.Cu")
		(net "LED_LAN_1_N")
	)
	(segment
		(start 480.347274 -13.068554)
		(end 480.347274 1.237996)
		(width 0.089408)
		(layer "In4.Cu")
		(net "LED_LAN_1_N")
	)
	(segment
		(start 500.183912 -29.538422)
		(end 497.962936 -27.317446)
		(width 0.089408)
		(layer "In4.Cu")
		(net "LED_LAN_1_N")
	)
	(segment
		(start 490.16412 -25.58288)
		(end 490.16412 -23.851616)
		(width 0.089408)
		(layer "In4.Cu")
		(net "LED_LAN_1_N")
	)
	(segment
		(start 488.588304 -17.443704)
		(end 487.9848 -16.8402)
		(width 0.089408)
		(layer "In4.Cu")
		(net "LED_LAN_1_N")
	)
	(segment
		(start 484.44912 -17.1704)
		(end 480.347274 -13.068554)
		(width 0.089408)
		(layer "In4.Cu")
		(net "LED_LAN_1_N")
	)
	(segment
		(start 495.744246 -41.415208)
		(end 499.646448 -41.415208)
		(width 0.089408)
		(layer "In4.Cu")
		(net "LED_LAN_1_N")
	)
	(segment
		(start 491.538768 -48.151542)
		(end 494.577116 -45.113194)
		(width 0.089408)
		(layer "In4.Cu")
		(net "LED_LAN_1_N")
	)
	(segment
		(start 494.577116 -45.113194)
		(end 494.577116 -42.582338)
		(width 0.089408)
		(layer "In4.Cu")
		(net "LED_LAN_1_N")
	)
	(segment
		(start 490.16412 -23.851616)
		(end 488.588304 -22.2758)
		(width 0.089408)
		(layer "In4.Cu")
		(net "LED_LAN_1_N")
	)
	(segment
		(start 487.9848 -16.8402)
		(end 487.6546 -16.8402)
		(width 0.089408)
		(layer "In4.Cu")
		(net "LED_LAN_1_N")
	)
	(segment
		(start 482.679502 3.10261)
		(end 483.40264 3.825748)
		(width 0.089408)
		(layer "In4.Cu")
		(net "LED_LAN_1_N")
	)
	(segment
		(start 487.6546 -16.8402)
		(end 487.3244 -17.1704)
		(width 0.089408)
		(layer "In4.Cu")
		(net "LED_LAN_1_N")
	)
	(segment
		(start 499.646448 -41.415208)
		(end 500.183912 -40.877744)
		(width 0.089408)
		(layer "In4.Cu")
		(net "LED_LAN_1_N")
	)
	(segment
		(start 485.055164 -48.151542)
		(end 491.538768 -48.151542)
		(width 0.089408)
		(layer "In4.Cu")
		(net "LED_LAN_1_N")
	)
	(segment
		(start 480.347274 1.237996)
		(end 482.211888 3.10261)
		(width 0.089408)
		(layer "In4.Cu")
		(net "LED_LAN_1_N")
	)
	(segment
		(start 488.588304 -22.2758)
		(end 488.588304 -17.443704)
		(width 0.089408)
		(layer "In4.Cu")
		(net "LED_LAN_1_N")
	)
	(segment
		(start 482.211888 3.10261)
		(end 482.679502 3.10261)
		(width 0.089408)
		(layer "In4.Cu")
		(net "LED_LAN_1_N")
	)
	(segment
		(start 491.898686 -27.317446)
		(end 490.16412 -25.58288)
		(width 0.089408)
		(layer "In4.Cu")
		(net "LED_LAN_1_N")
	)
	(segment
		(start 494.577116 -42.582338)
		(end 495.744246 -41.415208)
		(width 0.089408)
		(layer "In4.Cu")
		(net "LED_LAN_1_N")
	)
	(segment
		(start 480.27082 -49.59858)
		(end 480.27082 -50.32756)
		(width 0.10795)
		(layer "F.Cu")
		(net "LED_LAN_0_N")
	)
	(segment
		(start 481.00107 -48.3362)
		(end 481.00107 -48.86833)
		(width 0.10795)
		(layer "F.Cu")
		(net "LED_LAN_0_N")
	)
	(segment
		(start 480.27082 -50.32756)
		(end 480.557332 -50.614072)
		(width 0.10795)
		(layer "F.Cu")
		(net "LED_LAN_0_N")
	)
	(segment
		(start 481.00107 -48.86833)
		(end 480.27082 -49.59858)
		(width 0.10795)
		(layer "F.Cu")
		(net "LED_LAN_0_N")
	)
	(segment
		(start 480.56546 -50.614072)
		(end 480.768914 -50.817526)
		(width 0.10795)
		(layer "F.Cu")
		(net "LED_LAN_0_N")
	)
	(segment
		(start 480.557332 -50.614072)
		(end 480.56546 -50.614072)
		(width 0.10795)
		(layer "F.Cu")
		(net "LED_LAN_0_N")
	)
	(via
		(at 480.768914 -50.817526)
		(size 0.508)
		(drill 0.254)
		(layers "F.Cu" "B.Cu")
		(net "LED_LAN_0_N")
	)
	(via
		(at 487.7562 -17.3482)
		(size 0.508)
		(drill 0.254)
		(layers "F.Cu" "B.Cu")
		(net "LED_LAN_0_N")
	)
	(segment
		(start 487.7562 -17.3482)
		(end 487.707178 -17.299178)
		(width 0.10795)
		(layer "B.Cu")
		(net "LED_LAN_0_N")
	)
	(segment
		(start 483.017322 -17.071594)
		(end 483.021894 -17.067022)
		(width 0.10795)
		(layer "B.Cu")
		(net "LED_LAN_0_N")
	)
	(segment
		(start 486.141268 -19.299428)
		(end 485.513634 -19.927062)
		(width 0.10795)
		(layer "B.Cu")
		(net "LED_LAN_0_N")
	)
	(segment
		(start 485.513634 -19.927062)
		(end 484.620824 -19.927062)
		(width 0.10795)
		(layer "B.Cu")
		(net "LED_LAN_0_N")
	)
	(segment
		(start 483.017322 -17.929606)
		(end 483.017322 -17.071594)
		(width 0.10795)
		(layer "B.Cu")
		(net "LED_LAN_0_N")
	)
	(segment
		(start 486.141268 -17.614392)
		(end 486.141268 -19.299428)
		(width 0.10795)
		(layer "B.Cu")
		(net "LED_LAN_0_N")
	)
	(segment
		(start 484.620824 -19.927062)
		(end 483.017322 -18.32356)
		(width 0.10795)
		(layer "B.Cu")
		(net "LED_LAN_0_N")
	)
	(segment
		(start 486.456482 -17.299178)
		(end 486.141268 -17.614392)
		(width 0.10795)
		(layer "B.Cu")
		(net "LED_LAN_0_N")
	)
	(segment
		(start 487.707178 -17.299178)
		(end 486.456482 -17.299178)
		(width 0.10795)
		(layer "B.Cu")
		(net "LED_LAN_0_N")
	)
	(segment
		(start 483.017322 -18.32356)
		(end 483.017322 -17.929606)
		(width 0.10795)
		(layer "B.Cu")
		(net "LED_LAN_0_N")
	)
	(segment
		(start 491.819438 -27.508454)
		(end 489.851192 -25.540208)
		(width 0.089408)
		(layer "In4.Cu")
		(net "LED_LAN_0_N")
	)
	(segment
		(start 488.321096 -17.913096)
		(end 487.7562 -17.3482)
		(width 0.089408)
		(layer "In4.Cu")
		(net "LED_LAN_0_N")
	)
	(segment
		(start 480.768914 -50.817526)
		(end 482.059234 -50.817526)
		(width 0.089408)
		(layer "In4.Cu")
		(net "LED_LAN_0_N")
	)
	(segment
		(start 494.366804 -42.522394)
		(end 495.664998 -41.2242)
		(width 0.089408)
		(layer "In4.Cu")
		(net "LED_LAN_0_N")
	)
	(segment
		(start 494.366804 -45.005244)
		(end 494.366804 -42.522394)
		(width 0.089408)
		(layer "In4.Cu")
		(net "LED_LAN_0_N")
	)
	(segment
		(start 489.851192 -25.540208)
		(end 489.851192 -23.938992)
		(width 0.089408)
		(layer "In4.Cu")
		(net "LED_LAN_0_N")
	)
	(segment
		(start 484.916226 -47.960534)
		(end 491.411514 -47.960534)
		(width 0.089408)
		(layer "In4.Cu")
		(net "LED_LAN_0_N")
	)
	(segment
		(start 495.664998 -41.2242)
		(end 499.383304 -41.2242)
		(width 0.089408)
		(layer "In4.Cu")
		(net "LED_LAN_0_N")
	)
	(segment
		(start 491.411514 -47.960534)
		(end 494.366804 -45.005244)
		(width 0.089408)
		(layer "In4.Cu")
		(net "LED_LAN_0_N")
	)
	(segment
		(start 497.883688 -27.508454)
		(end 491.819438 -27.508454)
		(width 0.089408)
		(layer "In4.Cu")
		(net "LED_LAN_0_N")
	)
	(segment
		(start 499.383304 -41.2242)
		(end 499.992904 -40.6146)
		(width 0.089408)
		(layer "In4.Cu")
		(net "LED_LAN_0_N")
	)
	(segment
		(start 499.992904 -29.61767)
		(end 497.883688 -27.508454)
		(width 0.089408)
		(layer "In4.Cu")
		(net "LED_LAN_0_N")
	)
	(segment
		(start 488.321096 -22.408896)
		(end 488.321096 -17.913096)
		(width 0.089408)
		(layer "In4.Cu")
		(net "LED_LAN_0_N")
	)
	(segment
		(start 482.059234 -50.817526)
		(end 484.916226 -47.960534)
		(width 0.089408)
		(layer "In4.Cu")
		(net "LED_LAN_0_N")
	)
	(segment
		(start 499.992904 -40.6146)
		(end 499.992904 -29.61767)
		(width 0.089408)
		(layer "In4.Cu")
		(net "LED_LAN_0_N")
	)
	(segment
		(start 489.851192 -23.938992)
		(end 488.321096 -22.408896)
		(width 0.089408)
		(layer "In4.Cu")
		(net "LED_LAN_0_N")
	)
	(segment
		(start 380.13132 -92.969842)
		(end 380.13132 -89.908634)
		(width 0.0889)
		(layer "F.Cu")
		(net "IRQ_LPC_SERIRQ_N")
	)
	(segment
		(start 380.485142 -93.95968)
		(end 380.485142 -93.323664)
		(width 0.0889)
		(layer "F.Cu")
		(net "IRQ_LPC_SERIRQ_N")
	)
	(segment
		(start 380.485142 -93.323664)
		(end 380.13132 -92.969842)
		(width 0.0889)
		(layer "F.Cu")
		(net "IRQ_LPC_SERIRQ_N")
	)
	(segment
		(start 380.13132 -89.908634)
		(end 380.554484 -89.48547)
		(width 0.0889)
		(layer "F.Cu")
		(net "IRQ_LPC_SERIRQ_N")
	)
	(segment
		(start 380.484888 -93.959934)
		(end 380.485142 -93.95968)
		(width 0.0889)
		(layer "F.Cu")
		(net "IRQ_LPC_SERIRQ_N")
	)
	(via
		(at 409.956 -45.1612)
		(size 0.508)
		(drill 0.254)
		(layers "F.Cu" "B.Cu")
		(net "IRQ_LPC_SERIRQ_N")
	)
	(via
		(at 391.625074 -37.85362)
		(size 0.508)
		(drill 0.254)
		(layers "F.Cu" "B.Cu")
		(net "IRQ_LPC_SERIRQ_N")
	)
	(via
		(at 380.554484 -89.48547)
		(size 0.508)
		(drill 0.254)
		(layers "F.Cu" "B.Cu")
		(net "IRQ_LPC_SERIRQ_N")
	)
	(segment
		(start 410.33192 -45.53712)
		(end 409.956 -45.1612)
		(width 0.10795)
		(layer "B.Cu")
		(net "IRQ_LPC_SERIRQ_N")
	)
	(segment
		(start 411.21076 -45.53712)
		(end 410.33192 -45.53712)
		(width 0.10795)
		(layer "B.Cu")
		(net "IRQ_LPC_SERIRQ_N")
	)
	(segment
		(start 379.984 -88.2015)
		(end 380.554484 -88.771984)
		(width 0.10795)
		(layer "B.Cu")
		(net "IRQ_LPC_SERIRQ_N")
	)
	(segment
		(start 380.554484 -88.771984)
		(end 380.554484 -89.48547)
		(width 0.10795)
		(layer "B.Cu")
		(net "IRQ_LPC_SERIRQ_N")
	)
	(segment
		(start 406.11044 -42.92092)
		(end 406.289764 -43.100244)
		(width 0.089408)
		(layer "In4.Cu")
		(net "IRQ_LPC_SERIRQ_N")
	)
	(segment
		(start 401.47367 -42.01287)
		(end 402.38172 -42.92092)
		(width 0.089408)
		(layer "In4.Cu")
		(net "IRQ_LPC_SERIRQ_N")
	)
	(segment
		(start 391.625074 -37.85362)
		(end 392.397488 -37.85362)
		(width 0.089408)
		(layer "In4.Cu")
		(net "IRQ_LPC_SERIRQ_N")
	)
	(segment
		(start 397.517112 -39.122604)
		(end 400.407378 -42.01287)
		(width 0.089408)
		(layer "In4.Cu")
		(net "IRQ_LPC_SERIRQ_N")
	)
	(segment
		(start 406.9842 -43.103546)
		(end 409.041854 -45.1612)
		(width 0.089408)
		(layer "In4.Cu")
		(net "IRQ_LPC_SERIRQ_N")
	)
	(segment
		(start 393.666472 -39.122604)
		(end 397.517112 -39.122604)
		(width 0.089408)
		(layer "In4.Cu")
		(net "IRQ_LPC_SERIRQ_N")
	)
	(segment
		(start 406.289764 -43.100244)
		(end 406.290018 -43.100244)
		(width 0.089408)
		(layer "In4.Cu")
		(net "IRQ_LPC_SERIRQ_N")
	)
	(segment
		(start 406.290018 -43.100244)
		(end 406.29332 -43.103546)
		(width 0.089408)
		(layer "In4.Cu")
		(net "IRQ_LPC_SERIRQ_N")
	)
	(segment
		(start 409.041854 -45.1612)
		(end 409.956 -45.1612)
		(width 0.089408)
		(layer "In4.Cu")
		(net "IRQ_LPC_SERIRQ_N")
	)
	(segment
		(start 402.38172 -42.92092)
		(end 406.11044 -42.92092)
		(width 0.089408)
		(layer "In4.Cu")
		(net "IRQ_LPC_SERIRQ_N")
	)
	(segment
		(start 400.407378 -42.01287)
		(end 401.47367 -42.01287)
		(width 0.089408)
		(layer "In4.Cu")
		(net "IRQ_LPC_SERIRQ_N")
	)
	(segment
		(start 406.29332 -43.103546)
		(end 406.9842 -43.103546)
		(width 0.089408)
		(layer "In4.Cu")
		(net "IRQ_LPC_SERIRQ_N")
	)
	(segment
		(start 392.397488 -37.85362)
		(end 393.666472 -39.122604)
		(width 0.089408)
		(layer "In4.Cu")
		(net "IRQ_LPC_SERIRQ_N")
	)
	(segment
		(start 390.398254 -47.42434)
		(end 390.388856 -47.414942)
		(width 0.089408)
		(layer "In9.Cu")
		(net "IRQ_LPC_SERIRQ_N")
	)
	(segment
		(start 390.75614 -42.289476)
		(end 390.756394 -42.289222)
		(width 0.089408)
		(layer "In9.Cu")
		(net "IRQ_LPC_SERIRQ_N")
	)
	(segment
		(start 387.340348 -74.102722)
		(end 387.895338 -73.547732)
		(width 0.089408)
		(layer "In9.Cu")
		(net "IRQ_LPC_SERIRQ_N")
	)
	(segment
		(start 380.554484 -89.48547)
		(end 380.554484 -88.385396)
		(width 0.089408)
		(layer "In9.Cu")
		(net "IRQ_LPC_SERIRQ_N")
	)
	(segment
		(start 387.895338 -73.547732)
		(end 387.895338 -72.475598)
		(width 0.089408)
		(layer "In9.Cu")
		(net "IRQ_LPC_SERIRQ_N")
	)
	(segment
		(start 391.48004 -40.702992)
		(end 391.940034 -40.242998)
		(width 0.089408)
		(layer "In9.Cu")
		(net "IRQ_LPC_SERIRQ_N")
	)
	(segment
		(start 390.756394 -42.289222)
		(end 390.756394 -42.130726)
		(width 0.089408)
		(layer "In9.Cu")
		(net "IRQ_LPC_SERIRQ_N")
	)
	(segment
		(start 387.340348 -76.08697)
		(end 387.340348 -74.102722)
		(width 0.089408)
		(layer "In9.Cu")
		(net "IRQ_LPC_SERIRQ_N")
	)
	(segment
		(start 383.1082 -86.796626)
		(end 383.1082 -86.199726)
		(width 0.089408)
		(layer "In9.Cu")
		(net "IRQ_LPC_SERIRQ_N")
	)
	(segment
		(start 391.328402 -52.850288)
		(end 389.819896 -51.341782)
		(width 0.089408)
		(layer "In9.Cu")
		(net "IRQ_LPC_SERIRQ_N")
	)
	(segment
		(start 388.917688 -69.73951)
		(end 388.917688 -66.59499)
		(width 0.089408)
		(layer "In9.Cu")
		(net "IRQ_LPC_SERIRQ_N")
	)
	(segment
		(start 384.53695 -85.22589)
		(end 386.503672 -83.259168)
		(width 0.089408)
		(layer "In9.Cu")
		(net "IRQ_LPC_SERIRQ_N")
	)
	(segment
		(start 389.819896 -50.260504)
		(end 390.398254 -49.682146)
		(width 0.089408)
		(layer "In9.Cu")
		(net "IRQ_LPC_SERIRQ_N")
	)
	(segment
		(start 390.388856 -45.508164)
		(end 390.756648 -45.140372)
		(width 0.089408)
		(layer "In9.Cu")
		(net "IRQ_LPC_SERIRQ_N")
	)
	(segment
		(start 390.523476 -64.504062)
		(end 390.523222 -64.503808)
		(width 0.089408)
		(layer "In9.Cu")
		(net "IRQ_LPC_SERIRQ_N")
	)
	(segment
		(start 389.819896 -51.341782)
		(end 389.819896 -50.260504)
		(width 0.089408)
		(layer "In9.Cu")
		(net "IRQ_LPC_SERIRQ_N")
	)
	(segment
		(start 383.1082 -86.199726)
		(end 384.082036 -85.22589)
		(width 0.089408)
		(layer "In9.Cu")
		(net "IRQ_LPC_SERIRQ_N")
	)
	(segment
		(start 391.48004 -41.40708)
		(end 391.48004 -40.702992)
		(width 0.089408)
		(layer "In9.Cu")
		(net "IRQ_LPC_SERIRQ_N")
	)
	(segment
		(start 386.503672 -81.700624)
		(end 386.280152 -81.477104)
		(width 0.089408)
		(layer "In9.Cu")
		(net "IRQ_LPC_SERIRQ_N")
	)
	(segment
		(start 386.280152 -81.477104)
		(end 386.280152 -80.362806)
		(width 0.089408)
		(layer "In9.Cu")
		(net "IRQ_LPC_SERIRQ_N")
	)
	(segment
		(start 390.756648 -42.606468)
		(end 390.75614 -42.60596)
		(width 0.089408)
		(layer "In9.Cu")
		(net "IRQ_LPC_SERIRQ_N")
	)
	(segment
		(start 386.280152 -80.362806)
		(end 385.975352 -80.058006)
		(width 0.089408)
		(layer "In9.Cu")
		(net "IRQ_LPC_SERIRQ_N")
	)
	(segment
		(start 387.895338 -72.475598)
		(end 389.325104 -71.045832)
		(width 0.089408)
		(layer "In9.Cu")
		(net "IRQ_LPC_SERIRQ_N")
	)
	(segment
		(start 389.325104 -70.146926)
		(end 388.917688 -69.73951)
		(width 0.089408)
		(layer "In9.Cu")
		(net "IRQ_LPC_SERIRQ_N")
	)
	(segment
		(start 390.388856 -47.414942)
		(end 390.388856 -45.508164)
		(width 0.089408)
		(layer "In9.Cu")
		(net "IRQ_LPC_SERIRQ_N")
	)
	(segment
		(start 380.554484 -88.385396)
		(end 381.50546 -87.43442)
		(width 0.089408)
		(layer "In9.Cu")
		(net "IRQ_LPC_SERIRQ_N")
	)
	(segment
		(start 390.756394 -42.130726)
		(end 391.48004 -41.40708)
		(width 0.089408)
		(layer "In9.Cu")
		(net "IRQ_LPC_SERIRQ_N")
	)
	(segment
		(start 385.975352 -77.451966)
		(end 387.340348 -76.08697)
		(width 0.089408)
		(layer "In9.Cu")
		(net "IRQ_LPC_SERIRQ_N")
	)
	(segment
		(start 390.75614 -42.60596)
		(end 390.75614 -42.289476)
		(width 0.089408)
		(layer "In9.Cu")
		(net "IRQ_LPC_SERIRQ_N")
	)
	(segment
		(start 390.398254 -49.682146)
		(end 390.398254 -47.42434)
		(width 0.089408)
		(layer "In9.Cu")
		(net "IRQ_LPC_SERIRQ_N")
	)
	(segment
		(start 382.470406 -87.43442)
		(end 383.1082 -86.796626)
		(width 0.089408)
		(layer "In9.Cu")
		(net "IRQ_LPC_SERIRQ_N")
	)
	(segment
		(start 391.251948 -59.71159)
		(end 391.328402 -59.635136)
		(width 0.089408)
		(layer "In9.Cu")
		(net "IRQ_LPC_SERIRQ_N")
	)
	(segment
		(start 390.523476 -64.989202)
		(end 390.523476 -64.504062)
		(width 0.089408)
		(layer "In9.Cu")
		(net "IRQ_LPC_SERIRQ_N")
	)
	(segment
		(start 384.082036 -85.22589)
		(end 384.53695 -85.22589)
		(width 0.089408)
		(layer "In9.Cu")
		(net "IRQ_LPC_SERIRQ_N")
	)
	(segment
		(start 381.50546 -87.43442)
		(end 382.470406 -87.43442)
		(width 0.089408)
		(layer "In9.Cu")
		(net "IRQ_LPC_SERIRQ_N")
	)
	(segment
		(start 391.940034 -40.242998)
		(end 391.940034 -38.16858)
		(width 0.089408)
		(layer "In9.Cu")
		(net "IRQ_LPC_SERIRQ_N")
	)
	(segment
		(start 389.325104 -71.045832)
		(end 389.325104 -70.146926)
		(width 0.089408)
		(layer "In9.Cu")
		(net "IRQ_LPC_SERIRQ_N")
	)
	(segment
		(start 391.328402 -59.635136)
		(end 391.328402 -52.850288)
		(width 0.089408)
		(layer "In9.Cu")
		(net "IRQ_LPC_SERIRQ_N")
	)
	(segment
		(start 390.523222 -61.310012)
		(end 391.251948 -60.581286)
		(width 0.089408)
		(layer "In9.Cu")
		(net "IRQ_LPC_SERIRQ_N")
	)
	(segment
		(start 391.940034 -38.16858)
		(end 391.625074 -37.85362)
		(width 0.089408)
		(layer "In9.Cu")
		(net "IRQ_LPC_SERIRQ_N")
	)
	(segment
		(start 390.756648 -45.140372)
		(end 390.756648 -42.606468)
		(width 0.089408)
		(layer "In9.Cu")
		(net "IRQ_LPC_SERIRQ_N")
	)
	(segment
		(start 386.503672 -83.259168)
		(end 386.503672 -81.700624)
		(width 0.089408)
		(layer "In9.Cu")
		(net "IRQ_LPC_SERIRQ_N")
	)
	(segment
		(start 390.523222 -64.503808)
		(end 390.523222 -61.310012)
		(width 0.089408)
		(layer "In9.Cu")
		(net "IRQ_LPC_SERIRQ_N")
	)
	(segment
		(start 391.251948 -60.581286)
		(end 391.251948 -59.71159)
		(width 0.089408)
		(layer "In9.Cu")
		(net "IRQ_LPC_SERIRQ_N")
	)
	(segment
		(start 388.917688 -66.59499)
		(end 390.523476 -64.989202)
		(width 0.089408)
		(layer "In9.Cu")
		(net "IRQ_LPC_SERIRQ_N")
	)
	(segment
		(start 385.975352 -80.058006)
		(end 385.975352 -77.451966)
		(width 0.089408)
		(layer "In9.Cu")
		(net "IRQ_LPC_SERIRQ_N")
	)
	(via
		(at 457.373482 -145.533872)
		(size 0.6604)
		(drill 0.3302)
		(layers "F.Cu" "B.Cu")
		(net "FM_DEBUG_RST_BTN_R1_N")
	)
	(segment
		(start 459.3336 -141.727428)
		(end 460.065628 -141.727428)
		(width 0.10795)
		(layer "B.Cu")
		(net "FM_DEBUG_RST_BTN_R1_N")
	)
	(segment
		(start 460.065628 -141.727428)
		(end 460.388716 -142.050516)
		(width 0.10795)
		(layer "B.Cu")
		(net "FM_DEBUG_RST_BTN_R1_N")
	)
	(segment
		(start 457.373482 -145.533872)
		(end 456.7936 -144.95399)
		(width 0.10795)
		(layer "B.Cu")
		(net "FM_DEBUG_RST_BTN_R1_N")
	)
	(segment
		(start 459.3336 -141.727428)
		(end 458.093572 -141.727428)
		(width 0.10795)
		(layer "B.Cu")
		(net "FM_DEBUG_RST_BTN_R1_N")
	)
	(segment
		(start 457.92263 -146.08302)
		(end 457.373482 -145.533872)
		(width 0.10795)
		(layer "B.Cu")
		(net "FM_DEBUG_RST_BTN_R1_N")
	)
	(segment
		(start 460.388716 -145.320004)
		(end 459.6257 -146.08302)
		(width 0.10795)
		(layer "B.Cu")
		(net "FM_DEBUG_RST_BTN_R1_N")
	)
	(segment
		(start 460.388716 -142.050516)
		(end 460.388716 -145.320004)
		(width 0.10795)
		(layer "B.Cu")
		(net "FM_DEBUG_RST_BTN_R1_N")
	)
	(segment
		(start 458.093572 -141.727428)
		(end 457.8096 -142.0114)
		(width 0.10795)
		(layer "B.Cu")
		(net "FM_DEBUG_RST_BTN_R1_N")
	)
	(segment
		(start 456.7936 -144.95399)
		(end 456.7936 -142.9004)
		(width 0.10795)
		(layer "B.Cu")
		(net "FM_DEBUG_RST_BTN_R1_N")
	)
	(segment
		(start 459.6257 -146.08302)
		(end 457.92263 -146.08302)
		(width 0.10795)
		(layer "B.Cu")
		(net "FM_DEBUG_RST_BTN_R1_N")
	)
	(segment
		(start 398.63395 -96.9772)
		(end 399.18259 -97.08642)
		(width 0.10795)
		(layer "F.Cu")
		(net "FM_QAT_EN_N")
	)
	(via
		(at 400.336766 -95.999808)
		(size 0.6604)
		(drill 0.3302)
		(layers "F.Cu" "B.Cu")
		(net "FM_QAT_EN_N")
	)
	(via
		(at 399.18259 -97.08642)
		(size 0.508)
		(drill 0.254)
		(layers "F.Cu" "B.Cu")
		(net "FM_QAT_EN_N")
	)
	(segment
		(start 401.74037 -94.596204)
		(end 400.336766 -95.999808)
		(width 0.10795)
		(layer "B.Cu")
		(net "FM_QAT_EN_N")
	)
	(segment
		(start 403.243796 -94.596204)
		(end 401.74037 -94.596204)
		(width 0.10795)
		(layer "B.Cu")
		(net "FM_QAT_EN_N")
	)
	(segment
		(start 403.568408 -93.755718)
		(end 404.330408 -93.755718)
		(width 0.10795)
		(layer "B.Cu")
		(net "FM_QAT_EN_N")
	)
	(segment
		(start 403.5425 -94.204028)
		(end 403.5425 -94.2975)
		(width 0.10795)
		(layer "B.Cu")
		(net "FM_QAT_EN_N")
	)
	(segment
		(start 399.2118 -97.08642)
		(end 399.18259 -97.08642)
		(width 0.10795)
		(layer "B.Cu")
		(net "FM_QAT_EN_N")
	)
	(segment
		(start 399.2118 -97.0661)
		(end 399.2118 -97.08642)
		(width 0.10795)
		(layer "B.Cu")
		(net "FM_QAT_EN_N")
	)
	(segment
		(start 403.568408 -94.17812)
		(end 403.5425 -94.204028)
		(width 0.10795)
		(layer "B.Cu")
		(net "FM_QAT_EN_N")
	)
	(segment
		(start 403.568408 -93.755718)
		(end 403.568408 -94.17812)
		(width 0.10795)
		(layer "B.Cu")
		(net "FM_QAT_EN_N")
	)
	(segment
		(start 399.270474 -97.0661)
		(end 399.2118 -97.0661)
		(width 0.10795)
		(layer "B.Cu")
		(net "FM_QAT_EN_N")
	)
	(segment
		(start 400.336766 -95.999808)
		(end 399.270474 -97.0661)
		(width 0.10795)
		(layer "B.Cu")
		(net "FM_QAT_EN_N")
	)
	(segment
		(start 403.5425 -94.2975)
		(end 403.243796 -94.596204)
		(width 0.10795)
		(layer "B.Cu")
		(net "FM_QAT_EN_N")
	)
	(segment
		(start 363.08665 -44.187618)
		(end 364.321852 -44.187618)
		(width 0.10795)
		(layer "B.Cu")
		(net "FM_CPU_ERR1_LVT3_R_N")
	)
	(segment
		(start 362.270294 -44.020486)
		(end 362.919518 -44.020486)
		(width 0.10795)
		(layer "B.Cu")
		(net "FM_CPU_ERR1_LVT3_R_N")
	)
	(segment
		(start 362.919518 -44.020486)
		(end 363.08665 -44.187618)
		(width 0.10795)
		(layer "B.Cu")
		(net "FM_CPU_ERR1_LVT3_R_N")
	)
	(segment
		(start 405.384 -46.8249)
		(end 406.146 -46.8249)
		(width 0.10795)
		(layer "F.Cu")
		(net "FM_CPU_ERR1_LVT3_N")
	)
	(segment
		(start 406.1333 -46.205902)
		(end 406.146 -46.218602)
		(width 0.10795)
		(layer "F.Cu")
		(net "FM_CPU_ERR1_LVT3_N")
	)
	(segment
		(start 406.1333 -45.7962)
		(end 406.1333 -46.205902)
		(width 0.10795)
		(layer "F.Cu")
		(net "FM_CPU_ERR1_LVT3_N")
	)
	(segment
		(start 406.146 -46.218602)
		(end 406.146 -46.8249)
		(width 0.10795)
		(layer "F.Cu")
		(net "FM_CPU_ERR1_LVT3_N")
	)
	(via
		(at 384.900932 -38.542722)
		(size 0.508)
		(drill 0.254)
		(layers "F.Cu" "B.Cu")
		(net "FM_CPU_ERR1_LVT3_N")
	)
	(via
		(at 365.620554 -35.597846)
		(size 0.6604)
		(drill 0.3302)
		(layers "F.Cu" "B.Cu")
		(net "FM_CPU_ERR1_LVT3_N")
	)
	(via
		(at 406.1333 -45.7962)
		(size 0.508)
		(drill 0.254)
		(layers "F.Cu" "B.Cu")
		(net "FM_CPU_ERR1_LVT3_N")
	)
	(segment
		(start 365.9378 -34.80054)
		(end 366.471708 -34.266632)
		(width 0.10795)
		(layer "B.Cu")
		(net "FM_CPU_ERR1_LVT3_N")
	)
	(segment
		(start 381.338074 -38.115494)
		(end 384.473704 -38.115494)
		(width 0.10795)
		(layer "B.Cu")
		(net "FM_CPU_ERR1_LVT3_N")
	)
	(segment
		(start 369.4557 -34.266632)
		(end 370.199666 -35.010598)
		(width 0.10795)
		(layer "B.Cu")
		(net "FM_CPU_ERR1_LVT3_N")
	)
	(segment
		(start 365.9378 -35.2806)
		(end 365.9378 -34.80054)
		(width 0.10795)
		(layer "B.Cu")
		(net "FM_CPU_ERR1_LVT3_N")
	)
	(segment
		(start 366.471708 -34.266632)
		(end 369.4557 -34.266632)
		(width 0.10795)
		(layer "B.Cu")
		(net "FM_CPU_ERR1_LVT3_N")
	)
	(segment
		(start 365.620554 -35.597846)
		(end 365.140494 -35.597846)
		(width 0.10795)
		(layer "B.Cu")
		(net "FM_CPU_ERR1_LVT3_N")
	)
	(segment
		(start 384.473704 -38.115494)
		(end 384.900932 -38.542722)
		(width 0.10795)
		(layer "B.Cu")
		(net "FM_CPU_ERR1_LVT3_N")
	)
	(segment
		(start 375.209562 -35.010598)
		(end 376.103642 -35.904678)
		(width 0.10795)
		(layer "B.Cu")
		(net "FM_CPU_ERR1_LVT3_N")
	)
	(segment
		(start 380.725934 -37.219128)
		(end 380.725934 -37.503354)
		(width 0.10795)
		(layer "B.Cu")
		(net "FM_CPU_ERR1_LVT3_N")
	)
	(segment
		(start 360.025188 -43.194986)
		(end 360.555794 -43.194986)
		(width 0.10795)
		(layer "B.Cu")
		(net "FM_CPU_ERR1_LVT3_N")
	)
	(segment
		(start 380.725934 -37.503354)
		(end 381.338074 -38.115494)
		(width 0.10795)
		(layer "B.Cu")
		(net "FM_CPU_ERR1_LVT3_N")
	)
	(segment
		(start 379.411484 -35.904678)
		(end 380.725934 -37.219128)
		(width 0.10795)
		(layer "B.Cu")
		(net "FM_CPU_ERR1_LVT3_N")
	)
	(segment
		(start 365.620554 -35.597846)
		(end 365.9378 -35.2806)
		(width 0.10795)
		(layer "B.Cu")
		(net "FM_CPU_ERR1_LVT3_N")
	)
	(segment
		(start 376.103642 -35.904678)
		(end 379.411484 -35.904678)
		(width 0.10795)
		(layer "B.Cu")
		(net "FM_CPU_ERR1_LVT3_N")
	)
	(segment
		(start 370.199666 -35.010598)
		(end 375.209562 -35.010598)
		(width 0.10795)
		(layer "B.Cu")
		(net "FM_CPU_ERR1_LVT3_N")
	)
	(segment
		(start 359.907078 -43.076876)
		(end 360.025188 -43.194986)
		(width 0.10795)
		(layer "B.Cu")
		(net "FM_CPU_ERR1_LVT3_N")
	)
	(segment
		(start 365.140494 -35.597846)
		(end 359.907078 -40.831262)
		(width 0.10795)
		(layer "B.Cu")
		(net "FM_CPU_ERR1_LVT3_N")
	)
	(segment
		(start 359.907078 -40.831262)
		(end 359.907078 -43.076876)
		(width 0.10795)
		(layer "B.Cu")
		(net "FM_CPU_ERR1_LVT3_N")
	)
	(segment
		(start 396.911576 -43.112944)
		(end 396.219934 -42.421302)
		(width 0.089408)
		(layer "In4.Cu")
		(net "FM_CPU_ERR1_LVT3_N")
	)
	(segment
		(start 398.204944 -43.112944)
		(end 396.911576 -43.112944)
		(width 0.089408)
		(layer "In4.Cu")
		(net "FM_CPU_ERR1_LVT3_N")
	)
	(segment
		(start 402.472652 -45.339762)
		(end 400.882866 -43.749976)
		(width 0.089408)
		(layer "In4.Cu")
		(net "FM_CPU_ERR1_LVT3_N")
	)
	(segment
		(start 384.973322 -38.542722)
		(end 384.900932 -38.542722)
		(width 0.089408)
		(layer "In4.Cu")
		(net "FM_CPU_ERR1_LVT3_N")
	)
	(segment
		(start 389.217662 -39.122096)
		(end 385.552696 -39.122096)
		(width 0.089408)
		(layer "In4.Cu")
		(net "FM_CPU_ERR1_LVT3_N")
	)
	(segment
		(start 392.290808 -42.421302)
		(end 390.00684 -40.137334)
		(width 0.089408)
		(layer "In4.Cu")
		(net "FM_CPU_ERR1_LVT3_N")
	)
	(segment
		(start 390.00684 -40.137334)
		(end 390.00684 -39.911274)
		(width 0.089408)
		(layer "In4.Cu")
		(net "FM_CPU_ERR1_LVT3_N")
	)
	(segment
		(start 406.1333 -45.7962)
		(end 405.676862 -45.339762)
		(width 0.089408)
		(layer "In4.Cu")
		(net "FM_CPU_ERR1_LVT3_N")
	)
	(segment
		(start 396.219934 -42.421302)
		(end 392.290808 -42.421302)
		(width 0.089408)
		(layer "In4.Cu")
		(net "FM_CPU_ERR1_LVT3_N")
	)
	(segment
		(start 398.73809 -43.444922)
		(end 398.536922 -43.444922)
		(width 0.089408)
		(layer "In4.Cu")
		(net "FM_CPU_ERR1_LVT3_N")
	)
	(segment
		(start 405.676862 -45.339762)
		(end 402.472652 -45.339762)
		(width 0.089408)
		(layer "In4.Cu")
		(net "FM_CPU_ERR1_LVT3_N")
	)
	(segment
		(start 399.043144 -43.749976)
		(end 398.73809 -43.444922)
		(width 0.089408)
		(layer "In4.Cu")
		(net "FM_CPU_ERR1_LVT3_N")
	)
	(segment
		(start 390.00684 -39.911274)
		(end 389.217662 -39.122096)
		(width 0.089408)
		(layer "In4.Cu")
		(net "FM_CPU_ERR1_LVT3_N")
	)
	(segment
		(start 398.536922 -43.444922)
		(end 398.204944 -43.112944)
		(width 0.089408)
		(layer "In4.Cu")
		(net "FM_CPU_ERR1_LVT3_N")
	)
	(segment
		(start 400.882866 -43.749976)
		(end 399.043144 -43.749976)
		(width 0.089408)
		(layer "In4.Cu")
		(net "FM_CPU_ERR1_LVT3_N")
	)
	(segment
		(start 385.552696 -39.122096)
		(end 384.973322 -38.542722)
		(width 0.089408)
		(layer "In4.Cu")
		(net "FM_CPU_ERR1_LVT3_N")
	)
	(via
		(at 363.8804 -40.9702)
		(size 0.6604)
		(drill 0.3302)
		(layers "F.Cu" "B.Cu")
		(net "FM_CPU_ERR0_LVT3_R_N")
	)
	(segment
		(start 362.945172 -41.970198)
		(end 362.945172 -41.3893)
		(width 0.10795)
		(layer "B.Cu")
		(net "FM_CPU_ERR0_LVT3_R_N")
	)
	(segment
		(start 363.005116 -42.598848)
		(end 363.8804 -41.723564)
		(width 0.10795)
		(layer "B.Cu")
		(net "FM_CPU_ERR0_LVT3_R_N")
	)
	(segment
		(start 363.364272 -40.9702)
		(end 363.8804 -40.9702)
		(width 0.10795)
		(layer "B.Cu")
		(net "FM_CPU_ERR0_LVT3_R_N")
	)
	(segment
		(start 362.945172 -41.3893)
		(end 363.364272 -40.9702)
		(width 0.10795)
		(layer "B.Cu")
		(net "FM_CPU_ERR0_LVT3_R_N")
	)
	(segment
		(start 362.545884 -42.369486)
		(end 362.945172 -41.970198)
		(width 0.10795)
		(layer "B.Cu")
		(net "FM_CPU_ERR0_LVT3_R_N")
	)
	(segment
		(start 364.321852 -43.537378)
		(end 363.165136 -43.537378)
		(width 0.10795)
		(layer "B.Cu")
		(net "FM_CPU_ERR0_LVT3_R_N")
	)
	(segment
		(start 363.005116 -43.377358)
		(end 363.005116 -42.598848)
		(width 0.10795)
		(layer "B.Cu")
		(net "FM_CPU_ERR0_LVT3_R_N")
	)
	(segment
		(start 362.270294 -42.369486)
		(end 362.545884 -42.369486)
		(width 0.10795)
		(layer "B.Cu")
		(net "FM_CPU_ERR0_LVT3_R_N")
	)
	(segment
		(start 363.8804 -41.723564)
		(end 363.8804 -40.9702)
		(width 0.10795)
		(layer "B.Cu")
		(net "FM_CPU_ERR0_LVT3_R_N")
	)
	(segment
		(start 363.165136 -43.537378)
		(end 363.005116 -43.377358)
		(width 0.10795)
		(layer "B.Cu")
		(net "FM_CPU_ERR0_LVT3_R_N")
	)
	(via
		(at 384.429 -39.0652)
		(size 0.508)
		(drill 0.254)
		(layers "F.Cu" "B.Cu")
		(net "FM_CPU_ERR0_LVT3_N")
	)
	(via
		(at 409.387294 -54.230778)
		(size 0.508)
		(drill 0.254)
		(layers "F.Cu" "B.Cu")
		(net "FM_CPU_ERR0_LVT3_N")
	)
	(via
		(at 420.377874 -46.86427)
		(size 0.508)
		(drill 0.254)
		(layers "F.Cu" "B.Cu")
		(net "FM_CPU_ERR0_LVT3_N")
	)
	(via
		(at 364.617 -36.9316)
		(size 0.6604)
		(drill 0.3302)
		(layers "F.Cu" "B.Cu")
		(net "FM_CPU_ERR0_LVT3_N")
	)
	(segment
		(start 409.38958 -53.678074)
		(end 409.38958 -54.230778)
		(width 0.10795)
		(layer "B.Cu")
		(net "FM_CPU_ERR0_LVT3_N")
	)
	(segment
		(start 366.5982 -35.56)
		(end 366.5982 -35.027616)
		(width 0.10795)
		(layer "B.Cu")
		(net "FM_CPU_ERR0_LVT3_N")
	)
	(segment
		(start 412.329884 -47.822104)
		(end 412.329884 -48.210724)
		(width 0.10795)
		(layer "B.Cu")
		(net "FM_CPU_ERR0_LVT3_N")
	)
	(segment
		(start 366.5982 -35.027616)
		(end 366.8776 -34.748216)
		(width 0.10795)
		(layer "B.Cu")
		(net "FM_CPU_ERR0_LVT3_N")
	)
	(segment
		(start 384.372866 -39.0652)
		(end 384.429 -39.0652)
		(width 0.10795)
		(layer "B.Cu")
		(net "FM_CPU_ERR0_LVT3_N")
	)
	(segment
		(start 360.120692 -42.197782)
		(end 360.228896 -42.305986)
		(width 0.10795)
		(layer "B.Cu")
		(net "FM_CPU_ERR0_LVT3_N")
	)
	(segment
		(start 366.8776 -34.748216)
		(end 369.098068 -34.748216)
		(width 0.10795)
		(layer "B.Cu")
		(net "FM_CPU_ERR0_LVT3_N")
	)
	(segment
		(start 364.617 -36.9316)
		(end 365.2266 -36.9316)
		(width 0.10795)
		(layer "B.Cu")
		(net "FM_CPU_ERR0_LVT3_N")
	)
	(segment
		(start 360.120692 -40.914066)
		(end 360.120692 -42.197782)
		(width 0.10795)
		(layer "B.Cu")
		(net "FM_CPU_ERR0_LVT3_N")
	)
	(segment
		(start 360.228896 -42.305986)
		(end 360.555794 -42.305986)
		(width 0.10795)
		(layer "B.Cu")
		(net "FM_CPU_ERR0_LVT3_N")
	)
	(segment
		(start 412.313374 -48.687482)
		(end 412.313374 -50.75428)
		(width 0.10795)
		(layer "B.Cu")
		(net "FM_CPU_ERR0_LVT3_N")
	)
	(segment
		(start 380.444502 -37.446204)
		(end 380.444502 -37.58692)
		(width 0.10795)
		(layer "B.Cu")
		(net "FM_CPU_ERR0_LVT3_N")
	)
	(segment
		(start 409.38958 -54.230778)
		(end 409.387294 -54.230778)
		(width 0.10795)
		(layer "B.Cu")
		(net "FM_CPU_ERR0_LVT3_N")
	)
	(segment
		(start 369.098068 -34.748216)
		(end 369.786154 -35.436302)
		(width 0.10795)
		(layer "B.Cu")
		(net "FM_CPU_ERR0_LVT3_N")
	)
	(segment
		(start 380.383796 -37.385498)
		(end 380.444502 -37.446204)
		(width 0.10795)
		(layer "B.Cu")
		(net "FM_CPU_ERR0_LVT3_N")
	)
	(segment
		(start 412.329884 -48.210724)
		(end 412.313374 -48.227234)
		(width 0.10795)
		(layer "B.Cu")
		(net "FM_CPU_ERR0_LVT3_N")
	)
	(segment
		(start 380.383796 -37.173408)
		(end 380.383796 -37.385498)
		(width 0.10795)
		(layer "B.Cu")
		(net "FM_CPU_ERR0_LVT3_N")
	)
	(segment
		(start 380.444502 -37.58692)
		(end 381.248666 -38.391084)
		(width 0.10795)
		(layer "B.Cu")
		(net "FM_CPU_ERR0_LVT3_N")
	)
	(segment
		(start 375.981976 -36.134294)
		(end 379.344682 -36.134294)
		(width 0.10795)
		(layer "B.Cu")
		(net "FM_CPU_ERR0_LVT3_N")
	)
	(segment
		(start 412.313374 -50.75428)
		(end 409.38958 -53.678074)
		(width 0.10795)
		(layer "B.Cu")
		(net "FM_CPU_ERR0_LVT3_N")
	)
	(segment
		(start 365.2266 -36.9316)
		(end 366.5982 -35.56)
		(width 0.10795)
		(layer "B.Cu")
		(net "FM_CPU_ERR0_LVT3_N")
	)
	(segment
		(start 375.283984 -35.436302)
		(end 375.981976 -36.134294)
		(width 0.10795)
		(layer "B.Cu")
		(net "FM_CPU_ERR0_LVT3_N")
	)
	(segment
		(start 364.617 -36.9316)
		(end 364.103158 -36.9316)
		(width 0.10795)
		(layer "B.Cu")
		(net "FM_CPU_ERR0_LVT3_N")
	)
	(segment
		(start 381.248666 -38.391084)
		(end 383.69875 -38.391084)
		(width 0.10795)
		(layer "B.Cu")
		(net "FM_CPU_ERR0_LVT3_N")
	)
	(segment
		(start 383.69875 -38.391084)
		(end 384.372866 -39.0652)
		(width 0.10795)
		(layer "B.Cu")
		(net "FM_CPU_ERR0_LVT3_N")
	)
	(segment
		(start 364.103158 -36.9316)
		(end 360.120692 -40.914066)
		(width 0.10795)
		(layer "B.Cu")
		(net "FM_CPU_ERR0_LVT3_N")
	)
	(segment
		(start 369.786154 -35.436302)
		(end 375.283984 -35.436302)
		(width 0.10795)
		(layer "B.Cu")
		(net "FM_CPU_ERR0_LVT3_N")
	)
	(segment
		(start 412.313374 -48.227234)
		(end 412.313374 -48.687482)
		(width 0.10795)
		(layer "B.Cu")
		(net "FM_CPU_ERR0_LVT3_N")
	)
	(segment
		(start 379.344682 -36.134294)
		(end 380.383796 -37.173408)
		(width 0.10795)
		(layer "B.Cu")
		(net "FM_CPU_ERR0_LVT3_N")
	)
	(segment
		(start 418.154866 -46.587664)
		(end 417.381436 -46.587664)
		(width 0.089408)
		(layer "In4.Cu")
		(net "FM_CPU_ERR0_LVT3_N")
	)
	(segment
		(start 418.303202 -46.736)
		(end 418.154866 -46.587664)
		(width 0.089408)
		(layer "In4.Cu")
		(net "FM_CPU_ERR0_LVT3_N")
	)
	(segment
		(start 417.381436 -46.587664)
		(end 416.79495 -46.001178)
		(width 0.089408)
		(layer "In4.Cu")
		(net "FM_CPU_ERR0_LVT3_N")
	)
	(segment
		(start 406.789128 -45.500036)
		(end 406.55494 -45.734224)
		(width 0.089408)
		(layer "In4.Cu")
		(net "FM_CPU_ERR0_LVT3_N")
	)
	(segment
		(start 407.395934 -46.391068)
		(end 407.395934 -45.776388)
		(width 0.089408)
		(layer "In4.Cu")
		(net "FM_CPU_ERR0_LVT3_N")
	)
	(segment
		(start 398.143476 -43.3578)
		(end 396.721076 -43.3578)
		(width 0.089408)
		(layer "In4.Cu")
		(net "FM_CPU_ERR0_LVT3_N")
	)
	(segment
		(start 384.4798 -39.116)
		(end 384.429 -39.0652)
		(width 0.089408)
		(layer "In4.Cu")
		(net "FM_CPU_ERR0_LVT3_N")
	)
	(segment
		(start 396.13586 -42.772584)
		(end 391.606786 -42.772584)
		(width 0.089408)
		(layer "In4.Cu")
		(net "FM_CPU_ERR0_LVT3_N")
	)
	(segment
		(start 407.35504 -45.735494)
		(end 407.35504 -45.734224)
		(width 0.089408)
		(layer "In4.Cu")
		(net "FM_CPU_ERR0_LVT3_N")
	)
	(segment
		(start 407.35504 -45.734224)
		(end 407.120852 -45.500036)
		(width 0.089408)
		(layer "In4.Cu")
		(net "FM_CPU_ERR0_LVT3_N")
	)
	(segment
		(start 412.712154 -47.967646)
		(end 408.231848 -47.967646)
		(width 0.089408)
		(layer "In4.Cu")
		(net "FM_CPU_ERR0_LVT3_N")
	)
	(segment
		(start 404.908512 -46.19625)
		(end 404.595584 -45.883322)
		(width 0.089408)
		(layer "In4.Cu")
		(net "FM_CPU_ERR0_LVT3_N")
	)
	(segment
		(start 396.721076 -43.3578)
		(end 396.13586 -42.772584)
		(width 0.089408)
		(layer "In4.Cu")
		(net "FM_CPU_ERR0_LVT3_N")
	)
	(segment
		(start 406.299162 -46.19625)
		(end 404.908512 -46.19625)
		(width 0.089408)
		(layer "In4.Cu")
		(net "FM_CPU_ERR0_LVT3_N")
	)
	(segment
		(start 416.79495 -46.001178)
		(end 414.678368 -46.001178)
		(width 0.089408)
		(layer "In4.Cu")
		(net "FM_CPU_ERR0_LVT3_N")
	)
	(segment
		(start 406.53335 -45.756322)
		(end 406.53335 -45.962062)
		(width 0.089408)
		(layer "In4.Cu")
		(net "FM_CPU_ERR0_LVT3_N")
	)
	(segment
		(start 398.739868 -43.954192)
		(end 398.143476 -43.3578)
		(width 0.089408)
		(layer "In4.Cu")
		(net "FM_CPU_ERR0_LVT3_N")
	)
	(segment
		(start 407.395934 -45.776388)
		(end 407.35504 -45.735494)
		(width 0.089408)
		(layer "In4.Cu")
		(net "FM_CPU_ERR0_LVT3_N")
	)
	(segment
		(start 413.136334 -47.543466)
		(end 412.712154 -47.967646)
		(width 0.089408)
		(layer "In4.Cu")
		(net "FM_CPU_ERR0_LVT3_N")
	)
	(segment
		(start 384.962146 -39.116)
		(end 384.4798 -39.116)
		(width 0.089408)
		(layer "In4.Cu")
		(net "FM_CPU_ERR0_LVT3_N")
	)
	(segment
		(start 400.337274 -43.954192)
		(end 398.739868 -43.954192)
		(width 0.089408)
		(layer "In4.Cu")
		(net "FM_CPU_ERR0_LVT3_N")
	)
	(segment
		(start 390.144 -42.684954)
		(end 389.129524 -41.670478)
		(width 0.089408)
		(layer "In4.Cu")
		(net "FM_CPU_ERR0_LVT3_N")
	)
	(segment
		(start 406.55494 -45.734732)
		(end 406.53335 -45.756322)
		(width 0.089408)
		(layer "In4.Cu")
		(net "FM_CPU_ERR0_LVT3_N")
	)
	(segment
		(start 404.595584 -45.883322)
		(end 402.266404 -45.883322)
		(width 0.089408)
		(layer "In4.Cu")
		(net "FM_CPU_ERR0_LVT3_N")
	)
	(segment
		(start 402.266404 -45.883322)
		(end 400.337274 -43.954192)
		(width 0.089408)
		(layer "In4.Cu")
		(net "FM_CPU_ERR0_LVT3_N")
	)
	(segment
		(start 387.516624 -41.670478)
		(end 384.962146 -39.116)
		(width 0.089408)
		(layer "In4.Cu")
		(net "FM_CPU_ERR0_LVT3_N")
	)
	(segment
		(start 389.129524 -41.670478)
		(end 387.516624 -41.670478)
		(width 0.089408)
		(layer "In4.Cu")
		(net "FM_CPU_ERR0_LVT3_N")
	)
	(segment
		(start 414.678368 -46.001178)
		(end 413.136334 -47.543212)
		(width 0.089408)
		(layer "In4.Cu")
		(net "FM_CPU_ERR0_LVT3_N")
	)
	(segment
		(start 407.6573 -46.652434)
		(end 407.395934 -46.391068)
		(width 0.089408)
		(layer "In4.Cu")
		(net "FM_CPU_ERR0_LVT3_N")
	)
	(segment
		(start 391.606786 -42.772584)
		(end 391.519156 -42.684954)
		(width 0.089408)
		(layer "In4.Cu")
		(net "FM_CPU_ERR0_LVT3_N")
	)
	(segment
		(start 420.377874 -46.86427)
		(end 420.249604 -46.736)
		(width 0.089408)
		(layer "In4.Cu")
		(net "FM_CPU_ERR0_LVT3_N")
	)
	(segment
		(start 413.136334 -47.543212)
		(end 413.136334 -47.543466)
		(width 0.089408)
		(layer "In4.Cu")
		(net "FM_CPU_ERR0_LVT3_N")
	)
	(segment
		(start 407.120852 -45.500036)
		(end 406.789128 -45.500036)
		(width 0.089408)
		(layer "In4.Cu")
		(net "FM_CPU_ERR0_LVT3_N")
	)
	(segment
		(start 408.231848 -47.967646)
		(end 407.6573 -47.393098)
		(width 0.089408)
		(layer "In4.Cu")
		(net "FM_CPU_ERR0_LVT3_N")
	)
	(segment
		(start 391.519156 -42.684954)
		(end 390.144 -42.684954)
		(width 0.089408)
		(layer "In4.Cu")
		(net "FM_CPU_ERR0_LVT3_N")
	)
	(segment
		(start 406.53335 -45.962062)
		(end 406.299162 -46.19625)
		(width 0.089408)
		(layer "In4.Cu")
		(net "FM_CPU_ERR0_LVT3_N")
	)
	(segment
		(start 406.55494 -45.734224)
		(end 406.55494 -45.734732)
		(width 0.089408)
		(layer "In4.Cu")
		(net "FM_CPU_ERR0_LVT3_N")
	)
	(segment
		(start 420.249604 -46.736)
		(end 418.303202 -46.736)
		(width 0.089408)
		(layer "In4.Cu")
		(net "FM_CPU_ERR0_LVT3_N")
	)
	(segment
		(start 407.6573 -47.393098)
		(end 407.6573 -46.652434)
		(width 0.089408)
		(layer "In4.Cu")
		(net "FM_CPU_ERR0_LVT3_N")
	)
	(segment
		(start 418.191188 -48.866806)
		(end 416.366198 -48.866806)
		(width 0.089408)
		(layer "In9.Cu")
		(net "FM_CPU_ERR0_LVT3_N")
	)
	(segment
		(start 416.366198 -48.866806)
		(end 416.176714 -49.05629)
		(width 0.089408)
		(layer "In9.Cu")
		(net "FM_CPU_ERR0_LVT3_N")
	)
	(segment
		(start 413.312356 -49.420272)
		(end 413.302196 -49.430432)
		(width 0.089408)
		(layer "In9.Cu")
		(net "FM_CPU_ERR0_LVT3_N")
	)
	(segment
		(start 416.176714 -49.05629)
		(end 413.664908 -49.05629)
		(width 0.089408)
		(layer "In9.Cu")
		(net "FM_CPU_ERR0_LVT3_N")
	)
	(segment
		(start 413.312356 -49.408842)
		(end 413.312356 -49.420272)
		(width 0.089408)
		(layer "In9.Cu")
		(net "FM_CPU_ERR0_LVT3_N")
	)
	(segment
		(start 413.664908 -49.05629)
		(end 413.312356 -49.408842)
		(width 0.089408)
		(layer "In9.Cu")
		(net "FM_CPU_ERR0_LVT3_N")
	)
	(segment
		(start 418.510212 -48.606964)
		(end 418.509958 -48.607218)
		(width 0.089408)
		(layer "In9.Cu")
		(net "FM_CPU_ERR0_LVT3_N")
	)
	(segment
		(start 413.302196 -49.902872)
		(end 409.387294 -53.817774)
		(width 0.089408)
		(layer "In9.Cu")
		(net "FM_CPU_ERR0_LVT3_N")
	)
	(segment
		(start 418.450776 -48.607218)
		(end 418.191188 -48.866806)
		(width 0.089408)
		(layer "In9.Cu")
		(net "FM_CPU_ERR0_LVT3_N")
	)
	(segment
		(start 418.509958 -48.607218)
		(end 418.450776 -48.607218)
		(width 0.089408)
		(layer "In9.Cu")
		(net "FM_CPU_ERR0_LVT3_N")
	)
	(segment
		(start 420.377874 -47.16145)
		(end 418.932106 -48.607218)
		(width 0.089408)
		(layer "In9.Cu")
		(net "FM_CPU_ERR0_LVT3_N")
	)
	(segment
		(start 420.377874 -46.86427)
		(end 420.377874 -47.16145)
		(width 0.089408)
		(layer "In9.Cu")
		(net "FM_CPU_ERR0_LVT3_N")
	)
	(segment
		(start 418.6682 -48.606964)
		(end 418.510212 -48.606964)
		(width 0.089408)
		(layer "In9.Cu")
		(net "FM_CPU_ERR0_LVT3_N")
	)
	(segment
		(start 413.302196 -49.430432)
		(end 413.302196 -49.902872)
		(width 0.089408)
		(layer "In9.Cu")
		(net "FM_CPU_ERR0_LVT3_N")
	)
	(segment
		(start 418.668454 -48.607218)
		(end 418.6682 -48.606964)
		(width 0.089408)
		(layer "In9.Cu")
		(net "FM_CPU_ERR0_LVT3_N")
	)
	(segment
		(start 418.932106 -48.607218)
		(end 418.668454 -48.607218)
		(width 0.089408)
		(layer "In9.Cu")
		(net "FM_CPU_ERR0_LVT3_N")
	)
	(segment
		(start 409.387294 -53.817774)
		(end 409.387294 -54.230778)
		(width 0.089408)
		(layer "In9.Cu")
		(net "FM_CPU_ERR0_LVT3_N")
	)
	(via
		(at 362.027216 -59.622182)
		(size 0.6604)
		(drill 0.3302)
		(layers "F.Cu" "B.Cu")
		(net "FM_CPU1_FIVR_FAULT_R_LVT3")
	)
	(segment
		(start 366.4077 -59.4487)
		(end 366.67186 -59.71286)
		(width 0.10795)
		(layer "B.Cu")
		(net "FM_CPU1_FIVR_FAULT_R_LVT3")
	)
	(segment
		(start 365.71936 -59.57824)
		(end 365.8489 -59.4487)
		(width 0.10795)
		(layer "B.Cu")
		(net "FM_CPU1_FIVR_FAULT_R_LVT3")
	)
	(segment
		(start 362.071158 -59.57824)
		(end 362.027216 -59.622182)
		(width 0.10795)
		(layer "B.Cu")
		(net "FM_CPU1_FIVR_FAULT_R_LVT3")
	)
	(segment
		(start 364.4265 -59.57824)
		(end 362.071158 -59.57824)
		(width 0.10795)
		(layer "B.Cu")
		(net "FM_CPU1_FIVR_FAULT_R_LVT3")
	)
	(segment
		(start 364.4265 -59.57824)
		(end 365.71936 -59.57824)
		(width 0.10795)
		(layer "B.Cu")
		(net "FM_CPU1_FIVR_FAULT_R_LVT3")
	)
	(segment
		(start 366.522 -60.87872)
		(end 366.522 -62.2935)
		(width 0.10795)
		(layer "B.Cu")
		(net "FM_CPU1_FIVR_FAULT_R_LVT3")
	)
	(segment
		(start 366.67186 -59.71286)
		(end 366.67186 -60.72886)
		(width 0.10795)
		(layer "B.Cu")
		(net "FM_CPU1_FIVR_FAULT_R_LVT3")
	)
	(segment
		(start 366.67186 -60.72886)
		(end 366.522 -60.87872)
		(width 0.10795)
		(layer "B.Cu")
		(net "FM_CPU1_FIVR_FAULT_R_LVT3")
	)
	(segment
		(start 365.8489 -59.4487)
		(end 366.4077 -59.4487)
		(width 0.10795)
		(layer "B.Cu")
		(net "FM_CPU1_FIVR_FAULT_R_LVT3")
	)
	(segment
		(start 393.953746 -77.597)
		(end 393.851892 -77.495146)
		(width 0.10795)
		(layer "F.Cu")
		(net "FM_CPU0_FIVR_FAULT_R_LVT3")
	)
	(segment
		(start 393.851892 -77.495146)
		(end 393.717272 -77.495146)
		(width 0.10795)
		(layer "F.Cu")
		(net "FM_CPU0_FIVR_FAULT_R_LVT3")
	)
	(segment
		(start 393.71651 -77.494384)
		(end 393.65682 -77.494384)
		(width 0.10795)
		(layer "F.Cu")
		(net "FM_CPU0_FIVR_FAULT_R_LVT3")
	)
	(segment
		(start 394.6525 -77.597)
		(end 393.953746 -77.597)
		(width 0.10795)
		(layer "F.Cu")
		(net "FM_CPU0_FIVR_FAULT_R_LVT3")
	)
	(segment
		(start 393.250674 -77.088238)
		(end 392.295888 -77.088238)
		(width 0.10795)
		(layer "F.Cu")
		(net "FM_CPU0_FIVR_FAULT_R_LVT3")
	)
	(segment
		(start 393.717272 -77.495146)
		(end 393.71651 -77.494384)
		(width 0.10795)
		(layer "F.Cu")
		(net "FM_CPU0_FIVR_FAULT_R_LVT3")
	)
	(segment
		(start 393.65682 -77.494384)
		(end 393.250674 -77.088238)
		(width 0.10795)
		(layer "F.Cu")
		(net "FM_CPU0_FIVR_FAULT_R_LVT3")
	)
	(segment
		(start 400.977608 -102.721918)
		(end 400.598132 -102.721918)
		(width 0.0889)
		(layer "F.Cu")
		(net "PU_10GBE_LOM_PCI_DISABLE_N")
	)
	(segment
		(start 404.5712 -103.378)
		(end 403.340316 -103.378)
		(width 0.10795)
		(layer "F.Cu")
		(net "PU_10GBE_LOM_PCI_DISABLE_N")
	)
	(segment
		(start 401.911566 -102.456488)
		(end 401.809458 -102.558596)
		(width 0.0889)
		(layer "F.Cu")
		(net "PU_10GBE_LOM_PCI_DISABLE_N")
	)
	(segment
		(start 403.340316 -103.378)
		(end 402.761196 -102.79888)
		(width 0.10795)
		(layer "F.Cu")
		(net "PU_10GBE_LOM_PCI_DISABLE_N")
	)
	(segment
		(start 402.418804 -102.456488)
		(end 401.911566 -102.456488)
		(width 0.0889)
		(layer "F.Cu")
		(net "PU_10GBE_LOM_PCI_DISABLE_N")
	)
	(segment
		(start 400.598132 -102.721918)
		(end 400.465036 -102.855014)
		(width 0.0889)
		(layer "F.Cu")
		(net "PU_10GBE_LOM_PCI_DISABLE_N")
	)
	(segment
		(start 402.761196 -102.79888)
		(end 402.418804 -102.456488)
		(width 0.0889)
		(layer "F.Cu")
		(net "PU_10GBE_LOM_PCI_DISABLE_N")
	)
	(segment
		(start 401.809458 -102.558596)
		(end 401.14093 -102.558596)
		(width 0.0889)
		(layer "F.Cu")
		(net "PU_10GBE_LOM_PCI_DISABLE_N")
	)
	(segment
		(start 401.14093 -102.558596)
		(end 400.977608 -102.721918)
		(width 0.0889)
		(layer "F.Cu")
		(net "PU_10GBE_LOM_PCI_DISABLE_N")
	)
	(segment
		(start 405.8412 -104.648)
		(end 404.5712 -103.378)
		(width 0.10795)
		(layer "F.Cu")
		(net "PU_10GBE_LOM_PCI_DISABLE_N")
	)
	(segment
		(start 401.70481 -102.207314)
		(end 401.557236 -102.354888)
		(width 0.0889)
		(layer "F.Cu")
		(net "FM_10GBE_LOM_DISABLE_N")
	)
	(segment
		(start 405.2824 -103.7336)
		(end 404.6728 -103.124)
		(width 0.10795)
		(layer "F.Cu")
		(net "FM_10GBE_LOM_DISABLE_N")
	)
	(segment
		(start 403.435058 -103.124)
		(end 402.920708 -102.60965)
		(width 0.10795)
		(layer "F.Cu")
		(net "FM_10GBE_LOM_DISABLE_N")
	)
	(segment
		(start 401.557236 -102.354888)
		(end 400.880072 -102.354888)
		(width 0.0889)
		(layer "F.Cu")
		(net "FM_10GBE_LOM_DISABLE_N")
	)
	(segment
		(start 402.518372 -102.207314)
		(end 401.70481 -102.207314)
		(width 0.0889)
		(layer "F.Cu")
		(net "FM_10GBE_LOM_DISABLE_N")
	)
	(segment
		(start 405.8412 -103.7336)
		(end 405.2824 -103.7336)
		(width 0.10795)
		(layer "F.Cu")
		(net "FM_10GBE_LOM_DISABLE_N")
	)
	(segment
		(start 402.920708 -102.60965)
		(end 402.518372 -102.207314)
		(width 0.0889)
		(layer "F.Cu")
		(net "FM_10GBE_LOM_DISABLE_N")
	)
	(segment
		(start 404.6728 -103.124)
		(end 403.435058 -103.124)
		(width 0.10795)
		(layer "F.Cu")
		(net "FM_10GBE_LOM_DISABLE_N")
	)
	(segment
		(start 2.06248 -73.787)
		(end 2.06248 -74.51852)
		(width 0.10795)
		(layer "F.Cu")
		(net "SMB_SENSOR_TMP421_2_SDA")
	)
	(segment
		(start 2.06248 -74.51852)
		(end 2.032 -74.549)
		(width 0.10795)
		(layer "F.Cu")
		(net "SMB_SENSOR_TMP421_2_SDA")
	)
	(segment
		(start 2.032 -74.549)
		(end 2.032 -75.057)
		(width 0.10795)
		(layer "F.Cu")
		(net "SMB_SENSOR_TMP421_2_SDA")
	)
	(segment
		(start 1.27 -75.057)
		(end 1.27 -74.676)
		(width 0.10795)
		(layer "F.Cu")
		(net "SMB_SENSOR_TMP421_2_SCL")
	)
	(segment
		(start 1.41224 -74.53376)
		(end 1.41224 -73.787)
		(width 0.10795)
		(layer "F.Cu")
		(net "SMB_SENSOR_TMP421_2_SCL")
	)
	(segment
		(start 1.27 -74.676)
		(end 1.41224 -74.53376)
		(width 0.10795)
		(layer "F.Cu")
		(net "SMB_SENSOR_TMP421_2_SCL")
	)
	(segment
		(start 493.93348 -124.50318)
		(end 493.51438 -124.50318)
		(width 0.10795)
		(layer "F.Cu")
		(net "SMB_SENSOR_TMP421_1_SDA")
	)
	(segment
		(start 494.18494 -124.25172)
		(end 493.93348 -124.50318)
		(width 0.10795)
		(layer "F.Cu")
		(net "SMB_SENSOR_TMP421_1_SDA")
	)
	(segment
		(start 492.24184 -122.60326)
		(end 492.08944 -122.45086)
		(width 0.10795)
		(layer "F.Cu")
		(net "SMB_SENSOR_TMP421_1_SDA")
	)
	(segment
		(start 493.24006 -123.05538)
		(end 492.78794 -122.60326)
		(width 0.10795)
		(layer "F.Cu")
		(net "SMB_SENSOR_TMP421_1_SDA")
	)
	(segment
		(start 493.51438 -124.50318)
		(end 493.24006 -124.22886)
		(width 0.10795)
		(layer "F.Cu")
		(net "SMB_SENSOR_TMP421_1_SDA")
	)
	(segment
		(start 492.78794 -122.60326)
		(end 492.24184 -122.60326)
		(width 0.10795)
		(layer "F.Cu")
		(net "SMB_SENSOR_TMP421_1_SDA")
	)
	(segment
		(start 492.08944 -122.45086)
		(end 491.2106 -122.45086)
		(width 0.10795)
		(layer "F.Cu")
		(net "SMB_SENSOR_TMP421_1_SDA")
	)
	(segment
		(start 493.24006 -124.22886)
		(end 493.24006 -123.05538)
		(width 0.10795)
		(layer "F.Cu")
		(net "SMB_SENSOR_TMP421_1_SDA")
	)
	(segment
		(start 491.93196 -123.1011)
		(end 491.2106 -123.1011)
		(width 0.10795)
		(layer "F.Cu")
		(net "SMB_SENSOR_TMP421_1_SCL")
	)
	(segment
		(start 492.686848 -122.8471)
		(end 492.18596 -122.8471)
		(width 0.10795)
		(layer "F.Cu")
		(net "SMB_SENSOR_TMP421_1_SCL")
	)
	(segment
		(start 493.413288 -124.74702)
		(end 492.99622 -124.329952)
		(width 0.10795)
		(layer "F.Cu")
		(net "SMB_SENSOR_TMP421_1_SCL")
	)
	(segment
		(start 492.99622 -124.329952)
		(end 492.99622 -123.156472)
		(width 0.10795)
		(layer "F.Cu")
		(net "SMB_SENSOR_TMP421_1_SCL")
	)
	(segment
		(start 492.18596 -122.8471)
		(end 491.93196 -123.1011)
		(width 0.10795)
		(layer "F.Cu")
		(net "SMB_SENSOR_TMP421_1_SCL")
	)
	(segment
		(start 494.1697 -125.03912)
		(end 493.8776 -124.74702)
		(width 0.10795)
		(layer "F.Cu")
		(net "SMB_SENSOR_TMP421_1_SCL")
	)
	(segment
		(start 492.99622 -123.156472)
		(end 492.686848 -122.8471)
		(width 0.10795)
		(layer "F.Cu")
		(net "SMB_SENSOR_TMP421_1_SCL")
	)
	(segment
		(start 493.8776 -124.74702)
		(end 493.413288 -124.74702)
		(width 0.10795)
		(layer "F.Cu")
		(net "SMB_SENSOR_TMP421_1_SCL")
	)
	(segment
		(start 16.256 -80.391)
		(end 16.3195 -80.4545)
		(width 0.10795)
		(layer "F.Cu")
		(net "SMB_BMC_PMBUS_STBY_LVC3_SDA")
	)
	(segment
		(start 419.862 -19.7104)
		(end 419.862 -20.7645)
		(width 0.10795)
		(layer "F.Cu")
		(net "SMB_BMC_PMBUS_STBY_LVC3_SDA")
	)
	(segment
		(start 16.3195 -80.4545)
		(end 16.891 -80.4545)
		(width 0.10795)
		(layer "F.Cu")
		(net "SMB_BMC_PMBUS_STBY_LVC3_SDA")
	)
	(via
		(at 391.8204 -148.773896)
		(size 0.508)
		(drill 0.254)
		(layers "F.Cu" "B.Cu")
		(net "SMB_BMC_PMBUS_STBY_LVC3_SDA")
	)
	(via
		(at 185.322464 -155.159202)
		(size 0.508)
		(drill 0.254)
		(layers "F.Cu" "B.Cu")
		(net "SMB_BMC_PMBUS_STBY_LVC3_SDA")
	)
	(via
		(at 402.209 -76.99248)
		(size 0.508)
		(drill 0.254)
		(layers "F.Cu" "B.Cu")
		(net "SMB_BMC_PMBUS_STBY_LVC3_SDA")
	)
	(via
		(at 418.98062 -95.29318)
		(size 0.6604)
		(drill 0.3302)
		(layers "F.Cu" "B.Cu")
		(net "SMB_BMC_PMBUS_STBY_LVC3_SDA")
	)
	(via
		(at 431.104294 -132.128768)
		(size 0.508)
		(drill 0.254)
		(layers "F.Cu" "B.Cu")
		(net "SMB_BMC_PMBUS_STBY_LVC3_SDA")
	)
	(via
		(at 424.4467 -122.174)
		(size 0.508)
		(drill 0.254)
		(layers "F.Cu" "B.Cu")
		(net "SMB_BMC_PMBUS_STBY_LVC3_SDA")
	)
	(via
		(at 16.256 -80.391)
		(size 0.508)
		(drill 0.254)
		(layers "F.Cu" "B.Cu")
		(net "SMB_BMC_PMBUS_STBY_LVC3_SDA")
	)
	(via
		(at 478.418906 -50.752502)
		(size 0.508)
		(drill 0.254)
		(layers "F.Cu" "B.Cu")
		(net "SMB_BMC_PMBUS_STBY_LVC3_SDA")
	)
	(via
		(at 20.0533 -38.81374)
		(size 0.508)
		(drill 0.254)
		(layers "F.Cu" "B.Cu")
		(net "SMB_BMC_PMBUS_STBY_LVC3_SDA")
	)
	(via
		(at 419.862 -19.7104)
		(size 0.508)
		(drill 0.254)
		(layers "F.Cu" "B.Cu")
		(net "SMB_BMC_PMBUS_STBY_LVC3_SDA")
	)
	(via
		(at 407.3017 -157.0355)
		(size 0.508)
		(drill 0.254)
		(layers "F.Cu" "B.Cu")
		(net "SMB_BMC_PMBUS_STBY_LVC3_SDA")
	)
	(segment
		(start 435.2163 -156.408628)
		(end 435.2163 -150.430738)
		(width 0.10795)
		(layer "B.Cu")
		(net "SMB_BMC_PMBUS_STBY_LVC3_SDA")
	)
	(segment
		(start 407.940256 -157.975808)
		(end 433.64912 -157.975808)
		(width 0.10795)
		(layer "B.Cu")
		(net "SMB_BMC_PMBUS_STBY_LVC3_SDA")
	)
	(segment
		(start 402.326602 -75.409298)
		(end 402.326602 -75.008994)
		(width 0.10795)
		(layer "B.Cu")
		(net "SMB_BMC_PMBUS_STBY_LVC3_SDA")
	)
	(segment
		(start 403.606 -76.99248)
		(end 402.209 -76.99248)
		(width 0.10795)
		(layer "B.Cu")
		(net "SMB_BMC_PMBUS_STBY_LVC3_SDA")
	)
	(segment
		(start 401.786598 -75.949302)
		(end 402.326602 -75.409298)
		(width 0.10795)
		(layer "B.Cu")
		(net "SMB_BMC_PMBUS_STBY_LVC3_SDA")
	)
	(segment
		(start 415.692336 -83.83905)
		(end 415.41573 -83.83905)
		(width 0.10795)
		(layer "B.Cu")
		(net "SMB_BMC_PMBUS_STBY_LVC3_SDA")
	)
	(segment
		(start 431.78222 -134.170674)
		(end 431.3936 -133.782054)
		(width 0.10795)
		(layer "B.Cu")
		(net "SMB_BMC_PMBUS_STBY_LVC3_SDA")
	)
	(segment
		(start 437.027828 -137.8966)
		(end 437.027828 -135.38835)
		(width 0.10795)
		(layer "B.Cu")
		(net "SMB_BMC_PMBUS_STBY_LVC3_SDA")
	)
	(segment
		(start 418.7444 -95.5294)
		(end 418.98062 -95.29318)
		(width 0.10795)
		(layer "B.Cu")
		(net "SMB_BMC_PMBUS_STBY_LVC3_SDA")
	)
	(segment
		(start 420.051992 -117.41912)
		(end 420.051992 -102.718362)
		(width 0.10795)
		(layer "B.Cu")
		(net "SMB_BMC_PMBUS_STBY_LVC3_SDA")
	)
	(segment
		(start 402.16328 -76.99248)
		(end 401.786598 -76.615798)
		(width 0.10795)
		(layer "B.Cu")
		(net "SMB_BMC_PMBUS_STBY_LVC3_SDA")
	)
	(segment
		(start 424.4467 -122.174)
		(end 424.4467 -121.813828)
		(width 0.10795)
		(layer "B.Cu")
		(net "SMB_BMC_PMBUS_STBY_LVC3_SDA")
	)
	(segment
		(start 424.4467 -121.813828)
		(end 420.051992 -117.41912)
		(width 0.10795)
		(layer "B.Cu")
		(net "SMB_BMC_PMBUS_STBY_LVC3_SDA")
	)
	(segment
		(start 420.13251 -88.279224)
		(end 415.692336 -83.83905)
		(width 0.10795)
		(layer "B.Cu")
		(net "SMB_BMC_PMBUS_STBY_LVC3_SDA")
	)
	(segment
		(start 418.98062 -94.484952)
		(end 420.13251 -93.333062)
		(width 0.10795)
		(layer "B.Cu")
		(net "SMB_BMC_PMBUS_STBY_LVC3_SDA")
	)
	(segment
		(start 435.2163 -150.430738)
		(end 435.232302 -150.414736)
		(width 0.10795)
		(layer "B.Cu")
		(net "SMB_BMC_PMBUS_STBY_LVC3_SDA")
	)
	(segment
		(start 420.13251 -93.333062)
		(end 420.13251 -88.279224)
		(width 0.10795)
		(layer "B.Cu")
		(net "SMB_BMC_PMBUS_STBY_LVC3_SDA")
	)
	(segment
		(start 435.232302 -150.414736)
		(end 435.232302 -148.912326)
		(width 0.10795)
		(layer "B.Cu")
		(net "SMB_BMC_PMBUS_STBY_LVC3_SDA")
	)
	(segment
		(start 405.099012 -79.803498)
		(end 405.099012 -77.42174)
		(width 0.10795)
		(layer "B.Cu")
		(net "SMB_BMC_PMBUS_STBY_LVC3_SDA")
	)
	(segment
		(start 436.4101 -138.514328)
		(end 437.027828 -137.8966)
		(width 0.10795)
		(layer "B.Cu")
		(net "SMB_BMC_PMBUS_STBY_LVC3_SDA")
	)
	(segment
		(start 415.41573 -83.83905)
		(end 412.821374 -81.244694)
		(width 0.10795)
		(layer "B.Cu")
		(net "SMB_BMC_PMBUS_STBY_LVC3_SDA")
	)
	(segment
		(start 435.232302 -148.912326)
		(end 435.780434 -148.364194)
		(width 0.10795)
		(layer "B.Cu")
		(net "SMB_BMC_PMBUS_STBY_LVC3_SDA")
	)
	(segment
		(start 406.540208 -81.244694)
		(end 405.099012 -79.803498)
		(width 0.10795)
		(layer "B.Cu")
		(net "SMB_BMC_PMBUS_STBY_LVC3_SDA")
	)
	(segment
		(start 401.786598 -76.615798)
		(end 401.786598 -75.949302)
		(width 0.10795)
		(layer "B.Cu")
		(net "SMB_BMC_PMBUS_STBY_LVC3_SDA")
	)
	(segment
		(start 435.780434 -142.780766)
		(end 436.4101 -142.1511)
		(width 0.10795)
		(layer "B.Cu")
		(net "SMB_BMC_PMBUS_STBY_LVC3_SDA")
	)
	(segment
		(start 407.3017 -157.337252)
		(end 407.940256 -157.975808)
		(width 0.10795)
		(layer "B.Cu")
		(net "SMB_BMC_PMBUS_STBY_LVC3_SDA")
	)
	(segment
		(start 412.821374 -81.244694)
		(end 406.540208 -81.244694)
		(width 0.10795)
		(layer "B.Cu")
		(net "SMB_BMC_PMBUS_STBY_LVC3_SDA")
	)
	(segment
		(start 402.209 -76.99248)
		(end 402.16328 -76.99248)
		(width 0.10795)
		(layer "B.Cu")
		(net "SMB_BMC_PMBUS_STBY_LVC3_SDA")
	)
	(segment
		(start 435.780434 -148.364194)
		(end 435.780434 -142.780766)
		(width 0.10795)
		(layer "B.Cu")
		(net "SMB_BMC_PMBUS_STBY_LVC3_SDA")
	)
	(segment
		(start 431.3936 -133.782054)
		(end 431.3936 -132.418074)
		(width 0.10795)
		(layer "B.Cu")
		(net "SMB_BMC_PMBUS_STBY_LVC3_SDA")
	)
	(segment
		(start 418.98062 -95.29318)
		(end 418.98062 -94.484952)
		(width 0.10795)
		(layer "B.Cu")
		(net "SMB_BMC_PMBUS_STBY_LVC3_SDA")
	)
	(segment
		(start 437.027828 -135.38835)
		(end 435.810152 -134.170674)
		(width 0.10795)
		(layer "B.Cu")
		(net "SMB_BMC_PMBUS_STBY_LVC3_SDA")
	)
	(segment
		(start 431.3936 -132.418074)
		(end 431.104294 -132.128768)
		(width 0.10795)
		(layer "B.Cu")
		(net "SMB_BMC_PMBUS_STBY_LVC3_SDA")
	)
	(segment
		(start 407.3017 -157.0355)
		(end 407.3017 -157.337252)
		(width 0.10795)
		(layer "B.Cu")
		(net "SMB_BMC_PMBUS_STBY_LVC3_SDA")
	)
	(segment
		(start 405.099012 -77.42174)
		(end 404.669752 -76.99248)
		(width 0.10795)
		(layer "B.Cu")
		(net "SMB_BMC_PMBUS_STBY_LVC3_SDA")
	)
	(segment
		(start 401.828 -74.510392)
		(end 401.828 -74.295)
		(width 0.10795)
		(layer "B.Cu")
		(net "SMB_BMC_PMBUS_STBY_LVC3_SDA")
	)
	(segment
		(start 435.810152 -134.170674)
		(end 431.78222 -134.170674)
		(width 0.10795)
		(layer "B.Cu")
		(net "SMB_BMC_PMBUS_STBY_LVC3_SDA")
	)
	(segment
		(start 420.051992 -102.718362)
		(end 418.7444 -101.41077)
		(width 0.10795)
		(layer "B.Cu")
		(net "SMB_BMC_PMBUS_STBY_LVC3_SDA")
	)
	(segment
		(start 436.4101 -142.1511)
		(end 436.4101 -138.514328)
		(width 0.10795)
		(layer "B.Cu")
		(net "SMB_BMC_PMBUS_STBY_LVC3_SDA")
	)
	(segment
		(start 418.7444 -101.41077)
		(end 418.7444 -95.5294)
		(width 0.10795)
		(layer "B.Cu")
		(net "SMB_BMC_PMBUS_STBY_LVC3_SDA")
	)
	(segment
		(start 404.669752 -76.99248)
		(end 403.606 -76.99248)
		(width 0.10795)
		(layer "B.Cu")
		(net "SMB_BMC_PMBUS_STBY_LVC3_SDA")
	)
	(segment
		(start 402.326602 -75.008994)
		(end 401.828 -74.510392)
		(width 0.10795)
		(layer "B.Cu")
		(net "SMB_BMC_PMBUS_STBY_LVC3_SDA")
	)
	(segment
		(start 433.64912 -157.975808)
		(end 435.2163 -156.408628)
		(width 0.10795)
		(layer "B.Cu")
		(net "SMB_BMC_PMBUS_STBY_LVC3_SDA")
	)
	(segment
		(start 401.808696 -76.592176)
		(end 402.209 -76.99248)
		(width 0.089408)
		(layer "In2.Cu")
		(net "SMB_BMC_PMBUS_STBY_LVC3_SDA")
	)
	(segment
		(start 469.71585 -51.817778)
		(end 469.714326 -51.819302)
		(width 0.089408)
		(layer "In2.Cu")
		(net "SMB_BMC_PMBUS_STBY_LVC3_SDA")
	)
	(segment
		(start 407.72588 -55.859426)
		(end 407.72588 -59.68492)
		(width 0.089408)
		(layer "In2.Cu")
		(net "SMB_BMC_PMBUS_STBY_LVC3_SDA")
	)
	(segment
		(start 408.47645 -55.108856)
		(end 407.72588 -55.859426)
		(width 0.089408)
		(layer "In2.Cu")
		(net "SMB_BMC_PMBUS_STBY_LVC3_SDA")
	)
	(segment
		(start 402.032724 -75.932284)
		(end 401.808696 -76.156312)
		(width 0.089408)
		(layer "In2.Cu")
		(net "SMB_BMC_PMBUS_STBY_LVC3_SDA")
	)
	(segment
		(start 478.418906 -50.752502)
		(end 478.139252 -51.032156)
		(width 0.089408)
		(layer "In2.Cu")
		(net "SMB_BMC_PMBUS_STBY_LVC3_SDA")
	)
	(segment
		(start 464.038188 -54.552088)
		(end 436.522114 -54.552088)
		(width 0.089408)
		(layer "In2.Cu")
		(net "SMB_BMC_PMBUS_STBY_LVC3_SDA")
	)
	(segment
		(start 478.139252 -51.032156)
		(end 475.444058 -51.032156)
		(width 0.089408)
		(layer "In2.Cu")
		(net "SMB_BMC_PMBUS_STBY_LVC3_SDA")
	)
	(segment
		(start 435.395878 -53.425852)
		(end 427.567598 -53.425852)
		(width 0.089408)
		(layer "In2.Cu")
		(net "SMB_BMC_PMBUS_STBY_LVC3_SDA")
	)
	(segment
		(start 408.33802 -66.26352)
		(end 408.33802 -68.689474)
		(width 0.089408)
		(layer "In2.Cu")
		(net "SMB_BMC_PMBUS_STBY_LVC3_SDA")
	)
	(segment
		(start 426.82033 -54.17312)
		(end 424.504866 -54.17312)
		(width 0.089408)
		(layer "In2.Cu")
		(net "SMB_BMC_PMBUS_STBY_LVC3_SDA")
	)
	(segment
		(start 406.957784 -60.453016)
		(end 406.957784 -61.46673)
		(width 0.089408)
		(layer "In2.Cu")
		(net "SMB_BMC_PMBUS_STBY_LVC3_SDA")
	)
	(segment
		(start 420.331646 -53.6702)
		(end 414.817306 -53.6702)
		(width 0.089408)
		(layer "In2.Cu")
		(net "SMB_BMC_PMBUS_STBY_LVC3_SDA")
	)
	(segment
		(start 403.450552 -73.89876)
		(end 402.791422 -74.55789)
		(width 0.089408)
		(layer "In2.Cu")
		(net "SMB_BMC_PMBUS_STBY_LVC3_SDA")
	)
	(segment
		(start 407.85542 -62.381892)
		(end 407.85542 -65.78092)
		(width 0.089408)
		(layer "In2.Cu")
		(net "SMB_BMC_PMBUS_STBY_LVC3_SDA")
	)
	(segment
		(start 409.517342 -53.051964)
		(end 408.47645 -54.092856)
		(width 0.089408)
		(layer "In2.Cu")
		(net "SMB_BMC_PMBUS_STBY_LVC3_SDA")
	)
	(segment
		(start 414.817306 -53.6702)
		(end 414.19907 -53.051964)
		(width 0.089408)
		(layer "In2.Cu")
		(net "SMB_BMC_PMBUS_STBY_LVC3_SDA")
	)
	(segment
		(start 407.85542 -65.78092)
		(end 408.33802 -66.26352)
		(width 0.089408)
		(layer "In2.Cu")
		(net "SMB_BMC_PMBUS_STBY_LVC3_SDA")
	)
	(segment
		(start 467.738714 -53.723032)
		(end 467.738714 -54.61381)
		(width 0.089408)
		(layer "In2.Cu")
		(net "SMB_BMC_PMBUS_STBY_LVC3_SDA")
	)
	(segment
		(start 402.791422 -75.313794)
		(end 402.172932 -75.932284)
		(width 0.089408)
		(layer "In2.Cu")
		(net "SMB_BMC_PMBUS_STBY_LVC3_SDA")
	)
	(segment
		(start 475.444058 -51.032156)
		(end 474.658436 -51.817778)
		(width 0.089408)
		(layer "In2.Cu")
		(net "SMB_BMC_PMBUS_STBY_LVC3_SDA")
	)
	(segment
		(start 408.47645 -54.092856)
		(end 408.47645 -55.108856)
		(width 0.089408)
		(layer "In2.Cu")
		(net "SMB_BMC_PMBUS_STBY_LVC3_SDA")
	)
	(segment
		(start 407.008584 -61.535056)
		(end 407.85542 -62.381892)
		(width 0.089408)
		(layer "In2.Cu")
		(net "SMB_BMC_PMBUS_STBY_LVC3_SDA")
	)
	(segment
		(start 402.172932 -75.932284)
		(end 402.032724 -75.932284)
		(width 0.089408)
		(layer "In2.Cu")
		(net "SMB_BMC_PMBUS_STBY_LVC3_SDA")
	)
	(segment
		(start 427.567598 -53.425852)
		(end 426.82033 -54.17312)
		(width 0.089408)
		(layer "In2.Cu")
		(net "SMB_BMC_PMBUS_STBY_LVC3_SDA")
	)
	(segment
		(start 407.72588 -59.68492)
		(end 406.957784 -60.453016)
		(width 0.089408)
		(layer "In2.Cu")
		(net "SMB_BMC_PMBUS_STBY_LVC3_SDA")
	)
	(segment
		(start 414.19907 -53.051964)
		(end 409.517342 -53.051964)
		(width 0.089408)
		(layer "In2.Cu")
		(net "SMB_BMC_PMBUS_STBY_LVC3_SDA")
	)
	(segment
		(start 469.642444 -51.819302)
		(end 467.738714 -53.723032)
		(width 0.089408)
		(layer "In2.Cu")
		(net "SMB_BMC_PMBUS_STBY_LVC3_SDA")
	)
	(segment
		(start 423.516552 -53.184806)
		(end 420.81704 -53.184806)
		(width 0.089408)
		(layer "In2.Cu")
		(net "SMB_BMC_PMBUS_STBY_LVC3_SDA")
	)
	(segment
		(start 474.658436 -51.817778)
		(end 469.71585 -51.817778)
		(width 0.089408)
		(layer "In2.Cu")
		(net "SMB_BMC_PMBUS_STBY_LVC3_SDA")
	)
	(segment
		(start 407.008584 -61.51753)
		(end 407.008584 -61.535056)
		(width 0.089408)
		(layer "In2.Cu")
		(net "SMB_BMC_PMBUS_STBY_LVC3_SDA")
	)
	(segment
		(start 436.522114 -54.552088)
		(end 435.395878 -53.425852)
		(width 0.089408)
		(layer "In2.Cu")
		(net "SMB_BMC_PMBUS_STBY_LVC3_SDA")
	)
	(segment
		(start 466.812122 -55.540402)
		(end 465.026502 -55.540402)
		(width 0.089408)
		(layer "In2.Cu")
		(net "SMB_BMC_PMBUS_STBY_LVC3_SDA")
	)
	(segment
		(start 402.791422 -74.55789)
		(end 402.791422 -75.313794)
		(width 0.089408)
		(layer "In2.Cu")
		(net "SMB_BMC_PMBUS_STBY_LVC3_SDA")
	)
	(segment
		(start 401.808696 -76.156312)
		(end 401.808696 -76.592176)
		(width 0.089408)
		(layer "In2.Cu")
		(net "SMB_BMC_PMBUS_STBY_LVC3_SDA")
	)
	(segment
		(start 467.738714 -54.61381)
		(end 466.812122 -55.540402)
		(width 0.089408)
		(layer "In2.Cu")
		(net "SMB_BMC_PMBUS_STBY_LVC3_SDA")
	)
	(segment
		(start 403.450552 -73.576942)
		(end 403.450552 -73.89876)
		(width 0.089408)
		(layer "In2.Cu")
		(net "SMB_BMC_PMBUS_STBY_LVC3_SDA")
	)
	(segment
		(start 469.714326 -51.819302)
		(end 469.642444 -51.819302)
		(width 0.089408)
		(layer "In2.Cu")
		(net "SMB_BMC_PMBUS_STBY_LVC3_SDA")
	)
	(segment
		(start 408.33802 -68.689474)
		(end 403.450552 -73.576942)
		(width 0.089408)
		(layer "In2.Cu")
		(net "SMB_BMC_PMBUS_STBY_LVC3_SDA")
	)
	(segment
		(start 406.957784 -61.46673)
		(end 407.008584 -61.51753)
		(width 0.089408)
		(layer "In2.Cu")
		(net "SMB_BMC_PMBUS_STBY_LVC3_SDA")
	)
	(segment
		(start 424.504866 -54.17312)
		(end 423.516552 -53.184806)
		(width 0.089408)
		(layer "In2.Cu")
		(net "SMB_BMC_PMBUS_STBY_LVC3_SDA")
	)
	(segment
		(start 420.81704 -53.184806)
		(end 420.331646 -53.6702)
		(width 0.089408)
		(layer "In2.Cu")
		(net "SMB_BMC_PMBUS_STBY_LVC3_SDA")
	)
	(segment
		(start 465.026502 -55.540402)
		(end 464.038188 -54.552088)
		(width 0.089408)
		(layer "In2.Cu")
		(net "SMB_BMC_PMBUS_STBY_LVC3_SDA")
	)
	(segment
		(start 18.446496 -30.868366)
		(end 18.446496 -38.5318)
		(width 0.089408)
		(layer "In4.Cu")
		(net "SMB_BMC_PMBUS_STBY_LVC3_SDA")
	)
	(segment
		(start 472.274392 -32.406336)
		(end 472.274392 -31.916116)
		(width 0.089408)
		(layer "In4.Cu")
		(net "SMB_BMC_PMBUS_STBY_LVC3_SDA")
	)
	(segment
		(start 471.9955 -31.479236)
		(end 471.995754 -31.478982)
		(width 0.089408)
		(layer "In4.Cu")
		(net "SMB_BMC_PMBUS_STBY_LVC3_SDA")
	)
	(segment
		(start 462.618074 -27.744674)
		(end 460.7306 -25.8572)
		(width 0.089408)
		(layer "In4.Cu")
		(net "SMB_BMC_PMBUS_STBY_LVC3_SDA")
	)
	(segment
		(start 478.725738 -37.738304)
		(end 476.59671 -35.609276)
		(width 0.089408)
		(layer "In4.Cu")
		(net "SMB_BMC_PMBUS_STBY_LVC3_SDA")
	)
	(segment
		(start 454.118472 -26.293572)
		(end 450.96176 -23.13686)
		(width 0.089408)
		(layer "In4.Cu")
		(net "SMB_BMC_PMBUS_STBY_LVC3_SDA")
	)
	(segment
		(start 478.418906 -50.752502)
		(end 479.053652 -50.117756)
		(width 0.089408)
		(layer "In4.Cu")
		(net "SMB_BMC_PMBUS_STBY_LVC3_SDA")
	)
	(segment
		(start 472.274392 -32.836612)
		(end 472.274646 -32.836358)
		(width 0.089408)
		(layer "In4.Cu")
		(net "SMB_BMC_PMBUS_STBY_LVC3_SDA")
	)
	(segment
		(start 455.163174 -26.293572)
		(end 454.118472 -26.293572)
		(width 0.089408)
		(layer "In4.Cu")
		(net "SMB_BMC_PMBUS_STBY_LVC3_SDA")
	)
	(segment
		(start -0.508 -29.972)
		(end -1.016 -30.48)
		(width 0.089408)
		(layer "In4.Cu")
		(net "SMB_BMC_PMBUS_STBY_LVC3_SDA")
	)
	(segment
		(start 472.70289 -35.220656)
		(end 472.274138 -34.791904)
		(width 0.089408)
		(layer "In4.Cu")
		(net "SMB_BMC_PMBUS_STBY_LVC3_SDA")
	)
	(segment
		(start 10.033 -23.8506)
		(end 10.033 -27.564334)
		(width 0.089408)
		(layer "In4.Cu")
		(net "SMB_BMC_PMBUS_STBY_LVC3_SDA")
	)
	(segment
		(start 450.96176 -20.712684)
		(end 449.444364 -19.195288)
		(width 0.089408)
		(layer "In4.Cu")
		(net "SMB_BMC_PMBUS_STBY_LVC3_SDA")
	)
	(segment
		(start 19.738594 -39.128446)
		(end 20.0533 -38.81374)
		(width 0.089408)
		(layer "In4.Cu")
		(net "SMB_BMC_PMBUS_STBY_LVC3_SDA")
	)
	(segment
		(start 449.444364 -19.195288)
		(end 448.4624 -19.195288)
		(width 0.089408)
		(layer "In4.Cu")
		(net "SMB_BMC_PMBUS_STBY_LVC3_SDA")
	)
	(segment
		(start 480.034854 -47.347378)
		(end 480.034854 -38.602158)
		(width 0.089408)
		(layer "In4.Cu")
		(net "SMB_BMC_PMBUS_STBY_LVC3_SDA")
	)
	(segment
		(start -1.016 -30.48)
		(end -1.83007 -30.48)
		(width 0.089408)
		(layer "In4.Cu")
		(net "SMB_BMC_PMBUS_STBY_LVC3_SDA")
	)
	(segment
		(start 20.343876 -29.171138)
		(end 20.143724 -29.171138)
		(width 0.089408)
		(layer "In4.Cu")
		(net "SMB_BMC_PMBUS_STBY_LVC3_SDA")
	)
	(segment
		(start 471.995754 -30.60573)
		(end 469.134698 -27.744674)
		(width 0.089408)
		(layer "In4.Cu")
		(net "SMB_BMC_PMBUS_STBY_LVC3_SDA")
	)
	(segment
		(start 23.152608 -29.171392)
		(end 20.34413 -29.171392)
		(width 0.089408)
		(layer "In4.Cu")
		(net "SMB_BMC_PMBUS_STBY_LVC3_SDA")
	)
	(segment
		(start 472.274138 -32.677862)
		(end 472.274138 -32.40659)
		(width 0.089408)
		(layer "In4.Cu")
		(net "SMB_BMC_PMBUS_STBY_LVC3_SDA")
	)
	(segment
		(start 479.053652 -50.117756)
		(end 479.053652 -48.32858)
		(width 0.089408)
		(layer "In4.Cu")
		(net "SMB_BMC_PMBUS_STBY_LVC3_SDA")
	)
	(segment
		(start 432.393852 -19.422872)
		(end 431.028348 -20.788376)
		(width 0.089408)
		(layer "In4.Cu")
		(net "SMB_BMC_PMBUS_STBY_LVC3_SDA")
	)
	(segment
		(start 24.371808 -25.641808)
		(end 21.138388 -25.641808)
		(width 0.089408)
		(layer "In4.Cu")
		(net "SMB_BMC_PMBUS_STBY_LVC3_SDA")
	)
	(segment
		(start 19.257518 -21.536914)
		(end 15.093188 -21.536914)
		(width 0.089408)
		(layer "In4.Cu")
		(net "SMB_BMC_PMBUS_STBY_LVC3_SDA")
	)
	(segment
		(start 432.527456 -19.422872)
		(end 432.393852 -19.422872)
		(width 0.089408)
		(layer "In4.Cu")
		(net "SMB_BMC_PMBUS_STBY_LVC3_SDA")
	)
	(segment
		(start 474.2688 -35.220656)
		(end 472.70289 -35.220656)
		(width 0.089408)
		(layer "In4.Cu")
		(net "SMB_BMC_PMBUS_STBY_LVC3_SDA")
	)
	(segment
		(start 448.4624 -19.195288)
		(end 447.379598 -18.112486)
		(width 0.089408)
		(layer "In4.Cu")
		(net "SMB_BMC_PMBUS_STBY_LVC3_SDA")
	)
	(segment
		(start 20.34413 -29.171392)
		(end 20.343876 -29.171138)
		(width 0.089408)
		(layer "In4.Cu")
		(net "SMB_BMC_PMBUS_STBY_LVC3_SDA")
	)
	(segment
		(start 20.09902 -22.378416)
		(end 19.257518 -21.536914)
		(width 0.089408)
		(layer "In4.Cu")
		(net "SMB_BMC_PMBUS_STBY_LVC3_SDA")
	)
	(segment
		(start 480.034854 -38.602158)
		(end 479.171 -37.738304)
		(width 0.089408)
		(layer "In4.Cu")
		(net "SMB_BMC_PMBUS_STBY_LVC3_SDA")
	)
	(segment
		(start 24.741124 -26.67)
		(end 24.741124 -27.582876)
		(width 0.089408)
		(layer "In4.Cu")
		(net "SMB_BMC_PMBUS_STBY_LVC3_SDA")
	)
	(segment
		(start 479.171 -37.738304)
		(end 478.725738 -37.738304)
		(width 0.089408)
		(layer "In4.Cu")
		(net "SMB_BMC_PMBUS_STBY_LVC3_SDA")
	)
	(segment
		(start 427.823122 -20.788376)
		(end 426.745146 -19.7104)
		(width 0.089408)
		(layer "In4.Cu")
		(net "SMB_BMC_PMBUS_STBY_LVC3_SDA")
	)
	(segment
		(start 19.043142 -39.128446)
		(end 19.738594 -39.128446)
		(width 0.089408)
		(layer "In4.Cu")
		(net "SMB_BMC_PMBUS_STBY_LVC3_SDA")
	)
	(segment
		(start 24.741124 -27.582876)
		(end 23.152608 -29.171392)
		(width 0.089408)
		(layer "In4.Cu")
		(net "SMB_BMC_PMBUS_STBY_LVC3_SDA")
	)
	(segment
		(start 472.274392 -33.168336)
		(end 472.274392 -32.836612)
		(width 0.089408)
		(layer "In4.Cu")
		(net "SMB_BMC_PMBUS_STBY_LVC3_SDA")
	)
	(segment
		(start 440.130438 -18.112486)
		(end 439.180732 -19.062192)
		(width 0.089408)
		(layer "In4.Cu")
		(net "SMB_BMC_PMBUS_STBY_LVC3_SDA")
	)
	(segment
		(start 472.274646 -32.67837)
		(end 472.274138 -32.677862)
		(width 0.089408)
		(layer "In4.Cu")
		(net "SMB_BMC_PMBUS_STBY_LVC3_SDA")
	)
	(segment
		(start 432.888136 -19.062192)
		(end 432.527456 -19.422872)
		(width 0.089408)
		(layer "In4.Cu")
		(net "SMB_BMC_PMBUS_STBY_LVC3_SDA")
	)
	(segment
		(start 460.7306 -25.8572)
		(end 455.599546 -25.8572)
		(width 0.089408)
		(layer "In4.Cu")
		(net "SMB_BMC_PMBUS_STBY_LVC3_SDA")
	)
	(segment
		(start 8.641334 -28.956)
		(end 0 -28.956)
		(width 0.089408)
		(layer "In4.Cu")
		(net "SMB_BMC_PMBUS_STBY_LVC3_SDA")
	)
	(segment
		(start 14.39291 -22.237192)
		(end 11.664188 -22.237192)
		(width 0.089408)
		(layer "In4.Cu")
		(net "SMB_BMC_PMBUS_STBY_LVC3_SDA")
	)
	(segment
		(start 472.274138 -32.40659)
		(end 472.274392 -32.406336)
		(width 0.089408)
		(layer "In4.Cu")
		(net "SMB_BMC_PMBUS_STBY_LVC3_SDA")
	)
	(segment
		(start 471.995754 -31.478982)
		(end 471.995754 -30.60573)
		(width 0.089408)
		(layer "In4.Cu")
		(net "SMB_BMC_PMBUS_STBY_LVC3_SDA")
	)
	(segment
		(start 472.274646 -32.836358)
		(end 472.274646 -32.67837)
		(width 0.089408)
		(layer "In4.Cu")
		(net "SMB_BMC_PMBUS_STBY_LVC3_SDA")
	)
	(segment
		(start 431.028348 -20.788376)
		(end 427.823122 -20.788376)
		(width 0.089408)
		(layer "In4.Cu")
		(net "SMB_BMC_PMBUS_STBY_LVC3_SDA")
	)
	(segment
		(start 471.9955 -31.637224)
		(end 471.9955 -31.479236)
		(width 0.089408)
		(layer "In4.Cu")
		(net "SMB_BMC_PMBUS_STBY_LVC3_SDA")
	)
	(segment
		(start 455.599546 -25.8572)
		(end 455.163174 -26.293572)
		(width 0.089408)
		(layer "In4.Cu")
		(net "SMB_BMC_PMBUS_STBY_LVC3_SDA")
	)
	(segment
		(start 472.274392 -31.916116)
		(end 471.9955 -31.637224)
		(width 0.089408)
		(layer "In4.Cu")
		(net "SMB_BMC_PMBUS_STBY_LVC3_SDA")
	)
	(segment
		(start 426.745146 -19.7104)
		(end 419.862 -19.7104)
		(width 0.089408)
		(layer "In4.Cu")
		(net "SMB_BMC_PMBUS_STBY_LVC3_SDA")
	)
	(segment
		(start 450.96176 -23.13686)
		(end 450.96176 -20.712684)
		(width 0.089408)
		(layer "In4.Cu")
		(net "SMB_BMC_PMBUS_STBY_LVC3_SDA")
	)
	(segment
		(start 18.446496 -38.5318)
		(end 19.043142 -39.128446)
		(width 0.089408)
		(layer "In4.Cu")
		(net "SMB_BMC_PMBUS_STBY_LVC3_SDA")
	)
	(segment
		(start 20.09902 -24.60244)
		(end 20.09902 -22.378416)
		(width 0.089408)
		(layer "In4.Cu")
		(net "SMB_BMC_PMBUS_STBY_LVC3_SDA")
	)
	(segment
		(start 11.664188 -22.237192)
		(end 11.65098 -22.2504)
		(width 0.089408)
		(layer "In4.Cu")
		(net "SMB_BMC_PMBUS_STBY_LVC3_SDA")
	)
	(segment
		(start 439.180732 -19.062192)
		(end 432.888136 -19.062192)
		(width 0.089408)
		(layer "In4.Cu")
		(net "SMB_BMC_PMBUS_STBY_LVC3_SDA")
	)
	(segment
		(start 11.6332 -22.2504)
		(end 10.033 -23.8506)
		(width 0.089408)
		(layer "In4.Cu")
		(net "SMB_BMC_PMBUS_STBY_LVC3_SDA")
	)
	(segment
		(start 21.138388 -25.641808)
		(end 20.09902 -24.60244)
		(width 0.089408)
		(layer "In4.Cu")
		(net "SMB_BMC_PMBUS_STBY_LVC3_SDA")
	)
	(segment
		(start 472.274138 -33.16859)
		(end 472.274392 -33.168336)
		(width 0.089408)
		(layer "In4.Cu")
		(net "SMB_BMC_PMBUS_STBY_LVC3_SDA")
	)
	(segment
		(start 474.65742 -35.609276)
		(end 474.2688 -35.220656)
		(width 0.089408)
		(layer "In4.Cu")
		(net "SMB_BMC_PMBUS_STBY_LVC3_SDA")
	)
	(segment
		(start 11.65098 -22.2504)
		(end 11.6332 -22.2504)
		(width 0.089408)
		(layer "In4.Cu")
		(net "SMB_BMC_PMBUS_STBY_LVC3_SDA")
	)
	(segment
		(start 472.274138 -34.791904)
		(end 472.274138 -33.16859)
		(width 0.089408)
		(layer "In4.Cu")
		(net "SMB_BMC_PMBUS_STBY_LVC3_SDA")
	)
	(segment
		(start 476.59671 -35.609276)
		(end 474.65742 -35.609276)
		(width 0.089408)
		(layer "In4.Cu")
		(net "SMB_BMC_PMBUS_STBY_LVC3_SDA")
	)
	(segment
		(start 479.053652 -48.32858)
		(end 480.034854 -47.347378)
		(width 0.089408)
		(layer "In4.Cu")
		(net "SMB_BMC_PMBUS_STBY_LVC3_SDA")
	)
	(segment
		(start 15.093188 -21.536914)
		(end 14.39291 -22.237192)
		(width 0.089408)
		(layer "In4.Cu")
		(net "SMB_BMC_PMBUS_STBY_LVC3_SDA")
	)
	(segment
		(start -1.83007 -30.48)
		(end -2.599944 -29.710126)
		(width 0.089408)
		(layer "In4.Cu")
		(net "SMB_BMC_PMBUS_STBY_LVC3_SDA")
	)
	(segment
		(start 24.741124 -26.011124)
		(end 24.371808 -25.641808)
		(width 0.089408)
		(layer "In4.Cu")
		(net "SMB_BMC_PMBUS_STBY_LVC3_SDA")
	)
	(segment
		(start 447.379598 -18.112486)
		(end 440.130438 -18.112486)
		(width 0.089408)
		(layer "In4.Cu")
		(net "SMB_BMC_PMBUS_STBY_LVC3_SDA")
	)
	(segment
		(start 10.033 -27.564334)
		(end 8.641334 -28.956)
		(width 0.089408)
		(layer "In4.Cu")
		(net "SMB_BMC_PMBUS_STBY_LVC3_SDA")
	)
	(segment
		(start 0 -28.956)
		(end -0.508 -29.464)
		(width 0.089408)
		(layer "In4.Cu")
		(net "SMB_BMC_PMBUS_STBY_LVC3_SDA")
	)
	(segment
		(start 469.134698 -27.744674)
		(end 462.618074 -27.744674)
		(width 0.089408)
		(layer "In4.Cu")
		(net "SMB_BMC_PMBUS_STBY_LVC3_SDA")
	)
	(segment
		(start 24.741124 -26.67)
		(end 24.741124 -26.011124)
		(width 0.089408)
		(layer "In4.Cu")
		(net "SMB_BMC_PMBUS_STBY_LVC3_SDA")
	)
	(segment
		(start 20.143724 -29.171138)
		(end 18.446496 -30.868366)
		(width 0.089408)
		(layer "In4.Cu")
		(net "SMB_BMC_PMBUS_STBY_LVC3_SDA")
	)
	(segment
		(start -0.508 -29.464)
		(end -0.508 -29.972)
		(width 0.089408)
		(layer "In4.Cu")
		(net "SMB_BMC_PMBUS_STBY_LVC3_SDA")
	)
	(segment
		(start 342.530938 -138.776456)
		(end 338.274406 -138.776456)
		(width 0.089408)
		(layer "In9.Cu")
		(net "SMB_BMC_PMBUS_STBY_LVC3_SDA")
	)
	(segment
		(start 424.186604 -122.434096)
		(end 424.4467 -122.174)
		(width 0.089408)
		(layer "In9.Cu")
		(net "SMB_BMC_PMBUS_STBY_LVC3_SDA")
	)
	(segment
		(start 381.11938 -146.957542)
		(end 372.96598 -146.957542)
		(width 0.089408)
		(layer "In9.Cu")
		(net "SMB_BMC_PMBUS_STBY_LVC3_SDA")
	)
	(segment
		(start 188.11494 -157.023308)
		(end 186.793632 -155.702)
		(width 0.089408)
		(layer "In9.Cu")
		(net "SMB_BMC_PMBUS_STBY_LVC3_SDA")
	)
	(segment
		(start 336.733134 -156.04236)
		(end 330.35494 -156.04236)
		(width 0.089408)
		(layer "In9.Cu")
		(net "SMB_BMC_PMBUS_STBY_LVC3_SDA")
	)
	(segment
		(start 431.333148 -131.899914)
		(end 431.333148 -131.586986)
		(width 0.089408)
		(layer "In9.Cu")
		(net "SMB_BMC_PMBUS_STBY_LVC3_SDA")
	)
	(segment
		(start 337.4644 -139.586462)
		(end 337.4644 -155.311094)
		(width 0.089408)
		(layer "In9.Cu")
		(net "SMB_BMC_PMBUS_STBY_LVC3_SDA")
	)
	(segment
		(start 365.337344 -142.780512)
		(end 364.366048 -143.751808)
		(width 0.089408)
		(layer "In9.Cu")
		(net "SMB_BMC_PMBUS_STBY_LVC3_SDA")
	)
	(segment
		(start 391.737596 -148.691092)
		(end 382.85293 -148.691092)
		(width 0.089408)
		(layer "In9.Cu")
		(net "SMB_BMC_PMBUS_STBY_LVC3_SDA")
	)
	(segment
		(start 391.8204 -148.773896)
		(end 391.737596 -148.691092)
		(width 0.089408)
		(layer "In9.Cu")
		(net "SMB_BMC_PMBUS_STBY_LVC3_SDA")
	)
	(segment
		(start 350.636586 -140.447268)
		(end 350.423988 -140.23467)
		(width 0.089408)
		(layer "In9.Cu")
		(net "SMB_BMC_PMBUS_STBY_LVC3_SDA")
	)
	(segment
		(start 371.6274 -143.383)
		(end 369.165124 -140.920724)
		(width 0.089408)
		(layer "In9.Cu")
		(net "SMB_BMC_PMBUS_STBY_LVC3_SDA")
	)
	(segment
		(start 337.4644 -155.311094)
		(end 336.733134 -156.04236)
		(width 0.089408)
		(layer "In9.Cu")
		(net "SMB_BMC_PMBUS_STBY_LVC3_SDA")
	)
	(segment
		(start 351.993454 -140.447268)
		(end 350.636586 -140.447268)
		(width 0.089408)
		(layer "In9.Cu")
		(net "SMB_BMC_PMBUS_STBY_LVC3_SDA")
	)
	(segment
		(start 372.96598 -146.957542)
		(end 371.6274 -145.618962)
		(width 0.089408)
		(layer "In9.Cu")
		(net "SMB_BMC_PMBUS_STBY_LVC3_SDA")
	)
	(segment
		(start 355.297994 -143.751808)
		(end 351.993454 -140.447268)
		(width 0.089408)
		(layer "In9.Cu")
		(net "SMB_BMC_PMBUS_STBY_LVC3_SDA")
	)
	(segment
		(start 350.423988 -140.23467)
		(end 348.920054 -140.23467)
		(width 0.089408)
		(layer "In9.Cu")
		(net "SMB_BMC_PMBUS_STBY_LVC3_SDA")
	)
	(segment
		(start 364.366048 -143.751808)
		(end 355.297994 -143.751808)
		(width 0.089408)
		(layer "In9.Cu")
		(net "SMB_BMC_PMBUS_STBY_LVC3_SDA")
	)
	(segment
		(start 330.35494 -156.04236)
		(end 329.18654 -157.21076)
		(width 0.089408)
		(layer "In9.Cu")
		(net "SMB_BMC_PMBUS_STBY_LVC3_SDA")
	)
	(segment
		(start 366.453674 -140.920724)
		(end 365.337344 -142.037054)
		(width 0.089408)
		(layer "In9.Cu")
		(net "SMB_BMC_PMBUS_STBY_LVC3_SDA")
	)
	(segment
		(start 186.793632 -155.702)
		(end 185.498486 -155.702)
		(width 0.089408)
		(layer "In9.Cu")
		(net "SMB_BMC_PMBUS_STBY_LVC3_SDA")
	)
	(segment
		(start 264.41273 -156.71927)
		(end 264.108692 -157.023308)
		(width 0.089408)
		(layer "In9.Cu")
		(net "SMB_BMC_PMBUS_STBY_LVC3_SDA")
	)
	(segment
		(start 280.01849 -156.71927)
		(end 264.41273 -156.71927)
		(width 0.089408)
		(layer "In9.Cu")
		(net "SMB_BMC_PMBUS_STBY_LVC3_SDA")
	)
	(segment
		(start 423.05605 -123.176792)
		(end 423.798746 -122.434096)
		(width 0.089408)
		(layer "In9.Cu")
		(net "SMB_BMC_PMBUS_STBY_LVC3_SDA")
	)
	(segment
		(start 428.685452 -128.93929)
		(end 424.78452 -128.93929)
		(width 0.089408)
		(layer "In9.Cu")
		(net "SMB_BMC_PMBUS_STBY_LVC3_SDA")
	)
	(segment
		(start 329.18654 -157.21076)
		(end 280.50998 -157.21076)
		(width 0.089408)
		(layer "In9.Cu")
		(net "SMB_BMC_PMBUS_STBY_LVC3_SDA")
	)
	(segment
		(start 185.498486 -155.702)
		(end 185.322464 -155.525978)
		(width 0.089408)
		(layer "In9.Cu")
		(net "SMB_BMC_PMBUS_STBY_LVC3_SDA")
	)
	(segment
		(start 185.322464 -155.525978)
		(end 185.322464 -155.159202)
		(width 0.089408)
		(layer "In9.Cu")
		(net "SMB_BMC_PMBUS_STBY_LVC3_SDA")
	)
	(segment
		(start 264.108692 -157.023308)
		(end 188.11494 -157.023308)
		(width 0.089408)
		(layer "In9.Cu")
		(net "SMB_BMC_PMBUS_STBY_LVC3_SDA")
	)
	(segment
		(start 338.274406 -138.776456)
		(end 337.4644 -139.586462)
		(width 0.089408)
		(layer "In9.Cu")
		(net "SMB_BMC_PMBUS_STBY_LVC3_SDA")
	)
	(segment
		(start 371.6274 -145.618962)
		(end 371.6274 -143.383)
		(width 0.089408)
		(layer "In9.Cu")
		(net "SMB_BMC_PMBUS_STBY_LVC3_SDA")
	)
	(segment
		(start 423.05605 -127.21082)
		(end 423.05605 -123.176792)
		(width 0.089408)
		(layer "In9.Cu")
		(net "SMB_BMC_PMBUS_STBY_LVC3_SDA")
	)
	(segment
		(start 344.780108 -141.025626)
		(end 342.530938 -138.776456)
		(width 0.089408)
		(layer "In9.Cu")
		(net "SMB_BMC_PMBUS_STBY_LVC3_SDA")
	)
	(segment
		(start 348.129098 -141.025626)
		(end 344.780108 -141.025626)
		(width 0.089408)
		(layer "In9.Cu")
		(net "SMB_BMC_PMBUS_STBY_LVC3_SDA")
	)
	(segment
		(start 369.165124 -140.920724)
		(end 366.453674 -140.920724)
		(width 0.089408)
		(layer "In9.Cu")
		(net "SMB_BMC_PMBUS_STBY_LVC3_SDA")
	)
	(segment
		(start 382.85293 -148.691092)
		(end 381.11938 -146.957542)
		(width 0.089408)
		(layer "In9.Cu")
		(net "SMB_BMC_PMBUS_STBY_LVC3_SDA")
	)
	(segment
		(start 365.337344 -142.037054)
		(end 365.337344 -142.780512)
		(width 0.089408)
		(layer "In9.Cu")
		(net "SMB_BMC_PMBUS_STBY_LVC3_SDA")
	)
	(segment
		(start 431.104294 -132.128768)
		(end 431.333148 -131.899914)
		(width 0.089408)
		(layer "In9.Cu")
		(net "SMB_BMC_PMBUS_STBY_LVC3_SDA")
	)
	(segment
		(start 424.78452 -128.93929)
		(end 423.05605 -127.21082)
		(width 0.089408)
		(layer "In9.Cu")
		(net "SMB_BMC_PMBUS_STBY_LVC3_SDA")
	)
	(segment
		(start 423.798746 -122.434096)
		(end 424.186604 -122.434096)
		(width 0.089408)
		(layer "In9.Cu")
		(net "SMB_BMC_PMBUS_STBY_LVC3_SDA")
	)
	(segment
		(start 431.333148 -131.586986)
		(end 428.685452 -128.93929)
		(width 0.089408)
		(layer "In9.Cu")
		(net "SMB_BMC_PMBUS_STBY_LVC3_SDA")
	)
	(segment
		(start 348.920054 -140.23467)
		(end 348.129098 -141.025626)
		(width 0.089408)
		(layer "In9.Cu")
		(net "SMB_BMC_PMBUS_STBY_LVC3_SDA")
	)
	(segment
		(start 280.50998 -157.21076)
		(end 280.01849 -156.71927)
		(width 0.089408)
		(layer "In9.Cu")
		(net "SMB_BMC_PMBUS_STBY_LVC3_SDA")
	)
	(segment
		(start 16.966946 -82.55)
		(end 18.320766 -82.55)
		(width 0.089408)
		(layer "In11.Cu")
		(net "SMB_BMC_PMBUS_STBY_LVC3_SDA")
	)
	(segment
		(start 19.8882 -86.919054)
		(end 20.809712 -87.840566)
		(width 0.089408)
		(layer "In11.Cu")
		(net "SMB_BMC_PMBUS_STBY_LVC3_SDA")
	)
	(segment
		(start 181.61 -151.384)
		(end 181.61 -152.019)
		(width 0.089408)
		(layer "In11.Cu")
		(net "SMB_BMC_PMBUS_STBY_LVC3_SDA")
	)
	(segment
		(start 23.033482 -100.95484)
		(end 23.033482 -108.14304)
		(width 0.089408)
		(layer "In11.Cu")
		(net "SMB_BMC_PMBUS_STBY_LVC3_SDA")
	)
	(segment
		(start 172.593 -150.7998)
		(end 173.938946 -149.453854)
		(width 0.089408)
		(layer "In11.Cu")
		(net "SMB_BMC_PMBUS_STBY_LVC3_SDA")
	)
	(segment
		(start 24.702008 -74.176382)
		(end 24.702008 -77.99451)
		(width 0.089408)
		(layer "In11.Cu")
		(net "SMB_BMC_PMBUS_STBY_LVC3_SDA")
	)
	(segment
		(start 17.590262 -80.1878)
		(end 16.4592 -80.1878)
		(width 0.089408)
		(layer "In11.Cu")
		(net "SMB_BMC_PMBUS_STBY_LVC3_SDA")
	)
	(segment
		(start 391.8204 -148.773896)
		(end 392.029696 -148.5646)
		(width 0.089408)
		(layer "In11.Cu")
		(net "SMB_BMC_PMBUS_STBY_LVC3_SDA")
	)
	(segment
		(start 16.4592 -80.1878)
		(end 16.256 -80.391)
		(width 0.089408)
		(layer "In11.Cu")
		(net "SMB_BMC_PMBUS_STBY_LVC3_SDA")
	)
	(segment
		(start 21.697696 -99.619054)
		(end 23.033482 -100.95484)
		(width 0.089408)
		(layer "In11.Cu")
		(net "SMB_BMC_PMBUS_STBY_LVC3_SDA")
	)
	(segment
		(start 392.311382 -148.056092)
		(end 395.07033 -148.056092)
		(width 0.089408)
		(layer "In11.Cu")
		(net "SMB_BMC_PMBUS_STBY_LVC3_SDA")
	)
	(segment
		(start 405.7523 -152.2857)
		(end 405.7523 -152.984962)
		(width 0.089408)
		(layer "In11.Cu")
		(net "SMB_BMC_PMBUS_STBY_LVC3_SDA")
	)
	(segment
		(start 28.13177 -125.11786)
		(end 27.5336 -125.71603)
		(width 0.089408)
		(layer "In11.Cu")
		(net "SMB_BMC_PMBUS_STBY_LVC3_SDA")
	)
	(segment
		(start 16.256 -80.391)
		(end 15.875 -80.772)
		(width 0.089408)
		(layer "In11.Cu")
		(net "SMB_BMC_PMBUS_STBY_LVC3_SDA")
	)
	(segment
		(start 399.79473 -149.681692)
		(end 400.69643 -150.583392)
		(width 0.089408)
		(layer "In11.Cu")
		(net "SMB_BMC_PMBUS_STBY_LVC3_SDA")
	)
	(segment
		(start 28.13177 -113.241328)
		(end 28.13177 -125.11786)
		(width 0.089408)
		(layer "In11.Cu")
		(net "SMB_BMC_PMBUS_STBY_LVC3_SDA")
	)
	(segment
		(start 19.3548 -85.3694)
		(end 19.8882 -85.9028)
		(width 0.089408)
		(layer "In11.Cu")
		(net "SMB_BMC_PMBUS_STBY_LVC3_SDA")
	)
	(segment
		(start 20.809712 -89.161366)
		(end 22.516592 -90.868246)
		(width 0.089408)
		(layer "In11.Cu")
		(net "SMB_BMC_PMBUS_STBY_LVC3_SDA")
	)
	(segment
		(start 157.094682 -157.39491)
		(end 158.448756 -156.040836)
		(width 0.089408)
		(layer "In11.Cu")
		(net "SMB_BMC_PMBUS_STBY_LVC3_SDA")
	)
	(segment
		(start 22.516592 -98.106738)
		(end 21.697696 -98.925634)
		(width 0.089408)
		(layer "In11.Cu")
		(net "SMB_BMC_PMBUS_STBY_LVC3_SDA")
	)
	(segment
		(start 184.277 -153.416)
		(end 184.912 -153.416)
		(width 0.089408)
		(layer "In11.Cu")
		(net "SMB_BMC_PMBUS_STBY_LVC3_SDA")
	)
	(segment
		(start 22.51583 -50.836576)
		(end 22.51583 -51.31054)
		(width 0.089408)
		(layer "In11.Cu")
		(net "SMB_BMC_PMBUS_STBY_LVC3_SDA")
	)
	(segment
		(start 18.44167 -81.039208)
		(end 17.590262 -80.1878)
		(width 0.089408)
		(layer "In11.Cu")
		(net "SMB_BMC_PMBUS_STBY_LVC3_SDA")
	)
	(segment
		(start 27.915616 -127.652272)
		(end 27.915616 -130.163824)
		(width 0.089408)
		(layer "In11.Cu")
		(net "SMB_BMC_PMBUS_STBY_LVC3_SDA")
	)
	(segment
		(start 392.029696 -148.5646)
		(end 392.029696 -148.337778)
		(width 0.089408)
		(layer "In11.Cu")
		(net "SMB_BMC_PMBUS_STBY_LVC3_SDA")
	)
	(segment
		(start 407.099008 -156.235654)
		(end 407.099008 -156.832808)
		(width 0.089408)
		(layer "In11.Cu")
		(net "SMB_BMC_PMBUS_STBY_LVC3_SDA")
	)
	(segment
		(start 178.7144 -150.9014)
		(end 181.1274 -150.9014)
		(width 0.089408)
		(layer "In11.Cu")
		(net "SMB_BMC_PMBUS_STBY_LVC3_SDA")
	)
	(segment
		(start 395.07033 -148.056092)
		(end 396.69593 -149.681692)
		(width 0.089408)
		(layer "In11.Cu")
		(net "SMB_BMC_PMBUS_STBY_LVC3_SDA")
	)
	(segment
		(start 20.809712 -87.840566)
		(end 20.809712 -89.161366)
		(width 0.089408)
		(layer "In11.Cu")
		(net "SMB_BMC_PMBUS_STBY_LVC3_SDA")
	)
	(segment
		(start 26.533348 -55.328058)
		(end 26.533348 -72.345042)
		(width 0.089408)
		(layer "In11.Cu")
		(net "SMB_BMC_PMBUS_STBY_LVC3_SDA")
	)
	(segment
		(start 27.5336 -125.71603)
		(end 27.5336 -127.270256)
		(width 0.089408)
		(layer "In11.Cu")
		(net "SMB_BMC_PMBUS_STBY_LVC3_SDA")
	)
	(segment
		(start 184.912 -153.416)
		(end 185.338466 -153.842466)
		(width 0.089408)
		(layer "In11.Cu")
		(net "SMB_BMC_PMBUS_STBY_LVC3_SDA")
	)
	(segment
		(start 158.448756 -155.355544)
		(end 161.16554 -152.63876)
		(width 0.089408)
		(layer "In11.Cu")
		(net "SMB_BMC_PMBUS_STBY_LVC3_SDA")
	)
	(segment
		(start 15.875 -81.458054)
		(end 16.966946 -82.55)
		(width 0.089408)
		(layer "In11.Cu")
		(net "SMB_BMC_PMBUS_STBY_LVC3_SDA")
	)
	(segment
		(start 173.938946 -149.453854)
		(end 177.266854 -149.453854)
		(width 0.089408)
		(layer "In11.Cu")
		(net "SMB_BMC_PMBUS_STBY_LVC3_SDA")
	)
	(segment
		(start 27.666188 -131.867148)
		(end 27.666188 -155.372308)
		(width 0.089408)
		(layer "In11.Cu")
		(net "SMB_BMC_PMBUS_STBY_LVC3_SDA")
	)
	(segment
		(start 400.69643 -150.583392)
		(end 404.049992 -150.583392)
		(width 0.089408)
		(layer "In11.Cu")
		(net "SMB_BMC_PMBUS_STBY_LVC3_SDA")
	)
	(segment
		(start 181.1274 -150.9014)
		(end 181.61 -151.384)
		(width 0.089408)
		(layer "In11.Cu")
		(net "SMB_BMC_PMBUS_STBY_LVC3_SDA")
	)
	(segment
		(start 182.245 -152.654)
		(end 183.515 -152.654)
		(width 0.089408)
		(layer "In11.Cu")
		(net "SMB_BMC_PMBUS_STBY_LVC3_SDA")
	)
	(segment
		(start 405.7523 -152.984962)
		(end 406.502108 -153.73477)
		(width 0.089408)
		(layer "In11.Cu")
		(net "SMB_BMC_PMBUS_STBY_LVC3_SDA")
	)
	(segment
		(start 181.61 -152.019)
		(end 182.245 -152.654)
		(width 0.089408)
		(layer "In11.Cu")
		(net "SMB_BMC_PMBUS_STBY_LVC3_SDA")
	)
	(segment
		(start 23.033482 -108.14304)
		(end 28.13177 -113.241328)
		(width 0.089408)
		(layer "In11.Cu")
		(net "SMB_BMC_PMBUS_STBY_LVC3_SDA")
	)
	(segment
		(start 15.875 -80.772)
		(end 15.875 -81.458054)
		(width 0.089408)
		(layer "In11.Cu")
		(net "SMB_BMC_PMBUS_STBY_LVC3_SDA")
	)
	(segment
		(start 185.338466 -153.842466)
		(end 185.338466 -155.1432)
		(width 0.089408)
		(layer "In11.Cu")
		(net "SMB_BMC_PMBUS_STBY_LVC3_SDA")
	)
	(segment
		(start 161.16554 -152.63876)
		(end 164.728144 -152.63876)
		(width 0.089408)
		(layer "In11.Cu")
		(net "SMB_BMC_PMBUS_STBY_LVC3_SDA")
	)
	(segment
		(start 158.448756 -156.040836)
		(end 158.448756 -155.355544)
		(width 0.089408)
		(layer "In11.Cu")
		(net "SMB_BMC_PMBUS_STBY_LVC3_SDA")
	)
	(segment
		(start 26.533348 -72.345042)
		(end 24.702008 -74.176382)
		(width 0.089408)
		(layer "In11.Cu")
		(net "SMB_BMC_PMBUS_STBY_LVC3_SDA")
	)
	(segment
		(start 27.818588 -130.260852)
		(end 27.818588 -131.714748)
		(width 0.089408)
		(layer "In11.Cu")
		(net "SMB_BMC_PMBUS_STBY_LVC3_SDA")
	)
	(segment
		(start 112.86744 -157.39491)
		(end 157.094682 -157.39491)
		(width 0.089408)
		(layer "In11.Cu")
		(net "SMB_BMC_PMBUS_STBY_LVC3_SDA")
	)
	(segment
		(start 164.728144 -152.63876)
		(end 166.567104 -150.7998)
		(width 0.089408)
		(layer "In11.Cu")
		(net "SMB_BMC_PMBUS_STBY_LVC3_SDA")
	)
	(segment
		(start 404.049992 -150.583392)
		(end 405.7523 -152.2857)
		(width 0.089408)
		(layer "In11.Cu")
		(net "SMB_BMC_PMBUS_STBY_LVC3_SDA")
	)
	(segment
		(start 27.818588 -131.714748)
		(end 27.666188 -131.867148)
		(width 0.089408)
		(layer "In11.Cu")
		(net "SMB_BMC_PMBUS_STBY_LVC3_SDA")
	)
	(segment
		(start 27.666188 -155.372308)
		(end 30.357572 -158.063692)
		(width 0.089408)
		(layer "In11.Cu")
		(net "SMB_BMC_PMBUS_STBY_LVC3_SDA")
	)
	(segment
		(start 19.75358 -39.11346)
		(end 19.75358 -42.55262)
		(width 0.089408)
		(layer "In11.Cu")
		(net "SMB_BMC_PMBUS_STBY_LVC3_SDA")
	)
	(segment
		(start 27.915616 -130.163824)
		(end 27.818588 -130.260852)
		(width 0.089408)
		(layer "In11.Cu")
		(net "SMB_BMC_PMBUS_STBY_LVC3_SDA")
	)
	(segment
		(start 166.567104 -150.7998)
		(end 172.593 -150.7998)
		(width 0.089408)
		(layer "In11.Cu")
		(net "SMB_BMC_PMBUS_STBY_LVC3_SDA")
	)
	(segment
		(start 396.69593 -149.681692)
		(end 399.79473 -149.681692)
		(width 0.089408)
		(layer "In11.Cu")
		(net "SMB_BMC_PMBUS_STBY_LVC3_SDA")
	)
	(segment
		(start 21.65731 -81.039208)
		(end 18.44167 -81.039208)
		(width 0.089408)
		(layer "In11.Cu")
		(net "SMB_BMC_PMBUS_STBY_LVC3_SDA")
	)
	(segment
		(start 406.502108 -155.638754)
		(end 407.099008 -156.235654)
		(width 0.089408)
		(layer "In11.Cu")
		(net "SMB_BMC_PMBUS_STBY_LVC3_SDA")
	)
	(segment
		(start 19.8882 -85.9028)
		(end 19.8882 -86.919054)
		(width 0.089408)
		(layer "In11.Cu")
		(net "SMB_BMC_PMBUS_STBY_LVC3_SDA")
	)
	(segment
		(start 183.515 -152.654)
		(end 184.277 -153.416)
		(width 0.089408)
		(layer "In11.Cu")
		(net "SMB_BMC_PMBUS_STBY_LVC3_SDA")
	)
	(segment
		(start 18.320766 -82.55)
		(end 19.3548 -83.584034)
		(width 0.089408)
		(layer "In11.Cu")
		(net "SMB_BMC_PMBUS_STBY_LVC3_SDA")
	)
	(segment
		(start 27.5336 -127.270256)
		(end 27.915616 -127.652272)
		(width 0.089408)
		(layer "In11.Cu")
		(net "SMB_BMC_PMBUS_STBY_LVC3_SDA")
	)
	(segment
		(start 185.338466 -155.1432)
		(end 185.322464 -155.159202)
		(width 0.089408)
		(layer "In11.Cu")
		(net "SMB_BMC_PMBUS_STBY_LVC3_SDA")
	)
	(segment
		(start 19.3548 -83.584034)
		(end 19.3548 -85.3694)
		(width 0.089408)
		(layer "In11.Cu")
		(net "SMB_BMC_PMBUS_STBY_LVC3_SDA")
	)
	(segment
		(start 20.0533 -38.81374)
		(end 19.75358 -39.11346)
		(width 0.089408)
		(layer "In11.Cu")
		(net "SMB_BMC_PMBUS_STBY_LVC3_SDA")
	)
	(segment
		(start 21.42998 -44.22902)
		(end 21.42998 -49.750726)
		(width 0.089408)
		(layer "In11.Cu")
		(net "SMB_BMC_PMBUS_STBY_LVC3_SDA")
	)
	(segment
		(start 77.81417 -158.063692)
		(end 78.373478 -157.504384)
		(width 0.089408)
		(layer "In11.Cu")
		(net "SMB_BMC_PMBUS_STBY_LVC3_SDA")
	)
	(segment
		(start 406.502108 -153.73477)
		(end 406.502108 -155.638754)
		(width 0.089408)
		(layer "In11.Cu")
		(net "SMB_BMC_PMBUS_STBY_LVC3_SDA")
	)
	(segment
		(start 21.42998 -49.750726)
		(end 22.51583 -50.836576)
		(width 0.089408)
		(layer "In11.Cu")
		(net "SMB_BMC_PMBUS_STBY_LVC3_SDA")
	)
	(segment
		(start 392.029696 -148.337778)
		(end 392.311382 -148.056092)
		(width 0.089408)
		(layer "In11.Cu")
		(net "SMB_BMC_PMBUS_STBY_LVC3_SDA")
	)
	(segment
		(start 112.757966 -157.504384)
		(end 112.86744 -157.39491)
		(width 0.089408)
		(layer "In11.Cu")
		(net "SMB_BMC_PMBUS_STBY_LVC3_SDA")
	)
	(segment
		(start 21.697696 -98.925634)
		(end 21.697696 -99.619054)
		(width 0.089408)
		(layer "In11.Cu")
		(net "SMB_BMC_PMBUS_STBY_LVC3_SDA")
	)
	(segment
		(start 177.266854 -149.453854)
		(end 178.7144 -150.9014)
		(width 0.089408)
		(layer "In11.Cu")
		(net "SMB_BMC_PMBUS_STBY_LVC3_SDA")
	)
	(segment
		(start 407.099008 -156.832808)
		(end 407.3017 -157.0355)
		(width 0.089408)
		(layer "In11.Cu")
		(net "SMB_BMC_PMBUS_STBY_LVC3_SDA")
	)
	(segment
		(start 30.357572 -158.063692)
		(end 77.81417 -158.063692)
		(width 0.089408)
		(layer "In11.Cu")
		(net "SMB_BMC_PMBUS_STBY_LVC3_SDA")
	)
	(segment
		(start 19.75358 -42.55262)
		(end 21.42998 -44.22902)
		(width 0.089408)
		(layer "In11.Cu")
		(net "SMB_BMC_PMBUS_STBY_LVC3_SDA")
	)
	(segment
		(start 22.516592 -90.868246)
		(end 22.516592 -98.106738)
		(width 0.089408)
		(layer "In11.Cu")
		(net "SMB_BMC_PMBUS_STBY_LVC3_SDA")
	)
	(segment
		(start 22.51583 -51.31054)
		(end 26.533348 -55.328058)
		(width 0.089408)
		(layer "In11.Cu")
		(net "SMB_BMC_PMBUS_STBY_LVC3_SDA")
	)
	(segment
		(start 78.373478 -157.504384)
		(end 112.757966 -157.504384)
		(width 0.089408)
		(layer "In11.Cu")
		(net "SMB_BMC_PMBUS_STBY_LVC3_SDA")
	)
	(segment
		(start 24.702008 -77.99451)
		(end 21.65731 -81.039208)
		(width 0.089408)
		(layer "In11.Cu")
		(net "SMB_BMC_PMBUS_STBY_LVC3_SDA")
	)
	(segment
		(start 16.256 -79.7306)
		(end 16.256 -79.7814)
		(width 0.10795)
		(layer "F.Cu")
		(net "SMB_BMC_PMBUS_STBY_LVC3_SCL")
	)
	(segment
		(start 419.0746 -19.9644)
		(end 419.0746 -20.7645)
		(width 0.10795)
		(layer "F.Cu")
		(net "SMB_BMC_PMBUS_STBY_LVC3_SCL")
	)
	(segment
		(start 15.5829 -80.4545)
		(end 15.494 -80.4545)
		(width 0.10795)
		(layer "F.Cu")
		(net "SMB_BMC_PMBUS_STBY_LVC3_SCL")
	)
	(segment
		(start 16.256 -79.7814)
		(end 15.5829 -80.4545)
		(width 0.10795)
		(layer "F.Cu")
		(net "SMB_BMC_PMBUS_STBY_LVC3_SCL")
	)
	(via
		(at 19.21764 -38.70452)
		(size 0.508)
		(drill 0.254)
		(layers "F.Cu" "B.Cu")
		(net "SMB_BMC_PMBUS_STBY_LVC3_SCL")
	)
	(via
		(at 419.0746 -19.9644)
		(size 0.508)
		(drill 0.254)
		(layers "F.Cu" "B.Cu")
		(net "SMB_BMC_PMBUS_STBY_LVC3_SCL")
	)
	(via
		(at 402.209 -76.34224)
		(size 0.508)
		(drill 0.254)
		(layers "F.Cu" "B.Cu")
		(net "SMB_BMC_PMBUS_STBY_LVC3_SCL")
	)
	(via
		(at 419.395402 -97.69983)
		(size 0.6604)
		(drill 0.3302)
		(layers "F.Cu" "B.Cu")
		(net "SMB_BMC_PMBUS_STBY_LVC3_SCL")
	)
	(via
		(at 406.6413 -157.0355)
		(size 0.508)
		(drill 0.254)
		(layers "F.Cu" "B.Cu")
		(net "SMB_BMC_PMBUS_STBY_LVC3_SCL")
	)
	(via
		(at 424.4467 -122.8344)
		(size 0.508)
		(drill 0.254)
		(layers "F.Cu" "B.Cu")
		(net "SMB_BMC_PMBUS_STBY_LVC3_SCL")
	)
	(via
		(at 392.4808 -148.773896)
		(size 0.508)
		(drill 0.254)
		(layers "F.Cu" "B.Cu")
		(net "SMB_BMC_PMBUS_STBY_LVC3_SCL")
	)
	(via
		(at 184.621678 -155.161234)
		(size 0.508)
		(drill 0.254)
		(layers "F.Cu" "B.Cu")
		(net "SMB_BMC_PMBUS_STBY_LVC3_SCL")
	)
	(via
		(at 478.3709 -51.41214)
		(size 0.508)
		(drill 0.254)
		(layers "F.Cu" "B.Cu")
		(net "SMB_BMC_PMBUS_STBY_LVC3_SCL")
	)
	(via
		(at 431.764694 -132.128768)
		(size 0.508)
		(drill 0.254)
		(layers "F.Cu" "B.Cu")
		(net "SMB_BMC_PMBUS_STBY_LVC3_SCL")
	)
	(via
		(at 16.256 -79.7306)
		(size 0.508)
		(drill 0.254)
		(layers "F.Cu" "B.Cu")
		(net "SMB_BMC_PMBUS_STBY_LVC3_SCL")
	)
	(segment
		(start 419.479222 -95.499682)
		(end 419.395402 -95.583502)
		(width 0.10795)
		(layer "B.Cu")
		(net "SMB_BMC_PMBUS_STBY_LVC3_SCL")
	)
	(segment
		(start 436.015384 -148.470874)
		(end 436.015384 -142.914116)
		(width 0.10795)
		(layer "B.Cu")
		(net "SMB_BMC_PMBUS_STBY_LVC3_SCL")
	)
	(segment
		(start 436.6768 -134.704836)
		(end 436.6768 -134.669022)
		(width 0.10795)
		(layer "B.Cu")
		(net "SMB_BMC_PMBUS_STBY_LVC3_SCL")
	)
	(segment
		(start 419.479222 -94.504256)
		(end 419.479222 -95.499682)
		(width 0.10795)
		(layer "B.Cu")
		(net "SMB_BMC_PMBUS_STBY_LVC3_SCL")
	)
	(segment
		(start 402.59 -75.5142)
		(end 402.59 -74.295)
		(width 0.10795)
		(layer "B.Cu")
		(net "SMB_BMC_PMBUS_STBY_LVC3_SCL")
	)
	(segment
		(start 436.6768 -138.580114)
		(end 437.262778 -137.994136)
		(width 0.10795)
		(layer "B.Cu")
		(net "SMB_BMC_PMBUS_STBY_LVC3_SCL")
	)
	(segment
		(start 420.286942 -102.580694)
		(end 419.395402 -101.689154)
		(width 0.10795)
		(layer "B.Cu")
		(net "SMB_BMC_PMBUS_STBY_LVC3_SCL")
	)
	(segment
		(start 403.606 -76.34224)
		(end 404.64486 -76.34224)
		(width 0.10795)
		(layer "B.Cu")
		(net "SMB_BMC_PMBUS_STBY_LVC3_SCL")
	)
	(segment
		(start 406.648158 -80.984344)
		(end 412.89351 -80.984344)
		(width 0.10795)
		(layer "B.Cu")
		(net "SMB_BMC_PMBUS_STBY_LVC3_SCL")
	)
	(segment
		(start 436.6768 -142.2527)
		(end 436.6768 -138.580114)
		(width 0.10795)
		(layer "B.Cu")
		(net "SMB_BMC_PMBUS_STBY_LVC3_SCL")
	)
	(segment
		(start 431.65395 -132.239512)
		(end 431.764694 -132.128768)
		(width 0.10795)
		(layer "B.Cu")
		(net "SMB_BMC_PMBUS_STBY_LVC3_SCL")
	)
	(segment
		(start 412.89351 -80.984344)
		(end 415.513266 -83.6041)
		(width 0.10795)
		(layer "B.Cu")
		(net "SMB_BMC_PMBUS_STBY_LVC3_SCL")
	)
	(segment
		(start 435.47665 -156.516578)
		(end 435.47665 -149.009608)
		(width 0.10795)
		(layer "B.Cu")
		(net "SMB_BMC_PMBUS_STBY_LVC3_SCL")
	)
	(segment
		(start 420.36746 -88.181688)
		(end 420.36746 -93.616018)
		(width 0.10795)
		(layer "B.Cu")
		(net "SMB_BMC_PMBUS_STBY_LVC3_SCL")
	)
	(segment
		(start 419.395402 -95.583502)
		(end 419.395402 -97.69983)
		(width 0.10795)
		(layer "B.Cu")
		(net "SMB_BMC_PMBUS_STBY_LVC3_SCL")
	)
	(segment
		(start 435.47665 -149.009608)
		(end 436.015384 -148.470874)
		(width 0.10795)
		(layer "B.Cu")
		(net "SMB_BMC_PMBUS_STBY_LVC3_SCL")
	)
	(segment
		(start 437.262778 -137.994136)
		(end 437.262778 -135.290814)
		(width 0.10795)
		(layer "B.Cu")
		(net "SMB_BMC_PMBUS_STBY_LVC3_SCL")
	)
	(segment
		(start 402.18995 -75.91425)
		(end 402.59 -75.5142)
		(width 0.10795)
		(layer "B.Cu")
		(net "SMB_BMC_PMBUS_STBY_LVC3_SCL")
	)
	(segment
		(start 419.395402 -101.689154)
		(end 419.395402 -97.69983)
		(width 0.10795)
		(layer "B.Cu")
		(net "SMB_BMC_PMBUS_STBY_LVC3_SCL")
	)
	(segment
		(start 437.262778 -135.290814)
		(end 436.6768 -134.704836)
		(width 0.10795)
		(layer "B.Cu")
		(net "SMB_BMC_PMBUS_STBY_LVC3_SCL")
	)
	(segment
		(start 420.286942 -117.321584)
		(end 420.286942 -102.580694)
		(width 0.10795)
		(layer "B.Cu")
		(net "SMB_BMC_PMBUS_STBY_LVC3_SCL")
	)
	(segment
		(start 436.015384 -142.914116)
		(end 436.6768 -142.2527)
		(width 0.10795)
		(layer "B.Cu")
		(net "SMB_BMC_PMBUS_STBY_LVC3_SCL")
	)
	(segment
		(start 406.6413 -157.0355)
		(end 407.841958 -158.236158)
		(width 0.10795)
		(layer "B.Cu")
		(net "SMB_BMC_PMBUS_STBY_LVC3_SCL")
	)
	(segment
		(start 403.606 -76.34224)
		(end 402.209 -76.34224)
		(width 0.10795)
		(layer "B.Cu")
		(net "SMB_BMC_PMBUS_STBY_LVC3_SCL")
	)
	(segment
		(start 431.65395 -133.674104)
		(end 431.65395 -132.239512)
		(width 0.10795)
		(layer "B.Cu")
		(net "SMB_BMC_PMBUS_STBY_LVC3_SCL")
	)
	(segment
		(start 407.841958 -158.236158)
		(end 433.75707 -158.236158)
		(width 0.10795)
		(layer "B.Cu")
		(net "SMB_BMC_PMBUS_STBY_LVC3_SCL")
	)
	(segment
		(start 402.209 -76.34224)
		(end 402.18995 -76.32319)
		(width 0.10795)
		(layer "B.Cu")
		(net "SMB_BMC_PMBUS_STBY_LVC3_SCL")
	)
	(segment
		(start 424.4467 -122.8344)
		(end 424.869102 -122.411998)
		(width 0.10795)
		(layer "B.Cu")
		(net "SMB_BMC_PMBUS_STBY_LVC3_SCL")
	)
	(segment
		(start 405.359362 -77.056742)
		(end 405.359362 -79.695548)
		(width 0.10795)
		(layer "B.Cu")
		(net "SMB_BMC_PMBUS_STBY_LVC3_SCL")
	)
	(segment
		(start 404.64486 -76.34224)
		(end 405.359362 -77.056742)
		(width 0.10795)
		(layer "B.Cu")
		(net "SMB_BMC_PMBUS_STBY_LVC3_SCL")
	)
	(segment
		(start 420.36746 -93.616018)
		(end 419.479222 -94.504256)
		(width 0.10795)
		(layer "B.Cu")
		(net "SMB_BMC_PMBUS_STBY_LVC3_SCL")
	)
	(segment
		(start 424.869102 -122.411998)
		(end 424.869102 -121.903744)
		(width 0.10795)
		(layer "B.Cu")
		(net "SMB_BMC_PMBUS_STBY_LVC3_SCL")
	)
	(segment
		(start 405.359362 -79.695548)
		(end 406.648158 -80.984344)
		(width 0.10795)
		(layer "B.Cu")
		(net "SMB_BMC_PMBUS_STBY_LVC3_SCL")
	)
	(segment
		(start 435.918102 -133.910324)
		(end 431.89017 -133.910324)
		(width 0.10795)
		(layer "B.Cu")
		(net "SMB_BMC_PMBUS_STBY_LVC3_SCL")
	)
	(segment
		(start 424.869102 -121.903744)
		(end 420.286942 -117.321584)
		(width 0.10795)
		(layer "B.Cu")
		(net "SMB_BMC_PMBUS_STBY_LVC3_SCL")
	)
	(segment
		(start 402.18995 -76.32319)
		(end 402.18995 -75.91425)
		(width 0.10795)
		(layer "B.Cu")
		(net "SMB_BMC_PMBUS_STBY_LVC3_SCL")
	)
	(segment
		(start 415.513266 -83.6041)
		(end 415.789872 -83.6041)
		(width 0.10795)
		(layer "B.Cu")
		(net "SMB_BMC_PMBUS_STBY_LVC3_SCL")
	)
	(segment
		(start 433.75707 -158.236158)
		(end 435.47665 -156.516578)
		(width 0.10795)
		(layer "B.Cu")
		(net "SMB_BMC_PMBUS_STBY_LVC3_SCL")
	)
	(segment
		(start 436.6768 -134.669022)
		(end 435.918102 -133.910324)
		(width 0.10795)
		(layer "B.Cu")
		(net "SMB_BMC_PMBUS_STBY_LVC3_SCL")
	)
	(segment
		(start 415.789872 -83.6041)
		(end 420.36746 -88.181688)
		(width 0.10795)
		(layer "B.Cu")
		(net "SMB_BMC_PMBUS_STBY_LVC3_SCL")
	)
	(segment
		(start 431.89017 -133.910324)
		(end 431.65395 -133.674104)
		(width 0.10795)
		(layer "B.Cu")
		(net "SMB_BMC_PMBUS_STBY_LVC3_SCL")
	)
	(segment
		(start 464.926172 -55.78221)
		(end 463.937858 -54.793896)
		(width 0.089408)
		(layer "In2.Cu")
		(net "SMB_BMC_PMBUS_STBY_LVC3_SCL")
	)
	(segment
		(start 466.912452 -55.78221)
		(end 464.926172 -55.78221)
		(width 0.089408)
		(layer "In2.Cu")
		(net "SMB_BMC_PMBUS_STBY_LVC3_SCL")
	)
	(segment
		(start 436.493666 -54.793896)
		(end 435.31663 -53.61686)
		(width 0.089408)
		(layer "In2.Cu")
		(net "SMB_BMC_PMBUS_STBY_LVC3_SCL")
	)
	(segment
		(start 407.199592 -61.455808)
		(end 408.314652 -62.570868)
		(width 0.089408)
		(layer "In2.Cu")
		(net "SMB_BMC_PMBUS_STBY_LVC3_SCL")
	)
	(segment
		(start 403.648926 -73.648824)
		(end 403.648926 -73.970642)
		(width 0.089408)
		(layer "In2.Cu")
		(net "SMB_BMC_PMBUS_STBY_LVC3_SCL")
	)
	(segment
		(start 408.718258 -55.209186)
		(end 407.967688 -55.959756)
		(width 0.089408)
		(layer "In2.Cu")
		(net "SMB_BMC_PMBUS_STBY_LVC3_SCL")
	)
	(segment
		(start 427.48708 -54.414928)
		(end 424.404536 -54.414928)
		(width 0.089408)
		(layer "In2.Cu")
		(net "SMB_BMC_PMBUS_STBY_LVC3_SCL")
	)
	(segment
		(start 424.404536 -54.414928)
		(end 423.365422 -53.375814)
		(width 0.089408)
		(layer "In2.Cu")
		(net "SMB_BMC_PMBUS_STBY_LVC3_SCL")
	)
	(segment
		(start 409.07716 -64.7827)
		(end 408.5336 -65.32626)
		(width 0.089408)
		(layer "In2.Cu")
		(net "SMB_BMC_PMBUS_STBY_LVC3_SCL")
	)
	(segment
		(start 407.967688 -59.78525)
		(end 407.199592 -60.553346)
		(width 0.089408)
		(layer "In2.Cu")
		(net "SMB_BMC_PMBUS_STBY_LVC3_SCL")
	)
	(segment
		(start 408.594052 -62.570868)
		(end 409.07716 -63.053976)
		(width 0.089408)
		(layer "In2.Cu")
		(net "SMB_BMC_PMBUS_STBY_LVC3_SCL")
	)
	(segment
		(start 467.980522 -53.823362)
		(end 467.980522 -54.71414)
		(width 0.089408)
		(layer "In2.Cu")
		(net "SMB_BMC_PMBUS_STBY_LVC3_SCL")
	)
	(segment
		(start 478.3709 -51.41214)
		(end 478.232724 -51.273964)
		(width 0.089408)
		(layer "In2.Cu")
		(net "SMB_BMC_PMBUS_STBY_LVC3_SCL")
	)
	(segment
		(start 408.5336 -68.76415)
		(end 403.648926 -73.648824)
		(width 0.089408)
		(layer "In2.Cu")
		(net "SMB_BMC_PMBUS_STBY_LVC3_SCL")
	)
	(segment
		(start 469.795098 -52.008786)
		(end 467.980522 -53.823362)
		(width 0.089408)
		(layer "In2.Cu")
		(net "SMB_BMC_PMBUS_STBY_LVC3_SCL")
	)
	(segment
		(start 409.07716 -63.053976)
		(end 409.07716 -64.7827)
		(width 0.089408)
		(layer "In2.Cu")
		(net "SMB_BMC_PMBUS_STBY_LVC3_SCL")
	)
	(segment
		(start 408.5336 -65.32626)
		(end 408.5336 -68.76415)
		(width 0.089408)
		(layer "In2.Cu")
		(net "SMB_BMC_PMBUS_STBY_LVC3_SCL")
	)
	(segment
		(start 475.66072 -51.273964)
		(end 474.925898 -52.008786)
		(width 0.089408)
		(layer "In2.Cu")
		(net "SMB_BMC_PMBUS_STBY_LVC3_SCL")
	)
	(segment
		(start 414.716976 -53.912008)
		(end 414.09874 -53.293772)
		(width 0.089408)
		(layer "In2.Cu")
		(net "SMB_BMC_PMBUS_STBY_LVC3_SCL")
	)
	(segment
		(start 420.914576 -53.375814)
		(end 420.378382 -53.912008)
		(width 0.089408)
		(layer "In2.Cu")
		(net "SMB_BMC_PMBUS_STBY_LVC3_SCL")
	)
	(segment
		(start 408.314652 -62.570868)
		(end 408.594052 -62.570868)
		(width 0.089408)
		(layer "In2.Cu")
		(net "SMB_BMC_PMBUS_STBY_LVC3_SCL")
	)
	(segment
		(start 478.232724 -51.273964)
		(end 475.66072 -51.273964)
		(width 0.089408)
		(layer "In2.Cu")
		(net "SMB_BMC_PMBUS_STBY_LVC3_SCL")
	)
	(segment
		(start 414.09874 -53.293772)
		(end 409.617672 -53.293772)
		(width 0.089408)
		(layer "In2.Cu")
		(net "SMB_BMC_PMBUS_STBY_LVC3_SCL")
	)
	(segment
		(start 402.98243 -75.41768)
		(end 402.209 -76.19111)
		(width 0.089408)
		(layer "In2.Cu")
		(net "SMB_BMC_PMBUS_STBY_LVC3_SCL")
	)
	(segment
		(start 409.617672 -53.293772)
		(end 408.718258 -54.193186)
		(width 0.089408)
		(layer "In2.Cu")
		(net "SMB_BMC_PMBUS_STBY_LVC3_SCL")
	)
	(segment
		(start 402.209 -76.19111)
		(end 402.209 -76.34224)
		(width 0.089408)
		(layer "In2.Cu")
		(net "SMB_BMC_PMBUS_STBY_LVC3_SCL")
	)
	(segment
		(start 403.648926 -73.970642)
		(end 402.98243 -74.637138)
		(width 0.089408)
		(layer "In2.Cu")
		(net "SMB_BMC_PMBUS_STBY_LVC3_SCL")
	)
	(segment
		(start 407.967688 -55.959756)
		(end 407.967688 -59.78525)
		(width 0.089408)
		(layer "In2.Cu")
		(net "SMB_BMC_PMBUS_STBY_LVC3_SCL")
	)
	(segment
		(start 467.980522 -54.71414)
		(end 466.912452 -55.78221)
		(width 0.089408)
		(layer "In2.Cu")
		(net "SMB_BMC_PMBUS_STBY_LVC3_SCL")
	)
	(segment
		(start 423.365422 -53.375814)
		(end 420.914576 -53.375814)
		(width 0.089408)
		(layer "In2.Cu")
		(net "SMB_BMC_PMBUS_STBY_LVC3_SCL")
	)
	(segment
		(start 407.199592 -60.553346)
		(end 407.199592 -61.455808)
		(width 0.089408)
		(layer "In2.Cu")
		(net "SMB_BMC_PMBUS_STBY_LVC3_SCL")
	)
	(segment
		(start 435.31663 -53.61686)
		(end 428.285148 -53.61686)
		(width 0.089408)
		(layer "In2.Cu")
		(net "SMB_BMC_PMBUS_STBY_LVC3_SCL")
	)
	(segment
		(start 402.98243 -74.637138)
		(end 402.98243 -75.41768)
		(width 0.089408)
		(layer "In2.Cu")
		(net "SMB_BMC_PMBUS_STBY_LVC3_SCL")
	)
	(segment
		(start 463.937858 -54.793896)
		(end 436.493666 -54.793896)
		(width 0.089408)
		(layer "In2.Cu")
		(net "SMB_BMC_PMBUS_STBY_LVC3_SCL")
	)
	(segment
		(start 474.925898 -52.008786)
		(end 469.795098 -52.008786)
		(width 0.089408)
		(layer "In2.Cu")
		(net "SMB_BMC_PMBUS_STBY_LVC3_SCL")
	)
	(segment
		(start 420.378382 -53.912008)
		(end 414.716976 -53.912008)
		(width 0.089408)
		(layer "In2.Cu")
		(net "SMB_BMC_PMBUS_STBY_LVC3_SCL")
	)
	(segment
		(start 428.285148 -53.61686)
		(end 427.48708 -54.414928)
		(width 0.089408)
		(layer "In2.Cu")
		(net "SMB_BMC_PMBUS_STBY_LVC3_SCL")
	)
	(segment
		(start 408.718258 -54.193186)
		(end 408.718258 -55.209186)
		(width 0.089408)
		(layer "In2.Cu")
		(net "SMB_BMC_PMBUS_STBY_LVC3_SCL")
	)
	(segment
		(start 472.083384 -31.995364)
		(end 471.804492 -31.716472)
		(width 0.089408)
		(layer "In4.Cu")
		(net "SMB_BMC_PMBUS_STBY_LVC3_SCL")
	)
	(segment
		(start 460.679546 -26.0858)
		(end 455.7268 -26.0858)
		(width 0.089408)
		(layer "In4.Cu")
		(net "SMB_BMC_PMBUS_STBY_LVC3_SCL")
	)
	(segment
		(start 20.341082 -22.337522)
		(end 20.340828 -22.337268)
		(width 0.089408)
		(layer "In4.Cu")
		(net "SMB_BMC_PMBUS_STBY_LVC3_SCL")
	)
	(segment
		(start 474.189552 -35.411664)
		(end 472.623642 -35.411664)
		(width 0.089408)
		(layer "In4.Cu")
		(net "SMB_BMC_PMBUS_STBY_LVC3_SCL")
	)
	(segment
		(start 426.644816 -19.952208)
		(end 420.253414 -19.952208)
		(width 0.089408)
		(layer "In4.Cu")
		(net "SMB_BMC_PMBUS_STBY_LVC3_SCL")
	)
	(segment
		(start 439.50509 -19.2532)
		(end 433.533296 -19.2532)
		(width 0.089408)
		(layer "In4.Cu")
		(net "SMB_BMC_PMBUS_STBY_LVC3_SCL")
	)
	(segment
		(start 479.091752 -37.929312)
		(end 478.64649 -37.929312)
		(width 0.089408)
		(layer "In4.Cu")
		(net "SMB_BMC_PMBUS_STBY_LVC3_SCL")
	)
	(segment
		(start 21.2598 -25.3492)
		(end 20.341082 -24.430482)
		(width 0.089408)
		(layer "In4.Cu")
		(net "SMB_BMC_PMBUS_STBY_LVC3_SCL")
	)
	(segment
		(start 471.804746 -30.684978)
		(end 469.10625 -27.986482)
		(width 0.089408)
		(layer "In4.Cu")
		(net "SMB_BMC_PMBUS_STBY_LVC3_SCL")
	)
	(segment
		(start 14.29258 -21.995384)
		(end 11.563858 -21.995384)
		(width 0.089408)
		(layer "In4.Cu")
		(net "SMB_BMC_PMBUS_STBY_LVC3_SCL")
	)
	(segment
		(start -0.200152 -28.710128)
		(end -1.20015 -29.710126)
		(width 0.089408)
		(layer "In4.Cu")
		(net "SMB_BMC_PMBUS_STBY_LVC3_SCL")
	)
	(segment
		(start 472.08313 -32.75711)
		(end 472.08313 -32.327342)
		(width 0.089408)
		(layer "In4.Cu")
		(net "SMB_BMC_PMBUS_STBY_LVC3_SCL")
	)
	(segment
		(start 20.341082 -24.430482)
		(end 20.341082 -22.337522)
		(width 0.089408)
		(layer "In4.Cu")
		(net "SMB_BMC_PMBUS_STBY_LVC3_SCL")
	)
	(segment
		(start 440.454796 -18.303494)
		(end 439.50509 -19.2532)
		(width 0.089408)
		(layer "In4.Cu")
		(net "SMB_BMC_PMBUS_STBY_LVC3_SCL")
	)
	(segment
		(start 448.19189 -19.645122)
		(end 446.850262 -18.303494)
		(width 0.089408)
		(layer "In4.Cu")
		(net "SMB_BMC_PMBUS_STBY_LVC3_SCL")
	)
	(segment
		(start 478.729548 -49.854358)
		(end 478.729548 -48.382428)
		(width 0.089408)
		(layer "In4.Cu")
		(net "SMB_BMC_PMBUS_STBY_LVC3_SCL")
	)
	(segment
		(start 18.688304 -38.175184)
		(end 18.688304 -30.968696)
		(width 0.089408)
		(layer "In4.Cu")
		(net "SMB_BMC_PMBUS_STBY_LVC3_SCL")
	)
	(segment
		(start 477.98736 -51.0286)
		(end 477.98736 -50.596546)
		(width 0.089408)
		(layer "In4.Cu")
		(net "SMB_BMC_PMBUS_STBY_LVC3_SCL")
	)
	(segment
		(start 471.804746 -31.399734)
		(end 471.804746 -30.684978)
		(width 0.089408)
		(layer "In4.Cu")
		(net "SMB_BMC_PMBUS_STBY_LVC3_SCL")
	)
	(segment
		(start 427.722792 -21.030184)
		(end 426.644816 -19.952208)
		(width 0.089408)
		(layer "In4.Cu")
		(net "SMB_BMC_PMBUS_STBY_LVC3_SCL")
	)
	(segment
		(start 433.172616 -19.61388)
		(end 432.509422 -19.61388)
		(width 0.089408)
		(layer "In4.Cu")
		(net "SMB_BMC_PMBUS_STBY_LVC3_SCL")
	)
	(segment
		(start 450.723 -23.240238)
		(end 450.723 -21.871432)
		(width 0.089408)
		(layer "In4.Cu")
		(net "SMB_BMC_PMBUS_STBY_LVC3_SCL")
	)
	(segment
		(start 472.623642 -35.411664)
		(end 472.08313 -34.871152)
		(width 0.089408)
		(layer "In4.Cu")
		(net "SMB_BMC_PMBUS_STBY_LVC3_SCL")
	)
	(segment
		(start 419.3032 -20.193)
		(end 419.0746 -19.9644)
		(width 0.089408)
		(layer "In4.Cu")
		(net "SMB_BMC_PMBUS_STBY_LVC3_SCL")
	)
	(segment
		(start 478.729548 -48.382428)
		(end 479.843846 -47.26813)
		(width 0.089408)
		(layer "In4.Cu")
		(net "SMB_BMC_PMBUS_STBY_LVC3_SCL")
	)
	(segment
		(start 11.4554 -21.9964)
		(end 9.7282 -23.7236)
		(width 0.089408)
		(layer "In4.Cu")
		(net "SMB_BMC_PMBUS_STBY_LVC3_SCL")
	)
	(segment
		(start 420.253414 -19.952208)
		(end 420.012622 -20.193)
		(width 0.089408)
		(layer "In4.Cu")
		(net "SMB_BMC_PMBUS_STBY_LVC3_SCL")
	)
	(segment
		(start 432.509422 -19.61388)
		(end 431.093118 -21.030184)
		(width 0.089408)
		(layer "In4.Cu")
		(net "SMB_BMC_PMBUS_STBY_LVC3_SCL")
	)
	(segment
		(start 420.012622 -20.193)
		(end 419.3032 -20.193)
		(width 0.089408)
		(layer "In4.Cu")
		(net "SMB_BMC_PMBUS_STBY_LVC3_SCL")
	)
	(segment
		(start 19.357848 -21.295106)
		(end 14.992858 -21.295106)
		(width 0.089408)
		(layer "In4.Cu")
		(net "SMB_BMC_PMBUS_STBY_LVC3_SCL")
	)
	(segment
		(start 446.850262 -18.303494)
		(end 440.454796 -18.303494)
		(width 0.089408)
		(layer "In4.Cu")
		(net "SMB_BMC_PMBUS_STBY_LVC3_SCL")
	)
	(segment
		(start 18.688304 -30.968696)
		(end 20.2438 -29.4132)
		(width 0.089408)
		(layer "In4.Cu")
		(net "SMB_BMC_PMBUS_STBY_LVC3_SCL")
	)
	(segment
		(start 20.340828 -22.278086)
		(end 19.357848 -21.295106)
		(width 0.089408)
		(layer "In4.Cu")
		(net "SMB_BMC_PMBUS_STBY_LVC3_SCL")
	)
	(segment
		(start 25.991312 -26.67)
		(end 25.991312 -26.651712)
		(width 0.089408)
		(layer "In4.Cu")
		(net "SMB_BMC_PMBUS_STBY_LVC3_SCL")
	)
	(segment
		(start 469.10625 -27.986482)
		(end 462.580228 -27.986482)
		(width 0.089408)
		(layer "In4.Cu")
		(net "SMB_BMC_PMBUS_STBY_LVC3_SCL")
	)
	(segment
		(start 450.723 -21.871432)
		(end 448.49669 -19.645122)
		(width 0.089408)
		(layer "In4.Cu")
		(net "SMB_BMC_PMBUS_STBY_LVC3_SCL")
	)
	(segment
		(start 471.804492 -31.716472)
		(end 471.804492 -31.399988)
		(width 0.089408)
		(layer "In4.Cu")
		(net "SMB_BMC_PMBUS_STBY_LVC3_SCL")
	)
	(segment
		(start 8.424672 -28.710128)
		(end -0.200152 -28.710128)
		(width 0.089408)
		(layer "In4.Cu")
		(net "SMB_BMC_PMBUS_STBY_LVC3_SCL")
	)
	(segment
		(start 431.093118 -21.030184)
		(end 427.722792 -21.030184)
		(width 0.089408)
		(layer "In4.Cu")
		(net "SMB_BMC_PMBUS_STBY_LVC3_SCL")
	)
	(segment
		(start 448.49669 -19.645122)
		(end 448.19189 -19.645122)
		(width 0.089408)
		(layer "In4.Cu")
		(net "SMB_BMC_PMBUS_STBY_LVC3_SCL")
	)
	(segment
		(start 454.018142 -26.53538)
		(end 450.723 -23.240238)
		(width 0.089408)
		(layer "In4.Cu")
		(net "SMB_BMC_PMBUS_STBY_LVC3_SCL")
	)
	(segment
		(start 11.562842 -21.9964)
		(end 11.4554 -21.9964)
		(width 0.089408)
		(layer "In4.Cu")
		(net "SMB_BMC_PMBUS_STBY_LVC3_SCL")
	)
	(segment
		(start 472.08313 -33.089342)
		(end 472.083384 -33.089088)
		(width 0.089408)
		(layer "In4.Cu")
		(net "SMB_BMC_PMBUS_STBY_LVC3_SCL")
	)
	(segment
		(start 24.6888 -25.3492)
		(end 21.2598 -25.3492)
		(width 0.089408)
		(layer "In4.Cu")
		(net "SMB_BMC_PMBUS_STBY_LVC3_SCL")
	)
	(segment
		(start 433.533296 -19.2532)
		(end 433.172616 -19.61388)
		(width 0.089408)
		(layer "In4.Cu")
		(net "SMB_BMC_PMBUS_STBY_LVC3_SCL")
	)
	(segment
		(start 471.804492 -31.399988)
		(end 471.804746 -31.399734)
		(width 0.089408)
		(layer "In4.Cu")
		(net "SMB_BMC_PMBUS_STBY_LVC3_SCL")
	)
	(segment
		(start 472.083384 -32.757364)
		(end 472.08313 -32.75711)
		(width 0.089408)
		(layer "In4.Cu")
		(net "SMB_BMC_PMBUS_STBY_LVC3_SCL")
	)
	(segment
		(start 472.08313 -32.327342)
		(end 472.083384 -32.327088)
		(width 0.089408)
		(layer "In4.Cu")
		(net "SMB_BMC_PMBUS_STBY_LVC3_SCL")
	)
	(segment
		(start 472.08313 -34.871152)
		(end 472.08313 -33.089342)
		(width 0.089408)
		(layer "In4.Cu")
		(net "SMB_BMC_PMBUS_STBY_LVC3_SCL")
	)
	(segment
		(start 478.3709 -51.41214)
		(end 477.98736 -51.0286)
		(width 0.089408)
		(layer "In4.Cu")
		(net "SMB_BMC_PMBUS_STBY_LVC3_SCL")
	)
	(segment
		(start 25.991312 -26.651712)
		(end 24.6888 -25.3492)
		(width 0.089408)
		(layer "In4.Cu")
		(net "SMB_BMC_PMBUS_STBY_LVC3_SCL")
	)
	(segment
		(start 476.517462 -35.800284)
		(end 474.578172 -35.800284)
		(width 0.089408)
		(layer "In4.Cu")
		(net "SMB_BMC_PMBUS_STBY_LVC3_SCL")
	)
	(segment
		(start 9.7282 -23.7236)
		(end 9.7282 -27.4066)
		(width 0.089408)
		(layer "In4.Cu")
		(net "SMB_BMC_PMBUS_STBY_LVC3_SCL")
	)
	(segment
		(start 472.083384 -32.327088)
		(end 472.083384 -31.995364)
		(width 0.089408)
		(layer "In4.Cu")
		(net "SMB_BMC_PMBUS_STBY_LVC3_SCL")
	)
	(segment
		(start 479.843846 -38.681406)
		(end 479.091752 -37.929312)
		(width 0.089408)
		(layer "In4.Cu")
		(net "SMB_BMC_PMBUS_STBY_LVC3_SCL")
	)
	(segment
		(start 474.578172 -35.800284)
		(end 474.189552 -35.411664)
		(width 0.089408)
		(layer "In4.Cu")
		(net "SMB_BMC_PMBUS_STBY_LVC3_SCL")
	)
	(segment
		(start 11.563858 -21.995384)
		(end 11.562842 -21.9964)
		(width 0.089408)
		(layer "In4.Cu")
		(net "SMB_BMC_PMBUS_STBY_LVC3_SCL")
	)
	(segment
		(start 20.340828 -22.337268)
		(end 20.340828 -22.278086)
		(width 0.089408)
		(layer "In4.Cu")
		(net "SMB_BMC_PMBUS_STBY_LVC3_SCL")
	)
	(segment
		(start 19.21764 -38.70452)
		(end 18.688304 -38.175184)
		(width 0.089408)
		(layer "In4.Cu")
		(net "SMB_BMC_PMBUS_STBY_LVC3_SCL")
	)
	(segment
		(start 14.992858 -21.295106)
		(end 14.29258 -21.995384)
		(width 0.089408)
		(layer "In4.Cu")
		(net "SMB_BMC_PMBUS_STBY_LVC3_SCL")
	)
	(segment
		(start 477.98736 -50.596546)
		(end 478.729548 -49.854358)
		(width 0.089408)
		(layer "In4.Cu")
		(net "SMB_BMC_PMBUS_STBY_LVC3_SCL")
	)
	(segment
		(start 9.7282 -27.4066)
		(end 8.424672 -28.710128)
		(width 0.089408)
		(layer "In4.Cu")
		(net "SMB_BMC_PMBUS_STBY_LVC3_SCL")
	)
	(segment
		(start 20.2438 -29.4132)
		(end 23.29434 -29.4132)
		(width 0.089408)
		(layer "In4.Cu")
		(net "SMB_BMC_PMBUS_STBY_LVC3_SCL")
	)
	(segment
		(start 478.64649 -37.929312)
		(end 476.517462 -35.800284)
		(width 0.089408)
		(layer "In4.Cu")
		(net "SMB_BMC_PMBUS_STBY_LVC3_SCL")
	)
	(segment
		(start 479.843846 -47.26813)
		(end 479.843846 -38.681406)
		(width 0.089408)
		(layer "In4.Cu")
		(net "SMB_BMC_PMBUS_STBY_LVC3_SCL")
	)
	(segment
		(start 25.991312 -26.716228)
		(end 25.991312 -26.67)
		(width 0.089408)
		(layer "In4.Cu")
		(net "SMB_BMC_PMBUS_STBY_LVC3_SCL")
	)
	(segment
		(start 472.083384 -33.089088)
		(end 472.083384 -32.757364)
		(width 0.089408)
		(layer "In4.Cu")
		(net "SMB_BMC_PMBUS_STBY_LVC3_SCL")
	)
	(segment
		(start 23.29434 -29.4132)
		(end 25.991312 -26.716228)
		(width 0.089408)
		(layer "In4.Cu")
		(net "SMB_BMC_PMBUS_STBY_LVC3_SCL")
	)
	(segment
		(start 455.7268 -26.0858)
		(end 455.27722 -26.53538)
		(width 0.089408)
		(layer "In4.Cu")
		(net "SMB_BMC_PMBUS_STBY_LVC3_SCL")
	)
	(segment
		(start 462.580228 -27.986482)
		(end 460.679546 -26.0858)
		(width 0.089408)
		(layer "In4.Cu")
		(net "SMB_BMC_PMBUS_STBY_LVC3_SCL")
	)
	(segment
		(start 455.27722 -26.53538)
		(end 454.018142 -26.53538)
		(width 0.089408)
		(layer "In4.Cu")
		(net "SMB_BMC_PMBUS_STBY_LVC3_SCL")
	)
	(segment
		(start 381.01905 -147.19935)
		(end 382.7526 -148.9329)
		(width 0.089408)
		(layer "In9.Cu")
		(net "SMB_BMC_PMBUS_STBY_LVC3_SCL")
	)
	(segment
		(start 336.85988 -156.2862)
		(end 337.706208 -155.439872)
		(width 0.089408)
		(layer "In9.Cu")
		(net "SMB_BMC_PMBUS_STBY_LVC3_SCL")
	)
	(segment
		(start 344.679778 -141.267434)
		(end 348.229428 -141.267434)
		(width 0.089408)
		(layer "In9.Cu")
		(net "SMB_BMC_PMBUS_STBY_LVC3_SCL")
	)
	(segment
		(start 330.453238 -156.2862)
		(end 336.85988 -156.2862)
		(width 0.089408)
		(layer "In9.Cu")
		(net "SMB_BMC_PMBUS_STBY_LVC3_SCL")
	)
	(segment
		(start 423.247058 -127.131572)
		(end 424.863768 -128.748282)
		(width 0.089408)
		(layer "In9.Cu")
		(net "SMB_BMC_PMBUS_STBY_LVC3_SCL")
	)
	(segment
		(start 186.693302 -155.943808)
		(end 188.01461 -157.265116)
		(width 0.089408)
		(layer "In9.Cu")
		(net "SMB_BMC_PMBUS_STBY_LVC3_SCL")
	)
	(segment
		(start 364.466378 -143.993616)
		(end 365.579406 -142.880588)
		(width 0.089408)
		(layer "In9.Cu")
		(net "SMB_BMC_PMBUS_STBY_LVC3_SCL")
	)
	(segment
		(start 369.064794 -141.162532)
		(end 371.385592 -143.48333)
		(width 0.089408)
		(layer "In9.Cu")
		(net "SMB_BMC_PMBUS_STBY_LVC3_SCL")
	)
	(segment
		(start 352.537268 -141.351762)
		(end 355.179122 -143.993616)
		(width 0.089408)
		(layer "In9.Cu")
		(net "SMB_BMC_PMBUS_STBY_LVC3_SCL")
	)
	(segment
		(start 350.323658 -140.476478)
		(end 350.536256 -140.689076)
		(width 0.089408)
		(layer "In9.Cu")
		(net "SMB_BMC_PMBUS_STBY_LVC3_SCL")
	)
	(segment
		(start 382.7526 -148.9329)
		(end 391.1219 -148.9329)
		(width 0.089408)
		(layer "In9.Cu")
		(net "SMB_BMC_PMBUS_STBY_LVC3_SCL")
	)
	(segment
		(start 391.1219 -148.9329)
		(end 391.414 -149.225)
		(width 0.089408)
		(layer "In9.Cu")
		(net "SMB_BMC_PMBUS_STBY_LVC3_SCL")
	)
	(segment
		(start 349.020384 -140.476478)
		(end 350.323658 -140.476478)
		(width 0.089408)
		(layer "In9.Cu")
		(net "SMB_BMC_PMBUS_STBY_LVC3_SCL")
	)
	(segment
		(start 365.579406 -142.680436)
		(end 365.579152 -142.680182)
		(width 0.089408)
		(layer "In9.Cu")
		(net "SMB_BMC_PMBUS_STBY_LVC3_SCL")
	)
	(segment
		(start 391.414 -149.225)
		(end 392.029696 -149.225)
		(width 0.089408)
		(layer "In9.Cu")
		(net "SMB_BMC_PMBUS_STBY_LVC3_SCL")
	)
	(segment
		(start 264.008616 -157.26537)
		(end 264.208768 -157.26537)
		(width 0.089408)
		(layer "In9.Cu")
		(net "SMB_BMC_PMBUS_STBY_LVC3_SCL")
	)
	(segment
		(start 392.029696 -149.225)
		(end 392.4808 -148.773896)
		(width 0.089408)
		(layer "In9.Cu")
		(net "SMB_BMC_PMBUS_STBY_LVC3_SCL")
	)
	(segment
		(start 424.863768 -128.748282)
		(end 428.7647 -128.748282)
		(width 0.089408)
		(layer "In9.Cu")
		(net "SMB_BMC_PMBUS_STBY_LVC3_SCL")
	)
	(segment
		(start 348.229428 -141.267434)
		(end 349.020384 -140.476478)
		(width 0.089408)
		(layer "In9.Cu")
		(net "SMB_BMC_PMBUS_STBY_LVC3_SCL")
	)
	(segment
		(start 371.385592 -143.48333)
		(end 371.385592 -145.719292)
		(width 0.089408)
		(layer "In9.Cu")
		(net "SMB_BMC_PMBUS_STBY_LVC3_SCL")
	)
	(segment
		(start 264.51306 -156.961078)
		(end 279.91816 -156.961078)
		(width 0.089408)
		(layer "In9.Cu")
		(net "SMB_BMC_PMBUS_STBY_LVC3_SCL")
	)
	(segment
		(start 184.621678 -155.161234)
		(end 185.404252 -155.943808)
		(width 0.089408)
		(layer "In9.Cu")
		(net "SMB_BMC_PMBUS_STBY_LVC3_SCL")
	)
	(segment
		(start 365.579152 -142.680182)
		(end 365.579152 -142.137384)
		(width 0.089408)
		(layer "In9.Cu")
		(net "SMB_BMC_PMBUS_STBY_LVC3_SCL")
	)
	(segment
		(start 431.524156 -131.507738)
		(end 431.524156 -131.88823)
		(width 0.089408)
		(layer "In9.Cu")
		(net "SMB_BMC_PMBUS_STBY_LVC3_SCL")
	)
	(segment
		(start 431.524156 -131.88823)
		(end 431.764694 -132.128768)
		(width 0.089408)
		(layer "In9.Cu")
		(net "SMB_BMC_PMBUS_STBY_LVC3_SCL")
	)
	(segment
		(start 366.554004 -141.162532)
		(end 369.064794 -141.162532)
		(width 0.089408)
		(layer "In9.Cu")
		(net "SMB_BMC_PMBUS_STBY_LVC3_SCL")
	)
	(segment
		(start 352.537268 -141.33322)
		(end 352.537268 -141.351762)
		(width 0.089408)
		(layer "In9.Cu")
		(net "SMB_BMC_PMBUS_STBY_LVC3_SCL")
	)
	(segment
		(start 355.179122 -143.993616)
		(end 364.466378 -143.993616)
		(width 0.089408)
		(layer "In9.Cu")
		(net "SMB_BMC_PMBUS_STBY_LVC3_SCL")
	)
	(segment
		(start 264.008362 -157.265116)
		(end 264.008616 -157.26537)
		(width 0.089408)
		(layer "In9.Cu")
		(net "SMB_BMC_PMBUS_STBY_LVC3_SCL")
	)
	(segment
		(start 337.706208 -155.439872)
		(end 337.706208 -139.686792)
		(width 0.089408)
		(layer "In9.Cu")
		(net "SMB_BMC_PMBUS_STBY_LVC3_SCL")
	)
	(segment
		(start 423.877994 -122.625104)
		(end 423.247058 -123.25604)
		(width 0.089408)
		(layer "In9.Cu")
		(net "SMB_BMC_PMBUS_STBY_LVC3_SCL")
	)
	(segment
		(start 280.40965 -157.452568)
		(end 329.28687 -157.452568)
		(width 0.089408)
		(layer "In9.Cu")
		(net "SMB_BMC_PMBUS_STBY_LVC3_SCL")
	)
	(segment
		(start 365.579152 -142.137384)
		(end 366.554004 -141.162532)
		(width 0.089408)
		(layer "In9.Cu")
		(net "SMB_BMC_PMBUS_STBY_LVC3_SCL")
	)
	(segment
		(start 188.01461 -157.265116)
		(end 264.008362 -157.265116)
		(width 0.089408)
		(layer "In9.Cu")
		(net "SMB_BMC_PMBUS_STBY_LVC3_SCL")
	)
	(segment
		(start 337.706208 -139.686792)
		(end 338.374736 -139.018264)
		(width 0.089408)
		(layer "In9.Cu")
		(net "SMB_BMC_PMBUS_STBY_LVC3_SCL")
	)
	(segment
		(start 424.4467 -122.8344)
		(end 424.237404 -122.625104)
		(width 0.089408)
		(layer "In9.Cu")
		(net "SMB_BMC_PMBUS_STBY_LVC3_SCL")
	)
	(segment
		(start 351.893124 -140.689076)
		(end 352.537268 -141.33322)
		(width 0.089408)
		(layer "In9.Cu")
		(net "SMB_BMC_PMBUS_STBY_LVC3_SCL")
	)
	(segment
		(start 365.579406 -142.880588)
		(end 365.579406 -142.680436)
		(width 0.089408)
		(layer "In9.Cu")
		(net "SMB_BMC_PMBUS_STBY_LVC3_SCL")
	)
	(segment
		(start 423.247058 -123.25604)
		(end 423.247058 -127.131572)
		(width 0.089408)
		(layer "In9.Cu")
		(net "SMB_BMC_PMBUS_STBY_LVC3_SCL")
	)
	(segment
		(start 342.430608 -139.018264)
		(end 344.679778 -141.267434)
		(width 0.089408)
		(layer "In9.Cu")
		(net "SMB_BMC_PMBUS_STBY_LVC3_SCL")
	)
	(segment
		(start 428.7647 -128.748282)
		(end 431.524156 -131.507738)
		(width 0.089408)
		(layer "In9.Cu")
		(net "SMB_BMC_PMBUS_STBY_LVC3_SCL")
	)
	(segment
		(start 338.374736 -139.018264)
		(end 342.430608 -139.018264)
		(width 0.089408)
		(layer "In9.Cu")
		(net "SMB_BMC_PMBUS_STBY_LVC3_SCL")
	)
	(segment
		(start 371.385592 -145.719292)
		(end 372.86565 -147.19935)
		(width 0.089408)
		(layer "In9.Cu")
		(net "SMB_BMC_PMBUS_STBY_LVC3_SCL")
	)
	(segment
		(start 329.28687 -157.452568)
		(end 330.453238 -156.2862)
		(width 0.089408)
		(layer "In9.Cu")
		(net "SMB_BMC_PMBUS_STBY_LVC3_SCL")
	)
	(segment
		(start 279.91816 -156.961078)
		(end 280.40965 -157.452568)
		(width 0.089408)
		(layer "In9.Cu")
		(net "SMB_BMC_PMBUS_STBY_LVC3_SCL")
	)
	(segment
		(start 372.86565 -147.19935)
		(end 381.01905 -147.19935)
		(width 0.089408)
		(layer "In9.Cu")
		(net "SMB_BMC_PMBUS_STBY_LVC3_SCL")
	)
	(segment
		(start 264.208768 -157.26537)
		(end 264.51306 -156.961078)
		(width 0.089408)
		(layer "In9.Cu")
		(net "SMB_BMC_PMBUS_STBY_LVC3_SCL")
	)
	(segment
		(start 350.536256 -140.689076)
		(end 351.893124 -140.689076)
		(width 0.089408)
		(layer "In9.Cu")
		(net "SMB_BMC_PMBUS_STBY_LVC3_SCL")
	)
	(segment
		(start 424.237404 -122.625104)
		(end 423.877994 -122.625104)
		(width 0.089408)
		(layer "In9.Cu")
		(net "SMB_BMC_PMBUS_STBY_LVC3_SCL")
	)
	(segment
		(start 185.404252 -155.943808)
		(end 186.693302 -155.943808)
		(width 0.089408)
		(layer "In9.Cu")
		(net "SMB_BMC_PMBUS_STBY_LVC3_SCL")
	)
	(segment
		(start 22.274022 -50.936906)
		(end 22.274022 -51.41087)
		(width 0.089408)
		(layer "In11.Cu")
		(net "SMB_BMC_PMBUS_STBY_LVC3_SCL")
	)
	(segment
		(start 172.69333 -151.041608)
		(end 166.667434 -151.041608)
		(width 0.089408)
		(layer "In11.Cu")
		(net "SMB_BMC_PMBUS_STBY_LVC3_SCL")
	)
	(segment
		(start 19.646392 -86.00313)
		(end 19.112992 -85.46973)
		(width 0.089408)
		(layer "In11.Cu")
		(net "SMB_BMC_PMBUS_STBY_LVC3_SCL")
	)
	(segment
		(start 392.411712 -148.2979)
		(end 394.97 -148.2979)
		(width 0.089408)
		(layer "In11.Cu")
		(net "SMB_BMC_PMBUS_STBY_LVC3_SCL")
	)
	(segment
		(start 77.9145 -158.3055)
		(end 30.257242 -158.3055)
		(width 0.089408)
		(layer "In11.Cu")
		(net "SMB_BMC_PMBUS_STBY_LVC3_SCL")
	)
	(segment
		(start 15.855696 -80.449166)
		(end 15.855696 -80.130904)
		(width 0.089408)
		(layer "In11.Cu")
		(net "SMB_BMC_PMBUS_STBY_LVC3_SCL")
	)
	(segment
		(start 22.791674 -101.05517)
		(end 21.455888 -99.719384)
		(width 0.089408)
		(layer "In11.Cu")
		(net "SMB_BMC_PMBUS_STBY_LVC3_SCL")
	)
	(segment
		(start 406.8572 -156.8196)
		(end 406.6413 -157.0355)
		(width 0.089408)
		(layer "In11.Cu")
		(net "SMB_BMC_PMBUS_STBY_LVC3_SCL")
	)
	(segment
		(start 112.959896 -157.644592)
		(end 112.858296 -157.746192)
		(width 0.089408)
		(layer "In11.Cu")
		(net "SMB_BMC_PMBUS_STBY_LVC3_SCL")
	)
	(segment
		(start 16.866616 -82.791808)
		(end 15.633192 -81.558384)
		(width 0.089408)
		(layer "In11.Cu")
		(net "SMB_BMC_PMBUS_STBY_LVC3_SCL")
	)
	(segment
		(start 26.29154 -55.428388)
		(end 26.29154 -72.244712)
		(width 0.089408)
		(layer "In11.Cu")
		(net "SMB_BMC_PMBUS_STBY_LVC3_SCL")
	)
	(segment
		(start 19.646392 -87.019384)
		(end 19.646392 -86.00313)
		(width 0.089408)
		(layer "In11.Cu")
		(net "SMB_BMC_PMBUS_STBY_LVC3_SCL")
	)
	(segment
		(start 184.17667 -153.657808)
		(end 183.41467 -152.895808)
		(width 0.089408)
		(layer "In11.Cu")
		(net "SMB_BMC_PMBUS_STBY_LVC3_SCL")
	)
	(segment
		(start 20.567904 -89.261696)
		(end 20.567904 -87.940896)
		(width 0.089408)
		(layer "In11.Cu")
		(net "SMB_BMC_PMBUS_STBY_LVC3_SCL")
	)
	(segment
		(start 15.633192 -81.558384)
		(end 15.633192 -80.67167)
		(width 0.089408)
		(layer "In11.Cu")
		(net "SMB_BMC_PMBUS_STBY_LVC3_SCL")
	)
	(segment
		(start 15.633192 -80.67167)
		(end 15.855696 -80.449166)
		(width 0.089408)
		(layer "In11.Cu")
		(net "SMB_BMC_PMBUS_STBY_LVC3_SCL")
	)
	(segment
		(start 22.274784 -90.968576)
		(end 20.567904 -89.261696)
		(width 0.089408)
		(layer "In11.Cu")
		(net "SMB_BMC_PMBUS_STBY_LVC3_SCL")
	)
	(segment
		(start 157.195012 -157.636718)
		(end 157.188662 -157.636718)
		(width 0.089408)
		(layer "In11.Cu")
		(net "SMB_BMC_PMBUS_STBY_LVC3_SCL")
	)
	(segment
		(start 21.455888 -98.779076)
		(end 22.093682 -98.141282)
		(width 0.089408)
		(layer "In11.Cu")
		(net "SMB_BMC_PMBUS_STBY_LVC3_SCL")
	)
	(segment
		(start 27.673808 -130.083306)
		(end 27.673808 -127.68072)
		(width 0.089408)
		(layer "In11.Cu")
		(net "SMB_BMC_PMBUS_STBY_LVC3_SCL")
	)
	(segment
		(start 22.791674 -108.24337)
		(end 22.791674 -101.05517)
		(width 0.089408)
		(layer "In11.Cu")
		(net "SMB_BMC_PMBUS_STBY_LVC3_SCL")
	)
	(segment
		(start 27.42438 -131.766818)
		(end 27.57678 -131.614418)
		(width 0.089408)
		(layer "In11.Cu")
		(net "SMB_BMC_PMBUS_STBY_LVC3_SCL")
	)
	(segment
		(start 19.112992 -83.684364)
		(end 18.220436 -82.791808)
		(width 0.089408)
		(layer "In11.Cu")
		(net "SMB_BMC_PMBUS_STBY_LVC3_SCL")
	)
	(segment
		(start 27.342592 -125.634242)
		(end 27.889962 -125.086872)
		(width 0.089408)
		(layer "In11.Cu")
		(net "SMB_BMC_PMBUS_STBY_LVC3_SCL")
	)
	(segment
		(start 392.4808 -148.773896)
		(end 392.271504 -148.5646)
		(width 0.089408)
		(layer "In11.Cu")
		(net "SMB_BMC_PMBUS_STBY_LVC3_SCL")
	)
	(segment
		(start 21.455888 -99.719384)
		(end 21.455888 -98.779076)
		(width 0.089408)
		(layer "In11.Cu")
		(net "SMB_BMC_PMBUS_STBY_LVC3_SCL")
	)
	(segment
		(start 184.81167 -153.657808)
		(end 184.17667 -153.657808)
		(width 0.089408)
		(layer "In11.Cu")
		(net "SMB_BMC_PMBUS_STBY_LVC3_SCL")
	)
	(segment
		(start 392.271504 -148.5646)
		(end 392.271504 -148.438108)
		(width 0.089408)
		(layer "In11.Cu")
		(net "SMB_BMC_PMBUS_STBY_LVC3_SCL")
	)
	(segment
		(start 22.093682 -98.138488)
		(end 22.274784 -97.957386)
		(width 0.089408)
		(layer "In11.Cu")
		(net "SMB_BMC_PMBUS_STBY_LVC3_SCL")
	)
	(segment
		(start 27.889962 -113.341658)
		(end 22.791674 -108.24337)
		(width 0.089408)
		(layer "In11.Cu")
		(net "SMB_BMC_PMBUS_STBY_LVC3_SCL")
	)
	(segment
		(start 27.57678 -131.614418)
		(end 27.57678 -130.180334)
		(width 0.089408)
		(layer "In11.Cu")
		(net "SMB_BMC_PMBUS_STBY_LVC3_SCL")
	)
	(segment
		(start 405.510492 -153.085292)
		(end 406.2603 -153.8351)
		(width 0.089408)
		(layer "In11.Cu")
		(net "SMB_BMC_PMBUS_STBY_LVC3_SCL")
	)
	(segment
		(start 174.039276 -149.695662)
		(end 172.69333 -151.041608)
		(width 0.089408)
		(layer "In11.Cu")
		(net "SMB_BMC_PMBUS_STBY_LVC3_SCL")
	)
	(segment
		(start 19.511772 -38.998652)
		(end 19.511772 -42.65295)
		(width 0.089408)
		(layer "In11.Cu")
		(net "SMB_BMC_PMBUS_STBY_LVC3_SCL")
	)
	(segment
		(start 399.6944 -149.9235)
		(end 400.5961 -150.8252)
		(width 0.089408)
		(layer "In11.Cu")
		(net "SMB_BMC_PMBUS_STBY_LVC3_SCL")
	)
	(segment
		(start 403.949662 -150.8252)
		(end 405.510492 -152.38603)
		(width 0.089408)
		(layer "In11.Cu")
		(net "SMB_BMC_PMBUS_STBY_LVC3_SCL")
	)
	(segment
		(start 181.368192 -151.48433)
		(end 181.02707 -151.143208)
		(width 0.089408)
		(layer "In11.Cu")
		(net "SMB_BMC_PMBUS_STBY_LVC3_SCL")
	)
	(segment
		(start 164.828474 -152.880568)
		(end 161.26587 -152.880568)
		(width 0.089408)
		(layer "In11.Cu")
		(net "SMB_BMC_PMBUS_STBY_LVC3_SCL")
	)
	(segment
		(start 406.2603 -153.8351)
		(end 406.2603 -155.739084)
		(width 0.089408)
		(layer "In11.Cu")
		(net "SMB_BMC_PMBUS_STBY_LVC3_SCL")
	)
	(segment
		(start 394.97 -148.2979)
		(end 396.5956 -149.9235)
		(width 0.089408)
		(layer "In11.Cu")
		(net "SMB_BMC_PMBUS_STBY_LVC3_SCL")
	)
	(segment
		(start 27.889962 -125.086872)
		(end 27.889962 -113.341658)
		(width 0.089408)
		(layer "In11.Cu")
		(net "SMB_BMC_PMBUS_STBY_LVC3_SCL")
	)
	(segment
		(start 22.274784 -97.957386)
		(end 22.274784 -90.968576)
		(width 0.089408)
		(layer "In11.Cu")
		(net "SMB_BMC_PMBUS_STBY_LVC3_SCL")
	)
	(segment
		(start 400.5961 -150.8252)
		(end 403.949662 -150.8252)
		(width 0.089408)
		(layer "In11.Cu")
		(net "SMB_BMC_PMBUS_STBY_LVC3_SCL")
	)
	(segment
		(start 405.510492 -152.38603)
		(end 405.510492 -153.085292)
		(width 0.089408)
		(layer "In11.Cu")
		(net "SMB_BMC_PMBUS_STBY_LVC3_SCL")
	)
	(segment
		(start 406.8572 -156.335984)
		(end 406.8572 -156.8196)
		(width 0.089408)
		(layer "In11.Cu")
		(net "SMB_BMC_PMBUS_STBY_LVC3_SCL")
	)
	(segment
		(start 161.26587 -152.880568)
		(end 158.690564 -155.455874)
		(width 0.089408)
		(layer "In11.Cu")
		(net "SMB_BMC_PMBUS_STBY_LVC3_SCL")
	)
	(segment
		(start 27.57678 -130.180334)
		(end 27.673808 -130.083306)
		(width 0.089408)
		(layer "In11.Cu")
		(net "SMB_BMC_PMBUS_STBY_LVC3_SCL")
	)
	(segment
		(start 24.4602 -77.89418)
		(end 21.55698 -80.7974)
		(width 0.089408)
		(layer "In11.Cu")
		(net "SMB_BMC_PMBUS_STBY_LVC3_SCL")
	)
	(segment
		(start 20.567904 -87.940896)
		(end 19.646392 -87.019384)
		(width 0.089408)
		(layer "In11.Cu")
		(net "SMB_BMC_PMBUS_STBY_LVC3_SCL")
	)
	(segment
		(start 181.368192 -152.11933)
		(end 181.368192 -151.48433)
		(width 0.089408)
		(layer "In11.Cu")
		(net "SMB_BMC_PMBUS_STBY_LVC3_SCL")
	)
	(segment
		(start 21.55698 -80.7974)
		(end 18.542 -80.7974)
		(width 0.089408)
		(layer "In11.Cu")
		(net "SMB_BMC_PMBUS_STBY_LVC3_SCL")
	)
	(segment
		(start 185.096658 -153.942796)
		(end 184.81167 -153.657808)
		(width 0.089408)
		(layer "In11.Cu")
		(net "SMB_BMC_PMBUS_STBY_LVC3_SCL")
	)
	(segment
		(start 27.42438 -155.472638)
		(end 27.42438 -131.766818)
		(width 0.089408)
		(layer "In11.Cu")
		(net "SMB_BMC_PMBUS_STBY_LVC3_SCL")
	)
	(segment
		(start 185.096658 -154.686254)
		(end 185.096658 -153.942796)
		(width 0.089408)
		(layer "In11.Cu")
		(net "SMB_BMC_PMBUS_STBY_LVC3_SCL")
	)
	(segment
		(start 183.41467 -152.895808)
		(end 182.14467 -152.895808)
		(width 0.089408)
		(layer "In11.Cu")
		(net "SMB_BMC_PMBUS_STBY_LVC3_SCL")
	)
	(segment
		(start 30.257242 -158.3055)
		(end 27.42438 -155.472638)
		(width 0.089408)
		(layer "In11.Cu")
		(net "SMB_BMC_PMBUS_STBY_LVC3_SCL")
	)
	(segment
		(start 21.188172 -49.851056)
		(end 22.274022 -50.936906)
		(width 0.089408)
		(layer "In11.Cu")
		(net "SMB_BMC_PMBUS_STBY_LVC3_SCL")
	)
	(segment
		(start 18.220436 -82.791808)
		(end 16.866616 -82.791808)
		(width 0.089408)
		(layer "In11.Cu")
		(net "SMB_BMC_PMBUS_STBY_LVC3_SCL")
	)
	(segment
		(start 184.621678 -155.161234)
		(end 185.096658 -154.686254)
		(width 0.089408)
		(layer "In11.Cu")
		(net "SMB_BMC_PMBUS_STBY_LVC3_SCL")
	)
	(segment
		(start 21.188172 -44.32935)
		(end 21.188172 -49.851056)
		(width 0.089408)
		(layer "In11.Cu")
		(net "SMB_BMC_PMBUS_STBY_LVC3_SCL")
	)
	(segment
		(start 27.342592 -127.349504)
		(end 27.342592 -125.634242)
		(width 0.089408)
		(layer "In11.Cu")
		(net "SMB_BMC_PMBUS_STBY_LVC3_SCL")
	)
	(segment
		(start 15.855696 -80.130904)
		(end 16.256 -79.7306)
		(width 0.089408)
		(layer "In11.Cu")
		(net "SMB_BMC_PMBUS_STBY_LVC3_SCL")
	)
	(segment
		(start 18.542 -80.7974)
		(end 17.690592 -79.945992)
		(width 0.089408)
		(layer "In11.Cu")
		(net "SMB_BMC_PMBUS_STBY_LVC3_SCL")
	)
	(segment
		(start 158.690564 -156.141166)
		(end 157.195012 -157.636718)
		(width 0.089408)
		(layer "In11.Cu")
		(net "SMB_BMC_PMBUS_STBY_LVC3_SCL")
	)
	(segment
		(start 78.473808 -157.746192)
		(end 77.9145 -158.3055)
		(width 0.089408)
		(layer "In11.Cu")
		(net "SMB_BMC_PMBUS_STBY_LVC3_SCL")
	)
	(segment
		(start 16.471392 -79.945992)
		(end 16.256 -79.7306)
		(width 0.089408)
		(layer "In11.Cu")
		(net "SMB_BMC_PMBUS_STBY_LVC3_SCL")
	)
	(segment
		(start 19.21764 -38.70452)
		(end 19.511772 -38.998652)
		(width 0.089408)
		(layer "In11.Cu")
		(net "SMB_BMC_PMBUS_STBY_LVC3_SCL")
	)
	(segment
		(start 17.690592 -79.945992)
		(end 16.471392 -79.945992)
		(width 0.089408)
		(layer "In11.Cu")
		(net "SMB_BMC_PMBUS_STBY_LVC3_SCL")
	)
	(segment
		(start 182.14467 -152.895808)
		(end 181.368192 -152.11933)
		(width 0.089408)
		(layer "In11.Cu")
		(net "SMB_BMC_PMBUS_STBY_LVC3_SCL")
	)
	(segment
		(start 392.271504 -148.438108)
		(end 392.411712 -148.2979)
		(width 0.089408)
		(layer "In11.Cu")
		(net "SMB_BMC_PMBUS_STBY_LVC3_SCL")
	)
	(segment
		(start 178.61407 -151.143208)
		(end 177.166524 -149.695662)
		(width 0.089408)
		(layer "In11.Cu")
		(net "SMB_BMC_PMBUS_STBY_LVC3_SCL")
	)
	(segment
		(start 26.29154 -72.244712)
		(end 24.4602 -74.076052)
		(width 0.089408)
		(layer "In11.Cu")
		(net "SMB_BMC_PMBUS_STBY_LVC3_SCL")
	)
	(segment
		(start 166.667434 -151.041608)
		(end 164.828474 -152.880568)
		(width 0.089408)
		(layer "In11.Cu")
		(net "SMB_BMC_PMBUS_STBY_LVC3_SCL")
	)
	(segment
		(start 177.166524 -149.695662)
		(end 174.039276 -149.695662)
		(width 0.089408)
		(layer "In11.Cu")
		(net "SMB_BMC_PMBUS_STBY_LVC3_SCL")
	)
	(segment
		(start 406.2603 -155.739084)
		(end 406.8572 -156.335984)
		(width 0.089408)
		(layer "In11.Cu")
		(net "SMB_BMC_PMBUS_STBY_LVC3_SCL")
	)
	(segment
		(start 157.180788 -157.644592)
		(end 112.959896 -157.644592)
		(width 0.089408)
		(layer "In11.Cu")
		(net "SMB_BMC_PMBUS_STBY_LVC3_SCL")
	)
	(segment
		(start 112.858296 -157.746192)
		(end 78.473808 -157.746192)
		(width 0.089408)
		(layer "In11.Cu")
		(net "SMB_BMC_PMBUS_STBY_LVC3_SCL")
	)
	(segment
		(start 19.112992 -85.46973)
		(end 19.112992 -83.684364)
		(width 0.089408)
		(layer "In11.Cu")
		(net "SMB_BMC_PMBUS_STBY_LVC3_SCL")
	)
	(segment
		(start 181.02707 -151.143208)
		(end 178.61407 -151.143208)
		(width 0.089408)
		(layer "In11.Cu")
		(net "SMB_BMC_PMBUS_STBY_LVC3_SCL")
	)
	(segment
		(start 396.5956 -149.9235)
		(end 399.6944 -149.9235)
		(width 0.089408)
		(layer "In11.Cu")
		(net "SMB_BMC_PMBUS_STBY_LVC3_SCL")
	)
	(segment
		(start 157.188662 -157.636718)
		(end 157.180788 -157.644592)
		(width 0.089408)
		(layer "In11.Cu")
		(net "SMB_BMC_PMBUS_STBY_LVC3_SCL")
	)
	(segment
		(start 22.093682 -98.141282)
		(end 22.093682 -98.138488)
		(width 0.089408)
		(layer "In11.Cu")
		(net "SMB_BMC_PMBUS_STBY_LVC3_SCL")
	)
	(segment
		(start 158.690564 -155.455874)
		(end 158.690564 -156.141166)
		(width 0.089408)
		(layer "In11.Cu")
		(net "SMB_BMC_PMBUS_STBY_LVC3_SCL")
	)
	(segment
		(start 24.4602 -74.076052)
		(end 24.4602 -77.89418)
		(width 0.089408)
		(layer "In11.Cu")
		(net "SMB_BMC_PMBUS_STBY_LVC3_SCL")
	)
	(segment
		(start 27.673808 -127.68072)
		(end 27.342592 -127.349504)
		(width 0.089408)
		(layer "In11.Cu")
		(net "SMB_BMC_PMBUS_STBY_LVC3_SCL")
	)
	(segment
		(start 19.511772 -42.65295)
		(end 21.188172 -44.32935)
		(width 0.089408)
		(layer "In11.Cu")
		(net "SMB_BMC_PMBUS_STBY_LVC3_SCL")
	)
	(segment
		(start 22.274022 -51.41087)
		(end 26.29154 -55.428388)
		(width 0.089408)
		(layer "In11.Cu")
		(net "SMB_BMC_PMBUS_STBY_LVC3_SCL")
	)
	(segment
		(start 2.794 -70.358)
		(end 2.794 -69.977)
		(width 0.10795)
		(layer "F.Cu")
		(net "PU_TMP421_2_A0")
	)
	(segment
		(start 2.71272 -70.43928)
		(end 2.794 -70.358)
		(width 0.10795)
		(layer "F.Cu")
		(net "PU_TMP421_2_A0")
	)
	(segment
		(start 2.71272 -71.247)
		(end 2.71272 -70.43928)
		(width 0.10795)
		(layer "F.Cu")
		(net "PU_TMP421_2_A0")
	)
	(segment
		(start 2.032 -70.485)
		(end 2.032 -69.977)
		(width 0.10795)
		(layer "F.Cu")
		(net "PD_TMP421_2_A1")
	)
	(segment
		(start 2.06248 -70.51548)
		(end 2.032 -70.485)
		(width 0.10795)
		(layer "F.Cu")
		(net "PD_TMP421_2_A1")
	)
	(segment
		(start 2.06248 -71.247)
		(end 2.06248 -70.51548)
		(width 0.10795)
		(layer "F.Cu")
		(net "PD_TMP421_2_A1")
	)
	(segment
		(start 488.6706 -121.28754)
		(end 489.19892 -120.75922)
		(width 0.10795)
		(layer "F.Cu")
		(net "PD_TMP421_1_A0")
	)
	(segment
		(start 488.6706 -121.80062)
		(end 488.6706 -121.28754)
		(width 0.10795)
		(layer "F.Cu")
		(net "PD_TMP421_1_A0")
	)
	(segment
		(start 404.111714 -50.50536)
		(end 404.111714 -51.404012)
		(width 0.10795)
		(layer "F.Cu")
		(net "PD_FRU_WP")
	)
	(segment
		(start 405.289766 -50.230278)
		(end 404.386796 -50.230278)
		(width 0.10795)
		(layer "F.Cu")
		(net "PD_FRU_WP")
	)
	(segment
		(start 404.498556 -52.578)
		(end 406.1968 -52.578)
		(width 0.10795)
		(layer "F.Cu")
		(net "PD_FRU_WP")
	)
	(segment
		(start 405.482044 -50.038)
		(end 405.289766 -50.230278)
		(width 0.10795)
		(layer "F.Cu")
		(net "PD_FRU_WP")
	)
	(segment
		(start 406.0825 -50.038)
		(end 405.482044 -50.038)
		(width 0.10795)
		(layer "F.Cu")
		(net "PD_FRU_WP")
	)
	(segment
		(start 404.111714 -51.404012)
		(end 404.111714 -52.191158)
		(width 0.10795)
		(layer "F.Cu")
		(net "PD_FRU_WP")
	)
	(segment
		(start 404.111714 -52.191158)
		(end 404.498556 -52.578)
		(width 0.10795)
		(layer "F.Cu")
		(net "PD_FRU_WP")
	)
	(segment
		(start 404.386796 -50.230278)
		(end 404.111714 -50.50536)
		(width 0.10795)
		(layer "F.Cu")
		(net "PD_FRU_WP")
	)
	(via
		(at 404.111714 -51.404012)
		(size 0.508)
		(drill 0.254)
		(layers "F.Cu" "B.Cu")
		(net "PD_FRU_WP")
	)
	(segment
		(start 480.918774 -18.48739)
		(end 481.066094 -18.63471)
		(width 0.254)
		(layer "F.Cu")
		(net "GND_LAN_TRCT1234_C")
	)
	(segment
		(start 479.19386 -18.48739)
		(end 480.08286 -18.48739)
		(width 0.254)
		(layer "F.Cu")
		(net "GND_LAN_TRCT1234_C")
	)
	(segment
		(start 478.30486 -18.48739)
		(end 479.19386 -18.48739)
		(width 0.254)
		(layer "F.Cu")
		(net "GND_LAN_TRCT1234_C")
	)
	(segment
		(start 480.08286 -18.48739)
		(end 480.918774 -18.48739)
		(width 0.254)
		(layer "F.Cu")
		(net "GND_LAN_TRCT1234_C")
	)
	(via
		(at 481.066094 -18.63471)
		(size 0.508)
		(drill 0.254)
		(layers "F.Cu" "B.Cu")
		(net "GND_LAN_TRCT1234_C")
	)
	(via
		(at 479.2472 -18.415)
		(size 0.6604)
		(drill 0.3302)
		(layers "F.Cu" "B.Cu")
		(net "GND_LAN_TRCT1234_C")
	)
	(segment
		(start 482.84003 -10.575036)
		(end 480.525836 -10.575036)
		(width 0.254)
		(layer "B.Cu")
		(net "GND_LAN_TRCT1234_C")
	)
	(segment
		(start 479.7425 -10.3251)
		(end 479.2472 -10.8204)
		(width 0.254)
		(layer "B.Cu")
		(net "GND_LAN_TRCT1234_C")
	)
	(segment
		(start 479.6536 -18.8214)
		(end 480.852734 -18.8214)
		(width 0.254)
		(layer "B.Cu")
		(net "GND_LAN_TRCT1234_C")
	)
	(segment
		(start 479.2472 -10.8204)
		(end 479.2472 -18.415)
		(width 0.254)
		(layer "B.Cu")
		(net "GND_LAN_TRCT1234_C")
	)
	(segment
		(start 481.039424 -18.63471)
		(end 481.066094 -18.63471)
		(width 0.254)
		(layer "B.Cu")
		(net "GND_LAN_TRCT1234_C")
	)
	(segment
		(start 480.852734 -18.8214)
		(end 481.039424 -18.63471)
		(width 0.254)
		(layer "B.Cu")
		(net "GND_LAN_TRCT1234_C")
	)
	(segment
		(start 480.525836 -10.575036)
		(end 480.2759 -10.3251)
		(width 0.254)
		(layer "B.Cu")
		(net "GND_LAN_TRCT1234_C")
	)
	(segment
		(start 480.2759 -10.3251)
		(end 479.7425 -10.3251)
		(width 0.254)
		(layer "B.Cu")
		(net "GND_LAN_TRCT1234_C")
	)
	(segment
		(start 479.2472 -18.415)
		(end 479.6536 -18.8214)
		(width 0.254)
		(layer "B.Cu")
		(net "GND_LAN_TRCT1234_C")
	)
	(segment
		(start 480.385374 -0.900176)
		(end 480.385374 -9.701784)
		(width 0.254)
		(layer "In2.Cu")
		(net "GND_LAN_TRCT1234_C")
	)
	(segment
		(start 480.385374 -9.701784)
		(end 481.258626 -10.575036)
		(width 0.254)
		(layer "In2.Cu")
		(net "GND_LAN_TRCT1234_C")
	)
	(segment
		(start 481.258626 -10.575036)
		(end 482.84003 -10.575036)
		(width 0.254)
		(layer "In2.Cu")
		(net "GND_LAN_TRCT1234_C")
	)
	(segment
		(start 482.84003 -0.425196)
		(end 480.860354 -0.425196)
		(width 0.254)
		(layer "In2.Cu")
		(net "GND_LAN_TRCT1234_C")
	)
	(segment
		(start 480.860354 -0.425196)
		(end 480.385374 -0.900176)
		(width 0.254)
		(layer "In2.Cu")
		(net "GND_LAN_TRCT1234_C")
	)
	(segment
		(start 483.759256 4.259072)
		(end 483.759256 3.861562)
		(width 0.10795)
		(layer "B.Cu")
		(net "NIC_LED_ACT_ANODE_R")
	)
	(segment
		(start 484.471472 4.971288)
		(end 483.759256 4.259072)
		(width 0.10795)
		(layer "B.Cu")
		(net "NIC_LED_ACT_ANODE_R")
	)
	(segment
		(start 483.759256 3.861562)
		(end 482.84003 2.942336)
		(width 0.10795)
		(layer "B.Cu")
		(net "NIC_LED_ACT_ANODE_R")
	)
	(segment
		(start 485.049322 4.971288)
		(end 484.471472 4.971288)
		(width 0.10795)
		(layer "B.Cu")
		(net "NIC_LED_ACT_ANODE_R")
	)
	(segment
		(start 482.84003 2.942336)
		(end 482.84003 1.604772)
		(width 0.10795)
		(layer "B.Cu")
		(net "NIC_LED_ACT_ANODE_R")
	)
	(via
		(at 481.33 -15.6464)
		(size 0.6604)
		(drill 0.3302)
		(layers "F.Cu" "B.Cu")
		(net "LED_LAN_2_R_N")
	)
	(segment
		(start 483.785164 -17.036542)
		(end 483.785164 -16.60271)
		(width 0.10795)
		(layer "B.Cu")
		(net "LED_LAN_2_R_N")
	)
	(segment
		(start 481.33 -15.04823)
		(end 482.84003 -13.5382)
		(width 0.10795)
		(layer "B.Cu")
		(net "LED_LAN_2_R_N")
	)
	(segment
		(start 481.7872 -16.1036)
		(end 481.33 -15.6464)
		(width 0.10795)
		(layer "B.Cu")
		(net "LED_LAN_2_R_N")
	)
	(segment
		(start 481.33 -15.6464)
		(end 481.33 -15.04823)
		(width 0.10795)
		(layer "B.Cu")
		(net "LED_LAN_2_R_N")
	)
	(segment
		(start 483.785164 -16.60271)
		(end 483.286054 -16.1036)
		(width 0.10795)
		(layer "B.Cu")
		(net "LED_LAN_2_R_N")
	)
	(segment
		(start 482.84003 -13.5382)
		(end 482.84003 -12.605004)
		(width 0.10795)
		(layer "B.Cu")
		(net "LED_LAN_2_R_N")
	)
	(segment
		(start 483.286054 -16.1036)
		(end 481.7872 -16.1036)
		(width 0.10795)
		(layer "B.Cu")
		(net "LED_LAN_2_R_N")
	)
	(segment
		(start 479.16211 3.827272)
		(end 479.16211 2.997708)
		(width 0.10795)
		(layer "B.Cu")
		(net "LED_LAN_1_R_N")
	)
	(segment
		(start 479.16211 2.997708)
		(end 481.57003 0.589788)
		(width 0.10795)
		(layer "B.Cu")
		(net "LED_LAN_1_R_N")
	)
	(via
		(at 480.439476 -17.928336)
		(size 0.6604)
		(drill 0.3302)
		(layers "F.Cu" "B.Cu")
		(net "LED_LAN_0_R_N")
	)
	(segment
		(start 481.57003 -11.59002)
		(end 480.7204 -12.43965)
		(width 0.10795)
		(layer "B.Cu")
		(net "LED_LAN_0_R_N")
	)
	(segment
		(start 480.439476 -17.928336)
		(end 481.30079 -17.067022)
		(width 0.10795)
		(layer "B.Cu")
		(net "LED_LAN_0_R_N")
	)
	(segment
		(start 480.439476 -17.133824)
		(end 480.439476 -17.928336)
		(width 0.10795)
		(layer "B.Cu")
		(net "LED_LAN_0_R_N")
	)
	(segment
		(start 481.30079 -17.067022)
		(end 482.132894 -17.067022)
		(width 0.10795)
		(layer "B.Cu")
		(net "LED_LAN_0_R_N")
	)
	(segment
		(start 480.7204 -12.43965)
		(end 480.7204 -16.8529)
		(width 0.10795)
		(layer "B.Cu")
		(net "LED_LAN_0_R_N")
	)
	(segment
		(start 480.7204 -16.8529)
		(end 480.439476 -17.133824)
		(width 0.10795)
		(layer "B.Cu")
		(net "LED_LAN_0_R_N")
	)
	(via
		(at 17.3228 -48.5648)
		(size 0.6604)
		(drill 0.3302)
		(layers "F.Cu" "B.Cu")
		(net "ISENSE_TMP421_2_E")
	)
	(segment
		(start 16.025622 -50.369978)
		(end 17.3228 -49.0728)
		(width 0.254)
		(layer "B.Cu")
		(net "ISENSE_TMP421_2_E")
	)
	(segment
		(start 17.907 -47.371)
		(end 17.907 -47.9806)
		(width 0.254)
		(layer "B.Cu")
		(net "ISENSE_TMP421_2_E")
	)
	(segment
		(start 17.907 -47.9806)
		(end 17.3228 -48.5648)
		(width 0.254)
		(layer "B.Cu")
		(net "ISENSE_TMP421_2_E")
	)
	(segment
		(start 16.025622 -51.3842)
		(end 16.025622 -50.369978)
		(width 0.254)
		(layer "B.Cu")
		(net "ISENSE_TMP421_2_E")
	)
	(segment
		(start 17.3228 -49.0728)
		(end 17.3228 -48.5648)
		(width 0.254)
		(layer "B.Cu")
		(net "ISENSE_TMP421_2_E")
	)
	(segment
		(start 0.576326 -70.354952)
		(end 0.762 -70.540626)
		(width 0.254)
		(layer "F.Cu")
		(net "ISENSE_TMP421_2_DXP")
	)
	(segment
		(start 0.315468 -69.21627)
		(end 0.576326 -69.477128)
		(width 0.254)
		(layer "F.Cu")
		(net "ISENSE_TMP421_2_DXP")
	)
	(segment
		(start 0.576326 -69.477128)
		(end 0.576326 -70.354952)
		(width 0.254)
		(layer "F.Cu")
		(net "ISENSE_TMP421_2_DXP")
	)
	(segment
		(start 0.762 -70.540626)
		(end 0.762 -71.247)
		(width 0.254)
		(layer "F.Cu")
		(net "ISENSE_TMP421_2_DXP")
	)
	(segment
		(start 0.315468 -68.586858)
		(end 0.315468 -69.21627)
		(width 0.254)
		(layer "F.Cu")
		(net "ISENSE_TMP421_2_DXP")
	)
	(via
		(at 0.576326 -69.477128)
		(size 0.508)
		(drill 0.254)
		(layers "F.Cu" "B.Cu")
		(net "ISENSE_TMP421_2_DXP")
	)
	(via
		(at 15.559024 -47.244)
		(size 0.508)
		(drill 0.254)
		(layers "F.Cu" "B.Cu")
		(net "ISENSE_TMP421_2_DXP")
	)
	(segment
		(start 15.559024 -47.244)
		(end 15.686024 -47.371)
		(width 0.254)
		(layer "B.Cu")
		(net "ISENSE_TMP421_2_DXP")
	)
	(segment
		(start 15.686024 -47.371)
		(end 17.018 -47.371)
		(width 0.254)
		(layer "B.Cu")
		(net "ISENSE_TMP421_2_DXP")
	)
	(segment
		(start 14.216634 -46.830234)
		(end 14.899386 -46.830234)
		(width 0.254)
		(layer "In9.Cu")
		(net "ISENSE_TMP421_2_DXP")
	)
	(segment
		(start -2.890774 -48.36414)
		(end 12.682728 -48.36414)
		(width 0.254)
		(layer "In9.Cu")
		(net "ISENSE_TMP421_2_DXP")
	)
	(segment
		(start 12.682728 -48.36414)
		(end 14.216634 -46.830234)
		(width 0.254)
		(layer "In9.Cu")
		(net "ISENSE_TMP421_2_DXP")
	)
	(segment
		(start -0.287528 -69.94398)
		(end -0.690118 -69.54139)
		(width 0.254)
		(layer "In9.Cu")
		(net "ISENSE_TMP421_2_DXP")
	)
	(segment
		(start -4.296156 -59.96051)
		(end -4.296156 -49.769522)
		(width 0.254)
		(layer "In9.Cu")
		(net "ISENSE_TMP421_2_DXP")
	)
	(segment
		(start 0.576326 -69.507608)
		(end 0.139954 -69.94398)
		(width 0.254)
		(layer "In9.Cu")
		(net "ISENSE_TMP421_2_DXP")
	)
	(segment
		(start -0.690118 -69.54139)
		(end -0.690118 -63.566548)
		(width 0.254)
		(layer "In9.Cu")
		(net "ISENSE_TMP421_2_DXP")
	)
	(segment
		(start 15.313152 -47.244)
		(end 15.559024 -47.244)
		(width 0.254)
		(layer "In9.Cu")
		(net "ISENSE_TMP421_2_DXP")
	)
	(segment
		(start -0.690118 -63.566548)
		(end -4.296156 -59.96051)
		(width 0.254)
		(layer "In9.Cu")
		(net "ISENSE_TMP421_2_DXP")
	)
	(segment
		(start -4.296156 -49.769522)
		(end -2.890774 -48.36414)
		(width 0.254)
		(layer "In9.Cu")
		(net "ISENSE_TMP421_2_DXP")
	)
	(segment
		(start 14.899386 -46.830234)
		(end 15.313152 -47.244)
		(width 0.254)
		(layer "In9.Cu")
		(net "ISENSE_TMP421_2_DXP")
	)
	(segment
		(start 0.576326 -69.477128)
		(end 0.576326 -69.507608)
		(width 0.254)
		(layer "In9.Cu")
		(net "ISENSE_TMP421_2_DXP")
	)
	(segment
		(start 0.139954 -69.94398)
		(end -0.287528 -69.94398)
		(width 0.254)
		(layer "In9.Cu")
		(net "ISENSE_TMP421_2_DXP")
	)
	(segment
		(start 1.204468 -69.338444)
		(end 1.204468 -68.586858)
		(width 0.254)
		(layer "F.Cu")
		(net "ISENSE_TMP421_2_DXN")
	)
	(segment
		(start 1.41224 -70.230492)
		(end 1.30048 -70.118732)
		(width 0.254)
		(layer "F.Cu")
		(net "ISENSE_TMP421_2_DXN")
	)
	(segment
		(start 1.30048 -69.434456)
		(end 1.204468 -69.338444)
		(width 0.254)
		(layer "F.Cu")
		(net "ISENSE_TMP421_2_DXN")
	)
	(segment
		(start 1.41224 -71.247)
		(end 1.41224 -70.230492)
		(width 0.254)
		(layer "F.Cu")
		(net "ISENSE_TMP421_2_DXN")
	)
	(segment
		(start 1.30048 -70.118732)
		(end 1.30048 -69.434456)
		(width 0.254)
		(layer "F.Cu")
		(net "ISENSE_TMP421_2_DXN")
	)
	(via
		(at 1.30048 -70.118732)
		(size 0.508)
		(drill 0.254)
		(layers "F.Cu" "B.Cu")
		(net "ISENSE_TMP421_2_DXN")
	)
	(via
		(at 15.584424 -45.974)
		(size 0.508)
		(drill 0.254)
		(layers "F.Cu" "B.Cu")
		(net "ISENSE_TMP421_2_DXN")
	)
	(segment
		(start 16.094964 -46.482)
		(end 15.586964 -45.974)
		(width 0.254)
		(layer "B.Cu")
		(net "ISENSE_TMP421_2_DXN")
	)
	(segment
		(start 15.586964 -45.974)
		(end 15.584424 -45.974)
		(width 0.254)
		(layer "B.Cu")
		(net "ISENSE_TMP421_2_DXN")
	)
	(segment
		(start 17.018 -46.482)
		(end 16.094964 -46.482)
		(width 0.254)
		(layer "B.Cu")
		(net "ISENSE_TMP421_2_DXN")
	)
	(segment
		(start 1.091438 -70.118732)
		(end 1.30048 -70.118732)
		(width 0.254)
		(layer "In9.Cu")
		(net "ISENSE_TMP421_2_DXN")
	)
	(segment
		(start -5.100066 -49.40554)
		(end -5.100066 -60.27166)
		(width 0.254)
		(layer "In9.Cu")
		(net "ISENSE_TMP421_2_DXN")
	)
	(segment
		(start -3.24739 -47.552864)
		(end -5.100066 -49.40554)
		(width 0.254)
		(layer "In9.Cu")
		(net "ISENSE_TMP421_2_DXN")
	)
	(segment
		(start 12.355576 -47.552864)
		(end -3.24739 -47.552864)
		(width 0.254)
		(layer "In9.Cu")
		(net "ISENSE_TMP421_2_DXN")
	)
	(segment
		(start 15.584424 -45.974)
		(end 13.93444 -45.974)
		(width 0.254)
		(layer "In9.Cu")
		(net "ISENSE_TMP421_2_DXN")
	)
	(segment
		(start -5.100066 -60.27166)
		(end -1.494282 -63.877444)
		(width 0.254)
		(layer "In9.Cu")
		(net "ISENSE_TMP421_2_DXN")
	)
	(segment
		(start -1.494282 -63.877444)
		(end -1.494282 -70.023228)
		(width 0.254)
		(layer "In9.Cu")
		(net "ISENSE_TMP421_2_DXN")
	)
	(segment
		(start 0.430784 -70.779386)
		(end 1.091438 -70.118732)
		(width 0.254)
		(layer "In9.Cu")
		(net "ISENSE_TMP421_2_DXN")
	)
	(segment
		(start -1.494282 -70.023228)
		(end -0.738124 -70.779386)
		(width 0.254)
		(layer "In9.Cu")
		(net "ISENSE_TMP421_2_DXN")
	)
	(segment
		(start 13.93444 -45.974)
		(end 12.355576 -47.552864)
		(width 0.254)
		(layer "In9.Cu")
		(net "ISENSE_TMP421_2_DXN")
	)
	(segment
		(start -0.738124 -70.779386)
		(end 0.430784 -70.779386)
		(width 0.254)
		(layer "In9.Cu")
		(net "ISENSE_TMP421_2_DXN")
	)
	(via
		(at 19.8374 -48.1076)
		(size 0.6604)
		(drill 0.3302)
		(layers "F.Cu" "B.Cu")
		(net "ISENSE_TMP421_2_BC")
	)
	(segment
		(start 18.525744 -51.3842)
		(end 21.025866 -51.3842)
		(width 0.254)
		(layer "B.Cu")
		(net "ISENSE_TMP421_2_BC")
	)
	(segment
		(start 19.8374 -48.1076)
		(end 19.8374 -50.072544)
		(width 0.254)
		(layer "B.Cu")
		(net "ISENSE_TMP421_2_BC")
	)
	(segment
		(start 18.262346 -46.482)
		(end 19.8374 -48.057054)
		(width 0.254)
		(layer "B.Cu")
		(net "ISENSE_TMP421_2_BC")
	)
	(segment
		(start 19.8374 -50.072544)
		(end 18.525744 -51.3842)
		(width 0.254)
		(layer "B.Cu")
		(net "ISENSE_TMP421_2_BC")
	)
	(segment
		(start 17.907 -46.482)
		(end 18.262346 -46.482)
		(width 0.254)
		(layer "B.Cu")
		(net "ISENSE_TMP421_2_BC")
	)
	(segment
		(start 19.8374 -48.057054)
		(end 19.8374 -48.1076)
		(width 0.254)
		(layer "B.Cu")
		(net "ISENSE_TMP421_2_BC")
	)
	(segment
		(start 486.387394 -125.92685)
		(end 485.89184 -125.431296)
		(width 0.254)
		(layer "F.Cu")
		(net "ISENSE_TMP421_1_E")
	)
	(segment
		(start 485.89184 -125.431296)
		(end 485.89184 -123.79706)
		(width 0.254)
		(layer "F.Cu")
		(net "ISENSE_TMP421_1_E")
	)
	(segment
		(start 487.27868 -123.75134)
		(end 487.23296 -123.79706)
		(width 0.254)
		(layer "F.Cu")
		(net "ISENSE_TMP421_1_DXP")
	)
	(segment
		(start 487.49458 -123.81992)
		(end 487.426 -123.75134)
		(width 0.254)
		(layer "F.Cu")
		(net "ISENSE_TMP421_1_DXP")
	)
	(segment
		(start 488.60202 -123.81992)
		(end 487.49458 -123.81992)
		(width 0.254)
		(layer "F.Cu")
		(net "ISENSE_TMP421_1_DXP")
	)
	(segment
		(start 487.23296 -123.79706)
		(end 486.78084 -123.79706)
		(width 0.254)
		(layer "F.Cu")
		(net "ISENSE_TMP421_1_DXP")
	)
	(segment
		(start 487.426 -123.75134)
		(end 487.27868 -123.75134)
		(width 0.254)
		(layer "F.Cu")
		(net "ISENSE_TMP421_1_DXP")
	)
	(segment
		(start 488.6706 -123.75134)
		(end 488.60202 -123.81992)
		(width 0.254)
		(layer "F.Cu")
		(net "ISENSE_TMP421_1_DXP")
	)
	(via
		(at 487.426 -123.75134)
		(size 0.508)
		(drill 0.254)
		(layers "F.Cu" "B.Cu")
		(net "ISENSE_TMP421_1_DXP")
	)
	(segment
		(start 488.50804 -123.55068)
		(end 487.62666 -123.55068)
		(width 0.254)
		(layer "B.Cu")
		(net "ISENSE_TMP421_1_DXP")
	)
	(segment
		(start 487.62666 -123.55068)
		(end 487.426 -123.75134)
		(width 0.254)
		(layer "B.Cu")
		(net "ISENSE_TMP421_1_DXP")
	)
	(segment
		(start 487.48442 -122.8471)
		(end 487.48442 -122.79122)
		(width 0.254)
		(layer "F.Cu")
		(net "ISENSE_TMP421_1_DXN")
	)
	(segment
		(start 487.73842 -123.1011)
		(end 487.48442 -122.8471)
		(width 0.254)
		(layer "F.Cu")
		(net "ISENSE_TMP421_1_DXN")
	)
	(segment
		(start 486.76306 -122.91314)
		(end 486.88498 -122.79122)
		(width 0.254)
		(layer "F.Cu")
		(net "ISENSE_TMP421_1_DXN")
	)
	(segment
		(start 486.88498 -122.79122)
		(end 487.48442 -122.79122)
		(width 0.254)
		(layer "F.Cu")
		(net "ISENSE_TMP421_1_DXN")
	)
	(segment
		(start 488.6706 -123.1011)
		(end 487.73842 -123.1011)
		(width 0.254)
		(layer "F.Cu")
		(net "ISENSE_TMP421_1_DXN")
	)
	(via
		(at 487.48442 -122.79122)
		(size 0.508)
		(drill 0.254)
		(layers "F.Cu" "B.Cu")
		(net "ISENSE_TMP421_1_DXN")
	)
	(segment
		(start 488.50804 -122.66168)
		(end 487.61396 -122.66168)
		(width 0.254)
		(layer "B.Cu")
		(net "ISENSE_TMP421_1_DXN")
	)
	(segment
		(start 487.61396 -122.66168)
		(end 487.48442 -122.79122)
		(width 0.254)
		(layer "B.Cu")
		(net "ISENSE_TMP421_1_DXN")
	)
	(segment
		(start 485.77754 -127.0381)
		(end 487.776266 -127.0381)
		(width 0.254)
		(layer "F.Cu")
		(net "ISENSE_TMP421_1_BC")
	)
	(segment
		(start 485.87406 -122.91314)
		(end 485.06126 -123.72594)
		(width 0.254)
		(layer "F.Cu")
		(net "ISENSE_TMP421_1_BC")
	)
	(segment
		(start 485.06126 -123.72594)
		(end 485.06126 -126.32182)
		(width 0.254)
		(layer "F.Cu")
		(net "ISENSE_TMP421_1_BC")
	)
	(segment
		(start 485.06126 -126.32182)
		(end 485.77754 -127.0381)
		(width 0.254)
		(layer "F.Cu")
		(net "ISENSE_TMP421_1_BC")
	)
	(segment
		(start 487.776266 -127.0381)
		(end 488.887516 -125.92685)
		(width 0.254)
		(layer "F.Cu")
		(net "ISENSE_TMP421_1_BC")
	)
	(segment
		(start 488.887516 -125.92685)
		(end 491.387638 -125.92685)
		(width 0.254)
		(layer "F.Cu")
		(net "ISENSE_TMP421_1_BC")
	)
	(segment
		(start 490.752638 -125.29185)
		(end 491.387638 -125.92685)
		(width 0.508)
		(layer "In11.Cu")
		(net "ISENSE_TMP421_1_BC")
	)
	(segment
		(start 491.387638 -125.92685)
		(end 492.022638 -125.29185)
		(width 0.508)
		(layer "In11.Cu")
		(net "ISENSE_TMP421_1_BC")
	)
	(segment
		(start 488.887516 -125.92685)
		(end 489.522516 -125.29185)
		(width 0.508)
		(layer "In11.Cu")
		(net "ISENSE_TMP421_1_BC")
	)
	(segment
		(start 488.887516 -125.100842)
		(end 488.887516 -125.92685)
		(width 0.508)
		(layer "In11.Cu")
		(net "ISENSE_TMP421_1_BC")
	)
	(segment
		(start 471.88374 -31.960566)
		(end 471.88374 -30.02026)
		(width 0.10795)
		(layer "F.Cu")
		(net "SMB_HOST_STBY_LVC3_SDA")
	)
	(segment
		(start 422.9862 -108.204)
		(end 423.526966 -108.204)
		(width 0.10795)
		(layer "F.Cu")
		(net "SMB_HOST_STBY_LVC3_SDA")
	)
	(segment
		(start 472.059 -29.845)
		(end 472.313 -29.845)
		(width 0.10795)
		(layer "F.Cu")
		(net "SMB_HOST_STBY_LVC3_SDA")
	)
	(segment
		(start 462.980278 -148.219922)
		(end 461.41894 -148.219922)
		(width 0.10795)
		(layer "F.Cu")
		(net "SMB_HOST_STBY_LVC3_SDA")
	)
	(segment
		(start 174.058072 -73.839324)
		(end 174.948342 -73.839324)
		(width 0.10795)
		(layer "F.Cu")
		(net "SMB_HOST_STBY_LVC3_SDA")
	)
	(segment
		(start 461.41894 -148.219922)
		(end 461.277208 -148.361654)
		(width 0.10795)
		(layer "F.Cu")
		(net "SMB_HOST_STBY_LVC3_SDA")
	)
	(segment
		(start 419.725348 -108.51515)
		(end 422.67505 -108.51515)
		(width 0.10795)
		(layer "F.Cu")
		(net "SMB_HOST_STBY_LVC3_SDA")
	)
	(segment
		(start 174.36338 -71.84898)
		(end 174.36338 -71.68388)
		(width 0.10795)
		(layer "F.Cu")
		(net "SMB_HOST_STBY_LVC3_SDA")
	)
	(segment
		(start 412.13024 -106.8197)
		(end 418.029898 -106.8197)
		(width 0.10795)
		(layer "F.Cu")
		(net "SMB_HOST_STBY_LVC3_SDA")
	)
	(segment
		(start 471.88374 -30.02026)
		(end 472.059 -29.845)
		(width 0.10795)
		(layer "F.Cu")
		(net "SMB_HOST_STBY_LVC3_SDA")
	)
	(segment
		(start 175.43272 -72.91832)
		(end 174.36338 -71.84898)
		(width 0.10795)
		(layer "F.Cu")
		(net "SMB_HOST_STBY_LVC3_SDA")
	)
	(segment
		(start 422.67505 -108.51515)
		(end 422.9862 -108.204)
		(width 0.10795)
		(layer "F.Cu")
		(net "SMB_HOST_STBY_LVC3_SDA")
	)
	(segment
		(start 471.68308 -32.161226)
		(end 471.88374 -31.960566)
		(width 0.10795)
		(layer "F.Cu")
		(net "SMB_HOST_STBY_LVC3_SDA")
	)
	(segment
		(start 423.526966 -108.204)
		(end 423.603166 -108.1278)
		(width 0.10795)
		(layer "F.Cu")
		(net "SMB_HOST_STBY_LVC3_SDA")
	)
	(segment
		(start 401.77974 -32.902652)
		(end 401.381976 -32.902652)
		(width 0.10795)
		(layer "F.Cu")
		(net "SMB_HOST_STBY_LVC3_SDA")
	)
	(segment
		(start 401.381976 -32.902652)
		(end 401.14474 -32.665416)
		(width 0.10795)
		(layer "F.Cu")
		(net "SMB_HOST_STBY_LVC3_SDA")
	)
	(segment
		(start 174.948342 -73.839324)
		(end 175.43272 -73.354946)
		(width 0.10795)
		(layer "F.Cu")
		(net "SMB_HOST_STBY_LVC3_SDA")
	)
	(segment
		(start 175.43272 -73.354946)
		(end 175.43272 -72.91832)
		(width 0.10795)
		(layer "F.Cu")
		(net "SMB_HOST_STBY_LVC3_SDA")
	)
	(segment
		(start 411.695138 -106.384598)
		(end 412.13024 -106.8197)
		(width 0.10795)
		(layer "F.Cu")
		(net "SMB_HOST_STBY_LVC3_SDA")
	)
	(segment
		(start 423.603166 -108.1278)
		(end 423.603166 -107.853734)
		(width 0.10795)
		(layer "F.Cu")
		(net "SMB_HOST_STBY_LVC3_SDA")
	)
	(segment
		(start 418.029898 -106.8197)
		(end 419.725348 -108.51515)
		(width 0.10795)
		(layer "F.Cu")
		(net "SMB_HOST_STBY_LVC3_SDA")
	)
	(via
		(at 467.5505 -120.833896)
		(size 0.508)
		(drill 0.254)
		(layers "F.Cu" "B.Cu")
		(net "SMB_HOST_STBY_LVC3_SDA")
	)
	(via
		(at 478.0788 -59.5376)
		(size 0.508)
		(drill 0.254)
		(layers "F.Cu" "B.Cu")
		(net "SMB_HOST_STBY_LVC3_SDA")
	)
	(via
		(at 448.8815 -22.733)
		(size 0.508)
		(drill 0.254)
		(layers "F.Cu" "B.Cu")
		(net "SMB_HOST_STBY_LVC3_SDA")
	)
	(via
		(at 174.36338 -71.68388)
		(size 0.508)
		(drill 0.254)
		(layers "F.Cu" "B.Cu")
		(net "SMB_HOST_STBY_LVC3_SDA")
	)
	(via
		(at 402.300694 -17.19326)
		(size 0.508)
		(drill 0.254)
		(layers "F.Cu" "B.Cu")
		(net "SMB_HOST_STBY_LVC3_SDA")
	)
	(via
		(at 401.14474 -32.665416)
		(size 0.508)
		(drill 0.254)
		(layers "F.Cu" "B.Cu")
		(net "SMB_HOST_STBY_LVC3_SDA")
	)
	(via
		(at 190.9826 -0.1016)
		(size 0.508)
		(drill 0.254)
		(layers "F.Cu" "B.Cu")
		(net "SMB_HOST_STBY_LVC3_SDA")
	)
	(via
		(at 423.603166 -107.853734)
		(size 0.508)
		(drill 0.254)
		(layers "F.Cu" "B.Cu")
		(net "SMB_HOST_STBY_LVC3_SDA")
	)
	(via
		(at 471.68308 -32.161226)
		(size 0.508)
		(drill 0.254)
		(layers "F.Cu" "B.Cu")
		(net "SMB_HOST_STBY_LVC3_SDA")
	)
	(via
		(at 461.277208 -148.361654)
		(size 0.508)
		(drill 0.254)
		(layers "F.Cu" "B.Cu")
		(net "SMB_HOST_STBY_LVC3_SDA")
	)
	(via
		(at 332.481682 -23.828756)
		(size 0.508)
		(drill 0.254)
		(layers "F.Cu" "B.Cu")
		(net "SMB_HOST_STBY_LVC3_SDA")
	)
	(via
		(at 400.457924 -26.515568)
		(size 0.508)
		(drill 0.254)
		(layers "F.Cu" "B.Cu")
		(net "SMB_HOST_STBY_LVC3_SDA")
	)
	(via
		(at 401.270978 -19.263614)
		(size 0.508)
		(drill 0.254)
		(layers "F.Cu" "B.Cu")
		(net "SMB_HOST_STBY_LVC3_SDA")
	)
	(via
		(at 403.764242 -6.230112)
		(size 0.508)
		(drill 0.254)
		(layers "F.Cu" "B.Cu")
		(net "SMB_HOST_STBY_LVC3_SDA")
	)
	(segment
		(start 448.106546 -22.733)
		(end 447.642742 -22.269196)
		(width 0.10795)
		(layer "B.Cu")
		(net "SMB_HOST_STBY_LVC3_SDA")
	)
	(segment
		(start 447.642742 -22.269196)
		(end 447.136266 -22.269196)
		(width 0.10795)
		(layer "B.Cu")
		(net "SMB_HOST_STBY_LVC3_SDA")
	)
	(segment
		(start 404.007828 -6.473698)
		(end 404.007828 -8.506206)
		(width 0.10795)
		(layer "B.Cu")
		(net "SMB_HOST_STBY_LVC3_SDA")
	)
	(segment
		(start 403.674072 -11.266678)
		(end 403.674072 -15.819882)
		(width 0.10795)
		(layer "B.Cu")
		(net "SMB_HOST_STBY_LVC3_SDA")
	)
	(segment
		(start 404.961852 -9.978898)
		(end 403.674072 -11.266678)
		(width 0.10795)
		(layer "B.Cu")
		(net "SMB_HOST_STBY_LVC3_SDA")
	)
	(segment
		(start 401.488656 -19.045936)
		(end 401.270978 -19.263614)
		(width 0.10795)
		(layer "B.Cu")
		(net "SMB_HOST_STBY_LVC3_SDA")
	)
	(segment
		(start 403.674072 -15.819882)
		(end 402.300694 -17.19326)
		(width 0.10795)
		(layer "B.Cu")
		(net "SMB_HOST_STBY_LVC3_SDA")
	)
	(segment
		(start 404.961852 -9.46023)
		(end 404.961852 -9.978898)
		(width 0.10795)
		(layer "B.Cu")
		(net "SMB_HOST_STBY_LVC3_SDA")
	)
	(segment
		(start 404.007828 -8.506206)
		(end 404.961852 -9.46023)
		(width 0.10795)
		(layer "B.Cu")
		(net "SMB_HOST_STBY_LVC3_SDA")
	)
	(segment
		(start 401.488656 -18.005298)
		(end 401.488656 -19.045936)
		(width 0.10795)
		(layer "B.Cu")
		(net "SMB_HOST_STBY_LVC3_SDA")
	)
	(segment
		(start 402.300694 -17.19326)
		(end 401.488656 -18.005298)
		(width 0.10795)
		(layer "B.Cu")
		(net "SMB_HOST_STBY_LVC3_SDA")
	)
	(segment
		(start 449.6435 -22.733)
		(end 448.8815 -22.733)
		(width 0.10795)
		(layer "B.Cu")
		(net "SMB_HOST_STBY_LVC3_SDA")
	)
	(segment
		(start 403.764242 -6.230112)
		(end 404.007828 -6.473698)
		(width 0.10795)
		(layer "B.Cu")
		(net "SMB_HOST_STBY_LVC3_SDA")
	)
	(segment
		(start 448.8815 -22.733)
		(end 448.106546 -22.733)
		(width 0.10795)
		(layer "B.Cu")
		(net "SMB_HOST_STBY_LVC3_SDA")
	)
	(segment
		(start 468.468456 -63.3984)
		(end 467.025482 -63.3984)
		(width 0.089408)
		(layer "In2.Cu")
		(net "SMB_HOST_STBY_LVC3_SDA")
	)
	(segment
		(start 190.9826 -0.1016)
		(end 191.27978 0.19558)
		(width 0.089408)
		(layer "In2.Cu")
		(net "SMB_HOST_STBY_LVC3_SDA")
	)
	(segment
		(start 173.736 -70.47992)
		(end 174.05096 -70.79488)
		(width 0.089408)
		(layer "In2.Cu")
		(net "SMB_HOST_STBY_LVC3_SDA")
	)
	(segment
		(start 160.810448 -58.786268)
		(end 161.67608 -59.6519)
		(width 0.089408)
		(layer "In2.Cu")
		(net "SMB_HOST_STBY_LVC3_SDA")
	)
	(segment
		(start 183.8706 -44.055538)
		(end 180.805582 -47.120556)
		(width 0.089408)
		(layer "In2.Cu")
		(net "SMB_HOST_STBY_LVC3_SDA")
	)
	(segment
		(start 424.868594 -79.15148)
		(end 424.868594 -79.763874)
		(width 0.089408)
		(layer "In2.Cu")
		(net "SMB_HOST_STBY_LVC3_SDA")
	)
	(segment
		(start 477.865948 -59.45124)
		(end 477.476566 -59.840622)
		(width 0.089408)
		(layer "In2.Cu")
		(net "SMB_HOST_STBY_LVC3_SDA")
	)
	(segment
		(start 190.868808 -5.7912)
		(end 190.868808 -6.676898)
		(width 0.089408)
		(layer "In2.Cu")
		(net "SMB_HOST_STBY_LVC3_SDA")
	)
	(segment
		(start 191.162432 -2.084832)
		(end 192.385442 -3.307842)
		(width 0.089408)
		(layer "In2.Cu")
		(net "SMB_HOST_STBY_LVC3_SDA")
	)
	(segment
		(start 424.248072 -76.617576)
		(end 424.248072 -78.530958)
		(width 0.089408)
		(layer "In2.Cu")
		(net "SMB_HOST_STBY_LVC3_SDA")
	)
	(segment
		(start 171.98975 -63.810388)
		(end 171.590208 -64.20993)
		(width 0.089408)
		(layer "In2.Cu")
		(net "SMB_HOST_STBY_LVC3_SDA")
	)
	(segment
		(start 184.479946 -19.538442)
		(end 184.479946 -19.638264)
		(width 0.089408)
		(layer "In2.Cu")
		(net "SMB_HOST_STBY_LVC3_SDA")
	)
	(segment
		(start 191.162432 -1.84658)
		(end 191.162432 -2.084832)
		(width 0.089408)
		(layer "In2.Cu")
		(net "SMB_HOST_STBY_LVC3_SDA")
	)
	(segment
		(start 478.0788 -59.5376)
		(end 477.99244 -59.45124)
		(width 0.089408)
		(layer "In2.Cu")
		(net "SMB_HOST_STBY_LVC3_SDA")
	)
	(segment
		(start 171.590208 -64.20993)
		(end 171.590208 -67.39509)
		(width 0.089408)
		(layer "In2.Cu")
		(net "SMB_HOST_STBY_LVC3_SDA")
	)
	(segment
		(start 165.50132 -47.120556)
		(end 160.810448 -51.811428)
		(width 0.089408)
		(layer "In2.Cu")
		(net "SMB_HOST_STBY_LVC3_SDA")
	)
	(segment
		(start 173.6852 -62.27064)
		(end 173.6852 -63.278766)
		(width 0.089408)
		(layer "In2.Cu")
		(net "SMB_HOST_STBY_LVC3_SDA")
	)
	(segment
		(start 424.248072 -78.530958)
		(end 424.868594 -79.15148)
		(width 0.089408)
		(layer "In2.Cu")
		(net "SMB_HOST_STBY_LVC3_SDA")
	)
	(segment
		(start 163.91636 -63.3603)
		(end 165.65372 -61.62294)
		(width 0.089408)
		(layer "In2.Cu")
		(net "SMB_HOST_STBY_LVC3_SDA")
	)
	(segment
		(start 424.868594 -80.080866)
		(end 424.868594 -106.236262)
		(width 0.089408)
		(layer "In2.Cu")
		(net "SMB_HOST_STBY_LVC3_SDA")
	)
	(segment
		(start 427.951646 -64.848994)
		(end 426.431202 -64.848994)
		(width 0.089408)
		(layer "In2.Cu")
		(net "SMB_HOST_STBY_LVC3_SDA")
	)
	(segment
		(start 424.868848 -80.080612)
		(end 424.868594 -80.080866)
		(width 0.089408)
		(layer "In2.Cu")
		(net "SMB_HOST_STBY_LVC3_SDA")
	)
	(segment
		(start 465.574634 -64.849248)
		(end 427.9519 -64.849248)
		(width 0.089408)
		(layer "In2.Cu")
		(net "SMB_HOST_STBY_LVC3_SDA")
	)
	(segment
		(start 161.67608 -62.52972)
		(end 162.50666 -63.3603)
		(width 0.089408)
		(layer "In2.Cu")
		(net "SMB_HOST_STBY_LVC3_SDA")
	)
	(segment
		(start 173.153578 -63.810388)
		(end 171.98975 -63.810388)
		(width 0.089408)
		(layer "In2.Cu")
		(net "SMB_HOST_STBY_LVC3_SDA")
	)
	(segment
		(start 424.868594 -106.236262)
		(end 423.603166 -107.50169)
		(width 0.089408)
		(layer "In2.Cu")
		(net "SMB_HOST_STBY_LVC3_SDA")
	)
	(segment
		(start 469.649048 -62.217808)
		(end 468.468456 -63.3984)
		(width 0.089408)
		(layer "In2.Cu")
		(net "SMB_HOST_STBY_LVC3_SDA")
	)
	(segment
		(start 187.367418 -17.906746)
		(end 186.757564 -18.5166)
		(width 0.089408)
		(layer "In2.Cu")
		(net "SMB_HOST_STBY_LVC3_SDA")
	)
	(segment
		(start 192.05194 0.60452)
		(end 192.30848 0.34798)
		(width 0.089408)
		(layer "In2.Cu")
		(net "SMB_HOST_STBY_LVC3_SDA")
	)
	(segment
		(start 190.868808 -6.676898)
		(end 191.6176 -7.42569)
		(width 0.089408)
		(layer "In2.Cu")
		(net "SMB_HOST_STBY_LVC3_SDA")
	)
	(segment
		(start 187.367418 -16.209772)
		(end 187.367418 -17.906746)
		(width 0.089408)
		(layer "In2.Cu")
		(net "SMB_HOST_STBY_LVC3_SDA")
	)
	(segment
		(start 191.27978 0.41402)
		(end 191.47028 0.60452)
		(width 0.089408)
		(layer "In2.Cu")
		(net "SMB_HOST_STBY_LVC3_SDA")
	)
	(segment
		(start 477.476566 -60.604908)
		(end 475.068646 -63.012828)
		(width 0.089408)
		(layer "In2.Cu")
		(net "SMB_HOST_STBY_LVC3_SDA")
	)
	(segment
		(start 191.6176 -11.575034)
		(end 191.4144 -11.778234)
		(width 0.089408)
		(layer "In2.Cu")
		(net "SMB_HOST_STBY_LVC3_SDA")
	)
	(segment
		(start 173.6852 -63.278766)
		(end 173.153578 -63.810388)
		(width 0.089408)
		(layer "In2.Cu")
		(net "SMB_HOST_STBY_LVC3_SDA")
	)
	(segment
		(start 192.30848 0.34798)
		(end 192.30848 -0.700532)
		(width 0.089408)
		(layer "In2.Cu")
		(net "SMB_HOST_STBY_LVC3_SDA")
	)
	(segment
		(start 174.05096 -70.79488)
		(end 174.05096 -71.37146)
		(width 0.089408)
		(layer "In2.Cu")
		(net "SMB_HOST_STBY_LVC3_SDA")
	)
	(segment
		(start 160.810448 -51.811428)
		(end 160.810448 -58.786268)
		(width 0.089408)
		(layer "In2.Cu")
		(net "SMB_HOST_STBY_LVC3_SDA")
	)
	(segment
		(start 423.556938 -75.926442)
		(end 424.248072 -76.617576)
		(width 0.089408)
		(layer "In2.Cu")
		(net "SMB_HOST_STBY_LVC3_SDA")
	)
	(segment
		(start 467.025482 -63.3984)
		(end 465.574634 -64.849248)
		(width 0.089408)
		(layer "In2.Cu")
		(net "SMB_HOST_STBY_LVC3_SDA")
	)
	(segment
		(start 184.4802 -19.638518)
		(end 184.4802 -38.0492)
		(width 0.089408)
		(layer "In2.Cu")
		(net "SMB_HOST_STBY_LVC3_SDA")
	)
	(segment
		(start 475.068646 -63.012828)
		(end 473.028772 -63.012828)
		(width 0.089408)
		(layer "In2.Cu")
		(net "SMB_HOST_STBY_LVC3_SDA")
	)
	(segment
		(start 173.0375 -61.62294)
		(end 173.6852 -62.27064)
		(width 0.089408)
		(layer "In2.Cu")
		(net "SMB_HOST_STBY_LVC3_SDA")
	)
	(segment
		(start 174.05096 -71.37146)
		(end 174.36338 -71.68388)
		(width 0.089408)
		(layer "In2.Cu")
		(net "SMB_HOST_STBY_LVC3_SDA")
	)
	(segment
		(start 427.9519 -64.849248)
		(end 427.951646 -64.848994)
		(width 0.089408)
		(layer "In2.Cu")
		(net "SMB_HOST_STBY_LVC3_SDA")
	)
	(segment
		(start 424.868594 -79.763874)
		(end 424.868848 -79.764128)
		(width 0.089408)
		(layer "In2.Cu")
		(net "SMB_HOST_STBY_LVC3_SDA")
	)
	(segment
		(start 189.973204 -15.217394)
		(end 188.359796 -15.217394)
		(width 0.089408)
		(layer "In2.Cu")
		(net "SMB_HOST_STBY_LVC3_SDA")
	)
	(segment
		(start 191.7954 -5.2578)
		(end 191.402208 -5.2578)
		(width 0.089408)
		(layer "In2.Cu")
		(net "SMB_HOST_STBY_LVC3_SDA")
	)
	(segment
		(start 191.4144 -11.778234)
		(end 191.4144 -13.776198)
		(width 0.089408)
		(layer "In2.Cu")
		(net "SMB_HOST_STBY_LVC3_SDA")
	)
	(segment
		(start 171.590208 -67.39509)
		(end 173.736 -69.540882)
		(width 0.089408)
		(layer "In2.Cu")
		(net "SMB_HOST_STBY_LVC3_SDA")
	)
	(segment
		(start 192.385442 -3.307842)
		(end 192.385442 -4.664202)
		(width 0.089408)
		(layer "In2.Cu")
		(net "SMB_HOST_STBY_LVC3_SDA")
	)
	(segment
		(start 184.4802 -38.0492)
		(end 183.8706 -38.6588)
		(width 0.089408)
		(layer "In2.Cu")
		(net "SMB_HOST_STBY_LVC3_SDA")
	)
	(segment
		(start 185.501788 -18.5166)
		(end 184.479946 -19.538442)
		(width 0.089408)
		(layer "In2.Cu")
		(net "SMB_HOST_STBY_LVC3_SDA")
	)
	(segment
		(start 192.30848 -0.700532)
		(end 191.162432 -1.84658)
		(width 0.089408)
		(layer "In2.Cu")
		(net "SMB_HOST_STBY_LVC3_SDA")
	)
	(segment
		(start 162.50666 -63.3603)
		(end 163.91636 -63.3603)
		(width 0.089408)
		(layer "In2.Cu")
		(net "SMB_HOST_STBY_LVC3_SDA")
	)
	(segment
		(start 191.402208 -5.2578)
		(end 190.868808 -5.7912)
		(width 0.089408)
		(layer "In2.Cu")
		(net "SMB_HOST_STBY_LVC3_SDA")
	)
	(segment
		(start 192.385442 -4.664202)
		(end 192.38722 -4.66598)
		(width 0.089408)
		(layer "In2.Cu")
		(net "SMB_HOST_STBY_LVC3_SDA")
	)
	(segment
		(start 191.4144 -13.776198)
		(end 189.973204 -15.217394)
		(width 0.089408)
		(layer "In2.Cu")
		(net "SMB_HOST_STBY_LVC3_SDA")
	)
	(segment
		(start 477.99244 -59.45124)
		(end 477.865948 -59.45124)
		(width 0.089408)
		(layer "In2.Cu")
		(net "SMB_HOST_STBY_LVC3_SDA")
	)
	(segment
		(start 184.479946 -19.638264)
		(end 184.4802 -19.638518)
		(width 0.089408)
		(layer "In2.Cu")
		(net "SMB_HOST_STBY_LVC3_SDA")
	)
	(segment
		(start 180.805582 -47.120556)
		(end 165.50132 -47.120556)
		(width 0.089408)
		(layer "In2.Cu")
		(net "SMB_HOST_STBY_LVC3_SDA")
	)
	(segment
		(start 186.757564 -18.5166)
		(end 185.501788 -18.5166)
		(width 0.089408)
		(layer "In2.Cu")
		(net "SMB_HOST_STBY_LVC3_SDA")
	)
	(segment
		(start 423.603166 -107.50169)
		(end 423.603166 -107.853734)
		(width 0.089408)
		(layer "In2.Cu")
		(net "SMB_HOST_STBY_LVC3_SDA")
	)
	(segment
		(start 173.736 -69.540882)
		(end 173.736 -70.47992)
		(width 0.089408)
		(layer "In2.Cu")
		(net "SMB_HOST_STBY_LVC3_SDA")
	)
	(segment
		(start 188.359796 -15.217394)
		(end 187.367418 -16.209772)
		(width 0.089408)
		(layer "In2.Cu")
		(net "SMB_HOST_STBY_LVC3_SDA")
	)
	(segment
		(start 426.431202 -64.848994)
		(end 423.556938 -67.723258)
		(width 0.089408)
		(layer "In2.Cu")
		(net "SMB_HOST_STBY_LVC3_SDA")
	)
	(segment
		(start 192.38722 -4.66598)
		(end 191.7954 -5.2578)
		(width 0.089408)
		(layer "In2.Cu")
		(net "SMB_HOST_STBY_LVC3_SDA")
	)
	(segment
		(start 191.6176 -7.42569)
		(end 191.6176 -11.575034)
		(width 0.089408)
		(layer "In2.Cu")
		(net "SMB_HOST_STBY_LVC3_SDA")
	)
	(segment
		(start 191.27978 0.19558)
		(end 191.27978 0.41402)
		(width 0.089408)
		(layer "In2.Cu")
		(net "SMB_HOST_STBY_LVC3_SDA")
	)
	(segment
		(start 472.233752 -62.217808)
		(end 469.649048 -62.217808)
		(width 0.089408)
		(layer "In2.Cu")
		(net "SMB_HOST_STBY_LVC3_SDA")
	)
	(segment
		(start 161.67608 -59.6519)
		(end 161.67608 -62.52972)
		(width 0.089408)
		(layer "In2.Cu")
		(net "SMB_HOST_STBY_LVC3_SDA")
	)
	(segment
		(start 477.476566 -59.840622)
		(end 477.476566 -60.604908)
		(width 0.089408)
		(layer "In2.Cu")
		(net "SMB_HOST_STBY_LVC3_SDA")
	)
	(segment
		(start 423.556938 -67.723258)
		(end 423.556938 -75.926442)
		(width 0.089408)
		(layer "In2.Cu")
		(net "SMB_HOST_STBY_LVC3_SDA")
	)
	(segment
		(start 191.47028 0.60452)
		(end 192.05194 0.60452)
		(width 0.089408)
		(layer "In2.Cu")
		(net "SMB_HOST_STBY_LVC3_SDA")
	)
	(segment
		(start 424.868848 -79.764128)
		(end 424.868848 -80.080612)
		(width 0.089408)
		(layer "In2.Cu")
		(net "SMB_HOST_STBY_LVC3_SDA")
	)
	(segment
		(start 183.8706 -38.6588)
		(end 183.8706 -44.055538)
		(width 0.089408)
		(layer "In2.Cu")
		(net "SMB_HOST_STBY_LVC3_SDA")
	)
	(segment
		(start 473.028772 -63.012828)
		(end 472.233752 -62.217808)
		(width 0.089408)
		(layer "In2.Cu")
		(net "SMB_HOST_STBY_LVC3_SDA")
	)
	(segment
		(start 165.65372 -61.62294)
		(end 173.0375 -61.62294)
		(width 0.089408)
		(layer "In2.Cu")
		(net "SMB_HOST_STBY_LVC3_SDA")
	)
	(segment
		(start 471.400886 -32.44342)
		(end 471.68308 -32.161226)
		(width 0.089408)
		(layer "In4.Cu")
		(net "SMB_HOST_STBY_LVC3_SDA")
	)
	(segment
		(start 464.789774 -32.724598)
		(end 469.568276 -32.724598)
		(width 0.089408)
		(layer "In4.Cu")
		(net "SMB_HOST_STBY_LVC3_SDA")
	)
	(segment
		(start 446.34785 -20.376134)
		(end 445.304926 -19.33321)
		(width 0.089408)
		(layer "In4.Cu")
		(net "SMB_HOST_STBY_LVC3_SDA")
	)
	(segment
		(start 462.647792 -130.645408)
		(end 462.647792 -136.447784)
		(width 0.089408)
		(layer "In4.Cu")
		(net "SMB_HOST_STBY_LVC3_SDA")
	)
	(segment
		(start 447.26098 -20.376134)
		(end 446.34785 -20.376134)
		(width 0.089408)
		(layer "In4.Cu")
		(net "SMB_HOST_STBY_LVC3_SDA")
	)
	(segment
		(start 409.49626 -23.717758)
		(end 409.492704 -23.717758)
		(width 0.089408)
		(layer "In4.Cu")
		(net "SMB_HOST_STBY_LVC3_SDA")
	)
	(segment
		(start 453.844152 -27.386788)
		(end 460.821532 -27.386788)
		(width 0.089408)
		(layer "In4.Cu")
		(net "SMB_HOST_STBY_LVC3_SDA")
	)
	(segment
		(start 408.281632 -24.626316)
		(end 407.845006 -24.626316)
		(width 0.089408)
		(layer "In4.Cu")
		(net "SMB_HOST_STBY_LVC3_SDA")
	)
	(segment
		(start 403.91715 -26.453338)
		(end 403.916896 -26.453592)
		(width 0.089408)
		(layer "In4.Cu")
		(net "SMB_HOST_STBY_LVC3_SDA")
	)
	(segment
		(start 462.830672 -29.395928)
		(end 462.830672 -30.765496)
		(width 0.089408)
		(layer "In4.Cu")
		(net "SMB_HOST_STBY_LVC3_SDA")
	)
	(segment
		(start 448.791838 -23.262082)
		(end 448.508628 -23.262082)
		(width 0.089408)
		(layer "In4.Cu")
		(net "SMB_HOST_STBY_LVC3_SDA")
	)
	(segment
		(start 425.768516 -23.739348)
		(end 424.754802 -23.739348)
		(width 0.089408)
		(layer "In4.Cu")
		(net "SMB_HOST_STBY_LVC3_SDA")
	)
	(segment
		(start 191.459104 0.324104)
		(end 193.129154 0.324104)
		(width 0.089408)
		(layer "In4.Cu")
		(net "SMB_HOST_STBY_LVC3_SDA")
	)
	(segment
		(start 421.42918 -23.051516)
		(end 414.07207 -23.051516)
		(width 0.089408)
		(layer "In4.Cu")
		(net "SMB_HOST_STBY_LVC3_SDA")
	)
	(segment
		(start 409.492704 -23.717758)
		(end 408.5844 -24.626062)
		(width 0.089408)
		(layer "In4.Cu")
		(net "SMB_HOST_STBY_LVC3_SDA")
	)
	(segment
		(start 449.423282 -23.274782)
		(end 449.732146 -23.274782)
		(width 0.089408)
		(layer "In4.Cu")
		(net "SMB_HOST_STBY_LVC3_SDA")
	)
	(segment
		(start 191.0334 -0.1016)
		(end 191.459104 0.324104)
		(width 0.089408)
		(layer "In4.Cu")
		(net "SMB_HOST_STBY_LVC3_SDA")
	)
	(segment
		(start 403.916896 -26.453592)
		(end 401.48129 -26.453592)
		(width 0.089408)
		(layer "In4.Cu")
		(net "SMB_HOST_STBY_LVC3_SDA")
	)
	(segment
		(start 441.07735 -19.33321)
		(end 439.90006 -20.5105)
		(width 0.089408)
		(layer "In4.Cu")
		(net "SMB_HOST_STBY_LVC3_SDA")
	)
	(segment
		(start 408.5844 -24.626062)
		(end 408.281886 -24.626062)
		(width 0.089408)
		(layer "In4.Cu")
		(net "SMB_HOST_STBY_LVC3_SDA")
	)
	(segment
		(start 448.508628 -23.262082)
		(end 448.131692 -22.885146)
		(width 0.089408)
		(layer "In4.Cu")
		(net "SMB_HOST_STBY_LVC3_SDA")
	)
	(segment
		(start 329.248262 -25.183592)
		(end 330.294234 -24.13762)
		(width 0.089408)
		(layer "In4.Cu")
		(net "SMB_HOST_STBY_LVC3_SDA")
	)
	(segment
		(start 463.6262 -146.762978)
		(end 461.818228 -148.57095)
		(width 0.089408)
		(layer "In4.Cu")
		(net "SMB_HOST_STBY_LVC3_SDA")
	)
	(segment
		(start 326.71893 -25.183592)
		(end 329.248262 -25.183592)
		(width 0.089408)
		(layer "In4.Cu")
		(net "SMB_HOST_STBY_LVC3_SDA")
	)
	(segment
		(start 460.821532 -27.386788)
		(end 462.830672 -29.395928)
		(width 0.089408)
		(layer "In4.Cu")
		(net "SMB_HOST_STBY_LVC3_SDA")
	)
	(segment
		(start 467.741 -121.024396)
		(end 467.741 -121.449338)
		(width 0.089408)
		(layer "In4.Cu")
		(net "SMB_HOST_STBY_LVC3_SDA")
	)
	(segment
		(start 255.572768 1.106424)
		(end 256.04597 1.579626)
		(width 0.089408)
		(layer "In4.Cu")
		(net "SMB_HOST_STBY_LVC3_SDA")
	)
	(segment
		(start 439.90006 -20.5105)
		(end 433.555902 -20.5105)
		(width 0.089408)
		(layer "In4.Cu")
		(net "SMB_HOST_STBY_LVC3_SDA")
	)
	(segment
		(start 332.172818 -24.13762)
		(end 332.481682 -23.828756)
		(width 0.089408)
		(layer "In4.Cu")
		(net "SMB_HOST_STBY_LVC3_SDA")
	)
	(segment
		(start 253.798832 0.042164)
		(end 254.863092 1.106424)
		(width 0.089408)
		(layer "In4.Cu")
		(net "SMB_HOST_STBY_LVC3_SDA")
	)
	(segment
		(start 468.0712 -127.508)
		(end 465.7852 -127.508)
		(width 0.089408)
		(layer "In4.Cu")
		(net "SMB_HOST_STBY_LVC3_SDA")
	)
	(segment
		(start 190.9826 -0.1016)
		(end 191.0334 -0.1016)
		(width 0.089408)
		(layer "In4.Cu")
		(net "SMB_HOST_STBY_LVC3_SDA")
	)
	(segment
		(start 259.452872 1.27889)
		(end 261.58571 1.27889)
		(width 0.089408)
		(layer "In4.Cu")
		(net "SMB_HOST_STBY_LVC3_SDA")
	)
	(segment
		(start 259.152136 1.579626)
		(end 259.452872 1.27889)
		(width 0.089408)
		(layer "In4.Cu")
		(net "SMB_HOST_STBY_LVC3_SDA")
	)
	(segment
		(start 323.796914 -1.60274)
		(end 323.796914 -22.261576)
		(width 0.089408)
		(layer "In4.Cu")
		(net "SMB_HOST_STBY_LVC3_SDA")
	)
	(segment
		(start 407.11882 -25.352502)
		(end 406.61717 -25.352502)
		(width 0.089408)
		(layer "In4.Cu")
		(net "SMB_HOST_STBY_LVC3_SDA")
	)
	(segment
		(start 264.040112 -0.204216)
		(end 264.269728 0.0254)
		(width 0.089408)
		(layer "In4.Cu")
		(net "SMB_HOST_STBY_LVC3_SDA")
	)
	(segment
		(start 468.159592 -124.268992)
		(end 468.7824 -124.8918)
		(width 0.089408)
		(layer "In4.Cu")
		(net "SMB_HOST_STBY_LVC3_SDA")
	)
	(segment
		(start 409.827476 -23.386542)
		(end 409.82392 -23.386542)
		(width 0.089408)
		(layer "In4.Cu")
		(net "SMB_HOST_STBY_LVC3_SDA")
	)
	(segment
		(start 406.566116 -25.403302)
		(end 405.51608 -26.453338)
		(width 0.089408)
		(layer "In4.Cu")
		(net "SMB_HOST_STBY_LVC3_SDA")
	)
	(segment
		(start 406.61717 -25.352502)
		(end 406.56637 -25.403302)
		(width 0.089408)
		(layer "In4.Cu")
		(net "SMB_HOST_STBY_LVC3_SDA")
	)
	(segment
		(start 256.04597 1.579626)
		(end 259.152136 1.579626)
		(width 0.089408)
		(layer "In4.Cu")
		(net "SMB_HOST_STBY_LVC3_SDA")
	)
	(segment
		(start 401.173696 -26.761186)
		(end 400.703542 -26.761186)
		(width 0.089408)
		(layer "In4.Cu")
		(net "SMB_HOST_STBY_LVC3_SDA")
	)
	(segment
		(start 426.943012 -23.347172)
		(end 426.160692 -23.347172)
		(width 0.089408)
		(layer "In4.Cu")
		(net "SMB_HOST_STBY_LVC3_SDA")
	)
	(segment
		(start 424.623738 -23.504398)
		(end 424.623992 -23.504144)
		(width 0.089408)
		(layer "In4.Cu")
		(net "SMB_HOST_STBY_LVC3_SDA")
	)
	(segment
		(start 413.749236 -23.37435)
		(end 409.839668 -23.37435)
		(width 0.089408)
		(layer "In4.Cu")
		(net "SMB_HOST_STBY_LVC3_SDA")
	)
	(segment
		(start 421.728392 -22.752304)
		(end 421.42918 -23.051516)
		(width 0.089408)
		(layer "In4.Cu")
		(net "SMB_HOST_STBY_LVC3_SDA")
	)
	(segment
		(start 461.818228 -148.57095)
		(end 461.486504 -148.57095)
		(width 0.089408)
		(layer "In4.Cu")
		(net "SMB_HOST_STBY_LVC3_SDA")
	)
	(segment
		(start 409.785312 -23.428706)
		(end 409.49626 -23.717758)
		(width 0.089408)
		(layer "In4.Cu")
		(net "SMB_HOST_STBY_LVC3_SDA")
	)
	(segment
		(start 330.294234 -24.13762)
		(end 332.172818 -24.13762)
		(width 0.089408)
		(layer "In4.Cu")
		(net "SMB_HOST_STBY_LVC3_SDA")
	)
	(segment
		(start 424.623992 -23.504144)
		(end 424.623992 -23.17877)
		(width 0.089408)
		(layer "In4.Cu")
		(net "SMB_HOST_STBY_LVC3_SDA")
	)
	(segment
		(start 462.830672 -30.765496)
		(end 464.789774 -32.724598)
		(width 0.089408)
		(layer "In4.Cu")
		(net "SMB_HOST_STBY_LVC3_SDA")
	)
	(segment
		(start 414.07207 -23.051516)
		(end 413.749236 -23.37435)
		(width 0.089408)
		(layer "In4.Cu")
		(net "SMB_HOST_STBY_LVC3_SDA")
	)
	(segment
		(start 469.849454 -32.44342)
		(end 471.400886 -32.44342)
		(width 0.089408)
		(layer "In4.Cu")
		(net "SMB_HOST_STBY_LVC3_SDA")
	)
	(segment
		(start 424.03903 -22.752304)
		(end 421.728392 -22.752304)
		(width 0.089408)
		(layer "In4.Cu")
		(net "SMB_HOST_STBY_LVC3_SDA")
	)
	(segment
		(start 322.168774 0.0254)
		(end 323.796914 -1.60274)
		(width 0.089408)
		(layer "In4.Cu")
		(net "SMB_HOST_STBY_LVC3_SDA")
	)
	(segment
		(start 193.411094 0.042164)
		(end 253.798832 0.042164)
		(width 0.089408)
		(layer "In4.Cu")
		(net "SMB_HOST_STBY_LVC3_SDA")
	)
	(segment
		(start 468.7824 -124.8918)
		(end 468.7824 -126.7968)
		(width 0.089408)
		(layer "In4.Cu")
		(net "SMB_HOST_STBY_LVC3_SDA")
	)
	(segment
		(start 424.039284 -22.75205)
		(end 424.03903 -22.752304)
		(width 0.089408)
		(layer "In4.Cu")
		(net "SMB_HOST_STBY_LVC3_SDA")
	)
	(segment
		(start 407.845006 -24.626316)
		(end 407.11882 -25.352502)
		(width 0.089408)
		(layer "In4.Cu")
		(net "SMB_HOST_STBY_LVC3_SDA")
	)
	(segment
		(start 261.58571 1.27889)
		(end 263.068816 -0.204216)
		(width 0.089408)
		(layer "In4.Cu")
		(net "SMB_HOST_STBY_LVC3_SDA")
	)
	(segment
		(start 424.623738 -23.608284)
		(end 424.623738 -23.504398)
		(width 0.089408)
		(layer "In4.Cu")
		(net "SMB_HOST_STBY_LVC3_SDA")
	)
	(segment
		(start 426.160692 -23.347172)
		(end 425.768516 -23.739348)
		(width 0.089408)
		(layer "In4.Cu")
		(net "SMB_HOST_STBY_LVC3_SDA")
	)
	(segment
		(start 468.7824 -126.7968)
		(end 468.0712 -127.508)
		(width 0.089408)
		(layer "In4.Cu")
		(net "SMB_HOST_STBY_LVC3_SDA")
	)
	(segment
		(start 448.131692 -22.885146)
		(end 448.131692 -21.246846)
		(width 0.089408)
		(layer "In4.Cu")
		(net "SMB_HOST_STBY_LVC3_SDA")
	)
	(segment
		(start 463.6262 -137.426192)
		(end 463.6262 -146.762978)
		(width 0.089408)
		(layer "In4.Cu")
		(net "SMB_HOST_STBY_LVC3_SDA")
	)
	(segment
		(start 427.41596 -22.874224)
		(end 426.943012 -23.347172)
		(width 0.089408)
		(layer "In4.Cu")
		(net "SMB_HOST_STBY_LVC3_SDA")
	)
	(segment
		(start 424.754802 -23.739348)
		(end 424.623738 -23.608284)
		(width 0.089408)
		(layer "In4.Cu")
		(net "SMB_HOST_STBY_LVC3_SDA")
	)
	(segment
		(start 263.068816 -0.204216)
		(end 264.040112 -0.204216)
		(width 0.089408)
		(layer "In4.Cu")
		(net "SMB_HOST_STBY_LVC3_SDA")
	)
	(segment
		(start 401.48129 -26.453592)
		(end 401.173696 -26.761186)
		(width 0.089408)
		(layer "In4.Cu")
		(net "SMB_HOST_STBY_LVC3_SDA")
	)
	(segment
		(start 424.197272 -22.75205)
		(end 424.039284 -22.75205)
		(width 0.089408)
		(layer "In4.Cu")
		(net "SMB_HOST_STBY_LVC3_SDA")
	)
	(segment
		(start 409.839668 -23.37435)
		(end 409.827476 -23.386542)
		(width 0.089408)
		(layer "In4.Cu")
		(net "SMB_HOST_STBY_LVC3_SDA")
	)
	(segment
		(start 461.486504 -148.57095)
		(end 461.277208 -148.361654)
		(width 0.089408)
		(layer "In4.Cu")
		(net "SMB_HOST_STBY_LVC3_SDA")
	)
	(segment
		(start 467.741 -121.449338)
		(end 468.159592 -121.86793)
		(width 0.089408)
		(layer "In4.Cu")
		(net "SMB_HOST_STBY_LVC3_SDA")
	)
	(segment
		(start 409.82392 -23.386542)
		(end 409.785312 -23.42515)
		(width 0.089408)
		(layer "In4.Cu")
		(net "SMB_HOST_STBY_LVC3_SDA")
	)
	(segment
		(start 449.732146 -23.274782)
		(end 453.844152 -27.386788)
		(width 0.089408)
		(layer "In4.Cu")
		(net "SMB_HOST_STBY_LVC3_SDA")
	)
	(segment
		(start 409.785312 -23.42515)
		(end 409.785312 -23.428706)
		(width 0.089408)
		(layer "In4.Cu")
		(net "SMB_HOST_STBY_LVC3_SDA")
	)
	(segment
		(start 264.269728 0.0254)
		(end 322.168774 0.0254)
		(width 0.089408)
		(layer "In4.Cu")
		(net "SMB_HOST_STBY_LVC3_SDA")
	)
	(segment
		(start 254.863092 1.106424)
		(end 255.572768 1.106424)
		(width 0.089408)
		(layer "In4.Cu")
		(net "SMB_HOST_STBY_LVC3_SDA")
	)
	(segment
		(start 468.159592 -121.86793)
		(end 468.159592 -124.268992)
		(width 0.089408)
		(layer "In4.Cu")
		(net "SMB_HOST_STBY_LVC3_SDA")
	)
	(segment
		(start 405.51608 -26.453338)
		(end 403.91715 -26.453338)
		(width 0.089408)
		(layer "In4.Cu")
		(net "SMB_HOST_STBY_LVC3_SDA")
	)
	(segment
		(start 467.5505 -120.833896)
		(end 467.741 -121.024396)
		(width 0.089408)
		(layer "In4.Cu")
		(net "SMB_HOST_STBY_LVC3_SDA")
	)
	(segment
		(start 448.8815 -22.733)
		(end 448.8815 -23.17242)
		(width 0.089408)
		(layer "In4.Cu")
		(net "SMB_HOST_STBY_LVC3_SDA")
	)
	(segment
		(start 465.7852 -127.508)
		(end 462.647792 -130.645408)
		(width 0.089408)
		(layer "In4.Cu")
		(net "SMB_HOST_STBY_LVC3_SDA")
	)
	(segment
		(start 193.129154 0.324104)
		(end 193.411094 0.042164)
		(width 0.089408)
		(layer "In4.Cu")
		(net "SMB_HOST_STBY_LVC3_SDA")
	)
	(segment
		(start 445.304926 -19.33321)
		(end 441.07735 -19.33321)
		(width 0.089408)
		(layer "In4.Cu")
		(net "SMB_HOST_STBY_LVC3_SDA")
	)
	(segment
		(start 323.796914 -22.261576)
		(end 326.71893 -25.183592)
		(width 0.089408)
		(layer "In4.Cu")
		(net "SMB_HOST_STBY_LVC3_SDA")
	)
	(segment
		(start 448.131692 -21.246846)
		(end 447.26098 -20.376134)
		(width 0.089408)
		(layer "In4.Cu")
		(net "SMB_HOST_STBY_LVC3_SDA")
	)
	(segment
		(start 431.192178 -22.874224)
		(end 427.41596 -22.874224)
		(width 0.089408)
		(layer "In4.Cu")
		(net "SMB_HOST_STBY_LVC3_SDA")
	)
	(segment
		(start 448.8815 -23.17242)
		(end 448.791838 -23.262082)
		(width 0.089408)
		(layer "In4.Cu")
		(net "SMB_HOST_STBY_LVC3_SDA")
	)
	(segment
		(start 424.623992 -23.17877)
		(end 424.197272 -22.75205)
		(width 0.089408)
		(layer "In4.Cu")
		(net "SMB_HOST_STBY_LVC3_SDA")
	)
	(segment
		(start 448.8815 -22.733)
		(end 449.423282 -23.274782)
		(width 0.089408)
		(layer "In4.Cu")
		(net "SMB_HOST_STBY_LVC3_SDA")
	)
	(segment
		(start 406.56637 -25.403302)
		(end 406.566116 -25.403302)
		(width 0.089408)
		(layer "In4.Cu")
		(net "SMB_HOST_STBY_LVC3_SDA")
	)
	(segment
		(start 433.555902 -20.5105)
		(end 431.192178 -22.874224)
		(width 0.089408)
		(layer "In4.Cu")
		(net "SMB_HOST_STBY_LVC3_SDA")
	)
	(segment
		(start 469.568276 -32.724598)
		(end 469.849454 -32.44342)
		(width 0.089408)
		(layer "In4.Cu")
		(net "SMB_HOST_STBY_LVC3_SDA")
	)
	(segment
		(start 408.281886 -24.626062)
		(end 408.281632 -24.626316)
		(width 0.089408)
		(layer "In4.Cu")
		(net "SMB_HOST_STBY_LVC3_SDA")
	)
	(segment
		(start 462.647792 -136.447784)
		(end 463.6262 -137.426192)
		(width 0.089408)
		(layer "In4.Cu")
		(net "SMB_HOST_STBY_LVC3_SDA")
	)
	(segment
		(start 400.703542 -26.761186)
		(end 400.457924 -26.515568)
		(width 0.089408)
		(layer "In4.Cu")
		(net "SMB_HOST_STBY_LVC3_SDA")
	)
	(segment
		(start 423.905172 -108.13542)
		(end 424.233594 -108.13542)
		(width 0.089408)
		(layer "In9.Cu")
		(net "SMB_HOST_STBY_LVC3_SDA")
	)
	(segment
		(start 467.5505 -120.839992)
		(end 467.5505 -120.833896)
		(width 0.089408)
		(layer "In9.Cu")
		(net "SMB_HOST_STBY_LVC3_SDA")
	)
	(segment
		(start 467.074758 -120.9294)
		(end 467.461092 -120.9294)
		(width 0.089408)
		(layer "In9.Cu")
		(net "SMB_HOST_STBY_LVC3_SDA")
	)
	(segment
		(start 474.396562 -39.5478)
		(end 474.027754 -39.178992)
		(width 0.089408)
		(layer "In9.Cu")
		(net "SMB_HOST_STBY_LVC3_SDA")
	)
	(segment
		(start 473.452698 -32.81553)
		(end 473.084144 -32.446976)
		(width 0.089408)
		(layer "In9.Cu")
		(net "SMB_HOST_STBY_LVC3_SDA")
	)
	(segment
		(start 423.623486 -107.853734)
		(end 423.905172 -108.13542)
		(width 0.089408)
		(layer "In9.Cu")
		(net "SMB_HOST_STBY_LVC3_SDA")
	)
	(segment
		(start 471.96883 -32.446976)
		(end 471.68308 -32.161226)
		(width 0.089408)
		(layer "In9.Cu")
		(net "SMB_HOST_STBY_LVC3_SDA")
	)
	(segment
		(start 400.213068 -28.702)
		(end 400.786092 -29.275024)
		(width 0.089408)
		(layer "In9.Cu")
		(net "SMB_HOST_STBY_LVC3_SDA")
	)
	(segment
		(start 474.027754 -35.192716)
		(end 473.452698 -34.61766)
		(width 0.089408)
		(layer "In9.Cu")
		(net "SMB_HOST_STBY_LVC3_SDA")
	)
	(segment
		(start 465.638896 -149.166834)
		(end 465.447888 -148.975826)
		(width 0.089408)
		(layer "In9.Cu")
		(net "SMB_HOST_STBY_LVC3_SDA")
	)
	(segment
		(start 478.516696 -58.159904)
		(end 474.2688 -53.912008)
		(width 0.089408)
		(layer "In9.Cu")
		(net "SMB_HOST_STBY_LVC3_SDA")
	)
	(segment
		(start 461.790542 -147.84832)
		(end 461.277208 -148.361654)
		(width 0.089408)
		(layer "In9.Cu")
		(net "SMB_HOST_STBY_LVC3_SDA")
	)
	(segment
		(start 474.2688 -53.912008)
		(end 474.2688 -52.604416)
		(width 0.089408)
		(layer "In9.Cu")
		(net "SMB_HOST_STBY_LVC3_SDA")
	)
	(segment
		(start 475.720664 -51.152552)
		(end 475.720664 -44.493688)
		(width 0.089408)
		(layer "In9.Cu")
		(net "SMB_HOST_STBY_LVC3_SDA")
	)
	(segment
		(start 474.027754 -39.178992)
		(end 474.027754 -35.192716)
		(width 0.089408)
		(layer "In9.Cu")
		(net "SMB_HOST_STBY_LVC3_SDA")
	)
	(segment
		(start 465.447888 -148.590508)
		(end 464.7057 -147.84832)
		(width 0.089408)
		(layer "In9.Cu")
		(net "SMB_HOST_STBY_LVC3_SDA")
	)
	(segment
		(start 465.638896 -150.645622)
		(end 465.638896 -149.166834)
		(width 0.089408)
		(layer "In9.Cu")
		(net "SMB_HOST_STBY_LVC3_SDA")
	)
	(segment
		(start 478.0788 -59.5376)
		(end 478.516696 -59.099704)
		(width 0.089408)
		(layer "In9.Cu")
		(net "SMB_HOST_STBY_LVC3_SDA")
	)
	(segment
		(start 475.67088 -39.5478)
		(end 474.396562 -39.5478)
		(width 0.089408)
		(layer "In9.Cu")
		(net "SMB_HOST_STBY_LVC3_SDA")
	)
	(segment
		(start 463.274156 -117.136418)
		(end 463.281776 -117.136418)
		(width 0.089408)
		(layer "In9.Cu")
		(net "SMB_HOST_STBY_LVC3_SDA")
	)
	(segment
		(start 478.516696 -59.099704)
		(end 478.516696 -58.159904)
		(width 0.089408)
		(layer "In9.Cu")
		(net "SMB_HOST_STBY_LVC3_SDA")
	)
	(segment
		(start 474.2688 -52.604416)
		(end 475.720664 -51.152552)
		(width 0.089408)
		(layer "In9.Cu")
		(net "SMB_HOST_STBY_LVC3_SDA")
	)
	(segment
		(start 425.056808 -108.958634)
		(end 425.056808 -109.47654)
		(width 0.089408)
		(layer "In9.Cu")
		(net "SMB_HOST_STBY_LVC3_SDA")
	)
	(segment
		(start 424.233594 -108.13542)
		(end 425.056808 -108.958634)
		(width 0.089408)
		(layer "In9.Cu")
		(net "SMB_HOST_STBY_LVC3_SDA")
	)
	(segment
		(start 400.457924 -26.515568)
		(end 400.213068 -26.760424)
		(width 0.089408)
		(layer "In9.Cu")
		(net "SMB_HOST_STBY_LVC3_SDA")
	)
	(segment
		(start 423.603166 -107.853734)
		(end 423.623486 -107.853734)
		(width 0.089408)
		(layer "In9.Cu")
		(net "SMB_HOST_STBY_LVC3_SDA")
	)
	(segment
		(start 400.786092 -32.527494)
		(end 400.924014 -32.665416)
		(width 0.089408)
		(layer "In9.Cu")
		(net "SMB_HOST_STBY_LVC3_SDA")
	)
	(segment
		(start 480.335844 -150.39467)
		(end 480.080574 -150.64994)
		(width 0.089408)
		(layer "In9.Cu")
		(net "SMB_HOST_STBY_LVC3_SDA")
	)
	(segment
		(start 467.461092 -120.9294)
		(end 467.5505 -120.839992)
		(width 0.089408)
		(layer "In9.Cu")
		(net "SMB_HOST_STBY_LVC3_SDA")
	)
	(segment
		(start 400.924014 -32.665416)
		(end 401.14474 -32.665416)
		(width 0.089408)
		(layer "In9.Cu")
		(net "SMB_HOST_STBY_LVC3_SDA")
	)
	(segment
		(start 468.214456 -150.64994)
		(end 467.271862 -151.592534)
		(width 0.089408)
		(layer "In9.Cu")
		(net "SMB_HOST_STBY_LVC3_SDA")
	)
	(segment
		(start 425.056808 -109.47654)
		(end 427.752256 -112.171988)
		(width 0.089408)
		(layer "In9.Cu")
		(net "SMB_HOST_STBY_LVC3_SDA")
	)
	(segment
		(start 400.213068 -26.760424)
		(end 400.213068 -28.702)
		(width 0.089408)
		(layer "In9.Cu")
		(net "SMB_HOST_STBY_LVC3_SDA")
	)
	(segment
		(start 467.271862 -151.592534)
		(end 466.585808 -151.592534)
		(width 0.089408)
		(layer "In9.Cu")
		(net "SMB_HOST_STBY_LVC3_SDA")
	)
	(segment
		(start 437.405272 -116.293646)
		(end 462.431384 -116.293646)
		(width 0.089408)
		(layer "In9.Cu")
		(net "SMB_HOST_STBY_LVC3_SDA")
	)
	(segment
		(start 476.264224 -43.950128)
		(end 476.264224 -40.141144)
		(width 0.089408)
		(layer "In9.Cu")
		(net "SMB_HOST_STBY_LVC3_SDA")
	)
	(segment
		(start 473.084144 -32.446976)
		(end 471.96883 -32.446976)
		(width 0.089408)
		(layer "In9.Cu")
		(net "SMB_HOST_STBY_LVC3_SDA")
	)
	(segment
		(start 476.264224 -40.141144)
		(end 475.67088 -39.5478)
		(width 0.089408)
		(layer "In9.Cu")
		(net "SMB_HOST_STBY_LVC3_SDA")
	)
	(segment
		(start 400.786092 -29.275024)
		(end 400.786092 -32.527494)
		(width 0.089408)
		(layer "In9.Cu")
		(net "SMB_HOST_STBY_LVC3_SDA")
	)
	(segment
		(start 466.585808 -151.592534)
		(end 465.638896 -150.645622)
		(width 0.089408)
		(layer "In9.Cu")
		(net "SMB_HOST_STBY_LVC3_SDA")
	)
	(segment
		(start 480.080574 -150.64994)
		(end 468.214456 -150.64994)
		(width 0.089408)
		(layer "In9.Cu")
		(net "SMB_HOST_STBY_LVC3_SDA")
	)
	(segment
		(start 463.281776 -117.136418)
		(end 467.074758 -120.9294)
		(width 0.089408)
		(layer "In9.Cu")
		(net "SMB_HOST_STBY_LVC3_SDA")
	)
	(segment
		(start 475.720664 -44.493688)
		(end 476.264224 -43.950128)
		(width 0.089408)
		(layer "In9.Cu")
		(net "SMB_HOST_STBY_LVC3_SDA")
	)
	(segment
		(start 465.447888 -148.975826)
		(end 465.447888 -148.590508)
		(width 0.089408)
		(layer "In9.Cu")
		(net "SMB_HOST_STBY_LVC3_SDA")
	)
	(segment
		(start 462.431384 -116.293646)
		(end 463.274156 -117.136418)
		(width 0.089408)
		(layer "In9.Cu")
		(net "SMB_HOST_STBY_LVC3_SDA")
	)
	(segment
		(start 433.283614 -112.171988)
		(end 437.405272 -116.293646)
		(width 0.089408)
		(layer "In9.Cu")
		(net "SMB_HOST_STBY_LVC3_SDA")
	)
	(segment
		(start 473.452698 -34.61766)
		(end 473.452698 -32.81553)
		(width 0.089408)
		(layer "In9.Cu")
		(net "SMB_HOST_STBY_LVC3_SDA")
	)
	(segment
		(start 427.752256 -112.171988)
		(end 433.283614 -112.171988)
		(width 0.089408)
		(layer "In9.Cu")
		(net "SMB_HOST_STBY_LVC3_SDA")
	)
	(segment
		(start 464.7057 -147.84832)
		(end 461.790542 -147.84832)
		(width 0.089408)
		(layer "In9.Cu")
		(net "SMB_HOST_STBY_LVC3_SDA")
	)
	(segment
		(start 401.014692 -26.458926)
		(end 399.87601 -25.320244)
		(width 0.089408)
		(layer "In11.Cu")
		(net "SMB_HOST_STBY_LVC3_SDA")
	)
	(segment
		(start 391.396474 -8.697976)
		(end 394.095732 -8.697976)
		(width 0.089408)
		(layer "In11.Cu")
		(net "SMB_HOST_STBY_LVC3_SDA")
	)
	(segment
		(start 338.061046 -35.363912)
		(end 355.235256 -35.363912)
		(width 0.089408)
		(layer "In11.Cu")
		(net "SMB_HOST_STBY_LVC3_SDA")
	)
	(segment
		(start 378.319284 -7.250684)
		(end 380.213362 -9.144762)
		(width 0.089408)
		(layer "In11.Cu")
		(net "SMB_HOST_STBY_LVC3_SDA")
	)
	(segment
		(start 390.949688 -9.144762)
		(end 391.396474 -8.697976)
		(width 0.089408)
		(layer "In11.Cu")
		(net "SMB_HOST_STBY_LVC3_SDA")
	)
	(segment
		(start 401.32 -32.490156)
		(end 401.32 -30.213046)
		(width 0.089408)
		(layer "In11.Cu")
		(net "SMB_HOST_STBY_LVC3_SDA")
	)
	(segment
		(start 395.699488 -7.09422)
		(end 403.628606 -7.09422)
		(width 0.089408)
		(layer "In11.Cu")
		(net "SMB_HOST_STBY_LVC3_SDA")
	)
	(segment
		(start 401.270978 -19.653758)
		(end 401.270978 -19.263614)
		(width 0.089408)
		(layer "In11.Cu")
		(net "SMB_HOST_STBY_LVC3_SDA")
	)
	(segment
		(start 399.87601 -24.094186)
		(end 400.764756 -23.20544)
		(width 0.089408)
		(layer "In11.Cu")
		(net "SMB_HOST_STBY_LVC3_SDA")
	)
	(segment
		(start 401.14474 -32.665416)
		(end 401.32 -32.490156)
		(width 0.089408)
		(layer "In11.Cu")
		(net "SMB_HOST_STBY_LVC3_SDA")
	)
	(segment
		(start 372.875302 -7.250684)
		(end 378.319284 -7.250684)
		(width 0.089408)
		(layer "In11.Cu")
		(net "SMB_HOST_STBY_LVC3_SDA")
	)
	(segment
		(start 371.491002 -8.634984)
		(end 372.875302 -7.250684)
		(width 0.089408)
		(layer "In11.Cu")
		(net "SMB_HOST_STBY_LVC3_SDA")
	)
	(segment
		(start 400.764756 -23.20544)
		(end 400.764756 -20.15998)
		(width 0.089408)
		(layer "In11.Cu")
		(net "SMB_HOST_STBY_LVC3_SDA")
	)
	(segment
		(start 333.03083 -24.553164)
		(end 333.03083 -31.412434)
		(width 0.089408)
		(layer "In11.Cu")
		(net "SMB_HOST_STBY_LVC3_SDA")
	)
	(segment
		(start 355.235256 -35.363912)
		(end 362.982764 -27.616404)
		(width 0.089408)
		(layer "In11.Cu")
		(net "SMB_HOST_STBY_LVC3_SDA")
	)
	(segment
		(start 362.982764 -18.284698)
		(end 371.491002 -9.77646)
		(width 0.089408)
		(layer "In11.Cu")
		(net "SMB_HOST_STBY_LVC3_SDA")
	)
	(segment
		(start 371.491002 -9.77646)
		(end 371.491002 -8.634984)
		(width 0.089408)
		(layer "In11.Cu")
		(net "SMB_HOST_STBY_LVC3_SDA")
	)
	(segment
		(start 400.177508 -27.436318)
		(end 401.014692 -26.599134)
		(width 0.089408)
		(layer "In11.Cu")
		(net "SMB_HOST_STBY_LVC3_SDA")
	)
	(segment
		(start 337.729068 -35.031934)
		(end 338.061046 -35.363912)
		(width 0.089408)
		(layer "In11.Cu")
		(net "SMB_HOST_STBY_LVC3_SDA")
	)
	(segment
		(start 333.03083 -31.412434)
		(end 336.65033 -35.031934)
		(width 0.089408)
		(layer "In11.Cu")
		(net "SMB_HOST_STBY_LVC3_SDA")
	)
	(segment
		(start 400.764756 -20.15998)
		(end 401.270978 -19.653758)
		(width 0.089408)
		(layer "In11.Cu")
		(net "SMB_HOST_STBY_LVC3_SDA")
	)
	(segment
		(start 403.628606 -7.09422)
		(end 404.024592 -6.698234)
		(width 0.089408)
		(layer "In11.Cu")
		(net "SMB_HOST_STBY_LVC3_SDA")
	)
	(segment
		(start 399.87601 -25.320244)
		(end 399.87601 -24.094186)
		(width 0.089408)
		(layer "In11.Cu")
		(net "SMB_HOST_STBY_LVC3_SDA")
	)
	(segment
		(start 404.024592 -6.698234)
		(end 404.024592 -6.490462)
		(width 0.089408)
		(layer "In11.Cu")
		(net "SMB_HOST_STBY_LVC3_SDA")
	)
	(segment
		(start 380.213362 -9.144762)
		(end 390.949688 -9.144762)
		(width 0.089408)
		(layer "In11.Cu")
		(net "SMB_HOST_STBY_LVC3_SDA")
	)
	(segment
		(start 401.014692 -26.599134)
		(end 401.014692 -26.458926)
		(width 0.089408)
		(layer "In11.Cu")
		(net "SMB_HOST_STBY_LVC3_SDA")
	)
	(segment
		(start 400.177508 -29.070554)
		(end 400.177508 -27.436318)
		(width 0.089408)
		(layer "In11.Cu")
		(net "SMB_HOST_STBY_LVC3_SDA")
	)
	(segment
		(start 336.65033 -35.031934)
		(end 337.729068 -35.031934)
		(width 0.089408)
		(layer "In11.Cu")
		(net "SMB_HOST_STBY_LVC3_SDA")
	)
	(segment
		(start 332.481682 -23.828756)
		(end 332.481682 -24.004016)
		(width 0.089408)
		(layer "In11.Cu")
		(net "SMB_HOST_STBY_LVC3_SDA")
	)
	(segment
		(start 401.32 -30.213046)
		(end 400.177508 -29.070554)
		(width 0.089408)
		(layer "In11.Cu")
		(net "SMB_HOST_STBY_LVC3_SDA")
	)
	(segment
		(start 332.481682 -24.004016)
		(end 333.03083 -24.553164)
		(width 0.089408)
		(layer "In11.Cu")
		(net "SMB_HOST_STBY_LVC3_SDA")
	)
	(segment
		(start 394.095732 -8.697976)
		(end 395.699488 -7.09422)
		(width 0.089408)
		(layer "In11.Cu")
		(net "SMB_HOST_STBY_LVC3_SDA")
	)
	(segment
		(start 362.982764 -27.616404)
		(end 362.982764 -18.284698)
		(width 0.089408)
		(layer "In11.Cu")
		(net "SMB_HOST_STBY_LVC3_SDA")
	)
	(segment
		(start 404.024592 -6.490462)
		(end 403.764242 -6.230112)
		(width 0.089408)
		(layer "In11.Cu")
		(net "SMB_HOST_STBY_LVC3_SDA")
	)
	(segment
		(start 401.77974 -33.664652)
		(end 401.41271 -33.664652)
		(width 0.10795)
		(layer "F.Cu")
		(net "SMB_HOST_STBY_LVC3_SCL")
	)
	(segment
		(start 172.280072 -72.539352)
		(end 172.723048 -72.539352)
		(width 0.10795)
		(layer "F.Cu")
		(net "SMB_HOST_STBY_LVC3_SCL")
	)
	(segment
		(start 471.68308 -32.923226)
		(end 472.1352 -32.471106)
		(width 0.10795)
		(layer "F.Cu")
		(net "SMB_HOST_STBY_LVC3_SCL")
	)
	(segment
		(start 401.41271 -33.664652)
		(end 401.140168 -33.39211)
		(width 0.10795)
		(layer "F.Cu")
		(net "SMB_HOST_STBY_LVC3_SCL")
	)
	(segment
		(start 172.723048 -72.539352)
		(end 173.60646 -71.65594)
		(width 0.10795)
		(layer "F.Cu")
		(net "SMB_HOST_STBY_LVC3_SCL")
	)
	(segment
		(start 423.42435 -108.46435)
		(end 423.623486 -108.663486)
		(width 0.10795)
		(layer "F.Cu")
		(net "SMB_HOST_STBY_LVC3_SCL")
	)
	(segment
		(start 417.921948 -107.08005)
		(end 419.617398 -108.7755)
		(width 0.10795)
		(layer "F.Cu")
		(net "SMB_HOST_STBY_LVC3_SCL")
	)
	(segment
		(start 401.140168 -33.300416)
		(end 401.13966 -33.300416)
		(width 0.10795)
		(layer "F.Cu")
		(net "SMB_HOST_STBY_LVC3_SCL")
	)
	(segment
		(start 472.1352 -32.471106)
		(end 472.1352 -31.46806)
		(width 0.10795)
		(layer "F.Cu")
		(net "SMB_HOST_STBY_LVC3_SCL")
	)
	(segment
		(start 401.140168 -33.39211)
		(end 401.140168 -33.300416)
		(width 0.10795)
		(layer "F.Cu")
		(net "SMB_HOST_STBY_LVC3_SCL")
	)
	(segment
		(start 472.1352 -31.46806)
		(end 472.313 -31.29026)
		(width 0.10795)
		(layer "F.Cu")
		(net "SMB_HOST_STBY_LVC3_SCL")
	)
	(segment
		(start 464.133692 -148.719794)
		(end 462.980278 -148.719794)
		(width 0.10795)
		(layer "F.Cu")
		(net "SMB_HOST_STBY_LVC3_SCL")
	)
	(segment
		(start 422.783 -108.7755)
		(end 423.09415 -108.46435)
		(width 0.10795)
		(layer "F.Cu")
		(net "SMB_HOST_STBY_LVC3_SCL")
	)
	(segment
		(start 464.444588 -148.408898)
		(end 464.133692 -148.719794)
		(width 0.10795)
		(layer "F.Cu")
		(net "SMB_HOST_STBY_LVC3_SCL")
	)
	(segment
		(start 423.09415 -108.46435)
		(end 423.42435 -108.46435)
		(width 0.10795)
		(layer "F.Cu")
		(net "SMB_HOST_STBY_LVC3_SCL")
	)
	(segment
		(start 464.610704 -148.408898)
		(end 464.444588 -148.408898)
		(width 0.10795)
		(layer "F.Cu")
		(net "SMB_HOST_STBY_LVC3_SCL")
	)
	(segment
		(start 419.617398 -108.7755)
		(end 422.783 -108.7755)
		(width 0.10795)
		(layer "F.Cu")
		(net "SMB_HOST_STBY_LVC3_SCL")
	)
	(segment
		(start 411.761686 -107.08005)
		(end 417.921948 -107.08005)
		(width 0.10795)
		(layer "F.Cu")
		(net "SMB_HOST_STBY_LVC3_SCL")
	)
	(segment
		(start 472.313 -31.29026)
		(end 472.313 -30.607)
		(width 0.10795)
		(layer "F.Cu")
		(net "SMB_HOST_STBY_LVC3_SCL")
	)
	(segment
		(start 411.695138 -107.146598)
		(end 411.761686 -107.08005)
		(width 0.10795)
		(layer "F.Cu")
		(net "SMB_HOST_STBY_LVC3_SCL")
	)
	(via
		(at 464.610704 -148.408898)
		(size 0.508)
		(drill 0.254)
		(layers "F.Cu" "B.Cu")
		(net "SMB_HOST_STBY_LVC3_SCL")
	)
	(via
		(at 471.68308 -32.923226)
		(size 0.508)
		(drill 0.254)
		(layers "F.Cu" "B.Cu")
		(net "SMB_HOST_STBY_LVC3_SCL")
	)
	(via
		(at 332.478888 -24.572468)
		(size 0.508)
		(drill 0.254)
		(layers "F.Cu" "B.Cu")
		(net "SMB_HOST_STBY_LVC3_SCL")
	)
	(via
		(at 191.6684 -0.0762)
		(size 0.508)
		(drill 0.254)
		(layers "F.Cu" "B.Cu")
		(net "SMB_HOST_STBY_LVC3_SCL")
	)
	(via
		(at 448.8815 -24.003)
		(size 0.508)
		(drill 0.254)
		(layers "F.Cu" "B.Cu")
		(net "SMB_HOST_STBY_LVC3_SCL")
	)
	(via
		(at 401.931378 -19.263614)
		(size 0.508)
		(drill 0.254)
		(layers "F.Cu" "B.Cu")
		(net "SMB_HOST_STBY_LVC3_SCL")
	)
	(via
		(at 401.13966 -33.300416)
		(size 0.508)
		(drill 0.254)
		(layers "F.Cu" "B.Cu")
		(net "SMB_HOST_STBY_LVC3_SCL")
	)
	(via
		(at 468.3125 -120.833896)
		(size 0.508)
		(drill 0.254)
		(layers "F.Cu" "B.Cu")
		(net "SMB_HOST_STBY_LVC3_SCL")
	)
	(via
		(at 399.580862 -26.345134)
		(size 0.508)
		(drill 0.254)
		(layers "F.Cu" "B.Cu")
		(net "SMB_HOST_STBY_LVC3_SCL")
	)
	(via
		(at 173.60646 -71.65594)
		(size 0.508)
		(drill 0.254)
		(layers "F.Cu" "B.Cu")
		(net "SMB_HOST_STBY_LVC3_SCL")
	)
	(via
		(at 403.934422 -13.192252)
		(size 0.508)
		(drill 0.254)
		(layers "F.Cu" "B.Cu")
		(net "SMB_HOST_STBY_LVC3_SCL")
	)
	(via
		(at 423.623486 -108.663486)
		(size 0.508)
		(drill 0.254)
		(layers "F.Cu" "B.Cu")
		(net "SMB_HOST_STBY_LVC3_SCL")
	)
	(via
		(at 404.578566 -6.21284)
		(size 0.508)
		(drill 0.254)
		(layers "F.Cu" "B.Cu")
		(net "SMB_HOST_STBY_LVC3_SCL")
	)
	(via
		(at 478.11563 -58.886598)
		(size 0.508)
		(drill 0.254)
		(layers "F.Cu" "B.Cu")
		(net "SMB_HOST_STBY_LVC3_SCL")
	)
	(segment
		(start 403.934422 -11.338814)
		(end 403.934422 -13.192252)
		(width 0.10795)
		(layer "B.Cu")
		(net "SMB_HOST_STBY_LVC3_SCL")
	)
	(segment
		(start 403.934422 -15.892018)
		(end 403.934422 -13.192252)
		(width 0.10795)
		(layer "B.Cu")
		(net "SMB_HOST_STBY_LVC3_SCL")
	)
	(segment
		(start 401.739608 -18.086832)
		(end 403.934422 -15.892018)
		(width 0.10795)
		(layer "B.Cu")
		(net "SMB_HOST_STBY_LVC3_SCL")
	)
	(segment
		(start 401.739608 -19.071844)
		(end 401.739608 -18.086832)
		(width 0.10795)
		(layer "B.Cu")
		(net "SMB_HOST_STBY_LVC3_SCL")
	)
	(segment
		(start 404.268178 -6.523228)
		(end 404.268178 -8.329168)
		(width 0.10795)
		(layer "B.Cu")
		(net "SMB_HOST_STBY_LVC3_SCL")
	)
	(segment
		(start 449.6435 -24.003)
		(end 448.8815 -24.003)
		(width 0.10795)
		(layer "B.Cu")
		(net "SMB_HOST_STBY_LVC3_SCL")
	)
	(segment
		(start 405.251158 -9.312148)
		(end 405.251158 -10.022078)
		(width 0.10795)
		(layer "B.Cu")
		(net "SMB_HOST_STBY_LVC3_SCL")
	)
	(segment
		(start 447.51752 -24.003)
		(end 447.157094 -23.642574)
		(width 0.10795)
		(layer "B.Cu")
		(net "SMB_HOST_STBY_LVC3_SCL")
	)
	(segment
		(start 448.8815 -24.003)
		(end 447.51752 -24.003)
		(width 0.10795)
		(layer "B.Cu")
		(net "SMB_HOST_STBY_LVC3_SCL")
	)
	(segment
		(start 404.578566 -6.21284)
		(end 404.268178 -6.523228)
		(width 0.10795)
		(layer "B.Cu")
		(net "SMB_HOST_STBY_LVC3_SCL")
	)
	(segment
		(start 405.251158 -10.022078)
		(end 403.934422 -11.338814)
		(width 0.10795)
		(layer "B.Cu")
		(net "SMB_HOST_STBY_LVC3_SCL")
	)
	(segment
		(start 404.268178 -8.329168)
		(end 405.251158 -9.312148)
		(width 0.10795)
		(layer "B.Cu")
		(net "SMB_HOST_STBY_LVC3_SCL")
	)
	(segment
		(start 401.931378 -19.263614)
		(end 401.739608 -19.071844)
		(width 0.10795)
		(layer "B.Cu")
		(net "SMB_HOST_STBY_LVC3_SCL")
	)
	(segment
		(start 190.6778 -5.711952)
		(end 191.32296 -5.066792)
		(width 0.089408)
		(layer "In2.Cu")
		(net "SMB_HOST_STBY_LVC3_SCL")
	)
	(segment
		(start 173.494192 -62.349888)
		(end 172.958252 -61.813948)
		(width 0.089408)
		(layer "In2.Cu")
		(net "SMB_HOST_STBY_LVC3_SCL")
	)
	(segment
		(start 424.67784 -79.843376)
		(end 424.67784 -80.001364)
		(width 0.089408)
		(layer "In2.Cu")
		(net "SMB_HOST_STBY_LVC3_SCL")
	)
	(segment
		(start 160.61944 -51.73218)
		(end 165.422072 -46.929548)
		(width 0.089408)
		(layer "In2.Cu")
		(net "SMB_HOST_STBY_LVC3_SCL")
	)
	(segment
		(start 162.427412 -63.551308)
		(end 161.485072 -62.608968)
		(width 0.089408)
		(layer "In2.Cu")
		(net "SMB_HOST_STBY_LVC3_SCL")
	)
	(segment
		(start 171.3484 -64.1096)
		(end 171.88942 -63.56858)
		(width 0.089408)
		(layer "In2.Cu")
		(net "SMB_HOST_STBY_LVC3_SCL")
	)
	(segment
		(start 189.872874 -14.975586)
		(end 191.223392 -13.625068)
		(width 0.089408)
		(layer "In2.Cu")
		(net "SMB_HOST_STBY_LVC3_SCL")
	)
	(segment
		(start 191.972692 0.413512)
		(end 191.549528 0.413512)
		(width 0.089408)
		(layer "In2.Cu")
		(net "SMB_HOST_STBY_LVC3_SCL")
	)
	(segment
		(start 188.280548 -15.026386)
		(end 188.331094 -15.026386)
		(width 0.089408)
		(layer "In2.Cu")
		(net "SMB_HOST_STBY_LVC3_SCL")
	)
	(segment
		(start 191.549528 0.413512)
		(end 191.486028 0.350012)
		(width 0.089408)
		(layer "In2.Cu")
		(net "SMB_HOST_STBY_LVC3_SCL")
	)
	(segment
		(start 424.67784 -80.001364)
		(end 424.677586 -80.001618)
		(width 0.089408)
		(layer "In2.Cu")
		(net "SMB_HOST_STBY_LVC3_SCL")
	)
	(segment
		(start 173.519084 -70.605142)
		(end 173.519084 -69.666104)
		(width 0.089408)
		(layer "In2.Cu")
		(net "SMB_HOST_STBY_LVC3_SCL")
	)
	(segment
		(start 478.11563 -58.886598)
		(end 477.263968 -59.73826)
		(width 0.089408)
		(layer "In2.Cu")
		(net "SMB_HOST_STBY_LVC3_SCL")
	)
	(segment
		(start 173.519084 -69.666104)
		(end 171.3484 -67.49542)
		(width 0.089408)
		(layer "In2.Cu")
		(net "SMB_HOST_STBY_LVC3_SCL")
	)
	(segment
		(start 428.031148 -64.65824)
		(end 428.030894 -64.657986)
		(width 0.089408)
		(layer "In2.Cu")
		(net "SMB_HOST_STBY_LVC3_SCL")
	)
	(segment
		(start 426.351954 -64.657986)
		(end 423.36593 -67.64401)
		(width 0.089408)
		(layer "In2.Cu")
		(net "SMB_HOST_STBY_LVC3_SCL")
	)
	(segment
		(start 191.486028 0.350012)
		(end 191.486028 0.106172)
		(width 0.089408)
		(layer "In2.Cu")
		(net "SMB_HOST_STBY_LVC3_SCL")
	)
	(segment
		(start 191.223392 -11.698986)
		(end 191.426592 -11.495786)
		(width 0.089408)
		(layer "In2.Cu")
		(net "SMB_HOST_STBY_LVC3_SCL")
	)
	(segment
		(start 424.677586 -79.230728)
		(end 424.677586 -79.843122)
		(width 0.089408)
		(layer "In2.Cu")
		(net "SMB_HOST_STBY_LVC3_SCL")
	)
	(segment
		(start 183.628792 -43.955208)
		(end 183.628792 -38.55847)
		(width 0.089408)
		(layer "In2.Cu")
		(net "SMB_HOST_STBY_LVC3_SCL")
	)
	(segment
		(start 191.707008 -5.066792)
		(end 192.194434 -4.579366)
		(width 0.089408)
		(layer "In2.Cu")
		(net "SMB_HOST_STBY_LVC3_SCL")
	)
	(segment
		(start 173.053248 -63.56858)
		(end 173.494192 -63.127636)
		(width 0.089408)
		(layer "In2.Cu")
		(net "SMB_HOST_STBY_LVC3_SCL")
	)
	(segment
		(start 191.32296 -5.066792)
		(end 191.707008 -5.066792)
		(width 0.089408)
		(layer "In2.Cu")
		(net "SMB_HOST_STBY_LVC3_SCL")
	)
	(segment
		(start 424.677586 -79.843122)
		(end 424.67784 -79.843376)
		(width 0.089408)
		(layer "In2.Cu")
		(net "SMB_HOST_STBY_LVC3_SCL")
	)
	(segment
		(start 173.60646 -71.65594)
		(end 173.809152 -71.453248)
		(width 0.089408)
		(layer "In2.Cu")
		(net "SMB_HOST_STBY_LVC3_SCL")
	)
	(segment
		(start 424.057064 -78.610206)
		(end 424.677586 -79.230728)
		(width 0.089408)
		(layer "In2.Cu")
		(net "SMB_HOST_STBY_LVC3_SCL")
	)
	(segment
		(start 424.677586 -80.001618)
		(end 424.677586 -106.157014)
		(width 0.089408)
		(layer "In2.Cu")
		(net "SMB_HOST_STBY_LVC3_SCL")
	)
	(segment
		(start 477.263968 -59.73826)
		(end 477.263968 -60.54725)
		(width 0.089408)
		(layer "In2.Cu")
		(net "SMB_HOST_STBY_LVC3_SCL")
	)
	(segment
		(start 185.35269 -18.32356)
		(end 186.680348 -18.32356)
		(width 0.089408)
		(layer "In2.Cu")
		(net "SMB_HOST_STBY_LVC3_SCL")
	)
	(segment
		(start 190.6778 -6.756146)
		(end 190.6778 -5.711952)
		(width 0.089408)
		(layer "In2.Cu")
		(net "SMB_HOST_STBY_LVC3_SCL")
	)
	(segment
		(start 173.809152 -71.453248)
		(end 173.809152 -70.89521)
		(width 0.089408)
		(layer "In2.Cu")
		(net "SMB_HOST_STBY_LVC3_SCL")
	)
	(segment
		(start 186.680348 -18.32356)
		(end 187.17641 -17.827498)
		(width 0.089408)
		(layer "In2.Cu")
		(net "SMB_HOST_STBY_LVC3_SCL")
	)
	(segment
		(start 423.36593 -67.64401)
		(end 423.36593 -76.00569)
		(width 0.089408)
		(layer "In2.Cu")
		(net "SMB_HOST_STBY_LVC3_SCL")
	)
	(segment
		(start 428.030894 -64.657986)
		(end 426.351954 -64.657986)
		(width 0.089408)
		(layer "In2.Cu")
		(net "SMB_HOST_STBY_LVC3_SCL")
	)
	(segment
		(start 423.36593 -76.00569)
		(end 424.057064 -76.696824)
		(width 0.089408)
		(layer "In2.Cu")
		(net "SMB_HOST_STBY_LVC3_SCL")
	)
	(segment
		(start 190.971424 -1.767332)
		(end 192.117472 -0.621284)
		(width 0.089408)
		(layer "In2.Cu")
		(net "SMB_HOST_STBY_LVC3_SCL")
	)
	(segment
		(start 187.17641 -17.827498)
		(end 187.17641 -16.130524)
		(width 0.089408)
		(layer "In2.Cu")
		(net "SMB_HOST_STBY_LVC3_SCL")
	)
	(segment
		(start 180.654452 -46.929548)
		(end 183.628792 -43.955208)
		(width 0.089408)
		(layer "In2.Cu")
		(net "SMB_HOST_STBY_LVC3_SCL")
	)
	(segment
		(start 191.486028 0.106172)
		(end 191.6684 -0.0762)
		(width 0.089408)
		(layer "In2.Cu")
		(net "SMB_HOST_STBY_LVC3_SCL")
	)
	(segment
		(start 191.223392 -13.625068)
		(end 191.223392 -11.698986)
		(width 0.089408)
		(layer "In2.Cu")
		(net "SMB_HOST_STBY_LVC3_SCL")
	)
	(segment
		(start 424.057064 -76.696824)
		(end 424.057064 -78.610206)
		(width 0.089408)
		(layer "In2.Cu")
		(net "SMB_HOST_STBY_LVC3_SCL")
	)
	(segment
		(start 173.809152 -70.89521)
		(end 173.519084 -70.605142)
		(width 0.089408)
		(layer "In2.Cu")
		(net "SMB_HOST_STBY_LVC3_SCL")
	)
	(segment
		(start 472.313 -62.0268)
		(end 469.5698 -62.0268)
		(width 0.089408)
		(layer "In2.Cu")
		(net "SMB_HOST_STBY_LVC3_SCL")
	)
	(segment
		(start 191.426592 -7.504938)
		(end 190.6778 -6.756146)
		(width 0.089408)
		(layer "In2.Cu")
		(net "SMB_HOST_STBY_LVC3_SCL")
	)
	(segment
		(start 465.495386 -64.65824)
		(end 428.031148 -64.65824)
		(width 0.089408)
		(layer "In2.Cu")
		(net "SMB_HOST_STBY_LVC3_SCL")
	)
	(segment
		(start 474.989398 -62.82182)
		(end 473.10802 -62.82182)
		(width 0.089408)
		(layer "In2.Cu")
		(net "SMB_HOST_STBY_LVC3_SCL")
	)
	(segment
		(start 165.732968 -61.813948)
		(end 163.995608 -63.551308)
		(width 0.089408)
		(layer "In2.Cu")
		(net "SMB_HOST_STBY_LVC3_SCL")
	)
	(segment
		(start 469.5698 -62.0268)
		(end 468.4268 -63.1698)
		(width 0.089408)
		(layer "In2.Cu")
		(net "SMB_HOST_STBY_LVC3_SCL")
	)
	(segment
		(start 468.4268 -63.1698)
		(end 466.983826 -63.1698)
		(width 0.089408)
		(layer "In2.Cu")
		(net "SMB_HOST_STBY_LVC3_SCL")
	)
	(segment
		(start 423.1386 -107.696)
		(end 423.1386 -108.1786)
		(width 0.089408)
		(layer "In2.Cu")
		(net "SMB_HOST_STBY_LVC3_SCL")
	)
	(segment
		(start 183.628792 -38.55847)
		(end 184.238392 -37.94887)
		(width 0.089408)
		(layer "In2.Cu")
		(net "SMB_HOST_STBY_LVC3_SCL")
	)
	(segment
		(start 188.381894 -14.975586)
		(end 189.872874 -14.975586)
		(width 0.089408)
		(layer "In2.Cu")
		(net "SMB_HOST_STBY_LVC3_SCL")
	)
	(segment
		(start 161.485072 -62.608968)
		(end 161.485072 -59.731148)
		(width 0.089408)
		(layer "In2.Cu")
		(net "SMB_HOST_STBY_LVC3_SCL")
	)
	(segment
		(start 165.422072 -46.929548)
		(end 180.654452 -46.929548)
		(width 0.089408)
		(layer "In2.Cu")
		(net "SMB_HOST_STBY_LVC3_SCL")
	)
	(segment
		(start 473.10802 -62.82182)
		(end 472.313 -62.0268)
		(width 0.089408)
		(layer "In2.Cu")
		(net "SMB_HOST_STBY_LVC3_SCL")
	)
	(segment
		(start 184.238138 -19.438112)
		(end 185.35269 -18.32356)
		(width 0.089408)
		(layer "In2.Cu")
		(net "SMB_HOST_STBY_LVC3_SCL")
	)
	(segment
		(start 423.1386 -108.1786)
		(end 423.623486 -108.663486)
		(width 0.089408)
		(layer "In2.Cu")
		(net "SMB_HOST_STBY_LVC3_SCL")
	)
	(segment
		(start 184.238138 -19.738594)
		(end 184.238138 -19.438112)
		(width 0.089408)
		(layer "In2.Cu")
		(net "SMB_HOST_STBY_LVC3_SCL")
	)
	(segment
		(start 192.194434 -3.38709)
		(end 190.971424 -2.16408)
		(width 0.089408)
		(layer "In2.Cu")
		(net "SMB_HOST_STBY_LVC3_SCL")
	)
	(segment
		(start 192.194434 -4.579366)
		(end 192.194434 -3.38709)
		(width 0.089408)
		(layer "In2.Cu")
		(net "SMB_HOST_STBY_LVC3_SCL")
	)
	(segment
		(start 477.263968 -60.54725)
		(end 474.989398 -62.82182)
		(width 0.089408)
		(layer "In2.Cu")
		(net "SMB_HOST_STBY_LVC3_SCL")
	)
	(segment
		(start 173.494192 -63.127636)
		(end 173.494192 -62.349888)
		(width 0.089408)
		(layer "In2.Cu")
		(net "SMB_HOST_STBY_LVC3_SCL")
	)
	(segment
		(start 188.331094 -15.026386)
		(end 188.381894 -14.975586)
		(width 0.089408)
		(layer "In2.Cu")
		(net "SMB_HOST_STBY_LVC3_SCL")
	)
	(segment
		(start 424.677586 -106.157014)
		(end 423.1386 -107.696)
		(width 0.089408)
		(layer "In2.Cu")
		(net "SMB_HOST_STBY_LVC3_SCL")
	)
	(segment
		(start 161.485072 -59.731148)
		(end 160.61944 -58.865516)
		(width 0.089408)
		(layer "In2.Cu")
		(net "SMB_HOST_STBY_LVC3_SCL")
	)
	(segment
		(start 171.88942 -63.56858)
		(end 173.053248 -63.56858)
		(width 0.089408)
		(layer "In2.Cu")
		(net "SMB_HOST_STBY_LVC3_SCL")
	)
	(segment
		(start 466.983826 -63.1698)
		(end 465.495386 -64.65824)
		(width 0.089408)
		(layer "In2.Cu")
		(net "SMB_HOST_STBY_LVC3_SCL")
	)
	(segment
		(start 184.238392 -37.94887)
		(end 184.238392 -19.738848)
		(width 0.089408)
		(layer "In2.Cu")
		(net "SMB_HOST_STBY_LVC3_SCL")
	)
	(segment
		(start 192.117472 -0.621284)
		(end 192.117472 0.268732)
		(width 0.089408)
		(layer "In2.Cu")
		(net "SMB_HOST_STBY_LVC3_SCL")
	)
	(segment
		(start 190.971424 -2.16408)
		(end 190.971424 -1.767332)
		(width 0.089408)
		(layer "In2.Cu")
		(net "SMB_HOST_STBY_LVC3_SCL")
	)
	(segment
		(start 192.117472 0.268732)
		(end 191.972692 0.413512)
		(width 0.089408)
		(layer "In2.Cu")
		(net "SMB_HOST_STBY_LVC3_SCL")
	)
	(segment
		(start 163.995608 -63.551308)
		(end 162.427412 -63.551308)
		(width 0.089408)
		(layer "In2.Cu")
		(net "SMB_HOST_STBY_LVC3_SCL")
	)
	(segment
		(start 187.17641 -16.130524)
		(end 188.280548 -15.026386)
		(width 0.089408)
		(layer "In2.Cu")
		(net "SMB_HOST_STBY_LVC3_SCL")
	)
	(segment
		(start 172.958252 -61.813948)
		(end 165.732968 -61.813948)
		(width 0.089408)
		(layer "In2.Cu")
		(net "SMB_HOST_STBY_LVC3_SCL")
	)
	(segment
		(start 191.426592 -11.495786)
		(end 191.426592 -7.504938)
		(width 0.089408)
		(layer "In2.Cu")
		(net "SMB_HOST_STBY_LVC3_SCL")
	)
	(segment
		(start 184.238392 -19.738848)
		(end 184.238138 -19.738594)
		(width 0.089408)
		(layer "In2.Cu")
		(net "SMB_HOST_STBY_LVC3_SCL")
	)
	(segment
		(start 160.61944 -58.865516)
		(end 160.61944 -51.73218)
		(width 0.089408)
		(layer "In2.Cu")
		(net "SMB_HOST_STBY_LVC3_SCL")
	)
	(segment
		(start 171.3484 -67.49542)
		(end 171.3484 -64.1096)
		(width 0.089408)
		(layer "In2.Cu")
		(net "SMB_HOST_STBY_LVC3_SCL")
	)
	(segment
		(start 414.1724 -23.293324)
		(end 413.848296 -23.617428)
		(width 0.089408)
		(layer "In4.Cu")
		(net "SMB_HOST_STBY_LVC3_SCL")
	)
	(segment
		(start 424.118278 -22.943312)
		(end 421.879522 -22.943312)
		(width 0.089408)
		(layer "In4.Cu")
		(net "SMB_HOST_STBY_LVC3_SCL")
	)
	(segment
		(start 463.868008 -147.75307)
		(end 463.868008 -137.325862)
		(width 0.089408)
		(layer "In4.Cu")
		(net "SMB_HOST_STBY_LVC3_SCL")
	)
	(segment
		(start 431.271426 -23.065232)
		(end 427.55693 -23.065232)
		(width 0.089408)
		(layer "In4.Cu")
		(net "SMB_HOST_STBY_LVC3_SCL")
	)
	(segment
		(start 462.63941 -30.84449)
		(end 464.710526 -32.915606)
		(width 0.089408)
		(layer "In4.Cu")
		(net "SMB_HOST_STBY_LVC3_SCL")
	)
	(segment
		(start 264.11936 -0.395224)
		(end 264.348976 -0.165608)
		(width 0.089408)
		(layer "In4.Cu")
		(net "SMB_HOST_STBY_LVC3_SCL")
	)
	(segment
		(start 447.940684 -21.326094)
		(end 447.181732 -20.567142)
		(width 0.089408)
		(layer "In4.Cu")
		(net "SMB_HOST_STBY_LVC3_SCL")
	)
	(segment
		(start 421.52951 -23.293324)
		(end 414.1724 -23.293324)
		(width 0.089408)
		(layer "In4.Cu")
		(net "SMB_HOST_STBY_LVC3_SCL")
	)
	(segment
		(start 447.940684 -22.973284)
		(end 447.940684 -21.326094)
		(width 0.089408)
		(layer "In4.Cu")
		(net "SMB_HOST_STBY_LVC3_SCL")
	)
	(segment
		(start 332.260448 -24.354028)
		(end 332.478888 -24.572468)
		(width 0.089408)
		(layer "In4.Cu")
		(net "SMB_HOST_STBY_LVC3_SCL")
	)
	(segment
		(start 460.716884 -27.577796)
		(end 462.639664 -29.500576)
		(width 0.089408)
		(layer "In4.Cu")
		(net "SMB_HOST_STBY_LVC3_SCL")
	)
	(segment
		(start 469.024208 -124.79147)
		(end 468.4014 -124.168662)
		(width 0.089408)
		(layer "In4.Cu")
		(net "SMB_HOST_STBY_LVC3_SCL")
	)
	(segment
		(start 405.595328 -26.644346)
		(end 403.996398 -26.644346)
		(width 0.089408)
		(layer "In4.Cu")
		(net "SMB_HOST_STBY_LVC3_SCL")
	)
	(segment
		(start 191.877696 0.133096)
		(end 193.049906 0.133096)
		(width 0.089408)
		(layer "In4.Cu")
		(net "SMB_HOST_STBY_LVC3_SCL")
	)
	(segment
		(start 448.792092 -23.50389)
		(end 448.47129 -23.50389)
		(width 0.089408)
		(layer "In4.Cu")
		(net "SMB_HOST_STBY_LVC3_SCL")
	)
	(segment
		(start 462.8896 -136.347454)
		(end 462.8896 -130.745738)
		(width 0.089408)
		(layer "In4.Cu")
		(net "SMB_HOST_STBY_LVC3_SCL")
	)
	(segment
		(start 465.88553 -127.749808)
		(end 468.17153 -127.749808)
		(width 0.089408)
		(layer "In4.Cu")
		(net "SMB_HOST_STBY_LVC3_SCL")
	)
	(segment
		(start 403.996398 -26.644346)
		(end 403.996144 -26.6446)
		(width 0.089408)
		(layer "In4.Cu")
		(net "SMB_HOST_STBY_LVC3_SCL")
	)
	(segment
		(start 425.847764 -23.930102)
		(end 424.675554 -23.930102)
		(width 0.089408)
		(layer "In4.Cu")
		(net "SMB_HOST_STBY_LVC3_SCL")
	)
	(segment
		(start 407.94559 -24.86787)
		(end 407.219404 -25.594056)
		(width 0.089408)
		(layer "In4.Cu")
		(net "SMB_HOST_STBY_LVC3_SCL")
	)
	(segment
		(start 427.083982 -23.53818)
		(end 426.239686 -23.53818)
		(width 0.089408)
		(layer "In4.Cu")
		(net "SMB_HOST_STBY_LVC3_SCL")
	)
	(segment
		(start 462.639664 -29.500576)
		(end 462.639664 -30.545024)
		(width 0.089408)
		(layer "In4.Cu")
		(net "SMB_HOST_STBY_LVC3_SCL")
	)
	(segment
		(start 400.293332 -26.952448)
		(end 399.686018 -26.345134)
		(width 0.089408)
		(layer "In4.Cu")
		(net "SMB_HOST_STBY_LVC3_SCL")
	)
	(segment
		(start 400.293586 -26.952194)
		(end 400.293332 -26.952448)
		(width 0.089408)
		(layer "In4.Cu")
		(net "SMB_HOST_STBY_LVC3_SCL")
	)
	(segment
		(start 323.605906 -1.681988)
		(end 323.605906 -22.412706)
		(width 0.089408)
		(layer "In4.Cu")
		(net "SMB_HOST_STBY_LVC3_SCL")
	)
	(segment
		(start 427.55693 -23.065232)
		(end 427.083982 -23.53818)
		(width 0.089408)
		(layer "In4.Cu")
		(net "SMB_HOST_STBY_LVC3_SCL")
	)
	(segment
		(start 421.879522 -22.943312)
		(end 421.52951 -23.293324)
		(width 0.089408)
		(layer "In4.Cu")
		(net "SMB_HOST_STBY_LVC3_SCL")
	)
	(segment
		(start 254.94234 0.915416)
		(end 255.652016 0.915416)
		(width 0.089408)
		(layer "In4.Cu")
		(net "SMB_HOST_STBY_LVC3_SCL")
	)
	(segment
		(start 467.982808 -121.163588)
		(end 468.3125 -120.833896)
		(width 0.089408)
		(layer "In4.Cu")
		(net "SMB_HOST_STBY_LVC3_SCL")
	)
	(segment
		(start 468.4014 -121.7676)
		(end 467.982808 -121.349008)
		(width 0.089408)
		(layer "In4.Cu")
		(net "SMB_HOST_STBY_LVC3_SCL")
	)
	(segment
		(start 262.391144 0.2032)
		(end 262.989568 -0.395224)
		(width 0.089408)
		(layer "In4.Cu")
		(net "SMB_HOST_STBY_LVC3_SCL")
	)
	(segment
		(start 462.639664 -30.545024)
		(end 462.63941 -30.545278)
		(width 0.089408)
		(layer "In4.Cu")
		(net "SMB_HOST_STBY_LVC3_SCL")
	)
	(segment
		(start 406.934416 -25.59431)
		(end 406.645364 -25.59431)
		(width 0.089408)
		(layer "In4.Cu")
		(net "SMB_HOST_STBY_LVC3_SCL")
	)
	(segment
		(start 448.47129 -23.50389)
		(end 447.940684 -22.973284)
		(width 0.089408)
		(layer "In4.Cu")
		(net "SMB_HOST_STBY_LVC3_SCL")
	)
	(segment
		(start 424.432984 -23.687532)
		(end 424.432984 -23.258018)
		(width 0.089408)
		(layer "In4.Cu")
		(net "SMB_HOST_STBY_LVC3_SCL")
	)
	(segment
		(start 407.219404 -25.594056)
		(end 406.93467 -25.594056)
		(width 0.089408)
		(layer "In4.Cu")
		(net "SMB_HOST_STBY_LVC3_SCL")
	)
	(segment
		(start 330.356972 -24.354028)
		(end 332.260448 -24.354028)
		(width 0.089408)
		(layer "In4.Cu")
		(net "SMB_HOST_STBY_LVC3_SCL")
	)
	(segment
		(start 471.394282 -32.634428)
		(end 471.68308 -32.923226)
		(width 0.089408)
		(layer "In4.Cu")
		(net "SMB_HOST_STBY_LVC3_SCL")
	)
	(segment
		(start 326.6186 -25.4254)
		(end 329.2856 -25.4254)
		(width 0.089408)
		(layer "In4.Cu")
		(net "SMB_HOST_STBY_LVC3_SCL")
	)
	(segment
		(start 449.404486 -23.480014)
		(end 449.662042 -23.480014)
		(width 0.089408)
		(layer "In4.Cu")
		(net "SMB_HOST_STBY_LVC3_SCL")
	)
	(segment
		(start 448.8815 -23.593298)
		(end 448.792092 -23.50389)
		(width 0.089408)
		(layer "In4.Cu")
		(net "SMB_HOST_STBY_LVC3_SCL")
	)
	(segment
		(start 323.605906 -22.412706)
		(end 326.6186 -25.4254)
		(width 0.089408)
		(layer "In4.Cu")
		(net "SMB_HOST_STBY_LVC3_SCL")
	)
	(segment
		(start 445.225678 -19.524218)
		(end 441.156598 -19.524218)
		(width 0.089408)
		(layer "In4.Cu")
		(net "SMB_HOST_STBY_LVC3_SCL")
	)
	(segment
		(start 441.156598 -19.524218)
		(end 439.979308 -20.701508)
		(width 0.089408)
		(layer "In4.Cu")
		(net "SMB_HOST_STBY_LVC3_SCL")
	)
	(segment
		(start 469.024208 -126.89713)
		(end 469.024208 -124.79147)
		(width 0.089408)
		(layer "In4.Cu")
		(net "SMB_HOST_STBY_LVC3_SCL")
	)
	(segment
		(start 264.348976 -0.165608)
		(end 322.089526 -0.165608)
		(width 0.089408)
		(layer "In4.Cu")
		(net "SMB_HOST_STBY_LVC3_SCL")
	)
	(segment
		(start 193.331846 -0.148844)
		(end 253.87808 -0.148844)
		(width 0.089408)
		(layer "In4.Cu")
		(net "SMB_HOST_STBY_LVC3_SCL")
	)
	(segment
		(start 447.181732 -20.567142)
		(end 446.268602 -20.567142)
		(width 0.089408)
		(layer "In4.Cu")
		(net "SMB_HOST_STBY_LVC3_SCL")
	)
	(segment
		(start 453.759824 -27.577796)
		(end 460.716884 -27.577796)
		(width 0.089408)
		(layer "In4.Cu")
		(net "SMB_HOST_STBY_LVC3_SCL")
	)
	(segment
		(start 464.610704 -148.408898)
		(end 464.523836 -148.408898)
		(width 0.089408)
		(layer "In4.Cu")
		(net "SMB_HOST_STBY_LVC3_SCL")
	)
	(segment
		(start 406.93467 -25.594056)
		(end 406.934416 -25.59431)
		(width 0.089408)
		(layer "In4.Cu")
		(net "SMB_HOST_STBY_LVC3_SCL")
	)
	(segment
		(start 464.523836 -148.408898)
		(end 463.868008 -147.75307)
		(width 0.089408)
		(layer "In4.Cu")
		(net "SMB_HOST_STBY_LVC3_SCL")
	)
	(segment
		(start 403.996144 -26.6446)
		(end 401.560538 -26.6446)
		(width 0.089408)
		(layer "In4.Cu")
		(net "SMB_HOST_STBY_LVC3_SCL")
	)
	(segment
		(start 401.560538 -26.6446)
		(end 401.252944 -26.952194)
		(width 0.089408)
		(layer "In4.Cu")
		(net "SMB_HOST_STBY_LVC3_SCL")
	)
	(segment
		(start 464.710526 -32.915606)
		(end 469.647524 -32.915606)
		(width 0.089408)
		(layer "In4.Cu")
		(net "SMB_HOST_STBY_LVC3_SCL")
	)
	(segment
		(start 468.17153 -127.749808)
		(end 469.024208 -126.89713)
		(width 0.089408)
		(layer "In4.Cu")
		(net "SMB_HOST_STBY_LVC3_SCL")
	)
	(segment
		(start 322.089526 -0.165608)
		(end 323.605906 -1.681988)
		(width 0.089408)
		(layer "In4.Cu")
		(net "SMB_HOST_STBY_LVC3_SCL")
	)
	(segment
		(start 413.848296 -23.617428)
		(end 409.935172 -23.617428)
		(width 0.089408)
		(layer "In4.Cu")
		(net "SMB_HOST_STBY_LVC3_SCL")
	)
	(segment
		(start 448.8815 -24.003)
		(end 449.404486 -23.480014)
		(width 0.089408)
		(layer "In4.Cu")
		(net "SMB_HOST_STBY_LVC3_SCL")
	)
	(segment
		(start 399.686018 -26.345134)
		(end 399.580862 -26.345134)
		(width 0.089408)
		(layer "In4.Cu")
		(net "SMB_HOST_STBY_LVC3_SCL")
	)
	(segment
		(start 262.989568 -0.395224)
		(end 264.11936 -0.395224)
		(width 0.089408)
		(layer "In4.Cu")
		(net "SMB_HOST_STBY_LVC3_SCL")
	)
	(segment
		(start 463.868008 -137.325862)
		(end 462.8896 -136.347454)
		(width 0.089408)
		(layer "In4.Cu")
		(net "SMB_HOST_STBY_LVC3_SCL")
	)
	(segment
		(start 433.63515 -20.701508)
		(end 431.271426 -23.065232)
		(width 0.089408)
		(layer "In4.Cu")
		(net "SMB_HOST_STBY_LVC3_SCL")
	)
	(segment
		(start 191.6684 -0.0762)
		(end 191.877696 0.133096)
		(width 0.089408)
		(layer "In4.Cu")
		(net "SMB_HOST_STBY_LVC3_SCL")
	)
	(segment
		(start 468.4014 -124.168662)
		(end 468.4014 -121.7676)
		(width 0.089408)
		(layer "In4.Cu")
		(net "SMB_HOST_STBY_LVC3_SCL")
	)
	(segment
		(start 259.373624 1.087882)
		(end 261.502652 1.087882)
		(width 0.089408)
		(layer "In4.Cu")
		(net "SMB_HOST_STBY_LVC3_SCL")
	)
	(segment
		(start 424.675554 -23.930102)
		(end 424.432984 -23.687532)
		(width 0.089408)
		(layer "In4.Cu")
		(net "SMB_HOST_STBY_LVC3_SCL")
	)
	(segment
		(start 401.252944 -26.952194)
		(end 400.293586 -26.952194)
		(width 0.089408)
		(layer "In4.Cu")
		(net "SMB_HOST_STBY_LVC3_SCL")
	)
	(segment
		(start 469.647524 -32.915606)
		(end 469.928702 -32.634428)
		(width 0.089408)
		(layer "In4.Cu")
		(net "SMB_HOST_STBY_LVC3_SCL")
	)
	(segment
		(start 409.935172 -23.617428)
		(end 408.68473 -24.86787)
		(width 0.089408)
		(layer "In4.Cu")
		(net "SMB_HOST_STBY_LVC3_SCL")
	)
	(segment
		(start 446.268602 -20.567142)
		(end 445.225678 -19.524218)
		(width 0.089408)
		(layer "In4.Cu")
		(net "SMB_HOST_STBY_LVC3_SCL")
	)
	(segment
		(start 261.502652 1.087882)
		(end 262.387334 0.2032)
		(width 0.089408)
		(layer "In4.Cu")
		(net "SMB_HOST_STBY_LVC3_SCL")
	)
	(segment
		(start 329.2856 -25.4254)
		(end 330.356972 -24.354028)
		(width 0.089408)
		(layer "In4.Cu")
		(net "SMB_HOST_STBY_LVC3_SCL")
	)
	(segment
		(start 193.049906 0.133096)
		(end 193.331846 -0.148844)
		(width 0.089408)
		(layer "In4.Cu")
		(net "SMB_HOST_STBY_LVC3_SCL")
	)
	(segment
		(start 253.87808 -0.148844)
		(end 254.94234 0.915416)
		(width 0.089408)
		(layer "In4.Cu")
		(net "SMB_HOST_STBY_LVC3_SCL")
	)
	(segment
		(start 467.982808 -121.349008)
		(end 467.982808 -121.163588)
		(width 0.089408)
		(layer "In4.Cu")
		(net "SMB_HOST_STBY_LVC3_SCL")
	)
	(segment
		(start 262.387334 0.2032)
		(end 262.391144 0.2032)
		(width 0.089408)
		(layer "In4.Cu")
		(net "SMB_HOST_STBY_LVC3_SCL")
	)
	(segment
		(start 462.63941 -30.545278)
		(end 462.63941 -30.84449)
		(width 0.089408)
		(layer "In4.Cu")
		(net "SMB_HOST_STBY_LVC3_SCL")
	)
	(segment
		(start 255.652016 0.915416)
		(end 256.125218 1.388618)
		(width 0.089408)
		(layer "In4.Cu")
		(net "SMB_HOST_STBY_LVC3_SCL")
	)
	(segment
		(start 256.125218 1.388618)
		(end 259.072888 1.388618)
		(width 0.089408)
		(layer "In4.Cu")
		(net "SMB_HOST_STBY_LVC3_SCL")
	)
	(segment
		(start 439.979308 -20.701508)
		(end 433.63515 -20.701508)
		(width 0.089408)
		(layer "In4.Cu")
		(net "SMB_HOST_STBY_LVC3_SCL")
	)
	(segment
		(start 408.68473 -24.86787)
		(end 407.94559 -24.86787)
		(width 0.089408)
		(layer "In4.Cu")
		(net "SMB_HOST_STBY_LVC3_SCL")
	)
	(segment
		(start 448.8815 -24.003)
		(end 448.8815 -23.593298)
		(width 0.089408)
		(layer "In4.Cu")
		(net "SMB_HOST_STBY_LVC3_SCL")
	)
	(segment
		(start 469.928702 -32.634428)
		(end 471.394282 -32.634428)
		(width 0.089408)
		(layer "In4.Cu")
		(net "SMB_HOST_STBY_LVC3_SCL")
	)
	(segment
		(start 426.239686 -23.53818)
		(end 425.847764 -23.930102)
		(width 0.089408)
		(layer "In4.Cu")
		(net "SMB_HOST_STBY_LVC3_SCL")
	)
	(segment
		(start 424.432984 -23.258018)
		(end 424.118278 -22.943312)
		(width 0.089408)
		(layer "In4.Cu")
		(net "SMB_HOST_STBY_LVC3_SCL")
	)
	(segment
		(start 259.072888 1.388618)
		(end 259.373624 1.087882)
		(width 0.089408)
		(layer "In4.Cu")
		(net "SMB_HOST_STBY_LVC3_SCL")
	)
	(segment
		(start 449.662042 -23.480014)
		(end 453.759824 -27.577796)
		(width 0.089408)
		(layer "In4.Cu")
		(net "SMB_HOST_STBY_LVC3_SCL")
	)
	(segment
		(start 462.8896 -130.745738)
		(end 465.88553 -127.749808)
		(width 0.089408)
		(layer "In4.Cu")
		(net "SMB_HOST_STBY_LVC3_SCL")
	)
	(segment
		(start 406.645364 -25.59431)
		(end 405.595328 -26.644346)
		(width 0.089408)
		(layer "In4.Cu")
		(net "SMB_HOST_STBY_LVC3_SCL")
	)
	(segment
		(start 423.623486 -108.663486)
		(end 423.909744 -108.377228)
		(width 0.089408)
		(layer "In9.Cu")
		(net "SMB_HOST_STBY_LVC3_SCL")
	)
	(segment
		(start 463.181446 -117.378226)
		(end 467.03742 -121.2342)
		(width 0.089408)
		(layer "In9.Cu")
		(net "SMB_HOST_STBY_LVC3_SCL")
	)
	(segment
		(start 462.331054 -116.535454)
		(end 463.173826 -117.378226)
		(width 0.089408)
		(layer "In9.Cu")
		(net "SMB_HOST_STBY_LVC3_SCL")
	)
	(segment
		(start 463.173826 -117.378226)
		(end 463.181446 -117.378226)
		(width 0.089408)
		(layer "In9.Cu")
		(net "SMB_HOST_STBY_LVC3_SCL")
	)
	(segment
		(start 433.204366 -112.362996)
		(end 437.376824 -116.535454)
		(width 0.089408)
		(layer "In9.Cu")
		(net "SMB_HOST_STBY_LVC3_SCL")
	)
	(segment
		(start 474.077792 -53.991256)
		(end 478.325688 -58.239152)
		(width 0.089408)
		(layer "In9.Cu")
		(net "SMB_HOST_STBY_LVC3_SCL")
	)
	(segment
		(start 478.325688 -58.67654)
		(end 478.11563 -58.886598)
		(width 0.089408)
		(layer "In9.Cu")
		(net "SMB_HOST_STBY_LVC3_SCL")
	)
	(segment
		(start 400.544284 -29.375354)
		(end 399.97126 -28.80233)
		(width 0.089408)
		(layer "In9.Cu")
		(net "SMB_HOST_STBY_LVC3_SCL")
	)
	(segment
		(start 473.836746 -39.25824)
		(end 474.317568 -39.739062)
		(width 0.089408)
		(layer "In9.Cu")
		(net "SMB_HOST_STBY_LVC3_SCL")
	)
	(segment
		(start 423.909744 -108.377228)
		(end 424.133264 -108.377228)
		(width 0.089408)
		(layer "In9.Cu")
		(net "SMB_HOST_STBY_LVC3_SCL")
	)
	(segment
		(start 467.50097 -151.79802)
		(end 468.407242 -150.891748)
		(width 0.089408)
		(layer "In9.Cu")
		(net "SMB_HOST_STBY_LVC3_SCL")
	)
	(segment
		(start 399.62328 -26.345134)
		(end 399.580862 -26.345134)
		(width 0.089408)
		(layer "In9.Cu")
		(net "SMB_HOST_STBY_LVC3_SCL")
	)
	(segment
		(start 466.119972 -151.79802)
		(end 467.50097 -151.79802)
		(width 0.089408)
		(layer "In9.Cu")
		(net "SMB_HOST_STBY_LVC3_SCL")
	)
	(segment
		(start 399.97126 -28.80233)
		(end 399.97126 -26.693114)
		(width 0.089408)
		(layer "In9.Cu")
		(net "SMB_HOST_STBY_LVC3_SCL")
	)
	(segment
		(start 468.407242 -150.891748)
		(end 478.201482 -150.891748)
		(width 0.089408)
		(layer "In9.Cu")
		(net "SMB_HOST_STBY_LVC3_SCL")
	)
	(segment
		(start 427.673008 -112.362996)
		(end 433.204366 -112.362996)
		(width 0.089408)
		(layer "In9.Cu")
		(net "SMB_HOST_STBY_LVC3_SCL")
	)
	(segment
		(start 473.004896 -32.637984)
		(end 473.26169 -32.894778)
		(width 0.089408)
		(layer "In9.Cu")
		(net "SMB_HOST_STBY_LVC3_SCL")
	)
	(segment
		(start 464.610704 -148.408898)
		(end 465.447888 -149.246082)
		(width 0.089408)
		(layer "In9.Cu")
		(net "SMB_HOST_STBY_LVC3_SCL")
	)
	(segment
		(start 471.68308 -32.923226)
		(end 471.968322 -32.637984)
		(width 0.089408)
		(layer "In9.Cu")
		(net "SMB_HOST_STBY_LVC3_SCL")
	)
	(segment
		(start 473.26169 -32.894778)
		(end 473.26169 -34.696908)
		(width 0.089408)
		(layer "In9.Cu")
		(net "SMB_HOST_STBY_LVC3_SCL")
	)
	(segment
		(start 424.133264 -108.377228)
		(end 424.8658 -109.109764)
		(width 0.089408)
		(layer "In9.Cu")
		(net "SMB_HOST_STBY_LVC3_SCL")
	)
	(segment
		(start 476.073216 -40.220392)
		(end 476.073216 -43.87088)
		(width 0.089408)
		(layer "In9.Cu")
		(net "SMB_HOST_STBY_LVC3_SCL")
	)
	(segment
		(start 475.591886 -39.739062)
		(end 476.073216 -40.220392)
		(width 0.089408)
		(layer "In9.Cu")
		(net "SMB_HOST_STBY_LVC3_SCL")
	)
	(segment
		(start 479.171 -151.861266)
		(end 479.171 -154.309826)
		(width 0.089408)
		(layer "In9.Cu")
		(net "SMB_HOST_STBY_LVC3_SCL")
	)
	(segment
		(start 424.8658 -109.109764)
		(end 424.8658 -109.555788)
		(width 0.089408)
		(layer "In9.Cu")
		(net "SMB_HOST_STBY_LVC3_SCL")
	)
	(segment
		(start 465.447888 -151.125936)
		(end 466.119972 -151.79802)
		(width 0.089408)
		(layer "In9.Cu")
		(net "SMB_HOST_STBY_LVC3_SCL")
	)
	(segment
		(start 473.26169 -34.696908)
		(end 473.836746 -35.271964)
		(width 0.089408)
		(layer "In9.Cu")
		(net "SMB_HOST_STBY_LVC3_SCL")
	)
	(segment
		(start 467.03742 -121.2342)
		(end 467.912196 -121.2342)
		(width 0.089408)
		(layer "In9.Cu")
		(net "SMB_HOST_STBY_LVC3_SCL")
	)
	(segment
		(start 474.317568 -39.739062)
		(end 475.591886 -39.739062)
		(width 0.089408)
		(layer "In9.Cu")
		(net "SMB_HOST_STBY_LVC3_SCL")
	)
	(segment
		(start 465.447888 -149.246082)
		(end 465.447888 -151.125936)
		(width 0.089408)
		(layer "In9.Cu")
		(net "SMB_HOST_STBY_LVC3_SCL")
	)
	(segment
		(start 474.077792 -52.525168)
		(end 474.077792 -53.991256)
		(width 0.089408)
		(layer "In9.Cu")
		(net "SMB_HOST_STBY_LVC3_SCL")
	)
	(segment
		(start 476.073216 -43.87088)
		(end 475.529656 -44.41444)
		(width 0.089408)
		(layer "In9.Cu")
		(net "SMB_HOST_STBY_LVC3_SCL")
	)
	(segment
		(start 478.325688 -58.239152)
		(end 478.325688 -58.67654)
		(width 0.089408)
		(layer "In9.Cu")
		(net "SMB_HOST_STBY_LVC3_SCL")
	)
	(segment
		(start 401.13966 -33.300416)
		(end 400.544284 -32.70504)
		(width 0.089408)
		(layer "In9.Cu")
		(net "SMB_HOST_STBY_LVC3_SCL")
	)
	(segment
		(start 475.529656 -44.41444)
		(end 475.529656 -51.073304)
		(width 0.089408)
		(layer "In9.Cu")
		(net "SMB_HOST_STBY_LVC3_SCL")
	)
	(segment
		(start 479.171 -154.309826)
		(end 480.335844 -155.47467)
		(width 0.089408)
		(layer "In9.Cu")
		(net "SMB_HOST_STBY_LVC3_SCL")
	)
	(segment
		(start 475.529656 -51.073304)
		(end 474.077792 -52.525168)
		(width 0.089408)
		(layer "In9.Cu")
		(net "SMB_HOST_STBY_LVC3_SCL")
	)
	(segment
		(start 399.97126 -26.693114)
		(end 399.62328 -26.345134)
		(width 0.089408)
		(layer "In9.Cu")
		(net "SMB_HOST_STBY_LVC3_SCL")
	)
	(segment
		(start 471.968322 -32.637984)
		(end 473.004896 -32.637984)
		(width 0.089408)
		(layer "In9.Cu")
		(net "SMB_HOST_STBY_LVC3_SCL")
	)
	(segment
		(start 424.8658 -109.555788)
		(end 427.673008 -112.362996)
		(width 0.089408)
		(layer "In9.Cu")
		(net "SMB_HOST_STBY_LVC3_SCL")
	)
	(segment
		(start 478.201482 -150.891748)
		(end 479.171 -151.861266)
		(width 0.089408)
		(layer "In9.Cu")
		(net "SMB_HOST_STBY_LVC3_SCL")
	)
	(segment
		(start 473.836746 -35.271964)
		(end 473.836746 -39.25824)
		(width 0.089408)
		(layer "In9.Cu")
		(net "SMB_HOST_STBY_LVC3_SCL")
	)
	(segment
		(start 400.544284 -32.70504)
		(end 400.544284 -29.375354)
		(width 0.089408)
		(layer "In9.Cu")
		(net "SMB_HOST_STBY_LVC3_SCL")
	)
	(segment
		(start 437.376824 -116.535454)
		(end 462.331054 -116.535454)
		(width 0.089408)
		(layer "In9.Cu")
		(net "SMB_HOST_STBY_LVC3_SCL")
	)
	(segment
		(start 467.912196 -121.2342)
		(end 468.3125 -120.833896)
		(width 0.089408)
		(layer "In9.Cu")
		(net "SMB_HOST_STBY_LVC3_SCL")
	)
	(segment
		(start 401.13966 -33.300416)
		(end 401.58797 -32.852106)
		(width 0.089408)
		(layer "In11.Cu")
		(net "SMB_HOST_STBY_LVC3_SCL")
	)
	(segment
		(start 395.778736 -7.285228)
		(end 394.12418 -8.939784)
		(width 0.089408)
		(layer "In11.Cu")
		(net "SMB_HOST_STBY_LVC3_SCL")
	)
	(segment
		(start 404.460202 -6.21284)
		(end 404.2156 -6.457442)
		(width 0.089408)
		(layer "In11.Cu")
		(net "SMB_HOST_STBY_LVC3_SCL")
	)
	(segment
		(start 400.3802 -28.931108)
		(end 400.3802 -27.575764)
		(width 0.089408)
		(layer "In11.Cu")
		(net "SMB_HOST_STBY_LVC3_SCL")
	)
	(segment
		(start 371.73281 -8.663432)
		(end 371.73281 -9.87679)
		(width 0.089408)
		(layer "In11.Cu")
		(net "SMB_HOST_STBY_LVC3_SCL")
	)
	(segment
		(start 363.224826 -27.644598)
		(end 355.314504 -35.55492)
		(width 0.089408)
		(layer "In11.Cu")
		(net "SMB_HOST_STBY_LVC3_SCL")
	)
	(segment
		(start 380.062232 -9.33577)
		(end 378.168154 -7.441692)
		(width 0.089408)
		(layer "In11.Cu")
		(net "SMB_HOST_STBY_LVC3_SCL")
	)
	(segment
		(start 332.75016 -24.572468)
		(end 332.478888 -24.572468)
		(width 0.089408)
		(layer "In11.Cu")
		(net "SMB_HOST_STBY_LVC3_SCL")
	)
	(segment
		(start 372.95455 -7.441692)
		(end 371.73281 -8.663432)
		(width 0.089408)
		(layer "In11.Cu")
		(net "SMB_HOST_STBY_LVC3_SCL")
	)
	(segment
		(start 378.168154 -7.441692)
		(end 372.95455 -7.441692)
		(width 0.089408)
		(layer "In11.Cu")
		(net "SMB_HOST_STBY_LVC3_SCL")
	)
	(segment
		(start 337.64982 -35.222942)
		(end 336.571082 -35.222942)
		(width 0.089408)
		(layer "In11.Cu")
		(net "SMB_HOST_STBY_LVC3_SCL")
	)
	(segment
		(start 400.080226 -24.160226)
		(end 400.955764 -23.284688)
		(width 0.089408)
		(layer "In11.Cu")
		(net "SMB_HOST_STBY_LVC3_SCL")
	)
	(segment
		(start 337.981798 -35.55492)
		(end 337.64982 -35.222942)
		(width 0.089408)
		(layer "In11.Cu")
		(net "SMB_HOST_STBY_LVC3_SCL")
	)
	(segment
		(start 400.955764 -20.239228)
		(end 401.931378 -19.263614)
		(width 0.089408)
		(layer "In11.Cu")
		(net "SMB_HOST_STBY_LVC3_SCL")
	)
	(segment
		(start 404.578566 -6.21284)
		(end 404.460202 -6.21284)
		(width 0.089408)
		(layer "In11.Cu")
		(net "SMB_HOST_STBY_LVC3_SCL")
	)
	(segment
		(start 394.12418 -8.939784)
		(end 391.496804 -8.939784)
		(width 0.089408)
		(layer "In11.Cu")
		(net "SMB_HOST_STBY_LVC3_SCL")
	)
	(segment
		(start 401.58797 -32.852106)
		(end 401.58797 -30.138878)
		(width 0.089408)
		(layer "In11.Cu")
		(net "SMB_HOST_STBY_LVC3_SCL")
	)
	(segment
		(start 391.496804 -8.939784)
		(end 391.100818 -9.33577)
		(width 0.089408)
		(layer "In11.Cu")
		(net "SMB_HOST_STBY_LVC3_SCL")
	)
	(segment
		(start 363.224826 -18.384774)
		(end 363.224826 -27.644598)
		(width 0.089408)
		(layer "In11.Cu")
		(net "SMB_HOST_STBY_LVC3_SCL")
	)
	(segment
		(start 401.58797 -30.138878)
		(end 400.3802 -28.931108)
		(width 0.089408)
		(layer "In11.Cu")
		(net "SMB_HOST_STBY_LVC3_SCL")
	)
	(segment
		(start 332.839822 -31.491682)
		(end 332.839822 -24.66213)
		(width 0.089408)
		(layer "In11.Cu")
		(net "SMB_HOST_STBY_LVC3_SCL")
	)
	(segment
		(start 404.2156 -6.457442)
		(end 404.2156 -6.777482)
		(width 0.089408)
		(layer "In11.Cu")
		(net "SMB_HOST_STBY_LVC3_SCL")
	)
	(segment
		(start 332.839822 -24.66213)
		(end 332.75016 -24.572468)
		(width 0.089408)
		(layer "In11.Cu")
		(net "SMB_HOST_STBY_LVC3_SCL")
	)
	(segment
		(start 404.2156 -6.777482)
		(end 403.707854 -7.285228)
		(width 0.089408)
		(layer "In11.Cu")
		(net "SMB_HOST_STBY_LVC3_SCL")
	)
	(segment
		(start 400.080226 -25.254204)
		(end 400.080226 -24.160226)
		(width 0.089408)
		(layer "In11.Cu")
		(net "SMB_HOST_STBY_LVC3_SCL")
	)
	(segment
		(start 401.2057 -26.379678)
		(end 400.080226 -25.254204)
		(width 0.089408)
		(layer "In11.Cu")
		(net "SMB_HOST_STBY_LVC3_SCL")
	)
	(segment
		(start 400.3802 -27.575764)
		(end 401.2057 -26.750264)
		(width 0.089408)
		(layer "In11.Cu")
		(net "SMB_HOST_STBY_LVC3_SCL")
	)
	(segment
		(start 371.73281 -9.87679)
		(end 363.224826 -18.384774)
		(width 0.089408)
		(layer "In11.Cu")
		(net "SMB_HOST_STBY_LVC3_SCL")
	)
	(segment
		(start 336.571082 -35.222942)
		(end 332.839822 -31.491682)
		(width 0.089408)
		(layer "In11.Cu")
		(net "SMB_HOST_STBY_LVC3_SCL")
	)
	(segment
		(start 401.2057 -26.750264)
		(end 401.2057 -26.379678)
		(width 0.089408)
		(layer "In11.Cu")
		(net "SMB_HOST_STBY_LVC3_SCL")
	)
	(segment
		(start 403.707854 -7.285228)
		(end 395.778736 -7.285228)
		(width 0.089408)
		(layer "In11.Cu")
		(net "SMB_HOST_STBY_LVC3_SCL")
	)
	(segment
		(start 391.100818 -9.33577)
		(end 380.062232 -9.33577)
		(width 0.089408)
		(layer "In11.Cu")
		(net "SMB_HOST_STBY_LVC3_SCL")
	)
	(segment
		(start 400.955764 -23.284688)
		(end 400.955764 -20.239228)
		(width 0.089408)
		(layer "In11.Cu")
		(net "SMB_HOST_STBY_LVC3_SCL")
	)
	(segment
		(start 355.314504 -35.55492)
		(end 337.981798 -35.55492)
		(width 0.089408)
		(layer "In11.Cu")
		(net "SMB_HOST_STBY_LVC3_SCL")
	)
	(segment
		(start 391.647934 -89.381584)
		(end 391.40892 -89.14257)
		(width 0.10795)
		(layer "F.Cu")
		(net "PU_ADR_TIMER_HOLD_OFF_N")
	)
	(segment
		(start 392.87069 -93.905324)
		(end 392.663172 -93.697806)
		(width 0.0889)
		(layer "F.Cu")
		(net "PU_ADR_TIMER_HOLD_OFF_N")
	)
	(segment
		(start 391.477246 -87.3125)
		(end 391.795 -87.3125)
		(width 0.10795)
		(layer "F.Cu")
		(net "PU_ADR_TIMER_HOLD_OFF_N")
	)
	(segment
		(start 392.179556 -89.94902)
		(end 391.825988 -89.94902)
		(width 0.10795)
		(layer "F.Cu")
		(net "PU_ADR_TIMER_HOLD_OFF_N")
	)
	(segment
		(start 392.87069 -94.26067)
		(end 392.87069 -93.905324)
		(width 0.0889)
		(layer "F.Cu")
		(net "PU_ADR_TIMER_HOLD_OFF_N")
	)
	(segment
		(start 392.787124 -92.027248)
		(end 392.406378 -91.646502)
		(width 0.10795)
		(layer "F.Cu")
		(net "PU_ADR_TIMER_HOLD_OFF_N")
	)
	(segment
		(start 392.406378 -91.646502)
		(end 392.406378 -91.499436)
		(width 0.10795)
		(layer "F.Cu")
		(net "PU_ADR_TIMER_HOLD_OFF_N")
	)
	(segment
		(start 392.312906 -90.08237)
		(end 392.179556 -89.94902)
		(width 0.10795)
		(layer "F.Cu")
		(net "PU_ADR_TIMER_HOLD_OFF_N")
	)
	(segment
		(start 391.795 -87.001096)
		(end 391.403078 -86.609174)
		(width 0.10795)
		(layer "F.Cu")
		(net "PU_ADR_TIMER_HOLD_OFF_N")
	)
	(segment
		(start 391.647934 -89.770966)
		(end 391.647934 -89.381584)
		(width 0.10795)
		(layer "F.Cu")
		(net "PU_ADR_TIMER_HOLD_OFF_N")
	)
	(segment
		(start 391.795 -87.3125)
		(end 391.795 -87.001096)
		(width 0.10795)
		(layer "F.Cu")
		(net "PU_ADR_TIMER_HOLD_OFF_N")
	)
	(segment
		(start 391.403078 -86.609174)
		(end 391.403078 -86.569042)
		(width 0.10795)
		(layer "F.Cu")
		(net "PU_ADR_TIMER_HOLD_OFF_N")
	)
	(segment
		(start 392.663172 -93.697806)
		(end 392.663172 -93.408246)
		(width 0.0889)
		(layer "F.Cu")
		(net "PU_ADR_TIMER_HOLD_OFF_N")
	)
	(segment
		(start 391.224516 -87.56523)
		(end 391.477246 -87.3125)
		(width 0.10795)
		(layer "F.Cu")
		(net "PU_ADR_TIMER_HOLD_OFF_N")
	)
	(segment
		(start 392.942318 -93.1291)
		(end 392.942318 -92.182442)
		(width 0.0889)
		(layer "F.Cu")
		(net "PU_ADR_TIMER_HOLD_OFF_N")
	)
	(segment
		(start 392.942318 -92.182442)
		(end 392.787124 -92.027248)
		(width 0.0889)
		(layer "F.Cu")
		(net "PU_ADR_TIMER_HOLD_OFF_N")
	)
	(segment
		(start 391.825988 -89.94902)
		(end 391.647934 -89.770966)
		(width 0.10795)
		(layer "F.Cu")
		(net "PU_ADR_TIMER_HOLD_OFF_N")
	)
	(segment
		(start 392.98499 -94.37497)
		(end 392.87069 -94.26067)
		(width 0.0889)
		(layer "F.Cu")
		(net "PU_ADR_TIMER_HOLD_OFF_N")
	)
	(segment
		(start 391.40892 -89.14257)
		(end 391.224516 -88.958166)
		(width 0.10795)
		(layer "F.Cu")
		(net "PU_ADR_TIMER_HOLD_OFF_N")
	)
	(segment
		(start 392.312906 -91.405964)
		(end 392.312906 -90.08237)
		(width 0.10795)
		(layer "F.Cu")
		(net "PU_ADR_TIMER_HOLD_OFF_N")
	)
	(segment
		(start 391.224516 -88.958166)
		(end 391.224516 -87.56523)
		(width 0.10795)
		(layer "F.Cu")
		(net "PU_ADR_TIMER_HOLD_OFF_N")
	)
	(segment
		(start 392.663172 -93.408246)
		(end 392.942318 -93.1291)
		(width 0.0889)
		(layer "F.Cu")
		(net "PU_ADR_TIMER_HOLD_OFF_N")
	)
	(segment
		(start 392.406378 -91.499436)
		(end 392.312906 -91.405964)
		(width 0.10795)
		(layer "F.Cu")
		(net "PU_ADR_TIMER_HOLD_OFF_N")
	)
	(via
		(at 391.40892 -89.14257)
		(size 0.508)
		(drill 0.254)
		(layers "F.Cu" "B.Cu")
		(net "PU_ADR_TIMER_HOLD_OFF_N")
	)
	(segment
		(start 169.11193 -148.429218)
		(end 169.11193 -150.44547)
		(width 0.254)
		(layer "F.Cu")
		(net "VR_PVTT_KLM_SNS")
	)
	(segment
		(start 169.11193 -150.44547)
		(end 169.73804 -151.07158)
		(width 0.254)
		(layer "F.Cu")
		(net "VR_PVTT_KLM_SNS")
	)
	(segment
		(start 169.73804 -151.07158)
		(end 169.73804 -151.417528)
		(width 0.254)
		(layer "F.Cu")
		(net "VR_PVTT_KLM_SNS")
	)
	(segment
		(start 97.72142 -158.1277)
		(end 98.039174 -158.1277)
		(width 0.254)
		(layer "F.Cu")
		(net "VR_PVTT_KLM_SNS")
	)
	(segment
		(start 98.039174 -158.1277)
		(end 98.29038 -158.378906)
		(width 0.254)
		(layer "F.Cu")
		(net "VR_PVTT_KLM_SNS")
	)
	(segment
		(start 169.73804 -151.417528)
		(end 169.136568 -152.019)
		(width 0.254)
		(layer "F.Cu")
		(net "VR_PVTT_KLM_SNS")
	)
	(segment
		(start 169.136568 -152.019)
		(end 168.91 -152.019)
		(width 0.254)
		(layer "F.Cu")
		(net "VR_PVTT_KLM_SNS")
	)
	(via
		(at 169.73804 -151.07158)
		(size 0.762)
		(drill 0.381)
		(layers "F.Cu" "B.Cu")
		(net "VR_PVTT_KLM_SNS")
	)
	(via
		(at 98.29038 -158.378906)
		(size 0.508)
		(drill 0.254)
		(layers "F.Cu" "B.Cu")
		(net "VR_PVTT_KLM_SNS")
	)
	(via
		(at 168.91 -152.019)
		(size 0.508)
		(drill 0.254)
		(layers "F.Cu" "B.Cu")
		(net "VR_PVTT_KLM_SNS")
	)
	(segment
		(start 100.55352 -158.378906)
		(end 101.198426 -157.734)
		(width 0.254)
		(layer "In9.Cu")
		(net "VR_PVTT_KLM_SNS")
	)
	(segment
		(start 168.37914 -156.35986)
		(end 168.37914 -152.54986)
		(width 0.254)
		(layer "In9.Cu")
		(net "VR_PVTT_KLM_SNS")
	)
	(segment
		(start 98.29038 -158.378906)
		(end 100.55352 -158.378906)
		(width 0.254)
		(layer "In9.Cu")
		(net "VR_PVTT_KLM_SNS")
	)
	(segment
		(start 101.198426 -157.734)
		(end 167.005 -157.734)
		(width 0.254)
		(layer "In9.Cu")
		(net "VR_PVTT_KLM_SNS")
	)
	(segment
		(start 167.005 -157.734)
		(end 168.37914 -156.35986)
		(width 0.254)
		(layer "In9.Cu")
		(net "VR_PVTT_KLM_SNS")
	)
	(segment
		(start 168.37914 -152.54986)
		(end 168.91 -152.019)
		(width 0.254)
		(layer "In9.Cu")
		(net "VR_PVTT_KLM_SNS")
	)
	(segment
		(start 172.48378 -146.929348)
		(end 172.727366 -146.685762)
		(width 0.254)
		(layer "F.Cu")
		(net "VR_PVTT_KLM_BIAS")
	)
	(segment
		(start 172.727366 -146.685762)
		(end 173.228762 -146.685762)
		(width 0.254)
		(layer "F.Cu")
		(net "VR_PVTT_KLM_BIAS")
	)
	(segment
		(start 173.228762 -146.685762)
		(end 173.482 -146.939)
		(width 0.254)
		(layer "F.Cu")
		(net "VR_PVTT_KLM_BIAS")
	)
	(segment
		(start 171.983146 -146.929348)
		(end 172.48378 -146.929348)
		(width 0.254)
		(layer "F.Cu")
		(net "VR_PVTT_KLM_BIAS")
	)
	(via
		(at 172.727366 -146.685762)
		(size 0.508)
		(drill 0.254)
		(layers "F.Cu" "B.Cu")
		(net "VR_PVTT_KLM_BIAS")
	)
	(segment
		(start 172.727366 -146.685762)
		(end 172.980604 -146.939)
		(width 0.254)
		(layer "B.Cu")
		(net "VR_PVTT_KLM_BIAS")
	)
	(segment
		(start 172.980604 -146.939)
		(end 173.6344 -146.939)
		(width 0.254)
		(layer "B.Cu")
		(net "VR_PVTT_KLM_BIAS")
	)
	(segment
		(start 169.010584 -5.174996)
		(end 169.010584 -5.842)
		(width 0.254)
		(layer "F.Cu")
		(net "VR_PVTT_GHJ_SNS")
	)
	(via
		(at 95.097854 2.881884)
		(size 0.508)
		(drill 0.254)
		(layers "F.Cu" "B.Cu")
		(net "VR_PVTT_GHJ_SNS")
	)
	(via
		(at 169.010584 -5.842)
		(size 0.508)
		(drill 0.254)
		(layers "F.Cu" "B.Cu")
		(net "VR_PVTT_GHJ_SNS")
	)
	(segment
		(start 95.146368 2.881884)
		(end 95.400368 3.135884)
		(width 0.254)
		(layer "B.Cu")
		(net "VR_PVTT_GHJ_SNS")
	)
	(segment
		(start 95.400368 3.135884)
		(end 95.400368 3.4798)
		(width 0.254)
		(layer "B.Cu")
		(net "VR_PVTT_GHJ_SNS")
	)
	(segment
		(start 95.097854 2.881884)
		(end 95.146368 2.881884)
		(width 0.254)
		(layer "B.Cu")
		(net "VR_PVTT_GHJ_SNS")
	)
	(segment
		(start 95.64243 3.42646)
		(end 95.097854 2.881884)
		(width 0.254)
		(layer "In2.Cu")
		(net "VR_PVTT_GHJ_SNS")
	)
	(segment
		(start 117.479826 4.572)
		(end 116.334286 3.42646)
		(width 0.254)
		(layer "In2.Cu")
		(net "VR_PVTT_GHJ_SNS")
	)
	(segment
		(start 116.334286 3.42646)
		(end 95.64243 3.42646)
		(width 0.254)
		(layer "In2.Cu")
		(net "VR_PVTT_GHJ_SNS")
	)
	(segment
		(start 166.38524 -3.216656)
		(end 166.38524 2.568194)
		(width 0.254)
		(layer "In2.Cu")
		(net "VR_PVTT_GHJ_SNS")
	)
	(segment
		(start 166.38524 2.568194)
		(end 164.381434 4.572)
		(width 0.254)
		(layer "In2.Cu")
		(net "VR_PVTT_GHJ_SNS")
	)
	(segment
		(start 169.010584 -5.842)
		(end 166.38524 -3.216656)
		(width 0.254)
		(layer "In2.Cu")
		(net "VR_PVTT_GHJ_SNS")
	)
	(segment
		(start 164.381434 4.572)
		(end 117.479826 4.572)
		(width 0.254)
		(layer "In2.Cu")
		(net "VR_PVTT_GHJ_SNS")
	)
	(segment
		(start 172.7708 -3.3274)
		(end 173.1264 -3.683)
		(width 0.254)
		(layer "F.Cu")
		(net "VR_PVTT_GHJ_BIAS")
	)
	(segment
		(start 173.1264 -3.683)
		(end 173.609 -3.683)
		(width 0.254)
		(layer "F.Cu")
		(net "VR_PVTT_GHJ_BIAS")
	)
	(segment
		(start 171.8818 -3.675126)
		(end 172.423074 -3.675126)
		(width 0.254)
		(layer "F.Cu")
		(net "VR_PVTT_GHJ_BIAS")
	)
	(segment
		(start 172.423074 -3.675126)
		(end 172.7708 -3.3274)
		(width 0.254)
		(layer "F.Cu")
		(net "VR_PVTT_GHJ_BIAS")
	)
	(via
		(at 172.7708 -3.3274)
		(size 0.508)
		(drill 0.254)
		(layers "F.Cu" "B.Cu")
		(net "VR_PVTT_GHJ_BIAS")
	)
	(segment
		(start 173.2534 -3.683)
		(end 173.7233 -3.683)
		(width 0.254)
		(layer "B.Cu")
		(net "VR_PVTT_GHJ_BIAS")
	)
	(segment
		(start 172.8978 -3.3274)
		(end 173.2534 -3.683)
		(width 0.254)
		(layer "B.Cu")
		(net "VR_PVTT_GHJ_BIAS")
	)
	(segment
		(start 172.7708 -3.3274)
		(end 172.8978 -3.3274)
		(width 0.254)
		(layer "B.Cu")
		(net "VR_PVTT_GHJ_BIAS")
	)
	(via
		(at 184.912 -158.369)
		(size 0.508)
		(drill 0.254)
		(layers "F.Cu" "B.Cu")
		(net "VR_PVTT_DEF_SNS")
	)
	(via
		(at 254.494284 -157.85084)
		(size 0.6604)
		(drill 0.3302)
		(layers "F.Cu" "B.Cu")
		(net "VR_PVTT_DEF_SNS")
	)
	(segment
		(start 254.768604 -157.57652)
		(end 254.494284 -157.85084)
		(width 0.254)
		(layer "B.Cu")
		(net "VR_PVTT_DEF_SNS")
	)
	(segment
		(start 255.38938 -157.57652)
		(end 254.768604 -157.57652)
		(width 0.254)
		(layer "B.Cu")
		(net "VR_PVTT_DEF_SNS")
	)
	(segment
		(start 185.0517 -158.5087)
		(end 184.912 -158.369)
		(width 0.254)
		(layer "B.Cu")
		(net "VR_PVTT_DEF_SNS")
	)
	(segment
		(start 254.494284 -157.85084)
		(end 253.836424 -158.5087)
		(width 0.254)
		(layer "B.Cu")
		(net "VR_PVTT_DEF_SNS")
	)
	(segment
		(start 253.836424 -158.5087)
		(end 185.0517 -158.5087)
		(width 0.254)
		(layer "B.Cu")
		(net "VR_PVTT_DEF_SNS")
	)
	(segment
		(start 182.39105 -148.3487)
		(end 182.39105 -147.60575)
		(width 0.254)
		(layer "F.Cu")
		(net "VR_PVTT_DEF_BIAS")
	)
	(segment
		(start 182.39105 -147.60575)
		(end 182.4228 -147.574)
		(width 0.254)
		(layer "F.Cu")
		(net "VR_PVTT_DEF_BIAS")
	)
	(segment
		(start 181.5084 -146.950176)
		(end 181.5084 -146.812)
		(width 0.254)
		(layer "F.Cu")
		(net "VR_PVTT_DEF_BIAS")
	)
	(segment
		(start 182.132224 -147.574)
		(end 181.5084 -146.950176)
		(width 0.254)
		(layer "F.Cu")
		(net "VR_PVTT_DEF_BIAS")
	)
	(segment
		(start 182.4228 -147.574)
		(end 182.132224 -147.574)
		(width 0.254)
		(layer "F.Cu")
		(net "VR_PVTT_DEF_BIAS")
	)
	(via
		(at 182.4228 -147.574)
		(size 0.508)
		(drill 0.254)
		(layers "F.Cu" "B.Cu")
		(net "VR_PVTT_DEF_BIAS")
	)
	(segment
		(start 182.4228 -147.0025)
		(end 182.4228 -147.574)
		(width 0.254)
		(layer "B.Cu")
		(net "VR_PVTT_DEF_BIAS")
	)
	(segment
		(start 182.1053 -146.685)
		(end 182.4228 -147.0025)
		(width 0.254)
		(layer "B.Cu")
		(net "VR_PVTT_DEF_BIAS")
	)
	(segment
		(start 181.864 -146.685)
		(end 182.1053 -146.685)
		(width 0.254)
		(layer "B.Cu")
		(net "VR_PVTT_DEF_BIAS")
	)
	(segment
		(start 184.9628 -3.022854)
		(end 184.9628 -3.8227)
		(width 0.254)
		(layer "F.Cu")
		(net "VR_PVTT_ABC_VREF")
	)
	(segment
		(start 184.645554 -2.705608)
		(end 184.9628 -3.022854)
		(width 0.254)
		(layer "F.Cu")
		(net "VR_PVTT_ABC_VREF")
	)
	(segment
		(start 184.9628 -3.8227)
		(end 184.531 -4.2545)
		(width 0.254)
		(layer "F.Cu")
		(net "VR_PVTT_ABC_VREF")
	)
	(segment
		(start 184.133998 -2.705608)
		(end 184.645554 -2.705608)
		(width 0.254)
		(layer "F.Cu")
		(net "VR_PVTT_ABC_VREF")
	)
	(segment
		(start 181.749192 0.165608)
		(end 181.4322 0.4826)
		(width 0.254)
		(layer "F.Cu")
		(net "VR_PVTT_ABC_SNS")
	)
	(segment
		(start 182.134002 0.165608)
		(end 181.749192 0.165608)
		(width 0.254)
		(layer "F.Cu")
		(net "VR_PVTT_ABC_SNS")
	)
	(via
		(at 260.909308 2.79527)
		(size 0.508)
		(drill 0.254)
		(layers "F.Cu" "B.Cu")
		(net "VR_PVTT_ABC_SNS")
	)
	(via
		(at 181.4322 0.4826)
		(size 0.508)
		(drill 0.254)
		(layers "F.Cu" "B.Cu")
		(net "VR_PVTT_ABC_SNS")
	)
	(segment
		(start 260.909308 2.79527)
		(end 260.909308 2.794508)
		(width 0.1143)
		(layer "B.Cu")
		(net "VR_PVTT_ABC_SNS")
	)
	(segment
		(start 260.909308 2.794508)
		(end 260.863334 2.748534)
		(width 0.1143)
		(layer "B.Cu")
		(net "VR_PVTT_ABC_SNS")
	)
	(segment
		(start 260.863334 2.748534)
		(end 260.863334 2.123694)
		(width 0.1143)
		(layer "B.Cu")
		(net "VR_PVTT_ABC_SNS")
	)
	(segment
		(start 260.602222 2.794508)
		(end 260.909308 2.794508)
		(width 0.254)
		(layer "In2.Cu")
		(net "VR_PVTT_ABC_SNS")
	)
	(segment
		(start 181.4322 0.4826)
		(end 184.05348 0.4826)
		(width 0.254)
		(layer "In2.Cu")
		(net "VR_PVTT_ABC_SNS")
	)
	(segment
		(start 260.909308 2.794508)
		(end 260.909308 2.79527)
		(width 0.254)
		(layer "In2.Cu")
		(net "VR_PVTT_ABC_SNS")
	)
	(segment
		(start 187.275978 3.705098)
		(end 259.691632 3.705098)
		(width 0.254)
		(layer "In2.Cu")
		(net "VR_PVTT_ABC_SNS")
	)
	(segment
		(start 184.05348 0.4826)
		(end 187.275978 3.705098)
		(width 0.254)
		(layer "In2.Cu")
		(net "VR_PVTT_ABC_SNS")
	)
	(segment
		(start 259.691632 3.705098)
		(end 260.602222 2.794508)
		(width 0.254)
		(layer "In2.Cu")
		(net "VR_PVTT_ABC_SNS")
	)
	(segment
		(start 183.388 -4.2545)
		(end 183.423306 -4.2545)
		(width 0.254)
		(layer "F.Cu")
		(net "VR_PVTT_ABC_BIAS")
	)
	(segment
		(start 184.108598 -3.569208)
		(end 184.108598 -3.518408)
		(width 0.254)
		(layer "F.Cu")
		(net "VR_PVTT_ABC_BIAS")
	)
	(segment
		(start 183.633872 -2.705608)
		(end 183.633872 -3.043682)
		(width 0.254)
		(layer "F.Cu")
		(net "VR_PVTT_ABC_BIAS")
	)
	(segment
		(start 183.633872 -3.043682)
		(end 184.108598 -3.518408)
		(width 0.254)
		(layer "F.Cu")
		(net "VR_PVTT_ABC_BIAS")
	)
	(segment
		(start 183.423306 -4.2545)
		(end 184.108598 -3.569208)
		(width 0.254)
		(layer "F.Cu")
		(net "VR_PVTT_ABC_BIAS")
	)
	(via
		(at 184.108598 -3.518408)
		(size 0.508)
		(drill 0.254)
		(layers "F.Cu" "B.Cu")
		(net "VR_PVTT_ABC_BIAS")
	)
	(segment
		(start 183.625998 -4.001008)
		(end 183.625998 -4.432808)
		(width 0.254)
		(layer "B.Cu")
		(net "VR_PVTT_ABC_BIAS")
	)
	(segment
		(start 184.108598 -3.518408)
		(end 183.625998 -4.001008)
		(width 0.254)
		(layer "B.Cu")
		(net "VR_PVTT_ABC_BIAS")
	)
	(segment
		(start 419.88994 -39.334694)
		(end 419.490144 -39.73449)
		(width 0.089408)
		(layer "F.Cu")
		(net "SPI_BMC_BT_DO_R")
	)
	(segment
		(start 419.890194 -39.334694)
		(end 419.88994 -39.334694)
		(width 0.089408)
		(layer "F.Cu")
		(net "SPI_BMC_BT_DO_R")
	)
	(via
		(at 419.490144 -39.73449)
		(size 0.4572)
		(drill 0.2032)
		(layers "F.Cu" "B.Cu")
		(net "SPI_BMC_BT_DO_R")
	)
	(via
		(at 420.8018 -43.437556)
		(size 0.6604)
		(drill 0.3302)
		(layers "F.Cu" "B.Cu")
		(net "SPI_BMC_BT_DO_R")
	)
	(segment
		(start 420.464742 -42.0624)
		(end 420.464996 -42.062654)
		(width 0.10795)
		(layer "B.Cu")
		(net "SPI_BMC_BT_DO_R")
	)
	(segment
		(start 420.8018 -43.951906)
		(end 420.923466 -44.073572)
		(width 0.089408)
		(layer "B.Cu")
		(net "SPI_BMC_BT_DO_R")
	)
	(segment
		(start 420.464742 -41.864534)
		(end 420.464742 -42.0624)
		(width 0.10795)
		(layer "B.Cu")
		(net "SPI_BMC_BT_DO_R")
	)
	(segment
		(start 420.8018 -42.865294)
		(end 420.8018 -43.437556)
		(width 0.10795)
		(layer "B.Cu")
		(net "SPI_BMC_BT_DO_R")
	)
	(segment
		(start 420.464996 -42.062654)
		(end 420.464996 -42.52849)
		(width 0.10795)
		(layer "B.Cu")
		(net "SPI_BMC_BT_DO_R")
	)
	(segment
		(start 420.318946 -41.718738)
		(end 420.464742 -41.864534)
		(width 0.10795)
		(layer "B.Cu")
		(net "SPI_BMC_BT_DO_R")
	)
	(segment
		(start 419.894004 -41.293796)
		(end 419.905942 -41.305734)
		(width 0.10795)
		(layer "B.Cu")
		(net "SPI_BMC_BT_DO_R")
	)
	(segment
		(start 420.923466 -44.073572)
		(end 420.923466 -44.647612)
		(width 0.089408)
		(layer "B.Cu")
		(net "SPI_BMC_BT_DO_R")
	)
	(segment
		(start 420.130986 -41.718738)
		(end 420.318946 -41.718738)
		(width 0.10795)
		(layer "B.Cu")
		(net "SPI_BMC_BT_DO_R")
	)
	(segment
		(start 420.464996 -42.52849)
		(end 420.8018 -42.865294)
		(width 0.10795)
		(layer "B.Cu")
		(net "SPI_BMC_BT_DO_R")
	)
	(segment
		(start 419.490144 -39.73449)
		(end 419.894004 -40.13835)
		(width 0.10795)
		(layer "B.Cu")
		(net "SPI_BMC_BT_DO_R")
	)
	(segment
		(start 419.905942 -41.493694)
		(end 420.130986 -41.718738)
		(width 0.10795)
		(layer "B.Cu")
		(net "SPI_BMC_BT_DO_R")
	)
	(segment
		(start 419.905942 -41.305734)
		(end 419.905942 -41.493694)
		(width 0.10795)
		(layer "B.Cu")
		(net "SPI_BMC_BT_DO_R")
	)
	(segment
		(start 420.8018 -43.437556)
		(end 420.8018 -43.951906)
		(width 0.089408)
		(layer "B.Cu")
		(net "SPI_BMC_BT_DO_R")
	)
	(segment
		(start 419.894004 -40.13835)
		(end 419.894004 -41.293796)
		(width 0.10795)
		(layer "B.Cu")
		(net "SPI_BMC_BT_DO_R")
	)
	(segment
		(start 430.385474 -44.282868)
		(end 430.385474 -44.2849)
		(width 0.10795)
		(layer "F.Cu")
		(net "SPI_BMC_BT_CLK_R")
	)
	(segment
		(start 430.385474 -44.2849)
		(end 430.8856 -44.2849)
		(width 0.10795)
		(layer "F.Cu")
		(net "SPI_BMC_BT_CLK_R")
	)
	(segment
		(start 426.4914 -42.828464)
		(end 426.948854 -43.285918)
		(width 0.10795)
		(layer "F.Cu")
		(net "SPI_BMC_BT_CLK_R")
	)
	(segment
		(start 426.4914 -42.6974)
		(end 426.4914 -42.828464)
		(width 0.10795)
		(layer "F.Cu")
		(net "SPI_BMC_BT_CLK_R")
	)
	(segment
		(start 423.800778 -40.53459)
		(end 424.32859 -40.53459)
		(width 0.10795)
		(layer "F.Cu")
		(net "SPI_BMC_BT_CLK_R")
	)
	(segment
		(start 423.090086 -40.13454)
		(end 423.400728 -40.13454)
		(width 0.10795)
		(layer "F.Cu")
		(net "SPI_BMC_BT_CLK_R")
	)
	(segment
		(start 429.83404 -43.731434)
		(end 430.385474 -44.282868)
		(width 0.10795)
		(layer "F.Cu")
		(net "SPI_BMC_BT_CLK_R")
	)
	(segment
		(start 423.400728 -40.13454)
		(end 423.800778 -40.53459)
		(width 0.10795)
		(layer "F.Cu")
		(net "SPI_BMC_BT_CLK_R")
	)
	(segment
		(start 426.948854 -43.285918)
		(end 427.39437 -43.731434)
		(width 0.10795)
		(layer "F.Cu")
		(net "SPI_BMC_BT_CLK_R")
	)
	(segment
		(start 424.32859 -40.53459)
		(end 426.4914 -42.6974)
		(width 0.10795)
		(layer "F.Cu")
		(net "SPI_BMC_BT_CLK_R")
	)
	(segment
		(start 427.39437 -43.731434)
		(end 429.83404 -43.731434)
		(width 0.10795)
		(layer "F.Cu")
		(net "SPI_BMC_BT_CLK_R")
	)
	(via
		(at 426.948854 -43.285918)
		(size 0.762)
		(drill 0.381)
		(layers "F.Cu" "B.Cu")
		(net "SPI_BMC_BT_CLK_R")
	)
	(segment
		(start 405.216106 -39.334694)
		(end 407.090118 -39.334694)
		(width 0.10795)
		(layer "F.Cu")
		(net "LED_POSTCODE_4")
	)
	(segment
		(start 404.3553 -40.1955)
		(end 405.216106 -39.334694)
		(width 0.10795)
		(layer "F.Cu")
		(net "LED_POSTCODE_4")
	)
	(via
		(at 390.773412 -90.397076)
		(size 0.508)
		(drill 0.254)
		(layers "F.Cu" "B.Cu")
		(net "LED_POSTCODE_4")
	)
	(via
		(at 404.3553 -40.1955)
		(size 0.4572)
		(drill 0.2032)
		(layers "F.Cu" "B.Cu")
		(net "LED_POSTCODE_4")
	)
	(via
		(at 488.442 -144.4498)
		(size 0.508)
		(drill 0.254)
		(layers "F.Cu" "B.Cu")
		(net "LED_POSTCODE_4")
	)
	(via
		(at 489.1532 -144.145)
		(size 0.6604)
		(drill 0.3302)
		(layers "F.Cu" "B.Cu")
		(net "LED_POSTCODE_4")
	)
	(via
		(at 403.915372 -89.15273)
		(size 0.508)
		(drill 0.254)
		(layers "F.Cu" "B.Cu")
		(net "LED_POSTCODE_4")
	)
	(segment
		(start 488.8992 -144.0688)
		(end 488.5182 -144.4498)
		(width 0.10795)
		(layer "B.Cu")
		(net "LED_POSTCODE_4")
	)
	(segment
		(start 489.65739 -145.288)
		(end 489.65739 -144.64919)
		(width 0.10795)
		(layer "B.Cu")
		(net "LED_POSTCODE_4")
	)
	(segment
		(start 489.65739 -144.64919)
		(end 489.1532 -144.145)
		(width 0.10795)
		(layer "B.Cu")
		(net "LED_POSTCODE_4")
	)
	(segment
		(start 489.1532 -144.145)
		(end 489.077 -144.0688)
		(width 0.10795)
		(layer "B.Cu")
		(net "LED_POSTCODE_4")
	)
	(segment
		(start 488.5182 -144.4498)
		(end 488.442 -144.4498)
		(width 0.10795)
		(layer "B.Cu")
		(net "LED_POSTCODE_4")
	)
	(segment
		(start 489.077 -144.0688)
		(end 488.8992 -144.0688)
		(width 0.10795)
		(layer "B.Cu")
		(net "LED_POSTCODE_4")
	)
	(segment
		(start 491.390432 -127.117856)
		(end 492.694214 -128.421638)
		(width 0.089408)
		(layer "In2.Cu")
		(net "LED_POSTCODE_4")
	)
	(segment
		(start 482.733096 -125.736096)
		(end 484.114856 -127.117856)
		(width 0.089408)
		(layer "In2.Cu")
		(net "LED_POSTCODE_4")
	)
	(segment
		(start 403.915372 -89.222326)
		(end 404.74773 -90.054684)
		(width 0.089408)
		(layer "In2.Cu")
		(net "LED_POSTCODE_4")
	)
	(segment
		(start 403.915372 -89.15273)
		(end 403.915372 -89.222326)
		(width 0.089408)
		(layer "In2.Cu")
		(net "LED_POSTCODE_4")
	)
	(segment
		(start 414.903158 -118.017798)
		(end 415.38398 -118.017798)
		(width 0.089408)
		(layer "In2.Cu")
		(net "LED_POSTCODE_4")
	)
	(segment
		(start 491.8964 -141.097)
		(end 491.606078 -141.097)
		(width 0.089408)
		(layer "In2.Cu")
		(net "LED_POSTCODE_4")
	)
	(segment
		(start 416.284918 -118.918736)
		(end 421.59174 -118.918736)
		(width 0.089408)
		(layer "In2.Cu")
		(net "LED_POSTCODE_4")
	)
	(segment
		(start 436.62219 -115.831112)
		(end 466.34527 -115.831112)
		(width 0.089408)
		(layer "In2.Cu")
		(net "LED_POSTCODE_4")
	)
	(segment
		(start 421.917114 -119.24411)
		(end 423.59834 -119.24411)
		(width 0.089408)
		(layer "In2.Cu")
		(net "LED_POSTCODE_4")
	)
	(segment
		(start 404.74773 -98.023934)
		(end 405.344376 -98.62058)
		(width 0.089408)
		(layer "In2.Cu")
		(net "LED_POSTCODE_4")
	)
	(segment
		(start 466.34527 -115.831112)
		(end 466.70595 -116.191792)
		(width 0.089408)
		(layer "In2.Cu")
		(net "LED_POSTCODE_4")
	)
	(segment
		(start 409.00731 -109.135418)
		(end 409.00731 -111.92383)
		(width 0.089408)
		(layer "In2.Cu")
		(net "LED_POSTCODE_4")
	)
	(segment
		(start 495.084608 -134.648448)
		(end 495.084608 -136.039352)
		(width 0.089408)
		(layer "In2.Cu")
		(net "LED_POSTCODE_4")
	)
	(segment
		(start 428.24146 -119.066056)
		(end 433.387246 -119.066056)
		(width 0.089408)
		(layer "In2.Cu")
		(net "LED_POSTCODE_4")
	)
	(segment
		(start 408.899868 -104.01554)
		(end 408.899868 -109.027976)
		(width 0.089408)
		(layer "In2.Cu")
		(net "LED_POSTCODE_4")
	)
	(segment
		(start 492.694214 -132.258054)
		(end 495.084608 -134.648448)
		(width 0.089408)
		(layer "In2.Cu")
		(net "LED_POSTCODE_4")
	)
	(segment
		(start 421.59174 -118.918736)
		(end 421.917114 -119.24411)
		(width 0.089408)
		(layer "In2.Cu")
		(net "LED_POSTCODE_4")
	)
	(segment
		(start 409.70835 -112.883696)
		(end 410.515054 -113.6904)
		(width 0.089408)
		(layer "In2.Cu")
		(net "LED_POSTCODE_4")
	)
	(segment
		(start 488.15879 -144.16659)
		(end 488.442 -144.4498)
		(width 0.089408)
		(layer "In2.Cu")
		(net "LED_POSTCODE_4")
	)
	(segment
		(start 491.004606 -141.698472)
		(end 490.491272 -141.698472)
		(width 0.089408)
		(layer "In2.Cu")
		(net "LED_POSTCODE_4")
	)
	(segment
		(start 412.965392 -116.080032)
		(end 414.903158 -118.017798)
		(width 0.089408)
		(layer "In2.Cu")
		(net "LED_POSTCODE_4")
	)
	(segment
		(start 479.737928 -120.49506)
		(end 482.733096 -123.490228)
		(width 0.089408)
		(layer "In2.Cu")
		(net "LED_POSTCODE_4")
	)
	(segment
		(start 409.38577 -112.883696)
		(end 409.70835 -112.883696)
		(width 0.089408)
		(layer "In2.Cu")
		(net "LED_POSTCODE_4")
	)
	(segment
		(start 424.196002 -118.646448)
		(end 427.821852 -118.646448)
		(width 0.089408)
		(layer "In2.Cu")
		(net "LED_POSTCODE_4")
	)
	(segment
		(start 415.38398 -118.017798)
		(end 416.284918 -118.918736)
		(width 0.089408)
		(layer "In2.Cu")
		(net "LED_POSTCODE_4")
	)
	(segment
		(start 495.408712 -136.363456)
		(end 495.408712 -137.584688)
		(width 0.089408)
		(layer "In2.Cu")
		(net "LED_POSTCODE_4")
	)
	(segment
		(start 404.74773 -90.054684)
		(end 404.74773 -98.023934)
		(width 0.089408)
		(layer "In2.Cu")
		(net "LED_POSTCODE_4")
	)
	(segment
		(start 406.903936 -102.685596)
		(end 407.569924 -102.685596)
		(width 0.089408)
		(layer "In2.Cu")
		(net "LED_POSTCODE_4")
	)
	(segment
		(start 477.5073 -116.644166)
		(end 479.737928 -118.874794)
		(width 0.089408)
		(layer "In2.Cu")
		(net "LED_POSTCODE_4")
	)
	(segment
		(start 466.70595 -116.191792)
		(end 469.626696 -116.191792)
		(width 0.089408)
		(layer "In2.Cu")
		(net "LED_POSTCODE_4")
	)
	(segment
		(start 469.626696 -116.191792)
		(end 470.07907 -116.644166)
		(width 0.089408)
		(layer "In2.Cu")
		(net "LED_POSTCODE_4")
	)
	(segment
		(start 482.733096 -123.490228)
		(end 482.733096 -125.736096)
		(width 0.089408)
		(layer "In2.Cu")
		(net "LED_POSTCODE_4")
	)
	(segment
		(start 495.084608 -136.039352)
		(end 495.408712 -136.363456)
		(width 0.089408)
		(layer "In2.Cu")
		(net "LED_POSTCODE_4")
	)
	(segment
		(start 492.694214 -128.421638)
		(end 492.694214 -132.258054)
		(width 0.089408)
		(layer "In2.Cu")
		(net "LED_POSTCODE_4")
	)
	(segment
		(start 409.090368 -112.588294)
		(end 409.38577 -112.883696)
		(width 0.089408)
		(layer "In2.Cu")
		(net "LED_POSTCODE_4")
	)
	(segment
		(start 412.496 -113.6904)
		(end 412.965392 -114.159792)
		(width 0.089408)
		(layer "In2.Cu")
		(net "LED_POSTCODE_4")
	)
	(segment
		(start 479.737928 -118.874794)
		(end 479.737928 -120.49506)
		(width 0.089408)
		(layer "In2.Cu")
		(net "LED_POSTCODE_4")
	)
	(segment
		(start 405.344376 -98.62058)
		(end 405.344376 -101.126036)
		(width 0.089408)
		(layer "In2.Cu")
		(net "LED_POSTCODE_4")
	)
	(segment
		(start 408.899868 -109.027976)
		(end 409.00731 -109.135418)
		(width 0.089408)
		(layer "In2.Cu")
		(net "LED_POSTCODE_4")
	)
	(segment
		(start 433.387246 -119.066056)
		(end 436.62219 -115.831112)
		(width 0.089408)
		(layer "In2.Cu")
		(net "LED_POSTCODE_4")
	)
	(segment
		(start 470.07907 -116.644166)
		(end 477.5073 -116.644166)
		(width 0.089408)
		(layer "In2.Cu")
		(net "LED_POSTCODE_4")
	)
	(segment
		(start 484.114856 -127.117856)
		(end 491.390432 -127.117856)
		(width 0.089408)
		(layer "In2.Cu")
		(net "LED_POSTCODE_4")
	)
	(segment
		(start 488.637834 -142.7988)
		(end 488.15879 -143.277844)
		(width 0.089408)
		(layer "In2.Cu")
		(net "LED_POSTCODE_4")
	)
	(segment
		(start 423.59834 -119.24411)
		(end 424.196002 -118.646448)
		(width 0.089408)
		(layer "In2.Cu")
		(net "LED_POSTCODE_4")
	)
	(segment
		(start 495.408712 -137.584688)
		(end 491.8964 -141.097)
		(width 0.089408)
		(layer "In2.Cu")
		(net "LED_POSTCODE_4")
	)
	(segment
		(start 427.821852 -118.646448)
		(end 428.24146 -119.066056)
		(width 0.089408)
		(layer "In2.Cu")
		(net "LED_POSTCODE_4")
	)
	(segment
		(start 490.491272 -141.698472)
		(end 489.390944 -142.7988)
		(width 0.089408)
		(layer "In2.Cu")
		(net "LED_POSTCODE_4")
	)
	(segment
		(start 489.390944 -142.7988)
		(end 488.637834 -142.7988)
		(width 0.089408)
		(layer "In2.Cu")
		(net "LED_POSTCODE_4")
	)
	(segment
		(start 405.344376 -101.126036)
		(end 406.903936 -102.685596)
		(width 0.089408)
		(layer "In2.Cu")
		(net "LED_POSTCODE_4")
	)
	(segment
		(start 407.569924 -102.685596)
		(end 408.899868 -104.01554)
		(width 0.089408)
		(layer "In2.Cu")
		(net "LED_POSTCODE_4")
	)
	(segment
		(start 491.606078 -141.097)
		(end 491.004606 -141.698472)
		(width 0.089408)
		(layer "In2.Cu")
		(net "LED_POSTCODE_4")
	)
	(segment
		(start 409.00731 -111.92383)
		(end 409.090368 -112.006888)
		(width 0.089408)
		(layer "In2.Cu")
		(net "LED_POSTCODE_4")
	)
	(segment
		(start 409.090368 -112.006888)
		(end 409.090368 -112.588294)
		(width 0.089408)
		(layer "In2.Cu")
		(net "LED_POSTCODE_4")
	)
	(segment
		(start 488.15879 -143.277844)
		(end 488.15879 -144.16659)
		(width 0.089408)
		(layer "In2.Cu")
		(net "LED_POSTCODE_4")
	)
	(segment
		(start 412.965392 -114.159792)
		(end 412.965392 -116.080032)
		(width 0.089408)
		(layer "In2.Cu")
		(net "LED_POSTCODE_4")
	)
	(segment
		(start 410.515054 -113.6904)
		(end 412.496 -113.6904)
		(width 0.089408)
		(layer "In2.Cu")
		(net "LED_POSTCODE_4")
	)
	(segment
		(start 393.696444 -89.351104)
		(end 393.68984 -89.3445)
		(width 0.089408)
		(layer "In4.Cu")
		(net "LED_POSTCODE_4")
	)
	(segment
		(start 391.924032 -87.949024)
		(end 390.739122 -87.949024)
		(width 0.089408)
		(layer "In4.Cu")
		(net "LED_POSTCODE_4")
	)
	(segment
		(start 392.24077 -87.94877)
		(end 391.924286 -87.94877)
		(width 0.089408)
		(layer "In4.Cu")
		(net "LED_POSTCODE_4")
	)
	(segment
		(start 403.915372 -89.15273)
		(end 403.915372 -89.13241)
		(width 0.089408)
		(layer "In4.Cu")
		(net "LED_POSTCODE_4")
	)
	(segment
		(start 397.473424 -88.691974)
		(end 396.60195 -89.563448)
		(width 0.089408)
		(layer "In4.Cu")
		(net "LED_POSTCODE_4")
	)
	(segment
		(start 393.68984 -89.3445)
		(end 393.6365 -89.3445)
		(width 0.089408)
		(layer "In4.Cu")
		(net "LED_POSTCODE_4")
	)
	(segment
		(start 395.998446 -89.563448)
		(end 395.786102 -89.351104)
		(width 0.089408)
		(layer "In4.Cu")
		(net "LED_POSTCODE_4")
	)
	(segment
		(start 390.373108 -88.315038)
		(end 390.373108 -89.996772)
		(width 0.089408)
		(layer "In4.Cu")
		(net "LED_POSTCODE_4")
	)
	(segment
		(start 403.915372 -89.13241)
		(end 403.535642 -88.75268)
		(width 0.089408)
		(layer "In4.Cu")
		(net "LED_POSTCODE_4")
	)
	(segment
		(start 390.373108 -89.996772)
		(end 390.773412 -90.397076)
		(width 0.089408)
		(layer "In4.Cu")
		(net "LED_POSTCODE_4")
	)
	(segment
		(start 402.917406 -88.75268)
		(end 402.479002 -89.191084)
		(width 0.089408)
		(layer "In4.Cu")
		(net "LED_POSTCODE_4")
	)
	(segment
		(start 399.193004 -89.191084)
		(end 398.693894 -88.691974)
		(width 0.089408)
		(layer "In4.Cu")
		(net "LED_POSTCODE_4")
	)
	(segment
		(start 391.924286 -87.94877)
		(end 391.924032 -87.949024)
		(width 0.089408)
		(layer "In4.Cu")
		(net "LED_POSTCODE_4")
	)
	(segment
		(start 398.693894 -88.691974)
		(end 397.473424 -88.691974)
		(width 0.089408)
		(layer "In4.Cu")
		(net "LED_POSTCODE_4")
	)
	(segment
		(start 395.786102 -89.351104)
		(end 393.696444 -89.351104)
		(width 0.089408)
		(layer "In4.Cu")
		(net "LED_POSTCODE_4")
	)
	(segment
		(start 402.479002 -89.191084)
		(end 399.193004 -89.191084)
		(width 0.089408)
		(layer "In4.Cu")
		(net "LED_POSTCODE_4")
	)
	(segment
		(start 393.6365 -89.3445)
		(end 392.24077 -87.94877)
		(width 0.089408)
		(layer "In4.Cu")
		(net "LED_POSTCODE_4")
	)
	(segment
		(start 396.60195 -89.563448)
		(end 395.998446 -89.563448)
		(width 0.089408)
		(layer "In4.Cu")
		(net "LED_POSTCODE_4")
	)
	(segment
		(start 390.739122 -87.949024)
		(end 390.373108 -88.315038)
		(width 0.089408)
		(layer "In4.Cu")
		(net "LED_POSTCODE_4")
	)
	(segment
		(start 403.535642 -88.75268)
		(end 402.917406 -88.75268)
		(width 0.089408)
		(layer "In4.Cu")
		(net "LED_POSTCODE_4")
	)
	(segment
		(start 399.924016 -56.810148)
		(end 399.924016 -56.695848)
		(width 0.089408)
		(layer "In9.Cu")
		(net "LED_POSTCODE_4")
	)
	(segment
		(start 396.598648 -75.028806)
		(end 397.1036 -74.523854)
		(width 0.089408)
		(layer "In9.Cu")
		(net "LED_POSTCODE_4")
	)
	(segment
		(start 399.924016 -55.269384)
		(end 399.924016 -47.84979)
		(width 0.089408)
		(layer "In9.Cu")
		(net "LED_POSTCODE_4")
	)
	(segment
		(start 400.229832 -63.17107)
		(end 401.57146 -61.829442)
		(width 0.089408)
		(layer "In9.Cu")
		(net "LED_POSTCODE_4")
	)
	(segment
		(start 390.373108 -88.910414)
		(end 393.197842 -86.08568)
		(width 0.089408)
		(layer "In9.Cu")
		(net "LED_POSTCODE_4")
	)
	(segment
		(start 393.197842 -86.08568)
		(end 393.391644 -86.08568)
		(width 0.089408)
		(layer "In9.Cu")
		(net "LED_POSTCODE_4")
	)
	(segment
		(start 395.941804 -79.932276)
		(end 395.26591 -79.256382)
		(width 0.089408)
		(layer "In9.Cu")
		(net "LED_POSTCODE_4")
	)
	(segment
		(start 390.373108 -89.996772)
		(end 390.373108 -88.910414)
		(width 0.089408)
		(layer "In9.Cu")
		(net "LED_POSTCODE_4")
	)
	(segment
		(start 400.229832 -66.014854)
		(end 400.229832 -63.17107)
		(width 0.089408)
		(layer "In9.Cu")
		(net "LED_POSTCODE_4")
	)
	(segment
		(start 399.923762 -55.269638)
		(end 399.924016 -55.269384)
		(width 0.089408)
		(layer "In9.Cu")
		(net "LED_POSTCODE_4")
	)
	(segment
		(start 401.571206 -61.512704)
		(end 401.571206 -61.037724)
		(width 0.089408)
		(layer "In9.Cu")
		(net "LED_POSTCODE_4")
	)
	(segment
		(start 390.773412 -90.397076)
		(end 390.373108 -89.996772)
		(width 0.089408)
		(layer "In9.Cu")
		(net "LED_POSTCODE_4")
	)
	(segment
		(start 393.391644 -86.08568)
		(end 394.361416 -85.115908)
		(width 0.089408)
		(layer "In9.Cu")
		(net "LED_POSTCODE_4")
	)
	(segment
		(start 397.97736 -70.936358)
		(end 397.97736 -68.267326)
		(width 0.089408)
		(layer "In9.Cu")
		(net "LED_POSTCODE_4")
	)
	(segment
		(start 394.955014 -83.532726)
		(end 394.955014 -82.838798)
		(width 0.089408)
		(layer "In9.Cu")
		(net "LED_POSTCODE_4")
	)
	(segment
		(start 395.26591 -77.811122)
		(end 396.598648 -76.478384)
		(width 0.089408)
		(layer "In9.Cu")
		(net "LED_POSTCODE_4")
	)
	(segment
		(start 399.924016 -47.84979)
		(end 402.394674 -45.379132)
		(width 0.089408)
		(layer "In9.Cu")
		(net "LED_POSTCODE_4")
	)
	(segment
		(start 402.394674 -45.379132)
		(end 402.394674 -44.406312)
		(width 0.089408)
		(layer "In9.Cu")
		(net "LED_POSTCODE_4")
	)
	(segment
		(start 401.57146 -61.512958)
		(end 401.571206 -61.512704)
		(width 0.089408)
		(layer "In9.Cu")
		(net "LED_POSTCODE_4")
	)
	(segment
		(start 397.1036 -73.368662)
		(end 397.371062 -73.1012)
		(width 0.089408)
		(layer "In9.Cu")
		(net "LED_POSTCODE_4")
	)
	(segment
		(start 401.570952 -58.457084)
		(end 399.924016 -56.810148)
		(width 0.089408)
		(layer "In9.Cu")
		(net "LED_POSTCODE_4")
	)
	(segment
		(start 399.923762 -56.695594)
		(end 399.923762 -55.269638)
		(width 0.089408)
		(layer "In9.Cu")
		(net "LED_POSTCODE_4")
	)
	(segment
		(start 399.924016 -56.695848)
		(end 399.923762 -56.695594)
		(width 0.089408)
		(layer "In9.Cu")
		(net "LED_POSTCODE_4")
	)
	(segment
		(start 401.571206 -61.037724)
		(end 401.570952 -61.03747)
		(width 0.089408)
		(layer "In9.Cu")
		(net "LED_POSTCODE_4")
	)
	(segment
		(start 397.371062 -71.542656)
		(end 397.97736 -70.936358)
		(width 0.089408)
		(layer "In9.Cu")
		(net "LED_POSTCODE_4")
	)
	(segment
		(start 397.97736 -68.267326)
		(end 400.229832 -66.014854)
		(width 0.089408)
		(layer "In9.Cu")
		(net "LED_POSTCODE_4")
	)
	(segment
		(start 397.371062 -73.1012)
		(end 397.371062 -71.542656)
		(width 0.089408)
		(layer "In9.Cu")
		(net "LED_POSTCODE_4")
	)
	(segment
		(start 403.282404 -43.518582)
		(end 403.282404 -41.268396)
		(width 0.089408)
		(layer "In9.Cu")
		(net "LED_POSTCODE_4")
	)
	(segment
		(start 402.394674 -44.406312)
		(end 403.282404 -43.518582)
		(width 0.089408)
		(layer "In9.Cu")
		(net "LED_POSTCODE_4")
	)
	(segment
		(start 394.361416 -85.115908)
		(end 394.361416 -84.126324)
		(width 0.089408)
		(layer "In9.Cu")
		(net "LED_POSTCODE_4")
	)
	(segment
		(start 394.955014 -82.838798)
		(end 395.941804 -81.852008)
		(width 0.089408)
		(layer "In9.Cu")
		(net "LED_POSTCODE_4")
	)
	(segment
		(start 395.26591 -79.256382)
		(end 395.26591 -77.811122)
		(width 0.089408)
		(layer "In9.Cu")
		(net "LED_POSTCODE_4")
	)
	(segment
		(start 401.570952 -61.03747)
		(end 401.570952 -58.457084)
		(width 0.089408)
		(layer "In9.Cu")
		(net "LED_POSTCODE_4")
	)
	(segment
		(start 403.282404 -41.268396)
		(end 404.3553 -40.1955)
		(width 0.089408)
		(layer "In9.Cu")
		(net "LED_POSTCODE_4")
	)
	(segment
		(start 396.598648 -76.478384)
		(end 396.598648 -75.028806)
		(width 0.089408)
		(layer "In9.Cu")
		(net "LED_POSTCODE_4")
	)
	(segment
		(start 394.361416 -84.126324)
		(end 394.955014 -83.532726)
		(width 0.089408)
		(layer "In9.Cu")
		(net "LED_POSTCODE_4")
	)
	(segment
		(start 397.1036 -74.523854)
		(end 397.1036 -73.368662)
		(width 0.089408)
		(layer "In9.Cu")
		(net "LED_POSTCODE_4")
	)
	(segment
		(start 395.941804 -81.852008)
		(end 395.941804 -79.932276)
		(width 0.089408)
		(layer "In9.Cu")
		(net "LED_POSTCODE_4")
	)
	(segment
		(start 401.57146 -61.829442)
		(end 401.57146 -61.512958)
		(width 0.089408)
		(layer "In9.Cu")
		(net "LED_POSTCODE_4")
	)
	(segment
		(start 414.08096 -92.735146)
		(end 413.486854 -92.735146)
		(width 0.10795)
		(layer "F.Cu")
		(net "LED_POSTCODE_3")
	)
	(segment
		(start 413.486854 -92.735146)
		(end 412.877 -93.345)
		(width 0.10795)
		(layer "F.Cu")
		(net "LED_POSTCODE_3")
	)
	(segment
		(start 408.690064 -39.334694)
		(end 408.290014 -39.734744)
		(width 0.10795)
		(layer "F.Cu")
		(net "LED_POSTCODE_3")
	)
	(segment
		(start 489.3945 -144.653)
		(end 488.5944 -143.8529)
		(width 0.10795)
		(layer "F.Cu")
		(net "LED_POSTCODE_3")
	)
	(segment
		(start 489.3945 -144.638268)
		(end 489.3945 -144.653)
		(width 0.10795)
		(layer "F.Cu")
		(net "LED_POSTCODE_3")
	)
	(segment
		(start 488.5944 -143.8529)
		(end 488.5944 -143.5354)
		(width 0.10795)
		(layer "F.Cu")
		(net "LED_POSTCODE_3")
	)
	(via
		(at 488.5944 -143.5354)
		(size 0.508)
		(drill 0.254)
		(layers "F.Cu" "B.Cu")
		(net "LED_POSTCODE_3")
	)
	(via
		(at 414.08096 -92.735146)
		(size 0.508)
		(drill 0.254)
		(layers "F.Cu" "B.Cu")
		(net "LED_POSTCODE_3")
	)
	(via
		(at 390.773412 -89.736676)
		(size 0.508)
		(drill 0.254)
		(layers "F.Cu" "B.Cu")
		(net "LED_POSTCODE_3")
	)
	(via
		(at 412.877 -93.345)
		(size 0.762)
		(drill 0.381)
		(layers "F.Cu" "B.Cu")
		(net "LED_POSTCODE_3")
	)
	(via
		(at 408.290014 -39.734744)
		(size 0.4572)
		(drill 0.2032)
		(layers "F.Cu" "B.Cu")
		(net "LED_POSTCODE_3")
	)
	(segment
		(start 492.885222 -132.178806)
		(end 492.885222 -128.34239)
		(width 0.089408)
		(layer "In2.Cu")
		(net "LED_POSTCODE_3")
	)
	(segment
		(start 414.624012 -94.070932)
		(end 414.624012 -93.278198)
		(width 0.089408)
		(layer "In2.Cu")
		(net "LED_POSTCODE_3")
	)
	(segment
		(start 416.87242 -117.887242)
		(end 415.223452 -116.238274)
		(width 0.089408)
		(layer "In2.Cu")
		(net "LED_POSTCODE_3")
	)
	(segment
		(start 488.9246 -143.5354)
		(end 490.57052 -141.88948)
		(width 0.089408)
		(layer "In2.Cu")
		(net "LED_POSTCODE_3")
	)
	(segment
		(start 415.02711 -95.014034)
		(end 415.02711 -94.47403)
		(width 0.089408)
		(layer "In2.Cu")
		(net "LED_POSTCODE_3")
	)
	(segment
		(start 491.374176 -141.88948)
		(end 495.59972 -137.663936)
		(width 0.089408)
		(layer "In2.Cu")
		(net "LED_POSTCODE_3")
	)
	(segment
		(start 415.173668 -106.940858)
		(end 415.971736 -106.14279)
		(width 0.089408)
		(layer "In2.Cu")
		(net "LED_POSTCODE_3")
	)
	(segment
		(start 495.59972 -137.663936)
		(end 495.59972 -136.284208)
		(width 0.089408)
		(layer "In2.Cu")
		(net "LED_POSTCODE_3")
	)
	(segment
		(start 423.144696 -117.316504)
		(end 422.573958 -117.887242)
		(width 0.089408)
		(layer "In2.Cu")
		(net "LED_POSTCODE_3")
	)
	(segment
		(start 436.542942 -115.640104)
		(end 433.307998 -118.875048)
		(width 0.089408)
		(layer "In2.Cu")
		(net "LED_POSTCODE_3")
	)
	(segment
		(start 415.223452 -116.238274)
		(end 415.223452 -112.59058)
		(width 0.089408)
		(layer "In2.Cu")
		(net "LED_POSTCODE_3")
	)
	(segment
		(start 422.573958 -117.887242)
		(end 416.87242 -117.887242)
		(width 0.089408)
		(layer "In2.Cu")
		(net "LED_POSTCODE_3")
	)
	(segment
		(start 424.61942 -117.316504)
		(end 423.144696 -117.316504)
		(width 0.089408)
		(layer "In2.Cu")
		(net "LED_POSTCODE_3")
	)
	(segment
		(start 490.57052 -141.88948)
		(end 491.374176 -141.88948)
		(width 0.089408)
		(layer "In2.Cu")
		(net "LED_POSTCODE_3")
	)
	(segment
		(start 415.971736 -106.14279)
		(end 415.971736 -104.47147)
		(width 0.089408)
		(layer "In2.Cu")
		(net "LED_POSTCODE_3")
	)
	(segment
		(start 425.147486 -117.84457)
		(end 424.61942 -117.316504)
		(width 0.089408)
		(layer "In2.Cu")
		(net "LED_POSTCODE_3")
	)
	(segment
		(start 488.5944 -143.5354)
		(end 488.9246 -143.5354)
		(width 0.089408)
		(layer "In2.Cu")
		(net "LED_POSTCODE_3")
	)
	(segment
		(start 414.624012 -93.278198)
		(end 414.08096 -92.735146)
		(width 0.089408)
		(layer "In2.Cu")
		(net "LED_POSTCODE_3")
	)
	(segment
		(start 492.885222 -128.34239)
		(end 491.451392 -126.90856)
		(width 0.089408)
		(layer "In2.Cu")
		(net "LED_POSTCODE_3")
	)
	(segment
		(start 484.9749 -125.164342)
		(end 479.928936 -120.118378)
		(width 0.089408)
		(layer "In2.Cu")
		(net "LED_POSTCODE_3")
	)
	(segment
		(start 415.971736 -104.47147)
		(end 415.517076 -104.01681)
		(width 0.089408)
		(layer "In2.Cu")
		(net "LED_POSTCODE_3")
	)
	(segment
		(start 433.307998 -118.875048)
		(end 430.420018 -118.875048)
		(width 0.089408)
		(layer "In2.Cu")
		(net "LED_POSTCODE_3")
	)
	(segment
		(start 414.950656 -112.000792)
		(end 414.950656 -109.311948)
		(width 0.089408)
		(layer "In2.Cu")
		(net "LED_POSTCODE_3")
	)
	(segment
		(start 484.9749 -126.1364)
		(end 484.9749 -125.164342)
		(width 0.089408)
		(layer "In2.Cu")
		(net "LED_POSTCODE_3")
	)
	(segment
		(start 415.517076 -104.01681)
		(end 415.517076 -95.504)
		(width 0.089408)
		(layer "In2.Cu")
		(net "LED_POSTCODE_3")
	)
	(segment
		(start 414.950402 -112.31753)
		(end 414.950402 -112.001046)
		(width 0.089408)
		(layer "In2.Cu")
		(net "LED_POSTCODE_3")
	)
	(segment
		(start 425.148502 -117.84457)
		(end 425.147486 -117.84457)
		(width 0.089408)
		(layer "In2.Cu")
		(net "LED_POSTCODE_3")
	)
	(segment
		(start 495.275616 -134.5692)
		(end 492.885222 -132.178806)
		(width 0.089408)
		(layer "In2.Cu")
		(net "LED_POSTCODE_3")
	)
	(segment
		(start 491.451392 -126.90856)
		(end 485.74706 -126.90856)
		(width 0.089408)
		(layer "In2.Cu")
		(net "LED_POSTCODE_3")
	)
	(segment
		(start 495.59972 -136.284208)
		(end 495.275616 -135.960104)
		(width 0.089408)
		(layer "In2.Cu")
		(net "LED_POSTCODE_3")
	)
	(segment
		(start 415.02711 -94.47403)
		(end 414.624012 -94.070932)
		(width 0.089408)
		(layer "In2.Cu")
		(net "LED_POSTCODE_3")
	)
	(segment
		(start 415.173668 -109.088936)
		(end 415.173668 -106.940858)
		(width 0.089408)
		(layer "In2.Cu")
		(net "LED_POSTCODE_3")
	)
	(segment
		(start 477.134174 -116.000784)
		(end 466.785198 -116.000784)
		(width 0.089408)
		(layer "In2.Cu")
		(net "LED_POSTCODE_3")
	)
	(segment
		(start 466.785198 -116.000784)
		(end 466.424518 -115.640104)
		(width 0.089408)
		(layer "In2.Cu")
		(net "LED_POSTCODE_3")
	)
	(segment
		(start 485.74706 -126.90856)
		(end 484.9749 -126.1364)
		(width 0.089408)
		(layer "In2.Cu")
		(net "LED_POSTCODE_3")
	)
	(segment
		(start 415.517076 -95.504)
		(end 415.02711 -95.014034)
		(width 0.089408)
		(layer "In2.Cu")
		(net "LED_POSTCODE_3")
	)
	(segment
		(start 466.424518 -115.640104)
		(end 436.542942 -115.640104)
		(width 0.089408)
		(layer "In2.Cu")
		(net "LED_POSTCODE_3")
	)
	(segment
		(start 425.235116 -117.931184)
		(end 425.148502 -117.84457)
		(width 0.089408)
		(layer "In2.Cu")
		(net "LED_POSTCODE_3")
	)
	(segment
		(start 479.928936 -118.795546)
		(end 477.134174 -116.000784)
		(width 0.089408)
		(layer "In2.Cu")
		(net "LED_POSTCODE_3")
	)
	(segment
		(start 414.950656 -109.311948)
		(end 415.173668 -109.088936)
		(width 0.089408)
		(layer "In2.Cu")
		(net "LED_POSTCODE_3")
	)
	(segment
		(start 414.950402 -112.001046)
		(end 414.950656 -112.000792)
		(width 0.089408)
		(layer "In2.Cu")
		(net "LED_POSTCODE_3")
	)
	(segment
		(start 415.223452 -112.59058)
		(end 414.950402 -112.31753)
		(width 0.089408)
		(layer "In2.Cu")
		(net "LED_POSTCODE_3")
	)
	(segment
		(start 430.420018 -118.875048)
		(end 429.476154 -117.931184)
		(width 0.089408)
		(layer "In2.Cu")
		(net "LED_POSTCODE_3")
	)
	(segment
		(start 429.476154 -117.931184)
		(end 425.235116 -117.931184)
		(width 0.089408)
		(layer "In2.Cu")
		(net "LED_POSTCODE_3")
	)
	(segment
		(start 495.275616 -135.960104)
		(end 495.275616 -134.5692)
		(width 0.089408)
		(layer "In2.Cu")
		(net "LED_POSTCODE_3")
	)
	(segment
		(start 479.928936 -120.118378)
		(end 479.928936 -118.795546)
		(width 0.089408)
		(layer "In2.Cu")
		(net "LED_POSTCODE_3")
	)
	(segment
		(start 410.67736 -91.4273)
		(end 410.95803 -91.70797)
		(width 0.089408)
		(layer "In4.Cu")
		(net "LED_POSTCODE_3")
	)
	(segment
		(start 410.95803 -91.70797)
		(end 412.739586 -91.70797)
		(width 0.089408)
		(layer "In4.Cu")
		(net "LED_POSTCODE_3")
	)
	(segment
		(start 403.567138 -89.610184)
		(end 404.854664 -89.610184)
		(width 0.089408)
		(layer "In4.Cu")
		(net "LED_POSTCODE_3")
	)
	(segment
		(start 407.59634 -90.31478)
		(end 408.70886 -91.4273)
		(width 0.089408)
		(layer "In4.Cu")
		(net "LED_POSTCODE_3")
	)
	(segment
		(start 403.510242 -89.553288)
		(end 403.567138 -89.610184)
		(width 0.089408)
		(layer "In4.Cu")
		(net "LED_POSTCODE_3")
	)
	(segment
		(start 394.393674 -89.8652)
		(end 394.957554 -90.42908)
		(width 0.089408)
		(layer "In4.Cu")
		(net "LED_POSTCODE_3")
	)
	(segment
		(start 402.72589 -89.553288)
		(end 403.510242 -89.553288)
		(width 0.089408)
		(layer "In4.Cu")
		(net "LED_POSTCODE_3")
	)
	(segment
		(start 404.854664 -89.610184)
		(end 405.55926 -90.31478)
		(width 0.089408)
		(layer "In4.Cu")
		(net "LED_POSTCODE_3")
	)
	(segment
		(start 408.70886 -91.4273)
		(end 410.67736 -91.4273)
		(width 0.089408)
		(layer "In4.Cu")
		(net "LED_POSTCODE_3")
	)
	(segment
		(start 390.773412 -89.736676)
		(end 391.2362 -89.273888)
		(width 0.089408)
		(layer "In4.Cu")
		(net "LED_POSTCODE_3")
	)
	(segment
		(start 413.506666 -92.47505)
		(end 413.820864 -92.47505)
		(width 0.089408)
		(layer "In4.Cu")
		(net "LED_POSTCODE_3")
	)
	(segment
		(start 405.55926 -90.31478)
		(end 407.59634 -90.31478)
		(width 0.089408)
		(layer "In4.Cu")
		(net "LED_POSTCODE_3")
	)
	(segment
		(start 391.2362 -88.392)
		(end 391.29716 -88.33104)
		(width 0.089408)
		(layer "In4.Cu")
		(net "LED_POSTCODE_3")
	)
	(segment
		(start 394.957554 -90.42908)
		(end 396.394686 -90.42908)
		(width 0.089408)
		(layer "In4.Cu")
		(net "LED_POSTCODE_3")
	)
	(segment
		(start 396.394686 -90.42908)
		(end 397.749776 -89.07399)
		(width 0.089408)
		(layer "In4.Cu")
		(net "LED_POSTCODE_3")
	)
	(segment
		(start 398.431766 -89.07399)
		(end 399.033238 -89.675462)
		(width 0.089408)
		(layer "In4.Cu")
		(net "LED_POSTCODE_3")
	)
	(segment
		(start 391.29716 -88.33104)
		(end 392.082528 -88.33104)
		(width 0.089408)
		(layer "In4.Cu")
		(net "LED_POSTCODE_3")
	)
	(segment
		(start 413.820864 -92.47505)
		(end 414.08096 -92.735146)
		(width 0.089408)
		(layer "In4.Cu")
		(net "LED_POSTCODE_3")
	)
	(segment
		(start 399.033238 -89.675462)
		(end 402.603716 -89.675462)
		(width 0.089408)
		(layer "In4.Cu")
		(net "LED_POSTCODE_3")
	)
	(segment
		(start 392.082528 -88.33104)
		(end 393.616688 -89.8652)
		(width 0.089408)
		(layer "In4.Cu")
		(net "LED_POSTCODE_3")
	)
	(segment
		(start 412.739586 -91.70797)
		(end 413.506666 -92.47505)
		(width 0.089408)
		(layer "In4.Cu")
		(net "LED_POSTCODE_3")
	)
	(segment
		(start 393.616688 -89.8652)
		(end 394.393674 -89.8652)
		(width 0.089408)
		(layer "In4.Cu")
		(net "LED_POSTCODE_3")
	)
	(segment
		(start 391.2362 -89.273888)
		(end 391.2362 -88.392)
		(width 0.089408)
		(layer "In4.Cu")
		(net "LED_POSTCODE_3")
	)
	(segment
		(start 397.749776 -89.07399)
		(end 398.431766 -89.07399)
		(width 0.089408)
		(layer "In4.Cu")
		(net "LED_POSTCODE_3")
	)
	(segment
		(start 402.603716 -89.675462)
		(end 402.72589 -89.553288)
		(width 0.089408)
		(layer "In4.Cu")
		(net "LED_POSTCODE_3")
	)
	(segment
		(start 407.635202 -40.36949)
		(end 408.269948 -39.734744)
		(width 0.089408)
		(layer "In9.Cu")
		(net "LED_POSTCODE_3")
	)
	(segment
		(start 400.306032 -48.008286)
		(end 402.77669 -45.537628)
		(width 0.089408)
		(layer "In9.Cu")
		(net "LED_POSTCODE_3")
	)
	(segment
		(start 400.305778 -56.537098)
		(end 400.305778 -55.428134)
		(width 0.089408)
		(layer "In9.Cu")
		(net "LED_POSTCODE_3")
	)
	(segment
		(start 400.611848 -63.329566)
		(end 401.953476 -61.987938)
		(width 0.089408)
		(layer "In9.Cu")
		(net "LED_POSTCODE_3")
	)
	(segment
		(start 407.377138 -40.36949)
		(end 407.635202 -40.36949)
		(width 0.089408)
		(layer "In9.Cu")
		(net "LED_POSTCODE_3")
	)
	(segment
		(start 391.760456 -88.121744)
		(end 392.598656 -88.121744)
		(width 0.089408)
		(layer "In9.Cu")
		(net "LED_POSTCODE_3")
	)
	(segment
		(start 400.611848 -66.17335)
		(end 400.611848 -63.329566)
		(width 0.089408)
		(layer "In9.Cu")
		(net "LED_POSTCODE_3")
	)
	(segment
		(start 406.262332 -41.484296)
		(end 407.377138 -40.36949)
		(width 0.089408)
		(layer "In9.Cu")
		(net "LED_POSTCODE_3")
	)
	(segment
		(start 402.77669 -45.537628)
		(end 402.77669 -44.64304)
		(width 0.089408)
		(layer "In9.Cu")
		(net "LED_POSTCODE_3")
	)
	(segment
		(start 390.773412 -89.736676)
		(end 391.1854 -89.324688)
		(width 0.089408)
		(layer "In9.Cu")
		(net "LED_POSTCODE_3")
	)
	(segment
		(start 400.306032 -56.651652)
		(end 400.306032 -56.537352)
		(width 0.089408)
		(layer "In9.Cu")
		(net "LED_POSTCODE_3")
	)
	(segment
		(start 393.936728 -86.783672)
		(end 393.936728 -86.208108)
		(width 0.089408)
		(layer "In9.Cu")
		(net "LED_POSTCODE_3")
	)
	(segment
		(start 395.647926 -77.969618)
		(end 396.980664 -76.63688)
		(width 0.089408)
		(layer "In9.Cu")
		(net "LED_POSTCODE_3")
	)
	(segment
		(start 396.32382 -82.010504)
		(end 396.32382 -79.77378)
		(width 0.089408)
		(layer "In9.Cu")
		(net "LED_POSTCODE_3")
	)
	(segment
		(start 393.936728 -86.208108)
		(end 395.4526 -84.692236)
		(width 0.089408)
		(layer "In9.Cu")
		(net "LED_POSTCODE_3")
	)
	(segment
		(start 391.1854 -89.324688)
		(end 391.1854 -88.6968)
		(width 0.089408)
		(layer "In9.Cu")
		(net "LED_POSTCODE_3")
	)
	(segment
		(start 404.031704 -41.484296)
		(end 406.262332 -41.484296)
		(width 0.089408)
		(layer "In9.Cu")
		(net "LED_POSTCODE_3")
	)
	(segment
		(start 398.403318 -68.38188)
		(end 400.611848 -66.17335)
		(width 0.089408)
		(layer "In9.Cu")
		(net "LED_POSTCODE_3")
	)
	(segment
		(start 395.4526 -82.881724)
		(end 396.32382 -82.010504)
		(width 0.089408)
		(layer "In9.Cu")
		(net "LED_POSTCODE_3")
	)
	(segment
		(start 408.269948 -39.734744)
		(end 408.290014 -39.734744)
		(width 0.089408)
		(layer "In9.Cu")
		(net "LED_POSTCODE_3")
	)
	(segment
		(start 397.753078 -73.0885)
		(end 397.753078 -71.701152)
		(width 0.089408)
		(layer "In9.Cu")
		(net "LED_POSTCODE_3")
	)
	(segment
		(start 400.305778 -55.428134)
		(end 400.306032 -55.42788)
		(width 0.089408)
		(layer "In9.Cu")
		(net "LED_POSTCODE_3")
	)
	(segment
		(start 395.4526 -84.692236)
		(end 395.4526 -82.881724)
		(width 0.089408)
		(layer "In9.Cu")
		(net "LED_POSTCODE_3")
	)
	(segment
		(start 401.952968 -58.298588)
		(end 400.306032 -56.651652)
		(width 0.089408)
		(layer "In9.Cu")
		(net "LED_POSTCODE_3")
	)
	(segment
		(start 401.953476 -61.354462)
		(end 401.953222 -61.354208)
		(width 0.089408)
		(layer "In9.Cu")
		(net "LED_POSTCODE_3")
	)
	(segment
		(start 403.675088 -43.744642)
		(end 403.675088 -41.840912)
		(width 0.089408)
		(layer "In9.Cu")
		(net "LED_POSTCODE_3")
	)
	(segment
		(start 401.953476 -61.987938)
		(end 401.953476 -61.354462)
		(width 0.089408)
		(layer "In9.Cu")
		(net "LED_POSTCODE_3")
	)
	(segment
		(start 398.175988 -74.203306)
		(end 398.175988 -73.51141)
		(width 0.089408)
		(layer "In9.Cu")
		(net "LED_POSTCODE_3")
	)
	(segment
		(start 398.403318 -69.173852)
		(end 398.403318 -68.38188)
		(width 0.089408)
		(layer "In9.Cu")
		(net "LED_POSTCODE_3")
	)
	(segment
		(start 396.980664 -75.39863)
		(end 398.175988 -74.203306)
		(width 0.089408)
		(layer "In9.Cu")
		(net "LED_POSTCODE_3")
	)
	(segment
		(start 397.753078 -71.701152)
		(end 398.403572 -71.050658)
		(width 0.089408)
		(layer "In9.Cu")
		(net "LED_POSTCODE_3")
	)
	(segment
		(start 396.980664 -76.63688)
		(end 396.980664 -75.39863)
		(width 0.089408)
		(layer "In9.Cu")
		(net "LED_POSTCODE_3")
	)
	(segment
		(start 402.77669 -44.64304)
		(end 403.675088 -43.744642)
		(width 0.089408)
		(layer "In9.Cu")
		(net "LED_POSTCODE_3")
	)
	(segment
		(start 401.953222 -61.354208)
		(end 401.953222 -60.879228)
		(width 0.089408)
		(layer "In9.Cu")
		(net "LED_POSTCODE_3")
	)
	(segment
		(start 400.306032 -55.42788)
		(end 400.306032 -48.008286)
		(width 0.089408)
		(layer "In9.Cu")
		(net "LED_POSTCODE_3")
	)
	(segment
		(start 401.952968 -60.878974)
		(end 401.952968 -58.298588)
		(width 0.089408)
		(layer "In9.Cu")
		(net "LED_POSTCODE_3")
	)
	(segment
		(start 398.403572 -71.050658)
		(end 398.403572 -69.174106)
		(width 0.089408)
		(layer "In9.Cu")
		(net "LED_POSTCODE_3")
	)
	(segment
		(start 392.598656 -88.121744)
		(end 393.936728 -86.783672)
		(width 0.089408)
		(layer "In9.Cu")
		(net "LED_POSTCODE_3")
	)
	(segment
		(start 396.32382 -79.77378)
		(end 395.647926 -79.097886)
		(width 0.089408)
		(layer "In9.Cu")
		(net "LED_POSTCODE_3")
	)
	(segment
		(start 395.647926 -79.097886)
		(end 395.647926 -77.969618)
		(width 0.089408)
		(layer "In9.Cu")
		(net "LED_POSTCODE_3")
	)
	(segment
		(start 391.1854 -88.6968)
		(end 391.760456 -88.121744)
		(width 0.089408)
		(layer "In9.Cu")
		(net "LED_POSTCODE_3")
	)
	(segment
		(start 401.953222 -60.879228)
		(end 401.952968 -60.878974)
		(width 0.089408)
		(layer "In9.Cu")
		(net "LED_POSTCODE_3")
	)
	(segment
		(start 400.306032 -56.537352)
		(end 400.305778 -56.537098)
		(width 0.089408)
		(layer "In9.Cu")
		(net "LED_POSTCODE_3")
	)
	(segment
		(start 398.403572 -69.174106)
		(end 398.403318 -69.173852)
		(width 0.089408)
		(layer "In9.Cu")
		(net "LED_POSTCODE_3")
	)
	(segment
		(start 403.675088 -41.840912)
		(end 404.031704 -41.484296)
		(width 0.089408)
		(layer "In9.Cu")
		(net "LED_POSTCODE_3")
	)
	(segment
		(start 398.175988 -73.51141)
		(end 397.753078 -73.0885)
		(width 0.089408)
		(layer "In9.Cu")
		(net "LED_POSTCODE_3")
	)
	(segment
		(start 489.3945 -142.1511)
		(end 489.3564 -142.113)
		(width 0.10795)
		(layer "F.Cu")
		(net "LED_POSTCODE_2")
	)
	(segment
		(start 489.3945 -143.876268)
		(end 489.3945 -142.1511)
		(width 0.10795)
		(layer "F.Cu")
		(net "LED_POSTCODE_2")
	)
	(segment
		(start 409.490164 -39.334694)
		(end 409.090114 -38.934644)
		(width 0.10795)
		(layer "F.Cu")
		(net "LED_POSTCODE_2")
	)
	(via
		(at 403.106128 -89.152984)
		(size 0.508)
		(drill 0.254)
		(layers "F.Cu" "B.Cu")
		(net "LED_POSTCODE_2")
	)
	(via
		(at 489.3564 -142.113)
		(size 0.508)
		(drill 0.254)
		(layers "F.Cu" "B.Cu")
		(net "LED_POSTCODE_2")
	)
	(via
		(at 390.773412 -89.076276)
		(size 0.508)
		(drill 0.254)
		(layers "F.Cu" "B.Cu")
		(net "LED_POSTCODE_2")
	)
	(via
		(at 409.090114 -38.934644)
		(size 0.4572)
		(drill 0.2032)
		(layers "F.Cu" "B.Cu")
		(net "LED_POSTCODE_2")
	)
	(segment
		(start 408.89936 -112.086136)
		(end 408.816302 -112.003078)
		(width 0.089408)
		(layer "In2.Cu")
		(net "LED_POSTCODE_2")
	)
	(segment
		(start 466.626702 -116.3828)
		(end 466.266022 -116.02212)
		(width 0.089408)
		(layer "In2.Cu")
		(net "LED_POSTCODE_2")
	)
	(segment
		(start 469.999822 -116.835174)
		(end 469.547448 -116.3828)
		(width 0.089408)
		(layer "In2.Cu")
		(net "LED_POSTCODE_2")
	)
	(segment
		(start 490.925358 -141.507464)
		(end 491.615222 -140.8176)
		(width 0.089408)
		(layer "In2.Cu")
		(net "LED_POSTCODE_2")
	)
	(segment
		(start 489.962444 -141.507464)
		(end 490.925358 -141.507464)
		(width 0.089408)
		(layer "In2.Cu")
		(net "LED_POSTCODE_2")
	)
	(segment
		(start 433.466494 -119.257064)
		(end 428.162212 -119.257064)
		(width 0.089408)
		(layer "In2.Cu")
		(net "LED_POSTCODE_2")
	)
	(segment
		(start 466.266022 -116.02212)
		(end 436.701438 -116.02212)
		(width 0.089408)
		(layer "In2.Cu")
		(net "LED_POSTCODE_2")
	)
	(segment
		(start 405.153368 -98.75774)
		(end 404.525226 -98.129598)
		(width 0.089408)
		(layer "In2.Cu")
		(net "LED_POSTCODE_2")
	)
	(segment
		(start 484.055928 -127.329184)
		(end 482.542088 -125.815344)
		(width 0.089408)
		(layer "In2.Cu")
		(net "LED_POSTCODE_2")
	)
	(segment
		(start 408.816302 -112.003078)
		(end 408.816302 -109.214666)
		(width 0.089408)
		(layer "In2.Cu")
		(net "LED_POSTCODE_2")
	)
	(segment
		(start 479.498914 -120.526302)
		(end 479.498914 -118.906036)
		(width 0.089408)
		(layer "In2.Cu")
		(net "LED_POSTCODE_2")
	)
	(segment
		(start 492.4806 -128.47828)
		(end 491.331504 -127.329184)
		(width 0.089408)
		(layer "In2.Cu")
		(net "LED_POSTCODE_2")
	)
	(segment
		(start 408.89936 -113.276126)
		(end 408.89936 -112.086136)
		(width 0.089408)
		(layer "In2.Cu")
		(net "LED_POSTCODE_2")
	)
	(segment
		(start 482.542088 -123.569476)
		(end 479.498914 -120.526302)
		(width 0.089408)
		(layer "In2.Cu")
		(net "LED_POSTCODE_2")
	)
	(segment
		(start 436.701438 -116.02212)
		(end 433.466494 -119.257064)
		(width 0.089408)
		(layer "In2.Cu")
		(net "LED_POSTCODE_2")
	)
	(segment
		(start 495.217704 -137.470896)
		(end 495.217704 -136.442704)
		(width 0.089408)
		(layer "In2.Cu")
		(net "LED_POSTCODE_2")
	)
	(segment
		(start 495.217704 -136.442704)
		(end 494.8936 -136.1186)
		(width 0.089408)
		(layer "In2.Cu")
		(net "LED_POSTCODE_2")
	)
	(segment
		(start 492.4806 -132.314696)
		(end 492.4806 -128.47828)
		(width 0.089408)
		(layer "In2.Cu")
		(net "LED_POSTCODE_2")
	)
	(segment
		(start 412.75 -114.2492)
		(end 412.3944 -113.8936)
		(width 0.089408)
		(layer "In2.Cu")
		(net "LED_POSTCODE_2")
	)
	(segment
		(start 428.162212 -119.257064)
		(end 427.742604 -118.837456)
		(width 0.089408)
		(layer "In2.Cu")
		(net "LED_POSTCODE_2")
	)
	(segment
		(start 423.677588 -119.435118)
		(end 421.837866 -119.435118)
		(width 0.089408)
		(layer "In2.Cu")
		(net "LED_POSTCODE_2")
	)
	(segment
		(start 489.3564 -142.113)
		(end 489.356908 -142.113)
		(width 0.089408)
		(layer "In2.Cu")
		(net "LED_POSTCODE_2")
	)
	(segment
		(start 408.70886 -104.094788)
		(end 407.490676 -102.876604)
		(width 0.089408)
		(layer "In2.Cu")
		(net "LED_POSTCODE_2")
	)
	(segment
		(start 477.428052 -116.835174)
		(end 469.999822 -116.835174)
		(width 0.089408)
		(layer "In2.Cu")
		(net "LED_POSTCODE_2")
	)
	(segment
		(start 412.3944 -113.8936)
		(end 409.516834 -113.8936)
		(width 0.089408)
		(layer "In2.Cu")
		(net "LED_POSTCODE_2")
	)
	(segment
		(start 404.525226 -98.129598)
		(end 404.525226 -90.102436)
		(width 0.089408)
		(layer "In2.Cu")
		(net "LED_POSTCODE_2")
	)
	(segment
		(start 491.331504 -127.329184)
		(end 484.055928 -127.329184)
		(width 0.089408)
		(layer "In2.Cu")
		(net "LED_POSTCODE_2")
	)
	(segment
		(start 415.304732 -118.208806)
		(end 414.82391 -118.208806)
		(width 0.089408)
		(layer "In2.Cu")
		(net "LED_POSTCODE_2")
	)
	(segment
		(start 407.490676 -102.876604)
		(end 406.824688 -102.876604)
		(width 0.089408)
		(layer "In2.Cu")
		(net "LED_POSTCODE_2")
	)
	(segment
		(start 491.871 -140.8176)
		(end 495.217704 -137.470896)
		(width 0.089408)
		(layer "In2.Cu")
		(net "LED_POSTCODE_2")
	)
	(segment
		(start 406.824688 -102.876604)
		(end 405.153368 -101.205284)
		(width 0.089408)
		(layer "In2.Cu")
		(net "LED_POSTCODE_2")
	)
	(segment
		(start 408.816302 -109.214666)
		(end 408.70886 -109.107224)
		(width 0.089408)
		(layer "In2.Cu")
		(net "LED_POSTCODE_2")
	)
	(segment
		(start 421.512492 -119.109744)
		(end 416.20567 -119.109744)
		(width 0.089408)
		(layer "In2.Cu")
		(net "LED_POSTCODE_2")
	)
	(segment
		(start 404.525226 -90.102436)
		(end 403.99589 -89.5731)
		(width 0.089408)
		(layer "In2.Cu")
		(net "LED_POSTCODE_2")
	)
	(segment
		(start 409.516834 -113.8936)
		(end 408.89936 -113.276126)
		(width 0.089408)
		(layer "In2.Cu")
		(net "LED_POSTCODE_2")
	)
	(segment
		(start 427.742604 -118.837456)
		(end 424.27525 -118.837456)
		(width 0.089408)
		(layer "In2.Cu")
		(net "LED_POSTCODE_2")
	)
	(segment
		(start 494.8936 -136.1186)
		(end 494.8936 -134.727696)
		(width 0.089408)
		(layer "In2.Cu")
		(net "LED_POSTCODE_2")
	)
	(segment
		(start 469.547448 -116.3828)
		(end 466.626702 -116.3828)
		(width 0.089408)
		(layer "In2.Cu")
		(net "LED_POSTCODE_2")
	)
	(segment
		(start 421.837866 -119.435118)
		(end 421.512492 -119.109744)
		(width 0.089408)
		(layer "In2.Cu")
		(net "LED_POSTCODE_2")
	)
	(segment
		(start 403.329394 -89.152984)
		(end 403.106128 -89.152984)
		(width 0.089408)
		(layer "In2.Cu")
		(net "LED_POSTCODE_2")
	)
	(segment
		(start 489.356908 -142.113)
		(end 489.962444 -141.507464)
		(width 0.089408)
		(layer "In2.Cu")
		(net "LED_POSTCODE_2")
	)
	(segment
		(start 403.74951 -89.5731)
		(end 403.329394 -89.152984)
		(width 0.089408)
		(layer "In2.Cu")
		(net "LED_POSTCODE_2")
	)
	(segment
		(start 414.82391 -118.208806)
		(end 412.75 -116.134896)
		(width 0.089408)
		(layer "In2.Cu")
		(net "LED_POSTCODE_2")
	)
	(segment
		(start 403.99589 -89.5731)
		(end 403.74951 -89.5731)
		(width 0.089408)
		(layer "In2.Cu")
		(net "LED_POSTCODE_2")
	)
	(segment
		(start 412.75 -116.134896)
		(end 412.75 -114.2492)
		(width 0.089408)
		(layer "In2.Cu")
		(net "LED_POSTCODE_2")
	)
	(segment
		(start 408.70886 -109.107224)
		(end 408.70886 -104.094788)
		(width 0.089408)
		(layer "In2.Cu")
		(net "LED_POSTCODE_2")
	)
	(segment
		(start 405.153368 -101.205284)
		(end 405.153368 -98.75774)
		(width 0.089408)
		(layer "In2.Cu")
		(net "LED_POSTCODE_2")
	)
	(segment
		(start 479.498914 -118.906036)
		(end 477.428052 -116.835174)
		(width 0.089408)
		(layer "In2.Cu")
		(net "LED_POSTCODE_2")
	)
	(segment
		(start 424.27525 -118.837456)
		(end 423.677588 -119.435118)
		(width 0.089408)
		(layer "In2.Cu")
		(net "LED_POSTCODE_2")
	)
	(segment
		(start 416.20567 -119.109744)
		(end 415.304732 -118.208806)
		(width 0.089408)
		(layer "In2.Cu")
		(net "LED_POSTCODE_2")
	)
	(segment
		(start 494.8936 -134.727696)
		(end 492.4806 -132.314696)
		(width 0.089408)
		(layer "In2.Cu")
		(net "LED_POSTCODE_2")
	)
	(segment
		(start 491.615222 -140.8176)
		(end 491.871 -140.8176)
		(width 0.089408)
		(layer "In2.Cu")
		(net "LED_POSTCODE_2")
	)
	(segment
		(start 482.542088 -125.815344)
		(end 482.542088 -123.569476)
		(width 0.089408)
		(layer "In2.Cu")
		(net "LED_POSTCODE_2")
	)
	(segment
		(start 395.036802 -90.238072)
		(end 394.472922 -89.674192)
		(width 0.089408)
		(layer "In4.Cu")
		(net "LED_POSTCODE_2")
	)
	(segment
		(start 391.045192 -88.804496)
		(end 390.773412 -89.076276)
		(width 0.089408)
		(layer "In4.Cu")
		(net "LED_POSTCODE_2")
	)
	(segment
		(start 393.695936 -89.674192)
		(end 392.161522 -88.139778)
		(width 0.089408)
		(layer "In4.Cu")
		(net "LED_POSTCODE_2")
	)
	(segment
		(start 396.315438 -90.238072)
		(end 395.036802 -90.238072)
		(width 0.089408)
		(layer "In4.Cu")
		(net "LED_POSTCODE_2")
	)
	(segment
		(start 394.472922 -89.674192)
		(end 393.695936 -89.674192)
		(width 0.089408)
		(layer "In4.Cu")
		(net "LED_POSTCODE_2")
	)
	(segment
		(start 402.62683 -89.382092)
		(end 399.113756 -89.382092)
		(width 0.089408)
		(layer "In4.Cu")
		(net "LED_POSTCODE_2")
	)
	(segment
		(start 392.003534 -88.139778)
		(end 392.00328 -88.140032)
		(width 0.089408)
		(layer "In4.Cu")
		(net "LED_POSTCODE_2")
	)
	(segment
		(start 392.161522 -88.139778)
		(end 392.003534 -88.139778)
		(width 0.089408)
		(layer "In4.Cu")
		(net "LED_POSTCODE_2")
	)
	(segment
		(start 398.614646 -88.882982)
		(end 397.670528 -88.882982)
		(width 0.089408)
		(layer "In4.Cu")
		(net "LED_POSTCODE_2")
	)
	(segment
		(start 403.106128 -89.152984)
		(end 402.855938 -89.152984)
		(width 0.089408)
		(layer "In4.Cu")
		(net "LED_POSTCODE_2")
	)
	(segment
		(start 397.670528 -88.882982)
		(end 396.315438 -90.238072)
		(width 0.089408)
		(layer "In4.Cu")
		(net "LED_POSTCODE_2")
	)
	(segment
		(start 402.855938 -89.152984)
		(end 402.62683 -89.382092)
		(width 0.089408)
		(layer "In4.Cu")
		(net "LED_POSTCODE_2")
	)
	(segment
		(start 392.00328 -88.140032)
		(end 391.217912 -88.140032)
		(width 0.089408)
		(layer "In4.Cu")
		(net "LED_POSTCODE_2")
	)
	(segment
		(start 391.045192 -88.312752)
		(end 391.045192 -88.804496)
		(width 0.089408)
		(layer "In4.Cu")
		(net "LED_POSTCODE_2")
	)
	(segment
		(start 399.113756 -89.382092)
		(end 398.614646 -88.882982)
		(width 0.089408)
		(layer "In4.Cu")
		(net "LED_POSTCODE_2")
	)
	(segment
		(start 391.217912 -88.140032)
		(end 391.045192 -88.312752)
		(width 0.089408)
		(layer "In4.Cu")
		(net "LED_POSTCODE_2")
	)
	(segment
		(start 393.356084 -86.518496)
		(end 394.552424 -85.322156)
		(width 0.089408)
		(layer "In9.Cu")
		(net "LED_POSTCODE_2")
	)
	(segment
		(start 396.789656 -76.557632)
		(end 396.789656 -75.208638)
		(width 0.089408)
		(layer "In9.Cu")
		(net "LED_POSTCODE_2")
	)
	(segment
		(start 402.585682 -44.547536)
		(end 403.473412 -43.659806)
		(width 0.089408)
		(layer "In9.Cu")
		(net "LED_POSTCODE_2")
	)
	(segment
		(start 400.115024 -56.7309)
		(end 400.115024 -56.6166)
		(width 0.089408)
		(layer "In9.Cu")
		(net "LED_POSTCODE_2")
	)
	(segment
		(start 398.21231 -68.302632)
		(end 400.42084 -66.094102)
		(width 0.089408)
		(layer "In9.Cu")
		(net "LED_POSTCODE_2")
	)
	(segment
		(start 400.11477 -55.348886)
		(end 400.115024 -55.348632)
		(width 0.089408)
		(layer "In9.Cu")
		(net "LED_POSTCODE_2")
	)
	(segment
		(start 401.762214 -60.958476)
		(end 401.76196 -60.958222)
		(width 0.089408)
		(layer "In9.Cu")
		(net "LED_POSTCODE_2")
	)
	(segment
		(start 403.473412 -43.659806)
		(end 403.473412 -41.465754)
		(width 0.089408)
		(layer "In9.Cu")
		(net "LED_POSTCODE_2")
	)
	(segment
		(start 397.98498 -73.590658)
		(end 397.56207 -73.167748)
		(width 0.089408)
		(layer "In9.Cu")
		(net "LED_POSTCODE_2")
	)
	(segment
		(start 408.18562 -39.309294)
		(end 408.715464 -39.309294)
		(width 0.089408)
		(layer "In9.Cu")
		(net "LED_POSTCODE_2")
	)
	(segment
		(start 400.115024 -56.6166)
		(end 400.11477 -56.616346)
		(width 0.089408)
		(layer "In9.Cu")
		(net "LED_POSTCODE_2")
	)
	(segment
		(start 390.773412 -88.796622)
		(end 393.051538 -86.518496)
		(width 0.089408)
		(layer "In9.Cu")
		(net "LED_POSTCODE_2")
	)
	(segment
		(start 398.212564 -69.253354)
		(end 398.21231 -69.2531)
		(width 0.089408)
		(layer "In9.Cu")
		(net "LED_POSTCODE_2")
	)
	(segment
		(start 401.762468 -61.43371)
		(end 401.762214 -61.433456)
		(width 0.089408)
		(layer "In9.Cu")
		(net "LED_POSTCODE_2")
	)
	(segment
		(start 396.132812 -81.931256)
		(end 396.132812 -79.853028)
		(width 0.089408)
		(layer "In9.Cu")
		(net "LED_POSTCODE_2")
	)
	(segment
		(start 406.497536 -40.978836)
		(end 407.366724 -40.109648)
		(width 0.089408)
		(layer "In9.Cu")
		(net "LED_POSTCODE_2")
	)
	(segment
		(start 394.552424 -85.322156)
		(end 394.552424 -84.205572)
		(width 0.089408)
		(layer "In9.Cu")
		(net "LED_POSTCODE_2")
	)
	(segment
		(start 397.98498 -74.013314)
		(end 397.98498 -73.590658)
		(width 0.089408)
		(layer "In9.Cu")
		(net "LED_POSTCODE_2")
	)
	(segment
		(start 395.146022 -82.918046)
		(end 396.132812 -81.931256)
		(width 0.089408)
		(layer "In9.Cu")
		(net "LED_POSTCODE_2")
	)
	(segment
		(start 398.212564 -70.97141)
		(end 398.212564 -69.253354)
		(width 0.089408)
		(layer "In9.Cu")
		(net "LED_POSTCODE_2")
	)
	(segment
		(start 394.552424 -84.205572)
		(end 395.146022 -83.611974)
		(width 0.089408)
		(layer "In9.Cu")
		(net "LED_POSTCODE_2")
	)
	(segment
		(start 402.585682 -45.45838)
		(end 402.585682 -44.547536)
		(width 0.089408)
		(layer "In9.Cu")
		(net "LED_POSTCODE_2")
	)
	(segment
		(start 407.865072 -39.629842)
		(end 408.18562 -39.309294)
		(width 0.089408)
		(layer "In9.Cu")
		(net "LED_POSTCODE_2")
	)
	(segment
		(start 401.762214 -61.433456)
		(end 401.762214 -60.958476)
		(width 0.089408)
		(layer "In9.Cu")
		(net "LED_POSTCODE_2")
	)
	(segment
		(start 408.715464 -39.309294)
		(end 409.090114 -38.934644)
		(width 0.089408)
		(layer "In9.Cu")
		(net "LED_POSTCODE_2")
	)
	(segment
		(start 390.773412 -89.076276)
		(end 390.773412 -88.796622)
		(width 0.089408)
		(layer "In9.Cu")
		(net "LED_POSTCODE_2")
	)
	(segment
		(start 403.96033 -40.978836)
		(end 406.497536 -40.978836)
		(width 0.089408)
		(layer "In9.Cu")
		(net "LED_POSTCODE_2")
	)
	(segment
		(start 396.132812 -79.853028)
		(end 395.456918 -79.177134)
		(width 0.089408)
		(layer "In9.Cu")
		(net "LED_POSTCODE_2")
	)
	(segment
		(start 397.56207 -71.621904)
		(end 398.212564 -70.97141)
		(width 0.089408)
		(layer "In9.Cu")
		(net "LED_POSTCODE_2")
	)
	(segment
		(start 400.115024 -47.929038)
		(end 402.585682 -45.45838)
		(width 0.089408)
		(layer "In9.Cu")
		(net "LED_POSTCODE_2")
	)
	(segment
		(start 395.146022 -83.611974)
		(end 395.146022 -82.918046)
		(width 0.089408)
		(layer "In9.Cu")
		(net "LED_POSTCODE_2")
	)
	(segment
		(start 400.42084 -66.094102)
		(end 400.42084 -63.250318)
		(width 0.089408)
		(layer "In9.Cu")
		(net "LED_POSTCODE_2")
	)
	(segment
		(start 401.762468 -61.90869)
		(end 401.762468 -61.43371)
		(width 0.089408)
		(layer "In9.Cu")
		(net "LED_POSTCODE_2")
	)
	(segment
		(start 407.865072 -39.851076)
		(end 407.865072 -39.629842)
		(width 0.089408)
		(layer "In9.Cu")
		(net "LED_POSTCODE_2")
	)
	(segment
		(start 400.42084 -63.250318)
		(end 401.762468 -61.90869)
		(width 0.089408)
		(layer "In9.Cu")
		(net "LED_POSTCODE_2")
	)
	(segment
		(start 397.56207 -73.167748)
		(end 397.56207 -71.621904)
		(width 0.089408)
		(layer "In9.Cu")
		(net "LED_POSTCODE_2")
	)
	(segment
		(start 407.366724 -40.109648)
		(end 407.6065 -40.109648)
		(width 0.089408)
		(layer "In9.Cu")
		(net "LED_POSTCODE_2")
	)
	(segment
		(start 400.11477 -56.616346)
		(end 400.11477 -55.348886)
		(width 0.089408)
		(layer "In9.Cu")
		(net "LED_POSTCODE_2")
	)
	(segment
		(start 400.115024 -55.348632)
		(end 400.115024 -47.929038)
		(width 0.089408)
		(layer "In9.Cu")
		(net "LED_POSTCODE_2")
	)
	(segment
		(start 398.21231 -69.2531)
		(end 398.21231 -68.302632)
		(width 0.089408)
		(layer "In9.Cu")
		(net "LED_POSTCODE_2")
	)
	(segment
		(start 393.051538 -86.518496)
		(end 393.356084 -86.518496)
		(width 0.089408)
		(layer "In9.Cu")
		(net "LED_POSTCODE_2")
	)
	(segment
		(start 401.76196 -58.377836)
		(end 400.115024 -56.7309)
		(width 0.089408)
		(layer "In9.Cu")
		(net "LED_POSTCODE_2")
	)
	(segment
		(start 395.456918 -79.177134)
		(end 395.456918 -77.89037)
		(width 0.089408)
		(layer "In9.Cu")
		(net "LED_POSTCODE_2")
	)
	(segment
		(start 403.473412 -41.465754)
		(end 403.96033 -40.978836)
		(width 0.089408)
		(layer "In9.Cu")
		(net "LED_POSTCODE_2")
	)
	(segment
		(start 396.789656 -75.208638)
		(end 397.98498 -74.013314)
		(width 0.089408)
		(layer "In9.Cu")
		(net "LED_POSTCODE_2")
	)
	(segment
		(start 395.456918 -77.89037)
		(end 396.789656 -76.557632)
		(width 0.089408)
		(layer "In9.Cu")
		(net "LED_POSTCODE_2")
	)
	(segment
		(start 401.76196 -60.958222)
		(end 401.76196 -58.377836)
		(width 0.089408)
		(layer "In9.Cu")
		(net "LED_POSTCODE_2")
	)
	(segment
		(start 407.6065 -40.109648)
		(end 407.865072 -39.851076)
		(width 0.089408)
		(layer "In9.Cu")
		(net "LED_POSTCODE_2")
	)
	(segment
		(start 407.890218 -39.334694)
		(end 407.85161 -39.334694)
		(width 0.10795)
		(layer "F.Cu")
		(net "LED_POSTCODE_5")
	)
	(segment
		(start 407.85161 -39.334694)
		(end 407.458926 -39.727378)
		(width 0.10795)
		(layer "F.Cu")
		(net "LED_POSTCODE_5")
	)
	(via
		(at 401.327366 -90.501216)
		(size 0.6604)
		(drill 0.3302)
		(layers "F.Cu" "B.Cu")
		(net "LED_POSTCODE_5")
	)
	(via
		(at 402.971 -90.1446)
		(size 0.508)
		(drill 0.254)
		(layers "F.Cu" "B.Cu")
		(net "LED_POSTCODE_5")
	)
	(via
		(at 488.5944 -146.177)
		(size 0.508)
		(drill 0.254)
		(layers "F.Cu" "B.Cu")
		(net "LED_POSTCODE_5")
	)
	(via
		(at 390.752838 -91.912694)
		(size 0.508)
		(drill 0.254)
		(layers "F.Cu" "B.Cu")
		(net "LED_POSTCODE_5")
	)
	(via
		(at 407.458926 -39.727378)
		(size 0.4572)
		(drill 0.2032)
		(layers "F.Cu" "B.Cu")
		(net "LED_POSTCODE_5")
	)
	(segment
		(start 401.683982 -90.1446)
		(end 401.327366 -90.501216)
		(width 0.10795)
		(layer "B.Cu")
		(net "LED_POSTCODE_5")
	)
	(segment
		(start 488.5944 -146.177)
		(end 489.65739 -146.177)
		(width 0.10795)
		(layer "B.Cu")
		(net "LED_POSTCODE_5")
	)
	(segment
		(start 402.971 -90.1446)
		(end 401.683982 -90.1446)
		(width 0.10795)
		(layer "B.Cu")
		(net "LED_POSTCODE_5")
	)
	(segment
		(start 469.841326 -117.21719)
		(end 469.388952 -116.764816)
		(width 0.089408)
		(layer "In2.Cu")
		(net "LED_POSTCODE_5")
	)
	(segment
		(start 412.545784 -116.471192)
		(end 411.412436 -116.471192)
		(width 0.089408)
		(layer "In2.Cu")
		(net "LED_POSTCODE_5")
	)
	(segment
		(start 408.51709 -113.27638)
		(end 408.517344 -113.276126)
		(width 0.089408)
		(layer "In2.Cu")
		(net "LED_POSTCODE_5")
	)
	(segment
		(start 404.771352 -98.916236)
		(end 404.14321 -98.288094)
		(width 0.089408)
		(layer "In2.Cu")
		(net "LED_POSTCODE_5")
	)
	(segment
		(start 478.437702 -120.983502)
		(end 478.437702 -118.385336)
		(width 0.089408)
		(layer "In2.Cu")
		(net "LED_POSTCODE_5")
	)
	(segment
		(start 494.411 -137.9982)
		(end 494.411 -134.785608)
		(width 0.089408)
		(layer "In2.Cu")
		(net "LED_POSTCODE_5")
	)
	(segment
		(start 483.629208 -127.7112)
		(end 482.092 -126.173992)
		(width 0.089408)
		(layer "In2.Cu")
		(net "LED_POSTCODE_5")
	)
	(segment
		(start 411.412436 -116.471192)
		(end 408.517344 -113.5761)
		(width 0.089408)
		(layer "In2.Cu")
		(net "LED_POSTCODE_5")
	)
	(segment
		(start 421.353996 -119.49176)
		(end 416.047174 -119.49176)
		(width 0.089408)
		(layer "In2.Cu")
		(net "LED_POSTCODE_5")
	)
	(segment
		(start 494.411 -134.785608)
		(end 491.069376 -131.443984)
		(width 0.089408)
		(layer "In2.Cu")
		(net "LED_POSTCODE_5")
	)
	(segment
		(start 478.437702 -118.385336)
		(end 477.269556 -117.21719)
		(width 0.089408)
		(layer "In2.Cu")
		(net "LED_POSTCODE_5")
	)
	(segment
		(start 436.859934 -116.404136)
		(end 433.62499 -119.63908)
		(width 0.089408)
		(layer "In2.Cu")
		(net "LED_POSTCODE_5")
	)
	(segment
		(start 404.14321 -98.288094)
		(end 404.14321 -90.90152)
		(width 0.089408)
		(layer "In2.Cu")
		(net "LED_POSTCODE_5")
	)
	(segment
		(start 404.771352 -101.36378)
		(end 404.771352 -98.916236)
		(width 0.089408)
		(layer "In2.Cu")
		(net "LED_POSTCODE_5")
	)
	(segment
		(start 403.837394 -90.595704)
		(end 403.422104 -90.595704)
		(width 0.089408)
		(layer "In2.Cu")
		(net "LED_POSTCODE_5")
	)
	(segment
		(start 466.107526 -116.404136)
		(end 436.859934 -116.404136)
		(width 0.089408)
		(layer "In2.Cu")
		(net "LED_POSTCODE_5")
	)
	(segment
		(start 415.14649 -118.591076)
		(end 414.665668 -118.591076)
		(width 0.089408)
		(layer "In2.Cu")
		(net "LED_POSTCODE_5")
	)
	(segment
		(start 408.517344 -113.434622)
		(end 408.51709 -113.434368)
		(width 0.089408)
		(layer "In2.Cu")
		(net "LED_POSTCODE_5")
	)
	(segment
		(start 404.14321 -90.90152)
		(end 403.837394 -90.595704)
		(width 0.089408)
		(layer "In2.Cu")
		(net "LED_POSTCODE_5")
	)
	(segment
		(start 488.470956 -130.328416)
		(end 485.85374 -127.7112)
		(width 0.089408)
		(layer "In2.Cu")
		(net "LED_POSTCODE_5")
	)
	(segment
		(start 414.665668 -118.591076)
		(end 412.545784 -116.471192)
		(width 0.089408)
		(layer "In2.Cu")
		(net "LED_POSTCODE_5")
	)
	(segment
		(start 408.326844 -109.26572)
		(end 408.326844 -104.253284)
		(width 0.089408)
		(layer "In2.Cu")
		(net "LED_POSTCODE_5")
	)
	(segment
		(start 423.836084 -119.817134)
		(end 421.67937 -119.817134)
		(width 0.089408)
		(layer "In2.Cu")
		(net "LED_POSTCODE_5")
	)
	(segment
		(start 491.624366 -140.5382)
		(end 491.871 -140.5382)
		(width 0.089408)
		(layer "In2.Cu")
		(net "LED_POSTCODE_5")
	)
	(segment
		(start 408.434286 -109.373162)
		(end 408.326844 -109.26572)
		(width 0.089408)
		(layer "In2.Cu")
		(net "LED_POSTCODE_5")
	)
	(segment
		(start 469.388952 -116.764816)
		(end 466.468206 -116.764816)
		(width 0.089408)
		(layer "In2.Cu")
		(net "LED_POSTCODE_5")
	)
	(segment
		(start 491.871 -140.5382)
		(end 494.411 -137.9982)
		(width 0.089408)
		(layer "In2.Cu")
		(net "LED_POSTCODE_5")
	)
	(segment
		(start 421.67937 -119.817134)
		(end 421.353996 -119.49176)
		(width 0.089408)
		(layer "In2.Cu")
		(net "LED_POSTCODE_5")
	)
	(segment
		(start 403.422104 -90.595704)
		(end 402.971 -90.1446)
		(width 0.089408)
		(layer "In2.Cu")
		(net "LED_POSTCODE_5")
	)
	(segment
		(start 433.62499 -119.63908)
		(end 428.003716 -119.63908)
		(width 0.089408)
		(layer "In2.Cu")
		(net "LED_POSTCODE_5")
	)
	(segment
		(start 477.269556 -117.21719)
		(end 469.841326 -117.21719)
		(width 0.089408)
		(layer "In2.Cu")
		(net "LED_POSTCODE_5")
	)
	(segment
		(start 485.85374 -127.7112)
		(end 483.629208 -127.7112)
		(width 0.089408)
		(layer "In2.Cu")
		(net "LED_POSTCODE_5")
	)
	(segment
		(start 482.092 -124.6378)
		(end 478.437702 -120.983502)
		(width 0.089408)
		(layer "In2.Cu")
		(net "LED_POSTCODE_5")
	)
	(segment
		(start 424.433746 -119.219472)
		(end 423.836084 -119.817134)
		(width 0.089408)
		(layer "In2.Cu")
		(net "LED_POSTCODE_5")
	)
	(segment
		(start 416.047174 -119.49176)
		(end 415.14649 -118.591076)
		(width 0.089408)
		(layer "In2.Cu")
		(net "LED_POSTCODE_5")
	)
	(segment
		(start 427.584108 -119.219472)
		(end 424.433746 -119.219472)
		(width 0.089408)
		(layer "In2.Cu")
		(net "LED_POSTCODE_5")
	)
	(segment
		(start 488.5944 -146.177)
		(end 487.967782 -145.550382)
		(width 0.089408)
		(layer "In2.Cu")
		(net "LED_POSTCODE_5")
	)
	(segment
		(start 408.517344 -112.244632)
		(end 408.434286 -112.161574)
		(width 0.089408)
		(layer "In2.Cu")
		(net "LED_POSTCODE_5")
	)
	(segment
		(start 466.468206 -116.764816)
		(end 466.107526 -116.404136)
		(width 0.089408)
		(layer "In2.Cu")
		(net "LED_POSTCODE_5")
	)
	(segment
		(start 488.823508 -130.328416)
		(end 488.470956 -130.328416)
		(width 0.089408)
		(layer "In2.Cu")
		(net "LED_POSTCODE_5")
	)
	(segment
		(start 408.326844 -104.253284)
		(end 407.33218 -103.25862)
		(width 0.089408)
		(layer "In2.Cu")
		(net "LED_POSTCODE_5")
	)
	(segment
		(start 491.069376 -131.443984)
		(end 489.939076 -131.443984)
		(width 0.089408)
		(layer "In2.Cu")
		(net "LED_POSTCODE_5")
	)
	(segment
		(start 428.003716 -119.63908)
		(end 427.584108 -119.219472)
		(width 0.089408)
		(layer "In2.Cu")
		(net "LED_POSTCODE_5")
	)
	(segment
		(start 482.092 -126.173992)
		(end 482.092 -124.6378)
		(width 0.089408)
		(layer "In2.Cu")
		(net "LED_POSTCODE_5")
	)
	(segment
		(start 407.33218 -103.25862)
		(end 406.666192 -103.25862)
		(width 0.089408)
		(layer "In2.Cu")
		(net "LED_POSTCODE_5")
	)
	(segment
		(start 408.517344 -113.276126)
		(end 408.517344 -112.244632)
		(width 0.089408)
		(layer "In2.Cu")
		(net "LED_POSTCODE_5")
	)
	(segment
		(start 489.939076 -131.443984)
		(end 488.823508 -130.328416)
		(width 0.089408)
		(layer "In2.Cu")
		(net "LED_POSTCODE_5")
	)
	(segment
		(start 408.517344 -113.5761)
		(end 408.517344 -113.434622)
		(width 0.089408)
		(layer "In2.Cu")
		(net "LED_POSTCODE_5")
	)
	(segment
		(start 487.967782 -145.550382)
		(end 487.967782 -142.935452)
		(width 0.089408)
		(layer "In2.Cu")
		(net "LED_POSTCODE_5")
	)
	(segment
		(start 487.967782 -142.935452)
		(end 489.586778 -141.316456)
		(width 0.089408)
		(layer "In2.Cu")
		(net "LED_POSTCODE_5")
	)
	(segment
		(start 490.84611 -141.316456)
		(end 491.624366 -140.5382)
		(width 0.089408)
		(layer "In2.Cu")
		(net "LED_POSTCODE_5")
	)
	(segment
		(start 408.434286 -112.161574)
		(end 408.434286 -109.373162)
		(width 0.089408)
		(layer "In2.Cu")
		(net "LED_POSTCODE_5")
	)
	(segment
		(start 489.586778 -141.316456)
		(end 490.84611 -141.316456)
		(width 0.089408)
		(layer "In2.Cu")
		(net "LED_POSTCODE_5")
	)
	(segment
		(start 408.51709 -113.434368)
		(end 408.51709 -113.27638)
		(width 0.089408)
		(layer "In2.Cu")
		(net "LED_POSTCODE_5")
	)
	(segment
		(start 406.666192 -103.25862)
		(end 404.771352 -101.36378)
		(width 0.089408)
		(layer "In2.Cu")
		(net "LED_POSTCODE_5")
	)
	(segment
		(start 392.251946 -90.8304)
		(end 391.169652 -91.912694)
		(width 0.089408)
		(layer "In4.Cu")
		(net "LED_POSTCODE_5")
	)
	(segment
		(start 394.799312 -90.81135)
		(end 394.646658 -90.658696)
		(width 0.089408)
		(layer "In4.Cu")
		(net "LED_POSTCODE_5")
	)
	(segment
		(start 393.997434 -90.8304)
		(end 392.251946 -90.8304)
		(width 0.089408)
		(layer "In4.Cu")
		(net "LED_POSTCODE_5")
	)
	(segment
		(start 402.971 -90.1446)
		(end 402.916136 -90.089736)
		(width 0.089408)
		(layer "In4.Cu")
		(net "LED_POSTCODE_5")
	)
	(segment
		(start 394.646658 -90.658696)
		(end 394.169138 -90.658696)
		(width 0.089408)
		(layer "In4.Cu")
		(net "LED_POSTCODE_5")
	)
	(segment
		(start 396.75689 -90.81135)
		(end 394.799312 -90.81135)
		(width 0.089408)
		(layer "In4.Cu")
		(net "LED_POSTCODE_5")
	)
	(segment
		(start 402.916136 -90.089736)
		(end 397.478504 -90.089736)
		(width 0.089408)
		(layer "In4.Cu")
		(net "LED_POSTCODE_5")
	)
	(segment
		(start 394.169138 -90.658696)
		(end 393.997434 -90.8304)
		(width 0.089408)
		(layer "In4.Cu")
		(net "LED_POSTCODE_5")
	)
	(segment
		(start 397.478504 -90.089736)
		(end 396.75689 -90.81135)
		(width 0.089408)
		(layer "In4.Cu")
		(net "LED_POSTCODE_5")
	)
	(segment
		(start 391.169652 -91.912694)
		(end 390.752838 -91.912694)
		(width 0.089408)
		(layer "In4.Cu")
		(net "LED_POSTCODE_5")
	)
	(segment
		(start 395.181836 -80.68818)
		(end 395.181836 -82.071464)
		(width 0.089408)
		(layer "In9.Cu")
		(net "LED_POSTCODE_5")
	)
	(segment
		(start 396.216632 -74.711052)
		(end 396.216632 -76.319888)
		(width 0.089408)
		(layer "In9.Cu")
		(net "LED_POSTCODE_5")
	)
	(segment
		(start 389.991092 -88.751918)
		(end 389.991092 -90.155268)
		(width 0.089408)
		(layer "In9.Cu")
		(net "LED_POSTCODE_5")
	)
	(segment
		(start 393.9794 -84.957412)
		(end 393.233148 -85.703664)
		(width 0.089408)
		(layer "In9.Cu")
		(net "LED_POSTCODE_5")
	)
	(segment
		(start 396.989046 -71.38416)
		(end 396.989046 -72.942704)
		(width 0.089408)
		(layer "In9.Cu")
		(net "LED_POSTCODE_5")
	)
	(segment
		(start 406.078182 -40.104314)
		(end 405.682196 -40.5003)
		(width 0.089408)
		(layer "In9.Cu")
		(net "LED_POSTCODE_5")
	)
	(segment
		(start 390.16559 -90.329766)
		(end 390.16559 -91.325446)
		(width 0.089408)
		(layer "In9.Cu")
		(net "LED_POSTCODE_5")
	)
	(segment
		(start 405.682196 -40.5003)
		(end 405.337264 -40.5003)
		(width 0.089408)
		(layer "In9.Cu")
		(net "LED_POSTCODE_5")
	)
	(segment
		(start 399.542 -55.110888)
		(end 399.541746 -55.111142)
		(width 0.089408)
		(layer "In9.Cu")
		(net "LED_POSTCODE_5")
	)
	(segment
		(start 394.572744 -83.36026)
		(end 393.9794 -83.953604)
		(width 0.089408)
		(layer "In9.Cu")
		(net "LED_POSTCODE_5")
	)
	(segment
		(start 394.572744 -82.680556)
		(end 394.572744 -83.36026)
		(width 0.089408)
		(layer "In9.Cu")
		(net "LED_POSTCODE_5")
	)
	(segment
		(start 397.595344 -68.425822)
		(end 397.595344 -70.777862)
		(width 0.089408)
		(layer "In9.Cu")
		(net "LED_POSTCODE_5")
	)
	(segment
		(start 401.18919 -61.6712)
		(end 399.847816 -63.012574)
		(width 0.089408)
		(layer "In9.Cu")
		(net "LED_POSTCODE_5")
	)
	(segment
		(start 402.900388 -43.335702)
		(end 402.012658 -44.223432)
		(width 0.089408)
		(layer "In9.Cu")
		(net "LED_POSTCODE_5")
	)
	(segment
		(start 393.9794 -83.953604)
		(end 393.9794 -84.957412)
		(width 0.089408)
		(layer "In9.Cu")
		(net "LED_POSTCODE_5")
	)
	(segment
		(start 404.920958 -39.960804)
		(end 404.589996 -39.629842)
		(width 0.089408)
		(layer "In9.Cu")
		(net "LED_POSTCODE_5")
	)
	(segment
		(start 403.31771 -39.579042)
		(end 402.900388 -39.996364)
		(width 0.089408)
		(layer "In9.Cu")
		(net "LED_POSTCODE_5")
	)
	(segment
		(start 406.078182 -39.998142)
		(end 406.078182 -40.104314)
		(width 0.089408)
		(layer "In9.Cu")
		(net "LED_POSTCODE_5")
	)
	(segment
		(start 397.59509 -68.425568)
		(end 397.595344 -68.425822)
		(width 0.089408)
		(layer "In9.Cu")
		(net "LED_POSTCODE_5")
	)
	(segment
		(start 406.348946 -39.727378)
		(end 406.078182 -39.998142)
		(width 0.089408)
		(layer "In9.Cu")
		(net "LED_POSTCODE_5")
	)
	(segment
		(start 396.989046 -72.942704)
		(end 396.721584 -73.210166)
		(width 0.089408)
		(layer "In9.Cu")
		(net "LED_POSTCODE_5")
	)
	(segment
		(start 393.233148 -85.703664)
		(end 393.039346 -85.703664)
		(width 0.089408)
		(layer "In9.Cu")
		(net "LED_POSTCODE_5")
	)
	(segment
		(start 396.721584 -74.2061)
		(end 396.216632 -74.711052)
		(width 0.089408)
		(layer "In9.Cu")
		(net "LED_POSTCODE_5")
	)
	(segment
		(start 407.458926 -39.727378)
		(end 406.348946 -39.727378)
		(width 0.089408)
		(layer "In9.Cu")
		(net "LED_POSTCODE_5")
	)
	(segment
		(start 396.216632 -76.319888)
		(end 394.883894 -77.652626)
		(width 0.089408)
		(layer "In9.Cu")
		(net "LED_POSTCODE_5")
	)
	(segment
		(start 401.188936 -58.61558)
		(end 401.188936 -61.195966)
		(width 0.089408)
		(layer "In9.Cu")
		(net "LED_POSTCODE_5")
	)
	(segment
		(start 397.59509 -68.109084)
		(end 397.59509 -68.425568)
		(width 0.089408)
		(layer "In9.Cu")
		(net "LED_POSTCODE_5")
	)
	(segment
		(start 404.478998 -39.579296)
		(end 404.478744 -39.579042)
		(width 0.089408)
		(layer "In9.Cu")
		(net "LED_POSTCODE_5")
	)
	(segment
		(start 399.541746 -55.111142)
		(end 399.541746 -56.85409)
		(width 0.089408)
		(layer "In9.Cu")
		(net "LED_POSTCODE_5")
	)
	(segment
		(start 402.900388 -39.996364)
		(end 402.900388 -43.335702)
		(width 0.089408)
		(layer "In9.Cu")
		(net "LED_POSTCODE_5")
	)
	(segment
		(start 404.927562 -40.090598)
		(end 404.927562 -39.967916)
		(width 0.089408)
		(layer "In9.Cu")
		(net "LED_POSTCODE_5")
	)
	(segment
		(start 389.991092 -90.155268)
		(end 390.16559 -90.329766)
		(width 0.089408)
		(layer "In9.Cu")
		(net "LED_POSTCODE_5")
	)
	(segment
		(start 404.478744 -39.579042)
		(end 403.31771 -39.579042)
		(width 0.089408)
		(layer "In9.Cu")
		(net "LED_POSTCODE_5")
	)
	(segment
		(start 402.012658 -45.220636)
		(end 399.542 -47.691294)
		(width 0.089408)
		(layer "In9.Cu")
		(net "LED_POSTCODE_5")
	)
	(segment
		(start 390.16559 -91.325446)
		(end 390.752838 -91.912694)
		(width 0.089408)
		(layer "In9.Cu")
		(net "LED_POSTCODE_5")
	)
	(segment
		(start 404.920958 -39.961312)
		(end 404.920958 -39.960804)
		(width 0.089408)
		(layer "In9.Cu")
		(net "LED_POSTCODE_5")
	)
	(segment
		(start 396.721584 -73.210166)
		(end 396.721584 -74.2061)
		(width 0.089408)
		(layer "In9.Cu")
		(net "LED_POSTCODE_5")
	)
	(segment
		(start 395.181836 -82.071464)
		(end 394.572744 -82.680556)
		(width 0.089408)
		(layer "In9.Cu")
		(net "LED_POSTCODE_5")
	)
	(segment
		(start 394.883894 -77.652626)
		(end 394.883894 -80.390238)
		(width 0.089408)
		(layer "In9.Cu")
		(net "LED_POSTCODE_5")
	)
	(segment
		(start 404.538942 -39.579296)
		(end 404.478998 -39.579296)
		(width 0.089408)
		(layer "In9.Cu")
		(net "LED_POSTCODE_5")
	)
	(segment
		(start 399.542 -47.691294)
		(end 399.542 -55.110888)
		(width 0.089408)
		(layer "In9.Cu")
		(net "LED_POSTCODE_5")
	)
	(segment
		(start 393.039346 -85.703664)
		(end 389.991092 -88.751918)
		(width 0.089408)
		(layer "In9.Cu")
		(net "LED_POSTCODE_5")
	)
	(segment
		(start 402.012658 -44.223432)
		(end 402.012658 -45.220636)
		(width 0.089408)
		(layer "In9.Cu")
		(net "LED_POSTCODE_5")
	)
	(segment
		(start 399.542 -56.968644)
		(end 401.188936 -58.61558)
		(width 0.089408)
		(layer "In9.Cu")
		(net "LED_POSTCODE_5")
	)
	(segment
		(start 404.589996 -39.629842)
		(end 404.589488 -39.629842)
		(width 0.089408)
		(layer "In9.Cu")
		(net "LED_POSTCODE_5")
	)
	(segment
		(start 397.595344 -70.777862)
		(end 396.989046 -71.38416)
		(width 0.089408)
		(layer "In9.Cu")
		(net "LED_POSTCODE_5")
	)
	(segment
		(start 401.18919 -61.19622)
		(end 401.18919 -61.6712)
		(width 0.089408)
		(layer "In9.Cu")
		(net "LED_POSTCODE_5")
	)
	(segment
		(start 399.847816 -65.856358)
		(end 397.59509 -68.109084)
		(width 0.089408)
		(layer "In9.Cu")
		(net "LED_POSTCODE_5")
	)
	(segment
		(start 404.927562 -39.967916)
		(end 404.920958 -39.961312)
		(width 0.089408)
		(layer "In9.Cu")
		(net "LED_POSTCODE_5")
	)
	(segment
		(start 405.337264 -40.5003)
		(end 404.927562 -40.090598)
		(width 0.089408)
		(layer "In9.Cu")
		(net "LED_POSTCODE_5")
	)
	(segment
		(start 399.847816 -63.012574)
		(end 399.847816 -65.856358)
		(width 0.089408)
		(layer "In9.Cu")
		(net "LED_POSTCODE_5")
	)
	(segment
		(start 399.542 -56.854344)
		(end 399.542 -56.968644)
		(width 0.089408)
		(layer "In9.Cu")
		(net "LED_POSTCODE_5")
	)
	(segment
		(start 394.883894 -80.390238)
		(end 395.181836 -80.68818)
		(width 0.089408)
		(layer "In9.Cu")
		(net "LED_POSTCODE_5")
	)
	(segment
		(start 401.188936 -61.195966)
		(end 401.18919 -61.19622)
		(width 0.089408)
		(layer "In9.Cu")
		(net "LED_POSTCODE_5")
	)
	(segment
		(start 399.541746 -56.85409)
		(end 399.542 -56.854344)
		(width 0.089408)
		(layer "In9.Cu")
		(net "LED_POSTCODE_5")
	)
	(segment
		(start 404.589488 -39.629842)
		(end 404.538942 -39.579296)
		(width 0.089408)
		(layer "In9.Cu")
		(net "LED_POSTCODE_5")
	)
	(segment
		(start 425.63161 -112.178592)
		(end 425.63161 -112.734852)
		(width 0.10795)
		(layer "F.Cu")
		(net "FM_SOL_UART_CH_SEL")
	)
	(segment
		(start 371.145308 -76.694792)
		(end 371.545104 -76.294996)
		(width 0.1016)
		(layer "F.Cu")
		(net "FM_SOL_UART_CH_SEL")
	)
	(segment
		(start 426.214032 -113.317274)
		(end 426.214032 -115.980718)
		(width 0.10795)
		(layer "F.Cu")
		(net "FM_SOL_UART_CH_SEL")
	)
	(segment
		(start 415.493962 -92.187268)
		(end 415.493962 -91.0971)
		(width 0.10795)
		(layer "F.Cu")
		(net "FM_SOL_UART_CH_SEL")
	)
	(segment
		(start 425.914312 -111.289338)
		(end 425.914312 -111.89589)
		(width 0.10795)
		(layer "F.Cu")
		(net "FM_SOL_UART_CH_SEL")
	)
	(segment
		(start 425.63161 -112.734852)
		(end 426.214032 -113.317274)
		(width 0.10795)
		(layer "F.Cu")
		(net "FM_SOL_UART_CH_SEL")
	)
	(segment
		(start 415.496502 -98.142298)
		(end 415.496502 -92.189808)
		(width 0.10795)
		(layer "F.Cu")
		(net "FM_SOL_UART_CH_SEL")
	)
	(segment
		(start 424.792902 -93.126814)
		(end 424.792902 -110.167928)
		(width 0.10795)
		(layer "F.Cu")
		(net "FM_SOL_UART_CH_SEL")
	)
	(segment
		(start 411.09011 -41.73474)
		(end 411.09011 -41.734994)
		(width 0.089408)
		(layer "F.Cu")
		(net "FM_SOL_UART_CH_SEL")
	)
	(segment
		(start 415.496502 -92.189808)
		(end 415.493962 -92.187268)
		(width 0.10795)
		(layer "F.Cu")
		(net "FM_SOL_UART_CH_SEL")
	)
	(segment
		(start 420.677086 -89.010998)
		(end 424.792902 -93.126814)
		(width 0.10795)
		(layer "F.Cu")
		(net "FM_SOL_UART_CH_SEL")
	)
	(segment
		(start 418.563044 -90.3097)
		(end 418.815774 -90.05697)
		(width 0.10795)
		(layer "F.Cu")
		(net "FM_SOL_UART_CH_SEL")
	)
	(segment
		(start 415.496502 -90.93962)
		(end 416.126422 -90.3097)
		(width 0.10795)
		(layer "F.Cu")
		(net "FM_SOL_UART_CH_SEL")
	)
	(segment
		(start 427.017688 -119.398288)
		(end 429.245522 -121.626122)
		(width 0.10795)
		(layer "F.Cu")
		(net "FM_SOL_UART_CH_SEL")
	)
	(segment
		(start 418.84727 -90.05697)
		(end 419.232842 -89.671398)
		(width 0.10795)
		(layer "F.Cu")
		(net "FM_SOL_UART_CH_SEL")
	)
	(segment
		(start 419.480238 -89.010998)
		(end 420.677086 -89.010998)
		(width 0.10795)
		(layer "F.Cu")
		(net "FM_SOL_UART_CH_SEL")
	)
	(segment
		(start 427.017688 -116.784374)
		(end 427.017688 -119.398288)
		(width 0.10795)
		(layer "F.Cu")
		(net "FM_SOL_UART_CH_SEL")
	)
	(segment
		(start 411.09011 -41.734994)
		(end 410.690314 -42.13479)
		(width 0.089408)
		(layer "F.Cu")
		(net "FM_SOL_UART_CH_SEL")
	)
	(segment
		(start 419.232842 -89.671398)
		(end 419.232842 -89.258394)
		(width 0.10795)
		(layer "F.Cu")
		(net "FM_SOL_UART_CH_SEL")
	)
	(segment
		(start 415.493962 -91.0971)
		(end 415.496502 -91.09456)
		(width 0.10795)
		(layer "F.Cu")
		(net "FM_SOL_UART_CH_SEL")
	)
	(segment
		(start 419.232842 -89.258394)
		(end 419.480238 -89.010998)
		(width 0.10795)
		(layer "F.Cu")
		(net "FM_SOL_UART_CH_SEL")
	)
	(segment
		(start 414.1216 -99.5172)
		(end 415.496502 -98.142298)
		(width 0.10795)
		(layer "F.Cu")
		(net "FM_SOL_UART_CH_SEL")
	)
	(segment
		(start 429.245522 -121.626122)
		(end 429.245522 -123.749562)
		(width 0.10795)
		(layer "F.Cu")
		(net "FM_SOL_UART_CH_SEL")
	)
	(segment
		(start 425.914312 -111.89589)
		(end 425.63161 -112.178592)
		(width 0.10795)
		(layer "F.Cu")
		(net "FM_SOL_UART_CH_SEL")
	)
	(segment
		(start 395.66215 -95.888556)
		(end 395.16685 -96.11868)
		(width 0.10795)
		(layer "F.Cu")
		(net "FM_SOL_UART_CH_SEL")
	)
	(segment
		(start 424.792902 -110.167928)
		(end 425.914312 -111.289338)
		(width 0.10795)
		(layer "F.Cu")
		(net "FM_SOL_UART_CH_SEL")
	)
	(segment
		(start 418.815774 -90.05697)
		(end 418.84727 -90.05697)
		(width 0.10795)
		(layer "F.Cu")
		(net "FM_SOL_UART_CH_SEL")
	)
	(segment
		(start 426.214032 -115.980718)
		(end 427.017688 -116.784374)
		(width 0.10795)
		(layer "F.Cu")
		(net "FM_SOL_UART_CH_SEL")
	)
	(segment
		(start 415.496502 -91.09456)
		(end 415.496502 -90.93962)
		(width 0.10795)
		(layer "F.Cu")
		(net "FM_SOL_UART_CH_SEL")
	)
	(segment
		(start 416.126422 -90.3097)
		(end 418.563044 -90.3097)
		(width 0.10795)
		(layer "F.Cu")
		(net "FM_SOL_UART_CH_SEL")
	)
	(via
		(at 471.569542 -146.439636)
		(size 0.508)
		(drill 0.254)
		(layers "F.Cu" "B.Cu")
		(net "FM_SOL_UART_CH_SEL")
	)
	(via
		(at 414.1216 -99.5172)
		(size 0.508)
		(drill 0.254)
		(layers "F.Cu" "B.Cu")
		(net "FM_SOL_UART_CH_SEL")
	)
	(via
		(at 410.690314 -42.13479)
		(size 0.4572)
		(drill 0.2032)
		(layers "F.Cu" "B.Cu")
		(net "FM_SOL_UART_CH_SEL")
	)
	(via
		(at 395.66215 -95.888556)
		(size 0.508)
		(drill 0.254)
		(layers "F.Cu" "B.Cu")
		(net "FM_SOL_UART_CH_SEL")
	)
	(via
		(at 429.245522 -123.749562)
		(size 0.508)
		(drill 0.254)
		(layers "F.Cu" "B.Cu")
		(net "FM_SOL_UART_CH_SEL")
	)
	(via
		(at 367.577116 -63.93434)
		(size 0.508)
		(drill 0.254)
		(layers "F.Cu" "B.Cu")
		(net "FM_SOL_UART_CH_SEL")
	)
	(via
		(at 418.84727 -90.05697)
		(size 0.762)
		(drill 0.381)
		(layers "F.Cu" "B.Cu")
		(net "FM_SOL_UART_CH_SEL")
	)
	(via
		(at 375.566178 -91.206828)
		(size 0.508)
		(drill 0.254)
		(layers "F.Cu" "B.Cu")
		(net "FM_SOL_UART_CH_SEL")
	)
	(via
		(at 391.49655 -62.25286)
		(size 0.508)
		(drill 0.254)
		(layers "F.Cu" "B.Cu")
		(net "FM_SOL_UART_CH_SEL")
	)
	(via
		(at 371.145308 -76.694792)
		(size 0.4572)
		(drill 0.2032)
		(layers "F.Cu" "B.Cu")
		(net "FM_SOL_UART_CH_SEL")
	)
	(via
		(at 470.5096 -140.9446)
		(size 0.508)
		(drill 0.254)
		(layers "F.Cu" "B.Cu")
		(net "FM_SOL_UART_CH_SEL")
	)
	(segment
		(start 476.01505 -148.22805)
		(end 475.361 -147.574)
		(width 0.10795)
		(layer "B.Cu")
		(net "FM_SOL_UART_CH_SEL")
	)
	(segment
		(start 474.192346 -147.193)
		(end 473.438982 -146.439636)
		(width 0.10795)
		(layer "B.Cu")
		(net "FM_SOL_UART_CH_SEL")
	)
	(segment
		(start 478.23755 -148.22805)
		(end 476.01505 -148.22805)
		(width 0.10795)
		(layer "B.Cu")
		(net "FM_SOL_UART_CH_SEL")
	)
	(segment
		(start 478.8789 -147.024598)
		(end 478.8789 -147.5867)
		(width 0.10795)
		(layer "B.Cu")
		(net "FM_SOL_UART_CH_SEL")
	)
	(segment
		(start 475.361 -147.193)
		(end 474.192346 -147.193)
		(width 0.10795)
		(layer "B.Cu")
		(net "FM_SOL_UART_CH_SEL")
	)
	(segment
		(start 475.361 -147.574)
		(end 475.361 -147.193)
		(width 0.10795)
		(layer "B.Cu")
		(net "FM_SOL_UART_CH_SEL")
	)
	(segment
		(start 478.8789 -147.5867)
		(end 478.23755 -148.22805)
		(width 0.10795)
		(layer "B.Cu")
		(net "FM_SOL_UART_CH_SEL")
	)
	(segment
		(start 473.438982 -146.439636)
		(end 471.569542 -146.439636)
		(width 0.10795)
		(layer "B.Cu")
		(net "FM_SOL_UART_CH_SEL")
	)
	(segment
		(start 394.969746 -94.725744)
		(end 394.97 -94.725744)
		(width 0.089408)
		(layer "In2.Cu")
		(net "FM_SOL_UART_CH_SEL")
	)
	(segment
		(start 394.97 -94.725744)
		(end 395.415008 -95.170752)
		(width 0.089408)
		(layer "In2.Cu")
		(net "FM_SOL_UART_CH_SEL")
	)
	(segment
		(start 390.840722 -47.08779)
		(end 390.840722 -46.40961)
		(width 0.089408)
		(layer "In2.Cu")
		(net "FM_SOL_UART_CH_SEL")
	)
	(segment
		(start 429.631602 -123.363482)
		(end 430.046384 -123.363482)
		(width 0.089408)
		(layer "In2.Cu")
		(net "FM_SOL_UART_CH_SEL")
	)
	(segment
		(start 430.280826 -123.597924)
		(end 430.280826 -123.83389)
		(width 0.089408)
		(layer "In2.Cu")
		(net "FM_SOL_UART_CH_SEL")
	)
	(segment
		(start 406.441656 -41.0972)
		(end 407.076656 -41.7322)
		(width 0.089408)
		(layer "In2.Cu")
		(net "FM_SOL_UART_CH_SEL")
	)
	(segment
		(start 378.041662 -94.635574)
		(end 394.879576 -94.635574)
		(width 0.089408)
		(layer "In2.Cu")
		(net "FM_SOL_UART_CH_SEL")
	)
	(segment
		(start 456.005184 -125.652784)
		(end 464.213956 -125.652784)
		(width 0.089408)
		(layer "In2.Cu")
		(net "FM_SOL_UART_CH_SEL")
	)
	(segment
		(start 470.916 -139.5222)
		(end 470.5096 -139.9286)
		(width 0.089408)
		(layer "In2.Cu")
		(net "FM_SOL_UART_CH_SEL")
	)
	(segment
		(start 407.076656 -41.7322)
		(end 410.287724 -41.7322)
		(width 0.089408)
		(layer "In2.Cu")
		(net "FM_SOL_UART_CH_SEL")
	)
	(segment
		(start 390.840722 -46.40961)
		(end 391.779252 -45.47108)
		(width 0.089408)
		(layer "In2.Cu")
		(net "FM_SOL_UART_CH_SEL")
	)
	(segment
		(start 410.287724 -41.7322)
		(end 410.690314 -42.13479)
		(width 0.089408)
		(layer "In2.Cu")
		(net "FM_SOL_UART_CH_SEL")
	)
	(segment
		(start 391.059416 -51.45405)
		(end 391.059416 -47.306484)
		(width 0.089408)
		(layer "In2.Cu")
		(net "FM_SOL_UART_CH_SEL")
	)
	(segment
		(start 430.53127 -124.084334)
		(end 433.217066 -124.084334)
		(width 0.089408)
		(layer "In2.Cu")
		(net "FM_SOL_UART_CH_SEL")
	)
	(segment
		(start 467.165944 -122.700796)
		(end 470.33688 -122.700796)
		(width 0.089408)
		(layer "In2.Cu")
		(net "FM_SOL_UART_CH_SEL")
	)
	(segment
		(start 455.32294 -123.92914)
		(end 455.32294 -124.97054)
		(width 0.089408)
		(layer "In2.Cu")
		(net "FM_SOL_UART_CH_SEL")
	)
	(segment
		(start 392.11504 -45.470826)
		(end 392.115294 -45.47108)
		(width 0.089408)
		(layer "In2.Cu")
		(net "FM_SOL_UART_CH_SEL")
	)
	(segment
		(start 440.126374 -122.232928)
		(end 451.909688 -122.232928)
		(width 0.089408)
		(layer "In2.Cu")
		(net "FM_SOL_UART_CH_SEL")
	)
	(segment
		(start 391.956798 -45.47108)
		(end 391.957052 -45.470826)
		(width 0.089408)
		(layer "In2.Cu")
		(net "FM_SOL_UART_CH_SEL")
	)
	(segment
		(start 391.059416 -47.306484)
		(end 390.840722 -47.08779)
		(width 0.089408)
		(layer "In2.Cu")
		(net "FM_SOL_UART_CH_SEL")
	)
	(segment
		(start 470.916 -138.9126)
		(end 470.916 -139.5222)
		(width 0.089408)
		(layer "In2.Cu")
		(net "FM_SOL_UART_CH_SEL")
	)
	(segment
		(start 376.862848 -93.457014)
		(end 377.933458 -94.527624)
		(width 0.089408)
		(layer "In2.Cu")
		(net "FM_SOL_UART_CH_SEL")
	)
	(segment
		(start 471.47988 -133.53796)
		(end 468.63 -136.38784)
		(width 0.089408)
		(layer "In2.Cu")
		(net "FM_SOL_UART_CH_SEL")
	)
	(segment
		(start 468.63 -136.38784)
		(end 468.63 -136.6266)
		(width 0.089408)
		(layer "In2.Cu")
		(net "FM_SOL_UART_CH_SEL")
	)
	(segment
		(start 396.35684 -45.47108)
		(end 397.788892 -44.039028)
		(width 0.089408)
		(layer "In2.Cu")
		(net "FM_SOL_UART_CH_SEL")
	)
	(segment
		(start 454.71334 -123.31954)
		(end 455.32294 -123.92914)
		(width 0.089408)
		(layer "In2.Cu")
		(net "FM_SOL_UART_CH_SEL")
	)
	(segment
		(start 471.47988 -123.843796)
		(end 471.47988 -133.53796)
		(width 0.089408)
		(layer "In2.Cu")
		(net "FM_SOL_UART_CH_SEL")
	)
	(segment
		(start 377.933458 -94.527624)
		(end 377.933712 -94.527624)
		(width 0.089408)
		(layer "In2.Cu")
		(net "FM_SOL_UART_CH_SEL")
	)
	(segment
		(start 452.9963 -123.31954)
		(end 454.71334 -123.31954)
		(width 0.089408)
		(layer "In2.Cu")
		(net "FM_SOL_UART_CH_SEL")
	)
	(segment
		(start 375.566178 -91.206828)
		(end 376.200924 -91.841574)
		(width 0.089408)
		(layer "In2.Cu")
		(net "FM_SOL_UART_CH_SEL")
	)
	(segment
		(start 470.5096 -139.9286)
		(end 470.5096 -140.9446)
		(width 0.089408)
		(layer "In2.Cu")
		(net "FM_SOL_UART_CH_SEL")
	)
	(segment
		(start 392.115294 -45.47108)
		(end 396.35684 -45.47108)
		(width 0.089408)
		(layer "In2.Cu")
		(net "FM_SOL_UART_CH_SEL")
	)
	(segment
		(start 391.779252 -45.47108)
		(end 391.956798 -45.47108)
		(width 0.089408)
		(layer "In2.Cu")
		(net "FM_SOL_UART_CH_SEL")
	)
	(segment
		(start 397.788892 -44.039028)
		(end 400.84756 -44.039028)
		(width 0.089408)
		(layer "In2.Cu")
		(net "FM_SOL_UART_CH_SEL")
	)
	(segment
		(start 395.415008 -95.171006)
		(end 395.66215 -95.418148)
		(width 0.089408)
		(layer "In2.Cu")
		(net "FM_SOL_UART_CH_SEL")
	)
	(segment
		(start 400.84756 -44.039028)
		(end 403.789388 -41.0972)
		(width 0.089408)
		(layer "In2.Cu")
		(net "FM_SOL_UART_CH_SEL")
	)
	(segment
		(start 433.217066 -124.084334)
		(end 434.63845 -122.66295)
		(width 0.089408)
		(layer "In2.Cu")
		(net "FM_SOL_UART_CH_SEL")
	)
	(segment
		(start 395.415008 -95.170752)
		(end 395.415008 -95.171006)
		(width 0.089408)
		(layer "In2.Cu")
		(net "FM_SOL_UART_CH_SEL")
	)
	(segment
		(start 376.200924 -93.07957)
		(end 376.578368 -93.457014)
		(width 0.089408)
		(layer "In2.Cu")
		(net "FM_SOL_UART_CH_SEL")
	)
	(segment
		(start 429.245522 -123.749562)
		(end 429.631602 -123.363482)
		(width 0.089408)
		(layer "In2.Cu")
		(net "FM_SOL_UART_CH_SEL")
	)
	(segment
		(start 391.49655 -62.25286)
		(end 391.374884 -62.131194)
		(width 0.089408)
		(layer "In2.Cu")
		(net "FM_SOL_UART_CH_SEL")
	)
	(segment
		(start 430.280826 -123.83389)
		(end 430.53127 -124.084334)
		(width 0.089408)
		(layer "In2.Cu")
		(net "FM_SOL_UART_CH_SEL")
	)
	(segment
		(start 451.909688 -122.232928)
		(end 452.9963 -123.31954)
		(width 0.089408)
		(layer "In2.Cu")
		(net "FM_SOL_UART_CH_SEL")
	)
	(segment
		(start 391.926572 -52.321206)
		(end 391.059416 -51.45405)
		(width 0.089408)
		(layer "In2.Cu")
		(net "FM_SOL_UART_CH_SEL")
	)
	(segment
		(start 464.213956 -125.652784)
		(end 467.165944 -122.700796)
		(width 0.089408)
		(layer "In2.Cu")
		(net "FM_SOL_UART_CH_SEL")
	)
	(segment
		(start 391.957052 -45.470826)
		(end 392.11504 -45.470826)
		(width 0.089408)
		(layer "In2.Cu")
		(net "FM_SOL_UART_CH_SEL")
	)
	(segment
		(start 391.374884 -59.106308)
		(end 391.926572 -58.55462)
		(width 0.089408)
		(layer "In2.Cu")
		(net "FM_SOL_UART_CH_SEL")
	)
	(segment
		(start 391.374884 -62.131194)
		(end 391.374884 -59.106308)
		(width 0.089408)
		(layer "In2.Cu")
		(net "FM_SOL_UART_CH_SEL")
	)
	(segment
		(start 403.789388 -41.0972)
		(end 406.441656 -41.0972)
		(width 0.089408)
		(layer "In2.Cu")
		(net "FM_SOL_UART_CH_SEL")
	)
	(segment
		(start 395.66215 -95.418148)
		(end 395.66215 -95.888556)
		(width 0.089408)
		(layer "In2.Cu")
		(net "FM_SOL_UART_CH_SEL")
	)
	(segment
		(start 434.63845 -122.66295)
		(end 439.696352 -122.66295)
		(width 0.089408)
		(layer "In2.Cu")
		(net "FM_SOL_UART_CH_SEL")
	)
	(segment
		(start 455.32294 -124.97054)
		(end 456.005184 -125.652784)
		(width 0.089408)
		(layer "In2.Cu")
		(net "FM_SOL_UART_CH_SEL")
	)
	(segment
		(start 377.933712 -94.527624)
		(end 378.041662 -94.635574)
		(width 0.089408)
		(layer "In2.Cu")
		(net "FM_SOL_UART_CH_SEL")
	)
	(segment
		(start 439.696352 -122.66295)
		(end 440.126374 -122.232928)
		(width 0.089408)
		(layer "In2.Cu")
		(net "FM_SOL_UART_CH_SEL")
	)
	(segment
		(start 468.63 -136.6266)
		(end 470.916 -138.9126)
		(width 0.089408)
		(layer "In2.Cu")
		(net "FM_SOL_UART_CH_SEL")
	)
	(segment
		(start 470.33688 -122.700796)
		(end 471.47988 -123.843796)
		(width 0.089408)
		(layer "In2.Cu")
		(net "FM_SOL_UART_CH_SEL")
	)
	(segment
		(start 376.200924 -91.841574)
		(end 376.200924 -93.07957)
		(width 0.089408)
		(layer "In2.Cu")
		(net "FM_SOL_UART_CH_SEL")
	)
	(segment
		(start 430.046384 -123.363482)
		(end 430.280826 -123.597924)
		(width 0.089408)
		(layer "In2.Cu")
		(net "FM_SOL_UART_CH_SEL")
	)
	(segment
		(start 394.879576 -94.635574)
		(end 394.969746 -94.725744)
		(width 0.089408)
		(layer "In2.Cu")
		(net "FM_SOL_UART_CH_SEL")
	)
	(segment
		(start 391.926572 -58.55462)
		(end 391.926572 -52.321206)
		(width 0.089408)
		(layer "In2.Cu")
		(net "FM_SOL_UART_CH_SEL")
	)
	(segment
		(start 376.578368 -93.457014)
		(end 376.862848 -93.457014)
		(width 0.089408)
		(layer "In2.Cu")
		(net "FM_SOL_UART_CH_SEL")
	)
	(segment
		(start 372.99011 -61.30417)
		(end 374.76557 -61.30417)
		(width 0.089408)
		(layer "In4.Cu")
		(net "FM_SOL_UART_CH_SEL")
	)
	(segment
		(start 377.574302 -62.518036)
		(end 378.162566 -62.518036)
		(width 0.089408)
		(layer "In4.Cu")
		(net "FM_SOL_UART_CH_SEL")
	)
	(segment
		(start 379.71984 -62.376304)
		(end 379.875542 -62.220602)
		(width 0.089408)
		(layer "In4.Cu")
		(net "FM_SOL_UART_CH_SEL")
	)
	(segment
		(start 368.088672 -63.422784)
		(end 370.510816 -63.422784)
		(width 0.089408)
		(layer "In4.Cu")
		(net "FM_SOL_UART_CH_SEL")
	)
	(segment
		(start 385.414266 -63.170816)
		(end 385.414266 -61.9252)
		(width 0.089408)
		(layer "In4.Cu")
		(net "FM_SOL_UART_CH_SEL")
	)
	(segment
		(start 385.414266 -61.9252)
		(end 385.680458 -61.659008)
		(width 0.089408)
		(layer "In4.Cu")
		(net "FM_SOL_UART_CH_SEL")
	)
	(segment
		(start 388.00659 -61.656976)
		(end 388.301992 -61.656976)
		(width 0.089408)
		(layer "In4.Cu")
		(net "FM_SOL_UART_CH_SEL")
	)
	(segment
		(start 379.875542 -62.220602)
		(end 380.98476 -62.220602)
		(width 0.089408)
		(layer "In4.Cu")
		(net "FM_SOL_UART_CH_SEL")
	)
	(segment
		(start 378.162566 -62.518036)
		(end 378.304298 -62.376304)
		(width 0.089408)
		(layer "In4.Cu")
		(net "FM_SOL_UART_CH_SEL")
	)
	(segment
		(start 385.680458 -61.659008)
		(end 386.046218 -61.659008)
		(width 0.089408)
		(layer "In4.Cu")
		(net "FM_SOL_UART_CH_SEL")
	)
	(segment
		(start 382.906778 -61.544708)
		(end 383.869438 -61.544708)
		(width 0.089408)
		(layer "In4.Cu")
		(net "FM_SOL_UART_CH_SEL")
	)
	(segment
		(start 388.301992 -61.656976)
		(end 388.304024 -61.659008)
		(width 0.089408)
		(layer "In4.Cu")
		(net "FM_SOL_UART_CH_SEL")
	)
	(segment
		(start 378.304298 -62.376304)
		(end 379.71984 -62.376304)
		(width 0.089408)
		(layer "In4.Cu")
		(net "FM_SOL_UART_CH_SEL")
	)
	(segment
		(start 384.473958 -63.574168)
		(end 384.827018 -63.574168)
		(width 0.089408)
		(layer "In4.Cu")
		(net "FM_SOL_UART_CH_SEL")
	)
	(segment
		(start 383.869438 -61.544708)
		(end 383.869438 -61.559948)
		(width 0.089408)
		(layer "In4.Cu")
		(net "FM_SOL_UART_CH_SEL")
	)
	(segment
		(start 380.98476 -62.220602)
		(end 381.45339 -61.751972)
		(width 0.089408)
		(layer "In4.Cu")
		(net "FM_SOL_UART_CH_SEL")
	)
	(segment
		(start 382.699514 -61.751972)
		(end 382.906778 -61.544708)
		(width 0.089408)
		(layer "In4.Cu")
		(net "FM_SOL_UART_CH_SEL")
	)
	(segment
		(start 384.827018 -63.574168)
		(end 384.836924 -63.564262)
		(width 0.089408)
		(layer "In4.Cu")
		(net "FM_SOL_UART_CH_SEL")
	)
	(segment
		(start 383.869438 -61.559948)
		(end 384.175 -61.86551)
		(width 0.089408)
		(layer "In4.Cu")
		(net "FM_SOL_UART_CH_SEL")
	)
	(segment
		(start 372.206012 -61.727588)
		(end 372.566692 -61.727588)
		(width 0.089408)
		(layer "In4.Cu")
		(net "FM_SOL_UART_CH_SEL")
	)
	(segment
		(start 396.326106 -95.2246)
		(end 395.66215 -95.888556)
		(width 0.089408)
		(layer "In4.Cu")
		(net "FM_SOL_UART_CH_SEL")
	)
	(segment
		(start 375.158762 -61.697362)
		(end 376.941334 -61.697362)
		(width 0.089408)
		(layer "In4.Cu")
		(net "FM_SOL_UART_CH_SEL")
	)
	(segment
		(start 404.29434 -97.31756)
		(end 402.5265 -95.54972)
		(width 0.089408)
		(layer "In4.Cu")
		(net "FM_SOL_UART_CH_SEL")
	)
	(segment
		(start 388.304024 -61.659008)
		(end 390.41324 -61.659008)
		(width 0.089408)
		(layer "In4.Cu")
		(net "FM_SOL_UART_CH_SEL")
	)
	(segment
		(start 414.1216 -99.5172)
		(end 412.6738 -99.5172)
		(width 0.089408)
		(layer "In4.Cu")
		(net "FM_SOL_UART_CH_SEL")
	)
	(segment
		(start 386.64769 -62.26048)
		(end 387.403086 -62.26048)
		(width 0.089408)
		(layer "In4.Cu")
		(net "FM_SOL_UART_CH_SEL")
	)
	(segment
		(start 377.198382 -62.142116)
		(end 377.574302 -62.518036)
		(width 0.089408)
		(layer "In4.Cu")
		(net "FM_SOL_UART_CH_SEL")
	)
	(segment
		(start 372.566692 -61.727588)
		(end 372.99011 -61.30417)
		(width 0.089408)
		(layer "In4.Cu")
		(net "FM_SOL_UART_CH_SEL")
	)
	(segment
		(start 384.175 -63.27521)
		(end 384.473958 -63.574168)
		(width 0.089408)
		(layer "In4.Cu")
		(net "FM_SOL_UART_CH_SEL")
	)
	(segment
		(start 387.403086 -62.26048)
		(end 388.00659 -61.656976)
		(width 0.089408)
		(layer "In4.Cu")
		(net "FM_SOL_UART_CH_SEL")
	)
	(segment
		(start 381.45339 -61.751972)
		(end 382.699514 -61.751972)
		(width 0.089408)
		(layer "In4.Cu")
		(net "FM_SOL_UART_CH_SEL")
	)
	(segment
		(start 412.6738 -99.5172)
		(end 410.47416 -97.31756)
		(width 0.089408)
		(layer "In4.Cu")
		(net "FM_SOL_UART_CH_SEL")
	)
	(segment
		(start 410.47416 -97.31756)
		(end 404.29434 -97.31756)
		(width 0.089408)
		(layer "In4.Cu")
		(net "FM_SOL_UART_CH_SEL")
	)
	(segment
		(start 391.007092 -62.25286)
		(end 391.49655 -62.25286)
		(width 0.089408)
		(layer "In4.Cu")
		(net "FM_SOL_UART_CH_SEL")
	)
	(segment
		(start 374.76557 -61.30417)
		(end 375.158762 -61.697362)
		(width 0.089408)
		(layer "In4.Cu")
		(net "FM_SOL_UART_CH_SEL")
	)
	(segment
		(start 386.046218 -61.659008)
		(end 386.64769 -62.26048)
		(width 0.089408)
		(layer "In4.Cu")
		(net "FM_SOL_UART_CH_SEL")
	)
	(segment
		(start 400.52498 -95.54972)
		(end 400.19986 -95.2246)
		(width 0.089408)
		(layer "In4.Cu")
		(net "FM_SOL_UART_CH_SEL")
	)
	(segment
		(start 384.175 -61.86551)
		(end 384.175 -63.27521)
		(width 0.089408)
		(layer "In4.Cu")
		(net "FM_SOL_UART_CH_SEL")
	)
	(segment
		(start 376.941334 -61.697362)
		(end 377.198382 -61.95441)
		(width 0.089408)
		(layer "In4.Cu")
		(net "FM_SOL_UART_CH_SEL")
	)
	(segment
		(start 367.577116 -63.93434)
		(end 368.088672 -63.422784)
		(width 0.089408)
		(layer "In4.Cu")
		(net "FM_SOL_UART_CH_SEL")
	)
	(segment
		(start 384.836924 -63.564262)
		(end 385.02082 -63.564262)
		(width 0.089408)
		(layer "In4.Cu")
		(net "FM_SOL_UART_CH_SEL")
	)
	(segment
		(start 390.41324 -61.659008)
		(end 391.007092 -62.25286)
		(width 0.089408)
		(layer "In4.Cu")
		(net "FM_SOL_UART_CH_SEL")
	)
	(segment
		(start 385.02082 -63.564262)
		(end 385.414266 -63.170816)
		(width 0.089408)
		(layer "In4.Cu")
		(net "FM_SOL_UART_CH_SEL")
	)
	(segment
		(start 377.198382 -61.95441)
		(end 377.198382 -62.142116)
		(width 0.089408)
		(layer "In4.Cu")
		(net "FM_SOL_UART_CH_SEL")
	)
	(segment
		(start 400.19986 -95.2246)
		(end 396.326106 -95.2246)
		(width 0.089408)
		(layer "In4.Cu")
		(net "FM_SOL_UART_CH_SEL")
	)
	(segment
		(start 370.510816 -63.422784)
		(end 372.206012 -61.727588)
		(width 0.089408)
		(layer "In4.Cu")
		(net "FM_SOL_UART_CH_SEL")
	)
	(segment
		(start 402.5265 -95.54972)
		(end 400.52498 -95.54972)
		(width 0.089408)
		(layer "In4.Cu")
		(net "FM_SOL_UART_CH_SEL")
	)
	(segment
		(start 371.299994 -71.521828)
		(end 371.571774 -71.793608)
		(width 0.089408)
		(layer "In11.Cu")
		(net "FM_SOL_UART_CH_SEL")
	)
	(segment
		(start 371.145308 -76.478892)
		(end 371.145308 -76.694792)
		(width 0.089408)
		(layer "In11.Cu")
		(net "FM_SOL_UART_CH_SEL")
	)
	(segment
		(start 471.37447 -141.672818)
		(end 470.646252 -140.9446)
		(width 0.089408)
		(layer "In11.Cu")
		(net "FM_SOL_UART_CH_SEL")
	)
	(segment
		(start 371.881908 -80.632808)
		(end 372.198646 -80.949546)
		(width 0.089408)
		(layer "In11.Cu")
		(net "FM_SOL_UART_CH_SEL")
	)
	(segment
		(start 371.881908 -79.618332)
		(end 371.881908 -80.632808)
		(width 0.089408)
		(layer "In11.Cu")
		(net "FM_SOL_UART_CH_SEL")
	)
	(segment
		(start 371.145308 -76.937108)
		(end 371.518688 -77.310488)
		(width 0.089408)
		(layer "In11.Cu")
		(net "FM_SOL_UART_CH_SEL")
	)
	(segment
		(start 369.126008 -65.538096)
		(end 369.487196 -65.538096)
		(width 0.089408)
		(layer "In11.Cu")
		(net "FM_SOL_UART_CH_SEL")
	)
	(segment
		(start 371.145308 -76.694792)
		(end 371.145308 -76.937108)
		(width 0.089408)
		(layer "In11.Cu")
		(net "FM_SOL_UART_CH_SEL")
	)
	(segment
		(start 372.198646 -80.949546)
		(end 372.198646 -82.323686)
		(width 0.089408)
		(layer "In11.Cu")
		(net "FM_SOL_UART_CH_SEL")
	)
	(segment
		(start 371.571774 -76.052426)
		(end 371.145308 -76.478892)
		(width 0.089408)
		(layer "In11.Cu")
		(net "FM_SOL_UART_CH_SEL")
	)
	(segment
		(start 369.487196 -65.538096)
		(end 370.731288 -66.782188)
		(width 0.089408)
		(layer "In11.Cu")
		(net "FM_SOL_UART_CH_SEL")
	)
	(segment
		(start 374.537224 -90.276426)
		(end 375.439178 -91.17838)
		(width 0.089408)
		(layer "In11.Cu")
		(net "FM_SOL_UART_CH_SEL")
	)
	(segment
		(start 371.518688 -77.310488)
		(end 371.518688 -79.255112)
		(width 0.089408)
		(layer "In11.Cu")
		(net "FM_SOL_UART_CH_SEL")
	)
	(segment
		(start 471.569542 -146.439636)
		(end 471.37447 -146.244564)
		(width 0.089408)
		(layer "In11.Cu")
		(net "FM_SOL_UART_CH_SEL")
	)
	(segment
		(start 371.518688 -79.255112)
		(end 371.881908 -79.618332)
		(width 0.089408)
		(layer "In11.Cu")
		(net "FM_SOL_UART_CH_SEL")
	)
	(segment
		(start 375.439178 -91.17838)
		(end 375.53773 -91.17838)
		(width 0.089408)
		(layer "In11.Cu")
		(net "FM_SOL_UART_CH_SEL")
	)
	(segment
		(start 370.731288 -71.209154)
		(end 371.043962 -71.521828)
		(width 0.089408)
		(layer "In11.Cu")
		(net "FM_SOL_UART_CH_SEL")
	)
	(segment
		(start 373.328438 -83.453478)
		(end 373.453152 -83.453478)
		(width 0.089408)
		(layer "In11.Cu")
		(net "FM_SOL_UART_CH_SEL")
	)
	(segment
		(start 370.731288 -66.782188)
		(end 370.731288 -71.209154)
		(width 0.089408)
		(layer "In11.Cu")
		(net "FM_SOL_UART_CH_SEL")
	)
	(segment
		(start 371.043962 -71.521828)
		(end 371.299994 -71.521828)
		(width 0.089408)
		(layer "In11.Cu")
		(net "FM_SOL_UART_CH_SEL")
	)
	(segment
		(start 375.53773 -91.17838)
		(end 375.53773 -91.206828)
		(width 0.089408)
		(layer "In11.Cu")
		(net "FM_SOL_UART_CH_SEL")
	)
	(segment
		(start 375.53773 -91.206828)
		(end 375.566178 -91.206828)
		(width 0.089408)
		(layer "In11.Cu")
		(net "FM_SOL_UART_CH_SEL")
	)
	(segment
		(start 372.198646 -82.323686)
		(end 373.328438 -83.453478)
		(width 0.089408)
		(layer "In11.Cu")
		(net "FM_SOL_UART_CH_SEL")
	)
	(segment
		(start 374.537224 -84.53755)
		(end 374.537224 -90.276426)
		(width 0.089408)
		(layer "In11.Cu")
		(net "FM_SOL_UART_CH_SEL")
	)
	(segment
		(start 373.453152 -83.453478)
		(end 374.537224 -84.53755)
		(width 0.089408)
		(layer "In11.Cu")
		(net "FM_SOL_UART_CH_SEL")
	)
	(segment
		(start 371.571774 -71.793608)
		(end 371.571774 -76.052426)
		(width 0.089408)
		(layer "In11.Cu")
		(net "FM_SOL_UART_CH_SEL")
	)
	(segment
		(start 471.37447 -146.244564)
		(end 471.37447 -141.672818)
		(width 0.089408)
		(layer "In11.Cu")
		(net "FM_SOL_UART_CH_SEL")
	)
	(segment
		(start 367.577116 -63.989204)
		(end 369.126008 -65.538096)
		(width 0.089408)
		(layer "In11.Cu")
		(net "FM_SOL_UART_CH_SEL")
	)
	(segment
		(start 367.577116 -63.93434)
		(end 367.577116 -63.989204)
		(width 0.089408)
		(layer "In11.Cu")
		(net "FM_SOL_UART_CH_SEL")
	)
	(segment
		(start 470.646252 -140.9446)
		(end 470.5096 -140.9446)
		(width 0.089408)
		(layer "In11.Cu")
		(net "FM_SOL_UART_CH_SEL")
	)
	(segment
		(start 401.02155 -108.671868)
		(end 401.124166 -108.569252)
		(width 0.0889)
		(layer "F.Cu")
		(net "FM_BOARD_REV_ID2")
	)
	(segment
		(start 400.05 -108.354876)
		(end 400.42211 -108.354876)
		(width 0.0889)
		(layer "F.Cu")
		(net "FM_BOARD_REV_ID2")
	)
	(segment
		(start 401.124166 -108.569252)
		(end 401.451826 -108.569252)
		(width 0.0889)
		(layer "F.Cu")
		(net "FM_BOARD_REV_ID2")
	)
	(segment
		(start 410.350462 -46.966632)
		(end 410.333698 -46.966632)
		(width 0.10795)
		(layer "F.Cu")
		(net "FM_BOARD_REV_ID2")
	)
	(segment
		(start 401.451826 -108.569252)
		(end 401.635976 -108.753402)
		(width 0.0889)
		(layer "F.Cu")
		(net "FM_BOARD_REV_ID2")
	)
	(segment
		(start 410.333698 -46.989238)
		(end 409.685236 -47.6377)
		(width 0.10795)
		(layer "F.Cu")
		(net "FM_BOARD_REV_ID2")
	)
	(segment
		(start 402.340318 -108.753402)
		(end 402.395182 -108.698538)
		(width 0.0889)
		(layer "F.Cu")
		(net "FM_BOARD_REV_ID2")
	)
	(segment
		(start 410.290264 -41.73474)
		(end 409.890214 -42.13479)
		(width 0.089408)
		(layer "F.Cu")
		(net "FM_BOARD_REV_ID2")
	)
	(segment
		(start 400.739102 -108.671868)
		(end 401.02155 -108.671868)
		(width 0.0889)
		(layer "F.Cu")
		(net "FM_BOARD_REV_ID2")
	)
	(segment
		(start 401.635976 -108.753402)
		(end 402.340318 -108.753402)
		(width 0.0889)
		(layer "F.Cu")
		(net "FM_BOARD_REV_ID2")
	)
	(segment
		(start 410.333698 -46.966632)
		(end 410.333698 -46.989238)
		(width 0.10795)
		(layer "F.Cu")
		(net "FM_BOARD_REV_ID2")
	)
	(segment
		(start 409.685236 -47.6377)
		(end 409.685236 -47.825914)
		(width 0.10795)
		(layer "F.Cu")
		(net "FM_BOARD_REV_ID2")
	)
	(segment
		(start 400.42211 -108.354876)
		(end 400.739102 -108.671868)
		(width 0.0889)
		(layer "F.Cu")
		(net "FM_BOARD_REV_ID2")
	)
	(via
		(at 410.350462 -46.966632)
		(size 0.508)
		(drill 0.254)
		(layers "F.Cu" "B.Cu")
		(net "FM_BOARD_REV_ID2")
	)
	(via
		(at 409.702508 -43.096688)
		(size 0.6604)
		(drill 0.3302)
		(layers "F.Cu" "B.Cu")
		(net "FM_BOARD_REV_ID2")
	)
	(via
		(at 409.890214 -42.13479)
		(size 0.4572)
		(drill 0.2032)
		(layers "F.Cu" "B.Cu")
		(net "FM_BOARD_REV_ID2")
	)
	(via
		(at 402.395182 -108.698538)
		(size 0.508)
		(drill 0.254)
		(layers "F.Cu" "B.Cu")
		(net "FM_BOARD_REV_ID2")
	)
	(segment
		(start 409.93695 -44.6913)
		(end 409.7655 -44.6913)
		(width 0.10795)
		(layer "B.Cu")
		(net "FM_BOARD_REV_ID2")
	)
	(segment
		(start 410.597858 -44.275502)
		(end 410.352748 -44.275502)
		(width 0.10795)
		(layer "B.Cu")
		(net "FM_BOARD_REV_ID2")
	)
	(segment
		(start 410.890466 -43.982894)
		(end 410.597858 -44.275502)
		(width 0.10795)
		(layer "B.Cu")
		(net "FM_BOARD_REV_ID2")
	)
	(segment
		(start 410.396436 -43.434)
		(end 410.6418 -43.434)
		(width 0.10795)
		(layer "B.Cu")
		(net "FM_BOARD_REV_ID2")
	)
	(segment
		(start 409.890214 -42.13479)
		(end 409.890214 -42.277538)
		(width 0.10795)
		(layer "B.Cu")
		(net "FM_BOARD_REV_ID2")
	)
	(segment
		(start 409.702508 -43.096688)
		(end 410.059124 -43.096688)
		(width 0.10795)
		(layer "B.Cu")
		(net "FM_BOARD_REV_ID2")
	)
	(segment
		(start 409.448 -45.355256)
		(end 410.350462 -46.257718)
		(width 0.10795)
		(layer "B.Cu")
		(net "FM_BOARD_REV_ID2")
	)
	(segment
		(start 409.448 -45.0088)
		(end 409.448 -45.355256)
		(width 0.10795)
		(layer "B.Cu")
		(net "FM_BOARD_REV_ID2")
	)
	(segment
		(start 410.591 -47.20717)
		(end 410.591 -47.879)
		(width 0.10795)
		(layer "B.Cu")
		(net "FM_BOARD_REV_ID2")
	)
	(segment
		(start 410.059124 -43.096688)
		(end 410.396436 -43.434)
		(width 0.10795)
		(layer "B.Cu")
		(net "FM_BOARD_REV_ID2")
	)
	(segment
		(start 409.702508 -42.465244)
		(end 409.702508 -43.096688)
		(width 0.10795)
		(layer "B.Cu")
		(net "FM_BOARD_REV_ID2")
	)
	(segment
		(start 410.350462 -46.257718)
		(end 410.350462 -46.966632)
		(width 0.10795)
		(layer "B.Cu")
		(net "FM_BOARD_REV_ID2")
	)
	(segment
		(start 410.890466 -43.682666)
		(end 410.890466 -43.982894)
		(width 0.10795)
		(layer "B.Cu")
		(net "FM_BOARD_REV_ID2")
	)
	(segment
		(start 410.6418 -43.434)
		(end 410.890466 -43.682666)
		(width 0.10795)
		(layer "B.Cu")
		(net "FM_BOARD_REV_ID2")
	)
	(segment
		(start 410.352748 -44.275502)
		(end 409.93695 -44.6913)
		(width 0.10795)
		(layer "B.Cu")
		(net "FM_BOARD_REV_ID2")
	)
	(segment
		(start 409.890214 -42.277538)
		(end 409.702508 -42.465244)
		(width 0.10795)
		(layer "B.Cu")
		(net "FM_BOARD_REV_ID2")
	)
	(segment
		(start 409.7655 -44.6913)
		(end 409.448 -45.0088)
		(width 0.10795)
		(layer "B.Cu")
		(net "FM_BOARD_REV_ID2")
	)
	(segment
		(start 410.350462 -46.966632)
		(end 410.591 -47.20717)
		(width 0.10795)
		(layer "B.Cu")
		(net "FM_BOARD_REV_ID2")
	)
	(segment
		(start 398.356074 -75.920854)
		(end 398.356074 -73.451466)
		(width 0.089408)
		(layer "In2.Cu")
		(net "FM_BOARD_REV_ID2")
	)
	(segment
		(start 402.395182 -108.698538)
		(end 402.395182 -108.373418)
		(width 0.089408)
		(layer "In2.Cu")
		(net "FM_BOARD_REV_ID2")
	)
	(segment
		(start 395.578584 -70.673976)
		(end 395.578584 -66.509392)
		(width 0.089408)
		(layer "In2.Cu")
		(net "FM_BOARD_REV_ID2")
	)
	(segment
		(start 398.356074 -73.451466)
		(end 395.578584 -70.673976)
		(width 0.089408)
		(layer "In2.Cu")
		(net "FM_BOARD_REV_ID2")
	)
	(segment
		(start 399.573496 -85.508338)
		(end 399.573496 -83.417664)
		(width 0.089408)
		(layer "In2.Cu")
		(net "FM_BOARD_REV_ID2")
	)
	(segment
		(start 399.15719 -76.72197)
		(end 398.356074 -75.920854)
		(width 0.089408)
		(layer "In2.Cu")
		(net "FM_BOARD_REV_ID2")
	)
	(segment
		(start 399.924778 -105.903014)
		(end 399.924778 -99.881436)
		(width 0.089408)
		(layer "In2.Cu")
		(net "FM_BOARD_REV_ID2")
	)
	(segment
		(start 398.686528 -65.723008)
		(end 399.463768 -65.723008)
		(width 0.089408)
		(layer "In2.Cu")
		(net "FM_BOARD_REV_ID2")
	)
	(segment
		(start 395.578584 -66.509392)
		(end 395.920976 -66.167)
		(width 0.089408)
		(layer "In2.Cu")
		(net "FM_BOARD_REV_ID2")
	)
	(segment
		(start 409.852622 -47.464472)
		(end 410.350462 -46.966632)
		(width 0.089408)
		(layer "In2.Cu")
		(net "FM_BOARD_REV_ID2")
	)
	(segment
		(start 397.75638 -65.26784)
		(end 398.23136 -65.26784)
		(width 0.089408)
		(layer "In2.Cu")
		(net "FM_BOARD_REV_ID2")
	)
	(segment
		(start 395.920976 -66.167)
		(end 397.27632 -66.167)
		(width 0.089408)
		(layer "In2.Cu")
		(net "FM_BOARD_REV_ID2")
	)
	(segment
		(start 397.54556 -65.47866)
		(end 397.75638 -65.26784)
		(width 0.089408)
		(layer "In2.Cu")
		(net "FM_BOARD_REV_ID2")
	)
	(segment
		(start 399.15719 -77.620622)
		(end 399.15719 -76.72197)
		(width 0.089408)
		(layer "In2.Cu")
		(net "FM_BOARD_REV_ID2")
	)
	(segment
		(start 400.472656 -93.071188)
		(end 399.739612 -92.338144)
		(width 0.089408)
		(layer "In2.Cu")
		(net "FM_BOARD_REV_ID2")
	)
	(segment
		(start 399.924778 -99.881436)
		(end 400.472656 -99.333558)
		(width 0.089408)
		(layer "In2.Cu")
		(net "FM_BOARD_REV_ID2")
	)
	(segment
		(start 398.311116 -82.155284)
		(end 398.311116 -81.006696)
		(width 0.089408)
		(layer "In2.Cu")
		(net "FM_BOARD_REV_ID2")
	)
	(segment
		(start 398.311116 -81.006696)
		(end 399.403316 -79.914496)
		(width 0.089408)
		(layer "In2.Cu")
		(net "FM_BOARD_REV_ID2")
	)
	(segment
		(start 397.54556 -65.89776)
		(end 397.54556 -65.47866)
		(width 0.089408)
		(layer "In2.Cu")
		(net "FM_BOARD_REV_ID2")
	)
	(segment
		(start 399.382996 -86.030562)
		(end 399.382996 -85.698838)
		(width 0.089408)
		(layer "In2.Cu")
		(net "FM_BOARD_REV_ID2")
	)
	(segment
		(start 400.472656 -99.333558)
		(end 400.472656 -93.071188)
		(width 0.089408)
		(layer "In2.Cu")
		(net "FM_BOARD_REV_ID2")
	)
	(segment
		(start 399.739612 -86.387178)
		(end 399.382996 -86.030562)
		(width 0.089408)
		(layer "In2.Cu")
		(net "FM_BOARD_REV_ID2")
	)
	(segment
		(start 402.395182 -108.373418)
		(end 399.924778 -105.903014)
		(width 0.089408)
		(layer "In2.Cu")
		(net "FM_BOARD_REV_ID2")
	)
	(segment
		(start 398.23136 -65.26784)
		(end 398.686528 -65.723008)
		(width 0.089408)
		(layer "In2.Cu")
		(net "FM_BOARD_REV_ID2")
	)
	(segment
		(start 399.382996 -85.698838)
		(end 399.573496 -85.508338)
		(width 0.089408)
		(layer "In2.Cu")
		(net "FM_BOARD_REV_ID2")
	)
	(segment
		(start 405.125174 -57.286906)
		(end 405.125174 -52.14366)
		(width 0.089408)
		(layer "In2.Cu")
		(net "FM_BOARD_REV_ID2")
	)
	(segment
		(start 409.804362 -47.464472)
		(end 409.852622 -47.464472)
		(width 0.089408)
		(layer "In2.Cu")
		(net "FM_BOARD_REV_ID2")
	)
	(segment
		(start 400.844512 -61.567568)
		(end 405.125174 -57.286906)
		(width 0.089408)
		(layer "In2.Cu")
		(net "FM_BOARD_REV_ID2")
	)
	(segment
		(start 399.463768 -65.723008)
		(end 400.844512 -64.342264)
		(width 0.089408)
		(layer "In2.Cu")
		(net "FM_BOARD_REV_ID2")
	)
	(segment
		(start 399.403316 -77.866748)
		(end 399.15719 -77.620622)
		(width 0.089408)
		(layer "In2.Cu")
		(net "FM_BOARD_REV_ID2")
	)
	(segment
		(start 405.125174 -52.14366)
		(end 409.804362 -47.464472)
		(width 0.089408)
		(layer "In2.Cu")
		(net "FM_BOARD_REV_ID2")
	)
	(segment
		(start 399.573496 -83.417664)
		(end 398.311116 -82.155284)
		(width 0.089408)
		(layer "In2.Cu")
		(net "FM_BOARD_REV_ID2")
	)
	(segment
		(start 397.27632 -66.167)
		(end 397.54556 -65.89776)
		(width 0.089408)
		(layer "In2.Cu")
		(net "FM_BOARD_REV_ID2")
	)
	(segment
		(start 400.844512 -64.342264)
		(end 400.844512 -61.567568)
		(width 0.089408)
		(layer "In2.Cu")
		(net "FM_BOARD_REV_ID2")
	)
	(segment
		(start 399.739612 -92.338144)
		(end 399.739612 -86.387178)
		(width 0.089408)
		(layer "In2.Cu")
		(net "FM_BOARD_REV_ID2")
	)
	(segment
		(start 399.403316 -79.914496)
		(end 399.403316 -77.866748)
		(width 0.089408)
		(layer "In2.Cu")
		(net "FM_BOARD_REV_ID2")
	)
	(segment
		(start 409.490164 -40.13454)
		(end 409.48991 -40.13454)
		(width 0.10795)
		(layer "F.Cu")
		(net "LED_POSTCODE_7")
	)
	(segment
		(start 409.48991 -40.13454)
		(end 409.090114 -39.734744)
		(width 0.10795)
		(layer "F.Cu")
		(net "LED_POSTCODE_7")
	)
	(via
		(at 424.608752 -46.46295)
		(size 0.508)
		(drill 0.254)
		(layers "F.Cu" "B.Cu")
		(net "LED_POSTCODE_7")
	)
	(via
		(at 409.090114 -39.734744)
		(size 0.4572)
		(drill 0.2032)
		(layers "F.Cu" "B.Cu")
		(net "LED_POSTCODE_7")
	)
	(via
		(at 394.335 -91.059)
		(size 0.508)
		(drill 0.254)
		(layers "F.Cu" "B.Cu")
		(net "LED_POSTCODE_7")
	)
	(via
		(at 403.6314 -91.0336)
		(size 0.508)
		(drill 0.254)
		(layers "F.Cu" "B.Cu")
		(net "LED_POSTCODE_7")
	)
	(via
		(at 488.5436 -148.082)
		(size 0.508)
		(drill 0.254)
		(layers "F.Cu" "B.Cu")
		(net "LED_POSTCODE_7")
	)
	(segment
		(start 488.5436 -148.082)
		(end 489.65739 -148.082)
		(width 0.10795)
		(layer "B.Cu")
		(net "LED_POSTCODE_7")
	)
	(segment
		(start 488.614466 -146.6723)
		(end 488.969304 -147.027138)
		(width 0.089408)
		(layer "In2.Cu")
		(net "LED_POSTCODE_7")
	)
	(segment
		(start 403.6314 -91.0336)
		(end 403.85365 -91.0336)
		(width 0.089408)
		(layer "In2.Cu")
		(net "LED_POSTCODE_7")
	)
	(segment
		(start 421.600122 -120.008142)
		(end 423.915332 -120.008142)
		(width 0.089408)
		(layer "In2.Cu")
		(net "LED_POSTCODE_7")
	)
	(segment
		(start 491.415578 -139.2174)
		(end 487.776774 -142.856204)
		(width 0.089408)
		(layer "In2.Cu")
		(net "LED_POSTCODE_7")
	)
	(segment
		(start 404.580344 -100.229924)
		(end 404.580344 -101.443028)
		(width 0.089408)
		(layer "In2.Cu")
		(net "LED_POSTCODE_7")
	)
	(segment
		(start 436.939182 -116.595144)
		(end 466.028278 -116.595144)
		(width 0.089408)
		(layer "In2.Cu")
		(net "LED_POSTCODE_7")
	)
	(segment
		(start 469.762078 -117.408198)
		(end 477.190308 -117.408198)
		(width 0.089408)
		(layer "In2.Cu")
		(net "LED_POSTCODE_7")
	)
	(segment
		(start 404.580344 -101.443028)
		(end 406.586944 -103.449628)
		(width 0.089408)
		(layer "In2.Cu")
		(net "LED_POSTCODE_7")
	)
	(segment
		(start 469.309704 -116.955824)
		(end 469.762078 -117.408198)
		(width 0.089408)
		(layer "In2.Cu")
		(net "LED_POSTCODE_7")
	)
	(segment
		(start 403.85365 -91.0336)
		(end 403.943058 -91.123008)
		(width 0.089408)
		(layer "In2.Cu")
		(net "LED_POSTCODE_7")
	)
	(segment
		(start 488.35437 -130.519424)
		(end 488.74426 -130.519424)
		(width 0.089408)
		(layer "In2.Cu")
		(net "LED_POSTCODE_7")
	)
	(segment
		(start 480.06 -126.873)
		(end 481.089208 -127.902208)
		(width 0.089408)
		(layer "In2.Cu")
		(net "LED_POSTCODE_7")
	)
	(segment
		(start 466.028278 -116.595144)
		(end 466.388958 -116.955824)
		(width 0.089408)
		(layer "In2.Cu")
		(net "LED_POSTCODE_7")
	)
	(segment
		(start 488.74426 -130.519424)
		(end 489.859828 -131.634992)
		(width 0.089408)
		(layer "In2.Cu")
		(net "LED_POSTCODE_7")
	)
	(segment
		(start 406.586944 -103.449628)
		(end 407.252932 -103.449628)
		(width 0.089408)
		(layer "In2.Cu")
		(net "LED_POSTCODE_7")
	)
	(segment
		(start 408.326082 -113.513616)
		(end 408.326336 -113.51387)
		(width 0.089408)
		(layer "In2.Cu")
		(net "LED_POSTCODE_7")
	)
	(segment
		(start 415.967926 -119.682768)
		(end 421.274748 -119.682768)
		(width 0.089408)
		(layer "In2.Cu")
		(net "LED_POSTCODE_7")
	)
	(segment
		(start 408.326336 -112.32388)
		(end 408.326336 -113.196878)
		(width 0.089408)
		(layer "In2.Cu")
		(net "LED_POSTCODE_7")
	)
	(segment
		(start 478.246694 -121.06275)
		(end 480.06 -122.876056)
		(width 0.089408)
		(layer "In2.Cu")
		(net "LED_POSTCODE_7")
	)
	(segment
		(start 415.067242 -118.782084)
		(end 415.967926 -119.682768)
		(width 0.089408)
		(layer "In2.Cu")
		(net "LED_POSTCODE_7")
	)
	(segment
		(start 466.388958 -116.955824)
		(end 469.309704 -116.955824)
		(width 0.089408)
		(layer "In2.Cu")
		(net "LED_POSTCODE_7")
	)
	(segment
		(start 492.835946 -139.2174)
		(end 491.415578 -139.2174)
		(width 0.089408)
		(layer "In2.Cu")
		(net "LED_POSTCODE_7")
	)
	(segment
		(start 494.1824 -137.870946)
		(end 492.835946 -139.2174)
		(width 0.089408)
		(layer "In2.Cu")
		(net "LED_POSTCODE_7")
	)
	(segment
		(start 408.243278 -109.45241)
		(end 408.243278 -112.240822)
		(width 0.089408)
		(layer "In2.Cu")
		(net "LED_POSTCODE_7")
	)
	(segment
		(start 408.243278 -112.240822)
		(end 408.326336 -112.32388)
		(width 0.089408)
		(layer "In2.Cu")
		(net "LED_POSTCODE_7")
	)
	(segment
		(start 481.089208 -127.902208)
		(end 485.737154 -127.902208)
		(width 0.089408)
		(layer "In2.Cu")
		(net "LED_POSTCODE_7")
	)
	(segment
		(start 408.135836 -109.344968)
		(end 408.243278 -109.45241)
		(width 0.089408)
		(layer "In2.Cu")
		(net "LED_POSTCODE_7")
	)
	(segment
		(start 411.333188 -116.6622)
		(end 412.466536 -116.6622)
		(width 0.089408)
		(layer "In2.Cu")
		(net "LED_POSTCODE_7")
	)
	(segment
		(start 408.135836 -104.332532)
		(end 408.135836 -109.344968)
		(width 0.089408)
		(layer "In2.Cu")
		(net "LED_POSTCODE_7")
	)
	(segment
		(start 424.512994 -119.41048)
		(end 427.50486 -119.41048)
		(width 0.089408)
		(layer "In2.Cu")
		(net "LED_POSTCODE_7")
	)
	(segment
		(start 427.924468 -119.830088)
		(end 433.704238 -119.830088)
		(width 0.089408)
		(layer "In2.Cu")
		(net "LED_POSTCODE_7")
	)
	(segment
		(start 421.274748 -119.682768)
		(end 421.600122 -120.008142)
		(width 0.089408)
		(layer "In2.Cu")
		(net "LED_POSTCODE_7")
	)
	(segment
		(start 489.859828 -131.634992)
		(end 490.990128 -131.634992)
		(width 0.089408)
		(layer "In2.Cu")
		(net "LED_POSTCODE_7")
	)
	(segment
		(start 407.252932 -103.449628)
		(end 408.135836 -104.332532)
		(width 0.089408)
		(layer "In2.Cu")
		(net "LED_POSTCODE_7")
	)
	(segment
		(start 477.190308 -117.408198)
		(end 478.246694 -118.464584)
		(width 0.089408)
		(layer "In2.Cu")
		(net "LED_POSTCODE_7")
	)
	(segment
		(start 423.915332 -120.008142)
		(end 424.512994 -119.41048)
		(width 0.089408)
		(layer "In2.Cu")
		(net "LED_POSTCODE_7")
	)
	(segment
		(start 403.943058 -99.592638)
		(end 404.580344 -100.229924)
		(width 0.089408)
		(layer "In2.Cu")
		(net "LED_POSTCODE_7")
	)
	(segment
		(start 488.969304 -147.656296)
		(end 488.5436 -148.082)
		(width 0.089408)
		(layer "In2.Cu")
		(net "LED_POSTCODE_7")
	)
	(segment
		(start 485.737154 -127.902208)
		(end 488.35437 -130.519424)
		(width 0.089408)
		(layer "In2.Cu")
		(net "LED_POSTCODE_7")
	)
	(segment
		(start 494.1824 -134.827264)
		(end 494.1824 -137.870946)
		(width 0.089408)
		(layer "In2.Cu")
		(net "LED_POSTCODE_7")
	)
	(segment
		(start 488.969304 -147.027138)
		(end 488.969304 -147.656296)
		(width 0.089408)
		(layer "In2.Cu")
		(net "LED_POSTCODE_7")
	)
	(segment
		(start 408.326336 -113.51387)
		(end 408.326336 -113.655348)
		(width 0.089408)
		(layer "In2.Cu")
		(net "LED_POSTCODE_7")
	)
	(segment
		(start 412.466536 -116.6622)
		(end 414.58642 -118.782084)
		(width 0.089408)
		(layer "In2.Cu")
		(net "LED_POSTCODE_7")
	)
	(segment
		(start 487.776774 -145.92554)
		(end 488.523534 -146.6723)
		(width 0.089408)
		(layer "In2.Cu")
		(net "LED_POSTCODE_7")
	)
	(segment
		(start 480.06 -122.876056)
		(end 480.06 -126.873)
		(width 0.089408)
		(layer "In2.Cu")
		(net "LED_POSTCODE_7")
	)
	(segment
		(start 488.523534 -146.6723)
		(end 488.614466 -146.6723)
		(width 0.089408)
		(layer "In2.Cu")
		(net "LED_POSTCODE_7")
	)
	(segment
		(start 478.246694 -118.464584)
		(end 478.246694 -121.06275)
		(width 0.089408)
		(layer "In2.Cu")
		(net "LED_POSTCODE_7")
	)
	(segment
		(start 490.990128 -131.634992)
		(end 494.1824 -134.827264)
		(width 0.089408)
		(layer "In2.Cu")
		(net "LED_POSTCODE_7")
	)
	(segment
		(start 414.58642 -118.782084)
		(end 415.067242 -118.782084)
		(width 0.089408)
		(layer "In2.Cu")
		(net "LED_POSTCODE_7")
	)
	(segment
		(start 433.704238 -119.830088)
		(end 436.939182 -116.595144)
		(width 0.089408)
		(layer "In2.Cu")
		(net "LED_POSTCODE_7")
	)
	(segment
		(start 408.326336 -113.196878)
		(end 408.326082 -113.197132)
		(width 0.089408)
		(layer "In2.Cu")
		(net "LED_POSTCODE_7")
	)
	(segment
		(start 408.326082 -113.197132)
		(end 408.326082 -113.513616)
		(width 0.089408)
		(layer "In2.Cu")
		(net "LED_POSTCODE_7")
	)
	(segment
		(start 408.326336 -113.655348)
		(end 411.333188 -116.6622)
		(width 0.089408)
		(layer "In2.Cu")
		(net "LED_POSTCODE_7")
	)
	(segment
		(start 427.50486 -119.41048)
		(end 427.924468 -119.830088)
		(width 0.089408)
		(layer "In2.Cu")
		(net "LED_POSTCODE_7")
	)
	(segment
		(start 403.943058 -91.123008)
		(end 403.943058 -99.592638)
		(width 0.089408)
		(layer "In2.Cu")
		(net "LED_POSTCODE_7")
	)
	(segment
		(start 487.776774 -142.856204)
		(end 487.776774 -145.92554)
		(width 0.089408)
		(layer "In2.Cu")
		(net "LED_POSTCODE_7")
	)
	(segment
		(start 403.21865 -90.62085)
		(end 402.209762 -90.62085)
		(width 0.089408)
		(layer "In4.Cu")
		(net "LED_POSTCODE_7")
	)
	(segment
		(start 397.557752 -90.280744)
		(end 396.830296 -91.0082)
		(width 0.089408)
		(layer "In4.Cu")
		(net "LED_POSTCODE_7")
	)
	(segment
		(start 403.6314 -91.0336)
		(end 403.21865 -90.62085)
		(width 0.089408)
		(layer "In4.Cu")
		(net "LED_POSTCODE_7")
	)
	(segment
		(start 396.830296 -91.0082)
		(end 394.3858 -91.0082)
		(width 0.089408)
		(layer "In4.Cu")
		(net "LED_POSTCODE_7")
	)
	(segment
		(start 402.209762 -90.62085)
		(end 401.869656 -90.280744)
		(width 0.089408)
		(layer "In4.Cu")
		(net "LED_POSTCODE_7")
	)
	(segment
		(start 394.3858 -91.0082)
		(end 394.335 -91.059)
		(width 0.089408)
		(layer "In4.Cu")
		(net "LED_POSTCODE_7")
	)
	(segment
		(start 401.869656 -90.280744)
		(end 397.557752 -90.280744)
		(width 0.089408)
		(layer "In4.Cu")
		(net "LED_POSTCODE_7")
	)
	(segment
		(start 421.250872 -48.40097)
		(end 421.567356 -48.40097)
		(width 0.089408)
		(layer "In9.Cu")
		(net "LED_POSTCODE_7")
	)
	(segment
		(start 399.834608 -83.953096)
		(end 401.013168 -82.774536)
		(width 0.089408)
		(layer "In9.Cu")
		(net "LED_POSTCODE_7")
	)
	(segment
		(start 399.382996 -85.591396)
		(end 399.834608 -85.139784)
		(width 0.089408)
		(layer "In9.Cu")
		(net "LED_POSTCODE_7")
	)
	(segment
		(start 410.179266 -67.34048)
		(end 410.179266 -60.9346)
		(width 0.089408)
		(layer "In9.Cu")
		(net "LED_POSTCODE_7")
	)
	(segment
		(start 407.461212 -70.325742)
		(end 407.461212 -70.058534)
		(width 0.089408)
		(layer "In9.Cu")
		(net "LED_POSTCODE_7")
	)
	(segment
		(start 401.013168 -81.256124)
		(end 401.003516 -81.246472)
		(width 0.089408)
		(layer "In9.Cu")
		(net "LED_POSTCODE_7")
	)
	(segment
		(start 395.04112 -90.35288)
		(end 395.950186 -90.35288)
		(width 0.089408)
		(layer "In9.Cu")
		(net "LED_POSTCODE_7")
	)
	(segment
		(start 395.950186 -90.35288)
		(end 399.382996 -86.92007)
		(width 0.089408)
		(layer "In9.Cu")
		(net "LED_POSTCODE_7")
	)
	(segment
		(start 402.16074 -79.981044)
		(end 402.6535 -79.488284)
		(width 0.089408)
		(layer "In9.Cu")
		(net "LED_POSTCODE_7")
	)
	(segment
		(start 402.6535 -79.488284)
		(end 402.6535 -78.300326)
		(width 0.089408)
		(layer "In9.Cu")
		(net "LED_POSTCODE_7")
	)
	(segment
		(start 401.013168 -82.774536)
		(end 401.013168 -81.256124)
		(width 0.089408)
		(layer "In9.Cu")
		(net "LED_POSTCODE_7")
	)
	(segment
		(start 401.003516 -81.246472)
		(end 401.003516 -80.597756)
		(width 0.089408)
		(layer "In9.Cu")
		(net "LED_POSTCODE_7")
	)
	(segment
		(start 421.250618 -48.401224)
		(end 421.250872 -48.40097)
		(width 0.089408)
		(layer "In9.Cu")
		(net "LED_POSTCODE_7")
	)
	(segment
		(start 401.003516 -80.597756)
		(end 401.620228 -79.981044)
		(width 0.089408)
		(layer "In9.Cu")
		(net "LED_POSTCODE_7")
	)
	(segment
		(start 421.226742 -48.401224)
		(end 421.250618 -48.401224)
		(width 0.089408)
		(layer "In9.Cu")
		(net "LED_POSTCODE_7")
	)
	(segment
		(start 399.382996 -86.92007)
		(end 399.382996 -85.591396)
		(width 0.089408)
		(layer "In9.Cu")
		(net "LED_POSTCODE_7")
	)
	(segment
		(start 421.567356 -48.40097)
		(end 421.56761 -48.401224)
		(width 0.089408)
		(layer "In9.Cu")
		(net "LED_POSTCODE_7")
	)
	(segment
		(start 418.15893 -51.469036)
		(end 421.226742 -48.401224)
		(width 0.089408)
		(layer "In9.Cu")
		(net "LED_POSTCODE_7")
	)
	(segment
		(start 424.6118 -46.606968)
		(end 424.6118 -46.46295)
		(width 0.089408)
		(layer "In9.Cu")
		(net "LED_POSTCODE_7")
	)
	(segment
		(start 394.335 -91.059)
		(end 395.04112 -90.35288)
		(width 0.089408)
		(layer "In9.Cu")
		(net "LED_POSTCODE_7")
	)
	(segment
		(start 424.6118 -46.46295)
		(end 424.608752 -46.46295)
		(width 0.089408)
		(layer "In9.Cu")
		(net "LED_POSTCODE_7")
	)
	(segment
		(start 414.654238 -51.469036)
		(end 418.15893 -51.469036)
		(width 0.089408)
		(layer "In9.Cu")
		(net "LED_POSTCODE_7")
	)
	(segment
		(start 403.43582 -77.518006)
		(end 403.43582 -74.351134)
		(width 0.089408)
		(layer "In9.Cu")
		(net "LED_POSTCODE_7")
	)
	(segment
		(start 401.620228 -79.981044)
		(end 402.16074 -79.981044)
		(width 0.089408)
		(layer "In9.Cu")
		(net "LED_POSTCODE_7")
	)
	(segment
		(start 402.6535 -78.300326)
		(end 403.43582 -77.518006)
		(width 0.089408)
		(layer "In9.Cu")
		(net "LED_POSTCODE_7")
	)
	(segment
		(start 403.43582 -74.351134)
		(end 407.461212 -70.325742)
		(width 0.089408)
		(layer "In9.Cu")
		(net "LED_POSTCODE_7")
	)
	(segment
		(start 399.834608 -85.139784)
		(end 399.834608 -83.953096)
		(width 0.089408)
		(layer "In9.Cu")
		(net "LED_POSTCODE_7")
	)
	(segment
		(start 409.974288 -56.148986)
		(end 414.654238 -51.469036)
		(width 0.089408)
		(layer "In9.Cu")
		(net "LED_POSTCODE_7")
	)
	(segment
		(start 409.974288 -60.729622)
		(end 409.974288 -56.148986)
		(width 0.089408)
		(layer "In9.Cu")
		(net "LED_POSTCODE_7")
	)
	(segment
		(start 422.817544 -48.401224)
		(end 424.6118 -46.606968)
		(width 0.089408)
		(layer "In9.Cu")
		(net "LED_POSTCODE_7")
	)
	(segment
		(start 410.179266 -60.9346)
		(end 409.974288 -60.729622)
		(width 0.089408)
		(layer "In9.Cu")
		(net "LED_POSTCODE_7")
	)
	(segment
		(start 407.461212 -70.058534)
		(end 410.179266 -67.34048)
		(width 0.089408)
		(layer "In9.Cu")
		(net "LED_POSTCODE_7")
	)
	(segment
		(start 421.56761 -48.401224)
		(end 422.817544 -48.401224)
		(width 0.089408)
		(layer "In9.Cu")
		(net "LED_POSTCODE_7")
	)
	(segment
		(start 412.6992 -42.395394)
		(end 412.906464 -42.602658)
		(width 0.089408)
		(layer "In11.Cu")
		(net "LED_POSTCODE_7")
	)
	(segment
		(start 409.51531 -40.68953)
		(end 409.51531 -40.690038)
		(width 0.089408)
		(layer "In11.Cu")
		(net "LED_POSTCODE_7")
	)
	(segment
		(start 412.906464 -42.602658)
		(end 414.511236 -42.602658)
		(width 0.089408)
		(layer "In11.Cu")
		(net "LED_POSTCODE_7")
	)
	(segment
		(start 409.090114 -39.895272)
		(end 409.465018 -40.270176)
		(width 0.089408)
		(layer "In11.Cu")
		(net "LED_POSTCODE_7")
	)
	(segment
		(start 409.51531 -40.690038)
		(end 409.734766 -40.909494)
		(width 0.089408)
		(layer "In11.Cu")
		(net "LED_POSTCODE_7")
	)
	(segment
		(start 412.577534 -40.924734)
		(end 412.6992 -41.0464)
		(width 0.089408)
		(layer "In11.Cu")
		(net "LED_POSTCODE_7")
	)
	(segment
		(start 409.734766 -40.909494)
		(end 409.735274 -40.909494)
		(width 0.089408)
		(layer "In11.Cu")
		(net "LED_POSTCODE_7")
	)
	(segment
		(start 409.090114 -39.734744)
		(end 409.090114 -39.895272)
		(width 0.089408)
		(layer "In11.Cu")
		(net "LED_POSTCODE_7")
	)
	(segment
		(start 409.750514 -40.924734)
		(end 412.577534 -40.924734)
		(width 0.089408)
		(layer "In11.Cu")
		(net "LED_POSTCODE_7")
	)
	(segment
		(start 412.6992 -41.0464)
		(end 412.6992 -42.395394)
		(width 0.089408)
		(layer "In11.Cu")
		(net "LED_POSTCODE_7")
	)
	(segment
		(start 409.465018 -40.270176)
		(end 409.465018 -40.639238)
		(width 0.089408)
		(layer "In11.Cu")
		(net "LED_POSTCODE_7")
	)
	(segment
		(start 409.465018 -40.639238)
		(end 409.51531 -40.68953)
		(width 0.089408)
		(layer "In11.Cu")
		(net "LED_POSTCODE_7")
	)
	(segment
		(start 414.634172 -42.725594)
		(end 420.906194 -42.725594)
		(width 0.089408)
		(layer "In11.Cu")
		(net "LED_POSTCODE_7")
	)
	(segment
		(start 409.735274 -40.909494)
		(end 409.750514 -40.924734)
		(width 0.089408)
		(layer "In11.Cu")
		(net "LED_POSTCODE_7")
	)
	(segment
		(start 420.906194 -42.725594)
		(end 424.608752 -46.428152)
		(width 0.089408)
		(layer "In11.Cu")
		(net "LED_POSTCODE_7")
	)
	(segment
		(start 424.608752 -46.428152)
		(end 424.608752 -46.46295)
		(width 0.089408)
		(layer "In11.Cu")
		(net "LED_POSTCODE_7")
	)
	(segment
		(start 414.511236 -42.602658)
		(end 414.634172 -42.725594)
		(width 0.089408)
		(layer "In11.Cu")
		(net "LED_POSTCODE_7")
	)
	(segment
		(start 406.52446 -40.13454)
		(end 407.090118 -40.13454)
		(width 0.10795)
		(layer "F.Cu")
		(net "LED_POSTCODE_0")
	)
	(via
		(at 403.899116 -90.109548)
		(size 0.508)
		(drill 0.254)
		(layers "F.Cu" "B.Cu")
		(net "LED_POSTCODE_0")
	)
	(via
		(at 406.52446 -40.13454)
		(size 0.4572)
		(drill 0.2032)
		(layers "F.Cu" "B.Cu")
		(net "LED_POSTCODE_0")
	)
	(via
		(at 390.779 -91.278202)
		(size 0.508)
		(drill 0.254)
		(layers "F.Cu" "B.Cu")
		(net "LED_POSTCODE_0")
	)
	(via
		(at 494.8174 -136.8298)
		(size 0.508)
		(drill 0.254)
		(layers "F.Cu" "B.Cu")
		(net "LED_POSTCODE_0")
	)
	(segment
		(start 495.2492 -137.2616)
		(end 494.8174 -136.8298)
		(width 0.10795)
		(layer "B.Cu")
		(net "LED_POSTCODE_0")
	)
	(segment
		(start 495.2492 -137.7569)
		(end 495.2492 -137.2616)
		(width 0.10795)
		(layer "B.Cu")
		(net "LED_POSTCODE_0")
	)
	(segment
		(start 482.346 -123.643644)
		(end 479.307906 -120.60555)
		(width 0.089408)
		(layer "In2.Cu")
		(net "LED_POSTCODE_0")
	)
	(segment
		(start 412.2674 -114.0968)
		(end 409.449778 -114.0968)
		(width 0.089408)
		(layer "In2.Cu")
		(net "LED_POSTCODE_0")
	)
	(segment
		(start 421.758618 -119.626126)
		(end 421.433244 -119.300752)
		(width 0.089408)
		(layer "In2.Cu")
		(net "LED_POSTCODE_0")
	)
	(segment
		(start 490.737398 -127.520192)
		(end 483.97668 -127.520192)
		(width 0.089408)
		(layer "In2.Cu")
		(net "LED_POSTCODE_0")
	)
	(segment
		(start 408.625294 -109.293914)
		(end 408.517852 -109.186472)
		(width 0.089408)
		(layer "In2.Cu")
		(net "LED_POSTCODE_0")
	)
	(segment
		(start 477.348804 -117.026182)
		(end 469.920574 -117.026182)
		(width 0.089408)
		(layer "In2.Cu")
		(net "LED_POSTCODE_0")
	)
	(segment
		(start 491.6424 -131.746752)
		(end 491.6424 -128.425194)
		(width 0.089408)
		(layer "In2.Cu")
		(net "LED_POSTCODE_0")
	)
	(segment
		(start 491.6424 -128.425194)
		(end 490.737398 -127.520192)
		(width 0.089408)
		(layer "In2.Cu")
		(net "LED_POSTCODE_0")
	)
	(segment
		(start 479.307906 -118.985284)
		(end 477.348804 -117.026182)
		(width 0.089408)
		(layer "In2.Cu")
		(net "LED_POSTCODE_0")
	)
	(segment
		(start 469.4682 -116.573808)
		(end 466.547454 -116.573808)
		(width 0.089408)
		(layer "In2.Cu")
		(net "LED_POSTCODE_0")
	)
	(segment
		(start 404.96236 -98.836988)
		(end 404.334218 -98.208846)
		(width 0.089408)
		(layer "In2.Cu")
		(net "LED_POSTCODE_0")
	)
	(segment
		(start 436.780686 -116.213128)
		(end 433.545742 -119.448072)
		(width 0.089408)
		(layer "In2.Cu")
		(net "LED_POSTCODE_0")
	)
	(segment
		(start 407.411428 -103.067612)
		(end 406.74544 -103.067612)
		(width 0.089408)
		(layer "In2.Cu")
		(net "LED_POSTCODE_0")
	)
	(segment
		(start 408.625294 -112.082326)
		(end 408.625294 -109.293914)
		(width 0.089408)
		(layer "In2.Cu")
		(net "LED_POSTCODE_0")
	)
	(segment
		(start 427.663356 -119.028464)
		(end 424.354498 -119.028464)
		(width 0.089408)
		(layer "In2.Cu")
		(net "LED_POSTCODE_0")
	)
	(segment
		(start 404.334218 -90.54465)
		(end 403.899116 -90.109548)
		(width 0.089408)
		(layer "In2.Cu")
		(net "LED_POSTCODE_0")
	)
	(segment
		(start 421.433244 -119.300752)
		(end 416.126422 -119.300752)
		(width 0.089408)
		(layer "In2.Cu")
		(net "LED_POSTCODE_0")
	)
	(segment
		(start 466.186774 -116.213128)
		(end 436.780686 -116.213128)
		(width 0.089408)
		(layer "In2.Cu")
		(net "LED_POSTCODE_0")
	)
	(segment
		(start 408.517852 -104.174036)
		(end 407.411428 -103.067612)
		(width 0.089408)
		(layer "In2.Cu")
		(net "LED_POSTCODE_0")
	)
	(segment
		(start 433.545742 -119.448072)
		(end 428.082964 -119.448072)
		(width 0.089408)
		(layer "In2.Cu")
		(net "LED_POSTCODE_0")
	)
	(segment
		(start 483.97668 -127.520192)
		(end 482.35108 -125.894592)
		(width 0.089408)
		(layer "In2.Cu")
		(net "LED_POSTCODE_0")
	)
	(segment
		(start 414.744662 -118.399814)
		(end 412.5468 -116.201952)
		(width 0.089408)
		(layer "In2.Cu")
		(net "LED_POSTCODE_0")
	)
	(segment
		(start 494.8174 -136.8298)
		(end 494.665 -136.6774)
		(width 0.089408)
		(layer "In2.Cu")
		(net "LED_POSTCODE_0")
	)
	(segment
		(start 406.74544 -103.067612)
		(end 404.96236 -101.284532)
		(width 0.089408)
		(layer "In2.Cu")
		(net "LED_POSTCODE_0")
	)
	(segment
		(start 415.225484 -118.399814)
		(end 414.744662 -118.399814)
		(width 0.089408)
		(layer "In2.Cu")
		(net "LED_POSTCODE_0")
	)
	(segment
		(start 482.346 -125.5141)
		(end 482.346 -123.643644)
		(width 0.089408)
		(layer "In2.Cu")
		(net "LED_POSTCODE_0")
	)
	(segment
		(start 424.354498 -119.028464)
		(end 423.756836 -119.626126)
		(width 0.089408)
		(layer "In2.Cu")
		(net "LED_POSTCODE_0")
	)
	(segment
		(start 408.517852 -109.186472)
		(end 408.517852 -104.174036)
		(width 0.089408)
		(layer "In2.Cu")
		(net "LED_POSTCODE_0")
	)
	(segment
		(start 408.708352 -113.355374)
		(end 408.708352 -112.165384)
		(width 0.089408)
		(layer "In2.Cu")
		(net "LED_POSTCODE_0")
	)
	(segment
		(start 469.920574 -117.026182)
		(end 469.4682 -116.573808)
		(width 0.089408)
		(layer "In2.Cu")
		(net "LED_POSTCODE_0")
	)
	(segment
		(start 408.708352 -112.165384)
		(end 408.625294 -112.082326)
		(width 0.089408)
		(layer "In2.Cu")
		(net "LED_POSTCODE_0")
	)
	(segment
		(start 482.35108 -125.51918)
		(end 482.346 -125.5141)
		(width 0.089408)
		(layer "In2.Cu")
		(net "LED_POSTCODE_0")
	)
	(segment
		(start 404.96236 -101.284532)
		(end 404.96236 -98.836988)
		(width 0.089408)
		(layer "In2.Cu")
		(net "LED_POSTCODE_0")
	)
	(segment
		(start 479.307906 -120.60555)
		(end 479.307906 -118.985284)
		(width 0.089408)
		(layer "In2.Cu")
		(net "LED_POSTCODE_0")
	)
	(segment
		(start 404.334218 -98.208846)
		(end 404.334218 -90.54465)
		(width 0.089408)
		(layer "In2.Cu")
		(net "LED_POSTCODE_0")
	)
	(segment
		(start 412.5468 -114.3762)
		(end 412.2674 -114.0968)
		(width 0.089408)
		(layer "In2.Cu")
		(net "LED_POSTCODE_0")
	)
	(segment
		(start 466.547454 -116.573808)
		(end 466.186774 -116.213128)
		(width 0.089408)
		(layer "In2.Cu")
		(net "LED_POSTCODE_0")
	)
	(segment
		(start 428.082964 -119.448072)
		(end 427.663356 -119.028464)
		(width 0.089408)
		(layer "In2.Cu")
		(net "LED_POSTCODE_0")
	)
	(segment
		(start 494.665 -136.6774)
		(end 494.665 -134.769352)
		(width 0.089408)
		(layer "In2.Cu")
		(net "LED_POSTCODE_0")
	)
	(segment
		(start 482.35108 -125.894592)
		(end 482.35108 -125.51918)
		(width 0.089408)
		(layer "In2.Cu")
		(net "LED_POSTCODE_0")
	)
	(segment
		(start 416.126422 -119.300752)
		(end 415.225484 -118.399814)
		(width 0.089408)
		(layer "In2.Cu")
		(net "LED_POSTCODE_0")
	)
	(segment
		(start 494.665 -134.769352)
		(end 491.6424 -131.746752)
		(width 0.089408)
		(layer "In2.Cu")
		(net "LED_POSTCODE_0")
	)
	(segment
		(start 409.449778 -114.0968)
		(end 408.708352 -113.355374)
		(width 0.089408)
		(layer "In2.Cu")
		(net "LED_POSTCODE_0")
	)
	(segment
		(start 423.756836 -119.626126)
		(end 421.758618 -119.626126)
		(width 0.089408)
		(layer "In2.Cu")
		(net "LED_POSTCODE_0")
	)
	(segment
		(start 412.5468 -116.201952)
		(end 412.5468 -114.3762)
		(width 0.089408)
		(layer "In2.Cu")
		(net "LED_POSTCODE_0")
	)
	(segment
		(start 394.48994 -90.231722)
		(end 394.87856 -90.620342)
		(width 0.089408)
		(layer "In4.Cu")
		(net "LED_POSTCODE_0")
	)
	(segment
		(start 391.488422 -89.921588)
		(end 392.221974 -89.921588)
		(width 0.089408)
		(layer "In4.Cu")
		(net "LED_POSTCODE_0")
	)
	(segment
		(start 392.9888 -89.836498)
		(end 393.384024 -90.231722)
		(width 0.089408)
		(layer "In4.Cu")
		(net "LED_POSTCODE_0")
	)
	(segment
		(start 391.362946 -90.424)
		(end 391.362946 -90.047064)
		(width 0.089408)
		(layer "In4.Cu")
		(net "LED_POSTCODE_0")
	)
	(segment
		(start 396.677642 -90.620342)
		(end 397.407384 -89.8906)
		(width 0.089408)
		(layer "In4.Cu")
		(net "LED_POSTCODE_0")
	)
	(segment
		(start 397.407384 -89.8906)
		(end 402.658834 -89.8906)
		(width 0.089408)
		(layer "In4.Cu")
		(net "LED_POSTCODE_0")
	)
	(segment
		(start 390.779 -91.007946)
		(end 391.362946 -90.424)
		(width 0.089408)
		(layer "In4.Cu")
		(net "LED_POSTCODE_0")
	)
	(segment
		(start 390.779 -91.278202)
		(end 390.779 -91.007946)
		(width 0.089408)
		(layer "In4.Cu")
		(net "LED_POSTCODE_0")
	)
	(segment
		(start 403.261576 -89.744296)
		(end 403.626828 -90.109548)
		(width 0.089408)
		(layer "In4.Cu")
		(net "LED_POSTCODE_0")
	)
	(segment
		(start 402.805138 -89.744296)
		(end 403.261576 -89.744296)
		(width 0.089408)
		(layer "In4.Cu")
		(net "LED_POSTCODE_0")
	)
	(segment
		(start 402.658834 -89.8906)
		(end 402.805138 -89.744296)
		(width 0.089408)
		(layer "In4.Cu")
		(net "LED_POSTCODE_0")
	)
	(segment
		(start 392.221974 -89.921588)
		(end 392.307064 -89.836498)
		(width 0.089408)
		(layer "In4.Cu")
		(net "LED_POSTCODE_0")
	)
	(segment
		(start 394.87856 -90.620342)
		(end 396.677642 -90.620342)
		(width 0.089408)
		(layer "In4.Cu")
		(net "LED_POSTCODE_0")
	)
	(segment
		(start 403.626828 -90.109548)
		(end 403.899116 -90.109548)
		(width 0.089408)
		(layer "In4.Cu")
		(net "LED_POSTCODE_0")
	)
	(segment
		(start 391.362946 -90.047064)
		(end 391.488422 -89.921588)
		(width 0.089408)
		(layer "In4.Cu")
		(net "LED_POSTCODE_0")
	)
	(segment
		(start 393.384024 -90.231722)
		(end 394.48994 -90.231722)
		(width 0.089408)
		(layer "In4.Cu")
		(net "LED_POSTCODE_0")
	)
	(segment
		(start 392.307064 -89.836498)
		(end 392.9888 -89.836498)
		(width 0.089408)
		(layer "In4.Cu")
		(net "LED_POSTCODE_0")
	)
	(segment
		(start 397.786098 -68.34632)
		(end 397.786098 -68.188332)
		(width 0.089408)
		(layer "In9.Cu")
		(net "LED_POSTCODE_0")
	)
	(segment
		(start 401.380198 -61.591952)
		(end 401.380198 -61.116972)
		(width 0.089408)
		(layer "In9.Cu")
		(net "LED_POSTCODE_0")
	)
	(segment
		(start 399.732754 -55.19039)
		(end 399.733008 -55.190136)
		(width 0.089408)
		(layer "In9.Cu")
		(net "LED_POSTCODE_0")
	)
	(segment
		(start 390.373108 -90.267028)
		(end 390.1821 -90.07602)
		(width 0.089408)
		(layer "In9.Cu")
		(net "LED_POSTCODE_0")
	)
	(segment
		(start 401.380452 -61.592206)
		(end 401.380198 -61.591952)
		(width 0.089408)
		(layer "In9.Cu")
		(net "LED_POSTCODE_0")
	)
	(segment
		(start 399.733008 -55.190136)
		(end 399.733008 -47.770542)
		(width 0.089408)
		(layer "In9.Cu")
		(net "LED_POSTCODE_0")
	)
	(segment
		(start 403.091396 -43.439334)
		(end 403.091396 -40.92956)
		(width 0.089408)
		(layer "In9.Cu")
		(net "LED_POSTCODE_0")
	)
	(segment
		(start 390.1821 -88.831166)
		(end 393.118594 -85.894672)
		(width 0.089408)
		(layer "In9.Cu")
		(net "LED_POSTCODE_0")
	)
	(segment
		(start 394.763752 -82.759804)
		(end 395.372844 -82.150712)
		(width 0.089408)
		(layer "In9.Cu")
		(net "LED_POSTCODE_0")
	)
	(segment
		(start 405.258016 -40.691054)
		(end 405.967946 -40.691054)
		(width 0.089408)
		(layer "In9.Cu")
		(net "LED_POSTCODE_0")
	)
	(segment
		(start 395.372844 -82.150712)
		(end 395.372844 -80.608932)
		(width 0.089408)
		(layer "In9.Cu")
		(net "LED_POSTCODE_0")
	)
	(segment
		(start 397.786352 -68.346574)
		(end 397.786098 -68.34632)
		(width 0.089408)
		(layer "In9.Cu")
		(net "LED_POSTCODE_0")
	)
	(segment
		(start 395.074902 -80.31099)
		(end 395.074902 -77.731874)
		(width 0.089408)
		(layer "In9.Cu")
		(net "LED_POSTCODE_0")
	)
	(segment
		(start 390.373108 -90.87231)
		(end 390.373108 -90.267028)
		(width 0.089408)
		(layer "In9.Cu")
		(net "LED_POSTCODE_0")
	)
	(segment
		(start 404.459694 -39.77005)
		(end 404.51024 -39.820596)
		(width 0.089408)
		(layer "In9.Cu")
		(net "LED_POSTCODE_0")
	)
	(segment
		(start 396.40764 -74.906886)
		(end 396.912592 -74.401934)
		(width 0.089408)
		(layer "In9.Cu")
		(net "LED_POSTCODE_0")
	)
	(segment
		(start 397.180054 -73.021952)
		(end 397.180054 -71.463408)
		(width 0.089408)
		(layer "In9.Cu")
		(net "LED_POSTCODE_0")
	)
	(segment
		(start 404.730204 -40.04056)
		(end 404.7363 -40.046656)
		(width 0.089408)
		(layer "In9.Cu")
		(net "LED_POSTCODE_0")
	)
	(segment
		(start 399.733008 -47.770542)
		(end 402.203666 -45.299884)
		(width 0.089408)
		(layer "In9.Cu")
		(net "LED_POSTCODE_0")
	)
	(segment
		(start 404.250906 -39.77005)
		(end 404.459694 -39.77005)
		(width 0.089408)
		(layer "In9.Cu")
		(net "LED_POSTCODE_0")
	)
	(segment
		(start 404.730204 -40.040052)
		(end 404.730204 -40.04056)
		(width 0.089408)
		(layer "In9.Cu")
		(net "LED_POSTCODE_0")
	)
	(segment
		(start 390.779 -91.278202)
		(end 390.373108 -90.87231)
		(width 0.089408)
		(layer "In9.Cu")
		(net "LED_POSTCODE_0")
	)
	(segment
		(start 403.980396 -40.040052)
		(end 404.199852 -39.820596)
		(width 0.089408)
		(layer "In9.Cu")
		(net "LED_POSTCODE_0")
	)
	(segment
		(start 401.380452 -61.750194)
		(end 401.380452 -61.592206)
		(width 0.089408)
		(layer "In9.Cu")
		(net "LED_POSTCODE_0")
	)
	(segment
		(start 395.074902 -77.731874)
		(end 396.40764 -76.399136)
		(width 0.089408)
		(layer "In9.Cu")
		(net "LED_POSTCODE_0")
	)
	(segment
		(start 404.7363 -40.046656)
		(end 404.7363 -40.169338)
		(width 0.089408)
		(layer "In9.Cu")
		(net "LED_POSTCODE_0")
	)
	(segment
		(start 393.118594 -85.894672)
		(end 393.312396 -85.894672)
		(width 0.089408)
		(layer "In9.Cu")
		(net "LED_POSTCODE_0")
	)
	(segment
		(start 397.786352 -70.85711)
		(end 397.786352 -68.346574)
		(width 0.089408)
		(layer "In9.Cu")
		(net "LED_POSTCODE_0")
	)
	(segment
		(start 400.038824 -65.935606)
		(end 400.038824 -63.091822)
		(width 0.089408)
		(layer "In9.Cu")
		(net "LED_POSTCODE_0")
	)
	(segment
		(start 394.170408 -84.032852)
		(end 394.763752 -83.439508)
		(width 0.089408)
		(layer "In9.Cu")
		(net "LED_POSTCODE_0")
	)
	(segment
		(start 396.912592 -74.401934)
		(end 396.912592 -73.289414)
		(width 0.089408)
		(layer "In9.Cu")
		(net "LED_POSTCODE_0")
	)
	(segment
		(start 401.379944 -58.536332)
		(end 399.733008 -56.889396)
		(width 0.089408)
		(layer "In9.Cu")
		(net "LED_POSTCODE_0")
	)
	(segment
		(start 404.199852 -39.820596)
		(end 404.20036 -39.820596)
		(width 0.089408)
		(layer "In9.Cu")
		(net "LED_POSTCODE_0")
	)
	(segment
		(start 402.203666 -45.299884)
		(end 402.203666 -44.327064)
		(width 0.089408)
		(layer "In9.Cu")
		(net "LED_POSTCODE_0")
	)
	(segment
		(start 403.980396 -40.04056)
		(end 403.980396 -40.040052)
		(width 0.089408)
		(layer "In9.Cu")
		(net "LED_POSTCODE_0")
	)
	(segment
		(start 397.786098 -68.188332)
		(end 400.038824 -65.935606)
		(width 0.089408)
		(layer "In9.Cu")
		(net "LED_POSTCODE_0")
	)
	(segment
		(start 393.312396 -85.894672)
		(end 394.170408 -85.03666)
		(width 0.089408)
		(layer "In9.Cu")
		(net "LED_POSTCODE_0")
	)
	(segment
		(start 404.20036 -39.820596)
		(end 404.250906 -39.77005)
		(width 0.089408)
		(layer "In9.Cu")
		(net "LED_POSTCODE_0")
	)
	(segment
		(start 403.091396 -40.92956)
		(end 403.980396 -40.04056)
		(width 0.089408)
		(layer "In9.Cu")
		(net "LED_POSTCODE_0")
	)
	(segment
		(start 401.380198 -61.116972)
		(end 401.379944 -61.116718)
		(width 0.089408)
		(layer "In9.Cu")
		(net "LED_POSTCODE_0")
	)
	(segment
		(start 396.40764 -76.399136)
		(end 396.40764 -74.906886)
		(width 0.089408)
		(layer "In9.Cu")
		(net "LED_POSTCODE_0")
	)
	(segment
		(start 401.379944 -61.116718)
		(end 401.379944 -58.536332)
		(width 0.089408)
		(layer "In9.Cu")
		(net "LED_POSTCODE_0")
	)
	(segment
		(start 394.763752 -83.439508)
		(end 394.763752 -82.759804)
		(width 0.089408)
		(layer "In9.Cu")
		(net "LED_POSTCODE_0")
	)
	(segment
		(start 399.733008 -56.889396)
		(end 399.733008 -56.775096)
		(width 0.089408)
		(layer "In9.Cu")
		(net "LED_POSTCODE_0")
	)
	(segment
		(start 394.170408 -85.03666)
		(end 394.170408 -84.032852)
		(width 0.089408)
		(layer "In9.Cu")
		(net "LED_POSTCODE_0")
	)
	(segment
		(start 399.732754 -56.774842)
		(end 399.732754 -55.19039)
		(width 0.089408)
		(layer "In9.Cu")
		(net "LED_POSTCODE_0")
	)
	(segment
		(start 399.733008 -56.775096)
		(end 399.732754 -56.774842)
		(width 0.089408)
		(layer "In9.Cu")
		(net "LED_POSTCODE_0")
	)
	(segment
		(start 404.7363 -40.169338)
		(end 405.258016 -40.691054)
		(width 0.089408)
		(layer "In9.Cu")
		(net "LED_POSTCODE_0")
	)
	(segment
		(start 400.038824 -63.091822)
		(end 401.380452 -61.750194)
		(width 0.089408)
		(layer "In9.Cu")
		(net "LED_POSTCODE_0")
	)
	(segment
		(start 404.51024 -39.820596)
		(end 404.510748 -39.820596)
		(width 0.089408)
		(layer "In9.Cu")
		(net "LED_POSTCODE_0")
	)
	(segment
		(start 397.180054 -71.463408)
		(end 397.786352 -70.85711)
		(width 0.089408)
		(layer "In9.Cu")
		(net "LED_POSTCODE_0")
	)
	(segment
		(start 404.510748 -39.820596)
		(end 404.730204 -40.040052)
		(width 0.089408)
		(layer "In9.Cu")
		(net "LED_POSTCODE_0")
	)
	(segment
		(start 402.203666 -44.327064)
		(end 403.091396 -43.439334)
		(width 0.089408)
		(layer "In9.Cu")
		(net "LED_POSTCODE_0")
	)
	(segment
		(start 390.1821 -90.07602)
		(end 390.1821 -88.831166)
		(width 0.089408)
		(layer "In9.Cu")
		(net "LED_POSTCODE_0")
	)
	(segment
		(start 395.372844 -80.608932)
		(end 395.074902 -80.31099)
		(width 0.089408)
		(layer "In9.Cu")
		(net "LED_POSTCODE_0")
	)
	(segment
		(start 396.912592 -73.289414)
		(end 397.180054 -73.021952)
		(width 0.089408)
		(layer "In9.Cu")
		(net "LED_POSTCODE_0")
	)
	(segment
		(start 405.967946 -40.691054)
		(end 406.52446 -40.13454)
		(width 0.089408)
		(layer "In9.Cu")
		(net "LED_POSTCODE_0")
	)
	(segment
		(start 407.447242 -40.577516)
		(end 407.890218 -40.13454)
		(width 0.10795)
		(layer "F.Cu")
		(net "LED_POSTCODE_1")
	)
	(segment
		(start 405.944324 -40.577516)
		(end 407.447242 -40.577516)
		(width 0.10795)
		(layer "F.Cu")
		(net "LED_POSTCODE_1")
	)
	(segment
		(start 405.492458 -40.12565)
		(end 405.944324 -40.577516)
		(width 0.10795)
		(layer "F.Cu")
		(net "LED_POSTCODE_1")
	)
	(via
		(at 402.971 -91.0336)
		(size 0.508)
		(drill 0.254)
		(layers "F.Cu" "B.Cu")
		(net "LED_POSTCODE_1")
	)
	(via
		(at 389.58266 -91.511882)
		(size 0.508)
		(drill 0.254)
		(layers "F.Cu" "B.Cu")
		(net "LED_POSTCODE_1")
	)
	(via
		(at 405.492458 -40.12565)
		(size 0.4572)
		(drill 0.2032)
		(layers "F.Cu" "B.Cu")
		(net "LED_POSTCODE_1")
	)
	(via
		(at 492.7092 -138.7602)
		(size 0.508)
		(drill 0.254)
		(layers "F.Cu" "B.Cu")
		(net "LED_POSTCODE_1")
	)
	(segment
		(start 494.134902 -137.903458)
		(end 494.134902 -138.121898)
		(width 0.10795)
		(layer "B.Cu")
		(net "LED_POSTCODE_1")
	)
	(segment
		(start 493.6744 -138.5824)
		(end 492.887 -138.5824)
		(width 0.10795)
		(layer "B.Cu")
		(net "LED_POSTCODE_1")
	)
	(segment
		(start 494.26876 -137.7696)
		(end 494.134902 -137.903458)
		(width 0.10795)
		(layer "B.Cu")
		(net "LED_POSTCODE_1")
	)
	(segment
		(start 494.134902 -138.121898)
		(end 493.6744 -138.5824)
		(width 0.10795)
		(layer "B.Cu")
		(net "LED_POSTCODE_1")
	)
	(segment
		(start 494.4872 -137.7696)
		(end 494.26876 -137.7696)
		(width 0.10795)
		(layer "B.Cu")
		(net "LED_POSTCODE_1")
	)
	(segment
		(start 492.887 -138.5824)
		(end 492.7092 -138.7602)
		(width 0.10795)
		(layer "B.Cu")
		(net "LED_POSTCODE_1")
	)
	(segment
		(start 402.971 -91.0336)
		(end 403.401276 -91.463876)
		(width 0.089408)
		(layer "In2.Cu")
		(net "LED_POSTCODE_1")
	)
	(segment
		(start 408.135328 -113.593118)
		(end 408.135328 -113.734596)
		(width 0.089408)
		(layer "In2.Cu")
		(net "LED_POSTCODE_1")
	)
	(segment
		(start 412.39948 -116.8654)
		(end 414.507172 -118.973092)
		(width 0.089408)
		(layer "In2.Cu")
		(net "LED_POSTCODE_1")
	)
	(segment
		(start 403.662642 -91.463876)
		(end 403.75205 -91.553284)
		(width 0.089408)
		(layer "In2.Cu")
		(net "LED_POSTCODE_1")
	)
	(segment
		(start 489.78058 -131.826)
		(end 490.91088 -131.826)
		(width 0.089408)
		(layer "In2.Cu")
		(net "LED_POSTCODE_1")
	)
	(segment
		(start 408.052016 -109.531404)
		(end 408.052016 -112.319816)
		(width 0.089408)
		(layer "In2.Cu")
		(net "LED_POSTCODE_1")
	)
	(segment
		(start 437.01843 -116.786152)
		(end 465.94903 -116.786152)
		(width 0.089408)
		(layer "In2.Cu")
		(net "LED_POSTCODE_1")
	)
	(segment
		(start 465.94903 -116.786152)
		(end 466.30971 -117.146832)
		(width 0.089408)
		(layer "In2.Cu")
		(net "LED_POSTCODE_1")
	)
	(segment
		(start 492.53394 -133.44906)
		(end 492.53394 -136.62914)
		(width 0.089408)
		(layer "In2.Cu")
		(net "LED_POSTCODE_1")
	)
	(segment
		(start 479.806 -122.892312)
		(end 479.806 -127.127)
		(width 0.089408)
		(layer "In2.Cu")
		(net "LED_POSTCODE_1")
	)
	(segment
		(start 427.84522 -120.021096)
		(end 433.783486 -120.021096)
		(width 0.089408)
		(layer "In2.Cu")
		(net "LED_POSTCODE_1")
	)
	(segment
		(start 488.665012 -130.710432)
		(end 489.78058 -131.826)
		(width 0.089408)
		(layer "In2.Cu")
		(net "LED_POSTCODE_1")
	)
	(segment
		(start 408.135074 -113.592864)
		(end 408.135328 -113.593118)
		(width 0.089408)
		(layer "In2.Cu")
		(net "LED_POSTCODE_1")
	)
	(segment
		(start 421.1955 -119.873776)
		(end 421.520874 -120.19915)
		(width 0.089408)
		(layer "In2.Cu")
		(net "LED_POSTCODE_1")
	)
	(segment
		(start 406.507696 -103.640636)
		(end 407.173684 -103.640636)
		(width 0.089408)
		(layer "In2.Cu")
		(net "LED_POSTCODE_1")
	)
	(segment
		(start 407.173684 -103.640636)
		(end 407.944828 -104.41178)
		(width 0.089408)
		(layer "In2.Cu")
		(net "LED_POSTCODE_1")
	)
	(segment
		(start 476.069406 -117.599206)
		(end 477.800162 -119.329962)
		(width 0.089408)
		(layer "In2.Cu")
		(net "LED_POSTCODE_1")
	)
	(segment
		(start 404.389336 -101.522276)
		(end 406.507696 -103.640636)
		(width 0.089408)
		(layer "In2.Cu")
		(net "LED_POSTCODE_1")
	)
	(segment
		(start 488.240832 -130.710432)
		(end 488.665012 -130.710432)
		(width 0.089408)
		(layer "In2.Cu")
		(net "LED_POSTCODE_1")
	)
	(segment
		(start 411.266132 -116.8654)
		(end 412.39948 -116.8654)
		(width 0.089408)
		(layer "In2.Cu")
		(net "LED_POSTCODE_1")
	)
	(segment
		(start 408.052016 -112.319816)
		(end 408.135328 -112.403128)
		(width 0.089408)
		(layer "In2.Cu")
		(net "LED_POSTCODE_1")
	)
	(segment
		(start 408.135074 -113.117884)
		(end 408.135074 -113.592864)
		(width 0.089408)
		(layer "In2.Cu")
		(net "LED_POSTCODE_1")
	)
	(segment
		(start 404.389336 -100.311204)
		(end 404.389336 -101.522276)
		(width 0.089408)
		(layer "In2.Cu")
		(net "LED_POSTCODE_1")
	)
	(segment
		(start 403.75205 -91.553284)
		(end 403.75205 -99.673918)
		(width 0.089408)
		(layer "In2.Cu")
		(net "LED_POSTCODE_1")
	)
	(segment
		(start 403.75205 -99.673918)
		(end 404.389336 -100.311204)
		(width 0.089408)
		(layer "In2.Cu")
		(net "LED_POSTCODE_1")
	)
	(segment
		(start 423.99458 -120.19915)
		(end 424.592242 -119.601488)
		(width 0.089408)
		(layer "In2.Cu")
		(net "LED_POSTCODE_1")
	)
	(segment
		(start 479.806 -127.127)
		(end 481.33 -128.651)
		(width 0.089408)
		(layer "In2.Cu")
		(net "LED_POSTCODE_1")
	)
	(segment
		(start 477.800162 -120.886474)
		(end 479.806 -122.892312)
		(width 0.089408)
		(layer "In2.Cu")
		(net "LED_POSTCODE_1")
	)
	(segment
		(start 414.507172 -118.973092)
		(end 414.987994 -118.973092)
		(width 0.089408)
		(layer "In2.Cu")
		(net "LED_POSTCODE_1")
	)
	(segment
		(start 493.522 -137.6172)
		(end 493.522 -138.1252)
		(width 0.089408)
		(layer "In2.Cu")
		(net "LED_POSTCODE_1")
	)
	(segment
		(start 486.1814 -128.651)
		(end 488.240832 -130.710432)
		(width 0.089408)
		(layer "In2.Cu")
		(net "LED_POSTCODE_1")
	)
	(segment
		(start 493.522 -138.1252)
		(end 492.887 -138.7602)
		(width 0.089408)
		(layer "In2.Cu")
		(net "LED_POSTCODE_1")
	)
	(segment
		(start 481.33 -128.651)
		(end 486.1814 -128.651)
		(width 0.089408)
		(layer "In2.Cu")
		(net "LED_POSTCODE_1")
	)
	(segment
		(start 466.30971 -117.146832)
		(end 469.230456 -117.146832)
		(width 0.089408)
		(layer "In2.Cu")
		(net "LED_POSTCODE_1")
	)
	(segment
		(start 408.135328 -113.734596)
		(end 411.266132 -116.8654)
		(width 0.089408)
		(layer "In2.Cu")
		(net "LED_POSTCODE_1")
	)
	(segment
		(start 469.230456 -117.146832)
		(end 469.68283 -117.599206)
		(width 0.089408)
		(layer "In2.Cu")
		(net "LED_POSTCODE_1")
	)
	(segment
		(start 469.68283 -117.599206)
		(end 476.069406 -117.599206)
		(width 0.089408)
		(layer "In2.Cu")
		(net "LED_POSTCODE_1")
	)
	(segment
		(start 492.53394 -136.62914)
		(end 493.522 -137.6172)
		(width 0.089408)
		(layer "In2.Cu")
		(net "LED_POSTCODE_1")
	)
	(segment
		(start 414.987994 -118.973092)
		(end 415.888678 -119.873776)
		(width 0.089408)
		(layer "In2.Cu")
		(net "LED_POSTCODE_1")
	)
	(segment
		(start 433.783486 -120.021096)
		(end 437.01843 -116.786152)
		(width 0.089408)
		(layer "In2.Cu")
		(net "LED_POSTCODE_1")
	)
	(segment
		(start 415.888678 -119.873776)
		(end 421.1955 -119.873776)
		(width 0.089408)
		(layer "In2.Cu")
		(net "LED_POSTCODE_1")
	)
	(segment
		(start 408.135328 -112.403128)
		(end 408.135328 -113.11763)
		(width 0.089408)
		(layer "In2.Cu")
		(net "LED_POSTCODE_1")
	)
	(segment
		(start 427.425612 -119.601488)
		(end 427.84522 -120.021096)
		(width 0.089408)
		(layer "In2.Cu")
		(net "LED_POSTCODE_1")
	)
	(segment
		(start 408.135328 -113.11763)
		(end 408.135074 -113.117884)
		(width 0.089408)
		(layer "In2.Cu")
		(net "LED_POSTCODE_1")
	)
	(segment
		(start 421.520874 -120.19915)
		(end 423.99458 -120.19915)
		(width 0.089408)
		(layer "In2.Cu")
		(net "LED_POSTCODE_1")
	)
	(segment
		(start 490.91088 -131.826)
		(end 492.53394 -133.44906)
		(width 0.089408)
		(layer "In2.Cu")
		(net "LED_POSTCODE_1")
	)
	(segment
		(start 403.401276 -91.463876)
		(end 403.662642 -91.463876)
		(width 0.089408)
		(layer "In2.Cu")
		(net "LED_POSTCODE_1")
	)
	(segment
		(start 477.800162 -119.329962)
		(end 477.800162 -120.886474)
		(width 0.089408)
		(layer "In2.Cu")
		(net "LED_POSTCODE_1")
	)
	(segment
		(start 492.887 -138.7602)
		(end 492.7092 -138.7602)
		(width 0.089408)
		(layer "In2.Cu")
		(net "LED_POSTCODE_1")
	)
	(segment
		(start 407.944828 -104.41178)
		(end 407.944828 -109.424216)
		(width 0.089408)
		(layer "In2.Cu")
		(net "LED_POSTCODE_1")
	)
	(segment
		(start 424.592242 -119.601488)
		(end 427.425612 -119.601488)
		(width 0.089408)
		(layer "In2.Cu")
		(net "LED_POSTCODE_1")
	)
	(segment
		(start 407.944828 -109.424216)
		(end 408.052016 -109.531404)
		(width 0.089408)
		(layer "In2.Cu")
		(net "LED_POSTCODE_1")
	)
	(segment
		(start 390.297416 -92.288106)
		(end 389.580882 -91.571572)
		(width 0.089408)
		(layer "In4.Cu")
		(net "LED_POSTCODE_1")
	)
	(segment
		(start 389.580882 -91.571572)
		(end 389.580882 -91.511882)
		(width 0.089408)
		(layer "In4.Cu")
		(net "LED_POSTCODE_1")
	)
	(segment
		(start 390.297416 -93.145864)
		(end 390.297416 -92.288106)
		(width 0.089408)
		(layer "In4.Cu")
		(net "LED_POSTCODE_1")
	)
	(segment
		(start 402.971 -91.0336)
		(end 402.352256 -91.0336)
		(width 0.089408)
		(layer "In4.Cu")
		(net "LED_POSTCODE_1")
	)
	(segment
		(start 396.5702 -91.538552)
		(end 396.5702 -93.14942)
		(width 0.089408)
		(layer "In4.Cu")
		(net "LED_POSTCODE_1")
	)
	(segment
		(start 396.5702 -93.14942)
		(end 396.19682 -93.5228)
		(width 0.089408)
		(layer "In4.Cu")
		(net "LED_POSTCODE_1")
	)
	(segment
		(start 396.19682 -93.5228)
		(end 390.674352 -93.5228)
		(width 0.089408)
		(layer "In4.Cu")
		(net "LED_POSTCODE_1")
	)
	(segment
		(start 389.580882 -91.511882)
		(end 389.58266 -91.511882)
		(width 0.089408)
		(layer "In4.Cu")
		(net "LED_POSTCODE_1")
	)
	(segment
		(start 401.790408 -90.471752)
		(end 397.637 -90.471752)
		(width 0.089408)
		(layer "In4.Cu")
		(net "LED_POSTCODE_1")
	)
	(segment
		(start 390.674352 -93.5228)
		(end 390.297416 -93.145864)
		(width 0.089408)
		(layer "In4.Cu")
		(net "LED_POSTCODE_1")
	)
	(segment
		(start 402.352256 -91.0336)
		(end 401.790408 -90.471752)
		(width 0.089408)
		(layer "In4.Cu")
		(net "LED_POSTCODE_1")
	)
	(segment
		(start 397.637 -90.471752)
		(end 396.5702 -91.538552)
		(width 0.089408)
		(layer "In4.Cu")
		(net "LED_POSTCODE_1")
	)
	(segment
		(start 399.350992 -55.03164)
		(end 399.350738 -55.031894)
		(width 0.089408)
		(layer "In9.Cu")
		(net "LED_POSTCODE_1")
	)
	(segment
		(start 401.82165 -45.141388)
		(end 399.350992 -47.612046)
		(width 0.089408)
		(layer "In9.Cu")
		(net "LED_POSTCODE_1")
	)
	(segment
		(start 396.798038 -72.847962)
		(end 396.530576 -73.115424)
		(width 0.089408)
		(layer "In9.Cu")
		(net "LED_POSTCODE_1")
	)
	(segment
		(start 399.656808 -62.933326)
		(end 399.656808 -65.77711)
		(width 0.089408)
		(layer "In9.Cu")
		(net "LED_POSTCODE_1")
	)
	(segment
		(start 399.350992 -56.933592)
		(end 399.350992 -57.047892)
		(width 0.089408)
		(layer "In9.Cu")
		(net "LED_POSTCODE_1")
	)
	(segment
		(start 397.404336 -68.50507)
		(end 397.404336 -70.698614)
		(width 0.089408)
		(layer "In9.Cu")
		(net "LED_POSTCODE_1")
	)
	(segment
		(start 396.530576 -73.115424)
		(end 396.530576 -74.01179)
		(width 0.089408)
		(layer "In9.Cu")
		(net "LED_POSTCODE_1")
	)
	(segment
		(start 404.478744 -39.388034)
		(end 403.238462 -39.388034)
		(width 0.089408)
		(layer "In9.Cu")
		(net "LED_POSTCODE_1")
	)
	(segment
		(start 404.75535 -39.388542)
		(end 404.558246 -39.388542)
		(width 0.089408)
		(layer "In9.Cu")
		(net "LED_POSTCODE_1")
	)
	(segment
		(start 400.998182 -61.591952)
		(end 399.656808 -62.933326)
		(width 0.089408)
		(layer "In9.Cu")
		(net "LED_POSTCODE_1")
	)
	(segment
		(start 393.1539 -85.512656)
		(end 392.960098 -85.512656)
		(width 0.089408)
		(layer "In9.Cu")
		(net "LED_POSTCODE_1")
	)
	(segment
		(start 400.998182 -61.275468)
		(end 400.998182 -61.591952)
		(width 0.089408)
		(layer "In9.Cu")
		(net "LED_POSTCODE_1")
	)
	(segment
		(start 399.350992 -47.612046)
		(end 399.350992 -55.03164)
		(width 0.089408)
		(layer "In9.Cu")
		(net "LED_POSTCODE_1")
	)
	(segment
		(start 389.800084 -88.67267)
		(end 389.800084 -90.234516)
		(width 0.089408)
		(layer "In9.Cu")
		(net "LED_POSTCODE_1")
	)
	(segment
		(start 393.788392 -84.878164)
		(end 393.1539 -85.512656)
		(width 0.089408)
		(layer "In9.Cu")
		(net "LED_POSTCODE_1")
	)
	(segment
		(start 397.404082 -68.029836)
		(end 397.404082 -68.504816)
		(width 0.089408)
		(layer "In9.Cu")
		(net "LED_POSTCODE_1")
	)
	(segment
		(start 389.81253 -90.246962)
		(end 389.81253 -91.282012)
		(width 0.089408)
		(layer "In9.Cu")
		(net "LED_POSTCODE_1")
	)
	(segment
		(start 389.800084 -90.234516)
		(end 389.81253 -90.246962)
		(width 0.089408)
		(layer "In9.Cu")
		(net "LED_POSTCODE_1")
	)
	(segment
		(start 394.692886 -77.573378)
		(end 394.692886 -80.469486)
		(width 0.089408)
		(layer "In9.Cu")
		(net "LED_POSTCODE_1")
	)
	(segment
		(start 401.82165 -44.125896)
		(end 401.82165 -45.141388)
		(width 0.089408)
		(layer "In9.Cu")
		(net "LED_POSTCODE_1")
	)
	(segment
		(start 402.70938 -39.917116)
		(end 402.70938 -43.238166)
		(width 0.089408)
		(layer "In9.Cu")
		(net "LED_POSTCODE_1")
	)
	(segment
		(start 405.492458 -40.12565)
		(end 404.75535 -39.388542)
		(width 0.089408)
		(layer "In9.Cu")
		(net "LED_POSTCODE_1")
	)
	(segment
		(start 394.692886 -80.469486)
		(end 394.990828 -80.767428)
		(width 0.089408)
		(layer "In9.Cu")
		(net "LED_POSTCODE_1")
	)
	(segment
		(start 394.990828 -80.767428)
		(end 394.990828 -81.992216)
		(width 0.089408)
		(layer "In9.Cu")
		(net "LED_POSTCODE_1")
	)
	(segment
		(start 396.025624 -76.24064)
		(end 394.692886 -77.573378)
		(width 0.089408)
		(layer "In9.Cu")
		(net "LED_POSTCODE_1")
	)
	(segment
		(start 392.960098 -85.512656)
		(end 389.800084 -88.67267)
		(width 0.089408)
		(layer "In9.Cu")
		(net "LED_POSTCODE_1")
	)
	(segment
		(start 394.381736 -82.601308)
		(end 394.381736 -83.281012)
		(width 0.089408)
		(layer "In9.Cu")
		(net "LED_POSTCODE_1")
	)
	(segment
		(start 399.350738 -56.933338)
		(end 399.350992 -56.933592)
		(width 0.089408)
		(layer "In9.Cu")
		(net "LED_POSTCODE_1")
	)
	(segment
		(start 394.990828 -81.992216)
		(end 394.381736 -82.601308)
		(width 0.089408)
		(layer "In9.Cu")
		(net "LED_POSTCODE_1")
	)
	(segment
		(start 399.350992 -57.047892)
		(end 400.997928 -58.694828)
		(width 0.089408)
		(layer "In9.Cu")
		(net "LED_POSTCODE_1")
	)
	(segment
		(start 394.381736 -83.281012)
		(end 393.788392 -83.874356)
		(width 0.089408)
		(layer "In9.Cu")
		(net "LED_POSTCODE_1")
	)
	(segment
		(start 400.997928 -61.275214)
		(end 400.998182 -61.275468)
		(width 0.089408)
		(layer "In9.Cu")
		(net "LED_POSTCODE_1")
	)
	(segment
		(start 399.350738 -55.031894)
		(end 399.350738 -56.933338)
		(width 0.089408)
		(layer "In9.Cu")
		(net "LED_POSTCODE_1")
	)
	(segment
		(start 396.530576 -74.01179)
		(end 396.025624 -74.516742)
		(width 0.089408)
		(layer "In9.Cu")
		(net "LED_POSTCODE_1")
	)
	(segment
		(start 397.404082 -68.504816)
		(end 397.404336 -68.50507)
		(width 0.089408)
		(layer "In9.Cu")
		(net "LED_POSTCODE_1")
	)
	(segment
		(start 403.238462 -39.388034)
		(end 402.70938 -39.917116)
		(width 0.089408)
		(layer "In9.Cu")
		(net "LED_POSTCODE_1")
	)
	(segment
		(start 393.788392 -83.874356)
		(end 393.788392 -84.878164)
		(width 0.089408)
		(layer "In9.Cu")
		(net "LED_POSTCODE_1")
	)
	(segment
		(start 389.81253 -91.282012)
		(end 389.58266 -91.511882)
		(width 0.089408)
		(layer "In9.Cu")
		(net "LED_POSTCODE_1")
	)
	(segment
		(start 404.557992 -39.388288)
		(end 404.478998 -39.388288)
		(width 0.089408)
		(layer "In9.Cu")
		(net "LED_POSTCODE_1")
	)
	(segment
		(start 397.404336 -70.698614)
		(end 396.798038 -71.304912)
		(width 0.089408)
		(layer "In9.Cu")
		(net "LED_POSTCODE_1")
	)
	(segment
		(start 396.025624 -74.516742)
		(end 396.025624 -76.24064)
		(width 0.089408)
		(layer "In9.Cu")
		(net "LED_POSTCODE_1")
	)
	(segment
		(start 402.70938 -43.238166)
		(end 401.82165 -44.125896)
		(width 0.089408)
		(layer "In9.Cu")
		(net "LED_POSTCODE_1")
	)
	(segment
		(start 404.478998 -39.388288)
		(end 404.478744 -39.388034)
		(width 0.089408)
		(layer "In9.Cu")
		(net "LED_POSTCODE_1")
	)
	(segment
		(start 396.798038 -71.304912)
		(end 396.798038 -72.847962)
		(width 0.089408)
		(layer "In9.Cu")
		(net "LED_POSTCODE_1")
	)
	(segment
		(start 399.656808 -65.77711)
		(end 397.404082 -68.029836)
		(width 0.089408)
		(layer "In9.Cu")
		(net "LED_POSTCODE_1")
	)
	(segment
		(start 400.997928 -58.694828)
		(end 400.997928 -61.275214)
		(width 0.089408)
		(layer "In9.Cu")
		(net "LED_POSTCODE_1")
	)
	(segment
		(start 404.558246 -39.388542)
		(end 404.557992 -39.388288)
		(width 0.089408)
		(layer "In9.Cu")
		(net "LED_POSTCODE_1")
	)
	(segment
		(start 168.0972 -149.5552)
		(end 168.148 -149.606)
		(width 0.10795)
		(layer "F.Cu")
		(net "FM_PVTT_KLM_EN_R")
	)
	(segment
		(start 167.4876 -149.225)
		(end 167.9194 -149.225)
		(width 0.10795)
		(layer "F.Cu")
		(net "FM_PVTT_KLM_EN_R")
	)
	(segment
		(start 167.513 -149.2504)
		(end 167.513 -150.241)
		(width 0.10795)
		(layer "F.Cu")
		(net "FM_PVTT_KLM_EN_R")
	)
	(segment
		(start 169.11193 -147.929346)
		(end 168.26865 -147.929346)
		(width 0.10795)
		(layer "F.Cu")
		(net "FM_PVTT_KLM_EN_R")
	)
	(segment
		(start 167.513 -149.1996)
		(end 167.4876 -149.225)
		(width 0.10795)
		(layer "F.Cu")
		(net "FM_PVTT_KLM_EN_R")
	)
	(segment
		(start 167.4876 -149.225)
		(end 167.513 -149.2504)
		(width 0.10795)
		(layer "F.Cu")
		(net "FM_PVTT_KLM_EN_R")
	)
	(segment
		(start 168.26865 -147.929346)
		(end 167.513 -148.684996)
		(width 0.10795)
		(layer "F.Cu")
		(net "FM_PVTT_KLM_EN_R")
	)
	(segment
		(start 167.9194 -149.225)
		(end 168.0972 -149.4028)
		(width 0.10795)
		(layer "F.Cu")
		(net "FM_PVTT_KLM_EN_R")
	)
	(segment
		(start 167.513 -148.684996)
		(end 167.513 -149.1996)
		(width 0.10795)
		(layer "F.Cu")
		(net "FM_PVTT_KLM_EN_R")
	)
	(segment
		(start 168.0972 -149.4028)
		(end 168.0972 -149.5552)
		(width 0.10795)
		(layer "F.Cu")
		(net "FM_PVTT_KLM_EN_R")
	)
	(via
		(at 167.2844 -150.0886)
		(size 0.6604)
		(drill 0.3302)
		(layers "F.Cu" "B.Cu")
		(net "FM_PVTT_KLM_EN_R")
	)
	(via
		(at 168.148 -149.606)
		(size 0.508)
		(drill 0.254)
		(layers "F.Cu" "B.Cu")
		(net "FM_PVTT_KLM_EN_R")
	)
	(segment
		(start 167.2844 -149.17928)
		(end 167.72128 -148.7424)
		(width 0.10795)
		(layer "B.Cu")
		(net "FM_PVTT_KLM_EN_R")
	)
	(segment
		(start 168.148 -149.606)
		(end 167.6654 -150.0886)
		(width 0.10795)
		(layer "B.Cu")
		(net "FM_PVTT_KLM_EN_R")
	)
	(segment
		(start 167.2844 -150.0886)
		(end 167.2844 -149.17928)
		(width 0.10795)
		(layer "B.Cu")
		(net "FM_PVTT_KLM_EN_R")
	)
	(segment
		(start 167.6654 -150.0886)
		(end 167.2844 -150.0886)
		(width 0.10795)
		(layer "B.Cu")
		(net "FM_PVTT_KLM_EN_R")
	)
	(segment
		(start 167.3098 -6.5024)
		(end 167.3098 -6.0706)
		(width 0.10795)
		(layer "F.Cu")
		(net "FM_PVTT_GHJ_EN_R")
	)
	(segment
		(start 167.5638 -5.706364)
		(end 167.5638 -5.8166)
		(width 0.10795)
		(layer "F.Cu")
		(net "FM_PVTT_GHJ_EN_R")
	)
	(segment
		(start 167.2844 -6.477)
		(end 167.3098 -6.5024)
		(width 0.10795)
		(layer "F.Cu")
		(net "FM_PVTT_GHJ_EN_R")
	)
	(segment
		(start 166.497 -6.477)
		(end 167.2844 -6.477)
		(width 0.10795)
		(layer "F.Cu")
		(net "FM_PVTT_GHJ_EN_R")
	)
	(segment
		(start 168.59504 -4.675124)
		(end 167.5638 -5.706364)
		(width 0.10795)
		(layer "F.Cu")
		(net "FM_PVTT_GHJ_EN_R")
	)
	(segment
		(start 169.010584 -4.675124)
		(end 168.59504 -4.675124)
		(width 0.10795)
		(layer "F.Cu")
		(net "FM_PVTT_GHJ_EN_R")
	)
	(segment
		(start 167.3098 -6.0706)
		(end 167.5638 -5.8166)
		(width 0.10795)
		(layer "F.Cu")
		(net "FM_PVTT_GHJ_EN_R")
	)
	(via
		(at 167.5638 -5.8166)
		(size 0.508)
		(drill 0.254)
		(layers "F.Cu" "B.Cu")
		(net "FM_PVTT_GHJ_EN_R")
	)
	(via
		(at 169.418 -7.2136)
		(size 0.6604)
		(drill 0.3302)
		(layers "F.Cu" "B.Cu")
		(net "FM_PVTT_GHJ_EN_R")
	)
	(segment
		(start 168.6814 -6.477)
		(end 168.0972 -6.477)
		(width 0.10795)
		(layer "B.Cu")
		(net "FM_PVTT_GHJ_EN_R")
	)
	(segment
		(start 167.5638 -5.9436)
		(end 167.5638 -5.8166)
		(width 0.10795)
		(layer "B.Cu")
		(net "FM_PVTT_GHJ_EN_R")
	)
	(segment
		(start 168.0972 -6.477)
		(end 167.5638 -5.9436)
		(width 0.10795)
		(layer "B.Cu")
		(net "FM_PVTT_GHJ_EN_R")
	)
	(segment
		(start 169.418 -7.2136)
		(end 168.6814 -6.477)
		(width 0.10795)
		(layer "B.Cu")
		(net "FM_PVTT_GHJ_EN_R")
	)
	(segment
		(start 183.491124 -152.1333)
		(end 183.884824 -152.527)
		(width 0.10795)
		(layer "F.Cu")
		(net "FM_PVTT_DEF_EN_R")
	)
	(segment
		(start 183.884824 -152.527)
		(end 184.6072 -152.527)
		(width 0.10795)
		(layer "F.Cu")
		(net "FM_PVTT_DEF_EN_R")
	)
	(segment
		(start 184.6072 -152.527)
		(end 185.4454 -152.527)
		(width 0.10795)
		(layer "F.Cu")
		(net "FM_PVTT_DEF_EN_R")
	)
	(segment
		(start 183.391048 -152.033224)
		(end 183.491124 -152.1333)
		(width 0.10795)
		(layer "F.Cu")
		(net "FM_PVTT_DEF_EN_R")
	)
	(segment
		(start 183.391048 -151.219916)
		(end 183.391048 -152.033224)
		(width 0.10795)
		(layer "F.Cu")
		(net "FM_PVTT_DEF_EN_R")
	)
	(via
		(at 184.3024 -151.0284)
		(size 0.6604)
		(drill 0.3302)
		(layers "F.Cu" "B.Cu")
		(net "FM_PVTT_DEF_EN_R")
	)
	(via
		(at 183.491124 -152.1333)
		(size 0.508)
		(drill 0.254)
		(layers "F.Cu" "B.Cu")
		(net "FM_PVTT_DEF_EN_R")
	)
	(segment
		(start 184.658 -151.384)
		(end 184.3024 -151.0284)
		(width 0.10795)
		(layer "B.Cu")
		(net "FM_PVTT_DEF_EN_R")
	)
	(segment
		(start 184.3024 -151.0284)
		(end 183.9722 -151.0284)
		(width 0.10795)
		(layer "B.Cu")
		(net "FM_PVTT_DEF_EN_R")
	)
	(segment
		(start 184.658 -152.527)
		(end 184.658 -151.384)
		(width 0.10795)
		(layer "B.Cu")
		(net "FM_PVTT_DEF_EN_R")
	)
	(segment
		(start 183.9722 -151.0284)
		(end 183.491124 -151.509476)
		(width 0.10795)
		(layer "B.Cu")
		(net "FM_PVTT_DEF_EN_R")
	)
	(segment
		(start 183.491124 -151.509476)
		(end 183.491124 -152.1333)
		(width 0.10795)
		(layer "B.Cu")
		(net "FM_PVTT_DEF_EN_R")
	)
	(segment
		(start 182.097934 0.973328)
		(end 182.097934 1.536192)
		(width 0.10795)
		(layer "F.Cu")
		(net "FM_PVTT_ABC_EN_R")
	)
	(segment
		(start 182.633874 0.437388)
		(end 182.097934 0.973328)
		(width 0.10795)
		(layer "F.Cu")
		(net "FM_PVTT_ABC_EN_R")
	)
	(segment
		(start 182.633874 0.165608)
		(end 182.633874 0.437388)
		(width 0.10795)
		(layer "F.Cu")
		(net "FM_PVTT_ABC_EN_R")
	)
	(segment
		(start 181.339998 1.536192)
		(end 180.402992 1.536192)
		(width 0.10795)
		(layer "F.Cu")
		(net "FM_PVTT_ABC_EN_R")
	)
	(segment
		(start 182.097934 1.5494)
		(end 181.353206 1.5494)
		(width 0.10795)
		(layer "F.Cu")
		(net "FM_PVTT_ABC_EN_R")
	)
	(segment
		(start 181.353206 1.5494)
		(end 181.339998 1.536192)
		(width 0.10795)
		(layer "F.Cu")
		(net "FM_PVTT_ABC_EN_R")
	)
	(segment
		(start 180.402992 1.536192)
		(end 180.3781 1.5113)
		(width 0.10795)
		(layer "F.Cu")
		(net "FM_PVTT_ABC_EN_R")
	)
	(segment
		(start 180.479954 -0.167132)
		(end 180.3781 -0.065278)
		(width 0.10795)
		(layer "F.Cu")
		(net "FM_PVTT_ABC_EN_R")
	)
	(segment
		(start 182.097934 1.536192)
		(end 182.097934 1.5494)
		(width 0.10795)
		(layer "F.Cu")
		(net "FM_PVTT_ABC_EN_R")
	)
	(segment
		(start 180.3781 -0.065278)
		(end 180.3781 1.5113)
		(width 0.10795)
		(layer "F.Cu")
		(net "FM_PVTT_ABC_EN_R")
	)
	(via
		(at 180.479954 -0.167132)
		(size 0.762)
		(drill 0.381)
		(layers "F.Cu" "B.Cu")
		(net "FM_PVTT_ABC_EN_R")
	)
	(via
		(at 182.097934 1.536192)
		(size 0.508)
		(drill 0.254)
		(layers "F.Cu" "B.Cu")
		(net "FM_PVTT_ABC_EN_R")
	)
	(segment
		(start 182.097934 1.5494)
		(end 182.084726 1.536192)
		(width 0.10795)
		(layer "B.Cu")
		(net "FM_PVTT_ABC_EN_R")
	)
	(segment
		(start 182.084726 1.536192)
		(end 181.339998 1.536192)
		(width 0.10795)
		(layer "B.Cu")
		(net "FM_PVTT_ABC_EN_R")
	)
	(segment
		(start 182.097934 1.536192)
		(end 182.097934 1.5494)
		(width 0.10795)
		(layer "B.Cu")
		(net "FM_PVTT_ABC_EN_R")
	)
	(segment
		(start 397.3068 -87.4522)
		(end 397.3068 -88.671146)
		(width 0.10795)
		(layer "F.Cu")
		(net "FM_BMC_NMI_N")
	)
	(segment
		(start 426.681646 -49.226724)
		(end 425.938696 -49.969674)
		(width 0.10795)
		(layer "F.Cu")
		(net "FM_BMC_NMI_N")
	)
	(segment
		(start 426.681646 -48.968152)
		(end 426.681646 -49.226724)
		(width 0.10795)
		(layer "F.Cu")
		(net "FM_BMC_NMI_N")
	)
	(segment
		(start 395.171676 -90.80627)
		(end 395.171676 -93.28912)
		(width 0.0889)
		(layer "F.Cu")
		(net "FM_BMC_NMI_N")
	)
	(segment
		(start 395.174978 -93.292422)
		(end 395.174978 -93.292676)
		(width 0.0889)
		(layer "F.Cu")
		(net "FM_BMC_NMI_N")
	)
	(segment
		(start 395.280642 -93.724222)
		(end 395.162278 -93.842586)
		(width 0.0889)
		(layer "F.Cu")
		(net "FM_BMC_NMI_N")
	)
	(segment
		(start 396.367 -87.3125)
		(end 397.1671 -87.3125)
		(width 0.10795)
		(layer "F.Cu")
		(net "FM_BMC_NMI_N")
	)
	(segment
		(start 395.174978 -93.292676)
		(end 395.280642 -93.39834)
		(width 0.0889)
		(layer "F.Cu")
		(net "FM_BMC_NMI_N")
	)
	(segment
		(start 395.171676 -93.28912)
		(end 395.174978 -93.292422)
		(width 0.0889)
		(layer "F.Cu")
		(net "FM_BMC_NMI_N")
	)
	(segment
		(start 397.1671 -87.3125)
		(end 397.3068 -87.4522)
		(width 0.10795)
		(layer "F.Cu")
		(net "FM_BMC_NMI_N")
	)
	(segment
		(start 397.3068 -88.671146)
		(end 395.3129 -90.665046)
		(width 0.10795)
		(layer "F.Cu")
		(net "FM_BMC_NMI_N")
	)
	(segment
		(start 399.669 -85.979)
		(end 399.7833 -85.8647)
		(width 0.10795)
		(layer "F.Cu")
		(net "FM_BMC_NMI_N")
	)
	(segment
		(start 395.3129 -90.665046)
		(end 395.171676 -90.80627)
		(width 0.0889)
		(layer "F.Cu")
		(net "FM_BMC_NMI_N")
	)
	(segment
		(start 395.162278 -94.197678)
		(end 394.984986 -94.37497)
		(width 0.0889)
		(layer "F.Cu")
		(net "FM_BMC_NMI_N")
	)
	(segment
		(start 396.367 -85.979)
		(end 399.669 -85.979)
		(width 0.10795)
		(layer "F.Cu")
		(net "FM_BMC_NMI_N")
	)
	(segment
		(start 395.280642 -93.39834)
		(end 395.280642 -93.724222)
		(width 0.0889)
		(layer "F.Cu")
		(net "FM_BMC_NMI_N")
	)
	(segment
		(start 396.367 -87.3125)
		(end 396.367 -85.979)
		(width 0.10795)
		(layer "F.Cu")
		(net "FM_BMC_NMI_N")
	)
	(segment
		(start 395.162278 -93.842586)
		(end 395.162278 -94.197678)
		(width 0.0889)
		(layer "F.Cu")
		(net "FM_BMC_NMI_N")
	)
	(via
		(at 399.7833 -85.8647)
		(size 0.508)
		(drill 0.254)
		(layers "F.Cu" "B.Cu")
		(net "FM_BMC_NMI_N")
	)
	(via
		(at 425.938696 -49.969674)
		(size 0.508)
		(drill 0.254)
		(layers "F.Cu" "B.Cu")
		(net "FM_BMC_NMI_N")
	)
	(segment
		(start 398.502124 -81.085944)
		(end 399.594832 -79.993236)
		(width 0.089408)
		(layer "In2.Cu")
		(net "FM_BMC_NMI_N")
	)
	(segment
		(start 396.048992 -66.358008)
		(end 399.223992 -66.358008)
		(width 0.089408)
		(layer "In2.Cu")
		(net "FM_BMC_NMI_N")
	)
	(segment
		(start 416.7759 -49.738788)
		(end 418.171884 -48.342804)
		(width 0.089408)
		(layer "In2.Cu")
		(net "FM_BMC_NMI_N")
	)
	(segment
		(start 399.7833 -85.8647)
		(end 399.790158 -85.857842)
		(width 0.089408)
		(layer "In2.Cu")
		(net "FM_BMC_NMI_N")
	)
	(segment
		(start 425.938696 -49.666144)
		(end 425.938696 -49.969674)
		(width 0.089408)
		(layer "In2.Cu")
		(net "FM_BMC_NMI_N")
	)
	(segment
		(start 418.171884 -48.342804)
		(end 424.615356 -48.342804)
		(width 0.089408)
		(layer "In2.Cu")
		(net "FM_BMC_NMI_N")
	)
	(segment
		(start 399.348198 -74.173334)
		(end 395.769592 -70.594728)
		(width 0.089408)
		(layer "In2.Cu")
		(net "FM_BMC_NMI_N")
	)
	(segment
		(start 416.7759 -50.5333)
		(end 416.7759 -49.738788)
		(width 0.089408)
		(layer "In2.Cu")
		(net "FM_BMC_NMI_N")
	)
	(segment
		(start 395.769592 -70.594728)
		(end 395.769592 -66.637408)
		(width 0.089408)
		(layer "In2.Cu")
		(net "FM_BMC_NMI_N")
	)
	(segment
		(start 408.08783 -50.793904)
		(end 416.515296 -50.793904)
		(width 0.089408)
		(layer "In2.Cu")
		(net "FM_BMC_NMI_N")
	)
	(segment
		(start 399.790158 -85.857842)
		(end 399.790158 -83.36407)
		(width 0.089408)
		(layer "In2.Cu")
		(net "FM_BMC_NMI_N")
	)
	(segment
		(start 401.03552 -64.54648)
		(end 401.03552 -61.646816)
		(width 0.089408)
		(layer "In2.Cu")
		(net "FM_BMC_NMI_N")
	)
	(segment
		(start 398.502124 -82.076036)
		(end 398.502124 -81.085944)
		(width 0.089408)
		(layer "In2.Cu")
		(net "FM_BMC_NMI_N")
	)
	(segment
		(start 399.790158 -83.36407)
		(end 398.502124 -82.076036)
		(width 0.089408)
		(layer "In2.Cu")
		(net "FM_BMC_NMI_N")
	)
	(segment
		(start 401.03552 -61.646816)
		(end 405.507952 -57.174384)
		(width 0.089408)
		(layer "In2.Cu")
		(net "FM_BMC_NMI_N")
	)
	(segment
		(start 405.507952 -57.174384)
		(end 405.507952 -53.373782)
		(width 0.089408)
		(layer "In2.Cu")
		(net "FM_BMC_NMI_N")
	)
	(segment
		(start 416.515296 -50.793904)
		(end 416.7759 -50.5333)
		(width 0.089408)
		(layer "In2.Cu")
		(net "FM_BMC_NMI_N")
	)
	(segment
		(start 399.594832 -79.993236)
		(end 399.594832 -77.788008)
		(width 0.089408)
		(layer "In2.Cu")
		(net "FM_BMC_NMI_N")
	)
	(segment
		(start 399.594832 -77.788008)
		(end 399.348198 -77.541374)
		(width 0.089408)
		(layer "In2.Cu")
		(net "FM_BMC_NMI_N")
	)
	(segment
		(start 424.615356 -48.342804)
		(end 425.938696 -49.666144)
		(width 0.089408)
		(layer "In2.Cu")
		(net "FM_BMC_NMI_N")
	)
	(segment
		(start 399.348198 -77.541374)
		(end 399.348198 -74.173334)
		(width 0.089408)
		(layer "In2.Cu")
		(net "FM_BMC_NMI_N")
	)
	(segment
		(start 405.507952 -53.373782)
		(end 408.08783 -50.793904)
		(width 0.089408)
		(layer "In2.Cu")
		(net "FM_BMC_NMI_N")
	)
	(segment
		(start 399.223992 -66.358008)
		(end 401.03552 -64.54648)
		(width 0.089408)
		(layer "In2.Cu")
		(net "FM_BMC_NMI_N")
	)
	(segment
		(start 395.769592 -66.637408)
		(end 396.048992 -66.358008)
		(width 0.089408)
		(layer "In2.Cu")
		(net "FM_BMC_NMI_N")
	)
	(segment
		(start 406.437592 -38.534594)
		(end 407.090118 -38.534594)
		(width 0.10795)
		(layer "F.Cu")
		(net "LED_POSTCODE_6")
	)
	(via
		(at 403.271736 -92.113862)
		(size 0.508)
		(drill 0.254)
		(layers "F.Cu" "B.Cu")
		(net "LED_POSTCODE_6")
	)
	(via
		(at 488.569 -147.193)
		(size 0.508)
		(drill 0.254)
		(layers "F.Cu" "B.Cu")
		(net "LED_POSTCODE_6")
	)
	(via
		(at 406.437592 -38.534594)
		(size 0.4572)
		(drill 0.2032)
		(layers "F.Cu" "B.Cu")
		(net "LED_POSTCODE_6")
	)
	(via
		(at 389.564626 -92.146882)
		(size 0.508)
		(drill 0.254)
		(layers "F.Cu" "B.Cu")
		(net "LED_POSTCODE_6")
	)
	(segment
		(start 488.569 -147.193)
		(end 489.65739 -147.193)
		(width 0.10795)
		(layer "B.Cu")
		(net "LED_POSTCODE_6")
	)
	(segment
		(start 469.151208 -117.33784)
		(end 466.230462 -117.33784)
		(width 0.089408)
		(layer "In2.Cu")
		(net "LED_POSTCODE_6")
	)
	(segment
		(start 486.1306 -128.905)
		(end 481.151946 -128.905)
		(width 0.089408)
		(layer "In2.Cu")
		(net "LED_POSTCODE_6")
	)
	(segment
		(start 491.497366 -138.702034)
		(end 491.497366 -137.10793)
		(width 0.089408)
		(layer "In2.Cu")
		(net "LED_POSTCODE_6")
	)
	(segment
		(start 403.561042 -99.832414)
		(end 403.561042 -92.403168)
		(width 0.089408)
		(layer "In2.Cu")
		(net "LED_POSTCODE_6")
	)
	(segment
		(start 427.346364 -119.792496)
		(end 424.67149 -119.792496)
		(width 0.089408)
		(layer "In2.Cu")
		(net "LED_POSTCODE_6")
	)
	(segment
		(start 407.860754 -111.70412)
		(end 407.861008 -111.703866)
		(width 0.089408)
		(layer "In2.Cu")
		(net "LED_POSTCODE_6")
	)
	(segment
		(start 404.9268 -103.2764)
		(end 404.9268 -102.329996)
		(width 0.089408)
		(layer "In2.Cu")
		(net "LED_POSTCODE_6")
	)
	(segment
		(start 408.92222 -119.025416)
		(end 409.55087 -118.396766)
		(width 0.089408)
		(layer "In2.Cu")
		(net "LED_POSTCODE_6")
	)
	(segment
		(start 407.94432 -114.710464)
		(end 407.94432 -113.672366)
		(width 0.089408)
		(layer "In2.Cu")
		(net "LED_POSTCODE_6")
	)
	(segment
		(start 407.861008 -111.703866)
		(end 407.861008 -109.610652)
		(width 0.089408)
		(layer "In2.Cu")
		(net "LED_POSTCODE_6")
	)
	(segment
		(start 465.869782 -116.97716)
		(end 437.097678 -116.97716)
		(width 0.089408)
		(layer "In2.Cu")
		(net "LED_POSTCODE_6")
	)
	(segment
		(start 407.504392 -104.2416)
		(end 405.892 -104.2416)
		(width 0.089408)
		(layer "In2.Cu")
		(net "LED_POSTCODE_6")
	)
	(segment
		(start 410.845 -118.262654)
		(end 410.845 -117.611144)
		(width 0.089408)
		(layer "In2.Cu")
		(net "LED_POSTCODE_6")
	)
	(segment
		(start 421.44442 -120.392952)
		(end 421.116252 -120.064784)
		(width 0.089408)
		(layer "In2.Cu")
		(net "LED_POSTCODE_6")
	)
	(segment
		(start 488.12704 -130.90144)
		(end 486.1306 -128.905)
		(width 0.089408)
		(layer "In2.Cu")
		(net "LED_POSTCODE_6")
	)
	(segment
		(start 404.198328 -101.601524)
		(end 404.198328 -100.4697)
		(width 0.089408)
		(layer "In2.Cu")
		(net "LED_POSTCODE_6")
	)
	(segment
		(start 410.710888 -118.396766)
		(end 410.845 -118.262654)
		(width 0.089408)
		(layer "In2.Cu")
		(net "LED_POSTCODE_6")
	)
	(segment
		(start 407.861008 -109.610652)
		(end 407.753312 -109.502956)
		(width 0.089408)
		(layer "In2.Cu")
		(net "LED_POSTCODE_6")
	)
	(segment
		(start 407.94432 -112.482376)
		(end 407.860754 -112.39881)
		(width 0.089408)
		(layer "In2.Cu")
		(net "LED_POSTCODE_6")
	)
	(segment
		(start 481.151946 -128.905)
		(end 479.552 -127.305054)
		(width 0.089408)
		(layer "In2.Cu")
		(net "LED_POSTCODE_6")
	)
	(segment
		(start 408.92222 -120.769888)
		(end 408.92222 -119.025416)
		(width 0.089408)
		(layer "In2.Cu")
		(net "LED_POSTCODE_6")
	)
	(segment
		(start 477.408494 -119.525288)
		(end 475.67342 -117.790214)
		(width 0.089408)
		(layer "In2.Cu")
		(net "LED_POSTCODE_6")
	)
	(segment
		(start 403.561042 -92.403168)
		(end 403.271736 -92.113862)
		(width 0.089408)
		(layer "In2.Cu")
		(net "LED_POSTCODE_6")
	)
	(segment
		(start 491.497366 -137.10793)
		(end 492.243618 -136.361678)
		(width 0.089408)
		(layer "In2.Cu")
		(net "LED_POSTCODE_6")
	)
	(segment
		(start 411.459934 -121.531888)
		(end 411.32633 -121.398284)
		(width 0.089408)
		(layer "In2.Cu")
		(net "LED_POSTCODE_6")
	)
	(segment
		(start 405.892 -104.2416)
		(end 404.9268 -103.2764)
		(width 0.089408)
		(layer "In2.Cu")
		(net "LED_POSTCODE_6")
	)
	(segment
		(start 489.713524 -132.066538)
		(end 488.548426 -130.90144)
		(width 0.089408)
		(layer "In2.Cu")
		(net "LED_POSTCODE_6")
	)
	(segment
		(start 479.552 -127.305054)
		(end 479.552 -123.023884)
		(width 0.089408)
		(layer "In2.Cu")
		(net "LED_POSTCODE_6")
	)
	(segment
		(start 407.94432 -113.672366)
		(end 407.944066 -113.672112)
		(width 0.089408)
		(layer "In2.Cu")
		(net "LED_POSTCODE_6")
	)
	(segment
		(start 409.550616 -121.398284)
		(end 408.92222 -120.769888)
		(width 0.089408)
		(layer "In2.Cu")
		(net "LED_POSTCODE_6")
	)
	(segment
		(start 488.5436 -147.193)
		(end 487.585766 -146.235166)
		(width 0.089408)
		(layer "In2.Cu")
		(net "LED_POSTCODE_6")
	)
	(segment
		(start 492.243618 -136.361678)
		(end 492.243618 -133.581394)
		(width 0.089408)
		(layer "In2.Cu")
		(net "LED_POSTCODE_6")
	)
	(segment
		(start 424.67149 -119.792496)
		(end 424.071034 -120.392952)
		(width 0.089408)
		(layer "In2.Cu")
		(net "LED_POSTCODE_6")
	)
	(segment
		(start 475.67342 -117.790214)
		(end 469.603582 -117.790214)
		(width 0.089408)
		(layer "In2.Cu")
		(net "LED_POSTCODE_6")
	)
	(segment
		(start 418.110416 -120.064784)
		(end 416.643312 -121.531888)
		(width 0.089408)
		(layer "In2.Cu")
		(net "LED_POSTCODE_6")
	)
	(segment
		(start 407.860754 -112.39881)
		(end 407.860754 -111.70412)
		(width 0.089408)
		(layer "In2.Cu")
		(net "LED_POSTCODE_6")
	)
	(segment
		(start 421.116252 -120.064784)
		(end 418.110416 -120.064784)
		(width 0.089408)
		(layer "In2.Cu")
		(net "LED_POSTCODE_6")
	)
	(segment
		(start 477.408494 -120.880378)
		(end 477.408494 -119.525288)
		(width 0.089408)
		(layer "In2.Cu")
		(net "LED_POSTCODE_6")
	)
	(segment
		(start 488.569 -147.193)
		(end 488.5436 -147.193)
		(width 0.089408)
		(layer "In2.Cu")
		(net "LED_POSTCODE_6")
	)
	(segment
		(start 404.9268 -102.329996)
		(end 404.198328 -101.601524)
		(width 0.089408)
		(layer "In2.Cu")
		(net "LED_POSTCODE_6")
	)
	(segment
		(start 411.32633 -121.398284)
		(end 409.550616 -121.398284)
		(width 0.089408)
		(layer "In2.Cu")
		(net "LED_POSTCODE_6")
	)
	(segment
		(start 424.071034 -120.392952)
		(end 421.44442 -120.392952)
		(width 0.089408)
		(layer "In2.Cu")
		(net "LED_POSTCODE_6")
	)
	(segment
		(start 427.765972 -120.212104)
		(end 427.346364 -119.792496)
		(width 0.089408)
		(layer "In2.Cu")
		(net "LED_POSTCODE_6")
	)
	(segment
		(start 404.198328 -100.4697)
		(end 403.561042 -99.832414)
		(width 0.089408)
		(layer "In2.Cu")
		(net "LED_POSTCODE_6")
	)
	(segment
		(start 407.94432 -113.038382)
		(end 407.94432 -112.482376)
		(width 0.089408)
		(layer "In2.Cu")
		(net "LED_POSTCODE_6")
	)
	(segment
		(start 466.230462 -117.33784)
		(end 465.869782 -116.97716)
		(width 0.089408)
		(layer "In2.Cu")
		(net "LED_POSTCODE_6")
	)
	(segment
		(start 487.585766 -142.613634)
		(end 491.497366 -138.702034)
		(width 0.089408)
		(layer "In2.Cu")
		(net "LED_POSTCODE_6")
	)
	(segment
		(start 492.243618 -133.581394)
		(end 490.728762 -132.066538)
		(width 0.089408)
		(layer "In2.Cu")
		(net "LED_POSTCODE_6")
	)
	(segment
		(start 488.548426 -130.90144)
		(end 488.12704 -130.90144)
		(width 0.089408)
		(layer "In2.Cu")
		(net "LED_POSTCODE_6")
	)
	(segment
		(start 437.097678 -116.97716)
		(end 433.862734 -120.212104)
		(width 0.089408)
		(layer "In2.Cu")
		(net "LED_POSTCODE_6")
	)
	(segment
		(start 416.643312 -121.531888)
		(end 411.459934 -121.531888)
		(width 0.089408)
		(layer "In2.Cu")
		(net "LED_POSTCODE_6")
	)
	(segment
		(start 407.944066 -113.038636)
		(end 407.94432 -113.038382)
		(width 0.089408)
		(layer "In2.Cu")
		(net "LED_POSTCODE_6")
	)
	(segment
		(start 407.753312 -104.49052)
		(end 407.504392 -104.2416)
		(width 0.089408)
		(layer "In2.Cu")
		(net "LED_POSTCODE_6")
	)
	(segment
		(start 407.944066 -113.672112)
		(end 407.944066 -113.038636)
		(width 0.089408)
		(layer "In2.Cu")
		(net "LED_POSTCODE_6")
	)
	(segment
		(start 409.55087 -118.396766)
		(end 410.710888 -118.396766)
		(width 0.089408)
		(layer "In2.Cu")
		(net "LED_POSTCODE_6")
	)
	(segment
		(start 487.585766 -146.235166)
		(end 487.585766 -142.613634)
		(width 0.089408)
		(layer "In2.Cu")
		(net "LED_POSTCODE_6")
	)
	(segment
		(start 407.753312 -109.502956)
		(end 407.753312 -104.49052)
		(width 0.089408)
		(layer "In2.Cu")
		(net "LED_POSTCODE_6")
	)
	(segment
		(start 469.603582 -117.790214)
		(end 469.151208 -117.33784)
		(width 0.089408)
		(layer "In2.Cu")
		(net "LED_POSTCODE_6")
	)
	(segment
		(start 410.845 -117.611144)
		(end 407.94432 -114.710464)
		(width 0.089408)
		(layer "In2.Cu")
		(net "LED_POSTCODE_6")
	)
	(segment
		(start 490.728762 -132.066538)
		(end 489.713524 -132.066538)
		(width 0.089408)
		(layer "In2.Cu")
		(net "LED_POSTCODE_6")
	)
	(segment
		(start 433.862734 -120.212104)
		(end 427.765972 -120.212104)
		(width 0.089408)
		(layer "In2.Cu")
		(net "LED_POSTCODE_6")
	)
	(segment
		(start 479.552 -123.023884)
		(end 477.408494 -120.880378)
		(width 0.089408)
		(layer "In2.Cu")
		(net "LED_POSTCODE_6")
	)
	(segment
		(start 390.094216 -93.312234)
		(end 390.094216 -92.676472)
		(width 0.089408)
		(layer "In4.Cu")
		(net "LED_POSTCODE_6")
	)
	(segment
		(start 396.829534 -91.549474)
		(end 396.829534 -93.205046)
		(width 0.089408)
		(layer "In4.Cu")
		(net "LED_POSTCODE_6")
	)
	(segment
		(start 396.829534 -93.205046)
		(end 396.28318 -93.7514)
		(width 0.089408)
		(layer "In4.Cu")
		(net "LED_POSTCODE_6")
	)
	(segment
		(start 403.131528 -92.113862)
		(end 401.680426 -90.66276)
		(width 0.089408)
		(layer "In4.Cu")
		(net "LED_POSTCODE_6")
	)
	(segment
		(start 403.271736 -92.113862)
		(end 403.131528 -92.113862)
		(width 0.089408)
		(layer "In4.Cu")
		(net "LED_POSTCODE_6")
	)
	(segment
		(start 390.094216 -92.676472)
		(end 389.564626 -92.146882)
		(width 0.089408)
		(layer "In4.Cu")
		(net "LED_POSTCODE_6")
	)
	(segment
		(start 401.680426 -90.66276)
		(end 397.716248 -90.66276)
		(width 0.089408)
		(layer "In4.Cu")
		(net "LED_POSTCODE_6")
	)
	(segment
		(start 396.28318 -93.7514)
		(end 390.533382 -93.7514)
		(width 0.089408)
		(layer "In4.Cu")
		(net "LED_POSTCODE_6")
	)
	(segment
		(start 397.716248 -90.66276)
		(end 396.829534 -91.549474)
		(width 0.089408)
		(layer "In4.Cu")
		(net "LED_POSTCODE_6")
	)
	(segment
		(start 390.533382 -93.7514)
		(end 390.094216 -93.312234)
		(width 0.089408)
		(layer "In4.Cu")
		(net "LED_POSTCODE_6")
	)
	(segment
		(start 389.609076 -88.593422)
		(end 392.88085 -85.321648)
		(width 0.089408)
		(layer "In9.Cu")
		(net "LED_POSTCODE_6")
	)
	(segment
		(start 389.182356 -91.764612)
		(end 389.182356 -91.34602)
		(width 0.089408)
		(layer "In9.Cu")
		(net "LED_POSTCODE_6")
	)
	(segment
		(start 389.621522 -90.906854)
		(end 389.621522 -90.32621)
		(width 0.089408)
		(layer "In9.Cu")
		(net "LED_POSTCODE_6")
	)
	(segment
		(start 393.597384 -84.798916)
		(end 393.597384 -83.795108)
		(width 0.089408)
		(layer "In9.Cu")
		(net "LED_POSTCODE_6")
	)
	(segment
		(start 399.234152 -64.14643)
		(end 399.234152 -62.81547)
		(width 0.089408)
		(layer "In9.Cu")
		(net "LED_POSTCODE_6")
	)
	(segment
		(start 394.501878 -77.49413)
		(end 395.712696 -76.283312)
		(width 0.089408)
		(layer "In9.Cu")
		(net "LED_POSTCODE_6")
	)
	(segment
		(start 389.609076 -90.313764)
		(end 389.609076 -88.593422)
		(width 0.089408)
		(layer "In9.Cu")
		(net "LED_POSTCODE_6")
	)
	(segment
		(start 398.659604 -65.715642)
		(end 398.659604 -64.720978)
		(width 0.089408)
		(layer "In9.Cu")
		(net "LED_POSTCODE_6")
	)
	(segment
		(start 401.439634 -43.9674)
		(end 402.232622 -43.174412)
		(width 0.089408)
		(layer "In9.Cu")
		(net "LED_POSTCODE_6")
	)
	(segment
		(start 402.232622 -39.853362)
		(end 403.909022 -38.176962)
		(width 0.089408)
		(layer "In9.Cu")
		(net "LED_POSTCODE_6")
	)
	(segment
		(start 402.232622 -43.174412)
		(end 402.232622 -39.853362)
		(width 0.089408)
		(layer "In9.Cu")
		(net "LED_POSTCODE_6")
	)
	(segment
		(start 397.022066 -68.663312)
		(end 397.022066 -67.87134)
		(width 0.089408)
		(layer "In9.Cu")
		(net "LED_POSTCODE_6")
	)
	(segment
		(start 394.190728 -83.201764)
		(end 394.190728 -82.52206)
		(width 0.089408)
		(layer "In9.Cu")
		(net "LED_POSTCODE_6")
	)
	(segment
		(start 393.074652 -85.321648)
		(end 393.597384 -84.798916)
		(width 0.089408)
		(layer "In9.Cu")
		(net "LED_POSTCODE_6")
	)
	(segment
		(start 395.712696 -76.283312)
		(end 395.712696 -71.849742)
		(width 0.089408)
		(layer "In9.Cu")
		(net "LED_POSTCODE_6")
	)
	(segment
		(start 398.659604 -66.167762)
		(end 398.659604 -65.874138)
		(width 0.089408)
		(layer "In9.Cu")
		(net "LED_POSTCODE_6")
	)
	(segment
		(start 398.659604 -64.720978)
		(end 399.234152 -64.14643)
		(width 0.089408)
		(layer "In9.Cu")
		(net "LED_POSTCODE_6")
	)
	(segment
		(start 389.621522 -90.32621)
		(end 389.609076 -90.313764)
		(width 0.089408)
		(layer "In9.Cu")
		(net "LED_POSTCODE_6")
	)
	(segment
		(start 406.07996 -38.176962)
		(end 406.437592 -38.534594)
		(width 0.089408)
		(layer "In9.Cu")
		(net "LED_POSTCODE_6")
	)
	(segment
		(start 398.968722 -54.873398)
		(end 398.968976 -54.873144)
		(width 0.089408)
		(layer "In9.Cu")
		(net "LED_POSTCODE_6")
	)
	(segment
		(start 394.79982 -81.912968)
		(end 394.79982 -80.846676)
		(width 0.089408)
		(layer "In9.Cu")
		(net "LED_POSTCODE_6")
	)
	(segment
		(start 403.909022 -38.176962)
		(end 406.07996 -38.176962)
		(width 0.089408)
		(layer "In9.Cu")
		(net "LED_POSTCODE_6")
	)
	(segment
		(start 392.88085 -85.321648)
		(end 393.074652 -85.321648)
		(width 0.089408)
		(layer "In9.Cu")
		(net "LED_POSTCODE_6")
	)
	(segment
		(start 398.968976 -54.873144)
		(end 398.968976 -47.45355)
		(width 0.089408)
		(layer "In9.Cu")
		(net "LED_POSTCODE_6")
	)
	(segment
		(start 398.968976 -57.206388)
		(end 398.968976 -57.092088)
		(width 0.089408)
		(layer "In9.Cu")
		(net "LED_POSTCODE_6")
	)
	(segment
		(start 400.615912 -61.43371)
		(end 400.615912 -58.853324)
		(width 0.089408)
		(layer "In9.Cu")
		(net "LED_POSTCODE_6")
	)
	(segment
		(start 394.501878 -80.548734)
		(end 394.501878 -77.49413)
		(width 0.089408)
		(layer "In9.Cu")
		(net "LED_POSTCODE_6")
	)
	(segment
		(start 397.02232 -67.871086)
		(end 397.02232 -67.805046)
		(width 0.089408)
		(layer "In9.Cu")
		(net "LED_POSTCODE_6")
	)
	(segment
		(start 389.564626 -92.146882)
		(end 389.182356 -91.764612)
		(width 0.089408)
		(layer "In9.Cu")
		(net "LED_POSTCODE_6")
	)
	(segment
		(start 394.79982 -80.846676)
		(end 394.501878 -80.548734)
		(width 0.089408)
		(layer "In9.Cu")
		(net "LED_POSTCODE_6")
	)
	(segment
		(start 397.02232 -67.805046)
		(end 398.659604 -66.167762)
		(width 0.089408)
		(layer "In9.Cu")
		(net "LED_POSTCODE_6")
	)
	(segment
		(start 398.659604 -65.874138)
		(end 398.659858 -65.873884)
		(width 0.089408)
		(layer "In9.Cu")
		(net "LED_POSTCODE_6")
	)
	(segment
		(start 395.712696 -71.849742)
		(end 397.02232 -70.540118)
		(width 0.089408)
		(layer "In9.Cu")
		(net "LED_POSTCODE_6")
	)
	(segment
		(start 400.615912 -58.853324)
		(end 398.968976 -57.206388)
		(width 0.089408)
		(layer "In9.Cu")
		(net "LED_POSTCODE_6")
	)
	(segment
		(start 401.439634 -44.982892)
		(end 401.439634 -43.9674)
		(width 0.089408)
		(layer "In9.Cu")
		(net "LED_POSTCODE_6")
	)
	(segment
		(start 398.968976 -47.45355)
		(end 401.439634 -44.982892)
		(width 0.089408)
		(layer "In9.Cu")
		(net "LED_POSTCODE_6")
	)
	(segment
		(start 398.659858 -65.873884)
		(end 398.659858 -65.715896)
		(width 0.089408)
		(layer "In9.Cu")
		(net "LED_POSTCODE_6")
	)
	(segment
		(start 398.968722 -57.091834)
		(end 398.968722 -54.873398)
		(width 0.089408)
		(layer "In9.Cu")
		(net "LED_POSTCODE_6")
	)
	(segment
		(start 398.659858 -65.715896)
		(end 398.659604 -65.715642)
		(width 0.089408)
		(layer "In9.Cu")
		(net "LED_POSTCODE_6")
	)
	(segment
		(start 398.968976 -57.092088)
		(end 398.968722 -57.091834)
		(width 0.089408)
		(layer "In9.Cu")
		(net "LED_POSTCODE_6")
	)
	(segment
		(start 397.02232 -70.540118)
		(end 397.02232 -68.663566)
		(width 0.089408)
		(layer "In9.Cu")
		(net "LED_POSTCODE_6")
	)
	(segment
		(start 399.234152 -62.81547)
		(end 400.615912 -61.43371)
		(width 0.089408)
		(layer "In9.Cu")
		(net "LED_POSTCODE_6")
	)
	(segment
		(start 394.190728 -82.52206)
		(end 394.79982 -81.912968)
		(width 0.089408)
		(layer "In9.Cu")
		(net "LED_POSTCODE_6")
	)
	(segment
		(start 397.022066 -67.87134)
		(end 397.02232 -67.871086)
		(width 0.089408)
		(layer "In9.Cu")
		(net "LED_POSTCODE_6")
	)
	(segment
		(start 397.02232 -68.663566)
		(end 397.022066 -68.663312)
		(width 0.089408)
		(layer "In9.Cu")
		(net "LED_POSTCODE_6")
	)
	(segment
		(start 393.597384 -83.795108)
		(end 394.190728 -83.201764)
		(width 0.089408)
		(layer "In9.Cu")
		(net "LED_POSTCODE_6")
	)
	(segment
		(start 389.182356 -91.34602)
		(end 389.621522 -90.906854)
		(width 0.089408)
		(layer "In9.Cu")
		(net "LED_POSTCODE_6")
	)
	(segment
		(start 475.6658 -150.241)
		(end 475.2594 -149.8346)
		(width 0.10795)
		(layer "F.Cu")
		(net "RST_SYSTEM_BTN_N")
	)
	(segment
		(start 498.7798 -157.1498)
		(end 498.7798 -157.522164)
		(width 0.10795)
		(layer "F.Cu")
		(net "RST_SYSTEM_BTN_N")
	)
	(segment
		(start 479.062796 -153.714196)
		(end 478.79635 -153.44775)
		(width 0.10795)
		(layer "F.Cu")
		(net "RST_SYSTEM_BTN_N")
	)
	(segment
		(start 498.7798 -157.522164)
		(end 497.969286 -158.332678)
		(width 0.10795)
		(layer "F.Cu")
		(net "RST_SYSTEM_BTN_N")
	)
	(segment
		(start 480.273614 -158.332678)
		(end 479.062796 -157.12186)
		(width 0.10795)
		(layer "F.Cu")
		(net "RST_SYSTEM_BTN_N")
	)
	(segment
		(start 479.062796 -157.12186)
		(end 479.062796 -153.714196)
		(width 0.10795)
		(layer "F.Cu")
		(net "RST_SYSTEM_BTN_N")
	)
	(segment
		(start 497.969286 -158.332678)
		(end 480.273614 -158.332678)
		(width 0.10795)
		(layer "F.Cu")
		(net "RST_SYSTEM_BTN_N")
	)
	(segment
		(start 498.2718 -156.6418)
		(end 498.7798 -157.1498)
		(width 0.10795)
		(layer "F.Cu")
		(net "RST_SYSTEM_BTN_N")
	)
	(segment
		(start 397.14805 -97.83572)
		(end 397.64335 -97.605596)
		(width 0.10795)
		(layer "F.Cu")
		(net "RST_SYSTEM_BTN_N")
	)
	(segment
		(start 478.79635 -153.44775)
		(end 478.79635 -152.69845)
		(width 0.10795)
		(layer "F.Cu")
		(net "RST_SYSTEM_BTN_N")
	)
	(segment
		(start 476.3389 -150.241)
		(end 475.6658 -150.241)
		(width 0.10795)
		(layer "F.Cu")
		(net "RST_SYSTEM_BTN_N")
	)
	(segment
		(start 478.79635 -152.69845)
		(end 476.3389 -150.241)
		(width 0.10795)
		(layer "F.Cu")
		(net "RST_SYSTEM_BTN_N")
	)
	(via
		(at 498.2718 -156.6418)
		(size 0.508)
		(drill 0.254)
		(layers "F.Cu" "B.Cu")
		(net "RST_SYSTEM_BTN_N")
	)
	(via
		(at 453.898 -44.577)
		(size 0.508)
		(drill 0.254)
		(layers "F.Cu" "B.Cu")
		(net "RST_SYSTEM_BTN_N")
	)
	(via
		(at 420.334694 -100.745798)
		(size 0.508)
		(drill 0.254)
		(layers "F.Cu" "B.Cu")
		(net "RST_SYSTEM_BTN_N")
	)
	(via
		(at 397.64335 -97.605596)
		(size 0.508)
		(drill 0.254)
		(layers "F.Cu" "B.Cu")
		(net "RST_SYSTEM_BTN_N")
	)
	(segment
		(start 454.4822 -43.7515)
		(end 454.4822 -43.434)
		(width 0.10795)
		(layer "B.Cu")
		(net "RST_SYSTEM_BTN_N")
	)
	(segment
		(start 453.898 -44.10075)
		(end 454.00595 -43.9928)
		(width 0.10795)
		(layer "B.Cu")
		(net "RST_SYSTEM_BTN_N")
	)
	(segment
		(start 453.898 -44.577)
		(end 453.898 -44.10075)
		(width 0.10795)
		(layer "B.Cu")
		(net "RST_SYSTEM_BTN_N")
	)
	(segment
		(start 454.00595 -43.9928)
		(end 454.2409 -43.9928)
		(width 0.10795)
		(layer "B.Cu")
		(net "RST_SYSTEM_BTN_N")
	)
	(segment
		(start 454.2409 -43.9928)
		(end 454.4822 -43.7515)
		(width 0.10795)
		(layer "B.Cu")
		(net "RST_SYSTEM_BTN_N")
	)
	(segment
		(start 403.91461 -100.3808)
		(end 402.6662 -100.3808)
		(width 0.089408)
		(layer "In4.Cu")
		(net "RST_SYSTEM_BTN_N")
	)
	(segment
		(start 410.133292 -100.8634)
		(end 408.43835 -102.558342)
		(width 0.089408)
		(layer "In4.Cu")
		(net "RST_SYSTEM_BTN_N")
	)
	(segment
		(start 401.72767 -98.065336)
		(end 398.10309 -98.065336)
		(width 0.089408)
		(layer "In4.Cu")
		(net "RST_SYSTEM_BTN_N")
	)
	(segment
		(start 406.092152 -102.558342)
		(end 403.91461 -100.3808)
		(width 0.089408)
		(layer "In4.Cu")
		(net "RST_SYSTEM_BTN_N")
	)
	(segment
		(start 420.334694 -100.745798)
		(end 420.217092 -100.8634)
		(width 0.089408)
		(layer "In4.Cu")
		(net "RST_SYSTEM_BTN_N")
	)
	(segment
		(start 402.37918 -100.09378)
		(end 402.37918 -98.716846)
		(width 0.089408)
		(layer "In4.Cu")
		(net "RST_SYSTEM_BTN_N")
	)
	(segment
		(start 420.217092 -100.8634)
		(end 410.133292 -100.8634)
		(width 0.089408)
		(layer "In4.Cu")
		(net "RST_SYSTEM_BTN_N")
	)
	(segment
		(start 402.6662 -100.3808)
		(end 402.37918 -100.09378)
		(width 0.089408)
		(layer "In4.Cu")
		(net "RST_SYSTEM_BTN_N")
	)
	(segment
		(start 408.43835 -102.558342)
		(end 406.092152 -102.558342)
		(width 0.089408)
		(layer "In4.Cu")
		(net "RST_SYSTEM_BTN_N")
	)
	(segment
		(start 398.10309 -98.065336)
		(end 397.64335 -97.605596)
		(width 0.089408)
		(layer "In4.Cu")
		(net "RST_SYSTEM_BTN_N")
	)
	(segment
		(start 402.37918 -98.716846)
		(end 401.72767 -98.065336)
		(width 0.089408)
		(layer "In4.Cu")
		(net "RST_SYSTEM_BTN_N")
	)
	(segment
		(start 405.956516 -78.3209)
		(end 406.7048 -79.069184)
		(width 0.089408)
		(layer "In9.Cu")
		(net "RST_SYSTEM_BTN_N")
	)
	(segment
		(start 453.898 -44.577)
		(end 453.898 -45.577506)
		(width 0.089408)
		(layer "In9.Cu")
		(net "RST_SYSTEM_BTN_N")
	)
	(segment
		(start 398.619218 -95.503492)
		(end 397.64335 -96.47936)
		(width 0.089408)
		(layer "In9.Cu")
		(net "RST_SYSTEM_BTN_N")
	)
	(segment
		(start 414.528508 -61.621924)
		(end 414.528508 -63.535052)
		(width 0.089408)
		(layer "In9.Cu")
		(net "RST_SYSTEM_BTN_N")
	)
	(segment
		(start 414.528508 -58.453782)
		(end 414.528508 -60.399168)
		(width 0.089408)
		(layer "In9.Cu")
		(net "RST_SYSTEM_BTN_N")
	)
	(segment
		(start 499.2751 -127.1143)
		(end 500.818912 -128.658112)
		(width 0.089408)
		(layer "In9.Cu")
		(net "RST_SYSTEM_BTN_N")
	)
	(segment
		(start 499.904512 -133.943344)
		(end 499.904512 -155.009088)
		(width 0.089408)
		(layer "In9.Cu")
		(net "RST_SYSTEM_BTN_N")
	)
	(segment
		(start 420.334694 -100.745798)
		(end 420.722298 -100.745798)
		(width 0.089408)
		(layer "In9.Cu")
		(net "RST_SYSTEM_BTN_N")
	)
	(segment
		(start 497.619528 -110.967012)
		(end 500.818912 -114.166396)
		(width 0.089408)
		(layer "In9.Cu")
		(net "RST_SYSTEM_BTN_N")
	)
	(segment
		(start 413.932878 -67.735196)
		(end 413.932878 -67.736212)
		(width 0.089408)
		(layer "In9.Cu")
		(net "RST_SYSTEM_BTN_N")
	)
	(segment
		(start 414.528508 -63.535052)
		(end 414.323022 -63.740538)
		(width 0.089408)
		(layer "In9.Cu")
		(net "RST_SYSTEM_BTN_N")
	)
	(segment
		(start 409.902152 -71.501)
		(end 405.956516 -75.446636)
		(width 0.089408)
		(layer "In9.Cu")
		(net "RST_SYSTEM_BTN_N")
	)
	(segment
		(start 452.295514 -47.179992)
		(end 439.102754 -47.179992)
		(width 0.089408)
		(layer "In9.Cu")
		(net "RST_SYSTEM_BTN_N")
	)
	(segment
		(start 500.818912 -114.166396)
		(end 500.818912 -119.040148)
		(width 0.089408)
		(layer "In9.Cu")
		(net "RST_SYSTEM_BTN_N")
	)
	(segment
		(start 401.594828 -93.414596)
		(end 399.505932 -95.503492)
		(width 0.089408)
		(layer "In9.Cu")
		(net "RST_SYSTEM_BTN_N")
	)
	(segment
		(start 415.151824 -57.09666)
		(end 415.151824 -57.67197)
		(width 0.089408)
		(layer "In9.Cu")
		(net "RST_SYSTEM_BTN_N")
	)
	(segment
		(start 427.431708 -110.770416)
		(end 481.349304 -110.770416)
		(width 0.089408)
		(layer "In9.Cu")
		(net "RST_SYSTEM_BTN_N")
	)
	(segment
		(start 413.932878 -67.736212)
		(end 413.756348 -67.912742)
		(width 0.089408)
		(layer "In9.Cu")
		(net "RST_SYSTEM_BTN_N")
	)
	(segment
		(start 415.151824 -57.67197)
		(end 415.152078 -57.672224)
		(width 0.089408)
		(layer "In9.Cu")
		(net "RST_SYSTEM_BTN_N")
	)
	(segment
		(start 401.916646 -93.414596)
		(end 401.594828 -93.414596)
		(width 0.089408)
		(layer "In9.Cu")
		(net "RST_SYSTEM_BTN_N")
	)
	(segment
		(start 405.40686 -89.174828)
		(end 403.996398 -90.58529)
		(width 0.089408)
		(layer "In9.Cu")
		(net "RST_SYSTEM_BTN_N")
	)
	(segment
		(start 426.350938 -51.00447)
		(end 425.406312 -51.949096)
		(width 0.089408)
		(layer "In9.Cu")
		(net "RST_SYSTEM_BTN_N")
	)
	(segment
		(start 426.033692 -109.3724)
		(end 427.431708 -110.770416)
		(width 0.089408)
		(layer "In9.Cu")
		(net "RST_SYSTEM_BTN_N")
	)
	(segment
		(start 402.209762 -93.12148)
		(end 401.916646 -93.414596)
		(width 0.089408)
		(layer "In9.Cu")
		(net "RST_SYSTEM_BTN_N")
	)
	(segment
		(start 421.21074 -103.27894)
		(end 422.1988 -104.267)
		(width 0.089408)
		(layer "In9.Cu")
		(net "RST_SYSTEM_BTN_N")
	)
	(segment
		(start 423.835322 -51.949096)
		(end 423.1259 -52.658518)
		(width 0.089408)
		(layer "In9.Cu")
		(net "RST_SYSTEM_BTN_N")
	)
	(segment
		(start 413.756348 -67.912742)
		(end 413.756348 -69.986652)
		(width 0.089408)
		(layer "In9.Cu")
		(net "RST_SYSTEM_BTN_N")
	)
	(segment
		(start 415.152078 -57.672224)
		(end 415.152078 -57.830212)
		(width 0.089408)
		(layer "In9.Cu")
		(net "RST_SYSTEM_BTN_N")
	)
	(segment
		(start 499.904512 -155.009088)
		(end 498.2718 -156.6418)
		(width 0.089408)
		(layer "In9.Cu")
		(net "RST_SYSTEM_BTN_N")
	)
	(segment
		(start 416.904424 -54.90591)
		(end 416.904424 -55.34406)
		(width 0.089408)
		(layer "In9.Cu")
		(net "RST_SYSTEM_BTN_N")
	)
	(segment
		(start 426.033692 -106.120438)
		(end 426.033692 -109.3724)
		(width 0.089408)
		(layer "In9.Cu")
		(net "RST_SYSTEM_BTN_N")
	)
	(segment
		(start 481.349304 -110.770416)
		(end 482.641148 -112.06226)
		(width 0.089408)
		(layer "In9.Cu")
		(net "RST_SYSTEM_BTN_N")
	)
	(segment
		(start 421.21074 -101.23424)
		(end 421.21074 -103.27894)
		(width 0.089408)
		(layer "In9.Cu")
		(net "RST_SYSTEM_BTN_N")
	)
	(segment
		(start 405.40686 -87.220806)
		(end 405.40686 -89.174828)
		(width 0.089408)
		(layer "In9.Cu")
		(net "RST_SYSTEM_BTN_N")
	)
	(segment
		(start 412.242 -71.501)
		(end 409.902152 -71.501)
		(width 0.089408)
		(layer "In9.Cu")
		(net "RST_SYSTEM_BTN_N")
	)
	(segment
		(start 420.417752 -53.968396)
		(end 417.841938 -53.968396)
		(width 0.089408)
		(layer "In9.Cu")
		(net "RST_SYSTEM_BTN_N")
	)
	(segment
		(start 436.099458 -50.292254)
		(end 435.387242 -51.00447)
		(width 0.089408)
		(layer "In9.Cu")
		(net "RST_SYSTEM_BTN_N")
	)
	(segment
		(start 436.099458 -50.183288)
		(end 436.099458 -50.292254)
		(width 0.089408)
		(layer "In9.Cu")
		(net "RST_SYSTEM_BTN_N")
	)
	(segment
		(start 414.673288 -60.543948)
		(end 414.673288 -61.477144)
		(width 0.089408)
		(layer "In9.Cu")
		(net "RST_SYSTEM_BTN_N")
	)
	(segment
		(start 414.323022 -63.740538)
		(end 414.323022 -67.345052)
		(width 0.089408)
		(layer "In9.Cu")
		(net "RST_SYSTEM_BTN_N")
	)
	(segment
		(start 500.818912 -119.040148)
		(end 499.2751 -120.58396)
		(width 0.089408)
		(layer "In9.Cu")
		(net "RST_SYSTEM_BTN_N")
	)
	(segment
		(start 406.7048 -79.069184)
		(end 406.7048 -85.922866)
		(width 0.089408)
		(layer "In9.Cu")
		(net "RST_SYSTEM_BTN_N")
	)
	(segment
		(start 415.152078 -57.830212)
		(end 414.528508 -58.453782)
		(width 0.089408)
		(layer "In9.Cu")
		(net "RST_SYSTEM_BTN_N")
	)
	(segment
		(start 500.818912 -133.028944)
		(end 499.904512 -133.943344)
		(width 0.089408)
		(layer "In9.Cu")
		(net "RST_SYSTEM_BTN_N")
	)
	(segment
		(start 406.7048 -85.922866)
		(end 405.40686 -87.220806)
		(width 0.089408)
		(layer "In9.Cu")
		(net "RST_SYSTEM_BTN_N")
	)
	(segment
		(start 413.756348 -69.986652)
		(end 412.242 -71.501)
		(width 0.089408)
		(layer "In9.Cu")
		(net "RST_SYSTEM_BTN_N")
	)
	(segment
		(start 403.996398 -90.58529)
		(end 402.587714 -90.58529)
		(width 0.089408)
		(layer "In9.Cu")
		(net "RST_SYSTEM_BTN_N")
	)
	(segment
		(start 405.956516 -75.446636)
		(end 405.956516 -78.3209)
		(width 0.089408)
		(layer "In9.Cu")
		(net "RST_SYSTEM_BTN_N")
	)
	(segment
		(start 492.470948 -110.967012)
		(end 497.619528 -110.967012)
		(width 0.089408)
		(layer "In9.Cu")
		(net "RST_SYSTEM_BTN_N")
	)
	(segment
		(start 423.1259 -52.658518)
		(end 421.72763 -52.658518)
		(width 0.089408)
		(layer "In9.Cu")
		(net "RST_SYSTEM_BTN_N")
	)
	(segment
		(start 417.841938 -53.968396)
		(end 416.904424 -54.90591)
		(width 0.089408)
		(layer "In9.Cu")
		(net "RST_SYSTEM_BTN_N")
	)
	(segment
		(start 402.587714 -90.58529)
		(end 402.209762 -90.963242)
		(width 0.089408)
		(layer "In9.Cu")
		(net "RST_SYSTEM_BTN_N")
	)
	(segment
		(start 500.818912 -128.658112)
		(end 500.818912 -133.028944)
		(width 0.089408)
		(layer "In9.Cu")
		(net "RST_SYSTEM_BTN_N")
	)
	(segment
		(start 399.505932 -95.503492)
		(end 398.619218 -95.503492)
		(width 0.089408)
		(layer "In9.Cu")
		(net "RST_SYSTEM_BTN_N")
	)
	(segment
		(start 416.904424 -55.34406)
		(end 415.151824 -57.09666)
		(width 0.089408)
		(layer "In9.Cu")
		(net "RST_SYSTEM_BTN_N")
	)
	(segment
		(start 482.641148 -112.06226)
		(end 491.3757 -112.06226)
		(width 0.089408)
		(layer "In9.Cu")
		(net "RST_SYSTEM_BTN_N")
	)
	(segment
		(start 425.406312 -51.949096)
		(end 423.835322 -51.949096)
		(width 0.089408)
		(layer "In9.Cu")
		(net "RST_SYSTEM_BTN_N")
	)
	(segment
		(start 414.323022 -67.345052)
		(end 413.932878 -67.735196)
		(width 0.089408)
		(layer "In9.Cu")
		(net "RST_SYSTEM_BTN_N")
	)
	(segment
		(start 414.673288 -61.477144)
		(end 414.528508 -61.621924)
		(width 0.089408)
		(layer "In9.Cu")
		(net "RST_SYSTEM_BTN_N")
	)
	(segment
		(start 424.180254 -104.267)
		(end 426.033692 -106.120438)
		(width 0.089408)
		(layer "In9.Cu")
		(net "RST_SYSTEM_BTN_N")
	)
	(segment
		(start 435.387242 -51.00447)
		(end 426.350938 -51.00447)
		(width 0.089408)
		(layer "In9.Cu")
		(net "RST_SYSTEM_BTN_N")
	)
	(segment
		(start 499.2751 -120.58396)
		(end 499.2751 -127.1143)
		(width 0.089408)
		(layer "In9.Cu")
		(net "RST_SYSTEM_BTN_N")
	)
	(segment
		(start 397.64335 -96.47936)
		(end 397.64335 -97.605596)
		(width 0.089408)
		(layer "In9.Cu")
		(net "RST_SYSTEM_BTN_N")
	)
	(segment
		(start 453.898 -45.577506)
		(end 452.295514 -47.179992)
		(width 0.089408)
		(layer "In9.Cu")
		(net "RST_SYSTEM_BTN_N")
	)
	(segment
		(start 422.1988 -104.267)
		(end 424.180254 -104.267)
		(width 0.089408)
		(layer "In9.Cu")
		(net "RST_SYSTEM_BTN_N")
	)
	(segment
		(start 491.3757 -112.06226)
		(end 492.470948 -110.967012)
		(width 0.089408)
		(layer "In9.Cu")
		(net "RST_SYSTEM_BTN_N")
	)
	(segment
		(start 414.528508 -60.399168)
		(end 414.673288 -60.543948)
		(width 0.089408)
		(layer "In9.Cu")
		(net "RST_SYSTEM_BTN_N")
	)
	(segment
		(start 439.102754 -47.179992)
		(end 436.099458 -50.183288)
		(width 0.089408)
		(layer "In9.Cu")
		(net "RST_SYSTEM_BTN_N")
	)
	(segment
		(start 420.722298 -100.745798)
		(end 421.21074 -101.23424)
		(width 0.089408)
		(layer "In9.Cu")
		(net "RST_SYSTEM_BTN_N")
	)
	(segment
		(start 402.209762 -90.963242)
		(end 402.209762 -93.12148)
		(width 0.089408)
		(layer "In9.Cu")
		(net "RST_SYSTEM_BTN_N")
	)
	(segment
		(start 421.72763 -52.658518)
		(end 420.417752 -53.968396)
		(width 0.089408)
		(layer "In9.Cu")
		(net "RST_SYSTEM_BTN_N")
	)
	(segment
		(start 405.3332 -45.471588)
		(end 405.846788 -44.958)
		(width 0.10795)
		(layer "F.Cu")
		(net "RST_BMC_SYSRST_BTN_OUT_N")
	)
	(segment
		(start 406.400254 -44.958)
		(end 407.486358 -43.871896)
		(width 0.10795)
		(layer "F.Cu")
		(net "RST_BMC_SYSRST_BTN_OUT_N")
	)
	(segment
		(start 408.274774 -42.720768)
		(end 408.274774 -42.15003)
		(width 0.10795)
		(layer "F.Cu")
		(net "RST_BMC_SYSRST_BTN_OUT_N")
	)
	(segment
		(start 407.486358 -43.161458)
		(end 407.72461 -42.923206)
		(width 0.10795)
		(layer "F.Cu")
		(net "RST_BMC_SYSRST_BTN_OUT_N")
	)
	(segment
		(start 407.486358 -43.871896)
		(end 407.486358 -43.161458)
		(width 0.10795)
		(layer "F.Cu")
		(net "RST_BMC_SYSRST_BTN_OUT_N")
	)
	(segment
		(start 407.72461 -42.923206)
		(end 408.072336 -42.923206)
		(width 0.10795)
		(layer "F.Cu")
		(net "RST_BMC_SYSRST_BTN_OUT_N")
	)
	(segment
		(start 405.3332 -45.7962)
		(end 405.3332 -45.471588)
		(width 0.10795)
		(layer "F.Cu")
		(net "RST_BMC_SYSRST_BTN_OUT_N")
	)
	(segment
		(start 408.072336 -42.923206)
		(end 408.274774 -42.720768)
		(width 0.10795)
		(layer "F.Cu")
		(net "RST_BMC_SYSRST_BTN_OUT_N")
	)
	(segment
		(start 408.274774 -42.15003)
		(end 408.690064 -41.73474)
		(width 0.10795)
		(layer "F.Cu")
		(net "RST_BMC_SYSRST_BTN_OUT_N")
	)
	(segment
		(start 405.846788 -44.958)
		(end 406.400254 -44.958)
		(width 0.10795)
		(layer "F.Cu")
		(net "RST_BMC_SYSRST_BTN_OUT_N")
	)
	(via
		(at 403.567138 -44.484798)
		(size 0.6604)
		(drill 0.3302)
		(layers "F.Cu" "B.Cu")
		(net "RST_BMC_SYSRST_BTN_OUT_N")
	)
	(via
		(at 405.3332 -45.7962)
		(size 0.508)
		(drill 0.254)
		(layers "F.Cu" "B.Cu")
		(net "RST_BMC_SYSRST_BTN_OUT_N")
	)
	(segment
		(start 397.97355 -41.402)
		(end 398.643602 -40.731948)
		(width 0.10795)
		(layer "B.Cu")
		(net "RST_BMC_SYSRST_BTN_OUT_N")
	)
	(segment
		(start 397.860774 -32.398716)
		(end 397.886174 -32.373316)
		(width 0.10795)
		(layer "B.Cu")
		(net "RST_BMC_SYSRST_BTN_OUT_N")
	)
	(segment
		(start 398.379188 -36.22294)
		(end 397.83004 -36.22294)
		(width 0.10795)
		(layer "B.Cu")
		(net "RST_BMC_SYSRST_BTN_OUT_N")
	)
	(segment
		(start 403.567138 -44.484798)
		(end 404.021798 -44.484798)
		(width 0.10795)
		(layer "B.Cu")
		(net "RST_BMC_SYSRST_BTN_OUT_N")
	)
	(segment
		(start 397.407638 -35.800538)
		(end 397.407638 -32.666686)
		(width 0.10795)
		(layer "B.Cu")
		(net "RST_BMC_SYSRST_BTN_OUT_N")
	)
	(segment
		(start 397.97355 -42.947844)
		(end 397.97355 -41.402)
		(width 0.10795)
		(layer "B.Cu")
		(net "RST_BMC_SYSRST_BTN_OUT_N")
	)
	(segment
		(start 398.643602 -40.731948)
		(end 398.643602 -39.950898)
		(width 0.10795)
		(layer "B.Cu")
		(net "RST_BMC_SYSRST_BTN_OUT_N")
	)
	(segment
		(start 399.510504 -44.484798)
		(end 397.97355 -42.947844)
		(width 0.10795)
		(layer "B.Cu")
		(net "RST_BMC_SYSRST_BTN_OUT_N")
	)
	(segment
		(start 398.638268 -39.945564)
		(end 398.638268 -36.48202)
		(width 0.10795)
		(layer "B.Cu")
		(net "RST_BMC_SYSRST_BTN_OUT_N")
	)
	(segment
		(start 397.55191 -29.521404)
		(end 397.54302 -29.512514)
		(width 0.10795)
		(layer "B.Cu")
		(net "RST_BMC_SYSRST_BTN_OUT_N")
	)
	(segment
		(start 404.021798 -44.484798)
		(end 405.3332 -45.7962)
		(width 0.10795)
		(layer "B.Cu")
		(net "RST_BMC_SYSRST_BTN_OUT_N")
	)
	(segment
		(start 397.83004 -36.22294)
		(end 397.407638 -35.800538)
		(width 0.10795)
		(layer "B.Cu")
		(net "RST_BMC_SYSRST_BTN_OUT_N")
	)
	(segment
		(start 398.638268 -36.48202)
		(end 398.379188 -36.22294)
		(width 0.10795)
		(layer "B.Cu")
		(net "RST_BMC_SYSRST_BTN_OUT_N")
	)
	(segment
		(start 398.643602 -39.950898)
		(end 398.638268 -39.945564)
		(width 0.10795)
		(layer "B.Cu")
		(net "RST_BMC_SYSRST_BTN_OUT_N")
	)
	(segment
		(start 397.886174 -32.373316)
		(end 397.900144 -32.359346)
		(width 0.10795)
		(layer "B.Cu")
		(net "RST_BMC_SYSRST_BTN_OUT_N")
	)
	(segment
		(start 397.335502 -31.33471)
		(end 397.335502 -30.385004)
		(width 0.10795)
		(layer "B.Cu")
		(net "RST_BMC_SYSRST_BTN_OUT_N")
	)
	(segment
		(start 397.675608 -32.398716)
		(end 397.860774 -32.398716)
		(width 0.10795)
		(layer "B.Cu")
		(net "RST_BMC_SYSRST_BTN_OUT_N")
	)
	(segment
		(start 397.55191 -30.168596)
		(end 397.55191 -29.521404)
		(width 0.10795)
		(layer "B.Cu")
		(net "RST_BMC_SYSRST_BTN_OUT_N")
	)
	(segment
		(start 397.407638 -32.666686)
		(end 397.675608 -32.398716)
		(width 0.10795)
		(layer "B.Cu")
		(net "RST_BMC_SYSRST_BTN_OUT_N")
	)
	(segment
		(start 397.335502 -30.385004)
		(end 397.55191 -30.168596)
		(width 0.10795)
		(layer "B.Cu")
		(net "RST_BMC_SYSRST_BTN_OUT_N")
	)
	(segment
		(start 397.54302 -28.758642)
		(end 397.359378 -28.575)
		(width 0.10795)
		(layer "B.Cu")
		(net "RST_BMC_SYSRST_BTN_OUT_N")
	)
	(segment
		(start 397.900144 -32.359346)
		(end 397.900144 -31.899352)
		(width 0.10795)
		(layer "B.Cu")
		(net "RST_BMC_SYSRST_BTN_OUT_N")
	)
	(segment
		(start 397.359378 -28.575)
		(end 396.7226 -28.575)
		(width 0.10795)
		(layer "B.Cu")
		(net "RST_BMC_SYSRST_BTN_OUT_N")
	)
	(segment
		(start 403.567138 -44.484798)
		(end 399.510504 -44.484798)
		(width 0.10795)
		(layer "B.Cu")
		(net "RST_BMC_SYSRST_BTN_OUT_N")
	)
	(segment
		(start 397.54302 -29.512514)
		(end 397.54302 -28.758642)
		(width 0.10795)
		(layer "B.Cu")
		(net "RST_BMC_SYSRST_BTN_OUT_N")
	)
	(segment
		(start 397.900144 -31.899352)
		(end 397.335502 -31.33471)
		(width 0.10795)
		(layer "B.Cu")
		(net "RST_BMC_SYSRST_BTN_OUT_N")
	)
	(segment
		(start 387.2357 -52.959)
		(end 385.76885 -54.42585)
		(width 0.10795)
		(layer "F.Cu")
		(net "SPI_BMC_DI")
	)
	(segment
		(start 380.838202 -52.976526)
		(end 381.001016 -53.13934)
		(width 0.10795)
		(layer "F.Cu")
		(net "SPI_BMC_DI")
	)
	(segment
		(start 375.666 -52.63515)
		(end 376.007376 -52.976526)
		(width 0.10795)
		(layer "F.Cu")
		(net "SPI_BMC_DI")
	)
	(segment
		(start 383.76225 -54.42585)
		(end 383.03835 -53.70195)
		(width 0.10795)
		(layer "F.Cu")
		(net "SPI_BMC_DI")
	)
	(segment
		(start 385.76885 -54.42585)
		(end 383.76225 -54.42585)
		(width 0.10795)
		(layer "F.Cu")
		(net "SPI_BMC_DI")
	)
	(segment
		(start 381.563626 -53.70195)
		(end 381.001016 -53.13934)
		(width 0.10795)
		(layer "F.Cu")
		(net "SPI_BMC_DI")
	)
	(segment
		(start 376.007376 -52.976526)
		(end 380.838202 -52.976526)
		(width 0.10795)
		(layer "F.Cu")
		(net "SPI_BMC_DI")
	)
	(segment
		(start 406.446228 -37.734748)
		(end 407.090118 -37.734748)
		(width 0.10795)
		(layer "F.Cu")
		(net "SPI_BMC_DI")
	)
	(segment
		(start 383.03835 -53.70195)
		(end 381.563626 -53.70195)
		(width 0.10795)
		(layer "F.Cu")
		(net "SPI_BMC_DI")
	)
	(segment
		(start 389.89 -52.6288)
		(end 389.5598 -52.959)
		(width 0.10795)
		(layer "F.Cu")
		(net "SPI_BMC_DI")
	)
	(segment
		(start 389.5598 -52.959)
		(end 387.2357 -52.959)
		(width 0.10795)
		(layer "F.Cu")
		(net "SPI_BMC_DI")
	)
	(via
		(at 406.446228 -37.734748)
		(size 0.4572)
		(drill 0.2032)
		(layers "F.Cu" "B.Cu")
		(net "SPI_BMC_DI")
	)
	(via
		(at 381.001016 -53.13934)
		(size 0.762)
		(drill 0.381)
		(layers "F.Cu" "B.Cu")
		(net "SPI_BMC_DI")
	)
	(via
		(at 389.89 -52.6288)
		(size 0.508)
		(drill 0.254)
		(layers "F.Cu" "B.Cu")
		(net "SPI_BMC_DI")
	)
	(via
		(at 375.666 -52.63515)
		(size 0.508)
		(drill 0.254)
		(layers "F.Cu" "B.Cu")
		(net "SPI_BMC_DI")
	)
	(segment
		(start 377.1265 -52.8955)
		(end 375.92635 -52.8955)
		(width 0.10795)
		(layer "B.Cu")
		(net "SPI_BMC_DI")
	)
	(segment
		(start 375.92635 -52.8955)
		(end 375.666 -52.63515)
		(width 0.10795)
		(layer "B.Cu")
		(net "SPI_BMC_DI")
	)
	(segment
		(start 388.843012 -51.581812)
		(end 389.89 -52.6288)
		(width 0.089408)
		(layer "In2.Cu")
		(net "SPI_BMC_DI")
	)
	(segment
		(start 388.843012 -46.190154)
		(end 388.843012 -51.581812)
		(width 0.089408)
		(layer "In2.Cu")
		(net "SPI_BMC_DI")
	)
	(segment
		(start 405.99868 -37.2872)
		(end 399.426938 -37.2872)
		(width 0.089408)
		(layer "In2.Cu")
		(net "SPI_BMC_DI")
	)
	(segment
		(start 406.446228 -37.734748)
		(end 405.99868 -37.2872)
		(width 0.089408)
		(layer "In2.Cu")
		(net "SPI_BMC_DI")
	)
	(segment
		(start 399.426938 -37.2872)
		(end 397.608298 -39.10584)
		(width 0.089408)
		(layer "In2.Cu")
		(net "SPI_BMC_DI")
	)
	(segment
		(start 397.608298 -39.10584)
		(end 395.927326 -39.10584)
		(width 0.089408)
		(layer "In2.Cu")
		(net "SPI_BMC_DI")
	)
	(segment
		(start 395.927326 -39.10584)
		(end 388.843012 -46.190154)
		(width 0.089408)
		(layer "In2.Cu")
		(net "SPI_BMC_DI")
	)
	(segment
		(start 402.580602 -39.822628)
		(end 401.415758 -40.987472)
		(width 0.10795)
		(layer "F.Cu")
		(net "SPI_BMC_DO")
	)
	(segment
		(start 402.580602 -39.267384)
		(end 402.580602 -39.822628)
		(width 0.10795)
		(layer "F.Cu")
		(net "SPI_BMC_DO")
	)
	(segment
		(start 393.603226 -45.403262)
		(end 392.162538 -45.403262)
		(width 0.10795)
		(layer "F.Cu")
		(net "SPI_BMC_DO")
	)
	(segment
		(start 399.923 -41.491154)
		(end 399.572226 -41.14038)
		(width 0.10795)
		(layer "F.Cu")
		(net "SPI_BMC_DO")
	)
	(segment
		(start 399.572226 -41.14038)
		(end 398.328896 -41.14038)
		(width 0.10795)
		(layer "F.Cu")
		(net "SPI_BMC_DO")
	)
	(segment
		(start 392.162538 -45.403262)
		(end 390.828022 -46.737778)
		(width 0.10795)
		(layer "F.Cu")
		(net "SPI_BMC_DO")
	)
	(segment
		(start 387.50875 -46.737778)
		(end 386.334 -47.912528)
		(width 0.10795)
		(layer "F.Cu")
		(net "SPI_BMC_DO")
	)
	(segment
		(start 396.28826 -42.326306)
		(end 394.95349 -43.661076)
		(width 0.10795)
		(layer "F.Cu")
		(net "SPI_BMC_DO")
	)
	(segment
		(start 407.090118 -36.934648)
		(end 406.21458 -36.934648)
		(width 0.10795)
		(layer "F.Cu")
		(net "SPI_BMC_DO")
	)
	(segment
		(start 394.95349 -43.661076)
		(end 394.95349 -44.052998)
		(width 0.10795)
		(layer "F.Cu")
		(net "SPI_BMC_DO")
	)
	(segment
		(start 390.828022 -46.737778)
		(end 387.50875 -46.737778)
		(width 0.10795)
		(layer "F.Cu")
		(net "SPI_BMC_DO")
	)
	(segment
		(start 405.758396 -37.390832)
		(end 404.670768 -37.390832)
		(width 0.10795)
		(layer "F.Cu")
		(net "SPI_BMC_DO")
	)
	(segment
		(start 404.670768 -37.390832)
		(end 403.7838 -38.2778)
		(width 0.10795)
		(layer "F.Cu")
		(net "SPI_BMC_DO")
	)
	(segment
		(start 383.752598 -51.622198)
		(end 384.2258 -52.0954)
		(width 0.10795)
		(layer "F.Cu")
		(net "SPI_BMC_DO")
	)
	(segment
		(start 401.415758 -40.987472)
		(end 400.912076 -41.491154)
		(width 0.10795)
		(layer "F.Cu")
		(net "SPI_BMC_DO")
	)
	(segment
		(start 383.752598 -50.536856)
		(end 383.752598 -51.622198)
		(width 0.10795)
		(layer "F.Cu")
		(net "SPI_BMC_DO")
	)
	(segment
		(start 386.334 -47.912528)
		(end 386.334 -49.282604)
		(width 0.10795)
		(layer "F.Cu")
		(net "SPI_BMC_DO")
	)
	(segment
		(start 406.21458 -36.934648)
		(end 405.758396 -37.390832)
		(width 0.10795)
		(layer "F.Cu")
		(net "SPI_BMC_DO")
	)
	(segment
		(start 403.7838 -38.2778)
		(end 403.570186 -38.2778)
		(width 0.10795)
		(layer "F.Cu")
		(net "SPI_BMC_DO")
	)
	(segment
		(start 400.912076 -41.491154)
		(end 399.923 -41.491154)
		(width 0.10795)
		(layer "F.Cu")
		(net "SPI_BMC_DO")
	)
	(segment
		(start 383.992374 -50.29708)
		(end 383.752598 -50.536856)
		(width 0.10795)
		(layer "F.Cu")
		(net "SPI_BMC_DO")
	)
	(segment
		(start 398.328896 -41.14038)
		(end 397.14297 -42.326306)
		(width 0.10795)
		(layer "F.Cu")
		(net "SPI_BMC_DO")
	)
	(segment
		(start 397.14297 -42.326306)
		(end 396.28826 -42.326306)
		(width 0.10795)
		(layer "F.Cu")
		(net "SPI_BMC_DO")
	)
	(segment
		(start 403.570186 -38.2778)
		(end 402.580602 -39.267384)
		(width 0.10795)
		(layer "F.Cu")
		(net "SPI_BMC_DO")
	)
	(segment
		(start 386.334 -49.282604)
		(end 385.319524 -50.29708)
		(width 0.10795)
		(layer "F.Cu")
		(net "SPI_BMC_DO")
	)
	(segment
		(start 394.95349 -44.052998)
		(end 393.603226 -45.403262)
		(width 0.10795)
		(layer "F.Cu")
		(net "SPI_BMC_DO")
	)
	(segment
		(start 385.319524 -50.29708)
		(end 383.992374 -50.29708)
		(width 0.10795)
		(layer "F.Cu")
		(net "SPI_BMC_DO")
	)
	(via
		(at 401.415758 -40.987472)
		(size 0.762)
		(drill 0.381)
		(layers "F.Cu" "B.Cu")
		(net "SPI_BMC_DO")
	)
	(via
		(at 384.2258 -52.0954)
		(size 0.508)
		(drill 0.254)
		(layers "F.Cu" "B.Cu")
		(net "SPI_BMC_DO")
	)
	(segment
		(start 382.5875 -51.6255)
		(end 383.7559 -51.6255)
		(width 0.10795)
		(layer "B.Cu")
		(net "SPI_BMC_DO")
	)
	(segment
		(start 383.7559 -51.6255)
		(end 384.2258 -52.0954)
		(width 0.10795)
		(layer "B.Cu")
		(net "SPI_BMC_DO")
	)
	(segment
		(start 408.279854 -37.324538)
		(end 408.690064 -37.734748)
		(width 0.10795)
		(layer "F.Cu")
		(net "SPI_BMC_CLK")
	)
	(via
		(at 386.9436 -53.9496)
		(size 0.6604)
		(drill 0.3302)
		(layers "F.Cu" "B.Cu")
		(net "SPI_BMC_CLK")
	)
	(via
		(at 408.279854 -37.324538)
		(size 0.4572)
		(drill 0.2032)
		(layers "F.Cu" "B.Cu")
		(net "SPI_BMC_CLK")
	)
	(via
		(at 389.11149 -56.93664)
		(size 0.508)
		(drill 0.254)
		(layers "F.Cu" "B.Cu")
		(net "SPI_BMC_CLK")
	)
	(segment
		(start 384.8862 -52.6288)
		(end 384.683 -52.832)
		(width 0.10795)
		(layer "B.Cu")
		(net "SPI_BMC_CLK")
	)
	(segment
		(start 385.7117 -52.6288)
		(end 384.8862 -52.6288)
		(width 0.10795)
		(layer "B.Cu")
		(net "SPI_BMC_CLK")
	)
	(segment
		(start 389.11149 -56.999886)
		(end 389.11149 -56.93664)
		(width 0.10795)
		(layer "B.Cu")
		(net "SPI_BMC_CLK")
	)
	(segment
		(start 384.683 -53.2765)
		(end 384.429 -53.5305)
		(width 0.10795)
		(layer "B.Cu")
		(net "SPI_BMC_CLK")
	)
	(segment
		(start 386.9436 -53.9496)
		(end 387.4516 -54.4576)
		(width 0.10795)
		(layer "B.Cu")
		(net "SPI_BMC_CLK")
	)
	(segment
		(start 386.9436 -53.8607)
		(end 385.7117 -52.6288)
		(width 0.10795)
		(layer "B.Cu")
		(net "SPI_BMC_CLK")
	)
	(segment
		(start 387.819392 -56.698896)
		(end 387.819392 -57.123584)
		(width 0.10795)
		(layer "B.Cu")
		(net "SPI_BMC_CLK")
	)
	(segment
		(start 388.728204 -57.383172)
		(end 389.11149 -56.999886)
		(width 0.10795)
		(layer "B.Cu")
		(net "SPI_BMC_CLK")
	)
	(segment
		(start 388.07898 -57.383172)
		(end 388.728204 -57.383172)
		(width 0.10795)
		(layer "B.Cu")
		(net "SPI_BMC_CLK")
	)
	(segment
		(start 387.819392 -57.123584)
		(end 388.07898 -57.383172)
		(width 0.10795)
		(layer "B.Cu")
		(net "SPI_BMC_CLK")
	)
	(segment
		(start 384.683 -52.832)
		(end 384.683 -53.2765)
		(width 0.10795)
		(layer "B.Cu")
		(net "SPI_BMC_CLK")
	)
	(segment
		(start 387.4516 -56.331104)
		(end 387.819392 -56.698896)
		(width 0.10795)
		(layer "B.Cu")
		(net "SPI_BMC_CLK")
	)
	(segment
		(start 384.429 -53.5305)
		(end 382.5875 -53.5305)
		(width 0.10795)
		(layer "B.Cu")
		(net "SPI_BMC_CLK")
	)
	(segment
		(start 386.9436 -53.9496)
		(end 386.9436 -53.8607)
		(width 0.10795)
		(layer "B.Cu")
		(net "SPI_BMC_CLK")
	)
	(segment
		(start 387.4516 -54.4576)
		(end 387.4516 -56.331104)
		(width 0.10795)
		(layer "B.Cu")
		(net "SPI_BMC_CLK")
	)
	(segment
		(start 388.617206 -44.701968)
		(end 388.617206 -44.706794)
		(width 0.089408)
		(layer "In2.Cu")
		(net "SPI_BMC_CLK")
	)
	(segment
		(start 388.55015 -46.311312)
		(end 388.550404 -46.311566)
		(width 0.089408)
		(layer "In2.Cu")
		(net "SPI_BMC_CLK")
	)
	(segment
		(start 388.983474 -44.3357)
		(end 388.617206 -44.701968)
		(width 0.089408)
		(layer "In2.Cu")
		(net "SPI_BMC_CLK")
	)
	(segment
		(start 388.550404 -46.311566)
		(end 388.550404 -54.283356)
		(width 0.089408)
		(layer "In2.Cu")
		(net "SPI_BMC_CLK")
	)
	(segment
		(start 393.954 -39.627556)
		(end 393.954 -40.665146)
		(width 0.089408)
		(layer "In2.Cu")
		(net "SPI_BMC_CLK")
	)
	(segment
		(start 388.550404 -54.283356)
		(end 389.11149 -54.844442)
		(width 0.089408)
		(layer "In2.Cu")
		(net "SPI_BMC_CLK")
	)
	(segment
		(start 393.954 -40.665146)
		(end 390.283446 -44.3357)
		(width 0.089408)
		(layer "In2.Cu")
		(net "SPI_BMC_CLK")
	)
	(segment
		(start 397.558768 -38.74135)
		(end 394.840206 -38.74135)
		(width 0.089408)
		(layer "In2.Cu")
		(net "SPI_BMC_CLK")
	)
	(segment
		(start 389.11149 -54.844442)
		(end 389.11149 -56.93664)
		(width 0.089408)
		(layer "In2.Cu")
		(net "SPI_BMC_CLK")
	)
	(segment
		(start 394.840206 -38.74135)
		(end 393.954 -39.627556)
		(width 0.089408)
		(layer "In2.Cu")
		(net "SPI_BMC_CLK")
	)
	(segment
		(start 388.55015 -45.89145)
		(end 388.55015 -46.311312)
		(width 0.089408)
		(layer "In2.Cu")
		(net "SPI_BMC_CLK")
	)
	(segment
		(start 388.550404 -45.891196)
		(end 388.55015 -45.89145)
		(width 0.089408)
		(layer "In2.Cu")
		(net "SPI_BMC_CLK")
	)
	(segment
		(start 388.550404 -44.773596)
		(end 388.550404 -45.891196)
		(width 0.089408)
		(layer "In2.Cu")
		(net "SPI_BMC_CLK")
	)
	(segment
		(start 407.912316 -36.957)
		(end 399.343118 -36.957)
		(width 0.089408)
		(layer "In2.Cu")
		(net "SPI_BMC_CLK")
	)
	(segment
		(start 399.343118 -36.957)
		(end 397.558768 -38.74135)
		(width 0.089408)
		(layer "In2.Cu")
		(net "SPI_BMC_CLK")
	)
	(segment
		(start 408.279854 -37.324538)
		(end 407.912316 -36.957)
		(width 0.089408)
		(layer "In2.Cu")
		(net "SPI_BMC_CLK")
	)
	(segment
		(start 388.617206 -44.706794)
		(end 388.550404 -44.773596)
		(width 0.089408)
		(layer "In2.Cu")
		(net "SPI_BMC_CLK")
	)
	(segment
		(start 390.283446 -44.3357)
		(end 388.983474 -44.3357)
		(width 0.089408)
		(layer "In2.Cu")
		(net "SPI_BMC_CLK")
	)
	(segment
		(start 407.890218 -37.734748)
		(end 407.490168 -38.134798)
		(width 0.10795)
		(layer "F.Cu")
		(net "SPI_BMC_CS0_N")
	)
	(via
		(at 389.99795 -47.756064)
		(size 0.508)
		(drill 0.254)
		(layers "F.Cu" "B.Cu")
		(net "SPI_BMC_CS0_N")
	)
	(via
		(at 407.490168 -38.134798)
		(size 0.4572)
		(drill 0.2032)
		(layers "F.Cu" "B.Cu")
		(net "SPI_BMC_CS0_N")
	)
	(via
		(at 385.064 -48.0568)
		(size 0.6604)
		(drill 0.3302)
		(layers "F.Cu" "B.Cu")
		(net "SPI_BMC_CS0_N")
	)
	(segment
		(start 384.287776 -48.528224)
		(end 383.424176 -48.528224)
		(width 0.10795)
		(layer "B.Cu")
		(net "SPI_BMC_CS0_N")
	)
	(segment
		(start 389.99795 -47.174404)
		(end 389.531606 -46.70806)
		(width 0.10795)
		(layer "B.Cu")
		(net "SPI_BMC_CS0_N")
	)
	(segment
		(start 389.99795 -47.756064)
		(end 389.99795 -47.174404)
		(width 0.10795)
		(layer "B.Cu")
		(net "SPI_BMC_CS0_N")
	)
	(segment
		(start 382.7145 -49.2379)
		(end 380.529592 -49.2379)
		(width 0.10795)
		(layer "B.Cu")
		(net "SPI_BMC_CS0_N")
	)
	(segment
		(start 379.7554 -50.012092)
		(end 379.7554 -50.597054)
		(width 0.10795)
		(layer "B.Cu")
		(net "SPI_BMC_CS0_N")
	)
	(segment
		(start 383.424176 -48.528224)
		(end 382.7145 -49.2379)
		(width 0.10795)
		(layer "B.Cu")
		(net "SPI_BMC_CS0_N")
	)
	(segment
		(start 384.296412 -48.52797)
		(end 384.28803 -48.52797)
		(width 0.10795)
		(layer "B.Cu")
		(net "SPI_BMC_CS0_N")
	)
	(segment
		(start 384.97891 -47.108364)
		(end 384.97891 -47.539656)
		(width 0.10795)
		(layer "B.Cu")
		(net "SPI_BMC_CS0_N")
	)
	(segment
		(start 380.529592 -49.2379)
		(end 379.7554 -50.012092)
		(width 0.10795)
		(layer "B.Cu")
		(net "SPI_BMC_CS0_N")
	)
	(segment
		(start 385.379214 -46.70806)
		(end 384.97891 -47.108364)
		(width 0.10795)
		(layer "B.Cu")
		(net "SPI_BMC_CS0_N")
	)
	(segment
		(start 378.6124 -51.0286)
		(end 378.5743 -50.9905)
		(width 0.10795)
		(layer "B.Cu")
		(net "SPI_BMC_CS0_N")
	)
	(segment
		(start 379.7554 -50.597054)
		(end 379.323854 -51.0286)
		(width 0.10795)
		(layer "B.Cu")
		(net "SPI_BMC_CS0_N")
	)
	(segment
		(start 384.729482 -48.391318)
		(end 384.433064 -48.391318)
		(width 0.10795)
		(layer "B.Cu")
		(net "SPI_BMC_CS0_N")
	)
	(segment
		(start 379.323854 -51.0286)
		(end 378.6124 -51.0286)
		(width 0.10795)
		(layer "B.Cu")
		(net "SPI_BMC_CS0_N")
	)
	(segment
		(start 385.064 -48.0568)
		(end 384.729482 -48.391318)
		(width 0.10795)
		(layer "B.Cu")
		(net "SPI_BMC_CS0_N")
	)
	(segment
		(start 378.5743 -50.9905)
		(end 377.1265 -50.9905)
		(width 0.10795)
		(layer "B.Cu")
		(net "SPI_BMC_CS0_N")
	)
	(segment
		(start 384.28803 -48.52797)
		(end 384.287776 -48.528224)
		(width 0.10795)
		(layer "B.Cu")
		(net "SPI_BMC_CS0_N")
	)
	(segment
		(start 384.97891 -47.539656)
		(end 385.064 -47.624746)
		(width 0.10795)
		(layer "B.Cu")
		(net "SPI_BMC_CS0_N")
	)
	(segment
		(start 384.433064 -48.391318)
		(end 384.296412 -48.52797)
		(width 0.10795)
		(layer "B.Cu")
		(net "SPI_BMC_CS0_N")
	)
	(segment
		(start 389.531606 -46.70806)
		(end 385.379214 -46.70806)
		(width 0.10795)
		(layer "B.Cu")
		(net "SPI_BMC_CS0_N")
	)
	(segment
		(start 385.064 -47.624746)
		(end 385.064 -48.0568)
		(width 0.10795)
		(layer "B.Cu")
		(net "SPI_BMC_CS0_N")
	)
	(segment
		(start 396.324074 -42.343578)
		(end 396.324074 -40.71366)
		(width 0.089408)
		(layer "In2.Cu")
		(net "SPI_BMC_CS0_N")
	)
	(segment
		(start 390.076436 -47.404528)
		(end 390.075928 -47.40402)
		(width 0.089408)
		(layer "In2.Cu")
		(net "SPI_BMC_CS0_N")
	)
	(segment
		(start 389.99795 -47.756064)
		(end 390.076436 -47.677578)
		(width 0.089408)
		(layer "In2.Cu")
		(net "SPI_BMC_CS0_N")
	)
	(segment
		(start 400.933666 -40.417496)
		(end 402.227288 -39.123874)
		(width 0.089408)
		(layer "In2.Cu")
		(net "SPI_BMC_CS0_N")
	)
	(segment
		(start 391.574782 -44.594526)
		(end 391.752328 -44.594526)
		(width 0.089408)
		(layer "In2.Cu")
		(net "SPI_BMC_CS0_N")
	)
	(segment
		(start 396.324074 -40.71366)
		(end 396.620238 -40.417496)
		(width 0.089408)
		(layer "In2.Cu")
		(net "SPI_BMC_CS0_N")
	)
	(segment
		(start 391.91057 -44.594272)
		(end 391.910824 -44.594526)
		(width 0.089408)
		(layer "In2.Cu")
		(net "SPI_BMC_CS0_N")
	)
	(segment
		(start 391.752328 -44.594526)
		(end 391.752582 -44.594272)
		(width 0.089408)
		(layer "In2.Cu")
		(net "SPI_BMC_CS0_N")
	)
	(segment
		(start 394.073126 -44.594526)
		(end 396.324074 -42.343578)
		(width 0.089408)
		(layer "In2.Cu")
		(net "SPI_BMC_CS0_N")
	)
	(segment
		(start 396.620238 -40.417496)
		(end 400.933666 -40.417496)
		(width 0.089408)
		(layer "In2.Cu")
		(net "SPI_BMC_CS0_N")
	)
	(segment
		(start 391.752582 -44.594272)
		(end 391.91057 -44.594272)
		(width 0.089408)
		(layer "In2.Cu")
		(net "SPI_BMC_CS0_N")
	)
	(segment
		(start 406.501092 -39.123874)
		(end 407.490168 -38.134798)
		(width 0.089408)
		(layer "In2.Cu")
		(net "SPI_BMC_CS0_N")
	)
	(segment
		(start 390.076436 -46.092872)
		(end 391.574782 -44.594526)
		(width 0.089408)
		(layer "In2.Cu")
		(net "SPI_BMC_CS0_N")
	)
	(segment
		(start 390.076436 -46.296072)
		(end 390.076436 -46.092872)
		(width 0.089408)
		(layer "In2.Cu")
		(net "SPI_BMC_CS0_N")
	)
	(segment
		(start 391.910824 -44.594526)
		(end 394.073126 -44.594526)
		(width 0.089408)
		(layer "In2.Cu")
		(net "SPI_BMC_CS0_N")
	)
	(segment
		(start 390.075928 -46.29658)
		(end 390.076436 -46.296072)
		(width 0.089408)
		(layer "In2.Cu")
		(net "SPI_BMC_CS0_N")
	)
	(segment
		(start 402.227288 -39.123874)
		(end 406.501092 -39.123874)
		(width 0.089408)
		(layer "In2.Cu")
		(net "SPI_BMC_CS0_N")
	)
	(segment
		(start 390.076436 -47.677578)
		(end 390.076436 -47.404528)
		(width 0.089408)
		(layer "In2.Cu")
		(net "SPI_BMC_CS0_N")
	)
	(segment
		(start 390.075928 -47.40402)
		(end 390.075928 -46.29658)
		(width 0.089408)
		(layer "In2.Cu")
		(net "SPI_BMC_CS0_N")
	)
	(segment
		(start 413.3215 -109.363002)
		(end 413.3215 -109.728)
		(width 0.10795)
		(layer "F.Cu")
		(net "IRQ_BMC_PCH_NMI_STBY_N")
	)
	(segment
		(start 409.490164 -40.93464)
		(end 409.090114 -40.53459)
		(width 0.10795)
		(layer "F.Cu")
		(net "IRQ_BMC_PCH_NMI_STBY_N")
	)
	(segment
		(start 393.18565 -116.72316)
		(end 393.68095 -116.953284)
		(width 0.10668)
		(layer "F.Cu")
		(net "IRQ_BMC_PCH_NMI_STBY_N")
	)
	(segment
		(start 414.8455 -109.728)
		(end 414.8455 -109.413802)
		(width 0.10795)
		(layer "F.Cu")
		(net "IRQ_BMC_PCH_NMI_STBY_N")
	)
	(segment
		(start 414.0581 -108.626402)
		(end 413.3215 -109.363002)
		(width 0.10795)
		(layer "F.Cu")
		(net "IRQ_BMC_PCH_NMI_STBY_N")
	)
	(segment
		(start 414.8455 -109.413802)
		(end 414.0581 -108.626402)
		(width 0.10795)
		(layer "F.Cu")
		(net "IRQ_BMC_PCH_NMI_STBY_N")
	)
	(via
		(at 393.68095 -116.953284)
		(size 0.508)
		(drill 0.254)
		(layers "F.Cu" "B.Cu")
		(net "IRQ_BMC_PCH_NMI_STBY_N")
	)
	(via
		(at 414.0581 -108.626402)
		(size 0.508)
		(drill 0.254)
		(layers "F.Cu" "B.Cu")
		(net "IRQ_BMC_PCH_NMI_STBY_N")
	)
	(via
		(at 409.090114 -40.53459)
		(size 0.4572)
		(drill 0.2032)
		(layers "F.Cu" "B.Cu")
		(net "IRQ_BMC_PCH_NMI_STBY_N")
	)
	(via
		(at 473.49918 -53.814726)
		(size 0.508)
		(drill 0.254)
		(layers "F.Cu" "B.Cu")
		(net "IRQ_BMC_PCH_NMI_STBY_N")
	)
	(segment
		(start 413.902906 -79.262986)
		(end 413.902906 -78.946502)
		(width 0.089408)
		(layer "In2.Cu")
		(net "IRQ_BMC_PCH_NMI_STBY_N")
	)
	(segment
		(start 434.893974 -54.5719)
		(end 436.455566 -56.133492)
		(width 0.089408)
		(layer "In2.Cu")
		(net "IRQ_BMC_PCH_NMI_STBY_N")
	)
	(segment
		(start 413.902906 -78.946502)
		(end 413.90316 -78.946248)
		(width 0.089408)
		(layer "In2.Cu")
		(net "IRQ_BMC_PCH_NMI_STBY_N")
	)
	(segment
		(start 428.683166 -55.712868)
		(end 429.824134 -54.5719)
		(width 0.089408)
		(layer "In2.Cu")
		(net "IRQ_BMC_PCH_NMI_STBY_N")
	)
	(segment
		(start 413.90316 -77.76464)
		(end 413.902906 -77.764386)
		(width 0.089408)
		(layer "In2.Cu")
		(net "IRQ_BMC_PCH_NMI_STBY_N")
	)
	(segment
		(start 412.06801 -95.1992)
		(end 412.06801 -87.942674)
		(width 0.089408)
		(layer "In2.Cu")
		(net "IRQ_BMC_PCH_NMI_STBY_N")
	)
	(segment
		(start 413.333946 -80.436974)
		(end 413.90316 -79.86776)
		(width 0.089408)
		(layer "In2.Cu")
		(net "IRQ_BMC_PCH_NMI_STBY_N")
	)
	(segment
		(start 411.051756 -85.664802)
		(end 411.051756 -85.163152)
		(width 0.089408)
		(layer "In2.Cu")
		(net "IRQ_BMC_PCH_NMI_STBY_N")
	)
	(segment
		(start 417.664138 -60.52693)
		(end 422.4782 -55.712868)
		(width 0.089408)
		(layer "In2.Cu")
		(net "IRQ_BMC_PCH_NMI_STBY_N")
	)
	(segment
		(start 411.051756 -85.163152)
		(end 411.253432 -84.961476)
		(width 0.089408)
		(layer "In2.Cu")
		(net "IRQ_BMC_PCH_NMI_STBY_N")
	)
	(segment
		(start 416.209226 -60.526676)
		(end 416.20948 -60.52693)
		(width 0.089408)
		(layer "In2.Cu")
		(net "IRQ_BMC_PCH_NMI_STBY_N")
	)
	(segment
		(start 413.90316 -75.75804)
		(end 413.902906 -75.757786)
		(width 0.089408)
		(layer "In2.Cu")
		(net "IRQ_BMC_PCH_NMI_STBY_N")
	)
	(segment
		(start 413.18561 -71.387716)
		(end 413.185864 -71.387462)
		(width 0.089408)
		(layer "In2.Cu")
		(net "IRQ_BMC_PCH_NMI_STBY_N")
	)
	(segment
		(start 412.364682 -84.961476)
		(end 413.333946 -83.992212)
		(width 0.089408)
		(layer "In2.Cu")
		(net "IRQ_BMC_PCH_NMI_STBY_N")
	)
	(segment
		(start 413.185864 -72.116696)
		(end 413.185864 -71.704454)
		(width 0.089408)
		(layer "In2.Cu")
		(net "IRQ_BMC_PCH_NMI_STBY_N")
	)
	(segment
		(start 411.253432 -84.961476)
		(end 412.364682 -84.961476)
		(width 0.089408)
		(layer "In2.Cu")
		(net "IRQ_BMC_PCH_NMI_STBY_N")
	)
	(segment
		(start 469.680036 -54.716172)
		(end 472.386406 -54.716172)
		(width 0.089408)
		(layer "In2.Cu")
		(net "IRQ_BMC_PCH_NMI_STBY_N")
	)
	(segment
		(start 413.90316 -78.946248)
		(end 413.90316 -77.76464)
		(width 0.089408)
		(layer "In2.Cu")
		(net "IRQ_BMC_PCH_NMI_STBY_N")
	)
	(segment
		(start 414.10636 -68.524374)
		(end 414.50514 -68.125594)
		(width 0.089408)
		(layer "In2.Cu")
		(net "IRQ_BMC_PCH_NMI_STBY_N")
	)
	(segment
		(start 416.20948 -60.52693)
		(end 417.664138 -60.52693)
		(width 0.089408)
		(layer "In2.Cu")
		(net "IRQ_BMC_PCH_NMI_STBY_N")
	)
	(segment
		(start 413.185864 -71.704454)
		(end 413.18561 -71.7042)
		(width 0.089408)
		(layer "In2.Cu")
		(net "IRQ_BMC_PCH_NMI_STBY_N")
	)
	(segment
		(start 413.401764 -74.723498)
		(end 413.401764 -72.332596)
		(width 0.089408)
		(layer "In2.Cu")
		(net "IRQ_BMC_PCH_NMI_STBY_N")
	)
	(segment
		(start 411.421072 -95.846138)
		(end 412.06801 -95.1992)
		(width 0.089408)
		(layer "In2.Cu")
		(net "IRQ_BMC_PCH_NMI_STBY_N")
	)
	(segment
		(start 413.90316 -75.224894)
		(end 413.401764 -74.723498)
		(width 0.089408)
		(layer "In2.Cu")
		(net "IRQ_BMC_PCH_NMI_STBY_N")
	)
	(segment
		(start 413.90316 -77.289152)
		(end 413.90316 -75.75804)
		(width 0.089408)
		(layer "In2.Cu")
		(net "IRQ_BMC_PCH_NMI_STBY_N")
	)
	(segment
		(start 462.939892 -56.133492)
		(end 463.7278 -56.9214)
		(width 0.089408)
		(layer "In2.Cu")
		(net "IRQ_BMC_PCH_NMI_STBY_N")
	)
	(segment
		(start 413.185864 -70.738746)
		(end 414.10636 -69.81825)
		(width 0.089408)
		(layer "In2.Cu")
		(net "IRQ_BMC_PCH_NMI_STBY_N")
	)
	(segment
		(start 413.90316 -75.441048)
		(end 413.90316 -75.224894)
		(width 0.089408)
		(layer "In2.Cu")
		(net "IRQ_BMC_PCH_NMI_STBY_N")
	)
	(segment
		(start 411.421072 -98.797872)
		(end 411.421072 -95.846138)
		(width 0.089408)
		(layer "In2.Cu")
		(net "IRQ_BMC_PCH_NMI_STBY_N")
	)
	(segment
		(start 413.185864 -71.387462)
		(end 413.185864 -70.738746)
		(width 0.089408)
		(layer "In2.Cu")
		(net "IRQ_BMC_PCH_NMI_STBY_N")
	)
	(segment
		(start 414.50514 -61.755782)
		(end 415.734246 -60.526676)
		(width 0.089408)
		(layer "In2.Cu")
		(net "IRQ_BMC_PCH_NMI_STBY_N")
	)
	(segment
		(start 413.902906 -77.764386)
		(end 413.902906 -77.289406)
		(width 0.089408)
		(layer "In2.Cu")
		(net "IRQ_BMC_PCH_NMI_STBY_N")
	)
	(segment
		(start 412.960058 -100.336858)
		(end 411.421072 -98.797872)
		(width 0.089408)
		(layer "In2.Cu")
		(net "IRQ_BMC_PCH_NMI_STBY_N")
	)
	(segment
		(start 413.90316 -79.26324)
		(end 413.902906 -79.262986)
		(width 0.089408)
		(layer "In2.Cu")
		(net "IRQ_BMC_PCH_NMI_STBY_N")
	)
	(segment
		(start 415.734246 -60.526676)
		(end 416.209226 -60.526676)
		(width 0.089408)
		(layer "In2.Cu")
		(net "IRQ_BMC_PCH_NMI_STBY_N")
	)
	(segment
		(start 411.051502 -86.926166)
		(end 411.051502 -85.665056)
		(width 0.089408)
		(layer "In2.Cu")
		(net "IRQ_BMC_PCH_NMI_STBY_N")
	)
	(segment
		(start 467.474808 -56.9214)
		(end 469.680036 -54.716172)
		(width 0.089408)
		(layer "In2.Cu")
		(net "IRQ_BMC_PCH_NMI_STBY_N")
	)
	(segment
		(start 412.06801 -87.942674)
		(end 411.051502 -86.926166)
		(width 0.089408)
		(layer "In2.Cu")
		(net "IRQ_BMC_PCH_NMI_STBY_N")
	)
	(segment
		(start 413.401764 -72.332596)
		(end 413.185864 -72.116696)
		(width 0.089408)
		(layer "In2.Cu")
		(net "IRQ_BMC_PCH_NMI_STBY_N")
	)
	(segment
		(start 414.10636 -69.81825)
		(end 414.10636 -68.524374)
		(width 0.089408)
		(layer "In2.Cu")
		(net "IRQ_BMC_PCH_NMI_STBY_N")
	)
	(segment
		(start 463.7278 -56.9214)
		(end 467.474808 -56.9214)
		(width 0.089408)
		(layer "In2.Cu")
		(net "IRQ_BMC_PCH_NMI_STBY_N")
	)
	(segment
		(start 413.333946 -83.992212)
		(end 413.333946 -80.436974)
		(width 0.089408)
		(layer "In2.Cu")
		(net "IRQ_BMC_PCH_NMI_STBY_N")
	)
	(segment
		(start 422.4782 -55.712868)
		(end 428.683166 -55.712868)
		(width 0.089408)
		(layer "In2.Cu")
		(net "IRQ_BMC_PCH_NMI_STBY_N")
	)
	(segment
		(start 413.012382 -107.580684)
		(end 413.012382 -100.398326)
		(width 0.089408)
		(layer "In2.Cu")
		(net "IRQ_BMC_PCH_NMI_STBY_N")
	)
	(segment
		(start 412.960058 -100.346002)
		(end 412.960058 -100.336858)
		(width 0.089408)
		(layer "In2.Cu")
		(net "IRQ_BMC_PCH_NMI_STBY_N")
	)
	(segment
		(start 413.902906 -77.289406)
		(end 413.90316 -77.289152)
		(width 0.089408)
		(layer "In2.Cu")
		(net "IRQ_BMC_PCH_NMI_STBY_N")
	)
	(segment
		(start 414.50514 -68.125594)
		(end 414.50514 -61.755782)
		(width 0.089408)
		(layer "In2.Cu")
		(net "IRQ_BMC_PCH_NMI_STBY_N")
	)
	(segment
		(start 473.280994 -54.032912)
		(end 473.49918 -53.814726)
		(width 0.089408)
		(layer "In2.Cu")
		(net "IRQ_BMC_PCH_NMI_STBY_N")
	)
	(segment
		(start 411.051502 -85.665056)
		(end 411.051756 -85.664802)
		(width 0.089408)
		(layer "In2.Cu")
		(net "IRQ_BMC_PCH_NMI_STBY_N")
	)
	(segment
		(start 413.18561 -71.7042)
		(end 413.18561 -71.387716)
		(width 0.089408)
		(layer "In2.Cu")
		(net "IRQ_BMC_PCH_NMI_STBY_N")
	)
	(segment
		(start 472.386406 -54.716172)
		(end 473.069666 -54.032912)
		(width 0.089408)
		(layer "In2.Cu")
		(net "IRQ_BMC_PCH_NMI_STBY_N")
	)
	(segment
		(start 436.455566 -56.133492)
		(end 462.939892 -56.133492)
		(width 0.089408)
		(layer "In2.Cu")
		(net "IRQ_BMC_PCH_NMI_STBY_N")
	)
	(segment
		(start 413.90316 -79.86776)
		(end 413.90316 -79.26324)
		(width 0.089408)
		(layer "In2.Cu")
		(net "IRQ_BMC_PCH_NMI_STBY_N")
	)
	(segment
		(start 413.902906 -75.441302)
		(end 413.90316 -75.441048)
		(width 0.089408)
		(layer "In2.Cu")
		(net "IRQ_BMC_PCH_NMI_STBY_N")
	)
	(segment
		(start 414.0581 -108.626402)
		(end 413.012382 -107.580684)
		(width 0.089408)
		(layer "In2.Cu")
		(net "IRQ_BMC_PCH_NMI_STBY_N")
	)
	(segment
		(start 473.069666 -54.032912)
		(end 473.280994 -54.032912)
		(width 0.089408)
		(layer "In2.Cu")
		(net "IRQ_BMC_PCH_NMI_STBY_N")
	)
	(segment
		(start 429.824134 -54.5719)
		(end 434.893974 -54.5719)
		(width 0.089408)
		(layer "In2.Cu")
		(net "IRQ_BMC_PCH_NMI_STBY_N")
	)
	(segment
		(start 413.902906 -75.757786)
		(end 413.902906 -75.441302)
		(width 0.089408)
		(layer "In2.Cu")
		(net "IRQ_BMC_PCH_NMI_STBY_N")
	)
	(segment
		(start 413.012382 -100.398326)
		(end 412.960058 -100.346002)
		(width 0.089408)
		(layer "In2.Cu")
		(net "IRQ_BMC_PCH_NMI_STBY_N")
	)
	(segment
		(start 414.26511 -41.17975)
		(end 414.3248 -41.23944)
		(width 0.089408)
		(layer "In4.Cu")
		(net "IRQ_BMC_PCH_NMI_STBY_N")
	)
	(segment
		(start 464.85556 -41.3512)
		(end 466.632544 -41.3512)
		(width 0.089408)
		(layer "In4.Cu")
		(net "IRQ_BMC_PCH_NMI_STBY_N")
	)
	(segment
		(start 399.137378 -118.569486)
		(end 398.805146 -118.237254)
		(width 0.0889)
		(layer "In4.Cu")
		(net "IRQ_BMC_PCH_NMI_STBY_N")
	)
	(segment
		(start 411.426152 -116.131848)
		(end 408.042872 -116.131848)
		(width 0.089408)
		(layer "In4.Cu")
		(net "IRQ_BMC_PCH_NMI_STBY_N")
	)
	(segment
		(start 414.26511 -41.179242)
		(end 414.26511 -41.17975)
		(width 0.089408)
		(layer "In4.Cu")
		(net "IRQ_BMC_PCH_NMI_STBY_N")
	)
	(segment
		(start 450.346826 -40.699182)
		(end 451.021704 -40.024304)
		(width 0.089408)
		(layer "In4.Cu")
		(net "IRQ_BMC_PCH_NMI_STBY_N")
	)
	(segment
		(start 473.49537 -53.813964)
		(end 473.49537 -53.814726)
		(width 0.089408)
		(layer "In4.Cu")
		(net "IRQ_BMC_PCH_NMI_STBY_N")
	)
	(segment
		(start 425.80052 -41.178226)
		(end 427.700948 -39.277798)
		(width 0.089408)
		(layer "In4.Cu")
		(net "IRQ_BMC_PCH_NMI_STBY_N")
	)
	(segment
		(start 445.089026 -40.11422)
		(end 445.673988 -40.699182)
		(width 0.089408)
		(layer "In4.Cu")
		(net "IRQ_BMC_PCH_NMI_STBY_N")
	)
	(segment
		(start 462.610454 -39.106094)
		(end 464.85556 -41.3512)
		(width 0.089408)
		(layer "In4.Cu")
		(net "IRQ_BMC_PCH_NMI_STBY_N")
	)
	(segment
		(start 396.984728 -118.237254)
		(end 396.72006 -117.972586)
		(width 0.0889)
		(layer "In4.Cu")
		(net "IRQ_BMC_PCH_NMI_STBY_N")
	)
	(segment
		(start 414.045146 -40.959786)
		(end 414.045654 -40.959786)
		(width 0.089408)
		(layer "In4.Cu")
		(net "IRQ_BMC_PCH_NMI_STBY_N")
	)
	(segment
		(start 412.5214 -115.0366)
		(end 411.426152 -116.131848)
		(width 0.089408)
		(layer "In4.Cu")
		(net "IRQ_BMC_PCH_NMI_STBY_N")
	)
	(segment
		(start 470.958926 -45.371512)
		(end 472.52509 -46.937676)
		(width 0.089408)
		(layer "In4.Cu")
		(net "IRQ_BMC_PCH_NMI_STBY_N")
	)
	(segment
		(start 409.483814 -40.92829)
		(end 414.01365 -40.92829)
		(width 0.089408)
		(layer "In4.Cu")
		(net "IRQ_BMC_PCH_NMI_STBY_N")
	)
	(segment
		(start 451.021704 -40.024304)
		(end 454.88479 -40.024304)
		(width 0.089408)
		(layer "In4.Cu")
		(net "IRQ_BMC_PCH_NMI_STBY_N")
	)
	(segment
		(start 414.0581 -109.5248)
		(end 412.5214 -111.0615)
		(width 0.089408)
		(layer "In4.Cu")
		(net "IRQ_BMC_PCH_NMI_STBY_N")
	)
	(segment
		(start 405.605234 -118.569486)
		(end 401.068286 -118.569486)
		(width 0.089408)
		(layer "In4.Cu")
		(net "IRQ_BMC_PCH_NMI_STBY_N")
	)
	(segment
		(start 419.000432 -43.086528)
		(end 419.159182 -43.245278)
		(width 0.089408)
		(layer "In4.Cu")
		(net "IRQ_BMC_PCH_NMI_STBY_N")
	)
	(segment
		(start 415.42462 -43.086528)
		(end 419.000432 -43.086528)
		(width 0.089408)
		(layer "In4.Cu")
		(net "IRQ_BMC_PCH_NMI_STBY_N")
	)
	(segment
		(start 467.83244 -43.087036)
		(end 468.51697 -43.771566)
		(width 0.089408)
		(layer "In4.Cu")
		(net "IRQ_BMC_PCH_NMI_STBY_N")
	)
	(segment
		(start 409.090114 -40.53459)
		(end 409.483814 -40.92829)
		(width 0.089408)
		(layer "In4.Cu")
		(net "IRQ_BMC_PCH_NMI_STBY_N")
	)
	(segment
		(start 472.52509 -52.657756)
		(end 473.507562 -53.640228)
		(width 0.089408)
		(layer "In4.Cu")
		(net "IRQ_BMC_PCH_NMI_STBY_N")
	)
	(segment
		(start 455.803 -39.106094)
		(end 462.610454 -39.106094)
		(width 0.089408)
		(layer "In4.Cu")
		(net "IRQ_BMC_PCH_NMI_STBY_N")
	)
	(segment
		(start 468.51697 -43.771566)
		(end 468.759286 -43.771566)
		(width 0.089408)
		(layer "In4.Cu")
		(net "IRQ_BMC_PCH_NMI_STBY_N")
	)
	(segment
		(start 414.01365 -40.92829)
		(end 414.045146 -40.959786)
		(width 0.089408)
		(layer "In4.Cu")
		(net "IRQ_BMC_PCH_NMI_STBY_N")
	)
	(segment
		(start 401.068286 -118.569486)
		(end 399.137378 -118.569486)
		(width 0.0889)
		(layer "In4.Cu")
		(net "IRQ_BMC_PCH_NMI_STBY_N")
	)
	(segment
		(start 467.83244 -42.551096)
		(end 467.83244 -43.087036)
		(width 0.089408)
		(layer "In4.Cu")
		(net "IRQ_BMC_PCH_NMI_STBY_N")
	)
	(segment
		(start 470.857326 -45.371512)
		(end 470.958926 -45.371512)
		(width 0.089408)
		(layer "In4.Cu")
		(net "IRQ_BMC_PCH_NMI_STBY_N")
	)
	(segment
		(start 469.358726 -43.771312)
		(end 470.451688 -44.864274)
		(width 0.089408)
		(layer "In4.Cu")
		(net "IRQ_BMC_PCH_NMI_STBY_N")
	)
	(segment
		(start 414.3248 -41.23944)
		(end 414.3248 -41.986708)
		(width 0.089408)
		(layer "In4.Cu")
		(net "IRQ_BMC_PCH_NMI_STBY_N")
	)
	(segment
		(start 398.805146 -118.237254)
		(end 396.984728 -118.237254)
		(width 0.0889)
		(layer "In4.Cu")
		(net "IRQ_BMC_PCH_NMI_STBY_N")
	)
	(segment
		(start 468.75954 -43.771312)
		(end 469.358726 -43.771312)
		(width 0.089408)
		(layer "In4.Cu")
		(net "IRQ_BMC_PCH_NMI_STBY_N")
	)
	(segment
		(start 433.073048 -39.675308)
		(end 433.51196 -40.11422)
		(width 0.089408)
		(layer "In4.Cu")
		(net "IRQ_BMC_PCH_NMI_STBY_N")
	)
	(segment
		(start 430.550066 -39.675308)
		(end 433.073048 -39.675308)
		(width 0.089408)
		(layer "In4.Cu")
		(net "IRQ_BMC_PCH_NMI_STBY_N")
	)
	(segment
		(start 396.72006 -117.567202)
		(end 396.452852 -117.299994)
		(width 0.0889)
		(layer "In4.Cu")
		(net "IRQ_BMC_PCH_NMI_STBY_N")
	)
	(segment
		(start 468.759286 -43.771566)
		(end 468.75954 -43.771312)
		(width 0.089408)
		(layer "In4.Cu")
		(net "IRQ_BMC_PCH_NMI_STBY_N")
	)
	(segment
		(start 412.5214 -111.0615)
		(end 412.5214 -115.0366)
		(width 0.089408)
		(layer "In4.Cu")
		(net "IRQ_BMC_PCH_NMI_STBY_N")
	)
	(segment
		(start 423.916856 -41.178226)
		(end 425.80052 -41.178226)
		(width 0.089408)
		(layer "In4.Cu")
		(net "IRQ_BMC_PCH_NMI_STBY_N")
	)
	(segment
		(start 408.042872 -116.131848)
		(end 405.605234 -118.569486)
		(width 0.089408)
		(layer "In4.Cu")
		(net "IRQ_BMC_PCH_NMI_STBY_N")
	)
	(segment
		(start 430.152556 -39.277798)
		(end 430.550066 -39.675308)
		(width 0.089408)
		(layer "In4.Cu")
		(net "IRQ_BMC_PCH_NMI_STBY_N")
	)
	(segment
		(start 472.52509 -46.937676)
		(end 472.52509 -52.657756)
		(width 0.089408)
		(layer "In4.Cu")
		(net "IRQ_BMC_PCH_NMI_STBY_N")
	)
	(segment
		(start 445.673988 -40.699182)
		(end 450.346826 -40.699182)
		(width 0.089408)
		(layer "In4.Cu")
		(net "IRQ_BMC_PCH_NMI_STBY_N")
	)
	(segment
		(start 414.045654 -40.959786)
		(end 414.26511 -41.179242)
		(width 0.089408)
		(layer "In4.Cu")
		(net "IRQ_BMC_PCH_NMI_STBY_N")
	)
	(segment
		(start 433.51196 -40.11422)
		(end 445.089026 -40.11422)
		(width 0.089408)
		(layer "In4.Cu")
		(net "IRQ_BMC_PCH_NMI_STBY_N")
	)
	(segment
		(start 470.451688 -44.965874)
		(end 470.857326 -45.371512)
		(width 0.089408)
		(layer "In4.Cu")
		(net "IRQ_BMC_PCH_NMI_STBY_N")
	)
	(segment
		(start 419.159182 -43.245278)
		(end 421.849804 -43.245278)
		(width 0.089408)
		(layer "In4.Cu")
		(net "IRQ_BMC_PCH_NMI_STBY_N")
	)
	(segment
		(start 473.507562 -53.801772)
		(end 473.49537 -53.813964)
		(width 0.089408)
		(layer "In4.Cu")
		(net "IRQ_BMC_PCH_NMI_STBY_N")
	)
	(segment
		(start 396.72006 -117.972586)
		(end 396.72006 -117.567202)
		(width 0.0889)
		(layer "In4.Cu")
		(net "IRQ_BMC_PCH_NMI_STBY_N")
	)
	(segment
		(start 466.632544 -41.3512)
		(end 467.83244 -42.551096)
		(width 0.089408)
		(layer "In4.Cu")
		(net "IRQ_BMC_PCH_NMI_STBY_N")
	)
	(segment
		(start 427.700948 -39.277798)
		(end 430.152556 -39.277798)
		(width 0.089408)
		(layer "In4.Cu")
		(net "IRQ_BMC_PCH_NMI_STBY_N")
	)
	(segment
		(start 421.849804 -43.245278)
		(end 423.916856 -41.178226)
		(width 0.089408)
		(layer "In4.Cu")
		(net "IRQ_BMC_PCH_NMI_STBY_N")
	)
	(segment
		(start 473.49537 -53.814726)
		(end 473.49918 -53.814726)
		(width 0.089408)
		(layer "In4.Cu")
		(net "IRQ_BMC_PCH_NMI_STBY_N")
	)
	(segment
		(start 414.3248 -41.986708)
		(end 415.42462 -43.086528)
		(width 0.089408)
		(layer "In4.Cu")
		(net "IRQ_BMC_PCH_NMI_STBY_N")
	)
	(segment
		(start 414.0581 -108.626402)
		(end 414.0581 -109.5248)
		(width 0.089408)
		(layer "In4.Cu")
		(net "IRQ_BMC_PCH_NMI_STBY_N")
	)
	(segment
		(start 454.88479 -40.024304)
		(end 455.803 -39.106094)
		(width 0.089408)
		(layer "In4.Cu")
		(net "IRQ_BMC_PCH_NMI_STBY_N")
	)
	(segment
		(start 470.451688 -44.864274)
		(end 470.451688 -44.965874)
		(width 0.089408)
		(layer "In4.Cu")
		(net "IRQ_BMC_PCH_NMI_STBY_N")
	)
	(segment
		(start 473.507562 -53.640228)
		(end 473.507562 -53.801772)
		(width 0.089408)
		(layer "In4.Cu")
		(net "IRQ_BMC_PCH_NMI_STBY_N")
	)
	(arc
		(start 394.871448 -117.299994)
		(mid 394.67155 -117.353493)
		(end 394.471652 -117.299994)
		(width 0.0889)
		(layer "In4.Cu")
		(net "IRQ_BMC_PCH_NMI_STBY_N")
	)
	(arc
		(start 395.862048 -117.299994)
		(mid 395.66215 -117.353493)
		(end 395.462252 -117.299994)
		(width 0.0889)
		(layer "In4.Cu")
		(net "IRQ_BMC_PCH_NMI_STBY_N")
	)
	(arc
		(start 396.452852 -117.299994)
		(mid 396.15745 -117.220863)
		(end 395.862048 -117.299994)
		(width 0.0889)
		(layer "In4.Cu")
		(net "IRQ_BMC_PCH_NMI_STBY_N")
	)
	(arc
		(start 394.471652 -117.299994)
		(mid 394.085825 -117.104918)
		(end 393.68095 -116.953284)
		(width 0.0889)
		(layer "In4.Cu")
		(net "IRQ_BMC_PCH_NMI_STBY_N")
	)
	(arc
		(start 395.462252 -117.299994)
		(mid 395.16685 -117.220863)
		(end 394.871448 -117.299994)
		(width 0.0889)
		(layer "In4.Cu")
		(net "IRQ_BMC_PCH_NMI_STBY_N")
	)
	(via
		(at 424.307 -16.383)
		(size 0.6604)
		(drill 0.3302)
		(layers "F.Cu" "B.Cu")
		(net "H_CPU0_MEMDEF_MEMHOT_LVT3_N")
	)
	(segment
		(start 426.045884 -14.311884)
		(end 425.9072 -14.1732)
		(width 0.10795)
		(layer "B.Cu")
		(net "H_CPU0_MEMDEF_MEMHOT_LVT3_N")
	)
	(segment
		(start 424.307 -16.383)
		(end 424.37685 -16.383)
		(width 0.10795)
		(layer "B.Cu")
		(net "H_CPU0_MEMDEF_MEMHOT_LVT3_N")
	)
	(segment
		(start 424.37685 -16.383)
		(end 425.5008 -15.25905)
		(width 0.10795)
		(layer "B.Cu")
		(net "H_CPU0_MEMDEF_MEMHOT_LVT3_N")
	)
	(segment
		(start 425.9072 -14.1732)
		(end 425.5008 -14.1732)
		(width 0.10795)
		(layer "B.Cu")
		(net "H_CPU0_MEMDEF_MEMHOT_LVT3_N")
	)
	(segment
		(start 426.873162 -14.311884)
		(end 426.045884 -14.311884)
		(width 0.10795)
		(layer "B.Cu")
		(net "H_CPU0_MEMDEF_MEMHOT_LVT3_N")
	)
	(segment
		(start 425.5008 -14.1732)
		(end 425.5008 -15.0622)
		(width 0.10795)
		(layer "B.Cu")
		(net "H_CPU0_MEMDEF_MEMHOT_LVT3_N")
	)
	(segment
		(start 427.390052 -13.794994)
		(end 426.873162 -14.311884)
		(width 0.10795)
		(layer "B.Cu")
		(net "H_CPU0_MEMDEF_MEMHOT_LVT3_N")
	)
	(segment
		(start 425.5008 -15.25905)
		(end 425.5008 -15.0622)
		(width 0.10795)
		(layer "B.Cu")
		(net "H_CPU0_MEMDEF_MEMHOT_LVT3_N")
	)
	(via
		(at 415.503614 -12.156186)
		(size 0.6604)
		(drill 0.3302)
		(layers "F.Cu" "B.Cu")
		(net "H_CPU0_MEMABC_MEMHOT_LVT3_N")
	)
	(via
		(at 409.156662 -16.220694)
		(size 0.508)
		(drill 0.254)
		(layers "F.Cu" "B.Cu")
		(net "H_CPU0_MEMABC_MEMHOT_LVT3_N")
	)
	(via
		(at 380.491238 -85.990684)
		(size 0.508)
		(drill 0.254)
		(layers "F.Cu" "B.Cu")
		(net "H_CPU0_MEMABC_MEMHOT_LVT3_N")
	)
	(via
		(at 393.158726 -61.812424)
		(size 0.508)
		(drill 0.254)
		(layers "F.Cu" "B.Cu")
		(net "H_CPU0_MEMABC_MEMHOT_LVT3_N")
	)
	(via
		(at 383.4892 -62.147704)
		(size 0.508)
		(drill 0.254)
		(layers "F.Cu" "B.Cu")
		(net "H_CPU0_MEMABC_MEMHOT_LVT3_N")
	)
	(segment
		(start 381.409194 -84.890356)
		(end 381.61595 -84.6836)
		(width 0.10795)
		(layer "B.Cu")
		(net "H_CPU0_MEMABC_MEMHOT_LVT3_N")
	)
	(segment
		(start 412.397956 -16.043148)
		(end 412.397956 -15.261844)
		(width 0.10795)
		(layer "B.Cu")
		(net "H_CPU0_MEMABC_MEMHOT_LVT3_N")
	)
	(segment
		(start 409.156662 -16.220694)
		(end 409.623768 -16.6878)
		(width 0.10795)
		(layer "B.Cu")
		(net "H_CPU0_MEMABC_MEMHOT_LVT3_N")
	)
	(segment
		(start 409.623768 -16.6878)
		(end 411.753304 -16.6878)
		(width 0.10795)
		(layer "B.Cu")
		(net "H_CPU0_MEMABC_MEMHOT_LVT3_N")
	)
	(segment
		(start 412.397956 -15.261844)
		(end 415.503614 -12.156186)
		(width 0.10795)
		(layer "B.Cu")
		(net "H_CPU0_MEMABC_MEMHOT_LVT3_N")
	)
	(segment
		(start 411.753304 -16.6878)
		(end 412.397956 -16.043148)
		(width 0.10795)
		(layer "B.Cu")
		(net "H_CPU0_MEMABC_MEMHOT_LVT3_N")
	)
	(segment
		(start 380.491238 -85.990684)
		(end 380.962662 -85.990684)
		(width 0.10795)
		(layer "B.Cu")
		(net "H_CPU0_MEMABC_MEMHOT_LVT3_N")
	)
	(segment
		(start 380.962662 -85.990684)
		(end 381.28448 -85.668866)
		(width 0.10795)
		(layer "B.Cu")
		(net "H_CPU0_MEMABC_MEMHOT_LVT3_N")
	)
	(segment
		(start 426.906944 -11.947906)
		(end 426.285406 -11.947906)
		(width 0.10795)
		(layer "B.Cu")
		(net "H_CPU0_MEMABC_MEMHOT_LVT3_N")
	)
	(segment
		(start 416.7378 -10.922)
		(end 425.4754 -10.922)
		(width 0.10795)
		(layer "B.Cu")
		(net "H_CPU0_MEMABC_MEMHOT_LVT3_N")
	)
	(segment
		(start 415.503614 -12.156186)
		(end 416.7378 -10.922)
		(width 0.10795)
		(layer "B.Cu")
		(net "H_CPU0_MEMABC_MEMHOT_LVT3_N")
	)
	(segment
		(start 381.407924 -84.890356)
		(end 381.409194 -84.890356)
		(width 0.10795)
		(layer "B.Cu")
		(net "H_CPU0_MEMABC_MEMHOT_LVT3_N")
	)
	(segment
		(start 426.285406 -11.947906)
		(end 426.0215 -11.684)
		(width 0.10795)
		(layer "B.Cu")
		(net "H_CPU0_MEMABC_MEMHOT_LVT3_N")
	)
	(segment
		(start 381.28448 -85.0138)
		(end 381.407924 -84.890356)
		(width 0.10795)
		(layer "B.Cu")
		(net "H_CPU0_MEMABC_MEMHOT_LVT3_N")
	)
	(segment
		(start 426.0215 -11.4681)
		(end 426.0215 -11.684)
		(width 0.10795)
		(layer "B.Cu")
		(net "H_CPU0_MEMABC_MEMHOT_LVT3_N")
	)
	(segment
		(start 425.4754 -10.922)
		(end 426.0215 -11.4681)
		(width 0.10795)
		(layer "B.Cu")
		(net "H_CPU0_MEMABC_MEMHOT_LVT3_N")
	)
	(segment
		(start 381.28448 -85.668866)
		(end 381.28448 -85.0138)
		(width 0.10795)
		(layer "B.Cu")
		(net "H_CPU0_MEMABC_MEMHOT_LVT3_N")
	)
	(segment
		(start 381.61595 -84.6836)
		(end 381.7239 -84.6836)
		(width 0.10795)
		(layer "B.Cu")
		(net "H_CPU0_MEMABC_MEMHOT_LVT3_N")
	)
	(segment
		(start 381.547624 -76.901548)
		(end 382.586992 -75.86218)
		(width 0.089408)
		(layer "In2.Cu")
		(net "H_CPU0_MEMABC_MEMHOT_LVT3_N")
	)
	(segment
		(start 382.155192 -72.605138)
		(end 381.673608 -72.123554)
		(width 0.089408)
		(layer "In2.Cu")
		(net "H_CPU0_MEMABC_MEMHOT_LVT3_N")
	)
	(segment
		(start 381.673608 -71.282306)
		(end 384.224784 -68.73113)
		(width 0.089408)
		(layer "In2.Cu")
		(net "H_CPU0_MEMABC_MEMHOT_LVT3_N")
	)
	(segment
		(start 381.275336 -79.675228)
		(end 381.275336 -78.595474)
		(width 0.089408)
		(layer "In2.Cu")
		(net "H_CPU0_MEMABC_MEMHOT_LVT3_N")
	)
	(segment
		(start 381.547624 -78.323186)
		(end 381.547624 -76.901548)
		(width 0.089408)
		(layer "In2.Cu")
		(net "H_CPU0_MEMABC_MEMHOT_LVT3_N")
	)
	(segment
		(start 381.075184 -84.73567)
		(end 380.16688 -83.827366)
		(width 0.089408)
		(layer "In2.Cu")
		(net "H_CPU0_MEMABC_MEMHOT_LVT3_N")
	)
	(segment
		(start 380.491238 -85.990684)
		(end 381.075184 -85.406738)
		(width 0.089408)
		(layer "In2.Cu")
		(net "H_CPU0_MEMABC_MEMHOT_LVT3_N")
	)
	(segment
		(start 382.155192 -73.464928)
		(end 382.155192 -72.605138)
		(width 0.089408)
		(layer "In2.Cu")
		(net "H_CPU0_MEMABC_MEMHOT_LVT3_N")
	)
	(segment
		(start 381.673608 -72.123554)
		(end 381.673608 -71.282306)
		(width 0.089408)
		(layer "In2.Cu")
		(net "H_CPU0_MEMABC_MEMHOT_LVT3_N")
	)
	(segment
		(start 382.586992 -75.86218)
		(end 382.586992 -73.896728)
		(width 0.089408)
		(layer "In2.Cu")
		(net "H_CPU0_MEMABC_MEMHOT_LVT3_N")
	)
	(segment
		(start 382.586992 -73.896728)
		(end 382.155192 -73.464928)
		(width 0.089408)
		(layer "In2.Cu")
		(net "H_CPU0_MEMABC_MEMHOT_LVT3_N")
	)
	(segment
		(start 380.16688 -80.783684)
		(end 381.275336 -79.675228)
		(width 0.089408)
		(layer "In2.Cu")
		(net "H_CPU0_MEMABC_MEMHOT_LVT3_N")
	)
	(segment
		(start 380.16688 -83.827366)
		(end 380.16688 -80.783684)
		(width 0.089408)
		(layer "In2.Cu")
		(net "H_CPU0_MEMABC_MEMHOT_LVT3_N")
	)
	(segment
		(start 384.224784 -62.883288)
		(end 383.4892 -62.147704)
		(width 0.089408)
		(layer "In2.Cu")
		(net "H_CPU0_MEMABC_MEMHOT_LVT3_N")
	)
	(segment
		(start 384.224784 -68.73113)
		(end 384.224784 -62.883288)
		(width 0.089408)
		(layer "In2.Cu")
		(net "H_CPU0_MEMABC_MEMHOT_LVT3_N")
	)
	(segment
		(start 381.275336 -78.595474)
		(end 381.547624 -78.323186)
		(width 0.089408)
		(layer "In2.Cu")
		(net "H_CPU0_MEMABC_MEMHOT_LVT3_N")
	)
	(segment
		(start 381.075184 -85.406738)
		(end 381.075184 -84.73567)
		(width 0.089408)
		(layer "In2.Cu")
		(net "H_CPU0_MEMABC_MEMHOT_LVT3_N")
	)
	(segment
		(start 393.477496 -62.630304)
		(end 392.8872 -63.2206)
		(width 0.089408)
		(layer "In4.Cu")
		(net "H_CPU0_MEMABC_MEMHOT_LVT3_N")
	)
	(segment
		(start 393.158726 -61.812424)
		(end 393.477496 -62.131194)
		(width 0.089408)
		(layer "In4.Cu")
		(net "H_CPU0_MEMABC_MEMHOT_LVT3_N")
	)
	(segment
		(start 383.66573 -64.211454)
		(end 382.81356 -63.359284)
		(width 0.089408)
		(layer "In4.Cu")
		(net "H_CPU0_MEMABC_MEMHOT_LVT3_N")
	)
	(segment
		(start 382.81356 -63.359284)
		(end 382.81356 -62.569344)
		(width 0.089408)
		(layer "In4.Cu")
		(net "H_CPU0_MEMABC_MEMHOT_LVT3_N")
	)
	(segment
		(start 382.81356 -62.569344)
		(end 383.2352 -62.147704)
		(width 0.089408)
		(layer "In4.Cu")
		(net "H_CPU0_MEMABC_MEMHOT_LVT3_N")
	)
	(segment
		(start 390.21893 -63.2206)
		(end 389.52043 -62.5221)
		(width 0.089408)
		(layer "In4.Cu")
		(net "H_CPU0_MEMABC_MEMHOT_LVT3_N")
	)
	(segment
		(start 383.66573 -64.42075)
		(end 383.66573 -64.211454)
		(width 0.089408)
		(layer "In4.Cu")
		(net "H_CPU0_MEMABC_MEMHOT_LVT3_N")
	)
	(segment
		(start 388.535164 -62.769496)
		(end 386.768848 -62.769496)
		(width 0.089408)
		(layer "In4.Cu")
		(net "H_CPU0_MEMABC_MEMHOT_LVT3_N")
	)
	(segment
		(start 386.768848 -62.769496)
		(end 384.806698 -64.731646)
		(width 0.089408)
		(layer "In4.Cu")
		(net "H_CPU0_MEMABC_MEMHOT_LVT3_N")
	)
	(segment
		(start 389.52043 -62.5221)
		(end 388.78256 -62.5221)
		(width 0.089408)
		(layer "In4.Cu")
		(net "H_CPU0_MEMABC_MEMHOT_LVT3_N")
	)
	(segment
		(start 383.976626 -64.731646)
		(end 383.66573 -64.42075)
		(width 0.089408)
		(layer "In4.Cu")
		(net "H_CPU0_MEMABC_MEMHOT_LVT3_N")
	)
	(segment
		(start 383.2352 -62.147704)
		(end 383.4892 -62.147704)
		(width 0.089408)
		(layer "In4.Cu")
		(net "H_CPU0_MEMABC_MEMHOT_LVT3_N")
	)
	(segment
		(start 392.8872 -63.2206)
		(end 390.21893 -63.2206)
		(width 0.089408)
		(layer "In4.Cu")
		(net "H_CPU0_MEMABC_MEMHOT_LVT3_N")
	)
	(segment
		(start 384.806698 -64.731646)
		(end 383.976626 -64.731646)
		(width 0.089408)
		(layer "In4.Cu")
		(net "H_CPU0_MEMABC_MEMHOT_LVT3_N")
	)
	(segment
		(start 393.477496 -62.131194)
		(end 393.477496 -62.630304)
		(width 0.089408)
		(layer "In4.Cu")
		(net "H_CPU0_MEMABC_MEMHOT_LVT3_N")
	)
	(segment
		(start 388.78256 -62.5221)
		(end 388.535164 -62.769496)
		(width 0.089408)
		(layer "In4.Cu")
		(net "H_CPU0_MEMABC_MEMHOT_LVT3_N")
	)
	(segment
		(start 392.78687 -26.58745)
		(end 392.78687 -27.827224)
		(width 0.089408)
		(layer "In9.Cu")
		(net "H_CPU0_MEMABC_MEMHOT_LVT3_N")
	)
	(segment
		(start 392.868658 -53.085746)
		(end 393.630912 -53.848)
		(width 0.089408)
		(layer "In9.Cu")
		(net "H_CPU0_MEMABC_MEMHOT_LVT3_N")
	)
	(segment
		(start 392.226546 -51.569112)
		(end 392.868658 -52.211224)
		(width 0.089408)
		(layer "In9.Cu")
		(net "H_CPU0_MEMABC_MEMHOT_LVT3_N")
	)
	(segment
		(start 393.574524 -42.142664)
		(end 392.66241 -43.055032)
		(width 0.089408)
		(layer "In9.Cu")
		(net "H_CPU0_MEMABC_MEMHOT_LVT3_N")
	)
	(segment
		(start 402.31949 -19.045682)
		(end 402.006816 -18.733008)
		(width 0.089408)
		(layer "In9.Cu")
		(net "H_CPU0_MEMABC_MEMHOT_LVT3_N")
	)
	(segment
		(start 409.156662 -16.220694)
		(end 409.156662 -16.937482)
		(width 0.089408)
		(layer "In9.Cu")
		(net "H_CPU0_MEMABC_MEMHOT_LVT3_N")
	)
	(segment
		(start 405.872696 -18.815558)
		(end 405.872696 -19.24177)
		(width 0.089408)
		(layer "In9.Cu")
		(net "H_CPU0_MEMABC_MEMHOT_LVT3_N")
	)
	(segment
		(start 408.187144 -17.907)
		(end 406.781254 -17.907)
		(width 0.089408)
		(layer "In9.Cu")
		(net "H_CPU0_MEMABC_MEMHOT_LVT3_N")
	)
	(segment
		(start 392.501882 -35.819334)
		(end 393.539726 -36.857178)
		(width 0.089408)
		(layer "In9.Cu")
		(net "H_CPU0_MEMABC_MEMHOT_LVT3_N")
	)
	(segment
		(start 409.156662 -16.937482)
		(end 408.187144 -17.907)
		(width 0.089408)
		(layer "In9.Cu")
		(net "H_CPU0_MEMABC_MEMHOT_LVT3_N")
	)
	(segment
		(start 392.501882 -32.955738)
		(end 392.501882 -35.819334)
		(width 0.089408)
		(layer "In9.Cu")
		(net "H_CPU0_MEMABC_MEMHOT_LVT3_N")
	)
	(segment
		(start 402.396452 -19.045682)
		(end 402.31949 -19.045682)
		(width 0.089408)
		(layer "In9.Cu")
		(net "H_CPU0_MEMABC_MEMHOT_LVT3_N")
	)
	(segment
		(start 393.539726 -36.857178)
		(end 393.539726 -38.355524)
		(width 0.089408)
		(layer "In9.Cu")
		(net "H_CPU0_MEMABC_MEMHOT_LVT3_N")
	)
	(segment
		(start 392.226546 -48.2219)
		(end 392.226546 -51.569112)
		(width 0.089408)
		(layer "In9.Cu")
		(net "H_CPU0_MEMABC_MEMHOT_LVT3_N")
	)
	(segment
		(start 392.868658 -52.211224)
		(end 392.868658 -53.085746)
		(width 0.089408)
		(layer "In9.Cu")
		(net "H_CPU0_MEMABC_MEMHOT_LVT3_N")
	)
	(segment
		(start 402.006816 -18.733008)
		(end 398.659604 -18.733008)
		(width 0.089408)
		(layer "In9.Cu")
		(net "H_CPU0_MEMABC_MEMHOT_LVT3_N")
	)
	(segment
		(start 403.598634 -20.247864)
		(end 402.396452 -19.045682)
		(width 0.089408)
		(layer "In9.Cu")
		(net "H_CPU0_MEMABC_MEMHOT_LVT3_N")
	)
	(segment
		(start 405.872696 -19.24177)
		(end 404.866602 -20.247864)
		(width 0.089408)
		(layer "In9.Cu")
		(net "H_CPU0_MEMABC_MEMHOT_LVT3_N")
	)
	(segment
		(start 393.539726 -38.355524)
		(end 393.563348 -38.379146)
		(width 0.089408)
		(layer "In9.Cu")
		(net "H_CPU0_MEMABC_MEMHOT_LVT3_N")
	)
	(segment
		(start 393.896088 -41.8211)
		(end 393.574524 -42.142664)
		(width 0.089408)
		(layer "In9.Cu")
		(net "H_CPU0_MEMABC_MEMHOT_LVT3_N")
	)
	(segment
		(start 404.866602 -20.247864)
		(end 403.598634 -20.247864)
		(width 0.089408)
		(layer "In9.Cu")
		(net "H_CPU0_MEMABC_MEMHOT_LVT3_N")
	)
	(segment
		(start 393.563348 -40.006778)
		(end 393.896088 -40.339518)
		(width 0.089408)
		(layer "In9.Cu")
		(net "H_CPU0_MEMABC_MEMHOT_LVT3_N")
	)
	(segment
		(start 392.973306 -46.211998)
		(end 392.973306 -47.47514)
		(width 0.089408)
		(layer "In9.Cu")
		(net "H_CPU0_MEMABC_MEMHOT_LVT3_N")
	)
	(segment
		(start 393.563348 -38.379146)
		(end 393.563348 -40.006778)
		(width 0.089408)
		(layer "In9.Cu")
		(net "H_CPU0_MEMABC_MEMHOT_LVT3_N")
	)
	(segment
		(start 392.66241 -45.901102)
		(end 392.973306 -46.211998)
		(width 0.089408)
		(layer "In9.Cu")
		(net "H_CPU0_MEMABC_MEMHOT_LVT3_N")
	)
	(segment
		(start 393.158726 -60.823348)
		(end 393.158726 -61.812424)
		(width 0.089408)
		(layer "In9.Cu")
		(net "H_CPU0_MEMABC_MEMHOT_LVT3_N")
	)
	(segment
		(start 392.78687 -27.827224)
		(end 392.583162 -28.030932)
		(width 0.089408)
		(layer "In9.Cu")
		(net "H_CPU0_MEMABC_MEMHOT_LVT3_N")
	)
	(segment
		(start 392.583162 -28.030932)
		(end 392.583162 -32.874458)
		(width 0.089408)
		(layer "In9.Cu")
		(net "H_CPU0_MEMABC_MEMHOT_LVT3_N")
	)
	(segment
		(start 393.630912 -60.351162)
		(end 393.158726 -60.823348)
		(width 0.089408)
		(layer "In9.Cu")
		(net "H_CPU0_MEMABC_MEMHOT_LVT3_N")
	)
	(segment
		(start 393.896088 -40.339518)
		(end 393.896088 -41.8211)
		(width 0.089408)
		(layer "In9.Cu")
		(net "H_CPU0_MEMABC_MEMHOT_LVT3_N")
	)
	(segment
		(start 392.741404 -24.651208)
		(end 392.741404 -24.893524)
		(width 0.089408)
		(layer "In9.Cu")
		(net "H_CPU0_MEMABC_MEMHOT_LVT3_N")
	)
	(segment
		(start 392.741404 -24.893524)
		(end 392.741658 -24.893778)
		(width 0.089408)
		(layer "In9.Cu")
		(net "H_CPU0_MEMABC_MEMHOT_LVT3_N")
	)
	(segment
		(start 392.583162 -32.874458)
		(end 392.501882 -32.955738)
		(width 0.089408)
		(layer "In9.Cu")
		(net "H_CPU0_MEMABC_MEMHOT_LVT3_N")
	)
	(segment
		(start 398.659604 -18.733008)
		(end 392.741404 -24.651208)
		(width 0.089408)
		(layer "In9.Cu")
		(net "H_CPU0_MEMABC_MEMHOT_LVT3_N")
	)
	(segment
		(start 393.630912 -53.848)
		(end 393.630912 -60.351162)
		(width 0.089408)
		(layer "In9.Cu")
		(net "H_CPU0_MEMABC_MEMHOT_LVT3_N")
	)
	(segment
		(start 392.973306 -47.47514)
		(end 392.226546 -48.2219)
		(width 0.089408)
		(layer "In9.Cu")
		(net "H_CPU0_MEMABC_MEMHOT_LVT3_N")
	)
	(segment
		(start 392.741658 -24.893778)
		(end 392.741658 -26.542238)
		(width 0.089408)
		(layer "In9.Cu")
		(net "H_CPU0_MEMABC_MEMHOT_LVT3_N")
	)
	(segment
		(start 392.741658 -26.542238)
		(end 392.78687 -26.58745)
		(width 0.089408)
		(layer "In9.Cu")
		(net "H_CPU0_MEMABC_MEMHOT_LVT3_N")
	)
	(segment
		(start 392.66241 -43.055032)
		(end 392.66241 -45.901102)
		(width 0.089408)
		(layer "In9.Cu")
		(net "H_CPU0_MEMABC_MEMHOT_LVT3_N")
	)
	(segment
		(start 406.781254 -17.907)
		(end 405.872696 -18.815558)
		(width 0.089408)
		(layer "In9.Cu")
		(net "H_CPU0_MEMABC_MEMHOT_LVT3_N")
	)
	(segment
		(start 375.144792 -71.095108)
		(end 374.744996 -71.494904)
		(width 0.1016)
		(layer "F.Cu")
		(net "FM_CPU1_FIVR_FAULT_LVT3_N")
	)
	(via
		(at 400.2024 -42.164)
		(size 0.6604)
		(drill 0.3302)
		(layers "F.Cu" "B.Cu")
		(net "FM_CPU1_FIVR_FAULT_LVT3_N")
	)
	(via
		(at 375.144792 -71.095108)
		(size 0.4572)
		(drill 0.2032)
		(layers "F.Cu" "B.Cu")
		(net "FM_CPU1_FIVR_FAULT_LVT3_N")
	)
	(via
		(at 381.163322 -39.324026)
		(size 0.508)
		(drill 0.254)
		(layers "F.Cu" "B.Cu")
		(net "FM_CPU1_FIVR_FAULT_LVT3_N")
	)
	(via
		(at 398.854676 -42.515536)
		(size 0.508)
		(drill 0.254)
		(layers "F.Cu" "B.Cu")
		(net "FM_CPU1_FIVR_FAULT_LVT3_N")
	)
	(segment
		(start 400.2024 -42.164)
		(end 401.5105 -42.164)
		(width 0.10795)
		(layer "B.Cu")
		(net "FM_CPU1_FIVR_FAULT_LVT3_N")
	)
	(segment
		(start 399.368264 -42.515536)
		(end 399.7198 -42.164)
		(width 0.10795)
		(layer "B.Cu")
		(net "FM_CPU1_FIVR_FAULT_LVT3_N")
	)
	(segment
		(start 399.7198 -42.164)
		(end 400.2024 -42.164)
		(width 0.10795)
		(layer "B.Cu")
		(net "FM_CPU1_FIVR_FAULT_LVT3_N")
	)
	(segment
		(start 398.854676 -42.515536)
		(end 399.368264 -42.515536)
		(width 0.10795)
		(layer "B.Cu")
		(net "FM_CPU1_FIVR_FAULT_LVT3_N")
	)
	(segment
		(start 384.59918 -37.703506)
		(end 385.655312 -37.703506)
		(width 0.089408)
		(layer "In4.Cu")
		(net "FM_CPU1_FIVR_FAULT_LVT3_N")
	)
	(segment
		(start 392.658346 -40.613076)
		(end 393.19327 -41.148)
		(width 0.089408)
		(layer "In4.Cu")
		(net "FM_CPU1_FIVR_FAULT_LVT3_N")
	)
	(segment
		(start 391.863834 -40.60698)
		(end 391.86993 -40.613076)
		(width 0.089408)
		(layer "In4.Cu")
		(net "FM_CPU1_FIVR_FAULT_LVT3_N")
	)
	(segment
		(start 381.163322 -39.324026)
		(end 381.26416 -39.223188)
		(width 0.089408)
		(layer "In4.Cu")
		(net "FM_CPU1_FIVR_FAULT_LVT3_N")
	)
	(segment
		(start 390.600184 -39.794434)
		(end 391.412984 -40.607234)
		(width 0.089408)
		(layer "In4.Cu")
		(net "FM_CPU1_FIVR_FAULT_LVT3_N")
	)
	(segment
		(start 393.19327 -41.148)
		(end 394.064998 -41.148)
		(width 0.089408)
		(layer "In4.Cu")
		(net "FM_CPU1_FIVR_FAULT_LVT3_N")
	)
	(segment
		(start 397.125444 -42.516044)
		(end 398.854168 -42.516044)
		(width 0.089408)
		(layer "In4.Cu")
		(net "FM_CPU1_FIVR_FAULT_LVT3_N")
	)
	(segment
		(start 390.600438 -39.666418)
		(end 390.600184 -39.666672)
		(width 0.089408)
		(layer "In4.Cu")
		(net "FM_CPU1_FIVR_FAULT_LVT3_N")
	)
	(segment
		(start 385.655312 -37.703506)
		(end 386.466334 -38.514528)
		(width 0.089408)
		(layer "In4.Cu")
		(net "FM_CPU1_FIVR_FAULT_LVT3_N")
	)
	(segment
		(start 384.316986 -37.9857)
		(end 384.59918 -37.703506)
		(width 0.089408)
		(layer "In4.Cu")
		(net "FM_CPU1_FIVR_FAULT_LVT3_N")
	)
	(segment
		(start 398.854168 -42.516044)
		(end 398.854676 -42.515536)
		(width 0.089408)
		(layer "In4.Cu")
		(net "FM_CPU1_FIVR_FAULT_LVT3_N")
	)
	(segment
		(start 389.538972 -38.514528)
		(end 390.600438 -39.575994)
		(width 0.089408)
		(layer "In4.Cu")
		(net "FM_CPU1_FIVR_FAULT_LVT3_N")
	)
	(segment
		(start 390.600184 -39.666672)
		(end 390.600184 -39.794434)
		(width 0.089408)
		(layer "In4.Cu")
		(net "FM_CPU1_FIVR_FAULT_LVT3_N")
	)
	(segment
		(start 383.602484 -37.9857)
		(end 384.316986 -37.9857)
		(width 0.089408)
		(layer "In4.Cu")
		(net "FM_CPU1_FIVR_FAULT_LVT3_N")
	)
	(segment
		(start 382.364996 -39.223188)
		(end 383.602484 -37.9857)
		(width 0.089408)
		(layer "In4.Cu")
		(net "FM_CPU1_FIVR_FAULT_LVT3_N")
	)
	(segment
		(start 386.466334 -38.514528)
		(end 389.538972 -38.514528)
		(width 0.089408)
		(layer "In4.Cu")
		(net "FM_CPU1_FIVR_FAULT_LVT3_N")
	)
	(segment
		(start 394.064998 -41.148)
		(end 394.066014 -41.146984)
		(width 0.089408)
		(layer "In4.Cu")
		(net "FM_CPU1_FIVR_FAULT_LVT3_N")
	)
	(segment
		(start 391.813796 -40.607234)
		(end 391.81405 -40.60698)
		(width 0.089408)
		(layer "In4.Cu")
		(net "FM_CPU1_FIVR_FAULT_LVT3_N")
	)
	(segment
		(start 394.066014 -41.146984)
		(end 395.756384 -41.146984)
		(width 0.089408)
		(layer "In4.Cu")
		(net "FM_CPU1_FIVR_FAULT_LVT3_N")
	)
	(segment
		(start 391.81405 -40.60698)
		(end 391.863834 -40.60698)
		(width 0.089408)
		(layer "In4.Cu")
		(net "FM_CPU1_FIVR_FAULT_LVT3_N")
	)
	(segment
		(start 395.756384 -41.146984)
		(end 397.125444 -42.516044)
		(width 0.089408)
		(layer "In4.Cu")
		(net "FM_CPU1_FIVR_FAULT_LVT3_N")
	)
	(segment
		(start 391.86993 -40.613076)
		(end 392.658346 -40.613076)
		(width 0.089408)
		(layer "In4.Cu")
		(net "FM_CPU1_FIVR_FAULT_LVT3_N")
	)
	(segment
		(start 381.26416 -39.223188)
		(end 382.364996 -39.223188)
		(width 0.089408)
		(layer "In4.Cu")
		(net "FM_CPU1_FIVR_FAULT_LVT3_N")
	)
	(segment
		(start 391.412984 -40.607234)
		(end 391.813796 -40.607234)
		(width 0.089408)
		(layer "In4.Cu")
		(net "FM_CPU1_FIVR_FAULT_LVT3_N")
	)
	(segment
		(start 390.600438 -39.575994)
		(end 390.600438 -39.666418)
		(width 0.089408)
		(layer "In4.Cu")
		(net "FM_CPU1_FIVR_FAULT_LVT3_N")
	)
	(segment
		(start 375.571512 -69.340476)
		(end 375.571512 -70.668388)
		(width 0.089408)
		(layer "In9.Cu")
		(net "FM_CPU1_FIVR_FAULT_LVT3_N")
	)
	(segment
		(start 377.359926 -64.919352)
		(end 377.359926 -65.07734)
		(width 0.089408)
		(layer "In9.Cu")
		(net "FM_CPU1_FIVR_FAULT_LVT3_N")
	)
	(segment
		(start 375.571512 -70.668388)
		(end 375.144792 -71.095108)
		(width 0.089408)
		(layer "In9.Cu")
		(net "FM_CPU1_FIVR_FAULT_LVT3_N")
	)
	(segment
		(start 380.357888 -51.027838)
		(end 381.089154 -51.759104)
		(width 0.089408)
		(layer "In9.Cu")
		(net "FM_CPU1_FIVR_FAULT_LVT3_N")
	)
	(segment
		(start 381.571246 -43.821604)
		(end 381.571246 -45.637704)
		(width 0.089408)
		(layer "In9.Cu")
		(net "FM_CPU1_FIVR_FAULT_LVT3_N")
	)
	(segment
		(start 377.36018 -65.077594)
		(end 377.36018 -66.45148)
		(width 0.089408)
		(layer "In9.Cu")
		(net "FM_CPU1_FIVR_FAULT_LVT3_N")
	)
	(segment
		(start 379.7427 -41.993058)
		(end 381.571246 -43.821604)
		(width 0.089408)
		(layer "In9.Cu")
		(net "FM_CPU1_FIVR_FAULT_LVT3_N")
	)
	(segment
		(start 379.742954 -41.206928)
		(end 379.742954 -41.219882)
		(width 0.089408)
		(layer "In9.Cu")
		(net "FM_CPU1_FIVR_FAULT_LVT3_N")
	)
	(segment
		(start 381.163322 -39.324026)
		(end 380.374652 -40.112696)
		(width 0.089408)
		(layer "In9.Cu")
		(net "FM_CPU1_FIVR_FAULT_LVT3_N")
	)
	(segment
		(start 379.548644 -40.112696)
		(end 379.314202 -40.347138)
		(width 0.089408)
		(layer "In9.Cu")
		(net "FM_CPU1_FIVR_FAULT_LVT3_N")
	)
	(segment
		(start 379.7427 -41.220136)
		(end 379.7427 -41.993058)
		(width 0.089408)
		(layer "In9.Cu")
		(net "FM_CPU1_FIVR_FAULT_LVT3_N")
	)
	(segment
		(start 381.089154 -56.664352)
		(end 381.257302 -56.8325)
		(width 0.089408)
		(layer "In9.Cu")
		(net "FM_CPU1_FIVR_FAULT_LVT3_N")
	)
	(segment
		(start 376.318272 -67.493388)
		(end 376.318272 -68.850002)
		(width 0.089408)
		(layer "In9.Cu")
		(net "FM_CPU1_FIVR_FAULT_LVT3_N")
	)
	(segment
		(start 379.314202 -40.347138)
		(end 379.314202 -40.778176)
		(width 0.089408)
		(layer "In9.Cu")
		(net "FM_CPU1_FIVR_FAULT_LVT3_N")
	)
	(segment
		(start 377.359926 -65.07734)
		(end 377.36018 -65.077594)
		(width 0.089408)
		(layer "In9.Cu")
		(net "FM_CPU1_FIVR_FAULT_LVT3_N")
	)
	(segment
		(start 377.36018 -66.45148)
		(end 376.318272 -67.493388)
		(width 0.089408)
		(layer "In9.Cu")
		(net "FM_CPU1_FIVR_FAULT_LVT3_N")
	)
	(segment
		(start 380.374652 -40.112696)
		(end 379.548644 -40.112696)
		(width 0.089408)
		(layer "In9.Cu")
		(net "FM_CPU1_FIVR_FAULT_LVT3_N")
	)
	(segment
		(start 381.089154 -51.759104)
		(end 381.089154 -56.664352)
		(width 0.089408)
		(layer "In9.Cu")
		(net "FM_CPU1_FIVR_FAULT_LVT3_N")
	)
	(segment
		(start 377.662948 -64.23152)
		(end 377.662948 -64.61633)
		(width 0.089408)
		(layer "In9.Cu")
		(net "FM_CPU1_FIVR_FAULT_LVT3_N")
	)
	(segment
		(start 379.624844 -61.749178)
		(end 378.76226 -62.611762)
		(width 0.089408)
		(layer "In9.Cu")
		(net "FM_CPU1_FIVR_FAULT_LVT3_N")
	)
	(segment
		(start 376.099578 -69.068696)
		(end 375.843292 -69.068696)
		(width 0.089408)
		(layer "In9.Cu")
		(net "FM_CPU1_FIVR_FAULT_LVT3_N")
	)
	(segment
		(start 378.76226 -63.132208)
		(end 377.662948 -64.23152)
		(width 0.089408)
		(layer "In9.Cu")
		(net "FM_CPU1_FIVR_FAULT_LVT3_N")
	)
	(segment
		(start 375.843292 -69.068696)
		(end 375.571512 -69.340476)
		(width 0.089408)
		(layer "In9.Cu")
		(net "FM_CPU1_FIVR_FAULT_LVT3_N")
	)
	(segment
		(start 377.662948 -64.61633)
		(end 377.359926 -64.919352)
		(width 0.089408)
		(layer "In9.Cu")
		(net "FM_CPU1_FIVR_FAULT_LVT3_N")
	)
	(segment
		(start 381.571246 -45.637704)
		(end 380.357888 -46.851062)
		(width 0.089408)
		(layer "In9.Cu")
		(net "FM_CPU1_FIVR_FAULT_LVT3_N")
	)
	(segment
		(start 379.742954 -41.219882)
		(end 379.7427 -41.220136)
		(width 0.089408)
		(layer "In9.Cu")
		(net "FM_CPU1_FIVR_FAULT_LVT3_N")
	)
	(segment
		(start 378.76226 -62.611762)
		(end 378.76226 -63.132208)
		(width 0.089408)
		(layer "In9.Cu")
		(net "FM_CPU1_FIVR_FAULT_LVT3_N")
	)
	(segment
		(start 381.257302 -56.8325)
		(end 381.257302 -57.446926)
		(width 0.089408)
		(layer "In9.Cu")
		(net "FM_CPU1_FIVR_FAULT_LVT3_N")
	)
	(segment
		(start 379.314202 -40.778176)
		(end 379.742954 -41.206928)
		(width 0.089408)
		(layer "In9.Cu")
		(net "FM_CPU1_FIVR_FAULT_LVT3_N")
	)
	(segment
		(start 376.318272 -68.850002)
		(end 376.099578 -69.068696)
		(width 0.089408)
		(layer "In9.Cu")
		(net "FM_CPU1_FIVR_FAULT_LVT3_N")
	)
	(segment
		(start 380.357888 -46.851062)
		(end 380.357888 -51.027838)
		(width 0.089408)
		(layer "In9.Cu")
		(net "FM_CPU1_FIVR_FAULT_LVT3_N")
	)
	(segment
		(start 379.624844 -59.079384)
		(end 379.624844 -61.749178)
		(width 0.089408)
		(layer "In9.Cu")
		(net "FM_CPU1_FIVR_FAULT_LVT3_N")
	)
	(segment
		(start 381.257302 -57.446926)
		(end 379.624844 -59.079384)
		(width 0.089408)
		(layer "In9.Cu")
		(net "FM_CPU1_FIVR_FAULT_LVT3_N")
	)
	(segment
		(start 375.944892 -71.895208)
		(end 375.545096 -72.295004)
		(width 0.1016)
		(layer "F.Cu")
		(net "FM_CPU0_FIVR_FAULT_LVT3_N")
	)
	(via
		(at 380.363222 -41.167812)
		(size 0.508)
		(drill 0.254)
		(layers "F.Cu" "B.Cu")
		(net "FM_CPU0_FIVR_FAULT_LVT3_N")
	)
	(via
		(at 375.944892 -71.895208)
		(size 0.4572)
		(drill 0.2032)
		(layers "F.Cu" "B.Cu")
		(net "FM_CPU0_FIVR_FAULT_LVT3_N")
	)
	(via
		(at 399.495518 -43.15714)
		(size 0.508)
		(drill 0.254)
		(layers "F.Cu" "B.Cu")
		(net "FM_CPU0_FIVR_FAULT_LVT3_N")
	)
	(via
		(at 400.476466 -43.487086)
		(size 0.6604)
		(drill 0.3302)
		(layers "F.Cu" "B.Cu")
		(net "FM_CPU0_FIVR_FAULT_LVT3_N")
	)
	(segment
		(start 399.495518 -43.15714)
		(end 399.825464 -43.487086)
		(width 0.10795)
		(layer "B.Cu")
		(net "FM_CPU0_FIVR_FAULT_LVT3_N")
	)
	(segment
		(start 400.949414 -43.487086)
		(end 401.5105 -42.926)
		(width 0.10795)
		(layer "B.Cu")
		(net "FM_CPU0_FIVR_FAULT_LVT3_N")
	)
	(segment
		(start 400.476466 -43.487086)
		(end 400.949414 -43.487086)
		(width 0.10795)
		(layer "B.Cu")
		(net "FM_CPU0_FIVR_FAULT_LVT3_N")
	)
	(segment
		(start 399.825464 -43.487086)
		(end 400.476466 -43.487086)
		(width 0.10795)
		(layer "B.Cu")
		(net "FM_CPU0_FIVR_FAULT_LVT3_N")
	)
	(segment
		(start 392.208258 -41.672764)
		(end 393.81049 -41.672764)
		(width 0.089408)
		(layer "In4.Cu")
		(net "FM_CPU0_FIVR_FAULT_LVT3_N")
	)
	(segment
		(start 395.677136 -41.337992)
		(end 397.070072 -42.730928)
		(width 0.089408)
		(layer "In4.Cu")
		(net "FM_CPU0_FIVR_FAULT_LVT3_N")
	)
	(segment
		(start 385.576064 -37.894514)
		(end 386.387086 -38.705536)
		(width 0.089408)
		(layer "In4.Cu")
		(net "FM_CPU0_FIVR_FAULT_LVT3_N")
	)
	(segment
		(start 397.070072 -42.730928)
		(end 398.38122 -42.730928)
		(width 0.089408)
		(layer "In4.Cu")
		(net "FM_CPU0_FIVR_FAULT_LVT3_N")
	)
	(segment
		(start 390.409176 -39.873682)
		(end 392.208258 -41.672764)
		(width 0.089408)
		(layer "In4.Cu")
		(net "FM_CPU0_FIVR_FAULT_LVT3_N")
	)
	(segment
		(start 394.145262 -41.337992)
		(end 395.677136 -41.337992)
		(width 0.089408)
		(layer "In4.Cu")
		(net "FM_CPU0_FIVR_FAULT_LVT3_N")
	)
	(segment
		(start 380.397766 -41.133268)
		(end 380.847092 -41.133268)
		(width 0.089408)
		(layer "In4.Cu")
		(net "FM_CPU0_FIVR_FAULT_LVT3_N")
	)
	(segment
		(start 384.396234 -38.176708)
		(end 384.678428 -37.894514)
		(width 0.089408)
		(layer "In4.Cu")
		(net "FM_CPU0_FIVR_FAULT_LVT3_N")
	)
	(segment
		(start 386.387086 -38.705536)
		(end 389.459724 -38.705536)
		(width 0.089408)
		(layer "In4.Cu")
		(net "FM_CPU0_FIVR_FAULT_LVT3_N")
	)
	(segment
		(start 390.409176 -39.654988)
		(end 390.409176 -39.873682)
		(width 0.089408)
		(layer "In4.Cu")
		(net "FM_CPU0_FIVR_FAULT_LVT3_N")
	)
	(segment
		(start 398.7038 -43.053508)
		(end 399.391886 -43.053508)
		(width 0.089408)
		(layer "In4.Cu")
		(net "FM_CPU0_FIVR_FAULT_LVT3_N")
	)
	(segment
		(start 398.38122 -42.730928)
		(end 398.7038 -43.053508)
		(width 0.089408)
		(layer "In4.Cu")
		(net "FM_CPU0_FIVR_FAULT_LVT3_N")
	)
	(segment
		(start 399.391886 -43.053508)
		(end 399.495518 -43.15714)
		(width 0.089408)
		(layer "In4.Cu")
		(net "FM_CPU0_FIVR_FAULT_LVT3_N")
	)
	(segment
		(start 384.678428 -37.894514)
		(end 385.576064 -37.894514)
		(width 0.089408)
		(layer "In4.Cu")
		(net "FM_CPU0_FIVR_FAULT_LVT3_N")
	)
	(segment
		(start 389.459724 -38.705536)
		(end 390.409176 -39.654988)
		(width 0.089408)
		(layer "In4.Cu")
		(net "FM_CPU0_FIVR_FAULT_LVT3_N")
	)
	(segment
		(start 393.81049 -41.672764)
		(end 394.145262 -41.337992)
		(width 0.089408)
		(layer "In4.Cu")
		(net "FM_CPU0_FIVR_FAULT_LVT3_N")
	)
	(segment
		(start 380.847092 -41.133268)
		(end 383.803652 -38.176708)
		(width 0.089408)
		(layer "In4.Cu")
		(net "FM_CPU0_FIVR_FAULT_LVT3_N")
	)
	(segment
		(start 383.803652 -38.176708)
		(end 384.396234 -38.176708)
		(width 0.089408)
		(layer "In4.Cu")
		(net "FM_CPU0_FIVR_FAULT_LVT3_N")
	)
	(segment
		(start 380.363222 -41.167812)
		(end 380.397766 -41.133268)
		(width 0.089408)
		(layer "In4.Cu")
		(net "FM_CPU0_FIVR_FAULT_LVT3_N")
	)
	(segment
		(start 375.944892 -71.895208)
		(end 375.944892 -71.366888)
		(width 0.089408)
		(layer "In9.Cu")
		(net "FM_CPU0_FIVR_FAULT_LVT3_N")
	)
	(segment
		(start 380.4158 -41.22039)
		(end 380.363222 -41.167812)
		(width 0.089408)
		(layer "In9.Cu")
		(net "FM_CPU0_FIVR_FAULT_LVT3_N")
	)
	(segment
		(start 378.044964 -64.774826)
		(end 378.044964 -64.390016)
		(width 0.089408)
		(layer "In9.Cu")
		(net "FM_CPU0_FIVR_FAULT_LVT3_N")
	)
	(segment
		(start 378.49937 -68.321936)
		(end 378.243338 -68.321936)
		(width 0.089408)
		(layer "In9.Cu")
		(net "FM_CPU0_FIVR_FAULT_LVT3_N")
	)
	(segment
		(start 378.243338 -68.321936)
		(end 377.971304 -68.049902)
		(width 0.089408)
		(layer "In9.Cu")
		(net "FM_CPU0_FIVR_FAULT_LVT3_N")
	)
	(segment
		(start 381.639318 -56.674004)
		(end 381.47117 -56.505856)
		(width 0.089408)
		(layer "In9.Cu")
		(net "FM_CPU0_FIVR_FAULT_LVT3_N")
	)
	(segment
		(start 376.590052 -70.721728)
		(end 376.846338 -70.721728)
		(width 0.089408)
		(layer "In9.Cu")
		(net "FM_CPU0_FIVR_FAULT_LVT3_N")
	)
	(segment
		(start 377.971304 -68.049902)
		(end 377.971304 -67.667886)
		(width 0.089408)
		(layer "In9.Cu")
		(net "FM_CPU0_FIVR_FAULT_LVT3_N")
	)
	(segment
		(start 377.805442 -65.014348)
		(end 378.044964 -64.774826)
		(width 0.089408)
		(layer "In9.Cu")
		(net "FM_CPU0_FIVR_FAULT_LVT3_N")
	)
	(segment
		(start 381.639318 -58.914284)
		(end 381.639318 -56.674004)
		(width 0.089408)
		(layer "In9.Cu")
		(net "FM_CPU0_FIVR_FAULT_LVT3_N")
	)
	(segment
		(start 381.47117 -46.278292)
		(end 381.957326 -45.792136)
		(width 0.089408)
		(layer "In9.Cu")
		(net "FM_CPU0_FIVR_FAULT_LVT3_N")
	)
	(segment
		(start 378.718064 -68.850002)
		(end 378.718064 -68.54063)
		(width 0.089408)
		(layer "In9.Cu")
		(net "FM_CPU0_FIVR_FAULT_LVT3_N")
	)
	(segment
		(start 377.805442 -67.502024)
		(end 377.805442 -65.014348)
		(width 0.089408)
		(layer "In9.Cu")
		(net "FM_CPU0_FIVR_FAULT_LVT3_N")
	)
	(segment
		(start 381.957326 -43.667172)
		(end 380.4158 -42.125646)
		(width 0.089408)
		(layer "In9.Cu")
		(net "FM_CPU0_FIVR_FAULT_LVT3_N")
	)
	(segment
		(start 378.044964 -64.390016)
		(end 379.144276 -63.290704)
		(width 0.089408)
		(layer "In9.Cu")
		(net "FM_CPU0_FIVR_FAULT_LVT3_N")
	)
	(segment
		(start 377.971304 -67.667886)
		(end 377.805442 -67.502024)
		(width 0.089408)
		(layer "In9.Cu")
		(net "FM_CPU0_FIVR_FAULT_LVT3_N")
	)
	(segment
		(start 381.957326 -45.792136)
		(end 381.957326 -43.667172)
		(width 0.089408)
		(layer "In9.Cu")
		(net "FM_CPU0_FIVR_FAULT_LVT3_N")
	)
	(segment
		(start 375.944892 -71.366888)
		(end 376.590052 -70.721728)
		(width 0.089408)
		(layer "In9.Cu")
		(net "FM_CPU0_FIVR_FAULT_LVT3_N")
	)
	(segment
		(start 380.069344 -61.854842)
		(end 380.069344 -60.484258)
		(width 0.089408)
		(layer "In9.Cu")
		(net "FM_CPU0_FIVR_FAULT_LVT3_N")
	)
	(segment
		(start 379.144276 -62.77991)
		(end 380.069344 -61.854842)
		(width 0.089408)
		(layer "In9.Cu")
		(net "FM_CPU0_FIVR_FAULT_LVT3_N")
	)
	(segment
		(start 376.846338 -70.721728)
		(end 378.718064 -68.850002)
		(width 0.089408)
		(layer "In9.Cu")
		(net "FM_CPU0_FIVR_FAULT_LVT3_N")
	)
	(segment
		(start 380.4158 -42.125646)
		(end 380.4158 -41.22039)
		(width 0.089408)
		(layer "In9.Cu")
		(net "FM_CPU0_FIVR_FAULT_LVT3_N")
	)
	(segment
		(start 380.069344 -60.484258)
		(end 381.639318 -58.914284)
		(width 0.089408)
		(layer "In9.Cu")
		(net "FM_CPU0_FIVR_FAULT_LVT3_N")
	)
	(segment
		(start 379.144276 -63.290704)
		(end 379.144276 -62.77991)
		(width 0.089408)
		(layer "In9.Cu")
		(net "FM_CPU0_FIVR_FAULT_LVT3_N")
	)
	(segment
		(start 378.718064 -68.54063)
		(end 378.49937 -68.321936)
		(width 0.089408)
		(layer "In9.Cu")
		(net "FM_CPU0_FIVR_FAULT_LVT3_N")
	)
	(segment
		(start 381.47117 -56.505856)
		(end 381.47117 -46.278292)
		(width 0.089408)
		(layer "In9.Cu")
		(net "FM_CPU0_FIVR_FAULT_LVT3_N")
	)
	(segment
		(start 384.406394 -81.312766)
		(end 384.756406 -81.312766)
		(width 0.10795)
		(layer "F.Cu")
		(net "FM_BMC_READY_N")
	)
	(segment
		(start 419.890194 -40.93464)
		(end 419.890194 -40.934894)
		(width 0.10795)
		(layer "F.Cu")
		(net "FM_BMC_READY_N")
	)
	(segment
		(start 384.351022 -81.368138)
		(end 384.406394 -81.312766)
		(width 0.10795)
		(layer "F.Cu")
		(net "FM_BMC_READY_N")
	)
	(segment
		(start 384.312922 -81.368138)
		(end 384.351022 -81.368138)
		(width 0.10795)
		(layer "F.Cu")
		(net "FM_BMC_READY_N")
	)
	(segment
		(start 17.7038 -27.559)
		(end 17.7038 -26.006806)
		(width 0.10795)
		(layer "F.Cu")
		(net "FM_BMC_READY_N")
	)
	(segment
		(start 384.756406 -81.312766)
		(end 385.003802 -81.560162)
		(width 0.10795)
		(layer "F.Cu")
		(net "FM_BMC_READY_N")
	)
	(segment
		(start 17.7038 -26.006806)
		(end 20.839684 -22.870922)
		(width 0.10795)
		(layer "F.Cu")
		(net "FM_BMC_READY_N")
	)
	(segment
		(start 381.99314 -81.77022)
		(end 383.91084 -81.77022)
		(width 0.10795)
		(layer "F.Cu")
		(net "FM_BMC_READY_N")
	)
	(segment
		(start 381.21336 -81.24698)
		(end 381.4699 -81.24698)
		(width 0.10795)
		(layer "F.Cu")
		(net "FM_BMC_READY_N")
	)
	(segment
		(start 17.860518 -36.520882)
		(end 17.860518 -30.272482)
		(width 0.10795)
		(layer "F.Cu")
		(net "FM_BMC_READY_N")
	)
	(segment
		(start 18.1102 -27.9654)
		(end 17.7038 -27.559)
		(width 0.10795)
		(layer "F.Cu")
		(net "FM_BMC_READY_N")
	)
	(segment
		(start 383.91084 -81.77022)
		(end 384.312922 -81.368138)
		(width 0.10795)
		(layer "F.Cu")
		(net "FM_BMC_READY_N")
	)
	(segment
		(start 419.890194 -40.934894)
		(end 420.28999 -41.33469)
		(width 0.10795)
		(layer "F.Cu")
		(net "FM_BMC_READY_N")
	)
	(segment
		(start 385.003802 -81.560162)
		(end 385.003802 -81.989422)
		(width 0.10795)
		(layer "F.Cu")
		(net "FM_BMC_READY_N")
	)
	(segment
		(start 381.4699 -81.24698)
		(end 381.99314 -81.77022)
		(width 0.10795)
		(layer "F.Cu")
		(net "FM_BMC_READY_N")
	)
	(segment
		(start 14.1224 -37.719)
		(end 16.6624 -37.719)
		(width 0.10795)
		(layer "F.Cu")
		(net "FM_BMC_READY_N")
	)
	(segment
		(start 16.6624 -37.719)
		(end 17.860518 -36.520882)
		(width 0.10795)
		(layer "F.Cu")
		(net "FM_BMC_READY_N")
	)
	(segment
		(start 385.003802 -81.989422)
		(end 385.29514 -82.28076)
		(width 0.10795)
		(layer "F.Cu")
		(net "FM_BMC_READY_N")
	)
	(segment
		(start 17.860518 -30.272482)
		(end 18.1102 -30.0228)
		(width 0.10795)
		(layer "F.Cu")
		(net "FM_BMC_READY_N")
	)
	(segment
		(start 18.1102 -30.0228)
		(end 18.1102 -27.9654)
		(width 0.10795)
		(layer "F.Cu")
		(net "FM_BMC_READY_N")
	)
	(via
		(at 381.75438 -89.05494)
		(size 0.508)
		(drill 0.254)
		(layers "F.Cu" "B.Cu")
		(net "FM_BMC_READY_N")
	)
	(via
		(at 20.839684 -22.870922)
		(size 0.508)
		(drill 0.254)
		(layers "F.Cu" "B.Cu")
		(net "FM_BMC_READY_N")
	)
	(via
		(at 354.78212 -30.24632)
		(size 0.508)
		(drill 0.254)
		(layers "F.Cu" "B.Cu")
		(net "FM_BMC_READY_N")
	)
	(via
		(at 390.144 -34.29)
		(size 0.6604)
		(drill 0.3302)
		(layers "F.Cu" "B.Cu")
		(net "FM_BMC_READY_N")
	)
	(via
		(at 391.51306 -34.670492)
		(size 0.508)
		(drill 0.254)
		(layers "F.Cu" "B.Cu")
		(net "FM_BMC_READY_N")
	)
	(via
		(at 420.28999 -41.33469)
		(size 0.4572)
		(drill 0.2032)
		(layers "F.Cu" "B.Cu")
		(net "FM_BMC_READY_N")
	)
	(via
		(at 181.050184 4.066794)
		(size 0.508)
		(drill 0.254)
		(layers "F.Cu" "B.Cu")
		(net "FM_BMC_READY_N")
	)
	(via
		(at 330.039726 3.98272)
		(size 0.508)
		(drill 0.254)
		(layers "F.Cu" "B.Cu")
		(net "FM_BMC_READY_N")
	)
	(via
		(at 381.21336 -81.24698)
		(size 0.508)
		(drill 0.254)
		(layers "F.Cu" "B.Cu")
		(net "FM_BMC_READY_N")
	)
	(segment
		(start 356.11181 -30.699202)
		(end 355.841808 -30.4292)
		(width 0.10795)
		(layer "B.Cu")
		(net "FM_BMC_READY_N")
	)
	(segment
		(start 362.69803 -30.699202)
		(end 356.11181 -30.699202)
		(width 0.10795)
		(layer "B.Cu")
		(net "FM_BMC_READY_N")
	)
	(segment
		(start 371.283992 -29.033216)
		(end 364.364016 -29.033216)
		(width 0.10795)
		(layer "B.Cu")
		(net "FM_BMC_READY_N")
	)
	(segment
		(start 385.52755 -32.849312)
		(end 385.312666 -33.064196)
		(width 0.10795)
		(layer "B.Cu")
		(net "FM_BMC_READY_N")
	)
	(segment
		(start 382.27 -88.2015)
		(end 382.27 -88.53932)
		(width 0.10795)
		(layer "B.Cu")
		(net "FM_BMC_READY_N")
	)
	(segment
		(start 374.041924 -26.932128)
		(end 374.04167 -26.931874)
		(width 0.10795)
		(layer "B.Cu")
		(net "FM_BMC_READY_N")
	)
	(segment
		(start 391.51306 -34.670492)
		(end 390.524492 -34.670492)
		(width 0.10795)
		(layer "B.Cu")
		(net "FM_BMC_READY_N")
	)
	(segment
		(start 381.75438 -89.05494)
		(end 381.71374 -89.09558)
		(width 0.10795)
		(layer "B.Cu")
		(net "FM_BMC_READY_N")
	)
	(segment
		(start 386.294884 -33.225232)
		(end 385.918964 -32.849312)
		(width 0.10795)
		(layer "B.Cu")
		(net "FM_BMC_READY_N")
	)
	(segment
		(start 354.965 -30.4292)
		(end 354.78212 -30.24632)
		(width 0.10795)
		(layer "B.Cu")
		(net "FM_BMC_READY_N")
	)
	(segment
		(start 390.524492 -34.670492)
		(end 390.144 -34.29)
		(width 0.10795)
		(layer "B.Cu")
		(net "FM_BMC_READY_N")
	)
	(segment
		(start 381.71374 -90.105738)
		(end 381.7112 -90.108278)
		(width 0.10795)
		(layer "B.Cu")
		(net "FM_BMC_READY_N")
	)
	(segment
		(start 379.519942 -32.912304)
		(end 378.13234 -31.524702)
		(width 0.10795)
		(layer "B.Cu")
		(net "FM_BMC_READY_N")
	)
	(segment
		(start 373.478044 -26.932128)
		(end 373.38508 -26.932128)
		(width 0.10795)
		(layer "B.Cu")
		(net "FM_BMC_READY_N")
	)
	(segment
		(start 385.918964 -32.849312)
		(end 385.52755 -32.849312)
		(width 0.10795)
		(layer "B.Cu")
		(net "FM_BMC_READY_N")
	)
	(segment
		(start 389.079232 -33.225232)
		(end 386.294884 -33.225232)
		(width 0.10795)
		(layer "B.Cu")
		(net "FM_BMC_READY_N")
	)
	(segment
		(start 378.13234 -31.524702)
		(end 378.13234 -29.111956)
		(width 0.10795)
		(layer "B.Cu")
		(net "FM_BMC_READY_N")
	)
	(segment
		(start 373.478298 -26.931874)
		(end 373.478044 -26.932128)
		(width 0.10795)
		(layer "B.Cu")
		(net "FM_BMC_READY_N")
	)
	(segment
		(start 364.364016 -29.033216)
		(end 362.69803 -30.699202)
		(width 0.10795)
		(layer "B.Cu")
		(net "FM_BMC_READY_N")
	)
	(segment
		(start 390.144 -34.29)
		(end 389.079232 -33.225232)
		(width 0.10795)
		(layer "B.Cu")
		(net "FM_BMC_READY_N")
	)
	(segment
		(start 382.27 -88.53932)
		(end 381.75438 -89.05494)
		(width 0.10795)
		(layer "B.Cu")
		(net "FM_BMC_READY_N")
	)
	(segment
		(start 355.841808 -30.4292)
		(end 354.965 -30.4292)
		(width 0.10795)
		(layer "B.Cu")
		(net "FM_BMC_READY_N")
	)
	(segment
		(start 381.600964 -32.912304)
		(end 379.519942 -32.912304)
		(width 0.10795)
		(layer "B.Cu")
		(net "FM_BMC_READY_N")
	)
	(segment
		(start 378.13234 -29.111956)
		(end 375.952512 -26.932128)
		(width 0.10795)
		(layer "B.Cu")
		(net "FM_BMC_READY_N")
	)
	(segment
		(start 385.312666 -33.064196)
		(end 381.752856 -33.064196)
		(width 0.10795)
		(layer "B.Cu")
		(net "FM_BMC_READY_N")
	)
	(segment
		(start 375.952512 -26.932128)
		(end 374.041924 -26.932128)
		(width 0.10795)
		(layer "B.Cu")
		(net "FM_BMC_READY_N")
	)
	(segment
		(start 374.04167 -26.931874)
		(end 373.478298 -26.931874)
		(width 0.10795)
		(layer "B.Cu")
		(net "FM_BMC_READY_N")
	)
	(segment
		(start 381.7112 -90.108278)
		(end 381.7112 -90.53068)
		(width 0.10795)
		(layer "B.Cu")
		(net "FM_BMC_READY_N")
	)
	(segment
		(start 381.752856 -33.064196)
		(end 381.600964 -32.912304)
		(width 0.10795)
		(layer "B.Cu")
		(net "FM_BMC_READY_N")
	)
	(segment
		(start 381.71374 -89.09558)
		(end 381.71374 -90.105738)
		(width 0.10795)
		(layer "B.Cu")
		(net "FM_BMC_READY_N")
	)
	(segment
		(start 373.38508 -26.932128)
		(end 371.283992 -29.033216)
		(width 0.10795)
		(layer "B.Cu")
		(net "FM_BMC_READY_N")
	)
	(segment
		(start 265.61669 5.079492)
		(end 266.903454 3.792728)
		(width 0.089408)
		(layer "In2.Cu")
		(net "FM_BMC_READY_N")
	)
	(segment
		(start 181.050184 4.066794)
		(end 181.294024 4.066794)
		(width 0.089408)
		(layer "In2.Cu")
		(net "FM_BMC_READY_N")
	)
	(segment
		(start 330.039726 4.029964)
		(end 330.039726 3.98272)
		(width 0.089408)
		(layer "In2.Cu")
		(net "FM_BMC_READY_N")
	)
	(segment
		(start 329.108816 5.104384)
		(end 329.372976 4.840224)
		(width 0.089408)
		(layer "In2.Cu")
		(net "FM_BMC_READY_N")
	)
	(segment
		(start 321.945 3.792728)
		(end 323.256656 5.104384)
		(width 0.089408)
		(layer "In2.Cu")
		(net "FM_BMC_READY_N")
	)
	(segment
		(start 329.372976 4.840224)
		(end 329.372976 4.696714)
		(width 0.089408)
		(layer "In2.Cu")
		(net "FM_BMC_READY_N")
	)
	(segment
		(start 266.903454 3.792728)
		(end 321.945 3.792728)
		(width 0.089408)
		(layer "In2.Cu")
		(net "FM_BMC_READY_N")
	)
	(segment
		(start 323.256656 5.104384)
		(end 329.108816 5.104384)
		(width 0.089408)
		(layer "In2.Cu")
		(net "FM_BMC_READY_N")
	)
	(segment
		(start 329.372976 4.696714)
		(end 330.039726 4.029964)
		(width 0.089408)
		(layer "In2.Cu")
		(net "FM_BMC_READY_N")
	)
	(segment
		(start 182.306722 5.079492)
		(end 265.61669 5.079492)
		(width 0.089408)
		(layer "In2.Cu")
		(net "FM_BMC_READY_N")
	)
	(segment
		(start 181.294024 4.066794)
		(end 182.306722 5.079492)
		(width 0.089408)
		(layer "In2.Cu")
		(net "FM_BMC_READY_N")
	)
	(segment
		(start 167.82796 -0.971042)
		(end 166.17315 0.683768)
		(width 0.089408)
		(layer "In4.Cu")
		(net "FM_BMC_READY_N")
	)
	(segment
		(start 179.096162 -1.657604)
		(end 179.022248 -1.657604)
		(width 0.089408)
		(layer "In4.Cu")
		(net "FM_BMC_READY_N")
	)
	(segment
		(start 393.984988 -36.113466)
		(end 394.264388 -36.392866)
		(width 0.089408)
		(layer "In4.Cu")
		(net "FM_BMC_READY_N")
	)
	(segment
		(start 420.28999 -41.176194)
		(end 420.28999 -41.33469)
		(width 0.089408)
		(layer "In4.Cu")
		(net "FM_BMC_READY_N")
	)
	(segment
		(start 180.960014 1.594358)
		(end 179.553108 0.187452)
		(width 0.089408)
		(layer "In4.Cu")
		(net "FM_BMC_READY_N")
	)
	(segment
		(start 22.992588 -0.665734)
		(end 22.3266 -1.331722)
		(width 0.089408)
		(layer "In4.Cu")
		(net "FM_BMC_READY_N")
	)
	(segment
		(start 179.421028 -0.300228)
		(end 179.421028 -1.332738)
		(width 0.089408)
		(layer "In4.Cu")
		(net "FM_BMC_READY_N")
	)
	(segment
		(start 419.70071 -39.34714)
		(end 419.87978 -39.52621)
		(width 0.089408)
		(layer "In4.Cu")
		(net "FM_BMC_READY_N")
	)
	(segment
		(start 406.950926 -37.709348)
		(end 408.425142 -37.709348)
		(width 0.089408)
		(layer "In4.Cu")
		(net "FM_BMC_READY_N")
	)
	(segment
		(start 411.064964 -37.17925)
		(end 411.064964 -37.490146)
		(width 0.089408)
		(layer "In4.Cu")
		(net "FM_BMC_READY_N")
	)
	(segment
		(start 22.3266 -1.331722)
		(end 22.3266 -21.384006)
		(width 0.089408)
		(layer "In4.Cu")
		(net "FM_BMC_READY_N")
	)
	(segment
		(start 181.050184 4.066794)
		(end 181.049422 4.066794)
		(width 0.089408)
		(layer "In4.Cu")
		(net "FM_BMC_READY_N")
	)
	(segment
		(start 173.3804 -2.820416)
		(end 172.616368 -2.056892)
		(width 0.089408)
		(layer "In4.Cu")
		(net "FM_BMC_READY_N")
	)
	(segment
		(start 164.954204 5.078984)
		(end 116.746528 5.078984)
		(width 0.089408)
		(layer "In4.Cu")
		(net "FM_BMC_READY_N")
	)
	(segment
		(start 179.421028 -1.332738)
		(end 179.096162 -1.657604)
		(width 0.089408)
		(layer "In4.Cu")
		(net "FM_BMC_READY_N")
	)
	(segment
		(start 103.299514 4.41071)
		(end 102.743 4.967224)
		(width 0.089408)
		(layer "In4.Cu")
		(net "FM_BMC_READY_N")
	)
	(segment
		(start 179.553108 0.187452)
		(end 179.553108 -0.168148)
		(width 0.089408)
		(layer "In4.Cu")
		(net "FM_BMC_READY_N")
	)
	(segment
		(start 393.984988 -36.108386)
		(end 393.984988 -36.113466)
		(width 0.089408)
		(layer "In4.Cu")
		(net "FM_BMC_READY_N")
	)
	(segment
		(start 397.909288 -35.881056)
		(end 399.47469 -35.881056)
		(width 0.089408)
		(layer "In4.Cu")
		(net "FM_BMC_READY_N")
	)
	(segment
		(start 102.743 4.967224)
		(end 28.589224 4.967224)
		(width 0.089408)
		(layer "In4.Cu")
		(net "FM_BMC_READY_N")
	)
	(segment
		(start 116.746528 5.078984)
		(end 116.078254 4.41071)
		(width 0.089408)
		(layer "In4.Cu")
		(net "FM_BMC_READY_N")
	)
	(segment
		(start 392.547094 -34.670492)
		(end 393.984988 -36.108386)
		(width 0.089408)
		(layer "In4.Cu")
		(net "FM_BMC_READY_N")
	)
	(segment
		(start 180.960014 3.977386)
		(end 180.960014 1.594358)
		(width 0.089408)
		(layer "In4.Cu")
		(net "FM_BMC_READY_N")
	)
	(segment
		(start 168.563036 -2.056892)
		(end 167.82796 -1.321816)
		(width 0.089408)
		(layer "In4.Cu")
		(net "FM_BMC_READY_N")
	)
	(segment
		(start 410.845762 -36.960048)
		(end 411.064964 -37.17925)
		(width 0.089408)
		(layer "In4.Cu")
		(net "FM_BMC_READY_N")
	)
	(segment
		(start 394.264388 -36.392866)
		(end 394.269468 -36.392866)
		(width 0.089408)
		(layer "In4.Cu")
		(net "FM_BMC_READY_N")
	)
	(segment
		(start 411.91815 -39.175944)
		(end 412.246826 -39.50462)
		(width 0.089408)
		(layer "In4.Cu")
		(net "FM_BMC_READY_N")
	)
	(segment
		(start 166.17315 3.860038)
		(end 164.954204 5.078984)
		(width 0.089408)
		(layer "In4.Cu")
		(net "FM_BMC_READY_N")
	)
	(segment
		(start 400.588734 -34.767012)
		(end 401.34159 -34.767012)
		(width 0.089408)
		(layer "In4.Cu")
		(net "FM_BMC_READY_N")
	)
	(segment
		(start 411.91815 -38.033452)
		(end 411.91815 -39.175944)
		(width 0.089408)
		(layer "In4.Cu")
		(net "FM_BMC_READY_N")
	)
	(segment
		(start 399.47469 -35.881056)
		(end 400.588734 -34.767012)
		(width 0.089408)
		(layer "In4.Cu")
		(net "FM_BMC_READY_N")
	)
	(segment
		(start 167.82796 -1.321816)
		(end 167.82796 -0.971042)
		(width 0.089408)
		(layer "In4.Cu")
		(net "FM_BMC_READY_N")
	)
	(segment
		(start 417.0807 -39.50462)
		(end 417.23818 -39.34714)
		(width 0.089408)
		(layer "In4.Cu")
		(net "FM_BMC_READY_N")
	)
	(segment
		(start 404.676864 -37.12591)
		(end 406.367488 -37.12591)
		(width 0.089408)
		(layer "In4.Cu")
		(net "FM_BMC_READY_N")
	)
	(segment
		(start 401.34159 -34.767012)
		(end 402.33219 -35.757612)
		(width 0.089408)
		(layer "In4.Cu")
		(net "FM_BMC_READY_N")
	)
	(segment
		(start 394.269468 -36.392866)
		(end 394.837412 -36.96081)
		(width 0.089408)
		(layer "In4.Cu")
		(net "FM_BMC_READY_N")
	)
	(segment
		(start 166.17315 0.683768)
		(end 166.17315 3.860038)
		(width 0.089408)
		(layer "In4.Cu")
		(net "FM_BMC_READY_N")
	)
	(segment
		(start 178.664108 -2.309114)
		(end 178.664108 -2.327148)
		(width 0.089408)
		(layer "In4.Cu")
		(net "FM_BMC_READY_N")
	)
	(segment
		(start 178.670712 -2.30251)
		(end 178.664108 -2.309114)
		(width 0.089408)
		(layer "In4.Cu")
		(net "FM_BMC_READY_N")
	)
	(segment
		(start 406.367488 -37.12591)
		(end 406.950926 -37.709348)
		(width 0.089408)
		(layer "In4.Cu")
		(net "FM_BMC_READY_N")
	)
	(segment
		(start 408.673046 -37.221668)
		(end 408.934666 -36.960048)
		(width 0.089408)
		(layer "In4.Cu")
		(net "FM_BMC_READY_N")
	)
	(segment
		(start 22.3266 -21.384006)
		(end 20.839684 -22.870922)
		(width 0.089408)
		(layer "In4.Cu")
		(net "FM_BMC_READY_N")
	)
	(segment
		(start 178.17084 -2.820416)
		(end 173.3804 -2.820416)
		(width 0.089408)
		(layer "In4.Cu")
		(net "FM_BMC_READY_N")
	)
	(segment
		(start 178.664108 -2.327148)
		(end 178.17084 -2.820416)
		(width 0.089408)
		(layer "In4.Cu")
		(net "FM_BMC_READY_N")
	)
	(segment
		(start 26.998422 0.272542)
		(end 26.060146 -0.665734)
		(width 0.089408)
		(layer "In4.Cu")
		(net "FM_BMC_READY_N")
	)
	(segment
		(start 26.060146 -0.665734)
		(end 22.992588 -0.665734)
		(width 0.089408)
		(layer "In4.Cu")
		(net "FM_BMC_READY_N")
	)
	(segment
		(start 412.246826 -39.50462)
		(end 417.0807 -39.50462)
		(width 0.089408)
		(layer "In4.Cu")
		(net "FM_BMC_READY_N")
	)
	(segment
		(start 404.150322 -36.599368)
		(end 404.676864 -37.12591)
		(width 0.089408)
		(layer "In4.Cu")
		(net "FM_BMC_READY_N")
	)
	(segment
		(start 394.837412 -36.96081)
		(end 396.829534 -36.96081)
		(width 0.089408)
		(layer "In4.Cu")
		(net "FM_BMC_READY_N")
	)
	(segment
		(start 179.022248 -1.657604)
		(end 178.670712 -2.00914)
		(width 0.089408)
		(layer "In4.Cu")
		(net "FM_BMC_READY_N")
	)
	(segment
		(start 402.33219 -35.757612)
		(end 403.308566 -35.757612)
		(width 0.089408)
		(layer "In4.Cu")
		(net "FM_BMC_READY_N")
	)
	(segment
		(start 408.673046 -37.461444)
		(end 408.673046 -37.221668)
		(width 0.089408)
		(layer "In4.Cu")
		(net "FM_BMC_READY_N")
	)
	(segment
		(start 391.51306 -34.670492)
		(end 392.547094 -34.670492)
		(width 0.089408)
		(layer "In4.Cu")
		(net "FM_BMC_READY_N")
	)
	(segment
		(start 408.425142 -37.709348)
		(end 408.673046 -37.461444)
		(width 0.089408)
		(layer "In4.Cu")
		(net "FM_BMC_READY_N")
	)
	(segment
		(start 408.934666 -36.960048)
		(end 410.845762 -36.960048)
		(width 0.089408)
		(layer "In4.Cu")
		(net "FM_BMC_READY_N")
	)
	(segment
		(start 116.078254 4.41071)
		(end 103.299514 4.41071)
		(width 0.089408)
		(layer "In4.Cu")
		(net "FM_BMC_READY_N")
	)
	(segment
		(start 172.616368 -2.056892)
		(end 168.563036 -2.056892)
		(width 0.089408)
		(layer "In4.Cu")
		(net "FM_BMC_READY_N")
	)
	(segment
		(start 403.880574 -36.32962)
		(end 404.150322 -36.599368)
		(width 0.0889)
		(layer "In4.Cu")
		(net "FM_BMC_READY_N")
	)
	(segment
		(start 181.049422 4.066794)
		(end 180.960014 3.977386)
		(width 0.089408)
		(layer "In4.Cu")
		(net "FM_BMC_READY_N")
	)
	(segment
		(start 26.998422 3.376422)
		(end 26.998422 0.272542)
		(width 0.089408)
		(layer "In4.Cu")
		(net "FM_BMC_READY_N")
	)
	(segment
		(start 179.553108 -0.168148)
		(end 179.421028 -0.300228)
		(width 0.089408)
		(layer "In4.Cu")
		(net "FM_BMC_READY_N")
	)
	(segment
		(start 396.829534 -36.96081)
		(end 397.909288 -35.881056)
		(width 0.089408)
		(layer "In4.Cu")
		(net "FM_BMC_READY_N")
	)
	(segment
		(start 411.064964 -37.490146)
		(end 411.284166 -37.709348)
		(width 0.089408)
		(layer "In4.Cu")
		(net "FM_BMC_READY_N")
	)
	(segment
		(start 28.589224 4.967224)
		(end 26.998422 3.376422)
		(width 0.089408)
		(layer "In4.Cu")
		(net "FM_BMC_READY_N")
	)
	(segment
		(start 411.284166 -37.709348)
		(end 411.594046 -37.709348)
		(width 0.089408)
		(layer "In4.Cu")
		(net "FM_BMC_READY_N")
	)
	(segment
		(start 178.670712 -2.00914)
		(end 178.670712 -2.30251)
		(width 0.089408)
		(layer "In4.Cu")
		(net "FM_BMC_READY_N")
	)
	(segment
		(start 419.87978 -40.765984)
		(end 420.28999 -41.176194)
		(width 0.089408)
		(layer "In4.Cu")
		(net "FM_BMC_READY_N")
	)
	(segment
		(start 403.308566 -35.757612)
		(end 403.880574 -36.32962)
		(width 0.089408)
		(layer "In4.Cu")
		(net "FM_BMC_READY_N")
	)
	(segment
		(start 417.23818 -39.34714)
		(end 419.70071 -39.34714)
		(width 0.089408)
		(layer "In4.Cu")
		(net "FM_BMC_READY_N")
	)
	(segment
		(start 411.594046 -37.709348)
		(end 411.91815 -38.033452)
		(width 0.089408)
		(layer "In4.Cu")
		(net "FM_BMC_READY_N")
	)
	(segment
		(start 419.87978 -39.52621)
		(end 419.87978 -40.765984)
		(width 0.089408)
		(layer "In4.Cu")
		(net "FM_BMC_READY_N")
	)
	(segment
		(start 391.356088 -46.010322)
		(end 391.88644 -45.47997)
		(width 0.089408)
		(layer "In9.Cu")
		(net "FM_BMC_READY_N")
	)
	(segment
		(start 390.029192 -72.038972)
		(end 390.0297 -72.038464)
		(width 0.089408)
		(layer "In9.Cu")
		(net "FM_BMC_READY_N")
	)
	(segment
		(start 393.128754 -41.455848)
		(end 393.128754 -40.730932)
		(width 0.089408)
		(layer "In9.Cu")
		(net "FM_BMC_READY_N")
	)
	(segment
		(start 392.741404 -37.449252)
		(end 391.0076 -35.715448)
		(width 0.089408)
		(layer "In9.Cu")
		(net "FM_BMC_READY_N")
	)
	(segment
		(start 392.529314 -60.408312)
		(end 393.034012 -59.903614)
		(width 0.089408)
		(layer "In9.Cu")
		(net "FM_BMC_READY_N")
	)
	(segment
		(start 390.0297 -71.85152)
		(end 390.482328 -71.398892)
		(width 0.089408)
		(layer "In9.Cu")
		(net "FM_BMC_READY_N")
	)
	(segment
		(start 393.034012 -59.903614)
		(end 393.034012 -54.061868)
		(width 0.089408)
		(layer "In9.Cu")
		(net "FM_BMC_READY_N")
	)
	(segment
		(start 381.957326 -89.05494)
		(end 385.995418 -85.016848)
		(width 0.089408)
		(layer "In9.Cu")
		(net "FM_BMC_READY_N")
	)
	(segment
		(start 391.0076 -35.715448)
		(end 391.0076 -35.175952)
		(width 0.089408)
		(layer "In9.Cu")
		(net "FM_BMC_READY_N")
	)
	(segment
		(start 389.694674 -68.386452)
		(end 389.694674 -66.924936)
		(width 0.089408)
		(layer "In9.Cu")
		(net "FM_BMC_READY_N")
	)
	(segment
		(start 386.739638 -78.135734)
		(end 386.739384 -78.13548)
		(width 0.089408)
		(layer "In9.Cu")
		(net "FM_BMC_READY_N")
	)
	(segment
		(start 388.95528 -74.537062)
		(end 390.0297 -73.462642)
		(width 0.089408)
		(layer "In9.Cu")
		(net "FM_BMC_READY_N")
	)
	(segment
		(start 386.739638 -79.371952)
		(end 386.739638 -78.135734)
		(width 0.089408)
		(layer "In9.Cu")
		(net "FM_BMC_READY_N")
	)
	(segment
		(start 387.670802 -82.94243)
		(end 387.670802 -80.461612)
		(width 0.089408)
		(layer "In9.Cu")
		(net "FM_BMC_READY_N")
	)
	(segment
		(start 390.0297 -72.513952)
		(end 390.029446 -72.513698)
		(width 0.089408)
		(layer "In9.Cu")
		(net "FM_BMC_READY_N")
	)
	(segment
		(start 386.739384 -77.977492)
		(end 388.95528 -75.761596)
		(width 0.089408)
		(layer "In9.Cu")
		(net "FM_BMC_READY_N")
	)
	(segment
		(start 391.88644 -44.99483)
		(end 391.886186 -44.994576)
		(width 0.089408)
		(layer "In9.Cu")
		(net "FM_BMC_READY_N")
	)
	(segment
		(start 392.136884 -61.645038)
		(end 392.529314 -61.252608)
		(width 0.089408)
		(layer "In9.Cu")
		(net "FM_BMC_READY_N")
	)
	(segment
		(start 390.0297 -72.038464)
		(end 390.0297 -71.85152)
		(width 0.089408)
		(layer "In9.Cu")
		(net "FM_BMC_READY_N")
	)
	(segment
		(start 392.136884 -64.482726)
		(end 392.136884 -61.645038)
		(width 0.089408)
		(layer "In9.Cu")
		(net "FM_BMC_READY_N")
	)
	(segment
		(start 392.741404 -40.343582)
		(end 392.741404 -37.449252)
		(width 0.089408)
		(layer "In9.Cu")
		(net "FM_BMC_READY_N")
	)
	(segment
		(start 389.694674 -66.924936)
		(end 392.136884 -64.482726)
		(width 0.089408)
		(layer "In9.Cu")
		(net "FM_BMC_READY_N")
	)
	(segment
		(start 388.394702 -83.66633)
		(end 387.670802 -82.94243)
		(width 0.089408)
		(layer "In9.Cu")
		(net "FM_BMC_READY_N")
	)
	(segment
		(start 386.739384 -78.13548)
		(end 386.739384 -77.977492)
		(width 0.089408)
		(layer "In9.Cu")
		(net "FM_BMC_READY_N")
	)
	(segment
		(start 392.295634 -52.448968)
		(end 391.600944 -51.754278)
		(width 0.089408)
		(layer "In9.Cu")
		(net "FM_BMC_READY_N")
	)
	(segment
		(start 388.394702 -83.998054)
		(end 388.394702 -83.66633)
		(width 0.089408)
		(layer "In9.Cu")
		(net "FM_BMC_READY_N")
	)
	(segment
		(start 386.739384 -79.372206)
		(end 386.739638 -79.371952)
		(width 0.089408)
		(layer "In9.Cu")
		(net "FM_BMC_READY_N")
	)
	(segment
		(start 391.886186 -42.698416)
		(end 393.128754 -41.455848)
		(width 0.089408)
		(layer "In9.Cu")
		(net "FM_BMC_READY_N")
	)
	(segment
		(start 392.295634 -53.32349)
		(end 392.295634 -52.448968)
		(width 0.089408)
		(layer "In9.Cu")
		(net "FM_BMC_READY_N")
	)
	(segment
		(start 385.995418 -85.016848)
		(end 387.375908 -85.016848)
		(width 0.089408)
		(layer "In9.Cu")
		(net "FM_BMC_READY_N")
	)
	(segment
		(start 392.529314 -61.252608)
		(end 392.529314 -60.408312)
		(width 0.089408)
		(layer "In9.Cu")
		(net "FM_BMC_READY_N")
	)
	(segment
		(start 386.739384 -79.530194)
		(end 386.739384 -79.372206)
		(width 0.089408)
		(layer "In9.Cu")
		(net "FM_BMC_READY_N")
	)
	(segment
		(start 390.029446 -72.35571)
		(end 390.029192 -72.355456)
		(width 0.089408)
		(layer "In9.Cu")
		(net "FM_BMC_READY_N")
	)
	(segment
		(start 388.95528 -75.761596)
		(end 388.95528 -74.537062)
		(width 0.089408)
		(layer "In9.Cu")
		(net "FM_BMC_READY_N")
	)
	(segment
		(start 390.0297 -73.462642)
		(end 390.0297 -72.513952)
		(width 0.089408)
		(layer "In9.Cu")
		(net "FM_BMC_READY_N")
	)
	(segment
		(start 387.375908 -85.016848)
		(end 388.394702 -83.998054)
		(width 0.089408)
		(layer "In9.Cu")
		(net "FM_BMC_READY_N")
	)
	(segment
		(start 391.356088 -47.013622)
		(end 391.356088 -46.010322)
		(width 0.089408)
		(layer "In9.Cu")
		(net "FM_BMC_READY_N")
	)
	(segment
		(start 391.600944 -51.754278)
		(end 391.600944 -47.258478)
		(width 0.089408)
		(layer "In9.Cu")
		(net "FM_BMC_READY_N")
	)
	(segment
		(start 390.482328 -71.398892)
		(end 390.482328 -69.174106)
		(width 0.089408)
		(layer "In9.Cu")
		(net "FM_BMC_READY_N")
	)
	(segment
		(start 391.88644 -45.47997)
		(end 391.88644 -44.99483)
		(width 0.089408)
		(layer "In9.Cu")
		(net "FM_BMC_READY_N")
	)
	(segment
		(start 390.029192 -72.355456)
		(end 390.029192 -72.038972)
		(width 0.089408)
		(layer "In9.Cu")
		(net "FM_BMC_READY_N")
	)
	(segment
		(start 391.600944 -47.258478)
		(end 391.356088 -47.013622)
		(width 0.089408)
		(layer "In9.Cu")
		(net "FM_BMC_READY_N")
	)
	(segment
		(start 393.034012 -54.061868)
		(end 392.295634 -53.32349)
		(width 0.089408)
		(layer "In9.Cu")
		(net "FM_BMC_READY_N")
	)
	(segment
		(start 381.75438 -89.05494)
		(end 381.957326 -89.05494)
		(width 0.089408)
		(layer "In9.Cu")
		(net "FM_BMC_READY_N")
	)
	(segment
		(start 387.670802 -80.461612)
		(end 386.739384 -79.530194)
		(width 0.089408)
		(layer "In9.Cu")
		(net "FM_BMC_READY_N")
	)
	(segment
		(start 390.482328 -69.174106)
		(end 389.694674 -68.386452)
		(width 0.089408)
		(layer "In9.Cu")
		(net "FM_BMC_READY_N")
	)
	(segment
		(start 391.0076 -35.175952)
		(end 391.51306 -34.670492)
		(width 0.089408)
		(layer "In9.Cu")
		(net "FM_BMC_READY_N")
	)
	(segment
		(start 391.886186 -44.994576)
		(end 391.886186 -42.698416)
		(width 0.089408)
		(layer "In9.Cu")
		(net "FM_BMC_READY_N")
	)
	(segment
		(start 390.029446 -72.513698)
		(end 390.029446 -72.35571)
		(width 0.089408)
		(layer "In9.Cu")
		(net "FM_BMC_READY_N")
	)
	(segment
		(start 393.128754 -40.730932)
		(end 392.741404 -40.343582)
		(width 0.089408)
		(layer "In9.Cu")
		(net "FM_BMC_READY_N")
	)
	(segment
		(start 331.862938 4.794504)
		(end 337.241896 4.794504)
		(width 0.089408)
		(layer "In11.Cu")
		(net "FM_BMC_READY_N")
	)
	(segment
		(start 383.51714 -85.72754)
		(end 383.0701 -86.17458)
		(width 0.089408)
		(layer "In11.Cu")
		(net "FM_BMC_READY_N")
	)
	(segment
		(start 331.501496 4.293108)
		(end 331.501496 4.433062)
		(width 0.089408)
		(layer "In11.Cu")
		(net "FM_BMC_READY_N")
	)
	(segment
		(start 338.074 -10.390632)
		(end 340.397592 -12.714224)
		(width 0.089408)
		(layer "In11.Cu")
		(net "FM_BMC_READY_N")
	)
	(segment
		(start 350.264222 -21.637752)
		(end 352.52787 -23.9014)
		(width 0.089408)
		(layer "In11.Cu")
		(net "FM_BMC_READY_N")
	)
	(segment
		(start 349.512128 -18.508472)
		(end 348.9198 -19.1008)
		(width 0.089408)
		(layer "In11.Cu")
		(net "FM_BMC_READY_N")
	)
	(segment
		(start 381.13208 -81.32826)
		(end 381.13208 -83.96224)
		(width 0.089408)
		(layer "In11.Cu")
		(net "FM_BMC_READY_N")
	)
	(segment
		(start 383.0701 -86.17458)
		(end 383.0701 -87.73922)
		(width 0.089408)
		(layer "In11.Cu")
		(net "FM_BMC_READY_N")
	)
	(segment
		(start 383.26441 -84.65439)
		(end 383.51714 -84.90712)
		(width 0.089408)
		(layer "In11.Cu")
		(net "FM_BMC_READY_N")
	)
	(segment
		(start 348.9198 -19.1008)
		(end 348.9198 -21.370798)
		(width 0.089408)
		(layer "In11.Cu")
		(net "FM_BMC_READY_N")
	)
	(segment
		(start 356.1207 -25.16378)
		(end 356.1207 -28.189174)
		(width 0.089408)
		(layer "In11.Cu")
		(net "FM_BMC_READY_N")
	)
	(segment
		(start 383.51714 -84.90712)
		(end 383.51714 -85.72754)
		(width 0.089408)
		(layer "In11.Cu")
		(net "FM_BMC_READY_N")
	)
	(segment
		(start 356.1207 -28.189174)
		(end 355.176074 -29.1338)
		(width 0.089408)
		(layer "In11.Cu")
		(net "FM_BMC_READY_N")
	)
	(segment
		(start 340.397592 -12.714224)
		(end 346.87256 -12.714224)
		(width 0.089408)
		(layer "In11.Cu")
		(net "FM_BMC_READY_N")
	)
	(segment
		(start 349.512128 -15.353792)
		(end 349.512128 -18.508472)
		(width 0.089408)
		(layer "In11.Cu")
		(net "FM_BMC_READY_N")
	)
	(segment
		(start 348.9198 -21.370798)
		(end 349.186754 -21.637752)
		(width 0.089408)
		(layer "In11.Cu")
		(net "FM_BMC_READY_N")
	)
	(segment
		(start 330.039726 3.98272)
		(end 330.06538 3.957066)
		(width 0.089408)
		(layer "In11.Cu")
		(net "FM_BMC_READY_N")
	)
	(segment
		(start 346.87256 -12.714224)
		(end 349.512128 -15.353792)
		(width 0.089408)
		(layer "In11.Cu")
		(net "FM_BMC_READY_N")
	)
	(segment
		(start 330.06538 3.957066)
		(end 331.165454 3.957066)
		(width 0.089408)
		(layer "In11.Cu")
		(net "FM_BMC_READY_N")
	)
	(segment
		(start 383.0701 -87.73922)
		(end 381.75438 -89.05494)
		(width 0.089408)
		(layer "In11.Cu")
		(net "FM_BMC_READY_N")
	)
	(segment
		(start 352.52787 -23.9014)
		(end 354.85832 -23.9014)
		(width 0.089408)
		(layer "In11.Cu")
		(net "FM_BMC_READY_N")
	)
	(segment
		(start 381.82423 -84.65439)
		(end 383.26441 -84.65439)
		(width 0.089408)
		(layer "In11.Cu")
		(net "FM_BMC_READY_N")
	)
	(segment
		(start 381.13208 -83.96224)
		(end 381.82423 -84.65439)
		(width 0.089408)
		(layer "In11.Cu")
		(net "FM_BMC_READY_N")
	)
	(segment
		(start 354.85832 -23.9014)
		(end 356.1207 -25.16378)
		(width 0.089408)
		(layer "In11.Cu")
		(net "FM_BMC_READY_N")
	)
	(segment
		(start 338.074 3.9624)
		(end 338.074 -10.390632)
		(width 0.089408)
		(layer "In11.Cu")
		(net "FM_BMC_READY_N")
	)
	(segment
		(start 331.501496 4.433062)
		(end 331.862938 4.794504)
		(width 0.089408)
		(layer "In11.Cu")
		(net "FM_BMC_READY_N")
	)
	(segment
		(start 354.9396 -29.1338)
		(end 354.6348 -29.4386)
		(width 0.089408)
		(layer "In11.Cu")
		(net "FM_BMC_READY_N")
	)
	(segment
		(start 331.165454 3.957066)
		(end 331.501496 4.293108)
		(width 0.089408)
		(layer "In11.Cu")
		(net "FM_BMC_READY_N")
	)
	(segment
		(start 354.6348 -30.099)
		(end 354.78212 -30.24632)
		(width 0.089408)
		(layer "In11.Cu")
		(net "FM_BMC_READY_N")
	)
	(segment
		(start 349.186754 -21.637752)
		(end 350.264222 -21.637752)
		(width 0.089408)
		(layer "In11.Cu")
		(net "FM_BMC_READY_N")
	)
	(segment
		(start 337.241896 4.794504)
		(end 338.074 3.9624)
		(width 0.089408)
		(layer "In11.Cu")
		(net "FM_BMC_READY_N")
	)
	(segment
		(start 354.6348 -29.4386)
		(end 354.6348 -30.099)
		(width 0.089408)
		(layer "In11.Cu")
		(net "FM_BMC_READY_N")
	)
	(segment
		(start 355.176074 -29.1338)
		(end 354.9396 -29.1338)
		(width 0.089408)
		(layer "In11.Cu")
		(net "FM_BMC_READY_N")
	)
	(segment
		(start 381.21336 -81.24698)
		(end 381.13208 -81.32826)
		(width 0.089408)
		(layer "In11.Cu")
		(net "FM_BMC_READY_N")
	)
	(segment
		(start 175.133 -141.1605)
		(end 176.276 -141.1605)
		(width 0.4064)
		(layer "F.Cu")
		(net "VR_PVPP_KLM_SNUB")
	)
	(segment
		(start 176.276 -141.4907)
		(end 176.276 -141.1605)
		(width 0.4064)
		(layer "F.Cu")
		(net "VR_PVPP_KLM_SNUB")
	)
	(segment
		(start 177.43932 -142.65402)
		(end 176.276 -141.4907)
		(width 0.4064)
		(layer "F.Cu")
		(net "VR_PVPP_KLM_SNUB")
	)
	(via
		(at 177.43932 -142.65402)
		(size 0.762)
		(drill 0.381)
		(layers "F.Cu" "B.Cu")
		(net "VR_PVPP_KLM_SNUB")
	)
	(segment
		(start 174.857664 -17.65681)
		(end 176.437798 -17.65681)
		(width 0.381)
		(layer "F.Cu")
		(net "VR_PVPP_GHJ_SNUB")
	)
	(segment
		(start 171.69003 -10.262362)
		(end 171.696888 -10.255504)
		(width 0.508)
		(layer "F.Cu")
		(net "VR_PVPP_GHJ_BOOT_R")
	)
	(segment
		(start 170.500294 -10.262362)
		(end 171.69003 -10.262362)
		(width 0.508)
		(layer "F.Cu")
		(net "VR_PVPP_GHJ_BOOT_R")
	)
	(segment
		(start 344.297762 -138.132566)
		(end 343.0524 -138.132566)
		(width 0.4064)
		(layer "F.Cu")
		(net "VR_PVPP_DEF_SNUB")
	)
	(segment
		(start 344.45448 -138.289284)
		(end 344.297762 -138.132566)
		(width 0.4064)
		(layer "F.Cu")
		(net "VR_PVPP_DEF_SNUB")
	)
	(segment
		(start 342.646 -137.726166)
		(end 342.646 -137.1727)
		(width 0.4064)
		(layer "F.Cu")
		(net "VR_PVPP_DEF_SNUB")
	)
	(segment
		(start 343.0524 -138.132566)
		(end 342.646 -137.726166)
		(width 0.4064)
		(layer "F.Cu")
		(net "VR_PVPP_DEF_SNUB")
	)
	(segment
		(start 341.503 -137.1727)
		(end 342.646 -137.1727)
		(width 0.4064)
		(layer "F.Cu")
		(net "VR_PVPP_DEF_SNUB")
	)
	(via
		(at 344.45448 -138.289284)
		(size 0.762)
		(drill 0.381)
		(layers "F.Cu" "B.Cu")
		(net "VR_PVPP_DEF_SNUB")
	)
	(segment
		(start 338.03209 -130.580384)
		(end 337.906868 -130.455162)
		(width 0.508)
		(layer "F.Cu")
		(net "VR_PVPP_DEF_BOOT_R")
	)
	(segment
		(start 339.258656 -130.580384)
		(end 338.03209 -130.580384)
		(width 0.508)
		(layer "F.Cu")
		(net "VR_PVPP_DEF_BOOT_R")
	)
	(segment
		(start 343.9668 -32.8803)
		(end 342.8238 -32.8803)
		(width 0.4064)
		(layer "F.Cu")
		(net "VR_PVPP_ABC_SNUB")
	)
	(segment
		(start 346.617036 -28.312364)
		(end 345.3638 -29.5656)
		(width 0.254)
		(layer "F.Cu")
		(net "VR_PVPP_ABC_PHASE")
	)
	(segment
		(start 348.1959 -28.312364)
		(end 346.617036 -28.312364)
		(width 0.254)
		(layer "F.Cu")
		(net "VR_PVPP_ABC_PHASE")
	)
	(segment
		(start 340.775036 -25.576276)
		(end 339.943186 -25.576276)
		(width 0.508)
		(layer "F.Cu")
		(net "VR_PVPP_ABC_BOOT_R")
	)
	(segment
		(start 339.943186 -25.576276)
		(end 339.632036 -25.265126)
		(width 0.508)
		(layer "F.Cu")
		(net "VR_PVPP_ABC_BOOT_R")
	)
	(segment
		(start 340.775036 -26.973276)
		(end 340.775036 -27.237436)
		(width 0.508)
		(layer "F.Cu")
		(net "VR_PVPP_ABC_BOOT")
	)
	(segment
		(start 341.849964 -28.312364)
		(end 342.5317 -28.312364)
		(width 0.254)
		(layer "F.Cu")
		(net "VR_PVPP_ABC_BOOT")
	)
	(segment
		(start 341.503 -27.9654)
		(end 341.849964 -28.312364)
		(width 0.254)
		(layer "F.Cu")
		(net "VR_PVPP_ABC_BOOT")
	)
	(segment
		(start 340.775036 -27.237436)
		(end 341.503 -27.9654)
		(width 0.508)
		(layer "F.Cu")
		(net "VR_PVPP_ABC_BOOT")
	)
	(segment
		(start 5.842 -126.110746)
		(end 5.842 -125.603)
		(width 0.2032)
		(layer "F.Cu")
		(net "VR_PVDDQ_KLM_XADDR2")
	)
	(segment
		(start 5.842 -124.587)
		(end 6.35 -125.095)
		(width 0.2032)
		(layer "F.Cu")
		(net "VR_PVDDQ_KLM_XADDR2")
	)
	(segment
		(start 4.5085 -126.965202)
		(end 4.987544 -126.965202)
		(width 0.2032)
		(layer "F.Cu")
		(net "VR_PVDDQ_KLM_XADDR2")
	)
	(segment
		(start 5.842 -123.825)
		(end 5.842 -124.587)
		(width 0.2032)
		(layer "F.Cu")
		(net "VR_PVDDQ_KLM_XADDR2")
	)
	(segment
		(start 4.987544 -126.965202)
		(end 5.842 -126.110746)
		(width 0.2032)
		(layer "F.Cu")
		(net "VR_PVDDQ_KLM_XADDR2")
	)
	(segment
		(start 5.842 -125.603)
		(end 6.35 -125.095)
		(width 0.2032)
		(layer "F.Cu")
		(net "VR_PVDDQ_KLM_XADDR2")
	)
	(via
		(at 5.842 -123.825)
		(size 0.762)
		(drill 0.381)
		(layers "F.Cu" "B.Cu")
		(net "VR_PVDDQ_KLM_XADDR2")
	)
	(segment
		(start 5.306568 -128.165098)
		(end 5.662168 -127.809498)
		(width 0.1016)
		(layer "F.Cu")
		(net "VR_PVDDQ_KLM_XADDR1")
	)
	(segment
		(start 6.344666 -127.127)
		(end 6.35 -127.127)
		(width 0.1016)
		(layer "F.Cu")
		(net "VR_PVDDQ_KLM_XADDR1")
	)
	(segment
		(start 4.5085 -128.165098)
		(end 5.306568 -128.165098)
		(width 0.1016)
		(layer "F.Cu")
		(net "VR_PVDDQ_KLM_XADDR1")
	)
	(segment
		(start 5.662168 -127.809498)
		(end 6.344666 -127.127)
		(width 0.1016)
		(layer "F.Cu")
		(net "VR_PVDDQ_KLM_XADDR1")
	)
	(via
		(at 5.662168 -127.809498)
		(size 0.508)
		(drill 0.254)
		(layers "F.Cu" "B.Cu")
		(net "VR_PVDDQ_KLM_XADDR1")
	)
	(segment
		(start 9.200896 -124.19457)
		(end 9.200896 -124.854208)
		(width 0.254)
		(layer "F.Cu")
		(net "VR_PVDDQ_KLM_VINSEN")
	)
	(segment
		(start 6.448552 -128.137158)
		(end 7.119112 -128.137158)
		(width 0.2032)
		(layer "F.Cu")
		(net "VR_PVDDQ_KLM_VINSEN")
	)
	(segment
		(start 8.43915 -123.432824)
		(end 9.200896 -124.19457)
		(width 0.254)
		(layer "F.Cu")
		(net "VR_PVDDQ_KLM_VINSEN")
	)
	(segment
		(start 9.200896 -124.854208)
		(end 8.356346 -125.698758)
		(width 0.254)
		(layer "F.Cu")
		(net "VR_PVDDQ_KLM_VINSEN")
	)
	(segment
		(start 4.5085 -128.565148)
		(end 5.678932 -128.565148)
		(width 0.2032)
		(layer "F.Cu")
		(net "VR_PVDDQ_KLM_VINSEN")
	)
	(segment
		(start 5.678932 -128.565148)
		(end 6.106922 -128.137158)
		(width 0.2032)
		(layer "F.Cu")
		(net "VR_PVDDQ_KLM_VINSEN")
	)
	(segment
		(start 7.119112 -128.137158)
		(end 7.33298 -127.92329)
		(width 0.2032)
		(layer "F.Cu")
		(net "VR_PVDDQ_KLM_VINSEN")
	)
	(segment
		(start 8.356346 -125.698758)
		(end 8.356346 -126.899924)
		(width 0.254)
		(layer "F.Cu")
		(net "VR_PVDDQ_KLM_VINSEN")
	)
	(segment
		(start 7.728712 -123.432824)
		(end 8.43915 -123.432824)
		(width 0.254)
		(layer "F.Cu")
		(net "VR_PVDDQ_KLM_VINSEN")
	)
	(segment
		(start 8.356346 -126.899924)
		(end 7.33298 -127.92329)
		(width 0.254)
		(layer "F.Cu")
		(net "VR_PVDDQ_KLM_VINSEN")
	)
	(segment
		(start 6.106922 -128.137158)
		(end 6.448552 -128.137158)
		(width 0.2032)
		(layer "F.Cu")
		(net "VR_PVDDQ_KLM_VINSEN")
	)
	(via
		(at 7.728712 -123.432824)
		(size 0.762)
		(drill 0.381)
		(layers "F.Cu" "B.Cu")
		(net "VR_PVDDQ_KLM_VINSEN")
	)
	(segment
		(start 3.1623 -131.9149)
		(end 3.74142 -132.49402)
		(width 0.4064)
		(layer "F.Cu")
		(net "VR_PVDDQ_KLM_VD12")
	)
	(segment
		(start 3.74142 -132.49402)
		(end 4.31546 -132.49402)
		(width 0.4064)
		(layer "F.Cu")
		(net "VR_PVDDQ_KLM_VD12")
	)
	(segment
		(start 4.961382 -130.411982)
		(end 4.5085 -129.9591)
		(width 0.2032)
		(layer "F.Cu")
		(net "VR_PVDDQ_KLM_VD12")
	)
	(segment
		(start 5.20446 -132.49402)
		(end 5.20446 -130.65506)
		(width 0.4064)
		(layer "F.Cu")
		(net "VR_PVDDQ_KLM_VD12")
	)
	(segment
		(start 4.5085 -129.9591)
		(end 4.5085 -129.765298)
		(width 0.2032)
		(layer "F.Cu")
		(net "VR_PVDDQ_KLM_VD12")
	)
	(segment
		(start 4.31546 -132.49402)
		(end 5.20446 -132.49402)
		(width 0.4064)
		(layer "F.Cu")
		(net "VR_PVDDQ_KLM_VD12")
	)
	(segment
		(start 5.20446 -130.65506)
		(end 4.961382 -130.411982)
		(width 0.4064)
		(layer "F.Cu")
		(net "VR_PVDDQ_KLM_VD12")
	)
	(via
		(at 3.1623 -131.9149)
		(size 0.762)
		(drill 0.381)
		(layers "F.Cu" "B.Cu")
		(net "VR_PVDDQ_KLM_VD12")
	)
	(segment
		(start -3.429 -125.222)
		(end -2.5146 -125.222)
		(width 0.127)
		(layer "F.Cu")
		(net "VR_PVDDQ_KLM_AVSP")
	)
	(segment
		(start -1.3081 -125.9967)
		(end -0.739648 -126.565152)
		(width 0.127)
		(layer "F.Cu")
		(net "VR_PVDDQ_KLM_AVSP")
	)
	(segment
		(start -1.3081 -125.7935)
		(end -1.3081 -125.9967)
		(width 0.127)
		(layer "F.Cu")
		(net "VR_PVDDQ_KLM_AVSP")
	)
	(segment
		(start -0.739648 -126.565152)
		(end -0.3937 -126.565152)
		(width 0.127)
		(layer "F.Cu")
		(net "VR_PVDDQ_KLM_AVSP")
	)
	(segment
		(start -1.6637 -125.4379)
		(end -1.3081 -125.7935)
		(width 0.127)
		(layer "F.Cu")
		(net "VR_PVDDQ_KLM_AVSP")
	)
	(segment
		(start -1.8796 -125.222)
		(end -1.6637 -125.4379)
		(width 0.127)
		(layer "F.Cu")
		(net "VR_PVDDQ_KLM_AVSP")
	)
	(segment
		(start -2.5146 -125.222)
		(end -1.8796 -125.222)
		(width 0.127)
		(layer "F.Cu")
		(net "VR_PVDDQ_KLM_AVSP")
	)
	(via
		(at -1.6637 -125.4379)
		(size 0.508)
		(drill 0.254)
		(layers "F.Cu" "B.Cu")
		(net "VR_PVDDQ_KLM_AVSP")
	)
	(segment
		(start 8.991346 3.786124)
		(end 9.033002 3.744468)
		(width 0.254)
		(layer "F.Cu")
		(net "VR_PVDDQ_GHJ_XADDR2")
	)
	(segment
		(start 9.033002 3.214878)
		(end 9.033002 2.69875)
		(width 0.2032)
		(layer "F.Cu")
		(net "VR_PVDDQ_GHJ_XADDR2")
	)
	(segment
		(start 9.033002 3.744468)
		(end 9.033002 3.214878)
		(width 0.254)
		(layer "F.Cu")
		(net "VR_PVDDQ_GHJ_XADDR2")
	)
	(segment
		(start 9.205976 4.699)
		(end 8.993378 4.911598)
		(width 0.254)
		(layer "F.Cu")
		(net "VR_PVDDQ_GHJ_XADDR1")
	)
	(segment
		(start 10.0584 3.502406)
		(end 10.0584 4.368292)
		(width 0.254)
		(layer "F.Cu")
		(net "VR_PVDDQ_GHJ_XADDR1")
	)
	(segment
		(start 10.232898 3.327908)
		(end 10.0584 3.502406)
		(width 0.254)
		(layer "F.Cu")
		(net "VR_PVDDQ_GHJ_XADDR1")
	)
	(segment
		(start 10.0584 4.368292)
		(end 9.727692 4.699)
		(width 0.254)
		(layer "F.Cu")
		(net "VR_PVDDQ_GHJ_XADDR1")
	)
	(segment
		(start 10.232898 2.69875)
		(end 10.232898 3.327908)
		(width 0.2032)
		(layer "F.Cu")
		(net "VR_PVDDQ_GHJ_XADDR1")
	)
	(segment
		(start 9.727692 4.699)
		(end 9.205976 4.699)
		(width 0.254)
		(layer "F.Cu")
		(net "VR_PVDDQ_GHJ_XADDR1")
	)
	(segment
		(start 11.458702 4.45135)
		(end 11.458702 4.098798)
		(width 0.254)
		(layer "F.Cu")
		(net "VR_PVDDQ_GHJ_VINSEN")
	)
	(segment
		(start 10.859516 5.20319)
		(end 11.058144 5.004562)
		(width 0.254)
		(layer "F.Cu")
		(net "VR_PVDDQ_GHJ_VINSEN")
	)
	(segment
		(start 9.709658 5.20319)
		(end 10.859516 5.20319)
		(width 0.254)
		(layer "F.Cu")
		(net "VR_PVDDQ_GHJ_VINSEN")
	)
	(segment
		(start 11.458702 3.91922)
		(end 11.458702 4.098798)
		(width 0.1524)
		(layer "F.Cu")
		(net "VR_PVDDQ_GHJ_VINSEN")
	)
	(segment
		(start 11.058144 4.851908)
		(end 11.458702 4.45135)
		(width 0.254)
		(layer "F.Cu")
		(net "VR_PVDDQ_GHJ_VINSEN")
	)
	(segment
		(start 11.058144 5.004562)
		(end 11.058144 4.851908)
		(width 0.254)
		(layer "F.Cu")
		(net "VR_PVDDQ_GHJ_VINSEN")
	)
	(segment
		(start 10.632948 3.093466)
		(end 11.458702 3.91922)
		(width 0.1524)
		(layer "F.Cu")
		(net "VR_PVDDQ_GHJ_VINSEN")
	)
	(segment
		(start 10.632948 2.69875)
		(end 10.632948 3.093466)
		(width 0.1524)
		(layer "F.Cu")
		(net "VR_PVDDQ_GHJ_VINSEN")
	)
	(via
		(at 9.709658 5.20319)
		(size 0.508)
		(drill 0.254)
		(layers "F.Cu" "B.Cu")
		(net "VR_PVDDQ_GHJ_VINSEN")
	)
	(segment
		(start 9.709658 5.20319)
		(end 9.418574 5.20319)
		(width 0.254)
		(layer "B.Cu")
		(net "VR_PVDDQ_GHJ_VINSEN")
	)
	(segment
		(start 9.061958 4.846574)
		(end 9.061958 4.17322)
		(width 0.254)
		(layer "B.Cu")
		(net "VR_PVDDQ_GHJ_VINSEN")
	)
	(segment
		(start 9.418574 5.20319)
		(end 9.061958 4.846574)
		(width 0.254)
		(layer "B.Cu")
		(net "VR_PVDDQ_GHJ_VINSEN")
	)
	(segment
		(start 14.556486 1.902714)
		(end 14.637766 1.902714)
		(width 0.1016)
		(layer "F.Cu")
		(net "VR_PVDDQ_GHJ_VD12")
	)
	(segment
		(start 14.637766 1.902714)
		(end 14.81328 1.7272)
		(width 0.1016)
		(layer "F.Cu")
		(net "VR_PVDDQ_GHJ_VD12")
	)
	(segment
		(start 13.941806 2.692654)
		(end 13.941806 3.507232)
		(width 0.4064)
		(layer "F.Cu")
		(net "VR_PVDDQ_GHJ_VD12")
	)
	(segment
		(start 13.941806 2.517394)
		(end 14.556486 1.902714)
		(width 0.1016)
		(layer "F.Cu")
		(net "VR_PVDDQ_GHJ_VD12")
	)
	(segment
		(start 13.334746 2.811526)
		(end 13.453618 2.692654)
		(width 0.4064)
		(layer "F.Cu")
		(net "VR_PVDDQ_GHJ_VD12")
	)
	(segment
		(start 13.941806 2.692654)
		(end 13.941806 2.517394)
		(width 0.1016)
		(layer "F.Cu")
		(net "VR_PVDDQ_GHJ_VD12")
	)
	(segment
		(start 11.833098 2.69875)
		(end 11.910568 2.77622)
		(width 0.2032)
		(layer "F.Cu")
		(net "VR_PVDDQ_GHJ_VD12")
	)
	(segment
		(start 12.724384 2.77622)
		(end 12.75969 2.811526)
		(width 0.4064)
		(layer "F.Cu")
		(net "VR_PVDDQ_GHJ_VD12")
	)
	(segment
		(start 12.75969 2.811526)
		(end 13.334746 2.811526)
		(width 0.4064)
		(layer "F.Cu")
		(net "VR_PVDDQ_GHJ_VD12")
	)
	(segment
		(start 13.453618 2.692654)
		(end 13.941806 2.692654)
		(width 0.4064)
		(layer "F.Cu")
		(net "VR_PVDDQ_GHJ_VD12")
	)
	(segment
		(start 11.910568 2.77622)
		(end 12.724384 2.77622)
		(width 0.2032)
		(layer "F.Cu")
		(net "VR_PVDDQ_GHJ_VD12")
	)
	(via
		(at 14.81328 1.7272)
		(size 0.762)
		(drill 0.381)
		(layers "F.Cu" "B.Cu")
		(net "VR_PVDDQ_GHJ_VD12")
	)
	(segment
		(start 355.656388 -139.805156)
		(end 355.656388 -139.87399)
		(width 0.2032)
		(layer "F.Cu")
		(net "VR_PVDDQ_DEF_XADDR2")
	)
	(segment
		(start 356.84714 -139.164568)
		(end 356.296976 -139.164568)
		(width 0.2032)
		(layer "F.Cu")
		(net "VR_PVDDQ_DEF_XADDR2")
	)
	(segment
		(start 356.296976 -139.164568)
		(end 355.656388 -139.805156)
		(width 0.2032)
		(layer "F.Cu")
		(net "VR_PVDDQ_DEF_XADDR2")
	)
	(segment
		(start 356.105968 -137.964672)
		(end 355.211634 -138.859006)
		(width 0.2032)
		(layer "F.Cu")
		(net "VR_PVDDQ_DEF_XADDR1")
	)
	(segment
		(start 355.20757 -138.859006)
		(end 355.009196 -139.05738)
		(width 0.2032)
		(layer "F.Cu")
		(net "VR_PVDDQ_DEF_XADDR1")
	)
	(segment
		(start 352.21672 -139.37742)
		(end 351.51568 -139.37742)
		(width 0.2032)
		(layer "F.Cu")
		(net "VR_PVDDQ_DEF_XADDR1")
	)
	(segment
		(start 356.84714 -137.964672)
		(end 356.105968 -137.964672)
		(width 0.2032)
		(layer "F.Cu")
		(net "VR_PVDDQ_DEF_XADDR1")
	)
	(segment
		(start 355.009196 -139.05738)
		(end 352.53676 -139.05738)
		(width 0.2032)
		(layer "F.Cu")
		(net "VR_PVDDQ_DEF_XADDR1")
	)
	(segment
		(start 352.53676 -139.05738)
		(end 352.48088 -139.11326)
		(width 0.2032)
		(layer "F.Cu")
		(net "VR_PVDDQ_DEF_XADDR1")
	)
	(segment
		(start 352.48088 -139.11326)
		(end 352.21672 -139.37742)
		(width 0.2032)
		(layer "F.Cu")
		(net "VR_PVDDQ_DEF_XADDR1")
	)
	(segment
		(start 355.211634 -138.859006)
		(end 355.20757 -138.859006)
		(width 0.2032)
		(layer "F.Cu")
		(net "VR_PVDDQ_DEF_XADDR1")
	)
	(via
		(at 352.48088 -139.11326)
		(size 0.762)
		(drill 0.381)
		(layers "F.Cu" "B.Cu")
		(net "VR_PVDDQ_DEF_XADDR1")
	)
	(segment
		(start 353.863656 -137.897108)
		(end 354.244656 -138.278108)
		(width 0.254)
		(layer "F.Cu")
		(net "VR_PVDDQ_DEF_VINSEN")
	)
	(segment
		(start 353.177348 -137.6172)
		(end 353.457256 -137.897108)
		(width 0.254)
		(layer "F.Cu")
		(net "VR_PVDDQ_DEF_VINSEN")
	)
	(segment
		(start 354.751132 -138.039348)
		(end 355.149404 -138.039348)
		(width 0.254)
		(layer "F.Cu")
		(net "VR_PVDDQ_DEF_VINSEN")
	)
	(segment
		(start 355.980746 -137.564622)
		(end 356.84714 -137.564622)
		(width 0.2032)
		(layer "F.Cu")
		(net "VR_PVDDQ_DEF_VINSEN")
	)
	(segment
		(start 355.149404 -138.039348)
		(end 355.50602 -138.039348)
		(width 0.254)
		(layer "F.Cu")
		(net "VR_PVDDQ_DEF_VINSEN")
	)
	(segment
		(start 354.244656 -138.278108)
		(end 354.512372 -138.278108)
		(width 0.254)
		(layer "F.Cu")
		(net "VR_PVDDQ_DEF_VINSEN")
	)
	(segment
		(start 355.50602 -138.039348)
		(end 355.980746 -137.564622)
		(width 0.254)
		(layer "F.Cu")
		(net "VR_PVDDQ_DEF_VINSEN")
	)
	(segment
		(start 353.457256 -137.897108)
		(end 353.863656 -137.897108)
		(width 0.254)
		(layer "F.Cu")
		(net "VR_PVDDQ_DEF_VINSEN")
	)
	(segment
		(start 354.512372 -138.278108)
		(end 354.751132 -138.039348)
		(width 0.254)
		(layer "F.Cu")
		(net "VR_PVDDQ_DEF_VINSEN")
	)
	(via
		(at 353.177348 -137.6172)
		(size 0.508)
		(drill 0.254)
		(layers "F.Cu" "B.Cu")
		(net "VR_PVDDQ_DEF_VINSEN")
	)
	(segment
		(start 354.548948 -137.904728)
		(end 353.464876 -137.904728)
		(width 0.254)
		(layer "B.Cu")
		(net "VR_PVDDQ_DEF_VINSEN")
	)
	(segment
		(start 353.464876 -137.904728)
		(end 353.177348 -137.6172)
		(width 0.254)
		(layer "B.Cu")
		(net "VR_PVDDQ_DEF_VINSEN")
	)
	(segment
		(start 356.98684 -134.22757)
		(end 356.09784 -134.22757)
		(width 0.254)
		(layer "F.Cu")
		(net "VR_PVDDQ_DEF_VD12")
	)
	(segment
		(start 356.84714 -136.364472)
		(end 356.84714 -135.670798)
		(width 0.2032)
		(layer "F.Cu")
		(net "VR_PVDDQ_DEF_VD12")
	)
	(segment
		(start 355.15804 -133.88848)
		(end 355.49713 -134.22757)
		(width 0.1016)
		(layer "F.Cu")
		(net "VR_PVDDQ_DEF_VD12")
	)
	(segment
		(start 355.49713 -134.22757)
		(end 356.09784 -134.22757)
		(width 0.1016)
		(layer "F.Cu")
		(net "VR_PVDDQ_DEF_VD12")
	)
	(segment
		(start 356.09784 -134.921498)
		(end 356.09784 -134.22757)
		(width 0.2032)
		(layer "F.Cu")
		(net "VR_PVDDQ_DEF_VD12")
	)
	(segment
		(start 356.84714 -135.670798)
		(end 356.09784 -134.921498)
		(width 0.2032)
		(layer "F.Cu")
		(net "VR_PVDDQ_DEF_VD12")
	)
	(via
		(at 355.15804 -133.88848)
		(size 0.762)
		(drill 0.381)
		(layers "F.Cu" "B.Cu")
		(net "VR_PVDDQ_DEF_VD12")
	)
	(segment
		(start 406.437592 -36.134548)
		(end 407.090118 -36.134548)
		(width 0.10795)
		(layer "F.Cu")
		(net "SMB_OCP_FRU_STBY_LVC3_SDA_R")
	)
	(via
		(at 404.2918 -37.1348)
		(size 0.6604)
		(drill 0.3302)
		(layers "F.Cu" "B.Cu")
		(net "SMB_OCP_FRU_STBY_LVC3_SDA_R")
	)
	(via
		(at 406.437592 -36.134548)
		(size 0.4572)
		(drill 0.2032)
		(layers "F.Cu" "B.Cu")
		(net "SMB_OCP_FRU_STBY_LVC3_SDA_R")
	)
	(segment
		(start 403.47646 -37.509704)
		(end 403.089364 -37.8968)
		(width 0.10795)
		(layer "B.Cu")
		(net "SMB_OCP_FRU_STBY_LVC3_SDA_R")
	)
	(segment
		(start 404.545546 -36.652454)
		(end 404.545546 -36.881054)
		(width 0.10795)
		(layer "B.Cu")
		(net "SMB_OCP_FRU_STBY_LVC3_SDA_R")
	)
	(segment
		(start 402.4503 -37.8968)
		(end 402.4503 -37.1094)
		(width 0.10795)
		(layer "B.Cu")
		(net "SMB_OCP_FRU_STBY_LVC3_SDA_R")
	)
	(segment
		(start 403.089364 -37.8968)
		(end 402.4503 -37.8968)
		(width 0.10795)
		(layer "B.Cu")
		(net "SMB_OCP_FRU_STBY_LVC3_SDA_R")
	)
	(segment
		(start 406.437592 -36.134548)
		(end 405.063452 -36.134548)
		(width 0.10795)
		(layer "B.Cu")
		(net "SMB_OCP_FRU_STBY_LVC3_SDA_R")
	)
	(segment
		(start 403.916896 -37.509704)
		(end 403.47646 -37.509704)
		(width 0.10795)
		(layer "B.Cu")
		(net "SMB_OCP_FRU_STBY_LVC3_SDA_R")
	)
	(segment
		(start 405.063452 -36.134548)
		(end 404.545546 -36.652454)
		(width 0.10795)
		(layer "B.Cu")
		(net "SMB_OCP_FRU_STBY_LVC3_SDA_R")
	)
	(segment
		(start 404.2918 -37.1348)
		(end 403.916896 -37.509704)
		(width 0.10795)
		(layer "B.Cu")
		(net "SMB_OCP_FRU_STBY_LVC3_SDA_R")
	)
	(segment
		(start 404.545546 -36.881054)
		(end 404.2918 -37.1348)
		(width 0.10795)
		(layer "B.Cu")
		(net "SMB_OCP_FRU_STBY_LVC3_SDA_R")
	)
	(segment
		(start 441.350146 -57.596024)
		(end 441.350146 -58.695844)
		(width 0.10795)
		(layer "F.Cu")
		(net "SMB_OCP_FRU_STBY_LVC3_SDA")
	)
	(segment
		(start 419.853872 -121.740422)
		(end 420.779194 -121.740422)
		(width 0.10795)
		(layer "F.Cu")
		(net "SMB_OCP_FRU_STBY_LVC3_SDA")
	)
	(segment
		(start 441.350146 -58.695844)
		(end 441.921138 -59.266836)
		(width 0.10795)
		(layer "F.Cu")
		(net "SMB_OCP_FRU_STBY_LVC3_SDA")
	)
	(segment
		(start 475.800928 -112.205516)
		(end 475.800928 -113.684812)
		(width 0.10795)
		(layer "F.Cu")
		(net "SMB_OCP_FRU_STBY_LVC3_SDA")
	)
	(segment
		(start 419.589204 -122.00509)
		(end 419.853872 -121.740422)
		(width 0.10795)
		(layer "F.Cu")
		(net "SMB_OCP_FRU_STBY_LVC3_SDA")
	)
	(segment
		(start 475.800928 -113.684812)
		(end 475.70644 -113.7793)
		(width 0.10795)
		(layer "F.Cu")
		(net "SMB_OCP_FRU_STBY_LVC3_SDA")
	)
	(segment
		(start 419.589204 -122.478038)
		(end 419.589204 -122.00509)
		(width 0.10795)
		(layer "F.Cu")
		(net "SMB_OCP_FRU_STBY_LVC3_SDA")
	)
	(via
		(at 401.995386 -84.896198)
		(size 0.6604)
		(drill 0.3302)
		(layers "F.Cu" "B.Cu")
		(net "SMB_OCP_FRU_STBY_LVC3_SDA")
	)
	(via
		(at 458.745082 -59.076336)
		(size 0.508)
		(drill 0.254)
		(layers "F.Cu" "B.Cu")
		(net "SMB_OCP_FRU_STBY_LVC3_SDA")
	)
	(via
		(at 411.453838 -86.013544)
		(size 0.508)
		(drill 0.254)
		(layers "F.Cu" "B.Cu")
		(net "SMB_OCP_FRU_STBY_LVC3_SDA")
	)
	(via
		(at 400.75358 -37.977826)
		(size 0.508)
		(drill 0.254)
		(layers "F.Cu" "B.Cu")
		(net "SMB_OCP_FRU_STBY_LVC3_SDA")
	)
	(via
		(at 472.05138 -52.40909)
		(size 0.508)
		(drill 0.254)
		(layers "F.Cu" "B.Cu")
		(net "SMB_OCP_FRU_STBY_LVC3_SDA")
	)
	(via
		(at 441.921138 -59.266836)
		(size 0.508)
		(drill 0.254)
		(layers "F.Cu" "B.Cu")
		(net "SMB_OCP_FRU_STBY_LVC3_SDA")
	)
	(via
		(at 475.70644 -113.7793)
		(size 0.508)
		(drill 0.254)
		(layers "F.Cu" "B.Cu")
		(net "SMB_OCP_FRU_STBY_LVC3_SDA")
	)
	(via
		(at 419.589204 -122.478038)
		(size 0.508)
		(drill 0.254)
		(layers "F.Cu" "B.Cu")
		(net "SMB_OCP_FRU_STBY_LVC3_SDA")
	)
	(segment
		(start 402.876512 -85.15985)
		(end 407.154888 -85.15985)
		(width 0.10795)
		(layer "B.Cu")
		(net "SMB_OCP_FRU_STBY_LVC3_SDA")
	)
	(segment
		(start 400.199098 -84.896198)
		(end 398.262348 -82.959448)
		(width 0.10795)
		(layer "B.Cu")
		(net "SMB_OCP_FRU_STBY_LVC3_SDA")
	)
	(segment
		(start 417.869116 -121.590562)
		(end 417.869116 -120.674638)
		(width 0.10795)
		(layer "B.Cu")
		(net "SMB_OCP_FRU_STBY_LVC3_SDA")
	)
	(segment
		(start 417.869116 -119.913146)
		(end 417.868862 -119.912892)
		(width 0.10795)
		(layer "B.Cu")
		(net "SMB_OCP_FRU_STBY_LVC3_SDA")
	)
	(segment
		(start 413.4358 -87.210646)
		(end 412.076392 -85.851238)
		(width 0.10795)
		(layer "B.Cu")
		(net "SMB_OCP_FRU_STBY_LVC3_SDA")
	)
	(segment
		(start 401.995386 -84.896198)
		(end 400.199098 -84.896198)
		(width 0.10795)
		(layer "B.Cu")
		(net "SMB_OCP_FRU_STBY_LVC3_SDA")
	)
	(segment
		(start 394.476732 -84.596732)
		(end 394.589 -84.709)
		(width 0.10795)
		(layer "B.Cu")
		(net "SMB_OCP_FRU_STBY_LVC3_SDA")
	)
	(segment
		(start 413.718756 -88.343486)
		(end 413.4358 -88.06053)
		(width 0.10795)
		(layer "B.Cu")
		(net "SMB_OCP_FRU_STBY_LVC3_SDA")
	)
	(segment
		(start 419.589204 -122.478038)
		(end 419.416992 -122.65025)
		(width 0.10795)
		(layer "B.Cu")
		(net "SMB_OCP_FRU_STBY_LVC3_SDA")
	)
	(segment
		(start 417.868862 -118.827042)
		(end 416.010598 -116.968778)
		(width 0.10795)
		(layer "B.Cu")
		(net "SMB_OCP_FRU_STBY_LVC3_SDA")
	)
	(segment
		(start 417.869116 -120.10771)
		(end 417.869116 -119.913146)
		(width 0.10795)
		(layer "B.Cu")
		(net "SMB_OCP_FRU_STBY_LVC3_SDA")
	)
	(segment
		(start 409.757118 -84.732114)
		(end 411.03169 -86.006686)
		(width 0.10795)
		(layer "B.Cu")
		(net "SMB_OCP_FRU_STBY_LVC3_SDA")
	)
	(segment
		(start 411.03169 -86.006686)
		(end 411.44698 -86.006686)
		(width 0.10795)
		(layer "B.Cu")
		(net "SMB_OCP_FRU_STBY_LVC3_SDA")
	)
	(segment
		(start 417.579556 -107.5563)
		(end 417.579556 -104.09301)
		(width 0.10795)
		(layer "B.Cu")
		(net "SMB_OCP_FRU_STBY_LVC3_SDA")
	)
	(segment
		(start 414.257744 -88.343486)
		(end 413.718756 -88.343486)
		(width 0.10795)
		(layer "B.Cu")
		(net "SMB_OCP_FRU_STBY_LVC3_SDA")
	)
	(segment
		(start 411.44698 -86.006686)
		(end 411.453838 -86.013544)
		(width 0.10795)
		(layer "B.Cu")
		(net "SMB_OCP_FRU_STBY_LVC3_SDA")
	)
	(segment
		(start 417.579556 -104.09301)
		(end 415.738056 -102.25151)
		(width 0.10795)
		(layer "B.Cu")
		(net "SMB_OCP_FRU_STBY_LVC3_SDA")
	)
	(segment
		(start 414.947862 -90.00744)
		(end 414.947862 -89.033604)
		(width 0.10795)
		(layer "B.Cu")
		(net "SMB_OCP_FRU_STBY_LVC3_SDA")
	)
	(segment
		(start 394.476732 -84.250022)
		(end 394.476732 -84.596732)
		(width 0.10795)
		(layer "B.Cu")
		(net "SMB_OCP_FRU_STBY_LVC3_SDA")
	)
	(segment
		(start 416.010598 -116.968778)
		(end 416.010598 -109.125258)
		(width 0.10795)
		(layer "B.Cu")
		(net "SMB_OCP_FRU_STBY_LVC3_SDA")
	)
	(segment
		(start 414.947862 -89.033604)
		(end 414.257744 -88.343486)
		(width 0.10795)
		(layer "B.Cu")
		(net "SMB_OCP_FRU_STBY_LVC3_SDA")
	)
	(segment
		(start 415.738056 -102.25151)
		(end 415.738056 -95.04172)
		(width 0.10795)
		(layer "B.Cu")
		(net "SMB_OCP_FRU_STBY_LVC3_SDA")
	)
	(segment
		(start 417.868862 -121.590816)
		(end 417.869116 -121.590562)
		(width 0.10795)
		(layer "B.Cu")
		(net "SMB_OCP_FRU_STBY_LVC3_SDA")
	)
	(segment
		(start 402.61286 -84.896198)
		(end 402.876512 -85.15985)
		(width 0.10795)
		(layer "B.Cu")
		(net "SMB_OCP_FRU_STBY_LVC3_SDA")
	)
	(segment
		(start 415.398458 -94.702122)
		(end 415.398458 -90.458036)
		(width 0.10795)
		(layer "B.Cu")
		(net "SMB_OCP_FRU_STBY_LVC3_SDA")
	)
	(segment
		(start 398.262348 -82.959448)
		(end 395.767306 -82.959448)
		(width 0.10795)
		(layer "B.Cu")
		(net "SMB_OCP_FRU_STBY_LVC3_SDA")
	)
	(segment
		(start 417.728654 -121.731278)
		(end 417.868862 -121.59107)
		(width 0.10795)
		(layer "B.Cu")
		(net "SMB_OCP_FRU_STBY_LVC3_SDA")
	)
	(segment
		(start 417.868862 -120.674384)
		(end 417.868862 -120.107964)
		(width 0.10795)
		(layer "B.Cu")
		(net "SMB_OCP_FRU_STBY_LVC3_SDA")
	)
	(segment
		(start 419.416992 -122.65025)
		(end 417.99002 -122.65025)
		(width 0.10795)
		(layer "B.Cu")
		(net "SMB_OCP_FRU_STBY_LVC3_SDA")
	)
	(segment
		(start 395.767306 -82.959448)
		(end 394.476732 -84.250022)
		(width 0.10795)
		(layer "B.Cu")
		(net "SMB_OCP_FRU_STBY_LVC3_SDA")
	)
	(segment
		(start 417.868862 -119.912892)
		(end 417.868862 -118.827042)
		(width 0.10795)
		(layer "B.Cu")
		(net "SMB_OCP_FRU_STBY_LVC3_SDA")
	)
	(segment
		(start 401.995386 -84.896198)
		(end 402.61286 -84.896198)
		(width 0.10795)
		(layer "B.Cu")
		(net "SMB_OCP_FRU_STBY_LVC3_SDA")
	)
	(segment
		(start 417.99002 -122.65025)
		(end 417.728654 -122.388884)
		(width 0.10795)
		(layer "B.Cu")
		(net "SMB_OCP_FRU_STBY_LVC3_SDA")
	)
	(segment
		(start 401.5613 -37.8968)
		(end 400.834606 -37.8968)
		(width 0.10795)
		(layer "B.Cu")
		(net "SMB_OCP_FRU_STBY_LVC3_SDA")
	)
	(segment
		(start 416.010598 -109.125258)
		(end 417.579556 -107.5563)
		(width 0.10795)
		(layer "B.Cu")
		(net "SMB_OCP_FRU_STBY_LVC3_SDA")
	)
	(segment
		(start 417.728654 -122.388884)
		(end 417.728654 -121.731278)
		(width 0.10795)
		(layer "B.Cu")
		(net "SMB_OCP_FRU_STBY_LVC3_SDA")
	)
	(segment
		(start 415.738056 -95.04172)
		(end 415.398458 -94.702122)
		(width 0.10795)
		(layer "B.Cu")
		(net "SMB_OCP_FRU_STBY_LVC3_SDA")
	)
	(segment
		(start 394.589 -84.709)
		(end 394.589 -85.0265)
		(width 0.10795)
		(layer "B.Cu")
		(net "SMB_OCP_FRU_STBY_LVC3_SDA")
	)
	(segment
		(start 413.4358 -88.06053)
		(end 413.4358 -87.210646)
		(width 0.10795)
		(layer "B.Cu")
		(net "SMB_OCP_FRU_STBY_LVC3_SDA")
	)
	(segment
		(start 417.868862 -121.59107)
		(end 417.868862 -121.590816)
		(width 0.10795)
		(layer "B.Cu")
		(net "SMB_OCP_FRU_STBY_LVC3_SDA")
	)
	(segment
		(start 407.582624 -84.732114)
		(end 409.757118 -84.732114)
		(width 0.10795)
		(layer "B.Cu")
		(net "SMB_OCP_FRU_STBY_LVC3_SDA")
	)
	(segment
		(start 417.868862 -120.107964)
		(end 417.869116 -120.10771)
		(width 0.10795)
		(layer "B.Cu")
		(net "SMB_OCP_FRU_STBY_LVC3_SDA")
	)
	(segment
		(start 412.076392 -85.851238)
		(end 411.616144 -85.851238)
		(width 0.10795)
		(layer "B.Cu")
		(net "SMB_OCP_FRU_STBY_LVC3_SDA")
	)
	(segment
		(start 415.398458 -90.458036)
		(end 414.947862 -90.00744)
		(width 0.10795)
		(layer "B.Cu")
		(net "SMB_OCP_FRU_STBY_LVC3_SDA")
	)
	(segment
		(start 417.869116 -120.674638)
		(end 417.868862 -120.674384)
		(width 0.10795)
		(layer "B.Cu")
		(net "SMB_OCP_FRU_STBY_LVC3_SDA")
	)
	(segment
		(start 411.616144 -85.851238)
		(end 411.453838 -86.013544)
		(width 0.10795)
		(layer "B.Cu")
		(net "SMB_OCP_FRU_STBY_LVC3_SDA")
	)
	(segment
		(start 407.154888 -85.15985)
		(end 407.582624 -84.732114)
		(width 0.10795)
		(layer "B.Cu")
		(net "SMB_OCP_FRU_STBY_LVC3_SDA")
	)
	(segment
		(start 400.834606 -37.8968)
		(end 400.75358 -37.977826)
		(width 0.10795)
		(layer "B.Cu")
		(net "SMB_OCP_FRU_STBY_LVC3_SDA")
	)
	(segment
		(start 413.592772 -72.253348)
		(end 413.376872 -72.037448)
		(width 0.089408)
		(layer "In2.Cu")
		(net "SMB_OCP_FRU_STBY_LVC3_SDA")
	)
	(segment
		(start 413.592772 -74.64425)
		(end 413.592772 -72.253348)
		(width 0.089408)
		(layer "In2.Cu")
		(net "SMB_OCP_FRU_STBY_LVC3_SDA")
	)
	(segment
		(start 414.093914 -75.678538)
		(end 414.093914 -75.52055)
		(width 0.089408)
		(layer "In2.Cu")
		(net "SMB_OCP_FRU_STBY_LVC3_SDA")
	)
	(segment
		(start 413.524954 -84.07146)
		(end 413.524954 -80.516222)
		(width 0.089408)
		(layer "In2.Cu")
		(net "SMB_OCP_FRU_STBY_LVC3_SDA")
	)
	(segment
		(start 414.094168 -75.145646)
		(end 413.592772 -74.64425)
		(width 0.089408)
		(layer "In2.Cu")
		(net "SMB_OCP_FRU_STBY_LVC3_SDA")
	)
	(segment
		(start 414.696148 -68.204842)
		(end 414.696148 -61.83503)
		(width 0.089408)
		(layer "In2.Cu")
		(net "SMB_OCP_FRU_STBY_LVC3_SDA")
	)
	(segment
		(start 434.814726 -54.762908)
		(end 436.408576 -56.356758)
		(width 0.089408)
		(layer "In2.Cu")
		(net "SMB_OCP_FRU_STBY_LVC3_SDA")
	)
	(segment
		(start 429.903382 -54.762908)
		(end 434.814726 -54.762908)
		(width 0.089408)
		(layer "In2.Cu")
		(net "SMB_OCP_FRU_STBY_LVC3_SDA")
	)
	(segment
		(start 417.743386 -60.717938)
		(end 422.557448 -55.903876)
		(width 0.089408)
		(layer "In2.Cu")
		(net "SMB_OCP_FRU_STBY_LVC3_SDA")
	)
	(segment
		(start 414.297368 -68.603622)
		(end 414.696148 -68.204842)
		(width 0.089408)
		(layer "In2.Cu")
		(net "SMB_OCP_FRU_STBY_LVC3_SDA")
	)
	(segment
		(start 414.094168 -79.183992)
		(end 414.093914 -79.183738)
		(width 0.089408)
		(layer "In2.Cu")
		(net "SMB_OCP_FRU_STBY_LVC3_SDA")
	)
	(segment
		(start 413.376618 -71.466964)
		(end 413.376872 -71.46671)
		(width 0.089408)
		(layer "In2.Cu")
		(net "SMB_OCP_FRU_STBY_LVC3_SDA")
	)
	(segment
		(start 414.093914 -79.183738)
		(end 414.093914 -79.02575)
		(width 0.089408)
		(layer "In2.Cu")
		(net "SMB_OCP_FRU_STBY_LVC3_SDA")
	)
	(segment
		(start 428.762414 -55.903876)
		(end 429.903382 -54.762908)
		(width 0.089408)
		(layer "In2.Cu")
		(net "SMB_OCP_FRU_STBY_LVC3_SDA")
	)
	(segment
		(start 414.094168 -79.947008)
		(end 414.094168 -79.183992)
		(width 0.089408)
		(layer "In2.Cu")
		(net "SMB_OCP_FRU_STBY_LVC3_SDA")
	)
	(segment
		(start 414.093914 -77.685138)
		(end 414.093914 -77.368654)
		(width 0.089408)
		(layer "In2.Cu")
		(net "SMB_OCP_FRU_STBY_LVC3_SDA")
	)
	(segment
		(start 414.094168 -75.678792)
		(end 414.093914 -75.678538)
		(width 0.089408)
		(layer "In2.Cu")
		(net "SMB_OCP_FRU_STBY_LVC3_SDA")
	)
	(segment
		(start 413.524954 -80.516222)
		(end 414.094168 -79.947008)
		(width 0.089408)
		(layer "In2.Cu")
		(net "SMB_OCP_FRU_STBY_LVC3_SDA")
	)
	(segment
		(start 414.093914 -75.52055)
		(end 414.094168 -75.520296)
		(width 0.089408)
		(layer "In2.Cu")
		(net "SMB_OCP_FRU_STBY_LVC3_SDA")
	)
	(segment
		(start 414.696148 -61.83503)
		(end 415.813494 -60.717684)
		(width 0.089408)
		(layer "In2.Cu")
		(net "SMB_OCP_FRU_STBY_LVC3_SDA")
	)
	(segment
		(start 411.453838 -86.013544)
		(end 411.583632 -86.013544)
		(width 0.089408)
		(layer "In2.Cu")
		(net "SMB_OCP_FRU_STBY_LVC3_SDA")
	)
	(segment
		(start 414.094168 -75.520296)
		(end 414.094168 -75.145646)
		(width 0.089408)
		(layer "In2.Cu")
		(net "SMB_OCP_FRU_STBY_LVC3_SDA")
	)
	(segment
		(start 413.49549 -84.100924)
		(end 413.524954 -84.07146)
		(width 0.089408)
		(layer "In2.Cu")
		(net "SMB_OCP_FRU_STBY_LVC3_SDA")
	)
	(segment
		(start 415.813494 -60.717684)
		(end 416.129978 -60.717684)
		(width 0.089408)
		(layer "In2.Cu")
		(net "SMB_OCP_FRU_STBY_LVC3_SDA")
	)
	(segment
		(start 413.376872 -70.817994)
		(end 414.297368 -69.897498)
		(width 0.089408)
		(layer "In2.Cu")
		(net "SMB_OCP_FRU_STBY_LVC3_SDA")
	)
	(segment
		(start 413.49549 -84.101686)
		(end 413.49549 -84.100924)
		(width 0.089408)
		(layer "In2.Cu")
		(net "SMB_OCP_FRU_STBY_LVC3_SDA")
	)
	(segment
		(start 414.093914 -79.02575)
		(end 414.094168 -79.025496)
		(width 0.089408)
		(layer "In2.Cu")
		(net "SMB_OCP_FRU_STBY_LVC3_SDA")
	)
	(segment
		(start 413.376872 -71.625206)
		(end 413.376618 -71.624952)
		(width 0.089408)
		(layer "In2.Cu")
		(net "SMB_OCP_FRU_STBY_LVC3_SDA")
	)
	(segment
		(start 416.130232 -60.717938)
		(end 417.743386 -60.717938)
		(width 0.089408)
		(layer "In2.Cu")
		(net "SMB_OCP_FRU_STBY_LVC3_SDA")
	)
	(segment
		(start 422.557448 -55.903876)
		(end 428.762414 -55.903876)
		(width 0.089408)
		(layer "In2.Cu")
		(net "SMB_OCP_FRU_STBY_LVC3_SDA")
	)
	(segment
		(start 413.376872 -72.037448)
		(end 413.376872 -71.625206)
		(width 0.089408)
		(layer "In2.Cu")
		(net "SMB_OCP_FRU_STBY_LVC3_SDA")
	)
	(segment
		(start 411.583632 -86.013544)
		(end 413.49549 -84.101686)
		(width 0.089408)
		(layer "In2.Cu")
		(net "SMB_OCP_FRU_STBY_LVC3_SDA")
	)
	(segment
		(start 458.745082 -58.911236)
		(end 458.745082 -59.076336)
		(width 0.089408)
		(layer "In2.Cu")
		(net "SMB_OCP_FRU_STBY_LVC3_SDA")
	)
	(segment
		(start 414.094168 -79.025496)
		(end 414.094168 -77.685392)
		(width 0.089408)
		(layer "In2.Cu")
		(net "SMB_OCP_FRU_STBY_LVC3_SDA")
	)
	(segment
		(start 456.190604 -56.356758)
		(end 458.745082 -58.911236)
		(width 0.089408)
		(layer "In2.Cu")
		(net "SMB_OCP_FRU_STBY_LVC3_SDA")
	)
	(segment
		(start 413.376872 -71.46671)
		(end 413.376872 -70.817994)
		(width 0.089408)
		(layer "In2.Cu")
		(net "SMB_OCP_FRU_STBY_LVC3_SDA")
	)
	(segment
		(start 416.129978 -60.717684)
		(end 416.130232 -60.717938)
		(width 0.089408)
		(layer "In2.Cu")
		(net "SMB_OCP_FRU_STBY_LVC3_SDA")
	)
	(segment
		(start 414.297368 -69.897498)
		(end 414.297368 -68.603622)
		(width 0.089408)
		(layer "In2.Cu")
		(net "SMB_OCP_FRU_STBY_LVC3_SDA")
	)
	(segment
		(start 436.408576 -56.356758)
		(end 456.190604 -56.356758)
		(width 0.089408)
		(layer "In2.Cu")
		(net "SMB_OCP_FRU_STBY_LVC3_SDA")
	)
	(segment
		(start 414.094168 -77.685392)
		(end 414.093914 -77.685138)
		(width 0.089408)
		(layer "In2.Cu")
		(net "SMB_OCP_FRU_STBY_LVC3_SDA")
	)
	(segment
		(start 413.376618 -71.624952)
		(end 413.376618 -71.466964)
		(width 0.089408)
		(layer "In2.Cu")
		(net "SMB_OCP_FRU_STBY_LVC3_SDA")
	)
	(segment
		(start 414.093914 -77.368654)
		(end 414.094168 -77.3684)
		(width 0.089408)
		(layer "In2.Cu")
		(net "SMB_OCP_FRU_STBY_LVC3_SDA")
	)
	(segment
		(start 414.094168 -77.3684)
		(end 414.094168 -75.678792)
		(width 0.089408)
		(layer "In2.Cu")
		(net "SMB_OCP_FRU_STBY_LVC3_SDA")
	)
	(segment
		(start 458.715872 -39.358062)
		(end 455.821288 -39.358062)
		(width 0.089408)
		(layer "In4.Cu")
		(net "SMB_OCP_FRU_STBY_LVC3_SDA")
	)
	(segment
		(start 430.073308 -39.468806)
		(end 427.793912 -39.468806)
		(width 0.089408)
		(layer "In4.Cu")
		(net "SMB_OCP_FRU_STBY_LVC3_SDA")
	)
	(segment
		(start 468.437722 -43.962574)
		(end 467.641432 -43.166284)
		(width 0.089408)
		(layer "In4.Cu")
		(net "SMB_OCP_FRU_STBY_LVC3_SDA")
	)
	(segment
		(start 471.816684 -51.599338)
		(end 471.658696 -51.44135)
		(width 0.089408)
		(layer "In4.Cu")
		(net "SMB_OCP_FRU_STBY_LVC3_SDA")
	)
	(segment
		(start 461.123538 -42.2021)
		(end 460.743808 -41.82237)
		(width 0.089408)
		(layer "In4.Cu")
		(net "SMB_OCP_FRU_STBY_LVC3_SDA")
	)
	(segment
		(start 467.641432 -43.166284)
		(end 467.641432 -42.840148)
		(width 0.089408)
		(layer "In4.Cu")
		(net "SMB_OCP_FRU_STBY_LVC3_SDA")
	)
	(segment
		(start 472.05138 -52.40909)
		(end 471.816684 -52.174394)
		(width 0.089408)
		(layer "In4.Cu")
		(net "SMB_OCP_FRU_STBY_LVC3_SDA")
	)
	(segment
		(start 421.920162 -43.444922)
		(end 419.085268 -43.444922)
		(width 0.089408)
		(layer "In4.Cu")
		(net "SMB_OCP_FRU_STBY_LVC3_SDA")
	)
	(segment
		(start 418.917628 -43.277282)
		(end 413.697674 -43.277282)
		(width 0.089408)
		(layer "In4.Cu")
		(net "SMB_OCP_FRU_STBY_LVC3_SDA")
	)
	(segment
		(start 425.837604 -41.425114)
		(end 423.93997 -41.425114)
		(width 0.089408)
		(layer "In4.Cu")
		(net "SMB_OCP_FRU_STBY_LVC3_SDA")
	)
	(segment
		(start 467.641432 -42.840148)
		(end 467.460584 -42.6593)
		(width 0.089408)
		(layer "In4.Cu")
		(net "SMB_OCP_FRU_STBY_LVC3_SDA")
	)
	(segment
		(start 406.587706 -40.715692)
		(end 403.551644 -40.715692)
		(width 0.089408)
		(layer "In4.Cu")
		(net "SMB_OCP_FRU_STBY_LVC3_SDA")
	)
	(segment
		(start 469.043512 -43.962574)
		(end 468.437722 -43.962574)
		(width 0.089408)
		(layer "In4.Cu")
		(net "SMB_OCP_FRU_STBY_LVC3_SDA")
	)
	(segment
		(start 471.816684 -52.174394)
		(end 471.816684 -51.599338)
		(width 0.089408)
		(layer "In4.Cu")
		(net "SMB_OCP_FRU_STBY_LVC3_SDA")
	)
	(segment
		(start 430.470818 -39.866316)
		(end 430.073308 -39.468806)
		(width 0.089408)
		(layer "In4.Cu")
		(net "SMB_OCP_FRU_STBY_LVC3_SDA")
	)
	(segment
		(start 463.856324 -42.2021)
		(end 461.123538 -42.2021)
		(width 0.089408)
		(layer "In4.Cu")
		(net "SMB_OCP_FRU_STBY_LVC3_SDA")
	)
	(segment
		(start 460.743808 -41.82237)
		(end 460.743808 -40.34917)
		(width 0.089408)
		(layer "In4.Cu")
		(net "SMB_OCP_FRU_STBY_LVC3_SDA")
	)
	(segment
		(start 460.743808 -40.34917)
		(end 460.414624 -40.019986)
		(width 0.089408)
		(layer "In4.Cu")
		(net "SMB_OCP_FRU_STBY_LVC3_SDA")
	)
	(segment
		(start 435.141116 -40.926004)
		(end 434.703728 -40.488616)
		(width 0.089408)
		(layer "In4.Cu")
		(net "SMB_OCP_FRU_STBY_LVC3_SDA")
	)
	(segment
		(start 460.414624 -40.019986)
		(end 459.377796 -40.019986)
		(width 0.089408)
		(layer "In4.Cu")
		(net "SMB_OCP_FRU_STBY_LVC3_SDA")
	)
	(segment
		(start 471.658696 -50.64125)
		(end 472.155266 -50.14468)
		(width 0.089408)
		(layer "In4.Cu")
		(net "SMB_OCP_FRU_STBY_LVC3_SDA")
	)
	(segment
		(start 413.697674 -43.277282)
		(end 413.676592 -43.298364)
		(width 0.089408)
		(layer "In4.Cu")
		(net "SMB_OCP_FRU_STBY_LVC3_SDA")
	)
	(segment
		(start 408.611832 -42.739818)
		(end 406.587706 -40.715692)
		(width 0.089408)
		(layer "In4.Cu")
		(net "SMB_OCP_FRU_STBY_LVC3_SDA")
	)
	(segment
		(start 472.155266 -49.218088)
		(end 470.6874 -47.750222)
		(width 0.089408)
		(layer "In4.Cu")
		(net "SMB_OCP_FRU_STBY_LVC3_SDA")
	)
	(segment
		(start 403.551644 -40.715692)
		(end 400.813778 -37.977826)
		(width 0.089408)
		(layer "In4.Cu")
		(net "SMB_OCP_FRU_STBY_LVC3_SDA")
	)
	(segment
		(start 454.964038 -40.215312)
		(end 451.100952 -40.215312)
		(width 0.089408)
		(layer "In4.Cu")
		(net "SMB_OCP_FRU_STBY_LVC3_SDA")
	)
	(segment
		(start 427.793912 -39.468806)
		(end 425.837604 -41.425114)
		(width 0.089408)
		(layer "In4.Cu")
		(net "SMB_OCP_FRU_STBY_LVC3_SDA")
	)
	(segment
		(start 472.155266 -50.14468)
		(end 472.155266 -49.218088)
		(width 0.089408)
		(layer "In4.Cu")
		(net "SMB_OCP_FRU_STBY_LVC3_SDA")
	)
	(segment
		(start 451.100952 -40.215312)
		(end 450.39026 -40.926004)
		(width 0.089408)
		(layer "In4.Cu")
		(net "SMB_OCP_FRU_STBY_LVC3_SDA")
	)
	(segment
		(start 419.085268 -43.444922)
		(end 418.917628 -43.277282)
		(width 0.089408)
		(layer "In4.Cu")
		(net "SMB_OCP_FRU_STBY_LVC3_SDA")
	)
	(segment
		(start 455.821288 -39.358062)
		(end 454.964038 -40.215312)
		(width 0.089408)
		(layer "In4.Cu")
		(net "SMB_OCP_FRU_STBY_LVC3_SDA")
	)
	(segment
		(start 434.703728 -40.488616)
		(end 433.576476 -40.488616)
		(width 0.089408)
		(layer "In4.Cu")
		(net "SMB_OCP_FRU_STBY_LVC3_SDA")
	)
	(segment
		(start 450.39026 -40.926004)
		(end 435.141116 -40.926004)
		(width 0.089408)
		(layer "In4.Cu")
		(net "SMB_OCP_FRU_STBY_LVC3_SDA")
	)
	(segment
		(start 410.735018 -42.739818)
		(end 408.611832 -42.739818)
		(width 0.089408)
		(layer "In4.Cu")
		(net "SMB_OCP_FRU_STBY_LVC3_SDA")
	)
	(segment
		(start 423.93997 -41.425114)
		(end 421.920162 -43.444922)
		(width 0.089408)
		(layer "In4.Cu")
		(net "SMB_OCP_FRU_STBY_LVC3_SDA")
	)
	(segment
		(start 470.6874 -45.606462)
		(end 469.043512 -43.962574)
		(width 0.089408)
		(layer "In4.Cu")
		(net "SMB_OCP_FRU_STBY_LVC3_SDA")
	)
	(segment
		(start 464.313524 -42.6593)
		(end 463.856324 -42.2021)
		(width 0.089408)
		(layer "In4.Cu")
		(net "SMB_OCP_FRU_STBY_LVC3_SDA")
	)
	(segment
		(start 411.293564 -43.298364)
		(end 410.735018 -42.739818)
		(width 0.089408)
		(layer "In4.Cu")
		(net "SMB_OCP_FRU_STBY_LVC3_SDA")
	)
	(segment
		(start 432.954176 -39.866316)
		(end 430.470818 -39.866316)
		(width 0.089408)
		(layer "In4.Cu")
		(net "SMB_OCP_FRU_STBY_LVC3_SDA")
	)
	(segment
		(start 470.6874 -47.750222)
		(end 470.6874 -45.606462)
		(width 0.089408)
		(layer "In4.Cu")
		(net "SMB_OCP_FRU_STBY_LVC3_SDA")
	)
	(segment
		(start 400.813778 -37.977826)
		(end 400.75358 -37.977826)
		(width 0.089408)
		(layer "In4.Cu")
		(net "SMB_OCP_FRU_STBY_LVC3_SDA")
	)
	(segment
		(start 467.460584 -42.6593)
		(end 464.313524 -42.6593)
		(width 0.089408)
		(layer "In4.Cu")
		(net "SMB_OCP_FRU_STBY_LVC3_SDA")
	)
	(segment
		(start 471.658696 -51.44135)
		(end 471.658696 -50.64125)
		(width 0.089408)
		(layer "In4.Cu")
		(net "SMB_OCP_FRU_STBY_LVC3_SDA")
	)
	(segment
		(start 433.576476 -40.488616)
		(end 432.954176 -39.866316)
		(width 0.089408)
		(layer "In4.Cu")
		(net "SMB_OCP_FRU_STBY_LVC3_SDA")
	)
	(segment
		(start 413.676592 -43.298364)
		(end 411.293564 -43.298364)
		(width 0.089408)
		(layer "In4.Cu")
		(net "SMB_OCP_FRU_STBY_LVC3_SDA")
	)
	(segment
		(start 459.377796 -40.019986)
		(end 458.715872 -39.358062)
		(width 0.089408)
		(layer "In4.Cu")
		(net "SMB_OCP_FRU_STBY_LVC3_SDA")
	)
	(segment
		(start 433.81168 -119.28348)
		(end 423.41292 -119.28348)
		(width 0.089408)
		(layer "In11.Cu")
		(net "SMB_OCP_FRU_STBY_LVC3_SDA")
	)
	(segment
		(start 475.29242 -114.19332)
		(end 475.29242 -114.599466)
		(width 0.089408)
		(layer "In11.Cu")
		(net "SMB_OCP_FRU_STBY_LVC3_SDA")
	)
	(segment
		(start 475.615 -115.485164)
		(end 475.37878 -115.721384)
		(width 0.089408)
		(layer "In11.Cu")
		(net "SMB_OCP_FRU_STBY_LVC3_SDA")
	)
	(segment
		(start 441.876942 -58.41365)
		(end 441.876942 -59.22264)
		(width 0.089408)
		(layer "In11.Cu")
		(net "SMB_OCP_FRU_STBY_LVC3_SDA")
	)
	(segment
		(start 458.745082 -59.076336)
		(end 459.59141 -58.230008)
		(width 0.089408)
		(layer "In11.Cu")
		(net "SMB_OCP_FRU_STBY_LVC3_SDA")
	)
	(segment
		(start 439.42 -115.05692)
		(end 438.19572 -116.2812)
		(width 0.089408)
		(layer "In11.Cu")
		(net "SMB_OCP_FRU_STBY_LVC3_SDA")
	)
	(segment
		(start 471.988896 -52.40909)
		(end 472.05138 -52.40909)
		(width 0.089408)
		(layer "In11.Cu")
		(net "SMB_OCP_FRU_STBY_LVC3_SDA")
	)
	(segment
		(start 470.853008 -56.065674)
		(end 470.853008 -53.544978)
		(width 0.089408)
		(layer "In11.Cu")
		(net "SMB_OCP_FRU_STBY_LVC3_SDA")
	)
	(segment
		(start 470.853008 -53.544978)
		(end 471.988896 -52.40909)
		(width 0.089408)
		(layer "In11.Cu")
		(net "SMB_OCP_FRU_STBY_LVC3_SDA")
	)
	(segment
		(start 439.42 -114.65052)
		(end 439.42 -115.05692)
		(width 0.089408)
		(layer "In11.Cu")
		(net "SMB_OCP_FRU_STBY_LVC3_SDA")
	)
	(segment
		(start 441.09386 -112.97666)
		(end 439.42 -114.65052)
		(width 0.089408)
		(layer "In11.Cu")
		(net "SMB_OCP_FRU_STBY_LVC3_SDA")
	)
	(segment
		(start 423.41292 -119.28348)
		(end 420.051992 -122.644408)
		(width 0.089408)
		(layer "In11.Cu")
		(net "SMB_OCP_FRU_STBY_LVC3_SDA")
	)
	(segment
		(start 441.876942 -59.22264)
		(end 441.921138 -59.266836)
		(width 0.089408)
		(layer "In11.Cu")
		(net "SMB_OCP_FRU_STBY_LVC3_SDA")
	)
	(segment
		(start 438.19572 -116.2812)
		(end 436.81396 -116.2812)
		(width 0.089408)
		(layer "In11.Cu")
		(net "SMB_OCP_FRU_STBY_LVC3_SDA")
	)
	(segment
		(start 458.192886 -59.628532)
		(end 456.94981 -59.628532)
		(width 0.089408)
		(layer "In11.Cu")
		(net "SMB_OCP_FRU_STBY_LVC3_SDA")
	)
	(segment
		(start 475.29242 -114.599466)
		(end 475.615 -114.922046)
		(width 0.089408)
		(layer "In11.Cu")
		(net "SMB_OCP_FRU_STBY_LVC3_SDA")
	)
	(segment
		(start 471.666062 -115.721384)
		(end 468.921338 -112.97666)
		(width 0.089408)
		(layer "In11.Cu")
		(net "SMB_OCP_FRU_STBY_LVC3_SDA")
	)
	(segment
		(start 436.81396 -116.2812)
		(end 433.81168 -119.28348)
		(width 0.089408)
		(layer "In11.Cu")
		(net "SMB_OCP_FRU_STBY_LVC3_SDA")
	)
	(segment
		(start 468.688674 -58.230008)
		(end 470.853008 -56.065674)
		(width 0.089408)
		(layer "In11.Cu")
		(net "SMB_OCP_FRU_STBY_LVC3_SDA")
	)
	(segment
		(start 468.921338 -112.97666)
		(end 441.09386 -112.97666)
		(width 0.089408)
		(layer "In11.Cu")
		(net "SMB_OCP_FRU_STBY_LVC3_SDA")
	)
	(segment
		(start 419.755574 -122.644408)
		(end 419.589204 -122.478038)
		(width 0.089408)
		(layer "In11.Cu")
		(net "SMB_OCP_FRU_STBY_LVC3_SDA")
	)
	(segment
		(start 458.745082 -59.076336)
		(end 458.192886 -59.628532)
		(width 0.089408)
		(layer "In11.Cu")
		(net "SMB_OCP_FRU_STBY_LVC3_SDA")
	)
	(segment
		(start 442.060584 -58.230008)
		(end 441.876942 -58.41365)
		(width 0.089408)
		(layer "In11.Cu")
		(net "SMB_OCP_FRU_STBY_LVC3_SDA")
	)
	(segment
		(start 456.94981 -59.628532)
		(end 455.551286 -58.230008)
		(width 0.089408)
		(layer "In11.Cu")
		(net "SMB_OCP_FRU_STBY_LVC3_SDA")
	)
	(segment
		(start 475.70644 -113.7793)
		(end 475.29242 -114.19332)
		(width 0.089408)
		(layer "In11.Cu")
		(net "SMB_OCP_FRU_STBY_LVC3_SDA")
	)
	(segment
		(start 420.051992 -122.644408)
		(end 419.755574 -122.644408)
		(width 0.089408)
		(layer "In11.Cu")
		(net "SMB_OCP_FRU_STBY_LVC3_SDA")
	)
	(segment
		(start 455.551286 -58.230008)
		(end 442.060584 -58.230008)
		(width 0.089408)
		(layer "In11.Cu")
		(net "SMB_OCP_FRU_STBY_LVC3_SDA")
	)
	(segment
		(start 475.37878 -115.721384)
		(end 471.666062 -115.721384)
		(width 0.089408)
		(layer "In11.Cu")
		(net "SMB_OCP_FRU_STBY_LVC3_SDA")
	)
	(segment
		(start 475.615 -114.922046)
		(end 475.615 -115.485164)
		(width 0.089408)
		(layer "In11.Cu")
		(net "SMB_OCP_FRU_STBY_LVC3_SDA")
	)
	(segment
		(start 459.59141 -58.230008)
		(end 468.688674 -58.230008)
		(width 0.089408)
		(layer "In11.Cu")
		(net "SMB_OCP_FRU_STBY_LVC3_SDA")
	)
	(segment
		(start 408.690064 -36.934648)
		(end 409.10383 -36.520882)
		(width 0.10795)
		(layer "F.Cu")
		(net "SMB_OCP_FRU_STBY_LVC3_SCL_R")
	)
	(via
		(at 409.10383 -36.520882)
		(size 0.4572)
		(drill 0.2032)
		(layers "F.Cu" "B.Cu")
		(net "SMB_OCP_FRU_STBY_LVC3_SCL_R")
	)
	(via
		(at 403.5044 -38.227)
		(size 0.6604)
		(drill 0.3302)
		(layers "F.Cu" "B.Cu")
		(net "SMB_OCP_FRU_STBY_LVC3_SCL_R")
	)
	(segment
		(start 403.5044 -38.227)
		(end 402.971 -38.7604)
		(width 0.10795)
		(layer "B.Cu")
		(net "SMB_OCP_FRU_STBY_LVC3_SCL_R")
	)
	(segment
		(start 408.088846 -36.918646)
		(end 407.713942 -36.543742)
		(width 0.10795)
		(layer "B.Cu")
		(net "SMB_OCP_FRU_STBY_LVC3_SCL_R")
	)
	(segment
		(start 408.546554 -36.918646)
		(end 408.088846 -36.918646)
		(width 0.10795)
		(layer "B.Cu")
		(net "SMB_OCP_FRU_STBY_LVC3_SCL_R")
	)
	(segment
		(start 402.971 -38.7604)
		(end 402.4503 -38.7604)
		(width 0.10795)
		(layer "B.Cu")
		(net "SMB_OCP_FRU_STBY_LVC3_SCL_R")
	)
	(segment
		(start 404.920704 -36.815776)
		(end 404.920704 -37.317426)
		(width 0.10795)
		(layer "B.Cu")
		(net "SMB_OCP_FRU_STBY_LVC3_SCL_R")
	)
	(segment
		(start 404.378414 -37.859716)
		(end 403.871684 -37.859716)
		(width 0.10795)
		(layer "B.Cu")
		(net "SMB_OCP_FRU_STBY_LVC3_SCL_R")
	)
	(segment
		(start 409.10383 -36.520882)
		(end 408.944318 -36.520882)
		(width 0.10795)
		(layer "B.Cu")
		(net "SMB_OCP_FRU_STBY_LVC3_SCL_R")
	)
	(segment
		(start 403.871684 -37.859716)
		(end 403.5044 -38.227)
		(width 0.10795)
		(layer "B.Cu")
		(net "SMB_OCP_FRU_STBY_LVC3_SCL_R")
	)
	(segment
		(start 402.4503 -39.5224)
		(end 402.4503 -38.7604)
		(width 0.10795)
		(layer "B.Cu")
		(net "SMB_OCP_FRU_STBY_LVC3_SCL_R")
	)
	(segment
		(start 408.944318 -36.520882)
		(end 408.546554 -36.918646)
		(width 0.10795)
		(layer "B.Cu")
		(net "SMB_OCP_FRU_STBY_LVC3_SCL_R")
	)
	(segment
		(start 404.920704 -37.317426)
		(end 404.378414 -37.859716)
		(width 0.10795)
		(layer "B.Cu")
		(net "SMB_OCP_FRU_STBY_LVC3_SCL_R")
	)
	(segment
		(start 407.713942 -36.543742)
		(end 405.192738 -36.543742)
		(width 0.10795)
		(layer "B.Cu")
		(net "SMB_OCP_FRU_STBY_LVC3_SCL_R")
	)
	(segment
		(start 405.192738 -36.543742)
		(end 404.920704 -36.815776)
		(width 0.10795)
		(layer "B.Cu")
		(net "SMB_OCP_FRU_STBY_LVC3_SCL_R")
	)
	(segment
		(start 441.159138 -59.266836)
		(end 441.159138 -59.017916)
		(width 0.10795)
		(layer "F.Cu")
		(net "SMB_OCP_FRU_STBY_LVC3_SCL")
	)
	(segment
		(start 419.958012 -122.74042)
		(end 420.779194 -122.74042)
		(width 0.10795)
		(layer "F.Cu")
		(net "SMB_OCP_FRU_STBY_LVC3_SCL")
	)
	(segment
		(start 441.159138 -59.017916)
		(end 440.550046 -58.408824)
		(width 0.10795)
		(layer "F.Cu")
		(net "SMB_OCP_FRU_STBY_LVC3_SCL")
	)
	(segment
		(start 419.574218 -123.124214)
		(end 419.958012 -122.74042)
		(width 0.10795)
		(layer "F.Cu")
		(net "SMB_OCP_FRU_STBY_LVC3_SCL")
	)
	(segment
		(start 440.550046 -58.408824)
		(end 440.550046 -57.596024)
		(width 0.10795)
		(layer "F.Cu")
		(net "SMB_OCP_FRU_STBY_LVC3_SCL")
	)
	(segment
		(start 476.601028 -113.545112)
		(end 476.601028 -112.205516)
		(width 0.10795)
		(layer "F.Cu")
		(net "SMB_OCP_FRU_STBY_LVC3_SCL")
	)
	(segment
		(start 475.70644 -114.4397)
		(end 476.601028 -113.545112)
		(width 0.10795)
		(layer "F.Cu")
		(net "SMB_OCP_FRU_STBY_LVC3_SCL")
	)
	(via
		(at 411.453838 -86.648544)
		(size 0.508)
		(drill 0.254)
		(layers "F.Cu" "B.Cu")
		(net "SMB_OCP_FRU_STBY_LVC3_SCL")
	)
	(via
		(at 441.159138 -59.266836)
		(size 0.508)
		(drill 0.254)
		(layers "F.Cu" "B.Cu")
		(net "SMB_OCP_FRU_STBY_LVC3_SCL")
	)
	(via
		(at 407.69286 -85.345016)
		(size 0.6604)
		(drill 0.3302)
		(layers "F.Cu" "B.Cu")
		(net "SMB_OCP_FRU_STBY_LVC3_SCL")
	)
	(via
		(at 475.70644 -114.4397)
		(size 0.508)
		(drill 0.254)
		(layers "F.Cu" "B.Cu")
		(net "SMB_OCP_FRU_STBY_LVC3_SCL")
	)
	(via
		(at 458.03312 -59.083194)
		(size 0.508)
		(drill 0.254)
		(layers "F.Cu" "B.Cu")
		(net "SMB_OCP_FRU_STBY_LVC3_SCL")
	)
	(via
		(at 400.7993 -38.7604)
		(size 0.508)
		(drill 0.254)
		(layers "F.Cu" "B.Cu")
		(net "SMB_OCP_FRU_STBY_LVC3_SCL")
	)
	(via
		(at 419.574218 -123.124214)
		(size 0.508)
		(drill 0.254)
		(layers "F.Cu" "B.Cu")
		(net "SMB_OCP_FRU_STBY_LVC3_SCL")
	)
	(via
		(at 471.34018 -52.43322)
		(size 0.508)
		(drill 0.254)
		(layers "F.Cu" "B.Cu")
		(net "SMB_OCP_FRU_STBY_LVC3_SCL")
	)
	(segment
		(start 414.712912 -89.13114)
		(end 414.202372 -88.6206)
		(width 0.10795)
		(layer "B.Cu")
		(net "SMB_OCP_FRU_STBY_LVC3_SCL")
	)
	(segment
		(start 414.712912 -90.104976)
		(end 414.712912 -89.13114)
		(width 0.10795)
		(layer "B.Cu")
		(net "SMB_OCP_FRU_STBY_LVC3_SCL")
	)
	(segment
		(start 417.633912 -121.493534)
		(end 417.633912 -121.49328)
		(width 0.10795)
		(layer "B.Cu")
		(net "SMB_OCP_FRU_STBY_LVC3_SCL")
	)
	(segment
		(start 415.775394 -116.689124)
		(end 415.775648 -116.68887)
		(width 0.10795)
		(layer "B.Cu")
		(net "SMB_OCP_FRU_STBY_LVC3_SCL")
	)
	(segment
		(start 415.503106 -95.17507)
		(end 415.163508 -94.835472)
		(width 0.10795)
		(layer "B.Cu")
		(net "SMB_OCP_FRU_STBY_LVC3_SCL")
	)
	(segment
		(start 407.999184 -85.038692)
		(end 409.695396 -85.038692)
		(width 0.10795)
		(layer "B.Cu")
		(net "SMB_OCP_FRU_STBY_LVC3_SCL")
	)
	(segment
		(start 417.493704 -122.48642)
		(end 417.493704 -121.633742)
		(width 0.10795)
		(layer "B.Cu")
		(net "SMB_OCP_FRU_STBY_LVC3_SCL")
	)
	(segment
		(start 395.810994 -84.096606)
		(end 395.81836 -84.08924)
		(width 0.10795)
		(layer "B.Cu")
		(net "SMB_OCP_FRU_STBY_LVC3_SCL")
	)
	(segment
		(start 415.775648 -116.68887)
		(end 415.775648 -109.027722)
		(width 0.10795)
		(layer "B.Cu")
		(net "SMB_OCP_FRU_STBY_LVC3_SCL")
	)
	(segment
		(start 395.81836 -83.447128)
		(end 396.07109 -83.194398)
		(width 0.10795)
		(layer "B.Cu")
		(net "SMB_OCP_FRU_STBY_LVC3_SCL")
	)
	(segment
		(start 413.62757 -88.6206)
		(end 413.17545 -88.16848)
		(width 0.10795)
		(layer "B.Cu")
		(net "SMB_OCP_FRU_STBY_LVC3_SCL")
	)
	(segment
		(start 415.775648 -117.066314)
		(end 415.775648 -116.883942)
		(width 0.10795)
		(layer "B.Cu")
		(net "SMB_OCP_FRU_STBY_LVC3_SCL")
	)
	(segment
		(start 415.775648 -109.027722)
		(end 417.344606 -107.458764)
		(width 0.10795)
		(layer "B.Cu")
		(net "SMB_OCP_FRU_STBY_LVC3_SCL")
	)
	(segment
		(start 409.695396 -85.038692)
		(end 411.305248 -86.648544)
		(width 0.10795)
		(layer "B.Cu")
		(net "SMB_OCP_FRU_STBY_LVC3_SCL")
	)
	(segment
		(start 398.164812 -83.194398)
		(end 400.365214 -85.3948)
		(width 0.10795)
		(layer "B.Cu")
		(net "SMB_OCP_FRU_STBY_LVC3_SCL")
	)
	(segment
		(start 395.351 -84.676234)
		(end 395.810994 -84.21624)
		(width 0.10795)
		(layer "B.Cu")
		(net "SMB_OCP_FRU_STBY_LVC3_SCL")
	)
	(segment
		(start 396.07109 -83.194398)
		(end 398.164812 -83.194398)
		(width 0.10795)
		(layer "B.Cu")
		(net "SMB_OCP_FRU_STBY_LVC3_SCL")
	)
	(segment
		(start 407.643076 -85.3948)
		(end 407.69286 -85.345016)
		(width 0.10795)
		(layer "B.Cu")
		(net "SMB_OCP_FRU_STBY_LVC3_SCL")
	)
	(segment
		(start 417.344606 -104.190546)
		(end 415.503106 -102.349046)
		(width 0.10795)
		(layer "B.Cu")
		(net "SMB_OCP_FRU_STBY_LVC3_SCL")
	)
	(segment
		(start 417.344606 -107.458764)
		(end 417.344606 -104.190546)
		(width 0.10795)
		(layer "B.Cu")
		(net "SMB_OCP_FRU_STBY_LVC3_SCL")
	)
	(segment
		(start 417.633912 -120.77192)
		(end 417.633912 -118.924578)
		(width 0.10795)
		(layer "B.Cu")
		(net "SMB_OCP_FRU_STBY_LVC3_SCL")
	)
	(segment
		(start 395.351 -85.0265)
		(end 395.351 -84.676234)
		(width 0.10795)
		(layer "B.Cu")
		(net "SMB_OCP_FRU_STBY_LVC3_SCL")
	)
	(segment
		(start 401.5613 -38.7604)
		(end 400.7993 -38.7604)
		(width 0.10795)
		(layer "B.Cu")
		(net "SMB_OCP_FRU_STBY_LVC3_SCL")
	)
	(segment
		(start 417.633912 -121.49328)
		(end 417.634166 -121.493026)
		(width 0.10795)
		(layer "B.Cu")
		(net "SMB_OCP_FRU_STBY_LVC3_SCL")
	)
	(segment
		(start 412.368492 -86.511638)
		(end 411.590744 -86.511638)
		(width 0.10795)
		(layer "B.Cu")
		(net "SMB_OCP_FRU_STBY_LVC3_SCL")
	)
	(segment
		(start 415.503106 -102.349046)
		(end 415.503106 -95.17507)
		(width 0.10795)
		(layer "B.Cu")
		(net "SMB_OCP_FRU_STBY_LVC3_SCL")
	)
	(segment
		(start 400.365214 -85.3948)
		(end 407.643076 -85.3948)
		(width 0.10795)
		(layer "B.Cu")
		(net "SMB_OCP_FRU_STBY_LVC3_SCL")
	)
	(segment
		(start 411.590744 -86.511638)
		(end 411.453838 -86.648544)
		(width 0.10795)
		(layer "B.Cu")
		(net "SMB_OCP_FRU_STBY_LVC3_SCL")
	)
	(segment
		(start 395.810994 -84.21624)
		(end 395.810994 -84.096606)
		(width 0.10795)
		(layer "B.Cu")
		(net "SMB_OCP_FRU_STBY_LVC3_SCL")
	)
	(segment
		(start 419.574218 -123.124214)
		(end 419.360604 -122.9106)
		(width 0.10795)
		(layer "B.Cu")
		(net "SMB_OCP_FRU_STBY_LVC3_SCL")
	)
	(segment
		(start 417.917884 -122.9106)
		(end 417.493704 -122.48642)
		(width 0.10795)
		(layer "B.Cu")
		(net "SMB_OCP_FRU_STBY_LVC3_SCL")
	)
	(segment
		(start 417.634166 -121.493026)
		(end 417.634166 -120.772174)
		(width 0.10795)
		(layer "B.Cu")
		(net "SMB_OCP_FRU_STBY_LVC3_SCL")
	)
	(segment
		(start 417.634166 -120.772174)
		(end 417.633912 -120.77192)
		(width 0.10795)
		(layer "B.Cu")
		(net "SMB_OCP_FRU_STBY_LVC3_SCL")
	)
	(segment
		(start 395.81836 -84.08924)
		(end 395.81836 -83.447128)
		(width 0.10795)
		(layer "B.Cu")
		(net "SMB_OCP_FRU_STBY_LVC3_SCL")
	)
	(segment
		(start 417.493704 -121.633742)
		(end 417.633912 -121.493534)
		(width 0.10795)
		(layer "B.Cu")
		(net "SMB_OCP_FRU_STBY_LVC3_SCL")
	)
	(segment
		(start 415.775648 -116.883942)
		(end 415.775394 -116.883688)
		(width 0.10795)
		(layer "B.Cu")
		(net "SMB_OCP_FRU_STBY_LVC3_SCL")
	)
	(segment
		(start 413.17545 -88.16848)
		(end 413.17545 -87.318596)
		(width 0.10795)
		(layer "B.Cu")
		(net "SMB_OCP_FRU_STBY_LVC3_SCL")
	)
	(segment
		(start 415.163508 -90.555572)
		(end 414.712912 -90.104976)
		(width 0.10795)
		(layer "B.Cu")
		(net "SMB_OCP_FRU_STBY_LVC3_SCL")
	)
	(segment
		(start 415.163508 -94.835472)
		(end 415.163508 -90.555572)
		(width 0.10795)
		(layer "B.Cu")
		(net "SMB_OCP_FRU_STBY_LVC3_SCL")
	)
	(segment
		(start 415.775394 -116.883688)
		(end 415.775394 -116.689124)
		(width 0.10795)
		(layer "B.Cu")
		(net "SMB_OCP_FRU_STBY_LVC3_SCL")
	)
	(segment
		(start 407.69286 -85.345016)
		(end 407.999184 -85.038692)
		(width 0.10795)
		(layer "B.Cu")
		(net "SMB_OCP_FRU_STBY_LVC3_SCL")
	)
	(segment
		(start 411.305248 -86.648544)
		(end 411.453838 -86.648544)
		(width 0.10795)
		(layer "B.Cu")
		(net "SMB_OCP_FRU_STBY_LVC3_SCL")
	)
	(segment
		(start 417.633912 -118.924578)
		(end 415.775648 -117.066314)
		(width 0.10795)
		(layer "B.Cu")
		(net "SMB_OCP_FRU_STBY_LVC3_SCL")
	)
	(segment
		(start 413.17545 -87.318596)
		(end 412.368492 -86.511638)
		(width 0.10795)
		(layer "B.Cu")
		(net "SMB_OCP_FRU_STBY_LVC3_SCL")
	)
	(segment
		(start 419.360604 -122.9106)
		(end 417.917884 -122.9106)
		(width 0.10795)
		(layer "B.Cu")
		(net "SMB_OCP_FRU_STBY_LVC3_SCL")
	)
	(segment
		(start 414.202372 -88.6206)
		(end 413.62757 -88.6206)
		(width 0.10795)
		(layer "B.Cu")
		(net "SMB_OCP_FRU_STBY_LVC3_SCL")
	)
	(segment
		(start 414.887156 -68.28409)
		(end 414.488376 -68.68287)
		(width 0.089408)
		(layer "In2.Cu")
		(net "SMB_OCP_FRU_STBY_LVC3_SCL")
	)
	(segment
		(start 414.285176 -77.447648)
		(end 414.284922 -77.447902)
		(width 0.089408)
		(layer "In2.Cu")
		(net "SMB_OCP_FRU_STBY_LVC3_SCL")
	)
	(segment
		(start 422.636696 -56.094884)
		(end 417.822634 -60.908946)
		(width 0.089408)
		(layer "In2.Cu")
		(net "SMB_OCP_FRU_STBY_LVC3_SCL")
	)
	(segment
		(start 434.735478 -54.953916)
		(end 429.98263 -54.953916)
		(width 0.089408)
		(layer "In2.Cu")
		(net "SMB_OCP_FRU_STBY_LVC3_SCL")
	)
	(segment
		(start 458.03312 -58.753502)
		(end 455.861928 -56.58231)
		(width 0.089408)
		(layer "In2.Cu")
		(net "SMB_OCP_FRU_STBY_LVC3_SCL")
	)
	(segment
		(start 458.03312 -59.083194)
		(end 458.03312 -58.753502)
		(width 0.089408)
		(layer "In2.Cu")
		(net "SMB_OCP_FRU_STBY_LVC3_SCL")
	)
	(segment
		(start 416.050984 -60.908946)
		(end 416.05073 -60.908692)
		(width 0.089408)
		(layer "In2.Cu")
		(net "SMB_OCP_FRU_STBY_LVC3_SCL")
	)
	(segment
		(start 414.285176 -80.026256)
		(end 413.715962 -80.59547)
		(width 0.089408)
		(layer "In2.Cu")
		(net "SMB_OCP_FRU_STBY_LVC3_SCL")
	)
	(segment
		(start 413.715962 -84.150708)
		(end 413.686498 -84.180172)
		(width 0.089408)
		(layer "In2.Cu")
		(net "SMB_OCP_FRU_STBY_LVC3_SCL")
	)
	(segment
		(start 417.822634 -60.908946)
		(end 416.050984 -60.908946)
		(width 0.089408)
		(layer "In2.Cu")
		(net "SMB_OCP_FRU_STBY_LVC3_SCL")
	)
	(segment
		(start 411.453838 -86.57971)
		(end 411.453838 -86.648544)
		(width 0.089408)
		(layer "In2.Cu")
		(net "SMB_OCP_FRU_STBY_LVC3_SCL")
	)
	(segment
		(start 411.8864 -86.147148)
		(end 411.453838 -86.57971)
		(width 0.089408)
		(layer "In2.Cu")
		(net "SMB_OCP_FRU_STBY_LVC3_SCL")
	)
	(segment
		(start 428.841662 -56.094884)
		(end 422.636696 -56.094884)
		(width 0.089408)
		(layer "In2.Cu")
		(net "SMB_OCP_FRU_STBY_LVC3_SCL")
	)
	(segment
		(start 411.8864 -85.981032)
		(end 411.8864 -86.147148)
		(width 0.089408)
		(layer "In2.Cu")
		(net "SMB_OCP_FRU_STBY_LVC3_SCL")
	)
	(segment
		(start 414.285176 -77.606144)
		(end 414.285176 -80.026256)
		(width 0.089408)
		(layer "In2.Cu")
		(net "SMB_OCP_FRU_STBY_LVC3_SCL")
	)
	(segment
		(start 414.488376 -68.68287)
		(end 414.488376 -69.976746)
		(width 0.089408)
		(layer "In2.Cu")
		(net "SMB_OCP_FRU_STBY_LVC3_SCL")
	)
	(segment
		(start 414.284922 -77.447902)
		(end 414.284922 -77.60589)
		(width 0.089408)
		(layer "In2.Cu")
		(net "SMB_OCP_FRU_STBY_LVC3_SCL")
	)
	(segment
		(start 413.56788 -70.897242)
		(end 413.56788 -71.9582)
		(width 0.089408)
		(layer "In2.Cu")
		(net "SMB_OCP_FRU_STBY_LVC3_SCL")
	)
	(segment
		(start 413.686498 -84.180934)
		(end 411.8864 -85.981032)
		(width 0.089408)
		(layer "In2.Cu")
		(net "SMB_OCP_FRU_STBY_LVC3_SCL")
	)
	(segment
		(start 414.285176 -75.066398)
		(end 414.285176 -77.447648)
		(width 0.089408)
		(layer "In2.Cu")
		(net "SMB_OCP_FRU_STBY_LVC3_SCL")
	)
	(segment
		(start 413.715962 -80.59547)
		(end 413.715962 -84.150708)
		(width 0.089408)
		(layer "In2.Cu")
		(net "SMB_OCP_FRU_STBY_LVC3_SCL")
	)
	(segment
		(start 413.78378 -72.1741)
		(end 413.78378 -74.565002)
		(width 0.089408)
		(layer "In2.Cu")
		(net "SMB_OCP_FRU_STBY_LVC3_SCL")
	)
	(segment
		(start 415.892742 -60.908692)
		(end 414.887156 -61.914278)
		(width 0.089408)
		(layer "In2.Cu")
		(net "SMB_OCP_FRU_STBY_LVC3_SCL")
	)
	(segment
		(start 429.98263 -54.953916)
		(end 428.841662 -56.094884)
		(width 0.089408)
		(layer "In2.Cu")
		(net "SMB_OCP_FRU_STBY_LVC3_SCL")
	)
	(segment
		(start 416.05073 -60.908692)
		(end 415.892742 -60.908692)
		(width 0.089408)
		(layer "In2.Cu")
		(net "SMB_OCP_FRU_STBY_LVC3_SCL")
	)
	(segment
		(start 414.488376 -69.976746)
		(end 413.56788 -70.897242)
		(width 0.089408)
		(layer "In2.Cu")
		(net "SMB_OCP_FRU_STBY_LVC3_SCL")
	)
	(segment
		(start 414.887156 -61.914278)
		(end 414.887156 -68.28409)
		(width 0.089408)
		(layer "In2.Cu")
		(net "SMB_OCP_FRU_STBY_LVC3_SCL")
	)
	(segment
		(start 413.686498 -84.180172)
		(end 413.686498 -84.180934)
		(width 0.089408)
		(layer "In2.Cu")
		(net "SMB_OCP_FRU_STBY_LVC3_SCL")
	)
	(segment
		(start 413.56788 -71.9582)
		(end 413.78378 -72.1741)
		(width 0.089408)
		(layer "In2.Cu")
		(net "SMB_OCP_FRU_STBY_LVC3_SCL")
	)
	(segment
		(start 413.78378 -74.565002)
		(end 414.285176 -75.066398)
		(width 0.089408)
		(layer "In2.Cu")
		(net "SMB_OCP_FRU_STBY_LVC3_SCL")
	)
	(segment
		(start 414.284922 -77.60589)
		(end 414.285176 -77.606144)
		(width 0.089408)
		(layer "In2.Cu")
		(net "SMB_OCP_FRU_STBY_LVC3_SCL")
	)
	(segment
		(start 436.363872 -56.58231)
		(end 434.735478 -54.953916)
		(width 0.089408)
		(layer "In2.Cu")
		(net "SMB_OCP_FRU_STBY_LVC3_SCL")
	)
	(segment
		(start 455.861928 -56.58231)
		(end 436.363872 -56.58231)
		(width 0.089408)
		(layer "In2.Cu")
		(net "SMB_OCP_FRU_STBY_LVC3_SCL")
	)
	(segment
		(start 471.719402 -49.124108)
		(end 471.598244 -49.00295)
		(width 0.089408)
		(layer "In4.Cu")
		(net "SMB_OCP_FRU_STBY_LVC3_SCL")
	)
	(segment
		(start 427.898306 -39.659814)
		(end 426.338238 -41.219882)
		(width 0.089408)
		(layer "In4.Cu")
		(net "SMB_OCP_FRU_STBY_LVC3_SCL")
	)
	(segment
		(start 471.913458 -49.318418)
		(end 471.720164 -49.125124)
		(width 0.089408)
		(layer "In4.Cu")
		(net "SMB_OCP_FRU_STBY_LVC3_SCL")
	)
	(segment
		(start 435.061868 -41.117012)
		(end 434.633116 -40.68826)
		(width 0.089408)
		(layer "In4.Cu")
		(net "SMB_OCP_FRU_STBY_LVC3_SCL")
	)
	(segment
		(start 413.751776 -43.493182)
		(end 411.183328 -43.493182)
		(width 0.089408)
		(layer "In4.Cu")
		(net "SMB_OCP_FRU_STBY_LVC3_SCL")
	)
	(segment
		(start 460.502 -40.4495)
		(end 460.314294 -40.261794)
		(width 0.089408)
		(layer "In4.Cu")
		(net "SMB_OCP_FRU_STBY_LVC3_SCL")
	)
	(segment
		(start 450.469508 -41.117012)
		(end 435.061868 -41.117012)
		(width 0.089408)
		(layer "In4.Cu")
		(net "SMB_OCP_FRU_STBY_LVC3_SCL")
	)
	(segment
		(start 471.574876 -51.712876)
		(end 471.416888 -51.554888)
		(width 0.089408)
		(layer "In4.Cu")
		(net "SMB_OCP_FRU_STBY_LVC3_SCL")
	)
	(segment
		(start 430.39157 -40.057324)
		(end 429.99406 -39.659814)
		(width 0.089408)
		(layer "In4.Cu")
		(net "SMB_OCP_FRU_STBY_LVC3_SCL")
	)
	(segment
		(start 471.416888 -51.554888)
		(end 471.416888 -50.553112)
		(width 0.089408)
		(layer "In4.Cu")
		(net "SMB_OCP_FRU_STBY_LVC3_SCL")
	)
	(segment
		(start 434.633116 -40.68826)
		(end 433.49926 -40.68826)
		(width 0.089408)
		(layer "In4.Cu")
		(net "SMB_OCP_FRU_STBY_LVC3_SCL")
	)
	(segment
		(start 468.358474 -44.153582)
		(end 467.450424 -43.245532)
		(width 0.089408)
		(layer "In4.Cu")
		(net "SMB_OCP_FRU_STBY_LVC3_SCL")
	)
	(segment
		(start 468.892382 -44.153582)
		(end 468.358474 -44.153582)
		(width 0.089408)
		(layer "In4.Cu")
		(net "SMB_OCP_FRU_STBY_LVC3_SCL")
	)
	(segment
		(start 471.416888 -50.553112)
		(end 471.913458 -50.056288)
		(width 0.089408)
		(layer "In4.Cu")
		(net "SMB_OCP_FRU_STBY_LVC3_SCL")
	)
	(segment
		(start 461.023208 -42.443908)
		(end 460.502 -41.9227)
		(width 0.089408)
		(layer "In4.Cu")
		(net "SMB_OCP_FRU_STBY_LVC3_SCL")
	)
	(segment
		(start 460.314294 -40.261794)
		(end 459.193138 -40.261794)
		(width 0.089408)
		(layer "In4.Cu")
		(net "SMB_OCP_FRU_STBY_LVC3_SCL")
	)
	(segment
		(start 451.1802 -40.40632)
		(end 450.469508 -41.117012)
		(width 0.089408)
		(layer "In4.Cu")
		(net "SMB_OCP_FRU_STBY_LVC3_SCL")
	)
	(segment
		(start 410.671772 -42.981626)
		(end 408.511502 -42.981626)
		(width 0.089408)
		(layer "In4.Cu")
		(net "SMB_OCP_FRU_STBY_LVC3_SCL")
	)
	(segment
		(start 408.511502 -42.981626)
		(end 406.487376 -40.9575)
		(width 0.089408)
		(layer "In4.Cu")
		(net "SMB_OCP_FRU_STBY_LVC3_SCL")
	)
	(segment
		(start 467.450424 -42.991278)
		(end 467.360254 -42.901108)
		(width 0.089408)
		(layer "In4.Cu")
		(net "SMB_OCP_FRU_STBY_LVC3_SCL")
	)
	(segment
		(start 458.531214 -39.59987)
		(end 455.849736 -39.59987)
		(width 0.089408)
		(layer "In4.Cu")
		(net "SMB_OCP_FRU_STBY_LVC3_SCL")
	)
	(segment
		(start 460.502 -41.9227)
		(end 460.502 -40.4495)
		(width 0.089408)
		(layer "In4.Cu")
		(net "SMB_OCP_FRU_STBY_LVC3_SCL")
	)
	(segment
		(start 467.450424 -43.245532)
		(end 467.450424 -42.991278)
		(width 0.089408)
		(layer "In4.Cu")
		(net "SMB_OCP_FRU_STBY_LVC3_SCL")
	)
	(segment
		(start 411.183328 -43.493182)
		(end 410.671772 -42.981626)
		(width 0.089408)
		(layer "In4.Cu")
		(net "SMB_OCP_FRU_STBY_LVC3_SCL")
	)
	(segment
		(start 421.99941 -43.635676)
		(end 418.99332 -43.635676)
		(width 0.089408)
		(layer "In4.Cu")
		(net "SMB_OCP_FRU_STBY_LVC3_SCL")
	)
	(segment
		(start 471.913458 -50.056288)
		(end 471.913458 -49.318418)
		(width 0.089408)
		(layer "In4.Cu")
		(net "SMB_OCP_FRU_STBY_LVC3_SCL")
	)
	(segment
		(start 432.868324 -40.057324)
		(end 430.39157 -40.057324)
		(width 0.089408)
		(layer "In4.Cu")
		(net "SMB_OCP_FRU_STBY_LVC3_SCL")
	)
	(segment
		(start 464.25993 -42.901108)
		(end 463.80273 -42.443908)
		(width 0.089408)
		(layer "In4.Cu")
		(net "SMB_OCP_FRU_STBY_LVC3_SCL")
	)
	(segment
		(start 463.80273 -42.443908)
		(end 461.023208 -42.443908)
		(width 0.089408)
		(layer "In4.Cu")
		(net "SMB_OCP_FRU_STBY_LVC3_SCL")
	)
	(segment
		(start 418.99332 -43.635676)
		(end 418.82568 -43.468036)
		(width 0.089408)
		(layer "In4.Cu")
		(net "SMB_OCP_FRU_STBY_LVC3_SCL")
	)
	(segment
		(start 426.338238 -41.220136)
		(end 425.942506 -41.615868)
		(width 0.089408)
		(layer "In4.Cu")
		(net "SMB_OCP_FRU_STBY_LVC3_SCL")
	)
	(segment
		(start 403.451314 -40.9575)
		(end 401.254214 -38.7604)
		(width 0.089408)
		(layer "In4.Cu")
		(net "SMB_OCP_FRU_STBY_LVC3_SCL")
	)
	(segment
		(start 401.254214 -38.7604)
		(end 400.7993 -38.7604)
		(width 0.089408)
		(layer "In4.Cu")
		(net "SMB_OCP_FRU_STBY_LVC3_SCL")
	)
	(segment
		(start 471.598244 -49.00295)
		(end 471.597228 -49.002188)
		(width 0.089408)
		(layer "In4.Cu")
		(net "SMB_OCP_FRU_STBY_LVC3_SCL")
	)
	(segment
		(start 459.193138 -40.261794)
		(end 458.531214 -39.59987)
		(width 0.089408)
		(layer "In4.Cu")
		(net "SMB_OCP_FRU_STBY_LVC3_SCL")
	)
	(segment
		(start 433.49926 -40.68826)
		(end 432.868324 -40.057324)
		(width 0.089408)
		(layer "In4.Cu")
		(net "SMB_OCP_FRU_STBY_LVC3_SCL")
	)
	(segment
		(start 455.043286 -40.40632)
		(end 451.1802 -40.40632)
		(width 0.089408)
		(layer "In4.Cu")
		(net "SMB_OCP_FRU_STBY_LVC3_SCL")
	)
	(segment
		(start 471.720164 -49.125124)
		(end 471.719402 -49.124108)
		(width 0.089408)
		(layer "In4.Cu")
		(net "SMB_OCP_FRU_STBY_LVC3_SCL")
	)
	(segment
		(start 455.849736 -39.59987)
		(end 455.043286 -40.40632)
		(width 0.089408)
		(layer "In4.Cu")
		(net "SMB_OCP_FRU_STBY_LVC3_SCL")
	)
	(segment
		(start 471.597228 -49.002188)
		(end 470.4588 -47.86376)
		(width 0.089408)
		(layer "In4.Cu")
		(net "SMB_OCP_FRU_STBY_LVC3_SCL")
	)
	(segment
		(start 426.338238 -41.219882)
		(end 426.338238 -41.220136)
		(width 0.089408)
		(layer "In4.Cu")
		(net "SMB_OCP_FRU_STBY_LVC3_SCL")
	)
	(segment
		(start 470.4588 -47.86376)
		(end 470.4588 -45.72)
		(width 0.089408)
		(layer "In4.Cu")
		(net "SMB_OCP_FRU_STBY_LVC3_SCL")
	)
	(segment
		(start 406.487376 -40.9575)
		(end 403.451314 -40.9575)
		(width 0.089408)
		(layer "In4.Cu")
		(net "SMB_OCP_FRU_STBY_LVC3_SCL")
	)
	(segment
		(start 471.574876 -52.198524)
		(end 471.574876 -51.712876)
		(width 0.089408)
		(layer "In4.Cu")
		(net "SMB_OCP_FRU_STBY_LVC3_SCL")
	)
	(segment
		(start 467.360254 -42.901108)
		(end 464.25993 -42.901108)
		(width 0.089408)
		(layer "In4.Cu")
		(net "SMB_OCP_FRU_STBY_LVC3_SCL")
	)
	(segment
		(start 418.82568 -43.468036)
		(end 413.776922 -43.468036)
		(width 0.089408)
		(layer "In4.Cu")
		(net "SMB_OCP_FRU_STBY_LVC3_SCL")
	)
	(segment
		(start 424.019218 -41.615868)
		(end 421.99941 -43.635676)
		(width 0.089408)
		(layer "In4.Cu")
		(net "SMB_OCP_FRU_STBY_LVC3_SCL")
	)
	(segment
		(start 413.776922 -43.468036)
		(end 413.751776 -43.493182)
		(width 0.089408)
		(layer "In4.Cu")
		(net "SMB_OCP_FRU_STBY_LVC3_SCL")
	)
	(segment
		(start 471.34018 -52.43322)
		(end 471.574876 -52.198524)
		(width 0.089408)
		(layer "In4.Cu")
		(net "SMB_OCP_FRU_STBY_LVC3_SCL")
	)
	(segment
		(start 429.99406 -39.659814)
		(end 427.898306 -39.659814)
		(width 0.089408)
		(layer "In4.Cu")
		(net "SMB_OCP_FRU_STBY_LVC3_SCL")
	)
	(segment
		(start 425.942506 -41.615868)
		(end 424.019218 -41.615868)
		(width 0.089408)
		(layer "In4.Cu")
		(net "SMB_OCP_FRU_STBY_LVC3_SCL")
	)
	(segment
		(start 470.4588 -45.72)
		(end 468.892382 -44.153582)
		(width 0.089408)
		(layer "In4.Cu")
		(net "SMB_OCP_FRU_STBY_LVC3_SCL")
	)
	(segment
		(start 471.565732 -115.963192)
		(end 468.770208 -113.167668)
		(width 0.089408)
		(layer "In11.Cu")
		(net "SMB_OCP_FRU_STBY_LVC3_SCL")
	)
	(segment
		(start 459.128114 -57.9882)
		(end 468.588344 -57.9882)
		(width 0.089408)
		(layer "In11.Cu")
		(net "SMB_OCP_FRU_STBY_LVC3_SCL")
	)
	(segment
		(start 475.89821 -115.544092)
		(end 475.47911 -115.963192)
		(width 0.089408)
		(layer "In11.Cu")
		(net "SMB_OCP_FRU_STBY_LVC3_SCL")
	)
	(segment
		(start 471.34018 -52.715668)
		(end 471.34018 -52.43322)
		(width 0.089408)
		(layer "In11.Cu")
		(net "SMB_OCP_FRU_STBY_LVC3_SCL")
	)
	(segment
		(start 475.47911 -115.963192)
		(end 471.565732 -115.963192)
		(width 0.089408)
		(layer "In11.Cu")
		(net "SMB_OCP_FRU_STBY_LVC3_SCL")
	)
	(segment
		(start 439.661808 -114.75085)
		(end 439.661808 -115.15725)
		(width 0.089408)
		(layer "In11.Cu")
		(net "SMB_OCP_FRU_STBY_LVC3_SCL")
	)
	(segment
		(start 436.91429 -116.523008)
		(end 433.951888 -119.48541)
		(width 0.089408)
		(layer "In11.Cu")
		(net "SMB_OCP_FRU_STBY_LVC3_SCL")
	)
	(segment
		(start 420.152322 -122.886216)
		(end 419.812216 -122.886216)
		(width 0.089408)
		(layer "In11.Cu")
		(net "SMB_OCP_FRU_STBY_LVC3_SCL")
	)
	(segment
		(start 441.960254 -57.9882)
		(end 441.635134 -58.31332)
		(width 0.089408)
		(layer "In11.Cu")
		(net "SMB_OCP_FRU_STBY_LVC3_SCL")
	)
	(segment
		(start 423.442638 -119.596408)
		(end 420.152322 -122.886216)
		(width 0.089408)
		(layer "In11.Cu")
		(net "SMB_OCP_FRU_STBY_LVC3_SCL")
	)
	(segment
		(start 433.951888 -119.48541)
		(end 423.553636 -119.48541)
		(width 0.089408)
		(layer "In11.Cu")
		(net "SMB_OCP_FRU_STBY_LVC3_SCL")
	)
	(segment
		(start 455.662792 -57.9882)
		(end 441.960254 -57.9882)
		(width 0.089408)
		(layer "In11.Cu")
		(net "SMB_OCP_FRU_STBY_LVC3_SCL")
	)
	(segment
		(start 470.6112 -53.444648)
		(end 471.34018 -52.715668)
		(width 0.089408)
		(layer "In11.Cu")
		(net "SMB_OCP_FRU_STBY_LVC3_SCL")
	)
	(segment
		(start 457.112116 -59.437524)
		(end 455.662792 -57.9882)
		(width 0.089408)
		(layer "In11.Cu")
		(net "SMB_OCP_FRU_STBY_LVC3_SCL")
	)
	(segment
		(start 441.24499 -113.167668)
		(end 439.661808 -114.75085)
		(width 0.089408)
		(layer "In11.Cu")
		(net "SMB_OCP_FRU_STBY_LVC3_SCL")
	)
	(segment
		(start 423.553636 -119.48541)
		(end 423.442638 -119.596408)
		(width 0.089408)
		(layer "In11.Cu")
		(net "SMB_OCP_FRU_STBY_LVC3_SCL")
	)
	(segment
		(start 439.661808 -115.15725)
		(end 438.29605 -116.523008)
		(width 0.089408)
		(layer "In11.Cu")
		(net "SMB_OCP_FRU_STBY_LVC3_SCL")
	)
	(segment
		(start 475.89821 -114.63147)
		(end 475.89821 -115.544092)
		(width 0.089408)
		(layer "In11.Cu")
		(net "SMB_OCP_FRU_STBY_LVC3_SCL")
	)
	(segment
		(start 441.635134 -58.31332)
		(end 441.635134 -58.986674)
		(width 0.089408)
		(layer "In11.Cu")
		(net "SMB_OCP_FRU_STBY_LVC3_SCL")
	)
	(segment
		(start 441.354972 -59.266836)
		(end 441.159138 -59.266836)
		(width 0.089408)
		(layer "In11.Cu")
		(net "SMB_OCP_FRU_STBY_LVC3_SCL")
	)
	(segment
		(start 468.770208 -113.167668)
		(end 441.24499 -113.167668)
		(width 0.089408)
		(layer "In11.Cu")
		(net "SMB_OCP_FRU_STBY_LVC3_SCL")
	)
	(segment
		(start 457.67879 -59.437524)
		(end 457.112116 -59.437524)
		(width 0.089408)
		(layer "In11.Cu")
		(net "SMB_OCP_FRU_STBY_LVC3_SCL")
	)
	(segment
		(start 438.29605 -116.523008)
		(end 436.91429 -116.523008)
		(width 0.089408)
		(layer "In11.Cu")
		(net "SMB_OCP_FRU_STBY_LVC3_SCL")
	)
	(segment
		(start 458.03312 -59.083194)
		(end 459.128114 -57.9882)
		(width 0.089408)
		(layer "In11.Cu")
		(net "SMB_OCP_FRU_STBY_LVC3_SCL")
	)
	(segment
		(start 458.03312 -59.083194)
		(end 457.67879 -59.437524)
		(width 0.089408)
		(layer "In11.Cu")
		(net "SMB_OCP_FRU_STBY_LVC3_SCL")
	)
	(segment
		(start 470.6112 -55.965344)
		(end 470.6112 -53.444648)
		(width 0.089408)
		(layer "In11.Cu")
		(net "SMB_OCP_FRU_STBY_LVC3_SCL")
	)
	(segment
		(start 475.70644 -114.4397)
		(end 475.89821 -114.63147)
		(width 0.089408)
		(layer "In11.Cu")
		(net "SMB_OCP_FRU_STBY_LVC3_SCL")
	)
	(segment
		(start 441.635134 -58.986674)
		(end 441.354972 -59.266836)
		(width 0.089408)
		(layer "In11.Cu")
		(net "SMB_OCP_FRU_STBY_LVC3_SCL")
	)
	(segment
		(start 419.812216 -122.886216)
		(end 419.574218 -123.124214)
		(width 0.089408)
		(layer "In11.Cu")
		(net "SMB_OCP_FRU_STBY_LVC3_SCL")
	)
	(segment
		(start 468.588344 -57.9882)
		(end 470.6112 -55.965344)
		(width 0.089408)
		(layer "In11.Cu")
		(net "SMB_OCP_FRU_STBY_LVC3_SCL")
	)
	(segment
		(start 378.344684 -78.294738)
		(end 377.944888 -77.894942)
		(width 0.10795)
		(layer "F.Cu")
		(net "PWRGD_PVPP_KLM")
	)
	(segment
		(start 180.8734 -130.8735)
		(end 180.8734 -130.2258)
		(width 0.10795)
		(layer "F.Cu")
		(net "PWRGD_PVPP_KLM")
	)
	(via
		(at 378.344684 -78.294738)
		(size 0.4572)
		(drill 0.2032)
		(layers "F.Cu" "B.Cu")
		(net "PWRGD_PVPP_KLM")
	)
	(via
		(at 382.510284 -64.625728)
		(size 0.508)
		(drill 0.254)
		(layers "F.Cu" "B.Cu")
		(net "PWRGD_PVPP_KLM")
	)
	(via
		(at 180.8734 -130.2258)
		(size 0.508)
		(drill 0.254)
		(layers "F.Cu" "B.Cu")
		(net "PWRGD_PVPP_KLM")
	)
	(segment
		(start 267.43152 -154.505152)
		(end 268.165834 -154.505152)
		(width 0.089408)
		(layer "In4.Cu")
		(net "PWRGD_PVPP_KLM")
	)
	(segment
		(start 181.3052 -129.794)
		(end 182.331868 -129.794)
		(width 0.089408)
		(layer "In4.Cu")
		(net "PWRGD_PVPP_KLM")
	)
	(segment
		(start 325.644764 -127.801624)
		(end 326.718676 -126.727712)
		(width 0.089408)
		(layer "In4.Cu")
		(net "PWRGD_PVPP_KLM")
	)
	(segment
		(start 371.0432 -64.984376)
		(end 371.0432 -64.4652)
		(width 0.089408)
		(layer "In4.Cu")
		(net "PWRGD_PVPP_KLM")
	)
	(segment
		(start 270.014192 -154.652472)
		(end 270.702024 -154.652472)
		(width 0.089408)
		(layer "In4.Cu")
		(net "PWRGD_PVPP_KLM")
	)
	(segment
		(start 282.237942 -154.615896)
		(end 282.5242 -154.902154)
		(width 0.089408)
		(layer "In4.Cu")
		(net "PWRGD_PVPP_KLM")
	)
	(segment
		(start 189.862968 -133.419342)
		(end 190.77559 -134.331964)
		(width 0.089408)
		(layer "In4.Cu")
		(net "PWRGD_PVPP_KLM")
	)
	(segment
		(start 354.170996 -69.21246)
		(end 354.17125 -69.21246)
		(width 0.089408)
		(layer "In4.Cu")
		(net "PWRGD_PVPP_KLM")
	)
	(segment
		(start 263.257792 -152.768808)
		(end 264.369804 -152.768808)
		(width 0.089408)
		(layer "In4.Cu")
		(net "PWRGD_PVPP_KLM")
	)
	(segment
		(start 345.32824 -70.11289)
		(end 345.878912 -69.562218)
		(width 0.089408)
		(layer "In4.Cu")
		(net "PWRGD_PVPP_KLM")
	)
	(segment
		(start 325.368666 -118.716552)
		(end 324.972426 -118.320312)
		(width 0.089408)
		(layer "In4.Cu")
		(net "PWRGD_PVPP_KLM")
	)
	(segment
		(start 331.125576 -84.733892)
		(end 331.125576 -82.200242)
		(width 0.089408)
		(layer "In4.Cu")
		(net "PWRGD_PVPP_KLM")
	)
	(segment
		(start 357.714804 -69.211444)
		(end 358.922066 -70.418706)
		(width 0.089408)
		(layer "In4.Cu")
		(net "PWRGD_PVPP_KLM")
	)
	(segment
		(start 182.331868 -129.794)
		(end 182.916068 -130.3782)
		(width 0.089408)
		(layer "In4.Cu")
		(net "PWRGD_PVPP_KLM")
	)
	(segment
		(start 377.404122 -64.766444)
		(end 377.73229 -64.766444)
		(width 0.089408)
		(layer "In4.Cu")
		(net "PWRGD_PVPP_KLM")
	)
	(segment
		(start 268.165834 -154.505152)
		(end 268.313154 -154.652472)
		(width 0.089408)
		(layer "In4.Cu")
		(net "PWRGD_PVPP_KLM")
	)
	(segment
		(start 260.01345 -156.01315)
		(end 263.257792 -152.768808)
		(width 0.089408)
		(layer "In4.Cu")
		(net "PWRGD_PVPP_KLM")
	)
	(segment
		(start 358.922066 -70.418706)
		(end 362.514134 -70.418706)
		(width 0.089408)
		(layer "In4.Cu")
		(net "PWRGD_PVPP_KLM")
	)
	(segment
		(start 353.594416 -69.78904)
		(end 354.170996 -69.21246)
		(width 0.089408)
		(layer "In4.Cu")
		(net "PWRGD_PVPP_KLM")
	)
	(segment
		(start 324.090792 -137.962894)
		(end 324.090792 -137.620248)
		(width 0.089408)
		(layer "In4.Cu")
		(net "PWRGD_PVPP_KLM")
	)
	(segment
		(start 269.005304 -154.652472)
		(end 269.152624 -154.505152)
		(width 0.089408)
		(layer "In4.Cu")
		(net "PWRGD_PVPP_KLM")
	)
	(segment
		(start 352.863404 -69.78904)
		(end 353.594416 -69.78904)
		(width 0.089408)
		(layer "In4.Cu")
		(net "PWRGD_PVPP_KLM")
	)
	(segment
		(start 378.831856 -63.994284)
		(end 381.164084 -63.994284)
		(width 0.089408)
		(layer "In4.Cu")
		(net "PWRGD_PVPP_KLM")
	)
	(segment
		(start 326.718676 -124.52477)
		(end 325.368666 -123.17476)
		(width 0.089408)
		(layer "In4.Cu")
		(net "PWRGD_PVPP_KLM")
	)
	(segment
		(start 278.285448 -154.505152)
		(end 278.41448 -154.634184)
		(width 0.089408)
		(layer "In4.Cu")
		(net "PWRGD_PVPP_KLM")
	)
	(segment
		(start 363.262164 -69.670676)
		(end 363.262164 -69.36867)
		(width 0.089408)
		(layer "In4.Cu")
		(net "PWRGD_PVPP_KLM")
	)
	(segment
		(start 325.399654 -133.043676)
		(end 325.399654 -131.626102)
		(width 0.089408)
		(layer "In4.Cu")
		(net "PWRGD_PVPP_KLM")
	)
	(segment
		(start 366.451896 -66.178938)
		(end 367.789206 -66.178938)
		(width 0.089408)
		(layer "In4.Cu")
		(net "PWRGD_PVPP_KLM")
	)
	(segment
		(start 276.617176 -154.505152)
		(end 276.764496 -154.652472)
		(width 0.089408)
		(layer "In4.Cu")
		(net "PWRGD_PVPP_KLM")
	)
	(segment
		(start 273.223736 -154.505152)
		(end 273.371056 -154.652472)
		(width 0.089408)
		(layer "In4.Cu")
		(net "PWRGD_PVPP_KLM")
	)
	(segment
		(start 323.508878 -138.544808)
		(end 324.090792 -137.962894)
		(width 0.089408)
		(layer "In4.Cu")
		(net "PWRGD_PVPP_KLM")
	)
	(segment
		(start 268.313154 -154.652472)
		(end 269.005304 -154.652472)
		(width 0.089408)
		(layer "In4.Cu")
		(net "PWRGD_PVPP_KLM")
	)
	(segment
		(start 370.655088 -65.372488)
		(end 371.0432 -64.984376)
		(width 0.089408)
		(layer "In4.Cu")
		(net "PWRGD_PVPP_KLM")
	)
	(segment
		(start 274.075398 -154.652472)
		(end 274.222718 -154.505152)
		(width 0.089408)
		(layer "In4.Cu")
		(net "PWRGD_PVPP_KLM")
	)
	(segment
		(start 363.262164 -69.36867)
		(end 366.451896 -66.178938)
		(width 0.089408)
		(layer "In4.Cu")
		(net "PWRGD_PVPP_KLM")
	)
	(segment
		(start 324.228968 -135.824976)
		(end 324.228968 -134.214362)
		(width 0.089408)
		(layer "In4.Cu")
		(net "PWRGD_PVPP_KLM")
	)
	(segment
		(start 333.581248 -74.275696)
		(end 335.035144 -72.8218)
		(width 0.089408)
		(layer "In4.Cu")
		(net "PWRGD_PVPP_KLM")
	)
	(segment
		(start 270.702024 -154.652472)
		(end 270.849344 -154.505152)
		(width 0.089408)
		(layer "In4.Cu")
		(net "PWRGD_PVPP_KLM")
	)
	(segment
		(start 367.789206 -66.178938)
		(end 368.595656 -65.372488)
		(width 0.089408)
		(layer "In4.Cu")
		(net "PWRGD_PVPP_KLM")
	)
	(segment
		(start 371.0432 -64.4652)
		(end 372.132098 -63.376302)
		(width 0.089408)
		(layer "In4.Cu")
		(net "PWRGD_PVPP_KLM")
	)
	(segment
		(start 192.966594 -153.675842)
		(end 195.303902 -156.01315)
		(width 0.089408)
		(layer "In4.Cu")
		(net "PWRGD_PVPP_KLM")
	)
	(segment
		(start 323.780404 -136.27354)
		(end 324.228968 -135.824976)
		(width 0.089408)
		(layer "In4.Cu")
		(net "PWRGD_PVPP_KLM")
	)
	(segment
		(start 323.793104 -153.737818)
		(end 323.793104 -147.623784)
		(width 0.089408)
		(layer "In4.Cu")
		(net "PWRGD_PVPP_KLM")
	)
	(segment
		(start 265.810238 -154.209242)
		(end 266.248642 -154.209242)
		(width 0.089408)
		(layer "In4.Cu")
		(net "PWRGD_PVPP_KLM")
	)
	(segment
		(start 321.51574 -156.015182)
		(end 323.793104 -153.737818)
		(width 0.089408)
		(layer "In4.Cu")
		(net "PWRGD_PVPP_KLM")
	)
	(segment
		(start 378.67336 -63.994284)
		(end 378.673614 -63.99403)
		(width 0.089408)
		(layer "In4.Cu")
		(net "PWRGD_PVPP_KLM")
	)
	(segment
		(start 190.77559 -147.702524)
		(end 192.966594 -149.893528)
		(width 0.089408)
		(layer "In4.Cu")
		(net "PWRGD_PVPP_KLM")
	)
	(segment
		(start 195.303902 -156.01315)
		(end 260.01345 -156.01315)
		(width 0.089408)
		(layer "In4.Cu")
		(net "PWRGD_PVPP_KLM")
	)
	(segment
		(start 340.094824 -70.11289)
		(end 345.32824 -70.11289)
		(width 0.089408)
		(layer "In4.Cu")
		(net "PWRGD_PVPP_KLM")
	)
	(segment
		(start 266.691872 -154.652472)
		(end 267.2842 -154.652472)
		(width 0.089408)
		(layer "In4.Cu")
		(net "PWRGD_PVPP_KLM")
	)
	(segment
		(start 378.673614 -63.99403)
		(end 378.831602 -63.99403)
		(width 0.089408)
		(layer "In4.Cu")
		(net "PWRGD_PVPP_KLM")
	)
	(segment
		(start 333.581248 -79.74457)
		(end 333.581248 -74.275696)
		(width 0.089408)
		(layer "In4.Cu")
		(net "PWRGD_PVPP_KLM")
	)
	(segment
		(start 378.831602 -63.99403)
		(end 378.831856 -63.994284)
		(width 0.089408)
		(layer "In4.Cu")
		(net "PWRGD_PVPP_KLM")
	)
	(segment
		(start 323.684646 -114.997484)
		(end 323.684646 -92.174822)
		(width 0.089408)
		(layer "In4.Cu")
		(net "PWRGD_PVPP_KLM")
	)
	(segment
		(start 271.559782 -154.505152)
		(end 271.707102 -154.652472)
		(width 0.089408)
		(layer "In4.Cu")
		(net "PWRGD_PVPP_KLM")
	)
	(segment
		(start 274.222718 -154.505152)
		(end 274.940522 -154.505152)
		(width 0.089408)
		(layer "In4.Cu")
		(net "PWRGD_PVPP_KLM")
	)
	(segment
		(start 323.793104 -147.623784)
		(end 323.508878 -147.339558)
		(width 0.089408)
		(layer "In4.Cu")
		(net "PWRGD_PVPP_KLM")
	)
	(segment
		(start 264.369804 -152.768808)
		(end 265.810238 -154.209242)
		(width 0.089408)
		(layer "In4.Cu")
		(net "PWRGD_PVPP_KLM")
	)
	(segment
		(start 378.50445 -63.994284)
		(end 378.67336 -63.994284)
		(width 0.089408)
		(layer "In4.Cu")
		(net "PWRGD_PVPP_KLM")
	)
	(segment
		(start 354.172266 -69.211444)
		(end 357.714804 -69.211444)
		(width 0.089408)
		(layer "In4.Cu")
		(net "PWRGD_PVPP_KLM")
	)
	(segment
		(start 277.509732 -154.652472)
		(end 277.657052 -154.505152)
		(width 0.089408)
		(layer "In4.Cu")
		(net "PWRGD_PVPP_KLM")
	)
	(segment
		(start 282.5242 -154.902154)
		(end 282.5242 -155.648152)
		(width 0.089408)
		(layer "In4.Cu")
		(net "PWRGD_PVPP_KLM")
	)
	(segment
		(start 277.657052 -154.505152)
		(end 278.285448 -154.505152)
		(width 0.089408)
		(layer "In4.Cu")
		(net "PWRGD_PVPP_KLM")
	)
	(segment
		(start 275.087842 -154.652472)
		(end 275.7805 -154.652472)
		(width 0.089408)
		(layer "In4.Cu")
		(net "PWRGD_PVPP_KLM")
	)
	(segment
		(start 192.966594 -149.893528)
		(end 192.966594 -153.675842)
		(width 0.089408)
		(layer "In4.Cu")
		(net "PWRGD_PVPP_KLM")
	)
	(segment
		(start 267.2842 -154.652472)
		(end 267.43152 -154.505152)
		(width 0.089408)
		(layer "In4.Cu")
		(net "PWRGD_PVPP_KLM")
	)
	(segment
		(start 323.780404 -137.30986)
		(end 323.780404 -136.27354)
		(width 0.089408)
		(layer "In4.Cu")
		(net "PWRGD_PVPP_KLM")
	)
	(segment
		(start 376.91568 -64.62268)
		(end 377.260358 -64.62268)
		(width 0.089408)
		(layer "In4.Cu")
		(net "PWRGD_PVPP_KLM")
	)
	(segment
		(start 325.12635 -131.352798)
		(end 325.12635 -128.802892)
		(width 0.089408)
		(layer "In4.Cu")
		(net "PWRGD_PVPP_KLM")
	)
	(segment
		(start 187.495942 -133.419342)
		(end 189.862968 -133.419342)
		(width 0.089408)
		(layer "In4.Cu")
		(net "PWRGD_PVPP_KLM")
	)
	(segment
		(start 325.368666 -123.17476)
		(end 325.368666 -118.716552)
		(width 0.089408)
		(layer "In4.Cu")
		(net "PWRGD_PVPP_KLM")
	)
	(segment
		(start 279.181814 -154.615896)
		(end 282.237942 -154.615896)
		(width 0.089408)
		(layer "In4.Cu")
		(net "PWRGD_PVPP_KLM")
	)
	(segment
		(start 323.508878 -147.339558)
		(end 323.508878 -138.544808)
		(width 0.089408)
		(layer "In4.Cu")
		(net "PWRGD_PVPP_KLM")
	)
	(segment
		(start 278.41448 -154.634184)
		(end 279.163526 -154.634184)
		(width 0.089408)
		(layer "In4.Cu")
		(net "PWRGD_PVPP_KLM")
	)
	(segment
		(start 381.795528 -64.625728)
		(end 382.510284 -64.625728)
		(width 0.089408)
		(layer "In4.Cu")
		(net "PWRGD_PVPP_KLM")
	)
	(segment
		(start 273.371056 -154.652472)
		(end 274.075398 -154.652472)
		(width 0.089408)
		(layer "In4.Cu")
		(net "PWRGD_PVPP_KLM")
	)
	(segment
		(start 345.878912 -69.562218)
		(end 352.636582 -69.562218)
		(width 0.089408)
		(layer "In4.Cu")
		(net "PWRGD_PVPP_KLM")
	)
	(segment
		(start 266.248642 -154.209242)
		(end 266.691872 -154.652472)
		(width 0.089408)
		(layer "In4.Cu")
		(net "PWRGD_PVPP_KLM")
	)
	(segment
		(start 272.554192 -154.505152)
		(end 273.223736 -154.505152)
		(width 0.089408)
		(layer "In4.Cu")
		(net "PWRGD_PVPP_KLM")
	)
	(segment
		(start 324.228968 -134.214362)
		(end 325.399654 -133.043676)
		(width 0.089408)
		(layer "In4.Cu")
		(net "PWRGD_PVPP_KLM")
	)
	(segment
		(start 324.972426 -116.285264)
		(end 323.684646 -114.997484)
		(width 0.089408)
		(layer "In4.Cu")
		(net "PWRGD_PVPP_KLM")
	)
	(segment
		(start 354.17125 -69.21246)
		(end 354.172266 -69.211444)
		(width 0.089408)
		(layer "In4.Cu")
		(net "PWRGD_PVPP_KLM")
	)
	(segment
		(start 377.73229 -64.766444)
		(end 378.50445 -63.994284)
		(width 0.089408)
		(layer "In4.Cu")
		(net "PWRGD_PVPP_KLM")
	)
	(segment
		(start 339.086698 -71.121016)
		(end 340.094824 -70.11289)
		(width 0.089408)
		(layer "In4.Cu")
		(net "PWRGD_PVPP_KLM")
	)
	(segment
		(start 381.164084 -63.994284)
		(end 381.795528 -64.625728)
		(width 0.089408)
		(layer "In4.Cu")
		(net "PWRGD_PVPP_KLM")
	)
	(segment
		(start 274.940522 -154.505152)
		(end 275.087842 -154.652472)
		(width 0.089408)
		(layer "In4.Cu")
		(net "PWRGD_PVPP_KLM")
	)
	(segment
		(start 325.399654 -131.626102)
		(end 325.12635 -131.352798)
		(width 0.089408)
		(layer "In4.Cu")
		(net "PWRGD_PVPP_KLM")
	)
	(segment
		(start 184.4548 -130.3782)
		(end 187.495942 -133.419342)
		(width 0.089408)
		(layer "In4.Cu")
		(net "PWRGD_PVPP_KLM")
	)
	(segment
		(start 331.125576 -82.200242)
		(end 333.581248 -79.74457)
		(width 0.089408)
		(layer "In4.Cu")
		(net "PWRGD_PVPP_KLM")
	)
	(segment
		(start 326.718676 -126.727712)
		(end 326.718676 -124.52477)
		(width 0.089408)
		(layer "In4.Cu")
		(net "PWRGD_PVPP_KLM")
	)
	(segment
		(start 324.972426 -118.320312)
		(end 324.972426 -116.285264)
		(width 0.089408)
		(layer "In4.Cu")
		(net "PWRGD_PVPP_KLM")
	)
	(segment
		(start 335.035144 -72.8218)
		(end 336.947256 -72.8218)
		(width 0.089408)
		(layer "In4.Cu")
		(net "PWRGD_PVPP_KLM")
	)
	(segment
		(start 269.152624 -154.505152)
		(end 269.866872 -154.505152)
		(width 0.089408)
		(layer "In4.Cu")
		(net "PWRGD_PVPP_KLM")
	)
	(segment
		(start 272.406872 -154.652472)
		(end 272.554192 -154.505152)
		(width 0.089408)
		(layer "In4.Cu")
		(net "PWRGD_PVPP_KLM")
	)
	(segment
		(start 275.92782 -154.505152)
		(end 276.617176 -154.505152)
		(width 0.089408)
		(layer "In4.Cu")
		(net "PWRGD_PVPP_KLM")
	)
	(segment
		(start 275.7805 -154.652472)
		(end 275.92782 -154.505152)
		(width 0.089408)
		(layer "In4.Cu")
		(net "PWRGD_PVPP_KLM")
	)
	(segment
		(start 375.669302 -63.376302)
		(end 376.91568 -64.62268)
		(width 0.089408)
		(layer "In4.Cu")
		(net "PWRGD_PVPP_KLM")
	)
	(segment
		(start 182.916068 -130.3782)
		(end 184.4548 -130.3782)
		(width 0.089408)
		(layer "In4.Cu")
		(net "PWRGD_PVPP_KLM")
	)
	(segment
		(start 368.595656 -65.372488)
		(end 370.655088 -65.372488)
		(width 0.089408)
		(layer "In4.Cu")
		(net "PWRGD_PVPP_KLM")
	)
	(segment
		(start 282.89123 -156.015182)
		(end 321.51574 -156.015182)
		(width 0.089408)
		(layer "In4.Cu")
		(net "PWRGD_PVPP_KLM")
	)
	(segment
		(start 282.5242 -155.648152)
		(end 282.89123 -156.015182)
		(width 0.089408)
		(layer "In4.Cu")
		(net "PWRGD_PVPP_KLM")
	)
	(segment
		(start 362.514134 -70.418706)
		(end 363.262164 -69.670676)
		(width 0.089408)
		(layer "In4.Cu")
		(net "PWRGD_PVPP_KLM")
	)
	(segment
		(start 270.849344 -154.505152)
		(end 271.559782 -154.505152)
		(width 0.089408)
		(layer "In4.Cu")
		(net "PWRGD_PVPP_KLM")
	)
	(segment
		(start 276.764496 -154.652472)
		(end 277.509732 -154.652472)
		(width 0.089408)
		(layer "In4.Cu")
		(net "PWRGD_PVPP_KLM")
	)
	(segment
		(start 324.090792 -137.620248)
		(end 323.780404 -137.30986)
		(width 0.089408)
		(layer "In4.Cu")
		(net "PWRGD_PVPP_KLM")
	)
	(segment
		(start 325.644764 -128.284478)
		(end 325.644764 -127.801624)
		(width 0.089408)
		(layer "In4.Cu")
		(net "PWRGD_PVPP_KLM")
	)
	(segment
		(start 372.132098 -63.376302)
		(end 375.669302 -63.376302)
		(width 0.089408)
		(layer "In4.Cu")
		(net "PWRGD_PVPP_KLM")
	)
	(segment
		(start 325.12635 -128.802892)
		(end 325.644764 -128.284478)
		(width 0.089408)
		(layer "In4.Cu")
		(net "PWRGD_PVPP_KLM")
	)
	(segment
		(start 323.684646 -92.174822)
		(end 331.125576 -84.733892)
		(width 0.089408)
		(layer "In4.Cu")
		(net "PWRGD_PVPP_KLM")
	)
	(segment
		(start 279.163526 -154.634184)
		(end 279.181814 -154.615896)
		(width 0.089408)
		(layer "In4.Cu")
		(net "PWRGD_PVPP_KLM")
	)
	(segment
		(start 269.866872 -154.505152)
		(end 270.014192 -154.652472)
		(width 0.089408)
		(layer "In4.Cu")
		(net "PWRGD_PVPP_KLM")
	)
	(segment
		(start 338.64804 -71.121016)
		(end 339.086698 -71.121016)
		(width 0.089408)
		(layer "In4.Cu")
		(net "PWRGD_PVPP_KLM")
	)
	(segment
		(start 190.77559 -134.331964)
		(end 190.77559 -147.702524)
		(width 0.089408)
		(layer "In4.Cu")
		(net "PWRGD_PVPP_KLM")
	)
	(segment
		(start 336.947256 -72.8218)
		(end 338.64804 -71.121016)
		(width 0.089408)
		(layer "In4.Cu")
		(net "PWRGD_PVPP_KLM")
	)
	(segment
		(start 271.707102 -154.652472)
		(end 272.406872 -154.652472)
		(width 0.089408)
		(layer "In4.Cu")
		(net "PWRGD_PVPP_KLM")
	)
	(segment
		(start 180.8734 -130.2258)
		(end 181.3052 -129.794)
		(width 0.089408)
		(layer "In4.Cu")
		(net "PWRGD_PVPP_KLM")
	)
	(segment
		(start 352.636582 -69.562218)
		(end 352.863404 -69.78904)
		(width 0.089408)
		(layer "In4.Cu")
		(net "PWRGD_PVPP_KLM")
	)
	(segment
		(start 377.260358 -64.62268)
		(end 377.404122 -64.766444)
		(width 0.089408)
		(layer "In4.Cu")
		(net "PWRGD_PVPP_KLM")
	)
	(segment
		(start 379.7046 -72.669146)
		(end 379.84811 -72.525636)
		(width 0.089408)
		(layer "In9.Cu")
		(net "PWRGD_PVPP_KLM")
	)
	(segment
		(start 378.687584 -77.150214)
		(end 378.942854 -76.894944)
		(width 0.089408)
		(layer "In9.Cu")
		(net "PWRGD_PVPP_KLM")
	)
	(segment
		(start 381.42164 -68.58)
		(end 381.42164 -67.26936)
		(width 0.089408)
		(layer "In9.Cu")
		(net "PWRGD_PVPP_KLM")
	)
	(segment
		(start 381.166624 -70.508368)
		(end 381.166624 -68.835016)
		(width 0.089408)
		(layer "In9.Cu")
		(net "PWRGD_PVPP_KLM")
	)
	(segment
		(start 382.643888 -64.759332)
		(end 382.510284 -64.625728)
		(width 0.089408)
		(layer "In9.Cu")
		(net "PWRGD_PVPP_KLM")
	)
	(segment
		(start 378.344684 -78.294738)
		(end 378.687584 -77.951838)
		(width 0.089408)
		(layer "In9.Cu")
		(net "PWRGD_PVPP_KLM")
	)
	(segment
		(start 381.510286 -71.34225)
		(end 381.510286 -70.85203)
		(width 0.089408)
		(layer "In9.Cu")
		(net "PWRGD_PVPP_KLM")
	)
	(segment
		(start 379.84811 -72.525636)
		(end 380.3269 -72.525636)
		(width 0.089408)
		(layer "In9.Cu")
		(net "PWRGD_PVPP_KLM")
	)
	(segment
		(start 380.3269 -72.525636)
		(end 381.510286 -71.34225)
		(width 0.089408)
		(layer "In9.Cu")
		(net "PWRGD_PVPP_KLM")
	)
	(segment
		(start 381.42164 -67.26936)
		(end 382.643888 -66.047112)
		(width 0.089408)
		(layer "In9.Cu")
		(net "PWRGD_PVPP_KLM")
	)
	(segment
		(start 382.643888 -66.047112)
		(end 382.643888 -64.759332)
		(width 0.089408)
		(layer "In9.Cu")
		(net "PWRGD_PVPP_KLM")
	)
	(segment
		(start 378.687584 -77.951838)
		(end 378.687584 -77.150214)
		(width 0.089408)
		(layer "In9.Cu")
		(net "PWRGD_PVPP_KLM")
	)
	(segment
		(start 378.942854 -75.767946)
		(end 379.7046 -75.0062)
		(width 0.089408)
		(layer "In9.Cu")
		(net "PWRGD_PVPP_KLM")
	)
	(segment
		(start 381.166624 -68.835016)
		(end 381.42164 -68.58)
		(width 0.089408)
		(layer "In9.Cu")
		(net "PWRGD_PVPP_KLM")
	)
	(segment
		(start 379.7046 -75.0062)
		(end 379.7046 -72.669146)
		(width 0.089408)
		(layer "In9.Cu")
		(net "PWRGD_PVPP_KLM")
	)
	(segment
		(start 378.942854 -76.894944)
		(end 378.942854 -75.767946)
		(width 0.089408)
		(layer "In9.Cu")
		(net "PWRGD_PVPP_KLM")
	)
	(segment
		(start 381.510286 -70.85203)
		(end 381.166624 -70.508368)
		(width 0.089408)
		(layer "In9.Cu")
		(net "PWRGD_PVPP_KLM")
	)
	(segment
		(start 379.095 -77.755496)
		(end 378.873004 -77.5335)
		(width 0.10795)
		(layer "F.Cu")
		(net "PWRGD_PVPP_GHJ")
	)
	(segment
		(start 380.34722 -76.99248)
		(end 379.584204 -77.755496)
		(width 0.10795)
		(layer "F.Cu")
		(net "PWRGD_PVPP_GHJ")
	)
	(segment
		(start 378.3838 -77.5335)
		(end 377.945396 -77.095096)
		(width 0.10795)
		(layer "F.Cu")
		(net "PWRGD_PVPP_GHJ")
	)
	(segment
		(start 175.8696 -4.953)
		(end 175.8696 -5.2832)
		(width 0.10795)
		(layer "F.Cu")
		(net "PWRGD_PVPP_GHJ")
	)
	(segment
		(start 179.324 -5.461)
		(end 180.848 -6.985)
		(width 0.10795)
		(layer "F.Cu")
		(net "PWRGD_PVPP_GHJ")
	)
	(segment
		(start 176.6062 -4.5466)
		(end 176.276 -4.5466)
		(width 0.10795)
		(layer "F.Cu")
		(net "PWRGD_PVPP_GHJ")
	)
	(segment
		(start 378.873004 -77.5335)
		(end 378.3838 -77.5335)
		(width 0.10795)
		(layer "F.Cu")
		(net "PWRGD_PVPP_GHJ")
	)
	(segment
		(start 176.276 -4.5466)
		(end 175.8696 -4.953)
		(width 0.10795)
		(layer "F.Cu")
		(net "PWRGD_PVPP_GHJ")
	)
	(segment
		(start 180.848 -6.985)
		(end 180.848 -7.366)
		(width 0.10795)
		(layer "F.Cu")
		(net "PWRGD_PVPP_GHJ")
	)
	(segment
		(start 176.719992 -4.660392)
		(end 176.719992 -4.914138)
		(width 0.10795)
		(layer "F.Cu")
		(net "PWRGD_PVPP_GHJ")
	)
	(segment
		(start 177.266854 -5.461)
		(end 179.324 -5.461)
		(width 0.10795)
		(layer "F.Cu")
		(net "PWRGD_PVPP_GHJ")
	)
	(segment
		(start 380.367286 -76.99248)
		(end 380.34722 -76.99248)
		(width 0.10795)
		(layer "F.Cu")
		(net "PWRGD_PVPP_GHJ")
	)
	(segment
		(start 379.584204 -77.755496)
		(end 379.095 -77.755496)
		(width 0.10795)
		(layer "F.Cu")
		(net "PWRGD_PVPP_GHJ")
	)
	(segment
		(start 176.6062 -4.5466)
		(end 176.719992 -4.660392)
		(width 0.10795)
		(layer "F.Cu")
		(net "PWRGD_PVPP_GHJ")
	)
	(segment
		(start 377.945396 -77.095096)
		(end 377.944888 -77.095096)
		(width 0.10795)
		(layer "F.Cu")
		(net "PWRGD_PVPP_GHJ")
	)
	(segment
		(start 176.719992 -4.914138)
		(end 177.266854 -5.461)
		(width 0.10795)
		(layer "F.Cu")
		(net "PWRGD_PVPP_GHJ")
	)
	(via
		(at 176.6062 -4.5466)
		(size 0.762)
		(drill 0.381)
		(layers "F.Cu" "B.Cu")
		(net "PWRGD_PVPP_GHJ")
	)
	(via
		(at 175.8696 -5.2832)
		(size 0.508)
		(drill 0.254)
		(layers "F.Cu" "B.Cu")
		(net "PWRGD_PVPP_GHJ")
	)
	(via
		(at 380.367286 -76.99248)
		(size 0.4572)
		(drill 0.2032)
		(layers "F.Cu" "B.Cu")
		(net "PWRGD_PVPP_GHJ")
	)
	(segment
		(start 181.69763 2.405126)
		(end 183.835548 4.543044)
		(width 0.089408)
		(layer "In11.Cu")
		(net "PWRGD_PVPP_GHJ")
	)
	(segment
		(start 334.98028 -39.32428)
		(end 336.696304 -41.040304)
		(width 0.089408)
		(layer "In11.Cu")
		(net "PWRGD_PVPP_GHJ")
	)
	(segment
		(start 327.877424 -27.29484)
		(end 327.877424 -31.266384)
		(width 0.089408)
		(layer "In11.Cu")
		(net "PWRGD_PVPP_GHJ")
	)
	(segment
		(start 371.036342 -52.131468)
		(end 371.036342 -53.052218)
		(width 0.089408)
		(layer "In11.Cu")
		(net "PWRGD_PVPP_GHJ")
	)
	(segment
		(start 330.25842 -11.573002)
		(end 330.25842 -13.851636)
		(width 0.089408)
		(layer "In11.Cu")
		(net "PWRGD_PVPP_GHJ")
	)
	(segment
		(start 380.0602 -67.5894)
		(end 380.122176 -67.5894)
		(width 0.089408)
		(layer "In11.Cu")
		(net "PWRGD_PVPP_GHJ")
	)
	(segment
		(start 371.036342 -53.052218)
		(end 373.806974 -55.82285)
		(width 0.089408)
		(layer "In11.Cu")
		(net "PWRGD_PVPP_GHJ")
	)
	(segment
		(start 326.24649 -10.3378)
		(end 329.023218 -10.3378)
		(width 0.089408)
		(layer "In11.Cu")
		(net "PWRGD_PVPP_GHJ")
	)
	(segment
		(start 325.291704 3.946144)
		(end 325.291704 2.914904)
		(width 0.089408)
		(layer "In11.Cu")
		(net "PWRGD_PVPP_GHJ")
	)
	(segment
		(start 379.744732 -72.433434)
		(end 379.744732 -74.746866)
		(width 0.089408)
		(layer "In11.Cu")
		(net "PWRGD_PVPP_GHJ")
	)
	(segment
		(start 379.791468 -69.359018)
		(end 379.791468 -69.689726)
		(width 0.089408)
		(layer "In11.Cu")
		(net "PWRGD_PVPP_GHJ")
	)
	(segment
		(start 327.877424 -31.266384)
		(end 329.550776 -32.939736)
		(width 0.089408)
		(layer "In11.Cu")
		(net "PWRGD_PVPP_GHJ")
	)
	(segment
		(start 353.251262 -41.040304)
		(end 355.150166 -39.1414)
		(width 0.089408)
		(layer "In11.Cu")
		(net "PWRGD_PVPP_GHJ")
	)
	(segment
		(start 175.8696 -4.7625)
		(end 177.023268 -3.608832)
		(width 0.089408)
		(layer "In11.Cu")
		(net "PWRGD_PVPP_GHJ")
	)
	(segment
		(start 333.108808 -38.510464)
		(end 333.922624 -39.32428)
		(width 0.089408)
		(layer "In11.Cu")
		(net "PWRGD_PVPP_GHJ")
	)
	(segment
		(start 330.25842 -13.851636)
		(end 328.525124 -15.584932)
		(width 0.089408)
		(layer "In11.Cu")
		(net "PWRGD_PVPP_GHJ")
	)
	(segment
		(start 181.841902 -2.16027)
		(end 181.841902 1.22174)
		(width 0.089408)
		(layer "In11.Cu")
		(net "PWRGD_PVPP_GHJ")
	)
	(segment
		(start 380.122176 -67.5894)
		(end 380.365 -67.832224)
		(width 0.089408)
		(layer "In11.Cu")
		(net "PWRGD_PVPP_GHJ")
	)
	(segment
		(start 183.835548 4.543044)
		(end 324.694804 4.543044)
		(width 0.089408)
		(layer "In11.Cu")
		(net "PWRGD_PVPP_GHJ")
	)
	(segment
		(start 325.12635 2.74955)
		(end 325.12635 -1.965452)
		(width 0.089408)
		(layer "In11.Cu")
		(net "PWRGD_PVPP_GHJ")
	)
	(segment
		(start 377.89612 -63.635128)
		(end 377.89612 -66.303652)
		(width 0.089408)
		(layer "In11.Cu")
		(net "PWRGD_PVPP_GHJ")
	)
	(segment
		(start 378.476002 -63.049912)
		(end 377.971812 -63.554102)
		(width 0.089408)
		(layer "In11.Cu")
		(net "PWRGD_PVPP_GHJ")
	)
	(segment
		(start 379.80239 -69.700648)
		(end 379.80239 -69.963284)
		(width 0.089408)
		(layer "In11.Cu")
		(net "PWRGD_PVPP_GHJ")
	)
	(segment
		(start 379.80239 -69.963284)
		(end 379.791468 -69.974206)
		(width 0.089408)
		(layer "In11.Cu")
		(net "PWRGD_PVPP_GHJ")
	)
	(segment
		(start 367.272316 -48.367442)
		(end 371.036342 -52.131468)
		(width 0.089408)
		(layer "In11.Cu")
		(net "PWRGD_PVPP_GHJ")
	)
	(segment
		(start 325.291704 2.914904)
		(end 325.12635 2.74955)
		(width 0.089408)
		(layer "In11.Cu")
		(net "PWRGD_PVPP_GHJ")
	)
	(segment
		(start 377.971812 -63.559436)
		(end 377.89612 -63.635128)
		(width 0.089408)
		(layer "In11.Cu")
		(net "PWRGD_PVPP_GHJ")
	)
	(segment
		(start 366.073182 -48.367442)
		(end 367.272316 -48.367442)
		(width 0.089408)
		(layer "In11.Cu")
		(net "PWRGD_PVPP_GHJ")
	)
	(segment
		(start 378.776484 -67.184016)
		(end 379.654816 -67.184016)
		(width 0.089408)
		(layer "In11.Cu")
		(net "PWRGD_PVPP_GHJ")
	)
	(segment
		(start 380.365 -67.832224)
		(end 380.365 -68.326)
		(width 0.089408)
		(layer "In11.Cu")
		(net "PWRGD_PVPP_GHJ")
	)
	(segment
		(start 326.417432 -15.584932)
		(end 325.07555 -16.926814)
		(width 0.089408)
		(layer "In11.Cu")
		(net "PWRGD_PVPP_GHJ")
	)
	(segment
		(start 379.791468 -69.974206)
		(end 379.791468 -70.705472)
		(width 0.089408)
		(layer "In11.Cu")
		(net "PWRGD_PVPP_GHJ")
	)
	(segment
		(start 325.049388 -9.140698)
		(end 326.24649 -10.3378)
		(width 0.089408)
		(layer "In11.Cu")
		(net "PWRGD_PVPP_GHJ")
	)
	(segment
		(start 329.550776 -35.518598)
		(end 332.542642 -38.510464)
		(width 0.089408)
		(layer "In11.Cu")
		(net "PWRGD_PVPP_GHJ")
	)
	(segment
		(start 379.791468 -69.689726)
		(end 379.80239 -69.700648)
		(width 0.089408)
		(layer "In11.Cu")
		(net "PWRGD_PVPP_GHJ")
	)
	(segment
		(start 380.222506 -75.22464)
		(end 380.222506 -76.40828)
		(width 0.089408)
		(layer "In11.Cu")
		(net "PWRGD_PVPP_GHJ")
	)
	(segment
		(start 336.696304 -41.040304)
		(end 353.251262 -41.040304)
		(width 0.089408)
		(layer "In11.Cu")
		(net "PWRGD_PVPP_GHJ")
	)
	(segment
		(start 355.150166 -39.1414)
		(end 356.84714 -39.1414)
		(width 0.089408)
		(layer "In11.Cu")
		(net "PWRGD_PVPP_GHJ")
	)
	(segment
		(start 325.07555 -16.926814)
		(end 325.07555 -24.492966)
		(width 0.089408)
		(layer "In11.Cu")
		(net "PWRGD_PVPP_GHJ")
	)
	(segment
		(start 179.373784 -3.168904)
		(end 180.833268 -3.168904)
		(width 0.089408)
		(layer "In11.Cu")
		(net "PWRGD_PVPP_GHJ")
	)
	(segment
		(start 380.536704 -71.309738)
		(end 380.536704 -71.641462)
		(width 0.089408)
		(layer "In11.Cu")
		(net "PWRGD_PVPP_GHJ")
	)
	(segment
		(start 325.049388 -2.042414)
		(end 325.049388 -9.140698)
		(width 0.089408)
		(layer "In11.Cu")
		(net "PWRGD_PVPP_GHJ")
	)
	(segment
		(start 324.694804 4.543044)
		(end 325.291704 3.946144)
		(width 0.089408)
		(layer "In11.Cu")
		(net "PWRGD_PVPP_GHJ")
	)
	(segment
		(start 377.734068 -58.930286)
		(end 378.476002 -59.67222)
		(width 0.089408)
		(layer "In11.Cu")
		(net "PWRGD_PVPP_GHJ")
	)
	(segment
		(start 332.542642 -38.510464)
		(end 333.108808 -38.510464)
		(width 0.089408)
		(layer "In11.Cu")
		(net "PWRGD_PVPP_GHJ")
	)
	(segment
		(start 333.922624 -39.32428)
		(end 334.98028 -39.32428)
		(width 0.089408)
		(layer "In11.Cu")
		(net "PWRGD_PVPP_GHJ")
	)
	(segment
		(start 379.80239 -69.348096)
		(end 379.791468 -69.359018)
		(width 0.089408)
		(layer "In11.Cu")
		(net "PWRGD_PVPP_GHJ")
	)
	(segment
		(start 329.023218 -10.3378)
		(end 330.25842 -11.573002)
		(width 0.089408)
		(layer "In11.Cu")
		(net "PWRGD_PVPP_GHJ")
	)
	(segment
		(start 380.365 -68.326)
		(end 379.80239 -68.88861)
		(width 0.089408)
		(layer "In11.Cu")
		(net "PWRGD_PVPP_GHJ")
	)
	(segment
		(start 379.791468 -70.705472)
		(end 380.161292 -71.075296)
		(width 0.089408)
		(layer "In11.Cu")
		(net "PWRGD_PVPP_GHJ")
	)
	(segment
		(start 380.536704 -71.641462)
		(end 379.744732 -72.433434)
		(width 0.089408)
		(layer "In11.Cu")
		(net "PWRGD_PVPP_GHJ")
	)
	(segment
		(start 380.302262 -71.075296)
		(end 380.536704 -71.309738)
		(width 0.089408)
		(layer "In11.Cu")
		(net "PWRGD_PVPP_GHJ")
	)
	(segment
		(start 376.69724 -55.82285)
		(end 377.734068 -56.859678)
		(width 0.089408)
		(layer "In11.Cu")
		(net "PWRGD_PVPP_GHJ")
	)
	(segment
		(start 181.69763 1.366012)
		(end 181.69763 2.405126)
		(width 0.089408)
		(layer "In11.Cu")
		(net "PWRGD_PVPP_GHJ")
	)
	(segment
		(start 377.734068 -56.859678)
		(end 377.734068 -58.930286)
		(width 0.089408)
		(layer "In11.Cu")
		(net "PWRGD_PVPP_GHJ")
	)
	(segment
		(start 373.806974 -55.82285)
		(end 376.69724 -55.82285)
		(width 0.089408)
		(layer "In11.Cu")
		(net "PWRGD_PVPP_GHJ")
	)
	(segment
		(start 356.84714 -39.1414)
		(end 366.073182 -48.367442)
		(width 0.089408)
		(layer "In11.Cu")
		(net "PWRGD_PVPP_GHJ")
	)
	(segment
		(start 379.80239 -68.88861)
		(end 379.80239 -69.348096)
		(width 0.089408)
		(layer "In11.Cu")
		(net "PWRGD_PVPP_GHJ")
	)
	(segment
		(start 325.12635 -1.965452)
		(end 325.049388 -2.042414)
		(width 0.089408)
		(layer "In11.Cu")
		(net "PWRGD_PVPP_GHJ")
	)
	(segment
		(start 181.841902 1.22174)
		(end 181.69763 1.366012)
		(width 0.089408)
		(layer "In11.Cu")
		(net "PWRGD_PVPP_GHJ")
	)
	(segment
		(start 175.8696 -5.2832)
		(end 175.8696 -4.7625)
		(width 0.089408)
		(layer "In11.Cu")
		(net "PWRGD_PVPP_GHJ")
	)
	(segment
		(start 180.833268 -3.168904)
		(end 181.841902 -2.16027)
		(width 0.089408)
		(layer "In11.Cu")
		(net "PWRGD_PVPP_GHJ")
	)
	(segment
		(start 378.476002 -59.67222)
		(end 378.476002 -63.049912)
		(width 0.089408)
		(layer "In11.Cu")
		(net "PWRGD_PVPP_GHJ")
	)
	(segment
		(start 379.744732 -74.746866)
		(end 380.222506 -75.22464)
		(width 0.089408)
		(layer "In11.Cu")
		(net "PWRGD_PVPP_GHJ")
	)
	(segment
		(start 325.07555 -24.492966)
		(end 327.877424 -27.29484)
		(width 0.089408)
		(layer "In11.Cu")
		(net "PWRGD_PVPP_GHJ")
	)
	(segment
		(start 380.367286 -76.55306)
		(end 380.367286 -76.99248)
		(width 0.089408)
		(layer "In11.Cu")
		(net "PWRGD_PVPP_GHJ")
	)
	(segment
		(start 377.971812 -63.554102)
		(end 377.971812 -63.559436)
		(width 0.089408)
		(layer "In11.Cu")
		(net "PWRGD_PVPP_GHJ")
	)
	(segment
		(start 328.525124 -15.584932)
		(end 326.417432 -15.584932)
		(width 0.089408)
		(layer "In11.Cu")
		(net "PWRGD_PVPP_GHJ")
	)
	(segment
		(start 177.023268 -3.608832)
		(end 178.933856 -3.608832)
		(width 0.089408)
		(layer "In11.Cu")
		(net "PWRGD_PVPP_GHJ")
	)
	(segment
		(start 178.933856 -3.608832)
		(end 179.373784 -3.168904)
		(width 0.089408)
		(layer "In11.Cu")
		(net "PWRGD_PVPP_GHJ")
	)
	(segment
		(start 380.222506 -76.40828)
		(end 380.367286 -76.55306)
		(width 0.089408)
		(layer "In11.Cu")
		(net "PWRGD_PVPP_GHJ")
	)
	(segment
		(start 329.550776 -32.939736)
		(end 329.550776 -35.518598)
		(width 0.089408)
		(layer "In11.Cu")
		(net "PWRGD_PVPP_GHJ")
	)
	(segment
		(start 380.161292 -71.075296)
		(end 380.302262 -71.075296)
		(width 0.089408)
		(layer "In11.Cu")
		(net "PWRGD_PVPP_GHJ")
	)
	(segment
		(start 379.654816 -67.184016)
		(end 380.0602 -67.5894)
		(width 0.089408)
		(layer "In11.Cu")
		(net "PWRGD_PVPP_GHJ")
	)
	(segment
		(start 377.89612 -66.303652)
		(end 378.776484 -67.184016)
		(width 0.089408)
		(layer "In11.Cu")
		(net "PWRGD_PVPP_GHJ")
	)
	(segment
		(start 375.144792 -77.494892)
		(end 374.744996 -77.095096)
		(width 0.10795)
		(layer "F.Cu")
		(net "PWRGD_PVPP_DEF")
	)
	(segment
		(start 353.810062 -131.575048)
		(end 354.391468 -132.156454)
		(width 0.10795)
		(layer "F.Cu")
		(net "PWRGD_PVPP_DEF")
	)
	(segment
		(start 353.810062 -129.382266)
		(end 353.810062 -131.575048)
		(width 0.10795)
		(layer "F.Cu")
		(net "PWRGD_PVPP_DEF")
	)
	(via
		(at 375.144792 -77.494892)
		(size 0.4572)
		(drill 0.2032)
		(layers "F.Cu" "B.Cu")
		(net "PWRGD_PVPP_DEF")
	)
	(via
		(at 354.391468 -132.156454)
		(size 0.508)
		(drill 0.254)
		(layers "F.Cu" "B.Cu")
		(net "PWRGD_PVPP_DEF")
	)
	(via
		(at 365.495332 -83.819746)
		(size 0.6604)
		(drill 0.3302)
		(layers "F.Cu" "B.Cu")
		(net "PWRGD_PVPP_DEF")
	)
	(via
		(at 359.664 -85.217)
		(size 0.508)
		(drill 0.254)
		(layers "F.Cu" "B.Cu")
		(net "PWRGD_PVPP_DEF")
	)
	(segment
		(start 373.792496 -81.512664)
		(end 373.792496 -80.988154)
		(width 0.10795)
		(layer "B.Cu")
		(net "PWRGD_PVPP_DEF")
	)
	(segment
		(start 374.7516 -77.888084)
		(end 375.144792 -77.494892)
		(width 0.10795)
		(layer "B.Cu")
		(net "PWRGD_PVPP_DEF")
	)
	(segment
		(start 365.495332 -83.819746)
		(end 366.480344 -82.834734)
		(width 0.10795)
		(layer "B.Cu")
		(net "PWRGD_PVPP_DEF")
	)
	(segment
		(start 373.86768 -81.944972)
		(end 373.86768 -81.587848)
		(width 0.10795)
		(layer "B.Cu")
		(net "PWRGD_PVPP_DEF")
	)
	(segment
		(start 372.366032 -82.047334)
		(end 373.088154 -82.047334)
		(width 0.10795)
		(layer "B.Cu")
		(net "PWRGD_PVPP_DEF")
	)
	(segment
		(start 364.580678 -84.7344)
		(end 360.1466 -84.7344)
		(width 0.10795)
		(layer "B.Cu")
		(net "PWRGD_PVPP_DEF")
	)
	(segment
		(start 360.1466 -84.7344)
		(end 359.664 -85.217)
		(width 0.10795)
		(layer "B.Cu")
		(net "PWRGD_PVPP_DEF")
	)
	(segment
		(start 373.950992 -79.652622)
		(end 374.113298 -79.490316)
		(width 0.10795)
		(layer "B.Cu")
		(net "PWRGD_PVPP_DEF")
	)
	(segment
		(start 366.480344 -82.834734)
		(end 367.054892 -82.834734)
		(width 0.10795)
		(layer "B.Cu")
		(net "PWRGD_PVPP_DEF")
	)
	(segment
		(start 367.054892 -82.834734)
		(end 367.633758 -82.255868)
		(width 0.10795)
		(layer "B.Cu")
		(net "PWRGD_PVPP_DEF")
	)
	(segment
		(start 374.523254 -79.490316)
		(end 374.7516 -79.26197)
		(width 0.10795)
		(layer "B.Cu")
		(net "PWRGD_PVPP_DEF")
	)
	(segment
		(start 373.950992 -80.829658)
		(end 373.950992 -79.652622)
		(width 0.10795)
		(layer "B.Cu")
		(net "PWRGD_PVPP_DEF")
	)
	(segment
		(start 373.620284 -82.192368)
		(end 373.86768 -81.944972)
		(width 0.10795)
		(layer "B.Cu")
		(net "PWRGD_PVPP_DEF")
	)
	(segment
		(start 373.088154 -82.047334)
		(end 373.233188 -82.192368)
		(width 0.10795)
		(layer "B.Cu")
		(net "PWRGD_PVPP_DEF")
	)
	(segment
		(start 372.157498 -82.255868)
		(end 372.366032 -82.047334)
		(width 0.10795)
		(layer "B.Cu")
		(net "PWRGD_PVPP_DEF")
	)
	(segment
		(start 374.113298 -79.490316)
		(end 374.523254 -79.490316)
		(width 0.10795)
		(layer "B.Cu")
		(net "PWRGD_PVPP_DEF")
	)
	(segment
		(start 374.7516 -79.26197)
		(end 374.7516 -77.888084)
		(width 0.10795)
		(layer "B.Cu")
		(net "PWRGD_PVPP_DEF")
	)
	(segment
		(start 373.792496 -80.988154)
		(end 373.950992 -80.829658)
		(width 0.10795)
		(layer "B.Cu")
		(net "PWRGD_PVPP_DEF")
	)
	(segment
		(start 365.495332 -83.819746)
		(end 364.580678 -84.7344)
		(width 0.10795)
		(layer "B.Cu")
		(net "PWRGD_PVPP_DEF")
	)
	(segment
		(start 367.633758 -82.255868)
		(end 372.157498 -82.255868)
		(width 0.10795)
		(layer "B.Cu")
		(net "PWRGD_PVPP_DEF")
	)
	(segment
		(start 373.86768 -81.587848)
		(end 373.792496 -81.512664)
		(width 0.10795)
		(layer "B.Cu")
		(net "PWRGD_PVPP_DEF")
	)
	(segment
		(start 373.233188 -82.192368)
		(end 373.620284 -82.192368)
		(width 0.10795)
		(layer "B.Cu")
		(net "PWRGD_PVPP_DEF")
	)
	(segment
		(start 344.986102 -126.10211)
		(end 344.986102 -122.094752)
		(width 0.089408)
		(layer "In4.Cu")
		(net "PWRGD_PVPP_DEF")
	)
	(segment
		(start 354.391468 -131.75615)
		(end 353.201732 -130.566414)
		(width 0.089408)
		(layer "In4.Cu")
		(net "PWRGD_PVPP_DEF")
	)
	(segment
		(start 353.201732 -130.566414)
		(end 349.450406 -130.566414)
		(width 0.089408)
		(layer "In4.Cu")
		(net "PWRGD_PVPP_DEF")
	)
	(segment
		(start 359.181654 -85.699346)
		(end 359.664 -85.217)
		(width 0.089408)
		(layer "In4.Cu")
		(net "PWRGD_PVPP_DEF")
	)
	(segment
		(start 354.391468 -132.156454)
		(end 354.391468 -131.75615)
		(width 0.089408)
		(layer "In4.Cu")
		(net "PWRGD_PVPP_DEF")
	)
	(segment
		(start 359.181654 -87.98687)
		(end 359.181654 -85.699346)
		(width 0.089408)
		(layer "In4.Cu")
		(net "PWRGD_PVPP_DEF")
	)
	(segment
		(start 351.75063 -105.650792)
		(end 357.71074 -99.690682)
		(width 0.089408)
		(layer "In4.Cu")
		(net "PWRGD_PVPP_DEF")
	)
	(segment
		(start 345.865704 -108.618274)
		(end 348.833186 -105.650792)
		(width 0.089408)
		(layer "In4.Cu")
		(net "PWRGD_PVPP_DEF")
	)
	(segment
		(start 345.865704 -116.604288)
		(end 345.865704 -108.618274)
		(width 0.089408)
		(layer "In4.Cu")
		(net "PWRGD_PVPP_DEF")
	)
	(segment
		(start 357.71074 -99.690682)
		(end 357.71074 -89.457784)
		(width 0.089408)
		(layer "In4.Cu")
		(net "PWRGD_PVPP_DEF")
	)
	(segment
		(start 348.833186 -105.650792)
		(end 351.75063 -105.650792)
		(width 0.089408)
		(layer "In4.Cu")
		(net "PWRGD_PVPP_DEF")
	)
	(segment
		(start 349.450406 -130.566414)
		(end 344.986102 -126.10211)
		(width 0.089408)
		(layer "In4.Cu")
		(net "PWRGD_PVPP_DEF")
	)
	(segment
		(start 357.71074 -89.457784)
		(end 359.181654 -87.98687)
		(width 0.089408)
		(layer "In4.Cu")
		(net "PWRGD_PVPP_DEF")
	)
	(segment
		(start 344.986102 -122.094752)
		(end 345.636088 -121.444766)
		(width 0.089408)
		(layer "In4.Cu")
		(net "PWRGD_PVPP_DEF")
	)
	(segment
		(start 345.636088 -121.444766)
		(end 345.636088 -116.833904)
		(width 0.089408)
		(layer "In4.Cu")
		(net "PWRGD_PVPP_DEF")
	)
	(segment
		(start 345.636088 -116.833904)
		(end 345.865704 -116.604288)
		(width 0.089408)
		(layer "In4.Cu")
		(net "PWRGD_PVPP_DEF")
	)
	(segment
		(start 348.5642 -21.9456)
		(end 348.384114 -22.125686)
		(width 0.10795)
		(layer "F.Cu")
		(net "PWRGD_PVPP_ABC")
	)
	(segment
		(start 415.191194 -123.740418)
		(end 416.578288 -123.740418)
		(width 0.10795)
		(layer "F.Cu")
		(net "PWRGD_PVPP_ABC")
	)
	(segment
		(start 416.578288 -123.740418)
		(end 416.748722 -123.910852)
		(width 0.10795)
		(layer "F.Cu")
		(net "PWRGD_PVPP_ABC")
	)
	(segment
		(start 416.748722 -123.89104)
		(end 416.758374 -123.89104)
		(width 0.10795)
		(layer "F.Cu")
		(net "PWRGD_PVPP_ABC")
	)
	(segment
		(start 348.384114 -22.125686)
		(end 348.384114 -22.597618)
		(width 0.10795)
		(layer "F.Cu")
		(net "PWRGD_PVPP_ABC")
	)
	(segment
		(start 416.748722 -123.910852)
		(end 416.748722 -123.89104)
		(width 0.10795)
		(layer "F.Cu")
		(net "PWRGD_PVPP_ABC")
	)
	(segment
		(start 373.944896 -77.894942)
		(end 374.344692 -78.294738)
		(width 0.10795)
		(layer "F.Cu")
		(net "PWRGD_PVPP_ABC")
	)
	(via
		(at 324.5104 -26.9748)
		(size 0.508)
		(drill 0.254)
		(layers "F.Cu" "B.Cu")
		(net "PWRGD_PVPP_ABC")
	)
	(via
		(at 426.4914 -69.5706)
		(size 0.508)
		(drill 0.254)
		(layers "F.Cu" "B.Cu")
		(net "PWRGD_PVPP_ABC")
	)
	(via
		(at 412.698692 -61.451998)
		(size 0.508)
		(drill 0.254)
		(layers "F.Cu" "B.Cu")
		(net "PWRGD_PVPP_ABC")
	)
	(via
		(at 348.5642 -21.9456)
		(size 0.508)
		(drill 0.254)
		(layers "F.Cu" "B.Cu")
		(net "PWRGD_PVPP_ABC")
	)
	(via
		(at 374.344692 -78.294738)
		(size 0.4572)
		(drill 0.2032)
		(layers "F.Cu" "B.Cu")
		(net "PWRGD_PVPP_ABC")
	)
	(via
		(at 377.825 -62.103)
		(size 0.508)
		(drill 0.254)
		(layers "F.Cu" "B.Cu")
		(net "PWRGD_PVPP_ABC")
	)
	(via
		(at 416.758374 -123.89104)
		(size 0.508)
		(drill 0.254)
		(layers "F.Cu" "B.Cu")
		(net "PWRGD_PVPP_ABC")
	)
	(via
		(at 414.3502 -71.2216)
		(size 0.508)
		(drill 0.254)
		(layers "F.Cu" "B.Cu")
		(net "PWRGD_PVPP_ABC")
	)
	(segment
		(start 424.742864 -58.169048)
		(end 424.851068 -58.277252)
		(width 0.10795)
		(layer "B.Cu")
		(net "PWRGD_PVPP_ABC")
	)
	(segment
		(start 426.308012 -59.858148)
		(end 426.308012 -62.448694)
		(width 0.10795)
		(layer "B.Cu")
		(net "PWRGD_PVPP_ABC")
	)
	(segment
		(start 415.984182 -59.93384)
		(end 417.748974 -58.169048)
		(width 0.10795)
		(layer "B.Cu")
		(net "PWRGD_PVPP_ABC")
	)
	(segment
		(start 424.852846 -58.277252)
		(end 426.2882 -59.712606)
		(width 0.10795)
		(layer "B.Cu")
		(net "PWRGD_PVPP_ABC")
	)
	(segment
		(start 426.2882 -59.712606)
		(end 426.2882 -59.838336)
		(width 0.10795)
		(layer "B.Cu")
		(net "PWRGD_PVPP_ABC")
	)
	(segment
		(start 412.795466 -60.698888)
		(end 413.560514 -59.93384)
		(width 0.10795)
		(layer "B.Cu")
		(net "PWRGD_PVPP_ABC")
	)
	(segment
		(start 417.748974 -58.169048)
		(end 424.742864 -58.169048)
		(width 0.10795)
		(layer "B.Cu")
		(net "PWRGD_PVPP_ABC")
	)
	(segment
		(start 426.068998 -68.735194)
		(end 426.068998 -69.148198)
		(width 0.10795)
		(layer "B.Cu")
		(net "PWRGD_PVPP_ABC")
	)
	(segment
		(start 413.560514 -59.93384)
		(end 415.984182 -59.93384)
		(width 0.10795)
		(layer "B.Cu")
		(net "PWRGD_PVPP_ABC")
	)
	(segment
		(start 426.308012 -62.448694)
		(end 426.749718 -62.8904)
		(width 0.10795)
		(layer "B.Cu")
		(net "PWRGD_PVPP_ABC")
	)
	(segment
		(start 426.2882 -59.838336)
		(end 426.308012 -59.858148)
		(width 0.10795)
		(layer "B.Cu")
		(net "PWRGD_PVPP_ABC")
	)
	(segment
		(start 412.795466 -61.355224)
		(end 412.795466 -60.698888)
		(width 0.10795)
		(layer "B.Cu")
		(net "PWRGD_PVPP_ABC")
	)
	(segment
		(start 424.851068 -58.277252)
		(end 424.852846 -58.277252)
		(width 0.10795)
		(layer "B.Cu")
		(net "PWRGD_PVPP_ABC")
	)
	(segment
		(start 426.749718 -68.054474)
		(end 426.068998 -68.735194)
		(width 0.10795)
		(layer "B.Cu")
		(net "PWRGD_PVPP_ABC")
	)
	(segment
		(start 412.698692 -61.451998)
		(end 412.795466 -61.355224)
		(width 0.10795)
		(layer "B.Cu")
		(net "PWRGD_PVPP_ABC")
	)
	(segment
		(start 426.068998 -69.148198)
		(end 426.4914 -69.5706)
		(width 0.10795)
		(layer "B.Cu")
		(net "PWRGD_PVPP_ABC")
	)
	(segment
		(start 426.749718 -62.8904)
		(end 426.749718 -68.054474)
		(width 0.10795)
		(layer "B.Cu")
		(net "PWRGD_PVPP_ABC")
	)
	(segment
		(start 381.052324 -77.834744)
		(end 380.923546 -77.963522)
		(width 0.089408)
		(layer "In4.Cu")
		(net "PWRGD_PVPP_ABC")
	)
	(segment
		(start 348.1324 -21.5138)
		(end 344.0684 -21.5138)
		(width 0.089408)
		(layer "In4.Cu")
		(net "PWRGD_PVPP_ABC")
	)
	(segment
		(start 403.031706 -73.309226)
		(end 402.873718 -73.309226)
		(width 0.089408)
		(layer "In4.Cu")
		(net "PWRGD_PVPP_ABC")
	)
	(segment
		(start 419.202362 -121.91746)
		(end 420.702994 -121.91746)
		(width 0.089408)
		(layer "In4.Cu")
		(net "PWRGD_PVPP_ABC")
	)
	(segment
		(start 379.020832 -78.406498)
		(end 378.744734 -78.682596)
		(width 0.089408)
		(layer "In4.Cu")
		(net "PWRGD_PVPP_ABC")
	)
	(segment
		(start 424.663616 -94.492318)
		(end 424.66387 -94.492064)
		(width 0.089408)
		(layer "In4.Cu")
		(net "PWRGD_PVPP_ABC")
	)
	(segment
		(start 344.0684 -21.5138)
		(end 343.789 -21.2344)
		(width 0.089408)
		(layer "In4.Cu")
		(net "PWRGD_PVPP_ABC")
	)
	(segment
		(start 343.789 -21.2344)
		(end 343.789 -20.32)
		(width 0.089408)
		(layer "In4.Cu")
		(net "PWRGD_PVPP_ABC")
	)
	(segment
		(start 402.873718 -73.309226)
		(end 401.635976 -74.546968)
		(width 0.089408)
		(layer "In4.Cu")
		(net "PWRGD_PVPP_ABC")
	)
	(segment
		(start 400.563842 -75.619102)
		(end 396.302738 -75.619102)
		(width 0.089408)
		(layer "In4.Cu")
		(net "PWRGD_PVPP_ABC")
	)
	(segment
		(start 378.744734 -78.682596)
		(end 374.73255 -78.682596)
		(width 0.089408)
		(layer "In4.Cu")
		(net "PWRGD_PVPP_ABC")
	)
	(segment
		(start 421.1066 -117.83949)
		(end 420.311834 -117.044724)
		(width 0.089408)
		(layer "In4.Cu")
		(net "PWRGD_PVPP_ABC")
	)
	(segment
		(start 424.663616 -94.291658)
		(end 424.663616 -70.677532)
		(width 0.089408)
		(layer "In4.Cu")
		(net "PWRGD_PVPP_ABC")
	)
	(segment
		(start 338.6328 -19.177)
		(end 338.6328 -20.39239)
		(width 0.089408)
		(layer "In4.Cu")
		(net "PWRGD_PVPP_ABC")
	)
	(segment
		(start 424.66641 -106.22026)
		(end 424.66641 -103.846122)
		(width 0.089408)
		(layer "In4.Cu")
		(net "PWRGD_PVPP_ABC")
	)
	(segment
		(start 422.348406 -106.774488)
		(end 424.112182 -106.774488)
		(width 0.089408)
		(layer "In4.Cu")
		(net "PWRGD_PVPP_ABC")
	)
	(segment
		(start 412.220664 -72.817736)
		(end 407.074624 -72.817736)
		(width 0.089408)
		(layer "In4.Cu")
		(net "PWRGD_PVPP_ABC")
	)
	(segment
		(start 416.758374 -123.89104)
		(end 416.748722 -123.89104)
		(width 0.089408)
		(layer "In4.Cu")
		(net "PWRGD_PVPP_ABC")
	)
	(segment
		(start 380.48057 -78.406498)
		(end 379.020832 -78.406498)
		(width 0.089408)
		(layer "In4.Cu")
		(net "PWRGD_PVPP_ABC")
	)
	(segment
		(start 403.03196 -73.30948)
		(end 403.031706 -73.309226)
		(width 0.089408)
		(layer "In4.Cu")
		(net "PWRGD_PVPP_ABC")
	)
	(segment
		(start 414.3502 -71.2216)
		(end 413.8168 -71.2216)
		(width 0.089408)
		(layer "In4.Cu")
		(net "PWRGD_PVPP_ABC")
	)
	(segment
		(start 342.1634 -18.6944)
		(end 339.1154 -18.6944)
		(width 0.089408)
		(layer "In4.Cu")
		(net "PWRGD_PVPP_ABC")
	)
	(segment
		(start 380.923292 -77.963522)
		(end 380.732538 -78.154276)
		(width 0.089408)
		(layer "In4.Cu")
		(net "PWRGD_PVPP_ABC")
	)
	(segment
		(start 420.702994 -121.91746)
		(end 421.1066 -121.513854)
		(width 0.089408)
		(layer "In4.Cu")
		(net "PWRGD_PVPP_ABC")
	)
	(segment
		(start 326.29856 -26.9748)
		(end 324.5104 -26.9748)
		(width 0.089408)
		(layer "In4.Cu")
		(net "PWRGD_PVPP_ABC")
	)
	(segment
		(start 418.47516 -122.644662)
		(end 419.202362 -121.91746)
		(width 0.089408)
		(layer "In4.Cu")
		(net "PWRGD_PVPP_ABC")
	)
	(segment
		(start 330.9239 -30.7594)
		(end 330.3778 -30.7594)
		(width 0.089408)
		(layer "In4.Cu")
		(net "PWRGD_PVPP_ABC")
	)
	(segment
		(start 401.635976 -74.546968)
		(end 401.56765 -74.546968)
		(width 0.089408)
		(layer "In4.Cu")
		(net "PWRGD_PVPP_ABC")
	)
	(segment
		(start 392.534648 -76.18984)
		(end 391.974578 -76.74991)
		(width 0.089408)
		(layer "In4.Cu")
		(net "PWRGD_PVPP_ABC")
	)
	(segment
		(start 338.6328 -20.39239)
		(end 338.474304 -20.550886)
		(width 0.089408)
		(layer "In4.Cu")
		(net "PWRGD_PVPP_ABC")
	)
	(segment
		(start 331.4065 -27.37739)
		(end 331.4065 -30.2768)
		(width 0.089408)
		(layer "In4.Cu")
		(net "PWRGD_PVPP_ABC")
	)
	(segment
		(start 424.66387 -94.291912)
		(end 424.663616 -94.291658)
		(width 0.089408)
		(layer "In4.Cu")
		(net "PWRGD_PVPP_ABC")
	)
	(segment
		(start 328.549 -27.6098)
		(end 326.93356 -27.6098)
		(width 0.089408)
		(layer "In4.Cu")
		(net "PWRGD_PVPP_ABC")
	)
	(segment
		(start 416.904678 -123.620784)
		(end 417.8808 -122.644662)
		(width 0.089408)
		(layer "In4.Cu")
		(net "PWRGD_PVPP_ABC")
	)
	(segment
		(start 401.221448 -74.961496)
		(end 400.563842 -75.619102)
		(width 0.089408)
		(layer "In4.Cu")
		(net "PWRGD_PVPP_ABC")
	)
	(segment
		(start 424.66641 -103.846122)
		(end 424.663616 -103.843328)
		(width 0.089408)
		(layer "In4.Cu")
		(net "PWRGD_PVPP_ABC")
	)
	(segment
		(start 417.8808 -122.644662)
		(end 418.47516 -122.644662)
		(width 0.089408)
		(layer "In4.Cu")
		(net "PWRGD_PVPP_ABC")
	)
	(segment
		(start 332.323186 -26.460704)
		(end 331.4065 -27.37739)
		(width 0.089408)
		(layer "In4.Cu")
		(net "PWRGD_PVPP_ABC")
	)
	(segment
		(start 381.821944 -76.74991)
		(end 381.052324 -77.51953)
		(width 0.089408)
		(layer "In4.Cu")
		(net "PWRGD_PVPP_ABC")
	)
	(segment
		(start 406.58288 -73.30948)
		(end 403.03196 -73.30948)
		(width 0.089408)
		(layer "In4.Cu")
		(net "PWRGD_PVPP_ABC")
	)
	(segment
		(start 330.2508 -30.6324)
		(end 330.2508 -29.3116)
		(width 0.089408)
		(layer "In4.Cu")
		(net "PWRGD_PVPP_ABC")
	)
	(segment
		(start 407.074624 -72.817736)
		(end 406.58288 -73.30948)
		(width 0.089408)
		(layer "In4.Cu")
		(net "PWRGD_PVPP_ABC")
	)
	(segment
		(start 380.923546 -77.963522)
		(end 380.923292 -77.963522)
		(width 0.089408)
		(layer "In4.Cu")
		(net "PWRGD_PVPP_ABC")
	)
	(segment
		(start 401.221448 -74.89317)
		(end 401.221448 -74.961496)
		(width 0.089408)
		(layer "In4.Cu")
		(net "PWRGD_PVPP_ABC")
	)
	(segment
		(start 424.66387 -94.492064)
		(end 424.66387 -94.291912)
		(width 0.089408)
		(layer "In4.Cu")
		(net "PWRGD_PVPP_ABC")
	)
	(segment
		(start 338.474304 -20.550886)
		(end 338.474304 -21.37664)
		(width 0.089408)
		(layer "In4.Cu")
		(net "PWRGD_PVPP_ABC")
	)
	(segment
		(start 333.39024 -26.460704)
		(end 332.323186 -26.460704)
		(width 0.089408)
		(layer "In4.Cu")
		(net "PWRGD_PVPP_ABC")
	)
	(segment
		(start 339.1154 -18.6944)
		(end 338.6328 -19.177)
		(width 0.089408)
		(layer "In4.Cu")
		(net "PWRGD_PVPP_ABC")
	)
	(segment
		(start 396.302738 -75.619102)
		(end 395.732 -76.18984)
		(width 0.089408)
		(layer "In4.Cu")
		(net "PWRGD_PVPP_ABC")
	)
	(segment
		(start 424.663616 -70.677532)
		(end 425.770548 -69.5706)
		(width 0.089408)
		(layer "In4.Cu")
		(net "PWRGD_PVPP_ABC")
	)
	(segment
		(start 380.732538 -78.15453)
		(end 380.48057 -78.406498)
		(width 0.089408)
		(layer "In4.Cu")
		(net "PWRGD_PVPP_ABC")
	)
	(segment
		(start 380.732538 -78.154276)
		(end 380.732538 -78.15453)
		(width 0.089408)
		(layer "In4.Cu")
		(net "PWRGD_PVPP_ABC")
	)
	(segment
		(start 374.73255 -78.682596)
		(end 374.344692 -78.294738)
		(width 0.089408)
		(layer "In4.Cu")
		(net "PWRGD_PVPP_ABC")
	)
	(segment
		(start 338.474304 -21.37664)
		(end 333.39024 -26.460704)
		(width 0.089408)
		(layer "In4.Cu")
		(net "PWRGD_PVPP_ABC")
	)
	(segment
		(start 343.789 -20.32)
		(end 342.1634 -18.6944)
		(width 0.089408)
		(layer "In4.Cu")
		(net "PWRGD_PVPP_ABC")
	)
	(segment
		(start 416.748722 -123.89104)
		(end 416.748722 -123.910852)
		(width 0.089408)
		(layer "In4.Cu")
		(net "PWRGD_PVPP_ABC")
	)
	(segment
		(start 401.56765 -74.546968)
		(end 401.221448 -74.89317)
		(width 0.089408)
		(layer "In4.Cu")
		(net "PWRGD_PVPP_ABC")
	)
	(segment
		(start 348.5642 -21.9456)
		(end 348.1324 -21.5138)
		(width 0.089408)
		(layer "In4.Cu")
		(net "PWRGD_PVPP_ABC")
	)
	(segment
		(start 326.93356 -27.6098)
		(end 326.29856 -26.9748)
		(width 0.089408)
		(layer "In4.Cu")
		(net "PWRGD_PVPP_ABC")
	)
	(segment
		(start 330.3778 -30.7594)
		(end 330.2508 -30.6324)
		(width 0.089408)
		(layer "In4.Cu")
		(net "PWRGD_PVPP_ABC")
	)
	(segment
		(start 420.311834 -117.044724)
		(end 420.311834 -108.81106)
		(width 0.089408)
		(layer "In4.Cu")
		(net "PWRGD_PVPP_ABC")
	)
	(segment
		(start 416.904678 -123.754896)
		(end 416.904678 -123.620784)
		(width 0.089408)
		(layer "In4.Cu")
		(net "PWRGD_PVPP_ABC")
	)
	(segment
		(start 413.8168 -71.2216)
		(end 412.220664 -72.817736)
		(width 0.089408)
		(layer "In4.Cu")
		(net "PWRGD_PVPP_ABC")
	)
	(segment
		(start 381.052324 -77.51953)
		(end 381.052324 -77.834744)
		(width 0.089408)
		(layer "In4.Cu")
		(net "PWRGD_PVPP_ABC")
	)
	(segment
		(start 416.748722 -123.910852)
		(end 416.904678 -123.754896)
		(width 0.089408)
		(layer "In4.Cu")
		(net "PWRGD_PVPP_ABC")
	)
	(segment
		(start 420.311834 -108.81106)
		(end 422.348406 -106.774488)
		(width 0.089408)
		(layer "In4.Cu")
		(net "PWRGD_PVPP_ABC")
	)
	(segment
		(start 331.4065 -30.2768)
		(end 330.9239 -30.7594)
		(width 0.089408)
		(layer "In4.Cu")
		(net "PWRGD_PVPP_ABC")
	)
	(segment
		(start 391.974578 -76.74991)
		(end 381.821944 -76.74991)
		(width 0.089408)
		(layer "In4.Cu")
		(net "PWRGD_PVPP_ABC")
	)
	(segment
		(start 421.1066 -121.513854)
		(end 421.1066 -117.83949)
		(width 0.089408)
		(layer "In4.Cu")
		(net "PWRGD_PVPP_ABC")
	)
	(segment
		(start 425.770548 -69.5706)
		(end 426.4914 -69.5706)
		(width 0.089408)
		(layer "In4.Cu")
		(net "PWRGD_PVPP_ABC")
	)
	(segment
		(start 330.2508 -29.3116)
		(end 328.549 -27.6098)
		(width 0.089408)
		(layer "In4.Cu")
		(net "PWRGD_PVPP_ABC")
	)
	(segment
		(start 395.732 -76.18984)
		(end 392.534648 -76.18984)
		(width 0.089408)
		(layer "In4.Cu")
		(net "PWRGD_PVPP_ABC")
	)
	(segment
		(start 424.112182 -106.774488)
		(end 424.66641 -106.22026)
		(width 0.089408)
		(layer "In4.Cu")
		(net "PWRGD_PVPP_ABC")
	)
	(segment
		(start 424.663616 -103.843328)
		(end 424.663616 -94.492318)
		(width 0.089408)
		(layer "In4.Cu")
		(net "PWRGD_PVPP_ABC")
	)
	(segment
		(start 375.119392 -64.18707)
		(end 375.119392 -63.767208)
		(width 0.089408)
		(layer "In9.Cu")
		(net "PWRGD_PVPP_ABC")
	)
	(segment
		(start 373.443246 -77.921358)
		(end 372.970044 -77.448156)
		(width 0.089408)
		(layer "In9.Cu")
		(net "PWRGD_PVPP_ABC")
	)
	(segment
		(start 373.971312 -77.921358)
		(end 373.443246 -77.921358)
		(width 0.089408)
		(layer "In9.Cu")
		(net "PWRGD_PVPP_ABC")
	)
	(segment
		(start 372.711726 -68.188078)
		(end 372.711726 -67.621404)
		(width 0.089408)
		(layer "In9.Cu")
		(net "PWRGD_PVPP_ABC")
	)
	(segment
		(start 376.940826 -62.591696)
		(end 377.429522 -62.103)
		(width 0.089408)
		(layer "In9.Cu")
		(net "PWRGD_PVPP_ABC")
	)
	(segment
		(start 372.970044 -77.448156)
		(end 372.970044 -68.446396)
		(width 0.089408)
		(layer "In9.Cu")
		(net "PWRGD_PVPP_ABC")
	)
	(segment
		(start 374.535192 -64.77127)
		(end 375.119392 -64.18707)
		(width 0.089408)
		(layer "In9.Cu")
		(net "PWRGD_PVPP_ABC")
	)
	(segment
		(start 372.970044 -68.446396)
		(end 372.711726 -68.188078)
		(width 0.089408)
		(layer "In9.Cu")
		(net "PWRGD_PVPP_ABC")
	)
	(segment
		(start 373.9896 -66.34353)
		(end 373.9896 -64.999362)
		(width 0.089408)
		(layer "In9.Cu")
		(net "PWRGD_PVPP_ABC")
	)
	(segment
		(start 374.217692 -64.77127)
		(end 374.535192 -64.77127)
		(width 0.089408)
		(layer "In9.Cu")
		(net "PWRGD_PVPP_ABC")
	)
	(segment
		(start 374.344692 -78.294738)
		(end 373.971312 -77.921358)
		(width 0.089408)
		(layer "In9.Cu")
		(net "PWRGD_PVPP_ABC")
	)
	(segment
		(start 372.711726 -67.621404)
		(end 373.9896 -66.34353)
		(width 0.089408)
		(layer "In9.Cu")
		(net "PWRGD_PVPP_ABC")
	)
	(segment
		(start 375.119392 -63.767208)
		(end 376.294904 -62.591696)
		(width 0.089408)
		(layer "In9.Cu")
		(net "PWRGD_PVPP_ABC")
	)
	(segment
		(start 377.429522 -62.103)
		(end 377.825 -62.103)
		(width 0.089408)
		(layer "In9.Cu")
		(net "PWRGD_PVPP_ABC")
	)
	(segment
		(start 373.9896 -64.999362)
		(end 374.217692 -64.77127)
		(width 0.089408)
		(layer "In9.Cu")
		(net "PWRGD_PVPP_ABC")
	)
	(segment
		(start 376.294904 -62.591696)
		(end 376.940826 -62.591696)
		(width 0.089408)
		(layer "In9.Cu")
		(net "PWRGD_PVPP_ABC")
	)
	(segment
		(start 325.754746 -32.527494)
		(end 325.627746 -32.654494)
		(width 0.089408)
		(layer "In11.Cu")
		(net "PWRGD_PVPP_ABC")
	)
	(segment
		(start 414.140396 -66.596768)
		(end 414.4264 -66.882772)
		(width 0.089408)
		(layer "In11.Cu")
		(net "PWRGD_PVPP_ABC")
	)
	(segment
		(start 367.768378 -49.944528)
		(end 367.768378 -49.944782)
		(width 0.089408)
		(layer "In11.Cu")
		(net "PWRGD_PVPP_ABC")
	)
	(segment
		(start 334.296766 -40.3352)
		(end 335.705704 -41.744138)
		(width 0.089408)
		(layer "In11.Cu")
		(net "PWRGD_PVPP_ABC")
	)
	(segment
		(start 325.34479 -27.80919)
		(end 325.34479 -31.570676)
		(width 0.089408)
		(layer "In11.Cu")
		(net "PWRGD_PVPP_ABC")
	)
	(segment
		(start 326.876664 -40.2082)
		(end 327.696322 -40.2082)
		(width 0.089408)
		(layer "In11.Cu")
		(net "PWRGD_PVPP_ABC")
	)
	(segment
		(start 413.336994 -62.131194)
		(end 413.336994 -62.709044)
		(width 0.089408)
		(layer "In11.Cu")
		(net "PWRGD_PVPP_ABC")
	)
	(segment
		(start 370.27231 -52.448714)
		(end 370.27231 -53.36921)
		(width 0.089408)
		(layer "In11.Cu")
		(net "PWRGD_PVPP_ABC")
	)
	(segment
		(start 414.4264 -66.882772)
		(end 414.4264 -71.1454)
		(width 0.089408)
		(layer "In11.Cu")
		(net "PWRGD_PVPP_ABC")
	)
	(segment
		(start 413.336994 -62.709044)
		(end 413.841946 -63.213996)
		(width 0.089408)
		(layer "In11.Cu")
		(net "PWRGD_PVPP_ABC")
	)
	(segment
		(start 414.140396 -66.564002)
		(end 414.140396 -66.596768)
		(width 0.089408)
		(layer "In11.Cu")
		(net "PWRGD_PVPP_ABC")
	)
	(segment
		(start 374.394222 -56.91378)
		(end 377.88469 -60.404248)
		(width 0.089408)
		(layer "In11.Cu")
		(net "PWRGD_PVPP_ABC")
	)
	(segment
		(start 325.34479 -31.570676)
		(end 325.754746 -31.980632)
		(width 0.089408)
		(layer "In11.Cu")
		(net "PWRGD_PVPP_ABC")
	)
	(segment
		(start 336.198972 -42.7482)
		(end 355.160834 -42.7482)
		(width 0.089408)
		(layer "In11.Cu")
		(net "PWRGD_PVPP_ABC")
	)
	(segment
		(start 331.568298 -39.632128)
		(end 332.27137 -40.3352)
		(width 0.089408)
		(layer "In11.Cu")
		(net "PWRGD_PVPP_ABC")
	)
	(segment
		(start 412.698692 -61.492892)
		(end 413.336994 -62.131194)
		(width 0.089408)
		(layer "In11.Cu")
		(net "PWRGD_PVPP_ABC")
	)
	(segment
		(start 335.705704 -41.744138)
		(end 335.705704 -42.254932)
		(width 0.089408)
		(layer "In11.Cu")
		(net "PWRGD_PVPP_ABC")
	)
	(segment
		(start 328.272394 -39.632128)
		(end 331.568298 -39.632128)
		(width 0.089408)
		(layer "In11.Cu")
		(net "PWRGD_PVPP_ABC")
	)
	(segment
		(start 325.754746 -31.980632)
		(end 325.754746 -32.527494)
		(width 0.089408)
		(layer "In11.Cu")
		(net "PWRGD_PVPP_ABC")
	)
	(segment
		(start 332.27137 -40.3352)
		(end 334.296766 -40.3352)
		(width 0.089408)
		(layer "In11.Cu")
		(net "PWRGD_PVPP_ABC")
	)
	(segment
		(start 366.95507 -49.131474)
		(end 367.533682 -49.710086)
		(width 0.089408)
		(layer "In11.Cu")
		(net "PWRGD_PVPP_ABC")
	)
	(segment
		(start 413.841946 -66.265552)
		(end 414.140396 -66.564002)
		(width 0.089408)
		(layer "In11.Cu")
		(net "PWRGD_PVPP_ABC")
	)
	(segment
		(start 413.841946 -63.213996)
		(end 413.841946 -66.265552)
		(width 0.089408)
		(layer "In11.Cu")
		(net "PWRGD_PVPP_ABC")
	)
	(segment
		(start 326.01154 -35.366706)
		(end 326.01154 -39.343076)
		(width 0.089408)
		(layer "In11.Cu")
		(net "PWRGD_PVPP_ABC")
	)
	(segment
		(start 412.698692 -61.451998)
		(end 412.698692 -61.492892)
		(width 0.089408)
		(layer "In11.Cu")
		(net "PWRGD_PVPP_ABC")
	)
	(segment
		(start 359.264204 -42.80662)
		(end 365.589058 -49.131474)
		(width 0.089408)
		(layer "In11.Cu")
		(net "PWRGD_PVPP_ABC")
	)
	(segment
		(start 365.589058 -49.131474)
		(end 366.95507 -49.131474)
		(width 0.089408)
		(layer "In11.Cu")
		(net "PWRGD_PVPP_ABC")
	)
	(segment
		(start 370.27231 -53.36921)
		(end 373.81688 -56.91378)
		(width 0.089408)
		(layer "In11.Cu")
		(net "PWRGD_PVPP_ABC")
	)
	(segment
		(start 335.705704 -42.254932)
		(end 336.198972 -42.7482)
		(width 0.089408)
		(layer "In11.Cu")
		(net "PWRGD_PVPP_ABC")
	)
	(segment
		(start 367.533682 -49.710086)
		(end 367.533936 -49.710086)
		(width 0.089408)
		(layer "In11.Cu")
		(net "PWRGD_PVPP_ABC")
	)
	(segment
		(start 377.88469 -62.04331)
		(end 377.825 -62.103)
		(width 0.089408)
		(layer "In11.Cu")
		(net "PWRGD_PVPP_ABC")
	)
	(segment
		(start 373.81688 -56.91378)
		(end 374.394222 -56.91378)
		(width 0.089408)
		(layer "In11.Cu")
		(net "PWRGD_PVPP_ABC")
	)
	(segment
		(start 327.696322 -40.2082)
		(end 328.272394 -39.632128)
		(width 0.089408)
		(layer "In11.Cu")
		(net "PWRGD_PVPP_ABC")
	)
	(segment
		(start 355.219254 -42.80662)
		(end 359.264204 -42.80662)
		(width 0.089408)
		(layer "In11.Cu")
		(net "PWRGD_PVPP_ABC")
	)
	(segment
		(start 367.768378 -49.944782)
		(end 370.27231 -52.448714)
		(width 0.089408)
		(layer "In11.Cu")
		(net "PWRGD_PVPP_ABC")
	)
	(segment
		(start 324.5104 -26.9748)
		(end 325.34479 -27.80919)
		(width 0.089408)
		(layer "In11.Cu")
		(net "PWRGD_PVPP_ABC")
	)
	(segment
		(start 325.627746 -34.982912)
		(end 326.01154 -35.366706)
		(width 0.089408)
		(layer "In11.Cu")
		(net "PWRGD_PVPP_ABC")
	)
	(segment
		(start 355.160834 -42.7482)
		(end 355.219254 -42.80662)
		(width 0.089408)
		(layer "In11.Cu")
		(net "PWRGD_PVPP_ABC")
	)
	(segment
		(start 326.01154 -39.343076)
		(end 326.876664 -40.2082)
		(width 0.089408)
		(layer "In11.Cu")
		(net "PWRGD_PVPP_ABC")
	)
	(segment
		(start 367.533936 -49.710086)
		(end 367.768378 -49.944528)
		(width 0.089408)
		(layer "In11.Cu")
		(net "PWRGD_PVPP_ABC")
	)
	(segment
		(start 414.4264 -71.1454)
		(end 414.3502 -71.2216)
		(width 0.089408)
		(layer "In11.Cu")
		(net "PWRGD_PVPP_ABC")
	)
	(segment
		(start 325.627746 -32.654494)
		(end 325.627746 -34.982912)
		(width 0.089408)
		(layer "In11.Cu")
		(net "PWRGD_PVPP_ABC")
	)
	(segment
		(start 377.88469 -60.404248)
		(end 377.88469 -62.04331)
		(width 0.089408)
		(layer "In11.Cu")
		(net "PWRGD_PVPP_ABC")
	)
	(segment
		(start 166.624 -151.135842)
		(end 166.8018 -151.313642)
		(width 0.10795)
		(layer "F.Cu")
		(net "PWRGD_PVDDQ_KLM_R")
	)
	(segment
		(start 0.18034 -131.322064)
		(end 0.657352 -130.845052)
		(width 0.10795)
		(layer "F.Cu")
		(net "PWRGD_PVDDQ_KLM_R")
	)
	(segment
		(start 166.8018 -151.313642)
		(end 166.8018 -154.9146)
		(width 0.10795)
		(layer "F.Cu")
		(net "PWRGD_PVDDQ_KLM_R")
	)
	(segment
		(start -1.49098 -131.209542)
		(end -1.49098 -131.58724)
		(width 0.10795)
		(layer "F.Cu")
		(net "PWRGD_PVDDQ_KLM_R")
	)
	(segment
		(start -0.267716 -131.65836)
		(end -0.255016 -131.67106)
		(width 0.10795)
		(layer "F.Cu")
		(net "PWRGD_PVDDQ_KLM_R")
	)
	(segment
		(start 0.657352 -130.845052)
		(end 0.657352 -130.4163)
		(width 0.10795)
		(layer "F.Cu")
		(net "PWRGD_PVDDQ_KLM_R")
	)
	(segment
		(start -1.49098 -131.58724)
		(end -1.41986 -131.65836)
		(width 0.10795)
		(layer "F.Cu")
		(net "PWRGD_PVDDQ_KLM_R")
	)
	(segment
		(start -0.60706 -131.65836)
		(end -0.267716 -131.65836)
		(width 0.10795)
		(layer "F.Cu")
		(net "PWRGD_PVDDQ_KLM_R")
	)
	(segment
		(start -0.255016 -131.67106)
		(end 0.18034 -131.67106)
		(width 0.10795)
		(layer "F.Cu")
		(net "PWRGD_PVDDQ_KLM_R")
	)
	(segment
		(start 166.624 -150.241)
		(end 166.624 -151.135842)
		(width 0.10795)
		(layer "F.Cu")
		(net "PWRGD_PVDDQ_KLM_R")
	)
	(segment
		(start 0.18034 -131.67106)
		(end 0.18034 -131.322064)
		(width 0.10795)
		(layer "F.Cu")
		(net "PWRGD_PVDDQ_KLM_R")
	)
	(segment
		(start -1.41986 -131.65836)
		(end -0.60706 -131.65836)
		(width 0.10795)
		(layer "F.Cu")
		(net "PWRGD_PVDDQ_KLM_R")
	)
	(segment
		(start 166.8018 -154.9146)
		(end 166.3954 -155.321)
		(width 0.10795)
		(layer "F.Cu")
		(net "PWRGD_PVDDQ_KLM_R")
	)
	(segment
		(start -1.704848 -130.995674)
		(end -1.49098 -131.209542)
		(width 0.10795)
		(layer "F.Cu")
		(net "PWRGD_PVDDQ_KLM_R")
	)
	(via
		(at 166.3954 -155.321)
		(size 0.508)
		(drill 0.254)
		(layers "F.Cu" "B.Cu")
		(net "PWRGD_PVDDQ_KLM_R")
	)
	(via
		(at -2.709926 -131.101592)
		(size 0.6604)
		(drill 0.3302)
		(layers "F.Cu" "B.Cu")
		(net "PWRGD_PVDDQ_KLM_R")
	)
	(via
		(at -1.704848 -130.995674)
		(size 0.508)
		(drill 0.254)
		(layers "F.Cu" "B.Cu")
		(net "PWRGD_PVDDQ_KLM_R")
	)
	(via
		(at 23.355808 -157.7086)
		(size 0.508)
		(drill 0.254)
		(layers "F.Cu" "B.Cu")
		(net "PWRGD_PVDDQ_KLM_R")
	)
	(segment
		(start -2.604008 -130.995674)
		(end -1.704848 -130.995674)
		(width 0.10795)
		(layer "B.Cu")
		(net "PWRGD_PVDDQ_KLM_R")
	)
	(segment
		(start -2.709926 -131.101592)
		(end -2.604008 -130.995674)
		(width 0.10795)
		(layer "B.Cu")
		(net "PWRGD_PVDDQ_KLM_R")
	)
	(segment
		(start 3.837686 -124.20854)
		(end 2.28854 -124.20854)
		(width 0.089408)
		(layer "In2.Cu")
		(net "PWRGD_PVDDQ_KLM_R")
	)
	(segment
		(start 4.63804 -125.008894)
		(end 3.837686 -124.20854)
		(width 0.089408)
		(layer "In2.Cu")
		(net "PWRGD_PVDDQ_KLM_R")
	)
	(segment
		(start 21.349716 -156.698696)
		(end 22.264878 -155.783534)
		(width 0.089408)
		(layer "In2.Cu")
		(net "PWRGD_PVDDQ_KLM_R")
	)
	(segment
		(start 13.428472 -124.823728)
		(end 13.243306 -125.008894)
		(width 0.089408)
		(layer "In2.Cu")
		(net "PWRGD_PVDDQ_KLM_R")
	)
	(segment
		(start 23.355808 -157.7086)
		(end 22.936708 -158.1277)
		(width 0.089408)
		(layer "In2.Cu")
		(net "PWRGD_PVDDQ_KLM_R")
	)
	(segment
		(start -0.06477 -125.797564)
		(end -0.06477 -129.355596)
		(width 0.089408)
		(layer "In2.Cu")
		(net "PWRGD_PVDDQ_KLM_R")
	)
	(segment
		(start 21.349716 -157.82163)
		(end 21.349716 -156.698696)
		(width 0.089408)
		(layer "In2.Cu")
		(net "PWRGD_PVDDQ_KLM_R")
	)
	(segment
		(start 22.264878 -155.783534)
		(end 22.264878 -133.853428)
		(width 0.089408)
		(layer "In2.Cu")
		(net "PWRGD_PVDDQ_KLM_R")
	)
	(segment
		(start 17.495012 -129.083562)
		(end 17.495012 -126.022862)
		(width 0.089408)
		(layer "In2.Cu")
		(net "PWRGD_PVDDQ_KLM_R")
	)
	(segment
		(start 22.936708 -158.1277)
		(end 21.655786 -158.1277)
		(width 0.089408)
		(layer "In2.Cu")
		(net "PWRGD_PVDDQ_KLM_R")
	)
	(segment
		(start 22.264878 -133.853428)
		(end 17.495012 -129.083562)
		(width 0.089408)
		(layer "In2.Cu")
		(net "PWRGD_PVDDQ_KLM_R")
	)
	(segment
		(start 17.495012 -126.022862)
		(end 16.295878 -124.823728)
		(width 0.089408)
		(layer "In2.Cu")
		(net "PWRGD_PVDDQ_KLM_R")
	)
	(segment
		(start 1.488186 -125.008894)
		(end 0.7239 -125.008894)
		(width 0.089408)
		(layer "In2.Cu")
		(net "PWRGD_PVDDQ_KLM_R")
	)
	(segment
		(start -0.06477 -129.355596)
		(end -1.704848 -130.995674)
		(width 0.089408)
		(layer "In2.Cu")
		(net "PWRGD_PVDDQ_KLM_R")
	)
	(segment
		(start 16.295878 -124.823728)
		(end 13.428472 -124.823728)
		(width 0.089408)
		(layer "In2.Cu")
		(net "PWRGD_PVDDQ_KLM_R")
	)
	(segment
		(start 13.243306 -125.008894)
		(end 4.63804 -125.008894)
		(width 0.089408)
		(layer "In2.Cu")
		(net "PWRGD_PVDDQ_KLM_R")
	)
	(segment
		(start 2.28854 -124.20854)
		(end 1.488186 -125.008894)
		(width 0.089408)
		(layer "In2.Cu")
		(net "PWRGD_PVDDQ_KLM_R")
	)
	(segment
		(start 21.655786 -158.1277)
		(end 21.349716 -157.82163)
		(width 0.089408)
		(layer "In2.Cu")
		(net "PWRGD_PVDDQ_KLM_R")
	)
	(segment
		(start 0.7239 -125.008894)
		(end -0.06477 -125.797564)
		(width 0.089408)
		(layer "In2.Cu")
		(net "PWRGD_PVDDQ_KLM_R")
	)
	(segment
		(start 24.9174 -157.7086)
		(end 26.134314 -156.491686)
		(width 0.089408)
		(layer "In9.Cu")
		(net "PWRGD_PVDDQ_KLM_R")
	)
	(segment
		(start 99.855782 -156.910024)
		(end 163.156392 -156.910024)
		(width 0.089408)
		(layer "In9.Cu")
		(net "PWRGD_PVDDQ_KLM_R")
	)
	(segment
		(start 163.156392 -156.910024)
		(end 164.745416 -155.321)
		(width 0.089408)
		(layer "In9.Cu")
		(net "PWRGD_PVDDQ_KLM_R")
	)
	(segment
		(start 99.601782 -157.164024)
		(end 99.855782 -156.910024)
		(width 0.089408)
		(layer "In9.Cu")
		(net "PWRGD_PVDDQ_KLM_R")
	)
	(segment
		(start 164.745416 -155.321)
		(end 166.3954 -155.321)
		(width 0.089408)
		(layer "In9.Cu")
		(net "PWRGD_PVDDQ_KLM_R")
	)
	(segment
		(start 26.134314 -156.491686)
		(end 29.138626 -156.491686)
		(width 0.089408)
		(layer "In9.Cu")
		(net "PWRGD_PVDDQ_KLM_R")
	)
	(segment
		(start 29.810964 -157.164024)
		(end 99.601782 -157.164024)
		(width 0.089408)
		(layer "In9.Cu")
		(net "PWRGD_PVDDQ_KLM_R")
	)
	(segment
		(start 23.355808 -157.7086)
		(end 24.9174 -157.7086)
		(width 0.089408)
		(layer "In9.Cu")
		(net "PWRGD_PVDDQ_KLM_R")
	)
	(segment
		(start 29.138626 -156.491686)
		(end 29.810964 -157.164024)
		(width 0.089408)
		(layer "In9.Cu")
		(net "PWRGD_PVDDQ_KLM_R")
	)
	(segment
		(start 13.640816 -2.284476)
		(end 13.640816 -2.086864)
		(width 0.10795)
		(layer "F.Cu")
		(net "PWRGD_PVDDQ_GHJ_R")
	)
	(segment
		(start 165.608 -6.477)
		(end 165.608 -6.64083)
		(width 0.10795)
		(layer "F.Cu")
		(net "PWRGD_PVDDQ_GHJ_R")
	)
	(segment
		(start 16.451326 -2.197354)
		(end 16.451326 -2.716022)
		(width 0.10795)
		(layer "F.Cu")
		(net "PWRGD_PVDDQ_GHJ_R")
	)
	(segment
		(start 166.025068 -7.817104)
		(end 166.120064 -7.9121)
		(width 0.10795)
		(layer "F.Cu")
		(net "PWRGD_PVDDQ_GHJ_R")
	)
	(segment
		(start 13.640816 -1.197864)
		(end 13.640816 -0.775462)
		(width 0.10795)
		(layer "F.Cu")
		(net "PWRGD_PVDDQ_GHJ_R")
	)
	(segment
		(start 14.819122 -0.681228)
		(end 14.871446 -0.733552)
		(width 0.10795)
		(layer "F.Cu")
		(net "PWRGD_PVDDQ_GHJ_R")
	)
	(segment
		(start 16.343122 -2.08915)
		(end 16.451326 -2.197354)
		(width 0.10795)
		(layer "F.Cu")
		(net "PWRGD_PVDDQ_GHJ_R")
	)
	(segment
		(start 13.640816 -2.086864)
		(end 13.640816 -1.197864)
		(width 0.10795)
		(layer "F.Cu")
		(net "PWRGD_PVDDQ_GHJ_R")
	)
	(segment
		(start 16.068294 -2.08915)
		(end 16.343122 -2.08915)
		(width 0.10795)
		(layer "F.Cu")
		(net "PWRGD_PVDDQ_GHJ_R")
	)
	(segment
		(start 14.871446 -0.733552)
		(end 15.293848 -0.733552)
		(width 0.10795)
		(layer "F.Cu")
		(net "PWRGD_PVDDQ_GHJ_R")
	)
	(segment
		(start 12.4841 -1.152398)
		(end 13.045948 -1.152398)
		(width 0.10795)
		(layer "F.Cu")
		(net "PWRGD_PVDDQ_GHJ_R")
	)
	(segment
		(start 165.608 -6.64083)
		(end 166.025068 -7.057898)
		(width 0.10795)
		(layer "F.Cu")
		(net "PWRGD_PVDDQ_GHJ_R")
	)
	(segment
		(start 166.025068 -7.057898)
		(end 166.025068 -7.817104)
		(width 0.10795)
		(layer "F.Cu")
		(net "PWRGD_PVDDQ_GHJ_R")
	)
	(segment
		(start 15.669006 -2.08915)
		(end 15.129256 -2.6289)
		(width 0.10795)
		(layer "F.Cu")
		(net "PWRGD_PVDDQ_GHJ_R")
	)
	(segment
		(start 16.451326 -2.716022)
		(end 16.296386 -2.870962)
		(width 0.10795)
		(layer "F.Cu")
		(net "PWRGD_PVDDQ_GHJ_R")
	)
	(segment
		(start 13.98524 -2.6289)
		(end 13.640816 -2.284476)
		(width 0.10795)
		(layer "F.Cu")
		(net "PWRGD_PVDDQ_GHJ_R")
	)
	(segment
		(start 13.73505 -0.681228)
		(end 14.819122 -0.681228)
		(width 0.10795)
		(layer "F.Cu")
		(net "PWRGD_PVDDQ_GHJ_R")
	)
	(segment
		(start 16.068294 -2.08915)
		(end 15.669006 -2.08915)
		(width 0.10795)
		(layer "F.Cu")
		(net "PWRGD_PVDDQ_GHJ_R")
	)
	(segment
		(start 13.091414 -1.197864)
		(end 13.640816 -1.197864)
		(width 0.10795)
		(layer "F.Cu")
		(net "PWRGD_PVDDQ_GHJ_R")
	)
	(segment
		(start 15.129256 -2.6289)
		(end 13.98524 -2.6289)
		(width 0.10795)
		(layer "F.Cu")
		(net "PWRGD_PVDDQ_GHJ_R")
	)
	(segment
		(start 13.640816 -0.775462)
		(end 13.73505 -0.681228)
		(width 0.10795)
		(layer "F.Cu")
		(net "PWRGD_PVDDQ_GHJ_R")
	)
	(segment
		(start 13.045948 -1.152398)
		(end 13.091414 -1.197864)
		(width 0.10795)
		(layer "F.Cu")
		(net "PWRGD_PVDDQ_GHJ_R")
	)
	(via
		(at 16.296386 -2.870962)
		(size 0.508)
		(drill 0.254)
		(layers "F.Cu" "B.Cu")
		(net "PWRGD_PVDDQ_GHJ_R")
	)
	(via
		(at 166.120064 -7.9121)
		(size 0.508)
		(drill 0.254)
		(layers "F.Cu" "B.Cu")
		(net "PWRGD_PVDDQ_GHJ_R")
	)
	(via
		(at 16.068294 -2.08915)
		(size 0.508)
		(drill 0.254)
		(layers "F.Cu" "B.Cu")
		(net "PWRGD_PVDDQ_GHJ_R")
	)
	(segment
		(start 93.740986 -4.947158)
		(end 94.80423 -3.883914)
		(width 0.089408)
		(layer "In9.Cu")
		(net "PWRGD_PVDDQ_GHJ_R")
	)
	(segment
		(start 16.296386 -2.870962)
		(end 18.12925 -2.870962)
		(width 0.089408)
		(layer "In9.Cu")
		(net "PWRGD_PVDDQ_GHJ_R")
	)
	(segment
		(start 24.746966 -5.004816)
		(end 24.804624 -4.947158)
		(width 0.089408)
		(layer "In9.Cu")
		(net "PWRGD_PVDDQ_GHJ_R")
	)
	(segment
		(start 160.114488 -8.86333)
		(end 161.093404 -9.842246)
		(width 0.089408)
		(layer "In9.Cu")
		(net "PWRGD_PVDDQ_GHJ_R")
	)
	(segment
		(start 97.038922 -3.883914)
		(end 98.159824 -5.004816)
		(width 0.089408)
		(layer "In9.Cu")
		(net "PWRGD_PVDDQ_GHJ_R")
	)
	(segment
		(start 18.12925 -2.870962)
		(end 20.263104 -5.004816)
		(width 0.089408)
		(layer "In9.Cu")
		(net "PWRGD_PVDDQ_GHJ_R")
	)
	(segment
		(start 160.114488 -6.560058)
		(end 160.114488 -8.86333)
		(width 0.089408)
		(layer "In9.Cu")
		(net "PWRGD_PVDDQ_GHJ_R")
	)
	(segment
		(start 164.189918 -9.842246)
		(end 166.120064 -7.9121)
		(width 0.089408)
		(layer "In9.Cu")
		(net "PWRGD_PVDDQ_GHJ_R")
	)
	(segment
		(start 99.19843 -4.845558)
		(end 158.399988 -4.845558)
		(width 0.089408)
		(layer "In9.Cu")
		(net "PWRGD_PVDDQ_GHJ_R")
	)
	(segment
		(start 24.804624 -4.947158)
		(end 93.740986 -4.947158)
		(width 0.089408)
		(layer "In9.Cu")
		(net "PWRGD_PVDDQ_GHJ_R")
	)
	(segment
		(start 98.159824 -5.004816)
		(end 99.039172 -5.004816)
		(width 0.089408)
		(layer "In9.Cu")
		(net "PWRGD_PVDDQ_GHJ_R")
	)
	(segment
		(start 161.093404 -9.842246)
		(end 164.189918 -9.842246)
		(width 0.089408)
		(layer "In9.Cu")
		(net "PWRGD_PVDDQ_GHJ_R")
	)
	(segment
		(start 94.80423 -3.883914)
		(end 97.038922 -3.883914)
		(width 0.089408)
		(layer "In9.Cu")
		(net "PWRGD_PVDDQ_GHJ_R")
	)
	(segment
		(start 158.399988 -4.845558)
		(end 160.114488 -6.560058)
		(width 0.089408)
		(layer "In9.Cu")
		(net "PWRGD_PVDDQ_GHJ_R")
	)
	(segment
		(start 99.039172 -5.004816)
		(end 99.19843 -4.845558)
		(width 0.089408)
		(layer "In9.Cu")
		(net "PWRGD_PVDDQ_GHJ_R")
	)
	(segment
		(start 20.263104 -5.004816)
		(end 24.746966 -5.004816)
		(width 0.089408)
		(layer "In9.Cu")
		(net "PWRGD_PVDDQ_GHJ_R")
	)
	(segment
		(start 360.698288 -135.120888)
		(end 360.5784 -135.001)
		(width 0.10795)
		(layer "F.Cu")
		(net "PWRGD_PVDDQ_DEF_R")
	)
	(segment
		(start 360.698288 -135.71347)
		(end 360.698288 -135.120888)
		(width 0.10795)
		(layer "F.Cu")
		(net "PWRGD_PVDDQ_DEF_R")
	)
	(segment
		(start 361.639104 -133.97357)
		(end 361.627674 -133.985)
		(width 0.10795)
		(layer "F.Cu")
		(net "PWRGD_PVDDQ_DEF_R")
	)
	(segment
		(start 360.5784 -135.001)
		(end 360.5784 -134.5946)
		(width 0.10795)
		(layer "F.Cu")
		(net "PWRGD_PVDDQ_DEF_R")
	)
	(segment
		(start 360.5784 -134.5946)
		(end 361.188 -133.985)
		(width 0.10795)
		(layer "F.Cu")
		(net "PWRGD_PVDDQ_DEF_R")
	)
	(segment
		(start 361.627674 -133.985)
		(end 361.188 -133.985)
		(width 0.10795)
		(layer "F.Cu")
		(net "PWRGD_PVDDQ_DEF_R")
	)
	(segment
		(start 185.4454 -153.416)
		(end 186.190128 -153.416)
		(width 0.10795)
		(layer "F.Cu")
		(net "PWRGD_PVDDQ_DEF_R")
	)
	(segment
		(start 362.09224 -133.97357)
		(end 361.639104 -133.97357)
		(width 0.10795)
		(layer "F.Cu")
		(net "PWRGD_PVDDQ_DEF_R")
	)
	(via
		(at 360.5784 -135.001)
		(size 0.508)
		(drill 0.254)
		(layers "F.Cu" "B.Cu")
		(net "PWRGD_PVDDQ_DEF_R")
	)
	(via
		(at 186.190128 -153.416)
		(size 0.508)
		(drill 0.254)
		(layers "F.Cu" "B.Cu")
		(net "PWRGD_PVDDQ_DEF_R")
	)
	(segment
		(start 360.5784 -135.001)
		(end 359.8164 -134.239)
		(width 0.10795)
		(layer "B.Cu")
		(net "PWRGD_PVDDQ_DEF_R")
	)
	(segment
		(start 359.8164 -134.239)
		(end 359.8164 -134.112)
		(width 0.10795)
		(layer "B.Cu")
		(net "PWRGD_PVDDQ_DEF_R")
	)
	(segment
		(start 330.7588 -153.806906)
		(end 329.204828 -152.252934)
		(width 0.089408)
		(layer "In2.Cu")
		(net "PWRGD_PVDDQ_DEF_R")
	)
	(segment
		(start 329.204828 -148.79447)
		(end 329.874626 -148.124672)
		(width 0.089408)
		(layer "In2.Cu")
		(net "PWRGD_PVDDQ_DEF_R")
	)
	(segment
		(start 352.6155 -139.91336)
		(end 352.89998 -140.19784)
		(width 0.089408)
		(layer "In2.Cu")
		(net "PWRGD_PVDDQ_DEF_R")
	)
	(segment
		(start 329.874626 -148.124672)
		(end 329.874626 -142.114016)
		(width 0.089408)
		(layer "In2.Cu")
		(net "PWRGD_PVDDQ_DEF_R")
	)
	(segment
		(start 191.091058 -158.186374)
		(end 191.095376 -158.190692)
		(width 0.089408)
		(layer "In2.Cu")
		(net "PWRGD_PVDDQ_DEF_R")
	)
	(segment
		(start 278.784812 -157.310836)
		(end 323.353684 -157.310836)
		(width 0.089408)
		(layer "In2.Cu")
		(net "PWRGD_PVDDQ_DEF_R")
	)
	(segment
		(start 352.89998 -140.19784)
		(end 353.88042 -140.19784)
		(width 0.089408)
		(layer "In2.Cu")
		(net "PWRGD_PVDDQ_DEF_R")
	)
	(segment
		(start 186.207654 -153.416)
		(end 186.68238 -153.890726)
		(width 0.089408)
		(layer "In2.Cu")
		(net "PWRGD_PVDDQ_DEF_R")
	)
	(segment
		(start 191.095376 -158.190692)
		(end 265.167872 -158.190692)
		(width 0.089408)
		(layer "In2.Cu")
		(net "PWRGD_PVDDQ_DEF_R")
	)
	(segment
		(start 329.204828 -152.252934)
		(end 329.204828 -148.79447)
		(width 0.089408)
		(layer "In2.Cu")
		(net "PWRGD_PVDDQ_DEF_R")
	)
	(segment
		(start 329.766168 -139.651232)
		(end 329.922124 -139.495276)
		(width 0.089408)
		(layer "In2.Cu")
		(net "PWRGD_PVDDQ_DEF_R")
	)
	(segment
		(start 265.167872 -158.190692)
		(end 265.17219 -158.186374)
		(width 0.089408)
		(layer "In2.Cu")
		(net "PWRGD_PVDDQ_DEF_R")
	)
	(segment
		(start 357.58628 -133.33476)
		(end 358.91216 -133.33476)
		(width 0.089408)
		(layer "In2.Cu")
		(net "PWRGD_PVDDQ_DEF_R")
	)
	(segment
		(start 329.922124 -139.495276)
		(end 337.449414 -139.495276)
		(width 0.089408)
		(layer "In2.Cu")
		(net "PWRGD_PVDDQ_DEF_R")
	)
	(segment
		(start 186.190128 -153.416)
		(end 186.207654 -153.416)
		(width 0.089408)
		(layer "In2.Cu")
		(net "PWRGD_PVDDQ_DEF_R")
	)
	(segment
		(start 338.44992 -138.49477)
		(end 347.64853 -138.49477)
		(width 0.089408)
		(layer "In2.Cu")
		(net "PWRGD_PVDDQ_DEF_R")
	)
	(segment
		(start 349.06712 -139.91336)
		(end 352.6155 -139.91336)
		(width 0.089408)
		(layer "In2.Cu")
		(net "PWRGD_PVDDQ_DEF_R")
	)
	(segment
		(start 324.560946 -158.518098)
		(end 332.050136 -158.518098)
		(width 0.089408)
		(layer "In2.Cu")
		(net "PWRGD_PVDDQ_DEF_R")
	)
	(segment
		(start 330.7588 -154.702764)
		(end 330.7588 -153.806906)
		(width 0.089408)
		(layer "In2.Cu")
		(net "PWRGD_PVDDQ_DEF_R")
	)
	(segment
		(start 355.996748 -138.081512)
		(end 355.996748 -134.924292)
		(width 0.089408)
		(layer "In2.Cu")
		(net "PWRGD_PVDDQ_DEF_R")
	)
	(segment
		(start 329.874626 -142.114016)
		(end 329.766168 -142.005558)
		(width 0.089408)
		(layer "In2.Cu")
		(net "PWRGD_PVDDQ_DEF_R")
	)
	(segment
		(start 186.68238 -153.890726)
		(end 186.68238 -156.309568)
		(width 0.089408)
		(layer "In2.Cu")
		(net "PWRGD_PVDDQ_DEF_R")
	)
	(segment
		(start 265.61034 -157.886654)
		(end 278.208994 -157.886654)
		(width 0.089408)
		(layer "In2.Cu")
		(net "PWRGD_PVDDQ_DEF_R")
	)
	(segment
		(start 337.449414 -139.495276)
		(end 338.44992 -138.49477)
		(width 0.089408)
		(layer "In2.Cu")
		(net "PWRGD_PVDDQ_DEF_R")
	)
	(segment
		(start 358.91216 -133.33476)
		(end 360.5784 -135.001)
		(width 0.089408)
		(layer "In2.Cu")
		(net "PWRGD_PVDDQ_DEF_R")
	)
	(segment
		(start 332.665578 -156.609542)
		(end 330.7588 -154.702764)
		(width 0.089408)
		(layer "In2.Cu")
		(net "PWRGD_PVDDQ_DEF_R")
	)
	(segment
		(start 265.17219 -158.186374)
		(end 265.31062 -158.186374)
		(width 0.089408)
		(layer "In2.Cu")
		(net "PWRGD_PVDDQ_DEF_R")
	)
	(segment
		(start 355.996748 -134.924292)
		(end 357.58628 -133.33476)
		(width 0.089408)
		(layer "In2.Cu")
		(net "PWRGD_PVDDQ_DEF_R")
	)
	(segment
		(start 265.31062 -158.186374)
		(end 265.61034 -157.886654)
		(width 0.089408)
		(layer "In2.Cu")
		(net "PWRGD_PVDDQ_DEF_R")
	)
	(segment
		(start 332.050136 -158.518098)
		(end 332.665578 -157.902656)
		(width 0.089408)
		(layer "In2.Cu")
		(net "PWRGD_PVDDQ_DEF_R")
	)
	(segment
		(start 188.559186 -158.186374)
		(end 191.091058 -158.186374)
		(width 0.089408)
		(layer "In2.Cu")
		(net "PWRGD_PVDDQ_DEF_R")
	)
	(segment
		(start 329.766168 -142.005558)
		(end 329.766168 -139.651232)
		(width 0.089408)
		(layer "In2.Cu")
		(net "PWRGD_PVDDQ_DEF_R")
	)
	(segment
		(start 353.88042 -140.19784)
		(end 355.996748 -138.081512)
		(width 0.089408)
		(layer "In2.Cu")
		(net "PWRGD_PVDDQ_DEF_R")
	)
	(segment
		(start 186.68238 -156.309568)
		(end 188.559186 -158.186374)
		(width 0.089408)
		(layer "In2.Cu")
		(net "PWRGD_PVDDQ_DEF_R")
	)
	(segment
		(start 278.208994 -157.886654)
		(end 278.784812 -157.310836)
		(width 0.089408)
		(layer "In2.Cu")
		(net "PWRGD_PVDDQ_DEF_R")
	)
	(segment
		(start 347.64853 -138.49477)
		(end 349.06712 -139.91336)
		(width 0.089408)
		(layer "In2.Cu")
		(net "PWRGD_PVDDQ_DEF_R")
	)
	(segment
		(start 332.665578 -157.902656)
		(end 332.665578 -156.609542)
		(width 0.089408)
		(layer "In2.Cu")
		(net "PWRGD_PVDDQ_DEF_R")
	)
	(segment
		(start 323.353684 -157.310836)
		(end 324.560946 -158.518098)
		(width 0.089408)
		(layer "In2.Cu")
		(net "PWRGD_PVDDQ_DEF_R")
	)
	(segment
		(start -1.5621 -129.8829)
		(end -1.70434 -129.8829)
		(width 0.1016)
		(layer "F.Cu")
		(net "PU_VR_PVDDQ_KLM_FAULT1")
	)
	(segment
		(start -1.70434 -129.8829)
		(end -1.86944 -130.048)
		(width 0.1016)
		(layer "F.Cu")
		(net "PU_VR_PVDDQ_KLM_FAULT1")
	)
	(segment
		(start -1.2192 -129.54)
		(end -1.5621 -129.8829)
		(width 0.1016)
		(layer "F.Cu")
		(net "PU_VR_PVDDQ_KLM_FAULT1")
	)
	(segment
		(start -0.3937 -128.965198)
		(end -0.745998 -128.965198)
		(width 0.1016)
		(layer "F.Cu")
		(net "PU_VR_PVDDQ_KLM_FAULT1")
	)
	(segment
		(start -1.94564 -130.1242)
		(end -1.86944 -130.048)
		(width 0.10795)
		(layer "F.Cu")
		(net "PU_VR_PVDDQ_KLM_FAULT1")
	)
	(segment
		(start -2.667 -130.1242)
		(end -1.94564 -130.1242)
		(width 0.10795)
		(layer "F.Cu")
		(net "PU_VR_PVDDQ_KLM_FAULT1")
	)
	(segment
		(start -0.745998 -128.965198)
		(end -1.2192 -129.4384)
		(width 0.1016)
		(layer "F.Cu")
		(net "PU_VR_PVDDQ_KLM_FAULT1")
	)
	(segment
		(start -1.2192 -129.4384)
		(end -1.2192 -129.54)
		(width 0.1016)
		(layer "F.Cu")
		(net "PU_VR_PVDDQ_KLM_FAULT1")
	)
	(via
		(at -1.86944 -130.048)
		(size 0.508)
		(drill 0.254)
		(layers "F.Cu" "B.Cu")
		(net "PU_VR_PVDDQ_KLM_FAULT1")
	)
	(segment
		(start 11.032998 -2.62763)
		(end 11.032998 -2.20345)
		(width 0.10795)
		(layer "F.Cu")
		(net "PU_VR_PVDDQ_GHJ_FAULT1")
	)
	(segment
		(start 11.214608 -2.80924)
		(end 11.032998 -2.62763)
		(width 0.10795)
		(layer "F.Cu")
		(net "PU_VR_PVDDQ_GHJ_FAULT1")
	)
	(segment
		(start 12.66952 -3.53441)
		(end 12.66952 -3.39344)
		(width 0.10795)
		(layer "F.Cu")
		(net "PU_VR_PVDDQ_GHJ_FAULT1")
	)
	(segment
		(start 12.08532 -2.80924)
		(end 11.214608 -2.80924)
		(width 0.10795)
		(layer "F.Cu")
		(net "PU_VR_PVDDQ_GHJ_FAULT1")
	)
	(segment
		(start 12.66952 -3.39344)
		(end 12.08532 -2.80924)
		(width 0.10795)
		(layer "F.Cu")
		(net "PU_VR_PVDDQ_GHJ_FAULT1")
	)
	(segment
		(start 362.912914 -136.020048)
		(end 362.912914 -136.327896)
		(width 0.10795)
		(layer "F.Cu")
		(net "PU_VR_PVDDQ_DEF_FAULT1")
	)
	(segment
		(start 363.8804 -135.9916)
		(end 362.941362 -135.9916)
		(width 0.10795)
		(layer "F.Cu")
		(net "PU_VR_PVDDQ_DEF_FAULT1")
	)
	(segment
		(start 362.076238 -137.164572)
		(end 361.74934 -137.164572)
		(width 0.10795)
		(layer "F.Cu")
		(net "PU_VR_PVDDQ_DEF_FAULT1")
	)
	(segment
		(start 362.912914 -136.327896)
		(end 362.076238 -137.164572)
		(width 0.10795)
		(layer "F.Cu")
		(net "PU_VR_PVDDQ_DEF_FAULT1")
	)
	(segment
		(start 362.941362 -135.9916)
		(end 362.912914 -136.020048)
		(width 0.10795)
		(layer "F.Cu")
		(net "PU_VR_PVDDQ_DEF_FAULT1")
	)
	(via
		(at 362.912914 -136.020048)
		(size 0.508)
		(drill 0.254)
		(layers "F.Cu" "B.Cu")
		(net "PU_VR_PVDDQ_DEF_FAULT1")
	)
	(segment
		(start -1.3208 -129.1844)
		(end -1.7018 -129.1844)
		(width 0.10795)
		(layer "F.Cu")
		(net "NC_PVDDQ_KLM_GP1")
	)
	(segment
		(start -0.3937 -128.565148)
		(end -0.701548 -128.565148)
		(width 0.10795)
		(layer "F.Cu")
		(net "NC_PVDDQ_KLM_GP1")
	)
	(segment
		(start -2.667 -129.3622)
		(end -1.88087 -129.3622)
		(width 0.10795)
		(layer "F.Cu")
		(net "NC_PVDDQ_KLM_GP1")
	)
	(segment
		(start -1.7018 -129.1844)
		(end -1.7018 -129.183892)
		(width 0.10795)
		(layer "F.Cu")
		(net "NC_PVDDQ_KLM_GP1")
	)
	(segment
		(start -0.701548 -128.565148)
		(end -1.3208 -129.1844)
		(width 0.10795)
		(layer "F.Cu")
		(net "NC_PVDDQ_KLM_GP1")
	)
	(segment
		(start -1.88087 -129.3622)
		(end -1.702562 -129.183892)
		(width 0.10795)
		(layer "F.Cu")
		(net "NC_PVDDQ_KLM_GP1")
	)
	(segment
		(start -1.7018 -129.183892)
		(end -1.702562 -129.183892)
		(width 0.10795)
		(layer "F.Cu")
		(net "NC_PVDDQ_KLM_GP1")
	)
	(via
		(at -1.702562 -129.183892)
		(size 0.762)
		(drill 0.381)
		(layers "F.Cu" "B.Cu")
		(net "NC_PVDDQ_KLM_GP1")
	)
	(segment
		(start -2.96799 -125.9078)
		(end -3.9116 -125.9078)
		(width 0.10795)
		(layer "F.Cu")
		(net "NC_PVDDQ_KLM_GP0")
	)
	(segment
		(start -0.796798 -126.965202)
		(end -1.8542 -125.9078)
		(width 0.10795)
		(layer "F.Cu")
		(net "NC_PVDDQ_KLM_GP0")
	)
	(segment
		(start -1.8542 -125.9078)
		(end -2.96799 -125.9078)
		(width 0.10795)
		(layer "F.Cu")
		(net "NC_PVDDQ_KLM_GP0")
	)
	(segment
		(start -4.191 -125.6284)
		(end -4.191 -125.222)
		(width 0.10795)
		(layer "F.Cu")
		(net "NC_PVDDQ_KLM_GP0")
	)
	(segment
		(start -0.3937 -126.965202)
		(end -0.796798 -126.965202)
		(width 0.10795)
		(layer "F.Cu")
		(net "NC_PVDDQ_KLM_GP0")
	)
	(segment
		(start -3.9116 -125.9078)
		(end -4.191 -125.6284)
		(width 0.10795)
		(layer "F.Cu")
		(net "NC_PVDDQ_KLM_GP0")
	)
	(via
		(at -2.96799 -125.9078)
		(size 0.508)
		(drill 0.254)
		(layers "F.Cu" "B.Cu")
		(net "NC_PVDDQ_KLM_GP0")
	)
	(segment
		(start 10.632948 -2.20345)
		(end 10.632948 -2.581148)
		(width 0.10795)
		(layer "F.Cu")
		(net "TP_PVDDQ_GHJ_MP1")
	)
	(segment
		(start 10.632948 -2.581148)
		(end 11.12266 -3.07086)
		(width 0.10795)
		(layer "F.Cu")
		(net "TP_PVDDQ_GHJ_MP1")
	)
	(segment
		(start 11.12266 -3.07086)
		(end 11.72972 -3.07086)
		(width 0.10795)
		(layer "F.Cu")
		(net "TP_PVDDQ_GHJ_MP1")
	)
	(segment
		(start 11.72972 -3.07086)
		(end 11.89863 -3.23977)
		(width 0.10795)
		(layer "F.Cu")
		(net "TP_PVDDQ_GHJ_MP1")
	)
	(segment
		(start 11.89863 -3.23977)
		(end 11.89863 -3.541268)
		(width 0.10795)
		(layer "F.Cu")
		(net "TP_PVDDQ_GHJ_MP1")
	)
	(segment
		(start 362.231178 -137.564622)
		(end 363.0422 -136.7536)
		(width 0.10795)
		(layer "F.Cu")
		(net "TP_PVDDQ_DEF_MP1")
	)
	(segment
		(start 363.0422 -136.7536)
		(end 363.8804 -136.7536)
		(width 0.10795)
		(layer "F.Cu")
		(net "TP_PVDDQ_DEF_MP1")
	)
	(segment
		(start 361.74934 -137.564622)
		(end 362.231178 -137.564622)
		(width 0.10795)
		(layer "F.Cu")
		(net "TP_PVDDQ_DEF_MP1")
	)
	(segment
		(start 177.927 -130.8735)
		(end 177.927 -130.2639)
		(width 0.254)
		(layer "F.Cu")
		(net "AGND_PVPP_KLM")
	)
	(via
		(at 178.11877 -132.470652)
		(size 0.508)
		(drill 0.254)
		(layers "F.Cu" "B.Cu")
		(net "AGND_PVPP_KLM")
	)
	(via
		(at 172.72 -129.9972)
		(size 0.508)
		(drill 0.254)
		(layers "F.Cu" "B.Cu")
		(net "AGND_PVPP_KLM")
	)
	(via
		(at 174.33925 -134.055612)
		(size 0.508)
		(drill 0.254)
		(layers "F.Cu" "B.Cu")
		(net "AGND_PVPP_KLM")
	)
	(via
		(at 174.2948 -129.9718)
		(size 0.508)
		(drill 0.254)
		(layers "F.Cu" "B.Cu")
		(net "AGND_PVPP_KLM")
	)
	(via
		(at 177.927 -130.2639)
		(size 0.508)
		(drill 0.254)
		(layers "F.Cu" "B.Cu")
		(net "AGND_PVPP_KLM")
	)
	(via
		(at 178.1048 -133.1595)
		(size 0.508)
		(drill 0.254)
		(layers "F.Cu" "B.Cu")
		(net "AGND_PVPP_KLM")
	)
	(segment
		(start 172.9232 -133.985)
		(end 172.6692 -134.239)
		(width 0.508)
		(layer "B.Cu")
		(net "AGND_PVPP_KLM")
	)
	(segment
		(start 174.33925 -134.055612)
		(end 174.268638 -133.985)
		(width 0.508)
		(layer "B.Cu")
		(net "AGND_PVPP_KLM")
	)
	(segment
		(start 174.268638 -133.985)
		(end 172.9232 -133.985)
		(width 0.508)
		(layer "B.Cu")
		(net "AGND_PVPP_KLM")
	)
	(segment
		(start 177.927 -7.366)
		(end 177.927 -6.7564)
		(width 0.254)
		(layer "F.Cu")
		(net "AGND_PVPP_GHJ")
	)
	(via
		(at 178.029616 -9.763506)
		(size 0.508)
		(drill 0.254)
		(layers "F.Cu" "B.Cu")
		(net "AGND_PVPP_GHJ")
	)
	(via
		(at 173.965616 -10.145522)
		(size 0.508)
		(drill 0.254)
		(layers "F.Cu" "B.Cu")
		(net "AGND_PVPP_GHJ")
	)
	(via
		(at 177.927 -6.7564)
		(size 0.508)
		(drill 0.254)
		(layers "F.Cu" "B.Cu")
		(net "AGND_PVPP_GHJ")
	)
	(via
		(at 173.768004 -7.146798)
		(size 0.508)
		(drill 0.254)
		(layers "F.Cu" "B.Cu")
		(net "AGND_PVPP_GHJ")
	)
	(via
		(at 173.082204 -7.146798)
		(size 0.508)
		(drill 0.254)
		(layers "F.Cu" "B.Cu")
		(net "AGND_PVPP_GHJ")
	)
	(via
		(at 178.18735 -9.04494)
		(size 0.508)
		(drill 0.254)
		(layers "F.Cu" "B.Cu")
		(net "AGND_PVPP_GHJ")
	)
	(segment
		(start 173.50867 -10.10793)
		(end 173.928024 -10.10793)
		(width 0.254)
		(layer "B.Cu")
		(net "AGND_PVPP_GHJ")
	)
	(segment
		(start 172.8724 -10.7442)
		(end 173.50867 -10.10793)
		(width 0.254)
		(layer "B.Cu")
		(net "AGND_PVPP_GHJ")
	)
	(segment
		(start 173.928024 -10.10793)
		(end 173.965616 -10.145522)
		(width 0.254)
		(layer "B.Cu")
		(net "AGND_PVPP_GHJ")
	)
	(segment
		(start 344.932 -127.917448)
		(end 344.5256 -128.323848)
		(width 0.254)
		(layer "F.Cu")
		(net "AGND_PVPP_DEF")
	)
	(segment
		(start 344.932 -127.4572)
		(end 344.932 -127.917448)
		(width 0.254)
		(layer "F.Cu")
		(net "AGND_PVPP_DEF")
	)
	(segment
		(start 344.5256 -129.0066)
		(end 344.3732 -129.159)
		(width 0.254)
		(layer "F.Cu")
		(net "AGND_PVPP_DEF")
	)
	(segment
		(start 344.5256 -128.323848)
		(end 344.5256 -129.0066)
		(width 0.254)
		(layer "F.Cu")
		(net "AGND_PVPP_DEF")
	)
	(via
		(at 340.610444 -129.841498)
		(size 0.508)
		(drill 0.254)
		(layers "F.Cu" "B.Cu")
		(net "AGND_PVPP_DEF")
	)
	(via
		(at 338.9122 -126.8222)
		(size 0.508)
		(drill 0.254)
		(layers "F.Cu" "B.Cu")
		(net "AGND_PVPP_DEF")
	)
	(via
		(at 344.3732 -129.159)
		(size 0.508)
		(drill 0.254)
		(layers "F.Cu" "B.Cu")
		(net "AGND_PVPP_DEF")
	)
	(via
		(at 343.475564 -127.886714)
		(size 0.6604)
		(drill 0.3302)
		(layers "F.Cu" "B.Cu")
		(net "AGND_PVPP_DEF")
	)
	(via
		(at 339.6234 -126.8222)
		(size 0.508)
		(drill 0.254)
		(layers "F.Cu" "B.Cu")
		(net "AGND_PVPP_DEF")
	)
	(segment
		(start 339.098636 -23.9903)
		(end 338.933536 -24.1554)
		(width 0.4064)
		(layer "F.Cu")
		(net "AGND_PVPP_ABC")
	)
	(segment
		(start 342.138 -22.225)
		(end 342.138 -22.86)
		(width 0.4064)
		(layer "F.Cu")
		(net "AGND_PVPP_ABC")
	)
	(segment
		(start 345.6178 -21.9837)
		(end 345.6178 -22.5933)
		(width 0.4064)
		(layer "F.Cu")
		(net "AGND_PVPP_ABC")
	)
	(segment
		(start 338.933536 -24.1554)
		(end 338.328 -24.1554)
		(width 0.4064)
		(layer "F.Cu")
		(net "AGND_PVPP_ABC")
	)
	(segment
		(start 340.995 -21.971)
		(end 340.36 -21.971)
		(width 0.4064)
		(layer "F.Cu")
		(net "AGND_PVPP_ABC")
	)
	(segment
		(start 341.249 -22.86)
		(end 341.249 -22.225)
		(width 0.4064)
		(layer "F.Cu")
		(net "AGND_PVPP_ABC")
	)
	(segment
		(start 341.249 -22.225)
		(end 340.995 -21.971)
		(width 0.4064)
		(layer "F.Cu")
		(net "AGND_PVPP_ABC")
	)
	(segment
		(start 339.12048 -23.9903)
		(end 339.098636 -23.9903)
		(width 0.4064)
		(layer "F.Cu")
		(net "AGND_PVPP_ABC")
	)
	(via
		(at 345.855036 -24.871426)
		(size 0.508)
		(drill 0.254)
		(layers "F.Cu" "B.Cu")
		(net "AGND_PVPP_ABC")
	)
	(via
		(at 339.12048 -23.9903)
		(size 0.508)
		(drill 0.254)
		(layers "F.Cu" "B.Cu")
		(net "AGND_PVPP_ABC")
	)
	(via
		(at 345.6178 -21.9837)
		(size 0.508)
		(drill 0.254)
		(layers "F.Cu" "B.Cu")
		(net "AGND_PVPP_ABC")
	)
	(via
		(at 341.249 -22.225)
		(size 0.508)
		(drill 0.254)
		(layers "F.Cu" "B.Cu")
		(net "AGND_PVPP_ABC")
	)
	(via
		(at 339.979 -24.384)
		(size 0.508)
		(drill 0.254)
		(layers "F.Cu" "B.Cu")
		(net "AGND_PVPP_ABC")
	)
	(via
		(at 342.138 -22.225)
		(size 0.508)
		(drill 0.254)
		(layers "F.Cu" "B.Cu")
		(net "AGND_PVPP_ABC")
	)
	(via
		(at 345.855036 -24.261826)
		(size 0.508)
		(drill 0.254)
		(layers "F.Cu" "B.Cu")
		(net "AGND_PVPP_ABC")
	)
	(segment
		(start 339.979 -25.781)
		(end 339.979 -24.384)
		(width 0.508)
		(layer "B.Cu")
		(net "AGND_PVPP_ABC")
	)
	(segment
		(start 165.0492 -64.2493)
		(end 165.0492 -64.1604)
		(width 0.127)
		(layer "F.Cu")
		(net "VSENSE_PVCCIO_CPU1_AVSN")
	)
	(segment
		(start 165.763702 -65.001902)
		(end 165.6842 -64.9224)
		(width 0.127)
		(layer "F.Cu")
		(net "VSENSE_PVCCIO_CPU1_AVSN")
	)
	(segment
		(start 162.8394 -66.1162)
		(end 162.6362 -66.3194)
		(width 0.127)
		(layer "F.Cu")
		(net "VSENSE_PVCCIO_CPU1_AVSN")
	)
	(segment
		(start 166.7383 -65.001902)
		(end 165.763702 -65.001902)
		(width 0.127)
		(layer "F.Cu")
		(net "VSENSE_PVCCIO_CPU1_AVSN")
	)
	(segment
		(start 162.8394 -65.7606)
		(end 163.0426 -65.7606)
		(width 0.127)
		(layer "F.Cu")
		(net "VSENSE_PVCCIO_CPU1_AVSN")
	)
	(segment
		(start 165.6842 -64.9224)
		(end 164.973 -64.9224)
		(width 0.127)
		(layer "F.Cu")
		(net "VSENSE_PVCCIO_CPU1_AVSN")
	)
	(segment
		(start 163.3474 -65.4558)
		(end 163.3474 -64.4398)
		(width 0.127)
		(layer "F.Cu")
		(net "VSENSE_PVCCIO_CPU1_AVSN")
	)
	(segment
		(start 163.0426 -65.7606)
		(end 163.3474 -65.4558)
		(width 0.127)
		(layer "F.Cu")
		(net "VSENSE_PVCCIO_CPU1_AVSN")
	)
	(segment
		(start 162.8394 -65.7606)
		(end 162.8394 -66.1162)
		(width 0.127)
		(layer "F.Cu")
		(net "VSENSE_PVCCIO_CPU1_AVSN")
	)
	(segment
		(start 164.973 -64.9224)
		(end 164.973 -64.3255)
		(width 0.127)
		(layer "F.Cu")
		(net "VSENSE_PVCCIO_CPU1_AVSN")
	)
	(segment
		(start 164.973 -64.3255)
		(end 165.0492 -64.2493)
		(width 0.127)
		(layer "F.Cu")
		(net "VSENSE_PVCCIO_CPU1_AVSN")
	)
	(segment
		(start 162.6362 -66.3194)
		(end 162.6362 -66.675)
		(width 0.127)
		(layer "F.Cu")
		(net "VSENSE_PVCCIO_CPU1_AVSN")
	)
	(via
		(at 163.3474 -64.4398)
		(size 0.508)
		(drill 0.254)
		(layers "F.Cu" "B.Cu")
		(net "VSENSE_PVCCIO_CPU1_AVSN")
	)
	(via
		(at 165.0492 -64.1604)
		(size 0.508)
		(drill 0.254)
		(layers "F.Cu" "B.Cu")
		(net "VSENSE_PVCCIO_CPU1_AVSN")
	)
	(segment
		(start 163.3474 -64.4398)
		(end 163.6268 -64.1604)
		(width 0.127)
		(layer "B.Cu")
		(net "VSENSE_PVCCIO_CPU1_AVSN")
	)
	(segment
		(start 163.6268 -64.1604)
		(end 165.0492 -64.1604)
		(width 0.127)
		(layer "B.Cu")
		(net "VSENSE_PVCCIO_CPU1_AVSN")
	)
	(via
		(at 353.52863 -88.47455)
		(size 0.508)
		(drill 0.254)
		(layers "F.Cu" "B.Cu")
		(net "VSENSE_PVCCIO_CPU0_AVSN")
	)
	(via
		(at 341.561674 -91.330018)
		(size 0.508)
		(drill 0.254)
		(layers "F.Cu" "B.Cu")
		(net "VSENSE_PVCCIO_CPU0_AVSN")
	)
	(segment
		(start 353.52863 -88.47455)
		(end 353.6442 -88.59012)
		(width 0.127)
		(layer "B.Cu")
		(net "VSENSE_PVCCIO_CPU0_AVSN")
	)
	(segment
		(start 342.88984 -90.189558)
		(end 342.642952 -90.189558)
		(width 0.127)
		(layer "B.Cu")
		(net "VSENSE_PVCCIO_CPU0_AVSN")
	)
	(segment
		(start 343.8271 -89.252298)
		(end 342.88984 -90.189558)
		(width 0.127)
		(layer "B.Cu")
		(net "VSENSE_PVCCIO_CPU0_AVSN")
	)
	(segment
		(start 354.536502 -88.41232)
		(end 354.7872 -88.161622)
		(width 0.127)
		(layer "B.Cu")
		(net "VSENSE_PVCCIO_CPU0_AVSN")
	)
	(segment
		(start 344.0811 -89.252298)
		(end 343.8271 -89.252298)
		(width 0.127)
		(layer "B.Cu")
		(net "VSENSE_PVCCIO_CPU0_AVSN")
	)
	(segment
		(start 353.6442 -88.59012)
		(end 353.99472 -88.59012)
		(width 0.127)
		(layer "B.Cu")
		(net "VSENSE_PVCCIO_CPU0_AVSN")
	)
	(segment
		(start 341.561674 -90.850212)
		(end 342.222328 -90.189558)
		(width 0.127)
		(layer "B.Cu")
		(net "VSENSE_PVCCIO_CPU0_AVSN")
	)
	(segment
		(start 354.7872 -87.794592)
		(end 354.460048 -87.46744)
		(width 0.127)
		(layer "B.Cu")
		(net "VSENSE_PVCCIO_CPU0_AVSN")
	)
	(segment
		(start 353.52863 -88.47455)
		(end 353.367848 -88.635332)
		(width 0.127)
		(layer "B.Cu")
		(net "VSENSE_PVCCIO_CPU0_AVSN")
	)
	(segment
		(start 354.7872 -88.161622)
		(end 354.7872 -87.794592)
		(width 0.127)
		(layer "B.Cu")
		(net "VSENSE_PVCCIO_CPU0_AVSN")
	)
	(segment
		(start 353.367848 -88.635332)
		(end 353.367848 -89.98204)
		(width 0.127)
		(layer "B.Cu")
		(net "VSENSE_PVCCIO_CPU0_AVSN")
	)
	(segment
		(start 342.222328 -90.189558)
		(end 342.642952 -90.189558)
		(width 0.127)
		(layer "B.Cu")
		(net "VSENSE_PVCCIO_CPU0_AVSN")
	)
	(segment
		(start 341.561674 -91.330018)
		(end 341.561674 -90.850212)
		(width 0.127)
		(layer "B.Cu")
		(net "VSENSE_PVCCIO_CPU0_AVSN")
	)
	(segment
		(start 353.99472 -88.59012)
		(end 354.17252 -88.41232)
		(width 0.127)
		(layer "B.Cu")
		(net "VSENSE_PVCCIO_CPU0_AVSN")
	)
	(segment
		(start 354.17252 -88.41232)
		(end 354.536502 -88.41232)
		(width 0.127)
		(layer "B.Cu")
		(net "VSENSE_PVCCIO_CPU0_AVSN")
	)
	(segment
		(start 353.52863 -89.014554)
		(end 353.52863 -88.47455)
		(width 0.127)
		(layer "In11.Cu")
		(net "VSENSE_PVCCIO_CPU0_AVSN")
	)
	(segment
		(start 341.447882 -91.80195)
		(end 341.670132 -92.0242)
		(width 0.127)
		(layer "In11.Cu")
		(net "VSENSE_PVCCIO_CPU0_AVSN")
	)
	(segment
		(start 341.561674 -91.330018)
		(end 341.447882 -91.44381)
		(width 0.127)
		(layer "In11.Cu")
		(net "VSENSE_PVCCIO_CPU0_AVSN")
	)
	(segment
		(start 351.962212 -90.580972)
		(end 353.52863 -89.014554)
		(width 0.127)
		(layer "In11.Cu")
		(net "VSENSE_PVCCIO_CPU0_AVSN")
	)
	(segment
		(start 341.670132 -92.0242)
		(end 342.002618 -92.0242)
		(width 0.127)
		(layer "In11.Cu")
		(net "VSENSE_PVCCIO_CPU0_AVSN")
	)
	(segment
		(start 341.447882 -91.44381)
		(end 341.447882 -91.80195)
		(width 0.127)
		(layer "In11.Cu")
		(net "VSENSE_PVCCIO_CPU0_AVSN")
	)
	(segment
		(start 343.445846 -90.580972)
		(end 351.962212 -90.580972)
		(width 0.127)
		(layer "In11.Cu")
		(net "VSENSE_PVCCIO_CPU0_AVSN")
	)
	(segment
		(start 342.002618 -92.0242)
		(end 343.445846 -90.580972)
		(width 0.127)
		(layer "In11.Cu")
		(net "VSENSE_PVCCIO_CPU0_AVSN")
	)
	(segment
		(start 0.635 -143.8148)
		(end 0.635 -143.256)
		(width 0.4064)
		(layer "F.Cu")
		(net "VR_PVDDQ_KLM_PH2_VCIN")
	)
	(segment
		(start 1.017524 -144.933162)
		(end 1.017524 -144.426178)
		(width 0.254)
		(layer "F.Cu")
		(net "VR_PVDDQ_KLM_PH2_VCIN")
	)
	(segment
		(start 1.017524 -144.426178)
		(end 0.9144 -144.323054)
		(width 0.254)
		(layer "F.Cu")
		(net "VR_PVDDQ_KLM_PH2_VCIN")
	)
	(segment
		(start 0.9144 -144.0942)
		(end 0.635 -143.8148)
		(width 0.4064)
		(layer "F.Cu")
		(net "VR_PVDDQ_KLM_PH2_VCIN")
	)
	(segment
		(start 0.9144 -144.323054)
		(end 0.9144 -144.0942)
		(width 0.254)
		(layer "F.Cu")
		(net "VR_PVDDQ_KLM_PH2_VCIN")
	)
	(via
		(at 0.6858 -143.383)
		(size 0.6604)
		(drill 0.3302)
		(layers "F.Cu" "B.Cu")
		(net "VR_PVDDQ_KLM_PH2_VCIN")
	)
	(via
		(at 0.9144 -144.0942)
		(size 0.508)
		(drill 0.254)
		(layers "F.Cu" "B.Cu")
		(net "VR_PVDDQ_KLM_PH2_VCIN")
	)
	(segment
		(start 0.762 -144.8562)
		(end 0.762 -144.2466)
		(width 0.4064)
		(layer "B.Cu")
		(net "VR_PVDDQ_KLM_PH2_VCIN")
	)
	(segment
		(start 0.6858 -143.8656)
		(end 0.6858 -143.383)
		(width 0.4064)
		(layer "B.Cu")
		(net "VR_PVDDQ_KLM_PH2_VCIN")
	)
	(segment
		(start 0.9144 -144.0942)
		(end 0.6858 -143.8656)
		(width 0.4064)
		(layer "B.Cu")
		(net "VR_PVDDQ_KLM_PH2_VCIN")
	)
	(segment
		(start 0.762 -144.2466)
		(end 0.9144 -144.0942)
		(width 0.4064)
		(layer "B.Cu")
		(net "VR_PVDDQ_KLM_PH2_VCIN")
	)
	(segment
		(start -1.967484 -149.29231)
		(end -1.797558 -149.29231)
		(width 0.508)
		(layer "F.Cu")
		(net "VR_PVDDQ_KLM_PH2_PHASE")
	)
	(segment
		(start -0.983742 -148.478494)
		(end -0.497586 -148.478494)
		(width 0.254)
		(layer "F.Cu")
		(net "VR_PVDDQ_KLM_PH2_PHASE")
	)
	(segment
		(start -1.442974 -148.937726)
		(end -0.983742 -148.478494)
		(width 0.254)
		(layer "F.Cu")
		(net "VR_PVDDQ_KLM_PH2_PHASE")
	)
	(segment
		(start -1.797558 -149.29231)
		(end -1.442974 -148.937726)
		(width 0.508)
		(layer "F.Cu")
		(net "VR_PVDDQ_KLM_PH2_PHASE")
	)
	(segment
		(start -3.901694 -147.207986)
		(end -3.95478 -147.1549)
		(width 0.508)
		(layer "F.Cu")
		(net "VR_PVDDQ_KLM_PH2_BOOT")
	)
	(segment
		(start -3.60426 -149.29231)
		(end -3.901694 -148.994876)
		(width 0.508)
		(layer "F.Cu")
		(net "VR_PVDDQ_KLM_PH2_BOOT")
	)
	(segment
		(start -3.901694 -148.994876)
		(end -3.901694 -148.286978)
		(width 0.508)
		(layer "F.Cu")
		(net "VR_PVDDQ_KLM_PH2_BOOT")
	)
	(segment
		(start -2.856484 -149.29231)
		(end -3.60426 -149.29231)
		(width 0.508)
		(layer "F.Cu")
		(net "VR_PVDDQ_KLM_PH2_BOOT")
	)
	(segment
		(start -3.901694 -148.286978)
		(end -3.901694 -147.207986)
		(width 0.508)
		(layer "F.Cu")
		(net "VR_PVDDQ_KLM_PH2_BOOT")
	)
	(via
		(at -3.95478 -147.1549)
		(size 0.762)
		(drill 0.381)
		(layers "F.Cu" "B.Cu")
		(net "VR_PVDDQ_KLM_PH2_BOOT")
	)
	(segment
		(start 6.448552 -129.026158)
		(end 5.52196 -129.026158)
		(width 0.254)
		(layer "F.Cu")
		(net "VR_PVDDQ_KLM_AIINSEN")
	)
	(segment
		(start 7.025132 -128.81229)
		(end 7.33298 -128.81229)
		(width 0.254)
		(layer "F.Cu")
		(net "VR_PVDDQ_KLM_AIINSEN")
	)
	(segment
		(start 6.56209 -128.91262)
		(end 6.924802 -128.91262)
		(width 0.254)
		(layer "F.Cu")
		(net "VR_PVDDQ_KLM_AIINSEN")
	)
	(segment
		(start 8.382 -128.397)
		(end 9.215628 -127.563372)
		(width 0.254)
		(layer "F.Cu")
		(net "VR_PVDDQ_KLM_AIINSEN")
	)
	(segment
		(start 9.215628 -127.563372)
		(end 9.215628 -126.827026)
		(width 0.254)
		(layer "F.Cu")
		(net "VR_PVDDQ_KLM_AIINSEN")
	)
	(segment
		(start 6.448552 -129.026158)
		(end 6.56209 -128.91262)
		(width 0.254)
		(layer "F.Cu")
		(net "VR_PVDDQ_KLM_AIINSEN")
	)
	(segment
		(start 5.52196 -129.026158)
		(end 5.461 -128.965198)
		(width 0.254)
		(layer "F.Cu")
		(net "VR_PVDDQ_KLM_AIINSEN")
	)
	(segment
		(start 6.924802 -128.91262)
		(end 7.025132 -128.81229)
		(width 0.254)
		(layer "F.Cu")
		(net "VR_PVDDQ_KLM_AIINSEN")
	)
	(segment
		(start 5.461 -128.965198)
		(end 4.5085 -128.965198)
		(width 0.2032)
		(layer "F.Cu")
		(net "VR_PVDDQ_KLM_AIINSEN")
	)
	(segment
		(start 8.382 -128.397)
		(end 7.96671 -128.81229)
		(width 0.254)
		(layer "F.Cu")
		(net "VR_PVDDQ_KLM_AIINSEN")
	)
	(segment
		(start 7.96671 -128.81229)
		(end 7.33298 -128.81229)
		(width 0.254)
		(layer "F.Cu")
		(net "VR_PVDDQ_KLM_AIINSEN")
	)
	(via
		(at 8.382 -128.397)
		(size 0.762)
		(drill 0.381)
		(layers "F.Cu" "B.Cu")
		(net "VR_PVDDQ_KLM_AIINSEN")
	)
	(segment
		(start 12.003024 3.587242)
		(end 12.347702 3.93192)
		(width 0.2032)
		(layer "F.Cu")
		(net "VR_PVDDQ_GHJ_AIINSEN")
	)
	(segment
		(start 11.947144 5.004562)
		(end 11.979402 5.03682)
		(width 0.254)
		(layer "F.Cu")
		(net "VR_PVDDQ_GHJ_AIINSEN")
	)
	(segment
		(start 12.347702 3.93192)
		(end 12.347702 4.098798)
		(width 0.2032)
		(layer "F.Cu")
		(net "VR_PVDDQ_GHJ_AIINSEN")
	)
	(segment
		(start 11.979402 5.03682)
		(end 12.631166 5.03682)
		(width 0.254)
		(layer "F.Cu")
		(net "VR_PVDDQ_GHJ_AIINSEN")
	)
	(segment
		(start 11.947144 5.004562)
		(end 11.947144 4.819396)
		(width 0.254)
		(layer "F.Cu")
		(net "VR_PVDDQ_GHJ_AIINSEN")
	)
	(segment
		(start 11.032998 2.69875)
		(end 11.032998 3.095498)
		(width 0.2032)
		(layer "F.Cu")
		(net "VR_PVDDQ_GHJ_AIINSEN")
	)
	(segment
		(start 12.631166 5.03682)
		(end 12.848844 5.254498)
		(width 0.254)
		(layer "F.Cu")
		(net "VR_PVDDQ_GHJ_AIINSEN")
	)
	(segment
		(start 11.032998 3.095498)
		(end 11.524742 3.587242)
		(width 0.2032)
		(layer "F.Cu")
		(net "VR_PVDDQ_GHJ_AIINSEN")
	)
	(segment
		(start 11.524742 3.587242)
		(end 12.003024 3.587242)
		(width 0.2032)
		(layer "F.Cu")
		(net "VR_PVDDQ_GHJ_AIINSEN")
	)
	(segment
		(start 11.947144 4.819396)
		(end 12.347702 4.418838)
		(width 0.254)
		(layer "F.Cu")
		(net "VR_PVDDQ_GHJ_AIINSEN")
	)
	(segment
		(start 12.347702 4.418838)
		(end 12.347702 4.098798)
		(width 0.254)
		(layer "F.Cu")
		(net "VR_PVDDQ_GHJ_AIINSEN")
	)
	(via
		(at 12.848844 5.254498)
		(size 0.508)
		(drill 0.254)
		(layers "F.Cu" "B.Cu")
		(net "VR_PVDDQ_GHJ_AIINSEN")
	)
	(segment
		(start 12.820142 5.2832)
		(end 12.1666 5.2832)
		(width 0.254)
		(layer "B.Cu")
		(net "VR_PVDDQ_GHJ_AIINSEN")
	)
	(segment
		(start 12.848844 5.254498)
		(end 12.820142 5.2832)
		(width 0.254)
		(layer "B.Cu")
		(net "VR_PVDDQ_GHJ_AIINSEN")
	)
	(segment
		(start 12.1666 5.2832)
		(end 11.881358 4.997958)
		(width 0.254)
		(layer "B.Cu")
		(net "VR_PVDDQ_GHJ_AIINSEN")
	)
	(segment
		(start 11.881358 4.997958)
		(end 11.881358 4.17322)
		(width 0.254)
		(layer "B.Cu")
		(net "VR_PVDDQ_GHJ_AIINSEN")
	)
	(segment
		(start 350.538034 -15.75181)
		(end 349.886016 -15.75181)
		(width 0.254)
		(layer "F.Cu")
		(net "VR_PVDDQ_ABC_VINSEN")
	)
	(segment
		(start 349.040958 -15.743428)
		(end 349.877634 -15.743428)
		(width 0.254)
		(layer "F.Cu")
		(net "VR_PVDDQ_ABC_VINSEN")
	)
	(segment
		(start 348.132146 -15.5702)
		(end 348.614746 -15.5702)
		(width 0.254)
		(layer "F.Cu")
		(net "VR_PVDDQ_ABC_VINSEN")
	)
	(segment
		(start 348.614746 -15.5702)
		(end 348.787974 -15.743428)
		(width 0.254)
		(layer "F.Cu")
		(net "VR_PVDDQ_ABC_VINSEN")
	)
	(segment
		(start 347.1291 -15.966948)
		(end 347.735398 -15.966948)
		(width 0.2032)
		(layer "F.Cu")
		(net "VR_PVDDQ_ABC_VINSEN")
	)
	(segment
		(start 349.877634 -15.743428)
		(end 349.886016 -15.75181)
		(width 0.254)
		(layer "F.Cu")
		(net "VR_PVDDQ_ABC_VINSEN")
	)
	(segment
		(start 351.731834 -16.94561)
		(end 350.538034 -15.75181)
		(width 0.254)
		(layer "F.Cu")
		(net "VR_PVDDQ_ABC_VINSEN")
	)
	(segment
		(start 351.731834 -20.319238)
		(end 351.731834 -16.94561)
		(width 0.254)
		(layer "F.Cu")
		(net "VR_PVDDQ_ABC_VINSEN")
	)
	(segment
		(start 348.787974 -15.743428)
		(end 349.040958 -15.743428)
		(width 0.254)
		(layer "F.Cu")
		(net "VR_PVDDQ_ABC_VINSEN")
	)
	(segment
		(start 347.735398 -15.966948)
		(end 348.132146 -15.5702)
		(width 0.254)
		(layer "F.Cu")
		(net "VR_PVDDQ_ABC_VINSEN")
	)
	(segment
		(start 346.9894 -19.304)
		(end 348.0054 -19.304)
		(width 0.508)
		(layer "F.Cu")
		(net "VR_PVDDQ_ABC_VD12")
	)
	(segment
		(start 348.0054 -19.06524)
		(end 348.0054 -19.304)
		(width 0.508)
		(layer "F.Cu")
		(net "VR_PVDDQ_ABC_VD12")
	)
	(segment
		(start 348.072964 -18.997676)
		(end 348.0054 -19.06524)
		(width 0.508)
		(layer "F.Cu")
		(net "VR_PVDDQ_ABC_VD12")
	)
	(segment
		(start 348.072964 -18.496026)
		(end 348.072964 -18.997676)
		(width 0.508)
		(layer "F.Cu")
		(net "VR_PVDDQ_ABC_VD12")
	)
	(segment
		(start 347.1291 -17.564354)
		(end 348.060772 -18.496026)
		(width 0.508)
		(layer "F.Cu")
		(net "VR_PVDDQ_ABC_VD12")
	)
	(segment
		(start 348.060772 -18.496026)
		(end 348.072964 -18.496026)
		(width 0.508)
		(layer "F.Cu")
		(net "VR_PVDDQ_ABC_VD12")
	)
	(segment
		(start 347.1291 -17.167098)
		(end 347.1291 -17.564354)
		(width 0.2032)
		(layer "F.Cu")
		(net "VR_PVDDQ_ABC_VD12")
	)
	(via
		(at 348.072964 -18.496026)
		(size 0.508)
		(drill 0.254)
		(layers "F.Cu" "B.Cu")
		(net "VR_PVDDQ_ABC_VD12")
	)
	(segment
		(start 40.036496 -89.416382)
		(end 40.036496 -86.460076)
		(width 0.508)
		(layer "F.Cu")
		(net "VR_PVCCIN_CPU1_PHASE5")
	)
	(segment
		(start 40.036496 -86.460076)
		(end 39.27602 -85.6996)
		(width 0.508)
		(layer "F.Cu")
		(net "VR_PVCCIN_CPU1_PHASE5")
	)
	(segment
		(start 39.27602 -85.6996)
		(end 38.965886 -85.6996)
		(width 0.508)
		(layer "F.Cu")
		(net "VR_PVCCIN_CPU1_PHASE5")
	)
	(segment
		(start 32.54502 -86.7664)
		(end 32.4612 -86.68258)
		(width 0.254)
		(layer "F.Cu")
		(net "VR_PVCCIN_CPU1_PH5_VCIN")
	)
	(segment
		(start 32.258 -85.986874)
		(end 32.258 -86.106)
		(width 0.508)
		(layer "F.Cu")
		(net "VR_PVCCIN_CPU1_PH5_VCIN")
	)
	(segment
		(start 32.54502 -87.156544)
		(end 32.54502 -86.7664)
		(width 0.254)
		(layer "F.Cu")
		(net "VR_PVCCIN_CPU1_PH5_VCIN")
	)
	(segment
		(start 31.754826 -85.4837)
		(end 32.258 -85.986874)
		(width 0.508)
		(layer "F.Cu")
		(net "VR_PVCCIN_CPU1_PH5_VCIN")
	)
	(segment
		(start 32.4612 -86.3092)
		(end 32.258 -86.106)
		(width 0.254)
		(layer "F.Cu")
		(net "VR_PVCCIN_CPU1_PH5_VCIN")
	)
	(segment
		(start 32.4612 -86.68258)
		(end 32.4612 -86.3092)
		(width 0.254)
		(layer "F.Cu")
		(net "VR_PVCCIN_CPU1_PH5_VCIN")
	)
	(via
		(at 30.89148 -86.233)
		(size 0.6604)
		(drill 0.3302)
		(layers "F.Cu" "B.Cu")
		(net "VR_PVCCIN_CPU1_PH5_VCIN")
	)
	(via
		(at 32.258 -86.106)
		(size 0.508)
		(drill 0.254)
		(layers "F.Cu" "B.Cu")
		(net "VR_PVCCIN_CPU1_PH5_VCIN")
	)
	(segment
		(start 32.2834 -87.0204)
		(end 32.2834 -86.849712)
		(width 0.4064)
		(layer "B.Cu")
		(net "VR_PVCCIN_CPU1_PH5_VCIN")
	)
	(segment
		(start 32.101028 -86.106)
		(end 31.765748 -86.44128)
		(width 0.254)
		(layer "B.Cu")
		(net "VR_PVCCIN_CPU1_PH5_VCIN")
	)
	(segment
		(start 31.765748 -86.44128)
		(end 31.09976 -86.44128)
		(width 0.254)
		(layer "B.Cu")
		(net "VR_PVCCIN_CPU1_PH5_VCIN")
	)
	(segment
		(start 31.09976 -86.44128)
		(end 30.89148 -86.233)
		(width 0.254)
		(layer "B.Cu")
		(net "VR_PVCCIN_CPU1_PH5_VCIN")
	)
	(segment
		(start 32.258 -86.106)
		(end 32.101028 -86.106)
		(width 0.254)
		(layer "B.Cu")
		(net "VR_PVCCIN_CPU1_PH5_VCIN")
	)
	(segment
		(start 32.258 -86.824312)
		(end 32.258 -86.106)
		(width 0.4064)
		(layer "B.Cu")
		(net "VR_PVCCIN_CPU1_PH5_VCIN")
	)
	(segment
		(start 32.2834 -86.849712)
		(end 32.258 -86.824312)
		(width 0.4064)
		(layer "B.Cu")
		(net "VR_PVCCIN_CPU1_PH5_VCIN")
	)
	(segment
		(start 31.02991 -90.701876)
		(end 30.65526 -90.701876)
		(width 0.254)
		(layer "F.Cu")
		(net "VR_PVCCIN_CPU1_PH5_PHASE")
	)
	(segment
		(start 30.65526 -90.701876)
		(end 30.40126 -90.955876)
		(width 0.254)
		(layer "F.Cu")
		(net "VR_PVCCIN_CPU1_PH5_PHASE")
	)
	(segment
		(start 30.40126 -91.19362)
		(end 30.02788 -91.567)
		(width 0.254)
		(layer "F.Cu")
		(net "VR_PVCCIN_CPU1_PH5_PHASE")
	)
	(segment
		(start 30.02788 -91.567)
		(end 29.083 -91.567)
		(width 0.508)
		(layer "F.Cu")
		(net "VR_PVCCIN_CPU1_PH5_PHASE")
	)
	(segment
		(start 30.40126 -90.955876)
		(end 30.40126 -91.19362)
		(width 0.254)
		(layer "F.Cu")
		(net "VR_PVCCIN_CPU1_PH5_PHASE")
	)
	(via
		(at 30.02788 -91.567)
		(size 0.508)
		(drill 0.254)
		(layers "F.Cu" "B.Cu")
		(net "VR_PVCCIN_CPU1_PH5_PHASE")
	)
	(segment
		(start 28.194 -91.567)
		(end 28.194 -90.6145)
		(width 0.508)
		(layer "F.Cu")
		(net "VR_PVCCIN_CPU1_PH5_BOOT")
	)
	(segment
		(start 28.194 -91.567)
		(end 27.2542 -91.567)
		(width 0.508)
		(layer "F.Cu")
		(net "VR_PVCCIN_CPU1_PH5_BOOT")
	)
	(segment
		(start 28.194 -90.6145)
		(end 28.1305 -90.551)
		(width 0.508)
		(layer "F.Cu")
		(net "VR_PVCCIN_CPU1_PH5_BOOT")
	)
	(via
		(at 27.2542 -91.567)
		(size 0.762)
		(drill 0.381)
		(layers "F.Cu" "B.Cu")
		(net "VR_PVCCIN_CPU1_PH5_BOOT")
	)
	(segment
		(start 403.25294 -147.928584)
		(end 403.25294 -147.2057)
		(width 0.254)
		(layer "F.Cu")
		(net "VR_P1V8_PCH_STBY_FB")
	)
	(via
		(at 402.463 -147.068286)
		(size 0.6604)
		(drill 0.3302)
		(layers "F.Cu" "B.Cu")
		(net "VR_P1V8_PCH_STBY_FB")
	)
	(via
		(at 403.25294 -147.2057)
		(size 0.508)
		(drill 0.254)
		(layers "F.Cu" "B.Cu")
		(net "VR_P1V8_PCH_STBY_FB")
	)
	(segment
		(start 402.463 -148.1074)
		(end 402.9456 -148.1074)
		(width 0.254)
		(layer "B.Cu")
		(net "VR_P1V8_PCH_STBY_FB")
	)
	(segment
		(start 403.115526 -147.068286)
		(end 402.463 -147.068286)
		(width 0.254)
		(layer "B.Cu")
		(net "VR_P1V8_PCH_STBY_FB")
	)
	(segment
		(start 402.971 -148.082)
		(end 403.4282 -148.082)
		(width 0.254)
		(layer "B.Cu")
		(net "VR_P1V8_PCH_STBY_FB")
	)
	(segment
		(start 403.25294 -147.2057)
		(end 403.115526 -147.068286)
		(width 0.254)
		(layer "B.Cu")
		(net "VR_P1V8_PCH_STBY_FB")
	)
	(segment
		(start 402.463 -147.068286)
		(end 402.463 -148.1074)
		(width 0.254)
		(layer "B.Cu")
		(net "VR_P1V8_PCH_STBY_FB")
	)
	(segment
		(start 402.9456 -148.1074)
		(end 402.971 -148.082)
		(width 0.254)
		(layer "B.Cu")
		(net "VR_P1V8_PCH_STBY_FB")
	)
	(segment
		(start -1.0414 -140.8176)
		(end -1.162812 -140.939012)
		(width 0.508)
		(layer "F.Cu")
		(net "VR_FET_SW_P12V_STBY_PVDDQ_KLM")
	)
	(segment
		(start 0.365506 -140.660882)
		(end -0.06096 -140.234416)
		(width 0.254)
		(layer "F.Cu")
		(net "VR_FET_SW_P12V_STBY_PVDDQ_KLM")
	)
	(segment
		(start -0.06096 -140.234416)
		(end -0.497586 -140.234416)
		(width 0.254)
		(layer "F.Cu")
		(net "VR_FET_SW_P12V_STBY_PVDDQ_KLM")
	)
	(segment
		(start -1.162812 -140.939012)
		(end -1.864868 -140.939012)
		(width 0.508)
		(layer "F.Cu")
		(net "VR_FET_SW_P12V_STBY_PVDDQ_KLM")
	)
	(via
		(at 15.3162 -128.3843)
		(size 0.508)
		(drill 0.254)
		(layers "F.Cu" "B.Cu")
		(net "VR_FET_SW_P12V_STBY_PVDDQ_KLM")
	)
	(via
		(at 13.462 -133.1722)
		(size 0.508)
		(drill 0.254)
		(layers "F.Cu" "B.Cu")
		(net "VR_FET_SW_P12V_STBY_PVDDQ_KLM")
	)
	(via
		(at -0.3048 -141.351)
		(size 0.508)
		(drill 0.254)
		(layers "F.Cu" "B.Cu")
		(net "VR_FET_SW_P12V_STBY_PVDDQ_KLM")
	)
	(via
		(at 14.883638 -126.720092)
		(size 0.6604)
		(drill 0.3302)
		(layers "F.Cu" "B.Cu")
		(net "VR_FET_SW_P12V_STBY_PVDDQ_KLM")
	)
	(via
		(at 0.4064 -150.495)
		(size 0.508)
		(drill 0.254)
		(layers "F.Cu" "B.Cu")
		(net "VR_FET_SW_P12V_STBY_PVDDQ_KLM")
	)
	(via
		(at 0.365506 -149.804882)
		(size 0.508)
		(drill 0.254)
		(layers "F.Cu" "B.Cu")
		(net "VR_FET_SW_P12V_STBY_PVDDQ_KLM")
	)
	(via
		(at 13.6906 -128.3843)
		(size 0.508)
		(drill 0.254)
		(layers "F.Cu" "B.Cu")
		(net "VR_FET_SW_P12V_STBY_PVDDQ_KLM")
	)
	(via
		(at 13.462 -132.5372)
		(size 0.508)
		(drill 0.254)
		(layers "F.Cu" "B.Cu")
		(net "VR_FET_SW_P12V_STBY_PVDDQ_KLM")
	)
	(via
		(at 0.390906 -148.890482)
		(size 0.508)
		(drill 0.254)
		(layers "F.Cu" "B.Cu")
		(net "VR_FET_SW_P12V_STBY_PVDDQ_KLM")
	)
	(via
		(at 14.732 -132.5372)
		(size 0.508)
		(drill 0.254)
		(layers "F.Cu" "B.Cu")
		(net "VR_FET_SW_P12V_STBY_PVDDQ_KLM")
	)
	(via
		(at 14.097 -132.5372)
		(size 0.508)
		(drill 0.254)
		(layers "F.Cu" "B.Cu")
		(net "VR_FET_SW_P12V_STBY_PVDDQ_KLM")
	)
	(via
		(at 0.3556 -141.351)
		(size 0.508)
		(drill 0.254)
		(layers "F.Cu" "B.Cu")
		(net "VR_FET_SW_P12V_STBY_PVDDQ_KLM")
	)
	(via
		(at -1.0414 -140.8176)
		(size 0.508)
		(drill 0.254)
		(layers "F.Cu" "B.Cu")
		(net "VR_FET_SW_P12V_STBY_PVDDQ_KLM")
	)
	(via
		(at -1.0922 -141.8336)
		(size 0.508)
		(drill 0.254)
		(layers "F.Cu" "B.Cu")
		(net "VR_FET_SW_P12V_STBY_PVDDQ_KLM")
	)
	(via
		(at -0.2286 -150.495)
		(size 0.508)
		(drill 0.254)
		(layers "F.Cu" "B.Cu")
		(net "VR_FET_SW_P12V_STBY_PVDDQ_KLM")
	)
	(via
		(at 14.5034 -127.5715)
		(size 0.508)
		(drill 0.254)
		(layers "F.Cu" "B.Cu")
		(net "VR_FET_SW_P12V_STBY_PVDDQ_KLM")
	)
	(via
		(at -1.143 -150.876)
		(size 0.508)
		(drill 0.254)
		(layers "F.Cu" "B.Cu")
		(net "VR_FET_SW_P12V_STBY_PVDDQ_KLM")
	)
	(via
		(at 0.390906 -139.746482)
		(size 0.508)
		(drill 0.254)
		(layers "F.Cu" "B.Cu")
		(net "VR_FET_SW_P12V_STBY_PVDDQ_KLM")
	)
	(via
		(at 0.365506 -140.660882)
		(size 0.508)
		(drill 0.254)
		(layers "F.Cu" "B.Cu")
		(net "VR_FET_SW_P12V_STBY_PVDDQ_KLM")
	)
	(via
		(at 13.459968 -131.278884)
		(size 0.508)
		(drill 0.254)
		(layers "F.Cu" "B.Cu")
		(net "VR_FET_SW_P12V_STBY_PVDDQ_KLM")
	)
	(via
		(at 13.462 -131.9022)
		(size 0.508)
		(drill 0.254)
		(layers "F.Cu" "B.Cu")
		(net "VR_FET_SW_P12V_STBY_PVDDQ_KLM")
	)
	(via
		(at 0.365506 -138.832082)
		(size 0.508)
		(drill 0.254)
		(layers "F.Cu" "B.Cu")
		(net "VR_FET_SW_P12V_STBY_PVDDQ_KLM")
	)
	(via
		(at 14.097 -133.1722)
		(size 0.508)
		(drill 0.254)
		(layers "F.Cu" "B.Cu")
		(net "VR_FET_SW_P12V_STBY_PVDDQ_KLM")
	)
	(via
		(at 15.3162 -127.5715)
		(size 0.508)
		(drill 0.254)
		(layers "F.Cu" "B.Cu")
		(net "VR_FET_SW_P12V_STBY_PVDDQ_KLM")
	)
	(via
		(at 14.5034 -128.3843)
		(size 0.508)
		(drill 0.254)
		(layers "F.Cu" "B.Cu")
		(net "VR_FET_SW_P12V_STBY_PVDDQ_KLM")
	)
	(via
		(at 0.365506 -147.976082)
		(size 0.508)
		(drill 0.254)
		(layers "F.Cu" "B.Cu")
		(net "VR_FET_SW_P12V_STBY_PVDDQ_KLM")
	)
	(via
		(at 14.732 -133.1722)
		(size 0.508)
		(drill 0.254)
		(layers "F.Cu" "B.Cu")
		(net "VR_FET_SW_P12V_STBY_PVDDQ_KLM")
	)
	(via
		(at 13.6906 -127.5715)
		(size 0.508)
		(drill 0.254)
		(layers "F.Cu" "B.Cu")
		(net "VR_FET_SW_P12V_STBY_PVDDQ_KLM")
	)
	(via
		(at 14.715744 -131.879848)
		(size 0.508)
		(drill 0.254)
		(layers "F.Cu" "B.Cu")
		(net "VR_FET_SW_P12V_STBY_PVDDQ_KLM")
	)
	(via
		(at 14.097 -131.9022)
		(size 0.508)
		(drill 0.254)
		(layers "F.Cu" "B.Cu")
		(net "VR_FET_SW_P12V_STBY_PVDDQ_KLM")
	)
	(segment
		(start 180.3781 2.994914)
		(end 180.423058 3.039872)
		(width 0.10795)
		(layer "F.Cu")
		(net "PWRGD_PVDDQ_ABC_R")
	)
	(segment
		(start 343.281 -19.558)
		(end 343.277952 -19.554952)
		(width 0.10795)
		(layer "F.Cu")
		(net "PWRGD_PVDDQ_ABC_R")
	)
	(segment
		(start 343.277952 -19.554952)
		(end 343.277952 -18.796)
		(width 0.10795)
		(layer "F.Cu")
		(net "PWRGD_PVDDQ_ABC_R")
	)
	(segment
		(start 343.277952 -18.796)
		(end 343.277952 -17.8181)
		(width 0.10795)
		(layer "F.Cu")
		(net "PWRGD_PVDDQ_ABC_R")
	)
	(segment
		(start 180.3781 2.4003)
		(end 180.3781 2.994914)
		(width 0.10795)
		(layer "F.Cu")
		(net "PWRGD_PVDDQ_ABC_R")
	)
	(segment
		(start 342.265 -19.558)
		(end 343.281 -19.558)
		(width 0.10795)
		(layer "F.Cu")
		(net "PWRGD_PVDDQ_ABC_R")
	)
	(segment
		(start 341.376 -19.558)
		(end 342.265 -19.558)
		(width 0.10795)
		(layer "F.Cu")
		(net "PWRGD_PVDDQ_ABC_R")
	)
	(via
		(at 343.277952 -18.796)
		(size 0.508)
		(drill 0.254)
		(layers "F.Cu" "B.Cu")
		(net "PWRGD_PVDDQ_ABC_R")
	)
	(via
		(at 180.423058 3.039872)
		(size 0.508)
		(drill 0.254)
		(layers "F.Cu" "B.Cu")
		(net "PWRGD_PVDDQ_ABC_R")
	)
	(segment
		(start 180.423058 3.039872)
		(end 179.392326 4.070604)
		(width 0.089408)
		(layer "In11.Cu")
		(net "PWRGD_PVDDQ_ABC_R")
	)
	(segment
		(start 180.25999 5.498084)
		(end 329.041252 5.498084)
		(width 0.089408)
		(layer "In11.Cu")
		(net "PWRGD_PVDDQ_ABC_R")
	)
	(segment
		(start 338.385404 -12.036552)
		(end 340.760812 -14.41196)
		(width 0.089408)
		(layer "In11.Cu")
		(net "PWRGD_PVDDQ_ABC_R")
	)
	(segment
		(start 329.625452 -0.631444)
		(end 330.039218 -1.04521)
		(width 0.089408)
		(layer "In11.Cu")
		(net "PWRGD_PVDDQ_ABC_R")
	)
	(segment
		(start 341.20836 -18.796)
		(end 343.277952 -18.796)
		(width 0.089408)
		(layer "In11.Cu")
		(net "PWRGD_PVDDQ_ABC_R")
	)
	(segment
		(start 179.392326 4.63042)
		(end 180.25999 5.498084)
		(width 0.089408)
		(layer "In11.Cu")
		(net "PWRGD_PVDDQ_ABC_R")
	)
	(segment
		(start 338.27974 -12.036552)
		(end 338.385404 -12.036552)
		(width 0.089408)
		(layer "In11.Cu")
		(net "PWRGD_PVDDQ_ABC_R")
	)
	(segment
		(start 340.760812 -14.41196)
		(end 340.760812 -18.348452)
		(width 0.089408)
		(layer "In11.Cu")
		(net "PWRGD_PVDDQ_ABC_R")
	)
	(segment
		(start 340.760812 -18.348452)
		(end 341.20836 -18.796)
		(width 0.089408)
		(layer "In11.Cu")
		(net "PWRGD_PVDDQ_ABC_R")
	)
	(segment
		(start 338.276184 -12.032996)
		(end 338.27974 -12.036552)
		(width 0.089408)
		(layer "In11.Cu")
		(net "PWRGD_PVDDQ_ABC_R")
	)
	(segment
		(start 335.876646 -12.032996)
		(end 338.276184 -12.032996)
		(width 0.089408)
		(layer "In11.Cu")
		(net "PWRGD_PVDDQ_ABC_R")
	)
	(segment
		(start 179.392326 4.070604)
		(end 179.392326 4.63042)
		(width 0.089408)
		(layer "In11.Cu")
		(net "PWRGD_PVDDQ_ABC_R")
	)
	(segment
		(start 329.625452 4.913884)
		(end 329.625452 -0.631444)
		(width 0.089408)
		(layer "In11.Cu")
		(net "PWRGD_PVDDQ_ABC_R")
	)
	(segment
		(start 330.039218 -4.262374)
		(end 331.33792 -5.561076)
		(width 0.089408)
		(layer "In11.Cu")
		(net "PWRGD_PVDDQ_ABC_R")
	)
	(segment
		(start 331.33792 -7.49427)
		(end 335.876646 -12.032996)
		(width 0.089408)
		(layer "In11.Cu")
		(net "PWRGD_PVDDQ_ABC_R")
	)
	(segment
		(start 331.33792 -5.561076)
		(end 331.33792 -7.49427)
		(width 0.089408)
		(layer "In11.Cu")
		(net "PWRGD_PVDDQ_ABC_R")
	)
	(segment
		(start 330.039218 -1.04521)
		(end 330.039218 -4.262374)
		(width 0.089408)
		(layer "In11.Cu")
		(net "PWRGD_PVDDQ_ABC_R")
	)
	(segment
		(start 329.041252 5.498084)
		(end 329.625452 4.913884)
		(width 0.089408)
		(layer "In11.Cu")
		(net "PWRGD_PVDDQ_ABC_R")
	)
	(segment
		(start 408.44978 -154.2923)
		(end 408.44978 -148.88718)
		(width 0.10795)
		(layer "F.Cu")
		(net "PWRGD_P1V8_PCH_STBY")
	)
	(segment
		(start 404.90394 -155.32354)
		(end 405.33066 -155.75026)
		(width 0.10795)
		(layer "F.Cu")
		(net "PWRGD_P1V8_PCH_STBY")
	)
	(segment
		(start 408.84348 -148.49348)
		(end 408.84348 -146.44878)
		(width 0.10795)
		(layer "F.Cu")
		(net "PWRGD_P1V8_PCH_STBY")
	)
	(segment
		(start 407.32964 -145.97634)
		(end 406.172416 -147.133564)
		(width 0.10795)
		(layer "F.Cu")
		(net "PWRGD_P1V8_PCH_STBY")
	)
	(segment
		(start 406.99182 -155.75026)
		(end 408.44978 -154.2923)
		(width 0.10795)
		(layer "F.Cu")
		(net "PWRGD_P1V8_PCH_STBY")
	)
	(segment
		(start 405.33066 -155.75026)
		(end 406.99182 -155.75026)
		(width 0.10795)
		(layer "F.Cu")
		(net "PWRGD_P1V8_PCH_STBY")
	)
	(segment
		(start 408.44978 -148.88718)
		(end 408.84348 -148.49348)
		(width 0.10795)
		(layer "F.Cu")
		(net "PWRGD_P1V8_PCH_STBY")
	)
	(segment
		(start 408.37104 -145.97634)
		(end 407.32964 -145.97634)
		(width 0.10795)
		(layer "F.Cu")
		(net "PWRGD_P1V8_PCH_STBY")
	)
	(segment
		(start 408.84348 -146.44878)
		(end 408.37104 -145.97634)
		(width 0.10795)
		(layer "F.Cu")
		(net "PWRGD_P1V8_PCH_STBY")
	)
	(segment
		(start 406.172416 -147.133564)
		(end 406.172416 -147.420584)
		(width 0.10795)
		(layer "F.Cu")
		(net "PWRGD_P1V8_PCH_STBY")
	)
	(via
		(at 402.80082 -150.401528)
		(size 0.6604)
		(drill 0.3302)
		(layers "F.Cu" "B.Cu")
		(net "PWRGD_P1V8_PCH_STBY")
	)
	(via
		(at 404.90394 -155.32354)
		(size 0.508)
		(drill 0.254)
		(layers "F.Cu" "B.Cu")
		(net "PWRGD_P1V8_PCH_STBY")
	)
	(segment
		(start 405.01062 -151.53894)
		(end 405.01062 -155.21686)
		(width 0.10795)
		(layer "B.Cu")
		(net "PWRGD_P1V8_PCH_STBY")
	)
	(segment
		(start 403.521418 -150.634192)
		(end 404.105872 -150.634192)
		(width 0.10795)
		(layer "B.Cu")
		(net "PWRGD_P1V8_PCH_STBY")
	)
	(segment
		(start 403.288754 -150.401528)
		(end 403.521418 -150.634192)
		(width 0.10795)
		(layer "B.Cu")
		(net "PWRGD_P1V8_PCH_STBY")
	)
	(segment
		(start 402.80082 -150.401528)
		(end 403.288754 -150.401528)
		(width 0.10795)
		(layer "B.Cu")
		(net "PWRGD_P1V8_PCH_STBY")
	)
	(segment
		(start 400.829526 -149.663912)
		(end 400.829526 -150.061676)
		(width 0.10795)
		(layer "B.Cu")
		(net "PWRGD_P1V8_PCH_STBY")
	)
	(segment
		(start 400.829526 -150.061676)
		(end 401.169378 -150.401528)
		(width 0.10795)
		(layer "B.Cu")
		(net "PWRGD_P1V8_PCH_STBY")
	)
	(segment
		(start 405.01062 -155.21686)
		(end 404.90394 -155.32354)
		(width 0.10795)
		(layer "B.Cu")
		(net "PWRGD_P1V8_PCH_STBY")
	)
	(segment
		(start 401.169378 -150.401528)
		(end 402.80082 -150.401528)
		(width 0.10795)
		(layer "B.Cu")
		(net "PWRGD_P1V8_PCH_STBY")
	)
	(segment
		(start 404.105872 -150.634192)
		(end 405.01062 -151.53894)
		(width 0.10795)
		(layer "B.Cu")
		(net "PWRGD_P1V8_PCH_STBY")
	)
	(segment
		(start 341.849202 -16.366998)
		(end 339.9282 -18.288)
		(width 0.10795)
		(layer "F.Cu")
		(net "PU_VR_PVDDQ_ABC_FAULT1")
	)
	(segment
		(start 339.6996 -18.415)
		(end 339.6996 -18.288)
		(width 0.10795)
		(layer "F.Cu")
		(net "PU_VR_PVDDQ_ABC_FAULT1")
	)
	(segment
		(start 339.1916 -18.923)
		(end 339.6996 -18.415)
		(width 0.10795)
		(layer "F.Cu")
		(net "PU_VR_PVDDQ_ABC_FAULT1")
	)
	(segment
		(start 339.9282 -18.288)
		(end 339.6996 -18.288)
		(width 0.10795)
		(layer "F.Cu")
		(net "PU_VR_PVDDQ_ABC_FAULT1")
	)
	(segment
		(start 342.2269 -16.366998)
		(end 341.849202 -16.366998)
		(width 0.10795)
		(layer "F.Cu")
		(net "PU_VR_PVDDQ_ABC_FAULT1")
	)
	(segment
		(start 338.836 -18.923)
		(end 339.1916 -18.923)
		(width 0.10795)
		(layer "F.Cu")
		(net "PU_VR_PVDDQ_ABC_FAULT1")
	)
	(via
		(at 339.6996 -18.288)
		(size 0.508)
		(drill 0.254)
		(layers "F.Cu" "B.Cu")
		(net "PU_VR_PVDDQ_ABC_FAULT1")
	)
	(via
		(at 29.434282 -139.198096)
		(size 0.508)
		(drill 0.254)
		(layers "F.Cu" "B.Cu")
		(net "P12V_NVDIMM_KLM")
	)
	(via
		(at 16.383762 -132.347716)
		(size 0.508)
		(drill 0.254)
		(layers "F.Cu" "B.Cu")
		(net "P12V_NVDIMM_KLM")
	)
	(via
		(at 29.068268 -128.9812)
		(size 0.508)
		(drill 0.254)
		(layers "F.Cu" "B.Cu")
		(net "P12V_NVDIMM_KLM")
	)
	(via
		(at 16.9545 -131.9276)
		(size 0.508)
		(drill 0.254)
		(layers "F.Cu" "B.Cu")
		(net "P12V_NVDIMM_KLM")
	)
	(via
		(at 29.699458 -131.5466)
		(size 0.508)
		(drill 0.254)
		(layers "F.Cu" "B.Cu")
		(net "P12V_NVDIMM_KLM")
	)
	(via
		(at 14.193774 -133.966458)
		(size 0.6604)
		(drill 0.3302)
		(layers "F.Cu" "B.Cu")
		(net "P12V_NVDIMM_KLM")
	)
	(via
		(at 29.085286 -146.217132)
		(size 0.508)
		(drill 0.254)
		(layers "F.Cu" "B.Cu")
		(net "P12V_NVDIMM_KLM")
	)
	(via
		(at 16.4084 -131.5974)
		(size 0.508)
		(drill 0.254)
		(layers "F.Cu" "B.Cu")
		(net "P12V_NVDIMM_KLM")
	)
	(via
		(at 29.699458 -150.749)
		(size 0.508)
		(drill 0.254)
		(layers "F.Cu" "B.Cu")
		(net "P12V_NVDIMM_KLM")
	)
	(via
		(at 16.97736 -133.1722)
		(size 0.508)
		(drill 0.254)
		(layers "F.Cu" "B.Cu")
		(net "P12V_NVDIMM_KLM")
	)
	(via
		(at 16.4084 -130.9624)
		(size 0.508)
		(drill 0.254)
		(layers "F.Cu" "B.Cu")
		(net "P12V_NVDIMM_KLM")
	)
	(via
		(at 16.35252 -132.995924)
		(size 0.508)
		(drill 0.254)
		(layers "F.Cu" "B.Cu")
		(net "P12V_NVDIMM_KLM")
	)
	(via
		(at 16.35252 -133.655308)
		(size 0.508)
		(drill 0.254)
		(layers "F.Cu" "B.Cu")
		(net "P12V_NVDIMM_KLM")
	)
	(via
		(at 29.068268 -129.6162)
		(size 0.508)
		(drill 0.254)
		(layers "F.Cu" "B.Cu")
		(net "P12V_NVDIMM_KLM")
	)
	(via
		(at 16.9545 -132.5626)
		(size 0.508)
		(drill 0.254)
		(layers "F.Cu" "B.Cu")
		(net "P12V_NVDIMM_KLM")
	)
	(via
		(at 29.037788 -133.59892)
		(size 0.508)
		(drill 0.254)
		(layers "F.Cu" "B.Cu")
		(net "P12V_NVDIMM_KLM")
	)
	(via
		(at 16.9545 -131.2926)
		(size 0.508)
		(drill 0.254)
		(layers "F.Cu" "B.Cu")
		(net "P12V_NVDIMM_KLM")
	)
	(via
		(at 28.9941 -148.8059)
		(size 0.508)
		(drill 0.254)
		(layers "F.Cu" "B.Cu")
		(net "P12V_NVDIMM_KLM")
	)
	(via
		(at 12.031726 -133.85927)
		(size 0.508)
		(drill 0.254)
		(layers "F.Cu" "B.Cu")
		(net "P12V_NVDIMM_KLM")
	)
	(via
		(at 29.699458 -141.1478)
		(size 0.508)
		(drill 0.254)
		(layers "F.Cu" "B.Cu")
		(net "P12V_NVDIMM_KLM")
	)
	(via
		(at 16.97736 -133.8072)
		(size 0.508)
		(drill 0.254)
		(layers "F.Cu" "B.Cu")
		(net "P12V_NVDIMM_KLM")
	)
	(via
		(at 11.812778 -133.084062)
		(size 0.508)
		(drill 0.254)
		(layers "F.Cu" "B.Cu")
		(net "P12V_NVDIMM_KLM")
	)
	(segment
		(start 10.669778 -123.033536)
		(end 12.238736 -123.033536)
		(width 0.254)
		(layer "B.Cu")
		(net "P12V_NVDIMM_KLM")
	)
	(segment
		(start 12.7254 -123.5202)
		(end 12.7254 -123.841764)
		(width 0.254)
		(layer "B.Cu")
		(net "P12V_NVDIMM_KLM")
	)
	(segment
		(start 12.7254 -123.841764)
		(end 13.0048 -124.121164)
		(width 0.254)
		(layer "B.Cu")
		(net "P12V_NVDIMM_KLM")
	)
	(segment
		(start 10.2108 -123.921266)
		(end 10.2108 -123.492514)
		(width 0.254)
		(layer "B.Cu")
		(net "P12V_NVDIMM_KLM")
	)
	(segment
		(start 11.312144 -130.687826)
		(end 11.586718 -130.9624)
		(width 0.254)
		(layer "B.Cu")
		(net "P12V_NVDIMM_KLM")
	)
	(segment
		(start 12.851384 -127.382016)
		(end 12.851384 -129.085848)
		(width 0.254)
		(layer "B.Cu")
		(net "P12V_NVDIMM_KLM")
	)
	(segment
		(start 11.312144 -129.783078)
		(end 11.312144 -130.687826)
		(width 0.254)
		(layer "B.Cu")
		(net "P12V_NVDIMM_KLM")
	)
	(segment
		(start 12.238736 -123.033536)
		(end 12.7254 -123.5202)
		(width 0.254)
		(layer "B.Cu")
		(net "P12V_NVDIMM_KLM")
	)
	(segment
		(start 12.851384 -129.085848)
		(end 12.384024 -129.553208)
		(width 0.254)
		(layer "B.Cu")
		(net "P12V_NVDIMM_KLM")
	)
	(segment
		(start 12.384024 -129.553208)
		(end 11.542014 -129.553208)
		(width 0.254)
		(layer "B.Cu")
		(net "P12V_NVDIMM_KLM")
	)
	(segment
		(start 13.0048 -124.121164)
		(end 13.0048 -124.6505)
		(width 0.254)
		(layer "B.Cu")
		(net "P12V_NVDIMM_KLM")
	)
	(segment
		(start 10.2108 -123.492514)
		(end 10.669778 -123.033536)
		(width 0.254)
		(layer "B.Cu")
		(net "P12V_NVDIMM_KLM")
	)
	(segment
		(start 11.542014 -129.553208)
		(end 11.312144 -129.783078)
		(width 0.254)
		(layer "B.Cu")
		(net "P12V_NVDIMM_KLM")
	)
	(segment
		(start 11.586718 -130.9624)
		(end 12.192 -130.9624)
		(width 0.254)
		(layer "B.Cu")
		(net "P12V_NVDIMM_KLM")
	)
	(segment
		(start 13.646658 -125.292358)
		(end 13.646658 -126.586742)
		(width 0.254)
		(layer "B.Cu")
		(net "P12V_NVDIMM_KLM")
	)
	(segment
		(start 13.646658 -126.586742)
		(end 12.851384 -127.382016)
		(width 0.254)
		(layer "B.Cu")
		(net "P12V_NVDIMM_KLM")
	)
	(segment
		(start 13.0048 -124.6505)
		(end 13.646658 -125.292358)
		(width 0.254)
		(layer "B.Cu")
		(net "P12V_NVDIMM_KLM")
	)
	(segment
		(start 30.20949 -31.141162)
		(end 32.180784 -31.141162)
		(width 0.254)
		(layer "F.Cu")
		(net "P12V_NVDIMM_GHJ")
	)
	(segment
		(start 32.180784 -31.141162)
		(end 32.6263 -30.695646)
		(width 0.254)
		(layer "F.Cu")
		(net "P12V_NVDIMM_GHJ")
	)
	(segment
		(start 32.6263 -30.695646)
		(end 32.6263 -30.1498)
		(width 0.254)
		(layer "F.Cu")
		(net "P12V_NVDIMM_GHJ")
	)
	(via
		(at 29.2862 1.4224)
		(size 0.6604)
		(drill 0.3302)
		(layers "F.Cu" "B.Cu")
		(net "P12V_NVDIMM_GHJ")
	)
	(via
		(at 29.45892 -18.71472)
		(size 0.508)
		(drill 0.254)
		(layers "F.Cu" "B.Cu")
		(net "P12V_NVDIMM_GHJ")
	)
	(via
		(at 29.639768 0.4572)
		(size 0.508)
		(drill 0.254)
		(layers "F.Cu" "B.Cu")
		(net "P12V_NVDIMM_GHJ")
	)
	(via
		(at 25.052782 -19.934174)
		(size 0.5588)
		(drill 0.3048)
		(layers "F.Cu" "B.Cu")
		(net "P12V_NVDIMM_GHJ")
	)
	(via
		(at 30.530038 -27.073098)
		(size 0.508)
		(drill 0.254)
		(layers "F.Cu" "B.Cu")
		(net "P12V_NVDIMM_GHJ")
	)
	(via
		(at 28.7274 -14.67358)
		(size 0.508)
		(drill 0.254)
		(layers "F.Cu" "B.Cu")
		(net "P12V_NVDIMM_GHJ")
	)
	(via
		(at 29.48178 -9.08812)
		(size 0.508)
		(drill 0.254)
		(layers "F.Cu" "B.Cu")
		(net "P12V_NVDIMM_GHJ")
	)
	(via
		(at 25.43556 -21.12518)
		(size 0.508)
		(drill 0.254)
		(layers "F.Cu" "B.Cu")
		(net "P12V_NVDIMM_GHJ")
	)
	(via
		(at 28.9687 -5.41528)
		(size 0.508)
		(drill 0.254)
		(layers "F.Cu" "B.Cu")
		(net "P12V_NVDIMM_GHJ")
	)
	(via
		(at 23.250144 -19.934174)
		(size 0.5588)
		(drill 0.3048)
		(layers "F.Cu" "B.Cu")
		(net "P12V_NVDIMM_GHJ")
	)
	(via
		(at 29.5402 2.40284)
		(size 0.508)
		(drill 0.254)
		(layers "F.Cu" "B.Cu")
		(net "P12V_NVDIMM_GHJ")
	)
	(via
		(at 24.140414 -19.926554)
		(size 0.5588)
		(drill 0.3048)
		(layers "F.Cu" "B.Cu")
		(net "P12V_NVDIMM_GHJ")
	)
	(segment
		(start 192.685162 -127.604774)
		(end 192.479168 -127.39878)
		(width 0.254)
		(layer "F.Cu")
		(net "P12V_NVDIMM_DEF")
	)
	(segment
		(start 192.479168 -127.39878)
		(end 191.87287 -127.39878)
		(width 0.254)
		(layer "F.Cu")
		(net "P12V_NVDIMM_DEF")
	)
	(segment
		(start 187.784486 -127.150114)
		(end 187.607702 -126.97333)
		(width 0.254)
		(layer "F.Cu")
		(net "P12V_NVDIMM_DEF")
	)
	(segment
		(start 192.685162 -128.568958)
		(end 192.685162 -127.604774)
		(width 0.254)
		(layer "F.Cu")
		(net "P12V_NVDIMM_DEF")
	)
	(segment
		(start 187.784486 -128.143)
		(end 187.784486 -127.150114)
		(width 0.254)
		(layer "F.Cu")
		(net "P12V_NVDIMM_DEF")
	)
	(segment
		(start 187.607702 -126.97333)
		(end 186.882532 -126.97333)
		(width 0.254)
		(layer "F.Cu")
		(net "P12V_NVDIMM_DEF")
	)
	(segment
		(start 191.87287 -127.39878)
		(end 190.49365 -128.778)
		(width 0.254)
		(layer "F.Cu")
		(net "P12V_NVDIMM_DEF")
	)
	(segment
		(start 188.419486 -128.778)
		(end 187.784486 -128.143)
		(width 0.254)
		(layer "F.Cu")
		(net "P12V_NVDIMM_DEF")
	)
	(segment
		(start 190.49365 -128.778)
		(end 188.419486 -128.778)
		(width 0.254)
		(layer "F.Cu")
		(net "P12V_NVDIMM_DEF")
	)
	(via
		(at 194.0433 -129.80416)
		(size 0.508)
		(drill 0.254)
		(layers "F.Cu" "B.Cu")
		(net "P12V_NVDIMM_DEF")
	)
	(via
		(at 194.69989 -141.1478)
		(size 0.508)
		(drill 0.254)
		(layers "F.Cu" "B.Cu")
		(net "P12V_NVDIMM_DEF")
	)
	(via
		(at 194.69989 -131.5466)
		(size 0.508)
		(drill 0.254)
		(layers "F.Cu" "B.Cu")
		(net "P12V_NVDIMM_DEF")
	)
	(via
		(at 194.69989 -150.749)
		(size 0.508)
		(drill 0.254)
		(layers "F.Cu" "B.Cu")
		(net "P12V_NVDIMM_DEF")
	)
	(via
		(at 194.3354 -136.42594)
		(size 0.508)
		(drill 0.254)
		(layers "F.Cu" "B.Cu")
		(net "P12V_NVDIMM_DEF")
	)
	(via
		(at 194.0433 -128.53416)
		(size 0.508)
		(drill 0.254)
		(layers "F.Cu" "B.Cu")
		(net "P12V_NVDIMM_DEF")
	)
	(via
		(at 194.085718 -146.217132)
		(size 0.508)
		(drill 0.254)
		(layers "F.Cu" "B.Cu")
		(net "P12V_NVDIMM_DEF")
	)
	(via
		(at 193.1162 -153.4922)
		(size 0.6604)
		(drill 0.3302)
		(layers "F.Cu" "B.Cu")
		(net "P12V_NVDIMM_DEF")
	)
	(via
		(at 194.0433 -129.16916)
		(size 0.508)
		(drill 0.254)
		(layers "F.Cu" "B.Cu")
		(net "P12V_NVDIMM_DEF")
	)
	(segment
		(start 194.69989 -150.749)
		(end 194.700398 -150.749508)
		(width 0.254)
		(layer "B.Cu")
		(net "P12V_NVDIMM_DEF")
	)
	(segment
		(start 186.6011 -131.172204)
		(end 186.6011 -127.9398)
		(width 0.508)
		(layer "B.Cu")
		(net "P12V_NVDIMM_DEF")
	)
	(segment
		(start 188.159136 -132.73024)
		(end 186.6011 -131.172204)
		(width 0.508)
		(layer "B.Cu")
		(net "P12V_NVDIMM_DEF")
	)
	(segment
		(start 194.69989 -141.1478)
		(end 194.700398 -141.148308)
		(width 0.254)
		(layer "B.Cu")
		(net "P12V_NVDIMM_DEF")
	)
	(segment
		(start 189.7761 -132.73024)
		(end 188.159136 -132.73024)
		(width 0.508)
		(layer "B.Cu")
		(net "P12V_NVDIMM_DEF")
	)
	(segment
		(start 185.9661 -127.3048)
		(end 185.2549 -127.3048)
		(width 0.508)
		(layer "B.Cu")
		(net "P12V_NVDIMM_DEF")
	)
	(segment
		(start 194.700398 -136.790938)
		(end 194.3354 -136.42594)
		(width 0.254)
		(layer "B.Cu")
		(net "P12V_NVDIMM_DEF")
	)
	(segment
		(start 194.700398 -150.749508)
		(end 194.700398 -152.078436)
		(width 0.254)
		(layer "B.Cu")
		(net "P12V_NVDIMM_DEF")
	)
	(segment
		(start 194.700398 -137.877296)
		(end 194.700398 -136.790938)
		(width 0.254)
		(layer "B.Cu")
		(net "P12V_NVDIMM_DEF")
	)
	(segment
		(start 194.700398 -141.148308)
		(end 194.700398 -142.477236)
		(width 0.254)
		(layer "B.Cu")
		(net "P12V_NVDIMM_DEF")
	)
	(segment
		(start 194.69989 -131.5466)
		(end 194.700398 -131.547108)
		(width 0.254)
		(layer "B.Cu")
		(net "P12V_NVDIMM_DEF")
	)
	(segment
		(start 194.700398 -131.547108)
		(end 194.700398 -132.876036)
		(width 0.254)
		(layer "B.Cu")
		(net "P12V_NVDIMM_DEF")
	)
	(segment
		(start 186.6011 -127.9398)
		(end 185.9661 -127.3048)
		(width 0.508)
		(layer "B.Cu")
		(net "P12V_NVDIMM_DEF")
	)
	(segment
		(start 184.785 -24.030686)
		(end 184.785 -23.622)
		(width 0.254)
		(layer "F.Cu")
		(net "P12V_NVDIMM_ABC")
	)
	(segment
		(start 183.54802 -24.443436)
		(end 184.37225 -24.443436)
		(width 0.254)
		(layer "F.Cu")
		(net "P12V_NVDIMM_ABC")
	)
	(segment
		(start 183.536336 -24.431752)
		(end 183.54802 -24.443436)
		(width 0.254)
		(layer "F.Cu")
		(net "P12V_NVDIMM_ABC")
	)
	(segment
		(start 184.37225 -24.443436)
		(end 184.785 -24.030686)
		(width 0.254)
		(layer "F.Cu")
		(net "P12V_NVDIMM_ABC")
	)
	(segment
		(start 182.604664 -24.431752)
		(end 183.536336 -24.431752)
		(width 0.254)
		(layer "F.Cu")
		(net "P12V_NVDIMM_ABC")
	)
	(via
		(at 194.6402 0.4572)
		(size 0.508)
		(drill 0.254)
		(layers "F.Cu" "B.Cu")
		(net "P12V_NVDIMM_ABC")
	)
	(via
		(at 191.18072 -21.209)
		(size 0.508)
		(drill 0.254)
		(layers "F.Cu" "B.Cu")
		(net "P12V_NVDIMM_ABC")
	)
	(via
		(at 194.5386 -9.0932)
		(size 0.508)
		(drill 0.254)
		(layers "F.Cu" "B.Cu")
		(net "P12V_NVDIMM_ABC")
	)
	(via
		(at 193.929 -6.08076)
		(size 0.508)
		(drill 0.254)
		(layers "F.Cu" "B.Cu")
		(net "P12V_NVDIMM_ABC")
	)
	(via
		(at 193.929 -15.1638)
		(size 0.508)
		(drill 0.254)
		(layers "F.Cu" "B.Cu")
		(net "P12V_NVDIMM_ABC")
	)
	(via
		(at 186.8678 -21.0058)
		(size 0.508)
		(drill 0.254)
		(layers "F.Cu" "B.Cu")
		(net "P12V_NVDIMM_ABC")
	)
	(via
		(at 193.9036 -19.8882)
		(size 0.508)
		(drill 0.254)
		(layers "F.Cu" "B.Cu")
		(net "P12V_NVDIMM_ABC")
	)
	(via
		(at 194.056 -24.3205)
		(size 0.508)
		(drill 0.254)
		(layers "F.Cu" "B.Cu")
		(net "P12V_NVDIMM_ABC")
	)
	(via
		(at 194.4116 2.4892)
		(size 0.508)
		(drill 0.254)
		(layers "F.Cu" "B.Cu")
		(net "P12V_NVDIMM_ABC")
	)
	(via
		(at 191.1604 -21.8948)
		(size 0.508)
		(drill 0.254)
		(layers "F.Cu" "B.Cu")
		(net "P12V_NVDIMM_ABC")
	)
	(via
		(at 185.368692 -21.463762)
		(size 0.6604)
		(drill 0.3302)
		(layers "F.Cu" "B.Cu")
		(net "P12V_NVDIMM_ABC")
	)
	(segment
		(start 339.321648 -17.853152)
		(end 339.0138 -18.161)
		(width 0.10795)
		(layer "F.Cu")
		(net "TP_PVDDQ_ABC_MP1")
	)
	(segment
		(start 340.793578 -17.126204)
		(end 340.06663 -17.853152)
		(width 0.10795)
		(layer "F.Cu")
		(net "TP_PVDDQ_ABC_MP1")
	)
	(segment
		(start 340.793578 -16.813022)
		(end 340.793578 -17.126204)
		(width 0.10795)
		(layer "F.Cu")
		(net "TP_PVDDQ_ABC_MP1")
	)
	(segment
		(start 340.06663 -17.853152)
		(end 339.321648 -17.853152)
		(width 0.10795)
		(layer "F.Cu")
		(net "TP_PVDDQ_ABC_MP1")
	)
	(segment
		(start 341.639652 -15.966948)
		(end 340.793578 -16.813022)
		(width 0.10795)
		(layer "F.Cu")
		(net "TP_PVDDQ_ABC_MP1")
	)
	(segment
		(start 342.2269 -15.966948)
		(end 341.639652 -15.966948)
		(width 0.10795)
		(layer "F.Cu")
		(net "TP_PVDDQ_ABC_MP1")
	)
	(segment
		(start 339.0138 -18.161)
		(end 338.836 -18.161)
		(width 0.10795)
		(layer "F.Cu")
		(net "TP_PVDDQ_ABC_MP1")
	)
	(segment
		(start 405.78405 -113.18875)
		(end 406.38095 -113.18875)
		(width 0.10795)
		(layer "F.Cu")
		(net "FM_XRC_READY_N")
	)
	(segment
		(start 12.446 -102.0064)
		(end 12.065 -102.3874)
		(width 0.10795)
		(layer "F.Cu")
		(net "FM_XRC_READY_N")
	)
	(segment
		(start 402.975318 -111.913416)
		(end 403.370034 -112.308132)
		(width 0.0889)
		(layer "F.Cu")
		(net "FM_XRC_READY_N")
	)
	(segment
		(start 12.065 -104.67848)
		(end 11.7094 -105.03408)
		(width 0.10795)
		(layer "F.Cu")
		(net "FM_XRC_READY_N")
	)
	(segment
		(start 407.8351 -113.3094)
		(end 407.8605 -113.284)
		(width 0.10795)
		(layer "F.Cu")
		(net "FM_XRC_READY_N")
	)
	(segment
		(start 401.353528 -111.913416)
		(end 402.975318 -111.913416)
		(width 0.0889)
		(layer "F.Cu")
		(net "FM_XRC_READY_N")
	)
	(segment
		(start 12.065 -102.3874)
		(end 12.065 -104.67848)
		(width 0.10795)
		(layer "F.Cu")
		(net "FM_XRC_READY_N")
	)
	(segment
		(start 403.370034 -112.308132)
		(end 404.903432 -112.308132)
		(width 0.0889)
		(layer "F.Cu")
		(net "FM_XRC_READY_N")
	)
	(segment
		(start 406.5016 -113.3094)
		(end 407.8351 -113.3094)
		(width 0.10795)
		(layer "F.Cu")
		(net "FM_XRC_READY_N")
	)
	(segment
		(start 406.38095 -113.18875)
		(end 406.5016 -113.3094)
		(width 0.10795)
		(layer "F.Cu")
		(net "FM_XRC_READY_N")
	)
	(segment
		(start 421.49014 -28.934664)
		(end 421.89019 -28.534614)
		(width 0.10795)
		(layer "F.Cu")
		(net "FM_XRC_READY_N")
	)
	(segment
		(start 401.295108 -111.854996)
		(end 401.353528 -111.913416)
		(width 0.0889)
		(layer "F.Cu")
		(net "FM_XRC_READY_N")
	)
	(segment
		(start 404.903432 -112.308132)
		(end 405.78405 -113.18875)
		(width 0.10795)
		(layer "F.Cu")
		(net "FM_XRC_READY_N")
	)
	(via
		(at 406.5016 -113.3094)
		(size 0.508)
		(drill 0.254)
		(layers "F.Cu" "B.Cu")
		(net "FM_XRC_READY_N")
	)
	(via
		(at 409.357068 -117.316758)
		(size 0.508)
		(drill 0.254)
		(layers "F.Cu" "B.Cu")
		(net "FM_XRC_READY_N")
	)
	(via
		(at 408.698954 -61.82741)
		(size 0.508)
		(drill 0.254)
		(layers "F.Cu" "B.Cu")
		(net "FM_XRC_READY_N")
	)
	(via
		(at 10.543032 -102.259638)
		(size 0.6604)
		(drill 0.3302)
		(layers "F.Cu" "B.Cu")
		(net "FM_XRC_READY_N")
	)
	(via
		(at 421.89019 -28.534614)
		(size 0.4572)
		(drill 0.2032)
		(layers "F.Cu" "B.Cu")
		(net "FM_XRC_READY_N")
	)
	(via
		(at 11.7094 -105.03408)
		(size 0.508)
		(drill 0.254)
		(layers "F.Cu" "B.Cu")
		(net "FM_XRC_READY_N")
	)
	(via
		(at 371.161818 -124.40666)
		(size 0.508)
		(drill 0.254)
		(layers "F.Cu" "B.Cu")
		(net "FM_XRC_READY_N")
	)
	(segment
		(start 7.4676 -97.8154)
		(end 6.945376 -97.8154)
		(width 0.10795)
		(layer "B.Cu")
		(net "FM_XRC_READY_N")
	)
	(segment
		(start 6.945376 -97.8154)
		(end 5.899912 -96.769936)
		(width 0.10795)
		(layer "B.Cu")
		(net "FM_XRC_READY_N")
	)
	(segment
		(start 11.7094 -103.426006)
		(end 11.7094 -105.03408)
		(width 0.10795)
		(layer "B.Cu")
		(net "FM_XRC_READY_N")
	)
	(segment
		(start 10.543032 -102.259638)
		(end 7.874 -99.590606)
		(width 0.10795)
		(layer "B.Cu")
		(net "FM_XRC_READY_N")
	)
	(segment
		(start 10.543032 -102.259638)
		(end 11.7094 -103.426006)
		(width 0.10795)
		(layer "B.Cu")
		(net "FM_XRC_READY_N")
	)
	(segment
		(start 7.874 -98.2218)
		(end 7.4676 -97.8154)
		(width 0.10795)
		(layer "B.Cu")
		(net "FM_XRC_READY_N")
	)
	(segment
		(start 7.874 -99.590606)
		(end 7.874 -98.2218)
		(width 0.10795)
		(layer "B.Cu")
		(net "FM_XRC_READY_N")
	)
	(segment
		(start 404.687024 -86.677754)
		(end 403.778466 -87.586312)
		(width 0.089408)
		(layer "In2.Cu")
		(net "FM_XRC_READY_N")
	)
	(segment
		(start 404.030942 -74.129138)
		(end 403.38756 -74.77252)
		(width 0.089408)
		(layer "In2.Cu")
		(net "FM_XRC_READY_N")
	)
	(segment
		(start 404.151338 -106.158538)
		(end 405.83104 -107.83824)
		(width 0.089408)
		(layer "In2.Cu")
		(net "FM_XRC_READY_N")
	)
	(segment
		(start 403.778466 -87.586312)
		(end 403.079712 -87.586312)
		(width 0.089408)
		(layer "In2.Cu")
		(net "FM_XRC_READY_N")
	)
	(segment
		(start 403.38756 -74.77252)
		(end 403.38756 -76.650342)
		(width 0.089408)
		(layer "In2.Cu")
		(net "FM_XRC_READY_N")
	)
	(segment
		(start 401.736306 -102.28199)
		(end 401.736052 -102.282244)
		(width 0.089408)
		(layer "In2.Cu")
		(net "FM_XRC_READY_N")
	)
	(segment
		(start 409.503372 -62.631828)
		(end 409.503372 -66.850768)
		(width 0.089408)
		(layer "In2.Cu")
		(net "FM_XRC_READY_N")
	)
	(segment
		(start 402.50237 -80.77581)
		(end 402.50237 -82.106262)
		(width 0.089408)
		(layer "In2.Cu")
		(net "FM_XRC_READY_N")
	)
	(segment
		(start 402.378164 -103.66248)
		(end 403.304756 -103.66248)
		(width 0.089408)
		(layer "In2.Cu")
		(net "FM_XRC_READY_N")
	)
	(segment
		(start 409.62326 -66.970656)
		(end 409.62326 -68.215002)
		(width 0.089408)
		(layer "In2.Cu")
		(net "FM_XRC_READY_N")
	)
	(segment
		(start 402.274024 -77.763878)
		(end 402.274024 -78.636368)
		(width 0.089408)
		(layer "In2.Cu")
		(net "FM_XRC_READY_N")
	)
	(segment
		(start 402.22932 -99.573334)
		(end 402.22932 -101.63048)
		(width 0.089408)
		(layer "In2.Cu")
		(net "FM_XRC_READY_N")
	)
	(segment
		(start 402.50237 -82.106262)
		(end 403.902164 -83.506056)
		(width 0.089408)
		(layer "In2.Cu")
		(net "FM_XRC_READY_N")
	)
	(segment
		(start 404.030942 -73.80732)
		(end 404.030942 -74.129138)
		(width 0.089408)
		(layer "In2.Cu")
		(net "FM_XRC_READY_N")
	)
	(segment
		(start 405.83104 -107.83824)
		(end 405.83104 -112.63884)
		(width 0.089408)
		(layer "In2.Cu")
		(net "FM_XRC_READY_N")
	)
	(segment
		(start 402.311362 -80.23606)
		(end 402.311362 -80.584802)
		(width 0.089408)
		(layer "In2.Cu")
		(net "FM_XRC_READY_N")
	)
	(segment
		(start 402.679408 -79.043784)
		(end 402.679408 -79.868014)
		(width 0.089408)
		(layer "In2.Cu")
		(net "FM_XRC_READY_N")
	)
	(segment
		(start 402.581618 -92.79763)
		(end 402.581618 -99.221036)
		(width 0.089408)
		(layer "In2.Cu")
		(net "FM_XRC_READY_N")
	)
	(segment
		(start 404.151338 -104.509062)
		(end 404.151338 -106.158538)
		(width 0.089408)
		(layer "In2.Cu")
		(net "FM_XRC_READY_N")
	)
	(segment
		(start 402.068284 -88.59774)
		(end 402.068284 -92.284296)
		(width 0.089408)
		(layer "In2.Cu")
		(net "FM_XRC_READY_N")
	)
	(segment
		(start 407.02738 -114.98707)
		(end 409.357068 -117.316758)
		(width 0.089408)
		(layer "In2.Cu")
		(net "FM_XRC_READY_N")
	)
	(segment
		(start 403.902164 -83.506056)
		(end 404.229062 -83.506056)
		(width 0.089408)
		(layer "In2.Cu")
		(net "FM_XRC_READY_N")
	)
	(segment
		(start 405.83104 -112.63884)
		(end 406.5016 -113.3094)
		(width 0.089408)
		(layer "In2.Cu")
		(net "FM_XRC_READY_N")
	)
	(segment
		(start 409.503372 -66.850768)
		(end 409.62326 -66.970656)
		(width 0.089408)
		(layer "In2.Cu")
		(net "FM_XRC_READY_N")
	)
	(segment
		(start 402.274024 -78.636368)
		(end 402.680424 -79.042768)
		(width 0.089408)
		(layer "In2.Cu")
		(net "FM_XRC_READY_N")
	)
	(segment
		(start 401.736052 -102.282244)
		(end 401.736052 -103.020368)
		(width 0.089408)
		(layer "In2.Cu")
		(net "FM_XRC_READY_N")
	)
	(segment
		(start 402.581618 -99.221036)
		(end 402.22932 -99.573334)
		(width 0.089408)
		(layer "In2.Cu")
		(net "FM_XRC_READY_N")
	)
	(segment
		(start 403.079712 -87.586312)
		(end 402.068284 -88.59774)
		(width 0.089408)
		(layer "In2.Cu")
		(net "FM_XRC_READY_N")
	)
	(segment
		(start 404.229062 -83.506056)
		(end 404.687024 -83.964018)
		(width 0.089408)
		(layer "In2.Cu")
		(net "FM_XRC_READY_N")
	)
	(segment
		(start 404.687024 -83.964018)
		(end 404.687024 -86.677754)
		(width 0.089408)
		(layer "In2.Cu")
		(net "FM_XRC_READY_N")
	)
	(segment
		(start 409.62326 -68.215002)
		(end 404.030942 -73.80732)
		(width 0.089408)
		(layer "In2.Cu")
		(net "FM_XRC_READY_N")
	)
	(segment
		(start 402.068284 -92.284296)
		(end 402.581618 -92.79763)
		(width 0.089408)
		(layer "In2.Cu")
		(net "FM_XRC_READY_N")
	)
	(segment
		(start 407.02738 -113.83518)
		(end 407.02738 -114.98707)
		(width 0.089408)
		(layer "In2.Cu")
		(net "FM_XRC_READY_N")
	)
	(segment
		(start 406.5016 -113.3094)
		(end 407.02738 -113.83518)
		(width 0.089408)
		(layer "In2.Cu")
		(net "FM_XRC_READY_N")
	)
	(segment
		(start 402.22932 -101.63048)
		(end 401.736306 -102.123494)
		(width 0.089408)
		(layer "In2.Cu")
		(net "FM_XRC_READY_N")
	)
	(segment
		(start 401.736052 -103.020368)
		(end 402.378164 -103.66248)
		(width 0.089408)
		(layer "In2.Cu")
		(net "FM_XRC_READY_N")
	)
	(segment
		(start 403.38756 -76.650342)
		(end 402.274024 -77.763878)
		(width 0.089408)
		(layer "In2.Cu")
		(net "FM_XRC_READY_N")
	)
	(segment
		(start 402.679408 -79.868014)
		(end 402.311362 -80.23606)
		(width 0.089408)
		(layer "In2.Cu")
		(net "FM_XRC_READY_N")
	)
	(segment
		(start 401.736306 -102.123494)
		(end 401.736306 -102.28199)
		(width 0.089408)
		(layer "In2.Cu")
		(net "FM_XRC_READY_N")
	)
	(segment
		(start 402.680424 -79.042768)
		(end 402.679408 -79.043784)
		(width 0.089408)
		(layer "In2.Cu")
		(net "FM_XRC_READY_N")
	)
	(segment
		(start 402.311362 -80.584802)
		(end 402.50237 -80.77581)
		(width 0.089408)
		(layer "In2.Cu")
		(net "FM_XRC_READY_N")
	)
	(segment
		(start 408.698954 -61.82741)
		(end 409.503372 -62.631828)
		(width 0.089408)
		(layer "In2.Cu")
		(net "FM_XRC_READY_N")
	)
	(segment
		(start 403.304756 -103.66248)
		(end 404.151338 -104.509062)
		(width 0.089408)
		(layer "In2.Cu")
		(net "FM_XRC_READY_N")
	)
	(segment
		(start 379.502924 -124.370846)
		(end 400.813524 -124.370846)
		(width 0.089408)
		(layer "In4.Cu")
		(net "FM_XRC_READY_N")
	)
	(segment
		(start 401.68957 -123.4948)
		(end 403.4282 -123.4948)
		(width 0.089408)
		(layer "In4.Cu")
		(net "FM_XRC_READY_N")
	)
	(segment
		(start 371.927374 -123.641104)
		(end 375.47169 -123.641104)
		(width 0.089408)
		(layer "In4.Cu")
		(net "FM_XRC_READY_N")
	)
	(segment
		(start 403.4282 -123.4948)
		(end 409.025344 -117.897656)
		(width 0.089408)
		(layer "In4.Cu")
		(net "FM_XRC_READY_N")
	)
	(segment
		(start 409.025344 -117.6147)
		(end 409.323286 -117.316758)
		(width 0.089408)
		(layer "In4.Cu")
		(net "FM_XRC_READY_N")
	)
	(segment
		(start 400.813524 -124.370846)
		(end 401.68957 -123.4948)
		(width 0.089408)
		(layer "In4.Cu")
		(net "FM_XRC_READY_N")
	)
	(segment
		(start 375.47169 -123.641104)
		(end 375.901712 -124.071126)
		(width 0.089408)
		(layer "In4.Cu")
		(net "FM_XRC_READY_N")
	)
	(segment
		(start 409.025344 -117.897656)
		(end 409.025344 -117.6147)
		(width 0.089408)
		(layer "In4.Cu")
		(net "FM_XRC_READY_N")
	)
	(segment
		(start 371.161818 -124.40666)
		(end 371.927374 -123.641104)
		(width 0.089408)
		(layer "In4.Cu")
		(net "FM_XRC_READY_N")
	)
	(segment
		(start 409.323286 -117.316758)
		(end 409.357068 -117.316758)
		(width 0.089408)
		(layer "In4.Cu")
		(net "FM_XRC_READY_N")
	)
	(segment
		(start 377.6472 -124.994924)
		(end 378.878846 -124.994924)
		(width 0.089408)
		(layer "In4.Cu")
		(net "FM_XRC_READY_N")
	)
	(segment
		(start 378.878846 -124.994924)
		(end 379.502924 -124.370846)
		(width 0.089408)
		(layer "In4.Cu")
		(net "FM_XRC_READY_N")
	)
	(segment
		(start 376.723402 -124.071126)
		(end 377.6472 -124.994924)
		(width 0.089408)
		(layer "In4.Cu")
		(net "FM_XRC_READY_N")
	)
	(segment
		(start 375.901712 -124.071126)
		(end 376.723402 -124.071126)
		(width 0.089408)
		(layer "In4.Cu")
		(net "FM_XRC_READY_N")
	)
	(segment
		(start 18.66138 -114.81689)
		(end 18.66138 -115.834922)
		(width 0.089408)
		(layer "In9.Cu")
		(net "FM_XRC_READY_N")
	)
	(segment
		(start 12.109704 -105.938828)
		(end 11.884406 -106.164126)
		(width 0.089408)
		(layer "In9.Cu")
		(net "FM_XRC_READY_N")
	)
	(segment
		(start 29.863796 -151.512016)
		(end 157.47111 -151.512016)
		(width 0.089408)
		(layer "In9.Cu")
		(net "FM_XRC_READY_N")
	)
	(segment
		(start 11.7094 -105.03408)
		(end 12.109704 -105.434384)
		(width 0.089408)
		(layer "In9.Cu")
		(net "FM_XRC_READY_N")
	)
	(segment
		(start 325.317358 -139.479782)
		(end 326.347074 -138.450066)
		(width 0.089408)
		(layer "In9.Cu")
		(net "FM_XRC_READY_N")
	)
	(segment
		(start 328.683366 -146.804634)
		(end 328.683366 -143.187166)
		(width 0.089408)
		(layer "In9.Cu")
		(net "FM_XRC_READY_N")
	)
	(segment
		(start 161.301938 -147.681188)
		(end 169.878248 -147.681188)
		(width 0.089408)
		(layer "In9.Cu")
		(net "FM_XRC_READY_N")
	)
	(segment
		(start 419.611048 -29.7434)
		(end 418.7063 -29.7434)
		(width 0.089408)
		(layer "In9.Cu")
		(net "FM_XRC_READY_N")
	)
	(segment
		(start 418.729414 -43.220132)
		(end 418.29863 -43.650916)
		(width 0.089408)
		(layer "In9.Cu")
		(net "FM_XRC_READY_N")
	)
	(segment
		(start 366.196118 -129.7686)
		(end 369.946936 -126.017782)
		(width 0.089408)
		(layer "In9.Cu")
		(net "FM_XRC_READY_N")
	)
	(segment
		(start 178.238912 -146.815048)
		(end 180.526944 -146.815048)
		(width 0.089408)
		(layer "In9.Cu")
		(net "FM_XRC_READY_N")
	)
	(segment
		(start 419.650164 -40.149272)
		(end 419.8874 -40.386508)
		(width 0.089408)
		(layer "In9.Cu")
		(net "FM_XRC_READY_N")
	)
	(segment
		(start 419.864794 -29.489654)
		(end 419.864794 -29.490162)
		(width 0.089408)
		(layer "In9.Cu")
		(net "FM_XRC_READY_N")
	)
	(segment
		(start 27.750008 -149.398228)
		(end 29.863796 -151.512016)
		(width 0.089408)
		(layer "In9.Cu")
		(net "FM_XRC_READY_N")
	)
	(segment
		(start 418.559742 -47.376842)
		(end 417.669472 -48.267112)
		(width 0.089408)
		(layer "In9.Cu")
		(net "FM_XRC_READY_N")
	)
	(segment
		(start 169.878248 -147.681188)
		(end 172.734732 -144.824704)
		(width 0.089408)
		(layer "In9.Cu")
		(net "FM_XRC_READY_N")
	)
	(segment
		(start 356.60584 -130.963162)
		(end 358.307386 -130.963162)
		(width 0.089408)
		(layer "In9.Cu")
		(net "FM_XRC_READY_N")
	)
	(segment
		(start 339.544406 -134.01675)
		(end 353.003358 -134.01675)
		(width 0.089408)
		(layer "In9.Cu")
		(net "FM_XRC_READY_N")
	)
	(segment
		(start 329.385422 -138.450066)
		(end 331.965554 -135.869934)
		(width 0.089408)
		(layer "In9.Cu")
		(net "FM_XRC_READY_N")
	)
	(segment
		(start 421.89019 -28.534614)
		(end 421.478456 -28.946348)
		(width 0.089408)
		(layer "In9.Cu")
		(net "FM_XRC_READY_N")
	)
	(segment
		(start 419.8874 -41.462198)
		(end 420.176706 -41.751504)
		(width 0.089408)
		(layer "In9.Cu")
		(net "FM_XRC_READY_N")
	)
	(segment
		(start 11.884406 -108.039916)
		(end 18.66138 -114.81689)
		(width 0.089408)
		(layer "In9.Cu")
		(net "FM_XRC_READY_N")
	)
	(segment
		(start 22.533864 -133.3246)
		(end 24.90089 -133.3246)
		(width 0.089408)
		(layer "In9.Cu")
		(net "FM_XRC_READY_N")
	)
	(segment
		(start 419.081458 -39.487348)
		(end 419.081458 -39.915846)
		(width 0.089408)
		(layer "In9.Cu")
		(net "FM_XRC_READY_N")
	)
	(segment
		(start 418.559742 -47.34306)
		(end 418.559742 -47.376842)
		(width 0.089408)
		(layer "In9.Cu")
		(net "FM_XRC_READY_N")
	)
	(segment
		(start 18.029682 -128.391666)
		(end 20.117816 -130.4798)
		(width 0.089408)
		(layer "In9.Cu")
		(net "FM_XRC_READY_N")
	)
	(segment
		(start 12.109704 -105.434384)
		(end 12.109704 -105.938828)
		(width 0.089408)
		(layer "In9.Cu")
		(net "FM_XRC_READY_N")
	)
	(segment
		(start 325.317358 -140.87475)
		(end 325.317358 -139.479782)
		(width 0.089408)
		(layer "In9.Cu")
		(net "FM_XRC_READY_N")
	)
	(segment
		(start 331.965554 -135.869934)
		(end 331.965554 -135.148574)
		(width 0.089408)
		(layer "In9.Cu")
		(net "FM_XRC_READY_N")
	)
	(segment
		(start 413.341312 -48.47082)
		(end 412.143194 -49.668938)
		(width 0.089408)
		(layer "In9.Cu")
		(net "FM_XRC_READY_N")
	)
	(segment
		(start 418.304218 -32.97428)
		(end 417.660582 -33.617916)
		(width 0.089408)
		(layer "In9.Cu")
		(net "FM_XRC_READY_N")
	)
	(segment
		(start 353.003358 -134.01675)
		(end 354.257102 -132.763006)
		(width 0.089408)
		(layer "In9.Cu")
		(net "FM_XRC_READY_N")
	)
	(segment
		(start 418.060378 -39.32428)
		(end 418.91839 -39.32428)
		(width 0.089408)
		(layer "In9.Cu")
		(net "FM_XRC_READY_N")
	)
	(segment
		(start 418.29863 -45.350176)
		(end 419.080696 -46.132242)
		(width 0.089408)
		(layer "In9.Cu")
		(net "FM_XRC_READY_N")
	)
	(segment
		(start 418.7063 -29.7434)
		(end 418.304218 -30.145482)
		(width 0.089408)
		(layer "In9.Cu")
		(net "FM_XRC_READY_N")
	)
	(segment
		(start 419.864794 -29.490162)
		(end 419.645592 -29.709364)
		(width 0.089408)
		(layer "In9.Cu")
		(net "FM_XRC_READY_N")
	)
	(segment
		(start 417.660582 -38.924484)
		(end 418.060378 -39.32428)
		(width 0.089408)
		(layer "In9.Cu")
		(net "FM_XRC_READY_N")
	)
	(segment
		(start 420.164514 -29.189934)
		(end 419.864794 -29.489654)
		(width 0.089408)
		(layer "In9.Cu")
		(net "FM_XRC_READY_N")
	)
	(segment
		(start 418.29863 -43.650916)
		(end 418.29863 -45.350176)
		(width 0.089408)
		(layer "In9.Cu")
		(net "FM_XRC_READY_N")
	)
	(segment
		(start 422.309798 -42.58183)
		(end 421.671496 -43.220132)
		(width 0.089408)
		(layer "In9.Cu")
		(net "FM_XRC_READY_N")
	)
	(segment
		(start 412.143194 -49.668938)
		(end 412.143194 -50.206402)
		(width 0.089408)
		(layer "In9.Cu")
		(net "FM_XRC_READY_N")
	)
	(segment
		(start 327.8886 -147.5994)
		(end 328.683366 -146.804634)
		(width 0.089408)
		(layer "In9.Cu")
		(net "FM_XRC_READY_N")
	)
	(segment
		(start 408.694382 -53.655214)
		(end 408.694382 -55.467504)
		(width 0.089408)
		(layer "In9.Cu")
		(net "FM_XRC_READY_N")
	)
	(segment
		(start 412.143194 -50.206402)
		(end 408.694382 -53.655214)
		(width 0.089408)
		(layer "In9.Cu")
		(net "FM_XRC_READY_N")
	)
	(segment
		(start 408.592274 -55.569612)
		(end 408.592274 -61.72073)
		(width 0.089408)
		(layer "In9.Cu")
		(net "FM_XRC_READY_N")
	)
	(segment
		(start 420.66972 -29.189934)
		(end 420.164514 -29.189934)
		(width 0.089408)
		(layer "In9.Cu")
		(net "FM_XRC_READY_N")
	)
	(segment
		(start 20.173188 -117.34673)
		(end 20.173188 -123.005596)
		(width 0.089408)
		(layer "In9.Cu")
		(net "FM_XRC_READY_N")
	)
	(segment
		(start 422.09085 -41.751504)
		(end 422.309798 -41.970452)
		(width 0.089408)
		(layer "In9.Cu")
		(net "FM_XRC_READY_N")
	)
	(segment
		(start 419.645592 -29.709364)
		(end 419.645084 -29.709364)
		(width 0.089408)
		(layer "In9.Cu")
		(net "FM_XRC_READY_N")
	)
	(segment
		(start 369.946936 -125.569218)
		(end 371.109494 -124.40666)
		(width 0.089408)
		(layer "In9.Cu")
		(net "FM_XRC_READY_N")
	)
	(segment
		(start 328.683366 -143.187166)
		(end 328.5744 -143.0782)
		(width 0.089408)
		(layer "In9.Cu")
		(net "FM_XRC_READY_N")
	)
	(segment
		(start 184.92343 -148.131784)
		(end 188.253116 -151.46147)
		(width 0.089408)
		(layer "In9.Cu")
		(net "FM_XRC_READY_N")
	)
	(segment
		(start 419.645084 -29.709364)
		(end 419.611048 -29.7434)
		(width 0.089408)
		(layer "In9.Cu")
		(net "FM_XRC_READY_N")
	)
	(segment
		(start 416.11804 -48.267112)
		(end 415.914332 -48.47082)
		(width 0.089408)
		(layer "In9.Cu")
		(net "FM_XRC_READY_N")
	)
	(segment
		(start 371.109494 -124.40666)
		(end 371.161818 -124.40666)
		(width 0.089408)
		(layer "In9.Cu")
		(net "FM_XRC_READY_N")
	)
	(segment
		(start 172.734732 -144.824704)
		(end 176.248568 -144.824704)
		(width 0.089408)
		(layer "In9.Cu")
		(net "FM_XRC_READY_N")
	)
	(segment
		(start 334.679036 -132.435092)
		(end 337.962748 -132.435092)
		(width 0.089408)
		(layer "In9.Cu")
		(net "FM_XRC_READY_N")
	)
	(segment
		(start 331.965554 -135.148574)
		(end 334.679036 -132.435092)
		(width 0.089408)
		(layer "In9.Cu")
		(net "FM_XRC_READY_N")
	)
	(segment
		(start 422.309798 -41.970452)
		(end 422.309798 -42.58183)
		(width 0.089408)
		(layer "In9.Cu")
		(net "FM_XRC_READY_N")
	)
	(segment
		(start 188.253116 -151.46147)
		(end 328.15403 -151.46147)
		(width 0.089408)
		(layer "In9.Cu")
		(net "FM_XRC_READY_N")
	)
	(segment
		(start 27.750008 -136.173718)
		(end 27.750008 -149.398228)
		(width 0.089408)
		(layer "In9.Cu")
		(net "FM_XRC_READY_N")
	)
	(segment
		(start 419.081458 -39.915846)
		(end 419.314884 -40.149272)
		(width 0.089408)
		(layer "In9.Cu")
		(net "FM_XRC_READY_N")
	)
	(segment
		(start 327.8886 -148.049234)
		(end 327.8886 -147.5994)
		(width 0.089408)
		(layer "In9.Cu")
		(net "FM_XRC_READY_N")
	)
	(segment
		(start 326.352408 -141.9098)
		(end 325.317358 -140.87475)
		(width 0.089408)
		(layer "In9.Cu")
		(net "FM_XRC_READY_N")
	)
	(segment
		(start 24.90089 -133.3246)
		(end 27.750008 -136.173718)
		(width 0.089408)
		(layer "In9.Cu")
		(net "FM_XRC_READY_N")
	)
	(segment
		(start 419.080696 -46.132242)
		(end 419.080696 -46.463966)
		(width 0.089408)
		(layer "In9.Cu")
		(net "FM_XRC_READY_N")
	)
	(segment
		(start 328.5744 -143.0782)
		(end 328.5744 -142.3162)
		(width 0.089408)
		(layer "In9.Cu")
		(net "FM_XRC_READY_N")
	)
	(segment
		(start 369.946936 -126.017782)
		(end 369.946936 -125.569218)
		(width 0.089408)
		(layer "In9.Cu")
		(net "FM_XRC_READY_N")
	)
	(segment
		(start 408.592274 -61.72073)
		(end 408.698954 -61.82741)
		(width 0.089408)
		(layer "In9.Cu")
		(net "FM_XRC_READY_N")
	)
	(segment
		(start 11.884406 -106.164126)
		(end 11.884406 -108.039916)
		(width 0.089408)
		(layer "In9.Cu")
		(net "FM_XRC_READY_N")
	)
	(segment
		(start 176.248568 -144.824704)
		(end 178.238912 -146.815048)
		(width 0.089408)
		(layer "In9.Cu")
		(net "FM_XRC_READY_N")
	)
	(segment
		(start 20.117816 -130.4798)
		(end 20.117816 -130.908552)
		(width 0.089408)
		(layer "In9.Cu")
		(net "FM_XRC_READY_N")
	)
	(segment
		(start 354.805996 -132.763006)
		(end 356.60584 -130.963162)
		(width 0.089408)
		(layer "In9.Cu")
		(net "FM_XRC_READY_N")
	)
	(segment
		(start 419.314884 -40.149272)
		(end 419.650164 -40.149272)
		(width 0.089408)
		(layer "In9.Cu")
		(net "FM_XRC_READY_N")
	)
	(segment
		(start 421.671496 -43.220132)
		(end 418.729414 -43.220132)
		(width 0.089408)
		(layer "In9.Cu")
		(net "FM_XRC_READY_N")
	)
	(segment
		(start 328.168 -141.9098)
		(end 326.352408 -141.9098)
		(width 0.089408)
		(layer "In9.Cu")
		(net "FM_XRC_READY_N")
	)
	(segment
		(start 326.347074 -138.450066)
		(end 329.385422 -138.450066)
		(width 0.089408)
		(layer "In9.Cu")
		(net "FM_XRC_READY_N")
	)
	(segment
		(start 418.73424 -46.810422)
		(end 418.73424 -47.002446)
		(width 0.089408)
		(layer "In9.Cu")
		(net "FM_XRC_READY_N")
	)
	(segment
		(start 408.694382 -55.467504)
		(end 408.592274 -55.569612)
		(width 0.089408)
		(layer "In9.Cu")
		(net "FM_XRC_READY_N")
	)
	(segment
		(start 359.501948 -129.7686)
		(end 366.196118 -129.7686)
		(width 0.089408)
		(layer "In9.Cu")
		(net "FM_XRC_READY_N")
	)
	(segment
		(start 415.914332 -48.47082)
		(end 413.341312 -48.47082)
		(width 0.089408)
		(layer "In9.Cu")
		(net "FM_XRC_READY_N")
	)
	(segment
		(start 418.304218 -30.145482)
		(end 418.304218 -32.97428)
		(width 0.089408)
		(layer "In9.Cu")
		(net "FM_XRC_READY_N")
	)
	(segment
		(start 18.66138 -115.834922)
		(end 20.173188 -117.34673)
		(width 0.089408)
		(layer "In9.Cu")
		(net "FM_XRC_READY_N")
	)
	(segment
		(start 354.257102 -132.763006)
		(end 354.805996 -132.763006)
		(width 0.089408)
		(layer "In9.Cu")
		(net "FM_XRC_READY_N")
	)
	(segment
		(start 420.913306 -28.946348)
		(end 420.66972 -29.189934)
		(width 0.089408)
		(layer "In9.Cu")
		(net "FM_XRC_READY_N")
	)
	(segment
		(start 18.029682 -125.149102)
		(end 18.029682 -128.391666)
		(width 0.089408)
		(layer "In9.Cu")
		(net "FM_XRC_READY_N")
	)
	(segment
		(start 421.478456 -28.946348)
		(end 420.913306 -28.946348)
		(width 0.089408)
		(layer "In9.Cu")
		(net "FM_XRC_READY_N")
	)
	(segment
		(start 328.15403 -151.46147)
		(end 328.683366 -150.932134)
		(width 0.089408)
		(layer "In9.Cu")
		(net "FM_XRC_READY_N")
	)
	(segment
		(start 419.080696 -46.463966)
		(end 418.73424 -46.810422)
		(width 0.089408)
		(layer "In9.Cu")
		(net "FM_XRC_READY_N")
	)
	(segment
		(start 418.91839 -39.32428)
		(end 419.081458 -39.487348)
		(width 0.089408)
		(layer "In9.Cu")
		(net "FM_XRC_READY_N")
	)
	(segment
		(start 328.683366 -150.932134)
		(end 328.683366 -148.844)
		(width 0.089408)
		(layer "In9.Cu")
		(net "FM_XRC_READY_N")
	)
	(segment
		(start 337.962748 -132.435092)
		(end 339.544406 -134.01675)
		(width 0.089408)
		(layer "In9.Cu")
		(net "FM_XRC_READY_N")
	)
	(segment
		(start 358.307386 -130.963162)
		(end 359.501948 -129.7686)
		(width 0.089408)
		(layer "In9.Cu")
		(net "FM_XRC_READY_N")
	)
	(segment
		(start 418.661596 -47.241206)
		(end 418.559742 -47.34306)
		(width 0.089408)
		(layer "In9.Cu")
		(net "FM_XRC_READY_N")
	)
	(segment
		(start 419.8874 -40.386508)
		(end 419.8874 -41.462198)
		(width 0.089408)
		(layer "In9.Cu")
		(net "FM_XRC_READY_N")
	)
	(segment
		(start 157.47111 -151.512016)
		(end 161.301938 -147.681188)
		(width 0.089408)
		(layer "In9.Cu")
		(net "FM_XRC_READY_N")
	)
	(segment
		(start 417.660582 -33.617916)
		(end 417.660582 -38.924484)
		(width 0.089408)
		(layer "In9.Cu")
		(net "FM_XRC_READY_N")
	)
	(segment
		(start 328.683366 -148.844)
		(end 327.8886 -148.049234)
		(width 0.089408)
		(layer "In9.Cu")
		(net "FM_XRC_READY_N")
	)
	(segment
		(start 418.73424 -47.002446)
		(end 418.661596 -47.07509)
		(width 0.089408)
		(layer "In9.Cu")
		(net "FM_XRC_READY_N")
	)
	(segment
		(start 20.117816 -130.908552)
		(end 22.533864 -133.3246)
		(width 0.089408)
		(layer "In9.Cu")
		(net "FM_XRC_READY_N")
	)
	(segment
		(start 181.84368 -148.131784)
		(end 184.92343 -148.131784)
		(width 0.089408)
		(layer "In9.Cu")
		(net "FM_XRC_READY_N")
	)
	(segment
		(start 420.176706 -41.751504)
		(end 422.09085 -41.751504)
		(width 0.089408)
		(layer "In9.Cu")
		(net "FM_XRC_READY_N")
	)
	(segment
		(start 180.526944 -146.815048)
		(end 181.84368 -148.131784)
		(width 0.089408)
		(layer "In9.Cu")
		(net "FM_XRC_READY_N")
	)
	(segment
		(start 20.173188 -123.005596)
		(end 18.029682 -125.149102)
		(width 0.089408)
		(layer "In9.Cu")
		(net "FM_XRC_READY_N")
	)
	(segment
		(start 328.5744 -142.3162)
		(end 328.168 -141.9098)
		(width 0.089408)
		(layer "In9.Cu")
		(net "FM_XRC_READY_N")
	)
	(segment
		(start 417.669472 -48.267112)
		(end 416.11804 -48.267112)
		(width 0.089408)
		(layer "In9.Cu")
		(net "FM_XRC_READY_N")
	)
	(segment
		(start 418.661596 -47.07509)
		(end 418.661596 -47.241206)
		(width 0.089408)
		(layer "In9.Cu")
		(net "FM_XRC_READY_N")
	)
	(segment
		(start 394.682472 -67.691)
		(end 393.8905 -67.691)
		(width 0.2794)
		(layer "F.Cu")
		(net "VR_P5V_STBY_PHASE")
	)
	(segment
		(start 395.281404 -68.191126)
		(end 394.695172 -68.191126)
		(width 0.3048)
		(layer "F.Cu")
		(net "VR_P5V_STBY_PHASE")
	)
	(segment
		(start 395.70152 -67.691)
		(end 394.682472 -67.691)
		(width 0.3048)
		(layer "F.Cu")
		(net "VR_P5V_STBY_PHASE")
	)
	(segment
		(start 396.256002 -68.245482)
		(end 395.70152 -67.691)
		(width 0.3048)
		(layer "F.Cu")
		(net "VR_P5V_STBY_PHASE")
	)
	(segment
		(start 395.721078 -68.6308)
		(end 395.281404 -68.191126)
		(width 0.3048)
		(layer "F.Cu")
		(net "VR_P5V_STBY_PHASE")
	)
	(segment
		(start 394.695172 -68.191126)
		(end 393.8905 -68.191126)
		(width 0.2794)
		(layer "F.Cu")
		(net "VR_P5V_STBY_PHASE")
	)
	(segment
		(start 462.915 -23.9903)
		(end 462.6229 -24.2824)
		(width 0.10795)
		(layer "F.Cu")
		(net "PWRGD_P5V_STBY")
	)
	(segment
		(start 393.2936 -72.5932)
		(end 393.192 -72.4916)
		(width 0.10795)
		(layer "F.Cu")
		(net "PWRGD_P5V_STBY")
	)
	(segment
		(start 393.242546 -72.60082)
		(end 393.2936 -72.60082)
		(width 0.10795)
		(layer "F.Cu")
		(net "PWRGD_P5V_STBY")
	)
	(segment
		(start 464.7057 -23.0759)
		(end 464.0961 -23.0759)
		(width 0.10795)
		(layer "F.Cu")
		(net "PWRGD_P5V_STBY")
	)
	(segment
		(start 463.8929 -23.2791)
		(end 463.3849 -23.2791)
		(width 0.10795)
		(layer "F.Cu")
		(net "PWRGD_P5V_STBY")
	)
	(segment
		(start 393.2936 -72.60082)
		(end 393.2936 -72.5932)
		(width 0.10795)
		(layer "F.Cu")
		(net "PWRGD_P5V_STBY")
	)
	(segment
		(start 464.0961 -23.0759)
		(end 463.8929 -23.2791)
		(width 0.10795)
		(layer "F.Cu")
		(net "PWRGD_P5V_STBY")
	)
	(segment
		(start 463.3849 -23.9903)
		(end 463.3849 -23.2791)
		(width 0.10795)
		(layer "F.Cu")
		(net "PWRGD_P5V_STBY")
	)
	(segment
		(start 462.6229 -24.2824)
		(end 462.6229 -24.96058)
		(width 0.10795)
		(layer "F.Cu")
		(net "PWRGD_P5V_STBY")
	)
	(segment
		(start 463.3849 -23.9903)
		(end 462.915 -23.9903)
		(width 0.10795)
		(layer "F.Cu")
		(net "PWRGD_P5V_STBY")
	)
	(segment
		(start 393.192 -72.4916)
		(end 393.192 -71.9455)
		(width 0.10795)
		(layer "F.Cu")
		(net "PWRGD_P5V_STBY")
	)
	(via
		(at 425.323 -58.042302)
		(size 0.6604)
		(drill 0.3302)
		(layers "F.Cu" "B.Cu")
		(net "PWRGD_P5V_STBY")
	)
	(via
		(at 433.239164 -50.30597)
		(size 0.508)
		(drill 0.254)
		(layers "F.Cu" "B.Cu")
		(net "PWRGD_P5V_STBY")
	)
	(via
		(at 393.242546 -72.60082)
		(size 0.508)
		(drill 0.254)
		(layers "F.Cu" "B.Cu")
		(net "PWRGD_P5V_STBY")
	)
	(via
		(at 436.64632 -59.144408)
		(size 0.508)
		(drill 0.254)
		(layers "F.Cu" "B.Cu")
		(net "PWRGD_P5V_STBY")
	)
	(via
		(at 462.6229 -24.96058)
		(size 0.508)
		(drill 0.254)
		(layers "F.Cu" "B.Cu")
		(net "PWRGD_P5V_STBY")
	)
	(segment
		(start 395.374114 -69.93255)
		(end 396.903448 -69.93255)
		(width 0.10795)
		(layer "B.Cu")
		(net "PWRGD_P5V_STBY")
	)
	(segment
		(start 400.929856 -66.724022)
		(end 400.929856 -66.23304)
		(width 0.10795)
		(layer "B.Cu")
		(net "PWRGD_P5V_STBY")
	)
	(segment
		(start 415.886646 -59.69889)
		(end 417.651438 -57.934098)
		(width 0.10795)
		(layer "B.Cu")
		(net "PWRGD_P5V_STBY")
	)
	(segment
		(start 402.779992 -62.869064)
		(end 404.534624 -62.869064)
		(width 0.10795)
		(layer "B.Cu")
		(net "PWRGD_P5V_STBY")
	)
	(segment
		(start 424.948604 -58.042302)
		(end 425.323 -58.042302)
		(width 0.10795)
		(layer "B.Cu")
		(net "PWRGD_P5V_STBY")
	)
	(segment
		(start 402.180552 -64.594486)
		(end 402.427948 -64.34709)
		(width 0.10795)
		(layer "B.Cu")
		(net "PWRGD_P5V_STBY")
	)
	(segment
		(start 424.8404 -57.934098)
		(end 424.948604 -58.042302)
		(width 0.10795)
		(layer "B.Cu")
		(net "PWRGD_P5V_STBY")
	)
	(segment
		(start 410.189426 -62.792864)
		(end 413.2834 -59.69889)
		(width 0.10795)
		(layer "B.Cu")
		(net "PWRGD_P5V_STBY")
	)
	(segment
		(start 402.427948 -63.221108)
		(end 402.779992 -62.869064)
		(width 0.10795)
		(layer "B.Cu")
		(net "PWRGD_P5V_STBY")
	)
	(segment
		(start 413.2834 -59.69889)
		(end 415.886646 -59.69889)
		(width 0.10795)
		(layer "B.Cu")
		(net "PWRGD_P5V_STBY")
	)
	(segment
		(start 436.64632 -58.067194)
		(end 436.659528 -58.053986)
		(width 0.10795)
		(layer "B.Cu")
		(net "PWRGD_P5V_STBY")
	)
	(segment
		(start 404.534624 -62.869064)
		(end 404.79472 -63.12916)
		(width 0.10795)
		(layer "B.Cu")
		(net "PWRGD_P5V_STBY")
	)
	(segment
		(start 397.36903 -69.466968)
		(end 398.18691 -69.466968)
		(width 0.10795)
		(layer "B.Cu")
		(net "PWRGD_P5V_STBY")
	)
	(segment
		(start 408.11577 -62.792864)
		(end 410.189426 -62.792864)
		(width 0.10795)
		(layer "B.Cu")
		(net "PWRGD_P5V_STBY")
	)
	(segment
		(start 393.242546 -72.60082)
		(end 393.242546 -72.064118)
		(width 0.10795)
		(layer "B.Cu")
		(net "PWRGD_P5V_STBY")
	)
	(segment
		(start 402.427948 -64.34709)
		(end 402.427948 -63.221108)
		(width 0.10795)
		(layer "B.Cu")
		(net "PWRGD_P5V_STBY")
	)
	(segment
		(start 401.345908 -65.816988)
		(end 401.345908 -65.04051)
		(width 0.10795)
		(layer "B.Cu")
		(net "PWRGD_P5V_STBY")
	)
	(segment
		(start 398.18691 -69.466968)
		(end 400.929856 -66.724022)
		(width 0.10795)
		(layer "B.Cu")
		(net "PWRGD_P5V_STBY")
	)
	(segment
		(start 429.703484 -54.790594)
		(end 426.451776 -58.042302)
		(width 0.10795)
		(layer "B.Cu")
		(net "PWRGD_P5V_STBY")
	)
	(segment
		(start 433.208684 -54.790594)
		(end 429.703484 -54.790594)
		(width 0.10795)
		(layer "B.Cu")
		(net "PWRGD_P5V_STBY")
	)
	(segment
		(start 404.79472 -63.12916)
		(end 407.779474 -63.12916)
		(width 0.10795)
		(layer "B.Cu")
		(net "PWRGD_P5V_STBY")
	)
	(segment
		(start 401.345908 -65.04051)
		(end 401.791932 -64.594486)
		(width 0.10795)
		(layer "B.Cu")
		(net "PWRGD_P5V_STBY")
	)
	(segment
		(start 426.451776 -58.042302)
		(end 425.323 -58.042302)
		(width 0.10795)
		(layer "B.Cu")
		(net "PWRGD_P5V_STBY")
	)
	(segment
		(start 436.659528 -58.053986)
		(end 433.395882 -54.79034)
		(width 0.10795)
		(layer "B.Cu")
		(net "PWRGD_P5V_STBY")
	)
	(segment
		(start 436.64632 -59.144408)
		(end 436.64632 -58.067194)
		(width 0.10795)
		(layer "B.Cu")
		(net "PWRGD_P5V_STBY")
	)
	(segment
		(start 417.651438 -57.934098)
		(end 424.8404 -57.934098)
		(width 0.10795)
		(layer "B.Cu")
		(net "PWRGD_P5V_STBY")
	)
	(segment
		(start 433.208938 -54.79034)
		(end 433.208684 -54.790594)
		(width 0.10795)
		(layer "B.Cu")
		(net "PWRGD_P5V_STBY")
	)
	(segment
		(start 400.929856 -66.23304)
		(end 401.345908 -65.816988)
		(width 0.10795)
		(layer "B.Cu")
		(net "PWRGD_P5V_STBY")
	)
	(segment
		(start 407.779474 -63.12916)
		(end 408.11577 -62.792864)
		(width 0.10795)
		(layer "B.Cu")
		(net "PWRGD_P5V_STBY")
	)
	(segment
		(start 401.791932 -64.594486)
		(end 402.180552 -64.594486)
		(width 0.10795)
		(layer "B.Cu")
		(net "PWRGD_P5V_STBY")
	)
	(segment
		(start 433.395882 -54.79034)
		(end 433.208938 -54.79034)
		(width 0.10795)
		(layer "B.Cu")
		(net "PWRGD_P5V_STBY")
	)
	(segment
		(start 393.242546 -72.064118)
		(end 395.374114 -69.93255)
		(width 0.10795)
		(layer "B.Cu")
		(net "PWRGD_P5V_STBY")
	)
	(segment
		(start 396.903448 -69.93255)
		(end 397.36903 -69.466968)
		(width 0.10795)
		(layer "B.Cu")
		(net "PWRGD_P5V_STBY")
	)
	(segment
		(start 452.780654 -44.069)
		(end 454.164192 -44.069)
		(width 0.089408)
		(layer "In9.Cu")
		(net "PWRGD_P5V_STBY")
	)
	(segment
		(start 462.35239 -34.023046)
		(end 462.35239 -32.381444)
		(width 0.089408)
		(layer "In9.Cu")
		(net "PWRGD_P5V_STBY")
	)
	(segment
		(start 435.247034 -48.631094)
		(end 435.403244 -48.787304)
		(width 0.089408)
		(layer "In9.Cu")
		(net "PWRGD_P5V_STBY")
	)
	(segment
		(start 460.849726 -31.37154)
		(end 460.6163 -31.138114)
		(width 0.089408)
		(layer "In9.Cu")
		(net "PWRGD_P5V_STBY")
	)
	(segment
		(start 462.6229 -28.0543)
		(end 462.6229 -24.96058)
		(width 0.089408)
		(layer "In9.Cu")
		(net "PWRGD_P5V_STBY")
	)
	(segment
		(start 456.268582 -43.065192)
		(end 457.068936 -42.264838)
		(width 0.089408)
		(layer "In9.Cu")
		(net "PWRGD_P5V_STBY")
	)
	(segment
		(start 460.6163 -31.138114)
		(end 460.6163 -30.63621)
		(width 0.089408)
		(layer "In9.Cu")
		(net "PWRGD_P5V_STBY")
	)
	(segment
		(start 455.168 -43.065192)
		(end 456.268582 -43.065192)
		(width 0.089408)
		(layer "In9.Cu")
		(net "PWRGD_P5V_STBY")
	)
	(segment
		(start 461.342486 -31.37154)
		(end 460.849726 -31.37154)
		(width 0.089408)
		(layer "In9.Cu")
		(net "PWRGD_P5V_STBY")
	)
	(segment
		(start 458.217778 -37.163756)
		(end 460.834994 -34.54654)
		(width 0.089408)
		(layer "In9.Cu")
		(net "PWRGD_P5V_STBY")
	)
	(segment
		(start 461.7212 -29.53131)
		(end 461.7212 -28.956)
		(width 0.089408)
		(layer "In9.Cu")
		(net "PWRGD_P5V_STBY")
	)
	(segment
		(start 436.95493 -48.787304)
		(end 438.944258 -46.797976)
		(width 0.089408)
		(layer "In9.Cu")
		(net "PWRGD_P5V_STBY")
	)
	(segment
		(start 438.944258 -46.797976)
		(end 450.065648 -46.797976)
		(width 0.089408)
		(layer "In9.Cu")
		(net "PWRGD_P5V_STBY")
	)
	(segment
		(start 461.828896 -34.54654)
		(end 462.35239 -34.023046)
		(width 0.089408)
		(layer "In9.Cu")
		(net "PWRGD_P5V_STBY")
	)
	(segment
		(start 460.6163 -30.63621)
		(end 461.7212 -29.53131)
		(width 0.089408)
		(layer "In9.Cu")
		(net "PWRGD_P5V_STBY")
	)
	(segment
		(start 434.416708 -48.631094)
		(end 434.7464 -48.631094)
		(width 0.089408)
		(layer "In9.Cu")
		(net "PWRGD_P5V_STBY")
	)
	(segment
		(start 434.747924 -48.63084)
		(end 435.24551 -48.63084)
		(width 0.089408)
		(layer "In9.Cu")
		(net "PWRGD_P5V_STBY")
	)
	(segment
		(start 450.065648 -46.797976)
		(end 450.7992 -46.064424)
		(width 0.089408)
		(layer "In9.Cu")
		(net "PWRGD_P5V_STBY")
	)
	(segment
		(start 450.7992 -44.9072)
		(end 451.450456 -44.255944)
		(width 0.089408)
		(layer "In9.Cu")
		(net "PWRGD_P5V_STBY")
	)
	(segment
		(start 457.068936 -42.264838)
		(end 457.068936 -40.6146)
		(width 0.089408)
		(layer "In9.Cu")
		(net "PWRGD_P5V_STBY")
	)
	(segment
		(start 435.24551 -48.63084)
		(end 435.247034 -48.631094)
		(width 0.089408)
		(layer "In9.Cu")
		(net "PWRGD_P5V_STBY")
	)
	(segment
		(start 462.35239 -32.381444)
		(end 461.342486 -31.37154)
		(width 0.089408)
		(layer "In9.Cu")
		(net "PWRGD_P5V_STBY")
	)
	(segment
		(start 458.217778 -39.465758)
		(end 458.217778 -37.163756)
		(width 0.089408)
		(layer "In9.Cu")
		(net "PWRGD_P5V_STBY")
	)
	(segment
		(start 454.164192 -44.069)
		(end 455.168 -43.065192)
		(width 0.089408)
		(layer "In9.Cu")
		(net "PWRGD_P5V_STBY")
	)
	(segment
		(start 461.7212 -28.956)
		(end 462.6229 -28.0543)
		(width 0.089408)
		(layer "In9.Cu")
		(net "PWRGD_P5V_STBY")
	)
	(segment
		(start 452.59371 -44.255944)
		(end 452.780654 -44.069)
		(width 0.089408)
		(layer "In9.Cu")
		(net "PWRGD_P5V_STBY")
	)
	(segment
		(start 434.7464 -48.631094)
		(end 434.747924 -48.63084)
		(width 0.089408)
		(layer "In9.Cu")
		(net "PWRGD_P5V_STBY")
	)
	(segment
		(start 433.239164 -50.30597)
		(end 433.239164 -49.808638)
		(width 0.089408)
		(layer "In9.Cu")
		(net "PWRGD_P5V_STBY")
	)
	(segment
		(start 435.403244 -48.787304)
		(end 436.95493 -48.787304)
		(width 0.089408)
		(layer "In9.Cu")
		(net "PWRGD_P5V_STBY")
	)
	(segment
		(start 433.239164 -49.808638)
		(end 434.416708 -48.631094)
		(width 0.089408)
		(layer "In9.Cu")
		(net "PWRGD_P5V_STBY")
	)
	(segment
		(start 451.450456 -44.255944)
		(end 452.59371 -44.255944)
		(width 0.089408)
		(layer "In9.Cu")
		(net "PWRGD_P5V_STBY")
	)
	(segment
		(start 460.834994 -34.54654)
		(end 461.828896 -34.54654)
		(width 0.089408)
		(layer "In9.Cu")
		(net "PWRGD_P5V_STBY")
	)
	(segment
		(start 450.7992 -46.064424)
		(end 450.7992 -44.9072)
		(width 0.089408)
		(layer "In9.Cu")
		(net "PWRGD_P5V_STBY")
	)
	(segment
		(start 457.068936 -40.6146)
		(end 458.217778 -39.465758)
		(width 0.089408)
		(layer "In9.Cu")
		(net "PWRGD_P5V_STBY")
	)
	(segment
		(start 436.64632 -59.144408)
		(end 436.64632 -57.29732)
		(width 0.089408)
		(layer "In11.Cu")
		(net "PWRGD_P5V_STBY")
	)
	(segment
		(start 436.64632 -57.29732)
		(end 433.239164 -53.890164)
		(width 0.089408)
		(layer "In11.Cu")
		(net "PWRGD_P5V_STBY")
	)
	(segment
		(start 433.239164 -53.890164)
		(end 433.239164 -50.30597)
		(width 0.089408)
		(layer "In11.Cu")
		(net "PWRGD_P5V_STBY")
	)
	(segment
		(start 462.114392 -36.109148)
		(end 462.114392 -37.067998)
		(width 0.10795)
		(layer "F.Cu")
		(net "PWRGD_P1V15_BMC_STBY")
	)
	(segment
		(start 464.185 -36.8046)
		(end 464.185 -36.06292)
		(width 0.10795)
		(layer "F.Cu")
		(net "PWRGD_P1V15_BMC_STBY")
	)
	(segment
		(start 463.87258 -35.7505)
		(end 462.47304 -35.7505)
		(width 0.10795)
		(layer "F.Cu")
		(net "PWRGD_P1V15_BMC_STBY")
	)
	(segment
		(start 374.344692 -71.095108)
		(end 373.944896 -71.494904)
		(width 0.10795)
		(layer "F.Cu")
		(net "PWRGD_P1V15_BMC_STBY")
	)
	(segment
		(start 464.185 -36.06292)
		(end 463.87258 -35.7505)
		(width 0.10795)
		(layer "F.Cu")
		(net "PWRGD_P1V15_BMC_STBY")
	)
	(segment
		(start 462.47304 -35.7505)
		(end 462.114392 -36.109148)
		(width 0.10795)
		(layer "F.Cu")
		(net "PWRGD_P1V15_BMC_STBY")
	)
	(via
		(at 429.40351 -63.767208)
		(size 0.508)
		(drill 0.254)
		(layers "F.Cu" "B.Cu")
		(net "PWRGD_P1V15_BMC_STBY")
	)
	(via
		(at 374.344692 -71.095108)
		(size 0.4572)
		(drill 0.2032)
		(layers "F.Cu" "B.Cu")
		(net "PWRGD_P1V15_BMC_STBY")
	)
	(via
		(at 379.906784 -65.623694)
		(size 0.508)
		(drill 0.254)
		(layers "F.Cu" "B.Cu")
		(net "PWRGD_P1V15_BMC_STBY")
	)
	(via
		(at 438.885584 -62.52845)
		(size 0.508)
		(drill 0.254)
		(layers "F.Cu" "B.Cu")
		(net "PWRGD_P1V15_BMC_STBY")
	)
	(via
		(at 464.185 -36.8046)
		(size 0.508)
		(drill 0.254)
		(layers "F.Cu" "B.Cu")
		(net "PWRGD_P1V15_BMC_STBY")
	)
	(segment
		(start 435.087014 -62.315598)
		(end 435.087014 -63.138304)
		(width 0.10795)
		(layer "B.Cu")
		(net "PWRGD_P1V15_BMC_STBY")
	)
	(segment
		(start 381.0889 -66.513202)
		(end 380.199392 -65.623694)
		(width 0.10795)
		(layer "B.Cu")
		(net "PWRGD_P1V15_BMC_STBY")
	)
	(segment
		(start 375.527824 -71.736458)
		(end 375.527824 -72.819514)
		(width 0.10795)
		(layer "B.Cu")
		(net "PWRGD_P1V15_BMC_STBY")
	)
	(segment
		(start 377.961906 -71.267828)
		(end 377.961906 -70.936612)
		(width 0.10795)
		(layer "B.Cu")
		(net "PWRGD_P1V15_BMC_STBY")
	)
	(segment
		(start 379.73 -69.342254)
		(end 381.0889 -67.983354)
		(width 0.10795)
		(layer "B.Cu")
		(net "PWRGD_P1V15_BMC_STBY")
	)
	(segment
		(start 433.974494 -64.250824)
		(end 429.887126 -64.250824)
		(width 0.10795)
		(layer "B.Cu")
		(net "PWRGD_P1V15_BMC_STBY")
	)
	(segment
		(start 378.231908 -72.157336)
		(end 378.231908 -71.53783)
		(width 0.10795)
		(layer "B.Cu")
		(net "PWRGD_P1V15_BMC_STBY")
	)
	(segment
		(start 380.199392 -65.623694)
		(end 379.906784 -65.623694)
		(width 0.10795)
		(layer "B.Cu")
		(net "PWRGD_P1V15_BMC_STBY")
	)
	(segment
		(start 374.72747 -71.477886)
		(end 375.269252 -71.477886)
		(width 0.10795)
		(layer "B.Cu")
		(net "PWRGD_P1V15_BMC_STBY")
	)
	(segment
		(start 377.927616 -72.865996)
		(end 377.927616 -72.461628)
		(width 0.10795)
		(layer "B.Cu")
		(net "PWRGD_P1V15_BMC_STBY")
	)
	(segment
		(start 435.087014 -63.138304)
		(end 433.974494 -64.250824)
		(width 0.10795)
		(layer "B.Cu")
		(net "PWRGD_P1V15_BMC_STBY")
	)
	(segment
		(start 377.715526 -73.078086)
		(end 377.927616 -72.865996)
		(width 0.10795)
		(layer "B.Cu")
		(net "PWRGD_P1V15_BMC_STBY")
	)
	(segment
		(start 381.0889 -67.983354)
		(end 381.0889 -66.513202)
		(width 0.10795)
		(layer "B.Cu")
		(net "PWRGD_P1V15_BMC_STBY")
	)
	(segment
		(start 438.885584 -62.52845)
		(end 438.199276 -61.842142)
		(width 0.10795)
		(layer "B.Cu")
		(net "PWRGD_P1V15_BMC_STBY")
	)
	(segment
		(start 375.269252 -71.477886)
		(end 375.527824 -71.736458)
		(width 0.10795)
		(layer "B.Cu")
		(net "PWRGD_P1V15_BMC_STBY")
	)
	(segment
		(start 429.887126 -64.250824)
		(end 429.40351 -63.767208)
		(width 0.10795)
		(layer "B.Cu")
		(net "PWRGD_P1V15_BMC_STBY")
	)
	(segment
		(start 374.344692 -71.095108)
		(end 374.72747 -71.477886)
		(width 0.10795)
		(layer "B.Cu")
		(net "PWRGD_P1V15_BMC_STBY")
	)
	(segment
		(start 375.527824 -72.819514)
		(end 375.786396 -73.078086)
		(width 0.10795)
		(layer "B.Cu")
		(net "PWRGD_P1V15_BMC_STBY")
	)
	(segment
		(start 377.927616 -72.461628)
		(end 378.231908 -72.157336)
		(width 0.10795)
		(layer "B.Cu")
		(net "PWRGD_P1V15_BMC_STBY")
	)
	(segment
		(start 379.73 -69.885814)
		(end 379.73 -69.342254)
		(width 0.10795)
		(layer "B.Cu")
		(net "PWRGD_P1V15_BMC_STBY")
	)
	(segment
		(start 378.231908 -71.53783)
		(end 377.961906 -71.267828)
		(width 0.10795)
		(layer "B.Cu")
		(net "PWRGD_P1V15_BMC_STBY")
	)
	(segment
		(start 435.56047 -61.842142)
		(end 435.087014 -62.315598)
		(width 0.10795)
		(layer "B.Cu")
		(net "PWRGD_P1V15_BMC_STBY")
	)
	(segment
		(start 378.903484 -70.71233)
		(end 379.73 -69.885814)
		(width 0.10795)
		(layer "B.Cu")
		(net "PWRGD_P1V15_BMC_STBY")
	)
	(segment
		(start 378.186188 -70.71233)
		(end 378.903484 -70.71233)
		(width 0.10795)
		(layer "B.Cu")
		(net "PWRGD_P1V15_BMC_STBY")
	)
	(segment
		(start 375.786396 -73.078086)
		(end 377.715526 -73.078086)
		(width 0.10795)
		(layer "B.Cu")
		(net "PWRGD_P1V15_BMC_STBY")
	)
	(segment
		(start 438.199276 -61.842142)
		(end 435.56047 -61.842142)
		(width 0.10795)
		(layer "B.Cu")
		(net "PWRGD_P1V15_BMC_STBY")
	)
	(segment
		(start 377.961906 -70.936612)
		(end 378.186188 -70.71233)
		(width 0.10795)
		(layer "B.Cu")
		(net "PWRGD_P1V15_BMC_STBY")
	)
	(segment
		(start 468.046562 -40.556434)
		(end 468.046562 -40.314118)
		(width 0.089408)
		(layer "In4.Cu")
		(net "PWRGD_P1V15_BMC_STBY")
	)
	(segment
		(start 394.212318 -64.421512)
		(end 396.080488 -64.421512)
		(width 0.089408)
		(layer "In4.Cu")
		(net "PWRGD_P1V15_BMC_STBY")
	)
	(segment
		(start 471.615008 -43.309794)
		(end 471.615008 -42.2148)
		(width 0.089408)
		(layer "In4.Cu")
		(net "PWRGD_P1V15_BMC_STBY")
	)
	(segment
		(start 473.899484 -53.980588)
		(end 473.899484 -53.96738)
		(width 0.089408)
		(layer "In4.Cu")
		(net "PWRGD_P1V15_BMC_STBY")
	)
	(segment
		(start 407.067766 -65.723262)
		(end 407.48204 -66.137536)
		(width 0.089408)
		(layer "In4.Cu")
		(net "PWRGD_P1V15_BMC_STBY")
	)
	(segment
		(start 399.614136 -64.376808)
		(end 400.619976 -65.382648)
		(width 0.089408)
		(layer "In4.Cu")
		(net "PWRGD_P1V15_BMC_STBY")
	)
	(segment
		(start 466.791294 -38.452552)
		(end 466.786722 -38.457124)
		(width 0.089408)
		(layer "In4.Cu")
		(net "PWRGD_P1V15_BMC_STBY")
	)
	(segment
		(start 469.039702 -41.30675)
		(end 469.039448 -41.307004)
		(width 0.089408)
		(layer "In4.Cu")
		(net "PWRGD_P1V15_BMC_STBY")
	)
	(segment
		(start 428.06747 -62.025784)
		(end 429.40351 -63.361824)
		(width 0.089408)
		(layer "In4.Cu")
		(net "PWRGD_P1V15_BMC_STBY")
	)
	(segment
		(start 473.906088 -53.960776)
		(end 473.906088 -53.58892)
		(width 0.089408)
		(layer "In4.Cu")
		(net "PWRGD_P1V15_BMC_STBY")
	)
	(segment
		(start 474.14942 -45.40758)
		(end 472.993212 -44.251372)
		(width 0.089408)
		(layer "In4.Cu")
		(net "PWRGD_P1V15_BMC_STBY")
	)
	(segment
		(start 413.893 -65.659)
		(end 415.5694 -63.9826)
		(width 0.089408)
		(layer "In4.Cu")
		(net "PWRGD_P1V15_BMC_STBY")
	)
	(segment
		(start 473.907866 -53.575458)
		(end 473.109544 -52.777136)
		(width 0.089408)
		(layer "In4.Cu")
		(net "PWRGD_P1V15_BMC_STBY")
	)
	(segment
		(start 473.665042 -54.21503)
		(end 473.899484 -53.980588)
		(width 0.089408)
		(layer "In4.Cu")
		(net "PWRGD_P1V15_BMC_STBY")
	)
	(segment
		(start 466.875114 -38.440614)
		(end 466.875114 -38.452552)
		(width 0.089408)
		(layer "In4.Cu")
		(net "PWRGD_P1V15_BMC_STBY")
	)
	(segment
		(start 473.010738 -54.856126)
		(end 473.651834 -54.21503)
		(width 0.089408)
		(layer "In4.Cu")
		(net "PWRGD_P1V15_BMC_STBY")
	)
	(segment
		(start 464.2739 -54.821582)
		(end 465.370672 -53.72481)
		(width 0.089408)
		(layer "In4.Cu")
		(net "PWRGD_P1V15_BMC_STBY")
	)
	(segment
		(start 471.615008 -42.2148)
		(end 470.706958 -41.30675)
		(width 0.089408)
		(layer "In4.Cu")
		(net "PWRGD_P1V15_BMC_STBY")
	)
	(segment
		(start 429.40351 -63.361824)
		(end 429.40351 -63.767208)
		(width 0.089408)
		(layer "In4.Cu")
		(net "PWRGD_P1V15_BMC_STBY")
	)
	(segment
		(start 398.046702 -64.542924)
		(end 398.827498 -64.542924)
		(width 0.089408)
		(layer "In4.Cu")
		(net "PWRGD_P1V15_BMC_STBY")
	)
	(segment
		(start 457.455016 -61.878718)
		(end 462.79181 -61.878718)
		(width 0.089408)
		(layer "In4.Cu")
		(net "PWRGD_P1V15_BMC_STBY")
	)
	(segment
		(start 466.24621 -53.72481)
		(end 467.377526 -54.856126)
		(width 0.089408)
		(layer "In4.Cu")
		(net "PWRGD_P1V15_BMC_STBY")
	)
	(segment
		(start 466.875114 -38.452552)
		(end 466.791294 -38.452552)
		(width 0.089408)
		(layer "In4.Cu")
		(net "PWRGD_P1V15_BMC_STBY")
	)
	(segment
		(start 426.492162 -61.15558)
		(end 427.928532 -61.15558)
		(width 0.089408)
		(layer "In4.Cu")
		(net "PWRGD_P1V15_BMC_STBY")
	)
	(segment
		(start 393.419838 -64.421512)
		(end 393.420092 -64.421766)
		(width 0.089408)
		(layer "In4.Cu")
		(net "PWRGD_P1V15_BMC_STBY")
	)
	(segment
		(start 421.965374 -60.873386)
		(end 426.209968 -60.873386)
		(width 0.089408)
		(layer "In4.Cu")
		(net "PWRGD_P1V15_BMC_STBY")
	)
	(segment
		(start 472.799156 -44.251626)
		(end 472.55684 -44.251626)
		(width 0.089408)
		(layer "In4.Cu")
		(net "PWRGD_P1V15_BMC_STBY")
	)
	(segment
		(start 418.096954 -63.9826)
		(end 421.02913 -61.050424)
		(width 0.089408)
		(layer "In4.Cu")
		(net "PWRGD_P1V15_BMC_STBY")
	)
	(segment
		(start 473.89161 -50.828956)
		(end 474.14942 -50.571146)
		(width 0.089408)
		(layer "In4.Cu")
		(net "PWRGD_P1V15_BMC_STBY")
	)
	(segment
		(start 426.209968 -60.873386)
		(end 426.492162 -61.15558)
		(width 0.089408)
		(layer "In4.Cu")
		(net "PWRGD_P1V15_BMC_STBY")
	)
	(segment
		(start 393.57808 -64.421766)
		(end 393.578334 -64.42202)
		(width 0.089408)
		(layer "In4.Cu")
		(net "PWRGD_P1V15_BMC_STBY")
	)
	(segment
		(start 472.55684 -44.251626)
		(end 471.615008 -43.309794)
		(width 0.089408)
		(layer "In4.Cu")
		(net "PWRGD_P1V15_BMC_STBY")
	)
	(segment
		(start 380.400814 -65.623694)
		(end 381.32512 -66.548)
		(width 0.089408)
		(layer "In4.Cu")
		(net "PWRGD_P1V15_BMC_STBY")
	)
	(segment
		(start 415.5694 -63.9826)
		(end 418.096954 -63.9826)
		(width 0.089408)
		(layer "In4.Cu")
		(net "PWRGD_P1V15_BMC_STBY")
	)
	(segment
		(start 398.993614 -64.376808)
		(end 399.614136 -64.376808)
		(width 0.089408)
		(layer "In4.Cu")
		(net "PWRGD_P1V15_BMC_STBY")
	)
	(segment
		(start 463.571844 -59.142376)
		(end 463.571844 -58.810652)
		(width 0.089408)
		(layer "In4.Cu")
		(net "PWRGD_P1V15_BMC_STBY")
	)
	(segment
		(start 389.883396 -64.421512)
		(end 393.419838 -64.421512)
		(width 0.089408)
		(layer "In4.Cu")
		(net "PWRGD_P1V15_BMC_STBY")
	)
	(segment
		(start 396.34922 -64.15278)
		(end 397.656558 -64.15278)
		(width 0.089408)
		(layer "In4.Cu")
		(net "PWRGD_P1V15_BMC_STBY")
	)
	(segment
		(start 474.14942 -50.571146)
		(end 474.14942 -45.40758)
		(width 0.089408)
		(layer "In4.Cu")
		(net "PWRGD_P1V15_BMC_STBY")
	)
	(segment
		(start 394.21181 -64.42202)
		(end 394.212318 -64.421512)
		(width 0.089408)
		(layer "In4.Cu")
		(net "PWRGD_P1V15_BMC_STBY")
	)
	(segment
		(start 389.622792 -64.682116)
		(end 389.883396 -64.421512)
		(width 0.089408)
		(layer "In4.Cu")
		(net "PWRGD_P1V15_BMC_STBY")
	)
	(segment
		(start 473.109544 -50.918364)
		(end 473.198952 -50.828956)
		(width 0.089408)
		(layer "In4.Cu")
		(net "PWRGD_P1V15_BMC_STBY")
	)
	(segment
		(start 406.215596 -65.777872)
		(end 406.270206 -65.723262)
		(width 0.089408)
		(layer "In4.Cu")
		(net "PWRGD_P1V15_BMC_STBY")
	)
	(segment
		(start 468.036656 -38.75151)
		(end 467.491318 -38.206172)
		(width 0.089408)
		(layer "In4.Cu")
		(net "PWRGD_P1V15_BMC_STBY")
	)
	(segment
		(start 393.578334 -64.42202)
		(end 394.21181 -64.42202)
		(width 0.089408)
		(layer "In4.Cu")
		(net "PWRGD_P1V15_BMC_STBY")
	)
	(segment
		(start 381.32512 -66.548)
		(end 385.2164 -66.548)
		(width 0.089408)
		(layer "In4.Cu")
		(net "PWRGD_P1V15_BMC_STBY")
	)
	(segment
		(start 470.706958 -41.30675)
		(end 469.039702 -41.30675)
		(width 0.089408)
		(layer "In4.Cu")
		(net "PWRGD_P1V15_BMC_STBY")
	)
	(segment
		(start 465.370672 -53.72481)
		(end 466.24621 -53.72481)
		(width 0.089408)
		(layer "In4.Cu")
		(net "PWRGD_P1V15_BMC_STBY")
	)
	(segment
		(start 466.450426 -38.452552)
		(end 465.766912 -38.452552)
		(width 0.089408)
		(layer "In4.Cu")
		(net "PWRGD_P1V15_BMC_STBY")
	)
	(segment
		(start 396.080488 -64.421512)
		(end 396.34922 -64.15278)
		(width 0.089408)
		(layer "In4.Cu")
		(net "PWRGD_P1V15_BMC_STBY")
	)
	(segment
		(start 456.979274 -62.35446)
		(end 457.455016 -61.878718)
		(width 0.089408)
		(layer "In4.Cu")
		(net "PWRGD_P1V15_BMC_STBY")
	)
	(segment
		(start 439.059574 -62.35446)
		(end 456.979274 -62.35446)
		(width 0.089408)
		(layer "In4.Cu")
		(net "PWRGD_P1V15_BMC_STBY")
	)
	(segment
		(start 465.766912 -38.452552)
		(end 464.185 -36.87064)
		(width 0.089408)
		(layer "In4.Cu")
		(net "PWRGD_P1V15_BMC_STBY")
	)
	(segment
		(start 473.651834 -54.21503)
		(end 473.665042 -54.21503)
		(width 0.089408)
		(layer "In4.Cu")
		(net "PWRGD_P1V15_BMC_STBY")
	)
	(segment
		(start 406.270206 -65.723262)
		(end 407.067766 -65.723262)
		(width 0.089408)
		(layer "In4.Cu")
		(net "PWRGD_P1V15_BMC_STBY")
	)
	(segment
		(start 468.797132 -41.307004)
		(end 468.046562 -40.556434)
		(width 0.089408)
		(layer "In4.Cu")
		(net "PWRGD_P1V15_BMC_STBY")
	)
	(segment
		(start 469.039448 -41.307004)
		(end 468.797132 -41.307004)
		(width 0.089408)
		(layer "In4.Cu")
		(net "PWRGD_P1V15_BMC_STBY")
	)
	(segment
		(start 404.922736 -66.739008)
		(end 405.883872 -65.777872)
		(width 0.089408)
		(layer "In4.Cu")
		(net "PWRGD_P1V15_BMC_STBY")
	)
	(segment
		(start 401.800822 -66.739262)
		(end 401.95881 -66.739262)
		(width 0.089408)
		(layer "In4.Cu")
		(net "PWRGD_P1V15_BMC_STBY")
	)
	(segment
		(start 466.786722 -38.457124)
		(end 466.454998 -38.457124)
		(width 0.089408)
		(layer "In4.Cu")
		(net "PWRGD_P1V15_BMC_STBY")
	)
	(segment
		(start 464.274154 -59.835034)
		(end 463.815938 -59.376818)
		(width 0.089408)
		(layer "In4.Cu")
		(net "PWRGD_P1V15_BMC_STBY")
	)
	(segment
		(start 463.806286 -59.376818)
		(end 463.571844 -59.142376)
		(width 0.089408)
		(layer "In4.Cu")
		(net "PWRGD_P1V15_BMC_STBY")
	)
	(segment
		(start 467.377526 -54.856126)
		(end 473.010738 -54.856126)
		(width 0.089408)
		(layer "In4.Cu")
		(net "PWRGD_P1V15_BMC_STBY")
	)
	(segment
		(start 464.185 -36.87064)
		(end 464.185 -36.8046)
		(width 0.089408)
		(layer "In4.Cu")
		(net "PWRGD_P1V15_BMC_STBY")
	)
	(segment
		(start 393.420092 -64.421766)
		(end 393.57808 -64.421766)
		(width 0.089408)
		(layer "In4.Cu")
		(net "PWRGD_P1V15_BMC_STBY")
	)
	(segment
		(start 421.02913 -61.050424)
		(end 421.788336 -61.050424)
		(width 0.089408)
		(layer "In4.Cu")
		(net "PWRGD_P1V15_BMC_STBY")
	)
	(segment
		(start 379.906784 -65.623694)
		(end 380.400814 -65.623694)
		(width 0.089408)
		(layer "In4.Cu")
		(net "PWRGD_P1V15_BMC_STBY")
	)
	(segment
		(start 438.885584 -62.52845)
		(end 439.059574 -62.35446)
		(width 0.089408)
		(layer "In4.Cu")
		(net "PWRGD_P1V15_BMC_STBY")
	)
	(segment
		(start 413.029654 -65.659)
		(end 413.893 -65.659)
		(width 0.089408)
		(layer "In4.Cu")
		(net "PWRGD_P1V15_BMC_STBY")
	)
	(segment
		(start 467.109556 -38.206172)
		(end 466.875114 -38.440614)
		(width 0.089408)
		(layer "In4.Cu")
		(net "PWRGD_P1V15_BMC_STBY")
	)
	(segment
		(start 397.656558 -64.15278)
		(end 398.046702 -64.542924)
		(width 0.089408)
		(layer "In4.Cu")
		(net "PWRGD_P1V15_BMC_STBY")
	)
	(segment
		(start 463.571844 -58.810652)
		(end 464.2739 -58.108596)
		(width 0.089408)
		(layer "In4.Cu")
		(net "PWRGD_P1V15_BMC_STBY")
	)
	(segment
		(start 468.046816 -40.313864)
		(end 468.046816 -40.298116)
		(width 0.089408)
		(layer "In4.Cu")
		(net "PWRGD_P1V15_BMC_STBY")
	)
	(segment
		(start 472.79941 -44.251372)
		(end 472.799156 -44.251626)
		(width 0.089408)
		(layer "In4.Cu")
		(net "PWRGD_P1V15_BMC_STBY")
	)
	(segment
		(start 462.79181 -61.878718)
		(end 464.274154 -60.396374)
		(width 0.089408)
		(layer "In4.Cu")
		(net "PWRGD_P1V15_BMC_STBY")
	)
	(segment
		(start 400.619976 -65.558416)
		(end 401.800822 -66.739262)
		(width 0.089408)
		(layer "In4.Cu")
		(net "PWRGD_P1V15_BMC_STBY")
	)
	(segment
		(start 412.551118 -66.137536)
		(end 413.029654 -65.659)
		(width 0.089408)
		(layer "In4.Cu")
		(net "PWRGD_P1V15_BMC_STBY")
	)
	(segment
		(start 405.883872 -65.777872)
		(end 406.215596 -65.777872)
		(width 0.089408)
		(layer "In4.Cu")
		(net "PWRGD_P1V15_BMC_STBY")
	)
	(segment
		(start 466.454998 -38.457124)
		(end 466.450426 -38.452552)
		(width 0.089408)
		(layer "In4.Cu")
		(net "PWRGD_P1V15_BMC_STBY")
	)
	(segment
		(start 472.993212 -44.251372)
		(end 472.79941 -44.251372)
		(width 0.089408)
		(layer "In4.Cu")
		(net "PWRGD_P1V15_BMC_STBY")
	)
	(segment
		(start 387.082284 -64.682116)
		(end 389.622792 -64.682116)
		(width 0.089408)
		(layer "In4.Cu")
		(net "PWRGD_P1V15_BMC_STBY")
	)
	(segment
		(start 401.95881 -66.739262)
		(end 401.959064 -66.739008)
		(width 0.089408)
		(layer "In4.Cu")
		(net "PWRGD_P1V15_BMC_STBY")
	)
	(segment
		(start 467.491318 -38.206172)
		(end 467.109556 -38.206172)
		(width 0.089408)
		(layer "In4.Cu")
		(net "PWRGD_P1V15_BMC_STBY")
	)
	(segment
		(start 421.788336 -61.050424)
		(end 421.965374 -60.873386)
		(width 0.089408)
		(layer "In4.Cu")
		(net "PWRGD_P1V15_BMC_STBY")
	)
	(segment
		(start 407.48204 -66.137536)
		(end 412.551118 -66.137536)
		(width 0.089408)
		(layer "In4.Cu")
		(net "PWRGD_P1V15_BMC_STBY")
	)
	(segment
		(start 401.959064 -66.739008)
		(end 404.922736 -66.739008)
		(width 0.089408)
		(layer "In4.Cu")
		(net "PWRGD_P1V15_BMC_STBY")
	)
	(segment
		(start 473.899484 -53.96738)
		(end 473.906088 -53.960776)
		(width 0.089408)
		(layer "In4.Cu")
		(net "PWRGD_P1V15_BMC_STBY")
	)
	(segment
		(start 464.2739 -58.108596)
		(end 464.2739 -54.821582)
		(width 0.089408)
		(layer "In4.Cu")
		(net "PWRGD_P1V15_BMC_STBY")
	)
	(segment
		(start 463.815938 -59.376818)
		(end 463.806286 -59.376818)
		(width 0.089408)
		(layer "In4.Cu")
		(net "PWRGD_P1V15_BMC_STBY")
	)
	(segment
		(start 473.109544 -52.777136)
		(end 473.109544 -50.918364)
		(width 0.089408)
		(layer "In4.Cu")
		(net "PWRGD_P1V15_BMC_STBY")
	)
	(segment
		(start 400.619976 -65.382648)
		(end 400.619976 -65.558416)
		(width 0.089408)
		(layer "In4.Cu")
		(net "PWRGD_P1V15_BMC_STBY")
	)
	(segment
		(start 468.036656 -40.287956)
		(end 468.036656 -38.75151)
		(width 0.089408)
		(layer "In4.Cu")
		(net "PWRGD_P1V15_BMC_STBY")
	)
	(segment
		(start 473.906088 -53.58892)
		(end 473.907866 -53.587142)
		(width 0.089408)
		(layer "In4.Cu")
		(net "PWRGD_P1V15_BMC_STBY")
	)
	(segment
		(start 473.907866 -53.587142)
		(end 473.907866 -53.575458)
		(width 0.089408)
		(layer "In4.Cu")
		(net "PWRGD_P1V15_BMC_STBY")
	)
	(segment
		(start 398.827498 -64.542924)
		(end 398.993614 -64.376808)
		(width 0.089408)
		(layer "In4.Cu")
		(net "PWRGD_P1V15_BMC_STBY")
	)
	(segment
		(start 468.046562 -40.314118)
		(end 468.046816 -40.313864)
		(width 0.089408)
		(layer "In4.Cu")
		(net "PWRGD_P1V15_BMC_STBY")
	)
	(segment
		(start 468.046816 -40.298116)
		(end 468.036656 -40.287956)
		(width 0.089408)
		(layer "In4.Cu")
		(net "PWRGD_P1V15_BMC_STBY")
	)
	(segment
		(start 428.06747 -61.294518)
		(end 428.06747 -62.025784)
		(width 0.089408)
		(layer "In4.Cu")
		(net "PWRGD_P1V15_BMC_STBY")
	)
	(segment
		(start 385.2164 -66.548)
		(end 387.082284 -64.682116)
		(width 0.089408)
		(layer "In4.Cu")
		(net "PWRGD_P1V15_BMC_STBY")
	)
	(segment
		(start 473.198952 -50.828956)
		(end 473.89161 -50.828956)
		(width 0.089408)
		(layer "In4.Cu")
		(net "PWRGD_P1V15_BMC_STBY")
	)
	(segment
		(start 464.274154 -60.396374)
		(end 464.274154 -59.835034)
		(width 0.089408)
		(layer "In4.Cu")
		(net "PWRGD_P1V15_BMC_STBY")
	)
	(segment
		(start 427.928532 -61.15558)
		(end 428.06747 -61.294518)
		(width 0.089408)
		(layer "In4.Cu")
		(net "PWRGD_P1V15_BMC_STBY")
	)
	(segment
		(start 385.7371 -109.0549)
		(end 385.33705 -108.65485)
		(width 0.1143)
		(layer "F.Cu")
		(net "PVNN_PCH_STBY")
	)
	(segment
		(start 387.73735 -110.25505)
		(end 388.030212 -109.962188)
		(width 0.12446)
		(layer "F.Cu")
		(net "PVNN_PCH_STBY")
	)
	(segment
		(start 384.53695 -107.85475)
		(end 384.937 -108.2548)
		(width 0.1143)
		(layer "F.Cu")
		(net "PVNN_PCH_STBY")
	)
	(segment
		(start 387.73735 -107.85475)
		(end 387.3373 -107.4547)
		(width 0.12446)
		(layer "F.Cu")
		(net "PVNN_PCH_STBY")
	)
	(segment
		(start 383.73685 -107.05465)
		(end 384.1369 -107.4547)
		(width 0.1143)
		(layer "F.Cu")
		(net "PVNN_PCH_STBY")
	)
	(segment
		(start 386.13715 -109.45495)
		(end 385.7371 -109.0549)
		(width 0.12446)
		(layer "F.Cu")
		(net "PVNN_PCH_STBY")
	)
	(segment
		(start 384.1369 -111.4552)
		(end 383.73685 -111.05515)
		(width 0.1143)
		(layer "F.Cu")
		(net "PVNN_PCH_STBY")
	)
	(segment
		(start 390.13765 -107.85475)
		(end 390.5377 -107.4547)
		(width 0.12446)
		(layer "F.Cu")
		(net "PVNN_PCH_STBY")
	)
	(segment
		(start 391.3378 -109.0549)
		(end 390.93775 -109.45495)
		(width 0.12446)
		(layer "F.Cu")
		(net "PVNN_PCH_STBY")
	)
	(segment
		(start 390.5377 -109.0549)
		(end 390.93775 -109.45495)
		(width 0.12446)
		(layer "F.Cu")
		(net "PVNN_PCH_STBY")
	)
	(segment
		(start 386.13715 -107.85475)
		(end 385.7371 -108.2548)
		(width 0.1143)
		(layer "F.Cu")
		(net "PVNN_PCH_STBY")
	)
	(segment
		(start 389.33755 -109.45495)
		(end 389.630412 -109.747812)
		(width 0.12446)
		(layer "F.Cu")
		(net "PVNN_PCH_STBY")
	)
	(segment
		(start 382.643888 -108.361988)
		(end 382.93675 -108.65485)
		(width 0.12446)
		(layer "F.Cu")
		(net "PVNN_PCH_STBY")
	)
	(segment
		(start 383.3368 -108.2548)
		(end 382.93675 -108.65485)
		(width 0.1143)
		(layer "F.Cu")
		(net "PVNN_PCH_STBY")
	)
	(segment
		(start 383.3368 -107.4547)
		(end 383.73685 -107.05465)
		(width 0.1143)
		(layer "F.Cu")
		(net "PVNN_PCH_STBY")
	)
	(segment
		(start 381.79375 -110.71352)
		(end 382.369568 -111.031782)
		(width 0.254)
		(layer "F.Cu")
		(net "PVNN_PCH_STBY")
	)
	(segment
		(start 383.3368 -109.0549)
		(end 383.73685 -108.65485)
		(width 0.1143)
		(layer "F.Cu")
		(net "PVNN_PCH_STBY")
	)
	(segment
		(start 385.33705 -111.05515)
		(end 384.937 -111.4552)
		(width 0.12446)
		(layer "F.Cu")
		(net "PVNN_PCH_STBY")
	)
	(segment
		(start 384.1369 -109.0549)
		(end 384.53695 -109.45495)
		(width 0.12446)
		(layer "F.Cu")
		(net "PVNN_PCH_STBY")
	)
	(segment
		(start 385.7371 -108.2548)
		(end 385.33705 -108.65485)
		(width 0.1143)
		(layer "F.Cu")
		(net "PVNN_PCH_STBY")
	)
	(segment
		(start 390.13765 -107.85475)
		(end 390.5377 -108.2548)
		(width 0.1143)
		(layer "F.Cu")
		(net "PVNN_PCH_STBY")
	)
	(segment
		(start 385.33705 -111.85525)
		(end 384.937 -112.2553)
		(width 0.12446)
		(layer "F.Cu")
		(net "PVNN_PCH_STBY")
	)
	(segment
		(start 383.73685 -109.45495)
		(end 384.1369 -109.0549)
		(width 0.12446)
		(layer "F.Cu")
		(net "PVNN_PCH_STBY")
	)
	(segment
		(start 382.28905 -106.42092)
		(end 382.581912 -106.128058)
		(width 0.12446)
		(layer "F.Cu")
		(net "PVNN_PCH_STBY")
	)
	(segment
		(start 383.3368 -108.2548)
		(end 383.73685 -107.85475)
		(width 0.1143)
		(layer "F.Cu")
		(net "PVNN_PCH_STBY")
	)
	(segment
		(start 383.3368 -107.4547)
		(end 382.93675 -107.05465)
		(width 0.12446)
		(layer "F.Cu")
		(net "PVNN_PCH_STBY")
	)
	(segment
		(start 384.53695 -110.25505)
		(end 384.829812 -109.962188)
		(width 0.12446)
		(layer "F.Cu")
		(net "PVNN_PCH_STBY")
	)
	(segment
		(start 389.33755 -110.25505)
		(end 389.630412 -109.962188)
		(width 0.12446)
		(layer "F.Cu")
		(net "PVNN_PCH_STBY")
	)
	(segment
		(start 382.643888 -108.947712)
		(end 382.93675 -108.65485)
		(width 0.12446)
		(layer "F.Cu")
		(net "PVNN_PCH_STBY")
	)
	(segment
		(start 383.73685 -107.85475)
		(end 384.1369 -108.2548)
		(width 0.1143)
		(layer "F.Cu")
		(net "PVNN_PCH_STBY")
	)
	(segment
		(start 385.33705 -108.65485)
		(end 384.937 -109.0549)
		(width 0.1143)
		(layer "F.Cu")
		(net "PVNN_PCH_STBY")
	)
	(segment
		(start 384.53695 -111.05515)
		(end 384.1369 -111.4552)
		(width 0.12446)
		(layer "F.Cu")
		(net "PVNN_PCH_STBY")
	)
	(segment
		(start 382.93675 -111.85525)
		(end 382.669542 -111.588042)
		(width 0.1143)
		(layer "F.Cu")
		(net "PVNN_PCH_STBY")
	)
	(segment
		(start 383.443988 -109.747812)
		(end 383.73685 -109.45495)
		(width 0.12446)
		(layer "F.Cu")
		(net "PVNN_PCH_STBY")
	)
	(segment
		(start 381.79375 -107.27944)
		(end 382.086612 -107.572302)
		(width 0.12446)
		(layer "F.Cu")
		(net "PVNN_PCH_STBY")
	)
	(segment
		(start 385.044188 -109.747812)
		(end 385.33705 -109.45495)
		(width 0.12446)
		(layer "F.Cu")
		(net "PVNN_PCH_STBY")
	)
	(segment
		(start 388.244588 -108.361988)
		(end 388.53745 -108.65485)
		(width 0.12446)
		(layer "F.Cu")
		(net "PVNN_PCH_STBY")
	)
	(segment
		(start 390.13765 -109.45495)
		(end 389.630412 -109.962188)
		(width 0.1143)
		(layer "F.Cu")
		(net "PVNN_PCH_STBY")
	)
	(segment
		(start 384.53695 -106.25455)
		(end 384.1369 -105.8545)
		(width 0.12446)
		(layer "F.Cu")
		(net "PVNN_PCH_STBY")
	)
	(segment
		(start 382.524 -107.90301)
		(end 382.28905 -108.13796)
		(width 0.1143)
		(layer "F.Cu")
		(net "PVNN_PCH_STBY")
	)
	(segment
		(start 390.93775 -108.65485)
		(end 391.3378 -109.0549)
		(width 0.1143)
		(layer "F.Cu")
		(net "PVNN_PCH_STBY")
	)
	(segment
		(start 389.33755 -108.65485)
		(end 388.9375 -109.0549)
		(width 0.1143)
		(layer "F.Cu")
		(net "PVNN_PCH_STBY")
	)
	(segment
		(start 383.73685 -109.45495)
		(end 383.3368 -109.0549)
		(width 0.12446)
		(layer "F.Cu")
		(net "PVNN_PCH_STBY")
	)
	(segment
		(start 384.1369 -108.2548)
		(end 383.73685 -108.65485)
		(width 0.1143)
		(layer "F.Cu")
		(net "PVNN_PCH_STBY")
	)
	(segment
		(start 387.3373 -108.2548)
		(end 387.73735 -107.85475)
		(width 0.1143)
		(layer "F.Cu")
		(net "PVNN_PCH_STBY")
	)
	(segment
		(start 384.937 -109.0549)
		(end 384.53695 -109.45495)
		(width 0.12446)
		(layer "F.Cu")
		(net "PVNN_PCH_STBY")
	)
	(segment
		(start 383.3368 -106.6546)
		(end 382.93675 -107.05465)
		(width 0.12446)
		(layer "F.Cu")
		(net "PVNN_PCH_STBY")
	)
	(segment
		(start 390.13765 -109.45495)
		(end 389.7376 -109.0549)
		(width 0.1143)
		(layer "F.Cu")
		(net "PVNN_PCH_STBY")
	)
	(segment
		(start 388.244588 -110.762288)
		(end 388.53745 -111.05515)
		(width 0.12446)
		(layer "F.Cu")
		(net "PVNN_PCH_STBY")
	)
	(segment
		(start 384.53695 -109.45495)
		(end 384.829812 -109.747812)
		(width 0.12446)
		(layer "F.Cu")
		(net "PVNN_PCH_STBY")
	)
	(segment
		(start 387.73735 -111.05515)
		(end 388.030212 -110.762288)
		(width 0.12446)
		(layer "F.Cu")
		(net "PVNN_PCH_STBY")
	)
	(segment
		(start 388.53745 -107.85475)
		(end 388.9375 -107.4547)
		(width 0.12446)
		(layer "F.Cu")
		(net "PVNN_PCH_STBY")
	)
	(segment
		(start 381.996188 -108.430822)
		(end 382.28905 -108.13796)
		(width 0.12446)
		(layer "F.Cu")
		(net "PVNN_PCH_STBY")
	)
	(segment
		(start 387.73735 -108.65485)
		(end 388.030212 -108.361988)
		(width 0.12446)
		(layer "F.Cu")
		(net "PVNN_PCH_STBY")
	)
	(segment
		(start 384.937 -112.2553)
		(end 384.53695 -111.85525)
		(width 0.1143)
		(layer "F.Cu")
		(net "PVNN_PCH_STBY")
	)
	(segment
		(start 381.79375 -108.99648)
		(end 382.086612 -108.703618)
		(width 0.12446)
		(layer "F.Cu")
		(net "PVNN_PCH_STBY")
	)
	(segment
		(start 388.9375 -110.6551)
		(end 388.53745 -111.05515)
		(width 0.1143)
		(layer "F.Cu")
		(net "PVNN_PCH_STBY")
	)
	(segment
		(start 389.7376 -107.4547)
		(end 390.13765 -107.85475)
		(width 0.1143)
		(layer "F.Cu")
		(net "PVNN_PCH_STBY")
	)
	(segment
		(start 388.244588 -108.947712)
		(end 388.53745 -108.65485)
		(width 0.12446)
		(layer "F.Cu")
		(net "PVNN_PCH_STBY")
	)
	(segment
		(start 384.53695 -107.85475)
		(end 384.1369 -108.2548)
		(width 0.1143)
		(layer "F.Cu")
		(net "PVNN_PCH_STBY")
	)
	(segment
		(start 384.53695 -110.25505)
		(end 384.1369 -110.6551)
		(width 0.1143)
		(layer "F.Cu")
		(net "PVNN_PCH_STBY")
	)
	(segment
		(start 382.42367 -107.595416)
		(end 382.524 -107.695746)
		(width 0.1143)
		(layer "F.Cu")
		(net "PVNN_PCH_STBY")
	)
	(segment
		(start 389.7376 -109.0549)
		(end 390.13765 -108.65485)
		(width 0.1143)
		(layer "F.Cu")
		(net "PVNN_PCH_STBY")
	)
	(segment
		(start 383.3368 -112.2553)
		(end 383.73685 -111.85525)
		(width 0.12446)
		(layer "F.Cu")
		(net "PVNN_PCH_STBY")
	)
	(segment
		(start 382.93675 -107.85475)
		(end 382.68021 -108.11129)
		(width 0.1143)
		(layer "F.Cu")
		(net "PVNN_PCH_STBY")
	)
	(segment
		(start 384.1369 -109.0549)
		(end 383.73685 -108.65485)
		(width 0.1143)
		(layer "F.Cu")
		(net "PVNN_PCH_STBY")
	)
	(segment
		(start 383.73685 -108.65485)
		(end 383.3368 -108.2548)
		(width 0.12446)
		(layer "F.Cu")
		(net "PVNN_PCH_STBY")
	)
	(segment
		(start 387.73735 -111.05515)
		(end 388.030212 -111.348012)
		(width 0.12446)
		(layer "F.Cu")
		(net "PVNN_PCH_STBY")
	)
	(segment
		(start 382.42367 -107.56773)
		(end 382.93675 -107.05465)
		(width 0.12446)
		(layer "F.Cu")
		(net "PVNN_PCH_STBY")
	)
	(segment
		(start 382.93675 -106.25455)
		(end 383.3368 -105.8545)
		(width 0.12446)
		(layer "F.Cu")
		(net "PVNN_PCH_STBY")
	)
	(segment
		(start 382.369568 -111.031782)
		(end 382.28905 -111.57204)
		(width 0.254)
		(layer "F.Cu")
		(net "PVNN_PCH_STBY")
	)
	(segment
		(start 383.73685 -111.85525)
		(end 384.1369 -111.4552)
		(width 0.1143)
		(layer "F.Cu")
		(net "PVNN_PCH_STBY")
	)
	(segment
		(start 373.972328 -155.765754)
		(end 373.972328 -155.627832)
		(width 0.254)
		(layer "F.Cu")
		(net "PVNN_PCH_STBY")
	)
	(segment
		(start 382.643888 -106.547412)
		(end 382.93675 -106.25455)
		(width 0.12446)
		(layer "F.Cu")
		(net "PVNN_PCH_STBY")
	)
	(segment
		(start 387.73735 -110.25505)
		(end 387.3373 -110.6551)
		(width 0.12446)
		(layer "F.Cu")
		(net "PVNN_PCH_STBY")
	)
	(segment
		(start 388.9375 -109.0549)
		(end 389.33755 -109.45495)
		(width 0.1143)
		(layer "F.Cu")
		(net "PVNN_PCH_STBY")
	)
	(segment
		(start 384.1369 -107.4547)
		(end 383.73685 -107.85475)
		(width 0.1143)
		(layer "F.Cu")
		(net "PVNN_PCH_STBY")
	)
	(segment
		(start 382.28905 -108.13796)
		(end 382.581912 -108.430822)
		(width 0.12446)
		(layer "F.Cu")
		(net "PVNN_PCH_STBY")
	)
	(segment
		(start 384.53695 -106.25455)
		(end 384.937 -106.6546)
		(width 0.12446)
		(layer "F.Cu")
		(net "PVNN_PCH_STBY")
	)
	(segment
		(start 390.5377 -108.2548)
		(end 390.13765 -108.65485)
		(width 0.12446)
		(layer "F.Cu")
		(net "PVNN_PCH_STBY")
	)
	(segment
		(start 388.244588 -111.348012)
		(end 388.53745 -111.05515)
		(width 0.12446)
		(layer "F.Cu")
		(net "PVNN_PCH_STBY")
	)
	(segment
		(start 385.33705 -110.25505)
		(end 385.7371 -110.6551)
		(width 0.12446)
		(layer "F.Cu")
		(net "PVNN_PCH_STBY")
	)
	(segment
		(start 382.643888 -110.762288)
		(end 382.93675 -111.05515)
		(width 0.12446)
		(layer "F.Cu")
		(net "PVNN_PCH_STBY")
	)
	(segment
		(start 385.7371 -107.4547)
		(end 385.33705 -107.05465)
		(width 0.1143)
		(layer "F.Cu")
		(net "PVNN_PCH_STBY")
	)
	(segment
		(start 384.53695 -111.85525)
		(end 384.1369 -112.2553)
		(width 0.12446)
		(layer "F.Cu")
		(net "PVNN_PCH_STBY")
	)
	(segment
		(start 389.7376 -108.2548)
		(end 390.13765 -108.65485)
		(width 0.1143)
		(layer "F.Cu")
		(net "PVNN_PCH_STBY")
	)
	(segment
		(start 382.93675 -111.85525)
		(end 383.3368 -112.2553)
		(width 0.12446)
		(layer "F.Cu")
		(net "PVNN_PCH_STBY")
	)
	(segment
		(start 384.53695 -108.65485)
		(end 384.1369 -108.2548)
		(width 0.12446)
		(layer "F.Cu")
		(net "PVNN_PCH_STBY")
	)
	(segment
		(start 382.93675 -111.85525)
		(end 383.3368 -111.4552)
		(width 0.1143)
		(layer "F.Cu")
		(net "PVNN_PCH_STBY")
	)
	(segment
		(start 387.73735 -108.65485)
		(end 387.3373 -108.2548)
		(width 0.12446)
		(layer "F.Cu")
		(net "PVNN_PCH_STBY")
	)
	(segment
		(start 382.93675 -107.85475)
		(end 383.3368 -108.2548)
		(width 0.1143)
		(layer "F.Cu")
		(net "PVNN_PCH_STBY")
	)
	(segment
		(start 384.53695 -107.05465)
		(end 384.1369 -107.4547)
		(width 0.1143)
		(layer "F.Cu")
		(net "PVNN_PCH_STBY")
	)
	(segment
		(start 384.1369 -106.6546)
		(end 384.53695 -107.05465)
		(width 0.12446)
		(layer "F.Cu")
		(net "PVNN_PCH_STBY")
	)
	(segment
		(start 383.73685 -110.25505)
		(end 384.1369 -110.6551)
		(width 0.1143)
		(layer "F.Cu")
		(net "PVNN_PCH_STBY")
	)
	(segment
		(start 388.9375 -111.4552)
		(end 389.33755 -111.05515)
		(width 0.1143)
		(layer "F.Cu")
		(net "PVNN_PCH_STBY")
	)
	(segment
		(start 387.73735 -111.05515)
		(end 387.3373 -111.4552)
		(width 0.12446)
		(layer "F.Cu")
		(net "PVNN_PCH_STBY")
	)
	(segment
		(start 382.684528 -112.107472)
		(end 382.45161 -112.107472)
		(width 0.1143)
		(layer "F.Cu")
		(net "PVNN_PCH_STBY")
	)
	(segment
		(start 384.937 -110.6551)
		(end 385.33705 -111.05515)
		(width 0.12446)
		(layer "F.Cu")
		(net "PVNN_PCH_STBY")
	)
	(segment
		(start 388.53745 -109.45495)
		(end 388.9375 -109.0549)
		(width 0.12446)
		(layer "F.Cu")
		(net "PVNN_PCH_STBY")
	)
	(segment
		(start 389.33755 -110.25505)
		(end 389.7376 -110.6551)
		(width 0.12446)
		(layer "F.Cu")
		(net "PVNN_PCH_STBY")
	)
	(segment
		(start 389.33755 -108.65485)
		(end 389.7376 -109.0549)
		(width 0.1143)
		(layer "F.Cu")
		(net "PVNN_PCH_STBY")
	)
	(segment
		(start 388.244588 -110.547912)
		(end 388.53745 -110.25505)
		(width 0.12446)
		(layer "F.Cu")
		(net "PVNN_PCH_STBY")
	)
	(segment
		(start 382.93675 -109.45495)
		(end 382.711706 -109.679994)
		(width 0.1143)
		(layer "F.Cu")
		(net "PVNN_PCH_STBY")
	)
	(segment
		(start 382.93675 -107.85475)
		(end 382.677416 -107.595416)
		(width 0.1143)
		(layer "F.Cu")
		(net "PVNN_PCH_STBY")
	)
	(segment
		(start 390.93775 -107.85475)
		(end 391.3378 -108.2548)
		(width 0.1143)
		(layer "F.Cu")
		(net "PVNN_PCH_STBY")
	)
	(segment
		(start 385.7371 -111.4552)
		(end 385.33705 -111.05515)
		(width 0.12446)
		(layer "F.Cu")
		(net "PVNN_PCH_STBY")
	)
	(segment
		(start 389.044688 -109.962188)
		(end 389.33755 -110.25505)
		(width 0.12446)
		(layer "F.Cu")
		(net "PVNN_PCH_STBY")
	)
	(segment
		(start 383.73685 -106.25455)
		(end 383.3368 -106.6546)
		(width 0.1143)
		(layer "F.Cu")
		(net "PVNN_PCH_STBY")
	)
	(segment
		(start 384.937 -111.4552)
		(end 384.53695 -111.05515)
		(width 0.12446)
		(layer "F.Cu")
		(net "PVNN_PCH_STBY")
	)
	(segment
		(start 384.1369 -111.4552)
		(end 384.53695 -111.85525)
		(width 0.1143)
		(layer "F.Cu")
		(net "PVNN_PCH_STBY")
	)
	(segment
		(start 385.33705 -107.05465)
		(end 384.937 -107.4547)
		(width 0.1143)
		(layer "F.Cu")
		(net "PVNN_PCH_STBY")
	)
	(segment
		(start 388.9375 -108.2548)
		(end 388.53745 -107.85475)
		(width 0.1143)
		(layer "F.Cu")
		(net "PVNN_PCH_STBY")
	)
	(segment
		(start 383.3368 -111.4552)
		(end 382.93675 -111.05515)
		(width 0.1143)
		(layer "F.Cu")
		(net "PVNN_PCH_STBY")
	)
	(segment
		(start 389.33755 -107.85475)
		(end 389.7376 -108.2548)
		(width 0.1143)
		(layer "F.Cu")
		(net "PVNN_PCH_STBY")
	)
	(segment
		(start 388.244588 -109.747812)
		(end 388.53745 -109.45495)
		(width 0.12446)
		(layer "F.Cu")
		(net "PVNN_PCH_STBY")
	)
	(segment
		(start 385.33705 -108.65485)
		(end 384.937 -108.2548)
		(width 0.12446)
		(layer "F.Cu")
		(net "PVNN_PCH_STBY")
	)
	(segment
		(start 384.1369 -110.6551)
		(end 383.73685 -111.05515)
		(width 0.1143)
		(layer "F.Cu")
		(net "PVNN_PCH_STBY")
	)
	(segment
		(start 383.73685 -107.85475)
		(end 383.3368 -107.4547)
		(width 0.12446)
		(layer "F.Cu")
		(net "PVNN_PCH_STBY")
	)
	(segment
		(start 385.33705 -109.45495)
		(end 384.937 -109.0549)
		(width 0.12446)
		(layer "F.Cu")
		(net "PVNN_PCH_STBY")
	)
	(segment
		(start 382.643888 -109.162088)
		(end 382.93675 -109.45495)
		(width 0.12446)
		(layer "F.Cu")
		(net "PVNN_PCH_STBY")
	)
	(segment
		(start 381.79375 -108.99648)
		(end 382.086612 -109.289342)
		(width 0.12446)
		(layer "F.Cu")
		(net "PVNN_PCH_STBY")
	)
	(segment
		(start 385.7371 -109.0549)
		(end 385.33705 -109.45495)
		(width 0.12446)
		(layer "F.Cu")
		(net "PVNN_PCH_STBY")
	)
	(segment
		(start 391.3378 -108.2548)
		(end 390.93775 -108.65485)
		(width 0.12446)
		(layer "F.Cu")
		(net "PVNN_PCH_STBY")
	)
	(segment
		(start 382.643888 -105.961688)
		(end 382.93675 -106.25455)
		(width 0.12446)
		(layer "F.Cu")
		(net "PVNN_PCH_STBY")
	)
	(segment
		(start 382.524 -107.695746)
		(end 382.524 -107.90301)
		(width 0.1143)
		(layer "F.Cu")
		(net "PVNN_PCH_STBY")
	)
	(segment
		(start 388.9375 -108.2548)
		(end 389.33755 -108.65485)
		(width 0.1143)
		(layer "F.Cu")
		(net "PVNN_PCH_STBY")
	)
	(segment
		(start 372.831106 -157.216856)
		(end 372.831106 -156.906976)
		(width 0.254)
		(layer "F.Cu")
		(net "PVNN_PCH_STBY")
	)
	(segment
		(start 384.53695 -107.05465)
		(end 384.937 -107.4547)
		(width 0.1143)
		(layer "F.Cu")
		(net "PVNN_PCH_STBY")
	)
	(segment
		(start 385.33705 -111.85525)
		(end 384.937 -111.4552)
		(width 0.1143)
		(layer "F.Cu")
		(net "PVNN_PCH_STBY")
	)
	(segment
		(start 384.244088 -109.962188)
		(end 384.53695 -110.25505)
		(width 0.12446)
		(layer "F.Cu")
		(net "PVNN_PCH_STBY")
	)
	(segment
		(start 382.93675 -110.25505)
		(end 383.2479 -109.9439)
		(width 0.12446)
		(layer "F.Cu")
		(net "PVNN_PCH_STBY")
	)
	(segment
		(start 384.53695 -107.05465)
		(end 384.937 -106.6546)
		(width 0.1143)
		(layer "F.Cu")
		(net "PVNN_PCH_STBY")
	)
	(segment
		(start 388.244588 -109.162088)
		(end 388.53745 -109.45495)
		(width 0.12446)
		(layer "F.Cu")
		(net "PVNN_PCH_STBY")
	)
	(segment
		(start 382.93675 -106.25455)
		(end 383.3368 -106.6546)
		(width 0.1143)
		(layer "F.Cu")
		(net "PVNN_PCH_STBY")
	)
	(segment
		(start 388.53745 -108.65485)
		(end 388.9375 -108.2548)
		(width 0.12446)
		(layer "F.Cu")
		(net "PVNN_PCH_STBY")
	)
	(segment
		(start 389.33755 -111.05515)
		(end 388.9375 -110.6551)
		(width 0.1143)
		(layer "F.Cu")
		(net "PVNN_PCH_STBY")
	)
	(segment
		(start 382.93675 -109.45495)
		(end 383.3368 -109.0549)
		(width 0.12446)
		(layer "F.Cu")
		(net "PVNN_PCH_STBY")
	)
	(segment
		(start 389.33755 -108.65485)
		(end 389.7376 -108.2548)
		(width 0.12446)
		(layer "F.Cu")
		(net "PVNN_PCH_STBY")
	)
	(segment
		(start 384.53695 -111.05515)
		(end 384.1369 -110.6551)
		(width 0.12446)
		(layer "F.Cu")
		(net "PVNN_PCH_STBY")
	)
	(segment
		(start 389.33755 -109.45495)
		(end 389.7376 -109.0549)
		(width 0.12446)
		(layer "F.Cu")
		(net "PVNN_PCH_STBY")
	)
	(segment
		(start 388.244588 -108.147612)
		(end 388.53745 -107.85475)
		(width 0.12446)
		(layer "F.Cu")
		(net "PVNN_PCH_STBY")
	)
	(segment
		(start 387.444488 -109.962188)
		(end 387.73735 -110.25505)
		(width 0.12446)
		(layer "F.Cu")
		(net "PVNN_PCH_STBY")
	)
	(segment
		(start 390.93775 -108.65485)
		(end 390.5377 -109.0549)
		(width 0.1143)
		(layer "F.Cu")
		(net "PVNN_PCH_STBY")
	)
	(segment
		(start 383.73685 -110.25505)
		(end 384.029712 -109.962188)
		(width 0.12446)
		(layer "F.Cu")
		(net "PVNN_PCH_STBY")
	)
	(segment
		(start 384.53695 -106.25455)
		(end 384.1369 -106.6546)
		(width 0.12446)
		(layer "F.Cu")
		(net "PVNN_PCH_STBY")
	)
	(segment
		(start 385.044188 -109.962188)
		(end 385.33705 -110.25505)
		(width 0.12446)
		(layer "F.Cu")
		(net "PVNN_PCH_STBY")
	)
	(segment
		(start 390.13765 -109.45495)
		(end 390.5377 -109.0549)
		(width 0.12446)
		(layer "F.Cu")
		(net "PVNN_PCH_STBY")
	)
	(segment
		(start 388.53745 -111.05515)
		(end 388.9375 -111.4552)
		(width 0.12446)
		(layer "F.Cu")
		(net "PVNN_PCH_STBY")
	)
	(segment
		(start 383.3368 -110.6551)
		(end 383.73685 -111.05515)
		(width 0.1143)
		(layer "F.Cu")
		(net "PVNN_PCH_STBY")
	)
	(segment
		(start 387.73735 -107.85475)
		(end 388.030212 -107.561888)
		(width 0.12446)
		(layer "F.Cu")
		(net "PVNN_PCH_STBY")
	)
	(segment
		(start 385.33705 -109.45495)
		(end 385.629912 -109.747812)
		(width 0.12446)
		(layer "F.Cu")
		(net "PVNN_PCH_STBY")
	)
	(segment
		(start 382.93675 -111.85525)
		(end 382.684528 -112.107472)
		(width 0.1143)
		(layer "F.Cu")
		(net "PVNN_PCH_STBY")
	)
	(segment
		(start 383.3368 -111.4552)
		(end 383.73685 -111.85525)
		(width 0.1143)
		(layer "F.Cu")
		(net "PVNN_PCH_STBY")
	)
	(segment
		(start 390.5377 -109.0549)
		(end 390.13765 -108.65485)
		(width 0.1143)
		(layer "F.Cu")
		(net "PVNN_PCH_STBY")
	)
	(segment
		(start 385.7371 -110.6551)
		(end 386.13715 -111.05515)
		(width 0.1143)
		(layer "F.Cu")
		(net "PVNN_PCH_STBY")
	)
	(segment
		(start 381.79375 -107.27944)
		(end 382.086612 -106.986578)
		(width 0.12446)
		(layer "F.Cu")
		(net "PVNN_PCH_STBY")
	)
	(segment
		(start 382.93675 -109.45495)
		(end 383.229612 -109.747812)
		(width 0.12446)
		(layer "F.Cu")
		(net "PVNN_PCH_STBY")
	)
	(segment
		(start 388.53745 -110.25505)
		(end 388.9375 -110.6551)
		(width 0.12446)
		(layer "F.Cu")
		(net "PVNN_PCH_STBY")
	)
	(segment
		(start 386.13715 -110.25505)
		(end 385.7371 -110.6551)
		(width 0.12446)
		(layer "F.Cu")
		(net "PVNN_PCH_STBY")
	)
	(segment
		(start 386.13715 -111.05515)
		(end 385.7371 -111.4552)
		(width 0.12446)
		(layer "F.Cu")
		(net "PVNN_PCH_STBY")
	)
	(segment
		(start 383.73685 -107.05465)
		(end 384.1369 -106.6546)
		(width 0.1143)
		(layer "F.Cu")
		(net "PVNN_PCH_STBY")
	)
	(segment
		(start 389.044688 -109.747812)
		(end 389.33755 -109.45495)
		(width 0.12446)
		(layer "F.Cu")
		(net "PVNN_PCH_STBY")
	)
	(segment
		(start 383.73685 -109.45495)
		(end 384.029712 -109.747812)
		(width 0.12446)
		(layer "F.Cu")
		(net "PVNN_PCH_STBY")
	)
	(segment
		(start 386.13715 -110.25505)
		(end 385.803648 -109.921548)
		(width 0.1143)
		(layer "F.Cu")
		(net "PVNN_PCH_STBY")
	)
	(segment
		(start 383.73685 -110.25505)
		(end 383.3368 -110.6551)
		(width 0.12446)
		(layer "F.Cu")
		(net "PVNN_PCH_STBY")
	)
	(segment
		(start 383.3368 -110.6551)
		(end 382.93675 -111.05515)
		(width 0.12446)
		(layer "F.Cu")
		(net "PVNN_PCH_STBY")
	)
	(segment
		(start 382.93675 -110.25505)
		(end 383.3368 -110.6551)
		(width 0.12446)
		(layer "F.Cu")
		(net "PVNN_PCH_STBY")
	)
	(segment
		(start 387.3373 -110.6551)
		(end 387.73735 -111.05515)
		(width 0.1143)
		(layer "F.Cu")
		(net "PVNN_PCH_STBY")
	)
	(segment
		(start 384.1369 -112.2553)
		(end 383.73685 -111.85525)
		(width 0.1143)
		(layer "F.Cu")
		(net "PVNN_PCH_STBY")
	)
	(segment
		(start 382.93675 -107.85475)
		(end 383.3368 -107.4547)
		(width 0.12446)
		(layer "F.Cu")
		(net "PVNN_PCH_STBY")
	)
	(segment
		(start 385.7371 -111.4552)
		(end 385.33705 -111.85525)
		(width 0.1143)
		(layer "F.Cu")
		(net "PVNN_PCH_STBY")
	)
	(segment
		(start 386.13715 -108.65485)
		(end 385.7371 -109.0549)
		(width 0.1143)
		(layer "F.Cu")
		(net "PVNN_PCH_STBY")
	)
	(segment
		(start 384.53695 -108.65485)
		(end 384.1369 -109.0549)
		(width 0.1143)
		(layer "F.Cu")
		(net "PVNN_PCH_STBY")
	)
	(segment
		(start 383.3368 -109.0549)
		(end 382.93675 -108.65485)
		(width 0.12446)
		(layer "F.Cu")
		(net "PVNN_PCH_STBY")
	)
	(segment
		(start 390.5377 -107.4547)
		(end 390.93775 -107.85475)
		(width 0.1143)
		(layer "F.Cu")
		(net "PVNN_PCH_STBY")
	)
	(segment
		(start 391.3378 -107.4547)
		(end 390.93775 -107.85475)
		(width 0.12446)
		(layer "F.Cu")
		(net "PVNN_PCH_STBY")
	)
	(segment
		(start 382.28905 -106.42092)
		(end 382.581912 -106.713782)
		(width 0.12446)
		(layer "F.Cu")
		(net "PVNN_PCH_STBY")
	)
	(segment
		(start 384.937 -111.4552)
		(end 384.53695 -111.85525)
		(width 0.1143)
		(layer "F.Cu")
		(net "PVNN_PCH_STBY")
	)
	(segment
		(start 384.937 -106.6546)
		(end 385.33705 -107.05465)
		(width 0.12446)
		(layer "F.Cu")
		(net "PVNN_PCH_STBY")
	)
	(segment
		(start 381.996188 -106.128058)
		(end 382.28905 -106.42092)
		(width 0.12446)
		(layer "F.Cu")
		(net "PVNN_PCH_STBY")
	)
	(segment
		(start 390.13765 -107.85475)
		(end 389.7376 -108.2548)
		(width 0.1143)
		(layer "F.Cu")
		(net "PVNN_PCH_STBY")
	)
	(segment
		(start 390.93775 -107.85475)
		(end 390.5377 -108.2548)
		(width 0.1143)
		(layer "F.Cu")
		(net "PVNN_PCH_STBY")
	)
	(segment
		(start 372.831106 -156.906976)
		(end 373.972328 -155.765754)
		(width 0.254)
		(layer "F.Cu")
		(net "PVNN_PCH_STBY")
	)
	(segment
		(start 386.13715 -109.45495)
		(end 385.882896 -109.709204)
		(width 0.1143)
		(layer "F.Cu")
		(net "PVNN_PCH_STBY")
	)
	(segment
		(start 384.1369 -105.8545)
		(end 383.73685 -106.25455)
		(width 0.1143)
		(layer "F.Cu")
		(net "PVNN_PCH_STBY")
	)
	(segment
		(start 388.53745 -109.45495)
		(end 388.830312 -109.747812)
		(width 0.12446)
		(layer "F.Cu")
		(net "PVNN_PCH_STBY")
	)
	(segment
		(start 388.244588 -107.561888)
		(end 388.53745 -107.85475)
		(width 0.12446)
		(layer "F.Cu")
		(net "PVNN_PCH_STBY")
	)
	(segment
		(start 388.53745 -108.65485)
		(end 388.9375 -109.0549)
		(width 0.1143)
		(layer "F.Cu")
		(net "PVNN_PCH_STBY")
	)
	(segment
		(start 387.73735 -107.85475)
		(end 388.030212 -108.147612)
		(width 0.12446)
		(layer "F.Cu")
		(net "PVNN_PCH_STBY")
	)
	(segment
		(start 385.33705 -110.25505)
		(end 385.629912 -109.962188)
		(width 0.12446)
		(layer "F.Cu")
		(net "PVNN_PCH_STBY")
	)
	(segment
		(start 384.937 -109.0549)
		(end 384.53695 -108.65485)
		(width 0.1143)
		(layer "F.Cu")
		(net "PVNN_PCH_STBY")
	)
	(segment
		(start 388.9375 -107.4547)
		(end 389.33755 -107.85475)
		(width 0.1143)
		(layer "F.Cu")
		(net "PVNN_PCH_STBY")
	)
	(segment
		(start 384.244088 -109.747812)
		(end 384.53695 -109.45495)
		(width 0.12446)
		(layer "F.Cu")
		(net "PVNN_PCH_STBY")
	)
	(segment
		(start 388.53745 -110.25505)
		(end 388.830312 -109.962188)
		(width 0.12446)
		(layer "F.Cu")
		(net "PVNN_PCH_STBY")
	)
	(segment
		(start 382.677416 -107.595416)
		(end 382.42367 -107.595416)
		(width 0.1143)
		(layer "F.Cu")
		(net "PVNN_PCH_STBY")
	)
	(segment
		(start 384.937 -110.6551)
		(end 385.33705 -110.25505)
		(width 0.12446)
		(layer "F.Cu")
		(net "PVNN_PCH_STBY")
	)
	(segment
		(start 386.13715 -107.85475)
		(end 385.7371 -107.4547)
		(width 0.12446)
		(layer "F.Cu")
		(net "PVNN_PCH_STBY")
	)
	(segment
		(start 390.93775 -108.65485)
		(end 390.5377 -108.2548)
		(width 0.1143)
		(layer "F.Cu")
		(net "PVNN_PCH_STBY")
	)
	(segment
		(start 383.443988 -109.962188)
		(end 383.73685 -110.25505)
		(width 0.12446)
		(layer "F.Cu")
		(net "PVNN_PCH_STBY")
	)
	(segment
		(start 385.33705 -107.85475)
		(end 384.937 -107.4547)
		(width 0.12446)
		(layer "F.Cu")
		(net "PVNN_PCH_STBY")
	)
	(segment
		(start 381.996188 -106.713782)
		(end 382.28905 -106.42092)
		(width 0.12446)
		(layer "F.Cu")
		(net "PVNN_PCH_STBY")
	)
	(segment
		(start 385.7371 -110.6551)
		(end 385.33705 -111.05515)
		(width 0.12446)
		(layer "F.Cu")
		(net "PVNN_PCH_STBY")
	)
	(segment
		(start 384.53695 -111.05515)
		(end 384.937 -110.6551)
		(width 0.12446)
		(layer "F.Cu")
		(net "PVNN_PCH_STBY")
	)
	(segment
		(start 388.244588 -109.962188)
		(end 388.53745 -110.25505)
		(width 0.12446)
		(layer "F.Cu")
		(net "PVNN_PCH_STBY")
	)
	(segment
		(start 381.79375 -105.5624)
		(end 382.27 -105.72496)
		(width 0.254)
		(layer "F.Cu")
		(net "PVNN_PCH_STBY")
	)
	(segment
		(start 383.73685 -106.25455)
		(end 384.1369 -106.6546)
		(width 0.1143)
		(layer "F.Cu")
		(net "PVNN_PCH_STBY")
	)
	(segment
		(start 383.73685 -107.05465)
		(end 383.3368 -106.6546)
		(width 0.12446)
		(layer "F.Cu")
		(net "PVNN_PCH_STBY")
	)
	(segment
		(start 384.53695 -110.25505)
		(end 384.937 -110.6551)
		(width 0.12446)
		(layer "F.Cu")
		(net "PVNN_PCH_STBY")
	)
	(segment
		(start 389.7376 -110.6551)
		(end 389.33755 -111.05515)
		(width 0.1143)
		(layer "F.Cu")
		(net "PVNN_PCH_STBY")
	)
	(segment
		(start 387.73735 -108.65485)
		(end 388.030212 -108.947712)
		(width 0.12446)
		(layer "F.Cu")
		(net "PVNN_PCH_STBY")
	)
	(segment
		(start 383.3368 -105.8545)
		(end 383.73685 -106.25455)
		(width 0.12446)
		(layer "F.Cu")
		(net "PVNN_PCH_STBY")
	)
	(segment
		(start 384.937 -108.2548)
		(end 384.53695 -108.65485)
		(width 0.1143)
		(layer "F.Cu")
		(net "PVNN_PCH_STBY")
	)
	(segment
		(start 384.53695 -107.85475)
		(end 384.1369 -107.4547)
		(width 0.12446)
		(layer "F.Cu")
		(net "PVNN_PCH_STBY")
	)
	(segment
		(start 389.33755 -111.05515)
		(end 389.7376 -111.4552)
		(width 0.12446)
		(layer "F.Cu")
		(net "PVNN_PCH_STBY")
	)
	(segment
		(start 384.937 -107.4547)
		(end 384.53695 -107.85475)
		(width 0.1143)
		(layer "F.Cu")
		(net "PVNN_PCH_STBY")
	)
	(segment
		(start 386.13715 -108.65485)
		(end 385.7371 -108.2548)
		(width 0.12446)
		(layer "F.Cu")
		(net "PVNN_PCH_STBY")
	)
	(segment
		(start 382.643888 -111.348012)
		(end 382.93675 -111.05515)
		(width 0.12446)
		(layer "F.Cu")
		(net "PVNN_PCH_STBY")
	)
	(segment
		(start 382.42367 -107.595416)
		(end 382.42367 -107.56773)
		(width 0.12446)
		(layer "F.Cu")
		(net "PVNN_PCH_STBY")
	)
	(segment
		(start 389.33755 -107.85475)
		(end 389.7376 -107.4547)
		(width 0.12446)
		(layer "F.Cu")
		(net "PVNN_PCH_STBY")
	)
	(segment
		(start 383.73685 -111.05515)
		(end 383.3368 -111.4552)
		(width 0.12446)
		(layer "F.Cu")
		(net "PVNN_PCH_STBY")
	)
	(segment
		(start 389.33755 -107.85475)
		(end 388.9375 -108.2548)
		(width 0.1143)
		(layer "F.Cu")
		(net "PVNN_PCH_STBY")
	)
	(segment
		(start 387.73735 -110.25505)
		(end 388.030212 -110.547912)
		(width 0.12446)
		(layer "F.Cu")
		(net "PVNN_PCH_STBY")
	)
	(via
		(at 390.5377 -107.4547)
		(size 0.508)
		(drill 0.254)
		(layers "F.Cu" "B.Cu")
		(net "PVNN_PCH_STBY")
	)
	(via
		(at 381.13462 -142.715488)
		(size 0.5588)
		(drill 0.3048)
		(layers "F.Cu" "B.Cu")
		(net "PVNN_PCH_STBY")
	)
	(via
		(at 384.1369 -107.4547)
		(size 0.508)
		(drill 0.254)
		(layers "F.Cu" "B.Cu")
		(net "PVNN_PCH_STBY")
	)
	(via
		(at 351.706434 -54.567328)
		(size 0.508)
		(drill 0.254)
		(layers "F.Cu" "B.Cu")
		(net "PVNN_PCH_STBY")
	)
	(via
		(at 383.3368 -111.4552)
		(size 0.508)
		(drill 0.254)
		(layers "F.Cu" "B.Cu")
		(net "PVNN_PCH_STBY")
	)
	(via
		(at 382.42367 -107.595416)
		(size 0.508)
		(drill 0.254)
		(layers "F.Cu" "B.Cu")
		(net "PVNN_PCH_STBY")
	)
	(via
		(at 384.937 -107.4547)
		(size 0.508)
		(drill 0.254)
		(layers "F.Cu" "B.Cu")
		(net "PVNN_PCH_STBY")
	)
	(via
		(at 384.1369 -105.8545)
		(size 0.508)
		(drill 0.254)
		(layers "F.Cu" "B.Cu")
		(net "PVNN_PCH_STBY")
	)
	(via
		(at 379.777498 -142.707868)
		(size 0.5588)
		(drill 0.3048)
		(layers "F.Cu" "B.Cu")
		(net "PVNN_PCH_STBY")
	)
	(via
		(at 387.3373 -111.4552)
		(size 0.508)
		(drill 0.254)
		(layers "F.Cu" "B.Cu")
		(net "PVNN_PCH_STBY")
	)
	(via
		(at 383.3368 -112.2553)
		(size 0.508)
		(drill 0.254)
		(layers "F.Cu" "B.Cu")
		(net "PVNN_PCH_STBY")
	)
	(via
		(at 406.273 -19.05)
		(size 0.508)
		(drill 0.254)
		(layers "F.Cu" "B.Cu")
		(net "PVNN_PCH_STBY")
	)
	(via
		(at 385.7371 -108.2548)
		(size 0.508)
		(drill 0.254)
		(layers "F.Cu" "B.Cu")
		(net "PVNN_PCH_STBY")
	)
	(via
		(at 387.3373 -110.6551)
		(size 0.508)
		(drill 0.254)
		(layers "F.Cu" "B.Cu")
		(net "PVNN_PCH_STBY")
	)
	(via
		(at 389.7376 -110.6551)
		(size 0.508)
		(drill 0.254)
		(layers "F.Cu" "B.Cu")
		(net "PVNN_PCH_STBY")
	)
	(via
		(at 368.985546 -102.63124)
		(size 0.508)
		(drill 0.254)
		(layers "F.Cu" "B.Cu")
		(net "PVNN_PCH_STBY")
	)
	(via
		(at 370.5352 -108.3818)
		(size 0.6604)
		(drill 0.3302)
		(layers "F.Cu" "B.Cu")
		(net "PVNN_PCH_STBY")
	)
	(via
		(at 384.937 -108.2548)
		(size 0.508)
		(drill 0.254)
		(layers "F.Cu" "B.Cu")
		(net "PVNN_PCH_STBY")
	)
	(via
		(at 372.799356 -142.721584)
		(size 0.5588)
		(drill 0.3048)
		(layers "F.Cu" "B.Cu")
		(net "PVNN_PCH_STBY")
	)
	(via
		(at 380.2888 -106.9848)
		(size 0.508)
		(drill 0.254)
		(layers "F.Cu" "B.Cu")
		(net "PVNN_PCH_STBY")
	)
	(via
		(at 378.286264 -142.682468)
		(size 0.5588)
		(drill 0.3048)
		(layers "F.Cu" "B.Cu")
		(net "PVNN_PCH_STBY")
	)
	(via
		(at 369.104164 -139.060174)
		(size 0.5588)
		(drill 0.3048)
		(layers "F.Cu" "B.Cu")
		(net "PVNN_PCH_STBY")
	)
	(via
		(at 384.937 -106.6546)
		(size 0.508)
		(drill 0.254)
		(layers "F.Cu" "B.Cu")
		(net "PVNN_PCH_STBY")
	)
	(via
		(at 371.695726 -142.687802)
		(size 0.5588)
		(drill 0.3048)
		(layers "F.Cu" "B.Cu")
		(net "PVNN_PCH_STBY")
	)
	(via
		(at 384.937 -110.6551)
		(size 0.508)
		(drill 0.254)
		(layers "F.Cu" "B.Cu")
		(net "PVNN_PCH_STBY")
	)
	(via
		(at 385.7371 -107.4547)
		(size 0.508)
		(drill 0.254)
		(layers "F.Cu" "B.Cu")
		(net "PVNN_PCH_STBY")
	)
	(via
		(at 391.3378 -108.2548)
		(size 0.508)
		(drill 0.254)
		(layers "F.Cu" "B.Cu")
		(net "PVNN_PCH_STBY")
	)
	(via
		(at 384.1369 -106.6546)
		(size 0.508)
		(drill 0.254)
		(layers "F.Cu" "B.Cu")
		(net "PVNN_PCH_STBY")
	)
	(via
		(at 380.457964 -138.632438)
		(size 0.5588)
		(drill 0.3048)
		(layers "F.Cu" "B.Cu")
		(net "PVNN_PCH_STBY")
	)
	(via
		(at 384.1369 -109.0549)
		(size 0.508)
		(drill 0.254)
		(layers "F.Cu" "B.Cu")
		(net "PVNN_PCH_STBY")
	)
	(via
		(at 384.937 -109.0549)
		(size 0.508)
		(drill 0.254)
		(layers "F.Cu" "B.Cu")
		(net "PVNN_PCH_STBY")
	)
	(via
		(at 387.3373 -107.4547)
		(size 0.508)
		(drill 0.254)
		(layers "F.Cu" "B.Cu")
		(net "PVNN_PCH_STBY")
	)
	(via
		(at 389.7376 -109.0549)
		(size 0.508)
		(drill 0.254)
		(layers "F.Cu" "B.Cu")
		(net "PVNN_PCH_STBY")
	)
	(via
		(at 383.3368 -107.4547)
		(size 0.508)
		(drill 0.254)
		(layers "F.Cu" "B.Cu")
		(net "PVNN_PCH_STBY")
	)
	(via
		(at 388.9375 -108.2548)
		(size 0.508)
		(drill 0.254)
		(layers "F.Cu" "B.Cu")
		(net "PVNN_PCH_STBY")
	)
	(via
		(at 384.1369 -112.2553)
		(size 0.508)
		(drill 0.254)
		(layers "F.Cu" "B.Cu")
		(net "PVNN_PCH_STBY")
	)
	(via
		(at 369.1636 -107.442)
		(size 0.6604)
		(drill 0.3302)
		(layers "F.Cu" "B.Cu")
		(net "PVNN_PCH_STBY")
	)
	(via
		(at 372.831106 -157.216856)
		(size 0.508)
		(drill 0.254)
		(layers "F.Cu" "B.Cu")
		(net "PVNN_PCH_STBY")
	)
	(via
		(at 373.459756 -142.728442)
		(size 0.5588)
		(drill 0.3048)
		(layers "F.Cu" "B.Cu")
		(net "PVNN_PCH_STBY")
	)
	(via
		(at 383.3368 -110.6551)
		(size 0.508)
		(drill 0.254)
		(layers "F.Cu" "B.Cu")
		(net "PVNN_PCH_STBY")
	)
	(via
		(at 383.3368 -108.2548)
		(size 0.508)
		(drill 0.254)
		(layers "F.Cu" "B.Cu")
		(net "PVNN_PCH_STBY")
	)
	(via
		(at 388.9375 -110.6551)
		(size 0.508)
		(drill 0.254)
		(layers "F.Cu" "B.Cu")
		(net "PVNN_PCH_STBY")
	)
	(via
		(at 390.5377 -109.0549)
		(size 0.508)
		(drill 0.254)
		(layers "F.Cu" "B.Cu")
		(net "PVNN_PCH_STBY")
	)
	(via
		(at 382.45161 -112.107472)
		(size 0.508)
		(drill 0.254)
		(layers "F.Cu" "B.Cu")
		(net "PVNN_PCH_STBY")
	)
	(via
		(at 368.7826 -143.2306)
		(size 0.5588)
		(drill 0.3048)
		(layers "F.Cu" "B.Cu")
		(net "PVNN_PCH_STBY")
	)
	(via
		(at 385.7371 -111.4552)
		(size 0.508)
		(drill 0.254)
		(layers "F.Cu" "B.Cu")
		(net "PVNN_PCH_STBY")
	)
	(via
		(at 388.9375 -107.4547)
		(size 0.508)
		(drill 0.254)
		(layers "F.Cu" "B.Cu")
		(net "PVNN_PCH_STBY")
	)
	(via
		(at 382.386586 -106.961178)
		(size 0.508)
		(drill 0.254)
		(layers "F.Cu" "B.Cu")
		(net "PVNN_PCH_STBY")
	)
	(via
		(at 370.1542 -143.2306)
		(size 0.5588)
		(drill 0.3048)
		(layers "F.Cu" "B.Cu")
		(net "PVNN_PCH_STBY")
	)
	(via
		(at 385.7371 -110.6551)
		(size 0.508)
		(drill 0.254)
		(layers "F.Cu" "B.Cu")
		(net "PVNN_PCH_STBY")
	)
	(via
		(at 384.1369 -108.2548)
		(size 0.508)
		(drill 0.254)
		(layers "F.Cu" "B.Cu")
		(net "PVNN_PCH_STBY")
	)
	(via
		(at 379.00102 -138.66114)
		(size 0.5588)
		(drill 0.3048)
		(layers "F.Cu" "B.Cu")
		(net "PVNN_PCH_STBY")
	)
	(via
		(at 367.4364 -143.2306)
		(size 0.5588)
		(drill 0.3048)
		(layers "F.Cu" "B.Cu")
		(net "PVNN_PCH_STBY")
	)
	(via
		(at 389.7376 -111.4552)
		(size 0.508)
		(drill 0.254)
		(layers "F.Cu" "B.Cu")
		(net "PVNN_PCH_STBY")
	)
	(via
		(at 390.5377 -108.2548)
		(size 0.508)
		(drill 0.254)
		(layers "F.Cu" "B.Cu")
		(net "PVNN_PCH_STBY")
	)
	(via
		(at 389.7376 -107.4547)
		(size 0.508)
		(drill 0.254)
		(layers "F.Cu" "B.Cu")
		(net "PVNN_PCH_STBY")
	)
	(via
		(at 382.369568 -111.031782)
		(size 0.508)
		(drill 0.254)
		(layers "F.Cu" "B.Cu")
		(net "PVNN_PCH_STBY")
	)
	(via
		(at 381.794512 -106.652568)
		(size 0.508)
		(drill 0.254)
		(layers "F.Cu" "B.Cu")
		(net "PVNN_PCH_STBY")
	)
	(via
		(at 388.9375 -109.0549)
		(size 0.508)
		(drill 0.254)
		(layers "F.Cu" "B.Cu")
		(net "PVNN_PCH_STBY")
	)
	(via
		(at 389.7376 -108.2548)
		(size 0.508)
		(drill 0.254)
		(layers "F.Cu" "B.Cu")
		(net "PVNN_PCH_STBY")
	)
	(via
		(at 374.146572 -142.748762)
		(size 0.5588)
		(drill 0.3048)
		(layers "F.Cu" "B.Cu")
		(net "PVNN_PCH_STBY")
	)
	(via
		(at 373.02186 -33.3248)
		(size 0.508)
		(drill 0.254)
		(layers "F.Cu" "B.Cu")
		(net "PVNN_PCH_STBY")
	)
	(via
		(at 384.937 -111.4552)
		(size 0.508)
		(drill 0.254)
		(layers "F.Cu" "B.Cu")
		(net "PVNN_PCH_STBY")
	)
	(via
		(at 383.3368 -106.6546)
		(size 0.508)
		(drill 0.254)
		(layers "F.Cu" "B.Cu")
		(net "PVNN_PCH_STBY")
	)
	(via
		(at 387.3373 -108.2548)
		(size 0.508)
		(drill 0.254)
		(layers "F.Cu" "B.Cu")
		(net "PVNN_PCH_STBY")
	)
	(via
		(at 380.471172 -142.715488)
		(size 0.5588)
		(drill 0.3048)
		(layers "F.Cu" "B.Cu")
		(net "PVNN_PCH_STBY")
	)
	(via
		(at 391.3378 -109.0549)
		(size 0.508)
		(drill 0.254)
		(layers "F.Cu" "B.Cu")
		(net "PVNN_PCH_STBY")
	)
	(via
		(at 379.015498 -142.707868)
		(size 0.5588)
		(drill 0.3048)
		(layers "F.Cu" "B.Cu")
		(net "PVNN_PCH_STBY")
	)
	(via
		(at 368.1222 -143.2306)
		(size 0.5588)
		(drill 0.3048)
		(layers "F.Cu" "B.Cu")
		(net "PVNN_PCH_STBY")
	)
	(via
		(at 384.1369 -110.6551)
		(size 0.508)
		(drill 0.254)
		(layers "F.Cu" "B.Cu")
		(net "PVNN_PCH_STBY")
	)
	(via
		(at 385.7371 -109.0549)
		(size 0.508)
		(drill 0.254)
		(layers "F.Cu" "B.Cu")
		(net "PVNN_PCH_STBY")
	)
	(via
		(at 384.1369 -111.4552)
		(size 0.508)
		(drill 0.254)
		(layers "F.Cu" "B.Cu")
		(net "PVNN_PCH_STBY")
	)
	(via
		(at 369.84432 -139.07516)
		(size 0.5588)
		(drill 0.3048)
		(layers "F.Cu" "B.Cu")
		(net "PVNN_PCH_STBY")
	)
	(via
		(at 368.907568 -138.429492)
		(size 0.5588)
		(drill 0.3048)
		(layers "F.Cu" "B.Cu")
		(net "PVNN_PCH_STBY")
	)
	(via
		(at 391.3378 -107.4547)
		(size 0.508)
		(drill 0.254)
		(layers "F.Cu" "B.Cu")
		(net "PVNN_PCH_STBY")
	)
	(via
		(at 379.76302 -138.66114)
		(size 0.5588)
		(drill 0.3048)
		(layers "F.Cu" "B.Cu")
		(net "PVNN_PCH_STBY")
	)
	(via
		(at 388.9375 -111.4552)
		(size 0.508)
		(drill 0.254)
		(layers "F.Cu" "B.Cu")
		(net "PVNN_PCH_STBY")
	)
	(via
		(at 382.538986 -109.029246)
		(size 0.508)
		(drill 0.254)
		(layers "F.Cu" "B.Cu")
		(net "PVNN_PCH_STBY")
	)
	(via
		(at 369.4684 -143.2306)
		(size 0.5588)
		(drill 0.3048)
		(layers "F.Cu" "B.Cu")
		(net "PVNN_PCH_STBY")
	)
	(via
		(at 384.937 -112.2553)
		(size 0.508)
		(drill 0.254)
		(layers "F.Cu" "B.Cu")
		(net "PVNN_PCH_STBY")
	)
	(via
		(at 383.3368 -109.0549)
		(size 0.508)
		(drill 0.254)
		(layers "F.Cu" "B.Cu")
		(net "PVNN_PCH_STBY")
	)
	(via
		(at 383.3368 -105.8545)
		(size 0.508)
		(drill 0.254)
		(layers "F.Cu" "B.Cu")
		(net "PVNN_PCH_STBY")
	)
	(segment
		(start 372.598696 -33.3248)
		(end 373.02186 -33.3248)
		(width 0.254)
		(layer "B.Cu")
		(net "PVNN_PCH_STBY")
	)
	(segment
		(start 372.081044 -32.807148)
		(end 372.598696 -33.3248)
		(width 0.254)
		(layer "B.Cu")
		(net "PVNN_PCH_STBY")
	)
	(segment
		(start 358.608376 -45.607478)
		(end 358.608376 -40.112188)
		(width 0.254)
		(layer "B.Cu")
		(net "PVNN_PCH_STBY")
	)
	(segment
		(start 358.608376 -40.112188)
		(end 365.913416 -32.807148)
		(width 0.254)
		(layer "B.Cu")
		(net "PVNN_PCH_STBY")
	)
	(segment
		(start 406.273 -18.9865)
		(end 406.195022 -18.908522)
		(width 0.254)
		(layer "B.Cu")
		(net "PVNN_PCH_STBY")
	)
	(segment
		(start 406.195022 -18.908522)
		(end 406.195022 -17.838166)
		(width 0.254)
		(layer "B.Cu")
		(net "PVNN_PCH_STBY")
	)
	(segment
		(start 351.706434 -52.50942)
		(end 358.608376 -45.607478)
		(width 0.254)
		(layer "B.Cu")
		(net "PVNN_PCH_STBY")
	)
	(segment
		(start 365.913416 -32.807148)
		(end 372.081044 -32.807148)
		(width 0.254)
		(layer "B.Cu")
		(net "PVNN_PCH_STBY")
	)
	(segment
		(start 351.706434 -54.567328)
		(end 351.706434 -52.50942)
		(width 0.254)
		(layer "B.Cu")
		(net "PVNN_PCH_STBY")
	)
	(segment
		(start 406.273 -19.05)
		(end 406.273 -18.9865)
		(width 0.254)
		(layer "B.Cu")
		(net "PVNN_PCH_STBY")
	)
	(segment
		(start 372.831106 -156.608272)
		(end 372.831106 -157.216856)
		(width 0.4064)
		(layer "In2.Cu")
		(net "PVNN_PCH_STBY")
	)
	(segment
		(start 368.160808 -149.807676)
		(end 372.299484 -153.946352)
		(width 0.4064)
		(layer "In2.Cu")
		(net "PVNN_PCH_STBY")
	)
	(segment
		(start 370.1542 -143.4084)
		(end 369.915948 -143.646652)
		(width 0.4064)
		(layer "In2.Cu")
		(net "PVNN_PCH_STBY")
	)
	(segment
		(start 372.299484 -156.07665)
		(end 372.831106 -156.608272)
		(width 0.4064)
		(layer "In2.Cu")
		(net "PVNN_PCH_STBY")
	)
	(segment
		(start 369.915948 -143.646652)
		(end 369.915948 -145.925032)
		(width 0.4064)
		(layer "In2.Cu")
		(net "PVNN_PCH_STBY")
	)
	(segment
		(start 372.299484 -153.946352)
		(end 372.299484 -156.07665)
		(width 0.4064)
		(layer "In2.Cu")
		(net "PVNN_PCH_STBY")
	)
	(segment
		(start 370.1542 -143.2306)
		(end 370.1542 -143.4084)
		(width 0.4064)
		(layer "In2.Cu")
		(net "PVNN_PCH_STBY")
	)
	(segment
		(start 368.160808 -147.680172)
		(end 368.160808 -149.807676)
		(width 0.4064)
		(layer "In2.Cu")
		(net "PVNN_PCH_STBY")
	)
	(segment
		(start 369.915948 -145.925032)
		(end 368.160808 -147.680172)
		(width 0.4064)
		(layer "In2.Cu")
		(net "PVNN_PCH_STBY")
	)
	(segment
		(start 374.750584 -27.244294)
		(end 374.307354 -27.244294)
		(width 0.254)
		(layer "In4.Cu")
		(net "PVNN_PCH_STBY")
	)
	(segment
		(start 373.488458 -29.156914)
		(end 373.488458 -31.295848)
		(width 0.254)
		(layer "In4.Cu")
		(net "PVNN_PCH_STBY")
	)
	(segment
		(start 372.831614 -33.3248)
		(end 373.02186 -33.3248)
		(width 0.254)
		(layer "In4.Cu")
		(net "PVNN_PCH_STBY")
	)
	(segment
		(start 374.243346 -27.2796)
		(end 373.781574 -27.741372)
		(width 0.254)
		(layer "In4.Cu")
		(net "PVNN_PCH_STBY")
	)
	(segment
		(start 372.577614 -33.0708)
		(end 372.831614 -33.3248)
		(width 0.254)
		(layer "In4.Cu")
		(net "PVNN_PCH_STBY")
	)
	(segment
		(start 380.777242 -18.157952)
		(end 376.635264 -22.29993)
		(width 0.254)
		(layer "In4.Cu")
		(net "PVNN_PCH_STBY")
	)
	(segment
		(start 392.55446 -18.157952)
		(end 380.777242 -18.157952)
		(width 0.254)
		(layer "In4.Cu")
		(net "PVNN_PCH_STBY")
	)
	(segment
		(start 403.642322 -20.33016)
		(end 403.290532 -19.97837)
		(width 0.254)
		(layer "In4.Cu")
		(net "PVNN_PCH_STBY")
	)
	(segment
		(start 404.9014 -20.33016)
		(end 403.642322 -20.33016)
		(width 0.254)
		(layer "In4.Cu")
		(net "PVNN_PCH_STBY")
	)
	(segment
		(start 374.307354 -27.244294)
		(end 374.243346 -27.2796)
		(width 0.254)
		(layer "In4.Cu")
		(net "PVNN_PCH_STBY")
	)
	(segment
		(start 406.273 -19.05)
		(end 406.2095 -19.1135)
		(width 0.254)
		(layer "In4.Cu")
		(net "PVNN_PCH_STBY")
	)
	(segment
		(start 375.283476 -26.711402)
		(end 374.750584 -27.244294)
		(width 0.254)
		(layer "In4.Cu")
		(net "PVNN_PCH_STBY")
	)
	(segment
		(start 376.635264 -25.35936)
		(end 375.283476 -26.711402)
		(width 0.254)
		(layer "In4.Cu")
		(net "PVNN_PCH_STBY")
	)
	(segment
		(start 394.374878 -19.97837)
		(end 392.55446 -18.157952)
		(width 0.254)
		(layer "In4.Cu")
		(net "PVNN_PCH_STBY")
	)
	(segment
		(start 406.11806 -19.1135)
		(end 404.9014 -20.33016)
		(width 0.254)
		(layer "In4.Cu")
		(net "PVNN_PCH_STBY")
	)
	(segment
		(start 403.290532 -19.97837)
		(end 394.374878 -19.97837)
		(width 0.254)
		(layer "In4.Cu")
		(net "PVNN_PCH_STBY")
	)
	(segment
		(start 373.488458 -31.295848)
		(end 372.577614 -32.206692)
		(width 0.254)
		(layer "In4.Cu")
		(net "PVNN_PCH_STBY")
	)
	(segment
		(start 373.52732 -28.968446)
		(end 373.488458 -29.156914)
		(width 0.254)
		(layer "In4.Cu")
		(net "PVNN_PCH_STBY")
	)
	(segment
		(start 406.2095 -19.1135)
		(end 406.11806 -19.1135)
		(width 0.254)
		(layer "In4.Cu")
		(net "PVNN_PCH_STBY")
	)
	(segment
		(start 376.635264 -22.29993)
		(end 376.635264 -25.35936)
		(width 0.254)
		(layer "In4.Cu")
		(net "PVNN_PCH_STBY")
	)
	(segment
		(start 372.577614 -32.206692)
		(end 372.577614 -33.0708)
		(width 0.254)
		(layer "In4.Cu")
		(net "PVNN_PCH_STBY")
	)
	(segment
		(start 373.781574 -27.741372)
		(end 373.52732 -28.968446)
		(width 0.254)
		(layer "In4.Cu")
		(net "PVNN_PCH_STBY")
	)
	(segment
		(start 351.721166 -54.64556)
		(end 351.721166 -54.58206)
		(width 0.254)
		(layer "In11.Cu")
		(net "PVNN_PCH_STBY")
	)
	(segment
		(start 351.721166 -54.58206)
		(end 351.706434 -54.567328)
		(width 0.254)
		(layer "In11.Cu")
		(net "PVNN_PCH_STBY")
	)
	(segment
		(start 368.306096 -93.64472)
		(end 365.150654 -90.489278)
		(width 0.254)
		(layer "In11.Cu")
		(net "PVNN_PCH_STBY")
	)
	(segment
		(start 363.270546 -69.312536)
		(end 364.4138 -68.169282)
		(width 0.254)
		(layer "In11.Cu")
		(net "PVNN_PCH_STBY")
	)
	(segment
		(start 364.4138 -67.910964)
		(end 366.357408 -65.967356)
		(width 0.254)
		(layer "In11.Cu")
		(net "PVNN_PCH_STBY")
	)
	(segment
		(start 365.150654 -84.23529)
		(end 364.476284 -83.56092)
		(width 0.254)
		(layer "In11.Cu")
		(net "PVNN_PCH_STBY")
	)
	(segment
		(start 364.476284 -83.56092)
		(end 364.476284 -79.773272)
		(width 0.254)
		(layer "In11.Cu")
		(net "PVNN_PCH_STBY")
	)
	(segment
		(start 363.270546 -72.170798)
		(end 363.270546 -69.312536)
		(width 0.254)
		(layer "In11.Cu")
		(net "PVNN_PCH_STBY")
	)
	(segment
		(start 365.146082 -60.852304)
		(end 362.591858 -60.852304)
		(width 0.254)
		(layer "In11.Cu")
		(net "PVNN_PCH_STBY")
	)
	(segment
		(start 364.965996 -73.866248)
		(end 363.270546 -72.170798)
		(width 0.254)
		(layer "In11.Cu")
		(net "PVNN_PCH_STBY")
	)
	(segment
		(start 352.362516 -55.28691)
		(end 351.721166 -54.64556)
		(width 0.254)
		(layer "In11.Cu")
		(net "PVNN_PCH_STBY")
	)
	(segment
		(start 366.357408 -65.967356)
		(end 366.357408 -63.726568)
		(width 0.254)
		(layer "In11.Cu")
		(net "PVNN_PCH_STBY")
	)
	(segment
		(start 366.357408 -63.726568)
		(end 365.79556 -63.16472)
		(width 0.254)
		(layer "In11.Cu")
		(net "PVNN_PCH_STBY")
	)
	(segment
		(start 364.4138 -68.169282)
		(end 364.4138 -67.910964)
		(width 0.254)
		(layer "In11.Cu")
		(net "PVNN_PCH_STBY")
	)
	(segment
		(start 362.591858 -60.852304)
		(end 357.383842 -55.644288)
		(width 0.254)
		(layer "In11.Cu")
		(net "PVNN_PCH_STBY")
	)
	(segment
		(start 365.150654 -90.489278)
		(end 365.150654 -84.23529)
		(width 0.254)
		(layer "In11.Cu")
		(net "PVNN_PCH_STBY")
	)
	(segment
		(start 355.635814 -55.862982)
		(end 353.864418 -55.862982)
		(width 0.254)
		(layer "In11.Cu")
		(net "PVNN_PCH_STBY")
	)
	(segment
		(start 364.476284 -79.773272)
		(end 364.965996 -77.322426)
		(width 0.254)
		(layer "In11.Cu")
		(net "PVNN_PCH_STBY")
	)
	(segment
		(start 353.288346 -55.28691)
		(end 352.362516 -55.28691)
		(width 0.254)
		(layer "In11.Cu")
		(net "PVNN_PCH_STBY")
	)
	(segment
		(start 353.864418 -55.862982)
		(end 353.288346 -55.28691)
		(width 0.254)
		(layer "In11.Cu")
		(net "PVNN_PCH_STBY")
	)
	(segment
		(start 368.4905 -102.136194)
		(end 368.4905 -96.0882)
		(width 0.254)
		(layer "In11.Cu")
		(net "PVNN_PCH_STBY")
	)
	(segment
		(start 357.383842 -55.644288)
		(end 355.854508 -55.644288)
		(width 0.254)
		(layer "In11.Cu")
		(net "PVNN_PCH_STBY")
	)
	(segment
		(start 368.4905 -96.0882)
		(end 368.306096 -95.903796)
		(width 0.254)
		(layer "In11.Cu")
		(net "PVNN_PCH_STBY")
	)
	(segment
		(start 365.79556 -61.501782)
		(end 365.146082 -60.852304)
		(width 0.254)
		(layer "In11.Cu")
		(net "PVNN_PCH_STBY")
	)
	(segment
		(start 365.79556 -63.16472)
		(end 365.79556 -61.501782)
		(width 0.254)
		(layer "In11.Cu")
		(net "PVNN_PCH_STBY")
	)
	(segment
		(start 364.965996 -77.322426)
		(end 364.965996 -73.866248)
		(width 0.254)
		(layer "In11.Cu")
		(net "PVNN_PCH_STBY")
	)
	(segment
		(start 368.306096 -95.903796)
		(end 368.306096 -93.64472)
		(width 0.254)
		(layer "In11.Cu")
		(net "PVNN_PCH_STBY")
	)
	(segment
		(start 368.985546 -102.63124)
		(end 368.4905 -102.136194)
		(width 0.254)
		(layer "In11.Cu")
		(net "PVNN_PCH_STBY")
	)
	(segment
		(start 355.854508 -55.644288)
		(end 355.635814 -55.862982)
		(width 0.254)
		(layer "In11.Cu")
		(net "PVNN_PCH_STBY")
	)
	(segment
		(start 388.254748 -71.9455)
		(end 389.636 -71.9455)
		(width 0.508)
		(layer "F.Cu")
		(net "AGND_P5V_STBY")
	)
	(segment
		(start 391.5537 -63.6905)
		(end 391.16 -63.6905)
		(width 0.254)
		(layer "F.Cu")
		(net "AGND_P5V_STBY")
	)
	(segment
		(start 393.03325 -62.807596)
		(end 393.03325 -62.4459)
		(width 0.254)
		(layer "F.Cu")
		(net "AGND_P5V_STBY")
	)
	(segment
		(start 392.785346 -63.866776)
		(end 393.159996 -63.492126)
		(width 0.254)
		(layer "F.Cu")
		(net "AGND_P5V_STBY")
	)
	(segment
		(start 390.525 -71.9455)
		(end 389.636 -71.9455)
		(width 0.508)
		(layer "F.Cu")
		(net "AGND_P5V_STBY")
	)
	(segment
		(start 392.430508 -63.8175)
		(end 392.785346 -64.172338)
		(width 0.254)
		(layer "F.Cu")
		(net "AGND_P5V_STBY")
	)
	(segment
		(start 389.614156 -71.967344)
		(end 389.614156 -72.662542)
		(width 0.508)
		(layer "F.Cu")
		(net "AGND_P5V_STBY")
	)
	(segment
		(start 393.895326 -63.492126)
		(end 394.1826 -63.7794)
		(width 0.254)
		(layer "F.Cu")
		(net "AGND_P5V_STBY")
	)
	(segment
		(start 389.636 -71.9455)
		(end 389.614156 -71.967344)
		(width 0.508)
		(layer "F.Cu")
		(net "AGND_P5V_STBY")
	)
	(segment
		(start 394.1826 -65.344548)
		(end 394.573252 -65.7352)
		(width 0.254)
		(layer "F.Cu")
		(net "AGND_P5V_STBY")
	)
	(segment
		(start 394.573252 -65.7352)
		(end 394.8176 -65.7352)
		(width 0.254)
		(layer "F.Cu")
		(net "AGND_P5V_STBY")
	)
	(segment
		(start 392.785346 -64.172338)
		(end 392.785346 -63.866776)
		(width 0.254)
		(layer "F.Cu")
		(net "AGND_P5V_STBY")
	)
	(segment
		(start 392.023346 -63.8175)
		(end 391.6807 -63.8175)
		(width 0.254)
		(layer "F.Cu")
		(net "AGND_P5V_STBY")
	)
	(segment
		(start 391.6807 -63.8175)
		(end 391.5537 -63.6905)
		(width 0.254)
		(layer "F.Cu")
		(net "AGND_P5V_STBY")
	)
	(segment
		(start 394.1826 -63.7794)
		(end 394.1826 -65.344548)
		(width 0.254)
		(layer "F.Cu")
		(net "AGND_P5V_STBY")
	)
	(segment
		(start 393.159996 -63.492126)
		(end 393.895326 -63.492126)
		(width 0.254)
		(layer "F.Cu")
		(net "AGND_P5V_STBY")
	)
	(segment
		(start 392.023346 -63.8175)
		(end 392.430508 -63.8175)
		(width 0.254)
		(layer "F.Cu")
		(net "AGND_P5V_STBY")
	)
	(segment
		(start 392.023346 -63.8175)
		(end 393.03325 -62.807596)
		(width 0.254)
		(layer "F.Cu")
		(net "AGND_P5V_STBY")
	)
	(via
		(at 393.03325 -62.4459)
		(size 0.508)
		(drill 0.254)
		(layers "F.Cu" "B.Cu")
		(net "AGND_P5V_STBY")
	)
	(via
		(at 388.254748 -71.9455)
		(size 0.762)
		(drill 0.381)
		(layers "F.Cu" "B.Cu")
		(net "AGND_P5V_STBY")
	)
	(via
		(at 389.614156 -72.662542)
		(size 0.508)
		(drill 0.254)
		(layers "F.Cu" "B.Cu")
		(net "AGND_P5V_STBY")
	)
	(segment
		(start 389.614156 -70.386956)
		(end 389.614156 -72.662542)
		(width 0.254)
		(layer "In2.Cu")
		(net "AGND_P5V_STBY")
	)
	(segment
		(start 391.560558 -64.620902)
		(end 388.9756 -67.20586)
		(width 0.254)
		(layer "In2.Cu")
		(net "AGND_P5V_STBY")
	)
	(segment
		(start 393.03325 -62.4459)
		(end 391.560558 -63.918592)
		(width 0.254)
		(layer "In2.Cu")
		(net "AGND_P5V_STBY")
	)
	(segment
		(start 388.9756 -67.20586)
		(end 388.9756 -69.7484)
		(width 0.254)
		(layer "In2.Cu")
		(net "AGND_P5V_STBY")
	)
	(segment
		(start 391.560558 -63.918592)
		(end 391.560558 -64.620902)
		(width 0.254)
		(layer "In2.Cu")
		(net "AGND_P5V_STBY")
	)
	(segment
		(start 388.9756 -69.7484)
		(end 389.614156 -70.386956)
		(width 0.254)
		(layer "In2.Cu")
		(net "AGND_P5V_STBY")
	)
	(via
		(at 475.35084 -18.64106)
		(size 0.6604)
		(drill 0.3302)
		(layers "F.Cu" "B.Cu")
		(net "VR_P3V3_STBY_SNUB")
	)
	(segment
		(start 473.973906 -19.948398)
		(end 473.973906 -19.085052)
		(width 0.10795)
		(layer "B.Cu")
		(net "VR_P3V3_STBY_SNUB")
	)
	(segment
		(start 473.973906 -18.801334)
		(end 473.973906 -19.085052)
		(width 0.10795)
		(layer "B.Cu")
		(net "VR_P3V3_STBY_SNUB")
	)
	(segment
		(start 474.13418 -18.64106)
		(end 473.973906 -18.801334)
		(width 0.10795)
		(layer "B.Cu")
		(net "VR_P3V3_STBY_SNUB")
	)
	(segment
		(start 475.35084 -18.64106)
		(end 474.13418 -18.64106)
		(width 0.10795)
		(layer "B.Cu")
		(net "VR_P3V3_STBY_SNUB")
	)
	(segment
		(start 469.754204 -23.0378)
		(end 469.741504 -23.0505)
		(width 0.2032)
		(layer "F.Cu")
		(net "VR_P3V3_STBY_PHASE")
	)
	(segment
		(start 469.3031 -25.18156)
		(end 469.754204 -24.730456)
		(width 0.508)
		(layer "F.Cu")
		(net "VR_P3V3_STBY_PHASE")
	)
	(segment
		(start 469.754204 -24.730456)
		(end 469.754204 -24.257)
		(width 0.508)
		(layer "F.Cu")
		(net "VR_P3V3_STBY_PHASE")
	)
	(segment
		(start 469.741504 -23.0505)
		(end 468.9094 -23.0505)
		(width 0.2032)
		(layer "F.Cu")
		(net "VR_P3V3_STBY_PHASE")
	)
	(via
		(at 469.754204 -24.257)
		(size 0.508)
		(drill 0.254)
		(layers "F.Cu" "B.Cu")
		(net "VR_P3V3_STBY_PHASE")
	)
	(via
		(at 469.754204 -23.0378)
		(size 0.508)
		(drill 0.254)
		(layers "F.Cu" "B.Cu")
		(net "VR_P3V3_STBY_PHASE")
	)
	(via
		(at 472.0844 -18.8722)
		(size 0.508)
		(drill 0.254)
		(layers "F.Cu" "B.Cu")
		(net "VR_P3V3_STBY_PHASE")
	)
	(via
		(at 471.038428 -20.976082)
		(size 0.6604)
		(drill 0.3302)
		(layers "F.Cu" "B.Cu")
		(net "VR_P3V3_STBY_PHASE")
	)
	(segment
		(start 469.754204 -23.0378)
		(end 469.754204 -22.260306)
		(width 0.508)
		(layer "B.Cu")
		(net "VR_P3V3_STBY_PHASE")
	)
	(segment
		(start 471.80373 -19.15287)
		(end 472.0844 -18.8722)
		(width 0.508)
		(layer "B.Cu")
		(net "VR_P3V3_STBY_PHASE")
	)
	(segment
		(start 472.118944 -18.837656)
		(end 472.83751 -18.837656)
		(width 0.508)
		(layer "B.Cu")
		(net "VR_P3V3_STBY_PHASE")
	)
	(segment
		(start 472.0844 -18.8722)
		(end 472.118944 -18.837656)
		(width 0.508)
		(layer "B.Cu")
		(net "VR_P3V3_STBY_PHASE")
	)
	(segment
		(start 471.038428 -20.976082)
		(end 471.80373 -20.21078)
		(width 0.508)
		(layer "B.Cu")
		(net "VR_P3V3_STBY_PHASE")
	)
	(segment
		(start 472.83751 -18.837656)
		(end 473.084906 -19.085052)
		(width 0.508)
		(layer "B.Cu")
		(net "VR_P3V3_STBY_PHASE")
	)
	(segment
		(start 469.754204 -24.257)
		(end 469.754204 -23.0378)
		(width 0.508)
		(layer "B.Cu")
		(net "VR_P3V3_STBY_PHASE")
	)
	(segment
		(start 469.754204 -22.260306)
		(end 471.038428 -20.976082)
		(width 0.508)
		(layer "B.Cu")
		(net "VR_P3V3_STBY_PHASE")
	)
	(segment
		(start 471.80373 -20.21078)
		(end 471.80373 -19.15287)
		(width 0.508)
		(layer "B.Cu")
		(net "VR_P3V3_STBY_PHASE")
	)
	(segment
		(start 465.53882 -19.41322)
		(end 465.63534 -19.41322)
		(width 0.10795)
		(layer "F.Cu")
		(net "VR_P3V3_STBY_OCSELECT")
	)
	(segment
		(start 467.53145 -22.0726)
		(end 466.922358 -22.0726)
		(width 0.1016)
		(layer "F.Cu")
		(net "VR_P3V3_STBY_OCSELECT")
	)
	(segment
		(start 466.922358 -22.0726)
		(end 466.5345 -21.684742)
		(width 0.1016)
		(layer "F.Cu")
		(net "VR_P3V3_STBY_OCSELECT")
	)
	(segment
		(start 466.5345 -20.2311)
		(end 466.5345 -20.6502)
		(width 0.10795)
		(layer "F.Cu")
		(net "VR_P3V3_STBY_OCSELECT")
	)
	(segment
		(start 466.5345 -21.684742)
		(end 466.5345 -20.6502)
		(width 0.1016)
		(layer "F.Cu")
		(net "VR_P3V3_STBY_OCSELECT")
	)
	(segment
		(start 465.63534 -19.41322)
		(end 465.71662 -19.41322)
		(width 0.1016)
		(layer "F.Cu")
		(net "VR_P3V3_STBY_OCSELECT")
	)
	(segment
		(start 465.71662 -19.41322)
		(end 466.5345 -20.2311)
		(width 0.10795)
		(layer "F.Cu")
		(net "VR_P3V3_STBY_OCSELECT")
	)
	(via
		(at 465.53882 -19.41322)
		(size 0.762)
		(drill 0.381)
		(layers "F.Cu" "B.Cu")
		(net "VR_P3V3_STBY_OCSELECT")
	)
	(segment
		(start 468.68588 -26.57856)
		(end 468.613236 -26.651204)
		(width 0.508)
		(layer "F.Cu")
		(net "VR_P3V3_STBY_BOOT_R")
	)
	(segment
		(start 468.613236 -26.651204)
		(end 468.112856 -26.651204)
		(width 0.508)
		(layer "F.Cu")
		(net "VR_P3V3_STBY_BOOT_R")
	)
	(segment
		(start 469.3031 -26.57856)
		(end 468.68588 -26.57856)
		(width 0.508)
		(layer "F.Cu")
		(net "VR_P3V3_STBY_BOOT_R")
	)
	(segment
		(start 468.343996 -24.419052)
		(end 468.341456 -24.419052)
		(width 0.2032)
		(layer "F.Cu")
		(net "VR_P3V3_STBY_BOOT")
	)
	(segment
		(start 468.66556 -24.740616)
		(end 468.619078 -24.694134)
		(width 0.254)
		(layer "F.Cu")
		(net "VR_P3V3_STBY_BOOT")
	)
	(segment
		(start 468.619078 -24.694134)
		(end 468.343996 -24.419052)
		(width 0.2032)
		(layer "F.Cu")
		(net "VR_P3V3_STBY_BOOT")
	)
	(segment
		(start 468.112856 -25.762204)
		(end 468.41156 -25.762204)
		(width 0.254)
		(layer "F.Cu")
		(net "VR_P3V3_STBY_BOOT")
	)
	(segment
		(start 468.33155 -24.409146)
		(end 468.33155 -24.0284)
		(width 0.2032)
		(layer "F.Cu")
		(net "VR_P3V3_STBY_BOOT")
	)
	(segment
		(start 468.41156 -25.762204)
		(end 468.66556 -25.508204)
		(width 0.254)
		(layer "F.Cu")
		(net "VR_P3V3_STBY_BOOT")
	)
	(segment
		(start 468.341456 -24.419052)
		(end 468.33155 -24.409146)
		(width 0.2032)
		(layer "F.Cu")
		(net "VR_P3V3_STBY_BOOT")
	)
	(segment
		(start 468.66556 -25.508204)
		(end 468.66556 -24.740616)
		(width 0.254)
		(layer "F.Cu")
		(net "VR_P3V3_STBY_BOOT")
	)
	(segment
		(start 455.638408 -21.606002)
		(end 456.094338 -21.606002)
		(width 0.10795)
		(layer "F.Cu")
		(net "PWRGD_P3V3_STBY")
	)
	(segment
		(start 403.752812 -150.7998)
		(end 404.27402 -150.7998)
		(width 0.10795)
		(layer "F.Cu")
		(net "PWRGD_P3V3_STBY")
	)
	(segment
		(start 474.117924 -28.499816)
		(end 474.117924 -27.931618)
		(width 0.10795)
		(layer "F.Cu")
		(net "PWRGD_P3V3_STBY")
	)
	(segment
		(start 456.094338 -21.606002)
		(end 456.80503 -20.89531)
		(width 0.10795)
		(layer "F.Cu")
		(net "PWRGD_P3V3_STBY")
	)
	(segment
		(start 474.226128 -28.60802)
		(end 474.117924 -28.499816)
		(width 0.10795)
		(layer "F.Cu")
		(net "PWRGD_P3V3_STBY")
	)
	(segment
		(start 456.80503 -20.893024)
		(end 456.807316 -20.893024)
		(width 0.10795)
		(layer "F.Cu")
		(net "PWRGD_P3V3_STBY")
	)
	(segment
		(start 464.0834 -20.7264)
		(end 464.3755 -20.4343)
		(width 0.10795)
		(layer "F.Cu")
		(net "PWRGD_P3V3_STBY")
	)
	(segment
		(start 404.27402 -150.7998)
		(end 404.605236 -150.468584)
		(width 0.10795)
		(layer "F.Cu")
		(net "PWRGD_P3V3_STBY")
	)
	(segment
		(start 464.3755 -20.4343)
		(end 464.7946 -20.4343)
		(width 0.10795)
		(layer "F.Cu")
		(net "PWRGD_P3V3_STBY")
	)
	(segment
		(start 369.545108 -76.694792)
		(end 369.944904 -76.294996)
		(width 0.10795)
		(layer "F.Cu")
		(net "PWRGD_P3V3_STBY")
	)
	(segment
		(start 404.605236 -150.468584)
		(end 405.283416 -150.468584)
		(width 0.10795)
		(layer "F.Cu")
		(net "PWRGD_P3V3_STBY")
	)
	(segment
		(start 474.7895 -28.60802)
		(end 474.226128 -28.60802)
		(width 0.10795)
		(layer "F.Cu")
		(net "PWRGD_P3V3_STBY")
	)
	(segment
		(start 456.80503 -20.89531)
		(end 456.80503 -20.893024)
		(width 0.10795)
		(layer "F.Cu")
		(net "PWRGD_P3V3_STBY")
	)
	(via
		(at 454.206864 -15.036038)
		(size 0.508)
		(drill 0.254)
		(layers "F.Cu" "B.Cu")
		(net "PWRGD_P3V3_STBY")
	)
	(via
		(at 372.769638 -92.202)
		(size 0.508)
		(drill 0.254)
		(layers "F.Cu" "B.Cu")
		(net "PWRGD_P3V3_STBY")
	)
	(via
		(at 369.545108 -76.694792)
		(size 0.4572)
		(drill 0.2032)
		(layers "F.Cu" "B.Cu")
		(net "PWRGD_P3V3_STBY")
	)
	(via
		(at 373.036846 -144.783048)
		(size 0.508)
		(drill 0.254)
		(layers "F.Cu" "B.Cu")
		(net "PWRGD_P3V3_STBY")
	)
	(via
		(at 474.117924 -27.931618)
		(size 0.508)
		(drill 0.254)
		(layers "F.Cu" "B.Cu")
		(net "PWRGD_P3V3_STBY")
	)
	(via
		(at 464.0834 -20.7264)
		(size 0.508)
		(drill 0.254)
		(layers "F.Cu" "B.Cu")
		(net "PWRGD_P3V3_STBY")
	)
	(via
		(at 456.807316 -20.893024)
		(size 0.508)
		(drill 0.254)
		(layers "F.Cu" "B.Cu")
		(net "PWRGD_P3V3_STBY")
	)
	(via
		(at 443.624208 -9.8806)
		(size 0.508)
		(drill 0.254)
		(layers "F.Cu" "B.Cu")
		(net "PWRGD_P3V3_STBY")
	)
	(via
		(at 421.879776 -9.337294)
		(size 0.508)
		(drill 0.254)
		(layers "F.Cu" "B.Cu")
		(net "PWRGD_P3V3_STBY")
	)
	(via
		(at 404.605236 -150.468584)
		(size 0.508)
		(drill 0.254)
		(layers "F.Cu" "B.Cu")
		(net "PWRGD_P3V3_STBY")
	)
	(via
		(at 380.298198 -55.189374)
		(size 0.508)
		(drill 0.254)
		(layers "F.Cu" "B.Cu")
		(net "PWRGD_P3V3_STBY")
	)
	(via
		(at 374.367044 -8.93699)
		(size 0.6604)
		(drill 0.3302)
		(layers "F.Cu" "B.Cu")
		(net "PWRGD_P3V3_STBY")
	)
	(via
		(at 373.598948 -9.705086)
		(size 0.508)
		(drill 0.254)
		(layers "F.Cu" "B.Cu")
		(net "PWRGD_P3V3_STBY")
	)
	(segment
		(start 464.0834 -21.4122)
		(end 464.0834 -20.7264)
		(width 0.10795)
		(layer "B.Cu")
		(net "PWRGD_P3V3_STBY")
	)
	(segment
		(start 380.381002 -6.791198)
		(end 380.381002 -1.31191)
		(width 0.10795)
		(layer "B.Cu")
		(net "PWRGD_P3V3_STBY")
	)
	(segment
		(start 463.55 -23.235666)
		(end 463.55 -21.9456)
		(width 0.10795)
		(layer "B.Cu")
		(net "PWRGD_P3V3_STBY")
	)
	(segment
		(start 397.952722 5.1054)
		(end 393.7254 5.1054)
		(width 0.10795)
		(layer "B.Cu")
		(net "PWRGD_P3V3_STBY")
	)
	(segment
		(start 418.18814 -5.6515)
		(end 417.576 -5.6515)
		(width 0.10795)
		(layer "B.Cu")
		(net "PWRGD_P3V3_STBY")
	)
	(segment
		(start 376.065034 -7.239)
		(end 379.9332 -7.239)
		(width 0.10795)
		(layer "B.Cu")
		(net "PWRGD_P3V3_STBY")
	)
	(segment
		(start 472.294712 -26.162)
		(end 468.704422 -26.162)
		(width 0.10795)
		(layer "B.Cu")
		(net "PWRGD_P3V3_STBY")
	)
	(segment
		(start 419.124384 -4.191)
		(end 419.282118 -4.033266)
		(width 0.10795)
		(layer "B.Cu")
		(net "PWRGD_P3V3_STBY")
	)
	(segment
		(start 418.614098 -6.589014)
		(end 418.384228 -6.359144)
		(width 0.10795)
		(layer "B.Cu")
		(net "PWRGD_P3V3_STBY")
	)
	(segment
		(start 419.282118 -4.033266)
		(end 419.282118 -3.337814)
		(width 0.10795)
		(layer "B.Cu")
		(net "PWRGD_P3V3_STBY")
	)
	(segment
		(start 417.576 -4.395724)
		(end 417.576 -5.6515)
		(width 0.10795)
		(layer "B.Cu")
		(net "PWRGD_P3V3_STBY")
	)
	(segment
		(start 419.282118 -3.337814)
		(end 416.249104 -0.3048)
		(width 0.10795)
		(layer "B.Cu")
		(net "PWRGD_P3V3_STBY")
	)
	(segment
		(start 457.408534 -21.494242)
		(end 457.533756 -21.494242)
		(width 0.10795)
		(layer "B.Cu")
		(net "PWRGD_P3V3_STBY")
	)
	(segment
		(start 411.05455 4.953)
		(end 411.034992 4.953)
		(width 0.10795)
		(layer "B.Cu")
		(net "PWRGD_P3V3_STBY")
	)
	(segment
		(start 412.198566 3.808984)
		(end 411.05455 4.953)
		(width 0.10795)
		(layer "B.Cu")
		(net "PWRGD_P3V3_STBY")
	)
	(segment
		(start 397.971772 5.08635)
		(end 397.952722 5.1054)
		(width 0.10795)
		(layer "B.Cu")
		(net "PWRGD_P3V3_STBY")
	)
	(segment
		(start 385.099814 -0.17145)
		(end 389.503666 -0.17145)
		(width 0.10795)
		(layer "B.Cu")
		(net "PWRGD_P3V3_STBY")
	)
	(segment
		(start 474.06433 -27.931618)
		(end 472.294712 -26.162)
		(width 0.10795)
		(layer "B.Cu")
		(net "PWRGD_P3V3_STBY")
	)
	(segment
		(start 419.4175 -6.589014)
		(end 420.101014 -6.589014)
		(width 0.10795)
		(layer "B.Cu")
		(net "PWRGD_P3V3_STBY")
	)
	(segment
		(start 456.597512 -19.627342)
		(end 456.597512 -20.437856)
		(width 0.10795)
		(layer "B.Cu")
		(net "PWRGD_P3V3_STBY")
	)
	(segment
		(start 420.995348 -8.89)
		(end 421.432482 -8.89)
		(width 0.10795)
		(layer "B.Cu")
		(net "PWRGD_P3V3_STBY")
	)
	(segment
		(start 410.901642 5.08635)
		(end 397.971772 5.08635)
		(width 0.10795)
		(layer "B.Cu")
		(net "PWRGD_P3V3_STBY")
	)
	(segment
		(start 463.08518 -26.53284)
		(end 463.08518 -23.700486)
		(width 0.10795)
		(layer "B.Cu")
		(net "PWRGD_P3V3_STBY")
	)
	(segment
		(start 456.597512 -20.437856)
		(end 456.807316 -20.64766)
		(width 0.10795)
		(layer "B.Cu")
		(net "PWRGD_P3V3_STBY")
	)
	(segment
		(start 373.598948 -9.705086)
		(end 374.367044 -8.93699)
		(width 0.10795)
		(layer "B.Cu")
		(net "PWRGD_P3V3_STBY")
	)
	(segment
		(start 412.198566 3.173222)
		(end 412.198566 3.808984)
		(width 0.10795)
		(layer "B.Cu")
		(net "PWRGD_P3V3_STBY")
	)
	(segment
		(start 454.5711 -16.415766)
		(end 455.088498 -16.933164)
		(width 0.10795)
		(layer "B.Cu")
		(net "PWRGD_P3V3_STBY")
	)
	(segment
		(start 379.9332 -7.239)
		(end 380.381002 -6.791198)
		(width 0.10795)
		(layer "B.Cu")
		(net "PWRGD_P3V3_STBY")
	)
	(segment
		(start 463.55 -21.9456)
		(end 464.0834 -21.4122)
		(width 0.10795)
		(layer "B.Cu")
		(net "PWRGD_P3V3_STBY")
	)
	(segment
		(start 455.088498 -16.933164)
		(end 455.088498 -18.118328)
		(width 0.10795)
		(layer "B.Cu")
		(net "PWRGD_P3V3_STBY")
	)
	(segment
		(start 416.249104 -0.3048)
		(end 415.676588 -0.3048)
		(width 0.10795)
		(layer "B.Cu")
		(net "PWRGD_P3V3_STBY")
	)
	(segment
		(start 455.088498 -18.118328)
		(end 456.597512 -19.627342)
		(width 0.10795)
		(layer "B.Cu")
		(net "PWRGD_P3V3_STBY")
	)
	(segment
		(start 463.418174 -26.865834)
		(end 463.08518 -26.53284)
		(width 0.10795)
		(layer "B.Cu")
		(net "PWRGD_P3V3_STBY")
	)
	(segment
		(start 468.704422 -26.162)
		(end 468.000588 -26.865834)
		(width 0.10795)
		(layer "B.Cu")
		(net "PWRGD_P3V3_STBY")
	)
	(segment
		(start 411.034992 4.953)
		(end 410.901642 5.08635)
		(width 0.10795)
		(layer "B.Cu")
		(net "PWRGD_P3V3_STBY")
	)
	(segment
		(start 417.780724 -4.191)
		(end 417.576 -4.395724)
		(width 0.10795)
		(layer "B.Cu")
		(net "PWRGD_P3V3_STBY")
	)
	(segment
		(start 418.465 -4.191)
		(end 419.124384 -4.191)
		(width 0.10795)
		(layer "B.Cu")
		(net "PWRGD_P3V3_STBY")
	)
	(segment
		(start 454.5711 -15.400274)
		(end 454.5711 -16.415766)
		(width 0.10795)
		(layer "B.Cu")
		(net "PWRGD_P3V3_STBY")
	)
	(segment
		(start 456.807316 -20.893024)
		(end 457.408534 -21.494242)
		(width 0.10795)
		(layer "B.Cu")
		(net "PWRGD_P3V3_STBY")
	)
	(segment
		(start 454.206864 -15.036038)
		(end 454.5711 -15.400274)
		(width 0.10795)
		(layer "B.Cu")
		(net "PWRGD_P3V3_STBY")
	)
	(segment
		(start 468.000588 -26.865834)
		(end 463.418174 -26.865834)
		(width 0.10795)
		(layer "B.Cu")
		(net "PWRGD_P3V3_STBY")
	)
	(segment
		(start 374.367044 -8.93699)
		(end 376.065034 -7.239)
		(width 0.10795)
		(layer "B.Cu")
		(net "PWRGD_P3V3_STBY")
	)
	(segment
		(start 463.08518 -23.700486)
		(end 463.55 -23.235666)
		(width 0.10795)
		(layer "B.Cu")
		(net "PWRGD_P3V3_STBY")
	)
	(segment
		(start 382.551178 0.858266)
		(end 384.070098 0.858266)
		(width 0.10795)
		(layer "B.Cu")
		(net "PWRGD_P3V3_STBY")
	)
	(segment
		(start 474.117924 -27.931618)
		(end 474.06433 -27.931618)
		(width 0.10795)
		(layer "B.Cu")
		(net "PWRGD_P3V3_STBY")
	)
	(segment
		(start 418.384228 -5.847588)
		(end 418.18814 -5.6515)
		(width 0.10795)
		(layer "B.Cu")
		(net "PWRGD_P3V3_STBY")
	)
	(segment
		(start 389.503666 -0.17145)
		(end 392.43 2.754884)
		(width 0.10795)
		(layer "B.Cu")
		(net "PWRGD_P3V3_STBY")
	)
	(segment
		(start 421.432482 -8.89)
		(end 421.879776 -9.337294)
		(width 0.10795)
		(layer "B.Cu")
		(net "PWRGD_P3V3_STBY")
	)
	(segment
		(start 392.43 2.754884)
		(end 392.43 3.81)
		(width 0.10795)
		(layer "B.Cu")
		(net "PWRGD_P3V3_STBY")
	)
	(segment
		(start 420.243 -8.137652)
		(end 420.995348 -8.89)
		(width 0.10795)
		(layer "B.Cu")
		(net "PWRGD_P3V3_STBY")
	)
	(segment
		(start 456.807316 -20.64766)
		(end 456.807316 -20.893024)
		(width 0.10795)
		(layer "B.Cu")
		(net "PWRGD_P3V3_STBY")
	)
	(segment
		(start 419.4175 -6.589014)
		(end 418.614098 -6.589014)
		(width 0.10795)
		(layer "B.Cu")
		(net "PWRGD_P3V3_STBY")
	)
	(segment
		(start 384.070098 0.858266)
		(end 385.099814 -0.17145)
		(width 0.10795)
		(layer "B.Cu")
		(net "PWRGD_P3V3_STBY")
	)
	(segment
		(start 415.676588 -0.3048)
		(end 412.198566 3.173222)
		(width 0.10795)
		(layer "B.Cu")
		(net "PWRGD_P3V3_STBY")
	)
	(segment
		(start 420.101014 -6.589014)
		(end 420.243 -6.731)
		(width 0.10795)
		(layer "B.Cu")
		(net "PWRGD_P3V3_STBY")
	)
	(segment
		(start 418.384228 -6.359144)
		(end 418.384228 -5.847588)
		(width 0.10795)
		(layer "B.Cu")
		(net "PWRGD_P3V3_STBY")
	)
	(segment
		(start 393.7254 5.1054)
		(end 392.43 3.81)
		(width 0.10795)
		(layer "B.Cu")
		(net "PWRGD_P3V3_STBY")
	)
	(segment
		(start 380.381002 -1.31191)
		(end 382.551178 0.858266)
		(width 0.10795)
		(layer "B.Cu")
		(net "PWRGD_P3V3_STBY")
	)
	(segment
		(start 418.465 -4.191)
		(end 417.780724 -4.191)
		(width 0.10795)
		(layer "B.Cu")
		(net "PWRGD_P3V3_STBY")
	)
	(segment
		(start 420.243 -6.731)
		(end 420.243 -8.137652)
		(width 0.10795)
		(layer "B.Cu")
		(net "PWRGD_P3V3_STBY")
	)
	(segment
		(start 377.961906 -64.572134)
		(end 379.640084 -62.893956)
		(width 0.089408)
		(layer "In2.Cu")
		(net "PWRGD_P3V3_STBY")
	)
	(segment
		(start 370.731288 -66.96583)
		(end 370.943632 -66.753486)
		(width 0.089408)
		(layer "In2.Cu")
		(net "PWRGD_P3V3_STBY")
	)
	(segment
		(start 376.521218 -66.753486)
		(end 377.961906 -65.312798)
		(width 0.089408)
		(layer "In2.Cu")
		(net "PWRGD_P3V3_STBY")
	)
	(segment
		(start 370.943632 -66.753486)
		(end 376.521218 -66.753486)
		(width 0.089408)
		(layer "In2.Cu")
		(net "PWRGD_P3V3_STBY")
	)
	(segment
		(start 369.92433 -69.387974)
		(end 370.190522 -69.121782)
		(width 0.089408)
		(layer "In2.Cu")
		(net "PWRGD_P3V3_STBY")
	)
	(segment
		(start 369.390422 -73.068688)
		(end 369.171728 -72.849994)
		(width 0.089408)
		(layer "In2.Cu")
		(net "PWRGD_P3V3_STBY")
	)
	(segment
		(start 379.906276 -56.11749)
		(end 380.298198 -55.725568)
		(width 0.089408)
		(layer "In2.Cu")
		(net "PWRGD_P3V3_STBY")
	)
	(segment
		(start 369.651026 -69.91731)
		(end 369.92433 -69.644006)
		(width 0.089408)
		(layer "In2.Cu")
		(net "PWRGD_P3V3_STBY")
	)
	(segment
		(start 464.0834 -21.1836)
		(end 464.0834 -20.7264)
		(width 0.089408)
		(layer "In2.Cu")
		(net "PWRGD_P3V3_STBY")
	)
	(segment
		(start 369.545108 -76.694792)
		(end 369.545108 -76.453492)
		(width 0.089408)
		(layer "In2.Cu")
		(net "PWRGD_P3V3_STBY")
	)
	(segment
		(start 379.640084 -62.893956)
		(end 379.640084 -56.927496)
		(width 0.089408)
		(layer "In2.Cu")
		(net "PWRGD_P3V3_STBY")
	)
	(segment
		(start 369.394994 -69.91731)
		(end 369.651026 -69.91731)
		(width 0.089408)
		(layer "In2.Cu")
		(net "PWRGD_P3V3_STBY")
	)
	(segment
		(start 369.646708 -73.068688)
		(end 369.390422 -73.068688)
		(width 0.089408)
		(layer "In2.Cu")
		(net "PWRGD_P3V3_STBY")
	)
	(segment
		(start 369.171728 -70.140576)
		(end 369.394994 -69.91731)
		(width 0.089408)
		(layer "In2.Cu")
		(net "PWRGD_P3V3_STBY")
	)
	(segment
		(start 369.918488 -73.340468)
		(end 369.646708 -73.068688)
		(width 0.089408)
		(layer "In2.Cu")
		(net "PWRGD_P3V3_STBY")
	)
	(segment
		(start 370.190522 -69.121782)
		(end 370.4463 -69.121782)
		(width 0.089408)
		(layer "In2.Cu")
		(net "PWRGD_P3V3_STBY")
	)
	(segment
		(start 370.4463 -69.121782)
		(end 370.731288 -68.836794)
		(width 0.089408)
		(layer "In2.Cu")
		(net "PWRGD_P3V3_STBY")
	)
	(segment
		(start 369.545108 -76.453492)
		(end 369.918488 -76.080112)
		(width 0.089408)
		(layer "In2.Cu")
		(net "PWRGD_P3V3_STBY")
	)
	(segment
		(start 369.918488 -76.080112)
		(end 369.918488 -73.340468)
		(width 0.089408)
		(layer "In2.Cu")
		(net "PWRGD_P3V3_STBY")
	)
	(segment
		(start 457.515976 -20.893024)
		(end 458.343 -20.066)
		(width 0.089408)
		(layer "In2.Cu")
		(net "PWRGD_P3V3_STBY")
	)
	(segment
		(start 377.961906 -65.312798)
		(end 377.961906 -64.572134)
		(width 0.089408)
		(layer "In2.Cu")
		(net "PWRGD_P3V3_STBY")
	)
	(segment
		(start 370.731288 -68.836794)
		(end 370.731288 -66.96583)
		(width 0.089408)
		(layer "In2.Cu")
		(net "PWRGD_P3V3_STBY")
	)
	(segment
		(start 463.0674 -21.6662)
		(end 463.6008 -21.6662)
		(width 0.089408)
		(layer "In2.Cu")
		(net "PWRGD_P3V3_STBY")
	)
	(segment
		(start 369.92433 -69.644006)
		(end 369.92433 -69.387974)
		(width 0.089408)
		(layer "In2.Cu")
		(net "PWRGD_P3V3_STBY")
	)
	(segment
		(start 458.343 -20.066)
		(end 461.4672 -20.066)
		(width 0.089408)
		(layer "In2.Cu")
		(net "PWRGD_P3V3_STBY")
	)
	(segment
		(start 463.6008 -21.6662)
		(end 464.0834 -21.1836)
		(width 0.089408)
		(layer "In2.Cu")
		(net "PWRGD_P3V3_STBY")
	)
	(segment
		(start 461.4672 -20.066)
		(end 463.0674 -21.6662)
		(width 0.089408)
		(layer "In2.Cu")
		(net "PWRGD_P3V3_STBY")
	)
	(segment
		(start 380.298198 -55.725568)
		(end 380.298198 -55.189374)
		(width 0.089408)
		(layer "In2.Cu")
		(net "PWRGD_P3V3_STBY")
	)
	(segment
		(start 379.906276 -56.661304)
		(end 379.906276 -56.11749)
		(width 0.089408)
		(layer "In2.Cu")
		(net "PWRGD_P3V3_STBY")
	)
	(segment
		(start 369.171728 -72.849994)
		(end 369.171728 -70.140576)
		(width 0.089408)
		(layer "In2.Cu")
		(net "PWRGD_P3V3_STBY")
	)
	(segment
		(start 456.807316 -20.893024)
		(end 457.515976 -20.893024)
		(width 0.089408)
		(layer "In2.Cu")
		(net "PWRGD_P3V3_STBY")
	)
	(segment
		(start 379.640084 -56.927496)
		(end 379.906276 -56.661304)
		(width 0.089408)
		(layer "In2.Cu")
		(net "PWRGD_P3V3_STBY")
	)
	(segment
		(start 373.036846 -145.280126)
		(end 373.036846 -144.783048)
		(width 0.089408)
		(layer "In4.Cu")
		(net "PWRGD_P3V3_STBY")
	)
	(segment
		(start 454.206864 -15.036038)
		(end 454.206864 -14.71676)
		(width 0.089408)
		(layer "In4.Cu")
		(net "PWRGD_P3V3_STBY")
	)
	(segment
		(start 396.002256 -147.96516)
		(end 392.81608 -147.96516)
		(width 0.089408)
		(layer "In4.Cu")
		(net "PWRGD_P3V3_STBY")
	)
	(segment
		(start 392.815826 -147.964906)
		(end 392.25982 -147.964906)
		(width 0.089408)
		(layer "In4.Cu")
		(net "PWRGD_P3V3_STBY")
	)
	(segment
		(start 397.25346 -149.216364)
		(end 396.002256 -147.96516)
		(width 0.089408)
		(layer "In4.Cu")
		(net "PWRGD_P3V3_STBY")
	)
	(segment
		(start 404.605236 -150.468584)
		(end 401.702016 -150.468584)
		(width 0.089408)
		(layer "In4.Cu")
		(net "PWRGD_P3V3_STBY")
	)
	(segment
		(start 389.269224 -144.97431)
		(end 386.612384 -144.97431)
		(width 0.089408)
		(layer "In4.Cu")
		(net "PWRGD_P3V3_STBY")
	)
	(segment
		(start 392.81608 -147.96516)
		(end 392.815826 -147.964906)
		(width 0.089408)
		(layer "In4.Cu")
		(net "PWRGD_P3V3_STBY")
	)
	(segment
		(start 392.25982 -147.964906)
		(end 389.269224 -144.97431)
		(width 0.089408)
		(layer "In4.Cu")
		(net "PWRGD_P3V3_STBY")
	)
	(segment
		(start 401.702016 -150.468584)
		(end 400.449796 -149.216364)
		(width 0.089408)
		(layer "In4.Cu")
		(net "PWRGD_P3V3_STBY")
	)
	(segment
		(start 454.206864 -14.71676)
		(end 449.950586 -10.460482)
		(width 0.089408)
		(layer "In4.Cu")
		(net "PWRGD_P3V3_STBY")
	)
	(segment
		(start 386.612384 -144.97431)
		(end 384.753866 -146.832828)
		(width 0.089408)
		(layer "In4.Cu")
		(net "PWRGD_P3V3_STBY")
	)
	(segment
		(start 444.20409 -10.460482)
		(end 443.624208 -9.8806)
		(width 0.089408)
		(layer "In4.Cu")
		(net "PWRGD_P3V3_STBY")
	)
	(segment
		(start 449.950586 -10.460482)
		(end 444.20409 -10.460482)
		(width 0.089408)
		(layer "In4.Cu")
		(net "PWRGD_P3V3_STBY")
	)
	(segment
		(start 374.589548 -146.832828)
		(end 373.036846 -145.280126)
		(width 0.089408)
		(layer "In4.Cu")
		(net "PWRGD_P3V3_STBY")
	)
	(segment
		(start 384.753866 -146.832828)
		(end 374.589548 -146.832828)
		(width 0.089408)
		(layer "In4.Cu")
		(net "PWRGD_P3V3_STBY")
	)
	(segment
		(start 400.449796 -149.216364)
		(end 397.25346 -149.216364)
		(width 0.089408)
		(layer "In4.Cu")
		(net "PWRGD_P3V3_STBY")
	)
	(segment
		(start 380.40437 -104.864662)
		(end 380.70663 -105.166922)
		(width 0.089408)
		(layer "In9.Cu")
		(net "PWRGD_P3V3_STBY")
	)
	(segment
		(start 378.431044 -116.554504)
		(end 377.665996 -116.554504)
		(width 0.089408)
		(layer "In9.Cu")
		(net "PWRGD_P3V3_STBY")
	)
	(segment
		(start 372.47322 -130.227832)
		(end 370.71046 -131.990592)
		(width 0.089408)
		(layer "In9.Cu")
		(net "PWRGD_P3V3_STBY")
	)
	(segment
		(start 376.67946 -98.77806)
		(end 376.737118 -98.720402)
		(width 0.089408)
		(layer "In9.Cu")
		(net "PWRGD_P3V3_STBY")
	)
	(segment
		(start 369.757706 -132.688838)
		(end 369.757706 -137.79754)
		(width 0.089408)
		(layer "In9.Cu")
		(net "PWRGD_P3V3_STBY")
	)
	(segment
		(start 380.21133 -112.066324)
		(end 379.75794 -112.519714)
		(width 0.089408)
		(layer "In9.Cu")
		(net "PWRGD_P3V3_STBY")
	)
	(segment
		(start 379.90907 -108.600748)
		(end 379.90907 -109.61751)
		(width 0.089408)
		(layer "In9.Cu")
		(net "PWRGD_P3V3_STBY")
	)
	(segment
		(start 373.39397 -124.331222)
		(end 373.046244 -124.678948)
		(width 0.089408)
		(layer "In9.Cu")
		(net "PWRGD_P3V3_STBY")
	)
	(segment
		(start 374.70334 -96.22028)
		(end 373.956326 -96.22028)
		(width 0.089408)
		(layer "In9.Cu")
		(net "PWRGD_P3V3_STBY")
	)
	(segment
		(start 373.776494 -123.95454)
		(end 373.770398 -123.95454)
		(width 0.089408)
		(layer "In9.Cu")
		(net "PWRGD_P3V3_STBY")
	)
	(segment
		(start 377.04522 -98.43262)
		(end 377.805442 -98.43262)
		(width 0.089408)
		(layer "In9.Cu")
		(net "PWRGD_P3V3_STBY")
	)
	(segment
		(start 373.536718 -96.639888)
		(end 373.536718 -97.787968)
		(width 0.089408)
		(layer "In9.Cu")
		(net "PWRGD_P3V3_STBY")
	)
	(segment
		(start 380.21133 -108.298488)
		(end 379.90907 -108.600748)
		(width 0.089408)
		(layer "In9.Cu")
		(net "PWRGD_P3V3_STBY")
	)
	(segment
		(start 379.90907 -109.61751)
		(end 380.21133 -109.91977)
		(width 0.089408)
		(layer "In9.Cu")
		(net "PWRGD_P3V3_STBY")
	)
	(segment
		(start 379.4125 -101.018086)
		(end 379.4125 -101.050852)
		(width 0.0889)
		(layer "In9.Cu")
		(net "PWRGD_P3V3_STBY")
	)
	(segment
		(start 379.90907 -111.33455)
		(end 380.21133 -111.63681)
		(width 0.089408)
		(layer "In9.Cu")
		(net "PWRGD_P3V3_STBY")
	)
	(segment
		(start 380.70663 -105.166922)
		(end 380.70663 -106.002836)
		(width 0.089408)
		(layer "In9.Cu")
		(net "PWRGD_P3V3_STBY")
	)
	(segment
		(start 372.47322 -125.983492)
		(end 372.47322 -130.227832)
		(width 0.089408)
		(layer "In9.Cu")
		(net "PWRGD_P3V3_STBY")
	)
	(segment
		(start 372.12778 -143.253206)
		(end 371.887496 -143.49349)
		(width 0.089408)
		(layer "In9.Cu")
		(net "PWRGD_P3V3_STBY")
	)
	(segment
		(start 373.770398 -123.95454)
		(end 373.39397 -124.330968)
		(width 0.089408)
		(layer "In9.Cu")
		(net "PWRGD_P3V3_STBY")
	)
	(segment
		(start 371.887496 -145.083276)
		(end 372.15064 -145.34642)
		(width 0.089408)
		(layer "In9.Cu")
		(net "PWRGD_P3V3_STBY")
	)
	(segment
		(start 378.91847 -114.21237)
		(end 378.91847 -114.57559)
		(width 0.089408)
		(layer "In9.Cu")
		(net "PWRGD_P3V3_STBY")
	)
	(segment
		(start 375.501916 -98.24466)
		(end 375.6914 -98.24466)
		(width 0.089408)
		(layer "In9.Cu")
		(net "PWRGD_P3V3_STBY")
	)
	(segment
		(start 373.046244 -125.410468)
		(end 372.47322 -125.983492)
		(width 0.089408)
		(layer "In9.Cu")
		(net "PWRGD_P3V3_STBY")
	)
	(segment
		(start 379.22073 -113.438686)
		(end 379.22073 -113.91011)
		(width 0.089408)
		(layer "In9.Cu")
		(net "PWRGD_P3V3_STBY")
	)
	(segment
		(start 376.737118 -98.720402)
		(end 376.757438 -98.720402)
		(width 0.089408)
		(layer "In9.Cu")
		(net "PWRGD_P3V3_STBY")
	)
	(segment
		(start 379.89002 -107.421172)
		(end 380.21133 -107.742482)
		(width 0.089408)
		(layer "In9.Cu")
		(net "PWRGD_P3V3_STBY")
	)
	(segment
		(start 380.21133 -110.47603)
		(end 379.90907 -110.77829)
		(width 0.089408)
		(layer "In9.Cu")
		(net "PWRGD_P3V3_STBY")
	)
	(segment
		(start 370.510054 -138.549888)
		(end 370.510054 -140.84808)
		(width 0.089408)
		(layer "In9.Cu")
		(net "PWRGD_P3V3_STBY")
	)
	(segment
		(start 380.256796 -102.39375)
		(end 380.256796 -102.915466)
		(width 0.089408)
		(layer "In9.Cu")
		(net "PWRGD_P3V3_STBY")
	)
	(segment
		(start 374.99544 -94.429834)
		(end 374.99544 -95.92818)
		(width 0.089408)
		(layer "In9.Cu")
		(net "PWRGD_P3V3_STBY")
	)
	(segment
		(start 377.43257 -121.914666)
		(end 376.569224 -122.778012)
		(width 0.089408)
		(layer "In9.Cu")
		(net "PWRGD_P3V3_STBY")
	)
	(segment
		(start 373.39397 -124.330968)
		(end 373.39397 -124.331222)
		(width 0.089408)
		(layer "In9.Cu")
		(net "PWRGD_P3V3_STBY")
	)
	(segment
		(start 374.99544 -95.92818)
		(end 374.70334 -96.22028)
		(width 0.089408)
		(layer "In9.Cu")
		(net "PWRGD_P3V3_STBY")
	)
	(segment
		(start 377.851924 -119.802656)
		(end 377.43257 -120.22201)
		(width 0.089408)
		(layer "In9.Cu")
		(net "PWRGD_P3V3_STBY")
	)
	(segment
		(start 377.805442 -98.43262)
		(end 377.940062 -98.56724)
		(width 0.089408)
		(layer "In9.Cu")
		(net "PWRGD_P3V3_STBY")
	)
	(segment
		(start 380.107952 -102.244906)
		(end 380.256796 -102.39375)
		(width 0.089408)
		(layer "In9.Cu")
		(net "PWRGD_P3V3_STBY")
	)
	(segment
		(start 380.708662 -103.698548)
		(end 380.40437 -104.00284)
		(width 0.089408)
		(layer "In9.Cu")
		(net "PWRGD_P3V3_STBY")
	)
	(segment
		(start 378.72543 -116.260118)
		(end 378.431044 -116.554504)
		(width 0.089408)
		(layer "In9.Cu")
		(net "PWRGD_P3V3_STBY")
	)
	(segment
		(start 369.757706 -137.79754)
		(end 370.510054 -138.549888)
		(width 0.089408)
		(layer "In9.Cu")
		(net "PWRGD_P3V3_STBY")
	)
	(segment
		(start 378.72543 -115.79987)
		(end 378.72543 -116.260118)
		(width 0.089408)
		(layer "In9.Cu")
		(net "PWRGD_P3V3_STBY")
	)
	(segment
		(start 380.70663 -106.002836)
		(end 379.89002 -106.819446)
		(width 0.089408)
		(layer "In9.Cu")
		(net "PWRGD_P3V3_STBY")
	)
	(segment
		(start 372.473474 -145.34642)
		(end 373.036846 -144.783048)
		(width 0.089408)
		(layer "In9.Cu")
		(net "PWRGD_P3V3_STBY")
	)
	(segment
		(start 372.15064 -145.34642)
		(end 372.473474 -145.34642)
		(width 0.089408)
		(layer "In9.Cu")
		(net "PWRGD_P3V3_STBY")
	)
	(segment
		(start 370.455952 -131.990592)
		(end 369.757706 -132.688838)
		(width 0.089408)
		(layer "In9.Cu")
		(net "PWRGD_P3V3_STBY")
	)
	(segment
		(start 378.42317 -115.49761)
		(end 378.72543 -115.79987)
		(width 0.089408)
		(layer "In9.Cu")
		(net "PWRGD_P3V3_STBY")
	)
	(segment
		(start 379.9078 -101.876606)
		(end 379.9078 -101.909372)
		(width 0.0889)
		(layer "In9.Cu")
		(net "PWRGD_P3V3_STBY")
	)
	(segment
		(start 377.43257 -116.78793)
		(end 377.43257 -117.118638)
		(width 0.089408)
		(layer "In9.Cu")
		(net "PWRGD_P3V3_STBY")
	)
	(segment
		(start 380.708662 -103.367332)
		(end 380.708662 -103.698548)
		(width 0.089408)
		(layer "In9.Cu")
		(net "PWRGD_P3V3_STBY")
	)
	(segment
		(start 378.4219 -99.301046)
		(end 378.4219 -99.333812)
		(width 0.0889)
		(layer "In9.Cu")
		(net "PWRGD_P3V3_STBY")
	)
	(segment
		(start 379.75794 -112.901476)
		(end 379.22073 -113.438686)
		(width 0.089408)
		(layer "In9.Cu")
		(net "PWRGD_P3V3_STBY")
	)
	(segment
		(start 380.21133 -107.742482)
		(end 380.21133 -108.298488)
		(width 0.089408)
		(layer "In9.Cu")
		(net "PWRGD_P3V3_STBY")
	)
	(segment
		(start 380.21133 -109.91977)
		(end 380.21133 -110.47603)
		(width 0.089408)
		(layer "In9.Cu")
		(net "PWRGD_P3V3_STBY")
	)
	(segment
		(start 377.43257 -120.22201)
		(end 377.43257 -121.914666)
		(width 0.089408)
		(layer "In9.Cu")
		(net "PWRGD_P3V3_STBY")
	)
	(segment
		(start 373.046244 -124.678948)
		(end 373.046244 -125.410468)
		(width 0.089408)
		(layer "In9.Cu")
		(net "PWRGD_P3V3_STBY")
	)
	(segment
		(start 373.536718 -97.787968)
		(end 373.882158 -98.133408)
		(width 0.089408)
		(layer "In9.Cu")
		(net "PWRGD_P3V3_STBY")
	)
	(segment
		(start 378.42317 -115.07089)
		(end 378.42317 -115.49761)
		(width 0.089408)
		(layer "In9.Cu")
		(net "PWRGD_P3V3_STBY")
	)
	(segment
		(start 378.9172 -100.159566)
		(end 378.9172 -100.192332)
		(width 0.0889)
		(layer "In9.Cu")
		(net "PWRGD_P3V3_STBY")
	)
	(segment
		(start 376.757438 -98.720402)
		(end 377.04522 -98.43262)
		(width 0.089408)
		(layer "In9.Cu")
		(net "PWRGD_P3V3_STBY")
	)
	(segment
		(start 377.665996 -116.554504)
		(end 377.43257 -116.78793)
		(width 0.089408)
		(layer "In9.Cu")
		(net "PWRGD_P3V3_STBY")
	)
	(segment
		(start 371.887496 -143.49349)
		(end 371.887496 -145.083276)
		(width 0.089408)
		(layer "In9.Cu")
		(net "PWRGD_P3V3_STBY")
	)
	(segment
		(start 372.12778 -142.465806)
		(end 372.12778 -143.253206)
		(width 0.089408)
		(layer "In9.Cu")
		(net "PWRGD_P3V3_STBY")
	)
	(segment
		(start 372.769638 -92.202)
		(end 374.99544 -94.429834)
		(width 0.089408)
		(layer "In9.Cu")
		(net "PWRGD_P3V3_STBY")
	)
	(segment
		(start 378.91847 -114.57559)
		(end 378.42317 -115.07089)
		(width 0.089408)
		(layer "In9.Cu")
		(net "PWRGD_P3V3_STBY")
	)
	(segment
		(start 375.6914 -98.24466)
		(end 376.2248 -98.77806)
		(width 0.089408)
		(layer "In9.Cu")
		(net "PWRGD_P3V3_STBY")
	)
	(segment
		(start 380.40437 -104.00284)
		(end 380.40437 -104.864662)
		(width 0.089408)
		(layer "In9.Cu")
		(net "PWRGD_P3V3_STBY")
	)
	(segment
		(start 376.2248 -98.77806)
		(end 376.67946 -98.77806)
		(width 0.089408)
		(layer "In9.Cu")
		(net "PWRGD_P3V3_STBY")
	)
	(segment
		(start 377.43257 -117.118638)
		(end 377.851924 -117.537992)
		(width 0.089408)
		(layer "In9.Cu")
		(net "PWRGD_P3V3_STBY")
	)
	(segment
		(start 373.882158 -98.133408)
		(end 375.390664 -98.133408)
		(width 0.089408)
		(layer "In9.Cu")
		(net "PWRGD_P3V3_STBY")
	)
	(segment
		(start 380.21133 -111.63681)
		(end 380.21133 -112.066324)
		(width 0.089408)
		(layer "In9.Cu")
		(net "PWRGD_P3V3_STBY")
	)
	(segment
		(start 376.569224 -122.778012)
		(end 374.953022 -122.778012)
		(width 0.089408)
		(layer "In9.Cu")
		(net "PWRGD_P3V3_STBY")
	)
	(segment
		(start 370.71046 -131.990592)
		(end 370.455952 -131.990592)
		(width 0.089408)
		(layer "In9.Cu")
		(net "PWRGD_P3V3_STBY")
	)
	(segment
		(start 375.390664 -98.133408)
		(end 375.501916 -98.24466)
		(width 0.089408)
		(layer "In9.Cu")
		(net "PWRGD_P3V3_STBY")
	)
	(segment
		(start 370.510054 -140.84808)
		(end 372.12778 -142.465806)
		(width 0.089408)
		(layer "In9.Cu")
		(net "PWRGD_P3V3_STBY")
	)
	(segment
		(start 379.22073 -113.91011)
		(end 378.91847 -114.21237)
		(width 0.089408)
		(layer "In9.Cu")
		(net "PWRGD_P3V3_STBY")
	)
	(segment
		(start 374.953022 -122.778012)
		(end 373.776494 -123.95454)
		(width 0.089408)
		(layer "In9.Cu")
		(net "PWRGD_P3V3_STBY")
	)
	(segment
		(start 379.90907 -110.77829)
		(end 379.90907 -111.33455)
		(width 0.089408)
		(layer "In9.Cu")
		(net "PWRGD_P3V3_STBY")
	)
	(segment
		(start 373.956326 -96.22028)
		(end 373.536718 -96.639888)
		(width 0.089408)
		(layer "In9.Cu")
		(net "PWRGD_P3V3_STBY")
	)
	(segment
		(start 379.75794 -112.519714)
		(end 379.75794 -112.901476)
		(width 0.089408)
		(layer "In9.Cu")
		(net "PWRGD_P3V3_STBY")
	)
	(segment
		(start 379.89002 -106.819446)
		(end 379.89002 -107.421172)
		(width 0.089408)
		(layer "In9.Cu")
		(net "PWRGD_P3V3_STBY")
	)
	(segment
		(start 380.256796 -102.915466)
		(end 380.708662 -103.367332)
		(width 0.089408)
		(layer "In9.Cu")
		(net "PWRGD_P3V3_STBY")
	)
	(segment
		(start 377.851924 -117.537992)
		(end 377.851924 -119.802656)
		(width 0.089408)
		(layer "In9.Cu")
		(net "PWRGD_P3V3_STBY")
	)
	(arc
		(start 378.9172 -100.192332)
		(mid 378.97355 -100.386182)
		(end 379.117352 -100.527866)
		(width 0.0889)
		(layer "In9.Cu")
		(net "PWRGD_P3V3_STBY")
	)
	(arc
		(start 379.117352 -100.527866)
		(mid 379.328216 -100.73487)
		(end 379.4125 -101.018086)
		(width 0.0889)
		(layer "In9.Cu")
		(net "PWRGD_P3V3_STBY")
	)
	(arc
		(start 377.940062 -98.56724)
		(mid 378.009161 -98.707603)
		(end 378.126752 -98.810826)
		(width 0.0889)
		(layer "In9.Cu")
		(net "PWRGD_P3V3_STBY")
	)
	(arc
		(start 379.612652 -101.386386)
		(mid 379.823516 -101.59339)
		(end 379.9078 -101.876606)
		(width 0.0889)
		(layer "In9.Cu")
		(net "PWRGD_P3V3_STBY")
	)
	(arc
		(start 379.9078 -101.909372)
		(mid 379.96415 -102.103222)
		(end 380.107952 -102.244906)
		(width 0.0889)
		(layer "In9.Cu")
		(net "PWRGD_P3V3_STBY")
	)
	(arc
		(start 378.126752 -98.810826)
		(mid 378.337616 -99.01783)
		(end 378.4219 -99.301046)
		(width 0.0889)
		(layer "In9.Cu")
		(net "PWRGD_P3V3_STBY")
	)
	(arc
		(start 378.622052 -99.669346)
		(mid 378.832916 -99.87635)
		(end 378.9172 -100.159566)
		(width 0.0889)
		(layer "In9.Cu")
		(net "PWRGD_P3V3_STBY")
	)
	(arc
		(start 378.4219 -99.333812)
		(mid 378.47825 -99.527662)
		(end 378.622052 -99.669346)
		(width 0.0889)
		(layer "In9.Cu")
		(net "PWRGD_P3V3_STBY")
	)
	(arc
		(start 379.4125 -101.050852)
		(mid 379.46885 -101.244702)
		(end 379.612652 -101.386386)
		(width 0.0889)
		(layer "In9.Cu")
		(net "PWRGD_P3V3_STBY")
	)
	(segment
		(start 440.309 -8.509)
		(end 441.325 -9.525)
		(width 0.089408)
		(layer "In11.Cu")
		(net "PWRGD_P3V3_STBY")
	)
	(segment
		(start 429.171862 -8.870696)
		(end 429.533558 -8.509)
		(width 0.089408)
		(layer "In11.Cu")
		(net "PWRGD_P3V3_STBY")
	)
	(segment
		(start 373.598948 -15.581122)
		(end 373.598948 -9.705086)
		(width 0.089408)
		(layer "In11.Cu")
		(net "PWRGD_P3V3_STBY")
	)
	(segment
		(start 372.8974 -88.8238)
		(end 372.8974 -92.074238)
		(width 0.089408)
		(layer "In11.Cu")
		(net "PWRGD_P3V3_STBY")
	)
	(segment
		(start 368.028982 -29.156914)
		(end 368.028982 -21.151088)
		(width 0.089408)
		(layer "In11.Cu")
		(net "PWRGD_P3V3_STBY")
	)
	(segment
		(start 377.750832 -53.5686)
		(end 373.762524 -49.580292)
		(width 0.089408)
		(layer "In11.Cu")
		(net "PWRGD_P3V3_STBY")
	)
	(segment
		(start 443.268608 -9.525)
		(end 443.624208 -9.8806)
		(width 0.089408)
		(layer "In11.Cu")
		(net "PWRGD_P3V3_STBY")
	)
	(segment
		(start 368.028982 -21.151088)
		(end 373.598948 -15.581122)
		(width 0.089408)
		(layer "In11.Cu")
		(net "PWRGD_P3V3_STBY")
	)
	(segment
		(start 371.355112 -47.784004)
		(end 371.355112 -47.124112)
		(width 0.089408)
		(layer "In11.Cu")
		(net "PWRGD_P3V3_STBY")
	)
	(segment
		(start 441.325 -9.525)
		(end 443.268608 -9.525)
		(width 0.089408)
		(layer "In11.Cu")
		(net "PWRGD_P3V3_STBY")
	)
	(segment
		(start 369.27282 -34.371534)
		(end 369.27282 -30.400752)
		(width 0.089408)
		(layer "In11.Cu")
		(net "PWRGD_P3V3_STBY")
	)
	(segment
		(start 369.062 -41.81348)
		(end 368.77752 -41.529)
		(width 0.089408)
		(layer "In11.Cu")
		(net "PWRGD_P3V3_STBY")
	)
	(segment
		(start 369.964716 -77.1144)
		(end 369.964716 -82.802476)
		(width 0.089408)
		(layer "In11.Cu")
		(net "PWRGD_P3V3_STBY")
	)
	(segment
		(start 422.346374 -8.870696)
		(end 429.171862 -8.870696)
		(width 0.089408)
		(layer "In11.Cu")
		(net "PWRGD_P3V3_STBY")
	)
	(segment
		(start 373.762524 -49.580292)
		(end 373.1514 -49.580292)
		(width 0.089408)
		(layer "In11.Cu")
		(net "PWRGD_P3V3_STBY")
	)
	(segment
		(start 372.8974 -92.074238)
		(end 372.769638 -92.202)
		(width 0.089408)
		(layer "In11.Cu")
		(net "PWRGD_P3V3_STBY")
	)
	(segment
		(start 369.545108 -76.694792)
		(end 369.964716 -77.1144)
		(width 0.089408)
		(layer "In11.Cu")
		(net "PWRGD_P3V3_STBY")
	)
	(segment
		(start 368.77752 -41.529)
		(end 368.77752 -40.43172)
		(width 0.089408)
		(layer "In11.Cu")
		(net "PWRGD_P3V3_STBY")
	)
	(segment
		(start 372.205758 -88.132158)
		(end 372.8974 -88.8238)
		(width 0.089408)
		(layer "In11.Cu")
		(net "PWRGD_P3V3_STBY")
	)
	(segment
		(start 380.298198 -55.189374)
		(end 380.298198 -55.046372)
		(width 0.089408)
		(layer "In11.Cu")
		(net "PWRGD_P3V3_STBY")
	)
	(segment
		(start 380.298198 -55.046372)
		(end 378.820426 -53.5686)
		(width 0.089408)
		(layer "In11.Cu")
		(net "PWRGD_P3V3_STBY")
	)
	(segment
		(start 369.27282 -30.400752)
		(end 368.028982 -29.156914)
		(width 0.089408)
		(layer "In11.Cu")
		(net "PWRGD_P3V3_STBY")
	)
	(segment
		(start 368.77752 -40.43172)
		(end 369.70843 -39.50081)
		(width 0.089408)
		(layer "In11.Cu")
		(net "PWRGD_P3V3_STBY")
	)
	(segment
		(start 369.75923 -45.52823)
		(end 369.75923 -43.24731)
		(width 0.089408)
		(layer "In11.Cu")
		(net "PWRGD_P3V3_STBY")
	)
	(segment
		(start 369.75923 -43.24731)
		(end 369.062 -42.55008)
		(width 0.089408)
		(layer "In11.Cu")
		(net "PWRGD_P3V3_STBY")
	)
	(segment
		(start 369.062 -42.55008)
		(end 369.062 -41.81348)
		(width 0.089408)
		(layer "In11.Cu")
		(net "PWRGD_P3V3_STBY")
	)
	(segment
		(start 369.70843 -34.807144)
		(end 369.27282 -34.371534)
		(width 0.089408)
		(layer "In11.Cu")
		(net "PWRGD_P3V3_STBY")
	)
	(segment
		(start 421.879776 -9.337294)
		(end 422.346374 -8.870696)
		(width 0.089408)
		(layer "In11.Cu")
		(net "PWRGD_P3V3_STBY")
	)
	(segment
		(start 378.820426 -53.5686)
		(end 377.750832 -53.5686)
		(width 0.089408)
		(layer "In11.Cu")
		(net "PWRGD_P3V3_STBY")
	)
	(segment
		(start 373.1514 -49.580292)
		(end 371.355112 -47.784004)
		(width 0.089408)
		(layer "In11.Cu")
		(net "PWRGD_P3V3_STBY")
	)
	(segment
		(start 371.355112 -47.124112)
		(end 369.75923 -45.52823)
		(width 0.089408)
		(layer "In11.Cu")
		(net "PWRGD_P3V3_STBY")
	)
	(segment
		(start 369.964716 -82.802476)
		(end 372.205758 -85.043518)
		(width 0.089408)
		(layer "In11.Cu")
		(net "PWRGD_P3V3_STBY")
	)
	(segment
		(start 372.205758 -85.043518)
		(end 372.205758 -88.132158)
		(width 0.089408)
		(layer "In11.Cu")
		(net "PWRGD_P3V3_STBY")
	)
	(segment
		(start 369.70843 -39.50081)
		(end 369.70843 -34.807144)
		(width 0.089408)
		(layer "In11.Cu")
		(net "PWRGD_P3V3_STBY")
	)
	(segment
		(start 429.533558 -8.509)
		(end 440.309 -8.509)
		(width 0.089408)
		(layer "In11.Cu")
		(net "PWRGD_P3V3_STBY")
	)
	(segment
		(start 463.334608 -39.513002)
		(end 463.907378 -39.513002)
		(width 0.254)
		(layer "F.Cu")
		(net "PWRGD_P1V2_BMC_STBY")
	)
	(segment
		(start 463.003392 -37.956998)
		(end 463.279998 -37.956998)
		(width 0.254)
		(layer "F.Cu")
		(net "PWRGD_P1V2_BMC_STBY")
	)
	(segment
		(start 463.907378 -39.513002)
		(end 464.55584 -38.86454)
		(width 0.254)
		(layer "F.Cu")
		(net "PWRGD_P1V2_BMC_STBY")
	)
	(segment
		(start 464.32597 -38.63467)
		(end 464.55584 -38.86454)
		(width 0.254)
		(layer "F.Cu")
		(net "PWRGD_P1V2_BMC_STBY")
	)
	(segment
		(start 463.279998 -37.956998)
		(end 463.95767 -38.63467)
		(width 0.254)
		(layer "F.Cu")
		(net "PWRGD_P1V2_BMC_STBY")
	)
	(segment
		(start 463.95767 -38.63467)
		(end 464.32597 -38.63467)
		(width 0.254)
		(layer "F.Cu")
		(net "PWRGD_P1V2_BMC_STBY")
	)
	(via
		(at 464.55584 -38.86454)
		(size 0.508)
		(drill 0.254)
		(layers "F.Cu" "B.Cu")
		(net "PWRGD_P1V2_BMC_STBY")
	)
	(via
		(at 465.372958 -38.227)
		(size 0.6604)
		(drill 0.3302)
		(layers "F.Cu" "B.Cu")
		(net "PWRGD_P1V2_BMC_STBY")
	)
	(segment
		(start 464.55584 -38.86454)
		(end 464.735418 -38.86454)
		(width 0.10795)
		(layer "B.Cu")
		(net "PWRGD_P1V2_BMC_STBY")
	)
	(segment
		(start 465.995258 -37.6047)
		(end 465.372958 -38.227)
		(width 0.10795)
		(layer "B.Cu")
		(net "PWRGD_P1V2_BMC_STBY")
	)
	(segment
		(start 468.024972 -38.340792)
		(end 467.28888 -37.6047)
		(width 0.10795)
		(layer "B.Cu")
		(net "PWRGD_P1V2_BMC_STBY")
	)
	(segment
		(start 471.465402 -38.340792)
		(end 468.024972 -38.340792)
		(width 0.10795)
		(layer "B.Cu")
		(net "PWRGD_P1V2_BMC_STBY")
	)
	(segment
		(start 467.28888 -37.6047)
		(end 465.995258 -37.6047)
		(width 0.10795)
		(layer "B.Cu")
		(net "PWRGD_P1V2_BMC_STBY")
	)
	(segment
		(start 464.735418 -38.86454)
		(end 465.372958 -38.227)
		(width 0.10795)
		(layer "B.Cu")
		(net "PWRGD_P1V2_BMC_STBY")
	)
	(segment
		(start 391.735564 -115.05565)
		(end 391.73785 -115.05565)
		(width 0.254)
		(layer "F.Cu")
		(net "P1V05_PCH_STBY_WM26_PLL")
	)
	(segment
		(start 391.325862 -115.443762)
		(end 391.325862 -115.465352)
		(width 0.254)
		(layer "F.Cu")
		(net "P1V05_PCH_STBY_WM26_PLL")
	)
	(segment
		(start 389.33755 -115.05565)
		(end 389.216646 -115.6208)
		(width 0.254)
		(layer "F.Cu")
		(net "P1V05_PCH_STBY_WM26_PLL")
	)
	(segment
		(start 391.325862 -115.465352)
		(end 391.735564 -115.05565)
		(width 0.254)
		(layer "F.Cu")
		(net "P1V05_PCH_STBY_WM26_PLL")
	)
	(segment
		(start 390.93775 -115.05565)
		(end 391.325862 -115.443762)
		(width 0.254)
		(layer "F.Cu")
		(net "P1V05_PCH_STBY_WM26_PLL")
	)
	(via
		(at 389.216646 -115.6208)
		(size 0.508)
		(drill 0.254)
		(layers "F.Cu" "B.Cu")
		(net "P1V05_PCH_STBY_WM26_PLL")
	)
	(via
		(at 406.0698 -121.72315)
		(size 0.508)
		(drill 0.254)
		(layers "F.Cu" "B.Cu")
		(net "P1V05_PCH_STBY_WM26_PLL")
	)
	(via
		(at 406.795478 -121.72315)
		(size 0.508)
		(drill 0.254)
		(layers "F.Cu" "B.Cu")
		(net "P1V05_PCH_STBY_WM26_PLL")
	)
	(via
		(at 391.325862 -115.465352)
		(size 0.508)
		(drill 0.254)
		(layers "F.Cu" "B.Cu")
		(net "P1V05_PCH_STBY_WM26_PLL")
	)
	(segment
		(start 388.72795 -115.86464)
		(end 388.23265 -116.094764)
		(width 0.254)
		(layer "F.Cu")
		(net "P1V05_PCH_STBY_WM20_PLL")
	)
	(segment
		(start 388.23265 -116.094764)
		(end 387.73735 -115.86464)
		(width 0.254)
		(layer "F.Cu")
		(net "P1V05_PCH_STBY_WM20_PLL")
	)
	(via
		(at 388.23265 -116.094764)
		(size 0.508)
		(drill 0.254)
		(layers "F.Cu" "B.Cu")
		(net "P1V05_PCH_STBY_WM20_PLL")
	)
	(via
		(at 401.02536 -120.186704)
		(size 0.6604)
		(drill 0.3302)
		(layers "F.Cu" "B.Cu")
		(net "P1V05_PCH_STBY_WM20_PLL")
	)
	(segment
		(start 393.18565 -111.57204)
		(end 393.478512 -111.864902)
		(width 0.12446)
		(layer "F.Cu")
		(net "P1V05_PCH_STBY_KR_PLL")
	)
	(segment
		(start 393.18565 -111.57204)
		(end 393.478512 -111.279178)
		(width 0.12446)
		(layer "F.Cu")
		(net "P1V05_PCH_STBY_KR_PLL")
	)
	(segment
		(start 393.911074 -110.943644)
		(end 394.17625 -110.943644)
		(width 0.12446)
		(layer "F.Cu")
		(net "P1V05_PCH_STBY_KR_PLL")
	)
	(segment
		(start 392.53795 -111.85525)
		(end 392.830812 -112.148112)
		(width 0.12446)
		(layer "F.Cu")
		(net "P1V05_PCH_STBY_KR_PLL")
	)
	(segment
		(start 392.892788 -111.279178)
		(end 393.18565 -111.57204)
		(width 0.12446)
		(layer "F.Cu")
		(net "P1V05_PCH_STBY_KR_PLL")
	)
	(segment
		(start 392.53795 -111.85525)
		(end 392.1379 -112.2553)
		(width 0.12446)
		(layer "F.Cu")
		(net "P1V05_PCH_STBY_KR_PLL")
	)
	(segment
		(start 393.18565 -111.57204)
		(end 392.94562 -111.81207)
		(width 0.12446)
		(layer "F.Cu")
		(net "P1V05_PCH_STBY_KR_PLL")
	)
	(segment
		(start 393.68095 -110.71352)
		(end 393.911074 -110.943644)
		(width 0.12446)
		(layer "F.Cu")
		(net "P1V05_PCH_STBY_KR_PLL")
	)
	(segment
		(start 392.1633 -111.4298)
		(end 392.1633 -111.4552)
		(width 0.254)
		(layer "F.Cu")
		(net "P1V05_PCH_STBY_KR_PLL")
	)
	(segment
		(start 392.53795 -111.85525)
		(end 392.80338 -111.58982)
		(width 0.12446)
		(layer "F.Cu")
		(net "P1V05_PCH_STBY_KR_PLL")
	)
	(segment
		(start 392.245088 -111.562388)
		(end 392.53795 -111.85525)
		(width 0.12446)
		(layer "F.Cu")
		(net "P1V05_PCH_STBY_KR_PLL")
	)
	(segment
		(start 392.53795 -111.05515)
		(end 392.1633 -111.4298)
		(width 0.12446)
		(layer "F.Cu")
		(net "P1V05_PCH_STBY_KR_PLL")
	)
	(segment
		(start 393.68095 -110.71352)
		(end 393.93368 -110.46079)
		(width 0.12446)
		(layer "F.Cu")
		(net "P1V05_PCH_STBY_KR_PLL")
	)
	(segment
		(start 393.68095 -110.71352)
		(end 393.42822 -110.96625)
		(width 0.12446)
		(layer "F.Cu")
		(net "P1V05_PCH_STBY_KR_PLL")
	)
	(segment
		(start 392.53795 -111.05515)
		(end 392.80592 -111.32312)
		(width 0.12446)
		(layer "F.Cu")
		(net "P1V05_PCH_STBY_KR_PLL")
	)
	(via
		(at 393.690856 -107.887262)
		(size 0.508)
		(drill 0.254)
		(layers "F.Cu" "B.Cu")
		(net "P1V05_PCH_STBY_KR_PLL")
	)
	(via
		(at 392.1633 -111.4552)
		(size 0.508)
		(drill 0.254)
		(layers "F.Cu" "B.Cu")
		(net "P1V05_PCH_STBY_KR_PLL")
	)
	(via
		(at 400.12874 -112.97666)
		(size 0.6604)
		(drill 0.3302)
		(layers "F.Cu" "B.Cu")
		(net "P1V05_PCH_STBY_KR_PLL")
	)
	(via
		(at 392.1379 -112.2553)
		(size 0.508)
		(drill 0.254)
		(layers "F.Cu" "B.Cu")
		(net "P1V05_PCH_STBY_KR_PLL")
	)
	(via
		(at 393.68095 -111.802164)
		(size 0.508)
		(drill 0.254)
		(layers "F.Cu" "B.Cu")
		(net "P1V05_PCH_STBY_KR_PLL")
	)
	(via
		(at 394.17625 -110.943644)
		(size 0.508)
		(drill 0.254)
		(layers "F.Cu" "B.Cu")
		(net "P1V05_PCH_STBY_KR_PLL")
	)
	(via
		(at 406.282906 -110.935008)
		(size 0.6604)
		(drill 0.3302)
		(layers "F.Cu" "B.Cu")
		(net "P1V05_PCH_STBY_KR_PLL")
	)
	(segment
		(start 392.498834 -107.795314)
		(end 392.498834 -107.356148)
		(width 0.254)
		(layer "B.Cu")
		(net "P1V05_PCH_STBY_KR_PLL")
	)
	(segment
		(start 393.690856 -107.887262)
		(end 393.658598 -107.887262)
		(width 0.254)
		(layer "B.Cu")
		(net "P1V05_PCH_STBY_KR_PLL")
	)
	(segment
		(start 392.7983 -108.09478)
		(end 392.498834 -107.795314)
		(width 0.254)
		(layer "B.Cu")
		(net "P1V05_PCH_STBY_KR_PLL")
	)
	(segment
		(start 393.45108 -108.09478)
		(end 392.7983 -108.09478)
		(width 0.254)
		(layer "B.Cu")
		(net "P1V05_PCH_STBY_KR_PLL")
	)
	(segment
		(start 393.658598 -107.887262)
		(end 393.45108 -108.09478)
		(width 0.254)
		(layer "B.Cu")
		(net "P1V05_PCH_STBY_KR_PLL")
	)
	(segment
		(start 393.8905 -109.15396)
		(end 394.17625 -109.43971)
		(width 0.254)
		(layer "In4.Cu")
		(net "P1V05_PCH_STBY_KR_PLL")
	)
	(segment
		(start 393.66952 -108.95838)
		(end 393.8651 -109.15396)
		(width 0.254)
		(layer "In4.Cu")
		(net "P1V05_PCH_STBY_KR_PLL")
	)
	(segment
		(start 394.17625 -109.43971)
		(end 394.17625 -110.943644)
		(width 0.254)
		(layer "In4.Cu")
		(net "P1V05_PCH_STBY_KR_PLL")
	)
	(segment
		(start 393.8651 -109.15396)
		(end 393.8905 -109.15396)
		(width 0.254)
		(layer "In4.Cu")
		(net "P1V05_PCH_STBY_KR_PLL")
	)
	(segment
		(start 393.690856 -107.887262)
		(end 393.66952 -107.908598)
		(width 0.254)
		(layer "In4.Cu")
		(net "P1V05_PCH_STBY_KR_PLL")
	)
	(segment
		(start 393.66952 -107.908598)
		(end 393.66952 -108.95838)
		(width 0.254)
		(layer "In4.Cu")
		(net "P1V05_PCH_STBY_KR_PLL")
	)
	(segment
		(start 385.33705 -114.25555)
		(end 385.7371 -113.8555)
		(width 0.254)
		(layer "F.Cu")
		(net "P1V05_PCH_STBY_ISCLK_PLL")
	)
	(segment
		(start 385.7371 -113.8555)
		(end 386.13715 -113.45545)
		(width 0.254)
		(layer "F.Cu")
		(net "P1V05_PCH_STBY_ISCLK_PLL")
	)
	(segment
		(start 382.78435 -115.86464)
		(end 382.9304 -115.932458)
		(width 0.254)
		(layer "F.Cu")
		(net "P1V05_PCH_STBY_ISCLK_PLL")
	)
	(segment
		(start 387.05028 -114.94262)
		(end 387.05028 -114.72926)
		(width 0.12446)
		(layer "F.Cu")
		(net "P1V05_PCH_STBY_ISCLK_PLL")
	)
	(segment
		(start 387.05028 -114.72926)
		(end 386.97662 -114.6556)
		(width 0.12446)
		(layer "F.Cu")
		(net "P1V05_PCH_STBY_ISCLK_PLL")
	)
	(segment
		(start 382.9304 -115.932458)
		(end 383.27965 -116.094764)
		(width 0.254)
		(layer "F.Cu")
		(net "P1V05_PCH_STBY_ISCLK_PLL")
	)
	(segment
		(start 386.97662 -114.6556)
		(end 386.5372 -114.6556)
		(width 0.12446)
		(layer "F.Cu")
		(net "P1V05_PCH_STBY_ISCLK_PLL")
	)
	(segment
		(start 386.93725 -114.25555)
		(end 387.025642 -114.343942)
		(width 0.12446)
		(layer "F.Cu")
		(net "P1V05_PCH_STBY_ISCLK_PLL")
	)
	(segment
		(start 387.025642 -114.343942)
		(end 387.025642 -114.606578)
		(width 0.12446)
		(layer "F.Cu")
		(net "P1V05_PCH_STBY_ISCLK_PLL")
	)
	(segment
		(start 387.025642 -114.606578)
		(end 386.97662 -114.6556)
		(width 0.12446)
		(layer "F.Cu")
		(net "P1V05_PCH_STBY_ISCLK_PLL")
	)
	(segment
		(start 386.93725 -115.05565)
		(end 387.05028 -114.94262)
		(width 0.12446)
		(layer "F.Cu")
		(net "P1V05_PCH_STBY_ISCLK_PLL")
	)
	(via
		(at 373.68988 -131.89204)
		(size 0.6604)
		(drill 0.3302)
		(layers "F.Cu" "B.Cu")
		(net "P1V05_PCH_STBY_ISCLK_PLL")
	)
	(via
		(at 383.27965 -116.094764)
		(size 0.508)
		(drill 0.254)
		(layers "F.Cu" "B.Cu")
		(net "P1V05_PCH_STBY_ISCLK_PLL")
	)
	(via
		(at 384.908806 -114.6556)
		(size 0.508)
		(drill 0.254)
		(layers "F.Cu" "B.Cu")
		(net "P1V05_PCH_STBY_ISCLK_PLL")
	)
	(via
		(at 385.7371 -113.8555)
		(size 0.508)
		(drill 0.254)
		(layers "F.Cu" "B.Cu")
		(net "P1V05_PCH_STBY_ISCLK_PLL")
	)
	(via
		(at 374.015 -129.49174)
		(size 0.508)
		(drill 0.254)
		(layers "F.Cu" "B.Cu")
		(net "P1V05_PCH_STBY_ISCLK_PLL")
	)
	(via
		(at 386.5372 -114.6556)
		(size 0.508)
		(drill 0.254)
		(layers "F.Cu" "B.Cu")
		(net "P1V05_PCH_STBY_ISCLK_PLL")
	)
	(via
		(at 374.4976 -131.3688)
		(size 0.508)
		(drill 0.254)
		(layers "F.Cu" "B.Cu")
		(net "P1V05_PCH_STBY_ISCLK_PLL")
	)
	(segment
		(start 385.7371 -113.8555)
		(end 385.708906 -113.8555)
		(width 0.254)
		(layer "In2.Cu")
		(net "P1V05_PCH_STBY_ISCLK_PLL")
	)
	(segment
		(start 386.5372 -114.6556)
		(end 385.7371 -113.8555)
		(width 0.254)
		(layer "In2.Cu")
		(net "P1V05_PCH_STBY_ISCLK_PLL")
	)
	(segment
		(start 385.708906 -113.8555)
		(end 384.908806 -114.6556)
		(width 0.254)
		(layer "In2.Cu")
		(net "P1V05_PCH_STBY_ISCLK_PLL")
	)
	(segment
		(start 436.555134 -150.54961)
		(end 436.374032 -150.368508)
		(width 0.254)
		(layer "F.Cu")
		(net "P1V05_PCH_STBY")
	)
	(segment
		(start 392.53795 -109.45495)
		(end 392.830812 -109.747812)
		(width 0.12446)
		(layer "F.Cu")
		(net "P1V05_PCH_STBY")
	)
	(segment
		(start 409.448 -18.034)
		(end 409.35402 -18.12798)
		(width 0.254)
		(layer "F.Cu")
		(net "P1V05_PCH_STBY")
	)
	(segment
		(start 455.86777 -145.75663)
		(end 455.845926 -145.734786)
		(width 0.254)
		(layer "F.Cu")
		(net "P1V05_PCH_STBY")
	)
	(segment
		(start 391.320782 -109.872018)
		(end 390.93775 -110.25505)
		(width 0.1143)
		(layer "F.Cu")
		(net "P1V05_PCH_STBY")
	)
	(segment
		(start 437.891682 -150.54961)
		(end 436.555134 -150.54961)
		(width 0.254)
		(layer "F.Cu")
		(net "P1V05_PCH_STBY")
	)
	(segment
		(start 381.79375 -114.1476)
		(end 382.086612 -114.440462)
		(width 0.12446)
		(layer "F.Cu")
		(net "P1V05_PCH_STBY")
	)
	(segment
		(start 392.542014 -108.65485)
		(end 392.53795 -108.65485)
		(width 0.1143)
		(layer "F.Cu")
		(net "P1V05_PCH_STBY")
	)
	(segment
		(start 392.53795 -110.25505)
		(end 392.830812 -109.962188)
		(width 0.12446)
		(layer "F.Cu")
		(net "P1V05_PCH_STBY")
	)
	(segment
		(start 393.18565 -108.13796)
		(end 393.18565 -108.626402)
		(width 0.1397)
		(layer "F.Cu")
		(net "P1V05_PCH_STBY")
	)
	(segment
		(start 381.48895 -114.4524)
		(end 381.79375 -114.1476)
		(width 0.12446)
		(layer "F.Cu")
		(net "P1V05_PCH_STBY")
	)
	(segment
		(start 388.9375 -113.8555)
		(end 388.53745 -113.45545)
		(width 0.10795)
		(layer "F.Cu")
		(net "P1V05_PCH_STBY")
	)
	(segment
		(start 393.18565 -109.855)
		(end 393.478512 -109.562138)
		(width 0.12446)
		(layer "F.Cu")
		(net "P1V05_PCH_STBY")
	)
	(segment
		(start 383.73685 -114.25555)
		(end 383.44348 -113.96218)
		(width 0.12446)
		(layer "F.Cu")
		(net "P1V05_PCH_STBY")
	)
	(segment
		(start 388.53745 -112.65535)
		(end 388.287768 -112.905032)
		(width 0.1143)
		(layer "F.Cu")
		(net "P1V05_PCH_STBY")
	)
	(segment
		(start 392.53795 -107.05465)
		(end 392.830812 -106.761788)
		(width 0.12446)
		(layer "F.Cu")
		(net "P1V05_PCH_STBY")
	)
	(segment
		(start 393.12977 -107.58678)
		(end 392.80338 -107.75442)
		(width 0.254)
		(layer "F.Cu")
		(net "P1V05_PCH_STBY")
	)
	(segment
		(start 390.5377 -111.4552)
		(end 390.13765 -111.05515)
		(width 0.10795)
		(layer "F.Cu")
		(net "P1V05_PCH_STBY")
	)
	(segment
		(start 390.13765 -112.65535)
		(end 390.5377 -113.0554)
		(width 0.10795)
		(layer "F.Cu")
		(net "P1V05_PCH_STBY")
	)
	(segment
		(start 382.93675 -113.45545)
		(end 383.3368 -113.8555)
		(width 0.10795)
		(layer "F.Cu")
		(net "P1V05_PCH_STBY")
	)
	(segment
		(start 457.252324 -146.219926)
		(end 456.099926 -146.219926)
		(width 0.10795)
		(layer "F.Cu")
		(net "P1V05_PCH_STBY")
	)
	(segment
		(start 414.410652 -135.636)
		(end 414.758378 -135.636)
		(width 0.254)
		(layer "F.Cu")
		(net "P1V05_PCH_STBY")
	)
	(segment
		(start 456.099926 -146.219926)
		(end 455.873104 -145.993104)
		(width 0.10795)
		(layer "F.Cu")
		(net "P1V05_PCH_STBY")
	)
	(segment
		(start 382.1684 -116.03863)
		(end 382.28905 -116.094764)
		(width 0.254)
		(layer "F.Cu")
		(net "P1V05_PCH_STBY")
	)
	(segment
		(start 435.711346 -150.912322)
		(end 436.247794 -150.375874)
		(width 0.254)
		(layer "F.Cu")
		(net "P1V05_PCH_STBY")
	)
	(segment
		(start 383.3368 -114.6556)
		(end 382.93675 -114.25555)
		(width 0.10795)
		(layer "F.Cu")
		(net "P1V05_PCH_STBY")
	)
	(segment
		(start 415.012378 -134.732014)
		(end 415.266632 -134.47776)
		(width 0.254)
		(layer "F.Cu")
		(net "P1V05_PCH_STBY")
	)
	(segment
		(start 382.643888 -113.962688)
		(end 382.93675 -114.25555)
		(width 0.12446)
		(layer "F.Cu")
		(net "P1V05_PCH_STBY")
	)
	(segment
		(start 435.965346 -152.180036)
		(end 435.711346 -151.926036)
		(width 0.254)
		(layer "F.Cu")
		(net "P1V05_PCH_STBY")
	)
	(segment
		(start 389.7376 -113.0554)
		(end 390.13765 -113.45545)
		(width 0.1143)
		(layer "F.Cu")
		(net "P1V05_PCH_STBY")
	)
	(segment
		(start 387.3373 -113.0554)
		(end 387.73735 -113.45545)
		(width 0.1143)
		(layer "F.Cu")
		(net "P1V05_PCH_STBY")
	)
	(segment
		(start 387.73735 -105.45445)
		(end 388.1374 -105.0798)
		(width 0.254)
		(layer "F.Cu")
		(net "P1V05_PCH_STBY")
	)
	(segment
		(start 390.93775 -113.45545)
		(end 391.3378 -113.0554)
		(width 0.1143)
		(layer "F.Cu")
		(net "P1V05_PCH_STBY")
	)
	(segment
		(start 414.758378 -135.636)
		(end 415.012378 -135.382)
		(width 0.254)
		(layer "F.Cu")
		(net "P1V05_PCH_STBY")
	)
	(segment
		(start 382.081278 -156.932122)
		(end 382.719072 -156.294328)
		(width 0.254)
		(layer "F.Cu")
		(net "P1V05_PCH_STBY")
	)
	(segment
		(start 381.79375 -115.86464)
		(end 382.1684 -116.03863)
		(width 0.254)
		(layer "F.Cu")
		(net "P1V05_PCH_STBY")
	)
	(segment
		(start 453.2884 -148.59)
		(end 453.4027 -148.4757)
		(width 0.254)
		(layer "F.Cu")
		(net "P1V05_PCH_STBY")
	)
	(segment
		(start 391.73785 -113.45545)
		(end 391.3378 -113.8555)
		(width 0.254)
		(layer "F.Cu")
		(net "P1V05_PCH_STBY")
	)
	(segment
		(start 390.93775 -111.05515)
		(end 390.5377 -111.4552)
		(width 0.1143)
		(layer "F.Cu")
		(net "P1V05_PCH_STBY")
	)
	(segment
		(start 388.244588 -113.748312)
		(end 388.53745 -113.45545)
		(width 0.12446)
		(layer "F.Cu")
		(net "P1V05_PCH_STBY")
	)
	(segment
		(start 385.33705 -105.45445)
		(end 384.937 -105.0544)
		(width 0.254)
		(layer "F.Cu")
		(net "P1V05_PCH_STBY")
	)
	(segment
		(start 386.93725 -106.25455)
		(end 386.5372 -106.6546)
		(width 0.254)
		(layer "F.Cu")
		(net "P1V05_PCH_STBY")
	)
	(segment
		(start 392.892788 -110.147862)
		(end 393.18565 -109.855)
		(width 0.12446)
		(layer "F.Cu")
		(net "P1V05_PCH_STBY")
	)
	(segment
		(start 383.3368 -113.8555)
		(end 383.73685 -113.45545)
		(width 0.254)
		(layer "F.Cu")
		(net "P1V05_PCH_STBY")
	)
	(segment
		(start 455.845926 -145.734786)
		(end 455.845926 -145.483326)
		(width 0.254)
		(layer "F.Cu")
		(net "P1V05_PCH_STBY")
	)
	(segment
		(start 387.73735 -113.45545)
		(end 388.030212 -113.748312)
		(width 0.12446)
		(layer "F.Cu")
		(net "P1V05_PCH_STBY")
	)
	(segment
		(start 382.28905 -113.28908)
		(end 382.451356 -113.82883)
		(width 0.254)
		(layer "F.Cu")
		(net "P1V05_PCH_STBY")
	)
	(segment
		(start 392.245088 -109.962188)
		(end 392.53795 -110.25505)
		(width 0.12446)
		(layer "F.Cu")
		(net "P1V05_PCH_STBY")
	)
	(segment
		(start 393.18565 -108.626402)
		(end 393.129516 -108.682536)
		(width 0.1397)
		(layer "F.Cu")
		(net "P1V05_PCH_STBY")
	)
	(segment
		(start 388.244588 -113.162588)
		(end 388.53745 -113.45545)
		(width 0.12446)
		(layer "F.Cu")
		(net "P1V05_PCH_STBY")
	)
	(segment
		(start 415.012378 -135.382)
		(end 415.012378 -134.732014)
		(width 0.254)
		(layer "F.Cu")
		(net "P1V05_PCH_STBY")
	)
	(segment
		(start 391.3378 -110.6551)
		(end 390.93775 -111.05515)
		(width 0.1143)
		(layer "F.Cu")
		(net "P1V05_PCH_STBY")
	)
	(segment
		(start 386.5372 -113.0554)
		(end 386.93725 -112.65535)
		(width 0.10795)
		(layer "F.Cu")
		(net "P1V05_PCH_STBY")
	)
	(segment
		(start 387.73735 -113.45545)
		(end 388.030212 -113.162588)
		(width 0.12446)
		(layer "F.Cu")
		(net "P1V05_PCH_STBY")
	)
	(segment
		(start 409.35402 -18.12798)
		(end 409.35402 -18.830036)
		(width 0.254)
		(layer "F.Cu")
		(net "P1V05_PCH_STBY")
	)
	(segment
		(start 461.2894 -146.3548)
		(end 461.5688 -146.3548)
		(width 0.254)
		(layer "F.Cu")
		(net "P1V05_PCH_STBY")
	)
	(segment
		(start 389.33755 -113.45545)
		(end 389.7376 -113.8555)
		(width 0.10795)
		(layer "F.Cu")
		(net "P1V05_PCH_STBY")
	)
	(segment
		(start 387.73735 -112.65535)
		(end 387.3373 -113.0554)
		(width 0.10795)
		(layer "F.Cu")
		(net "P1V05_PCH_STBY")
	)
	(segment
		(start 392.892788 -109.562138)
		(end 393.18565 -109.855)
		(width 0.12446)
		(layer "F.Cu")
		(net "P1V05_PCH_STBY")
	)
	(segment
		(start 452.628 -148.59)
		(end 453.2884 -148.59)
		(width 0.254)
		(layer "F.Cu")
		(net "P1V05_PCH_STBY")
	)
	(segment
		(start 435.711346 -151.926036)
		(end 435.711346 -150.912322)
		(width 0.254)
		(layer "F.Cu")
		(net "P1V05_PCH_STBY")
	)
	(segment
		(start 390.93775 -110.25505)
		(end 391.3378 -110.6551)
		(width 0.10795)
		(layer "F.Cu")
		(net "P1V05_PCH_STBY")
	)
	(segment
		(start 409.448 -18.029936)
		(end 409.448 -18.034)
		(width 0.254)
		(layer "F.Cu")
		(net "P1V05_PCH_STBY")
	)
	(segment
		(start 391.9982 -109.872018)
		(end 391.320782 -109.872018)
		(width 0.1143)
		(layer "F.Cu")
		(net "P1V05_PCH_STBY")
	)
	(segment
		(start 382.451356 -113.82883)
		(end 382.56337 -113.82883)
		(width 0.12446)
		(layer "F.Cu")
		(net "P1V05_PCH_STBY")
	)
	(segment
		(start 390.13765 -113.45545)
		(end 390.5377 -113.8555)
		(width 0.1143)
		(layer "F.Cu")
		(net "P1V05_PCH_STBY")
	)
	(segment
		(start 455.873104 -145.96491)
		(end 455.86777 -145.959576)
		(width 0.254)
		(layer "F.Cu")
		(net "P1V05_PCH_STBY")
	)
	(segment
		(start 389.7376 -113.8555)
		(end 390.13765 -113.45545)
		(width 0.1143)
		(layer "F.Cu")
		(net "P1V05_PCH_STBY")
	)
	(segment
		(start 389.33755 -113.45545)
		(end 388.9375 -113.8555)
		(width 0.1143)
		(layer "F.Cu")
		(net "P1V05_PCH_STBY")
	)
	(segment
		(start 382.719072 -156.141674)
		(end 382.910842 -155.949904)
		(width 0.254)
		(layer "F.Cu")
		(net "P1V05_PCH_STBY")
	)
	(segment
		(start 381.500888 -113.854738)
		(end 381.79375 -114.1476)
		(width 0.12446)
		(layer "F.Cu")
		(net "P1V05_PCH_STBY")
	)
	(segment
		(start 455.1172 -144.0688)
		(end 455.1934 -143.9926)
		(width 0.254)
		(layer "F.Cu")
		(net "P1V05_PCH_STBY")
	)
	(segment
		(start 391.3378 -113.8555)
		(end 390.93775 -113.45545)
		(width 0.10795)
		(layer "F.Cu")
		(net "P1V05_PCH_STBY")
	)
	(segment
		(start 392.53795 -110.25505)
		(end 392.938 -110.6551)
		(width 0.10795)
		(layer "F.Cu")
		(net "P1V05_PCH_STBY")
	)
	(segment
		(start 388.53745 -112.65535)
		(end 388.9375 -113.0554)
		(width 0.10795)
		(layer "F.Cu")
		(net "P1V05_PCH_STBY")
	)
	(segment
		(start 392.245088 -107.347512)
		(end 392.53795 -107.05465)
		(width 0.12446)
		(layer "F.Cu")
		(net "P1V05_PCH_STBY")
	)
	(segment
		(start 393.18565 -109.857286)
		(end 393.18565 -109.855)
		(width 0.1143)
		(layer "F.Cu")
		(net "P1V05_PCH_STBY")
	)
	(segment
		(start 386.74675 -115.86464)
		(end 387.24205 -116.094764)
		(width 0.254)
		(layer "F.Cu")
		(net "P1V05_PCH_STBY")
	)
	(segment
		(start 381.79375 -114.1476)
		(end 382.086612 -113.854738)
		(width 0.12446)
		(layer "F.Cu")
		(net "P1V05_PCH_STBY")
	)
	(segment
		(start 455.873104 -145.993104)
		(end 455.873104 -145.96491)
		(width 0.254)
		(layer "F.Cu")
		(net "P1V05_PCH_STBY")
	)
	(segment
		(start 415.91484 -134.47776)
		(end 415.925 -134.4676)
		(width 0.254)
		(layer "F.Cu")
		(net "P1V05_PCH_STBY")
	)
	(segment
		(start 389.33755 -113.45545)
		(end 389.7376 -113.0554)
		(width 0.1143)
		(layer "F.Cu")
		(net "P1V05_PCH_STBY")
	)
	(segment
		(start 455.1172 -144.7546)
		(end 455.1172 -144.0688)
		(width 0.254)
		(layer "F.Cu")
		(net "P1V05_PCH_STBY")
	)
	(segment
		(start 392.53795 -107.05465)
		(end 392.830812 -107.347512)
		(width 0.12446)
		(layer "F.Cu")
		(net "P1V05_PCH_STBY")
	)
	(segment
		(start 441.00623 -151.564594)
		(end 441.759594 -151.564594)
		(width 0.254)
		(layer "F.Cu")
		(net "P1V05_PCH_STBY")
	)
	(segment
		(start 382.910842 -155.949904)
		(end 382.99898 -155.949904)
		(width 0.254)
		(layer "F.Cu")
		(net "P1V05_PCH_STBY")
	)
	(segment
		(start 383.73685 -114.25555)
		(end 383.3368 -114.6556)
		(width 0.10795)
		(layer "F.Cu")
		(net "P1V05_PCH_STBY")
	)
	(segment
		(start 394.67155 -114.1476)
		(end 394.67155 -115.236244)
		(width 0.254)
		(layer "F.Cu")
		(net "P1V05_PCH_STBY")
	)
	(segment
		(start 383.77495 -103.84536)
		(end 383.36601 -104.2543)
		(width 0.254)
		(layer "F.Cu")
		(net "P1V05_PCH_STBY")
	)
	(segment
		(start 390.93775 -111.05515)
		(end 391.3378 -111.4552)
		(width 0.10795)
		(layer "F.Cu")
		(net "P1V05_PCH_STBY")
	)
	(segment
		(start 382.719072 -156.294328)
		(end 382.719072 -156.141674)
		(width 0.254)
		(layer "F.Cu")
		(net "P1V05_PCH_STBY")
	)
	(segment
		(start 383.36601 -104.2543)
		(end 383.3368 -104.2543)
		(width 0.254)
		(layer "F.Cu")
		(net "P1V05_PCH_STBY")
	)
	(segment
		(start 390.5377 -113.0554)
		(end 390.93775 -112.65535)
		(width 0.254)
		(layer "F.Cu")
		(net "P1V05_PCH_STBY")
	)
	(segment
		(start 437.906414 -152.064466)
		(end 437.194706 -152.064466)
		(width 0.254)
		(layer "F.Cu")
		(net "P1V05_PCH_STBY")
	)
	(segment
		(start 387.73735 -113.45545)
		(end 387.3373 -113.8555)
		(width 0.10795)
		(layer "F.Cu")
		(net "P1V05_PCH_STBY")
	)
	(segment
		(start 388.53745 -115.05565)
		(end 388.149338 -115.454684)
		(width 0.254)
		(layer "F.Cu")
		(net "P1V05_PCH_STBY")
	)
	(segment
		(start 384.53695 -104.65435)
		(end 384.1369 -104.2543)
		(width 0.254)
		(layer "F.Cu")
		(net "P1V05_PCH_STBY")
	)
	(segment
		(start 383.3368 -104.2543)
		(end 382.93675 -104.65435)
		(width 0.254)
		(layer "F.Cu")
		(net "P1V05_PCH_STBY")
	)
	(segment
		(start 393.417806 -110.089442)
		(end 393.18565 -109.857286)
		(width 0.1143)
		(layer "F.Cu")
		(net "P1V05_PCH_STBY")
	)
	(segment
		(start 415.266632 -134.47776)
		(end 415.91484 -134.47776)
		(width 0.254)
		(layer "F.Cu")
		(net "P1V05_PCH_STBY")
	)
	(segment
		(start 461.703674 -146.219926)
		(end 462.980278 -146.219926)
		(width 0.254)
		(layer "F.Cu")
		(net "P1V05_PCH_STBY")
	)
	(segment
		(start 390.13765 -115.05565)
		(end 390.2202 -115.6208)
		(width 0.254)
		(layer "F.Cu")
		(net "P1V05_PCH_STBY")
	)
	(segment
		(start 391.3378 -113.0554)
		(end 391.73785 -112.65535)
		(width 0.254)
		(layer "F.Cu")
		(net "P1V05_PCH_STBY")
	)
	(segment
		(start 387.73735 -112.65535)
		(end 387.965188 -112.883188)
		(width 0.1143)
		(layer "F.Cu")
		(net "P1V05_PCH_STBY")
	)
	(segment
		(start 388.1374 -105.0798)
		(end 388.53745 -105.45445)
		(width 0.254)
		(layer "F.Cu")
		(net "P1V05_PCH_STBY")
	)
	(segment
		(start 461.5688 -146.3548)
		(end 461.703674 -146.219926)
		(width 0.254)
		(layer "F.Cu")
		(net "P1V05_PCH_STBY")
	)
	(segment
		(start 387.3373 -113.0554)
		(end 386.93725 -112.65535)
		(width 0.1143)
		(layer "F.Cu")
		(net "P1V05_PCH_STBY")
	)
	(segment
		(start 389.33755 -113.45545)
		(end 388.9375 -113.0554)
		(width 0.1143)
		(layer "F.Cu")
		(net "P1V05_PCH_STBY")
	)
	(segment
		(start 392.245088 -109.747812)
		(end 392.53795 -109.45495)
		(width 0.12446)
		(layer "F.Cu")
		(net "P1V05_PCH_STBY")
	)
	(segment
		(start 392.53795 -109.45495)
		(end 392.830812 -109.162088)
		(width 0.12446)
		(layer "F.Cu")
		(net "P1V05_PCH_STBY")
	)
	(segment
		(start 437.906414 -150.564342)
		(end 437.891682 -150.54961)
		(width 0.254)
		(layer "F.Cu")
		(net "P1V05_PCH_STBY")
	)
	(segment
		(start 436.247794 -150.375874)
		(end 436.366666 -150.375874)
		(width 0.254)
		(layer "F.Cu")
		(net "P1V05_PCH_STBY")
	)
	(segment
		(start 382.643888 -114.548412)
		(end 382.93675 -114.25555)
		(width 0.12446)
		(layer "F.Cu")
		(net "P1V05_PCH_STBY")
	)
	(segment
		(start 437.079136 -152.180036)
		(end 435.965346 -152.180036)
		(width 0.254)
		(layer "F.Cu")
		(net "P1V05_PCH_STBY")
	)
	(segment
		(start 390.93775 -113.45545)
		(end 390.5377 -113.0554)
		(width 0.1143)
		(layer "F.Cu")
		(net "P1V05_PCH_STBY")
	)
	(segment
		(start 382.93675 -114.25555)
		(end 383.229612 -113.962688)
		(width 0.12446)
		(layer "F.Cu")
		(net "P1V05_PCH_STBY")
	)
	(segment
		(start 381.11303 -157.468824)
		(end 381.11303 -157.291532)
		(width 0.254)
		(layer "F.Cu")
		(net "P1V05_PCH_STBY")
	)
	(segment
		(start 436.366666 -150.375874)
		(end 436.374032 -150.368508)
		(width 0.254)
		(layer "F.Cu")
		(net "P1V05_PCH_STBY")
	)
	(segment
		(start 390.5377 -113.0554)
		(end 390.13765 -113.45545)
		(width 0.1143)
		(layer "F.Cu")
		(net "P1V05_PCH_STBY")
	)
	(segment
		(start 381.11303 -157.291532)
		(end 381.47244 -156.932122)
		(width 0.254)
		(layer "F.Cu")
		(net "P1V05_PCH_STBY")
	)
	(segment
		(start 390.13765 -112.65535)
		(end 389.7376 -113.0554)
		(width 0.1143)
		(layer "F.Cu")
		(net "P1V05_PCH_STBY")
	)
	(segment
		(start 388.9375 -113.0554)
		(end 388.53745 -113.45545)
		(width 0.1143)
		(layer "F.Cu")
		(net "P1V05_PCH_STBY")
	)
	(segment
		(start 455.86777 -145.959576)
		(end 455.86777 -145.75663)
		(width 0.254)
		(layer "F.Cu")
		(net "P1V05_PCH_STBY")
	)
	(segment
		(start 382.56337 -113.82883)
		(end 382.93675 -113.45545)
		(width 0.12446)
		(layer "F.Cu")
		(net "P1V05_PCH_STBY")
	)
	(segment
		(start 455.845926 -145.483326)
		(end 455.1172 -144.7546)
		(width 0.254)
		(layer "F.Cu")
		(net "P1V05_PCH_STBY")
	)
	(segment
		(start 381.3048 -114.4524)
		(end 381.48895 -114.4524)
		(width 0.12446)
		(layer "F.Cu")
		(net "P1V05_PCH_STBY")
	)
	(segment
		(start 389.7376 -113.0554)
		(end 389.33755 -112.65535)
		(width 0.10795)
		(layer "F.Cu")
		(net "P1V05_PCH_STBY")
	)
	(segment
		(start 390.5377 -113.8555)
		(end 390.93775 -113.45545)
		(width 0.1143)
		(layer "F.Cu")
		(net "P1V05_PCH_STBY")
	)
	(segment
		(start 388.9375 -113.0554)
		(end 389.33755 -112.65535)
		(width 0.1143)
		(layer "F.Cu")
		(net "P1V05_PCH_STBY")
	)
	(segment
		(start 392.81735 -108.379514)
		(end 392.542014 -108.65485)
		(width 0.1143)
		(layer "F.Cu")
		(net "P1V05_PCH_STBY")
	)
	(segment
		(start 414.410652 -135.636)
		(end 413.521652 -135.636)
		(width 0.254)
		(layer "F.Cu")
		(net "P1V05_PCH_STBY")
	)
	(segment
		(start 392.80338 -107.75442)
		(end 392.53795 -107.85475)
		(width 0.254)
		(layer "F.Cu")
		(net "P1V05_PCH_STBY")
	)
	(segment
		(start 381.47244 -156.932122)
		(end 382.081278 -156.932122)
		(width 0.254)
		(layer "F.Cu")
		(net "P1V05_PCH_STBY")
	)
	(segment
		(start 394.67155 -115.236244)
		(end 394.17625 -115.00612)
		(width 0.254)
		(layer "F.Cu")
		(net "P1V05_PCH_STBY")
	)
	(segment
		(start 437.194706 -152.064466)
		(end 437.079136 -152.180036)
		(width 0.254)
		(layer "F.Cu")
		(net "P1V05_PCH_STBY")
	)
	(via
		(at 388.61619 -142.846044)
		(size 0.5588)
		(drill 0.3048)
		(layers "F.Cu" "B.Cu")
		(net "P1V05_PCH_STBY")
	)
	(via
		(at 388.1374 -105.0798)
		(size 0.508)
		(drill 0.254)
		(layers "F.Cu" "B.Cu")
		(net "P1V05_PCH_STBY")
	)
	(via
		(at 461.34782 -138.49604)
		(size 0.508)
		(drill 0.254)
		(layers "F.Cu" "B.Cu")
		(net "P1V05_PCH_STBY")
	)
	(via
		(at 387.24205 -116.094764)
		(size 0.508)
		(drill 0.254)
		(layers "F.Cu" "B.Cu")
		(net "P1V05_PCH_STBY")
	)
	(via
		(at 390.5377 -111.4552)
		(size 0.508)
		(drill 0.254)
		(layers "F.Cu" "B.Cu")
		(net "P1V05_PCH_STBY")
	)
	(via
		(at 406.006046 -30.67304)
		(size 0.508)
		(drill 0.254)
		(layers "F.Cu" "B.Cu")
		(net "P1V05_PCH_STBY")
	)
	(via
		(at 392.89355 -143.760444)
		(size 0.5588)
		(drill 0.3048)
		(layers "F.Cu" "B.Cu")
		(net "P1V05_PCH_STBY")
	)
	(via
		(at 389.7376 -113.0554)
		(size 0.508)
		(drill 0.254)
		(layers "F.Cu" "B.Cu")
		(net "P1V05_PCH_STBY")
	)
	(via
		(at 383.3368 -104.2543)
		(size 0.508)
		(drill 0.254)
		(layers "F.Cu" "B.Cu")
		(net "P1V05_PCH_STBY")
	)
	(via
		(at 384.504184 -83.99272)
		(size 0.508)
		(drill 0.254)
		(layers "F.Cu" "B.Cu")
		(net "P1V05_PCH_STBY")
	)
	(via
		(at 402.58365 -116.89334)
		(size 0.508)
		(drill 0.254)
		(layers "F.Cu" "B.Cu")
		(net "P1V05_PCH_STBY")
	)
	(via
		(at 392.167618 -143.04899)
		(size 0.5588)
		(drill 0.3048)
		(layers "F.Cu" "B.Cu")
		(net "P1V05_PCH_STBY")
	)
	(via
		(at 393.129516 -108.682536)
		(size 0.508)
		(drill 0.254)
		(layers "F.Cu" "B.Cu")
		(net "P1V05_PCH_STBY")
	)
	(via
		(at 410.1846 -126.63805)
		(size 0.508)
		(drill 0.254)
		(layers "F.Cu" "B.Cu")
		(net "P1V05_PCH_STBY")
	)
	(via
		(at 415.925 -134.4676)
		(size 0.508)
		(drill 0.254)
		(layers "F.Cu" "B.Cu")
		(net "P1V05_PCH_STBY")
	)
	(via
		(at 386.5372 -106.6546)
		(size 0.508)
		(drill 0.254)
		(layers "F.Cu" "B.Cu")
		(net "P1V05_PCH_STBY")
	)
	(via
		(at 442.722 -145.923)
		(size 0.508)
		(drill 0.254)
		(layers "F.Cu" "B.Cu")
		(net "P1V05_PCH_STBY")
	)
	(via
		(at 376.8598 -134.9248)
		(size 0.508)
		(drill 0.254)
		(layers "F.Cu" "B.Cu")
		(net "P1V05_PCH_STBY")
	)
	(via
		(at 387.232652 -142.820644)
		(size 0.5588)
		(drill 0.3048)
		(layers "F.Cu" "B.Cu")
		(net "P1V05_PCH_STBY")
	)
	(via
		(at 453.4027 -148.4757)
		(size 0.508)
		(drill 0.254)
		(layers "F.Cu" "B.Cu")
		(net "P1V05_PCH_STBY")
	)
	(via
		(at 390.736074 -143.233902)
		(size 0.5588)
		(drill 0.3048)
		(layers "F.Cu" "B.Cu")
		(net "P1V05_PCH_STBY")
	)
	(via
		(at 393.68095 -109.624876)
		(size 0.508)
		(drill 0.254)
		(layers "F.Cu" "B.Cu")
		(net "P1V05_PCH_STBY")
	)
	(via
		(at 381.79375 -113.519204)
		(size 0.508)
		(drill 0.254)
		(layers "F.Cu" "B.Cu")
		(net "P1V05_PCH_STBY")
	)
	(via
		(at 388.9375 -113.8555)
		(size 0.508)
		(drill 0.254)
		(layers "F.Cu" "B.Cu")
		(net "P1V05_PCH_STBY")
	)
	(via
		(at 393.54633 -143.139414)
		(size 0.5588)
		(drill 0.3048)
		(layers "F.Cu" "B.Cu")
		(net "P1V05_PCH_STBY")
	)
	(via
		(at 384.937 -105.0544)
		(size 0.508)
		(drill 0.254)
		(layers "F.Cu" "B.Cu")
		(net "P1V05_PCH_STBY")
	)
	(via
		(at 439.612786 -139.233148)
		(size 0.508)
		(drill 0.254)
		(layers "F.Cu" "B.Cu")
		(net "P1V05_PCH_STBY")
	)
	(via
		(at 391.3378 -113.8555)
		(size 0.508)
		(drill 0.254)
		(layers "F.Cu" "B.Cu")
		(net "P1V05_PCH_STBY")
	)
	(via
		(at 376.174 -88.9)
		(size 0.508)
		(drill 0.254)
		(layers "F.Cu" "B.Cu")
		(net "P1V05_PCH_STBY")
	)
	(via
		(at 370.640102 -130.859784)
		(size 0.508)
		(drill 0.254)
		(layers "F.Cu" "B.Cu")
		(net "P1V05_PCH_STBY")
	)
	(via
		(at 408.721052 -128.2827)
		(size 0.6604)
		(drill 0.3302)
		(layers "F.Cu" "B.Cu")
		(net "P1V05_PCH_STBY")
	)
	(via
		(at 384.1369 -104.2543)
		(size 0.508)
		(drill 0.254)
		(layers "F.Cu" "B.Cu")
		(net "P1V05_PCH_STBY")
	)
	(via
		(at 391.3378 -110.6551)
		(size 0.508)
		(drill 0.254)
		(layers "F.Cu" "B.Cu")
		(net "P1V05_PCH_STBY")
	)
	(via
		(at 393.12977 -106.969052)
		(size 0.508)
		(drill 0.254)
		(layers "F.Cu" "B.Cu")
		(net "P1V05_PCH_STBY")
	)
	(via
		(at 376.9868 -130.9878)
		(size 0.508)
		(drill 0.254)
		(layers "F.Cu" "B.Cu")
		(net "P1V05_PCH_STBY")
	)
	(via
		(at 461.2894 -146.3548)
		(size 0.508)
		(drill 0.254)
		(layers "F.Cu" "B.Cu")
		(net "P1V05_PCH_STBY")
	)
	(via
		(at 387.3373 -113.0554)
		(size 0.508)
		(drill 0.254)
		(layers "F.Cu" "B.Cu")
		(net "P1V05_PCH_STBY")
	)
	(via
		(at 370.491766 -135.027416)
		(size 0.508)
		(drill 0.254)
		(layers "F.Cu" "B.Cu")
		(net "P1V05_PCH_STBY")
	)
	(via
		(at 382.451356 -113.82883)
		(size 0.508)
		(drill 0.254)
		(layers "F.Cu" "B.Cu")
		(net "P1V05_PCH_STBY")
	)
	(via
		(at 410.2354 -122.2756)
		(size 0.508)
		(drill 0.254)
		(layers "F.Cu" "B.Cu")
		(net "P1V05_PCH_STBY")
	)
	(via
		(at 388.9375 -113.0554)
		(size 0.508)
		(drill 0.254)
		(layers "F.Cu" "B.Cu")
		(net "P1V05_PCH_STBY")
	)
	(via
		(at 441.759594 -151.564594)
		(size 0.508)
		(drill 0.254)
		(layers "F.Cu" "B.Cu")
		(net "P1V05_PCH_STBY")
	)
	(via
		(at 410.7942 -131.826)
		(size 0.508)
		(drill 0.254)
		(layers "F.Cu" "B.Cu")
		(net "P1V05_PCH_STBY")
	)
	(via
		(at 393.51839 -144.495774)
		(size 0.5588)
		(drill 0.3048)
		(layers "F.Cu" "B.Cu")
		(net "P1V05_PCH_STBY")
	)
	(via
		(at 391.3378 -111.4552)
		(size 0.508)
		(drill 0.254)
		(layers "F.Cu" "B.Cu")
		(net "P1V05_PCH_STBY")
	)
	(via
		(at 392.88593 -143.082264)
		(size 0.5588)
		(drill 0.3048)
		(layers "F.Cu" "B.Cu")
		(net "P1V05_PCH_STBY")
	)
	(via
		(at 393.129516 -109.309154)
		(size 0.508)
		(drill 0.254)
		(layers "F.Cu" "B.Cu")
		(net "P1V05_PCH_STBY")
	)
	(via
		(at 393.12977 -107.58678)
		(size 0.508)
		(drill 0.254)
		(layers "F.Cu" "B.Cu")
		(net "P1V05_PCH_STBY")
	)
	(via
		(at 377.2535 -103.636318)
		(size 0.508)
		(drill 0.254)
		(layers "F.Cu" "B.Cu")
		(net "P1V05_PCH_STBY")
	)
	(via
		(at 381.3048 -114.4524)
		(size 0.508)
		(drill 0.254)
		(layers "F.Cu" "B.Cu")
		(net "P1V05_PCH_STBY")
	)
	(via
		(at 390.5377 -113.0554)
		(size 0.508)
		(drill 0.254)
		(layers "F.Cu" "B.Cu")
		(net "P1V05_PCH_STBY")
	)
	(via
		(at 391.481818 -143.04899)
		(size 0.5588)
		(drill 0.3048)
		(layers "F.Cu" "B.Cu")
		(net "P1V05_PCH_STBY")
	)
	(via
		(at 410.913834 -126.673356)
		(size 0.508)
		(drill 0.254)
		(layers "F.Cu" "B.Cu")
		(net "P1V05_PCH_STBY")
	)
	(via
		(at 410.8704 -122.2756)
		(size 0.508)
		(drill 0.254)
		(layers "F.Cu" "B.Cu")
		(net "P1V05_PCH_STBY")
	)
	(via
		(at 371.221 -135.001)
		(size 0.508)
		(drill 0.254)
		(layers "F.Cu" "B.Cu")
		(net "P1V05_PCH_STBY")
	)
	(via
		(at 376.3518 -130.9878)
		(size 0.508)
		(drill 0.254)
		(layers "F.Cu" "B.Cu")
		(net "P1V05_PCH_STBY")
	)
	(via
		(at 387.93039 -142.846044)
		(size 0.5588)
		(drill 0.3048)
		(layers "F.Cu" "B.Cu")
		(net "P1V05_PCH_STBY")
	)
	(via
		(at 391.3378 -113.0554)
		(size 0.508)
		(drill 0.254)
		(layers "F.Cu" "B.Cu")
		(net "P1V05_PCH_STBY")
	)
	(via
		(at 409.448 -18.029936)
		(size 0.508)
		(drill 0.254)
		(layers "F.Cu" "B.Cu")
		(net "P1V05_PCH_STBY")
	)
	(via
		(at 390.5377 -113.8555)
		(size 0.508)
		(drill 0.254)
		(layers "F.Cu" "B.Cu")
		(net "P1V05_PCH_STBY")
	)
	(via
		(at 392.19632 -143.728186)
		(size 0.5588)
		(drill 0.3048)
		(layers "F.Cu" "B.Cu")
		(net "P1V05_PCH_STBY")
	)
	(via
		(at 389.863838 -142.191232)
		(size 0.5588)
		(drill 0.3048)
		(layers "F.Cu" "B.Cu")
		(net "P1V05_PCH_STBY")
	)
	(via
		(at 381.29845 -112.660684)
		(size 0.508)
		(drill 0.254)
		(layers "F.Cu" "B.Cu")
		(net "P1V05_PCH_STBY")
	)
	(via
		(at 389.98779 -142.846044)
		(size 0.5588)
		(drill 0.3048)
		(layers "F.Cu" "B.Cu")
		(net "P1V05_PCH_STBY")
	)
	(via
		(at 403.21865 -116.89334)
		(size 0.508)
		(drill 0.254)
		(layers "F.Cu" "B.Cu")
		(net "P1V05_PCH_STBY")
	)
	(via
		(at 390.2202 -115.6208)
		(size 0.508)
		(drill 0.254)
		(layers "F.Cu" "B.Cu")
		(net "P1V05_PCH_STBY")
	)
	(via
		(at 386.5372 -113.0554)
		(size 0.508)
		(drill 0.254)
		(layers "F.Cu" "B.Cu")
		(net "P1V05_PCH_STBY")
	)
	(via
		(at 388.149338 -115.454684)
		(size 0.508)
		(drill 0.254)
		(layers "F.Cu" "B.Cu")
		(net "P1V05_PCH_STBY")
	)
	(via
		(at 392.85799 -144.438624)
		(size 0.5588)
		(drill 0.3048)
		(layers "F.Cu" "B.Cu")
		(net "P1V05_PCH_STBY")
	)
	(via
		(at 392.938 -110.6551)
		(size 0.508)
		(drill 0.254)
		(layers "F.Cu" "B.Cu")
		(net "P1V05_PCH_STBY")
	)
	(via
		(at 401.8788 -116.91874)
		(size 0.508)
		(drill 0.254)
		(layers "F.Cu" "B.Cu")
		(net "P1V05_PCH_STBY")
	)
	(via
		(at 389.7376 -113.8555)
		(size 0.508)
		(drill 0.254)
		(layers "F.Cu" "B.Cu")
		(net "P1V05_PCH_STBY")
	)
	(via
		(at 387.3373 -113.8555)
		(size 0.508)
		(drill 0.254)
		(layers "F.Cu" "B.Cu")
		(net "P1V05_PCH_STBY")
	)
	(via
		(at 389.124444 -142.20444)
		(size 0.5588)
		(drill 0.3048)
		(layers "F.Cu" "B.Cu")
		(net "P1V05_PCH_STBY")
	)
	(via
		(at 391.43432 -143.728186)
		(size 0.5588)
		(drill 0.3048)
		(layers "F.Cu" "B.Cu")
		(net "P1V05_PCH_STBY")
	)
	(via
		(at 382.28905 -116.094764)
		(size 0.508)
		(drill 0.254)
		(layers "F.Cu" "B.Cu")
		(net "P1V05_PCH_STBY")
	)
	(via
		(at 389.30199 -142.846044)
		(size 0.5588)
		(drill 0.3048)
		(layers "F.Cu" "B.Cu")
		(net "P1V05_PCH_STBY")
	)
	(via
		(at 436.374032 -150.368508)
		(size 0.508)
		(drill 0.254)
		(layers "F.Cu" "B.Cu")
		(net "P1V05_PCH_STBY")
	)
	(via
		(at 392.19632 -144.490186)
		(size 0.5588)
		(drill 0.3048)
		(layers "F.Cu" "B.Cu")
		(net "P1V05_PCH_STBY")
	)
	(via
		(at 390.74979 -142.488412)
		(size 0.5588)
		(drill 0.3048)
		(layers "F.Cu" "B.Cu")
		(net "P1V05_PCH_STBY")
	)
	(via
		(at 393.55395 -143.817594)
		(size 0.5588)
		(drill 0.3048)
		(layers "F.Cu" "B.Cu")
		(net "P1V05_PCH_STBY")
	)
	(via
		(at 376.2248 -134.9248)
		(size 0.508)
		(drill 0.254)
		(layers "F.Cu" "B.Cu")
		(net "P1V05_PCH_STBY")
	)
	(via
		(at 381.11303 -157.468824)
		(size 0.508)
		(drill 0.254)
		(layers "F.Cu" "B.Cu")
		(net "P1V05_PCH_STBY")
	)
	(via
		(at 455.1934 -143.9926)
		(size 0.508)
		(drill 0.254)
		(layers "F.Cu" "B.Cu")
		(net "P1V05_PCH_STBY")
	)
	(via
		(at 388.438644 -142.20444)
		(size 0.5588)
		(drill 0.3048)
		(layers "F.Cu" "B.Cu")
		(net "P1V05_PCH_STBY")
	)
	(via
		(at 371.82298 -93.438726)
		(size 0.508)
		(drill 0.254)
		(layers "F.Cu" "B.Cu")
		(net "P1V05_PCH_STBY")
	)
	(via
		(at 394.67155 -115.236244)
		(size 0.508)
		(drill 0.254)
		(layers "F.Cu" "B.Cu")
		(net "P1V05_PCH_STBY")
	)
	(via
		(at 387.752844 -142.20444)
		(size 0.5588)
		(drill 0.3048)
		(layers "F.Cu" "B.Cu")
		(net "P1V05_PCH_STBY")
	)
	(via
		(at 371.275102 -130.859784)
		(size 0.508)
		(drill 0.254)
		(layers "F.Cu" "B.Cu")
		(net "P1V05_PCH_STBY")
	)
	(segment
		(start 461.3402 -146.304)
		(end 461.2894 -146.3548)
		(width 0.10795)
		(layer "B.Cu")
		(net "P1V05_PCH_STBY")
	)
	(segment
		(start 455.1934 -143.9926)
		(end 455.1172 -143.9164)
		(width 0.254)
		(layer "B.Cu")
		(net "P1V05_PCH_STBY")
	)
	(segment
		(start 381.3048 -150.0886)
		(end 381.3048 -157.277054)
		(width 0.2286)
		(layer "B.Cu")
		(net "P1V05_PCH_STBY")
	)
	(segment
		(start 462.801208 -137.414254)
		(end 462.801208 -136.525254)
		(width 0.254)
		(layer "B.Cu")
		(net "P1V05_PCH_STBY")
	)
	(segment
		(start 454.453752 -143.566896)
		(end 454.453752 -142.776448)
		(width 0.254)
		(layer "B.Cu")
		(net "P1V05_PCH_STBY")
	)
	(segment
		(start 385.051808 -84.540344)
		(end 384.504184 -83.99272)
		(width 0.254)
		(layer "B.Cu")
		(net "P1V05_PCH_STBY")
	)
	(segment
		(start 453.6948 -148.1836)
		(end 453.4027 -148.4757)
		(width 0.254)
		(layer "B.Cu")
		(net "P1V05_PCH_STBY")
	)
	(segment
		(start 385.813808 -84.729828)
		(end 386.575808 -84.729828)
		(width 0.254)
		(layer "B.Cu")
		(net "P1V05_PCH_STBY")
	)
	(segment
		(start 385.051808 -84.729828)
		(end 385.813808 -84.729828)
		(width 0.254)
		(layer "B.Cu")
		(net "P1V05_PCH_STBY")
	)
	(segment
		(start 461.34782 -138.49604)
		(end 462.429606 -137.414254)
		(width 0.254)
		(layer "B.Cu")
		(net "P1V05_PCH_STBY")
	)
	(segment
		(start 453.6948 -147.5486)
		(end 453.6948 -148.1836)
		(width 0.254)
		(layer "B.Cu")
		(net "P1V05_PCH_STBY")
	)
	(segment
		(start 455.1172 -143.9164)
		(end 455.1172 -143.820896)
		(width 0.254)
		(layer "B.Cu")
		(net "P1V05_PCH_STBY")
	)
	(segment
		(start 454.787 -142.4432)
		(end 454.787 -142.0114)
		(width 0.254)
		(layer "B.Cu")
		(net "P1V05_PCH_STBY")
	)
	(segment
		(start 382.143 -144.272)
		(end 382.143 -149.2504)
		(width 0.254)
		(layer "B.Cu")
		(net "P1V05_PCH_STBY")
	)
	(segment
		(start 376.174 -88.0745)
		(end 376.174 -88.9)
		(width 0.254)
		(layer "B.Cu")
		(net "P1V05_PCH_STBY")
	)
	(segment
		(start 461.899 -146.304)
		(end 461.3402 -146.304)
		(width 0.10795)
		(layer "B.Cu")
		(net "P1V05_PCH_STBY")
	)
	(segment
		(start 382.7272 -114.104674)
		(end 382.7272 -114.554)
		(width 0.10795)
		(layer "B.Cu")
		(net "P1V05_PCH_STBY")
	)
	(segment
		(start 385.051808 -84.729828)
		(end 385.051808 -84.540344)
		(width 0.254)
		(layer "B.Cu")
		(net "P1V05_PCH_STBY")
	)
	(segment
		(start 381.3048 -157.277054)
		(end 381.11303 -157.468824)
		(width 0.2286)
		(layer "B.Cu")
		(net "P1V05_PCH_STBY")
	)
	(segment
		(start 455.1172 -143.820896)
		(end 454.8632 -143.566896)
		(width 0.254)
		(layer "B.Cu")
		(net "P1V05_PCH_STBY")
	)
	(segment
		(start 454.8632 -143.566896)
		(end 454.453752 -143.566896)
		(width 0.254)
		(layer "B.Cu")
		(net "P1V05_PCH_STBY")
	)
	(segment
		(start 382.143 -149.2504)
		(end 381.3048 -150.0886)
		(width 0.2286)
		(layer "B.Cu")
		(net "P1V05_PCH_STBY")
	)
	(segment
		(start 384.289808 -84.729828)
		(end 385.051808 -84.729828)
		(width 0.254)
		(layer "B.Cu")
		(net "P1V05_PCH_STBY")
	)
	(segment
		(start 382.451356 -113.82883)
		(end 382.7272 -114.104674)
		(width 0.10795)
		(layer "B.Cu")
		(net "P1V05_PCH_STBY")
	)
	(segment
		(start 454.453752 -142.776448)
		(end 454.787 -142.4432)
		(width 0.254)
		(layer "B.Cu")
		(net "P1V05_PCH_STBY")
	)
	(segment
		(start 462.429606 -137.414254)
		(end 462.801208 -137.414254)
		(width 0.254)
		(layer "B.Cu")
		(net "P1V05_PCH_STBY")
	)
	(segment
		(start 383.54 -142.875)
		(end 382.143 -144.272)
		(width 0.254)
		(layer "B.Cu")
		(net "P1V05_PCH_STBY")
	)
	(segment
		(start 385.064 -142.875)
		(end 383.54 -142.875)
		(width 0.254)
		(layer "B.Cu")
		(net "P1V05_PCH_STBY")
	)
	(segment
		(start 385.41325 -77.212444)
		(end 385.412996 -77.21219)
		(width 0.254)
		(layer "In2.Cu")
		(net "P1V05_PCH_STBY")
	)
	(segment
		(start 435.929278 -134.846822)
		(end 439.612786 -138.53033)
		(width 0.508)
		(layer "In2.Cu")
		(net "P1V05_PCH_STBY")
	)
	(segment
		(start 417.763198 -133.427724)
		(end 422.410636 -133.427724)
		(width 0.508)
		(layer "In2.Cu")
		(net "P1V05_PCH_STBY")
	)
	(segment
		(start 398.196816 -29.9974)
		(end 399.76298 -29.9974)
		(width 0.254)
		(layer "In2.Cu")
		(net "P1V05_PCH_STBY")
	)
	(segment
		(start 385.418584 -72.219312)
		(end 385.418584 -70.32625)
		(width 0.254)
		(layer "In2.Cu")
		(net "P1V05_PCH_STBY")
	)
	(segment
		(start 430.90719 -134.846822)
		(end 435.929278 -134.846822)
		(width 0.508)
		(layer "In2.Cu")
		(net "P1V05_PCH_STBY")
	)
	(segment
		(start 385.9149 -51.296316)
		(end 385.373626 -50.755042)
		(width 0.254)
		(layer "In2.Cu")
		(net "P1V05_PCH_STBY")
	)
	(segment
		(start 384.19786 -79.828898)
		(end 384.19786 -78.653894)
		(width 0.254)
		(layer "In2.Cu")
		(net "P1V05_PCH_STBY")
	)
	(segment
		(start 461.264 -146.3294)
		(end 461.2894 -146.3548)
		(width 0.4064)
		(layer "In2.Cu")
		(net "P1V05_PCH_STBY")
	)
	(segment
		(start 385.067048 -73.0758)
		(end 385.052824 -73.061576)
		(width 0.254)
		(layer "In2.Cu")
		(net "P1V05_PCH_STBY")
	)
	(segment
		(start 422.410636 -133.427724)
		(end 423.083736 -132.754624)
		(width 0.508)
		(layer "In2.Cu")
		(net "P1V05_PCH_STBY")
	)
	(segment
		(start 385.052824 -72.661272)
		(end 385.067048 -72.647048)
		(width 0.254)
		(layer "In2.Cu")
		(net "P1V05_PCH_STBY")
	)
	(segment
		(start 428.814992 -132.754624)
		(end 430.90719 -134.846822)
		(width 0.508)
		(layer "In2.Cu")
		(net "P1V05_PCH_STBY")
	)
	(segment
		(start 380.556516 -104.003348)
		(end 380.52502 -104.019858)
		(width 0.254)
		(layer "In2.Cu")
		(net "P1V05_PCH_STBY")
	)
	(segment
		(start 455.422 -143.764)
		(end 457.327 -143.764)
		(width 0.4064)
		(layer "In2.Cu")
		(net "P1V05_PCH_STBY")
	)
	(segment
		(start 386.252466 -69.492368)
		(end 386.252466 -64.882014)
		(width 0.254)
		(layer "In2.Cu")
		(net "P1V05_PCH_STBY")
	)
	(segment
		(start 402.053806 -30.483556)
		(end 402.99005 -31.4198)
		(width 0.254)
		(layer "In2.Cu")
		(net "P1V05_PCH_STBY")
	)
	(segment
		(start 387.291072 -63.843408)
		(end 387.794246 -63.843408)
		(width 0.254)
		(layer "In2.Cu")
		(net "P1V05_PCH_STBY")
	)
	(segment
		(start 388.188708 -62.79261)
		(end 387.713728 -62.31763)
		(width 0.254)
		(layer "In2.Cu")
		(net "P1V05_PCH_STBY")
	)
	(segment
		(start 385.373626 -48.246284)
		(end 384.855466 -47.728124)
		(width 0.254)
		(layer "In2.Cu")
		(net "P1V05_PCH_STBY")
	)
	(segment
		(start 384.855466 -46.874176)
		(end 386.120132 -45.60951)
		(width 0.254)
		(layer "In2.Cu")
		(net "P1V05_PCH_STBY")
	)
	(segment
		(start 416.723322 -134.4676)
		(end 417.763198 -133.427724)
		(width 0.508)
		(layer "In2.Cu")
		(net "P1V05_PCH_STBY")
	)
	(segment
		(start 385.41325 -77.438504)
		(end 385.41325 -77.212444)
		(width 0.254)
		(layer "In2.Cu")
		(net "P1V05_PCH_STBY")
	)
	(segment
		(start 402.99005 -31.4198)
		(end 404.0378 -31.4198)
		(width 0.254)
		(layer "In2.Cu")
		(net "P1V05_PCH_STBY")
	)
	(segment
		(start 404.7998 -30.6578)
		(end 405.990806 -30.6578)
		(width 0.254)
		(layer "In2.Cu")
		(net "P1V05_PCH_STBY")
	)
	(segment
		(start 379.732794 -103.947468)
		(end 379.5649 -104.044496)
		(width 0.254)
		(layer "In2.Cu")
		(net "P1V05_PCH_STBY")
	)
	(segment
		(start 385.373372 -53.71846)
		(end 385.9149 -53.176932)
		(width 0.254)
		(layer "In2.Cu")
		(net "P1V05_PCH_STBY")
	)
	(segment
		(start 383.65176 -83.15706)
		(end 383.65176 -80.374998)
		(width 0.254)
		(layer "In2.Cu")
		(net "P1V05_PCH_STBY")
	)
	(segment
		(start 389.324342 -37.91966)
		(end 390.447784 -36.796218)
		(width 0.254)
		(layer "In2.Cu")
		(net "P1V05_PCH_STBY")
	)
	(segment
		(start 387.0833 -58.686192)
		(end 387.077458 -58.68035)
		(width 0.254)
		(layer "In2.Cu")
		(net "P1V05_PCH_STBY")
	)
	(segment
		(start 386.252466 -64.882014)
		(end 387.291072 -63.843408)
		(width 0.254)
		(layer "In2.Cu")
		(net "P1V05_PCH_STBY")
	)
	(segment
		(start 415.925 -134.4676)
		(end 416.723322 -134.4676)
		(width 0.508)
		(layer "In2.Cu")
		(net "P1V05_PCH_STBY")
	)
	(segment
		(start 387.713728 -60.269882)
		(end 387.0833 -59.639454)
		(width 0.254)
		(layer "In2.Cu")
		(net "P1V05_PCH_STBY")
	)
	(segment
		(start 455.1934 -143.9926)
		(end 455.422 -143.764)
		(width 0.4064)
		(layer "In2.Cu")
		(net "P1V05_PCH_STBY")
	)
	(segment
		(start 405.990806 -30.6578)
		(end 406.006046 -30.67304)
		(width 0.254)
		(layer "In2.Cu")
		(net "P1V05_PCH_STBY")
	)
	(segment
		(start 383.126996 -104.044496)
		(end 383.032 -104.044496)
		(width 0.254)
		(layer "In2.Cu")
		(net "P1V05_PCH_STBY")
	)
	(segment
		(start 384.504184 -83.99272)
		(end 384.48742 -83.99272)
		(width 0.254)
		(layer "In2.Cu")
		(net "P1V05_PCH_STBY")
	)
	(segment
		(start 385.9149 -53.176932)
		(end 385.9149 -51.296316)
		(width 0.254)
		(layer "In2.Cu")
		(net "P1V05_PCH_STBY")
	)
	(segment
		(start 394.697458 -33.306258)
		(end 395.979142 -33.306258)
		(width 0.254)
		(layer "In2.Cu")
		(net "P1V05_PCH_STBY")
	)
	(segment
		(start 457.327 -143.764)
		(end 457.6826 -144.1196)
		(width 0.4064)
		(layer "In2.Cu")
		(net "P1V05_PCH_STBY")
	)
	(segment
		(start 399.76298 -29.9974)
		(end 400.249136 -30.483556)
		(width 0.254)
		(layer "In2.Cu")
		(net "P1V05_PCH_STBY")
	)
	(segment
		(start 387.0833 -59.639454)
		(end 387.0833 -58.686192)
		(width 0.254)
		(layer "In2.Cu")
		(net "P1V05_PCH_STBY")
	)
	(segment
		(start 423.083736 -132.754624)
		(end 428.814992 -132.754624)
		(width 0.508)
		(layer "In2.Cu")
		(net "P1V05_PCH_STBY")
	)
	(segment
		(start 385.067048 -72.647048)
		(end 385.067048 -72.570848)
		(width 0.254)
		(layer "In2.Cu")
		(net "P1V05_PCH_STBY")
	)
	(segment
		(start 439.612786 -138.53033)
		(end 439.612786 -139.233148)
		(width 0.508)
		(layer "In2.Cu")
		(net "P1V05_PCH_STBY")
	)
	(segment
		(start 387.077458 -58.68035)
		(end 387.077458 -57.868058)
		(width 0.254)
		(layer "In2.Cu")
		(net "P1V05_PCH_STBY")
	)
	(segment
		(start 385.418584 -70.32625)
		(end 386.252466 -69.492368)
		(width 0.254)
		(layer "In2.Cu")
		(net "P1V05_PCH_STBY")
	)
	(segment
		(start 387.794246 -63.843408)
		(end 388.188708 -63.448946)
		(width 0.254)
		(layer "In2.Cu")
		(net "P1V05_PCH_STBY")
	)
	(segment
		(start 458.9272 -146.3294)
		(end 461.264 -146.3294)
		(width 0.4064)
		(layer "In2.Cu")
		(net "P1V05_PCH_STBY")
	)
	(segment
		(start 393.299442 -33.293304)
		(end 393.46632 -33.126426)
		(width 0.254)
		(layer "In2.Cu")
		(net "P1V05_PCH_STBY")
	)
	(segment
		(start 393.46632 -33.126426)
		(end 394.517626 -33.126426)
		(width 0.254)
		(layer "In2.Cu")
		(net "P1V05_PCH_STBY")
	)
	(segment
		(start 391.673842 -33.293304)
		(end 393.299442 -33.293304)
		(width 0.254)
		(layer "In2.Cu")
		(net "P1V05_PCH_STBY")
	)
	(segment
		(start 395.979142 -33.306258)
		(end 396.4051 -32.8803)
		(width 0.254)
		(layer "In2.Cu")
		(net "P1V05_PCH_STBY")
	)
	(segment
		(start 387.077458 -57.868058)
		(end 385.373372 -56.163972)
		(width 0.254)
		(layer "In2.Cu")
		(net "P1V05_PCH_STBY")
	)
	(segment
		(start 388.810754 -37.91966)
		(end 389.324342 -37.91966)
		(width 0.254)
		(layer "In2.Cu")
		(net "P1V05_PCH_STBY")
	)
	(segment
		(start 457.6826 -145.0848)
		(end 458.9272 -146.3294)
		(width 0.4064)
		(layer "In2.Cu")
		(net "P1V05_PCH_STBY")
	)
	(segment
		(start 385.067048 -72.570848)
		(end 385.418584 -72.219312)
		(width 0.254)
		(layer "In2.Cu")
		(net "P1V05_PCH_STBY")
	)
	(segment
		(start 396.4051 -31.789116)
		(end 398.196816 -29.9974)
		(width 0.254)
		(layer "In2.Cu")
		(net "P1V05_PCH_STBY")
	)
	(segment
		(start 378.079 -104.044496)
		(end 377.2535 -103.636318)
		(width 0.254)
		(layer "In2.Cu")
		(net "P1V05_PCH_STBY")
	)
	(segment
		(start 381.0508 -104.044496)
		(end 380.885192 -103.948992)
		(width 0.254)
		(layer "In2.Cu")
		(net "P1V05_PCH_STBY")
	)
	(segment
		(start 390.447784 -34.519362)
		(end 391.673842 -33.293304)
		(width 0.254)
		(layer "In2.Cu")
		(net "P1V05_PCH_STBY")
	)
	(segment
		(start 390.447784 -36.796218)
		(end 390.447784 -34.519362)
		(width 0.254)
		(layer "In2.Cu")
		(net "P1V05_PCH_STBY")
	)
	(segment
		(start 385.067048 -73.553574)
		(end 385.067048 -73.0758)
		(width 0.254)
		(layer "In2.Cu")
		(net "P1V05_PCH_STBY")
	)
	(segment
		(start 394.517626 -33.126426)
		(end 394.697458 -33.306258)
		(width 0.254)
		(layer "In2.Cu")
		(net "P1V05_PCH_STBY")
	)
	(segment
		(start 400.249136 -30.483556)
		(end 402.053806 -30.483556)
		(width 0.254)
		(layer "In2.Cu")
		(net "P1V05_PCH_STBY")
	)
	(segment
		(start 388.188708 -63.448946)
		(end 388.188708 -62.79261)
		(width 0.254)
		(layer "In2.Cu")
		(net "P1V05_PCH_STBY")
	)
	(segment
		(start 384.19786 -78.653894)
		(end 385.41325 -77.438504)
		(width 0.254)
		(layer "In2.Cu")
		(net "P1V05_PCH_STBY")
	)
	(segment
		(start 385.052824 -73.061576)
		(end 385.052824 -72.661272)
		(width 0.254)
		(layer "In2.Cu")
		(net "P1V05_PCH_STBY")
	)
	(segment
		(start 386.120132 -40.610282)
		(end 388.810754 -37.91966)
		(width 0.254)
		(layer "In2.Cu")
		(net "P1V05_PCH_STBY")
	)
	(segment
		(start 383.3368 -104.2543)
		(end 383.126996 -104.044496)
		(width 0.254)
		(layer "In2.Cu")
		(net "P1V05_PCH_STBY")
	)
	(segment
		(start 385.373372 -56.163972)
		(end 385.373372 -53.71846)
		(width 0.254)
		(layer "In2.Cu")
		(net "P1V05_PCH_STBY")
	)
	(segment
		(start 457.6826 -144.1196)
		(end 457.6826 -145.0848)
		(width 0.4064)
		(layer "In2.Cu")
		(net "P1V05_PCH_STBY")
	)
	(segment
		(start 404.0378 -31.4198)
		(end 404.7998 -30.6578)
		(width 0.254)
		(layer "In2.Cu")
		(net "P1V05_PCH_STBY")
	)
	(segment
		(start 384.855466 -47.728124)
		(end 384.855466 -46.874176)
		(width 0.254)
		(layer "In2.Cu")
		(net "P1V05_PCH_STBY")
	)
	(segment
		(start 385.412996 -73.899522)
		(end 385.067048 -73.553574)
		(width 0.254)
		(layer "In2.Cu")
		(net "P1V05_PCH_STBY")
	)
	(segment
		(start 387.713728 -62.31763)
		(end 387.713728 -60.269882)
		(width 0.254)
		(layer "In2.Cu")
		(net "P1V05_PCH_STBY")
	)
	(segment
		(start 384.48742 -83.99272)
		(end 383.65176 -83.15706)
		(width 0.254)
		(layer "In2.Cu")
		(net "P1V05_PCH_STBY")
	)
	(segment
		(start 385.373626 -50.755042)
		(end 385.373626 -48.246284)
		(width 0.254)
		(layer "In2.Cu")
		(net "P1V05_PCH_STBY")
	)
	(segment
		(start 386.120132 -45.60951)
		(end 386.120132 -40.610282)
		(width 0.254)
		(layer "In2.Cu")
		(net "P1V05_PCH_STBY")
	)
	(segment
		(start 385.412996 -77.21219)
		(end 385.412996 -73.899522)
		(width 0.254)
		(layer "In2.Cu")
		(net "P1V05_PCH_STBY")
	)
	(segment
		(start 396.4051 -32.8803)
		(end 396.4051 -31.789116)
		(width 0.254)
		(layer "In2.Cu")
		(net "P1V05_PCH_STBY")
	)
	(segment
		(start 383.65176 -80.374998)
		(end 384.19786 -79.828898)
		(width 0.254)
		(layer "In2.Cu")
		(net "P1V05_PCH_STBY")
	)
	(arc
		(start 382.5367 -104.044496)
		(mid 382.28905 -104.110811)
		(end 382.0414 -104.044496)
		(width 0.254)
		(layer "In2.Cu")
		(net "P1V05_PCH_STBY")
	)
	(arc
		(start 380.885192 -103.948992)
		(mid 380.716483 -103.949736)
		(end 380.556516 -104.003348)
		(width 0.254)
		(layer "In2.Cu")
		(net "P1V05_PCH_STBY")
	)
	(arc
		(start 380.52502 -104.019858)
		(mid 380.291221 -104.06483)
		(end 380.061216 -104.003348)
		(width 0.254)
		(layer "In2.Cu")
		(net "P1V05_PCH_STBY")
	)
	(arc
		(start 380.061216 -104.003348)
		(mid 379.90149 -103.949076)
		(end 379.732794 -103.947468)
		(width 0.254)
		(layer "In2.Cu")
		(net "P1V05_PCH_STBY")
	)
	(arc
		(start 383.032 -104.044496)
		(mid 382.78435 -103.978181)
		(end 382.5367 -104.044496)
		(width 0.254)
		(layer "In2.Cu")
		(net "P1V05_PCH_STBY")
	)
	(arc
		(start 382.0414 -104.044496)
		(mid 381.79375 -103.978181)
		(end 381.5461 -104.044496)
		(width 0.254)
		(layer "In2.Cu")
		(net "P1V05_PCH_STBY")
	)
	(arc
		(start 378.5743 -104.044496)
		(mid 378.32665 -104.110811)
		(end 378.079 -104.044496)
		(width 0.254)
		(layer "In2.Cu")
		(net "P1V05_PCH_STBY")
	)
	(arc
		(start 379.5649 -104.044496)
		(mid 379.31725 -104.110811)
		(end 379.0696 -104.044496)
		(width 0.254)
		(layer "In2.Cu")
		(net "P1V05_PCH_STBY")
	)
	(arc
		(start 381.5461 -104.044496)
		(mid 381.29845 -104.110811)
		(end 381.0508 -104.044496)
		(width 0.254)
		(layer "In2.Cu")
		(net "P1V05_PCH_STBY")
	)
	(arc
		(start 379.0696 -104.044496)
		(mid 378.82195 -103.978181)
		(end 378.5743 -104.044496)
		(width 0.254)
		(layer "In2.Cu")
		(net "P1V05_PCH_STBY")
	)
	(segment
		(start 462.28 -145.5166)
		(end 462.28 -139.5476)
		(width 0.4064)
		(layer "In4.Cu")
		(net "P1V05_PCH_STBY")
	)
	(segment
		(start 378.91466 -86.913466)
		(end 378.91466 -85.62594)
		(width 0.254)
		(layer "In4.Cu")
		(net "P1V05_PCH_STBY")
	)
	(segment
		(start 370.115846 -100.104448)
		(end 370.6114 -99.608894)
		(width 0.254)
		(layer "In4.Cu")
		(net "P1V05_PCH_STBY")
	)
	(segment
		(start 371.3226 -102.959662)
		(end 371.1956 -102.581456)
		(width 0.254)
		(layer "In4.Cu")
		(net "P1V05_PCH_STBY")
	)
	(segment
		(start 370.182902 -100.883212)
		(end 370.096034 -100.43922)
		(width 0.254)
		(layer "In4.Cu")
		(net "P1V05_PCH_STBY")
	)
	(segment
		(start 371.1956 -102.124256)
		(end 371.0178 -101.906324)
		(width 0.254)
		(layer "In4.Cu")
		(net "P1V05_PCH_STBY")
	)
	(segment
		(start 372.581932 -105.167684)
		(end 372.2116 -104.797352)
		(width 0.254)
		(layer "In4.Cu")
		(net "P1V05_PCH_STBY")
	)
	(segment
		(start 370.6114 -99.608894)
		(end 370.6114 -95.389954)
		(width 0.254)
		(layer "In4.Cu")
		(net "P1V05_PCH_STBY")
	)
	(segment
		(start 376.109992 -103.873808)
		(end 374.816116 -105.167684)
		(width 0.254)
		(layer "In4.Cu")
		(net "P1V05_PCH_STBY")
	)
	(segment
		(start 413.235648 -132.7531)
		(end 414.946846 -132.7531)
		(width 0.254)
		(layer "In4.Cu")
		(net "P1V05_PCH_STBY")
	)
	(segment
		(start 461.4418 -146.3548)
		(end 462.28 -145.5166)
		(width 0.4064)
		(layer "In4.Cu")
		(net "P1V05_PCH_STBY")
	)
	(segment
		(start 376.243088 -89.158572)
		(end 376.2502 -89.15146)
		(width 0.254)
		(layer "In4.Cu")
		(net "P1V05_PCH_STBY")
	)
	(segment
		(start 370.096034 -100.43922)
		(end 370.096034 -100.20427)
		(width 0.254)
		(layer "In4.Cu")
		(net "P1V05_PCH_STBY")
	)
	(segment
		(start 462.28 -139.5476)
		(end 461.34782 -138.61542)
		(width 0.4064)
		(layer "In4.Cu")
		(net "P1V05_PCH_STBY")
	)
	(segment
		(start 414.946846 -132.7531)
		(end 415.361374 -133.167628)
		(width 0.254)
		(layer "In4.Cu")
		(net "P1V05_PCH_STBY")
	)
	(segment
		(start 384.36804 -83.99272)
		(end 384.504184 -83.99272)
		(width 0.254)
		(layer "In4.Cu")
		(net "P1V05_PCH_STBY")
	)
	(segment
		(start 376.2502 -89.15146)
		(end 376.2502 -88.9762)
		(width 0.254)
		(layer "In4.Cu")
		(net "P1V05_PCH_STBY")
	)
	(segment
		(start 372.2116 -104.797352)
		(end 372.2116 -103.8606)
		(width 0.254)
		(layer "In4.Cu")
		(net "P1V05_PCH_STBY")
	)
	(segment
		(start 379.984 -84.5566)
		(end 383.80416 -84.5566)
		(width 0.254)
		(layer "In4.Cu")
		(net "P1V05_PCH_STBY")
	)
	(segment
		(start 371.82298 -94.178374)
		(end 371.82298 -93.438726)
		(width 0.254)
		(layer "In4.Cu")
		(net "P1V05_PCH_STBY")
	)
	(segment
		(start 372.2116 -103.8606)
		(end 371.328696 -102.977696)
		(width 0.254)
		(layer "In4.Cu")
		(net "P1V05_PCH_STBY")
	)
	(segment
		(start 461.2894 -146.3548)
		(end 461.4418 -146.3548)
		(width 0.4064)
		(layer "In4.Cu")
		(net "P1V05_PCH_STBY")
	)
	(segment
		(start 378.91466 -85.62594)
		(end 379.984 -84.5566)
		(width 0.254)
		(layer "In4.Cu")
		(net "P1V05_PCH_STBY")
	)
	(segment
		(start 371.82298 -93.438726)
		(end 372.625366 -93.438726)
		(width 0.254)
		(layer "In4.Cu")
		(net "P1V05_PCH_STBY")
	)
	(segment
		(start 410.7942 -131.826)
		(end 410.870654 -131.902454)
		(width 0.254)
		(layer "In4.Cu")
		(net "P1V05_PCH_STBY")
	)
	(segment
		(start 372.625366 -93.438726)
		(end 375.378472 -90.68562)
		(width 0.254)
		(layer "In4.Cu")
		(net "P1V05_PCH_STBY")
	)
	(segment
		(start 374.816116 -105.167684)
		(end 372.581932 -105.167684)
		(width 0.254)
		(layer "In4.Cu")
		(net "P1V05_PCH_STBY")
	)
	(segment
		(start 376.707146 -88.366854)
		(end 377.461272 -88.366854)
		(width 0.254)
		(layer "In4.Cu")
		(net "P1V05_PCH_STBY")
	)
	(segment
		(start 415.361374 -133.167628)
		(end 415.361374 -133.903974)
		(width 0.254)
		(layer "In4.Cu")
		(net "P1V05_PCH_STBY")
	)
	(segment
		(start 371.1956 -102.581456)
		(end 371.1956 -102.124256)
		(width 0.254)
		(layer "In4.Cu")
		(net "P1V05_PCH_STBY")
	)
	(segment
		(start 410.870654 -131.902454)
		(end 412.385002 -131.902454)
		(width 0.254)
		(layer "In4.Cu")
		(net "P1V05_PCH_STBY")
	)
	(segment
		(start 383.80416 -84.5566)
		(end 384.36804 -83.99272)
		(width 0.254)
		(layer "In4.Cu")
		(net "P1V05_PCH_STBY")
	)
	(segment
		(start 412.385002 -131.902454)
		(end 413.235648 -132.7531)
		(width 0.254)
		(layer "In4.Cu")
		(net "P1V05_PCH_STBY")
	)
	(segment
		(start 371.0178 -101.906324)
		(end 370.182902 -100.883212)
		(width 0.254)
		(layer "In4.Cu")
		(net "P1V05_PCH_STBY")
	)
	(segment
		(start 377.461272 -88.366854)
		(end 378.91466 -86.913466)
		(width 0.254)
		(layer "In4.Cu")
		(net "P1V05_PCH_STBY")
	)
	(segment
		(start 461.34782 -138.61542)
		(end 461.34782 -138.49604)
		(width 0.4064)
		(layer "In4.Cu")
		(net "P1V05_PCH_STBY")
	)
	(segment
		(start 375.378472 -90.68562)
		(end 375.900188 -90.68562)
		(width 0.254)
		(layer "In4.Cu")
		(net "P1V05_PCH_STBY")
	)
	(segment
		(start 377.2535 -103.636318)
		(end 377.01601 -103.873808)
		(width 0.254)
		(layer "In4.Cu")
		(net "P1V05_PCH_STBY")
	)
	(segment
		(start 376.2502 -88.9762)
		(end 376.174 -88.9)
		(width 0.254)
		(layer "In4.Cu")
		(net "P1V05_PCH_STBY")
	)
	(segment
		(start 377.01601 -103.873808)
		(end 376.109992 -103.873808)
		(width 0.254)
		(layer "In4.Cu")
		(net "P1V05_PCH_STBY")
	)
	(segment
		(start 376.174 -88.9)
		(end 376.707146 -88.366854)
		(width 0.254)
		(layer "In4.Cu")
		(net "P1V05_PCH_STBY")
	)
	(segment
		(start 415.361374 -133.903974)
		(end 415.925 -134.4676)
		(width 0.254)
		(layer "In4.Cu")
		(net "P1V05_PCH_STBY")
	)
	(segment
		(start 370.096034 -100.20427)
		(end 370.115846 -100.104448)
		(width 0.254)
		(layer "In4.Cu")
		(net "P1V05_PCH_STBY")
	)
	(segment
		(start 375.900188 -90.68562)
		(end 376.243088 -90.34272)
		(width 0.254)
		(layer "In4.Cu")
		(net "P1V05_PCH_STBY")
	)
	(segment
		(start 371.328696 -102.977696)
		(end 371.3226 -102.959662)
		(width 0.254)
		(layer "In4.Cu")
		(net "P1V05_PCH_STBY")
	)
	(segment
		(start 376.243088 -90.34272)
		(end 376.243088 -89.158572)
		(width 0.254)
		(layer "In4.Cu")
		(net "P1V05_PCH_STBY")
	)
	(segment
		(start 370.6114 -95.389954)
		(end 371.82298 -94.178374)
		(width 0.254)
		(layer "In4.Cu")
		(net "P1V05_PCH_STBY")
	)
	(segment
		(start 439.547 -139.298934)
		(end 439.547 -143.5608)
		(width 0.4064)
		(layer "In9.Cu")
		(net "P1V05_PCH_STBY")
	)
	(segment
		(start 441.9092 -145.923)
		(end 442.722 -145.923)
		(width 0.4064)
		(layer "In9.Cu")
		(net "P1V05_PCH_STBY")
	)
	(segment
		(start 439.612786 -139.233148)
		(end 439.547 -139.298934)
		(width 0.4064)
		(layer "In9.Cu")
		(net "P1V05_PCH_STBY")
	)
	(segment
		(start 439.547 -143.5608)
		(end 441.9092 -145.923)
		(width 0.4064)
		(layer "In9.Cu")
		(net "P1V05_PCH_STBY")
	)
	(segment
		(start 437.261 -150.876)
		(end 436.753508 -150.368508)
		(width 0.4064)
		(layer "In11.Cu")
		(net "P1V05_PCH_STBY")
	)
	(segment
		(start 454.24852 -147.50796)
		(end 453.4027 -148.35378)
		(width 0.4064)
		(layer "In11.Cu")
		(net "P1V05_PCH_STBY")
	)
	(segment
		(start 442.722 -145.923)
		(end 443.205362 -146.406362)
		(width 0.4064)
		(layer "In11.Cu")
		(net "P1V05_PCH_STBY")
	)
	(segment
		(start 405.993346 -20.9804)
		(end 405.406098 -20.393152)
		(width 0.254)
		(layer "In11.Cu")
		(net "P1V05_PCH_STBY")
	)
	(segment
		(start 404.9141 -18.951448)
		(end 405.21636 -18.649188)
		(width 0.254)
		(layer "In11.Cu")
		(net "P1V05_PCH_STBY")
	)
	(segment
		(start 442.778642 -151.959818)
		(end 443.205362 -151.533098)
		(width 0.4064)
		(layer "In11.Cu")
		(net "P1V05_PCH_STBY")
	)
	(segment
		(start 407.149046 -24.8666)
		(end 407.7462 -24.8666)
		(width 0.254)
		(layer "In11.Cu")
		(net "P1V05_PCH_STBY")
	)
	(segment
		(start 437.261 -151.257)
		(end 437.261 -150.876)
		(width 0.4064)
		(layer "In11.Cu")
		(net "P1V05_PCH_STBY")
	)
	(segment
		(start 442.154818 -151.959818)
		(end 442.778642 -151.959818)
		(width 0.4064)
		(layer "In11.Cu")
		(net "P1V05_PCH_STBY")
	)
	(segment
		(start 405.406098 -20.393152)
		(end 405.406098 -19.884898)
		(width 0.254)
		(layer "In11.Cu")
		(net "P1V05_PCH_STBY")
	)
	(segment
		(start 443.205362 -151.533098)
		(end 443.205362 -146.406362)
		(width 0.4064)
		(layer "In11.Cu")
		(net "P1V05_PCH_STBY")
	)
	(segment
		(start 405.406098 -19.884898)
		(end 404.9141 -19.3929)
		(width 0.254)
		(layer "In11.Cu")
		(net "P1V05_PCH_STBY")
	)
	(segment
		(start 408.586178 -24.026622)
		(end 408.586178 -23.395178)
		(width 0.254)
		(layer "In11.Cu")
		(net "P1V05_PCH_STBY")
	)
	(segment
		(start 447.1924 -147.7518)
		(end 447.6242 -147.32)
		(width 0.4064)
		(layer "In11.Cu")
		(net "P1V05_PCH_STBY")
	)
	(segment
		(start 407.7462 -24.8666)
		(end 408.586178 -24.026622)
		(width 0.254)
		(layer "In11.Cu")
		(net "P1V05_PCH_STBY")
	)
	(segment
		(start 407.543 -21.209)
		(end 407.3144 -20.9804)
		(width 0.254)
		(layer "In11.Cu")
		(net "P1V05_PCH_STBY")
	)
	(segment
		(start 409.368752 -17.950688)
		(end 409.448 -18.029936)
		(width 0.254)
		(layer "In11.Cu")
		(net "P1V05_PCH_STBY")
	)
	(segment
		(start 455.1934 -143.9926)
		(end 455.05116 -144.13484)
		(width 0.4064)
		(layer "In11.Cu")
		(net "P1V05_PCH_STBY")
	)
	(segment
		(start 454.24852 -145.99158)
		(end 454.24852 -147.50796)
		(width 0.4064)
		(layer "In11.Cu")
		(net "P1V05_PCH_STBY")
	)
	(segment
		(start 404.504652 -27.510994)
		(end 407.149046 -24.8666)
		(width 0.254)
		(layer "In11.Cu")
		(net "P1V05_PCH_STBY")
	)
	(segment
		(start 438.277 -152.273)
		(end 437.261 -151.257)
		(width 0.4064)
		(layer "In11.Cu")
		(net "P1V05_PCH_STBY")
	)
	(segment
		(start 454.30186 -143.9926)
		(end 455.1934 -143.9926)
		(width 0.4064)
		(layer "In11.Cu")
		(net "P1V05_PCH_STBY")
	)
	(segment
		(start 407.543 -22.352)
		(end 407.543 -21.209)
		(width 0.254)
		(layer "In11.Cu")
		(net "P1V05_PCH_STBY")
	)
	(segment
		(start 443.205362 -146.406362)
		(end 444.5508 -147.7518)
		(width 0.4064)
		(layer "In11.Cu")
		(net "P1V05_PCH_STBY")
	)
	(segment
		(start 441.051188 -152.273)
		(end 438.277 -152.273)
		(width 0.4064)
		(layer "In11.Cu")
		(net "P1V05_PCH_STBY")
	)
	(segment
		(start 453.4027 -148.35378)
		(end 453.4027 -148.4757)
		(width 0.4064)
		(layer "In11.Cu")
		(net "P1V05_PCH_STBY")
	)
	(segment
		(start 441.759594 -151.564594)
		(end 441.051188 -152.273)
		(width 0.4064)
		(layer "In11.Cu")
		(net "P1V05_PCH_STBY")
	)
	(segment
		(start 406.006046 -30.67304)
		(end 404.504652 -29.171646)
		(width 0.254)
		(layer "In11.Cu")
		(net "P1V05_PCH_STBY")
	)
	(segment
		(start 407.3144 -20.9804)
		(end 405.993346 -20.9804)
		(width 0.254)
		(layer "In11.Cu")
		(net "P1V05_PCH_STBY")
	)
	(segment
		(start 408.586178 -23.395178)
		(end 407.543 -22.352)
		(width 0.254)
		(layer "In11.Cu")
		(net "P1V05_PCH_STBY")
	)
	(segment
		(start 447.6242 -147.32)
		(end 450.97446 -147.32)
		(width 0.4064)
		(layer "In11.Cu")
		(net "P1V05_PCH_STBY")
	)
	(segment
		(start 441.759594 -151.564594)
		(end 442.154818 -151.959818)
		(width 0.4064)
		(layer "In11.Cu")
		(net "P1V05_PCH_STBY")
	)
	(segment
		(start 436.753508 -150.368508)
		(end 436.374032 -150.368508)
		(width 0.4064)
		(layer "In11.Cu")
		(net "P1V05_PCH_STBY")
	)
	(segment
		(start 404.9141 -19.3929)
		(end 404.9141 -18.951448)
		(width 0.254)
		(layer "In11.Cu")
		(net "P1V05_PCH_STBY")
	)
	(segment
		(start 450.97446 -147.32)
		(end 454.30186 -143.9926)
		(width 0.4064)
		(layer "In11.Cu")
		(net "P1V05_PCH_STBY")
	)
	(segment
		(start 444.5508 -147.7518)
		(end 447.1924 -147.7518)
		(width 0.4064)
		(layer "In11.Cu")
		(net "P1V05_PCH_STBY")
	)
	(segment
		(start 455.05116 -144.13484)
		(end 455.05116 -145.18894)
		(width 0.4064)
		(layer "In11.Cu")
		(net "P1V05_PCH_STBY")
	)
	(segment
		(start 405.569674 -18.649188)
		(end 406.268174 -17.950688)
		(width 0.254)
		(layer "In11.Cu")
		(net "P1V05_PCH_STBY")
	)
	(segment
		(start 406.268174 -17.950688)
		(end 409.368752 -17.950688)
		(width 0.254)
		(layer "In11.Cu")
		(net "P1V05_PCH_STBY")
	)
	(segment
		(start 404.504652 -29.171646)
		(end 404.504652 -27.510994)
		(width 0.254)
		(layer "In11.Cu")
		(net "P1V05_PCH_STBY")
	)
	(segment
		(start 455.05116 -145.18894)
		(end 454.24852 -145.99158)
		(width 0.4064)
		(layer "In11.Cu")
		(net "P1V05_PCH_STBY")
	)
	(segment
		(start 405.21636 -18.649188)
		(end 405.569674 -18.649188)
		(width 0.254)
		(layer "In11.Cu")
		(net "P1V05_PCH_STBY")
	)
	(segment
		(start 386.74675 -102.756716)
		(end 386.25145 -102.98684)
		(width 0.254)
		(layer "F.Cu")
		(net "A_PVCCRTC_EXT_CAP")
	)
	(via
		(at 386.74675 -102.756716)
		(size 0.508)
		(drill 0.254)
		(layers "F.Cu" "B.Cu")
		(net "A_PVCCRTC_EXT_CAP")
	)
	(segment
		(start 386.74675 -102.756716)
		(end 386.479034 -102.489)
		(width 0.3556)
		(layer "B.Cu")
		(net "A_PVCCRTC_EXT_CAP")
	)
	(segment
		(start 386.479034 -102.489)
		(end 385.6228 -102.489)
		(width 0.3556)
		(layer "B.Cu")
		(net "A_PVCCRTC_EXT_CAP")
	)
	(segment
		(start 463.3849 -24.8793)
		(end 464.058 -24.8793)
		(width 0.254)
		(layer "F.Cu")
		(net "AGND_P3V3_STBY")
	)
	(segment
		(start 468.33155 -21.5392)
		(end 468.12835 -21.336)
		(width 0.2032)
		(layer "F.Cu")
		(net "AGND_P3V3_STBY")
	)
	(segment
		(start 464.1088 -24.8539)
		(end 464.7057 -24.8539)
		(width 0.254)
		(layer "F.Cu")
		(net "AGND_P3V3_STBY")
	)
	(segment
		(start 468.12835 -21.336)
		(end 467.9315 -21.336)
		(width 0.2032)
		(layer "F.Cu")
		(net "AGND_P3V3_STBY")
	)
	(segment
		(start 464.0961 -24.8412)
		(end 464.1088 -24.8539)
		(width 0.254)
		(layer "F.Cu")
		(net "AGND_P3V3_STBY")
	)
	(segment
		(start 468.33155 -22.0726)
		(end 468.33155 -21.5392)
		(width 0.2032)
		(layer "F.Cu")
		(net "AGND_P3V3_STBY")
	)
	(segment
		(start 465.071206 -25.77846)
		(end 464.900264 -25.949402)
		(width 0.254)
		(layer "F.Cu")
		(net "AGND_P3V3_STBY")
	)
	(segment
		(start 465.587842 -25.77846)
		(end 465.071206 -25.77846)
		(width 0.254)
		(layer "F.Cu")
		(net "AGND_P3V3_STBY")
	)
	(segment
		(start 464.058 -24.8793)
		(end 464.0961 -24.8412)
		(width 0.254)
		(layer "F.Cu")
		(net "AGND_P3V3_STBY")
	)
	(segment
		(start 467.9315 -22.0726)
		(end 467.9315 -21.336)
		(width 0.2032)
		(layer "F.Cu")
		(net "AGND_P3V3_STBY")
	)
	(via
		(at 464.900264 -25.949402)
		(size 0.508)
		(drill 0.254)
		(layers "F.Cu" "B.Cu")
		(net "AGND_P3V3_STBY")
	)
	(via
		(at 467.9315 -23.0505)
		(size 0.508)
		(drill 0.254)
		(layers "F.Cu" "B.Cu")
		(net "AGND_P3V3_STBY")
	)
	(via
		(at 466.5472 -23.114)
		(size 0.6604)
		(drill 0.3302)
		(layers "F.Cu" "B.Cu")
		(net "AGND_P3V3_STBY")
	)
	(via
		(at 464.0961 -24.8412)
		(size 0.508)
		(drill 0.254)
		(layers "F.Cu" "B.Cu")
		(net "AGND_P3V3_STBY")
	)
	(via
		(at 467.9315 -21.336)
		(size 0.508)
		(drill 0.254)
		(layers "F.Cu" "B.Cu")
		(net "AGND_P3V3_STBY")
	)
	(segment
		(start 162.56 -121.666)
		(end 162.46602 -121.75998)
		(width 0.10795)
		(layer "F.Cu")
		(net "TP_SMB_DDR_KLM_EN")
	)
	(segment
		(start 162.56 -121.031)
		(end 162.56 -121.666)
		(width 0.10795)
		(layer "F.Cu")
		(net "TP_SMB_DDR_KLM_EN")
	)
	(segment
		(start 162.33648 -120.80748)
		(end 162.56 -121.031)
		(width 0.10795)
		(layer "F.Cu")
		(net "TP_SMB_DDR_KLM_EN")
	)
	(segment
		(start 162.46602 -121.75998)
		(end 161.27222 -121.75998)
		(width 0.10795)
		(layer "F.Cu")
		(net "TP_SMB_DDR_KLM_EN")
	)
	(via
		(at 162.33648 -120.80748)
		(size 0.508)
		(drill 0.254)
		(layers "F.Cu" "B.Cu")
		(net "TP_SMB_DDR_KLM_EN")
	)
	(via
		(at 321.7926 -119.253)
		(size 0.6604)
		(drill 0.3302)
		(layers "F.Cu" "B.Cu")
		(net "TP_SMB_DDR_DEF_EN")
	)
	(segment
		(start 321.7926 -119.253)
		(end 320.9544 -120.0912)
		(width 0.10795)
		(layer "B.Cu")
		(net "TP_SMB_DDR_DEF_EN")
	)
	(segment
		(start 320.9544 -120.0912)
		(end 320.9544 -120.86844)
		(width 0.10795)
		(layer "B.Cu")
		(net "TP_SMB_DDR_DEF_EN")
	)
	(segment
		(start 320.973704 -27.644344)
		(end 321.18554 -27.85618)
		(width 0.10795)
		(layer "F.Cu")
		(net "TP_SMB_DDR_ABC_EN")
	)
	(segment
		(start 321.18554 -27.85618)
		(end 321.65798 -27.85618)
		(width 0.10795)
		(layer "F.Cu")
		(net "TP_SMB_DDR_ABC_EN")
	)
	(segment
		(start 320.480436 -27.644344)
		(end 320.973704 -27.644344)
		(width 0.10795)
		(layer "F.Cu")
		(net "TP_SMB_DDR_ABC_EN")
	)
	(via
		(at 320.480436 -27.644344)
		(size 0.762)
		(drill 0.381)
		(layers "F.Cu" "B.Cu")
		(net "TP_SMB_DDR_ABC_EN")
	)
	(segment
		(start 380.80315 -96.9772)
		(end 381.29845 -96.747076)
		(width 0.10795)
		(layer "F.Cu")
		(net "PWRGD_CPUPWRGD_GTL")
	)
	(via
		(at 373.20982 -63.263526)
		(size 0.6604)
		(drill 0.3302)
		(layers "F.Cu" "B.Cu")
		(net "PWRGD_CPUPWRGD_GTL")
	)
	(via
		(at 391.84326 -59.9567)
		(size 0.508)
		(drill 0.254)
		(layers "F.Cu" "B.Cu")
		(net "PWRGD_CPUPWRGD_GTL")
	)
	(via
		(at 381.29845 -96.747076)
		(size 0.508)
		(drill 0.254)
		(layers "F.Cu" "B.Cu")
		(net "PWRGD_CPUPWRGD_GTL")
	)
	(segment
		(start 385.701286 -61.343032)
		(end 385.479544 -61.564774)
		(width 0.10795)
		(layer "B.Cu")
		(net "PWRGD_CPUPWRGD_GTL")
	)
	(segment
		(start 391.84326 -59.9567)
		(end 391.84326 -60.214002)
		(width 0.10795)
		(layer "B.Cu")
		(net "PWRGD_CPUPWRGD_GTL")
	)
	(segment
		(start 383.15519 -64.347344)
		(end 381.332486 -62.52464)
		(width 0.10795)
		(layer "B.Cu")
		(net "PWRGD_CPUPWRGD_GTL")
	)
	(segment
		(start 371.443758 -63.048642)
		(end 371.443758 -62.635638)
		(width 0.10795)
		(layer "B.Cu")
		(net "PWRGD_CPUPWRGD_GTL")
	)
	(segment
		(start 372.3259 -63.55588)
		(end 371.950996 -63.55588)
		(width 0.10795)
		(layer "B.Cu")
		(net "PWRGD_CPUPWRGD_GTL")
	)
	(segment
		(start 385.479544 -61.564774)
		(end 385.479544 -62.09665)
		(width 0.10795)
		(layer "B.Cu")
		(net "PWRGD_CPUPWRGD_GTL")
	)
	(segment
		(start 369.134898 -60.302902)
		(end 369.20932 -60.22848)
		(width 0.10795)
		(layer "B.Cu")
		(net "PWRGD_CPUPWRGD_GTL")
	)
	(segment
		(start 371.01018 -61.29528)
		(end 369.304062 -61.29528)
		(width 0.10795)
		(layer "B.Cu")
		(net "PWRGD_CPUPWRGD_GTL")
	)
	(segment
		(start 386.68071 -60.937394)
		(end 386.275072 -61.343032)
		(width 0.10795)
		(layer "B.Cu")
		(net "PWRGD_CPUPWRGD_GTL")
	)
	(segment
		(start 375.01068 -62.829948)
		(end 374.861328 -62.9793)
		(width 0.10795)
		(layer "B.Cu")
		(net "PWRGD_CPUPWRGD_GTL")
	)
	(segment
		(start 376.973084 -62.542674)
		(end 376.312938 -62.542674)
		(width 0.10795)
		(layer "B.Cu")
		(net "PWRGD_CPUPWRGD_GTL")
	)
	(segment
		(start 376.991118 -62.52464)
		(end 376.973084 -62.542674)
		(width 0.10795)
		(layer "B.Cu")
		(net "PWRGD_CPUPWRGD_GTL")
	)
	(segment
		(start 386.275072 -61.343032)
		(end 385.701286 -61.343032)
		(width 0.10795)
		(layer "B.Cu")
		(net "PWRGD_CPUPWRGD_GTL")
	)
	(segment
		(start 377.649994 -62.525402)
		(end 377.649232 -62.52464)
		(width 0.10795)
		(layer "B.Cu")
		(net "PWRGD_CPUPWRGD_GTL")
	)
	(segment
		(start 385.477512 -62.098682)
		(end 385.477512 -63.492888)
		(width 0.10795)
		(layer "B.Cu")
		(net "PWRGD_CPUPWRGD_GTL")
	)
	(segment
		(start 372.618254 -63.263526)
		(end 372.3259 -63.55588)
		(width 0.10795)
		(layer "B.Cu")
		(net "PWRGD_CPUPWRGD_GTL")
	)
	(segment
		(start 371.950996 -63.55588)
		(end 371.443758 -63.048642)
		(width 0.10795)
		(layer "B.Cu")
		(net "PWRGD_CPUPWRGD_GTL")
	)
	(segment
		(start 376.312938 -62.542674)
		(end 376.025664 -62.829948)
		(width 0.10795)
		(layer "B.Cu")
		(net "PWRGD_CPUPWRGD_GTL")
	)
	(segment
		(start 391.84326 -60.214002)
		(end 391.376154 -60.681108)
		(width 0.10795)
		(layer "B.Cu")
		(net "PWRGD_CPUPWRGD_GTL")
	)
	(segment
		(start 369.134898 -61.126116)
		(end 369.134898 -60.302902)
		(width 0.10795)
		(layer "B.Cu")
		(net "PWRGD_CPUPWRGD_GTL")
	)
	(segment
		(start 369.20932 -60.22848)
		(end 370.3955 -60.22848)
		(width 0.10795)
		(layer "B.Cu")
		(net "PWRGD_CPUPWRGD_GTL")
	)
	(segment
		(start 374.861328 -62.9793)
		(end 373.997728 -62.9793)
		(width 0.10795)
		(layer "B.Cu")
		(net "PWRGD_CPUPWRGD_GTL")
	)
	(segment
		(start 384.623056 -64.347344)
		(end 383.15519 -64.347344)
		(width 0.10795)
		(layer "B.Cu")
		(net "PWRGD_CPUPWRGD_GTL")
	)
	(segment
		(start 385.479544 -62.09665)
		(end 385.477512 -62.098682)
		(width 0.10795)
		(layer "B.Cu")
		(net "PWRGD_CPUPWRGD_GTL")
	)
	(segment
		(start 371.62994 -62.449456)
		(end 371.62994 -61.91504)
		(width 0.10795)
		(layer "B.Cu")
		(net "PWRGD_CPUPWRGD_GTL")
	)
	(segment
		(start 387.644386 -60.937394)
		(end 386.68071 -60.937394)
		(width 0.10795)
		(layer "B.Cu")
		(net "PWRGD_CPUPWRGD_GTL")
	)
	(segment
		(start 385.477512 -63.492888)
		(end 384.623056 -64.347344)
		(width 0.10795)
		(layer "B.Cu")
		(net "PWRGD_CPUPWRGD_GTL")
	)
	(segment
		(start 378.000768 -62.52464)
		(end 378.000006 -62.525402)
		(width 0.10795)
		(layer "B.Cu")
		(net "PWRGD_CPUPWRGD_GTL")
	)
	(segment
		(start 381.332486 -62.52464)
		(end 378.000768 -62.52464)
		(width 0.10795)
		(layer "B.Cu")
		(net "PWRGD_CPUPWRGD_GTL")
	)
	(segment
		(start 371.62994 -61.91504)
		(end 371.01018 -61.29528)
		(width 0.10795)
		(layer "B.Cu")
		(net "PWRGD_CPUPWRGD_GTL")
	)
	(segment
		(start 378.000006 -62.525402)
		(end 377.649994 -62.525402)
		(width 0.10795)
		(layer "B.Cu")
		(net "PWRGD_CPUPWRGD_GTL")
	)
	(segment
		(start 373.997728 -62.9793)
		(end 373.713502 -63.263526)
		(width 0.10795)
		(layer "B.Cu")
		(net "PWRGD_CPUPWRGD_GTL")
	)
	(segment
		(start 373.713502 -63.263526)
		(end 373.20982 -63.263526)
		(width 0.10795)
		(layer "B.Cu")
		(net "PWRGD_CPUPWRGD_GTL")
	)
	(segment
		(start 376.025664 -62.829948)
		(end 375.01068 -62.829948)
		(width 0.10795)
		(layer "B.Cu")
		(net "PWRGD_CPUPWRGD_GTL")
	)
	(segment
		(start 373.20982 -63.263526)
		(end 372.618254 -63.263526)
		(width 0.10795)
		(layer "B.Cu")
		(net "PWRGD_CPUPWRGD_GTL")
	)
	(segment
		(start 377.649232 -62.52464)
		(end 376.991118 -62.52464)
		(width 0.10795)
		(layer "B.Cu")
		(net "PWRGD_CPUPWRGD_GTL")
	)
	(segment
		(start 391.376154 -60.681108)
		(end 387.900672 -60.681108)
		(width 0.10795)
		(layer "B.Cu")
		(net "PWRGD_CPUPWRGD_GTL")
	)
	(segment
		(start 387.900672 -60.681108)
		(end 387.644386 -60.937394)
		(width 0.10795)
		(layer "B.Cu")
		(net "PWRGD_CPUPWRGD_GTL")
	)
	(segment
		(start 369.304062 -61.29528)
		(end 369.134898 -61.126116)
		(width 0.10795)
		(layer "B.Cu")
		(net "PWRGD_CPUPWRGD_GTL")
	)
	(segment
		(start 371.443758 -62.635638)
		(end 371.62994 -62.449456)
		(width 0.10795)
		(layer "B.Cu")
		(net "PWRGD_CPUPWRGD_GTL")
	)
	(segment
		(start 381.742188 -88.036908)
		(end 382.705102 -88.036908)
		(width 0.089408)
		(layer "In9.Cu")
		(net "PWRGD_CPUPWRGD_GTL")
	)
	(segment
		(start 381.29845 -96.747076)
		(end 381.636524 -96.747076)
		(width 0.0889)
		(layer "In9.Cu")
		(net "PWRGD_CPUPWRGD_GTL")
	)
	(segment
		(start 386.357368 -77.818996)
		(end 388.526782 -75.649582)
		(width 0.089408)
		(layer "In9.Cu")
		(net "PWRGD_CPUPWRGD_GTL")
	)
	(segment
		(start 388.526782 -75.649582)
		(end 388.526782 -74.245724)
		(width 0.089408)
		(layer "In9.Cu")
		(net "PWRGD_CPUPWRGD_GTL")
	)
	(segment
		(start 381.2032 -91.5416)
		(end 381.34544 -91.39936)
		(width 0.089408)
		(layer "In9.Cu")
		(net "PWRGD_CPUPWRGD_GTL")
	)
	(segment
		(start 388.526782 -74.245724)
		(end 388.3406 -74.059542)
		(width 0.089408)
		(layer "In9.Cu")
		(net "PWRGD_CPUPWRGD_GTL")
	)
	(segment
		(start 386.665978 -84.780882)
		(end 386.96138 -84.48548)
		(width 0.089408)
		(layer "In9.Cu")
		(net "PWRGD_CPUPWRGD_GTL")
	)
	(segment
		(start 390.100312 -70.909688)
		(end 390.100312 -69.374258)
		(width 0.089408)
		(layer "In9.Cu")
		(net "PWRGD_CPUPWRGD_GTL")
	)
	(segment
		(start 389.312658 -68.586604)
		(end 389.312658 -66.76644)
		(width 0.089408)
		(layer "In9.Cu")
		(net "PWRGD_CPUPWRGD_GTL")
	)
	(segment
		(start 388.3406 -74.059542)
		(end 388.3406 -72.6694)
		(width 0.089408)
		(layer "In9.Cu")
		(net "PWRGD_CPUPWRGD_GTL")
	)
	(segment
		(start 388.3406 -72.6694)
		(end 390.100312 -70.909688)
		(width 0.089408)
		(layer "In9.Cu")
		(net "PWRGD_CPUPWRGD_GTL")
	)
	(segment
		(start 386.662168 -81.318608)
		(end 386.662168 -80.20431)
		(width 0.089408)
		(layer "In9.Cu")
		(net "PWRGD_CPUPWRGD_GTL")
	)
	(segment
		(start 386.357368 -79.89951)
		(end 386.357368 -77.818996)
		(width 0.089408)
		(layer "In9.Cu")
		(net "PWRGD_CPUPWRGD_GTL")
	)
	(segment
		(start 381.34544 -91.39936)
		(end 381.34544 -88.433656)
		(width 0.089408)
		(layer "In9.Cu")
		(net "PWRGD_CPUPWRGD_GTL")
	)
	(segment
		(start 382.705102 -88.036908)
		(end 385.961128 -84.780882)
		(width 0.089408)
		(layer "In9.Cu")
		(net "PWRGD_CPUPWRGD_GTL")
	)
	(segment
		(start 381.636524 -96.747076)
		(end 381.694436 -96.689164)
		(width 0.0889)
		(layer "In9.Cu")
		(net "PWRGD_CPUPWRGD_GTL")
	)
	(segment
		(start 391.096246 -64.982852)
		(end 391.096246 -61.2775)
		(width 0.089408)
		(layer "In9.Cu")
		(net "PWRGD_CPUPWRGD_GTL")
	)
	(segment
		(start 386.96138 -81.61782)
		(end 386.662168 -81.318608)
		(width 0.089408)
		(layer "In9.Cu")
		(net "PWRGD_CPUPWRGD_GTL")
	)
	(segment
		(start 385.961128 -84.780882)
		(end 386.665978 -84.780882)
		(width 0.089408)
		(layer "In9.Cu")
		(net "PWRGD_CPUPWRGD_GTL")
	)
	(segment
		(start 386.96138 -84.48548)
		(end 386.96138 -81.61782)
		(width 0.089408)
		(layer "In9.Cu")
		(net "PWRGD_CPUPWRGD_GTL")
	)
	(segment
		(start 386.662168 -80.20431)
		(end 386.357368 -79.89951)
		(width 0.089408)
		(layer "In9.Cu")
		(net "PWRGD_CPUPWRGD_GTL")
	)
	(segment
		(start 389.312658 -66.76644)
		(end 391.096246 -64.982852)
		(width 0.089408)
		(layer "In9.Cu")
		(net "PWRGD_CPUPWRGD_GTL")
	)
	(segment
		(start 390.100312 -69.374258)
		(end 389.312658 -68.586604)
		(width 0.089408)
		(layer "In9.Cu")
		(net "PWRGD_CPUPWRGD_GTL")
	)
	(segment
		(start 381.2032 -95.910146)
		(end 381.2032 -95.197676)
		(width 0.0889)
		(layer "In9.Cu")
		(net "PWRGD_CPUPWRGD_GTL")
	)
	(segment
		(start 381.2032 -95.197676)
		(end 381.2032 -91.5416)
		(width 0.089408)
		(layer "In9.Cu")
		(net "PWRGD_CPUPWRGD_GTL")
	)
	(segment
		(start 391.096246 -61.2775)
		(end 391.84326 -60.530486)
		(width 0.089408)
		(layer "In9.Cu")
		(net "PWRGD_CPUPWRGD_GTL")
	)
	(segment
		(start 391.84326 -60.530486)
		(end 391.84326 -59.9567)
		(width 0.089408)
		(layer "In9.Cu")
		(net "PWRGD_CPUPWRGD_GTL")
	)
	(segment
		(start 381.34544 -88.433656)
		(end 381.742188 -88.036908)
		(width 0.089408)
		(layer "In9.Cu")
		(net "PWRGD_CPUPWRGD_GTL")
	)
	(arc
		(start 381.694436 -96.689164)
		(mid 381.629536 -96.522263)
		(end 381.498348 -96.400366)
		(width 0.0889)
		(layer "In9.Cu")
		(net "PWRGD_CPUPWRGD_GTL")
	)
	(arc
		(start 381.498348 -96.400366)
		(mid 381.287484 -96.193362)
		(end 381.2032 -95.910146)
		(width 0.0889)
		(layer "In9.Cu")
		(net "PWRGD_CPUPWRGD_GTL")
	)
	(segment
		(start 132.806694 -70.268084)
		(end 133.378194 -70.268084)
		(width 0.10795)
		(layer "F.Cu")
		(net "PD_CPU1_DMIMODE_OVERRIDE")
	)
	(via
		(at 133.378194 -70.268084)
		(size 0.508)
		(drill 0.254)
		(layers "F.Cu" "B.Cu")
		(net "PD_CPU1_DMIMODE_OVERRIDE")
	)
	(via
		(at 120.063768 -74.26579)
		(size 0.6604)
		(drill 0.3302)
		(layers "F.Cu" "B.Cu")
		(net "PD_CPU1_DMIMODE_OVERRIDE")
	)
	(segment
		(start 122.030236 -74.288904)
		(end 122.419872 -74.288904)
		(width 0.10795)
		(layer "B.Cu")
		(net "PD_CPU1_DMIMODE_OVERRIDE")
	)
	(segment
		(start 126.718568 -73.693528)
		(end 127.123444 -73.288652)
		(width 0.10795)
		(layer "B.Cu")
		(net "PD_CPU1_DMIMODE_OVERRIDE")
	)
	(segment
		(start 122.86869 -74.737722)
		(end 123.146058 -74.737722)
		(width 0.10795)
		(layer "B.Cu")
		(net "PD_CPU1_DMIMODE_OVERRIDE")
	)
	(segment
		(start 132.337048 -71.208646)
		(end 132.722366 -71.208646)
		(width 0.10795)
		(layer "B.Cu")
		(net "PD_CPU1_DMIMODE_OVERRIDE")
	)
	(segment
		(start 117.693186 -75.692)
		(end 119.130572 -74.254614)
		(width 0.10795)
		(layer "B.Cu")
		(net "PD_CPU1_DMIMODE_OVERRIDE")
	)
	(segment
		(start 131.832096 -71.713598)
		(end 132.337048 -71.208646)
		(width 0.10795)
		(layer "B.Cu")
		(net "PD_CPU1_DMIMODE_OVERRIDE")
	)
	(segment
		(start 130.68808 -72.231758)
		(end 130.923792 -72.231758)
		(width 0.10795)
		(layer "B.Cu")
		(net "PD_CPU1_DMIMODE_OVERRIDE")
	)
	(segment
		(start 123.656344 -74.227436)
		(end 124.14123 -74.227436)
		(width 0.10795)
		(layer "B.Cu")
		(net "PD_CPU1_DMIMODE_OVERRIDE")
	)
	(segment
		(start 124.14123 -74.227436)
		(end 124.630688 -74.716894)
		(width 0.10795)
		(layer "B.Cu")
		(net "PD_CPU1_DMIMODE_OVERRIDE")
	)
	(segment
		(start 125.733556 -74.316844)
		(end 126.356872 -73.693528)
		(width 0.10795)
		(layer "B.Cu")
		(net "PD_CPU1_DMIMODE_OVERRIDE")
	)
	(segment
		(start 127.651764 -73.288652)
		(end 128.028446 -73.665334)
		(width 0.10795)
		(layer "B.Cu")
		(net "PD_CPU1_DMIMODE_OVERRIDE")
	)
	(segment
		(start 124.630688 -74.716894)
		(end 124.99213 -74.716894)
		(width 0.10795)
		(layer "B.Cu")
		(net "PD_CPU1_DMIMODE_OVERRIDE")
	)
	(segment
		(start 129.251202 -73.302114)
		(end 129.839466 -72.71385)
		(width 0.10795)
		(layer "B.Cu")
		(net "PD_CPU1_DMIMODE_OVERRIDE")
	)
	(segment
		(start 128.828038 -73.302114)
		(end 129.251202 -73.302114)
		(width 0.10795)
		(layer "B.Cu")
		(net "PD_CPU1_DMIMODE_OVERRIDE")
	)
	(segment
		(start 119.130572 -74.254614)
		(end 120.052592 -74.254614)
		(width 0.10795)
		(layer "B.Cu")
		(net "PD_CPU1_DMIMODE_OVERRIDE")
	)
	(segment
		(start 130.923792 -72.231758)
		(end 131.441952 -71.713598)
		(width 0.10795)
		(layer "B.Cu")
		(net "PD_CPU1_DMIMODE_OVERRIDE")
	)
	(segment
		(start 127.123444 -73.288652)
		(end 127.651764 -73.288652)
		(width 0.10795)
		(layer "B.Cu")
		(net "PD_CPU1_DMIMODE_OVERRIDE")
	)
	(segment
		(start 125.39218 -74.316844)
		(end 125.733556 -74.316844)
		(width 0.10795)
		(layer "B.Cu")
		(net "PD_CPU1_DMIMODE_OVERRIDE")
	)
	(segment
		(start 129.839466 -72.71385)
		(end 130.205988 -72.71385)
		(width 0.10795)
		(layer "B.Cu")
		(net "PD_CPU1_DMIMODE_OVERRIDE")
	)
	(segment
		(start 126.356872 -73.693528)
		(end 126.718568 -73.693528)
		(width 0.10795)
		(layer "B.Cu")
		(net "PD_CPU1_DMIMODE_OVERRIDE")
	)
	(segment
		(start 128.464818 -73.665334)
		(end 128.828038 -73.302114)
		(width 0.10795)
		(layer "B.Cu")
		(net "PD_CPU1_DMIMODE_OVERRIDE")
	)
	(segment
		(start 120.063768 -74.26579)
		(end 120.466104 -74.668126)
		(width 0.10795)
		(layer "B.Cu")
		(net "PD_CPU1_DMIMODE_OVERRIDE")
	)
	(segment
		(start 130.205988 -72.71385)
		(end 130.68808 -72.231758)
		(width 0.10795)
		(layer "B.Cu")
		(net "PD_CPU1_DMIMODE_OVERRIDE")
	)
	(segment
		(start 128.028446 -73.665334)
		(end 128.464818 -73.665334)
		(width 0.10795)
		(layer "B.Cu")
		(net "PD_CPU1_DMIMODE_OVERRIDE")
	)
	(segment
		(start 117.221 -75.692)
		(end 117.693186 -75.692)
		(width 0.10795)
		(layer "B.Cu")
		(net "PD_CPU1_DMIMODE_OVERRIDE")
	)
	(segment
		(start 123.146058 -74.737722)
		(end 123.656344 -74.227436)
		(width 0.10795)
		(layer "B.Cu")
		(net "PD_CPU1_DMIMODE_OVERRIDE")
	)
	(segment
		(start 122.419872 -74.288904)
		(end 122.86869 -74.737722)
		(width 0.10795)
		(layer "B.Cu")
		(net "PD_CPU1_DMIMODE_OVERRIDE")
	)
	(segment
		(start 133.378194 -70.552818)
		(end 133.378194 -70.268084)
		(width 0.10795)
		(layer "B.Cu")
		(net "PD_CPU1_DMIMODE_OVERRIDE")
	)
	(segment
		(start 120.466104 -74.668126)
		(end 121.651014 -74.668126)
		(width 0.10795)
		(layer "B.Cu")
		(net "PD_CPU1_DMIMODE_OVERRIDE")
	)
	(segment
		(start 121.651014 -74.668126)
		(end 122.030236 -74.288904)
		(width 0.10795)
		(layer "B.Cu")
		(net "PD_CPU1_DMIMODE_OVERRIDE")
	)
	(segment
		(start 124.99213 -74.716894)
		(end 125.39218 -74.316844)
		(width 0.10795)
		(layer "B.Cu")
		(net "PD_CPU1_DMIMODE_OVERRIDE")
	)
	(segment
		(start 131.441952 -71.713598)
		(end 131.832096 -71.713598)
		(width 0.10795)
		(layer "B.Cu")
		(net "PD_CPU1_DMIMODE_OVERRIDE")
	)
	(segment
		(start 132.722366 -71.208646)
		(end 133.378194 -70.552818)
		(width 0.10795)
		(layer "B.Cu")
		(net "PD_CPU1_DMIMODE_OVERRIDE")
	)
	(segment
		(start 120.052592 -74.254614)
		(end 120.063768 -74.26579)
		(width 0.10795)
		(layer "B.Cu")
		(net "PD_CPU1_DMIMODE_OVERRIDE")
	)
	(segment
		(start 297.807126 -70.268084)
		(end 298.378626 -70.268084)
		(width 0.10795)
		(layer "F.Cu")
		(net "PD_CPU0_DMIMODE_OVERRIDE")
	)
	(via
		(at 298.378626 -70.268084)
		(size 0.508)
		(drill 0.254)
		(layers "F.Cu" "B.Cu")
		(net "PD_CPU0_DMIMODE_OVERRIDE")
	)
	(via
		(at 285.437326 -73.818496)
		(size 0.6604)
		(drill 0.3302)
		(layers "F.Cu" "B.Cu")
		(net "PD_CPU0_DMIMODE_OVERRIDE")
	)
	(segment
		(start 293.026592 -70.773036)
		(end 293.428928 -70.773036)
		(width 0.10795)
		(layer "B.Cu")
		(net "PD_CPU0_DMIMODE_OVERRIDE")
	)
	(segment
		(start 287.909 -71.6788)
		(end 288.23412 -71.6788)
		(width 0.10795)
		(layer "B.Cu")
		(net "PD_CPU0_DMIMODE_OVERRIDE")
	)
	(segment
		(start 297.726608 -70.265036)
		(end 297.729656 -70.268084)
		(width 0.10795)
		(layer "B.Cu")
		(net "PD_CPU0_DMIMODE_OVERRIDE")
	)
	(segment
		(start 297.729656 -70.268084)
		(end 298.378626 -70.268084)
		(width 0.10795)
		(layer "B.Cu")
		(net "PD_CPU0_DMIMODE_OVERRIDE")
	)
	(segment
		(start 296.7736 -70.739)
		(end 297.247564 -70.265036)
		(width 0.10795)
		(layer "B.Cu")
		(net "PD_CPU0_DMIMODE_OVERRIDE")
	)
	(segment
		(start 286.87268 -72.3138)
		(end 287.274 -72.3138)
		(width 0.10795)
		(layer "B.Cu")
		(net "PD_CPU0_DMIMODE_OVERRIDE")
	)
	(segment
		(start 286.364934 -72.657716)
		(end 286.528764 -72.657716)
		(width 0.10795)
		(layer "B.Cu")
		(net "PD_CPU0_DMIMODE_OVERRIDE")
	)
	(segment
		(start 282.746196 -75.165204)
		(end 283.334206 -74.577194)
		(width 0.10795)
		(layer "B.Cu")
		(net "PD_CPU0_DMIMODE_OVERRIDE")
	)
	(segment
		(start 288.567114 -71.345806)
		(end 289.168332 -71.345806)
		(width 0.10795)
		(layer "B.Cu")
		(net "PD_CPU0_DMIMODE_OVERRIDE")
	)
	(segment
		(start 290.486592 -71.247)
		(end 290.921694 -71.247)
		(width 0.10795)
		(layer "B.Cu")
		(net "PD_CPU0_DMIMODE_OVERRIDE")
	)
	(segment
		(start 282.746196 -75.241404)
		(end 282.746196 -75.165204)
		(width 0.10795)
		(layer "B.Cu")
		(net "PD_CPU0_DMIMODE_OVERRIDE")
	)
	(segment
		(start 282.2702 -75.7174)
		(end 282.746196 -75.241404)
		(width 0.10795)
		(layer "B.Cu")
		(net "PD_CPU0_DMIMODE_OVERRIDE")
	)
	(segment
		(start 288.23412 -71.6788)
		(end 288.567114 -71.345806)
		(width 0.10795)
		(layer "B.Cu")
		(net "PD_CPU0_DMIMODE_OVERRIDE")
	)
	(segment
		(start 297.247564 -70.265036)
		(end 297.726608 -70.265036)
		(width 0.10795)
		(layer "B.Cu")
		(net "PD_CPU0_DMIMODE_OVERRIDE")
	)
	(segment
		(start 285.437326 -73.818496)
		(end 285.896812 -73.35901)
		(width 0.10795)
		(layer "B.Cu")
		(net "PD_CPU0_DMIMODE_OVERRIDE")
	)
	(segment
		(start 291.34181 -71.667116)
		(end 291.781484 -71.667116)
		(width 0.10795)
		(layer "B.Cu")
		(net "PD_CPU0_DMIMODE_OVERRIDE")
	)
	(segment
		(start 292.1508 -71.2978)
		(end 292.501828 -71.2978)
		(width 0.10795)
		(layer "B.Cu")
		(net "PD_CPU0_DMIMODE_OVERRIDE")
	)
	(segment
		(start 289.587178 -70.76059)
		(end 290.000182 -70.76059)
		(width 0.10795)
		(layer "B.Cu")
		(net "PD_CPU0_DMIMODE_OVERRIDE")
	)
	(segment
		(start 289.295332 -71.052436)
		(end 289.587178 -70.76059)
		(width 0.10795)
		(layer "B.Cu")
		(net "PD_CPU0_DMIMODE_OVERRIDE")
	)
	(segment
		(start 295.226994 -70.7644)
		(end 295.634156 -71.171562)
		(width 0.10795)
		(layer "B.Cu")
		(net "PD_CPU0_DMIMODE_OVERRIDE")
	)
	(segment
		(start 284.114748 -74.2696)
		(end 284.986222 -74.2696)
		(width 0.10795)
		(layer "B.Cu")
		(net "PD_CPU0_DMIMODE_OVERRIDE")
	)
	(segment
		(start 296.405046 -70.739)
		(end 296.7736 -70.739)
		(width 0.10795)
		(layer "B.Cu")
		(net "PD_CPU0_DMIMODE_OVERRIDE")
	)
	(segment
		(start 293.923974 -71.268082)
		(end 294.212518 -71.268082)
		(width 0.10795)
		(layer "B.Cu")
		(net "PD_CPU0_DMIMODE_OVERRIDE")
	)
	(segment
		(start 295.634156 -71.171562)
		(end 295.972484 -71.171562)
		(width 0.10795)
		(layer "B.Cu")
		(net "PD_CPU0_DMIMODE_OVERRIDE")
	)
	(segment
		(start 295.972484 -71.171562)
		(end 296.405046 -70.739)
		(width 0.10795)
		(layer "B.Cu")
		(net "PD_CPU0_DMIMODE_OVERRIDE")
	)
	(segment
		(start 289.295332 -71.218806)
		(end 289.295332 -71.052436)
		(width 0.10795)
		(layer "B.Cu")
		(net "PD_CPU0_DMIMODE_OVERRIDE")
	)
	(segment
		(start 284.986222 -74.2696)
		(end 285.437326 -73.818496)
		(width 0.10795)
		(layer "B.Cu")
		(net "PD_CPU0_DMIMODE_OVERRIDE")
	)
	(segment
		(start 293.428928 -70.773036)
		(end 293.923974 -71.268082)
		(width 0.10795)
		(layer "B.Cu")
		(net "PD_CPU0_DMIMODE_OVERRIDE")
	)
	(segment
		(start 287.274 -72.3138)
		(end 287.909 -71.6788)
		(width 0.10795)
		(layer "B.Cu")
		(net "PD_CPU0_DMIMODE_OVERRIDE")
	)
	(segment
		(start 283.807154 -74.577194)
		(end 284.114748 -74.2696)
		(width 0.10795)
		(layer "B.Cu")
		(net "PD_CPU0_DMIMODE_OVERRIDE")
	)
	(segment
		(start 285.896812 -73.35901)
		(end 285.896812 -73.125838)
		(width 0.10795)
		(layer "B.Cu")
		(net "PD_CPU0_DMIMODE_OVERRIDE")
	)
	(segment
		(start 294.212518 -71.268082)
		(end 294.7162 -70.7644)
		(width 0.10795)
		(layer "B.Cu")
		(net "PD_CPU0_DMIMODE_OVERRIDE")
	)
	(segment
		(start 292.501828 -71.2978)
		(end 293.026592 -70.773036)
		(width 0.10795)
		(layer "B.Cu")
		(net "PD_CPU0_DMIMODE_OVERRIDE")
	)
	(segment
		(start 290.000182 -70.76059)
		(end 290.486592 -71.247)
		(width 0.10795)
		(layer "B.Cu")
		(net "PD_CPU0_DMIMODE_OVERRIDE")
	)
	(segment
		(start 286.528764 -72.657716)
		(end 286.87268 -72.3138)
		(width 0.10795)
		(layer "B.Cu")
		(net "PD_CPU0_DMIMODE_OVERRIDE")
	)
	(segment
		(start 289.168332 -71.345806)
		(end 289.295332 -71.218806)
		(width 0.10795)
		(layer "B.Cu")
		(net "PD_CPU0_DMIMODE_OVERRIDE")
	)
	(segment
		(start 285.896812 -73.125838)
		(end 286.364934 -72.657716)
		(width 0.10795)
		(layer "B.Cu")
		(net "PD_CPU0_DMIMODE_OVERRIDE")
	)
	(segment
		(start 290.921694 -71.247)
		(end 291.34181 -71.667116)
		(width 0.10795)
		(layer "B.Cu")
		(net "PD_CPU0_DMIMODE_OVERRIDE")
	)
	(segment
		(start 294.7162 -70.7644)
		(end 295.226994 -70.7644)
		(width 0.10795)
		(layer "B.Cu")
		(net "PD_CPU0_DMIMODE_OVERRIDE")
	)
	(segment
		(start 291.781484 -71.667116)
		(end 292.1508 -71.2978)
		(width 0.10795)
		(layer "B.Cu")
		(net "PD_CPU0_DMIMODE_OVERRIDE")
	)
	(segment
		(start 283.334206 -74.577194)
		(end 283.807154 -74.577194)
		(width 0.10795)
		(layer "B.Cu")
		(net "PD_CPU0_DMIMODE_OVERRIDE")
	)
	(segment
		(start 384.866388 -76.026264)
		(end 385.104894 -75.787758)
		(width 0.10795)
		(layer "F.Cu")
		(net "H_CPU_ERR2_GTL_N")
	)
	(segment
		(start 384.422904 -76.026264)
		(end 384.866388 -76.026264)
		(width 0.10795)
		(layer "F.Cu")
		(net "H_CPU_ERR2_GTL_N")
	)
	(segment
		(start 385.104894 -75.787758)
		(end 386.326888 -75.787758)
		(width 0.10795)
		(layer "F.Cu")
		(net "H_CPU_ERR2_GTL_N")
	)
	(segment
		(start 372.411752 -43.504358)
		(end 371.728492 -44.187618)
		(width 0.10795)
		(layer "B.Cu")
		(net "H_CPU_ERR1_GTL_N")
	)
	(segment
		(start 371.728492 -44.187618)
		(end 370.290852 -44.187618)
		(width 0.10795)
		(layer "B.Cu")
		(net "H_CPU_ERR1_GTL_N")
	)
	(via
		(at 370.088922 -41.01973)
		(size 0.6604)
		(drill 0.3302)
		(layers "F.Cu" "B.Cu")
		(net "H_CPU_ERR0_GTL_N")
	)
	(segment
		(start 370.088922 -41.01973)
		(end 370.57584 -41.506648)
		(width 0.10795)
		(layer "B.Cu")
		(net "H_CPU_ERR0_GTL_N")
	)
	(segment
		(start 371.6401 -42.5831)
		(end 371.6401 -43.296078)
		(width 0.10795)
		(layer "B.Cu")
		(net "H_CPU_ERR0_GTL_N")
	)
	(segment
		(start 371.3988 -43.537378)
		(end 370.290852 -43.537378)
		(width 0.10795)
		(layer "B.Cu")
		(net "H_CPU_ERR0_GTL_N")
	)
	(segment
		(start 370.57584 -41.506648)
		(end 370.986558 -41.506648)
		(width 0.10795)
		(layer "B.Cu")
		(net "H_CPU_ERR0_GTL_N")
	)
	(segment
		(start 370.986558 -41.506648)
		(end 370.986558 -41.929558)
		(width 0.10795)
		(layer "B.Cu")
		(net "H_CPU_ERR0_GTL_N")
	)
	(segment
		(start 371.6401 -43.296078)
		(end 371.3988 -43.537378)
		(width 0.10795)
		(layer "B.Cu")
		(net "H_CPU_ERR0_GTL_N")
	)
	(segment
		(start 370.986558 -41.929558)
		(end 371.6401 -42.5831)
		(width 0.10795)
		(layer "B.Cu")
		(net "H_CPU_ERR0_GTL_N")
	)
	(segment
		(start 133.665214 -65.810384)
		(end 134.236714 -65.810384)
		(width 0.1016)
		(layer "F.Cu")
		(net "H_CPU1_ERR1_G_N")
	)
	(via
		(at 134.236714 -65.810384)
		(size 0.508)
		(drill 0.254)
		(layers "F.Cu" "B.Cu")
		(net "H_CPU1_ERR1_G_N")
	)
	(via
		(at 374.367552 -44.125134)
		(size 0.508)
		(drill 0.254)
		(layers "F.Cu" "B.Cu")
		(net "H_CPU1_ERR1_G_N")
	)
	(via
		(at 367.791746 -52.23383)
		(size 0.508)
		(drill 0.254)
		(layers "F.Cu" "B.Cu")
		(net "H_CPU1_ERR1_G_N")
	)
	(via
		(at 321.093084 -38.248336)
		(size 0.508)
		(drill 0.254)
		(layers "F.Cu" "B.Cu")
		(net "H_CPU1_ERR1_G_N")
	)
	(via
		(at 186.751214 -22.435566)
		(size 0.508)
		(drill 0.254)
		(layers "F.Cu" "B.Cu")
		(net "H_CPU1_ERR1_G_N")
	)
	(via
		(at 161.79419 -73.219056)
		(size 0.508)
		(drill 0.254)
		(layers "F.Cu" "B.Cu")
		(net "H_CPU1_ERR1_G_N")
	)
	(segment
		(start 374.646952 -43.224958)
		(end 374.646952 -43.845734)
		(width 0.10795)
		(layer "B.Cu")
		(net "H_CPU1_ERR1_G_N")
	)
	(segment
		(start 374.646952 -43.845734)
		(end 374.367552 -44.125134)
		(width 0.10795)
		(layer "B.Cu")
		(net "H_CPU1_ERR1_G_N")
	)
	(segment
		(start 133.922516 -66.058288)
		(end 133.943598 -65.979548)
		(width 0.0889)
		(layer "In4.Cu")
		(net "H_CPU1_ERR1_G_N")
	)
	(segment
		(start 139.40282 -66.210434)
		(end 139.372848 -66.210434)
		(width 0.0889)
		(layer "In4.Cu")
		(net "H_CPU1_ERR1_G_N")
	)
	(segment
		(start 133.943598 -65.979548)
		(end 134.236714 -65.810384)
		(width 0.0889)
		(layer "In4.Cu")
		(net "H_CPU1_ERR1_G_N")
	)
	(segment
		(start 155.263596 -68.39077)
		(end 146.20494 -68.39077)
		(width 0.089408)
		(layer "In4.Cu")
		(net "H_CPU1_ERR1_G_N")
	)
	(segment
		(start 141.208506 -66.210434)
		(end 141.089888 -66.210434)
		(width 0.0889)
		(layer "In4.Cu")
		(net "H_CPU1_ERR1_G_N")
	)
	(segment
		(start 138.550904 -65.715388)
		(end 138.507724 -65.715388)
		(width 0.0889)
		(layer "In4.Cu")
		(net "H_CPU1_ERR1_G_N")
	)
	(segment
		(start 141.215364 -66.203576)
		(end 141.208506 -66.210434)
		(width 0.0889)
		(layer "In4.Cu")
		(net "H_CPU1_ERR1_G_N")
	)
	(segment
		(start 144.017746 -66.210434)
		(end 143.817848 -66.010536)
		(width 0.089408)
		(layer "In4.Cu")
		(net "H_CPU1_ERR1_G_N")
	)
	(segment
		(start 140.267944 -65.715388)
		(end 140.224764 -65.715388)
		(width 0.0889)
		(layer "In4.Cu")
		(net "H_CPU1_ERR1_G_N")
	)
	(segment
		(start 143.817848 -66.010536)
		(end 141.482064 -66.010536)
		(width 0.089408)
		(layer "In4.Cu")
		(net "H_CPU1_ERR1_G_N")
	)
	(segment
		(start 141.482064 -66.010536)
		(end 141.289024 -66.203576)
		(width 0.089408)
		(layer "In4.Cu")
		(net "H_CPU1_ERR1_G_N")
	)
	(segment
		(start 146.20494 -68.39077)
		(end 144.024604 -66.210434)
		(width 0.089408)
		(layer "In4.Cu")
		(net "H_CPU1_ERR1_G_N")
	)
	(segment
		(start 136.833864 -65.715388)
		(end 136.790684 -65.715388)
		(width 0.0889)
		(layer "In4.Cu")
		(net "H_CPU1_ERR1_G_N")
	)
	(segment
		(start 144.024604 -66.210434)
		(end 144.017746 -66.210434)
		(width 0.089408)
		(layer "In4.Cu")
		(net "H_CPU1_ERR1_G_N")
	)
	(segment
		(start 161.09315 -72.518016)
		(end 159.390842 -72.518016)
		(width 0.089408)
		(layer "In4.Cu")
		(net "H_CPU1_ERR1_G_N")
	)
	(segment
		(start 159.390842 -72.518016)
		(end 155.263596 -68.39077)
		(width 0.089408)
		(layer "In4.Cu")
		(net "H_CPU1_ERR1_G_N")
	)
	(segment
		(start 134.2517 -66.210434)
		(end 134.221728 -66.210434)
		(width 0.0889)
		(layer "In4.Cu")
		(net "H_CPU1_ERR1_G_N")
	)
	(segment
		(start 141.289024 -66.203576)
		(end 141.215364 -66.203576)
		(width 0.0889)
		(layer "In4.Cu")
		(net "H_CPU1_ERR1_G_N")
	)
	(segment
		(start 135.116824 -65.715388)
		(end 135.073644 -65.715388)
		(width 0.0889)
		(layer "In4.Cu")
		(net "H_CPU1_ERR1_G_N")
	)
	(segment
		(start 135.96874 -66.210434)
		(end 135.938768 -66.210434)
		(width 0.0889)
		(layer "In4.Cu")
		(net "H_CPU1_ERR1_G_N")
	)
	(segment
		(start 137.68578 -66.210434)
		(end 137.655808 -66.210434)
		(width 0.0889)
		(layer "In4.Cu")
		(net "H_CPU1_ERR1_G_N")
	)
	(segment
		(start 161.79419 -73.219056)
		(end 161.09315 -72.518016)
		(width 0.089408)
		(layer "In4.Cu")
		(net "H_CPU1_ERR1_G_N")
	)
	(arc
		(start 140.758164 -66.010536)
		(mid 140.55116 -65.799672)
		(end 140.267944 -65.715388)
		(width 0.0889)
		(layer "In4.Cu")
		(net "H_CPU1_ERR1_G_N")
	)
	(arc
		(start 137.324084 -66.010536)
		(mid 137.11708 -65.799672)
		(end 136.833864 -65.715388)
		(width 0.0889)
		(layer "In4.Cu")
		(net "H_CPU1_ERR1_G_N")
	)
	(arc
		(start 136.300464 -66.010536)
		(mid 136.160385 -66.153272)
		(end 135.96874 -66.210434)
		(width 0.0889)
		(layer "In4.Cu")
		(net "H_CPU1_ERR1_G_N")
	)
	(arc
		(start 138.507724 -65.715388)
		(mid 138.224507 -65.799669)
		(end 138.017504 -66.010536)
		(width 0.0889)
		(layer "In4.Cu")
		(net "H_CPU1_ERR1_G_N")
	)
	(arc
		(start 140.224764 -65.715388)
		(mid 139.941547 -65.799669)
		(end 139.734544 -66.010536)
		(width 0.0889)
		(layer "In4.Cu")
		(net "H_CPU1_ERR1_G_N")
	)
	(arc
		(start 139.734544 -66.010536)
		(mid 139.594465 -66.153272)
		(end 139.40282 -66.210434)
		(width 0.0889)
		(layer "In4.Cu")
		(net "H_CPU1_ERR1_G_N")
	)
	(arc
		(start 139.372848 -66.210434)
		(mid 139.181206 -66.153268)
		(end 139.041124 -66.010536)
		(width 0.0889)
		(layer "In4.Cu")
		(net "H_CPU1_ERR1_G_N")
	)
	(arc
		(start 141.089888 -66.210434)
		(mid 140.898246 -66.153268)
		(end 140.758164 -66.010536)
		(width 0.0889)
		(layer "In4.Cu")
		(net "H_CPU1_ERR1_G_N")
	)
	(arc
		(start 135.073644 -65.715388)
		(mid 134.790427 -65.799669)
		(end 134.583424 -66.010536)
		(width 0.0889)
		(layer "In4.Cu")
		(net "H_CPU1_ERR1_G_N")
	)
	(arc
		(start 135.607044 -66.010536)
		(mid 135.40004 -65.799672)
		(end 135.116824 -65.715388)
		(width 0.0889)
		(layer "In4.Cu")
		(net "H_CPU1_ERR1_G_N")
	)
	(arc
		(start 139.041124 -66.010536)
		(mid 138.83412 -65.799672)
		(end 138.550904 -65.715388)
		(width 0.0889)
		(layer "In4.Cu")
		(net "H_CPU1_ERR1_G_N")
	)
	(arc
		(start 136.790684 -65.715388)
		(mid 136.507467 -65.799669)
		(end 136.300464 -66.010536)
		(width 0.0889)
		(layer "In4.Cu")
		(net "H_CPU1_ERR1_G_N")
	)
	(arc
		(start 138.017504 -66.010536)
		(mid 137.877425 -66.153272)
		(end 137.68578 -66.210434)
		(width 0.0889)
		(layer "In4.Cu")
		(net "H_CPU1_ERR1_G_N")
	)
	(arc
		(start 134.221728 -66.210434)
		(mid 134.055434 -66.1672)
		(end 133.922516 -66.058288)
		(width 0.0889)
		(layer "In4.Cu")
		(net "H_CPU1_ERR1_G_N")
	)
	(arc
		(start 134.583424 -66.010536)
		(mid 134.443345 -66.153272)
		(end 134.2517 -66.210434)
		(width 0.0889)
		(layer "In4.Cu")
		(net "H_CPU1_ERR1_G_N")
	)
	(arc
		(start 135.938768 -66.210434)
		(mid 135.747126 -66.153268)
		(end 135.607044 -66.010536)
		(width 0.0889)
		(layer "In4.Cu")
		(net "H_CPU1_ERR1_G_N")
	)
	(arc
		(start 137.655808 -66.210434)
		(mid 137.464166 -66.153268)
		(end 137.324084 -66.010536)
		(width 0.0889)
		(layer "In4.Cu")
		(net "H_CPU1_ERR1_G_N")
	)
	(segment
		(start 193.53022 -22.229826)
		(end 192.729866 -23.03018)
		(width 0.089408)
		(layer "In9.Cu")
		(net "H_CPU1_ERR1_G_N")
	)
	(segment
		(start 192.729866 -23.03018)
		(end 192.64884 -23.03018)
		(width 0.089408)
		(layer "In9.Cu")
		(net "H_CPU1_ERR1_G_N")
	)
	(segment
		(start 239.0648 -21.580602)
		(end 238.597186 -21.112988)
		(width 0.089408)
		(layer "In9.Cu")
		(net "H_CPU1_ERR1_G_N")
	)
	(segment
		(start 312.80227 -32.594042)
		(end 306.30368 -26.095452)
		(width 0.089408)
		(layer "In9.Cu")
		(net "H_CPU1_ERR1_G_N")
	)
	(segment
		(start 262.273542 -27.300428)
		(end 259.81152 -24.838406)
		(width 0.089408)
		(layer "In9.Cu")
		(net "H_CPU1_ERR1_G_N")
	)
	(segment
		(start 367.791746 -52.23383)
		(end 368.626898 -52.23383)
		(width 0.089408)
		(layer "In9.Cu")
		(net "H_CPU1_ERR1_G_N")
	)
	(segment
		(start 259.81152 -24.838406)
		(end 245.926102 -24.838406)
		(width 0.089408)
		(layer "In9.Cu")
		(net "H_CPU1_ERR1_G_N")
	)
	(segment
		(start 266.000738 -29.67736)
		(end 263.623806 -27.300428)
		(width 0.089408)
		(layer "In9.Cu")
		(net "H_CPU1_ERR1_G_N")
	)
	(segment
		(start 372.884954 -46.861984)
		(end 372.884954 -45.607732)
		(width 0.089408)
		(layer "In9.Cu")
		(net "H_CPU1_ERR1_G_N")
	)
	(segment
		(start 317.555626 -37.848032)
		(end 312.80227 -33.094676)
		(width 0.089408)
		(layer "In9.Cu")
		(net "H_CPU1_ERR1_G_N")
	)
	(segment
		(start 239.0648 -21.9964)
		(end 239.0648 -21.580602)
		(width 0.089408)
		(layer "In9.Cu")
		(net "H_CPU1_ERR1_G_N")
	)
	(segment
		(start 244.430804 -24.545544)
		(end 243.948458 -24.063198)
		(width 0.089408)
		(layer "In9.Cu")
		(net "H_CPU1_ERR1_G_N")
	)
	(segment
		(start 372.884954 -45.607732)
		(end 374.367552 -44.125134)
		(width 0.089408)
		(layer "In9.Cu")
		(net "H_CPU1_ERR1_G_N")
	)
	(segment
		(start 196.238114 -21.112988)
		(end 195.89496 -21.456142)
		(width 0.089408)
		(layer "In9.Cu")
		(net "H_CPU1_ERR1_G_N")
	)
	(segment
		(start 279.274016 -26.095452)
		(end 275.692108 -29.67736)
		(width 0.089408)
		(layer "In9.Cu")
		(net "H_CPU1_ERR1_G_N")
	)
	(segment
		(start 241.131598 -24.063198)
		(end 239.0648 -21.9964)
		(width 0.089408)
		(layer "In9.Cu")
		(net "H_CPU1_ERR1_G_N")
	)
	(segment
		(start 188.231526 -24.499824)
		(end 187.07481 -23.343108)
		(width 0.089408)
		(layer "In9.Cu")
		(net "H_CPU1_ERR1_G_N")
	)
	(segment
		(start 195.89496 -21.456142)
		(end 195.89496 -21.638006)
		(width 0.089408)
		(layer "In9.Cu")
		(net "H_CPU1_ERR1_G_N")
	)
	(segment
		(start 371.770656 -49.090072)
		(end 371.770656 -47.976282)
		(width 0.089408)
		(layer "In9.Cu")
		(net "H_CPU1_ERR1_G_N")
	)
	(segment
		(start 312.80227 -33.094676)
		(end 312.80227 -32.594042)
		(width 0.089408)
		(layer "In9.Cu")
		(net "H_CPU1_ERR1_G_N")
	)
	(segment
		(start 368.626898 -52.23383)
		(end 371.770656 -49.090072)
		(width 0.089408)
		(layer "In9.Cu")
		(net "H_CPU1_ERR1_G_N")
	)
	(segment
		(start 238.597186 -21.112988)
		(end 196.238114 -21.112988)
		(width 0.089408)
		(layer "In9.Cu")
		(net "H_CPU1_ERR1_G_N")
	)
	(segment
		(start 306.30368 -26.095452)
		(end 279.274016 -26.095452)
		(width 0.089408)
		(layer "In9.Cu")
		(net "H_CPU1_ERR1_G_N")
	)
	(segment
		(start 263.623806 -27.300428)
		(end 262.273542 -27.300428)
		(width 0.089408)
		(layer "In9.Cu")
		(net "H_CPU1_ERR1_G_N")
	)
	(segment
		(start 371.770656 -47.976282)
		(end 372.884954 -46.861984)
		(width 0.089408)
		(layer "In9.Cu")
		(net "H_CPU1_ERR1_G_N")
	)
	(segment
		(start 186.751214 -22.875748)
		(end 186.751214 -22.435566)
		(width 0.089408)
		(layer "In9.Cu")
		(net "H_CPU1_ERR1_G_N")
	)
	(segment
		(start 191.179196 -24.499824)
		(end 188.231526 -24.499824)
		(width 0.089408)
		(layer "In9.Cu")
		(net "H_CPU1_ERR1_G_N")
	)
	(segment
		(start 320.69278 -37.848032)
		(end 317.555626 -37.848032)
		(width 0.089408)
		(layer "In9.Cu")
		(net "H_CPU1_ERR1_G_N")
	)
	(segment
		(start 245.63324 -24.545544)
		(end 244.430804 -24.545544)
		(width 0.089408)
		(layer "In9.Cu")
		(net "H_CPU1_ERR1_G_N")
	)
	(segment
		(start 275.692108 -29.67736)
		(end 266.000738 -29.67736)
		(width 0.089408)
		(layer "In9.Cu")
		(net "H_CPU1_ERR1_G_N")
	)
	(segment
		(start 195.89496 -21.638006)
		(end 195.30314 -22.229826)
		(width 0.089408)
		(layer "In9.Cu")
		(net "H_CPU1_ERR1_G_N")
	)
	(segment
		(start 187.07481 -23.199344)
		(end 186.751214 -22.875748)
		(width 0.089408)
		(layer "In9.Cu")
		(net "H_CPU1_ERR1_G_N")
	)
	(segment
		(start 321.093084 -38.248336)
		(end 320.69278 -37.848032)
		(width 0.089408)
		(layer "In9.Cu")
		(net "H_CPU1_ERR1_G_N")
	)
	(segment
		(start 243.948458 -24.063198)
		(end 241.131598 -24.063198)
		(width 0.089408)
		(layer "In9.Cu")
		(net "H_CPU1_ERR1_G_N")
	)
	(segment
		(start 192.64884 -23.03018)
		(end 191.179196 -24.499824)
		(width 0.089408)
		(layer "In9.Cu")
		(net "H_CPU1_ERR1_G_N")
	)
	(segment
		(start 187.07481 -23.343108)
		(end 187.07481 -23.199344)
		(width 0.089408)
		(layer "In9.Cu")
		(net "H_CPU1_ERR1_G_N")
	)
	(segment
		(start 195.30314 -22.229826)
		(end 193.53022 -22.229826)
		(width 0.089408)
		(layer "In9.Cu")
		(net "H_CPU1_ERR1_G_N")
	)
	(segment
		(start 245.926102 -24.838406)
		(end 245.63324 -24.545544)
		(width 0.089408)
		(layer "In9.Cu")
		(net "H_CPU1_ERR1_G_N")
	)
	(segment
		(start 186.147964 -31.075376)
		(end 186.147964 -25.769062)
		(width 0.089408)
		(layer "In11.Cu")
		(net "H_CPU1_ERR1_G_N")
	)
	(segment
		(start 167.158924 -59.80811)
		(end 167.158924 -50.064416)
		(width 0.089408)
		(layer "In11.Cu")
		(net "H_CPU1_ERR1_G_N")
	)
	(segment
		(start 159.920686 -67.046348)
		(end 167.158924 -59.80811)
		(width 0.089408)
		(layer "In11.Cu")
		(net "H_CPU1_ERR1_G_N")
	)
	(segment
		(start 326.12203 -41.783)
		(end 322.118482 -37.779452)
		(width 0.089408)
		(layer "In11.Cu")
		(net "H_CPU1_ERR1_G_N")
	)
	(segment
		(start 186.751214 -23.655274)
		(end 186.751214 -22.435566)
		(width 0.089408)
		(layer "In11.Cu")
		(net "H_CPU1_ERR1_G_N")
	)
	(segment
		(start 358.596184 -45.526198)
		(end 358.121204 -45.526198)
		(width 0.089408)
		(layer "In11.Cu")
		(net "H_CPU1_ERR1_G_N")
	)
	(segment
		(start 334.038702 -45.526452)
		(end 332.513686 -44.001436)
		(width 0.089408)
		(layer "In11.Cu")
		(net "H_CPU1_ERR1_G_N")
	)
	(segment
		(start 328.0664 -41.783)
		(end 326.12203 -41.783)
		(width 0.089408)
		(layer "In11.Cu")
		(net "H_CPU1_ERR1_G_N")
	)
	(segment
		(start 161.79419 -73.219056)
		(end 162.194748 -72.818498)
		(width 0.089408)
		(layer "In11.Cu")
		(net "H_CPU1_ERR1_G_N")
	)
	(segment
		(start 358.12095 -45.526452)
		(end 334.038702 -45.526452)
		(width 0.089408)
		(layer "In11.Cu")
		(net "H_CPU1_ERR1_G_N")
	)
	(segment
		(start 322.118482 -37.779452)
		(end 321.561968 -37.779452)
		(width 0.089408)
		(layer "In11.Cu")
		(net "H_CPU1_ERR1_G_N")
	)
	(segment
		(start 332.513686 -44.001436)
		(end 330.284836 -44.001436)
		(width 0.089408)
		(layer "In11.Cu")
		(net "H_CPU1_ERR1_G_N")
	)
	(segment
		(start 364.69955 -51.629564)
		(end 358.596184 -45.526198)
		(width 0.089408)
		(layer "In11.Cu")
		(net "H_CPU1_ERR1_G_N")
	)
	(segment
		(start 187.106306 -24.81072)
		(end 187.106306 -24.010366)
		(width 0.089408)
		(layer "In11.Cu")
		(net "H_CPU1_ERR1_G_N")
	)
	(segment
		(start 187.106306 -24.010366)
		(end 186.751214 -23.655274)
		(width 0.089408)
		(layer "In11.Cu")
		(net "H_CPU1_ERR1_G_N")
	)
	(segment
		(start 366.9538 -51.629564)
		(end 364.69955 -51.629564)
		(width 0.089408)
		(layer "In11.Cu")
		(net "H_CPU1_ERR1_G_N")
	)
	(segment
		(start 367.558066 -52.23383)
		(end 366.9538 -51.629564)
		(width 0.089408)
		(layer "In11.Cu")
		(net "H_CPU1_ERR1_G_N")
	)
	(segment
		(start 167.158924 -50.064416)
		(end 186.147964 -31.075376)
		(width 0.089408)
		(layer "In11.Cu")
		(net "H_CPU1_ERR1_G_N")
	)
	(segment
		(start 162.194748 -72.430894)
		(end 159.920686 -70.156832)
		(width 0.089408)
		(layer "In11.Cu")
		(net "H_CPU1_ERR1_G_N")
	)
	(segment
		(start 162.194748 -72.818498)
		(end 162.194748 -72.430894)
		(width 0.089408)
		(layer "In11.Cu")
		(net "H_CPU1_ERR1_G_N")
	)
	(segment
		(start 321.561968 -37.779452)
		(end 321.093084 -38.248336)
		(width 0.089408)
		(layer "In11.Cu")
		(net "H_CPU1_ERR1_G_N")
	)
	(segment
		(start 159.920686 -70.156832)
		(end 159.920686 -67.046348)
		(width 0.089408)
		(layer "In11.Cu")
		(net "H_CPU1_ERR1_G_N")
	)
	(segment
		(start 367.791746 -52.23383)
		(end 367.558066 -52.23383)
		(width 0.089408)
		(layer "In11.Cu")
		(net "H_CPU1_ERR1_G_N")
	)
	(segment
		(start 186.147964 -25.769062)
		(end 187.106306 -24.81072)
		(width 0.089408)
		(layer "In11.Cu")
		(net "H_CPU1_ERR1_G_N")
	)
	(segment
		(start 330.284836 -44.001436)
		(end 328.0664 -41.783)
		(width 0.089408)
		(layer "In11.Cu")
		(net "H_CPU1_ERR1_G_N")
	)
	(segment
		(start 358.121204 -45.526198)
		(end 358.12095 -45.526452)
		(width 0.089408)
		(layer "In11.Cu")
		(net "H_CPU1_ERR1_G_N")
	)
	(segment
		(start 132.806694 -65.315338)
		(end 133.378194 -65.315338)
		(width 0.1016)
		(layer "F.Cu")
		(net "H_CPU1_ERR0_G_N")
	)
	(via
		(at 320.432684 -38.248336)
		(size 0.508)
		(drill 0.254)
		(layers "F.Cu" "B.Cu")
		(net "H_CPU1_ERR0_G_N")
	)
	(via
		(at 379.239526 -38.819836)
		(size 0.508)
		(drill 0.254)
		(layers "F.Cu" "B.Cu")
		(net "H_CPU1_ERR0_G_N")
	)
	(via
		(at 377.1392 -40.0812)
		(size 0.6604)
		(drill 0.3302)
		(layers "F.Cu" "B.Cu")
		(net "H_CPU1_ERR0_G_N")
	)
	(via
		(at 186.080146 -22.455632)
		(size 0.508)
		(drill 0.254)
		(layers "F.Cu" "B.Cu")
		(net "H_CPU1_ERR0_G_N")
	)
	(via
		(at 133.378194 -65.315338)
		(size 0.508)
		(drill 0.254)
		(layers "F.Cu" "B.Cu")
		(net "H_CPU1_ERR0_G_N")
	)
	(via
		(at 376.5296 -62.992)
		(size 0.508)
		(drill 0.254)
		(layers "F.Cu" "B.Cu")
		(net "H_CPU1_ERR0_G_N")
	)
	(via
		(at 161.746946 -72.56018)
		(size 0.508)
		(drill 0.254)
		(layers "F.Cu" "B.Cu")
		(net "H_CPU1_ERR0_G_N")
	)
	(segment
		(start 377.1138 -40.0558)
		(end 377.1392 -40.0812)
		(width 0.10795)
		(layer "B.Cu")
		(net "H_CPU1_ERR0_G_N")
	)
	(segment
		(start 377.1392 -40.0812)
		(end 377.6726 -39.5478)
		(width 0.10795)
		(layer "B.Cu")
		(net "H_CPU1_ERR0_G_N")
	)
	(segment
		(start 375.484644 -40.662352)
		(end 375.510044 -40.636952)
		(width 0.10795)
		(layer "B.Cu")
		(net "H_CPU1_ERR0_G_N")
	)
	(segment
		(start 378.984764 -38.819836)
		(end 379.239526 -38.819836)
		(width 0.10795)
		(layer "B.Cu")
		(net "H_CPU1_ERR0_G_N")
	)
	(segment
		(start 375.510044 -40.636952)
		(end 375.694448 -40.636952)
		(width 0.10795)
		(layer "B.Cu")
		(net "H_CPU1_ERR0_G_N")
	)
	(segment
		(start 375.062242 -40.662352)
		(end 375.484644 -40.662352)
		(width 0.10795)
		(layer "B.Cu")
		(net "H_CPU1_ERR0_G_N")
	)
	(segment
		(start 376.2756 -40.0558)
		(end 377.1138 -40.0558)
		(width 0.10795)
		(layer "B.Cu")
		(net "H_CPU1_ERR0_G_N")
	)
	(segment
		(start 375.694448 -40.636952)
		(end 376.2756 -40.0558)
		(width 0.10795)
		(layer "B.Cu")
		(net "H_CPU1_ERR0_G_N")
	)
	(segment
		(start 377.6726 -39.5478)
		(end 378.2568 -39.5478)
		(width 0.10795)
		(layer "B.Cu")
		(net "H_CPU1_ERR0_G_N")
	)
	(segment
		(start 378.2568 -39.5478)
		(end 378.984764 -38.819836)
		(width 0.10795)
		(layer "B.Cu")
		(net "H_CPU1_ERR0_G_N")
	)
	(segment
		(start 380.11481 -40.241728)
		(end 380.11481 -40.734234)
		(width 0.089408)
		(layer "In2.Cu")
		(net "H_CPU1_ERR0_G_N")
	)
	(segment
		(start 378.280168 -47.262796)
		(end 378.280168 -55.863998)
		(width 0.089408)
		(layer "In2.Cu")
		(net "H_CPU1_ERR0_G_N")
	)
	(segment
		(start 379.916436 -40.932608)
		(end 379.916436 -41.613836)
		(width 0.089408)
		(layer "In2.Cu")
		(net "H_CPU1_ERR0_G_N")
	)
	(segment
		(start 376.397774 -61.95441)
		(end 376.397774 -62.860174)
		(width 0.089408)
		(layer "In2.Cu")
		(net "H_CPU1_ERR0_G_N")
	)
	(segment
		(start 379.916436 -41.613836)
		(end 380.58344 -42.28084)
		(width 0.089408)
		(layer "In2.Cu")
		(net "H_CPU1_ERR0_G_N")
	)
	(segment
		(start 380.11481 -40.734234)
		(end 379.916436 -40.932608)
		(width 0.089408)
		(layer "In2.Cu")
		(net "H_CPU1_ERR0_G_N")
	)
	(segment
		(start 377.80595 -56.338216)
		(end 377.80595 -60.546234)
		(width 0.089408)
		(layer "In2.Cu")
		(net "H_CPU1_ERR0_G_N")
	)
	(segment
		(start 379.40234 -39.529258)
		(end 380.11481 -40.241728)
		(width 0.089408)
		(layer "In2.Cu")
		(net "H_CPU1_ERR0_G_N")
	)
	(segment
		(start 377.80595 -60.546234)
		(end 376.397774 -61.95441)
		(width 0.089408)
		(layer "In2.Cu")
		(net "H_CPU1_ERR0_G_N")
	)
	(segment
		(start 380.58344 -42.28084)
		(end 380.58344 -44.959524)
		(width 0.089408)
		(layer "In2.Cu")
		(net "H_CPU1_ERR0_G_N")
	)
	(segment
		(start 379.239526 -38.819836)
		(end 379.40234 -38.98265)
		(width 0.089408)
		(layer "In2.Cu")
		(net "H_CPU1_ERR0_G_N")
	)
	(segment
		(start 380.58344 -44.959524)
		(end 378.280168 -47.262796)
		(width 0.089408)
		(layer "In2.Cu")
		(net "H_CPU1_ERR0_G_N")
	)
	(segment
		(start 378.280168 -55.863998)
		(end 377.80595 -56.338216)
		(width 0.089408)
		(layer "In2.Cu")
		(net "H_CPU1_ERR0_G_N")
	)
	(segment
		(start 376.397774 -62.860174)
		(end 376.5296 -62.992)
		(width 0.089408)
		(layer "In2.Cu")
		(net "H_CPU1_ERR0_G_N")
	)
	(segment
		(start 379.40234 -38.98265)
		(end 379.40234 -39.529258)
		(width 0.089408)
		(layer "In2.Cu")
		(net "H_CPU1_ERR0_G_N")
	)
	(segment
		(start 135.954008 -65.410588)
		(end 135.9535 -65.410588)
		(width 0.0889)
		(layer "In4.Cu")
		(net "H_CPU1_ERR0_G_N")
	)
	(segment
		(start 146.284188 -68.199762)
		(end 143.857472 -65.773046)
		(width 0.089408)
		(layer "In4.Cu")
		(net "H_CPU1_ERR0_G_N")
	)
	(segment
		(start 137.692384 -65.410334)
		(end 137.649204 -65.410334)
		(width 0.0889)
		(layer "In4.Cu")
		(net "H_CPU1_ERR0_G_N")
	)
	(segment
		(start 141.457934 -65.410334)
		(end 141.083284 -65.410334)
		(width 0.0889)
		(layer "In4.Cu")
		(net "H_CPU1_ERR0_G_N")
	)
	(segment
		(start 159.479742 -72.327008)
		(end 155.352496 -68.199762)
		(width 0.089408)
		(layer "In4.Cu")
		(net "H_CPU1_ERR0_G_N")
	)
	(segment
		(start 143.857472 -65.773046)
		(end 141.820646 -65.773046)
		(width 0.0889)
		(layer "In4.Cu")
		(net "H_CPU1_ERR0_G_N")
	)
	(segment
		(start 155.352496 -68.199762)
		(end 146.284188 -68.199762)
		(width 0.089408)
		(layer "In4.Cu")
		(net "H_CPU1_ERR0_G_N")
	)
	(segment
		(start 134.19963 -65.410334)
		(end 133.378194 -65.315338)
		(width 0.0889)
		(layer "In4.Cu")
		(net "H_CPU1_ERR0_G_N")
	)
	(segment
		(start 139.409424 -65.410334)
		(end 139.366244 -65.410334)
		(width 0.0889)
		(layer "In4.Cu")
		(net "H_CPU1_ERR0_G_N")
	)
	(segment
		(start 161.513774 -72.327008)
		(end 159.479742 -72.327008)
		(width 0.089408)
		(layer "In4.Cu")
		(net "H_CPU1_ERR0_G_N")
	)
	(segment
		(start 140.26134 -64.915288)
		(end 140.231368 -64.915288)
		(width 0.0889)
		(layer "In4.Cu")
		(net "H_CPU1_ERR0_G_N")
	)
	(segment
		(start 138.5443 -64.915288)
		(end 138.514328 -64.915288)
		(width 0.0889)
		(layer "In4.Cu")
		(net "H_CPU1_ERR0_G_N")
	)
	(segment
		(start 161.746946 -72.56018)
		(end 161.513774 -72.327008)
		(width 0.089408)
		(layer "In4.Cu")
		(net "H_CPU1_ERR0_G_N")
	)
	(segment
		(start 134.258304 -65.410334)
		(end 134.19963 -65.410334)
		(width 0.0889)
		(layer "In4.Cu")
		(net "H_CPU1_ERR0_G_N")
	)
	(segment
		(start 141.820646 -65.773046)
		(end 141.457934 -65.410334)
		(width 0.0889)
		(layer "In4.Cu")
		(net "H_CPU1_ERR0_G_N")
	)
	(segment
		(start 135.11022 -64.915288)
		(end 135.080248 -64.915288)
		(width 0.0889)
		(layer "In4.Cu")
		(net "H_CPU1_ERR0_G_N")
	)
	(arc
		(start 136.465564 -65.115186)
		(mid 136.24938 -65.331465)
		(end 135.954008 -65.410588)
		(width 0.0889)
		(layer "In4.Cu")
		(net "H_CPU1_ERR0_G_N")
	)
	(arc
		(start 135.441944 -65.115186)
		(mid 135.301865 -64.97245)
		(end 135.11022 -64.915288)
		(width 0.0889)
		(layer "In4.Cu")
		(net "H_CPU1_ERR0_G_N")
	)
	(arc
		(start 137.158984 -65.115186)
		(mid 136.812274 -64.915002)
		(end 136.465564 -65.115186)
		(width 0.0889)
		(layer "In4.Cu")
		(net "H_CPU1_ERR0_G_N")
	)
	(arc
		(start 140.593064 -65.115186)
		(mid 140.452985 -64.97245)
		(end 140.26134 -64.915288)
		(width 0.0889)
		(layer "In4.Cu")
		(net "H_CPU1_ERR0_G_N")
	)
	(arc
		(start 139.899644 -65.115186)
		(mid 139.69264 -65.32605)
		(end 139.409424 -65.410334)
		(width 0.0889)
		(layer "In4.Cu")
		(net "H_CPU1_ERR0_G_N")
	)
	(arc
		(start 138.182604 -65.115186)
		(mid 137.9756 -65.32605)
		(end 137.692384 -65.410334)
		(width 0.0889)
		(layer "In4.Cu")
		(net "H_CPU1_ERR0_G_N")
	)
	(arc
		(start 140.231368 -64.915288)
		(mid 140.039726 -64.972454)
		(end 139.899644 -65.115186)
		(width 0.0889)
		(layer "In4.Cu")
		(net "H_CPU1_ERR0_G_N")
	)
	(arc
		(start 137.649204 -65.410334)
		(mid 137.365987 -65.326053)
		(end 137.158984 -65.115186)
		(width 0.0889)
		(layer "In4.Cu")
		(net "H_CPU1_ERR0_G_N")
	)
	(arc
		(start 138.876024 -65.115186)
		(mid 138.735945 -64.97245)
		(end 138.5443 -64.915288)
		(width 0.0889)
		(layer "In4.Cu")
		(net "H_CPU1_ERR0_G_N")
	)
	(arc
		(start 134.748524 -65.115186)
		(mid 134.54152 -65.32605)
		(end 134.258304 -65.410334)
		(width 0.0889)
		(layer "In4.Cu")
		(net "H_CPU1_ERR0_G_N")
	)
	(arc
		(start 135.9535 -65.410588)
		(mid 135.65815 -65.331426)
		(end 135.441944 -65.115186)
		(width 0.0889)
		(layer "In4.Cu")
		(net "H_CPU1_ERR0_G_N")
	)
	(arc
		(start 135.080248 -64.915288)
		(mid 134.888606 -64.972454)
		(end 134.748524 -65.115186)
		(width 0.0889)
		(layer "In4.Cu")
		(net "H_CPU1_ERR0_G_N")
	)
	(arc
		(start 141.083284 -65.410334)
		(mid 140.800067 -65.326053)
		(end 140.593064 -65.115186)
		(width 0.0889)
		(layer "In4.Cu")
		(net "H_CPU1_ERR0_G_N")
	)
	(arc
		(start 138.514328 -64.915288)
		(mid 138.322686 -64.972454)
		(end 138.182604 -65.115186)
		(width 0.0889)
		(layer "In4.Cu")
		(net "H_CPU1_ERR0_G_N")
	)
	(arc
		(start 139.366244 -65.410334)
		(mid 139.083027 -65.326053)
		(end 138.876024 -65.115186)
		(width 0.0889)
		(layer "In4.Cu")
		(net "H_CPU1_ERR0_G_N")
	)
	(segment
		(start 245.511828 -24.838152)
		(end 245.80469 -25.131014)
		(width 0.089408)
		(layer "In9.Cu")
		(net "H_CPU1_ERR0_G_N")
	)
	(segment
		(start 313.688476 -38.248336)
		(end 320.432684 -38.248336)
		(width 0.089408)
		(layer "In9.Cu")
		(net "H_CPU1_ERR0_G_N")
	)
	(segment
		(start 195.645786 -24.355806)
		(end 243.814346 -24.355806)
		(width 0.089408)
		(layer "In9.Cu")
		(net "H_CPU1_ERR0_G_N")
	)
	(segment
		(start 244.296692 -24.838152)
		(end 245.511828 -24.838152)
		(width 0.089408)
		(layer "In9.Cu")
		(net "H_CPU1_ERR0_G_N")
	)
	(segment
		(start 186.782202 -23.320756)
		(end 186.782202 -23.46452)
		(width 0.089408)
		(layer "In9.Cu")
		(net "H_CPU1_ERR0_G_N")
	)
	(segment
		(start 186.782202 -23.46452)
		(end 188.110114 -24.792432)
		(width 0.089408)
		(layer "In9.Cu")
		(net "H_CPU1_ERR0_G_N")
	)
	(segment
		(start 305.410108 -29.969968)
		(end 313.688476 -38.248336)
		(width 0.089408)
		(layer "In9.Cu")
		(net "H_CPU1_ERR0_G_N")
	)
	(segment
		(start 263.502394 -27.593036)
		(end 265.879326 -29.969968)
		(width 0.089408)
		(layer "In9.Cu")
		(net "H_CPU1_ERR0_G_N")
	)
	(segment
		(start 262.15213 -27.593036)
		(end 263.502394 -27.593036)
		(width 0.089408)
		(layer "In9.Cu")
		(net "H_CPU1_ERR0_G_N")
	)
	(segment
		(start 243.814346 -24.355806)
		(end 244.296692 -24.838152)
		(width 0.089408)
		(layer "In9.Cu")
		(net "H_CPU1_ERR0_G_N")
	)
	(segment
		(start 259.690108 -25.131014)
		(end 262.15213 -27.593036)
		(width 0.089408)
		(layer "In9.Cu")
		(net "H_CPU1_ERR0_G_N")
	)
	(segment
		(start 194.612768 -23.322788)
		(end 195.645786 -24.355806)
		(width 0.089408)
		(layer "In9.Cu")
		(net "H_CPU1_ERR0_G_N")
	)
	(segment
		(start 188.110114 -24.792432)
		(end 191.300608 -24.792432)
		(width 0.089408)
		(layer "In9.Cu")
		(net "H_CPU1_ERR0_G_N")
	)
	(segment
		(start 192.770252 -23.322788)
		(end 194.612768 -23.322788)
		(width 0.089408)
		(layer "In9.Cu")
		(net "H_CPU1_ERR0_G_N")
	)
	(segment
		(start 191.300608 -24.792432)
		(end 192.770252 -23.322788)
		(width 0.089408)
		(layer "In9.Cu")
		(net "H_CPU1_ERR0_G_N")
	)
	(segment
		(start 186.080146 -22.6187)
		(end 186.782202 -23.320756)
		(width 0.089408)
		(layer "In9.Cu")
		(net "H_CPU1_ERR0_G_N")
	)
	(segment
		(start 245.80469 -25.131014)
		(end 259.690108 -25.131014)
		(width 0.089408)
		(layer "In9.Cu")
		(net "H_CPU1_ERR0_G_N")
	)
	(segment
		(start 265.879326 -29.969968)
		(end 305.410108 -29.969968)
		(width 0.089408)
		(layer "In9.Cu")
		(net "H_CPU1_ERR0_G_N")
	)
	(segment
		(start 186.080146 -22.455632)
		(end 186.080146 -22.6187)
		(width 0.089408)
		(layer "In9.Cu")
		(net "H_CPU1_ERR0_G_N")
	)
	(segment
		(start 374.459754 -59.652154)
		(end 375.43232 -59.652154)
		(width 0.089408)
		(layer "In11.Cu")
		(net "H_CPU1_ERR0_G_N")
	)
	(segment
		(start 334.001364 -46.20133)
		(end 334.001618 -46.201076)
		(width 0.089408)
		(layer "In11.Cu")
		(net "H_CPU1_ERR0_G_N")
	)
	(segment
		(start 330.247752 -44.67606)
		(end 332.233778 -44.67606)
		(width 0.089408)
		(layer "In11.Cu")
		(net "H_CPU1_ERR0_G_N")
	)
	(segment
		(start 159.628078 -70.441312)
		(end 159.628078 -66.924936)
		(width 0.089408)
		(layer "In11.Cu")
		(net "H_CPU1_ERR0_G_N")
	)
	(segment
		(start 161.746946 -72.56018)
		(end 159.628078 -70.441312)
		(width 0.089408)
		(layer "In11.Cu")
		(net "H_CPU1_ERR0_G_N")
	)
	(segment
		(start 374.099328 -59.650376)
		(end 374.457976 -59.650376)
		(width 0.089408)
		(layer "In11.Cu")
		(net "H_CPU1_ERR0_G_N")
	)
	(segment
		(start 368.48415 -53.124354)
		(end 371.125496 -55.7657)
		(width 0.089408)
		(layer "In11.Cu")
		(net "H_CPU1_ERR0_G_N")
	)
	(segment
		(start 321.399662 -38.918896)
		(end 322.372482 -39.891716)
		(width 0.089408)
		(layer "In11.Cu")
		(net "H_CPU1_ERR0_G_N")
	)
	(segment
		(start 330.005182 -44.676314)
		(end 330.247498 -44.676314)
		(width 0.089408)
		(layer "In11.Cu")
		(net "H_CPU1_ERR0_G_N")
	)
	(segment
		(start 364.67415 -52.558696)
		(end 365.671862 -52.558696)
		(width 0.089408)
		(layer "In11.Cu")
		(net "H_CPU1_ERR0_G_N")
	)
	(segment
		(start 325.834248 -42.625264)
		(end 327.954132 -42.625264)
		(width 0.089408)
		(layer "In11.Cu")
		(net "H_CPU1_ERR0_G_N")
	)
	(segment
		(start 322.372482 -39.891716)
		(end 322.792344 -39.891716)
		(width 0.089408)
		(layer "In11.Cu")
		(net "H_CPU1_ERR0_G_N")
	)
	(segment
		(start 320.432684 -38.248336)
		(end 321.103244 -38.918896)
		(width 0.089408)
		(layer "In11.Cu")
		(net "H_CPU1_ERR0_G_N")
	)
	(segment
		(start 166.866316 -49.943004)
		(end 185.349896 -31.459424)
		(width 0.089408)
		(layer "In11.Cu")
		(net "H_CPU1_ERR0_G_N")
	)
	(segment
		(start 371.125496 -56.477662)
		(end 372.985792 -58.337958)
		(width 0.089408)
		(layer "In11.Cu")
		(net "H_CPU1_ERR0_G_N")
	)
	(segment
		(start 376.37974 -60.599574)
		(end 376.37974 -62.66434)
		(width 0.089408)
		(layer "In11.Cu")
		(net "H_CPU1_ERR0_G_N")
	)
	(segment
		(start 334.001618 -46.201076)
		(end 358.31653 -46.201076)
		(width 0.089408)
		(layer "In11.Cu")
		(net "H_CPU1_ERR0_G_N")
	)
	(segment
		(start 185.349896 -31.459424)
		(end 185.349896 -23.185882)
		(width 0.089408)
		(layer "In11.Cu")
		(net "H_CPU1_ERR0_G_N")
	)
	(segment
		(start 185.349896 -23.185882)
		(end 186.080146 -22.455632)
		(width 0.089408)
		(layer "In11.Cu")
		(net "H_CPU1_ERR0_G_N")
	)
	(segment
		(start 327.954132 -42.625264)
		(end 330.005182 -44.676314)
		(width 0.089408)
		(layer "In11.Cu")
		(net "H_CPU1_ERR0_G_N")
	)
	(segment
		(start 159.628078 -66.924936)
		(end 166.866316 -59.686698)
		(width 0.089408)
		(layer "In11.Cu")
		(net "H_CPU1_ERR0_G_N")
	)
	(segment
		(start 358.31653 -46.201076)
		(end 364.67415 -52.558696)
		(width 0.089408)
		(layer "In11.Cu")
		(net "H_CPU1_ERR0_G_N")
	)
	(segment
		(start 376.37974 -62.66434)
		(end 376.5296 -62.8142)
		(width 0.089408)
		(layer "In11.Cu")
		(net "H_CPU1_ERR0_G_N")
	)
	(segment
		(start 366.23752 -53.124354)
		(end 368.48415 -53.124354)
		(width 0.089408)
		(layer "In11.Cu")
		(net "H_CPU1_ERR0_G_N")
	)
	(segment
		(start 322.792344 -39.891716)
		(end 322.837048 -39.93642)
		(width 0.089408)
		(layer "In11.Cu")
		(net "H_CPU1_ERR0_G_N")
	)
	(segment
		(start 365.671862 -52.558696)
		(end 366.23752 -53.124354)
		(width 0.089408)
		(layer "In11.Cu")
		(net "H_CPU1_ERR0_G_N")
	)
	(segment
		(start 372.985792 -58.53684)
		(end 374.099328 -59.650376)
		(width 0.089408)
		(layer "In11.Cu")
		(net "H_CPU1_ERR0_G_N")
	)
	(segment
		(start 375.43232 -59.652154)
		(end 376.37974 -60.599574)
		(width 0.089408)
		(layer "In11.Cu")
		(net "H_CPU1_ERR0_G_N")
	)
	(segment
		(start 322.837048 -39.93642)
		(end 323.145404 -39.93642)
		(width 0.089408)
		(layer "In11.Cu")
		(net "H_CPU1_ERR0_G_N")
	)
	(segment
		(start 323.145404 -39.93642)
		(end 325.834248 -42.625264)
		(width 0.089408)
		(layer "In11.Cu")
		(net "H_CPU1_ERR0_G_N")
	)
	(segment
		(start 376.5296 -62.8142)
		(end 376.5296 -62.992)
		(width 0.089408)
		(layer "In11.Cu")
		(net "H_CPU1_ERR0_G_N")
	)
	(segment
		(start 374.457976 -59.650376)
		(end 374.459754 -59.652154)
		(width 0.089408)
		(layer "In11.Cu")
		(net "H_CPU1_ERR0_G_N")
	)
	(segment
		(start 166.866316 -59.686698)
		(end 166.866316 -49.943004)
		(width 0.089408)
		(layer "In11.Cu")
		(net "H_CPU1_ERR0_G_N")
	)
	(segment
		(start 330.247498 -44.676314)
		(end 330.247752 -44.67606)
		(width 0.089408)
		(layer "In11.Cu")
		(net "H_CPU1_ERR0_G_N")
	)
	(segment
		(start 371.125496 -55.7657)
		(end 371.125496 -56.477662)
		(width 0.089408)
		(layer "In11.Cu")
		(net "H_CPU1_ERR0_G_N")
	)
	(segment
		(start 332.233778 -44.67606)
		(end 333.759048 -46.20133)
		(width 0.089408)
		(layer "In11.Cu")
		(net "H_CPU1_ERR0_G_N")
	)
	(segment
		(start 333.759048 -46.20133)
		(end 334.001364 -46.20133)
		(width 0.089408)
		(layer "In11.Cu")
		(net "H_CPU1_ERR0_G_N")
	)
	(segment
		(start 321.103244 -38.918896)
		(end 321.399662 -38.918896)
		(width 0.089408)
		(layer "In11.Cu")
		(net "H_CPU1_ERR0_G_N")
	)
	(segment
		(start 372.985792 -58.337958)
		(end 372.985792 -58.53684)
		(width 0.089408)
		(layer "In11.Cu")
		(net "H_CPU1_ERR0_G_N")
	)
	(segment
		(start 298.665646 -65.810384)
		(end 299.237146 -65.810384)
		(width 0.1016)
		(layer "F.Cu")
		(net "H_CPU0_ERR1_G_N")
	)
	(via
		(at 375.256552 -43.938952)
		(size 0.508)
		(drill 0.254)
		(layers "F.Cu" "B.Cu")
		(net "H_CPU0_ERR1_G_N")
	)
	(via
		(at 299.237146 -65.810384)
		(size 0.508)
		(drill 0.254)
		(layers "F.Cu" "B.Cu")
		(net "H_CPU0_ERR1_G_N")
	)
	(via
		(at 365.379 -64.8716)
		(size 0.508)
		(drill 0.254)
		(layers "F.Cu" "B.Cu")
		(net "H_CPU0_ERR1_G_N")
	)
	(via
		(at 366.1664 -65.6082)
		(size 0.6604)
		(drill 0.3302)
		(layers "F.Cu" "B.Cu")
		(net "H_CPU0_ERR1_G_N")
	)
	(segment
		(start 365.379 -64.8716)
		(end 365.4298 -64.8716)
		(width 0.10795)
		(layer "B.Cu")
		(net "H_CPU0_ERR1_G_N")
	)
	(segment
		(start 375.408952 -43.224958)
		(end 375.408952 -43.786552)
		(width 0.10795)
		(layer "B.Cu")
		(net "H_CPU0_ERR1_G_N")
	)
	(segment
		(start 375.408952 -43.786552)
		(end 375.256552 -43.938952)
		(width 0.10795)
		(layer "B.Cu")
		(net "H_CPU0_ERR1_G_N")
	)
	(segment
		(start 365.4298 -64.8716)
		(end 366.1664 -65.6082)
		(width 0.10795)
		(layer "B.Cu")
		(net "H_CPU0_ERR1_G_N")
	)
	(segment
		(start 369.852702 -62.281562)
		(end 369.852702 -53.918612)
		(width 0.089408)
		(layer "In9.Cu")
		(net "H_CPU0_ERR1_G_N")
	)
	(segment
		(start 369.852702 -53.918612)
		(end 372.152926 -51.618388)
		(width 0.089408)
		(layer "In9.Cu")
		(net "H_CPU0_ERR1_G_N")
	)
	(segment
		(start 373.302022 -46.42866)
		(end 375.256552 -44.47413)
		(width 0.089408)
		(layer "In9.Cu")
		(net "H_CPU0_ERR1_G_N")
	)
	(segment
		(start 366.084104 -64.54775)
		(end 366.084104 -64.001142)
		(width 0.089408)
		(layer "In9.Cu")
		(net "H_CPU0_ERR1_G_N")
	)
	(segment
		(start 366.084104 -64.001142)
		(end 367.24717 -62.838076)
		(width 0.089408)
		(layer "In9.Cu")
		(net "H_CPU0_ERR1_G_N")
	)
	(segment
		(start 375.256552 -44.47413)
		(end 375.256552 -43.938952)
		(width 0.089408)
		(layer "In9.Cu")
		(net "H_CPU0_ERR1_G_N")
	)
	(segment
		(start 369.296188 -62.838076)
		(end 369.852702 -62.281562)
		(width 0.089408)
		(layer "In9.Cu")
		(net "H_CPU0_ERR1_G_N")
	)
	(segment
		(start 372.152926 -48.134524)
		(end 373.302022 -46.985428)
		(width 0.089408)
		(layer "In9.Cu")
		(net "H_CPU0_ERR1_G_N")
	)
	(segment
		(start 367.24717 -62.838076)
		(end 369.296188 -62.838076)
		(width 0.089408)
		(layer "In9.Cu")
		(net "H_CPU0_ERR1_G_N")
	)
	(segment
		(start 373.302022 -46.985428)
		(end 373.302022 -46.42866)
		(width 0.089408)
		(layer "In9.Cu")
		(net "H_CPU0_ERR1_G_N")
	)
	(segment
		(start 372.152926 -51.618388)
		(end 372.152926 -48.134524)
		(width 0.089408)
		(layer "In9.Cu")
		(net "H_CPU0_ERR1_G_N")
	)
	(segment
		(start 365.760254 -64.8716)
		(end 366.084104 -64.54775)
		(width 0.089408)
		(layer "In9.Cu")
		(net "H_CPU0_ERR1_G_N")
	)
	(segment
		(start 365.379 -64.8716)
		(end 365.760254 -64.8716)
		(width 0.089408)
		(layer "In9.Cu")
		(net "H_CPU0_ERR1_G_N")
	)
	(segment
		(start 298.922948 -65.562734)
		(end 298.94403 -65.641474)
		(width 0.0889)
		(layer "In11.Cu")
		(net "H_CPU0_ERR1_G_N")
	)
	(segment
		(start 364.203234 -66.04)
		(end 363.321346 -66.04)
		(width 0.089408)
		(layer "In11.Cu")
		(net "H_CPU0_ERR1_G_N")
	)
	(segment
		(start 354.59797 -63.533528)
		(end 335.384648 -63.533528)
		(width 0.089408)
		(layer "In11.Cu")
		(net "H_CPU0_ERR1_G_N")
	)
	(segment
		(start 365.379 -64.8716)
		(end 365.371634 -64.8716)
		(width 0.089408)
		(layer "In11.Cu")
		(net "H_CPU0_ERR1_G_N")
	)
	(segment
		(start 307.47335 -65.065402)
		(end 307.323744 -64.915796)
		(width 0.089408)
		(layer "In11.Cu")
		(net "H_CPU0_ERR1_G_N")
	)
	(segment
		(start 335.384648 -63.533528)
		(end 332.560168 -66.358008)
		(width 0.089408)
		(layer "In11.Cu")
		(net "H_CPU0_ERR1_G_N")
	)
	(segment
		(start 355.052122 -63.079376)
		(end 354.59797 -63.533528)
		(width 0.089408)
		(layer "In11.Cu")
		(net "H_CPU0_ERR1_G_N")
	)
	(segment
		(start 363.321346 -66.04)
		(end 361.074716 -63.79337)
		(width 0.089408)
		(layer "In11.Cu")
		(net "H_CPU0_ERR1_G_N")
	)
	(segment
		(start 311.55513 -65.065402)
		(end 307.47335 -65.065402)
		(width 0.089408)
		(layer "In11.Cu")
		(net "H_CPU0_ERR1_G_N")
	)
	(segment
		(start 298.94403 -65.641474)
		(end 299.237146 -65.810384)
		(width 0.0889)
		(layer "In11.Cu")
		(net "H_CPU0_ERR1_G_N")
	)
	(segment
		(start 305.264566 -64.915288)
		(end 305.2318 -64.915288)
		(width 0.0889)
		(layer "In11.Cu")
		(net "H_CPU0_ERR1_G_N")
	)
	(segment
		(start 332.560168 -66.358008)
		(end 312.847736 -66.358008)
		(width 0.089408)
		(layer "In11.Cu")
		(net "H_CPU0_ERR1_G_N")
	)
	(segment
		(start 356.713536 -63.79337)
		(end 355.999542 -63.079376)
		(width 0.089408)
		(layer "In11.Cu")
		(net "H_CPU0_ERR1_G_N")
	)
	(segment
		(start 312.847736 -66.358008)
		(end 311.55513 -65.065402)
		(width 0.089408)
		(layer "In11.Cu")
		(net "H_CPU0_ERR1_G_N")
	)
	(segment
		(start 300.975776 -65.410334)
		(end 300.94301 -65.410334)
		(width 0.0889)
		(layer "In11.Cu")
		(net "H_CPU0_ERR1_G_N")
	)
	(segment
		(start 307.323744 -64.915796)
		(end 306.964334 -64.915796)
		(width 0.0889)
		(layer "In11.Cu")
		(net "H_CPU0_ERR1_G_N")
	)
	(segment
		(start 361.074716 -63.79337)
		(end 356.713536 -63.79337)
		(width 0.089408)
		(layer "In11.Cu")
		(net "H_CPU0_ERR1_G_N")
	)
	(segment
		(start 365.371634 -64.8716)
		(end 364.203234 -66.04)
		(width 0.089408)
		(layer "In11.Cu")
		(net "H_CPU0_ERR1_G_N")
	)
	(segment
		(start 355.999542 -63.079376)
		(end 355.052122 -63.079376)
		(width 0.089408)
		(layer "In11.Cu")
		(net "H_CPU0_ERR1_G_N")
	)
	(arc
		(start 300.94301 -65.410334)
		(mid 300.74916 -65.466684)
		(end 300.607476 -65.610486)
		(width 0.0889)
		(layer "In11.Cu")
		(net "H_CPU0_ERR1_G_N")
	)
	(arc
		(start 302.159416 -65.115186)
		(mid 301.812706 -64.915002)
		(end 301.465996 -65.115186)
		(width 0.0889)
		(layer "In11.Cu")
		(net "H_CPU0_ERR1_G_N")
	)
	(arc
		(start 299.583856 -65.610486)
		(mid 299.266036 -65.411219)
		(end 298.922948 -65.562734)
		(width 0.0889)
		(layer "In11.Cu")
		(net "H_CPU0_ERR1_G_N")
	)
	(arc
		(start 305.758596 -64.619886)
		(mid 305.549988 -64.831818)
		(end 305.264566 -64.915288)
		(width 0.0889)
		(layer "In11.Cu")
		(net "H_CPU0_ERR1_G_N")
	)
	(arc
		(start 300.607476 -65.610486)
		(mid 300.095666 -65.906153)
		(end 299.583856 -65.610486)
		(width 0.0889)
		(layer "In11.Cu")
		(net "H_CPU0_ERR1_G_N")
	)
	(arc
		(start 303.876456 -65.115186)
		(mid 303.529746 -64.915002)
		(end 303.183036 -65.115186)
		(width 0.0889)
		(layer "In11.Cu")
		(net "H_CPU0_ERR1_G_N")
	)
	(arc
		(start 306.964334 -64.915796)
		(mid 306.668534 -64.836492)
		(end 306.452016 -64.619886)
		(width 0.0889)
		(layer "In11.Cu")
		(net "H_CPU0_ERR1_G_N")
	)
	(arc
		(start 304.900076 -65.115186)
		(mid 304.388266 -65.410725)
		(end 303.876456 -65.115186)
		(width 0.0889)
		(layer "In11.Cu")
		(net "H_CPU0_ERR1_G_N")
	)
	(arc
		(start 306.452016 -64.619886)
		(mid 306.105306 -64.419575)
		(end 305.758596 -64.619886)
		(width 0.0889)
		(layer "In11.Cu")
		(net "H_CPU0_ERR1_G_N")
	)
	(arc
		(start 303.183036 -65.115186)
		(mid 302.671226 -65.410725)
		(end 302.159416 -65.115186)
		(width 0.0889)
		(layer "In11.Cu")
		(net "H_CPU0_ERR1_G_N")
	)
	(arc
		(start 301.465996 -65.115186)
		(mid 301.258992 -65.32605)
		(end 300.975776 -65.410334)
		(width 0.0889)
		(layer "In11.Cu")
		(net "H_CPU0_ERR1_G_N")
	)
	(arc
		(start 305.2318 -64.915288)
		(mid 305.040158 -64.972454)
		(end 304.900076 -65.115186)
		(width 0.0889)
		(layer "In11.Cu")
		(net "H_CPU0_ERR1_G_N")
	)
	(segment
		(start 366.138206 -63.234824)
		(end 373.820944 -63.234824)
		(width 0.10795)
		(layer "F.Cu")
		(net "H_CPU0_ERR0_G_N")
	)
	(segment
		(start 297.807126 -65.315338)
		(end 298.378626 -65.315338)
		(width 0.1016)
		(layer "F.Cu")
		(net "H_CPU0_ERR0_G_N")
	)
	(segment
		(start 373.820944 -63.234824)
		(end 374.52808 -63.94196)
		(width 0.10795)
		(layer "F.Cu")
		(net "H_CPU0_ERR0_G_N")
	)
	(segment
		(start 363.996478 -65.376552)
		(end 366.138206 -63.234824)
		(width 0.10795)
		(layer "F.Cu")
		(net "H_CPU0_ERR0_G_N")
	)
	(via
		(at 298.378626 -65.315338)
		(size 0.508)
		(drill 0.254)
		(layers "F.Cu" "B.Cu")
		(net "H_CPU0_ERR0_G_N")
	)
	(via
		(at 374.52808 -63.94196)
		(size 0.508)
		(drill 0.254)
		(layers "F.Cu" "B.Cu")
		(net "H_CPU0_ERR0_G_N")
	)
	(via
		(at 376.301 -41.050718)
		(size 0.6604)
		(drill 0.3302)
		(layers "F.Cu" "B.Cu")
		(net "H_CPU0_ERR0_G_N")
	)
	(via
		(at 363.996478 -65.376552)
		(size 0.508)
		(drill 0.254)
		(layers "F.Cu" "B.Cu")
		(net "H_CPU0_ERR0_G_N")
	)
	(via
		(at 378.0282 -40.2082)
		(size 0.508)
		(drill 0.254)
		(layers "F.Cu" "B.Cu")
		(net "H_CPU0_ERR0_G_N")
	)
	(segment
		(start 376.301 -41.050718)
		(end 375.927366 -41.424352)
		(width 0.10795)
		(layer "B.Cu")
		(net "H_CPU0_ERR0_G_N")
	)
	(segment
		(start 375.927366 -41.424352)
		(end 375.062242 -41.424352)
		(width 0.10795)
		(layer "B.Cu")
		(net "H_CPU0_ERR0_G_N")
	)
	(segment
		(start 377.707398 -40.249602)
		(end 376.906282 -41.050718)
		(width 0.10795)
		(layer "B.Cu")
		(net "H_CPU0_ERR0_G_N")
	)
	(segment
		(start 378.0282 -40.2082)
		(end 377.986798 -40.249602)
		(width 0.10795)
		(layer "B.Cu")
		(net "H_CPU0_ERR0_G_N")
	)
	(segment
		(start 377.986798 -40.249602)
		(end 377.707398 -40.249602)
		(width 0.10795)
		(layer "B.Cu")
		(net "H_CPU0_ERR0_G_N")
	)
	(segment
		(start 376.906282 -41.050718)
		(end 376.301 -41.050718)
		(width 0.10795)
		(layer "B.Cu")
		(net "H_CPU0_ERR0_G_N")
	)
	(segment
		(start 380.795022 -44.224956)
		(end 380.795022 -44.382944)
		(width 0.089408)
		(layer "In9.Cu")
		(net "H_CPU0_ERR0_G_N")
	)
	(segment
		(start 379.56363 -55.561484)
		(end 379.56363 -57.905142)
		(width 0.089408)
		(layer "In9.Cu")
		(net "H_CPU0_ERR0_G_N")
	)
	(segment
		(start 379.593856 -46.53407)
		(end 379.593856 -51.027838)
		(width 0.089408)
		(layer "In9.Cu")
		(net "H_CPU0_ERR0_G_N")
	)
	(segment
		(start 380.794768 -44.383198)
		(end 380.794768 -45.333158)
		(width 0.089408)
		(layer "In9.Cu")
		(net "H_CPU0_ERR0_G_N")
	)
	(segment
		(start 377.585224 -41.331642)
		(end 378.552964 -42.299382)
		(width 0.089408)
		(layer "In9.Cu")
		(net "H_CPU0_ERR0_G_N")
	)
	(segment
		(start 377.585224 -40.651176)
		(end 377.585224 -41.331642)
		(width 0.089408)
		(layer "In9.Cu")
		(net "H_CPU0_ERR0_G_N")
	)
	(segment
		(start 379.56363 -57.905142)
		(end 376.91949 -60.549282)
		(width 0.089408)
		(layer "In9.Cu")
		(net "H_CPU0_ERR0_G_N")
	)
	(segment
		(start 378.875798 -42.305732)
		(end 378.894594 -42.305732)
		(width 0.089408)
		(layer "In9.Cu")
		(net "H_CPU0_ERR0_G_N")
	)
	(segment
		(start 378.0282 -40.2082)
		(end 377.585224 -40.651176)
		(width 0.089408)
		(layer "In9.Cu")
		(net "H_CPU0_ERR0_G_N")
	)
	(segment
		(start 378.894594 -42.305732)
		(end 380.794768 -44.205906)
		(width 0.089408)
		(layer "In9.Cu")
		(net "H_CPU0_ERR0_G_N")
	)
	(segment
		(start 374.52808 -63.739014)
		(end 374.52808 -63.94196)
		(width 0.089408)
		(layer "In9.Cu")
		(net "H_CPU0_ERR0_G_N")
	)
	(segment
		(start 378.869448 -42.299382)
		(end 378.875798 -42.305732)
		(width 0.089408)
		(layer "In9.Cu")
		(net "H_CPU0_ERR0_G_N")
	)
	(segment
		(start 376.91949 -60.549282)
		(end 376.91949 -61.347604)
		(width 0.089408)
		(layer "In9.Cu")
		(net "H_CPU0_ERR0_G_N")
	)
	(segment
		(start 380.794768 -45.333158)
		(end 379.593856 -46.53407)
		(width 0.089408)
		(layer "In9.Cu")
		(net "H_CPU0_ERR0_G_N")
	)
	(segment
		(start 380.795022 -44.382944)
		(end 380.794768 -44.383198)
		(width 0.089408)
		(layer "In9.Cu")
		(net "H_CPU0_ERR0_G_N")
	)
	(segment
		(start 380.794768 -44.224702)
		(end 380.795022 -44.224956)
		(width 0.089408)
		(layer "In9.Cu")
		(net "H_CPU0_ERR0_G_N")
	)
	(segment
		(start 379.465078 -51.156616)
		(end 379.465078 -55.462932)
		(width 0.089408)
		(layer "In9.Cu")
		(net "H_CPU0_ERR0_G_N")
	)
	(segment
		(start 376.91949 -61.347604)
		(end 374.52808 -63.739014)
		(width 0.089408)
		(layer "In9.Cu")
		(net "H_CPU0_ERR0_G_N")
	)
	(segment
		(start 380.794768 -44.205906)
		(end 380.794768 -44.224702)
		(width 0.089408)
		(layer "In9.Cu")
		(net "H_CPU0_ERR0_G_N")
	)
	(segment
		(start 378.552964 -42.299382)
		(end 378.869448 -42.299382)
		(width 0.089408)
		(layer "In9.Cu")
		(net "H_CPU0_ERR0_G_N")
	)
	(segment
		(start 379.465078 -55.462932)
		(end 379.56363 -55.561484)
		(width 0.089408)
		(layer "In9.Cu")
		(net "H_CPU0_ERR0_G_N")
	)
	(segment
		(start 379.593856 -51.027838)
		(end 379.465078 -51.156616)
		(width 0.089408)
		(layer "In9.Cu")
		(net "H_CPU0_ERR0_G_N")
	)
	(segment
		(start 354.972874 -62.888368)
		(end 354.518722 -63.34252)
		(width 0.089408)
		(layer "In11.Cu")
		(net "H_CPU0_ERR0_G_N")
	)
	(segment
		(start 298.671742 -65.484248)
		(end 298.378626 -65.315338)
		(width 0.0889)
		(layer "In11.Cu")
		(net "H_CPU0_ERR0_G_N")
	)
	(segment
		(start 305.257962 -64.724788)
		(end 305.225196 -64.724788)
		(width 0.0889)
		(layer "In11.Cu")
		(net "H_CPU0_ERR0_G_N")
	)
	(segment
		(start 363.996478 -65.376552)
		(end 362.153708 -63.533782)
		(width 0.089408)
		(layer "In11.Cu")
		(net "H_CPU0_ERR0_G_N")
	)
	(segment
		(start 354.518722 -63.34252)
		(end 335.3054 -63.34252)
		(width 0.089408)
		(layer "In11.Cu")
		(net "H_CPU0_ERR0_G_N")
	)
	(segment
		(start 332.58252 -66.0654)
		(end 312.969148 -66.0654)
		(width 0.089408)
		(layer "In11.Cu")
		(net "H_CPU0_ERR0_G_N")
	)
	(segment
		(start 311.676542 -64.772794)
		(end 311.63641 -64.772794)
		(width 0.089408)
		(layer "In11.Cu")
		(net "H_CPU0_ERR0_G_N")
	)
	(segment
		(start 310.232298 -64.724788)
		(end 306.95265 -64.724788)
		(width 0.0889)
		(layer "In11.Cu")
		(net "H_CPU0_ERR0_G_N")
	)
	(segment
		(start 312.969148 -66.0654)
		(end 311.676542 -64.772794)
		(width 0.089408)
		(layer "In11.Cu")
		(net "H_CPU0_ERR0_G_N")
	)
	(segment
		(start 310.232552 -64.724534)
		(end 310.232298 -64.724788)
		(width 0.089408)
		(layer "In11.Cu")
		(net "H_CPU0_ERR0_G_N")
	)
	(segment
		(start 335.3054 -63.34252)
		(end 332.58252 -66.0654)
		(width 0.089408)
		(layer "In11.Cu")
		(net "H_CPU0_ERR0_G_N")
	)
	(segment
		(start 300.969172 -65.219834)
		(end 300.936406 -65.219834)
		(width 0.0889)
		(layer "In11.Cu")
		(net "H_CPU0_ERR0_G_N")
	)
	(segment
		(start 298.76115 -65.460118)
		(end 298.671742 -65.484248)
		(width 0.0889)
		(layer "In11.Cu")
		(net "H_CPU0_ERR0_G_N")
	)
	(segment
		(start 356.07879 -62.888368)
		(end 354.972874 -62.888368)
		(width 0.089408)
		(layer "In11.Cu")
		(net "H_CPU0_ERR0_G_N")
	)
	(segment
		(start 311.58815 -64.724534)
		(end 310.232552 -64.724534)
		(width 0.089408)
		(layer "In11.Cu")
		(net "H_CPU0_ERR0_G_N")
	)
	(segment
		(start 311.63641 -64.772794)
		(end 311.58815 -64.724534)
		(width 0.089408)
		(layer "In11.Cu")
		(net "H_CPU0_ERR0_G_N")
	)
	(segment
		(start 362.153708 -63.533782)
		(end 356.724204 -63.533782)
		(width 0.089408)
		(layer "In11.Cu")
		(net "H_CPU0_ERR0_G_N")
	)
	(segment
		(start 356.724204 -63.533782)
		(end 356.07879 -62.888368)
		(width 0.089408)
		(layer "In11.Cu")
		(net "H_CPU0_ERR0_G_N")
	)
	(arc
		(start 303.017936 -65.019936)
		(mid 302.671226 -65.22012)
		(end 302.324516 -65.019936)
		(width 0.0889)
		(layer "In11.Cu")
		(net "H_CPU0_ERR0_G_N")
	)
	(arc
		(start 300.442376 -65.515236)
		(mid 300.095666 -65.715547)
		(end 299.748956 -65.515236)
		(width 0.0889)
		(layer "In11.Cu")
		(net "H_CPU0_ERR0_G_N")
	)
	(arc
		(start 305.225196 -64.724788)
		(mid 304.941979 -64.809069)
		(end 304.734976 -65.019936)
		(width 0.0889)
		(layer "In11.Cu")
		(net "H_CPU0_ERR0_G_N")
	)
	(arc
		(start 302.324516 -65.019936)
		(mid 301.812706 -64.724397)
		(end 301.300896 -65.019936)
		(width 0.0889)
		(layer "In11.Cu")
		(net "H_CPU0_ERR0_G_N")
	)
	(arc
		(start 306.95265 -64.724788)
		(mid 306.7588 -64.668438)
		(end 306.617116 -64.524636)
		(width 0.0889)
		(layer "In11.Cu")
		(net "H_CPU0_ERR0_G_N")
	)
	(arc
		(start 299.219366 -65.219834)
		(mid 298.962544 -65.287135)
		(end 298.76115 -65.460118)
		(width 0.0889)
		(layer "In11.Cu")
		(net "H_CPU0_ERR0_G_N")
	)
	(arc
		(start 305.593496 -64.524636)
		(mid 305.451813 -64.66844)
		(end 305.257962 -64.724788)
		(width 0.0889)
		(layer "In11.Cu")
		(net "H_CPU0_ERR0_G_N")
	)
	(arc
		(start 301.300896 -65.019936)
		(mid 301.160817 -65.162672)
		(end 300.969172 -65.219834)
		(width 0.0889)
		(layer "In11.Cu")
		(net "H_CPU0_ERR0_G_N")
	)
	(arc
		(start 300.936406 -65.219834)
		(mid 300.650982 -65.303301)
		(end 300.442376 -65.515236)
		(width 0.0889)
		(layer "In11.Cu")
		(net "H_CPU0_ERR0_G_N")
	)
	(arc
		(start 304.041556 -65.019936)
		(mid 303.529746 -64.724397)
		(end 303.017936 -65.019936)
		(width 0.0889)
		(layer "In11.Cu")
		(net "H_CPU0_ERR0_G_N")
	)
	(arc
		(start 304.734976 -65.019936)
		(mid 304.388266 -65.22012)
		(end 304.041556 -65.019936)
		(width 0.0889)
		(layer "In11.Cu")
		(net "H_CPU0_ERR0_G_N")
	)
	(arc
		(start 299.748956 -65.515236)
		(mid 299.524908 -65.294492)
		(end 299.219366 -65.219834)
		(width 0.0889)
		(layer "In11.Cu")
		(net "H_CPU0_ERR0_G_N")
	)
	(arc
		(start 306.617116 -64.524636)
		(mid 306.105306 -64.228969)
		(end 305.593496 -64.524636)
		(width 0.0889)
		(layer "In11.Cu")
		(net "H_CPU0_ERR0_G_N")
	)
	(segment
		(start 401.057364 -100.1776)
		(end 400.880072 -100.354892)
		(width 0.0889)
		(layer "F.Cu")
		(net "XTAL_KR_25M_OUT")
	)
	(segment
		(start 401.424648 -100.1776)
		(end 401.057364 -100.1776)
		(width 0.0889)
		(layer "F.Cu")
		(net "XTAL_KR_25M_OUT")
	)
	(segment
		(start 402.40458 -99.67722)
		(end 401.925028 -99.67722)
		(width 0.10795)
		(layer "F.Cu")
		(net "XTAL_KR_25M_OUT")
	)
	(segment
		(start 405.344122 -97.967038)
		(end 405.443436 -97.867724)
		(width 0.10795)
		(layer "F.Cu")
		(net "XTAL_KR_25M_OUT")
	)
	(segment
		(start 407.126186 -98.470212)
		(end 407.010616 -98.585782)
		(width 0.10795)
		(layer "F.Cu")
		(net "XTAL_KR_25M_OUT")
	)
	(segment
		(start 405.344122 -98.137218)
		(end 405.344122 -97.967038)
		(width 0.10795)
		(layer "F.Cu")
		(net "XTAL_KR_25M_OUT")
	)
	(segment
		(start 404.927054 -98.441764)
		(end 405.039576 -98.441764)
		(width 0.10795)
		(layer "F.Cu")
		(net "XTAL_KR_25M_OUT")
	)
	(segment
		(start 405.443436 -97.867724)
		(end 406.999186 -97.867724)
		(width 0.10795)
		(layer "F.Cu")
		(net "XTAL_KR_25M_OUT")
	)
	(segment
		(start 403.640036 -98.441764)
		(end 402.40458 -99.67722)
		(width 0.10795)
		(layer "F.Cu")
		(net "XTAL_KR_25M_OUT")
	)
	(segment
		(start 407.010616 -98.585782)
		(end 406.203658 -98.585782)
		(width 0.10795)
		(layer "F.Cu")
		(net "XTAL_KR_25M_OUT")
	)
	(segment
		(start 401.925028 -99.67722)
		(end 401.424648 -100.1776)
		(width 0.0889)
		(layer "F.Cu")
		(net "XTAL_KR_25M_OUT")
	)
	(segment
		(start 406.999186 -97.867724)
		(end 407.126186 -97.994724)
		(width 0.10795)
		(layer "F.Cu")
		(net "XTAL_KR_25M_OUT")
	)
	(segment
		(start 404.927054 -98.441764)
		(end 403.640036 -98.441764)
		(width 0.10795)
		(layer "F.Cu")
		(net "XTAL_KR_25M_OUT")
	)
	(segment
		(start 405.039576 -98.441764)
		(end 405.344122 -98.137218)
		(width 0.10795)
		(layer "F.Cu")
		(net "XTAL_KR_25M_OUT")
	)
	(segment
		(start 407.126186 -97.994724)
		(end 407.126186 -98.470212)
		(width 0.10795)
		(layer "F.Cu")
		(net "XTAL_KR_25M_OUT")
	)
	(segment
		(start 401.371054 -100.53701)
		(end 401.68195 -100.226114)
		(width 0.0889)
		(layer "F.Cu")
		(net "XTAL_KR_25M_IN")
	)
	(segment
		(start 404.879556 -100.226114)
		(end 404.990554 -100.337112)
		(width 0.10795)
		(layer "F.Cu")
		(net "XTAL_KR_25M_IN")
	)
	(segment
		(start 405.422354 -100.748338)
		(end 405.422354 -100.474018)
		(width 0.10795)
		(layer "F.Cu")
		(net "XTAL_KR_25M_IN")
	)
	(segment
		(start 402.057362 -100.226114)
		(end 404.879556 -100.226114)
		(width 0.10795)
		(layer "F.Cu")
		(net "XTAL_KR_25M_IN")
	)
	(segment
		(start 401.16252 -100.53701)
		(end 401.371054 -100.53701)
		(width 0.0889)
		(layer "F.Cu")
		(net "XTAL_KR_25M_IN")
	)
	(segment
		(start 405.593804 -100.919788)
		(end 405.422354 -100.748338)
		(width 0.10795)
		(layer "F.Cu")
		(net "XTAL_KR_25M_IN")
	)
	(segment
		(start 408.30373 -100.185982)
		(end 408.280362 -100.185982)
		(width 0.10795)
		(layer "F.Cu")
		(net "XTAL_KR_25M_IN")
	)
	(segment
		(start 401.033488 -100.666042)
		(end 401.16252 -100.53701)
		(width 0.0889)
		(layer "F.Cu")
		(net "XTAL_KR_25M_IN")
	)
	(segment
		(start 401.68195 -100.226114)
		(end 402.057362 -100.226114)
		(width 0.0889)
		(layer "F.Cu")
		(net "XTAL_KR_25M_IN")
	)
	(segment
		(start 405.285448 -100.337112)
		(end 404.990554 -100.337112)
		(width 0.10795)
		(layer "F.Cu")
		(net "XTAL_KR_25M_IN")
	)
	(segment
		(start 400.418046 -100.354892)
		(end 400.729196 -100.666042)
		(width 0.0889)
		(layer "F.Cu")
		(net "XTAL_KR_25M_IN")
	)
	(segment
		(start 400.729196 -100.666042)
		(end 401.033488 -100.666042)
		(width 0.0889)
		(layer "F.Cu")
		(net "XTAL_KR_25M_IN")
	)
	(segment
		(start 408.280362 -100.185982)
		(end 407.546556 -100.919788)
		(width 0.10795)
		(layer "F.Cu")
		(net "XTAL_KR_25M_IN")
	)
	(segment
		(start 405.422354 -100.474018)
		(end 405.285448 -100.337112)
		(width 0.10795)
		(layer "F.Cu")
		(net "XTAL_KR_25M_IN")
	)
	(segment
		(start 400.05 -100.354892)
		(end 400.418046 -100.354892)
		(width 0.0889)
		(layer "F.Cu")
		(net "XTAL_KR_25M_IN")
	)
	(segment
		(start 407.546556 -100.919788)
		(end 405.593804 -100.919788)
		(width 0.10795)
		(layer "F.Cu")
		(net "XTAL_KR_25M_IN")
	)
	(segment
		(start 482.6508 -34.04616)
		(end 482.6508 -33.909)
		(width 0.10795)
		(layer "F.Cu")
		(net "XTAL_CK_MNG_OUT")
	)
	(segment
		(start 483.9843 -33.78454)
		(end 483.07244 -34.6964)
		(width 0.10795)
		(layer "F.Cu")
		(net "XTAL_CK_MNG_OUT")
	)
	(segment
		(start 483.07244 -34.6964)
		(end 482.00056 -34.6964)
		(width 0.10795)
		(layer "F.Cu")
		(net "XTAL_CK_MNG_OUT")
	)
	(segment
		(start 482.00056 -34.6964)
		(end 482.6508 -34.04616)
		(width 0.10795)
		(layer "F.Cu")
		(net "XTAL_CK_MNG_OUT")
	)
	(segment
		(start 481.94468 -32.2834)
		(end 482.6508 -32.2834)
		(width 0.10795)
		(layer "F.Cu")
		(net "XTAL_CK_MNG_IN")
	)
	(segment
		(start 483.288086 -32.579818)
		(end 484.68915 -32.579818)
		(width 0.10795)
		(layer "F.Cu")
		(net "XTAL_CK_MNG_IN")
	)
	(segment
		(start 482.991668 -32.2834)
		(end 483.288086 -32.579818)
		(width 0.10795)
		(layer "F.Cu")
		(net "XTAL_CK_MNG_IN")
	)
	(segment
		(start 481.612956 -32.61106)
		(end 481.875846 -32.34817)
		(width 0.10795)
		(layer "F.Cu")
		(net "XTAL_CK_MNG_IN")
	)
	(segment
		(start 482.6508 -32.2834)
		(end 482.991668 -32.2834)
		(width 0.10795)
		(layer "F.Cu")
		(net "XTAL_CK_MNG_IN")
	)
	(segment
		(start 481.0125 -32.61106)
		(end 481.612956 -32.61106)
		(width 0.10795)
		(layer "F.Cu")
		(net "XTAL_CK_MNG_IN")
	)
	(segment
		(start 481.87991 -32.34817)
		(end 481.94468 -32.2834)
		(width 0.10795)
		(layer "F.Cu")
		(net "XTAL_CK_MNG_IN")
	)
	(segment
		(start 484.68915 -32.579818)
		(end 485.5845 -31.684468)
		(width 0.10795)
		(layer "F.Cu")
		(net "XTAL_CK_MNG_IN")
	)
	(segment
		(start 481.875846 -32.34817)
		(end 481.87991 -32.34817)
		(width 0.10795)
		(layer "F.Cu")
		(net "XTAL_CK_MNG_IN")
	)
	(segment
		(start 380.30785 -111.57204)
		(end 380.80315 -111.802164)
		(width 0.10795)
		(layer "F.Cu")
		(net "TP_PCH_RSVD23")
	)
	(via
		(at 380.80315 -111.802164)
		(size 0.508)
		(drill 0.254)
		(layers "F.Cu" "B.Cu")
		(net "TP_PCH_RSVD23")
	)
	(segment
		(start 380.80315 -103.84536)
		(end 381.29845 -103.615236)
		(width 0.10795)
		(layer "F.Cu")
		(net "TP_PCH_RSVD54")
	)
	(via
		(at 381.29845 -103.615236)
		(size 0.508)
		(drill 0.254)
		(layers "F.Cu" "B.Cu")
		(net "TP_PCH_RSVD54")
	)
	(segment
		(start 380.30785 -104.70388)
		(end 380.428246 -104.648)
		(width 0.10795)
		(layer "F.Cu")
		(net "TP_PCH_RSVD53")
	)
	(segment
		(start 380.428246 -104.648)
		(end 380.80315 -104.473756)
		(width 0.10795)
		(layer "F.Cu")
		(net "TP_PCH_RSVD53")
	)
	(via
		(at 380.80315 -104.473756)
		(size 0.508)
		(drill 0.254)
		(layers "F.Cu" "B.Cu")
		(net "TP_PCH_RSVD53")
	)
	(segment
		(start 398.13865 -108.13796)
		(end 398.269714 -108.077)
		(width 0.10795)
		(layer "F.Cu")
		(net "TP_10GBE_KR1_MON_DP")
	)
	(segment
		(start 398.269714 -108.077)
		(end 398.63395 -107.907836)
		(width 0.10795)
		(layer "F.Cu")
		(net "TP_10GBE_KR1_MON_DP")
	)
	(via
		(at 398.63395 -107.907836)
		(size 0.508)
		(drill 0.254)
		(layers "F.Cu" "B.Cu")
		(net "TP_10GBE_KR1_MON_DP")
	)
	(segment
		(start 397.558768 -107.947206)
		(end 397.64335 -107.907836)
		(width 0.10795)
		(layer "F.Cu")
		(net "TP_10GBE_KR1_MON_DN")
	)
	(segment
		(start 397.14805 -108.13796)
		(end 397.279114 -108.077)
		(width 0.10795)
		(layer "F.Cu")
		(net "TP_10GBE_KR1_MON_DN")
	)
	(segment
		(start 397.279114 -108.077)
		(end 397.558768 -107.947206)
		(width 0.10795)
		(layer "F.Cu")
		(net "TP_10GBE_KR1_MON_DN")
	)
	(via
		(at 397.64335 -107.907836)
		(size 0.508)
		(drill 0.254)
		(layers "F.Cu" "B.Cu")
		(net "TP_10GBE_KR1_MON_DN")
	)
	(segment
		(start 395.224 -111.59871)
		(end 395.66215 -111.802164)
		(width 0.10795)
		(layer "F.Cu")
		(net "TP_PCH_RSVD42")
	)
	(segment
		(start 395.16685 -111.57204)
		(end 395.224 -111.59871)
		(width 0.10795)
		(layer "F.Cu")
		(net "TP_PCH_RSVD42")
	)
	(via
		(at 395.66215 -111.802164)
		(size 0.508)
		(drill 0.254)
		(layers "F.Cu" "B.Cu")
		(net "TP_PCH_RSVD42")
	)
	(segment
		(start 396.15745 -111.57204)
		(end 396.65275 -111.802164)
		(width 0.10795)
		(layer "F.Cu")
		(net "TP_PCH_RSVD41")
	)
	(via
		(at 396.65275 -111.802164)
		(size 0.508)
		(drill 0.254)
		(layers "F.Cu" "B.Cu")
		(net "TP_PCH_RSVD41")
	)
	(segment
		(start 382.28905 -97.83572)
		(end 382.3462 -97.809304)
		(width 0.10795)
		(layer "F.Cu")
		(net "TP_PCH_RSVD3")
	)
	(segment
		(start 382.3462 -97.809304)
		(end 382.397 -97.785682)
		(width 0.10795)
		(layer "F.Cu")
		(net "TP_PCH_RSVD3")
	)
	(segment
		(start 382.397 -97.785682)
		(end 382.78435 -97.605596)
		(width 0.10795)
		(layer "F.Cu")
		(net "TP_PCH_RSVD3")
	)
	(via
		(at 382.78435 -97.605596)
		(size 0.508)
		(drill 0.254)
		(layers "F.Cu" "B.Cu")
		(net "TP_PCH_RSVD3")
	)
	(segment
		(start 397.64335 -104.473756)
		(end 398.13865 -104.70388)
		(width 0.10795)
		(layer "F.Cu")
		(net "TP_10GBE_KR0_MON_DP")
	)
	(via
		(at 397.64335 -104.473756)
		(size 0.508)
		(drill 0.254)
		(layers "F.Cu" "B.Cu")
		(net "TP_10GBE_KR0_MON_DP")
	)
	(segment
		(start 397.14805 -104.70388)
		(end 396.65275 -104.473756)
		(width 0.10795)
		(layer "F.Cu")
		(net "TP_10GBE_KR0_MON_DN")
	)
	(via
		(at 396.65275 -104.473756)
		(size 0.508)
		(drill 0.254)
		(layers "F.Cu" "B.Cu")
		(net "TP_10GBE_KR0_MON_DN")
	)
	(segment
		(start 397.14805 -106.42092)
		(end 397.104616 -106.4006)
		(width 0.10795)
		(layer "F.Cu")
		(net "TP_PCH_RSVD38")
	)
	(segment
		(start 397.104616 -106.4006)
		(end 396.65275 -106.190796)
		(width 0.10795)
		(layer "F.Cu")
		(net "TP_PCH_RSVD38")
	)
	(via
		(at 396.65275 -106.190796)
		(size 0.508)
		(drill 0.254)
		(layers "F.Cu" "B.Cu")
		(net "TP_PCH_RSVD38")
	)
	(segment
		(start 398.13865 -106.42092)
		(end 398.0942 -106.400346)
		(width 0.10795)
		(layer "F.Cu")
		(net "TP_PCH_RSVD37")
	)
	(segment
		(start 398.0942 -106.400346)
		(end 397.64335 -106.190796)
		(width 0.10795)
		(layer "F.Cu")
		(net "TP_PCH_RSVD37")
	)
	(via
		(at 397.64335 -106.190796)
		(size 0.508)
		(drill 0.254)
		(layers "F.Cu" "B.Cu")
		(net "TP_PCH_RSVD37")
	)
	(segment
		(start 395.16685 -104.70388)
		(end 395.16685 -105.332276)
		(width 0.10795)
		(layer "F.Cu")
		(net "TP_PCH_RSVD27")
	)
	(via
		(at 395.16685 -105.332276)
		(size 0.508)
		(drill 0.254)
		(layers "F.Cu" "B.Cu")
		(net "TP_PCH_RSVD27")
	)
	(segment
		(start 395.66215 -103.84536)
		(end 395.16685 -103.615236)
		(width 0.10795)
		(layer "F.Cu")
		(net "TP_PCH_RSVD26")
	)
	(via
		(at 395.16685 -103.615236)
		(size 0.508)
		(drill 0.254)
		(layers "F.Cu" "B.Cu")
		(net "TP_PCH_RSVD26")
	)
	(segment
		(start 383.840482 -119.3292)
		(end 384.27025 -119.528844)
		(width 0.10795)
		(layer "F.Cu")
		(net "TP_PCH_RSVD2")
	)
	(segment
		(start 383.77495 -119.29872)
		(end 383.840482 -119.3292)
		(width 0.10795)
		(layer "F.Cu")
		(net "TP_PCH_RSVD2")
	)
	(via
		(at 384.27025 -119.528844)
		(size 0.508)
		(drill 0.254)
		(layers "F.Cu" "B.Cu")
		(net "TP_PCH_RSVD2")
	)
	(segment
		(start 384.762248 -118.6688)
		(end 384.76555 -118.670324)
		(width 0.10795)
		(layer "F.Cu")
		(net "TP_PCH_RSVD1")
	)
	(segment
		(start 384.27025 -118.4402)
		(end 384.762248 -118.6688)
		(width 0.10795)
		(layer "F.Cu")
		(net "TP_PCH_RSVD1")
	)
	(via
		(at 384.76555 -118.670324)
		(size 0.508)
		(drill 0.254)
		(layers "F.Cu" "B.Cu")
		(net "TP_PCH_RSVD1")
	)
	(segment
		(start 385.75615 -121.01576)
		(end 386.25145 -121.245884)
		(width 0.10795)
		(layer "F.Cu")
		(net "TP_PCH_RSVD0")
	)
	(via
		(at 386.25145 -121.245884)
		(size 0.508)
		(drill 0.254)
		(layers "F.Cu" "B.Cu")
		(net "TP_PCH_RSVD0")
	)
	(segment
		(start 377.83135 -102.12832)
		(end 378.32665 -101.898196)
		(width 0.10795)
		(layer "F.Cu")
		(net "TP_PCH_HDA_SYNC")
	)
	(via
		(at 378.32665 -101.898196)
		(size 0.508)
		(drill 0.254)
		(layers "F.Cu" "B.Cu")
		(net "TP_PCH_HDA_SYNC")
	)
	(segment
		(start 378.82195 -102.12832)
		(end 379.31725 -101.898196)
		(width 0.10795)
		(layer "F.Cu")
		(net "TP_PCH_HDA_SDI_0")
	)
	(via
		(at 379.31725 -101.898196)
		(size 0.508)
		(drill 0.254)
		(layers "F.Cu" "B.Cu")
		(net "TP_PCH_HDA_SDI_0")
	)
	(segment
		(start 380.30785 -102.98684)
		(end 380.80315 -102.756716)
		(width 0.10795)
		(layer "F.Cu")
		(net "TP_PCH_RSVD45")
	)
	(via
		(at 380.80315 -102.756716)
		(size 0.508)
		(drill 0.254)
		(layers "F.Cu" "B.Cu")
		(net "TP_PCH_RSVD45")
	)
	(segment
		(start 380.80315 -101.039676)
		(end 380.30785 -101.2698)
		(width 0.10795)
		(layer "F.Cu")
		(net "TP_PCH_HDA_BCLK")
	)
	(via
		(at 380.80315 -101.039676)
		(size 0.508)
		(drill 0.254)
		(layers "F.Cu" "B.Cu")
		(net "TP_PCH_HDA_BCLK")
	)
	(segment
		(start 379.81255 -101.039676)
		(end 379.31725 -101.2698)
		(width 0.10795)
		(layer "F.Cu")
		(net "TP_PCH_HSA_RST_N")
	)
	(via
		(at 379.81255 -101.039676)
		(size 0.508)
		(drill 0.254)
		(layers "F.Cu" "B.Cu")
		(net "TP_PCH_HSA_RST_N")
	)
	(segment
		(start 386.25145 -99.55276)
		(end 386.74675 -99.322636)
		(width 0.10795)
		(layer "F.Cu")
		(net "TP_PCH_RSVD5")
	)
	(via
		(at 386.74675 -99.322636)
		(size 0.508)
		(drill 0.254)
		(layers "F.Cu" "B.Cu")
		(net "TP_PCH_RSVD5")
	)
	(segment
		(start 382.28905 -102.98684)
		(end 382.3462 -102.960424)
		(width 0.10795)
		(layer "F.Cu")
		(net "TP_PCH_DISPA_SDO")
	)
	(segment
		(start 382.3462 -102.960424)
		(end 382.78435 -102.756716)
		(width 0.10795)
		(layer "F.Cu")
		(net "TP_PCH_DISPA_SDO")
	)
	(via
		(at 382.78435 -102.756716)
		(size 0.508)
		(drill 0.254)
		(layers "F.Cu" "B.Cu")
		(net "TP_PCH_DISPA_SDO")
	)
	(segment
		(start 380.80315 -102.12832)
		(end 381.29845 -101.898196)
		(width 0.10795)
		(layer "F.Cu")
		(net "TP_PCH_DISPA_SDI")
	)
	(via
		(at 381.29845 -101.898196)
		(size 0.508)
		(drill 0.254)
		(layers "F.Cu" "B.Cu")
		(net "TP_PCH_DISPA_SDI")
	)
	(segment
		(start 381.79375 -102.12832)
		(end 382.1684 -101.95433)
		(width 0.10795)
		(layer "F.Cu")
		(net "TP_PCH_DISPA_BCLK")
	)
	(segment
		(start 382.1684 -101.95433)
		(end 382.28905 -101.898196)
		(width 0.10795)
		(layer "F.Cu")
		(net "TP_PCH_DISPA_BCLK")
	)
	(via
		(at 382.28905 -101.898196)
		(size 0.508)
		(drill 0.254)
		(layers "F.Cu" "B.Cu")
		(net "TP_PCH_DISPA_BCLK")
	)
	(segment
		(start 141.142974 -80.669384)
		(end 140.533374 -80.669384)
		(width 0.10795)
		(layer "F.Cu")
		(net "TP_P3E_CPU1_PE2_RSR_TXP<9>")
	)
	(segment
		(start 141.181074 -80.631284)
		(end 141.142974 -80.669384)
		(width 0.10795)
		(layer "F.Cu")
		(net "TP_P3E_CPU1_PE2_RSR_TXP<9>")
	)
	(via
		(at 141.181074 -80.631284)
		(size 0.508)
		(drill 0.254)
		(layers "F.Cu" "B.Cu")
		(net "TP_P3E_CPU1_PE2_RSR_TXP<9>")
	)
	(segment
		(start 140.533374 -82.650584)
		(end 141.104874 -82.650584)
		(width 0.10795)
		(layer "F.Cu")
		(net "TP_P3E_CPU1_PE2_RSR_TXP<8>")
	)
	(via
		(at 141.104874 -82.650584)
		(size 0.508)
		(drill 0.254)
		(layers "F.Cu" "B.Cu")
		(net "TP_P3E_CPU1_PE2_RSR_TXP<8>")
	)
	(segment
		(start 139.674854 -83.146138)
		(end 140.246354 -83.146138)
		(width 0.10795)
		(layer "F.Cu")
		(net "TP_P3E_CPU1_PE2_RSR_TXP<7>")
	)
	(via
		(at 140.246354 -83.146138)
		(size 0.508)
		(drill 0.254)
		(layers "F.Cu" "B.Cu")
		(net "TP_P3E_CPU1_PE2_RSR_TXP<7>")
	)
	(segment
		(start 141.391894 -83.146138)
		(end 142.039594 -83.146138)
		(width 0.10795)
		(layer "F.Cu")
		(net "TP_P3E_CPU1_PE2_RSR_TXP<6>")
	)
	(via
		(at 142.039594 -83.146138)
		(size 0.508)
		(drill 0.254)
		(layers "F.Cu" "B.Cu")
		(net "TP_P3E_CPU1_PE2_RSR_TXP<6>")
	)
	(segment
		(start 140.533374 -85.622384)
		(end 141.104874 -85.622384)
		(width 0.10795)
		(layer "F.Cu")
		(net "TP_P3E_CPU1_PE2_RSR_TXP<5>")
	)
	(via
		(at 141.104874 -85.622384)
		(size 0.4826)
		(drill 0.254)
		(layers "F.Cu" "B.Cu")
		(net "TP_P3E_CPU1_PE2_RSR_TXP<5>")
	)
	(segment
		(start 142.250414 -85.622384)
		(end 142.898114 -85.622384)
		(width 0.10795)
		(layer "F.Cu")
		(net "TP_P3E_CPU1_PE2_RSR_TXP<4>")
	)
	(via
		(at 142.898114 -85.622384)
		(size 0.4826)
		(drill 0.254)
		(layers "F.Cu" "B.Cu")
		(net "TP_P3E_CPU1_PE2_RSR_TXP<4>")
	)
	(segment
		(start 140.533374 -87.603584)
		(end 141.104874 -87.603584)
		(width 0.10795)
		(layer "F.Cu")
		(net "TP_P3E_CPU1_PE2_RSR_TXP<3>")
	)
	(via
		(at 141.104874 -87.603584)
		(size 0.4826)
		(drill 0.254)
		(layers "F.Cu" "B.Cu")
		(net "TP_P3E_CPU1_PE2_RSR_TXP<3>")
	)
	(segment
		(start 151.5364 -85.3186)
		(end 151.0284 -85.3186)
		(width 0.10795)
		(layer "F.Cu")
		(net "TP_P3E_CPU1_PE2_RSR_TXP<2>")
	)
	(segment
		(start 148.2598 -88.0872)
		(end 141.403832 -88.0872)
		(width 0.10795)
		(layer "F.Cu")
		(net "TP_P3E_CPU1_PE2_RSR_TXP<2>")
	)
	(segment
		(start 141.403832 -88.0872)
		(end 141.391894 -88.099138)
		(width 0.10795)
		(layer "F.Cu")
		(net "TP_P3E_CPU1_PE2_RSR_TXP<2>")
	)
	(segment
		(start 151.0284 -85.3186)
		(end 148.2598 -88.0872)
		(width 0.10795)
		(layer "F.Cu")
		(net "TP_P3E_CPU1_PE2_RSR_TXP<2>")
	)
	(via
		(at 151.5364 -85.3186)
		(size 0.762)
		(drill 0.381)
		(layers "F.Cu" "B.Cu")
		(net "TP_P3E_CPU1_PE2_RSR_TXP<2>")
	)
	(segment
		(start 141.391894 -89.089738)
		(end 141.963394 -89.089738)
		(width 0.10795)
		(layer "F.Cu")
		(net "TP_P3E_CPU1_PE2_RSR_TXP<1>")
	)
	(via
		(at 141.963394 -89.089738)
		(size 0.4826)
		(drill 0.254)
		(layers "F.Cu" "B.Cu")
		(net "TP_P3E_CPU1_PE2_RSR_TXP<1>")
	)
	(segment
		(start 138.816334 -75.716384)
		(end 139.387834 -75.716384)
		(width 0.10795)
		(layer "F.Cu")
		(net "TP_P3E_CPU1_PE2_RSR_TXP<15>")
	)
	(via
		(at 139.387834 -75.716384)
		(size 0.508)
		(drill 0.254)
		(layers "F.Cu" "B.Cu")
		(net "TP_P3E_CPU1_PE2_RSR_TXP<15>")
	)
	(segment
		(start 140.533374 -76.706984)
		(end 141.181074 -76.706984)
		(width 0.10795)
		(layer "F.Cu")
		(net "TP_P3E_CPU1_PE2_RSR_TXP<14>")
	)
	(via
		(at 141.181074 -76.706984)
		(size 0.508)
		(drill 0.254)
		(layers "F.Cu" "B.Cu")
		(net "TP_P3E_CPU1_PE2_RSR_TXP<14>")
	)
	(segment
		(start 139.674854 -77.202538)
		(end 140.246354 -77.202538)
		(width 0.10795)
		(layer "F.Cu")
		(net "TP_P3E_CPU1_PE2_RSR_TXP<13>")
	)
	(via
		(at 140.246354 -77.202538)
		(size 0.508)
		(drill 0.254)
		(layers "F.Cu" "B.Cu")
		(net "TP_P3E_CPU1_PE2_RSR_TXP<13>")
	)
	(segment
		(start 139.674854 -78.193138)
		(end 140.246354 -78.193138)
		(width 0.10795)
		(layer "F.Cu")
		(net "TP_P3E_CPU1_PE2_RSR_TXP<12>")
	)
	(via
		(at 140.246354 -78.193138)
		(size 0.508)
		(drill 0.254)
		(layers "F.Cu" "B.Cu")
		(net "TP_P3E_CPU1_PE2_RSR_TXP<12>")
	)
	(segment
		(start 140.533374 -79.678784)
		(end 141.181074 -79.678784)
		(width 0.10795)
		(layer "F.Cu")
		(net "TP_P3E_CPU1_PE2_RSR_TXP<11>")
	)
	(via
		(at 141.181074 -79.678784)
		(size 0.508)
		(drill 0.254)
		(layers "F.Cu" "B.Cu")
		(net "TP_P3E_CPU1_PE2_RSR_TXP<11>")
	)
	(segment
		(start 138.816334 -80.669384)
		(end 139.387834 -80.669384)
		(width 0.10795)
		(layer "F.Cu")
		(net "TP_P3E_CPU1_PE2_RSR_TXP<10>")
	)
	(via
		(at 139.387834 -80.669384)
		(size 0.508)
		(drill 0.254)
		(layers "F.Cu" "B.Cu")
		(net "TP_P3E_CPU1_PE2_RSR_TXP<10>")
	)
	(segment
		(start 139.674854 -90.080338)
		(end 140.246354 -90.080338)
		(width 0.10795)
		(layer "F.Cu")
		(net "TP_P3E_CPU1_PE2_RSR_TXP<0>")
	)
	(via
		(at 140.246354 -90.080338)
		(size 0.4826)
		(drill 0.254)
		(layers "F.Cu" "B.Cu")
		(net "TP_P3E_CPU1_PE2_RSR_TXP<0>")
	)
	(segment
		(start 140.533374 -81.659984)
		(end 141.104874 -81.659984)
		(width 0.10795)
		(layer "F.Cu")
		(net "TP_P3E_CPU1_PE2_RSR_TXN<9>")
	)
	(via
		(at 141.104874 -81.659984)
		(size 0.508)
		(drill 0.254)
		(layers "F.Cu" "B.Cu")
		(net "TP_P3E_CPU1_PE2_RSR_TXN<9>")
	)
	(segment
		(start 141.391894 -82.155284)
		(end 142.039594 -82.155284)
		(width 0.10795)
		(layer "F.Cu")
		(net "TP_P3E_CPU1_PE2_RSR_TXN<8>")
	)
	(via
		(at 142.039594 -82.155284)
		(size 0.508)
		(drill 0.254)
		(layers "F.Cu" "B.Cu")
		(net "TP_P3E_CPU1_PE2_RSR_TXN<8>")
	)
	(segment
		(start 140.533374 -83.641184)
		(end 141.104874 -83.641184)
		(width 0.10795)
		(layer "F.Cu")
		(net "TP_P3E_CPU1_PE2_RSR_TXN<7>")
	)
	(via
		(at 141.104874 -83.641184)
		(size 0.508)
		(drill 0.254)
		(layers "F.Cu" "B.Cu")
		(net "TP_P3E_CPU1_PE2_RSR_TXN<7>")
	)
	(segment
		(start 142.003018 -84.136738)
		(end 141.391894 -84.136738)
		(width 0.10795)
		(layer "F.Cu")
		(net "TP_P3E_CPU1_PE2_RSR_TXN<6>")
	)
	(segment
		(start 142.039594 -84.100162)
		(end 142.003018 -84.136738)
		(width 0.10795)
		(layer "F.Cu")
		(net "TP_P3E_CPU1_PE2_RSR_TXN<6>")
	)
	(via
		(at 142.039594 -84.100162)
		(size 0.508)
		(drill 0.254)
		(layers "F.Cu" "B.Cu")
		(net "TP_P3E_CPU1_PE2_RSR_TXN<6>")
	)
	(segment
		(start 141.391894 -86.117938)
		(end 141.963394 -86.117938)
		(width 0.10795)
		(layer "F.Cu")
		(net "TP_P3E_CPU1_PE2_RSR_TXN<5>")
	)
	(via
		(at 141.963394 -86.117938)
		(size 0.4826)
		(drill 0.254)
		(layers "F.Cu" "B.Cu")
		(net "TP_P3E_CPU1_PE2_RSR_TXN<5>")
	)
	(segment
		(start 142.898114 -86.612984)
		(end 142.250414 -86.612984)
		(width 0.10795)
		(layer "F.Cu")
		(net "TP_P3E_CPU1_PE2_RSR_TXN<4>")
	)
	(via
		(at 142.898114 -86.612984)
		(size 0.4826)
		(drill 0.254)
		(layers "F.Cu" "B.Cu")
		(net "TP_P3E_CPU1_PE2_RSR_TXN<4>")
	)
	(segment
		(start 140.533374 -88.594184)
		(end 141.104874 -88.594184)
		(width 0.10795)
		(layer "F.Cu")
		(net "TP_P3E_CPU1_PE2_RSR_TXN<3>")
	)
	(via
		(at 141.104874 -88.594184)
		(size 0.4826)
		(drill 0.254)
		(layers "F.Cu" "B.Cu")
		(net "TP_P3E_CPU1_PE2_RSR_TXN<3>")
	)
	(segment
		(start 151.5364 -86.5886)
		(end 151.003 -86.5886)
		(width 0.10795)
		(layer "F.Cu")
		(net "TP_P3E_CPU1_PE2_RSR_TXN<2>")
	)
	(segment
		(start 151.003 -86.5886)
		(end 148.5138 -89.0778)
		(width 0.10795)
		(layer "F.Cu")
		(net "TP_P3E_CPU1_PE2_RSR_TXN<2>")
	)
	(segment
		(start 142.73403 -89.0778)
		(end 142.250414 -88.594184)
		(width 0.10795)
		(layer "F.Cu")
		(net "TP_P3E_CPU1_PE2_RSR_TXN<2>")
	)
	(segment
		(start 148.5138 -89.0778)
		(end 142.73403 -89.0778)
		(width 0.10795)
		(layer "F.Cu")
		(net "TP_P3E_CPU1_PE2_RSR_TXN<2>")
	)
	(via
		(at 151.5364 -86.5886)
		(size 0.762)
		(drill 0.381)
		(layers "F.Cu" "B.Cu")
		(net "TP_P3E_CPU1_PE2_RSR_TXN<2>")
	)
	(segment
		(start 140.533374 -89.584784)
		(end 141.104874 -89.584784)
		(width 0.10795)
		(layer "F.Cu")
		(net "TP_P3E_CPU1_PE2_RSR_TXN<1>")
	)
	(via
		(at 141.104874 -89.584784)
		(size 0.4826)
		(drill 0.254)
		(layers "F.Cu" "B.Cu")
		(net "TP_P3E_CPU1_PE2_RSR_TXN<1>")
	)
	(segment
		(start 138.816334 -76.706984)
		(end 139.387834 -76.706984)
		(width 0.10795)
		(layer "F.Cu")
		(net "TP_P3E_CPU1_PE2_RSR_TXN<15>")
	)
	(via
		(at 139.387834 -76.706984)
		(size 0.508)
		(drill 0.254)
		(layers "F.Cu" "B.Cu")
		(net "TP_P3E_CPU1_PE2_RSR_TXN<15>")
	)
	(segment
		(start 139.674854 -76.211938)
		(end 140.246354 -76.211938)
		(width 0.10795)
		(layer "F.Cu")
		(net "TP_P3E_CPU1_PE2_RSR_TXN<14>")
	)
	(via
		(at 140.246354 -76.211938)
		(size 0.508)
		(drill 0.254)
		(layers "F.Cu" "B.Cu")
		(net "TP_P3E_CPU1_PE2_RSR_TXN<14>")
	)
	(segment
		(start 138.816334 -77.697584)
		(end 139.387834 -77.697584)
		(width 0.10795)
		(layer "F.Cu")
		(net "TP_P3E_CPU1_PE2_RSR_TXN<13>")
	)
	(via
		(at 139.387834 -77.697584)
		(size 0.508)
		(drill 0.254)
		(layers "F.Cu" "B.Cu")
		(net "TP_P3E_CPU1_PE2_RSR_TXN<13>")
	)
	(segment
		(start 139.674854 -79.183738)
		(end 140.246354 -79.183738)
		(width 0.10795)
		(layer "F.Cu")
		(net "TP_P3E_CPU1_PE2_RSR_TXN<12>")
	)
	(via
		(at 140.246354 -79.183738)
		(size 0.508)
		(drill 0.254)
		(layers "F.Cu" "B.Cu")
		(net "TP_P3E_CPU1_PE2_RSR_TXN<12>")
	)
	(segment
		(start 139.674854 -80.174338)
		(end 140.246354 -80.174338)
		(width 0.10795)
		(layer "F.Cu")
		(net "TP_P3E_CPU1_PE2_RSR_TXN<11>")
	)
	(via
		(at 140.246354 -80.174338)
		(size 0.508)
		(drill 0.254)
		(layers "F.Cu" "B.Cu")
		(net "TP_P3E_CPU1_PE2_RSR_TXN<11>")
	)
	(segment
		(start 139.674854 -81.164938)
		(end 140.246354 -81.164938)
		(width 0.10795)
		(layer "F.Cu")
		(net "TP_P3E_CPU1_PE2_RSR_TXN<10>")
	)
	(via
		(at 140.246354 -81.164938)
		(size 0.508)
		(drill 0.254)
		(layers "F.Cu" "B.Cu")
		(net "TP_P3E_CPU1_PE2_RSR_TXN<10>")
	)
	(segment
		(start 136.812274 -80.174338)
		(end 136.240774 -80.174338)
		(width 0.10795)
		(layer "F.Cu")
		(net "TP_P3E_CPU1_PE2_RSR_RXP<9>")
	)
	(via
		(at 136.812274 -80.174338)
		(size 0.508)
		(drill 0.254)
		(layers "F.Cu" "B.Cu")
		(net "TP_P3E_CPU1_PE2_RSR_RXP<9>")
	)
	(segment
		(start 135.382254 -79.678784)
		(end 135.953754 -79.678784)
		(width 0.10795)
		(layer "F.Cu")
		(net "TP_P3E_CPU1_PE2_RSR_RXP<8>")
	)
	(via
		(at 135.953754 -79.678784)
		(size 0.508)
		(drill 0.254)
		(layers "F.Cu" "B.Cu")
		(net "TP_P3E_CPU1_PE2_RSR_RXP<8>")
	)
	(segment
		(start 136.240774 -82.155284)
		(end 136.812274 -82.155284)
		(width 0.10795)
		(layer "F.Cu")
		(net "TP_P3E_CPU1_PE2_RSR_RXP<7>")
	)
	(via
		(at 136.812274 -82.155284)
		(size 0.4826)
		(drill 0.254)
		(layers "F.Cu" "B.Cu")
		(net "TP_P3E_CPU1_PE2_RSR_RXP<7>")
	)
	(segment
		(start 137.670794 -82.650584)
		(end 137.099294 -82.650584)
		(width 0.10795)
		(layer "F.Cu")
		(net "TP_P3E_CPU1_PE2_RSR_RXP<6>")
	)
	(via
		(at 137.670794 -82.650584)
		(size 0.4826)
		(drill 0.254)
		(layers "F.Cu" "B.Cu")
		(net "TP_P3E_CPU1_PE2_RSR_RXP<6>")
	)
	(segment
		(start 137.670794 -83.641184)
		(end 137.099294 -83.641184)
		(width 0.10795)
		(layer "F.Cu")
		(net "TP_P3E_CPU1_PE2_RSR_RXP<5>")
	)
	(via
		(at 137.670794 -83.641184)
		(size 0.4826)
		(drill 0.254)
		(layers "F.Cu" "B.Cu")
		(net "TP_P3E_CPU1_PE2_RSR_RXP<5>")
	)
	(segment
		(start 137.670794 -84.631784)
		(end 137.099294 -84.631784)
		(width 0.10795)
		(layer "F.Cu")
		(net "TP_P3E_CPU1_PE2_RSR_RXP<4>")
	)
	(via
		(at 137.670794 -84.631784)
		(size 0.4826)
		(drill 0.254)
		(layers "F.Cu" "B.Cu")
		(net "TP_P3E_CPU1_PE2_RSR_RXP<4>")
	)
	(segment
		(start 137.957814 -86.117938)
		(end 138.529314 -86.117938)
		(width 0.10795)
		(layer "F.Cu")
		(net "TP_P3E_CPU1_PE2_RSR_RXP<3>")
	)
	(via
		(at 138.529314 -86.117938)
		(size 0.4826)
		(drill 0.254)
		(layers "F.Cu" "B.Cu")
		(net "TP_P3E_CPU1_PE2_RSR_RXP<3>")
	)
	(segment
		(start 136.240774 -87.108538)
		(end 136.812274 -87.108538)
		(width 0.10795)
		(layer "F.Cu")
		(net "TP_P3E_CPU1_PE2_RSR_RXP<2>")
	)
	(via
		(at 136.812274 -87.108538)
		(size 0.4826)
		(drill 0.254)
		(layers "F.Cu" "B.Cu")
		(net "TP_P3E_CPU1_PE2_RSR_RXP<2>")
	)
	(segment
		(start 135.382254 -86.612984)
		(end 135.953754 -86.612984)
		(width 0.10795)
		(layer "F.Cu")
		(net "TP_P3E_CPU1_PE2_RSR_RXP<1>")
	)
	(via
		(at 135.953754 -86.612984)
		(size 0.4826)
		(drill 0.254)
		(layers "F.Cu" "B.Cu")
		(net "TP_P3E_CPU1_PE2_RSR_RXP<1>")
	)
	(segment
		(start 134.523734 -75.221338)
		(end 135.095234 -75.221338)
		(width 0.10795)
		(layer "F.Cu")
		(net "TP_P3E_CPU1_PE2_RSR_RXP<15>")
	)
	(via
		(at 135.095234 -75.221338)
		(size 0.508)
		(drill 0.254)
		(layers "F.Cu" "B.Cu")
		(net "TP_P3E_CPU1_PE2_RSR_RXP<15>")
	)
	(segment
		(start 136.240774 -75.221338)
		(end 136.812274 -75.221338)
		(width 0.10795)
		(layer "F.Cu")
		(net "TP_P3E_CPU1_PE2_RSR_RXP<14>")
	)
	(via
		(at 136.812274 -75.221338)
		(size 0.508)
		(drill 0.254)
		(layers "F.Cu" "B.Cu")
		(net "TP_P3E_CPU1_PE2_RSR_RXP<14>")
	)
	(segment
		(start 137.099294 -76.706984)
		(end 137.670794 -76.706984)
		(width 0.10795)
		(layer "F.Cu")
		(net "TP_P3E_CPU1_PE2_RSR_RXP<13>")
	)
	(via
		(at 137.670794 -76.706984)
		(size 0.508)
		(drill 0.254)
		(layers "F.Cu" "B.Cu")
		(net "TP_P3E_CPU1_PE2_RSR_RXP<13>")
	)
	(segment
		(start 135.382254 -77.697584)
		(end 135.953754 -77.697584)
		(width 0.10795)
		(layer "F.Cu")
		(net "TP_P3E_CPU1_PE2_RSR_RXP<12>")
	)
	(via
		(at 135.953754 -77.697584)
		(size 0.508)
		(drill 0.254)
		(layers "F.Cu" "B.Cu")
		(net "TP_P3E_CPU1_PE2_RSR_RXP<12>")
	)
	(segment
		(start 137.099294 -77.697584)
		(end 137.670794 -77.697584)
		(width 0.10795)
		(layer "F.Cu")
		(net "TP_P3E_CPU1_PE2_RSR_RXP<11>")
	)
	(via
		(at 137.670794 -77.697584)
		(size 0.508)
		(drill 0.254)
		(layers "F.Cu" "B.Cu")
		(net "TP_P3E_CPU1_PE2_RSR_RXP<11>")
	)
	(segment
		(start 137.957814 -79.183738)
		(end 138.529314 -79.183738)
		(width 0.10795)
		(layer "F.Cu")
		(net "TP_P3E_CPU1_PE2_RSR_RXP<10>")
	)
	(via
		(at 138.529314 -79.183738)
		(size 0.508)
		(drill 0.254)
		(layers "F.Cu" "B.Cu")
		(net "TP_P3E_CPU1_PE2_RSR_RXP<10>")
	)
	(segment
		(start 136.240774 -88.099138)
		(end 136.812274 -88.099138)
		(width 0.10795)
		(layer "F.Cu")
		(net "TP_P3E_CPU1_PE2_RSR_RXP<0>")
	)
	(via
		(at 136.812274 -88.099138)
		(size 0.4826)
		(drill 0.254)
		(layers "F.Cu" "B.Cu")
		(net "TP_P3E_CPU1_PE2_RSR_RXP<0>")
	)
	(segment
		(start 137.099294 -80.669384)
		(end 137.670794 -80.669384)
		(width 0.10795)
		(layer "F.Cu")
		(net "TP_P3E_CPU1_PE2_RSR_RXN<9>")
	)
	(via
		(at 137.670794 -80.669384)
		(size 0.508)
		(drill 0.254)
		(layers "F.Cu" "B.Cu")
		(net "TP_P3E_CPU1_PE2_RSR_RXN<9>")
	)
	(segment
		(start 135.382254 -80.669384)
		(end 135.953754 -80.669384)
		(width 0.10795)
		(layer "F.Cu")
		(net "TP_P3E_CPU1_PE2_RSR_RXN<8>")
	)
	(via
		(at 135.953754 -80.669384)
		(size 0.508)
		(drill 0.254)
		(layers "F.Cu" "B.Cu")
		(net "TP_P3E_CPU1_PE2_RSR_RXN<8>")
	)
	(segment
		(start 136.240774 -83.146138)
		(end 136.812274 -83.146138)
		(width 0.10795)
		(layer "F.Cu")
		(net "TP_P3E_CPU1_PE2_RSR_RXN<7>")
	)
	(via
		(at 136.812274 -83.146138)
		(size 0.4826)
		(drill 0.254)
		(layers "F.Cu" "B.Cu")
		(net "TP_P3E_CPU1_PE2_RSR_RXN<7>")
	)
	(segment
		(start 137.957814 -83.146138)
		(end 138.529314 -83.146138)
		(width 0.10795)
		(layer "F.Cu")
		(net "TP_P3E_CPU1_PE2_RSR_RXN<6>")
	)
	(via
		(at 138.529314 -83.146138)
		(size 0.4826)
		(drill 0.254)
		(layers "F.Cu" "B.Cu")
		(net "TP_P3E_CPU1_PE2_RSR_RXN<6>")
	)
	(segment
		(start 136.240774 -84.136738)
		(end 136.812274 -84.136738)
		(width 0.10795)
		(layer "F.Cu")
		(net "TP_P3E_CPU1_PE2_RSR_RXN<5>")
	)
	(via
		(at 136.812274 -84.136738)
		(size 0.4826)
		(drill 0.254)
		(layers "F.Cu" "B.Cu")
		(net "TP_P3E_CPU1_PE2_RSR_RXN<5>")
	)
	(segment
		(start 137.670794 -85.622384)
		(end 137.099294 -85.622384)
		(width 0.10795)
		(layer "F.Cu")
		(net "TP_P3E_CPU1_PE2_RSR_RXN<4>")
	)
	(via
		(at 137.670794 -85.622384)
		(size 0.4826)
		(drill 0.254)
		(layers "F.Cu" "B.Cu")
		(net "TP_P3E_CPU1_PE2_RSR_RXN<4>")
	)
	(segment
		(start 137.670794 -86.612984)
		(end 137.099294 -86.612984)
		(width 0.10795)
		(layer "F.Cu")
		(net "TP_P3E_CPU1_PE2_RSR_RXN<3>")
	)
	(via
		(at 137.670794 -86.612984)
		(size 0.4826)
		(drill 0.254)
		(layers "F.Cu" "B.Cu")
		(net "TP_P3E_CPU1_PE2_RSR_RXN<3>")
	)
	(segment
		(start 137.670794 -87.603584)
		(end 137.099294 -87.603584)
		(width 0.10795)
		(layer "F.Cu")
		(net "TP_P3E_CPU1_PE2_RSR_RXN<2>")
	)
	(via
		(at 137.670794 -87.603584)
		(size 0.4826)
		(drill 0.254)
		(layers "F.Cu" "B.Cu")
		(net "TP_P3E_CPU1_PE2_RSR_RXN<2>")
	)
	(segment
		(start 135.382254 -87.603584)
		(end 135.953754 -87.603584)
		(width 0.10795)
		(layer "F.Cu")
		(net "TP_P3E_CPU1_PE2_RSR_RXN<1>")
	)
	(via
		(at 135.953754 -87.603584)
		(size 0.4826)
		(drill 0.254)
		(layers "F.Cu" "B.Cu")
		(net "TP_P3E_CPU1_PE2_RSR_RXN<1>")
	)
	(segment
		(start 135.382254 -75.716384)
		(end 135.953754 -75.716384)
		(width 0.10795)
		(layer "F.Cu")
		(net "TP_P3E_CPU1_PE2_RSR_RXN<15>")
	)
	(via
		(at 135.953754 -75.716384)
		(size 0.508)
		(drill 0.254)
		(layers "F.Cu" "B.Cu")
		(net "TP_P3E_CPU1_PE2_RSR_RXN<15>")
	)
	(segment
		(start 136.240774 -76.211938)
		(end 136.812274 -76.211938)
		(width 0.10795)
		(layer "F.Cu")
		(net "TP_P3E_CPU1_PE2_RSR_RXN<14>")
	)
	(via
		(at 136.812274 -76.211938)
		(size 0.508)
		(drill 0.254)
		(layers "F.Cu" "B.Cu")
		(net "TP_P3E_CPU1_PE2_RSR_RXN<14>")
	)
	(segment
		(start 136.240774 -77.202538)
		(end 136.812274 -77.202538)
		(width 0.10795)
		(layer "F.Cu")
		(net "TP_P3E_CPU1_PE2_RSR_RXN<13>")
	)
	(via
		(at 136.812274 -77.202538)
		(size 0.508)
		(drill 0.254)
		(layers "F.Cu" "B.Cu")
		(net "TP_P3E_CPU1_PE2_RSR_RXN<13>")
	)
	(segment
		(start 136.240774 -78.193138)
		(end 136.812274 -78.193138)
		(width 0.10795)
		(layer "F.Cu")
		(net "TP_P3E_CPU1_PE2_RSR_RXN<12>")
	)
	(via
		(at 136.812274 -78.193138)
		(size 0.508)
		(drill 0.254)
		(layers "F.Cu" "B.Cu")
		(net "TP_P3E_CPU1_PE2_RSR_RXN<12>")
	)
	(segment
		(start 137.099294 -78.688438)
		(end 137.670794 -78.688438)
		(width 0.10795)
		(layer "F.Cu")
		(net "TP_P3E_CPU1_PE2_RSR_RXN<11>")
	)
	(via
		(at 137.670794 -78.688438)
		(size 0.508)
		(drill 0.254)
		(layers "F.Cu" "B.Cu")
		(net "TP_P3E_CPU1_PE2_RSR_RXN<11>")
	)
	(segment
		(start 137.099294 -79.678784)
		(end 137.670794 -79.678784)
		(width 0.10795)
		(layer "F.Cu")
		(net "TP_P3E_CPU1_PE2_RSR_RXN<10>")
	)
	(via
		(at 137.670794 -79.678784)
		(size 0.508)
		(drill 0.254)
		(layers "F.Cu" "B.Cu")
		(net "TP_P3E_CPU1_PE2_RSR_RXN<10>")
	)
	(segment
		(start 135.382254 -88.594184)
		(end 135.953754 -88.594184)
		(width 0.10795)
		(layer "F.Cu")
		(net "TP_P3E_CPU1_PE2_RSR_RXN<0>")
	)
	(via
		(at 135.953754 -88.594184)
		(size 0.4826)
		(drill 0.254)
		(layers "F.Cu" "B.Cu")
		(net "TP_P3E_CPU1_PE2_RSR_RXN<0>")
	)
	(segment
		(start 141.391894 -98.995738)
		(end 142.039848 -98.995738)
		(width 0.10795)
		(layer "F.Cu")
		(net "TP_P3E_CPU1_PE1_RSR3_TXP<9>")
	)
	(via
		(at 142.039848 -98.995738)
		(size 0.508)
		(drill 0.254)
		(layers "F.Cu" "B.Cu")
		(net "TP_P3E_CPU1_PE1_RSR3_TXP<9>")
	)
	(segment
		(start 139.674854 -98.005138)
		(end 140.246354 -98.005138)
		(width 0.10795)
		(layer "F.Cu")
		(net "TP_P3E_CPU1_PE1_RSR3_TXP<8>")
	)
	(via
		(at 140.246354 -98.005138)
		(size 0.4826)
		(drill 0.254)
		(layers "F.Cu" "B.Cu")
		(net "TP_P3E_CPU1_PE1_RSR3_TXP<8>")
	)
	(segment
		(start 136.240774 -101.967538)
		(end 135.7884 -102.419912)
		(width 0.10795)
		(layer "F.Cu")
		(net "TP_P3E_CPU1_PE1_RSR3_TXP<15>")
	)
	(segment
		(start 135.7884 -103.126032)
		(end 138.351768 -105.6894)
		(width 0.10795)
		(layer "F.Cu")
		(net "TP_P3E_CPU1_PE1_RSR3_TXP<15>")
	)
	(segment
		(start 138.351768 -105.6894)
		(end 152.019 -105.6894)
		(width 0.10795)
		(layer "F.Cu")
		(net "TP_P3E_CPU1_PE1_RSR3_TXP<15>")
	)
	(segment
		(start 152.019 -105.6894)
		(end 152.8318 -106.5022)
		(width 0.10795)
		(layer "F.Cu")
		(net "TP_P3E_CPU1_PE1_RSR3_TXP<15>")
	)
	(segment
		(start 152.8318 -106.5022)
		(end 153.6446 -106.5022)
		(width 0.10795)
		(layer "F.Cu")
		(net "TP_P3E_CPU1_PE1_RSR3_TXP<15>")
	)
	(segment
		(start 135.7884 -102.419912)
		(end 135.7884 -103.126032)
		(width 0.10795)
		(layer "F.Cu")
		(net "TP_P3E_CPU1_PE1_RSR3_TXP<15>")
	)
	(via
		(at 153.6446 -106.5022)
		(size 0.762)
		(drill 0.381)
		(layers "F.Cu" "B.Cu")
		(net "TP_P3E_CPU1_PE1_RSR3_TXP<15>")
	)
	(segment
		(start 137.099294 -101.471984)
		(end 137.541 -101.91369)
		(width 0.10795)
		(layer "F.Cu")
		(net "TP_P3E_CPU1_PE1_RSR3_TXP<14>")
	)
	(segment
		(start 137.541 -103.4542)
		(end 139.319 -105.2322)
		(width 0.10795)
		(layer "F.Cu")
		(net "TP_P3E_CPU1_PE1_RSR3_TXP<14>")
	)
	(segment
		(start 139.319 -105.2322)
		(end 153.6446 -105.2322)
		(width 0.10795)
		(layer "F.Cu")
		(net "TP_P3E_CPU1_PE1_RSR3_TXP<14>")
	)
	(segment
		(start 137.541 -101.91369)
		(end 137.541 -103.4542)
		(width 0.10795)
		(layer "F.Cu")
		(net "TP_P3E_CPU1_PE1_RSR3_TXP<14>")
	)
	(via
		(at 153.6446 -105.2322)
		(size 0.762)
		(drill 0.381)
		(layers "F.Cu" "B.Cu")
		(net "TP_P3E_CPU1_PE1_RSR3_TXP<14>")
	)
	(segment
		(start 137.957814 -99.986338)
		(end 138.529314 -99.986338)
		(width 0.10795)
		(layer "F.Cu")
		(net "TP_P3E_CPU1_PE1_RSR3_TXP<13>")
	)
	(via
		(at 138.529314 -99.986338)
		(size 0.508)
		(drill 0.254)
		(layers "F.Cu" "B.Cu")
		(net "TP_P3E_CPU1_PE1_RSR3_TXP<13>")
	)
	(segment
		(start 137.099294 -98.500184)
		(end 137.670794 -98.500184)
		(width 0.10795)
		(layer "F.Cu")
		(net "TP_P3E_CPU1_PE1_RSR3_TXP<12>")
	)
	(via
		(at 137.670794 -98.500184)
		(size 0.508)
		(drill 0.254)
		(layers "F.Cu" "B.Cu")
		(net "TP_P3E_CPU1_PE1_RSR3_TXP<12>")
	)
	(segment
		(start 152.572974 -101.981)
		(end 152.750774 -101.8032)
		(width 0.10795)
		(layer "F.Cu")
		(net "TP_P3E_CPU1_PE1_RSR3_TXP<11>")
	)
	(segment
		(start 139.1666 -99.84105)
		(end 139.1666 -100.1776)
		(width 0.10795)
		(layer "F.Cu")
		(net "TP_P3E_CPU1_PE1_RSR3_TXP<11>")
	)
	(segment
		(start 140.310108 -100.940108)
		(end 140.741654 -100.940108)
		(width 0.10795)
		(layer "F.Cu")
		(net "TP_P3E_CPU1_PE1_RSR3_TXP<11>")
	)
	(segment
		(start 141.75867 -101.1301)
		(end 142.60957 -101.981)
		(width 0.10795)
		(layer "F.Cu")
		(net "TP_P3E_CPU1_PE1_RSR3_TXP<11>")
	)
	(segment
		(start 140.741654 -100.940108)
		(end 140.931646 -101.1301)
		(width 0.10795)
		(layer "F.Cu")
		(net "TP_P3E_CPU1_PE1_RSR3_TXP<11>")
	)
	(segment
		(start 140.931646 -101.1301)
		(end 141.75867 -101.1301)
		(width 0.10795)
		(layer "F.Cu")
		(net "TP_P3E_CPU1_PE1_RSR3_TXP<11>")
	)
	(segment
		(start 139.4714 -100.4824)
		(end 139.8524 -100.4824)
		(width 0.10795)
		(layer "F.Cu")
		(net "TP_P3E_CPU1_PE1_RSR3_TXP<11>")
	)
	(segment
		(start 139.1666 -100.1776)
		(end 139.4714 -100.4824)
		(width 0.10795)
		(layer "F.Cu")
		(net "TP_P3E_CPU1_PE1_RSR3_TXP<11>")
	)
	(segment
		(start 142.60957 -101.981)
		(end 152.572974 -101.981)
		(width 0.10795)
		(layer "F.Cu")
		(net "TP_P3E_CPU1_PE1_RSR3_TXP<11>")
	)
	(segment
		(start 139.8524 -100.4824)
		(end 140.310108 -100.940108)
		(width 0.10795)
		(layer "F.Cu")
		(net "TP_P3E_CPU1_PE1_RSR3_TXP<11>")
	)
	(segment
		(start 138.816334 -99.490784)
		(end 139.1666 -99.84105)
		(width 0.10795)
		(layer "F.Cu")
		(net "TP_P3E_CPU1_PE1_RSR3_TXP<11>")
	)
	(via
		(at 152.750774 -101.8032)
		(size 0.762)
		(drill 0.381)
		(layers "F.Cu" "B.Cu")
		(net "TP_P3E_CPU1_PE1_RSR3_TXP<11>")
	)
	(segment
		(start 153.2382 -95.377)
		(end 154.4066 -94.2086)
		(width 0.10795)
		(layer "F.Cu")
		(net "TP_P3E_CPU1_PE1_RSR3_TXP<10>")
	)
	(segment
		(start 140.626338 -98.995738)
		(end 141.1478 -99.5172)
		(width 0.10795)
		(layer "F.Cu")
		(net "TP_P3E_CPU1_PE1_RSR3_TXP<10>")
	)
	(segment
		(start 151.511 -95.377)
		(end 153.2382 -95.377)
		(width 0.10795)
		(layer "F.Cu")
		(net "TP_P3E_CPU1_PE1_RSR3_TXP<10>")
	)
	(segment
		(start 139.674854 -98.995738)
		(end 140.626338 -98.995738)
		(width 0.10795)
		(layer "F.Cu")
		(net "TP_P3E_CPU1_PE1_RSR3_TXP<10>")
	)
	(segment
		(start 147.3708 -99.5172)
		(end 151.511 -95.377)
		(width 0.10795)
		(layer "F.Cu")
		(net "TP_P3E_CPU1_PE1_RSR3_TXP<10>")
	)
	(segment
		(start 141.1478 -99.5172)
		(end 147.3708 -99.5172)
		(width 0.10795)
		(layer "F.Cu")
		(net "TP_P3E_CPU1_PE1_RSR3_TXP<10>")
	)
	(via
		(at 154.4066 -94.2086)
		(size 0.762)
		(drill 0.381)
		(layers "F.Cu" "B.Cu")
		(net "TP_P3E_CPU1_PE1_RSR3_TXP<10>")
	)
	(segment
		(start 140.8684 -99.82581)
		(end 140.8684 -100.1776)
		(width 0.10795)
		(layer "F.Cu")
		(net "TP_P3E_CPU1_PE1_RSR3_TXN<9>")
	)
	(segment
		(start 140.533374 -99.490784)
		(end 140.8684 -99.82581)
		(width 0.10795)
		(layer "F.Cu")
		(net "TP_P3E_CPU1_PE1_RSR3_TXN<9>")
	)
	(segment
		(start 147.066 -100.584)
		(end 151.7396 -95.9104)
		(width 0.10795)
		(layer "F.Cu")
		(net "TP_P3E_CPU1_PE1_RSR3_TXN<9>")
	)
	(segment
		(start 140.8684 -100.1776)
		(end 141.2748 -100.584)
		(width 0.10795)
		(layer "F.Cu")
		(net "TP_P3E_CPU1_PE1_RSR3_TXN<9>")
	)
	(segment
		(start 141.2748 -100.584)
		(end 147.066 -100.584)
		(width 0.10795)
		(layer "F.Cu")
		(net "TP_P3E_CPU1_PE1_RSR3_TXN<9>")
	)
	(segment
		(start 151.7396 -95.9104)
		(end 154.9908 -95.9104)
		(width 0.10795)
		(layer "F.Cu")
		(net "TP_P3E_CPU1_PE1_RSR3_TXN<9>")
	)
	(via
		(at 154.9908 -95.9104)
		(size 0.762)
		(drill 0.381)
		(layers "F.Cu" "B.Cu")
		(net "TP_P3E_CPU1_PE1_RSR3_TXN<9>")
	)
	(segment
		(start 138.816334 -98.500184)
		(end 139.387834 -98.500184)
		(width 0.10795)
		(layer "F.Cu")
		(net "TP_P3E_CPU1_PE1_RSR3_TXN<8>")
	)
	(via
		(at 139.387834 -98.500184)
		(size 0.4826)
		(drill 0.254)
		(layers "F.Cu" "B.Cu")
		(net "TP_P3E_CPU1_PE1_RSR3_TXN<8>")
	)
	(segment
		(start 135.509 -103.3907)
		(end 138.2141 -106.0958)
		(width 0.10795)
		(layer "F.Cu")
		(net "TP_P3E_CPU1_PE1_RSR3_TXN<15>")
	)
	(segment
		(start 135.509 -102.58933)
		(end 135.509 -103.3907)
		(width 0.10795)
		(layer "F.Cu")
		(net "TP_P3E_CPU1_PE1_RSR3_TXN<15>")
	)
	(segment
		(start 151.9682 -106.0958)
		(end 153.6446 -107.7722)
		(width 0.10795)
		(layer "F.Cu")
		(net "TP_P3E_CPU1_PE1_RSR3_TXN<15>")
	)
	(segment
		(start 135.382254 -102.462584)
		(end 135.509 -102.58933)
		(width 0.10795)
		(layer "F.Cu")
		(net "TP_P3E_CPU1_PE1_RSR3_TXN<15>")
	)
	(segment
		(start 138.2141 -106.0958)
		(end 151.9682 -106.0958)
		(width 0.10795)
		(layer "F.Cu")
		(net "TP_P3E_CPU1_PE1_RSR3_TXN<15>")
	)
	(via
		(at 153.6446 -107.7722)
		(size 0.762)
		(drill 0.381)
		(layers "F.Cu" "B.Cu")
		(net "TP_P3E_CPU1_PE1_RSR3_TXN<15>")
	)
	(segment
		(start 137.670794 -100.481638)
		(end 137.099294 -100.481638)
		(width 0.10795)
		(layer "F.Cu")
		(net "TP_P3E_CPU1_PE1_RSR3_TXN<13>")
	)
	(via
		(at 137.670794 -100.481638)
		(size 0.508)
		(drill 0.254)
		(layers "F.Cu" "B.Cu")
		(net "TP_P3E_CPU1_PE1_RSR3_TXN<13>")
	)
	(segment
		(start 137.670794 -99.490784)
		(end 137.099294 -99.490784)
		(width 0.10795)
		(layer "F.Cu")
		(net "TP_P3E_CPU1_PE1_RSR3_TXN<12>")
	)
	(via
		(at 137.670794 -99.490784)
		(size 0.508)
		(drill 0.254)
		(layers "F.Cu" "B.Cu")
		(net "TP_P3E_CPU1_PE1_RSR3_TXN<12>")
	)
	(segment
		(start 137.957814 -98.995738)
		(end 138.529314 -98.995738)
		(width 0.10795)
		(layer "F.Cu")
		(net "TP_P3E_CPU1_PE1_RSR3_TXN<11>")
	)
	(via
		(at 138.529314 -98.995738)
		(size 0.508)
		(drill 0.254)
		(layers "F.Cu" "B.Cu")
		(net "TP_P3E_CPU1_PE1_RSR3_TXN<11>")
	)
	(segment
		(start 139.674854 -99.986338)
		(end 140.246354 -99.986338)
		(width 0.10795)
		(layer "F.Cu")
		(net "TP_P3E_CPU1_PE1_RSR3_TXN<10>")
	)
	(via
		(at 140.246354 -99.986338)
		(size 0.508)
		(drill 0.254)
		(layers "F.Cu" "B.Cu")
		(net "TP_P3E_CPU1_PE1_RSR3_TXN<10>")
	)
	(segment
		(start 134.523734 -97.014538)
		(end 135.095234 -97.014538)
		(width 0.10795)
		(layer "F.Cu")
		(net "TP_P3E_CPU1_PE1_RSR3_RXP<9>")
	)
	(via
		(at 135.095234 -97.014538)
		(size 0.4826)
		(drill 0.254)
		(layers "F.Cu" "B.Cu")
		(net "TP_P3E_CPU1_PE1_RSR3_RXP<9>")
	)
	(segment
		(start 133.665214 -95.528384)
		(end 134.236714 -95.528384)
		(width 0.10795)
		(layer "F.Cu")
		(net "TP_P3E_CPU1_PE1_RSR3_RXP<8>")
	)
	(via
		(at 134.236714 -95.528384)
		(size 0.4826)
		(drill 0.254)
		(layers "F.Cu" "B.Cu")
		(net "TP_P3E_CPU1_PE1_RSR3_RXP<8>")
	)
	(segment
		(start 130.231388 -98.500184)
		(end 130.802888 -98.500184)
		(width 0.10795)
		(layer "F.Cu")
		(net "TP_P3E_CPU1_PE1_RSR3_RXP<15>")
	)
	(via
		(at 130.802888 -98.500184)
		(size 0.4826)
		(drill 0.254)
		(layers "F.Cu" "B.Cu")
		(net "TP_P3E_CPU1_PE1_RSR3_RXP<15>")
	)
	(segment
		(start 130.231388 -99.490784)
		(end 130.802888 -99.490784)
		(width 0.10795)
		(layer "F.Cu")
		(net "TP_P3E_CPU1_PE1_RSR3_RXP<14>")
	)
	(via
		(at 130.802888 -99.490784)
		(size 0.4826)
		(drill 0.254)
		(layers "F.Cu" "B.Cu")
		(net "TP_P3E_CPU1_PE1_RSR3_RXP<14>")
	)
	(segment
		(start 131.948174 -100.481638)
		(end 132.519674 -100.481638)
		(width 0.10795)
		(layer "F.Cu")
		(net "TP_P3E_CPU1_PE1_RSR3_RXP<13>")
	)
	(via
		(at 132.519674 -100.481638)
		(size 0.4826)
		(drill 0.254)
		(layers "F.Cu" "B.Cu")
		(net "TP_P3E_CPU1_PE1_RSR3_RXP<13>")
	)
	(segment
		(start 132.806694 -98.995738)
		(end 133.378194 -98.995738)
		(width 0.10795)
		(layer "F.Cu")
		(net "TP_P3E_CPU1_PE1_RSR3_RXP<12>")
	)
	(via
		(at 133.378194 -98.995738)
		(size 0.4826)
		(drill 0.254)
		(layers "F.Cu" "B.Cu")
		(net "TP_P3E_CPU1_PE1_RSR3_RXP<12>")
	)
	(segment
		(start 131.948174 -97.509584)
		(end 132.519674 -97.509584)
		(width 0.10795)
		(layer "F.Cu")
		(net "TP_P3E_CPU1_PE1_RSR3_RXP<11>")
	)
	(via
		(at 132.519674 -97.509584)
		(size 0.4826)
		(drill 0.254)
		(layers "F.Cu" "B.Cu")
		(net "TP_P3E_CPU1_PE1_RSR3_RXP<11>")
	)
	(segment
		(start 132.806694 -98.005138)
		(end 133.378194 -98.005138)
		(width 0.10795)
		(layer "F.Cu")
		(net "TP_P3E_CPU1_PE1_RSR3_RXP<10>")
	)
	(via
		(at 133.378194 -98.005138)
		(size 0.4826)
		(drill 0.254)
		(layers "F.Cu" "B.Cu")
		(net "TP_P3E_CPU1_PE1_RSR3_RXP<10>")
	)
	(segment
		(start 133.665214 -97.509584)
		(end 134.236714 -97.509584)
		(width 0.10795)
		(layer "F.Cu")
		(net "TP_P3E_CPU1_PE1_RSR3_RXN<9>")
	)
	(via
		(at 134.236714 -97.509584)
		(size 0.4826)
		(drill 0.254)
		(layers "F.Cu" "B.Cu")
		(net "TP_P3E_CPU1_PE1_RSR3_RXN<9>")
	)
	(segment
		(start 133.665214 -96.518984)
		(end 134.236714 -96.518984)
		(width 0.10795)
		(layer "F.Cu")
		(net "TP_P3E_CPU1_PE1_RSR3_RXN<8>")
	)
	(via
		(at 134.236714 -96.518984)
		(size 0.4826)
		(drill 0.254)
		(layers "F.Cu" "B.Cu")
		(net "TP_P3E_CPU1_PE1_RSR3_RXN<8>")
	)
	(segment
		(start 129.372868 -98.995738)
		(end 129.944368 -98.995738)
		(width 0.10795)
		(layer "F.Cu")
		(net "TP_P3E_CPU1_PE1_RSR3_RXN<15>")
	)
	(via
		(at 129.944368 -98.995738)
		(size 0.4826)
		(drill 0.254)
		(layers "F.Cu" "B.Cu")
		(net "TP_P3E_CPU1_PE1_RSR3_RXN<15>")
	)
	(segment
		(start 130.231388 -100.481638)
		(end 130.802888 -100.481638)
		(width 0.10795)
		(layer "F.Cu")
		(net "TP_P3E_CPU1_PE1_RSR3_RXN<14>")
	)
	(via
		(at 130.802888 -100.481638)
		(size 0.4826)
		(drill 0.254)
		(layers "F.Cu" "B.Cu")
		(net "TP_P3E_CPU1_PE1_RSR3_RXN<14>")
	)
	(segment
		(start 131.089908 -99.986338)
		(end 131.661408 -99.986338)
		(width 0.10795)
		(layer "F.Cu")
		(net "TP_P3E_CPU1_PE1_RSR3_RXN<13>")
	)
	(via
		(at 131.661408 -99.986338)
		(size 0.4826)
		(drill 0.254)
		(layers "F.Cu" "B.Cu")
		(net "TP_P3E_CPU1_PE1_RSR3_RXN<13>")
	)
	(segment
		(start 131.948174 -99.490784)
		(end 132.519674 -99.490784)
		(width 0.10795)
		(layer "F.Cu")
		(net "TP_P3E_CPU1_PE1_RSR3_RXN<12>")
	)
	(via
		(at 132.519674 -99.490784)
		(size 0.4826)
		(drill 0.254)
		(layers "F.Cu" "B.Cu")
		(net "TP_P3E_CPU1_PE1_RSR3_RXN<12>")
	)
	(segment
		(start 131.948174 -98.500184)
		(end 132.519674 -98.500184)
		(width 0.10795)
		(layer "F.Cu")
		(net "TP_P3E_CPU1_PE1_RSR3_RXN<11>")
	)
	(via
		(at 132.519674 -98.500184)
		(size 0.4826)
		(drill 0.254)
		(layers "F.Cu" "B.Cu")
		(net "TP_P3E_CPU1_PE1_RSR3_RXN<11>")
	)
	(segment
		(start 133.665214 -98.500184)
		(end 134.236714 -98.500184)
		(width 0.10795)
		(layer "F.Cu")
		(net "TP_P3E_CPU1_PE1_RSR3_RXN<10>")
	)
	(via
		(at 134.236714 -98.500184)
		(size 0.4826)
		(drill 0.254)
		(layers "F.Cu" "B.Cu")
		(net "TP_P3E_CPU1_PE1_RSR3_RXN<10>")
	)
	(segment
		(start 476.64878 -26.925778)
		(end 476.504254 -26.781252)
		(width 0.10795)
		(layer "F.Cu")
		(net "TP_CLK_96M_CKMNG_P")
	)
	(segment
		(start 476.64878 -27.7495)
		(end 476.64878 -26.925778)
		(width 0.10795)
		(layer "F.Cu")
		(net "TP_CLK_96M_CKMNG_P")
	)
	(via
		(at 476.504254 -26.781252)
		(size 0.508)
		(drill 0.254)
		(layers "F.Cu" "B.Cu")
		(net "TP_CLK_96M_CKMNG_P")
	)
	(segment
		(start 477.14916 -26.375614)
		(end 477.14916 -27.7495)
		(width 0.10795)
		(layer "F.Cu")
		(net "TP_CLK_96M_CKMNG_N")
	)
	(segment
		(start 476.852488 -26.078942)
		(end 477.14916 -26.375614)
		(width 0.10795)
		(layer "F.Cu")
		(net "TP_CLK_96M_CKMNG_N")
	)
	(via
		(at 476.852488 -26.078942)
		(size 0.762)
		(drill 0.381)
		(layers "F.Cu" "B.Cu")
		(net "TP_CLK_96M_CKMNG_N")
	)
	(segment
		(start 478.6503 -27.182572)
		(end 478.6503 -27.7495)
		(width 0.10795)
		(layer "F.Cu")
		(net "TP_CLK_100M_R_DP")
	)
	(segment
		(start 478.329752 -26.263346)
		(end 478.329752 -26.862024)
		(width 0.10795)
		(layer "F.Cu")
		(net "TP_CLK_100M_R_DP")
	)
	(segment
		(start 478.162112 -26.095706)
		(end 478.329752 -26.263346)
		(width 0.10795)
		(layer "F.Cu")
		(net "TP_CLK_100M_R_DP")
	)
	(segment
		(start 478.329752 -26.862024)
		(end 478.6503 -27.182572)
		(width 0.10795)
		(layer "F.Cu")
		(net "TP_CLK_100M_R_DP")
	)
	(via
		(at 478.162112 -26.095706)
		(size 0.762)
		(drill 0.381)
		(layers "F.Cu" "B.Cu")
		(net "TP_CLK_100M_R_DP")
	)
	(segment
		(start 479.15068 -27.182318)
		(end 479.15068 -27.7495)
		(width 0.10795)
		(layer "F.Cu")
		(net "TP_CLK_100M_R_DN")
	)
	(segment
		(start 478.815908 -25.688036)
		(end 478.815908 -26.847546)
		(width 0.10795)
		(layer "F.Cu")
		(net "TP_CLK_100M_R_DN")
	)
	(segment
		(start 478.815908 -26.847546)
		(end 479.15068 -27.182318)
		(width 0.10795)
		(layer "F.Cu")
		(net "TP_CLK_100M_R_DN")
	)
	(via
		(at 478.815908 -25.688036)
		(size 0.508)
		(drill 0.254)
		(layers "F.Cu" "B.Cu")
		(net "TP_CLK_100M_R_DN")
	)
	(segment
		(start 388.048754 -85.8647)
		(end 387.934454 -85.979)
		(width 0.10795)
		(layer "F.Cu")
		(net "RMII_BMC_PCH_SPRNGVLLE_RXER")
	)
	(segment
		(start 386.842 -86.7029)
		(end 386.842 -87.3125)
		(width 0.10795)
		(layer "F.Cu")
		(net "RMII_BMC_PCH_SPRNGVLLE_RXER")
	)
	(segment
		(start 387.934454 -85.979)
		(end 386.9055 -85.979)
		(width 0.10795)
		(layer "F.Cu")
		(net "RMII_BMC_PCH_SPRNGVLLE_RXER")
	)
	(segment
		(start 392.14425 -83.34375)
		(end 391.922 -83.34375)
		(width 0.10795)
		(layer "F.Cu")
		(net "RMII_BMC_PCH_SPRNGVLLE_RXER")
	)
	(segment
		(start 390.610344 -84.302854)
		(end 389.048498 -85.8647)
		(width 0.10795)
		(layer "F.Cu")
		(net "RMII_BMC_PCH_SPRNGVLLE_RXER")
	)
	(segment
		(start 393.162028 -81.011268)
		(end 392.52525 -81.648046)
		(width 0.10795)
		(layer "F.Cu")
		(net "RMII_BMC_PCH_SPRNGVLLE_RXER")
	)
	(segment
		(start 389.048498 -85.8647)
		(end 388.048754 -85.8647)
		(width 0.10795)
		(layer "F.Cu")
		(net "RMII_BMC_PCH_SPRNGVLLE_RXER")
	)
	(segment
		(start 390.962896 -84.302854)
		(end 390.610344 -84.302854)
		(width 0.10795)
		(layer "F.Cu")
		(net "RMII_BMC_PCH_SPRNGVLLE_RXER")
	)
	(segment
		(start 386.9055 -86.6394)
		(end 386.842 -86.7029)
		(width 0.10795)
		(layer "F.Cu")
		(net "RMII_BMC_PCH_SPRNGVLLE_RXER")
	)
	(segment
		(start 392.52525 -81.648046)
		(end 392.52525 -82.96275)
		(width 0.10795)
		(layer "F.Cu")
		(net "RMII_BMC_PCH_SPRNGVLLE_RXER")
	)
	(segment
		(start 392.52525 -82.96275)
		(end 392.14425 -83.34375)
		(width 0.10795)
		(layer "F.Cu")
		(net "RMII_BMC_PCH_SPRNGVLLE_RXER")
	)
	(segment
		(start 391.922 -83.34375)
		(end 390.962896 -84.302854)
		(width 0.10795)
		(layer "F.Cu")
		(net "RMII_BMC_PCH_SPRNGVLLE_RXER")
	)
	(segment
		(start 386.9055 -85.979)
		(end 386.9055 -86.6394)
		(width 0.10795)
		(layer "F.Cu")
		(net "RMII_BMC_PCH_SPRNGVLLE_RXER")
	)
	(segment
		(start 410.290264 -30.53461)
		(end 409.890214 -30.13456)
		(width 0.10795)
		(layer "F.Cu")
		(net "RMII_BMC_PCH_SPRNGVLLE_RXER")
	)
	(via
		(at 393.162028 -81.011268)
		(size 0.508)
		(drill 0.254)
		(layers "F.Cu" "B.Cu")
		(net "RMII_BMC_PCH_SPRNGVLLE_RXER")
	)
	(via
		(at 409.890214 -30.13456)
		(size 0.4572)
		(drill 0.2032)
		(layers "F.Cu" "B.Cu")
		(net "RMII_BMC_PCH_SPRNGVLLE_RXER")
	)
	(via
		(at 374.1674 -32.7533)
		(size 0.508)
		(drill 0.254)
		(layers "F.Cu" "B.Cu")
		(net "RMII_BMC_PCH_SPRNGVLLE_RXER")
	)
	(segment
		(start 375.679462 -32.7533)
		(end 374.1674 -32.7533)
		(width 0.089408)
		(layer "In4.Cu")
		(net "RMII_BMC_PCH_SPRNGVLLE_RXER")
	)
	(segment
		(start 389.577326 -32.323532)
		(end 386.691632 -32.323532)
		(width 0.089408)
		(layer "In4.Cu")
		(net "RMII_BMC_PCH_SPRNGVLLE_RXER")
	)
	(segment
		(start 409.890214 -30.13456)
		(end 409.515564 -29.75991)
		(width 0.089408)
		(layer "In4.Cu")
		(net "RMII_BMC_PCH_SPRNGVLLE_RXER")
	)
	(segment
		(start 402.112226 -30.346396)
		(end 401.473416 -29.707586)
		(width 0.089408)
		(layer "In4.Cu")
		(net "RMII_BMC_PCH_SPRNGVLLE_RXER")
	)
	(segment
		(start 405.7142 -31.082488)
		(end 404.978108 -30.346396)
		(width 0.089408)
		(layer "In4.Cu")
		(net "RMII_BMC_PCH_SPRNGVLLE_RXER")
	)
	(segment
		(start 385.686046 -31.317946)
		(end 383.585974 -31.317946)
		(width 0.089408)
		(layer "In4.Cu")
		(net "RMII_BMC_PCH_SPRNGVLLE_RXER")
	)
	(segment
		(start 386.691632 -32.323532)
		(end 385.686046 -31.317946)
		(width 0.089408)
		(layer "In4.Cu")
		(net "RMII_BMC_PCH_SPRNGVLLE_RXER")
	)
	(segment
		(start 392.068812 -32.466788)
		(end 389.720582 -32.466788)
		(width 0.089408)
		(layer "In4.Cu")
		(net "RMII_BMC_PCH_SPRNGVLLE_RXER")
	)
	(segment
		(start 406.202642 -31.082488)
		(end 405.7142 -31.082488)
		(width 0.089408)
		(layer "In4.Cu")
		(net "RMII_BMC_PCH_SPRNGVLLE_RXER")
	)
	(segment
		(start 394.828014 -29.707586)
		(end 392.068812 -32.466788)
		(width 0.089408)
		(layer "In4.Cu")
		(net "RMII_BMC_PCH_SPRNGVLLE_RXER")
	)
	(segment
		(start 383.585974 -31.317946)
		(end 382.131316 -32.772604)
		(width 0.089408)
		(layer "In4.Cu")
		(net "RMII_BMC_PCH_SPRNGVLLE_RXER")
	)
	(segment
		(start 404.978108 -30.346396)
		(end 402.112226 -30.346396)
		(width 0.089408)
		(layer "In4.Cu")
		(net "RMII_BMC_PCH_SPRNGVLLE_RXER")
	)
	(segment
		(start 389.720582 -32.466788)
		(end 389.577326 -32.323532)
		(width 0.089408)
		(layer "In4.Cu")
		(net "RMII_BMC_PCH_SPRNGVLLE_RXER")
	)
	(segment
		(start 380.957074 -32.772604)
		(end 380.352554 -32.168084)
		(width 0.089408)
		(layer "In4.Cu")
		(net "RMII_BMC_PCH_SPRNGVLLE_RXER")
	)
	(segment
		(start 376.264678 -32.168084)
		(end 375.679462 -32.7533)
		(width 0.089408)
		(layer "In4.Cu")
		(net "RMII_BMC_PCH_SPRNGVLLE_RXER")
	)
	(segment
		(start 409.515564 -29.75991)
		(end 407.52522 -29.75991)
		(width 0.089408)
		(layer "In4.Cu")
		(net "RMII_BMC_PCH_SPRNGVLLE_RXER")
	)
	(segment
		(start 382.131316 -32.772604)
		(end 380.957074 -32.772604)
		(width 0.089408)
		(layer "In4.Cu")
		(net "RMII_BMC_PCH_SPRNGVLLE_RXER")
	)
	(segment
		(start 407.52522 -29.75991)
		(end 406.202642 -31.082488)
		(width 0.089408)
		(layer "In4.Cu")
		(net "RMII_BMC_PCH_SPRNGVLLE_RXER")
	)
	(segment
		(start 401.473416 -29.707586)
		(end 394.828014 -29.707586)
		(width 0.089408)
		(layer "In4.Cu")
		(net "RMII_BMC_PCH_SPRNGVLLE_RXER")
	)
	(segment
		(start 380.352554 -32.168084)
		(end 376.264678 -32.168084)
		(width 0.089408)
		(layer "In4.Cu")
		(net "RMII_BMC_PCH_SPRNGVLLE_RXER")
	)
	(segment
		(start 391.674858 -79.524098)
		(end 391.674858 -70.475094)
		(width 0.089408)
		(layer "In11.Cu")
		(net "RMII_BMC_PCH_SPRNGVLLE_RXER")
	)
	(segment
		(start 386.258816 -52.982622)
		(end 386.258816 -51.200304)
		(width 0.089408)
		(layer "In11.Cu")
		(net "RMII_BMC_PCH_SPRNGVLLE_RXER")
	)
	(segment
		(start 373.714772 -32.984948)
		(end 373.94642 -32.7533)
		(width 0.089408)
		(layer "In11.Cu")
		(net "RMII_BMC_PCH_SPRNGVLLE_RXER")
	)
	(segment
		(start 386.258816 -51.200304)
		(end 384.93192 -49.873408)
		(width 0.089408)
		(layer "In11.Cu")
		(net "RMII_BMC_PCH_SPRNGVLLE_RXER")
	)
	(segment
		(start 378.405136 -48.497236)
		(end 376.387868 -46.479968)
		(width 0.089408)
		(layer "In11.Cu")
		(net "RMII_BMC_PCH_SPRNGVLLE_RXER")
	)
	(segment
		(start 373.714772 -34.254186)
		(end 373.714772 -32.984948)
		(width 0.089408)
		(layer "In11.Cu")
		(net "RMII_BMC_PCH_SPRNGVLLE_RXER")
	)
	(segment
		(start 376.387868 -43.400726)
		(end 376.388122 -43.400472)
		(width 0.089408)
		(layer "In11.Cu")
		(net "RMII_BMC_PCH_SPRNGVLLE_RXER")
	)
	(segment
		(start 375.981214 -36.520628)
		(end 373.714772 -34.254186)
		(width 0.089408)
		(layer "In11.Cu")
		(net "RMII_BMC_PCH_SPRNGVLLE_RXER")
	)
	(segment
		(start 389.80491 -60.702952)
		(end 389.80491 -56.528716)
		(width 0.089408)
		(layer "In11.Cu")
		(net "RMII_BMC_PCH_SPRNGVLLE_RXER")
	)
	(segment
		(start 381.42418 -48.497236)
		(end 378.405136 -48.497236)
		(width 0.089408)
		(layer "In11.Cu")
		(net "RMII_BMC_PCH_SPRNGVLLE_RXER")
	)
	(segment
		(start 390.19988 -61.097922)
		(end 389.80491 -60.702952)
		(width 0.089408)
		(layer "In11.Cu")
		(net "RMII_BMC_PCH_SPRNGVLLE_RXER")
	)
	(segment
		(start 376.388122 -43.400472)
		(end 376.388122 -43.158156)
		(width 0.089408)
		(layer "In11.Cu")
		(net "RMII_BMC_PCH_SPRNGVLLE_RXER")
	)
	(segment
		(start 390.19988 -69.000116)
		(end 390.19988 -61.097922)
		(width 0.089408)
		(layer "In11.Cu")
		(net "RMII_BMC_PCH_SPRNGVLLE_RXER")
	)
	(segment
		(start 389.80491 -56.528716)
		(end 386.258816 -52.982622)
		(width 0.089408)
		(layer "In11.Cu")
		(net "RMII_BMC_PCH_SPRNGVLLE_RXER")
	)
	(segment
		(start 391.674858 -70.475094)
		(end 390.19988 -69.000116)
		(width 0.089408)
		(layer "In11.Cu")
		(net "RMII_BMC_PCH_SPRNGVLLE_RXER")
	)
	(segment
		(start 376.387868 -46.479968)
		(end 376.387868 -43.400726)
		(width 0.089408)
		(layer "In11.Cu")
		(net "RMII_BMC_PCH_SPRNGVLLE_RXER")
	)
	(segment
		(start 384.93192 -49.873408)
		(end 382.800352 -49.873408)
		(width 0.089408)
		(layer "In11.Cu")
		(net "RMII_BMC_PCH_SPRNGVLLE_RXER")
	)
	(segment
		(start 373.94642 -32.7533)
		(end 374.1674 -32.7533)
		(width 0.089408)
		(layer "In11.Cu")
		(net "RMII_BMC_PCH_SPRNGVLLE_RXER")
	)
	(segment
		(start 376.388122 -43.158156)
		(end 375.981214 -42.751248)
		(width 0.089408)
		(layer "In11.Cu")
		(net "RMII_BMC_PCH_SPRNGVLLE_RXER")
	)
	(segment
		(start 375.981214 -42.751248)
		(end 375.981214 -36.520628)
		(width 0.089408)
		(layer "In11.Cu")
		(net "RMII_BMC_PCH_SPRNGVLLE_RXER")
	)
	(segment
		(start 382.800352 -49.873408)
		(end 381.42418 -48.497236)
		(width 0.089408)
		(layer "In11.Cu")
		(net "RMII_BMC_PCH_SPRNGVLLE_RXER")
	)
	(segment
		(start 393.162028 -81.011268)
		(end 391.674858 -79.524098)
		(width 0.089408)
		(layer "In11.Cu")
		(net "RMII_BMC_PCH_SPRNGVLLE_RXER")
	)
	(segment
		(start 489.2294 -38.8874)
		(end 489.458 -38.6588)
		(width 0.10795)
		(layer "F.Cu")
		(net "PU_SPRV_LAN_PWR_GOOD")
	)
	(segment
		(start 489.8136 -39.0144)
		(end 490.601 -39.0144)
		(width 0.10795)
		(layer "F.Cu")
		(net "PU_SPRV_LAN_PWR_GOOD")
	)
	(segment
		(start 488.6198 -39.5732)
		(end 489.2294 -38.9636)
		(width 0.10795)
		(layer "F.Cu")
		(net "PU_SPRV_LAN_PWR_GOOD")
	)
	(segment
		(start 488.6198 -40.217344)
		(end 488.6198 -39.5732)
		(width 0.10795)
		(layer "F.Cu")
		(net "PU_SPRV_LAN_PWR_GOOD")
	)
	(segment
		(start 489.2294 -38.9636)
		(end 489.2294 -38.8874)
		(width 0.10795)
		(layer "F.Cu")
		(net "PU_SPRV_LAN_PWR_GOOD")
	)
	(segment
		(start 489.458 -38.6588)
		(end 489.8136 -39.0144)
		(width 0.10795)
		(layer "F.Cu")
		(net "PU_SPRV_LAN_PWR_GOOD")
	)
	(via
		(at 489.458 -38.6588)
		(size 0.508)
		(drill 0.254)
		(layers "F.Cu" "B.Cu")
		(net "PU_SPRV_LAN_PWR_GOOD")
	)
	(via
		(at 490.1692 -38.5826)
		(size 0.6604)
		(drill 0.3302)
		(layers "F.Cu" "B.Cu")
		(net "PU_SPRV_LAN_PWR_GOOD")
	)
	(segment
		(start 489.458 -38.6588)
		(end 489.5342 -38.5826)
		(width 0.10795)
		(layer "B.Cu")
		(net "PU_SPRV_LAN_PWR_GOOD")
	)
	(segment
		(start 489.5342 -38.5826)
		(end 490.1692 -38.5826)
		(width 0.10795)
		(layer "B.Cu")
		(net "PU_SPRV_LAN_PWR_GOOD")
	)
	(via
		(at 486.83164 -17.79778)
		(size 0.6604)
		(drill 0.3302)
		(layers "F.Cu" "B.Cu")
		(net "PU_NV_WP_N")
	)
	(segment
		(start 487.807 -18.593054)
		(end 487.807 -18.161)
		(width 0.10795)
		(layer "B.Cu")
		(net "PU_NV_WP_N")
	)
	(segment
		(start 488.538266 -18.82775)
		(end 488.430316 -18.7198)
		(width 0.10795)
		(layer "B.Cu")
		(net "PU_NV_WP_N")
	)
	(segment
		(start 487.933746 -18.7198)
		(end 487.807 -18.593054)
		(width 0.10795)
		(layer "B.Cu")
		(net "PU_NV_WP_N")
	)
	(segment
		(start 487.807 -18.161)
		(end 487.19486 -18.161)
		(width 0.10795)
		(layer "B.Cu")
		(net "PU_NV_WP_N")
	)
	(segment
		(start 487.19486 -18.161)
		(end 486.83164 -17.79778)
		(width 0.10795)
		(layer "B.Cu")
		(net "PU_NV_WP_N")
	)
	(segment
		(start 488.538266 -20.00758)
		(end 488.538266 -18.82775)
		(width 0.10795)
		(layer "B.Cu")
		(net "PU_NV_WP_N")
	)
	(segment
		(start 488.430316 -18.7198)
		(end 487.933746 -18.7198)
		(width 0.10795)
		(layer "B.Cu")
		(net "PU_NV_WP_N")
	)
	(via
		(at 490.22 -29.110432)
		(size 0.6604)
		(drill 0.3302)
		(layers "F.Cu" "B.Cu")
		(net "PU_NV_HOLD_N")
	)
	(segment
		(start 489.808266 -27.245564)
		(end 488.98429 -28.06954)
		(width 0.10795)
		(layer "B.Cu")
		(net "PU_NV_HOLD_N")
	)
	(segment
		(start 489.532168 -28.4226)
		(end 490.22 -29.110432)
		(width 0.10795)
		(layer "B.Cu")
		(net "PU_NV_HOLD_N")
	)
	(segment
		(start 488.98429 -28.4226)
		(end 489.532168 -28.4226)
		(width 0.10795)
		(layer "B.Cu")
		(net "PU_NV_HOLD_N")
	)
	(segment
		(start 488.98429 -28.06954)
		(end 488.98429 -28.4226)
		(width 0.10795)
		(layer "B.Cu")
		(net "PU_NV_HOLD_N")
	)
	(segment
		(start 489.808266 -26.76398)
		(end 489.808266 -27.245564)
		(width 0.10795)
		(layer "B.Cu")
		(net "PU_NV_HOLD_N")
	)
	(segment
		(start 478.4852 -39.8018)
		(end 478.271332 -40.015668)
		(width 0.10795)
		(layer "F.Cu")
		(net "PD_SPRV_RSET")
	)
	(segment
		(start 478.271332 -40.127936)
		(end 478.1931 -40.206168)
		(width 0.10795)
		(layer "F.Cu")
		(net "PD_SPRV_RSET")
	)
	(segment
		(start 479.044 -39.8018)
		(end 478.4852 -39.8018)
		(width 0.10795)
		(layer "F.Cu")
		(net "PD_SPRV_RSET")
	)
	(segment
		(start 478.271332 -40.015668)
		(end 478.271332 -40.127936)
		(width 0.10795)
		(layer "F.Cu")
		(net "PD_SPRV_RSET")
	)
	(segment
		(start 479.4504 -40.217344)
		(end 479.4504 -40.2082)
		(width 0.10795)
		(layer "F.Cu")
		(net "PD_SPRV_RSET")
	)
	(segment
		(start 479.8822 -40.217344)
		(end 479.4504 -40.217344)
		(width 0.10795)
		(layer "F.Cu")
		(net "PD_SPRV_RSET")
	)
	(segment
		(start 479.4504 -40.2082)
		(end 479.044 -39.8018)
		(width 0.10795)
		(layer "F.Cu")
		(net "PD_SPRV_RSET")
	)
	(segment
		(start 478.1931 -40.206168)
		(end 478.1931 -40.4114)
		(width 0.10795)
		(layer "F.Cu")
		(net "PD_SPRV_RSET")
	)
	(via
		(at 479.044 -39.8018)
		(size 0.508)
		(drill 0.254)
		(layers "F.Cu" "B.Cu")
		(net "PD_SPRV_RSET")
	)
	(segment
		(start 478.14992 -27.146504)
		(end 477.81591 -26.812494)
		(width 0.10795)
		(layer "F.Cu")
		(net "PD_CKMNG_OE")
	)
	(segment
		(start 478.14992 -27.7495)
		(end 478.14992 -27.146504)
		(width 0.10795)
		(layer "F.Cu")
		(net "PD_CKMNG_OE")
	)
	(segment
		(start 477.81591 -26.812494)
		(end 477.64954 -26.978864)
		(width 0.10795)
		(layer "F.Cu")
		(net "PD_CKMNG_OE")
	)
	(segment
		(start 477.64954 -26.978864)
		(end 477.64954 -27.7495)
		(width 0.10795)
		(layer "F.Cu")
		(net "PD_CKMNG_OE")
	)
	(via
		(at 477.81591 -26.812494)
		(size 0.508)
		(drill 0.254)
		(layers "F.Cu" "B.Cu")
		(net "PD_CKMNG_OE")
	)
	(segment
		(start 477.81591 -26.812494)
		(end 477.81591 -26.819098)
		(width 0.10795)
		(layer "B.Cu")
		(net "PD_CKMNG_OE")
	)
	(segment
		(start 477.81591 -26.819098)
		(end 477.84766 -26.850848)
		(width 0.10795)
		(layer "B.Cu")
		(net "PD_CKMNG_OE")
	)
	(segment
		(start 477.84766 -26.850848)
		(end 477.84766 -27.70632)
		(width 0.10795)
		(layer "B.Cu")
		(net "PD_CKMNG_OE")
	)
	(segment
		(start 477.766634 -35.033966)
		(end 477.734376 -35.066224)
		(width 0.254)
		(layer "F.Cu")
		(net "P3V3_STBY_MNG_RMII")
	)
	(segment
		(start 474.7895 -33.257744)
		(end 474.7895 -33.11144)
		(width 0.254)
		(layer "F.Cu")
		(net "P3V3_STBY_MNG_RMII")
	)
	(segment
		(start 474.937836 -34.109914)
		(end 474.937836 -33.40608)
		(width 0.254)
		(layer "F.Cu")
		(net "P3V3_STBY_MNG_RMII")
	)
	(segment
		(start 477.734376 -35.09899)
		(end 477.300544 -35.532822)
		(width 0.254)
		(layer "F.Cu")
		(net "P3V3_STBY_MNG_RMII")
	)
	(segment
		(start 474.654626 -34.393124)
		(end 474.937836 -34.109914)
		(width 0.254)
		(layer "F.Cu")
		(net "P3V3_STBY_MNG_RMII")
	)
	(segment
		(start 474.28912 -34.393124)
		(end 474.654626 -34.393124)
		(width 0.254)
		(layer "F.Cu")
		(net "P3V3_STBY_MNG_RMII")
	)
	(segment
		(start 477.734376 -35.066224)
		(end 477.734376 -35.09899)
		(width 0.254)
		(layer "F.Cu")
		(net "P3V3_STBY_MNG_RMII")
	)
	(segment
		(start 477.300544 -35.532822)
		(end 477.203262 -35.532822)
		(width 0.254)
		(layer "F.Cu")
		(net "P3V3_STBY_MNG_RMII")
	)
	(segment
		(start 477.64954 -33.9725)
		(end 477.64954 -34.557208)
		(width 0.254)
		(layer "F.Cu")
		(net "P3V3_STBY_MNG_RMII")
	)
	(segment
		(start 477.64954 -34.557208)
		(end 477.766634 -34.674302)
		(width 0.254)
		(layer "F.Cu")
		(net "P3V3_STBY_MNG_RMII")
	)
	(segment
		(start 477.766634 -34.674302)
		(end 477.766634 -35.033966)
		(width 0.254)
		(layer "F.Cu")
		(net "P3V3_STBY_MNG_RMII")
	)
	(segment
		(start 474.937836 -33.40608)
		(end 474.7895 -33.257744)
		(width 0.254)
		(layer "F.Cu")
		(net "P3V3_STBY_MNG_RMII")
	)
	(via
		(at 477.203262 -35.532822)
		(size 0.508)
		(drill 0.254)
		(layers "F.Cu" "B.Cu")
		(net "P3V3_STBY_MNG_RMII")
	)
	(via
		(at 474.3196 -35.3187)
		(size 0.6604)
		(drill 0.3302)
		(layers "F.Cu" "B.Cu")
		(net "P3V3_STBY_MNG_RMII")
	)
	(via
		(at 474.28912 -34.393124)
		(size 0.508)
		(drill 0.254)
		(layers "F.Cu" "B.Cu")
		(net "P3V3_STBY_MNG_RMII")
	)
	(segment
		(start 472.1606 -33.146238)
		(end 472.17838 -33.128458)
		(width 0.254)
		(layer "F.Cu")
		(net "P3V3_STBY_MNG_RGMII")
	)
	(segment
		(start 472.927934 -32.575246)
		(end 473.856558 -31.646622)
		(width 0.254)
		(layer "F.Cu")
		(net "P3V3_STBY_MNG_RGMII")
	)
	(segment
		(start 473.856558 -31.6103)
		(end 474.7895 -31.6103)
		(width 0.254)
		(layer "F.Cu")
		(net "P3V3_STBY_MNG_RGMII")
	)
	(segment
		(start 472.1606 -34.01822)
		(end 472.1606 -33.146238)
		(width 0.254)
		(layer "F.Cu")
		(net "P3V3_STBY_MNG_RGMII")
	)
	(segment
		(start 472.17838 -33.128458)
		(end 472.17838 -33.043368)
		(width 0.254)
		(layer "F.Cu")
		(net "P3V3_STBY_MNG_RGMII")
	)
	(segment
		(start 472.646502 -32.575246)
		(end 472.927934 -32.575246)
		(width 0.254)
		(layer "F.Cu")
		(net "P3V3_STBY_MNG_RGMII")
	)
	(segment
		(start 473.856558 -31.646622)
		(end 473.856558 -31.6103)
		(width 0.254)
		(layer "F.Cu")
		(net "P3V3_STBY_MNG_RGMII")
	)
	(segment
		(start 471.83548 -34.34334)
		(end 472.1606 -34.01822)
		(width 0.254)
		(layer "F.Cu")
		(net "P3V3_STBY_MNG_RGMII")
	)
	(segment
		(start 472.17838 -33.043368)
		(end 472.646502 -32.575246)
		(width 0.254)
		(layer "F.Cu")
		(net "P3V3_STBY_MNG_RGMII")
	)
	(via
		(at 471.83548 -34.34334)
		(size 0.762)
		(drill 0.381)
		(layers "F.Cu" "B.Cu")
		(net "P3V3_STBY_MNG_RGMII")
	)
	(via
		(at 473.856558 -31.6103)
		(size 0.508)
		(drill 0.254)
		(layers "F.Cu" "B.Cu")
		(net "P3V3_STBY_MNG_RGMII")
	)
	(segment
		(start 479.65106 -27.7495)
		(end 479.65106 -27.009598)
		(width 0.10795)
		(layer "F.Cu")
		(net "P3V3_STBY_MNG_CPU")
	)
	(segment
		(start 479.65106 -27.009598)
		(end 479.424238 -26.782776)
		(width 0.10795)
		(layer "F.Cu")
		(net "P3V3_STBY_MNG_CPU")
	)
	(via
		(at 479.424238 -26.782776)
		(size 0.508)
		(drill 0.254)
		(layers "F.Cu" "B.Cu")
		(net "P3V3_STBY_MNG_CPU")
	)
	(segment
		(start 476.1484 -27.7495)
		(end 476.1484 -27.116024)
		(width 0.2032)
		(layer "F.Cu")
		(net "P3V3_STBY_MNG")
	)
	(segment
		(start 476.059754 -26.213562)
		(end 476.061532 -26.211784)
		(width 0.2032)
		(layer "F.Cu")
		(net "P3V3_STBY_MNG")
	)
	(segment
		(start 476.059754 -26.561034)
		(end 476.059754 -26.213562)
		(width 0.2032)
		(layer "F.Cu")
		(net "P3V3_STBY_MNG")
	)
	(segment
		(start 479.15068 -33.9725)
		(end 479.15068 -35.0012)
		(width 0.254)
		(layer "F.Cu")
		(net "P3V3_STBY_MNG")
	)
	(segment
		(start 478.9678 -35.18408)
		(end 478.9678 -35.8648)
		(width 0.254)
		(layer "F.Cu")
		(net "P3V3_STBY_MNG")
	)
	(segment
		(start 476.1484 -27.116024)
		(end 476.034354 -27.001978)
		(width 0.2032)
		(layer "F.Cu")
		(net "P3V3_STBY_MNG")
	)
	(segment
		(start 476.034354 -26.586434)
		(end 476.059754 -26.561034)
		(width 0.2032)
		(layer "F.Cu")
		(net "P3V3_STBY_MNG")
	)
	(segment
		(start 479.15068 -35.0012)
		(end 478.9678 -35.18408)
		(width 0.254)
		(layer "F.Cu")
		(net "P3V3_STBY_MNG")
	)
	(segment
		(start 481.974144 -30.60954)
		(end 481.0125 -30.60954)
		(width 0.254)
		(layer "F.Cu")
		(net "P3V3_STBY_MNG")
	)
	(segment
		(start 481.974144 -29.1084)
		(end 481.0125 -29.1084)
		(width 0.254)
		(layer "F.Cu")
		(net "P3V3_STBY_MNG")
	)
	(segment
		(start 476.034354 -27.001978)
		(end 476.034354 -26.586434)
		(width 0.2032)
		(layer "F.Cu")
		(net "P3V3_STBY_MNG")
	)
	(via
		(at 481.974144 -29.1084)
		(size 0.508)
		(drill 0.254)
		(layers "F.Cu" "B.Cu")
		(net "P3V3_STBY_MNG")
	)
	(via
		(at 478.9678 -35.8648)
		(size 0.508)
		(drill 0.254)
		(layers "F.Cu" "B.Cu")
		(net "P3V3_STBY_MNG")
	)
	(via
		(at 481.974144 -30.60954)
		(size 0.508)
		(drill 0.254)
		(layers "F.Cu" "B.Cu")
		(net "P3V3_STBY_MNG")
	)
	(via
		(at 474.686376 -26.19502)
		(size 0.6604)
		(drill 0.3302)
		(layers "F.Cu" "B.Cu")
		(net "P3V3_STBY_MNG")
	)
	(via
		(at 476.061532 -26.211784)
		(size 0.508)
		(drill 0.254)
		(layers "F.Cu" "B.Cu")
		(net "P3V3_STBY_MNG")
	)
	(via
		(at 480.568 -32.131)
		(size 0.6604)
		(drill 0.3302)
		(layers "F.Cu" "B.Cu")
		(net "P3V3_STBY_MNG")
	)
	(segment
		(start 137.670794 -97.509584)
		(end 137.099294 -97.509584)
		(width 0.1143)
		(layer "F.Cu")
		(net "P3E_CPU1_PE3_MP_TXP<7>")
	)
	(segment
		(start 14.7828 -36.576)
		(end 15.10665 -36.25215)
		(width 0.1143)
		(layer "F.Cu")
		(net "P3E_CPU1_PE3_MP_TXP<7>")
	)
	(segment
		(start 15.336774 -36.25215)
		(end 15.451074 -36.36645)
		(width 0.1143)
		(layer "F.Cu")
		(net "P3E_CPU1_PE3_MP_TXP<7>")
	)
	(segment
		(start 15.451074 -36.36645)
		(end 15.451074 -36.7665)
		(width 0.1143)
		(layer "F.Cu")
		(net "P3E_CPU1_PE3_MP_TXP<7>")
	)
	(segment
		(start 15.10665 -36.25215)
		(end 15.336774 -36.25215)
		(width 0.1143)
		(layer "F.Cu")
		(net "P3E_CPU1_PE3_MP_TXP<7>")
	)
	(via
		(at 15.451074 -36.7665)
		(size 0.508)
		(drill 0.254)
		(layers "F.Cu" "B.Cu")
		(net "P3E_CPU1_PE3_MP_TXP<7>")
	)
	(via
		(at 137.670794 -97.509584)
		(size 0.508)
		(drill 0.254)
		(layers "F.Cu" "B.Cu")
		(net "P3E_CPU1_PE3_MP_TXP<7>")
	)
	(segment
		(start 17.581118 -35.79368)
		(end 18.95221 -35.79368)
		(width 0.1143)
		(layer "In9.Cu")
		(net "P3E_CPU1_PE3_MP_TXP<7>")
	)
	(segment
		(start 37.912548 -38.19906)
		(end 38.121844 -38.095682)
		(width 0.1143)
		(layer "In9.Cu")
		(net "P3E_CPU1_PE3_MP_TXP<7>")
	)
	(segment
		(start 130.652012 -108.221018)
		(end 133.112002 -108.221018)
		(width 0.1143)
		(layer "In9.Cu")
		(net "P3E_CPU1_PE3_MP_TXP<7>")
	)
	(segment
		(start 61.277754 -59.726068)
		(end 61.2775 -59.726068)
		(width 0.1143)
		(layer "In9.Cu")
		(net "P3E_CPU1_PE3_MP_TXP<7>")
	)
	(segment
		(start 18.95221 -35.79368)
		(end 24.519382 -33.547558)
		(width 0.1143)
		(layer "In9.Cu")
		(net "P3E_CPU1_PE3_MP_TXP<7>")
	)
	(segment
		(start 32.754316 -36.276534)
		(end 32.857694 -36.486084)
		(width 0.1143)
		(layer "In9.Cu")
		(net "P3E_CPU1_PE3_MP_TXP<7>")
	)
	(segment
		(start 137.377678 -97.678748)
		(end 137.670794 -97.509584)
		(width 0.0889)
		(layer "In9.Cu")
		(net "P3E_CPU1_PE3_MP_TXP<7>")
	)
	(segment
		(start 138.128248 -103.864156)
		(end 138.128248 -101.98862)
		(width 0.0889)
		(layer "In9.Cu")
		(net "P3E_CPU1_PE3_MP_TXP<7>")
	)
	(segment
		(start 37.484558 -37.879782)
		(end 37.587936 -38.089078)
		(width 0.1143)
		(layer "In9.Cu")
		(net "P3E_CPU1_PE3_MP_TXP<7>")
	)
	(segment
		(start 37.587936 -38.089078)
		(end 37.912548 -38.19906)
		(width 0.1143)
		(layer "In9.Cu")
		(net "P3E_CPU1_PE3_MP_TXP<7>")
	)
	(segment
		(start 34.144458 -36.922202)
		(end 34.354008 -36.818824)
		(width 0.1143)
		(layer "In9.Cu")
		(net "P3E_CPU1_PE3_MP_TXP<7>")
	)
	(segment
		(start 62.922658 -77.216)
		(end 60.409582 -89.782142)
		(width 0.1143)
		(layer "In9.Cu")
		(net "P3E_CPU1_PE3_MP_TXP<7>")
	)
	(segment
		(start 39.08425 -38.421818)
		(end 39.408862 -38.5318)
		(width 0.1143)
		(layer "In9.Cu")
		(net "P3E_CPU1_PE3_MP_TXP<7>")
	)
	(segment
		(start 41.33342 -39.184072)
		(end 54.742588 -48.130206)
		(width 0.1143)
		(layer "In9.Cu")
		(net "P3E_CPU1_PE3_MP_TXP<7>")
	)
	(segment
		(start 39.837106 -38.851332)
		(end 40.046402 -38.747954)
		(width 0.1143)
		(layer "In9.Cu")
		(net "P3E_CPU1_PE3_MP_TXP<7>")
	)
	(segment
		(start 97.981262 -108.08462)
		(end 106.6927 -109.82706)
		(width 0.1143)
		(layer "In9.Cu")
		(net "P3E_CPU1_PE3_MP_TXP<7>")
	)
	(segment
		(start 40.799258 -39.177468)
		(end 41.008554 -39.07409)
		(width 0.1143)
		(layer "In9.Cu")
		(net "P3E_CPU1_PE3_MP_TXP<7>")
	)
	(segment
		(start 114.722656 -110.216442)
		(end 127.674878 -107.625642)
		(width 0.1143)
		(layer "In9.Cu")
		(net "P3E_CPU1_PE3_MP_TXP<7>")
	)
	(segment
		(start 15.451074 -36.406328)
		(end 15.57401 -36.283392)
		(width 0.1143)
		(layer "In9.Cu")
		(net "P3E_CPU1_PE3_MP_TXP<7>")
	)
	(segment
		(start 38.44671 -38.205664)
		(end 38.550088 -38.415214)
		(width 0.1143)
		(layer "In9.Cu")
		(net "P3E_CPU1_PE3_MP_TXP<7>")
	)
	(segment
		(start 40.474646 -39.067232)
		(end 40.799258 -39.177468)
		(width 0.1143)
		(layer "In9.Cu")
		(net "P3E_CPU1_PE3_MP_TXP<7>")
	)
	(segment
		(start 138.182604 -100.776786)
		(end 138.188954 -100.766118)
		(width 0.0889)
		(layer "In9.Cu")
		(net "P3E_CPU1_PE3_MP_TXP<7>")
	)
	(segment
		(start 15.451074 -36.7665)
		(end 15.451074 -36.406328)
		(width 0.1143)
		(layer "In9.Cu")
		(net "P3E_CPU1_PE3_MP_TXP<7>")
	)
	(segment
		(start 32.42945 -36.166552)
		(end 32.754316 -36.276534)
		(width 0.1143)
		(layer "In9.Cu")
		(net "P3E_CPU1_PE3_MP_TXP<7>")
	)
	(segment
		(start 137.324084 -98.300286)
		(end 137.330434 -98.289618)
		(width 0.0889)
		(layer "In9.Cu")
		(net "P3E_CPU1_PE3_MP_TXP<7>")
	)
	(segment
		(start 38.8747 -38.525196)
		(end 39.08425 -38.421818)
		(width 0.1143)
		(layer "In9.Cu")
		(net "P3E_CPU1_PE3_MP_TXP<7>")
	)
	(segment
		(start 137.319258 -98.308922)
		(end 137.324084 -98.300286)
		(width 0.0889)
		(layer "In9.Cu")
		(net "P3E_CPU1_PE3_MP_TXP<7>")
	)
	(segment
		(start 41.008554 -39.07409)
		(end 41.33342 -39.184072)
		(width 0.1143)
		(layer "In9.Cu")
		(net "P3E_CPU1_PE3_MP_TXP<7>")
	)
	(segment
		(start 137.688574 -98.900234)
		(end 137.655808 -98.900234)
		(width 0.0889)
		(layer "In9.Cu")
		(net "P3E_CPU1_PE3_MP_TXP<7>")
	)
	(segment
		(start 34.354008 -36.818824)
		(end 37.484558 -37.879782)
		(width 0.1143)
		(layer "In9.Cu")
		(net "P3E_CPU1_PE3_MP_TXP<7>")
	)
	(segment
		(start 33.819846 -36.811966)
		(end 34.144458 -36.922202)
		(width 0.1143)
		(layer "In9.Cu")
		(net "P3E_CPU1_PE3_MP_TXP<7>")
	)
	(segment
		(start 33.391602 -36.492688)
		(end 33.716468 -36.60267)
		(width 0.1143)
		(layer "In9.Cu")
		(net "P3E_CPU1_PE3_MP_TXP<7>")
	)
	(segment
		(start 32.857694 -36.486084)
		(end 33.182306 -36.596066)
		(width 0.1143)
		(layer "In9.Cu")
		(net "P3E_CPU1_PE3_MP_TXP<7>")
	)
	(segment
		(start 106.6927 -109.82706)
		(end 109.733588 -109.218476)
		(width 0.1143)
		(layer "In9.Cu")
		(net "P3E_CPU1_PE3_MP_TXP<7>")
	)
	(segment
		(start 61.2775 -59.726068)
		(end 60.350908 -64.358774)
		(width 0.1143)
		(layer "In9.Cu")
		(net "P3E_CPU1_PE3_MP_TXP<7>")
	)
	(segment
		(start 127.674878 -107.625642)
		(end 130.652012 -108.221018)
		(width 0.1143)
		(layer "In9.Cu")
		(net "P3E_CPU1_PE3_MP_TXP<7>")
	)
	(segment
		(start 109.733588 -109.218476)
		(end 114.722656 -110.216442)
		(width 0.1143)
		(layer "In9.Cu")
		(net "P3E_CPU1_PE3_MP_TXP<7>")
	)
	(segment
		(start 138.182604 -100.186236)
		(end 138.177778 -100.1776)
		(width 0.0889)
		(layer "In9.Cu")
		(net "P3E_CPU1_PE3_MP_TXP<7>")
	)
	(segment
		(start 60.350908 -64.358774)
		(end 62.922658 -77.216)
		(width 0.1143)
		(layer "In9.Cu")
		(net "P3E_CPU1_PE3_MP_TXP<7>")
	)
	(segment
		(start 133.1341 -108.221018)
		(end 133.1849 -108.170218)
		(width 0.0889)
		(layer "In9.Cu")
		(net "P3E_CPU1_PE3_MP_TXP<7>")
	)
	(segment
		(start 75.113134 -108.890054)
		(end 83.345782 -107.24388)
		(width 0.1143)
		(layer "In9.Cu")
		(net "P3E_CPU1_PE3_MP_TXP<7>")
	)
	(segment
		(start 25.135332 -33.547558)
		(end 29.481018 -35.38728)
		(width 0.1143)
		(layer "In9.Cu")
		(net "P3E_CPU1_PE3_MP_TXP<7>")
	)
	(segment
		(start 83.345782 -107.24388)
		(end 92.764864 -109.127798)
		(width 0.1143)
		(layer "In9.Cu")
		(net "P3E_CPU1_PE3_MP_TXP<7>")
	)
	(segment
		(start 133.1849 -108.170218)
		(end 133.822186 -108.170218)
		(width 0.0889)
		(layer "In9.Cu")
		(net "P3E_CPU1_PE3_MP_TXP<7>")
	)
	(segment
		(start 16.398494 -36.283392)
		(end 17.581118 -35.79368)
		(width 0.1143)
		(layer "In9.Cu")
		(net "P3E_CPU1_PE3_MP_TXP<7>")
	)
	(segment
		(start 40.371268 -38.857936)
		(end 40.474646 -39.067232)
		(width 0.1143)
		(layer "In9.Cu")
		(net "P3E_CPU1_PE3_MP_TXP<7>")
	)
	(segment
		(start 39.51224 -38.74135)
		(end 39.837106 -38.851332)
		(width 0.1143)
		(layer "In9.Cu")
		(net "P3E_CPU1_PE3_MP_TXP<7>")
	)
	(segment
		(start 92.764864 -109.127798)
		(end 97.981262 -108.08462)
		(width 0.1143)
		(layer "In9.Cu")
		(net "P3E_CPU1_PE3_MP_TXP<7>")
	)
	(segment
		(start 68.642992 -107.597702)
		(end 75.113134 -108.890054)
		(width 0.1143)
		(layer "In9.Cu")
		(net "P3E_CPU1_PE3_MP_TXP<7>")
	)
	(segment
		(start 133.112002 -108.221018)
		(end 133.1341 -108.221018)
		(width 0.0889)
		(layer "In9.Cu")
		(net "P3E_CPU1_PE3_MP_TXP<7>")
	)
	(segment
		(start 60.763404 -57.159906)
		(end 61.277754 -59.726068)
		(width 0.1143)
		(layer "In9.Cu")
		(net "P3E_CPU1_PE3_MP_TXP<7>")
	)
	(segment
		(start 133.822186 -108.170218)
		(end 138.128248 -103.864156)
		(width 0.0889)
		(layer "In9.Cu")
		(net "P3E_CPU1_PE3_MP_TXP<7>")
	)
	(segment
		(start 40.046402 -38.747954)
		(end 40.371268 -38.857936)
		(width 0.1143)
		(layer "In9.Cu")
		(net "P3E_CPU1_PE3_MP_TXP<7>")
	)
	(segment
		(start 33.182306 -36.596066)
		(end 33.391602 -36.492688)
		(width 0.1143)
		(layer "In9.Cu")
		(net "P3E_CPU1_PE3_MP_TXP<7>")
	)
	(segment
		(start 39.408862 -38.5318)
		(end 39.51224 -38.74135)
		(width 0.1143)
		(layer "In9.Cu")
		(net "P3E_CPU1_PE3_MP_TXP<7>")
	)
	(segment
		(start 33.716468 -36.60267)
		(end 33.819846 -36.811966)
		(width 0.1143)
		(layer "In9.Cu")
		(net "P3E_CPU1_PE3_MP_TXP<7>")
	)
	(segment
		(start 64.24422 -104.666288)
		(end 68.642992 -107.597702)
		(width 0.1143)
		(layer "In9.Cu")
		(net "P3E_CPU1_PE3_MP_TXP<7>")
	)
	(segment
		(start 29.481018 -35.38728)
		(end 32.42945 -36.166552)
		(width 0.1143)
		(layer "In9.Cu")
		(net "P3E_CPU1_PE3_MP_TXP<7>")
	)
	(segment
		(start 137.353802 -97.768156)
		(end 137.377678 -97.678748)
		(width 0.0889)
		(layer "In9.Cu")
		(net "P3E_CPU1_PE3_MP_TXP<7>")
	)
	(segment
		(start 54.742588 -48.130206)
		(end 60.763404 -57.159906)
		(width 0.1143)
		(layer "In9.Cu")
		(net "P3E_CPU1_PE3_MP_TXP<7>")
	)
	(segment
		(start 24.519382 -33.547558)
		(end 25.135332 -33.547558)
		(width 0.1143)
		(layer "In9.Cu")
		(net "P3E_CPU1_PE3_MP_TXP<7>")
	)
	(segment
		(start 38.550088 -38.415214)
		(end 38.8747 -38.525196)
		(width 0.1143)
		(layer "In9.Cu")
		(net "P3E_CPU1_PE3_MP_TXP<7>")
	)
	(segment
		(start 15.57401 -36.283392)
		(end 16.398494 -36.283392)
		(width 0.1143)
		(layer "In9.Cu")
		(net "P3E_CPU1_PE3_MP_TXP<7>")
	)
	(segment
		(start 63.014098 -102.82047)
		(end 64.24422 -104.666288)
		(width 0.1143)
		(layer "In9.Cu")
		(net "P3E_CPU1_PE3_MP_TXP<7>")
	)
	(segment
		(start 60.409582 -89.782142)
		(end 63.014098 -102.82047)
		(width 0.1143)
		(layer "In9.Cu")
		(net "P3E_CPU1_PE3_MP_TXP<7>")
	)
	(segment
		(start 38.121844 -38.095682)
		(end 38.44671 -38.205664)
		(width 0.1143)
		(layer "In9.Cu")
		(net "P3E_CPU1_PE3_MP_TXP<7>")
	)
	(arc
		(start 138.182604 -99.195636)
		(mid 137.973996 -98.983704)
		(end 137.688574 -98.900234)
		(width 0.0889)
		(layer "In9.Cu")
		(net "P3E_CPU1_PE3_MP_TXP<7>")
	)
	(arc
		(start 138.128248 -101.98862)
		(mid 138.143409 -101.868766)
		(end 138.187938 -101.756464)
		(width 0.0889)
		(layer "In9.Cu")
		(net "P3E_CPU1_PE3_MP_TXP<7>")
	)
	(arc
		(start 138.188954 -100.766118)
		(mid 138.261752 -100.475355)
		(end 138.182604 -100.186236)
		(width 0.0889)
		(layer "In9.Cu")
		(net "P3E_CPU1_PE3_MP_TXP<7>")
	)
	(arc
		(start 138.182604 -99.786186)
		(mid 138.261609 -99.490928)
		(end 138.182604 -99.195636)
		(width 0.0889)
		(layer "In9.Cu")
		(net "P3E_CPU1_PE3_MP_TXP<7>")
	)
	(arc
		(start 137.655808 -98.900234)
		(mid 137.32289 -98.698243)
		(end 137.319258 -98.308922)
		(width 0.0889)
		(layer "In9.Cu")
		(net "P3E_CPU1_PE3_MP_TXP<7>")
	)
	(arc
		(start 137.330434 -98.289618)
		(mid 137.402829 -98.031606)
		(end 137.353802 -97.768156)
		(width 0.0889)
		(layer "In9.Cu")
		(net "P3E_CPU1_PE3_MP_TXP<7>")
	)
	(arc
		(start 138.177778 -100.1776)
		(mid 138.129023 -99.981248)
		(end 138.182604 -99.786186)
		(width 0.0889)
		(layer "In9.Cu")
		(net "P3E_CPU1_PE3_MP_TXP<7>")
	)
	(arc
		(start 138.182604 -101.176582)
		(mid 138.129105 -100.976684)
		(end 138.182604 -100.776786)
		(width 0.0889)
		(layer "In9.Cu")
		(net "P3E_CPU1_PE3_MP_TXP<7>")
	)
	(arc
		(start 138.187938 -101.756464)
		(mid 138.261458 -101.465819)
		(end 138.182604 -101.176582)
		(width 0.0889)
		(layer "In9.Cu")
		(net "P3E_CPU1_PE3_MP_TXP<7>")
	)
	(segment
		(start 14.7828 -33.909)
		(end 15.10665 -34.23285)
		(width 0.1143)
		(layer "F.Cu")
		(net "P3E_CPU1_PE3_MP_TXP<6>")
	)
	(segment
		(start 15.10665 -34.23285)
		(end 16.570198 -34.23285)
		(width 0.1143)
		(layer "F.Cu")
		(net "P3E_CPU1_PE3_MP_TXP<6>")
	)
	(segment
		(start 16.684498 -34.11855)
		(end 16.684498 -33.7185)
		(width 0.1143)
		(layer "F.Cu")
		(net "P3E_CPU1_PE3_MP_TXP<6>")
	)
	(segment
		(start 135.382254 -98.500184)
		(end 135.953754 -98.500184)
		(width 0.1143)
		(layer "F.Cu")
		(net "P3E_CPU1_PE3_MP_TXP<6>")
	)
	(segment
		(start 16.570198 -34.23285)
		(end 16.684498 -34.11855)
		(width 0.1143)
		(layer "F.Cu")
		(net "P3E_CPU1_PE3_MP_TXP<6>")
	)
	(via
		(at 16.684498 -33.7185)
		(size 0.508)
		(drill 0.254)
		(layers "F.Cu" "B.Cu")
		(net "P3E_CPU1_PE3_MP_TXP<6>")
	)
	(via
		(at 135.953754 -98.500184)
		(size 0.508)
		(drill 0.254)
		(layers "F.Cu" "B.Cu")
		(net "P3E_CPU1_PE3_MP_TXP<6>")
	)
	(segment
		(start 63.93434 -77.0001)
		(end 61.425328 -89.546938)
		(width 0.1143)
		(layer "In9.Cu")
		(net "P3E_CPU1_PE3_MP_TXP<6>")
	)
	(segment
		(start 18.38198 -33.243012)
		(end 19.144996 -33.243012)
		(width 0.1143)
		(layer "In9.Cu")
		(net "P3E_CPU1_PE3_MP_TXP<6>")
	)
	(segment
		(start 136.24687 -98.669348)
		(end 135.953754 -98.500184)
		(width 0.0889)
		(layer "In9.Cu")
		(net "P3E_CPU1_PE3_MP_TXP<6>")
	)
	(segment
		(start 136.264396 -104.20223)
		(end 136.39038 -104.076246)
		(width 0.0889)
		(layer "In9.Cu")
		(net "P3E_CPU1_PE3_MP_TXP<6>")
	)
	(segment
		(start 136.82726 -99.586288)
		(end 136.794494 -99.586288)
		(width 0.0889)
		(layer "In9.Cu")
		(net "P3E_CPU1_PE3_MP_TXP<6>")
	)
	(segment
		(start 127.775208 -106.651806)
		(end 130.769106 -107.250484)
		(width 0.1143)
		(layer "In9.Cu")
		(net "P3E_CPU1_PE3_MP_TXP<6>")
	)
	(segment
		(start 137.24128 -102.32898)
		(end 137.24128 -102.07752)
		(width 0.0889)
		(layer "In9.Cu")
		(net "P3E_CPU1_PE3_MP_TXP<6>")
	)
	(segment
		(start 18.096738 -33.528254)
		(end 18.38198 -33.243012)
		(width 0.1143)
		(layer "In9.Cu")
		(net "P3E_CPU1_PE3_MP_TXP<6>")
	)
	(segment
		(start 24.329136 -32.552132)
		(end 25.33015 -32.552132)
		(width 0.1143)
		(layer "In9.Cu")
		(net "P3E_CPU1_PE3_MP_TXP<6>")
	)
	(segment
		(start 115.04549 -109.197648)
		(end 127.775208 -106.651806)
		(width 0.1143)
		(layer "In9.Cu")
		(net "P3E_CPU1_PE3_MP_TXP<6>")
	)
	(segment
		(start 137.159238 -100.186236)
		(end 137.164064 -100.1776)
		(width 0.0889)
		(layer "In9.Cu")
		(net "P3E_CPU1_PE3_MP_TXP<6>")
	)
	(segment
		(start 133.287262 -107.301284)
		(end 136.264396 -104.32415)
		(width 0.0889)
		(layer "In9.Cu")
		(net "P3E_CPU1_PE3_MP_TXP<6>")
	)
	(segment
		(start 137.24128 -102.663244)
		(end 137.163048 -102.585012)
		(width 0.0889)
		(layer "In9.Cu")
		(net "P3E_CPU1_PE3_MP_TXP<6>")
	)
	(segment
		(start 92.70746 -108.170472)
		(end 98.095562 -107.093004)
		(width 0.1143)
		(layer "In9.Cu")
		(net "P3E_CPU1_PE3_MP_TXP<6>")
	)
	(segment
		(start 64.040258 -102.633018)
		(end 64.961008 -104.01427)
		(width 0.1143)
		(layer "In9.Cu")
		(net "P3E_CPU1_PE3_MP_TXP<6>")
	)
	(segment
		(start 110.071916 -108.20273)
		(end 115.04549 -109.197648)
		(width 0.1143)
		(layer "In9.Cu")
		(net "P3E_CPU1_PE3_MP_TXP<6>")
	)
	(segment
		(start 32.790638 -34.090356)
		(end 39.604442 -36.913312)
		(width 0.1143)
		(layer "In9.Cu")
		(net "P3E_CPU1_PE3_MP_TXP<6>")
	)
	(segment
		(start 136.671558 -103.795068)
		(end 136.797542 -103.669084)
		(width 0.0889)
		(layer "In9.Cu")
		(net "P3E_CPU1_PE3_MP_TXP<6>")
	)
	(segment
		(start 68.988432 -106.698034)
		(end 75.167236 -107.932982)
		(width 0.1143)
		(layer "In9.Cu")
		(net "P3E_CPU1_PE3_MP_TXP<6>")
	)
	(segment
		(start 19.144996 -33.243012)
		(end 19.430238 -33.528254)
		(width 0.1143)
		(layer "In9.Cu")
		(net "P3E_CPU1_PE3_MP_TXP<6>")
	)
	(segment
		(start 19.430238 -33.528254)
		(end 19.430238 -34.09315)
		(width 0.1143)
		(layer "In9.Cu")
		(net "P3E_CPU1_PE3_MP_TXP<6>")
	)
	(segment
		(start 39.604442 -36.913312)
		(end 55.730394 -47.670212)
		(width 0.1143)
		(layer "In9.Cu")
		(net "P3E_CPU1_PE3_MP_TXP<6>")
	)
	(segment
		(start 137.163048 -102.585012)
		(end 137.163048 -102.407212)
		(width 0.0889)
		(layer "In9.Cu")
		(net "P3E_CPU1_PE3_MP_TXP<6>")
	)
	(segment
		(start 16.684498 -33.7185)
		(end 16.684498 -34.09315)
		(width 0.1143)
		(layer "In9.Cu")
		(net "P3E_CPU1_PE3_MP_TXP<6>")
	)
	(segment
		(start 136.264396 -104.32415)
		(end 136.264396 -104.20223)
		(width 0.0889)
		(layer "In9.Cu")
		(net "P3E_CPU1_PE3_MP_TXP<6>")
	)
	(segment
		(start 18.096738 -34.09315)
		(end 18.096738 -33.528254)
		(width 0.1143)
		(layer "In9.Cu")
		(net "P3E_CPU1_PE3_MP_TXP<6>")
	)
	(segment
		(start 83.34375 -106.29773)
		(end 92.70746 -108.170472)
		(width 0.1143)
		(layer "In9.Cu")
		(net "P3E_CPU1_PE3_MP_TXP<6>")
	)
	(segment
		(start 132.871972 -107.250484)
		(end 132.89407 -107.250484)
		(width 0.0889)
		(layer "In9.Cu")
		(net "P3E_CPU1_PE3_MP_TXP<6>")
	)
	(segment
		(start 64.961008 -104.01427)
		(end 68.988432 -106.698034)
		(width 0.1143)
		(layer "In9.Cu")
		(net "P3E_CPU1_PE3_MP_TXP<6>")
	)
	(segment
		(start 75.167236 -107.932982)
		(end 83.34375 -106.29773)
		(width 0.1143)
		(layer "In9.Cu")
		(net "P3E_CPU1_PE3_MP_TXP<6>")
	)
	(segment
		(start 136.270746 -98.758756)
		(end 136.24687 -98.669348)
		(width 0.0889)
		(layer "In9.Cu")
		(net "P3E_CPU1_PE3_MP_TXP<6>")
	)
	(segment
		(start 61.425328 -89.546938)
		(end 64.040258 -102.63251)
		(width 0.1143)
		(layer "In9.Cu")
		(net "P3E_CPU1_PE3_MP_TXP<6>")
	)
	(segment
		(start 20.133056 -34.29)
		(end 24.329136 -32.552132)
		(width 0.1143)
		(layer "In9.Cu")
		(net "P3E_CPU1_PE3_MP_TXP<6>")
	)
	(segment
		(start 132.94487 -107.301284)
		(end 133.287262 -107.301284)
		(width 0.0889)
		(layer "In9.Cu")
		(net "P3E_CPU1_PE3_MP_TXP<6>")
	)
	(segment
		(start 106.857292 -108.845858)
		(end 110.071916 -108.20273)
		(width 0.1143)
		(layer "In9.Cu")
		(net "P3E_CPU1_PE3_MP_TXP<6>")
	)
	(segment
		(start 136.919462 -103.669084)
		(end 137.24128 -103.347266)
		(width 0.0889)
		(layer "In9.Cu")
		(net "P3E_CPU1_PE3_MP_TXP<6>")
	)
	(segment
		(start 61.693806 -56.61406)
		(end 62.32779 -59.776614)
		(width 0.1143)
		(layer "In9.Cu")
		(net "P3E_CPU1_PE3_MP_TXP<6>")
	)
	(segment
		(start 136.5123 -104.076246)
		(end 136.671558 -103.916988)
		(width 0.0889)
		(layer "In9.Cu")
		(net "P3E_CPU1_PE3_MP_TXP<6>")
	)
	(segment
		(start 19.627088 -34.29)
		(end 20.133056 -34.29)
		(width 0.1143)
		(layer "In9.Cu")
		(net "P3E_CPU1_PE3_MP_TXP<6>")
	)
	(segment
		(start 19.430238 -34.09315)
		(end 19.627088 -34.29)
		(width 0.1143)
		(layer "In9.Cu")
		(net "P3E_CPU1_PE3_MP_TXP<6>")
	)
	(segment
		(start 16.798798 -34.20745)
		(end 17.982438 -34.20745)
		(width 0.1143)
		(layer "In9.Cu")
		(net "P3E_CPU1_PE3_MP_TXP<6>")
	)
	(segment
		(start 137.24128 -103.347266)
		(end 137.24128 -102.663244)
		(width 0.0889)
		(layer "In9.Cu")
		(net "P3E_CPU1_PE3_MP_TXP<6>")
	)
	(segment
		(start 136.39038 -104.076246)
		(end 136.5123 -104.076246)
		(width 0.0889)
		(layer "In9.Cu")
		(net "P3E_CPU1_PE3_MP_TXP<6>")
	)
	(segment
		(start 130.769106 -107.250484)
		(end 132.871972 -107.250484)
		(width 0.1143)
		(layer "In9.Cu")
		(net "P3E_CPU1_PE3_MP_TXP<6>")
	)
	(segment
		(start 16.684498 -34.09315)
		(end 16.798798 -34.20745)
		(width 0.1143)
		(layer "In9.Cu")
		(net "P3E_CPU1_PE3_MP_TXP<6>")
	)
	(segment
		(start 30.277308 -34.601404)
		(end 32.790638 -34.090356)
		(width 0.1143)
		(layer "In9.Cu")
		(net "P3E_CPU1_PE3_MP_TXP<6>")
	)
	(segment
		(start 61.409072 -64.37122)
		(end 63.93434 -77.0001)
		(width 0.1143)
		(layer "In9.Cu")
		(net "P3E_CPU1_PE3_MP_TXP<6>")
	)
	(segment
		(start 62.32779 -59.776614)
		(end 61.409072 -64.37122)
		(width 0.1143)
		(layer "In9.Cu")
		(net "P3E_CPU1_PE3_MP_TXP<6>")
	)
	(segment
		(start 136.797542 -103.669084)
		(end 136.919462 -103.669084)
		(width 0.0889)
		(layer "In9.Cu")
		(net "P3E_CPU1_PE3_MP_TXP<6>")
	)
	(segment
		(start 137.150856 -101.189282)
		(end 137.157968 -101.176328)
		(width 0.0889)
		(layer "In9.Cu")
		(net "P3E_CPU1_PE3_MP_TXP<6>")
	)
	(segment
		(start 25.33015 -32.552132)
		(end 30.277308 -34.601404)
		(width 0.1143)
		(layer "In9.Cu")
		(net "P3E_CPU1_PE3_MP_TXP<6>")
	)
	(segment
		(start 98.095562 -107.093004)
		(end 106.857292 -108.845858)
		(width 0.1143)
		(layer "In9.Cu")
		(net "P3E_CPU1_PE3_MP_TXP<6>")
	)
	(segment
		(start 137.163048 -102.407212)
		(end 137.24128 -102.32898)
		(width 0.0889)
		(layer "In9.Cu")
		(net "P3E_CPU1_PE3_MP_TXP<6>")
	)
	(segment
		(start 17.982438 -34.20745)
		(end 18.096738 -34.09315)
		(width 0.1143)
		(layer "In9.Cu")
		(net "P3E_CPU1_PE3_MP_TXP<6>")
	)
	(segment
		(start 55.730394 -47.670212)
		(end 61.693806 -56.61406)
		(width 0.1143)
		(layer "In9.Cu")
		(net "P3E_CPU1_PE3_MP_TXP<6>")
	)
	(segment
		(start 64.040258 -102.63251)
		(end 64.040258 -102.633018)
		(width 0.1143)
		(layer "In9.Cu")
		(net "P3E_CPU1_PE3_MP_TXP<6>")
	)
	(segment
		(start 136.671558 -103.916988)
		(end 136.671558 -103.795068)
		(width 0.0889)
		(layer "In9.Cu")
		(net "P3E_CPU1_PE3_MP_TXP<6>")
	)
	(segment
		(start 132.89407 -107.250484)
		(end 132.94487 -107.301284)
		(width 0.0889)
		(layer "In9.Cu")
		(net "P3E_CPU1_PE3_MP_TXP<6>")
	)
	(arc
		(start 137.164064 -100.1776)
		(mid 137.1716 -99.810169)
		(end 136.876282 -99.591368)
		(width 0.0889)
		(layer "In9.Cu")
		(net "P3E_CPU1_PE3_MP_TXP<6>")
	)
	(arc
		(start 137.157968 -100.776532)
		(mid 137.155555 -100.771263)
		(end 137.152888 -100.766118)
		(width 0.0889)
		(layer "In9.Cu")
		(net "P3E_CPU1_PE3_MP_TXP<6>")
	)
	(arc
		(start 137.157968 -101.176328)
		(mid 137.211467 -100.97643)
		(end 137.157968 -100.776532)
		(width 0.0889)
		(layer "In9.Cu")
		(net "P3E_CPU1_PE3_MP_TXP<6>")
	)
	(arc
		(start 136.876282 -99.591368)
		(mid 136.85185 -99.588066)
		(end 136.82726 -99.586288)
		(width 0.0889)
		(layer "In9.Cu")
		(net "P3E_CPU1_PE3_MP_TXP<6>")
	)
	(arc
		(start 137.152888 -100.766118)
		(mid 137.08009 -100.475355)
		(end 137.159238 -100.186236)
		(width 0.0889)
		(layer "In9.Cu")
		(net "P3E_CPU1_PE3_MP_TXP<6>")
	)
	(arc
		(start 136.794494 -99.586288)
		(mid 136.312783 -99.311679)
		(end 136.270746 -98.758756)
		(width 0.0889)
		(layer "In9.Cu")
		(net "P3E_CPU1_PE3_MP_TXP<6>")
	)
	(arc
		(start 137.24128 -102.07752)
		(mid 137.220019 -101.916854)
		(end 137.157968 -101.767132)
		(width 0.0889)
		(layer "In9.Cu")
		(net "P3E_CPU1_PE3_MP_TXP<6>")
	)
	(arc
		(start 137.157968 -101.767132)
		(mid 137.079007 -101.47915)
		(end 137.150856 -101.189282)
		(width 0.0889)
		(layer "In9.Cu")
		(net "P3E_CPU1_PE3_MP_TXP<6>")
	)
	(segment
		(start 15.451074 -32.81045)
		(end 15.451074 -33.2105)
		(width 0.1143)
		(layer "F.Cu")
		(net "P3E_CPU1_PE3_MP_TXP<5>")
	)
	(segment
		(start 135.382254 -99.490784)
		(end 135.953754 -99.490784)
		(width 0.1143)
		(layer "F.Cu")
		(net "P3E_CPU1_PE3_MP_TXP<5>")
	)
	(segment
		(start 15.088616 -32.714184)
		(end 15.354808 -32.714184)
		(width 0.1143)
		(layer "F.Cu")
		(net "P3E_CPU1_PE3_MP_TXP<5>")
	)
	(segment
		(start 15.354808 -32.714184)
		(end 15.451074 -32.81045)
		(width 0.1143)
		(layer "F.Cu")
		(net "P3E_CPU1_PE3_MP_TXP<5>")
	)
	(segment
		(start 14.7828 -33.02)
		(end 15.088616 -32.714184)
		(width 0.1143)
		(layer "F.Cu")
		(net "P3E_CPU1_PE3_MP_TXP<5>")
	)
	(via
		(at 15.451074 -33.2105)
		(size 0.508)
		(drill 0.254)
		(layers "F.Cu" "B.Cu")
		(net "P3E_CPU1_PE3_MP_TXP<5>")
	)
	(via
		(at 135.953754 -99.490784)
		(size 0.508)
		(drill 0.254)
		(layers "F.Cu" "B.Cu")
		(net "P3E_CPU1_PE3_MP_TXP<5>")
	)
	(segment
		(start 61.805312 -89.509346)
		(end 64.327278 -76.899008)
		(width 0.1143)
		(layer "In9.Cu")
		(net "P3E_CPU1_PE3_MP_TXP<5>")
	)
	(segment
		(start 132.575554 -106.652568)
		(end 132.524754 -106.703368)
		(width 0.0889)
		(layer "In9.Cu")
		(net "P3E_CPU1_PE3_MP_TXP<5>")
	)
	(segment
		(start 127.840232 -106.2863)
		(end 115.51285 -108.751624)
		(width 0.1143)
		(layer "In9.Cu")
		(net "P3E_CPU1_PE3_MP_TXP<5>")
	)
	(segment
		(start 83.539584 -105.906062)
		(end 75.167744 -107.580684)
		(width 0.1143)
		(layer "In9.Cu")
		(net "P3E_CPU1_PE3_MP_TXP<5>")
	)
	(segment
		(start 136.577324 -102.754176)
		(end 136.271 -103.0605)
		(width 0.0889)
		(layer "In9.Cu")
		(net "P3E_CPU1_PE3_MP_TXP<5>")
	)
	(segment
		(start 39.554658 -36.33597)
		(end 38.994588 -35.776154)
		(width 0.1143)
		(layer "In9.Cu")
		(net "P3E_CPU1_PE3_MP_TXP<5>")
	)
	(segment
		(start 136.58342 -100.665026)
		(end 136.58342 -100.937822)
		(width 0.0889)
		(layer "In9.Cu")
		(net "P3E_CPU1_PE3_MP_TXP<5>")
	)
	(segment
		(start 30.08122 -32.4231)
		(end 28.518358 -31.7754)
		(width 0.1143)
		(layer "In9.Cu")
		(net "P3E_CPU1_PE3_MP_TXP<5>")
	)
	(segment
		(start 64.327278 -76.899008)
		(end 61.832744 -64.424052)
		(width 0.1143)
		(layer "In9.Cu")
		(net "P3E_CPU1_PE3_MP_TXP<5>")
	)
	(segment
		(start 62.730888 -59.93257)
		(end 62.041024 -56.488838)
		(width 0.1143)
		(layer "In9.Cu")
		(net "P3E_CPU1_PE3_MP_TXP<5>")
	)
	(segment
		(start 136.47166 -100.197158)
		(end 136.47039 -100.194618)
		(width 0.0889)
		(layer "In9.Cu")
		(net "P3E_CPU1_PE3_MP_TXP<5>")
	)
	(segment
		(start 55.85587 -47.21225)
		(end 39.554658 -36.33597)
		(width 0.1143)
		(layer "In9.Cu")
		(net "P3E_CPU1_PE3_MP_TXP<5>")
	)
	(segment
		(start 110.259622 -107.700572)
		(end 106.742484 -108.404152)
		(width 0.1143)
		(layer "In9.Cu")
		(net "P3E_CPU1_PE3_MP_TXP<5>")
	)
	(segment
		(start 15.451074 -32.83585)
		(end 15.451074 -33.2105)
		(width 0.1143)
		(layer "In9.Cu")
		(net "P3E_CPU1_PE3_MP_TXP<5>")
	)
	(segment
		(start 30.90164 -32.4231)
		(end 30.08122 -32.4231)
		(width 0.1143)
		(layer "In9.Cu")
		(net "P3E_CPU1_PE3_MP_TXP<5>")
	)
	(segment
		(start 75.167744 -107.580684)
		(end 69.204078 -106.388662)
		(width 0.1143)
		(layer "In9.Cu")
		(net "P3E_CPU1_PE3_MP_TXP<5>")
	)
	(segment
		(start 133.322822 -106.652568)
		(end 132.575554 -106.652568)
		(width 0.0889)
		(layer "In9.Cu")
		(net "P3E_CPU1_PE3_MP_TXP<5>")
	)
	(segment
		(start 62.041278 -56.488838)
		(end 55.85587 -47.21225)
		(width 0.1143)
		(layer "In9.Cu")
		(net "P3E_CPU1_PE3_MP_TXP<5>")
	)
	(segment
		(start 61.832744 -64.424052)
		(end 62.730888 -59.93257)
		(width 0.1143)
		(layer "In9.Cu")
		(net "P3E_CPU1_PE3_MP_TXP<5>")
	)
	(segment
		(start 135.660638 -99.659948)
		(end 135.639556 -99.738688)
		(width 0.0889)
		(layer "In9.Cu")
		(net "P3E_CPU1_PE3_MP_TXP<5>")
	)
	(segment
		(start 35.744658 -34.4297)
		(end 30.90164 -32.4231)
		(width 0.1143)
		(layer "In9.Cu")
		(net "P3E_CPU1_PE3_MP_TXP<5>")
	)
	(segment
		(start 135.938768 -99.890834)
		(end 135.966454 -99.890834)
		(width 0.0889)
		(layer "In9.Cu")
		(net "P3E_CPU1_PE3_MP_TXP<5>")
	)
	(segment
		(start 19.419316 -31.7754)
		(end 17.135094 -32.72155)
		(width 0.1143)
		(layer "In9.Cu")
		(net "P3E_CPU1_PE3_MP_TXP<5>")
	)
	(segment
		(start 136.460738 -102.1588)
		(end 136.577324 -102.372922)
		(width 0.0889)
		(layer "In9.Cu")
		(net "P3E_CPU1_PE3_MP_TXP<5>")
	)
	(segment
		(start 36.150804 -34.776664)
		(end 35.834066 -34.645346)
		(width 0.1143)
		(layer "In9.Cu")
		(net "P3E_CPU1_PE3_MP_TXP<5>")
	)
	(segment
		(start 129.929382 -106.703368)
		(end 127.840232 -106.2863)
		(width 0.1143)
		(layer "In9.Cu")
		(net "P3E_CPU1_PE3_MP_TXP<5>")
	)
	(segment
		(start 106.742484 -108.404152)
		(end 98.043746 -106.663998)
		(width 0.1143)
		(layer "In9.Cu")
		(net "P3E_CPU1_PE3_MP_TXP<5>")
	)
	(segment
		(start 62.041024 -56.488838)
		(end 62.041278 -56.488838)
		(width 0.1143)
		(layer "In9.Cu")
		(net "P3E_CPU1_PE3_MP_TXP<5>")
	)
	(segment
		(start 37.71138 -35.423094)
		(end 37.621972 -35.207448)
		(width 0.1143)
		(layer "In9.Cu")
		(net "P3E_CPU1_PE3_MP_TXP<5>")
	)
	(segment
		(start 28.518358 -31.7754)
		(end 19.419316 -31.7754)
		(width 0.1143)
		(layer "In9.Cu")
		(net "P3E_CPU1_PE3_MP_TXP<5>")
	)
	(segment
		(start 136.271 -103.70439)
		(end 133.322822 -106.652568)
		(width 0.0889)
		(layer "In9.Cu")
		(net "P3E_CPU1_PE3_MP_TXP<5>")
	)
	(segment
		(start 38.028118 -35.554412)
		(end 37.71138 -35.423094)
		(width 0.1143)
		(layer "In9.Cu")
		(net "P3E_CPU1_PE3_MP_TXP<5>")
	)
	(segment
		(start 36.772596 -35.03422)
		(end 36.683442 -34.818574)
		(width 0.1143)
		(layer "In9.Cu")
		(net "P3E_CPU1_PE3_MP_TXP<5>")
	)
	(segment
		(start 35.834066 -34.645346)
		(end 35.744658 -34.4297)
		(width 0.1143)
		(layer "In9.Cu")
		(net "P3E_CPU1_PE3_MP_TXP<5>")
	)
	(segment
		(start 36.366704 -34.687256)
		(end 36.150804 -34.776664)
		(width 0.1143)
		(layer "In9.Cu")
		(net "P3E_CPU1_PE3_MP_TXP<5>")
	)
	(segment
		(start 115.51285 -108.751624)
		(end 110.259622 -107.700572)
		(width 0.1143)
		(layer "In9.Cu")
		(net "P3E_CPU1_PE3_MP_TXP<5>")
	)
	(segment
		(start 37.089588 -35.165538)
		(end 36.772596 -35.03422)
		(width 0.1143)
		(layer "In9.Cu")
		(net "P3E_CPU1_PE3_MP_TXP<5>")
	)
	(segment
		(start 17.135094 -32.72155)
		(end 15.565374 -32.72155)
		(width 0.1143)
		(layer "In9.Cu")
		(net "P3E_CPU1_PE3_MP_TXP<5>")
	)
	(segment
		(start 37.621972 -35.207448)
		(end 37.305234 -35.07613)
		(width 0.1143)
		(layer "In9.Cu")
		(net "P3E_CPU1_PE3_MP_TXP<5>")
	)
	(segment
		(start 36.683442 -34.818574)
		(end 36.366704 -34.687256)
		(width 0.1143)
		(layer "In9.Cu")
		(net "P3E_CPU1_PE3_MP_TXP<5>")
	)
	(segment
		(start 132.502656 -106.703368)
		(end 129.929382 -106.703368)
		(width 0.1143)
		(layer "In9.Cu")
		(net "P3E_CPU1_PE3_MP_TXP<5>")
	)
	(segment
		(start 132.524754 -106.703368)
		(end 132.502656 -106.703368)
		(width 0.0889)
		(layer "In9.Cu")
		(net "P3E_CPU1_PE3_MP_TXP<5>")
	)
	(segment
		(start 65.498472 -103.919274)
		(end 64.337184 -102.176326)
		(width 0.1143)
		(layer "In9.Cu")
		(net "P3E_CPU1_PE3_MP_TXP<5>")
	)
	(segment
		(start 136.577324 -102.372922)
		(end 136.577324 -102.754176)
		(width 0.0889)
		(layer "In9.Cu")
		(net "P3E_CPU1_PE3_MP_TXP<5>")
	)
	(segment
		(start 92.686378 -107.73537)
		(end 83.539584 -105.906062)
		(width 0.1143)
		(layer "In9.Cu")
		(net "P3E_CPU1_PE3_MP_TXP<5>")
	)
	(segment
		(start 136.271 -103.0605)
		(end 136.271 -103.70439)
		(width 0.0889)
		(layer "In9.Cu")
		(net "P3E_CPU1_PE3_MP_TXP<5>")
	)
	(segment
		(start 69.204078 -106.388662)
		(end 65.498472 -103.919274)
		(width 0.1143)
		(layer "In9.Cu")
		(net "P3E_CPU1_PE3_MP_TXP<5>")
	)
	(segment
		(start 135.953754 -99.490784)
		(end 135.660638 -99.659948)
		(width 0.0889)
		(layer "In9.Cu")
		(net "P3E_CPU1_PE3_MP_TXP<5>")
	)
	(segment
		(start 15.565374 -32.72155)
		(end 15.451074 -32.83585)
		(width 0.1143)
		(layer "In9.Cu")
		(net "P3E_CPU1_PE3_MP_TXP<5>")
	)
	(segment
		(start 136.465564 -100.185982)
		(end 136.47166 -100.197158)
		(width 0.0889)
		(layer "In9.Cu")
		(net "P3E_CPU1_PE3_MP_TXP<5>")
	)
	(segment
		(start 37.305234 -35.07613)
		(end 37.089588 -35.165538)
		(width 0.1143)
		(layer "In9.Cu")
		(net "P3E_CPU1_PE3_MP_TXP<5>")
	)
	(segment
		(start 38.243764 -35.465004)
		(end 38.028118 -35.554412)
		(width 0.1143)
		(layer "In9.Cu")
		(net "P3E_CPU1_PE3_MP_TXP<5>")
	)
	(segment
		(start 64.337184 -102.176326)
		(end 61.805312 -89.509346)
		(width 0.1143)
		(layer "In9.Cu")
		(net "P3E_CPU1_PE3_MP_TXP<5>")
	)
	(segment
		(start 38.994588 -35.776154)
		(end 38.243764 -35.465004)
		(width 0.1143)
		(layer "In9.Cu")
		(net "P3E_CPU1_PE3_MP_TXP<5>")
	)
	(segment
		(start 98.043746 -106.663998)
		(end 92.686378 -107.73537)
		(width 0.1143)
		(layer "In9.Cu")
		(net "P3E_CPU1_PE3_MP_TXP<5>")
	)
	(arc
		(start 136.47039 -100.194618)
		(mid 136.55481 -100.423113)
		(end 136.58342 -100.665026)
		(width 0.0889)
		(layer "In9.Cu")
		(net "P3E_CPU1_PE3_MP_TXP<5>")
	)
	(arc
		(start 136.58342 -100.937822)
		(mid 136.580374 -101.185171)
		(end 136.570974 -101.43236)
		(width 0.0889)
		(layer "In9.Cu")
		(net "P3E_CPU1_PE3_MP_TXP<5>")
	)
	(arc
		(start 136.570974 -101.43236)
		(mid 136.540576 -101.603181)
		(end 136.46912 -101.76129)
		(width 0.0889)
		(layer "In9.Cu")
		(net "P3E_CPU1_PE3_MP_TXP<5>")
	)
	(arc
		(start 135.966454 -99.890834)
		(mid 136.254646 -99.973037)
		(end 136.465564 -100.185982)
		(width 0.0889)
		(layer "In9.Cu")
		(net "P3E_CPU1_PE3_MP_TXP<5>")
	)
	(arc
		(start 135.639556 -99.738688)
		(mid 135.772437 -99.847671)
		(end 135.938768 -99.890834)
		(width 0.0889)
		(layer "In9.Cu")
		(net "P3E_CPU1_PE3_MP_TXP<5>")
	)
	(arc
		(start 136.46912 -101.76129)
		(mid 136.412126 -101.95892)
		(end 136.460738 -102.1588)
		(width 0.0889)
		(layer "In9.Cu")
		(net "P3E_CPU1_PE3_MP_TXP<5>")
	)
	(segment
		(start 16.49476 -30.67558)
		(end 16.61287 -30.55747)
		(width 0.1143)
		(layer "F.Cu")
		(net "P3E_CPU1_PE3_MP_TXP<4>")
	)
	(segment
		(start 16.61287 -30.55747)
		(end 16.61287 -30.15742)
		(width 0.1143)
		(layer "F.Cu")
		(net "P3E_CPU1_PE3_MP_TXP<4>")
	)
	(segment
		(start 15.10538 -30.67558)
		(end 16.49476 -30.67558)
		(width 0.1143)
		(layer "F.Cu")
		(net "P3E_CPU1_PE3_MP_TXP<4>")
	)
	(segment
		(start 135.382254 -100.481638)
		(end 135.953754 -100.481638)
		(width 0.1143)
		(layer "F.Cu")
		(net "P3E_CPU1_PE3_MP_TXP<4>")
	)
	(segment
		(start 14.7828 -30.353)
		(end 15.10538 -30.67558)
		(width 0.1143)
		(layer "F.Cu")
		(net "P3E_CPU1_PE3_MP_TXP<4>")
	)
	(via
		(at 135.953754 -100.481638)
		(size 0.508)
		(drill 0.254)
		(layers "F.Cu" "B.Cu")
		(net "P3E_CPU1_PE3_MP_TXP<4>")
	)
	(via
		(at 16.61287 -30.15742)
		(size 0.508)
		(drill 0.254)
		(layers "F.Cu" "B.Cu")
		(net "P3E_CPU1_PE3_MP_TXP<4>")
	)
	(segment
		(start 23.295864 -29.79293)
		(end 23.295864 -29.792676)
		(width 0.1143)
		(layer "In9.Cu")
		(net "P3E_CPU1_PE3_MP_TXP<4>")
	)
	(segment
		(start 83.599274 -104.948482)
		(end 75.241404 -106.620056)
		(width 0.1143)
		(layer "In9.Cu")
		(net "P3E_CPU1_PE3_MP_TXP<4>")
	)
	(segment
		(start 56.61787 -46.504606)
		(end 40.971216 -36.069016)
		(width 0.1143)
		(layer "In9.Cu")
		(net "P3E_CPU1_PE3_MP_TXP<4>")
	)
	(segment
		(start 17.389602 -30.651196)
		(end 17.389348 -30.65145)
		(width 0.1143)
		(layer "In9.Cu")
		(net "P3E_CPU1_PE3_MP_TXP<4>")
	)
	(segment
		(start 135.521954 -103.146352)
		(end 132.90042 -105.767886)
		(width 0.0889)
		(layer "In9.Cu")
		(net "P3E_CPU1_PE3_MP_TXP<4>")
	)
	(segment
		(start 27.183334 -29.783532)
		(end 23.295864 -29.79293)
		(width 0.1143)
		(layer "In9.Cu")
		(net "P3E_CPU1_PE3_MP_TXP<4>")
	)
	(segment
		(start 63.746126 -60.114688)
		(end 62.910974 -55.943246)
		(width 0.1143)
		(layer "In9.Cu")
		(net "P3E_CPU1_PE3_MP_TXP<4>")
	)
	(segment
		(start 65.28308 -76.936854)
		(end 62.832488 -64.68237)
		(width 0.1143)
		(layer "In9.Cu")
		(net "P3E_CPU1_PE3_MP_TXP<4>")
	)
	(segment
		(start 132.320538 -105.717086)
		(end 132.29844 -105.717086)
		(width 0.0889)
		(layer "In9.Cu")
		(net "P3E_CPU1_PE3_MP_TXP<4>")
	)
	(segment
		(start 128.099312 -105.284016)
		(end 115.783868 -107.747054)
		(width 0.1143)
		(layer "In9.Cu")
		(net "P3E_CPU1_PE3_MP_TXP<4>")
	)
	(segment
		(start 106.742484 -107.352592)
		(end 98.044 -105.612438)
		(width 0.1143)
		(layer "In9.Cu")
		(net "P3E_CPU1_PE3_MP_TXP<4>")
	)
	(segment
		(start 132.371338 -105.767886)
		(end 132.320538 -105.717086)
		(width 0.0889)
		(layer "In9.Cu")
		(net "P3E_CPU1_PE3_MP_TXP<4>")
	)
	(segment
		(start 19.439382 -29.802074)
		(end 17.389602 -30.651196)
		(width 0.1143)
		(layer "In9.Cu")
		(net "P3E_CPU1_PE3_MP_TXP<4>")
	)
	(segment
		(start 135.441944 -102.757986)
		(end 135.481822 -102.827074)
		(width 0.0889)
		(layer "In9.Cu")
		(net "P3E_CPU1_PE3_MP_TXP<4>")
	)
	(segment
		(start 132.29844 -105.717086)
		(end 130.265424 -105.717086)
		(width 0.1143)
		(layer "In9.Cu")
		(net "P3E_CPU1_PE3_MP_TXP<4>")
	)
	(segment
		(start 75.241404 -106.620056)
		(end 69.62648 -105.49763)
		(width 0.1143)
		(layer "In9.Cu")
		(net "P3E_CPU1_PE3_MP_TXP<4>")
	)
	(segment
		(start 38.810692 -33.908492)
		(end 32.079692 -31.121858)
		(width 0.1143)
		(layer "In9.Cu")
		(net "P3E_CPU1_PE3_MP_TXP<4>")
	)
	(segment
		(start 17.389348 -30.65145)
		(end 16.73225 -30.65145)
		(width 0.1143)
		(layer "In9.Cu")
		(net "P3E_CPU1_PE3_MP_TXP<4>")
	)
	(segment
		(start 135.953754 -100.819712)
		(end 135.888984 -100.884482)
		(width 0.0889)
		(layer "In9.Cu")
		(net "P3E_CPU1_PE3_MP_TXP<4>")
	)
	(segment
		(start 98.044 -105.612438)
		(end 92.480892 -106.724958)
		(width 0.1143)
		(layer "In9.Cu")
		(net "P3E_CPU1_PE3_MP_TXP<4>")
	)
	(segment
		(start 135.48233 -102.827836)
		(end 135.521954 -102.89667)
		(width 0.0889)
		(layer "In9.Cu")
		(net "P3E_CPU1_PE3_MP_TXP<4>")
	)
	(segment
		(start 62.910974 -55.943246)
		(end 56.61787 -46.504606)
		(width 0.1143)
		(layer "In9.Cu")
		(net "P3E_CPU1_PE3_MP_TXP<4>")
	)
	(segment
		(start 135.953754 -100.481638)
		(end 135.953754 -100.819712)
		(width 0.0889)
		(layer "In9.Cu")
		(net "P3E_CPU1_PE3_MP_TXP<4>")
	)
	(segment
		(start 69.62648 -105.49763)
		(end 66.23431 -103.237284)
		(width 0.1143)
		(layer "In9.Cu")
		(net "P3E_CPU1_PE3_MP_TXP<4>")
	)
	(segment
		(start 65.254632 -101.768148)
		(end 62.786514 -89.4207)
		(width 0.1143)
		(layer "In9.Cu")
		(net "P3E_CPU1_PE3_MP_TXP<4>")
	)
	(segment
		(start 40.971216 -36.069016)
		(end 38.810692 -33.908492)
		(width 0.1143)
		(layer "In9.Cu")
		(net "P3E_CPU1_PE3_MP_TXP<4>")
	)
	(segment
		(start 62.832488 -64.68237)
		(end 63.746126 -60.114688)
		(width 0.1143)
		(layer "In9.Cu")
		(net "P3E_CPU1_PE3_MP_TXP<4>")
	)
	(segment
		(start 132.90042 -105.767886)
		(end 132.371338 -105.767886)
		(width 0.0889)
		(layer "In9.Cu")
		(net "P3E_CPU1_PE3_MP_TXP<4>")
	)
	(segment
		(start 130.265424 -105.717086)
		(end 128.099312 -105.284016)
		(width 0.1143)
		(layer "In9.Cu")
		(net "P3E_CPU1_PE3_MP_TXP<4>")
	)
	(segment
		(start 16.73225 -30.65145)
		(end 16.61287 -30.53207)
		(width 0.1143)
		(layer "In9.Cu")
		(net "P3E_CPU1_PE3_MP_TXP<4>")
	)
	(segment
		(start 135.44677 -102.1588)
		(end 135.441944 -102.167436)
		(width 0.0889)
		(layer "In9.Cu")
		(net "P3E_CPU1_PE3_MP_TXP<4>")
	)
	(segment
		(start 66.23431 -103.237284)
		(end 65.254632 -101.768148)
		(width 0.1143)
		(layer "In9.Cu")
		(net "P3E_CPU1_PE3_MP_TXP<4>")
	)
	(segment
		(start 135.481822 -102.827074)
		(end 135.48233 -102.827836)
		(width 0.0889)
		(layer "In9.Cu")
		(net "P3E_CPU1_PE3_MP_TXP<4>")
	)
	(segment
		(start 23.295864 -29.792676)
		(end 19.439382 -29.802074)
		(width 0.1143)
		(layer "In9.Cu")
		(net "P3E_CPU1_PE3_MP_TXP<4>")
	)
	(segment
		(start 32.079692 -31.121858)
		(end 27.952446 -30.296358)
		(width 0.1143)
		(layer "In9.Cu")
		(net "P3E_CPU1_PE3_MP_TXP<4>")
	)
	(segment
		(start 92.480892 -106.724958)
		(end 83.599274 -104.948482)
		(width 0.1143)
		(layer "In9.Cu")
		(net "P3E_CPU1_PE3_MP_TXP<4>")
	)
	(segment
		(start 16.61287 -30.53207)
		(end 16.61287 -30.15742)
		(width 0.1143)
		(layer "In9.Cu")
		(net "P3E_CPU1_PE3_MP_TXP<4>")
	)
	(segment
		(start 110.277148 -106.645456)
		(end 106.742484 -107.352592)
		(width 0.1143)
		(layer "In9.Cu")
		(net "P3E_CPU1_PE3_MP_TXP<4>")
	)
	(segment
		(start 27.952446 -30.296358)
		(end 27.183334 -29.783532)
		(width 0.1143)
		(layer "In9.Cu")
		(net "P3E_CPU1_PE3_MP_TXP<4>")
	)
	(segment
		(start 62.786514 -89.4207)
		(end 65.28308 -76.936854)
		(width 0.1143)
		(layer "In9.Cu")
		(net "P3E_CPU1_PE3_MP_TXP<4>")
	)
	(segment
		(start 115.783868 -107.747054)
		(end 110.277148 -106.645456)
		(width 0.1143)
		(layer "In9.Cu")
		(net "P3E_CPU1_PE3_MP_TXP<4>")
	)
	(segment
		(start 135.441944 -102.167436)
		(end 135.435594 -102.178104)
		(width 0.0889)
		(layer "In9.Cu")
		(net "P3E_CPU1_PE3_MP_TXP<4>")
	)
	(segment
		(start 135.521954 -102.89667)
		(end 135.521954 -103.146352)
		(width 0.0889)
		(layer "In9.Cu")
		(net "P3E_CPU1_PE3_MP_TXP<4>")
	)
	(arc
		(start 135.868156 -100.887022)
		(mid 135.421849 -101.214266)
		(end 135.441944 -101.767386)
		(width 0.0889)
		(layer "In9.Cu")
		(net "P3E_CPU1_PE3_MP_TXP<4>")
	)
	(arc
		(start 135.435594 -102.178104)
		(mid 135.362796 -102.468867)
		(end 135.441944 -102.757986)
		(width 0.0889)
		(layer "In9.Cu")
		(net "P3E_CPU1_PE3_MP_TXP<4>")
	)
	(arc
		(start 135.441944 -101.767386)
		(mid 135.495414 -101.962449)
		(end 135.44677 -102.1588)
		(width 0.0889)
		(layer "In9.Cu")
		(net "P3E_CPU1_PE3_MP_TXP<4>")
	)
	(arc
		(start 135.888984 -100.884482)
		(mid 135.878559 -100.885661)
		(end 135.868156 -100.887022)
		(width 0.0889)
		(layer "In9.Cu")
		(net "P3E_CPU1_PE3_MP_TXP<4>")
	)
	(segment
		(start 15.4178 -29.25445)
		(end 15.4178 -29.6545)
		(width 0.1143)
		(layer "F.Cu")
		(net "P3E_CPU1_PE3_MP_TXP<3>")
	)
	(segment
		(start 15.109952 -29.136848)
		(end 15.300198 -29.136848)
		(width 0.1143)
		(layer "F.Cu")
		(net "P3E_CPU1_PE3_MP_TXP<3>")
	)
	(segment
		(start 14.7828 -29.464)
		(end 15.109952 -29.136848)
		(width 0.1143)
		(layer "F.Cu")
		(net "P3E_CPU1_PE3_MP_TXP<3>")
	)
	(segment
		(start 15.300198 -29.136848)
		(end 15.4178 -29.25445)
		(width 0.1143)
		(layer "F.Cu")
		(net "P3E_CPU1_PE3_MP_TXP<3>")
	)
	(segment
		(start 134.523734 -100.976684)
		(end 135.095234 -100.976684)
		(width 0.1143)
		(layer "F.Cu")
		(net "P3E_CPU1_PE3_MP_TXP<3>")
	)
	(via
		(at 15.4178 -29.6545)
		(size 0.508)
		(drill 0.254)
		(layers "F.Cu" "B.Cu")
		(net "P3E_CPU1_PE3_MP_TXP<3>")
	)
	(via
		(at 135.095234 -100.976684)
		(size 0.508)
		(drill 0.254)
		(layers "F.Cu" "B.Cu")
		(net "P3E_CPU1_PE3_MP_TXP<3>")
	)
	(segment
		(start 134.743698 -102.1588)
		(end 134.754874 -102.178866)
		(width 0.0889)
		(layer "In9.Cu")
		(net "P3E_CPU1_PE3_MP_TXP<3>")
	)
	(segment
		(start 63.146432 -89.433146)
		(end 65.650364 -76.91247)
		(width 0.1143)
		(layer "In9.Cu")
		(net "P3E_CPU1_PE3_MP_TXP<3>")
	)
	(segment
		(start 135.095234 -100.976684)
		(end 134.802118 -100.807774)
		(width 0.0889)
		(layer "In9.Cu")
		(net "P3E_CPU1_PE3_MP_TXP<3>")
	)
	(segment
		(start 130.171444 -105.28935)
		(end 130.165856 -105.283762)
		(width 0.1143)
		(layer "In9.Cu")
		(net "P3E_CPU1_PE3_MP_TXP<3>")
	)
	(segment
		(start 64.139572 -60.01766)
		(end 64.139826 -60.01766)
		(width 0.1143)
		(layer "In9.Cu")
		(net "P3E_CPU1_PE3_MP_TXP<3>")
	)
	(segment
		(start 56.696864 -45.951394)
		(end 41.57853 -35.870388)
		(width 0.1143)
		(layer "In9.Cu")
		(net "P3E_CPU1_PE3_MP_TXP<3>")
	)
	(segment
		(start 106.742484 -106.978196)
		(end 98.044 -105.238042)
		(width 0.1143)
		(layer "In9.Cu")
		(net "P3E_CPU1_PE3_MP_TXP<3>")
	)
	(segment
		(start 134.754874 -102.178866)
		(end 134.755636 -102.180136)
		(width 0.0889)
		(layer "In9.Cu")
		(net "P3E_CPU1_PE3_MP_TXP<3>")
	)
	(segment
		(start 128.154684 -104.882188)
		(end 116.019072 -107.309412)
		(width 0.1143)
		(layer "In9.Cu")
		(net "P3E_CPU1_PE3_MP_TXP<3>")
	)
	(segment
		(start 17.945354 -29.153104)
		(end 15.544546 -29.153104)
		(width 0.1143)
		(layer "In9.Cu")
		(net "P3E_CPU1_PE3_MP_TXP<3>")
	)
	(segment
		(start 116.019072 -107.309412)
		(end 110.554008 -106.215942)
		(width 0.1143)
		(layer "In9.Cu")
		(net "P3E_CPU1_PE3_MP_TXP<3>")
	)
	(segment
		(start 132.854446 -105.23855)
		(end 132.120132 -105.23855)
		(width 0.0889)
		(layer "In9.Cu")
		(net "P3E_CPU1_PE3_MP_TXP<3>")
	)
	(segment
		(start 65.543176 -101.419914)
		(end 63.146432 -89.433146)
		(width 0.1143)
		(layer "In9.Cu")
		(net "P3E_CPU1_PE3_MP_TXP<3>")
	)
	(segment
		(start 134.748524 -102.757732)
		(end 134.61238 -102.993444)
		(width 0.0889)
		(layer "In9.Cu")
		(net "P3E_CPU1_PE3_MP_TXP<3>")
	)
	(segment
		(start 83.65871 -104.586024)
		(end 75.253088 -106.26725)
		(width 0.1143)
		(layer "In9.Cu")
		(net "P3E_CPU1_PE3_MP_TXP<3>")
	)
	(segment
		(start 98.044 -105.238042)
		(end 92.480892 -106.350562)
		(width 0.1143)
		(layer "In9.Cu")
		(net "P3E_CPU1_PE3_MP_TXP<3>")
	)
	(segment
		(start 63.3095 -55.86984)
		(end 56.696864 -45.951394)
		(width 0.1143)
		(layer "In9.Cu")
		(net "P3E_CPU1_PE3_MP_TXP<3>")
	)
	(segment
		(start 130.165856 -105.283762)
		(end 128.154684 -104.882188)
		(width 0.1143)
		(layer "In9.Cu")
		(net "P3E_CPU1_PE3_MP_TXP<3>")
	)
	(segment
		(start 63.205868 -64.687704)
		(end 64.139572 -60.01766)
		(width 0.1143)
		(layer "In9.Cu")
		(net "P3E_CPU1_PE3_MP_TXP<3>")
	)
	(segment
		(start 41.57853 -35.870388)
		(end 39.285672 -33.577784)
		(width 0.1143)
		(layer "In9.Cu")
		(net "P3E_CPU1_PE3_MP_TXP<3>")
	)
	(segment
		(start 29.27604 -29.431742)
		(end 18.617946 -29.431742)
		(width 0.1143)
		(layer "In9.Cu")
		(net "P3E_CPU1_PE3_MP_TXP<3>")
	)
	(segment
		(start 132.069332 -105.28935)
		(end 132.047234 -105.28935)
		(width 0.0889)
		(layer "In9.Cu")
		(net "P3E_CPU1_PE3_MP_TXP<3>")
	)
	(segment
		(start 92.480892 -106.350562)
		(end 83.65871 -104.586024)
		(width 0.1143)
		(layer "In9.Cu")
		(net "P3E_CPU1_PE3_MP_TXP<3>")
	)
	(segment
		(start 110.554008 -106.215942)
		(end 106.742484 -106.978196)
		(width 0.1143)
		(layer "In9.Cu")
		(net "P3E_CPU1_PE3_MP_TXP<3>")
	)
	(segment
		(start 132.047234 -105.28935)
		(end 130.171444 -105.28935)
		(width 0.1143)
		(layer "In9.Cu")
		(net "P3E_CPU1_PE3_MP_TXP<3>")
	)
	(segment
		(start 65.650364 -76.91247)
		(end 63.205868 -64.687704)
		(width 0.1143)
		(layer "In9.Cu")
		(net "P3E_CPU1_PE3_MP_TXP<3>")
	)
	(segment
		(start 15.544546 -29.153104)
		(end 15.4178 -29.27985)
		(width 0.1143)
		(layer "In9.Cu")
		(net "P3E_CPU1_PE3_MP_TXP<3>")
	)
	(segment
		(start 75.253088 -106.26725)
		(end 69.854318 -105.187496)
		(width 0.1143)
		(layer "In9.Cu")
		(net "P3E_CPU1_PE3_MP_TXP<3>")
	)
	(segment
		(start 18.617946 -29.431742)
		(end 17.945354 -29.153104)
		(width 0.1143)
		(layer "In9.Cu")
		(net "P3E_CPU1_PE3_MP_TXP<3>")
	)
	(segment
		(start 134.61238 -102.993444)
		(end 134.61238 -103.480616)
		(width 0.0889)
		(layer "In9.Cu")
		(net "P3E_CPU1_PE3_MP_TXP<3>")
	)
	(segment
		(start 15.4178 -29.27985)
		(end 15.4178 -29.6545)
		(width 0.1143)
		(layer "In9.Cu")
		(net "P3E_CPU1_PE3_MP_TXP<3>")
	)
	(segment
		(start 39.285672 -33.577784)
		(end 29.27604 -29.431742)
		(width 0.1143)
		(layer "In9.Cu")
		(net "P3E_CPU1_PE3_MP_TXP<3>")
	)
	(segment
		(start 134.802118 -100.807774)
		(end 134.723378 -100.82911)
		(width 0.0889)
		(layer "In9.Cu")
		(net "P3E_CPU1_PE3_MP_TXP<3>")
	)
	(segment
		(start 132.120132 -105.23855)
		(end 132.069332 -105.28935)
		(width 0.0889)
		(layer "In9.Cu")
		(net "P3E_CPU1_PE3_MP_TXP<3>")
	)
	(segment
		(start 66.616072 -103.030274)
		(end 65.543176 -101.419914)
		(width 0.1143)
		(layer "In9.Cu")
		(net "P3E_CPU1_PE3_MP_TXP<3>")
	)
	(segment
		(start 64.139826 -60.01766)
		(end 63.3095 -55.86984)
		(width 0.1143)
		(layer "In9.Cu")
		(net "P3E_CPU1_PE3_MP_TXP<3>")
	)
	(segment
		(start 134.61238 -103.480616)
		(end 132.854446 -105.23855)
		(width 0.0889)
		(layer "In9.Cu")
		(net "P3E_CPU1_PE3_MP_TXP<3>")
	)
	(segment
		(start 69.854318 -105.187496)
		(end 66.616072 -103.030274)
		(width 0.1143)
		(layer "In9.Cu")
		(net "P3E_CPU1_PE3_MP_TXP<3>")
	)
	(arc
		(start 134.755636 -102.180136)
		(mid 134.82748 -102.469862)
		(end 134.748524 -102.757732)
		(width 0.0889)
		(layer "In9.Cu")
		(net "P3E_CPU1_PE3_MP_TXP<3>")
	)
	(arc
		(start 134.748524 -101.767386)
		(mid 134.695054 -101.962449)
		(end 134.743698 -102.1588)
		(width 0.0889)
		(layer "In9.Cu")
		(net "P3E_CPU1_PE3_MP_TXP<3>")
	)
	(arc
		(start 134.723378 -100.82911)
		(mid 134.696109 -101.005739)
		(end 134.748524 -101.176582)
		(width 0.0889)
		(layer "In9.Cu")
		(net "P3E_CPU1_PE3_MP_TXP<3>")
	)
	(arc
		(start 134.748524 -101.176582)
		(mid 134.827655 -101.471984)
		(end 134.748524 -101.767386)
		(width 0.0889)
		(layer "In9.Cu")
		(net "P3E_CPU1_PE3_MP_TXP<3>")
	)
	(segment
		(start 15.10665 -27.36215)
		(end 14.7828 -27.686)
		(width 0.1143)
		(layer "F.Cu")
		(net "P3E_CPU1_PE3_MP_TXP<2>")
	)
	(segment
		(start 16.607536 -27.8765)
		(end 16.607536 -27.630882)
		(width 0.1143)
		(layer "F.Cu")
		(net "P3E_CPU1_PE3_MP_TXP<2>")
	)
	(segment
		(start 16.607536 -27.630882)
		(end 16.338804 -27.36215)
		(width 0.1143)
		(layer "F.Cu")
		(net "P3E_CPU1_PE3_MP_TXP<2>")
	)
	(segment
		(start 16.338804 -27.36215)
		(end 15.10665 -27.36215)
		(width 0.1143)
		(layer "F.Cu")
		(net "P3E_CPU1_PE3_MP_TXP<2>")
	)
	(segment
		(start 133.665214 -101.471984)
		(end 134.236714 -101.471984)
		(width 0.1143)
		(layer "F.Cu")
		(net "P3E_CPU1_PE3_MP_TXP<2>")
	)
	(via
		(at 134.236714 -101.471984)
		(size 0.508)
		(drill 0.254)
		(layers "F.Cu" "B.Cu")
		(net "P3E_CPU1_PE3_MP_TXP<2>")
	)
	(via
		(at 16.607536 -27.8765)
		(size 0.508)
		(drill 0.254)
		(layers "F.Cu" "B.Cu")
		(net "P3E_CPU1_PE3_MP_TXP<2>")
	)
	(segment
		(start 44.456096 -36.95827)
		(end 38.404038 -31.995872)
		(width 0.1143)
		(layer "In9.Cu")
		(net "P3E_CPU1_PE3_MP_TXP<2>")
	)
	(segment
		(start 116.379752 -106.53903)
		(end 110.94212 -105.451402)
		(width 0.1143)
		(layer "In9.Cu")
		(net "P3E_CPU1_PE3_MP_TXP<2>")
	)
	(segment
		(start 92.356686 -105.639108)
		(end 83.751166 -103.918004)
		(width 0.1143)
		(layer "In9.Cu")
		(net "P3E_CPU1_PE3_MP_TXP<2>")
	)
	(segment
		(start 134.236714 -101.471984)
		(end 133.943598 -101.641148)
		(width 0.0889)
		(layer "In9.Cu")
		(net "P3E_CPU1_PE3_MP_TXP<2>")
	)
	(segment
		(start 75.963018 -105.475532)
		(end 69.66585 -104.216454)
		(width 0.1143)
		(layer "In9.Cu")
		(net "P3E_CPU1_PE3_MP_TXP<2>")
	)
	(segment
		(start 67.0433 -102.468934)
		(end 66.19367 -101.1936)
		(width 0.1143)
		(layer "In9.Cu")
		(net "P3E_CPU1_PE3_MP_TXP<2>")
	)
	(segment
		(start 130.179318 -104.509824)
		(end 130.128518 -104.560624)
		(width 0.0889)
		(layer "In9.Cu")
		(net "P3E_CPU1_PE3_MP_TXP<2>")
	)
	(segment
		(start 19.153124 -27.96794)
		(end 17.831308 -27.96794)
		(width 0.1143)
		(layer "In9.Cu")
		(net "P3E_CPU1_PE3_MP_TXP<2>")
	)
	(segment
		(start 17.380204 -27.516074)
		(end 17.069562 -27.38755)
		(width 0.1143)
		(layer "In9.Cu")
		(net "P3E_CPU1_PE3_MP_TXP<2>")
	)
	(segment
		(start 110.94212 -105.451402)
		(end 106.74223 -106.291634)
		(width 0.1143)
		(layer "In9.Cu")
		(net "P3E_CPU1_PE3_MP_TXP<2>")
	)
	(segment
		(start 66.19367 -101.1936)
		(end 63.819532 -89.319608)
		(width 0.1143)
		(layer "In9.Cu")
		(net "P3E_CPU1_PE3_MP_TXP<2>")
	)
	(segment
		(start 50.850038 -41.222422)
		(end 50.850038 -41.222168)
		(width 0.1143)
		(layer "In9.Cu")
		(net "P3E_CPU1_PE3_MP_TXP<2>")
	)
	(segment
		(start 133.943598 -101.641148)
		(end 133.919722 -101.730556)
		(width 0.0889)
		(layer "In9.Cu")
		(net "P3E_CPU1_PE3_MP_TXP<2>")
	)
	(segment
		(start 57.244234 -45.486828)
		(end 50.850038 -41.222422)
		(width 0.1143)
		(layer "In9.Cu")
		(net "P3E_CPU1_PE3_MP_TXP<2>")
	)
	(segment
		(start 132.665216 -104.509824)
		(end 130.179318 -104.509824)
		(width 0.0889)
		(layer "In9.Cu")
		(net "P3E_CPU1_PE3_MP_TXP<2>")
	)
	(segment
		(start 27.984704 -27.67965)
		(end 19.441414 -27.67965)
		(width 0.1143)
		(layer "In9.Cu")
		(net "P3E_CPU1_PE3_MP_TXP<2>")
	)
	(segment
		(start 133.890004 -102.662736)
		(end 133.9723 -102.805484)
		(width 0.0889)
		(layer "In9.Cu")
		(net "P3E_CPU1_PE3_MP_TXP<2>")
	)
	(segment
		(start 130.10642 -104.560624)
		(end 129.83337 -104.560624)
		(width 0.1143)
		(layer "In9.Cu")
		(net "P3E_CPU1_PE3_MP_TXP<2>")
	)
	(segment
		(start 133.9723 -103.20274)
		(end 132.665216 -104.509824)
		(width 0.0889)
		(layer "In9.Cu")
		(net "P3E_CPU1_PE3_MP_TXP<2>")
	)
	(segment
		(start 69.66585 -104.216454)
		(end 67.0433 -102.468934)
		(width 0.1143)
		(layer "In9.Cu")
		(net "P3E_CPU1_PE3_MP_TXP<2>")
	)
	(segment
		(start 63.951104 -55.54599)
		(end 57.244234 -45.486828)
		(width 0.1143)
		(layer "In9.Cu")
		(net "P3E_CPU1_PE3_MP_TXP<2>")
	)
	(segment
		(start 66.300858 -76.911708)
		(end 63.874396 -64.778128)
		(width 0.1143)
		(layer "In9.Cu")
		(net "P3E_CPU1_PE3_MP_TXP<2>")
	)
	(segment
		(start 63.819532 -89.319608)
		(end 66.300858 -76.911708)
		(width 0.1143)
		(layer "In9.Cu")
		(net "P3E_CPU1_PE3_MP_TXP<2>")
	)
	(segment
		(start 83.751166 -103.918004)
		(end 75.963018 -105.475532)
		(width 0.1143)
		(layer "In9.Cu")
		(net "P3E_CPU1_PE3_MP_TXP<2>")
	)
	(segment
		(start 133.896354 -102.252018)
		(end 133.890004 -102.262686)
		(width 0.0889)
		(layer "In9.Cu")
		(net "P3E_CPU1_PE3_MP_TXP<2>")
	)
	(segment
		(start 128.0668 -104.201722)
		(end 116.379752 -106.53903)
		(width 0.1143)
		(layer "In9.Cu")
		(net "P3E_CPU1_PE3_MP_TXP<2>")
	)
	(segment
		(start 133.9723 -102.805484)
		(end 133.9723 -103.20274)
		(width 0.0889)
		(layer "In9.Cu")
		(net "P3E_CPU1_PE3_MP_TXP<2>")
	)
	(segment
		(start 97.91954 -104.526588)
		(end 92.356686 -105.639108)
		(width 0.1143)
		(layer "In9.Cu")
		(net "P3E_CPU1_PE3_MP_TXP<2>")
	)
	(segment
		(start 130.128518 -104.560624)
		(end 130.10642 -104.560624)
		(width 0.0889)
		(layer "In9.Cu")
		(net "P3E_CPU1_PE3_MP_TXP<2>")
	)
	(segment
		(start 16.607536 -27.50185)
		(end 16.607536 -27.8765)
		(width 0.1143)
		(layer "In9.Cu")
		(net "P3E_CPU1_PE3_MP_TXP<2>")
	)
	(segment
		(start 64.83604 -59.9694)
		(end 63.951104 -55.54599)
		(width 0.1143)
		(layer "In9.Cu")
		(net "P3E_CPU1_PE3_MP_TXP<2>")
	)
	(segment
		(start 19.441414 -27.67965)
		(end 19.153124 -27.96794)
		(width 0.1143)
		(layer "In9.Cu")
		(net "P3E_CPU1_PE3_MP_TXP<2>")
	)
	(segment
		(start 133.890004 -102.262686)
		(end 133.885178 -102.271322)
		(width 0.0889)
		(layer "In9.Cu")
		(net "P3E_CPU1_PE3_MP_TXP<2>")
	)
	(segment
		(start 38.404038 -31.995872)
		(end 27.984704 -27.67965)
		(width 0.1143)
		(layer "In9.Cu")
		(net "P3E_CPU1_PE3_MP_TXP<2>")
	)
	(segment
		(start 106.74223 -106.291634)
		(end 97.91954 -104.526588)
		(width 0.1143)
		(layer "In9.Cu")
		(net "P3E_CPU1_PE3_MP_TXP<2>")
	)
	(segment
		(start 50.850038 -41.222168)
		(end 44.456096 -36.95827)
		(width 0.1143)
		(layer "In9.Cu")
		(net "P3E_CPU1_PE3_MP_TXP<2>")
	)
	(segment
		(start 17.069562 -27.38755)
		(end 16.721836 -27.38755)
		(width 0.1143)
		(layer "In9.Cu")
		(net "P3E_CPU1_PE3_MP_TXP<2>")
	)
	(segment
		(start 129.83337 -104.560624)
		(end 128.0668 -104.201722)
		(width 0.1143)
		(layer "In9.Cu")
		(net "P3E_CPU1_PE3_MP_TXP<2>")
	)
	(segment
		(start 63.874396 -64.778128)
		(end 64.83604 -59.9694)
		(width 0.1143)
		(layer "In9.Cu")
		(net "P3E_CPU1_PE3_MP_TXP<2>")
	)
	(segment
		(start 17.831308 -27.96794)
		(end 17.380204 -27.516074)
		(width 0.1143)
		(layer "In9.Cu")
		(net "P3E_CPU1_PE3_MP_TXP<2>")
	)
	(segment
		(start 16.721836 -27.38755)
		(end 16.607536 -27.50185)
		(width 0.1143)
		(layer "In9.Cu")
		(net "P3E_CPU1_PE3_MP_TXP<2>")
	)
	(arc
		(start 133.885178 -102.271322)
		(mid 133.836423 -102.467674)
		(end 133.890004 -102.662736)
		(width 0.0889)
		(layer "In9.Cu")
		(net "P3E_CPU1_PE3_MP_TXP<2>")
	)
	(arc
		(start 133.919722 -101.730556)
		(mid 133.968734 -101.994005)
		(end 133.896354 -102.252018)
		(width 0.0889)
		(layer "In9.Cu")
		(net "P3E_CPU1_PE3_MP_TXP<2>")
	)
	(segment
		(start 15.451074 -25.22855)
		(end 15.443454 -24.8285)
		(width 0.1143)
		(layer "F.Cu")
		(net "P3E_CPU1_PE3_MP_TXP<1>")
	)
	(segment
		(start 14.7828 -25.019)
		(end 15.088616 -25.324816)
		(width 0.1143)
		(layer "F.Cu")
		(net "P3E_CPU1_PE3_MP_TXP<1>")
	)
	(segment
		(start 15.088616 -25.324816)
		(end 15.354808 -25.324816)
		(width 0.1143)
		(layer "F.Cu")
		(net "P3E_CPU1_PE3_MP_TXP<1>")
	)
	(segment
		(start 131.948174 -102.462584)
		(end 132.519674 -102.462584)
		(width 0.1143)
		(layer "F.Cu")
		(net "P3E_CPU1_PE3_MP_TXP<1>")
	)
	(segment
		(start 15.354808 -25.324816)
		(end 15.451074 -25.22855)
		(width 0.1143)
		(layer "F.Cu")
		(net "P3E_CPU1_PE3_MP_TXP<1>")
	)
	(via
		(at 15.443454 -24.8285)
		(size 0.508)
		(drill 0.254)
		(layers "F.Cu" "B.Cu")
		(net "P3E_CPU1_PE3_MP_TXP<1>")
	)
	(via
		(at 132.519674 -102.462584)
		(size 0.508)
		(drill 0.254)
		(layers "F.Cu" "B.Cu")
		(net "P3E_CPU1_PE3_MP_TXP<1>")
	)
	(segment
		(start 67.634358 -101.66731)
		(end 67.096132 -100.859844)
		(width 0.1143)
		(layer "In9.Cu")
		(net "P3E_CPU1_PE3_MP_TXP<1>")
	)
	(segment
		(start 131.684522 -103.572818)
		(end 131.506722 -103.572818)
		(width 0.0889)
		(layer "In9.Cu")
		(net "P3E_CPU1_PE3_MP_TXP<1>")
	)
	(segment
		(start 132.074412 -103.411274)
		(end 132.074412 -103.533448)
		(width 0.0889)
		(layer "In9.Cu")
		(net "P3E_CPU1_PE3_MP_TXP<1>")
	)
	(segment
		(start 116.70538 -105.498138)
		(end 111.34217 -104.425496)
		(width 0.1143)
		(layer "In9.Cu")
		(net "P3E_CPU1_PE3_MP_TXP<1>")
	)
	(segment
		(start 64.833246 -55.091584)
		(end 57.785254 -44.520358)
		(width 0.1143)
		(layer "In9.Cu")
		(net "P3E_CPU1_PE3_MP_TXP<1>")
	)
	(segment
		(start 130.978402 -103.572818)
		(end 130.892042 -103.659178)
		(width 0.0889)
		(layer "In9.Cu")
		(net "P3E_CPU1_PE3_MP_TXP<1>")
	)
	(segment
		(start 83.748626 -102.971854)
		(end 76.152248 -104.491028)
		(width 0.1143)
		(layer "In9.Cu")
		(net "P3E_CPU1_PE3_MP_TXP<1>")
	)
	(segment
		(start 130.892042 -103.659178)
		(end 130.398266 -103.659178)
		(width 0.0889)
		(layer "In9.Cu")
		(net "P3E_CPU1_PE3_MP_TXP<1>")
	)
	(segment
		(start 67.096132 -100.859844)
		(end 67.096132 -100.859336)
		(width 0.1143)
		(layer "In9.Cu")
		(net "P3E_CPU1_PE3_MP_TXP<1>")
	)
	(segment
		(start 132.519674 -102.462584)
		(end 132.789422 -102.61854)
		(width 0.0889)
		(layer "In9.Cu")
		(net "P3E_CPU1_PE3_MP_TXP<1>")
	)
	(segment
		(start 130.347466 -103.608378)
		(end 130.325368 -103.608378)
		(width 0.0889)
		(layer "In9.Cu")
		(net "P3E_CPU1_PE3_MP_TXP<1>")
	)
	(segment
		(start 64.821308 -64.771524)
		(end 65.795398 -59.901582)
		(width 0.1143)
		(layer "In9.Cu")
		(net "P3E_CPU1_PE3_MP_TXP<1>")
	)
	(segment
		(start 32.490664 -26.326084)
		(end 27.336496 -25.29459)
		(width 0.1143)
		(layer "In9.Cu")
		(net "P3E_CPU1_PE3_MP_TXP<1>")
	)
	(segment
		(start 131.770882 -103.659178)
		(end 131.684522 -103.572818)
		(width 0.0889)
		(layer "In9.Cu")
		(net "P3E_CPU1_PE3_MP_TXP<1>")
	)
	(segment
		(start 132.074412 -103.533448)
		(end 131.948682 -103.659178)
		(width 0.0889)
		(layer "In9.Cu")
		(net "P3E_CPU1_PE3_MP_TXP<1>")
	)
	(segment
		(start 131.242562 -103.659178)
		(end 131.156202 -103.572818)
		(width 0.0889)
		(layer "In9.Cu")
		(net "P3E_CPU1_PE3_MP_TXP<1>")
	)
	(segment
		(start 64.78016 -89.281762)
		(end 67.25158 -76.924408)
		(width 0.1143)
		(layer "In9.Cu")
		(net "P3E_CPU1_PE3_MP_TXP<1>")
	)
	(segment
		(start 44.416218 -34.284412)
		(end 32.490664 -26.326084)
		(width 0.1143)
		(layer "In9.Cu")
		(net "P3E_CPU1_PE3_MP_TXP<1>")
	)
	(segment
		(start 76.152248 -104.491028)
		(end 70.03542 -103.267764)
		(width 0.1143)
		(layer "In9.Cu")
		(net "P3E_CPU1_PE3_MP_TXP<1>")
	)
	(segment
		(start 129.902966 -103.608378)
		(end 128.030986 -103.232712)
		(width 0.1143)
		(layer "In9.Cu")
		(net "P3E_CPU1_PE3_MP_TXP<1>")
	)
	(segment
		(start 131.420362 -103.659178)
		(end 131.242562 -103.659178)
		(width 0.0889)
		(layer "In9.Cu")
		(net "P3E_CPU1_PE3_MP_TXP<1>")
	)
	(segment
		(start 70.03542 -103.267764)
		(end 67.634358 -101.66731)
		(width 0.1143)
		(layer "In9.Cu")
		(net "P3E_CPU1_PE3_MP_TXP<1>")
	)
	(segment
		(start 92.356686 -104.693466)
		(end 83.748626 -102.971854)
		(width 0.1143)
		(layer "In9.Cu")
		(net "P3E_CPU1_PE3_MP_TXP<1>")
	)
	(segment
		(start 98.173286 -103.530146)
		(end 92.356686 -104.693466)
		(width 0.1143)
		(layer "In9.Cu")
		(net "P3E_CPU1_PE3_MP_TXP<1>")
	)
	(segment
		(start 67.25158 -76.924408)
		(end 64.821308 -64.771524)
		(width 0.1143)
		(layer "In9.Cu")
		(net "P3E_CPU1_PE3_MP_TXP<1>")
	)
	(segment
		(start 46.003464 -36.665154)
		(end 44.416218 -34.284412)
		(width 0.1143)
		(layer "In9.Cu")
		(net "P3E_CPU1_PE3_MP_TXP<1>")
	)
	(segment
		(start 15.450566 -25.181306)
		(end 15.443454 -24.8285)
		(width 0.1143)
		(layer "In9.Cu")
		(net "P3E_CPU1_PE3_MP_TXP<1>")
	)
	(segment
		(start 131.156202 -103.572818)
		(end 130.978402 -103.572818)
		(width 0.0889)
		(layer "In9.Cu")
		(net "P3E_CPU1_PE3_MP_TXP<1>")
	)
	(segment
		(start 132.200142 -103.285544)
		(end 132.074412 -103.411274)
		(width 0.0889)
		(layer "In9.Cu")
		(net "P3E_CPU1_PE3_MP_TXP<1>")
	)
	(segment
		(start 128.030986 -103.232712)
		(end 116.70538 -105.498138)
		(width 0.1143)
		(layer "In9.Cu")
		(net "P3E_CPU1_PE3_MP_TXP<1>")
	)
	(segment
		(start 111.34217 -104.425496)
		(end 106.994706 -105.294938)
		(width 0.1143)
		(layer "In9.Cu")
		(net "P3E_CPU1_PE3_MP_TXP<1>")
	)
	(segment
		(start 132.789422 -102.61854)
		(end 132.82168 -102.739952)
		(width 0.0889)
		(layer "In9.Cu")
		(net "P3E_CPU1_PE3_MP_TXP<1>")
	)
	(segment
		(start 132.758942 -102.848918)
		(end 132.322316 -103.285544)
		(width 0.0889)
		(layer "In9.Cu")
		(net "P3E_CPU1_PE3_MP_TXP<1>")
	)
	(segment
		(start 106.994706 -105.294938)
		(end 98.173286 -103.530146)
		(width 0.1143)
		(layer "In9.Cu")
		(net "P3E_CPU1_PE3_MP_TXP<1>")
	)
	(segment
		(start 130.325368 -103.608378)
		(end 129.902966 -103.608378)
		(width 0.1143)
		(layer "In9.Cu")
		(net "P3E_CPU1_PE3_MP_TXP<1>")
	)
	(segment
		(start 57.785254 -44.520358)
		(end 46.003464 -36.665154)
		(width 0.1143)
		(layer "In9.Cu")
		(net "P3E_CPU1_PE3_MP_TXP<1>")
	)
	(segment
		(start 27.336496 -25.29459)
		(end 15.566136 -25.29459)
		(width 0.1143)
		(layer "In9.Cu")
		(net "P3E_CPU1_PE3_MP_TXP<1>")
	)
	(segment
		(start 132.82168 -102.739952)
		(end 132.758942 -102.848918)
		(width 0.0889)
		(layer "In9.Cu")
		(net "P3E_CPU1_PE3_MP_TXP<1>")
	)
	(segment
		(start 131.948682 -103.659178)
		(end 131.770882 -103.659178)
		(width 0.0889)
		(layer "In9.Cu")
		(net "P3E_CPU1_PE3_MP_TXP<1>")
	)
	(segment
		(start 132.322316 -103.285544)
		(end 132.200142 -103.285544)
		(width 0.0889)
		(layer "In9.Cu")
		(net "P3E_CPU1_PE3_MP_TXP<1>")
	)
	(segment
		(start 131.506722 -103.572818)
		(end 131.420362 -103.659178)
		(width 0.0889)
		(layer "In9.Cu")
		(net "P3E_CPU1_PE3_MP_TXP<1>")
	)
	(segment
		(start 130.398266 -103.659178)
		(end 130.347466 -103.608378)
		(width 0.0889)
		(layer "In9.Cu")
		(net "P3E_CPU1_PE3_MP_TXP<1>")
	)
	(segment
		(start 67.096132 -100.859336)
		(end 64.78016 -89.281762)
		(width 0.1143)
		(layer "In9.Cu")
		(net "P3E_CPU1_PE3_MP_TXP<1>")
	)
	(segment
		(start 15.566136 -25.29459)
		(end 15.450566 -25.181306)
		(width 0.1143)
		(layer "In9.Cu")
		(net "P3E_CPU1_PE3_MP_TXP<1>")
	)
	(segment
		(start 65.795398 -59.901582)
		(end 64.833246 -55.091584)
		(width 0.1143)
		(layer "In9.Cu")
		(net "P3E_CPU1_PE3_MP_TXP<1>")
	)
	(segment
		(start 17.1196 -23.0886)
		(end 17.45615 -23.0886)
		(width 0.1143)
		(layer "F.Cu")
		(net "P3E_CPU1_PE3_MP_TXP<0>")
	)
	(segment
		(start 17.0053 -23.2029)
		(end 17.1196 -23.0886)
		(width 0.1143)
		(layer "F.Cu")
		(net "P3E_CPU1_PE3_MP_TXP<0>")
	)
	(segment
		(start 14.7828 -24.13)
		(end 14.96695 -23.94585)
		(width 0.1143)
		(layer "F.Cu")
		(net "P3E_CPU1_PE3_MP_TXP<0>")
	)
	(segment
		(start 17.0053 -23.574502)
		(end 17.0053 -23.2029)
		(width 0.1143)
		(layer "F.Cu")
		(net "P3E_CPU1_PE3_MP_TXP<0>")
	)
	(segment
		(start 16.633952 -23.94585)
		(end 17.0053 -23.574502)
		(width 0.1143)
		(layer "F.Cu")
		(net "P3E_CPU1_PE3_MP_TXP<0>")
	)
	(segment
		(start 131.089908 -101.967538)
		(end 131.661408 -101.967538)
		(width 0.1143)
		(layer "F.Cu")
		(net "P3E_CPU1_PE3_MP_TXP<0>")
	)
	(segment
		(start 14.96695 -23.94585)
		(end 16.633952 -23.94585)
		(width 0.1143)
		(layer "F.Cu")
		(net "P3E_CPU1_PE3_MP_TXP<0>")
	)
	(via
		(at 17.45615 -23.0886)
		(size 0.508)
		(drill 0.254)
		(layers "F.Cu" "B.Cu")
		(net "P3E_CPU1_PE3_MP_TXP<0>")
	)
	(via
		(at 131.661408 -101.967538)
		(size 0.508)
		(drill 0.254)
		(layers "F.Cu" "B.Cu")
		(net "P3E_CPU1_PE3_MP_TXP<0>")
	)
	(segment
		(start 84.272882 -102.0699)
		(end 76.178918 -103.688642)
		(width 0.1143)
		(layer "In9.Cu")
		(net "P3E_CPU1_PE3_MP_TXP<0>")
	)
	(segment
		(start 46.553882 -36.25215)
		(end 44.857162 -33.707324)
		(width 0.1143)
		(layer "In9.Cu")
		(net "P3E_CPU1_PE3_MP_TXP<0>")
	)
	(segment
		(start 129.381504 -102.367588)
		(end 129.330704 -102.316788)
		(width 0.0889)
		(layer "In9.Cu")
		(net "P3E_CPU1_PE3_MP_TXP<0>")
	)
	(segment
		(start 68.057522 -101.121972)
		(end 67.789298 -100.718874)
		(width 0.1143)
		(layer "In9.Cu")
		(net "P3E_CPU1_PE3_MP_TXP<0>")
	)
	(segment
		(start 66.55689 -60.052204)
		(end 65.537588 -54.955186)
		(width 0.1143)
		(layer "In9.Cu")
		(net "P3E_CPU1_PE3_MP_TXP<0>")
	)
	(segment
		(start 16.9672 -23.2029)
		(end 17.0815 -23.0886)
		(width 0.1143)
		(layer "In9.Cu")
		(net "P3E_CPU1_PE3_MP_TXP<0>")
	)
	(segment
		(start 111.66348 -103.648764)
		(end 106.876596 -104.60609)
		(width 0.1143)
		(layer "In9.Cu")
		(net "P3E_CPU1_PE3_MP_TXP<0>")
	)
	(segment
		(start 44.857162 -33.707324)
		(end 32.949388 -25.76703)
		(width 0.1143)
		(layer "In9.Cu")
		(net "P3E_CPU1_PE3_MP_TXP<0>")
	)
	(segment
		(start 17.279366 -23.676864)
		(end 16.9672 -23.364698)
		(width 0.1143)
		(layer "In9.Cu")
		(net "P3E_CPU1_PE3_MP_TXP<0>")
	)
	(segment
		(start 92.57538 -103.730552)
		(end 84.272882 -102.0699)
		(width 0.1143)
		(layer "In9.Cu")
		(net "P3E_CPU1_PE3_MP_TXP<0>")
	)
	(segment
		(start 117.1448 -104.745282)
		(end 111.66348 -103.648764)
		(width 0.1143)
		(layer "In9.Cu")
		(net "P3E_CPU1_PE3_MP_TXP<0>")
	)
	(segment
		(start 70.078854 -102.46868)
		(end 68.057522 -101.121972)
		(width 0.1143)
		(layer "In9.Cu")
		(net "P3E_CPU1_PE3_MP_TXP<0>")
	)
	(segment
		(start 58.095642 -43.792394)
		(end 46.553882 -36.25215)
		(width 0.1143)
		(layer "In9.Cu")
		(net "P3E_CPU1_PE3_MP_TXP<0>")
	)
	(segment
		(start 65.473834 -89.142316)
		(end 67.921886 -76.89977)
		(width 0.1143)
		(layer "In9.Cu")
		(net "P3E_CPU1_PE3_MP_TXP<0>")
	)
	(segment
		(start 25.845262 -24.3459)
		(end 20.640802 -24.3459)
		(width 0.1143)
		(layer "In9.Cu")
		(net "P3E_CPU1_PE3_MP_TXP<0>")
	)
	(segment
		(start 106.876596 -104.60609)
		(end 97.538794 -102.73792)
		(width 0.1143)
		(layer "In9.Cu")
		(net "P3E_CPU1_PE3_MP_TXP<0>")
	)
	(segment
		(start 131.661408 -101.967538)
		(end 131.661408 -102.305612)
		(width 0.0889)
		(layer "In9.Cu")
		(net "P3E_CPU1_PE3_MP_TXP<0>")
	)
	(segment
		(start 17.0815 -23.0886)
		(end 17.45615 -23.0886)
		(width 0.1143)
		(layer "In9.Cu")
		(net "P3E_CPU1_PE3_MP_TXP<0>")
	)
	(segment
		(start 16.9672 -23.364698)
		(end 16.9672 -23.2029)
		(width 0.1143)
		(layer "In9.Cu")
		(net "P3E_CPU1_PE3_MP_TXP<0>")
	)
	(segment
		(start 65.55486 -65.0621)
		(end 66.55689 -60.052204)
		(width 0.1143)
		(layer "In9.Cu")
		(net "P3E_CPU1_PE3_MP_TXP<0>")
	)
	(segment
		(start 128.733042 -102.316788)
		(end 128.59512 -102.45471)
		(width 0.1143)
		(layer "In9.Cu")
		(net "P3E_CPU1_PE3_MP_TXP<0>")
	)
	(segment
		(start 67.921886 -76.89977)
		(end 65.55486 -65.0621)
		(width 0.1143)
		(layer "In9.Cu")
		(net "P3E_CPU1_PE3_MP_TXP<0>")
	)
	(segment
		(start 131.661408 -102.305612)
		(end 131.603496 -102.363524)
		(width 0.0889)
		(layer "In9.Cu")
		(net "P3E_CPU1_PE3_MP_TXP<0>")
	)
	(segment
		(start 129.944622 -102.367588)
		(end 129.381504 -102.367588)
		(width 0.0889)
		(layer "In9.Cu")
		(net "P3E_CPU1_PE3_MP_TXP<0>")
	)
	(segment
		(start 32.949388 -25.76703)
		(end 25.845262 -24.3459)
		(width 0.1143)
		(layer "In9.Cu")
		(net "P3E_CPU1_PE3_MP_TXP<0>")
	)
	(segment
		(start 129.308606 -102.316788)
		(end 128.733042 -102.316788)
		(width 0.1143)
		(layer "In9.Cu")
		(net "P3E_CPU1_PE3_MP_TXP<0>")
	)
	(segment
		(start 67.789298 -100.718874)
		(end 65.473834 -89.142316)
		(width 0.1143)
		(layer "In9.Cu")
		(net "P3E_CPU1_PE3_MP_TXP<0>")
	)
	(segment
		(start 65.537588 -54.955186)
		(end 58.095642 -43.792394)
		(width 0.1143)
		(layer "In9.Cu")
		(net "P3E_CPU1_PE3_MP_TXP<0>")
	)
	(segment
		(start 97.538794 -102.73792)
		(end 92.57538 -103.730552)
		(width 0.1143)
		(layer "In9.Cu")
		(net "P3E_CPU1_PE3_MP_TXP<0>")
	)
	(segment
		(start 129.330704 -102.316788)
		(end 129.308606 -102.316788)
		(width 0.0889)
		(layer "In9.Cu")
		(net "P3E_CPU1_PE3_MP_TXP<0>")
	)
	(segment
		(start 20.640802 -24.3459)
		(end 17.279366 -23.676864)
		(width 0.1143)
		(layer "In9.Cu")
		(net "P3E_CPU1_PE3_MP_TXP<0>")
	)
	(segment
		(start 76.178918 -103.688642)
		(end 70.078854 -102.46868)
		(width 0.1143)
		(layer "In9.Cu")
		(net "P3E_CPU1_PE3_MP_TXP<0>")
	)
	(segment
		(start 128.59512 -102.45471)
		(end 117.1448 -104.745282)
		(width 0.1143)
		(layer "In9.Cu")
		(net "P3E_CPU1_PE3_MP_TXP<0>")
	)
	(arc
		(start 131.603496 -102.363524)
		(mid 131.436595 -102.298624)
		(end 131.314698 -102.167436)
		(width 0.0889)
		(layer "In9.Cu")
		(net "P3E_CPU1_PE3_MP_TXP<0>")
	)
	(arc
		(start 130.291078 -102.167436)
		(mid 130.144696 -102.314)
		(end 129.944622 -102.367588)
		(width 0.0889)
		(layer "In9.Cu")
		(net "P3E_CPU1_PE3_MP_TXP<0>")
	)
	(arc
		(start 131.314698 -102.167436)
		(mid 130.802888 -101.871642)
		(end 130.291078 -102.167436)
		(width 0.0889)
		(layer "In9.Cu")
		(net "P3E_CPU1_PE3_MP_TXP<0>")
	)
	(segment
		(start 14.7828 -35.687)
		(end 15.10665 -36.01085)
		(width 0.1143)
		(layer "F.Cu")
		(net "P3E_CPU1_PE3_MP_TXN<7>")
	)
	(segment
		(start 15.451074 -35.89655)
		(end 15.451074 -35.4965)
		(width 0.1143)
		(layer "F.Cu")
		(net "P3E_CPU1_PE3_MP_TXN<7>")
	)
	(segment
		(start 15.336774 -36.01085)
		(end 15.451074 -35.89655)
		(width 0.1143)
		(layer "F.Cu")
		(net "P3E_CPU1_PE3_MP_TXN<7>")
	)
	(segment
		(start 136.240774 -98.005138)
		(end 136.812274 -98.005138)
		(width 0.1143)
		(layer "F.Cu")
		(net "P3E_CPU1_PE3_MP_TXN<7>")
	)
	(segment
		(start 15.10665 -36.01085)
		(end 15.336774 -36.01085)
		(width 0.1143)
		(layer "F.Cu")
		(net "P3E_CPU1_PE3_MP_TXN<7>")
	)
	(via
		(at 136.812274 -98.005138)
		(size 0.508)
		(drill 0.254)
		(layers "F.Cu" "B.Cu")
		(net "P3E_CPU1_PE3_MP_TXN<7>")
	)
	(via
		(at 15.451074 -35.4965)
		(size 0.508)
		(drill 0.254)
		(layers "F.Cu" "B.Cu")
		(net "P3E_CPU1_PE3_MP_TXN<7>")
	)
	(segment
		(start 68.757292 -107.32262)
		(end 75.113134 -108.592112)
		(width 0.1143)
		(layer "In9.Cu")
		(net "P3E_CPU1_PE3_MP_TXN<7>")
	)
	(segment
		(start 133.1849 -107.979718)
		(end 133.743192 -107.979718)
		(width 0.0889)
		(layer "In9.Cu")
		(net "P3E_CPU1_PE3_MP_TXN<7>")
	)
	(segment
		(start 136.950958 -104.66197)
		(end 137.06094 -104.66197)
		(width 0.0889)
		(layer "In9.Cu")
		(net "P3E_CPU1_PE3_MP_TXN<7>")
	)
	(segment
		(start 63.2206 -77.216)
		(end 60.707524 -89.782142)
		(width 0.1143)
		(layer "In9.Cu")
		(net "P3E_CPU1_PE3_MP_TXN<7>")
	)
	(segment
		(start 75.113134 -108.592112)
		(end 83.345782 -106.945938)
		(width 0.1143)
		(layer "In9.Cu")
		(net "P3E_CPU1_PE3_MP_TXN<7>")
	)
	(segment
		(start 137.871962 -103.31196)
		(end 137.937748 -103.246174)
		(width 0.0889)
		(layer "In9.Cu")
		(net "P3E_CPU1_PE3_MP_TXN<7>")
	)
	(segment
		(start 137.937748 -103.555546)
		(end 137.871962 -103.48976)
		(width 0.0889)
		(layer "In9.Cu")
		(net "P3E_CPU1_PE3_MP_TXN<7>")
	)
	(segment
		(start 137.438638 -104.284272)
		(end 137.564114 -104.158796)
		(width 0.0889)
		(layer "In9.Cu")
		(net "P3E_CPU1_PE3_MP_TXN<7>")
	)
	(segment
		(start 92.764864 -108.829856)
		(end 97.981262 -107.786678)
		(width 0.1143)
		(layer "In9.Cu")
		(net "P3E_CPU1_PE3_MP_TXN<7>")
	)
	(segment
		(start 137.851388 -102.429056)
		(end 137.851388 -102.251256)
		(width 0.0889)
		(layer "In9.Cu")
		(net "P3E_CPU1_PE3_MP_TXN<7>")
	)
	(segment
		(start 137.564114 -104.158796)
		(end 137.564114 -104.036622)
		(width 0.0889)
		(layer "In9.Cu")
		(net "P3E_CPU1_PE3_MP_TXN<7>")
	)
	(segment
		(start 15.451074 -35.87115)
		(end 15.571216 -35.991292)
		(width 0.1143)
		(layer "In9.Cu")
		(net "P3E_CPU1_PE3_MP_TXN<7>")
	)
	(segment
		(start 41.463468 -38.919658)
		(end 54.953408 -47.919386)
		(width 0.1143)
		(layer "In9.Cu")
		(net "P3E_CPU1_PE3_MP_TXN<7>")
	)
	(segment
		(start 137.690098 -103.910638)
		(end 137.812272 -103.910638)
		(width 0.0889)
		(layer "In9.Cu")
		(net "P3E_CPU1_PE3_MP_TXN<7>")
	)
	(segment
		(start 63.289434 -102.706424)
		(end 64.45504 -104.455468)
		(width 0.1143)
		(layer "In9.Cu")
		(net "P3E_CPU1_PE3_MP_TXN<7>")
	)
	(segment
		(start 137.937748 -103.785162)
		(end 137.937748 -103.555546)
		(width 0.0889)
		(layer "In9.Cu")
		(net "P3E_CPU1_PE3_MP_TXN<7>")
	)
	(segment
		(start 137.18413 -97.85731)
		(end 137.10539 -97.835974)
		(width 0.0889)
		(layer "In9.Cu")
		(net "P3E_CPU1_PE3_MP_TXN<7>")
	)
	(segment
		(start 114.722656 -109.9185)
		(end 127.674878 -107.3277)
		(width 0.1143)
		(layer "In9.Cu")
		(net "P3E_CPU1_PE3_MP_TXN<7>")
	)
	(segment
		(start 29.57576 -35.110166)
		(end 32.513778 -35.886644)
		(width 0.1143)
		(layer "In9.Cu")
		(net "P3E_CPU1_PE3_MP_TXN<7>")
	)
	(segment
		(start 32.847788 -35.999928)
		(end 41.463468 -38.919658)
		(width 0.1143)
		(layer "In9.Cu")
		(net "P3E_CPU1_PE3_MP_TXN<7>")
	)
	(segment
		(start 136.824974 -104.787954)
		(end 136.950958 -104.66197)
		(width 0.0889)
		(layer "In9.Cu")
		(net "P3E_CPU1_PE3_MP_TXN<7>")
	)
	(segment
		(start 138.02233 -99.299522)
		(end 138.017504 -99.290886)
		(width 0.0889)
		(layer "In9.Cu")
		(net "P3E_CPU1_PE3_MP_TXN<7>")
	)
	(segment
		(start 61.038486 -57.04586)
		(end 61.575696 -59.726068)
		(width 0.1143)
		(layer "In9.Cu")
		(net "P3E_CPU1_PE3_MP_TXN<7>")
	)
	(segment
		(start 136.824974 -104.897936)
		(end 136.824974 -104.787954)
		(width 0.0889)
		(layer "In9.Cu")
		(net "P3E_CPU1_PE3_MP_TXN<7>")
	)
	(segment
		(start 137.851388 -102.251256)
		(end 137.937748 -102.164896)
		(width 0.0889)
		(layer "In9.Cu")
		(net "P3E_CPU1_PE3_MP_TXN<7>")
	)
	(segment
		(start 137.10539 -97.835974)
		(end 136.812274 -98.005138)
		(width 0.0889)
		(layer "In9.Cu")
		(net "P3E_CPU1_PE3_MP_TXN<7>")
	)
	(segment
		(start 109.733588 -108.920534)
		(end 114.722656 -109.9185)
		(width 0.1143)
		(layer "In9.Cu")
		(net "P3E_CPU1_PE3_MP_TXN<7>")
	)
	(segment
		(start 137.937748 -103.043736)
		(end 137.851388 -102.957376)
		(width 0.0889)
		(layer "In9.Cu")
		(net "P3E_CPU1_PE3_MP_TXN<7>")
	)
	(segment
		(start 137.937748 -102.693216)
		(end 137.937748 -102.515416)
		(width 0.0889)
		(layer "In9.Cu")
		(net "P3E_CPU1_PE3_MP_TXN<7>")
	)
	(segment
		(start 24.462486 -33.255458)
		(end 25.194768 -33.255458)
		(width 0.1143)
		(layer "In9.Cu")
		(net "P3E_CPU1_PE3_MP_TXN<7>")
	)
	(segment
		(start 137.68197 -99.090734)
		(end 137.649204 -99.090734)
		(width 0.0889)
		(layer "In9.Cu")
		(net "P3E_CPU1_PE3_MP_TXN<7>")
	)
	(segment
		(start 137.871962 -103.48976)
		(end 137.871962 -103.31196)
		(width 0.0889)
		(layer "In9.Cu")
		(net "P3E_CPU1_PE3_MP_TXN<7>")
	)
	(segment
		(start 138.011154 -100.692204)
		(end 138.017504 -100.681536)
		(width 0.0889)
		(layer "In9.Cu")
		(net "P3E_CPU1_PE3_MP_TXN<7>")
	)
	(segment
		(start 83.345782 -106.945938)
		(end 92.764864 -108.829856)
		(width 0.1143)
		(layer "In9.Cu")
		(net "P3E_CPU1_PE3_MP_TXN<7>")
	)
	(segment
		(start 32.847788 -35.999674)
		(end 32.847788 -35.999928)
		(width 0.1143)
		(layer "In9.Cu")
		(net "P3E_CPU1_PE3_MP_TXN<7>")
	)
	(segment
		(start 137.937748 -102.164896)
		(end 137.937748 -101.987096)
		(width 0.0889)
		(layer "In9.Cu")
		(net "P3E_CPU1_PE3_MP_TXN<7>")
	)
	(segment
		(start 18.895314 -35.50158)
		(end 24.462486 -33.255458)
		(width 0.1143)
		(layer "In9.Cu")
		(net "P3E_CPU1_PE3_MP_TXN<7>")
	)
	(segment
		(start 137.937748 -102.515416)
		(end 137.851388 -102.429056)
		(width 0.0889)
		(layer "In9.Cu")
		(net "P3E_CPU1_PE3_MP_TXN<7>")
	)
	(segment
		(start 32.513778 -35.886644)
		(end 32.847788 -35.999674)
		(width 0.1143)
		(layer "In9.Cu")
		(net "P3E_CPU1_PE3_MP_TXN<7>")
	)
	(segment
		(start 137.812272 -103.910638)
		(end 137.937748 -103.785162)
		(width 0.0889)
		(layer "In9.Cu")
		(net "P3E_CPU1_PE3_MP_TXN<7>")
	)
	(segment
		(start 15.451074 -35.4965)
		(end 15.451074 -35.87115)
		(width 0.1143)
		(layer "In9.Cu")
		(net "P3E_CPU1_PE3_MP_TXN<7>")
	)
	(segment
		(start 54.953408 -47.919386)
		(end 61.038486 -57.04586)
		(width 0.1143)
		(layer "In9.Cu")
		(net "P3E_CPU1_PE3_MP_TXN<7>")
	)
	(segment
		(start 60.707524 -89.782142)
		(end 63.289434 -102.706424)
		(width 0.1143)
		(layer "In9.Cu")
		(net "P3E_CPU1_PE3_MP_TXN<7>")
	)
	(segment
		(start 60.64885 -64.358774)
		(end 63.2206 -77.216)
		(width 0.1143)
		(layer "In9.Cu")
		(net "P3E_CPU1_PE3_MP_TXN<7>")
	)
	(segment
		(start 137.06094 -104.66197)
		(end 137.19048 -104.53243)
		(width 0.0889)
		(layer "In9.Cu")
		(net "P3E_CPU1_PE3_MP_TXN<7>")
	)
	(segment
		(start 68.757038 -107.32262)
		(end 68.757292 -107.32262)
		(width 0.1143)
		(layer "In9.Cu")
		(net "P3E_CPU1_PE3_MP_TXN<7>")
	)
	(segment
		(start 25.194768 -33.255458)
		(end 29.57576 -35.110166)
		(width 0.1143)
		(layer "In9.Cu")
		(net "P3E_CPU1_PE3_MP_TXN<7>")
	)
	(segment
		(start 130.680968 -107.928918)
		(end 133.112002 -107.928918)
		(width 0.1143)
		(layer "In9.Cu")
		(net "P3E_CPU1_PE3_MP_TXN<7>")
	)
	(segment
		(start 97.981262 -107.786678)
		(end 106.6927 -109.529118)
		(width 0.1143)
		(layer "In9.Cu")
		(net "P3E_CPU1_PE3_MP_TXN<7>")
	)
	(segment
		(start 137.937748 -103.246174)
		(end 137.937748 -103.043736)
		(width 0.0889)
		(layer "In9.Cu")
		(net "P3E_CPU1_PE3_MP_TXN<7>")
	)
	(segment
		(start 16.340328 -35.991292)
		(end 17.522952 -35.50158)
		(width 0.1143)
		(layer "In9.Cu")
		(net "P3E_CPU1_PE3_MP_TXN<7>")
	)
	(segment
		(start 137.851388 -102.779576)
		(end 137.937748 -102.693216)
		(width 0.0889)
		(layer "In9.Cu")
		(net "P3E_CPU1_PE3_MP_TXN<7>")
	)
	(segment
		(start 127.674878 -107.3277)
		(end 130.680968 -107.928918)
		(width 0.1143)
		(layer "In9.Cu")
		(net "P3E_CPU1_PE3_MP_TXN<7>")
	)
	(segment
		(start 17.522952 -35.50158)
		(end 18.895314 -35.50158)
		(width 0.1143)
		(layer "In9.Cu")
		(net "P3E_CPU1_PE3_MP_TXN<7>")
	)
	(segment
		(start 137.152634 -98.215704)
		(end 137.158984 -98.205036)
		(width 0.0889)
		(layer "In9.Cu")
		(net "P3E_CPU1_PE3_MP_TXN<7>")
	)
	(segment
		(start 61.575696 -59.726068)
		(end 60.64885 -64.358774)
		(width 0.1143)
		(layer "In9.Cu")
		(net "P3E_CPU1_PE3_MP_TXN<7>")
	)
	(segment
		(start 137.19048 -104.53243)
		(end 137.19048 -104.410256)
		(width 0.0889)
		(layer "In9.Cu")
		(net "P3E_CPU1_PE3_MP_TXN<7>")
	)
	(segment
		(start 64.45504 -104.455468)
		(end 68.757038 -107.32262)
		(width 0.1143)
		(layer "In9.Cu")
		(net "P3E_CPU1_PE3_MP_TXN<7>")
	)
	(segment
		(start 137.851388 -102.957376)
		(end 137.851388 -102.779576)
		(width 0.0889)
		(layer "In9.Cu")
		(net "P3E_CPU1_PE3_MP_TXN<7>")
	)
	(segment
		(start 137.316464 -104.284272)
		(end 137.438638 -104.284272)
		(width 0.0889)
		(layer "In9.Cu")
		(net "P3E_CPU1_PE3_MP_TXN<7>")
	)
	(segment
		(start 133.1341 -107.928918)
		(end 133.1849 -107.979718)
		(width 0.0889)
		(layer "In9.Cu")
		(net "P3E_CPU1_PE3_MP_TXN<7>")
	)
	(segment
		(start 137.564114 -104.036622)
		(end 137.690098 -103.910638)
		(width 0.0889)
		(layer "In9.Cu")
		(net "P3E_CPU1_PE3_MP_TXN<7>")
	)
	(segment
		(start 106.6927 -109.529118)
		(end 109.733588 -108.920534)
		(width 0.1143)
		(layer "In9.Cu")
		(net "P3E_CPU1_PE3_MP_TXN<7>")
	)
	(segment
		(start 133.112002 -107.928918)
		(end 133.1341 -107.928918)
		(width 0.0889)
		(layer "In9.Cu")
		(net "P3E_CPU1_PE3_MP_TXN<7>")
	)
	(segment
		(start 15.571216 -35.991292)
		(end 16.340328 -35.991292)
		(width 0.1143)
		(layer "In9.Cu")
		(net "P3E_CPU1_PE3_MP_TXN<7>")
	)
	(segment
		(start 133.743192 -107.979718)
		(end 136.824974 -104.897936)
		(width 0.0889)
		(layer "In9.Cu")
		(net "P3E_CPU1_PE3_MP_TXN<7>")
	)
	(segment
		(start 137.19048 -104.410256)
		(end 137.316464 -104.284272)
		(width 0.0889)
		(layer "In9.Cu")
		(net "P3E_CPU1_PE3_MP_TXN<7>")
	)
	(segment
		(start 137.158984 -98.205036)
		(end 137.16381 -98.1964)
		(width 0.0889)
		(layer "In9.Cu")
		(net "P3E_CPU1_PE3_MP_TXN<7>")
	)
	(arc
		(start 137.937748 -101.987096)
		(mid 137.958977 -101.819867)
		(end 138.021314 -101.663246)
		(width 0.0889)
		(layer "In9.Cu")
		(net "P3E_CPU1_PE3_MP_TXN<7>")
	)
	(arc
		(start 138.017504 -101.272086)
		(mid 137.938282 -100.982968)
		(end 138.011154 -100.692204)
		(width 0.0889)
		(layer "In9.Cu")
		(net "P3E_CPU1_PE3_MP_TXN<7>")
	)
	(arc
		(start 138.017504 -100.681536)
		(mid 138.071003 -100.481638)
		(end 138.017504 -100.28174)
		(width 0.0889)
		(layer "In9.Cu")
		(net "P3E_CPU1_PE3_MP_TXN<7>")
	)
	(arc
		(start 137.16381 -98.1964)
		(mid 137.211723 -98.029115)
		(end 137.18413 -97.85731)
		(width 0.0889)
		(layer "In9.Cu")
		(net "P3E_CPU1_PE3_MP_TXN<7>")
	)
	(arc
		(start 138.017504 -99.290886)
		(mid 137.875821 -99.147082)
		(end 137.68197 -99.090734)
		(width 0.0889)
		(layer "In9.Cu")
		(net "P3E_CPU1_PE3_MP_TXN<7>")
	)
	(arc
		(start 137.649204 -99.090734)
		(mid 137.156814 -98.791801)
		(end 137.152634 -98.215704)
		(width 0.0889)
		(layer "In9.Cu")
		(net "P3E_CPU1_PE3_MP_TXN<7>")
	)
	(arc
		(start 138.021314 -101.663246)
		(mid 138.070916 -101.467156)
		(end 138.017504 -101.272086)
		(width 0.0889)
		(layer "In9.Cu")
		(net "P3E_CPU1_PE3_MP_TXN<7>")
	)
	(arc
		(start 138.017504 -99.690936)
		(mid 138.070974 -99.495873)
		(end 138.02233 -99.299522)
		(width 0.0889)
		(layer "In9.Cu")
		(net "P3E_CPU1_PE3_MP_TXN<7>")
	)
	(arc
		(start 138.017504 -100.28174)
		(mid 137.938373 -99.986338)
		(end 138.017504 -99.690936)
		(width 0.0889)
		(layer "In9.Cu")
		(net "P3E_CPU1_PE3_MP_TXN<7>")
	)
	(segment
		(start 14.7828 -34.798)
		(end 15.10665 -34.47415)
		(width 0.1143)
		(layer "F.Cu")
		(net "P3E_CPU1_PE3_MP_TXN<6>")
	)
	(segment
		(start 16.684498 -34.58845)
		(end 16.684498 -34.9885)
		(width 0.1143)
		(layer "F.Cu")
		(net "P3E_CPU1_PE3_MP_TXN<6>")
	)
	(segment
		(start 15.10665 -34.47415)
		(end 16.570198 -34.47415)
		(width 0.1143)
		(layer "F.Cu")
		(net "P3E_CPU1_PE3_MP_TXN<6>")
	)
	(segment
		(start 16.570198 -34.47415)
		(end 16.684498 -34.58845)
		(width 0.1143)
		(layer "F.Cu")
		(net "P3E_CPU1_PE3_MP_TXN<6>")
	)
	(segment
		(start 136.240774 -98.995738)
		(end 136.812274 -98.995738)
		(width 0.1143)
		(layer "F.Cu")
		(net "P3E_CPU1_PE3_MP_TXN<6>")
	)
	(via
		(at 16.684498 -34.9885)
		(size 0.508)
		(drill 0.254)
		(layers "F.Cu" "B.Cu")
		(net "P3E_CPU1_PE3_MP_TXN<6>")
	)
	(via
		(at 136.812274 -98.995738)
		(size 0.508)
		(drill 0.254)
		(layers "F.Cu" "B.Cu")
		(net "P3E_CPU1_PE3_MP_TXN<6>")
	)
	(segment
		(start 38.616636 -36.999164)
		(end 38.933628 -37.130482)
		(width 0.1143)
		(layer "In9.Cu")
		(net "P3E_CPU1_PE3_MP_TXN<6>")
	)
	(segment
		(start 25.271984 -32.844232)
		(end 30.248098 -34.905696)
		(width 0.1143)
		(layer "In9.Cu")
		(net "P3E_CPU1_PE3_MP_TXN<6>")
	)
	(segment
		(start 19.50593 -34.5821)
		(end 20.191222 -34.5821)
		(width 0.1143)
		(layer "In9.Cu")
		(net "P3E_CPU1_PE3_MP_TXN<6>")
	)
	(segment
		(start 75.167236 -108.230924)
		(end 83.34375 -106.595672)
		(width 0.1143)
		(layer "In9.Cu")
		(net "P3E_CPU1_PE3_MP_TXN<6>")
	)
	(segment
		(start 37.678106 -36.61029)
		(end 37.994844 -36.741608)
		(width 0.1143)
		(layer "In9.Cu")
		(net "P3E_CPU1_PE3_MP_TXN<6>")
	)
	(segment
		(start 18.103596 -34.49955)
		(end 18.388838 -34.214308)
		(width 0.1143)
		(layer "In9.Cu")
		(net "P3E_CPU1_PE3_MP_TXN<6>")
	)
	(segment
		(start 35.800792 -35.832542)
		(end 36.11753 -35.96386)
		(width 0.1143)
		(layer "In9.Cu")
		(net "P3E_CPU1_PE3_MP_TXN<6>")
	)
	(segment
		(start 132.89407 -107.542584)
		(end 132.94487 -107.491784)
		(width 0.0889)
		(layer "In9.Cu")
		(net "P3E_CPU1_PE3_MP_TXN<6>")
	)
	(segment
		(start 64.750188 -104.22509)
		(end 68.874386 -106.97337)
		(width 0.1143)
		(layer "In9.Cu")
		(net "P3E_CPU1_PE3_MP_TXN<6>")
	)
	(segment
		(start 137.43178 -103.42626)
		(end 137.43178 -102.077774)
		(width 0.0889)
		(layer "In9.Cu")
		(net "P3E_CPU1_PE3_MP_TXN<6>")
	)
	(segment
		(start 36.33343 -35.874452)
		(end 36.650168 -36.00577)
		(width 0.1143)
		(layer "In9.Cu")
		(net "P3E_CPU1_PE3_MP_TXN<6>")
	)
	(segment
		(start 136.833864 -99.395788)
		(end 136.801098 -99.395788)
		(width 0.0889)
		(layer "In9.Cu")
		(net "P3E_CPU1_PE3_MP_TXN<6>")
	)
	(segment
		(start 136.519158 -98.826574)
		(end 136.812274 -98.995738)
		(width 0.0889)
		(layer "In9.Cu")
		(net "P3E_CPU1_PE3_MP_TXN<6>")
	)
	(segment
		(start 130.74015 -107.542584)
		(end 132.871972 -107.542584)
		(width 0.1143)
		(layer "In9.Cu")
		(net "P3E_CPU1_PE3_MP_TXN<6>")
	)
	(segment
		(start 16.684498 -34.9885)
		(end 16.684498 -34.61385)
		(width 0.1143)
		(layer "In9.Cu")
		(net "P3E_CPU1_PE3_MP_TXN<6>")
	)
	(segment
		(start 39.149274 -37.041074)
		(end 39.466012 -37.172392)
		(width 0.1143)
		(layer "In9.Cu")
		(net "P3E_CPU1_PE3_MP_TXN<6>")
	)
	(segment
		(start 61.127386 -89.546938)
		(end 63.764922 -102.746556)
		(width 0.1143)
		(layer "In9.Cu")
		(net "P3E_CPU1_PE3_MP_TXN<6>")
	)
	(segment
		(start 127.775208 -106.949748)
		(end 130.74015 -107.542584)
		(width 0.1143)
		(layer "In9.Cu")
		(net "P3E_CPU1_PE3_MP_TXN<6>")
	)
	(segment
		(start 18.388838 -34.214308)
		(end 18.388838 -33.649412)
		(width 0.1143)
		(layer "In9.Cu")
		(net "P3E_CPU1_PE3_MP_TXN<6>")
	)
	(segment
		(start 32.761428 -34.394648)
		(end 35.711384 -35.616896)
		(width 0.1143)
		(layer "In9.Cu")
		(net "P3E_CPU1_PE3_MP_TXN<6>")
	)
	(segment
		(start 37.994844 -36.741608)
		(end 38.21049 -36.6522)
		(width 0.1143)
		(layer "In9.Cu")
		(net "P3E_CPU1_PE3_MP_TXN<6>")
	)
	(segment
		(start 36.650168 -36.00577)
		(end 36.739322 -36.221416)
		(width 0.1143)
		(layer "In9.Cu")
		(net "P3E_CPU1_PE3_MP_TXN<6>")
	)
	(segment
		(start 83.34375 -106.595672)
		(end 92.70746 -108.468414)
		(width 0.1143)
		(layer "In9.Cu")
		(net "P3E_CPU1_PE3_MP_TXN<6>")
	)
	(segment
		(start 18.503138 -33.535112)
		(end 19.023838 -33.535112)
		(width 0.1143)
		(layer "In9.Cu")
		(net "P3E_CPU1_PE3_MP_TXN<6>")
	)
	(segment
		(start 39.466012 -37.172392)
		(end 55.519574 -47.881032)
		(width 0.1143)
		(layer "In9.Cu")
		(net "P3E_CPU1_PE3_MP_TXN<6>")
	)
	(segment
		(start 63.764922 -102.746556)
		(end 64.750188 -104.22509)
		(width 0.1143)
		(layer "In9.Cu")
		(net "P3E_CPU1_PE3_MP_TXN<6>")
	)
	(segment
		(start 61.11113 -64.37122)
		(end 63.636398 -77.0001)
		(width 0.1143)
		(layer "In9.Cu")
		(net "P3E_CPU1_PE3_MP_TXN<6>")
	)
	(segment
		(start 19.138138 -33.649412)
		(end 19.138138 -34.214308)
		(width 0.1143)
		(layer "In9.Cu")
		(net "P3E_CPU1_PE3_MP_TXN<6>")
	)
	(segment
		(start 18.388838 -33.649412)
		(end 18.503138 -33.535112)
		(width 0.1143)
		(layer "In9.Cu")
		(net "P3E_CPU1_PE3_MP_TXN<6>")
	)
	(segment
		(start 115.04549 -109.49559)
		(end 127.775208 -106.949748)
		(width 0.1143)
		(layer "In9.Cu")
		(net "P3E_CPU1_PE3_MP_TXN<6>")
	)
	(segment
		(start 106.857292 -109.1438)
		(end 110.071916 -108.500672)
		(width 0.1143)
		(layer "In9.Cu")
		(net "P3E_CPU1_PE3_MP_TXN<6>")
	)
	(segment
		(start 37.056314 -36.352734)
		(end 37.27196 -36.263326)
		(width 0.1143)
		(layer "In9.Cu")
		(net "P3E_CPU1_PE3_MP_TXN<6>")
	)
	(segment
		(start 92.70746 -108.468414)
		(end 98.095562 -107.390946)
		(width 0.1143)
		(layer "In9.Cu")
		(net "P3E_CPU1_PE3_MP_TXN<6>")
	)
	(segment
		(start 62.029848 -59.776614)
		(end 61.11113 -64.37122)
		(width 0.1143)
		(layer "In9.Cu")
		(net "P3E_CPU1_PE3_MP_TXN<6>")
	)
	(segment
		(start 63.636398 -77.0001)
		(end 61.127386 -89.546938)
		(width 0.1143)
		(layer "In9.Cu")
		(net "P3E_CPU1_PE3_MP_TXN<6>")
	)
	(segment
		(start 137.318242 -101.280468)
		(end 137.323068 -101.271832)
		(width 0.0889)
		(layer "In9.Cu")
		(net "P3E_CPU1_PE3_MP_TXN<6>")
	)
	(segment
		(start 38.933628 -37.130482)
		(end 39.149274 -37.041074)
		(width 0.1143)
		(layer "In9.Cu")
		(net "P3E_CPU1_PE3_MP_TXN<6>")
	)
	(segment
		(start 19.138138 -34.214308)
		(end 19.50593 -34.5821)
		(width 0.1143)
		(layer "In9.Cu")
		(net "P3E_CPU1_PE3_MP_TXN<6>")
	)
	(segment
		(start 19.023838 -33.535112)
		(end 19.138138 -33.649412)
		(width 0.1143)
		(layer "In9.Cu")
		(net "P3E_CPU1_PE3_MP_TXN<6>")
	)
	(segment
		(start 68.874386 -106.97337)
		(end 75.167236 -108.230924)
		(width 0.1143)
		(layer "In9.Cu")
		(net "P3E_CPU1_PE3_MP_TXN<6>")
	)
	(segment
		(start 16.684498 -34.61385)
		(end 16.798798 -34.49955)
		(width 0.1143)
		(layer "In9.Cu")
		(net "P3E_CPU1_PE3_MP_TXN<6>")
	)
	(segment
		(start 98.095562 -107.390946)
		(end 106.857292 -109.1438)
		(width 0.1143)
		(layer "In9.Cu")
		(net "P3E_CPU1_PE3_MP_TXN<6>")
	)
	(segment
		(start 137.324338 -100.28174)
		(end 137.330434 -100.270818)
		(width 0.0889)
		(layer "In9.Cu")
		(net "P3E_CPU1_PE3_MP_TXN<6>")
	)
	(segment
		(start 20.191222 -34.5821)
		(end 24.387302 -32.844232)
		(width 0.1143)
		(layer "In9.Cu")
		(net "P3E_CPU1_PE3_MP_TXN<6>")
	)
	(segment
		(start 38.21049 -36.6522)
		(end 38.527482 -36.783518)
		(width 0.1143)
		(layer "In9.Cu")
		(net "P3E_CPU1_PE3_MP_TXN<6>")
	)
	(segment
		(start 110.071916 -108.500672)
		(end 115.04549 -109.49559)
		(width 0.1143)
		(layer "In9.Cu")
		(net "P3E_CPU1_PE3_MP_TXN<6>")
	)
	(segment
		(start 24.387302 -32.844232)
		(end 25.271984 -32.844232)
		(width 0.1143)
		(layer "In9.Cu")
		(net "P3E_CPU1_PE3_MP_TXN<6>")
	)
	(segment
		(start 36.739322 -36.221416)
		(end 37.056314 -36.352734)
		(width 0.1143)
		(layer "In9.Cu")
		(net "P3E_CPU1_PE3_MP_TXN<6>")
	)
	(segment
		(start 37.27196 -36.263326)
		(end 37.588698 -36.394644)
		(width 0.1143)
		(layer "In9.Cu")
		(net "P3E_CPU1_PE3_MP_TXN<6>")
	)
	(segment
		(start 16.798798 -34.49955)
		(end 18.103596 -34.49955)
		(width 0.1143)
		(layer "In9.Cu")
		(net "P3E_CPU1_PE3_MP_TXN<6>")
	)
	(segment
		(start 30.248098 -34.905696)
		(end 32.761428 -34.394648)
		(width 0.1143)
		(layer "In9.Cu")
		(net "P3E_CPU1_PE3_MP_TXN<6>")
	)
	(segment
		(start 55.519574 -47.881032)
		(end 61.418724 -56.728106)
		(width 0.1143)
		(layer "In9.Cu")
		(net "P3E_CPU1_PE3_MP_TXN<6>")
	)
	(segment
		(start 36.11753 -35.96386)
		(end 36.33343 -35.874452)
		(width 0.1143)
		(layer "In9.Cu")
		(net "P3E_CPU1_PE3_MP_TXN<6>")
	)
	(segment
		(start 136.440418 -98.84791)
		(end 136.519158 -98.826574)
		(width 0.0889)
		(layer "In9.Cu")
		(net "P3E_CPU1_PE3_MP_TXN<6>")
	)
	(segment
		(start 133.366256 -107.491784)
		(end 137.43178 -103.42626)
		(width 0.0889)
		(layer "In9.Cu")
		(net "P3E_CPU1_PE3_MP_TXN<6>")
	)
	(segment
		(start 37.588698 -36.394644)
		(end 37.678106 -36.61029)
		(width 0.1143)
		(layer "In9.Cu")
		(net "P3E_CPU1_PE3_MP_TXN<6>")
	)
	(segment
		(start 132.871972 -107.542584)
		(end 132.89407 -107.542584)
		(width 0.0889)
		(layer "In9.Cu")
		(net "P3E_CPU1_PE3_MP_TXN<6>")
	)
	(segment
		(start 132.94487 -107.491784)
		(end 133.366256 -107.491784)
		(width 0.0889)
		(layer "In9.Cu")
		(net "P3E_CPU1_PE3_MP_TXN<6>")
	)
	(segment
		(start 38.527482 -36.783518)
		(end 38.616636 -36.999164)
		(width 0.1143)
		(layer "In9.Cu")
		(net "P3E_CPU1_PE3_MP_TXN<6>")
	)
	(segment
		(start 61.418724 -56.728106)
		(end 62.029848 -59.776614)
		(width 0.1143)
		(layer "In9.Cu")
		(net "P3E_CPU1_PE3_MP_TXN<6>")
	)
	(segment
		(start 35.711384 -35.616896)
		(end 35.800792 -35.832542)
		(width 0.1143)
		(layer "In9.Cu")
		(net "P3E_CPU1_PE3_MP_TXN<6>")
	)
	(arc
		(start 136.801098 -99.395788)
		(mid 136.478213 -99.215747)
		(end 136.440418 -98.84791)
		(width 0.0889)
		(layer "In9.Cu")
		(net "P3E_CPU1_PE3_MP_TXN<6>")
	)
	(arc
		(start 136.906762 -99.4029)
		(mid 136.870423 -99.398213)
		(end 136.833864 -99.395788)
		(width 0.0889)
		(layer "In9.Cu")
		(net "P3E_CPU1_PE3_MP_TXN<6>")
	)
	(arc
		(start 137.43178 -102.077774)
		(mid 137.40413 -101.867676)
		(end 137.323068 -101.671882)
		(width 0.0889)
		(layer "In9.Cu")
		(net "P3E_CPU1_PE3_MP_TXN<6>")
	)
	(arc
		(start 137.323068 -101.271832)
		(mid 137.40229 -100.982714)
		(end 137.329418 -100.69195)
		(width 0.0889)
		(layer "In9.Cu")
		(net "P3E_CPU1_PE3_MP_TXN<6>")
	)
	(arc
		(start 137.324338 -100.681536)
		(mid 137.270839 -100.481638)
		(end 137.324338 -100.28174)
		(width 0.0889)
		(layer "In9.Cu")
		(net "P3E_CPU1_PE3_MP_TXN<6>")
	)
	(arc
		(start 137.323068 -101.671882)
		(mid 137.269598 -101.476819)
		(end 137.318242 -101.280468)
		(width 0.0889)
		(layer "In9.Cu")
		(net "P3E_CPU1_PE3_MP_TXN<6>")
	)
	(arc
		(start 137.330434 -100.270818)
		(mid 137.343491 -99.727056)
		(end 136.906762 -99.4029)
		(width 0.0889)
		(layer "In9.Cu")
		(net "P3E_CPU1_PE3_MP_TXN<6>")
	)
	(arc
		(start 137.329418 -100.69195)
		(mid 137.327057 -100.686656)
		(end 137.324338 -100.681536)
		(width 0.0889)
		(layer "In9.Cu")
		(net "P3E_CPU1_PE3_MP_TXN<6>")
	)
	(segment
		(start 14.7828 -32.131)
		(end 15.088616 -32.436816)
		(width 0.1143)
		(layer "F.Cu")
		(net "P3E_CPU1_PE3_MP_TXN<5>")
	)
	(segment
		(start 15.451074 -32.34055)
		(end 15.451074 -31.9405)
		(width 0.1143)
		(layer "F.Cu")
		(net "P3E_CPU1_PE3_MP_TXN<5>")
	)
	(segment
		(start 15.088616 -32.436816)
		(end 15.354808 -32.436816)
		(width 0.1143)
		(layer "F.Cu")
		(net "P3E_CPU1_PE3_MP_TXN<5>")
	)
	(segment
		(start 15.354808 -32.436816)
		(end 15.451074 -32.34055)
		(width 0.1143)
		(layer "F.Cu")
		(net "P3E_CPU1_PE3_MP_TXN<5>")
	)
	(segment
		(start 134.523734 -99.986338)
		(end 135.095234 -99.986338)
		(width 0.1143)
		(layer "F.Cu")
		(net "P3E_CPU1_PE3_MP_TXN<5>")
	)
	(via
		(at 15.451074 -31.9405)
		(size 0.508)
		(drill 0.254)
		(layers "F.Cu" "B.Cu")
		(net "P3E_CPU1_PE3_MP_TXN<5>")
	)
	(via
		(at 135.095234 -99.986338)
		(size 0.508)
		(drill 0.254)
		(layers "F.Cu" "B.Cu")
		(net "P3E_CPU1_PE3_MP_TXN<5>")
	)
	(segment
		(start 135.149844 -104.556052)
		(end 135.006588 -104.556052)
		(width 0.0889)
		(layer "In9.Cu")
		(net "P3E_CPU1_PE3_MP_TXN<5>")
	)
	(segment
		(start 135.952484 -100.081588)
		(end 135.952738 -100.081334)
		(width 0.0889)
		(layer "In9.Cu")
		(net "P3E_CPU1_PE3_MP_TXN<5>")
	)
	(segment
		(start 69.318124 -106.113326)
		(end 65.709292 -103.708454)
		(width 0.1143)
		(layer "In9.Cu")
		(net "P3E_CPU1_PE3_MP_TXN<5>")
	)
	(segment
		(start 75.167744 -107.282742)
		(end 69.318124 -106.113326)
		(width 0.1143)
		(layer "In9.Cu")
		(net "P3E_CPU1_PE3_MP_TXN<5>")
	)
	(segment
		(start 135.40105 -104.16159)
		(end 135.27532 -104.28732)
		(width 0.0889)
		(layer "In9.Cu")
		(net "P3E_CPU1_PE3_MP_TXN<5>")
	)
	(segment
		(start 136.38657 -102.421436)
		(end 136.386824 -102.42169)
		(width 0.0889)
		(layer "In9.Cu")
		(net "P3E_CPU1_PE3_MP_TXN<5>")
	)
	(segment
		(start 136.307068 -101.66096)
		(end 136.306814 -101.66096)
		(width 0.0889)
		(layer "In9.Cu")
		(net "P3E_CPU1_PE3_MP_TXN<5>")
	)
	(segment
		(start 56.06669 -47.00143)
		(end 39.74084 -36.108894)
		(width 0.1143)
		(layer "In9.Cu")
		(net "P3E_CPU1_PE3_MP_TXN<5>")
	)
	(segment
		(start 136.0805 -102.981506)
		(end 136.0805 -103.625396)
		(width 0.0889)
		(layer "In9.Cu")
		(net "P3E_CPU1_PE3_MP_TXN<5>")
	)
	(segment
		(start 134.486396 -105.2195)
		(end 134.36092 -105.344976)
		(width 0.0889)
		(layer "In9.Cu")
		(net "P3E_CPU1_PE3_MP_TXN<5>")
	)
	(segment
		(start 30.959806 -32.131)
		(end 30.139386 -32.131)
		(width 0.1143)
		(layer "In9.Cu")
		(net "P3E_CPU1_PE3_MP_TXN<5>")
	)
	(segment
		(start 135.938768 -103.767128)
		(end 135.795512 -103.767128)
		(width 0.0889)
		(layer "In9.Cu")
		(net "P3E_CPU1_PE3_MP_TXN<5>")
	)
	(segment
		(start 135.544306 -104.16159)
		(end 135.40105 -104.16159)
		(width 0.0889)
		(layer "In9.Cu")
		(net "P3E_CPU1_PE3_MP_TXN<5>")
	)
	(segment
		(start 132.502656 -106.411268)
		(end 129.958338 -106.411268)
		(width 0.1143)
		(layer "In9.Cu")
		(net "P3E_CPU1_PE3_MP_TXN<5>")
	)
	(segment
		(start 133.243828 -106.462068)
		(end 132.575554 -106.462068)
		(width 0.0889)
		(layer "In9.Cu")
		(net "P3E_CPU1_PE3_MP_TXN<5>")
	)
	(segment
		(start 135.27532 -104.430576)
		(end 135.149844 -104.556052)
		(width 0.0889)
		(layer "In9.Cu")
		(net "P3E_CPU1_PE3_MP_TXN<5>")
	)
	(segment
		(start 83.539584 -105.60812)
		(end 75.167744 -107.282742)
		(width 0.1143)
		(layer "In9.Cu")
		(net "P3E_CPU1_PE3_MP_TXN<5>")
	)
	(segment
		(start 134.091934 -105.613962)
		(end 133.243828 -106.462068)
		(width 0.0889)
		(layer "In9.Cu")
		(net "P3E_CPU1_PE3_MP_TXN<5>")
	)
	(segment
		(start 132.524754 -106.411268)
		(end 132.502656 -106.411268)
		(width 0.0889)
		(layer "In9.Cu")
		(net "P3E_CPU1_PE3_MP_TXN<5>")
	)
	(segment
		(start 132.575554 -106.462068)
		(end 132.524754 -106.411268)
		(width 0.0889)
		(layer "In9.Cu")
		(net "P3E_CPU1_PE3_MP_TXN<5>")
	)
	(segment
		(start 92.686378 -107.437428)
		(end 83.539584 -105.60812)
		(width 0.1143)
		(layer "In9.Cu")
		(net "P3E_CPU1_PE3_MP_TXN<5>")
	)
	(segment
		(start 127.840232 -105.988358)
		(end 115.51285 -108.453682)
		(width 0.1143)
		(layer "In9.Cu")
		(net "P3E_CPU1_PE3_MP_TXN<5>")
	)
	(segment
		(start 64.62522 -76.899008)
		(end 62.130686 -64.424052)
		(width 0.1143)
		(layer "In9.Cu")
		(net "P3E_CPU1_PE3_MP_TXN<5>")
	)
	(segment
		(start 134.880858 -104.681782)
		(end 134.880858 -104.825038)
		(width 0.0889)
		(layer "In9.Cu")
		(net "P3E_CPU1_PE3_MP_TXN<5>")
	)
	(segment
		(start 115.51285 -108.453682)
		(end 110.259622 -107.40263)
		(width 0.1143)
		(layer "In9.Cu")
		(net "P3E_CPU1_PE3_MP_TXN<5>")
	)
	(segment
		(start 110.259622 -107.40263)
		(end 106.742484 -108.10621)
		(width 0.1143)
		(layer "In9.Cu")
		(net "P3E_CPU1_PE3_MP_TXN<5>")
	)
	(segment
		(start 30.139386 -32.131)
		(end 28.576524 -31.4833)
		(width 0.1143)
		(layer "In9.Cu")
		(net "P3E_CPU1_PE3_MP_TXN<5>")
	)
	(segment
		(start 134.36092 -105.344976)
		(end 134.217664 -105.344976)
		(width 0.0889)
		(layer "In9.Cu")
		(net "P3E_CPU1_PE3_MP_TXN<5>")
	)
	(segment
		(start 135.27532 -104.28732)
		(end 135.27532 -104.430576)
		(width 0.0889)
		(layer "In9.Cu")
		(net "P3E_CPU1_PE3_MP_TXN<5>")
	)
	(segment
		(start 135.795512 -103.767128)
		(end 135.669782 -103.892858)
		(width 0.0889)
		(layer "In9.Cu")
		(net "P3E_CPU1_PE3_MP_TXN<5>")
	)
	(segment
		(start 129.958338 -106.411268)
		(end 127.840232 -105.988358)
		(width 0.1143)
		(layer "In9.Cu")
		(net "P3E_CPU1_PE3_MP_TXN<5>")
	)
	(segment
		(start 134.755382 -104.950514)
		(end 134.612126 -104.950514)
		(width 0.0889)
		(layer "In9.Cu")
		(net "P3E_CPU1_PE3_MP_TXN<5>")
	)
	(segment
		(start 136.299956 -100.280216)
		(end 136.30148 -100.283264)
		(width 0.0889)
		(layer "In9.Cu")
		(net "P3E_CPU1_PE3_MP_TXN<5>")
	)
	(segment
		(start 15.565374 -32.42945)
		(end 15.451074 -32.31515)
		(width 0.1143)
		(layer "In9.Cu")
		(net "P3E_CPU1_PE3_MP_TXN<5>")
	)
	(segment
		(start 136.30148 -100.283264)
		(end 136.301734 -100.283518)
		(width 0.0889)
		(layer "In9.Cu")
		(net "P3E_CPU1_PE3_MP_TXN<5>")
	)
	(segment
		(start 134.217664 -105.344976)
		(end 134.091934 -105.470706)
		(width 0.0889)
		(layer "In9.Cu")
		(net "P3E_CPU1_PE3_MP_TXN<5>")
	)
	(segment
		(start 135.095234 -99.986338)
		(end 135.38835 -99.817174)
		(width 0.0889)
		(layer "In9.Cu")
		(net "P3E_CPU1_PE3_MP_TXN<5>")
	)
	(segment
		(start 15.451074 -32.31515)
		(end 15.451074 -31.9405)
		(width 0.1143)
		(layer "In9.Cu")
		(net "P3E_CPU1_PE3_MP_TXN<5>")
	)
	(segment
		(start 28.576524 -31.4833)
		(end 19.36115 -31.4833)
		(width 0.1143)
		(layer "In9.Cu")
		(net "P3E_CPU1_PE3_MP_TXN<5>")
	)
	(segment
		(start 39.74084 -36.108894)
		(end 39.160196 -35.52825)
		(width 0.1143)
		(layer "In9.Cu")
		(net "P3E_CPU1_PE3_MP_TXN<5>")
	)
	(segment
		(start 62.130686 -64.424052)
		(end 63.02883 -59.93257)
		(width 0.1143)
		(layer "In9.Cu")
		(net "P3E_CPU1_PE3_MP_TXN<5>")
	)
	(segment
		(start 64.61252 -102.06228)
		(end 62.103254 -89.509346)
		(width 0.1143)
		(layer "In9.Cu")
		(net "P3E_CPU1_PE3_MP_TXN<5>")
	)
	(segment
		(start 136.386824 -102.675182)
		(end 136.0805 -102.981506)
		(width 0.0889)
		(layer "In9.Cu")
		(net "P3E_CPU1_PE3_MP_TXN<5>")
	)
	(segment
		(start 39.160196 -35.52825)
		(end 30.959806 -32.131)
		(width 0.1143)
		(layer "In9.Cu")
		(net "P3E_CPU1_PE3_MP_TXN<5>")
	)
	(segment
		(start 135.006588 -104.556052)
		(end 134.880858 -104.681782)
		(width 0.0889)
		(layer "In9.Cu")
		(net "P3E_CPU1_PE3_MP_TXN<5>")
	)
	(segment
		(start 136.0805 -103.625396)
		(end 135.938768 -103.767128)
		(width 0.0889)
		(layer "In9.Cu")
		(net "P3E_CPU1_PE3_MP_TXN<5>")
	)
	(segment
		(start 135.669782 -104.036114)
		(end 135.544306 -104.16159)
		(width 0.0889)
		(layer "In9.Cu")
		(net "P3E_CPU1_PE3_MP_TXN<5>")
	)
	(segment
		(start 136.39292 -100.664772)
		(end 136.39292 -100.937822)
		(width 0.0889)
		(layer "In9.Cu")
		(net "P3E_CPU1_PE3_MP_TXN<5>")
	)
	(segment
		(start 17.076928 -32.42945)
		(end 15.565374 -32.42945)
		(width 0.1143)
		(layer "In9.Cu")
		(net "P3E_CPU1_PE3_MP_TXN<5>")
	)
	(segment
		(start 62.103254 -89.509346)
		(end 64.62522 -76.899008)
		(width 0.1143)
		(layer "In9.Cu")
		(net "P3E_CPU1_PE3_MP_TXN<5>")
	)
	(segment
		(start 62.31636 -56.374792)
		(end 56.06669 -47.00143)
		(width 0.1143)
		(layer "In9.Cu")
		(net "P3E_CPU1_PE3_MP_TXN<5>")
	)
	(segment
		(start 136.293098 -102.249986)
		(end 136.38657 -102.421436)
		(width 0.0889)
		(layer "In9.Cu")
		(net "P3E_CPU1_PE3_MP_TXN<5>")
	)
	(segment
		(start 98.043746 -106.366056)
		(end 92.686378 -107.437428)
		(width 0.1143)
		(layer "In9.Cu")
		(net "P3E_CPU1_PE3_MP_TXN<5>")
	)
	(segment
		(start 134.091934 -105.470706)
		(end 134.091934 -105.613962)
		(width 0.0889)
		(layer "In9.Cu")
		(net "P3E_CPU1_PE3_MP_TXN<5>")
	)
	(segment
		(start 134.880858 -104.825038)
		(end 134.755382 -104.950514)
		(width 0.0889)
		(layer "In9.Cu")
		(net "P3E_CPU1_PE3_MP_TXN<5>")
	)
	(segment
		(start 134.486396 -105.076244)
		(end 134.486396 -105.2195)
		(width 0.0889)
		(layer "In9.Cu")
		(net "P3E_CPU1_PE3_MP_TXN<5>")
	)
	(segment
		(start 106.742484 -108.10621)
		(end 98.043746 -106.366056)
		(width 0.1143)
		(layer "In9.Cu")
		(net "P3E_CPU1_PE3_MP_TXN<5>")
	)
	(segment
		(start 19.36115 -31.4833)
		(end 17.076928 -32.42945)
		(width 0.1143)
		(layer "In9.Cu")
		(net "P3E_CPU1_PE3_MP_TXN<5>")
	)
	(segment
		(start 63.02883 -59.93257)
		(end 62.31636 -56.374792)
		(width 0.1143)
		(layer "In9.Cu")
		(net "P3E_CPU1_PE3_MP_TXN<5>")
	)
	(segment
		(start 135.38835 -99.817174)
		(end 135.477758 -99.841304)
		(width 0.0889)
		(layer "In9.Cu")
		(net "P3E_CPU1_PE3_MP_TXN<5>")
	)
	(segment
		(start 136.386824 -102.42169)
		(end 136.386824 -102.675182)
		(width 0.0889)
		(layer "In9.Cu")
		(net "P3E_CPU1_PE3_MP_TXN<5>")
	)
	(segment
		(start 135.9408 -100.081588)
		(end 135.952484 -100.081588)
		(width 0.0889)
		(layer "In9.Cu")
		(net "P3E_CPU1_PE3_MP_TXN<5>")
	)
	(segment
		(start 135.952738 -100.081334)
		(end 135.964168 -100.081334)
		(width 0.0889)
		(layer "In9.Cu")
		(net "P3E_CPU1_PE3_MP_TXN<5>")
	)
	(segment
		(start 135.669782 -103.892858)
		(end 135.669782 -104.036114)
		(width 0.0889)
		(layer "In9.Cu")
		(net "P3E_CPU1_PE3_MP_TXN<5>")
	)
	(segment
		(start 65.709292 -103.708454)
		(end 64.61252 -102.06228)
		(width 0.1143)
		(layer "In9.Cu")
		(net "P3E_CPU1_PE3_MP_TXN<5>")
	)
	(segment
		(start 134.612126 -104.950514)
		(end 134.486396 -105.076244)
		(width 0.0889)
		(layer "In9.Cu")
		(net "P3E_CPU1_PE3_MP_TXN<5>")
	)
	(arc
		(start 135.477758 -99.841304)
		(mid 135.68133 -100.015301)
		(end 135.9408 -100.081588)
		(width 0.0889)
		(layer "In9.Cu")
		(net "P3E_CPU1_PE3_MP_TXN<5>")
	)
	(arc
		(start 136.380474 -101.422454)
		(mid 136.358582 -101.546264)
		(end 136.307068 -101.66096)
		(width 0.0889)
		(layer "In9.Cu")
		(net "P3E_CPU1_PE3_MP_TXN<5>")
	)
	(arc
		(start 136.306814 -101.66096)
		(mid 136.221359 -101.953628)
		(end 136.293098 -102.249986)
		(width 0.0889)
		(layer "In9.Cu")
		(net "P3E_CPU1_PE3_MP_TXN<5>")
	)
	(arc
		(start 135.964168 -100.081334)
		(mid 136.157892 -100.137139)
		(end 136.299956 -100.280216)
		(width 0.0889)
		(layer "In9.Cu")
		(net "P3E_CPU1_PE3_MP_TXN<5>")
	)
	(arc
		(start 136.301734 -100.283518)
		(mid 136.369835 -100.468764)
		(end 136.39292 -100.664772)
		(width 0.0889)
		(layer "In9.Cu")
		(net "P3E_CPU1_PE3_MP_TXN<5>")
	)
	(arc
		(start 136.39292 -100.937822)
		(mid 136.389808 -101.180218)
		(end 136.380474 -101.422454)
		(width 0.0889)
		(layer "In9.Cu")
		(net "P3E_CPU1_PE3_MP_TXN<5>")
	)
	(segment
		(start 16.61287 -31.02737)
		(end 16.61287 -31.42742)
		(width 0.1143)
		(layer "F.Cu")
		(net "P3E_CPU1_PE3_MP_TXN<4>")
	)
	(segment
		(start 16.50238 -30.91688)
		(end 16.61287 -31.02737)
		(width 0.1143)
		(layer "F.Cu")
		(net "P3E_CPU1_PE3_MP_TXN<4>")
	)
	(segment
		(start 135.382254 -101.471984)
		(end 135.953754 -101.471984)
		(width 0.1143)
		(layer "F.Cu")
		(net "P3E_CPU1_PE3_MP_TXN<4>")
	)
	(segment
		(start 15.10792 -30.91688)
		(end 16.50238 -30.91688)
		(width 0.1143)
		(layer "F.Cu")
		(net "P3E_CPU1_PE3_MP_TXN<4>")
	)
	(segment
		(start 14.7828 -31.242)
		(end 15.10792 -30.91688)
		(width 0.1143)
		(layer "F.Cu")
		(net "P3E_CPU1_PE3_MP_TXN<4>")
	)
	(via
		(at 135.953754 -101.471984)
		(size 0.508)
		(drill 0.254)
		(layers "F.Cu" "B.Cu")
		(net "P3E_CPU1_PE3_MP_TXN<4>")
	)
	(via
		(at 16.61287 -31.42742)
		(size 0.508)
		(drill 0.254)
		(layers "F.Cu" "B.Cu")
		(net "P3E_CPU1_PE3_MP_TXN<4>")
	)
	(segment
		(start 62.488572 -89.4207)
		(end 64.985138 -76.936854)
		(width 0.1143)
		(layer "In9.Cu")
		(net "P3E_CPU1_PE3_MP_TXN<4>")
	)
	(segment
		(start 132.979414 -105.958386)
		(end 132.371338 -105.958386)
		(width 0.0889)
		(layer "In9.Cu")
		(net "P3E_CPU1_PE3_MP_TXN<4>")
	)
	(segment
		(start 30.467554 -31.265622)
		(end 30.131258 -31.198566)
		(width 0.1143)
		(layer "In9.Cu")
		(net "P3E_CPU1_PE3_MP_TXN<4>")
	)
	(segment
		(start 66.02349 -103.448104)
		(end 64.97955 -101.882194)
		(width 0.1143)
		(layer "In9.Cu")
		(net "P3E_CPU1_PE3_MP_TXN<4>")
	)
	(segment
		(start 92.480892 -107.0229)
		(end 83.599274 -105.246424)
		(width 0.1143)
		(layer "In9.Cu")
		(net "P3E_CPU1_PE3_MP_TXN<4>")
	)
	(segment
		(start 35.499802 -32.854138)
		(end 35.284156 -32.943546)
		(width 0.1143)
		(layer "In9.Cu")
		(net "P3E_CPU1_PE3_MP_TXN<4>")
	)
	(segment
		(start 56.40705 -46.715426)
		(end 40.785034 -36.296092)
		(width 0.1143)
		(layer "In9.Cu")
		(net "P3E_CPU1_PE3_MP_TXN<4>")
	)
	(segment
		(start 63.448184 -60.114688)
		(end 62.635638 -56.057292)
		(width 0.1143)
		(layer "In9.Cu")
		(net "P3E_CPU1_PE3_MP_TXN<4>")
	)
	(segment
		(start 30.001718 -31.004256)
		(end 27.8384 -30.57144)
		(width 0.1143)
		(layer "In9.Cu")
		(net "P3E_CPU1_PE3_MP_TXN<4>")
	)
	(segment
		(start 23.296372 -30.08503)
		(end 23.296626 -30.08503)
		(width 0.1143)
		(layer "In9.Cu")
		(net "P3E_CPU1_PE3_MP_TXN<4>")
	)
	(segment
		(start 19.497802 -30.094174)
		(end 17.447768 -30.94355)
		(width 0.1143)
		(layer "In9.Cu")
		(net "P3E_CPU1_PE3_MP_TXN<4>")
	)
	(segment
		(start 36.22294 -33.332166)
		(end 35.906202 -33.201102)
		(width 0.1143)
		(layer "In9.Cu")
		(net "P3E_CPU1_PE3_MP_TXN<4>")
	)
	(segment
		(start 106.742484 -107.650534)
		(end 98.044 -105.91038)
		(width 0.1143)
		(layer "In9.Cu")
		(net "P3E_CPU1_PE3_MP_TXN<4>")
	)
	(segment
		(start 132.320538 -106.009186)
		(end 132.29844 -106.009186)
		(width 0.0889)
		(layer "In9.Cu")
		(net "P3E_CPU1_PE3_MP_TXN<4>")
	)
	(segment
		(start 69.512434 -105.772966)
		(end 66.02349 -103.448104)
		(width 0.1143)
		(layer "In9.Cu")
		(net "P3E_CPU1_PE3_MP_TXN<4>")
	)
	(segment
		(start 30.661864 -31.136336)
		(end 30.467554 -31.265622)
		(width 0.1143)
		(layer "In9.Cu")
		(net "P3E_CPU1_PE3_MP_TXN<4>")
	)
	(segment
		(start 38.645084 -34.156396)
		(end 38.316154 -34.020252)
		(width 0.1143)
		(layer "In9.Cu")
		(net "P3E_CPU1_PE3_MP_TXN<4>")
	)
	(segment
		(start 37.161724 -33.720786)
		(end 36.844732 -33.589722)
		(width 0.1143)
		(layer "In9.Cu")
		(net "P3E_CPU1_PE3_MP_TXN<4>")
	)
	(segment
		(start 135.607044 -102.262686)
		(end 135.602218 -102.271322)
		(width 0.0889)
		(layer "In9.Cu")
		(net "P3E_CPU1_PE3_MP_TXN<4>")
	)
	(segment
		(start 40.785034 -36.296092)
		(end 38.645084 -34.156396)
		(width 0.1143)
		(layer "In9.Cu")
		(net "P3E_CPU1_PE3_MP_TXN<4>")
	)
	(segment
		(start 34.967418 -32.812482)
		(end 34.87801 -32.596582)
		(width 0.1143)
		(layer "In9.Cu")
		(net "P3E_CPU1_PE3_MP_TXN<4>")
	)
	(segment
		(start 31.1277 -31.397702)
		(end 30.99816 -31.203392)
		(width 0.1143)
		(layer "In9.Cu")
		(net "P3E_CPU1_PE3_MP_TXN<4>")
	)
	(segment
		(start 35.284156 -32.943546)
		(end 34.967418 -32.812482)
		(width 0.1143)
		(layer "In9.Cu")
		(net "P3E_CPU1_PE3_MP_TXN<4>")
	)
	(segment
		(start 132.29844 -106.009186)
		(end 130.236468 -106.009186)
		(width 0.1143)
		(layer "In9.Cu")
		(net "P3E_CPU1_PE3_MP_TXN<4>")
	)
	(segment
		(start 62.635638 -56.057292)
		(end 62.635892 -56.057292)
		(width 0.1143)
		(layer "In9.Cu")
		(net "P3E_CPU1_PE3_MP_TXN<4>")
	)
	(segment
		(start 110.277148 -106.943398)
		(end 106.742484 -107.650534)
		(width 0.1143)
		(layer "In9.Cu")
		(net "P3E_CPU1_PE3_MP_TXN<4>")
	)
	(segment
		(start 83.599274 -105.246424)
		(end 75.241404 -106.917998)
		(width 0.1143)
		(layer "In9.Cu")
		(net "P3E_CPU1_PE3_MP_TXN<4>")
	)
	(segment
		(start 115.783868 -108.044996)
		(end 110.277148 -106.943398)
		(width 0.1143)
		(layer "In9.Cu")
		(net "P3E_CPU1_PE3_MP_TXN<4>")
	)
	(segment
		(start 23.296626 -30.08503)
		(end 19.497802 -30.094174)
		(width 0.1143)
		(layer "In9.Cu")
		(net "P3E_CPU1_PE3_MP_TXN<4>")
	)
	(segment
		(start 135.712454 -103.225346)
		(end 132.979414 -105.958386)
		(width 0.0889)
		(layer "In9.Cu")
		(net "P3E_CPU1_PE3_MP_TXN<4>")
	)
	(segment
		(start 31.463742 -31.465012)
		(end 31.1277 -31.397702)
		(width 0.1143)
		(layer "In9.Cu")
		(net "P3E_CPU1_PE3_MP_TXN<4>")
	)
	(segment
		(start 35.816794 -32.985456)
		(end 35.499802 -32.854138)
		(width 0.1143)
		(layer "In9.Cu")
		(net "P3E_CPU1_PE3_MP_TXN<4>")
	)
	(segment
		(start 135.712454 -102.845616)
		(end 135.712454 -103.225346)
		(width 0.0889)
		(layer "In9.Cu")
		(net "P3E_CPU1_PE3_MP_TXN<4>")
	)
	(segment
		(start 135.607044 -102.662736)
		(end 135.646922 -102.731824)
		(width 0.0889)
		(layer "In9.Cu")
		(net "P3E_CPU1_PE3_MP_TXN<4>")
	)
	(segment
		(start 37.783516 -33.978342)
		(end 37.694108 -33.762696)
		(width 0.1143)
		(layer "In9.Cu")
		(net "P3E_CPU1_PE3_MP_TXN<4>")
	)
	(segment
		(start 75.241404 -106.917998)
		(end 69.512434 -105.772966)
		(width 0.1143)
		(layer "In9.Cu")
		(net "P3E_CPU1_PE3_MP_TXN<4>")
	)
	(segment
		(start 135.953754 -101.13391)
		(end 135.895842 -101.075998)
		(width 0.0889)
		(layer "In9.Cu")
		(net "P3E_CPU1_PE3_MP_TXN<4>")
	)
	(segment
		(start 38.316154 -34.020252)
		(end 38.100254 -34.10966)
		(width 0.1143)
		(layer "In9.Cu")
		(net "P3E_CPU1_PE3_MP_TXN<4>")
	)
	(segment
		(start 36.438586 -33.242758)
		(end 36.22294 -33.332166)
		(width 0.1143)
		(layer "In9.Cu")
		(net "P3E_CPU1_PE3_MP_TXN<4>")
	)
	(segment
		(start 135.646922 -102.731824)
		(end 135.64743 -102.732586)
		(width 0.0889)
		(layer "In9.Cu")
		(net "P3E_CPU1_PE3_MP_TXN<4>")
	)
	(segment
		(start 62.534546 -64.68237)
		(end 63.44793 -60.114688)
		(width 0.1143)
		(layer "In9.Cu")
		(net "P3E_CPU1_PE3_MP_TXN<4>")
	)
	(segment
		(start 132.371338 -105.958386)
		(end 132.320538 -106.009186)
		(width 0.0889)
		(layer "In9.Cu")
		(net "P3E_CPU1_PE3_MP_TXN<4>")
	)
	(segment
		(start 31.658052 -31.335472)
		(end 31.463742 -31.465012)
		(width 0.1143)
		(layer "In9.Cu")
		(net "P3E_CPU1_PE3_MP_TXN<4>")
	)
	(segment
		(start 128.099312 -105.581958)
		(end 115.783868 -108.044996)
		(width 0.1143)
		(layer "In9.Cu")
		(net "P3E_CPU1_PE3_MP_TXN<4>")
	)
	(segment
		(start 135.613394 -102.252018)
		(end 135.607044 -102.262686)
		(width 0.0889)
		(layer "In9.Cu")
		(net "P3E_CPU1_PE3_MP_TXN<4>")
	)
	(segment
		(start 98.044 -105.91038)
		(end 92.480892 -107.0229)
		(width 0.1143)
		(layer "In9.Cu")
		(net "P3E_CPU1_PE3_MP_TXN<4>")
	)
	(segment
		(start 38.100254 -34.10966)
		(end 37.783516 -33.978342)
		(width 0.1143)
		(layer "In9.Cu")
		(net "P3E_CPU1_PE3_MP_TXN<4>")
	)
	(segment
		(start 62.635892 -56.057292)
		(end 56.40705 -46.715426)
		(width 0.1143)
		(layer "In9.Cu")
		(net "P3E_CPU1_PE3_MP_TXN<4>")
	)
	(segment
		(start 135.953754 -101.471984)
		(end 135.953754 -101.13391)
		(width 0.0889)
		(layer "In9.Cu")
		(net "P3E_CPU1_PE3_MP_TXN<4>")
	)
	(segment
		(start 27.8384 -30.57144)
		(end 27.095196 -30.075886)
		(width 0.1143)
		(layer "In9.Cu")
		(net "P3E_CPU1_PE3_MP_TXN<4>")
	)
	(segment
		(start 36.844732 -33.589722)
		(end 36.755324 -33.374076)
		(width 0.1143)
		(layer "In9.Cu")
		(net "P3E_CPU1_PE3_MP_TXN<4>")
	)
	(segment
		(start 34.87801 -32.596582)
		(end 31.994348 -31.402782)
		(width 0.1143)
		(layer "In9.Cu")
		(net "P3E_CPU1_PE3_MP_TXN<4>")
	)
	(segment
		(start 16.72209 -30.94355)
		(end 16.61287 -31.05277)
		(width 0.1143)
		(layer "In9.Cu")
		(net "P3E_CPU1_PE3_MP_TXN<4>")
	)
	(segment
		(start 16.61287 -31.05277)
		(end 16.61287 -31.42742)
		(width 0.1143)
		(layer "In9.Cu")
		(net "P3E_CPU1_PE3_MP_TXN<4>")
	)
	(segment
		(start 64.97955 -101.882194)
		(end 62.488572 -89.4207)
		(width 0.1143)
		(layer "In9.Cu")
		(net "P3E_CPU1_PE3_MP_TXN<4>")
	)
	(segment
		(start 17.447768 -30.94355)
		(end 16.72209 -30.94355)
		(width 0.1143)
		(layer "In9.Cu")
		(net "P3E_CPU1_PE3_MP_TXN<4>")
	)
	(segment
		(start 63.44793 -60.114688)
		(end 63.448184 -60.114688)
		(width 0.1143)
		(layer "In9.Cu")
		(net "P3E_CPU1_PE3_MP_TXN<4>")
	)
	(segment
		(start 27.095196 -30.075886)
		(end 23.296372 -30.08503)
		(width 0.1143)
		(layer "In9.Cu")
		(net "P3E_CPU1_PE3_MP_TXN<4>")
	)
	(segment
		(start 64.985138 -76.936854)
		(end 62.534546 -64.68237)
		(width 0.1143)
		(layer "In9.Cu")
		(net "P3E_CPU1_PE3_MP_TXN<4>")
	)
	(segment
		(start 37.37737 -33.631632)
		(end 37.161724 -33.720786)
		(width 0.1143)
		(layer "In9.Cu")
		(net "P3E_CPU1_PE3_MP_TXN<4>")
	)
	(segment
		(start 135.64743 -102.732586)
		(end 135.712454 -102.845616)
		(width 0.0889)
		(layer "In9.Cu")
		(net "P3E_CPU1_PE3_MP_TXN<4>")
	)
	(segment
		(start 31.994348 -31.402782)
		(end 31.658052 -31.335472)
		(width 0.1143)
		(layer "In9.Cu")
		(net "P3E_CPU1_PE3_MP_TXN<4>")
	)
	(segment
		(start 130.236468 -106.009186)
		(end 128.099312 -105.581958)
		(width 0.1143)
		(layer "In9.Cu")
		(net "P3E_CPU1_PE3_MP_TXN<4>")
	)
	(segment
		(start 36.755324 -33.374076)
		(end 36.438586 -33.242758)
		(width 0.1143)
		(layer "In9.Cu")
		(net "P3E_CPU1_PE3_MP_TXN<4>")
	)
	(segment
		(start 35.906202 -33.201102)
		(end 35.816794 -32.985456)
		(width 0.1143)
		(layer "In9.Cu")
		(net "P3E_CPU1_PE3_MP_TXN<4>")
	)
	(segment
		(start 37.694108 -33.762696)
		(end 37.37737 -33.631632)
		(width 0.1143)
		(layer "In9.Cu")
		(net "P3E_CPU1_PE3_MP_TXN<4>")
	)
	(segment
		(start 30.99816 -31.203392)
		(end 30.661864 -31.136336)
		(width 0.1143)
		(layer "In9.Cu")
		(net "P3E_CPU1_PE3_MP_TXN<4>")
	)
	(segment
		(start 30.131258 -31.198566)
		(end 30.001718 -31.004256)
		(width 0.1143)
		(layer "In9.Cu")
		(net "P3E_CPU1_PE3_MP_TXN<4>")
	)
	(arc
		(start 135.607044 -101.672136)
		(mid 135.686266 -101.961254)
		(end 135.613394 -102.252018)
		(width 0.0889)
		(layer "In9.Cu")
		(net "P3E_CPU1_PE3_MP_TXN<4>")
	)
	(arc
		(start 135.895842 -101.075998)
		(mid 135.593573 -101.297547)
		(end 135.607044 -101.672136)
		(width 0.0889)
		(layer "In9.Cu")
		(net "P3E_CPU1_PE3_MP_TXN<4>")
	)
	(arc
		(start 135.602218 -102.271322)
		(mid 135.553463 -102.467674)
		(end 135.607044 -102.662736)
		(width 0.0889)
		(layer "In9.Cu")
		(net "P3E_CPU1_PE3_MP_TXN<4>")
	)
	(segment
		(start 133.665214 -100.481638)
		(end 134.236714 -100.481638)
		(width 0.1143)
		(layer "F.Cu")
		(net "P3E_CPU1_PE3_MP_TXN<3>")
	)
	(segment
		(start 15.4178 -28.78455)
		(end 15.4178 -28.3845)
		(width 0.1143)
		(layer "F.Cu")
		(net "P3E_CPU1_PE3_MP_TXN<3>")
	)
	(segment
		(start 15.306802 -28.895548)
		(end 15.4178 -28.78455)
		(width 0.1143)
		(layer "F.Cu")
		(net "P3E_CPU1_PE3_MP_TXN<3>")
	)
	(segment
		(start 14.7828 -28.575)
		(end 15.103348 -28.895548)
		(width 0.1143)
		(layer "F.Cu")
		(net "P3E_CPU1_PE3_MP_TXN<3>")
	)
	(segment
		(start 15.103348 -28.895548)
		(end 15.306802 -28.895548)
		(width 0.1143)
		(layer "F.Cu")
		(net "P3E_CPU1_PE3_MP_TXN<3>")
	)
	(via
		(at 15.4178 -28.3845)
		(size 0.508)
		(drill 0.254)
		(layers "F.Cu" "B.Cu")
		(net "P3E_CPU1_PE3_MP_TXN<3>")
	)
	(via
		(at 134.236714 -100.481638)
		(size 0.508)
		(drill 0.254)
		(layers "F.Cu" "B.Cu")
		(net "P3E_CPU1_PE3_MP_TXN<3>")
	)
	(segment
		(start 36.783518 -32.046164)
		(end 36.567872 -32.135572)
		(width 0.1143)
		(layer "In9.Cu")
		(net "P3E_CPU1_PE3_MP_TXN<3>")
	)
	(segment
		(start 38.03904 -32.566356)
		(end 37.722302 -32.435038)
		(width 0.1143)
		(layer "In9.Cu")
		(net "P3E_CPU1_PE3_MP_TXN<3>")
	)
	(segment
		(start 34.906204 -31.26867)
		(end 34.690558 -31.358078)
		(width 0.1143)
		(layer "In9.Cu")
		(net "P3E_CPU1_PE3_MP_TXN<3>")
	)
	(segment
		(start 37.722302 -32.435038)
		(end 37.506402 -32.524446)
		(width 0.1143)
		(layer "In9.Cu")
		(net "P3E_CPU1_PE3_MP_TXN<3>")
	)
	(segment
		(start 15.4178 -28.746704)
		(end 15.4178 -28.3845)
		(width 0.1143)
		(layer "In9.Cu")
		(net "P3E_CPU1_PE3_MP_TXN<3>")
	)
	(segment
		(start 110.554008 -105.918)
		(end 106.742484 -106.680254)
		(width 0.1143)
		(layer "In9.Cu")
		(net "P3E_CPU1_PE3_MP_TXN<3>")
	)
	(segment
		(start 133.413754 -104.295956)
		(end 133.28777 -104.42194)
		(width 0.0889)
		(layer "In9.Cu")
		(net "P3E_CPU1_PE3_MP_TXN<3>")
	)
	(segment
		(start 37.100256 -32.177482)
		(end 36.783518 -32.046164)
		(width 0.1143)
		(layer "In9.Cu")
		(net "P3E_CPU1_PE3_MP_TXN<3>")
	)
	(segment
		(start 134.583424 -101.272086)
		(end 134.58825 -101.280722)
		(width 0.0889)
		(layer "In9.Cu")
		(net "P3E_CPU1_PE3_MP_TXN<3>")
	)
	(segment
		(start 31.646622 -30.097222)
		(end 31.557214 -29.881576)
		(width 0.1143)
		(layer "In9.Cu")
		(net "P3E_CPU1_PE3_MP_TXN<3>")
	)
	(segment
		(start 133.905244 -103.918258)
		(end 133.78307 -103.918258)
		(width 0.0889)
		(layer "In9.Cu")
		(net "P3E_CPU1_PE3_MP_TXN<3>")
	)
	(segment
		(start 132.069332 -104.99725)
		(end 132.047234 -104.99725)
		(width 0.0889)
		(layer "In9.Cu")
		(net "P3E_CPU1_PE3_MP_TXN<3>")
	)
	(segment
		(start 38.128448 -32.782002)
		(end 38.03904 -32.566356)
		(width 0.1143)
		(layer "In9.Cu")
		(net "P3E_CPU1_PE3_MP_TXN<3>")
	)
	(segment
		(start 132.775452 -105.04805)
		(end 132.120132 -105.04805)
		(width 0.0889)
		(layer "In9.Cu")
		(net "P3E_CPU1_PE3_MP_TXN<3>")
	)
	(segment
		(start 35.222942 -31.399988)
		(end 34.906204 -31.26867)
		(width 0.1143)
		(layer "In9.Cu")
		(net "P3E_CPU1_PE3_MP_TXN<3>")
	)
	(segment
		(start 134.577074 -102.252018)
		(end 134.583424 -102.262686)
		(width 0.0889)
		(layer "In9.Cu")
		(net "P3E_CPU1_PE3_MP_TXN<3>")
	)
	(segment
		(start 18.676112 -29.139642)
		(end 18.00352 -28.861004)
		(width 0.1143)
		(layer "In9.Cu")
		(net "P3E_CPU1_PE3_MP_TXN<3>")
	)
	(segment
		(start 134.03072 -103.792782)
		(end 133.905244 -103.918258)
		(width 0.0889)
		(layer "In9.Cu")
		(net "P3E_CPU1_PE3_MP_TXN<3>")
	)
	(segment
		(start 106.742484 -106.680254)
		(end 98.044 -104.9401)
		(width 0.1143)
		(layer "In9.Cu")
		(net "P3E_CPU1_PE3_MP_TXN<3>")
	)
	(segment
		(start 66.826892 -102.819454)
		(end 65.818512 -101.305868)
		(width 0.1143)
		(layer "In9.Cu")
		(net "P3E_CPU1_PE3_MP_TXN<3>")
	)
	(segment
		(start 134.156704 -103.544624)
		(end 134.03072 -103.670608)
		(width 0.0889)
		(layer "In9.Cu")
		(net "P3E_CPU1_PE3_MP_TXN<3>")
	)
	(segment
		(start 128.154684 -104.584246)
		(end 116.019072 -107.01147)
		(width 0.1143)
		(layer "In9.Cu")
		(net "P3E_CPU1_PE3_MP_TXN<3>")
	)
	(segment
		(start 31.557214 -29.881576)
		(end 31.240222 -29.750512)
		(width 0.1143)
		(layer "In9.Cu")
		(net "P3E_CPU1_PE3_MP_TXN<3>")
	)
	(segment
		(start 116.019072 -107.01147)
		(end 110.554008 -105.918)
		(width 0.1143)
		(layer "In9.Cu")
		(net "P3E_CPU1_PE3_MP_TXN<3>")
	)
	(segment
		(start 134.52983 -100.650548)
		(end 134.553706 -100.739702)
		(width 0.0889)
		(layer "In9.Cu")
		(net "P3E_CPU1_PE3_MP_TXN<3>")
	)
	(segment
		(start 134.583424 -102.662482)
		(end 134.42188 -102.942136)
		(width 0.0889)
		(layer "In9.Cu")
		(net "P3E_CPU1_PE3_MP_TXN<3>")
	)
	(segment
		(start 18.00352 -28.861004)
		(end 15.5321 -28.861004)
		(width 0.1143)
		(layer "In9.Cu")
		(net "P3E_CPU1_PE3_MP_TXN<3>")
	)
	(segment
		(start 35.629088 -31.746952)
		(end 35.31235 -31.615634)
		(width 0.1143)
		(layer "In9.Cu")
		(net "P3E_CPU1_PE3_MP_TXN<3>")
	)
	(segment
		(start 41.764712 -35.643312)
		(end 39.45128 -33.32988)
		(width 0.1143)
		(layer "In9.Cu")
		(net "P3E_CPU1_PE3_MP_TXN<3>")
	)
	(segment
		(start 32.179006 -30.139132)
		(end 31.96336 -30.22854)
		(width 0.1143)
		(layer "In9.Cu")
		(net "P3E_CPU1_PE3_MP_TXN<3>")
	)
	(segment
		(start 130.223006 -104.99725)
		(end 128.154684 -104.584246)
		(width 0.1143)
		(layer "In9.Cu")
		(net "P3E_CPU1_PE3_MP_TXN<3>")
	)
	(segment
		(start 133.527546 -104.295956)
		(end 133.413754 -104.295956)
		(width 0.0889)
		(layer "In9.Cu")
		(net "P3E_CPU1_PE3_MP_TXN<3>")
	)
	(segment
		(start 98.044 -104.9401)
		(end 92.480892 -106.05262)
		(width 0.1143)
		(layer "In9.Cu")
		(net "P3E_CPU1_PE3_MP_TXN<3>")
	)
	(segment
		(start 37.506402 -32.524446)
		(end 37.189664 -32.393128)
		(width 0.1143)
		(layer "In9.Cu")
		(net "P3E_CPU1_PE3_MP_TXN<3>")
	)
	(segment
		(start 134.42188 -103.401622)
		(end 134.278878 -103.544624)
		(width 0.0889)
		(layer "In9.Cu")
		(net "P3E_CPU1_PE3_MP_TXN<3>")
	)
	(segment
		(start 132.120132 -105.04805)
		(end 132.069332 -104.99725)
		(width 0.0889)
		(layer "In9.Cu")
		(net "P3E_CPU1_PE3_MP_TXN<3>")
	)
	(segment
		(start 56.907684 -45.740574)
		(end 41.764712 -35.643312)
		(width 0.1143)
		(layer "In9.Cu")
		(net "P3E_CPU1_PE3_MP_TXN<3>")
	)
	(segment
		(start 34.690558 -31.358078)
		(end 32.585152 -30.486096)
		(width 0.1143)
		(layer "In9.Cu")
		(net "P3E_CPU1_PE3_MP_TXN<3>")
	)
	(segment
		(start 133.28777 -104.535732)
		(end 132.775452 -105.04805)
		(width 0.0889)
		(layer "In9.Cu")
		(net "P3E_CPU1_PE3_MP_TXN<3>")
	)
	(segment
		(start 35.844734 -31.657544)
		(end 35.629088 -31.746952)
		(width 0.1143)
		(layer "In9.Cu")
		(net "P3E_CPU1_PE3_MP_TXN<3>")
	)
	(segment
		(start 133.28777 -104.42194)
		(end 133.28777 -104.535732)
		(width 0.0889)
		(layer "In9.Cu")
		(net "P3E_CPU1_PE3_MP_TXN<3>")
	)
	(segment
		(start 92.480892 -106.05262)
		(end 83.65871 -104.288082)
		(width 0.1143)
		(layer "In9.Cu")
		(net "P3E_CPU1_PE3_MP_TXN<3>")
	)
	(segment
		(start 39.45128 -33.32988)
		(end 38.128448 -32.782002)
		(width 0.1143)
		(layer "In9.Cu")
		(net "P3E_CPU1_PE3_MP_TXN<3>")
	)
	(segment
		(start 65.948306 -76.91247)
		(end 63.50381 -64.687704)
		(width 0.1143)
		(layer "In9.Cu")
		(net "P3E_CPU1_PE3_MP_TXN<3>")
	)
	(segment
		(start 31.96336 -30.22854)
		(end 31.646622 -30.097222)
		(width 0.1143)
		(layer "In9.Cu")
		(net "P3E_CPU1_PE3_MP_TXN<3>")
	)
	(segment
		(start 15.5321 -28.861004)
		(end 15.4178 -28.746704)
		(width 0.1143)
		(layer "In9.Cu")
		(net "P3E_CPU1_PE3_MP_TXN<3>")
	)
	(segment
		(start 133.657086 -104.044242)
		(end 133.657086 -104.166416)
		(width 0.0889)
		(layer "In9.Cu")
		(net "P3E_CPU1_PE3_MP_TXN<3>")
	)
	(segment
		(start 134.278878 -103.544624)
		(end 134.156704 -103.544624)
		(width 0.0889)
		(layer "In9.Cu")
		(net "P3E_CPU1_PE3_MP_TXN<3>")
	)
	(segment
		(start 63.444374 -89.433146)
		(end 65.948306 -76.91247)
		(width 0.1143)
		(layer "In9.Cu")
		(net "P3E_CPU1_PE3_MP_TXN<3>")
	)
	(segment
		(start 36.567872 -32.135572)
		(end 36.25088 -32.004508)
		(width 0.1143)
		(layer "In9.Cu")
		(net "P3E_CPU1_PE3_MP_TXN<3>")
	)
	(segment
		(start 65.818512 -101.305868)
		(end 63.444374 -89.433146)
		(width 0.1143)
		(layer "In9.Cu")
		(net "P3E_CPU1_PE3_MP_TXN<3>")
	)
	(segment
		(start 133.78307 -103.918258)
		(end 133.657086 -104.044242)
		(width 0.0889)
		(layer "In9.Cu")
		(net "P3E_CPU1_PE3_MP_TXN<3>")
	)
	(segment
		(start 134.583424 -102.262686)
		(end 134.58825 -102.271322)
		(width 0.0889)
		(layer "In9.Cu")
		(net "P3E_CPU1_PE3_MP_TXN<3>")
	)
	(segment
		(start 31.024576 -29.839666)
		(end 29.334206 -29.139642)
		(width 0.1143)
		(layer "In9.Cu")
		(net "P3E_CPU1_PE3_MP_TXN<3>")
	)
	(segment
		(start 83.65871 -104.288082)
		(end 75.253088 -105.969308)
		(width 0.1143)
		(layer "In9.Cu")
		(net "P3E_CPU1_PE3_MP_TXN<3>")
	)
	(segment
		(start 75.253088 -105.969308)
		(end 69.968364 -104.91216)
		(width 0.1143)
		(layer "In9.Cu")
		(net "P3E_CPU1_PE3_MP_TXN<3>")
	)
	(segment
		(start 36.161726 -31.788608)
		(end 35.844734 -31.657544)
		(width 0.1143)
		(layer "In9.Cu")
		(net "P3E_CPU1_PE3_MP_TXN<3>")
	)
	(segment
		(start 36.25088 -32.004508)
		(end 36.161726 -31.788608)
		(width 0.1143)
		(layer "In9.Cu")
		(net "P3E_CPU1_PE3_MP_TXN<3>")
	)
	(segment
		(start 35.31235 -31.615634)
		(end 35.222942 -31.399988)
		(width 0.1143)
		(layer "In9.Cu")
		(net "P3E_CPU1_PE3_MP_TXN<3>")
	)
	(segment
		(start 31.240222 -29.750512)
		(end 31.024576 -29.839666)
		(width 0.1143)
		(layer "In9.Cu")
		(net "P3E_CPU1_PE3_MP_TXN<3>")
	)
	(segment
		(start 37.189664 -32.393128)
		(end 37.100256 -32.177482)
		(width 0.1143)
		(layer "In9.Cu")
		(net "P3E_CPU1_PE3_MP_TXN<3>")
	)
	(segment
		(start 64.437768 -60.01766)
		(end 63.584582 -55.755794)
		(width 0.1143)
		(layer "In9.Cu")
		(net "P3E_CPU1_PE3_MP_TXN<3>")
	)
	(segment
		(start 132.047234 -104.99725)
		(end 130.223006 -104.99725)
		(width 0.1143)
		(layer "In9.Cu")
		(net "P3E_CPU1_PE3_MP_TXN<3>")
	)
	(segment
		(start 32.495744 -30.27045)
		(end 32.179006 -30.139132)
		(width 0.1143)
		(layer "In9.Cu")
		(net "P3E_CPU1_PE3_MP_TXN<3>")
	)
	(segment
		(start 32.585152 -30.486096)
		(end 32.495744 -30.27045)
		(width 0.1143)
		(layer "In9.Cu")
		(net "P3E_CPU1_PE3_MP_TXN<3>")
	)
	(segment
		(start 134.236714 -100.481638)
		(end 134.52983 -100.650548)
		(width 0.0889)
		(layer "In9.Cu")
		(net "P3E_CPU1_PE3_MP_TXN<3>")
	)
	(segment
		(start 63.50381 -64.687704)
		(end 64.437768 -60.01766)
		(width 0.1143)
		(layer "In9.Cu")
		(net "P3E_CPU1_PE3_MP_TXN<3>")
	)
	(segment
		(start 134.42188 -102.942136)
		(end 134.42188 -103.401622)
		(width 0.0889)
		(layer "In9.Cu")
		(net "P3E_CPU1_PE3_MP_TXN<3>")
	)
	(segment
		(start 133.657086 -104.166416)
		(end 133.527546 -104.295956)
		(width 0.0889)
		(layer "In9.Cu")
		(net "P3E_CPU1_PE3_MP_TXN<3>")
	)
	(segment
		(start 63.584582 -55.755794)
		(end 56.907684 -45.740574)
		(width 0.1143)
		(layer "In9.Cu")
		(net "P3E_CPU1_PE3_MP_TXN<3>")
	)
	(segment
		(start 29.334206 -29.139642)
		(end 18.676112 -29.139642)
		(width 0.1143)
		(layer "In9.Cu")
		(net "P3E_CPU1_PE3_MP_TXN<3>")
	)
	(segment
		(start 69.968364 -104.91216)
		(end 66.826892 -102.819454)
		(width 0.1143)
		(layer "In9.Cu")
		(net "P3E_CPU1_PE3_MP_TXN<3>")
	)
	(segment
		(start 134.03072 -103.670608)
		(end 134.03072 -103.792782)
		(width 0.0889)
		(layer "In9.Cu")
		(net "P3E_CPU1_PE3_MP_TXN<3>")
	)
	(arc
		(start 134.58825 -101.280722)
		(mid 134.637005 -101.477074)
		(end 134.583424 -101.672136)
		(width 0.0889)
		(layer "In9.Cu")
		(net "P3E_CPU1_PE3_MP_TXN<3>")
	)
	(arc
		(start 134.58825 -102.271322)
		(mid 134.636882 -102.46753)
		(end 134.583424 -102.662482)
		(width 0.0889)
		(layer "In9.Cu")
		(net "P3E_CPU1_PE3_MP_TXN<3>")
	)
	(arc
		(start 134.583424 -101.672136)
		(mid 134.504202 -101.961254)
		(end 134.577074 -102.252018)
		(width 0.0889)
		(layer "In9.Cu")
		(net "P3E_CPU1_PE3_MP_TXN<3>")
	)
	(arc
		(start 134.553706 -100.739702)
		(mid 134.505146 -101.009427)
		(end 134.583424 -101.272086)
		(width 0.0889)
		(layer "In9.Cu")
		(net "P3E_CPU1_PE3_MP_TXN<3>")
	)
	(segment
		(start 132.806694 -101.967538)
		(end 133.378194 -101.967538)
		(width 0.1143)
		(layer "F.Cu")
		(net "P3E_CPU1_PE3_MP_TXN<2>")
	)
	(segment
		(start 16.607536 -27.00655)
		(end 16.607536 -26.6065)
		(width 0.1143)
		(layer "F.Cu")
		(net "P3E_CPU1_PE3_MP_TXN<2>")
	)
	(segment
		(start 16.493236 -27.12085)
		(end 16.607536 -27.00655)
		(width 0.1143)
		(layer "F.Cu")
		(net "P3E_CPU1_PE3_MP_TXN<2>")
	)
	(segment
		(start 15.10665 -27.12085)
		(end 16.493236 -27.12085)
		(width 0.1143)
		(layer "F.Cu")
		(net "P3E_CPU1_PE3_MP_TXN<2>")
	)
	(segment
		(start 14.7828 -26.797)
		(end 15.10665 -27.12085)
		(width 0.1143)
		(layer "F.Cu")
		(net "P3E_CPU1_PE3_MP_TXN<2>")
	)
	(via
		(at 133.378194 -101.967538)
		(size 0.508)
		(drill 0.254)
		(layers "F.Cu" "B.Cu")
		(net "P3E_CPU1_PE3_MP_TXN<2>")
	)
	(via
		(at 16.607536 -26.6065)
		(size 0.508)
		(drill 0.254)
		(layers "F.Cu" "B.Cu")
		(net "P3E_CPU1_PE3_MP_TXN<2>")
	)
	(segment
		(start 44.63034 -36.723066)
		(end 57.455054 -45.276008)
		(width 0.1143)
		(layer "In9.Cu")
		(net "P3E_CPU1_PE3_MP_TXN<2>")
	)
	(segment
		(start 133.336284 -103.569262)
		(end 133.7818 -103.123746)
		(width 0.0889)
		(layer "In9.Cu")
		(net "P3E_CPU1_PE3_MP_TXN<2>")
	)
	(segment
		(start 128.067308 -103.903526)
		(end 129.862326 -104.268524)
		(width 0.1143)
		(layer "In9.Cu")
		(net "P3E_CPU1_PE3_MP_TXN<2>")
	)
	(segment
		(start 39.993316 -32.707326)
		(end 40.016176 -32.939736)
		(width 0.1143)
		(layer "In9.Cu")
		(net "P3E_CPU1_PE3_MP_TXN<2>")
	)
	(segment
		(start 133.7818 -102.856792)
		(end 133.753606 -102.80777)
		(width 0.0889)
		(layer "In9.Cu")
		(net "P3E_CPU1_PE3_MP_TXN<2>")
	)
	(segment
		(start 106.74223 -105.993692)
		(end 110.94212 -105.15346)
		(width 0.1143)
		(layer "In9.Cu")
		(net "P3E_CPU1_PE3_MP_TXN<2>")
	)
	(segment
		(start 132.714746 -104.1908)
		(end 132.714746 -104.06888)
		(width 0.0889)
		(layer "In9.Cu")
		(net "P3E_CPU1_PE3_MP_TXN<2>")
	)
	(segment
		(start 133.67131 -101.798374)
		(end 133.5024 -101.89591)
		(width 0.0889)
		(layer "In9.Cu")
		(net "P3E_CPU1_PE3_MP_TXN<2>")
	)
	(segment
		(start 130.806952 -104.319324)
		(end 131.001262 -104.319324)
		(width 0.0889)
		(layer "In9.Cu")
		(net "P3E_CPU1_PE3_MP_TXN<2>")
	)
	(segment
		(start 40.016176 -32.939736)
		(end 40.281352 -33.15716)
		(width 0.1143)
		(layer "In9.Cu")
		(net "P3E_CPU1_PE3_MP_TXN<2>")
	)
	(segment
		(start 132.057902 -104.319324)
		(end 132.144262 -104.232964)
		(width 0.0889)
		(layer "In9.Cu")
		(net "P3E_CPU1_PE3_MP_TXN<2>")
	)
	(segment
		(start 65.133982 -59.9694)
		(end 64.172338 -64.778128)
		(width 0.1143)
		(layer "In9.Cu")
		(net "P3E_CPU1_PE3_MP_TXN<2>")
	)
	(segment
		(start 40.778938 -33.351724)
		(end 40.801798 -33.58388)
		(width 0.1143)
		(layer "In9.Cu")
		(net "P3E_CPU1_PE3_MP_TXN<2>")
	)
	(segment
		(start 40.513762 -33.1343)
		(end 40.778938 -33.351724)
		(width 0.1143)
		(layer "In9.Cu")
		(net "P3E_CPU1_PE3_MP_TXN<2>")
	)
	(segment
		(start 132.322062 -104.232964)
		(end 132.408422 -104.319324)
		(width 0.0889)
		(layer "In9.Cu")
		(net "P3E_CPU1_PE3_MP_TXN<2>")
	)
	(segment
		(start 133.753352 -102.807262)
		(end 133.72465 -102.757986)
		(width 0.0889)
		(layer "In9.Cu")
		(net "P3E_CPU1_PE3_MP_TXN<2>")
	)
	(segment
		(start 41.56456 -33.995868)
		(end 41.587674 -34.228278)
		(width 0.1143)
		(layer "In9.Cu")
		(net "P3E_CPU1_PE3_MP_TXN<2>")
	)
	(segment
		(start 19.031966 -27.67584)
		(end 19.320256 -27.38755)
		(width 0.1143)
		(layer "In9.Cu")
		(net "P3E_CPU1_PE3_MP_TXN<2>")
	)
	(segment
		(start 67.25412 -102.258114)
		(end 69.779896 -103.941118)
		(width 0.1143)
		(layer "In9.Cu")
		(net "P3E_CPU1_PE3_MP_TXN<2>")
	)
	(segment
		(start 16.607536 -26.98115)
		(end 16.721836 -27.09545)
		(width 0.1143)
		(layer "In9.Cu")
		(net "P3E_CPU1_PE3_MP_TXN<2>")
	)
	(segment
		(start 64.226186 -55.431944)
		(end 65.133982 -59.9694)
		(width 0.1143)
		(layer "In9.Cu")
		(net "P3E_CPU1_PE3_MP_TXN<2>")
	)
	(segment
		(start 28.04287 -27.38755)
		(end 32.16021 -29.09316)
		(width 0.1143)
		(layer "In9.Cu")
		(net "P3E_CPU1_PE3_MP_TXN<2>")
	)
	(segment
		(start 133.724904 -102.167436)
		(end 133.72973 -102.1588)
		(width 0.0889)
		(layer "In9.Cu")
		(net "P3E_CPU1_PE3_MP_TXN<2>")
	)
	(segment
		(start 41.299384 -33.778444)
		(end 41.56456 -33.995868)
		(width 0.1143)
		(layer "In9.Cu")
		(net "P3E_CPU1_PE3_MP_TXN<2>")
	)
	(segment
		(start 133.753606 -102.80777)
		(end 133.753352 -102.807262)
		(width 0.0889)
		(layer "In9.Cu")
		(net "P3E_CPU1_PE3_MP_TXN<2>")
	)
	(segment
		(start 39.49573 -32.513016)
		(end 39.72814 -32.489902)
		(width 0.1143)
		(layer "In9.Cu")
		(net "P3E_CPU1_PE3_MP_TXN<2>")
	)
	(segment
		(start 64.117474 -89.319608)
		(end 66.469006 -101.079554)
		(width 0.1143)
		(layer "In9.Cu")
		(net "P3E_CPU1_PE3_MP_TXN<2>")
	)
	(segment
		(start 33.720532 -29.73959)
		(end 34.037524 -29.870654)
		(width 0.1143)
		(layer "In9.Cu")
		(net "P3E_CPU1_PE3_MP_TXN<2>")
	)
	(segment
		(start 32.692594 -29.134816)
		(end 32.782002 -29.350716)
		(width 0.1143)
		(layer "In9.Cu")
		(net "P3E_CPU1_PE3_MP_TXN<2>")
	)
	(segment
		(start 131.880102 -104.319324)
		(end 132.057902 -104.319324)
		(width 0.0889)
		(layer "In9.Cu")
		(net "P3E_CPU1_PE3_MP_TXN<2>")
	)
	(segment
		(start 97.91954 -104.228646)
		(end 106.74223 -105.993692)
		(width 0.1143)
		(layer "In9.Cu")
		(net "P3E_CPU1_PE3_MP_TXN<2>")
	)
	(segment
		(start 34.569908 -29.912564)
		(end 34.659316 -30.12821)
		(width 0.1143)
		(layer "In9.Cu")
		(net "P3E_CPU1_PE3_MP_TXN<2>")
	)
	(segment
		(start 130.179318 -104.319324)
		(end 130.489452 -104.319324)
		(width 0.0889)
		(layer "In9.Cu")
		(net "P3E_CPU1_PE3_MP_TXN<2>")
	)
	(segment
		(start 41.587674 -34.228278)
		(end 44.63034 -36.723066)
		(width 0.1143)
		(layer "In9.Cu")
		(net "P3E_CPU1_PE3_MP_TXN<2>")
	)
	(segment
		(start 132.408422 -104.319324)
		(end 132.586222 -104.319324)
		(width 0.0889)
		(layer "In9.Cu")
		(net "P3E_CPU1_PE3_MP_TXN<2>")
	)
	(segment
		(start 32.782002 -29.350716)
		(end 33.09874 -29.48178)
		(width 0.1143)
		(layer "In9.Cu")
		(net "P3E_CPU1_PE3_MP_TXN<2>")
	)
	(segment
		(start 66.469006 -101.080062)
		(end 67.25412 -102.258114)
		(width 0.1143)
		(layer "In9.Cu")
		(net "P3E_CPU1_PE3_MP_TXN<2>")
	)
	(segment
		(start 130.128518 -104.268524)
		(end 130.179318 -104.319324)
		(width 0.0889)
		(layer "In9.Cu")
		(net "P3E_CPU1_PE3_MP_TXN<2>")
	)
	(segment
		(start 17.952466 -27.67584)
		(end 19.031966 -27.67584)
		(width 0.1143)
		(layer "In9.Cu")
		(net "P3E_CPU1_PE3_MP_TXN<2>")
	)
	(segment
		(start 110.94212 -105.15346)
		(end 116.379752 -106.241088)
		(width 0.1143)
		(layer "In9.Cu")
		(net "P3E_CPU1_PE3_MP_TXN<2>")
	)
	(segment
		(start 133.088126 -103.81742)
		(end 133.088126 -103.695246)
		(width 0.0889)
		(layer "In9.Cu")
		(net "P3E_CPU1_PE3_MP_TXN<2>")
	)
	(segment
		(start 33.631378 -29.52369)
		(end 33.720532 -29.73959)
		(width 0.1143)
		(layer "In9.Cu")
		(net "P3E_CPU1_PE3_MP_TXN<2>")
	)
	(segment
		(start 129.862326 -104.268524)
		(end 130.10642 -104.268524)
		(width 0.1143)
		(layer "In9.Cu")
		(net "P3E_CPU1_PE3_MP_TXN<2>")
	)
	(segment
		(start 130.489452 -104.319324)
		(end 130.559302 -104.249474)
		(width 0.0889)
		(layer "In9.Cu")
		(net "P3E_CPU1_PE3_MP_TXN<2>")
	)
	(segment
		(start 130.737102 -104.249474)
		(end 130.806952 -104.319324)
		(width 0.0889)
		(layer "In9.Cu")
		(net "P3E_CPU1_PE3_MP_TXN<2>")
	)
	(segment
		(start 132.84073 -103.942896)
		(end 132.96265 -103.942896)
		(width 0.0889)
		(layer "In9.Cu")
		(net "P3E_CPU1_PE3_MP_TXN<2>")
	)
	(segment
		(start 83.751166 -103.620062)
		(end 92.356686 -105.341166)
		(width 0.1143)
		(layer "In9.Cu")
		(net "P3E_CPU1_PE3_MP_TXN<2>")
	)
	(segment
		(start 32.375856 -29.003752)
		(end 32.692594 -29.134816)
		(width 0.1143)
		(layer "In9.Cu")
		(net "P3E_CPU1_PE3_MP_TXN<2>")
	)
	(segment
		(start 131.793742 -104.232964)
		(end 131.880102 -104.319324)
		(width 0.0889)
		(layer "In9.Cu")
		(net "P3E_CPU1_PE3_MP_TXN<2>")
	)
	(segment
		(start 57.455054 -45.276008)
		(end 64.226186 -55.431944)
		(width 0.1143)
		(layer "In9.Cu")
		(net "P3E_CPU1_PE3_MP_TXN<2>")
	)
	(segment
		(start 40.281352 -33.15716)
		(end 40.513762 -33.1343)
		(width 0.1143)
		(layer "In9.Cu")
		(net "P3E_CPU1_PE3_MP_TXN<2>")
	)
	(segment
		(start 16.607536 -26.6065)
		(end 16.607536 -26.98115)
		(width 0.1143)
		(layer "In9.Cu")
		(net "P3E_CPU1_PE3_MP_TXN<2>")
	)
	(segment
		(start 130.559302 -104.249474)
		(end 130.737102 -104.249474)
		(width 0.0889)
		(layer "In9.Cu")
		(net "P3E_CPU1_PE3_MP_TXN<2>")
	)
	(segment
		(start 131.529582 -104.319324)
		(end 131.615942 -104.232964)
		(width 0.0889)
		(layer "In9.Cu")
		(net "P3E_CPU1_PE3_MP_TXN<2>")
	)
	(segment
		(start 69.779896 -103.941118)
		(end 75.963018 -105.17759)
		(width 0.1143)
		(layer "In9.Cu")
		(net "P3E_CPU1_PE3_MP_TXN<2>")
	)
	(segment
		(start 75.963018 -105.17759)
		(end 83.751166 -103.620062)
		(width 0.1143)
		(layer "In9.Cu")
		(net "P3E_CPU1_PE3_MP_TXN<2>")
	)
	(segment
		(start 39.72814 -32.489902)
		(end 39.993316 -32.707326)
		(width 0.1143)
		(layer "In9.Cu")
		(net "P3E_CPU1_PE3_MP_TXN<2>")
	)
	(segment
		(start 32.16021 -29.09316)
		(end 32.375856 -29.003752)
		(width 0.1143)
		(layer "In9.Cu")
		(net "P3E_CPU1_PE3_MP_TXN<2>")
	)
	(segment
		(start 66.469006 -101.079554)
		(end 66.469006 -101.080062)
		(width 0.1143)
		(layer "In9.Cu")
		(net "P3E_CPU1_PE3_MP_TXN<2>")
	)
	(segment
		(start 133.718554 -102.178104)
		(end 133.724904 -102.167436)
		(width 0.0889)
		(layer "In9.Cu")
		(net "P3E_CPU1_PE3_MP_TXN<2>")
	)
	(segment
		(start 132.96265 -103.942896)
		(end 133.088126 -103.81742)
		(width 0.0889)
		(layer "In9.Cu")
		(net "P3E_CPU1_PE3_MP_TXN<2>")
	)
	(segment
		(start 132.714746 -104.06888)
		(end 132.84073 -103.942896)
		(width 0.0889)
		(layer "In9.Cu")
		(net "P3E_CPU1_PE3_MP_TXN<2>")
	)
	(segment
		(start 132.144262 -104.232964)
		(end 132.322062 -104.232964)
		(width 0.0889)
		(layer "In9.Cu")
		(net "P3E_CPU1_PE3_MP_TXN<2>")
	)
	(segment
		(start 17.127728 -27.09545)
		(end 17.545812 -27.268424)
		(width 0.1143)
		(layer "In9.Cu")
		(net "P3E_CPU1_PE3_MP_TXN<2>")
	)
	(segment
		(start 64.172338 -64.778128)
		(end 64.389 -65.861438)
		(width 0.1143)
		(layer "In9.Cu")
		(net "P3E_CPU1_PE3_MP_TXN<2>")
	)
	(segment
		(start 17.545812 -27.268424)
		(end 17.952466 -27.67584)
		(width 0.1143)
		(layer "In9.Cu")
		(net "P3E_CPU1_PE3_MP_TXN<2>")
	)
	(segment
		(start 131.615942 -104.232964)
		(end 131.793742 -104.232964)
		(width 0.0889)
		(layer "In9.Cu")
		(net "P3E_CPU1_PE3_MP_TXN<2>")
	)
	(segment
		(start 132.586222 -104.319324)
		(end 132.714746 -104.1908)
		(width 0.0889)
		(layer "In9.Cu")
		(net "P3E_CPU1_PE3_MP_TXN<2>")
	)
	(segment
		(start 16.721836 -27.09545)
		(end 17.127728 -27.09545)
		(width 0.1143)
		(layer "In9.Cu")
		(net "P3E_CPU1_PE3_MP_TXN<2>")
	)
	(segment
		(start 131.087622 -104.232964)
		(end 131.265422 -104.232964)
		(width 0.0889)
		(layer "In9.Cu")
		(net "P3E_CPU1_PE3_MP_TXN<2>")
	)
	(segment
		(start 34.037524 -29.870654)
		(end 34.25317 -29.781246)
		(width 0.1143)
		(layer "In9.Cu")
		(net "P3E_CPU1_PE3_MP_TXN<2>")
	)
	(segment
		(start 64.389 -65.861438)
		(end 66.5988 -76.911708)
		(width 0.1143)
		(layer "In9.Cu")
		(net "P3E_CPU1_PE3_MP_TXN<2>")
	)
	(segment
		(start 34.659316 -30.12821)
		(end 38.55593 -31.74238)
		(width 0.1143)
		(layer "In9.Cu")
		(net "P3E_CPU1_PE3_MP_TXN<2>")
	)
	(segment
		(start 131.265422 -104.232964)
		(end 131.351782 -104.319324)
		(width 0.0889)
		(layer "In9.Cu")
		(net "P3E_CPU1_PE3_MP_TXN<2>")
	)
	(segment
		(start 41.066974 -33.801304)
		(end 41.299384 -33.778444)
		(width 0.1143)
		(layer "In9.Cu")
		(net "P3E_CPU1_PE3_MP_TXN<2>")
	)
	(segment
		(start 133.75005 -101.81971)
		(end 133.67131 -101.798374)
		(width 0.0889)
		(layer "In9.Cu")
		(net "P3E_CPU1_PE3_MP_TXN<2>")
	)
	(segment
		(start 33.09874 -29.48178)
		(end 33.314386 -29.392626)
		(width 0.1143)
		(layer "In9.Cu")
		(net "P3E_CPU1_PE3_MP_TXN<2>")
	)
	(segment
		(start 131.351782 -104.319324)
		(end 131.529582 -104.319324)
		(width 0.0889)
		(layer "In9.Cu")
		(net "P3E_CPU1_PE3_MP_TXN<2>")
	)
	(segment
		(start 66.5988 -76.911708)
		(end 64.117474 -89.319608)
		(width 0.1143)
		(layer "In9.Cu")
		(net "P3E_CPU1_PE3_MP_TXN<2>")
	)
	(segment
		(start 34.25317 -29.781246)
		(end 34.569908 -29.912564)
		(width 0.1143)
		(layer "In9.Cu")
		(net "P3E_CPU1_PE3_MP_TXN<2>")
	)
	(segment
		(start 133.21411 -103.569262)
		(end 133.336284 -103.569262)
		(width 0.0889)
		(layer "In9.Cu")
		(net "P3E_CPU1_PE3_MP_TXN<2>")
	)
	(segment
		(start 19.320256 -27.38755)
		(end 28.04287 -27.38755)
		(width 0.1143)
		(layer "In9.Cu")
		(net "P3E_CPU1_PE3_MP_TXN<2>")
	)
	(segment
		(start 130.10642 -104.268524)
		(end 130.128518 -104.268524)
		(width 0.0889)
		(layer "In9.Cu")
		(net "P3E_CPU1_PE3_MP_TXN<2>")
	)
	(segment
		(start 116.379752 -106.241088)
		(end 128.067308 -103.903526)
		(width 0.1143)
		(layer "In9.Cu")
		(net "P3E_CPU1_PE3_MP_TXN<2>")
	)
	(segment
		(start 133.5024 -101.89591)
		(end 133.378194 -101.967538)
		(width 0.0889)
		(layer "In9.Cu")
		(net "P3E_CPU1_PE3_MP_TXN<2>")
	)
	(segment
		(start 40.801798 -33.58388)
		(end 41.066974 -33.801304)
		(width 0.1143)
		(layer "In9.Cu")
		(net "P3E_CPU1_PE3_MP_TXN<2>")
	)
	(segment
		(start 133.088126 -103.695246)
		(end 133.21411 -103.569262)
		(width 0.0889)
		(layer "In9.Cu")
		(net "P3E_CPU1_PE3_MP_TXN<2>")
	)
	(segment
		(start 92.356686 -105.341166)
		(end 97.91954 -104.228646)
		(width 0.1143)
		(layer "In9.Cu")
		(net "P3E_CPU1_PE3_MP_TXN<2>")
	)
	(segment
		(start 133.7818 -103.123746)
		(end 133.7818 -102.856792)
		(width 0.0889)
		(layer "In9.Cu")
		(net "P3E_CPU1_PE3_MP_TXN<2>")
	)
	(segment
		(start 131.001262 -104.319324)
		(end 131.087622 -104.232964)
		(width 0.0889)
		(layer "In9.Cu")
		(net "P3E_CPU1_PE3_MP_TXN<2>")
	)
	(segment
		(start 33.314386 -29.392626)
		(end 33.631378 -29.52369)
		(width 0.1143)
		(layer "In9.Cu")
		(net "P3E_CPU1_PE3_MP_TXN<2>")
	)
	(segment
		(start 38.55593 -31.74238)
		(end 39.49573 -32.513016)
		(width 0.1143)
		(layer "In9.Cu")
		(net "P3E_CPU1_PE3_MP_TXN<2>")
	)
	(arc
		(start 133.72465 -102.757986)
		(mid 133.645586 -102.468838)
		(end 133.718554 -102.178104)
		(width 0.0889)
		(layer "In9.Cu")
		(net "P3E_CPU1_PE3_MP_TXN<2>")
	)
	(arc
		(start 133.72973 -102.1588)
		(mid 133.777643 -101.991515)
		(end 133.75005 -101.81971)
		(width 0.0889)
		(layer "In9.Cu")
		(net "P3E_CPU1_PE3_MP_TXN<2>")
	)
	(segment
		(start 15.088616 -25.602184)
		(end 15.354808 -25.602184)
		(width 0.1143)
		(layer "F.Cu")
		(net "P3E_CPU1_PE3_MP_TXN<1>")
	)
	(segment
		(start 132.806694 -102.958138)
		(end 133.378194 -102.958138)
		(width 0.1143)
		(layer "F.Cu")
		(net "P3E_CPU1_PE3_MP_TXN<1>")
	)
	(segment
		(start 15.354808 -25.602184)
		(end 15.451074 -25.69845)
		(width 0.1143)
		(layer "F.Cu")
		(net "P3E_CPU1_PE3_MP_TXN<1>")
	)
	(segment
		(start 14.7828 -25.908)
		(end 15.088616 -25.602184)
		(width 0.1143)
		(layer "F.Cu")
		(net "P3E_CPU1_PE3_MP_TXN<1>")
	)
	(segment
		(start 15.451074 -25.69845)
		(end 15.443454 -26.0985)
		(width 0.1143)
		(layer "F.Cu")
		(net "P3E_CPU1_PE3_MP_TXN<1>")
	)
	(via
		(at 133.378194 -102.958138)
		(size 0.508)
		(drill 0.254)
		(layers "F.Cu" "B.Cu")
		(net "P3E_CPU1_PE3_MP_TXN<1>")
	)
	(via
		(at 15.443454 -26.0985)
		(size 0.508)
		(drill 0.254)
		(layers "F.Cu" "B.Cu")
		(net "P3E_CPU1_PE3_MP_TXN<1>")
	)
	(segment
		(start 69.921374 -103.542846)
		(end 76.152248 -104.78897)
		(width 0.1143)
		(layer "In9.Cu")
		(net "P3E_CPU1_PE3_MP_TXN<1>")
	)
	(segment
		(start 76.152248 -104.78897)
		(end 83.748626 -103.269796)
		(width 0.1143)
		(layer "In9.Cu")
		(net "P3E_CPU1_PE3_MP_TXN<1>")
	)
	(segment
		(start 111.34217 -104.723438)
		(end 116.70538 -105.79608)
		(width 0.1143)
		(layer "In9.Cu")
		(net "P3E_CPU1_PE3_MP_TXN<1>")
	)
	(segment
		(start 129.873756 -103.900478)
		(end 130.325368 -103.900478)
		(width 0.1143)
		(layer "In9.Cu")
		(net "P3E_CPU1_PE3_MP_TXN<1>")
	)
	(segment
		(start 133.110224 -102.802944)
		(end 133.378194 -102.958138)
		(width 0.0889)
		(layer "In9.Cu")
		(net "P3E_CPU1_PE3_MP_TXN<1>")
	)
	(segment
		(start 132.985764 -102.83698)
		(end 133.110224 -102.802944)
		(width 0.0889)
		(layer "In9.Cu")
		(net "P3E_CPU1_PE3_MP_TXN<1>")
	)
	(segment
		(start 106.994706 -105.59288)
		(end 111.34217 -104.723438)
		(width 0.1143)
		(layer "In9.Cu")
		(net "P3E_CPU1_PE3_MP_TXN<1>")
	)
	(segment
		(start 28.303728 -25.78608)
		(end 28.640024 -25.85339)
		(width 0.1143)
		(layer "In9.Cu")
		(net "P3E_CPU1_PE3_MP_TXN<1>")
	)
	(segment
		(start 29.299916 -25.98547)
		(end 29.636212 -26.05278)
		(width 0.1143)
		(layer "In9.Cu")
		(net "P3E_CPU1_PE3_MP_TXN<1>")
	)
	(segment
		(start 32.376618 -26.601166)
		(end 44.205398 -34.495232)
		(width 0.1143)
		(layer "In9.Cu")
		(net "P3E_CPU1_PE3_MP_TXN<1>")
	)
	(segment
		(start 30.296358 -26.18486)
		(end 30.6324 -26.25217)
		(width 0.1143)
		(layer "In9.Cu")
		(net "P3E_CPU1_PE3_MP_TXN<1>")
	)
	(segment
		(start 31.098236 -26.51379)
		(end 31.292546 -26.38425)
		(width 0.1143)
		(layer "In9.Cu")
		(net "P3E_CPU1_PE3_MP_TXN<1>")
	)
	(segment
		(start 65.497456 -59.901582)
		(end 64.523366 -64.771524)
		(width 0.1143)
		(layer "In9.Cu")
		(net "P3E_CPU1_PE3_MP_TXN<1>")
	)
	(segment
		(start 66.953638 -76.924408)
		(end 66.953384 -76.924408)
		(width 0.1143)
		(layer "In9.Cu")
		(net "P3E_CPU1_PE3_MP_TXN<1>")
	)
	(segment
		(start 29.765752 -26.24709)
		(end 30.102048 -26.3144)
		(width 0.1143)
		(layer "In9.Cu")
		(net "P3E_CPU1_PE3_MP_TXN<1>")
	)
	(segment
		(start 30.6324 -26.25217)
		(end 30.76194 -26.44648)
		(width 0.1143)
		(layer "In9.Cu")
		(net "P3E_CPU1_PE3_MP_TXN<1>")
	)
	(segment
		(start 27.773376 -25.84831)
		(end 28.109418 -25.91562)
		(width 0.1143)
		(layer "In9.Cu")
		(net "P3E_CPU1_PE3_MP_TXN<1>")
	)
	(segment
		(start 130.325368 -103.900478)
		(end 130.347466 -103.900478)
		(width 0.0889)
		(layer "In9.Cu")
		(net "P3E_CPU1_PE3_MP_TXN<1>")
	)
	(segment
		(start 31.292546 -26.38425)
		(end 32.376618 -26.601166)
		(width 0.1143)
		(layer "In9.Cu")
		(net "P3E_CPU1_PE3_MP_TXN<1>")
	)
	(segment
		(start 30.102048 -26.3144)
		(end 30.296358 -26.18486)
		(width 0.1143)
		(layer "In9.Cu")
		(net "P3E_CPU1_PE3_MP_TXN<1>")
	)
	(segment
		(start 128.030986 -103.530654)
		(end 129.873756 -103.900478)
		(width 0.1143)
		(layer "In9.Cu")
		(net "P3E_CPU1_PE3_MP_TXN<1>")
	)
	(segment
		(start 29.636212 -26.05278)
		(end 29.765752 -26.24709)
		(width 0.1143)
		(layer "In9.Cu")
		(net "P3E_CPU1_PE3_MP_TXN<1>")
	)
	(segment
		(start 64.523366 -64.771524)
		(end 66.953638 -76.924408)
		(width 0.1143)
		(layer "In9.Cu")
		(net "P3E_CPU1_PE3_MP_TXN<1>")
	)
	(segment
		(start 132.911596 -102.966012)
		(end 132.985764 -102.83698)
		(width 0.0889)
		(layer "In9.Cu")
		(net "P3E_CPU1_PE3_MP_TXN<1>")
	)
	(segment
		(start 66.820796 -100.973382)
		(end 67.423538 -101.87813)
		(width 0.1143)
		(layer "In9.Cu")
		(net "P3E_CPU1_PE3_MP_TXN<1>")
	)
	(segment
		(start 92.356686 -104.991408)
		(end 98.173286 -103.828088)
		(width 0.1143)
		(layer "In9.Cu")
		(net "P3E_CPU1_PE3_MP_TXN<1>")
	)
	(segment
		(start 116.70538 -105.79608)
		(end 128.030986 -103.530654)
		(width 0.1143)
		(layer "In9.Cu")
		(net "P3E_CPU1_PE3_MP_TXN<1>")
	)
	(segment
		(start 45.792644 -36.875974)
		(end 57.574434 -44.731178)
		(width 0.1143)
		(layer "In9.Cu")
		(net "P3E_CPU1_PE3_MP_TXN<1>")
	)
	(segment
		(start 28.769564 -26.0477)
		(end 29.10586 -26.11501)
		(width 0.1143)
		(layer "In9.Cu")
		(net "P3E_CPU1_PE3_MP_TXN<1>")
	)
	(segment
		(start 15.443454 -26.0985)
		(end 15.451074 -25.72385)
		(width 0.1143)
		(layer "In9.Cu")
		(net "P3E_CPU1_PE3_MP_TXN<1>")
	)
	(segment
		(start 27.30754 -25.58669)
		(end 27.643836 -25.654)
		(width 0.1143)
		(layer "In9.Cu")
		(net "P3E_CPU1_PE3_MP_TXN<1>")
	)
	(segment
		(start 130.398266 -103.849678)
		(end 132.027676 -103.849678)
		(width 0.0889)
		(layer "In9.Cu")
		(net "P3E_CPU1_PE3_MP_TXN<1>")
	)
	(segment
		(start 57.574434 -44.731178)
		(end 64.558164 -55.20563)
		(width 0.1143)
		(layer "In9.Cu")
		(net "P3E_CPU1_PE3_MP_TXN<1>")
	)
	(segment
		(start 29.10586 -26.11501)
		(end 29.299916 -25.98547)
		(width 0.1143)
		(layer "In9.Cu")
		(net "P3E_CPU1_PE3_MP_TXN<1>")
	)
	(segment
		(start 64.558164 -55.20563)
		(end 65.497456 -59.901582)
		(width 0.1143)
		(layer "In9.Cu")
		(net "P3E_CPU1_PE3_MP_TXN<1>")
	)
	(segment
		(start 44.205398 -34.495232)
		(end 45.792644 -36.875974)
		(width 0.1143)
		(layer "In9.Cu")
		(net "P3E_CPU1_PE3_MP_TXN<1>")
	)
	(segment
		(start 66.953384 -76.924408)
		(end 64.482218 -89.281762)
		(width 0.1143)
		(layer "In9.Cu")
		(net "P3E_CPU1_PE3_MP_TXN<1>")
	)
	(segment
		(start 28.109418 -25.91562)
		(end 28.303728 -25.78608)
		(width 0.1143)
		(layer "In9.Cu")
		(net "P3E_CPU1_PE3_MP_TXN<1>")
	)
	(segment
		(start 98.173286 -103.828088)
		(end 106.994706 -105.59288)
		(width 0.1143)
		(layer "In9.Cu")
		(net "P3E_CPU1_PE3_MP_TXN<1>")
	)
	(segment
		(start 15.588234 -25.58669)
		(end 27.30754 -25.58669)
		(width 0.1143)
		(layer "In9.Cu")
		(net "P3E_CPU1_PE3_MP_TXN<1>")
	)
	(segment
		(start 130.347466 -103.900478)
		(end 130.398266 -103.849678)
		(width 0.0889)
		(layer "In9.Cu")
		(net "P3E_CPU1_PE3_MP_TXN<1>")
	)
	(segment
		(start 83.748626 -103.269796)
		(end 92.356686 -104.991408)
		(width 0.1143)
		(layer "In9.Cu")
		(net "P3E_CPU1_PE3_MP_TXN<1>")
	)
	(segment
		(start 28.640024 -25.85339)
		(end 28.769564 -26.0477)
		(width 0.1143)
		(layer "In9.Cu")
		(net "P3E_CPU1_PE3_MP_TXN<1>")
	)
	(segment
		(start 30.76194 -26.44648)
		(end 31.098236 -26.51379)
		(width 0.1143)
		(layer "In9.Cu")
		(net "P3E_CPU1_PE3_MP_TXN<1>")
	)
	(segment
		(start 15.451074 -25.72385)
		(end 15.588234 -25.58669)
		(width 0.1143)
		(layer "In9.Cu")
		(net "P3E_CPU1_PE3_MP_TXN<1>")
	)
	(segment
		(start 27.643836 -25.654)
		(end 27.773376 -25.84831)
		(width 0.1143)
		(layer "In9.Cu")
		(net "P3E_CPU1_PE3_MP_TXN<1>")
	)
	(segment
		(start 64.482218 -89.281762)
		(end 66.820796 -100.973382)
		(width 0.1143)
		(layer "In9.Cu")
		(net "P3E_CPU1_PE3_MP_TXN<1>")
	)
	(segment
		(start 67.423538 -101.87813)
		(end 69.921374 -103.542846)
		(width 0.1143)
		(layer "In9.Cu")
		(net "P3E_CPU1_PE3_MP_TXN<1>")
	)
	(segment
		(start 132.027676 -103.849678)
		(end 132.911596 -102.966012)
		(width 0.0889)
		(layer "In9.Cu")
		(net "P3E_CPU1_PE3_MP_TXN<1>")
	)
	(segment
		(start 131.089908 -102.958138)
		(end 131.661408 -102.958138)
		(width 0.1143)
		(layer "F.Cu")
		(net "P3E_CPU1_PE3_MP_TXN<0>")
	)
	(segment
		(start 14.7828 -23.53056)
		(end 14.95679 -23.70455)
		(width 0.1143)
		(layer "F.Cu")
		(net "P3E_CPU1_PE3_MP_TXN<0>")
	)
	(segment
		(start 16.533876 -23.70455)
		(end 16.764 -23.474426)
		(width 0.1143)
		(layer "F.Cu")
		(net "P3E_CPU1_PE3_MP_TXN<0>")
	)
	(segment
		(start 16.764 -23.474426)
		(end 16.764 -23.2029)
		(width 0.1143)
		(layer "F.Cu")
		(net "P3E_CPU1_PE3_MP_TXN<0>")
	)
	(segment
		(start 16.6497 -23.0886)
		(end 16.18615 -23.0886)
		(width 0.1143)
		(layer "F.Cu")
		(net "P3E_CPU1_PE3_MP_TXN<0>")
	)
	(segment
		(start 16.764 -23.2029)
		(end 16.6497 -23.0886)
		(width 0.1143)
		(layer "F.Cu")
		(net "P3E_CPU1_PE3_MP_TXN<0>")
	)
	(segment
		(start 14.7828 -23.241)
		(end 14.7828 -23.53056)
		(width 0.1143)
		(layer "F.Cu")
		(net "P3E_CPU1_PE3_MP_TXN<0>")
	)
	(segment
		(start 14.95679 -23.70455)
		(end 16.533876 -23.70455)
		(width 0.1143)
		(layer "F.Cu")
		(net "P3E_CPU1_PE3_MP_TXN<0>")
	)
	(via
		(at 16.18615 -23.0886)
		(size 0.508)
		(drill 0.254)
		(layers "F.Cu" "B.Cu")
		(net "P3E_CPU1_PE3_MP_TXN<0>")
	)
	(via
		(at 131.661408 -102.958138)
		(size 0.508)
		(drill 0.254)
		(layers "F.Cu" "B.Cu")
		(net "P3E_CPU1_PE3_MP_TXN<0>")
	)
	(segment
		(start 128.739138 -102.72395)
		(end 117.1448 -105.043224)
		(width 0.1143)
		(layer "In9.Cu")
		(net "P3E_CPU1_PE3_MP_TXN<0>")
	)
	(segment
		(start 117.1448 -105.043224)
		(end 111.66348 -103.946706)
		(width 0.1143)
		(layer "In9.Cu")
		(net "P3E_CPU1_PE3_MP_TXN<0>")
	)
	(segment
		(start 128.8542 -102.608888)
		(end 128.739138 -102.72395)
		(width 0.1143)
		(layer "In9.Cu")
		(net "P3E_CPU1_PE3_MP_TXN<0>")
	)
	(segment
		(start 65.175892 -89.142316)
		(end 67.623944 -76.89977)
		(width 0.1143)
		(layer "In9.Cu")
		(net "P3E_CPU1_PE3_MP_TXN<0>")
	)
	(segment
		(start 20.611846 -24.638)
		(end 17.135348 -23.946104)
		(width 0.1143)
		(layer "In9.Cu")
		(net "P3E_CPU1_PE3_MP_TXN<0>")
	)
	(segment
		(start 84.272882 -102.367842)
		(end 76.178918 -103.986584)
		(width 0.1143)
		(layer "In9.Cu")
		(net "P3E_CPU1_PE3_MP_TXN<0>")
	)
	(segment
		(start 131.661408 -102.620064)
		(end 131.59613 -102.554786)
		(width 0.0889)
		(layer "In9.Cu")
		(net "P3E_CPU1_PE3_MP_TXN<0>")
	)
	(segment
		(start 21.970746 -24.638)
		(end 21.627846 -24.638)
		(width 0.1143)
		(layer "In9.Cu")
		(net "P3E_CPU1_PE3_MP_TXN<0>")
	)
	(segment
		(start 32.835342 -26.042112)
		(end 25.816306 -24.638)
		(width 0.1143)
		(layer "In9.Cu")
		(net "P3E_CPU1_PE3_MP_TXN<0>")
	)
	(segment
		(start 24.167846 -24.8031)
		(end 24.002746 -24.638)
		(width 0.1143)
		(layer "In9.Cu")
		(net "P3E_CPU1_PE3_MP_TXN<0>")
	)
	(segment
		(start 65.256918 -65.0621)
		(end 66.258948 -60.052204)
		(width 0.1143)
		(layer "In9.Cu")
		(net "P3E_CPU1_PE3_MP_TXN<0>")
	)
	(segment
		(start 67.513962 -100.83292)
		(end 65.175892 -89.142316)
		(width 0.1143)
		(layer "In9.Cu")
		(net "P3E_CPU1_PE3_MP_TXN<0>")
	)
	(segment
		(start 16.5608 -23.0886)
		(end 16.18615 -23.0886)
		(width 0.1143)
		(layer "In9.Cu")
		(net "P3E_CPU1_PE3_MP_TXN<0>")
	)
	(segment
		(start 22.643846 -24.638)
		(end 22.478746 -24.8031)
		(width 0.1143)
		(layer "In9.Cu")
		(net "P3E_CPU1_PE3_MP_TXN<0>")
	)
	(segment
		(start 16.6751 -23.485856)
		(end 16.6751 -23.2029)
		(width 0.1143)
		(layer "In9.Cu")
		(net "P3E_CPU1_PE3_MP_TXN<0>")
	)
	(segment
		(start 67.623944 -76.89977)
		(end 65.256918 -65.0621)
		(width 0.1143)
		(layer "In9.Cu")
		(net "P3E_CPU1_PE3_MP_TXN<0>")
	)
	(segment
		(start 23.494746 -24.8031)
		(end 23.151846 -24.8031)
		(width 0.1143)
		(layer "In9.Cu")
		(net "P3E_CPU1_PE3_MP_TXN<0>")
	)
	(segment
		(start 69.964808 -102.744016)
		(end 67.846702 -101.332538)
		(width 0.1143)
		(layer "In9.Cu")
		(net "P3E_CPU1_PE3_MP_TXN<0>")
	)
	(segment
		(start 44.646342 -33.918144)
		(end 32.835342 -26.042112)
		(width 0.1143)
		(layer "In9.Cu")
		(net "P3E_CPU1_PE3_MP_TXN<0>")
	)
	(segment
		(start 129.381504 -102.558088)
		(end 129.330704 -102.608888)
		(width 0.0889)
		(layer "In9.Cu")
		(net "P3E_CPU1_PE3_MP_TXN<0>")
	)
	(segment
		(start 46.343824 -36.46424)
		(end 44.646342 -33.918144)
		(width 0.1143)
		(layer "In9.Cu")
		(net "P3E_CPU1_PE3_MP_TXN<0>")
	)
	(segment
		(start 65.262506 -55.069232)
		(end 57.885584 -44.004484)
		(width 0.1143)
		(layer "In9.Cu")
		(net "P3E_CPU1_PE3_MP_TXN<0>")
	)
	(segment
		(start 131.661408 -102.958138)
		(end 131.661408 -102.620064)
		(width 0.0889)
		(layer "In9.Cu")
		(net "P3E_CPU1_PE3_MP_TXN<0>")
	)
	(segment
		(start 66.258948 -60.052204)
		(end 65.262506 -55.069232)
		(width 0.1143)
		(layer "In9.Cu")
		(net "P3E_CPU1_PE3_MP_TXN<0>")
	)
	(segment
		(start 22.135846 -24.8031)
		(end 21.970746 -24.638)
		(width 0.1143)
		(layer "In9.Cu")
		(net "P3E_CPU1_PE3_MP_TXN<0>")
	)
	(segment
		(start 23.659846 -24.638)
		(end 23.494746 -24.8031)
		(width 0.1143)
		(layer "In9.Cu")
		(net "P3E_CPU1_PE3_MP_TXN<0>")
	)
	(segment
		(start 21.627846 -24.638)
		(end 21.462746 -24.8031)
		(width 0.1143)
		(layer "In9.Cu")
		(net "P3E_CPU1_PE3_MP_TXN<0>")
	)
	(segment
		(start 24.510746 -24.8031)
		(end 24.167846 -24.8031)
		(width 0.1143)
		(layer "In9.Cu")
		(net "P3E_CPU1_PE3_MP_TXN<0>")
	)
	(segment
		(start 111.66348 -103.946706)
		(end 106.876596 -104.904032)
		(width 0.1143)
		(layer "In9.Cu")
		(net "P3E_CPU1_PE3_MP_TXN<0>")
	)
	(segment
		(start 129.330704 -102.608888)
		(end 129.308606 -102.608888)
		(width 0.0889)
		(layer "In9.Cu")
		(net "P3E_CPU1_PE3_MP_TXN<0>")
	)
	(segment
		(start 57.885584 -44.004484)
		(end 46.343824 -36.46424)
		(width 0.1143)
		(layer "In9.Cu")
		(net "P3E_CPU1_PE3_MP_TXN<0>")
	)
	(segment
		(start 21.462746 -24.8031)
		(end 21.119846 -24.8031)
		(width 0.1143)
		(layer "In9.Cu")
		(net "P3E_CPU1_PE3_MP_TXN<0>")
	)
	(segment
		(start 20.954746 -24.638)
		(end 20.611846 -24.638)
		(width 0.1143)
		(layer "In9.Cu")
		(net "P3E_CPU1_PE3_MP_TXN<0>")
	)
	(segment
		(start 129.944368 -102.558088)
		(end 129.381504 -102.558088)
		(width 0.0889)
		(layer "In9.Cu")
		(net "P3E_CPU1_PE3_MP_TXN<0>")
	)
	(segment
		(start 97.538794 -103.035862)
		(end 92.57538 -104.028494)
		(width 0.1143)
		(layer "In9.Cu")
		(net "P3E_CPU1_PE3_MP_TXN<0>")
	)
	(segment
		(start 21.119846 -24.8031)
		(end 20.954746 -24.638)
		(width 0.1143)
		(layer "In9.Cu")
		(net "P3E_CPU1_PE3_MP_TXN<0>")
	)
	(segment
		(start 22.986746 -24.638)
		(end 22.643846 -24.638)
		(width 0.1143)
		(layer "In9.Cu")
		(net "P3E_CPU1_PE3_MP_TXN<0>")
	)
	(segment
		(start 76.178918 -103.986584)
		(end 69.964808 -102.744016)
		(width 0.1143)
		(layer "In9.Cu")
		(net "P3E_CPU1_PE3_MP_TXN<0>")
	)
	(segment
		(start 106.876596 -104.904032)
		(end 97.538794 -103.035862)
		(width 0.1143)
		(layer "In9.Cu")
		(net "P3E_CPU1_PE3_MP_TXN<0>")
	)
	(segment
		(start 23.151846 -24.8031)
		(end 22.986746 -24.638)
		(width 0.1143)
		(layer "In9.Cu")
		(net "P3E_CPU1_PE3_MP_TXN<0>")
	)
	(segment
		(start 25.816306 -24.638)
		(end 24.675846 -24.638)
		(width 0.1143)
		(layer "In9.Cu")
		(net "P3E_CPU1_PE3_MP_TXN<0>")
	)
	(segment
		(start 24.002746 -24.638)
		(end 23.659846 -24.638)
		(width 0.1143)
		(layer "In9.Cu")
		(net "P3E_CPU1_PE3_MP_TXN<0>")
	)
	(segment
		(start 92.57538 -104.028494)
		(end 84.272882 -102.367842)
		(width 0.1143)
		(layer "In9.Cu")
		(net "P3E_CPU1_PE3_MP_TXN<0>")
	)
	(segment
		(start 129.308606 -102.608888)
		(end 128.8542 -102.608888)
		(width 0.1143)
		(layer "In9.Cu")
		(net "P3E_CPU1_PE3_MP_TXN<0>")
	)
	(segment
		(start 67.846702 -101.332538)
		(end 67.513962 -100.83292)
		(width 0.1143)
		(layer "In9.Cu")
		(net "P3E_CPU1_PE3_MP_TXN<0>")
	)
	(segment
		(start 24.675846 -24.638)
		(end 24.510746 -24.8031)
		(width 0.1143)
		(layer "In9.Cu")
		(net "P3E_CPU1_PE3_MP_TXN<0>")
	)
	(segment
		(start 16.6751 -23.2029)
		(end 16.5608 -23.0886)
		(width 0.1143)
		(layer "In9.Cu")
		(net "P3E_CPU1_PE3_MP_TXN<0>")
	)
	(segment
		(start 22.478746 -24.8031)
		(end 22.135846 -24.8031)
		(width 0.1143)
		(layer "In9.Cu")
		(net "P3E_CPU1_PE3_MP_TXN<0>")
	)
	(segment
		(start 17.135348 -23.946104)
		(end 16.6751 -23.485856)
		(width 0.1143)
		(layer "In9.Cu")
		(net "P3E_CPU1_PE3_MP_TXN<0>")
	)
	(arc
		(start 130.456178 -102.262686)
		(mid 130.239895 -102.479022)
		(end 129.944368 -102.558088)
		(width 0.0889)
		(layer "In9.Cu")
		(net "P3E_CPU1_PE3_MP_TXN<0>")
	)
	(arc
		(start 131.149598 -102.262686)
		(mid 130.802888 -102.062375)
		(end 130.456178 -102.262686)
		(width 0.0889)
		(layer "In9.Cu")
		(net "P3E_CPU1_PE3_MP_TXN<0>")
	)
	(arc
		(start 131.59613 -102.554786)
		(mid 131.337993 -102.462032)
		(end 131.149598 -102.262686)
		(width 0.0889)
		(layer "In9.Cu")
		(net "P3E_CPU1_PE3_MP_TXN<0>")
	)
	(segment
		(start 131.089908 -95.033084)
		(end 131.661408 -95.033084)
		(width 0.1143)
		(layer "F.Cu")
		(net "P3E_CPU1_PE3_MP_RXP<7>")
	)
	(via
		(at 131.661408 -95.033084)
		(size 0.508)
		(drill 0.254)
		(layers "F.Cu" "B.Cu")
		(net "P3E_CPU1_PE3_MP_RXP<7>")
	)
	(segment
		(start 83.300062 -108.77042)
		(end 92.783152 -110.666784)
		(width 0.1143)
		(layer "In9.Cu")
		(net "P3E_CPU1_PE3_MP_RXP<7>")
	)
	(segment
		(start 59.414156 -67.242944)
		(end 59.414156 -67.481704)
		(width 0.1143)
		(layer "In9.Cu")
		(net "P3E_CPU1_PE3_MP_RXP<7>")
	)
	(segment
		(start 58.54192 -68.35394)
		(end 58.54192 -70.372224)
		(width 0.1143)
		(layer "In9.Cu")
		(net "P3E_CPU1_PE3_MP_RXP<7>")
	)
	(segment
		(start 53.535072 -49.1871)
		(end 59.344052 -57.901078)
		(width 0.1143)
		(layer "In9.Cu")
		(net "P3E_CPU1_PE3_MP_RXP<7>")
	)
	(segment
		(start 60.933584 -74.8411)
		(end 61.336682 -76.856082)
		(width 0.1143)
		(layer "In9.Cu")
		(net "P3E_CPU1_PE3_MP_RXP<7>")
	)
	(segment
		(start 96.472756 -109.92866)
		(end 123.09983 -115.224814)
		(width 0.1143)
		(layer "In9.Cu")
		(net "P3E_CPU1_PE3_MP_RXP<7>")
	)
	(segment
		(start 7.711694 -35.119564)
		(end 9.935718 -36.605718)
		(width 0.1143)
		(layer "In9.Cu")
		(net "P3E_CPU1_PE3_MP_RXP<7>")
	)
	(segment
		(start 26.399744 -40.2463)
		(end 26.564844 -40.0812)
		(width 0.1143)
		(layer "In9.Cu")
		(net "P3E_CPU1_PE3_MP_RXP<7>")
	)
	(segment
		(start 61.727588 -103.509318)
		(end 61.732922 -103.53421)
		(width 0.1143)
		(layer "In9.Cu")
		(net "P3E_CPU1_PE3_MP_RXP<7>")
	)
	(segment
		(start 26.564844 -40.0812)
		(end 27.923744 -40.0812)
		(width 0.1143)
		(layer "In9.Cu")
		(net "P3E_CPU1_PE3_MP_RXP<7>")
	)
	(segment
		(start 59.344052 -57.901078)
		(end 59.700922 -59.684412)
		(width 0.1143)
		(layer "In9.Cu")
		(net "P3E_CPU1_PE3_MP_RXP<7>")
	)
	(segment
		(start 63.30442 -105.891838)
		(end 68.59651 -109.419136)
		(width 0.1143)
		(layer "In9.Cu")
		(net "P3E_CPU1_PE3_MP_RXP<7>")
	)
	(segment
		(start 139.887198 -101.981254)
		(end 139.887198 -100.825046)
		(width 0.0889)
		(layer "In9.Cu")
		(net "P3E_CPU1_PE3_MP_RXP<7>")
	)
	(segment
		(start 29.180028 -39.116)
		(end 34.766758 -39.116)
		(width 0.1143)
		(layer "In9.Cu")
		(net "P3E_CPU1_PE3_MP_RXP<7>")
	)
	(segment
		(start 130.687064 -113.714784)
		(end 138.406632 -105.995216)
		(width 0.1143)
		(layer "In9.Cu")
		(net "P3E_CPU1_PE3_MP_RXP<7>")
	)
	(segment
		(start 15.066264 -39.247064)
		(end 17.229836 -40.142414)
		(width 0.1143)
		(layer "In9.Cu")
		(net "P3E_CPU1_PE3_MP_RXP<7>")
	)
	(segment
		(start 26.056844 -40.2463)
		(end 26.399744 -40.2463)
		(width 0.1143)
		(layer "In9.Cu")
		(net "P3E_CPU1_PE3_MP_RXP<7>")
	)
	(segment
		(start 1.700022 -35.710114)
		(end 1.509014 -35.710114)
		(width 0.1143)
		(layer "In9.Cu")
		(net "P3E_CPU1_PE3_MP_RXP<7>")
	)
	(segment
		(start 61.732922 -103.53421)
		(end 63.30442 -105.891838)
		(width 0.1143)
		(layer "In9.Cu")
		(net "P3E_CPU1_PE3_MP_RXP<7>")
	)
	(segment
		(start 41.59631 -41.228518)
		(end 53.535072 -49.1871)
		(width 0.1143)
		(layer "In9.Cu")
		(net "P3E_CPU1_PE3_MP_RXP<7>")
	)
	(segment
		(start 74.325226 -110.565184)
		(end 83.300062 -108.77042)
		(width 0.1143)
		(layer "In9.Cu")
		(net "P3E_CPU1_PE3_MP_RXP<7>")
	)
	(segment
		(start 22.90572 -41.112186)
		(end 23.311866 -41.040304)
		(width 0.1143)
		(layer "In9.Cu")
		(net "P3E_CPU1_PE3_MP_RXP<7>")
	)
	(segment
		(start 24.993092 -40.0812)
		(end 25.891744 -40.0812)
		(width 0.1143)
		(layer "In9.Cu")
		(net "P3E_CPU1_PE3_MP_RXP<7>")
	)
	(segment
		(start 139.901168 -100.77704)
		(end 139.907518 -100.766372)
		(width 0.0889)
		(layer "In9.Cu")
		(net "P3E_CPU1_PE3_MP_RXP<7>")
	)
	(segment
		(start 139.887452 -101.981)
		(end 139.887198 -101.981254)
		(width 0.0889)
		(layer "In9.Cu")
		(net "P3E_CPU1_PE3_MP_RXP<7>")
	)
	(segment
		(start 139.896342 -99.795076)
		(end 139.901168 -99.78644)
		(width 0.0889)
		(layer "In9.Cu")
		(net "P3E_CPU1_PE3_MP_RXP<7>")
	)
	(segment
		(start 27.923744 -40.0812)
		(end 29.180028 -39.116)
		(width 0.1143)
		(layer "In9.Cu")
		(net "P3E_CPU1_PE3_MP_RXP<7>")
	)
	(segment
		(start 139.899898 -100.779072)
		(end 139.901168 -100.77704)
		(width 0.0889)
		(layer "In9.Cu")
		(net "P3E_CPU1_PE3_MP_RXP<7>")
	)
	(segment
		(start 68.59651 -109.419136)
		(end 74.325226 -110.565184)
		(width 0.1143)
		(layer "In9.Cu")
		(net "P3E_CPU1_PE3_MP_RXP<7>")
	)
	(segment
		(start 138.548364 -96.423988)
		(end 138.518138 -96.423988)
		(width 0.0889)
		(layer "In9.Cu")
		(net "P3E_CPU1_PE3_MP_RXP<7>")
	)
	(segment
		(start 138.406632 -105.995216)
		(end 138.422126 -105.979722)
		(width 0.0889)
		(layer "In9.Cu")
		(net "P3E_CPU1_PE3_MP_RXP<7>")
	)
	(segment
		(start 7.075932 -34.856166)
		(end 7.711694 -35.119564)
		(width 0.1143)
		(layer "In9.Cu")
		(net "P3E_CPU1_PE3_MP_RXP<7>")
	)
	(segment
		(start 59.700922 -59.684412)
		(end 58.80227 -64.180974)
		(width 0.1143)
		(layer "In9.Cu")
		(net "P3E_CPU1_PE3_MP_RXP<7>")
	)
	(segment
		(start 131.726686 -95.436436)
		(end 131.661408 -95.371158)
		(width 0.0889)
		(layer "In9.Cu")
		(net "P3E_CPU1_PE3_MP_RXP<7>")
	)
	(segment
		(start 138.422126 -105.979722)
		(end 138.422126 -105.908094)
		(width 0.0889)
		(layer "In9.Cu")
		(net "P3E_CPU1_PE3_MP_RXP<7>")
	)
	(segment
		(start 92.783152 -110.666784)
		(end 96.472756 -109.92866)
		(width 0.1143)
		(layer "In9.Cu")
		(net "P3E_CPU1_PE3_MP_RXP<7>")
	)
	(segment
		(start 10.843514 -37.513514)
		(end 11.757152 -37.7063)
		(width 0.1143)
		(layer "In9.Cu")
		(net "P3E_CPU1_PE3_MP_RXP<7>")
	)
	(segment
		(start 134.254494 -95.928434)
		(end 134.221728 -95.928434)
		(width 0.0889)
		(layer "In9.Cu")
		(net "P3E_CPU1_PE3_MP_RXP<7>")
	)
	(segment
		(start 132.17652 -95.734124)
		(end 132.173218 -95.728282)
		(width 0.0889)
		(layer "In9.Cu")
		(net "P3E_CPU1_PE3_MP_RXP<7>")
	)
	(segment
		(start 25.891744 -40.0812)
		(end 26.056844 -40.2463)
		(width 0.1143)
		(layer "In9.Cu")
		(net "P3E_CPU1_PE3_MP_RXP<7>")
	)
	(segment
		(start 12.631674 -37.7063)
		(end 14.157706 -38.338506)
		(width 0.1143)
		(layer "In9.Cu")
		(net "P3E_CPU1_PE3_MP_RXP<7>")
	)
	(segment
		(start 23.311866 -41.040304)
		(end 24.993092 -40.0812)
		(width 0.1143)
		(layer "In9.Cu")
		(net "P3E_CPU1_PE3_MP_RXP<7>")
	)
	(segment
		(start 59.414156 -67.481704)
		(end 58.54192 -68.35394)
		(width 0.1143)
		(layer "In9.Cu")
		(net "P3E_CPU1_PE3_MP_RXP<7>")
	)
	(segment
		(start 17.229836 -40.142414)
		(end 22.90572 -41.112186)
		(width 0.1143)
		(layer "In9.Cu")
		(net "P3E_CPU1_PE3_MP_RXP<7>")
	)
	(segment
		(start 1.30937 -34.856166)
		(end 7.075932 -34.856166)
		(width 0.1143)
		(layer "In9.Cu")
		(net "P3E_CPU1_PE3_MP_RXP<7>")
	)
	(segment
		(start 140.033248 -104.296718)
		(end 140.033248 -102.578408)
		(width 0.0889)
		(layer "In9.Cu")
		(net "P3E_CPU1_PE3_MP_RXP<7>")
	)
	(segment
		(start 61.336682 -76.856082)
		(end 58.85053 -89.286588)
		(width 0.1143)
		(layer "In9.Cu")
		(net "P3E_CPU1_PE3_MP_RXP<7>")
	)
	(segment
		(start 131.661408 -95.371158)
		(end 131.661408 -95.033084)
		(width 0.0889)
		(layer "In9.Cu")
		(net "P3E_CPU1_PE3_MP_RXP<7>")
	)
	(segment
		(start 58.85053 -89.286588)
		(end 61.680852 -103.43896)
		(width 0.1143)
		(layer "In9.Cu")
		(net "P3E_CPU1_PE3_MP_RXP<7>")
	)
	(segment
		(start 139.907518 -98.215958)
		(end 139.901168 -98.20529)
		(width 0.0889)
		(layer "In9.Cu")
		(net "P3E_CPU1_PE3_MP_RXP<7>")
	)
	(segment
		(start 139.901168 -99.78644)
		(end 139.907518 -99.775772)
		(width 0.0889)
		(layer "In9.Cu")
		(net "P3E_CPU1_PE3_MP_RXP<7>")
	)
	(segment
		(start 58.54192 -70.372224)
		(end 60.933584 -74.8411)
		(width 0.1143)
		(layer "In9.Cu")
		(net "P3E_CPU1_PE3_MP_RXP<7>")
	)
	(segment
		(start 135.116824 -96.423988)
		(end 135.084058 -96.423988)
		(width 0.0889)
		(layer "In9.Cu")
		(net "P3E_CPU1_PE3_MP_RXP<7>")
	)
	(segment
		(start 136.82345 -96.423988)
		(end 136.790684 -96.423988)
		(width 0.0889)
		(layer "In9.Cu")
		(net "P3E_CPU1_PE3_MP_RXP<7>")
	)
	(segment
		(start 137.688574 -95.928434)
		(end 137.653014 -95.928434)
		(width 0.0889)
		(layer "In9.Cu")
		(net "P3E_CPU1_PE3_MP_RXP<7>")
	)
	(segment
		(start 1.509014 -35.710114)
		(end 1.1176 -35.3187)
		(width 0.1143)
		(layer "In9.Cu")
		(net "P3E_CPU1_PE3_MP_RXP<7>")
	)
	(segment
		(start 139.896342 -98.804476)
		(end 139.901168 -98.79584)
		(width 0.0889)
		(layer "In9.Cu")
		(net "P3E_CPU1_PE3_MP_RXP<7>")
	)
	(segment
		(start 34.766758 -39.116)
		(end 41.59631 -41.228518)
		(width 0.1143)
		(layer "In9.Cu")
		(net "P3E_CPU1_PE3_MP_RXP<7>")
	)
	(segment
		(start 1.1176 -35.047936)
		(end 1.30937 -34.856166)
		(width 0.1143)
		(layer "In9.Cu")
		(net "P3E_CPU1_PE3_MP_RXP<7>")
	)
	(segment
		(start 139.410694 -96.919542)
		(end 139.377928 -96.919542)
		(width 0.0889)
		(layer "In9.Cu")
		(net "P3E_CPU1_PE3_MP_RXP<7>")
	)
	(segment
		(start 14.157706 -38.338506)
		(end 15.066264 -39.247064)
		(width 0.1143)
		(layer "In9.Cu")
		(net "P3E_CPU1_PE3_MP_RXP<7>")
	)
	(segment
		(start 123.09983 -115.224814)
		(end 130.687064 -113.714784)
		(width 0.1143)
		(layer "In9.Cu")
		(net "P3E_CPU1_PE3_MP_RXP<7>")
	)
	(segment
		(start 11.757152 -37.7063)
		(end 12.631674 -37.7063)
		(width 0.1143)
		(layer "In9.Cu")
		(net "P3E_CPU1_PE3_MP_RXP<7>")
	)
	(segment
		(start 61.680852 -103.43896)
		(end 61.727588 -103.509318)
		(width 0.1143)
		(layer "In9.Cu")
		(net "P3E_CPU1_PE3_MP_RXP<7>")
	)
	(segment
		(start 1.1176 -35.3187)
		(end 1.1176 -35.047936)
		(width 0.1143)
		(layer "In9.Cu")
		(net "P3E_CPU1_PE3_MP_RXP<7>")
	)
	(segment
		(start 135.96874 -96.919034)
		(end 135.938768 -96.919034)
		(width 0.0889)
		(layer "In9.Cu")
		(net "P3E_CPU1_PE3_MP_RXP<7>")
	)
	(segment
		(start 9.935718 -36.605718)
		(end 10.843514 -37.513514)
		(width 0.1143)
		(layer "In9.Cu")
		(net "P3E_CPU1_PE3_MP_RXP<7>")
	)
	(segment
		(start 139.901168 -97.805494)
		(end 139.907264 -97.794572)
		(width 0.0889)
		(layer "In9.Cu")
		(net "P3E_CPU1_PE3_MP_RXP<7>")
	)
	(segment
		(start 138.422126 -105.908094)
		(end 140.033248 -104.296718)
		(width 0.0889)
		(layer "In9.Cu")
		(net "P3E_CPU1_PE3_MP_RXP<7>")
	)
	(segment
		(start 58.80227 -64.180974)
		(end 59.414156 -67.242944)
		(width 0.1143)
		(layer "In9.Cu")
		(net "P3E_CPU1_PE3_MP_RXP<7>")
	)
	(arc
		(start 139.042394 -96.71939)
		(mid 138.833786 -96.507458)
		(end 138.548364 -96.423988)
		(width 0.0889)
		(layer "In9.Cu")
		(net "P3E_CPU1_PE3_MP_RXP<7>")
	)
	(arc
		(start 139.907264 -97.794572)
		(mid 139.920321 -97.25081)
		(end 139.483592 -96.926654)
		(width 0.0889)
		(layer "In9.Cu")
		(net "P3E_CPU1_PE3_MP_RXP<7>")
	)
	(arc
		(start 139.901168 -99.19589)
		(mid 139.847698 -99.000827)
		(end 139.896342 -98.804476)
		(width 0.0889)
		(layer "In9.Cu")
		(net "P3E_CPU1_PE3_MP_RXP<7>")
	)
	(arc
		(start 139.901168 -100.18649)
		(mid 139.847698 -99.991427)
		(end 139.896342 -99.795076)
		(width 0.0889)
		(layer "In9.Cu")
		(net "P3E_CPU1_PE3_MP_RXP<7>")
	)
	(arc
		(start 135.938768 -96.919034)
		(mid 135.747126 -96.861868)
		(end 135.607044 -96.719136)
		(width 0.0889)
		(layer "In9.Cu")
		(net "P3E_CPU1_PE3_MP_RXP<7>")
	)
	(arc
		(start 139.907518 -100.766372)
		(mid 139.980316 -100.475609)
		(end 139.901168 -100.18649)
		(width 0.0889)
		(layer "In9.Cu")
		(net "P3E_CPU1_PE3_MP_RXP<7>")
	)
	(arc
		(start 137.653014 -95.928434)
		(mid 137.36759 -96.011901)
		(end 137.158984 -96.223836)
		(width 0.0889)
		(layer "In9.Cu")
		(net "P3E_CPU1_PE3_MP_RXP<7>")
	)
	(arc
		(start 132.866384 -95.728536)
		(mid 132.726196 -95.871338)
		(end 132.534406 -95.928434)
		(width 0.0889)
		(layer "In9.Cu")
		(net "P3E_CPU1_PE3_MP_RXP<7>")
	)
	(arc
		(start 135.607044 -96.719136)
		(mid 135.40004 -96.508272)
		(end 135.116824 -96.423988)
		(width 0.0889)
		(layer "In9.Cu")
		(net "P3E_CPU1_PE3_MP_RXP<7>")
	)
	(arc
		(start 139.377928 -96.919542)
		(mid 139.184078 -96.863192)
		(end 139.042394 -96.71939)
		(width 0.0889)
		(layer "In9.Cu")
		(net "P3E_CPU1_PE3_MP_RXP<7>")
	)
	(arc
		(start 132.534406 -95.928434)
		(mid 132.328882 -95.880245)
		(end 132.17652 -95.734124)
		(width 0.0889)
		(layer "In9.Cu")
		(net "P3E_CPU1_PE3_MP_RXP<7>")
	)
	(arc
		(start 136.790684 -96.423988)
		(mid 136.507467 -96.508269)
		(end 136.300464 -96.719136)
		(width 0.0889)
		(layer "In9.Cu")
		(net "P3E_CPU1_PE3_MP_RXP<7>")
	)
	(arc
		(start 132.173218 -95.728282)
		(mid 131.984738 -95.529146)
		(end 131.726686 -95.436436)
		(width 0.0889)
		(layer "In9.Cu")
		(net "P3E_CPU1_PE3_MP_RXP<7>")
	)
	(arc
		(start 140.033248 -102.578408)
		(mid 140.020357 -102.401856)
		(end 139.955778 -102.237032)
		(width 0.0889)
		(layer "In9.Cu")
		(net "P3E_CPU1_PE3_MP_RXP<7>")
	)
	(arc
		(start 139.901168 -98.79584)
		(mid 139.98039 -98.506722)
		(end 139.907518 -98.215958)
		(width 0.0889)
		(layer "In9.Cu")
		(net "P3E_CPU1_PE3_MP_RXP<7>")
	)
	(arc
		(start 139.955778 -102.237032)
		(mid 139.904761 -102.113511)
		(end 139.887452 -101.981)
		(width 0.0889)
		(layer "In9.Cu")
		(net "P3E_CPU1_PE3_MP_RXP<7>")
	)
	(arc
		(start 133.890004 -95.728536)
		(mid 133.683217 -95.517803)
		(end 133.400292 -95.433388)
		(width 0.0889)
		(layer "In9.Cu")
		(net "P3E_CPU1_PE3_MP_RXP<7>")
	)
	(arc
		(start 139.887198 -100.825046)
		(mid 139.890428 -100.801196)
		(end 139.899898 -100.779072)
		(width 0.0889)
		(layer "In9.Cu")
		(net "P3E_CPU1_PE3_MP_RXP<7>")
	)
	(arc
		(start 139.483592 -96.926654)
		(mid 139.447253 -96.921967)
		(end 139.410694 -96.919542)
		(width 0.0889)
		(layer "In9.Cu")
		(net "P3E_CPU1_PE3_MP_RXP<7>")
	)
	(arc
		(start 137.158984 -96.223836)
		(mid 137.017301 -96.36764)
		(end 136.82345 -96.423988)
		(width 0.0889)
		(layer "In9.Cu")
		(net "P3E_CPU1_PE3_MP_RXP<7>")
	)
	(arc
		(start 133.356096 -95.433388)
		(mid 133.07316 -95.517784)
		(end 132.866384 -95.728536)
		(width 0.0889)
		(layer "In9.Cu")
		(net "P3E_CPU1_PE3_MP_RXP<7>")
	)
	(arc
		(start 138.182604 -96.223836)
		(mid 137.973996 -96.011904)
		(end 137.688574 -95.928434)
		(width 0.0889)
		(layer "In9.Cu")
		(net "P3E_CPU1_PE3_MP_RXP<7>")
	)
	(arc
		(start 134.748524 -96.223836)
		(mid 134.539916 -96.011904)
		(end 134.254494 -95.928434)
		(width 0.0889)
		(layer "In9.Cu")
		(net "P3E_CPU1_PE3_MP_RXP<7>")
	)
	(arc
		(start 134.221728 -95.928434)
		(mid 134.030086 -95.871268)
		(end 133.890004 -95.728536)
		(width 0.0889)
		(layer "In9.Cu")
		(net "P3E_CPU1_PE3_MP_RXP<7>")
	)
	(arc
		(start 139.901168 -98.20529)
		(mid 139.847669 -98.005392)
		(end 139.901168 -97.805494)
		(width 0.0889)
		(layer "In9.Cu")
		(net "P3E_CPU1_PE3_MP_RXP<7>")
	)
	(arc
		(start 135.084058 -96.423988)
		(mid 134.890208 -96.367638)
		(end 134.748524 -96.223836)
		(width 0.0889)
		(layer "In9.Cu")
		(net "P3E_CPU1_PE3_MP_RXP<7>")
	)
	(arc
		(start 139.907518 -99.775772)
		(mid 139.980316 -99.485009)
		(end 139.901168 -99.19589)
		(width 0.0889)
		(layer "In9.Cu")
		(net "P3E_CPU1_PE3_MP_RXP<7>")
	)
	(arc
		(start 133.400292 -95.433388)
		(mid 133.378194 -95.432975)
		(end 133.356096 -95.433388)
		(width 0.0889)
		(layer "In9.Cu")
		(net "P3E_CPU1_PE3_MP_RXP<7>")
	)
	(arc
		(start 138.518138 -96.423988)
		(mid 138.324288 -96.367638)
		(end 138.182604 -96.223836)
		(width 0.0889)
		(layer "In9.Cu")
		(net "P3E_CPU1_PE3_MP_RXP<7>")
	)
	(arc
		(start 136.300464 -96.719136)
		(mid 136.160385 -96.861872)
		(end 135.96874 -96.919034)
		(width 0.0889)
		(layer "In9.Cu")
		(net "P3E_CPU1_PE3_MP_RXP<7>")
	)
	(segment
		(start 131.948174 -96.518984)
		(end 132.519674 -96.518984)
		(width 0.1143)
		(layer "F.Cu")
		(net "P3E_CPU1_PE3_MP_RXP<6>")
	)
	(via
		(at 132.519674 -96.518984)
		(size 0.508)
		(drill 0.254)
		(layers "F.Cu" "B.Cu")
		(net "P3E_CPU1_PE3_MP_RXP<6>")
	)
	(via
		(at 15.89024 -37.83076)
		(size 0.508)
		(drill 0.254)
		(layers "F.Cu" "B.Cu")
		(net "P3E_CPU1_PE3_MP_RXP<6>")
	)
	(via
		(at 16.026892 -38.474142)
		(size 0.508)
		(drill 0.254)
		(layers "F.Cu" "B.Cu")
		(net "P3E_CPU1_PE3_MP_RXP<6>")
	)
	(segment
		(start -2.886964 -36.827714)
		(end 9.813798 -36.827714)
		(width 0.1143)
		(layer "B.Cu")
		(net "P3E_CPU1_PE3_MP_RXP<6>")
	)
	(segment
		(start -3.899916 -35.710114)
		(end -3.434842 -35.710114)
		(width 0.1143)
		(layer "B.Cu")
		(net "P3E_CPU1_PE3_MP_RXP<6>")
	)
	(segment
		(start -3.434842 -35.710114)
		(end -3.320542 -35.824414)
		(width 0.1143)
		(layer "B.Cu")
		(net "P3E_CPU1_PE3_MP_RXP<6>")
	)
	(segment
		(start 16.401034 -37.83076)
		(end 16.541242 -37.970968)
		(width 0.1143)
		(layer "B.Cu")
		(net "P3E_CPU1_PE3_MP_RXP<6>")
	)
	(segment
		(start 13.747242 -37.62375)
		(end 13.954252 -37.83076)
		(width 0.1143)
		(layer "B.Cu")
		(net "P3E_CPU1_PE3_MP_RXP<6>")
	)
	(segment
		(start 13.954252 -37.83076)
		(end 15.89024 -37.83076)
		(width 0.1143)
		(layer "B.Cu")
		(net "P3E_CPU1_PE3_MP_RXP<6>")
	)
	(segment
		(start 10.609834 -37.62375)
		(end 13.747242 -37.62375)
		(width 0.1143)
		(layer "B.Cu")
		(net "P3E_CPU1_PE3_MP_RXP<6>")
	)
	(segment
		(start 16.541242 -38.359842)
		(end 16.426942 -38.474142)
		(width 0.1143)
		(layer "B.Cu")
		(net "P3E_CPU1_PE3_MP_RXP<6>")
	)
	(segment
		(start -3.320542 -35.824414)
		(end -3.320542 -36.394136)
		(width 0.1143)
		(layer "B.Cu")
		(net "P3E_CPU1_PE3_MP_RXP<6>")
	)
	(segment
		(start 16.426942 -38.474142)
		(end 16.026892 -38.474142)
		(width 0.1143)
		(layer "B.Cu")
		(net "P3E_CPU1_PE3_MP_RXP<6>")
	)
	(segment
		(start 9.813798 -36.827714)
		(end 10.609834 -37.62375)
		(width 0.1143)
		(layer "B.Cu")
		(net "P3E_CPU1_PE3_MP_RXP<6>")
	)
	(segment
		(start -3.320542 -36.394136)
		(end -2.886964 -36.827714)
		(width 0.1143)
		(layer "B.Cu")
		(net "P3E_CPU1_PE3_MP_RXP<6>")
	)
	(segment
		(start 16.541242 -37.970968)
		(end 16.541242 -38.359842)
		(width 0.1143)
		(layer "B.Cu")
		(net "P3E_CPU1_PE3_MP_RXP<6>")
	)
	(segment
		(start 15.89024 -37.83076)
		(end 16.401034 -37.83076)
		(width 0.1143)
		(layer "B.Cu")
		(net "P3E_CPU1_PE3_MP_RXP<6>")
	)
	(segment
		(start 63.666624 -105.27284)
		(end 68.55714 -108.532168)
		(width 0.1143)
		(layer "In9.Cu")
		(net "P3E_CPU1_PE3_MP_RXP<6>")
	)
	(segment
		(start 133.686804 -108.966)
		(end 134.189978 -108.966)
		(width 0.0889)
		(layer "In9.Cu")
		(net "P3E_CPU1_PE3_MP_RXP<6>")
	)
	(segment
		(start 16.992346 -39.337488)
		(end 21.040598 -40.146986)
		(width 0.1143)
		(layer "In9.Cu")
		(net "P3E_CPU1_PE3_MP_RXP<6>")
	)
	(segment
		(start 106.400346 -111.01324)
		(end 107.04957 -110.883446)
		(width 0.1143)
		(layer "In9.Cu")
		(net "P3E_CPU1_PE3_MP_RXP<6>")
	)
	(segment
		(start 83.2104 -108.076746)
		(end 92.647516 -109.96422)
		(width 0.1143)
		(layer "In9.Cu")
		(net "P3E_CPU1_PE3_MP_RXP<6>")
	)
	(segment
		(start 115.17376 -111.026448)
		(end 115.36807 -111.155988)
		(width 0.1143)
		(layer "In9.Cu")
		(net "P3E_CPU1_PE3_MP_RXP<6>")
	)
	(segment
		(start 108.045758 -110.68431)
		(end 108.240068 -110.81385)
		(width 0.1143)
		(layer "In9.Cu")
		(net "P3E_CPU1_PE3_MP_RXP<6>")
	)
	(segment
		(start 110.418118 -110.210092)
		(end 114.836702 -111.094012)
		(width 0.1143)
		(layer "In9.Cu")
		(net "P3E_CPU1_PE3_MP_RXP<6>")
	)
	(segment
		(start 59.96432 -70.219824)
		(end 59.96432 -70.562724)
		(width 0.1143)
		(layer "In9.Cu")
		(net "P3E_CPU1_PE3_MP_RXP<6>")
	)
	(segment
		(start 134.254494 -96.919034)
		(end 134.221728 -96.919034)
		(width 0.0889)
		(layer "In9.Cu")
		(net "P3E_CPU1_PE3_MP_RXP<6>")
	)
	(segment
		(start 107.579922 -110.94593)
		(end 107.709462 -110.75162)
		(width 0.1143)
		(layer "In9.Cu")
		(net "P3E_CPU1_PE3_MP_RXP<6>")
	)
	(segment
		(start 114.837464 -111.093758)
		(end 115.17376 -111.026448)
		(width 0.1143)
		(layer "In9.Cu")
		(net "P3E_CPU1_PE3_MP_RXP<6>")
	)
	(segment
		(start 108.240068 -110.81385)
		(end 108.576364 -110.74654)
		(width 0.1143)
		(layer "In9.Cu")
		(net "P3E_CPU1_PE3_MP_RXP<6>")
	)
	(segment
		(start 133.399784 -96.423988)
		(end 133.356604 -96.423988)
		(width 0.0889)
		(layer "In9.Cu")
		(net "P3E_CPU1_PE3_MP_RXP<6>")
	)
	(segment
		(start 115.36807 -111.155988)
		(end 115.704112 -111.088678)
		(width 0.1143)
		(layer "In9.Cu")
		(net "P3E_CPU1_PE3_MP_RXP<6>")
	)
	(segment
		(start 107.709462 -110.75162)
		(end 108.045758 -110.68431)
		(width 0.1143)
		(layer "In9.Cu")
		(net "P3E_CPU1_PE3_MP_RXP<6>")
	)
	(segment
		(start 135.96874 -97.909634)
		(end 135.938768 -97.909634)
		(width 0.0889)
		(layer "In9.Cu")
		(net "P3E_CPU1_PE3_MP_RXP<6>")
	)
	(segment
		(start 138.188954 -97.225104)
		(end 138.182604 -97.214436)
		(width 0.0889)
		(layer "In9.Cu")
		(net "P3E_CPU1_PE3_MP_RXP<6>")
	)
	(segment
		(start 16.515842 -38.860984)
		(end 16.992346 -39.337488)
		(width 0.1143)
		(layer "In9.Cu")
		(net "P3E_CPU1_PE3_MP_RXP<6>")
	)
	(segment
		(start 60.12942 -70.054724)
		(end 59.96432 -70.219824)
		(width 0.1143)
		(layer "In9.Cu")
		(net "P3E_CPU1_PE3_MP_RXP<6>")
	)
	(segment
		(start 133.613906 -109.0168)
		(end 133.636004 -109.0168)
		(width 0.0889)
		(layer "In9.Cu")
		(net "P3E_CPU1_PE3_MP_RXP<6>")
	)
	(segment
		(start 60.12942 -70.727824)
		(end 60.12942 -71.860156)
		(width 0.1143)
		(layer "In9.Cu")
		(net "P3E_CPU1_PE3_MP_RXP<6>")
	)
	(segment
		(start 135.116824 -97.414588)
		(end 135.084058 -97.414588)
		(width 0.0889)
		(layer "In9.Cu")
		(net "P3E_CPU1_PE3_MP_RXP<6>")
	)
	(segment
		(start 127.812546 -108.49864)
		(end 130.403092 -109.0168)
		(width 0.1143)
		(layer "In9.Cu")
		(net "P3E_CPU1_PE3_MP_RXP<6>")
	)
	(segment
		(start 60.459874 -59.752738)
		(end 59.53252 -64.387984)
		(width 0.1143)
		(layer "In9.Cu")
		(net "P3E_CPU1_PE3_MP_RXP<6>")
	)
	(segment
		(start 60.12942 -71.860156)
		(end 61.56198 -74.537062)
		(width 0.1143)
		(layer "In9.Cu")
		(net "P3E_CPU1_PE3_MP_RXP<6>")
	)
	(segment
		(start 60.009278 -57.502552)
		(end 60.459874 -59.752738)
		(width 0.1143)
		(layer "In9.Cu")
		(net "P3E_CPU1_PE3_MP_RXP<6>")
	)
	(segment
		(start 133.636004 -109.0168)
		(end 133.686804 -108.966)
		(width 0.0889)
		(layer "In9.Cu")
		(net "P3E_CPU1_PE3_MP_RXP<6>")
	)
	(segment
		(start 139.036552 -100.290122)
		(end 139.041378 -100.281486)
		(width 0.0889)
		(layer "In9.Cu")
		(net "P3E_CPU1_PE3_MP_RXP<6>")
	)
	(segment
		(start 139.137644 -102.166928)
		(end 139.137644 -101.040438)
		(width 0.0889)
		(layer "In9.Cu")
		(net "P3E_CPU1_PE3_MP_RXP<6>")
	)
	(segment
		(start 62.279276 -103.19131)
		(end 63.666624 -105.27284)
		(width 0.1143)
		(layer "In9.Cu")
		(net "P3E_CPU1_PE3_MP_RXP<6>")
	)
	(segment
		(start 139.041378 -99.29114)
		(end 139.047474 -99.280218)
		(width 0.0889)
		(layer "In9.Cu")
		(net "P3E_CPU1_PE3_MP_RXP<6>")
	)
	(segment
		(start 62.03188 -76.886562)
		(end 59.525154 -89.421462)
		(width 0.1143)
		(layer "In9.Cu")
		(net "P3E_CPU1_PE3_MP_RXP<6>")
	)
	(segment
		(start 138.550904 -98.405188)
		(end 138.518138 -98.405188)
		(width 0.0889)
		(layer "In9.Cu")
		(net "P3E_CPU1_PE3_MP_RXP<6>")
	)
	(segment
		(start 139.047728 -99.701604)
		(end 139.041378 -99.690936)
		(width 0.0889)
		(layer "In9.Cu")
		(net "P3E_CPU1_PE3_MP_RXP<6>")
	)
	(segment
		(start 54.163722 -48.733202)
		(end 60.009278 -57.502552)
		(width 0.1143)
		(layer "In9.Cu")
		(net "P3E_CPU1_PE3_MP_RXP<6>")
	)
	(segment
		(start 59.53252 -64.387984)
		(end 60.12942 -67.372738)
		(width 0.1143)
		(layer "In9.Cu")
		(net "P3E_CPU1_PE3_MP_RXP<6>")
	)
	(segment
		(start 136.82345 -97.414588)
		(end 136.790684 -97.414588)
		(width 0.0889)
		(layer "In9.Cu")
		(net "P3E_CPU1_PE3_MP_RXP<6>")
	)
	(segment
		(start 74.743564 -109.770164)
		(end 83.2104 -108.076746)
		(width 0.1143)
		(layer "In9.Cu")
		(net "P3E_CPU1_PE3_MP_RXP<6>")
	)
	(segment
		(start 16.026892 -38.474142)
		(end 16.426942 -38.474142)
		(width 0.1143)
		(layer "In9.Cu")
		(net "P3E_CPU1_PE3_MP_RXP<6>")
	)
	(segment
		(start 130.403092 -109.0168)
		(end 133.613906 -109.0168)
		(width 0.1143)
		(layer "In9.Cu")
		(net "P3E_CPU1_PE3_MP_RXP<6>")
	)
	(segment
		(start 27.373072 -38.980618)
		(end 28.965652 -38.3921)
		(width 0.1143)
		(layer "In9.Cu")
		(net "P3E_CPU1_PE3_MP_RXP<6>")
	)
	(segment
		(start 16.515842 -38.563042)
		(end 16.515842 -38.860984)
		(width 0.1143)
		(layer "In9.Cu")
		(net "P3E_CPU1_PE3_MP_RXP<6>")
	)
	(segment
		(start 107.243626 -111.012986)
		(end 107.579922 -110.94593)
		(width 0.1143)
		(layer "In9.Cu")
		(net "P3E_CPU1_PE3_MP_RXP<6>")
	)
	(segment
		(start 107.04957 -110.883446)
		(end 107.243626 -111.012986)
		(width 0.1143)
		(layer "In9.Cu")
		(net "P3E_CPU1_PE3_MP_RXP<6>")
	)
	(segment
		(start 108.705904 -110.552484)
		(end 110.418118 -110.210092)
		(width 0.1143)
		(layer "In9.Cu")
		(net "P3E_CPU1_PE3_MP_RXP<6>")
	)
	(segment
		(start 134.189978 -108.966)
		(end 139.174474 -103.981504)
		(width 0.0889)
		(layer "In9.Cu")
		(net "P3E_CPU1_PE3_MP_RXP<6>")
	)
	(segment
		(start 137.688574 -96.919034)
		(end 137.653014 -96.919034)
		(width 0.0889)
		(layer "In9.Cu")
		(net "P3E_CPU1_PE3_MP_RXP<6>")
	)
	(segment
		(start 59.525154 -89.421462)
		(end 62.279276 -103.19131)
		(width 0.1143)
		(layer "In9.Cu")
		(net "P3E_CPU1_PE3_MP_RXP<6>")
	)
	(segment
		(start 139.174474 -103.981504)
		(end 139.174474 -103.076248)
		(width 0.0889)
		(layer "In9.Cu")
		(net "P3E_CPU1_PE3_MP_RXP<6>")
	)
	(segment
		(start 115.833652 -110.894622)
		(end 127.812546 -108.49864)
		(width 0.1143)
		(layer "In9.Cu")
		(net "P3E_CPU1_PE3_MP_RXP<6>")
	)
	(segment
		(start 115.704112 -111.088678)
		(end 115.833652 -110.894622)
		(width 0.1143)
		(layer "In9.Cu")
		(net "P3E_CPU1_PE3_MP_RXP<6>")
	)
	(segment
		(start 42.136314 -40.713914)
		(end 54.163722 -48.733202)
		(width 0.1143)
		(layer "In9.Cu")
		(net "P3E_CPU1_PE3_MP_RXP<6>")
	)
	(segment
		(start 96.900746 -109.113574)
		(end 106.400346 -111.01324)
		(width 0.1143)
		(layer "In9.Cu")
		(net "P3E_CPU1_PE3_MP_RXP<6>")
	)
	(segment
		(start 16.426942 -38.474142)
		(end 16.515842 -38.563042)
		(width 0.1143)
		(layer "In9.Cu")
		(net "P3E_CPU1_PE3_MP_RXP<6>")
	)
	(segment
		(start 23.44547 -39.2811)
		(end 25.55113 -39.2811)
		(width 0.1143)
		(layer "In9.Cu")
		(net "P3E_CPU1_PE3_MP_RXP<6>")
	)
	(segment
		(start 28.965652 -38.3921)
		(end 34.5948 -38.3921)
		(width 0.1143)
		(layer "In9.Cu")
		(net "P3E_CPU1_PE3_MP_RXP<6>")
	)
	(segment
		(start 132.226812 -96.687894)
		(end 132.519674 -96.518984)
		(width 0.0889)
		(layer "In9.Cu")
		(net "P3E_CPU1_PE3_MP_RXP<6>")
	)
	(segment
		(start 108.576364 -110.74654)
		(end 108.705904 -110.552484)
		(width 0.1143)
		(layer "In9.Cu")
		(net "P3E_CPU1_PE3_MP_RXP<6>")
	)
	(segment
		(start 60.12942 -67.372738)
		(end 60.12942 -70.054724)
		(width 0.1143)
		(layer "In9.Cu")
		(net "P3E_CPU1_PE3_MP_RXP<6>")
	)
	(segment
		(start 132.20573 -96.766634)
		(end 132.226812 -96.687894)
		(width 0.0889)
		(layer "In9.Cu")
		(net "P3E_CPU1_PE3_MP_RXP<6>")
	)
	(segment
		(start 59.96432 -70.562724)
		(end 60.12942 -70.727824)
		(width 0.1143)
		(layer "In9.Cu")
		(net "P3E_CPU1_PE3_MP_RXP<6>")
	)
	(segment
		(start 114.836702 -111.094012)
		(end 114.837464 -111.093758)
		(width 0.1143)
		(layer "In9.Cu")
		(net "P3E_CPU1_PE3_MP_RXP<6>")
	)
	(segment
		(start 61.56198 -74.537062)
		(end 62.03188 -76.886562)
		(width 0.1143)
		(layer "In9.Cu")
		(net "P3E_CPU1_PE3_MP_RXP<6>")
	)
	(segment
		(start 34.5948 -38.3921)
		(end 39.895526 -39.954708)
		(width 0.1143)
		(layer "In9.Cu")
		(net "P3E_CPU1_PE3_MP_RXP<6>")
	)
	(segment
		(start 25.55113 -39.2811)
		(end 27.373072 -38.980618)
		(width 0.1143)
		(layer "In9.Cu")
		(net "P3E_CPU1_PE3_MP_RXP<6>")
	)
	(segment
		(start 92.647516 -109.96422)
		(end 96.900746 -109.113574)
		(width 0.1143)
		(layer "In9.Cu")
		(net "P3E_CPU1_PE3_MP_RXP<6>")
	)
	(segment
		(start 21.040598 -40.146986)
		(end 23.44547 -39.2811)
		(width 0.1143)
		(layer "In9.Cu")
		(net "P3E_CPU1_PE3_MP_RXP<6>")
	)
	(segment
		(start 39.895526 -39.954708)
		(end 42.136314 -40.713914)
		(width 0.1143)
		(layer "In9.Cu")
		(net "P3E_CPU1_PE3_MP_RXP<6>")
	)
	(segment
		(start 68.55714 -108.532168)
		(end 74.743564 -109.770164)
		(width 0.1143)
		(layer "In9.Cu")
		(net "P3E_CPU1_PE3_MP_RXP<6>")
	)
	(arc
		(start 136.300464 -97.709736)
		(mid 136.160385 -97.852472)
		(end 135.96874 -97.909634)
		(width 0.0889)
		(layer "In9.Cu")
		(net "P3E_CPU1_PE3_MP_RXP<6>")
	)
	(arc
		(start 139.174474 -103.076248)
		(mid 139.162116 -102.898277)
		(end 139.097258 -102.732078)
		(width 0.0889)
		(layer "In9.Cu")
		(net "P3E_CPU1_PE3_MP_RXP<6>")
	)
	(arc
		(start 139.041378 -99.690936)
		(mid 138.987879 -99.491038)
		(end 139.041378 -99.29114)
		(width 0.0889)
		(layer "In9.Cu")
		(net "P3E_CPU1_PE3_MP_RXP<6>")
	)
	(arc
		(start 132.534406 -96.91878)
		(mid 132.351866 -96.882029)
		(end 132.20573 -96.766634)
		(width 0.0889)
		(layer "In9.Cu")
		(net "P3E_CPU1_PE3_MP_RXP<6>")
	)
	(arc
		(start 139.092432 -102.340664)
		(mid 139.126161 -102.25669)
		(end 139.137644 -102.166928)
		(width 0.0889)
		(layer "In9.Cu")
		(net "P3E_CPU1_PE3_MP_RXP<6>")
	)
	(arc
		(start 135.607044 -97.709736)
		(mid 135.40004 -97.498872)
		(end 135.116824 -97.414588)
		(width 0.0889)
		(layer "In9.Cu")
		(net "P3E_CPU1_PE3_MP_RXP<6>")
	)
	(arc
		(start 139.047474 -99.280218)
		(mid 139.060531 -98.736456)
		(end 138.623802 -98.4123)
		(width 0.0889)
		(layer "In9.Cu")
		(net "P3E_CPU1_PE3_MP_RXP<6>")
	)
	(arc
		(start 133.356604 -96.423988)
		(mid 133.073387 -96.508269)
		(end 132.866384 -96.719136)
		(width 0.0889)
		(layer "In9.Cu")
		(net "P3E_CPU1_PE3_MP_RXP<6>")
	)
	(arc
		(start 135.084058 -97.414588)
		(mid 134.890208 -97.358238)
		(end 134.748524 -97.214436)
		(width 0.0889)
		(layer "In9.Cu")
		(net "P3E_CPU1_PE3_MP_RXP<6>")
	)
	(arc
		(start 138.182604 -97.214436)
		(mid 137.973996 -97.002504)
		(end 137.688574 -96.919034)
		(width 0.0889)
		(layer "In9.Cu")
		(net "P3E_CPU1_PE3_MP_RXP<6>")
	)
	(arc
		(start 134.221728 -96.919034)
		(mid 134.030086 -96.861868)
		(end 133.890004 -96.719136)
		(width 0.0889)
		(layer "In9.Cu")
		(net "P3E_CPU1_PE3_MP_RXP<6>")
	)
	(arc
		(start 137.158984 -97.214436)
		(mid 137.017301 -97.35824)
		(end 136.82345 -97.414588)
		(width 0.0889)
		(layer "In9.Cu")
		(net "P3E_CPU1_PE3_MP_RXP<6>")
	)
	(arc
		(start 138.623802 -98.4123)
		(mid 138.587463 -98.407613)
		(end 138.550904 -98.405188)
		(width 0.0889)
		(layer "In9.Cu")
		(net "P3E_CPU1_PE3_MP_RXP<6>")
	)
	(arc
		(start 137.653014 -96.919034)
		(mid 137.36759 -97.002501)
		(end 137.158984 -97.214436)
		(width 0.0889)
		(layer "In9.Cu")
		(net "P3E_CPU1_PE3_MP_RXP<6>")
	)
	(arc
		(start 134.748524 -97.214436)
		(mid 134.539916 -97.002504)
		(end 134.254494 -96.919034)
		(width 0.0889)
		(layer "In9.Cu")
		(net "P3E_CPU1_PE3_MP_RXP<6>")
	)
	(arc
		(start 135.938768 -97.909634)
		(mid 135.747126 -97.852468)
		(end 135.607044 -97.709736)
		(width 0.0889)
		(layer "In9.Cu")
		(net "P3E_CPU1_PE3_MP_RXP<6>")
	)
	(arc
		(start 139.041378 -100.681536)
		(mid 138.987908 -100.486473)
		(end 139.036552 -100.290122)
		(width 0.0889)
		(layer "In9.Cu")
		(net "P3E_CPU1_PE3_MP_RXP<6>")
	)
	(arc
		(start 138.518138 -98.405188)
		(mid 138.179969 -98.20039)
		(end 138.182604 -97.804986)
		(width 0.0889)
		(layer "In9.Cu")
		(net "P3E_CPU1_PE3_MP_RXP<6>")
	)
	(arc
		(start 139.097258 -102.732078)
		(mid 139.043788 -102.537015)
		(end 139.092432 -102.340664)
		(width 0.0889)
		(layer "In9.Cu")
		(net "P3E_CPU1_PE3_MP_RXP<6>")
	)
	(arc
		(start 139.137644 -101.040438)
		(mid 139.113163 -100.854642)
		(end 139.041378 -100.681536)
		(width 0.0889)
		(layer "In9.Cu")
		(net "P3E_CPU1_PE3_MP_RXP<6>")
	)
	(arc
		(start 138.182604 -97.804986)
		(mid 138.261826 -97.515868)
		(end 138.188954 -97.225104)
		(width 0.0889)
		(layer "In9.Cu")
		(net "P3E_CPU1_PE3_MP_RXP<6>")
	)
	(arc
		(start 133.890004 -96.719136)
		(mid 133.683 -96.508272)
		(end 133.399784 -96.423988)
		(width 0.0889)
		(layer "In9.Cu")
		(net "P3E_CPU1_PE3_MP_RXP<6>")
	)
	(arc
		(start 132.866384 -96.719136)
		(mid 132.726178 -96.861845)
		(end 132.534406 -96.91878)
		(width 0.0889)
		(layer "In9.Cu")
		(net "P3E_CPU1_PE3_MP_RXP<6>")
	)
	(arc
		(start 136.790684 -97.414588)
		(mid 136.507467 -97.498869)
		(end 136.300464 -97.709736)
		(width 0.0889)
		(layer "In9.Cu")
		(net "P3E_CPU1_PE3_MP_RXP<6>")
	)
	(arc
		(start 139.041378 -100.281486)
		(mid 139.1206 -99.992368)
		(end 139.047728 -99.701604)
		(width 0.0889)
		(layer "In9.Cu")
		(net "P3E_CPU1_PE3_MP_RXP<6>")
	)
	(segment
		(start 130.231388 -97.509584)
		(end 130.802888 -97.509584)
		(width 0.1143)
		(layer "F.Cu")
		(net "P3E_CPU1_PE3_MP_RXP<5>")
	)
	(via
		(at 12.016486 -39.206424)
		(size 0.508)
		(drill 0.254)
		(layers "F.Cu" "B.Cu")
		(net "P3E_CPU1_PE3_MP_RXP<5>")
	)
	(via
		(at 130.802888 -97.509584)
		(size 0.508)
		(drill 0.254)
		(layers "F.Cu" "B.Cu")
		(net "P3E_CPU1_PE3_MP_RXP<5>")
	)
	(segment
		(start 6.379464 -38.459664)
		(end 6.764528 -38.844728)
		(width 0.1143)
		(layer "B.Cu")
		(net "P3E_CPU1_PE3_MP_RXP<5>")
	)
	(segment
		(start 9.858756 -38.59022)
		(end 12.19962 -38.59022)
		(width 0.1143)
		(layer "B.Cu")
		(net "P3E_CPU1_PE3_MP_RXP<5>")
	)
	(segment
		(start 6.265164 -37.71011)
		(end 6.379464 -37.82441)
		(width 0.1143)
		(layer "B.Cu")
		(net "P3E_CPU1_PE3_MP_RXP<5>")
	)
	(segment
		(start 5.80009 -37.71011)
		(end 6.265164 -37.71011)
		(width 0.1143)
		(layer "B.Cu")
		(net "P3E_CPU1_PE3_MP_RXP<5>")
	)
	(segment
		(start 6.764528 -38.844728)
		(end 9.604248 -38.844728)
		(width 0.1143)
		(layer "B.Cu")
		(net "P3E_CPU1_PE3_MP_RXP<5>")
	)
	(segment
		(start 12.19962 -38.59022)
		(end 12.403836 -38.794436)
		(width 0.1143)
		(layer "B.Cu")
		(net "P3E_CPU1_PE3_MP_RXP<5>")
	)
	(segment
		(start 6.379464 -37.82441)
		(end 6.379464 -38.459664)
		(width 0.1143)
		(layer "B.Cu")
		(net "P3E_CPU1_PE3_MP_RXP<5>")
	)
	(segment
		(start 12.403836 -38.794436)
		(end 12.403836 -39.092124)
		(width 0.1143)
		(layer "B.Cu")
		(net "P3E_CPU1_PE3_MP_RXP<5>")
	)
	(segment
		(start 12.289536 -39.206424)
		(end 12.016486 -39.206424)
		(width 0.1143)
		(layer "B.Cu")
		(net "P3E_CPU1_PE3_MP_RXP<5>")
	)
	(segment
		(start 9.604248 -38.844728)
		(end 9.858756 -38.59022)
		(width 0.1143)
		(layer "B.Cu")
		(net "P3E_CPU1_PE3_MP_RXP<5>")
	)
	(segment
		(start 12.403836 -39.092124)
		(end 12.289536 -39.206424)
		(width 0.1143)
		(layer "B.Cu")
		(net "P3E_CPU1_PE3_MP_RXP<5>")
	)
	(segment
		(start 131.149598 -96.319086)
		(end 131.154424 -96.327722)
		(width 0.0889)
		(layer "In9.Cu")
		(net "P3E_CPU1_PE3_MP_RXP<5>")
	)
	(segment
		(start 71.428864 -112.332516)
		(end 83.07832 -114.662966)
		(width 0.1143)
		(layer "In9.Cu")
		(net "P3E_CPU1_PE3_MP_RXP<5>")
	)
	(segment
		(start 139.405614 -95.928434)
		(end 139.372848 -95.928434)
		(width 0.0889)
		(layer "In9.Cu")
		(net "P3E_CPU1_PE3_MP_RXP<5>")
	)
	(segment
		(start 27.868118 -40.836088)
		(end 28.078684 -40.936926)
		(width 0.1143)
		(layer "In9.Cu")
		(net "P3E_CPU1_PE3_MP_RXP<5>")
	)
	(segment
		(start 137.692384 -94.937834)
		(end 137.649204 -94.937834)
		(width 0.0889)
		(layer "In9.Cu")
		(net "P3E_CPU1_PE3_MP_RXP<5>")
	)
	(segment
		(start 41.41089 -41.933368)
		(end 53.019706 -49.672494)
		(width 0.1143)
		(layer "In9.Cu")
		(net "P3E_CPU1_PE3_MP_RXP<5>")
	)
	(segment
		(start 122.854212 -115.949476)
		(end 131.370578 -114.243358)
		(width 0.1143)
		(layer "In9.Cu")
		(net "P3E_CPU1_PE3_MP_RXP<5>")
	)
	(segment
		(start 12.264136 -39.206424)
		(end 12.378436 -39.320724)
		(width 0.1143)
		(layer "In9.Cu")
		(net "P3E_CPU1_PE3_MP_RXP<5>")
	)
	(segment
		(start 134.258304 -94.937834)
		(end 134.21868 -94.937834)
		(width 0.0889)
		(layer "In9.Cu")
		(net "P3E_CPU1_PE3_MP_RXP<5>")
	)
	(segment
		(start 58.980832 -59.52744)
		(end 58.083704 -64.013334)
		(width 0.1143)
		(layer "In9.Cu")
		(net "P3E_CPU1_PE3_MP_RXP<5>")
	)
	(segment
		(start 139.44473 -106.239056)
		(end 139.44473 -106.16692)
		(width 0.0889)
		(layer "In9.Cu")
		(net "P3E_CPU1_PE3_MP_RXP<5>")
	)
	(segment
		(start 12.016486 -39.206424)
		(end 12.264136 -39.206424)
		(width 0.1143)
		(layer "In9.Cu")
		(net "P3E_CPU1_PE3_MP_RXP<5>")
	)
	(segment
		(start 53.019706 -49.672494)
		(end 58.71972 -58.22188)
		(width 0.1143)
		(layer "In9.Cu")
		(net "P3E_CPU1_PE3_MP_RXP<5>")
	)
	(segment
		(start 131.143248 -97.299018)
		(end 131.149598 -97.309686)
		(width 0.0889)
		(layer "In9.Cu")
		(net "P3E_CPU1_PE3_MP_RXP<5>")
	)
	(segment
		(start 131.149598 -94.737936)
		(end 131.143248 -94.748604)
		(width 0.0889)
		(layer "In9.Cu")
		(net "P3E_CPU1_PE3_MP_RXP<5>")
	)
	(segment
		(start 12.683744 -39.973758)
		(end 13.042646 -40.10914)
		(width 0.1143)
		(layer "In9.Cu")
		(net "P3E_CPU1_PE3_MP_RXP<5>")
	)
	(segment
		(start 131.679188 -94.442534)
		(end 131.643628 -94.442534)
		(width 0.0889)
		(layer "In9.Cu")
		(net "P3E_CPU1_PE3_MP_RXP<5>")
	)
	(segment
		(start 131.370578 -114.243358)
		(end 131.370578 -114.243612)
		(width 0.1143)
		(layer "In9.Cu")
		(net "P3E_CPU1_PE3_MP_RXP<5>")
	)
	(segment
		(start 138.542268 -95.433134)
		(end 138.518138 -95.433134)
		(width 0.0889)
		(layer "In9.Cu")
		(net "P3E_CPU1_PE3_MP_RXP<5>")
	)
	(segment
		(start 135.108188 -95.433134)
		(end 135.084058 -95.433134)
		(width 0.0889)
		(layer "In9.Cu")
		(net "P3E_CPU1_PE3_MP_RXP<5>")
	)
	(segment
		(start 60.688728 -76.855574)
		(end 60.433712 -78.131416)
		(width 0.1143)
		(layer "In9.Cu")
		(net "P3E_CPU1_PE3_MP_RXP<5>")
	)
	(segment
		(start 139.44473 -106.16692)
		(end 140.890752 -104.720898)
		(width 0.0889)
		(layer "In9.Cu")
		(net "P3E_CPU1_PE3_MP_RXP<5>")
	)
	(segment
		(start 28.402026 -40.82288)
		(end 28.50261 -40.61206)
		(width 0.1143)
		(layer "In9.Cu")
		(net "P3E_CPU1_PE3_MP_RXP<5>")
	)
	(segment
		(start 12.378436 -39.320724)
		(end 12.378436 -39.60114)
		(width 0.1143)
		(layer "In9.Cu")
		(net "P3E_CPU1_PE3_MP_RXP<5>")
	)
	(segment
		(start 28.50261 -40.61206)
		(end 29.43606 -40.282622)
		(width 0.1143)
		(layer "In9.Cu")
		(net "P3E_CPU1_PE3_MP_RXP<5>")
	)
	(segment
		(start 131.143248 -96.308418)
		(end 131.149598 -96.319086)
		(width 0.0889)
		(layer "In9.Cu")
		(net "P3E_CPU1_PE3_MP_RXP<5>")
	)
	(segment
		(start 103.048054 -111.9886)
		(end 122.854212 -115.949476)
		(width 0.1143)
		(layer "In9.Cu")
		(net "P3E_CPU1_PE3_MP_RXP<5>")
	)
	(segment
		(start 140.753592 -98.308922)
		(end 140.758418 -98.300286)
		(width 0.0889)
		(layer "In9.Cu")
		(net "P3E_CPU1_PE3_MP_RXP<5>")
	)
	(segment
		(start 131.370578 -114.243612)
		(end 131.4577 -114.226086)
		(width 0.1143)
		(layer "In9.Cu")
		(net "P3E_CPU1_PE3_MP_RXP<5>")
	)
	(segment
		(start 83.07832 -114.662966)
		(end 97.110804 -111.856266)
		(width 0.1143)
		(layer "In9.Cu")
		(net "P3E_CPU1_PE3_MP_RXP<5>")
	)
	(segment
		(start 60.433712 -78.131416)
		(end 58.47715 -81.061814)
		(width 0.1143)
		(layer "In9.Cu")
		(net "P3E_CPU1_PE3_MP_RXP<5>")
	)
	(segment
		(start 131.149598 -97.309686)
		(end 131.154424 -97.318322)
		(width 0.0889)
		(layer "In9.Cu")
		(net "P3E_CPU1_PE3_MP_RXP<5>")
	)
	(segment
		(start 23.63089 -42.078656)
		(end 25.577038 -41.644824)
		(width 0.1143)
		(layer "In9.Cu")
		(net "P3E_CPU1_PE3_MP_RXP<5>")
	)
	(segment
		(start 140.705586 -101.335586)
		(end 140.705586 -100.511102)
		(width 0.0889)
		(layer "In9.Cu")
		(net "P3E_CPU1_PE3_MP_RXP<5>")
	)
	(segment
		(start 30.445964 -39.7764)
		(end 34.27603 -39.7764)
		(width 0.1143)
		(layer "In9.Cu")
		(net "P3E_CPU1_PE3_MP_RXP<5>")
	)
	(segment
		(start 12.378436 -39.60114)
		(end 12.683744 -39.973758)
		(width 0.1143)
		(layer "In9.Cu")
		(net "P3E_CPU1_PE3_MP_RXP<5>")
	)
	(segment
		(start 25.577038 -41.644824)
		(end 25.90038 -41.530778)
		(width 0.1143)
		(layer "In9.Cu")
		(net "P3E_CPU1_PE3_MP_RXP<5>")
	)
	(segment
		(start 100.410772 -112.516158)
		(end 103.048054 -111.9886)
		(width 0.1143)
		(layer "In9.Cu")
		(net "P3E_CPU1_PE3_MP_RXP<5>")
	)
	(segment
		(start 28.078684 -40.936926)
		(end 28.402026 -40.82288)
		(width 0.1143)
		(layer "In9.Cu")
		(net "P3E_CPU1_PE3_MP_RXP<5>")
	)
	(segment
		(start 140.705586 -100.511102)
		(end 140.705332 -100.505514)
		(width 0.0889)
		(layer "In9.Cu")
		(net "P3E_CPU1_PE3_MP_RXP<5>")
	)
	(segment
		(start 58.70702 -86.516464)
		(end 58.690764 -86.581234)
		(width 0.1143)
		(layer "In9.Cu")
		(net "P3E_CPU1_PE3_MP_RXP<5>")
	)
	(segment
		(start 140.705332 -100.505514)
		(end 140.705586 -100.505514)
		(width 0.0889)
		(layer "In9.Cu")
		(net "P3E_CPU1_PE3_MP_RXP<5>")
	)
	(segment
		(start 58.70702 -83.431634)
		(end 58.70702 -86.516464)
		(width 0.1143)
		(layer "In9.Cu")
		(net "P3E_CPU1_PE3_MP_RXP<5>")
	)
	(segment
		(start 133.395974 -94.442534)
		(end 133.360414 -94.442534)
		(width 0.0889)
		(layer "In9.Cu")
		(net "P3E_CPU1_PE3_MP_RXP<5>")
	)
	(segment
		(start 131.4577 -114.226086)
		(end 139.429236 -106.25455)
		(width 0.1143)
		(layer "In9.Cu")
		(net "P3E_CPU1_PE3_MP_RXP<5>")
	)
	(segment
		(start 140.764768 -97.720404)
		(end 140.758418 -97.709736)
		(width 0.0889)
		(layer "In9.Cu")
		(net "P3E_CPU1_PE3_MP_RXP<5>")
	)
	(segment
		(start 131.096004 -97.678748)
		(end 130.802888 -97.509584)
		(width 0.0889)
		(layer "In9.Cu")
		(net "P3E_CPU1_PE3_MP_RXP<5>")
	)
	(segment
		(start 60.34786 -75.153012)
		(end 60.688728 -76.855574)
		(width 0.1143)
		(layer "In9.Cu")
		(net "P3E_CPU1_PE3_MP_RXP<5>")
	)
	(segment
		(start 26.434288 -41.517316)
		(end 26.535126 -41.30675)
		(width 0.1143)
		(layer "In9.Cu")
		(net "P3E_CPU1_PE3_MP_RXP<5>")
	)
	(segment
		(start 58.12028 -89.4334)
		(end 60.95492 -103.608124)
		(width 0.1143)
		(layer "In9.Cu")
		(net "P3E_CPU1_PE3_MP_RXP<5>")
	)
	(segment
		(start 63.047372 -106.74731)
		(end 71.428864 -112.332516)
		(width 0.1143)
		(layer "In9.Cu")
		(net "P3E_CPU1_PE3_MP_RXP<5>")
	)
	(segment
		(start 140.753592 -99.299522)
		(end 140.758418 -99.290886)
		(width 0.0889)
		(layer "In9.Cu")
		(net "P3E_CPU1_PE3_MP_RXP<5>")
	)
	(segment
		(start 58.690764 -86.581234)
		(end 58.12028 -89.4334)
		(width 0.1143)
		(layer "In9.Cu")
		(net "P3E_CPU1_PE3_MP_RXP<5>")
	)
	(segment
		(start 57.76722 -67.468242)
		(end 57.76722 -70.330568)
		(width 0.1143)
		(layer "In9.Cu")
		(net "P3E_CPU1_PE3_MP_RXP<5>")
	)
	(segment
		(start 29.43606 -40.282622)
		(end 30.445964 -39.7764)
		(width 0.1143)
		(layer "In9.Cu")
		(net "P3E_CPU1_PE3_MP_RXP<5>")
	)
	(segment
		(start 58.47715 -81.061814)
		(end 58.47715 -81.90611)
		(width 0.1143)
		(layer "In9.Cu")
		(net "P3E_CPU1_PE3_MP_RXP<5>")
	)
	(segment
		(start 131.174744 -97.657412)
		(end 131.096004 -97.678748)
		(width 0.0889)
		(layer "In9.Cu")
		(net "P3E_CPU1_PE3_MP_RXP<5>")
	)
	(segment
		(start 26.110946 -41.631362)
		(end 26.434288 -41.517316)
		(width 0.1143)
		(layer "In9.Cu")
		(net "P3E_CPU1_PE3_MP_RXP<5>")
	)
	(segment
		(start 140.758418 -97.30994)
		(end 140.764514 -97.299018)
		(width 0.0889)
		(layer "In9.Cu")
		(net "P3E_CPU1_PE3_MP_RXP<5>")
	)
	(segment
		(start 140.267944 -96.423988)
		(end 140.235178 -96.423988)
		(width 0.0889)
		(layer "In9.Cu")
		(net "P3E_CPU1_PE3_MP_RXP<5>")
	)
	(segment
		(start 140.753592 -100.290122)
		(end 140.758418 -100.281486)
		(width 0.0889)
		(layer "In9.Cu")
		(net "P3E_CPU1_PE3_MP_RXP<5>")
	)
	(segment
		(start 34.27603 -39.7764)
		(end 41.41089 -41.933368)
		(width 0.1143)
		(layer "In9.Cu")
		(net "P3E_CPU1_PE3_MP_RXP<5>")
	)
	(segment
		(start 140.890752 -104.720898)
		(end 140.890752 -102.094792)
		(width 0.0889)
		(layer "In9.Cu")
		(net "P3E_CPU1_PE3_MP_RXP<5>")
	)
	(segment
		(start 58.083704 -64.013334)
		(end 58.373518 -65.46342)
		(width 0.1143)
		(layer "In9.Cu")
		(net "P3E_CPU1_PE3_MP_RXP<5>")
	)
	(segment
		(start 136.82345 -95.433134)
		(end 136.79932 -95.433134)
		(width 0.0889)
		(layer "In9.Cu")
		(net "P3E_CPU1_PE3_MP_RXP<5>")
	)
	(segment
		(start 140.758418 -100.281486)
		(end 140.764768 -100.270818)
		(width 0.0889)
		(layer "In9.Cu")
		(net "P3E_CPU1_PE3_MP_RXP<5>")
	)
	(segment
		(start 58.71972 -58.22188)
		(end 58.980832 -59.52744)
		(width 0.1143)
		(layer "In9.Cu")
		(net "P3E_CPU1_PE3_MP_RXP<5>")
	)
	(segment
		(start 132.537708 -94.937834)
		(end 132.507482 -94.937834)
		(width 0.0889)
		(layer "In9.Cu")
		(net "P3E_CPU1_PE3_MP_RXP<5>")
	)
	(segment
		(start 25.90038 -41.530778)
		(end 26.110946 -41.631362)
		(width 0.1143)
		(layer "In9.Cu")
		(net "P3E_CPU1_PE3_MP_RXP<5>")
	)
	(segment
		(start 139.429236 -106.25455)
		(end 139.44473 -106.239056)
		(width 0.0889)
		(layer "In9.Cu")
		(net "P3E_CPU1_PE3_MP_RXP<5>")
	)
	(segment
		(start 17.26184 -40.804338)
		(end 23.63089 -42.078656)
		(width 0.1143)
		(layer "In9.Cu")
		(net "P3E_CPU1_PE3_MP_RXP<5>")
	)
	(segment
		(start 58.47715 -81.90611)
		(end 58.85815 -82.28711)
		(width 0.1143)
		(layer "In9.Cu")
		(net "P3E_CPU1_PE3_MP_RXP<5>")
	)
	(segment
		(start 135.96874 -95.928434)
		(end 135.938768 -95.928434)
		(width 0.0889)
		(layer "In9.Cu")
		(net "P3E_CPU1_PE3_MP_RXP<5>")
	)
	(segment
		(start 57.76722 -70.330568)
		(end 60.34786 -75.153012)
		(width 0.1143)
		(layer "In9.Cu")
		(net "P3E_CPU1_PE3_MP_RXP<5>")
	)
	(segment
		(start 60.95492 -103.608124)
		(end 63.047372 -106.74731)
		(width 0.1143)
		(layer "In9.Cu")
		(net "P3E_CPU1_PE3_MP_RXP<5>")
	)
	(segment
		(start 58.85815 -83.280504)
		(end 58.70702 -83.431634)
		(width 0.1143)
		(layer "In9.Cu")
		(net "P3E_CPU1_PE3_MP_RXP<5>")
	)
	(segment
		(start 26.535126 -41.30675)
		(end 27.868118 -40.836088)
		(width 0.1143)
		(layer "In9.Cu")
		(net "P3E_CPU1_PE3_MP_RXP<5>")
	)
	(segment
		(start 58.373518 -65.46342)
		(end 57.76722 -67.468242)
		(width 0.1143)
		(layer "In9.Cu")
		(net "P3E_CPU1_PE3_MP_RXP<5>")
	)
	(segment
		(start 97.110804 -111.856266)
		(end 100.410772 -112.516158)
		(width 0.1143)
		(layer "In9.Cu")
		(net "P3E_CPU1_PE3_MP_RXP<5>")
	)
	(segment
		(start 58.85815 -82.28711)
		(end 58.85815 -83.280504)
		(width 0.1143)
		(layer "In9.Cu")
		(net "P3E_CPU1_PE3_MP_RXP<5>")
	)
	(segment
		(start 13.042646 -40.10914)
		(end 17.26184 -40.804338)
		(width 0.1143)
		(layer "In9.Cu")
		(net "P3E_CPU1_PE3_MP_RXP<5>")
	)
	(segment
		(start 140.758418 -99.290886)
		(end 140.764768 -99.280218)
		(width 0.0889)
		(layer "In9.Cu")
		(net "P3E_CPU1_PE3_MP_RXP<5>")
	)
	(segment
		(start 131.149598 -95.328486)
		(end 131.154424 -95.337122)
		(width 0.0889)
		(layer "In9.Cu")
		(net "P3E_CPU1_PE3_MP_RXP<5>")
	)
	(arc
		(start 133.360414 -94.442534)
		(mid 133.07499 -94.526001)
		(end 132.866384 -94.737936)
		(width 0.0889)
		(layer "In9.Cu")
		(net "P3E_CPU1_PE3_MP_RXP<5>")
	)
	(arc
		(start 139.041124 -95.728536)
		(mid 138.830411 -95.515457)
		(end 138.542268 -95.433134)
		(width 0.0889)
		(layer "In9.Cu")
		(net "P3E_CPU1_PE3_MP_RXP<5>")
	)
	(arc
		(start 135.084058 -95.433134)
		(mid 134.890208 -95.376784)
		(end 134.748524 -95.232982)
		(width 0.0889)
		(layer "In9.Cu")
		(net "P3E_CPU1_PE3_MP_RXP<5>")
	)
	(arc
		(start 140.764768 -100.270818)
		(mid 140.837566 -99.980055)
		(end 140.758418 -99.690936)
		(width 0.0889)
		(layer "In9.Cu")
		(net "P3E_CPU1_PE3_MP_RXP<5>")
	)
	(arc
		(start 140.340842 -96.4311)
		(mid 140.304503 -96.426413)
		(end 140.267944 -96.423988)
		(width 0.0889)
		(layer "In9.Cu")
		(net "P3E_CPU1_PE3_MP_RXP<5>")
	)
	(arc
		(start 137.158984 -95.232982)
		(mid 137.017301 -95.376786)
		(end 136.82345 -95.433134)
		(width 0.0889)
		(layer "In9.Cu")
		(net "P3E_CPU1_PE3_MP_RXP<5>")
	)
	(arc
		(start 139.372848 -95.928434)
		(mid 139.181206 -95.871268)
		(end 139.041124 -95.728536)
		(width 0.0889)
		(layer "In9.Cu")
		(net "P3E_CPU1_PE3_MP_RXP<5>")
	)
	(arc
		(start 133.890004 -94.737936)
		(mid 133.681396 -94.526004)
		(end 133.395974 -94.442534)
		(width 0.0889)
		(layer "In9.Cu")
		(net "P3E_CPU1_PE3_MP_RXP<5>")
	)
	(arc
		(start 131.154424 -97.318322)
		(mid 131.202337 -97.485607)
		(end 131.174744 -97.657412)
		(width 0.0889)
		(layer "In9.Cu")
		(net "P3E_CPU1_PE3_MP_RXP<5>")
	)
	(arc
		(start 140.758418 -98.300286)
		(mid 140.83764 -98.011168)
		(end 140.764768 -97.720404)
		(width 0.0889)
		(layer "In9.Cu")
		(net "P3E_CPU1_PE3_MP_RXP<5>")
	)
	(arc
		(start 140.235178 -96.423988)
		(mid 140.041328 -96.367638)
		(end 139.899644 -96.223836)
		(width 0.0889)
		(layer "In9.Cu")
		(net "P3E_CPU1_PE3_MP_RXP<5>")
	)
	(arc
		(start 131.149598 -96.719136)
		(mid 131.070376 -97.008254)
		(end 131.143248 -97.299018)
		(width 0.0889)
		(layer "In9.Cu")
		(net "P3E_CPU1_PE3_MP_RXP<5>")
	)
	(arc
		(start 140.764768 -99.280218)
		(mid 140.837566 -98.989455)
		(end 140.758418 -98.700336)
		(width 0.0889)
		(layer "In9.Cu")
		(net "P3E_CPU1_PE3_MP_RXP<5>")
	)
	(arc
		(start 131.154424 -96.327722)
		(mid 131.203179 -96.524074)
		(end 131.149598 -96.719136)
		(width 0.0889)
		(layer "In9.Cu")
		(net "P3E_CPU1_PE3_MP_RXP<5>")
	)
	(arc
		(start 131.149598 -95.728536)
		(mid 131.070376 -96.017654)
		(end 131.143248 -96.308418)
		(width 0.0889)
		(layer "In9.Cu")
		(net "P3E_CPU1_PE3_MP_RXP<5>")
	)
	(arc
		(start 140.764514 -97.299018)
		(mid 140.777571 -96.755256)
		(end 140.340842 -96.4311)
		(width 0.0889)
		(layer "In9.Cu")
		(net "P3E_CPU1_PE3_MP_RXP<5>")
	)
	(arc
		(start 140.758418 -99.690936)
		(mid 140.704948 -99.495873)
		(end 140.753592 -99.299522)
		(width 0.0889)
		(layer "In9.Cu")
		(net "P3E_CPU1_PE3_MP_RXP<5>")
	)
	(arc
		(start 136.300464 -95.728536)
		(mid 136.160385 -95.871272)
		(end 135.96874 -95.928434)
		(width 0.0889)
		(layer "In9.Cu")
		(net "P3E_CPU1_PE3_MP_RXP<5>")
	)
	(arc
		(start 132.507482 -94.937834)
		(mid 132.314379 -94.881315)
		(end 132.173218 -94.737936)
		(width 0.0889)
		(layer "In9.Cu")
		(net "P3E_CPU1_PE3_MP_RXP<5>")
	)
	(arc
		(start 139.899644 -96.223836)
		(mid 139.691036 -96.011904)
		(end 139.405614 -95.928434)
		(width 0.0889)
		(layer "In9.Cu")
		(net "P3E_CPU1_PE3_MP_RXP<5>")
	)
	(arc
		(start 131.643628 -94.442534)
		(mid 131.358204 -94.526001)
		(end 131.149598 -94.737936)
		(width 0.0889)
		(layer "In9.Cu")
		(net "P3E_CPU1_PE3_MP_RXP<5>")
	)
	(arc
		(start 140.758418 -97.709736)
		(mid 140.704919 -97.509838)
		(end 140.758418 -97.30994)
		(width 0.0889)
		(layer "In9.Cu")
		(net "P3E_CPU1_PE3_MP_RXP<5>")
	)
	(arc
		(start 131.154424 -95.337122)
		(mid 131.203179 -95.533474)
		(end 131.149598 -95.728536)
		(width 0.0889)
		(layer "In9.Cu")
		(net "P3E_CPU1_PE3_MP_RXP<5>")
	)
	(arc
		(start 138.518138 -95.433134)
		(mid 138.324288 -95.376784)
		(end 138.182604 -95.232982)
		(width 0.0889)
		(layer "In9.Cu")
		(net "P3E_CPU1_PE3_MP_RXP<5>")
	)
	(arc
		(start 140.814298 -101.741478)
		(mid 140.73328 -101.545677)
		(end 140.705586 -101.335586)
		(width 0.0889)
		(layer "In9.Cu")
		(net "P3E_CPU1_PE3_MP_RXP<5>")
	)
	(arc
		(start 132.173218 -94.737936)
		(mid 131.96461 -94.526004)
		(end 131.679188 -94.442534)
		(width 0.0889)
		(layer "In9.Cu")
		(net "P3E_CPU1_PE3_MP_RXP<5>")
	)
	(arc
		(start 140.705586 -100.505514)
		(mid 140.714483 -100.394456)
		(end 140.753592 -100.290122)
		(width 0.0889)
		(layer "In9.Cu")
		(net "P3E_CPU1_PE3_MP_RXP<5>")
	)
	(arc
		(start 137.649204 -94.937834)
		(mid 137.365987 -95.022115)
		(end 137.158984 -95.232982)
		(width 0.0889)
		(layer "In9.Cu")
		(net "P3E_CPU1_PE3_MP_RXP<5>")
	)
	(arc
		(start 134.748524 -95.232982)
		(mid 134.54152 -95.022118)
		(end 134.258304 -94.937834)
		(width 0.0889)
		(layer "In9.Cu")
		(net "P3E_CPU1_PE3_MP_RXP<5>")
	)
	(arc
		(start 138.182604 -95.232982)
		(mid 137.9756 -95.022118)
		(end 137.692384 -94.937834)
		(width 0.0889)
		(layer "In9.Cu")
		(net "P3E_CPU1_PE3_MP_RXP<5>")
	)
	(arc
		(start 140.890752 -102.094792)
		(mid 140.880205 -101.912144)
		(end 140.814298 -101.741478)
		(width 0.0889)
		(layer "In9.Cu")
		(net "P3E_CPU1_PE3_MP_RXP<5>")
	)
	(arc
		(start 135.607044 -95.728536)
		(mid 135.396331 -95.515457)
		(end 135.108188 -95.433134)
		(width 0.0889)
		(layer "In9.Cu")
		(net "P3E_CPU1_PE3_MP_RXP<5>")
	)
	(arc
		(start 135.938768 -95.928434)
		(mid 135.747126 -95.871268)
		(end 135.607044 -95.728536)
		(width 0.0889)
		(layer "In9.Cu")
		(net "P3E_CPU1_PE3_MP_RXP<5>")
	)
	(arc
		(start 140.758418 -98.700336)
		(mid 140.704948 -98.505273)
		(end 140.753592 -98.308922)
		(width 0.0889)
		(layer "In9.Cu")
		(net "P3E_CPU1_PE3_MP_RXP<5>")
	)
	(arc
		(start 136.79932 -95.433134)
		(mid 136.511175 -95.515453)
		(end 136.300464 -95.728536)
		(width 0.0889)
		(layer "In9.Cu")
		(net "P3E_CPU1_PE3_MP_RXP<5>")
	)
	(arc
		(start 131.143248 -94.748604)
		(mid 131.07045 -95.039367)
		(end 131.149598 -95.328486)
		(width 0.0889)
		(layer "In9.Cu")
		(net "P3E_CPU1_PE3_MP_RXP<5>")
	)
	(arc
		(start 132.866384 -94.737936)
		(mid 132.72764 -94.879969)
		(end 132.537708 -94.937834)
		(width 0.0889)
		(layer "In9.Cu")
		(net "P3E_CPU1_PE3_MP_RXP<5>")
	)
	(arc
		(start 134.21868 -94.937834)
		(mid 134.028751 -94.879964)
		(end 133.890004 -94.737936)
		(width 0.0889)
		(layer "In9.Cu")
		(net "P3E_CPU1_PE3_MP_RXP<5>")
	)
	(segment
		(start 129.372868 -97.014538)
		(end 129.944368 -97.014538)
		(width 0.1143)
		(layer "F.Cu")
		(net "P3E_CPU1_PE3_MP_RXP<4>")
	)
	(via
		(at 129.944368 -97.014538)
		(size 0.508)
		(drill 0.254)
		(layers "F.Cu" "B.Cu")
		(net "P3E_CPU1_PE3_MP_RXP<4>")
	)
	(segment
		(start 83.04149 -115.330732)
		(end 95.572834 -112.824006)
		(width 0.1143)
		(layer "In9.Cu")
		(net "P3E_CPU1_PE3_MP_RXP<4>")
	)
	(segment
		(start 10.906252 -39.78656)
		(end 12.56792 -40.718994)
		(width 0.1143)
		(layer "In9.Cu")
		(net "P3E_CPU1_PE3_MP_RXP<4>")
	)
	(segment
		(start 31.086806 -40.4114)
		(end 34.181034 -40.4114)
		(width 0.1143)
		(layer "In9.Cu")
		(net "P3E_CPU1_PE3_MP_RXP<4>")
	)
	(segment
		(start 141.777466 -102.415848)
		(end 141.777466 -101.184202)
		(width 0.0889)
		(layer "In9.Cu")
		(net "P3E_CPU1_PE3_MP_RXP<4>")
	)
	(segment
		(start 25.715976 -43.1673)
		(end 26.668476 -43.107864)
		(width 0.1143)
		(layer "In9.Cu")
		(net "P3E_CPU1_PE3_MP_RXP<4>")
	)
	(segment
		(start 70.907402 -112.903762)
		(end 83.04149 -115.330732)
		(width 0.1143)
		(layer "In9.Cu")
		(net "P3E_CPU1_PE3_MP_RXP<4>")
	)
	(segment
		(start 17.620234 -41.548812)
		(end 25.715976 -43.1673)
		(width 0.1143)
		(layer "In9.Cu")
		(net "P3E_CPU1_PE3_MP_RXP<4>")
	)
	(segment
		(start 141.777466 -101.184202)
		(end 141.590776 -100.997512)
		(width 0.0889)
		(layer "In9.Cu")
		(net "P3E_CPU1_PE3_MP_RXP<4>")
	)
	(segment
		(start 141.828266 -102.488746)
		(end 141.828266 -102.466648)
		(width 0.0889)
		(layer "In9.Cu")
		(net "P3E_CPU1_PE3_MP_RXP<4>")
	)
	(segment
		(start 10.353294 -38.627812)
		(end 10.689082 -39.534084)
		(width 0.1143)
		(layer "In9.Cu")
		(net "P3E_CPU1_PE3_MP_RXP<4>")
	)
	(segment
		(start 29.85389 -41.04132)
		(end 31.086806 -40.4114)
		(width 0.1143)
		(layer "In9.Cu")
		(net "P3E_CPU1_PE3_MP_RXP<4>")
	)
	(segment
		(start 57.92089 -86.823296)
		(end 57.42432 -89.306146)
		(width 0.1143)
		(layer "In9.Cu")
		(net "P3E_CPU1_PE3_MP_RXP<4>")
	)
	(segment
		(start 57.375044 -63.873634)
		(end 57.531 -64.653668)
		(width 0.1143)
		(layer "In9.Cu")
		(net "P3E_CPU1_PE3_MP_RXP<4>")
	)
	(segment
		(start 141.828266 -105.161334)
		(end 141.828266 -102.488746)
		(width 0.1143)
		(layer "In9.Cu")
		(net "P3E_CPU1_PE3_MP_RXP<4>")
	)
	(segment
		(start 140.264642 -95.433388)
		(end 140.244322 -95.433388)
		(width 0.0889)
		(layer "In9.Cu")
		(net "P3E_CPU1_PE3_MP_RXP<4>")
	)
	(segment
		(start 130.284728 -94.822518)
		(end 130.291078 -94.833186)
		(width 0.0889)
		(layer "In9.Cu")
		(net "P3E_CPU1_PE3_MP_RXP<4>")
	)
	(segment
		(start 57.961784 -58.50128)
		(end 58.205624 -59.720734)
		(width 0.1143)
		(layer "In9.Cu")
		(net "P3E_CPU1_PE3_MP_RXP<4>")
	)
	(segment
		(start 10.689082 -39.534084)
		(end 10.906252 -39.78656)
		(width 0.1143)
		(layer "In9.Cu")
		(net "P3E_CPU1_PE3_MP_RXP<4>")
	)
	(segment
		(start 138.547094 -94.442534)
		(end 138.51128 -94.442534)
		(width 0.0889)
		(layer "In9.Cu")
		(net "P3E_CPU1_PE3_MP_RXP<4>")
	)
	(segment
		(start 58.205624 -59.720734)
		(end 58.205878 -59.720734)
		(width 0.1143)
		(layer "In9.Cu")
		(net "P3E_CPU1_PE3_MP_RXP<4>")
	)
	(segment
		(start 141.183614 -95.93326)
		(end 141.183106 -95.93326)
		(width 0.0889)
		(layer "In9.Cu")
		(net "P3E_CPU1_PE3_MP_RXP<4>")
	)
	(segment
		(start 2.3876 -36.993068)
		(end 2.524506 -36.856162)
		(width 0.1143)
		(layer "In9.Cu")
		(net "P3E_CPU1_PE3_MP_RXP<4>")
	)
	(segment
		(start 2.833624 -37.71011)
		(end 2.3876 -37.264086)
		(width 0.1143)
		(layer "In9.Cu")
		(net "P3E_CPU1_PE3_MP_RXP<4>")
	)
	(segment
		(start 141.566646 -96.134936)
		(end 141.54531 -96.108012)
		(width 0.0889)
		(layer "In9.Cu")
		(net "P3E_CPU1_PE3_MP_RXP<4>")
	)
	(segment
		(start 57.531 -64.653668)
		(end 57.531 -65.95872)
		(width 0.1143)
		(layer "In9.Cu")
		(net "P3E_CPU1_PE3_MP_RXP<4>")
	)
	(segment
		(start 60.040774 -76.85532)
		(end 59.835288 -77.883512)
		(width 0.1143)
		(layer "In9.Cu")
		(net "P3E_CPU1_PE3_MP_RXP<4>")
	)
	(segment
		(start 134.249668 -93.947234)
		(end 134.221728 -93.947234)
		(width 0.0889)
		(layer "In9.Cu")
		(net "P3E_CPU1_PE3_MP_RXP<4>")
	)
	(segment
		(start 133.399784 -93.452188)
		(end 133.356604 -93.452188)
		(width 0.0889)
		(layer "In9.Cu")
		(net "P3E_CPU1_PE3_MP_RXP<4>")
	)
	(segment
		(start 56.99252 -70.230492)
		(end 59.74461 -75.37704)
		(width 0.1143)
		(layer "In9.Cu")
		(net "P3E_CPU1_PE3_MP_RXP<4>")
	)
	(segment
		(start 57.42432 -89.306146)
		(end 60.328048 -103.827072)
		(width 0.1143)
		(layer "In9.Cu")
		(net "P3E_CPU1_PE3_MP_RXP<4>")
	)
	(segment
		(start 95.572834 -112.824006)
		(end 99.160076 -113.543842)
		(width 0.1143)
		(layer "In9.Cu")
		(net "P3E_CPU1_PE3_MP_RXP<4>")
	)
	(segment
		(start 52.316126 -50.03292)
		(end 57.961784 -58.50128)
		(width 0.1143)
		(layer "In9.Cu")
		(net "P3E_CPU1_PE3_MP_RXP<4>")
	)
	(segment
		(start 136.830308 -94.442534)
		(end 136.794494 -94.442534)
		(width 0.0889)
		(layer "In9.Cu")
		(net "P3E_CPU1_PE3_MP_RXP<4>")
	)
	(segment
		(start 2.3876 -37.264086)
		(end 2.3876 -36.993068)
		(width 0.1143)
		(layer "In9.Cu")
		(net "P3E_CPU1_PE3_MP_RXP<4>")
	)
	(segment
		(start 62.756796 -107.46994)
		(end 70.907402 -112.903762)
		(width 0.1143)
		(layer "In9.Cu")
		(net "P3E_CPU1_PE3_MP_RXP<4>")
	)
	(segment
		(start 34.181034 -40.4114)
		(end 40.955976 -42.459656)
		(width 0.1143)
		(layer "In9.Cu")
		(net "P3E_CPU1_PE3_MP_RXP<4>")
	)
	(segment
		(start 2.524506 -36.856162)
		(end 8.46201 -36.856162)
		(width 0.1143)
		(layer "In9.Cu")
		(net "P3E_CPU1_PE3_MP_RXP<4>")
	)
	(segment
		(start 141.10589 -95.92818)
		(end 141.103858 -95.92818)
		(width 0.0889)
		(layer "In9.Cu")
		(net "P3E_CPU1_PE3_MP_RXP<4>")
	)
	(segment
		(start 130.291078 -96.223836)
		(end 130.284728 -96.234504)
		(width 0.0889)
		(layer "In9.Cu")
		(net "P3E_CPU1_PE3_MP_RXP<4>")
	)
	(segment
		(start 12.56792 -40.718994)
		(end 17.620234 -41.548812)
		(width 0.1143)
		(layer "In9.Cu")
		(net "P3E_CPU1_PE3_MP_RXP<4>")
	)
	(segment
		(start 135.971788 -94.937834)
		(end 135.93572 -94.937834)
		(width 0.0889)
		(layer "In9.Cu")
		(net "P3E_CPU1_PE3_MP_RXP<4>")
	)
	(segment
		(start 140.244322 -95.433388)
		(end 140.235178 -95.433134)
		(width 0.0889)
		(layer "In9.Cu")
		(net "P3E_CPU1_PE3_MP_RXP<4>")
	)
	(segment
		(start 57.23255 -82.009234)
		(end 57.23255 -83.17611)
		(width 0.1143)
		(layer "In9.Cu")
		(net "P3E_CPU1_PE3_MP_RXP<4>")
	)
	(segment
		(start 130.817874 -93.947234)
		(end 130.789934 -93.947234)
		(width 0.0889)
		(layer "In9.Cu")
		(net "P3E_CPU1_PE3_MP_RXP<4>")
	)
	(segment
		(start 139.409424 -94.937834)
		(end 139.3698 -94.937834)
		(width 0.0889)
		(layer "In9.Cu")
		(net "P3E_CPU1_PE3_MP_RXP<4>")
	)
	(segment
		(start 130.295904 -96.2152)
		(end 130.291078 -96.223836)
		(width 0.0889)
		(layer "In9.Cu")
		(net "P3E_CPU1_PE3_MP_RXP<4>")
	)
	(segment
		(start 141.126464 -95.928434)
		(end 141.12367 -95.928434)
		(width 0.0889)
		(layer "In9.Cu")
		(net "P3E_CPU1_PE3_MP_RXP<4>")
	)
	(segment
		(start 2.999994 -37.71011)
		(end 2.833624 -37.71011)
		(width 0.1143)
		(layer "In9.Cu")
		(net "P3E_CPU1_PE3_MP_RXP<4>")
	)
	(segment
		(start 57.531 -65.95872)
		(end 56.99252 -67.258946)
		(width 0.1143)
		(layer "In9.Cu")
		(net "P3E_CPU1_PE3_MP_RXP<4>")
	)
	(segment
		(start 141.828266 -102.466648)
		(end 141.777466 -102.415848)
		(width 0.0889)
		(layer "In9.Cu")
		(net "P3E_CPU1_PE3_MP_RXP<4>")
	)
	(segment
		(start 8.46201 -36.856162)
		(end 9.262872 -37.407088)
		(width 0.1143)
		(layer "In9.Cu")
		(net "P3E_CPU1_PE3_MP_RXP<4>")
	)
	(segment
		(start 122.960892 -116.674646)
		(end 132.152898 -114.836702)
		(width 0.1143)
		(layer "In9.Cu")
		(net "P3E_CPU1_PE3_MP_RXP<4>")
	)
	(segment
		(start 26.668476 -43.107864)
		(end 28.668472 -42.211498)
		(width 0.1143)
		(layer "In9.Cu")
		(net "P3E_CPU1_PE3_MP_RXP<4>")
	)
	(segment
		(start 56.99252 -67.258946)
		(end 56.99252 -70.230492)
		(width 0.1143)
		(layer "In9.Cu")
		(net "P3E_CPU1_PE3_MP_RXP<4>")
	)
	(segment
		(start 141.590776 -100.997512)
		(end 141.590776 -99.056698)
		(width 0.0889)
		(layer "In9.Cu")
		(net "P3E_CPU1_PE3_MP_RXP<4>")
	)
	(segment
		(start 57.23255 -83.17611)
		(end 57.92089 -83.86445)
		(width 0.1143)
		(layer "In9.Cu")
		(net "P3E_CPU1_PE3_MP_RXP<4>")
	)
	(segment
		(start 135.113014 -94.442534)
		(end 135.0772 -94.442534)
		(width 0.0889)
		(layer "In9.Cu")
		(net "P3E_CPU1_PE3_MP_RXP<4>")
	)
	(segment
		(start 59.74461 -75.37704)
		(end 60.040774 -76.85532)
		(width 0.1143)
		(layer "In9.Cu")
		(net "P3E_CPU1_PE3_MP_RXP<4>")
	)
	(segment
		(start 28.668472 -42.211498)
		(end 29.85389 -41.04132)
		(width 0.1143)
		(layer "In9.Cu")
		(net "P3E_CPU1_PE3_MP_RXP<4>")
	)
	(segment
		(start 60.328048 -103.827072)
		(end 62.756796 -107.46994)
		(width 0.1143)
		(layer "In9.Cu")
		(net "P3E_CPU1_PE3_MP_RXP<4>")
	)
	(segment
		(start 129.944368 -97.352612)
		(end 129.944368 -97.014538)
		(width 0.0889)
		(layer "In9.Cu")
		(net "P3E_CPU1_PE3_MP_RXP<4>")
	)
	(segment
		(start 103.23322 -112.729264)
		(end 122.960892 -116.674646)
		(width 0.1143)
		(layer "In9.Cu")
		(net "P3E_CPU1_PE3_MP_RXP<4>")
	)
	(segment
		(start 57.92089 -83.86445)
		(end 57.92089 -86.823296)
		(width 0.1143)
		(layer "In9.Cu")
		(net "P3E_CPU1_PE3_MP_RXP<4>")
	)
	(segment
		(start 58.205878 -59.720734)
		(end 57.375044 -63.873634)
		(width 0.1143)
		(layer "In9.Cu")
		(net "P3E_CPU1_PE3_MP_RXP<4>")
	)
	(segment
		(start 141.66469 -97.232724)
		(end 141.656562 -97.217484)
		(width 0.0889)
		(layer "In9.Cu")
		(net "P3E_CPU1_PE3_MP_RXP<4>")
	)
	(segment
		(start 59.835288 -77.883512)
		(end 57.84215 -80.869028)
		(width 0.1143)
		(layer "In9.Cu")
		(net "P3E_CPU1_PE3_MP_RXP<4>")
	)
	(segment
		(start 57.84215 -80.869028)
		(end 57.23255 -82.009234)
		(width 0.1143)
		(layer "In9.Cu")
		(net "P3E_CPU1_PE3_MP_RXP<4>")
	)
	(segment
		(start 9.262872 -37.407088)
		(end 10.353294 -38.627812)
		(width 0.1143)
		(layer "In9.Cu")
		(net "P3E_CPU1_PE3_MP_RXP<4>")
	)
	(segment
		(start 99.160076 -113.543842)
		(end 103.23322 -112.729264)
		(width 0.1143)
		(layer "In9.Cu")
		(net "P3E_CPU1_PE3_MP_RXP<4>")
	)
	(segment
		(start 130.00228 -97.410524)
		(end 129.944368 -97.352612)
		(width 0.0889)
		(layer "In9.Cu")
		(net "P3E_CPU1_PE3_MP_RXP<4>")
	)
	(segment
		(start 132.152898 -114.836702)
		(end 141.828266 -105.161334)
		(width 0.1143)
		(layer "In9.Cu")
		(net "P3E_CPU1_PE3_MP_RXP<4>")
	)
	(segment
		(start 40.955976 -42.459656)
		(end 52.316126 -50.03292)
		(width 0.1143)
		(layer "In9.Cu")
		(net "P3E_CPU1_PE3_MP_RXP<4>")
	)
	(arc
		(start 141.103858 -95.92818)
		(mid 140.904267 -95.874677)
		(end 140.758164 -95.728536)
		(width 0.0889)
		(layer "In9.Cu")
		(net "P3E_CPU1_PE3_MP_RXP<4>")
	)
	(arc
		(start 141.656562 -98.792538)
		(mid 141.70872 -98.659439)
		(end 141.729206 -98.517964)
		(width 0.0889)
		(layer "In9.Cu")
		(net "P3E_CPU1_PE3_MP_RXP<4>")
	)
	(arc
		(start 140.758164 -95.728536)
		(mid 140.549745 -95.516823)
		(end 140.264642 -95.433388)
		(width 0.0889)
		(layer "In9.Cu")
		(net "P3E_CPU1_PE3_MP_RXP<4>")
	)
	(arc
		(start 130.284728 -96.234504)
		(mid 130.21193 -96.525267)
		(end 130.291078 -96.814386)
		(width 0.0889)
		(layer "In9.Cu")
		(net "P3E_CPU1_PE3_MP_RXP<4>")
	)
	(arc
		(start 130.291078 -95.232982)
		(mid 130.211947 -95.528384)
		(end 130.291078 -95.823786)
		(width 0.0889)
		(layer "In9.Cu")
		(net "P3E_CPU1_PE3_MP_RXP<4>")
	)
	(arc
		(start 135.0772 -94.442534)
		(mid 134.887271 -94.384664)
		(end 134.748524 -94.242636)
		(width 0.0889)
		(layer "In9.Cu")
		(net "P3E_CPU1_PE3_MP_RXP<4>")
	)
	(arc
		(start 132.19811 -93.785182)
		(mid 132.186691 -93.769471)
		(end 132.17652 -93.752924)
		(width 0.0889)
		(layer "In9.Cu")
		(net "P3E_CPU1_PE3_MP_RXP<4>")
	)
	(arc
		(start 132.17652 -93.752924)
		(mid 131.950288 -93.527102)
		(end 131.639564 -93.452188)
		(width 0.0889)
		(layer "In9.Cu")
		(net "P3E_CPU1_PE3_MP_RXP<4>")
	)
	(arc
		(start 131.639564 -93.452188)
		(mid 131.356487 -93.536527)
		(end 131.149598 -93.747336)
		(width 0.0889)
		(layer "In9.Cu")
		(net "P3E_CPU1_PE3_MP_RXP<4>")
	)
	(arc
		(start 132.866384 -93.747336)
		(mid 132.723667 -93.891543)
		(end 132.528564 -93.947234)
		(width 0.0889)
		(layer "In9.Cu")
		(net "P3E_CPU1_PE3_MP_RXP<4>")
	)
	(arc
		(start 138.182604 -94.242636)
		(mid 137.670794 -93.947097)
		(end 137.158984 -94.242636)
		(width 0.0889)
		(layer "In9.Cu")
		(net "P3E_CPU1_PE3_MP_RXP<4>")
	)
	(arc
		(start 141.729206 -98.517964)
		(mid 141.71293 -98.358329)
		(end 141.656562 -98.208084)
		(width 0.0889)
		(layer "In9.Cu")
		(net "P3E_CPU1_PE3_MP_RXP<4>")
	)
	(arc
		(start 130.291078 -95.823786)
		(mid 130.344548 -96.018849)
		(end 130.295904 -96.2152)
		(width 0.0889)
		(layer "In9.Cu")
		(net "P3E_CPU1_PE3_MP_RXP<4>")
	)
	(arc
		(start 139.3698 -94.937834)
		(mid 139.179871 -94.879964)
		(end 139.041124 -94.737936)
		(width 0.0889)
		(layer "In9.Cu")
		(net "P3E_CPU1_PE3_MP_RXP<4>")
	)
	(arc
		(start 135.93572 -94.937834)
		(mid 135.745791 -94.879964)
		(end 135.607044 -94.737936)
		(width 0.0889)
		(layer "In9.Cu")
		(net "P3E_CPU1_PE3_MP_RXP<4>")
	)
	(arc
		(start 141.665706 -96.791018)
		(mid 141.703476 -96.449802)
		(end 141.566646 -96.134936)
		(width 0.0889)
		(layer "In9.Cu")
		(net "P3E_CPU1_PE3_MP_RXP<4>")
	)
	(arc
		(start 132.528564 -93.947234)
		(mid 132.51815 -93.94737)
		(end 132.507736 -93.947234)
		(width 0.0889)
		(layer "In9.Cu")
		(net "P3E_CPU1_PE3_MP_RXP<4>")
	)
	(arc
		(start 141.183106 -95.93326)
		(mid 141.154843 -95.930163)
		(end 141.126464 -95.928434)
		(width 0.0889)
		(layer "In9.Cu")
		(net "P3E_CPU1_PE3_MP_RXP<4>")
	)
	(arc
		(start 131.149598 -93.747336)
		(mid 131.009519 -93.890072)
		(end 130.817874 -93.947234)
		(width 0.0889)
		(layer "In9.Cu")
		(net "P3E_CPU1_PE3_MP_RXP<4>")
	)
	(arc
		(start 141.590776 -99.056698)
		(mid 141.607467 -98.920582)
		(end 141.656562 -98.792538)
		(width 0.0889)
		(layer "In9.Cu")
		(net "P3E_CPU1_PE3_MP_RXP<4>")
	)
	(arc
		(start 135.607044 -94.737936)
		(mid 135.398436 -94.526004)
		(end 135.113014 -94.442534)
		(width 0.0889)
		(layer "In9.Cu")
		(net "P3E_CPU1_PE3_MP_RXP<4>")
	)
	(arc
		(start 141.656562 -97.217484)
		(mid 141.606149 -97.014538)
		(end 141.656562 -96.811592)
		(width 0.0889)
		(layer "In9.Cu")
		(net "P3E_CPU1_PE3_MP_RXP<4>")
	)
	(arc
		(start 141.54531 -96.108012)
		(mid 141.384457 -95.97926)
		(end 141.183614 -95.93326)
		(width 0.0889)
		(layer "In9.Cu")
		(net "P3E_CPU1_PE3_MP_RXP<4>")
	)
	(arc
		(start 141.656562 -98.208084)
		(mid 141.606149 -98.005138)
		(end 141.656562 -97.802192)
		(width 0.0889)
		(layer "In9.Cu")
		(net "P3E_CPU1_PE3_MP_RXP<4>")
	)
	(arc
		(start 133.356604 -93.452188)
		(mid 133.073387 -93.536469)
		(end 132.866384 -93.747336)
		(width 0.0889)
		(layer "In9.Cu")
		(net "P3E_CPU1_PE3_MP_RXP<4>")
	)
	(arc
		(start 130.789934 -93.947234)
		(mid 130.291053 -94.242671)
		(end 130.284728 -94.822518)
		(width 0.0889)
		(layer "In9.Cu")
		(net "P3E_CPU1_PE3_MP_RXP<4>")
	)
	(arc
		(start 139.899644 -95.232982)
		(mid 139.69264 -95.022118)
		(end 139.409424 -94.937834)
		(width 0.0889)
		(layer "In9.Cu")
		(net "P3E_CPU1_PE3_MP_RXP<4>")
	)
	(arc
		(start 130.291078 -96.814386)
		(mid 130.304502 -97.188841)
		(end 130.00228 -97.410524)
		(width 0.0889)
		(layer "In9.Cu")
		(net "P3E_CPU1_PE3_MP_RXP<4>")
	)
	(arc
		(start 133.890004 -93.747336)
		(mid 133.683 -93.536472)
		(end 133.399784 -93.452188)
		(width 0.0889)
		(layer "In9.Cu")
		(net "P3E_CPU1_PE3_MP_RXP<4>")
	)
	(arc
		(start 136.794494 -94.442534)
		(mid 136.50907 -94.526001)
		(end 136.300464 -94.737936)
		(width 0.0889)
		(layer "In9.Cu")
		(net "P3E_CPU1_PE3_MP_RXP<4>")
	)
	(arc
		(start 134.221728 -93.947234)
		(mid 134.030086 -93.890068)
		(end 133.890004 -93.747336)
		(width 0.0889)
		(layer "In9.Cu")
		(net "P3E_CPU1_PE3_MP_RXP<4>")
	)
	(arc
		(start 130.291078 -94.833186)
		(mid 130.344577 -95.033084)
		(end 130.291078 -95.232982)
		(width 0.0889)
		(layer "In9.Cu")
		(net "P3E_CPU1_PE3_MP_RXP<4>")
	)
	(arc
		(start 132.507736 -93.947234)
		(mid 132.334311 -93.901775)
		(end 132.19811 -93.785182)
		(width 0.0889)
		(layer "In9.Cu")
		(net "P3E_CPU1_PE3_MP_RXP<4>")
	)
	(arc
		(start 141.656562 -97.802192)
		(mid 141.729294 -97.518445)
		(end 141.66469 -97.232724)
		(width 0.0889)
		(layer "In9.Cu")
		(net "P3E_CPU1_PE3_MP_RXP<4>")
	)
	(arc
		(start 134.748524 -94.242636)
		(mid 134.537811 -94.029557)
		(end 134.249668 -93.947234)
		(width 0.0889)
		(layer "In9.Cu")
		(net "P3E_CPU1_PE3_MP_RXP<4>")
	)
	(arc
		(start 141.12367 -95.928434)
		(mid 141.114781 -95.928241)
		(end 141.10589 -95.92818)
		(width 0.0889)
		(layer "In9.Cu")
		(net "P3E_CPU1_PE3_MP_RXP<4>")
	)
	(arc
		(start 140.235178 -95.433134)
		(mid 140.041328 -95.376784)
		(end 139.899644 -95.232982)
		(width 0.0889)
		(layer "In9.Cu")
		(net "P3E_CPU1_PE3_MP_RXP<4>")
	)
	(arc
		(start 139.041124 -94.737936)
		(mid 138.832516 -94.526004)
		(end 138.547094 -94.442534)
		(width 0.0889)
		(layer "In9.Cu")
		(net "P3E_CPU1_PE3_MP_RXP<4>")
	)
	(arc
		(start 137.158984 -94.242636)
		(mid 137.02024 -94.384669)
		(end 136.830308 -94.442534)
		(width 0.0889)
		(layer "In9.Cu")
		(net "P3E_CPU1_PE3_MP_RXP<4>")
	)
	(arc
		(start 138.51128 -94.442534)
		(mid 138.321351 -94.384664)
		(end 138.182604 -94.242636)
		(width 0.0889)
		(layer "In9.Cu")
		(net "P3E_CPU1_PE3_MP_RXP<4>")
	)
	(arc
		(start 136.300464 -94.737936)
		(mid 136.16172 -94.879969)
		(end 135.971788 -94.937834)
		(width 0.0889)
		(layer "In9.Cu")
		(net "P3E_CPU1_PE3_MP_RXP<4>")
	)
	(arc
		(start 141.656562 -96.811592)
		(mid 141.661385 -96.801416)
		(end 141.665706 -96.791018)
		(width 0.0889)
		(layer "In9.Cu")
		(net "P3E_CPU1_PE3_MP_RXP<4>")
	)
	(segment
		(start 127.655828 -98.005138)
		(end 128.227328 -98.005138)
		(width 0.1143)
		(layer "F.Cu")
		(net "P3E_CPU1_PE3_MP_RXP<3>")
	)
	(via
		(at 128.227328 -98.005138)
		(size 0.508)
		(drill 0.254)
		(layers "F.Cu" "B.Cu")
		(net "P3E_CPU1_PE3_MP_RXP<3>")
	)
	(segment
		(start 51.893216 -50.18659)
		(end 57.364376 -58.393076)
		(width 0.1143)
		(layer "In9.Cu")
		(net "P3E_CPU1_PE3_MP_RXP<3>")
	)
	(segment
		(start 68.354448 -111.842042)
		(end 68.48221 -111.816388)
		(width 0.1143)
		(layer "In9.Cu")
		(net "P3E_CPU1_PE3_MP_RXP<3>")
	)
	(segment
		(start 69.09054 -112.33277)
		(end 69.25437 -112.29975)
		(width 0.1143)
		(layer "In9.Cu")
		(net "P3E_CPU1_PE3_MP_RXP<3>")
	)
	(segment
		(start 139.745212 -108.011976)
		(end 142.51432 -105.242868)
		(width 0.1143)
		(layer "In9.Cu")
		(net "P3E_CPU1_PE3_MP_RXP<3>")
	)
	(segment
		(start 142.56512 -97.090484)
		(end 142.464028 -96.989392)
		(width 0.0889)
		(layer "In9.Cu")
		(net "P3E_CPU1_PE3_MP_RXP<3>")
	)
	(segment
		(start 31.365952 -42.576242)
		(end 33.870392 -41.329102)
		(width 0.1143)
		(layer "In9.Cu")
		(net "P3E_CPU1_PE3_MP_RXP<3>")
	)
	(segment
		(start 142.56512 -100.094034)
		(end 142.56512 -99.778566)
		(width 0.0889)
		(layer "In9.Cu")
		(net "P3E_CPU1_PE3_MP_RXP<3>")
	)
	(segment
		(start 141.979142 -95.737934)
		(end 141.94155 -95.647002)
		(width 0.0889)
		(layer "In9.Cu")
		(net "P3E_CPU1_PE3_MP_RXP<3>")
	)
	(segment
		(start 142.491206 -99.526852)
		(end 142.56512 -99.452938)
		(width 0.0889)
		(layer "In9.Cu")
		(net "P3E_CPU1_PE3_MP_RXP<3>")
	)
	(segment
		(start 127.855472 -98.152712)
		(end 127.934212 -98.174048)
		(width 0.0889)
		(layer "In9.Cu")
		(net "P3E_CPU1_PE3_MP_RXP<3>")
	)
	(segment
		(start 142.56512 -99.452938)
		(end 142.56512 -99.262692)
		(width 0.0889)
		(layer "In9.Cu")
		(net "P3E_CPU1_PE3_MP_RXP<3>")
	)
	(segment
		(start 142.478506 -96.257872)
		(end 142.56512 -96.171258)
		(width 0.0889)
		(layer "In9.Cu")
		(net "P3E_CPU1_PE3_MP_RXP<3>")
	)
	(segment
		(start 59.378088 -103.47833)
		(end 62.234826 -107.762548)
		(width 0.1143)
		(layer "In9.Cu")
		(net "P3E_CPU1_PE3_MP_RXP<3>")
	)
	(segment
		(start 142.47876 -99.176332)
		(end 142.47876 -98.998532)
		(width 0.0889)
		(layer "In9.Cu")
		(net "P3E_CPU1_PE3_MP_RXP<3>")
	)
	(segment
		(start 142.464028 -97.92716)
		(end 142.56512 -97.826068)
		(width 0.0889)
		(layer "In9.Cu")
		(net "P3E_CPU1_PE3_MP_RXP<3>")
	)
	(segment
		(start 69.572632 -112.654588)
		(end 70.299326 -113.13922)
		(width 0.1143)
		(layer "In9.Cu")
		(net "P3E_CPU1_PE3_MP_RXP<3>")
	)
	(segment
		(start 54.901084 -81.26984)
		(end 56.39689 -84.880196)
		(width 0.1143)
		(layer "In9.Cu")
		(net "P3E_CPU1_PE3_MP_RXP<3>")
	)
	(segment
		(start 132.53085 -92.156534)
		(end 132.519674 -92.156534)
		(width 0.0889)
		(layer "In9.Cu")
		(net "P3E_CPU1_PE3_MP_RXP<3>")
	)
	(segment
		(start 103.995982 -113.269268)
		(end 122.998992 -117.070124)
		(width 0.1143)
		(layer "In9.Cu")
		(net "P3E_CPU1_PE3_MP_RXP<3>")
	)
	(segment
		(start 122.998992 -117.070124)
		(end 132.608828 -115.14836)
		(width 0.1143)
		(layer "In9.Cu")
		(net "P3E_CPU1_PE3_MP_RXP<3>")
	)
	(segment
		(start 142.56512 -98.734372)
		(end 142.47876 -98.648012)
		(width 0.0889)
		(layer "In9.Cu")
		(net "P3E_CPU1_PE3_MP_RXP<3>")
	)
	(segment
		(start 127.880618 -97.214436)
		(end 127.886968 -97.225104)
		(width 0.0889)
		(layer "In9.Cu")
		(net "P3E_CPU1_PE3_MP_RXP<3>")
	)
	(segment
		(start -1.303528 -38.564058)
		(end 7.17042 -38.564058)
		(width 0.1143)
		(layer "In9.Cu")
		(net "P3E_CPU1_PE3_MP_RXP<3>")
	)
	(segment
		(start 139.583668 -108.011976)
		(end 139.745212 -108.011976)
		(width 0.1143)
		(layer "In9.Cu")
		(net "P3E_CPU1_PE3_MP_RXP<3>")
	)
	(segment
		(start 129.098802 -94.137988)
		(end 129.074672 -94.137988)
		(width 0.0889)
		(layer "In9.Cu")
		(net "P3E_CPU1_PE3_MP_RXP<3>")
	)
	(segment
		(start 142.464028 -96.989392)
		(end 142.464028 -96.811592)
		(width 0.0889)
		(layer "In9.Cu")
		(net "P3E_CPU1_PE3_MP_RXP<3>")
	)
	(segment
		(start 142.56512 -98.383852)
		(end 142.56512 -98.206052)
		(width 0.0889)
		(layer "In9.Cu")
		(net "P3E_CPU1_PE3_MP_RXP<3>")
	)
	(segment
		(start 129.962148 -93.642688)
		(end 129.929382 -93.642688)
		(width 0.0889)
		(layer "In9.Cu")
		(net "P3E_CPU1_PE3_MP_RXP<3>")
	)
	(segment
		(start 142.464028 -97.369376)
		(end 142.56512 -97.268284)
		(width 0.0889)
		(layer "In9.Cu")
		(net "P3E_CPU1_PE3_MP_RXP<3>")
	)
	(segment
		(start 94.350078 -113.466626)
		(end 98.679254 -114.332258)
		(width 0.1143)
		(layer "In9.Cu")
		(net "P3E_CPU1_PE3_MP_RXP<3>")
	)
	(segment
		(start 127.875792 -97.2058)
		(end 127.880618 -97.214436)
		(width 0.0889)
		(layer "In9.Cu")
		(net "P3E_CPU1_PE3_MP_RXP<3>")
	)
	(segment
		(start 142.143734 -95.806006)
		(end 141.979142 -95.737934)
		(width 0.0889)
		(layer "In9.Cu")
		(net "P3E_CPU1_PE3_MP_RXP<3>")
	)
	(segment
		(start 139.340844 -108.416344)
		(end 139.340844 -108.2548)
		(width 0.1143)
		(layer "In9.Cu")
		(net "P3E_CPU1_PE3_MP_RXP<3>")
	)
	(segment
		(start 141.039596 -95.346012)
		(end 141.003274 -95.258128)
		(width 0.0889)
		(layer "In9.Cu")
		(net "P3E_CPU1_PE3_MP_RXP<3>")
	)
	(segment
		(start 142.56512 -95.974916)
		(end 142.446248 -95.856044)
		(width 0.0889)
		(layer "In9.Cu")
		(net "P3E_CPU1_PE3_MP_RXP<3>")
	)
	(segment
		(start -1.7272 -37.842952)
		(end -1.7272 -38.140386)
		(width 0.1143)
		(layer "In9.Cu")
		(net "P3E_CPU1_PE3_MP_RXP<3>")
	)
	(segment
		(start 134.24789 -93.147134)
		(end 134.215124 -93.147134)
		(width 0.0889)
		(layer "In9.Cu")
		(net "P3E_CPU1_PE3_MP_RXP<3>")
	)
	(segment
		(start 141.471396 -95.452184)
		(end 141.291564 -95.378016)
		(width 0.0889)
		(layer "In9.Cu")
		(net "P3E_CPU1_PE3_MP_RXP<3>")
	)
	(segment
		(start 17.710658 -41.936416)
		(end 26.138124 -43.621706)
		(width 0.1143)
		(layer "In9.Cu")
		(net "P3E_CPU1_PE3_MP_RXP<3>")
	)
	(segment
		(start 142.51432 -100.166932)
		(end 142.51432 -100.144834)
		(width 0.0889)
		(layer "In9.Cu")
		(net "P3E_CPU1_PE3_MP_RXP<3>")
	)
	(segment
		(start 83.142074 -115.708176)
		(end 94.350078 -113.466626)
		(width 0.1143)
		(layer "In9.Cu")
		(net "P3E_CPU1_PE3_MP_RXP<3>")
	)
	(segment
		(start 68.48221 -111.816388)
		(end 68.768214 -112.006888)
		(width 0.1143)
		(layer "In9.Cu")
		(net "P3E_CPU1_PE3_MP_RXP<3>")
	)
	(segment
		(start 69.572632 -112.654334)
		(end 69.572632 -112.654588)
		(width 0.1143)
		(layer "In9.Cu")
		(net "P3E_CPU1_PE3_MP_RXP<3>")
	)
	(segment
		(start 142.56512 -99.262692)
		(end 142.47876 -99.176332)
		(width 0.0889)
		(layer "In9.Cu")
		(net "P3E_CPU1_PE3_MP_RXP<3>")
	)
	(segment
		(start 142.56512 -97.268284)
		(end 142.56512 -97.090484)
		(width 0.0889)
		(layer "In9.Cu")
		(net "P3E_CPU1_PE3_MP_RXP<3>")
	)
	(segment
		(start 142.47876 -98.998532)
		(end 142.56512 -98.912172)
		(width 0.0889)
		(layer "In9.Cu")
		(net "P3E_CPU1_PE3_MP_RXP<3>")
	)
	(segment
		(start 142.56512 -99.778566)
		(end 142.491206 -99.704652)
		(width 0.0889)
		(layer "In9.Cu")
		(net "P3E_CPU1_PE3_MP_RXP<3>")
	)
	(segment
		(start 142.56512 -96.7105)
		(end 142.56512 -96.522286)
		(width 0.0889)
		(layer "In9.Cu")
		(net "P3E_CPU1_PE3_MP_RXP<3>")
	)
	(segment
		(start 135.966708 -94.137988)
		(end 135.9408 -94.137988)
		(width 0.0889)
		(layer "In9.Cu")
		(net "P3E_CPU1_PE3_MP_RXP<3>")
	)
	(segment
		(start 142.56512 -97.826068)
		(end 142.56512 -97.648268)
		(width 0.0889)
		(layer "In9.Cu")
		(net "P3E_CPU1_PE3_MP_RXP<3>")
	)
	(segment
		(start 141.673834 -95.61195)
		(end 141.509242 -95.544132)
		(width 0.0889)
		(layer "In9.Cu")
		(net "P3E_CPU1_PE3_MP_RXP<3>")
	)
	(segment
		(start 57.364376 -58.393076)
		(end 57.60593 -59.604148)
		(width 0.1143)
		(layer "In9.Cu")
		(net "P3E_CPU1_PE3_MP_RXP<3>")
	)
	(segment
		(start 142.464028 -97.547176)
		(end 142.464028 -97.369376)
		(width 0.0889)
		(layer "In9.Cu")
		(net "P3E_CPU1_PE3_MP_RXP<3>")
	)
	(segment
		(start 141.003274 -95.258128)
		(end 140.787628 -95.168974)
		(width 0.0889)
		(layer "In9.Cu")
		(net "P3E_CPU1_PE3_MP_RXP<3>")
	)
	(segment
		(start 69.540374 -112.49025)
		(end 69.572632 -112.654334)
		(width 0.1143)
		(layer "In9.Cu")
		(net "P3E_CPU1_PE3_MP_RXP<3>")
	)
	(segment
		(start 142.56512 -98.206052)
		(end 142.464028 -98.10496)
		(width 0.0889)
		(layer "In9.Cu")
		(net "P3E_CPU1_PE3_MP_RXP<3>")
	)
	(segment
		(start 133.39318 -92.652088)
		(end 133.360414 -92.652088)
		(width 0.0889)
		(layer "In9.Cu")
		(net "P3E_CPU1_PE3_MP_RXP<3>")
	)
	(segment
		(start 135.11022 -93.642688)
		(end 135.077454 -93.642688)
		(width 0.0889)
		(layer "In9.Cu")
		(net "P3E_CPU1_PE3_MP_RXP<3>")
	)
	(segment
		(start 54.087014 -77.199236)
		(end 54.901084 -81.26984)
		(width 0.1143)
		(layer "In9.Cu")
		(net "P3E_CPU1_PE3_MP_RXP<3>")
	)
	(segment
		(start 142.47876 -98.470212)
		(end 142.56512 -98.383852)
		(width 0.0889)
		(layer "In9.Cu")
		(net "P3E_CPU1_PE3_MP_RXP<3>")
	)
	(segment
		(start 57.60593 -59.604148)
		(end 54.087014 -77.199236)
		(width 0.1143)
		(layer "In9.Cu")
		(net "P3E_CPU1_PE3_MP_RXP<3>")
	)
	(segment
		(start 26.138124 -43.621706)
		(end 31.365952 -42.576242)
		(width 0.1143)
		(layer "In9.Cu")
		(net "P3E_CPU1_PE3_MP_RXP<3>")
	)
	(segment
		(start 142.478506 -96.435672)
		(end 142.478506 -96.257872)
		(width 0.0889)
		(layer "In9.Cu")
		(net "P3E_CPU1_PE3_MP_RXP<3>")
	)
	(segment
		(start 142.56512 -96.171258)
		(end 142.56512 -95.974916)
		(width 0.0889)
		(layer "In9.Cu")
		(net "P3E_CPU1_PE3_MP_RXP<3>")
	)
	(segment
		(start 62.234826 -107.762548)
		(end 68.354448 -111.842042)
		(width 0.1143)
		(layer "In9.Cu")
		(net "P3E_CPU1_PE3_MP_RXP<3>")
	)
	(segment
		(start 140.787628 -95.168974)
		(end 140.593064 -94.833186)
		(width 0.0889)
		(layer "In9.Cu")
		(net "P3E_CPU1_PE3_MP_RXP<3>")
	)
	(segment
		(start 142.446248 -95.856044)
		(end 142.234412 -95.768414)
		(width 0.0889)
		(layer "In9.Cu")
		(net "P3E_CPU1_PE3_MP_RXP<3>")
	)
	(segment
		(start 142.491206 -99.704652)
		(end 142.491206 -99.526852)
		(width 0.0889)
		(layer "In9.Cu")
		(net "P3E_CPU1_PE3_MP_RXP<3>")
	)
	(segment
		(start 130.824478 -93.147134)
		(end 130.791712 -93.147134)
		(width 0.0889)
		(layer "In9.Cu")
		(net "P3E_CPU1_PE3_MP_RXP<3>")
	)
	(segment
		(start 138.5443 -93.642688)
		(end 138.511534 -93.642688)
		(width 0.0889)
		(layer "In9.Cu")
		(net "P3E_CPU1_PE3_MP_RXP<3>")
	)
	(segment
		(start 56.79694 -90.572336)
		(end 59.378088 -103.47833)
		(width 0.1143)
		(layer "In9.Cu")
		(net "P3E_CPU1_PE3_MP_RXP<3>")
	)
	(segment
		(start 7.17042 -38.564058)
		(end 8.24103 -38.954964)
		(width 0.1143)
		(layer "In9.Cu")
		(net "P3E_CPU1_PE3_MP_RXP<3>")
	)
	(segment
		(start 8.835898 -39.487856)
		(end 11.988038 -40.997378)
		(width 0.1143)
		(layer "In9.Cu")
		(net "P3E_CPU1_PE3_MP_RXP<3>")
	)
	(segment
		(start 136.830054 -93.642688)
		(end 136.797288 -93.642688)
		(width 0.0889)
		(layer "In9.Cu")
		(net "P3E_CPU1_PE3_MP_RXP<3>")
	)
	(segment
		(start 141.509242 -95.544132)
		(end 141.471396 -95.452184)
		(width 0.0889)
		(layer "In9.Cu")
		(net "P3E_CPU1_PE3_MP_RXP<3>")
	)
	(segment
		(start -1.594358 -37.71011)
		(end -1.7272 -37.842952)
		(width 0.1143)
		(layer "In9.Cu")
		(net "P3E_CPU1_PE3_MP_RXP<3>")
	)
	(segment
		(start 141.291564 -95.378016)
		(end 141.204188 -95.414084)
		(width 0.0889)
		(layer "In9.Cu")
		(net "P3E_CPU1_PE3_MP_RXP<3>")
	)
	(segment
		(start 137.68197 -93.147134)
		(end 137.659618 -93.147134)
		(width 0.0889)
		(layer "In9.Cu")
		(net "P3E_CPU1_PE3_MP_RXP<3>")
	)
	(segment
		(start 142.464028 -96.811592)
		(end 142.56512 -96.7105)
		(width 0.0889)
		(layer "In9.Cu")
		(net "P3E_CPU1_PE3_MP_RXP<3>")
	)
	(segment
		(start 142.464028 -98.10496)
		(end 142.464028 -97.92716)
		(width 0.0889)
		(layer "In9.Cu")
		(net "P3E_CPU1_PE3_MP_RXP<3>")
	)
	(segment
		(start 36.030662 -41.329102)
		(end 40.742616 -42.753788)
		(width 0.1143)
		(layer "In9.Cu")
		(net "P3E_CPU1_PE3_MP_RXP<3>")
	)
	(segment
		(start 142.51432 -100.144834)
		(end 142.56512 -100.094034)
		(width 0.0889)
		(layer "In9.Cu")
		(net "P3E_CPU1_PE3_MP_RXP<3>")
	)
	(segment
		(start 132.17652 -92.350844)
		(end 132.173218 -92.356686)
		(width 0.0889)
		(layer "In9.Cu")
		(net "P3E_CPU1_PE3_MP_RXP<3>")
	)
	(segment
		(start 139.340844 -108.2548)
		(end 139.583668 -108.011976)
		(width 0.1143)
		(layer "In9.Cu")
		(net "P3E_CPU1_PE3_MP_RXP<3>")
	)
	(segment
		(start 139.39901 -94.137734)
		(end 139.366244 -94.137734)
		(width 0.0889)
		(layer "In9.Cu")
		(net "P3E_CPU1_PE3_MP_RXP<3>")
	)
	(segment
		(start 69.25437 -112.29975)
		(end 69.540374 -112.49025)
		(width 0.1143)
		(layer "In9.Cu")
		(net "P3E_CPU1_PE3_MP_RXP<3>")
	)
	(segment
		(start 57.166002 -88.727026)
		(end 56.79694 -90.572336)
		(width 0.1143)
		(layer "In9.Cu")
		(net "P3E_CPU1_PE3_MP_RXP<3>")
	)
	(segment
		(start 142.56512 -97.648268)
		(end 142.464028 -97.547176)
		(width 0.0889)
		(layer "In9.Cu")
		(net "P3E_CPU1_PE3_MP_RXP<3>")
	)
	(segment
		(start 141.94155 -95.647002)
		(end 141.765274 -95.574104)
		(width 0.0889)
		(layer "In9.Cu")
		(net "P3E_CPU1_PE3_MP_RXP<3>")
	)
	(segment
		(start 127.934212 -98.174048)
		(end 128.227328 -98.005138)
		(width 0.0889)
		(layer "In9.Cu")
		(net "P3E_CPU1_PE3_MP_RXP<3>")
	)
	(segment
		(start -1.20015 -37.71011)
		(end -1.594358 -37.71011)
		(width 0.1143)
		(layer "In9.Cu")
		(net "P3E_CPU1_PE3_MP_RXP<3>")
	)
	(segment
		(start 141.204188 -95.414084)
		(end 141.039596 -95.346012)
		(width 0.0889)
		(layer "In9.Cu")
		(net "P3E_CPU1_PE3_MP_RXP<3>")
	)
	(segment
		(start 142.47876 -98.648012)
		(end 142.47876 -98.470212)
		(width 0.0889)
		(layer "In9.Cu")
		(net "P3E_CPU1_PE3_MP_RXP<3>")
	)
	(segment
		(start 131.679188 -92.652088)
		(end 131.646422 -92.652088)
		(width 0.0889)
		(layer "In9.Cu")
		(net "P3E_CPU1_PE3_MP_RXP<3>")
	)
	(segment
		(start 68.768214 -112.006888)
		(end 68.79336 -112.134904)
		(width 0.1143)
		(layer "In9.Cu")
		(net "P3E_CPU1_PE3_MP_RXP<3>")
	)
	(segment
		(start 56.39689 -84.880196)
		(end 57.166002 -88.727026)
		(width 0.1143)
		(layer "In9.Cu")
		(net "P3E_CPU1_PE3_MP_RXP<3>")
	)
	(segment
		(start 8.24103 -38.954964)
		(end 8.835898 -39.487856)
		(width 0.1143)
		(layer "In9.Cu")
		(net "P3E_CPU1_PE3_MP_RXP<3>")
	)
	(segment
		(start 127.880618 -96.223836)
		(end 127.886968 -96.234504)
		(width 0.0889)
		(layer "In9.Cu")
		(net "P3E_CPU1_PE3_MP_RXP<3>")
	)
	(segment
		(start 68.79336 -112.134904)
		(end 69.09054 -112.33277)
		(width 0.1143)
		(layer "In9.Cu")
		(net "P3E_CPU1_PE3_MP_RXP<3>")
	)
	(segment
		(start 70.299326 -113.13922)
		(end 83.142074 -115.708176)
		(width 0.1143)
		(layer "In9.Cu")
		(net "P3E_CPU1_PE3_MP_RXP<3>")
	)
	(segment
		(start 128.248918 -94.633288)
		(end 128.209294 -94.633288)
		(width 0.0889)
		(layer "In9.Cu")
		(net "P3E_CPU1_PE3_MP_RXP<3>")
	)
	(segment
		(start 11.988038 -40.997378)
		(end 17.710658 -41.936416)
		(width 0.1143)
		(layer "In9.Cu")
		(net "P3E_CPU1_PE3_MP_RXP<3>")
	)
	(segment
		(start 98.679254 -114.332258)
		(end 103.995982 -113.269268)
		(width 0.1143)
		(layer "In9.Cu")
		(net "P3E_CPU1_PE3_MP_RXP<3>")
	)
	(segment
		(start 142.51432 -105.242868)
		(end 142.51432 -100.166932)
		(width 0.1143)
		(layer "In9.Cu")
		(net "P3E_CPU1_PE3_MP_RXP<3>")
	)
	(segment
		(start 40.742616 -42.753788)
		(end 51.893216 -50.18659)
		(width 0.1143)
		(layer "In9.Cu")
		(net "P3E_CPU1_PE3_MP_RXP<3>")
	)
	(segment
		(start 33.870392 -41.329102)
		(end 36.030662 -41.329102)
		(width 0.1143)
		(layer "In9.Cu")
		(net "P3E_CPU1_PE3_MP_RXP<3>")
	)
	(segment
		(start 142.56512 -98.912172)
		(end 142.56512 -98.734372)
		(width 0.0889)
		(layer "In9.Cu")
		(net "P3E_CPU1_PE3_MP_RXP<3>")
	)
	(segment
		(start 142.56512 -96.522286)
		(end 142.478506 -96.435672)
		(width 0.0889)
		(layer "In9.Cu")
		(net "P3E_CPU1_PE3_MP_RXP<3>")
	)
	(segment
		(start 142.234412 -95.768414)
		(end 142.143734 -95.806006)
		(width 0.0889)
		(layer "In9.Cu")
		(net "P3E_CPU1_PE3_MP_RXP<3>")
	)
	(segment
		(start 127.875792 -96.2152)
		(end 127.880618 -96.223836)
		(width 0.0889)
		(layer "In9.Cu")
		(net "P3E_CPU1_PE3_MP_RXP<3>")
	)
	(segment
		(start 132.608828 -115.14836)
		(end 139.340844 -108.416344)
		(width 0.1143)
		(layer "In9.Cu")
		(net "P3E_CPU1_PE3_MP_RXP<3>")
	)
	(segment
		(start 140.264388 -94.633288)
		(end 140.228574 -94.633288)
		(width 0.0889)
		(layer "In9.Cu")
		(net "P3E_CPU1_PE3_MP_RXP<3>")
	)
	(segment
		(start -1.7272 -38.140386)
		(end -1.303528 -38.564058)
		(width 0.1143)
		(layer "In9.Cu")
		(net "P3E_CPU1_PE3_MP_RXP<3>")
	)
	(segment
		(start 141.765274 -95.574104)
		(end 141.673834 -95.61195)
		(width 0.0889)
		(layer "In9.Cu")
		(net "P3E_CPU1_PE3_MP_RXP<3>")
	)
	(arc
		(start 136.465564 -93.842586)
		(mid 136.254851 -94.055665)
		(end 135.966708 -94.137988)
		(width 0.0889)
		(layer "In9.Cu")
		(net "P3E_CPU1_PE3_MP_RXP<3>")
	)
	(arc
		(start 135.077454 -93.642688)
		(mid 134.79203 -93.559221)
		(end 134.583424 -93.347286)
		(width 0.0889)
		(layer "In9.Cu")
		(net "P3E_CPU1_PE3_MP_RXP<3>")
	)
	(arc
		(start 129.074672 -94.137988)
		(mid 128.880822 -94.194338)
		(end 128.739138 -94.33814)
		(width 0.0889)
		(layer "In9.Cu")
		(net "P3E_CPU1_PE3_MP_RXP<3>")
	)
	(arc
		(start 135.441944 -93.842586)
		(mid 135.301865 -93.69985)
		(end 135.11022 -93.642688)
		(width 0.0889)
		(layer "In9.Cu")
		(net "P3E_CPU1_PE3_MP_RXP<3>")
	)
	(arc
		(start 139.366244 -94.137734)
		(mid 139.083027 -94.053453)
		(end 138.876024 -93.842586)
		(width 0.0889)
		(layer "In9.Cu")
		(net "P3E_CPU1_PE3_MP_RXP<3>")
	)
	(arc
		(start 127.880618 -97.804986)
		(mid 127.828198 -97.975971)
		(end 127.855472 -98.152712)
		(width 0.0889)
		(layer "In9.Cu")
		(net "P3E_CPU1_PE3_MP_RXP<3>")
	)
	(arc
		(start 138.017504 -93.347286)
		(mid 137.875821 -93.203482)
		(end 137.68197 -93.147134)
		(width 0.0889)
		(layer "In9.Cu")
		(net "P3E_CPU1_PE3_MP_RXP<3>")
	)
	(arc
		(start 138.876024 -93.842586)
		(mid 138.735945 -93.69985)
		(end 138.5443 -93.642688)
		(width 0.0889)
		(layer "In9.Cu")
		(net "P3E_CPU1_PE3_MP_RXP<3>")
	)
	(arc
		(start 133.360414 -92.652088)
		(mid 133.07499 -92.568621)
		(end 132.866384 -92.356686)
		(width 0.0889)
		(layer "In9.Cu")
		(net "P3E_CPU1_PE3_MP_RXP<3>")
	)
	(arc
		(start 130.456178 -93.347286)
		(mid 130.24757 -93.559218)
		(end 129.962148 -93.642688)
		(width 0.0889)
		(layer "In9.Cu")
		(net "P3E_CPU1_PE3_MP_RXP<3>")
	)
	(arc
		(start 133.724904 -92.851986)
		(mid 133.584825 -92.70925)
		(end 133.39318 -92.652088)
		(width 0.0889)
		(layer "In9.Cu")
		(net "P3E_CPU1_PE3_MP_RXP<3>")
	)
	(arc
		(start 140.228574 -94.633288)
		(mid 139.94315 -94.549821)
		(end 139.734544 -94.337886)
		(width 0.0889)
		(layer "In9.Cu")
		(net "P3E_CPU1_PE3_MP_RXP<3>")
	)
	(arc
		(start 137.324084 -93.347286)
		(mid 137.115476 -93.559218)
		(end 136.830054 -93.642688)
		(width 0.0889)
		(layer "In9.Cu")
		(net "P3E_CPU1_PE3_MP_RXP<3>")
	)
	(arc
		(start 131.646422 -92.652088)
		(mid 131.45478 -92.709254)
		(end 131.314698 -92.851986)
		(width 0.0889)
		(layer "In9.Cu")
		(net "P3E_CPU1_PE3_MP_RXP<3>")
	)
	(arc
		(start 127.880618 -96.814386)
		(mid 127.827148 -97.009449)
		(end 127.875792 -97.2058)
		(width 0.0889)
		(layer "In9.Cu")
		(net "P3E_CPU1_PE3_MP_RXP<3>")
	)
	(arc
		(start 139.734544 -94.337886)
		(mid 139.592861 -94.194082)
		(end 139.39901 -94.137734)
		(width 0.0889)
		(layer "In9.Cu")
		(net "P3E_CPU1_PE3_MP_RXP<3>")
	)
	(arc
		(start 138.511534 -93.642688)
		(mid 138.22611 -93.559221)
		(end 138.017504 -93.347286)
		(width 0.0889)
		(layer "In9.Cu")
		(net "P3E_CPU1_PE3_MP_RXP<3>")
	)
	(arc
		(start 132.173218 -92.356686)
		(mid 131.96461 -92.568618)
		(end 131.679188 -92.652088)
		(width 0.0889)
		(layer "In9.Cu")
		(net "P3E_CPU1_PE3_MP_RXP<3>")
	)
	(arc
		(start 130.791712 -93.147134)
		(mid 130.597862 -93.203484)
		(end 130.456178 -93.347286)
		(width 0.0889)
		(layer "In9.Cu")
		(net "P3E_CPU1_PE3_MP_RXP<3>")
	)
	(arc
		(start 135.9408 -94.137988)
		(mid 135.652655 -94.055669)
		(end 135.441944 -93.842586)
		(width 0.0889)
		(layer "In9.Cu")
		(net "P3E_CPU1_PE3_MP_RXP<3>")
	)
	(arc
		(start 131.314698 -92.851986)
		(mid 131.107694 -93.06285)
		(end 130.824478 -93.147134)
		(width 0.0889)
		(layer "In9.Cu")
		(net "P3E_CPU1_PE3_MP_RXP<3>")
	)
	(arc
		(start 140.593064 -94.833186)
		(mid 140.45432 -94.691153)
		(end 140.264388 -94.633288)
		(width 0.0889)
		(layer "In9.Cu")
		(net "P3E_CPU1_PE3_MP_RXP<3>")
	)
	(arc
		(start 128.739138 -94.33814)
		(mid 128.532134 -94.549004)
		(end 128.248918 -94.633288)
		(width 0.0889)
		(layer "In9.Cu")
		(net "P3E_CPU1_PE3_MP_RXP<3>")
	)
	(arc
		(start 132.519674 -92.156534)
		(mid 132.322513 -92.208493)
		(end 132.17652 -92.350844)
		(width 0.0889)
		(layer "In9.Cu")
		(net "P3E_CPU1_PE3_MP_RXP<3>")
	)
	(arc
		(start 134.583424 -93.347286)
		(mid 134.441741 -93.203482)
		(end 134.24789 -93.147134)
		(width 0.0889)
		(layer "In9.Cu")
		(net "P3E_CPU1_PE3_MP_RXP<3>")
	)
	(arc
		(start 136.797288 -93.642688)
		(mid 136.605646 -93.699854)
		(end 136.465564 -93.842586)
		(width 0.0889)
		(layer "In9.Cu")
		(net "P3E_CPU1_PE3_MP_RXP<3>")
	)
	(arc
		(start 128.209294 -94.633288)
		(mid 128.019365 -94.691158)
		(end 127.880618 -94.833186)
		(width 0.0889)
		(layer "In9.Cu")
		(net "P3E_CPU1_PE3_MP_RXP<3>")
	)
	(arc
		(start 129.929382 -93.642688)
		(mid 129.73774 -93.699854)
		(end 129.597658 -93.842586)
		(width 0.0889)
		(layer "In9.Cu")
		(net "P3E_CPU1_PE3_MP_RXP<3>")
	)
	(arc
		(start 127.880618 -94.833186)
		(mid 127.827119 -95.033084)
		(end 127.880618 -95.232982)
		(width 0.0889)
		(layer "In9.Cu")
		(net "P3E_CPU1_PE3_MP_RXP<3>")
	)
	(arc
		(start 127.880618 -95.232982)
		(mid 127.959749 -95.528384)
		(end 127.880618 -95.823786)
		(width 0.0889)
		(layer "In9.Cu")
		(net "P3E_CPU1_PE3_MP_RXP<3>")
	)
	(arc
		(start 134.215124 -93.147134)
		(mid 133.931907 -93.062853)
		(end 133.724904 -92.851986)
		(width 0.0889)
		(layer "In9.Cu")
		(net "P3E_CPU1_PE3_MP_RXP<3>")
	)
	(arc
		(start 127.886968 -96.234504)
		(mid 127.959766 -96.525267)
		(end 127.880618 -96.814386)
		(width 0.0889)
		(layer "In9.Cu")
		(net "P3E_CPU1_PE3_MP_RXP<3>")
	)
	(arc
		(start 137.659618 -93.147134)
		(mid 137.465768 -93.203484)
		(end 137.324084 -93.347286)
		(width 0.0889)
		(layer "In9.Cu")
		(net "P3E_CPU1_PE3_MP_RXP<3>")
	)
	(arc
		(start 127.886968 -97.225104)
		(mid 127.959766 -97.515867)
		(end 127.880618 -97.804986)
		(width 0.0889)
		(layer "In9.Cu")
		(net "P3E_CPU1_PE3_MP_RXP<3>")
	)
	(arc
		(start 129.597658 -93.842586)
		(mid 129.386945 -94.055665)
		(end 129.098802 -94.137988)
		(width 0.0889)
		(layer "In9.Cu")
		(net "P3E_CPU1_PE3_MP_RXP<3>")
	)
	(arc
		(start 127.880618 -95.823786)
		(mid 127.827148 -96.018849)
		(end 127.875792 -96.2152)
		(width 0.0889)
		(layer "In9.Cu")
		(net "P3E_CPU1_PE3_MP_RXP<3>")
	)
	(arc
		(start 132.866384 -92.356686)
		(mid 132.724701 -92.212882)
		(end 132.53085 -92.156534)
		(width 0.0889)
		(layer "In9.Cu")
		(net "P3E_CPU1_PE3_MP_RXP<3>")
	)
	(segment
		(start 128.514348 -99.490784)
		(end 129.085848 -99.490784)
		(width 0.1143)
		(layer "F.Cu")
		(net "P3E_CPU1_PE3_MP_RXP<2>")
	)
	(via
		(at 129.085848 -99.490784)
		(size 0.508)
		(drill 0.254)
		(layers "F.Cu" "B.Cu")
		(net "P3E_CPU1_PE3_MP_RXP<2>")
	)
	(segment
		(start 51.153568 -50.879502)
		(end 40.150542 -43.543982)
		(width 0.1143)
		(layer "In9.Cu")
		(net "P3E_CPU1_PE3_MP_RXP<2>")
	)
	(segment
		(start 98.412046 -115.6843)
		(end 93.385894 -114.678714)
		(width 0.1143)
		(layer "In9.Cu")
		(net "P3E_CPU1_PE3_MP_RXP<2>")
	)
	(segment
		(start 135.938768 -92.956634)
		(end 135.96874 -92.956634)
		(width 0.0889)
		(layer "In9.Cu")
		(net "P3E_CPU1_PE3_MP_RXP<2>")
	)
	(segment
		(start 10.434828 -41.852088)
		(end 5.773166 -41.08831)
		(width 0.1143)
		(layer "In9.Cu")
		(net "P3E_CPU1_PE3_MP_RXP<2>")
	)
	(segment
		(start 5.439664 -40.944038)
		(end 4.9911 -40.496998)
		(width 0.1143)
		(layer "In9.Cu")
		(net "P3E_CPU1_PE3_MP_RXP<2>")
	)
	(segment
		(start 143.53032 -105.752138)
		(end 133.304534 -115.977924)
		(width 0.1143)
		(layer "In9.Cu")
		(net "P3E_CPU1_PE3_MP_RXP<2>")
	)
	(segment
		(start 25.72004 -44.650914)
		(end 13.997432 -42.306748)
		(width 0.1143)
		(layer "In9.Cu")
		(net "P3E_CPU1_PE3_MP_RXP<2>")
	)
	(segment
		(start 13.997432 -42.306748)
		(end 10.758932 -41.776142)
		(width 0.1143)
		(layer "In9.Cu")
		(net "P3E_CPU1_PE3_MP_RXP<2>")
	)
	(segment
		(start 141.094206 -93.947234)
		(end 141.10335 -93.947488)
		(width 0.0889)
		(layer "In9.Cu")
		(net "P3E_CPU1_PE3_MP_RXP<2>")
	)
	(segment
		(start 139.370308 -92.956634)
		(end 139.406122 -92.956634)
		(width 0.0889)
		(layer "In9.Cu")
		(net "P3E_CPU1_PE3_MP_RXP<2>")
	)
	(segment
		(start 56.00446 -58.155332)
		(end 51.153568 -50.879502)
		(width 0.1143)
		(layer "In9.Cu")
		(net "P3E_CPU1_PE3_MP_RXP<2>")
	)
	(segment
		(start 134.221728 -91.966034)
		(end 134.254494 -91.966034)
		(width 0.0889)
		(layer "In9.Cu")
		(net "P3E_CPU1_PE3_MP_RXP<2>")
	)
	(segment
		(start 126.850648 -97.225104)
		(end 126.856998 -97.214436)
		(width 0.0889)
		(layer "In9.Cu")
		(net "P3E_CPU1_PE3_MP_RXP<2>")
	)
	(segment
		(start 53.036978 -77.596238)
		(end 54.417976 -70.655688)
		(width 0.1143)
		(layer "In9.Cu")
		(net "P3E_CPU1_PE3_MP_RXP<2>")
	)
	(segment
		(start 141.10335 -93.947488)
		(end 141.12367 -93.947488)
		(width 0.0889)
		(layer "In9.Cu")
		(net "P3E_CPU1_PE3_MP_RXP<2>")
	)
	(segment
		(start 141.962886 -94.44228)
		(end 142.465552 -94.44228)
		(width 0.0889)
		(layer "In9.Cu")
		(net "P3E_CPU1_PE3_MP_RXP<2>")
	)
	(segment
		(start 140.228828 -93.451934)
		(end 140.268452 -93.451934)
		(width 0.0889)
		(layer "In9.Cu")
		(net "P3E_CPU1_PE3_MP_RXP<2>")
	)
	(segment
		(start 126.856998 -97.214436)
		(end 126.861824 -97.2058)
		(width 0.0889)
		(layer "In9.Cu")
		(net "P3E_CPU1_PE3_MP_RXP<2>")
	)
	(segment
		(start 55.286656 -86.763606)
		(end 54.691026 -85.862922)
		(width 0.1143)
		(layer "In9.Cu")
		(net "P3E_CPU1_PE3_MP_RXP<2>")
	)
	(segment
		(start 54.691026 -85.862922)
		(end 53.036978 -77.596238)
		(width 0.1143)
		(layer "In9.Cu")
		(net "P3E_CPU1_PE3_MP_RXP<2>")
	)
	(segment
		(start 4.500118 -39.710106)
		(end 4.499864 -39.710106)
		(width 0.1143)
		(layer "In9.Cu")
		(net "P3E_CPU1_PE3_MP_RXP<2>")
	)
	(segment
		(start 69.957696 -114.04981)
		(end 61.424566 -108.36148)
		(width 0.1143)
		(layer "In9.Cu")
		(net "P3E_CPU1_PE3_MP_RXP<2>")
	)
	(segment
		(start 130.785108 -91.966034)
		(end 130.817874 -91.966034)
		(width 0.0889)
		(layer "In9.Cu")
		(net "P3E_CPU1_PE3_MP_RXP<2>")
	)
	(segment
		(start 143.53032 -98.165158)
		(end 143.53032 -98.187256)
		(width 0.0889)
		(layer "In9.Cu")
		(net "P3E_CPU1_PE3_MP_RXP<2>")
	)
	(segment
		(start 126.850648 -96.234504)
		(end 126.856998 -96.223836)
		(width 0.0889)
		(layer "In9.Cu")
		(net "P3E_CPU1_PE3_MP_RXP<2>")
	)
	(segment
		(start 34.106612 -42.256202)
		(end 31.795212 -43.436286)
		(width 0.1143)
		(layer "In9.Cu")
		(net "P3E_CPU1_PE3_MP_RXP<2>")
	)
	(segment
		(start 58.235342 -103.577136)
		(end 55.635398 -90.58275)
		(width 0.1143)
		(layer "In9.Cu")
		(net "P3E_CPU1_PE3_MP_RXP<2>")
	)
	(segment
		(start 5.773166 -41.08831)
		(end 5.439664 -40.944038)
		(width 0.1143)
		(layer "In9.Cu")
		(net "P3E_CPU1_PE3_MP_RXP<2>")
	)
	(segment
		(start 104.846628 -114.398044)
		(end 98.412046 -115.6843)
		(width 0.1143)
		(layer "In9.Cu")
		(net "P3E_CPU1_PE3_MP_RXP<2>")
	)
	(segment
		(start 93.385894 -114.678714)
		(end 83.243674 -116.706904)
		(width 0.1143)
		(layer "In9.Cu")
		(net "P3E_CPU1_PE3_MP_RXP<2>")
	)
	(segment
		(start 142.465552 -94.44228)
		(end 143.47952 -95.456248)
		(width 0.0889)
		(layer "In9.Cu")
		(net "P3E_CPU1_PE3_MP_RXP<2>")
	)
	(segment
		(start 136.790684 -92.461588)
		(end 136.82345 -92.461588)
		(width 0.0889)
		(layer "In9.Cu")
		(net "P3E_CPU1_PE3_MP_RXP<2>")
	)
	(segment
		(start 55.84952 -89.529666)
		(end 55.286656 -86.763606)
		(width 0.1143)
		(layer "In9.Cu")
		(net "P3E_CPU1_PE3_MP_RXP<2>")
	)
	(segment
		(start 143.47952 -98.114358)
		(end 143.53032 -98.165158)
		(width 0.0889)
		(layer "In9.Cu")
		(net "P3E_CPU1_PE3_MP_RXP<2>")
	)
	(segment
		(start 137.653014 -91.966034)
		(end 137.688574 -91.966034)
		(width 0.0889)
		(layer "In9.Cu")
		(net "P3E_CPU1_PE3_MP_RXP<2>")
	)
	(segment
		(start 129.922778 -92.461588)
		(end 129.955544 -92.461588)
		(width 0.0889)
		(layer "In9.Cu")
		(net "P3E_CPU1_PE3_MP_RXP<2>")
	)
	(segment
		(start 143.47952 -95.456248)
		(end 143.47952 -98.114358)
		(width 0.0889)
		(layer "In9.Cu")
		(net "P3E_CPU1_PE3_MP_RXP<2>")
	)
	(segment
		(start 126.856998 -98.205036)
		(end 126.861824 -98.1964)
		(width 0.0889)
		(layer "In9.Cu")
		(net "P3E_CPU1_PE3_MP_RXP<2>")
	)
	(segment
		(start 127.390398 -99.090734)
		(end 127.347218 -99.090734)
		(width 0.0889)
		(layer "In9.Cu")
		(net "P3E_CPU1_PE3_MP_RXP<2>")
	)
	(segment
		(start 133.304534 -115.977924)
		(end 123.025154 -118.032784)
		(width 0.1143)
		(layer "In9.Cu")
		(net "P3E_CPU1_PE3_MP_RXP<2>")
	)
	(segment
		(start 138.518138 -92.461588)
		(end 138.550904 -92.461588)
		(width 0.0889)
		(layer "In9.Cu")
		(net "P3E_CPU1_PE3_MP_RXP<2>")
	)
	(segment
		(start 129.068068 -92.956634)
		(end 129.100834 -92.956634)
		(width 0.0889)
		(layer "In9.Cu")
		(net "P3E_CPU1_PE3_MP_RXP<2>")
	)
	(segment
		(start 129.097024 -99.090734)
		(end 129.064258 -99.090734)
		(width 0.0889)
		(layer "In9.Cu")
		(net "P3E_CPU1_PE3_MP_RXP<2>")
	)
	(segment
		(start 129.378964 -99.659948)
		(end 129.457704 -99.638612)
		(width 0.0889)
		(layer "In9.Cu")
		(net "P3E_CPU1_PE3_MP_RXP<2>")
	)
	(segment
		(start 129.085848 -99.490784)
		(end 129.378964 -99.659948)
		(width 0.0889)
		(layer "In9.Cu")
		(net "P3E_CPU1_PE3_MP_RXP<2>")
	)
	(segment
		(start 4.9911 -40.201088)
		(end 4.500118 -39.710106)
		(width 0.1143)
		(layer "In9.Cu")
		(net "P3E_CPU1_PE3_MP_RXP<2>")
	)
	(segment
		(start 128.242314 -98.595688)
		(end 128.212342 -98.595688)
		(width 0.0889)
		(layer "In9.Cu")
		(net "P3E_CPU1_PE3_MP_RXP<2>")
	)
	(segment
		(start 132.004562 -91.276678)
		(end 132.007864 -91.270836)
		(width 0.0889)
		(layer "In9.Cu")
		(net "P3E_CPU1_PE3_MP_RXP<2>")
	)
	(segment
		(start 123.025154 -118.032784)
		(end 104.846628 -114.398044)
		(width 0.1143)
		(layer "In9.Cu")
		(net "P3E_CPU1_PE3_MP_RXP<2>")
	)
	(segment
		(start 10.758932 -41.776142)
		(end 10.434828 -41.852088)
		(width 0.1143)
		(layer "In9.Cu")
		(net "P3E_CPU1_PE3_MP_RXP<2>")
	)
	(segment
		(start 31.795212 -43.436286)
		(end 25.72004 -44.650914)
		(width 0.1143)
		(layer "In9.Cu")
		(net "P3E_CPU1_PE3_MP_RXP<2>")
	)
	(segment
		(start 128.205738 -93.452188)
		(end 128.238504 -93.452188)
		(width 0.0889)
		(layer "In9.Cu")
		(net "P3E_CPU1_PE3_MP_RXP<2>")
	)
	(segment
		(start 143.53032 -98.187256)
		(end 143.53032 -105.752138)
		(width 0.1143)
		(layer "In9.Cu")
		(net "P3E_CPU1_PE3_MP_RXP<2>")
	)
	(segment
		(start 55.635144 -90.582496)
		(end 55.84952 -89.529666)
		(width 0.1143)
		(layer "In9.Cu")
		(net "P3E_CPU1_PE3_MP_RXP<2>")
	)
	(segment
		(start 135.084058 -92.461588)
		(end 135.116824 -92.461588)
		(width 0.0889)
		(layer "In9.Cu")
		(net "P3E_CPU1_PE3_MP_RXP<2>")
	)
	(segment
		(start 126.850648 -98.215704)
		(end 126.856998 -98.205036)
		(width 0.0889)
		(layer "In9.Cu")
		(net "P3E_CPU1_PE3_MP_RXP<2>")
	)
	(segment
		(start 4.9911 -40.496998)
		(end 4.9911 -40.201088)
		(width 0.1143)
		(layer "In9.Cu")
		(net "P3E_CPU1_PE3_MP_RXP<2>")
	)
	(segment
		(start 126.856998 -96.223836)
		(end 126.861824 -96.2152)
		(width 0.0889)
		(layer "In9.Cu")
		(net "P3E_CPU1_PE3_MP_RXP<2>")
	)
	(segment
		(start 54.417976 -70.655688)
		(end 54.417976 -66.096642)
		(width 0.1143)
		(layer "In9.Cu")
		(net "P3E_CPU1_PE3_MP_RXP<2>")
	)
	(segment
		(start 83.243674 -116.706904)
		(end 69.957696 -114.04981)
		(width 0.1143)
		(layer "In9.Cu")
		(net "P3E_CPU1_PE3_MP_RXP<2>")
	)
	(segment
		(start 133.367018 -91.470988)
		(end 133.399784 -91.470988)
		(width 0.0889)
		(layer "In9.Cu")
		(net "P3E_CPU1_PE3_MP_RXP<2>")
	)
	(segment
		(start 126.856998 -94.833186)
		(end 126.850648 -94.822518)
		(width 0.0889)
		(layer "In9.Cu")
		(net "P3E_CPU1_PE3_MP_RXP<2>")
	)
	(segment
		(start 127.355854 -93.947234)
		(end 127.383794 -93.947234)
		(width 0.0889)
		(layer "In9.Cu")
		(net "P3E_CPU1_PE3_MP_RXP<2>")
	)
	(segment
		(start 54.417976 -66.096642)
		(end 56.00446 -58.155332)
		(width 0.1143)
		(layer "In9.Cu")
		(net "P3E_CPU1_PE3_MP_RXP<2>")
	)
	(segment
		(start 55.635398 -90.58275)
		(end 55.635144 -90.582496)
		(width 0.1143)
		(layer "In9.Cu")
		(net "P3E_CPU1_PE3_MP_RXP<2>")
	)
	(segment
		(start 35.892994 -42.256202)
		(end 34.106612 -42.256202)
		(width 0.1143)
		(layer "In9.Cu")
		(net "P3E_CPU1_PE3_MP_RXP<2>")
	)
	(segment
		(start 61.424566 -108.36148)
		(end 58.235342 -103.577136)
		(width 0.1143)
		(layer "In9.Cu")
		(net "P3E_CPU1_PE3_MP_RXP<2>")
	)
	(segment
		(start 131.639818 -91.470988)
		(end 131.661408 -91.470988)
		(width 0.0889)
		(layer "In9.Cu")
		(net "P3E_CPU1_PE3_MP_RXP<2>")
	)
	(segment
		(start 40.150542 -43.543982)
		(end 35.892994 -42.256202)
		(width 0.1143)
		(layer "In9.Cu")
		(net "P3E_CPU1_PE3_MP_RXP<2>")
	)
	(arc
		(start 126.856998 -95.823786)
		(mid 126.777867 -95.528384)
		(end 126.856998 -95.232982)
		(width 0.0889)
		(layer "In9.Cu")
		(net "P3E_CPU1_PE3_MP_RXP<2>")
	)
	(arc
		(start 140.268452 -93.451934)
		(mid 140.551669 -93.536215)
		(end 140.758672 -93.747082)
		(width 0.0889)
		(layer "In9.Cu")
		(net "P3E_CPU1_PE3_MP_RXP<2>")
	)
	(arc
		(start 126.861824 -96.2152)
		(mid 126.910579 -96.018848)
		(end 126.856998 -95.823786)
		(width 0.0889)
		(layer "In9.Cu")
		(net "P3E_CPU1_PE3_MP_RXP<2>")
	)
	(arc
		(start 127.880618 -98.795586)
		(mid 127.673614 -99.00645)
		(end 127.390398 -99.090734)
		(width 0.0889)
		(layer "In9.Cu")
		(net "P3E_CPU1_PE3_MP_RXP<2>")
	)
	(arc
		(start 138.550904 -92.461588)
		(mid 138.834121 -92.545869)
		(end 139.041124 -92.756736)
		(width 0.0889)
		(layer "In9.Cu")
		(net "P3E_CPU1_PE3_MP_RXP<2>")
	)
	(arc
		(start 128.574038 -93.252036)
		(mid 128.782646 -93.040104)
		(end 129.068068 -92.956634)
		(width 0.0889)
		(layer "In9.Cu")
		(net "P3E_CPU1_PE3_MP_RXP<2>")
	)
	(arc
		(start 139.406122 -92.956634)
		(mid 139.691546 -93.040101)
		(end 139.900152 -93.252036)
		(width 0.0889)
		(layer "In9.Cu")
		(net "P3E_CPU1_PE3_MP_RXP<2>")
	)
	(arc
		(start 132.502148 -90.975434)
		(mid 132.807587 -91.050075)
		(end 133.031484 -91.270836)
		(width 0.0889)
		(layer "In9.Cu")
		(net "P3E_CPU1_PE3_MP_RXP<2>")
	)
	(arc
		(start 133.399784 -91.470988)
		(mid 133.683001 -91.555269)
		(end 133.890004 -91.766136)
		(width 0.0889)
		(layer "In9.Cu")
		(net "P3E_CPU1_PE3_MP_RXP<2>")
	)
	(arc
		(start 141.12367 -93.947488)
		(mid 141.408717 -94.031016)
		(end 141.617192 -94.242636)
		(width 0.0889)
		(layer "In9.Cu")
		(net "P3E_CPU1_PE3_MP_RXP<2>")
	)
	(arc
		(start 131.149598 -91.766136)
		(mid 131.356602 -91.555272)
		(end 131.639818 -91.470988)
		(width 0.0889)
		(layer "In9.Cu")
		(net "P3E_CPU1_PE3_MP_RXP<2>")
	)
	(arc
		(start 135.116824 -92.461588)
		(mid 135.400041 -92.545869)
		(end 135.607044 -92.756736)
		(width 0.0889)
		(layer "In9.Cu")
		(net "P3E_CPU1_PE3_MP_RXP<2>")
	)
	(arc
		(start 136.82345 -92.461588)
		(mid 137.0173 -92.405238)
		(end 137.158984 -92.261436)
		(width 0.0889)
		(layer "In9.Cu")
		(net "P3E_CPU1_PE3_MP_RXP<2>")
	)
	(arc
		(start 140.758672 -93.747082)
		(mid 140.900355 -93.890886)
		(end 141.094206 -93.947234)
		(width 0.0889)
		(layer "In9.Cu")
		(net "P3E_CPU1_PE3_MP_RXP<2>")
	)
	(arc
		(start 129.432558 -92.756736)
		(mid 129.639562 -92.545872)
		(end 129.922778 -92.461588)
		(width 0.0889)
		(layer "In9.Cu")
		(net "P3E_CPU1_PE3_MP_RXP<2>")
	)
	(arc
		(start 133.890004 -91.766136)
		(mid 134.030083 -91.908872)
		(end 134.221728 -91.966034)
		(width 0.0889)
		(layer "In9.Cu")
		(net "P3E_CPU1_PE3_MP_RXP<2>")
	)
	(arc
		(start 128.574038 -98.795586)
		(mid 128.433959 -98.65285)
		(end 128.242314 -98.595688)
		(width 0.0889)
		(layer "In9.Cu")
		(net "P3E_CPU1_PE3_MP_RXP<2>")
	)
	(arc
		(start 127.383794 -93.947234)
		(mid 127.575436 -93.890068)
		(end 127.715518 -93.747336)
		(width 0.0889)
		(layer "In9.Cu")
		(net "P3E_CPU1_PE3_MP_RXP<2>")
	)
	(arc
		(start 129.955544 -92.461588)
		(mid 130.149394 -92.405238)
		(end 130.291078 -92.261436)
		(width 0.0889)
		(layer "In9.Cu")
		(net "P3E_CPU1_PE3_MP_RXP<2>")
	)
	(arc
		(start 127.715518 -93.747336)
		(mid 127.922522 -93.536472)
		(end 128.205738 -93.452188)
		(width 0.0889)
		(layer "In9.Cu")
		(net "P3E_CPU1_PE3_MP_RXP<2>")
	)
	(arc
		(start 134.748524 -92.261436)
		(mid 134.890207 -92.40524)
		(end 135.084058 -92.461588)
		(width 0.0889)
		(layer "In9.Cu")
		(net "P3E_CPU1_PE3_MP_RXP<2>")
	)
	(arc
		(start 126.850648 -94.822518)
		(mid 126.856825 -94.242586)
		(end 127.355854 -93.947234)
		(width 0.0889)
		(layer "In9.Cu")
		(net "P3E_CPU1_PE3_MP_RXP<2>")
	)
	(arc
		(start 130.291078 -92.261436)
		(mid 130.499686 -92.049504)
		(end 130.785108 -91.966034)
		(width 0.0889)
		(layer "In9.Cu")
		(net "P3E_CPU1_PE3_MP_RXP<2>")
	)
	(arc
		(start 133.031484 -91.270836)
		(mid 133.173167 -91.41464)
		(end 133.367018 -91.470988)
		(width 0.0889)
		(layer "In9.Cu")
		(net "P3E_CPU1_PE3_MP_RXP<2>")
	)
	(arc
		(start 135.96874 -92.956634)
		(mid 136.160382 -92.899468)
		(end 136.300464 -92.756736)
		(width 0.0889)
		(layer "In9.Cu")
		(net "P3E_CPU1_PE3_MP_RXP<2>")
	)
	(arc
		(start 126.861824 -97.2058)
		(mid 126.910579 -97.009448)
		(end 126.856998 -96.814386)
		(width 0.0889)
		(layer "In9.Cu")
		(net "P3E_CPU1_PE3_MP_RXP<2>")
	)
	(arc
		(start 137.688574 -91.966034)
		(mid 137.973998 -92.049501)
		(end 138.182604 -92.261436)
		(width 0.0889)
		(layer "In9.Cu")
		(net "P3E_CPU1_PE3_MP_RXP<2>")
	)
	(arc
		(start 129.457704 -99.638612)
		(mid 129.420064 -99.270673)
		(end 129.097024 -99.090734)
		(width 0.0889)
		(layer "In9.Cu")
		(net "P3E_CPU1_PE3_MP_RXP<2>")
	)
	(arc
		(start 141.617192 -94.242636)
		(mid 141.763275 -94.388812)
		(end 141.962886 -94.44228)
		(width 0.0889)
		(layer "In9.Cu")
		(net "P3E_CPU1_PE3_MP_RXP<2>")
	)
	(arc
		(start 138.182604 -92.261436)
		(mid 138.324287 -92.40524)
		(end 138.518138 -92.461588)
		(width 0.0889)
		(layer "In9.Cu")
		(net "P3E_CPU1_PE3_MP_RXP<2>")
	)
	(arc
		(start 127.347218 -99.090734)
		(mid 126.854828 -98.791801)
		(end 126.850648 -98.215704)
		(width 0.0889)
		(layer "In9.Cu")
		(net "P3E_CPU1_PE3_MP_RXP<2>")
	)
	(arc
		(start 135.607044 -92.756736)
		(mid 135.747123 -92.899472)
		(end 135.938768 -92.956634)
		(width 0.0889)
		(layer "In9.Cu")
		(net "P3E_CPU1_PE3_MP_RXP<2>")
	)
	(arc
		(start 126.856998 -97.804986)
		(mid 126.777776 -97.515868)
		(end 126.850648 -97.225104)
		(width 0.0889)
		(layer "In9.Cu")
		(net "P3E_CPU1_PE3_MP_RXP<2>")
	)
	(arc
		(start 134.254494 -91.966034)
		(mid 134.539918 -92.049501)
		(end 134.748524 -92.261436)
		(width 0.0889)
		(layer "In9.Cu")
		(net "P3E_CPU1_PE3_MP_RXP<2>")
	)
	(arc
		(start 128.238504 -93.452188)
		(mid 128.432354 -93.395838)
		(end 128.574038 -93.252036)
		(width 0.0889)
		(layer "In9.Cu")
		(net "P3E_CPU1_PE3_MP_RXP<2>")
	)
	(arc
		(start 129.100834 -92.956634)
		(mid 129.292476 -92.899468)
		(end 129.432558 -92.756736)
		(width 0.0889)
		(layer "In9.Cu")
		(net "P3E_CPU1_PE3_MP_RXP<2>")
	)
	(arc
		(start 137.158984 -92.261436)
		(mid 137.367592 -92.049504)
		(end 137.653014 -91.966034)
		(width 0.0889)
		(layer "In9.Cu")
		(net "P3E_CPU1_PE3_MP_RXP<2>")
	)
	(arc
		(start 132.007864 -91.270836)
		(mid 132.216581 -91.058839)
		(end 132.502148 -90.975434)
		(width 0.0889)
		(layer "In9.Cu")
		(net "P3E_CPU1_PE3_MP_RXP<2>")
	)
	(arc
		(start 126.856998 -95.232982)
		(mid 126.910497 -95.033084)
		(end 126.856998 -94.833186)
		(width 0.0889)
		(layer "In9.Cu")
		(net "P3E_CPU1_PE3_MP_RXP<2>")
	)
	(arc
		(start 126.861824 -98.1964)
		(mid 126.910579 -98.000048)
		(end 126.856998 -97.804986)
		(width 0.0889)
		(layer "In9.Cu")
		(net "P3E_CPU1_PE3_MP_RXP<2>")
	)
	(arc
		(start 136.300464 -92.756736)
		(mid 136.507468 -92.545872)
		(end 136.790684 -92.461588)
		(width 0.0889)
		(layer "In9.Cu")
		(net "P3E_CPU1_PE3_MP_RXP<2>")
	)
	(arc
		(start 128.212342 -98.595688)
		(mid 128.0207 -98.652854)
		(end 127.880618 -98.795586)
		(width 0.0889)
		(layer "In9.Cu")
		(net "P3E_CPU1_PE3_MP_RXP<2>")
	)
	(arc
		(start 129.064258 -99.090734)
		(mid 128.781041 -99.006453)
		(end 128.574038 -98.795586)
		(width 0.0889)
		(layer "In9.Cu")
		(net "P3E_CPU1_PE3_MP_RXP<2>")
	)
	(arc
		(start 139.041124 -92.756736)
		(mid 139.180117 -92.898816)
		(end 139.370308 -92.956634)
		(width 0.0889)
		(layer "In9.Cu")
		(net "P3E_CPU1_PE3_MP_RXP<2>")
	)
	(arc
		(start 126.856998 -96.814386)
		(mid 126.777776 -96.525268)
		(end 126.850648 -96.234504)
		(width 0.0889)
		(layer "In9.Cu")
		(net "P3E_CPU1_PE3_MP_RXP<2>")
	)
	(arc
		(start 131.661408 -91.470988)
		(mid 131.858569 -91.419029)
		(end 132.004562 -91.276678)
		(width 0.0889)
		(layer "In9.Cu")
		(net "P3E_CPU1_PE3_MP_RXP<2>")
	)
	(arc
		(start 130.817874 -91.966034)
		(mid 131.009516 -91.908868)
		(end 131.149598 -91.766136)
		(width 0.0889)
		(layer "In9.Cu")
		(net "P3E_CPU1_PE3_MP_RXP<2>")
	)
	(arc
		(start 139.900152 -93.252036)
		(mid 140.038896 -93.394069)
		(end 140.228828 -93.451934)
		(width 0.0889)
		(layer "In9.Cu")
		(net "P3E_CPU1_PE3_MP_RXP<2>")
	)
	(segment
		(start 127.655828 -98.995738)
		(end 128.227328 -98.995738)
		(width 0.1143)
		(layer "F.Cu")
		(net "P3E_CPU1_PE3_MP_RXP<1>")
	)
	(via
		(at 128.227328 -98.995738)
		(size 0.508)
		(drill 0.254)
		(layers "F.Cu" "B.Cu")
		(net "P3E_CPU1_PE3_MP_RXP<1>")
	)
	(segment
		(start 128.227328 -98.995738)
		(end 128.227328 -99.303078)
		(width 0.0889)
		(layer "In9.Cu")
		(net "P3E_CPU1_PE3_MP_RXP<1>")
	)
	(segment
		(start 138.789664 -111.26851)
		(end 138.556238 -111.26851)
		(width 0.1143)
		(layer "In9.Cu")
		(net "P3E_CPU1_PE3_MP_RXP<1>")
	)
	(segment
		(start 52.332128 -79.20355)
		(end 54.06644 -70.531482)
		(width 0.1143)
		(layer "In9.Cu")
		(net "P3E_CPU1_PE3_MP_RXP<1>")
	)
	(segment
		(start 126.163578 -94.242636)
		(end 126.158752 -94.234)
		(width 0.0889)
		(layer "In9.Cu")
		(net "P3E_CPU1_PE3_MP_RXP<1>")
	)
	(segment
		(start 141.11097 -93.025468)
		(end 141.236446 -93.150944)
		(width 0.0889)
		(layer "In9.Cu")
		(net "P3E_CPU1_PE3_MP_RXP<1>")
	)
	(segment
		(start 142.318486 -93.64218)
		(end 142.386304 -93.709998)
		(width 0.0889)
		(layer "In9.Cu")
		(net "P3E_CPU1_PE3_MP_RXP<1>")
	)
	(segment
		(start 6.28142 -41.543478)
		(end 3.400044 -41.543478)
		(width 0.1143)
		(layer "In9.Cu")
		(net "P3E_CPU1_PE3_MP_RXP<1>")
	)
	(segment
		(start 52.94376 -80.356964)
		(end 52.688998 -80.408018)
		(width 0.1143)
		(layer "In9.Cu")
		(net "P3E_CPU1_PE3_MP_RXP<1>")
	)
	(segment
		(start 13.962888 -42.672762)
		(end 10.820654 -42.157904)
		(width 0.1143)
		(layer "In9.Cu")
		(net "P3E_CPU1_PE3_MP_RXP<1>")
	)
	(segment
		(start 135.077454 -91.661488)
		(end 135.11022 -91.661488)
		(width 0.0889)
		(layer "In9.Cu")
		(net "P3E_CPU1_PE3_MP_RXP<1>")
	)
	(segment
		(start 53.588412 -82.126328)
		(end 53.252878 -81.9023)
		(width 0.1143)
		(layer "In9.Cu")
		(net "P3E_CPU1_PE3_MP_RXP<1>")
	)
	(segment
		(start 53.252878 -81.9023)
		(end 52.998116 -81.953354)
		(width 0.1143)
		(layer "In9.Cu")
		(net "P3E_CPU1_PE3_MP_RXP<1>")
	)
	(segment
		(start 139.27455 -110.549944)
		(end 139.032234 -110.792514)
		(width 0.1143)
		(layer "In9.Cu")
		(net "P3E_CPU1_PE3_MP_RXP<1>")
	)
	(segment
		(start 1.0922 -40.317928)
		(end 1.700022 -39.710106)
		(width 0.1143)
		(layer "In9.Cu")
		(net "P3E_CPU1_PE3_MP_RXP<1>")
	)
	(segment
		(start 141.236446 -93.150944)
		(end 141.236446 -93.273118)
		(width 0.0889)
		(layer "In9.Cu")
		(net "P3E_CPU1_PE3_MP_RXP<1>")
	)
	(segment
		(start 142.564104 -93.709998)
		(end 142.631922 -93.64218)
		(width 0.0889)
		(layer "In9.Cu")
		(net "P3E_CPU1_PE3_MP_RXP<1>")
	)
	(segment
		(start 3.400044 -41.543478)
		(end 3.282696 -41.42613)
		(width 0.1143)
		(layer "In9.Cu")
		(net "P3E_CPU1_PE3_MP_RXP<1>")
	)
	(segment
		(start 57.447688 -102.857046)
		(end 57.218834 -102.81158)
		(width 0.1143)
		(layer "In9.Cu")
		(net "P3E_CPU1_PE3_MP_RXP<1>")
	)
	(segment
		(start 53.120544 -83.146392)
		(end 53.209952 -83.012534)
		(width 0.1143)
		(layer "In9.Cu")
		(net "P3E_CPU1_PE3_MP_RXP<1>")
	)
	(segment
		(start 141.727682 -93.64218)
		(end 142.318486 -93.64218)
		(width 0.0889)
		(layer "In9.Cu")
		(net "P3E_CPU1_PE3_MP_RXP<1>")
	)
	(segment
		(start 53.155596 -81.416144)
		(end 53.379624 -81.080356)
		(width 0.1143)
		(layer "In9.Cu")
		(net "P3E_CPU1_PE3_MP_RXP<1>")
	)
	(segment
		(start 53.379624 -81.080356)
		(end 53.279294 -80.580992)
		(width 0.1143)
		(layer "In9.Cu")
		(net "P3E_CPU1_PE3_MP_RXP<1>")
	)
	(segment
		(start 142.631922 -93.64218)
		(end 142.865856 -93.64218)
		(width 0.0889)
		(layer "In9.Cu")
		(net "P3E_CPU1_PE3_MP_RXP<1>")
	)
	(segment
		(start 53.279294 -80.580992)
		(end 52.94376 -80.356964)
		(width 0.1143)
		(layer "In9.Cu")
		(net "P3E_CPU1_PE3_MP_RXP<1>")
	)
	(segment
		(start 123.047506 -118.400068)
		(end 105.965498 -114.984276)
		(width 0.1143)
		(layer "In9.Cu")
		(net "P3E_CPU1_PE3_MP_RXP<1>")
	)
	(segment
		(start 52.811426 -81.601056)
		(end 52.900834 -81.467198)
		(width 0.1143)
		(layer "In9.Cu")
		(net "P3E_CPU1_PE3_MP_RXP<1>")
	)
	(segment
		(start 134.215124 -91.165934)
		(end 134.24789 -91.165934)
		(width 0.0889)
		(layer "In9.Cu")
		(net "P3E_CPU1_PE3_MP_RXP<1>")
	)
	(segment
		(start 52.331874 -79.204058)
		(end 52.332128 -79.20355)
		(width 0.1143)
		(layer "In9.Cu")
		(net "P3E_CPU1_PE3_MP_RXP<1>")
	)
	(segment
		(start 126.495302 -93.642688)
		(end 126.528068 -93.642688)
		(width 0.0889)
		(layer "In9.Cu")
		(net "P3E_CPU1_PE3_MP_RXP<1>")
	)
	(segment
		(start 1.0922 -40.832532)
		(end 1.0922 -40.317928)
		(width 0.1143)
		(layer "In9.Cu")
		(net "P3E_CPU1_PE3_MP_RXP<1>")
	)
	(segment
		(start 138.556238 -111.26851)
		(end 138.313668 -111.510826)
		(width 0.1143)
		(layer "In9.Cu")
		(net "P3E_CPU1_PE3_MP_RXP<1>")
	)
	(segment
		(start 53.209952 -83.012534)
		(end 53.464714 -82.96148)
		(width 0.1143)
		(layer "In9.Cu")
		(net "P3E_CPU1_PE3_MP_RXP<1>")
	)
	(segment
		(start 35.886644 -42.612818)
		(end 34.36239 -42.612818)
		(width 0.1143)
		(layer "In9.Cu")
		(net "P3E_CPU1_PE3_MP_RXP<1>")
	)
	(segment
		(start 138.511534 -91.661488)
		(end 138.5443 -91.661488)
		(width 0.0889)
		(layer "In9.Cu")
		(net "P3E_CPU1_PE3_MP_RXP<1>")
	)
	(segment
		(start 126.163578 -96.223836)
		(end 126.158752 -96.2152)
		(width 0.0889)
		(layer "In9.Cu")
		(net "P3E_CPU1_PE3_MP_RXP<1>")
	)
	(segment
		(start 52.554886 -80.318356)
		(end 52.331874 -79.204058)
		(width 0.1143)
		(layer "In9.Cu")
		(net "P3E_CPU1_PE3_MP_RXP<1>")
	)
	(segment
		(start 127.383794 -99.890834)
		(end 127.353822 -99.890834)
		(width 0.0889)
		(layer "In9.Cu")
		(net "P3E_CPU1_PE3_MP_RXP<1>")
	)
	(segment
		(start 39.978838 -43.85056)
		(end 35.886644 -42.612818)
		(width 0.1143)
		(layer "In9.Cu")
		(net "P3E_CPU1_PE3_MP_RXP<1>")
	)
	(segment
		(start 142.386304 -93.709998)
		(end 142.564104 -93.709998)
		(width 0.0889)
		(layer "In9.Cu")
		(net "P3E_CPU1_PE3_MP_RXP<1>")
	)
	(segment
		(start 135.932164 -92.156534)
		(end 135.975344 -92.156534)
		(width 0.0889)
		(layer "In9.Cu")
		(net "P3E_CPU1_PE3_MP_RXP<1>")
	)
	(segment
		(start 126.169928 -98.215704)
		(end 126.163578 -98.205036)
		(width 0.0889)
		(layer "In9.Cu")
		(net "P3E_CPU1_PE3_MP_RXP<1>")
	)
	(segment
		(start 10.495788 -42.23385)
		(end 6.28142 -41.543478)
		(width 0.1143)
		(layer "In9.Cu")
		(net "P3E_CPU1_PE3_MP_RXP<1>")
	)
	(segment
		(start 133.810248 -116.247926)
		(end 123.047506 -118.400068)
		(width 0.1143)
		(layer "In9.Cu")
		(net "P3E_CPU1_PE3_MP_RXP<1>")
	)
	(segment
		(start 131.646422 -90.670888)
		(end 131.679188 -90.670888)
		(width 0.0889)
		(layer "In9.Cu")
		(net "P3E_CPU1_PE3_MP_RXP<1>")
	)
	(segment
		(start 140.862812 -92.77731)
		(end 140.862812 -92.899484)
		(width 0.0889)
		(layer "In9.Cu")
		(net "P3E_CPU1_PE3_MP_RXP<1>")
	)
	(segment
		(start 132.173218 -90.375486)
		(end 132.17652 -90.369644)
		(width 0.0889)
		(layer "In9.Cu")
		(net "P3E_CPU1_PE3_MP_RXP<1>")
	)
	(segment
		(start 143.158972 -94.007432)
		(end 143.174466 -94.022926)
		(width 0.0889)
		(layer "In9.Cu")
		(net "P3E_CPU1_PE3_MP_RXP<1>")
	)
	(segment
		(start 139.366244 -92.156534)
		(end 139.39901 -92.156534)
		(width 0.0889)
		(layer "In9.Cu")
		(net "P3E_CPU1_PE3_MP_RXP<1>")
	)
	(segment
		(start 130.791712 -91.165934)
		(end 130.824478 -91.165934)
		(width 0.0889)
		(layer "In9.Cu")
		(net "P3E_CPU1_PE3_MP_RXP<1>")
	)
	(segment
		(start 1.975866 -41.543478)
		(end 1.597914 -41.337992)
		(width 0.1143)
		(layer "In9.Cu")
		(net "P3E_CPU1_PE3_MP_RXP<1>")
	)
	(segment
		(start 140.73759 -92.652088)
		(end 140.862812 -92.77731)
		(width 0.0889)
		(layer "In9.Cu")
		(net "P3E_CPU1_PE3_MP_RXP<1>")
	)
	(segment
		(start 105.965498 -114.984276)
		(end 98.436938 -116.488718)
		(width 0.1143)
		(layer "In9.Cu")
		(net "P3E_CPU1_PE3_MP_RXP<1>")
	)
	(segment
		(start 143.89862 -94.74708)
		(end 143.89862 -106.159554)
		(width 0.1143)
		(layer "In9.Cu")
		(net "P3E_CPU1_PE3_MP_RXP<1>")
	)
	(segment
		(start 126.531878 -99.395788)
		(end 126.499112 -99.395788)
		(width 0.0889)
		(layer "In9.Cu")
		(net "P3E_CPU1_PE3_MP_RXP<1>")
	)
	(segment
		(start 138.313668 -111.744506)
		(end 133.810248 -116.247926)
		(width 0.1143)
		(layer "In9.Cu")
		(net "P3E_CPU1_PE3_MP_RXP<1>")
	)
	(segment
		(start 53.464714 -82.96148)
		(end 53.688742 -82.625692)
		(width 0.1143)
		(layer "In9.Cu")
		(net "P3E_CPU1_PE3_MP_RXP<1>")
	)
	(segment
		(start 57.592722 -103.371142)
		(end 57.638188 -103.142288)
		(width 0.1143)
		(layer "In9.Cu")
		(net "P3E_CPU1_PE3_MP_RXP<1>")
	)
	(segment
		(start 56.980074 -102.454202)
		(end 53.120544 -83.146392)
		(width 0.1143)
		(layer "In9.Cu")
		(net "P3E_CPU1_PE3_MP_RXP<1>")
	)
	(segment
		(start 52.864004 -81.863692)
		(end 52.811426 -81.601056)
		(width 0.1143)
		(layer "In9.Cu")
		(net "P3E_CPU1_PE3_MP_RXP<1>")
	)
	(segment
		(start 31.912052 -43.76293)
		(end 25.661366 -45.012356)
		(width 0.1143)
		(layer "In9.Cu")
		(net "P3E_CPU1_PE3_MP_RXP<1>")
	)
	(segment
		(start 140.245846 -92.652088)
		(end 140.73759 -92.652088)
		(width 0.0889)
		(layer "In9.Cu")
		(net "P3E_CPU1_PE3_MP_RXP<1>")
	)
	(segment
		(start 92.279216 -115.257326)
		(end 83.155282 -117.082316)
		(width 0.1143)
		(layer "In9.Cu")
		(net "P3E_CPU1_PE3_MP_RXP<1>")
	)
	(segment
		(start 52.900834 -81.467198)
		(end 53.155596 -81.416144)
		(width 0.1143)
		(layer "In9.Cu")
		(net "P3E_CPU1_PE3_MP_RXP<1>")
	)
	(segment
		(start 54.06644 -70.531482)
		(end 54.06644 -65.561972)
		(width 0.1143)
		(layer "In9.Cu")
		(net "P3E_CPU1_PE3_MP_RXP<1>")
	)
	(segment
		(start 141.236446 -93.273118)
		(end 141.36243 -93.399102)
		(width 0.0889)
		(layer "In9.Cu")
		(net "P3E_CPU1_PE3_MP_RXP<1>")
	)
	(segment
		(start 50.748184 -51.029616)
		(end 39.978838 -43.85056)
		(width 0.1143)
		(layer "In9.Cu")
		(net "P3E_CPU1_PE3_MP_RXP<1>")
	)
	(segment
		(start 3.282696 -41.42613)
		(end 2.939796 -41.42613)
		(width 0.1143)
		(layer "In9.Cu")
		(net "P3E_CPU1_PE3_MP_RXP<1>")
	)
	(segment
		(start 140.988796 -93.025468)
		(end 141.11097 -93.025468)
		(width 0.0889)
		(layer "In9.Cu")
		(net "P3E_CPU1_PE3_MP_RXP<1>")
	)
	(segment
		(start 69.900038 -114.431064)
		(end 61.027564 -108.514642)
		(width 0.1143)
		(layer "In9.Cu")
		(net "P3E_CPU1_PE3_MP_RXP<1>")
	)
	(segment
		(start 126.163578 -98.205036)
		(end 126.158752 -98.1964)
		(width 0.0889)
		(layer "In9.Cu")
		(net "P3E_CPU1_PE3_MP_RXP<1>")
	)
	(segment
		(start 57.218834 -102.81158)
		(end 56.980074 -102.454202)
		(width 0.1143)
		(layer "In9.Cu")
		(net "P3E_CPU1_PE3_MP_RXP<1>")
	)
	(segment
		(start 127.357632 -93.147134)
		(end 127.390398 -93.147134)
		(width 0.0889)
		(layer "In9.Cu")
		(net "P3E_CPU1_PE3_MP_RXP<1>")
	)
	(segment
		(start 128.160272 -99.464876)
		(end 127.982218 -99.64293)
		(width 0.0889)
		(layer "In9.Cu")
		(net "P3E_CPU1_PE3_MP_RXP<1>")
	)
	(segment
		(start 2.822448 -41.543478)
		(end 1.975866 -41.543478)
		(width 0.1143)
		(layer "In9.Cu")
		(net "P3E_CPU1_PE3_MP_RXP<1>")
	)
	(segment
		(start 126.163578 -97.214436)
		(end 126.158752 -97.2058)
		(width 0.0889)
		(layer "In9.Cu")
		(net "P3E_CPU1_PE3_MP_RXP<1>")
	)
	(segment
		(start 143.89862 -106.159554)
		(end 139.50823 -110.549944)
		(width 0.1143)
		(layer "In9.Cu")
		(net "P3E_CPU1_PE3_MP_RXP<1>")
	)
	(segment
		(start 142.865856 -93.64218)
		(end 143.158972 -93.935296)
		(width 0.0889)
		(layer "In9.Cu")
		(net "P3E_CPU1_PE3_MP_RXP<1>")
	)
	(segment
		(start 98.436938 -116.488718)
		(end 92.279216 -115.257326)
		(width 0.1143)
		(layer "In9.Cu")
		(net "P3E_CPU1_PE3_MP_RXP<1>")
	)
	(segment
		(start 143.158972 -93.935296)
		(end 143.158972 -94.007432)
		(width 0.0889)
		(layer "In9.Cu")
		(net "P3E_CPU1_PE3_MP_RXP<1>")
	)
	(segment
		(start 139.032234 -111.02594)
		(end 138.789664 -111.26851)
		(width 0.1143)
		(layer "In9.Cu")
		(net "P3E_CPU1_PE3_MP_RXP<1>")
	)
	(segment
		(start 52.998116 -81.953354)
		(end 52.864004 -81.863692)
		(width 0.1143)
		(layer "In9.Cu")
		(net "P3E_CPU1_PE3_MP_RXP<1>")
	)
	(segment
		(start 126.169928 -97.225104)
		(end 126.163578 -97.214436)
		(width 0.0889)
		(layer "In9.Cu")
		(net "P3E_CPU1_PE3_MP_RXP<1>")
	)
	(segment
		(start 141.36243 -93.399102)
		(end 141.484604 -93.399102)
		(width 0.0889)
		(layer "In9.Cu")
		(net "P3E_CPU1_PE3_MP_RXP<1>")
	)
	(segment
		(start 1.597914 -41.337992)
		(end 1.0922 -40.832532)
		(width 0.1143)
		(layer "In9.Cu")
		(net "P3E_CPU1_PE3_MP_RXP<1>")
	)
	(segment
		(start 126.163578 -94.833186)
		(end 126.169928 -94.822518)
		(width 0.0889)
		(layer "In9.Cu")
		(net "P3E_CPU1_PE3_MP_RXP<1>")
	)
	(segment
		(start 136.797288 -91.661488)
		(end 136.830054 -91.661488)
		(width 0.0889)
		(layer "In9.Cu")
		(net "P3E_CPU1_PE3_MP_RXP<1>")
	)
	(segment
		(start 25.661366 -45.012356)
		(end 13.962888 -42.672762)
		(width 0.1143)
		(layer "In9.Cu")
		(net "P3E_CPU1_PE3_MP_RXP<1>")
	)
	(segment
		(start 129.074672 -92.156534)
		(end 129.107438 -92.156534)
		(width 0.0889)
		(layer "In9.Cu")
		(net "P3E_CPU1_PE3_MP_RXP<1>")
	)
	(segment
		(start 55.536338 -58.211974)
		(end 50.748184 -51.029616)
		(width 0.1143)
		(layer "In9.Cu")
		(net "P3E_CPU1_PE3_MP_RXP<1>")
	)
	(segment
		(start 129.929382 -91.661488)
		(end 129.962148 -91.661488)
		(width 0.0889)
		(layer "In9.Cu")
		(net "P3E_CPU1_PE3_MP_RXP<1>")
	)
	(segment
		(start 139.032234 -110.792514)
		(end 139.032234 -111.02594)
		(width 0.1143)
		(layer "In9.Cu")
		(net "P3E_CPU1_PE3_MP_RXP<1>")
	)
	(segment
		(start 133.360414 -90.670888)
		(end 133.39318 -90.670888)
		(width 0.0889)
		(layer "In9.Cu")
		(net "P3E_CPU1_PE3_MP_RXP<1>")
	)
	(segment
		(start 143.174466 -94.022926)
		(end 143.89862 -94.74708)
		(width 0.1143)
		(layer "In9.Cu")
		(net "P3E_CPU1_PE3_MP_RXP<1>")
	)
	(segment
		(start 140.862812 -92.899484)
		(end 140.988796 -93.025468)
		(width 0.0889)
		(layer "In9.Cu")
		(net "P3E_CPU1_PE3_MP_RXP<1>")
	)
	(segment
		(start 141.484604 -93.399102)
		(end 141.727682 -93.64218)
		(width 0.0889)
		(layer "In9.Cu")
		(net "P3E_CPU1_PE3_MP_RXP<1>")
	)
	(segment
		(start 53.688742 -82.625692)
		(end 53.588412 -82.126328)
		(width 0.1143)
		(layer "In9.Cu")
		(net "P3E_CPU1_PE3_MP_RXP<1>")
	)
	(segment
		(start 52.688998 -80.408018)
		(end 52.554886 -80.318356)
		(width 0.1143)
		(layer "In9.Cu")
		(net "P3E_CPU1_PE3_MP_RXP<1>")
	)
	(segment
		(start 126.169928 -96.234504)
		(end 126.163578 -96.223836)
		(width 0.0889)
		(layer "In9.Cu")
		(net "P3E_CPU1_PE3_MP_RXP<1>")
	)
	(segment
		(start 61.027564 -108.514642)
		(end 57.592722 -103.371142)
		(width 0.1143)
		(layer "In9.Cu")
		(net "P3E_CPU1_PE3_MP_RXP<1>")
	)
	(segment
		(start 2.939796 -41.42613)
		(end 2.822448 -41.543478)
		(width 0.1143)
		(layer "In9.Cu")
		(net "P3E_CPU1_PE3_MP_RXP<1>")
	)
	(segment
		(start 138.313668 -111.510826)
		(end 138.313668 -111.744506)
		(width 0.1143)
		(layer "In9.Cu")
		(net "P3E_CPU1_PE3_MP_RXP<1>")
	)
	(segment
		(start 128.212342 -92.652088)
		(end 128.245108 -92.652088)
		(width 0.0889)
		(layer "In9.Cu")
		(net "P3E_CPU1_PE3_MP_RXP<1>")
	)
	(segment
		(start 34.36239 -42.612818)
		(end 31.912052 -43.76293)
		(width 0.1143)
		(layer "In9.Cu")
		(net "P3E_CPU1_PE3_MP_RXP<1>")
	)
	(segment
		(start 10.820654 -42.157904)
		(end 10.495788 -42.23385)
		(width 0.1143)
		(layer "In9.Cu")
		(net "P3E_CPU1_PE3_MP_RXP<1>")
	)
	(segment
		(start 139.50823 -110.549944)
		(end 139.27455 -110.549944)
		(width 0.1143)
		(layer "In9.Cu")
		(net "P3E_CPU1_PE3_MP_RXP<1>")
	)
	(segment
		(start 57.638188 -103.142288)
		(end 57.447688 -102.857046)
		(width 0.1143)
		(layer "In9.Cu")
		(net "P3E_CPU1_PE3_MP_RXP<1>")
	)
	(segment
		(start 54.06644 -65.561972)
		(end 55.536338 -58.211974)
		(width 0.1143)
		(layer "In9.Cu")
		(net "P3E_CPU1_PE3_MP_RXP<1>")
	)
	(segment
		(start 83.155282 -117.082316)
		(end 69.900038 -114.431064)
		(width 0.1143)
		(layer "In9.Cu")
		(net "P3E_CPU1_PE3_MP_RXP<1>")
	)
	(arc
		(start 127.353822 -99.890834)
		(mid 127.16218 -99.833668)
		(end 127.022098 -99.690936)
		(width 0.0889)
		(layer "In9.Cu")
		(net "P3E_CPU1_PE3_MP_RXP<1>")
	)
	(arc
		(start 139.39901 -92.156534)
		(mid 139.59286 -92.212884)
		(end 139.734544 -92.356686)
		(width 0.0889)
		(layer "In9.Cu")
		(net "P3E_CPU1_PE3_MP_RXP<1>")
	)
	(arc
		(start 126.163578 -95.823786)
		(mid 126.242709 -95.528384)
		(end 126.163578 -95.232982)
		(width 0.0889)
		(layer "In9.Cu")
		(net "P3E_CPU1_PE3_MP_RXP<1>")
	)
	(arc
		(start 126.158752 -98.1964)
		(mid 126.109997 -98.000048)
		(end 126.163578 -97.804986)
		(width 0.0889)
		(layer "In9.Cu")
		(net "P3E_CPU1_PE3_MP_RXP<1>")
	)
	(arc
		(start 126.158752 -94.234)
		(mid 126.162499 -93.844744)
		(end 126.495302 -93.642688)
		(width 0.0889)
		(layer "In9.Cu")
		(net "P3E_CPU1_PE3_MP_RXP<1>")
	)
	(arc
		(start 126.158752 -96.2152)
		(mid 126.109997 -96.018848)
		(end 126.163578 -95.823786)
		(width 0.0889)
		(layer "In9.Cu")
		(net "P3E_CPU1_PE3_MP_RXP<1>")
	)
	(arc
		(start 130.824478 -91.165934)
		(mid 131.107695 -91.081653)
		(end 131.314698 -90.870786)
		(width 0.0889)
		(layer "In9.Cu")
		(net "P3E_CPU1_PE3_MP_RXP<1>")
	)
	(arc
		(start 131.314698 -90.870786)
		(mid 131.454777 -90.72805)
		(end 131.646422 -90.670888)
		(width 0.0889)
		(layer "In9.Cu")
		(net "P3E_CPU1_PE3_MP_RXP<1>")
	)
	(arc
		(start 137.682732 -91.165934)
		(mid 137.876158 -91.222461)
		(end 138.017504 -91.366086)
		(width 0.0889)
		(layer "In9.Cu")
		(net "P3E_CPU1_PE3_MP_RXP<1>")
	)
	(arc
		(start 127.982218 -99.64293)
		(mid 127.707659 -99.826385)
		(end 127.383794 -99.890834)
		(width 0.0889)
		(layer "In9.Cu")
		(net "P3E_CPU1_PE3_MP_RXP<1>")
	)
	(arc
		(start 138.017504 -91.366086)
		(mid 138.226112 -91.578018)
		(end 138.511534 -91.661488)
		(width 0.0889)
		(layer "In9.Cu")
		(net "P3E_CPU1_PE3_MP_RXP<1>")
	)
	(arc
		(start 133.39318 -90.670888)
		(mid 133.584822 -90.728054)
		(end 133.724904 -90.870786)
		(width 0.0889)
		(layer "In9.Cu")
		(net "P3E_CPU1_PE3_MP_RXP<1>")
	)
	(arc
		(start 127.022098 -93.347286)
		(mid 127.163781 -93.203482)
		(end 127.357632 -93.147134)
		(width 0.0889)
		(layer "In9.Cu")
		(net "P3E_CPU1_PE3_MP_RXP<1>")
	)
	(arc
		(start 135.975344 -92.156534)
		(mid 136.258561 -92.072253)
		(end 136.465564 -91.861386)
		(width 0.0889)
		(layer "In9.Cu")
		(net "P3E_CPU1_PE3_MP_RXP<1>")
	)
	(arc
		(start 126.499112 -99.395788)
		(mid 126.160943 -99.19099)
		(end 126.163578 -98.795586)
		(width 0.0889)
		(layer "In9.Cu")
		(net "P3E_CPU1_PE3_MP_RXP<1>")
	)
	(arc
		(start 136.465564 -91.861386)
		(mid 136.605643 -91.71865)
		(end 136.797288 -91.661488)
		(width 0.0889)
		(layer "In9.Cu")
		(net "P3E_CPU1_PE3_MP_RXP<1>")
	)
	(arc
		(start 135.441944 -91.861386)
		(mid 135.648948 -92.07225)
		(end 135.932164 -92.156534)
		(width 0.0889)
		(layer "In9.Cu")
		(net "P3E_CPU1_PE3_MP_RXP<1>")
	)
	(arc
		(start 126.163578 -97.804986)
		(mid 126.2428 -97.515868)
		(end 126.169928 -97.225104)
		(width 0.0889)
		(layer "In9.Cu")
		(net "P3E_CPU1_PE3_MP_RXP<1>")
	)
	(arc
		(start 127.390398 -93.147134)
		(mid 127.673615 -93.062853)
		(end 127.880618 -92.851986)
		(width 0.0889)
		(layer "In9.Cu")
		(net "P3E_CPU1_PE3_MP_RXP<1>")
	)
	(arc
		(start 139.734544 -92.356686)
		(mid 139.950607 -92.572895)
		(end 140.245846 -92.652088)
		(width 0.0889)
		(layer "In9.Cu")
		(net "P3E_CPU1_PE3_MP_RXP<1>")
	)
	(arc
		(start 126.158752 -97.2058)
		(mid 126.109997 -97.009448)
		(end 126.163578 -96.814386)
		(width 0.0889)
		(layer "In9.Cu")
		(net "P3E_CPU1_PE3_MP_RXP<1>")
	)
	(arc
		(start 127.880618 -92.851986)
		(mid 128.020697 -92.70925)
		(end 128.212342 -92.652088)
		(width 0.0889)
		(layer "In9.Cu")
		(net "P3E_CPU1_PE3_MP_RXP<1>")
	)
	(arc
		(start 126.169928 -94.822518)
		(mid 126.242726 -94.531755)
		(end 126.163578 -94.242636)
		(width 0.0889)
		(layer "In9.Cu")
		(net "P3E_CPU1_PE3_MP_RXP<1>")
	)
	(arc
		(start 126.163578 -96.814386)
		(mid 126.2428 -96.525268)
		(end 126.169928 -96.234504)
		(width 0.0889)
		(layer "In9.Cu")
		(net "P3E_CPU1_PE3_MP_RXP<1>")
	)
	(arc
		(start 129.597658 -91.861386)
		(mid 129.737737 -91.71865)
		(end 129.929382 -91.661488)
		(width 0.0889)
		(layer "In9.Cu")
		(net "P3E_CPU1_PE3_MP_RXP<1>")
	)
	(arc
		(start 132.17652 -90.369644)
		(mid 132.523093 -90.175294)
		(end 132.866384 -90.375486)
		(width 0.0889)
		(layer "In9.Cu")
		(net "P3E_CPU1_PE3_MP_RXP<1>")
	)
	(arc
		(start 134.583424 -91.366086)
		(mid 134.792032 -91.578018)
		(end 135.077454 -91.661488)
		(width 0.0889)
		(layer "In9.Cu")
		(net "P3E_CPU1_PE3_MP_RXP<1>")
	)
	(arc
		(start 128.245108 -92.652088)
		(mid 128.530532 -92.568621)
		(end 128.739138 -92.356686)
		(width 0.0889)
		(layer "In9.Cu")
		(net "P3E_CPU1_PE3_MP_RXP<1>")
	)
	(arc
		(start 126.528068 -93.642688)
		(mid 126.813492 -93.559221)
		(end 127.022098 -93.347286)
		(width 0.0889)
		(layer "In9.Cu")
		(net "P3E_CPU1_PE3_MP_RXP<1>")
	)
	(arc
		(start 126.163578 -98.795586)
		(mid 126.2428 -98.506468)
		(end 126.169928 -98.215704)
		(width 0.0889)
		(layer "In9.Cu")
		(net "P3E_CPU1_PE3_MP_RXP<1>")
	)
	(arc
		(start 128.227328 -99.303078)
		(mid 128.209908 -99.390657)
		(end 128.160272 -99.464876)
		(width 0.0889)
		(layer "In9.Cu")
		(net "P3E_CPU1_PE3_MP_RXP<1>")
	)
	(arc
		(start 134.24789 -91.165934)
		(mid 134.44174 -91.222284)
		(end 134.583424 -91.366086)
		(width 0.0889)
		(layer "In9.Cu")
		(net "P3E_CPU1_PE3_MP_RXP<1>")
	)
	(arc
		(start 129.962148 -91.661488)
		(mid 130.247572 -91.578021)
		(end 130.456178 -91.366086)
		(width 0.0889)
		(layer "In9.Cu")
		(net "P3E_CPU1_PE3_MP_RXP<1>")
	)
	(arc
		(start 126.163578 -95.232982)
		(mid 126.110079 -95.033084)
		(end 126.163578 -94.833186)
		(width 0.0889)
		(layer "In9.Cu")
		(net "P3E_CPU1_PE3_MP_RXP<1>")
	)
	(arc
		(start 127.022098 -99.690936)
		(mid 126.815094 -99.480072)
		(end 126.531878 -99.395788)
		(width 0.0889)
		(layer "In9.Cu")
		(net "P3E_CPU1_PE3_MP_RXP<1>")
	)
	(arc
		(start 130.456178 -91.366086)
		(mid 130.597861 -91.222282)
		(end 130.791712 -91.165934)
		(width 0.0889)
		(layer "In9.Cu")
		(net "P3E_CPU1_PE3_MP_RXP<1>")
	)
	(arc
		(start 128.739138 -92.356686)
		(mid 128.880821 -92.212882)
		(end 129.074672 -92.156534)
		(width 0.0889)
		(layer "In9.Cu")
		(net "P3E_CPU1_PE3_MP_RXP<1>")
	)
	(arc
		(start 138.876024 -91.861386)
		(mid 139.083028 -92.07225)
		(end 139.366244 -92.156534)
		(width 0.0889)
		(layer "In9.Cu")
		(net "P3E_CPU1_PE3_MP_RXP<1>")
	)
	(arc
		(start 137.658856 -91.165934)
		(mid 137.670794 -91.165756)
		(end 137.682732 -91.165934)
		(width 0.0889)
		(layer "In9.Cu")
		(net "P3E_CPU1_PE3_MP_RXP<1>")
	)
	(arc
		(start 138.5443 -91.661488)
		(mid 138.735942 -91.718654)
		(end 138.876024 -91.861386)
		(width 0.0889)
		(layer "In9.Cu")
		(net "P3E_CPU1_PE3_MP_RXP<1>")
	)
	(arc
		(start 132.866384 -90.375486)
		(mid 133.074992 -90.587418)
		(end 133.360414 -90.670888)
		(width 0.0889)
		(layer "In9.Cu")
		(net "P3E_CPU1_PE3_MP_RXP<1>")
	)
	(arc
		(start 135.11022 -91.661488)
		(mid 135.301862 -91.718654)
		(end 135.441944 -91.861386)
		(width 0.0889)
		(layer "In9.Cu")
		(net "P3E_CPU1_PE3_MP_RXP<1>")
	)
	(arc
		(start 129.107438 -92.156534)
		(mid 129.390655 -92.072253)
		(end 129.597658 -91.861386)
		(width 0.0889)
		(layer "In9.Cu")
		(net "P3E_CPU1_PE3_MP_RXP<1>")
	)
	(arc
		(start 136.830054 -91.661488)
		(mid 137.115478 -91.578021)
		(end 137.324084 -91.366086)
		(width 0.0889)
		(layer "In9.Cu")
		(net "P3E_CPU1_PE3_MP_RXP<1>")
	)
	(arc
		(start 133.724904 -90.870786)
		(mid 133.931908 -91.08165)
		(end 134.215124 -91.165934)
		(width 0.0889)
		(layer "In9.Cu")
		(net "P3E_CPU1_PE3_MP_RXP<1>")
	)
	(arc
		(start 131.679188 -90.670888)
		(mid 131.964612 -90.587421)
		(end 132.173218 -90.375486)
		(width 0.0889)
		(layer "In9.Cu")
		(net "P3E_CPU1_PE3_MP_RXP<1>")
	)
	(arc
		(start 137.324084 -91.366086)
		(mid 137.46544 -91.222477)
		(end 137.658856 -91.165934)
		(width 0.0889)
		(layer "In9.Cu")
		(net "P3E_CPU1_PE3_MP_RXP<1>")
	)
	(segment
		(start 128.514348 -100.481638)
		(end 129.085848 -100.481638)
		(width 0.1143)
		(layer "F.Cu")
		(net "P3E_CPU1_PE3_MP_RXP<0>")
	)
	(via
		(at 129.085848 -100.481638)
		(size 0.508)
		(drill 0.254)
		(layers "F.Cu" "B.Cu")
		(net "P3E_CPU1_PE3_MP_RXP<0>")
	)
	(segment
		(start 25.93975 -45.71619)
		(end 25.940004 -45.715936)
		(width 0.1143)
		(layer "In9.Cu")
		(net "P3E_CPU1_PE3_MP_RXP<0>")
	)
	(segment
		(start 106.711242 -115.832382)
		(end 106.905552 -115.961922)
		(width 0.1143)
		(layer "In9.Cu")
		(net "P3E_CPU1_PE3_MP_RXP<0>")
	)
	(segment
		(start 144.60982 -106.792268)
		(end 144.60982 -94.151958)
		(width 0.1143)
		(layer "In9.Cu")
		(net "P3E_CPU1_PE3_MP_RXP<0>")
	)
	(segment
		(start 141.595094 -91.06535)
		(end 141.451838 -91.06535)
		(width 0.0889)
		(layer "In9.Cu")
		(net "P3E_CPU1_PE3_MP_RXP<0>")
	)
	(segment
		(start 134.24789 -90.175334)
		(end 134.215124 -90.175334)
		(width 0.0889)
		(layer "In9.Cu")
		(net "P3E_CPU1_PE3_MP_RXP<0>")
	)
	(segment
		(start 130.824478 -90.175334)
		(end 130.791712 -90.175334)
		(width 0.0889)
		(layer "In9.Cu")
		(net "P3E_CPU1_PE3_MP_RXP<0>")
	)
	(segment
		(start 135.975344 -91.165934)
		(end 135.932164 -91.165934)
		(width 0.0889)
		(layer "In9.Cu")
		(net "P3E_CPU1_PE3_MP_RXP<0>")
	)
	(segment
		(start 6.414262 -42.2402)
		(end 9.98982 -42.9514)
		(width 0.1143)
		(layer "In9.Cu")
		(net "P3E_CPU1_PE3_MP_RXP<0>")
	)
	(segment
		(start 131.679188 -89.680288)
		(end 131.646422 -89.680288)
		(width 0.0889)
		(layer "In9.Cu")
		(net "P3E_CPU1_PE3_MP_RXP<0>")
	)
	(segment
		(start 128.703324 -100.626418)
		(end 128.792732 -100.650548)
		(width 0.0889)
		(layer "In9.Cu")
		(net "P3E_CPU1_PE3_MP_RXP<0>")
	)
	(segment
		(start 28.38577 -47.013114)
		(end 29.123894 -47.160434)
		(width 0.1143)
		(layer "In9.Cu")
		(net "P3E_CPU1_PE3_MP_RXP<0>")
	)
	(segment
		(start 139.409424 -91.165934)
		(end 139.366244 -91.165934)
		(width 0.0889)
		(layer "In9.Cu")
		(net "P3E_CPU1_PE3_MP_RXP<0>")
	)
	(segment
		(start 26.763472 -45.54474)
		(end 27.651964 -45.841158)
		(width 0.1143)
		(layer "In9.Cu")
		(net "P3E_CPU1_PE3_MP_RXP<0>")
	)
	(segment
		(start 34.414714 -43.29049)
		(end 35.825684 -43.29049)
		(width 0.1143)
		(layer "In9.Cu")
		(net "P3E_CPU1_PE3_MP_RXP<0>")
	)
	(segment
		(start 142.240762 -91.854274)
		(end 142.115032 -91.728544)
		(width 0.0889)
		(layer "In9.Cu")
		(net "P3E_CPU1_PE3_MP_RXP<0>")
	)
	(segment
		(start 126.528068 -92.652088)
		(end 126.495302 -92.652088)
		(width 0.0889)
		(layer "In9.Cu")
		(net "P3E_CPU1_PE3_MP_RXP<0>")
	)
	(segment
		(start 142.509494 -92.123006)
		(end 142.509494 -91.97975)
		(width 0.0889)
		(layer "In9.Cu")
		(net "P3E_CPU1_PE3_MP_RXP<0>")
	)
	(segment
		(start 144.60982 -94.151958)
		(end 143.781018 -93.323156)
		(width 0.1143)
		(layer "In9.Cu")
		(net "P3E_CPU1_PE3_MP_RXP<0>")
	)
	(segment
		(start 126.492254 -100.386134)
		(end 126.528068 -100.386134)
		(width 0.0889)
		(layer "In9.Cu")
		(net "P3E_CPU1_PE3_MP_RXP<0>")
	)
	(segment
		(start 129.107438 -91.165934)
		(end 129.074672 -91.165934)
		(width 0.0889)
		(layer "In9.Cu")
		(net "P3E_CPU1_PE3_MP_RXP<0>")
	)
	(segment
		(start 35.825684 -43.29049)
		(end 39.472616 -44.361862)
		(width 0.1143)
		(layer "In9.Cu")
		(net "P3E_CPU1_PE3_MP_RXP<0>")
	)
	(segment
		(start 142.77848 -92.248736)
		(end 142.635224 -92.248736)
		(width 0.0889)
		(layer "In9.Cu")
		(net "P3E_CPU1_PE3_MP_RXP<0>")
	)
	(segment
		(start -1.397 -42.2402)
		(end 6.414262 -42.2402)
		(width 0.1143)
		(layer "In9.Cu")
		(net "P3E_CPU1_PE3_MP_RXP<0>")
	)
	(segment
		(start 104.718866 -116.231162)
		(end 104.913176 -116.360702)
		(width 0.1143)
		(layer "In9.Cu")
		(net "P3E_CPU1_PE3_MP_RXP<0>")
	)
	(segment
		(start 142.115032 -91.728544)
		(end 142.115032 -91.585288)
		(width 0.0889)
		(layer "In9.Cu")
		(net "P3E_CPU1_PE3_MP_RXP<0>")
	)
	(segment
		(start 140.66774 -90.77198)
		(end 140.566648 -90.670888)
		(width 0.0889)
		(layer "In9.Cu")
		(net "P3E_CPU1_PE3_MP_RXP<0>")
	)
	(segment
		(start 60.264548 -108.815378)
		(end 69.735446 -115.129818)
		(width 0.1143)
		(layer "In9.Cu")
		(net "P3E_CPU1_PE3_MP_RXP<0>")
	)
	(segment
		(start 125.305058 -94.737936)
		(end 125.311408 -94.748604)
		(width 0.0889)
		(layer "In9.Cu")
		(net "P3E_CPU1_PE3_MP_RXP<0>")
	)
	(segment
		(start 50.262282 -51.537362)
		(end 54.778656 -58.311034)
		(width 0.1143)
		(layer "In9.Cu")
		(net "P3E_CPU1_PE3_MP_RXP<0>")
	)
	(segment
		(start 54.778656 -58.311034)
		(end 53.31714 -65.618614)
		(width 0.1143)
		(layer "In9.Cu")
		(net "P3E_CPU1_PE3_MP_RXP<0>")
	)
	(segment
		(start 125.311408 -99.280218)
		(end 125.305058 -99.290886)
		(width 0.0889)
		(layer "In9.Cu")
		(net "P3E_CPU1_PE3_MP_RXP<0>")
	)
	(segment
		(start 138.5443 -90.670888)
		(end 138.511534 -90.670888)
		(width 0.0889)
		(layer "In9.Cu")
		(net "P3E_CPU1_PE3_MP_RXP<0>")
	)
	(segment
		(start 69.735446 -115.129818)
		(end 82.964782 -117.775482)
		(width 0.1143)
		(layer "In9.Cu")
		(net "P3E_CPU1_PE3_MP_RXP<0>")
	)
	(segment
		(start 39.51986 -44.375832)
		(end 50.262282 -51.537362)
		(width 0.1143)
		(layer "In9.Cu")
		(net "P3E_CPU1_PE3_MP_RXP<0>")
	)
	(segment
		(start 128.792732 -100.650548)
		(end 129.085848 -100.481638)
		(width 0.0889)
		(layer "In9.Cu")
		(net "P3E_CPU1_PE3_MP_RXP<0>")
	)
	(segment
		(start 29.78658 -47.0281)
		(end 29.78785 -47.027592)
		(width 0.1143)
		(layer "In9.Cu")
		(net "P3E_CPU1_PE3_MP_RXP<0>")
	)
	(segment
		(start 125.305058 -95.328486)
		(end 125.300232 -95.337122)
		(width 0.0889)
		(layer "In9.Cu")
		(net "P3E_CPU1_PE3_MP_RXP<0>")
	)
	(segment
		(start 125.305058 -99.290886)
		(end 125.300232 -99.299522)
		(width 0.0889)
		(layer "In9.Cu")
		(net "P3E_CPU1_PE3_MP_RXP<0>")
	)
	(segment
		(start 133.39318 -89.680288)
		(end 133.360414 -89.680288)
		(width 0.0889)
		(layer "In9.Cu")
		(net "P3E_CPU1_PE3_MP_RXP<0>")
	)
	(segment
		(start 32.01289 -44.418504)
		(end 34.414714 -43.29049)
		(width 0.1143)
		(layer "In9.Cu")
		(net "P3E_CPU1_PE3_MP_RXP<0>")
	)
	(segment
		(start 98.400108 -117.664738)
		(end 104.253284 -116.492782)
		(width 0.1143)
		(layer "In9.Cu")
		(net "P3E_CPU1_PE3_MP_RXP<0>")
	)
	(segment
		(start 105.378758 -116.099082)
		(end 105.715054 -116.031772)
		(width 0.1143)
		(layer "In9.Cu")
		(net "P3E_CPU1_PE3_MP_RXP<0>")
	)
	(segment
		(start 136.830054 -90.670888)
		(end 136.797288 -90.670888)
		(width 0.0889)
		(layer "In9.Cu")
		(net "P3E_CPU1_PE3_MP_RXP<0>")
	)
	(segment
		(start 17.090898 -43.946318)
		(end 25.93975 -45.71619)
		(width 0.1143)
		(layer "In9.Cu")
		(net "P3E_CPU1_PE3_MP_RXP<0>")
	)
	(segment
		(start 29.123894 -47.160434)
		(end 29.785818 -47.028354)
		(width 0.1143)
		(layer "In9.Cu")
		(net "P3E_CPU1_PE3_MP_RXP<0>")
	)
	(segment
		(start 27.651964 -45.841158)
		(end 27.957018 -46.589442)
		(width 0.1143)
		(layer "In9.Cu")
		(net "P3E_CPU1_PE3_MP_RXP<0>")
	)
	(segment
		(start 39.475664 -44.362878)
		(end 39.476934 -44.363132)
		(width 0.1143)
		(layer "In9.Cu")
		(net "P3E_CPU1_PE3_MP_RXP<0>")
	)
	(segment
		(start 104.913176 -116.360702)
		(end 105.249472 -116.293392)
		(width 0.1143)
		(layer "In9.Cu")
		(net "P3E_CPU1_PE3_MP_RXP<0>")
	)
	(segment
		(start 82.964782 -117.775482)
		(end 90.958924 -116.17706)
		(width 0.1143)
		(layer "In9.Cu")
		(net "P3E_CPU1_PE3_MP_RXP<0>")
	)
	(segment
		(start 125.311408 -97.299018)
		(end 125.305058 -97.309686)
		(width 0.0889)
		(layer "In9.Cu")
		(net "P3E_CPU1_PE3_MP_RXP<0>")
	)
	(segment
		(start -3.0734 -40.283384)
		(end -3.0734 -40.5638)
		(width 0.1143)
		(layer "In9.Cu")
		(net "P3E_CPU1_PE3_MP_RXP<0>")
	)
	(segment
		(start 143.781018 -93.323156)
		(end 143.781018 -93.32341)
		(width 0.0889)
		(layer "In9.Cu")
		(net "P3E_CPU1_PE3_MP_RXP<0>")
	)
	(segment
		(start 106.24566 -116.094002)
		(end 106.3752 -115.899692)
		(width 0.1143)
		(layer "In9.Cu")
		(net "P3E_CPU1_PE3_MP_RXP<0>")
	)
	(segment
		(start 53.31714 -70.566026)
		(end 51.59121 -79.194406)
		(width 0.1143)
		(layer "In9.Cu")
		(net "P3E_CPU1_PE3_MP_RXP<0>")
	)
	(segment
		(start 142.635224 -92.248736)
		(end 142.509494 -92.123006)
		(width 0.0889)
		(layer "In9.Cu")
		(net "P3E_CPU1_PE3_MP_RXP<0>")
	)
	(segment
		(start 125.305058 -98.300286)
		(end 125.300232 -98.308922)
		(width 0.0889)
		(layer "In9.Cu")
		(net "P3E_CPU1_PE3_MP_RXP<0>")
	)
	(segment
		(start 143.029686 -92.643198)
		(end 142.903956 -92.517468)
		(width 0.0889)
		(layer "In9.Cu")
		(net "P3E_CPU1_PE3_MP_RXP<0>")
	)
	(segment
		(start 125.636782 -99.890834)
		(end 125.664722 -99.890834)
		(width 0.0889)
		(layer "In9.Cu")
		(net "P3E_CPU1_PE3_MP_RXP<0>")
	)
	(segment
		(start 140.946632 -90.670888)
		(end 140.84554 -90.77198)
		(width 0.0889)
		(layer "In9.Cu")
		(net "P3E_CPU1_PE3_MP_RXP<0>")
	)
	(segment
		(start 142.115032 -91.585288)
		(end 141.989556 -91.459812)
		(width 0.0889)
		(layer "In9.Cu")
		(net "P3E_CPU1_PE3_MP_RXP<0>")
	)
	(segment
		(start 56.30799 -102.880922)
		(end 60.264548 -108.815378)
		(width 0.1143)
		(layer "In9.Cu")
		(net "P3E_CPU1_PE3_MP_RXP<0>")
	)
	(segment
		(start 51.59121 -79.194406)
		(end 56.30799 -102.880922)
		(width 0.1143)
		(layer "In9.Cu")
		(net "P3E_CPU1_PE3_MP_RXP<0>")
	)
	(segment
		(start 29.78785 -47.027592)
		(end 32.01289 -44.418504)
		(width 0.1143)
		(layer "In9.Cu")
		(net "P3E_CPU1_PE3_MP_RXP<0>")
	)
	(segment
		(start 140.84554 -90.77198)
		(end 140.66774 -90.77198)
		(width 0.0889)
		(layer "In9.Cu")
		(net "P3E_CPU1_PE3_MP_RXP<0>")
	)
	(segment
		(start 127.390398 -92.156534)
		(end 127.357632 -92.156534)
		(width 0.0889)
		(layer "In9.Cu")
		(net "P3E_CPU1_PE3_MP_RXP<0>")
	)
	(segment
		(start 141.989556 -91.459812)
		(end 141.8463 -91.459812)
		(width 0.0889)
		(layer "In9.Cu")
		(net "P3E_CPU1_PE3_MP_RXP<0>")
	)
	(segment
		(start 39.476934 -44.363132)
		(end 39.519606 -44.375578)
		(width 0.1143)
		(layer "In9.Cu")
		(net "P3E_CPU1_PE3_MP_RXP<0>")
	)
	(segment
		(start 125.305058 -97.309686)
		(end 125.300232 -97.318322)
		(width 0.0889)
		(layer "In9.Cu")
		(net "P3E_CPU1_PE3_MP_RXP<0>")
	)
	(segment
		(start 143.765524 -93.23578)
		(end 143.172942 -92.643198)
		(width 0.0889)
		(layer "In9.Cu")
		(net "P3E_CPU1_PE3_MP_RXP<0>")
	)
	(segment
		(start 106.3752 -115.899692)
		(end 106.711242 -115.832382)
		(width 0.1143)
		(layer "In9.Cu")
		(net "P3E_CPU1_PE3_MP_RXP<0>")
	)
	(segment
		(start 125.673358 -93.147134)
		(end 125.640592 -93.147134)
		(width 0.0889)
		(layer "In9.Cu")
		(net "P3E_CPU1_PE3_MP_RXP<0>")
	)
	(segment
		(start 53.31714 -65.618614)
		(end 53.31714 -70.566026)
		(width 0.1143)
		(layer "In9.Cu")
		(net "P3E_CPU1_PE3_MP_RXP<0>")
	)
	(segment
		(start 9.98982 -42.9514)
		(end 11.208766 -42.9514)
		(width 0.1143)
		(layer "In9.Cu")
		(net "P3E_CPU1_PE3_MP_RXP<0>")
	)
	(segment
		(start 142.509494 -91.97975)
		(end 142.384018 -91.854274)
		(width 0.0889)
		(layer "In9.Cu")
		(net "P3E_CPU1_PE3_MP_RXP<0>")
	)
	(segment
		(start 143.172942 -92.643198)
		(end 143.029686 -92.643198)
		(width 0.0889)
		(layer "In9.Cu")
		(net "P3E_CPU1_PE3_MP_RXP<0>")
	)
	(segment
		(start 141.326108 -90.93962)
		(end 141.326108 -90.796364)
		(width 0.0889)
		(layer "In9.Cu")
		(net "P3E_CPU1_PE3_MP_RXP<0>")
	)
	(segment
		(start 104.253284 -116.492782)
		(end 104.382824 -116.298472)
		(width 0.1143)
		(layer "In9.Cu")
		(net "P3E_CPU1_PE3_MP_RXP<0>")
	)
	(segment
		(start 39.519606 -44.375578)
		(end 39.51986 -44.375832)
		(width 0.1143)
		(layer "In9.Cu")
		(net "P3E_CPU1_PE3_MP_RXP<0>")
	)
	(segment
		(start 128.245108 -91.661488)
		(end 128.212342 -91.661488)
		(width 0.0889)
		(layer "In9.Cu")
		(net "P3E_CPU1_PE3_MP_RXP<0>")
	)
	(segment
		(start 25.940004 -45.715936)
		(end 25.940004 -45.71619)
		(width 0.1143)
		(layer "In9.Cu")
		(net "P3E_CPU1_PE3_MP_RXP<0>")
	)
	(segment
		(start 141.451838 -91.06535)
		(end 141.326108 -90.93962)
		(width 0.0889)
		(layer "In9.Cu")
		(net "P3E_CPU1_PE3_MP_RXP<0>")
	)
	(segment
		(start 129.962148 -90.670888)
		(end 129.929382 -90.670888)
		(width 0.0889)
		(layer "In9.Cu")
		(net "P3E_CPU1_PE3_MP_RXP<0>")
	)
	(segment
		(start 141.72057 -91.334082)
		(end 141.72057 -91.190826)
		(width 0.0889)
		(layer "In9.Cu")
		(net "P3E_CPU1_PE3_MP_RXP<0>")
	)
	(segment
		(start 134.620762 -116.781326)
		(end 144.60982 -106.792268)
		(width 0.1143)
		(layer "In9.Cu")
		(net "P3E_CPU1_PE3_MP_RXP<0>")
	)
	(segment
		(start -3.0734 -40.5638)
		(end -1.397 -42.2402)
		(width 0.1143)
		(layer "In9.Cu")
		(net "P3E_CPU1_PE3_MP_RXP<0>")
	)
	(segment
		(start 25.940004 -45.71619)
		(end 26.763472 -45.54474)
		(width 0.1143)
		(layer "In9.Cu")
		(net "P3E_CPU1_PE3_MP_RXP<0>")
	)
	(segment
		(start 141.326108 -90.796364)
		(end 141.200632 -90.670888)
		(width 0.0889)
		(layer "In9.Cu")
		(net "P3E_CPU1_PE3_MP_RXP<0>")
	)
	(segment
		(start 27.957018 -46.589442)
		(end 28.38577 -47.013114)
		(width 0.1143)
		(layer "In9.Cu")
		(net "P3E_CPU1_PE3_MP_RXP<0>")
	)
	(segment
		(start 125.311408 -98.289618)
		(end 125.305058 -98.300286)
		(width 0.0889)
		(layer "In9.Cu")
		(net "P3E_CPU1_PE3_MP_RXP<0>")
	)
	(segment
		(start 142.903956 -92.374212)
		(end 142.77848 -92.248736)
		(width 0.0889)
		(layer "In9.Cu")
		(net "P3E_CPU1_PE3_MP_RXP<0>")
	)
	(segment
		(start 141.200632 -90.670888)
		(end 140.946632 -90.670888)
		(width 0.0889)
		(layer "In9.Cu")
		(net "P3E_CPU1_PE3_MP_RXP<0>")
	)
	(segment
		(start 135.11022 -90.670888)
		(end 135.077454 -90.670888)
		(width 0.0889)
		(layer "In9.Cu")
		(net "P3E_CPU1_PE3_MP_RXP<0>")
	)
	(segment
		(start 143.765524 -93.307916)
		(end 143.765524 -93.23578)
		(width 0.0889)
		(layer "In9.Cu")
		(net "P3E_CPU1_PE3_MP_RXP<0>")
	)
	(segment
		(start 142.384018 -91.854274)
		(end 142.240762 -91.854274)
		(width 0.0889)
		(layer "In9.Cu")
		(net "P3E_CPU1_PE3_MP_RXP<0>")
	)
	(segment
		(start 143.781018 -93.32341)
		(end 143.765524 -93.307916)
		(width 0.0889)
		(layer "In9.Cu")
		(net "P3E_CPU1_PE3_MP_RXP<0>")
	)
	(segment
		(start 128.209548 -100.386134)
		(end 128.245108 -100.386134)
		(width 0.0889)
		(layer "In9.Cu")
		(net "P3E_CPU1_PE3_MP_RXP<0>")
	)
	(segment
		(start 125.305058 -96.319086)
		(end 125.300232 -96.327722)
		(width 0.0889)
		(layer "In9.Cu")
		(net "P3E_CPU1_PE3_MP_RXP<0>")
	)
	(segment
		(start 123.147582 -119.075708)
		(end 134.620762 -116.781326)
		(width 0.1143)
		(layer "In9.Cu")
		(net "P3E_CPU1_PE3_MP_RXP<0>")
	)
	(segment
		(start 90.958924 -116.17706)
		(end 98.400108 -117.664738)
		(width 0.1143)
		(layer "In9.Cu")
		(net "P3E_CPU1_PE3_MP_RXP<0>")
	)
	(segment
		(start 132.17652 -89.379044)
		(end 132.173218 -89.384886)
		(width 0.0889)
		(layer "In9.Cu")
		(net "P3E_CPU1_PE3_MP_RXP<0>")
	)
	(segment
		(start 141.72057 -91.190826)
		(end 141.595094 -91.06535)
		(width 0.0889)
		(layer "In9.Cu")
		(net "P3E_CPU1_PE3_MP_RXP<0>")
	)
	(segment
		(start 105.249472 -116.293392)
		(end 105.378758 -116.099082)
		(width 0.1143)
		(layer "In9.Cu")
		(net "P3E_CPU1_PE3_MP_RXP<0>")
	)
	(segment
		(start -2.500122 -39.710106)
		(end -3.0734 -40.283384)
		(width 0.1143)
		(layer "In9.Cu")
		(net "P3E_CPU1_PE3_MP_RXP<0>")
	)
	(segment
		(start 16.21155 -43.946318)
		(end 17.090898 -43.946318)
		(width 0.1143)
		(layer "In9.Cu")
		(net "P3E_CPU1_PE3_MP_RXP<0>")
	)
	(segment
		(start 125.311408 -96.308418)
		(end 125.305058 -96.319086)
		(width 0.0889)
		(layer "In9.Cu")
		(net "P3E_CPU1_PE3_MP_RXP<0>")
	)
	(segment
		(start 142.903956 -92.517468)
		(end 142.903956 -92.374212)
		(width 0.0889)
		(layer "In9.Cu")
		(net "P3E_CPU1_PE3_MP_RXP<0>")
	)
	(segment
		(start 105.715054 -116.031772)
		(end 105.909364 -116.161312)
		(width 0.1143)
		(layer "In9.Cu")
		(net "P3E_CPU1_PE3_MP_RXP<0>")
	)
	(segment
		(start 140.566648 -90.670888)
		(end 140.231368 -90.670888)
		(width 0.0889)
		(layer "In9.Cu")
		(net "P3E_CPU1_PE3_MP_RXP<0>")
	)
	(segment
		(start 104.382824 -116.298472)
		(end 104.718866 -116.231162)
		(width 0.1143)
		(layer "In9.Cu")
		(net "P3E_CPU1_PE3_MP_RXP<0>")
	)
	(segment
		(start 105.909364 -116.161312)
		(end 106.24566 -116.094002)
		(width 0.1143)
		(layer "In9.Cu")
		(net "P3E_CPU1_PE3_MP_RXP<0>")
	)
	(segment
		(start 11.208766 -42.9514)
		(end 16.21155 -43.946318)
		(width 0.1143)
		(layer "In9.Cu")
		(net "P3E_CPU1_PE3_MP_RXP<0>")
	)
	(segment
		(start 29.785818 -47.028354)
		(end 29.78658 -47.0281)
		(width 0.1143)
		(layer "In9.Cu")
		(net "P3E_CPU1_PE3_MP_RXP<0>")
	)
	(segment
		(start 107.241848 -115.894612)
		(end 123.147582 -119.075708)
		(width 0.1143)
		(layer "In9.Cu")
		(net "P3E_CPU1_PE3_MP_RXP<0>")
	)
	(segment
		(start 141.8463 -91.459812)
		(end 141.72057 -91.334082)
		(width 0.0889)
		(layer "In9.Cu")
		(net "P3E_CPU1_PE3_MP_RXP<0>")
	)
	(segment
		(start 106.905552 -115.961922)
		(end 107.241848 -115.894612)
		(width 0.1143)
		(layer "In9.Cu")
		(net "P3E_CPU1_PE3_MP_RXP<0>")
	)
	(segment
		(start 39.472616 -44.361862)
		(end 39.475664 -44.362878)
		(width 0.1143)
		(layer "In9.Cu")
		(net "P3E_CPU1_PE3_MP_RXP<0>")
	)
	(arc
		(start 125.300232 -98.308922)
		(mid 125.251477 -98.505274)
		(end 125.305058 -98.700336)
		(width 0.0889)
		(layer "In9.Cu")
		(net "P3E_CPU1_PE3_MP_RXP<0>")
	)
	(arc
		(start 125.305058 -93.747336)
		(mid 125.384189 -94.042738)
		(end 125.305058 -94.33814)
		(width 0.0889)
		(layer "In9.Cu")
		(net "P3E_CPU1_PE3_MP_RXP<0>")
	)
	(arc
		(start 125.640592 -93.147134)
		(mid 125.302423 -93.351932)
		(end 125.305058 -93.747336)
		(width 0.0889)
		(layer "In9.Cu")
		(net "P3E_CPU1_PE3_MP_RXP<0>")
	)
	(arc
		(start 130.456178 -90.375486)
		(mid 130.24757 -90.587418)
		(end 129.962148 -90.670888)
		(width 0.0889)
		(layer "In9.Cu")
		(net "P3E_CPU1_PE3_MP_RXP<0>")
	)
	(arc
		(start 127.880618 -91.861386)
		(mid 127.673614 -92.07225)
		(end 127.390398 -92.156534)
		(width 0.0889)
		(layer "In9.Cu")
		(net "P3E_CPU1_PE3_MP_RXP<0>")
	)
	(arc
		(start 128.739138 -91.366086)
		(mid 128.53053 -91.578018)
		(end 128.245108 -91.661488)
		(width 0.0889)
		(layer "In9.Cu")
		(net "P3E_CPU1_PE3_MP_RXP<0>")
	)
	(arc
		(start 137.682732 -90.175334)
		(mid 137.670794 -90.175156)
		(end 137.658856 -90.175334)
		(width 0.0889)
		(layer "In9.Cu")
		(net "P3E_CPU1_PE3_MP_RXP<0>")
	)
	(arc
		(start 125.300232 -99.299522)
		(mid 125.303979 -99.688778)
		(end 125.636782 -99.890834)
		(width 0.0889)
		(layer "In9.Cu")
		(net "P3E_CPU1_PE3_MP_RXP<0>")
	)
	(arc
		(start 125.305058 -95.728536)
		(mid 125.38428 -96.017654)
		(end 125.311408 -96.308418)
		(width 0.0889)
		(layer "In9.Cu")
		(net "P3E_CPU1_PE3_MP_RXP<0>")
	)
	(arc
		(start 139.366244 -91.165934)
		(mid 139.083027 -91.081653)
		(end 138.876024 -90.870786)
		(width 0.0889)
		(layer "In9.Cu")
		(net "P3E_CPU1_PE3_MP_RXP<0>")
	)
	(arc
		(start 127.715518 -100.681536)
		(mid 127.924126 -100.469604)
		(end 128.209548 -100.386134)
		(width 0.0889)
		(layer "In9.Cu")
		(net "P3E_CPU1_PE3_MP_RXP<0>")
	)
	(arc
		(start 126.163578 -92.851986)
		(mid 125.956574 -93.06285)
		(end 125.673358 -93.147134)
		(width 0.0889)
		(layer "In9.Cu")
		(net "P3E_CPU1_PE3_MP_RXP<0>")
	)
	(arc
		(start 128.245108 -100.386134)
		(mid 128.50193 -100.453435)
		(end 128.703324 -100.626418)
		(width 0.0889)
		(layer "In9.Cu")
		(net "P3E_CPU1_PE3_MP_RXP<0>")
	)
	(arc
		(start 125.305058 -94.33814)
		(mid 125.251559 -94.538038)
		(end 125.305058 -94.737936)
		(width 0.0889)
		(layer "In9.Cu")
		(net "P3E_CPU1_PE3_MP_RXP<0>")
	)
	(arc
		(start 135.077454 -90.670888)
		(mid 134.79203 -90.587421)
		(end 134.583424 -90.375486)
		(width 0.0889)
		(layer "In9.Cu")
		(net "P3E_CPU1_PE3_MP_RXP<0>")
	)
	(arc
		(start 127.022098 -100.681536)
		(mid 127.368808 -100.881847)
		(end 127.715518 -100.681536)
		(width 0.0889)
		(layer "In9.Cu")
		(net "P3E_CPU1_PE3_MP_RXP<0>")
	)
	(arc
		(start 127.357632 -92.156534)
		(mid 127.163782 -92.212884)
		(end 127.022098 -92.356686)
		(width 0.0889)
		(layer "In9.Cu")
		(net "P3E_CPU1_PE3_MP_RXP<0>")
	)
	(arc
		(start 126.163578 -100.186236)
		(mid 126.302322 -100.328269)
		(end 126.492254 -100.386134)
		(width 0.0889)
		(layer "In9.Cu")
		(net "P3E_CPU1_PE3_MP_RXP<0>")
	)
	(arc
		(start 138.017504 -90.375486)
		(mid 137.876148 -90.231877)
		(end 137.682732 -90.175334)
		(width 0.0889)
		(layer "In9.Cu")
		(net "P3E_CPU1_PE3_MP_RXP<0>")
	)
	(arc
		(start 125.664722 -99.890834)
		(mid 125.952867 -99.973153)
		(end 126.163578 -100.186236)
		(width 0.0889)
		(layer "In9.Cu")
		(net "P3E_CPU1_PE3_MP_RXP<0>")
	)
	(arc
		(start 140.231368 -90.670888)
		(mid 140.039726 -90.728054)
		(end 139.899644 -90.870786)
		(width 0.0889)
		(layer "In9.Cu")
		(net "P3E_CPU1_PE3_MP_RXP<0>")
	)
	(arc
		(start 132.173218 -89.384886)
		(mid 131.96461 -89.596818)
		(end 131.679188 -89.680288)
		(width 0.0889)
		(layer "In9.Cu")
		(net "P3E_CPU1_PE3_MP_RXP<0>")
	)
	(arc
		(start 134.215124 -90.175334)
		(mid 133.931907 -90.091053)
		(end 133.724904 -89.880186)
		(width 0.0889)
		(layer "In9.Cu")
		(net "P3E_CPU1_PE3_MP_RXP<0>")
	)
	(arc
		(start 136.465564 -90.870786)
		(mid 136.25856 -91.08165)
		(end 135.975344 -91.165934)
		(width 0.0889)
		(layer "In9.Cu")
		(net "P3E_CPU1_PE3_MP_RXP<0>")
	)
	(arc
		(start 125.305058 -97.709736)
		(mid 125.38428 -97.998854)
		(end 125.311408 -98.289618)
		(width 0.0889)
		(layer "In9.Cu")
		(net "P3E_CPU1_PE3_MP_RXP<0>")
	)
	(arc
		(start 131.314698 -89.880186)
		(mid 131.107694 -90.09105)
		(end 130.824478 -90.175334)
		(width 0.0889)
		(layer "In9.Cu")
		(net "P3E_CPU1_PE3_MP_RXP<0>")
	)
	(arc
		(start 137.658856 -90.175334)
		(mid 137.46543 -90.231861)
		(end 137.324084 -90.375486)
		(width 0.0889)
		(layer "In9.Cu")
		(net "P3E_CPU1_PE3_MP_RXP<0>")
	)
	(arc
		(start 134.583424 -90.375486)
		(mid 134.441741 -90.231682)
		(end 134.24789 -90.175334)
		(width 0.0889)
		(layer "In9.Cu")
		(net "P3E_CPU1_PE3_MP_RXP<0>")
	)
	(arc
		(start 138.511534 -90.670888)
		(mid 138.22611 -90.587421)
		(end 138.017504 -90.375486)
		(width 0.0889)
		(layer "In9.Cu")
		(net "P3E_CPU1_PE3_MP_RXP<0>")
	)
	(arc
		(start 125.300232 -97.318322)
		(mid 125.251477 -97.514674)
		(end 125.305058 -97.709736)
		(width 0.0889)
		(layer "In9.Cu")
		(net "P3E_CPU1_PE3_MP_RXP<0>")
	)
	(arc
		(start 138.876024 -90.870786)
		(mid 138.735945 -90.72805)
		(end 138.5443 -90.670888)
		(width 0.0889)
		(layer "In9.Cu")
		(net "P3E_CPU1_PE3_MP_RXP<0>")
	)
	(arc
		(start 133.360414 -89.680288)
		(mid 133.07499 -89.596821)
		(end 132.866384 -89.384886)
		(width 0.0889)
		(layer "In9.Cu")
		(net "P3E_CPU1_PE3_MP_RXP<0>")
	)
	(arc
		(start 135.932164 -91.165934)
		(mid 135.648947 -91.081653)
		(end 135.441944 -90.870786)
		(width 0.0889)
		(layer "In9.Cu")
		(net "P3E_CPU1_PE3_MP_RXP<0>")
	)
	(arc
		(start 125.300232 -96.327722)
		(mid 125.251477 -96.524074)
		(end 125.305058 -96.719136)
		(width 0.0889)
		(layer "In9.Cu")
		(net "P3E_CPU1_PE3_MP_RXP<0>")
	)
	(arc
		(start 128.212342 -91.661488)
		(mid 128.0207 -91.718654)
		(end 127.880618 -91.861386)
		(width 0.0889)
		(layer "In9.Cu")
		(net "P3E_CPU1_PE3_MP_RXP<0>")
	)
	(arc
		(start 133.724904 -89.880186)
		(mid 133.584825 -89.73745)
		(end 133.39318 -89.680288)
		(width 0.0889)
		(layer "In9.Cu")
		(net "P3E_CPU1_PE3_MP_RXP<0>")
	)
	(arc
		(start 135.441944 -90.870786)
		(mid 135.301865 -90.72805)
		(end 135.11022 -90.670888)
		(width 0.0889)
		(layer "In9.Cu")
		(net "P3E_CPU1_PE3_MP_RXP<0>")
	)
	(arc
		(start 139.899644 -90.870786)
		(mid 139.69264 -91.08165)
		(end 139.409424 -91.165934)
		(width 0.0889)
		(layer "In9.Cu")
		(net "P3E_CPU1_PE3_MP_RXP<0>")
	)
	(arc
		(start 131.646422 -89.680288)
		(mid 131.45478 -89.737454)
		(end 131.314698 -89.880186)
		(width 0.0889)
		(layer "In9.Cu")
		(net "P3E_CPU1_PE3_MP_RXP<0>")
	)
	(arc
		(start 127.022098 -92.356686)
		(mid 126.81349 -92.568618)
		(end 126.528068 -92.652088)
		(width 0.0889)
		(layer "In9.Cu")
		(net "P3E_CPU1_PE3_MP_RXP<0>")
	)
	(arc
		(start 129.929382 -90.670888)
		(mid 129.73774 -90.728054)
		(end 129.597658 -90.870786)
		(width 0.0889)
		(layer "In9.Cu")
		(net "P3E_CPU1_PE3_MP_RXP<0>")
	)
	(arc
		(start 125.300232 -95.337122)
		(mid 125.251477 -95.533474)
		(end 125.305058 -95.728536)
		(width 0.0889)
		(layer "In9.Cu")
		(net "P3E_CPU1_PE3_MP_RXP<0>")
	)
	(arc
		(start 130.791712 -90.175334)
		(mid 130.597862 -90.231684)
		(end 130.456178 -90.375486)
		(width 0.0889)
		(layer "In9.Cu")
		(net "P3E_CPU1_PE3_MP_RXP<0>")
	)
	(arc
		(start 132.866384 -89.384886)
		(mid 132.523094 -89.184463)
		(end 132.17652 -89.379044)
		(width 0.0889)
		(layer "In9.Cu")
		(net "P3E_CPU1_PE3_MP_RXP<0>")
	)
	(arc
		(start 129.597658 -90.870786)
		(mid 129.390654 -91.08165)
		(end 129.107438 -91.165934)
		(width 0.0889)
		(layer "In9.Cu")
		(net "P3E_CPU1_PE3_MP_RXP<0>")
	)
	(arc
		(start 126.495302 -92.652088)
		(mid 126.30366 -92.709254)
		(end 126.163578 -92.851986)
		(width 0.0889)
		(layer "In9.Cu")
		(net "P3E_CPU1_PE3_MP_RXP<0>")
	)
	(arc
		(start 137.324084 -90.375486)
		(mid 137.115476 -90.587418)
		(end 136.830054 -90.670888)
		(width 0.0889)
		(layer "In9.Cu")
		(net "P3E_CPU1_PE3_MP_RXP<0>")
	)
	(arc
		(start 136.797288 -90.670888)
		(mid 136.605646 -90.728054)
		(end 136.465564 -90.870786)
		(width 0.0889)
		(layer "In9.Cu")
		(net "P3E_CPU1_PE3_MP_RXP<0>")
	)
	(arc
		(start 125.305058 -96.719136)
		(mid 125.38428 -97.008254)
		(end 125.311408 -97.299018)
		(width 0.0889)
		(layer "In9.Cu")
		(net "P3E_CPU1_PE3_MP_RXP<0>")
	)
	(arc
		(start 125.305058 -98.700336)
		(mid 125.38428 -98.989454)
		(end 125.311408 -99.280218)
		(width 0.0889)
		(layer "In9.Cu")
		(net "P3E_CPU1_PE3_MP_RXP<0>")
	)
	(arc
		(start 125.311408 -94.748604)
		(mid 125.384206 -95.039367)
		(end 125.305058 -95.328486)
		(width 0.0889)
		(layer "In9.Cu")
		(net "P3E_CPU1_PE3_MP_RXP<0>")
	)
	(arc
		(start 129.074672 -91.165934)
		(mid 128.880822 -91.222284)
		(end 128.739138 -91.366086)
		(width 0.0889)
		(layer "In9.Cu")
		(net "P3E_CPU1_PE3_MP_RXP<0>")
	)
	(arc
		(start 126.528068 -100.386134)
		(mid 126.813492 -100.469601)
		(end 127.022098 -100.681536)
		(width 0.0889)
		(layer "In9.Cu")
		(net "P3E_CPU1_PE3_MP_RXP<0>")
	)
	(segment
		(start 131.089908 -96.023938)
		(end 131.661408 -96.023938)
		(width 0.1143)
		(layer "F.Cu")
		(net "P3E_CPU1_PE3_MP_RXN<7>")
	)
	(via
		(at 131.661408 -96.023938)
		(size 0.508)
		(drill 0.254)
		(layers "F.Cu" "B.Cu")
		(net "P3E_CPU1_PE3_MP_RXN<7>")
	)
	(segment
		(start 137.659618 -96.118934)
		(end 137.68197 -96.118934)
		(width 0.0889)
		(layer "In9.Cu")
		(net "P3E_CPU1_PE3_MP_RXN<7>")
	)
	(segment
		(start 0.487934 -35.710114)
		(end 0.299974 -35.710114)
		(width 0.1143)
		(layer "In9.Cu")
		(net "P3E_CPU1_PE3_MP_RXN<7>")
	)
	(segment
		(start 139.469114 -104.469184)
		(end 139.469114 -104.591358)
		(width 0.0889)
		(layer "In9.Cu")
		(net "P3E_CPU1_PE3_MP_RXN<7>")
	)
	(segment
		(start 59.148472 -89.286588)
		(end 61.634624 -76.856082)
		(width 0.1143)
		(layer "In9.Cu")
		(net "P3E_CPU1_PE3_MP_RXN<7>")
	)
	(segment
		(start 62.002416 -103.394764)
		(end 61.956188 -103.325168)
		(width 0.1143)
		(layer "In9.Cu")
		(net "P3E_CPU1_PE3_MP_RXN<7>")
	)
	(segment
		(start 123.09983 -114.926872)
		(end 117.229382 -113.759234)
		(width 0.1143)
		(layer "In9.Cu")
		(net "P3E_CPU1_PE3_MP_RXN<7>")
	)
	(segment
		(start 12.68984 -37.4142)
		(end 11.787886 -37.4142)
		(width 0.1143)
		(layer "In9.Cu")
		(net "P3E_CPU1_PE3_MP_RXN<7>")
	)
	(segment
		(start 135.932164 -97.109534)
		(end 135.975344 -97.109534)
		(width 0.0889)
		(layer "In9.Cu")
		(net "P3E_CPU1_PE3_MP_RXN<7>")
	)
	(segment
		(start 74.325226 -110.267242)
		(end 68.710556 -109.144054)
		(width 0.1143)
		(layer "In9.Cu")
		(net "P3E_CPU1_PE3_MP_RXN<7>")
	)
	(segment
		(start 136.797288 -96.614488)
		(end 136.830054 -96.614488)
		(width 0.0889)
		(layer "In9.Cu")
		(net "P3E_CPU1_PE3_MP_RXN<7>")
	)
	(segment
		(start 92.783152 -110.368842)
		(end 83.300062 -108.472478)
		(width 0.1143)
		(layer "In9.Cu")
		(net "P3E_CPU1_PE3_MP_RXN<7>")
	)
	(segment
		(start 139.842748 -102.570788)
		(end 139.842748 -102.803452)
		(width 0.0889)
		(layer "In9.Cu")
		(net "P3E_CPU1_PE3_MP_RXN<7>")
	)
	(segment
		(start 1.188212 -34.564066)
		(end 0.8255 -34.926778)
		(width 0.1143)
		(layer "In9.Cu")
		(net "P3E_CPU1_PE3_MP_RXN<7>")
	)
	(segment
		(start 135.077454 -96.614488)
		(end 135.11022 -96.614488)
		(width 0.0889)
		(layer "In9.Cu")
		(net "P3E_CPU1_PE3_MP_RXN<7>")
	)
	(segment
		(start 28.373832 -39.366952)
		(end 28.373578 -39.366952)
		(width 0.1143)
		(layer "In9.Cu")
		(net "P3E_CPU1_PE3_MP_RXN<7>")
	)
	(segment
		(start 138.199876 -105.788714)
		(end 130.543046 -113.445544)
		(width 0.1143)
		(layer "In9.Cu")
		(net "P3E_CPU1_PE3_MP_RXN<7>")
	)
	(segment
		(start 8.946642 -35.394646)
		(end 8.6614 -35.2044)
		(width 0.1143)
		(layer "In9.Cu")
		(net "P3E_CPU1_PE3_MP_RXN<7>")
	)
	(segment
		(start 133.363208 -95.623888)
		(end 133.39318 -95.623888)
		(width 0.0889)
		(layer "In9.Cu")
		(net "P3E_CPU1_PE3_MP_RXN<7>")
	)
	(segment
		(start 59.706256 -67.212718)
		(end 59.100212 -64.180974)
		(width 0.1143)
		(layer "In9.Cu")
		(net "P3E_CPU1_PE3_MP_RXN<7>")
	)
	(segment
		(start 10.988802 -37.245544)
		(end 10.122154 -36.378642)
		(width 0.1143)
		(layer "In9.Cu")
		(net "P3E_CPU1_PE3_MP_RXN<7>")
	)
	(segment
		(start 9.506458 -35.768788)
		(end 9.27735 -35.814254)
		(width 0.1143)
		(layer "In9.Cu")
		(net "P3E_CPU1_PE3_MP_RXN<7>")
	)
	(segment
		(start 139.741656 -103.462328)
		(end 139.741656 -103.640128)
		(width 0.0889)
		(layer "In9.Cu")
		(net "P3E_CPU1_PE3_MP_RXN<7>")
	)
	(segment
		(start 96.472502 -109.630718)
		(end 92.783152 -110.368842)
		(width 0.1143)
		(layer "In9.Cu")
		(net "P3E_CPU1_PE3_MP_RXN<7>")
	)
	(segment
		(start 17.31137 -39.859966)
		(end 15.231872 -38.99916)
		(width 0.1143)
		(layer "In9.Cu")
		(net "P3E_CPU1_PE3_MP_RXN<7>")
	)
	(segment
		(start 59.706256 -67.602862)
		(end 59.706256 -67.212718)
		(width 0.1143)
		(layer "In9.Cu")
		(net "P3E_CPU1_PE3_MP_RXN<7>")
	)
	(segment
		(start 61.956188 -103.325168)
		(end 59.148472 -89.286588)
		(width 0.1143)
		(layer "In9.Cu")
		(net "P3E_CPU1_PE3_MP_RXN<7>")
	)
	(segment
		(start 117.229382 -113.759234)
		(end 117.099588 -113.565178)
		(width 0.1143)
		(layer "In9.Cu")
		(net "P3E_CPU1_PE3_MP_RXN<7>")
	)
	(segment
		(start 138.721846 -105.216452)
		(end 138.721846 -105.338626)
		(width 0.0889)
		(layer "In9.Cu")
		(net "P3E_CPU1_PE3_MP_RXN<7>")
	)
	(segment
		(start 7.850124 -34.860738)
		(end 7.134098 -34.564066)
		(width 0.1143)
		(layer "In9.Cu")
		(net "P3E_CPU1_PE3_MP_RXN<7>")
	)
	(segment
		(start 83.300062 -108.472478)
		(end 74.325226 -110.267242)
		(width 0.1143)
		(layer "In9.Cu")
		(net "P3E_CPU1_PE3_MP_RXN<7>")
	)
	(segment
		(start 139.741656 -102.904544)
		(end 139.741656 -103.082344)
		(width 0.0889)
		(layer "In9.Cu")
		(net "P3E_CPU1_PE3_MP_RXN<7>")
	)
	(segment
		(start 68.710556 -109.144054)
		(end 63.51524 -105.681018)
		(width 0.1143)
		(layer "In9.Cu")
		(net "P3E_CPU1_PE3_MP_RXN<7>")
	)
	(segment
		(start 117.099588 -113.565178)
		(end 116.763292 -113.498376)
		(width 0.1143)
		(layer "In9.Cu")
		(net "P3E_CPU1_PE3_MP_RXN<7>")
	)
	(segment
		(start 139.595098 -104.3432)
		(end 139.469114 -104.469184)
		(width 0.0889)
		(layer "In9.Cu")
		(net "P3E_CPU1_PE3_MP_RXN<7>")
	)
	(segment
		(start 139.696698 -101.008942)
		(end 139.601702 -101.103938)
		(width 0.0889)
		(layer "In9.Cu")
		(net "P3E_CPU1_PE3_MP_RXN<7>")
	)
	(segment
		(start 139.843256 -102.563676)
		(end 139.842748 -102.570788)
		(width 0.0889)
		(layer "In9.Cu")
		(net "P3E_CPU1_PE3_MP_RXN<7>")
	)
	(segment
		(start 131.661408 -95.685864)
		(end 131.719066 -95.628206)
		(width 0.0889)
		(layer "In9.Cu")
		(net "P3E_CPU1_PE3_MP_RXN<7>")
	)
	(segment
		(start 8.992108 -35.623754)
		(end 8.946642 -35.394646)
		(width 0.1143)
		(layer "In9.Cu")
		(net "P3E_CPU1_PE3_MP_RXN<7>")
	)
	(segment
		(start 139.696698 -100.825046)
		(end 139.696698 -101.008942)
		(width 0.0889)
		(layer "In9.Cu")
		(net "P3E_CPU1_PE3_MP_RXN<7>")
	)
	(segment
		(start 139.736068 -99.69119)
		(end 139.729718 -99.701858)
		(width 0.0889)
		(layer "In9.Cu")
		(net "P3E_CPU1_PE3_MP_RXN<7>")
	)
	(segment
		(start 61.211714 -74.741278)
		(end 58.83402 -70.298818)
		(width 0.1143)
		(layer "In9.Cu")
		(net "P3E_CPU1_PE3_MP_RXN<7>")
	)
	(segment
		(start 139.842748 -103.183436)
		(end 139.842748 -103.361236)
		(width 0.0889)
		(layer "In9.Cu")
		(net "P3E_CPU1_PE3_MP_RXN<7>")
	)
	(segment
		(start 62.007496 -103.419402)
		(end 62.002416 -103.394764)
		(width 0.1143)
		(layer "In9.Cu")
		(net "P3E_CPU1_PE3_MP_RXN<7>")
	)
	(segment
		(start 14.323314 -38.090602)
		(end 12.68984 -37.4142)
		(width 0.1143)
		(layer "In9.Cu")
		(net "P3E_CPU1_PE3_MP_RXN<7>")
	)
	(segment
		(start 24.915622 -39.7891)
		(end 23.211028 -40.761412)
		(width 0.1143)
		(layer "In9.Cu")
		(net "P3E_CPU1_PE3_MP_RXN<7>")
	)
	(segment
		(start 138.721846 -105.338626)
		(end 138.287506 -105.772966)
		(width 0.0889)
		(layer "In9.Cu")
		(net "P3E_CPU1_PE3_MP_RXN<7>")
	)
	(segment
		(start 139.842748 -102.803452)
		(end 139.741656 -102.904544)
		(width 0.0889)
		(layer "In9.Cu")
		(net "P3E_CPU1_PE3_MP_RXN<7>")
	)
	(segment
		(start 10.122154 -36.378642)
		(end 9.836912 -36.188142)
		(width 0.1143)
		(layer "In9.Cu")
		(net "P3E_CPU1_PE3_MP_RXN<7>")
	)
	(segment
		(start 9.27735 -35.814254)
		(end 8.992108 -35.623754)
		(width 0.1143)
		(layer "In9.Cu")
		(net "P3E_CPU1_PE3_MP_RXN<7>")
	)
	(segment
		(start 139.221464 -104.716834)
		(end 139.09548 -104.842818)
		(width 0.0889)
		(layer "In9.Cu")
		(net "P3E_CPU1_PE3_MP_RXN<7>")
	)
	(segment
		(start 139.842748 -103.74122)
		(end 139.842748 -104.217724)
		(width 0.0889)
		(layer "In9.Cu")
		(net "P3E_CPU1_PE3_MP_RXN<7>")
	)
	(segment
		(start 138.21537 -105.772966)
		(end 138.199876 -105.78846)
		(width 0.0889)
		(layer "In9.Cu")
		(net "P3E_CPU1_PE3_MP_RXN<7>")
	)
	(segment
		(start 116.763292 -113.498376)
		(end 116.569236 -113.627916)
		(width 0.1143)
		(layer "In9.Cu")
		(net "P3E_CPU1_PE3_MP_RXN<7>")
	)
	(segment
		(start 61.634624 -76.856082)
		(end 61.211714 -74.741278)
		(width 0.1143)
		(layer "In9.Cu")
		(net "P3E_CPU1_PE3_MP_RXN<7>")
	)
	(segment
		(start 28.373578 -39.366952)
		(end 27.82443 -39.7891)
		(width 0.1143)
		(layer "In9.Cu")
		(net "P3E_CPU1_PE3_MP_RXN<7>")
	)
	(segment
		(start 139.469114 -104.591358)
		(end 139.343638 -104.716834)
		(width 0.0889)
		(layer "In9.Cu")
		(net "P3E_CPU1_PE3_MP_RXN<7>")
	)
	(segment
		(start 139.741656 -103.082344)
		(end 139.842748 -103.183436)
		(width 0.0889)
		(layer "In9.Cu")
		(net "P3E_CPU1_PE3_MP_RXN<7>")
	)
	(segment
		(start 134.215124 -96.118934)
		(end 134.24789 -96.118934)
		(width 0.0889)
		(layer "In9.Cu")
		(net "P3E_CPU1_PE3_MP_RXN<7>")
	)
	(segment
		(start 138.970004 -105.090468)
		(end 138.84783 -105.090468)
		(width 0.0889)
		(layer "In9.Cu")
		(net "P3E_CPU1_PE3_MP_RXN<7>")
	)
	(segment
		(start 139.740894 -97.701354)
		(end 139.736068 -97.70999)
		(width 0.0889)
		(layer "In9.Cu")
		(net "P3E_CPU1_PE3_MP_RXN<7>")
	)
	(segment
		(start 131.661408 -96.023938)
		(end 131.661408 -95.685864)
		(width 0.0889)
		(layer "In9.Cu")
		(net "P3E_CPU1_PE3_MP_RXN<7>")
	)
	(segment
		(start 139.741656 -103.640128)
		(end 139.842748 -103.74122)
		(width 0.0889)
		(layer "In9.Cu")
		(net "P3E_CPU1_PE3_MP_RXN<7>")
	)
	(segment
		(start 22.904958 -40.815514)
		(end 17.31137 -39.859966)
		(width 0.1143)
		(layer "In9.Cu")
		(net "P3E_CPU1_PE3_MP_RXN<7>")
	)
	(segment
		(start 53.745892 -48.97628)
		(end 41.72331 -40.961818)
		(width 0.1143)
		(layer "In9.Cu")
		(net "P3E_CPU1_PE3_MP_RXN<7>")
	)
	(segment
		(start 11.787886 -37.4142)
		(end 10.988802 -37.245544)
		(width 0.1143)
		(layer "In9.Cu")
		(net "P3E_CPU1_PE3_MP_RXN<7>")
	)
	(segment
		(start 138.199876 -105.78846)
		(end 138.199876 -105.788714)
		(width 0.0889)
		(layer "In9.Cu")
		(net "P3E_CPU1_PE3_MP_RXN<7>")
	)
	(segment
		(start 139.09548 -104.842818)
		(end 139.09548 -104.964992)
		(width 0.0889)
		(layer "In9.Cu")
		(net "P3E_CPU1_PE3_MP_RXN<7>")
	)
	(segment
		(start 58.83402 -68.475098)
		(end 59.706256 -67.602862)
		(width 0.1143)
		(layer "In9.Cu")
		(net "P3E_CPU1_PE3_MP_RXN<7>")
	)
	(segment
		(start 59.100212 -64.180974)
		(end 59.998864 -59.684412)
		(width 0.1143)
		(layer "In9.Cu")
		(net "P3E_CPU1_PE3_MP_RXN<7>")
	)
	(segment
		(start 139.696698 -101.376734)
		(end 139.696698 -101.981)
		(width 0.0889)
		(layer "In9.Cu")
		(net "P3E_CPU1_PE3_MP_RXN<7>")
	)
	(segment
		(start 139.09548 -104.964992)
		(end 138.970004 -105.090468)
		(width 0.0889)
		(layer "In9.Cu")
		(net "P3E_CPU1_PE3_MP_RXN<7>")
	)
	(segment
		(start 139.371324 -97.110042)
		(end 139.40409 -97.110042)
		(width 0.0889)
		(layer "In9.Cu")
		(net "P3E_CPU1_PE3_MP_RXN<7>")
	)
	(segment
		(start 63.51524 -105.681018)
		(end 62.007496 -103.419402)
		(width 0.1143)
		(layer "In9.Cu")
		(net "P3E_CPU1_PE3_MP_RXN<7>")
	)
	(segment
		(start 139.601702 -101.281738)
		(end 139.696698 -101.376734)
		(width 0.0889)
		(layer "In9.Cu")
		(net "P3E_CPU1_PE3_MP_RXN<7>")
	)
	(segment
		(start 23.211028 -40.761412)
		(end 22.904958 -40.815514)
		(width 0.1143)
		(layer "In9.Cu")
		(net "P3E_CPU1_PE3_MP_RXN<7>")
	)
	(segment
		(start 139.842748 -104.217724)
		(end 139.717272 -104.3432)
		(width 0.0889)
		(layer "In9.Cu")
		(net "P3E_CPU1_PE3_MP_RXN<7>")
	)
	(segment
		(start 138.84783 -105.090468)
		(end 138.721846 -105.216452)
		(width 0.0889)
		(layer "In9.Cu")
		(net "P3E_CPU1_PE3_MP_RXN<7>")
	)
	(segment
		(start 34.810954 -38.8239)
		(end 29.080714 -38.8239)
		(width 0.1143)
		(layer "In9.Cu")
		(net "P3E_CPU1_PE3_MP_RXN<7>")
	)
	(segment
		(start 139.740894 -100.673154)
		(end 139.736068 -100.68179)
		(width 0.0889)
		(layer "In9.Cu")
		(net "P3E_CPU1_PE3_MP_RXN<7>")
	)
	(segment
		(start 59.998864 -59.684412)
		(end 59.619134 -57.787032)
		(width 0.1143)
		(layer "In9.Cu")
		(net "P3E_CPU1_PE3_MP_RXN<7>")
	)
	(segment
		(start 8.6614 -35.2044)
		(end 8.432546 -35.249866)
		(width 0.1143)
		(layer "In9.Cu")
		(net "P3E_CPU1_PE3_MP_RXN<7>")
	)
	(segment
		(start 139.343638 -104.716834)
		(end 139.221464 -104.716834)
		(width 0.0889)
		(layer "In9.Cu")
		(net "P3E_CPU1_PE3_MP_RXN<7>")
	)
	(segment
		(start 59.619134 -57.787032)
		(end 53.745892 -48.97628)
		(width 0.1143)
		(layer "In9.Cu")
		(net "P3E_CPU1_PE3_MP_RXN<7>")
	)
	(segment
		(start 139.729718 -98.289872)
		(end 139.736068 -98.30054)
		(width 0.0889)
		(layer "In9.Cu")
		(net "P3E_CPU1_PE3_MP_RXN<7>")
	)
	(segment
		(start 7.134098 -34.564066)
		(end 1.188212 -34.564066)
		(width 0.1143)
		(layer "In9.Cu")
		(net "P3E_CPU1_PE3_MP_RXN<7>")
	)
	(segment
		(start 139.740894 -99.682554)
		(end 139.736068 -99.69119)
		(width 0.0889)
		(layer "In9.Cu")
		(net "P3E_CPU1_PE3_MP_RXN<7>")
	)
	(segment
		(start 116.569236 -113.627916)
		(end 96.472502 -109.630718)
		(width 0.1143)
		(layer "In9.Cu")
		(net "P3E_CPU1_PE3_MP_RXN<7>")
	)
	(segment
		(start 139.601702 -101.103938)
		(end 139.601702 -101.281738)
		(width 0.0889)
		(layer "In9.Cu")
		(net "P3E_CPU1_PE3_MP_RXN<7>")
	)
	(segment
		(start 138.287506 -105.772966)
		(end 138.21537 -105.772966)
		(width 0.0889)
		(layer "In9.Cu")
		(net "P3E_CPU1_PE3_MP_RXN<7>")
	)
	(segment
		(start 58.83402 -70.298818)
		(end 58.83402 -68.475098)
		(width 0.1143)
		(layer "In9.Cu")
		(net "P3E_CPU1_PE3_MP_RXN<7>")
	)
	(segment
		(start 29.080714 -38.8239)
		(end 28.373832 -39.366952)
		(width 0.1143)
		(layer "In9.Cu")
		(net "P3E_CPU1_PE3_MP_RXN<7>")
	)
	(segment
		(start 132.004562 -95.818198)
		(end 132.007864 -95.82404)
		(width 0.0889)
		(layer "In9.Cu")
		(net "P3E_CPU1_PE3_MP_RXN<7>")
	)
	(segment
		(start 27.82443 -39.7891)
		(end 24.915622 -39.7891)
		(width 0.1143)
		(layer "In9.Cu")
		(net "P3E_CPU1_PE3_MP_RXN<7>")
	)
	(segment
		(start 9.791446 -35.959034)
		(end 9.506458 -35.768788)
		(width 0.1143)
		(layer "In9.Cu")
		(net "P3E_CPU1_PE3_MP_RXN<7>")
	)
	(segment
		(start 0.8255 -35.372548)
		(end 0.487934 -35.710114)
		(width 0.1143)
		(layer "In9.Cu")
		(net "P3E_CPU1_PE3_MP_RXN<7>")
	)
	(segment
		(start 8.432546 -35.249866)
		(end 7.850124 -34.860738)
		(width 0.1143)
		(layer "In9.Cu")
		(net "P3E_CPU1_PE3_MP_RXN<7>")
	)
	(segment
		(start 41.72331 -40.961818)
		(end 34.810954 -38.8239)
		(width 0.1143)
		(layer "In9.Cu")
		(net "P3E_CPU1_PE3_MP_RXN<7>")
	)
	(segment
		(start 138.511534 -96.614488)
		(end 138.54176 -96.614488)
		(width 0.0889)
		(layer "In9.Cu")
		(net "P3E_CPU1_PE3_MP_RXN<7>")
	)
	(segment
		(start 130.543046 -113.445544)
		(end 123.09983 -114.926872)
		(width 0.1143)
		(layer "In9.Cu")
		(net "P3E_CPU1_PE3_MP_RXN<7>")
	)
	(segment
		(start 15.231872 -38.99916)
		(end 14.323314 -38.090602)
		(width 0.1143)
		(layer "In9.Cu")
		(net "P3E_CPU1_PE3_MP_RXN<7>")
	)
	(segment
		(start 0.8255 -34.926778)
		(end 0.8255 -35.372548)
		(width 0.1143)
		(layer "In9.Cu")
		(net "P3E_CPU1_PE3_MP_RXN<7>")
	)
	(segment
		(start 139.842748 -103.361236)
		(end 139.741656 -103.462328)
		(width 0.0889)
		(layer "In9.Cu")
		(net "P3E_CPU1_PE3_MP_RXN<7>")
	)
	(segment
		(start 9.836912 -36.188142)
		(end 9.791446 -35.959034)
		(width 0.1143)
		(layer "In9.Cu")
		(net "P3E_CPU1_PE3_MP_RXN<7>")
	)
	(segment
		(start 139.717272 -104.3432)
		(end 139.595098 -104.3432)
		(width 0.0889)
		(layer "In9.Cu")
		(net "P3E_CPU1_PE3_MP_RXN<7>")
	)
	(arc
		(start 139.736068 -99.29114)
		(mid 139.789538 -99.486203)
		(end 139.740894 -99.682554)
		(width 0.0889)
		(layer "In9.Cu")
		(net "P3E_CPU1_PE3_MP_RXN<7>")
	)
	(arc
		(start 138.877294 -96.81464)
		(mid 139.085902 -97.026572)
		(end 139.371324 -97.110042)
		(width 0.0889)
		(layer "In9.Cu")
		(net "P3E_CPU1_PE3_MP_RXN<7>")
	)
	(arc
		(start 132.007864 -95.82404)
		(mid 132.233714 -96.045674)
		(end 132.541518 -96.118934)
		(width 0.0889)
		(layer "In9.Cu")
		(net "P3E_CPU1_PE3_MP_RXN<7>")
	)
	(arc
		(start 139.736068 -98.30054)
		(mid 139.789567 -98.500438)
		(end 139.736068 -98.700336)
		(width 0.0889)
		(layer "In9.Cu")
		(net "P3E_CPU1_PE3_MP_RXN<7>")
	)
	(arc
		(start 139.729718 -99.701858)
		(mid 139.65692 -99.992621)
		(end 139.736068 -100.28174)
		(width 0.0889)
		(layer "In9.Cu")
		(net "P3E_CPU1_PE3_MP_RXN<7>")
	)
	(arc
		(start 134.583424 -96.319086)
		(mid 134.792032 -96.531018)
		(end 135.077454 -96.614488)
		(width 0.0889)
		(layer "In9.Cu")
		(net "P3E_CPU1_PE3_MP_RXN<7>")
	)
	(arc
		(start 133.031484 -95.823786)
		(mid 133.171563 -95.68105)
		(end 133.363208 -95.623888)
		(width 0.0889)
		(layer "In9.Cu")
		(net "P3E_CPU1_PE3_MP_RXN<7>")
	)
	(arc
		(start 133.39318 -95.623888)
		(mid 133.584822 -95.681054)
		(end 133.724904 -95.823786)
		(width 0.0889)
		(layer "In9.Cu")
		(net "P3E_CPU1_PE3_MP_RXN<7>")
	)
	(arc
		(start 138.54176 -96.614488)
		(mid 138.73561 -96.670838)
		(end 138.877294 -96.81464)
		(width 0.0889)
		(layer "In9.Cu")
		(net "P3E_CPU1_PE3_MP_RXN<7>")
	)
	(arc
		(start 135.11022 -96.614488)
		(mid 135.301862 -96.671654)
		(end 135.441944 -96.814386)
		(width 0.0889)
		(layer "In9.Cu")
		(net "P3E_CPU1_PE3_MP_RXN<7>")
	)
	(arc
		(start 137.68197 -96.118934)
		(mid 137.87582 -96.175284)
		(end 138.017504 -96.319086)
		(width 0.0889)
		(layer "In9.Cu")
		(net "P3E_CPU1_PE3_MP_RXN<7>")
	)
	(arc
		(start 132.541518 -96.118934)
		(mid 132.824595 -96.034595)
		(end 133.031484 -95.823786)
		(width 0.0889)
		(layer "In9.Cu")
		(net "P3E_CPU1_PE3_MP_RXN<7>")
	)
	(arc
		(start 139.696698 -101.981)
		(mid 139.720612 -102.162811)
		(end 139.790678 -102.332282)
		(width 0.0889)
		(layer "In9.Cu")
		(net "P3E_CPU1_PE3_MP_RXN<7>")
	)
	(arc
		(start 139.736068 -100.28174)
		(mid 139.789538 -100.476803)
		(end 139.740894 -100.673154)
		(width 0.0889)
		(layer "In9.Cu")
		(net "P3E_CPU1_PE3_MP_RXN<7>")
	)
	(arc
		(start 139.736068 -100.68179)
		(mid 139.70673 -100.750764)
		(end 139.696698 -100.825046)
		(width 0.0889)
		(layer "In9.Cu")
		(net "P3E_CPU1_PE3_MP_RXN<7>")
	)
	(arc
		(start 138.017504 -96.319086)
		(mid 138.226112 -96.531018)
		(end 138.511534 -96.614488)
		(width 0.0889)
		(layer "In9.Cu")
		(net "P3E_CPU1_PE3_MP_RXN<7>")
	)
	(arc
		(start 139.40409 -97.110042)
		(mid 139.428678 -97.111833)
		(end 139.453112 -97.115122)
		(width 0.0889)
		(layer "In9.Cu")
		(net "P3E_CPU1_PE3_MP_RXN<7>")
	)
	(arc
		(start 139.790678 -102.332282)
		(mid 139.834486 -102.443996)
		(end 139.843256 -102.563676)
		(width 0.0889)
		(layer "In9.Cu")
		(net "P3E_CPU1_PE3_MP_RXN<7>")
	)
	(arc
		(start 134.24789 -96.118934)
		(mid 134.44174 -96.175284)
		(end 134.583424 -96.319086)
		(width 0.0889)
		(layer "In9.Cu")
		(net "P3E_CPU1_PE3_MP_RXN<7>")
	)
	(arc
		(start 136.465564 -96.814386)
		(mid 136.605643 -96.67165)
		(end 136.797288 -96.614488)
		(width 0.0889)
		(layer "In9.Cu")
		(net "P3E_CPU1_PE3_MP_RXN<7>")
	)
	(arc
		(start 139.736068 -98.700336)
		(mid 139.656937 -98.995738)
		(end 139.736068 -99.29114)
		(width 0.0889)
		(layer "In9.Cu")
		(net "P3E_CPU1_PE3_MP_RXN<7>")
	)
	(arc
		(start 139.453112 -97.115122)
		(mid 139.748496 -97.333891)
		(end 139.740894 -97.701354)
		(width 0.0889)
		(layer "In9.Cu")
		(net "P3E_CPU1_PE3_MP_RXN<7>")
	)
	(arc
		(start 139.736068 -97.70999)
		(mid 139.656846 -97.999108)
		(end 139.729718 -98.289872)
		(width 0.0889)
		(layer "In9.Cu")
		(net "P3E_CPU1_PE3_MP_RXN<7>")
	)
	(arc
		(start 135.975344 -97.109534)
		(mid 136.258561 -97.025253)
		(end 136.465564 -96.814386)
		(width 0.0889)
		(layer "In9.Cu")
		(net "P3E_CPU1_PE3_MP_RXN<7>")
	)
	(arc
		(start 133.724904 -95.823786)
		(mid 133.931908 -96.03465)
		(end 134.215124 -96.118934)
		(width 0.0889)
		(layer "In9.Cu")
		(net "P3E_CPU1_PE3_MP_RXN<7>")
	)
	(arc
		(start 135.441944 -96.814386)
		(mid 135.648948 -97.02525)
		(end 135.932164 -97.109534)
		(width 0.0889)
		(layer "In9.Cu")
		(net "P3E_CPU1_PE3_MP_RXN<7>")
	)
	(arc
		(start 136.830054 -96.614488)
		(mid 137.115478 -96.531021)
		(end 137.324084 -96.319086)
		(width 0.0889)
		(layer "In9.Cu")
		(net "P3E_CPU1_PE3_MP_RXN<7>")
	)
	(arc
		(start 131.719066 -95.628206)
		(mid 131.883243 -95.691023)
		(end 132.004562 -95.818198)
		(width 0.0889)
		(layer "In9.Cu")
		(net "P3E_CPU1_PE3_MP_RXN<7>")
	)
	(arc
		(start 137.324084 -96.319086)
		(mid 137.465767 -96.175282)
		(end 137.659618 -96.118934)
		(width 0.0889)
		(layer "In9.Cu")
		(net "P3E_CPU1_PE3_MP_RXN<7>")
	)
	(segment
		(start 131.089908 -97.014538)
		(end 131.661408 -97.014538)
		(width 0.1143)
		(layer "F.Cu")
		(net "P3E_CPU1_PE3_MP_RXN<6>")
	)
	(via
		(at 17.296892 -38.474142)
		(size 0.508)
		(drill 0.254)
		(layers "F.Cu" "B.Cu")
		(net "P3E_CPU1_PE3_MP_RXN<6>")
	)
	(via
		(at 14.495526 -37.58946)
		(size 0.508)
		(drill 0.254)
		(layers "F.Cu" "B.Cu")
		(net "P3E_CPU1_PE3_MP_RXN<6>")
	)
	(via
		(at 131.661408 -97.014538)
		(size 0.508)
		(drill 0.254)
		(layers "F.Cu" "B.Cu")
		(net "P3E_CPU1_PE3_MP_RXN<6>")
	)
	(segment
		(start 14.054328 -37.58946)
		(end 13.847318 -37.38245)
		(width 0.1143)
		(layer "B.Cu")
		(net "P3E_CPU1_PE3_MP_RXN<6>")
	)
	(segment
		(start -3.079242 -35.824414)
		(end -2.964942 -35.710114)
		(width 0.1143)
		(layer "B.Cu")
		(net "P3E_CPU1_PE3_MP_RXN<6>")
	)
	(segment
		(start 16.782542 -37.870892)
		(end 16.50111 -37.58946)
		(width 0.1143)
		(layer "B.Cu")
		(net "P3E_CPU1_PE3_MP_RXN<6>")
	)
	(segment
		(start 9.913874 -36.586414)
		(end -2.786888 -36.586414)
		(width 0.1143)
		(layer "B.Cu")
		(net "P3E_CPU1_PE3_MP_RXN<6>")
	)
	(segment
		(start 17.296892 -38.474142)
		(end 16.896842 -38.474142)
		(width 0.1143)
		(layer "B.Cu")
		(net "P3E_CPU1_PE3_MP_RXN<6>")
	)
	(segment
		(start 16.782542 -38.359842)
		(end 16.782542 -37.870892)
		(width 0.1143)
		(layer "B.Cu")
		(net "P3E_CPU1_PE3_MP_RXN<6>")
	)
	(segment
		(start -2.964942 -35.710114)
		(end -2.500122 -35.710114)
		(width 0.1143)
		(layer "B.Cu")
		(net "P3E_CPU1_PE3_MP_RXN<6>")
	)
	(segment
		(start 14.495526 -37.58946)
		(end 14.054328 -37.58946)
		(width 0.1143)
		(layer "B.Cu")
		(net "P3E_CPU1_PE3_MP_RXN<6>")
	)
	(segment
		(start 16.50111 -37.58946)
		(end 14.495526 -37.58946)
		(width 0.1143)
		(layer "B.Cu")
		(net "P3E_CPU1_PE3_MP_RXN<6>")
	)
	(segment
		(start 16.896842 -38.474142)
		(end 16.782542 -38.359842)
		(width 0.1143)
		(layer "B.Cu")
		(net "P3E_CPU1_PE3_MP_RXN<6>")
	)
	(segment
		(start 13.847318 -37.38245)
		(end 10.70991 -37.38245)
		(width 0.1143)
		(layer "B.Cu")
		(net "P3E_CPU1_PE3_MP_RXN<6>")
	)
	(segment
		(start 10.70991 -37.38245)
		(end 9.913874 -36.586414)
		(width 0.1143)
		(layer "B.Cu")
		(net "P3E_CPU1_PE3_MP_RXN<6>")
	)
	(segment
		(start -3.079242 -36.29406)
		(end -3.079242 -35.824414)
		(width 0.1143)
		(layer "B.Cu")
		(net "P3E_CPU1_PE3_MP_RXN<6>")
	)
	(segment
		(start -2.786888 -36.586414)
		(end -3.079242 -36.29406)
		(width 0.1143)
		(layer "B.Cu")
		(net "P3E_CPU1_PE3_MP_RXN<6>")
	)
	(segment
		(start 133.613906 -108.7247)
		(end 130.432048 -108.7247)
		(width 0.1143)
		(layer "In9.Cu")
		(net "P3E_CPU1_PE3_MP_RXN<6>")
	)
	(segment
		(start 138.36269 -104.40162)
		(end 138.236706 -104.527604)
		(width 0.0889)
		(layer "In9.Cu")
		(net "P3E_CPU1_PE3_MP_RXN<6>")
	)
	(segment
		(start 138.869928 -99.775518)
		(end 138.876278 -99.786186)
		(width 0.0889)
		(layer "In9.Cu")
		(net "P3E_CPU1_PE3_MP_RXN<6>")
	)
	(segment
		(start 138.947144 -101.744272)
		(end 138.947144 -102.166928)
		(width 0.0889)
		(layer "In9.Cu")
		(net "P3E_CPU1_PE3_MP_RXN<6>")
	)
	(segment
		(start 138.017504 -97.309686)
		(end 138.02233 -97.318322)
		(width 0.0889)
		(layer "In9.Cu")
		(net "P3E_CPU1_PE3_MP_RXN<6>")
	)
	(segment
		(start 137.615422 -105.148888)
		(end 137.489438 -105.274872)
		(width 0.0889)
		(layer "In9.Cu")
		(net "P3E_CPU1_PE3_MP_RXN<6>")
	)
	(segment
		(start 16.807942 -38.739826)
		(end 16.807942 -38.563042)
		(width 0.1143)
		(layer "In9.Cu")
		(net "P3E_CPU1_PE3_MP_RXN<6>")
	)
	(segment
		(start 138.11123 -104.775254)
		(end 137.989056 -104.775254)
		(width 0.0889)
		(layer "In9.Cu")
		(net "P3E_CPU1_PE3_MP_RXN<6>")
	)
	(segment
		(start 96.900746 -108.815632)
		(end 92.647516 -109.666278)
		(width 0.1143)
		(layer "In9.Cu")
		(net "P3E_CPU1_PE3_MP_RXN<6>")
	)
	(segment
		(start 138.918188 -103.340408)
		(end 138.918188 -103.518208)
		(width 0.0889)
		(layer "In9.Cu")
		(net "P3E_CPU1_PE3_MP_RXN<6>")
	)
	(segment
		(start 138.875008 -100.188522)
		(end 138.869674 -100.19792)
		(width 0.0889)
		(layer "In9.Cu")
		(net "P3E_CPU1_PE3_MP_RXN<6>")
	)
	(segment
		(start 68.671186 -108.257086)
		(end 63.877444 -105.06202)
		(width 0.1143)
		(layer "In9.Cu")
		(net "P3E_CPU1_PE3_MP_RXN<6>")
	)
	(segment
		(start 137.489438 -105.274872)
		(end 137.489438 -105.397046)
		(width 0.0889)
		(layer "In9.Cu")
		(net "P3E_CPU1_PE3_MP_RXN<6>")
	)
	(segment
		(start 138.918188 -103.518208)
		(end 138.983974 -103.583994)
		(width 0.0889)
		(layer "In9.Cu")
		(net "P3E_CPU1_PE3_MP_RXN<6>")
	)
	(segment
		(start 59.830462 -64.387984)
		(end 60.757816 -59.752738)
		(width 0.1143)
		(layer "In9.Cu")
		(net "P3E_CPU1_PE3_MP_RXN<6>")
	)
	(segment
		(start 138.876278 -100.185982)
		(end 138.875008 -100.188522)
		(width 0.0889)
		(layer "In9.Cu")
		(net "P3E_CPU1_PE3_MP_RXN<6>")
	)
	(segment
		(start 138.858498 -104.027986)
		(end 138.736324 -104.027986)
		(width 0.0889)
		(layer "In9.Cu")
		(net "P3E_CPU1_PE3_MP_RXN<6>")
	)
	(segment
		(start 60.284106 -57.38749)
		(end 54.374542 -48.522382)
		(width 0.1143)
		(layer "In9.Cu")
		(net "P3E_CPU1_PE3_MP_RXN<6>")
	)
	(segment
		(start 138.983974 -103.068374)
		(end 138.983974 -103.274622)
		(width 0.0889)
		(layer "In9.Cu")
		(net "P3E_CPU1_PE3_MP_RXN<6>")
	)
	(segment
		(start 138.87323 -101.670358)
		(end 138.947144 -101.744272)
		(width 0.0889)
		(layer "In9.Cu")
		(net "P3E_CPU1_PE3_MP_RXN<6>")
	)
	(segment
		(start 16.896842 -38.474142)
		(end 17.296892 -38.474142)
		(width 0.1143)
		(layer "In9.Cu")
		(net "P3E_CPU1_PE3_MP_RXN<6>")
	)
	(segment
		(start 110.418118 -109.91215)
		(end 106.400346 -110.715298)
		(width 0.1143)
		(layer "In9.Cu")
		(net "P3E_CPU1_PE3_MP_RXN<6>")
	)
	(segment
		(start 74.743564 -109.472222)
		(end 68.671186 -108.257086)
		(width 0.1143)
		(layer "In9.Cu")
		(net "P3E_CPU1_PE3_MP_RXN<6>")
	)
	(segment
		(start 92.647516 -109.666278)
		(end 83.2104 -107.778804)
		(width 0.1143)
		(layer "In9.Cu")
		(net "P3E_CPU1_PE3_MP_RXN<6>")
	)
	(segment
		(start 25.527 -38.989)
		(end 23.394162 -38.989)
		(width 0.1143)
		(layer "In9.Cu")
		(net "P3E_CPU1_PE3_MP_RXN<6>")
	)
	(segment
		(start 131.661408 -97.014538)
		(end 131.95427 -96.845628)
		(width 0.0889)
		(layer "In9.Cu")
		(net "P3E_CPU1_PE3_MP_RXN<6>")
	)
	(segment
		(start 137.863072 -105.023412)
		(end 137.737596 -105.148888)
		(width 0.0889)
		(layer "In9.Cu")
		(net "P3E_CPU1_PE3_MP_RXN<6>")
	)
	(segment
		(start 136.797288 -97.605088)
		(end 136.830054 -97.605088)
		(width 0.0889)
		(layer "In9.Cu")
		(net "P3E_CPU1_PE3_MP_RXN<6>")
	)
	(segment
		(start 138.881104 -99.187)
		(end 138.876278 -99.195636)
		(width 0.0889)
		(layer "In9.Cu")
		(net "P3E_CPU1_PE3_MP_RXN<6>")
	)
	(segment
		(start 42.266362 -40.4495)
		(end 39.983664 -39.67607)
		(width 0.1143)
		(layer "In9.Cu")
		(net "P3E_CPU1_PE3_MP_RXN<6>")
	)
	(segment
		(start 60.28436 -57.388506)
		(end 60.284106 -57.38749)
		(width 0.1143)
		(layer "In9.Cu")
		(net "P3E_CPU1_PE3_MP_RXN<6>")
	)
	(segment
		(start 114.837464 -110.795816)
		(end 110.418118 -109.91215)
		(width 0.1143)
		(layer "In9.Cu")
		(net "P3E_CPU1_PE3_MP_RXN<6>")
	)
	(segment
		(start 27.297888 -38.6969)
		(end 25.527 -38.989)
		(width 0.1143)
		(layer "In9.Cu")
		(net "P3E_CPU1_PE3_MP_RXN<6>")
	)
	(segment
		(start 34.636964 -38.1)
		(end 28.909518 -38.1)
		(width 0.1143)
		(layer "In9.Cu")
		(net "P3E_CPU1_PE3_MP_RXN<6>")
	)
	(segment
		(start 138.983974 -103.583994)
		(end 138.983974 -103.90251)
		(width 0.0889)
		(layer "In9.Cu")
		(net "P3E_CPU1_PE3_MP_RXN<6>")
	)
	(segment
		(start 138.984482 -103.0605)
		(end 138.983974 -103.068374)
		(width 0.0889)
		(layer "In9.Cu")
		(net "P3E_CPU1_PE3_MP_RXN<6>")
	)
	(segment
		(start 138.983974 -103.90251)
		(end 138.858498 -104.027986)
		(width 0.0889)
		(layer "In9.Cu")
		(net "P3E_CPU1_PE3_MP_RXN<6>")
	)
	(segment
		(start 134.110984 -108.7755)
		(end 133.686804 -108.7755)
		(width 0.0889)
		(layer "In9.Cu")
		(net "P3E_CPU1_PE3_MP_RXN<6>")
	)
	(segment
		(start 106.400346 -110.715298)
		(end 96.900746 -108.815632)
		(width 0.1143)
		(layer "In9.Cu")
		(net "P3E_CPU1_PE3_MP_RXN<6>")
	)
	(segment
		(start 21.018246 -39.844472)
		(end 17.136364 -39.068248)
		(width 0.1143)
		(layer "In9.Cu")
		(net "P3E_CPU1_PE3_MP_RXN<6>")
	)
	(segment
		(start 133.363208 -96.614488)
		(end 133.39318 -96.614488)
		(width 0.0889)
		(layer "In9.Cu")
		(net "P3E_CPU1_PE3_MP_RXN<6>")
	)
	(segment
		(start 137.489438 -105.397046)
		(end 134.110984 -108.7755)
		(width 0.0889)
		(layer "In9.Cu")
		(net "P3E_CPU1_PE3_MP_RXN<6>")
	)
	(segment
		(start 137.863072 -104.901238)
		(end 137.863072 -105.023412)
		(width 0.0889)
		(layer "In9.Cu")
		(net "P3E_CPU1_PE3_MP_RXN<6>")
	)
	(segment
		(start 133.636004 -108.7247)
		(end 133.613906 -108.7247)
		(width 0.0889)
		(layer "In9.Cu")
		(net "P3E_CPU1_PE3_MP_RXN<6>")
	)
	(segment
		(start 17.136364 -39.068248)
		(end 16.807942 -38.739826)
		(width 0.1143)
		(layer "In9.Cu")
		(net "P3E_CPU1_PE3_MP_RXN<6>")
	)
	(segment
		(start 138.736324 -104.027986)
		(end 138.61034 -104.15397)
		(width 0.0889)
		(layer "In9.Cu")
		(net "P3E_CPU1_PE3_MP_RXN<6>")
	)
	(segment
		(start 60.42152 -71.78675)
		(end 60.42152 -67.343782)
		(width 0.1143)
		(layer "In9.Cu")
		(net "P3E_CPU1_PE3_MP_RXN<6>")
	)
	(segment
		(start 62.554358 -103.077264)
		(end 59.823096 -89.421462)
		(width 0.1143)
		(layer "In9.Cu")
		(net "P3E_CPU1_PE3_MP_RXN<6>")
	)
	(segment
		(start 63.877444 -105.06202)
		(end 62.554358 -103.077264)
		(width 0.1143)
		(layer "In9.Cu")
		(net "P3E_CPU1_PE3_MP_RXN<6>")
	)
	(segment
		(start 39.983664 -39.67607)
		(end 34.636964 -38.1)
		(width 0.1143)
		(layer "In9.Cu")
		(net "P3E_CPU1_PE3_MP_RXN<6>")
	)
	(segment
		(start 59.823096 -89.421462)
		(end 62.329822 -76.886562)
		(width 0.1143)
		(layer "In9.Cu")
		(net "P3E_CPU1_PE3_MP_RXN<6>")
	)
	(segment
		(start 138.236706 -104.527604)
		(end 138.236706 -104.649778)
		(width 0.0889)
		(layer "In9.Cu")
		(net "P3E_CPU1_PE3_MP_RXN<6>")
	)
	(segment
		(start 135.077454 -97.605088)
		(end 135.11022 -97.605088)
		(width 0.0889)
		(layer "In9.Cu")
		(net "P3E_CPU1_PE3_MP_RXN<6>")
	)
	(segment
		(start 138.87323 -101.492558)
		(end 138.87323 -101.670358)
		(width 0.0889)
		(layer "In9.Cu")
		(net "P3E_CPU1_PE3_MP_RXN<6>")
	)
	(segment
		(start 138.947144 -101.418644)
		(end 138.87323 -101.492558)
		(width 0.0889)
		(layer "In9.Cu")
		(net "P3E_CPU1_PE3_MP_RXN<6>")
	)
	(segment
		(start 133.686804 -108.7755)
		(end 133.636004 -108.7247)
		(width 0.0889)
		(layer "In9.Cu")
		(net "P3E_CPU1_PE3_MP_RXN<6>")
	)
	(segment
		(start 62.329822 -76.886562)
		(end 61.84011 -74.43724)
		(width 0.1143)
		(layer "In9.Cu")
		(net "P3E_CPU1_PE3_MP_RXN<6>")
	)
	(segment
		(start 134.215124 -97.109534)
		(end 134.24789 -97.109534)
		(width 0.0889)
		(layer "In9.Cu")
		(net "P3E_CPU1_PE3_MP_RXN<6>")
	)
	(segment
		(start 138.511534 -98.595688)
		(end 138.5443 -98.595688)
		(width 0.0889)
		(layer "In9.Cu")
		(net "P3E_CPU1_PE3_MP_RXN<6>")
	)
	(segment
		(start 135.932164 -98.100134)
		(end 135.975344 -98.100134)
		(width 0.0889)
		(layer "In9.Cu")
		(net "P3E_CPU1_PE3_MP_RXN<6>")
	)
	(segment
		(start 16.807942 -38.563042)
		(end 16.896842 -38.474142)
		(width 0.1143)
		(layer "In9.Cu")
		(net "P3E_CPU1_PE3_MP_RXN<6>")
	)
	(segment
		(start 60.757816 -59.752738)
		(end 60.28436 -57.388506)
		(width 0.1143)
		(layer "In9.Cu")
		(net "P3E_CPU1_PE3_MP_RXN<6>")
	)
	(segment
		(start 138.484864 -104.40162)
		(end 138.36269 -104.40162)
		(width 0.0889)
		(layer "In9.Cu")
		(net "P3E_CPU1_PE3_MP_RXN<6>")
	)
	(segment
		(start 137.659618 -97.109534)
		(end 137.68197 -97.109534)
		(width 0.0889)
		(layer "In9.Cu")
		(net "P3E_CPU1_PE3_MP_RXN<6>")
	)
	(segment
		(start 28.909518 -38.1)
		(end 27.297888 -38.6969)
		(width 0.1143)
		(layer "In9.Cu")
		(net "P3E_CPU1_PE3_MP_RXN<6>")
	)
	(segment
		(start 131.95427 -96.845628)
		(end 132.043678 -96.869758)
		(width 0.0889)
		(layer "In9.Cu")
		(net "P3E_CPU1_PE3_MP_RXN<6>")
	)
	(segment
		(start 60.42152 -67.343782)
		(end 59.830462 -64.387984)
		(width 0.1143)
		(layer "In9.Cu")
		(net "P3E_CPU1_PE3_MP_RXN<6>")
	)
	(segment
		(start 54.374542 -48.522382)
		(end 42.266362 -40.4495)
		(width 0.1143)
		(layer "In9.Cu")
		(net "P3E_CPU1_PE3_MP_RXN<6>")
	)
	(segment
		(start 138.947144 -101.040692)
		(end 138.947144 -101.418644)
		(width 0.0889)
		(layer "In9.Cu")
		(net "P3E_CPU1_PE3_MP_RXN<6>")
	)
	(segment
		(start 138.236706 -104.649778)
		(end 138.11123 -104.775254)
		(width 0.0889)
		(layer "In9.Cu")
		(net "P3E_CPU1_PE3_MP_RXN<6>")
	)
	(segment
		(start 138.983974 -103.274622)
		(end 138.918188 -103.340408)
		(width 0.0889)
		(layer "In9.Cu")
		(net "P3E_CPU1_PE3_MP_RXN<6>")
	)
	(segment
		(start 83.2104 -107.778804)
		(end 74.743564 -109.472222)
		(width 0.1143)
		(layer "In9.Cu")
		(net "P3E_CPU1_PE3_MP_RXN<6>")
	)
	(segment
		(start 61.84011 -74.43724)
		(end 60.42152 -71.78675)
		(width 0.1143)
		(layer "In9.Cu")
		(net "P3E_CPU1_PE3_MP_RXN<6>")
	)
	(segment
		(start 138.61034 -104.276144)
		(end 138.484864 -104.40162)
		(width 0.0889)
		(layer "In9.Cu")
		(net "P3E_CPU1_PE3_MP_RXN<6>")
	)
	(segment
		(start 23.394162 -38.989)
		(end 21.018246 -39.844472)
		(width 0.1143)
		(layer "In9.Cu")
		(net "P3E_CPU1_PE3_MP_RXN<6>")
	)
	(segment
		(start 130.432048 -108.7247)
		(end 127.812546 -108.200698)
		(width 0.1143)
		(layer "In9.Cu")
		(net "P3E_CPU1_PE3_MP_RXN<6>")
	)
	(segment
		(start 138.61034 -104.15397)
		(end 138.61034 -104.276144)
		(width 0.0889)
		(layer "In9.Cu")
		(net "P3E_CPU1_PE3_MP_RXN<6>")
	)
	(segment
		(start 137.737596 -105.148888)
		(end 137.615422 -105.148888)
		(width 0.0889)
		(layer "In9.Cu")
		(net "P3E_CPU1_PE3_MP_RXN<6>")
	)
	(segment
		(start 137.989056 -104.775254)
		(end 137.863072 -104.901238)
		(width 0.0889)
		(layer "In9.Cu")
		(net "P3E_CPU1_PE3_MP_RXN<6>")
	)
	(segment
		(start 127.812546 -108.200698)
		(end 114.837464 -110.795816)
		(width 0.1143)
		(layer "In9.Cu")
		(net "P3E_CPU1_PE3_MP_RXN<6>")
	)
	(arc
		(start 138.876278 -99.195636)
		(mid 138.797056 -99.484754)
		(end 138.869928 -99.775518)
		(width 0.0889)
		(layer "In9.Cu")
		(net "P3E_CPU1_PE3_MP_RXN<6>")
	)
	(arc
		(start 136.830054 -97.605088)
		(mid 137.115478 -97.521621)
		(end 137.324084 -97.309686)
		(width 0.0889)
		(layer "In9.Cu")
		(net "P3E_CPU1_PE3_MP_RXN<6>")
	)
	(arc
		(start 132.541264 -97.109534)
		(mid 132.824481 -97.025253)
		(end 133.031484 -96.814386)
		(width 0.0889)
		(layer "In9.Cu")
		(net "P3E_CPU1_PE3_MP_RXN<6>")
	)
	(arc
		(start 138.947144 -102.166928)
		(mid 138.941628 -102.209094)
		(end 138.925554 -102.248462)
		(width 0.0889)
		(layer "In9.Cu")
		(net "P3E_CPU1_PE3_MP_RXN<6>")
	)
	(arc
		(start 137.68197 -97.109534)
		(mid 137.87582 -97.165884)
		(end 138.017504 -97.309686)
		(width 0.0889)
		(layer "In9.Cu")
		(net "P3E_CPU1_PE3_MP_RXN<6>")
	)
	(arc
		(start 132.043678 -96.869758)
		(mid 132.262774 -97.051281)
		(end 132.541264 -97.109534)
		(width 0.0889)
		(layer "In9.Cu")
		(net "P3E_CPU1_PE3_MP_RXN<6>")
	)
	(arc
		(start 133.031484 -96.814386)
		(mid 133.171563 -96.67165)
		(end 133.363208 -96.614488)
		(width 0.0889)
		(layer "In9.Cu")
		(net "P3E_CPU1_PE3_MP_RXN<6>")
	)
	(arc
		(start 138.017504 -97.709736)
		(mid 138.013175 -98.292908)
		(end 138.511534 -98.595688)
		(width 0.0889)
		(layer "In9.Cu")
		(net "P3E_CPU1_PE3_MP_RXN<6>")
	)
	(arc
		(start 134.583424 -97.309686)
		(mid 134.792032 -97.521618)
		(end 135.077454 -97.605088)
		(width 0.0889)
		(layer "In9.Cu")
		(net "P3E_CPU1_PE3_MP_RXN<6>")
	)
	(arc
		(start 135.441944 -97.804986)
		(mid 135.648948 -98.01585)
		(end 135.932164 -98.100134)
		(width 0.0889)
		(layer "In9.Cu")
		(net "P3E_CPU1_PE3_MP_RXN<6>")
	)
	(arc
		(start 138.925554 -102.248462)
		(mid 138.853156 -102.538747)
		(end 138.932158 -102.827328)
		(width 0.0889)
		(layer "In9.Cu")
		(net "P3E_CPU1_PE3_MP_RXN<6>")
	)
	(arc
		(start 138.869674 -100.19792)
		(mid 138.797276 -100.488205)
		(end 138.876278 -100.776786)
		(width 0.0889)
		(layer "In9.Cu")
		(net "P3E_CPU1_PE3_MP_RXN<6>")
	)
	(arc
		(start 137.324084 -97.309686)
		(mid 137.465767 -97.165882)
		(end 137.659618 -97.109534)
		(width 0.0889)
		(layer "In9.Cu")
		(net "P3E_CPU1_PE3_MP_RXN<6>")
	)
	(arc
		(start 138.02233 -97.318322)
		(mid 138.071085 -97.514674)
		(end 138.017504 -97.709736)
		(width 0.0889)
		(layer "In9.Cu")
		(net "P3E_CPU1_PE3_MP_RXN<6>")
	)
	(arc
		(start 138.5443 -98.595688)
		(mid 138.568888 -98.597479)
		(end 138.593322 -98.600768)
		(width 0.0889)
		(layer "In9.Cu")
		(net "P3E_CPU1_PE3_MP_RXN<6>")
	)
	(arc
		(start 138.932158 -102.827328)
		(mid 138.976091 -102.939921)
		(end 138.984482 -103.0605)
		(width 0.0889)
		(layer "In9.Cu")
		(net "P3E_CPU1_PE3_MP_RXN<6>")
	)
	(arc
		(start 133.724904 -96.814386)
		(mid 133.931908 -97.02525)
		(end 134.215124 -97.109534)
		(width 0.0889)
		(layer "In9.Cu")
		(net "P3E_CPU1_PE3_MP_RXN<6>")
	)
	(arc
		(start 136.465564 -97.804986)
		(mid 136.605643 -97.66225)
		(end 136.797288 -97.605088)
		(width 0.0889)
		(layer "In9.Cu")
		(net "P3E_CPU1_PE3_MP_RXN<6>")
	)
	(arc
		(start 133.39318 -96.614488)
		(mid 133.584822 -96.671654)
		(end 133.724904 -96.814386)
		(width 0.0889)
		(layer "In9.Cu")
		(net "P3E_CPU1_PE3_MP_RXN<6>")
	)
	(arc
		(start 135.11022 -97.605088)
		(mid 135.301862 -97.662254)
		(end 135.441944 -97.804986)
		(width 0.0889)
		(layer "In9.Cu")
		(net "P3E_CPU1_PE3_MP_RXN<6>")
	)
	(arc
		(start 138.593322 -98.600768)
		(mid 138.888706 -98.819537)
		(end 138.881104 -99.187)
		(width 0.0889)
		(layer "In9.Cu")
		(net "P3E_CPU1_PE3_MP_RXN<6>")
	)
	(arc
		(start 134.24789 -97.109534)
		(mid 134.44174 -97.165884)
		(end 134.583424 -97.309686)
		(width 0.0889)
		(layer "In9.Cu")
		(net "P3E_CPU1_PE3_MP_RXN<6>")
	)
	(arc
		(start 135.975344 -98.100134)
		(mid 136.258561 -98.015853)
		(end 136.465564 -97.804986)
		(width 0.0889)
		(layer "In9.Cu")
		(net "P3E_CPU1_PE3_MP_RXN<6>")
	)
	(arc
		(start 138.876278 -99.786186)
		(mid 138.929777 -99.986084)
		(end 138.876278 -100.185982)
		(width 0.0889)
		(layer "In9.Cu")
		(net "P3E_CPU1_PE3_MP_RXN<6>")
	)
	(arc
		(start 138.876278 -100.776786)
		(mid 138.929148 -100.904059)
		(end 138.947144 -101.040692)
		(width 0.0889)
		(layer "In9.Cu")
		(net "P3E_CPU1_PE3_MP_RXN<6>")
	)
	(segment
		(start 131.089908 -98.005138)
		(end 131.661408 -98.005138)
		(width 0.1143)
		(layer "F.Cu")
		(net "P3E_CPU1_PE3_MP_RXN<5>")
	)
	(via
		(at 131.661408 -98.005138)
		(size 0.508)
		(drill 0.254)
		(layers "F.Cu" "B.Cu")
		(net "P3E_CPU1_PE3_MP_RXN<5>")
	)
	(via
		(at 13.032486 -39.206424)
		(size 0.508)
		(drill 0.254)
		(layers "F.Cu" "B.Cu")
		(net "P3E_CPU1_PE3_MP_RXN<5>")
	)
	(segment
		(start 6.620764 -37.98189)
		(end 6.620764 -38.359588)
		(width 0.1143)
		(layer "B.Cu")
		(net "P3E_CPU1_PE3_MP_RXN<5>")
	)
	(segment
		(start 6.892544 -37.71011)
		(end 6.620764 -37.98189)
		(width 0.1143)
		(layer "B.Cu")
		(net "P3E_CPU1_PE3_MP_RXN<5>")
	)
	(segment
		(start 9.504172 -38.603428)
		(end 9.75868 -38.34892)
		(width 0.1143)
		(layer "B.Cu")
		(net "P3E_CPU1_PE3_MP_RXN<5>")
	)
	(segment
		(start 12.299696 -38.34892)
		(end 12.645136 -38.69436)
		(width 0.1143)
		(layer "B.Cu")
		(net "P3E_CPU1_PE3_MP_RXN<5>")
	)
	(segment
		(start 12.645136 -38.984936)
		(end 12.866624 -39.206424)
		(width 0.1143)
		(layer "B.Cu")
		(net "P3E_CPU1_PE3_MP_RXN<5>")
	)
	(segment
		(start 12.645136 -38.69436)
		(end 12.645136 -38.984936)
		(width 0.1143)
		(layer "B.Cu")
		(net "P3E_CPU1_PE3_MP_RXN<5>")
	)
	(segment
		(start 6.864604 -38.603428)
		(end 9.504172 -38.603428)
		(width 0.1143)
		(layer "B.Cu")
		(net "P3E_CPU1_PE3_MP_RXN<5>")
	)
	(segment
		(start 12.866624 -39.206424)
		(end 13.032486 -39.206424)
		(width 0.1143)
		(layer "B.Cu")
		(net "P3E_CPU1_PE3_MP_RXN<5>")
	)
	(segment
		(start 7.199884 -37.71011)
		(end 6.892544 -37.71011)
		(width 0.1143)
		(layer "B.Cu")
		(net "P3E_CPU1_PE3_MP_RXN<5>")
	)
	(segment
		(start 6.620764 -38.359588)
		(end 6.864604 -38.603428)
		(width 0.1143)
		(layer "B.Cu")
		(net "P3E_CPU1_PE3_MP_RXN<5>")
	)
	(segment
		(start 9.75868 -38.34892)
		(end 12.299696 -38.34892)
		(width 0.1143)
		(layer "B.Cu")
		(net "P3E_CPU1_PE3_MP_RXN<5>")
	)
	(segment
		(start 139.39901 -96.118934)
		(end 139.366244 -96.118934)
		(width 0.0889)
		(layer "In9.Cu")
		(net "P3E_CPU1_PE3_MP_RXN<5>")
	)
	(segment
		(start 122.854212 -115.651534)
		(end 131.313428 -113.956846)
		(width 0.1143)
		(layer "In9.Cu")
		(net "P3E_CPU1_PE3_MP_RXN<5>")
	)
	(segment
		(start 58.76925 -81.15046)
		(end 58.76925 -81.784952)
		(width 0.1143)
		(layer "In9.Cu")
		(net "P3E_CPU1_PE3_MP_RXN<5>")
	)
	(segment
		(start 140.438378 -100.79863)
		(end 140.515086 -100.721922)
		(width 0.0889)
		(layer "In9.Cu")
		(net "P3E_CPU1_PE3_MP_RXN<5>")
	)
	(segment
		(start 140.515086 -100.515674)
		(end 140.514832 -100.514912)
		(width 0.0889)
		(layer "In9.Cu")
		(net "P3E_CPU1_PE3_MP_RXN<5>")
	)
	(segment
		(start 139.911328 -105.287318)
		(end 140.037058 -105.161588)
		(width 0.0889)
		(layer "In9.Cu")
		(net "P3E_CPU1_PE3_MP_RXN<5>")
	)
	(segment
		(start 140.586968 -99.206304)
		(end 140.593318 -99.195636)
		(width 0.0889)
		(layer "In9.Cu")
		(net "P3E_CPU1_PE3_MP_RXN<5>")
	)
	(segment
		(start 140.700252 -102.630732)
		(end 140.611606 -102.542086)
		(width 0.0889)
		(layer "In9.Cu")
		(net "P3E_CPU1_PE3_MP_RXN<5>")
	)
	(segment
		(start 140.180314 -105.161588)
		(end 140.30579 -105.036112)
		(width 0.0889)
		(layer "In9.Cu")
		(net "P3E_CPU1_PE3_MP_RXN<5>")
	)
	(segment
		(start 140.700252 -103.758746)
		(end 140.59916 -103.657654)
		(width 0.0889)
		(layer "In9.Cu")
		(net "P3E_CPU1_PE3_MP_RXN<5>")
	)
	(segment
		(start 137.688828 -95.128588)
		(end 137.65276 -95.128588)
		(width 0.0889)
		(layer "In9.Cu")
		(net "P3E_CPU1_PE3_MP_RXN<5>")
	)
	(segment
		(start 140.700252 -102.820978)
		(end 140.700252 -102.630732)
		(width 0.0889)
		(layer "In9.Cu")
		(net "P3E_CPU1_PE3_MP_RXN<5>")
	)
	(segment
		(start 58.99912 -86.552532)
		(end 58.976006 -86.645242)
		(width 0.1143)
		(layer "In9.Cu")
		(net "P3E_CPU1_PE3_MP_RXN<5>")
	)
	(segment
		(start 139.785852 -105.55605)
		(end 139.911328 -105.430574)
		(width 0.0889)
		(layer "In9.Cu")
		(net "P3E_CPU1_PE3_MP_RXN<5>")
	)
	(segment
		(start 29.321506 -40.013128)
		(end 30.376622 -39.4843)
		(width 0.1143)
		(layer "In9.Cu")
		(net "P3E_CPU1_PE3_MP_RXN<5>")
	)
	(segment
		(start 58.99912 -83.552792)
		(end 58.99912 -86.552532)
		(width 0.1143)
		(layer "In9.Cu")
		(net "P3E_CPU1_PE3_MP_RXN<5>")
	)
	(segment
		(start 140.59916 -102.92207)
		(end 140.700252 -102.820978)
		(width 0.0889)
		(layer "In9.Cu")
		(net "P3E_CPU1_PE3_MP_RXN<5>")
	)
	(segment
		(start 140.700252 -103.200962)
		(end 140.59916 -103.09987)
		(width 0.0889)
		(layer "In9.Cu")
		(net "P3E_CPU1_PE3_MP_RXN<5>")
	)
	(segment
		(start 61.230002 -103.494078)
		(end 63.258192 -106.53649)
		(width 0.1143)
		(layer "In9.Cu")
		(net "P3E_CPU1_PE3_MP_RXN<5>")
	)
	(segment
		(start 59.278774 -59.52744)
		(end 58.381646 -64.013334)
		(width 0.1143)
		(layer "In9.Cu")
		(net "P3E_CPU1_PE3_MP_RXN<5>")
	)
	(segment
		(start 140.700252 -104.64165)
		(end 140.700252 -104.31653)
		(width 0.0889)
		(layer "In9.Cu")
		(net "P3E_CPU1_PE3_MP_RXN<5>")
	)
	(segment
		(start 133.396228 -94.633288)
		(end 133.36016 -94.633288)
		(width 0.0889)
		(layer "In9.Cu")
		(net "P3E_CPU1_PE3_MP_RXN<5>")
	)
	(segment
		(start 34.319464 -39.4843)
		(end 41.536874 -41.66616)
		(width 0.1143)
		(layer "In9.Cu")
		(net "P3E_CPU1_PE3_MP_RXN<5>")
	)
	(segment
		(start 136.825228 -95.623888)
		(end 136.797288 -95.623888)
		(width 0.0889)
		(layer "In9.Cu")
		(net "P3E_CPU1_PE3_MP_RXN<5>")
	)
	(segment
		(start 140.59916 -103.479854)
		(end 140.700252 -103.378762)
		(width 0.0889)
		(layer "In9.Cu")
		(net "P3E_CPU1_PE3_MP_RXN<5>")
	)
	(segment
		(start 58.05932 -67.511676)
		(end 58.05932 -70.257162)
		(width 0.1143)
		(layer "In9.Cu")
		(net "P3E_CPU1_PE3_MP_RXN<5>")
	)
	(segment
		(start 135.11022 -95.623888)
		(end 135.08228 -95.623888)
		(width 0.0889)
		(layer "In9.Cu")
		(net "P3E_CPU1_PE3_MP_RXN<5>")
	)
	(segment
		(start 13.119354 -39.825676)
		(end 17.314164 -40.51681)
		(width 0.1143)
		(layer "In9.Cu")
		(net "P3E_CPU1_PE3_MP_RXN<5>")
	)
	(segment
		(start 140.037058 -105.161588)
		(end 140.180314 -105.161588)
		(width 0.0889)
		(layer "In9.Cu")
		(net "P3E_CPU1_PE3_MP_RXN<5>")
	)
	(segment
		(start 140.700252 -104.31653)
		(end 140.59916 -104.215438)
		(width 0.0889)
		(layer "In9.Cu")
		(net "P3E_CPU1_PE3_MP_RXN<5>")
	)
	(segment
		(start 60.98667 -76.855574)
		(end 60.708794 -78.245462)
		(width 0.1143)
		(layer "In9.Cu")
		(net "P3E_CPU1_PE3_MP_RXN<5>")
	)
	(segment
		(start 140.515086 -101.33584)
		(end 140.515086 -101.053138)
		(width 0.0889)
		(layer "In9.Cu")
		(net "P3E_CPU1_PE3_MP_RXN<5>")
	)
	(segment
		(start 97.110804 -111.558324)
		(end 100.410772 -112.218216)
		(width 0.1143)
		(layer "In9.Cu")
		(net "P3E_CPU1_PE3_MP_RXN<5>")
	)
	(segment
		(start 12.670536 -39.295324)
		(end 12.670536 -39.496492)
		(width 0.1143)
		(layer "In9.Cu")
		(net "P3E_CPU1_PE3_MP_RXN<5>")
	)
	(segment
		(start 63.258192 -106.53649)
		(end 71.54291 -112.057434)
		(width 0.1143)
		(layer "In9.Cu")
		(net "P3E_CPU1_PE3_MP_RXN<5>")
	)
	(segment
		(start 139.911328 -105.430574)
		(end 139.911328 -105.287318)
		(width 0.0889)
		(layer "In9.Cu")
		(net "P3E_CPU1_PE3_MP_RXN<5>")
	)
	(segment
		(start 83.075272 -114.364262)
		(end 83.07832 -114.365024)
		(width 0.1143)
		(layer "In9.Cu")
		(net "P3E_CPU1_PE3_MP_RXN<5>")
	)
	(segment
		(start 131.309872 -97.2058)
		(end 131.314698 -97.214436)
		(width 0.0889)
		(layer "In9.Cu")
		(net "P3E_CPU1_PE3_MP_RXN<5>")
	)
	(segment
		(start 140.611606 -102.364286)
		(end 140.700252 -102.27564)
		(width 0.0889)
		(layer "In9.Cu")
		(net "P3E_CPU1_PE3_MP_RXN<5>")
	)
	(segment
		(start 103.048054 -111.690658)
		(end 122.854212 -115.651534)
		(width 0.1143)
		(layer "In9.Cu")
		(net "P3E_CPU1_PE3_MP_RXN<5>")
	)
	(segment
		(start 140.611606 -102.542086)
		(end 140.611606 -102.364286)
		(width 0.0889)
		(layer "In9.Cu")
		(net "P3E_CPU1_PE3_MP_RXN<5>")
	)
	(segment
		(start 140.26134 -96.614488)
		(end 140.228574 -96.614488)
		(width 0.0889)
		(layer "In9.Cu")
		(net "P3E_CPU1_PE3_MP_RXN<5>")
	)
	(segment
		(start 134.254748 -95.128588)
		(end 134.218934 -95.128588)
		(width 0.0889)
		(layer "In9.Cu")
		(net "P3E_CPU1_PE3_MP_RXN<5>")
	)
	(segment
		(start 12.860274 -39.727886)
		(end 13.119354 -39.825676)
		(width 0.1143)
		(layer "In9.Cu")
		(net "P3E_CPU1_PE3_MP_RXN<5>")
	)
	(segment
		(start 139.642596 -105.55605)
		(end 139.785852 -105.55605)
		(width 0.0889)
		(layer "In9.Cu")
		(net "P3E_CPU1_PE3_MP_RXN<5>")
	)
	(segment
		(start 135.975344 -96.118934)
		(end 135.932164 -96.118934)
		(width 0.0889)
		(layer "In9.Cu")
		(net "P3E_CPU1_PE3_MP_RXN<5>")
	)
	(segment
		(start 140.59916 -103.09987)
		(end 140.59916 -102.92207)
		(width 0.0889)
		(layer "In9.Cu")
		(net "P3E_CPU1_PE3_MP_RXN<5>")
	)
	(segment
		(start 140.593318 -97.214436)
		(end 140.598144 -97.2058)
		(width 0.0889)
		(layer "In9.Cu")
		(net "P3E_CPU1_PE3_MP_RXN<5>")
	)
	(segment
		(start 140.43152 -104.767126)
		(end 140.574776 -104.767126)
		(width 0.0889)
		(layer "In9.Cu")
		(net "P3E_CPU1_PE3_MP_RXN<5>")
	)
	(segment
		(start 140.700252 -102.085394)
		(end 140.701014 -102.07625)
		(width 0.0889)
		(layer "In9.Cu")
		(net "P3E_CPU1_PE3_MP_RXN<5>")
	)
	(segment
		(start 100.410772 -112.218216)
		(end 103.048054 -111.690658)
		(width 0.1143)
		(layer "In9.Cu")
		(net "P3E_CPU1_PE3_MP_RXN<5>")
	)
	(segment
		(start 140.593318 -97.804986)
		(end 140.586968 -97.794318)
		(width 0.0889)
		(layer "In9.Cu")
		(net "P3E_CPU1_PE3_MP_RXN<5>")
	)
	(segment
		(start 60.708794 -78.245462)
		(end 58.76925 -81.15046)
		(width 0.1143)
		(layer "In9.Cu")
		(net "P3E_CPU1_PE3_MP_RXN<5>")
	)
	(segment
		(start 58.76925 -81.784952)
		(end 59.15025 -82.165952)
		(width 0.1143)
		(layer "In9.Cu")
		(net "P3E_CPU1_PE3_MP_RXN<5>")
	)
	(segment
		(start 140.700252 -103.936546)
		(end 140.700252 -103.758746)
		(width 0.0889)
		(layer "In9.Cu")
		(net "P3E_CPU1_PE3_MP_RXN<5>")
	)
	(segment
		(start 139.516866 -105.68178)
		(end 139.642596 -105.55605)
		(width 0.0889)
		(layer "In9.Cu")
		(net "P3E_CPU1_PE3_MP_RXN<5>")
	)
	(segment
		(start 12.759436 -39.206424)
		(end 12.670536 -39.295324)
		(width 0.1143)
		(layer "In9.Cu")
		(net "P3E_CPU1_PE3_MP_RXN<5>")
	)
	(segment
		(start 58.418476 -89.433908)
		(end 61.230002 -103.494078)
		(width 0.1143)
		(layer "In9.Cu")
		(net "P3E_CPU1_PE3_MP_RXN<5>")
	)
	(segment
		(start 131.6736 -94.633288)
		(end 131.643374 -94.633288)
		(width 0.0889)
		(layer "In9.Cu")
		(net "P3E_CPU1_PE3_MP_RXN<5>")
	)
	(segment
		(start 131.368292 -97.835974)
		(end 131.661408 -98.005138)
		(width 0.0889)
		(layer "In9.Cu")
		(net "P3E_CPU1_PE3_MP_RXN<5>")
	)
	(segment
		(start 140.59916 -104.037638)
		(end 140.700252 -103.936546)
		(width 0.0889)
		(layer "In9.Cu")
		(net "P3E_CPU1_PE3_MP_RXN<5>")
	)
	(segment
		(start 59.15025 -83.401662)
		(end 58.99912 -83.552792)
		(width 0.1143)
		(layer "In9.Cu")
		(net "P3E_CPU1_PE3_MP_RXN<5>")
	)
	(segment
		(start 41.536874 -41.66616)
		(end 53.230526 -49.461674)
		(width 0.1143)
		(layer "In9.Cu")
		(net "P3E_CPU1_PE3_MP_RXN<5>")
	)
	(segment
		(start 58.976006 -86.645242)
		(end 58.418476 -89.433908)
		(width 0.1143)
		(layer "In9.Cu")
		(net "P3E_CPU1_PE3_MP_RXN<5>")
	)
	(segment
		(start 139.309602 -106.0323)
		(end 139.516866 -105.825036)
		(width 0.0889)
		(layer "In9.Cu")
		(net "P3E_CPU1_PE3_MP_RXN<5>")
	)
	(segment
		(start 139.22248 -106.047794)
		(end 139.237974 -106.0323)
		(width 0.0889)
		(layer "In9.Cu")
		(net "P3E_CPU1_PE3_MP_RXN<5>")
	)
	(segment
		(start 17.314164 -40.51681)
		(end 23.627588 -41.779952)
		(width 0.1143)
		(layer "In9.Cu")
		(net "P3E_CPU1_PE3_MP_RXN<5>")
	)
	(segment
		(start 140.515086 -100.721922)
		(end 140.515086 -100.515674)
		(width 0.0889)
		(layer "In9.Cu")
		(net "P3E_CPU1_PE3_MP_RXN<5>")
	)
	(segment
		(start 131.309872 -96.2152)
		(end 131.314698 -96.223836)
		(width 0.0889)
		(layer "In9.Cu")
		(net "P3E_CPU1_PE3_MP_RXN<5>")
	)
	(segment
		(start 23.627588 -41.779952)
		(end 25.496266 -41.363392)
		(width 0.1143)
		(layer "In9.Cu")
		(net "P3E_CPU1_PE3_MP_RXN<5>")
	)
	(segment
		(start 139.516866 -105.825036)
		(end 139.516866 -105.68178)
		(width 0.0889)
		(layer "In9.Cu")
		(net "P3E_CPU1_PE3_MP_RXN<5>")
	)
	(segment
		(start 140.574776 -104.767126)
		(end 140.700252 -104.64165)
		(width 0.0889)
		(layer "In9.Cu")
		(net "P3E_CPU1_PE3_MP_RXN<5>")
	)
	(segment
		(start 140.30579 -105.036112)
		(end 140.30579 -104.892856)
		(width 0.0889)
		(layer "In9.Cu")
		(net "P3E_CPU1_PE3_MP_RXN<5>")
	)
	(segment
		(start 140.700252 -102.27564)
		(end 140.700252 -102.085394)
		(width 0.0889)
		(layer "In9.Cu")
		(net "P3E_CPU1_PE3_MP_RXN<5>")
	)
	(segment
		(start 140.59916 -103.657654)
		(end 140.59916 -103.479854)
		(width 0.0889)
		(layer "In9.Cu")
		(net "P3E_CPU1_PE3_MP_RXN<5>")
	)
	(segment
		(start 132.537454 -95.128588)
		(end 132.501894 -95.128588)
		(width 0.0889)
		(layer "In9.Cu")
		(net "P3E_CPU1_PE3_MP_RXN<5>")
	)
	(segment
		(start 25.496266 -41.363392)
		(end 29.321506 -40.013128)
		(width 0.1143)
		(layer "In9.Cu")
		(net "P3E_CPU1_PE3_MP_RXN<5>")
	)
	(segment
		(start 140.700252 -103.378762)
		(end 140.700252 -103.200962)
		(width 0.0889)
		(layer "In9.Cu")
		(net "P3E_CPU1_PE3_MP_RXN<5>")
	)
	(segment
		(start 131.314698 -96.223836)
		(end 131.321048 -96.234504)
		(width 0.0889)
		(layer "In9.Cu")
		(net "P3E_CPU1_PE3_MP_RXN<5>")
	)
	(segment
		(start 58.381646 -64.013334)
		(end 58.674508 -65.477644)
		(width 0.1143)
		(layer "In9.Cu")
		(net "P3E_CPU1_PE3_MP_RXN<5>")
	)
	(segment
		(start 58.674508 -65.477644)
		(end 58.05932 -67.511676)
		(width 0.1143)
		(layer "In9.Cu")
		(net "P3E_CPU1_PE3_MP_RXN<5>")
	)
	(segment
		(start 58.05932 -70.257162)
		(end 60.62599 -75.05319)
		(width 0.1143)
		(layer "In9.Cu")
		(net "P3E_CPU1_PE3_MP_RXN<5>")
	)
	(segment
		(start 30.376622 -39.4843)
		(end 34.319464 -39.4843)
		(width 0.1143)
		(layer "In9.Cu")
		(net "P3E_CPU1_PE3_MP_RXN<5>")
	)
	(segment
		(start 60.62599 -75.05319)
		(end 60.98667 -76.855574)
		(width 0.1143)
		(layer "In9.Cu")
		(net "P3E_CPU1_PE3_MP_RXN<5>")
	)
	(segment
		(start 53.230526 -49.461674)
		(end 58.994802 -58.107834)
		(width 0.1143)
		(layer "In9.Cu")
		(net "P3E_CPU1_PE3_MP_RXN<5>")
	)
	(segment
		(start 71.54291 -112.057434)
		(end 83.075272 -114.364262)
		(width 0.1143)
		(layer "In9.Cu")
		(net "P3E_CPU1_PE3_MP_RXN<5>")
	)
	(segment
		(start 13.032486 -39.206424)
		(end 12.759436 -39.206424)
		(width 0.1143)
		(layer "In9.Cu")
		(net "P3E_CPU1_PE3_MP_RXN<5>")
	)
	(segment
		(start 140.438378 -100.97643)
		(end 140.438378 -100.79863)
		(width 0.0889)
		(layer "In9.Cu")
		(net "P3E_CPU1_PE3_MP_RXN<5>")
	)
	(segment
		(start 59.15025 -82.165952)
		(end 59.15025 -83.401662)
		(width 0.1143)
		(layer "In9.Cu")
		(net "P3E_CPU1_PE3_MP_RXN<5>")
	)
	(segment
		(start 140.593318 -100.186236)
		(end 140.598144 -100.1776)
		(width 0.0889)
		(layer "In9.Cu")
		(net "P3E_CPU1_PE3_MP_RXN<5>")
	)
	(segment
		(start 139.237974 -106.0323)
		(end 139.309602 -106.0323)
		(width 0.0889)
		(layer "In9.Cu")
		(net "P3E_CPU1_PE3_MP_RXN<5>")
	)
	(segment
		(start 131.314698 -97.214436)
		(end 131.321048 -97.225104)
		(width 0.0889)
		(layer "In9.Cu")
		(net "P3E_CPU1_PE3_MP_RXN<5>")
	)
	(segment
		(start 131.313428 -113.956846)
		(end 139.22248 -106.047794)
		(width 0.1143)
		(layer "In9.Cu")
		(net "P3E_CPU1_PE3_MP_RXN<5>")
	)
	(segment
		(start 140.586968 -100.196904)
		(end 140.593318 -100.186236)
		(width 0.0889)
		(layer "In9.Cu")
		(net "P3E_CPU1_PE3_MP_RXN<5>")
	)
	(segment
		(start 140.59916 -104.215438)
		(end 140.59916 -104.037638)
		(width 0.0889)
		(layer "In9.Cu")
		(net "P3E_CPU1_PE3_MP_RXN<5>")
	)
	(segment
		(start 140.30579 -104.892856)
		(end 140.43152 -104.767126)
		(width 0.0889)
		(layer "In9.Cu")
		(net "P3E_CPU1_PE3_MP_RXN<5>")
	)
	(segment
		(start 83.07832 -114.365024)
		(end 97.110804 -111.558324)
		(width 0.1143)
		(layer "In9.Cu")
		(net "P3E_CPU1_PE3_MP_RXN<5>")
	)
	(segment
		(start 138.5443 -95.623888)
		(end 138.51636 -95.623888)
		(width 0.0889)
		(layer "In9.Cu")
		(net "P3E_CPU1_PE3_MP_RXN<5>")
	)
	(segment
		(start 140.593318 -99.195636)
		(end 140.598144 -99.187)
		(width 0.0889)
		(layer "In9.Cu")
		(net "P3E_CPU1_PE3_MP_RXN<5>")
	)
	(segment
		(start 58.994802 -58.107834)
		(end 59.278774 -59.52744)
		(width 0.1143)
		(layer "In9.Cu")
		(net "P3E_CPU1_PE3_MP_RXN<5>")
	)
	(segment
		(start 131.344416 -97.746566)
		(end 131.368292 -97.835974)
		(width 0.0889)
		(layer "In9.Cu")
		(net "P3E_CPU1_PE3_MP_RXN<5>")
	)
	(segment
		(start 12.670536 -39.496492)
		(end 12.860274 -39.727886)
		(width 0.1143)
		(layer "In9.Cu")
		(net "P3E_CPU1_PE3_MP_RXN<5>")
	)
	(segment
		(start 140.515086 -101.053138)
		(end 140.438378 -100.97643)
		(width 0.0889)
		(layer "In9.Cu")
		(net "P3E_CPU1_PE3_MP_RXN<5>")
	)
	(arc
		(start 133.36016 -94.633288)
		(mid 133.170231 -94.691158)
		(end 133.031484 -94.833186)
		(width 0.0889)
		(layer "In9.Cu")
		(net "P3E_CPU1_PE3_MP_RXN<5>")
	)
	(arc
		(start 135.08228 -95.623888)
		(mid 134.794135 -95.541569)
		(end 134.583424 -95.328486)
		(width 0.0889)
		(layer "In9.Cu")
		(net "P3E_CPU1_PE3_MP_RXN<5>")
	)
	(arc
		(start 131.314698 -95.823786)
		(mid 131.261228 -96.018849)
		(end 131.309872 -96.2152)
		(width 0.0889)
		(layer "In9.Cu")
		(net "P3E_CPU1_PE3_MP_RXN<5>")
	)
	(arc
		(start 137.65276 -95.128588)
		(mid 137.462831 -95.186458)
		(end 137.324084 -95.328486)
		(width 0.0889)
		(layer "In9.Cu")
		(net "P3E_CPU1_PE3_MP_RXN<5>")
	)
	(arc
		(start 140.310362 -96.619568)
		(mid 140.28593 -96.616266)
		(end 140.26134 -96.614488)
		(width 0.0889)
		(layer "In9.Cu")
		(net "P3E_CPU1_PE3_MP_RXN<5>")
	)
	(arc
		(start 140.593318 -99.786186)
		(mid 140.514096 -99.497068)
		(end 140.586968 -99.206304)
		(width 0.0889)
		(layer "In9.Cu")
		(net "P3E_CPU1_PE3_MP_RXN<5>")
	)
	(arc
		(start 135.932164 -96.118934)
		(mid 135.648947 -96.034653)
		(end 135.441944 -95.823786)
		(width 0.0889)
		(layer "In9.Cu")
		(net "P3E_CPU1_PE3_MP_RXN<5>")
	)
	(arc
		(start 132.007864 -94.833186)
		(mid 131.866707 -94.689801)
		(end 131.6736 -94.633288)
		(width 0.0889)
		(layer "In9.Cu")
		(net "P3E_CPU1_PE3_MP_RXN<5>")
	)
	(arc
		(start 138.51636 -95.623888)
		(mid 138.228215 -95.541569)
		(end 138.017504 -95.328486)
		(width 0.0889)
		(layer "In9.Cu")
		(net "P3E_CPU1_PE3_MP_RXN<5>")
	)
	(arc
		(start 134.583424 -95.328486)
		(mid 134.44468 -95.186453)
		(end 134.254748 -95.128588)
		(width 0.0889)
		(layer "In9.Cu")
		(net "P3E_CPU1_PE3_MP_RXN<5>")
	)
	(arc
		(start 140.598144 -97.2058)
		(mid 140.60568 -96.838369)
		(end 140.310362 -96.619568)
		(width 0.0889)
		(layer "In9.Cu")
		(net "P3E_CPU1_PE3_MP_RXN<5>")
	)
	(arc
		(start 140.649198 -101.836728)
		(mid 140.549194 -101.595103)
		(end 140.515086 -101.33584)
		(width 0.0889)
		(layer "In9.Cu")
		(net "P3E_CPU1_PE3_MP_RXN<5>")
	)
	(arc
		(start 131.643374 -94.633288)
		(mid 131.453445 -94.691158)
		(end 131.314698 -94.833186)
		(width 0.0889)
		(layer "In9.Cu")
		(net "P3E_CPU1_PE3_MP_RXN<5>")
	)
	(arc
		(start 140.598144 -100.1776)
		(mid 140.646899 -99.981248)
		(end 140.593318 -99.786186)
		(width 0.0889)
		(layer "In9.Cu")
		(net "P3E_CPU1_PE3_MP_RXN<5>")
	)
	(arc
		(start 131.314698 -95.232982)
		(mid 131.393829 -95.528384)
		(end 131.314698 -95.823786)
		(width 0.0889)
		(layer "In9.Cu")
		(net "P3E_CPU1_PE3_MP_RXN<5>")
	)
	(arc
		(start 139.366244 -96.118934)
		(mid 139.083027 -96.034653)
		(end 138.876024 -95.823786)
		(width 0.0889)
		(layer "In9.Cu")
		(net "P3E_CPU1_PE3_MP_RXN<5>")
	)
	(arc
		(start 133.031484 -94.833186)
		(mid 132.822876 -95.045118)
		(end 132.537454 -95.128588)
		(width 0.0889)
		(layer "In9.Cu")
		(net "P3E_CPU1_PE3_MP_RXN<5>")
	)
	(arc
		(start 131.321048 -96.234504)
		(mid 131.393846 -96.525267)
		(end 131.314698 -96.814386)
		(width 0.0889)
		(layer "In9.Cu")
		(net "P3E_CPU1_PE3_MP_RXN<5>")
	)
	(arc
		(start 135.441944 -95.823786)
		(mid 135.301865 -95.68105)
		(end 135.11022 -95.623888)
		(width 0.0889)
		(layer "In9.Cu")
		(net "P3E_CPU1_PE3_MP_RXN<5>")
	)
	(arc
		(start 140.514832 -100.514912)
		(mid 140.52855 -100.350841)
		(end 140.586968 -100.196904)
		(width 0.0889)
		(layer "In9.Cu")
		(net "P3E_CPU1_PE3_MP_RXN<5>")
	)
	(arc
		(start 132.501894 -95.128588)
		(mid 132.21647 -95.045121)
		(end 132.007864 -94.833186)
		(width 0.0889)
		(layer "In9.Cu")
		(net "P3E_CPU1_PE3_MP_RXN<5>")
	)
	(arc
		(start 140.586968 -97.794318)
		(mid 140.51417 -97.503555)
		(end 140.593318 -97.214436)
		(width 0.0889)
		(layer "In9.Cu")
		(net "P3E_CPU1_PE3_MP_RXN<5>")
	)
	(arc
		(start 136.797288 -95.623888)
		(mid 136.605646 -95.681054)
		(end 136.465564 -95.823786)
		(width 0.0889)
		(layer "In9.Cu")
		(net "P3E_CPU1_PE3_MP_RXN<5>")
	)
	(arc
		(start 134.218934 -95.128588)
		(mid 133.93351 -95.045121)
		(end 133.724904 -94.833186)
		(width 0.0889)
		(layer "In9.Cu")
		(net "P3E_CPU1_PE3_MP_RXN<5>")
	)
	(arc
		(start 140.593318 -98.795586)
		(mid 140.514187 -98.500184)
		(end 140.593318 -98.204782)
		(width 0.0889)
		(layer "In9.Cu")
		(net "P3E_CPU1_PE3_MP_RXN<5>")
	)
	(arc
		(start 140.701014 -102.07625)
		(mid 140.693868 -101.952432)
		(end 140.649198 -101.836728)
		(width 0.0889)
		(layer "In9.Cu")
		(net "P3E_CPU1_PE3_MP_RXN<5>")
	)
	(arc
		(start 139.734544 -96.319086)
		(mid 139.592861 -96.175282)
		(end 139.39901 -96.118934)
		(width 0.0889)
		(layer "In9.Cu")
		(net "P3E_CPU1_PE3_MP_RXN<5>")
	)
	(arc
		(start 131.314698 -96.814386)
		(mid 131.261228 -97.009449)
		(end 131.309872 -97.2058)
		(width 0.0889)
		(layer "In9.Cu")
		(net "P3E_CPU1_PE3_MP_RXN<5>")
	)
	(arc
		(start 138.876024 -95.823786)
		(mid 138.735945 -95.68105)
		(end 138.5443 -95.623888)
		(width 0.0889)
		(layer "In9.Cu")
		(net "P3E_CPU1_PE3_MP_RXN<5>")
	)
	(arc
		(start 136.465564 -95.823786)
		(mid 136.25856 -96.03465)
		(end 135.975344 -96.118934)
		(width 0.0889)
		(layer "In9.Cu")
		(net "P3E_CPU1_PE3_MP_RXN<5>")
	)
	(arc
		(start 140.593318 -98.204782)
		(mid 140.646817 -98.004884)
		(end 140.593318 -97.804986)
		(width 0.0889)
		(layer "In9.Cu")
		(net "P3E_CPU1_PE3_MP_RXN<5>")
	)
	(arc
		(start 137.324084 -95.328486)
		(mid 137.113371 -95.541565)
		(end 136.825228 -95.623888)
		(width 0.0889)
		(layer "In9.Cu")
		(net "P3E_CPU1_PE3_MP_RXN<5>")
	)
	(arc
		(start 140.598144 -99.187)
		(mid 140.646899 -98.990648)
		(end 140.593318 -98.795586)
		(width 0.0889)
		(layer "In9.Cu")
		(net "P3E_CPU1_PE3_MP_RXN<5>")
	)
	(arc
		(start 131.314698 -94.833186)
		(mid 131.261199 -95.033084)
		(end 131.314698 -95.232982)
		(width 0.0889)
		(layer "In9.Cu")
		(net "P3E_CPU1_PE3_MP_RXN<5>")
	)
	(arc
		(start 138.017504 -95.328486)
		(mid 137.87876 -95.186453)
		(end 137.688828 -95.128588)
		(width 0.0889)
		(layer "In9.Cu")
		(net "P3E_CPU1_PE3_MP_RXN<5>")
	)
	(arc
		(start 140.228574 -96.614488)
		(mid 139.94315 -96.531021)
		(end 139.734544 -96.319086)
		(width 0.0889)
		(layer "In9.Cu")
		(net "P3E_CPU1_PE3_MP_RXN<5>")
	)
	(arc
		(start 131.321048 -97.225104)
		(mid 131.393443 -97.483116)
		(end 131.344416 -97.746566)
		(width 0.0889)
		(layer "In9.Cu")
		(net "P3E_CPU1_PE3_MP_RXN<5>")
	)
	(arc
		(start 133.724904 -94.833186)
		(mid 133.58616 -94.691153)
		(end 133.396228 -94.633288)
		(width 0.0889)
		(layer "In9.Cu")
		(net "P3E_CPU1_PE3_MP_RXN<5>")
	)
	(segment
		(start 129.372868 -98.005138)
		(end 129.944368 -98.005138)
		(width 0.1143)
		(layer "F.Cu")
		(net "P3E_CPU1_PE3_MP_RXN<4>")
	)
	(via
		(at 129.944368 -98.005138)
		(size 0.508)
		(drill 0.254)
		(layers "F.Cu" "B.Cu")
		(net "P3E_CPU1_PE3_MP_RXN<4>")
	)
	(segment
		(start 141.586966 -102.415848)
		(end 141.536166 -102.466648)
		(width 0.0889)
		(layer "In9.Cu")
		(net "P3E_CPU1_PE3_MP_RXN<4>")
	)
	(segment
		(start 57.672986 -63.873634)
		(end 58.50382 -59.720734)
		(width 0.1143)
		(layer "In9.Cu")
		(net "P3E_CPU1_PE3_MP_RXN<4>")
	)
	(segment
		(start 130.791712 -94.137988)
		(end 130.815842 -94.137988)
		(width 0.0889)
		(layer "In9.Cu")
		(net "P3E_CPU1_PE3_MP_RXN<4>")
	)
	(segment
		(start 2.0955 -37.24148)
		(end 1.62687 -37.71011)
		(width 0.1143)
		(layer "In9.Cu")
		(net "P3E_CPU1_PE3_MP_RXN<4>")
	)
	(segment
		(start 132.004562 -93.836998)
		(end 132.007864 -93.84284)
		(width 0.0889)
		(layer "In9.Cu")
		(net "P3E_CPU1_PE3_MP_RXN<4>")
	)
	(segment
		(start 2.403348 -36.564062)
		(end 2.0955 -36.87191)
		(width 0.1143)
		(layer "In9.Cu")
		(net "P3E_CPU1_PE3_MP_RXN<4>")
	)
	(segment
		(start 139.370054 -95.128588)
		(end 139.405868 -95.128588)
		(width 0.0889)
		(layer "In9.Cu")
		(net "P3E_CPU1_PE3_MP_RXN<4>")
	)
	(segment
		(start 57.52465 -82.08264)
		(end 58.093102 -81.019396)
		(width 0.1143)
		(layer "In9.Cu")
		(net "P3E_CPU1_PE3_MP_RXN<4>")
	)
	(segment
		(start 97.698306 -112.784128)
		(end 97.362264 -112.716818)
		(width 0.1143)
		(layer "In9.Cu")
		(net "P3E_CPU1_PE3_MP_RXN<4>")
	)
	(segment
		(start 52.526946 -49.8221)
		(end 41.08196 -42.192448)
		(width 0.1143)
		(layer "In9.Cu")
		(net "P3E_CPU1_PE3_MP_RXN<4>")
	)
	(segment
		(start 141.400276 -100.392484)
		(end 141.299184 -100.493576)
		(width 0.0889)
		(layer "In9.Cu")
		(net "P3E_CPU1_PE3_MP_RXN<4>")
	)
	(segment
		(start 60.02274 -75.277218)
		(end 57.28462 -70.156324)
		(width 0.1143)
		(layer "In9.Cu")
		(net "P3E_CPU1_PE3_MP_RXN<4>")
	)
	(segment
		(start 57.722262 -89.306146)
		(end 58.21299 -86.852252)
		(width 0.1143)
		(layer "In9.Cu")
		(net "P3E_CPU1_PE3_MP_RXN<4>")
	)
	(segment
		(start 10.37971 -38.218618)
		(end 10.392664 -37.985446)
		(width 0.1143)
		(layer "In9.Cu")
		(net "P3E_CPU1_PE3_MP_RXN<4>")
	)
	(segment
		(start 141.327886 -99.513136)
		(end 141.400276 -99.585526)
		(width 0.0889)
		(layer "In9.Cu")
		(net "P3E_CPU1_PE3_MP_RXN<4>")
	)
	(segment
		(start 130.462528 -94.748604)
		(end 130.456178 -94.737936)
		(width 0.0889)
		(layer "In9.Cu")
		(net "P3E_CPU1_PE3_MP_RXN<4>")
	)
	(segment
		(start 141.586966 -101.263196)
		(end 141.586966 -101.844094)
		(width 0.0889)
		(layer "In9.Cu")
		(net "P3E_CPU1_PE3_MP_RXN<4>")
	)
	(segment
		(start 2.0955 -36.87191)
		(end 2.0955 -37.24148)
		(width 0.1143)
		(layer "In9.Cu")
		(net "P3E_CPU1_PE3_MP_RXN<4>")
	)
	(segment
		(start 31.016448 -40.1193)
		(end 29.680662 -40.801544)
		(width 0.1143)
		(layer "In9.Cu")
		(net "P3E_CPU1_PE3_MP_RXN<4>")
	)
	(segment
		(start 57.52465 -83.054952)
		(end 57.52465 -82.08264)
		(width 0.1143)
		(layer "In9.Cu")
		(net "P3E_CPU1_PE3_MP_RXN<4>")
	)
	(segment
		(start 135.073644 -94.633288)
		(end 135.113268 -94.633288)
		(width 0.0889)
		(layer "In9.Cu")
		(net "P3E_CPU1_PE3_MP_RXN<4>")
	)
	(segment
		(start 97.362264 -112.716818)
		(end 97.1677 -112.846104)
		(width 0.1143)
		(layer "In9.Cu")
		(net "P3E_CPU1_PE3_MP_RXN<4>")
	)
	(segment
		(start 139.552426 -107.023916)
		(end 139.319 -107.023916)
		(width 0.1143)
		(layer "In9.Cu")
		(net "P3E_CPU1_PE3_MP_RXN<4>")
	)
	(segment
		(start 129.944368 -98.005138)
		(end 129.944368 -97.667064)
		(width 0.0889)
		(layer "In9.Cu")
		(net "P3E_CPU1_PE3_MP_RXN<4>")
	)
	(segment
		(start 57.8231 -66.016886)
		(end 57.8231 -64.624712)
		(width 0.1143)
		(layer "In9.Cu")
		(net "P3E_CPU1_PE3_MP_RXN<4>")
	)
	(segment
		(start 141.586966 -102.169722)
		(end 141.586966 -102.415848)
		(width 0.0889)
		(layer "In9.Cu")
		(net "P3E_CPU1_PE3_MP_RXN<4>")
	)
	(segment
		(start 130.451352 -95.337122)
		(end 130.456178 -95.328486)
		(width 0.0889)
		(layer "In9.Cu")
		(net "P3E_CPU1_PE3_MP_RXN<4>")
	)
	(segment
		(start 58.21299 -83.743292)
		(end 57.52465 -83.054952)
		(width 0.1143)
		(layer "In9.Cu")
		(net "P3E_CPU1_PE3_MP_RXN<4>")
	)
	(segment
		(start 140.2334 -95.623888)
		(end 140.26134 -95.623888)
		(width 0.0889)
		(layer "In9.Cu")
		(net "P3E_CPU1_PE3_MP_RXN<4>")
	)
	(segment
		(start 122.960892 -116.376704)
		(end 103.23322 -112.431322)
		(width 0.1143)
		(layer "In9.Cu")
		(net "P3E_CPU1_PE3_MP_RXN<4>")
	)
	(segment
		(start 29.680662 -40.801544)
		(end 28.500578 -41.966388)
		(width 0.1143)
		(layer "In9.Cu")
		(net "P3E_CPU1_PE3_MP_RXN<4>")
	)
	(segment
		(start 139.07643 -107.499912)
		(end 132.00888 -114.567462)
		(width 0.1143)
		(layer "In9.Cu")
		(net "P3E_CPU1_PE3_MP_RXN<4>")
	)
	(segment
		(start 58.23712 -58.387234)
		(end 58.236866 -58.387234)
		(width 0.1143)
		(layer "In9.Cu")
		(net "P3E_CPU1_PE3_MP_RXN<4>")
	)
	(segment
		(start 34.224468 -40.1193)
		(end 31.016448 -40.1193)
		(width 0.1143)
		(layer "In9.Cu")
		(net "P3E_CPU1_PE3_MP_RXN<4>")
	)
	(segment
		(start 135.935974 -95.128588)
		(end 135.971534 -95.128588)
		(width 0.0889)
		(layer "In9.Cu")
		(net "P3E_CPU1_PE3_MP_RXN<4>")
	)
	(segment
		(start 141.400276 -99.262946)
		(end 141.327886 -99.335336)
		(width 0.0889)
		(layer "In9.Cu")
		(net "P3E_CPU1_PE3_MP_RXN<4>")
	)
	(segment
		(start 17.672558 -41.261284)
		(end 12.666218 -40.438832)
		(width 0.1143)
		(layer "In9.Cu")
		(net "P3E_CPU1_PE3_MP_RXN<4>")
	)
	(segment
		(start 10.94486 -39.383462)
		(end 10.608056 -38.474396)
		(width 0.1143)
		(layer "In9.Cu")
		(net "P3E_CPU1_PE3_MP_RXN<4>")
	)
	(segment
		(start 62.967616 -107.25912)
		(end 60.60313 -103.713026)
		(width 0.1143)
		(layer "In9.Cu")
		(net "P3E_CPU1_PE3_MP_RXN<4>")
	)
	(segment
		(start 139.319 -107.023916)
		(end 139.07643 -107.266232)
		(width 0.1143)
		(layer "In9.Cu")
		(net "P3E_CPU1_PE3_MP_RXN<4>")
	)
	(segment
		(start 136.79424 -94.633288)
		(end 136.833864 -94.633288)
		(width 0.0889)
		(layer "In9.Cu")
		(net "P3E_CPU1_PE3_MP_RXN<4>")
	)
	(segment
		(start 141.480032 -97.291398)
		(end 141.48816 -97.306638)
		(width 0.0889)
		(layer "In9.Cu")
		(net "P3E_CPU1_PE3_MP_RXN<4>")
	)
	(segment
		(start 141.299184 -100.671376)
		(end 141.400276 -100.772468)
		(width 0.0889)
		(layer "In9.Cu")
		(net "P3E_CPU1_PE3_MP_RXN<4>")
	)
	(segment
		(start 141.482318 -98.28657)
		(end 141.48816 -98.297492)
		(width 0.0889)
		(layer "In9.Cu")
		(net "P3E_CPU1_PE3_MP_RXN<4>")
	)
	(segment
		(start 141.400276 -99.792028)
		(end 141.299184 -99.89312)
		(width 0.0889)
		(layer "In9.Cu")
		(net "P3E_CPU1_PE3_MP_RXN<4>")
	)
	(segment
		(start 57.8231 -64.624712)
		(end 57.672986 -63.873634)
		(width 0.1143)
		(layer "In9.Cu")
		(net "P3E_CPU1_PE3_MP_RXN<4>")
	)
	(segment
		(start 141.327886 -99.335336)
		(end 141.327886 -99.513136)
		(width 0.0889)
		(layer "In9.Cu")
		(net "P3E_CPU1_PE3_MP_RXN<4>")
	)
	(segment
		(start 139.07643 -107.266232)
		(end 139.07643 -107.499912)
		(width 0.1143)
		(layer "In9.Cu")
		(net "P3E_CPU1_PE3_MP_RXN<4>")
	)
	(segment
		(start 57.28462 -67.317112)
		(end 57.8231 -66.016886)
		(width 0.1143)
		(layer "In9.Cu")
		(net "P3E_CPU1_PE3_MP_RXN<4>")
	)
	(segment
		(start 97.1677 -112.846104)
		(end 95.572834 -112.526064)
		(width 0.1143)
		(layer "In9.Cu")
		(net "P3E_CPU1_PE3_MP_RXN<4>")
	)
	(segment
		(start 141.395958 -96.226376)
		(end 141.417294 -96.2533)
		(width 0.0889)
		(layer "In9.Cu")
		(net "P3E_CPU1_PE3_MP_RXN<4>")
	)
	(segment
		(start 141.400276 -100.172012)
		(end 141.400276 -100.392484)
		(width 0.0889)
		(layer "In9.Cu")
		(net "P3E_CPU1_PE3_MP_RXN<4>")
	)
	(segment
		(start 103.23322 -112.431322)
		(end 99.160076 -113.2459)
		(width 0.1143)
		(layer "In9.Cu")
		(net "P3E_CPU1_PE3_MP_RXN<4>")
	)
	(segment
		(start 141.513052 -101.918008)
		(end 141.513052 -102.095808)
		(width 0.0889)
		(layer "In9.Cu")
		(net "P3E_CPU1_PE3_MP_RXN<4>")
	)
	(segment
		(start 134.22376 -94.137988)
		(end 134.24789 -94.137988)
		(width 0.0889)
		(layer "In9.Cu")
		(net "P3E_CPU1_PE3_MP_RXN<4>")
	)
	(segment
		(start 24.687784 -42.505884)
		(end 24.506428 -42.627296)
		(width 0.1143)
		(layer "In9.Cu")
		(net "P3E_CPU1_PE3_MP_RXN<4>")
	)
	(segment
		(start 141.586966 -101.844094)
		(end 141.513052 -101.918008)
		(width 0.0889)
		(layer "In9.Cu")
		(net "P3E_CPU1_PE3_MP_RXN<4>")
	)
	(segment
		(start 83.04149 -115.03279)
		(end 71.021448 -112.62868)
		(width 0.1143)
		(layer "In9.Cu")
		(net "P3E_CPU1_PE3_MP_RXN<4>")
	)
	(segment
		(start 41.08196 -42.192448)
		(end 34.224468 -40.1193)
		(width 0.1143)
		(layer "In9.Cu")
		(net "P3E_CPU1_PE3_MP_RXN<4>")
	)
	(segment
		(start 132.00888 -114.567462)
		(end 122.960892 -116.376704)
		(width 0.1143)
		(layer "In9.Cu")
		(net "P3E_CPU1_PE3_MP_RXN<4>")
	)
	(segment
		(start 60.11037 -77.997558)
		(end 60.338716 -76.85532)
		(width 0.1143)
		(layer "In9.Cu")
		(net "P3E_CPU1_PE3_MP_RXN<4>")
	)
	(segment
		(start 130.456178 -96.319086)
		(end 130.462528 -96.308418)
		(width 0.0889)
		(layer "In9.Cu")
		(net "P3E_CPU1_PE3_MP_RXN<4>")
	)
	(segment
		(start 141.169136 -96.12376)
		(end 141.183614 -96.12376)
		(width 0.0889)
		(layer "In9.Cu")
		(net "P3E_CPU1_PE3_MP_RXN<4>")
	)
	(segment
		(start 141.400276 -100.772468)
		(end 141.400276 -101.076506)
		(width 0.0889)
		(layer "In9.Cu")
		(net "P3E_CPU1_PE3_MP_RXN<4>")
	)
	(segment
		(start 141.536166 -102.466648)
		(end 141.536166 -102.488746)
		(width 0.0889)
		(layer "In9.Cu")
		(net "P3E_CPU1_PE3_MP_RXN<4>")
	)
	(segment
		(start 141.400276 -99.056444)
		(end 141.400276 -99.262946)
		(width 0.0889)
		(layer "In9.Cu")
		(net "P3E_CPU1_PE3_MP_RXN<4>")
	)
	(segment
		(start 71.021448 -112.62868)
		(end 62.967616 -107.25912)
		(width 0.1143)
		(layer "In9.Cu")
		(net "P3E_CPU1_PE3_MP_RXN<4>")
	)
	(segment
		(start 8.552942 -36.564062)
		(end 2.403348 -36.564062)
		(width 0.1143)
		(layer "In9.Cu")
		(net "P3E_CPU1_PE3_MP_RXN<4>")
	)
	(segment
		(start 99.160076 -113.2459)
		(end 97.827846 -112.978438)
		(width 0.1143)
		(layer "In9.Cu")
		(net "P3E_CPU1_PE3_MP_RXN<4>")
	)
	(segment
		(start 28.500578 -41.966388)
		(end 26.597356 -42.819574)
		(width 0.1143)
		(layer "In9.Cu")
		(net "P3E_CPU1_PE3_MP_RXN<4>")
	)
	(segment
		(start 129.944368 -97.667064)
		(end 130.009646 -97.601786)
		(width 0.0889)
		(layer "In9.Cu")
		(net "P3E_CPU1_PE3_MP_RXN<4>")
	)
	(segment
		(start 25.024588 -42.573448)
		(end 24.687784 -42.505884)
		(width 0.1143)
		(layer "In9.Cu")
		(net "P3E_CPU1_PE3_MP_RXN<4>")
	)
	(segment
		(start 141.103858 -96.11868)
		(end 141.105636 -96.11868)
		(width 0.0889)
		(layer "In9.Cu")
		(net "P3E_CPU1_PE3_MP_RXN<4>")
	)
	(segment
		(start 130.451352 -96.327722)
		(end 130.456178 -96.319086)
		(width 0.0889)
		(layer "In9.Cu")
		(net "P3E_CPU1_PE3_MP_RXN<4>")
	)
	(segment
		(start 97.827846 -112.978438)
		(end 97.698306 -112.784128)
		(width 0.1143)
		(layer "In9.Cu")
		(net "P3E_CPU1_PE3_MP_RXN<4>")
	)
	(segment
		(start 10.164318 -37.729922)
		(end 9.931146 -37.716714)
		(width 0.1143)
		(layer "In9.Cu")
		(net "P3E_CPU1_PE3_MP_RXN<4>")
	)
	(segment
		(start 138.507724 -94.633288)
		(end 138.547348 -94.633288)
		(width 0.0889)
		(layer "In9.Cu")
		(net "P3E_CPU1_PE3_MP_RXN<4>")
	)
	(segment
		(start 9.457436 -37.186362)
		(end 8.552942 -36.564062)
		(width 0.1143)
		(layer "In9.Cu")
		(net "P3E_CPU1_PE3_MP_RXN<4>")
	)
	(segment
		(start 1.62687 -37.71011)
		(end 1.599946 -37.71011)
		(width 0.1143)
		(layer "In9.Cu")
		(net "P3E_CPU1_PE3_MP_RXN<4>")
	)
	(segment
		(start 25.736042 -42.873168)
		(end 25.145492 -42.754804)
		(width 0.1143)
		(layer "In9.Cu")
		(net "P3E_CPU1_PE3_MP_RXN<4>")
	)
	(segment
		(start 60.338716 -76.85532)
		(end 60.02274 -75.277218)
		(width 0.1143)
		(layer "In9.Cu")
		(net "P3E_CPU1_PE3_MP_RXN<4>")
	)
	(segment
		(start 132.501894 -94.137988)
		(end 132.532628 -94.137988)
		(width 0.0889)
		(layer "In9.Cu")
		(net "P3E_CPU1_PE3_MP_RXN<4>")
	)
	(segment
		(start 141.513052 -102.095808)
		(end 141.586966 -102.169722)
		(width 0.0889)
		(layer "In9.Cu")
		(net "P3E_CPU1_PE3_MP_RXN<4>")
	)
	(segment
		(start 12.666218 -40.438832)
		(end 11.094212 -39.556944)
		(width 0.1143)
		(layer "In9.Cu")
		(net "P3E_CPU1_PE3_MP_RXN<4>")
	)
	(segment
		(start 11.094212 -39.556944)
		(end 10.94486 -39.383462)
		(width 0.1143)
		(layer "In9.Cu")
		(net "P3E_CPU1_PE3_MP_RXN<4>")
	)
	(segment
		(start 141.299184 -99.89312)
		(end 141.299184 -100.07092)
		(width 0.0889)
		(layer "In9.Cu")
		(net "P3E_CPU1_PE3_MP_RXN<4>")
	)
	(segment
		(start 141.400276 -101.076506)
		(end 141.586966 -101.263196)
		(width 0.0889)
		(layer "In9.Cu")
		(net "P3E_CPU1_PE3_MP_RXN<4>")
	)
	(segment
		(start 10.392664 -37.985446)
		(end 10.164318 -37.729922)
		(width 0.1143)
		(layer "In9.Cu")
		(net "P3E_CPU1_PE3_MP_RXN<4>")
	)
	(segment
		(start 141.400276 -99.585526)
		(end 141.400276 -99.792028)
		(width 0.0889)
		(layer "In9.Cu")
		(net "P3E_CPU1_PE3_MP_RXN<4>")
	)
	(segment
		(start 24.506428 -42.627296)
		(end 17.672558 -41.261284)
		(width 0.1143)
		(layer "In9.Cu")
		(net "P3E_CPU1_PE3_MP_RXN<4>")
	)
	(segment
		(start 141.299184 -100.07092)
		(end 141.400276 -100.172012)
		(width 0.0889)
		(layer "In9.Cu")
		(net "P3E_CPU1_PE3_MP_RXN<4>")
	)
	(segment
		(start 95.572834 -112.526064)
		(end 83.04149 -115.03279)
		(width 0.1143)
		(layer "In9.Cu")
		(net "P3E_CPU1_PE3_MP_RXN<4>")
	)
	(segment
		(start 58.236866 -58.387234)
		(end 52.526946 -49.8221)
		(width 0.1143)
		(layer "In9.Cu")
		(net "P3E_CPU1_PE3_MP_RXN<4>")
	)
	(segment
		(start 58.50382 -59.720734)
		(end 58.23712 -58.387234)
		(width 0.1143)
		(layer "In9.Cu")
		(net "P3E_CPU1_PE3_MP_RXN<4>")
	)
	(segment
		(start 10.608056 -38.474396)
		(end 10.37971 -38.218618)
		(width 0.1143)
		(layer "In9.Cu")
		(net "P3E_CPU1_PE3_MP_RXN<4>")
	)
	(segment
		(start 58.093102 -81.019396)
		(end 60.11037 -77.997558)
		(width 0.1143)
		(layer "In9.Cu")
		(net "P3E_CPU1_PE3_MP_RXN<4>")
	)
	(segment
		(start 141.299184 -100.493576)
		(end 141.299184 -100.671376)
		(width 0.0889)
		(layer "In9.Cu")
		(net "P3E_CPU1_PE3_MP_RXN<4>")
	)
	(segment
		(start 9.931146 -37.716714)
		(end 9.457436 -37.186362)
		(width 0.1143)
		(layer "In9.Cu")
		(net "P3E_CPU1_PE3_MP_RXN<4>")
	)
	(segment
		(start 57.28462 -70.156324)
		(end 57.28462 -67.317112)
		(width 0.1143)
		(layer "In9.Cu")
		(net "P3E_CPU1_PE3_MP_RXN<4>")
	)
	(segment
		(start 60.60313 -103.713026)
		(end 57.722262 -89.306146)
		(width 0.1143)
		(layer "In9.Cu")
		(net "P3E_CPU1_PE3_MP_RXN<4>")
	)
	(segment
		(start 133.363208 -93.642688)
		(end 133.39318 -93.642688)
		(width 0.0889)
		(layer "In9.Cu")
		(net "P3E_CPU1_PE3_MP_RXN<4>")
	)
	(segment
		(start 141.536166 -105.040176)
		(end 139.552426 -107.023916)
		(width 0.1143)
		(layer "In9.Cu")
		(net "P3E_CPU1_PE3_MP_RXN<4>")
	)
	(segment
		(start 141.536166 -102.488746)
		(end 141.536166 -105.040176)
		(width 0.1143)
		(layer "In9.Cu")
		(net "P3E_CPU1_PE3_MP_RXN<4>")
	)
	(segment
		(start 25.145492 -42.754804)
		(end 25.024588 -42.573448)
		(width 0.1143)
		(layer "In9.Cu")
		(net "P3E_CPU1_PE3_MP_RXN<4>")
	)
	(segment
		(start 26.597356 -42.819574)
		(end 25.736042 -42.873168)
		(width 0.1143)
		(layer "In9.Cu")
		(net "P3E_CPU1_PE3_MP_RXN<4>")
	)
	(segment
		(start 58.21299 -86.852252)
		(end 58.21299 -83.743292)
		(width 0.1143)
		(layer "In9.Cu")
		(net "P3E_CPU1_PE3_MP_RXN<4>")
	)
	(arc
		(start 132.007864 -93.84284)
		(mid 132.025484 -93.871304)
		(end 132.044694 -93.89872)
		(width 0.0889)
		(layer "In9.Cu")
		(net "P3E_CPU1_PE3_MP_RXN<4>")
	)
	(arc
		(start 132.532628 -94.137988)
		(mid 132.820773 -94.055669)
		(end 133.031484 -93.842586)
		(width 0.0889)
		(layer "In9.Cu")
		(net "P3E_CPU1_PE3_MP_RXN<4>")
	)
	(arc
		(start 133.39318 -93.642688)
		(mid 133.584822 -93.699854)
		(end 133.724904 -93.842586)
		(width 0.0889)
		(layer "In9.Cu")
		(net "P3E_CPU1_PE3_MP_RXN<4>")
	)
	(arc
		(start 130.456178 -96.719136)
		(mid 130.402708 -96.524073)
		(end 130.451352 -96.327722)
		(width 0.0889)
		(layer "In9.Cu")
		(net "P3E_CPU1_PE3_MP_RXN<4>")
	)
	(arc
		(start 139.405868 -95.128588)
		(mid 139.595797 -95.186458)
		(end 139.734544 -95.328486)
		(width 0.0889)
		(layer "In9.Cu")
		(net "P3E_CPU1_PE3_MP_RXN<4>")
	)
	(arc
		(start 130.456178 -94.737936)
		(mid 130.453595 -94.342689)
		(end 130.791712 -94.137988)
		(width 0.0889)
		(layer "In9.Cu")
		(net "P3E_CPU1_PE3_MP_RXN<4>")
	)
	(arc
		(start 140.26134 -95.623888)
		(mid 140.452982 -95.681054)
		(end 140.593064 -95.823786)
		(width 0.0889)
		(layer "In9.Cu")
		(net "P3E_CPU1_PE3_MP_RXN<4>")
	)
	(arc
		(start 135.441944 -94.833186)
		(mid 135.650552 -95.045118)
		(end 135.935974 -95.128588)
		(width 0.0889)
		(layer "In9.Cu")
		(net "P3E_CPU1_PE3_MP_RXN<4>")
	)
	(arc
		(start 132.044694 -93.89872)
		(mid 132.2458 -94.0709)
		(end 132.501894 -94.137988)
		(width 0.0889)
		(layer "In9.Cu")
		(net "P3E_CPU1_PE3_MP_RXN<4>")
	)
	(arc
		(start 138.547348 -94.633288)
		(mid 138.737277 -94.691158)
		(end 138.876024 -94.833186)
		(width 0.0889)
		(layer "In9.Cu")
		(net "P3E_CPU1_PE3_MP_RXN<4>")
	)
	(arc
		(start 130.815842 -94.137988)
		(mid 131.103987 -94.055669)
		(end 131.314698 -93.842586)
		(width 0.0889)
		(layer "In9.Cu")
		(net "P3E_CPU1_PE3_MP_RXN<4>")
	)
	(arc
		(start 141.417294 -96.2533)
		(mid 141.515078 -96.478185)
		(end 141.48816 -96.72193)
		(width 0.0889)
		(layer "In9.Cu")
		(net "P3E_CPU1_PE3_MP_RXN<4>")
	)
	(arc
		(start 134.24789 -94.137988)
		(mid 134.44174 -94.194338)
		(end 134.583424 -94.33814)
		(width 0.0889)
		(layer "In9.Cu")
		(net "P3E_CPU1_PE3_MP_RXN<4>")
	)
	(arc
		(start 137.324084 -94.33814)
		(mid 137.670794 -94.137829)
		(end 138.017504 -94.33814)
		(width 0.0889)
		(layer "In9.Cu")
		(net "P3E_CPU1_PE3_MP_RXN<4>")
	)
	(arc
		(start 141.105636 -96.11868)
		(mid 141.137488 -96.119949)
		(end 141.169136 -96.12376)
		(width 0.0889)
		(layer "In9.Cu")
		(net "P3E_CPU1_PE3_MP_RXN<4>")
	)
	(arc
		(start 131.646676 -93.642942)
		(mid 131.852103 -93.691122)
		(end 132.004562 -93.836998)
		(width 0.0889)
		(layer "In9.Cu")
		(net "P3E_CPU1_PE3_MP_RXN<4>")
	)
	(arc
		(start 135.971534 -95.128588)
		(mid 136.256958 -95.045121)
		(end 136.465564 -94.833186)
		(width 0.0889)
		(layer "In9.Cu")
		(net "P3E_CPU1_PE3_MP_RXN<4>")
	)
	(arc
		(start 141.48816 -98.70313)
		(mid 141.422553 -98.8744)
		(end 141.400276 -99.056444)
		(width 0.0889)
		(layer "In9.Cu")
		(net "P3E_CPU1_PE3_MP_RXN<4>")
	)
	(arc
		(start 141.48816 -98.297492)
		(mid 141.537369 -98.468136)
		(end 141.514068 -98.644202)
		(width 0.0889)
		(layer "In9.Cu")
		(net "P3E_CPU1_PE3_MP_RXN<4>")
	)
	(arc
		(start 141.48816 -97.306638)
		(mid 141.538573 -97.509584)
		(end 141.48816 -97.71253)
		(width 0.0889)
		(layer "In9.Cu")
		(net "P3E_CPU1_PE3_MP_RXN<4>")
	)
	(arc
		(start 133.031484 -93.842586)
		(mid 133.171563 -93.69985)
		(end 133.363208 -93.642688)
		(width 0.0889)
		(layer "In9.Cu")
		(net "P3E_CPU1_PE3_MP_RXN<4>")
	)
	(arc
		(start 139.734544 -95.328486)
		(mid 139.945257 -95.541565)
		(end 140.2334 -95.623888)
		(width 0.0889)
		(layer "In9.Cu")
		(net "P3E_CPU1_PE3_MP_RXN<4>")
	)
	(arc
		(start 131.314698 -93.842586)
		(mid 131.454937 -93.699963)
		(end 131.646676 -93.642942)
		(width 0.0889)
		(layer "In9.Cu")
		(net "P3E_CPU1_PE3_MP_RXN<4>")
	)
	(arc
		(start 141.183614 -96.12376)
		(mid 141.301534 -96.150758)
		(end 141.395958 -96.226376)
		(width 0.0889)
		(layer "In9.Cu")
		(net "P3E_CPU1_PE3_MP_RXN<4>")
	)
	(arc
		(start 130.456178 -95.328486)
		(mid 130.5354 -95.039368)
		(end 130.462528 -94.748604)
		(width 0.0889)
		(layer "In9.Cu")
		(net "P3E_CPU1_PE3_MP_RXN<4>")
	)
	(arc
		(start 138.017504 -94.33814)
		(mid 138.224508 -94.549004)
		(end 138.507724 -94.633288)
		(width 0.0889)
		(layer "In9.Cu")
		(net "P3E_CPU1_PE3_MP_RXN<4>")
	)
	(arc
		(start 136.833864 -94.633288)
		(mid 137.117081 -94.549007)
		(end 137.324084 -94.33814)
		(width 0.0889)
		(layer "In9.Cu")
		(net "P3E_CPU1_PE3_MP_RXN<4>")
	)
	(arc
		(start 135.113268 -94.633288)
		(mid 135.303197 -94.691158)
		(end 135.441944 -94.833186)
		(width 0.0889)
		(layer "In9.Cu")
		(net "P3E_CPU1_PE3_MP_RXN<4>")
	)
	(arc
		(start 141.48816 -97.71253)
		(mid 141.415397 -97.998833)
		(end 141.482318 -98.28657)
		(width 0.0889)
		(layer "In9.Cu")
		(net "P3E_CPU1_PE3_MP_RXN<4>")
	)
	(arc
		(start 136.465564 -94.833186)
		(mid 136.604308 -94.691153)
		(end 136.79424 -94.633288)
		(width 0.0889)
		(layer "In9.Cu")
		(net "P3E_CPU1_PE3_MP_RXN<4>")
	)
	(arc
		(start 138.876024 -94.833186)
		(mid 139.084632 -95.045118)
		(end 139.370054 -95.128588)
		(width 0.0889)
		(layer "In9.Cu")
		(net "P3E_CPU1_PE3_MP_RXN<4>")
	)
	(arc
		(start 130.009646 -97.601786)
		(mid 130.471615 -97.281244)
		(end 130.456178 -96.719136)
		(width 0.0889)
		(layer "In9.Cu")
		(net "P3E_CPU1_PE3_MP_RXN<4>")
	)
	(arc
		(start 133.724904 -93.842586)
		(mid 133.935617 -94.055665)
		(end 134.22376 -94.137988)
		(width 0.0889)
		(layer "In9.Cu")
		(net "P3E_CPU1_PE3_MP_RXN<4>")
	)
	(arc
		(start 141.48816 -96.72193)
		(mid 141.415428 -97.005677)
		(end 141.480032 -97.291398)
		(width 0.0889)
		(layer "In9.Cu")
		(net "P3E_CPU1_PE3_MP_RXN<4>")
	)
	(arc
		(start 140.593064 -95.823786)
		(mid 140.808918 -96.039767)
		(end 141.103858 -96.11868)
		(width 0.0889)
		(layer "In9.Cu")
		(net "P3E_CPU1_PE3_MP_RXN<4>")
	)
	(arc
		(start 134.583424 -94.33814)
		(mid 134.790428 -94.549004)
		(end 135.073644 -94.633288)
		(width 0.0889)
		(layer "In9.Cu")
		(net "P3E_CPU1_PE3_MP_RXN<4>")
	)
	(arc
		(start 130.462528 -96.308418)
		(mid 130.535326 -96.017655)
		(end 130.456178 -95.728536)
		(width 0.0889)
		(layer "In9.Cu")
		(net "P3E_CPU1_PE3_MP_RXN<4>")
	)
	(arc
		(start 130.456178 -95.728536)
		(mid 130.402708 -95.533473)
		(end 130.451352 -95.337122)
		(width 0.0889)
		(layer "In9.Cu")
		(net "P3E_CPU1_PE3_MP_RXN<4>")
	)
	(arc
		(start 141.514068 -98.644202)
		(mid 141.5022 -98.674143)
		(end 141.48816 -98.70313)
		(width 0.0889)
		(layer "In9.Cu")
		(net "P3E_CPU1_PE3_MP_RXN<4>")
	)
	(segment
		(start 126.797308 -98.500184)
		(end 127.368808 -98.500184)
		(width 0.1143)
		(layer "F.Cu")
		(net "P3E_CPU1_PE3_MP_RXN<3>")
	)
	(via
		(at 127.368808 -98.500184)
		(size 0.508)
		(drill 0.254)
		(layers "F.Cu" "B.Cu")
		(net "P3E_CPU1_PE3_MP_RXN<3>")
	)
	(segment
		(start 62.024006 -107.973368)
		(end 59.103006 -103.592376)
		(width 0.1143)
		(layer "In9.Cu")
		(net "P3E_CPU1_PE3_MP_RXN<3>")
	)
	(segment
		(start 128.209548 -94.442534)
		(end 128.245362 -94.442534)
		(width 0.0889)
		(layer "In9.Cu")
		(net "P3E_CPU1_PE3_MP_RXN<3>")
	)
	(segment
		(start 138.518138 -93.452188)
		(end 138.550904 -93.452188)
		(width 0.0889)
		(layer "In9.Cu")
		(net "P3E_CPU1_PE3_MP_RXN<3>")
	)
	(segment
		(start 31.461456 -42.855134)
		(end 26.138124 -43.919648)
		(width 0.1143)
		(layer "In9.Cu")
		(net "P3E_CPU1_PE3_MP_RXN<3>")
	)
	(segment
		(start 11.899392 -41.279064)
		(end 8.671814 -39.733474)
		(width 0.1143)
		(layer "In9.Cu")
		(net "P3E_CPU1_PE3_MP_RXN<3>")
	)
	(segment
		(start 135.938768 -93.947234)
		(end 135.96874 -93.947234)
		(width 0.0889)
		(layer "In9.Cu")
		(net "P3E_CPU1_PE3_MP_RXN<3>")
	)
	(segment
		(start 17.658334 -42.223944)
		(end 11.899392 -41.279064)
		(width 0.1143)
		(layer "In9.Cu")
		(net "P3E_CPU1_PE3_MP_RXN<3>")
	)
	(segment
		(start 142.75562 -95.895922)
		(end 142.75562 -100.094034)
		(width 0.0889)
		(layer "In9.Cu")
		(net "P3E_CPU1_PE3_MP_RXN<3>")
	)
	(segment
		(start 53.789072 -77.199236)
		(end 57.307988 -59.604148)
		(width 0.1143)
		(layer "In9.Cu")
		(net "P3E_CPU1_PE3_MP_RXN<3>")
	)
	(segment
		(start 137.653014 -92.956634)
		(end 137.688574 -92.956634)
		(width 0.0889)
		(layer "In9.Cu")
		(net "P3E_CPU1_PE3_MP_RXN<3>")
	)
	(segment
		(start 134.221728 -92.956634)
		(end 134.254494 -92.956634)
		(width 0.0889)
		(layer "In9.Cu")
		(net "P3E_CPU1_PE3_MP_RXN<3>")
	)
	(segment
		(start 98.679254 -114.6302)
		(end 94.350078 -113.764568)
		(width 0.1143)
		(layer "In9.Cu")
		(net "P3E_CPU1_PE3_MP_RXN<3>")
	)
	(segment
		(start 94.350078 -113.764568)
		(end 83.142074 -116.006118)
		(width 0.1143)
		(layer "In9.Cu")
		(net "P3E_CPU1_PE3_MP_RXN<3>")
	)
	(segment
		(start 56.86806 -88.727026)
		(end 56.115966 -84.96554)
		(width 0.1143)
		(layer "In9.Cu")
		(net "P3E_CPU1_PE3_MP_RXN<3>")
	)
	(segment
		(start 140.22832 -94.442534)
		(end 140.264134 -94.442534)
		(width 0.0889)
		(layer "In9.Cu")
		(net "P3E_CPU1_PE3_MP_RXN<3>")
	)
	(segment
		(start 40.616632 -43.020996)
		(end 35.987228 -41.621202)
		(width 0.1143)
		(layer "In9.Cu")
		(net "P3E_CPU1_PE3_MP_RXN<3>")
	)
	(segment
		(start 8.087868 -39.210234)
		(end 7.118604 -38.856158)
		(width 0.1143)
		(layer "In9.Cu")
		(net "P3E_CPU1_PE3_MP_RXN<3>")
	)
	(segment
		(start 127.720344 -97.318322)
		(end 127.715518 -97.309686)
		(width 0.0889)
		(layer "In9.Cu")
		(net "P3E_CPU1_PE3_MP_RXN<3>")
	)
	(segment
		(start -2.0193 -37.833554)
		(end -2.142744 -37.71011)
		(width 0.1143)
		(layer "In9.Cu")
		(net "P3E_CPU1_PE3_MP_RXN<3>")
	)
	(segment
		(start 54.62016 -81.355184)
		(end 53.789072 -77.199236)
		(width 0.1143)
		(layer "In9.Cu")
		(net "P3E_CPU1_PE3_MP_RXN<3>")
	)
	(segment
		(start -2.0193 -38.261544)
		(end -2.0193 -37.833554)
		(width 0.1143)
		(layer "In9.Cu")
		(net "P3E_CPU1_PE3_MP_RXN<3>")
	)
	(segment
		(start 127.720344 -95.337122)
		(end 127.715518 -95.328486)
		(width 0.0889)
		(layer "In9.Cu")
		(net "P3E_CPU1_PE3_MP_RXN<3>")
	)
	(segment
		(start 127.661924 -98.331274)
		(end 127.6858 -98.24212)
		(width 0.0889)
		(layer "In9.Cu")
		(net "P3E_CPU1_PE3_MP_RXN<3>")
	)
	(segment
		(start 51.682396 -50.39741)
		(end 40.616632 -43.020996)
		(width 0.1143)
		(layer "In9.Cu")
		(net "P3E_CPU1_PE3_MP_RXN<3>")
	)
	(segment
		(start 103.995982 -113.56721)
		(end 98.679254 -114.6302)
		(width 0.1143)
		(layer "In9.Cu")
		(net "P3E_CPU1_PE3_MP_RXN<3>")
	)
	(segment
		(start 132.752846 -115.4176)
		(end 122.998992 -117.368066)
		(width 0.1143)
		(layer "In9.Cu")
		(net "P3E_CPU1_PE3_MP_RXN<3>")
	)
	(segment
		(start 127.720344 -96.327722)
		(end 127.715518 -96.319086)
		(width 0.0889)
		(layer "In9.Cu")
		(net "P3E_CPU1_PE3_MP_RXN<3>")
	)
	(segment
		(start 129.922778 -93.452188)
		(end 129.955544 -93.452188)
		(width 0.0889)
		(layer "In9.Cu")
		(net "P3E_CPU1_PE3_MP_RXN<3>")
	)
	(segment
		(start -2.142744 -37.71011)
		(end -2.599944 -37.71011)
		(width 0.1143)
		(layer "In9.Cu")
		(net "P3E_CPU1_PE3_MP_RXN<3>")
	)
	(segment
		(start 130.785108 -92.956634)
		(end 130.817874 -92.956634)
		(width 0.0889)
		(layer "In9.Cu")
		(net "P3E_CPU1_PE3_MP_RXN<3>")
	)
	(segment
		(start 26.138124 -43.919648)
		(end 17.658334 -42.223944)
		(width 0.1143)
		(layer "In9.Cu")
		(net "P3E_CPU1_PE3_MP_RXN<3>")
	)
	(segment
		(start 56.498998 -90.572336)
		(end 56.86806 -88.727026)
		(width 0.1143)
		(layer "In9.Cu")
		(net "P3E_CPU1_PE3_MP_RXN<3>")
	)
	(segment
		(start 56.115966 -84.96554)
		(end 54.62016 -81.355184)
		(width 0.1143)
		(layer "In9.Cu")
		(net "P3E_CPU1_PE3_MP_RXN<3>")
	)
	(segment
		(start 57.08904 -58.507122)
		(end 51.682396 -50.39741)
		(width 0.1143)
		(layer "In9.Cu")
		(net "P3E_CPU1_PE3_MP_RXN<3>")
	)
	(segment
		(start -1.424686 -38.856158)
		(end -2.0193 -38.261544)
		(width 0.1143)
		(layer "In9.Cu")
		(net "P3E_CPU1_PE3_MP_RXN<3>")
	)
	(segment
		(start 70.18528 -113.414302)
		(end 62.024006 -107.973368)
		(width 0.1143)
		(layer "In9.Cu")
		(net "P3E_CPU1_PE3_MP_RXN<3>")
	)
	(segment
		(start 33.939226 -41.621202)
		(end 31.461456 -42.855134)
		(width 0.1143)
		(layer "In9.Cu")
		(net "P3E_CPU1_PE3_MP_RXN<3>")
	)
	(segment
		(start 142.75562 -100.094034)
		(end 142.80642 -100.144834)
		(width 0.0889)
		(layer "In9.Cu")
		(net "P3E_CPU1_PE3_MP_RXN<3>")
	)
	(segment
		(start 57.307988 -59.604148)
		(end 57.08904 -58.507122)
		(width 0.1143)
		(layer "In9.Cu")
		(net "P3E_CPU1_PE3_MP_RXN<3>")
	)
	(segment
		(start 8.671814 -39.733474)
		(end 8.087868 -39.210234)
		(width 0.1143)
		(layer "In9.Cu")
		(net "P3E_CPU1_PE3_MP_RXN<3>")
	)
	(segment
		(start 132.501894 -91.966034)
		(end 132.537454 -91.966034)
		(width 0.0889)
		(layer "In9.Cu")
		(net "P3E_CPU1_PE3_MP_RXN<3>")
	)
	(segment
		(start 59.103006 -103.592376)
		(end 56.498998 -90.572336)
		(width 0.1143)
		(layer "In9.Cu")
		(net "P3E_CPU1_PE3_MP_RXN<3>")
	)
	(segment
		(start 140.758164 -94.737936)
		(end 140.92047 -95.01759)
		(width 0.0889)
		(layer "In9.Cu")
		(net "P3E_CPU1_PE3_MP_RXN<3>")
	)
	(segment
		(start 127.368808 -98.500184)
		(end 127.661924 -98.331274)
		(width 0.0889)
		(layer "In9.Cu")
		(net "P3E_CPU1_PE3_MP_RXN<3>")
	)
	(segment
		(start 127.715518 -96.319086)
		(end 127.709168 -96.308418)
		(width 0.0889)
		(layer "In9.Cu")
		(net "P3E_CPU1_PE3_MP_RXN<3>")
	)
	(segment
		(start 127.715518 -97.309686)
		(end 127.709168 -97.299018)
		(width 0.0889)
		(layer "In9.Cu")
		(net "P3E_CPU1_PE3_MP_RXN<3>")
	)
	(segment
		(start 142.80642 -100.166932)
		(end 142.80642 -105.364026)
		(width 0.1143)
		(layer "In9.Cu")
		(net "P3E_CPU1_PE3_MP_RXN<3>")
	)
	(segment
		(start 129.072894 -93.947234)
		(end 129.100834 -93.947234)
		(width 0.0889)
		(layer "In9.Cu")
		(net "P3E_CPU1_PE3_MP_RXN<3>")
	)
	(segment
		(start 133.367018 -92.461588)
		(end 133.399784 -92.461588)
		(width 0.0889)
		(layer "In9.Cu")
		(net "P3E_CPU1_PE3_MP_RXN<3>")
	)
	(segment
		(start 140.92047 -95.01759)
		(end 142.554198 -95.6945)
		(width 0.0889)
		(layer "In9.Cu")
		(net "P3E_CPU1_PE3_MP_RXN<3>")
	)
	(segment
		(start 135.084058 -93.452188)
		(end 135.116824 -93.452188)
		(width 0.0889)
		(layer "In9.Cu")
		(net "P3E_CPU1_PE3_MP_RXN<3>")
	)
	(segment
		(start 122.998992 -117.368066)
		(end 103.995982 -113.56721)
		(width 0.1143)
		(layer "In9.Cu")
		(net "P3E_CPU1_PE3_MP_RXN<3>")
	)
	(segment
		(start 139.372848 -93.947234)
		(end 139.405614 -93.947234)
		(width 0.0889)
		(layer "In9.Cu")
		(net "P3E_CPU1_PE3_MP_RXN<3>")
	)
	(segment
		(start 142.80642 -105.364026)
		(end 132.752846 -115.4176)
		(width 0.1143)
		(layer "In9.Cu")
		(net "P3E_CPU1_PE3_MP_RXN<3>")
	)
	(segment
		(start 35.987228 -41.621202)
		(end 33.939226 -41.621202)
		(width 0.1143)
		(layer "In9.Cu")
		(net "P3E_CPU1_PE3_MP_RXN<3>")
	)
	(segment
		(start 127.709168 -94.748604)
		(end 127.715518 -94.737936)
		(width 0.0889)
		(layer "In9.Cu")
		(net "P3E_CPU1_PE3_MP_RXN<3>")
	)
	(segment
		(start 142.554198 -95.6945)
		(end 142.75562 -95.895922)
		(width 0.0889)
		(layer "In9.Cu")
		(net "P3E_CPU1_PE3_MP_RXN<3>")
	)
	(segment
		(start 142.80642 -100.144834)
		(end 142.80642 -100.166932)
		(width 0.0889)
		(layer "In9.Cu")
		(net "P3E_CPU1_PE3_MP_RXN<3>")
	)
	(segment
		(start 136.790684 -93.452188)
		(end 136.82345 -93.452188)
		(width 0.0889)
		(layer "In9.Cu")
		(net "P3E_CPU1_PE3_MP_RXN<3>")
	)
	(segment
		(start 131.639818 -92.461588)
		(end 131.661408 -92.461588)
		(width 0.0889)
		(layer "In9.Cu")
		(net "P3E_CPU1_PE3_MP_RXN<3>")
	)
	(segment
		(start 83.142074 -116.006118)
		(end 70.18528 -113.414302)
		(width 0.1143)
		(layer "In9.Cu")
		(net "P3E_CPU1_PE3_MP_RXN<3>")
	)
	(segment
		(start 132.004562 -92.267278)
		(end 132.007864 -92.261436)
		(width 0.0889)
		(layer "In9.Cu")
		(net "P3E_CPU1_PE3_MP_RXN<3>")
	)
	(segment
		(start 7.118604 -38.856158)
		(end -1.424686 -38.856158)
		(width 0.1143)
		(layer "In9.Cu")
		(net "P3E_CPU1_PE3_MP_RXN<3>")
	)
	(arc
		(start 139.405614 -93.947234)
		(mid 139.691038 -94.030701)
		(end 139.899644 -94.242636)
		(width 0.0889)
		(layer "In9.Cu")
		(net "P3E_CPU1_PE3_MP_RXN<3>")
	)
	(arc
		(start 138.182604 -93.252036)
		(mid 138.324287 -93.39584)
		(end 138.518138 -93.452188)
		(width 0.0889)
		(layer "In9.Cu")
		(net "P3E_CPU1_PE3_MP_RXN<3>")
	)
	(arc
		(start 133.890004 -92.756736)
		(mid 134.030083 -92.899472)
		(end 134.221728 -92.956634)
		(width 0.0889)
		(layer "In9.Cu")
		(net "P3E_CPU1_PE3_MP_RXN<3>")
	)
	(arc
		(start 136.82345 -93.452188)
		(mid 137.0173 -93.395838)
		(end 137.158984 -93.252036)
		(width 0.0889)
		(layer "In9.Cu")
		(net "P3E_CPU1_PE3_MP_RXN<3>")
	)
	(arc
		(start 140.264134 -94.442534)
		(mid 140.549558 -94.526001)
		(end 140.758164 -94.737936)
		(width 0.0889)
		(layer "In9.Cu")
		(net "P3E_CPU1_PE3_MP_RXN<3>")
	)
	(arc
		(start 127.715518 -95.328486)
		(mid 127.636296 -95.039368)
		(end 127.709168 -94.748604)
		(width 0.0889)
		(layer "In9.Cu")
		(net "P3E_CPU1_PE3_MP_RXN<3>")
	)
	(arc
		(start 128.245362 -94.442534)
		(mid 128.435291 -94.384664)
		(end 128.574038 -94.242636)
		(width 0.0889)
		(layer "In9.Cu")
		(net "P3E_CPU1_PE3_MP_RXN<3>")
	)
	(arc
		(start 129.955544 -93.452188)
		(mid 130.149394 -93.395838)
		(end 130.291078 -93.252036)
		(width 0.0889)
		(layer "In9.Cu")
		(net "P3E_CPU1_PE3_MP_RXN<3>")
	)
	(arc
		(start 137.158984 -93.252036)
		(mid 137.367592 -93.040104)
		(end 137.653014 -92.956634)
		(width 0.0889)
		(layer "In9.Cu")
		(net "P3E_CPU1_PE3_MP_RXN<3>")
	)
	(arc
		(start 134.254494 -92.956634)
		(mid 134.539918 -93.040101)
		(end 134.748524 -93.252036)
		(width 0.0889)
		(layer "In9.Cu")
		(net "P3E_CPU1_PE3_MP_RXN<3>")
	)
	(arc
		(start 135.96874 -93.947234)
		(mid 136.160382 -93.890068)
		(end 136.300464 -93.747336)
		(width 0.0889)
		(layer "In9.Cu")
		(net "P3E_CPU1_PE3_MP_RXN<3>")
	)
	(arc
		(start 127.709168 -97.299018)
		(mid 127.63637 -97.008255)
		(end 127.715518 -96.719136)
		(width 0.0889)
		(layer "In9.Cu")
		(net "P3E_CPU1_PE3_MP_RXN<3>")
	)
	(arc
		(start 138.550904 -93.452188)
		(mid 138.834121 -93.536469)
		(end 139.041124 -93.747336)
		(width 0.0889)
		(layer "In9.Cu")
		(net "P3E_CPU1_PE3_MP_RXN<3>")
	)
	(arc
		(start 130.817874 -92.956634)
		(mid 131.009516 -92.899468)
		(end 131.149598 -92.756736)
		(width 0.0889)
		(layer "In9.Cu")
		(net "P3E_CPU1_PE3_MP_RXN<3>")
	)
	(arc
		(start 130.291078 -93.252036)
		(mid 130.499686 -93.040104)
		(end 130.785108 -92.956634)
		(width 0.0889)
		(layer "In9.Cu")
		(net "P3E_CPU1_PE3_MP_RXN<3>")
	)
	(arc
		(start 127.715518 -95.728536)
		(mid 127.768988 -95.533473)
		(end 127.720344 -95.337122)
		(width 0.0889)
		(layer "In9.Cu")
		(net "P3E_CPU1_PE3_MP_RXN<3>")
	)
	(arc
		(start 139.899644 -94.242636)
		(mid 140.038388 -94.384669)
		(end 140.22832 -94.442534)
		(width 0.0889)
		(layer "In9.Cu")
		(net "P3E_CPU1_PE3_MP_RXN<3>")
	)
	(arc
		(start 131.149598 -92.756736)
		(mid 131.356602 -92.545872)
		(end 131.639818 -92.461588)
		(width 0.0889)
		(layer "In9.Cu")
		(net "P3E_CPU1_PE3_MP_RXN<3>")
	)
	(arc
		(start 131.661408 -92.461588)
		(mid 131.858569 -92.409629)
		(end 132.004562 -92.267278)
		(width 0.0889)
		(layer "In9.Cu")
		(net "P3E_CPU1_PE3_MP_RXN<3>")
	)
	(arc
		(start 137.688574 -92.956634)
		(mid 137.973998 -93.040101)
		(end 138.182604 -93.252036)
		(width 0.0889)
		(layer "In9.Cu")
		(net "P3E_CPU1_PE3_MP_RXN<3>")
	)
	(arc
		(start 127.6858 -98.24212)
		(mid 127.63724 -97.972395)
		(end 127.715518 -97.709736)
		(width 0.0889)
		(layer "In9.Cu")
		(net "P3E_CPU1_PE3_MP_RXN<3>")
	)
	(arc
		(start 129.432558 -93.747336)
		(mid 129.639562 -93.536472)
		(end 129.922778 -93.452188)
		(width 0.0889)
		(layer "In9.Cu")
		(net "P3E_CPU1_PE3_MP_RXN<3>")
	)
	(arc
		(start 132.007864 -92.261436)
		(mid 132.216472 -92.049504)
		(end 132.501894 -91.966034)
		(width 0.0889)
		(layer "In9.Cu")
		(net "P3E_CPU1_PE3_MP_RXN<3>")
	)
	(arc
		(start 127.715518 -94.737936)
		(mid 127.924126 -94.526004)
		(end 128.209548 -94.442534)
		(width 0.0889)
		(layer "In9.Cu")
		(net "P3E_CPU1_PE3_MP_RXN<3>")
	)
	(arc
		(start 133.031484 -92.261436)
		(mid 133.173167 -92.40524)
		(end 133.367018 -92.461588)
		(width 0.0889)
		(layer "In9.Cu")
		(net "P3E_CPU1_PE3_MP_RXN<3>")
	)
	(arc
		(start 127.715518 -97.709736)
		(mid 127.768988 -97.514673)
		(end 127.720344 -97.318322)
		(width 0.0889)
		(layer "In9.Cu")
		(net "P3E_CPU1_PE3_MP_RXN<3>")
	)
	(arc
		(start 132.537454 -91.966034)
		(mid 132.822878 -92.049501)
		(end 133.031484 -92.261436)
		(width 0.0889)
		(layer "In9.Cu")
		(net "P3E_CPU1_PE3_MP_RXN<3>")
	)
	(arc
		(start 127.715518 -96.719136)
		(mid 127.768988 -96.524073)
		(end 127.720344 -96.327722)
		(width 0.0889)
		(layer "In9.Cu")
		(net "P3E_CPU1_PE3_MP_RXN<3>")
	)
	(arc
		(start 128.574038 -94.242636)
		(mid 128.784751 -94.029557)
		(end 129.072894 -93.947234)
		(width 0.0889)
		(layer "In9.Cu")
		(net "P3E_CPU1_PE3_MP_RXN<3>")
	)
	(arc
		(start 135.116824 -93.452188)
		(mid 135.400041 -93.536469)
		(end 135.607044 -93.747336)
		(width 0.0889)
		(layer "In9.Cu")
		(net "P3E_CPU1_PE3_MP_RXN<3>")
	)
	(arc
		(start 133.399784 -92.461588)
		(mid 133.683001 -92.545869)
		(end 133.890004 -92.756736)
		(width 0.0889)
		(layer "In9.Cu")
		(net "P3E_CPU1_PE3_MP_RXN<3>")
	)
	(arc
		(start 129.100834 -93.947234)
		(mid 129.292476 -93.890068)
		(end 129.432558 -93.747336)
		(width 0.0889)
		(layer "In9.Cu")
		(net "P3E_CPU1_PE3_MP_RXN<3>")
	)
	(arc
		(start 139.041124 -93.747336)
		(mid 139.181203 -93.890072)
		(end 139.372848 -93.947234)
		(width 0.0889)
		(layer "In9.Cu")
		(net "P3E_CPU1_PE3_MP_RXN<3>")
	)
	(arc
		(start 127.709168 -96.308418)
		(mid 127.63637 -96.017655)
		(end 127.715518 -95.728536)
		(width 0.0889)
		(layer "In9.Cu")
		(net "P3E_CPU1_PE3_MP_RXN<3>")
	)
	(arc
		(start 136.300464 -93.747336)
		(mid 136.507468 -93.536472)
		(end 136.790684 -93.452188)
		(width 0.0889)
		(layer "In9.Cu")
		(net "P3E_CPU1_PE3_MP_RXN<3>")
	)
	(arc
		(start 134.748524 -93.252036)
		(mid 134.890207 -93.39584)
		(end 135.084058 -93.452188)
		(width 0.0889)
		(layer "In9.Cu")
		(net "P3E_CPU1_PE3_MP_RXN<3>")
	)
	(arc
		(start 135.607044 -93.747336)
		(mid 135.747123 -93.890072)
		(end 135.938768 -93.947234)
		(width 0.0889)
		(layer "In9.Cu")
		(net "P3E_CPU1_PE3_MP_RXN<3>")
	)
	(segment
		(start 129.372868 -99.986338)
		(end 129.944368 -99.986338)
		(width 0.1143)
		(layer "F.Cu")
		(net "P3E_CPU1_PE3_MP_RXN<2>")
	)
	(via
		(at 129.944368 -99.986338)
		(size 0.508)
		(drill 0.254)
		(layers "F.Cu" "B.Cu")
		(net "P3E_CPU1_PE3_MP_RXN<2>")
	)
	(segment
		(start 70.071742 -113.774728)
		(end 61.635386 -108.15066)
		(width 0.1143)
		(layer "In9.Cu")
		(net "P3E_CPU1_PE3_MP_RXN<2>")
	)
	(segment
		(start 136.797288 -92.652088)
		(end 136.830054 -92.652088)
		(width 0.0889)
		(layer "In9.Cu")
		(net "P3E_CPU1_PE3_MP_RXN<2>")
	)
	(segment
		(start 128.212342 -93.642688)
		(end 128.245108 -93.642688)
		(width 0.0889)
		(layer "In9.Cu")
		(net "P3E_CPU1_PE3_MP_RXN<2>")
	)
	(segment
		(start 104.846628 -114.100102)
		(end 104.287066 -114.211862)
		(width 0.1143)
		(layer "In9.Cu")
		(net "P3E_CPU1_PE3_MP_RXN<2>")
	)
	(segment
		(start 53.839618 -54.3814)
		(end 53.839364 -54.381146)
		(width 0.1143)
		(layer "In9.Cu")
		(net "P3E_CPU1_PE3_MP_RXN<2>")
	)
	(segment
		(start 134.215124 -92.156534)
		(end 134.24789 -92.156534)
		(width 0.0889)
		(layer "In9.Cu")
		(net "P3E_CPU1_PE3_MP_RXN<2>")
	)
	(segment
		(start 53.839364 -54.381146)
		(end 51.364388 -50.668936)
		(width 0.1143)
		(layer "In9.Cu")
		(net "P3E_CPU1_PE3_MP_RXN<2>")
	)
	(segment
		(start 143.187928 -95.814134)
		(end 143.187928 -95.991934)
		(width 0.0889)
		(layer "In9.Cu")
		(net "P3E_CPU1_PE3_MP_RXN<2>")
	)
	(segment
		(start 140.229082 -93.642688)
		(end 140.264896 -93.642688)
		(width 0.0889)
		(layer "In9.Cu")
		(net "P3E_CPU1_PE3_MP_RXN<2>")
	)
	(segment
		(start 5.2832 -40.375586)
		(end 5.2832 -40.163496)
		(width 0.1143)
		(layer "In9.Cu")
		(net "P3E_CPU1_PE3_MP_RXN<2>")
	)
	(segment
		(start 54.966362 -85.749384)
		(end 53.33492 -77.595984)
		(width 0.1143)
		(layer "In9.Cu")
		(net "P3E_CPU1_PE3_MP_RXN<2>")
	)
	(segment
		(start 104.287066 -114.211862)
		(end 104.092756 -114.082322)
		(width 0.1143)
		(layer "In9.Cu")
		(net "P3E_CPU1_PE3_MP_RXN<2>")
	)
	(segment
		(start 129.651252 -99.817174)
		(end 129.627376 -99.727766)
		(width 0.0889)
		(layer "In9.Cu")
		(net "P3E_CPU1_PE3_MP_RXN<2>")
	)
	(segment
		(start 53.33492 -77.595984)
		(end 54.710076 -70.684644)
		(width 0.1143)
		(layer "In9.Cu")
		(net "P3E_CPU1_PE3_MP_RXN<2>")
	)
	(segment
		(start 143.187928 -95.991934)
		(end 143.28902 -96.093026)
		(width 0.0889)
		(layer "In9.Cu")
		(net "P3E_CPU1_PE3_MP_RXN<2>")
	)
	(segment
		(start 14.04747 -42.018712)
		(end 10.749026 -41.478454)
		(width 0.1143)
		(layer "In9.Cu")
		(net "P3E_CPU1_PE3_MP_RXN<2>")
	)
	(segment
		(start 129.074672 -93.147134)
		(end 129.107438 -93.147134)
		(width 0.0889)
		(layer "In9.Cu")
		(net "P3E_CPU1_PE3_MP_RXN<2>")
	)
	(segment
		(start 143.168878 -95.4151)
		(end 143.28902 -95.535242)
		(width 0.0889)
		(layer "In9.Cu")
		(net "P3E_CPU1_PE3_MP_RXN<2>")
	)
	(segment
		(start 127.383794 -98.900234)
		(end 127.353822 -98.900234)
		(width 0.0889)
		(layer "In9.Cu")
		(net "P3E_CPU1_PE3_MP_RXN<2>")
	)
	(segment
		(start 127.017272 -98.308922)
		(end 127.022098 -98.300286)
		(width 0.0889)
		(layer "In9.Cu")
		(net "P3E_CPU1_PE3_MP_RXN<2>")
	)
	(segment
		(start 143.28902 -98.114358)
		(end 143.23822 -98.165158)
		(width 0.0889)
		(layer "In9.Cu")
		(net "P3E_CPU1_PE3_MP_RXN<2>")
	)
	(segment
		(start 98.412046 -115.386358)
		(end 93.385894 -114.380772)
		(width 0.1143)
		(layer "In9.Cu")
		(net "P3E_CPU1_PE3_MP_RXN<2>")
	)
	(segment
		(start 5.73659 -39.710106)
		(end 5.899912 -39.710106)
		(width 0.1143)
		(layer "In9.Cu")
		(net "P3E_CPU1_PE3_MP_RXN<2>")
	)
	(segment
		(start 133.360414 -91.661488)
		(end 133.39318 -91.661488)
		(width 0.0889)
		(layer "In9.Cu")
		(net "P3E_CPU1_PE3_MP_RXN<2>")
	)
	(segment
		(start 129.103628 -98.900234)
		(end 129.070862 -98.900234)
		(width 0.0889)
		(layer "In9.Cu")
		(net "P3E_CPU1_PE3_MP_RXN<2>")
	)
	(segment
		(start 129.929382 -92.652088)
		(end 129.962148 -92.652088)
		(width 0.0889)
		(layer "In9.Cu")
		(net "P3E_CPU1_PE3_MP_RXN<2>")
	)
	(segment
		(start 101.764084 -114.547904)
		(end 101.634544 -114.742214)
		(width 0.1143)
		(layer "In9.Cu")
		(net "P3E_CPU1_PE3_MP_RXN<2>")
	)
	(segment
		(start 101.63429 -114.742214)
		(end 98.412046 -115.386358)
		(width 0.1143)
		(layer "In9.Cu")
		(net "P3E_CPU1_PE3_MP_RXN<2>")
	)
	(segment
		(start 54.966108 -85.749384)
		(end 54.966362 -85.749384)
		(width 0.1143)
		(layer "In9.Cu")
		(net "P3E_CPU1_PE3_MP_RXN<2>")
	)
	(segment
		(start 103.756714 -114.149632)
		(end 103.627174 -114.343942)
		(width 0.1143)
		(layer "In9.Cu")
		(net "P3E_CPU1_PE3_MP_RXN<2>")
	)
	(segment
		(start 61.635386 -108.15066)
		(end 58.510424 -103.46309)
		(width 0.1143)
		(layer "In9.Cu")
		(net "P3E_CPU1_PE3_MP_RXN<2>")
	)
	(segment
		(start 56.147716 -89.529666)
		(end 55.561738 -86.64956)
		(width 0.1143)
		(layer "In9.Cu")
		(net "P3E_CPU1_PE3_MP_RXN<2>")
	)
	(segment
		(start 102.760272 -114.348768)
		(end 102.630732 -114.543078)
		(width 0.1143)
		(layer "In9.Cu")
		(net "P3E_CPU1_PE3_MP_RXN<2>")
	)
	(segment
		(start 51.364388 -50.668936)
		(end 40.27678 -43.276774)
		(width 0.1143)
		(layer "In9.Cu")
		(net "P3E_CPU1_PE3_MP_RXN<2>")
	)
	(segment
		(start 127.022098 -98.300286)
		(end 127.028448 -98.289618)
		(width 0.0889)
		(layer "In9.Cu")
		(net "P3E_CPU1_PE3_MP_RXN<2>")
	)
	(segment
		(start 143.28902 -96.270826)
		(end 143.187928 -96.371918)
		(width 0.0889)
		(layer "In9.Cu")
		(net "P3E_CPU1_PE3_MP_RXN<2>")
	)
	(segment
		(start 135.932164 -93.147134)
		(end 135.975344 -93.147134)
		(width 0.0889)
		(layer "In9.Cu")
		(net "P3E_CPU1_PE3_MP_RXN<2>")
	)
	(segment
		(start 143.23822 -98.187256)
		(end 143.23822 -105.63098)
		(width 0.1143)
		(layer "In9.Cu")
		(net "P3E_CPU1_PE3_MP_RXN<2>")
	)
	(segment
		(start 5.85597 -40.805862)
		(end 5.606542 -40.697912)
		(width 0.1143)
		(layer "In9.Cu")
		(net "P3E_CPU1_PE3_MP_RXN<2>")
	)
	(segment
		(start 143.28902 -96.093026)
		(end 143.28902 -96.270826)
		(width 0.0889)
		(layer "In9.Cu")
		(net "P3E_CPU1_PE3_MP_RXN<2>")
	)
	(segment
		(start 129.944368 -99.986338)
		(end 129.651252 -99.817174)
		(width 0.0889)
		(layer "In9.Cu")
		(net "P3E_CPU1_PE3_MP_RXN<2>")
	)
	(segment
		(start 127.028448 -94.748604)
		(end 127.022098 -94.737936)
		(width 0.0889)
		(layer "In9.Cu")
		(net "P3E_CPU1_PE3_MP_RXN<2>")
	)
	(segment
		(start 34.036254 -41.964102)
		(end 31.698438 -43.157648)
		(width 0.1143)
		(layer "In9.Cu")
		(net "P3E_CPU1_PE3_MP_RXN<2>")
	)
	(segment
		(start 127.022098 -96.319086)
		(end 127.028448 -96.308418)
		(width 0.0889)
		(layer "In9.Cu")
		(net "P3E_CPU1_PE3_MP_RXN<2>")
	)
	(segment
		(start 102.10038 -114.480594)
		(end 101.764084 -114.547904)
		(width 0.1143)
		(layer "In9.Cu")
		(net "P3E_CPU1_PE3_MP_RXN<2>")
	)
	(segment
		(start 103.627174 -114.343942)
		(end 103.290878 -114.410998)
		(width 0.1143)
		(layer "In9.Cu")
		(net "P3E_CPU1_PE3_MP_RXN<2>")
	)
	(segment
		(start 127.022098 -97.309686)
		(end 127.028448 -97.299018)
		(width 0.0889)
		(layer "In9.Cu")
		(net "P3E_CPU1_PE3_MP_RXN<2>")
	)
	(segment
		(start 123.025154 -117.734842)
		(end 104.846628 -114.100102)
		(width 0.1143)
		(layer "In9.Cu")
		(net "P3E_CPU1_PE3_MP_RXN<2>")
	)
	(segment
		(start 143.28902 -97.766378)
		(end 143.28902 -98.114358)
		(width 0.0889)
		(layer "In9.Cu")
		(net "P3E_CPU1_PE3_MP_RXN<2>")
	)
	(segment
		(start 131.646422 -91.661488)
		(end 131.679188 -91.661488)
		(width 0.0889)
		(layer "In9.Cu")
		(net "P3E_CPU1_PE3_MP_RXN<2>")
	)
	(segment
		(start 143.187928 -97.665286)
		(end 143.28902 -97.766378)
		(width 0.0889)
		(layer "In9.Cu")
		(net "P3E_CPU1_PE3_MP_RXN<2>")
	)
	(segment
		(start 128.248918 -98.405188)
		(end 128.205738 -98.405188)
		(width 0.0889)
		(layer "In9.Cu")
		(net "P3E_CPU1_PE3_MP_RXN<2>")
	)
	(segment
		(start 130.791712 -92.156534)
		(end 130.824478 -92.156534)
		(width 0.0889)
		(layer "In9.Cu")
		(net "P3E_CPU1_PE3_MP_RXN<2>")
	)
	(segment
		(start 5.2832 -40.163496)
		(end 5.73659 -39.710106)
		(width 0.1143)
		(layer "In9.Cu")
		(net "P3E_CPU1_PE3_MP_RXN<2>")
	)
	(segment
		(start 40.27678 -43.276774)
		(end 35.936428 -41.964102)
		(width 0.1143)
		(layer "In9.Cu")
		(net "P3E_CPU1_PE3_MP_RXN<2>")
	)
	(segment
		(start 141.962886 -94.63278)
		(end 142.386558 -94.63278)
		(width 0.0889)
		(layer "In9.Cu")
		(net "P3E_CPU1_PE3_MP_RXN<2>")
	)
	(segment
		(start 104.092756 -114.082322)
		(end 103.756714 -114.149632)
		(width 0.1143)
		(layer "In9.Cu")
		(net "P3E_CPU1_PE3_MP_RXN<2>")
	)
	(segment
		(start 102.630732 -114.543078)
		(end 102.294436 -114.610134)
		(width 0.1143)
		(layer "In9.Cu")
		(net "P3E_CPU1_PE3_MP_RXN<2>")
	)
	(segment
		(start 93.385894 -114.380772)
		(end 83.243674 -116.408962)
		(width 0.1143)
		(layer "In9.Cu")
		(net "P3E_CPU1_PE3_MP_RXN<2>")
	)
	(segment
		(start 143.187928 -96.371918)
		(end 143.187928 -96.549718)
		(width 0.0889)
		(layer "In9.Cu")
		(net "P3E_CPU1_PE3_MP_RXN<2>")
	)
	(segment
		(start 31.698438 -43.157648)
		(end 25.72004 -44.352972)
		(width 0.1143)
		(layer "In9.Cu")
		(net "P3E_CPU1_PE3_MP_RXN<2>")
	)
	(segment
		(start 137.659618 -92.156534)
		(end 137.68197 -92.156534)
		(width 0.0889)
		(layer "In9.Cu")
		(net "P3E_CPU1_PE3_MP_RXN<2>")
	)
	(segment
		(start 142.906242 -95.289116)
		(end 143.032226 -95.4151)
		(width 0.0889)
		(layer "In9.Cu")
		(net "P3E_CPU1_PE3_MP_RXN<2>")
	)
	(segment
		(start 143.032226 -95.4151)
		(end 143.168878 -95.4151)
		(width 0.0889)
		(layer "In9.Cu")
		(net "P3E_CPU1_PE3_MP_RXN<2>")
	)
	(segment
		(start 127.017272 -96.327722)
		(end 127.022098 -96.319086)
		(width 0.0889)
		(layer "In9.Cu")
		(net "P3E_CPU1_PE3_MP_RXN<2>")
	)
	(segment
		(start 142.638018 -95.024956)
		(end 142.778734 -95.024956)
		(width 0.0889)
		(layer "In9.Cu")
		(net "P3E_CPU1_PE3_MP_RXN<2>")
	)
	(segment
		(start 103.290878 -114.410998)
		(end 103.096568 -114.281458)
		(width 0.1143)
		(layer "In9.Cu")
		(net "P3E_CPU1_PE3_MP_RXN<2>")
	)
	(segment
		(start 143.23822 -98.165158)
		(end 143.23822 -98.187256)
		(width 0.0889)
		(layer "In9.Cu")
		(net "P3E_CPU1_PE3_MP_RXN<2>")
	)
	(segment
		(start 143.187928 -97.487486)
		(end 143.187928 -97.665286)
		(width 0.0889)
		(layer "In9.Cu")
		(net "P3E_CPU1_PE3_MP_RXN<2>")
	)
	(segment
		(start 141.092428 -94.137988)
		(end 141.120368 -94.137988)
		(width 0.0889)
		(layer "In9.Cu")
		(net "P3E_CPU1_PE3_MP_RXN<2>")
	)
	(segment
		(start 127.017272 -95.337122)
		(end 127.022098 -95.328486)
		(width 0.0889)
		(layer "In9.Cu")
		(net "P3E_CPU1_PE3_MP_RXN<2>")
	)
	(segment
		(start 5.606542 -40.697912)
		(end 5.2832 -40.375586)
		(width 0.1143)
		(layer "In9.Cu")
		(net "P3E_CPU1_PE3_MP_RXN<2>")
	)
	(segment
		(start 143.28902 -97.386394)
		(end 143.187928 -97.487486)
		(width 0.0889)
		(layer "In9.Cu")
		(net "P3E_CPU1_PE3_MP_RXN<2>")
	)
	(segment
		(start 10.424668 -41.5544)
		(end 5.85597 -40.805862)
		(width 0.1143)
		(layer "In9.Cu")
		(net "P3E_CPU1_PE3_MP_RXN<2>")
	)
	(segment
		(start 101.634544 -114.742214)
		(end 101.63429 -114.742214)
		(width 0.1143)
		(layer "In9.Cu")
		(net "P3E_CPU1_PE3_MP_RXN<2>")
	)
	(segment
		(start 55.93334 -90.583004)
		(end 56.147716 -89.529666)
		(width 0.1143)
		(layer "In9.Cu")
		(net "P3E_CPU1_PE3_MP_RXN<2>")
	)
	(segment
		(start 138.511534 -92.652088)
		(end 138.5443 -92.652088)
		(width 0.0889)
		(layer "In9.Cu")
		(net "P3E_CPU1_PE3_MP_RXN<2>")
	)
	(segment
		(start 143.28902 -95.535242)
		(end 143.28902 -95.713042)
		(width 0.0889)
		(layer "In9.Cu")
		(net "P3E_CPU1_PE3_MP_RXN<2>")
	)
	(segment
		(start 132.173218 -91.366086)
		(end 132.17652 -91.360244)
		(width 0.0889)
		(layer "In9.Cu")
		(net "P3E_CPU1_PE3_MP_RXN<2>")
	)
	(segment
		(start 54.710076 -66.125598)
		(end 56.314848 -58.093864)
		(width 0.1143)
		(layer "In9.Cu")
		(net "P3E_CPU1_PE3_MP_RXN<2>")
	)
	(segment
		(start 143.28902 -97.208594)
		(end 143.28902 -97.386394)
		(width 0.0889)
		(layer "In9.Cu")
		(net "P3E_CPU1_PE3_MP_RXN<2>")
	)
	(segment
		(start 127.357632 -94.137988)
		(end 127.381762 -94.137988)
		(width 0.0889)
		(layer "In9.Cu")
		(net "P3E_CPU1_PE3_MP_RXN<2>")
	)
	(segment
		(start 139.380214 -93.147388)
		(end 139.406376 -93.147388)
		(width 0.0889)
		(layer "In9.Cu")
		(net "P3E_CPU1_PE3_MP_RXN<2>")
	)
	(segment
		(start 143.187928 -96.549718)
		(end 143.28902 -96.65081)
		(width 0.0889)
		(layer "In9.Cu")
		(net "P3E_CPU1_PE3_MP_RXN<2>")
	)
	(segment
		(start 143.23822 -105.63098)
		(end 133.160516 -115.708684)
		(width 0.1143)
		(layer "In9.Cu")
		(net "P3E_CPU1_PE3_MP_RXN<2>")
	)
	(segment
		(start 143.187928 -97.107502)
		(end 143.28902 -97.208594)
		(width 0.0889)
		(layer "In9.Cu")
		(net "P3E_CPU1_PE3_MP_RXN<2>")
	)
	(segment
		(start 143.28902 -96.65081)
		(end 143.28902 -96.82861)
		(width 0.0889)
		(layer "In9.Cu")
		(net "P3E_CPU1_PE3_MP_RXN<2>")
	)
	(segment
		(start 25.72004 -44.352972)
		(end 14.04747 -42.018712)
		(width 0.1143)
		(layer "In9.Cu")
		(net "P3E_CPU1_PE3_MP_RXN<2>")
	)
	(segment
		(start 142.512034 -94.898972)
		(end 142.638018 -95.024956)
		(width 0.0889)
		(layer "In9.Cu")
		(net "P3E_CPU1_PE3_MP_RXN<2>")
	)
	(segment
		(start 143.28902 -95.713042)
		(end 143.187928 -95.814134)
		(width 0.0889)
		(layer "In9.Cu")
		(net "P3E_CPU1_PE3_MP_RXN<2>")
	)
	(segment
		(start 102.294436 -114.610134)
		(end 102.10038 -114.480594)
		(width 0.1143)
		(layer "In9.Cu")
		(net "P3E_CPU1_PE3_MP_RXN<2>")
	)
	(segment
		(start 133.160516 -115.708684)
		(end 123.025154 -117.734842)
		(width 0.1143)
		(layer "In9.Cu")
		(net "P3E_CPU1_PE3_MP_RXN<2>")
	)
	(segment
		(start 58.510424 -103.46309)
		(end 55.93334 -90.583004)
		(width 0.1143)
		(layer "In9.Cu")
		(net "P3E_CPU1_PE3_MP_RXN<2>")
	)
	(segment
		(start 142.512034 -94.758256)
		(end 142.512034 -94.898972)
		(width 0.0889)
		(layer "In9.Cu")
		(net "P3E_CPU1_PE3_MP_RXN<2>")
	)
	(segment
		(start 10.749026 -41.478454)
		(end 10.424668 -41.5544)
		(width 0.1143)
		(layer "In9.Cu")
		(net "P3E_CPU1_PE3_MP_RXN<2>")
	)
	(segment
		(start 135.077454 -92.652088)
		(end 135.11022 -92.652088)
		(width 0.0889)
		(layer "In9.Cu")
		(net "P3E_CPU1_PE3_MP_RXN<2>")
	)
	(segment
		(start 142.386558 -94.63278)
		(end 142.512034 -94.758256)
		(width 0.0889)
		(layer "In9.Cu")
		(net "P3E_CPU1_PE3_MP_RXN<2>")
	)
	(segment
		(start 103.096568 -114.281458)
		(end 102.760272 -114.348768)
		(width 0.1143)
		(layer "In9.Cu")
		(net "P3E_CPU1_PE3_MP_RXN<2>")
	)
	(segment
		(start 55.561738 -86.64956)
		(end 54.966108 -85.749384)
		(width 0.1143)
		(layer "In9.Cu")
		(net "P3E_CPU1_PE3_MP_RXN<2>")
	)
	(segment
		(start 142.906242 -95.152464)
		(end 142.906242 -95.289116)
		(width 0.0889)
		(layer "In9.Cu")
		(net "P3E_CPU1_PE3_MP_RXN<2>")
	)
	(segment
		(start 142.778734 -95.024956)
		(end 142.906242 -95.152464)
		(width 0.0889)
		(layer "In9.Cu")
		(net "P3E_CPU1_PE3_MP_RXN<2>")
	)
	(segment
		(start 83.243674 -116.408962)
		(end 70.071742 -113.774728)
		(width 0.1143)
		(layer "In9.Cu")
		(net "P3E_CPU1_PE3_MP_RXN<2>")
	)
	(segment
		(start 143.187928 -96.929702)
		(end 143.187928 -97.107502)
		(width 0.0889)
		(layer "In9.Cu")
		(net "P3E_CPU1_PE3_MP_RXN<2>")
	)
	(segment
		(start 54.710076 -70.684644)
		(end 54.710076 -66.125598)
		(width 0.1143)
		(layer "In9.Cu")
		(net "P3E_CPU1_PE3_MP_RXN<2>")
	)
	(segment
		(start 35.936428 -41.964102)
		(end 34.036254 -41.964102)
		(width 0.1143)
		(layer "In9.Cu")
		(net "P3E_CPU1_PE3_MP_RXN<2>")
	)
	(segment
		(start 56.314848 -58.093864)
		(end 53.839618 -54.3814)
		(width 0.1143)
		(layer "In9.Cu")
		(net "P3E_CPU1_PE3_MP_RXN<2>")
	)
	(segment
		(start 127.017272 -97.318322)
		(end 127.022098 -97.309686)
		(width 0.0889)
		(layer "In9.Cu")
		(net "P3E_CPU1_PE3_MP_RXN<2>")
	)
	(segment
		(start 143.28902 -96.82861)
		(end 143.187928 -96.929702)
		(width 0.0889)
		(layer "In9.Cu")
		(net "P3E_CPU1_PE3_MP_RXN<2>")
	)
	(arc
		(start 139.406376 -93.147388)
		(mid 139.596305 -93.205258)
		(end 139.735052 -93.347286)
		(width 0.0889)
		(layer "In9.Cu")
		(net "P3E_CPU1_PE3_MP_RXN<2>")
	)
	(arc
		(start 129.962148 -92.652088)
		(mid 130.247572 -92.568621)
		(end 130.456178 -92.356686)
		(width 0.0889)
		(layer "In9.Cu")
		(net "P3E_CPU1_PE3_MP_RXN<2>")
	)
	(arc
		(start 127.381762 -94.137988)
		(mid 127.669907 -94.055669)
		(end 127.880618 -93.842586)
		(width 0.0889)
		(layer "In9.Cu")
		(net "P3E_CPU1_PE3_MP_RXN<2>")
	)
	(arc
		(start 127.028448 -98.289618)
		(mid 127.101246 -97.998855)
		(end 127.022098 -97.709736)
		(width 0.0889)
		(layer "In9.Cu")
		(net "P3E_CPU1_PE3_MP_RXN<2>")
	)
	(arc
		(start 135.11022 -92.652088)
		(mid 135.301862 -92.709254)
		(end 135.441944 -92.851986)
		(width 0.0889)
		(layer "In9.Cu")
		(net "P3E_CPU1_PE3_MP_RXN<2>")
	)
	(arc
		(start 137.68197 -92.156534)
		(mid 137.87582 -92.212884)
		(end 138.017504 -92.356686)
		(width 0.0889)
		(layer "In9.Cu")
		(net "P3E_CPU1_PE3_MP_RXN<2>")
	)
	(arc
		(start 133.39318 -91.661488)
		(mid 133.584822 -91.718654)
		(end 133.724904 -91.861386)
		(width 0.0889)
		(layer "In9.Cu")
		(net "P3E_CPU1_PE3_MP_RXN<2>")
	)
	(arc
		(start 129.107438 -93.147134)
		(mid 129.390655 -93.062853)
		(end 129.597658 -92.851986)
		(width 0.0889)
		(layer "In9.Cu")
		(net "P3E_CPU1_PE3_MP_RXN<2>")
	)
	(arc
		(start 141.452092 -94.337886)
		(mid 141.667946 -94.553867)
		(end 141.962886 -94.63278)
		(width 0.0889)
		(layer "In9.Cu")
		(net "P3E_CPU1_PE3_MP_RXN<2>")
	)
	(arc
		(start 135.441944 -92.851986)
		(mid 135.648948 -93.06285)
		(end 135.932164 -93.147134)
		(width 0.0889)
		(layer "In9.Cu")
		(net "P3E_CPU1_PE3_MP_RXN<2>")
	)
	(arc
		(start 130.456178 -92.356686)
		(mid 130.597861 -92.212882)
		(end 130.791712 -92.156534)
		(width 0.0889)
		(layer "In9.Cu")
		(net "P3E_CPU1_PE3_MP_RXN<2>")
	)
	(arc
		(start 134.24789 -92.156534)
		(mid 134.44174 -92.212884)
		(end 134.583424 -92.356686)
		(width 0.0889)
		(layer "In9.Cu")
		(net "P3E_CPU1_PE3_MP_RXN<2>")
	)
	(arc
		(start 129.597658 -92.851986)
		(mid 129.737737 -92.70925)
		(end 129.929382 -92.652088)
		(width 0.0889)
		(layer "In9.Cu")
		(net "P3E_CPU1_PE3_MP_RXN<2>")
	)
	(arc
		(start 137.324084 -92.356686)
		(mid 137.465767 -92.212882)
		(end 137.659618 -92.156534)
		(width 0.0889)
		(layer "In9.Cu")
		(net "P3E_CPU1_PE3_MP_RXN<2>")
	)
	(arc
		(start 129.070862 -98.900234)
		(mid 128.87922 -98.843068)
		(end 128.739138 -98.700336)
		(width 0.0889)
		(layer "In9.Cu")
		(net "P3E_CPU1_PE3_MP_RXN<2>")
	)
	(arc
		(start 128.739138 -98.700336)
		(mid 128.532134 -98.489472)
		(end 128.248918 -98.405188)
		(width 0.0889)
		(layer "In9.Cu")
		(net "P3E_CPU1_PE3_MP_RXN<2>")
	)
	(arc
		(start 130.824478 -92.156534)
		(mid 131.107695 -92.072253)
		(end 131.314698 -91.861386)
		(width 0.0889)
		(layer "In9.Cu")
		(net "P3E_CPU1_PE3_MP_RXN<2>")
	)
	(arc
		(start 127.028448 -96.308418)
		(mid 127.101246 -96.017655)
		(end 127.022098 -95.728536)
		(width 0.0889)
		(layer "In9.Cu")
		(net "P3E_CPU1_PE3_MP_RXN<2>")
	)
	(arc
		(start 127.022098 -96.719136)
		(mid 126.968628 -96.524073)
		(end 127.017272 -96.327722)
		(width 0.0889)
		(layer "In9.Cu")
		(net "P3E_CPU1_PE3_MP_RXN<2>")
	)
	(arc
		(start 138.017504 -92.356686)
		(mid 138.226112 -92.568618)
		(end 138.511534 -92.652088)
		(width 0.0889)
		(layer "In9.Cu")
		(net "P3E_CPU1_PE3_MP_RXN<2>")
	)
	(arc
		(start 127.353822 -98.900234)
		(mid 127.020904 -98.698243)
		(end 127.017272 -98.308922)
		(width 0.0889)
		(layer "In9.Cu")
		(net "P3E_CPU1_PE3_MP_RXN<2>")
	)
	(arc
		(start 134.583424 -92.356686)
		(mid 134.792032 -92.568618)
		(end 135.077454 -92.652088)
		(width 0.0889)
		(layer "In9.Cu")
		(net "P3E_CPU1_PE3_MP_RXN<2>")
	)
	(arc
		(start 127.880618 -93.842586)
		(mid 128.020697 -93.69985)
		(end 128.212342 -93.642688)
		(width 0.0889)
		(layer "In9.Cu")
		(net "P3E_CPU1_PE3_MP_RXN<2>")
	)
	(arc
		(start 136.830054 -92.652088)
		(mid 137.115478 -92.568621)
		(end 137.324084 -92.356686)
		(width 0.0889)
		(layer "In9.Cu")
		(net "P3E_CPU1_PE3_MP_RXN<2>")
	)
	(arc
		(start 132.17652 -91.360244)
		(mid 132.317315 -91.220825)
		(end 132.507736 -91.165934)
		(width 0.0889)
		(layer "In9.Cu")
		(net "P3E_CPU1_PE3_MP_RXN<2>")
	)
	(arc
		(start 128.245108 -93.642688)
		(mid 128.530532 -93.559221)
		(end 128.739138 -93.347286)
		(width 0.0889)
		(layer "In9.Cu")
		(net "P3E_CPU1_PE3_MP_RXN<2>")
	)
	(arc
		(start 138.5443 -92.652088)
		(mid 138.735942 -92.709254)
		(end 138.876024 -92.851986)
		(width 0.0889)
		(layer "In9.Cu")
		(net "P3E_CPU1_PE3_MP_RXN<2>")
	)
	(arc
		(start 136.465564 -92.851986)
		(mid 136.605643 -92.70925)
		(end 136.797288 -92.652088)
		(width 0.0889)
		(layer "In9.Cu")
		(net "P3E_CPU1_PE3_MP_RXN<2>")
	)
	(arc
		(start 127.022098 -95.728536)
		(mid 126.968628 -95.533473)
		(end 127.017272 -95.337122)
		(width 0.0889)
		(layer "In9.Cu")
		(net "P3E_CPU1_PE3_MP_RXN<2>")
	)
	(arc
		(start 127.022098 -97.709736)
		(mid 126.968628 -97.514673)
		(end 127.017272 -97.318322)
		(width 0.0889)
		(layer "In9.Cu")
		(net "P3E_CPU1_PE3_MP_RXN<2>")
	)
	(arc
		(start 140.264896 -93.642688)
		(mid 140.454825 -93.700558)
		(end 140.593572 -93.842586)
		(width 0.0889)
		(layer "In9.Cu")
		(net "P3E_CPU1_PE3_MP_RXN<2>")
	)
	(arc
		(start 131.679188 -91.661488)
		(mid 131.964612 -91.578021)
		(end 132.173218 -91.366086)
		(width 0.0889)
		(layer "In9.Cu")
		(net "P3E_CPU1_PE3_MP_RXN<2>")
	)
	(arc
		(start 128.205738 -98.405188)
		(mid 127.922521 -98.489469)
		(end 127.715518 -98.700336)
		(width 0.0889)
		(layer "In9.Cu")
		(net "P3E_CPU1_PE3_MP_RXN<2>")
	)
	(arc
		(start 127.028448 -97.299018)
		(mid 127.101246 -97.008255)
		(end 127.022098 -96.719136)
		(width 0.0889)
		(layer "In9.Cu")
		(net "P3E_CPU1_PE3_MP_RXN<2>")
	)
	(arc
		(start 140.593572 -93.842586)
		(mid 140.804285 -94.055665)
		(end 141.092428 -94.137988)
		(width 0.0889)
		(layer "In9.Cu")
		(net "P3E_CPU1_PE3_MP_RXN<2>")
	)
	(arc
		(start 135.975344 -93.147134)
		(mid 136.258561 -93.062853)
		(end 136.465564 -92.851986)
		(width 0.0889)
		(layer "In9.Cu")
		(net "P3E_CPU1_PE3_MP_RXN<2>")
	)
	(arc
		(start 127.715518 -98.700336)
		(mid 127.575439 -98.843072)
		(end 127.383794 -98.900234)
		(width 0.0889)
		(layer "In9.Cu")
		(net "P3E_CPU1_PE3_MP_RXN<2>")
	)
	(arc
		(start 127.022098 -95.328486)
		(mid 127.10132 -95.039368)
		(end 127.028448 -94.748604)
		(width 0.0889)
		(layer "In9.Cu")
		(net "P3E_CPU1_PE3_MP_RXN<2>")
	)
	(arc
		(start 132.866384 -91.366086)
		(mid 133.074992 -91.578018)
		(end 133.360414 -91.661488)
		(width 0.0889)
		(layer "In9.Cu")
		(net "P3E_CPU1_PE3_MP_RXN<2>")
	)
	(arc
		(start 139.366244 -93.147134)
		(mid 139.373228 -93.147326)
		(end 139.380214 -93.147388)
		(width 0.0889)
		(layer "In9.Cu")
		(net "P3E_CPU1_PE3_MP_RXN<2>")
	)
	(arc
		(start 127.022098 -94.737936)
		(mid 127.019515 -94.342689)
		(end 127.357632 -94.137988)
		(width 0.0889)
		(layer "In9.Cu")
		(net "P3E_CPU1_PE3_MP_RXN<2>")
	)
	(arc
		(start 141.120368 -94.137988)
		(mid 141.31201 -94.195154)
		(end 141.452092 -94.337886)
		(width 0.0889)
		(layer "In9.Cu")
		(net "P3E_CPU1_PE3_MP_RXN<2>")
	)
	(arc
		(start 129.627376 -99.727766)
		(mid 129.585397 -99.174806)
		(end 129.103628 -98.900234)
		(width 0.0889)
		(layer "In9.Cu")
		(net "P3E_CPU1_PE3_MP_RXN<2>")
	)
	(arc
		(start 131.314698 -91.861386)
		(mid 131.454777 -91.71865)
		(end 131.646422 -91.661488)
		(width 0.0889)
		(layer "In9.Cu")
		(net "P3E_CPU1_PE3_MP_RXN<2>")
	)
	(arc
		(start 138.876024 -92.851986)
		(mid 139.083028 -93.06285)
		(end 139.366244 -93.147134)
		(width 0.0889)
		(layer "In9.Cu")
		(net "P3E_CPU1_PE3_MP_RXN<2>")
	)
	(arc
		(start 139.735052 -93.347286)
		(mid 139.94366 -93.559218)
		(end 140.229082 -93.642688)
		(width 0.0889)
		(layer "In9.Cu")
		(net "P3E_CPU1_PE3_MP_RXN<2>")
	)
	(arc
		(start 132.507736 -91.165934)
		(mid 132.7147 -91.216488)
		(end 132.866384 -91.366086)
		(width 0.0889)
		(layer "In9.Cu")
		(net "P3E_CPU1_PE3_MP_RXN<2>")
	)
	(arc
		(start 133.724904 -91.861386)
		(mid 133.931908 -92.07225)
		(end 134.215124 -92.156534)
		(width 0.0889)
		(layer "In9.Cu")
		(net "P3E_CPU1_PE3_MP_RXN<2>")
	)
	(arc
		(start 128.739138 -93.347286)
		(mid 128.880821 -93.203482)
		(end 129.074672 -93.147134)
		(width 0.0889)
		(layer "In9.Cu")
		(net "P3E_CPU1_PE3_MP_RXN<2>")
	)
	(segment
		(start 127.655828 -99.986338)
		(end 128.227328 -99.986338)
		(width 0.1143)
		(layer "F.Cu")
		(net "P3E_CPU1_PE3_MP_RXN<1>")
	)
	(via
		(at 128.227328 -99.986338)
		(size 0.508)
		(drill 0.254)
		(layers "F.Cu" "B.Cu")
		(net "P3E_CPU1_PE3_MP_RXN<1>")
	)
	(segment
		(start 138.518138 -91.470988)
		(end 138.550904 -91.470988)
		(width 0.0889)
		(layer "In9.Cu")
		(net "P3E_CPU1_PE3_MP_RXN<1>")
	)
	(segment
		(start 132.004562 -90.286078)
		(end 132.007864 -90.280236)
		(width 0.0889)
		(layer "In9.Cu")
		(net "P3E_CPU1_PE3_MP_RXN<1>")
	)
	(segment
		(start 92.279216 -115.555268)
		(end 83.155282 -117.380258)
		(width 0.1143)
		(layer "In9.Cu")
		(net "P3E_CPU1_PE3_MP_RXN<1>")
	)
	(segment
		(start 50.537364 -51.240436)
		(end 39.8526 -44.117768)
		(width 0.1143)
		(layer "In9.Cu")
		(net "P3E_CPU1_PE3_MP_RXN<1>")
	)
	(segment
		(start 126.488698 -93.452188)
		(end 126.521464 -93.452188)
		(width 0.0889)
		(layer "In9.Cu")
		(net "P3E_CPU1_PE3_MP_RXN<1>")
	)
	(segment
		(start 135.938768 -91.966034)
		(end 135.96874 -91.966034)
		(width 0.0889)
		(layer "In9.Cu")
		(net "P3E_CPU1_PE3_MP_RXN<1>")
	)
	(segment
		(start 52.033932 -79.204058)
		(end 53.77434 -70.502526)
		(width 0.1143)
		(layer "In9.Cu")
		(net "P3E_CPU1_PE3_MP_RXN<1>")
	)
	(segment
		(start 125.998478 -96.319086)
		(end 125.992128 -96.308418)
		(width 0.0889)
		(layer "In9.Cu")
		(net "P3E_CPU1_PE3_MP_RXN<1>")
	)
	(segment
		(start 52.882292 -80.667352)
		(end 52.62753 -80.718406)
		(width 0.1143)
		(layer "In9.Cu")
		(net "P3E_CPU1_PE3_MP_RXN<1>")
	)
	(segment
		(start 34.427668 -42.904918)
		(end 32.004254 -44.042584)
		(width 0.1143)
		(layer "In9.Cu")
		(net "P3E_CPU1_PE3_MP_RXN<1>")
	)
	(segment
		(start 140.816584 -92.461588)
		(end 141.806676 -93.45168)
		(width 0.0889)
		(layer "In9.Cu")
		(net "P3E_CPU1_PE3_MP_RXN<1>")
	)
	(segment
		(start 128.205738 -92.461588)
		(end 128.238504 -92.461588)
		(width 0.0889)
		(layer "In9.Cu")
		(net "P3E_CPU1_PE3_MP_RXN<1>")
	)
	(segment
		(start 53.016658 -80.757014)
		(end 52.882292 -80.667352)
		(width 0.1143)
		(layer "In9.Cu")
		(net "P3E_CPU1_PE3_MP_RXN<1>")
	)
	(segment
		(start 0.8001 -40.209978)
		(end 0.300228 -39.710106)
		(width 0.1143)
		(layer "In9.Cu")
		(net "P3E_CPU1_PE3_MP_RXN<1>")
	)
	(segment
		(start 140.2461 -92.461588)
		(end 140.816584 -92.461588)
		(width 0.0889)
		(layer "In9.Cu")
		(net "P3E_CPU1_PE3_MP_RXN<1>")
	)
	(segment
		(start 53.77434 -65.533016)
		(end 55.22595 -58.273442)
		(width 0.1143)
		(layer "In9.Cu")
		(net "P3E_CPU1_PE3_MP_RXN<1>")
	)
	(segment
		(start 10.830814 -42.455592)
		(end 10.505694 -42.531538)
		(width 0.1143)
		(layer "In9.Cu")
		(net "P3E_CPU1_PE3_MP_RXN<1>")
	)
	(segment
		(start 53.325776 -82.30235)
		(end 53.19141 -82.212688)
		(width 0.1143)
		(layer "In9.Cu")
		(net "P3E_CPU1_PE3_MP_RXN<1>")
	)
	(segment
		(start 55.22595 -58.273442)
		(end 50.537364 -51.240436)
		(width 0.1143)
		(layer "In9.Cu")
		(net "P3E_CPU1_PE3_MP_RXN<1>")
	)
	(segment
		(start 53.069236 -81.018888)
		(end 53.016658 -80.757014)
		(width 0.1143)
		(layer "In9.Cu")
		(net "P3E_CPU1_PE3_MP_RXN<1>")
	)
	(segment
		(start 125.998478 -98.300286)
		(end 125.992128 -98.289618)
		(width 0.0889)
		(layer "In9.Cu")
		(net "P3E_CPU1_PE3_MP_RXN<1>")
	)
	(segment
		(start 133.954266 -116.517166)
		(end 123.047506 -118.69801)
		(width 0.1143)
		(layer "In9.Cu")
		(net "P3E_CPU1_PE3_MP_RXN<1>")
	)
	(segment
		(start 35.84321 -42.904918)
		(end 34.427668 -42.904918)
		(width 0.1143)
		(layer "In9.Cu")
		(net "P3E_CPU1_PE3_MP_RXN<1>")
	)
	(segment
		(start 53.77434 -70.502526)
		(end 53.77434 -65.533016)
		(width 0.1143)
		(layer "In9.Cu")
		(net "P3E_CPU1_PE3_MP_RXN<1>")
	)
	(segment
		(start 126.003304 -98.308922)
		(end 125.998478 -98.300286)
		(width 0.0889)
		(layer "In9.Cu")
		(net "P3E_CPU1_PE3_MP_RXN<1>")
	)
	(segment
		(start 139.372848 -91.966034)
		(end 139.40155 -91.966034)
		(width 0.0889)
		(layer "In9.Cu")
		(net "P3E_CPU1_PE3_MP_RXN<1>")
	)
	(segment
		(start 53.378354 -82.564224)
		(end 53.325776 -82.30235)
		(width 0.1143)
		(layer "In9.Cu")
		(net "P3E_CPU1_PE3_MP_RXN<1>")
	)
	(segment
		(start 137.653014 -90.975434)
		(end 137.688574 -90.975434)
		(width 0.0889)
		(layer "In9.Cu")
		(net "P3E_CPU1_PE3_MP_RXN<1>")
	)
	(segment
		(start 131.639818 -90.480388)
		(end 131.661408 -90.480388)
		(width 0.0889)
		(layer "In9.Cu")
		(net "P3E_CPU1_PE3_MP_RXN<1>")
	)
	(segment
		(start 141.806676 -93.45168)
		(end 142.945104 -93.45168)
		(width 0.0889)
		(layer "In9.Cu")
		(net "P3E_CPU1_PE3_MP_RXN<1>")
	)
	(segment
		(start 125.992128 -94.748604)
		(end 125.998478 -94.737936)
		(width 0.0889)
		(layer "In9.Cu")
		(net "P3E_CPU1_PE3_MP_RXN<1>")
	)
	(segment
		(start 32.004254 -44.042584)
		(end 25.661366 -45.310298)
		(width 0.1143)
		(layer "In9.Cu")
		(net "P3E_CPU1_PE3_MP_RXN<1>")
	)
	(segment
		(start 52.62753 -80.718406)
		(end 52.291996 -80.494378)
		(width 0.1143)
		(layer "In9.Cu")
		(net "P3E_CPU1_PE3_MP_RXN<1>")
	)
	(segment
		(start 142.945104 -93.45168)
		(end 143.2941 -93.800676)
		(width 0.0889)
		(layer "In9.Cu")
		(net "P3E_CPU1_PE3_MP_RXN<1>")
	)
	(segment
		(start 136.790684 -91.470988)
		(end 136.82345 -91.470988)
		(width 0.0889)
		(layer "In9.Cu")
		(net "P3E_CPU1_PE3_MP_RXN<1>")
	)
	(segment
		(start 6.257544 -41.835578)
		(end 1.901698 -41.835578)
		(width 0.1143)
		(layer "In9.Cu")
		(net "P3E_CPU1_PE3_MP_RXN<1>")
	)
	(segment
		(start 144.19072 -106.280712)
		(end 133.954266 -116.517166)
		(width 0.1143)
		(layer "In9.Cu")
		(net "P3E_CPU1_PE3_MP_RXN<1>")
	)
	(segment
		(start 52.810156 -83.084924)
		(end 53.03393 -82.749644)
		(width 0.1143)
		(layer "In9.Cu")
		(net "P3E_CPU1_PE3_MP_RXN<1>")
	)
	(segment
		(start 125.998478 -97.309686)
		(end 125.992128 -97.299018)
		(width 0.0889)
		(layer "In9.Cu")
		(net "P3E_CPU1_PE3_MP_RXN<1>")
	)
	(segment
		(start 127.351028 -92.956634)
		(end 127.383794 -92.956634)
		(width 0.0889)
		(layer "In9.Cu")
		(net "P3E_CPU1_PE3_MP_RXN<1>")
	)
	(segment
		(start 52.724812 -81.204308)
		(end 52.979574 -81.153254)
		(width 0.1143)
		(layer "In9.Cu")
		(net "P3E_CPU1_PE3_MP_RXN<1>")
	)
	(segment
		(start 25.661366 -45.310298)
		(end 13.910564 -42.96029)
		(width 0.1143)
		(layer "In9.Cu")
		(net "P3E_CPU1_PE3_MP_RXN<1>")
	)
	(segment
		(start 123.047506 -118.69801)
		(end 105.965498 -115.282218)
		(width 0.1143)
		(layer "In9.Cu")
		(net "P3E_CPU1_PE3_MP_RXN<1>")
	)
	(segment
		(start 0.8001 -40.95369)
		(end 0.8001 -40.209978)
		(width 0.1143)
		(layer "In9.Cu")
		(net "P3E_CPU1_PE3_MP_RXN<1>")
	)
	(segment
		(start 56.704738 -102.568502)
		(end 52.810156 -83.084924)
		(width 0.1143)
		(layer "In9.Cu")
		(net "P3E_CPU1_PE3_MP_RXN<1>")
	)
	(segment
		(start 126.003304 -96.327722)
		(end 125.998478 -96.319086)
		(width 0.0889)
		(layer "In9.Cu")
		(net "P3E_CPU1_PE3_MP_RXN<1>")
	)
	(segment
		(start 39.8526 -44.117768)
		(end 35.84321 -42.904918)
		(width 0.1143)
		(layer "In9.Cu")
		(net "P3E_CPU1_PE3_MP_RXN<1>")
	)
	(segment
		(start 0.300228 -39.710106)
		(end 0.299974 -39.710106)
		(width 0.1143)
		(layer "In9.Cu")
		(net "P3E_CPU1_PE3_MP_RXN<1>")
	)
	(segment
		(start 98.436938 -116.78666)
		(end 92.279216 -115.555268)
		(width 0.1143)
		(layer "In9.Cu")
		(net "P3E_CPU1_PE3_MP_RXN<1>")
	)
	(segment
		(start 1.42113 -41.57472)
		(end 0.8001 -40.95369)
		(width 0.1143)
		(layer "In9.Cu")
		(net "P3E_CPU1_PE3_MP_RXN<1>")
	)
	(segment
		(start 52.601114 -82.039714)
		(end 52.501038 -81.539588)
		(width 0.1143)
		(layer "In9.Cu")
		(net "P3E_CPU1_PE3_MP_RXN<1>")
	)
	(segment
		(start 129.922778 -91.470988)
		(end 129.955544 -91.470988)
		(width 0.0889)
		(layer "In9.Cu")
		(net "P3E_CPU1_PE3_MP_RXN<1>")
	)
	(segment
		(start 143.2941 -93.800676)
		(end 143.365474 -93.800676)
		(width 0.0889)
		(layer "In9.Cu")
		(net "P3E_CPU1_PE3_MP_RXN<1>")
	)
	(segment
		(start 143.365474 -93.800676)
		(end 143.380968 -93.81617)
		(width 0.0889)
		(layer "In9.Cu")
		(net "P3E_CPU1_PE3_MP_RXN<1>")
	)
	(segment
		(start 69.785992 -114.706146)
		(end 60.816998 -108.725462)
		(width 0.1143)
		(layer "In9.Cu")
		(net "P3E_CPU1_PE3_MP_RXN<1>")
	)
	(segment
		(start 130.785108 -90.975434)
		(end 130.817874 -90.975434)
		(width 0.0889)
		(layer "In9.Cu")
		(net "P3E_CPU1_PE3_MP_RXN<1>")
	)
	(segment
		(start 105.965498 -115.282218)
		(end 98.436938 -116.78666)
		(width 0.1143)
		(layer "In9.Cu")
		(net "P3E_CPU1_PE3_MP_RXN<1>")
	)
	(segment
		(start 134.221728 -90.975434)
		(end 134.254494 -90.975434)
		(width 0.0889)
		(layer "In9.Cu")
		(net "P3E_CPU1_PE3_MP_RXN<1>")
	)
	(segment
		(start 52.936648 -82.263742)
		(end 52.601114 -82.039714)
		(width 0.1143)
		(layer "In9.Cu")
		(net "P3E_CPU1_PE3_MP_RXN<1>")
	)
	(segment
		(start 129.068068 -91.966034)
		(end 129.100834 -91.966034)
		(width 0.0889)
		(layer "In9.Cu")
		(net "P3E_CPU1_PE3_MP_RXN<1>")
	)
	(segment
		(start 126.525274 -99.586288)
		(end 126.492508 -99.586288)
		(width 0.0889)
		(layer "In9.Cu")
		(net "P3E_CPU1_PE3_MP_RXN<1>")
	)
	(segment
		(start 1.901698 -41.835578)
		(end 1.42113 -41.57472)
		(width 0.1143)
		(layer "In9.Cu")
		(net "P3E_CPU1_PE3_MP_RXN<1>")
	)
	(segment
		(start 144.19072 -94.625922)
		(end 144.19072 -106.280712)
		(width 0.1143)
		(layer "In9.Cu")
		(net "P3E_CPU1_PE3_MP_RXN<1>")
	)
	(segment
		(start 133.367018 -90.480388)
		(end 133.399784 -90.480388)
		(width 0.0889)
		(layer "In9.Cu")
		(net "P3E_CPU1_PE3_MP_RXN<1>")
	)
	(segment
		(start 60.816744 -108.725462)
		(end 56.704738 -102.568502)
		(width 0.1143)
		(layer "In9.Cu")
		(net "P3E_CPU1_PE3_MP_RXN<1>")
	)
	(segment
		(start 83.155282 -117.380258)
		(end 69.785992 -114.706146)
		(width 0.1143)
		(layer "In9.Cu")
		(net "P3E_CPU1_PE3_MP_RXN<1>")
	)
	(segment
		(start 53.288692 -82.69859)
		(end 53.378354 -82.564224)
		(width 0.1143)
		(layer "In9.Cu")
		(net "P3E_CPU1_PE3_MP_RXN<1>")
	)
	(segment
		(start 53.03393 -82.749644)
		(end 53.288692 -82.69859)
		(width 0.1143)
		(layer "In9.Cu")
		(net "P3E_CPU1_PE3_MP_RXN<1>")
	)
	(segment
		(start 13.910564 -42.96029)
		(end 10.830814 -42.455592)
		(width 0.1143)
		(layer "In9.Cu")
		(net "P3E_CPU1_PE3_MP_RXN<1>")
	)
	(segment
		(start 52.979574 -81.153254)
		(end 53.069236 -81.018888)
		(width 0.1143)
		(layer "In9.Cu")
		(net "P3E_CPU1_PE3_MP_RXN<1>")
	)
	(segment
		(start 60.816998 -108.725462)
		(end 60.816744 -108.725462)
		(width 0.1143)
		(layer "In9.Cu")
		(net "P3E_CPU1_PE3_MP_RXN<1>")
	)
	(segment
		(start 10.505694 -42.531538)
		(end 6.257544 -41.835578)
		(width 0.1143)
		(layer "In9.Cu")
		(net "P3E_CPU1_PE3_MP_RXN<1>")
	)
	(segment
		(start 53.19141 -82.212688)
		(end 52.936648 -82.263742)
		(width 0.1143)
		(layer "In9.Cu")
		(net "P3E_CPU1_PE3_MP_RXN<1>")
	)
	(segment
		(start 126.003304 -97.318322)
		(end 125.998478 -97.309686)
		(width 0.0889)
		(layer "In9.Cu")
		(net "P3E_CPU1_PE3_MP_RXN<1>")
	)
	(segment
		(start 52.291996 -80.494378)
		(end 52.033932 -79.204058)
		(width 0.1143)
		(layer "In9.Cu")
		(net "P3E_CPU1_PE3_MP_RXN<1>")
	)
	(segment
		(start 126.003304 -95.337122)
		(end 125.998478 -95.328486)
		(width 0.0889)
		(layer "In9.Cu")
		(net "P3E_CPU1_PE3_MP_RXN<1>")
	)
	(segment
		(start 52.501038 -81.539588)
		(end 52.724812 -81.204308)
		(width 0.1143)
		(layer "In9.Cu")
		(net "P3E_CPU1_PE3_MP_RXN<1>")
	)
	(segment
		(start 143.380968 -93.81617)
		(end 144.19072 -94.625922)
		(width 0.1143)
		(layer "In9.Cu")
		(net "P3E_CPU1_PE3_MP_RXN<1>")
	)
	(segment
		(start 135.084058 -91.470988)
		(end 135.116824 -91.470988)
		(width 0.0889)
		(layer "In9.Cu")
		(net "P3E_CPU1_PE3_MP_RXN<1>")
	)
	(arc
		(start 139.40155 -91.966034)
		(mid 139.689237 -92.048555)
		(end 139.899644 -92.261436)
		(width 0.0889)
		(layer "In9.Cu")
		(net "P3E_CPU1_PE3_MP_RXN<1>")
	)
	(arc
		(start 125.998478 -94.33814)
		(mid 125.993224 -93.756632)
		(end 126.488698 -93.452188)
		(width 0.0889)
		(layer "In9.Cu")
		(net "P3E_CPU1_PE3_MP_RXN<1>")
	)
	(arc
		(start 129.432558 -91.766136)
		(mid 129.639562 -91.555272)
		(end 129.922778 -91.470988)
		(width 0.0889)
		(layer "In9.Cu")
		(net "P3E_CPU1_PE3_MP_RXN<1>")
	)
	(arc
		(start 126.856998 -99.786186)
		(mid 126.716919 -99.64345)
		(end 126.525274 -99.586288)
		(width 0.0889)
		(layer "In9.Cu")
		(net "P3E_CPU1_PE3_MP_RXN<1>")
	)
	(arc
		(start 126.856998 -93.252036)
		(mid 127.065606 -93.040104)
		(end 127.351028 -92.956634)
		(width 0.0889)
		(layer "In9.Cu")
		(net "P3E_CPU1_PE3_MP_RXN<1>")
	)
	(arc
		(start 127.34671 -100.081334)
		(mid 127.063774 -99.996938)
		(end 126.856998 -99.786186)
		(width 0.0889)
		(layer "In9.Cu")
		(net "P3E_CPU1_PE3_MP_RXN<1>")
	)
	(arc
		(start 125.992128 -97.299018)
		(mid 125.91933 -97.008255)
		(end 125.998478 -96.719136)
		(width 0.0889)
		(layer "In9.Cu")
		(net "P3E_CPU1_PE3_MP_RXN<1>")
	)
	(arc
		(start 135.116824 -91.470988)
		(mid 135.400041 -91.555269)
		(end 135.607044 -91.766136)
		(width 0.0889)
		(layer "In9.Cu")
		(net "P3E_CPU1_PE3_MP_RXN<1>")
	)
	(arc
		(start 125.998478 -97.709736)
		(mid 126.051948 -97.514673)
		(end 126.003304 -97.318322)
		(width 0.0889)
		(layer "In9.Cu")
		(net "P3E_CPU1_PE3_MP_RXN<1>")
	)
	(arc
		(start 131.149598 -90.775536)
		(mid 131.356602 -90.564672)
		(end 131.639818 -90.480388)
		(width 0.0889)
		(layer "In9.Cu")
		(net "P3E_CPU1_PE3_MP_RXN<1>")
	)
	(arc
		(start 126.492508 -99.586288)
		(mid 125.994257 -99.283448)
		(end 125.998478 -98.700336)
		(width 0.0889)
		(layer "In9.Cu")
		(net "P3E_CPU1_PE3_MP_RXN<1>")
	)
	(arc
		(start 125.998478 -94.737936)
		(mid 126.051977 -94.538038)
		(end 125.998478 -94.33814)
		(width 0.0889)
		(layer "In9.Cu")
		(net "P3E_CPU1_PE3_MP_RXN<1>")
	)
	(arc
		(start 133.399784 -90.480388)
		(mid 133.683001 -90.564669)
		(end 133.890004 -90.775536)
		(width 0.0889)
		(layer "In9.Cu")
		(net "P3E_CPU1_PE3_MP_RXN<1>")
	)
	(arc
		(start 137.158984 -91.270836)
		(mid 137.367592 -91.058904)
		(end 137.653014 -90.975434)
		(width 0.0889)
		(layer "In9.Cu")
		(net "P3E_CPU1_PE3_MP_RXN<1>")
	)
	(arc
		(start 126.521464 -93.452188)
		(mid 126.715314 -93.395838)
		(end 126.856998 -93.252036)
		(width 0.0889)
		(layer "In9.Cu")
		(net "P3E_CPU1_PE3_MP_RXN<1>")
	)
	(arc
		(start 138.182604 -91.270836)
		(mid 138.324287 -91.41464)
		(end 138.518138 -91.470988)
		(width 0.0889)
		(layer "In9.Cu")
		(net "P3E_CPU1_PE3_MP_RXN<1>")
	)
	(arc
		(start 128.574038 -92.261436)
		(mid 128.782646 -92.049504)
		(end 129.068068 -91.966034)
		(width 0.0889)
		(layer "In9.Cu")
		(net "P3E_CPU1_PE3_MP_RXN<1>")
	)
	(arc
		(start 131.661408 -90.480388)
		(mid 131.858569 -90.428429)
		(end 132.004562 -90.286078)
		(width 0.0889)
		(layer "In9.Cu")
		(net "P3E_CPU1_PE3_MP_RXN<1>")
	)
	(arc
		(start 128.227328 -99.986338)
		(mid 127.790465 -100.06577)
		(end 127.34671 -100.081334)
		(width 0.0889)
		(layer "In9.Cu")
		(net "P3E_CPU1_PE3_MP_RXN<1>")
	)
	(arc
		(start 127.715518 -92.756736)
		(mid 127.922522 -92.545872)
		(end 128.205738 -92.461588)
		(width 0.0889)
		(layer "In9.Cu")
		(net "P3E_CPU1_PE3_MP_RXN<1>")
	)
	(arc
		(start 125.998478 -98.700336)
		(mid 126.051948 -98.505273)
		(end 126.003304 -98.308922)
		(width 0.0889)
		(layer "In9.Cu")
		(net "P3E_CPU1_PE3_MP_RXN<1>")
	)
	(arc
		(start 135.607044 -91.766136)
		(mid 135.747123 -91.908872)
		(end 135.938768 -91.966034)
		(width 0.0889)
		(layer "In9.Cu")
		(net "P3E_CPU1_PE3_MP_RXN<1>")
	)
	(arc
		(start 139.041124 -91.766136)
		(mid 139.181203 -91.908872)
		(end 139.372848 -91.966034)
		(width 0.0889)
		(layer "In9.Cu")
		(net "P3E_CPU1_PE3_MP_RXN<1>")
	)
	(arc
		(start 130.291078 -91.270836)
		(mid 130.499686 -91.058904)
		(end 130.785108 -90.975434)
		(width 0.0889)
		(layer "In9.Cu")
		(net "P3E_CPU1_PE3_MP_RXN<1>")
	)
	(arc
		(start 134.254494 -90.975434)
		(mid 134.539918 -91.058901)
		(end 134.748524 -91.270836)
		(width 0.0889)
		(layer "In9.Cu")
		(net "P3E_CPU1_PE3_MP_RXN<1>")
	)
	(arc
		(start 139.899644 -92.261436)
		(mid 140.046026 -92.408)
		(end 140.2461 -92.461588)
		(width 0.0889)
		(layer "In9.Cu")
		(net "P3E_CPU1_PE3_MP_RXN<1>")
	)
	(arc
		(start 135.96874 -91.966034)
		(mid 136.160382 -91.908868)
		(end 136.300464 -91.766136)
		(width 0.0889)
		(layer "In9.Cu")
		(net "P3E_CPU1_PE3_MP_RXN<1>")
	)
	(arc
		(start 136.82345 -91.470988)
		(mid 137.0173 -91.414638)
		(end 137.158984 -91.270836)
		(width 0.0889)
		(layer "In9.Cu")
		(net "P3E_CPU1_PE3_MP_RXN<1>")
	)
	(arc
		(start 134.748524 -91.270836)
		(mid 134.890207 -91.41464)
		(end 135.084058 -91.470988)
		(width 0.0889)
		(layer "In9.Cu")
		(net "P3E_CPU1_PE3_MP_RXN<1>")
	)
	(arc
		(start 129.100834 -91.966034)
		(mid 129.292476 -91.908868)
		(end 129.432558 -91.766136)
		(width 0.0889)
		(layer "In9.Cu")
		(net "P3E_CPU1_PE3_MP_RXN<1>")
	)
	(arc
		(start 125.998478 -96.719136)
		(mid 126.051948 -96.524073)
		(end 126.003304 -96.327722)
		(width 0.0889)
		(layer "In9.Cu")
		(net "P3E_CPU1_PE3_MP_RXN<1>")
	)
	(arc
		(start 125.998478 -95.328486)
		(mid 125.919256 -95.039368)
		(end 125.992128 -94.748604)
		(width 0.0889)
		(layer "In9.Cu")
		(net "P3E_CPU1_PE3_MP_RXN<1>")
	)
	(arc
		(start 130.817874 -90.975434)
		(mid 131.009516 -90.918268)
		(end 131.149598 -90.775536)
		(width 0.0889)
		(layer "In9.Cu")
		(net "P3E_CPU1_PE3_MP_RXN<1>")
	)
	(arc
		(start 125.992128 -96.308418)
		(mid 125.91933 -96.017655)
		(end 125.998478 -95.728536)
		(width 0.0889)
		(layer "In9.Cu")
		(net "P3E_CPU1_PE3_MP_RXN<1>")
	)
	(arc
		(start 133.031484 -90.280236)
		(mid 133.173167 -90.42404)
		(end 133.367018 -90.480388)
		(width 0.0889)
		(layer "In9.Cu")
		(net "P3E_CPU1_PE3_MP_RXN<1>")
	)
	(arc
		(start 137.688574 -90.975434)
		(mid 137.973998 -91.058901)
		(end 138.182604 -91.270836)
		(width 0.0889)
		(layer "In9.Cu")
		(net "P3E_CPU1_PE3_MP_RXN<1>")
	)
	(arc
		(start 129.955544 -91.470988)
		(mid 130.149394 -91.414638)
		(end 130.291078 -91.270836)
		(width 0.0889)
		(layer "In9.Cu")
		(net "P3E_CPU1_PE3_MP_RXN<1>")
	)
	(arc
		(start 138.550904 -91.470988)
		(mid 138.834121 -91.555269)
		(end 139.041124 -91.766136)
		(width 0.0889)
		(layer "In9.Cu")
		(net "P3E_CPU1_PE3_MP_RXN<1>")
	)
	(arc
		(start 133.890004 -90.775536)
		(mid 134.030083 -90.918272)
		(end 134.221728 -90.975434)
		(width 0.0889)
		(layer "In9.Cu")
		(net "P3E_CPU1_PE3_MP_RXN<1>")
	)
	(arc
		(start 125.998478 -95.728536)
		(mid 126.051948 -95.533473)
		(end 126.003304 -95.337122)
		(width 0.0889)
		(layer "In9.Cu")
		(net "P3E_CPU1_PE3_MP_RXN<1>")
	)
	(arc
		(start 128.238504 -92.461588)
		(mid 128.432354 -92.405238)
		(end 128.574038 -92.261436)
		(width 0.0889)
		(layer "In9.Cu")
		(net "P3E_CPU1_PE3_MP_RXN<1>")
	)
	(arc
		(start 125.992128 -98.289618)
		(mid 125.91933 -97.998855)
		(end 125.998478 -97.709736)
		(width 0.0889)
		(layer "In9.Cu")
		(net "P3E_CPU1_PE3_MP_RXN<1>")
	)
	(arc
		(start 127.383794 -92.956634)
		(mid 127.575436 -92.899468)
		(end 127.715518 -92.756736)
		(width 0.0889)
		(layer "In9.Cu")
		(net "P3E_CPU1_PE3_MP_RXN<1>")
	)
	(arc
		(start 136.300464 -91.766136)
		(mid 136.507468 -91.555272)
		(end 136.790684 -91.470988)
		(width 0.0889)
		(layer "In9.Cu")
		(net "P3E_CPU1_PE3_MP_RXN<1>")
	)
	(arc
		(start 132.007864 -90.280236)
		(mid 132.519674 -89.984569)
		(end 133.031484 -90.280236)
		(width 0.0889)
		(layer "In9.Cu")
		(net "P3E_CPU1_PE3_MP_RXN<1>")
	)
	(segment
		(start 127.655828 -100.976684)
		(end 128.227328 -100.976684)
		(width 0.1143)
		(layer "F.Cu")
		(net "P3E_CPU1_PE3_MP_RXN<0>")
	)
	(via
		(at 128.227328 -100.976684)
		(size 0.508)
		(drill 0.254)
		(layers "F.Cu" "B.Cu")
		(net "P3E_CPU1_PE3_MP_RXN<0>")
	)
	(segment
		(start 39.394892 -44.643802)
		(end 50.051462 -51.748182)
		(width 0.1143)
		(layer "In9.Cu")
		(net "P3E_CPU1_PE3_MP_RXN<0>")
	)
	(segment
		(start 126.488698 -100.576888)
		(end 126.528322 -100.576888)
		(width 0.0889)
		(layer "In9.Cu")
		(net "P3E_CPU1_PE3_MP_RXN<0>")
	)
	(segment
		(start 34.479992 -43.58259)
		(end 35.78352 -43.58259)
		(width 0.1143)
		(layer "In9.Cu")
		(net "P3E_CPU1_PE3_MP_RXN<0>")
	)
	(segment
		(start 25.94102 -46.014386)
		(end 26.745692 -45.847)
		(width 0.1143)
		(layer "In9.Cu")
		(net "P3E_CPU1_PE3_MP_RXN<0>")
	)
	(segment
		(start 132.007864 -89.289636)
		(end 132.004562 -89.295478)
		(width 0.0889)
		(layer "In9.Cu")
		(net "P3E_CPU1_PE3_MP_RXN<0>")
	)
	(segment
		(start 128.238504 -91.470988)
		(end 128.205738 -91.470988)
		(width 0.0889)
		(layer "In9.Cu")
		(net "P3E_CPU1_PE3_MP_RXN<0>")
	)
	(segment
		(start 98.400108 -117.96268)
		(end 107.241848 -116.192554)
		(width 0.1143)
		(layer "In9.Cu")
		(net "P3E_CPU1_PE3_MP_RXN<0>")
	)
	(segment
		(start -3.899916 -39.710106)
		(end -3.899662 -39.710106)
		(width 0.1143)
		(layer "In9.Cu")
		(net "P3E_CPU1_PE3_MP_RXN<0>")
	)
	(segment
		(start 28.242514 -47.282608)
		(end 29.123894 -47.458376)
		(width 0.1143)
		(layer "In9.Cu")
		(net "P3E_CPU1_PE3_MP_RXN<0>")
	)
	(segment
		(start 50.051462 -51.748182)
		(end 54.468268 -58.372502)
		(width 0.1143)
		(layer "In9.Cu")
		(net "P3E_CPU1_PE3_MP_RXN<0>")
	)
	(segment
		(start 125.144784 -94.234)
		(end 125.139958 -94.242636)
		(width 0.0889)
		(layer "In9.Cu")
		(net "P3E_CPU1_PE3_MP_RXN<0>")
	)
	(segment
		(start 144.90192 -94.0308)
		(end 143.987774 -93.116654)
		(width 0.1143)
		(layer "In9.Cu")
		(net "P3E_CPU1_PE3_MP_RXN<0>")
	)
	(segment
		(start 138.550904 -90.480388)
		(end 138.518138 -90.480388)
		(width 0.0889)
		(layer "In9.Cu")
		(net "P3E_CPU1_PE3_MP_RXN<0>")
	)
	(segment
		(start 134.76478 -117.050566)
		(end 144.90192 -106.913426)
		(width 0.1143)
		(layer "In9.Cu")
		(net "P3E_CPU1_PE3_MP_RXN<0>")
	)
	(segment
		(start 125.144784 -98.1964)
		(end 125.139958 -98.205036)
		(width 0.0889)
		(layer "In9.Cu")
		(net "P3E_CPU1_PE3_MP_RXN<0>")
	)
	(segment
		(start 16.182594 -44.238418)
		(end 17.061942 -44.238418)
		(width 0.1143)
		(layer "In9.Cu")
		(net "P3E_CPU1_PE3_MP_RXN<0>")
	)
	(segment
		(start 11.17981 -43.2435)
		(end 16.182594 -44.238418)
		(width 0.1143)
		(layer "In9.Cu")
		(net "P3E_CPU1_PE3_MP_RXN<0>")
	)
	(segment
		(start 82.964782 -118.073424)
		(end 90.958924 -116.475002)
		(width 0.1143)
		(layer "In9.Cu")
		(net "P3E_CPU1_PE3_MP_RXN<0>")
	)
	(segment
		(start 107.241848 -116.192554)
		(end 123.147582 -119.37365)
		(width 0.1143)
		(layer "In9.Cu")
		(net "P3E_CPU1_PE3_MP_RXN<0>")
	)
	(segment
		(start 137.688574 -89.984834)
		(end 137.653014 -89.984834)
		(width 0.0889)
		(layer "In9.Cu")
		(net "P3E_CPU1_PE3_MP_RXN<0>")
	)
	(segment
		(start 60.053728 -109.026198)
		(end 69.6214 -115.4049)
		(width 0.1143)
		(layer "In9.Cu")
		(net "P3E_CPU1_PE3_MP_RXN<0>")
	)
	(segment
		(start 134.254494 -89.984834)
		(end 134.221728 -89.984834)
		(width 0.0889)
		(layer "In9.Cu")
		(net "P3E_CPU1_PE3_MP_RXN<0>")
	)
	(segment
		(start 125.144784 -97.2058)
		(end 125.139958 -97.214436)
		(width 0.0889)
		(layer "In9.Cu")
		(net "P3E_CPU1_PE3_MP_RXN<0>")
	)
	(segment
		(start 128.209294 -100.576888)
		(end 128.245362 -100.576888)
		(width 0.0889)
		(layer "In9.Cu")
		(net "P3E_CPU1_PE3_MP_RXN<0>")
	)
	(segment
		(start 125.139958 -99.195636)
		(end 125.133608 -99.206304)
		(width 0.0889)
		(layer "In9.Cu")
		(net "P3E_CPU1_PE3_MP_RXN<0>")
	)
	(segment
		(start 56.032654 -102.994968)
		(end 60.053728 -109.026198)
		(width 0.1143)
		(layer "In9.Cu")
		(net "P3E_CPU1_PE3_MP_RXN<0>")
	)
	(segment
		(start 39.390066 -44.642532)
		(end 39.393114 -44.643294)
		(width 0.1143)
		(layer "In9.Cu")
		(net "P3E_CPU1_PE3_MP_RXN<0>")
	)
	(segment
		(start 133.399784 -89.489788)
		(end 133.367018 -89.489788)
		(width 0.0889)
		(layer "In9.Cu")
		(net "P3E_CPU1_PE3_MP_RXN<0>")
	)
	(segment
		(start 135.96874 -90.975434)
		(end 135.938768 -90.975434)
		(width 0.0889)
		(layer "In9.Cu")
		(net "P3E_CPU1_PE3_MP_RXN<0>")
	)
	(segment
		(start 27.432 -46.075854)
		(end 27.70886 -46.755304)
		(width 0.1143)
		(layer "In9.Cu")
		(net "P3E_CPU1_PE3_MP_RXN<0>")
	)
	(segment
		(start 54.468268 -58.372502)
		(end 53.02504 -65.589658)
		(width 0.1143)
		(layer "In9.Cu")
		(net "P3E_CPU1_PE3_MP_RXN<0>")
	)
	(segment
		(start 129.955544 -90.480388)
		(end 129.922778 -90.480388)
		(width 0.0889)
		(layer "In9.Cu")
		(net "P3E_CPU1_PE3_MP_RXN<0>")
	)
	(segment
		(start 136.82345 -90.480388)
		(end 136.790684 -90.480388)
		(width 0.0889)
		(layer "In9.Cu")
		(net "P3E_CPU1_PE3_MP_RXN<0>")
	)
	(segment
		(start -1.518158 -42.5323)
		(end 6.385306 -42.5323)
		(width 0.1143)
		(layer "In9.Cu")
		(net "P3E_CPU1_PE3_MP_RXN<0>")
	)
	(segment
		(start 125.638814 -100.081588)
		(end 125.662944 -100.081588)
		(width 0.0889)
		(layer "In9.Cu")
		(net "P3E_CPU1_PE3_MP_RXN<0>")
	)
	(segment
		(start 131.661408 -89.489788)
		(end 131.639818 -89.489788)
		(width 0.0889)
		(layer "In9.Cu")
		(net "P3E_CPU1_PE3_MP_RXN<0>")
	)
	(segment
		(start 90.958924 -116.475002)
		(end 98.400108 -117.96268)
		(width 0.1143)
		(layer "In9.Cu")
		(net "P3E_CPU1_PE3_MP_RXN<0>")
	)
	(segment
		(start -3.899662 -39.710106)
		(end -3.3655 -40.244268)
		(width 0.1143)
		(layer "In9.Cu")
		(net "P3E_CPU1_PE3_MP_RXN<0>")
	)
	(segment
		(start 129.100834 -90.975434)
		(end 129.068068 -90.975434)
		(width 0.0889)
		(layer "In9.Cu")
		(net "P3E_CPU1_PE3_MP_RXN<0>")
	)
	(segment
		(start 32.194246 -44.656248)
		(end 34.479992 -43.58259)
		(width 0.1143)
		(layer "In9.Cu")
		(net "P3E_CPU1_PE3_MP_RXN<0>")
	)
	(segment
		(start 125.144784 -99.187)
		(end 125.139958 -99.195636)
		(width 0.0889)
		(layer "In9.Cu")
		(net "P3E_CPU1_PE3_MP_RXN<0>")
	)
	(segment
		(start 35.78352 -43.58259)
		(end 39.390066 -44.642532)
		(width 0.1143)
		(layer "In9.Cu")
		(net "P3E_CPU1_PE3_MP_RXN<0>")
	)
	(segment
		(start -3.3655 -40.684958)
		(end -1.518158 -42.5323)
		(width 0.1143)
		(layer "In9.Cu")
		(net "P3E_CPU1_PE3_MP_RXN<0>")
	)
	(segment
		(start 9.960864 -43.2435)
		(end 11.17981 -43.2435)
		(width 0.1143)
		(layer "In9.Cu")
		(net "P3E_CPU1_PE3_MP_RXN<0>")
	)
	(segment
		(start 126.521464 -92.461588)
		(end 126.488698 -92.461588)
		(width 0.0889)
		(layer "In9.Cu")
		(net "P3E_CPU1_PE3_MP_RXN<0>")
	)
	(segment
		(start 125.139958 -98.205036)
		(end 125.133608 -98.215704)
		(width 0.0889)
		(layer "In9.Cu")
		(net "P3E_CPU1_PE3_MP_RXN<0>")
	)
	(segment
		(start 139.40282 -90.975434)
		(end 139.372848 -90.975434)
		(width 0.0889)
		(layer "In9.Cu")
		(net "P3E_CPU1_PE3_MP_RXN<0>")
	)
	(segment
		(start 69.6214 -115.4049)
		(end 82.964782 -118.073424)
		(width 0.1143)
		(layer "In9.Cu")
		(net "P3E_CPU1_PE3_MP_RXN<0>")
	)
	(segment
		(start -3.3655 -40.244268)
		(end -3.3655 -40.684958)
		(width 0.1143)
		(layer "In9.Cu")
		(net "P3E_CPU1_PE3_MP_RXN<0>")
	)
	(segment
		(start 26.745692 -45.847)
		(end 27.432 -46.075854)
		(width 0.1143)
		(layer "In9.Cu")
		(net "P3E_CPU1_PE3_MP_RXN<0>")
	)
	(segment
		(start 17.061942 -44.238418)
		(end 25.940766 -46.014386)
		(width 0.1143)
		(layer "In9.Cu")
		(net "P3E_CPU1_PE3_MP_RXN<0>")
	)
	(segment
		(start 123.147582 -119.37365)
		(end 134.76478 -117.050566)
		(width 0.1143)
		(layer "In9.Cu")
		(net "P3E_CPU1_PE3_MP_RXN<0>")
	)
	(segment
		(start 39.393114 -44.643294)
		(end 39.394892 -44.643802)
		(width 0.1143)
		(layer "In9.Cu")
		(net "P3E_CPU1_PE3_MP_RXN<0>")
	)
	(segment
		(start 143.97228 -93.10116)
		(end 143.900398 -93.10116)
		(width 0.0889)
		(layer "In9.Cu")
		(net "P3E_CPU1_PE3_MP_RXN<0>")
	)
	(segment
		(start 53.02504 -70.53707)
		(end 51.293268 -79.194152)
		(width 0.1143)
		(layer "In9.Cu")
		(net "P3E_CPU1_PE3_MP_RXN<0>")
	)
	(segment
		(start 125.144784 -96.2152)
		(end 125.139958 -96.223836)
		(width 0.0889)
		(layer "In9.Cu")
		(net "P3E_CPU1_PE3_MP_RXN<0>")
	)
	(segment
		(start 125.139958 -96.223836)
		(end 125.133608 -96.234504)
		(width 0.0889)
		(layer "In9.Cu")
		(net "P3E_CPU1_PE3_MP_RXN<0>")
	)
	(segment
		(start 27.70886 -46.755304)
		(end 28.242514 -47.282608)
		(width 0.1143)
		(layer "In9.Cu")
		(net "P3E_CPU1_PE3_MP_RXN<0>")
	)
	(segment
		(start 130.817874 -89.984834)
		(end 130.785108 -89.984834)
		(width 0.0889)
		(layer "In9.Cu")
		(net "P3E_CPU1_PE3_MP_RXN<0>")
	)
	(segment
		(start 141.279626 -90.480388)
		(end 140.224764 -90.480388)
		(width 0.0889)
		(layer "In9.Cu")
		(net "P3E_CPU1_PE3_MP_RXN<0>")
	)
	(segment
		(start 125.139958 -97.214436)
		(end 125.133608 -97.225104)
		(width 0.0889)
		(layer "In9.Cu")
		(net "P3E_CPU1_PE3_MP_RXN<0>")
	)
	(segment
		(start 125.666754 -92.956634)
		(end 125.633988 -92.956634)
		(width 0.0889)
		(layer "In9.Cu")
		(net "P3E_CPU1_PE3_MP_RXN<0>")
	)
	(segment
		(start 125.133608 -94.822518)
		(end 125.139958 -94.833186)
		(width 0.0889)
		(layer "In9.Cu")
		(net "P3E_CPU1_PE3_MP_RXN<0>")
	)
	(segment
		(start 6.385306 -42.5323)
		(end 9.960864 -43.2435)
		(width 0.1143)
		(layer "In9.Cu")
		(net "P3E_CPU1_PE3_MP_RXN<0>")
	)
	(segment
		(start 143.987774 -93.116654)
		(end 143.97228 -93.10116)
		(width 0.0889)
		(layer "In9.Cu")
		(net "P3E_CPU1_PE3_MP_RXN<0>")
	)
	(segment
		(start 143.900398 -93.10116)
		(end 141.279626 -90.480388)
		(width 0.0889)
		(layer "In9.Cu")
		(net "P3E_CPU1_PE3_MP_RXN<0>")
	)
	(segment
		(start 127.383794 -91.966034)
		(end 127.351028 -91.966034)
		(width 0.0889)
		(layer "In9.Cu")
		(net "P3E_CPU1_PE3_MP_RXN<0>")
	)
	(segment
		(start 29.932884 -47.308516)
		(end 32.194246 -44.656248)
		(width 0.1143)
		(layer "In9.Cu")
		(net "P3E_CPU1_PE3_MP_RXN<0>")
	)
	(segment
		(start 51.293268 -79.194152)
		(end 56.032654 -102.994968)
		(width 0.1143)
		(layer "In9.Cu")
		(net "P3E_CPU1_PE3_MP_RXN<0>")
	)
	(segment
		(start 25.940766 -46.014386)
		(end 25.94102 -46.014386)
		(width 0.1143)
		(layer "In9.Cu")
		(net "P3E_CPU1_PE3_MP_RXN<0>")
	)
	(segment
		(start 128.541526 -100.729034)
		(end 128.520444 -100.807774)
		(width 0.0889)
		(layer "In9.Cu")
		(net "P3E_CPU1_PE3_MP_RXN<0>")
	)
	(segment
		(start 53.02504 -65.589658)
		(end 53.02504 -70.53707)
		(width 0.1143)
		(layer "In9.Cu")
		(net "P3E_CPU1_PE3_MP_RXN<0>")
	)
	(segment
		(start 29.123894 -47.458376)
		(end 29.827474 -47.317914)
		(width 0.1143)
		(layer "In9.Cu")
		(net "P3E_CPU1_PE3_MP_RXN<0>")
	)
	(segment
		(start 144.90192 -106.913426)
		(end 144.90192 -94.0308)
		(width 0.1143)
		(layer "In9.Cu")
		(net "P3E_CPU1_PE3_MP_RXN<0>")
	)
	(segment
		(start 128.520444 -100.807774)
		(end 128.227328 -100.976684)
		(width 0.0889)
		(layer "In9.Cu")
		(net "P3E_CPU1_PE3_MP_RXN<0>")
	)
	(segment
		(start 29.827474 -47.317914)
		(end 29.932884 -47.308516)
		(width 0.1143)
		(layer "In9.Cu")
		(net "P3E_CPU1_PE3_MP_RXN<0>")
	)
	(segment
		(start 135.116824 -90.480388)
		(end 135.084058 -90.480388)
		(width 0.0889)
		(layer "In9.Cu")
		(net "P3E_CPU1_PE3_MP_RXN<0>")
	)
	(arc
		(start 126.488698 -92.461588)
		(mid 126.205481 -92.545869)
		(end 125.998478 -92.756736)
		(width 0.0889)
		(layer "In9.Cu")
		(net "P3E_CPU1_PE3_MP_RXN<0>")
	)
	(arc
		(start 125.139958 -95.232982)
		(mid 125.060827 -95.528384)
		(end 125.139958 -95.823786)
		(width 0.0889)
		(layer "In9.Cu")
		(net "P3E_CPU1_PE3_MP_RXN<0>")
	)
	(arc
		(start 125.633988 -92.956634)
		(mid 125.135737 -93.259474)
		(end 125.139958 -93.842586)
		(width 0.0889)
		(layer "In9.Cu")
		(net "P3E_CPU1_PE3_MP_RXN<0>")
	)
	(arc
		(start 138.518138 -90.480388)
		(mid 138.324288 -90.424038)
		(end 138.182604 -90.280236)
		(width 0.0889)
		(layer "In9.Cu")
		(net "P3E_CPU1_PE3_MP_RXN<0>")
	)
	(arc
		(start 125.139958 -97.804986)
		(mid 125.193428 -98.000049)
		(end 125.144784 -98.1964)
		(width 0.0889)
		(layer "In9.Cu")
		(net "P3E_CPU1_PE3_MP_RXN<0>")
	)
	(arc
		(start 126.528322 -100.576888)
		(mid 126.718251 -100.634758)
		(end 126.856998 -100.776786)
		(width 0.0889)
		(layer "In9.Cu")
		(net "P3E_CPU1_PE3_MP_RXN<0>")
	)
	(arc
		(start 139.372848 -90.975434)
		(mid 139.181206 -90.918268)
		(end 139.041124 -90.775536)
		(width 0.0889)
		(layer "In9.Cu")
		(net "P3E_CPU1_PE3_MP_RXN<0>")
	)
	(arc
		(start 137.653014 -89.984834)
		(mid 137.36759 -90.068301)
		(end 137.158984 -90.280236)
		(width 0.0889)
		(layer "In9.Cu")
		(net "P3E_CPU1_PE3_MP_RXN<0>")
	)
	(arc
		(start 139.041124 -90.775536)
		(mid 138.83412 -90.564672)
		(end 138.550904 -90.480388)
		(width 0.0889)
		(layer "In9.Cu")
		(net "P3E_CPU1_PE3_MP_RXN<0>")
	)
	(arc
		(start 125.998478 -92.756736)
		(mid 125.858399 -92.899472)
		(end 125.666754 -92.956634)
		(width 0.0889)
		(layer "In9.Cu")
		(net "P3E_CPU1_PE3_MP_RXN<0>")
	)
	(arc
		(start 129.922778 -90.480388)
		(mid 129.639561 -90.564669)
		(end 129.432558 -90.775536)
		(width 0.0889)
		(layer "In9.Cu")
		(net "P3E_CPU1_PE3_MP_RXN<0>")
	)
	(arc
		(start 133.031484 -89.289636)
		(mid 132.519674 -88.993969)
		(end 132.007864 -89.289636)
		(width 0.0889)
		(layer "In9.Cu")
		(net "P3E_CPU1_PE3_MP_RXN<0>")
	)
	(arc
		(start 130.785108 -89.984834)
		(mid 130.499684 -90.068301)
		(end 130.291078 -90.280236)
		(width 0.0889)
		(layer "In9.Cu")
		(net "P3E_CPU1_PE3_MP_RXN<0>")
	)
	(arc
		(start 126.856998 -100.776786)
		(mid 127.368808 -101.072453)
		(end 127.880618 -100.776786)
		(width 0.0889)
		(layer "In9.Cu")
		(net "P3E_CPU1_PE3_MP_RXN<0>")
	)
	(arc
		(start 127.715518 -91.766136)
		(mid 127.575439 -91.908872)
		(end 127.383794 -91.966034)
		(width 0.0889)
		(layer "In9.Cu")
		(net "P3E_CPU1_PE3_MP_RXN<0>")
	)
	(arc
		(start 134.748524 -90.280236)
		(mid 134.539916 -90.068304)
		(end 134.254494 -89.984834)
		(width 0.0889)
		(layer "In9.Cu")
		(net "P3E_CPU1_PE3_MP_RXN<0>")
	)
	(arc
		(start 134.221728 -89.984834)
		(mid 134.030086 -89.927668)
		(end 133.890004 -89.784936)
		(width 0.0889)
		(layer "In9.Cu")
		(net "P3E_CPU1_PE3_MP_RXN<0>")
	)
	(arc
		(start 125.998478 -100.28174)
		(mid 126.205482 -100.492604)
		(end 126.488698 -100.576888)
		(width 0.0889)
		(layer "In9.Cu")
		(net "P3E_CPU1_PE3_MP_RXN<0>")
	)
	(arc
		(start 128.205738 -91.470988)
		(mid 127.922521 -91.555269)
		(end 127.715518 -91.766136)
		(width 0.0889)
		(layer "In9.Cu")
		(net "P3E_CPU1_PE3_MP_RXN<0>")
	)
	(arc
		(start 135.938768 -90.975434)
		(mid 135.747126 -90.918268)
		(end 135.607044 -90.775536)
		(width 0.0889)
		(layer "In9.Cu")
		(net "P3E_CPU1_PE3_MP_RXN<0>")
	)
	(arc
		(start 135.607044 -90.775536)
		(mid 135.40004 -90.564672)
		(end 135.116824 -90.480388)
		(width 0.0889)
		(layer "In9.Cu")
		(net "P3E_CPU1_PE3_MP_RXN<0>")
	)
	(arc
		(start 127.351028 -91.966034)
		(mid 127.065604 -92.049501)
		(end 126.856998 -92.261436)
		(width 0.0889)
		(layer "In9.Cu")
		(net "P3E_CPU1_PE3_MP_RXN<0>")
	)
	(arc
		(start 125.139958 -93.842586)
		(mid 125.193428 -94.037649)
		(end 125.144784 -94.234)
		(width 0.0889)
		(layer "In9.Cu")
		(net "P3E_CPU1_PE3_MP_RXN<0>")
	)
	(arc
		(start 125.133608 -97.225104)
		(mid 125.06081 -97.515867)
		(end 125.139958 -97.804986)
		(width 0.0889)
		(layer "In9.Cu")
		(net "P3E_CPU1_PE3_MP_RXN<0>")
	)
	(arc
		(start 129.432558 -90.775536)
		(mid 129.292479 -90.918272)
		(end 129.100834 -90.975434)
		(width 0.0889)
		(layer "In9.Cu")
		(net "P3E_CPU1_PE3_MP_RXN<0>")
	)
	(arc
		(start 135.084058 -90.480388)
		(mid 134.890208 -90.424038)
		(end 134.748524 -90.280236)
		(width 0.0889)
		(layer "In9.Cu")
		(net "P3E_CPU1_PE3_MP_RXN<0>")
	)
	(arc
		(start 136.790684 -90.480388)
		(mid 136.507467 -90.564669)
		(end 136.300464 -90.775536)
		(width 0.0889)
		(layer "In9.Cu")
		(net "P3E_CPU1_PE3_MP_RXN<0>")
	)
	(arc
		(start 129.068068 -90.975434)
		(mid 128.782644 -91.058901)
		(end 128.574038 -91.270836)
		(width 0.0889)
		(layer "In9.Cu")
		(net "P3E_CPU1_PE3_MP_RXN<0>")
	)
	(arc
		(start 131.149598 -89.784936)
		(mid 131.009519 -89.927672)
		(end 130.817874 -89.984834)
		(width 0.0889)
		(layer "In9.Cu")
		(net "P3E_CPU1_PE3_MP_RXN<0>")
	)
	(arc
		(start 131.639818 -89.489788)
		(mid 131.356601 -89.574069)
		(end 131.149598 -89.784936)
		(width 0.0889)
		(layer "In9.Cu")
		(net "P3E_CPU1_PE3_MP_RXN<0>")
	)
	(arc
		(start 125.133608 -98.215704)
		(mid 125.06081 -98.506467)
		(end 125.139958 -98.795586)
		(width 0.0889)
		(layer "In9.Cu")
		(net "P3E_CPU1_PE3_MP_RXN<0>")
	)
	(arc
		(start 125.133608 -96.234504)
		(mid 125.06081 -96.525267)
		(end 125.139958 -96.814386)
		(width 0.0889)
		(layer "In9.Cu")
		(net "P3E_CPU1_PE3_MP_RXN<0>")
	)
	(arc
		(start 126.856998 -92.261436)
		(mid 126.715315 -92.40524)
		(end 126.521464 -92.461588)
		(width 0.0889)
		(layer "In9.Cu")
		(net "P3E_CPU1_PE3_MP_RXN<0>")
	)
	(arc
		(start 128.574038 -91.270836)
		(mid 128.432355 -91.41464)
		(end 128.238504 -91.470988)
		(width 0.0889)
		(layer "In9.Cu")
		(net "P3E_CPU1_PE3_MP_RXN<0>")
	)
	(arc
		(start 133.367018 -89.489788)
		(mid 133.173168 -89.433438)
		(end 133.031484 -89.289636)
		(width 0.0889)
		(layer "In9.Cu")
		(net "P3E_CPU1_PE3_MP_RXN<0>")
	)
	(arc
		(start 125.139958 -94.833186)
		(mid 125.193457 -95.033084)
		(end 125.139958 -95.232982)
		(width 0.0889)
		(layer "In9.Cu")
		(net "P3E_CPU1_PE3_MP_RXN<0>")
	)
	(arc
		(start 125.139958 -94.242636)
		(mid 125.060736 -94.531754)
		(end 125.133608 -94.822518)
		(width 0.0889)
		(layer "In9.Cu")
		(net "P3E_CPU1_PE3_MP_RXN<0>")
	)
	(arc
		(start 125.139958 -96.814386)
		(mid 125.193428 -97.009449)
		(end 125.144784 -97.2058)
		(width 0.0889)
		(layer "In9.Cu")
		(net "P3E_CPU1_PE3_MP_RXN<0>")
	)
	(arc
		(start 133.890004 -89.784936)
		(mid 133.683 -89.574072)
		(end 133.399784 -89.489788)
		(width 0.0889)
		(layer "In9.Cu")
		(net "P3E_CPU1_PE3_MP_RXN<0>")
	)
	(arc
		(start 137.158984 -90.280236)
		(mid 137.017301 -90.42404)
		(end 136.82345 -90.480388)
		(width 0.0889)
		(layer "In9.Cu")
		(net "P3E_CPU1_PE3_MP_RXN<0>")
	)
	(arc
		(start 136.300464 -90.775536)
		(mid 136.160385 -90.918272)
		(end 135.96874 -90.975434)
		(width 0.0889)
		(layer "In9.Cu")
		(net "P3E_CPU1_PE3_MP_RXN<0>")
	)
	(arc
		(start 140.224764 -90.480388)
		(mid 139.941547 -90.564669)
		(end 139.734544 -90.775536)
		(width 0.0889)
		(layer "In9.Cu")
		(net "P3E_CPU1_PE3_MP_RXN<0>")
	)
	(arc
		(start 128.245362 -100.576888)
		(mid 128.41 -100.620721)
		(end 128.541526 -100.729034)
		(width 0.0889)
		(layer "In9.Cu")
		(net "P3E_CPU1_PE3_MP_RXN<0>")
	)
	(arc
		(start 125.139958 -98.795586)
		(mid 125.193428 -98.990649)
		(end 125.144784 -99.187)
		(width 0.0889)
		(layer "In9.Cu")
		(net "P3E_CPU1_PE3_MP_RXN<0>")
	)
	(arc
		(start 125.662944 -100.081588)
		(mid 125.856794 -100.137938)
		(end 125.998478 -100.28174)
		(width 0.0889)
		(layer "In9.Cu")
		(net "P3E_CPU1_PE3_MP_RXN<0>")
	)
	(arc
		(start 139.734544 -90.775536)
		(mid 139.594465 -90.918272)
		(end 139.40282 -90.975434)
		(width 0.0889)
		(layer "In9.Cu")
		(net "P3E_CPU1_PE3_MP_RXN<0>")
	)
	(arc
		(start 138.182604 -90.280236)
		(mid 137.973996 -90.068304)
		(end 137.688574 -89.984834)
		(width 0.0889)
		(layer "In9.Cu")
		(net "P3E_CPU1_PE3_MP_RXN<0>")
	)
	(arc
		(start 125.133608 -99.206304)
		(mid 125.139785 -99.786236)
		(end 125.638814 -100.081588)
		(width 0.0889)
		(layer "In9.Cu")
		(net "P3E_CPU1_PE3_MP_RXN<0>")
	)
	(arc
		(start 130.291078 -90.280236)
		(mid 130.149395 -90.42404)
		(end 129.955544 -90.480388)
		(width 0.0889)
		(layer "In9.Cu")
		(net "P3E_CPU1_PE3_MP_RXN<0>")
	)
	(arc
		(start 132.004562 -89.295478)
		(mid 131.858596 -89.437877)
		(end 131.661408 -89.489788)
		(width 0.0889)
		(layer "In9.Cu")
		(net "P3E_CPU1_PE3_MP_RXN<0>")
	)
	(arc
		(start 127.880618 -100.776786)
		(mid 128.019362 -100.634753)
		(end 128.209294 -100.576888)
		(width 0.0889)
		(layer "In9.Cu")
		(net "P3E_CPU1_PE3_MP_RXN<0>")
	)
	(arc
		(start 125.139958 -95.823786)
		(mid 125.193428 -96.018849)
		(end 125.144784 -96.2152)
		(width 0.0889)
		(layer "In9.Cu")
		(net "P3E_CPU1_PE3_MP_RXN<0>")
	)
	(segment
		(start 13.56995 -36.25215)
		(end 12.0269 -36.25215)
		(width 0.1143)
		(layer "F.Cu")
		(net "P3E_CPU1_PE3_MP_C_TXP<7>")
	)
	(segment
		(start 11.9126 -36.36645)
		(end 11.9126 -36.7665)
		(width 0.1143)
		(layer "F.Cu")
		(net "P3E_CPU1_PE3_MP_C_TXP<7>")
	)
	(segment
		(start 12.0269 -36.25215)
		(end 11.9126 -36.36645)
		(width 0.1143)
		(layer "F.Cu")
		(net "P3E_CPU1_PE3_MP_C_TXP<7>")
	)
	(segment
		(start 13.8938 -36.576)
		(end 13.56995 -36.25215)
		(width 0.1143)
		(layer "F.Cu")
		(net "P3E_CPU1_PE3_MP_C_TXP<7>")
	)
	(via
		(at 11.9126 -36.7665)
		(size 0.508)
		(drill 0.254)
		(layers "F.Cu" "B.Cu")
		(net "P3E_CPU1_PE3_MP_C_TXP<7>")
	)
	(segment
		(start 11.9126 -36.4744)
		(end 11.9126 -36.7665)
		(width 0.1143)
		(layer "In11.Cu")
		(net "P3E_CPU1_PE3_MP_C_TXP<7>")
	)
	(segment
		(start 6.307582 -30.29585)
		(end 6.944106 -30.932374)
		(width 0.1143)
		(layer "In11.Cu")
		(net "P3E_CPU1_PE3_MP_C_TXP<7>")
	)
	(segment
		(start 6.944106 -30.932374)
		(end 7.811516 -30.932374)
		(width 0.1143)
		(layer "In11.Cu")
		(net "P3E_CPU1_PE3_MP_C_TXP<7>")
	)
	(segment
		(start 6.307582 -29.853382)
		(end 6.307582 -30.29585)
		(width 0.1143)
		(layer "In11.Cu")
		(net "P3E_CPU1_PE3_MP_C_TXP<7>")
	)
	(segment
		(start 9.8552 -35.668204)
		(end 10.503916 -36.31692)
		(width 0.1143)
		(layer "In11.Cu")
		(net "P3E_CPU1_PE3_MP_C_TXP<7>")
	)
	(segment
		(start 6.164326 -29.710126)
		(end 6.307582 -29.853382)
		(width 0.1143)
		(layer "In11.Cu")
		(net "P3E_CPU1_PE3_MP_C_TXP<7>")
	)
	(segment
		(start 9.8552 -34.041588)
		(end 9.8552 -35.668204)
		(width 0.1143)
		(layer "In11.Cu")
		(net "P3E_CPU1_PE3_MP_C_TXP<7>")
	)
	(segment
		(start 8.279384 -32.465772)
		(end 9.8552 -34.041588)
		(width 0.1143)
		(layer "In11.Cu")
		(net "P3E_CPU1_PE3_MP_C_TXP<7>")
	)
	(segment
		(start 7.811516 -30.932374)
		(end 8.279384 -31.400242)
		(width 0.1143)
		(layer "In11.Cu")
		(net "P3E_CPU1_PE3_MP_C_TXP<7>")
	)
	(segment
		(start 10.503916 -36.31692)
		(end 11.75512 -36.31692)
		(width 0.1143)
		(layer "In11.Cu")
		(net "P3E_CPU1_PE3_MP_C_TXP<7>")
	)
	(segment
		(start 11.75512 -36.31692)
		(end 11.9126 -36.4744)
		(width 0.1143)
		(layer "In11.Cu")
		(net "P3E_CPU1_PE3_MP_C_TXP<7>")
	)
	(segment
		(start 8.279384 -31.400242)
		(end 8.279384 -32.465772)
		(width 0.1143)
		(layer "In11.Cu")
		(net "P3E_CPU1_PE3_MP_C_TXP<7>")
	)
	(segment
		(start 5.80009 -29.710126)
		(end 6.164326 -29.710126)
		(width 0.1143)
		(layer "In11.Cu")
		(net "P3E_CPU1_PE3_MP_C_TXP<7>")
	)
	(segment
		(start 13.8938 -33.909)
		(end 13.56995 -34.23285)
		(width 0.1143)
		(layer "F.Cu")
		(net "P3E_CPU1_PE3_MP_C_TXP<6>")
	)
	(segment
		(start 13.212826 -34.23285)
		(end 13.098526 -34.11855)
		(width 0.1143)
		(layer "F.Cu")
		(net "P3E_CPU1_PE3_MP_C_TXP<6>")
	)
	(segment
		(start 13.098526 -34.11855)
		(end 13.098526 -33.7185)
		(width 0.1143)
		(layer "F.Cu")
		(net "P3E_CPU1_PE3_MP_C_TXP<6>")
	)
	(segment
		(start 13.56995 -34.23285)
		(end 13.212826 -34.23285)
		(width 0.1143)
		(layer "F.Cu")
		(net "P3E_CPU1_PE3_MP_C_TXP<6>")
	)
	(via
		(at 13.098526 -33.7185)
		(size 0.508)
		(drill 0.254)
		(layers "F.Cu" "B.Cu")
		(net "P3E_CPU1_PE3_MP_C_TXP<6>")
	)
	(segment
		(start 10.315956 -33.34258)
		(end 10.558272 -33.584896)
		(width 0.1143)
		(layer "B.Cu")
		(net "P3E_CPU1_PE3_MP_C_TXP<6>")
	)
	(segment
		(start 9.022842 -31.887668)
		(end 9.022842 -32.049466)
		(width 0.1143)
		(layer "B.Cu")
		(net "P3E_CPU1_PE3_MP_C_TXP<6>")
	)
	(segment
		(start 7.56285 -30.589474)
		(end 8.618728 -31.645352)
		(width 0.1143)
		(layer "B.Cu")
		(net "P3E_CPU1_PE3_MP_C_TXP<6>")
	)
	(segment
		(start 12.935966 -34.23158)
		(end 13.098526 -34.06902)
		(width 0.1143)
		(layer "B.Cu")
		(net "P3E_CPU1_PE3_MP_C_TXP<6>")
	)
	(segment
		(start 2.585466 -29.710126)
		(end 2.41681 -29.878782)
		(width 0.1143)
		(layer "B.Cu")
		(net "P3E_CPU1_PE3_MP_C_TXP<6>")
	)
	(segment
		(start 2.41681 -29.878782)
		(end 2.41681 -30.22981)
		(width 0.1143)
		(layer "B.Cu")
		(net "P3E_CPU1_PE3_MP_C_TXP<6>")
	)
	(segment
		(start 13.098526 -34.06902)
		(end 13.098526 -33.7185)
		(width 0.1143)
		(layer "B.Cu")
		(net "P3E_CPU1_PE3_MP_C_TXP<6>")
	)
	(segment
		(start 10.315956 -33.180782)
		(end 10.315956 -33.34258)
		(width 0.1143)
		(layer "B.Cu")
		(net "P3E_CPU1_PE3_MP_C_TXP<6>")
	)
	(segment
		(start 10.558272 -33.584896)
		(end 10.72007 -33.584896)
		(width 0.1143)
		(layer "B.Cu")
		(net "P3E_CPU1_PE3_MP_C_TXP<6>")
	)
	(segment
		(start 2.41681 -30.22981)
		(end 2.776474 -30.589474)
		(width 0.1143)
		(layer "B.Cu")
		(net "P3E_CPU1_PE3_MP_C_TXP<6>")
	)
	(segment
		(start 2.776474 -30.589474)
		(end 7.56285 -30.589474)
		(width 0.1143)
		(layer "B.Cu")
		(net "P3E_CPU1_PE3_MP_C_TXP<6>")
	)
	(segment
		(start 10.962386 -33.98901)
		(end 11.204956 -34.23158)
		(width 0.1143)
		(layer "B.Cu")
		(net "P3E_CPU1_PE3_MP_C_TXP<6>")
	)
	(segment
		(start 9.265158 -32.291782)
		(end 9.426956 -32.291782)
		(width 0.1143)
		(layer "B.Cu")
		(net "P3E_CPU1_PE3_MP_C_TXP<6>")
	)
	(segment
		(start 11.204956 -34.23158)
		(end 12.935966 -34.23158)
		(width 0.1143)
		(layer "B.Cu")
		(net "P3E_CPU1_PE3_MP_C_TXP<6>")
	)
	(segment
		(start 10.72007 -33.584896)
		(end 10.962386 -33.827466)
		(width 0.1143)
		(layer "B.Cu")
		(net "P3E_CPU1_PE3_MP_C_TXP<6>")
	)
	(segment
		(start 9.911842 -32.938466)
		(end 10.073386 -32.938466)
		(width 0.1143)
		(layer "B.Cu")
		(net "P3E_CPU1_PE3_MP_C_TXP<6>")
	)
	(segment
		(start 8.618728 -31.645352)
		(end 8.780272 -31.645352)
		(width 0.1143)
		(layer "B.Cu")
		(net "P3E_CPU1_PE3_MP_C_TXP<6>")
	)
	(segment
		(start 8.780272 -31.645352)
		(end 9.022842 -31.887668)
		(width 0.1143)
		(layer "B.Cu")
		(net "P3E_CPU1_PE3_MP_C_TXP<6>")
	)
	(segment
		(start 9.669272 -32.534352)
		(end 9.669272 -32.695896)
		(width 0.1143)
		(layer "B.Cu")
		(net "P3E_CPU1_PE3_MP_C_TXP<6>")
	)
	(segment
		(start 9.022842 -32.049466)
		(end 9.265158 -32.291782)
		(width 0.1143)
		(layer "B.Cu")
		(net "P3E_CPU1_PE3_MP_C_TXP<6>")
	)
	(segment
		(start 9.426956 -32.291782)
		(end 9.669272 -32.534352)
		(width 0.1143)
		(layer "B.Cu")
		(net "P3E_CPU1_PE3_MP_C_TXP<6>")
	)
	(segment
		(start 10.073386 -32.938466)
		(end 10.315956 -33.180782)
		(width 0.1143)
		(layer "B.Cu")
		(net "P3E_CPU1_PE3_MP_C_TXP<6>")
	)
	(segment
		(start 2.999994 -29.710126)
		(end 2.585466 -29.710126)
		(width 0.1143)
		(layer "B.Cu")
		(net "P3E_CPU1_PE3_MP_C_TXP<6>")
	)
	(segment
		(start 9.669272 -32.695896)
		(end 9.911842 -32.938466)
		(width 0.1143)
		(layer "B.Cu")
		(net "P3E_CPU1_PE3_MP_C_TXP<6>")
	)
	(segment
		(start 10.962386 -33.827466)
		(end 10.962386 -33.98901)
		(width 0.1143)
		(layer "B.Cu")
		(net "P3E_CPU1_PE3_MP_C_TXP<6>")
	)
	(segment
		(start 12.0269 -32.69615)
		(end 11.9126 -32.81045)
		(width 0.1143)
		(layer "F.Cu")
		(net "P3E_CPU1_PE3_MP_C_TXP<5>")
	)
	(segment
		(start 13.8938 -33.02)
		(end 13.56995 -32.69615)
		(width 0.1143)
		(layer "F.Cu")
		(net "P3E_CPU1_PE3_MP_C_TXP<5>")
	)
	(segment
		(start 11.9126 -32.81045)
		(end 11.9126 -33.2105)
		(width 0.1143)
		(layer "F.Cu")
		(net "P3E_CPU1_PE3_MP_C_TXP<5>")
	)
	(segment
		(start 13.56995 -32.69615)
		(end 12.0269 -32.69615)
		(width 0.1143)
		(layer "F.Cu")
		(net "P3E_CPU1_PE3_MP_C_TXP<5>")
	)
	(via
		(at 11.9126 -33.2105)
		(size 0.508)
		(drill 0.254)
		(layers "F.Cu" "B.Cu")
		(net "P3E_CPU1_PE3_MP_C_TXP<5>")
	)
	(segment
		(start 4.900676 -27.71013)
		(end 5.02158 -27.831034)
		(width 0.1143)
		(layer "In11.Cu")
		(net "P3E_CPU1_PE3_MP_C_TXP<5>")
	)
	(segment
		(start 4.499864 -27.71013)
		(end 4.900676 -27.71013)
		(width 0.1143)
		(layer "In11.Cu")
		(net "P3E_CPU1_PE3_MP_C_TXP<5>")
	)
	(segment
		(start 8.782812 -28.856178)
		(end 9.230614 -29.30398)
		(width 0.1143)
		(layer "In11.Cu")
		(net "P3E_CPU1_PE3_MP_C_TXP<5>")
	)
	(segment
		(start 5.02158 -27.831034)
		(end 5.02158 -28.208224)
		(width 0.1143)
		(layer "In11.Cu")
		(net "P3E_CPU1_PE3_MP_C_TXP<5>")
	)
	(segment
		(start 10.896854 -32.7152)
		(end 11.72464 -32.7152)
		(width 0.1143)
		(layer "In11.Cu")
		(net "P3E_CPU1_PE3_MP_C_TXP<5>")
	)
	(segment
		(start 11.72464 -32.7152)
		(end 11.9126 -32.90316)
		(width 0.1143)
		(layer "In11.Cu")
		(net "P3E_CPU1_PE3_MP_C_TXP<5>")
	)
	(segment
		(start 5.02158 -28.208224)
		(end 5.669534 -28.856178)
		(width 0.1143)
		(layer "In11.Cu")
		(net "P3E_CPU1_PE3_MP_C_TXP<5>")
	)
	(segment
		(start 9.230614 -31.04896)
		(end 10.896854 -32.7152)
		(width 0.1143)
		(layer "In11.Cu")
		(net "P3E_CPU1_PE3_MP_C_TXP<5>")
	)
	(segment
		(start 5.669534 -28.856178)
		(end 8.782812 -28.856178)
		(width 0.1143)
		(layer "In11.Cu")
		(net "P3E_CPU1_PE3_MP_C_TXP<5>")
	)
	(segment
		(start 9.230614 -29.30398)
		(end 9.230614 -31.04896)
		(width 0.1143)
		(layer "In11.Cu")
		(net "P3E_CPU1_PE3_MP_C_TXP<5>")
	)
	(segment
		(start 11.9126 -32.90316)
		(end 11.9126 -33.2105)
		(width 0.1143)
		(layer "In11.Cu")
		(net "P3E_CPU1_PE3_MP_C_TXP<5>")
	)
	(segment
		(start 13.8938 -30.353)
		(end 13.56995 -30.67685)
		(width 0.1143)
		(layer "F.Cu")
		(net "P3E_CPU1_PE3_MP_C_TXP<4>")
	)
	(segment
		(start 13.56995 -30.67685)
		(end 13.212826 -30.67685)
		(width 0.1143)
		(layer "F.Cu")
		(net "P3E_CPU1_PE3_MP_C_TXP<4>")
	)
	(segment
		(start 13.098526 -30.56255)
		(end 13.098526 -30.1625)
		(width 0.1143)
		(layer "F.Cu")
		(net "P3E_CPU1_PE3_MP_C_TXP<4>")
	)
	(segment
		(start 13.212826 -30.67685)
		(end 13.098526 -30.56255)
		(width 0.1143)
		(layer "F.Cu")
		(net "P3E_CPU1_PE3_MP_C_TXP<4>")
	)
	(via
		(at 13.098526 -30.1625)
		(size 0.508)
		(drill 0.254)
		(layers "F.Cu" "B.Cu")
		(net "P3E_CPU1_PE3_MP_C_TXP<4>")
	)
	(segment
		(start 7.0104 -28.589478)
		(end 7.1247 -28.475178)
		(width 0.1143)
		(layer "B.Cu")
		(net "P3E_CPU1_PE3_MP_C_TXP<4>")
	)
	(segment
		(start 5.6388 -28.475178)
		(end 5.7531 -28.589478)
		(width 0.1143)
		(layer "B.Cu")
		(net "P3E_CPU1_PE3_MP_C_TXP<4>")
	)
	(segment
		(start 5.7531 -28.589478)
		(end 6.096 -28.589478)
		(width 0.1143)
		(layer "B.Cu")
		(net "P3E_CPU1_PE3_MP_C_TXP<4>")
	)
	(segment
		(start 1.394714 -27.71013)
		(end 1.194054 -27.91079)
		(width 0.1143)
		(layer "B.Cu")
		(net "P3E_CPU1_PE3_MP_C_TXP<4>")
	)
	(segment
		(start 8.4963 -28.589478)
		(end 8.8392 -28.589478)
		(width 0.1143)
		(layer "B.Cu")
		(net "P3E_CPU1_PE3_MP_C_TXP<4>")
	)
	(segment
		(start 1.449578 -28.589478)
		(end 5.1816 -28.589478)
		(width 0.1143)
		(layer "B.Cu")
		(net "P3E_CPU1_PE3_MP_C_TXP<4>")
	)
	(segment
		(start 5.1816 -28.589478)
		(end 5.2959 -28.475178)
		(width 0.1143)
		(layer "B.Cu")
		(net "P3E_CPU1_PE3_MP_C_TXP<4>")
	)
	(segment
		(start 10.677652 -30.266386)
		(end 10.677652 -30.42793)
		(width 0.1143)
		(layer "B.Cu")
		(net "P3E_CPU1_PE3_MP_C_TXP<4>")
	)
	(segment
		(start 10.677652 -30.42793)
		(end 10.920222 -30.6705)
		(width 0.1143)
		(layer "B.Cu")
		(net "P3E_CPU1_PE3_MP_C_TXP<4>")
	)
	(segment
		(start 10.435336 -30.023816)
		(end 10.677652 -30.266386)
		(width 0.1143)
		(layer "B.Cu")
		(net "P3E_CPU1_PE3_MP_C_TXP<4>")
	)
	(segment
		(start 8.8392 -28.589478)
		(end 9.627108 -29.377386)
		(width 0.1143)
		(layer "B.Cu")
		(net "P3E_CPU1_PE3_MP_C_TXP<4>")
	)
	(segment
		(start 8.0391 -28.475178)
		(end 8.382 -28.475178)
		(width 0.1143)
		(layer "B.Cu")
		(net "P3E_CPU1_PE3_MP_C_TXP<4>")
	)
	(segment
		(start 12.9159 -30.6705)
		(end 13.098526 -30.487874)
		(width 0.1143)
		(layer "B.Cu")
		(net "P3E_CPU1_PE3_MP_C_TXP<4>")
	)
	(segment
		(start 8.382 -28.475178)
		(end 8.4963 -28.589478)
		(width 0.1143)
		(layer "B.Cu")
		(net "P3E_CPU1_PE3_MP_C_TXP<4>")
	)
	(segment
		(start 6.6675 -28.589478)
		(end 7.0104 -28.589478)
		(width 0.1143)
		(layer "B.Cu")
		(net "P3E_CPU1_PE3_MP_C_TXP<4>")
	)
	(segment
		(start 9.788652 -29.377386)
		(end 10.031222 -29.619702)
		(width 0.1143)
		(layer "B.Cu")
		(net "P3E_CPU1_PE3_MP_C_TXP<4>")
	)
	(segment
		(start 6.5532 -28.475178)
		(end 6.6675 -28.589478)
		(width 0.1143)
		(layer "B.Cu")
		(net "P3E_CPU1_PE3_MP_C_TXP<4>")
	)
	(segment
		(start 6.096 -28.589478)
		(end 6.2103 -28.475178)
		(width 0.1143)
		(layer "B.Cu")
		(net "P3E_CPU1_PE3_MP_C_TXP<4>")
	)
	(segment
		(start 13.098526 -30.487874)
		(end 13.098526 -30.1625)
		(width 0.1143)
		(layer "B.Cu")
		(net "P3E_CPU1_PE3_MP_C_TXP<4>")
	)
	(segment
		(start 1.194054 -27.91079)
		(end 1.194054 -28.333954)
		(width 0.1143)
		(layer "B.Cu")
		(net "P3E_CPU1_PE3_MP_C_TXP<4>")
	)
	(segment
		(start 7.4676 -28.475178)
		(end 7.5819 -28.589478)
		(width 0.1143)
		(layer "B.Cu")
		(net "P3E_CPU1_PE3_MP_C_TXP<4>")
	)
	(segment
		(start 7.1247 -28.475178)
		(end 7.4676 -28.475178)
		(width 0.1143)
		(layer "B.Cu")
		(net "P3E_CPU1_PE3_MP_C_TXP<4>")
	)
	(segment
		(start 10.920222 -30.6705)
		(end 12.9159 -30.6705)
		(width 0.1143)
		(layer "B.Cu")
		(net "P3E_CPU1_PE3_MP_C_TXP<4>")
	)
	(segment
		(start 1.700022 -27.71013)
		(end 1.394714 -27.71013)
		(width 0.1143)
		(layer "B.Cu")
		(net "P3E_CPU1_PE3_MP_C_TXP<4>")
	)
	(segment
		(start 10.031222 -29.7815)
		(end 10.273538 -30.023816)
		(width 0.1143)
		(layer "B.Cu")
		(net "P3E_CPU1_PE3_MP_C_TXP<4>")
	)
	(segment
		(start 1.194054 -28.333954)
		(end 1.449578 -28.589478)
		(width 0.1143)
		(layer "B.Cu")
		(net "P3E_CPU1_PE3_MP_C_TXP<4>")
	)
	(segment
		(start 5.2959 -28.475178)
		(end 5.6388 -28.475178)
		(width 0.1143)
		(layer "B.Cu")
		(net "P3E_CPU1_PE3_MP_C_TXP<4>")
	)
	(segment
		(start 7.5819 -28.589478)
		(end 7.9248 -28.589478)
		(width 0.1143)
		(layer "B.Cu")
		(net "P3E_CPU1_PE3_MP_C_TXP<4>")
	)
	(segment
		(start 9.627108 -29.377386)
		(end 9.788652 -29.377386)
		(width 0.1143)
		(layer "B.Cu")
		(net "P3E_CPU1_PE3_MP_C_TXP<4>")
	)
	(segment
		(start 6.2103 -28.475178)
		(end 6.5532 -28.475178)
		(width 0.1143)
		(layer "B.Cu")
		(net "P3E_CPU1_PE3_MP_C_TXP<4>")
	)
	(segment
		(start 7.9248 -28.589478)
		(end 8.0391 -28.475178)
		(width 0.1143)
		(layer "B.Cu")
		(net "P3E_CPU1_PE3_MP_C_TXP<4>")
	)
	(segment
		(start 10.273538 -30.023816)
		(end 10.435336 -30.023816)
		(width 0.1143)
		(layer "B.Cu")
		(net "P3E_CPU1_PE3_MP_C_TXP<4>")
	)
	(segment
		(start 10.031222 -29.619702)
		(end 10.031222 -29.7815)
		(width 0.1143)
		(layer "B.Cu")
		(net "P3E_CPU1_PE3_MP_C_TXP<4>")
	)
	(segment
		(start 13.56995 -29.14015)
		(end 12.0269 -29.14015)
		(width 0.1143)
		(layer "F.Cu")
		(net "P3E_CPU1_PE3_MP_C_TXP<3>")
	)
	(segment
		(start 11.9126 -29.25445)
		(end 11.9126 -29.6545)
		(width 0.1143)
		(layer "F.Cu")
		(net "P3E_CPU1_PE3_MP_C_TXP<3>")
	)
	(segment
		(start 12.0269 -29.14015)
		(end 11.9126 -29.25445)
		(width 0.1143)
		(layer "F.Cu")
		(net "P3E_CPU1_PE3_MP_C_TXP<3>")
	)
	(segment
		(start 13.8938 -29.464)
		(end 13.56995 -29.14015)
		(width 0.1143)
		(layer "F.Cu")
		(net "P3E_CPU1_PE3_MP_C_TXP<3>")
	)
	(via
		(at 11.9126 -29.6545)
		(size 0.508)
		(drill 0.254)
		(layers "F.Cu" "B.Cu")
		(net "P3E_CPU1_PE3_MP_C_TXP<3>")
	)
	(segment
		(start 9.877806 -28.198318)
		(end 10.120376 -28.440888)
		(width 0.1143)
		(layer "In11.Cu")
		(net "P3E_CPU1_PE3_MP_C_TXP<3>")
	)
	(segment
		(start 8.683498 -27.00401)
		(end 8.683498 -27.237436)
		(width 0.1143)
		(layer "In11.Cu")
		(net "P3E_CPU1_PE3_MP_C_TXP<3>")
	)
	(segment
		(start -3.06324 -27.189684)
		(end -2.643378 -26.769822)
		(width 0.1143)
		(layer "In11.Cu")
		(net "P3E_CPU1_PE3_MP_C_TXP<3>")
	)
	(segment
		(start 9.40181 -27.722322)
		(end 9.40181 -27.955748)
		(width 0.1143)
		(layer "In11.Cu")
		(net "P3E_CPU1_PE3_MP_C_TXP<3>")
	)
	(segment
		(start -2.500122 -27.71013)
		(end -2.863596 -27.71013)
		(width 0.1143)
		(layer "In11.Cu")
		(net "P3E_CPU1_PE3_MP_C_TXP<3>")
	)
	(segment
		(start 8.925814 -27.480006)
		(end 9.159494 -27.480006)
		(width 0.1143)
		(layer "In11.Cu")
		(net "P3E_CPU1_PE3_MP_C_TXP<3>")
	)
	(segment
		(start 10.838688 -29.1592)
		(end 11.7856 -29.1592)
		(width 0.1143)
		(layer "In11.Cu")
		(net "P3E_CPU1_PE3_MP_C_TXP<3>")
	)
	(segment
		(start 9.64438 -28.198318)
		(end 9.877806 -28.198318)
		(width 0.1143)
		(layer "In11.Cu")
		(net "P3E_CPU1_PE3_MP_C_TXP<3>")
	)
	(segment
		(start 8.44931 -26.769822)
		(end 8.683498 -27.00401)
		(width 0.1143)
		(layer "In11.Cu")
		(net "P3E_CPU1_PE3_MP_C_TXP<3>")
	)
	(segment
		(start 9.159494 -27.480006)
		(end 9.40181 -27.722322)
		(width 0.1143)
		(layer "In11.Cu")
		(net "P3E_CPU1_PE3_MP_C_TXP<3>")
	)
	(segment
		(start -2.643378 -26.769822)
		(end 8.44931 -26.769822)
		(width 0.1143)
		(layer "In11.Cu")
		(net "P3E_CPU1_PE3_MP_C_TXP<3>")
	)
	(segment
		(start 10.362692 -28.91663)
		(end 10.596118 -28.91663)
		(width 0.1143)
		(layer "In11.Cu")
		(net "P3E_CPU1_PE3_MP_C_TXP<3>")
	)
	(segment
		(start -3.06324 -27.510486)
		(end -3.06324 -27.189684)
		(width 0.1143)
		(layer "In11.Cu")
		(net "P3E_CPU1_PE3_MP_C_TXP<3>")
	)
	(segment
		(start 10.596118 -28.91663)
		(end 10.838688 -29.1592)
		(width 0.1143)
		(layer "In11.Cu")
		(net "P3E_CPU1_PE3_MP_C_TXP<3>")
	)
	(segment
		(start 11.9126 -29.2862)
		(end 11.9126 -29.6545)
		(width 0.1143)
		(layer "In11.Cu")
		(net "P3E_CPU1_PE3_MP_C_TXP<3>")
	)
	(segment
		(start 8.683498 -27.237436)
		(end 8.925814 -27.480006)
		(width 0.1143)
		(layer "In11.Cu")
		(net "P3E_CPU1_PE3_MP_C_TXP<3>")
	)
	(segment
		(start 10.120376 -28.674314)
		(end 10.362692 -28.91663)
		(width 0.1143)
		(layer "In11.Cu")
		(net "P3E_CPU1_PE3_MP_C_TXP<3>")
	)
	(segment
		(start 10.120376 -28.440888)
		(end 10.120376 -28.674314)
		(width 0.1143)
		(layer "In11.Cu")
		(net "P3E_CPU1_PE3_MP_C_TXP<3>")
	)
	(segment
		(start 9.40181 -27.955748)
		(end 9.64438 -28.198318)
		(width 0.1143)
		(layer "In11.Cu")
		(net "P3E_CPU1_PE3_MP_C_TXP<3>")
	)
	(segment
		(start 11.7856 -29.1592)
		(end 11.9126 -29.2862)
		(width 0.1143)
		(layer "In11.Cu")
		(net "P3E_CPU1_PE3_MP_C_TXP<3>")
	)
	(segment
		(start -2.863596 -27.71013)
		(end -3.06324 -27.510486)
		(width 0.1143)
		(layer "In11.Cu")
		(net "P3E_CPU1_PE3_MP_C_TXP<3>")
	)
	(segment
		(start 13.587984 -27.380184)
		(end 13.14704 -27.380184)
		(width 0.1143)
		(layer "F.Cu")
		(net "P3E_CPU1_PE3_MP_C_TXP<2>")
	)
	(segment
		(start 13.8938 -27.686)
		(end 13.587984 -27.380184)
		(width 0.1143)
		(layer "F.Cu")
		(net "P3E_CPU1_PE3_MP_C_TXP<2>")
	)
	(segment
		(start 13.050774 -27.47645)
		(end 13.050774 -27.8765)
		(width 0.1143)
		(layer "F.Cu")
		(net "P3E_CPU1_PE3_MP_C_TXP<2>")
	)
	(segment
		(start 13.14704 -27.380184)
		(end 13.050774 -27.47645)
		(width 0.1143)
		(layer "F.Cu")
		(net "P3E_CPU1_PE3_MP_C_TXP<2>")
	)
	(via
		(at 13.050774 -27.8765)
		(size 0.508)
		(drill 0.254)
		(layers "F.Cu" "B.Cu")
		(net "P3E_CPU1_PE3_MP_C_TXP<2>")
	)
	(segment
		(start 11.004296 -27.15387)
		(end 11.237722 -27.15387)
		(width 0.1143)
		(layer "In11.Cu")
		(net "P3E_CPU1_PE3_MP_C_TXP<2>")
	)
	(segment
		(start 11.237722 -27.15387)
		(end 11.480292 -27.39644)
		(width 0.1143)
		(layer "In11.Cu")
		(net "P3E_CPU1_PE3_MP_C_TXP<2>")
	)
	(segment
		(start 13.050774 -27.554174)
		(end 13.050774 -27.8765)
		(width 0.1143)
		(layer "In11.Cu")
		(net "P3E_CPU1_PE3_MP_C_TXP<2>")
	)
	(segment
		(start 9.325102 -25.474676)
		(end 9.567418 -25.717246)
		(width 0.1143)
		(layer "In11.Cu")
		(net "P3E_CPU1_PE3_MP_C_TXP<2>")
	)
	(segment
		(start 10.76198 -26.911554)
		(end 11.004296 -27.15387)
		(width 0.1143)
		(layer "In11.Cu")
		(net "P3E_CPU1_PE3_MP_C_TXP<2>")
	)
	(segment
		(start 9.567418 -25.717246)
		(end 9.801098 -25.717246)
		(width 0.1143)
		(layer "In11.Cu")
		(net "P3E_CPU1_PE3_MP_C_TXP<2>")
	)
	(segment
		(start 10.76198 -26.678128)
		(end 10.76198 -26.911554)
		(width 0.1143)
		(layer "In11.Cu")
		(net "P3E_CPU1_PE3_MP_C_TXP<2>")
	)
	(segment
		(start 8.902192 -24.81834)
		(end 9.325102 -25.24125)
		(width 0.1143)
		(layer "In11.Cu")
		(net "P3E_CPU1_PE3_MP_C_TXP<2>")
	)
	(segment
		(start 10.51941 -26.435558)
		(end 10.76198 -26.678128)
		(width 0.1143)
		(layer "In11.Cu")
		(net "P3E_CPU1_PE3_MP_C_TXP<2>")
	)
	(segment
		(start 9.325102 -25.24125)
		(end 9.325102 -25.474676)
		(width 0.1143)
		(layer "In11.Cu")
		(net "P3E_CPU1_PE3_MP_C_TXP<2>")
	)
	(segment
		(start 10.043414 -26.192988)
		(end 10.285984 -26.435558)
		(width 0.1143)
		(layer "In11.Cu")
		(net "P3E_CPU1_PE3_MP_C_TXP<2>")
	)
	(segment
		(start 12.89304 -27.39644)
		(end 13.050774 -27.554174)
		(width 0.1143)
		(layer "In11.Cu")
		(net "P3E_CPU1_PE3_MP_C_TXP<2>")
	)
	(segment
		(start 11.480292 -27.39644)
		(end 12.89304 -27.39644)
		(width 0.1143)
		(layer "In11.Cu")
		(net "P3E_CPU1_PE3_MP_C_TXP<2>")
	)
	(segment
		(start 6.72846 -24.81834)
		(end 8.902192 -24.81834)
		(width 0.1143)
		(layer "In11.Cu")
		(net "P3E_CPU1_PE3_MP_C_TXP<2>")
	)
	(segment
		(start 9.801098 -25.717246)
		(end 10.043414 -25.959562)
		(width 0.1143)
		(layer "In11.Cu")
		(net "P3E_CPU1_PE3_MP_C_TXP<2>")
	)
	(segment
		(start 10.043414 -25.959562)
		(end 10.043414 -26.192988)
		(width 0.1143)
		(layer "In11.Cu")
		(net "P3E_CPU1_PE3_MP_C_TXP<2>")
	)
	(segment
		(start 10.285984 -26.435558)
		(end 10.51941 -26.435558)
		(width 0.1143)
		(layer "In11.Cu")
		(net "P3E_CPU1_PE3_MP_C_TXP<2>")
	)
	(segment
		(start 6.61416 -24.93264)
		(end 6.72846 -24.81834)
		(width 0.1143)
		(layer "In11.Cu")
		(net "P3E_CPU1_PE3_MP_C_TXP<2>")
	)
	(segment
		(start 6.61416 -25.41016)
		(end 6.61416 -24.93264)
		(width 0.1143)
		(layer "In11.Cu")
		(net "P3E_CPU1_PE3_MP_C_TXP<2>")
	)
	(segment
		(start 7.199884 -25.710134)
		(end 6.914134 -25.710134)
		(width 0.1143)
		(layer "In11.Cu")
		(net "P3E_CPU1_PE3_MP_C_TXP<2>")
	)
	(segment
		(start 6.914134 -25.710134)
		(end 6.61416 -25.41016)
		(width 0.1143)
		(layer "In11.Cu")
		(net "P3E_CPU1_PE3_MP_C_TXP<2>")
	)
	(segment
		(start 13.8938 -25.019)
		(end 13.56995 -25.34285)
		(width 0.1143)
		(layer "F.Cu")
		(net "P3E_CPU1_PE3_MP_C_TXP<1>")
	)
	(segment
		(start 11.9126 -25.22855)
		(end 11.9126 -24.8285)
		(width 0.1143)
		(layer "F.Cu")
		(net "P3E_CPU1_PE3_MP_C_TXP<1>")
	)
	(segment
		(start 12.0269 -25.34285)
		(end 11.9126 -25.22855)
		(width 0.1143)
		(layer "F.Cu")
		(net "P3E_CPU1_PE3_MP_C_TXP<1>")
	)
	(segment
		(start 13.56995 -25.34285)
		(end 12.0269 -25.34285)
		(width 0.1143)
		(layer "F.Cu")
		(net "P3E_CPU1_PE3_MP_C_TXP<1>")
	)
	(via
		(at 11.9126 -24.8285)
		(size 0.508)
		(drill 0.254)
		(layers "F.Cu" "B.Cu")
		(net "P3E_CPU1_PE3_MP_C_TXP<1>")
	)
	(segment
		(start 9.404604 -25.969976)
		(end 9.553956 -26.031698)
		(width 0.1143)
		(layer "B.Cu")
		(net "P3E_CPU1_PE3_MP_C_TXP<1>")
	)
	(segment
		(start 6.210554 -26.592276)
		(end 6.553454 -26.592276)
		(width 0.1143)
		(layer "B.Cu")
		(net "P3E_CPU1_PE3_MP_C_TXP<1>")
	)
	(segment
		(start 7.582154 -26.706576)
		(end 7.925054 -26.706576)
		(width 0.1143)
		(layer "B.Cu")
		(net "P3E_CPU1_PE3_MP_C_TXP<1>")
	)
	(segment
		(start 6.667754 -26.706576)
		(end 7.010654 -26.706576)
		(width 0.1143)
		(layer "B.Cu")
		(net "P3E_CPU1_PE3_MP_C_TXP<1>")
	)
	(segment
		(start 2.999994 -25.710134)
		(end 2.53492 -25.710134)
		(width 0.1143)
		(layer "B.Cu")
		(net "P3E_CPU1_PE3_MP_C_TXP<1>")
	)
	(segment
		(start 9.870694 -25.90038)
		(end 9.93267 -25.751028)
		(width 0.1143)
		(layer "B.Cu")
		(net "P3E_CPU1_PE3_MP_C_TXP<1>")
	)
	(segment
		(start 7.467854 -26.592276)
		(end 7.582154 -26.706576)
		(width 0.1143)
		(layer "B.Cu")
		(net "P3E_CPU1_PE3_MP_C_TXP<1>")
	)
	(segment
		(start 6.096254 -26.706576)
		(end 6.210554 -26.592276)
		(width 0.1143)
		(layer "B.Cu")
		(net "P3E_CPU1_PE3_MP_C_TXP<1>")
	)
	(segment
		(start 9.553956 -26.031698)
		(end 9.870694 -25.90038)
		(width 0.1143)
		(layer "B.Cu")
		(net "P3E_CPU1_PE3_MP_C_TXP<1>")
	)
	(segment
		(start 2.42062 -25.824434)
		(end 2.42062 -26.28392)
		(width 0.1143)
		(layer "B.Cu")
		(net "P3E_CPU1_PE3_MP_C_TXP<1>")
	)
	(segment
		(start 9.02589 -26.250392)
		(end 9.087866 -26.10104)
		(width 0.1143)
		(layer "B.Cu")
		(net "P3E_CPU1_PE3_MP_C_TXP<1>")
	)
	(segment
		(start 10.39876 -25.681686)
		(end 11.220196 -25.34158)
		(width 0.1143)
		(layer "B.Cu")
		(net "P3E_CPU1_PE3_MP_C_TXP<1>")
	)
	(segment
		(start 11.79957 -25.34158)
		(end 11.9126 -25.22855)
		(width 0.1143)
		(layer "B.Cu")
		(net "P3E_CPU1_PE3_MP_C_TXP<1>")
	)
	(segment
		(start 9.93267 -25.751028)
		(end 10.249408 -25.619964)
		(width 0.1143)
		(layer "B.Cu")
		(net "P3E_CPU1_PE3_MP_C_TXP<1>")
	)
	(segment
		(start 7.925054 -26.706576)
		(end 9.02589 -26.250392)
		(width 0.1143)
		(layer "B.Cu")
		(net "P3E_CPU1_PE3_MP_C_TXP<1>")
	)
	(segment
		(start 11.220196 -25.34158)
		(end 11.79957 -25.34158)
		(width 0.1143)
		(layer "B.Cu")
		(net "P3E_CPU1_PE3_MP_C_TXP<1>")
	)
	(segment
		(start 7.010654 -26.706576)
		(end 7.124954 -26.592276)
		(width 0.1143)
		(layer "B.Cu")
		(net "P3E_CPU1_PE3_MP_C_TXP<1>")
	)
	(segment
		(start 9.087866 -26.10104)
		(end 9.404604 -25.969976)
		(width 0.1143)
		(layer "B.Cu")
		(net "P3E_CPU1_PE3_MP_C_TXP<1>")
	)
	(segment
		(start 10.249408 -25.619964)
		(end 10.39876 -25.681686)
		(width 0.1143)
		(layer "B.Cu")
		(net "P3E_CPU1_PE3_MP_C_TXP<1>")
	)
	(segment
		(start 11.9126 -25.22855)
		(end 11.9126 -24.8285)
		(width 0.1143)
		(layer "B.Cu")
		(net "P3E_CPU1_PE3_MP_C_TXP<1>")
	)
	(segment
		(start 2.53492 -25.710134)
		(end 2.42062 -25.824434)
		(width 0.1143)
		(layer "B.Cu")
		(net "P3E_CPU1_PE3_MP_C_TXP<1>")
	)
	(segment
		(start 2.843276 -26.706576)
		(end 6.096254 -26.706576)
		(width 0.1143)
		(layer "B.Cu")
		(net "P3E_CPU1_PE3_MP_C_TXP<1>")
	)
	(segment
		(start 2.42062 -26.28392)
		(end 2.843276 -26.706576)
		(width 0.1143)
		(layer "B.Cu")
		(net "P3E_CPU1_PE3_MP_C_TXP<1>")
	)
	(segment
		(start 6.553454 -26.592276)
		(end 6.667754 -26.706576)
		(width 0.1143)
		(layer "B.Cu")
		(net "P3E_CPU1_PE3_MP_C_TXP<1>")
	)
	(segment
		(start 7.124954 -26.592276)
		(end 7.467854 -26.592276)
		(width 0.1143)
		(layer "B.Cu")
		(net "P3E_CPU1_PE3_MP_C_TXP<1>")
	)
	(segment
		(start 13.587984 -23.824184)
		(end 13.14704 -23.824184)
		(width 0.1143)
		(layer "F.Cu")
		(net "P3E_CPU1_PE3_MP_C_TXP<0>")
	)
	(segment
		(start 13.14704 -23.824184)
		(end 13.050774 -23.92045)
		(width 0.1143)
		(layer "F.Cu")
		(net "P3E_CPU1_PE3_MP_C_TXP<0>")
	)
	(segment
		(start 13.8938 -24.13)
		(end 13.587984 -23.824184)
		(width 0.1143)
		(layer "F.Cu")
		(net "P3E_CPU1_PE3_MP_C_TXP<0>")
	)
	(segment
		(start 13.050774 -23.92045)
		(end 13.050774 -24.3205)
		(width 0.1143)
		(layer "F.Cu")
		(net "P3E_CPU1_PE3_MP_C_TXP<0>")
	)
	(via
		(at 13.050774 -24.3205)
		(size 0.508)
		(drill 0.254)
		(layers "F.Cu" "B.Cu")
		(net "P3E_CPU1_PE3_MP_C_TXP<0>")
	)
	(segment
		(start -1.690116 -25.131522)
		(end -1.488694 -24.9301)
		(width 0.1143)
		(layer "B.Cu")
		(net "P3E_CPU1_PE3_MP_C_TXP<0>")
	)
	(segment
		(start 4.87299 -24.9301)
		(end 8.126476 -24.9301)
		(width 0.1143)
		(layer "B.Cu")
		(net "P3E_CPU1_PE3_MP_C_TXP<0>")
	)
	(segment
		(start 8.697976 -24.9301)
		(end 8.913876 -24.9301)
		(width 0.1143)
		(layer "B.Cu")
		(net "P3E_CPU1_PE3_MP_C_TXP<0>")
	)
	(segment
		(start 9.788906 -24.05507)
		(end 10.031476 -23.8125)
		(width 0.1143)
		(layer "B.Cu")
		(net "P3E_CPU1_PE3_MP_C_TXP<0>")
	)
	(segment
		(start 11.93419 -23.9268)
		(end 12.04849 -23.8125)
		(width 0.1143)
		(layer "B.Cu")
		(net "P3E_CPU1_PE3_MP_C_TXP<0>")
	)
	(segment
		(start 9.54659 -24.459184)
		(end 9.788906 -24.216614)
		(width 0.1143)
		(layer "B.Cu")
		(net "P3E_CPU1_PE3_MP_C_TXP<0>")
	)
	(segment
		(start 8.240776 -25.0444)
		(end 8.583676 -25.0444)
		(width 0.1143)
		(layer "B.Cu")
		(net "P3E_CPU1_PE3_MP_C_TXP<0>")
	)
	(segment
		(start -1.690116 -25.522428)
		(end -1.690116 -25.131522)
		(width 0.1143)
		(layer "B.Cu")
		(net "P3E_CPU1_PE3_MP_C_TXP<0>")
	)
	(segment
		(start 10.67689 -23.9268)
		(end 11.01979 -23.9268)
		(width 0.1143)
		(layer "B.Cu")
		(net "P3E_CPU1_PE3_MP_C_TXP<0>")
	)
	(segment
		(start 12.908534 -23.8125)
		(end 13.050774 -23.95474)
		(width 0.1143)
		(layer "B.Cu")
		(net "P3E_CPU1_PE3_MP_C_TXP<0>")
	)
	(segment
		(start 12.04849 -23.8125)
		(end 12.908534 -23.8125)
		(width 0.1143)
		(layer "B.Cu")
		(net "P3E_CPU1_PE3_MP_C_TXP<0>")
	)
	(segment
		(start 11.59129 -23.9268)
		(end 11.93419 -23.9268)
		(width 0.1143)
		(layer "B.Cu")
		(net "P3E_CPU1_PE3_MP_C_TXP<0>")
	)
	(segment
		(start 9.788906 -24.216614)
		(end 9.788906 -24.05507)
		(width 0.1143)
		(layer "B.Cu")
		(net "P3E_CPU1_PE3_MP_C_TXP<0>")
	)
	(segment
		(start 11.47699 -23.8125)
		(end 11.59129 -23.9268)
		(width 0.1143)
		(layer "B.Cu")
		(net "P3E_CPU1_PE3_MP_C_TXP<0>")
	)
	(segment
		(start 4.30149 -24.9301)
		(end 4.41579 -25.0444)
		(width 0.1143)
		(layer "B.Cu")
		(net "P3E_CPU1_PE3_MP_C_TXP<0>")
	)
	(segment
		(start 13.050774 -23.95474)
		(end 13.050774 -24.3205)
		(width 0.1143)
		(layer "B.Cu")
		(net "P3E_CPU1_PE3_MP_C_TXP<0>")
	)
	(segment
		(start 0.543052 -24.9301)
		(end 4.30149 -24.9301)
		(width 0.1143)
		(layer "B.Cu")
		(net "P3E_CPU1_PE3_MP_C_TXP<0>")
	)
	(segment
		(start -1.20015 -25.710134)
		(end -1.50241 -25.710134)
		(width 0.1143)
		(layer "B.Cu")
		(net "P3E_CPU1_PE3_MP_C_TXP<0>")
	)
	(segment
		(start 9.384792 -24.459184)
		(end 9.54659 -24.459184)
		(width 0.1143)
		(layer "B.Cu")
		(net "P3E_CPU1_PE3_MP_C_TXP<0>")
	)
	(segment
		(start 8.126476 -24.9301)
		(end 8.240776 -25.0444)
		(width 0.1143)
		(layer "B.Cu")
		(net "P3E_CPU1_PE3_MP_C_TXP<0>")
	)
	(segment
		(start 0.428752 -25.0444)
		(end 0.543052 -24.9301)
		(width 0.1143)
		(layer "B.Cu")
		(net "P3E_CPU1_PE3_MP_C_TXP<0>")
	)
	(segment
		(start 11.01979 -23.9268)
		(end 11.13409 -23.8125)
		(width 0.1143)
		(layer "B.Cu")
		(net "P3E_CPU1_PE3_MP_C_TXP<0>")
	)
	(segment
		(start 0.085852 -25.0444)
		(end 0.428752 -25.0444)
		(width 0.1143)
		(layer "B.Cu")
		(net "P3E_CPU1_PE3_MP_C_TXP<0>")
	)
	(segment
		(start -1.488694 -24.9301)
		(end -0.028448 -24.9301)
		(width 0.1143)
		(layer "B.Cu")
		(net "P3E_CPU1_PE3_MP_C_TXP<0>")
	)
	(segment
		(start 4.41579 -25.0444)
		(end 4.75869 -25.0444)
		(width 0.1143)
		(layer "B.Cu")
		(net "P3E_CPU1_PE3_MP_C_TXP<0>")
	)
	(segment
		(start 11.13409 -23.8125)
		(end 11.47699 -23.8125)
		(width 0.1143)
		(layer "B.Cu")
		(net "P3E_CPU1_PE3_MP_C_TXP<0>")
	)
	(segment
		(start 4.75869 -25.0444)
		(end 4.87299 -24.9301)
		(width 0.1143)
		(layer "B.Cu")
		(net "P3E_CPU1_PE3_MP_C_TXP<0>")
	)
	(segment
		(start 8.913876 -24.9301)
		(end 9.384792 -24.459184)
		(width 0.1143)
		(layer "B.Cu")
		(net "P3E_CPU1_PE3_MP_C_TXP<0>")
	)
	(segment
		(start 8.583676 -25.0444)
		(end 8.697976 -24.9301)
		(width 0.1143)
		(layer "B.Cu")
		(net "P3E_CPU1_PE3_MP_C_TXP<0>")
	)
	(segment
		(start 10.56259 -23.8125)
		(end 10.67689 -23.9268)
		(width 0.1143)
		(layer "B.Cu")
		(net "P3E_CPU1_PE3_MP_C_TXP<0>")
	)
	(segment
		(start -1.50241 -25.710134)
		(end -1.690116 -25.522428)
		(width 0.1143)
		(layer "B.Cu")
		(net "P3E_CPU1_PE3_MP_C_TXP<0>")
	)
	(segment
		(start -0.028448 -24.9301)
		(end 0.085852 -25.0444)
		(width 0.1143)
		(layer "B.Cu")
		(net "P3E_CPU1_PE3_MP_C_TXP<0>")
	)
	(segment
		(start 10.031476 -23.8125)
		(end 10.56259 -23.8125)
		(width 0.1143)
		(layer "B.Cu")
		(net "P3E_CPU1_PE3_MP_C_TXP<0>")
	)
	(segment
		(start 12.0269 -36.01085)
		(end 11.9126 -35.89655)
		(width 0.1143)
		(layer "F.Cu")
		(net "P3E_CPU1_PE3_MP_C_TXN<7>")
	)
	(segment
		(start 13.8938 -35.687)
		(end 13.56995 -36.01085)
		(width 0.1143)
		(layer "F.Cu")
		(net "P3E_CPU1_PE3_MP_C_TXN<7>")
	)
	(segment
		(start 11.9126 -35.89655)
		(end 11.9126 -35.4965)
		(width 0.1143)
		(layer "F.Cu")
		(net "P3E_CPU1_PE3_MP_C_TXN<7>")
	)
	(segment
		(start 13.56995 -36.01085)
		(end 12.0269 -36.01085)
		(width 0.1143)
		(layer "F.Cu")
		(net "P3E_CPU1_PE3_MP_C_TXN<7>")
	)
	(via
		(at 11.9126 -35.4965)
		(size 0.508)
		(drill 0.254)
		(layers "F.Cu" "B.Cu")
		(net "P3E_CPU1_PE3_MP_C_TXN<7>")
	)
	(segment
		(start 10.1473 -33.92043)
		(end 10.1473 -34.26333)
		(width 0.1143)
		(layer "In11.Cu")
		(net "P3E_CPU1_PE3_MP_C_TXN<7>")
	)
	(segment
		(start 11.754104 -36.02482)
		(end 11.9126 -35.866324)
		(width 0.1143)
		(layer "In11.Cu")
		(net "P3E_CPU1_PE3_MP_C_TXN<7>")
	)
	(segment
		(start 6.840474 -29.710126)
		(end 6.599682 -29.950918)
		(width 0.1143)
		(layer "In11.Cu")
		(net "P3E_CPU1_PE3_MP_C_TXN<7>")
	)
	(segment
		(start 8.571484 -32.344614)
		(end 8.814054 -32.587184)
		(width 0.1143)
		(layer "In11.Cu")
		(net "P3E_CPU1_PE3_MP_C_TXN<7>")
	)
	(segment
		(start 6.599682 -29.950918)
		(end 6.599682 -30.174692)
		(width 0.1143)
		(layer "In11.Cu")
		(net "P3E_CPU1_PE3_MP_C_TXN<7>")
	)
	(segment
		(start 10.3124 -34.77133)
		(end 10.1473 -34.93643)
		(width 0.1143)
		(layer "In11.Cu")
		(net "P3E_CPU1_PE3_MP_C_TXN<7>")
	)
	(segment
		(start 10.1473 -35.547046)
		(end 10.625074 -36.02482)
		(width 0.1143)
		(layer "In11.Cu")
		(net "P3E_CPU1_PE3_MP_C_TXN<7>")
	)
	(segment
		(start 10.625074 -36.02482)
		(end 11.754104 -36.02482)
		(width 0.1143)
		(layer "In11.Cu")
		(net "P3E_CPU1_PE3_MP_C_TXN<7>")
	)
	(segment
		(start 9.04748 -32.587184)
		(end 9.289796 -32.8295)
		(width 0.1143)
		(layer "In11.Cu")
		(net "P3E_CPU1_PE3_MP_C_TXN<7>")
	)
	(segment
		(start 10.1473 -34.26333)
		(end 10.3124 -34.42843)
		(width 0.1143)
		(layer "In11.Cu")
		(net "P3E_CPU1_PE3_MP_C_TXN<7>")
	)
	(segment
		(start 8.814054 -32.587184)
		(end 9.04748 -32.587184)
		(width 0.1143)
		(layer "In11.Cu")
		(net "P3E_CPU1_PE3_MP_C_TXN<7>")
	)
	(segment
		(start 7.932674 -30.640274)
		(end 8.571484 -31.279084)
		(width 0.1143)
		(layer "In11.Cu")
		(net "P3E_CPU1_PE3_MP_C_TXN<7>")
	)
	(segment
		(start 6.599682 -30.174692)
		(end 7.065264 -30.640274)
		(width 0.1143)
		(layer "In11.Cu")
		(net "P3E_CPU1_PE3_MP_C_TXN<7>")
	)
	(segment
		(start 10.1473 -34.93643)
		(end 10.1473 -35.547046)
		(width 0.1143)
		(layer "In11.Cu")
		(net "P3E_CPU1_PE3_MP_C_TXN<7>")
	)
	(segment
		(start 7.065264 -30.640274)
		(end 7.932674 -30.640274)
		(width 0.1143)
		(layer "In11.Cu")
		(net "P3E_CPU1_PE3_MP_C_TXN<7>")
	)
	(segment
		(start 11.9126 -35.866324)
		(end 11.9126 -35.4965)
		(width 0.1143)
		(layer "In11.Cu")
		(net "P3E_CPU1_PE3_MP_C_TXN<7>")
	)
	(segment
		(start 8.571484 -31.279084)
		(end 8.571484 -32.344614)
		(width 0.1143)
		(layer "In11.Cu")
		(net "P3E_CPU1_PE3_MP_C_TXN<7>")
	)
	(segment
		(start 9.289796 -32.8295)
		(end 9.289796 -33.062926)
		(width 0.1143)
		(layer "In11.Cu")
		(net "P3E_CPU1_PE3_MP_C_TXN<7>")
	)
	(segment
		(start 9.289796 -33.062926)
		(end 10.1473 -33.92043)
		(width 0.1143)
		(layer "In11.Cu")
		(net "P3E_CPU1_PE3_MP_C_TXN<7>")
	)
	(segment
		(start 10.3124 -34.42843)
		(end 10.3124 -34.77133)
		(width 0.1143)
		(layer "In11.Cu")
		(net "P3E_CPU1_PE3_MP_C_TXN<7>")
	)
	(segment
		(start 7.199884 -29.710126)
		(end 6.840474 -29.710126)
		(width 0.1143)
		(layer "In11.Cu")
		(net "P3E_CPU1_PE3_MP_C_TXN<7>")
	)
	(segment
		(start 13.56995 -34.47415)
		(end 13.212826 -34.47415)
		(width 0.1143)
		(layer "F.Cu")
		(net "P3E_CPU1_PE3_MP_C_TXN<6>")
	)
	(segment
		(start 13.098526 -34.58845)
		(end 13.098526 -34.9885)
		(width 0.1143)
		(layer "F.Cu")
		(net "P3E_CPU1_PE3_MP_C_TXN<6>")
	)
	(segment
		(start 13.8938 -34.798)
		(end 13.56995 -34.47415)
		(width 0.1143)
		(layer "F.Cu")
		(net "P3E_CPU1_PE3_MP_C_TXN<6>")
	)
	(segment
		(start 13.212826 -34.47415)
		(end 13.098526 -34.58845)
		(width 0.1143)
		(layer "F.Cu")
		(net "P3E_CPU1_PE3_MP_C_TXN<6>")
	)
	(via
		(at 13.098526 -34.9885)
		(size 0.508)
		(drill 0.254)
		(layers "F.Cu" "B.Cu")
		(net "P3E_CPU1_PE3_MP_C_TXN<6>")
	)
	(segment
		(start 2.676398 -30.830774)
		(end 7.462774 -30.830774)
		(width 0.1143)
		(layer "B.Cu")
		(net "P3E_CPU1_PE3_MP_C_TXN<6>")
	)
	(segment
		(start 2.022856 -29.710126)
		(end 2.17551 -29.86278)
		(width 0.1143)
		(layer "B.Cu")
		(net "P3E_CPU1_PE3_MP_C_TXN<6>")
	)
	(segment
		(start 1.599946 -29.710126)
		(end 2.022856 -29.710126)
		(width 0.1143)
		(layer "B.Cu")
		(net "P3E_CPU1_PE3_MP_C_TXN<6>")
	)
	(segment
		(start 2.17551 -30.329886)
		(end 2.676398 -30.830774)
		(width 0.1143)
		(layer "B.Cu")
		(net "P3E_CPU1_PE3_MP_C_TXN<6>")
	)
	(segment
		(start 13.098526 -34.614612)
		(end 13.098526 -34.9885)
		(width 0.1143)
		(layer "B.Cu")
		(net "P3E_CPU1_PE3_MP_C_TXN<6>")
	)
	(segment
		(start 2.17551 -29.86278)
		(end 2.17551 -30.329886)
		(width 0.1143)
		(layer "B.Cu")
		(net "P3E_CPU1_PE3_MP_C_TXN<6>")
	)
	(segment
		(start 12.956794 -34.47288)
		(end 13.098526 -34.614612)
		(width 0.1143)
		(layer "B.Cu")
		(net "P3E_CPU1_PE3_MP_C_TXN<6>")
	)
	(segment
		(start 11.10488 -34.47288)
		(end 12.956794 -34.47288)
		(width 0.1143)
		(layer "B.Cu")
		(net "P3E_CPU1_PE3_MP_C_TXN<6>")
	)
	(segment
		(start 7.462774 -30.830774)
		(end 11.10488 -34.47288)
		(width 0.1143)
		(layer "B.Cu")
		(net "P3E_CPU1_PE3_MP_C_TXN<6>")
	)
	(segment
		(start 11.9126 -32.34055)
		(end 11.9126 -31.9405)
		(width 0.1143)
		(layer "F.Cu")
		(net "P3E_CPU1_PE3_MP_C_TXN<5>")
	)
	(segment
		(start 12.0269 -32.45485)
		(end 11.9126 -32.34055)
		(width 0.1143)
		(layer "F.Cu")
		(net "P3E_CPU1_PE3_MP_C_TXN<5>")
	)
	(segment
		(start 13.8938 -32.131)
		(end 13.56995 -32.45485)
		(width 0.1143)
		(layer "F.Cu")
		(net "P3E_CPU1_PE3_MP_C_TXN<5>")
	)
	(segment
		(start 13.56995 -32.45485)
		(end 12.0269 -32.45485)
		(width 0.1143)
		(layer "F.Cu")
		(net "P3E_CPU1_PE3_MP_C_TXN<5>")
	)
	(via
		(at 11.9126 -31.9405)
		(size 0.508)
		(drill 0.254)
		(layers "F.Cu" "B.Cu")
		(net "P3E_CPU1_PE3_MP_C_TXN<5>")
	)
	(segment
		(start 8.90397 -28.564078)
		(end 9.522714 -29.182822)
		(width 0.1143)
		(layer "In11.Cu")
		(net "P3E_CPU1_PE3_MP_C_TXN<5>")
	)
	(segment
		(start 9.522714 -29.182822)
		(end 9.522714 -29.911802)
		(width 0.1143)
		(layer "In11.Cu")
		(net "P3E_CPU1_PE3_MP_C_TXN<5>")
	)
	(segment
		(start 11.018012 -32.4231)
		(end 11.7221 -32.4231)
		(width 0.1143)
		(layer "In11.Cu")
		(net "P3E_CPU1_PE3_MP_C_TXN<5>")
	)
	(segment
		(start 5.43687 -27.71013)
		(end 5.31368 -27.83332)
		(width 0.1143)
		(layer "In11.Cu")
		(net "P3E_CPU1_PE3_MP_C_TXN<5>")
	)
	(segment
		(start 5.790692 -28.564078)
		(end 7.88797 -28.564078)
		(width 0.1143)
		(layer "In11.Cu")
		(net "P3E_CPU1_PE3_MP_C_TXN<5>")
	)
	(segment
		(start 10.533126 -31.704788)
		(end 10.775442 -31.947104)
		(width 0.1143)
		(layer "In11.Cu")
		(net "P3E_CPU1_PE3_MP_C_TXN<5>")
	)
	(segment
		(start 8.56107 -28.564078)
		(end 8.90397 -28.564078)
		(width 0.1143)
		(layer "In11.Cu")
		(net "P3E_CPU1_PE3_MP_C_TXN<5>")
	)
	(segment
		(start 9.687814 -30.076902)
		(end 9.687814 -30.419802)
		(width 0.1143)
		(layer "In11.Cu")
		(net "P3E_CPU1_PE3_MP_C_TXN<5>")
	)
	(segment
		(start 11.9126 -32.2326)
		(end 11.9126 -31.9405)
		(width 0.1143)
		(layer "In11.Cu")
		(net "P3E_CPU1_PE3_MP_C_TXN<5>")
	)
	(segment
		(start 7.88797 -28.564078)
		(end 8.05307 -28.398978)
		(width 0.1143)
		(layer "In11.Cu")
		(net "P3E_CPU1_PE3_MP_C_TXN<5>")
	)
	(segment
		(start 11.7221 -32.4231)
		(end 11.9126 -32.2326)
		(width 0.1143)
		(layer "In11.Cu")
		(net "P3E_CPU1_PE3_MP_C_TXN<5>")
	)
	(segment
		(start 9.522714 -30.584902)
		(end 9.522714 -30.927802)
		(width 0.1143)
		(layer "In11.Cu")
		(net "P3E_CPU1_PE3_MP_C_TXN<5>")
	)
	(segment
		(start 9.522714 -30.927802)
		(end 10.2997 -31.704788)
		(width 0.1143)
		(layer "In11.Cu")
		(net "P3E_CPU1_PE3_MP_C_TXN<5>")
	)
	(segment
		(start 9.687814 -30.419802)
		(end 9.522714 -30.584902)
		(width 0.1143)
		(layer "In11.Cu")
		(net "P3E_CPU1_PE3_MP_C_TXN<5>")
	)
	(segment
		(start 9.522714 -29.911802)
		(end 9.687814 -30.076902)
		(width 0.1143)
		(layer "In11.Cu")
		(net "P3E_CPU1_PE3_MP_C_TXN<5>")
	)
	(segment
		(start 5.31368 -28.087066)
		(end 5.790692 -28.564078)
		(width 0.1143)
		(layer "In11.Cu")
		(net "P3E_CPU1_PE3_MP_C_TXN<5>")
	)
	(segment
		(start 10.775442 -32.18053)
		(end 11.018012 -32.4231)
		(width 0.1143)
		(layer "In11.Cu")
		(net "P3E_CPU1_PE3_MP_C_TXN<5>")
	)
	(segment
		(start 10.775442 -31.947104)
		(end 10.775442 -32.18053)
		(width 0.1143)
		(layer "In11.Cu")
		(net "P3E_CPU1_PE3_MP_C_TXN<5>")
	)
	(segment
		(start 8.39597 -28.398978)
		(end 8.56107 -28.564078)
		(width 0.1143)
		(layer "In11.Cu")
		(net "P3E_CPU1_PE3_MP_C_TXN<5>")
	)
	(segment
		(start 8.05307 -28.398978)
		(end 8.39597 -28.398978)
		(width 0.1143)
		(layer "In11.Cu")
		(net "P3E_CPU1_PE3_MP_C_TXN<5>")
	)
	(segment
		(start 10.2997 -31.704788)
		(end 10.533126 -31.704788)
		(width 0.1143)
		(layer "In11.Cu")
		(net "P3E_CPU1_PE3_MP_C_TXN<5>")
	)
	(segment
		(start 5.899912 -27.71013)
		(end 5.43687 -27.71013)
		(width 0.1143)
		(layer "In11.Cu")
		(net "P3E_CPU1_PE3_MP_C_TXN<5>")
	)
	(segment
		(start 5.31368 -27.83332)
		(end 5.31368 -28.087066)
		(width 0.1143)
		(layer "In11.Cu")
		(net "P3E_CPU1_PE3_MP_C_TXN<5>")
	)
	(segment
		(start 13.8938 -31.242)
		(end 13.56995 -30.91815)
		(width 0.1143)
		(layer "F.Cu")
		(net "P3E_CPU1_PE3_MP_C_TXN<4>")
	)
	(segment
		(start 13.212826 -30.91815)
		(end 13.098526 -31.03245)
		(width 0.1143)
		(layer "F.Cu")
		(net "P3E_CPU1_PE3_MP_C_TXN<4>")
	)
	(segment
		(start 13.56995 -30.91815)
		(end 13.212826 -30.91815)
		(width 0.1143)
		(layer "F.Cu")
		(net "P3E_CPU1_PE3_MP_C_TXN<4>")
	)
	(segment
		(start 13.098526 -31.03245)
		(end 13.098526 -31.4325)
		(width 0.1143)
		(layer "F.Cu")
		(net "P3E_CPU1_PE3_MP_C_TXN<4>")
	)
	(via
		(at 13.098526 -31.4325)
		(size 0.508)
		(drill 0.254)
		(layers "F.Cu" "B.Cu")
		(net "P3E_CPU1_PE3_MP_C_TXN<4>")
	)
	(segment
		(start 13.098526 -31.176214)
		(end 13.098526 -31.4325)
		(width 0.1143)
		(layer "B.Cu")
		(net "P3E_CPU1_PE3_MP_C_TXN<4>")
	)
	(segment
		(start 0.299974 -27.71013)
		(end 0.765048 -27.71013)
		(width 0.1143)
		(layer "B.Cu")
		(net "P3E_CPU1_PE3_MP_C_TXN<4>")
	)
	(segment
		(start 0.952754 -27.897836)
		(end 0.952754 -28.43403)
		(width 0.1143)
		(layer "B.Cu")
		(net "P3E_CPU1_PE3_MP_C_TXN<4>")
	)
	(segment
		(start 12.834112 -30.9118)
		(end 13.098526 -31.176214)
		(width 0.1143)
		(layer "B.Cu")
		(net "P3E_CPU1_PE3_MP_C_TXN<4>")
	)
	(segment
		(start 1.349502 -28.830778)
		(end 8.739124 -28.830778)
		(width 0.1143)
		(layer "B.Cu")
		(net "P3E_CPU1_PE3_MP_C_TXN<4>")
	)
	(segment
		(start 10.820146 -30.9118)
		(end 12.834112 -30.9118)
		(width 0.1143)
		(layer "B.Cu")
		(net "P3E_CPU1_PE3_MP_C_TXN<4>")
	)
	(segment
		(start 0.952754 -28.43403)
		(end 1.349502 -28.830778)
		(width 0.1143)
		(layer "B.Cu")
		(net "P3E_CPU1_PE3_MP_C_TXN<4>")
	)
	(segment
		(start 8.739124 -28.830778)
		(end 10.820146 -30.9118)
		(width 0.1143)
		(layer "B.Cu")
		(net "P3E_CPU1_PE3_MP_C_TXN<4>")
	)
	(segment
		(start 0.765048 -27.71013)
		(end 0.952754 -27.897836)
		(width 0.1143)
		(layer "B.Cu")
		(net "P3E_CPU1_PE3_MP_C_TXN<4>")
	)
	(segment
		(start 11.9126 -28.78455)
		(end 11.9126 -28.3845)
		(width 0.1143)
		(layer "F.Cu")
		(net "P3E_CPU1_PE3_MP_C_TXN<3>")
	)
	(segment
		(start 12.0269 -28.89885)
		(end 11.9126 -28.78455)
		(width 0.1143)
		(layer "F.Cu")
		(net "P3E_CPU1_PE3_MP_C_TXN<3>")
	)
	(segment
		(start 13.8938 -28.575)
		(end 13.56995 -28.89885)
		(width 0.1143)
		(layer "F.Cu")
		(net "P3E_CPU1_PE3_MP_C_TXN<3>")
	)
	(segment
		(start 13.56995 -28.89885)
		(end 12.0269 -28.89885)
		(width 0.1143)
		(layer "F.Cu")
		(net "P3E_CPU1_PE3_MP_C_TXN<3>")
	)
	(via
		(at 11.9126 -28.3845)
		(size 0.508)
		(drill 0.254)
		(layers "F.Cu" "B.Cu")
		(net "P3E_CPU1_PE3_MP_C_TXN<3>")
	)
	(segment
		(start -3.35534 -27.51074)
		(end -3.35534 -27.068526)
		(width 0.1143)
		(layer "In11.Cu")
		(net "P3E_CPU1_PE3_MP_C_TXN<3>")
	)
	(segment
		(start -3.55473 -27.71013)
		(end -3.35534 -27.51074)
		(width 0.1143)
		(layer "In11.Cu")
		(net "P3E_CPU1_PE3_MP_C_TXN<3>")
	)
	(segment
		(start -2.764536 -26.477722)
		(end 8.570468 -26.477722)
		(width 0.1143)
		(layer "In11.Cu")
		(net "P3E_CPU1_PE3_MP_C_TXN<3>")
	)
	(segment
		(start 11.7856 -28.8671)
		(end 11.9126 -28.7401)
		(width 0.1143)
		(layer "In11.Cu")
		(net "P3E_CPU1_PE3_MP_C_TXN<3>")
	)
	(segment
		(start -3.35534 -27.068526)
		(end -2.764536 -26.477722)
		(width 0.1143)
		(layer "In11.Cu")
		(net "P3E_CPU1_PE3_MP_C_TXN<3>")
	)
	(segment
		(start -3.899916 -27.71013)
		(end -3.55473 -27.71013)
		(width 0.1143)
		(layer "In11.Cu")
		(net "P3E_CPU1_PE3_MP_C_TXN<3>")
	)
	(segment
		(start 10.959846 -28.8671)
		(end 11.7856 -28.8671)
		(width 0.1143)
		(layer "In11.Cu")
		(net "P3E_CPU1_PE3_MP_C_TXN<3>")
	)
	(segment
		(start 11.9126 -28.7401)
		(end 11.9126 -28.3845)
		(width 0.1143)
		(layer "In11.Cu")
		(net "P3E_CPU1_PE3_MP_C_TXN<3>")
	)
	(segment
		(start 8.570468 -26.477722)
		(end 10.959846 -28.8671)
		(width 0.1143)
		(layer "In11.Cu")
		(net "P3E_CPU1_PE3_MP_C_TXN<3>")
	)
	(segment
		(start 13.587984 -27.102816)
		(end 13.14704 -27.102816)
		(width 0.1143)
		(layer "F.Cu")
		(net "P3E_CPU1_PE3_MP_C_TXN<2>")
	)
	(segment
		(start 13.14704 -27.102816)
		(end 13.050774 -27.00655)
		(width 0.1143)
		(layer "F.Cu")
		(net "P3E_CPU1_PE3_MP_C_TXN<2>")
	)
	(segment
		(start 13.8938 -26.797)
		(end 13.587984 -27.102816)
		(width 0.1143)
		(layer "F.Cu")
		(net "P3E_CPU1_PE3_MP_C_TXN<2>")
	)
	(segment
		(start 13.050774 -27.00655)
		(end 13.050774 -26.6065)
		(width 0.1143)
		(layer "F.Cu")
		(net "P3E_CPU1_PE3_MP_C_TXN<2>")
	)
	(via
		(at 13.050774 -26.6065)
		(size 0.508)
		(drill 0.254)
		(layers "F.Cu" "B.Cu")
		(net "P3E_CPU1_PE3_MP_C_TXN<2>")
	)
	(segment
		(start 6.32206 -24.811482)
		(end 6.607302 -24.52624)
		(width 0.1143)
		(layer "In11.Cu")
		(net "P3E_CPU1_PE3_MP_C_TXN<2>")
	)
	(segment
		(start 6.32206 -25.407874)
		(end 6.32206 -24.811482)
		(width 0.1143)
		(layer "In11.Cu")
		(net "P3E_CPU1_PE3_MP_C_TXN<2>")
	)
	(segment
		(start 5.80009 -25.710134)
		(end 6.0198 -25.710134)
		(width 0.1143)
		(layer "In11.Cu")
		(net "P3E_CPU1_PE3_MP_C_TXN<2>")
	)
	(segment
		(start 6.0198 -25.710134)
		(end 6.32206 -25.407874)
		(width 0.1143)
		(layer "In11.Cu")
		(net "P3E_CPU1_PE3_MP_C_TXN<2>")
	)
	(segment
		(start 11.60145 -27.10434)
		(end 12.89558 -27.10434)
		(width 0.1143)
		(layer "In11.Cu")
		(net "P3E_CPU1_PE3_MP_C_TXN<2>")
	)
	(segment
		(start 13.050774 -26.949146)
		(end 13.050774 -26.6065)
		(width 0.1143)
		(layer "In11.Cu")
		(net "P3E_CPU1_PE3_MP_C_TXN<2>")
	)
	(segment
		(start 9.02335 -24.52624)
		(end 11.60145 -27.10434)
		(width 0.1143)
		(layer "In11.Cu")
		(net "P3E_CPU1_PE3_MP_C_TXN<2>")
	)
	(segment
		(start 12.89558 -27.10434)
		(end 13.050774 -26.949146)
		(width 0.1143)
		(layer "In11.Cu")
		(net "P3E_CPU1_PE3_MP_C_TXN<2>")
	)
	(segment
		(start 6.607302 -24.52624)
		(end 9.02335 -24.52624)
		(width 0.1143)
		(layer "In11.Cu")
		(net "P3E_CPU1_PE3_MP_C_TXN<2>")
	)
	(segment
		(start 13.8938 -25.908)
		(end 13.56995 -25.58415)
		(width 0.1143)
		(layer "F.Cu")
		(net "P3E_CPU1_PE3_MP_C_TXN<1>")
	)
	(segment
		(start 13.56995 -25.58415)
		(end 12.0269 -25.58415)
		(width 0.1143)
		(layer "F.Cu")
		(net "P3E_CPU1_PE3_MP_C_TXN<1>")
	)
	(segment
		(start 11.9126 -25.69845)
		(end 11.9126 -26.0985)
		(width 0.1143)
		(layer "F.Cu")
		(net "P3E_CPU1_PE3_MP_C_TXN<1>")
	)
	(segment
		(start 12.0269 -25.58415)
		(end 11.9126 -25.69845)
		(width 0.1143)
		(layer "F.Cu")
		(net "P3E_CPU1_PE3_MP_C_TXN<1>")
	)
	(via
		(at 11.9126 -26.0985)
		(size 0.508)
		(drill 0.254)
		(layers "F.Cu" "B.Cu")
		(net "P3E_CPU1_PE3_MP_C_TXN<1>")
	)
	(segment
		(start 1.599946 -25.710134)
		(end 2.06502 -25.710134)
		(width 0.1143)
		(layer "B.Cu")
		(net "P3E_CPU1_PE3_MP_C_TXN<1>")
	)
	(segment
		(start 7.97306 -26.947876)
		(end 11.268202 -25.58288)
		(width 0.1143)
		(layer "B.Cu")
		(net "P3E_CPU1_PE3_MP_C_TXN<1>")
	)
	(segment
		(start 2.17932 -25.824434)
		(end 2.17932 -26.383996)
		(width 0.1143)
		(layer "B.Cu")
		(net "P3E_CPU1_PE3_MP_C_TXN<1>")
	)
	(segment
		(start 2.7432 -26.947876)
		(end 7.97306 -26.947876)
		(width 0.1143)
		(layer "B.Cu")
		(net "P3E_CPU1_PE3_MP_C_TXN<1>")
	)
	(segment
		(start 11.9126 -25.69845)
		(end 11.9126 -26.0985)
		(width 0.1143)
		(layer "B.Cu")
		(net "P3E_CPU1_PE3_MP_C_TXN<1>")
	)
	(segment
		(start 11.79703 -25.58288)
		(end 11.9126 -25.69845)
		(width 0.1143)
		(layer "B.Cu")
		(net "P3E_CPU1_PE3_MP_C_TXN<1>")
	)
	(segment
		(start 11.268202 -25.58288)
		(end 11.79703 -25.58288)
		(width 0.1143)
		(layer "B.Cu")
		(net "P3E_CPU1_PE3_MP_C_TXN<1>")
	)
	(segment
		(start 2.06502 -25.710134)
		(end 2.17932 -25.824434)
		(width 0.1143)
		(layer "B.Cu")
		(net "P3E_CPU1_PE3_MP_C_TXN<1>")
	)
	(segment
		(start 2.17932 -26.383996)
		(end 2.7432 -26.947876)
		(width 0.1143)
		(layer "B.Cu")
		(net "P3E_CPU1_PE3_MP_C_TXN<1>")
	)
	(segment
		(start 13.14704 -23.546816)
		(end 13.050774 -23.45055)
		(width 0.1143)
		(layer "F.Cu")
		(net "P3E_CPU1_PE3_MP_C_TXN<0>")
	)
	(segment
		(start 13.050774 -23.45055)
		(end 13.050774 -23.0505)
		(width 0.1143)
		(layer "F.Cu")
		(net "P3E_CPU1_PE3_MP_C_TXN<0>")
	)
	(segment
		(start 13.587984 -23.546816)
		(end 13.14704 -23.546816)
		(width 0.1143)
		(layer "F.Cu")
		(net "P3E_CPU1_PE3_MP_C_TXN<0>")
	)
	(segment
		(start 13.8938 -23.241)
		(end 13.587984 -23.546816)
		(width 0.1143)
		(layer "F.Cu")
		(net "P3E_CPU1_PE3_MP_C_TXN<0>")
	)
	(via
		(at 13.050774 -23.0505)
		(size 0.508)
		(drill 0.254)
		(layers "F.Cu" "B.Cu")
		(net "P3E_CPU1_PE3_MP_C_TXN<0>")
	)
	(segment
		(start 12.902946 -23.5712)
		(end 13.050774 -23.423372)
		(width 0.1143)
		(layer "B.Cu")
		(net "P3E_CPU1_PE3_MP_C_TXN<0>")
	)
	(segment
		(start -1.58877 -24.6888)
		(end 8.8138 -24.6888)
		(width 0.1143)
		(layer "B.Cu")
		(net "P3E_CPU1_PE3_MP_C_TXN<0>")
	)
	(segment
		(start 9.9314 -23.5712)
		(end 12.902946 -23.5712)
		(width 0.1143)
		(layer "B.Cu")
		(net "P3E_CPU1_PE3_MP_C_TXN<0>")
	)
	(segment
		(start 13.050774 -23.423372)
		(end 13.050774 -23.0505)
		(width 0.1143)
		(layer "B.Cu")
		(net "P3E_CPU1_PE3_MP_C_TXN<0>")
	)
	(segment
		(start -1.931416 -25.031446)
		(end -1.58877 -24.6888)
		(width 0.1143)
		(layer "B.Cu")
		(net "P3E_CPU1_PE3_MP_C_TXN<0>")
	)
	(segment
		(start 8.8138 -24.6888)
		(end 9.9314 -23.5712)
		(width 0.1143)
		(layer "B.Cu")
		(net "P3E_CPU1_PE3_MP_C_TXN<0>")
	)
	(segment
		(start -1.931416 -25.44191)
		(end -1.931416 -25.031446)
		(width 0.1143)
		(layer "B.Cu")
		(net "P3E_CPU1_PE3_MP_C_TXN<0>")
	)
	(segment
		(start -2.19964 -25.710134)
		(end -1.931416 -25.44191)
		(width 0.1143)
		(layer "B.Cu")
		(net "P3E_CPU1_PE3_MP_C_TXN<0>")
	)
	(segment
		(start -2.599944 -25.710134)
		(end -2.19964 -25.710134)
		(width 0.1143)
		(layer "B.Cu")
		(net "P3E_CPU1_PE3_MP_C_TXN<0>")
	)
	(segment
		(start 478.539556 -44.717462)
		(end 478.51822 -44.738798)
		(width 0.254)
		(layer "F.Cu")
		(net "P1V5_LAN")
	)
	(segment
		(start 479.8822 -40.71747)
		(end 479.27133 -40.71747)
		(width 0.254)
		(layer "F.Cu")
		(net "P1V5_LAN")
	)
	(segment
		(start 479.27133 -40.71747)
		(end 479.0948 -40.894)
		(width 0.254)
		(layer "F.Cu")
		(net "P1V5_LAN")
	)
	(segment
		(start 479.8822 -44.717462)
		(end 478.539556 -44.717462)
		(width 0.254)
		(layer "F.Cu")
		(net "P1V5_LAN")
	)
	(via
		(at 477.4438 -39.5478)
		(size 0.6604)
		(drill 0.3302)
		(layers "F.Cu" "B.Cu")
		(net "P1V5_LAN")
	)
	(via
		(at 483.893368 -38.14318)
		(size 0.508)
		(drill 0.254)
		(layers "F.Cu" "B.Cu")
		(net "P1V5_LAN")
	)
	(via
		(at 479.0948 -40.894)
		(size 0.508)
		(drill 0.254)
		(layers "F.Cu" "B.Cu")
		(net "P1V5_LAN")
	)
	(via
		(at 478.51822 -44.738798)
		(size 0.508)
		(drill 0.254)
		(layers "F.Cu" "B.Cu")
		(net "P1V5_LAN")
	)
	(segment
		(start 483.893368 -38.14318)
		(end 483.25532 -38.14318)
		(width 0.508)
		(layer "B.Cu")
		(net "P1V5_LAN")
	)
	(segment
		(start 483.25532 -38.14318)
		(end 482.9556 -38.4429)
		(width 0.508)
		(layer "B.Cu")
		(net "P1V5_LAN")
	)
	(segment
		(start 479.679 -44.323)
		(end 479.263202 -44.738798)
		(width 0.254)
		(layer "B.Cu")
		(net "P1V5_LAN")
	)
	(segment
		(start 479.9965 -44.323)
		(end 479.9965 -44.6405)
		(width 0.254)
		(layer "B.Cu")
		(net "P1V5_LAN")
	)
	(segment
		(start 479.9965 -44.323)
		(end 479.679 -44.323)
		(width 0.254)
		(layer "B.Cu")
		(net "P1V5_LAN")
	)
	(segment
		(start 480.2251 -44.8691)
		(end 480.2251 -45.3644)
		(width 0.254)
		(layer "B.Cu")
		(net "P1V5_LAN")
	)
	(segment
		(start 478.24136 -38.4302)
		(end 478.49536 -38.6842)
		(width 0.254)
		(layer "B.Cu")
		(net "P1V5_LAN")
	)
	(segment
		(start 476.60052 -38.32606)
		(end 477.24314 -38.32606)
		(width 0.254)
		(layer "B.Cu")
		(net "P1V5_LAN")
	)
	(segment
		(start 478.49536 -38.6842)
		(end 478.49536 -40.20947)
		(width 0.254)
		(layer "B.Cu")
		(net "P1V5_LAN")
	)
	(segment
		(start 476.4151 -37.5412)
		(end 476.4151 -38.14064)
		(width 0.254)
		(layer "B.Cu")
		(net "P1V5_LAN")
	)
	(segment
		(start 477.24314 -38.32606)
		(end 477.34728 -38.4302)
		(width 0.254)
		(layer "B.Cu")
		(net "P1V5_LAN")
	)
	(segment
		(start 476.4151 -38.14064)
		(end 476.60052 -38.32606)
		(width 0.254)
		(layer "B.Cu")
		(net "P1V5_LAN")
	)
	(segment
		(start 477.34728 -38.4302)
		(end 478.24136 -38.4302)
		(width 0.254)
		(layer "B.Cu")
		(net "P1V5_LAN")
	)
	(segment
		(start 479.263202 -44.738798)
		(end 478.51822 -44.738798)
		(width 0.254)
		(layer "B.Cu")
		(net "P1V5_LAN")
	)
	(segment
		(start 479.9965 -44.6405)
		(end 480.2251 -44.8691)
		(width 0.254)
		(layer "B.Cu")
		(net "P1V5_LAN")
	)
	(segment
		(start 479.441002 -44.738798)
		(end 478.51822 -44.738798)
		(width 0.508)
		(layer "In9.Cu")
		(net "P1V5_LAN")
	)
	(segment
		(start 479.0948 -41.2496)
		(end 479.8314 -41.9862)
		(width 0.508)
		(layer "In9.Cu")
		(net "P1V5_LAN")
	)
	(segment
		(start 479.8314 -41.9862)
		(end 479.8314 -44.3484)
		(width 0.508)
		(layer "In9.Cu")
		(net "P1V5_LAN")
	)
	(segment
		(start 479.0948 -40.894)
		(end 479.0948 -41.2496)
		(width 0.508)
		(layer "In9.Cu")
		(net "P1V5_LAN")
	)
	(segment
		(start 479.8314 -44.3484)
		(end 479.441002 -44.738798)
		(width 0.508)
		(layer "In9.Cu")
		(net "P1V5_LAN")
	)
	(segment
		(start 483.893368 -38.14318)
		(end 483.16642 -38.14318)
		(width 0.508)
		(layer "In11.Cu")
		(net "P1V5_LAN")
	)
	(segment
		(start 483.16642 -38.14318)
		(end 480.4156 -40.894)
		(width 0.508)
		(layer "In11.Cu")
		(net "P1V5_LAN")
	)
	(segment
		(start 480.4156 -40.894)
		(end 479.0948 -40.894)
		(width 0.508)
		(layer "In11.Cu")
		(net "P1V5_LAN")
	)
	(segment
		(start 488.6198 -45.217334)
		(end 489.735114 -45.217334)
		(width 0.254)
		(layer "F.Cu")
		(net "P0V9_LAN")
	)
	(segment
		(start 480.500944 -48.3362)
		(end 480.1362 -48.3362)
		(width 0.3048)
		(layer "F.Cu")
		(net "P0V9_LAN")
	)
	(segment
		(start 485.500934 -38.99916)
		(end 485.638094 -38.862)
		(width 0.3048)
		(layer "F.Cu")
		(net "P0V9_LAN")
	)
	(segment
		(start 479.8822 -43.217338)
		(end 479.182938 -43.217338)
		(width 0.254)
		(layer "F.Cu")
		(net "P0V9_LAN")
	)
	(segment
		(start 485.500934 -39.5986)
		(end 485.500934 -38.99916)
		(width 0.3048)
		(layer "F.Cu")
		(net "P0V9_LAN")
	)
	(segment
		(start 480.1362 -48.3362)
		(end 479.9076 -48.5648)
		(width 0.3048)
		(layer "F.Cu")
		(net "P0V9_LAN")
	)
	(segment
		(start 479.182938 -43.217338)
		(end 479.1456 -43.18)
		(width 0.254)
		(layer "F.Cu")
		(net "P0V9_LAN")
	)
	(segment
		(start 489.735114 -45.217334)
		(end 489.775246 -45.257466)
		(width 0.254)
		(layer "F.Cu")
		(net "P0V9_LAN")
	)
	(via
		(at 489.775246 -45.257466)
		(size 0.508)
		(drill 0.254)
		(layers "F.Cu" "B.Cu")
		(net "P0V9_LAN")
	)
	(via
		(at 479.1456 -43.18)
		(size 0.508)
		(drill 0.254)
		(layers "F.Cu" "B.Cu")
		(net "P0V9_LAN")
	)
	(via
		(at 489.08208 -45.50664)
		(size 0.6604)
		(drill 0.3302)
		(layers "F.Cu" "B.Cu")
		(net "P0V9_LAN")
	)
	(via
		(at 485.638094 -38.862)
		(size 0.508)
		(drill 0.254)
		(layers "F.Cu" "B.Cu")
		(net "P0V9_LAN")
	)
	(via
		(at 479.9076 -48.5648)
		(size 0.508)
		(drill 0.254)
		(layers "F.Cu" "B.Cu")
		(net "P0V9_LAN")
	)
	(segment
		(start 485.1908 -39.5986)
		(end 485.3178 -39.7256)
		(width 0.254)
		(layer "B.Cu")
		(net "P0V9_LAN")
	)
	(segment
		(start 480.8474 -47.625)
		(end 479.9076 -48.5648)
		(width 0.508)
		(layer "B.Cu")
		(net "P0V9_LAN")
	)
	(segment
		(start 482.2825 -47.1932)
		(end 481.6475 -46.5582)
		(width 0.508)
		(layer "B.Cu")
		(net "P0V9_LAN")
	)
	(segment
		(start 489.08208 -45.50664)
		(end 489.526072 -45.50664)
		(width 0.508)
		(layer "B.Cu")
		(net "P0V9_LAN")
	)
	(segment
		(start 482.2825 -47.625)
		(end 482.2825 -47.1932)
		(width 0.508)
		(layer "B.Cu")
		(net "P0V9_LAN")
	)
	(segment
		(start 482.2825 -47.625)
		(end 480.8474 -47.625)
		(width 0.508)
		(layer "B.Cu")
		(net "P0V9_LAN")
	)
	(segment
		(start 488.191302 -45.584872)
		(end 488.191302 -46.854872)
		(width 0.508)
		(layer "B.Cu")
		(net "P0V9_LAN")
	)
	(segment
		(start 489.003848 -45.584872)
		(end 489.08208 -45.50664)
		(width 0.508)
		(layer "B.Cu")
		(net "P0V9_LAN")
	)
	(segment
		(start 489.526072 -45.50664)
		(end 489.775246 -45.257466)
		(width 0.508)
		(layer "B.Cu")
		(net "P0V9_LAN")
	)
	(segment
		(start 488.191302 -45.584872)
		(end 489.003848 -45.584872)
		(width 0.508)
		(layer "B.Cu")
		(net "P0V9_LAN")
	)
	(segment
		(start 485.6734 -38.897306)
		(end 485.6734 -39.7256)
		(width 0.254)
		(layer "B.Cu")
		(net "P0V9_LAN")
	)
	(segment
		(start 479.7298 -42.5958)
		(end 479.9838 -42.5958)
		(width 0.254)
		(layer "B.Cu")
		(net "P0V9_LAN")
	)
	(segment
		(start 488.181396 -44.48556)
		(end 488.181396 -45.574966)
		(width 0.254)
		(layer "B.Cu")
		(net "P0V9_LAN")
	)
	(segment
		(start 488.191302 -48.124872)
		(end 488.191302 -46.854872)
		(width 0.508)
		(layer "B.Cu")
		(net "P0V9_LAN")
	)
	(segment
		(start 488.181396 -45.574966)
		(end 488.191302 -45.584872)
		(width 0.254)
		(layer "B.Cu")
		(net "P0V9_LAN")
	)
	(segment
		(start 485.3178 -39.7256)
		(end 485.6734 -39.7256)
		(width 0.254)
		(layer "B.Cu")
		(net "P0V9_LAN")
	)
	(segment
		(start 479.1456 -43.18)
		(end 479.7298 -42.5958)
		(width 0.254)
		(layer "B.Cu")
		(net "P0V9_LAN")
	)
	(segment
		(start 485.638094 -38.862)
		(end 485.6734 -38.897306)
		(width 0.254)
		(layer "B.Cu")
		(net "P0V9_LAN")
	)
	(segment
		(start 484.6574 -39.5986)
		(end 485.1908 -39.5986)
		(width 0.254)
		(layer "B.Cu")
		(net "P0V9_LAN")
	)
	(segment
		(start 488.990132 -46.217332)
		(end 489.5342 -46.7614)
		(width 0.10795)
		(layer "F.Cu")
		(net "SPI_NIC_SCLK_R")
	)
	(segment
		(start 488.6198 -46.217332)
		(end 488.990132 -46.217332)
		(width 0.10795)
		(layer "F.Cu")
		(net "SPI_NIC_SCLK_R")
	)
	(segment
		(start 489.5342 -46.7614)
		(end 490.2581 -46.7614)
		(width 0.10795)
		(layer "F.Cu")
		(net "SPI_NIC_SCLK_R")
	)
	(segment
		(start 490.1311 -46.1264)
		(end 489.4326 -46.1264)
		(width 0.10795)
		(layer "F.Cu")
		(net "SPI_NIC_MOSI_R")
	)
	(segment
		(start 489.02366 -45.71746)
		(end 488.6198 -45.71746)
		(width 0.10795)
		(layer "F.Cu")
		(net "SPI_NIC_MOSI_R")
	)
	(segment
		(start 489.4326 -46.1264)
		(end 489.02366 -45.71746)
		(width 0.10795)
		(layer "F.Cu")
		(net "SPI_NIC_MOSI_R")
	)
	(segment
		(start 490.2581 -45.9994)
		(end 490.1311 -46.1264)
		(width 0.10795)
		(layer "F.Cu")
		(net "SPI_NIC_MOSI_R")
	)
	(segment
		(start 488.956858 -46.717458)
		(end 490.2581 -48.0187)
		(width 0.10795)
		(layer "F.Cu")
		(net "SPI_NIC_MISO")
	)
	(segment
		(start 488.6198 -46.717458)
		(end 488.956858 -46.717458)
		(width 0.10795)
		(layer "F.Cu")
		(net "SPI_NIC_MISO")
	)
	(segment
		(start 490.2581 -48.0187)
		(end 490.2581 -48.2854)
		(width 0.10795)
		(layer "F.Cu")
		(net "SPI_NIC_MISO")
	)
	(segment
		(start 489.6866 -48.768)
		(end 489.98886 -49.07026)
		(width 0.10795)
		(layer "F.Cu")
		(net "SPI_NIC_CS_R_N")
	)
	(segment
		(start 490.7153 -49.53508)
		(end 490.7153 -49.8094)
		(width 0.10795)
		(layer "F.Cu")
		(net "SPI_NIC_CS_R_N")
	)
	(segment
		(start 488.6198 -47.21733)
		(end 488.92333 -47.21733)
		(width 0.10795)
		(layer "F.Cu")
		(net "SPI_NIC_CS_R_N")
	)
	(segment
		(start 489.98886 -49.07026)
		(end 490.25048 -49.07026)
		(width 0.10795)
		(layer "F.Cu")
		(net "SPI_NIC_CS_R_N")
	)
	(segment
		(start 489.331 -47.625)
		(end 489.331 -47.9298)
		(width 0.10795)
		(layer "F.Cu")
		(net "SPI_NIC_CS_R_N")
	)
	(segment
		(start 488.92333 -47.21733)
		(end 489.331 -47.625)
		(width 0.10795)
		(layer "F.Cu")
		(net "SPI_NIC_CS_R_N")
	)
	(segment
		(start 489.6866 -48.2854)
		(end 489.6866 -48.768)
		(width 0.10795)
		(layer "F.Cu")
		(net "SPI_NIC_CS_R_N")
	)
	(segment
		(start 489.331 -47.9298)
		(end 489.6866 -48.2854)
		(width 0.10795)
		(layer "F.Cu")
		(net "SPI_NIC_CS_R_N")
	)
	(segment
		(start 490.25048 -49.07026)
		(end 490.7153 -49.53508)
		(width 0.10795)
		(layer "F.Cu")
		(net "SPI_NIC_CS_R_N")
	)
	(via
		(at 489.98886 -49.07026)
		(size 0.508)
		(drill 0.254)
		(layers "F.Cu" "B.Cu")
		(net "SPI_NIC_CS_R_N")
	)
	(segment
		(start 486.33126 -38.75532)
		(end 486.33126 -38.84676)
		(width 0.10795)
		(layer "F.Cu")
		(net "TP_SPRV_SDP3")
	)
	(segment
		(start 486.33126 -38.84676)
		(end 486.31094 -38.86708)
		(width 0.10795)
		(layer "F.Cu")
		(net "TP_SPRV_SDP3")
	)
	(segment
		(start 486.00106 -39.181278)
		(end 486.00106 -39.5986)
		(width 0.10795)
		(layer "F.Cu")
		(net "TP_SPRV_SDP3")
	)
	(segment
		(start 486.31094 -38.871398)
		(end 486.00106 -39.181278)
		(width 0.10795)
		(layer "F.Cu")
		(net "TP_SPRV_SDP3")
	)
	(segment
		(start 486.31094 -38.86708)
		(end 486.31094 -38.871398)
		(width 0.10795)
		(layer "F.Cu")
		(net "TP_SPRV_SDP3")
	)
	(via
		(at 486.33126 -38.75532)
		(size 0.508)
		(drill 0.254)
		(layers "F.Cu" "B.Cu")
		(net "TP_SPRV_SDP3")
	)
	(segment
		(start 487.2736 -38.8874)
		(end 487.2736 -38.6334)
		(width 0.10795)
		(layer "F.Cu")
		(net "TP_SPRV_SDP2")
	)
	(segment
		(start 487.001058 -39.5986)
		(end 487.001058 -39.159942)
		(width 0.10795)
		(layer "F.Cu")
		(net "TP_SPRV_SDP2")
	)
	(segment
		(start 487.2736 -38.6334)
		(end 487.548936 -38.358064)
		(width 0.10795)
		(layer "F.Cu")
		(net "TP_SPRV_SDP2")
	)
	(segment
		(start 487.001058 -39.159942)
		(end 487.2736 -38.8874)
		(width 0.10795)
		(layer "F.Cu")
		(net "TP_SPRV_SDP2")
	)
	(segment
		(start 487.548936 -38.358064)
		(end 487.548936 -37.973)
		(width 0.10795)
		(layer "F.Cu")
		(net "TP_SPRV_SDP2")
	)
	(via
		(at 486.5878 -36.6268)
		(size 0.6604)
		(drill 0.3302)
		(layers "F.Cu" "B.Cu")
		(net "TP_SPRV_SDP2")
	)
	(via
		(at 487.548936 -37.973)
		(size 0.508)
		(drill 0.254)
		(layers "F.Cu" "B.Cu")
		(net "TP_SPRV_SDP2")
	)
	(segment
		(start 487.548936 -37.973)
		(end 486.9434 -37.367464)
		(width 0.10795)
		(layer "B.Cu")
		(net "TP_SPRV_SDP2")
	)
	(segment
		(start 486.9434 -36.9824)
		(end 486.5878 -36.6268)
		(width 0.10795)
		(layer "B.Cu")
		(net "TP_SPRV_SDP2")
	)
	(segment
		(start 486.9434 -37.367464)
		(end 486.9434 -36.9824)
		(width 0.10795)
		(layer "B.Cu")
		(net "TP_SPRV_SDP2")
	)
	(segment
		(start 487.982006 -38.283642)
		(end 487.540554 -38.725094)
		(width 0.10795)
		(layer "F.Cu")
		(net "TP_SPRV_SDP0")
	)
	(segment
		(start 488.6452 -38.354)
		(end 488.574842 -38.283642)
		(width 0.10795)
		(layer "F.Cu")
		(net "TP_SPRV_SDP0")
	)
	(segment
		(start 487.540554 -39.558976)
		(end 487.50093 -39.5986)
		(width 0.10795)
		(layer "F.Cu")
		(net "TP_SPRV_SDP0")
	)
	(segment
		(start 487.540554 -38.725094)
		(end 487.540554 -39.558976)
		(width 0.10795)
		(layer "F.Cu")
		(net "TP_SPRV_SDP0")
	)
	(segment
		(start 488.574842 -38.283642)
		(end 487.982006 -38.283642)
		(width 0.10795)
		(layer "F.Cu")
		(net "TP_SPRV_SDP0")
	)
	(via
		(at 488.6452 -38.354)
		(size 0.508)
		(drill 0.254)
		(layers "F.Cu" "B.Cu")
		(net "TP_SPRV_SDP0")
	)
	(segment
		(start 491.8456 -144.145)
		(end 491.9726 -144.272)
		(width 0.10795)
		(layer "F.Cu")
		(net "LED_POSTCODE_3_R")
	)
	(segment
		(start 490.2835 -144.638268)
		(end 490.806232 -145.161)
		(width 0.10795)
		(layer "F.Cu")
		(net "LED_POSTCODE_3_R")
	)
	(segment
		(start 490.74832 -144.50568)
		(end 491.109 -144.145)
		(width 0.10795)
		(layer "F.Cu")
		(net "LED_POSTCODE_3_R")
	)
	(segment
		(start 491.109 -144.145)
		(end 491.8456 -144.145)
		(width 0.10795)
		(layer "F.Cu")
		(net "LED_POSTCODE_3_R")
	)
	(segment
		(start 490.2835 -144.638268)
		(end 490.416088 -144.50568)
		(width 0.10795)
		(layer "F.Cu")
		(net "LED_POSTCODE_3_R")
	)
	(segment
		(start 492.68888 -145.161)
		(end 494.000028 -143.849852)
		(width 0.10795)
		(layer "F.Cu")
		(net "LED_POSTCODE_3_R")
	)
	(segment
		(start 490.416088 -144.50568)
		(end 490.74832 -144.50568)
		(width 0.10795)
		(layer "F.Cu")
		(net "LED_POSTCODE_3_R")
	)
	(segment
		(start 490.806232 -145.161)
		(end 492.68888 -145.161)
		(width 0.10795)
		(layer "F.Cu")
		(net "LED_POSTCODE_3_R")
	)
	(via
		(at 491.9726 -144.272)
		(size 0.508)
		(drill 0.254)
		(layers "F.Cu" "B.Cu")
		(net "LED_POSTCODE_3_R")
	)
	(via
		(at 492.2012 -139.6238)
		(size 0.508)
		(drill 0.254)
		(layers "F.Cu" "B.Cu")
		(net "LED_POSTCODE_3_R")
	)
	(segment
		(start 481.0252 -138.4808)
		(end 481.0252 -138.1252)
		(width 0.10795)
		(layer "B.Cu")
		(net "LED_POSTCODE_3_R")
	)
	(segment
		(start 481.0506 -138.5062)
		(end 481.0252 -138.4808)
		(width 0.10795)
		(layer "B.Cu")
		(net "LED_POSTCODE_3_R")
	)
	(segment
		(start 479.299016 -140.387832)
		(end 480.132644 -140.387832)
		(width 0.10795)
		(layer "B.Cu")
		(net "LED_POSTCODE_3_R")
	)
	(segment
		(start 481.0252 -138.1252)
		(end 481.0506 -138.0998)
		(width 0.10795)
		(layer "B.Cu")
		(net "LED_POSTCODE_3_R")
	)
	(segment
		(start 481.0506 -138.0998)
		(end 481.0506 -138.049)
		(width 0.10795)
		(layer "B.Cu")
		(net "LED_POSTCODE_3_R")
	)
	(segment
		(start 481.0506 -138.743436)
		(end 481.0506 -138.5062)
		(width 0.10795)
		(layer "B.Cu")
		(net "LED_POSTCODE_3_R")
	)
	(segment
		(start 491.5916 -139.0142)
		(end 492.2012 -139.6238)
		(width 0.10795)
		(layer "B.Cu")
		(net "LED_POSTCODE_3_R")
	)
	(segment
		(start 491.5916 -137.998454)
		(end 491.5916 -139.0142)
		(width 0.10795)
		(layer "B.Cu")
		(net "LED_POSTCODE_3_R")
	)
	(segment
		(start 481.0506 -138.049)
		(end 482.1682 -136.9314)
		(width 0.10795)
		(layer "B.Cu")
		(net "LED_POSTCODE_3_R")
	)
	(segment
		(start 490.524546 -136.9314)
		(end 491.5916 -137.998454)
		(width 0.10795)
		(layer "B.Cu")
		(net "LED_POSTCODE_3_R")
	)
	(segment
		(start 480.132644 -140.387832)
		(end 480.59975 -139.920726)
		(width 0.10795)
		(layer "B.Cu")
		(net "LED_POSTCODE_3_R")
	)
	(segment
		(start 480.59975 -139.920726)
		(end 480.59975 -139.194286)
		(width 0.10795)
		(layer "B.Cu")
		(net "LED_POSTCODE_3_R")
	)
	(segment
		(start 480.59975 -139.194286)
		(end 481.0506 -138.743436)
		(width 0.10795)
		(layer "B.Cu")
		(net "LED_POSTCODE_3_R")
	)
	(segment
		(start 482.1682 -136.9314)
		(end 490.524546 -136.9314)
		(width 0.10795)
		(layer "B.Cu")
		(net "LED_POSTCODE_3_R")
	)
	(segment
		(start 492.7092 -142.875)
		(end 491.9726 -143.6116)
		(width 0.089408)
		(layer "In9.Cu")
		(net "LED_POSTCODE_3_R")
	)
	(segment
		(start 492.2012 -139.6238)
		(end 492.7092 -140.1318)
		(width 0.089408)
		(layer "In9.Cu")
		(net "LED_POSTCODE_3_R")
	)
	(segment
		(start 491.9726 -143.6116)
		(end 491.9726 -144.272)
		(width 0.089408)
		(layer "In9.Cu")
		(net "LED_POSTCODE_3_R")
	)
	(segment
		(start 492.7092 -140.1318)
		(end 492.7092 -142.875)
		(width 0.089408)
		(layer "In9.Cu")
		(net "LED_POSTCODE_3_R")
	)
	(segment
		(start 491.363 -143.891)
		(end 490.2835 -143.891)
		(width 0.10795)
		(layer "F.Cu")
		(net "LED_POSTCODE_2_R")
	)
	(segment
		(start 490.2835 -143.876268)
		(end 490.2835 -143.4719)
		(width 0.10795)
		(layer "F.Cu")
		(net "LED_POSTCODE_2_R")
	)
	(segment
		(start 490.2835 -143.4719)
		(end 490.4232 -143.3322)
		(width 0.10795)
		(layer "F.Cu")
		(net "LED_POSTCODE_2_R")
	)
	(segment
		(start 495.050572 -142.9004)
		(end 492.3536 -142.9004)
		(width 0.10795)
		(layer "F.Cu")
		(net "LED_POSTCODE_2_R")
	)
	(segment
		(start 492.3536 -142.9004)
		(end 491.363 -143.891)
		(width 0.10795)
		(layer "F.Cu")
		(net "LED_POSTCODE_2_R")
	)
	(segment
		(start 490.2835 -143.891)
		(end 490.2835 -143.876268)
		(width 0.10795)
		(layer "F.Cu")
		(net "LED_POSTCODE_2_R")
	)
	(segment
		(start 490.4232 -143.3322)
		(end 490.9312 -143.3322)
		(width 0.10795)
		(layer "F.Cu")
		(net "LED_POSTCODE_2_R")
	)
	(segment
		(start 496.000024 -143.849852)
		(end 495.050572 -142.9004)
		(width 0.10795)
		(layer "F.Cu")
		(net "LED_POSTCODE_2_R")
	)
	(via
		(at 490.9312 -143.3322)
		(size 0.508)
		(drill 0.254)
		(layers "F.Cu" "B.Cu")
		(net "LED_POSTCODE_2_R")
	)
	(via
		(at 491.5916 -139.9032)
		(size 0.508)
		(drill 0.254)
		(layers "F.Cu" "B.Cu")
		(net "LED_POSTCODE_2_R")
	)
	(via
		(at 486.43159 -137.1854)
		(size 0.508)
		(drill 0.254)
		(layers "F.Cu" "B.Cu")
		(net "LED_POSTCODE_2_R")
	)
	(segment
		(start 480.8093 -139.281154)
		(end 480.8093 -140.348716)
		(width 0.10795)
		(layer "B.Cu")
		(net "LED_POSTCODE_2_R")
	)
	(segment
		(start 481.26015 -138.830304)
		(end 480.8093 -139.281154)
		(width 0.10795)
		(layer "B.Cu")
		(net "LED_POSTCODE_2_R")
	)
	(segment
		(start 481.26015 -138.16584)
		(end 481.26015 -138.19505)
		(width 0.10795)
		(layer "B.Cu")
		(net "LED_POSTCODE_2_R")
	)
	(segment
		(start 491.363 -138.0998)
		(end 490.4486 -137.1854)
		(width 0.10795)
		(layer "B.Cu")
		(net "LED_POSTCODE_2_R")
	)
	(segment
		(start 486.43159 -137.1854)
		(end 482.24059 -137.1854)
		(width 0.10795)
		(layer "B.Cu")
		(net "LED_POSTCODE_2_R")
	)
	(segment
		(start 481.2538 -138.4046)
		(end 481.26015 -138.41095)
		(width 0.10795)
		(layer "B.Cu")
		(net "LED_POSTCODE_2_R")
	)
	(segment
		(start 491.5916 -139.9032)
		(end 491.363 -139.6746)
		(width 0.10795)
		(layer "B.Cu")
		(net "LED_POSTCODE_2_R")
	)
	(segment
		(start 491.363 -139.6746)
		(end 491.363 -138.0998)
		(width 0.10795)
		(layer "B.Cu")
		(net "LED_POSTCODE_2_R")
	)
	(segment
		(start 482.24059 -137.1854)
		(end 481.26015 -138.16584)
		(width 0.10795)
		(layer "B.Cu")
		(net "LED_POSTCODE_2_R")
	)
	(segment
		(start 481.2538 -138.2014)
		(end 481.2538 -138.4046)
		(width 0.10795)
		(layer "B.Cu")
		(net "LED_POSTCODE_2_R")
	)
	(segment
		(start 481.26015 -138.19505)
		(end 481.2538 -138.2014)
		(width 0.10795)
		(layer "B.Cu")
		(net "LED_POSTCODE_2_R")
	)
	(segment
		(start 480.8093 -140.348716)
		(end 480.119944 -141.038072)
		(width 0.10795)
		(layer "B.Cu")
		(net "LED_POSTCODE_2_R")
	)
	(segment
		(start 490.4486 -137.1854)
		(end 486.43159 -137.1854)
		(width 0.10795)
		(layer "B.Cu")
		(net "LED_POSTCODE_2_R")
	)
	(segment
		(start 481.26015 -138.41095)
		(end 481.26015 -138.830304)
		(width 0.10795)
		(layer "B.Cu")
		(net "LED_POSTCODE_2_R")
	)
	(segment
		(start 480.119944 -141.038072)
		(end 479.299016 -141.038072)
		(width 0.10795)
		(layer "B.Cu")
		(net "LED_POSTCODE_2_R")
	)
	(segment
		(start 491.371128 -143.3322)
		(end 490.9312 -143.3322)
		(width 0.089408)
		(layer "In9.Cu")
		(net "LED_POSTCODE_2_R")
	)
	(segment
		(start 491.5916 -139.9032)
		(end 491.885986 -140.197586)
		(width 0.089408)
		(layer "In9.Cu")
		(net "LED_POSTCODE_2_R")
	)
	(segment
		(start 491.885986 -140.197586)
		(end 491.885986 -142.817342)
		(width 0.089408)
		(layer "In9.Cu")
		(net "LED_POSTCODE_2_R")
	)
	(segment
		(start 491.885986 -142.817342)
		(end 491.371128 -143.3322)
		(width 0.089408)
		(layer "In9.Cu")
		(net "LED_POSTCODE_2_R")
	)
	(segment
		(start 494.157 -139.6746)
		(end 494.000028 -139.831572)
		(width 0.10795)
		(layer "F.Cu")
		(net "LED_POSTCODE_1_R")
	)
	(segment
		(start 494.000028 -139.831572)
		(end 494.000028 -141.849856)
		(width 0.10795)
		(layer "F.Cu")
		(net "LED_POSTCODE_1_R")
	)
	(segment
		(start 494.2586 -139.6746)
		(end 494.157 -139.6746)
		(width 0.10795)
		(layer "F.Cu")
		(net "LED_POSTCODE_1_R")
	)
	(via
		(at 494.2586 -139.6746)
		(size 0.508)
		(drill 0.254)
		(layers "F.Cu" "B.Cu")
		(net "LED_POSTCODE_1_R")
	)
	(via
		(at 484.70693 -137.4267)
		(size 0.508)
		(drill 0.254)
		(layers "F.Cu" "B.Cu")
		(net "LED_POSTCODE_1_R")
	)
	(segment
		(start 494.6904 -139.8778)
		(end 494.6904 -138.8618)
		(width 0.10795)
		(layer "B.Cu")
		(net "LED_POSTCODE_1_R")
	)
	(segment
		(start 491.1344 -140.106654)
		(end 491.413546 -140.3858)
		(width 0.10795)
		(layer "B.Cu")
		(net "LED_POSTCODE_1_R")
	)
	(segment
		(start 481.4697 -138.307572)
		(end 482.363272 -137.414)
		(width 0.10795)
		(layer "B.Cu")
		(net "LED_POSTCODE_1_R")
	)
	(segment
		(start 481.0379 -139.348972)
		(end 481.4697 -138.917172)
		(width 0.10795)
		(layer "B.Cu")
		(net "LED_POSTCODE_1_R")
	)
	(segment
		(start 480.103688 -141.688312)
		(end 481.0379 -140.7541)
		(width 0.10795)
		(layer "B.Cu")
		(net "LED_POSTCODE_1_R")
	)
	(segment
		(start 484.70693 -137.4267)
		(end 490.384846 -137.4267)
		(width 0.10795)
		(layer "B.Cu")
		(net "LED_POSTCODE_1_R")
	)
	(segment
		(start 491.1344 -138.176254)
		(end 491.1344 -140.106654)
		(width 0.10795)
		(layer "B.Cu")
		(net "LED_POSTCODE_1_R")
	)
	(segment
		(start 494.6904 -138.8618)
		(end 494.4872 -138.6586)
		(width 0.10795)
		(layer "B.Cu")
		(net "LED_POSTCODE_1_R")
	)
	(segment
		(start 481.0379 -140.7541)
		(end 481.0379 -139.348972)
		(width 0.10795)
		(layer "B.Cu")
		(net "LED_POSTCODE_1_R")
	)
	(segment
		(start 494.4872 -138.6586)
		(end 494.2586 -138.8872)
		(width 0.10795)
		(layer "B.Cu")
		(net "LED_POSTCODE_1_R")
	)
	(segment
		(start 481.4697 -138.917172)
		(end 481.4697 -138.307572)
		(width 0.10795)
		(layer "B.Cu")
		(net "LED_POSTCODE_1_R")
	)
	(segment
		(start 490.384846 -137.4267)
		(end 491.1344 -138.176254)
		(width 0.10795)
		(layer "B.Cu")
		(net "LED_POSTCODE_1_R")
	)
	(segment
		(start 482.363272 -137.414)
		(end 484.69423 -137.414)
		(width 0.10795)
		(layer "B.Cu")
		(net "LED_POSTCODE_1_R")
	)
	(segment
		(start 494.2586 -138.8872)
		(end 494.2586 -139.6746)
		(width 0.10795)
		(layer "B.Cu")
		(net "LED_POSTCODE_1_R")
	)
	(segment
		(start 491.413546 -140.3858)
		(end 494.1824 -140.3858)
		(width 0.10795)
		(layer "B.Cu")
		(net "LED_POSTCODE_1_R")
	)
	(segment
		(start 479.299016 -141.688312)
		(end 480.103688 -141.688312)
		(width 0.10795)
		(layer "B.Cu")
		(net "LED_POSTCODE_1_R")
	)
	(segment
		(start 484.69423 -137.414)
		(end 484.70693 -137.4267)
		(width 0.10795)
		(layer "B.Cu")
		(net "LED_POSTCODE_1_R")
	)
	(segment
		(start 494.1824 -140.3858)
		(end 494.6904 -139.8778)
		(width 0.10795)
		(layer "B.Cu")
		(net "LED_POSTCODE_1_R")
	)
	(via
		(at 483.024434 -137.668)
		(size 0.508)
		(drill 0.254)
		(layers "F.Cu" "B.Cu")
		(net "LED_POSTCODE_0_R")
	)
	(segment
		(start 481.2792 -140.8938)
		(end 481.2792 -139.4206)
		(width 0.10795)
		(layer "B.Cu")
		(net "LED_POSTCODE_0_R")
	)
	(segment
		(start 482.4222 -137.668)
		(end 483.024434 -137.668)
		(width 0.10795)
		(layer "B.Cu")
		(net "LED_POSTCODE_0_R")
	)
	(segment
		(start 481.2792 -139.4206)
		(end 481.6856 -139.0142)
		(width 0.10795)
		(layer "B.Cu")
		(net "LED_POSTCODE_0_R")
	)
	(segment
		(start 495.7572 -140.7668)
		(end 496.000024 -141.009624)
		(width 0.10795)
		(layer "B.Cu")
		(net "LED_POSTCODE_0_R")
	)
	(segment
		(start 479.299016 -142.338552)
		(end 479.834448 -142.338552)
		(width 0.10795)
		(layer "B.Cu")
		(net "LED_POSTCODE_0_R")
	)
	(segment
		(start 494.5634 -140.6652)
		(end 495.2492 -139.9794)
		(width 0.10795)
		(layer "B.Cu")
		(net "LED_POSTCODE_0_R")
	)
	(segment
		(start 495.2492 -138.6459)
		(end 495.6175 -138.6459)
		(width 0.10795)
		(layer "B.Cu")
		(net "LED_POSTCODE_0_R")
	)
	(segment
		(start 491.3884 -140.6652)
		(end 494.5634 -140.6652)
		(width 0.10795)
		(layer "B.Cu")
		(net "LED_POSTCODE_0_R")
	)
	(segment
		(start 481.6856 -138.4046)
		(end 482.4222 -137.668)
		(width 0.10795)
		(layer "B.Cu")
		(net "LED_POSTCODE_0_R")
	)
	(segment
		(start 490.2962 -137.668)
		(end 490.8804 -138.2522)
		(width 0.10795)
		(layer "B.Cu")
		(net "LED_POSTCODE_0_R")
	)
	(segment
		(start 490.8804 -140.1572)
		(end 491.3884 -140.6652)
		(width 0.10795)
		(layer "B.Cu")
		(net "LED_POSTCODE_0_R")
	)
	(segment
		(start 490.8804 -138.2522)
		(end 490.8804 -140.1572)
		(width 0.10795)
		(layer "B.Cu")
		(net "LED_POSTCODE_0_R")
	)
	(segment
		(start 481.6856 -139.0142)
		(end 481.6856 -138.4046)
		(width 0.10795)
		(layer "B.Cu")
		(net "LED_POSTCODE_0_R")
	)
	(segment
		(start 496.000024 -141.009624)
		(end 496.000024 -141.849856)
		(width 0.10795)
		(layer "B.Cu")
		(net "LED_POSTCODE_0_R")
	)
	(segment
		(start 483.024434 -137.668)
		(end 490.2962 -137.668)
		(width 0.10795)
		(layer "B.Cu")
		(net "LED_POSTCODE_0_R")
	)
	(segment
		(start 495.6175 -138.6459)
		(end 495.7572 -138.7856)
		(width 0.10795)
		(layer "B.Cu")
		(net "LED_POSTCODE_0_R")
	)
	(segment
		(start 495.7572 -138.7856)
		(end 495.7572 -140.7668)
		(width 0.10795)
		(layer "B.Cu")
		(net "LED_POSTCODE_0_R")
	)
	(segment
		(start 479.834448 -142.338552)
		(end 481.2792 -140.8938)
		(width 0.10795)
		(layer "B.Cu")
		(net "LED_POSTCODE_0_R")
	)
	(segment
		(start 495.2492 -139.9794)
		(end 495.2492 -138.6459)
		(width 0.10795)
		(layer "B.Cu")
		(net "LED_POSTCODE_0_R")
	)
	(segment
		(start 381.79375 -98.69424)
		(end 382.1684 -98.52025)
		(width 0.10795)
		(layer "F.Cu")
		(net "H_PM_SYNC1_GTL_R")
	)
	(segment
		(start 382.1684 -98.52025)
		(end 382.28905 -98.464116)
		(width 0.10795)
		(layer "F.Cu")
		(net "H_PM_SYNC1_GTL_R")
	)
	(via
		(at 378.714 -93.392498)
		(size 0.6604)
		(drill 0.3302)
		(layers "F.Cu" "B.Cu")
		(net "H_PM_SYNC1_GTL_R")
	)
	(via
		(at 382.28905 -98.464116)
		(size 0.508)
		(drill 0.254)
		(layers "F.Cu" "B.Cu")
		(net "H_PM_SYNC1_GTL_R")
	)
	(segment
		(start 377.421902 -93.068902)
		(end 377.745498 -93.392498)
		(width 0.10795)
		(layer "B.Cu")
		(net "H_PM_SYNC1_GTL_R")
	)
	(segment
		(start 382.1938 -97.627186)
		(end 382.1938 -97.59442)
		(width 0.0889)
		(layer "B.Cu")
		(net "H_PM_SYNC1_GTL_R")
	)
	(segment
		(start 382.6891 -98.475292)
		(end 382.6891 -98.45294)
		(width 0.0889)
		(layer "B.Cu")
		(net "H_PM_SYNC1_GTL_R")
	)
	(segment
		(start 380.862078 -95.273622)
		(end 379.712728 -94.124272)
		(width 0.10795)
		(layer "B.Cu")
		(net "H_PM_SYNC1_GTL_R")
	)
	(segment
		(start 376.14606 -89.4715)
		(end 376.46356 -89.789)
		(width 0.10795)
		(layer "B.Cu")
		(net "H_PM_SYNC1_GTL_R")
	)
	(segment
		(start 382.45796 -98.757232)
		(end 382.5367 -98.778314)
		(width 0.0889)
		(layer "B.Cu")
		(net "H_PM_SYNC1_GTL_R")
	)
	(segment
		(start 382.28905 -98.464116)
		(end 382.45796 -98.757232)
		(width 0.0889)
		(layer "B.Cu")
		(net "H_PM_SYNC1_GTL_R")
	)
	(segment
		(start 381.2032 -95.910146)
		(end 381.2032 -95.614744)
		(width 0.0889)
		(layer "B.Cu")
		(net "H_PM_SYNC1_GTL_R")
	)
	(segment
		(start 379.445774 -94.124272)
		(end 378.714 -93.392498)
		(width 0.10795)
		(layer "B.Cu")
		(net "H_PM_SYNC1_GTL_R")
	)
	(segment
		(start 376.673618 -89.789)
		(end 377.421902 -90.537284)
		(width 0.10795)
		(layer "B.Cu")
		(net "H_PM_SYNC1_GTL_R")
	)
	(segment
		(start 381.6985 -96.768666)
		(end 381.6985 -96.7359)
		(width 0.0889)
		(layer "B.Cu")
		(net "H_PM_SYNC1_GTL_R")
	)
	(segment
		(start 377.421902 -90.537284)
		(end 377.421902 -93.068902)
		(width 0.10795)
		(layer "B.Cu")
		(net "H_PM_SYNC1_GTL_R")
	)
	(segment
		(start 375.285 -89.4715)
		(end 376.14606 -89.4715)
		(width 0.10795)
		(layer "B.Cu")
		(net "H_PM_SYNC1_GTL_R")
	)
	(segment
		(start 381.2032 -95.614744)
		(end 380.862078 -95.273622)
		(width 0.0889)
		(layer "B.Cu")
		(net "H_PM_SYNC1_GTL_R")
	)
	(segment
		(start 377.745498 -93.392498)
		(end 378.714 -93.392498)
		(width 0.10795)
		(layer "B.Cu")
		(net "H_PM_SYNC1_GTL_R")
	)
	(segment
		(start 379.712728 -94.124272)
		(end 379.445774 -94.124272)
		(width 0.10795)
		(layer "B.Cu")
		(net "H_PM_SYNC1_GTL_R")
	)
	(segment
		(start 376.46356 -89.789)
		(end 376.673618 -89.789)
		(width 0.10795)
		(layer "B.Cu")
		(net "H_PM_SYNC1_GTL_R")
	)
	(arc
		(start 381.6985 -96.7359)
		(mid 381.64215 -96.54205)
		(end 381.498348 -96.400366)
		(width 0.0889)
		(layer "B.Cu")
		(net "H_PM_SYNC1_GTL_R")
	)
	(arc
		(start 382.1938 -97.59442)
		(mid 382.13745 -97.40057)
		(end 381.993648 -97.258886)
		(width 0.0889)
		(layer "B.Cu")
		(net "H_PM_SYNC1_GTL_R")
	)
	(arc
		(start 382.5367 -98.778314)
		(mid 382.646612 -98.643752)
		(end 382.6891 -98.475292)
		(width 0.0889)
		(layer "B.Cu")
		(net "H_PM_SYNC1_GTL_R")
	)
	(arc
		(start 381.498348 -96.400366)
		(mid 381.287484 -96.193362)
		(end 381.2032 -95.910146)
		(width 0.0889)
		(layer "B.Cu")
		(net "H_PM_SYNC1_GTL_R")
	)
	(arc
		(start 382.488948 -98.117406)
		(mid 382.278084 -97.910402)
		(end 382.1938 -97.627186)
		(width 0.0889)
		(layer "B.Cu")
		(net "H_PM_SYNC1_GTL_R")
	)
	(arc
		(start 381.993648 -97.258886)
		(mid 381.782784 -97.051882)
		(end 381.6985 -96.768666)
		(width 0.0889)
		(layer "B.Cu")
		(net "H_PM_SYNC1_GTL_R")
	)
	(arc
		(start 382.6891 -98.45294)
		(mid 382.63275 -98.25909)
		(end 382.488948 -98.117406)
		(width 0.0889)
		(layer "B.Cu")
		(net "H_PM_SYNC1_GTL_R")
	)
	(via
		(at 492.9632 -136.4742)
		(size 0.508)
		(drill 0.254)
		(layers "F.Cu" "B.Cu")
		(net "LED_POSTCODE_7_R")
	)
	(via
		(at 491.5916 -148.082)
		(size 0.508)
		(drill 0.254)
		(layers "F.Cu" "B.Cu")
		(net "LED_POSTCODE_7_R")
	)
	(segment
		(start 494.000028 -147.849844)
		(end 493.259872 -148.59)
		(width 0.10795)
		(layer "B.Cu")
		(net "LED_POSTCODE_7_R")
	)
	(segment
		(start 490.5375 -148.48205)
		(end 490.5375 -148.082)
		(width 0.10795)
		(layer "B.Cu")
		(net "LED_POSTCODE_7_R")
	)
	(segment
		(start 480.1362 -137.786872)
		(end 480.1362 -137.7442)
		(width 0.10795)
		(layer "B.Cu")
		(net "LED_POSTCODE_7_R")
	)
	(segment
		(start 481.838 -136.0424)
		(end 492.5314 -136.0424)
		(width 0.10795)
		(layer "B.Cu")
		(net "LED_POSTCODE_7_R")
	)
	(segment
		(start 491.5916 -148.082)
		(end 490.54639 -148.082)
		(width 0.10795)
		(layer "B.Cu")
		(net "LED_POSTCODE_7_R")
	)
	(segment
		(start 479.299016 -137.786872)
		(end 480.1362 -137.786872)
		(width 0.10795)
		(layer "B.Cu")
		(net "LED_POSTCODE_7_R")
	)
	(segment
		(start 480.1362 -137.7442)
		(end 481.838 -136.0424)
		(width 0.10795)
		(layer "B.Cu")
		(net "LED_POSTCODE_7_R")
	)
	(segment
		(start 490.64545 -148.59)
		(end 490.5375 -148.48205)
		(width 0.10795)
		(layer "B.Cu")
		(net "LED_POSTCODE_7_R")
	)
	(segment
		(start 493.259872 -148.59)
		(end 490.64545 -148.59)
		(width 0.10795)
		(layer "B.Cu")
		(net "LED_POSTCODE_7_R")
	)
	(segment
		(start 492.5314 -136.0424)
		(end 492.9632 -136.4742)
		(width 0.10795)
		(layer "B.Cu")
		(net "LED_POSTCODE_7_R")
	)
	(segment
		(start 490.5375 -148.082)
		(end 490.54639 -148.082)
		(width 0.10795)
		(layer "B.Cu")
		(net "LED_POSTCODE_7_R")
	)
	(segment
		(start 490.474 -138.304778)
		(end 490.474 -142.17396)
		(width 0.089408)
		(layer "In9.Cu")
		(net "LED_POSTCODE_7_R")
	)
	(segment
		(start 490.474 -142.17396)
		(end 489.957872 -142.690088)
		(width 0.089408)
		(layer "In9.Cu")
		(net "LED_POSTCODE_7_R")
	)
	(segment
		(start 489.957872 -146.448272)
		(end 491.5916 -148.082)
		(width 0.089408)
		(layer "In9.Cu")
		(net "LED_POSTCODE_7_R")
	)
	(segment
		(start 492.9124 -136.4234)
		(end 492.355378 -136.4234)
		(width 0.089408)
		(layer "In9.Cu")
		(net "LED_POSTCODE_7_R")
	)
	(segment
		(start 489.957872 -142.690088)
		(end 489.957872 -146.448272)
		(width 0.089408)
		(layer "In9.Cu")
		(net "LED_POSTCODE_7_R")
	)
	(segment
		(start 492.9632 -136.4742)
		(end 492.9124 -136.4234)
		(width 0.089408)
		(layer "In9.Cu")
		(net "LED_POSTCODE_7_R")
	)
	(segment
		(start 492.355378 -136.4234)
		(end 490.474 -138.304778)
		(width 0.089408)
		(layer "In9.Cu")
		(net "LED_POSTCODE_7_R")
	)
	(via
		(at 492.6838 -137.3886)
		(size 0.508)
		(drill 0.254)
		(layers "F.Cu" "B.Cu")
		(net "LED_POSTCODE_6_R")
	)
	(via
		(at 491.2868 -146.7358)
		(size 0.508)
		(drill 0.254)
		(layers "F.Cu" "B.Cu")
		(net "LED_POSTCODE_6_R")
	)
	(segment
		(start 480.3648 -137.8204)
		(end 480.3648 -137.8712)
		(width 0.10795)
		(layer "B.Cu")
		(net "LED_POSTCODE_6_R")
	)
	(segment
		(start 491.5662 -136.271)
		(end 481.9142 -136.271)
		(width 0.10795)
		(layer "B.Cu")
		(net "LED_POSTCODE_6_R")
	)
	(segment
		(start 495.01298 -146.8628)
		(end 496.000024 -147.849844)
		(width 0.10795)
		(layer "B.Cu")
		(net "LED_POSTCODE_6_R")
	)
	(segment
		(start 490.87659 -147.5232)
		(end 492.6584 -147.5232)
		(width 0.10795)
		(layer "B.Cu")
		(net "LED_POSTCODE_6_R")
	)
	(segment
		(start 480.3648 -137.8712)
		(end 480.3394 -137.8966)
		(width 0.10795)
		(layer "B.Cu")
		(net "LED_POSTCODE_6_R")
	)
	(segment
		(start 492.6584 -147.5232)
		(end 493.3188 -146.8628)
		(width 0.10795)
		(layer "B.Cu")
		(net "LED_POSTCODE_6_R")
	)
	(segment
		(start 492.6838 -137.3886)
		(end 491.5662 -136.271)
		(width 0.10795)
		(layer "B.Cu")
		(net "LED_POSTCODE_6_R")
	)
	(segment
		(start 480.179888 -138.437112)
		(end 479.299016 -138.437112)
		(width 0.10795)
		(layer "B.Cu")
		(net "LED_POSTCODE_6_R")
	)
	(segment
		(start 481.9142 -136.271)
		(end 480.3648 -137.8204)
		(width 0.10795)
		(layer "B.Cu")
		(net "LED_POSTCODE_6_R")
	)
	(segment
		(start 480.3394 -137.8966)
		(end 480.3394 -138.2776)
		(width 0.10795)
		(layer "B.Cu")
		(net "LED_POSTCODE_6_R")
	)
	(segment
		(start 490.54639 -147.193)
		(end 490.87659 -147.5232)
		(width 0.10795)
		(layer "B.Cu")
		(net "LED_POSTCODE_6_R")
	)
	(segment
		(start 493.3188 -146.8628)
		(end 495.01298 -146.8628)
		(width 0.10795)
		(layer "B.Cu")
		(net "LED_POSTCODE_6_R")
	)
	(segment
		(start 480.3394 -138.2776)
		(end 480.179888 -138.437112)
		(width 0.10795)
		(layer "B.Cu")
		(net "LED_POSTCODE_6_R")
	)
	(segment
		(start 490.84738 -146.7358)
		(end 490.54639 -147.03679)
		(width 0.10795)
		(layer "B.Cu")
		(net "LED_POSTCODE_6_R")
	)
	(segment
		(start 491.2868 -146.7358)
		(end 490.84738 -146.7358)
		(width 0.10795)
		(layer "B.Cu")
		(net "LED_POSTCODE_6_R")
	)
	(segment
		(start 490.54639 -147.03679)
		(end 490.54639 -147.193)
		(width 0.10795)
		(layer "B.Cu")
		(net "LED_POSTCODE_6_R")
	)
	(segment
		(start 492.6838 -137.3886)
		(end 492.6838 -136.868408)
		(width 0.089408)
		(layer "In9.Cu")
		(net "LED_POSTCODE_6_R")
	)
	(segment
		(start 490.14888 -145.59788)
		(end 491.2868 -146.7358)
		(width 0.089408)
		(layer "In9.Cu")
		(net "LED_POSTCODE_6_R")
	)
	(segment
		(start 490.665262 -142.252954)
		(end 490.14888 -142.769336)
		(width 0.089408)
		(layer "In9.Cu")
		(net "LED_POSTCODE_6_R")
	)
	(segment
		(start 490.14888 -142.769336)
		(end 490.14888 -145.59788)
		(width 0.089408)
		(layer "In9.Cu")
		(net "LED_POSTCODE_6_R")
	)
	(segment
		(start 490.665262 -138.383772)
		(end 490.665262 -142.252954)
		(width 0.089408)
		(layer "In9.Cu")
		(net "LED_POSTCODE_6_R")
	)
	(segment
		(start 492.6838 -136.868408)
		(end 492.594392 -136.779)
		(width 0.089408)
		(layer "In9.Cu")
		(net "LED_POSTCODE_6_R")
	)
	(segment
		(start 492.594392 -136.779)
		(end 492.270034 -136.779)
		(width 0.089408)
		(layer "In9.Cu")
		(net "LED_POSTCODE_6_R")
	)
	(segment
		(start 492.270034 -136.779)
		(end 490.665262 -138.383772)
		(width 0.089408)
		(layer "In9.Cu")
		(net "LED_POSTCODE_6_R")
	)
	(via
		(at 492.0742 -137.5664)
		(size 0.508)
		(drill 0.254)
		(layers "F.Cu" "B.Cu")
		(net "LED_POSTCODE_5_R")
	)
	(via
		(at 491.2868 -145.7198)
		(size 0.508)
		(drill 0.254)
		(layers "F.Cu" "B.Cu")
		(net "LED_POSTCODE_5_R")
	)
	(segment
		(start 491.0074 -136.4996)
		(end 481.9904 -136.4996)
		(width 0.10795)
		(layer "B.Cu")
		(net "LED_POSTCODE_5_R")
	)
	(segment
		(start 480.5934 -137.9474)
		(end 480.568 -137.9728)
		(width 0.10795)
		(layer "B.Cu")
		(net "LED_POSTCODE_5_R")
	)
	(segment
		(start 480.1616 -139.0142)
		(end 480.1616 -139.0396)
		(width 0.10795)
		(layer "B.Cu")
		(net "LED_POSTCODE_5_R")
	)
	(segment
		(start 480.568 -138.6078)
		(end 480.1616 -139.0142)
		(width 0.10795)
		(layer "B.Cu")
		(net "LED_POSTCODE_5_R")
	)
	(segment
		(start 494.000028 -145.849848)
		(end 493.545876 -146.304)
		(width 0.10795)
		(layer "B.Cu")
		(net "LED_POSTCODE_5_R")
	)
	(segment
		(start 490.65434 -145.7198)
		(end 491.2868 -145.7198)
		(width 0.10795)
		(layer "B.Cu")
		(net "LED_POSTCODE_5_R")
	)
	(segment
		(start 480.113848 -139.087352)
		(end 479.299016 -139.087352)
		(width 0.10795)
		(layer "B.Cu")
		(net "LED_POSTCODE_5_R")
	)
	(segment
		(start 490.54639 -146.177)
		(end 490.54639 -145.82775)
		(width 0.10795)
		(layer "B.Cu")
		(net "LED_POSTCODE_5_R")
	)
	(segment
		(start 492.0742 -137.5664)
		(end 491.0074 -136.4996)
		(width 0.10795)
		(layer "B.Cu")
		(net "LED_POSTCODE_5_R")
	)
	(segment
		(start 480.568 -137.9728)
		(end 480.568 -138.6078)
		(width 0.10795)
		(layer "B.Cu")
		(net "LED_POSTCODE_5_R")
	)
	(segment
		(start 480.1616 -139.0396)
		(end 480.113848 -139.087352)
		(width 0.10795)
		(layer "B.Cu")
		(net "LED_POSTCODE_5_R")
	)
	(segment
		(start 490.54639 -145.82775)
		(end 490.65434 -145.7198)
		(width 0.10795)
		(layer "B.Cu")
		(net "LED_POSTCODE_5_R")
	)
	(segment
		(start 490.67339 -146.304)
		(end 490.54639 -146.177)
		(width 0.10795)
		(layer "B.Cu")
		(net "LED_POSTCODE_5_R")
	)
	(segment
		(start 481.9904 -136.4996)
		(end 480.5934 -137.8966)
		(width 0.10795)
		(layer "B.Cu")
		(net "LED_POSTCODE_5_R")
	)
	(segment
		(start 493.545876 -146.304)
		(end 490.67339 -146.304)
		(width 0.10795)
		(layer "B.Cu")
		(net "LED_POSTCODE_5_R")
	)
	(segment
		(start 480.5934 -137.8966)
		(end 480.5934 -137.9474)
		(width 0.10795)
		(layer "B.Cu")
		(net "LED_POSTCODE_5_R")
	)
	(segment
		(start 490.85627 -138.506962)
		(end 490.85627 -142.332202)
		(width 0.089408)
		(layer "In9.Cu")
		(net "LED_POSTCODE_5_R")
	)
	(segment
		(start 490.339888 -144.772888)
		(end 491.2868 -145.7198)
		(width 0.089408)
		(layer "In9.Cu")
		(net "LED_POSTCODE_5_R")
	)
	(segment
		(start 490.339888 -142.848584)
		(end 490.339888 -144.772888)
		(width 0.089408)
		(layer "In9.Cu")
		(net "LED_POSTCODE_5_R")
	)
	(segment
		(start 490.85627 -142.332202)
		(end 490.339888 -142.848584)
		(width 0.089408)
		(layer "In9.Cu")
		(net "LED_POSTCODE_5_R")
	)
	(segment
		(start 491.87227 -137.490962)
		(end 490.85627 -138.506962)
		(width 0.089408)
		(layer "In9.Cu")
		(net "LED_POSTCODE_5_R")
	)
	(segment
		(start 492.0742 -137.5664)
		(end 491.998762 -137.490962)
		(width 0.089408)
		(layer "In9.Cu")
		(net "LED_POSTCODE_5_R")
	)
	(segment
		(start 491.998762 -137.490962)
		(end 491.87227 -137.490962)
		(width 0.089408)
		(layer "In9.Cu")
		(net "LED_POSTCODE_5_R")
	)
	(via
		(at 491.3376 -144.6276)
		(size 0.508)
		(drill 0.254)
		(layers "F.Cu" "B.Cu")
		(net "LED_POSTCODE_4_R")
	)
	(via
		(at 492.0488 -138.4554)
		(size 0.508)
		(drill 0.254)
		(layers "F.Cu" "B.Cu")
		(net "LED_POSTCODE_4_R")
	)
	(segment
		(start 495.006376 -144.8562)
		(end 492.594392 -144.8562)
		(width 0.10795)
		(layer "B.Cu")
		(net "LED_POSTCODE_4_R")
	)
	(segment
		(start 480.7966 -138.557)
		(end 480.7966 -138.049)
		(width 0.10795)
		(layer "B.Cu")
		(net "LED_POSTCODE_4_R")
	)
	(segment
		(start 491.8456 -137.9474)
		(end 491.8456 -138.2522)
		(width 0.10795)
		(layer "B.Cu")
		(net "LED_POSTCODE_4_R")
	)
	(segment
		(start 490.611414 -136.72185)
		(end 490.617764 -136.7282)
		(width 0.10795)
		(layer "B.Cu")
		(net "LED_POSTCODE_4_R")
	)
	(segment
		(start 480.174808 -139.737592)
		(end 480.3902 -139.5222)
		(width 0.10795)
		(layer "B.Cu")
		(net "LED_POSTCODE_4_R")
	)
	(segment
		(start 480.822 -138.0236)
		(end 480.822 -137.9728)
		(width 0.10795)
		(layer "B.Cu")
		(net "LED_POSTCODE_4_R")
	)
	(segment
		(start 491.8456 -138.2522)
		(end 492.0488 -138.4554)
		(width 0.10795)
		(layer "B.Cu")
		(net "LED_POSTCODE_4_R")
	)
	(segment
		(start 490.6264 -136.7282)
		(end 491.8456 -137.9474)
		(width 0.10795)
		(layer "B.Cu")
		(net "LED_POSTCODE_4_R")
	)
	(segment
		(start 480.3902 -139.5222)
		(end 480.3902 -139.107418)
		(width 0.10795)
		(layer "B.Cu")
		(net "LED_POSTCODE_4_R")
	)
	(segment
		(start 490.617764 -136.7282)
		(end 490.6264 -136.7282)
		(width 0.10795)
		(layer "B.Cu")
		(net "LED_POSTCODE_4_R")
	)
	(segment
		(start 482.0666 -136.7282)
		(end 482.074982 -136.7282)
		(width 0.10795)
		(layer "B.Cu")
		(net "LED_POSTCODE_4_R")
	)
	(segment
		(start 480.3902 -139.107418)
		(end 480.822 -138.675618)
		(width 0.10795)
		(layer "B.Cu")
		(net "LED_POSTCODE_4_R")
	)
	(segment
		(start 492.594392 -144.8562)
		(end 492.162592 -145.288)
		(width 0.10795)
		(layer "B.Cu")
		(net "LED_POSTCODE_4_R")
	)
	(segment
		(start 479.299016 -139.737592)
		(end 480.174808 -139.737592)
		(width 0.10795)
		(layer "B.Cu")
		(net "LED_POSTCODE_4_R")
	)
	(segment
		(start 480.822 -137.9728)
		(end 482.0666 -136.7282)
		(width 0.10795)
		(layer "B.Cu")
		(net "LED_POSTCODE_4_R")
	)
	(segment
		(start 480.822 -138.5824)
		(end 480.7966 -138.557)
		(width 0.10795)
		(layer "B.Cu")
		(net "LED_POSTCODE_4_R")
	)
	(segment
		(start 482.081332 -136.72185)
		(end 490.611414 -136.72185)
		(width 0.10795)
		(layer "B.Cu")
		(net "LED_POSTCODE_4_R")
	)
	(segment
		(start 482.074982 -136.7282)
		(end 482.081332 -136.72185)
		(width 0.10795)
		(layer "B.Cu")
		(net "LED_POSTCODE_4_R")
	)
	(segment
		(start 490.7788 -144.6276)
		(end 491.3376 -144.6276)
		(width 0.10795)
		(layer "B.Cu")
		(net "LED_POSTCODE_4_R")
	)
	(segment
		(start 490.5375 -145.288)
		(end 490.5375 -144.8689)
		(width 0.10795)
		(layer "B.Cu")
		(net "LED_POSTCODE_4_R")
	)
	(segment
		(start 480.822 -138.675618)
		(end 480.822 -138.5824)
		(width 0.10795)
		(layer "B.Cu")
		(net "LED_POSTCODE_4_R")
	)
	(segment
		(start 496.000024 -145.849848)
		(end 495.006376 -144.8562)
		(width 0.10795)
		(layer "B.Cu")
		(net "LED_POSTCODE_4_R")
	)
	(segment
		(start 480.7966 -138.049)
		(end 480.822 -138.0236)
		(width 0.10795)
		(layer "B.Cu")
		(net "LED_POSTCODE_4_R")
	)
	(segment
		(start 490.54639 -145.288)
		(end 490.5375 -145.288)
		(width 0.10795)
		(layer "B.Cu")
		(net "LED_POSTCODE_4_R")
	)
	(segment
		(start 490.5375 -144.8689)
		(end 490.7788 -144.6276)
		(width 0.10795)
		(layer "B.Cu")
		(net "LED_POSTCODE_4_R")
	)
	(segment
		(start 492.162592 -145.288)
		(end 490.54639 -145.288)
		(width 0.10795)
		(layer "B.Cu")
		(net "LED_POSTCODE_4_R")
	)
	(segment
		(start 491.047278 -142.41145)
		(end 490.530896 -142.927832)
		(width 0.089408)
		(layer "In9.Cu")
		(net "LED_POSTCODE_4_R")
	)
	(segment
		(start 491.871 -138.4554)
		(end 491.047278 -139.279122)
		(width 0.089408)
		(layer "In9.Cu")
		(net "LED_POSTCODE_4_R")
	)
	(segment
		(start 491.047278 -139.279122)
		(end 491.047278 -142.41145)
		(width 0.089408)
		(layer "In9.Cu")
		(net "LED_POSTCODE_4_R")
	)
	(segment
		(start 490.530896 -143.820896)
		(end 491.3376 -144.6276)
		(width 0.089408)
		(layer "In9.Cu")
		(net "LED_POSTCODE_4_R")
	)
	(segment
		(start 492.0488 -138.4554)
		(end 491.871 -138.4554)
		(width 0.089408)
		(layer "In9.Cu")
		(net "LED_POSTCODE_4_R")
	)
	(segment
		(start 490.530896 -142.927832)
		(end 490.530896 -143.820896)
		(width 0.089408)
		(layer "In9.Cu")
		(net "LED_POSTCODE_4_R")
	)
	(segment
		(start 383.949956 -89.215214)
		(end 383.949956 -91.634564)
		(width 0.0889)
		(layer "F.Cu")
		(net "FM_MB_SLOT_ID1")
	)
	(segment
		(start 383.949956 -91.634564)
		(end 384.030982 -91.71559)
		(width 0.0889)
		(layer "F.Cu")
		(net "FM_MB_SLOT_ID1")
	)
	(segment
		(start 384.102102 -94.257876)
		(end 383.985008 -94.37497)
		(width 0.0889)
		(layer "F.Cu")
		(net "FM_MB_SLOT_ID1")
	)
	(segment
		(start 425.812712 -18.960084)
		(end 426.40758 -19.554952)
		(width 0.10795)
		(layer "F.Cu")
		(net "FM_MB_SLOT_ID1")
	)
	(segment
		(start 384.270758 -93.223334)
		(end 384.270758 -93.717618)
		(width 0.0889)
		(layer "F.Cu")
		(net "FM_MB_SLOT_ID1")
	)
	(segment
		(start 384.270758 -93.717618)
		(end 384.102102 -93.886274)
		(width 0.0889)
		(layer "F.Cu")
		(net "FM_MB_SLOT_ID1")
	)
	(segment
		(start 429.21936 -18.313654)
		(end 429.21936 -17.4244)
		(width 0.10795)
		(layer "F.Cu")
		(net "FM_MB_SLOT_ID1")
	)
	(segment
		(start 384.030982 -92.983558)
		(end 384.270758 -93.223334)
		(width 0.0889)
		(layer "F.Cu")
		(net "FM_MB_SLOT_ID1")
	)
	(segment
		(start 383.794 -88.2015)
		(end 383.794 -89.059258)
		(width 0.10795)
		(layer "F.Cu")
		(net "FM_MB_SLOT_ID1")
	)
	(segment
		(start 481.419916 -19.2151)
		(end 483.257352 -19.2151)
		(width 0.10795)
		(layer "F.Cu")
		(net "FM_MB_SLOT_ID1")
	)
	(segment
		(start 384.102102 -93.886274)
		(end 384.102102 -94.257876)
		(width 0.0889)
		(layer "F.Cu")
		(net "FM_MB_SLOT_ID1")
	)
	(segment
		(start 483.257352 -19.2151)
		(end 483.526592 -19.48434)
		(width 0.10795)
		(layer "F.Cu")
		(net "FM_MB_SLOT_ID1")
	)
	(segment
		(start 383.794 -89.059258)
		(end 383.949956 -89.215214)
		(width 0.10795)
		(layer "F.Cu")
		(net "FM_MB_SLOT_ID1")
	)
	(segment
		(start 427.978062 -19.554952)
		(end 429.21936 -18.313654)
		(width 0.10795)
		(layer "F.Cu")
		(net "FM_MB_SLOT_ID1")
	)
	(segment
		(start 384.030982 -91.71559)
		(end 384.030982 -92.983558)
		(width 0.0889)
		(layer "F.Cu")
		(net "FM_MB_SLOT_ID1")
	)
	(segment
		(start 426.40758 -19.554952)
		(end 427.978062 -19.554952)
		(width 0.10795)
		(layer "F.Cu")
		(net "FM_MB_SLOT_ID1")
	)
	(via
		(at 395.727174 -35.93338)
		(size 0.508)
		(drill 0.254)
		(layers "F.Cu" "B.Cu")
		(net "FM_MB_SLOT_ID1")
	)
	(via
		(at 16.175482 3.267964)
		(size 0.508)
		(drill 0.254)
		(layers "F.Cu" "B.Cu")
		(net "FM_MB_SLOT_ID1")
	)
	(via
		(at 483.526592 -19.48434)
		(size 0.762)
		(drill 0.381)
		(layers "F.Cu" "B.Cu")
		(net "FM_MB_SLOT_ID1")
	)
	(via
		(at 481.419916 -19.2151)
		(size 0.508)
		(drill 0.254)
		(layers "F.Cu" "B.Cu")
		(net "FM_MB_SLOT_ID1")
	)
	(via
		(at 383.794 -89.059258)
		(size 0.508)
		(drill 0.254)
		(layers "F.Cu" "B.Cu")
		(net "FM_MB_SLOT_ID1")
	)
	(via
		(at 425.812712 -18.960084)
		(size 0.508)
		(drill 0.254)
		(layers "F.Cu" "B.Cu")
		(net "FM_MB_SLOT_ID1")
	)
	(via
		(at 473.0496 -31.623)
		(size 0.508)
		(drill 0.254)
		(layers "F.Cu" "B.Cu")
		(net "FM_MB_SLOT_ID1")
	)
	(via
		(at 408.306016 4.405884)
		(size 0.508)
		(drill 0.254)
		(layers "F.Cu" "B.Cu")
		(net "FM_MB_SLOT_ID1")
	)
	(segment
		(start 386.08 -77.726794)
		(end 386.08 -84.877656)
		(width 0.089408)
		(layer "In2.Cu")
		(net "FM_MB_SLOT_ID1")
	)
	(segment
		(start 386.92836 -42.933874)
		(end 386.92836 -44.765722)
		(width 0.089408)
		(layer "In2.Cu")
		(net "FM_MB_SLOT_ID1")
	)
	(segment
		(start 491.44936 -27.725624)
		(end 491.44936 -30.53969)
		(width 0.089408)
		(layer "In2.Cu")
		(net "FM_MB_SLOT_ID1")
	)
	(segment
		(start 386.08 -84.877656)
		(end 384.203956 -86.7537)
		(width 0.089408)
		(layer "In2.Cu")
		(net "FM_MB_SLOT_ID1")
	)
	(segment
		(start 488.936538 -33.923732)
		(end 488.296204 -33.283398)
		(width 0.089408)
		(layer "In2.Cu")
		(net "FM_MB_SLOT_ID1")
	)
	(segment
		(start 474.89745 -33.128204)
		(end 474.876622 -33.107376)
		(width 0.089408)
		(layer "In2.Cu")
		(net "FM_MB_SLOT_ID1")
	)
	(segment
		(start 386.92836 -44.765722)
		(end 386.928614 -44.765976)
		(width 0.089408)
		(layer "In2.Cu")
		(net "FM_MB_SLOT_ID1")
	)
	(segment
		(start 393.786868 -36.051998)
		(end 392.8618 -35.12693)
		(width 0.089408)
		(layer "In2.Cu")
		(net "FM_MB_SLOT_ID1")
	)
	(segment
		(start 489.67644 -23.036022)
		(end 489.67644 -25.785064)
		(width 0.089408)
		(layer "In2.Cu")
		(net "FM_MB_SLOT_ID1")
	)
	(segment
		(start 386.928614 -44.765976)
		(end 386.928614 -53.98008)
		(width 0.089408)
		(layer "In2.Cu")
		(net "FM_MB_SLOT_ID1")
	)
	(segment
		(start 482.999288 -31.192724)
		(end 482.999288 -32.096456)
		(width 0.089408)
		(layer "In2.Cu")
		(net "FM_MB_SLOT_ID1")
	)
	(segment
		(start 384.203956 -86.7537)
		(end 384.203956 -88.649302)
		(width 0.089408)
		(layer "In2.Cu")
		(net "FM_MB_SLOT_ID1")
	)
	(segment
		(start 389.014716 -41.97604)
		(end 387.762496 -41.97604)
		(width 0.089408)
		(layer "In2.Cu")
		(net "FM_MB_SLOT_ID1")
	)
	(segment
		(start 388.404608 -60.764928)
		(end 389.20039 -61.56071)
		(width 0.089408)
		(layer "In2.Cu")
		(net "FM_MB_SLOT_ID1")
	)
	(segment
		(start 389.20039 -62.342014)
		(end 388.76732 -62.775084)
		(width 0.089408)
		(layer "In2.Cu")
		(net "FM_MB_SLOT_ID1")
	)
	(segment
		(start 388.76732 -63.670942)
		(end 388.028942 -64.40932)
		(width 0.089408)
		(layer "In2.Cu")
		(net "FM_MB_SLOT_ID1")
	)
	(segment
		(start 386.30352 -77.503274)
		(end 386.08 -77.726794)
		(width 0.089408)
		(layer "In2.Cu")
		(net "FM_MB_SLOT_ID1")
	)
	(segment
		(start 387.525768 -64.40932)
		(end 386.818378 -65.11671)
		(width 0.089408)
		(layer "In2.Cu")
		(net "FM_MB_SLOT_ID1")
	)
	(segment
		(start 385.984496 -72.252586)
		(end 386.30352 -72.57161)
		(width 0.089408)
		(layer "In2.Cu")
		(net "FM_MB_SLOT_ID1")
	)
	(segment
		(start 489.676186 -25.785318)
		(end 489.676186 -25.943306)
		(width 0.089408)
		(layer "In2.Cu")
		(net "FM_MB_SLOT_ID1")
	)
	(segment
		(start 386.928614 -42.93362)
		(end 386.92836 -42.933874)
		(width 0.089408)
		(layer "In2.Cu")
		(net "FM_MB_SLOT_ID1")
	)
	(segment
		(start 481.96754 -33.128204)
		(end 474.89745 -33.128204)
		(width 0.089408)
		(layer "In2.Cu")
		(net "FM_MB_SLOT_ID1")
	)
	(segment
		(start 485.26319 -18.622772)
		(end 489.67644 -23.036022)
		(width 0.089408)
		(layer "In2.Cu")
		(net "FM_MB_SLOT_ID1")
	)
	(segment
		(start 387.604254 -41.975786)
		(end 386.928614 -42.651426)
		(width 0.089408)
		(layer "In2.Cu")
		(net "FM_MB_SLOT_ID1")
	)
	(segment
		(start 483.356158 -30.835854)
		(end 482.999288 -31.192724)
		(width 0.089408)
		(layer "In2.Cu")
		(net "FM_MB_SLOT_ID1")
	)
	(segment
		(start 386.928614 -42.651426)
		(end 386.928614 -42.93362)
		(width 0.089408)
		(layer "In2.Cu")
		(net "FM_MB_SLOT_ID1")
	)
	(segment
		(start 390.445244 -40.545512)
		(end 389.014716 -41.97604)
		(width 0.089408)
		(layer "In2.Cu")
		(net "FM_MB_SLOT_ID1")
	)
	(segment
		(start 387.762496 -41.97604)
		(end 387.762242 -41.975786)
		(width 0.089408)
		(layer "In2.Cu")
		(net "FM_MB_SLOT_ID1")
	)
	(segment
		(start 386.296154 -56.2102)
		(end 387.672834 -57.58688)
		(width 0.089408)
		(layer "In2.Cu")
		(net "FM_MB_SLOT_ID1")
	)
	(segment
		(start 489.67644 -25.952704)
		(end 491.44936 -27.725624)
		(width 0.089408)
		(layer "In2.Cu")
		(net "FM_MB_SLOT_ID1")
	)
	(segment
		(start 391.212578 -35.12693)
		(end 391.033508 -35.306)
		(width 0.089408)
		(layer "In2.Cu")
		(net "FM_MB_SLOT_ID1")
	)
	(segment
		(start 489.67644 -25.785064)
		(end 489.676186 -25.785318)
		(width 0.089408)
		(layer "In2.Cu")
		(net "FM_MB_SLOT_ID1")
	)
	(segment
		(start 387.762242 -41.975786)
		(end 387.604254 -41.975786)
		(width 0.089408)
		(layer "In2.Cu")
		(net "FM_MB_SLOT_ID1")
	)
	(segment
		(start 488.296204 -33.283398)
		(end 488.296204 -31.518606)
		(width 0.089408)
		(layer "In2.Cu")
		(net "FM_MB_SLOT_ID1")
	)
	(segment
		(start 483.15753 -18.622772)
		(end 485.26319 -18.622772)
		(width 0.089408)
		(layer "In2.Cu")
		(net "FM_MB_SLOT_ID1")
	)
	(segment
		(start 386.928614 -53.98008)
		(end 386.296154 -54.61254)
		(width 0.089408)
		(layer "In2.Cu")
		(net "FM_MB_SLOT_ID1")
	)
	(segment
		(start 390.445244 -38.048438)
		(end 390.445244 -40.545512)
		(width 0.089408)
		(layer "In2.Cu")
		(net "FM_MB_SLOT_ID1")
	)
	(segment
		(start 391.033508 -37.460174)
		(end 390.445244 -38.048438)
		(width 0.089408)
		(layer "In2.Cu")
		(net "FM_MB_SLOT_ID1")
	)
	(segment
		(start 482.999288 -32.096456)
		(end 481.96754 -33.128204)
		(width 0.089408)
		(layer "In2.Cu")
		(net "FM_MB_SLOT_ID1")
	)
	(segment
		(start 490.782864 -31.206186)
		(end 490.782864 -33.478724)
		(width 0.089408)
		(layer "In2.Cu")
		(net "FM_MB_SLOT_ID1")
	)
	(segment
		(start 387.672834 -58.384186)
		(end 388.404608 -59.11596)
		(width 0.089408)
		(layer "In2.Cu")
		(net "FM_MB_SLOT_ID1")
	)
	(segment
		(start 490.337856 -33.923732)
		(end 488.936538 -33.923732)
		(width 0.089408)
		(layer "In2.Cu")
		(net "FM_MB_SLOT_ID1")
	)
	(segment
		(start 391.033508 -35.306)
		(end 391.033508 -37.460174)
		(width 0.089408)
		(layer "In2.Cu")
		(net "FM_MB_SLOT_ID1")
	)
	(segment
		(start 384.203956 -88.649302)
		(end 383.794 -89.059258)
		(width 0.089408)
		(layer "In2.Cu")
		(net "FM_MB_SLOT_ID1")
	)
	(segment
		(start 386.818378 -69.74332)
		(end 385.984496 -70.577202)
		(width 0.089408)
		(layer "In2.Cu")
		(net "FM_MB_SLOT_ID1")
	)
	(segment
		(start 474.876622 -33.107376)
		(end 474.533976 -33.107376)
		(width 0.089408)
		(layer "In2.Cu")
		(net "FM_MB_SLOT_ID1")
	)
	(segment
		(start 388.404608 -59.11596)
		(end 388.404608 -60.764928)
		(width 0.089408)
		(layer "In2.Cu")
		(net "FM_MB_SLOT_ID1")
	)
	(segment
		(start 386.818378 -65.11671)
		(end 386.818378 -69.74332)
		(width 0.089408)
		(layer "In2.Cu")
		(net "FM_MB_SLOT_ID1")
	)
	(segment
		(start 489.67644 -25.94356)
		(end 489.67644 -25.952704)
		(width 0.089408)
		(layer "In2.Cu")
		(net "FM_MB_SLOT_ID1")
	)
	(segment
		(start 386.296154 -54.61254)
		(end 386.296154 -56.2102)
		(width 0.089408)
		(layer "In2.Cu")
		(net "FM_MB_SLOT_ID1")
	)
	(segment
		(start 489.676186 -25.943306)
		(end 489.67644 -25.94356)
		(width 0.089408)
		(layer "In2.Cu")
		(net "FM_MB_SLOT_ID1")
	)
	(segment
		(start 474.533976 -33.107376)
		(end 473.0496 -31.623)
		(width 0.089408)
		(layer "In2.Cu")
		(net "FM_MB_SLOT_ID1")
	)
	(segment
		(start 388.028942 -64.40932)
		(end 387.525768 -64.40932)
		(width 0.089408)
		(layer "In2.Cu")
		(net "FM_MB_SLOT_ID1")
	)
	(segment
		(start 386.30352 -72.57161)
		(end 386.30352 -77.503274)
		(width 0.089408)
		(layer "In2.Cu")
		(net "FM_MB_SLOT_ID1")
	)
	(segment
		(start 388.76732 -62.775084)
		(end 388.76732 -63.670942)
		(width 0.089408)
		(layer "In2.Cu")
		(net "FM_MB_SLOT_ID1")
	)
	(segment
		(start 387.672834 -57.58688)
		(end 387.672834 -58.384186)
		(width 0.089408)
		(layer "In2.Cu")
		(net "FM_MB_SLOT_ID1")
	)
	(segment
		(start 395.727174 -35.93338)
		(end 395.608556 -36.051998)
		(width 0.089408)
		(layer "In2.Cu")
		(net "FM_MB_SLOT_ID1")
	)
	(segment
		(start 395.608556 -36.051998)
		(end 393.786868 -36.051998)
		(width 0.089408)
		(layer "In2.Cu")
		(net "FM_MB_SLOT_ID1")
	)
	(segment
		(start 491.44936 -30.53969)
		(end 490.782864 -31.206186)
		(width 0.089408)
		(layer "In2.Cu")
		(net "FM_MB_SLOT_ID1")
	)
	(segment
		(start 490.782864 -33.478724)
		(end 490.337856 -33.923732)
		(width 0.089408)
		(layer "In2.Cu")
		(net "FM_MB_SLOT_ID1")
	)
	(segment
		(start 482.565202 -19.2151)
		(end 483.15753 -18.622772)
		(width 0.089408)
		(layer "In2.Cu")
		(net "FM_MB_SLOT_ID1")
	)
	(segment
		(start 385.984496 -70.577202)
		(end 385.984496 -72.252586)
		(width 0.089408)
		(layer "In2.Cu")
		(net "FM_MB_SLOT_ID1")
	)
	(segment
		(start 481.419916 -19.2151)
		(end 482.565202 -19.2151)
		(width 0.089408)
		(layer "In2.Cu")
		(net "FM_MB_SLOT_ID1")
	)
	(segment
		(start 389.20039 -61.56071)
		(end 389.20039 -62.342014)
		(width 0.089408)
		(layer "In2.Cu")
		(net "FM_MB_SLOT_ID1")
	)
	(segment
		(start 488.296204 -31.518606)
		(end 487.613452 -30.835854)
		(width 0.089408)
		(layer "In2.Cu")
		(net "FM_MB_SLOT_ID1")
	)
	(segment
		(start 487.613452 -30.835854)
		(end 483.356158 -30.835854)
		(width 0.089408)
		(layer "In2.Cu")
		(net "FM_MB_SLOT_ID1")
	)
	(segment
		(start 392.8618 -35.12693)
		(end 391.212578 -35.12693)
		(width 0.089408)
		(layer "In2.Cu")
		(net "FM_MB_SLOT_ID1")
	)
	(segment
		(start 470.751154 -11.91514)
		(end 468.48776 -9.651746)
		(width 0.089408)
		(layer "In4.Cu")
		(net "FM_MB_SLOT_ID1")
	)
	(segment
		(start 427.693836 -17.018)
		(end 444.6524 -17.018)
		(width 0.089408)
		(layer "In4.Cu")
		(net "FM_MB_SLOT_ID1")
	)
	(segment
		(start 466.147912 -2.529586)
		(end 466.148166 -2.529332)
		(width 0.089408)
		(layer "In4.Cu")
		(net "FM_MB_SLOT_ID1")
	)
	(segment
		(start 464.691984 1.321816)
		(end 463.23885 2.77495)
		(width 0.089408)
		(layer "In4.Cu")
		(net "FM_MB_SLOT_ID1")
	)
	(segment
		(start 479.48723 -18.704306)
		(end 477.976184 -17.19326)
		(width 0.089408)
		(layer "In4.Cu")
		(net "FM_MB_SLOT_ID1")
	)
	(segment
		(start 464.483196 -23.615396)
		(end 467.98484 -27.11704)
		(width 0.089408)
		(layer "In4.Cu")
		(net "FM_MB_SLOT_ID1")
	)
	(segment
		(start 463.136996 -23.615396)
		(end 464.483196 -23.615396)
		(width 0.089408)
		(layer "In4.Cu")
		(net "FM_MB_SLOT_ID1")
	)
	(segment
		(start 464.691984 0.239776)
		(end 464.691984 1.321816)
		(width 0.089408)
		(layer "In4.Cu")
		(net "FM_MB_SLOT_ID1")
	)
	(segment
		(start 466.147912 -3.659378)
		(end 466.147912 -2.529586)
		(width 0.089408)
		(layer "In4.Cu")
		(net "FM_MB_SLOT_ID1")
	)
	(segment
		(start 468.48776 -9.651746)
		(end 468.48776 -8.883904)
		(width 0.089408)
		(layer "In4.Cu")
		(net "FM_MB_SLOT_ID1")
	)
	(segment
		(start 463.23885 4.32435)
		(end 462.6864 4.8768)
		(width 0.089408)
		(layer "In4.Cu")
		(net "FM_MB_SLOT_ID1")
	)
	(segment
		(start 460.8068 -21.2852)
		(end 463.136996 -23.615396)
		(width 0.089408)
		(layer "In4.Cu")
		(net "FM_MB_SLOT_ID1")
	)
	(segment
		(start 454.774808 -20.935442)
		(end 455.94143 -22.102064)
		(width 0.089408)
		(layer "In4.Cu")
		(net "FM_MB_SLOT_ID1")
	)
	(segment
		(start 466.101684 -8.618474)
		(end 464.404964 -8.618474)
		(width 0.089408)
		(layer "In4.Cu")
		(net "FM_MB_SLOT_ID1")
	)
	(segment
		(start 466.45322 -8.266938)
		(end 466.101684 -8.618474)
		(width 0.089408)
		(layer "In4.Cu")
		(net "FM_MB_SLOT_ID1")
	)
	(segment
		(start 467.98484 -27.11704)
		(end 469.35644 -27.11704)
		(width 0.089408)
		(layer "In4.Cu")
		(net "FM_MB_SLOT_ID1")
	)
	(segment
		(start 466.148166 -2.529332)
		(end 466.148166 -2.371344)
		(width 0.089408)
		(layer "In4.Cu")
		(net "FM_MB_SLOT_ID1")
	)
	(segment
		(start 465.443316 -0.511556)
		(end 464.691984 0.239776)
		(width 0.089408)
		(layer "In4.Cu")
		(net "FM_MB_SLOT_ID1")
	)
	(segment
		(start 463.23885 2.77495)
		(end 463.23885 4.32435)
		(width 0.089408)
		(layer "In4.Cu")
		(net "FM_MB_SLOT_ID1")
	)
	(segment
		(start 473.0496 -30.8102)
		(end 473.0496 -31.623)
		(width 0.089408)
		(layer "In4.Cu")
		(net "FM_MB_SLOT_ID1")
	)
	(segment
		(start 448.601592 -16.2306)
		(end 450.042026 -17.671034)
		(width 0.089408)
		(layer "In4.Cu")
		(net "FM_MB_SLOT_ID1")
	)
	(segment
		(start 445.4398 -16.2306)
		(end 448.601592 -16.2306)
		(width 0.089408)
		(layer "In4.Cu")
		(net "FM_MB_SLOT_ID1")
	)
	(segment
		(start 455.94143 -22.102064)
		(end 457.805536 -22.102064)
		(width 0.089408)
		(layer "In4.Cu")
		(net "FM_MB_SLOT_ID1")
	)
	(segment
		(start 444.6524 -17.018)
		(end 445.4398 -16.2306)
		(width 0.089408)
		(layer "In4.Cu")
		(net "FM_MB_SLOT_ID1")
	)
	(segment
		(start 458.6224 -21.2852)
		(end 460.8068 -21.2852)
		(width 0.089408)
		(layer "In4.Cu")
		(net "FM_MB_SLOT_ID1")
	)
	(segment
		(start 452.69658 -20.935442)
		(end 454.774808 -20.935442)
		(width 0.089408)
		(layer "In4.Cu")
		(net "FM_MB_SLOT_ID1")
	)
	(segment
		(start 408.776932 4.8768)
		(end 408.306016 4.405884)
		(width 0.089408)
		(layer "In4.Cu")
		(net "FM_MB_SLOT_ID1")
	)
	(segment
		(start 480.935538 -19.2151)
		(end 480.424744 -18.704306)
		(width 0.089408)
		(layer "In4.Cu")
		(net "FM_MB_SLOT_ID1")
	)
	(segment
		(start 464.404964 -8.618474)
		(end 463.566764 -7.780274)
		(width 0.089408)
		(layer "In4.Cu")
		(net "FM_MB_SLOT_ID1")
	)
	(segment
		(start 463.566764 -6.781292)
		(end 464.5152 -5.832856)
		(width 0.089408)
		(layer "In4.Cu")
		(net "FM_MB_SLOT_ID1")
	)
	(segment
		(start 425.812712 -18.960084)
		(end 425.812712 -18.899124)
		(width 0.089408)
		(layer "In4.Cu")
		(net "FM_MB_SLOT_ID1")
	)
	(segment
		(start 469.35644 -27.11704)
		(end 473.0496 -30.8102)
		(width 0.089408)
		(layer "In4.Cu")
		(net "FM_MB_SLOT_ID1")
	)
	(segment
		(start 463.566764 -7.780274)
		(end 463.566764 -6.781292)
		(width 0.089408)
		(layer "In4.Cu")
		(net "FM_MB_SLOT_ID1")
	)
	(segment
		(start 480.424744 -18.704306)
		(end 479.48723 -18.704306)
		(width 0.089408)
		(layer "In4.Cu")
		(net "FM_MB_SLOT_ID1")
	)
	(segment
		(start 457.805536 -22.102064)
		(end 458.6224 -21.2852)
		(width 0.089408)
		(layer "In4.Cu")
		(net "FM_MB_SLOT_ID1")
	)
	(segment
		(start 477.11106 -17.19326)
		(end 471.83294 -11.91514)
		(width 0.089408)
		(layer "In4.Cu")
		(net "FM_MB_SLOT_ID1")
	)
	(segment
		(start 450.042026 -17.671034)
		(end 450.042026 -18.280888)
		(width 0.089408)
		(layer "In4.Cu")
		(net "FM_MB_SLOT_ID1")
	)
	(segment
		(start 467.870794 -8.266938)
		(end 466.45322 -8.266938)
		(width 0.089408)
		(layer "In4.Cu")
		(net "FM_MB_SLOT_ID1")
	)
	(segment
		(start 462.6864 4.8768)
		(end 408.776932 4.8768)
		(width 0.089408)
		(layer "In4.Cu")
		(net "FM_MB_SLOT_ID1")
	)
	(segment
		(start 468.48776 -8.883904)
		(end 467.870794 -8.266938)
		(width 0.089408)
		(layer "In4.Cu")
		(net "FM_MB_SLOT_ID1")
	)
	(segment
		(start 465.443316 -1.666494)
		(end 465.443316 -0.511556)
		(width 0.089408)
		(layer "In4.Cu")
		(net "FM_MB_SLOT_ID1")
	)
	(segment
		(start 466.148166 -2.371344)
		(end 465.443316 -1.666494)
		(width 0.089408)
		(layer "In4.Cu")
		(net "FM_MB_SLOT_ID1")
	)
	(segment
		(start 464.5152 -5.29209)
		(end 466.147912 -3.659378)
		(width 0.089408)
		(layer "In4.Cu")
		(net "FM_MB_SLOT_ID1")
	)
	(segment
		(start 471.83294 -11.91514)
		(end 470.751154 -11.91514)
		(width 0.089408)
		(layer "In4.Cu")
		(net "FM_MB_SLOT_ID1")
	)
	(segment
		(start 481.419916 -19.2151)
		(end 480.935538 -19.2151)
		(width 0.089408)
		(layer "In4.Cu")
		(net "FM_MB_SLOT_ID1")
	)
	(segment
		(start 425.812712 -18.899124)
		(end 427.693836 -17.018)
		(width 0.089408)
		(layer "In4.Cu")
		(net "FM_MB_SLOT_ID1")
	)
	(segment
		(start 464.5152 -5.832856)
		(end 464.5152 -5.29209)
		(width 0.089408)
		(layer "In4.Cu")
		(net "FM_MB_SLOT_ID1")
	)
	(segment
		(start 450.042026 -18.280888)
		(end 452.69658 -20.935442)
		(width 0.089408)
		(layer "In4.Cu")
		(net "FM_MB_SLOT_ID1")
	)
	(segment
		(start 477.976184 -17.19326)
		(end 477.11106 -17.19326)
		(width 0.089408)
		(layer "In4.Cu")
		(net "FM_MB_SLOT_ID1")
	)
	(segment
		(start 427.728888 -18.717514)
		(end 427.728888 -19.049238)
		(width 0.089408)
		(layer "In9.Cu")
		(net "FM_MB_SLOT_ID1")
	)
	(segment
		(start 402.785834 -22.810724)
		(end 409.462478 -22.810724)
		(width 0.089408)
		(layer "In9.Cu")
		(net "FM_MB_SLOT_ID1")
	)
	(segment
		(start 323.216016 0.61087)
		(end 322.41871 0.61087)
		(width 0.089408)
		(layer "In9.Cu")
		(net "FM_MB_SLOT_ID1")
	)
	(segment
		(start 22.216872 4.633976)
		(end 19.906996 4.633976)
		(width 0.089408)
		(layer "In9.Cu")
		(net "FM_MB_SLOT_ID1")
	)
	(segment
		(start 19.906996 4.633976)
		(end 18.122392 2.849372)
		(width 0.089408)
		(layer "In9.Cu")
		(net "FM_MB_SLOT_ID1")
	)
	(segment
		(start 364.310676 -9.556496)
		(end 362.307632 -11.55954)
		(width 0.089408)
		(layer "In9.Cu")
		(net "FM_MB_SLOT_ID1")
	)
	(segment
		(start 332.819248 -8.569706)
		(end 331.493622 -7.24408)
		(width 0.089408)
		(layer "In9.Cu")
		(net "FM_MB_SLOT_ID1")
	)
	(segment
		(start 341.719408 -13.519404)
		(end 339.79485 -11.594846)
		(width 0.089408)
		(layer "In9.Cu")
		(net "FM_MB_SLOT_ID1")
	)
	(segment
		(start 171.2976 -3.3528)
		(end 168.184322 -3.3528)
		(width 0.089408)
		(layer "In9.Cu")
		(net "FM_MB_SLOT_ID1")
	)
	(segment
		(start 421.56761 -19.107912)
		(end 421.835326 -18.840196)
		(width 0.089408)
		(layer "In9.Cu")
		(net "FM_MB_SLOT_ID1")
	)
	(segment
		(start 411.61335 -19.910298)
		(end 413.384238 -19.910298)
		(width 0.089408)
		(layer "In9.Cu")
		(net "FM_MB_SLOT_ID1")
	)
	(segment
		(start 360.26471 -20.904454)
		(end 360.264964 -20.904708)
		(width 0.089408)
		(layer "In9.Cu")
		(net "FM_MB_SLOT_ID1")
	)
	(segment
		(start 386.847588 2.553208)
		(end 382.384554 2.553208)
		(width 0.089408)
		(layer "In9.Cu")
		(net "FM_MB_SLOT_ID1")
	)
	(segment
		(start 321.856862 2.812288)
		(end 321.322954 3.346196)
		(width 0.089408)
		(layer "In9.Cu")
		(net "FM_MB_SLOT_ID1")
	)
	(segment
		(start 258.971542 3.383534)
		(end 186.99226 3.383534)
		(width 0.089408)
		(layer "In9.Cu")
		(net "FM_MB_SLOT_ID1")
	)
	(segment
		(start 397.09471 -31.242)
		(end 397.09471 -23.019512)
		(width 0.089408)
		(layer "In9.Cu")
		(net "FM_MB_SLOT_ID1")
	)
	(segment
		(start 423.138346 -18.840196)
		(end 423.60977 -18.368772)
		(width 0.089408)
		(layer "In9.Cu")
		(net "FM_MB_SLOT_ID1")
	)
	(segment
		(start 356.235254 -22.589744)
		(end 355.571552 -22.589744)
		(width 0.089408)
		(layer "In9.Cu")
		(net "FM_MB_SLOT_ID1")
	)
	(segment
		(start 418.4777 -19.372072)
		(end 418.74186 -19.107912)
		(width 0.089408)
		(layer "In9.Cu")
		(net "FM_MB_SLOT_ID1")
	)
	(segment
		(start 361.05338 -12.171172)
		(end 361.05338 -18.720308)
		(width 0.089408)
		(layer "In9.Cu")
		(net "FM_MB_SLOT_ID1")
	)
	(segment
		(start 410.675836 -20.847812)
		(end 411.61335 -19.910298)
		(width 0.089408)
		(layer "In9.Cu")
		(net "FM_MB_SLOT_ID1")
	)
	(segment
		(start 421.835326 -18.840196)
		(end 423.138346 -18.840196)
		(width 0.089408)
		(layer "In9.Cu")
		(net "FM_MB_SLOT_ID1")
	)
	(segment
		(start 400.851624 -21.977858)
		(end 401.820126 -22.94636)
		(width 0.089408)
		(layer "In9.Cu")
		(net "FM_MB_SLOT_ID1")
	)
	(segment
		(start 341.719408 -17.49171)
		(end 341.719408 -13.519404)
		(width 0.089408)
		(layer "In9.Cu")
		(net "FM_MB_SLOT_ID1")
	)
	(segment
		(start 361.665012 -11.55954)
		(end 361.05338 -12.171172)
		(width 0.089408)
		(layer "In9.Cu")
		(net "FM_MB_SLOT_ID1")
	)
	(segment
		(start 427.050454 -18.368772)
		(end 427.468284 -18.45691)
		(width 0.089408)
		(layer "In9.Cu")
		(net "FM_MB_SLOT_ID1")
	)
	(segment
		(start 351.968054 -22.936962)
		(end 351.104962 -22.07387)
		(width 0.089408)
		(layer "In9.Cu")
		(net "FM_MB_SLOT_ID1")
	)
	(segment
		(start 103.533194 3.903472)
		(end 102.80269 4.633976)
		(width 0.089408)
		(layer "In9.Cu")
		(net "FM_MB_SLOT_ID1")
	)
	(segment
		(start 413.384238 -19.910298)
		(end 413.922464 -19.372072)
		(width 0.089408)
		(layer "In9.Cu")
		(net "FM_MB_SLOT_ID1")
	)
	(segment
		(start 425.918376 -18.960084)
		(end 425.812712 -18.960084)
		(width 0.089408)
		(layer "In9.Cu")
		(net "FM_MB_SLOT_ID1")
	)
	(segment
		(start 328.726546 -5.138928)
		(end 328.726546 -2.614422)
		(width 0.089408)
		(layer "In9.Cu")
		(net "FM_MB_SLOT_ID1")
	)
	(segment
		(start 339.79485 -10.745724)
		(end 337.618832 -8.569706)
		(width 0.089408)
		(layer "In9.Cu")
		(net "FM_MB_SLOT_ID1")
	)
	(segment
		(start 171.704 -3.7592)
		(end 171.2976 -3.3528)
		(width 0.089408)
		(layer "In9.Cu")
		(net "FM_MB_SLOT_ID1")
	)
	(segment
		(start 23.280624 3.570224)
		(end 22.216872 4.633976)
		(width 0.089408)
		(layer "In9.Cu")
		(net "FM_MB_SLOT_ID1")
	)
	(segment
		(start 165.936676 -1.105154)
		(end 165.936676 2.86893)
		(width 0.089408)
		(layer "In9.Cu")
		(net "FM_MB_SLOT_ID1")
	)
	(segment
		(start 398.034002 -22.093936)
		(end 398.15008 -21.977858)
		(width 0.089408)
		(layer "In9.Cu")
		(net "FM_MB_SLOT_ID1")
	)
	(segment
		(start 392.797284 2.553208)
		(end 387.090412 2.553208)
		(width 0.089408)
		(layer "In9.Cu")
		(net "FM_MB_SLOT_ID1")
	)
	(segment
		(start 395.727174 -35.93338)
		(end 395.842236 -35.93338)
		(width 0.089408)
		(layer "In9.Cu")
		(net "FM_MB_SLOT_ID1")
	)
	(segment
		(start 349.738696 -22.07387)
		(end 348.203266 -20.53844)
		(width 0.089408)
		(layer "In9.Cu")
		(net "FM_MB_SLOT_ID1")
	)
	(segment
		(start 407.684732 3.7846)
		(end 403.6314 3.7846)
		(width 0.089408)
		(layer "In9.Cu")
		(net "FM_MB_SLOT_ID1")
	)
	(segment
		(start 342.44915 -18.221452)
		(end 341.719408 -17.49171)
		(width 0.089408)
		(layer "In9.Cu")
		(net "FM_MB_SLOT_ID1")
	)
	(segment
		(start 400.0246 2.1336)
		(end 393.192 2.1336)
		(width 0.089408)
		(layer "In9.Cu")
		(net "FM_MB_SLOT_ID1")
	)
	(segment
		(start 184.020968 -0.890016)
		(end 184.020968 -1.233424)
		(width 0.089408)
		(layer "In9.Cu")
		(net "FM_MB_SLOT_ID1")
	)
	(segment
		(start 173.228 -3.7592)
		(end 171.704 -3.7592)
		(width 0.089408)
		(layer "In9.Cu")
		(net "FM_MB_SLOT_ID1")
	)
	(segment
		(start 185.116978 0.205994)
		(end 184.020968 -0.890016)
		(width 0.089408)
		(layer "In9.Cu")
		(net "FM_MB_SLOT_ID1")
	)
	(segment
		(start 427.454822 -19.323304)
		(end 426.281596 -19.323304)
		(width 0.089408)
		(layer "In9.Cu")
		(net "FM_MB_SLOT_ID1")
	)
	(segment
		(start 382.384554 2.553208)
		(end 380.119128 0.287782)
		(width 0.089408)
		(layer "In9.Cu")
		(net "FM_MB_SLOT_ID1")
	)
	(segment
		(start 259.00888 3.346196)
		(end 258.971542 3.383534)
		(width 0.089408)
		(layer "In9.Cu")
		(net "FM_MB_SLOT_ID1")
	)
	(segment
		(start 331.493622 -7.24408)
		(end 330.831698 -7.24408)
		(width 0.089408)
		(layer "In9.Cu")
		(net "FM_MB_SLOT_ID1")
	)
	(segment
		(start 393.0904 2.2352)
		(end 393.0904 2.260092)
		(width 0.089408)
		(layer "In9.Cu")
		(net "FM_MB_SLOT_ID1")
	)
	(segment
		(start 16.594074 2.849372)
		(end 16.175482 3.267964)
		(width 0.089408)
		(layer "In9.Cu")
		(net "FM_MB_SLOT_ID1")
	)
	(segment
		(start 397.429736 -31.577026)
		(end 397.09471 -31.242)
		(width 0.089408)
		(layer "In9.Cu")
		(net "FM_MB_SLOT_ID1")
	)
	(segment
		(start 181.874922 -3.37947)
		(end 178.651154 -3.37947)
		(width 0.089408)
		(layer "In9.Cu")
		(net "FM_MB_SLOT_ID1")
	)
	(segment
		(start 398.020286 -22.093936)
		(end 398.034002 -22.093936)
		(width 0.089408)
		(layer "In9.Cu")
		(net "FM_MB_SLOT_ID1")
	)
	(segment
		(start 387.090158 2.553462)
		(end 386.847842 2.553462)
		(width 0.089408)
		(layer "In9.Cu")
		(net "FM_MB_SLOT_ID1")
	)
	(segment
		(start 401.3454 3.4544)
		(end 400.0246 2.1336)
		(width 0.089408)
		(layer "In9.Cu")
		(net "FM_MB_SLOT_ID1")
	)
	(segment
		(start 396.794736 -32.923226)
		(end 397.429736 -32.288226)
		(width 0.089408)
		(layer "In9.Cu")
		(net "FM_MB_SLOT_ID1")
	)
	(segment
		(start 178.399694 -3.12801)
		(end 173.85919 -3.12801)
		(width 0.089408)
		(layer "In9.Cu")
		(net "FM_MB_SLOT_ID1")
	)
	(segment
		(start 102.80269 4.633976)
		(end 25.368504 4.633976)
		(width 0.089408)
		(layer "In9.Cu")
		(net "FM_MB_SLOT_ID1")
	)
	(segment
		(start 348.203266 -19.026378)
		(end 347.39834 -18.221452)
		(width 0.089408)
		(layer "In9.Cu")
		(net "FM_MB_SLOT_ID1")
	)
	(segment
		(start 321.856862 1.172718)
		(end 321.856862 2.812288)
		(width 0.089408)
		(layer "In9.Cu")
		(net "FM_MB_SLOT_ID1")
	)
	(segment
		(start 413.922464 -19.372072)
		(end 418.4777 -19.372072)
		(width 0.089408)
		(layer "In9.Cu")
		(net "FM_MB_SLOT_ID1")
	)
	(segment
		(start 423.60977 -18.368772)
		(end 427.050454 -18.368772)
		(width 0.089408)
		(layer "In9.Cu")
		(net "FM_MB_SLOT_ID1")
	)
	(segment
		(start 387.090412 2.553208)
		(end 387.090158 2.553462)
		(width 0.089408)
		(layer "In9.Cu")
		(net "FM_MB_SLOT_ID1")
	)
	(segment
		(start 328.726546 -2.614422)
		(end 327.702926 -1.590802)
		(width 0.089408)
		(layer "In9.Cu")
		(net "FM_MB_SLOT_ID1")
	)
	(segment
		(start 418.74186 -19.107912)
		(end 421.56761 -19.107912)
		(width 0.089408)
		(layer "In9.Cu")
		(net "FM_MB_SLOT_ID1")
	)
	(segment
		(start 366.440974 -4.907026)
		(end 364.310676 -7.037324)
		(width 0.089408)
		(layer "In9.Cu")
		(net "FM_MB_SLOT_ID1")
	)
	(segment
		(start 355.571552 -22.589744)
		(end 355.224334 -22.936962)
		(width 0.089408)
		(layer "In9.Cu")
		(net "FM_MB_SLOT_ID1")
	)
	(segment
		(start 360.264964 -21.062696)
		(end 358.867964 -22.459696)
		(width 0.089408)
		(layer "In9.Cu")
		(net "FM_MB_SLOT_ID1")
	)
	(segment
		(start 380.119128 -2.194052)
		(end 377.406154 -4.907026)
		(width 0.089408)
		(layer "In9.Cu")
		(net "FM_MB_SLOT_ID1")
	)
	(segment
		(start 410.675836 -21.597366)
		(end 410.675836 -20.847812)
		(width 0.089408)
		(layer "In9.Cu")
		(net "FM_MB_SLOT_ID1")
	)
	(segment
		(start 337.618832 -8.569706)
		(end 332.819248 -8.569706)
		(width 0.089408)
		(layer "In9.Cu")
		(net "FM_MB_SLOT_ID1")
	)
	(segment
		(start 427.728888 -19.049238)
		(end 427.454822 -19.323304)
		(width 0.089408)
		(layer "In9.Cu")
		(net "FM_MB_SLOT_ID1")
	)
	(segment
		(start 360.26471 -19.508978)
		(end 360.26471 -20.904454)
		(width 0.089408)
		(layer "In9.Cu")
		(net "FM_MB_SLOT_ID1")
	)
	(segment
		(start 364.310676 -7.037324)
		(end 364.310676 -9.556496)
		(width 0.089408)
		(layer "In9.Cu")
		(net "FM_MB_SLOT_ID1")
	)
	(segment
		(start 178.651154 -3.37947)
		(end 178.399694 -3.12801)
		(width 0.089408)
		(layer "In9.Cu")
		(net "FM_MB_SLOT_ID1")
	)
	(segment
		(start 330.831698 -7.24408)
		(end 328.726546 -5.138928)
		(width 0.089408)
		(layer "In9.Cu")
		(net "FM_MB_SLOT_ID1")
	)
	(segment
		(start 184.020968 -1.233424)
		(end 181.874922 -3.37947)
		(width 0.089408)
		(layer "In9.Cu")
		(net "FM_MB_SLOT_ID1")
	)
	(segment
		(start 339.79485 -11.594846)
		(end 339.79485 -10.745724)
		(width 0.089408)
		(layer "In9.Cu")
		(net "FM_MB_SLOT_ID1")
	)
	(segment
		(start 427.468284 -18.45691)
		(end 427.728888 -18.717514)
		(width 0.089408)
		(layer "In9.Cu")
		(net "FM_MB_SLOT_ID1")
	)
	(segment
		(start 393.192 2.1336)
		(end 393.0904 2.2352)
		(width 0.089408)
		(layer "In9.Cu")
		(net "FM_MB_SLOT_ID1")
	)
	(segment
		(start 362.307632 -11.55954)
		(end 361.665012 -11.55954)
		(width 0.089408)
		(layer "In9.Cu")
		(net "FM_MB_SLOT_ID1")
	)
	(segment
		(start 348.203266 -20.53844)
		(end 348.203266 -19.026378)
		(width 0.089408)
		(layer "In9.Cu")
		(net "FM_MB_SLOT_ID1")
	)
	(segment
		(start 408.306016 4.405884)
		(end 407.684732 3.7846)
		(width 0.089408)
		(layer "In9.Cu")
		(net "FM_MB_SLOT_ID1")
	)
	(segment
		(start 380.119128 0.287782)
		(end 380.119128 -2.194052)
		(width 0.089408)
		(layer "In9.Cu")
		(net "FM_MB_SLOT_ID1")
	)
	(segment
		(start 401.820126 -22.94636)
		(end 401.978114 -22.94636)
		(width 0.089408)
		(layer "In9.Cu")
		(net "FM_MB_SLOT_ID1")
	)
	(segment
		(start 358.867964 -22.459696)
		(end 356.365302 -22.459696)
		(width 0.089408)
		(layer "In9.Cu")
		(net "FM_MB_SLOT_ID1")
	)
	(segment
		(start 377.406154 -4.907026)
		(end 366.440974 -4.907026)
		(width 0.089408)
		(layer "In9.Cu")
		(net "FM_MB_SLOT_ID1")
	)
	(segment
		(start 351.104962 -22.07387)
		(end 349.738696 -22.07387)
		(width 0.089408)
		(layer "In9.Cu")
		(net "FM_MB_SLOT_ID1")
	)
	(segment
		(start 403.3012 3.4544)
		(end 401.3454 3.4544)
		(width 0.089408)
		(layer "In9.Cu")
		(net "FM_MB_SLOT_ID1")
	)
	(segment
		(start 321.322954 3.346196)
		(end 259.00888 3.346196)
		(width 0.089408)
		(layer "In9.Cu")
		(net "FM_MB_SLOT_ID1")
	)
	(segment
		(start 398.15008 -21.977858)
		(end 400.851624 -21.977858)
		(width 0.089408)
		(layer "In9.Cu")
		(net "FM_MB_SLOT_ID1")
	)
	(segment
		(start 409.462478 -22.810724)
		(end 410.675836 -21.597366)
		(width 0.089408)
		(layer "In9.Cu")
		(net "FM_MB_SLOT_ID1")
	)
	(segment
		(start 165.936676 2.86893)
		(end 164.902134 3.903472)
		(width 0.089408)
		(layer "In9.Cu")
		(net "FM_MB_SLOT_ID1")
	)
	(segment
		(start 393.0904 2.260092)
		(end 392.797284 2.553208)
		(width 0.089408)
		(layer "In9.Cu")
		(net "FM_MB_SLOT_ID1")
	)
	(segment
		(start 403.6314 3.7846)
		(end 403.3012 3.4544)
		(width 0.089408)
		(layer "In9.Cu")
		(net "FM_MB_SLOT_ID1")
	)
	(segment
		(start 402.650452 -22.946106)
		(end 402.785834 -22.810724)
		(width 0.089408)
		(layer "In9.Cu")
		(net "FM_MB_SLOT_ID1")
	)
	(segment
		(start 396.794736 -34.98088)
		(end 396.794736 -32.923226)
		(width 0.089408)
		(layer "In9.Cu")
		(net "FM_MB_SLOT_ID1")
	)
	(segment
		(start 397.429736 -32.288226)
		(end 397.429736 -31.577026)
		(width 0.089408)
		(layer "In9.Cu")
		(net "FM_MB_SLOT_ID1")
	)
	(segment
		(start 25.368504 4.633976)
		(end 24.304752 3.570224)
		(width 0.089408)
		(layer "In9.Cu")
		(net "FM_MB_SLOT_ID1")
	)
	(segment
		(start 185.116978 1.508252)
		(end 185.116978 0.205994)
		(width 0.089408)
		(layer "In9.Cu")
		(net "FM_MB_SLOT_ID1")
	)
	(segment
		(start 395.842236 -35.93338)
		(end 396.794736 -34.98088)
		(width 0.089408)
		(layer "In9.Cu")
		(net "FM_MB_SLOT_ID1")
	)
	(segment
		(start 401.978114 -22.94636)
		(end 401.978368 -22.946106)
		(width 0.089408)
		(layer "In9.Cu")
		(net "FM_MB_SLOT_ID1")
	)
	(segment
		(start 325.417688 -1.590802)
		(end 323.216016 0.61087)
		(width 0.089408)
		(layer "In9.Cu")
		(net "FM_MB_SLOT_ID1")
	)
	(segment
		(start 322.41871 0.61087)
		(end 321.856862 1.172718)
		(width 0.089408)
		(layer "In9.Cu")
		(net "FM_MB_SLOT_ID1")
	)
	(segment
		(start 386.847842 2.553462)
		(end 386.847588 2.553208)
		(width 0.089408)
		(layer "In9.Cu")
		(net "FM_MB_SLOT_ID1")
	)
	(segment
		(start 397.09471 -23.019512)
		(end 398.020286 -22.093936)
		(width 0.089408)
		(layer "In9.Cu")
		(net "FM_MB_SLOT_ID1")
	)
	(segment
		(start 164.902134 3.903472)
		(end 103.533194 3.903472)
		(width 0.089408)
		(layer "In9.Cu")
		(net "FM_MB_SLOT_ID1")
	)
	(segment
		(start 173.85919 -3.12801)
		(end 173.228 -3.7592)
		(width 0.089408)
		(layer "In9.Cu")
		(net "FM_MB_SLOT_ID1")
	)
	(segment
		(start 355.224334 -22.936962)
		(end 351.968054 -22.936962)
		(width 0.089408)
		(layer "In9.Cu")
		(net "FM_MB_SLOT_ID1")
	)
	(segment
		(start 356.365302 -22.459696)
		(end 356.235254 -22.589744)
		(width 0.089408)
		(layer "In9.Cu")
		(net "FM_MB_SLOT_ID1")
	)
	(segment
		(start 401.978368 -22.946106)
		(end 402.650452 -22.946106)
		(width 0.089408)
		(layer "In9.Cu")
		(net "FM_MB_SLOT_ID1")
	)
	(segment
		(start 347.39834 -18.221452)
		(end 342.44915 -18.221452)
		(width 0.089408)
		(layer "In9.Cu")
		(net "FM_MB_SLOT_ID1")
	)
	(segment
		(start 168.184322 -3.3528)
		(end 165.936676 -1.105154)
		(width 0.089408)
		(layer "In9.Cu")
		(net "FM_MB_SLOT_ID1")
	)
	(segment
		(start 186.99226 3.383534)
		(end 185.116978 1.508252)
		(width 0.089408)
		(layer "In9.Cu")
		(net "FM_MB_SLOT_ID1")
	)
	(segment
		(start 24.304752 3.570224)
		(end 23.280624 3.570224)
		(width 0.089408)
		(layer "In9.Cu")
		(net "FM_MB_SLOT_ID1")
	)
	(segment
		(start 327.702926 -1.590802)
		(end 325.417688 -1.590802)
		(width 0.089408)
		(layer "In9.Cu")
		(net "FM_MB_SLOT_ID1")
	)
	(segment
		(start 426.281596 -19.323304)
		(end 425.918376 -18.960084)
		(width 0.089408)
		(layer "In9.Cu")
		(net "FM_MB_SLOT_ID1")
	)
	(segment
		(start 360.264964 -20.904708)
		(end 360.264964 -21.062696)
		(width 0.089408)
		(layer "In9.Cu")
		(net "FM_MB_SLOT_ID1")
	)
	(segment
		(start 18.122392 2.849372)
		(end 16.594074 2.849372)
		(width 0.089408)
		(layer "In9.Cu")
		(net "FM_MB_SLOT_ID1")
	)
	(segment
		(start 361.05338 -18.720308)
		(end 360.26471 -19.508978)
		(width 0.089408)
		(layer "In9.Cu")
		(net "FM_MB_SLOT_ID1")
	)
	(segment
		(start 8.784844 2.543048)
		(end 1.914652 -4.327144)
		(width 0.089408)
		(layer "In11.Cu")
		(net "FM_MB_SLOT_ID1")
	)
	(segment
		(start -4.86156 -16.490188)
		(end -4.86156 -30.097984)
		(width 0.089408)
		(layer "In11.Cu")
		(net "FM_MB_SLOT_ID1")
	)
	(segment
		(start -4.227576 -15.856204)
		(end -4.86156 -16.490188)
		(width 0.089408)
		(layer "In11.Cu")
		(net "FM_MB_SLOT_ID1")
	)
	(segment
		(start 1.914652 -4.327144)
		(end -3.757422 -4.327144)
		(width 0.089408)
		(layer "In11.Cu")
		(net "FM_MB_SLOT_ID1")
	)
	(segment
		(start -3.757422 -4.327144)
		(end -4.227576 -4.797298)
		(width 0.089408)
		(layer "In11.Cu")
		(net "FM_MB_SLOT_ID1")
	)
	(segment
		(start -4.86156 -30.097984)
		(end -4.344924 -30.61462)
		(width 0.089408)
		(layer "In11.Cu")
		(net "FM_MB_SLOT_ID1")
	)
	(segment
		(start -4.227576 -4.797298)
		(end -4.227576 -15.856204)
		(width 0.089408)
		(layer "In11.Cu")
		(net "FM_MB_SLOT_ID1")
	)
	(segment
		(start 15.450566 2.543048)
		(end 8.784844 2.543048)
		(width 0.089408)
		(layer "In11.Cu")
		(net "FM_MB_SLOT_ID1")
	)
	(segment
		(start 4.499864 -31.709868)
		(end 4.499864 -31.710122)
		(width 0.089408)
		(layer "In11.Cu")
		(net "FM_MB_SLOT_ID1")
	)
	(segment
		(start 3.404616 -30.61462)
		(end 4.499864 -31.709868)
		(width 0.089408)
		(layer "In11.Cu")
		(net "FM_MB_SLOT_ID1")
	)
	(segment
		(start -4.344924 -30.61462)
		(end 3.404616 -30.61462)
		(width 0.089408)
		(layer "In11.Cu")
		(net "FM_MB_SLOT_ID1")
	)
	(segment
		(start 16.175482 3.267964)
		(end 15.450566 2.543048)
		(width 0.089408)
		(layer "In11.Cu")
		(net "FM_MB_SLOT_ID1")
	)
	(segment
		(start 381.19304 -92.063824)
		(end 380.570486 -91.44127)
		(width 0.0889)
		(layer "F.Cu")
		(net "FM_MB_SLOT_ID0")
	)
	(segment
		(start 381.484886 -94.790006)
		(end 381.484886 -94.43466)
		(width 0.0889)
		(layer "F.Cu")
		(net "FM_MB_SLOT_ID0")
	)
	(segment
		(start 381.173482 -94.123256)
		(end 381.173482 -93.798898)
		(width 0.0889)
		(layer "F.Cu")
		(net "FM_MB_SLOT_ID0")
	)
	(segment
		(start 429.8696 -18.350992)
		(end 429.8696 -17.4244)
		(width 0.10795)
		(layer "F.Cu")
		(net "FM_MB_SLOT_ID0")
	)
	(segment
		(start 381.284988 -93.397578)
		(end 381.19304 -93.30563)
		(width 0.0889)
		(layer "F.Cu")
		(net "FM_MB_SLOT_ID0")
	)
	(segment
		(start 429.820578 -18.400014)
		(end 429.8696 -18.350992)
		(width 0.10795)
		(layer "F.Cu")
		(net "FM_MB_SLOT_ID0")
	)
	(segment
		(start 381.173482 -93.798898)
		(end 381.284988 -93.687392)
		(width 0.0889)
		(layer "F.Cu")
		(net "FM_MB_SLOT_ID0")
	)
	(segment
		(start 425.2976 -19.904202)
		(end 428.335186 -19.904202)
		(width 0.10795)
		(layer "F.Cu")
		(net "FM_MB_SLOT_ID0")
	)
	(segment
		(start 429.820578 -19.15795)
		(end 429.820578 -18.400014)
		(width 0.10795)
		(layer "F.Cu")
		(net "FM_MB_SLOT_ID0")
	)
	(segment
		(start 428.335186 -19.904202)
		(end 428.973488 -19.2659)
		(width 0.10795)
		(layer "F.Cu")
		(net "FM_MB_SLOT_ID0")
	)
	(segment
		(start 423.672 -20.7264)
		(end 424.494198 -19.904202)
		(width 0.10795)
		(layer "F.Cu")
		(net "FM_MB_SLOT_ID0")
	)
	(segment
		(start 429.712628 -19.2659)
		(end 429.820578 -19.15795)
		(width 0.10795)
		(layer "F.Cu")
		(net "FM_MB_SLOT_ID0")
	)
	(segment
		(start 381.484886 -94.43466)
		(end 381.173482 -94.123256)
		(width 0.0889)
		(layer "F.Cu")
		(net "FM_MB_SLOT_ID0")
	)
	(segment
		(start 381.284988 -93.687392)
		(end 381.284988 -93.397578)
		(width 0.0889)
		(layer "F.Cu")
		(net "FM_MB_SLOT_ID0")
	)
	(segment
		(start 381.19304 -93.30563)
		(end 381.19304 -92.063824)
		(width 0.0889)
		(layer "F.Cu")
		(net "FM_MB_SLOT_ID0")
	)
	(segment
		(start 424.494198 -19.904202)
		(end 425.2976 -19.904202)
		(width 0.10795)
		(layer "F.Cu")
		(net "FM_MB_SLOT_ID0")
	)
	(segment
		(start 428.973488 -19.2659)
		(end 429.712628 -19.2659)
		(width 0.10795)
		(layer "F.Cu")
		(net "FM_MB_SLOT_ID0")
	)
	(via
		(at 423.672 -20.7264)
		(size 0.508)
		(drill 0.254)
		(layers "F.Cu" "B.Cu")
		(net "FM_MB_SLOT_ID0")
	)
	(via
		(at 405.9682 -29.585158)
		(size 0.508)
		(drill 0.254)
		(layers "F.Cu" "B.Cu")
		(net "FM_MB_SLOT_ID0")
	)
	(via
		(at 467.62924 -9.02716)
		(size 0.508)
		(drill 0.254)
		(layers "F.Cu" "B.Cu")
		(net "FM_MB_SLOT_ID0")
	)
	(via
		(at 380.570486 -91.44127)
		(size 0.508)
		(drill 0.254)
		(layers "F.Cu" "B.Cu")
		(net "FM_MB_SLOT_ID0")
	)
	(via
		(at 381.4826 2.317496)
		(size 0.508)
		(drill 0.254)
		(layers "F.Cu" "B.Cu")
		(net "FM_MB_SLOT_ID0")
	)
	(via
		(at 428.752 -0.762)
		(size 0.508)
		(drill 0.254)
		(layers "F.Cu" "B.Cu")
		(net "FM_MB_SLOT_ID0")
	)
	(via
		(at 425.2976 -19.904202)
		(size 0.762)
		(drill 0.381)
		(layers "F.Cu" "B.Cu")
		(net "FM_MB_SLOT_ID0")
	)
	(via
		(at 383.756154 -86.388702)
		(size 0.508)
		(drill 0.254)
		(layers "F.Cu" "B.Cu")
		(net "FM_MB_SLOT_ID0")
	)
	(via
		(at 16.779494 3.477006)
		(size 0.508)
		(drill 0.254)
		(layers "F.Cu" "B.Cu")
		(net "FM_MB_SLOT_ID0")
	)
	(segment
		(start 380.118366 -90.98915)
		(end 380.118366 -89.791286)
		(width 0.10795)
		(layer "B.Cu")
		(net "FM_MB_SLOT_ID0")
	)
	(segment
		(start 380.118366 -89.791286)
		(end 379.561598 -89.234518)
		(width 0.10795)
		(layer "B.Cu")
		(net "FM_MB_SLOT_ID0")
	)
	(segment
		(start 380.570486 -91.44127)
		(end 380.118366 -90.98915)
		(width 0.10795)
		(layer "B.Cu")
		(net "FM_MB_SLOT_ID0")
	)
	(segment
		(start 379.561598 -89.234518)
		(end 379.561598 -88.541098)
		(width 0.10795)
		(layer "B.Cu")
		(net "FM_MB_SLOT_ID0")
	)
	(segment
		(start 379.561598 -88.541098)
		(end 379.222 -88.2015)
		(width 0.10795)
		(layer "B.Cu")
		(net "FM_MB_SLOT_ID0")
	)
	(segment
		(start 386.737352 -44.686982)
		(end 386.737352 -44.84497)
		(width 0.089408)
		(layer "In2.Cu")
		(net "FM_MB_SLOT_ID0")
	)
	(segment
		(start 387.841744 -41.785032)
		(end 387.841236 -41.784524)
		(width 0.089408)
		(layer "In2.Cu")
		(net "FM_MB_SLOT_ID0")
	)
	(segment
		(start 386.737098 -44.686728)
		(end 386.737352 -44.686982)
		(width 0.089408)
		(layer "In2.Cu")
		(net "FM_MB_SLOT_ID0")
	)
	(segment
		(start 406.145746 -31.242)
		(end 405.097996 -31.242)
		(width 0.089408)
		(layer "In2.Cu")
		(net "FM_MB_SLOT_ID0")
	)
	(segment
		(start 462.684368 -1.516126)
		(end 463.354928 -1.516126)
		(width 0.089408)
		(layer "In2.Cu")
		(net "FM_MB_SLOT_ID0")
	)
	(segment
		(start 406.48763 -30.900116)
		(end 406.145746 -31.242)
		(width 0.089408)
		(layer "In2.Cu")
		(net "FM_MB_SLOT_ID0")
	)
	(segment
		(start 385.793488 -72.477122)
		(end 385.973828 -72.657462)
		(width 0.089408)
		(layer "In2.Cu")
		(net "FM_MB_SLOT_ID0")
	)
	(segment
		(start 396.285466 -35.372802)
		(end 396.14475 -35.513518)
		(width 0.089408)
		(layer "In2.Cu")
		(net "FM_MB_SLOT_ID0")
	)
	(segment
		(start 387.682994 -41.784778)
		(end 387.525006 -41.784778)
		(width 0.089408)
		(layer "In2.Cu")
		(net "FM_MB_SLOT_ID0")
	)
	(segment
		(start 390.8425 -34.774886)
		(end 390.8425 -37.261292)
		(width 0.089408)
		(layer "In2.Cu")
		(net "FM_MB_SLOT_ID0")
	)
	(segment
		(start 392.782806 -34.270188)
		(end 391.347198 -34.270188)
		(width 0.089408)
		(layer "In2.Cu")
		(net "FM_MB_SLOT_ID0")
	)
	(segment
		(start 387.949694 -64.218312)
		(end 387.44652 -64.218312)
		(width 0.089408)
		(layer "In2.Cu")
		(net "FM_MB_SLOT_ID0")
	)
	(segment
		(start 390.226804 -37.876988)
		(end 390.226804 -40.493696)
		(width 0.089408)
		(layer "In2.Cu")
		(net "FM_MB_SLOT_ID0")
	)
	(segment
		(start 463.805016 -4.861306)
		(end 464.171284 -5.227574)
		(width 0.089408)
		(layer "In2.Cu")
		(net "FM_MB_SLOT_ID0")
	)
	(segment
		(start 388.563612 -63.604394)
		(end 387.949694 -64.218312)
		(width 0.089408)
		(layer "In2.Cu")
		(net "FM_MB_SLOT_ID0")
	)
	(segment
		(start 460.899764 -0.180594)
		(end 461.645 -0.92583)
		(width 0.089408)
		(layer "In2.Cu")
		(net "FM_MB_SLOT_ID0")
	)
	(segment
		(start 383.756154 -86.31809)
		(end 383.756154 -86.388702)
		(width 0.089408)
		(layer "In2.Cu")
		(net "FM_MB_SLOT_ID0")
	)
	(segment
		(start 464.171284 -5.227574)
		(end 464.171284 -6.786626)
		(width 0.089408)
		(layer "In2.Cu")
		(net "FM_MB_SLOT_ID0")
	)
	(segment
		(start 385.8768 -84.197444)
		(end 383.756154 -86.31809)
		(width 0.089408)
		(layer "In2.Cu")
		(net "FM_MB_SLOT_ID0")
	)
	(segment
		(start 396.14475 -35.513518)
		(end 395.62659 -35.513518)
		(width 0.089408)
		(layer "In2.Cu")
		(net "FM_MB_SLOT_ID0")
	)
	(segment
		(start 467.171278 -8.421878)
		(end 467.62924 -8.87984)
		(width 0.089408)
		(layer "In2.Cu")
		(net "FM_MB_SLOT_ID0")
	)
	(segment
		(start 395.62659 -35.513518)
		(end 395.607032 -35.533076)
		(width 0.089408)
		(layer "In2.Cu")
		(net "FM_MB_SLOT_ID0")
	)
	(segment
		(start 463.805016 -1.966214)
		(end 463.805016 -4.861306)
		(width 0.089408)
		(layer "In2.Cu")
		(net "FM_MB_SLOT_ID0")
	)
	(segment
		(start 388.2136 -60.844176)
		(end 389.001 -61.631576)
		(width 0.089408)
		(layer "In2.Cu")
		(net "FM_MB_SLOT_ID0")
	)
	(segment
		(start 395.561312 -35.533076)
		(end 395.388084 -35.706304)
		(width 0.089408)
		(layer "In2.Cu")
		(net "FM_MB_SLOT_ID0")
	)
	(segment
		(start 398.927828 -31.157672)
		(end 396.285466 -33.800034)
		(width 0.089408)
		(layer "In2.Cu")
		(net "FM_MB_SLOT_ID0")
	)
	(segment
		(start 389.001 -61.631576)
		(end 389.001 -62.251082)
		(width 0.089408)
		(layer "In2.Cu")
		(net "FM_MB_SLOT_ID0")
	)
	(segment
		(start 395.607032 -35.533076)
		(end 395.561312 -35.533076)
		(width 0.089408)
		(layer "In2.Cu")
		(net "FM_MB_SLOT_ID0")
	)
	(segment
		(start 385.8768 -81.20126)
		(end 385.8768 -84.197444)
		(width 0.089408)
		(layer "In2.Cu")
		(net "FM_MB_SLOT_ID0")
	)
	(segment
		(start 386.048504 -72.751442)
		(end 386.048504 -77.36713)
		(width 0.089408)
		(layer "In2.Cu")
		(net "FM_MB_SLOT_ID0")
	)
	(segment
		(start 387.452362 -58.524902)
		(end 388.2136 -59.28614)
		(width 0.089408)
		(layer "In2.Cu")
		(net "FM_MB_SLOT_ID0")
	)
	(segment
		(start 428.752 -0.762)
		(end 429.528224 0.014224)
		(width 0.089408)
		(layer "In2.Cu")
		(net "FM_MB_SLOT_ID0")
	)
	(segment
		(start 387.44652 -64.218312)
		(end 386.62737 -65.037462)
		(width 0.089408)
		(layer "In2.Cu")
		(net "FM_MB_SLOT_ID0")
	)
	(segment
		(start 405.097996 -31.242)
		(end 404.540212 -31.799784)
		(width 0.089408)
		(layer "In2.Cu")
		(net "FM_MB_SLOT_ID0")
	)
	(segment
		(start 385.793488 -70.481698)
		(end 385.793488 -72.477122)
		(width 0.089408)
		(layer "In2.Cu")
		(net "FM_MB_SLOT_ID0")
	)
	(segment
		(start 406.48763 -30.104588)
		(end 406.48763 -30.900116)
		(width 0.089408)
		(layer "In2.Cu")
		(net "FM_MB_SLOT_ID0")
	)
	(segment
		(start 456.37069 0.014224)
		(end 456.565508 -0.180594)
		(width 0.089408)
		(layer "In2.Cu")
		(net "FM_MB_SLOT_ID0")
	)
	(segment
		(start 467.62924 -8.87984)
		(end 467.62924 -9.02716)
		(width 0.089408)
		(layer "In2.Cu")
		(net "FM_MB_SLOT_ID0")
	)
	(segment
		(start 464.171284 -6.786626)
		(end 465.806536 -8.421878)
		(width 0.089408)
		(layer "In2.Cu")
		(net "FM_MB_SLOT_ID0")
	)
	(segment
		(start 388.935468 -41.785032)
		(end 387.841744 -41.785032)
		(width 0.089408)
		(layer "In2.Cu")
		(net "FM_MB_SLOT_ID0")
	)
	(segment
		(start 389.001 -62.251082)
		(end 388.563612 -62.68847)
		(width 0.089408)
		(layer "In2.Cu")
		(net "FM_MB_SLOT_ID0")
	)
	(segment
		(start 386.737352 -44.84497)
		(end 386.737606 -44.845224)
		(width 0.089408)
		(layer "In2.Cu")
		(net "FM_MB_SLOT_ID0")
	)
	(segment
		(start 385.75996 -81.08442)
		(end 385.8768 -81.20126)
		(width 0.089408)
		(layer "In2.Cu")
		(net "FM_MB_SLOT_ID0")
	)
	(segment
		(start 429.528224 0.014224)
		(end 456.37069 0.014224)
		(width 0.089408)
		(layer "In2.Cu")
		(net "FM_MB_SLOT_ID0")
	)
	(segment
		(start 387.683248 -41.784524)
		(end 387.682994 -41.784778)
		(width 0.089408)
		(layer "In2.Cu")
		(net "FM_MB_SLOT_ID0")
	)
	(segment
		(start 386.737606 -44.845224)
		(end 386.737606 -53.900832)
		(width 0.089408)
		(layer "In2.Cu")
		(net "FM_MB_SLOT_ID0")
	)
	(segment
		(start 404.540212 -31.799784)
		(end 402.753068 -31.799784)
		(width 0.089408)
		(layer "In2.Cu")
		(net "FM_MB_SLOT_ID0")
	)
	(segment
		(start 385.08686 -80.723994)
		(end 385.447286 -81.08442)
		(width 0.089408)
		(layer "In2.Cu")
		(net "FM_MB_SLOT_ID0")
	)
	(segment
		(start 465.806536 -8.421878)
		(end 467.171278 -8.421878)
		(width 0.089408)
		(layer "In2.Cu")
		(net "FM_MB_SLOT_ID0")
	)
	(segment
		(start 386.048504 -77.36713)
		(end 385.8768 -77.538834)
		(width 0.089408)
		(layer "In2.Cu")
		(net "FM_MB_SLOT_ID0")
	)
	(segment
		(start 462.094072 -0.92583)
		(end 462.684368 -1.516126)
		(width 0.089408)
		(layer "In2.Cu")
		(net "FM_MB_SLOT_ID0")
	)
	(segment
		(start 386.105146 -56.289448)
		(end 387.452362 -57.636664)
		(width 0.089408)
		(layer "In2.Cu")
		(net "FM_MB_SLOT_ID0")
	)
	(segment
		(start 390.226804 -40.493696)
		(end 388.935468 -41.785032)
		(width 0.089408)
		(layer "In2.Cu")
		(net "FM_MB_SLOT_ID0")
	)
	(segment
		(start 395.388084 -35.706304)
		(end 394.218922 -35.706304)
		(width 0.089408)
		(layer "In2.Cu")
		(net "FM_MB_SLOT_ID0")
	)
	(segment
		(start 386.105146 -54.533292)
		(end 386.105146 -56.289448)
		(width 0.089408)
		(layer "In2.Cu")
		(net "FM_MB_SLOT_ID0")
	)
	(segment
		(start 386.62737 -69.647816)
		(end 385.793488 -70.481698)
		(width 0.089408)
		(layer "In2.Cu")
		(net "FM_MB_SLOT_ID0")
	)
	(segment
		(start 386.737098 -42.85488)
		(end 386.737098 -44.686728)
		(width 0.089408)
		(layer "In2.Cu")
		(net "FM_MB_SLOT_ID0")
	)
	(segment
		(start 402.110956 -31.157672)
		(end 398.927828 -31.157672)
		(width 0.089408)
		(layer "In2.Cu")
		(net "FM_MB_SLOT_ID0")
	)
	(segment
		(start 385.8768 -79.522066)
		(end 385.08686 -80.312006)
		(width 0.089408)
		(layer "In2.Cu")
		(net "FM_MB_SLOT_ID0")
	)
	(segment
		(start 388.2136 -59.28614)
		(end 388.2136 -60.844176)
		(width 0.089408)
		(layer "In2.Cu")
		(net "FM_MB_SLOT_ID0")
	)
	(segment
		(start 387.841236 -41.784524)
		(end 387.683248 -41.784524)
		(width 0.089408)
		(layer "In2.Cu")
		(net "FM_MB_SLOT_ID0")
	)
	(segment
		(start 456.565508 -0.180594)
		(end 460.899764 -0.180594)
		(width 0.089408)
		(layer "In2.Cu")
		(net "FM_MB_SLOT_ID0")
	)
	(segment
		(start 402.753068 -31.799784)
		(end 402.110956 -31.157672)
		(width 0.089408)
		(layer "In2.Cu")
		(net "FM_MB_SLOT_ID0")
	)
	(segment
		(start 386.62737 -65.037462)
		(end 386.62737 -69.647816)
		(width 0.089408)
		(layer "In2.Cu")
		(net "FM_MB_SLOT_ID0")
	)
	(segment
		(start 385.08686 -80.312006)
		(end 385.08686 -80.723994)
		(width 0.089408)
		(layer "In2.Cu")
		(net "FM_MB_SLOT_ID0")
	)
	(segment
		(start 385.447286 -81.08442)
		(end 385.75996 -81.08442)
		(width 0.089408)
		(layer "In2.Cu")
		(net "FM_MB_SLOT_ID0")
	)
	(segment
		(start 461.645 -0.92583)
		(end 462.094072 -0.92583)
		(width 0.089408)
		(layer "In2.Cu")
		(net "FM_MB_SLOT_ID0")
	)
	(segment
		(start 385.8768 -77.538834)
		(end 385.8768 -79.522066)
		(width 0.089408)
		(layer "In2.Cu")
		(net "FM_MB_SLOT_ID0")
	)
	(segment
		(start 387.525006 -41.784778)
		(end 386.737606 -42.572178)
		(width 0.089408)
		(layer "In2.Cu")
		(net "FM_MB_SLOT_ID0")
	)
	(segment
		(start 386.737606 -42.572178)
		(end 386.737606 -42.854372)
		(width 0.089408)
		(layer "In2.Cu")
		(net "FM_MB_SLOT_ID0")
	)
	(segment
		(start 463.354928 -1.516126)
		(end 463.805016 -1.966214)
		(width 0.089408)
		(layer "In2.Cu")
		(net "FM_MB_SLOT_ID0")
	)
	(segment
		(start 390.8425 -37.261292)
		(end 390.226804 -37.876988)
		(width 0.089408)
		(layer "In2.Cu")
		(net "FM_MB_SLOT_ID0")
	)
	(segment
		(start 386.737606 -53.900832)
		(end 386.105146 -54.533292)
		(width 0.089408)
		(layer "In2.Cu")
		(net "FM_MB_SLOT_ID0")
	)
	(segment
		(start 385.973828 -72.657462)
		(end 385.973828 -72.676766)
		(width 0.089408)
		(layer "In2.Cu")
		(net "FM_MB_SLOT_ID0")
	)
	(segment
		(start 385.973828 -72.676766)
		(end 386.048504 -72.751442)
		(width 0.089408)
		(layer "In2.Cu")
		(net "FM_MB_SLOT_ID0")
	)
	(segment
		(start 387.452362 -57.636664)
		(end 387.452362 -58.524902)
		(width 0.089408)
		(layer "In2.Cu")
		(net "FM_MB_SLOT_ID0")
	)
	(segment
		(start 391.347198 -34.270188)
		(end 390.8425 -34.774886)
		(width 0.089408)
		(layer "In2.Cu")
		(net "FM_MB_SLOT_ID0")
	)
	(segment
		(start 388.563612 -62.68847)
		(end 388.563612 -63.604394)
		(width 0.089408)
		(layer "In2.Cu")
		(net "FM_MB_SLOT_ID0")
	)
	(segment
		(start 405.9682 -29.585158)
		(end 406.48763 -30.104588)
		(width 0.089408)
		(layer "In2.Cu")
		(net "FM_MB_SLOT_ID0")
	)
	(segment
		(start 386.737606 -42.854372)
		(end 386.737098 -42.85488)
		(width 0.089408)
		(layer "In2.Cu")
		(net "FM_MB_SLOT_ID0")
	)
	(segment
		(start 396.285466 -33.800034)
		(end 396.285466 -35.372802)
		(width 0.089408)
		(layer "In2.Cu")
		(net "FM_MB_SLOT_ID0")
	)
	(segment
		(start 394.218922 -35.706304)
		(end 392.782806 -34.270188)
		(width 0.089408)
		(layer "In2.Cu")
		(net "FM_MB_SLOT_ID0")
	)
	(segment
		(start 388.683754 -2.019046)
		(end 400.025362 -2.019046)
		(width 0.089408)
		(layer "In4.Cu")
		(net "FM_MB_SLOT_ID0")
	)
	(segment
		(start 406.527254 -1.282446)
		(end 407.592276 -0.217424)
		(width 0.089408)
		(layer "In4.Cu")
		(net "FM_MB_SLOT_ID0")
	)
	(segment
		(start 407.592276 -0.217424)
		(end 415.825686 -0.217424)
		(width 0.089408)
		(layer "In4.Cu")
		(net "FM_MB_SLOT_ID0")
	)
	(segment
		(start 426.597572 -1.162304)
		(end 428.351696 -1.162304)
		(width 0.089408)
		(layer "In4.Cu")
		(net "FM_MB_SLOT_ID0")
	)
	(segment
		(start 386.1816 0.7874)
		(end 386.715 0.254)
		(width 0.089408)
		(layer "In4.Cu")
		(net "FM_MB_SLOT_ID0")
	)
	(segment
		(start 420.348664 1.334262)
		(end 422.209722 -0.526796)
		(width 0.089408)
		(layer "In4.Cu")
		(net "FM_MB_SLOT_ID0")
	)
	(segment
		(start 386.715 -1.397)
		(end 387.5532 -2.2352)
		(width 0.089408)
		(layer "In4.Cu")
		(net "FM_MB_SLOT_ID0")
	)
	(segment
		(start 387.5532 -2.2352)
		(end 388.4676 -2.2352)
		(width 0.089408)
		(layer "In4.Cu")
		(net "FM_MB_SLOT_ID0")
	)
	(segment
		(start 428.351696 -1.162304)
		(end 428.752 -0.762)
		(width 0.089408)
		(layer "In4.Cu")
		(net "FM_MB_SLOT_ID0")
	)
	(segment
		(start 400.025362 -2.019046)
		(end 400.272504 -1.771904)
		(width 0.089408)
		(layer "In4.Cu")
		(net "FM_MB_SLOT_ID0")
	)
	(segment
		(start 382.1938 0.7874)
		(end 386.1816 0.7874)
		(width 0.089408)
		(layer "In4.Cu")
		(net "FM_MB_SLOT_ID0")
	)
	(segment
		(start 386.715 0.254)
		(end 386.715 -1.397)
		(width 0.089408)
		(layer "In4.Cu")
		(net "FM_MB_SLOT_ID0")
	)
	(segment
		(start 403.027896 -1.771904)
		(end 403.517354 -1.282446)
		(width 0.089408)
		(layer "In4.Cu")
		(net "FM_MB_SLOT_ID0")
	)
	(segment
		(start 388.4676 -2.2352)
		(end 388.683754 -2.019046)
		(width 0.089408)
		(layer "In4.Cu")
		(net "FM_MB_SLOT_ID0")
	)
	(segment
		(start 381.381 2.2352)
		(end 381.381 1.6002)
		(width 0.089408)
		(layer "In4.Cu")
		(net "FM_MB_SLOT_ID0")
	)
	(segment
		(start 417.377372 1.334262)
		(end 420.348664 1.334262)
		(width 0.089408)
		(layer "In4.Cu")
		(net "FM_MB_SLOT_ID0")
	)
	(segment
		(start 381.381 1.6002)
		(end 382.1938 0.7874)
		(width 0.089408)
		(layer "In4.Cu")
		(net "FM_MB_SLOT_ID0")
	)
	(segment
		(start 415.825686 -0.217424)
		(end 417.377372 1.334262)
		(width 0.089408)
		(layer "In4.Cu")
		(net "FM_MB_SLOT_ID0")
	)
	(segment
		(start 381.4826 2.3368)
		(end 381.381 2.2352)
		(width 0.089408)
		(layer "In4.Cu")
		(net "FM_MB_SLOT_ID0")
	)
	(segment
		(start 422.209722 -0.526796)
		(end 425.962064 -0.526796)
		(width 0.089408)
		(layer "In4.Cu")
		(net "FM_MB_SLOT_ID0")
	)
	(segment
		(start 425.962064 -0.526796)
		(end 426.597572 -1.162304)
		(width 0.089408)
		(layer "In4.Cu")
		(net "FM_MB_SLOT_ID0")
	)
	(segment
		(start 381.4826 2.317496)
		(end 381.4826 2.3368)
		(width 0.089408)
		(layer "In4.Cu")
		(net "FM_MB_SLOT_ID0")
	)
	(segment
		(start 400.272504 -1.771904)
		(end 403.027896 -1.771904)
		(width 0.089408)
		(layer "In4.Cu")
		(net "FM_MB_SLOT_ID0")
	)
	(segment
		(start 403.517354 -1.282446)
		(end 406.527254 -1.282446)
		(width 0.089408)
		(layer "In4.Cu")
		(net "FM_MB_SLOT_ID0")
	)
	(segment
		(start 16.779494 3.477006)
		(end 17.010888 3.245612)
		(width 0.089408)
		(layer "In9.Cu")
		(net "FM_MB_SLOT_ID0")
	)
	(segment
		(start 25.289256 4.824984)
		(end 102.881938 4.824984)
		(width 0.089408)
		(layer "In9.Cu")
		(net "FM_MB_SLOT_ID0")
	)
	(segment
		(start 382.625854 -87.8459)
		(end 383.756154 -86.7156)
		(width 0.089408)
		(layer "In9.Cu")
		(net "FM_MB_SLOT_ID0")
	)
	(segment
		(start 322.101718 2.837942)
		(end 322.101718 1.312418)
		(width 0.089408)
		(layer "In9.Cu")
		(net "FM_MB_SLOT_ID0")
	)
	(segment
		(start 356.286054 -22.268688)
		(end 358.788716 -22.268688)
		(width 0.089408)
		(layer "In9.Cu")
		(net "FM_MB_SLOT_ID0")
	)
	(segment
		(start 414.82264 -28.15971)
		(end 415.417 -27.56535)
		(width 0.089408)
		(layer "In9.Cu")
		(net "FM_MB_SLOT_ID0")
	)
	(segment
		(start 342.024716 -12.451334)
		(end 342.024716 -17.285208)
		(width 0.089408)
		(layer "In9.Cu")
		(net "FM_MB_SLOT_ID0")
	)
	(segment
		(start 349.855028 -21.882862)
		(end 351.18421 -21.882862)
		(width 0.089408)
		(layer "In9.Cu")
		(net "FM_MB_SLOT_ID0")
	)
	(segment
		(start 363.428026 -9.517126)
		(end 363.428026 -7.538974)
		(width 0.089408)
		(layer "In9.Cu")
		(net "FM_MB_SLOT_ID0")
	)
	(segment
		(start 178.491134 -2.845816)
		(end 178.83378 -3.188462)
		(width 0.089408)
		(layer "In9.Cu")
		(net "FM_MB_SLOT_ID0")
	)
	(segment
		(start 23.359872 3.761232)
		(end 24.225504 3.761232)
		(width 0.089408)
		(layer "In9.Cu")
		(net "FM_MB_SLOT_ID0")
	)
	(segment
		(start 414.534604 -28.15971)
		(end 414.82264 -28.15971)
		(width 0.089408)
		(layer "In9.Cu")
		(net "FM_MB_SLOT_ID0")
	)
	(segment
		(start 321.318128 3.621532)
		(end 322.101718 2.837942)
		(width 0.089408)
		(layer "In9.Cu")
		(net "FM_MB_SLOT_ID0")
	)
	(segment
		(start 102.881938 4.824984)
		(end 103.612442 4.09448)
		(width 0.089408)
		(layer "In9.Cu")
		(net "FM_MB_SLOT_ID0")
	)
	(segment
		(start 416.56 -22.987)
		(end 421.512492 -22.987)
		(width 0.089408)
		(layer "In9.Cu")
		(net "FM_MB_SLOT_ID0")
	)
	(segment
		(start 323.364352 0.833374)
		(end 325.59752 -1.399794)
		(width 0.089408)
		(layer "In9.Cu")
		(net "FM_MB_SLOT_ID0")
	)
	(segment
		(start 415.417 -24.13)
		(end 416.56 -22.987)
		(width 0.089408)
		(layer "In9.Cu")
		(net "FM_MB_SLOT_ID0")
	)
	(segment
		(start 335.041748 -6.749288)
		(end 336.63636 -8.3439)
		(width 0.089408)
		(layer "In9.Cu")
		(net "FM_MB_SLOT_ID0")
	)
	(segment
		(start 347.263466 -17.76349)
		(end 348.42196 -18.921984)
		(width 0.089408)
		(layer "In9.Cu")
		(net "FM_MB_SLOT_ID0")
	)
	(segment
		(start 22.29612 4.824984)
		(end 23.359872 3.761232)
		(width 0.089408)
		(layer "In9.Cu")
		(net "FM_MB_SLOT_ID0")
	)
	(segment
		(start 186.959748 3.621278)
		(end 321.317874 3.621278)
		(width 0.089408)
		(layer "In9.Cu")
		(net "FM_MB_SLOT_ID0")
	)
	(segment
		(start 336.63636 -8.3439)
		(end 337.917282 -8.3439)
		(width 0.089408)
		(layer "In9.Cu")
		(net "FM_MB_SLOT_ID0")
	)
	(segment
		(start 348.42196 -18.921984)
		(end 348.42196 -20.449794)
		(width 0.089408)
		(layer "In9.Cu")
		(net "FM_MB_SLOT_ID0")
	)
	(segment
		(start 181.795674 -3.188462)
		(end 183.82996 -1.154176)
		(width 0.089408)
		(layer "In9.Cu")
		(net "FM_MB_SLOT_ID0")
	)
	(segment
		(start 322.580762 0.833374)
		(end 323.364352 0.833374)
		(width 0.089408)
		(layer "In9.Cu")
		(net "FM_MB_SLOT_ID0")
	)
	(segment
		(start 423.417746 -20.980654)
		(end 423.672 -20.7264)
		(width 0.089408)
		(layer "In9.Cu")
		(net "FM_MB_SLOT_ID0")
	)
	(segment
		(start 360.073702 -20.983702)
		(end 360.073702 -19.42973)
		(width 0.089408)
		(layer "In9.Cu")
		(net "FM_MB_SLOT_ID0")
	)
	(segment
		(start 355.145086 -22.745954)
		(end 355.492304 -22.398736)
		(width 0.089408)
		(layer "In9.Cu")
		(net "FM_MB_SLOT_ID0")
	)
	(segment
		(start 363.428026 -7.538974)
		(end 366.250982 -4.716018)
		(width 0.089408)
		(layer "In9.Cu")
		(net "FM_MB_SLOT_ID0")
	)
	(segment
		(start 421.512492 -22.987)
		(end 423.417746 -21.081746)
		(width 0.089408)
		(layer "In9.Cu")
		(net "FM_MB_SLOT_ID0")
	)
	(segment
		(start 348.42196 -20.449794)
		(end 349.855028 -21.882862)
		(width 0.089408)
		(layer "In9.Cu")
		(net "FM_MB_SLOT_ID0")
	)
	(segment
		(start 414.274 -29.4894)
		(end 414.274 -28.420314)
		(width 0.089408)
		(layer "In9.Cu")
		(net "FM_MB_SLOT_ID0")
	)
	(segment
		(start 171.717208 -3.161792)
		(end 172.033184 -2.845816)
		(width 0.089408)
		(layer "In9.Cu")
		(net "FM_MB_SLOT_ID0")
	)
	(segment
		(start 184.92597 1.5875)
		(end 186.959748 3.621278)
		(width 0.089408)
		(layer "In9.Cu")
		(net "FM_MB_SLOT_ID0")
	)
	(segment
		(start 381.66294 -87.8459)
		(end 382.625854 -87.8459)
		(width 0.089408)
		(layer "In9.Cu")
		(net "FM_MB_SLOT_ID0")
	)
	(segment
		(start 414.274 -28.420314)
		(end 414.534604 -28.15971)
		(width 0.089408)
		(layer "In9.Cu")
		(net "FM_MB_SLOT_ID0")
	)
	(segment
		(start 328.917554 -5.05968)
		(end 330.607162 -6.749288)
		(width 0.089408)
		(layer "In9.Cu")
		(net "FM_MB_SLOT_ID0")
	)
	(segment
		(start 406.8953 -30.512258)
		(end 413.352742 -30.512258)
		(width 0.089408)
		(layer "In9.Cu")
		(net "FM_MB_SLOT_ID0")
	)
	(segment
		(start 327.782174 -1.399794)
		(end 328.917554 -2.535174)
		(width 0.089408)
		(layer "In9.Cu")
		(net "FM_MB_SLOT_ID0")
	)
	(segment
		(start 342.502998 -17.76349)
		(end 347.263466 -17.76349)
		(width 0.089408)
		(layer "In9.Cu")
		(net "FM_MB_SLOT_ID0")
	)
	(segment
		(start 330.607162 -6.749288)
		(end 335.041748 -6.749288)
		(width 0.089408)
		(layer "In9.Cu")
		(net "FM_MB_SLOT_ID0")
	)
	(segment
		(start 184.92597 0.285242)
		(end 184.92597 1.5875)
		(width 0.089408)
		(layer "In9.Cu")
		(net "FM_MB_SLOT_ID0")
	)
	(segment
		(start 381.4826 1.9558)
		(end 381.4826 2.317496)
		(width 0.089408)
		(layer "In9.Cu")
		(net "FM_MB_SLOT_ID0")
	)
	(segment
		(start 360.862372 -12.08278)
		(end 363.428026 -9.517126)
		(width 0.089408)
		(layer "In9.Cu")
		(net "FM_MB_SLOT_ID0")
	)
	(segment
		(start 168.26357 -3.161792)
		(end 171.717208 -3.161792)
		(width 0.089408)
		(layer "In9.Cu")
		(net "FM_MB_SLOT_ID0")
	)
	(segment
		(start 413.6898 -29.718)
		(end 414.0454 -29.718)
		(width 0.089408)
		(layer "In9.Cu")
		(net "FM_MB_SLOT_ID0")
	)
	(segment
		(start 355.492304 -22.398736)
		(end 356.00767 -22.398736)
		(width 0.089408)
		(layer "In9.Cu")
		(net "FM_MB_SLOT_ID0")
	)
	(segment
		(start 178.83378 -3.188462)
		(end 181.795674 -3.188462)
		(width 0.089408)
		(layer "In9.Cu")
		(net "FM_MB_SLOT_ID0")
	)
	(segment
		(start 414.0454 -29.718)
		(end 414.274 -29.4894)
		(width 0.089408)
		(layer "In9.Cu")
		(net "FM_MB_SLOT_ID0")
	)
	(segment
		(start 352.047302 -22.745954)
		(end 355.145086 -22.745954)
		(width 0.089408)
		(layer "In9.Cu")
		(net "FM_MB_SLOT_ID0")
	)
	(segment
		(start 18.248376 3.245612)
		(end 19.827748 4.824984)
		(width 0.089408)
		(layer "In9.Cu")
		(net "FM_MB_SLOT_ID0")
	)
	(segment
		(start 342.024716 -17.285208)
		(end 342.502998 -17.76349)
		(width 0.089408)
		(layer "In9.Cu")
		(net "FM_MB_SLOT_ID0")
	)
	(segment
		(start 381.1524 -90.859356)
		(end 381.1524 -88.35644)
		(width 0.089408)
		(layer "In9.Cu")
		(net "FM_MB_SLOT_ID0")
	)
	(segment
		(start 405.9682 -29.585158)
		(end 406.8953 -30.512258)
		(width 0.089408)
		(layer "In9.Cu")
		(net "FM_MB_SLOT_ID0")
	)
	(segment
		(start 379.878082 0.351282)
		(end 381.4826 1.9558)
		(width 0.089408)
		(layer "In9.Cu")
		(net "FM_MB_SLOT_ID0")
	)
	(segment
		(start 321.317874 3.621278)
		(end 321.318128 3.621532)
		(width 0.089408)
		(layer "In9.Cu")
		(net "FM_MB_SLOT_ID0")
	)
	(segment
		(start 356.007924 -22.398482)
		(end 356.15626 -22.398482)
		(width 0.089408)
		(layer "In9.Cu")
		(net "FM_MB_SLOT_ID0")
	)
	(segment
		(start 172.033184 -2.845816)
		(end 178.491134 -2.845816)
		(width 0.089408)
		(layer "In9.Cu")
		(net "FM_MB_SLOT_ID0")
	)
	(segment
		(start 413.512 -29.8958)
		(end 413.6898 -29.718)
		(width 0.089408)
		(layer "In9.Cu")
		(net "FM_MB_SLOT_ID0")
	)
	(segment
		(start 383.756154 -86.7156)
		(end 383.756154 -86.388702)
		(width 0.089408)
		(layer "In9.Cu")
		(net "FM_MB_SLOT_ID0")
	)
	(segment
		(start 380.570486 -91.44127)
		(end 381.1524 -90.859356)
		(width 0.089408)
		(layer "In9.Cu")
		(net "FM_MB_SLOT_ID0")
	)
	(segment
		(start 377.326906 -4.716018)
		(end 379.878082 -2.164842)
		(width 0.089408)
		(layer "In9.Cu")
		(net "FM_MB_SLOT_ID0")
	)
	(segment
		(start 358.788716 -22.268688)
		(end 360.073702 -20.983702)
		(width 0.089408)
		(layer "In9.Cu")
		(net "FM_MB_SLOT_ID0")
	)
	(segment
		(start 322.101718 1.312418)
		(end 322.580762 0.833374)
		(width 0.089408)
		(layer "In9.Cu")
		(net "FM_MB_SLOT_ID0")
	)
	(segment
		(start 381.1524 -88.35644)
		(end 381.66294 -87.8459)
		(width 0.089408)
		(layer "In9.Cu")
		(net "FM_MB_SLOT_ID0")
	)
	(segment
		(start 413.512 -30.353)
		(end 413.512 -29.8958)
		(width 0.089408)
		(layer "In9.Cu")
		(net "FM_MB_SLOT_ID0")
	)
	(segment
		(start 415.417 -27.56535)
		(end 415.417 -24.13)
		(width 0.089408)
		(layer "In9.Cu")
		(net "FM_MB_SLOT_ID0")
	)
	(segment
		(start 413.352742 -30.512258)
		(end 413.512 -30.353)
		(width 0.089408)
		(layer "In9.Cu")
		(net "FM_MB_SLOT_ID0")
	)
	(segment
		(start 166.183818 -1.08204)
		(end 168.26357 -3.161792)
		(width 0.089408)
		(layer "In9.Cu")
		(net "FM_MB_SLOT_ID0")
	)
	(segment
		(start 166.183818 2.892044)
		(end 166.183818 -1.08204)
		(width 0.089408)
		(layer "In9.Cu")
		(net "FM_MB_SLOT_ID0")
	)
	(segment
		(start 24.225504 3.761232)
		(end 25.289256 4.824984)
		(width 0.089408)
		(layer "In9.Cu")
		(net "FM_MB_SLOT_ID0")
	)
	(segment
		(start 183.82996 -1.154176)
		(end 183.82996 -0.810768)
		(width 0.089408)
		(layer "In9.Cu")
		(net "FM_MB_SLOT_ID0")
	)
	(segment
		(start 356.15626 -22.398482)
		(end 356.286054 -22.268688)
		(width 0.089408)
		(layer "In9.Cu")
		(net "FM_MB_SLOT_ID0")
	)
	(segment
		(start 337.917282 -8.3439)
		(end 342.024716 -12.451334)
		(width 0.089408)
		(layer "In9.Cu")
		(net "FM_MB_SLOT_ID0")
	)
	(segment
		(start 164.981382 4.09448)
		(end 166.183818 2.892044)
		(width 0.089408)
		(layer "In9.Cu")
		(net "FM_MB_SLOT_ID0")
	)
	(segment
		(start 360.862372 -18.64106)
		(end 360.862372 -12.08278)
		(width 0.089408)
		(layer "In9.Cu")
		(net "FM_MB_SLOT_ID0")
	)
	(segment
		(start 356.00767 -22.398736)
		(end 356.007924 -22.398482)
		(width 0.089408)
		(layer "In9.Cu")
		(net "FM_MB_SLOT_ID0")
	)
	(segment
		(start 19.827748 4.824984)
		(end 22.29612 4.824984)
		(width 0.089408)
		(layer "In9.Cu")
		(net "FM_MB_SLOT_ID0")
	)
	(segment
		(start 351.18421 -21.882862)
		(end 352.047302 -22.745954)
		(width 0.089408)
		(layer "In9.Cu")
		(net "FM_MB_SLOT_ID0")
	)
	(segment
		(start 328.917554 -2.535174)
		(end 328.917554 -5.05968)
		(width 0.089408)
		(layer "In9.Cu")
		(net "FM_MB_SLOT_ID0")
	)
	(segment
		(start 379.878082 -2.164842)
		(end 379.878082 0.351282)
		(width 0.089408)
		(layer "In9.Cu")
		(net "FM_MB_SLOT_ID0")
	)
	(segment
		(start 103.612442 4.09448)
		(end 164.981382 4.09448)
		(width 0.089408)
		(layer "In9.Cu")
		(net "FM_MB_SLOT_ID0")
	)
	(segment
		(start 183.82996 -0.810768)
		(end 184.92597 0.285242)
		(width 0.089408)
		(layer "In9.Cu")
		(net "FM_MB_SLOT_ID0")
	)
	(segment
		(start 325.59752 -1.399794)
		(end 327.782174 -1.399794)
		(width 0.089408)
		(layer "In9.Cu")
		(net "FM_MB_SLOT_ID0")
	)
	(segment
		(start 17.010888 3.245612)
		(end 18.248376 3.245612)
		(width 0.089408)
		(layer "In9.Cu")
		(net "FM_MB_SLOT_ID0")
	)
	(segment
		(start 423.417746 -21.081746)
		(end 423.417746 -20.980654)
		(width 0.089408)
		(layer "In9.Cu")
		(net "FM_MB_SLOT_ID0")
	)
	(segment
		(start 366.250982 -4.716018)
		(end 377.326906 -4.716018)
		(width 0.089408)
		(layer "In9.Cu")
		(net "FM_MB_SLOT_ID0")
	)
	(segment
		(start 360.073702 -19.42973)
		(end 360.862372 -18.64106)
		(width 0.089408)
		(layer "In9.Cu")
		(net "FM_MB_SLOT_ID0")
	)
	(segment
		(start -4.418584 -15.731744)
		(end -4.418584 -4.71805)
		(width 0.089408)
		(layer "In11.Cu")
		(net "FM_MB_SLOT_ID0")
	)
	(segment
		(start 433.160424 -20.189698)
		(end 439.142378 -20.189698)
		(width 0.089408)
		(layer "In11.Cu")
		(net "FM_MB_SLOT_ID0")
	)
	(segment
		(start -4.418584 -4.71805)
		(end -3.83667 -4.136136)
		(width 0.089408)
		(layer "In11.Cu")
		(net "FM_MB_SLOT_ID0")
	)
	(segment
		(start 464.51266 -9.19734)
		(end 465.5947 -9.19734)
		(width 0.089408)
		(layer "In11.Cu")
		(net "FM_MB_SLOT_ID0")
	)
	(segment
		(start 464.15833 -9.55167)
		(end 464.51266 -9.19734)
		(width 0.089408)
		(layer "In11.Cu")
		(net "FM_MB_SLOT_ID0")
	)
	(segment
		(start -5.052568 -30.177232)
		(end -5.052568 -16.365728)
		(width 0.089408)
		(layer "In11.Cu")
		(net "FM_MB_SLOT_ID0")
	)
	(segment
		(start 450.000116 -18.81632)
		(end 450.476874 -18.339562)
		(width 0.089408)
		(layer "In11.Cu")
		(net "FM_MB_SLOT_ID0")
	)
	(segment
		(start 424.617896 -21.672296)
		(end 428.102776 -21.672296)
		(width 0.089408)
		(layer "In11.Cu")
		(net "FM_MB_SLOT_ID0")
	)
	(segment
		(start 452.328534 -15.192756)
		(end 452.328534 -13.118846)
		(width 0.089408)
		(layer "In11.Cu")
		(net "FM_MB_SLOT_ID0")
	)
	(segment
		(start 16.553688 3.695192)
		(end 16.771874 3.477006)
		(width 0.089408)
		(layer "In11.Cu")
		(net "FM_MB_SLOT_ID0")
	)
	(segment
		(start 462.928716 -9.786112)
		(end 463.163158 -9.55167)
		(width 0.089408)
		(layer "In11.Cu")
		(net "FM_MB_SLOT_ID0")
	)
	(segment
		(start 14.237716 2.737866)
		(end 15.195042 3.695192)
		(width 0.089408)
		(layer "In11.Cu")
		(net "FM_MB_SLOT_ID0")
	)
	(segment
		(start 432.302666 -21.047456)
		(end 433.160424 -20.189698)
		(width 0.089408)
		(layer "In11.Cu")
		(net "FM_MB_SLOT_ID0")
	)
	(segment
		(start 465.87156 -9.4742)
		(end 467.1822 -9.4742)
		(width 0.089408)
		(layer "In11.Cu")
		(net "FM_MB_SLOT_ID0")
	)
	(segment
		(start 15.195042 3.695192)
		(end 16.553688 3.695192)
		(width 0.089408)
		(layer "In11.Cu")
		(net "FM_MB_SLOT_ID0")
	)
	(segment
		(start 440.0804 -19.251676)
		(end 445.61887 -19.251676)
		(width 0.089408)
		(layer "In11.Cu")
		(net "FM_MB_SLOT_ID0")
	)
	(segment
		(start 454.665588 -10.781792)
		(end 462.26476 -10.781792)
		(width 0.089408)
		(layer "In11.Cu")
		(net "FM_MB_SLOT_ID0")
	)
	(segment
		(start 16.771874 3.477006)
		(end 16.779494 3.477006)
		(width 0.089408)
		(layer "In11.Cu")
		(net "FM_MB_SLOT_ID0")
	)
	(segment
		(start 467.1822 -9.4742)
		(end 467.62924 -9.02716)
		(width 0.089408)
		(layer "In11.Cu")
		(net "FM_MB_SLOT_ID0")
	)
	(segment
		(start 423.672 -20.7264)
		(end 424.617896 -21.672296)
		(width 0.089408)
		(layer "In11.Cu")
		(net "FM_MB_SLOT_ID0")
	)
	(segment
		(start 3.10007 -31.709868)
		(end 2.19583 -30.805628)
		(width 0.089408)
		(layer "In11.Cu")
		(net "FM_MB_SLOT_ID0")
	)
	(segment
		(start -4.424172 -30.805628)
		(end -5.052568 -30.177232)
		(width 0.089408)
		(layer "In11.Cu")
		(net "FM_MB_SLOT_ID0")
	)
	(segment
		(start -3.83667 -4.136136)
		(end 1.835404 -4.136136)
		(width 0.089408)
		(layer "In11.Cu")
		(net "FM_MB_SLOT_ID0")
	)
	(segment
		(start 8.709406 2.737866)
		(end 14.237716 2.737866)
		(width 0.089408)
		(layer "In11.Cu")
		(net "FM_MB_SLOT_ID0")
	)
	(segment
		(start 465.5947 -9.19734)
		(end 465.87156 -9.4742)
		(width 0.089408)
		(layer "In11.Cu")
		(net "FM_MB_SLOT_ID0")
	)
	(segment
		(start 1.835404 -4.136136)
		(end 8.709406 2.737866)
		(width 0.089408)
		(layer "In11.Cu")
		(net "FM_MB_SLOT_ID0")
	)
	(segment
		(start 428.727616 -21.047456)
		(end 432.302666 -21.047456)
		(width 0.089408)
		(layer "In11.Cu")
		(net "FM_MB_SLOT_ID0")
	)
	(segment
		(start 450.476874 -17.044416)
		(end 452.328534 -15.192756)
		(width 0.089408)
		(layer "In11.Cu")
		(net "FM_MB_SLOT_ID0")
	)
	(segment
		(start 428.102776 -21.672296)
		(end 428.727616 -21.047456)
		(width 0.089408)
		(layer "In11.Cu")
		(net "FM_MB_SLOT_ID0")
	)
	(segment
		(start 445.61887 -19.251676)
		(end 445.701928 -19.334734)
		(width 0.089408)
		(layer "In11.Cu")
		(net "FM_MB_SLOT_ID0")
	)
	(segment
		(start -5.052568 -16.365728)
		(end -4.418584 -15.731744)
		(width 0.089408)
		(layer "In11.Cu")
		(net "FM_MB_SLOT_ID0")
	)
	(segment
		(start 445.701928 -19.334734)
		(end 447.458592 -19.334734)
		(width 0.089408)
		(layer "In11.Cu")
		(net "FM_MB_SLOT_ID0")
	)
	(segment
		(start 462.928716 -10.117836)
		(end 462.928716 -9.786112)
		(width 0.089408)
		(layer "In11.Cu")
		(net "FM_MB_SLOT_ID0")
	)
	(segment
		(start 462.26476 -10.781792)
		(end 462.928716 -10.117836)
		(width 0.089408)
		(layer "In11.Cu")
		(net "FM_MB_SLOT_ID0")
	)
	(segment
		(start 450.476874 -18.339562)
		(end 450.476874 -17.044416)
		(width 0.089408)
		(layer "In11.Cu")
		(net "FM_MB_SLOT_ID0")
	)
	(segment
		(start 452.328534 -13.118846)
		(end 454.665588 -10.781792)
		(width 0.089408)
		(layer "In11.Cu")
		(net "FM_MB_SLOT_ID0")
	)
	(segment
		(start 2.19583 -30.805628)
		(end -4.424172 -30.805628)
		(width 0.089408)
		(layer "In11.Cu")
		(net "FM_MB_SLOT_ID0")
	)
	(segment
		(start 463.163158 -9.55167)
		(end 464.15833 -9.55167)
		(width 0.089408)
		(layer "In11.Cu")
		(net "FM_MB_SLOT_ID0")
	)
	(segment
		(start 439.142378 -20.189698)
		(end 440.0804 -19.251676)
		(width 0.089408)
		(layer "In11.Cu")
		(net "FM_MB_SLOT_ID0")
	)
	(segment
		(start 3.10007 -31.710122)
		(end 3.10007 -31.709868)
		(width 0.089408)
		(layer "In11.Cu")
		(net "FM_MB_SLOT_ID0")
	)
	(segment
		(start 447.977006 -18.81632)
		(end 450.000116 -18.81632)
		(width 0.089408)
		(layer "In11.Cu")
		(net "FM_MB_SLOT_ID0")
	)
	(segment
		(start 447.458592 -19.334734)
		(end 447.977006 -18.81632)
		(width 0.089408)
		(layer "In11.Cu")
		(net "FM_MB_SLOT_ID0")
	)
	(segment
		(start 22.479 -26.907744)
		(end 22.479 -29.972)
		(width 0.10795)
		(layer "F.Cu")
		(net "FM_MATED_IN_N")
	)
	(segment
		(start 23.15464 -32.76346)
		(end 20.903692 -35.014408)
		(width 0.10795)
		(layer "F.Cu")
		(net "FM_MATED_IN_N")
	)
	(segment
		(start 1.83515 -34.55035)
		(end 1.599946 -34.315146)
		(width 0.10795)
		(layer "F.Cu")
		(net "FM_MATED_IN_N")
	)
	(segment
		(start 20.2184 -39.4716)
		(end 15.6972 -39.4716)
		(width 0.10795)
		(layer "F.Cu")
		(net "FM_MATED_IN_N")
	)
	(segment
		(start 15.6972 -39.4716)
		(end 14.4018 -38.1762)
		(width 0.10795)
		(layer "F.Cu")
		(net "FM_MATED_IN_N")
	)
	(segment
		(start 11.332464 -38.1762)
		(end 7.706614 -34.55035)
		(width 0.10795)
		(layer "F.Cu")
		(net "FM_MATED_IN_N")
	)
	(segment
		(start 22.241256 -26.67)
		(end 22.479 -26.907744)
		(width 0.10795)
		(layer "F.Cu")
		(net "FM_MATED_IN_N")
	)
	(segment
		(start 20.903692 -38.786308)
		(end 20.2184 -39.4716)
		(width 0.10795)
		(layer "F.Cu")
		(net "FM_MATED_IN_N")
	)
	(segment
		(start 1.599946 -34.315146)
		(end 1.599946 -33.710118)
		(width 0.10795)
		(layer "F.Cu")
		(net "FM_MATED_IN_N")
	)
	(segment
		(start 14.4018 -38.1762)
		(end 11.332464 -38.1762)
		(width 0.10795)
		(layer "F.Cu")
		(net "FM_MATED_IN_N")
	)
	(segment
		(start 7.706614 -34.55035)
		(end 1.83515 -34.55035)
		(width 0.10795)
		(layer "F.Cu")
		(net "FM_MATED_IN_N")
	)
	(segment
		(start 22.479 -29.972)
		(end 22.479 -30.71876)
		(width 0.10795)
		(layer "F.Cu")
		(net "FM_MATED_IN_N")
	)
	(segment
		(start 23.15464 -31.3944)
		(end 23.15464 -32.76346)
		(width 0.10795)
		(layer "F.Cu")
		(net "FM_MATED_IN_N")
	)
	(segment
		(start 22.479 -30.71876)
		(end 23.15464 -31.3944)
		(width 0.10795)
		(layer "F.Cu")
		(net "FM_MATED_IN_N")
	)
	(segment
		(start 20.903692 -35.014408)
		(end 20.903692 -38.786308)
		(width 0.10795)
		(layer "F.Cu")
		(net "FM_MATED_IN_N")
	)
	(segment
		(start 26.0096 -28.7528)
		(end 25.053544 -27.796744)
		(width 0.10795)
		(layer "B.Cu")
		(net "FM_MATED_IN_N")
	)
	(segment
		(start 23.368 -27.796744)
		(end 22.241256 -26.67)
		(width 0.10795)
		(layer "B.Cu")
		(net "FM_MATED_IN_N")
	)
	(segment
		(start 26.0096 -30.099)
		(end 26.8478 -30.099)
		(width 0.10795)
		(layer "B.Cu")
		(net "FM_MATED_IN_N")
	)
	(segment
		(start 25.053544 -27.796744)
		(end 23.368 -27.796744)
		(width 0.10795)
		(layer "B.Cu")
		(net "FM_MATED_IN_N")
	)
	(segment
		(start 26.0096 -30.099)
		(end 26.0096 -28.7528)
		(width 0.10795)
		(layer "B.Cu")
		(net "FM_MATED_IN_N")
	)
	(segment
		(start 20.23618 -32.72282)
		(end 20.701 -32.258)
		(width 0.10795)
		(layer "F.Cu")
		(net "FM_MATED_IN_D2_N")
	)
	(segment
		(start 20.23618 -33.6042)
		(end 20.23618 -32.72282)
		(width 0.10795)
		(layer "F.Cu")
		(net "FM_MATED_IN_D2_N")
	)
	(via
		(at 20.23618 -34.500312)
		(size 0.6604)
		(drill 0.3302)
		(layers "F.Cu" "B.Cu")
		(net "FM_MATED_IN_D2_N")
	)
	(via
		(at 20.23618 -33.6042)
		(size 0.508)
		(drill 0.254)
		(layers "F.Cu" "B.Cu")
		(net "FM_MATED_IN_D2_N")
	)
	(segment
		(start 20.7264 -31.6738)
		(end 20.7264 -33.11398)
		(width 0.10795)
		(layer "B.Cu")
		(net "FM_MATED_IN_D2_N")
	)
	(segment
		(start 20.7264 -33.11398)
		(end 20.23618 -33.6042)
		(width 0.10795)
		(layer "B.Cu")
		(net "FM_MATED_IN_D2_N")
	)
	(segment
		(start 20.23618 -34.500312)
		(end 20.23618 -33.6042)
		(width 0.10795)
		(layer "B.Cu")
		(net "FM_MATED_IN_D2_N")
	)
	(segment
		(start 22.479 -31.5722)
		(end 22.479 -32.258)
		(width 0.10795)
		(layer "F.Cu")
		(net "FM_MATED_IN_D1_N")
	)
	(segment
		(start 21.2598 -31.2166)
		(end 22.1234 -31.2166)
		(width 0.10795)
		(layer "F.Cu")
		(net "FM_MATED_IN_D1_N")
	)
	(segment
		(start 20.701 -29.972)
		(end 19.9136 -29.972)
		(width 0.10795)
		(layer "F.Cu")
		(net "FM_MATED_IN_D1_N")
	)
	(segment
		(start 18.8976 -30.988)
		(end 18.415 -30.988)
		(width 0.10795)
		(layer "F.Cu")
		(net "FM_MATED_IN_D1_N")
	)
	(segment
		(start 20.701 -30.6578)
		(end 21.2598 -31.2166)
		(width 0.10795)
		(layer "F.Cu")
		(net "FM_MATED_IN_D1_N")
	)
	(segment
		(start 22.1234 -31.2166)
		(end 22.479 -31.5722)
		(width 0.10795)
		(layer "F.Cu")
		(net "FM_MATED_IN_D1_N")
	)
	(segment
		(start 20.701 -29.972)
		(end 20.701 -30.6578)
		(width 0.10795)
		(layer "F.Cu")
		(net "FM_MATED_IN_D1_N")
	)
	(segment
		(start 19.9136 -29.972)
		(end 18.8976 -30.988)
		(width 0.10795)
		(layer "F.Cu")
		(net "FM_MATED_IN_D1_N")
	)
	(via
		(at 18.415 -30.988)
		(size 0.762)
		(drill 0.381)
		(layers "F.Cu" "B.Cu")
		(net "FM_MATED_IN_D1_N")
	)
	(segment
		(start 482.74224 -28.1432)
		(end 483.37978 -28.1432)
		(width 0.254)
		(layer "F.Cu")
		(net "A_COMP_CKMNG")
	)
	(segment
		(start 482.00818 -28.60802)
		(end 482.54666 -28.06954)
		(width 0.254)
		(layer "F.Cu")
		(net "A_COMP_CKMNG")
	)
	(segment
		(start 483.37978 -28.1432)
		(end 483.38486 -28.14828)
		(width 0.254)
		(layer "F.Cu")
		(net "A_COMP_CKMNG")
	)
	(segment
		(start 482.66858 -28.06954)
		(end 482.74224 -28.1432)
		(width 0.254)
		(layer "F.Cu")
		(net "A_COMP_CKMNG")
	)
	(segment
		(start 481.0125 -28.60802)
		(end 482.00818 -28.60802)
		(width 0.254)
		(layer "F.Cu")
		(net "A_COMP_CKMNG")
	)
	(segment
		(start 482.54666 -28.06954)
		(end 482.66858 -28.06954)
		(width 0.254)
		(layer "F.Cu")
		(net "A_COMP_CKMNG")
	)
	(via
		(at 482.54666 -28.06954)
		(size 0.762)
		(drill 0.381)
		(layers "F.Cu" "B.Cu")
		(net "A_COMP_CKMNG")
	)
	(segment
		(start 476.64878 -35.1663)
		(end 476.786194 -35.303714)
		(width 0.10795)
		(layer "F.Cu")
		(net "CLK_50M_CKMNG_SPRVLLE_R")
	)
	(segment
		(start 477.139 -36.074858)
		(end 477.139 -36.6395)
		(width 0.10795)
		(layer "F.Cu")
		(net "CLK_50M_CKMNG_SPRVLLE_R")
	)
	(segment
		(start 476.786194 -35.303714)
		(end 476.786194 -35.722052)
		(width 0.10795)
		(layer "F.Cu")
		(net "CLK_50M_CKMNG_SPRVLLE_R")
	)
	(segment
		(start 476.786194 -35.722052)
		(end 477.139 -36.074858)
		(width 0.10795)
		(layer "F.Cu")
		(net "CLK_50M_CKMNG_SPRVLLE_R")
	)
	(segment
		(start 476.64878 -33.9725)
		(end 476.64878 -35.1663)
		(width 0.10795)
		(layer "F.Cu")
		(net "CLK_50M_CKMNG_SPRVLLE_R")
	)
	(segment
		(start 477.901 -36.6395)
		(end 477.901 -35.8648)
		(width 0.10795)
		(layer "F.Cu")
		(net "CLK_50M_CKMNG_PCH_10GBE_R")
	)
	(segment
		(start 478.216722 -34.871914)
		(end 478.216722 -35.549078)
		(width 0.10795)
		(layer "F.Cu")
		(net "CLK_50M_CKMNG_PCH_10GBE_R")
	)
	(segment
		(start 478.14992 -33.9725)
		(end 478.14992 -34.805112)
		(width 0.10795)
		(layer "F.Cu")
		(net "CLK_50M_CKMNG_PCH_10GBE_R")
	)
	(segment
		(start 478.216722 -35.549078)
		(end 477.9518 -35.814)
		(width 0.10795)
		(layer "F.Cu")
		(net "CLK_50M_CKMNG_PCH_10GBE_R")
	)
	(segment
		(start 478.14992 -34.805112)
		(end 478.216722 -34.871914)
		(width 0.10795)
		(layer "F.Cu")
		(net "CLK_50M_CKMNG_PCH_10GBE_R")
	)
	(segment
		(start 477.901 -35.8648)
		(end 477.9518 -35.814)
		(width 0.10795)
		(layer "F.Cu")
		(net "CLK_50M_CKMNG_PCH_10GBE_R")
	)
	(via
		(at 477.9518 -35.814)
		(size 0.762)
		(drill 0.381)
		(layers "F.Cu" "B.Cu")
		(net "CLK_50M_CKMNG_PCH_10GBE_R")
	)
	(segment
		(start 387.492494 -89.116154)
		(end 386.850636 -89.758012)
		(width 0.10795)
		(layer "F.Cu")
		(net "CLK_50M_CKMNG_PCH_10GBE")
	)
	(segment
		(start 477.41967 -39.266622)
		(end 477.520254 -39.367206)
		(width 0.10795)
		(layer "F.Cu")
		(net "CLK_50M_CKMNG_PCH_10GBE")
	)
	(segment
		(start 475.6658 -39.5224)
		(end 475.921578 -39.266622)
		(width 0.10795)
		(layer "F.Cu")
		(net "CLK_50M_CKMNG_PCH_10GBE")
	)
	(segment
		(start 387.492494 -88.964262)
		(end 387.604 -88.852756)
		(width 0.10795)
		(layer "F.Cu")
		(net "CLK_50M_CKMNG_PCH_10GBE")
	)
	(segment
		(start 472.329002 -39.887398)
		(end 472.694 -39.5224)
		(width 0.10795)
		(layer "F.Cu")
		(net "CLK_50M_CKMNG_PCH_10GBE")
	)
	(segment
		(start 478.320862 -38.431216)
		(end 477.901 -38.011354)
		(width 0.10795)
		(layer "F.Cu")
		(net "CLK_50M_CKMNG_PCH_10GBE")
	)
	(segment
		(start 386.985002 -92.592144)
		(end 386.985002 -93.544898)
		(width 0.0889)
		(layer "F.Cu")
		(net "CLK_50M_CKMNG_PCH_10GBE")
	)
	(segment
		(start 478.243646 -39.219124)
		(end 478.26041 -39.219124)
		(width 0.10795)
		(layer "F.Cu")
		(net "CLK_50M_CKMNG_PCH_10GBE")
	)
	(segment
		(start 387.604 -88.852756)
		(end 387.604 -88.2015)
		(width 0.10795)
		(layer "F.Cu")
		(net "CLK_50M_CKMNG_PCH_10GBE")
	)
	(segment
		(start 472.694 -39.5224)
		(end 475.6658 -39.5224)
		(width 0.10795)
		(layer "F.Cu")
		(net "CLK_50M_CKMNG_PCH_10GBE")
	)
	(segment
		(start 387.124956 -92.45219)
		(end 386.985002 -92.592144)
		(width 0.0889)
		(layer "F.Cu")
		(net "CLK_50M_CKMNG_PCH_10GBE")
	)
	(segment
		(start 471.136472 -46.905418)
		(end 470.544398 -46.313344)
		(width 0.10795)
		(layer "F.Cu")
		(net "CLK_50M_CKMNG_PCH_10GBE")
	)
	(segment
		(start 472.329002 -41.927018)
		(end 472.330018 -41.926002)
		(width 0.10795)
		(layer "F.Cu")
		(net "CLK_50M_CKMNG_PCH_10GBE")
	)
	(segment
		(start 472.329002 -43.15841)
		(end 472.329002 -41.927018)
		(width 0.10795)
		(layer "F.Cu")
		(net "CLK_50M_CKMNG_PCH_10GBE")
	)
	(segment
		(start 472.330018 -41.926002)
		(end 472.330018 -41.57599)
		(width 0.10795)
		(layer "F.Cu")
		(net "CLK_50M_CKMNG_PCH_10GBE")
	)
	(segment
		(start 386.850636 -91.415362)
		(end 387.124956 -91.689682)
		(width 0.10795)
		(layer "F.Cu")
		(net "CLK_50M_CKMNG_PCH_10GBE")
	)
	(segment
		(start 478.26041 -39.219124)
		(end 478.320862 -39.158672)
		(width 0.10795)
		(layer "F.Cu")
		(net "CLK_50M_CKMNG_PCH_10GBE")
	)
	(segment
		(start 387.124956 -91.689682)
		(end 387.124956 -92.45219)
		(width 0.10795)
		(layer "F.Cu")
		(net "CLK_50M_CKMNG_PCH_10GBE")
	)
	(segment
		(start 470.544398 -46.313344)
		(end 470.544398 -44.681394)
		(width 0.10795)
		(layer "F.Cu")
		(net "CLK_50M_CKMNG_PCH_10GBE")
	)
	(segment
		(start 387.492494 -88.964262)
		(end 387.492494 -89.116154)
		(width 0.10795)
		(layer "F.Cu")
		(net "CLK_50M_CKMNG_PCH_10GBE")
	)
	(segment
		(start 471.286586 -43.939206)
		(end 471.548206 -43.939206)
		(width 0.10795)
		(layer "F.Cu")
		(net "CLK_50M_CKMNG_PCH_10GBE")
	)
	(segment
		(start 472.330018 -41.57599)
		(end 472.329002 -41.574974)
		(width 0.10795)
		(layer "F.Cu")
		(net "CLK_50M_CKMNG_PCH_10GBE")
	)
	(segment
		(start 386.850636 -89.758012)
		(end 386.850636 -91.415362)
		(width 0.10795)
		(layer "F.Cu")
		(net "CLK_50M_CKMNG_PCH_10GBE")
	)
	(segment
		(start 477.520254 -39.367206)
		(end 478.095564 -39.367206)
		(width 0.10795)
		(layer "F.Cu")
		(net "CLK_50M_CKMNG_PCH_10GBE")
	)
	(segment
		(start 477.901 -38.011354)
		(end 477.901 -37.5285)
		(width 0.10795)
		(layer "F.Cu")
		(net "CLK_50M_CKMNG_PCH_10GBE")
	)
	(segment
		(start 470.544398 -44.681394)
		(end 471.286586 -43.939206)
		(width 0.10795)
		(layer "F.Cu")
		(net "CLK_50M_CKMNG_PCH_10GBE")
	)
	(segment
		(start 475.921578 -39.266622)
		(end 477.41967 -39.266622)
		(width 0.10795)
		(layer "F.Cu")
		(net "CLK_50M_CKMNG_PCH_10GBE")
	)
	(segment
		(start 478.095564 -39.367206)
		(end 478.243646 -39.219124)
		(width 0.10795)
		(layer "F.Cu")
		(net "CLK_50M_CKMNG_PCH_10GBE")
	)
	(segment
		(start 478.320862 -39.158672)
		(end 478.320862 -38.431216)
		(width 0.10795)
		(layer "F.Cu")
		(net "CLK_50M_CKMNG_PCH_10GBE")
	)
	(segment
		(start 472.329002 -41.574974)
		(end 472.329002 -39.887398)
		(width 0.10795)
		(layer "F.Cu")
		(net "CLK_50M_CKMNG_PCH_10GBE")
	)
	(segment
		(start 471.548206 -43.939206)
		(end 472.329002 -43.15841)
		(width 0.10795)
		(layer "F.Cu")
		(net "CLK_50M_CKMNG_PCH_10GBE")
	)
	(via
		(at 387.492494 -88.964262)
		(size 0.508)
		(drill 0.254)
		(layers "F.Cu" "B.Cu")
		(net "CLK_50M_CKMNG_PCH_10GBE")
	)
	(via
		(at 471.136472 -46.905418)
		(size 0.508)
		(drill 0.254)
		(layers "F.Cu" "B.Cu")
		(net "CLK_50M_CKMNG_PCH_10GBE")
	)
	(segment
		(start 434.928264 -51.516534)
		(end 431.918872 -51.516534)
		(width 0.089408)
		(layer "In2.Cu")
		(net "CLK_50M_CKMNG_PCH_10GBE")
	)
	(segment
		(start 395.44244 -48.40732)
		(end 395.2748 -48.57496)
		(width 0.089408)
		(layer "In2.Cu")
		(net "CLK_50M_CKMNG_PCH_10GBE")
	)
	(segment
		(start 430.774094 -51.516534)
		(end 428.557182 -51.516534)
		(width 0.089408)
		(layer "In2.Cu")
		(net "CLK_50M_CKMNG_PCH_10GBE")
	)
	(segment
		(start 393.84732 -70.538848)
		(end 392.186668 -72.1995)
		(width 0.089408)
		(layer "In2.Cu")
		(net "CLK_50M_CKMNG_PCH_10GBE")
	)
	(segment
		(start 410.581602 -46.325536)
		(end 409.353512 -46.325536)
		(width 0.089408)
		(layer "In2.Cu")
		(net "CLK_50M_CKMNG_PCH_10GBE")
	)
	(segment
		(start 387.485128 -88.964262)
		(end 387.492494 -88.964262)
		(width 0.089408)
		(layer "In2.Cu")
		(net "CLK_50M_CKMNG_PCH_10GBE")
	)
	(segment
		(start 428.556928 -51.516788)
		(end 427.34611 -51.516788)
		(width 0.089408)
		(layer "In2.Cu")
		(net "CLK_50M_CKMNG_PCH_10GBE")
	)
	(segment
		(start 415.250884 -48.024796)
		(end 414.91916 -47.693072)
		(width 0.089408)
		(layer "In2.Cu")
		(net "CLK_50M_CKMNG_PCH_10GBE")
	)
	(segment
		(start 392.186668 -72.1995)
		(end 392.186668 -77.573632)
		(width 0.089408)
		(layer "In2.Cu")
		(net "CLK_50M_CKMNG_PCH_10GBE")
	)
	(segment
		(start 391.287 -78.4733)
		(end 391.287 -80.073754)
		(width 0.089408)
		(layer "In2.Cu")
		(net "CLK_50M_CKMNG_PCH_10GBE")
	)
	(segment
		(start 413.025336 -45.829982)
		(end 412.308548 -46.54677)
		(width 0.089408)
		(layer "In2.Cu")
		(net "CLK_50M_CKMNG_PCH_10GBE")
	)
	(segment
		(start 426.339 -49.616614)
		(end 424.747182 -48.024796)
		(width 0.089408)
		(layer "In2.Cu")
		(net "CLK_50M_CKMNG_PCH_10GBE")
	)
	(segment
		(start 409.353512 -46.325536)
		(end 409.350718 -46.322742)
		(width 0.089408)
		(layer "In2.Cu")
		(net "CLK_50M_CKMNG_PCH_10GBE")
	)
	(segment
		(start 403.317456 -47.914052)
		(end 396.541752 -47.914052)
		(width 0.089408)
		(layer "In2.Cu")
		(net "CLK_50M_CKMNG_PCH_10GBE")
	)
	(segment
		(start 414.91916 -47.693072)
		(end 414.91916 -46.924214)
		(width 0.089408)
		(layer "In2.Cu")
		(net "CLK_50M_CKMNG_PCH_10GBE")
	)
	(segment
		(start 389.021828 -87.51189)
		(end 388.537704 -87.51189)
		(width 0.089408)
		(layer "In2.Cu")
		(net "CLK_50M_CKMNG_PCH_10GBE")
	)
	(segment
		(start 424.747182 -48.024796)
		(end 415.250884 -48.024796)
		(width 0.089408)
		(layer "In2.Cu")
		(net "CLK_50M_CKMNG_PCH_10GBE")
	)
	(segment
		(start 391.287 -80.073754)
		(end 390.607296 -80.753458)
		(width 0.089408)
		(layer "In2.Cu")
		(net "CLK_50M_CKMNG_PCH_10GBE")
	)
	(segment
		(start 407.87955 -46.322742)
		(end 407.473658 -46.322742)
		(width 0.089408)
		(layer "In2.Cu")
		(net "CLK_50M_CKMNG_PCH_10GBE")
	)
	(segment
		(start 431.918872 -51.516534)
		(end 431.918618 -51.516788)
		(width 0.089408)
		(layer "In2.Cu")
		(net "CLK_50M_CKMNG_PCH_10GBE")
	)
	(segment
		(start 395.1478 -51.483514)
		(end 395.1478 -63.1444)
		(width 0.089408)
		(layer "In2.Cu")
		(net "CLK_50M_CKMNG_PCH_10GBE")
	)
	(segment
		(start 404.673308 -46.5582)
		(end 403.317456 -47.914052)
		(width 0.089408)
		(layer "In2.Cu")
		(net "CLK_50M_CKMNG_PCH_10GBE")
	)
	(segment
		(start 413.83966 -45.829982)
		(end 413.025336 -45.829982)
		(width 0.089408)
		(layer "In2.Cu")
		(net "CLK_50M_CKMNG_PCH_10GBE")
	)
	(segment
		(start 426.338746 -50.509424)
		(end 426.338746 -50.24628)
		(width 0.089408)
		(layer "In2.Cu")
		(net "CLK_50M_CKMNG_PCH_10GBE")
	)
	(segment
		(start 414.822894 -46.813216)
		(end 413.83966 -45.829982)
		(width 0.089408)
		(layer "In2.Cu")
		(net "CLK_50M_CKMNG_PCH_10GBE")
	)
	(segment
		(start 409.290012 -46.322742)
		(end 409.289758 -46.322488)
		(width 0.089408)
		(layer "In2.Cu")
		(net "CLK_50M_CKMNG_PCH_10GBE")
	)
	(segment
		(start 409.289758 -46.322488)
		(end 407.879804 -46.322488)
		(width 0.089408)
		(layer "In2.Cu")
		(net "CLK_50M_CKMNG_PCH_10GBE")
	)
	(segment
		(start 471.136472 -46.905418)
		(end 469.425274 -48.616616)
		(width 0.089408)
		(layer "In2.Cu")
		(net "CLK_50M_CKMNG_PCH_10GBE")
	)
	(segment
		(start 390.607296 -80.753458)
		(end 390.607296 -81.547462)
		(width 0.089408)
		(layer "In2.Cu")
		(net "CLK_50M_CKMNG_PCH_10GBE")
	)
	(segment
		(start 390.773158 -85.024468)
		(end 390.773158 -85.76056)
		(width 0.089408)
		(layer "In2.Cu")
		(net "CLK_50M_CKMNG_PCH_10GBE")
	)
	(segment
		(start 390.773158 -81.713324)
		(end 390.773158 -82.93481)
		(width 0.089408)
		(layer "In2.Cu")
		(net "CLK_50M_CKMNG_PCH_10GBE")
	)
	(segment
		(start 436.228744 -51.516788)
		(end 434.928518 -51.516788)
		(width 0.089408)
		(layer "In2.Cu")
		(net "CLK_50M_CKMNG_PCH_10GBE")
	)
	(segment
		(start 407.2382 -46.5582)
		(end 404.673308 -46.5582)
		(width 0.089408)
		(layer "In2.Cu")
		(net "CLK_50M_CKMNG_PCH_10GBE")
	)
	(segment
		(start 409.350718 -46.322742)
		(end 409.290012 -46.322742)
		(width 0.089408)
		(layer "In2.Cu")
		(net "CLK_50M_CKMNG_PCH_10GBE")
	)
	(segment
		(start 414.822894 -46.827948)
		(end 414.822894 -46.813216)
		(width 0.089408)
		(layer "In2.Cu")
		(net "CLK_50M_CKMNG_PCH_10GBE")
	)
	(segment
		(start 407.473658 -46.322742)
		(end 407.2382 -46.5582)
		(width 0.089408)
		(layer "In2.Cu")
		(net "CLK_50M_CKMNG_PCH_10GBE")
	)
	(segment
		(start 469.425274 -48.616616)
		(end 439.128916 -48.616616)
		(width 0.089408)
		(layer "In2.Cu")
		(net "CLK_50M_CKMNG_PCH_10GBE")
	)
	(segment
		(start 392.186668 -77.573632)
		(end 391.287 -78.4733)
		(width 0.089408)
		(layer "In2.Cu")
		(net "CLK_50M_CKMNG_PCH_10GBE")
	)
	(segment
		(start 426.338746 -50.24628)
		(end 426.339 -50.246026)
		(width 0.089408)
		(layer "In2.Cu")
		(net "CLK_50M_CKMNG_PCH_10GBE")
	)
	(segment
		(start 395.2748 -48.57496)
		(end 395.2748 -50.934366)
		(width 0.089408)
		(layer "In2.Cu")
		(net "CLK_50M_CKMNG_PCH_10GBE")
	)
	(segment
		(start 427.34611 -51.516788)
		(end 426.338746 -50.509424)
		(width 0.089408)
		(layer "In2.Cu")
		(net "CLK_50M_CKMNG_PCH_10GBE")
	)
	(segment
		(start 396.541752 -47.914052)
		(end 396.048484 -48.40732)
		(width 0.089408)
		(layer "In2.Cu")
		(net "CLK_50M_CKMNG_PCH_10GBE")
	)
	(segment
		(start 439.128916 -48.616616)
		(end 436.228744 -51.516788)
		(width 0.089408)
		(layer "In2.Cu")
		(net "CLK_50M_CKMNG_PCH_10GBE")
	)
	(segment
		(start 391.155428 -84.642198)
		(end 390.773158 -85.024468)
		(width 0.089408)
		(layer "In2.Cu")
		(net "CLK_50M_CKMNG_PCH_10GBE")
	)
	(segment
		(start 407.879804 -46.322488)
		(end 407.87955 -46.322742)
		(width 0.089408)
		(layer "In2.Cu")
		(net "CLK_50M_CKMNG_PCH_10GBE")
	)
	(segment
		(start 395.2748 -50.934366)
		(end 395.275054 -50.93462)
		(width 0.089408)
		(layer "In2.Cu")
		(net "CLK_50M_CKMNG_PCH_10GBE")
	)
	(segment
		(start 388.537704 -87.51189)
		(end 387.485128 -88.564466)
		(width 0.089408)
		(layer "In2.Cu")
		(net "CLK_50M_CKMNG_PCH_10GBE")
	)
	(segment
		(start 391.155428 -83.31708)
		(end 391.155428 -84.642198)
		(width 0.089408)
		(layer "In2.Cu")
		(net "CLK_50M_CKMNG_PCH_10GBE")
	)
	(segment
		(start 431.918618 -51.516788)
		(end 430.774348 -51.516788)
		(width 0.089408)
		(layer "In2.Cu")
		(net "CLK_50M_CKMNG_PCH_10GBE")
	)
	(segment
		(start 395.275054 -50.93462)
		(end 395.275054 -51.35626)
		(width 0.089408)
		(layer "In2.Cu")
		(net "CLK_50M_CKMNG_PCH_10GBE")
	)
	(segment
		(start 412.308548 -46.54677)
		(end 410.802836 -46.54677)
		(width 0.089408)
		(layer "In2.Cu")
		(net "CLK_50M_CKMNG_PCH_10GBE")
	)
	(segment
		(start 390.773158 -82.93481)
		(end 391.155428 -83.31708)
		(width 0.089408)
		(layer "In2.Cu")
		(net "CLK_50M_CKMNG_PCH_10GBE")
	)
	(segment
		(start 434.928518 -51.516788)
		(end 434.928264 -51.516534)
		(width 0.089408)
		(layer "In2.Cu")
		(net "CLK_50M_CKMNG_PCH_10GBE")
	)
	(segment
		(start 390.607296 -81.547462)
		(end 390.773158 -81.713324)
		(width 0.089408)
		(layer "In2.Cu")
		(net "CLK_50M_CKMNG_PCH_10GBE")
	)
	(segment
		(start 410.802836 -46.54677)
		(end 410.581602 -46.325536)
		(width 0.089408)
		(layer "In2.Cu")
		(net "CLK_50M_CKMNG_PCH_10GBE")
	)
	(segment
		(start 393.84732 -64.44488)
		(end 393.84732 -70.538848)
		(width 0.089408)
		(layer "In2.Cu")
		(net "CLK_50M_CKMNG_PCH_10GBE")
	)
	(segment
		(start 387.485128 -88.564466)
		(end 387.485128 -88.964262)
		(width 0.089408)
		(layer "In2.Cu")
		(net "CLK_50M_CKMNG_PCH_10GBE")
	)
	(segment
		(start 428.557182 -51.516534)
		(end 428.556928 -51.516788)
		(width 0.089408)
		(layer "In2.Cu")
		(net "CLK_50M_CKMNG_PCH_10GBE")
	)
	(segment
		(start 426.339 -50.246026)
		(end 426.339 -49.616614)
		(width 0.089408)
		(layer "In2.Cu")
		(net "CLK_50M_CKMNG_PCH_10GBE")
	)
	(segment
		(start 396.048484 -48.40732)
		(end 395.44244 -48.40732)
		(width 0.089408)
		(layer "In2.Cu")
		(net "CLK_50M_CKMNG_PCH_10GBE")
	)
	(segment
		(start 395.1478 -63.1444)
		(end 393.84732 -64.44488)
		(width 0.089408)
		(layer "In2.Cu")
		(net "CLK_50M_CKMNG_PCH_10GBE")
	)
	(segment
		(start 390.773158 -85.76056)
		(end 389.021828 -87.51189)
		(width 0.089408)
		(layer "In2.Cu")
		(net "CLK_50M_CKMNG_PCH_10GBE")
	)
	(segment
		(start 414.91916 -46.924214)
		(end 414.822894 -46.827948)
		(width 0.089408)
		(layer "In2.Cu")
		(net "CLK_50M_CKMNG_PCH_10GBE")
	)
	(segment
		(start 430.774348 -51.516788)
		(end 430.774094 -51.516534)
		(width 0.089408)
		(layer "In2.Cu")
		(net "CLK_50M_CKMNG_PCH_10GBE")
	)
	(segment
		(start 395.275054 -51.35626)
		(end 395.1478 -51.483514)
		(width 0.089408)
		(layer "In2.Cu")
		(net "CLK_50M_CKMNG_PCH_10GBE")
	)
	(segment
		(start 476.1484 -33.9725)
		(end 476.1484 -35.753548)
		(width 0.10795)
		(layer "F.Cu")
		(net "CLK_50M_CKMNG_BMC_2_R")
	)
	(segment
		(start 476.1484 -35.753548)
		(end 476.1484 -36.068254)
		(width 0.10795)
		(layer "F.Cu")
		(net "CLK_50M_CKMNG_BMC_2_R")
	)
	(segment
		(start 476.1484 -36.068254)
		(end 476.377 -36.296854)
		(width 0.10795)
		(layer "F.Cu")
		(net "CLK_50M_CKMNG_BMC_2_R")
	)
	(segment
		(start 476.377 -36.296854)
		(end 476.377 -36.6395)
		(width 0.10795)
		(layer "F.Cu")
		(net "CLK_50M_CKMNG_BMC_2_R")
	)
	(via
		(at 476.1484 -35.753548)
		(size 0.508)
		(drill 0.254)
		(layers "F.Cu" "B.Cu")
		(net "CLK_50M_CKMNG_BMC_2_R")
	)
	(segment
		(start 481.0125 -29.60878)
		(end 482.346 -29.60878)
		(width 0.10795)
		(layer "F.Cu")
		(net "CLK_32K_SUSCLK_PLD_R")
	)
	(segment
		(start 482.346 -29.60878)
		(end 482.67366 -29.28112)
		(width 0.10795)
		(layer "F.Cu")
		(net "CLK_32K_SUSCLK_PLD_R")
	)
	(segment
		(start 482.174042 -31.10992)
		(end 482.47173 -30.812232)
		(width 0.10795)
		(layer "F.Cu")
		(net "CLK_25M_BMC_R")
	)
	(segment
		(start 482.47173 -30.812232)
		(end 482.47173 -30.49905)
		(width 0.10795)
		(layer "F.Cu")
		(net "CLK_25M_BMC_R")
	)
	(segment
		(start 482.47173 -30.49905)
		(end 482.67366 -30.29712)
		(width 0.10795)
		(layer "F.Cu")
		(net "CLK_25M_BMC_R")
	)
	(segment
		(start 481.0125 -31.10992)
		(end 482.174042 -31.10992)
		(width 0.10795)
		(layer "F.Cu")
		(net "CLK_25M_BMC_R")
	)
	(segment
		(start 404.547578 -116.148612)
		(end 407.096214 -116.148612)
		(width 0.10795)
		(layer "F.Cu")
		(net "H_PMSYNC_CLK_24M_R")
	)
	(segment
		(start 408.124914 -116.800122)
		(end 409.208478 -116.800122)
		(width 0.10795)
		(layer "F.Cu")
		(net "H_PMSYNC_CLK_24M_R")
	)
	(segment
		(start 400.962114 -116.355114)
		(end 401.1168 -116.5098)
		(width 0.10795)
		(layer "F.Cu")
		(net "H_PMSYNC_CLK_24M_R")
	)
	(segment
		(start 401.1168 -116.5098)
		(end 402.187156 -116.5098)
		(width 0.10795)
		(layer "F.Cu")
		(net "H_PMSYNC_CLK_24M_R")
	)
	(segment
		(start 409.208478 -116.800122)
		(end 409.3972 -116.6114)
		(width 0.10795)
		(layer "F.Cu")
		(net "H_PMSYNC_CLK_24M_R")
	)
	(segment
		(start 407.096214 -116.148612)
		(end 407.747724 -116.800122)
		(width 0.10795)
		(layer "F.Cu")
		(net "H_PMSYNC_CLK_24M_R")
	)
	(segment
		(start 407.747724 -116.800122)
		(end 408.124914 -116.800122)
		(width 0.10795)
		(layer "F.Cu")
		(net "H_PMSYNC_CLK_24M_R")
	)
	(segment
		(start 402.187156 -116.5098)
		(end 402.325078 -116.371878)
		(width 0.10795)
		(layer "F.Cu")
		(net "H_PMSYNC_CLK_24M_R")
	)
	(segment
		(start 402.325078 -116.371878)
		(end 404.324312 -116.371878)
		(width 0.10795)
		(layer "F.Cu")
		(net "H_PMSYNC_CLK_24M_R")
	)
	(segment
		(start 404.324312 -116.371878)
		(end 404.547578 -116.148612)
		(width 0.10795)
		(layer "F.Cu")
		(net "H_PMSYNC_CLK_24M_R")
	)
	(segment
		(start 400.880072 -116.355114)
		(end 400.962114 -116.355114)
		(width 0.10795)
		(layer "F.Cu")
		(net "H_PMSYNC_CLK_24M_R")
	)
	(via
		(at 408.124914 -116.800122)
		(size 0.762)
		(drill 0.381)
		(layers "F.Cu" "B.Cu")
		(net "H_PMSYNC_CLK_24M_R")
	)
	(segment
		(start 386.74675 -119.29872)
		(end 387.24205 -119.528844)
		(width 0.254)
		(layer "F.Cu")
		(net "A_PCIEUP_RCOMP_P")
	)
	(via
		(at 387.244082 -124.354844)
		(size 0.6604)
		(drill 0.3302)
		(layers "F.Cu" "B.Cu")
		(net "A_PCIEUP_RCOMP_P")
	)
	(via
		(at 387.24205 -119.528844)
		(size 0.508)
		(drill 0.254)
		(layers "F.Cu" "B.Cu")
		(net "A_PCIEUP_RCOMP_P")
	)
	(segment
		(start 387.244082 -124.354844)
		(end 388.0104 -125.121162)
		(width 0.2032)
		(layer "B.Cu")
		(net "A_PCIEUP_RCOMP_P")
	)
	(segment
		(start 387.756654 -121.401586)
		(end 387.223 -121.93524)
		(width 0.2032)
		(layer "B.Cu")
		(net "A_PCIEUP_RCOMP_P")
	)
	(segment
		(start 387.244082 -123.651518)
		(end 387.244082 -124.354844)
		(width 0.2032)
		(layer "B.Cu")
		(net "A_PCIEUP_RCOMP_P")
	)
	(segment
		(start 387.223 -121.93524)
		(end 387.223 -122.27052)
		(width 0.2032)
		(layer "B.Cu")
		(net "A_PCIEUP_RCOMP_P")
	)
	(segment
		(start 387.24205 -120.55475)
		(end 387.756654 -121.069354)
		(width 0.2032)
		(layer "B.Cu")
		(net "A_PCIEUP_RCOMP_P")
	)
	(segment
		(start 387.756654 -121.069354)
		(end 387.756654 -121.401586)
		(width 0.2032)
		(layer "B.Cu")
		(net "A_PCIEUP_RCOMP_P")
	)
	(segment
		(start 387.744716 -122.792236)
		(end 387.744716 -123.150884)
		(width 0.2032)
		(layer "B.Cu")
		(net "A_PCIEUP_RCOMP_P")
	)
	(segment
		(start 387.744716 -123.150884)
		(end 387.244082 -123.651518)
		(width 0.2032)
		(layer "B.Cu")
		(net "A_PCIEUP_RCOMP_P")
	)
	(segment
		(start 387.223 -122.27052)
		(end 387.744716 -122.792236)
		(width 0.2032)
		(layer "B.Cu")
		(net "A_PCIEUP_RCOMP_P")
	)
	(segment
		(start 388.0104 -125.121162)
		(end 388.0104 -125.507242)
		(width 0.2032)
		(layer "B.Cu")
		(net "A_PCIEUP_RCOMP_P")
	)
	(segment
		(start 387.24205 -119.528844)
		(end 387.24205 -120.55475)
		(width 0.2032)
		(layer "B.Cu")
		(net "A_PCIEUP_RCOMP_P")
	)
	(segment
		(start 404.304754 -105.162604)
		(end 404.835614 -105.693464)
		(width 0.254)
		(layer "F.Cu")
		(net "A_RCOMP_3P3")
	)
	(segment
		(start 401.837906 -104.47147)
		(end 401.935442 -104.373934)
		(width 0.254)
		(layer "F.Cu")
		(net "A_RCOMP_3P3")
	)
	(segment
		(start 400.880072 -104.354884)
		(end 400.996658 -104.47147)
		(width 0.254)
		(layer "F.Cu")
		(net "A_RCOMP_3P3")
	)
	(segment
		(start 402.627592 -104.876092)
		(end 402.914104 -105.162604)
		(width 0.254)
		(layer "F.Cu")
		(net "A_RCOMP_3P3")
	)
	(segment
		(start 400.996658 -104.47147)
		(end 401.837906 -104.47147)
		(width 0.254)
		(layer "F.Cu")
		(net "A_RCOMP_3P3")
	)
	(segment
		(start 402.627592 -104.851962)
		(end 402.627592 -104.876092)
		(width 0.254)
		(layer "F.Cu")
		(net "A_RCOMP_3P3")
	)
	(segment
		(start 405.799036 -105.693464)
		(end 405.8285 -105.664)
		(width 0.254)
		(layer "F.Cu")
		(net "A_RCOMP_3P3")
	)
	(segment
		(start 402.615908 -104.724454)
		(end 402.616924 -104.72547)
		(width 0.254)
		(layer "F.Cu")
		(net "A_RCOMP_3P3")
	)
	(segment
		(start 402.914104 -105.162604)
		(end 404.304754 -105.162604)
		(width 0.254)
		(layer "F.Cu")
		(net "A_RCOMP_3P3")
	)
	(segment
		(start 401.935442 -104.373934)
		(end 402.334222 -104.373934)
		(width 0.254)
		(layer "F.Cu")
		(net "A_RCOMP_3P3")
	)
	(segment
		(start 402.616924 -104.841294)
		(end 402.627592 -104.851962)
		(width 0.254)
		(layer "F.Cu")
		(net "A_RCOMP_3P3")
	)
	(segment
		(start 402.334222 -104.373934)
		(end 402.615908 -104.65562)
		(width 0.254)
		(layer "F.Cu")
		(net "A_RCOMP_3P3")
	)
	(segment
		(start 402.615908 -104.65562)
		(end 402.615908 -104.724454)
		(width 0.254)
		(layer "F.Cu")
		(net "A_RCOMP_3P3")
	)
	(segment
		(start 404.835614 -105.693464)
		(end 405.799036 -105.693464)
		(width 0.254)
		(layer "F.Cu")
		(net "A_RCOMP_3P3")
	)
	(segment
		(start 402.616924 -104.72547)
		(end 402.616924 -104.841294)
		(width 0.254)
		(layer "F.Cu")
		(net "A_RCOMP_3P3")
	)
	(segment
		(start 388.379716 -89.941908)
		(end 388.435596 -89.886028)
		(width 0.0889)
		(layer "F.Cu")
		(net "A_1P8_3P3_RCOMP")
	)
	(segment
		(start 388.162292 -93.810074)
		(end 388.27075 -93.701616)
		(width 0.0889)
		(layer "F.Cu")
		(net "A_1P8_3P3_RCOMP")
	)
	(segment
		(start 388.27075 -93.287342)
		(end 388.16661 -93.183202)
		(width 0.0889)
		(layer "F.Cu")
		(net "A_1P8_3P3_RCOMP")
	)
	(segment
		(start 388.162292 -94.104968)
		(end 388.162292 -93.810074)
		(width 0.0889)
		(layer "F.Cu")
		(net "A_1P8_3P3_RCOMP")
	)
	(segment
		(start 388.485126 -94.427802)
		(end 388.162292 -94.104968)
		(width 0.0889)
		(layer "F.Cu")
		(net "A_1P8_3P3_RCOMP")
	)
	(segment
		(start 388.16661 -91.93276)
		(end 388.379716 -91.719654)
		(width 0.0889)
		(layer "F.Cu")
		(net "A_1P8_3P3_RCOMP")
	)
	(segment
		(start 388.485126 -94.790006)
		(end 388.485126 -94.427802)
		(width 0.0889)
		(layer "F.Cu")
		(net "A_1P8_3P3_RCOMP")
	)
	(segment
		(start 388.435596 -89.886028)
		(end 389.128 -89.193624)
		(width 0.254)
		(layer "F.Cu")
		(net "A_1P8_3P3_RCOMP")
	)
	(segment
		(start 388.27075 -93.701616)
		(end 388.27075 -93.287342)
		(width 0.0889)
		(layer "F.Cu")
		(net "A_1P8_3P3_RCOMP")
	)
	(segment
		(start 389.128 -89.193624)
		(end 389.128 -88.2015)
		(width 0.254)
		(layer "F.Cu")
		(net "A_1P8_3P3_RCOMP")
	)
	(segment
		(start 388.16661 -93.183202)
		(end 388.16661 -91.93276)
		(width 0.0889)
		(layer "F.Cu")
		(net "A_1P8_3P3_RCOMP")
	)
	(segment
		(start 388.379716 -91.719654)
		(end 388.379716 -89.941908)
		(width 0.0889)
		(layer "F.Cu")
		(net "A_1P8_3P3_RCOMP")
	)
	(segment
		(start 477.504252 -46.434248)
		(end 477.8756 -46.0629)
		(width 0.254)
		(layer "F.Cu")
		(net "A_CBOT")
	)
	(segment
		(start 479.1583 -46.0629)
		(end 477.8756 -46.0629)
		(width 0.254)
		(layer "F.Cu")
		(net "A_CBOT")
	)
	(segment
		(start 479.50374 -45.71746)
		(end 479.1583 -46.0629)
		(width 0.254)
		(layer "F.Cu")
		(net "A_CBOT")
	)
	(segment
		(start 479.8822 -45.71746)
		(end 479.50374 -45.71746)
		(width 0.254)
		(layer "F.Cu")
		(net "A_CBOT")
	)
	(segment
		(start 477.504252 -47.139352)
		(end 477.504252 -46.434248)
		(width 0.254)
		(layer "F.Cu")
		(net "A_CBOT")
	)
	(via
		(at 477.504252 -47.139352)
		(size 0.762)
		(drill 0.381)
		(layers "F.Cu" "B.Cu")
		(net "A_CBOT")
	)
	(segment
		(start 478.815908 -44.27855)
		(end 479.284792 -44.27855)
		(width 0.10795)
		(layer "F.Cu")
		(net "A_CTOP")
	)
	(segment
		(start 477.8756 -45.1739)
		(end 477.8756 -44.661328)
		(width 0.10795)
		(layer "F.Cu")
		(net "A_CTOP")
	)
	(segment
		(start 478.70872 -44.171362)
		(end 478.815908 -44.27855)
		(width 0.10795)
		(layer "F.Cu")
		(net "A_CTOP")
	)
	(segment
		(start 478.167192 -44.369736)
		(end 478.365566 -44.171362)
		(width 0.10795)
		(layer "F.Cu")
		(net "A_CTOP")
	)
	(segment
		(start 479.284792 -44.27855)
		(end 479.346006 -44.217336)
		(width 0.10795)
		(layer "F.Cu")
		(net "A_CTOP")
	)
	(segment
		(start 479.346006 -44.217336)
		(end 479.8822 -44.217336)
		(width 0.10795)
		(layer "F.Cu")
		(net "A_CTOP")
	)
	(segment
		(start 477.8756 -44.661328)
		(end 478.167192 -44.369736)
		(width 0.10795)
		(layer "F.Cu")
		(net "A_CTOP")
	)
	(segment
		(start 478.365566 -44.171362)
		(end 478.70872 -44.171362)
		(width 0.10795)
		(layer "F.Cu")
		(net "A_CTOP")
	)
	(via
		(at 478.167192 -44.369736)
		(size 0.508)
		(drill 0.254)
		(layers "F.Cu" "B.Cu")
		(net "A_CTOP")
	)
	(segment
		(start 185.677048 -72.7456)
		(end 185.677048 -74.018648)
		(width 0.10795)
		(layer "F.Cu")
		(net "PU_VR_PVCCIN_CPU0_IMON")
	)
	(segment
		(start 186.4868 -74.8284)
		(end 186.4868 -75.6031)
		(width 0.10795)
		(layer "F.Cu")
		(net "PU_VR_PVCCIN_CPU0_IMON")
	)
	(segment
		(start 185.677048 -74.018648)
		(end 186.1058 -74.4474)
		(width 0.10795)
		(layer "F.Cu")
		(net "PU_VR_PVCCIN_CPU0_IMON")
	)
	(segment
		(start 186.1058 -74.4474)
		(end 186.4868 -74.8284)
		(width 0.10795)
		(layer "F.Cu")
		(net "PU_VR_PVCCIN_CPU0_IMON")
	)
	(via
		(at 186.1058 -74.4474)
		(size 0.762)
		(drill 0.381)
		(layers "F.Cu" "B.Cu")
		(net "PU_VR_PVCCIN_CPU0_IMON")
	)
	(segment
		(start 488.9754 -49.4538)
		(end 488.39628 -48.87468)
		(width 0.10795)
		(layer "F.Cu")
		(net "RST_PLTRST_SPRV_R_N")
	)
	(segment
		(start 488.39628 -48.490124)
		(end 488.242356 -48.3362)
		(width 0.10795)
		(layer "F.Cu")
		(net "RST_PLTRST_SPRV_R_N")
	)
	(segment
		(start 488.9754 -49.784)
		(end 488.9754 -49.4538)
		(width 0.10795)
		(layer "F.Cu")
		(net "RST_PLTRST_SPRV_R_N")
	)
	(segment
		(start 488.39628 -48.87468)
		(end 488.39628 -48.490124)
		(width 0.10795)
		(layer "F.Cu")
		(net "RST_PLTRST_SPRV_R_N")
	)
	(segment
		(start 488.242356 -48.3362)
		(end 488.001056 -48.3362)
		(width 0.10795)
		(layer "F.Cu")
		(net "RST_PLTRST_SPRV_R_N")
	)
	(segment
		(start 489.1659 -49.7459)
		(end 489.0516 -49.8602)
		(width 0.10795)
		(layer "F.Cu")
		(net "RST_PLTRST_SPRV_R_N")
	)
	(segment
		(start 489.0516 -49.8602)
		(end 488.9754 -49.784)
		(width 0.10795)
		(layer "F.Cu")
		(net "RST_PLTRST_SPRV_R_N")
	)
	(segment
		(start 489.712 -49.7459)
		(end 489.1659 -49.7459)
		(width 0.10795)
		(layer "F.Cu")
		(net "RST_PLTRST_SPRV_R_N")
	)
	(via
		(at 489.0516 -49.8602)
		(size 0.508)
		(drill 0.254)
		(layers "F.Cu" "B.Cu")
		(net "RST_PLTRST_SPRV_R_N")
	)
	(segment
		(start 487.713528 -51.112928)
		(end 487.232706 -50.632106)
		(width 0.10795)
		(layer "B.Cu")
		(net "RST_PLTRST_SPRV_R_N")
	)
	(segment
		(start 488.230418 -51.112928)
		(end 487.713528 -51.112928)
		(width 0.10795)
		(layer "B.Cu")
		(net "RST_PLTRST_SPRV_R_N")
	)
	(segment
		(start 489.0516 -49.8602)
		(end 489.0516 -50.291746)
		(width 0.10795)
		(layer "B.Cu")
		(net "RST_PLTRST_SPRV_R_N")
	)
	(segment
		(start 486.635806 -50.632106)
		(end 485.8639 -49.8602)
		(width 0.10795)
		(layer "B.Cu")
		(net "RST_PLTRST_SPRV_R_N")
	)
	(segment
		(start 487.232706 -50.632106)
		(end 486.635806 -50.632106)
		(width 0.10795)
		(layer "B.Cu")
		(net "RST_PLTRST_SPRV_R_N")
	)
	(segment
		(start 489.0516 -50.291746)
		(end 488.230418 -51.112928)
		(width 0.10795)
		(layer "B.Cu")
		(net "RST_PLTRST_SPRV_R_N")
	)
	(segment
		(start 396.15745 -121.87428)
		(end 396.583916 -122.0724)
		(width 0.1143)
		(layer "F.Cu")
		(net "PE_PCH_SPRV_TX_DP")
	)
	(segment
		(start 396.583916 -122.0724)
		(end 396.65275 -122.104404)
		(width 0.1143)
		(layer "F.Cu")
		(net "PE_PCH_SPRV_TX_DP")
	)
	(via
		(at 396.65275 -122.104404)
		(size 0.508)
		(drill 0.254)
		(layers "F.Cu" "B.Cu")
		(net "PE_PCH_SPRV_TX_DP")
	)
	(segment
		(start 396.119858 -122.37339)
		(end 396.119858 -122.373136)
		(width 0.0889)
		(layer "B.Cu")
		(net "PE_PCH_SPRV_TX_DP")
	)
	(segment
		(start 395.0716 -124.11837)
		(end 395.0716 -123.799854)
		(width 0.0889)
		(layer "B.Cu")
		(net "PE_PCH_SPRV_TX_DP")
	)
	(segment
		(start 400.761708 -127.163322)
		(end 399.640298 -127.163322)
		(width 0.1143)
		(layer "B.Cu")
		(net "PE_PCH_SPRV_TX_DP")
	)
	(segment
		(start 399.640298 -127.163322)
		(end 399.6182 -127.163322)
		(width 0.0889)
		(layer "B.Cu")
		(net "PE_PCH_SPRV_TX_DP")
	)
	(segment
		(start 397.470884 -126.517654)
		(end 395.0716 -124.11837)
		(width 0.0889)
		(layer "B.Cu")
		(net "PE_PCH_SPRV_TX_DP")
	)
	(segment
		(start 395.5669 -122.9741)
		(end 395.5669 -122.949208)
		(width 0.0889)
		(layer "B.Cu")
		(net "PE_PCH_SPRV_TX_DP")
	)
	(segment
		(start 396.119858 -122.373136)
		(end 396.65275 -122.104404)
		(width 0.0889)
		(layer "B.Cu")
		(net "PE_PCH_SPRV_TX_DP")
	)
	(segment
		(start 399.070322 -127.137922)
		(end 398.450054 -126.517654)
		(width 0.0889)
		(layer "B.Cu")
		(net "PE_PCH_SPRV_TX_DP")
	)
	(segment
		(start 401.25777 -127.659384)
		(end 400.761708 -127.163322)
		(width 0.1143)
		(layer "B.Cu")
		(net "PE_PCH_SPRV_TX_DP")
	)
	(segment
		(start 399.5928 -127.137922)
		(end 399.070322 -127.137922)
		(width 0.0889)
		(layer "B.Cu")
		(net "PE_PCH_SPRV_TX_DP")
	)
	(segment
		(start 399.6182 -127.163322)
		(end 399.5928 -127.137922)
		(width 0.0889)
		(layer "B.Cu")
		(net "PE_PCH_SPRV_TX_DP")
	)
	(segment
		(start 398.450054 -126.517654)
		(end 397.470884 -126.517654)
		(width 0.0889)
		(layer "B.Cu")
		(net "PE_PCH_SPRV_TX_DP")
	)
	(arc
		(start 395.0716 -123.799854)
		(mid 395.155881 -123.516637)
		(end 395.366748 -123.309634)
		(width 0.0889)
		(layer "B.Cu")
		(net "PE_PCH_SPRV_TX_DP")
	)
	(arc
		(start 395.366748 -123.309634)
		(mid 395.510552 -123.167951)
		(end 395.5669 -122.9741)
		(width 0.0889)
		(layer "B.Cu")
		(net "PE_PCH_SPRV_TX_DP")
	)
	(arc
		(start 395.5669 -122.949208)
		(mid 395.731392 -122.553764)
		(end 396.119858 -122.37339)
		(width 0.0889)
		(layer "B.Cu")
		(net "PE_PCH_SPRV_TX_DP")
	)
	(segment
		(start 395.66215 -122.7328)
		(end 396.15745 -122.962924)
		(width 0.1143)
		(layer "F.Cu")
		(net "PE_PCH_SPRV_TX_DN")
	)
	(via
		(at 396.15745 -122.962924)
		(size 0.508)
		(drill 0.254)
		(layers "F.Cu" "B.Cu")
		(net "PE_PCH_SPRV_TX_DN")
	)
	(via
		(at 400.32305 -126.922022)
		(size 0.508)
		(drill 0.254)
		(layers "F.Cu" "B.Cu")
		(net "PE_PCH_SPRV_TX_DN")
	)
	(segment
		(start 395.554962 -124.332238)
		(end 395.2621 -124.039376)
		(width 0.0889)
		(layer "B.Cu")
		(net "PE_PCH_SPRV_TX_DN")
	)
	(segment
		(start 396.995904 -125.632718)
		(end 396.870174 -125.506988)
		(width 0.0889)
		(layer "B.Cu")
		(net "PE_PCH_SPRV_TX_DN")
	)
	(segment
		(start 396.338044 -125.11532)
		(end 396.212568 -124.989844)
		(width 0.0889)
		(layer "B.Cu")
		(net "PE_PCH_SPRV_TX_DN")
	)
	(segment
		(start 396.212568 -124.849382)
		(end 396.086838 -124.723652)
		(width 0.0889)
		(layer "B.Cu")
		(net "PE_PCH_SPRV_TX_DN")
	)
	(segment
		(start 398.064228 -126.228094)
		(end 397.886428 -126.228094)
		(width 0.0889)
		(layer "B.Cu")
		(net "PE_PCH_SPRV_TX_DN")
	)
	(segment
		(start 396.329916 -122.916442)
		(end 396.15745 -122.962924)
		(width 0.0889)
		(layer "B.Cu")
		(net "PE_PCH_SPRV_TX_DN")
	)
	(segment
		(start 395.69517 -124.332238)
		(end 395.554962 -124.332238)
		(width 0.0889)
		(layer "B.Cu")
		(net "PE_PCH_SPRV_TX_DN")
	)
	(segment
		(start 399.640298 -126.922022)
		(end 399.6182 -126.922022)
		(width 0.0889)
		(layer "B.Cu")
		(net "PE_PCH_SPRV_TX_DN")
	)
	(segment
		(start 397.387572 -126.024386)
		(end 397.261842 -125.898656)
		(width 0.0889)
		(layer "B.Cu")
		(net "PE_PCH_SPRV_TX_DN")
	)
	(segment
		(start 396.604236 -125.24105)
		(end 396.478506 -125.11532)
		(width 0.0889)
		(layer "B.Cu")
		(net "PE_PCH_SPRV_TX_DN")
	)
	(segment
		(start 397.12138 -125.898656)
		(end 396.995904 -125.77318)
		(width 0.0889)
		(layer "B.Cu")
		(net "PE_PCH_SPRV_TX_DN")
	)
	(segment
		(start 395.8209 -124.598176)
		(end 395.8209 -124.457968)
		(width 0.0889)
		(layer "B.Cu")
		(net "PE_PCH_SPRV_TX_DN")
	)
	(segment
		(start 398.529048 -126.327154)
		(end 398.163288 -126.327154)
		(width 0.0889)
		(layer "B.Cu")
		(net "PE_PCH_SPRV_TX_DN")
	)
	(segment
		(start 396.086838 -124.723652)
		(end 395.946376 -124.723652)
		(width 0.0889)
		(layer "B.Cu")
		(net "PE_PCH_SPRV_TX_DN")
	)
	(segment
		(start 397.261842 -125.898656)
		(end 397.12138 -125.898656)
		(width 0.0889)
		(layer "B.Cu")
		(net "PE_PCH_SPRV_TX_DN")
	)
	(segment
		(start 399.149316 -126.947422)
		(end 398.529048 -126.327154)
		(width 0.0889)
		(layer "B.Cu")
		(net "PE_PCH_SPRV_TX_DN")
	)
	(segment
		(start 396.478506 -125.11532)
		(end 396.338044 -125.11532)
		(width 0.0889)
		(layer "B.Cu")
		(net "PE_PCH_SPRV_TX_DN")
	)
	(segment
		(start 399.5928 -126.947422)
		(end 399.149316 -126.947422)
		(width 0.0889)
		(layer "B.Cu")
		(net "PE_PCH_SPRV_TX_DN")
	)
	(segment
		(start 395.7574 -122.984514)
		(end 395.7574 -122.951748)
		(width 0.0889)
		(layer "B.Cu")
		(net "PE_PCH_SPRV_TX_DN")
	)
	(segment
		(start 400.32305 -126.922022)
		(end 400.725132 -126.922022)
		(width 0.1143)
		(layer "B.Cu")
		(net "PE_PCH_SPRV_TX_DN")
	)
	(segment
		(start 396.604236 -125.381512)
		(end 396.604236 -125.24105)
		(width 0.0889)
		(layer "B.Cu")
		(net "PE_PCH_SPRV_TX_DN")
	)
	(segment
		(start 397.549878 -126.327154)
		(end 397.387572 -126.164848)
		(width 0.0889)
		(layer "B.Cu")
		(net "PE_PCH_SPRV_TX_DN")
	)
	(segment
		(start 400.32305 -126.922022)
		(end 399.640298 -126.922022)
		(width 0.1143)
		(layer "B.Cu")
		(net "PE_PCH_SPRV_TX_DN")
	)
	(segment
		(start 396.870174 -125.506988)
		(end 396.729712 -125.506988)
		(width 0.0889)
		(layer "B.Cu")
		(net "PE_PCH_SPRV_TX_DN")
	)
	(segment
		(start 399.6182 -126.922022)
		(end 399.5928 -126.947422)
		(width 0.0889)
		(layer "B.Cu")
		(net "PE_PCH_SPRV_TX_DN")
	)
	(segment
		(start 397.387572 -126.164848)
		(end 397.387572 -126.024386)
		(width 0.0889)
		(layer "B.Cu")
		(net "PE_PCH_SPRV_TX_DN")
	)
	(segment
		(start 398.163288 -126.327154)
		(end 398.064228 -126.228094)
		(width 0.0889)
		(layer "B.Cu")
		(net "PE_PCH_SPRV_TX_DN")
	)
	(segment
		(start 396.995904 -125.77318)
		(end 396.995904 -125.632718)
		(width 0.0889)
		(layer "B.Cu")
		(net "PE_PCH_SPRV_TX_DN")
	)
	(segment
		(start 397.787368 -126.327154)
		(end 397.549878 -126.327154)
		(width 0.0889)
		(layer "B.Cu")
		(net "PE_PCH_SPRV_TX_DN")
	)
	(segment
		(start 396.366746 -122.731784)
		(end 396.366746 -122.852434)
		(width 0.0889)
		(layer "B.Cu")
		(net "PE_PCH_SPRV_TX_DN")
	)
	(segment
		(start 396.366746 -122.852434)
		(end 396.329916 -122.916442)
		(width 0.0889)
		(layer "B.Cu")
		(net "PE_PCH_SPRV_TX_DN")
	)
	(segment
		(start 395.2621 -124.039376)
		(end 395.2621 -123.803918)
		(width 0.0889)
		(layer "B.Cu")
		(net "PE_PCH_SPRV_TX_DN")
	)
	(segment
		(start 395.946376 -124.723652)
		(end 395.8209 -124.598176)
		(width 0.0889)
		(layer "B.Cu")
		(net "PE_PCH_SPRV_TX_DN")
	)
	(segment
		(start 395.461998 -123.474734)
		(end 395.462252 -123.474734)
		(width 0.0889)
		(layer "B.Cu")
		(net "PE_PCH_SPRV_TX_DN")
	)
	(segment
		(start 396.729712 -125.506988)
		(end 396.604236 -125.381512)
		(width 0.0889)
		(layer "B.Cu")
		(net "PE_PCH_SPRV_TX_DN")
	)
	(segment
		(start 395.8209 -124.457968)
		(end 395.69517 -124.332238)
		(width 0.0889)
		(layer "B.Cu")
		(net "PE_PCH_SPRV_TX_DN")
	)
	(segment
		(start 400.725132 -126.922022)
		(end 401.25777 -126.389384)
		(width 0.1143)
		(layer "B.Cu")
		(net "PE_PCH_SPRV_TX_DN")
	)
	(segment
		(start 396.212568 -124.989844)
		(end 396.212568 -124.849382)
		(width 0.0889)
		(layer "B.Cu")
		(net "PE_PCH_SPRV_TX_DN")
	)
	(segment
		(start 397.886428 -126.228094)
		(end 397.787368 -126.327154)
		(width 0.0889)
		(layer "B.Cu")
		(net "PE_PCH_SPRV_TX_DN")
	)
	(arc
		(start 395.2621 -123.803918)
		(mid 395.319835 -123.613676)
		(end 395.461998 -123.474734)
		(width 0.0889)
		(layer "B.Cu")
		(net "PE_PCH_SPRV_TX_DN")
	)
	(arc
		(start 395.462252 -123.474734)
		(mid 395.673116 -123.26773)
		(end 395.7574 -122.984514)
		(width 0.0889)
		(layer "B.Cu")
		(net "PE_PCH_SPRV_TX_DN")
	)
	(arc
		(start 395.7574 -122.951748)
		(mid 395.86947 -122.685017)
		(end 396.13205 -122.563636)
		(width 0.0889)
		(layer "B.Cu")
		(net "PE_PCH_SPRV_TX_DN")
	)
	(arc
		(start 396.13205 -122.563636)
		(mid 396.279368 -122.605862)
		(end 396.366746 -122.731784)
		(width 0.0889)
		(layer "B.Cu")
		(net "PE_PCH_SPRV_TX_DN")
	)
	(segment
		(start 484.209598 -51.344068)
		(end 484.095044 -51.458622)
		(width 0.1143)
		(layer "F.Cu")
		(net "PE_PCH_SPRV_TX_C_DP")
	)
	(segment
		(start 484.759762 -50.304192)
		(end 484.209598 -50.854356)
		(width 0.1143)
		(layer "F.Cu")
		(net "PE_PCH_SPRV_TX_C_DP")
	)
	(segment
		(start 484.645462 -49.4538)
		(end 484.645462 -49.7967)
		(width 0.1143)
		(layer "F.Cu")
		(net "PE_PCH_SPRV_TX_C_DP")
	)
	(segment
		(start 484.759762 -49.911)
		(end 484.759762 -50.304192)
		(width 0.1143)
		(layer "F.Cu")
		(net "PE_PCH_SPRV_TX_C_DP")
	)
	(segment
		(start 484.209598 -50.854356)
		(end 484.209598 -51.344068)
		(width 0.1143)
		(layer "F.Cu")
		(net "PE_PCH_SPRV_TX_C_DP")
	)
	(segment
		(start 484.50119 -48.862234)
		(end 484.565706 -48.92675)
		(width 0.1143)
		(layer "F.Cu")
		(net "PE_PCH_SPRV_TX_C_DP")
	)
	(segment
		(start 484.645462 -49.7967)
		(end 484.759762 -49.911)
		(width 0.1143)
		(layer "F.Cu")
		(net "PE_PCH_SPRV_TX_C_DP")
	)
	(segment
		(start 484.095044 -51.458622)
		(end 483.879652 -51.458622)
		(width 0.1143)
		(layer "F.Cu")
		(net "PE_PCH_SPRV_TX_C_DP")
	)
	(segment
		(start 484.565706 -48.92675)
		(end 484.689912 -48.92675)
		(width 0.1143)
		(layer "F.Cu")
		(net "PE_PCH_SPRV_TX_C_DP")
	)
	(segment
		(start 484.759762 -48.9966)
		(end 484.759762 -49.3395)
		(width 0.1143)
		(layer "F.Cu")
		(net "PE_PCH_SPRV_TX_C_DP")
	)
	(segment
		(start 484.759762 -49.3395)
		(end 484.645462 -49.4538)
		(width 0.1143)
		(layer "F.Cu")
		(net "PE_PCH_SPRV_TX_C_DP")
	)
	(segment
		(start 483.879652 -51.458622)
		(end 483.594918 -51.173888)
		(width 0.1143)
		(layer "F.Cu")
		(net "PE_PCH_SPRV_TX_C_DP")
	)
	(segment
		(start 484.50119 -48.3362)
		(end 484.50119 -48.862234)
		(width 0.1143)
		(layer "F.Cu")
		(net "PE_PCH_SPRV_TX_C_DP")
	)
	(segment
		(start 484.689912 -48.92675)
		(end 484.759762 -48.9966)
		(width 0.1143)
		(layer "F.Cu")
		(net "PE_PCH_SPRV_TX_C_DP")
	)
	(via
		(at 406.59812 -125.835664)
		(size 0.508)
		(drill 0.254)
		(layers "F.Cu" "B.Cu")
		(net "PE_PCH_SPRV_TX_C_DP")
	)
	(via
		(at 483.594918 -51.173888)
		(size 0.508)
		(drill 0.254)
		(layers "F.Cu" "B.Cu")
		(net "PE_PCH_SPRV_TX_C_DP")
	)
	(via
		(at 403.039834 -127.159512)
		(size 0.508)
		(drill 0.254)
		(layers "F.Cu" "B.Cu")
		(net "PE_PCH_SPRV_TX_C_DP")
	)
	(segment
		(start 402.14677 -127.659384)
		(end 402.646642 -127.159512)
		(width 0.1143)
		(layer "B.Cu")
		(net "PE_PCH_SPRV_TX_C_DP")
	)
	(segment
		(start 406.35174 -126.653036)
		(end 406.35174 -126.082044)
		(width 0.1143)
		(layer "B.Cu")
		(net "PE_PCH_SPRV_TX_C_DP")
	)
	(segment
		(start 403.039834 -127.159512)
		(end 405.845264 -127.159512)
		(width 0.1143)
		(layer "B.Cu")
		(net "PE_PCH_SPRV_TX_C_DP")
	)
	(segment
		(start 405.845264 -127.159512)
		(end 406.35174 -126.653036)
		(width 0.1143)
		(layer "B.Cu")
		(net "PE_PCH_SPRV_TX_C_DP")
	)
	(segment
		(start 406.35174 -126.082044)
		(end 406.59812 -125.835664)
		(width 0.1143)
		(layer "B.Cu")
		(net "PE_PCH_SPRV_TX_C_DP")
	)
	(segment
		(start 402.646642 -127.159512)
		(end 403.039834 -127.159512)
		(width 0.1143)
		(layer "B.Cu")
		(net "PE_PCH_SPRV_TX_C_DP")
	)
	(segment
		(start 415.85261 -121.979436)
		(end 414.794446 -123.0376)
		(width 0.1143)
		(layer "In4.Cu")
		(net "PE_PCH_SPRV_TX_C_DP")
	)
	(segment
		(start 407.978102 -124.969778)
		(end 406.531064 -124.969778)
		(width 0.1143)
		(layer "In4.Cu")
		(net "PE_PCH_SPRV_TX_C_DP")
	)
	(segment
		(start 425.417488 -66.565272)
		(end 422.928542 -69.054218)
		(width 0.1143)
		(layer "In4.Cu")
		(net "PE_PCH_SPRV_TX_C_DP")
	)
	(segment
		(start 423.151554 -97.489264)
		(end 423.151554 -103.216456)
		(width 0.1143)
		(layer "In4.Cu")
		(net "PE_PCH_SPRV_TX_C_DP")
	)
	(segment
		(start 421.983916 -77.938884)
		(end 421.983916 -96.321626)
		(width 0.1143)
		(layer "In4.Cu")
		(net "PE_PCH_SPRV_TX_C_DP")
	)
	(segment
		(start 422.928542 -69.054218)
		(end 422.928542 -76.994258)
		(width 0.1143)
		(layer "In4.Cu")
		(net "PE_PCH_SPRV_TX_C_DP")
	)
	(segment
		(start 406.305258 -125.542802)
		(end 406.59812 -125.835664)
		(width 0.1143)
		(layer "In4.Cu")
		(net "PE_PCH_SPRV_TX_C_DP")
	)
	(segment
		(start 484.19131 -51.478434)
		(end 484.476552 -51.763676)
		(width 0.1143)
		(layer "In4.Cu")
		(net "PE_PCH_SPRV_TX_C_DP")
	)
	(segment
		(start 483.82301 -51.40198)
		(end 483.892352 -51.40198)
		(width 0.1143)
		(layer "In4.Cu")
		(net "PE_PCH_SPRV_TX_C_DP")
	)
	(segment
		(start 406.531064 -124.969778)
		(end 406.305258 -125.195584)
		(width 0.1143)
		(layer "In4.Cu")
		(net "PE_PCH_SPRV_TX_C_DP")
	)
	(segment
		(start 418.28466 -108.08335)
		(end 416.952938 -108.08335)
		(width 0.1143)
		(layer "In4.Cu")
		(net "PE_PCH_SPRV_TX_C_DP")
	)
	(segment
		(start 417.068 -121.37898)
		(end 416.467544 -121.979436)
		(width 0.1143)
		(layer "In4.Cu")
		(net "PE_PCH_SPRV_TX_C_DP")
	)
	(segment
		(start 483.968806 -51.478434)
		(end 484.19131 -51.478434)
		(width 0.1143)
		(layer "In4.Cu")
		(net "PE_PCH_SPRV_TX_C_DP")
	)
	(segment
		(start 484.476552 -59.014868)
		(end 482.962966 -60.528454)
		(width 0.1143)
		(layer "In4.Cu")
		(net "PE_PCH_SPRV_TX_C_DP")
	)
	(segment
		(start 416.952938 -108.08335)
		(end 415.760154 -109.276134)
		(width 0.1143)
		(layer "In4.Cu")
		(net "PE_PCH_SPRV_TX_C_DP")
	)
	(segment
		(start 409.4226 -123.0376)
		(end 408.944318 -123.515882)
		(width 0.1143)
		(layer "In4.Cu")
		(net "PE_PCH_SPRV_TX_C_DP")
	)
	(segment
		(start 421.983916 -96.321626)
		(end 423.151554 -97.489264)
		(width 0.1143)
		(layer "In4.Cu")
		(net "PE_PCH_SPRV_TX_C_DP")
	)
	(segment
		(start 483.892352 -51.40198)
		(end 483.968806 -51.478434)
		(width 0.1143)
		(layer "In4.Cu")
		(net "PE_PCH_SPRV_TX_C_DP")
	)
	(segment
		(start 479.891852 -60.528454)
		(end 473.855034 -66.565272)
		(width 0.1143)
		(layer "In4.Cu")
		(net "PE_PCH_SPRV_TX_C_DP")
	)
	(segment
		(start 482.962966 -60.528454)
		(end 479.891852 -60.528454)
		(width 0.1143)
		(layer "In4.Cu")
		(net "PE_PCH_SPRV_TX_C_DP")
	)
	(segment
		(start 473.855034 -66.565272)
		(end 425.417488 -66.565272)
		(width 0.1143)
		(layer "In4.Cu")
		(net "PE_PCH_SPRV_TX_C_DP")
	)
	(segment
		(start 416.467544 -121.979436)
		(end 415.85261 -121.979436)
		(width 0.1143)
		(layer "In4.Cu")
		(net "PE_PCH_SPRV_TX_C_DP")
	)
	(segment
		(start 415.760154 -109.276134)
		(end 415.760154 -116.979954)
		(width 0.1143)
		(layer "In4.Cu")
		(net "PE_PCH_SPRV_TX_C_DP")
	)
	(segment
		(start 417.068 -118.2878)
		(end 417.068 -121.37898)
		(width 0.1143)
		(layer "In4.Cu")
		(net "PE_PCH_SPRV_TX_C_DP")
	)
	(segment
		(start 483.594918 -51.173888)
		(end 483.82301 -51.40198)
		(width 0.1143)
		(layer "In4.Cu")
		(net "PE_PCH_SPRV_TX_C_DP")
	)
	(segment
		(start 406.305258 -125.195584)
		(end 406.305258 -125.542802)
		(width 0.1143)
		(layer "In4.Cu")
		(net "PE_PCH_SPRV_TX_C_DP")
	)
	(segment
		(start 423.151554 -103.216456)
		(end 418.28466 -108.08335)
		(width 0.1143)
		(layer "In4.Cu")
		(net "PE_PCH_SPRV_TX_C_DP")
	)
	(segment
		(start 422.928542 -76.994258)
		(end 421.983916 -77.938884)
		(width 0.1143)
		(layer "In4.Cu")
		(net "PE_PCH_SPRV_TX_C_DP")
	)
	(segment
		(start 415.760154 -116.979954)
		(end 417.068 -118.2878)
		(width 0.1143)
		(layer "In4.Cu")
		(net "PE_PCH_SPRV_TX_C_DP")
	)
	(segment
		(start 484.476552 -51.763676)
		(end 484.476552 -59.014868)
		(width 0.1143)
		(layer "In4.Cu")
		(net "PE_PCH_SPRV_TX_C_DP")
	)
	(segment
		(start 408.944318 -123.515882)
		(end 408.944318 -124.003562)
		(width 0.1143)
		(layer "In4.Cu")
		(net "PE_PCH_SPRV_TX_C_DP")
	)
	(segment
		(start 408.944318 -124.003562)
		(end 407.978102 -124.969778)
		(width 0.1143)
		(layer "In4.Cu")
		(net "PE_PCH_SPRV_TX_C_DP")
	)
	(segment
		(start 414.794446 -123.0376)
		(end 409.4226 -123.0376)
		(width 0.1143)
		(layer "In4.Cu")
		(net "PE_PCH_SPRV_TX_C_DP")
	)
	(segment
		(start 484.450898 -51.444144)
		(end 484.19512 -51.699922)
		(width 0.1143)
		(layer "F.Cu")
		(net "PE_PCH_SPRV_TX_C_DN")
	)
	(segment
		(start 483.970076 -51.699922)
		(end 483.626668 -52.04333)
		(width 0.1143)
		(layer "F.Cu")
		(net "PE_PCH_SPRV_TX_C_DN")
	)
	(segment
		(start 485.001062 -48.3362)
		(end 485.001062 -50.404268)
		(width 0.1143)
		(layer "F.Cu")
		(net "PE_PCH_SPRV_TX_C_DN")
	)
	(segment
		(start 484.19512 -51.699922)
		(end 483.970076 -51.699922)
		(width 0.1143)
		(layer "F.Cu")
		(net "PE_PCH_SPRV_TX_C_DN")
	)
	(segment
		(start 484.450898 -50.954432)
		(end 484.450898 -51.444144)
		(width 0.1143)
		(layer "F.Cu")
		(net "PE_PCH_SPRV_TX_C_DN")
	)
	(segment
		(start 485.001062 -50.404268)
		(end 484.450898 -50.954432)
		(width 0.1143)
		(layer "F.Cu")
		(net "PE_PCH_SPRV_TX_C_DN")
	)
	(via
		(at 483.626668 -52.04333)
		(size 0.508)
		(drill 0.254)
		(layers "F.Cu" "B.Cu")
		(net "PE_PCH_SPRV_TX_C_DN")
	)
	(via
		(at 405.346154 -126.918212)
		(size 0.508)
		(drill 0.254)
		(layers "F.Cu" "B.Cu")
		(net "PE_PCH_SPRV_TX_C_DN")
	)
	(via
		(at 405.73452 -125.835664)
		(size 0.508)
		(drill 0.254)
		(layers "F.Cu" "B.Cu")
		(net "PE_PCH_SPRV_TX_C_DN")
	)
	(segment
		(start 405.346154 -126.918212)
		(end 404.504398 -126.918212)
		(width 0.1143)
		(layer "B.Cu")
		(net "PE_PCH_SPRV_TX_C_DN")
	)
	(segment
		(start 403.932898 -126.918212)
		(end 403.589998 -126.918212)
		(width 0.1143)
		(layer "B.Cu")
		(net "PE_PCH_SPRV_TX_C_DN")
	)
	(segment
		(start 406.11044 -126.55296)
		(end 406.11044 -125.99924)
		(width 0.1143)
		(layer "B.Cu")
		(net "PE_PCH_SPRV_TX_C_DN")
	)
	(segment
		(start 406.11044 -125.99924)
		(end 405.946864 -125.835664)
		(width 0.1143)
		(layer "B.Cu")
		(net "PE_PCH_SPRV_TX_C_DN")
	)
	(segment
		(start 402.675598 -126.918212)
		(end 402.14677 -126.389384)
		(width 0.1143)
		(layer "B.Cu")
		(net "PE_PCH_SPRV_TX_C_DN")
	)
	(segment
		(start 404.047198 -126.803912)
		(end 403.932898 -126.918212)
		(width 0.1143)
		(layer "B.Cu")
		(net "PE_PCH_SPRV_TX_C_DN")
	)
	(segment
		(start 403.589998 -126.918212)
		(end 403.475698 -126.803912)
		(width 0.1143)
		(layer "B.Cu")
		(net "PE_PCH_SPRV_TX_C_DN")
	)
	(segment
		(start 405.745188 -126.918212)
		(end 406.11044 -126.55296)
		(width 0.1143)
		(layer "B.Cu")
		(net "PE_PCH_SPRV_TX_C_DN")
	)
	(segment
		(start 403.018498 -126.918212)
		(end 402.675598 -126.918212)
		(width 0.1143)
		(layer "B.Cu")
		(net "PE_PCH_SPRV_TX_C_DN")
	)
	(segment
		(start 405.346154 -126.918212)
		(end 405.745188 -126.918212)
		(width 0.1143)
		(layer "B.Cu")
		(net "PE_PCH_SPRV_TX_C_DN")
	)
	(segment
		(start 403.132798 -126.803912)
		(end 403.018498 -126.918212)
		(width 0.1143)
		(layer "B.Cu")
		(net "PE_PCH_SPRV_TX_C_DN")
	)
	(segment
		(start 403.475698 -126.803912)
		(end 403.132798 -126.803912)
		(width 0.1143)
		(layer "B.Cu")
		(net "PE_PCH_SPRV_TX_C_DN")
	)
	(segment
		(start 405.946864 -125.835664)
		(end 405.73452 -125.835664)
		(width 0.1143)
		(layer "B.Cu")
		(net "PE_PCH_SPRV_TX_C_DN")
	)
	(segment
		(start 404.390098 -126.803912)
		(end 404.047198 -126.803912)
		(width 0.1143)
		(layer "B.Cu")
		(net "PE_PCH_SPRV_TX_C_DN")
	)
	(segment
		(start 404.504398 -126.918212)
		(end 404.390098 -126.803912)
		(width 0.1143)
		(layer "B.Cu")
		(net "PE_PCH_SPRV_TX_C_DN")
	)
	(segment
		(start 415.731452 -121.687336)
		(end 414.673288 -122.7455)
		(width 0.1143)
		(layer "In4.Cu")
		(net "PE_PCH_SPRV_TX_C_DN")
	)
	(segment
		(start 483.626668 -52.04333)
		(end 483.899464 -51.770534)
		(width 0.1143)
		(layer "In4.Cu")
		(net "PE_PCH_SPRV_TX_C_DN")
	)
	(segment
		(start 476.486728 -63.286894)
		(end 476.244412 -63.52921)
		(width 0.1143)
		(layer "In4.Cu")
		(net "PE_PCH_SPRV_TX_C_DN")
	)
	(segment
		(start 482.841808 -60.236354)
		(end 479.770694 -60.236354)
		(width 0.1143)
		(layer "In4.Cu")
		(net "PE_PCH_SPRV_TX_C_DN")
	)
	(segment
		(start 416.83178 -107.79125)
		(end 415.468054 -109.154976)
		(width 0.1143)
		(layer "In4.Cu")
		(net "PE_PCH_SPRV_TX_C_DN")
	)
	(segment
		(start 406.409906 -124.677678)
		(end 406.013158 -125.074426)
		(width 0.1143)
		(layer "In4.Cu")
		(net "PE_PCH_SPRV_TX_C_DN")
	)
	(segment
		(start 407.856944 -124.677678)
		(end 406.409906 -124.677678)
		(width 0.1143)
		(layer "In4.Cu")
		(net "PE_PCH_SPRV_TX_C_DN")
	)
	(segment
		(start 418.163502 -107.79125)
		(end 416.83178 -107.79125)
		(width 0.1143)
		(layer "In4.Cu")
		(net "PE_PCH_SPRV_TX_C_DN")
	)
	(segment
		(start 483.899464 -51.770534)
		(end 484.070152 -51.770534)
		(width 0.1143)
		(layer "In4.Cu")
		(net "PE_PCH_SPRV_TX_C_DN")
	)
	(segment
		(start 477.923606 -61.850016)
		(end 477.681036 -62.092332)
		(width 0.1143)
		(layer "In4.Cu")
		(net "PE_PCH_SPRV_TX_C_DN")
	)
	(segment
		(start 476.244412 -63.762636)
		(end 476.001842 -64.005206)
		(width 0.1143)
		(layer "In4.Cu")
		(net "PE_PCH_SPRV_TX_C_DN")
	)
	(segment
		(start 477.43872 -62.568328)
		(end 477.205294 -62.568328)
		(width 0.1143)
		(layer "In4.Cu")
		(net "PE_PCH_SPRV_TX_C_DN")
	)
	(segment
		(start 414.673288 -122.7455)
		(end 409.301442 -122.7455)
		(width 0.1143)
		(layer "In4.Cu")
		(net "PE_PCH_SPRV_TX_C_DN")
	)
	(segment
		(start 477.681036 -62.092332)
		(end 477.681036 -62.326012)
		(width 0.1143)
		(layer "In4.Cu")
		(net "PE_PCH_SPRV_TX_C_DN")
	)
	(segment
		(start 416.7759 -121.257822)
		(end 416.346386 -121.687336)
		(width 0.1143)
		(layer "In4.Cu")
		(net "PE_PCH_SPRV_TX_C_DN")
	)
	(segment
		(start 406.013158 -125.557026)
		(end 405.73452 -125.835664)
		(width 0.1143)
		(layer "In4.Cu")
		(net "PE_PCH_SPRV_TX_C_DN")
	)
	(segment
		(start 415.468054 -109.154976)
		(end 415.468054 -117.101112)
		(width 0.1143)
		(layer "In4.Cu")
		(net "PE_PCH_SPRV_TX_C_DN")
	)
	(segment
		(start 409.301442 -122.7455)
		(end 408.652218 -123.394724)
		(width 0.1143)
		(layer "In4.Cu")
		(net "PE_PCH_SPRV_TX_C_DN")
	)
	(segment
		(start 406.013158 -125.074426)
		(end 406.013158 -125.557026)
		(width 0.1143)
		(layer "In4.Cu")
		(net "PE_PCH_SPRV_TX_C_DN")
	)
	(segment
		(start 484.070152 -51.770534)
		(end 484.184452 -51.884834)
		(width 0.1143)
		(layer "In4.Cu")
		(net "PE_PCH_SPRV_TX_C_DN")
	)
	(segment
		(start 422.859454 -97.610422)
		(end 422.859454 -103.095298)
		(width 0.1143)
		(layer "In4.Cu")
		(net "PE_PCH_SPRV_TX_C_DN")
	)
	(segment
		(start 415.468054 -117.101112)
		(end 416.7759 -118.408958)
		(width 0.1143)
		(layer "In4.Cu")
		(net "PE_PCH_SPRV_TX_C_DN")
	)
	(segment
		(start 473.733876 -66.273172)
		(end 425.29633 -66.273172)
		(width 0.1143)
		(layer "In4.Cu")
		(net "PE_PCH_SPRV_TX_C_DN")
	)
	(segment
		(start 478.157032 -61.850016)
		(end 477.923606 -61.850016)
		(width 0.1143)
		(layer "In4.Cu")
		(net "PE_PCH_SPRV_TX_C_DN")
	)
	(segment
		(start 475.525846 -64.247776)
		(end 475.525846 -64.481202)
		(width 0.1143)
		(layer "In4.Cu")
		(net "PE_PCH_SPRV_TX_C_DN")
	)
	(segment
		(start 476.962724 -63.044324)
		(end 476.720154 -63.286894)
		(width 0.1143)
		(layer "In4.Cu")
		(net "PE_PCH_SPRV_TX_C_DN")
	)
	(segment
		(start 408.652218 -123.394724)
		(end 408.652218 -123.882404)
		(width 0.1143)
		(layer "In4.Cu")
		(net "PE_PCH_SPRV_TX_C_DN")
	)
	(segment
		(start 477.205294 -62.568328)
		(end 476.962724 -62.810898)
		(width 0.1143)
		(layer "In4.Cu")
		(net "PE_PCH_SPRV_TX_C_DN")
	)
	(segment
		(start 421.691816 -77.817726)
		(end 421.691816 -96.442784)
		(width 0.1143)
		(layer "In4.Cu")
		(net "PE_PCH_SPRV_TX_C_DN")
	)
	(segment
		(start 476.962724 -62.810898)
		(end 476.962724 -63.044324)
		(width 0.1143)
		(layer "In4.Cu")
		(net "PE_PCH_SPRV_TX_C_DN")
	)
	(segment
		(start 484.184452 -51.884834)
		(end 484.184452 -58.89371)
		(width 0.1143)
		(layer "In4.Cu")
		(net "PE_PCH_SPRV_TX_C_DN")
	)
	(segment
		(start 484.184452 -58.89371)
		(end 482.841808 -60.236354)
		(width 0.1143)
		(layer "In4.Cu")
		(net "PE_PCH_SPRV_TX_C_DN")
	)
	(segment
		(start 477.681036 -62.326012)
		(end 477.43872 -62.568328)
		(width 0.1143)
		(layer "In4.Cu")
		(net "PE_PCH_SPRV_TX_C_DN")
	)
	(segment
		(start 416.346386 -121.687336)
		(end 415.731452 -121.687336)
		(width 0.1143)
		(layer "In4.Cu")
		(net "PE_PCH_SPRV_TX_C_DN")
	)
	(segment
		(start 476.001842 -64.005206)
		(end 475.768416 -64.005206)
		(width 0.1143)
		(layer "In4.Cu")
		(net "PE_PCH_SPRV_TX_C_DN")
	)
	(segment
		(start 475.768416 -64.005206)
		(end 475.525846 -64.247776)
		(width 0.1143)
		(layer "In4.Cu")
		(net "PE_PCH_SPRV_TX_C_DN")
	)
	(segment
		(start 421.691816 -96.442784)
		(end 422.859454 -97.610422)
		(width 0.1143)
		(layer "In4.Cu")
		(net "PE_PCH_SPRV_TX_C_DN")
	)
	(segment
		(start 422.636442 -76.8731)
		(end 421.691816 -77.817726)
		(width 0.1143)
		(layer "In4.Cu")
		(net "PE_PCH_SPRV_TX_C_DN")
	)
	(segment
		(start 408.652218 -123.882404)
		(end 407.856944 -124.677678)
		(width 0.1143)
		(layer "In4.Cu")
		(net "PE_PCH_SPRV_TX_C_DN")
	)
	(segment
		(start 476.244412 -63.52921)
		(end 476.244412 -63.762636)
		(width 0.1143)
		(layer "In4.Cu")
		(net "PE_PCH_SPRV_TX_C_DN")
	)
	(segment
		(start 479.770694 -60.236354)
		(end 478.157032 -61.850016)
		(width 0.1143)
		(layer "In4.Cu")
		(net "PE_PCH_SPRV_TX_C_DN")
	)
	(segment
		(start 416.7759 -118.408958)
		(end 416.7759 -121.257822)
		(width 0.1143)
		(layer "In4.Cu")
		(net "PE_PCH_SPRV_TX_C_DN")
	)
	(segment
		(start 425.29633 -66.273172)
		(end 422.636442 -68.93306)
		(width 0.1143)
		(layer "In4.Cu")
		(net "PE_PCH_SPRV_TX_C_DN")
	)
	(segment
		(start 475.525846 -64.481202)
		(end 473.733876 -66.273172)
		(width 0.1143)
		(layer "In4.Cu")
		(net "PE_PCH_SPRV_TX_C_DN")
	)
	(segment
		(start 476.720154 -63.286894)
		(end 476.486728 -63.286894)
		(width 0.1143)
		(layer "In4.Cu")
		(net "PE_PCH_SPRV_TX_C_DN")
	)
	(segment
		(start 422.636442 -68.93306)
		(end 422.636442 -76.8731)
		(width 0.1143)
		(layer "In4.Cu")
		(net "PE_PCH_SPRV_TX_C_DN")
	)
	(segment
		(start 422.859454 -103.095298)
		(end 418.163502 -107.79125)
		(width 0.1143)
		(layer "In4.Cu")
		(net "PE_PCH_SPRV_TX_C_DN")
	)
	(segment
		(start 486.123234 -49.022254)
		(end 486.123234 -49.11979)
		(width 0.1143)
		(layer "F.Cu")
		(net "PE_PCH_SPRV_RX_DP")
	)
	(segment
		(start 486.123234 -49.11979)
		(end 485.836468 -49.406556)
		(width 0.1143)
		(layer "F.Cu")
		(net "PE_PCH_SPRV_RX_DP")
	)
	(segment
		(start 485.836468 -49.913032)
		(end 485.4956 -50.2539)
		(width 0.1143)
		(layer "F.Cu")
		(net "PE_PCH_SPRV_RX_DP")
	)
	(segment
		(start 486.00106 -48.3362)
		(end 486.00106 -48.90008)
		(width 0.1143)
		(layer "F.Cu")
		(net "PE_PCH_SPRV_RX_DP")
	)
	(segment
		(start 485.836468 -49.406556)
		(end 485.836468 -49.913032)
		(width 0.1143)
		(layer "F.Cu")
		(net "PE_PCH_SPRV_RX_DP")
	)
	(segment
		(start 486.00106 -48.90008)
		(end 486.123234 -49.022254)
		(width 0.1143)
		(layer "F.Cu")
		(net "PE_PCH_SPRV_RX_DP")
	)
	(segment
		(start 486.501186 -48.3362)
		(end 486.501186 -48.905414)
		(width 0.1143)
		(layer "F.Cu")
		(net "PE_PCH_SPRV_RX_DN")
	)
	(segment
		(start 486.077768 -49.506632)
		(end 486.077768 -49.947068)
		(width 0.1143)
		(layer "F.Cu")
		(net "PE_PCH_SPRV_RX_DN")
	)
	(segment
		(start 486.501186 -48.905414)
		(end 486.364534 -49.042066)
		(width 0.1143)
		(layer "F.Cu")
		(net "PE_PCH_SPRV_RX_DN")
	)
	(segment
		(start 486.364534 -49.042066)
		(end 486.364534 -49.219866)
		(width 0.1143)
		(layer "F.Cu")
		(net "PE_PCH_SPRV_RX_DN")
	)
	(segment
		(start 486.364534 -49.219866)
		(end 486.077768 -49.506632)
		(width 0.1143)
		(layer "F.Cu")
		(net "PE_PCH_SPRV_RX_DN")
	)
	(segment
		(start 486.077768 -49.947068)
		(end 486.3846 -50.2539)
		(width 0.1143)
		(layer "F.Cu")
		(net "PE_PCH_SPRV_RX_DN")
	)
	(segment
		(start 389.462518 -128.803146)
		(end 389.53313 -128.873758)
		(width 0.0889)
		(layer "F.Cu")
		(net "PE_PCH_SPRV_RX_C_DP")
	)
	(segment
		(start 388.164832 -126.454154)
		(end 388.164832 -127.823468)
		(width 0.0889)
		(layer "F.Cu")
		(net "PE_PCH_SPRV_RX_C_DP")
	)
	(segment
		(start 388.164832 -127.823468)
		(end 388.224522 -127.883158)
		(width 0.0889)
		(layer "F.Cu")
		(net "PE_PCH_SPRV_RX_C_DP")
	)
	(segment
		(start 485.909366 -51.787806)
		(end 485.795066 -51.673506)
		(width 0.1143)
		(layer "F.Cu")
		(net "PE_PCH_SPRV_RX_C_DP")
	)
	(segment
		(start 484.997252 -52.265326)
		(end 485.170226 -52.4383)
		(width 0.1143)
		(layer "F.Cu")
		(net "PE_PCH_SPRV_RX_C_DP")
	)
	(segment
		(start 389.14451 -128.803146)
		(end 389.462518 -128.803146)
		(width 0.0889)
		(layer "F.Cu")
		(net "PE_PCH_SPRV_RX_C_DP")
	)
	(segment
		(start 388.224522 -127.883158)
		(end 388.224522 -128.009142)
		(width 0.0889)
		(layer "F.Cu")
		(net "PE_PCH_SPRV_RX_C_DP")
	)
	(segment
		(start 485.4956 -51.559206)
		(end 485.4956 -51.1429)
		(width 0.1143)
		(layer "F.Cu")
		(net "PE_PCH_SPRV_RX_C_DP")
	)
	(segment
		(start 388.511796 -126.015242)
		(end 388.390638 -126.22784)
		(width 0.0889)
		(layer "F.Cu")
		(net "PE_PCH_SPRV_RX_C_DP")
	)
	(segment
		(start 388.57047 -125.873764)
		(end 388.511796 -126.015242)
		(width 0.0889)
		(layer "F.Cu")
		(net "PE_PCH_SPRV_RX_C_DP")
	)
	(segment
		(start 388.413244 -128.197864)
		(end 388.538974 -128.197864)
		(width 0.0889)
		(layer "F.Cu")
		(net "PE_PCH_SPRV_RX_C_DP")
	)
	(segment
		(start 485.170226 -52.4383)
		(end 485.5845 -52.4383)
		(width 0.1143)
		(layer "F.Cu")
		(net "PE_PCH_SPRV_RX_C_DP")
	)
	(segment
		(start 388.390638 -126.22784)
		(end 388.164832 -126.454154)
		(width 0.0889)
		(layer "F.Cu")
		(net "PE_PCH_SPRV_RX_C_DP")
	)
	(segment
		(start 485.5845 -52.4383)
		(end 485.909366 -52.113434)
		(width 0.1143)
		(layer "F.Cu")
		(net "PE_PCH_SPRV_RX_C_DP")
	)
	(segment
		(start 485.795066 -51.673506)
		(end 485.6099 -51.673506)
		(width 0.1143)
		(layer "F.Cu")
		(net "PE_PCH_SPRV_RX_C_DP")
	)
	(segment
		(start 485.909366 -52.113434)
		(end 485.909366 -51.787806)
		(width 0.1143)
		(layer "F.Cu")
		(net "PE_PCH_SPRV_RX_C_DP")
	)
	(segment
		(start 389.042148 -128.700784)
		(end 389.14451 -128.803146)
		(width 0.0889)
		(layer "F.Cu")
		(net "PE_PCH_SPRV_RX_C_DP")
	)
	(segment
		(start 388.916164 -128.700784)
		(end 389.042148 -128.700784)
		(width 0.0889)
		(layer "F.Cu")
		(net "PE_PCH_SPRV_RX_C_DP")
	)
	(segment
		(start 388.727442 -128.512062)
		(end 388.916164 -128.700784)
		(width 0.0889)
		(layer "F.Cu")
		(net "PE_PCH_SPRV_RX_C_DP")
	)
	(segment
		(start 389.53313 -128.873758)
		(end 389.53313 -129.29362)
		(width 0.0889)
		(layer "F.Cu")
		(net "PE_PCH_SPRV_RX_C_DP")
	)
	(segment
		(start 388.515352 -125.76048)
		(end 388.57047 -125.873764)
		(width 0.0889)
		(layer "F.Cu")
		(net "PE_PCH_SPRV_RX_C_DP")
	)
	(segment
		(start 388.224522 -128.009142)
		(end 388.413244 -128.197864)
		(width 0.0889)
		(layer "F.Cu")
		(net "PE_PCH_SPRV_RX_C_DP")
	)
	(segment
		(start 388.485126 -125.750066)
		(end 388.515352 -125.76048)
		(width 0.0889)
		(layer "F.Cu")
		(net "PE_PCH_SPRV_RX_C_DP")
	)
	(segment
		(start 485.6099 -51.673506)
		(end 485.4956 -51.559206)
		(width 0.1143)
		(layer "F.Cu")
		(net "PE_PCH_SPRV_RX_C_DP")
	)
	(segment
		(start 388.538974 -128.197864)
		(end 388.727442 -128.386332)
		(width 0.0889)
		(layer "F.Cu")
		(net "PE_PCH_SPRV_RX_C_DP")
	)
	(segment
		(start 388.727442 -128.386332)
		(end 388.727442 -128.512062)
		(width 0.0889)
		(layer "F.Cu")
		(net "PE_PCH_SPRV_RX_C_DP")
	)
	(segment
		(start 484.997252 -51.893978)
		(end 484.997252 -52.265326)
		(width 0.1143)
		(layer "F.Cu")
		(net "PE_PCH_SPRV_RX_C_DP")
	)
	(via
		(at 484.997252 -51.893978)
		(size 0.508)
		(drill 0.254)
		(layers "F.Cu" "B.Cu")
		(net "PE_PCH_SPRV_RX_C_DP")
	)
	(via
		(at 389.53313 -129.29362)
		(size 0.508)
		(drill 0.254)
		(layers "F.Cu" "B.Cu")
		(net "PE_PCH_SPRV_RX_C_DP")
	)
	(segment
		(start 485.126792 -52.3367)
		(end 485.616758 -52.3367)
		(width 0.1143)
		(layer "In4.Cu")
		(net "PE_PCH_SPRV_RX_C_DP")
	)
	(segment
		(start 401.625816 -126.944628)
		(end 401.015962 -126.334774)
		(width 0.1143)
		(layer "In4.Cu")
		(net "PE_PCH_SPRV_RX_C_DP")
	)
	(segment
		(start 484.997252 -51.893978)
		(end 484.995728 -52.20208)
		(width 0.1143)
		(layer "In4.Cu")
		(net "PE_PCH_SPRV_RX_C_DP")
	)
	(segment
		(start 391.167112 -126.334774)
		(end 390.659112 -126.842774)
		(width 0.1143)
		(layer "In4.Cu")
		(net "PE_PCH_SPRV_RX_C_DP")
	)
	(segment
		(start 390.659112 -126.842774)
		(end 390.659112 -128.601978)
		(width 0.1143)
		(layer "In4.Cu")
		(net "PE_PCH_SPRV_RX_C_DP")
	)
	(segment
		(start 486.25252 -52.972462)
		(end 486.25252 -57.37479)
		(width 0.1143)
		(layer "In4.Cu")
		(net "PE_PCH_SPRV_RX_C_DP")
	)
	(segment
		(start 423.478198 -104.003856)
		(end 423.477944 -104.003856)
		(width 0.1143)
		(layer "In4.Cu")
		(net "PE_PCH_SPRV_RX_C_DP")
	)
	(segment
		(start 418.581332 -108.871004)
		(end 418.581078 -108.87075)
		(width 0.1143)
		(layer "In4.Cu")
		(net "PE_PCH_SPRV_RX_C_DP")
	)
	(segment
		(start 486.25252 -57.37479)
		(end 487.56189 -58.68416)
		(width 0.1143)
		(layer "In4.Cu")
		(net "PE_PCH_SPRV_RX_C_DP")
	)
	(segment
		(start 487.56189 -58.68416)
		(end 487.56189 -59.486292)
		(width 0.1143)
		(layer "In4.Cu")
		(net "PE_PCH_SPRV_RX_C_DP")
	)
	(segment
		(start 484.995728 -52.20208)
		(end 484.995728 -52.205128)
		(width 0.1143)
		(layer "In4.Cu")
		(net "PE_PCH_SPRV_RX_C_DP")
	)
	(segment
		(start 417.615624 -117.083078)
		(end 418.1221 -117.589554)
		(width 0.1143)
		(layer "In4.Cu")
		(net "PE_PCH_SPRV_RX_C_DP")
	)
	(segment
		(start 415.564828 -123.825)
		(end 410.017976 -123.825)
		(width 0.1143)
		(layer "In4.Cu")
		(net "PE_PCH_SPRV_RX_C_DP")
	)
	(segment
		(start 418.1221 -117.589554)
		(end 418.1221 -121.4501)
		(width 0.1143)
		(layer "In4.Cu")
		(net "PE_PCH_SPRV_RX_C_DP")
	)
	(segment
		(start 416.473386 -122.916442)
		(end 415.564828 -123.825)
		(width 0.1143)
		(layer "In4.Cu")
		(net "PE_PCH_SPRV_RX_C_DP")
	)
	(segment
		(start 418.581078 -108.87075)
		(end 418.196522 -108.87075)
		(width 0.1143)
		(layer "In4.Cu")
		(net "PE_PCH_SPRV_RX_C_DP")
	)
	(segment
		(start 418.610796 -108.871004)
		(end 418.581332 -108.871004)
		(width 0.1143)
		(layer "In4.Cu")
		(net "PE_PCH_SPRV_RX_C_DP")
	)
	(segment
		(start 401.015962 -126.334774)
		(end 391.167112 -126.334774)
		(width 0.1143)
		(layer "In4.Cu")
		(net "PE_PCH_SPRV_RX_C_DP")
	)
	(segment
		(start 423.938954 -69.42328)
		(end 423.938954 -103.5431)
		(width 0.1143)
		(layer "In4.Cu")
		(net "PE_PCH_SPRV_RX_C_DP")
	)
	(segment
		(start 410.017976 -123.825)
		(end 409.86075 -123.98248)
		(width 0.1143)
		(layer "In4.Cu")
		(net "PE_PCH_SPRV_RX_C_DP")
	)
	(segment
		(start 390.659112 -128.601978)
		(end 390.289796 -128.971294)
		(width 0.1143)
		(layer "In4.Cu")
		(net "PE_PCH_SPRV_RX_C_DP")
	)
	(segment
		(start 417.615624 -109.451648)
		(end 417.615624 -117.083078)
		(width 0.1143)
		(layer "In4.Cu")
		(net "PE_PCH_SPRV_RX_C_DP")
	)
	(segment
		(start 480.469194 -61.315854)
		(end 474.432376 -67.352672)
		(width 0.1143)
		(layer "In4.Cu")
		(net "PE_PCH_SPRV_RX_C_DP")
	)
	(segment
		(start 418.196522 -108.87075)
		(end 417.615624 -109.451648)
		(width 0.1143)
		(layer "In4.Cu")
		(net "PE_PCH_SPRV_RX_C_DP")
	)
	(segment
		(start 484.995728 -52.205128)
		(end 485.126792 -52.3367)
		(width 0.1143)
		(layer "In4.Cu")
		(net "PE_PCH_SPRV_RX_C_DP")
	)
	(segment
		(start 407.840434 -126.413006)
		(end 406.634696 -126.944628)
		(width 0.1143)
		(layer "In4.Cu")
		(net "PE_PCH_SPRV_RX_C_DP")
	)
	(segment
		(start 485.732328 -61.315854)
		(end 480.469194 -61.315854)
		(width 0.1143)
		(layer "In4.Cu")
		(net "PE_PCH_SPRV_RX_C_DP")
	)
	(segment
		(start 423.938954 -103.5431)
		(end 423.478198 -104.003856)
		(width 0.1143)
		(layer "In4.Cu")
		(net "PE_PCH_SPRV_RX_C_DP")
	)
	(segment
		(start 418.1221 -121.4501)
		(end 416.655758 -122.916442)
		(width 0.1143)
		(layer "In4.Cu")
		(net "PE_PCH_SPRV_RX_C_DP")
	)
	(segment
		(start 389.855456 -128.971294)
		(end 389.53313 -129.29362)
		(width 0.1143)
		(layer "In4.Cu")
		(net "PE_PCH_SPRV_RX_C_DP")
	)
	(segment
		(start 409.86075 -123.98248)
		(end 409.449524 -124.803916)
		(width 0.1143)
		(layer "In4.Cu")
		(net "PE_PCH_SPRV_RX_C_DP")
	)
	(segment
		(start 474.432376 -67.352672)
		(end 426.009562 -67.352672)
		(width 0.1143)
		(layer "In4.Cu")
		(net "PE_PCH_SPRV_RX_C_DP")
	)
	(segment
		(start 485.616758 -52.3367)
		(end 486.25252 -52.972462)
		(width 0.1143)
		(layer "In4.Cu")
		(net "PE_PCH_SPRV_RX_C_DP")
	)
	(segment
		(start 390.289796 -128.971294)
		(end 389.855456 -128.971294)
		(width 0.1143)
		(layer "In4.Cu")
		(net "PE_PCH_SPRV_RX_C_DP")
	)
	(segment
		(start 487.56189 -59.486292)
		(end 485.732328 -61.315854)
		(width 0.1143)
		(layer "In4.Cu")
		(net "PE_PCH_SPRV_RX_C_DP")
	)
	(segment
		(start 406.634696 -126.944628)
		(end 401.625816 -126.944628)
		(width 0.1143)
		(layer "In4.Cu")
		(net "PE_PCH_SPRV_RX_C_DP")
	)
	(segment
		(start 409.449524 -124.803916)
		(end 407.840434 -126.413006)
		(width 0.1143)
		(layer "In4.Cu")
		(net "PE_PCH_SPRV_RX_C_DP")
	)
	(segment
		(start 426.009562 -67.352672)
		(end 423.938954 -69.42328)
		(width 0.1143)
		(layer "In4.Cu")
		(net "PE_PCH_SPRV_RX_C_DP")
	)
	(segment
		(start 423.477944 -104.003856)
		(end 418.610796 -108.871004)
		(width 0.1143)
		(layer "In4.Cu")
		(net "PE_PCH_SPRV_RX_C_DP")
	)
	(segment
		(start 416.655758 -122.916442)
		(end 416.473386 -122.916442)
		(width 0.1143)
		(layer "In4.Cu")
		(net "PE_PCH_SPRV_RX_C_DP")
	)
	(segment
		(start 388.355332 -126.533148)
		(end 388.355332 -127.744474)
		(width 0.0889)
		(layer "F.Cu")
		(net "PE_PCH_SPRV_RX_C_DN")
	)
	(segment
		(start 388.6835 -126.099316)
		(end 388.543546 -126.344426)
		(width 0.0889)
		(layer "F.Cu")
		(net "PE_PCH_SPRV_RX_C_DN")
	)
	(segment
		(start 389.325104 -128.612646)
		(end 389.53313 -128.40462)
		(width 0.0889)
		(layer "F.Cu")
		(net "PE_PCH_SPRV_RX_C_DN")
	)
	(segment
		(start 485.684576 -52.6796)
		(end 486.150666 -52.21351)
		(width 0.1143)
		(layer "F.Cu")
		(net "PE_PCH_SPRV_RX_C_DN")
	)
	(segment
		(start 484.992934 -53.03647)
		(end 485.349804 -52.6796)
		(width 0.1143)
		(layer "F.Cu")
		(net "PE_PCH_SPRV_RX_C_DN")
	)
	(segment
		(start 388.543546 -126.344426)
		(end 388.355332 -126.533148)
		(width 0.0889)
		(layer "F.Cu")
		(net "PE_PCH_SPRV_RX_C_DN")
	)
	(segment
		(start 388.7978 -125.674882)
		(end 388.7978 -125.82271)
		(width 0.0889)
		(layer "F.Cu")
		(net "PE_PCH_SPRV_RX_C_DN")
	)
	(segment
		(start 388.6708 -125.4125)
		(end 388.7978 -125.674882)
		(width 0.0889)
		(layer "F.Cu")
		(net "PE_PCH_SPRV_RX_C_DN")
	)
	(segment
		(start 486.3846 -51.486816)
		(end 486.3846 -51.1429)
		(width 0.1143)
		(layer "F.Cu")
		(net "PE_PCH_SPRV_RX_C_DN")
	)
	(segment
		(start 388.355332 -127.744474)
		(end 389.223504 -128.612646)
		(width 0.0889)
		(layer "F.Cu")
		(net "PE_PCH_SPRV_RX_C_DN")
	)
	(segment
		(start 389.223504 -128.612646)
		(end 389.325104 -128.612646)
		(width 0.0889)
		(layer "F.Cu")
		(net "PE_PCH_SPRV_RX_C_DN")
	)
	(segment
		(start 388.7978 -125.82271)
		(end 388.6835 -126.099316)
		(width 0.0889)
		(layer "F.Cu")
		(net "PE_PCH_SPRV_RX_C_DN")
	)
	(segment
		(start 388.485126 -124.919994)
		(end 388.6708 -125.4125)
		(width 0.0889)
		(layer "F.Cu")
		(net "PE_PCH_SPRV_RX_C_DN")
	)
	(segment
		(start 485.349804 -52.6796)
		(end 485.684576 -52.6796)
		(width 0.1143)
		(layer "F.Cu")
		(net "PE_PCH_SPRV_RX_C_DN")
	)
	(segment
		(start 486.150666 -51.72075)
		(end 486.3846 -51.486816)
		(width 0.1143)
		(layer "F.Cu")
		(net "PE_PCH_SPRV_RX_C_DN")
	)
	(segment
		(start 486.150666 -52.21351)
		(end 486.150666 -51.72075)
		(width 0.1143)
		(layer "F.Cu")
		(net "PE_PCH_SPRV_RX_C_DN")
	)
	(via
		(at 389.53313 -128.40462)
		(size 0.508)
		(drill 0.254)
		(layers "F.Cu" "B.Cu")
		(net "PE_PCH_SPRV_RX_C_DN")
	)
	(via
		(at 484.992934 -53.03647)
		(size 0.508)
		(drill 0.254)
		(layers "F.Cu" "B.Cu")
		(net "PE_PCH_SPRV_RX_C_DN")
	)
	(segment
		(start 406.572974 -126.652528)
		(end 401.746974 -126.652528)
		(width 0.1143)
		(layer "In4.Cu")
		(net "PE_PCH_SPRV_RX_C_DN")
	)
	(segment
		(start 394.878814 -125.877574)
		(end 394.713714 -126.042674)
		(width 0.1143)
		(layer "In4.Cu")
		(net "PE_PCH_SPRV_RX_C_DN")
	)
	(segment
		(start 477.254062 -63.884302)
		(end 477.011746 -64.126618)
		(width 0.1143)
		(layer "In4.Cu")
		(net "PE_PCH_SPRV_RX_C_DN")
	)
	(segment
		(start 415.44367 -123.5329)
		(end 409.896818 -123.5329)
		(width 0.1143)
		(layer "In4.Cu")
		(net "PE_PCH_SPRV_RX_C_DN")
	)
	(segment
		(start 476.050864 -65.320926)
		(end 475.817184 -65.320926)
		(width 0.1143)
		(layer "In4.Cu")
		(net "PE_PCH_SPRV_RX_C_DN")
	)
	(segment
		(start 390.367012 -128.48082)
		(end 390.168638 -128.679194)
		(width 0.1143)
		(layer "In4.Cu")
		(net "PE_PCH_SPRV_RX_C_DN")
	)
	(segment
		(start 389.807704 -128.679194)
		(end 389.53313 -128.40462)
		(width 0.1143)
		(layer "In4.Cu")
		(net "PE_PCH_SPRV_RX_C_DN")
	)
	(segment
		(start 418.075364 -108.57865)
		(end 417.323524 -109.33049)
		(width 0.1143)
		(layer "In4.Cu")
		(net "PE_PCH_SPRV_RX_C_DN")
	)
	(segment
		(start 417.323524 -117.204236)
		(end 417.83 -117.710712)
		(width 0.1143)
		(layer "In4.Cu")
		(net "PE_PCH_SPRV_RX_C_DN")
	)
	(segment
		(start 395.221714 -125.877574)
		(end 394.878814 -125.877574)
		(width 0.1143)
		(layer "In4.Cu")
		(net "PE_PCH_SPRV_RX_C_DN")
	)
	(segment
		(start 423.646854 -103.421942)
		(end 423.35704 -103.711756)
		(width 0.1143)
		(layer "In4.Cu")
		(net "PE_PCH_SPRV_RX_C_DN")
	)
	(segment
		(start 425.888404 -67.060572)
		(end 423.646854 -69.302122)
		(width 0.1143)
		(layer "In4.Cu")
		(net "PE_PCH_SPRV_RX_C_DN")
	)
	(segment
		(start 393.189714 -125.877574)
		(end 392.846814 -125.877574)
		(width 0.1143)
		(layer "In4.Cu")
		(net "PE_PCH_SPRV_RX_C_DN")
	)
	(segment
		(start 423.356786 -103.711756)
		(end 418.489892 -108.57865)
		(width 0.1143)
		(layer "In4.Cu")
		(net "PE_PCH_SPRV_RX_C_DN")
	)
	(segment
		(start 487.26979 -58.805318)
		(end 487.26979 -59.365134)
		(width 0.1143)
		(layer "In4.Cu")
		(net "PE_PCH_SPRV_RX_C_DN")
	)
	(segment
		(start 390.367012 -126.721616)
		(end 390.367012 -128.48082)
		(width 0.1143)
		(layer "In4.Cu")
		(net "PE_PCH_SPRV_RX_C_DN")
	)
	(segment
		(start 485.96042 -53.09362)
		(end 485.96042 -57.495948)
		(width 0.1143)
		(layer "In4.Cu")
		(net "PE_PCH_SPRV_RX_C_DN")
	)
	(segment
		(start 478.206054 -63.165736)
		(end 477.972628 -63.165736)
		(width 0.1143)
		(layer "In4.Cu")
		(net "PE_PCH_SPRV_RX_C_DN")
	)
	(segment
		(start 477.972628 -63.165736)
		(end 477.730058 -63.408306)
		(width 0.1143)
		(layer "In4.Cu")
		(net "PE_PCH_SPRV_RX_C_DN")
	)
	(segment
		(start 409.620466 -123.809252)
		(end 409.20924 -124.630688)
		(width 0.1143)
		(layer "In4.Cu")
		(net "PE_PCH_SPRV_RX_C_DN")
	)
	(segment
		(start 409.20924 -124.630688)
		(end 407.672286 -126.167642)
		(width 0.1143)
		(layer "In4.Cu")
		(net "PE_PCH_SPRV_RX_C_DN")
	)
	(segment
		(start 395.729714 -126.042674)
		(end 395.386814 -126.042674)
		(width 0.1143)
		(layer "In4.Cu")
		(net "PE_PCH_SPRV_RX_C_DN")
	)
	(segment
		(start 477.730058 -63.641732)
		(end 477.487488 -63.884302)
		(width 0.1143)
		(layer "In4.Cu")
		(net "PE_PCH_SPRV_RX_C_DN")
	)
	(segment
		(start 477.730058 -63.408306)
		(end 477.730058 -63.641732)
		(width 0.1143)
		(layer "In4.Cu")
		(net "PE_PCH_SPRV_RX_C_DN")
	)
	(segment
		(start 392.681714 -126.042674)
		(end 391.045954 -126.042674)
		(width 0.1143)
		(layer "In4.Cu")
		(net "PE_PCH_SPRV_RX_C_DN")
	)
	(segment
		(start 390.168638 -128.679194)
		(end 389.807704 -128.679194)
		(width 0.1143)
		(layer "In4.Cu")
		(net "PE_PCH_SPRV_RX_C_DN")
	)
	(segment
		(start 393.697714 -126.042674)
		(end 393.354814 -126.042674)
		(width 0.1143)
		(layer "In4.Cu")
		(net "PE_PCH_SPRV_RX_C_DN")
	)
	(segment
		(start 416.5346 -122.624342)
		(end 416.352228 -122.624342)
		(width 0.1143)
		(layer "In4.Cu")
		(net "PE_PCH_SPRV_RX_C_DN")
	)
	(segment
		(start 392.846814 -125.877574)
		(end 392.681714 -126.042674)
		(width 0.1143)
		(layer "In4.Cu")
		(net "PE_PCH_SPRV_RX_C_DN")
	)
	(segment
		(start 423.646854 -69.302122)
		(end 423.646854 -103.421942)
		(width 0.1143)
		(layer "In4.Cu")
		(net "PE_PCH_SPRV_RX_C_DN")
	)
	(segment
		(start 476.29318 -64.84493)
		(end 476.29318 -65.07861)
		(width 0.1143)
		(layer "In4.Cu")
		(net "PE_PCH_SPRV_RX_C_DN")
	)
	(segment
		(start 418.489892 -108.57865)
		(end 418.075364 -108.57865)
		(width 0.1143)
		(layer "In4.Cu")
		(net "PE_PCH_SPRV_RX_C_DN")
	)
	(segment
		(start 487.26979 -59.365134)
		(end 485.61117 -61.023754)
		(width 0.1143)
		(layer "In4.Cu")
		(net "PE_PCH_SPRV_RX_C_DN")
	)
	(segment
		(start 476.53575 -64.602614)
		(end 476.29318 -64.84493)
		(width 0.1143)
		(layer "In4.Cu")
		(net "PE_PCH_SPRV_RX_C_DN")
	)
	(segment
		(start 477.011746 -64.360044)
		(end 476.769176 -64.602614)
		(width 0.1143)
		(layer "In4.Cu")
		(net "PE_PCH_SPRV_RX_C_DN")
	)
	(segment
		(start 394.370814 -126.042674)
		(end 394.205714 -125.877574)
		(width 0.1143)
		(layer "In4.Cu")
		(net "PE_PCH_SPRV_RX_C_DN")
	)
	(segment
		(start 394.713714 -126.042674)
		(end 394.370814 -126.042674)
		(width 0.1143)
		(layer "In4.Cu")
		(net "PE_PCH_SPRV_RX_C_DN")
	)
	(segment
		(start 474.311218 -67.060572)
		(end 425.888404 -67.060572)
		(width 0.1143)
		(layer "In4.Cu")
		(net "PE_PCH_SPRV_RX_C_DN")
	)
	(segment
		(start 485.96042 -57.495948)
		(end 487.26979 -58.805318)
		(width 0.1143)
		(layer "In4.Cu")
		(net "PE_PCH_SPRV_RX_C_DN")
	)
	(segment
		(start 484.994204 -52.742846)
		(end 485.109012 -52.6288)
		(width 0.1143)
		(layer "In4.Cu")
		(net "PE_PCH_SPRV_RX_C_DN")
	)
	(segment
		(start 485.109012 -52.6288)
		(end 485.4956 -52.6288)
		(width 0.1143)
		(layer "In4.Cu")
		(net "PE_PCH_SPRV_RX_C_DN")
	)
	(segment
		(start 417.83 -121.328942)
		(end 416.5346 -122.624342)
		(width 0.1143)
		(layer "In4.Cu")
		(net "PE_PCH_SPRV_RX_C_DN")
	)
	(segment
		(start 476.29318 -65.07861)
		(end 476.050864 -65.320926)
		(width 0.1143)
		(layer "In4.Cu")
		(net "PE_PCH_SPRV_RX_C_DN")
	)
	(segment
		(start 393.862814 -125.877574)
		(end 393.697714 -126.042674)
		(width 0.1143)
		(layer "In4.Cu")
		(net "PE_PCH_SPRV_RX_C_DN")
	)
	(segment
		(start 477.487488 -63.884302)
		(end 477.254062 -63.884302)
		(width 0.1143)
		(layer "In4.Cu")
		(net "PE_PCH_SPRV_RX_C_DN")
	)
	(segment
		(start 407.672286 -126.167642)
		(end 406.572974 -126.652528)
		(width 0.1143)
		(layer "In4.Cu")
		(net "PE_PCH_SPRV_RX_C_DN")
	)
	(segment
		(start 423.35704 -103.711756)
		(end 423.356786 -103.711756)
		(width 0.1143)
		(layer "In4.Cu")
		(net "PE_PCH_SPRV_RX_C_DN")
	)
	(segment
		(start 476.769176 -64.602614)
		(end 476.53575 -64.602614)
		(width 0.1143)
		(layer "In4.Cu")
		(net "PE_PCH_SPRV_RX_C_DN")
	)
	(segment
		(start 396.237714 -125.877574)
		(end 395.894814 -125.877574)
		(width 0.1143)
		(layer "In4.Cu")
		(net "PE_PCH_SPRV_RX_C_DN")
	)
	(segment
		(start 480.348036 -61.023754)
		(end 478.206054 -63.165736)
		(width 0.1143)
		(layer "In4.Cu")
		(net "PE_PCH_SPRV_RX_C_DN")
	)
	(segment
		(start 393.354814 -126.042674)
		(end 393.189714 -125.877574)
		(width 0.1143)
		(layer "In4.Cu")
		(net "PE_PCH_SPRV_RX_C_DN")
	)
	(segment
		(start 409.896818 -123.5329)
		(end 409.620466 -123.809252)
		(width 0.1143)
		(layer "In4.Cu")
		(net "PE_PCH_SPRV_RX_C_DN")
	)
	(segment
		(start 485.4956 -52.6288)
		(end 485.96042 -53.09362)
		(width 0.1143)
		(layer "In4.Cu")
		(net "PE_PCH_SPRV_RX_C_DN")
	)
	(segment
		(start 484.992934 -53.03647)
		(end 484.994204 -52.742846)
		(width 0.1143)
		(layer "In4.Cu")
		(net "PE_PCH_SPRV_RX_C_DN")
	)
	(segment
		(start 391.045954 -126.042674)
		(end 390.367012 -126.721616)
		(width 0.1143)
		(layer "In4.Cu")
		(net "PE_PCH_SPRV_RX_C_DN")
	)
	(segment
		(start 485.61117 -61.023754)
		(end 480.348036 -61.023754)
		(width 0.1143)
		(layer "In4.Cu")
		(net "PE_PCH_SPRV_RX_C_DN")
	)
	(segment
		(start 475.574868 -65.796922)
		(end 474.311218 -67.060572)
		(width 0.1143)
		(layer "In4.Cu")
		(net "PE_PCH_SPRV_RX_C_DN")
	)
	(segment
		(start 417.323524 -109.33049)
		(end 417.323524 -117.204236)
		(width 0.1143)
		(layer "In4.Cu")
		(net "PE_PCH_SPRV_RX_C_DN")
	)
	(segment
		(start 475.574868 -65.563496)
		(end 475.574868 -65.796922)
		(width 0.1143)
		(layer "In4.Cu")
		(net "PE_PCH_SPRV_RX_C_DN")
	)
	(segment
		(start 394.205714 -125.877574)
		(end 393.862814 -125.877574)
		(width 0.1143)
		(layer "In4.Cu")
		(net "PE_PCH_SPRV_RX_C_DN")
	)
	(segment
		(start 401.13712 -126.042674)
		(end 396.402814 -126.042674)
		(width 0.1143)
		(layer "In4.Cu")
		(net "PE_PCH_SPRV_RX_C_DN")
	)
	(segment
		(start 477.011746 -64.126618)
		(end 477.011746 -64.360044)
		(width 0.1143)
		(layer "In4.Cu")
		(net "PE_PCH_SPRV_RX_C_DN")
	)
	(segment
		(start 475.817184 -65.320926)
		(end 475.574868 -65.563496)
		(width 0.1143)
		(layer "In4.Cu")
		(net "PE_PCH_SPRV_RX_C_DN")
	)
	(segment
		(start 401.746974 -126.652528)
		(end 401.13712 -126.042674)
		(width 0.1143)
		(layer "In4.Cu")
		(net "PE_PCH_SPRV_RX_C_DN")
	)
	(segment
		(start 395.386814 -126.042674)
		(end 395.221714 -125.877574)
		(width 0.1143)
		(layer "In4.Cu")
		(net "PE_PCH_SPRV_RX_C_DN")
	)
	(segment
		(start 417.83 -117.710712)
		(end 417.83 -121.328942)
		(width 0.1143)
		(layer "In4.Cu")
		(net "PE_PCH_SPRV_RX_C_DN")
	)
	(segment
		(start 395.894814 -125.877574)
		(end 395.729714 -126.042674)
		(width 0.1143)
		(layer "In4.Cu")
		(net "PE_PCH_SPRV_RX_C_DN")
	)
	(segment
		(start 416.352228 -122.624342)
		(end 415.44367 -123.5329)
		(width 0.1143)
		(layer "In4.Cu")
		(net "PE_PCH_SPRV_RX_C_DN")
	)
	(segment
		(start 396.402814 -126.042674)
		(end 396.237714 -125.877574)
		(width 0.1143)
		(layer "In4.Cu")
		(net "PE_PCH_SPRV_RX_C_DN")
	)
	(segment
		(start 355.71303 -129.580386)
		(end 355.71303 -129.812796)
		(width 0.254)
		(layer "F.Cu")
		(net "P3V3_STBY")
	)
	(segment
		(start 380.299214 -53.326538)
		(end 376.532902 -53.326538)
		(width 0.254)
		(layer "F.Cu")
		(net "P3V3_STBY")
	)
	(segment
		(start 479.524568 -147.0914)
		(end 478.186496 -147.0914)
		(width 0.254)
		(layer "F.Cu")
		(net "P3V3_STBY")
	)
	(segment
		(start 378.218192 -55.2831)
		(end 377.964192 -55.5371)
		(width 0.254)
		(layer "F.Cu")
		(net "P3V3_STBY")
	)
	(segment
		(start 375.944892 -70.295262)
		(end 375.545096 -70.695058)
		(width 0.254)
		(layer "F.Cu")
		(net "P3V3_STBY")
	)
	(segment
		(start -3.123692 -119.86006)
		(end -2.34696 -119.86006)
		(width 0.254)
		(layer "F.Cu")
		(net "P3V3_STBY")
	)
	(segment
		(start 179.959 -130.8735)
		(end 179.959 -130.175)
		(width 0.4064)
		(layer "F.Cu")
		(net "P3V3_STBY")
	)
	(segment
		(start 408.7495 -110.617)
		(end 408.7495 -109.855)
		(width 0.254)
		(layer "F.Cu")
		(net "P3V3_STBY")
	)
	(segment
		(start 441.404756 -146.477228)
		(end 441.404756 -147.621244)
		(width 0.254)
		(layer "F.Cu")
		(net "P3V3_STBY")
	)
	(segment
		(start 374.751854 -53.191918)
		(end 375.002806 -52.940966)
		(width 0.254)
		(layer "F.Cu")
		(net "P3V3_STBY")
	)
	(segment
		(start 414.8328 -112.8268)
		(end 414.8328 -113.2332)
		(width 0.254)
		(layer "F.Cu")
		(net "P3V3_STBY")
	)
	(segment
		(start 452.90994 -146.55546)
		(end 453.0598 -146.4056)
		(width 0.254)
		(layer "F.Cu")
		(net "P3V3_STBY")
	)
	(segment
		(start 398.8689 -87.4649)
		(end 398.8689 -86.868)
		(width 0.254)
		(layer "F.Cu")
		(net "P3V3_STBY")
	)
	(segment
		(start 392.53795 -115.05565)
		(end 392.1379 -115.4557)
		(width 0.254)
		(layer "F.Cu")
		(net "P3V3_STBY")
	)
	(segment
		(start 482.5873 -135.636)
		(end 482.6635 -135.5598)
		(width 0.254)
		(layer "F.Cu")
		(net "P3V3_STBY")
	)
	(segment
		(start 384.76555 -103.84536)
		(end 384.732784 -103.852726)
		(width 0.254)
		(layer "F.Cu")
		(net "P3V3_STBY")
	)
	(segment
		(start -3.14198 -119.868188)
		(end -3.13182 -119.868188)
		(width 0.254)
		(layer "F.Cu")
		(net "P3V3_STBY")
	)
	(segment
		(start -3.22326 -133.19506)
		(end -3.6576 -133.6294)
		(width 0.254)
		(layer "F.Cu")
		(net "P3V3_STBY")
	)
	(segment
		(start 401.169124 -80.72755)
		(end 401.169124 -81.352136)
		(width 0.254)
		(layer "F.Cu")
		(net "P3V3_STBY")
	)
	(segment
		(start 392.557 -88.632284)
		(end 392.557 -88.2015)
		(width 0.254)
		(layer "F.Cu")
		(net "P3V3_STBY")
	)
	(segment
		(start 0.762 -74.549)
		(end 0.381 -74.93)
		(width 0.254)
		(layer "F.Cu")
		(net "P3V3_STBY")
	)
	(segment
		(start 391.69975 -103.84536)
		(end 391.76706 -103.880666)
		(width 0.254)
		(layer "F.Cu")
		(net "P3V3_STBY")
	)
	(segment
		(start 13.438124 -4.426204)
		(end 13.438124 -5.164836)
		(width 0.254)
		(layer "F.Cu")
		(net "P3V3_STBY")
	)
	(segment
		(start 362.09224 -133.08457)
		(end 362.09224 -132.92836)
		(width 0.4064)
		(layer "F.Cu")
		(net "P3V3_STBY")
	)
	(segment
		(start 178.181 -66.548)
		(end 178.0032 -66.3702)
		(width 0.254)
		(layer "F.Cu")
		(net "P3V3_STBY")
	)
	(segment
		(start 472.7575 -138.43)
		(end 472.7575 -137.8585)
		(width 0.254)
		(layer "F.Cu")
		(net "P3V3_STBY")
	)
	(segment
		(start 438.124346 -148.525992)
		(end 438.70626 -149.107906)
		(width 0.254)
		(layer "F.Cu")
		(net "P3V3_STBY")
	)
	(segment
		(start 164.084 -70.14718)
		(end 164.457126 -70.520306)
		(width 0.254)
		(layer "F.Cu")
		(net "P3V3_STBY")
	)
	(segment
		(start 417.9316 -57.1119)
		(end 418.012118 -57.031382)
		(width 0.254)
		(layer "F.Cu")
		(net "P3V3_STBY")
	)
	(segment
		(start 22.991572 -98.762312)
		(end 22.4282 -98.19894)
		(width 0.4064)
		(layer "F.Cu")
		(net "P3V3_STBY")
	)
	(segment
		(start 488.3912 -50.6857)
		(end 489.6612 -50.6857)
		(width 0.254)
		(layer "F.Cu")
		(net "P3V3_STBY")
	)
	(segment
		(start 418.0078 -54.3687)
		(end 417.7665 -54.61)
		(width 0.254)
		(layer "F.Cu")
		(net "P3V3_STBY")
	)
	(segment
		(start 375.002806 -52.597812)
		(end 375.460768 -52.13985)
		(width 0.254)
		(layer "F.Cu")
		(net "P3V3_STBY")
	)
	(segment
		(start 369.545108 -78.294738)
		(end 369.944904 -77.894942)
		(width 0.254)
		(layer "F.Cu")
		(net "P3V3_STBY")
	)
	(segment
		(start 371.145308 -73.495154)
		(end 371.545104 -73.89495)
		(width 0.254)
		(layer "F.Cu")
		(net "P3V3_STBY")
	)
	(segment
		(start 172.101002 -92.835984)
		(end 172.5676 -93.302582)
		(width 0.254)
		(layer "F.Cu")
		(net "P3V3_STBY")
	)
	(segment
		(start 441.404756 -148.542756)
		(end 441.833 -148.971)
		(width 0.254)
		(layer "F.Cu")
		(net "P3V3_STBY")
	)
	(segment
		(start 355.161596 -132.471414)
		(end 355.161596 -130.13182)
		(width 0.254)
		(layer "F.Cu")
		(net "P3V3_STBY")
	)
	(segment
		(start 478.186496 -147.0914)
		(end 477.484948 -147.792948)
		(width 0.254)
		(layer "F.Cu")
		(net "P3V3_STBY")
	)
	(segment
		(start 366.344962 -67.894962)
		(end 366.745012 -68.295012)
		(width 0.254)
		(layer "F.Cu")
		(net "P3V3_STBY")
	)
	(segment
		(start 457.976732 -36.411154)
		(end 457.83119 -36.265612)
		(width 0.254)
		(layer "F.Cu")
		(net "P3V3_STBY")
	)
	(segment
		(start 472.948 -143.8275)
		(end 472.358974 -143.8275)
		(width 0.254)
		(layer "F.Cu")
		(net "P3V3_STBY")
	)
	(segment
		(start 347.622114 -22.184614)
		(end 347.3958 -21.9583)
		(width 0.381)
		(layer "F.Cu")
		(net "P3V3_STBY")
	)
	(segment
		(start 25.781 -76.581)
		(end 25.908 -76.454)
		(width 0.127)
		(layer "F.Cu")
		(net "P3V3_STBY")
	)
	(segment
		(start 400.304 -149.225)
		(end 399.923 -149.225)
		(width 0.4064)
		(layer "F.Cu")
		(net "P3V3_STBY")
	)
	(segment
		(start 433.1335 -11.4046)
		(end 433.6034 -11.4046)
		(width 0.254)
		(layer "F.Cu")
		(net "P3V3_STBY")
	)
	(segment
		(start 411.822138 -105.485438)
		(end 411.214062 -105.485438)
		(width 0.254)
		(layer "F.Cu")
		(net "P3V3_STBY")
	)
	(segment
		(start 94.362778 -88.775286)
		(end 93.791278 -88.775286)
		(width 0.381)
		(layer "F.Cu")
		(net "P3V3_STBY")
	)
	(segment
		(start 370.541804 -92.030804)
		(end 371.620796 -92.030804)
		(width 0.254)
		(layer "F.Cu")
		(net "P3V3_STBY")
	)
	(segment
		(start 419.859714 -81.620614)
		(end 418.084 -81.620614)
		(width 0.254)
		(layer "F.Cu")
		(net "P3V3_STBY")
	)
	(segment
		(start 24.738584 -30.861)
		(end 24.622506 -30.977078)
		(width 0.4064)
		(layer "F.Cu")
		(net "P3V3_STBY")
	)
	(segment
		(start 423.418 -13.6398)
		(end 423.418 -13.081)
		(width 0.254)
		(layer "F.Cu")
		(net "P3V3_STBY")
	)
	(segment
		(start 413.302958 -66.107818)
		(end 413.380682 -66.030094)
		(width 0.254)
		(layer "F.Cu")
		(net "P3V3_STBY")
	)
	(segment
		(start 486.9942 -138.4554)
		(end 486.4227 -139.0269)
		(width 0.254)
		(layer "F.Cu")
		(net "P3V3_STBY")
	)
	(segment
		(start 179.832 -6.7564)
		(end 179.959 -6.8834)
		(width 0.4064)
		(layer "F.Cu")
		(net "P3V3_STBY")
	)
	(segment
		(start 415.594546 -51.1302)
		(end 415.1249 -51.1302)
		(width 0.254)
		(layer "F.Cu")
		(net "P3V3_STBY")
	)
	(segment
		(start -3.6576 -133.6294)
		(end -3.7592 -133.6294)
		(width 0.254)
		(layer "F.Cu")
		(net "P3V3_STBY")
	)
	(segment
		(start 20.1168 -85.9536)
		(end 20.3835 -85.9536)
		(width 0.254)
		(layer "F.Cu")
		(net "P3V3_STBY")
	)
	(segment
		(start 376.532902 -53.326538)
		(end 376.088656 -53.770784)
		(width 0.254)
		(layer "F.Cu")
		(net "P3V3_STBY")
	)
	(segment
		(start 422.737534 -49.591976)
		(end 423.252646 -49.591976)
		(width 0.254)
		(layer "F.Cu")
		(net "P3V3_STBY")
	)
	(segment
		(start 418.084 -79.959454)
		(end 418.42944 -79.614014)
		(width 0.254)
		(layer "F.Cu")
		(net "P3V3_STBY")
	)
	(segment
		(start 343.281 -20.447)
		(end 343.281 -21.082)
		(width 0.254)
		(layer "F.Cu")
		(net "P3V3_STBY")
	)
	(segment
		(start 403.112986 -82.804)
		(end 403.112986 -81.548986)
		(width 0.254)
		(layer "F.Cu")
		(net "P3V3_STBY")
	)
	(segment
		(start 399.932144 -40.404542)
		(end 400.33194 -40.404542)
		(width 0.254)
		(layer "F.Cu")
		(net "P3V3_STBY")
	)
	(segment
		(start 414.126426 -113.2332)
		(end 414.075626 -113.284)
		(width 0.254)
		(layer "F.Cu")
		(net "P3V3_STBY")
	)
	(segment
		(start 412.02356 -109.728)
		(end 411.76448 -109.98708)
		(width 0.254)
		(layer "F.Cu")
		(net "P3V3_STBY")
	)
	(segment
		(start 477.6851 -140.8684)
		(end 477.4057 -140.589)
		(width 0.254)
		(layer "F.Cu")
		(net "P3V3_STBY")
	)
	(segment
		(start 408.457146 -50.06975)
		(end 408.488896 -50.038)
		(width 0.254)
		(layer "F.Cu")
		(net "P3V3_STBY")
	)
	(segment
		(start 371.945154 -72.695308)
		(end 372.34495 -73.095104)
		(width 0.254)
		(layer "F.Cu")
		(net "P3V3_STBY")
	)
	(segment
		(start 14.6812 -99.5934)
		(end 13.9954 -98.9076)
		(width 0.4064)
		(layer "F.Cu")
		(net "P3V3_STBY")
	)
	(segment
		(start 28.43784 -103.7844)
		(end 28.7528 -103.7844)
		(width 0.254)
		(layer "F.Cu")
		(net "P3V3_STBY")
	)
	(segment
		(start 489.43006 -18.568924)
		(end 488.3912 -19.607784)
		(width 0.254)
		(layer "F.Cu")
		(net "P3V3_STBY")
	)
	(segment
		(start 20.3835 -85.9536)
		(end 20.4597 -86.0298)
		(width 0.254)
		(layer "F.Cu")
		(net "P3V3_STBY")
	)
	(segment
		(start 455.062336 -38.555168)
		(end 455.242168 -38.735)
		(width 0.254)
		(layer "F.Cu")
		(net "P3V3_STBY")
	)
	(segment
		(start 491.2106 -123.75134)
		(end 492.08436 -123.75134)
		(width 0.254)
		(layer "F.Cu")
		(net "P3V3_STBY")
	)
	(segment
		(start 400.489674 -33.50514)
		(end 399.209514 -33.50514)
		(width 0.254)
		(layer "F.Cu")
		(net "P3V3_STBY")
	)
	(segment
		(start 407.7335 -22.5425)
		(end 408.043888 -22.232112)
		(width 0.254)
		(layer "F.Cu")
		(net "P3V3_STBY")
	)
	(segment
		(start 423.506646 -49.337976)
		(end 423.506646 -48.968152)
		(width 0.254)
		(layer "F.Cu")
		(net "P3V3_STBY")
	)
	(segment
		(start 19.812 -86.2584)
		(end 20.1168 -85.9536)
		(width 0.254)
		(layer "F.Cu")
		(net "P3V3_STBY")
	)
	(segment
		(start 413.890206 -38.934644)
		(end 413.490156 -39.334694)
		(width 0.254)
		(layer "F.Cu")
		(net "P3V3_STBY")
	)
	(segment
		(start 417.83 -56.4896)
		(end 417.83 -56.2229)
		(width 0.254)
		(layer "F.Cu")
		(net "P3V3_STBY")
	)
	(segment
		(start 17.5768 -43.6626)
		(end 17.0434 -43.1292)
		(width 0.254)
		(layer "F.Cu")
		(net "P3V3_STBY")
	)
	(segment
		(start 412.4325 -109.728)
		(end 412.02356 -109.728)
		(width 0.254)
		(layer "F.Cu")
		(net "P3V3_STBY")
	)
	(segment
		(start 377.76785 -52.13985)
		(end 378.134118 -52.506118)
		(width 0.254)
		(layer "F.Cu")
		(net "P3V3_STBY")
	)
	(segment
		(start 412.369 -101.7524)
		(end 412.5468 -101.9302)
		(width 0.254)
		(layer "F.Cu")
		(net "P3V3_STBY")
	)
	(segment
		(start 367.088928 -43.96232)
		(end 368.045746 -43.96232)
		(width 0.254)
		(layer "F.Cu")
		(net "P3V3_STBY")
	)
	(segment
		(start 185.481214 -61.976)
		(end 184.985914 -61.976)
		(width 0.254)
		(layer "F.Cu")
		(net "P3V3_STBY")
	)
	(segment
		(start 398.231106 -36.565586)
		(end 398.874996 -36.565586)
		(width 0.381)
		(layer "F.Cu")
		(net "P3V3_STBY")
	)
	(segment
		(start 401.13966 -153.78176)
		(end 401.13966 -152.66416)
		(width 0.4064)
		(layer "F.Cu")
		(net "P3V3_STBY")
	)
	(segment
		(start 488.3912 -19.607784)
		(end 488.3912 -22.1996)
		(width 0.254)
		(layer "F.Cu")
		(net "P3V3_STBY")
	)
	(segment
		(start 337.4517 -20.3581)
		(end 337.2612 -20.5486)
		(width 0.254)
		(layer "F.Cu")
		(net "P3V3_STBY")
	)
	(segment
		(start 411.49016 -32.534606)
		(end 411.09011 -32.134556)
		(width 0.254)
		(layer "F.Cu")
		(net "P3V3_STBY")
	)
	(segment
		(start 378.46 -87.3125)
		(end 377.698 -87.3125)
		(width 0.254)
		(layer "F.Cu")
		(net "P3V3_STBY")
	)
	(segment
		(start 442.5188 -140.640562)
		(end 443.187328 -141.30909)
		(width 0.254)
		(layer "F.Cu")
		(net "P3V3_STBY")
	)
	(segment
		(start 15.069058 -2.086864)
		(end 15.24889 -1.907032)
		(width 0.4064)
		(layer "F.Cu")
		(net "P3V3_STBY")
	)
	(segment
		(start 369.545108 -70.295262)
		(end 369.944904 -70.695058)
		(width 0.254)
		(layer "F.Cu")
		(net "P3V3_STBY")
	)
	(segment
		(start 378.744988 -80.29448)
		(end 379.144784 -79.894684)
		(width 0.254)
		(layer "F.Cu")
		(net "P3V3_STBY")
	)
	(segment
		(start 445.1985 -2.368042)
		(end 445.1985 -1.143)
		(width 0.254)
		(layer "F.Cu")
		(net "P3V3_STBY")
	)
	(segment
		(start 442.5188 -140.427202)
		(end 442.5188 -140.640562)
		(width 0.254)
		(layer "F.Cu")
		(net "P3V3_STBY")
	)
	(segment
		(start 400.66468 -149.58568)
		(end 400.304 -149.225)
		(width 0.4064)
		(layer "F.Cu")
		(net "P3V3_STBY")
	)
	(segment
		(start 411.745176 -110.074456)
		(end 411.52572 -109.855)
		(width 0.254)
		(layer "F.Cu")
		(net "P3V3_STBY")
	)
	(segment
		(start 479.268536 -43.717464)
		(end 479.1456 -43.8404)
		(width 0.254)
		(layer "F.Cu")
		(net "P3V3_STBY")
	)
	(segment
		(start 400.685 -81.83626)
		(end 400.685 -82.3595)
		(width 0.254)
		(layer "F.Cu")
		(net "P3V3_STBY")
	)
	(segment
		(start 353.387914 -133.514338)
		(end 354.096066 -132.806186)
		(width 0.254)
		(layer "F.Cu")
		(net "P3V3_STBY")
	)
	(segment
		(start 412.232602 -115.443)
		(end 412.4452 -115.230402)
		(width 0.254)
		(layer "F.Cu")
		(net "P3V3_STBY")
	)
	(segment
		(start 454.3298 -38.608)
		(end 454.331832 -38.608)
		(width 0.254)
		(layer "F.Cu")
		(net "P3V3_STBY")
	)
	(segment
		(start 432.6636 -11.4046)
		(end 433.1335 -11.4046)
		(width 0.254)
		(layer "F.Cu")
		(net "P3V3_STBY")
	)
	(segment
		(start 368.745262 -71.095108)
		(end 369.145058 -71.494904)
		(width 0.254)
		(layer "F.Cu")
		(net "P3V3_STBY")
	)
	(segment
		(start 419.64864 -111.125)
		(end 419.64864 -112.92586)
		(width 0.254)
		(layer "F.Cu")
		(net "P3V3_STBY")
	)
	(segment
		(start 378.134118 -52.506118)
		(end 381.706882 -52.506118)
		(width 0.254)
		(layer "F.Cu")
		(net "P3V3_STBY")
	)
	(segment
		(start 433.9336 -18.533872)
		(end 433.9336 -19.440144)
		(width 0.254)
		(layer "F.Cu")
		(net "P3V3_STBY")
	)
	(segment
		(start 464.581494 -26.557224)
		(end 465.593938 -26.557224)
		(width 0.254)
		(layer "F.Cu")
		(net "P3V3_STBY")
	)
	(segment
		(start 403.3901 -24.8539)
		(end 403.352 -24.892)
		(width 0.254)
		(layer "F.Cu")
		(net "P3V3_STBY")
	)
	(segment
		(start 2.4003 -114.554)
		(end 2.4003 -117.014498)
		(width 0.254)
		(layer "F.Cu")
		(net "P3V3_STBY")
	)
	(segment
		(start 465.074 4.1402)
		(end 465.2264 3.9878)
		(width 0.254)
		(layer "F.Cu")
		(net "P3V3_STBY")
	)
	(segment
		(start 418.012118 -56.671718)
		(end 417.83 -56.4896)
		(width 0.254)
		(layer "F.Cu")
		(net "P3V3_STBY")
	)
	(segment
		(start 174.5996 -104.4448)
		(end 173.5836 -104.4448)
		(width 0.254)
		(layer "F.Cu")
		(net "P3V3_STBY")
	)
	(segment
		(start 442.352176 -2.324354)
		(end 442.352176 -1.685036)
		(width 0.254)
		(layer "F.Cu")
		(net "P3V3_STBY")
	)
	(segment
		(start 402.73478 -80.48498)
		(end 402.73478 -80.41894)
		(width 0.254)
		(layer "F.Cu")
		(net "P3V3_STBY")
	)
	(segment
		(start 479.8822 -43.717464)
		(end 479.268536 -43.717464)
		(width 0.254)
		(layer "F.Cu")
		(net "P3V3_STBY")
	)
	(segment
		(start 393.827 -87.3125)
		(end 393.827 -85.217)
		(width 0.254)
		(layer "F.Cu")
		(net "P3V3_STBY")
	)
	(segment
		(start 406.273 -22.005798)
		(end 406.273 -21.463)
		(width 0.254)
		(layer "F.Cu")
		(net "P3V3_STBY")
	)
	(segment
		(start 479.806 -146.809968)
		(end 479.524568 -147.0914)
		(width 0.254)
		(layer "F.Cu")
		(net "P3V3_STBY")
	)
	(segment
		(start 373.544846 -72.695308)
		(end 373.14505 -73.095104)
		(width 0.254)
		(layer "F.Cu")
		(net "P3V3_STBY")
	)
	(segment
		(start 371.945154 -75.894692)
		(end 372.34495 -75.494896)
		(width 0.254)
		(layer "F.Cu")
		(net "P3V3_STBY")
	)
	(segment
		(start 483.001066 -49.205134)
		(end 482.8794 -49.3268)
		(width 0.254)
		(layer "F.Cu")
		(net "P3V3_STBY")
	)
	(segment
		(start 28.7528 -102.997)
		(end 28.459176 -102.997)
		(width 0.254)
		(layer "F.Cu")
		(net "P3V3_STBY")
	)
	(segment
		(start -0.446532 -74.102468)
		(end -0.446532 -68.270882)
		(width 0.254)
		(layer "F.Cu")
		(net "P3V3_STBY")
	)
	(segment
		(start 457.83119 -36.265612)
		(end 457.83119 -35.569906)
		(width 0.254)
		(layer "F.Cu")
		(net "P3V3_STBY")
	)
	(segment
		(start 473.075 -148.9075)
		(end 471.932 -148.9075)
		(width 0.254)
		(layer "F.Cu")
		(net "P3V3_STBY")
	)
	(segment
		(start 17.436592 -117.145054)
		(end 16.890492 -117.691154)
		(width 0.4064)
		(layer "F.Cu")
		(net "P3V3_STBY")
	)
	(segment
		(start 419.5445 -113.03)
		(end 419.5445 -113.4999)
		(width 0.254)
		(layer "F.Cu")
		(net "P3V3_STBY")
	)
	(segment
		(start 398.879568 -33.835086)
		(end 398.879568 -34.279586)
		(width 0.254)
		(layer "F.Cu")
		(net "P3V3_STBY")
	)
	(segment
		(start 371.620796 -92.030804)
		(end 371.6528 -91.9988)
		(width 0.254)
		(layer "F.Cu")
		(net "P3V3_STBY")
	)
	(segment
		(start 432.6509 -45.1739)
		(end 432.6509 -47.2821)
		(width 0.254)
		(layer "F.Cu")
		(net "P3V3_STBY")
	)
	(segment
		(start 398.8689 -86.868)
		(end 398.925796 -86.811104)
		(width 0.254)
		(layer "F.Cu")
		(net "P3V3_STBY")
	)
	(segment
		(start -4.694936 -132.66039)
		(end -4.694936 -131.593336)
		(width 0.254)
		(layer "F.Cu")
		(net "P3V3_STBY")
	)
	(segment
		(start 418.084 -81.620614)
		(end 418.084 -79.959454)
		(width 0.254)
		(layer "F.Cu")
		(net "P3V3_STBY")
	)
	(segment
		(start 435.3306 -22.3266)
		(end 435.3306 -22.281896)
		(width 0.254)
		(layer "F.Cu")
		(net "P3V3_STBY")
	)
	(segment
		(start 402.049996 -53.53558)
		(end 401.7518 -53.53558)
		(width 0.254)
		(layer "F.Cu")
		(net "P3V3_STBY")
	)
	(segment
		(start 427.427136 -132.981446)
		(end 427.00321 -133.405372)
		(width 0.254)
		(layer "F.Cu")
		(net "P3V3_STBY")
	)
	(segment
		(start 411.198568 -32.026098)
		(end 411.198568 -31.443168)
		(width 0.254)
		(layer "F.Cu")
		(net "P3V3_STBY")
	)
	(segment
		(start 17.423384 -41.5036)
		(end 17.0434 -41.5036)
		(width 0.254)
		(layer "F.Cu")
		(net "P3V3_STBY")
	)
	(segment
		(start 386.13715 -106.25455)
		(end 385.7371 -105.8545)
		(width 0.254)
		(layer "F.Cu")
		(net "P3V3_STBY")
	)
	(segment
		(start 0.762 -73.787)
		(end 0.762 -74.549)
		(width 0.254)
		(layer "F.Cu")
		(net "P3V3_STBY")
	)
	(segment
		(start 357.085138 -131.184904)
		(end 363.594396 -131.184904)
		(width 0.254)
		(layer "F.Cu")
		(net "P3V3_STBY")
	)
	(segment
		(start 488.6198 -44.717462)
		(end 489.612432 -44.717462)
		(width 0.254)
		(layer "F.Cu")
		(net "P3V3_STBY")
	)
	(segment
		(start 391.18032 -103.606346)
		(end 391.20445 -103.615236)
		(width 0.254)
		(layer "F.Cu")
		(net "P3V3_STBY")
	)
	(segment
		(start 24.622506 -30.977078)
		(end 23.508208 -30.977078)
		(width 0.4064)
		(layer "F.Cu")
		(net "P3V3_STBY")
	)
	(segment
		(start 180.2257 -77.9145)
		(end 180.2257 -77.31125)
		(width 0.4064)
		(layer "F.Cu")
		(net "P3V3_STBY")
	)
	(segment
		(start 394.589 -84.735162)
		(end 394.952728 -84.371434)
		(width 0.254)
		(layer "F.Cu")
		(net "P3V3_STBY")
	)
	(segment
		(start 464.727544 -6.77672)
		(end 464.478878 -7.025386)
		(width 0.254)
		(layer "F.Cu")
		(net "P3V3_STBY")
	)
	(segment
		(start 13.8176 -86.4362)
		(end 14.1224 -86.741)
		(width 0.4064)
		(layer "F.Cu")
		(net "P3V3_STBY")
	)
	(segment
		(start 16.764 -86.741)
		(end 16.764 -86.1314)
		(width 0.254)
		(layer "F.Cu")
		(net "P3V3_STBY")
	)
	(segment
		(start 409.356052 -115.521486)
		(end 408.728926 -115.521486)
		(width 0.254)
		(layer "F.Cu")
		(net "P3V3_STBY")
	)
	(segment
		(start 14.1224 -86.741)
		(end 14.478 -86.741)
		(width 0.4064)
		(layer "F.Cu")
		(net "P3V3_STBY")
	)
	(segment
		(start 394.17625 -113.28908)
		(end 394.67155 -113.519204)
		(width 0.254)
		(layer "F.Cu")
		(net "P3V3_STBY")
	)
	(segment
		(start 367.116106 -66.509392)
		(end 366.377728 -67.24777)
		(width 0.254)
		(layer "F.Cu")
		(net "P3V3_STBY")
	)
	(segment
		(start 418.4904 -113.03)
		(end 419.5445 -113.03)
		(width 0.254)
		(layer "F.Cu")
		(net "P3V3_STBY")
	)
	(segment
		(start 417.7665 -54.61)
		(end 416.814 -54.61)
		(width 0.254)
		(layer "F.Cu")
		(net "P3V3_STBY")
	)
	(segment
		(start 25.781 -76.8858)
		(end 25.781 -76.581)
		(width 0.127)
		(layer "F.Cu")
		(net "P3V3_STBY")
	)
	(segment
		(start 452.312024 -146.55546)
		(end 452.90994 -146.55546)
		(width 0.254)
		(layer "F.Cu")
		(net "P3V3_STBY")
	)
	(segment
		(start 26.2128 -85.13826)
		(end 26.2128 -84.7217)
		(width 0.254)
		(layer "F.Cu")
		(net "P3V3_STBY")
	)
	(segment
		(start 370.111274 -64.334898)
		(end 369.720368 -64.725804)
		(width 0.254)
		(layer "F.Cu")
		(net "P3V3_STBY")
	)
	(segment
		(start 338.836 -21.209)
		(end 338.2772 -21.7678)
		(width 0.254)
		(layer "F.Cu")
		(net "P3V3_STBY")
	)
	(segment
		(start 401.13966 -151.72436)
		(end 401.13966 -151.15286)
		(width 0.4064)
		(layer "F.Cu")
		(net "P3V3_STBY")
	)
	(segment
		(start 420.49827 -52.9082)
		(end 420.49827 -53.853588)
		(width 0.254)
		(layer "F.Cu")
		(net "P3V3_STBY")
	)
	(segment
		(start 477.8756 -49.488344)
		(end 478.142808 -49.755552)
		(width 0.508)
		(layer "F.Cu")
		(net "P3V3_STBY")
	)
	(segment
		(start 477.8756 -48.9839)
		(end 477.8756 -49.488344)
		(width 0.508)
		(layer "F.Cu")
		(net "P3V3_STBY")
	)
	(segment
		(start 418.012118 -57.031382)
		(end 418.012118 -56.671718)
		(width 0.254)
		(layer "F.Cu")
		(net "P3V3_STBY")
	)
	(segment
		(start 446.170812 -149.032722)
		(end 446.170812 -148.460968)
		(width 0.254)
		(layer "F.Cu")
		(net "P3V3_STBY")
	)
	(segment
		(start 407.9875 -104.252014)
		(end 408.051 -104.188514)
		(width 0.254)
		(layer "F.Cu")
		(net "P3V3_STBY")
	)
	(segment
		(start 172.681138 -102.279704)
		(end 172.6819 -102.280466)
		(width 0.254)
		(layer "F.Cu")
		(net "P3V3_STBY")
	)
	(segment
		(start 167.259 -71.5264)
		(end 167.259 -72.263)
		(width 0.254)
		(layer "F.Cu")
		(net "P3V3_STBY")
	)
	(segment
		(start 375.460768 -52.13985)
		(end 377.76785 -52.13985)
		(width 0.254)
		(layer "F.Cu")
		(net "P3V3_STBY")
	)
	(segment
		(start 454.258934 -1.793494)
		(end 454.258934 -2.062988)
		(width 0.254)
		(layer "F.Cu")
		(net "P3V3_STBY")
	)
	(segment
		(start 371.708934 -101.219)
		(end 371.925342 -101.002592)
		(width 0.254)
		(layer "F.Cu")
		(net "P3V3_STBY")
	)
	(segment
		(start 386.08 -86.808564)
		(end 386.274564 -86.614)
		(width 0.254)
		(layer "F.Cu")
		(net "P3V3_STBY")
	)
	(segment
		(start 375.944892 -78.294738)
		(end 375.545096 -77.894942)
		(width 0.254)
		(layer "F.Cu")
		(net "P3V3_STBY")
	)
	(segment
		(start 420.49827 -53.853588)
		(end 420.324026 -54.027832)
		(width 0.254)
		(layer "F.Cu")
		(net "P3V3_STBY")
	)
	(segment
		(start 416.814 -54.61)
		(end 416.56 -54.864)
		(width 0.254)
		(layer "F.Cu")
		(net "P3V3_STBY")
	)
	(segment
		(start 386.74675 -103.84536)
		(end 387.24205 -103.536496)
		(width 0.254)
		(layer "F.Cu")
		(net "P3V3_STBY")
	)
	(segment
		(start 411.4546 -115.443)
		(end 412.232602 -115.443)
		(width 0.254)
		(layer "F.Cu")
		(net "P3V3_STBY")
	)
	(segment
		(start 402.303996 -55.307484)
		(end 402.303996 -53.78958)
		(width 0.254)
		(layer "F.Cu")
		(net "P3V3_STBY")
	)
	(segment
		(start 23.508208 -30.977078)
		(end 23.345902 -30.814772)
		(width 0.4064)
		(layer "F.Cu")
		(net "P3V3_STBY")
	)
	(segment
		(start 408.025854 -63.373)
		(end 407.8351 -63.373)
		(width 0.254)
		(layer "F.Cu")
		(net "P3V3_STBY")
	)
	(segment
		(start 444.1825 -146.5834)
		(end 444.1825 -147.193)
		(width 0.254)
		(layer "F.Cu")
		(net "P3V3_STBY")
	)
	(segment
		(start 377.964192 -55.5371)
		(end 377.879864 -55.5371)
		(width 0.254)
		(layer "F.Cu")
		(net "P3V3_STBY")
	)
	(segment
		(start 355.161596 -130.13182)
		(end 355.71303 -129.580386)
		(width 0.254)
		(layer "F.Cu")
		(net "P3V3_STBY")
	)
	(segment
		(start 20.955 -86.7156)
		(end 20.4724 -86.7156)
		(width 0.254)
		(layer "F.Cu")
		(net "P3V3_STBY")
	)
	(segment
		(start 407.470864 -51.308)
		(end 408.457146 -50.321718)
		(width 0.254)
		(layer "F.Cu")
		(net "P3V3_STBY")
	)
	(segment
		(start 411.214062 -105.485438)
		(end 411.1625 -105.537)
		(width 0.254)
		(layer "F.Cu")
		(net "P3V3_STBY")
	)
	(segment
		(start 491.49 -39.0144)
		(end 492.2266 -39.0144)
		(width 0.4064)
		(layer "F.Cu")
		(net "P3V3_STBY")
	)
	(segment
		(start 408.457146 -50.321718)
		(end 408.457146 -50.06975)
		(width 0.254)
		(layer "F.Cu")
		(net "P3V3_STBY")
	)
	(segment
		(start 376.088656 -53.770784)
		(end 375.17832 -53.770784)
		(width 0.254)
		(layer "F.Cu")
		(net "P3V3_STBY")
	)
	(segment
		(start 433.646072 -19.727672)
		(end 433.084986 -19.727672)
		(width 0.254)
		(layer "F.Cu")
		(net "P3V3_STBY")
	)
	(segment
		(start 400.489674 -33.50514)
		(end 400.489674 -34.069274)
		(width 0.254)
		(layer "F.Cu")
		(net "P3V3_STBY")
	)
	(segment
		(start 438.70626 -149.107906)
		(end 438.70626 -149.51456)
		(width 0.254)
		(layer "F.Cu")
		(net "P3V3_STBY")
	)
	(segment
		(start 383.86512 -49.83988)
		(end 385.23926 -49.83988)
		(width 0.254)
		(layer "F.Cu")
		(net "P3V3_STBY")
	)
	(segment
		(start 2.032 -68.056506)
		(end 2.032 -69.088)
		(width 0.254)
		(layer "F.Cu")
		(net "P3V3_STBY")
	)
	(segment
		(start 13.843 -89.281)
		(end 13.3096 -89.281)
		(width 0.254)
		(layer "F.Cu")
		(net "P3V3_STBY")
	)
	(segment
		(start -4.694936 -131.593336)
		(end -4.3688 -131.2672)
		(width 0.254)
		(layer "F.Cu")
		(net "P3V3_STBY")
	)
	(segment
		(start 368.3889 -93.9673)
		(end 368.3889 -92.4306)
		(width 0.254)
		(layer "F.Cu")
		(net "P3V3_STBY")
	)
	(segment
		(start 16.764 -86.1314)
		(end 16.7132 -86.0806)
		(width 0.254)
		(layer "F.Cu")
		(net "P3V3_STBY")
	)
	(segment
		(start 17.524984 -41.402)
		(end 17.423384 -41.5036)
		(width 0.254)
		(layer "F.Cu")
		(net "P3V3_STBY")
	)
	(segment
		(start 400.7358 -39.459662)
		(end 400.81581 -39.459662)
		(width 0.254)
		(layer "F.Cu")
		(net "P3V3_STBY")
	)
	(segment
		(start 180.63464 -78.32344)
		(end 180.2257 -77.9145)
		(width 0.4064)
		(layer "F.Cu")
		(net "P3V3_STBY")
	)
	(segment
		(start 411.1752 -115.1636)
		(end 411.4546 -115.443)
		(width 0.254)
		(layer "F.Cu")
		(net "P3V3_STBY")
	)
	(segment
		(start 490.728 -146.939)
		(end 491.109 -147.32)
		(width 0.254)
		(layer "F.Cu")
		(net "P3V3_STBY")
	)
	(segment
		(start 413.3215 -113.411)
		(end 413.948626 -113.411)
		(width 0.254)
		(layer "F.Cu")
		(net "P3V3_STBY")
	)
	(segment
		(start 392.97356 -104.23906)
		(end 392.55827 -104.65435)
		(width 0.254)
		(layer "F.Cu")
		(net "P3V3_STBY")
	)
	(segment
		(start 377.805696 -19.139662)
		(end 376.879866 -19.139662)
		(width 0.254)
		(layer "F.Cu")
		(net "P3V3_STBY")
	)
	(segment
		(start 433.9336 -11.0744)
		(end 434.6194 -11.0744)
		(width 0.254)
		(layer "F.Cu")
		(net "P3V3_STBY")
	)
	(segment
		(start 17.0434 -43.1292)
		(end 17.0434 -41.5036)
		(width 0.254)
		(layer "F.Cu")
		(net "P3V3_STBY")
	)
	(segment
		(start 489.612432 -44.717462)
		(end 489.767372 -44.562522)
		(width 0.254)
		(layer "F.Cu")
		(net "P3V3_STBY")
	)
	(segment
		(start 380.74219 -37.895022)
		(end 380.646686 -37.990526)
		(width 0.254)
		(layer "F.Cu")
		(net "P3V3_STBY")
	)
	(segment
		(start 399.923 -149.225)
		(end 399.159222 -149.225)
		(width 0.4064)
		(layer "F.Cu")
		(net "P3V3_STBY")
	)
	(segment
		(start 404.9141 -20.9677)
		(end 404.495 -21.3868)
		(width 0.254)
		(layer "F.Cu")
		(net "P3V3_STBY")
	)
	(segment
		(start 423.86758 -118.12524)
		(end 423.86758 -117.864636)
		(width 0.254)
		(layer "F.Cu")
		(net "P3V3_STBY")
	)
	(segment
		(start 395.351 -84.769706)
		(end 395.351 -85.0265)
		(width 0.254)
		(layer "F.Cu")
		(net "P3V3_STBY")
	)
	(segment
		(start 461.098392 -36.432998)
		(end 461.098392 -37.067998)
		(width 0.4064)
		(layer "F.Cu")
		(net "P3V3_STBY")
	)
	(segment
		(start 454.331832 -38.608)
		(end 454.384664 -38.555168)
		(width 0.254)
		(layer "F.Cu")
		(net "P3V3_STBY")
	)
	(segment
		(start 416.01898 -50.184558)
		(end 416.01898 -50.705766)
		(width 0.254)
		(layer "F.Cu")
		(net "P3V3_STBY")
	)
	(segment
		(start 422.402 -20.7264)
		(end 422.402 -21.2344)
		(width 0.254)
		(layer "F.Cu")
		(net "P3V3_STBY")
	)
	(segment
		(start 416.56 -55.118)
		(end 416.56 -55.7784)
		(width 0.254)
		(layer "F.Cu")
		(net "P3V3_STBY")
	)
	(segment
		(start 411.780228 -108.481114)
		(end 411.295342 -108.966)
		(width 0.254)
		(layer "F.Cu")
		(net "P3V3_STBY")
	)
	(segment
		(start 419.64864 -112.92586)
		(end 419.5445 -113.03)
		(width 0.254)
		(layer "F.Cu")
		(net "P3V3_STBY")
	)
	(segment
		(start 362.9406 -132.4356)
		(end 362.9406 -133.0706)
		(width 0.4064)
		(layer "F.Cu")
		(net "P3V3_STBY")
	)
	(segment
		(start 172.6819 -102.280466)
		(end 172.6819 -103.358188)
		(width 0.254)
		(layer "F.Cu")
		(net "P3V3_STBY")
	)
	(segment
		(start 422.402 -21.2344)
		(end 422.5798 -21.4122)
		(width 0.254)
		(layer "F.Cu")
		(net "P3V3_STBY")
	)
	(segment
		(start 406.107646 -22.171152)
		(end 406.273 -22.005798)
		(width 0.254)
		(layer "F.Cu")
		(net "P3V3_STBY")
	)
	(segment
		(start 13.438124 -5.164836)
		(end 13.405104 -5.197856)
		(width 0.254)
		(layer "F.Cu")
		(net "P3V3_STBY")
	)
	(segment
		(start 16.890492 -117.691154)
		(end 16.890492 -118.838472)
		(width 0.4064)
		(layer "F.Cu")
		(net "P3V3_STBY")
	)
	(segment
		(start 20.4597 -86.0298)
		(end 20.6121 -86.0298)
		(width 0.254)
		(layer "F.Cu")
		(net "P3V3_STBY")
	)
	(segment
		(start 400.33194 -40.404542)
		(end 400.7358 -40.000682)
		(width 0.254)
		(layer "F.Cu")
		(net "P3V3_STBY")
	)
	(segment
		(start 461.229202 -0.78613)
		(end 461.229202 -0.771144)
		(width 0.254)
		(layer "F.Cu")
		(net "P3V3_STBY")
	)
	(segment
		(start 373.544846 -75.894692)
		(end 373.14505 -75.494896)
		(width 0.254)
		(layer "F.Cu")
		(net "P3V3_STBY")
	)
	(segment
		(start 393.186158 -104.70388)
		(end 393.681204 -104.473248)
		(width 0.254)
		(layer "F.Cu")
		(net "P3V3_STBY")
	)
	(segment
		(start 413.948626 -113.411)
		(end 414.075626 -113.284)
		(width 0.254)
		(layer "F.Cu")
		(net "P3V3_STBY")
	)
	(segment
		(start 380.646686 -37.990526)
		(end 380.646686 -38.263068)
		(width 0.254)
		(layer "F.Cu")
		(net "P3V3_STBY")
	)
	(segment
		(start 454.384664 -38.555168)
		(end 455.062336 -38.555168)
		(width 0.254)
		(layer "F.Cu")
		(net "P3V3_STBY")
	)
	(segment
		(start 368.14887 -129.286)
		(end 367.462308 -129.972562)
		(width 0.254)
		(layer "F.Cu")
		(net "P3V3_STBY")
	)
	(segment
		(start 482.03104 -51.36134)
		(end 482.03104 -54.264814)
		(width 0.254)
		(layer "F.Cu")
		(net "P3V3_STBY")
	)
	(segment
		(start 411.0355 -112.395)
		(end 411.0355 -111.633)
		(width 0.254)
		(layer "F.Cu")
		(net "P3V3_STBY")
	)
	(segment
		(start 401.8915 -38.383972)
		(end 401.8915 -37.9984)
		(width 0.254)
		(layer "F.Cu")
		(net "P3V3_STBY")
	)
	(segment
		(start 383.23901 -50.97399)
		(end 383.23901 -50.46599)
		(width 0.254)
		(layer "F.Cu")
		(net "P3V3_STBY")
	)
	(segment
		(start 368.3889 -92.4306)
		(end 368.1349 -92.1766)
		(width 0.254)
		(layer "F.Cu")
		(net "P3V3_STBY")
	)
	(segment
		(start 423.2529 -117.249956)
		(end 423.2529 -114.552222)
		(width 0.254)
		(layer "F.Cu")
		(net "P3V3_STBY")
	)
	(segment
		(start 347.622114 -22.5933)
		(end 347.622114 -22.184614)
		(width 0.381)
		(layer "F.Cu")
		(net "P3V3_STBY")
	)
	(segment
		(start 492.08436 -123.75134)
		(end 492.3282 -123.5075)
		(width 0.254)
		(layer "F.Cu")
		(net "P3V3_STBY")
	)
	(segment
		(start 365.917988 -133.508496)
		(end 365.917988 -134.102094)
		(width 0.254)
		(layer "F.Cu")
		(net "P3V3_STBY")
	)
	(segment
		(start 462.683098 -25.533096)
		(end 463.557366 -25.533096)
		(width 0.254)
		(layer "F.Cu")
		(net "P3V3_STBY")
	)
	(segment
		(start 25.4 -81.026)
		(end 26.289 -81.026)
		(width 0.254)
		(layer "F.Cu")
		(net "P3V3_STBY")
	)
	(segment
		(start 391.795 -88.625172)
		(end 391.795 -88.2015)
		(width 0.254)
		(layer "F.Cu")
		(net "P3V3_STBY")
	)
	(segment
		(start 367.4872 -92.1766)
		(end 366.2172 -92.1766)
		(width 0.254)
		(layer "F.Cu")
		(net "P3V3_STBY")
	)
	(segment
		(start 20.3327 -86.6521)
		(end 20.3073 -86.6267)
		(width 0.254)
		(layer "F.Cu")
		(net "P3V3_STBY")
	)
	(segment
		(start 411.198568 -31.443168)
		(end 411.09011 -31.33471)
		(width 0.254)
		(layer "F.Cu")
		(net "P3V3_STBY")
	)
	(segment
		(start 394.589 -85.0265)
		(end 394.589 -84.735162)
		(width 0.254)
		(layer "F.Cu")
		(net "P3V3_STBY")
	)
	(segment
		(start 354.826824 -132.806186)
		(end 355.161596 -132.471414)
		(width 0.254)
		(layer "F.Cu")
		(net "P3V3_STBY")
	)
	(segment
		(start 370.4463 -91.9353)
		(end 370.541804 -92.030804)
		(width 0.254)
		(layer "F.Cu")
		(net "P3V3_STBY")
	)
	(segment
		(start 18.071592 -117.145054)
		(end 17.436592 -117.145054)
		(width 0.4064)
		(layer "F.Cu")
		(net "P3V3_STBY")
	)
	(segment
		(start 400.66468 -150.67788)
		(end 400.66468 -149.58568)
		(width 0.4064)
		(layer "F.Cu")
		(net "P3V3_STBY")
	)
	(segment
		(start 434.47335 -14.224)
		(end 434.594 -14.10335)
		(width 0.254)
		(layer "F.Cu")
		(net "P3V3_STBY")
	)
	(segment
		(start 369.8494 -129.286)
		(end 368.14887 -129.286)
		(width 0.254)
		(layer "F.Cu")
		(net "P3V3_STBY")
	)
	(segment
		(start 2.4003 -117.014498)
		(end 2.63271 -117.246908)
		(width 0.254)
		(layer "F.Cu")
		(net "P3V3_STBY")
	)
	(segment
		(start 411.090364 -33.734756)
		(end 411.49016 -34.134552)
		(width 0.254)
		(layer "F.Cu")
		(net "P3V3_STBY")
	)
	(segment
		(start 393.1412 1.5748)
		(end 392.577828 1.5748)
		(width 0.254)
		(layer "F.Cu")
		(net "P3V3_STBY")
	)
	(segment
		(start 400.7358 -40.000682)
		(end 400.7358 -39.459662)
		(width 0.254)
		(layer "F.Cu")
		(net "P3V3_STBY")
	)
	(segment
		(start 337.947 -19.7612)
		(end 337.7057 -19.7612)
		(width 0.254)
		(layer "F.Cu")
		(net "P3V3_STBY")
	)
	(segment
		(start 380.646686 -38.263068)
		(end 379.993652 -38.916102)
		(width 0.254)
		(layer "F.Cu")
		(net "P3V3_STBY")
	)
	(segment
		(start 389.22325 -103.615236)
		(end 388.72795 -103.84536)
		(width 0.254)
		(layer "F.Cu")
		(net "P3V3_STBY")
	)
	(segment
		(start 406.1968 -51.308)
		(end 407.470864 -51.308)
		(width 0.254)
		(layer "F.Cu")
		(net "P3V3_STBY")
	)
	(segment
		(start 411.0355 -111.633)
		(end 411.48 -111.633)
		(width 0.254)
		(layer "F.Cu")
		(net "P3V3_STBY")
	)
	(segment
		(start 378.744988 -80.294988)
		(end 378.744988 -80.29448)
		(width 0.254)
		(layer "F.Cu")
		(net "P3V3_STBY")
	)
	(segment
		(start 376.744738 -77.494892)
		(end 376.344942 -77.095096)
		(width 0.254)
		(layer "F.Cu")
		(net "P3V3_STBY")
	)
	(segment
		(start 478.282 -140.8684)
		(end 477.6851 -140.8684)
		(width 0.254)
		(layer "F.Cu")
		(net "P3V3_STBY")
	)
	(segment
		(start 25.654 -30.861)
		(end 24.738584 -30.861)
		(width 0.4064)
		(layer "F.Cu")
		(net "P3V3_STBY")
	)
	(segment
		(start 472.358974 -143.8275)
		(end 472.104974 -144.0815)
		(width 0.254)
		(layer "F.Cu")
		(net "P3V3_STBY")
	)
	(segment
		(start 20.3073 -86.6267)
		(end 19.812 -86.6267)
		(width 0.254)
		(layer "F.Cu")
		(net "P3V3_STBY")
	)
	(segment
		(start 423.506646 -48.968152)
		(end 422.744646 -48.968152)
		(width 0.254)
		(layer "F.Cu")
		(net "P3V3_STBY")
	)
	(segment
		(start -0.60706 -132.54736)
		(end -0.60706 -133.1722)
		(width 0.254)
		(layer "F.Cu")
		(net "P3V3_STBY")
	)
	(segment
		(start 407.7335 -22.987)
		(end 407.7335 -22.5425)
		(width 0.254)
		(layer "F.Cu")
		(net "P3V3_STBY")
	)
	(segment
		(start 363.249718 -72.133206)
		(end 363.249718 -71.623682)
		(width 0.254)
		(layer "F.Cu")
		(net "P3V3_STBY")
	)
	(segment
		(start 362.6866 -132.334)
		(end 362.839 -132.334)
		(width 0.4064)
		(layer "F.Cu")
		(net "P3V3_STBY")
	)
	(segment
		(start 401.2946 -153.9367)
		(end 401.13966 -153.78176)
		(width 0.4064)
		(layer "F.Cu")
		(net "P3V3_STBY")
	)
	(segment
		(start 406.019 -20.9677)
		(end 404.9141 -20.9677)
		(width 0.254)
		(layer "F.Cu")
		(net "P3V3_STBY")
	)
	(segment
		(start 425.503848 -48.968152)
		(end 425.919646 -48.968152)
		(width 0.254)
		(layer "F.Cu")
		(net "P3V3_STBY")
	)
	(segment
		(start 444.1825 -1.143)
		(end 445.1985 -1.143)
		(width 0.254)
		(layer "F.Cu")
		(net "P3V3_STBY")
	)
	(segment
		(start 436.0037 -21.1455)
		(end 436.499 -21.1455)
		(width 0.254)
		(layer "F.Cu")
		(net "P3V3_STBY")
	)
	(segment
		(start 362.839 -132.334)
		(end 362.9406 -132.4356)
		(width 0.4064)
		(layer "F.Cu")
		(net "P3V3_STBY")
	)
	(segment
		(start -3.889248 -120.35536)
		(end -4.155948 -120.62206)
		(width 0.254)
		(layer "F.Cu")
		(net "P3V3_STBY")
	)
	(segment
		(start 407.344626 -104.648)
		(end 407.9875 -104.648)
		(width 0.254)
		(layer "F.Cu")
		(net "P3V3_STBY")
	)
	(segment
		(start 186.944 -76.9493)
		(end 186.944 -77.0636)
		(width 0.4064)
		(layer "F.Cu")
		(net "P3V3_STBY")
	)
	(segment
		(start 434.6194 -11.0744)
		(end 435.0004 -11.4554)
		(width 0.254)
		(layer "F.Cu")
		(net "P3V3_STBY")
	)
	(segment
		(start 418.42944 -79.614014)
		(end 418.973 -79.614014)
		(width 0.254)
		(layer "F.Cu")
		(net "P3V3_STBY")
	)
	(segment
		(start 423.650664 -13.872464)
		(end 423.418 -13.6398)
		(width 0.254)
		(layer "F.Cu")
		(net "P3V3_STBY")
	)
	(segment
		(start 416.01898 -50.705766)
		(end 415.594546 -51.1302)
		(width 0.254)
		(layer "F.Cu")
		(net "P3V3_STBY")
	)
	(segment
		(start 394.952728 -84.371434)
		(end 395.351 -84.769706)
		(width 0.254)
		(layer "F.Cu")
		(net "P3V3_STBY")
	)
	(segment
		(start 423.2529 -114.552222)
		(end 422.2115 -113.510822)
		(width 0.254)
		(layer "F.Cu")
		(net "P3V3_STBY")
	)
	(segment
		(start 368.554 -94.742)
		(end 368.0587 -94.742)
		(width 0.254)
		(layer "F.Cu")
		(net "P3V3_STBY")
	)
	(segment
		(start 411.988 -111.633)
		(end 411.734 -111.887)
		(width 0.254)
		(layer "F.Cu")
		(net "P3V3_STBY")
	)
	(segment
		(start 411.0355 -108.204)
		(end 411.503114 -108.204)
		(width 0.254)
		(layer "F.Cu")
		(net "P3V3_STBY")
	)
	(segment
		(start 432.2826 -11.7856)
		(end 432.6636 -11.4046)
		(width 0.254)
		(layer "F.Cu")
		(net "P3V3_STBY")
	)
	(segment
		(start 403.112986 -80.863186)
		(end 402.73478 -80.48498)
		(width 0.254)
		(layer "F.Cu")
		(net "P3V3_STBY")
	)
	(segment
		(start 26.289 -77.3938)
		(end 25.781 -76.8858)
		(width 0.127)
		(layer "F.Cu")
		(net "P3V3_STBY")
	)
	(segment
		(start 416.56 -54.864)
		(end 416.56 -55.118)
		(width 0.254)
		(layer "F.Cu")
		(net "P3V3_STBY")
	)
	(segment
		(start 371.145308 -72.695308)
		(end 371.545104 -73.095104)
		(width 0.254)
		(layer "F.Cu")
		(net "P3V3_STBY")
	)
	(segment
		(start 403.352 -24.892)
		(end 402.717 -24.892)
		(width 0.254)
		(layer "F.Cu")
		(net "P3V3_STBY")
	)
	(segment
		(start 407.344626 -104.648)
		(end 406.7302 -104.648)
		(width 0.254)
		(layer "F.Cu")
		(net "P3V3_STBY")
	)
	(segment
		(start 15.124684 -4.632452)
		(end 14.5923 -5.164836)
		(width 0.254)
		(layer "F.Cu")
		(net "P3V3_STBY")
	)
	(segment
		(start 489.6612 -50.6857)
		(end 489.712 -50.6349)
		(width 0.254)
		(layer "F.Cu")
		(net "P3V3_STBY")
	)
	(segment
		(start 378.755656 -21.062442)
		(end 378.755656 -20.089622)
		(width 0.254)
		(layer "F.Cu")
		(net "P3V3_STBY")
	)
	(segment
		(start 477.139 -140.589)
		(end 477.139 -141.1478)
		(width 0.254)
		(layer "F.Cu")
		(net "P3V3_STBY")
	)
	(segment
		(start 490.453934 -146.939)
		(end 490.728 -146.939)
		(width 0.254)
		(layer "F.Cu")
		(net "P3V3_STBY")
	)
	(segment
		(start 368.745262 -77.494892)
		(end 369.145058 -77.095096)
		(width 0.254)
		(layer "F.Cu")
		(net "P3V3_STBY")
	)
	(segment
		(start 417.425378 -81.620614)
		(end 418.084 -81.620614)
		(width 0.254)
		(layer "F.Cu")
		(net "P3V3_STBY")
	)
	(segment
		(start 368.64671 -43.361356)
		(end 368.64671 -43.260772)
		(width 0.254)
		(layer "F.Cu")
		(net "P3V3_STBY")
	)
	(segment
		(start 479.806 -146.2278)
		(end 479.806 -146.809968)
		(width 0.254)
		(layer "F.Cu")
		(net "P3V3_STBY")
	)
	(segment
		(start 20.4724 -86.7156)
		(end 20.4089 -86.6521)
		(width 0.254)
		(layer "F.Cu")
		(net "P3V3_STBY")
	)
	(segment
		(start 408.673046 -107.434634)
		(end 409.300172 -107.434634)
		(width 0.254)
		(layer "F.Cu")
		(net "P3V3_STBY")
	)
	(segment
		(start 15.596108 -44.678092)
		(end 15.596108 -45.154342)
		(width 0.254)
		(layer "F.Cu")
		(net "P3V3_STBY")
	)
	(segment
		(start 366.745012 -80.294988)
		(end 367.164112 -80.714088)
		(width 0.254)
		(layer "F.Cu")
		(net "P3V3_STBY")
	)
	(segment
		(start 414.5788 -112.5728)
		(end 414.8328 -112.8268)
		(width 0.254)
		(layer "F.Cu")
		(net "P3V3_STBY")
	)
	(segment
		(start 407.9875 -104.648)
		(end 407.9875 -104.252014)
		(width 0.254)
		(layer "F.Cu")
		(net "P3V3_STBY")
	)
	(segment
		(start 355.494844 -129.3622)
		(end 355.71303 -129.580386)
		(width 0.254)
		(layer "F.Cu")
		(net "P3V3_STBY")
	)
	(segment
		(start 463.306922 3.434334)
		(end 464.012788 4.1402)
		(width 0.254)
		(layer "F.Cu")
		(net "P3V3_STBY")
	)
	(segment
		(start 377.09348 -86.79688)
		(end 377.6091 -87.3125)
		(width 0.254)
		(layer "F.Cu")
		(net "P3V3_STBY")
	)
	(segment
		(start 461.137 -0.878332)
		(end 461.229202 -0.78613)
		(width 0.254)
		(layer "F.Cu")
		(net "P3V3_STBY")
	)
	(segment
		(start 441.404756 -147.621244)
		(end 441.404756 -148.542756)
		(width 0.254)
		(layer "F.Cu")
		(net "P3V3_STBY")
	)
	(segment
		(start -0.000508 -67.824858)
		(end 1.800352 -67.824858)
		(width 0.254)
		(layer "F.Cu")
		(net "P3V3_STBY")
	)
	(segment
		(start 411.48 -111.633)
		(end 411.734 -111.887)
		(width 0.254)
		(layer "F.Cu")
		(net "P3V3_STBY")
	)
	(segment
		(start 353.387914 -134.222744)
		(end 353.387914 -133.514338)
		(width 0.254)
		(layer "F.Cu")
		(net "P3V3_STBY")
	)
	(segment
		(start 477.139 -140.589)
		(end 477.139 -140.208)
		(width 0.254)
		(layer "F.Cu")
		(net "P3V3_STBY")
	)
	(segment
		(start 443.187328 -141.30909)
		(end 444.492634 -141.30909)
		(width 0.254)
		(layer "F.Cu")
		(net "P3V3_STBY")
	)
	(segment
		(start 18.5166 -41.402)
		(end 17.524984 -41.402)
		(width 0.254)
		(layer "F.Cu")
		(net "P3V3_STBY")
	)
	(segment
		(start 455.6125 -30.48)
		(end 455.6125 -30.847284)
		(width 0.254)
		(layer "F.Cu")
		(net "P3V3_STBY")
	)
	(segment
		(start -0.60706 -133.1722)
		(end -0.61722 -133.18236)
		(width 0.254)
		(layer "F.Cu")
		(net "P3V3_STBY")
	)
	(segment
		(start 390.70915 -103.84536)
		(end 390.71804 -103.82123)
		(width 0.254)
		(layer "F.Cu")
		(net "P3V3_STBY")
	)
	(segment
		(start -1.44526 -118.95836)
		(end -1.44526 -118.83136)
		(width 0.254)
		(layer "F.Cu")
		(net "P3V3_STBY")
	)
	(segment
		(start 489.0008 -149.8854)
		(end 488.570016 -150.316184)
		(width 0.254)
		(layer "F.Cu")
		(net "P3V3_STBY")
	)
	(segment
		(start 421.627046 -49.131474)
		(end 421.152828 -49.605692)
		(width 0.254)
		(layer "F.Cu")
		(net "P3V3_STBY")
	)
	(segment
		(start 337.45424 -21.7678)
		(end 336.9564 -21.26996)
		(width 0.254)
		(layer "F.Cu")
		(net "P3V3_STBY")
	)
	(segment
		(start -3.60426 -120.35536)
		(end -3.60426 -120.330468)
		(width 0.254)
		(layer "F.Cu")
		(net "P3V3_STBY")
	)
	(segment
		(start 28.459176 -102.997)
		(end 28.054808 -103.401368)
		(width 0.254)
		(layer "F.Cu")
		(net "P3V3_STBY")
	)
	(segment
		(start 411.52572 -109.855)
		(end 411.0355 -109.855)
		(width 0.254)
		(layer "F.Cu")
		(net "P3V3_STBY")
	)
	(segment
		(start 394.0175 -85.0265)
		(end 394.589 -85.0265)
		(width 0.254)
		(layer "F.Cu")
		(net "P3V3_STBY")
	)
	(segment
		(start 16.890492 -118.838472)
		(end 16.768064 -118.9609)
		(width 0.4064)
		(layer "F.Cu")
		(net "P3V3_STBY")
	)
	(segment
		(start 446.532 -15.621)
		(end 446.532 -14.732)
		(width 0.254)
		(layer "F.Cu")
		(net "P3V3_STBY")
	)
	(segment
		(start 488.001056 -38.862)
		(end 488.001056 -39.5986)
		(width 0.3048)
		(layer "F.Cu")
		(net "P3V3_STBY")
	)
	(segment
		(start 440.055 -140.716)
		(end 440.055 -141.351)
		(width 0.254)
		(layer "F.Cu")
		(net "P3V3_STBY")
	)
	(segment
		(start 389.71855 -103.84536)
		(end 390.21385 -103.615236)
		(width 0.254)
		(layer "F.Cu")
		(net "P3V3_STBY")
	)
	(segment
		(start 457.0095 -30.48)
		(end 456.311 -30.48)
		(width 0.254)
		(layer "F.Cu")
		(net "P3V3_STBY")
	)
	(segment
		(start 488.570016 -150.316184)
		(end 488.570016 -150.495)
		(width 0.254)
		(layer "F.Cu")
		(net "P3V3_STBY")
	)
	(segment
		(start 444.1825 -147.193)
		(end 444.1952 -147.2057)
		(width 0.254)
		(layer "F.Cu")
		(net "P3V3_STBY")
	)
	(segment
		(start 460.121 -1.524)
		(end 461.137 -1.524)
		(width 0.254)
		(layer "F.Cu")
		(net "P3V3_STBY")
	)
	(segment
		(start 404.101046 -24.8539)
		(end 403.3901 -24.8539)
		(width 0.254)
		(layer "F.Cu")
		(net "P3V3_STBY")
	)
	(segment
		(start 413.380682 -66.030094)
		(end 414.556448 -66.030094)
		(width 0.254)
		(layer "F.Cu")
		(net "P3V3_STBY")
	)
	(segment
		(start 412.0134 -101.7524)
		(end 412.369 -101.7524)
		(width 0.254)
		(layer "F.Cu")
		(net "P3V3_STBY")
	)
	(segment
		(start 26.5684 -80.416908)
		(end 26.289 -80.696308)
		(width 0.254)
		(layer "F.Cu")
		(net "P3V3_STBY")
	)
	(segment
		(start 392.55827 -104.65435)
		(end 392.53795 -104.65435)
		(width 0.254)
		(layer "F.Cu")
		(net "P3V3_STBY")
	)
	(segment
		(start 379.145038 -67.894962)
		(end 378.744988 -68.295012)
		(width 0.254)
		(layer "F.Cu")
		(net "P3V3_STBY")
	)
	(segment
		(start 425.212764 -49.953164)
		(end 425.212764 -49.259236)
		(width 0.254)
		(layer "F.Cu")
		(net "P3V3_STBY")
	)
	(segment
		(start 398.15008 -33.871916)
		(end 398.471898 -33.871916)
		(width 0.381)
		(layer "F.Cu")
		(net "P3V3_STBY")
	)
	(segment
		(start 462.87309 0.2032)
		(end 463.306922 0.637032)
		(width 0.254)
		(layer "F.Cu")
		(net "P3V3_STBY")
	)
	(segment
		(start 13.3096 -89.281)
		(end 13.1826 -89.154)
		(width 0.254)
		(layer "F.Cu")
		(net "P3V3_STBY")
	)
	(segment
		(start 392.02741 -104.01681)
		(end 392.2141 -104.1146)
		(width 0.254)
		(layer "F.Cu")
		(net "P3V3_STBY")
	)
	(segment
		(start 477.4057 -140.589)
		(end 477.139 -140.589)
		(width 0.254)
		(layer "F.Cu")
		(net "P3V3_STBY")
	)
	(segment
		(start -2.34696 -119.86006)
		(end -1.44526 -118.95836)
		(width 0.254)
		(layer "F.Cu")
		(net "P3V3_STBY")
	)
	(segment
		(start 391.76706 -103.880666)
		(end 392.02741 -104.01681)
		(width 0.254)
		(layer "F.Cu")
		(net "P3V3_STBY")
	)
	(segment
		(start 386.1054 1.651)
		(end 386.7404 1.651)
		(width 0.254)
		(layer "F.Cu")
		(net "P3V3_STBY")
	)
	(segment
		(start -3.60426 -120.35536)
		(end -3.889248 -120.35536)
		(width 0.254)
		(layer "F.Cu")
		(net "P3V3_STBY")
	)
	(segment
		(start 368.0587 -94.742)
		(end 367.8047 -94.996)
		(width 0.254)
		(layer "F.Cu")
		(net "P3V3_STBY")
	)
	(segment
		(start 466.344 -139.1158)
		(end 466.344 -138.811)
		(width 0.254)
		(layer "F.Cu")
		(net "P3V3_STBY")
	)
	(segment
		(start 172.5676 -93.302582)
		(end 172.5676 -93.3958)
		(width 0.254)
		(layer "F.Cu")
		(net "P3V3_STBY")
	)
	(segment
		(start 20.656296 -80.294226)
		(end 20.447 -80.503522)
		(width 0.254)
		(layer "F.Cu")
		(net "P3V3_STBY")
	)
	(segment
		(start 446.786 -16.448532)
		(end 447.044064 -16.706596)
		(width 0.254)
		(layer "F.Cu")
		(net "P3V3_STBY")
	)
	(segment
		(start 339.471 -21.209)
		(end 338.836 -21.209)
		(width 0.254)
		(layer "F.Cu")
		(net "P3V3_STBY")
	)
	(segment
		(start 373.944896 -73.89495)
		(end 373.944896 -74.69505)
		(width 0.254)
		(layer "F.Cu")
		(net "P3V3_STBY")
	)
	(segment
		(start 354.096066 -132.806186)
		(end 354.826824 -132.806186)
		(width 0.254)
		(layer "F.Cu")
		(net "P3V3_STBY")
	)
	(segment
		(start 477.755204 -138.880596)
		(end 477.9264 -138.7094)
		(width 0.254)
		(layer "F.Cu")
		(net "P3V3_STBY")
	)
	(segment
		(start 416.814 -82.55)
		(end 416.814 -82.231992)
		(width 0.254)
		(layer "F.Cu")
		(net "P3V3_STBY")
	)
	(segment
		(start 390.93775 -105.45445)
		(end 391.3378 -105.0544)
		(width 0.254)
		(layer "F.Cu")
		(net "P3V3_STBY")
	)
	(segment
		(start 445.474344 -147.7645)
		(end 444.1952 -147.7645)
		(width 0.254)
		(layer "F.Cu")
		(net "P3V3_STBY")
	)
	(segment
		(start 185.842148 -62.919864)
		(end 185.842148 -62.336934)
		(width 0.254)
		(layer "F.Cu")
		(net "P3V3_STBY")
	)
	(segment
		(start 490.453934 -146.156934)
		(end 490.453934 -146.939)
		(width 0.254)
		(layer "F.Cu")
		(net "P3V3_STBY")
	)
	(segment
		(start 0.381 -74.93)
		(end -0.446532 -74.102468)
		(width 0.254)
		(layer "F.Cu")
		(net "P3V3_STBY")
	)
	(segment
		(start 379.993652 -38.916102)
		(end 379.993652 -39.174166)
		(width 0.254)
		(layer "F.Cu")
		(net "P3V3_STBY")
	)
	(segment
		(start 433.9336 -19.440144)
		(end 433.646072 -19.727672)
		(width 0.254)
		(layer "F.Cu")
		(net "P3V3_STBY")
	)
	(segment
		(start 404.495 -21.3868)
		(end 404.495 -22.098)
		(width 0.254)
		(layer "F.Cu")
		(net "P3V3_STBY")
	)
	(segment
		(start 491.81512 -152.15616)
		(end 492.252 -151.71928)
		(width 0.254)
		(layer "F.Cu")
		(net "P3V3_STBY")
	)
	(segment
		(start 25.908 -76.454)
		(end 25.908 -75.819)
		(width 0.127)
		(layer "F.Cu")
		(net "P3V3_STBY")
	)
	(segment
		(start 366.137952 -134.8994)
		(end 365.5568 -134.8994)
		(width 0.254)
		(layer "F.Cu")
		(net "P3V3_STBY")
	)
	(segment
		(start 394.17625 -111.57204)
		(end 394.67155 -111.802164)
		(width 0.254)
		(layer "F.Cu")
		(net "P3V3_STBY")
	)
	(segment
		(start 174.6377 -70.612)
		(end 175.13554 -70.612)
		(width 0.4064)
		(layer "F.Cu")
		(net "P3V3_STBY")
	)
	(segment
		(start -0.446532 -68.270882)
		(end -0.000508 -67.824858)
		(width 0.254)
		(layer "F.Cu")
		(net "P3V3_STBY")
	)
	(segment
		(start 456.311 -30.48)
		(end 455.6125 -30.48)
		(width 0.254)
		(layer "F.Cu")
		(net "P3V3_STBY")
	)
	(segment
		(start 420.103046 -48.968152)
		(end 420.865046 -48.968152)
		(width 0.254)
		(layer "F.Cu")
		(net "P3V3_STBY")
	)
	(segment
		(start 371.2718 -101.346)
		(end 371.3988 -101.219)
		(width 0.254)
		(layer "F.Cu")
		(net "P3V3_STBY")
	)
	(segment
		(start 472.7575 -139.573)
		(end 472.7575 -138.43)
		(width 0.254)
		(layer "F.Cu")
		(net "P3V3_STBY")
	)
	(segment
		(start 19.812 -86.6267)
		(end 19.812 -86.2584)
		(width 0.254)
		(layer "F.Cu")
		(net "P3V3_STBY")
	)
	(segment
		(start 412.4325 -109.728)
		(end 412.4325 -110.617)
		(width 0.254)
		(layer "F.Cu")
		(net "P3V3_STBY")
	)
	(segment
		(start 434.594 -14.6812)
		(end 434.594 -14.10335)
		(width 0.254)
		(layer "F.Cu")
		(net "P3V3_STBY")
	)
	(segment
		(start 173.5836 -104.259888)
		(end 173.5836 -104.4448)
		(width 0.254)
		(layer "F.Cu")
		(net "P3V3_STBY")
	)
	(segment
		(start 392.1379 -114.6556)
		(end 392.53795 -115.05565)
		(width 0.254)
		(layer "F.Cu")
		(net "P3V3_STBY")
	)
	(segment
		(start 380.74219 -37.22751)
		(end 380.74219 -37.895022)
		(width 0.254)
		(layer "F.Cu")
		(net "P3V3_STBY")
	)
	(segment
		(start 419.5445 -113.4999)
		(end 419.0492 -113.9952)
		(width 0.254)
		(layer "F.Cu")
		(net "P3V3_STBY")
	)
	(segment
		(start 371.545104 -74.69505)
		(end 371.145308 -75.094846)
		(width 0.254)
		(layer "F.Cu")
		(net "P3V3_STBY")
	)
	(segment
		(start 402.711666 -80.41894)
		(end 402.73478 -80.41894)
		(width 0.254)
		(layer "F.Cu")
		(net "P3V3_STBY")
	)
	(segment
		(start 20.4089 -86.6521)
		(end 20.3327 -86.6521)
		(width 0.254)
		(layer "F.Cu")
		(net "P3V3_STBY")
	)
	(segment
		(start 392.056112 -88.886284)
		(end 391.795 -88.625172)
		(width 0.254)
		(layer "F.Cu")
		(net "P3V3_STBY")
	)
	(segment
		(start 417.0045 -56.2229)
		(end 417.83 -56.2229)
		(width 0.254)
		(layer "F.Cu")
		(net "P3V3_STBY")
	)
	(segment
		(start 1.800352 -67.824858)
		(end 2.032 -68.056506)
		(width 0.254)
		(layer "F.Cu")
		(net "P3V3_STBY")
	)
	(segment
		(start 338.2772 -21.7678)
		(end 337.45424 -21.7678)
		(width 0.254)
		(layer "F.Cu")
		(net "P3V3_STBY")
	)
	(segment
		(start 488.3912 -50.6857)
		(end 487.6292 -50.6857)
		(width 0.254)
		(layer "F.Cu")
		(net "P3V3_STBY")
	)
	(segment
		(start 385.887722 -49.191418)
		(end 385.887722 -48.673258)
		(width 0.254)
		(layer "F.Cu")
		(net "P3V3_STBY")
	)
	(segment
		(start 20.447 -80.503522)
		(end 20.447 -80.90408)
		(width 0.254)
		(layer "F.Cu")
		(net "P3V3_STBY")
	)
	(segment
		(start 461.229202 -0.771144)
		(end 462.203546 0.2032)
		(width 0.254)
		(layer "F.Cu")
		(net "P3V3_STBY")
	)
	(segment
		(start 392.53795 -113.45799)
		(end 392.53795 -113.45545)
		(width 0.12446)
		(layer "F.Cu")
		(net "P3V3_STBY")
	)
	(segment
		(start 432.6509 -47.2821)
		(end 432.435 -47.498)
		(width 0.254)
		(layer "F.Cu")
		(net "P3V3_STBY")
	)
	(segment
		(start 374.344692 -72.695308)
		(end 373.944896 -73.095104)
		(width 0.254)
		(layer "F.Cu")
		(net "P3V3_STBY")
	)
	(segment
		(start 418.20592 -112.74552)
		(end 418.4904 -113.03)
		(width 0.254)
		(layer "F.Cu")
		(net "P3V3_STBY")
	)
	(segment
		(start 440.817 -143.002)
		(end 440.817 -143.764)
		(width 0.254)
		(layer "F.Cu")
		(net "P3V3_STBY")
	)
	(segment
		(start 400.847052 -34.426652)
		(end 401.701 -34.426652)
		(width 0.254)
		(layer "F.Cu")
		(net "P3V3_STBY")
	)
	(segment
		(start 421.627046 -48.968152)
		(end 421.627046 -49.131474)
		(width 0.254)
		(layer "F.Cu")
		(net "P3V3_STBY")
	)
	(segment
		(start 420.618412 -52.788058)
		(end 420.49827 -52.9082)
		(width 0.254)
		(layer "F.Cu")
		(net "P3V3_STBY")
	)
	(segment
		(start 398.471898 -33.871916)
		(end 398.879568 -34.279586)
		(width 0.381)
		(layer "F.Cu")
		(net "P3V3_STBY")
	)
	(segment
		(start 406.273 -21.463)
		(end 406.273 -21.2217)
		(width 0.254)
		(layer "F.Cu")
		(net "P3V3_STBY")
	)
	(segment
		(start 490.2835 -145.9865)
		(end 490.453934 -146.156934)
		(width 0.254)
		(layer "F.Cu")
		(net "P3V3_STBY")
	)
	(segment
		(start 355.71303 -129.812796)
		(end 357.085138 -131.184904)
		(width 0.254)
		(layer "F.Cu")
		(net "P3V3_STBY")
	)
	(segment
		(start 375.002806 -52.940966)
		(end 375.002806 -52.597812)
		(width 0.254)
		(layer "F.Cu")
		(net "P3V3_STBY")
	)
	(segment
		(start 412.4452 -111.633)
		(end 411.988 -111.633)
		(width 0.254)
		(layer "F.Cu")
		(net "P3V3_STBY")
	)
	(segment
		(start 408.051 -63.398146)
		(end 408.025854 -63.373)
		(width 0.254)
		(layer "F.Cu")
		(net "P3V3_STBY")
	)
	(segment
		(start 454.512934 -1.539494)
		(end 454.258934 -1.793494)
		(width 0.254)
		(layer "F.Cu")
		(net "P3V3_STBY")
	)
	(segment
		(start 402.303996 -53.78958)
		(end 402.049996 -53.53558)
		(width 0.254)
		(layer "F.Cu")
		(net "P3V3_STBY")
	)
	(segment
		(start 384.297682 -103.576628)
		(end 384.290316 -103.543862)
		(width 0.254)
		(layer "F.Cu")
		(net "P3V3_STBY")
	)
	(segment
		(start 411.295342 -108.966)
		(end 411.0355 -108.966)
		(width 0.254)
		(layer "F.Cu")
		(net "P3V3_STBY")
	)
	(segment
		(start 14.5923 -5.164836)
		(end 13.438124 -5.164836)
		(width 0.254)
		(layer "F.Cu")
		(net "P3V3_STBY")
	)
	(segment
		(start 482.5873 -137.033)
		(end 482.5873 -135.636)
		(width 0.254)
		(layer "F.Cu")
		(net "P3V3_STBY")
	)
	(segment
		(start 442.352176 -1.685036)
		(end 441.488322 -0.821182)
		(width 0.254)
		(layer "F.Cu")
		(net "P3V3_STBY")
	)
	(segment
		(start 431.82032 -11.7856)
		(end 432.2826 -11.7856)
		(width 0.254)
		(layer "F.Cu")
		(net "P3V3_STBY")
	)
	(segment
		(start 413.801306 -112.649)
		(end 414.075626 -112.92332)
		(width 0.254)
		(layer "F.Cu")
		(net "P3V3_STBY")
	)
	(segment
		(start 337.4517 -20.0152)
		(end 337.4517 -20.3581)
		(width 0.254)
		(layer "F.Cu")
		(net "P3V3_STBY")
	)
	(segment
		(start 435.3306 -22.281896)
		(end 435.483508 -22.128988)
		(width 0.254)
		(layer "F.Cu")
		(net "P3V3_STBY")
	)
	(segment
		(start 179.705 -64.135)
		(end 180.594 -64.135)
		(width 0.4064)
		(layer "F.Cu")
		(net "P3V3_STBY")
	)
	(segment
		(start 365.917988 -134.102094)
		(end 365.5568 -134.463282)
		(width 0.254)
		(layer "F.Cu")
		(net "P3V3_STBY")
	)
	(segment
		(start 486.4227 -139.0269)
		(end 486.4227 -139.1666)
		(width 0.254)
		(layer "F.Cu")
		(net "P3V3_STBY")
	)
	(segment
		(start -3.13182 -119.868188)
		(end -3.123692 -119.86006)
		(width 0.254)
		(layer "F.Cu")
		(net "P3V3_STBY")
	)
	(segment
		(start 411.503114 -108.204)
		(end 411.780228 -108.481114)
		(width 0.254)
		(layer "F.Cu")
		(net "P3V3_STBY")
	)
	(segment
		(start -3.60426 -120.330468)
		(end -3.14198 -119.868188)
		(width 0.254)
		(layer "F.Cu")
		(net "P3V3_STBY")
	)
	(segment
		(start 414.5788 -112.2426)
		(end 414.5788 -112.5728)
		(width 0.254)
		(layer "F.Cu")
		(net "P3V3_STBY")
	)
	(segment
		(start 404.483062 -2.159508)
		(end 404.483062 -1.397508)
		(width 0.254)
		(layer "F.Cu")
		(net "P3V3_STBY")
	)
	(segment
		(start 186.4868 -76.4921)
		(end 186.944 -76.9493)
		(width 0.4064)
		(layer "F.Cu")
		(net "P3V3_STBY")
	)
	(segment
		(start 368.045746 -43.96232)
		(end 368.64671 -43.361356)
		(width 0.254)
		(layer "F.Cu")
		(net "P3V3_STBY")
	)
	(segment
		(start 414.075626 -112.92332)
		(end 414.075626 -113.284)
		(width 0.254)
		(layer "F.Cu")
		(net "P3V3_STBY")
	)
	(segment
		(start 444.1952 -147.2057)
		(end 444.1952 -147.7645)
		(width 0.254)
		(layer "F.Cu")
		(net "P3V3_STBY")
	)
	(segment
		(start 487.2228 -138.4554)
		(end 486.9942 -138.4554)
		(width 0.254)
		(layer "F.Cu")
		(net "P3V3_STBY")
	)
	(segment
		(start 369.720368 -64.725804)
		(end 369.7224 -64.725804)
		(width 0.254)
		(layer "F.Cu")
		(net "P3V3_STBY")
	)
	(segment
		(start 485.963214 -138.770614)
		(end 486.3592 -139.1666)
		(width 0.254)
		(layer "F.Cu")
		(net "P3V3_STBY")
	)
	(segment
		(start 440.182254 -141.478)
		(end 440.817 -142.112746)
		(width 0.254)
		(layer "F.Cu")
		(net "P3V3_STBY")
	)
	(segment
		(start 489.712 -50.6349)
		(end 490.596682 -50.6349)
		(width 0.254)
		(layer "F.Cu")
		(net "P3V3_STBY")
	)
	(segment
		(start 464.012788 4.1402)
		(end 465.074 4.1402)
		(width 0.254)
		(layer "F.Cu")
		(net "P3V3_STBY")
	)
	(segment
		(start 14.478 -86.741)
		(end 15.24 -86.741)
		(width 0.4064)
		(layer "F.Cu")
		(net "P3V3_STBY")
	)
	(segment
		(start 446.786 -16.002)
		(end 446.786 -15.875)
		(width 0.254)
		(layer "F.Cu")
		(net "P3V3_STBY")
	)
	(segment
		(start -4.61264 -132.742686)
		(end -4.694936 -132.66039)
		(width 0.254)
		(layer "F.Cu")
		(net "P3V3_STBY")
	)
	(segment
		(start 392.577828 1.5748)
		(end 392.400028 1.7526)
		(width 0.254)
		(layer "F.Cu")
		(net "P3V3_STBY")
	)
	(segment
		(start 416.56 -55.7784)
		(end 417.0045 -56.2229)
		(width 0.254)
		(layer "F.Cu")
		(net "P3V3_STBY")
	)
	(segment
		(start 178.943 -64.135)
		(end 179.705 -64.135)
		(width 0.4064)
		(layer "F.Cu")
		(net "P3V3_STBY")
	)
	(segment
		(start 383.794 -55.4355)
		(end 383.3495 -54.991)
		(width 0.254)
		(layer "F.Cu")
		(net "P3V3_STBY")
	)
	(segment
		(start 371.3988 -101.219)
		(end 371.708934 -101.219)
		(width 0.254)
		(layer "F.Cu")
		(net "P3V3_STBY")
	)
	(segment
		(start 401.13966 -151.15286)
		(end 400.66468 -150.67788)
		(width 0.4064)
		(layer "F.Cu")
		(net "P3V3_STBY")
	)
	(segment
		(start 455.6125 -30.847284)
		(end 455.422 -31.037784)
		(width 0.254)
		(layer "F.Cu")
		(net "P3V3_STBY")
	)
	(segment
		(start 400.81581 -39.459662)
		(end 401.8915 -38.383972)
		(width 0.254)
		(layer "F.Cu")
		(net "P3V3_STBY")
	)
	(segment
		(start 428.9425 -130.7465)
		(end 427.427136 -132.261864)
		(width 0.254)
		(layer "F.Cu")
		(net "P3V3_STBY")
	)
	(segment
		(start 416.814 -82.231992)
		(end 417.425378 -81.620614)
		(width 0.254)
		(layer "F.Cu")
		(net "P3V3_STBY")
	)
	(segment
		(start 13.405104 -5.197856)
		(end 12.7127 -5.197856)
		(width 0.254)
		(layer "F.Cu")
		(net "P3V3_STBY")
	)
	(segment
		(start 411.76448 -110.055152)
		(end 411.745176 -110.074456)
		(width 0.254)
		(layer "F.Cu")
		(net "P3V3_STBY")
	)
	(segment
		(start 477.139 -141.1478)
		(end 476.6691 -141.6177)
		(width 0.254)
		(layer "F.Cu")
		(net "P3V3_STBY")
	)
	(segment
		(start 491.426246 -152.15616)
		(end 491.433104 -152.15616)
		(width 0.10795)
		(layer "F.Cu")
		(net "P3V3_STBY")
	)
	(segment
		(start 462.203546 0.2032)
		(end 462.87309 0.2032)
		(width 0.254)
		(layer "F.Cu")
		(net "P3V3_STBY")
	)
	(segment
		(start 482.03104 -54.264814)
		(end 481.9523 -54.343554)
		(width 0.254)
		(layer "F.Cu")
		(net "P3V3_STBY")
	)
	(segment
		(start 366.377728 -67.862196)
		(end 366.344962 -67.894962)
		(width 0.254)
		(layer "F.Cu")
		(net "P3V3_STBY")
	)
	(segment
		(start 406.273 -21.2217)
		(end 406.019 -20.9677)
		(width 0.254)
		(layer "F.Cu")
		(net "P3V3_STBY")
	)
	(segment
		(start 363.249718 -71.623682)
		(end 363.564424 -71.308976)
		(width 0.254)
		(layer "F.Cu")
		(net "P3V3_STBY")
	)
	(segment
		(start 477.284796 -147.792948)
		(end 476.900748 -147.4089)
		(width 0.254)
		(layer "F.Cu")
		(net "P3V3_STBY")
	)
	(segment
		(start 463.557366 -25.533096)
		(end 464.581494 -26.557224)
		(width 0.254)
		(layer "F.Cu")
		(net "P3V3_STBY")
	)
	(segment
		(start 402.649182 -80.399382)
		(end 402.449284 -80.199484)
		(width 0.254)
		(layer "F.Cu")
		(net "P3V3_STBY")
	)
	(segment
		(start 363.564424 -71.308976)
		(end 364.073948 -71.308976)
		(width 0.254)
		(layer "F.Cu")
		(net "P3V3_STBY")
	)
	(segment
		(start 457.976732 -36.508182)
		(end 457.976732 -36.411154)
		(width 0.254)
		(layer "F.Cu")
		(net "P3V3_STBY")
	)
	(segment
		(start -3.22326 -132.86486)
		(end -3.22326 -133.19506)
		(width 0.254)
		(layer "F.Cu")
		(net "P3V3_STBY")
	)
	(segment
		(start 425.212764 -49.259236)
		(end 425.503848 -48.968152)
		(width 0.254)
		(layer "F.Cu")
		(net "P3V3_STBY")
	)
	(segment
		(start 433.6034 -11.4046)
		(end 433.9336 -11.0744)
		(width 0.254)
		(layer "F.Cu")
		(net "P3V3_STBY")
	)
	(segment
		(start 16.6116 -43.6626)
		(end 15.596108 -44.678092)
		(width 0.254)
		(layer "F.Cu")
		(net "P3V3_STBY")
	)
	(segment
		(start 400.489674 -34.069274)
		(end 400.847052 -34.426652)
		(width 0.254)
		(layer "F.Cu")
		(net "P3V3_STBY")
	)
	(segment
		(start 461.137 -1.524)
		(end 461.137 -0.878332)
		(width 0.254)
		(layer "F.Cu")
		(net "P3V3_STBY")
	)
	(segment
		(start 472.7575 -137.8585)
		(end 472.059 -137.16)
		(width 0.254)
		(layer "F.Cu")
		(net "P3V3_STBY")
	)
	(segment
		(start 367.462308 -129.972562)
		(end 367.462308 -133.575044)
		(width 0.254)
		(layer "F.Cu")
		(net "P3V3_STBY")
	)
	(segment
		(start 383.3495 -54.991)
		(end 381.963676 -54.991)
		(width 0.254)
		(layer "F.Cu")
		(net "P3V3_STBY")
	)
	(segment
		(start 181.34838 -78.32344)
		(end 180.63464 -78.32344)
		(width 0.4064)
		(layer "F.Cu")
		(net "P3V3_STBY")
	)
	(segment
		(start 440.182 -141.478)
		(end 440.182254 -141.478)
		(width 0.254)
		(layer "F.Cu")
		(net "P3V3_STBY")
	)
	(segment
		(start 440.055 -141.351)
		(end 440.182 -141.478)
		(width 0.254)
		(layer "F.Cu")
		(net "P3V3_STBY")
	)
	(segment
		(start 490.2835 -145.527268)
		(end 490.2835 -145.9865)
		(width 0.254)
		(layer "F.Cu")
		(net "P3V3_STBY")
	)
	(segment
		(start 368.554 -94.742)
		(end 368.554 -94.1324)
		(width 0.254)
		(layer "F.Cu")
		(net "P3V3_STBY")
	)
	(segment
		(start 26.2128 -84.7217)
		(end 26.4795 -84.455)
		(width 0.254)
		(layer "F.Cu")
		(net "P3V3_STBY")
	)
	(segment
		(start 465.2264 3.9878)
		(end 465.7344 3.9878)
		(width 0.254)
		(layer "F.Cu")
		(net "P3V3_STBY")
	)
	(segment
		(start 433.832 -14.224)
		(end 434.47335 -14.224)
		(width 0.254)
		(layer "F.Cu")
		(net "P3V3_STBY")
	)
	(segment
		(start 371.145308 -75.894692)
		(end 371.545104 -75.494896)
		(width 0.254)
		(layer "F.Cu")
		(net "P3V3_STBY")
	)
	(segment
		(start 477.755204 -139.591796)
		(end 477.755204 -138.880596)
		(width 0.254)
		(layer "F.Cu")
		(net "P3V3_STBY")
	)
	(segment
		(start 378.755656 -20.089622)
		(end 377.805696 -19.139662)
		(width 0.254)
		(layer "F.Cu")
		(net "P3V3_STBY")
	)
	(segment
		(start 337.2612 -20.5486)
		(end 336.9564 -20.5486)
		(width 0.254)
		(layer "F.Cu")
		(net "P3V3_STBY")
	)
	(segment
		(start 406.172416 -149.452584)
		(end 406.690322 -149.452584)
		(width 0.4064)
		(layer "F.Cu")
		(net "P3V3_STBY")
	)
	(segment
		(start 401.169124 -81.352136)
		(end 400.685 -81.83626)
		(width 0.254)
		(layer "F.Cu")
		(net "P3V3_STBY")
	)
	(segment
		(start 412.5468 -101.9302)
		(end 412.5468 -102.489)
		(width 0.254)
		(layer "F.Cu")
		(net "P3V3_STBY")
	)
	(segment
		(start 423.252646 -49.591976)
		(end 423.506646 -49.337976)
		(width 0.254)
		(layer "F.Cu")
		(net "P3V3_STBY")
	)
	(segment
		(start 374.344692 -73.495154)
		(end 373.944896 -73.89495)
		(width 0.254)
		(layer "F.Cu")
		(net "P3V3_STBY")
	)
	(segment
		(start 28.054808 -103.401368)
		(end 28.43784 -103.7844)
		(width 0.254)
		(layer "F.Cu")
		(net "P3V3_STBY")
	)
	(segment
		(start 408.50312 -63.305436)
		(end 408.41041 -63.398146)
		(width 0.254)
		(layer "F.Cu")
		(net "P3V3_STBY")
	)
	(segment
		(start 446.786 -15.875)
		(end 446.532 -15.621)
		(width 0.254)
		(layer "F.Cu")
		(net "P3V3_STBY")
	)
	(segment
		(start 367.462308 -133.575044)
		(end 366.137952 -134.8994)
		(width 0.254)
		(layer "F.Cu")
		(net "P3V3_STBY")
	)
	(segment
		(start 483.001066 -48.3362)
		(end 483.001066 -49.205134)
		(width 0.254)
		(layer "F.Cu")
		(net "P3V3_STBY")
	)
	(segment
		(start 454.2028 -38.735)
		(end 454.3298 -38.608)
		(width 0.254)
		(layer "F.Cu")
		(net "P3V3_STBY")
	)
	(segment
		(start 411.76448 -109.98708)
		(end 411.76448 -110.055152)
		(width 0.254)
		(layer "F.Cu")
		(net "P3V3_STBY")
	)
	(segment
		(start 454.025 -38.735)
		(end 454.2028 -38.735)
		(width 0.254)
		(layer "F.Cu")
		(net "P3V3_STBY")
	)
	(segment
		(start 172.6819 -103.358188)
		(end 173.5836 -104.259888)
		(width 0.254)
		(layer "F.Cu")
		(net "P3V3_STBY")
	)
	(segment
		(start 392.53795 -114.25555)
		(end 392.1379 -114.6556)
		(width 0.254)
		(layer "F.Cu")
		(net "P3V3_STBY")
	)
	(segment
		(start 427.427136 -132.261864)
		(end 427.427136 -132.981446)
		(width 0.254)
		(layer "F.Cu")
		(net "P3V3_STBY")
	)
	(segment
		(start 354.805234 -129.3622)
		(end 355.494844 -129.3622)
		(width 0.254)
		(layer "F.Cu")
		(net "P3V3_STBY")
	)
	(segment
		(start 381.963676 -54.991)
		(end 380.299214 -53.326538)
		(width 0.254)
		(layer "F.Cu")
		(net "P3V3_STBY")
	)
	(segment
		(start 408.7495 -109.855)
		(end 409.5115 -109.855)
		(width 0.254)
		(layer "F.Cu")
		(net "P3V3_STBY")
	)
	(segment
		(start 408.051 -104.188514)
		(end 408.051 -103.8225)
		(width 0.254)
		(layer "F.Cu")
		(net "P3V3_STBY")
	)
	(segment
		(start 403.154388 -28.490926)
		(end 403.58441 -28.490926)
		(width 0.254)
		(layer "F.Cu")
		(net "P3V3_STBY")
	)
	(segment
		(start 2.032 -69.088)
		(end 2.794 -69.088)
		(width 0.254)
		(layer "F.Cu")
		(net "P3V3_STBY")
	)
	(segment
		(start 402.449284 -80.199484)
		(end 401.69719 -80.199484)
		(width 0.254)
		(layer "F.Cu")
		(net "P3V3_STBY")
	)
	(segment
		(start 398.12595 -36.670742)
		(end 398.231106 -36.565586)
		(width 0.381)
		(layer "F.Cu")
		(net "P3V3_STBY")
	)
	(segment
		(start 381.706882 -52.506118)
		(end 383.23901 -50.97399)
		(width 0.254)
		(layer "F.Cu")
		(net "P3V3_STBY")
	)
	(segment
		(start 409.4734 -113.284)
		(end 408.7495 -113.284)
		(width 0.254)
		(layer "F.Cu")
		(net "P3V3_STBY")
	)
	(segment
		(start 401.69719 -80.199484)
		(end 401.169124 -80.72755)
		(width 0.254)
		(layer "F.Cu")
		(net "P3V3_STBY")
	)
	(segment
		(start 403.58441 -28.490926)
		(end 403.763988 -28.670504)
		(width 0.254)
		(layer "F.Cu")
		(net "P3V3_STBY")
	)
	(segment
		(start 373.944896 -74.69505)
		(end 374.344692 -75.094846)
		(width 0.254)
		(layer "F.Cu")
		(net "P3V3_STBY")
	)
	(segment
		(start 455.422 -31.037784)
		(end 455.422 -31.735014)
		(width 0.254)
		(layer "F.Cu")
		(net "P3V3_STBY")
	)
	(segment
		(start 377.09348 -86.144608)
		(end 377.09348 -86.79688)
		(width 0.254)
		(layer "F.Cu")
		(net "P3V3_STBY")
	)
	(segment
		(start 477.484948 -147.792948)
		(end 477.284796 -147.792948)
		(width 0.254)
		(layer "F.Cu")
		(net "P3V3_STBY")
	)
	(segment
		(start 175.13554 -70.612)
		(end 175.29302 -70.45452)
		(width 0.4064)
		(layer "F.Cu")
		(net "P3V3_STBY")
	)
	(segment
		(start 392.1379 -113.0554)
		(end 392.53795 -112.65535)
		(width 0.254)
		(layer "F.Cu")
		(net "P3V3_STBY")
	)
	(segment
		(start 403.112986 -81.548986)
		(end 403.112986 -80.863186)
		(width 0.254)
		(layer "F.Cu")
		(net "P3V3_STBY")
	)
	(segment
		(start 408.043888 -22.232112)
		(end 408.043888 -22.055582)
		(width 0.254)
		(layer "F.Cu")
		(net "P3V3_STBY")
	)
	(segment
		(start 441.488322 -0.821182)
		(end 436.794402 -0.821182)
		(width 0.254)
		(layer "F.Cu")
		(net "P3V3_STBY")
	)
	(segment
		(start 378.218192 -54.643528)
		(end 378.218192 -55.2831)
		(width 0.254)
		(layer "F.Cu")
		(net "P3V3_STBY")
	)
	(segment
		(start 408.043888 -22.055582)
		(end 408.071066 -22.028404)
		(width 0.254)
		(layer "F.Cu")
		(net "P3V3_STBY")
	)
	(segment
		(start 411.09011 -32.134556)
		(end 411.198568 -32.026098)
		(width 0.254)
		(layer "F.Cu")
		(net "P3V3_STBY")
	)
	(segment
		(start 422.2115 -113.510822)
		(end 422.2115 -113.03)
		(width 0.254)
		(layer "F.Cu")
		(net "P3V3_STBY")
	)
	(segment
		(start 402.73478 -80.399382)
		(end 402.649182 -80.399382)
		(width 0.254)
		(layer "F.Cu")
		(net "P3V3_STBY")
	)
	(segment
		(start 454.025 -38.735)
		(end 454.025 -39.41318)
		(width 0.254)
		(layer "F.Cu")
		(net "P3V3_STBY")
	)
	(segment
		(start 384.732784 -103.852726)
		(end 384.297682 -103.576628)
		(width 0.254)
		(layer "F.Cu")
		(net "P3V3_STBY")
	)
	(segment
		(start 489.2294 -149.8854)
		(end 489.0008 -149.8854)
		(width 0.254)
		(layer "F.Cu")
		(net "P3V3_STBY")
	)
	(segment
		(start 420.865046 -49.31791)
		(end 420.865046 -48.968152)
		(width 0.254)
		(layer "F.Cu")
		(net "P3V3_STBY")
	)
	(segment
		(start 421.152828 -49.605692)
		(end 420.865046 -49.31791)
		(width 0.254)
		(layer "F.Cu")
		(net "P3V3_STBY")
	)
	(segment
		(start 414.8328 -113.2332)
		(end 414.126426 -113.2332)
		(width 0.254)
		(layer "F.Cu")
		(net "P3V3_STBY")
	)
	(segment
		(start 26.289 -80.696308)
		(end 26.289 -81.026)
		(width 0.254)
		(layer "F.Cu")
		(net "P3V3_STBY")
	)
	(segment
		(start 383.23901 -50.46599)
		(end 383.86512 -49.83988)
		(width 0.254)
		(layer "F.Cu")
		(net "P3V3_STBY")
	)
	(segment
		(start 362.09224 -132.92836)
		(end 362.6866 -132.334)
		(width 0.4064)
		(layer "F.Cu")
		(net "P3V3_STBY")
	)
	(segment
		(start 455.217784 -1.539494)
		(end 454.512934 -1.539494)
		(width 0.254)
		(layer "F.Cu")
		(net "P3V3_STBY")
	)
	(segment
		(start 472.104974 -144.0815)
		(end 472.104974 -144.294098)
		(width 0.254)
		(layer "F.Cu")
		(net "P3V3_STBY")
	)
	(segment
		(start 259.36321 -88.775286)
		(end 258.79171 -88.775286)
		(width 0.381)
		(layer "F.Cu")
		(net "P3V3_STBY")
	)
	(segment
		(start 435.483508 -21.665692)
		(end 436.0037 -21.1455)
		(width 0.254)
		(layer "F.Cu")
		(net "P3V3_STBY")
	)
	(segment
		(start 401.13966 -152.66416)
		(end 401.13966 -151.72436)
		(width 0.4064)
		(layer "F.Cu")
		(net "P3V3_STBY")
	)
	(segment
		(start 491.433104 -152.15616)
		(end 491.81512 -152.15616)
		(width 0.254)
		(layer "F.Cu")
		(net "P3V3_STBY")
	)
	(segment
		(start 411.0355 -110.617)
		(end 411.0355 -109.855)
		(width 0.254)
		(layer "F.Cu")
		(net "P3V3_STBY")
	)
	(segment
		(start 365.5568 -134.463282)
		(end 365.5568 -134.8994)
		(width 0.254)
		(layer "F.Cu")
		(net "P3V3_STBY")
	)
	(segment
		(start 392.056112 -88.886284)
		(end 392.303 -88.886284)
		(width 0.254)
		(layer "F.Cu")
		(net "P3V3_STBY")
	)
	(segment
		(start 337.7057 -19.7612)
		(end 337.4517 -20.0152)
		(width 0.254)
		(layer "F.Cu")
		(net "P3V3_STBY")
	)
	(segment
		(start 371.545104 -73.89495)
		(end 371.545104 -74.69505)
		(width 0.254)
		(layer "F.Cu")
		(net "P3V3_STBY")
	)
	(segment
		(start 466.852 -139.6238)
		(end 466.344 -139.1158)
		(width 0.254)
		(layer "F.Cu")
		(net "P3V3_STBY")
	)
	(segment
		(start 374.344692 -75.894692)
		(end 373.944896 -75.494896)
		(width 0.254)
		(layer "F.Cu")
		(net "P3V3_STBY")
	)
	(segment
		(start 435.0004 -11.4554)
		(end 435.0004 -11.7094)
		(width 0.254)
		(layer "F.Cu")
		(net "P3V3_STBY")
	)
	(segment
		(start 464.7057 -24.0157)
		(end 464.058 -24.0157)
		(width 0.254)
		(layer "F.Cu")
		(net "P3V3_STBY")
	)
	(segment
		(start 390.71804 -103.82123)
		(end 391.18032 -103.606346)
		(width 0.254)
		(layer "F.Cu")
		(net "P3V3_STBY")
	)
	(segment
		(start 392.69035 -103.84536)
		(end 392.98372 -103.68026)
		(width 0.254)
		(layer "F.Cu")
		(net "P3V3_STBY")
	)
	(segment
		(start 435.483508 -22.128988)
		(end 435.483508 -21.665692)
		(width 0.254)
		(layer "F.Cu")
		(net "P3V3_STBY")
	)
	(segment
		(start 392.303 -88.886284)
		(end 392.557 -88.632284)
		(width 0.254)
		(layer "F.Cu")
		(net "P3V3_STBY")
	)
	(segment
		(start 463.306922 0.637032)
		(end 463.306922 3.434334)
		(width 0.254)
		(layer "F.Cu")
		(net "P3V3_STBY")
	)
	(segment
		(start 387.35 1.651)
		(end 386.7404 1.651)
		(width 0.254)
		(layer "F.Cu")
		(net "P3V3_STBY")
	)
	(segment
		(start 385.23926 -49.83988)
		(end 385.887722 -49.191418)
		(width 0.254)
		(layer "F.Cu")
		(net "P3V3_STBY")
	)
	(segment
		(start 477.139 -140.208)
		(end 477.755204 -139.591796)
		(width 0.254)
		(layer "F.Cu")
		(net "P3V3_STBY")
	)
	(segment
		(start 374.751854 -53.344318)
		(end 374.751854 -53.191918)
		(width 0.254)
		(layer "F.Cu")
		(net "P3V3_STBY")
	)
	(segment
		(start 445.238632 -2.408174)
		(end 445.1985 -2.368042)
		(width 0.254)
		(layer "F.Cu")
		(net "P3V3_STBY")
	)
	(segment
		(start 17.5768 -43.6626)
		(end 16.6116 -43.6626)
		(width 0.254)
		(layer "F.Cu")
		(net "P3V3_STBY")
	)
	(segment
		(start 406.690322 -149.452584)
		(end 406.79116 -149.553422)
		(width 0.4064)
		(layer "F.Cu")
		(net "P3V3_STBY")
	)
	(segment
		(start 185.842148 -62.336934)
		(end 185.481214 -61.976)
		(width 0.254)
		(layer "F.Cu")
		(net "P3V3_STBY")
	)
	(segment
		(start 368.1349 -92.1766)
		(end 367.4872 -92.1766)
		(width 0.254)
		(layer "F.Cu")
		(net "P3V3_STBY")
	)
	(segment
		(start 475.7801 -141.6177)
		(end 476.6691 -141.6177)
		(width 0.254)
		(layer "F.Cu")
		(net "P3V3_STBY")
	)
	(segment
		(start 382.27 -87.3125)
		(end 382.27 -86.61146)
		(width 0.254)
		(layer "F.Cu")
		(net "P3V3_STBY")
	)
	(segment
		(start 13.9954 -98.9076)
		(end 13.9446 -98.9076)
		(width 0.4064)
		(layer "F.Cu")
		(net "P3V3_STBY")
	)
	(segment
		(start 336.9564 -21.26996)
		(end 336.9564 -20.5486)
		(width 0.254)
		(layer "F.Cu")
		(net "P3V3_STBY")
	)
	(segment
		(start 434.7718 -14.859)
		(end 434.594 -14.6812)
		(width 0.254)
		(layer "F.Cu")
		(net "P3V3_STBY")
	)
	(segment
		(start 429.26 -130.7465)
		(end 428.9425 -130.7465)
		(width 0.254)
		(layer "F.Cu")
		(net "P3V3_STBY")
	)
	(segment
		(start 411.49016 -34.134552)
		(end 411.09011 -34.534602)
		(width 0.254)
		(layer "F.Cu")
		(net "P3V3_STBY")
	)
	(segment
		(start 476.900748 -147.4089)
		(end 476.4659 -147.4089)
		(width 0.254)
		(layer "F.Cu")
		(net "P3V3_STBY")
	)
	(segment
		(start 411.09011 -33.734756)
		(end 411.090364 -33.734756)
		(width 0.254)
		(layer "F.Cu")
		(net "P3V3_STBY")
	)
	(segment
		(start 367.8047 -94.996)
		(end 367.8047 -95.2373)
		(width 0.254)
		(layer "F.Cu")
		(net "P3V3_STBY")
	)
	(segment
		(start 491.9345 -41.0464)
		(end 492.924338 -41.0464)
		(width 0.4064)
		(layer "F.Cu")
		(net "P3V3_STBY")
	)
	(segment
		(start 455.242168 -38.735)
		(end 455.422 -38.735)
		(width 0.254)
		(layer "F.Cu")
		(net "P3V3_STBY")
	)
	(segment
		(start 15.607284 -4.632452)
		(end 15.124684 -4.632452)
		(width 0.254)
		(layer "F.Cu")
		(net "P3V3_STBY")
	)
	(segment
		(start 181.356 -64.135)
		(end 180.594 -64.135)
		(width 0.4064)
		(layer "F.Cu")
		(net "P3V3_STBY")
	)
	(segment
		(start 408.41041 -63.398146)
		(end 408.051 -63.398146)
		(width 0.254)
		(layer "F.Cu")
		(net "P3V3_STBY")
	)
	(segment
		(start 408.488896 -50.038)
		(end 409.1305 -50.038)
		(width 0.254)
		(layer "F.Cu")
		(net "P3V3_STBY")
	)
	(segment
		(start 491.109 -147.32)
		(end 491.6043 -147.32)
		(width 0.254)
		(layer "F.Cu")
		(net "P3V3_STBY")
	)
	(segment
		(start 413.3215 -112.649)
		(end 413.801306 -112.649)
		(width 0.254)
		(layer "F.Cu")
		(net "P3V3_STBY")
	)
	(segment
		(start 367.116106 -64.81064)
		(end 367.116106 -66.509392)
		(width 0.254)
		(layer "F.Cu")
		(net "P3V3_STBY")
	)
	(segment
		(start 464.478878 -7.025386)
		(end 464.478878 -7.789672)
		(width 0.254)
		(layer "F.Cu")
		(net "P3V3_STBY")
	)
	(segment
		(start 392.2649 -113.73104)
		(end 392.53795 -113.45799)
		(width 0.12446)
		(layer "F.Cu")
		(net "P3V3_STBY")
	)
	(segment
		(start -4.155948 -120.62206)
		(end -4.155948 -121.49836)
		(width 0.254)
		(layer "F.Cu")
		(net "P3V3_STBY")
	)
	(segment
		(start 485.394 -138.770614)
		(end 485.963214 -138.770614)
		(width 0.254)
		(layer "F.Cu")
		(net "P3V3_STBY")
	)
	(segment
		(start 377.6091 -87.3125)
		(end 377.698 -87.3125)
		(width 0.254)
		(layer "F.Cu")
		(net "P3V3_STBY")
	)
	(segment
		(start 14.529816 -2.086864)
		(end 15.069058 -2.086864)
		(width 0.4064)
		(layer "F.Cu")
		(net "P3V3_STBY")
	)
	(segment
		(start 164.084 -69.9262)
		(end 164.084 -70.14718)
		(width 0.254)
		(layer "F.Cu")
		(net "P3V3_STBY")
	)
	(segment
		(start 339.471 -21.209)
		(end 339.471 -20.5994)
		(width 0.254)
		(layer "F.Cu")
		(net "P3V3_STBY")
	)
	(segment
		(start 399.209514 -33.50514)
		(end 398.879568 -33.835086)
		(width 0.254)
		(layer "F.Cu")
		(net "P3V3_STBY")
	)
	(segment
		(start 393.827 -85.217)
		(end 394.0175 -85.0265)
		(width 0.254)
		(layer "F.Cu")
		(net "P3V3_STBY")
	)
	(segment
		(start 491.6043 -147.32)
		(end 492.0615 -146.8628)
		(width 0.254)
		(layer "F.Cu")
		(net "P3V3_STBY")
	)
	(segment
		(start 363.594396 -131.184904)
		(end 365.917988 -133.508496)
		(width 0.254)
		(layer "F.Cu")
		(net "P3V3_STBY")
	)
	(segment
		(start 386.08 -87.3125)
		(end 386.08 -86.808564)
		(width 0.254)
		(layer "F.Cu")
		(net "P3V3_STBY")
	)
	(segment
		(start 368.554 -94.1324)
		(end 368.3889 -93.9673)
		(width 0.254)
		(layer "F.Cu")
		(net "P3V3_STBY")
	)
	(segment
		(start 446.170812 -148.460968)
		(end 445.474344 -147.7645)
		(width 0.254)
		(layer "F.Cu")
		(net "P3V3_STBY")
	)
	(segment
		(start 178.689 -66.548)
		(end 178.181 -66.548)
		(width 0.254)
		(layer "F.Cu")
		(net "P3V3_STBY")
	)
	(segment
		(start 366.377728 -67.24777)
		(end 366.377728 -67.862196)
		(width 0.254)
		(layer "F.Cu")
		(net "P3V3_STBY")
	)
	(segment
		(start 376.744738 -71.095108)
		(end 376.344942 -71.494904)
		(width 0.254)
		(layer "F.Cu")
		(net "P3V3_STBY")
	)
	(segment
		(start 402.73478 -80.41894)
		(end 402.73478 -80.399382)
		(width 0.254)
		(layer "F.Cu")
		(net "P3V3_STBY")
	)
	(segment
		(start 423.86758 -117.864636)
		(end 423.2529 -117.249956)
		(width 0.254)
		(layer "F.Cu")
		(net "P3V3_STBY")
	)
	(segment
		(start 423.886122 -118.12524)
		(end 423.86758 -118.12524)
		(width 0.254)
		(layer "F.Cu")
		(net "P3V3_STBY")
	)
	(segment
		(start 375.17832 -53.770784)
		(end 374.751854 -53.344318)
		(width 0.254)
		(layer "F.Cu")
		(net "P3V3_STBY")
	)
	(segment
		(start 433.9336 -16.0528)
		(end 433.9336 -18.533872)
		(width 0.254)
		(layer "F.Cu")
		(net "P3V3_STBY")
	)
	(segment
		(start 179.959 -6.8834)
		(end 179.959 -7.366)
		(width 0.4064)
		(layer "F.Cu")
		(net "P3V3_STBY")
	)
	(segment
		(start 446.786 -16.002)
		(end 446.786 -16.448532)
		(width 0.254)
		(layer "F.Cu")
		(net "P3V3_STBY")
	)
	(segment
		(start 414.290256 -39.334694)
		(end 413.890206 -38.934644)
		(width 0.254)
		(layer "F.Cu")
		(net "P3V3_STBY")
	)
	(segment
		(start 392.53795 -113.45545)
		(end 392.1379 -113.0554)
		(width 0.12446)
		(layer "F.Cu")
		(net "P3V3_STBY")
	)
	(segment
		(start 440.817 -142.112746)
		(end 440.817 -143.002)
		(width 0.254)
		(layer "F.Cu")
		(net "P3V3_STBY")
	)
	(segment
		(start 370.111274 -64.113664)
		(end 370.111274 -64.334898)
		(width 0.254)
		(layer "F.Cu")
		(net "P3V3_STBY")
	)
	(segment
		(start 486.3592 -139.1666)
		(end 486.4227 -139.1666)
		(width 0.254)
		(layer "F.Cu")
		(net "P3V3_STBY")
	)
	(segment
		(start 362.9406 -133.0706)
		(end 362.9152 -133.096)
		(width 0.4064)
		(layer "F.Cu")
		(net "P3V3_STBY")
	)
	(via
		(at 164.457126 -70.520306)
		(size 0.508)
		(drill 0.254)
		(layers "F.Cu" "B.Cu")
		(net "P3V3_STBY")
	)
	(via
		(at 376.3264 -1.3462)
		(size 0.508)
		(drill 0.254)
		(layers "F.Cu" "B.Cu")
		(net "P3V3_STBY")
	)
	(via
		(at 379.145038 -67.894962)
		(size 0.508)
		(drill 0.254)
		(layers "F.Cu" "B.Cu")
		(net "P3V3_STBY")
	)
	(via
		(at 460.239618 -22.724872)
		(size 0.5588)
		(drill 0.3048)
		(layers "F.Cu" "B.Cu")
		(net "P3V3_STBY")
	)
	(via
		(at 403.937216 -151.611584)
		(size 0.508)
		(drill 0.254)
		(layers "F.Cu" "B.Cu")
		(net "P3V3_STBY")
	)
	(via
		(at 490.596682 -50.6349)
		(size 0.508)
		(drill 0.254)
		(layers "F.Cu" "B.Cu")
		(net "P3V3_STBY")
	)
	(via
		(at 481.9523 -54.343554)
		(size 0.508)
		(drill 0.254)
		(layers "F.Cu" "B.Cu")
		(net "P3V3_STBY")
	)
	(via
		(at 398.12595 -36.670742)
		(size 0.5588)
		(drill 0.3048)
		(layers "F.Cu" "B.Cu")
		(net "P3V3_STBY")
	)
	(via
		(at 20.656296 -80.294226)
		(size 0.508)
		(drill 0.254)
		(layers "F.Cu" "B.Cu")
		(net "P3V3_STBY")
	)
	(via
		(at 442.352176 -2.324354)
		(size 0.508)
		(drill 0.254)
		(layers "F.Cu" "B.Cu")
		(net "P3V3_STBY")
	)
	(via
		(at 376.744738 -71.095108)
		(size 0.4572)
		(drill 0.2032)
		(layers "F.Cu" "B.Cu")
		(net "P3V3_STBY")
	)
	(via
		(at 393.493498 -26.597102)
		(size 0.508)
		(drill 0.254)
		(layers "F.Cu" "B.Cu")
		(net "P3V3_STBY")
	)
	(via
		(at 93.791278 -88.775286)
		(size 0.508)
		(drill 0.254)
		(layers "F.Cu" "B.Cu")
		(net "P3V3_STBY")
	)
	(via
		(at 402.046186 -86.642448)
		(size 0.508)
		(drill 0.254)
		(layers "F.Cu" "B.Cu")
		(net "P3V3_STBY")
	)
	(via
		(at 23.96744 -85.14334)
		(size 0.508)
		(drill 0.254)
		(layers "F.Cu" "B.Cu")
		(net "P3V3_STBY")
	)
	(via
		(at 466.908896 -149.0091)
		(size 0.508)
		(drill 0.254)
		(layers "F.Cu" "B.Cu")
		(net "P3V3_STBY")
	)
	(via
		(at 463.25282 -15.4178)
		(size 0.5588)
		(drill 0.3048)
		(layers "F.Cu" "B.Cu")
		(net "P3V3_STBY")
	)
	(via
		(at 482.999796 -115.423188)
		(size 0.508)
		(drill 0.254)
		(layers "F.Cu" "B.Cu")
		(net "P3V3_STBY")
	)
	(via
		(at 175.21555 -125.54077)
		(size 0.508)
		(drill 0.254)
		(layers "F.Cu" "B.Cu")
		(net "P3V3_STBY")
	)
	(via
		(at 460.239618 -23.410672)
		(size 0.5588)
		(drill 0.3048)
		(layers "F.Cu" "B.Cu")
		(net "P3V3_STBY")
	)
	(via
		(at 338.25688 -85.04174)
		(size 0.508)
		(drill 0.254)
		(layers "F.Cu" "B.Cu")
		(net "P3V3_STBY")
	)
	(via
		(at 365.340392 -39.600632)
		(size 0.508)
		(drill 0.254)
		(layers "F.Cu" "B.Cu")
		(net "P3V3_STBY")
	)
	(via
		(at 2.63271 -117.246908)
		(size 0.508)
		(drill 0.254)
		(layers "F.Cu" "B.Cu")
		(net "P3V3_STBY")
	)
	(via
		(at 392.2141 -104.1146)
		(size 0.508)
		(drill 0.254)
		(layers "F.Cu" "B.Cu")
		(net "P3V3_STBY")
	)
	(via
		(at 371.145308 -73.495154)
		(size 0.4572)
		(drill 0.2032)
		(layers "F.Cu" "B.Cu")
		(net "P3V3_STBY")
	)
	(via
		(at 20.955 -86.7156)
		(size 0.508)
		(drill 0.254)
		(layers "F.Cu" "B.Cu")
		(net "P3V3_STBY")
	)
	(via
		(at 368.547142 -28.50515)
		(size 0.508)
		(drill 0.254)
		(layers "F.Cu" "B.Cu")
		(net "P3V3_STBY")
	)
	(via
		(at 394.67155 -111.802164)
		(size 0.508)
		(drill 0.254)
		(layers "F.Cu" "B.Cu")
		(net "P3V3_STBY")
	)
	(via
		(at 482.8794 -49.3268)
		(size 0.508)
		(drill 0.254)
		(layers "F.Cu" "B.Cu")
		(net "P3V3_STBY")
	)
	(via
		(at 202.63612 -107.564936)
		(size 0.508)
		(drill 0.254)
		(layers "F.Cu" "B.Cu")
		(net "P3V3_STBY")
	)
	(via
		(at 460.239618 -22.064472)
		(size 0.5588)
		(drill 0.3048)
		(layers "F.Cu" "B.Cu")
		(net "P3V3_STBY")
	)
	(via
		(at 336.328258 -12.910058)
		(size 0.508)
		(drill 0.254)
		(layers "F.Cu" "B.Cu")
		(net "P3V3_STBY")
	)
	(via
		(at 371.6528 -91.9988)
		(size 0.508)
		(drill 0.254)
		(layers "F.Cu" "B.Cu")
		(net "P3V3_STBY")
	)
	(via
		(at 369.545108 -70.295262)
		(size 0.4572)
		(drill 0.2032)
		(layers "F.Cu" "B.Cu")
		(net "P3V3_STBY")
	)
	(via
		(at 342.9254 -114.935)
		(size 0.508)
		(drill 0.254)
		(layers "F.Cu" "B.Cu")
		(net "P3V3_STBY")
	)
	(via
		(at 463.08137 -19.641566)
		(size 0.5588)
		(drill 0.3048)
		(layers "F.Cu" "B.Cu")
		(net "P3V3_STBY")
	)
	(via
		(at 368.559334 -38.513004)
		(size 0.508)
		(drill 0.254)
		(layers "F.Cu" "B.Cu")
		(net "P3V3_STBY")
	)
	(via
		(at 383.1971 -73.025)
		(size 0.508)
		(drill 0.254)
		(layers "F.Cu" "B.Cu")
		(net "P3V3_STBY")
	)
	(via
		(at 479.1456 -43.8404)
		(size 0.508)
		(drill 0.254)
		(layers "F.Cu" "B.Cu")
		(net "P3V3_STBY")
	)
	(via
		(at 420.618412 -52.788058)
		(size 0.508)
		(drill 0.254)
		(layers "F.Cu" "B.Cu")
		(net "P3V3_STBY")
	)
	(via
		(at 374.344692 -73.495154)
		(size 0.4572)
		(drill 0.2032)
		(layers "F.Cu" "B.Cu")
		(net "P3V3_STBY")
	)
	(via
		(at 400.7358 -35.597846)
		(size 0.508)
		(drill 0.254)
		(layers "F.Cu" "B.Cu")
		(net "P3V3_STBY")
	)
	(via
		(at 368.745262 -77.494892)
		(size 0.4572)
		(drill 0.2032)
		(layers "F.Cu" "B.Cu")
		(net "P3V3_STBY")
	)
	(via
		(at 393.446 -29.355034)
		(size 0.508)
		(drill 0.254)
		(layers "F.Cu" "B.Cu")
		(net "P3V3_STBY")
	)
	(via
		(at 392.1379 -114.6556)
		(size 0.508)
		(drill 0.254)
		(layers "F.Cu" "B.Cu")
		(net "P3V3_STBY")
	)
	(via
		(at 482.3968 -119.4308)
		(size 0.508)
		(drill 0.254)
		(layers "F.Cu" "B.Cu")
		(net "P3V3_STBY")
	)
	(via
		(at 458.47 -154.051)
		(size 0.508)
		(drill 0.254)
		(layers "F.Cu" "B.Cu")
		(net "P3V3_STBY")
	)
	(via
		(at 401.891246 -48.695864)
		(size 0.508)
		(drill 0.254)
		(layers "F.Cu" "B.Cu")
		(net "P3V3_STBY")
	)
	(via
		(at 489.43006 -18.568924)
		(size 0.508)
		(drill 0.254)
		(layers "F.Cu" "B.Cu")
		(net "P3V3_STBY")
	)
	(via
		(at 477.198944 -135.39216)
		(size 0.508)
		(drill 0.254)
		(layers "F.Cu" "B.Cu")
		(net "P3V3_STBY")
	)
	(via
		(at 164.9984 -99.3648)
		(size 0.508)
		(drill 0.254)
		(layers "F.Cu" "B.Cu")
		(net "P3V3_STBY")
	)
	(via
		(at 379.087126 -45.564298)
		(size 0.508)
		(drill 0.254)
		(layers "F.Cu" "B.Cu")
		(net "P3V3_STBY")
	)
	(via
		(at 475.1324 -6.35)
		(size 0.508)
		(drill 0.254)
		(layers "F.Cu" "B.Cu")
		(net "P3V3_STBY")
	)
	(via
		(at 462.55178 -18.40992)
		(size 0.5588)
		(drill 0.3048)
		(layers "F.Cu" "B.Cu")
		(net "P3V3_STBY")
	)
	(via
		(at 492.2266 -39.0144)
		(size 0.508)
		(drill 0.254)
		(layers "F.Cu" "B.Cu")
		(net "P3V3_STBY")
	)
	(via
		(at 371.945154 -72.695308)
		(size 0.4572)
		(drill 0.2032)
		(layers "F.Cu" "B.Cu")
		(net "P3V3_STBY")
	)
	(via
		(at 16.7132 -86.0806)
		(size 0.508)
		(drill 0.254)
		(layers "F.Cu" "B.Cu")
		(net "P3V3_STBY")
	)
	(via
		(at 355.71303 -129.580386)
		(size 0.508)
		(drill 0.254)
		(layers "F.Cu" "B.Cu")
		(net "P3V3_STBY")
	)
	(via
		(at 373.544846 -75.894692)
		(size 0.4572)
		(drill 0.2032)
		(layers "F.Cu" "B.Cu")
		(net "P3V3_STBY")
	)
	(via
		(at 406.273 -21.463)
		(size 0.508)
		(drill 0.254)
		(layers "F.Cu" "B.Cu")
		(net "P3V3_STBY")
	)
	(via
		(at 482.785166 -144.667478)
		(size 0.508)
		(drill 0.254)
		(layers "F.Cu" "B.Cu")
		(net "P3V3_STBY")
	)
	(via
		(at 483.6922 -119.4562)
		(size 0.508)
		(drill 0.254)
		(layers "F.Cu" "B.Cu")
		(net "P3V3_STBY")
	)
	(via
		(at 386.7404 1.651)
		(size 0.508)
		(drill 0.254)
		(layers "F.Cu" "B.Cu")
		(net "P3V3_STBY")
	)
	(via
		(at 410.806138 -24.023574)
		(size 0.508)
		(drill 0.254)
		(layers "F.Cu" "B.Cu")
		(net "P3V3_STBY")
	)
	(via
		(at 450.6468 -130.2512)
		(size 0.508)
		(drill 0.254)
		(layers "F.Cu" "B.Cu")
		(net "P3V3_STBY")
	)
	(via
		(at 474.49994 -136.144)
		(size 0.508)
		(drill 0.254)
		(layers "F.Cu" "B.Cu")
		(net "P3V3_STBY")
	)
	(via
		(at 393.681204 -104.473248)
		(size 0.508)
		(drill 0.254)
		(layers "F.Cu" "B.Cu")
		(net "P3V3_STBY")
	)
	(via
		(at 423.886122 -118.12524)
		(size 0.508)
		(drill 0.254)
		(layers "F.Cu" "B.Cu")
		(net "P3V3_STBY")
	)
	(via
		(at 460.239618 -24.096472)
		(size 0.5588)
		(drill 0.3048)
		(layers "F.Cu" "B.Cu")
		(net "P3V3_STBY")
	)
	(via
		(at 408.071066 -22.028404)
		(size 0.508)
		(drill 0.254)
		(layers "F.Cu" "B.Cu")
		(net "P3V3_STBY")
	)
	(via
		(at 488.001056 -38.862)
		(size 0.508)
		(drill 0.254)
		(layers "F.Cu" "B.Cu")
		(net "P3V3_STBY")
	)
	(via
		(at 437.9595 -149.4155)
		(size 0.508)
		(drill 0.254)
		(layers "F.Cu" "B.Cu")
		(net "P3V3_STBY")
	)
	(via
		(at 492.0742 -129.2606)
		(size 0.508)
		(drill 0.254)
		(layers "F.Cu" "B.Cu")
		(net "P3V3_STBY")
	)
	(via
		(at 471.932 -148.9075)
		(size 0.508)
		(drill 0.254)
		(layers "F.Cu" "B.Cu")
		(net "P3V3_STBY")
	)
	(via
		(at 342.9254 -113.665)
		(size 0.508)
		(drill 0.254)
		(layers "F.Cu" "B.Cu")
		(net "P3V3_STBY")
	)
	(via
		(at 28.054808 -103.401368)
		(size 0.508)
		(drill 0.254)
		(layers "F.Cu" "B.Cu")
		(net "P3V3_STBY")
	)
	(via
		(at 501.0658 -146.4056)
		(size 0.508)
		(drill 0.254)
		(layers "F.Cu" "B.Cu")
		(net "P3V3_STBY")
	)
	(via
		(at 439.5216 -49.7459)
		(size 0.508)
		(drill 0.254)
		(layers "F.Cu" "B.Cu")
		(net "P3V3_STBY")
	)
	(via
		(at 13.1826 -89.154)
		(size 0.508)
		(drill 0.254)
		(layers "F.Cu" "B.Cu")
		(net "P3V3_STBY")
	)
	(via
		(at 411.1752 -115.1636)
		(size 0.508)
		(drill 0.254)
		(layers "F.Cu" "B.Cu")
		(net "P3V3_STBY")
	)
	(via
		(at 452.946008 -27.697176)
		(size 0.508)
		(drill 0.254)
		(layers "F.Cu" "B.Cu")
		(net "P3V3_STBY")
	)
	(via
		(at 457.976732 -36.508182)
		(size 0.508)
		(drill 0.254)
		(layers "F.Cu" "B.Cu")
		(net "P3V3_STBY")
	)
	(via
		(at 398.78508 -75.01636)
		(size 0.5588)
		(drill 0.3048)
		(layers "F.Cu" "B.Cu")
		(net "P3V3_STBY")
	)
	(via
		(at 405.8539 -93.301566)
		(size 0.508)
		(drill 0.254)
		(layers "F.Cu" "B.Cu")
		(net "P3V3_STBY")
	)
	(via
		(at 460.925418 -23.410672)
		(size 0.5588)
		(drill 0.3048)
		(layers "F.Cu" "B.Cu")
		(net "P3V3_STBY")
	)
	(via
		(at 409.5115 -109.855)
		(size 0.508)
		(drill 0.254)
		(layers "F.Cu" "B.Cu")
		(net "P3V3_STBY")
	)
	(via
		(at 408.50312 -63.305436)
		(size 0.5588)
		(drill 0.3048)
		(layers "F.Cu" "B.Cu")
		(net "P3V3_STBY")
	)
	(via
		(at 170.0022 -128.016)
		(size 0.508)
		(drill 0.254)
		(layers "F.Cu" "B.Cu")
		(net "P3V3_STBY")
	)
	(via
		(at 400.7358 -39.459662)
		(size 0.508)
		(drill 0.254)
		(layers "F.Cu" "B.Cu")
		(net "P3V3_STBY")
	)
	(via
		(at 410.718 -2.413)
		(size 0.508)
		(drill 0.254)
		(layers "F.Cu" "B.Cu")
		(net "P3V3_STBY")
	)
	(via
		(at 364.073948 -71.308976)
		(size 0.508)
		(drill 0.254)
		(layers "F.Cu" "B.Cu")
		(net "P3V3_STBY")
	)
	(via
		(at 482.3714 -120.0404)
		(size 0.508)
		(drill 0.254)
		(layers "F.Cu" "B.Cu")
		(net "P3V3_STBY")
	)
	(via
		(at 463.31124 -18.40484)
		(size 0.5588)
		(drill 0.3048)
		(layers "F.Cu" "B.Cu")
		(net "P3V3_STBY")
	)
	(via
		(at 482.6635 -135.5598)
		(size 0.508)
		(drill 0.254)
		(layers "F.Cu" "B.Cu")
		(net "P3V3_STBY")
	)
	(via
		(at 425.212764 -49.953164)
		(size 0.508)
		(drill 0.254)
		(layers "F.Cu" "B.Cu")
		(net "P3V3_STBY")
	)
	(via
		(at 483.0572 -119.4308)
		(size 0.508)
		(drill 0.254)
		(layers "F.Cu" "B.Cu")
		(net "P3V3_STBY")
	)
	(via
		(at 403.763988 -28.670504)
		(size 0.508)
		(drill 0.254)
		(layers "F.Cu" "B.Cu")
		(net "P3V3_STBY")
	)
	(via
		(at 447.044064 -16.706596)
		(size 0.508)
		(drill 0.254)
		(layers "F.Cu" "B.Cu")
		(net "P3V3_STBY")
	)
	(via
		(at 15.607284 -4.632452)
		(size 0.508)
		(drill 0.254)
		(layers "F.Cu" "B.Cu")
		(net "P3V3_STBY")
	)
	(via
		(at 402.303996 -55.307484)
		(size 0.508)
		(drill 0.254)
		(layers "F.Cu" "B.Cu")
		(net "P3V3_STBY")
	)
	(via
		(at 463.3849 -14.01572)
		(size 0.5588)
		(drill 0.3048)
		(layers "F.Cu" "B.Cu")
		(net "P3V3_STBY")
	)
	(via
		(at 461.30845 -144.187926)
		(size 0.508)
		(drill 0.254)
		(layers "F.Cu" "B.Cu")
		(net "P3V3_STBY")
	)
	(via
		(at 382.27 -86.61146)
		(size 0.508)
		(drill 0.254)
		(layers "F.Cu" "B.Cu")
		(net "P3V3_STBY")
	)
	(via
		(at 176.175416 -125.552962)
		(size 0.508)
		(drill 0.254)
		(layers "F.Cu" "B.Cu")
		(net "P3V3_STBY")
	)
	(via
		(at 377.879864 -55.5371)
		(size 0.508)
		(drill 0.254)
		(layers "F.Cu" "B.Cu")
		(net "P3V3_STBY")
	)
	(via
		(at 407.344626 -104.648)
		(size 0.508)
		(drill 0.254)
		(layers "F.Cu" "B.Cu")
		(net "P3V3_STBY")
	)
	(via
		(at 422.402 -20.7264)
		(size 0.508)
		(drill 0.254)
		(layers "F.Cu" "B.Cu")
		(net "P3V3_STBY")
	)
	(via
		(at 469.304116 -41.814496)
		(size 0.5588)
		(drill 0.3048)
		(layers "F.Cu" "B.Cu")
		(net "P3V3_STBY")
	)
	(via
		(at 374.651016 -62.556898)
		(size 0.508)
		(drill 0.254)
		(layers "F.Cu" "B.Cu")
		(net "P3V3_STBY")
	)
	(via
		(at 442.5188 -140.427202)
		(size 0.508)
		(drill 0.254)
		(layers "F.Cu" "B.Cu")
		(net "P3V3_STBY")
	)
	(via
		(at 310.328818 -44.667932)
		(size 0.508)
		(drill 0.254)
		(layers "F.Cu" "B.Cu")
		(net "P3V3_STBY")
	)
	(via
		(at 403.270466 -151.604218)
		(size 0.508)
		(drill 0.254)
		(layers "F.Cu" "B.Cu")
		(net "P3V3_STBY")
	)
	(via
		(at 460.925418 -24.096472)
		(size 0.5588)
		(drill 0.3048)
		(layers "F.Cu" "B.Cu")
		(net "P3V3_STBY")
	)
	(via
		(at 339.471 -20.5994)
		(size 0.508)
		(drill 0.254)
		(layers "F.Cu" "B.Cu")
		(net "P3V3_STBY")
	)
	(via
		(at 418.20592 -112.74552)
		(size 0.508)
		(drill 0.254)
		(layers "F.Cu" "B.Cu")
		(net "P3V3_STBY")
	)
	(via
		(at 376.744738 -77.494892)
		(size 0.4572)
		(drill 0.2032)
		(layers "F.Cu" "B.Cu")
		(net "P3V3_STBY")
	)
	(via
		(at 374.344692 -75.894692)
		(size 0.4572)
		(drill 0.2032)
		(layers "F.Cu" "B.Cu")
		(net "P3V3_STBY")
	)
	(via
		(at 26.2128 -85.13826)
		(size 0.508)
		(drill 0.254)
		(layers "F.Cu" "B.Cu")
		(net "P3V3_STBY")
	)
	(via
		(at 392.400028 1.7526)
		(size 0.508)
		(drill 0.254)
		(layers "F.Cu" "B.Cu")
		(net "P3V3_STBY")
	)
	(via
		(at 489.767372 -44.562522)
		(size 0.508)
		(drill 0.254)
		(layers "F.Cu" "B.Cu")
		(net "P3V3_STBY")
	)
	(via
		(at 26.289 -77.3938)
		(size 0.508)
		(drill 0.254)
		(layers "F.Cu" "B.Cu")
		(net "P3V3_STBY")
	)
	(via
		(at 481.9523 -55.003954)
		(size 0.508)
		(drill 0.254)
		(layers "F.Cu" "B.Cu")
		(net "P3V3_STBY")
	)
	(via
		(at 477.139 -140.589)
		(size 0.508)
		(drill 0.254)
		(layers "F.Cu" "B.Cu")
		(net "P3V3_STBY")
	)
	(via
		(at 409.998926 -24.131016)
		(size 0.508)
		(drill 0.254)
		(layers "F.Cu" "B.Cu")
		(net "P3V3_STBY")
	)
	(via
		(at 473.60332 -136.41324)
		(size 0.508)
		(drill 0.254)
		(layers "F.Cu" "B.Cu")
		(net "P3V3_STBY")
	)
	(via
		(at 423.418 -13.081)
		(size 0.508)
		(drill 0.254)
		(layers "F.Cu" "B.Cu")
		(net "P3V3_STBY")
	)
	(via
		(at 16.768064 -118.9609)
		(size 0.508)
		(drill 0.254)
		(layers "F.Cu" "B.Cu")
		(net "P3V3_STBY")
	)
	(via
		(at 352.933 -91.567)
		(size 0.508)
		(drill 0.254)
		(layers "F.Cu" "B.Cu")
		(net "P3V3_STBY")
	)
	(via
		(at 176.175416 -124.917962)
		(size 0.508)
		(drill 0.254)
		(layers "F.Cu" "B.Cu")
		(net "P3V3_STBY")
	)
	(via
		(at 15.596108 -45.154342)
		(size 0.508)
		(drill 0.254)
		(layers "F.Cu" "B.Cu")
		(net "P3V3_STBY")
	)
	(via
		(at 391.20445 -103.615236)
		(size 0.508)
		(drill 0.254)
		(layers "F.Cu" "B.Cu")
		(net "P3V3_STBY")
	)
	(via
		(at 394.952728 -84.371434)
		(size 0.508)
		(drill 0.254)
		(layers "F.Cu" "B.Cu")
		(net "P3V3_STBY")
	)
	(via
		(at 167.259 -72.263)
		(size 0.508)
		(drill 0.254)
		(layers "F.Cu" "B.Cu")
		(net "P3V3_STBY")
	)
	(via
		(at -1.44526 -118.83136)
		(size 0.508)
		(drill 0.254)
		(layers "F.Cu" "B.Cu")
		(net "P3V3_STBY")
	)
	(via
		(at 462.60258 -17.64538)
		(size 0.5588)
		(drill 0.3048)
		(layers "F.Cu" "B.Cu")
		(net "P3V3_STBY")
	)
	(via
		(at 432.435 -47.498)
		(size 0.508)
		(drill 0.254)
		(layers "F.Cu" "B.Cu")
		(net "P3V3_STBY")
	)
	(via
		(at 432.4223 -48.26)
		(size 0.508)
		(drill 0.254)
		(layers "F.Cu" "B.Cu")
		(net "P3V3_STBY")
	)
	(via
		(at 466.852 -139.6238)
		(size 0.508)
		(drill 0.254)
		(layers "F.Cu" "B.Cu")
		(net "P3V3_STBY")
	)
	(via
		(at 386.274564 -86.614)
		(size 0.508)
		(drill 0.254)
		(layers "F.Cu" "B.Cu")
		(net "P3V3_STBY")
	)
	(via
		(at 492.0615 -146.8628)
		(size 0.508)
		(drill 0.254)
		(layers "F.Cu" "B.Cu")
		(net "P3V3_STBY")
	)
	(via
		(at 396.246096 -84.2772)
		(size 0.508)
		(drill 0.254)
		(layers "F.Cu" "B.Cu")
		(net "P3V3_STBY")
	)
	(via
		(at 486.4227 -139.1666)
		(size 0.508)
		(drill 0.254)
		(layers "F.Cu" "B.Cu")
		(net "P3V3_STBY")
	)
	(via
		(at 379.28296 -82.760312)
		(size 0.508)
		(drill 0.254)
		(layers "F.Cu" "B.Cu")
		(net "P3V3_STBY")
	)
	(via
		(at 481.7872 -119.4308)
		(size 0.508)
		(drill 0.254)
		(layers "F.Cu" "B.Cu")
		(net "P3V3_STBY")
	)
	(via
		(at 441.833 -148.971)
		(size 0.508)
		(drill 0.254)
		(layers "F.Cu" "B.Cu")
		(net "P3V3_STBY")
	)
	(via
		(at 392.056112 -88.886284)
		(size 0.508)
		(drill 0.254)
		(layers "F.Cu" "B.Cu")
		(net "P3V3_STBY")
	)
	(via
		(at 453.0598 -146.4056)
		(size 0.508)
		(drill 0.254)
		(layers "F.Cu" "B.Cu")
		(net "P3V3_STBY")
	)
	(via
		(at 486.1052 -141.097)
		(size 0.508)
		(drill 0.254)
		(layers "F.Cu" "B.Cu")
		(net "P3V3_STBY")
	)
	(via
		(at 19.340322 -46.486826)
		(size 0.508)
		(drill 0.254)
		(layers "F.Cu" "B.Cu")
		(net "P3V3_STBY")
	)
	(via
		(at -0.61722 -133.18236)
		(size 0.508)
		(drill 0.254)
		(layers "F.Cu" "B.Cu")
		(net "P3V3_STBY")
	)
	(via
		(at 477.484948 -147.792948)
		(size 0.508)
		(drill 0.254)
		(layers "F.Cu" "B.Cu")
		(net "P3V3_STBY")
	)
	(via
		(at 456.7555 -134.4168)
		(size 0.508)
		(drill 0.254)
		(layers "F.Cu" "B.Cu")
		(net "P3V3_STBY")
	)
	(via
		(at 345.2368 -81.8388)
		(size 0.508)
		(drill 0.254)
		(layers "F.Cu" "B.Cu")
		(net "P3V3_STBY")
	)
	(via
		(at 186.944 -77.0636)
		(size 0.508)
		(drill 0.254)
		(layers "F.Cu" "B.Cu")
		(net "P3V3_STBY")
	)
	(via
		(at 465.19084 -18.6182)
		(size 0.5588)
		(drill 0.3048)
		(layers "F.Cu" "B.Cu")
		(net "P3V3_STBY")
	)
	(via
		(at 457.6064 -130.9624)
		(size 0.508)
		(drill 0.254)
		(layers "F.Cu" "B.Cu")
		(net "P3V3_STBY")
	)
	(via
		(at 497.1415 -130.0607)
		(size 0.508)
		(drill 0.254)
		(layers "F.Cu" "B.Cu")
		(net "P3V3_STBY")
	)
	(via
		(at 427.00321 -133.405372)
		(size 0.508)
		(drill 0.254)
		(layers "F.Cu" "B.Cu")
		(net "P3V3_STBY")
	)
	(via
		(at 398.925796 -86.811104)
		(size 0.508)
		(drill 0.254)
		(layers "F.Cu" "B.Cu")
		(net "P3V3_STBY")
	)
	(via
		(at 374.20677 -94.654116)
		(size 0.508)
		(drill 0.254)
		(layers "F.Cu" "B.Cu")
		(net "P3V3_STBY")
	)
	(via
		(at 411.734 -111.887)
		(size 0.508)
		(drill 0.254)
		(layers "F.Cu" "B.Cu")
		(net "P3V3_STBY")
	)
	(via
		(at 405.8666 -93.98)
		(size 0.508)
		(drill 0.254)
		(layers "F.Cu" "B.Cu")
		(net "P3V3_STBY")
	)
	(via
		(at 348.361 -16.0528)
		(size 0.508)
		(drill 0.254)
		(layers "F.Cu" "B.Cu")
		(net "P3V3_STBY")
	)
	(via
		(at 419.859714 -81.620614)
		(size 0.508)
		(drill 0.254)
		(layers "F.Cu" "B.Cu")
		(net "P3V3_STBY")
	)
	(via
		(at 440.182 -141.478)
		(size 0.508)
		(drill 0.254)
		(layers "F.Cu" "B.Cu")
		(net "P3V3_STBY")
	)
	(via
		(at 361.259374 -56.255666)
		(size 0.508)
		(drill 0.254)
		(layers "F.Cu" "B.Cu")
		(net "P3V3_STBY")
	)
	(via
		(at 421.003476 -74.375264)
		(size 0.508)
		(drill 0.254)
		(layers "F.Cu" "B.Cu")
		(net "P3V3_STBY")
	)
	(via
		(at 371.925342 -101.002592)
		(size 0.508)
		(drill 0.254)
		(layers "F.Cu" "B.Cu")
		(net "P3V3_STBY")
	)
	(via
		(at 431.00498 -21.867622)
		(size 0.508)
		(drill 0.254)
		(layers "F.Cu" "B.Cu")
		(net "P3V3_STBY")
	)
	(via
		(at 371.145308 -75.094846)
		(size 0.4572)
		(drill 0.2032)
		(layers "F.Cu" "B.Cu")
		(net "P3V3_STBY")
	)
	(via
		(at 38.2651 -104.10444)
		(size 0.508)
		(drill 0.254)
		(layers "F.Cu" "B.Cu")
		(net "P3V3_STBY")
	)
	(via
		(at 398.15008 -33.871916)
		(size 0.508)
		(drill 0.254)
		(layers "F.Cu" "B.Cu")
		(net "P3V3_STBY")
	)
	(via
		(at 454.258934 -2.062988)
		(size 0.508)
		(drill 0.254)
		(layers "F.Cu" "B.Cu")
		(net "P3V3_STBY")
	)
	(via
		(at 389.533384 -69.470016)
		(size 0.508)
		(drill 0.254)
		(layers "F.Cu" "B.Cu")
		(net "P3V3_STBY")
	)
	(via
		(at 403.98573 -54.48935)
		(size 0.508)
		(drill 0.254)
		(layers "F.Cu" "B.Cu")
		(net "P3V3_STBY")
	)
	(via
		(at 411.49016 -34.134552)
		(size 0.4572)
		(drill 0.2032)
		(layers "F.Cu" "B.Cu")
		(net "P3V3_STBY")
	)
	(via
		(at 382.1176 -5.1562)
		(size 0.508)
		(drill 0.254)
		(layers "F.Cu" "B.Cu")
		(net "P3V3_STBY")
	)
	(via
		(at 368.745262 -71.095108)
		(size 0.4572)
		(drill 0.2032)
		(layers "F.Cu" "B.Cu")
		(net "P3V3_STBY")
	)
	(via
		(at 473.542106 -129.42824)
		(size 0.508)
		(drill 0.254)
		(layers "F.Cu" "B.Cu")
		(net "P3V3_STBY")
	)
	(via
		(at 367.8047 -95.2373)
		(size 0.508)
		(drill 0.254)
		(layers "F.Cu" "B.Cu")
		(net "P3V3_STBY")
	)
	(via
		(at 463.78622 -13.4366)
		(size 0.5588)
		(drill 0.3048)
		(layers "F.Cu" "B.Cu")
		(net "P3V3_STBY")
	)
	(via
		(at 423.291 -2.667)
		(size 0.508)
		(drill 0.254)
		(layers "F.Cu" "B.Cu")
		(net "P3V3_STBY")
	)
	(via
		(at 416.1917 -1.8288)
		(size 0.508)
		(drill 0.254)
		(layers "F.Cu" "B.Cu")
		(net "P3V3_STBY")
	)
	(via
		(at 347.3958 -21.9583)
		(size 0.508)
		(drill 0.254)
		(layers "F.Cu" "B.Cu")
		(net "P3V3_STBY")
	)
	(via
		(at 404.483062 -2.159508)
		(size 0.508)
		(drill 0.254)
		(layers "F.Cu" "B.Cu")
		(net "P3V3_STBY")
	)
	(via
		(at 178.943 -64.135)
		(size 0.508)
		(drill 0.254)
		(layers "F.Cu" "B.Cu")
		(net "P3V3_STBY")
	)
	(via
		(at 448.265042 -155.8544)
		(size 0.508)
		(drill 0.254)
		(layers "F.Cu" "B.Cu")
		(net "P3V3_STBY")
	)
	(via
		(at 470.574116 -41.814496)
		(size 0.5588)
		(drill 0.3048)
		(layers "F.Cu" "B.Cu")
		(net "P3V3_STBY")
	)
	(via
		(at 464.41106 -42.0624)
		(size 0.5588)
		(drill 0.3048)
		(layers "F.Cu" "B.Cu")
		(net "P3V3_STBY")
	)
	(via
		(at 419.2524 -47.3202)
		(size 0.508)
		(drill 0.254)
		(layers "F.Cu" "B.Cu")
		(net "P3V3_STBY")
	)
	(via
		(at 456.311 -30.48)
		(size 0.508)
		(drill 0.254)
		(layers "F.Cu" "B.Cu")
		(net "P3V3_STBY")
	)
	(via
		(at 404.101046 -24.8539)
		(size 0.508)
		(drill 0.254)
		(layers "F.Cu" "B.Cu")
		(net "P3V3_STBY")
	)
	(via
		(at 491.5662 -114.4524)
		(size 0.508)
		(drill 0.254)
		(layers "F.Cu" "B.Cu")
		(net "P3V3_STBY")
	)
	(via
		(at 368.64671 -43.260772)
		(size 0.508)
		(drill 0.254)
		(layers "F.Cu" "B.Cu")
		(net "P3V3_STBY")
	)
	(via
		(at 385.887722 -48.673258)
		(size 0.508)
		(drill 0.254)
		(layers "F.Cu" "B.Cu")
		(net "P3V3_STBY")
	)
	(via
		(at 402.711666 -80.41894)
		(size 0.508)
		(drill 0.254)
		(layers "F.Cu" "B.Cu")
		(net "P3V3_STBY")
	)
	(via
		(at 447.69913 -146.352514)
		(size 0.508)
		(drill 0.254)
		(layers "F.Cu" "B.Cu")
		(net "P3V3_STBY")
	)
	(via
		(at 409.356052 -115.521486)
		(size 0.508)
		(drill 0.254)
		(layers "F.Cu" "B.Cu")
		(net "P3V3_STBY")
	)
	(via
		(at 433.646072 -19.727672)
		(size 0.508)
		(drill 0.254)
		(layers "F.Cu" "B.Cu")
		(net "P3V3_STBY")
	)
	(via
		(at 389.22325 -103.615236)
		(size 0.508)
		(drill 0.254)
		(layers "F.Cu" "B.Cu")
		(net "P3V3_STBY")
	)
	(via
		(at 460.925418 -22.064472)
		(size 0.5588)
		(drill 0.3048)
		(layers "F.Cu" "B.Cu")
		(net "P3V3_STBY")
	)
	(via
		(at 390.21385 -103.615236)
		(size 0.508)
		(drill 0.254)
		(layers "F.Cu" "B.Cu")
		(net "P3V3_STBY")
	)
	(via
		(at 435.0004 -11.7094)
		(size 0.508)
		(drill 0.254)
		(layers "F.Cu" "B.Cu")
		(net "P3V3_STBY")
	)
	(via
		(at 461.098392 -36.432998)
		(size 0.508)
		(drill 0.254)
		(layers "F.Cu" "B.Cu")
		(net "P3V3_STBY")
	)
	(via
		(at 373.544846 -72.695308)
		(size 0.4572)
		(drill 0.2032)
		(layers "F.Cu" "B.Cu")
		(net "P3V3_STBY")
	)
	(via
		(at 366.344962 -67.894962)
		(size 0.4572)
		(drill 0.2032)
		(layers "F.Cu" "B.Cu")
		(net "P3V3_STBY")
	)
	(via
		(at 22.991572 -98.762312)
		(size 0.508)
		(drill 0.254)
		(layers "F.Cu" "B.Cu")
		(net "P3V3_STBY")
	)
	(via
		(at 463.40014 -14.73962)
		(size 0.5588)
		(drill 0.3048)
		(layers "F.Cu" "B.Cu")
		(net "P3V3_STBY")
	)
	(via
		(at 175.29302 -70.45452)
		(size 0.508)
		(drill 0.254)
		(layers "F.Cu" "B.Cu")
		(net "P3V3_STBY")
	)
	(via
		(at 446.6717 -153.5049)
		(size 0.508)
		(drill 0.254)
		(layers "F.Cu" "B.Cu")
		(net "P3V3_STBY")
	)
	(via
		(at 418.0078 -54.3687)
		(size 0.508)
		(drill 0.254)
		(layers "F.Cu" "B.Cu")
		(net "P3V3_STBY")
	)
	(via
		(at 411.780228 -108.481114)
		(size 0.508)
		(drill 0.254)
		(layers "F.Cu" "B.Cu")
		(net "P3V3_STBY")
	)
	(via
		(at 483.0318 -120.0404)
		(size 0.508)
		(drill 0.254)
		(layers "F.Cu" "B.Cu")
		(net "P3V3_STBY")
	)
	(via
		(at 478.142808 -49.755552)
		(size 0.508)
		(drill 0.254)
		(layers "F.Cu" "B.Cu")
		(net "P3V3_STBY")
	)
	(via
		(at 413.890206 -38.934644)
		(size 0.4572)
		(drill 0.2032)
		(layers "F.Cu" "B.Cu")
		(net "P3V3_STBY")
	)
	(via
		(at 40.096948 -105.667048)
		(size 0.508)
		(drill 0.254)
		(layers "F.Cu" "B.Cu")
		(net "P3V3_STBY")
	)
	(via
		(at 15.24889 -1.907032)
		(size 0.508)
		(drill 0.254)
		(layers "F.Cu" "B.Cu")
		(net "P3V3_STBY")
	)
	(via
		(at 371.945154 -75.894692)
		(size 0.4572)
		(drill 0.2032)
		(layers "F.Cu" "B.Cu")
		(net "P3V3_STBY")
	)
	(via
		(at 408.457146 -50.06975)
		(size 0.5588)
		(drill 0.3048)
		(layers "F.Cu" "B.Cu")
		(net "P3V3_STBY")
	)
	(via
		(at 376.936 -65.405)
		(size 0.508)
		(drill 0.254)
		(layers "F.Cu" "B.Cu")
		(net "P3V3_STBY")
	)
	(via
		(at 416.01898 -50.184558)
		(size 0.508)
		(drill 0.254)
		(layers "F.Cu" "B.Cu")
		(net "P3V3_STBY")
	)
	(via
		(at 371.145308 -75.894692)
		(size 0.4572)
		(drill 0.2032)
		(layers "F.Cu" "B.Cu")
		(net "P3V3_STBY")
	)
	(via
		(at 463.089752 -20.305522)
		(size 0.5588)
		(drill 0.3048)
		(layers "F.Cu" "B.Cu")
		(net "P3V3_STBY")
	)
	(via
		(at 384.290316 -103.543862)
		(size 0.508)
		(drill 0.254)
		(layers "F.Cu" "B.Cu")
		(net "P3V3_STBY")
	)
	(via
		(at 459.553818 -24.096472)
		(size 0.5588)
		(drill 0.3048)
		(layers "F.Cu" "B.Cu")
		(net "P3V3_STBY")
	)
	(via
		(at 374.344692 -75.094846)
		(size 0.4572)
		(drill 0.2032)
		(layers "F.Cu" "B.Cu")
		(net "P3V3_STBY")
	)
	(via
		(at 446.170812 -149.032722)
		(size 0.508)
		(drill 0.254)
		(layers "F.Cu" "B.Cu")
		(net "P3V3_STBY")
	)
	(via
		(at 409.4734 -113.284)
		(size 0.508)
		(drill 0.254)
		(layers "F.Cu" "B.Cu")
		(net "P3V3_STBY")
	)
	(via
		(at 488.570016 -150.495)
		(size 0.508)
		(drill 0.254)
		(layers "F.Cu" "B.Cu")
		(net "P3V3_STBY")
	)
	(via
		(at 448.853814 -141.097)
		(size 0.508)
		(drill 0.254)
		(layers "F.Cu" "B.Cu")
		(net "P3V3_STBY")
	)
	(via
		(at 465.19084 -17.9324)
		(size 0.5588)
		(drill 0.3048)
		(layers "F.Cu" "B.Cu")
		(net "P3V3_STBY")
	)
	(via
		(at 371.526816 -64.63538)
		(size 0.508)
		(drill 0.254)
		(layers "F.Cu" "B.Cu")
		(net "P3V3_STBY")
	)
	(via
		(at 464.727544 -6.77672)
		(size 0.508)
		(drill 0.254)
		(layers "F.Cu" "B.Cu")
		(net "P3V3_STBY")
	)
	(via
		(at 434.34 -151.257)
		(size 0.508)
		(drill 0.254)
		(layers "F.Cu" "B.Cu")
		(net "P3V3_STBY")
	)
	(via
		(at 468.733378 -135.427212)
		(size 0.508)
		(drill 0.254)
		(layers "F.Cu" "B.Cu")
		(net "P3V3_STBY")
	)
	(via
		(at 389.9662 -19.93646)
		(size 0.508)
		(drill 0.254)
		(layers "F.Cu" "B.Cu")
		(net "P3V3_STBY")
	)
	(via
		(at 342.8492 -116.3828)
		(size 0.508)
		(drill 0.254)
		(layers "F.Cu" "B.Cu")
		(net "P3V3_STBY")
	)
	(via
		(at 434.594 -14.10335)
		(size 0.508)
		(drill 0.254)
		(layers "F.Cu" "B.Cu")
		(net "P3V3_STBY")
	)
	(via
		(at 258.79171 -88.775286)
		(size 0.508)
		(drill 0.254)
		(layers "F.Cu" "B.Cu")
		(net "P3V3_STBY")
	)
	(via
		(at 362.839 -132.334)
		(size 0.508)
		(drill 0.254)
		(layers "F.Cu" "B.Cu")
		(net "P3V3_STBY")
	)
	(via
		(at 460.925418 -22.724872)
		(size 0.5588)
		(drill 0.3048)
		(layers "F.Cu" "B.Cu")
		(net "P3V3_STBY")
	)
	(via
		(at 459.553818 -23.410672)
		(size 0.5588)
		(drill 0.3048)
		(layers "F.Cu" "B.Cu")
		(net "P3V3_STBY")
	)
	(via
		(at -3.7592 -133.6294)
		(size 0.508)
		(drill 0.254)
		(layers "F.Cu" "B.Cu")
		(net "P3V3_STBY")
	)
	(via
		(at 369.7224 -64.725804)
		(size 0.508)
		(drill 0.254)
		(layers "F.Cu" "B.Cu")
		(net "P3V3_STBY")
	)
	(via
		(at 498.7036 -35.8394)
		(size 0.508)
		(drill 0.254)
		(layers "F.Cu" "B.Cu")
		(net "P3V3_STBY")
	)
	(via
		(at 411.49016 -32.534606)
		(size 0.4572)
		(drill 0.2032)
		(layers "F.Cu" "B.Cu")
		(net "P3V3_STBY")
	)
	(via
		(at 499.6688 -132.4864)
		(size 0.508)
		(drill 0.254)
		(layers "F.Cu" "B.Cu")
		(net "P3V3_STBY")
	)
	(via
		(at 179.832 -6.7564)
		(size 0.508)
		(drill 0.254)
		(layers "F.Cu" "B.Cu")
		(net "P3V3_STBY")
	)
	(via
		(at 375.944892 -70.295262)
		(size 0.4572)
		(drill 0.2032)
		(layers "F.Cu" "B.Cu")
		(net "P3V3_STBY")
	)
	(via
		(at 435.3306 -22.3266)
		(size 0.508)
		(drill 0.254)
		(layers "F.Cu" "B.Cu")
		(net "P3V3_STBY")
	)
	(via
		(at 498.626638 -139.954)
		(size 0.508)
		(drill 0.254)
		(layers "F.Cu" "B.Cu")
		(net "P3V3_STBY")
	)
	(via
		(at 403.6568 -30.9372)
		(size 0.508)
		(drill 0.254)
		(layers "F.Cu" "B.Cu")
		(net "P3V3_STBY")
	)
	(via
		(at 369.545108 -78.294738)
		(size 0.4572)
		(drill 0.2032)
		(layers "F.Cu" "B.Cu")
		(net "P3V3_STBY")
	)
	(via
		(at 483.799896 -113.77422)
		(size 0.508)
		(drill 0.254)
		(layers "F.Cu" "B.Cu")
		(net "P3V3_STBY")
	)
	(via
		(at 421.152828 -49.605692)
		(size 0.508)
		(drill 0.254)
		(layers "F.Cu" "B.Cu")
		(net "P3V3_STBY")
	)
	(via
		(at 440.40552 -59.13374)
		(size 0.508)
		(drill 0.254)
		(layers "F.Cu" "B.Cu")
		(net "P3V3_STBY")
	)
	(via
		(at 379.144784 -79.894684)
		(size 0.4572)
		(drill 0.2032)
		(layers "F.Cu" "B.Cu")
		(net "P3V3_STBY")
	)
	(via
		(at 450.013578 -21.971)
		(size 0.508)
		(drill 0.254)
		(layers "F.Cu" "B.Cu")
		(net "P3V3_STBY")
	)
	(via
		(at 175.21555 -124.90577)
		(size 0.508)
		(drill 0.254)
		(layers "F.Cu" "B.Cu")
		(net "P3V3_STBY")
	)
	(via
		(at 434.34 -152.4)
		(size 0.508)
		(drill 0.254)
		(layers "F.Cu" "B.Cu")
		(net "P3V3_STBY")
	)
	(via
		(at 454.025 -39.41318)
		(size 0.508)
		(drill 0.254)
		(layers "F.Cu" "B.Cu")
		(net "P3V3_STBY")
	)
	(via
		(at 392.1379 -113.0554)
		(size 0.508)
		(drill 0.254)
		(layers "F.Cu" "B.Cu")
		(net "P3V3_STBY")
	)
	(via
		(at 481.7618 -120.0404)
		(size 0.508)
		(drill 0.254)
		(layers "F.Cu" "B.Cu")
		(net "P3V3_STBY")
	)
	(via
		(at 374.344692 -72.695308)
		(size 0.4572)
		(drill 0.2032)
		(layers "F.Cu" "B.Cu")
		(net "P3V3_STBY")
	)
	(via
		(at 472.104974 -144.294098)
		(size 0.508)
		(drill 0.254)
		(layers "F.Cu" "B.Cu")
		(net "P3V3_STBY")
	)
	(via
		(at 412.0134 -101.7524)
		(size 0.508)
		(drill 0.254)
		(layers "F.Cu" "B.Cu")
		(net "P3V3_STBY")
	)
	(via
		(at 379.993652 -39.174166)
		(size 0.508)
		(drill 0.254)
		(layers "F.Cu" "B.Cu")
		(net "P3V3_STBY")
	)
	(via
		(at 13.8176 -86.4362)
		(size 0.508)
		(drill 0.254)
		(layers "F.Cu" "B.Cu")
		(net "P3V3_STBY")
	)
	(via
		(at 459.959202 -142.401798)
		(size 0.508)
		(drill 0.254)
		(layers "F.Cu" "B.Cu")
		(net "P3V3_STBY")
	)
	(via
		(at 477.2152 -10.974578)
		(size 0.508)
		(drill 0.254)
		(layers "F.Cu" "B.Cu")
		(net "P3V3_STBY")
	)
	(via
		(at 23.345902 -30.814772)
		(size 0.508)
		(drill 0.254)
		(layers "F.Cu" "B.Cu")
		(net "P3V3_STBY")
	)
	(via
		(at 174.5996 -104.4448)
		(size 0.508)
		(drill 0.254)
		(layers "F.Cu" "B.Cu")
		(net "P3V3_STBY")
	)
	(via
		(at 406.79116 -149.553422)
		(size 0.508)
		(drill 0.254)
		(layers "F.Cu" "B.Cu")
		(net "P3V3_STBY")
	)
	(via
		(at 411.745176 -110.074456)
		(size 0.508)
		(drill 0.254)
		(layers "F.Cu" "B.Cu")
		(net "P3V3_STBY")
	)
	(via
		(at 494.557812 -35.3822)
		(size 0.508)
		(drill 0.254)
		(layers "F.Cu" "B.Cu")
		(net "P3V3_STBY")
	)
	(via
		(at 385.7371 -105.8545)
		(size 0.508)
		(drill 0.254)
		(layers "F.Cu" "B.Cu")
		(net "P3V3_STBY")
	)
	(via
		(at 432.4096 -49.1363)
		(size 0.508)
		(drill 0.254)
		(layers "F.Cu" "B.Cu")
		(net "P3V3_STBY")
	)
	(via
		(at 408.559 0.9144)
		(size 0.508)
		(drill 0.254)
		(layers "F.Cu" "B.Cu")
		(net "P3V3_STBY")
	)
	(via
		(at 413.302958 -66.107818)
		(size 0.508)
		(drill 0.254)
		(layers "F.Cu" "B.Cu")
		(net "P3V3_STBY")
	)
	(via
		(at 438.124346 -148.525992)
		(size 0.508)
		(drill 0.254)
		(layers "F.Cu" "B.Cu")
		(net "P3V3_STBY")
	)
	(via
		(at 465.328 -42.1132)
		(size 0.5588)
		(drill 0.3048)
		(layers "F.Cu" "B.Cu")
		(net "P3V3_STBY")
	)
	(via
		(at 461.0608 -127.381)
		(size 0.508)
		(drill 0.254)
		(layers "F.Cu" "B.Cu")
		(net "P3V3_STBY")
	)
	(via
		(at 434.34 -153.543)
		(size 0.508)
		(drill 0.254)
		(layers "F.Cu" "B.Cu")
		(net "P3V3_STBY")
	)
	(via
		(at 375.944892 -78.294738)
		(size 0.4572)
		(drill 0.2032)
		(layers "F.Cu" "B.Cu")
		(net "P3V3_STBY")
	)
	(via
		(at 0.381 -74.93)
		(size 0.508)
		(drill 0.254)
		(layers "F.Cu" "B.Cu")
		(net "P3V3_STBY")
	)
	(via
		(at 178.0032 -66.3702)
		(size 0.508)
		(drill 0.254)
		(layers "F.Cu" "B.Cu")
		(net "P3V3_STBY")
	)
	(via
		(at 422.737534 -49.591976)
		(size 0.508)
		(drill 0.254)
		(layers "F.Cu" "B.Cu")
		(net "P3V3_STBY")
	)
	(via
		(at 445.238632 -2.408174)
		(size 0.508)
		(drill 0.254)
		(layers "F.Cu" "B.Cu")
		(net "P3V3_STBY")
	)
	(via
		(at 501.225312 -37.414962)
		(size 0.508)
		(drill 0.254)
		(layers "F.Cu" "B.Cu")
		(net "P3V3_STBY")
	)
	(via
		(at 352.6663 -84.1375)
		(size 0.508)
		(drill 0.254)
		(layers "F.Cu" "B.Cu")
		(net "P3V3_STBY")
	)
	(via
		(at 418.680646 -46.298104)
		(size 0.508)
		(drill 0.254)
		(layers "F.Cu" "B.Cu")
		(net "P3V3_STBY")
	)
	(via
		(at 26.5684 -80.416908)
		(size 0.508)
		(drill 0.254)
		(layers "F.Cu" "B.Cu")
		(net "P3V3_STBY")
	)
	(via
		(at 374.751854 -53.344318)
		(size 0.508)
		(drill 0.254)
		(layers "F.Cu" "B.Cu")
		(net "P3V3_STBY")
	)
	(via
		(at 446.532 -63.5)
		(size 0.5588)
		(drill 0.3048)
		(layers "F.Cu" "B.Cu")
		(net "P3V3_STBY")
	)
	(via
		(at 427.328584 -18.883376)
		(size 0.508)
		(drill 0.254)
		(layers "F.Cu" "B.Cu")
		(net "P3V3_STBY")
	)
	(via
		(at 462.39557 -19.641566)
		(size 0.5588)
		(drill 0.3048)
		(layers "F.Cu" "B.Cu")
		(net "P3V3_STBY")
	)
	(via
		(at 394.67155 -113.519204)
		(size 0.508)
		(drill 0.254)
		(layers "F.Cu" "B.Cu")
		(net "P3V3_STBY")
	)
	(via
		(at 13.9446 -98.9076)
		(size 0.508)
		(drill 0.254)
		(layers "F.Cu" "B.Cu")
		(net "P3V3_STBY")
	)
	(via
		(at 366.344962 -75.894946)
		(size 0.4572)
		(drill 0.2032)
		(layers "F.Cu" "B.Cu")
		(net "P3V3_STBY")
	)
	(via
		(at 387.24205 -103.536496)
		(size 0.508)
		(drill 0.254)
		(layers "F.Cu" "B.Cu")
		(net "P3V3_STBY")
	)
	(via
		(at 492.252 -151.71928)
		(size 0.508)
		(drill 0.254)
		(layers "F.Cu" "B.Cu")
		(net "P3V3_STBY")
	)
	(via
		(at 472.059 -137.16)
		(size 0.508)
		(drill 0.254)
		(layers "F.Cu" "B.Cu")
		(net "P3V3_STBY")
	)
	(via
		(at 185.842148 -62.919864)
		(size 0.508)
		(drill 0.254)
		(layers "F.Cu" "B.Cu")
		(net "P3V3_STBY")
	)
	(via
		(at 394.67155 -104.473756)
		(size 0.508)
		(drill 0.254)
		(layers "F.Cu" "B.Cu")
		(net "P3V3_STBY")
	)
	(via
		(at 414.075626 -113.284)
		(size 0.508)
		(drill 0.254)
		(layers "F.Cu" "B.Cu")
		(net "P3V3_STBY")
	)
	(via
		(at 377.09348 -86.144608)
		(size 0.508)
		(drill 0.254)
		(layers "F.Cu" "B.Cu")
		(net "P3V3_STBY")
	)
	(via
		(at 492.924338 -41.0464)
		(size 0.508)
		(drill 0.254)
		(layers "F.Cu" "B.Cu")
		(net "P3V3_STBY")
	)
	(via
		(at 465.074 4.1402)
		(size 0.508)
		(drill 0.254)
		(layers "F.Cu" "B.Cu")
		(net "P3V3_STBY")
	)
	(via
		(at 371.145308 -72.695308)
		(size 0.4572)
		(drill 0.2032)
		(layers "F.Cu" "B.Cu")
		(net "P3V3_STBY")
	)
	(via
		(at 179.959 -130.175)
		(size 0.508)
		(drill 0.254)
		(layers "F.Cu" "B.Cu")
		(net "P3V3_STBY")
	)
	(via
		(at 481.812346 -141.67866)
		(size 0.508)
		(drill 0.254)
		(layers "F.Cu" "B.Cu")
		(net "P3V3_STBY")
	)
	(via
		(at 390.755124 -83.859878)
		(size 0.508)
		(drill 0.254)
		(layers "F.Cu" "B.Cu")
		(net "P3V3_STBY")
	)
	(via
		(at 378.755656 -21.062442)
		(size 0.508)
		(drill 0.254)
		(layers "F.Cu" "B.Cu")
		(net "P3V3_STBY")
	)
	(via
		(at 464.0326 -14.351)
		(size 0.5588)
		(drill 0.3048)
		(layers "F.Cu" "B.Cu")
		(net "P3V3_STBY")
	)
	(via
		(at 417.248848 -86.956138)
		(size 0.508)
		(drill 0.254)
		(layers "F.Cu" "B.Cu")
		(net "P3V3_STBY")
	)
	(via
		(at 401.2946 -153.9367)
		(size 0.508)
		(drill 0.254)
		(layers "F.Cu" "B.Cu")
		(net "P3V3_STBY")
	)
	(via
		(at 343.281 -21.082)
		(size 0.508)
		(drill 0.254)
		(layers "F.Cu" "B.Cu")
		(net "P3V3_STBY")
	)
	(via
		(at 493.713008 -34.937192)
		(size 0.508)
		(drill 0.254)
		(layers "F.Cu" "B.Cu")
		(net "P3V3_STBY")
	)
	(via
		(at 463.34172 -17.64284)
		(size 0.5588)
		(drill 0.3048)
		(layers "F.Cu" "B.Cu")
		(net "P3V3_STBY")
	)
	(via
		(at 459.553818 -22.724872)
		(size 0.5588)
		(drill 0.3048)
		(layers "F.Cu" "B.Cu")
		(net "P3V3_STBY")
	)
	(via
		(at 466.5726 -42.1132)
		(size 0.508)
		(drill 0.254)
		(layers "F.Cu" "B.Cu")
		(net "P3V3_STBY")
	)
	(via
		(at 324.658482 -58.899044)
		(size 0.508)
		(drill 0.254)
		(layers "F.Cu" "B.Cu")
		(net "P3V3_STBY")
	)
	(via
		(at 492.3282 -123.5075)
		(size 0.508)
		(drill 0.254)
		(layers "F.Cu" "B.Cu")
		(net "P3V3_STBY")
	)
	(via
		(at -3.60426 -120.35536)
		(size 0.508)
		(drill 0.254)
		(layers "F.Cu" "B.Cu")
		(net "P3V3_STBY")
	)
	(via
		(at 172.101002 -92.835984)
		(size 0.508)
		(drill 0.254)
		(layers "F.Cu" "B.Cu")
		(net "P3V3_STBY")
	)
	(via
		(at 486.683812 4.157472)
		(size 0.508)
		(drill 0.254)
		(layers "F.Cu" "B.Cu")
		(net "P3V3_STBY")
	)
	(via
		(at 181.34838 -78.32344)
		(size 0.508)
		(drill 0.254)
		(layers "F.Cu" "B.Cu")
		(net "P3V3_STBY")
	)
	(via
		(at 470.4715 -139.1666)
		(size 0.508)
		(drill 0.254)
		(layers "F.Cu" "B.Cu")
		(net "P3V3_STBY")
	)
	(via
		(at 465.850986 -17.907254)
		(size 0.5588)
		(drill 0.3048)
		(layers "F.Cu" "B.Cu")
		(net "P3V3_STBY")
	)
	(via
		(at 459.553818 -22.064472)
		(size 0.5588)
		(drill 0.3048)
		(layers "F.Cu" "B.Cu")
		(net "P3V3_STBY")
	)
	(via
		(at 455.7014 -132.5626)
		(size 0.508)
		(drill 0.254)
		(layers "F.Cu" "B.Cu")
		(net "P3V3_STBY")
	)
	(via
		(at 367.164112 -80.714088)
		(size 0.4572)
		(drill 0.2032)
		(layers "F.Cu" "B.Cu")
		(net "P3V3_STBY")
	)
	(via
		(at 402.635466 -151.613108)
		(size 0.508)
		(drill 0.254)
		(layers "F.Cu" "B.Cu")
		(net "P3V3_STBY")
	)
	(via
		(at 391.858754 -61.081158)
		(size 0.508)
		(drill 0.254)
		(layers "F.Cu" "B.Cu")
		(net "P3V3_STBY")
	)
	(via
		(at 163.2712 -67.056)
		(size 0.508)
		(drill 0.254)
		(layers "F.Cu" "B.Cu")
		(net "P3V3_STBY")
	)
	(via
		(at 19.75866 -30.74162)
		(size 0.508)
		(drill 0.254)
		(layers "F.Cu" "B.Cu")
		(net "P3V3_STBY")
	)
	(via
		(at 409.300172 -107.434634)
		(size 0.508)
		(drill 0.254)
		(layers "F.Cu" "B.Cu")
		(net "P3V3_STBY")
	)
	(via
		(at 411.822138 -105.485438)
		(size 0.508)
		(drill 0.254)
		(layers "F.Cu" "B.Cu")
		(net "P3V3_STBY")
	)
	(via
		(at 336.8802 -86.692486)
		(size 0.508)
		(drill 0.254)
		(layers "F.Cu" "B.Cu")
		(net "P3V3_STBY")
	)
	(via
		(at 391.3378 -105.0544)
		(size 0.508)
		(drill 0.254)
		(layers "F.Cu" "B.Cu")
		(net "P3V3_STBY")
	)
	(via
		(at 462.403952 -20.305522)
		(size 0.5588)
		(drill 0.3048)
		(layers "F.Cu" "B.Cu")
		(net "P3V3_STBY")
	)
	(via
		(at -4.61264 -132.742686)
		(size 0.508)
		(drill 0.254)
		(layers "F.Cu" "B.Cu")
		(net "P3V3_STBY")
	)
	(via
		(at 375.258838 -65.190878)
		(size 0.508)
		(drill 0.254)
		(layers "F.Cu" "B.Cu")
		(net "P3V3_STBY")
	)
	(via
		(at 481.1014 -120.0404)
		(size 0.508)
		(drill 0.254)
		(layers "F.Cu" "B.Cu")
		(net "P3V3_STBY")
	)
	(via
		(at 464.058 -24.0157)
		(size 0.508)
		(drill 0.254)
		(layers "F.Cu" "B.Cu")
		(net "P3V3_STBY")
	)
	(via
		(at 483.6668 -120.0658)
		(size 0.508)
		(drill 0.254)
		(layers "F.Cu" "B.Cu")
		(net "P3V3_STBY")
	)
	(via
		(at 13.306806 3.621532)
		(size 0.508)
		(drill 0.254)
		(layers "F.Cu" "B.Cu")
		(net "P3V3_STBY")
	)
	(via
		(at 481.1268 -119.4308)
		(size 0.508)
		(drill 0.254)
		(layers "F.Cu" "B.Cu")
		(net "P3V3_STBY")
	)
	(via
		(at 440.69 -157.734508)
		(size 0.508)
		(drill 0.254)
		(layers "F.Cu" "B.Cu")
		(net "P3V3_STBY")
	)
	(via
		(at 411.226 -9.779)
		(size 0.508)
		(drill 0.254)
		(layers "F.Cu" "B.Cu")
		(net "P3V3_STBY")
	)
	(segment
		(start 480.130866 -119.4308)
		(end 479.171 -120.390666)
		(width 0.254)
		(layer "B.Cu")
		(net "P3V3_STBY")
	)
	(segment
		(start 381.4826 -4.5212)
		(end 381.4826 -3.185414)
		(width 0.254)
		(layer "B.Cu")
		(net "P3V3_STBY")
	)
	(segment
		(start 394.208 -61.59627)
		(end 393.840462 -61.228732)
		(width 0.254)
		(layer "B.Cu")
		(net "P3V3_STBY")
	)
	(segment
		(start 381.49022 -79.38516)
		(end 381.23622 -79.63916)
		(width 0.254)
		(layer "B.Cu")
		(net "P3V3_STBY")
	)
	(segment
		(start 369.545108 -70.19671)
		(end 369.847622 -69.894196)
		(width 0.254)
		(layer "B.Cu")
		(net "P3V3_STBY")
	)
	(segment
		(start 2.869946 -87.278718)
		(end 3.514852 -87.923624)
		(width 0.254)
		(layer "B.Cu")
		(net "P3V3_STBY")
	)
	(segment
		(start 484.632 -48.5775)
		(end 485.267 -48.5775)
		(width 0.508)
		(layer "B.Cu")
		(net "P3V3_STBY")
	)
	(segment
		(start 374.84177 -95.136716)
		(end 374.35917 -94.654116)
		(width 0.254)
		(layer "B.Cu")
		(net "P3V3_STBY")
	)
	(segment
		(start 379.53696 -82.423)
		(end 380.1872 -82.423)
		(width 0.254)
		(layer "B.Cu")
		(net "P3V3_STBY")
	)
	(segment
		(start 481.812346 -141.67866)
		(end 482.24186 -141.67866)
		(width 0.254)
		(layer "B.Cu")
		(net "P3V3_STBY")
	)
	(segment
		(start 86.320884 -87.719916)
		(end 86.68639 -87.35441)
		(width 0.1524)
		(layer "B.Cu")
		(net "P3V3_STBY")
	)
	(segment
		(start 458.2414 -130.9624)
		(end 457.6064 -130.9624)
		(width 0.254)
		(layer "B.Cu")
		(net "P3V3_STBY")
	)
	(segment
		(start 177.548794 -66.860674)
		(end 177.5333 -66.876168)
		(width 0.254)
		(layer "B.Cu")
		(net "P3V3_STBY")
	)
	(segment
		(start 450.3674 -4.7498)
		(end 450.368162 -4.750562)
		(width 0.254)
		(layer "B.Cu")
		(net "P3V3_STBY")
	)
	(segment
		(start 489.684314 -44.562522)
		(end 488.708192 -43.5864)
		(width 0.254)
		(layer "B.Cu")
		(net "P3V3_STBY")
	)
	(segment
		(start 378.228606 -3.248406)
		(end 378.228606 -4.193794)
		(width 0.381)
		(layer "B.Cu")
		(net "P3V3_STBY")
	)
	(segment
		(start 421.3225 -6.1595)
		(end 421.3225 -6.589014)
		(width 0.4064)
		(layer "B.Cu")
		(net "P3V3_STBY")
	)
	(segment
		(start 396.113 -86.637368)
		(end 396.246096 -86.504272)
		(width 0.254)
		(layer "B.Cu")
		(net "P3V3_STBY")
	)
	(segment
		(start 390.135364 -84.371688)
		(end 390.135364 -84.713572)
		(width 0.254)
		(layer "B.Cu")
		(net "P3V3_STBY")
	)
	(segment
		(start 428.095664 -42.223436)
		(end 428.095664 -44.697396)
		(width 0.508)
		(layer "B.Cu")
		(net "P3V3_STBY")
	)
	(segment
		(start 381.4826 -2.870454)
		(end 381.5842 -2.768854)
		(width 0.254)
		(layer "B.Cu")
		(net "P3V3_STBY")
	)
	(segment
		(start 390.906 -84.010754)
		(end 390.906 -84.709)
		(width 0.254)
		(layer "B.Cu")
		(net "P3V3_STBY")
	)
	(segment
		(start 427.328584 -18.883376)
		(end 427.255432 -18.883376)
		(width 0.254)
		(layer "B.Cu")
		(net "P3V3_STBY")
	)
	(segment
		(start 368.559334 -38.513004)
		(end 367.903252 -37.856922)
		(width 0.254)
		(layer "B.Cu")
		(net "P3V3_STBY")
	)
	(segment
		(start 371.54485 -72.295004)
		(end 371.945154 -72.695308)
		(width 0.254)
		(layer "B.Cu")
		(net "P3V3_STBY")
	)
	(segment
		(start 367.538 -39.8272)
		(end 367.157 -39.8272)
		(width 0.254)
		(layer "B.Cu")
		(net "P3V3_STBY")
	)
	(segment
		(start 19.05 -45.94352)
		(end 19.05 -45.72)
		(width 0.254)
		(layer "B.Cu")
		(net "P3V3_STBY")
	)
	(segment
		(start 37.407596 -104.10444)
		(end 38.2651 -104.10444)
		(width 0.254)
		(layer "B.Cu")
		(net "P3V3_STBY")
	)
	(segment
		(start 488.98429 -29.3116)
		(end 489.478066 -29.3116)
		(width 0.381)
		(layer "B.Cu")
		(net "P3V3_STBY")
	)
	(segment
		(start 337.1596 -85.70722)
		(end 337.1596 -86.413086)
		(width 0.4064)
		(layer "B.Cu")
		(net "P3V3_STBY")
	)
	(segment
		(start 379.476 -20.342098)
		(end 378.755656 -21.062442)
		(width 0.254)
		(layer "B.Cu")
		(net "P3V3_STBY")
	)
	(segment
		(start 473.122498 -134.965694)
		(end 473.122498 -135.78459)
		(width 0.254)
		(layer "B.Cu")
		(net "P3V3_STBY")
	)
	(segment
		(start 400.798538 -39.5224)
		(end 401.5613 -39.5224)
		(width 0.508)
		(layer "B.Cu")
		(net "P3V3_STBY")
	)
	(segment
		(start 29.092652 -103.401368)
		(end 30.13202 -102.362)
		(width 0.254)
		(layer "B.Cu")
		(net "P3V3_STBY")
	)
	(segment
		(start 82.021934 -86.298786)
		(end 82.452464 -86.729316)
		(width 0.1524)
		(layer "B.Cu")
		(net "P3V3_STBY")
	)
	(segment
		(start 490.3724 -34.300414)
		(end 490.000798 -33.928812)
		(width 0.508)
		(layer "B.Cu")
		(net "P3V3_STBY")
	)
	(segment
		(start 487.62666 -30.226)
		(end 487.73588 -30.226)
		(width 0.381)
		(layer "B.Cu")
		(net "P3V3_STBY")
	)
	(segment
		(start 85.01507 -87.35441)
		(end 85.44687 -87.35441)
		(width 0.1524)
		(layer "B.Cu")
		(net "P3V3_STBY")
	)
	(segment
		(start 375.258838 -65.206372)
		(end 375.412 -65.359534)
		(width 0.254)
		(layer "B.Cu")
		(net "P3V3_STBY")
	)
	(segment
		(start 397.787622 -37.00907)
		(end 397.787622 -37.009578)
		(width 0.254)
		(layer "B.Cu")
		(net "P3V3_STBY")
	)
	(segment
		(start 376.744738 -77.400404)
		(end 376.744738 -77.494892)
		(width 0.254)
		(layer "B.Cu")
		(net "P3V3_STBY")
	)
	(segment
		(start 379.3998 -45.8216)
		(end 379.3998 -46.2026)
		(width 0.254)
		(layer "B.Cu")
		(net "P3V3_STBY")
	)
	(segment
		(start 404.5585 -97.917)
		(end 404.5585 -97.155)
		(width 0.508)
		(layer "B.Cu")
		(net "P3V3_STBY")
	)
	(segment
		(start 441.833 -148.49348)
		(end 442.663326 -147.663154)
		(width 0.254)
		(layer "B.Cu")
		(net "P3V3_STBY")
	)
	(segment
		(start 377.879864 -55.5371)
		(end 377.879864 -55.477664)
		(width 0.254)
		(layer "B.Cu")
		(net "P3V3_STBY")
	)
	(segment
		(start 409.146248 -10.834624)
		(end 408.443176 -10.834624)
		(width 0.508)
		(layer "B.Cu")
		(net "P3V3_STBY")
	)
	(segment
		(start 492.76762 -123.06808)
		(end 492.3282 -123.5075)
		(width 0.254)
		(layer "B.Cu")
		(net "P3V3_STBY")
	)
	(segment
		(start 374.4976 -53.8099)
		(end 374.751854 -53.555646)
		(width 0.254)
		(layer "B.Cu")
		(net "P3V3_STBY")
	)
	(segment
		(start 379.087126 -45.564298)
		(end 379.087634 -45.564298)
		(width 0.254)
		(layer "B.Cu")
		(net "P3V3_STBY")
	)
	(segment
		(start 12.095988 -86.008718)
		(end 12.986004 -86.008718)
		(width 0.254)
		(layer "B.Cu")
		(net "P3V3_STBY")
	)
	(segment
		(start 457.6064 -143.1036)
		(end 457.6064 -144.145)
		(width 0.381)
		(layer "B.Cu")
		(net "P3V3_STBY")
	)
	(segment
		(start 422.3004 -13.904976)
		(end 421.740076 -14.4653)
		(width 0.254)
		(layer "B.Cu")
		(net "P3V3_STBY")
	)
	(segment
		(start 482.8794 -49.3268)
		(end 483.0445 -49.1617)
		(width 0.508)
		(layer "B.Cu")
		(net "P3V3_STBY")
	)
	(segment
		(start 431.00498 -21.867622)
		(end 430.7332 -21.867622)
		(width 0.254)
		(layer "B.Cu")
		(net "P3V3_STBY")
	)
	(segment
		(start 439.801 -141.097)
		(end 440.182 -141.478)
		(width 0.254)
		(layer "B.Cu")
		(net "P3V3_STBY")
	)
	(segment
		(start 478.010982 -147.266914)
		(end 478.010982 -146.671538)
		(width 0.254)
		(layer "B.Cu")
		(net "P3V3_STBY")
	)
	(segment
		(start 269.92072 -91.847416)
		(end 269.92072 -91.538806)
		(width 0.1524)
		(layer "B.Cu")
		(net "P3V3_STBY")
	)
	(segment
		(start 372.351046 -75.4888)
		(end 371.945154 -75.894692)
		(width 0.254)
		(layer "B.Cu")
		(net "P3V3_STBY")
	)
	(segment
		(start 311.128664 -28.944824)
		(end 311.0738 -28.999688)
		(width 0.508)
		(layer "B.Cu")
		(net "P3V3_STBY")
	)
	(segment
		(start 367.157 -40.5892)
		(end 367.157 -39.8272)
		(width 0.254)
		(layer "B.Cu")
		(net "P3V3_STBY")
	)
	(segment
		(start 370.74348 -73.15327)
		(end 370.74348 -73.095358)
		(width 0.254)
		(layer "B.Cu")
		(net "P3V3_STBY")
	)
	(segment
		(start 393.840462 -61.228732)
		(end 392.796268 -61.228732)
		(width 0.254)
		(layer "B.Cu")
		(net "P3V3_STBY")
	)
	(segment
		(start 258.844796 -88.7222)
		(end 258.79171 -88.775286)
		(width 0.1524)
		(layer "B.Cu")
		(net "P3V3_STBY")
	)
	(segment
		(start 469.646 -134.7978)
		(end 469.133174 -134.7978)
		(width 0.254)
		(layer "B.Cu")
		(net "P3V3_STBY")
	)
	(segment
		(start 390.597136 -14.85011)
		(end 390.275318 -14.528292)
		(width 0.254)
		(layer "B.Cu")
		(net "P3V3_STBY")
	)
	(segment
		(start 404.483062 -1.524508)
		(end 404.483062 -2.159508)
		(width 0.254)
		(layer "B.Cu")
		(net "P3V3_STBY")
	)
	(segment
		(start 78.931008 -86.298786)
		(end 82.021934 -86.298786)
		(width 0.1524)
		(layer "B.Cu")
		(net "P3V3_STBY")
	)
	(segment
		(start 418.0078 -54.18709)
		(end 419.398196 -52.796694)
		(width 0.508)
		(layer "B.Cu")
		(net "P3V3_STBY")
	)
	(segment
		(start 369.145058 -77.096112)
		(end 369.03533 -77.096112)
		(width 0.254)
		(layer "B.Cu")
		(net "P3V3_STBY")
	)
	(segment
		(start 379.28296 -82.74812)
		(end 379.08992 -82.74812)
		(width 0.254)
		(layer "B.Cu")
		(net "P3V3_STBY")
	)
	(segment
		(start 447.3702 -155.8544)
		(end 448.265042 -155.8544)
		(width 0.254)
		(layer "B.Cu")
		(net "P3V3_STBY")
	)
	(segment
		(start 393.647676 -26.597102)
		(end 393.750292 -26.699718)
		(width 0.254)
		(layer "B.Cu")
		(net "P3V3_STBY")
	)
	(segment
		(start 395.478 -29.845)
		(end 396.240508 -29.845)
		(width 0.254)
		(layer "B.Cu")
		(net "P3V3_STBY")
	)
	(segment
		(start 384.683 -3.659632)
		(end 384.429 -3.405632)
		(width 0.254)
		(layer "B.Cu")
		(net "P3V3_STBY")
	)
	(segment
		(start 177.33899 -68.326508)
		(end 177.33899 -68.39839)
		(width 0.254)
		(layer "B.Cu")
		(net "P3V3_STBY")
	)
	(segment
		(start 87.9348 -87.757)
		(end 88.392762 -88.214962)
		(width 0.1524)
		(layer "B.Cu")
		(net "P3V3_STBY")
	)
	(segment
		(start 339.70722 -83.5914)
		(end 338.25688 -85.04174)
		(width 0.254)
		(layer "B.Cu")
		(net "P3V3_STBY")
	)
	(segment
		(start 367.903252 -37.856922)
		(end 367.646712 -37.856922)
		(width 0.254)
		(layer "B.Cu")
		(net "P3V3_STBY")
	)
	(segment
		(start 482.854 -31.369)
		(end 482.854 -32.512)
		(width 0.254)
		(layer "B.Cu")
		(net "P3V3_STBY")
	)
	(segment
		(start 409.702 0.2794)
		(end 408.559 0.2794)
		(width 0.254)
		(layer "B.Cu")
		(net "P3V3_STBY")
	)
	(segment
		(start 375.544842 -77.894434)
		(end 375.544842 -77.894688)
		(width 0.254)
		(layer "B.Cu")
		(net "P3V3_STBY")
	)
	(segment
		(start 267.49375 -89.33561)
		(end 266.998704 -88.840564)
		(width 0.1524)
		(layer "B.Cu")
		(net "P3V3_STBY")
	)
	(segment
		(start 457.542392 -135.394192)
		(end 457.2254 -135.0772)
		(width 0.254)
		(layer "B.Cu")
		(net "P3V3_STBY")
	)
	(segment
		(start 449.523358 -21.48078)
		(end 450.013578 -21.971)
		(width 0.508)
		(layer "B.Cu")
		(net "P3V3_STBY")
	)
	(segment
		(start 71.69531 -87.314532)
		(end 72.150478 -86.859364)
		(width 0.1524)
		(layer "B.Cu")
		(net "P3V3_STBY")
	)
	(segment
		(start 394.843 -27.92476)
		(end 394.35024 -27.92476)
		(width 0.254)
		(layer "B.Cu")
		(net "P3V3_STBY")
	)
	(segment
		(start 428.095664 -44.697396)
		(end 428.706026 -45.307758)
		(width 0.508)
		(layer "B.Cu")
		(net "P3V3_STBY")
	)
	(segment
		(start 414.032446 -39.735252)
		(end 414.032446 -39.076884)
		(width 0.4572)
		(layer "B.Cu")
		(net "P3V3_STBY")
	)
	(segment
		(start 379.74905 -68.498974)
		(end 379.74905 -68.707)
		(width 0.254)
		(layer "B.Cu")
		(net "P3V3_STBY")
	)
	(segment
		(start 394.95984 -37.578792)
		(end 394.95984 -37.0586)
		(width 0.254)
		(layer "B.Cu")
		(net "P3V3_STBY")
	)
	(segment
		(start 491.69066 -131.90982)
		(end 492.18342 -131.90982)
		(width 0.254)
		(layer "B.Cu")
		(net "P3V3_STBY")
	)
	(segment
		(start 411.2895 -11.000994)
		(end 409.312618 -11.000994)
		(width 0.508)
		(layer "B.Cu")
		(net "P3V3_STBY")
	)
	(segment
		(start 477.484948 -147.792948)
		(end 478.010982 -147.266914)
		(width 0.254)
		(layer "B.Cu")
		(net "P3V3_STBY")
	)
	(segment
		(start 473.91574 -135.16356)
		(end 473.91574 -135.41756)
		(width 0.254)
		(layer "B.Cu")
		(net "P3V3_STBY")
	)
	(segment
		(start 400.7358 -35.597846)
		(end 400.351498 -35.213544)
		(width 0.508)
		(layer "B.Cu")
		(net "P3V3_STBY")
	)
	(segment
		(start 379.000766 -46.2026)
		(end 379.3998 -46.2026)
		(width 0.254)
		(layer "B.Cu")
		(net "P3V3_STBY")
	)
	(segment
		(start 174.9044 -65.024)
		(end 174.954946 -64.973454)
		(width 0.254)
		(layer "B.Cu")
		(net "P3V3_STBY")
	)
	(segment
		(start 375.944892 -70.21195)
		(end 376.261376 -69.895466)
		(width 0.254)
		(layer "B.Cu")
		(net "P3V3_STBY")
	)
	(segment
		(start 411.5435 -33.401)
		(end 411.5435 -32.587946)
		(width 0.4572)
		(layer "B.Cu")
		(net "P3V3_STBY")
	)
	(segment
		(start 442.669168 -147.253452)
		(end 442.669168 -146.875754)
		(width 0.254)
		(layer "B.Cu")
		(net "P3V3_STBY")
	)
	(segment
		(start 268.36878 -90.62466)
		(end 267.9446 -90.20048)
		(width 0.1524)
		(layer "B.Cu")
		(net "P3V3_STBY")
	)
	(segment
		(start 459.3336 -143.0274)
		(end 458.597 -143.0274)
		(width 0.254)
		(layer "B.Cu")
		(net "P3V3_STBY")
	)
	(segment
		(start 430.7332 -21.867622)
		(end 430.4792 -22.121622)
		(width 0.254)
		(layer "B.Cu")
		(net "P3V3_STBY")
	)
	(segment
		(start 177.548794 -66.824606)
		(end 177.548794 -66.860674)
		(width 0.254)
		(layer "B.Cu")
		(net "P3V3_STBY")
	)
	(segment
		(start 474.14942 -134.92988)
		(end 473.91574 -135.16356)
		(width 0.254)
		(layer "B.Cu")
		(net "P3V3_STBY")
	)
	(segment
		(start 379.476 -19.304)
		(end 379.476 -20.193)
		(width 0.254)
		(layer "B.Cu")
		(net "P3V3_STBY")
	)
	(segment
		(start 486.3338 -35.56)
		(end 486.3338 -34.9504)
		(width 0.254)
		(layer "B.Cu")
		(net "P3V3_STBY")
	)
	(segment
		(start 474.229684 -136.144)
		(end 474.49994 -136.144)
		(width 0.254)
		(layer "B.Cu")
		(net "P3V3_STBY")
	)
	(segment
		(start 85.812376 -87.719916)
		(end 86.320884 -87.719916)
		(width 0.1524)
		(layer "B.Cu")
		(net "P3V3_STBY")
	)
	(segment
		(start 418.0078 -54.3687)
		(end 418.0078 -54.18709)
		(width 0.508)
		(layer "B.Cu")
		(net "P3V3_STBY")
	)
	(segment
		(start 78.819502 -86.410292)
		(end 78.931008 -86.298786)
		(width 0.1524)
		(layer "B.Cu")
		(net "P3V3_STBY")
	)
	(segment
		(start 401.472146 -40.598852)
		(end 401.472146 -41.360852)
		(width 0.508)
		(layer "B.Cu")
		(net "P3V3_STBY")
	)
	(segment
		(start 490.000798 -33.928812)
		(end 489.6993 -33.928812)
		(width 0.508)
		(layer "B.Cu")
		(net "P3V3_STBY")
	)
	(segment
		(start 390.275318 -14.528292)
		(end 389.867902 -14.528292)
		(width 0.254)
		(layer "B.Cu")
		(net "P3V3_STBY")
	)
	(segment
		(start 33.3248 -102.87)
		(end 36.173156 -102.87)
		(width 0.254)
		(layer "B.Cu")
		(net "P3V3_STBY")
	)
	(segment
		(start 169.4942 -128.016)
		(end 168.6052 -127.127)
		(width 0.254)
		(layer "B.Cu")
		(net "P3V3_STBY")
	)
	(segment
		(start 407.3652 -11.9126)
		(end 407.3652 -13.0683)
		(width 0.508)
		(layer "B.Cu")
		(net "P3V3_STBY")
	)
	(segment
		(start 88.392762 -88.214962)
		(end 88.835738 -88.214962)
		(width 0.1524)
		(layer "B.Cu")
		(net "P3V3_STBY")
	)
	(segment
		(start 484.886 -30.607)
		(end 483.616 -30.607)
		(width 0.254)
		(layer "B.Cu")
		(net "P3V3_STBY")
	)
	(segment
		(start 26.5684 -80.416908)
		(end 26.5684 -82.5246)
		(width 0.254)
		(layer "B.Cu")
		(net "P3V3_STBY")
	)
	(segment
		(start 417.677854 -51.02733)
		(end 417.677854 -50.748692)
		(width 0.254)
		(layer "B.Cu")
		(net "P3V3_STBY")
	)
	(segment
		(start 264.07618 -88.840564)
		(end 263.97331 -88.737694)
		(width 0.1524)
		(layer "B.Cu")
		(net "P3V3_STBY")
	)
	(segment
		(start 415.589974 -2.430526)
		(end 415.589974 -3.022854)
		(width 0.254)
		(layer "B.Cu")
		(net "P3V3_STBY")
	)
	(segment
		(start 461.0608 -127.381)
		(end 460.8322 -127.381)
		(width 0.254)
		(layer "B.Cu")
		(net "P3V3_STBY")
	)
	(segment
		(start 452.2978 -26.543)
		(end 452.2978 -27.048968)
		(width 0.508)
		(layer "B.Cu")
		(net "P3V3_STBY")
	)
	(segment
		(start 399.2372 -87.122508)
		(end 398.925796 -86.811104)
		(width 0.254)
		(layer "B.Cu")
		(net "P3V3_STBY")
	)
	(segment
		(start 386.865368 -3.659632)
		(end 384.683 -3.659632)
		(width 0.254)
		(layer "B.Cu")
		(net "P3V3_STBY")
	)
	(segment
		(start 420.414958 -15.494)
		(end 421.132 -15.494)
		(width 0.254)
		(layer "B.Cu")
		(net "P3V3_STBY")
	)
	(segment
		(start 484.5812 -48.5267)
		(end 484.632 -48.5775)
		(width 0.508)
		(layer "B.Cu")
		(net "P3V3_STBY")
	)
	(segment
		(start 260.796786 -88.24214)
		(end 260.37286 -88.24214)
		(width 0.1524)
		(layer "B.Cu")
		(net "P3V3_STBY")
	)
	(segment
		(start 473.660216 -144.289272)
		(end 472.1098 -144.289272)
		(width 0.254)
		(layer "B.Cu")
		(net "P3V3_STBY")
	)
	(segment
		(start 386.842 -87.3125)
		(end 387.604 -87.3125)
		(width 0.254)
		(layer "B.Cu")
		(net "P3V3_STBY")
	)
	(segment
		(start 400.351498 -35.213544)
		(end 400.351498 -34.782506)
		(width 0.508)
		(layer "B.Cu")
		(net "P3V3_STBY")
	)
	(segment
		(start 76.837032 -87.314532)
		(end 77.2922 -86.859364)
		(width 0.1524)
		(layer "B.Cu")
		(net "P3V3_STBY")
	)
	(segment
		(start 402.711666 -79.868776)
		(end 403.344634 -79.235808)
		(width 0.508)
		(layer "B.Cu")
		(net "P3V3_STBY")
	)
	(segment
		(start 490.78896 -34.7472)
		(end 490.3724 -34.33064)
		(width 0.508)
		(layer "B.Cu")
		(net "P3V3_STBY")
	)
	(segment
		(start 499.491 -138.557)
		(end 499.491 -139.8524)
		(width 0.254)
		(layer "B.Cu")
		(net "P3V3_STBY")
	)
	(segment
		(start 452.5772 -147.944078)
		(end 452.487792 -147.85467)
		(width 0.254)
		(layer "B.Cu")
		(net "P3V3_STBY")
	)
	(segment
		(start 417.821872 -54.3687)
		(end 415.629598 -56.560974)
		(width 0.508)
		(layer "B.Cu")
		(net "P3V3_STBY")
	)
	(segment
		(start 411.4165 -4.318)
		(end 411.4165 -4.497832)
		(width 0.254)
		(layer "B.Cu")
		(net "P3V3_STBY")
	)
	(segment
		(start 393.750292 -26.699718)
		(end 397.274288 -26.699718)
		(width 0.254)
		(layer "B.Cu")
		(net "P3V3_STBY")
	)
	(segment
		(start 310.307228 -28.944824)
		(end 309.436516 -28.944824)
		(width 0.508)
		(layer "B.Cu")
		(net "P3V3_STBY")
	)
	(segment
		(start 13.88745 3.74396)
		(end 13.453618 3.74396)
		(width 0.254)
		(layer "B.Cu")
		(net "P3V3_STBY")
	)
	(segment
		(start 269.92072 -91.538806)
		(end 269.984982 -91.474544)
		(width 0.1524)
		(layer "B.Cu")
		(net "P3V3_STBY")
	)
	(segment
		(start 404.763732 -52.19192)
		(end 405.40432 -52.19192)
		(width 0.508)
		(layer "B.Cu")
		(net "P3V3_STBY")
	)
	(segment
		(start 483.0445 -48.514)
		(end 483.0572 -48.5267)
		(width 0.508)
		(layer "B.Cu")
		(net "P3V3_STBY")
	)
	(segment
		(start 442.663326 -147.663154)
		(end 442.663326 -147.259294)
		(width 0.254)
		(layer "B.Cu")
		(net "P3V3_STBY")
	)
	(segment
		(start 405.0284 -1.270508)
		(end 404.7744 -1.524508)
		(width 0.254)
		(layer "B.Cu")
		(net "P3V3_STBY")
	)
	(segment
		(start 371.3353 -39.0271)
		(end 371.88902 -38.47338)
		(width 0.254)
		(layer "B.Cu")
		(net "P3V3_STBY")
	)
	(segment
		(start 402.463 -152.527)
		(end 402.463 -153.289)
		(width 0.254)
		(layer "B.Cu")
		(net "P3V3_STBY")
	)
	(segment
		(start 78.070202 -87.224362)
		(end 78.51648 -87.224362)
		(width 0.1524)
		(layer "B.Cu")
		(net "P3V3_STBY")
	)
	(segment
		(start 385.9276 -87.1601)
		(end 386.08 -87.3125)
		(width 0.254)
		(layer "B.Cu")
		(net "P3V3_STBY")
	)
	(segment
		(start 449.707 -141.097)
		(end 448.853814 -141.097)
		(width 0.254)
		(layer "B.Cu")
		(net "P3V3_STBY")
	)
	(segment
		(start 331.343 -11.7094)
		(end 331.343 -12.260834)
		(width 0.254)
		(layer "B.Cu")
		(net "P3V3_STBY")
	)
	(segment
		(start 450.368162 -5.073396)
		(end 451.163182 -5.868416)
		(width 0.254)
		(layer "B.Cu")
		(net "P3V3_STBY")
	)
	(segment
		(start 438.124346 -148.349208)
		(end 438.976516 -147.497038)
		(width 0.254)
		(layer "B.Cu")
		(net "P3V3_STBY")
	)
	(segment
		(start 91.044776 -87.8332)
		(end 91.389454 -87.8332)
		(width 0.1524)
		(layer "B.Cu")
		(net "P3V3_STBY")
	)
	(segment
		(start 473.701872 -145.864072)
		(end 474.197172 -146.359372)
		(width 0.254)
		(layer "B.Cu")
		(net "P3V3_STBY")
	)
	(segment
		(start 448.2846 -129.3622)
		(end 449.1736 -129.3622)
		(width 0.254)
		(layer "B.Cu")
		(net "P3V3_STBY")
	)
	(segment
		(start 373.761 -6.1595)
		(end 372.872 -6.1595)
		(width 0.4572)
		(layer "B.Cu")
		(net "P3V3_STBY")
	)
	(segment
		(start 387.1468 -3.103372)
		(end 387.1468 -3.3782)
		(width 0.254)
		(layer "B.Cu")
		(net "P3V3_STBY")
	)
	(segment
		(start 411.5435 -32.587946)
		(end 411.49016 -32.534606)
		(width 0.4572)
		(layer "B.Cu")
		(net "P3V3_STBY")
	)
	(segment
		(start 402.463 -152.146)
		(end 402.463 -152.527)
		(width 0.254)
		(layer "B.Cu")
		(net "P3V3_STBY")
	)
	(segment
		(start 405.219408 -94.517718)
		(end 405.219408 -93.755718)
		(width 0.508)
		(layer "B.Cu")
		(net "P3V3_STBY")
	)
	(segment
		(start 87.50427 -87.757)
		(end 87.9348 -87.757)
		(width 0.1524)
		(layer "B.Cu")
		(net "P3V3_STBY")
	)
	(segment
		(start 466.74405 -148.844254)
		(end 465.595208 -148.844254)
		(width 0.4064)
		(layer "B.Cu")
		(net "P3V3_STBY")
	)
	(segment
		(start 401.131024 -35.569652)
		(end 401.10283 -35.597846)
		(width 0.508)
		(layer "B.Cu")
		(net "P3V3_STBY")
	)
	(segment
		(start 405.111204 -97.917)
		(end 404.5585 -97.917)
		(width 0.254)
		(layer "B.Cu")
		(net "P3V3_STBY")
	)
	(segment
		(start 387.1468 -3.3782)
		(end 386.865368 -3.659632)
		(width 0.254)
		(layer "B.Cu")
		(net "P3V3_STBY")
	)
	(segment
		(start 82.452464 -86.729316)
		(end 82.679032 -86.729316)
		(width 0.1524)
		(layer "B.Cu")
		(net "P3V3_STBY")
	)
	(segment
		(start 459.130146 -153.695146)
		(end 459.359 -153.924)
		(width 0.3048)
		(layer "B.Cu")
		(net "P3V3_STBY")
	)
	(segment
		(start 410.834332 -5.08)
		(end 410.21 -5.08)
		(width 0.254)
		(layer "B.Cu")
		(net "P3V3_STBY")
	)
	(segment
		(start 418.7063 -48.1584)
		(end 418.7063 -47.7647)
		(width 0.508)
		(layer "B.Cu")
		(net "P3V3_STBY")
	)
	(segment
		(start 377.698 -20.32)
		(end 377.698 -19.558)
		(width 0.254)
		(layer "B.Cu")
		(net "P3V3_STBY")
	)
	(segment
		(start 443.4586 -142.0368)
		(end 443.1538 -142.0368)
		(width 0.254)
		(layer "B.Cu")
		(net "P3V3_STBY")
	)
	(segment
		(start 438.703974 -22.283166)
		(end 439.02884 -21.9583)
		(width 0.254)
		(layer "B.Cu")
		(net "P3V3_STBY")
	)
	(segment
		(start 384.429 -2.702814)
		(end 384.175 -2.448814)
		(width 0.254)
		(layer "B.Cu")
		(net "P3V3_STBY")
	)
	(segment
		(start 415.589974 -3.022854)
		(end 415.593784 -3.026664)
		(width 0.254)
		(layer "B.Cu")
		(net "P3V3_STBY")
	)
	(segment
		(start 408.071066 -22.028404)
		(end 407.906982 -22.192488)
		(width 0.254)
		(layer "B.Cu")
		(net "P3V3_STBY")
	)
	(segment
		(start 369.545108 -78.294738)
		(end 369.690904 -78.294738)
		(width 0.254)
		(layer "B.Cu")
		(net "P3V3_STBY")
	)
	(segment
		(start 449.16725 -155.8544)
		(end 448.265042 -155.8544)
		(width 0.254)
		(layer "B.Cu")
		(net "P3V3_STBY")
	)
	(segment
		(start 489.6993 -33.928812)
		(end 489.4453 -33.674812)
		(width 0.508)
		(layer "B.Cu")
		(net "P3V3_STBY")
	)
	(segment
		(start 390.144 -16.383)
		(end 390.144 -16.002254)
		(width 0.254)
		(layer "B.Cu")
		(net "P3V3_STBY")
	)
	(segment
		(start 452.4883 -147.398232)
		(end 452.4883 -146.987768)
		(width 0.254)
		(layer "B.Cu")
		(net "P3V3_STBY")
	)
	(segment
		(start 498.7036 -35.8394)
		(end 499.084854 -35.458146)
		(width 0.254)
		(layer "B.Cu")
		(net "P3V3_STBY")
	)
	(segment
		(start 446.8876 -61.8236)
		(end 446.8876 -62.5856)
		(width 0.254)
		(layer "B.Cu")
		(net "P3V3_STBY")
	)
	(segment
		(start 24.257 -85.9028)
		(end 24.257 -85.4329)
		(width 0.254)
		(layer "B.Cu")
		(net "P3V3_STBY")
	)
	(segment
		(start 438.976516 -147.497038)
		(end 438.976516 -146.282156)
		(width 0.254)
		(layer "B.Cu")
		(net "P3V3_STBY")
	)
	(segment
		(start 368.745262 -71.095108)
		(end 368.346228 -70.696074)
		(width 0.254)
		(layer "B.Cu")
		(net "P3V3_STBY")
	)
	(segment
		(start 389.255 -66.167)
		(end 389.255 -69.191632)
		(width 0.254)
		(layer "B.Cu")
		(net "P3V3_STBY")
	)
	(segment
		(start 477.139 -45.3644)
		(end 477.7994 -44.704)
		(width 0.508)
		(layer "B.Cu")
		(net "P3V3_STBY")
	)
	(segment
		(start 373.151654 -75.5015)
		(end 373.544846 -75.894692)
		(width 0.254)
		(layer "B.Cu")
		(net "P3V3_STBY")
	)
	(segment
		(start 327.95718 -58.448448)
		(end 327.95718 -58.724546)
		(width 0.254)
		(layer "B.Cu")
		(net "P3V3_STBY")
	)
	(segment
		(start 446.292478 -153.237946)
		(end 446.559432 -153.5049)
		(width 0.254)
		(layer "B.Cu")
		(net "P3V3_STBY")
	)
	(segment
		(start 442.6966 -141.5542)
		(end 442.8744 -141.5542)
		(width 0.254)
		(layer "B.Cu")
		(net "P3V3_STBY")
	)
	(segment
		(start 419.1508 -47.3202)
		(end 419.2524 -47.3202)
		(width 0.508)
		(layer "B.Cu")
		(net "P3V3_STBY")
	)
	(segment
		(start 423.164 -13.335)
		(end 422.3004 -13.335)
		(width 0.254)
		(layer "B.Cu")
		(net "P3V3_STBY")
	)
	(segment
		(start 362.1024 -132.9182)
		(end 362.1024 -133.0198)
		(width 0.381)
		(layer "B.Cu")
		(net "P3V3_STBY")
	)
	(segment
		(start 163.6268 -67.31)
		(end 163.3728 -67.056)
		(width 0.254)
		(layer "B.Cu")
		(net "P3V3_STBY")
	)
	(segment
		(start 495.665506 -131.8895)
		(end 495.665506 -130.733546)
		(width 0.254)
		(layer "B.Cu")
		(net "P3V3_STBY")
	)
	(segment
		(start 492.26978 -123.56592)
		(end 492.3282 -123.5075)
		(width 0.254)
		(layer "B.Cu")
		(net "P3V3_STBY")
	)
	(segment
		(start 379.145038 -67.894962)
		(end 379.74905 -68.498974)
		(width 0.254)
		(layer "B.Cu")
		(net "P3V3_STBY")
	)
	(segment
		(start 376.936 -66.04)
		(end 376.936 -65.405)
		(width 0.254)
		(layer "B.Cu")
		(net "P3V3_STBY")
	)
	(segment
		(start 495.665506 -130.733546)
		(end 495.45748 -130.52552)
		(width 0.254)
		(layer "B.Cu")
		(net "P3V3_STBY")
	)
	(segment
		(start 77.705204 -86.859364)
		(end 78.070202 -87.224362)
		(width 0.1524)
		(layer "B.Cu")
		(net "P3V3_STBY")
	)
	(segment
		(start 376.344688 -77.096366)
		(end 376.4407 -77.096366)
		(width 0.254)
		(layer "B.Cu")
		(net "P3V3_STBY")
	)
	(segment
		(start 393.493498 -26.855928)
		(end 393.493498 -26.597102)
		(width 0.254)
		(layer "B.Cu")
		(net "P3V3_STBY")
	)
	(segment
		(start 475.412816 -146.359372)
		(end 474.650816 -146.359372)
		(width 0.254)
		(layer "B.Cu")
		(net "P3V3_STBY")
	)
	(segment
		(start 473.719652 -145.477484)
		(end 473.701872 -145.495264)
		(width 0.254)
		(layer "B.Cu")
		(net "P3V3_STBY")
	)
	(segment
		(start 177.2666 -64.135)
		(end 178.943 -64.135)
		(width 0.254)
		(layer "B.Cu")
		(net "P3V3_STBY")
	)
	(segment
		(start 70.433438 -86.859364)
		(end 70.790054 -86.859364)
		(width 0.1524)
		(layer "B.Cu")
		(net "P3V3_STBY")
	)
	(segment
		(start 412.623 -8.661146)
		(end 411.505146 -9.779)
		(width 0.254)
		(layer "B.Cu")
		(net "P3V3_STBY")
	)
	(segment
		(start 374.751854 -53.555646)
		(end 374.751854 -53.344318)
		(width 0.254)
		(layer "B.Cu")
		(net "P3V3_STBY")
	)
	(segment
		(start 26.6446 -77.089)
		(end 26.3398 -77.3938)
		(width 0.254)
		(layer "B.Cu")
		(net "P3V3_STBY")
	)
	(segment
		(start 460.9846 -36.055808)
		(end 461.098392 -36.1696)
		(width 0.254)
		(layer "B.Cu")
		(net "P3V3_STBY")
	)
	(segment
		(start 25.8572 -77.978)
		(end 25.654 -77.978)
		(width 0.254)
		(layer "B.Cu")
		(net "P3V3_STBY")
	)
	(segment
		(start 371.145308 -75.094846)
		(end 370.745512 -75.494642)
		(width 0.254)
		(layer "B.Cu")
		(net "P3V3_STBY")
	)
	(segment
		(start 177.5333 -66.876168)
		(end 177.5333 -67.554856)
		(width 0.254)
		(layer "B.Cu")
		(net "P3V3_STBY")
	)
	(segment
		(start 378.196348 -47.007018)
		(end 379.000766 -46.2026)
		(width 0.254)
		(layer "B.Cu")
		(net "P3V3_STBY")
	)
	(segment
		(start 428.706026 -45.307758)
		(end 432.079908 -45.307758)
		(width 0.508)
		(layer "B.Cu")
		(net "P3V3_STBY")
	)
	(segment
		(start 352.183192 -90.639392)
		(end 351.86112 -90.639392)
		(width 0.254)
		(layer "B.Cu")
		(net "P3V3_STBY")
	)
	(segment
		(start 487.7054 -36.3474)
		(end 487.1212 -36.3474)
		(width 0.254)
		(layer "B.Cu")
		(net "P3V3_STBY")
	)
	(segment
		(start 261.226046 -87.81288)
		(end 260.796786 -88.24214)
		(width 0.1524)
		(layer "B.Cu")
		(net "P3V3_STBY")
	)
	(segment
		(start 392.2141 -104.1146)
		(end 392.2141 -104.1781)
		(width 0.3556)
		(layer "B.Cu")
		(net "P3V3_STBY")
	)
	(segment
		(start 454.690988 -4.2164)
		(end 455.549 -4.2164)
		(width 0.254)
		(layer "B.Cu")
		(net "P3V3_STBY")
	)
	(segment
		(start 401.472146 -40.0431)
		(end 401.5613 -39.953946)
		(width 0.508)
		(layer "B.Cu")
		(net "P3V3_STBY")
	)
	(segment
		(start 396.875 -37.846)
		(end 397.637 -37.846)
		(width 0.254)
		(layer "B.Cu")
		(net "P3V3_STBY")
	)
	(segment
		(start 372.122192 -91.9988)
		(end 372.5164 -91.604592)
		(width 0.254)
		(layer "B.Cu")
		(net "P3V3_STBY")
	)
	(segment
		(start 419.8874 -16.021558)
		(end 420.414958 -15.494)
		(width 0.254)
		(layer "B.Cu")
		(net "P3V3_STBY")
	)
	(segment
		(start 164.084 -67.31)
		(end 164.9222 -67.31)
		(width 0.254)
		(layer "B.Cu")
		(net "P3V3_STBY")
	)
	(segment
		(start 70.790054 -86.859364)
		(end 71.245222 -87.314532)
		(width 0.1524)
		(layer "B.Cu")
		(net "P3V3_STBY")
	)
	(segment
		(start 411.240224 -55.767478)
		(end 409.636722 -57.37098)
		(width 0.508)
		(layer "B.Cu")
		(net "P3V3_STBY")
	)
	(segment
		(start 476.984568 -12.0015)
		(end 476.984568 -11.457432)
		(width 0.254)
		(layer "B.Cu")
		(net "P3V3_STBY")
	)
	(segment
		(start 457.8096 -142.9004)
		(end 457.6064 -143.1036)
		(width 0.381)
		(layer "B.Cu")
		(net "P3V3_STBY")
	)
	(segment
		(start 202.63612 -107.564936)
		(end 206.379064 -107.564936)
		(width 0.254)
		(layer "B.Cu")
		(net "P3V3_STBY")
	)
	(segment
		(start 348.8182 -16.51)
		(end 349.377 -16.51)
		(width 0.254)
		(layer "B.Cu")
		(net "P3V3_STBY")
	)
	(segment
		(start 414.032446 -39.076884)
		(end 413.890206 -38.934644)
		(width 0.4572)
		(layer "B.Cu")
		(net "P3V3_STBY")
	)
	(segment
		(start 395.5923 -28.271724)
		(end 395.5923 -29.184092)
		(width 0.254)
		(layer "B.Cu")
		(net "P3V3_STBY")
	)
	(segment
		(start 448.31 -146.963384)
		(end 447.69913 -146.352514)
		(width 0.254)
		(layer "B.Cu")
		(net "P3V3_STBY")
	)
	(segment
		(start 488.001056 -38.862)
		(end 487.162856 -39.7002)
		(width 0.254)
		(layer "B.Cu")
		(net "P3V3_STBY")
	)
	(segment
		(start 407.2255 -23.0505)
		(end 406.908 -23.0505)
		(width 0.254)
		(layer "B.Cu")
		(net "P3V3_STBY")
	)
	(segment
		(start 433.578 -153.543)
		(end 434.34 -153.543)
		(width 0.4064)
		(layer "B.Cu")
		(net "P3V3_STBY")
	)
	(segment
		(start 470.4715 -138.557)
		(end 470.4715 -139.1666)
		(width 0.254)
		(layer "B.Cu")
		(net "P3V3_STBY")
	)
	(segment
		(start 369.690904 -78.294738)
		(end 369.945158 -78.040484)
		(width 0.254)
		(layer "B.Cu")
		(net "P3V3_STBY")
	)
	(segment
		(start 16.4084 -86.8807)
		(end 16.7132 -86.5759)
		(width 0.254)
		(layer "B.Cu")
		(net "P3V3_STBY")
	)
	(segment
		(start 485.267 -30.226)
		(end 484.886 -30.607)
		(width 0.254)
		(layer "B.Cu")
		(net "P3V3_STBY")
	)
	(segment
		(start 177.824892 -66.3702)
		(end 176.428146 -64.973454)
		(width 0.254)
		(layer "B.Cu")
		(net "P3V3_STBY")
	)
	(segment
		(start 374.74271 -75.492864)
		(end 374.344692 -75.094846)
		(width 0.254)
		(layer "B.Cu")
		(net "P3V3_STBY")
	)
	(segment
		(start 367.8047 -92.48521)
		(end 367.8047 -95.2373)
		(width 0.254)
		(layer "B.Cu")
		(net "P3V3_STBY")
	)
	(segment
		(start 489.022136 -18.161)
		(end 489.43006 -18.568924)
		(width 0.254)
		(layer "B.Cu")
		(net "P3V3_STBY")
	)
	(segment
		(start 461.7466 -126.7714)
		(end 460.8576 -126.7714)
		(width 0.254)
		(layer "B.Cu")
		(net "P3V3_STBY")
	)
	(segment
		(start 408.722576 -14.031976)
		(end 407.7589 -13.0683)
		(width 0.508)
		(layer "B.Cu")
		(net "P3V3_STBY")
	)
	(segment
		(start 3.514852 -87.923624)
		(end 10.181082 -87.923624)
		(width 0.254)
		(layer "B.Cu")
		(net "P3V3_STBY")
	)
	(segment
		(start 404.028656 -54.446424)
		(end 404.028656 -52.926996)
		(width 0.508)
		(layer "B.Cu")
		(net "P3V3_STBY")
	)
	(segment
		(start 485.942894 4.157472)
		(end 486.683812 4.157472)
		(width 0.508)
		(layer "B.Cu")
		(net "P3V3_STBY")
	)
	(segment
		(start 460.4512 -127.762)
		(end 460.4512 -127.9144)
		(width 0.254)
		(layer "B.Cu")
		(net "P3V3_STBY")
	)
	(segment
		(start 451.50151 -6.761226)
		(end 451.50151 -8.094726)
		(width 0.254)
		(layer "B.Cu")
		(net "P3V3_STBY")
	)
	(segment
		(start 390.636252 -64.270382)
		(end 390.463532 -64.443102)
		(width 0.1016)
		(layer "B.Cu")
		(net "P3V3_STBY")
	)
	(segment
		(start 419.8874 -18.9484)
		(end 419.8874 -16.021558)
		(width 0.254)
		(layer "B.Cu")
		(net "P3V3_STBY")
	)
	(segment
		(start 499.62816 -130.30454)
		(end 499.62816 -131.61264)
		(width 0.254)
		(layer "B.Cu")
		(net "P3V3_STBY")
	)
	(segment
		(start 375.544842 -77.894688)
		(end 375.944892 -78.294738)
		(width 0.254)
		(layer "B.Cu")
		(net "P3V3_STBY")
	)
	(segment
		(start 404.2918 2.4384)
		(end 404.397972 2.332228)
		(width 0.254)
		(layer "B.Cu")
		(net "P3V3_STBY")
	)
	(segment
		(start 442.3918 -141.062202)
		(end 442.3918 -140.554202)
		(width 0.254)
		(layer "B.Cu")
		(net "P3V3_STBY")
	)
	(segment
		(start 482.512116 -141.948916)
		(end 482.512116 -142.485872)
		(width 0.254)
		(layer "B.Cu")
		(net "P3V3_STBY")
	)
	(segment
		(start 386.842 -87.3125)
		(end 386.08 -87.3125)
		(width 0.254)
		(layer "B.Cu")
		(net "P3V3_STBY")
	)
	(segment
		(start 450.088 -4.7498)
		(end 450.3674 -4.7498)
		(width 0.254)
		(layer "B.Cu")
		(net "P3V3_STBY")
	)
	(segment
		(start 460.9846 -35.7124)
		(end 460.9846 -36.055808)
		(width 0.254)
		(layer "B.Cu")
		(net "P3V3_STBY")
	)
	(segment
		(start 479.1456 -43.8404)
		(end 479.3234 -43.8404)
		(width 0.254)
		(layer "B.Cu")
		(net "P3V3_STBY")
	)
	(segment
		(start 376.4407 -77.096366)
		(end 376.744738 -77.400404)
		(width 0.254)
		(layer "B.Cu")
		(net "P3V3_STBY")
	)
	(segment
		(start 477.2914 -10.974578)
		(end 477.2152 -10.974578)
		(width 0.254)
		(layer "B.Cu")
		(net "P3V3_STBY")
	)
	(segment
		(start 206.379064 -107.564936)
		(end 208.2038 -105.7402)
		(width 0.254)
		(layer "B.Cu")
		(net "P3V3_STBY")
	)
	(segment
		(start 398.00657 -27.432)
		(end 398.272 -27.432)
		(width 0.254)
		(layer "B.Cu")
		(net "P3V3_STBY")
	)
	(segment
		(start 451.50151 -6.761226)
		(end 451.960996 -6.30174)
		(width 0.254)
		(layer "B.Cu")
		(net "P3V3_STBY")
	)
	(segment
		(start 10.181082 -87.923624)
		(end 12.095988 -86.008718)
		(width 0.254)
		(layer "B.Cu")
		(net "P3V3_STBY")
	)
	(segment
		(start 446.9892 -16.76146)
		(end 447.044064 -16.706596)
		(width 0.254)
		(layer "B.Cu")
		(net "P3V3_STBY")
	)
	(segment
		(start 396.246096 -86.504272)
		(end 396.246096 -84.2772)
		(width 0.254)
		(layer "B.Cu")
		(net "P3V3_STBY")
	)
	(segment
		(start 374.930162 -62.277752)
		(end 374.651016 -62.556898)
		(width 0.254)
		(layer "B.Cu")
		(net "P3V3_STBY")
	)
	(segment
		(start 393.981178 -16.691864)
		(end 393.981178 -15.827502)
		(width 0.254)
		(layer "B.Cu")
		(net "P3V3_STBY")
	)
	(segment
		(start 451.960996 -6.30174)
		(end 454.32726 -6.30174)
		(width 0.254)
		(layer "B.Cu")
		(net "P3V3_STBY")
	)
	(segment
		(start 501.225312 -37.43452)
		(end 501.225312 -37.414962)
		(width 0.254)
		(layer "B.Cu")
		(net "P3V3_STBY")
	)
	(segment
		(start 478.3836 -44.1198)
		(end 478.8662 -44.1198)
		(width 0.254)
		(layer "B.Cu")
		(net "P3V3_STBY")
	)
	(segment
		(start 500.38 -144.78)
		(end 500.38 -145.8976)
		(width 0.254)
		(layer "B.Cu")
		(net "P3V3_STBY")
	)
	(segment
		(start 446.825878 -153.5049)
		(end 447.079878 -153.2509)
		(width 0.254)
		(layer "B.Cu")
		(net "P3V3_STBY")
	)
	(segment
		(start 392.796268 -61.228732)
		(end 392.2522 -61.7728)
		(width 0.254)
		(layer "B.Cu")
		(net "P3V3_STBY")
	)
	(segment
		(start 83.649312 -87.314532)
		(end 84.054696 -87.719916)
		(width 0.1524)
		(layer "B.Cu")
		(net "P3V3_STBY")
	)
	(segment
		(start 458.353414 -130.850386)
		(end 458.2414 -130.9624)
		(width 0.254)
		(layer "B.Cu")
		(net "P3V3_STBY")
	)
	(segment
		(start 269.703296 -90.794078)
		(end 269.304516 -90.794078)
		(width 0.1524)
		(layer "B.Cu")
		(net "P3V3_STBY")
	)
	(segment
		(start 407.906982 -22.192488)
		(end 407.906982 -22.369018)
		(width 0.254)
		(layer "B.Cu")
		(net "P3V3_STBY")
	)
	(segment
		(start 476.174816 -146.359372)
		(end 475.412816 -146.359372)
		(width 0.254)
		(layer "B.Cu")
		(net "P3V3_STBY")
	)
	(segment
		(start 439.0263 -21.29028)
		(end 435.65572 -21.29028)
		(width 0.254)
		(layer "B.Cu")
		(net "P3V3_STBY")
	)
	(segment
		(start 368.64671 -43.260772)
		(end 368.472212 -43.260772)
		(width 0.254)
		(layer "B.Cu")
		(net "P3V3_STBY")
	)
	(segment
		(start 25.908 -83.185)
		(end 24.257 -83.185)
		(width 0.254)
		(layer "B.Cu")
		(net "P3V3_STBY")
	)
	(segment
		(start 68.674996 -86.859364)
		(end 69.074284 -86.859364)
		(width 0.1524)
		(layer "B.Cu")
		(net "P3V3_STBY")
	)
	(segment
		(start 371.05209 -65.110106)
		(end 371.526816 -64.63538)
		(width 0.254)
		(layer "B.Cu")
		(net "P3V3_STBY")
	)
	(segment
		(start 484.0732 -48.5267)
		(end 484.5812 -48.5267)
		(width 0.508)
		(layer "B.Cu")
		(net "P3V3_STBY")
	)
	(segment
		(start 406.273 -21.463)
		(end 406.273 -22.1996)
		(width 0.508)
		(layer "B.Cu")
		(net "P3V3_STBY")
	)
	(segment
		(start 176.428146 -64.973454)
		(end 177.2666 -64.135)
		(width 0.254)
		(layer "B.Cu")
		(net "P3V3_STBY")
	)
	(segment
		(start 381.5842 -2.768854)
		(end 381.5842 -2.448814)
		(width 0.254)
		(layer "B.Cu")
		(net "P3V3_STBY")
	)
	(segment
		(start 497.1415 -130.0607)
		(end 496.67668 -130.52552)
		(width 0.381)
		(layer "B.Cu")
		(net "P3V3_STBY")
	)
	(segment
		(start 376.261376 -69.895466)
		(end 376.344688 -69.895466)
		(width 0.254)
		(layer "B.Cu")
		(net "P3V3_STBY")
	)
	(segment
		(start 379.3363 -67.21856)
		(end 379.349 -67.23126)
		(width 0.254)
		(layer "B.Cu")
		(net "P3V3_STBY")
	)
	(segment
		(start 74.233532 -86.859364)
		(end 74.6887 -87.314532)
		(width 0.1524)
		(layer "B.Cu")
		(net "P3V3_STBY")
	)
	(segment
		(start 390.463532 -64.443102)
		(end 390.1821 -64.443102)
		(width 0.1016)
		(layer "B.Cu")
		(net "P3V3_STBY")
	)
	(segment
		(start 72.872092 -87.224362)
		(end 73.50252 -87.224362)
		(width 0.1524)
		(layer "B.Cu")
		(net "P3V3_STBY")
	)
	(segment
		(start 382.1176 -5.1562)
		(end 381.4826 -4.5212)
		(width 0.254)
		(layer "B.Cu")
		(net "P3V3_STBY")
	)
	(segment
		(start 449.3895 -21.48078)
		(end 449.523358 -21.48078)
		(width 0.508)
		(layer "B.Cu")
		(net "P3V3_STBY")
	)
	(segment
		(start 371.05209 -65.411604)
		(end 371.05209 -65.110106)
		(width 0.254)
		(layer "B.Cu")
		(net "P3V3_STBY")
	)
	(segment
		(start 476.25 -147.193)
		(end 476.25 -146.434556)
		(width 0.254)
		(layer "B.Cu")
		(net "P3V3_STBY")
	)
	(segment
		(start 449.7578 -129.3622)
		(end 449.1736 -129.3622)
		(width 0.254)
		(layer "B.Cu")
		(net "P3V3_STBY")
	)
	(segment
		(start 488.2515 -43.5864)
		(end 488.2515 -42.6085)
		(width 0.254)
		(layer "B.Cu")
		(net "P3V3_STBY")
	)
	(segment
		(start 450.7484 -8.847836)
		(end 450.7484 -9.6012)
		(width 0.254)
		(layer "B.Cu")
		(net "P3V3_STBY")
	)
	(segment
		(start 13.413486 -86.4362)
		(end 13.8176 -86.4362)
		(width 0.254)
		(layer "B.Cu")
		(net "P3V3_STBY")
	)
	(segment
		(start 401.701 -35.467798)
		(end 401.599146 -35.569652)
		(width 0.254)
		(layer "B.Cu")
		(net "P3V3_STBY")
	)
	(segment
		(start 476.25 -146.434556)
		(end 476.174816 -146.359372)
		(width 0.254)
		(layer "B.Cu")
		(net "P3V3_STBY")
	)
	(segment
		(start 412.942532 -56.560974)
		(end 412.149036 -55.767478)
		(width 0.508)
		(layer "B.Cu")
		(net "P3V3_STBY")
	)
	(segment
		(start 444.58001 -142.465298)
		(end 443.887098 -142.465298)
		(width 0.254)
		(layer "B.Cu")
		(net "P3V3_STBY")
	)
	(segment
		(start 422.3004 -13.335)
		(end 422.3004 -13.904976)
		(width 0.254)
		(layer "B.Cu")
		(net "P3V3_STBY")
	)
	(segment
		(start 398.15008 -33.871916)
		(end 398.15008 -33.848294)
		(width 0.254)
		(layer "B.Cu")
		(net "P3V3_STBY")
	)
	(segment
		(start 269.252954 -90.742516)
		(end 269.216886 -90.742516)
		(width 0.1524)
		(layer "B.Cu")
		(net "P3V3_STBY")
	)
	(segment
		(start 352.354388 -83.510628)
		(end 352.6663 -83.82254)
		(width 0.254)
		(layer "B.Cu")
		(net "P3V3_STBY")
	)
	(segment
		(start 174.371 -65.024)
		(end 174.9044 -65.024)
		(width 0.254)
		(layer "B.Cu")
		(net "P3V3_STBY")
	)
	(segment
		(start 83.264248 -87.314532)
		(end 83.649312 -87.314532)
		(width 0.1524)
		(layer "B.Cu")
		(net "P3V3_STBY")
	)
	(segment
		(start 325.89851 -58.228484)
		(end 326.653144 -58.228484)
		(width 0.254)
		(layer "B.Cu")
		(net "P3V3_STBY")
	)
	(segment
		(start 63.0428 -93.1672)
		(end 63.0428 -92.4052)
		(width 0.381)
		(layer "B.Cu")
		(net "P3V3_STBY")
	)
	(segment
		(start 385.887722 -48.673258)
		(end 386.08 -48.48098)
		(width 0.254)
		(layer "B.Cu")
		(net "P3V3_STBY")
	)
	(segment
		(start 473.122498 -135.78459)
		(end 473.122498 -135.932418)
		(width 0.254)
		(layer "B.Cu")
		(net "P3V3_STBY")
	)
	(segment
		(start -1.44526 -118.83136)
		(end -1.44526 -119.46636)
		(width 0.254)
		(layer "B.Cu")
		(net "P3V3_STBY")
	)
	(segment
		(start 486.2322 -141.224)
		(end 486.6386 -141.224)
		(width 0.254)
		(layer "B.Cu")
		(net "P3V3_STBY")
	)
	(segment
		(start 373.017288 -36.096448)
		(end 373.017288 -36.456112)
		(width 0.254)
		(layer "B.Cu")
		(net "P3V3_STBY")
	)
	(segment
		(start 391.639806 -61.7728)
		(end 391.162286 -61.29528)
		(width 0.254)
		(layer "B.Cu")
		(net "P3V3_STBY")
	)
	(segment
		(start 397.886174 -33.584388)
		(end 397.886174 -33.262316)
		(width 0.254)
		(layer "B.Cu")
		(net "P3V3_STBY")
	)
	(segment
		(start 459.959202 -142.401798)
		(end 459.3336 -143.0274)
		(width 0.254)
		(layer "B.Cu")
		(net "P3V3_STBY")
	)
	(segment
		(start 25.509474 -79.4766)
		(end 25.509474 -78.122526)
		(width 0.254)
		(layer "B.Cu")
		(net "P3V3_STBY")
	)
	(segment
		(start 476.25 -147.193)
		(end 476.849948 -147.792948)
		(width 0.254)
		(layer "B.Cu")
		(net "P3V3_STBY")
	)
	(segment
		(start 423.418 -4.191)
		(end 422.8465 -4.191)
		(width 0.508)
		(layer "B.Cu")
		(net "P3V3_STBY")
	)
	(segment
		(start 379.0188 -82.677)
		(end 378.587 -82.677)
		(width 0.254)
		(layer "B.Cu")
		(net "P3V3_STBY")
	)
	(segment
		(start 371.6782 -65.6844)
		(end 371.405404 -65.411604)
		(width 0.254)
		(layer "B.Cu")
		(net "P3V3_STBY")
	)
	(segment
		(start 84.649564 -87.719916)
		(end 85.01507 -87.35441)
		(width 0.1524)
		(layer "B.Cu")
		(net "P3V3_STBY")
	)
	(segment
		(start 415.9885 -3.447288)
		(end 415.9885 -4.318)
		(width 0.254)
		(layer "B.Cu")
		(net "P3V3_STBY")
	)
	(segment
		(start 458.353414 -129.6924)
		(end 458.353414 -130.850386)
		(width 0.254)
		(layer "B.Cu")
		(net "P3V3_STBY")
	)
	(segment
		(start 415.593784 -3.052572)
		(end 415.9885 -3.447288)
		(width 0.254)
		(layer "B.Cu")
		(net "P3V3_STBY")
	)
	(segment
		(start 311.0738 -38.1381)
		(end 310.328818 -38.883082)
		(width 0.508)
		(layer "B.Cu")
		(net "P3V3_STBY")
	)
	(segment
		(start 379.28296 -82.677)
		(end 379.53696 -82.423)
		(width 0.254)
		(layer "B.Cu")
		(net "P3V3_STBY")
	)
	(segment
		(start 389.255 -69.191632)
		(end 389.533384 -69.470016)
		(width 0.254)
		(layer "B.Cu")
		(net "P3V3_STBY")
	)
	(segment
		(start 451.50151 -8.094726)
		(end 450.7484 -8.847836)
		(width 0.254)
		(layer "B.Cu")
		(net "P3V3_STBY")
	)
	(segment
		(start 390.144 -18.161)
		(end 390.144 -17.272)
		(width 0.254)
		(layer "B.Cu")
		(net "P3V3_STBY")
	)
	(segment
		(start 452.4883 -146.987768)
		(end 452.487792 -146.98726)
		(width 0.254)
		(layer "B.Cu")
		(net "P3V3_STBY")
	)
	(segment
		(start 75.57516 -86.859364)
		(end 75.941174 -86.859364)
		(width 0.1524)
		(layer "B.Cu")
		(net "P3V3_STBY")
	)
	(segment
		(start 478.010982 -146.671538)
		(end 477.698816 -146.359372)
		(width 0.254)
		(layer "B.Cu")
		(net "P3V3_STBY")
	)
	(segment
		(start 411.226 -9.779)
		(end 411.2895 -9.8425)
		(width 0.254)
		(layer "B.Cu")
		(net "P3V3_STBY")
	)
	(segment
		(start 371.145308 -72.695308)
		(end 370.745512 -72.295512)
		(width 0.254)
		(layer "B.Cu")
		(net "P3V3_STBY")
	)
	(segment
		(start 396.246096 -84.2772)
		(end 396.6845 -84.2772)
		(width 0.254)
		(layer "B.Cu")
		(net "P3V3_STBY")
	)
	(segment
		(start 263.626854 -88.605868)
		(end 263.284462 -88.605868)
		(width 0.1524)
		(layer "B.Cu")
		(net "P3V3_STBY")
	)
	(segment
		(start 488.708192 -43.5864)
		(end 488.2515 -43.5864)
		(width 0.254)
		(layer "B.Cu")
		(net "P3V3_STBY")
	)
	(segment
		(start 430.4792 -22.121622)
		(end 430.4792 -22.5298)
		(width 0.254)
		(layer "B.Cu")
		(net "P3V3_STBY")
	)
	(segment
		(start 391.46734 -63.5762)
		(end 391.05713 -63.98641)
		(width 0.1016)
		(layer "B.Cu")
		(net "P3V3_STBY")
	)
	(segment
		(start 409.4226 -14.097)
		(end 408.7876 -14.097)
		(width 0.4064)
		(layer "B.Cu")
		(net "P3V3_STBY")
	)
	(segment
		(start 267.806932 -89.648792)
		(end 267.806932 -89.587578)
		(width 0.1524)
		(layer "B.Cu")
		(net "P3V3_STBY")
	)
	(segment
		(start 450.368162 -4.750562)
		(end 450.368162 -5.073396)
		(width 0.254)
		(layer "B.Cu")
		(net "P3V3_STBY")
	)
	(segment
		(start 482.680772 -144.771872)
		(end 482.785166 -144.667478)
		(width 0.254)
		(layer "B.Cu")
		(net "P3V3_STBY")
	)
	(segment
		(start 473.719652 -144.348708)
		(end 473.660216 -144.289272)
		(width 0.254)
		(layer "B.Cu")
		(net "P3V3_STBY")
	)
	(segment
		(start 365.379 -40.5892)
		(end 366.268 -40.5892)
		(width 0.254)
		(layer "B.Cu")
		(net "P3V3_STBY")
	)
	(segment
		(start 411.4165 -4.318)
		(end 411.4165 -3.7465)
		(width 0.254)
		(layer "B.Cu")
		(net "P3V3_STBY")
	)
	(segment
		(start 445.238632 -2.408174)
		(end 446.018158 -3.1877)
		(width 0.254)
		(layer "B.Cu")
		(net "P3V3_STBY")
	)
	(segment
		(start 410.21 -5.08)
		(end 409.955746 -5.334254)
		(width 0.254)
		(layer "B.Cu")
		(net "P3V3_STBY")
	)
	(segment
		(start 492.18342 -131.90982)
		(end 492.3536 -131.73964)
		(width 0.254)
		(layer "B.Cu")
		(net "P3V3_STBY")
	)
	(segment
		(start 380.84506 -79.63916)
		(end 380.13386 -80.35036)
		(width 0.254)
		(layer "B.Cu")
		(net "P3V3_STBY")
	)
	(segment
		(start 26.289 -77.5462)
		(end 25.8572 -77.978)
		(width 0.254)
		(layer "B.Cu")
		(net "P3V3_STBY")
	)
	(segment
		(start 410.973016 -103.245412)
		(end 410.973016 -98.56724)
		(width 0.254)
		(layer "B.Cu")
		(net "P3V3_STBY")
	)
	(segment
		(start 396.846298 -37.817298)
		(end 395.198346 -37.817298)
		(width 0.254)
		(layer "B.Cu")
		(net "P3V3_STBY")
	)
	(segment
		(start 63.2968 -88.8492)
		(end 63.2968 -89.9922)
		(width 0.4064)
		(layer "B.Cu")
		(net "P3V3_STBY")
	)
	(segment
		(start 449.172838 -155.848812)
		(end 449.16725 -155.8544)
		(width 0.254)
		(layer "B.Cu")
		(net "P3V3_STBY")
	)
	(segment
		(start 401.599146 -36.331652)
		(end 401.599146 -35.569652)
		(width 0.508)
		(layer "B.Cu")
		(net "P3V3_STBY")
	)
	(segment
		(start 335.420716 -13.8176)
		(end 336.328258 -12.910058)
		(width 0.254)
		(layer "B.Cu")
		(net "P3V3_STBY")
	)
	(segment
		(start 394.208 -62.738)
		(end 394.208 -61.59627)
		(width 0.254)
		(layer "B.Cu")
		(net "P3V3_STBY")
	)
	(segment
		(start 375.4882 -5.7658)
		(end 374.5992 -5.7658)
		(width 0.381)
		(layer "B.Cu")
		(net "P3V3_STBY")
	)
	(segment
		(start 208.2038 -105.7402)
		(end 215.141048 -105.7402)
		(width 0.254)
		(layer "B.Cu")
		(net "P3V3_STBY")
	)
	(segment
		(start 402.053044 -86.649306)
		(end 402.082 -86.649306)
		(width 0.254)
		(layer "B.Cu")
		(net "P3V3_STBY")
	)
	(segment
		(start 415.593784 -3.026664)
		(end 415.593784 -3.052572)
		(width 0.254)
		(layer "B.Cu")
		(net "P3V3_STBY")
	)
	(segment
		(start 453.928734 -31.999174)
		(end 453.771508 -32.1564)
		(width 0.508)
		(layer "B.Cu")
		(net "P3V3_STBY")
	)
	(segment
		(start 378.013214 -20.32)
		(end 377.698 -20.32)
		(width 0.254)
		(layer "B.Cu")
		(net "P3V3_STBY")
	)
	(segment
		(start 422.8465 -4.8895)
		(end 422.8465 -4.191)
		(width 0.508)
		(layer "B.Cu")
		(net "P3V3_STBY")
	)
	(segment
		(start 443.1538 -141.8336)
		(end 443.1538 -142.0368)
		(width 0.254)
		(layer "B.Cu")
		(net "P3V3_STBY")
	)
	(segment
		(start 368.547142 -28.50515)
		(end 368.576606 -28.534614)
		(width 0.381)
		(layer "B.Cu")
		(net "P3V3_STBY")
	)
	(segment
		(start 474.823282 -36.195)
		(end 474.218 -36.800282)
		(width 0.508)
		(layer "B.Cu")
		(net "P3V3_STBY")
	)
	(segment
		(start 473.122498 -135.932418)
		(end 473.60332 -136.41324)
		(width 0.254)
		(layer "B.Cu")
		(net "P3V3_STBY")
	)
	(segment
		(start 267.554964 -89.33561)
		(end 267.49375 -89.33561)
		(width 0.1524)
		(layer "B.Cu")
		(net "P3V3_STBY")
	)
	(segment
		(start 382.397 -2.448814)
		(end 381.5842 -2.448814)
		(width 0.254)
		(layer "B.Cu")
		(net "P3V3_STBY")
	)
	(segment
		(start 487.62666 -30.226)
		(end 485.267 -30.226)
		(width 0.508)
		(layer "B.Cu")
		(net "P3V3_STBY")
	)
	(segment
		(start 435.65572 -21.29028)
		(end 435.3306 -21.6154)
		(width 0.254)
		(layer "B.Cu")
		(net "P3V3_STBY")
	)
	(segment
		(start 390.767824 -63.98641)
		(end 390.636252 -64.117982)
		(width 0.1016)
		(layer "B.Cu")
		(net "P3V3_STBY")
	)
	(segment
		(start 92.331032 -88.305132)
		(end 92.75318 -88.72728)
		(width 0.1524)
		(layer "B.Cu")
		(net "P3V3_STBY")
	)
	(segment
		(start 447.0146 -129.377186)
		(end 448.269614 -129.377186)
		(width 0.254)
		(layer "B.Cu")
		(net "P3V3_STBY")
	)
	(segment
		(start 411.5435 -33.401)
		(end 411.5435 -34.081212)
		(width 0.4572)
		(layer "B.Cu")
		(net "P3V3_STBY")
	)
	(segment
		(start 400.97964 -153.9367)
		(end 400.02714 -154.8892)
		(width 0.254)
		(layer "B.Cu")
		(net "P3V3_STBY")
	)
	(segment
		(start 311.128664 -28.944824)
		(end 310.307228 -28.944824)
		(width 0.508)
		(layer "B.Cu")
		(net "P3V3_STBY")
	)
	(segment
		(start 84.054696 -87.719916)
		(end 84.649564 -87.719916)
		(width 0.1524)
		(layer "B.Cu")
		(net "P3V3_STBY")
	)
	(segment
		(start 492.2774 -38.9636)
		(end 492.2266 -39.0144)
		(width 0.254)
		(layer "B.Cu")
		(net "P3V3_STBY")
	)
	(segment
		(start 419.887146 -47.853346)
		(end 419.887146 -48.160432)
		(width 0.508)
		(layer "B.Cu")
		(net "P3V3_STBY")
	)
	(segment
		(start 417.677854 -50.748692)
		(end 417.11372 -50.184558)
		(width 0.254)
		(layer "B.Cu")
		(net "P3V3_STBY")
	)
	(segment
		(start 438.703974 -22.6314)
		(end 438.703974 -22.283166)
		(width 0.254)
		(layer "B.Cu")
		(net "P3V3_STBY")
	)
	(segment
		(start 477.139 -45.6438)
		(end 477.139 -45.3644)
		(width 0.508)
		(layer "B.Cu")
		(net "P3V3_STBY")
	)
	(segment
		(start 500.844566 -37.815266)
		(end 501.225312 -37.43452)
		(width 0.254)
		(layer "B.Cu")
		(net "P3V3_STBY")
	)
	(segment
		(start 391.46734 -62.925452)
		(end 391.46734 -63.5762)
		(width 0.1016)
		(layer "B.Cu")
		(net "P3V3_STBY")
	)
	(segment
		(start 438.124346 -148.525992)
		(end 438.124346 -148.349208)
		(width 0.254)
		(layer "B.Cu")
		(net "P3V3_STBY")
	)
	(segment
		(start 488.044236 -38.81882)
		(end 488.001056 -38.862)
		(width 0.254)
		(layer "B.Cu")
		(net "P3V3_STBY")
	)
	(segment
		(start 175.39843 -70.34911)
		(end 175.29302 -70.45452)
		(width 0.254)
		(layer "B.Cu")
		(net "P3V3_STBY")
	)
	(segment
		(start 63.0428 -92.4052)
		(end 63.2968 -92.1512)
		(width 0.381)
		(layer "B.Cu")
		(net "P3V3_STBY")
	)
	(segment
		(start 446.6717 -153.5049)
		(end 446.825878 -153.5049)
		(width 0.254)
		(layer "B.Cu")
		(net "P3V3_STBY")
	)
	(segment
		(start 374.344692 -72.581008)
		(end 374.344692 -72.695308)
		(width 0.254)
		(layer "B.Cu")
		(net "P3V3_STBY")
	)
	(segment
		(start 267.9446 -90.20048)
		(end 267.9446 -89.78646)
		(width 0.1524)
		(layer "B.Cu")
		(net "P3V3_STBY")
	)
	(segment
		(start 391.05713 -63.98641)
		(end 390.767824 -63.98641)
		(width 0.1016)
		(layer "B.Cu")
		(net "P3V3_STBY")
	)
	(segment
		(start 15.845028 -45.154342)
		(end 16.410686 -45.72)
		(width 0.254)
		(layer "B.Cu")
		(net "P3V3_STBY")
	)
	(segment
		(start 397.787622 -37.009578)
		(end 397.637 -37.1602)
		(width 0.254)
		(layer "B.Cu")
		(net "P3V3_STBY")
	)
	(segment
		(start 487.172 -139.6746)
		(end 486.9307 -139.6746)
		(width 0.254)
		(layer "B.Cu")
		(net "P3V3_STBY")
	)
	(segment
		(start 479.3234 -43.8404)
		(end 479.7552 -43.4086)
		(width 0.254)
		(layer "B.Cu")
		(net "P3V3_STBY")
	)
	(segment
		(start 310.328818 -38.883082)
		(end 310.328818 -44.667932)
		(width 0.508)
		(layer "B.Cu")
		(net "P3V3_STBY")
	)
	(segment
		(start 368.472212 -43.260772)
		(end 367.792 -42.58056)
		(width 0.254)
		(layer "B.Cu")
		(net "P3V3_STBY")
	)
	(segment
		(start 402.463 -153.67762)
		(end 402.20392 -153.9367)
		(width 0.254)
		(layer "B.Cu")
		(net "P3V3_STBY")
	)
	(segment
		(start 402.463 -153.289)
		(end 402.463 -153.67762)
		(width 0.254)
		(layer "B.Cu")
		(net "P3V3_STBY")
	)
	(segment
		(start 30.13202 -102.362)
		(end 32.8168 -102.362)
		(width 0.254)
		(layer "B.Cu")
		(net "P3V3_STBY")
	)
	(segment
		(start 406.273 -22.1996)
		(end 405.8285 -22.6441)
		(width 0.508)
		(layer "B.Cu")
		(net "P3V3_STBY")
	)
	(segment
		(start 378.46 -83.4644)
		(end 378.46 -82.804)
		(width 0.254)
		(layer "B.Cu")
		(net "P3V3_STBY")
	)
	(segment
		(start 439.4073 -141.097)
		(end 439.801 -141.097)
		(width 0.254)
		(layer "B.Cu")
		(net "P3V3_STBY")
	)
	(segment
		(start 75.119992 -87.314532)
		(end 75.57516 -86.859364)
		(width 0.1524)
		(layer "B.Cu")
		(net "P3V3_STBY")
	)
	(segment
		(start 348.361 -16.0528)
		(end 348.8182 -16.51)
		(width 0.254)
		(layer "B.Cu")
		(net "P3V3_STBY")
	)
	(segment
		(start 486.9307 -139.6746)
		(end 486.4227 -139.1666)
		(width 0.254)
		(layer "B.Cu")
		(net "P3V3_STBY")
	)
	(segment
		(start 405.280114 -97.74809)
		(end 405.111204 -97.917)
		(width 0.254)
		(layer "B.Cu")
		(net "P3V3_STBY")
	)
	(segment
		(start 489.478066 -29.3116)
		(end 489.947712 -29.781246)
		(width 0.381)
		(layer "B.Cu")
		(net "P3V3_STBY")
	)
	(segment
		(start 375.412 -65.359534)
		(end 375.412 -66.04)
		(width 0.254)
		(layer "B.Cu")
		(net "P3V3_STBY")
	)
	(segment
		(start 459.359 -153.924)
		(end 458.597 -153.924)
		(width 0.508)
		(layer "B.Cu")
		(net "P3V3_STBY")
	)
	(segment
		(start 393.446 -28.575)
		(end 393.446 -27.686)
		(width 0.254)
		(layer "B.Cu")
		(net "P3V3_STBY")
	)
	(segment
		(start 442.3918 -141.2494)
		(end 442.6966 -141.5542)
		(width 0.254)
		(layer "B.Cu")
		(net "P3V3_STBY")
	)
	(segment
		(start 369.847622 -69.894196)
		(end 369.944904 -69.894196)
		(width 0.254)
		(layer "B.Cu")
		(net "P3V3_STBY")
	)
	(segment
		(start 85.44687 -87.35441)
		(end 85.812376 -87.719916)
		(width 0.1524)
		(layer "B.Cu")
		(net "P3V3_STBY")
	)
	(segment
		(start 340.741 -83.5914)
		(end 340.741 -84.5058)
		(width 0.254)
		(layer "B.Cu")
		(net "P3V3_STBY")
	)
	(segment
		(start 482.981 -115.441984)
		(end 482.981 -114.554)
		(width 0.254)
		(layer "B.Cu")
		(net "P3V3_STBY")
	)
	(segment
		(start 36.173156 -102.87)
		(end 37.407596 -104.10444)
		(width 0.254)
		(layer "B.Cu")
		(net "P3V3_STBY")
	)
	(segment
		(start 501.0658 -146.4056)
		(end 500.6086 -145.9484)
		(width 0.254)
		(layer "B.Cu")
		(net "P3V3_STBY")
	)
	(segment
		(start 392.2522 -61.7728)
		(end 392.2522 -62.382908)
		(width 0.1016)
		(layer "B.Cu")
		(net "P3V3_STBY")
	)
	(segment
		(start 411.2895 -9.8425)
		(end 411.2895 -11.000994)
		(width 0.508)
		(layer "B.Cu")
		(net "P3V3_STBY")
	)
	(segment
		(start 410.973016 -98.56724)
		(end 410.153866 -97.74809)
		(width 0.254)
		(layer "B.Cu")
		(net "P3V3_STBY")
	)
	(segment
		(start 371.6528 -91.9988)
		(end 372.122192 -91.9988)
		(width 0.254)
		(layer "B.Cu")
		(net "P3V3_STBY")
	)
	(segment
		(start 416.7251 -6.04901)
		(end 417.21659 -6.5405)
		(width 0.508)
		(layer "B.Cu")
		(net "P3V3_STBY")
	)
	(segment
		(start 89.66962 -87.8332)
		(end 90.141552 -88.305132)
		(width 0.1524)
		(layer "B.Cu")
		(net "P3V3_STBY")
	)
	(segment
		(start 379.349 -67.23126)
		(end 379.349 -67.691)
		(width 0.254)
		(layer "B.Cu")
		(net "P3V3_STBY")
	)
	(segment
		(start 466.852 -140.3604)
		(end 466.852 -139.6238)
		(width 0.254)
		(layer "B.Cu")
		(net "P3V3_STBY")
	)
	(segment
		(start 179.206144 -68.341494)
		(end 179.206144 -67.049142)
		(width 0.254)
		(layer "B.Cu")
		(net "P3V3_STBY")
	)
	(segment
		(start 500.253 -149.4028)
		(end 501.0658 -148.59)
		(width 0.254)
		(layer "B.Cu")
		(net "P3V3_STBY")
	)
	(segment
		(start 458.2033 -135.394192)
		(end 457.542392 -135.394192)
		(width 0.254)
		(layer "B.Cu")
		(net "P3V3_STBY")
	)
	(segment
		(start 372.707916 -36.765484)
		(end 372.707916 -37.08654)
		(width 0.254)
		(layer "B.Cu")
		(net "P3V3_STBY")
	)
	(segment
		(start 491.07344 -123.56592)
		(end 492.26978 -123.56592)
		(width 0.254)
		(layer "B.Cu")
		(net "P3V3_STBY")
	)
	(segment
		(start 71.245222 -87.314532)
		(end 71.69531 -87.314532)
		(width 0.1524)
		(layer "B.Cu")
		(net "P3V3_STBY")
	)
	(segment
		(start 421.386 -15.24)
		(end 421.386 -14.9352)
		(width 0.254)
		(layer "B.Cu")
		(net "P3V3_STBY")
	)
	(segment
		(start 371.085364 -73.495154)
		(end 370.74348 -73.15327)
		(width 0.254)
		(layer "B.Cu")
		(net "P3V3_STBY")
	)
	(segment
		(start 418.7063 -47.7647)
		(end 419.1508 -47.3202)
		(width 0.508)
		(layer "B.Cu")
		(net "P3V3_STBY")
	)
	(segment
		(start 439.02884 -21.29282)
		(end 439.0263 -21.29028)
		(width 0.254)
		(layer "B.Cu")
		(net "P3V3_STBY")
	)
	(segment
		(start 474.197172 -146.359372)
		(end 474.650816 -146.359372)
		(width 0.254)
		(layer "B.Cu")
		(net "P3V3_STBY")
	)
	(segment
		(start 402.0058 -151.6888)
		(end 402.463 -152.146)
		(width 0.254)
		(layer "B.Cu")
		(net "P3V3_STBY")
	)
	(segment
		(start 363.9185 -55.16372)
		(end 362.65104 -55.16372)
		(width 0.254)
		(layer "B.Cu")
		(net "P3V3_STBY")
	)
	(segment
		(start 389.96874 -19.93392)
		(end 389.96874 -18.33626)
		(width 0.254)
		(layer "B.Cu")
		(net "P3V3_STBY")
	)
	(segment
		(start 16.410686 -45.72)
		(end 18.161 -45.72)
		(width 0.254)
		(layer "B.Cu")
		(net "P3V3_STBY")
	)
	(segment
		(start 368.189256 -92.100654)
		(end 367.8047 -92.48521)
		(width 0.254)
		(layer "B.Cu")
		(net "P3V3_STBY")
	)
	(segment
		(start 164.9222 -67.31)
		(end 164.973 -67.2592)
		(width 0.254)
		(layer "B.Cu")
		(net "P3V3_STBY")
	)
	(segment
		(start 361.559094 -56.255666)
		(end 361.259374 -56.255666)
		(width 0.254)
		(layer "B.Cu")
		(net "P3V3_STBY")
	)
	(segment
		(start 76.396342 -87.314532)
		(end 76.837032 -87.314532)
		(width 0.1524)
		(layer "B.Cu")
		(net "P3V3_STBY")
	)
	(segment
		(start 427.364652 -18.887948)
		(end 427.9519 -18.3007)
		(width 0.254)
		(layer "B.Cu")
		(net "P3V3_STBY")
	)
	(segment
		(start 430.4792 -22.5298)
		(end 431.2412 -22.5298)
		(width 0.254)
		(layer "B.Cu")
		(net "P3V3_STBY")
	)
	(segment
		(start 405.44369 -93.98)
		(end 405.8666 -93.98)
		(width 0.254)
		(layer "B.Cu")
		(net "P3V3_STBY")
	)
	(segment
		(start 473.91574 -135.830056)
		(end 474.229684 -136.144)
		(width 0.254)
		(layer "B.Cu")
		(net "P3V3_STBY")
	)
	(segment
		(start 474.218 -38.71849)
		(end 471.811604 -41.124886)
		(width 0.508)
		(layer "B.Cu")
		(net "P3V3_STBY")
	)
	(segment
		(start 500.844566 -38.049454)
		(end 500.844566 -37.815266)
		(width 0.254)
		(layer "B.Cu")
		(net "P3V3_STBY")
	)
	(segment
		(start 345.2368 -81.9404)
		(end 344.678 -82.4992)
		(width 0.254)
		(layer "B.Cu")
		(net "P3V3_STBY")
	)
	(segment
		(start 460.8322 -127.381)
		(end 460.4512 -127.762)
		(width 0.254)
		(layer "B.Cu")
		(net "P3V3_STBY")
	)
	(segment
		(start 408.559 0.2794)
		(end 408.559 0.9144)
		(width 0.254)
		(layer "B.Cu")
		(net "P3V3_STBY")
	)
	(segment
		(start 488.09148 -29.3116)
		(end 488.98429 -29.3116)
		(width 0.381)
		(layer "B.Cu")
		(net "P3V3_STBY")
	)
	(segment
		(start 411.5435 -34.081212)
		(end 411.49016 -34.134552)
		(width 0.4572)
		(layer "B.Cu")
		(net "P3V3_STBY")
	)
	(segment
		(start 454.740772 -32.60852)
		(end 454.438258 -32.306006)
		(width 0.254)
		(layer "B.Cu")
		(net "P3V3_STBY")
	)
	(segment
		(start 379.28296 -82.74812)
		(end 379.28296 -82.677)
		(width 0.254)
		(layer "B.Cu")
		(net "P3V3_STBY")
	)
	(segment
		(start 459.130146 -152.426162)
		(end 459.130146 -153.695146)
		(width 0.3048)
		(layer "B.Cu")
		(net "P3V3_STBY")
	)
	(segment
		(start 380.13386 -80.35036)
		(end 379.60046 -80.35036)
		(width 0.254)
		(layer "B.Cu")
		(net "P3V3_STBY")
	)
	(segment
		(start 384.175 -2.448814)
		(end 383.5908 -2.448814)
		(width 0.254)
		(layer "B.Cu")
		(net "P3V3_STBY")
	)
	(segment
		(start 390.755124 -83.859878)
		(end 390.906 -84.010754)
		(width 0.254)
		(layer "B.Cu")
		(net "P3V3_STBY")
	)
	(segment
		(start 411.505146 -34.149538)
		(end 411.505146 -34.934652)
		(width 0.4572)
		(layer "B.Cu")
		(net "P3V3_STBY")
	)
	(segment
		(start 407.906982 -22.369018)
		(end 407.2255 -23.0505)
		(width 0.254)
		(layer "B.Cu")
		(net "P3V3_STBY")
	)
	(segment
		(start 474.218 -38.354)
		(end 474.218 -38.71849)
		(width 0.508)
		(layer "B.Cu")
		(net "P3V3_STBY")
	)
	(segment
		(start 267.806932 -89.587578)
		(end 267.554964 -89.33561)
		(width 0.1524)
		(layer "B.Cu")
		(net "P3V3_STBY")
	)
	(segment
		(start 446.292478 -152.855168)
		(end 446.292478 -153.237946)
		(width 0.254)
		(layer "B.Cu")
		(net "P3V3_STBY")
	)
	(segment
		(start 374.84177 -95.568516)
		(end 374.84177 -95.136716)
		(width 0.254)
		(layer "B.Cu")
		(net "P3V3_STBY")
	)
	(segment
		(start 389.96874 -18.33626)
		(end 390.144 -18.161)
		(width 0.254)
		(layer "B.Cu")
		(net "P3V3_STBY")
	)
	(segment
		(start 457.2254 -135.0772)
		(end 456.7555 -135.0772)
		(width 0.254)
		(layer "B.Cu")
		(net "P3V3_STBY")
	)
	(segment
		(start 471.811604 -41.124886)
		(end 471.263726 -41.124886)
		(width 0.508)
		(layer "B.Cu")
		(net "P3V3_STBY")
	)
	(segment
		(start 477.2914 -11.1506)
		(end 477.2914 -10.974578)
		(width 0.254)
		(layer "B.Cu")
		(net "P3V3_STBY")
	)
	(segment
		(start 385.318 -87.1601)
		(end 385.9276 -87.1601)
		(width 0.254)
		(layer "B.Cu")
		(net "P3V3_STBY")
	)
	(segment
		(start 491.41888 -132.1816)
		(end 491.69066 -131.90982)
		(width 0.254)
		(layer "B.Cu")
		(net "P3V3_STBY")
	)
	(segment
		(start 421.132 -15.494)
		(end 421.386 -15.24)
		(width 0.254)
		(layer "B.Cu")
		(net "P3V3_STBY")
	)
	(segment
		(start 16.4084 -87.1601)
		(end 16.4084 -86.8807)
		(width 0.254)
		(layer "B.Cu")
		(net "P3V3_STBY")
	)
	(segment
		(start 378.755656 -21.062442)
		(end 378.013214 -20.32)
		(width 0.254)
		(layer "B.Cu")
		(net "P3V3_STBY")
	)
	(segment
		(start 177.33899 -68.39839)
		(end 176.403 -69.33438)
		(width 0.254)
		(layer "B.Cu")
		(net "P3V3_STBY")
	)
	(segment
		(start 332.899766 -13.8176)
		(end 335.420716 -13.8176)
		(width 0.254)
		(layer "B.Cu")
		(net "P3V3_STBY")
	)
	(segment
		(start 422.91 -4.953)
		(end 422.8465 -4.8895)
		(width 0.508)
		(layer "B.Cu")
		(net "P3V3_STBY")
	)
	(segment
		(start 379.349 -67.691)
		(end 379.145038 -67.894962)
		(width 0.254)
		(layer "B.Cu")
		(net "P3V3_STBY")
	)
	(segment
		(start 483.0445 -49.1617)
		(end 483.0445 -48.514)
		(width 0.508)
		(layer "B.Cu")
		(net "P3V3_STBY")
	)
	(segment
		(start 421.386 -14.755368)
		(end 421.386 -14.9352)
		(width 0.254)
		(layer "B.Cu")
		(net "P3V3_STBY")
	)
	(segment
		(start 404.5585 -97.155)
		(end 404.5585 -96.393)
		(width 0.508)
		(layer "B.Cu")
		(net "P3V3_STBY")
	)
	(segment
		(start 499.62816 -131.61264)
		(end 499.618 -131.6228)
		(width 0.254)
		(layer "B.Cu")
		(net "P3V3_STBY")
	)
	(segment
		(start 392.2522 -61.474604)
		(end 391.858754 -61.081158)
		(width 0.254)
		(layer "B.Cu")
		(net "P3V3_STBY")
	)
	(segment
		(start 451.163182 -5.868416)
		(end 451.163182 -6.422898)
		(width 0.254)
		(layer "B.Cu")
		(net "P3V3_STBY")
	)
	(segment
		(start 445.503046 -149.032722)
		(end 446.170812 -149.032722)
		(width 0.254)
		(layer "B.Cu")
		(net "P3V3_STBY")
	)
	(segment
		(start 374.35917 -94.654116)
		(end 374.20677 -94.654116)
		(width 0.254)
		(layer "B.Cu")
		(net "P3V3_STBY")
	)
	(segment
		(start 474.14942 -134.00024)
		(end 474.14942 -134.92988)
		(width 0.254)
		(layer "B.Cu")
		(net "P3V3_STBY")
	)
	(segment
		(start 368.745262 -77.38618)
		(end 368.745262 -77.494892)
		(width 0.254)
		(layer "B.Cu")
		(net "P3V3_STBY")
	)
	(segment
		(start 440.69 -157.1498)
		(end 440.69 -157.734508)
		(width 0.254)
		(layer "B.Cu")
		(net "P3V3_STBY")
	)
	(segment
		(start 400.7358 -39.459662)
		(end 400.798538 -39.5224)
		(width 0.508)
		(layer "B.Cu")
		(net "P3V3_STBY")
	)
	(segment
		(start 453.009 -30.861)
		(end 453.009 -30.226)
		(width 0.508)
		(layer "B.Cu")
		(net "P3V3_STBY")
	)
	(segment
		(start 461.7466 -126.7714)
		(end 462.8134 -126.7714)
		(width 0.254)
		(layer "B.Cu")
		(net "P3V3_STBY")
	)
	(segment
		(start 411.49016 -34.134552)
		(end 411.505146 -34.149538)
		(width 0.4572)
		(layer "B.Cu")
		(net "P3V3_STBY")
	)
	(segment
		(start 421.740076 -14.4653)
		(end 421.676068 -14.4653)
		(width 0.254)
		(layer "B.Cu")
		(net "P3V3_STBY")
	)
	(segment
		(start 410.153866 -97.74809)
		(end 405.280114 -97.74809)
		(width 0.254)
		(layer "B.Cu")
		(net "P3V3_STBY")
	)
	(segment
		(start 352.933 -91.3892)
		(end 352.183192 -90.639392)
		(width 0.254)
		(layer "B.Cu")
		(net "P3V3_STBY")
	)
	(segment
		(start 422.4655 -5.0165)
		(end 421.65016 -5.83184)
		(width 0.508)
		(layer "B.Cu")
		(net "P3V3_STBY")
	)
	(segment
		(start 390.636252 -64.117982)
		(end 390.636252 -64.270382)
		(width 0.1016)
		(layer "B.Cu")
		(net "P3V3_STBY")
	)
	(segment
		(start 401.701 -34.798)
		(end 401.701 -35.467798)
		(width 0.254)
		(layer "B.Cu")
		(net "P3V3_STBY")
	)
	(segment
		(start 178.527202 -66.3702)
		(end 178.0032 -66.3702)
		(width 0.254)
		(layer "B.Cu")
		(net "P3V3_STBY")
	)
	(segment
		(start 13.33119 3.621532)
		(end 13.306806 3.621532)
		(width 0.254)
		(layer "B.Cu")
		(net "P3V3_STBY")
	)
	(segment
		(start 19.340322 -46.233842)
		(end 19.05 -45.94352)
		(width 0.254)
		(layer "B.Cu")
		(net "P3V3_STBY")
	)
	(segment
		(start 415.629598 -56.560974)
		(end 412.942532 -56.560974)
		(width 0.508)
		(layer "B.Cu")
		(net "P3V3_STBY")
	)
	(segment
		(start 420.8653 -19.9263)
		(end 419.8874 -18.9484)
		(width 0.254)
		(layer "B.Cu")
		(net "P3V3_STBY")
	)
	(segment
		(start 397.002 -85.0265)
		(end 397.764 -85.0265)
		(width 0.254)
		(layer "B.Cu")
		(net "P3V3_STBY")
	)
	(segment
		(start 263.75868 -88.737694)
		(end 263.626854 -88.605868)
		(width 0.1524)
		(layer "B.Cu")
		(net "P3V3_STBY")
	)
	(segment
		(start 377.879864 -55.477664)
		(end 377.2027 -54.8005)
		(width 0.254)
		(layer "B.Cu")
		(net "P3V3_STBY")
	)
	(segment
		(start 487.62666 -30.781498)
		(end 487.62666 -30.226)
		(width 0.508)
		(layer "B.Cu")
		(net "P3V3_STBY")
	)
	(segment
		(start 393.446 -26.903426)
		(end 393.493498 -26.855928)
		(width 0.254)
		(layer "B.Cu")
		(net "P3V3_STBY")
	)
	(segment
		(start 371.145308 -73.495154)
		(end 371.085364 -73.495154)
		(width 0.254)
		(layer "B.Cu")
		(net "P3V3_STBY")
	)
	(segment
		(start 409.955746 -5.334254)
		(end 409.955746 -6.0198)
		(width 0.254)
		(layer "B.Cu")
		(net "P3V3_STBY")
	)
	(segment
		(start 379.28296 -82.760312)
		(end 379.28296 -82.74812)
		(width 0.254)
		(layer "B.Cu")
		(net "P3V3_STBY")
	)
	(segment
		(start 500.38 -145.8976)
		(end 500.3292 -145.9484)
		(width 0.254)
		(layer "B.Cu")
		(net "P3V3_STBY")
	)
	(segment
		(start 416.1917 -1.8288)
		(end 415.589974 -2.430526)
		(width 0.254)
		(layer "B.Cu")
		(net "P3V3_STBY")
	)
	(segment
		(start 452.6661 -31.769558)
		(end 452.6661 -31.2039)
		(width 0.508)
		(layer "B.Cu")
		(net "P3V3_STBY")
	)
	(segment
		(start 395.198346 -37.817298)
		(end 394.95984 -37.578792)
		(width 0.254)
		(layer "B.Cu")
		(net "P3V3_STBY")
	)
	(segment
		(start 410.742892 -2.704592)
		(end 410.718 -2.6797)
		(width 0.254)
		(layer "B.Cu")
		(net "P3V3_STBY")
	)
	(segment
		(start 454.311258 -31.999174)
		(end 453.928734 -31.999174)
		(width 0.508)
		(layer "B.Cu")
		(net "P3V3_STBY")
	)
	(segment
		(start 266.998704 -88.840564)
		(end 264.07618 -88.840564)
		(width 0.1524)
		(layer "B.Cu")
		(net "P3V3_STBY")
	)
	(segment
		(start 390.647174 -83.859878)
		(end 390.135364 -84.371688)
		(width 0.254)
		(layer "B.Cu")
		(net "P3V3_STBY")
	)
	(segment
		(start 500.824246 -38.069774)
		(end 500.844566 -38.049454)
		(width 0.254)
		(layer "B.Cu")
		(net "P3V3_STBY")
	)
	(segment
		(start 227.536248 -93.345)
		(end 227.584 -93.345)
		(width 0.254)
		(layer "B.Cu")
		(net "P3V3_STBY")
	)
	(segment
		(start 474.218 -36.800282)
		(end 474.218 -38.354)
		(width 0.508)
		(layer "B.Cu")
		(net "P3V3_STBY")
	)
	(segment
		(start 375.519696 -62.277752)
		(end 375.881392 -62.277752)
		(width 0.254)
		(layer "B.Cu")
		(net "P3V3_STBY")
	)
	(segment
		(start 461.098392 -36.1696)
		(end 461.098392 -36.432998)
		(width 0.254)
		(layer "B.Cu")
		(net "P3V3_STBY")
	)
	(segment
		(start 371.348 -64.008)
		(end 371.348 -64.456564)
		(width 0.254)
		(layer "B.Cu")
		(net "P3V3_STBY")
	)
	(segment
		(start 50.288444 -105.921556)
		(end 40.351456 -105.921556)
		(width 0.4064)
		(layer "B.Cu")
		(net "P3V3_STBY")
	)
	(segment
		(start 13.921232 3.777742)
		(end 13.88745 3.74396)
		(width 0.254)
		(layer "B.Cu")
		(net "P3V3_STBY")
	)
	(segment
		(start 452.487792 -146.98726)
		(end 452.487792 -146.977608)
		(width 0.254)
		(layer "B.Cu")
		(net "P3V3_STBY")
	)
	(segment
		(start 396.875 -87.3252)
		(end 396.1257 -87.3252)
		(width 0.254)
		(layer "B.Cu")
		(net "P3V3_STBY")
	)
	(segment
		(start 379.087634 -45.52696)
		(end 379.088142 -45.52696)
		(width 0.254)
		(layer "B.Cu")
		(net "P3V3_STBY")
	)
	(segment
		(start 461.0608 -126.9746)
		(end 461.0608 -127.381)
		(width 0.254)
		(layer "B.Cu")
		(net "P3V3_STBY")
	)
	(segment
		(start 488.09148 -29.8704)
		(end 488.09148 -29.3116)
		(width 0.381)
		(layer "B.Cu")
		(net "P3V3_STBY")
	)
	(segment
		(start 488.044236 -37.767768)
		(end 488.044236 -38.81882)
		(width 0.254)
		(layer "B.Cu")
		(net "P3V3_STBY")
	)
	(segment
		(start 78.819502 -86.92134)
		(end 78.819502 -86.410292)
		(width 0.1524)
		(layer "B.Cu")
		(net "P3V3_STBY")
	)
	(segment
		(start 371.545358 -75.494388)
		(end 371.545358 -75.494642)
		(width 0.254)
		(layer "B.Cu")
		(net "P3V3_STBY")
	)
	(segment
		(start 408.18816 -57.37098)
		(end 407.86304 -57.04586)
		(width 0.508)
		(layer "B.Cu")
		(net "P3V3_STBY")
	)
	(segment
		(start 68.25488 -87.27948)
		(end 68.674996 -86.859364)
		(width 0.1524)
		(layer "B.Cu")
		(net "P3V3_STBY")
	)
	(segment
		(start 32.8168 -102.362)
		(end 33.3248 -102.87)
		(width 0.254)
		(layer "B.Cu")
		(net "P3V3_STBY")
	)
	(segment
		(start 491.4392 -115.3668)
		(end 491.4392 -114.5794)
		(width 0.254)
		(layer "B.Cu")
		(net "P3V3_STBY")
	)
	(segment
		(start 311.128664 -28.944824)
		(end 311.130696 -28.942792)
		(width 0.508)
		(layer "B.Cu")
		(net "P3V3_STBY")
	)
	(segment
		(start 177.5333 -67.554856)
		(end 177.611024 -67.63258)
		(width 0.254)
		(layer "B.Cu")
		(net "P3V3_STBY")
	)
	(segment
		(start 418.680646 -45.539152)
		(end 418.680646 -46.298104)
		(width 0.508)
		(layer "B.Cu")
		(net "P3V3_STBY")
	)
	(segment
		(start 374.5992 -5.7658)
		(end 374.2055 -6.1595)
		(width 0.381)
		(layer "B.Cu")
		(net "P3V3_STBY")
	)
	(segment
		(start 389.23722 -61.29528)
		(end 389.1915 -61.341)
		(width 0.254)
		(layer "B.Cu")
		(net "P3V3_STBY")
	)
	(segment
		(start 163.3728 -67.056)
		(end 163.2712 -67.056)
		(width 0.254)
		(layer "B.Cu")
		(net "P3V3_STBY")
	)
	(segment
		(start 375.944892 -70.295262)
		(end 375.944892 -70.21195)
		(width 0.254)
		(layer "B.Cu")
		(net "P3V3_STBY")
	)
	(segment
		(start 370.745512 -72.295512)
		(end 370.745512 -72.294242)
		(width 0.254)
		(layer "B.Cu")
		(net "P3V3_STBY")
	)
	(segment
		(start 402.711666 -80.41894)
		(end 402.711666 -79.868776)
		(width 0.508)
		(layer "B.Cu")
		(net "P3V3_STBY")
	)
	(segment
		(start 446.018158 -3.1877)
		(end 448.5259 -3.1877)
		(width 0.254)
		(layer "B.Cu")
		(net "P3V3_STBY")
	)
	(segment
		(start 499.618 -132.4356)
		(end 499.6688 -132.4864)
		(width 0.254)
		(layer "B.Cu")
		(net "P3V3_STBY")
	)
	(segment
		(start 395.5923 -29.184092)
		(end 395.478 -29.298392)
		(width 0.254)
		(layer "B.Cu")
		(net "P3V3_STBY")
	)
	(segment
		(start 401.04568 -48.49368)
		(end 401.689062 -48.49368)
		(width 0.508)
		(layer "B.Cu")
		(net "P3V3_STBY")
	)
	(segment
		(start 456.7555 -135.0772)
		(end 456.7555 -134.4168)
		(width 0.254)
		(layer "B.Cu")
		(net "P3V3_STBY")
	)
	(segment
		(start 442.663326 -147.259294)
		(end 442.669168 -147.253452)
		(width 0.254)
		(layer "B.Cu")
		(net "P3V3_STBY")
	)
	(segment
		(start 371.405404 -65.411604)
		(end 371.05209 -65.411604)
		(width 0.254)
		(layer "B.Cu")
		(net "P3V3_STBY")
	)
	(segment
		(start 168.6052 -127.127)
		(end 168.402 -127.127)
		(width 0.254)
		(layer "B.Cu")
		(net "P3V3_STBY")
	)
	(segment
		(start 73.867518 -86.859364)
		(end 74.233532 -86.859364)
		(width 0.1524)
		(layer "B.Cu")
		(net "P3V3_STBY")
	)
	(segment
		(start 371.54485 -72.29348)
		(end 371.54485 -72.295004)
		(width 0.254)
		(layer "B.Cu")
		(net "P3V3_STBY")
	)
	(segment
		(start 454.165208 -3.69062)
		(end 454.690988 -4.2164)
		(width 0.254)
		(layer "B.Cu")
		(net "P3V3_STBY")
	)
	(segment
		(start 404.2156 -28.321)
		(end 404.48738 -28.04922)
		(width 0.254)
		(layer "B.Cu")
		(net "P3V3_STBY")
	)
	(segment
		(start 397.637 -37.1602)
		(end 397.637 -37.846)
		(width 0.254)
		(layer "B.Cu")
		(net "P3V3_STBY")
	)
	(segment
		(start 90.572844 -88.305132)
		(end 91.044776 -87.8332)
		(width 0.1524)
		(layer "B.Cu")
		(net "P3V3_STBY")
	)
	(segment
		(start 473.130118 -134.958074)
		(end 473.122498 -134.965694)
		(width 0.254)
		(layer "B.Cu")
		(net "P3V3_STBY")
	)
	(segment
		(start 326.653144 -58.228484)
		(end 326.96531 -57.916318)
		(width 0.254)
		(layer "B.Cu")
		(net "P3V3_STBY")
	)
	(segment
		(start 13.921232 3.752342)
		(end 13.921232 3.777742)
		(width 0.254)
		(layer "B.Cu")
		(net "P3V3_STBY")
	)
	(segment
		(start 382.782826 -72.058276)
		(end 382.782826 -72.610726)
		(width 0.254)
		(layer "B.Cu")
		(net "P3V3_STBY")
	)
	(segment
		(start 176.403 -69.33438)
		(end 176.403 -69.989192)
		(width 0.254)
		(layer "B.Cu")
		(net "P3V3_STBY")
	)
	(segment
		(start 78.51648 -87.224362)
		(end 78.819502 -86.92134)
		(width 0.1524)
		(layer "B.Cu")
		(net "P3V3_STBY")
	)
	(segment
		(start 407.162 -27.94)
		(end 407.035 -27.94)
		(width 0.254)
		(layer "B.Cu")
		(net "P3V3_STBY")
	)
	(segment
		(start 215.141048 -105.7402)
		(end 227.536248 -93.345)
		(width 0.254)
		(layer "B.Cu")
		(net "P3V3_STBY")
	)
	(segment
		(start 395.478 -29.298392)
		(end 395.478 -29.845)
		(width 0.254)
		(layer "B.Cu")
		(net "P3V3_STBY")
	)
	(segment
		(start 411.861 -6.5405)
		(end 411.861 -7.4295)
		(width 0.508)
		(layer "B.Cu")
		(net "P3V3_STBY")
	)
	(segment
		(start 499.3894 -139.954)
		(end 498.626638 -139.954)
		(width 0.254)
		(layer "B.Cu")
		(net "P3V3_STBY")
	)
	(segment
		(start 15.596108 -45.154342)
		(end 15.845028 -45.154342)
		(width 0.254)
		(layer "B.Cu")
		(net "P3V3_STBY")
	)
	(segment
		(start 446.559432 -153.5049)
		(end 446.6717 -153.5049)
		(width 0.254)
		(layer "B.Cu")
		(net "P3V3_STBY")
	)
	(segment
		(start 376.6566 -5.7658)
		(end 375.4882 -5.7658)
		(width 0.381)
		(layer "B.Cu")
		(net "P3V3_STBY")
	)
	(segment
		(start 471.263726 -41.124886)
		(end 470.574116 -41.814496)
		(width 0.508)
		(layer "B.Cu")
		(net "P3V3_STBY")
	)
	(segment
		(start 419.398196 -52.796694)
		(end 420.52113 -52.796694)
		(width 0.508)
		(layer "B.Cu")
		(net "P3V3_STBY")
	)
	(segment
		(start 418.680646 -46.298104)
		(end 419.318694 -46.298104)
		(width 0.508)
		(layer "B.Cu")
		(net "P3V3_STBY")
	)
	(segment
		(start 399.2372 -87.4522)
		(end 399.2372 -87.122508)
		(width 0.254)
		(layer "B.Cu")
		(net "P3V3_STBY")
	)
	(segment
		(start 372.193312 -36.096448)
		(end 373.017288 -36.096448)
		(width 0.254)
		(layer "B.Cu")
		(net "P3V3_STBY")
	)
	(segment
		(start 489.26496 -151.06904)
		(end 489.144056 -151.06904)
		(width 0.254)
		(layer "B.Cu")
		(net "P3V3_STBY")
	)
	(segment
		(start 439.02884 -21.9583)
		(end 439.02884 -21.29282)
		(width 0.254)
		(layer "B.Cu")
		(net "P3V3_STBY")
	)
	(segment
		(start 177.611024 -68.054474)
		(end 177.33899 -68.326508)
		(width 0.254)
		(layer "B.Cu")
		(net "P3V3_STBY")
	)
	(segment
		(start 324.658482 -58.899044)
		(end 325.22795 -58.899044)
		(width 0.254)
		(layer "B.Cu")
		(net "P3V3_STBY")
	)
	(segment
		(start 394.843 -27.92476)
		(end 395.245336 -27.92476)
		(width 0.254)
		(layer "B.Cu")
		(net "P3V3_STBY")
	)
	(segment
		(start 390.144 -16.383)
		(end 390.144 -17.272)
		(width 0.254)
		(layer "B.Cu")
		(net "P3V3_STBY")
	)
	(segment
		(start 382.782826 -72.610726)
		(end 383.1971 -73.025)
		(width 0.254)
		(layer "B.Cu")
		(net "P3V3_STBY")
	)
	(segment
		(start 375.258838 -65.190878)
		(end 375.258838 -65.206372)
		(width 0.254)
		(layer "B.Cu")
		(net "P3V3_STBY")
	)
	(segment
		(start 373.945404 -75.495404)
		(end 374.344692 -75.894692)
		(width 0.254)
		(layer "B.Cu")
		(net "P3V3_STBY")
	)
	(segment
		(start 176.403 -69.989192)
		(end 176.043082 -70.34911)
		(width 0.254)
		(layer "B.Cu")
		(net "P3V3_STBY")
	)
	(segment
		(start 453.36841 -29.86659)
		(end 453.009 -30.226)
		(width 0.508)
		(layer "B.Cu")
		(net "P3V3_STBY")
	)
	(segment
		(start 262.491474 -87.81288)
		(end 261.226046 -87.81288)
		(width 0.1524)
		(layer "B.Cu")
		(net "P3V3_STBY")
	)
	(segment
		(start 446.8876 -63.1444)
		(end 446.532 -63.5)
		(width 0.254)
		(layer "B.Cu")
		(net "P3V3_STBY")
	)
	(segment
		(start 393.453112 -64.381888)
		(end 394.208 -63.627)
		(width 0.254)
		(layer "B.Cu")
		(net "P3V3_STBY")
	)
	(segment
		(start 455.549 -5.08)
		(end 455.549 -4.2164)
		(width 0.254)
		(layer "B.Cu")
		(net "P3V3_STBY")
	)
	(segment
		(start 491.078266 -29.423614)
		(end 491.078266 -26.76398)
		(width 0.381)
		(layer "B.Cu")
		(net "P3V3_STBY")
	)
	(segment
		(start 392.2522 -61.7728)
		(end 392.2522 -61.474604)
		(width 0.254)
		(layer "B.Cu")
		(net "P3V3_STBY")
	)
	(segment
		(start 368.576606 -28.534614)
		(end 369.115594 -28.534614)
		(width 0.381)
		(layer "B.Cu")
		(net "P3V3_STBY")
	)
	(segment
		(start 368.559334 -38.513004)
		(end 369.07343 -39.0271)
		(width 0.254)
		(layer "B.Cu")
		(net "P3V3_STBY")
	)
	(segment
		(start 489.08589 -32.240728)
		(end 487.62666 -30.781498)
		(width 0.508)
		(layer "B.Cu")
		(net "P3V3_STBY")
	)
	(segment
		(start 263.97331 -88.737694)
		(end 263.75868 -88.737694)
		(width 0.1524)
		(layer "B.Cu")
		(net "P3V3_STBY")
	)
	(segment
		(start 454.165208 -2.156714)
		(end 454.165208 -3.69062)
		(width 0.254)
		(layer "B.Cu")
		(net "P3V3_STBY")
	)
	(segment
		(start 487.1212 -36.3474)
		(end 486.3338 -35.56)
		(width 0.254)
		(layer "B.Cu")
		(net "P3V3_STBY")
	)
	(segment
		(start 13.453618 3.74396)
		(end 13.33119 3.621532)
		(width 0.254)
		(layer "B.Cu")
		(net "P3V3_STBY")
	)
	(segment
		(start 311.0738 -28.999688)
		(end 311.0738 -38.1381)
		(width 0.508)
		(layer "B.Cu")
		(net "P3V3_STBY")
	)
	(segment
		(start 374.059196 -72.295512)
		(end 374.344692 -72.581008)
		(width 0.254)
		(layer "B.Cu")
		(net "P3V3_STBY")
	)
	(segment
		(start 454.32726 -6.30174)
		(end 455.549 -5.08)
		(width 0.254)
		(layer "B.Cu")
		(net "P3V3_STBY")
	)
	(segment
		(start 394.35024 -27.92476)
		(end 393.7 -28.575)
		(width 0.254)
		(layer "B.Cu")
		(net "P3V3_STBY")
	)
	(segment
		(start 408.443176 -10.834624)
		(end 407.3652 -11.9126)
		(width 0.508)
		(layer "B.Cu")
		(net "P3V3_STBY")
	)
	(segment
		(start 398.47774 -154.8892)
		(end 397.251682 -156.115258)
		(width 0.254)
		(layer "B.Cu")
		(net "P3V3_STBY")
	)
	(segment
		(start 389.9662 -19.93646)
		(end 389.96874 -19.93392)
		(width 0.254)
		(layer "B.Cu")
		(net "P3V3_STBY")
	)
	(segment
		(start 369.115594 -28.534614)
		(end 369.202208 -28.448)
		(width 0.381)
		(layer "B.Cu")
		(net "P3V3_STBY")
	)
	(segment
		(start 28.054808 -103.401368)
		(end 29.092652 -103.401368)
		(width 0.254)
		(layer "B.Cu")
		(net "P3V3_STBY")
	)
	(segment
		(start 489.144056 -151.06904)
		(end 488.570016 -150.495)
		(width 0.254)
		(layer "B.Cu")
		(net "P3V3_STBY")
	)
	(segment
		(start 397.274288 -26.699718)
		(end 398.00657 -27.432)
		(width 0.254)
		(layer "B.Cu")
		(net "P3V3_STBY")
	)
	(segment
		(start 455.7014 -131.318)
		(end 454.8378 -130.4544)
		(width 0.254)
		(layer "B.Cu")
		(net "P3V3_STBY")
	)
	(segment
		(start 72.150478 -86.859364)
		(end 72.507094 -86.859364)
		(width 0.1524)
		(layer "B.Cu")
		(net "P3V3_STBY")
	)
	(segment
		(start 381.23622 -79.63916)
		(end 380.84506 -79.63916)
		(width 0.254)
		(layer "B.Cu")
		(net "P3V3_STBY")
	)
	(segment
		(start 389.867902 -15.726156)
		(end 389.867902 -14.528292)
		(width 0.254)
		(layer "B.Cu")
		(net "P3V3_STBY")
	)
	(segment
		(start 468.733378 -135.197596)
		(end 468.733378 -135.427212)
		(width 0.254)
		(layer "B.Cu")
		(net "P3V3_STBY")
	)
	(segment
		(start 372.5164 -91.604592)
		(end 372.5164 -91.567)
		(width 0.254)
		(layer "B.Cu")
		(net "P3V3_STBY")
	)
	(segment
		(start 435.3306 -21.6154)
		(end 435.3306 -22.3266)
		(width 0.254)
		(layer "B.Cu")
		(net "P3V3_STBY")
	)
	(segment
		(start 371.88902 -36.40074)
		(end 372.193312 -36.096448)
		(width 0.254)
		(layer "B.Cu")
		(net "P3V3_STBY")
	)
	(segment
		(start 179.199794 -69.230494)
		(end 179.199794 -68.347844)
		(width 0.254)
		(layer "B.Cu")
		(net "P3V3_STBY")
	)
	(segment
		(start 87.10168 -87.35441)
		(end 87.50427 -87.757)
		(width 0.1524)
		(layer "B.Cu")
		(net "P3V3_STBY")
	)
	(segment
		(start 367.157 -39.8272)
		(end 365.56696 -39.8272)
		(width 0.254)
		(layer "B.Cu")
		(net "P3V3_STBY")
	)
	(segment
		(start 402.082 -86.649306)
		(end 402.336 -86.903306)
		(width 0.254)
		(layer "B.Cu")
		(net "P3V3_STBY")
	)
	(segment
		(start 412.149036 -55.767478)
		(end 411.240224 -55.767478)
		(width 0.508)
		(layer "B.Cu")
		(net "P3V3_STBY")
	)
	(segment
		(start 463.55 -127.508)
		(end 463.55 -127.9398)
		(width 0.254)
		(layer "B.Cu")
		(net "P3V3_STBY")
	)
	(segment
		(start 404.48738 -28.04922)
		(end 404.48738 -28.03652)
		(width 0.254)
		(layer "B.Cu")
		(net "P3V3_STBY")
	)
	(segment
		(start 362.6866 -132.334)
		(end 362.1024 -132.9182)
		(width 0.381)
		(layer "B.Cu")
		(net "P3V3_STBY")
	)
	(segment
		(start 441.833 -148.971)
		(end 441.833 -148.49348)
		(width 0.254)
		(layer "B.Cu")
		(net "P3V3_STBY")
	)
	(segment
		(start 421.6019 -19.9263)
		(end 420.8653 -19.9263)
		(width 0.254)
		(layer "B.Cu")
		(net "P3V3_STBY")
	)
	(segment
		(start 259.8928 -88.7222)
		(end 258.844796 -88.7222)
		(width 0.1524)
		(layer "B.Cu")
		(net "P3V3_STBY")
	)
	(segment
		(start 437.5785 -149.7965)
		(end 437.0197 -149.7965)
		(width 0.254)
		(layer "B.Cu")
		(net "P3V3_STBY")
	)
	(segment
		(start 375.519696 -62.277752)
		(end 374.930162 -62.277752)
		(width 0.254)
		(layer "B.Cu")
		(net "P3V3_STBY")
	)
	(segment
		(start 327.578466 -58.069734)
		(end 327.95718 -58.448448)
		(width 0.254)
		(layer "B.Cu")
		(net "P3V3_STBY")
	)
	(segment
		(start 386.08 -86.808564)
		(end 386.274564 -86.614)
		(width 0.254)
		(layer "B.Cu")
		(net "P3V3_STBY")
	)
	(segment
		(start 411.49016 -32.534606)
		(end 411.479492 -32.523938)
		(width 0.508)
		(layer "B.Cu")
		(net "P3V3_STBY")
	)
	(segment
		(start 91.389454 -87.8332)
		(end 91.861386 -88.305132)
		(width 0.1524)
		(layer "B.Cu")
		(net "P3V3_STBY")
	)
	(segment
		(start 402.046186 -86.642448)
		(end 402.053044 -86.649306)
		(width 0.254)
		(layer "B.Cu")
		(net "P3V3_STBY")
	)
	(segment
		(start 375.881392 -62.277752)
		(end 376.627644 -61.5315)
		(width 0.254)
		(layer "B.Cu")
		(net "P3V3_STBY")
	)
	(segment
		(start 393.446 -27.686)
		(end 393.446 -26.903426)
		(width 0.254)
		(layer "B.Cu")
		(net "P3V3_STBY")
	)
	(segment
		(start 401.10283 -35.597846)
		(end 400.7358 -35.597846)
		(width 0.508)
		(layer "B.Cu")
		(net "P3V3_STBY")
	)
	(segment
		(start 423.418 -13.081)
		(end 423.164 -13.335)
		(width 0.254)
		(layer "B.Cu")
		(net "P3V3_STBY")
	)
	(segment
		(start 401.599146 -35.569652)
		(end 401.131024 -35.569652)
		(width 0.508)
		(layer "B.Cu")
		(net "P3V3_STBY")
	)
	(segment
		(start 69.439282 -87.224362)
		(end 70.06844 -87.224362)
		(width 0.1524)
		(layer "B.Cu")
		(net "P3V3_STBY")
	)
	(segment
		(start 432.079908 -45.307758)
		(end 432.435 -45.66285)
		(width 0.508)
		(layer "B.Cu")
		(net "P3V3_STBY")
	)
	(segment
		(start 27.0764 -77.089)
		(end 26.6446 -77.089)
		(width 0.254)
		(layer "B.Cu")
		(net "P3V3_STBY")
	)
	(segment
		(start 404.7744 -1.524508)
		(end 404.483062 -1.524508)
		(width 0.254)
		(layer "B.Cu")
		(net "P3V3_STBY")
	)
	(segment
		(start 415.9885 -4.318)
		(end 416.7251 -5.0546)
		(width 0.508)
		(layer "B.Cu")
		(net "P3V3_STBY")
	)
	(segment
		(start 379.476 -20.193)
		(end 379.476 -20.342098)
		(width 0.254)
		(layer "B.Cu")
		(net "P3V3_STBY")
	)
	(segment
		(start 164.084 -67.31)
		(end 163.6268 -67.31)
		(width 0.254)
		(layer "B.Cu")
		(net "P3V3_STBY")
	)
	(segment
		(start 419.318694 -46.298104)
		(end 420.077646 -45.539152)
		(width 0.508)
		(layer "B.Cu")
		(net "P3V3_STBY")
	)
	(segment
		(start 420.920926 -45.539152)
		(end 420.077646 -45.539152)
		(width 0.508)
		(layer "B.Cu")
		(net "P3V3_STBY")
	)
	(segment
		(start 410.742892 -3.072892)
		(end 410.742892 -2.704592)
		(width 0.254)
		(layer "B.Cu")
		(net "P3V3_STBY")
	)
	(segment
		(start 25.9842 -85.9028)
		(end 25.9842 -85.5218)
		(width 0.4064)
		(layer "B.Cu")
		(net "P3V3_STBY")
	)
	(segment
		(start 404.48738 -28.03652)
		(end 405.3459 -27.178)
		(width 0.254)
		(layer "B.Cu")
		(net "P3V3_STBY")
	)
	(segment
		(start 448.31 -147.066)
		(end 448.31 -146.963384)
		(width 0.254)
		(layer "B.Cu")
		(net "P3V3_STBY")
	)
	(segment
		(start 452.2978 -26.543)
		(end 450.5325 -26.543)
		(width 0.508)
		(layer "B.Cu")
		(net "P3V3_STBY")
	)
	(segment
		(start 450.6468 -130.2512)
		(end 449.7578 -129.3622)
		(width 0.254)
		(layer "B.Cu")
		(net "P3V3_STBY")
	)
	(segment
		(start 448.269614 -129.377186)
		(end 448.2846 -129.3622)
		(width 0.254)
		(layer "B.Cu")
		(net "P3V3_STBY")
	)
	(segment
		(start 419.354 -47.3202)
		(end 419.887146 -47.853346)
		(width 0.508)
		(layer "B.Cu")
		(net "P3V3_STBY")
	)
	(segment
		(start 12.986004 -86.008718)
		(end 13.413486 -86.4362)
		(width 0.254)
		(layer "B.Cu")
		(net "P3V3_STBY")
	)
	(segment
		(start 469.133174 -134.7978)
		(end 468.733378 -135.197596)
		(width 0.254)
		(layer "B.Cu")
		(net "P3V3_STBY")
	)
	(segment
		(start 352.933 -91.567)
		(end 352.933 -91.3892)
		(width 0.254)
		(layer "B.Cu")
		(net "P3V3_STBY")
	)
	(segment
		(start 407.035 -27.94)
		(end 406.654 -27.559)
		(width 0.254)
		(layer "B.Cu")
		(net "P3V3_STBY")
	)
	(segment
		(start 0.381 -74.93)
		(end 0.381 -76.98613)
		(width 0.254)
		(layer "B.Cu")
		(net "P3V3_STBY")
	)
	(segment
		(start 25.9842 -85.5218)
		(end 26.2128 -85.2932)
		(width 0.4064)
		(layer "B.Cu")
		(net "P3V3_STBY")
	)
	(segment
		(start 452.5772 -148.59)
		(end 452.5772 -147.944078)
		(width 0.254)
		(layer "B.Cu")
		(net "P3V3_STBY")
	)
	(segment
		(start 422.91 -5.0165)
		(end 422.4655 -5.0165)
		(width 0.508)
		(layer "B.Cu")
		(net "P3V3_STBY")
	)
	(segment
		(start 377.2027 -54.8005)
		(end 377.1265 -54.8005)
		(width 0.254)
		(layer "B.Cu")
		(net "P3V3_STBY")
	)
	(segment
		(start 393.003786 -14.85011)
		(end 390.597136 -14.85011)
		(width 0.254)
		(layer "B.Cu")
		(net "P3V3_STBY")
	)
	(segment
		(start 90.141552 -88.305132)
		(end 90.572844 -88.305132)
		(width 0.1524)
		(layer "B.Cu")
		(net "P3V3_STBY")
	)
	(segment
		(start 411.505146 -9.779)
		(end 411.226 -9.779)
		(width 0.254)
		(layer "B.Cu")
		(net "P3V3_STBY")
	)
	(segment
		(start 179.206144 -67.049142)
		(end 178.527202 -66.3702)
		(width 0.254)
		(layer "B.Cu")
		(net "P3V3_STBY")
	)
	(segment
		(start 401.2946 -153.9367)
		(end 400.97964 -153.9367)
		(width 0.254)
		(layer "B.Cu")
		(net "P3V3_STBY")
	)
	(segment
		(start 409.636722 -57.37098)
		(end 408.18816 -57.37098)
		(width 0.508)
		(layer "B.Cu")
		(net "P3V3_STBY")
	)
	(segment
		(start 499.491 -139.8524)
		(end 499.3894 -139.954)
		(width 0.254)
		(layer "B.Cu")
		(net "P3V3_STBY")
	)
	(segment
		(start 375.412 -66.04)
		(end 374.65 -66.04)
		(width 0.254)
		(layer "B.Cu")
		(net "P3V3_STBY")
	)
	(segment
		(start 499.084854 -35.458146)
		(end 499.967504 -35.458146)
		(width 0.254)
		(layer "B.Cu")
		(net "P3V3_STBY")
	)
	(segment
		(start 269.984982 -91.474544)
		(end 269.984982 -91.075764)
		(width 0.1524)
		(layer "B.Cu")
		(net "P3V3_STBY")
	)
	(segment
		(start 89.2175 -87.8332)
		(end 89.66962 -87.8332)
		(width 0.1524)
		(layer "B.Cu")
		(net "P3V3_STBY")
	)
	(segment
		(start 19.340322 -46.486826)
		(end 19.340322 -46.233842)
		(width 0.254)
		(layer "B.Cu")
		(net "P3V3_STBY")
	)
	(segment
		(start 374.2055 -6.1595)
		(end 373.761 -6.1595)
		(width 0.381)
		(layer "B.Cu")
		(net "P3V3_STBY")
	)
	(segment
		(start 472.1098 -144.289272)
		(end 472.104974 -144.294098)
		(width 0.254)
		(layer "B.Cu")
		(net "P3V3_STBY")
	)
	(segment
		(start 500.253 -149.9362)
		(end 500.253 -149.4028)
		(width 0.254)
		(layer "B.Cu")
		(net "P3V3_STBY")
	)
	(segment
		(start 489.4453 -33.674812)
		(end 489.08589 -33.674812)
		(width 0.508)
		(layer "B.Cu")
		(net "P3V3_STBY")
	)
	(segment
		(start 420.923466 -45.536612)
		(end 420.920926 -45.539152)
		(width 0.508)
		(layer "B.Cu")
		(net "P3V3_STBY")
	)
	(segment
		(start 351.93732 -83.510628)
		(end 352.354388 -83.510628)
		(width 0.254)
		(layer "B.Cu")
		(net "P3V3_STBY")
	)
	(segment
		(start 460.8576 -126.7714)
		(end 461.0608 -126.9746)
		(width 0.254)
		(layer "B.Cu")
		(net "P3V3_STBY")
	)
	(segment
		(start 489.767372 -44.562522)
		(end 489.684314 -44.562522)
		(width 0.254)
		(layer "B.Cu")
		(net "P3V3_STBY")
	)
	(segment
		(start 427.255432 -18.887948)
		(end 427.364652 -18.887948)
		(width 0.254)
		(layer "B.Cu")
		(net "P3V3_STBY")
	)
	(segment
		(start 337.1596 -86.413086)
		(end 336.8802 -86.692486)
		(width 0.4064)
		(layer "B.Cu")
		(net "P3V3_STBY")
	)
	(segment
		(start 374.744742 -73.095104)
		(end 374.344692 -73.495154)
		(width 0.254)
		(layer "B.Cu")
		(net "P3V3_STBY")
	)
	(segment
		(start 458.597 -143.0274)
		(end 458.47 -142.9004)
		(width 0.254)
		(layer "B.Cu")
		(net "P3V3_STBY")
	)
	(segment
		(start 67.740276 -87.27948)
		(end 68.25488 -87.27948)
		(width 0.1524)
		(layer "B.Cu")
		(net "P3V3_STBY")
	)
	(segment
		(start 473.542106 -129.42824)
		(end 474.14942 -129.42824)
		(width 0.254)
		(layer "B.Cu")
		(net "P3V3_STBY")
	)
	(segment
		(start 401.5613 -39.953946)
		(end 401.5613 -39.5224)
		(width 0.508)
		(layer "B.Cu")
		(net "P3V3_STBY")
	)
	(segment
		(start 390.144 -16.002254)
		(end 389.867902 -15.726156)
		(width 0.254)
		(layer "B.Cu")
		(net "P3V3_STBY")
	)
	(segment
		(start 392.041888 -115.315746)
		(end 392.041888 -114.751612)
		(width 0.4064)
		(layer "B.Cu")
		(net "P3V3_STBY")
	)
	(segment
		(start 379.087634 -45.564298)
		(end 379.087634 -45.52696)
		(width 0.254)
		(layer "B.Cu")
		(net "P3V3_STBY")
	)
	(segment
		(start 454.8378 -130.4544)
		(end 454.4822 -130.4544)
		(width 0.254)
		(layer "B.Cu")
		(net "P3V3_STBY")
	)
	(segment
		(start 442.3918 -140.554202)
		(end 442.5188 -140.427202)
		(width 0.254)
		(layer "B.Cu")
		(net "P3V3_STBY")
	)
	(segment
		(start 267.9446 -89.78646)
		(end 267.806932 -89.648792)
		(width 0.1524)
		(layer "B.Cu")
		(net "P3V3_STBY")
	)
	(segment
		(start 479.7552 -43.4086)
		(end 479.9838 -43.4086)
		(width 0.254)
		(layer "B.Cu")
		(net "P3V3_STBY")
	)
	(segment
		(start 492.0742 -131.1656)
		(end 492.3536 -131.445)
		(width 0.254)
		(layer "B.Cu")
		(net "P3V3_STBY")
	)
	(segment
		(start 442.8744 -141.5542)
		(end 443.1538 -141.8336)
		(width 0.254)
		(layer "B.Cu")
		(net "P3V3_STBY")
	)
	(segment
		(start 381.4826 -3.185414)
		(end 381.4826 -2.870454)
		(width 0.254)
		(layer "B.Cu")
		(net "P3V3_STBY")
	)
	(segment
		(start 367.792 -42.58056)
		(end 367.792 -40.0812)
		(width 0.254)
		(layer "B.Cu")
		(net "P3V3_STBY")
	)
	(segment
		(start 452.2978 -27.048968)
		(end 452.946008 -27.697176)
		(width 0.508)
		(layer "B.Cu")
		(net "P3V3_STBY")
	)
	(segment
		(start 379.088142 -45.52696)
		(end 379.088142 -45.509942)
		(width 0.254)
		(layer "B.Cu")
		(net "P3V3_STBY")
	)
	(segment
		(start 63.2968 -91.1352)
		(end 63.2968 -92.1512)
		(width 0.4064)
		(layer "B.Cu")
		(net "P3V3_STBY")
	)
	(segment
		(start 377.144788 -70.695058)
		(end 376.744738 -71.095108)
		(width 0.254)
		(layer "B.Cu")
		(net "P3V3_STBY")
	)
	(segment
		(start 477.1644 -48.777144)
		(end 478.142808 -49.755552)
		(width 0.508)
		(layer "B.Cu")
		(net "P3V3_STBY")
	)
	(segment
		(start 362.65104 -55.16372)
		(end 361.559094 -56.255666)
		(width 0.254)
		(layer "B.Cu")
		(net "P3V3_STBY")
	)
	(segment
		(start 481.1268 -119.4308)
		(end 480.130866 -119.4308)
		(width 0.254)
		(layer "B.Cu")
		(net "P3V3_STBY")
	)
	(segment
		(start 269.216886 -90.742516)
		(end 269.09903 -90.62466)
		(width 0.1524)
		(layer "B.Cu")
		(net "P3V3_STBY")
	)
	(segment
		(start 70.06844 -87.224362)
		(end 70.433438 -86.859364)
		(width 0.1524)
		(layer "B.Cu")
		(net "P3V3_STBY")
	)
	(segment
		(start 423.632376 -3.976624)
		(end 423.418 -4.191)
		(width 0.508)
		(layer "B.Cu")
		(net "P3V3_STBY")
	)
	(segment
		(start 394.208 -62.738)
		(end 394.208 -63.627)
		(width 0.254)
		(layer "B.Cu")
		(net "P3V3_STBY")
	)
	(segment
		(start 72.507094 -86.859364)
		(end 72.872092 -87.224362)
		(width 0.1524)
		(layer "B.Cu")
		(net "P3V3_STBY")
	)
	(segment
		(start 491.591346 -34.7472)
		(end 490.78896 -34.7472)
		(width 0.508)
		(layer "B.Cu")
		(net "P3V3_STBY")
	)
	(segment
		(start 67.272916 -87.74684)
		(end 67.740276 -87.27948)
		(width 0.1524)
		(layer "B.Cu")
		(net "P3V3_STBY")
	)
	(segment
		(start 406.4762 -13.3096)
		(end 406.4762 -13.8303)
		(width 0.508)
		(layer "B.Cu")
		(net "P3V3_STBY")
	)
	(segment
		(start 499.618 -131.6228)
		(end 499.618 -132.4356)
		(width 0.254)
		(layer "B.Cu")
		(net "P3V3_STBY")
	)
	(segment
		(start 403.8854 2.4384)
		(end 404.2918 2.4384)
		(width 0.254)
		(layer "B.Cu")
		(net "P3V3_STBY")
	)
	(segment
		(start 473.701872 -145.495264)
		(end 473.701872 -145.864072)
		(width 0.254)
		(layer "B.Cu")
		(net "P3V3_STBY")
	)
	(segment
		(start 376.627644 -61.5315)
		(end 377.3043 -61.5315)
		(width 0.254)
		(layer "B.Cu")
		(net "P3V3_STBY")
	)
	(segment
		(start 392.2522 -62.382908)
		(end 391.917936 -62.717172)
		(width 0.1016)
		(layer "B.Cu")
		(net "P3V3_STBY")
	)
	(segment
		(start 452.278242 -29.786326)
		(end 452.569326 -29.786326)
		(width 0.508)
		(layer "B.Cu")
		(net "P3V3_STBY")
	)
	(segment
		(start 416.7251 -5.0546)
		(end 416.7251 -6.04901)
		(width 0.508)
		(layer "B.Cu")
		(net "P3V3_STBY")
	)
	(segment
		(start 447.079878 -153.2509)
		(end 447.079878 -152.842722)
		(width 0.254)
		(layer "B.Cu")
		(net "P3V3_STBY")
	)
	(segment
		(start 408.7876 -14.097)
		(end 408.722576 -14.031976)
		(width 0.4064)
		(layer "B.Cu")
		(net "P3V3_STBY")
	)
	(segment
		(start 394.175234 -150.95474)
		(end 394.439394 -150.95474)
		(width 0.254)
		(layer "B.Cu")
		(net "P3V3_STBY")
	)
	(segment
		(start 412.2293 -7.4295)
		(end 412.623 -7.8232)
		(width 0.254)
		(layer "B.Cu")
		(net "P3V3_STBY")
	)
	(segment
		(start 74.6887 -87.314532)
		(end 75.119992 -87.314532)
		(width 0.1524)
		(layer "B.Cu")
		(net "P3V3_STBY")
	)
	(segment
		(start 480.78644 -49.39284)
		(end 481.44049 -50.04689)
		(width 0.508)
		(layer "B.Cu")
		(net "P3V3_STBY")
	)
	(segment
		(start 69.074284 -86.859364)
		(end 69.439282 -87.224362)
		(width 0.1524)
		(layer "B.Cu")
		(net "P3V3_STBY")
	)
	(segment
		(start 452.487792 -147.85467)
		(end 452.487792 -147.39874)
		(width 0.254)
		(layer "B.Cu")
		(net "P3V3_STBY")
	)
	(segment
		(start 427.9519 -18.3007)
		(end 427.9519 -18.034)
		(width 0.254)
		(layer "B.Cu")
		(net "P3V3_STBY")
	)
	(segment
		(start 406.7175 -13.0683)
		(end 406.4762 -13.3096)
		(width 0.508)
		(layer "B.Cu")
		(net "P3V3_STBY")
	)
	(segment
		(start 386.66166 -86.614)
		(end 387.75894 -85.51672)
		(width 0.254)
		(layer "B.Cu")
		(net "P3V3_STBY")
	)
	(segment
		(start 488.696 -18.161)
		(end 489.022136 -18.161)
		(width 0.254)
		(layer "B.Cu")
		(net "P3V3_STBY")
	)
	(segment
		(start 16.7132 -86.5759)
		(end 16.7132 -86.0806)
		(width 0.254)
		(layer "B.Cu")
		(net "P3V3_STBY")
	)
	(segment
		(start 269.304516 -90.794078)
		(end 269.252954 -90.742516)
		(width 0.1524)
		(layer "B.Cu")
		(net "P3V3_STBY")
	)
	(segment
		(start 369.945158 -78.040484)
		(end 369.945158 -77.896212)
		(width 0.254)
		(layer "B.Cu")
		(net "P3V3_STBY")
	)
	(segment
		(start 453.6948 -145.9738)
		(end 453.4916 -145.9738)
		(width 0.254)
		(layer "B.Cu")
		(net "P3V3_STBY")
	)
	(segment
		(start 492.0742 -129.2606)
		(end 492.0742 -131.1656)
		(width 0.254)
		(layer "B.Cu")
		(net "P3V3_STBY")
	)
	(segment
		(start 381.49022 -79.12354)
		(end 381.49022 -79.38516)
		(width 0.254)
		(layer "B.Cu")
		(net "P3V3_STBY")
	)
	(segment
		(start 63.79972 -88.03894)
		(end 66.20002 -88.03894)
		(width 0.254)
		(layer "B.Cu")
		(net "P3V3_STBY")
	)
	(segment
		(start 462.8134 -126.7714)
		(end 463.55 -127.508)
		(width 0.254)
		(layer "B.Cu")
		(net "P3V3_STBY")
	)
	(segment
		(start 73.50252 -87.224362)
		(end 73.867518 -86.859364)
		(width 0.1524)
		(layer "B.Cu")
		(net "P3V3_STBY")
	)
	(segment
		(start 396.875 -37.846)
		(end 396.846298 -37.817298)
		(width 0.254)
		(layer "B.Cu")
		(net "P3V3_STBY")
	)
	(segment
		(start 487.162856 -39.7002)
		(end 486.7402 -39.7002)
		(width 0.254)
		(layer "B.Cu")
		(net "P3V3_STBY")
	)
	(segment
		(start 400.02714 -154.8892)
		(end 398.47774 -154.8892)
		(width 0.254)
		(layer "B.Cu")
		(net "P3V3_STBY")
	)
	(segment
		(start 392.041888 -114.751612)
		(end 392.1379 -114.6556)
		(width 0.4064)
		(layer "B.Cu")
		(net "P3V3_STBY")
	)
	(segment
		(start 396.113 -87.3125)
		(end 396.113 -86.637368)
		(width 0.254)
		(layer "B.Cu")
		(net "P3V3_STBY")
	)
	(segment
		(start 386.274564 -86.614)
		(end 386.66166 -86.614)
		(width 0.254)
		(layer "B.Cu")
		(net "P3V3_STBY")
	)
	(segment
		(start 501.0658 -148.59)
		(end 501.0658 -146.4056)
		(width 0.254)
		(layer "B.Cu")
		(net "P3V3_STBY")
	)
	(segment
		(start 393.493498 -26.597102)
		(end 393.647676 -26.597102)
		(width 0.254)
		(layer "B.Cu")
		(net "P3V3_STBY")
	)
	(segment
		(start 393.1031 -64.381888)
		(end 393.453112 -64.381888)
		(width 0.254)
		(layer "B.Cu")
		(net "P3V3_STBY")
	)
	(segment
		(start 417.11372 -50.184558)
		(end 416.01898 -50.184558)
		(width 0.254)
		(layer "B.Cu")
		(net "P3V3_STBY")
	)
	(segment
		(start 496.67668 -130.52552)
		(end 496.34648 -130.52552)
		(width 0.381)
		(layer "B.Cu")
		(net "P3V3_STBY")
	)
	(segment
		(start 392.2141 -104.1781)
		(end 392.6586 -104.6226)
		(width 0.3556)
		(layer "B.Cu")
		(net "P3V3_STBY")
	)
	(segment
		(start 496.34648 -130.52552)
		(end 495.45748 -130.52552)
		(width 0.254)
		(layer "B.Cu")
		(net "P3V3_STBY")
	)
	(segment
		(start 66.20002 -88.03894)
		(end 66.49212 -87.74684)
		(width 0.254)
		(layer "B.Cu")
		(net "P3V3_STBY")
	)
	(segment
		(start 458.47 -142.9004)
		(end 457.8096 -142.9004)
		(width 0.254)
		(layer "B.Cu")
		(net "P3V3_STBY")
	)
	(segment
		(start 371.88902 -38.47338)
		(end 371.88902 -36.40074)
		(width 0.254)
		(layer "B.Cu")
		(net "P3V3_STBY")
	)
	(segment
		(start 418.0078 -54.3687)
		(end 417.821872 -54.3687)
		(width 0.508)
		(layer "B.Cu")
		(net "P3V3_STBY")
	)
	(segment
		(start 82.679032 -86.729316)
		(end 83.264248 -87.314532)
		(width 0.1524)
		(layer "B.Cu")
		(net "P3V3_STBY")
	)
	(segment
		(start 455.7014 -132.5626)
		(end 455.7014 -131.318)
		(width 0.254)
		(layer "B.Cu")
		(net "P3V3_STBY")
	)
	(segment
		(start 423.291 -2.667)
		(end 423.632376 -3.008376)
		(width 0.508)
		(layer "B.Cu")
		(net "P3V3_STBY")
	)
	(segment
		(start 407.3652 -13.0683)
		(end 406.7175 -13.0683)
		(width 0.508)
		(layer "B.Cu")
		(net "P3V3_STBY")
	)
	(segment
		(start 500.6086 -145.9484)
		(end 500.3292 -145.9484)
		(width 0.254)
		(layer "B.Cu")
		(net "P3V3_STBY")
	)
	(segment
		(start 362.839 -132.334)
		(end 362.6866 -132.334)
		(width 0.381)
		(layer "B.Cu")
		(net "P3V3_STBY")
	)
	(segment
		(start 26.5684 -82.5246)
		(end 25.908 -83.185)
		(width 0.254)
		(layer "B.Cu")
		(net "P3V3_STBY")
	)
	(segment
		(start 404.101046 -25.600152)
		(end 404.101046 -24.8539)
		(width 0.254)
		(layer "B.Cu")
		(net "P3V3_STBY")
	)
	(segment
		(start 420.52113 -52.796694)
		(end 420.529766 -52.788058)
		(width 0.508)
		(layer "B.Cu")
		(net "P3V3_STBY")
	)
	(segment
		(start 374.1928 -53.8099)
		(end 374.4976 -53.8099)
		(width 0.254)
		(layer "B.Cu")
		(net "P3V3_STBY")
	)
	(segment
		(start 91.861386 -88.305132)
		(end 92.331032 -88.305132)
		(width 0.1524)
		(layer "B.Cu")
		(net "P3V3_STBY")
	)
	(segment
		(start 391.917936 -62.717172)
		(end 391.67562 -62.717172)
		(width 0.1016)
		(layer "B.Cu")
		(net "P3V3_STBY")
	)
	(segment
		(start 179.199794 -68.347844)
		(end 179.206144 -68.341494)
		(width 0.254)
		(layer "B.Cu")
		(net "P3V3_STBY")
	)
	(segment
		(start 461.646778 -144.526254)
		(end 461.30845 -144.187926)
		(width 0.4064)
		(layer "B.Cu")
		(net "P3V3_STBY")
	)
	(segment
		(start 452.946008 -27.697176)
		(end 453.36841 -28.119578)
		(width 0.508)
		(layer "B.Cu")
		(net "P3V3_STBY")
	)
	(segment
		(start 486.6386 -141.224)
		(end 487.045 -140.8176)
		(width 0.254)
		(layer "B.Cu")
		(net "P3V3_STBY")
	)
	(segment
		(start 371.983 -6.1595)
		(end 372.872 -6.1595)
		(width 0.4572)
		(layer "B.Cu")
		(net "P3V3_STBY")
	)
	(segment
		(start 404.028656 -52.926996)
		(end 404.763732 -52.19192)
		(width 0.508)
		(layer "B.Cu")
		(net "P3V3_STBY")
	)
	(segment
		(start 478.8662 -44.1198)
		(end 479.1456 -43.8404)
		(width 0.254)
		(layer "B.Cu")
		(net "P3V3_STBY")
	)
	(segment
		(start 448.5259 -3.1877)
		(end 450.088 -4.7498)
		(width 0.254)
		(layer "B.Cu")
		(net "P3V3_STBY")
	)
	(segment
		(start 447.657982 -146.393662)
		(end 447.69913 -146.352514)
		(width 0.254)
		(layer "B.Cu")
		(net "P3V3_STBY")
	)
	(segment
		(start -1.44526 -119.46636)
		(end -2.20726 -119.46636)
		(width 0.254)
		(layer "B.Cu")
		(net "P3V3_STBY")
	)
	(segment
		(start 454.438258 -32.306006)
		(end 454.438258 -32.126174)
		(width 0.254)
		(layer "B.Cu")
		(net "P3V3_STBY")
	)
	(segment
		(start 427.255432 -18.883376)
		(end 427.255432 -18.887948)
		(width 0.254)
		(layer "B.Cu")
		(net "P3V3_STBY")
	)
	(segment
		(start 453.36841 -28.119578)
		(end 453.36841 -29.86659)
		(width 0.508)
		(layer "B.Cu")
		(net "P3V3_STBY")
	)
	(segment
		(start 488.2515 -42.6085)
		(end 488.3404 -42.5196)
		(width 0.254)
		(layer "B.Cu")
		(net "P3V3_STBY")
	)
	(segment
		(start 26.289 -77.3938)
		(end 26.289 -77.5462)
		(width 0.254)
		(layer "B.Cu")
		(net "P3V3_STBY")
	)
	(segment
		(start 481.44049 -50.04689)
		(end 482.15931 -50.04689)
		(width 0.508)
		(layer "B.Cu")
		(net "P3V3_STBY")
	)
	(segment
		(start 367.792 -40.0812)
		(end 367.538 -39.8272)
		(width 0.254)
		(layer "B.Cu")
		(net "P3V3_STBY")
	)
	(segment
		(start 473.719652 -145.477484)
		(end 473.719652 -144.348708)
		(width 0.254)
		(layer "B.Cu")
		(net "P3V3_STBY")
	)
	(segment
		(start 422.91 -5.0165)
		(end 422.91 -4.953)
		(width 0.508)
		(layer "B.Cu")
		(net "P3V3_STBY")
	)
	(segment
		(start 260.37286 -88.24214)
		(end 259.8928 -88.7222)
		(width 0.1524)
		(layer "B.Cu")
		(net "P3V3_STBY")
	)
	(segment
		(start 476.4151 -36.2712)
		(end 476.2627 -36.195)
		(width 0.254)
		(layer "B.Cu")
		(net "P3V3_STBY")
	)
	(segment
		(start 174.954946 -64.973454)
		(end 176.428146 -64.973454)
		(width 0.254)
		(layer "B.Cu")
		(net "P3V3_STBY")
	)
	(segment
		(start 453.4916 -145.9738)
		(end 453.0598 -146.4056)
		(width 0.254)
		(layer "B.Cu")
		(net "P3V3_STBY")
	)
	(segment
		(start 490.3724 -34.33064)
		(end 490.3724 -34.300414)
		(width 0.508)
		(layer "B.Cu")
		(net "P3V3_STBY")
	)
	(segment
		(start 24.257 -85.4329)
		(end 23.96744 -85.14334)
		(width 0.254)
		(layer "B.Cu")
		(net "P3V3_STBY")
	)
	(segment
		(start 369.03533 -77.096112)
		(end 368.745262 -77.38618)
		(width 0.254)
		(layer "B.Cu")
		(net "P3V3_STBY")
	)
	(segment
		(start 454.438258 -32.126174)
		(end 454.311258 -31.999174)
		(width 0.254)
		(layer "B.Cu")
		(net "P3V3_STBY")
	)
	(segment
		(start 379.60046 -80.35036)
		(end 379.144784 -79.894684)
		(width 0.254)
		(layer "B.Cu")
		(net "P3V3_STBY")
	)
	(segment
		(start 405.219408 -93.755718)
		(end 405.44369 -93.98)
		(width 0.254)
		(layer "B.Cu")
		(net "P3V3_STBY")
	)
	(segment
		(start 440.67222 -58.02376)
		(end 440.40552 -58.29046)
		(width 0.381)
		(layer "B.Cu")
		(net "P3V3_STBY")
	)
	(segment
		(start 423.632376 -3.008376)
		(end 423.632376 -3.976624)
		(width 0.508)
		(layer "B.Cu")
		(net "P3V3_STBY")
	)
	(segment
		(start 452.487792 -147.39874)
		(end 452.4883 -147.398232)
		(width 0.254)
		(layer "B.Cu")
		(net "P3V3_STBY")
	)
	(segment
		(start 405.3459 -27.178)
		(end 406.654 -27.178)
		(width 0.254)
		(layer "B.Cu")
		(net "P3V3_STBY")
	)
	(segment
		(start 331.343 -12.260834)
		(end 332.899766 -13.8176)
		(width 0.254)
		(layer "B.Cu")
		(net "P3V3_STBY")
	)
	(segment
		(start 86.68639 -87.35441)
		(end 87.10168 -87.35441)
		(width 0.1524)
		(layer "B.Cu")
		(net "P3V3_STBY")
	)
	(segment
		(start 483.0572 -48.5267)
		(end 484.0732 -48.5267)
		(width 0.508)
		(layer "B.Cu")
		(net "P3V3_STBY")
	)
	(segment
		(start 440.40552 -58.29046)
		(end 440.40552 -59.13374)
		(width 0.381)
		(layer "B.Cu")
		(net "P3V3_STBY")
	)
	(segment
		(start 344.678 -82.4992)
		(end 344.678 -82.677)
		(width 0.254)
		(layer "B.Cu")
		(net "P3V3_STBY")
	)
	(segment
		(start 170.0022 -128.016)
		(end 169.4942 -128.016)
		(width 0.254)
		(layer "B.Cu")
		(net "P3V3_STBY")
	)
	(segment
		(start 392.2522 -61.7728)
		(end 391.639806 -61.7728)
		(width 0.254)
		(layer "B.Cu")
		(net "P3V3_STBY")
	)
	(segment
		(start 454.258934 -2.062988)
		(end 454.165208 -2.156714)
		(width 0.254)
		(layer "B.Cu")
		(net "P3V3_STBY")
	)
	(segment
		(start 63.2968 -88.54186)
		(end 63.79972 -88.03894)
		(width 0.254)
		(layer "B.Cu")
		(net "P3V3_STBY")
	)
	(segment
		(start 451.163182 -6.422898)
		(end 451.50151 -6.761226)
		(width 0.254)
		(layer "B.Cu")
		(net "P3V3_STBY")
	)
	(segment
		(start 487.73588 -30.226)
		(end 488.09148 -29.8704)
		(width 0.381)
		(layer "B.Cu")
		(net "P3V3_STBY")
	)
	(segment
		(start 373.126 -75.5015)
		(end 373.151654 -75.5015)
		(width 0.254)
		(layer "B.Cu")
		(net "P3V3_STBY")
	)
	(segment
		(start 386.08 -87.3125)
		(end 386.08 -86.808564)
		(width 0.254)
		(layer "B.Cu")
		(net "P3V3_STBY")
	)
	(segment
		(start 491.896146 -35.052)
		(end 491.591346 -34.7472)
		(width 0.508)
		(layer "B.Cu")
		(net "P3V3_STBY")
	)
	(segment
		(start 442.3918 -141.062202)
		(end 442.3918 -141.2494)
		(width 0.254)
		(layer "B.Cu")
		(net "P3V3_STBY")
	)
	(segment
		(start 439.481976 -157.1498)
		(end 439.478928 -157.152848)
		(width 0.254)
		(layer "B.Cu")
		(net "P3V3_STBY")
	)
	(segment
		(start 92.75318 -88.72728)
		(end 93.743272 -88.72728)
		(width 0.1524)
		(layer "B.Cu")
		(net "P3V3_STBY")
	)
	(segment
		(start 476.414084 -135.41756)
		(end 477.173544 -135.41756)
		(width 0.254)
		(layer "B.Cu")
		(net "P3V3_STBY")
	)
	(segment
		(start 393.446 -28.575)
		(end 393.446 -29.355034)
		(width 0.254)
		(layer "B.Cu")
		(net "P3V3_STBY")
	)
	(segment
		(start 379.08992 -82.74812)
		(end 379.0188 -82.677)
		(width 0.254)
		(layer "B.Cu")
		(net "P3V3_STBY")
	)
	(segment
		(start 401.472146 -40.598852)
		(end 401.472146 -40.0431)
		(width 0.508)
		(layer "B.Cu")
		(net "P3V3_STBY")
	)
	(segment
		(start 372.980966 -72.678036)
		(end 373.527574 -72.678036)
		(width 0.254)
		(layer "B.Cu")
		(net "P3V3_STBY")
	)
	(segment
		(start 482.24186 -141.67866)
		(end 482.512116 -141.948916)
		(width 0.254)
		(layer "B.Cu")
		(net "P3V3_STBY")
	)
	(segment
		(start 458.597 -153.924)
		(end 458.47 -154.051)
		(width 0.508)
		(layer "B.Cu")
		(net "P3V3_STBY")
	)
	(segment
		(start 411.479492 -32.523938)
		(end 411.479492 -31.107888)
		(width 0.508)
		(layer "B.Cu")
		(net "P3V3_STBY")
	)
	(segment
		(start 485.942894 4.966716)
		(end 485.938322 4.971288)
		(width 0.508)
		(layer "B.Cu")
		(net "P3V3_STBY")
	)
	(segment
		(start 477.7994 -44.704)
		(end 478.3836 -44.1198)
		(width 0.254)
		(layer "B.Cu")
		(net "P3V3_STBY")
	)
	(segment
		(start 483.616 -30.607)
		(end 482.854 -31.369)
		(width 0.254)
		(layer "B.Cu")
		(net "P3V3_STBY")
	)
	(segment
		(start 419.2524 -47.3202)
		(end 419.354 -47.3202)
		(width 0.508)
		(layer "B.Cu")
		(net "P3V3_STBY")
	)
	(segment
		(start 19.05 -45.72)
		(end 18.161 -45.72)
		(width 0.254)
		(layer "B.Cu")
		(net "P3V3_STBY")
	)
	(segment
		(start 477.139 -48.514)
		(end 477.1644 -48.5394)
		(width 0.508)
		(layer "B.Cu")
		(net "P3V3_STBY")
	)
	(segment
		(start 446.9892 -17.3482)
		(end 446.9892 -16.76146)
		(width 0.254)
		(layer "B.Cu")
		(net "P3V3_STBY")
	)
	(segment
		(start 401.5613 -36.369498)
		(end 401.599146 -36.331652)
		(width 0.508)
		(layer "B.Cu")
		(net "P3V3_STBY")
	)
	(segment
		(start 401.5613 -37.1094)
		(end 401.5613 -36.369498)
		(width 0.508)
		(layer "B.Cu")
		(net "P3V3_STBY")
	)
	(segment
		(start 178.0032 -66.3702)
		(end 177.548794 -66.824606)
		(width 0.254)
		(layer "B.Cu")
		(net "P3V3_STBY")
	)
	(segment
		(start 487.7054 -36.3474)
		(end 487.7054 -37.428932)
		(width 0.254)
		(layer "B.Cu")
		(net "P3V3_STBY")
	)
	(segment
		(start 452.569326 -29.786326)
		(end 453.009 -30.226)
		(width 0.508)
		(layer "B.Cu")
		(net "P3V3_STBY")
	)
	(segment
		(start 379.088142 -45.509942)
		(end 379.3998 -45.8216)
		(width 0.254)
		(layer "B.Cu")
		(net "P3V3_STBY")
	)
	(segment
		(start 77.2922 -86.859364)
		(end 77.705204 -86.859364)
		(width 0.1524)
		(layer "B.Cu")
		(net "P3V3_STBY")
	)
	(segment
		(start 326.96531 -57.916318)
		(end 327.578466 -57.916318)
		(width 0.254)
		(layer "B.Cu")
		(net "P3V3_STBY")
	)
	(segment
		(start 398.15008 -33.848294)
		(end 397.886174 -33.584388)
		(width 0.254)
		(layer "B.Cu")
		(net "P3V3_STBY")
	)
	(segment
		(start 394.439394 -150.95474)
		(end 395.173454 -151.6888)
		(width 0.254)
		(layer "B.Cu")
		(net "P3V3_STBY")
	)
	(segment
		(start 369.545108 -70.295262)
		(end 369.545108 -70.19671)
		(width 0.254)
		(layer "B.Cu")
		(net "P3V3_STBY")
	)
	(segment
		(start 178.0032 -66.3702)
		(end 177.824892 -66.3702)
		(width 0.254)
		(layer "B.Cu")
		(net "P3V3_STBY")
	)
	(segment
		(start 428.244 -42.0751)
		(end 428.095664 -42.223436)
		(width 0.508)
		(layer "B.Cu")
		(net "P3V3_STBY")
	)
	(segment
		(start 327.578466 -57.916318)
		(end 327.578466 -58.069734)
		(width 0.254)
		(layer "B.Cu")
		(net "P3V3_STBY")
	)
	(segment
		(start 404.5585 -98.679)
		(end 404.5585 -97.917)
		(width 0.508)
		(layer "B.Cu")
		(net "P3V3_STBY")
	)
	(segment
		(start 40.351456 -105.921556)
		(end 40.096948 -105.667048)
		(width 0.4064)
		(layer "B.Cu")
		(net "P3V3_STBY")
	)
	(segment
		(start 489.947712 -29.781246)
		(end 490.720634 -29.781246)
		(width 0.381)
		(layer "B.Cu")
		(net "P3V3_STBY")
	)
	(segment
		(start 482.131116 -144.771872)
		(end 482.680772 -144.771872)
		(width 0.254)
		(layer "B.Cu")
		(net "P3V3_STBY")
	)
	(segment
		(start 75.941174 -86.859364)
		(end 76.396342 -87.314532)
		(width 0.1524)
		(layer "B.Cu")
		(net "P3V3_STBY")
	)
	(segment
		(start 476.2627 -36.195)
		(end 474.823282 -36.195)
		(width 0.254)
		(layer "B.Cu")
		(net "P3V3_STBY")
	)
	(segment
		(start 453.052942 -32.1564)
		(end 452.6661 -31.769558)
		(width 0.508)
		(layer "B.Cu")
		(net "P3V3_STBY")
	)
	(segment
		(start 482.999796 -115.423188)
		(end 482.981 -115.441984)
		(width 0.254)
		(layer "B.Cu")
		(net "P3V3_STBY")
	)
	(segment
		(start 405.8285 -22.6441)
		(end 405.8285 -22.987)
		(width 0.508)
		(layer "B.Cu")
		(net "P3V3_STBY")
	)
	(segment
		(start 401.689062 -48.49368)
		(end 401.891246 -48.695864)
		(width 0.508)
		(layer "B.Cu")
		(net "P3V3_STBY")
	)
	(segment
		(start 269.09903 -90.62466)
		(end 268.36878 -90.62466)
		(width 0.1524)
		(layer "B.Cu")
		(net "P3V3_STBY")
	)
	(segment
		(start 433.578 -152.4)
		(end 434.34 -152.4)
		(width 0.4064)
		(layer "B.Cu")
		(net "P3V3_STBY")
	)
	(segment
		(start 391.67562 -62.717172)
		(end 391.46734 -62.925452)
		(width 0.1016)
		(layer "B.Cu")
		(net "P3V3_STBY")
	)
	(segment
		(start 378.46 -82.804)
		(end 378.587 -82.677)
		(width 0.254)
		(layer "B.Cu")
		(net "P3V3_STBY")
	)
	(segment
		(start 420.529766 -52.788058)
		(end 420.618412 -52.788058)
		(width 0.508)
		(layer "B.Cu")
		(net "P3V3_STBY")
	)
	(segment
		(start 452.6661 -31.2039)
		(end 453.009 -30.861)
		(width 0.508)
		(layer "B.Cu")
		(net "P3V3_STBY")
	)
	(segment
		(start 63.2968 -89.9922)
		(end 63.2968 -91.1352)
		(width 0.4064)
		(layer "B.Cu")
		(net "P3V3_STBY")
	)
	(segment
		(start 369.07343 -39.0271)
		(end 371.3353 -39.0271)
		(width 0.254)
		(layer "B.Cu")
		(net "P3V3_STBY")
	)
	(segment
		(start 365.56696 -39.8272)
		(end 365.340392 -39.600632)
		(width 0.254)
		(layer "B.Cu")
		(net "P3V3_STBY")
	)
	(segment
		(start 371.545358 -75.494642)
		(end 371.145308 -75.894692)
		(width 0.254)
		(layer "B.Cu")
		(net "P3V3_STBY")
	)
	(segment
		(start 404.397972 2.332228)
		(end 405.0284 2.332228)
		(width 0.254)
		(layer "B.Cu")
		(net "P3V3_STBY")
	)
	(segment
		(start 417.21659 -6.5405)
		(end 417.576 -6.5405)
		(width 0.508)
		(layer "B.Cu")
		(net "P3V3_STBY")
	)
	(segment
		(start 478.50552 -49.39284)
		(end 480.78644 -49.39284)
		(width 0.508)
		(layer "B.Cu")
		(net "P3V3_STBY")
	)
	(segment
		(start 473.91574 -135.41756)
		(end 473.91574 -135.830056)
		(width 0.254)
		(layer "B.Cu")
		(net "P3V3_STBY")
	)
	(segment
		(start 397.002 -84.5947)
		(end 397.002 -85.0265)
		(width 0.254)
		(layer "B.Cu")
		(net "P3V3_STBY")
	)
	(segment
		(start 437.9595 -149.4155)
		(end 437.5785 -149.7965)
		(width 0.254)
		(layer "B.Cu")
		(net "P3V3_STBY")
	)
	(segment
		(start 402.336 -86.903306)
		(end 402.336 -87.3125)
		(width 0.254)
		(layer "B.Cu")
		(net "P3V3_STBY")
	)
	(segment
		(start 26.2128 -85.2932)
		(end 26.2128 -85.13826)
		(width 0.4064)
		(layer "B.Cu")
		(net "P3V3_STBY")
	)
	(segment
		(start 384.429 -3.405632)
		(end 384.429 -2.702814)
		(width 0.254)
		(layer "B.Cu")
		(net "P3V3_STBY")
	)
	(segment
		(start 490.720634 -29.781246)
		(end 491.078266 -29.423614)
		(width 0.381)
		(layer "B.Cu")
		(net "P3V3_STBY")
	)
	(segment
		(start 403.98573 -54.48935)
		(end 404.028656 -54.446424)
		(width 0.508)
		(layer "B.Cu")
		(net "P3V3_STBY")
	)
	(segment
		(start 378.228606 -4.193794)
		(end 376.6566 -5.7658)
		(width 0.381)
		(layer "B.Cu")
		(net "P3V3_STBY")
	)
	(segment
		(start 478.142808 -49.755552)
		(end 478.50552 -49.39284)
		(width 0.508)
		(layer "B.Cu")
		(net "P3V3_STBY")
	)
	(segment
		(start 395.245336 -27.92476)
		(end 395.5923 -28.271724)
		(width 0.254)
		(layer "B.Cu")
		(net "P3V3_STBY")
	)
	(segment
		(start -3.85826 -120.60936)
		(end -3.60426 -120.35536)
		(width 0.254)
		(layer "B.Cu")
		(net "P3V3_STBY")
	)
	(segment
		(start 489.08589 -33.674812)
		(end 489.08589 -32.240728)
		(width 0.508)
		(layer "B.Cu")
		(net "P3V3_STBY")
	)
	(segment
		(start 409.312618 -11.000994)
		(end 409.146248 -10.834624)
		(width 0.508)
		(layer "B.Cu")
		(net "P3V3_STBY")
	)
	(segment
		(start 477.1644 -48.5394)
		(end 477.1644 -48.777144)
		(width 0.508)
		(layer "B.Cu")
		(net "P3V3_STBY")
	)
	(segment
		(start 373.017288 -36.456112)
		(end 372.707916 -36.765484)
		(width 0.254)
		(layer "B.Cu")
		(net "P3V3_STBY")
	)
	(segment
		(start 66.49212 -87.74684)
		(end 67.272916 -87.74684)
		(width 0.1524)
		(layer "B.Cu")
		(net "P3V3_STBY")
	)
	(segment
		(start 440.69 -157.1498)
		(end 439.481976 -157.1498)
		(width 0.254)
		(layer "B.Cu")
		(net "P3V3_STBY")
	)
	(segment
		(start 396.6845 -84.2772)
		(end 397.002 -84.5947)
		(width 0.254)
		(layer "B.Cu")
		(net "P3V3_STBY")
	)
	(segment
		(start 421.676068 -14.4653)
		(end 421.386 -14.755368)
		(width 0.254)
		(layer "B.Cu")
		(net "P3V3_STBY")
	)
	(segment
		(start 63.2968 -88.8492)
		(end 63.2968 -88.54186)
		(width 0.254)
		(layer "B.Cu")
		(net "P3V3_STBY")
	)
	(segment
		(start 443.887098 -142.465298)
		(end 443.4586 -142.0368)
		(width 0.254)
		(layer "B.Cu")
		(net "P3V3_STBY")
	)
	(segment
		(start 25.509474 -78.122526)
		(end 25.654 -77.978)
		(width 0.254)
		(layer "B.Cu")
		(net "P3V3_STBY")
	)
	(segment
		(start 376.3264 -1.3462)
		(end 378.228606 -3.248406)
		(width 0.381)
		(layer "B.Cu")
		(net "P3V3_STBY")
	)
	(segment
		(start 466.908896 -149.0091)
		(end 466.74405 -148.844254)
		(width 0.4064)
		(layer "B.Cu")
		(net "P3V3_STBY")
	)
	(segment
		(start 340.741 -83.5914)
		(end 339.70722 -83.5914)
		(width 0.254)
		(layer "B.Cu")
		(net "P3V3_STBY")
	)
	(segment
		(start 345.2368 -81.8388)
		(end 345.2368 -81.9404)
		(width 0.254)
		(layer "B.Cu")
		(net "P3V3_STBY")
	)
	(segment
		(start 446.479168 -146.393662)
		(end 447.657982 -146.393662)
		(width 0.254)
		(layer "B.Cu")
		(net "P3V3_STBY")
	)
	(segment
		(start 269.984982 -91.075764)
		(end 269.703296 -90.794078)
		(width 0.1524)
		(layer "B.Cu")
		(net "P3V3_STBY")
	)
	(segment
		(start 373.527574 -72.678036)
		(end 373.544846 -72.695308)
		(width 0.254)
		(layer "B.Cu")
		(net "P3V3_STBY")
	)
	(segment
		(start 391.162286 -61.29528)
		(end 389.23722 -61.29528)
		(width 0.254)
		(layer "B.Cu")
		(net "P3V3_STBY")
	)
	(segment
		(start -4.36626 -120.60936)
		(end -3.85826 -120.60936)
		(width 0.254)
		(layer "B.Cu")
		(net "P3V3_STBY")
	)
	(segment
		(start 405.0284 2.332228)
		(end 405.0284 -1.270508)
		(width 0.254)
		(layer "B.Cu")
		(net "P3V3_STBY")
	)
	(segment
		(start 410.718 -2.6797)
		(end 410.718 -2.413)
		(width 0.254)
		(layer "B.Cu")
		(net "P3V3_STBY")
	)
	(segment
		(start 477.139 -45.6438)
		(end 477.139 -48.514)
		(width 0.508)
		(layer "B.Cu")
		(net "P3V3_STBY")
	)
	(segment
		(start 491.4392 -114.5794)
		(end 491.5662 -114.4524)
		(width 0.254)
		(layer "B.Cu")
		(net "P3V3_STBY")
	)
	(segment
		(start 446.8876 -62.5856)
		(end 446.8876 -63.1444)
		(width 0.254)
		(layer "B.Cu")
		(net "P3V3_STBY")
	)
	(segment
		(start 487.7054 -37.428932)
		(end 488.044236 -37.767768)
		(width 0.254)
		(layer "B.Cu")
		(net "P3V3_STBY")
	)
	(segment
		(start 370.745512 -75.494642)
		(end 370.745258 -75.494642)
		(width 0.254)
		(layer "B.Cu")
		(net "P3V3_STBY")
	)
	(segment
		(start 383.5908 -2.448814)
		(end 382.397 -2.448814)
		(width 0.254)
		(layer "B.Cu")
		(net "P3V3_STBY")
	)
	(segment
		(start 492.9886 -38.9636)
		(end 492.2774 -38.9636)
		(width 0.254)
		(layer "B.Cu")
		(net "P3V3_STBY")
	)
	(segment
		(start 26.3398 -77.3938)
		(end 26.289 -77.3938)
		(width 0.254)
		(layer "B.Cu")
		(net "P3V3_STBY")
	)
	(segment
		(start 390.755124 -83.859878)
		(end 390.647174 -83.859878)
		(width 0.254)
		(layer "B.Cu")
		(net "P3V3_STBY")
	)
	(segment
		(start 482.15931 -50.04689)
		(end 482.8794 -49.3268)
		(width 0.508)
		(layer "B.Cu")
		(net "P3V3_STBY")
	)
	(segment
		(start 411.4165 -4.497832)
		(end 410.834332 -5.08)
		(width 0.254)
		(layer "B.Cu")
		(net "P3V3_STBY")
	)
	(segment
		(start 452.487792 -146.977608)
		(end 453.0598 -146.4056)
		(width 0.254)
		(layer "B.Cu")
		(net "P3V3_STBY")
	)
	(segment
		(start 476.849948 -147.792948)
		(end 477.484948 -147.792948)
		(width 0.254)
		(layer "B.Cu")
		(net "P3V3_STBY")
	)
	(segment
		(start 93.743272 -88.72728)
		(end 93.791278 -88.775286)
		(width 0.1524)
		(layer "B.Cu")
		(net "P3V3_STBY")
	)
	(segment
		(start 63.0428 -93.1672)
		(end 50.288444 -105.921556)
		(width 0.4064)
		(layer "B.Cu")
		(net "P3V3_STBY")
	)
	(segment
		(start 493.06734 -123.06808)
		(end 492.76762 -123.06808)
		(width 0.254)
		(layer "B.Cu")
		(net "P3V3_STBY")
	)
	(segment
		(start 371.348 -64.456564)
		(end 371.526816 -64.63538)
		(width 0.254)
		(layer "B.Cu")
		(net "P3V3_STBY")
	)
	(segment
		(start 176.043082 -70.34911)
		(end 175.39843 -70.34911)
		(width 0.254)
		(layer "B.Cu")
		(net "P3V3_STBY")
	)
	(segment
		(start 479.171 -120.390666)
		(end 479.175064 -120.39473)
		(width 0.254)
		(layer "B.Cu")
		(net "P3V3_STBY")
	)
	(segment
		(start 371.983 -65.6844)
		(end 371.6782 -65.6844)
		(width 0.254)
		(layer "B.Cu")
		(net "P3V3_STBY")
	)
	(segment
		(start 402.20392 -153.9367)
		(end 401.2946 -153.9367)
		(width 0.254)
		(layer "B.Cu")
		(net "P3V3_STBY")
	)
	(segment
		(start 439.4073 -141.097)
		(end 438.6199 -141.097)
		(width 0.254)
		(layer "B.Cu")
		(net "P3V3_STBY")
	)
	(segment
		(start 369.202208 -28.448)
		(end 370.078 -28.448)
		(width 0.381)
		(layer "B.Cu")
		(net "P3V3_STBY")
	)
	(segment
		(start 398.12595 -36.670742)
		(end 397.787622 -37.00907)
		(width 0.254)
		(layer "B.Cu")
		(net "P3V3_STBY")
	)
	(segment
		(start 492.3536 -131.73964)
		(end 492.3536 -131.445)
		(width 0.254)
		(layer "B.Cu")
		(net "P3V3_STBY")
	)
	(segment
		(start 432.435 -45.66285)
		(end 432.435 -47.498)
		(width 0.508)
		(layer "B.Cu")
		(net "P3V3_STBY")
	)
	(segment
		(start 263.284462 -88.605868)
		(end 262.491474 -87.81288)
		(width 0.1524)
		(layer "B.Cu")
		(net "P3V3_STBY")
	)
	(segment
		(start 405.219408 -93.755718)
		(end 405.219408 -92.993718)
		(width 0.508)
		(layer "B.Cu")
		(net "P3V3_STBY")
	)
	(segment
		(start 177.611024 -67.63258)
		(end 177.611024 -68.054474)
		(width 0.254)
		(layer "B.Cu")
		(net "P3V3_STBY")
	)
	(segment
		(start 411.475428 -103.747824)
		(end 410.973016 -103.245412)
		(width 0.254)
		(layer "B.Cu")
		(net "P3V3_STBY")
	)
	(segment
		(start 393.981178 -15.827502)
		(end 393.003786 -14.85011)
		(width 0.254)
		(layer "B.Cu")
		(net "P3V3_STBY")
	)
	(segment
		(start 422.402 -20.7264)
		(end 421.6019 -19.9263)
		(width 0.254)
		(layer "B.Cu")
		(net "P3V3_STBY")
	)
	(segment
		(start 406.654 -27.559)
		(end 406.654 -27.178)
		(width 0.254)
		(layer "B.Cu")
		(net "P3V3_STBY")
	)
	(segment
		(start 396.1257 -87.3252)
		(end 396.113 -87.3125)
		(width 0.254)
		(layer "B.Cu")
		(net "P3V3_STBY")
	)
	(segment
		(start 476.984568 -11.457432)
		(end 477.2914 -11.1506)
		(width 0.254)
		(layer "B.Cu")
		(net "P3V3_STBY")
	)
	(segment
		(start 13.921232 3.777742)
		(end 13.921232 4.537456)
		(width 0.254)
		(layer "B.Cu")
		(net "P3V3_STBY")
	)
	(segment
		(start 386.08 -48.48098)
		(end 386.08 -48.006)
		(width 0.254)
		(layer "B.Cu")
		(net "P3V3_STBY")
	)
	(segment
		(start 352.6663 -83.82254)
		(end 352.6663 -84.1375)
		(width 0.254)
		(layer "B.Cu")
		(net "P3V3_STBY")
	)
	(segment
		(start 486.1052 -141.097)
		(end 486.2322 -141.224)
		(width 0.254)
		(layer "B.Cu")
		(net "P3V3_STBY")
	)
	(segment
		(start 462.801208 -144.526254)
		(end 461.646778 -144.526254)
		(width 0.4064)
		(layer "B.Cu")
		(net "P3V3_STBY")
	)
	(segment
		(start 421.65016 -5.83184)
		(end 421.3225 -6.1595)
		(width 0.4064)
		(layer "B.Cu")
		(net "P3V3_STBY")
	)
	(segment
		(start 453.771508 -32.1564)
		(end 453.052942 -32.1564)
		(width 0.508)
		(layer "B.Cu")
		(net "P3V3_STBY")
	)
	(segment
		(start 325.22795 -58.899044)
		(end 325.89851 -58.228484)
		(width 0.254)
		(layer "B.Cu")
		(net "P3V3_STBY")
	)
	(segment
		(start 454.740772 -33.396174)
		(end 454.740772 -32.60852)
		(width 0.254)
		(layer "B.Cu")
		(net "P3V3_STBY")
	)
	(segment
		(start 412.623 -7.8232)
		(end 412.623 -8.661146)
		(width 0.254)
		(layer "B.Cu")
		(net "P3V3_STBY")
	)
	(segment
		(start 393.7 -28.575)
		(end 393.446 -28.575)
		(width 0.254)
		(layer "B.Cu")
		(net "P3V3_STBY")
	)
	(segment
		(start 407.7589 -13.0683)
		(end 407.3652 -13.0683)
		(width 0.508)
		(layer "B.Cu")
		(net "P3V3_STBY")
	)
	(segment
		(start 433.578 -151.257)
		(end 434.34 -151.257)
		(width 0.4064)
		(layer "B.Cu")
		(net "P3V3_STBY")
	)
	(segment
		(start 499.491 -137.287)
		(end 499.491 -138.557)
		(width 0.254)
		(layer "B.Cu")
		(net "P3V3_STBY")
	)
	(segment
		(start 373.944642 -72.295512)
		(end 374.059196 -72.295512)
		(width 0.254)
		(layer "B.Cu")
		(net "P3V3_STBY")
	)
	(segment
		(start 397.251682 -156.115258)
		(end 396.376906 -156.115258)
		(width 0.254)
		(layer "B.Cu")
		(net "P3V3_STBY")
	)
	(segment
		(start 477.173544 -135.41756)
		(end 477.198944 -135.39216)
		(width 0.254)
		(layer "B.Cu")
		(net "P3V3_STBY")
	)
	(segment
		(start 88.835738 -88.214962)
		(end 89.2175 -87.8332)
		(width 0.1524)
		(layer "B.Cu")
		(net "P3V3_STBY")
	)
	(segment
		(start 485.942894 4.157472)
		(end 485.942894 4.966716)
		(width 0.508)
		(layer "B.Cu")
		(net "P3V3_STBY")
	)
	(segment
		(start 411.861 -7.4295)
		(end 412.2293 -7.4295)
		(width 0.254)
		(layer "B.Cu")
		(net "P3V3_STBY")
	)
	(segment
		(start 2.869946 -79.475076)
		(end 2.869946 -87.278718)
		(width 0.254)
		(layer "B.Cu")
		(net "P3V3_STBY")
	)
	(segment
		(start 366.268 -40.5892)
		(end 367.157 -40.5892)
		(width 0.254)
		(layer "B.Cu")
		(net "P3V3_STBY")
	)
	(segment
		(start 411.4165 -3.7465)
		(end 410.742892 -3.072892)
		(width 0.254)
		(layer "B.Cu")
		(net "P3V3_STBY")
	)
	(segment
		(start 0.381 -76.98613)
		(end 2.869946 -79.475076)
		(width 0.254)
		(layer "B.Cu")
		(net "P3V3_STBY")
	)
	(segment
		(start 395.173454 -151.6888)
		(end 402.0058 -151.6888)
		(width 0.254)
		(layer "B.Cu")
		(net "P3V3_STBY")
	)
	(segment
		(start 19.4056 -86.7156)
		(end 19.1516 -86.9696)
		(width 0.254)
		(layer "In2.Cu")
		(net "P3V3_STBY")
	)
	(segment
		(start 377.879864 -55.5371)
		(end 377.972574 -55.44439)
		(width 0.254)
		(layer "In2.Cu")
		(net "P3V3_STBY")
	)
	(segment
		(start 377.44273 -60.26658)
		(end 375.152412 -62.556898)
		(width 0.254)
		(layer "In2.Cu")
		(net "P3V3_STBY")
	)
	(segment
		(start 377.879864 -55.698136)
		(end 377.44273 -56.13527)
		(width 0.254)
		(layer "In2.Cu")
		(net "P3V3_STBY")
	)
	(segment
		(start 14.4272 -99.3902)
		(end 13.9446 -98.9076)
		(width 0.4064)
		(layer "In2.Cu")
		(net "P3V3_STBY")
	)
	(segment
		(start 13.6906 -88.646)
		(end 13.1826 -89.154)
		(width 0.254)
		(layer "In2.Cu")
		(net "P3V3_STBY")
	)
	(segment
		(start 26.714196 -80.562704)
		(end 26.714196 -84.636864)
		(width 0.254)
		(layer "In2.Cu")
		(net "P3V3_STBY")
	)
	(segment
		(start 375.152412 -62.556898)
		(end 374.651016 -62.556898)
		(width 0.254)
		(layer "In2.Cu")
		(net "P3V3_STBY")
	)
	(segment
		(start 26.714196 -84.636864)
		(end 26.2128 -85.13826)
		(width 0.254)
		(layer "In2.Cu")
		(net "P3V3_STBY")
	)
	(segment
		(start 171.2468 -95.123)
		(end 170.2943 -96.0755)
		(width 0.254)
		(layer "In2.Cu")
		(net "P3V3_STBY")
	)
	(segment
		(start 377.879864 -55.5371)
		(end 377.879864 -55.698136)
		(width 0.254)
		(layer "In2.Cu")
		(net "P3V3_STBY")
	)
	(segment
		(start 19.1516 -86.9696)
		(end 17.6022 -86.9696)
		(width 0.254)
		(layer "In2.Cu")
		(net "P3V3_STBY")
	)
	(segment
		(start 18.4912 -26.67)
		(end 18.5039 -26.6827)
		(width 0.254)
		(layer "In2.Cu")
		(net "P3V3_STBY")
	)
	(segment
		(start 377.972574 -46.67885)
		(end 379.087126 -45.564298)
		(width 0.254)
		(layer "In2.Cu")
		(net "P3V3_STBY")
	)
	(segment
		(start 165.481 -98.8822)
		(end 164.9984 -99.3648)
		(width 0.254)
		(layer "In2.Cu")
		(net "P3V3_STBY")
	)
	(segment
		(start 168.275 -98.8822)
		(end 165.481 -98.8822)
		(width 0.254)
		(layer "In2.Cu")
		(net "P3V3_STBY")
	)
	(segment
		(start 15.1638 -99.3902)
		(end 14.4272 -99.3902)
		(width 0.4064)
		(layer "In2.Cu")
		(net "P3V3_STBY")
	)
	(segment
		(start 375.031 -64.96304)
		(end 375.258838 -65.190878)
		(width 0.254)
		(layer "In2.Cu")
		(net "P3V3_STBY")
	)
	(segment
		(start 377.44273 -56.13527)
		(end 377.44273 -60.26658)
		(width 0.254)
		(layer "In2.Cu")
		(net "P3V3_STBY")
	)
	(segment
		(start 374.651016 -63.340742)
		(end 375.031 -63.720726)
		(width 0.254)
		(layer "In2.Cu")
		(net "P3V3_STBY")
	)
	(segment
		(start 20.955 -86.7156)
		(end 19.4056 -86.7156)
		(width 0.254)
		(layer "In2.Cu")
		(net "P3V3_STBY")
	)
	(segment
		(start 15.24889 -4.274058)
		(end 15.24889 -1.907032)
		(width 0.254)
		(layer "In2.Cu")
		(net "P3V3_STBY")
	)
	(segment
		(start 170.2943 -96.8629)
		(end 168.275 -98.8822)
		(width 0.254)
		(layer "In2.Cu")
		(net "P3V3_STBY")
	)
	(segment
		(start 172.101002 -92.835984)
		(end 171.2468 -93.690186)
		(width 0.254)
		(layer "In2.Cu")
		(net "P3V3_STBY")
	)
	(segment
		(start 16.3576 -98.1964)
		(end 15.1638 -99.3902)
		(width 0.4064)
		(layer "In2.Cu")
		(net "P3V3_STBY")
	)
	(segment
		(start 13.6906 -87.1474)
		(end 13.6906 -88.646)
		(width 0.254)
		(layer "In2.Cu")
		(net "P3V3_STBY")
	)
	(segment
		(start 13.8176 -86.4362)
		(end 13.8176 -87.0204)
		(width 0.254)
		(layer "In2.Cu")
		(net "P3V3_STBY")
	)
	(segment
		(start 18.5039 -26.6827)
		(end 18.5039 -29.227272)
		(width 0.254)
		(layer "In2.Cu")
		(net "P3V3_STBY")
	)
	(segment
		(start 171.2468 -93.690186)
		(end 171.2468 -95.123)
		(width 0.254)
		(layer "In2.Cu")
		(net "P3V3_STBY")
	)
	(segment
		(start 170.2943 -96.0755)
		(end 170.2943 -96.8629)
		(width 0.254)
		(layer "In2.Cu")
		(net "P3V3_STBY")
	)
	(segment
		(start 374.651016 -62.556898)
		(end 374.651016 -63.340742)
		(width 0.254)
		(layer "In2.Cu")
		(net "P3V3_STBY")
	)
	(segment
		(start 377.972574 -55.44439)
		(end 377.972574 -46.67885)
		(width 0.254)
		(layer "In2.Cu")
		(net "P3V3_STBY")
	)
	(segment
		(start 16.0528 -86.741)
		(end 14.1224 -86.741)
		(width 0.254)
		(layer "In2.Cu")
		(net "P3V3_STBY")
	)
	(segment
		(start 21.546312 -98.762312)
		(end 20.9804 -98.1964)
		(width 0.4064)
		(layer "In2.Cu")
		(net "P3V3_STBY")
	)
	(segment
		(start 19.75866 -30.482032)
		(end 19.75866 -30.74162)
		(width 0.254)
		(layer "In2.Cu")
		(net "P3V3_STBY")
	)
	(segment
		(start 14.1224 -86.741)
		(end 13.8176 -86.4362)
		(width 0.254)
		(layer "In2.Cu")
		(net "P3V3_STBY")
	)
	(segment
		(start 20.9804 -98.1964)
		(end 16.3576 -98.1964)
		(width 0.4064)
		(layer "In2.Cu")
		(net "P3V3_STBY")
	)
	(segment
		(start 375.031 -63.720726)
		(end 375.031 -64.96304)
		(width 0.254)
		(layer "In2.Cu")
		(net "P3V3_STBY")
	)
	(segment
		(start 15.607284 -4.632452)
		(end 15.24889 -4.274058)
		(width 0.254)
		(layer "In2.Cu")
		(net "P3V3_STBY")
	)
	(segment
		(start 16.7132 -86.0806)
		(end 16.0528 -86.741)
		(width 0.254)
		(layer "In2.Cu")
		(net "P3V3_STBY")
	)
	(segment
		(start 18.5039 -29.227272)
		(end 19.75866 -30.482032)
		(width 0.254)
		(layer "In2.Cu")
		(net "P3V3_STBY")
	)
	(segment
		(start 22.991572 -98.762312)
		(end 21.546312 -98.762312)
		(width 0.4064)
		(layer "In2.Cu")
		(net "P3V3_STBY")
	)
	(segment
		(start 17.6022 -86.9696)
		(end 16.7132 -86.0806)
		(width 0.254)
		(layer "In2.Cu")
		(net "P3V3_STBY")
	)
	(segment
		(start 26.5684 -80.416908)
		(end 26.714196 -80.562704)
		(width 0.254)
		(layer "In2.Cu")
		(net "P3V3_STBY")
	)
	(segment
		(start 13.8176 -87.0204)
		(end 13.6906 -87.1474)
		(width 0.254)
		(layer "In2.Cu")
		(net "P3V3_STBY")
	)
	(segment
		(start 185.842148 -62.919864)
		(end 185.842148 -63.126112)
		(width 0.254)
		(layer "In4.Cu")
		(net "P3V3_STBY")
	)
	(segment
		(start 186.8678 -77.1398)
		(end 186.944 -77.0636)
		(width 0.254)
		(layer "In4.Cu")
		(net "P3V3_STBY")
	)
	(segment
		(start 169.927016 -71.2978)
		(end 172.342048 -71.2978)
		(width 0.254)
		(layer "In4.Cu")
		(net "P3V3_STBY")
	)
	(segment
		(start 192.80632 -109.488986)
		(end 186.558428 -103.241094)
		(width 0.254)
		(layer "In4.Cu")
		(net "P3V3_STBY")
	)
	(segment
		(start 183.74106 -65.2272)
		(end 183.74106 -66.33972)
		(width 0.254)
		(layer "In4.Cu")
		(net "P3V3_STBY")
	)
	(segment
		(start 184.8612 -76.2508)
		(end 185.7502 -77.1398)
		(width 0.254)
		(layer "In4.Cu")
		(net "P3V3_STBY")
	)
	(segment
		(start 420.102792 -0.8636)
		(end 417.8046 -0.8636)
		(width 0.254)
		(layer "In4.Cu")
		(net "P3V3_STBY")
	)
	(segment
		(start 423.291 -2.667)
		(end 422.4655 -1.8415)
		(width 0.254)
		(layer "In4.Cu")
		(net "P3V3_STBY")
	)
	(segment
		(start 167.998648 -71.8566)
		(end 169.368216 -71.8566)
		(width 0.254)
		(layer "In4.Cu")
		(net "P3V3_STBY")
	)
	(segment
		(start 422.4655 -1.8415)
		(end 421.830754 -1.8415)
		(width 0.254)
		(layer "In4.Cu")
		(net "P3V3_STBY")
	)
	(segment
		(start 182.003954 -68.076826)
		(end 182.003954 -71.419212)
		(width 0.254)
		(layer "In4.Cu")
		(net "P3V3_STBY")
	)
	(segment
		(start 420.350442 -1.11125)
		(end 420.102792 -0.8636)
		(width 0.254)
		(layer "In4.Cu")
		(net "P3V3_STBY")
	)
	(segment
		(start 181.34838 -78.32344)
		(end 183.42102 -76.2508)
		(width 0.254)
		(layer "In4.Cu")
		(net "P3V3_STBY")
	)
	(segment
		(start 172.342048 -71.2978)
		(end 172.519848 -71.12)
		(width 0.254)
		(layer "In4.Cu")
		(net "P3V3_STBY")
	)
	(segment
		(start 23.25497 -30.72384)
		(end 19.77644 -30.72384)
		(width 0.254)
		(layer "In4.Cu")
		(net "P3V3_STBY")
	)
	(segment
		(start 167.259 -72.263)
		(end 167.592248 -72.263)
		(width 0.254)
		(layer "In4.Cu")
		(net "P3V3_STBY")
	)
	(segment
		(start 164.47262 -70.5358)
		(end 165.5318 -70.5358)
		(width 0.254)
		(layer "In4.Cu")
		(net "P3V3_STBY")
	)
	(segment
		(start 337.355942 -85.04174)
		(end 336.8802 -85.517482)
		(width 0.254)
		(layer "In4.Cu")
		(net "P3V3_STBY")
	)
	(segment
		(start 185.7502 -77.1398)
		(end 186.8678 -77.1398)
		(width 0.254)
		(layer "In4.Cu")
		(net "P3V3_STBY")
	)
	(segment
		(start 167.592248 -72.263)
		(end 167.998648 -71.8566)
		(width 0.254)
		(layer "In4.Cu")
		(net "P3V3_STBY")
	)
	(segment
		(start 184.877964 -61.95568)
		(end 185.842148 -62.919864)
		(width 0.254)
		(layer "In4.Cu")
		(net "P3V3_STBY")
	)
	(segment
		(start 417.8046 -0.8636)
		(end 416.8394 -1.8288)
		(width 0.254)
		(layer "In4.Cu")
		(net "P3V3_STBY")
	)
	(segment
		(start 336.8802 -85.517482)
		(end 336.8802 -86.692486)
		(width 0.254)
		(layer "In4.Cu")
		(net "P3V3_STBY")
	)
	(segment
		(start 170.559984 -128.573784)
		(end 174.778416 -128.573784)
		(width 0.4064)
		(layer "In4.Cu")
		(net "P3V3_STBY")
	)
	(segment
		(start 202.59294 -107.564936)
		(end 200.66889 -109.488986)
		(width 0.254)
		(layer "In4.Cu")
		(net "P3V3_STBY")
	)
	(segment
		(start 164.1856 -70.24878)
		(end 164.457126 -70.520306)
		(width 0.254)
		(layer "In4.Cu")
		(net "P3V3_STBY")
	)
	(segment
		(start 421.100504 -1.11125)
		(end 420.350442 -1.11125)
		(width 0.254)
		(layer "In4.Cu")
		(net "P3V3_STBY")
	)
	(segment
		(start 172.519848 -71.12)
		(end 174.62754 -71.12)
		(width 0.254)
		(layer "In4.Cu")
		(net "P3V3_STBY")
	)
	(segment
		(start 179.39766 -64.135)
		(end 181.57698 -61.95568)
		(width 0.254)
		(layer "In4.Cu")
		(net "P3V3_STBY")
	)
	(segment
		(start 174.778416 -128.573784)
		(end 176.175416 -127.176784)
		(width 0.4064)
		(layer "In4.Cu")
		(net "P3V3_STBY")
	)
	(segment
		(start 178.943 -64.135)
		(end 179.39766 -64.135)
		(width 0.254)
		(layer "In4.Cu")
		(net "P3V3_STBY")
	)
	(segment
		(start 164.1856 -67.437)
		(end 164.1856 -70.24878)
		(width 0.254)
		(layer "In4.Cu")
		(net "P3V3_STBY")
	)
	(segment
		(start 200.66889 -109.488986)
		(end 192.80632 -109.488986)
		(width 0.254)
		(layer "In4.Cu")
		(net "P3V3_STBY")
	)
	(segment
		(start 174.62754 -71.12)
		(end 175.29302 -70.45452)
		(width 0.254)
		(layer "In4.Cu")
		(net "P3V3_STBY")
	)
	(segment
		(start 183.74106 -66.33972)
		(end 182.003954 -68.076826)
		(width 0.254)
		(layer "In4.Cu")
		(net "P3V3_STBY")
	)
	(segment
		(start 338.25688 -85.04174)
		(end 337.355942 -85.04174)
		(width 0.254)
		(layer "In4.Cu")
		(net "P3V3_STBY")
	)
	(segment
		(start 186.558428 -103.241094)
		(end 186.558428 -77.449172)
		(width 0.254)
		(layer "In4.Cu")
		(net "P3V3_STBY")
	)
	(segment
		(start 176.175416 -127.176784)
		(end 176.175416 -125.552962)
		(width 0.4064)
		(layer "In4.Cu")
		(net "P3V3_STBY")
	)
	(segment
		(start 186.944 -76.359258)
		(end 186.944 -77.0636)
		(width 0.254)
		(layer "In4.Cu")
		(net "P3V3_STBY")
	)
	(segment
		(start 169.368216 -71.8566)
		(end 169.927016 -71.2978)
		(width 0.254)
		(layer "In4.Cu")
		(net "P3V3_STBY")
	)
	(segment
		(start 170.0022 -128.016)
		(end 170.559984 -128.573784)
		(width 0.4064)
		(layer "In4.Cu")
		(net "P3V3_STBY")
	)
	(segment
		(start 165.5318 -70.5358)
		(end 167.259 -72.263)
		(width 0.254)
		(layer "In4.Cu")
		(net "P3V3_STBY")
	)
	(segment
		(start 416.8394 -1.8288)
		(end 416.1917 -1.8288)
		(width 0.254)
		(layer "In4.Cu")
		(net "P3V3_STBY")
	)
	(segment
		(start 23.345902 -30.814772)
		(end 23.25497 -30.72384)
		(width 0.254)
		(layer "In4.Cu")
		(net "P3V3_STBY")
	)
	(segment
		(start 186.558428 -77.449172)
		(end 186.8678 -77.1398)
		(width 0.254)
		(layer "In4.Cu")
		(net "P3V3_STBY")
	)
	(segment
		(start 182.003954 -71.419212)
		(end 186.944 -76.359258)
		(width 0.254)
		(layer "In4.Cu")
		(net "P3V3_STBY")
	)
	(segment
		(start 202.63612 -107.564936)
		(end 202.59294 -107.564936)
		(width 0.254)
		(layer "In4.Cu")
		(net "P3V3_STBY")
	)
	(segment
		(start 163.2712 -67.056)
		(end 163.8046 -67.056)
		(width 0.254)
		(layer "In4.Cu")
		(net "P3V3_STBY")
	)
	(segment
		(start 163.8046 -67.056)
		(end 164.1856 -67.437)
		(width 0.254)
		(layer "In4.Cu")
		(net "P3V3_STBY")
	)
	(segment
		(start 185.842148 -63.126112)
		(end 183.74106 -65.2272)
		(width 0.254)
		(layer "In4.Cu")
		(net "P3V3_STBY")
	)
	(segment
		(start 19.77644 -30.72384)
		(end 19.75866 -30.74162)
		(width 0.254)
		(layer "In4.Cu")
		(net "P3V3_STBY")
	)
	(segment
		(start 421.830754 -1.8415)
		(end 421.100504 -1.11125)
		(width 0.254)
		(layer "In4.Cu")
		(net "P3V3_STBY")
	)
	(segment
		(start 164.457126 -70.520306)
		(end 164.47262 -70.5358)
		(width 0.254)
		(layer "In4.Cu")
		(net "P3V3_STBY")
	)
	(segment
		(start 181.57698 -61.95568)
		(end 184.877964 -61.95568)
		(width 0.254)
		(layer "In4.Cu")
		(net "P3V3_STBY")
	)
	(segment
		(start 183.42102 -76.2508)
		(end 184.8612 -76.2508)
		(width 0.254)
		(layer "In4.Cu")
		(net "P3V3_STBY")
	)
	(segment
		(start 18.4912 -26.67)
		(end 19.01825 -27.19705)
		(width 0.254)
		(layer "In6.Cu")
		(net "P3V3_STBY")
	)
	(segment
		(start 17.96415 -27.19705)
		(end 18.4912 -26.67)
		(width 0.254)
		(layer "In6.Cu")
		(net "P3V3_STBY")
	)
	(segment
		(start 18.4912 -26.67)
		(end 19.01825 -26.14295)
		(width 0.254)
		(layer "In6.Cu")
		(net "P3V3_STBY")
	)
	(segment
		(start 17.96415 -26.14295)
		(end 18.4912 -26.67)
		(width 0.254)
		(layer "In6.Cu")
		(net "P3V3_STBY")
	)
	(segment
		(start 369.9383 -70.8533)
		(end 369.9383 -73.7616)
		(width 0.1016)
		(layer "In7.Cu")
		(net "P3V3_STBY")
	)
	(segment
		(start 368.2111 -71.501)
		(end 367.7285 -71.501)
		(width 0.1016)
		(layer "In7.Cu")
		(net "P3V3_STBY")
	)
	(segment
		(start 371.5512 -79.3242)
		(end 371.5512 -78.9051)
		(width 0.1016)
		(layer "In7.Cu")
		(net "P3V3_STBY")
	)
	(segment
		(start 369.9383 -78.9305)
		(end 369.9383 -80.1243)
		(width 0.1016)
		(layer "In7.Cu")
		(net "P3V3_STBY")
	)
	(segment
		(start 370.7511 -76.5302)
		(end 370.7511 -77.724)
		(width 0.1016)
		(layer "In7.Cu")
		(net "P3V3_STBY")
	)
	(segment
		(start 368.3254 -74.8538)
		(end 368.3254 -76.9366)
		(width 0.1016)
		(layer "In7.Cu")
		(net "P3V3_STBY")
	)
	(segment
		(start 375.412 -78.7146)
		(end 373.2657 -78.7146)
		(width 0.1016)
		(layer "In7.Cu")
		(net "P3V3_STBY")
	)
	(segment
		(start 376.1613 -77.0763)
		(end 373.2911 -77.0763)
		(width 0.1016)
		(layer "In7.Cu")
		(net "P3V3_STBY")
	)
	(segment
		(start 368.1857 -78.6892)
		(end 366.1156 -78.6892)
		(width 0.1016)
		(layer "In7.Cu")
		(net "P3V3_STBY")
	)
	(segment
		(start 373.2276 -77.8764)
		(end 375.3612 -77.8764)
		(width 0.1016)
		(layer "In7.Cu")
		(net "P3V3_STBY")
	)
	(segment
		(start 376.3391 -78.867)
		(end 376.3391 -80.0989)
		(width 0.1016)
		(layer "In7.Cu")
		(net "P3V3_STBY")
	)
	(segment
		(start 368.1476 -77.9018)
		(end 366.0902 -77.9018)
		(width 0.1016)
		(layer "In7.Cu")
		(net "P3V3_STBY")
	)
	(segment
		(start 368.3254 -78.8797)
		(end 368.3254 -80.9625)
		(width 0.1016)
		(layer "In7.Cu")
		(net "P3V3_STBY")
	)
	(segment
		(start 369.1382 -74.8665)
		(end 369.1382 -76.9493)
		(width 0.1016)
		(layer "In7.Cu")
		(net "P3V3_STBY")
	)
	(segment
		(start 378.5997 -78.7019)
		(end 376.5169 -78.7019)
		(width 0.1016)
		(layer "In7.Cu")
		(net "P3V3_STBY")
	)
	(segment
		(start 369.9256 -69.8246)
		(end 369.9256 -68.3895)
		(width 0.1016)
		(layer "In7.Cu")
		(net "P3V3_STBY")
	)
	(segment
		(start 377.7869 -77.1144)
		(end 377.3424 -77.1144)
		(width 0.1016)
		(layer "In7.Cu")
		(net "P3V3_STBY")
	)
	(segment
		(start 368.3381 -71.7169)
		(end 368.3381 -73.6727)
		(width 0.1016)
		(layer "In7.Cu")
		(net "P3V3_STBY")
	)
	(segment
		(start 370.1288 -70.6882)
		(end 372.1481 -70.6882)
		(width 0.1016)
		(layer "In7.Cu")
		(net "P3V3_STBY")
	)
	(segment
		(start 377.0249 -69.9008)
		(end 376.4915 -69.9008)
		(width 0.1016)
		(layer "In7.Cu")
		(net "P3V3_STBY")
	)
	(segment
		(start 369.1382 -78.867)
		(end 369.1382 -80.9879)
		(width 0.1016)
		(layer "In7.Cu")
		(net "P3V3_STBY")
	)
	(segment
		(start 375.539 -79.2734)
		(end 375.539 -78.9051)
		(width 0.1016)
		(layer "In7.Cu")
		(net "P3V3_STBY")
	)
	(segment
		(start 376.3391 -74.8284)
		(end 376.3391 -76.9112)
		(width 0.1016)
		(layer "In7.Cu")
		(net "P3V3_STBY")
	)
	(segment
		(start 372.2243 -78.6765)
		(end 371.729 -78.6765)
		(width 0.1016)
		(layer "In7.Cu")
		(net "P3V3_STBY")
	)
	(segment
		(start 370.7257 -78.9051)
		(end 370.7257 -80.1116)
		(width 0.1016)
		(layer "In7.Cu")
		(net "P3V3_STBY")
	)
	(segment
		(start 372.11 -77.9018)
		(end 371.7544 -77.9018)
		(width 0.1016)
		(layer "In7.Cu")
		(net "P3V3_STBY")
	)
	(segment
		(start 368.2492 -70.7009)
		(end 366.9157 -70.7009)
		(width 0.1016)
		(layer "In7.Cu")
		(net "P3V3_STBY")
	)
	(segment
		(start 370.1542 -78.7146)
		(end 370.586 -78.7146)
		(width 0.1016)
		(layer "In7.Cu")
		(net "P3V3_STBY")
	)
	(segment
		(start 371.5385 -76.4921)
		(end 371.5385 -77.6986)
		(width 0.1016)
		(layer "In7.Cu")
		(net "P3V3_STBY")
	)
	(segment
		(start 369.1509 -69.8373)
		(end 369.1509 -68.4149)
		(width 0.1016)
		(layer "In7.Cu")
		(net "P3V3_STBY")
	)
	(segment
		(start 368.9477 -69.9135)
		(end 366.8776 -69.9135)
		(width 0.1016)
		(layer "In7.Cu")
		(net "P3V3_STBY")
	)
	(segment
		(start 369.9637 -77.724)
		(end 369.9637 -74.8665)
		(width 0.1016)
		(layer "In7.Cu")
		(net "P3V3_STBY")
	)
	(segment
		(start 370.1288 -77.9145)
		(end 370.586 -77.9145)
		(width 0.1016)
		(layer "In7.Cu")
		(net "P3V3_STBY")
	)
	(segment
		(start 369.1255 -71.6915)
		(end 369.1255 -73.7489)
		(width 0.1016)
		(layer "In7.Cu")
		(net "P3V3_STBY")
	)
	(segment
		(start 377.1519 -74.7649)
		(end 377.1519 -76.9112)
		(width 0.1016)
		(layer "In7.Cu")
		(net "P3V3_STBY")
	)
	(segment
		(start 370.1161 -69.9008)
		(end 371.3988 -69.9008)
		(width 0.1016)
		(layer "In7.Cu")
		(net "P3V3_STBY")
	)
	(segment
		(start 368.1476 -77.1017)
		(end 366.0521 -77.1017)
		(width 0.1016)
		(layer "In7.Cu")
		(net "P3V3_STBY")
	)
	(segment
		(start 377.7869 -77.8764)
		(end 377.3551 -77.8764)
		(width 0.1016)
		(layer "In7.Cu")
		(net "P3V3_STBY")
	)
	(segment
		(start 342.0618 -84.1756)
		(end 343.8906 -82.3468)
		(width 0.254)
		(layer "In9.Cu")
		(net "P3V3_STBY")
	)
	(segment
		(start 26.0604 -77.3938)
		(end 26.289 -77.3938)
		(width 0.254)
		(layer "In9.Cu")
		(net "P3V3_STBY")
	)
	(segment
		(start 1.303274 -117.6147)
		(end 0.086614 -118.83136)
		(width 0.254)
		(layer "In9.Cu")
		(net "P3V3_STBY")
	)
	(segment
		(start 30.371034 -107.202986)
		(end 30.371034 -105.898696)
		(width 0.254)
		(layer "In9.Cu")
		(net "P3V3_STBY")
	)
	(segment
		(start 22.991572 -98.762312)
		(end 22.991572 -99.689158)
		(width 0.254)
		(layer "In9.Cu")
		(net "P3V3_STBY")
	)
	(segment
		(start 24.090376 -106.35361)
		(end 25.846024 -108.109258)
		(width 0.254)
		(layer "In9.Cu")
		(net "P3V3_STBY")
	)
	(segment
		(start 377.722384 -55.37962)
		(end 377.42622 -55.37962)
		(width 0.254)
		(layer "In9.Cu")
		(net "P3V3_STBY")
	)
	(segment
		(start 31.985458 -105.135934)
		(end 33.016952 -104.10444)
		(width 0.254)
		(layer "In9.Cu")
		(net "P3V3_STBY")
	)
	(segment
		(start 25.527 -77.9272)
		(end 26.0604 -77.3938)
		(width 0.254)
		(layer "In9.Cu")
		(net "P3V3_STBY")
	)
	(segment
		(start 21.12899 -86.54161)
		(end 20.955 -86.7156)
		(width 0.254)
		(layer "In9.Cu")
		(net "P3V3_STBY")
	)
	(segment
		(start 22.22881 -86.54161)
		(end 21.12899 -86.54161)
		(width 0.254)
		(layer "In9.Cu")
		(net "P3V3_STBY")
	)
	(segment
		(start 33.016952 -104.10444)
		(end 38.2651 -104.10444)
		(width 0.254)
		(layer "In9.Cu")
		(net "P3V3_STBY")
	)
	(segment
		(start 26.2128 -85.13826)
		(end 26.2128 -84.86902)
		(width 0.254)
		(layer "In9.Cu")
		(net "P3V3_STBY")
	)
	(segment
		(start 356.32136 -89.598246)
		(end 354.972366 -90.94724)
		(width 0.254)
		(layer "In9.Cu")
		(net "P3V3_STBY")
	)
	(segment
		(start 25.846024 -108.109258)
		(end 29.464762 -108.109258)
		(width 0.254)
		(layer "In9.Cu")
		(net "P3V3_STBY")
	)
	(segment
		(start 0.086614 -118.83136)
		(end -1.44526 -118.83136)
		(width 0.254)
		(layer "In9.Cu")
		(net "P3V3_STBY")
	)
	(segment
		(start 353.55276 -90.94724)
		(end 352.933 -91.567)
		(width 0.254)
		(layer "In9.Cu")
		(net "P3V3_STBY")
	)
	(segment
		(start 374.751854 -53.720238)
		(end 374.751854 -53.344318)
		(width 0.254)
		(layer "In9.Cu")
		(net "P3V3_STBY")
	)
	(segment
		(start 25.527 -79.440786)
		(end 25.527 -77.9272)
		(width 0.254)
		(layer "In9.Cu")
		(net "P3V3_STBY")
	)
	(segment
		(start 16.768064 -118.289578)
		(end 12.295378 -113.816892)
		(width 0.254)
		(layer "In9.Cu")
		(net "P3V3_STBY")
	)
	(segment
		(start 23.36292 -85.14334)
		(end 22.92096 -85.5853)
		(width 0.254)
		(layer "In9.Cu")
		(net "P3V3_STBY")
	)
	(segment
		(start 30.371034 -105.898696)
		(end 31.133796 -105.135934)
		(width 0.254)
		(layer "In9.Cu")
		(net "P3V3_STBY")
	)
	(segment
		(start 22.92096 -85.84946)
		(end 22.22881 -86.54161)
		(width 0.254)
		(layer "In9.Cu")
		(net "P3V3_STBY")
	)
	(segment
		(start 12.295378 -113.816892)
		(end 5.48005 -113.816892)
		(width 0.254)
		(layer "In9.Cu")
		(net "P3V3_STBY")
	)
	(segment
		(start 376.020838 -53.974238)
		(end 375.005854 -53.974238)
		(width 0.254)
		(layer "In9.Cu")
		(net "P3V3_STBY")
	)
	(segment
		(start 22.991572 -99.689158)
		(end 24.090376 -100.787962)
		(width 0.254)
		(layer "In9.Cu")
		(net "P3V3_STBY")
	)
	(segment
		(start 38.53434 -104.10444)
		(end 38.2651 -104.10444)
		(width 0.4064)
		(layer "In9.Cu")
		(net "P3V3_STBY")
	)
	(segment
		(start 24.090376 -100.787962)
		(end 24.090376 -106.35361)
		(width 0.254)
		(layer "In9.Cu")
		(net "P3V3_STBY")
	)
	(segment
		(start 26.2128 -84.86902)
		(end 25.82672 -84.48294)
		(width 0.254)
		(layer "In9.Cu")
		(net "P3V3_STBY")
	)
	(segment
		(start 339.75929 -85.36686)
		(end 340.95055 -84.1756)
		(width 0.254)
		(layer "In9.Cu")
		(net "P3V3_STBY")
	)
	(segment
		(start 31.133796 -105.135934)
		(end 31.985458 -105.135934)
		(width 0.254)
		(layer "In9.Cu")
		(net "P3V3_STBY")
	)
	(segment
		(start 40.096948 -105.667048)
		(end 38.53434 -104.10444)
		(width 0.4064)
		(layer "In9.Cu")
		(net "P3V3_STBY")
	)
	(segment
		(start 338.25688 -85.04174)
		(end 338.25688 -85.11286)
		(width 0.254)
		(layer "In9.Cu")
		(net "P3V3_STBY")
	)
	(segment
		(start 16.768064 -118.9609)
		(end 16.768064 -118.289578)
		(width 0.254)
		(layer "In9.Cu")
		(net "P3V3_STBY")
	)
	(segment
		(start 352.6663 -84.1375)
		(end 352.72726 -84.19846)
		(width 0.254)
		(layer "In9.Cu")
		(net "P3V3_STBY")
	)
	(segment
		(start 340.95055 -84.1756)
		(end 342.0618 -84.1756)
		(width 0.254)
		(layer "In9.Cu")
		(net "P3V3_STBY")
	)
	(segment
		(start 377.42622 -55.37962)
		(end 376.020838 -53.974238)
		(width 0.254)
		(layer "In9.Cu")
		(net "P3V3_STBY")
	)
	(segment
		(start 26.503122 -80.416908)
		(end 25.527 -79.440786)
		(width 0.254)
		(layer "In9.Cu")
		(net "P3V3_STBY")
	)
	(segment
		(start 345.0844 -82.3468)
		(end 345.2368 -82.1944)
		(width 0.254)
		(layer "In9.Cu")
		(net "P3V3_STBY")
	)
	(segment
		(start 24.62784 -84.48294)
		(end 23.96744 -85.14334)
		(width 0.254)
		(layer "In9.Cu")
		(net "P3V3_STBY")
	)
	(segment
		(start 5.48005 -113.816892)
		(end 2.63271 -116.664232)
		(width 0.254)
		(layer "In9.Cu")
		(net "P3V3_STBY")
	)
	(segment
		(start 352.72726 -84.19846)
		(end 353.041966 -84.19846)
		(width 0.254)
		(layer "In9.Cu")
		(net "P3V3_STBY")
	)
	(segment
		(start 29.464762 -108.109258)
		(end 30.371034 -107.202986)
		(width 0.254)
		(layer "In9.Cu")
		(net "P3V3_STBY")
	)
	(segment
		(start 26.5684 -80.416908)
		(end 26.503122 -80.416908)
		(width 0.254)
		(layer "In9.Cu")
		(net "P3V3_STBY")
	)
	(segment
		(start 377.879864 -55.5371)
		(end 377.722384 -55.37962)
		(width 0.254)
		(layer "In9.Cu")
		(net "P3V3_STBY")
	)
	(segment
		(start 356.32136 -87.477854)
		(end 356.32136 -89.598246)
		(width 0.254)
		(layer "In9.Cu")
		(net "P3V3_STBY")
	)
	(segment
		(start 338.25688 -85.11286)
		(end 338.51088 -85.36686)
		(width 0.254)
		(layer "In9.Cu")
		(net "P3V3_STBY")
	)
	(segment
		(start 343.8906 -82.3468)
		(end 345.0844 -82.3468)
		(width 0.254)
		(layer "In9.Cu")
		(net "P3V3_STBY")
	)
	(segment
		(start 345.2368 -82.1944)
		(end 345.2368 -81.8388)
		(width 0.254)
		(layer "In9.Cu")
		(net "P3V3_STBY")
	)
	(segment
		(start 23.96744 -85.14334)
		(end 23.36292 -85.14334)
		(width 0.254)
		(layer "In9.Cu")
		(net "P3V3_STBY")
	)
	(segment
		(start 338.51088 -85.36686)
		(end 339.75929 -85.36686)
		(width 0.254)
		(layer "In9.Cu")
		(net "P3V3_STBY")
	)
	(segment
		(start 25.82672 -84.48294)
		(end 24.62784 -84.48294)
		(width 0.254)
		(layer "In9.Cu")
		(net "P3V3_STBY")
	)
	(segment
		(start 22.92096 -85.5853)
		(end 22.92096 -85.84946)
		(width 0.254)
		(layer "In9.Cu")
		(net "P3V3_STBY")
	)
	(segment
		(start 354.972366 -90.94724)
		(end 353.55276 -90.94724)
		(width 0.254)
		(layer "In9.Cu")
		(net "P3V3_STBY")
	)
	(segment
		(start 2.63271 -116.664232)
		(end 2.63271 -117.246908)
		(width 0.254)
		(layer "In9.Cu")
		(net "P3V3_STBY")
	)
	(segment
		(start 2.264918 -117.6147)
		(end 1.303274 -117.6147)
		(width 0.254)
		(layer "In9.Cu")
		(net "P3V3_STBY")
	)
	(segment
		(start 2.63271 -117.246908)
		(end 2.264918 -117.6147)
		(width 0.254)
		(layer "In9.Cu")
		(net "P3V3_STBY")
	)
	(segment
		(start 353.041966 -84.19846)
		(end 356.32136 -87.477854)
		(width 0.254)
		(layer "In9.Cu")
		(net "P3V3_STBY")
	)
	(segment
		(start 375.005854 -53.974238)
		(end 374.751854 -53.720238)
		(width 0.254)
		(layer "In9.Cu")
		(net "P3V3_STBY")
	)
	(segment
		(start 337.512152 -14.894306)
		(end 336.836258 -14.894306)
		(width 0.508)
		(layer "In11.Cu")
		(net "P3V3_STBY")
	)
	(segment
		(start 336.836258 -14.894306)
		(end 336.328258 -14.386306)
		(width 0.508)
		(layer "In11.Cu")
		(net "P3V3_STBY")
	)
	(segment
		(start 339.471 -20.5994)
		(end 338.482432 -19.610832)
		(width 0.508)
		(layer "In11.Cu")
		(net "P3V3_STBY")
	)
	(segment
		(start 433.143152 -49.1363)
		(end 432.4096 -49.1363)
		(width 0.254)
		(layer "In11.Cu")
		(net "P3V3_STBY")
	)
	(segment
		(start 440.0042 -61.341)
		(end 439.6232 -60.96)
		(width 0.381)
		(layer "In11.Cu")
		(net "P3V3_STBY")
	)
	(segment
		(start 389.9662 -19.93646)
		(end 389.9662 -24.825706)
		(width 0.254)
		(layer "In11.Cu")
		(net "P3V3_STBY")
	)
	(segment
		(start 440.4614 -64.262)
		(end 440.0042 -63.8048)
		(width 0.381)
		(layer "In11.Cu")
		(net "P3V3_STBY")
	)
	(segment
		(start 343.281 -20.71751)
		(end 343.281 -21.082)
		(width 0.508)
		(layer "In11.Cu")
		(net "P3V3_STBY")
	)
	(segment
		(start 445.77 -64.262)
		(end 440.4614 -64.262)
		(width 0.381)
		(layer "In11.Cu")
		(net "P3V3_STBY")
	)
	(segment
		(start -4.064 -123.808744)
		(end -4.064 -122.7328)
		(width 0.254)
		(layer "In11.Cu")
		(net "P3V3_STBY")
	)
	(segment
		(start 176.200816 -127.12827)
		(end 176.2506 -127.178054)
		(width 0.254)
		(layer "In11.Cu")
		(net "P3V3_STBY")
	)
	(segment
		(start 446.532 -63.5)
		(end 445.77 -64.262)
		(width 0.381)
		(layer "In11.Cu")
		(net "P3V3_STBY")
	)
	(segment
		(start 368.319304 -60.953904)
		(end 365.126016 -57.760616)
		(width 0.254)
		(layer "In11.Cu")
		(net "P3V3_STBY")
	)
	(segment
		(start 340.9696 -20.5994)
		(end 341.364824 -20.204176)
		(width 0.508)
		(layer "In11.Cu")
		(net "P3V3_STBY")
	)
	(segment
		(start 433.720748 -49.713896)
		(end 433.143152 -49.1363)
		(width 0.254)
		(layer "In11.Cu")
		(net "P3V3_STBY")
	)
	(segment
		(start 171.2214 -95.924624)
		(end 170.694096 -96.451928)
		(width 0.254)
		(layer "In11.Cu")
		(net "P3V3_STBY")
	)
	(segment
		(start -1.44526 -120.11406)
		(end -1.44526 -118.83136)
		(width 0.254)
		(layer "In11.Cu")
		(net "P3V3_STBY")
	)
	(segment
		(start 176.200816 -125.578362)
		(end 176.200816 -127.12827)
		(width 0.254)
		(layer "In11.Cu")
		(net "P3V3_STBY")
	)
	(segment
		(start 336.328258 -14.386306)
		(end 336.328258 -12.910058)
		(width 0.508)
		(layer "In11.Cu")
		(net "P3V3_STBY")
	)
	(segment
		(start 338.482432 -19.610832)
		(end 338.482432 -15.864586)
		(width 0.508)
		(layer "In11.Cu")
		(net "P3V3_STBY")
	)
	(segment
		(start -3.2004 -129.921)
		(end -3.2004 -124.672344)
		(width 0.254)
		(layer "In11.Cu")
		(net "P3V3_STBY")
	)
	(segment
		(start 176.175416 -125.552962)
		(end 176.200816 -125.578362)
		(width 0.254)
		(layer "In11.Cu")
		(net "P3V3_STBY")
	)
	(segment
		(start 368.319304 -62.776608)
		(end 368.319304 -60.953904)
		(width 0.254)
		(layer "In11.Cu")
		(net "P3V3_STBY")
	)
	(segment
		(start 338.482432 -15.864586)
		(end 337.512152 -14.894306)
		(width 0.508)
		(layer "In11.Cu")
		(net "P3V3_STBY")
	)
	(segment
		(start 439.6232 -59.91606)
		(end 440.40552 -59.13374)
		(width 0.381)
		(layer "In11.Cu")
		(net "P3V3_STBY")
	)
	(segment
		(start 391.737596 -26.597102)
		(end 393.493498 -26.597102)
		(width 0.254)
		(layer "In11.Cu")
		(net "P3V3_STBY")
	)
	(segment
		(start 179.320444 -130.813556)
		(end 179.959 -130.175)
		(width 0.254)
		(layer "In11.Cu")
		(net "P3V3_STBY")
	)
	(segment
		(start -3.2004 -124.672344)
		(end -4.064 -123.808744)
		(width 0.254)
		(layer "In11.Cu")
		(net "P3V3_STBY")
	)
	(segment
		(start -4.714748 -132.640578)
		(end -4.714748 -131.435348)
		(width 0.254)
		(layer "In11.Cu")
		(net "P3V3_STBY")
	)
	(segment
		(start 434.811678 -51.5239)
		(end 433.721764 -50.433986)
		(width 0.254)
		(layer "In11.Cu")
		(net "P3V3_STBY")
	)
	(segment
		(start 341.364824 -20.204176)
		(end 342.767666 -20.204176)
		(width 0.508)
		(layer "In11.Cu")
		(net "P3V3_STBY")
	)
	(segment
		(start 436.9689 -51.5239)
		(end 434.811678 -51.5239)
		(width 0.254)
		(layer "In11.Cu")
		(net "P3V3_STBY")
	)
	(segment
		(start 365.126016 -57.760616)
		(end 362.764324 -57.760616)
		(width 0.254)
		(layer "In11.Cu")
		(net "P3V3_STBY")
	)
	(segment
		(start 170.694096 -96.451928)
		(end 170.694096 -100.539296)
		(width 0.254)
		(layer "In11.Cu")
		(net "P3V3_STBY")
	)
	(segment
		(start 362.764324 -57.760616)
		(end 361.259374 -56.255666)
		(width 0.254)
		(layer "In11.Cu")
		(net "P3V3_STBY")
	)
	(segment
		(start 369.7224 -64.179704)
		(end 368.319304 -62.776608)
		(width 0.254)
		(layer "In11.Cu")
		(net "P3V3_STBY")
	)
	(segment
		(start 369.7224 -64.725804)
		(end 369.7224 -64.179704)
		(width 0.254)
		(layer "In11.Cu")
		(net "P3V3_STBY")
	)
	(segment
		(start -4.064 -122.7328)
		(end -1.44526 -120.11406)
		(width 0.254)
		(layer "In11.Cu")
		(net "P3V3_STBY")
	)
	(segment
		(start 176.2506 -127.178054)
		(end 176.2506 -127.7112)
		(width 0.254)
		(layer "In11.Cu")
		(net "P3V3_STBY")
	)
	(segment
		(start 436.9689 -51.5239)
		(end 438.7469 -49.7459)
		(width 0.381)
		(layer "In11.Cu")
		(net "P3V3_STBY")
	)
	(segment
		(start 172.101002 -92.835984)
		(end 171.2214 -93.715586)
		(width 0.254)
		(layer "In11.Cu")
		(net "P3V3_STBY")
	)
	(segment
		(start 440.0042 -63.8048)
		(end 440.0042 -61.341)
		(width 0.381)
		(layer "In11.Cu")
		(net "P3V3_STBY")
	)
	(segment
		(start 433.720748 -50.163476)
		(end 433.720748 -49.713896)
		(width 0.254)
		(layer "In11.Cu")
		(net "P3V3_STBY")
	)
	(segment
		(start 177.0888 -130.4036)
		(end 177.498756 -130.813556)
		(width 0.254)
		(layer "In11.Cu")
		(net "P3V3_STBY")
	)
	(segment
		(start 439.6232 -60.96)
		(end 439.6232 -59.91606)
		(width 0.381)
		(layer "In11.Cu")
		(net "P3V3_STBY")
	)
	(segment
		(start 389.9662 -24.825706)
		(end 391.737596 -26.597102)
		(width 0.254)
		(layer "In11.Cu")
		(net "P3V3_STBY")
	)
	(segment
		(start 433.721764 -50.433986)
		(end 433.721764 -50.164492)
		(width 0.254)
		(layer "In11.Cu")
		(net "P3V3_STBY")
	)
	(segment
		(start 177.0888 -128.5494)
		(end 177.0888 -130.4036)
		(width 0.254)
		(layer "In11.Cu")
		(net "P3V3_STBY")
	)
	(segment
		(start 339.471 -20.5994)
		(end 340.9696 -20.5994)
		(width 0.508)
		(layer "In11.Cu")
		(net "P3V3_STBY")
	)
	(segment
		(start 440.40552 -59.13374)
		(end 436.9689 -55.69712)
		(width 0.381)
		(layer "In11.Cu")
		(net "P3V3_STBY")
	)
	(segment
		(start 171.2214 -93.715586)
		(end 171.2214 -95.924624)
		(width 0.254)
		(layer "In11.Cu")
		(net "P3V3_STBY")
	)
	(segment
		(start 177.498756 -130.813556)
		(end 179.320444 -130.813556)
		(width 0.254)
		(layer "In11.Cu")
		(net "P3V3_STBY")
	)
	(segment
		(start 170.694096 -100.539296)
		(end 174.5996 -104.4448)
		(width 0.254)
		(layer "In11.Cu")
		(net "P3V3_STBY")
	)
	(segment
		(start -4.714748 -131.435348)
		(end -3.2004 -129.921)
		(width 0.254)
		(layer "In11.Cu")
		(net "P3V3_STBY")
	)
	(segment
		(start -4.61264 -132.742686)
		(end -4.714748 -132.640578)
		(width 0.254)
		(layer "In11.Cu")
		(net "P3V3_STBY")
	)
	(segment
		(start 438.7469 -49.7459)
		(end 439.5216 -49.7459)
		(width 0.381)
		(layer "In11.Cu")
		(net "P3V3_STBY")
	)
	(segment
		(start 176.2506 -127.7112)
		(end 177.0888 -128.5494)
		(width 0.254)
		(layer "In11.Cu")
		(net "P3V3_STBY")
	)
	(segment
		(start 342.767666 -20.204176)
		(end 343.281 -20.71751)
		(width 0.508)
		(layer "In11.Cu")
		(net "P3V3_STBY")
	)
	(segment
		(start 436.9689 -55.69712)
		(end 436.9689 -51.5239)
		(width 0.381)
		(layer "In11.Cu")
		(net "P3V3_STBY")
	)
	(segment
		(start 433.721764 -50.164492)
		(end 433.720748 -50.163476)
		(width 0.254)
		(layer "In11.Cu")
		(net "P3V3_STBY")
	)
	(segment
		(start 408.6225 -21.310092)
		(end 408.284426 -20.972018)
		(width 0.10795)
		(layer "F.Cu")
		(net "RMII_SPRNGVLLE_BMC_PCH_RXD1")
	)
	(segment
		(start 393.192 -84.165694)
		(end 393.080494 -84.2772)
		(width 0.10795)
		(layer "F.Cu")
		(net "RMII_SPRNGVLLE_BMC_PCH_RXD1")
	)
	(segment
		(start 491.9345 -42.0624)
		(end 492.6457 -42.0624)
		(width 0.10795)
		(layer "F.Cu")
		(net "RMII_SPRNGVLLE_BMC_PCH_RXD1")
	)
	(segment
		(start 391.3886 -85.25764)
		(end 391.079482 -85.25764)
		(width 0.10795)
		(layer "F.Cu")
		(net "RMII_SPRNGVLLE_BMC_PCH_RXD1")
	)
	(segment
		(start 409.490164 -25.315164)
		(end 409.490164 -26.534618)
		(width 0.10795)
		(layer "F.Cu")
		(net "RMII_SPRNGVLLE_BMC_PCH_RXD1")
	)
	(segment
		(start 406.6921 -20.2311)
		(end 405.926798 -20.2311)
		(width 0.10795)
		(layer "F.Cu")
		(net "RMII_SPRNGVLLE_BMC_PCH_RXD1")
	)
	(segment
		(start 405.926798 -20.2311)
		(end 405.888698 -20.193)
		(width 0.10795)
		(layer "F.Cu")
		(net "RMII_SPRNGVLLE_BMC_PCH_RXD1")
	)
	(segment
		(start 408.6225 -24.4475)
		(end 409.490164 -25.315164)
		(width 0.10795)
		(layer "F.Cu")
		(net "RMII_SPRNGVLLE_BMC_PCH_RXD1")
	)
	(segment
		(start 407.433018 -20.972018)
		(end 406.6921 -20.2311)
		(width 0.10795)
		(layer "F.Cu")
		(net "RMII_SPRNGVLLE_BMC_PCH_RXD1")
	)
	(segment
		(start 391.079482 -85.25764)
		(end 390.779 -85.558122)
		(width 0.10795)
		(layer "F.Cu")
		(net "RMII_SPRNGVLLE_BMC_PCH_RXD1")
	)
	(segment
		(start 392.36904 -84.2772)
		(end 391.3886 -85.25764)
		(width 0.10795)
		(layer "F.Cu")
		(net "RMII_SPRNGVLLE_BMC_PCH_RXD1")
	)
	(segment
		(start 390.652 -86.7156)
		(end 390.652 -87.3125)
		(width 0.10795)
		(layer "F.Cu")
		(net "RMII_SPRNGVLLE_BMC_PCH_RXD1")
	)
	(segment
		(start 390.779 -85.558122)
		(end 390.779 -86.5886)
		(width 0.10795)
		(layer "F.Cu")
		(net "RMII_SPRNGVLLE_BMC_PCH_RXD1")
	)
	(segment
		(start 393.080494 -84.2772)
		(end 392.36904 -84.2772)
		(width 0.10795)
		(layer "F.Cu")
		(net "RMII_SPRNGVLLE_BMC_PCH_RXD1")
	)
	(segment
		(start 408.6225 -22.987)
		(end 408.6225 -21.310092)
		(width 0.10795)
		(layer "F.Cu")
		(net "RMII_SPRNGVLLE_BMC_PCH_RXD1")
	)
	(segment
		(start 390.779 -86.5886)
		(end 390.652 -86.7156)
		(width 0.10795)
		(layer "F.Cu")
		(net "RMII_SPRNGVLLE_BMC_PCH_RXD1")
	)
	(segment
		(start 408.284426 -20.972018)
		(end 407.433018 -20.972018)
		(width 0.10795)
		(layer "F.Cu")
		(net "RMII_SPRNGVLLE_BMC_PCH_RXD1")
	)
	(segment
		(start 408.6225 -22.987)
		(end 408.6225 -24.4475)
		(width 0.10795)
		(layer "F.Cu")
		(net "RMII_SPRNGVLLE_BMC_PCH_RXD1")
	)
	(via
		(at 492.6457 -42.0624)
		(size 0.508)
		(drill 0.254)
		(layers "F.Cu" "B.Cu")
		(net "RMII_SPRNGVLLE_BMC_PCH_RXD1")
	)
	(via
		(at 393.192 -84.165694)
		(size 0.508)
		(drill 0.254)
		(layers "F.Cu" "B.Cu")
		(net "RMII_SPRNGVLLE_BMC_PCH_RXD1")
	)
	(via
		(at 405.888698 -20.193)
		(size 0.508)
		(drill 0.254)
		(layers "F.Cu" "B.Cu")
		(net "RMII_SPRNGVLLE_BMC_PCH_RXD1")
	)
	(via
		(at 374.015 -31.4198)
		(size 0.508)
		(drill 0.254)
		(layers "F.Cu" "B.Cu")
		(net "RMII_SPRNGVLLE_BMC_PCH_RXD1")
	)
	(segment
		(start 485.851962 -35.662108)
		(end 485.200706 -35.662108)
		(width 0.089408)
		(layer "In4.Cu")
		(net "RMII_SPRNGVLLE_BMC_PCH_RXD1")
	)
	(segment
		(start 412.477712 -14.26718)
		(end 412.35122 -14.26718)
		(width 0.089408)
		(layer "In4.Cu")
		(net "RMII_SPRNGVLLE_BMC_PCH_RXD1")
	)
	(segment
		(start 498.767862 -40.1701)
		(end 498.678454 -40.080692)
		(width 0.089408)
		(layer "In4.Cu")
		(net "RMII_SPRNGVLLE_BMC_PCH_RXD1")
	)
	(segment
		(start 406.770078 -18.972784)
		(end 406.770078 -19.167348)
		(width 0.089408)
		(layer "In4.Cu")
		(net "RMII_SPRNGVLLE_BMC_PCH_RXD1")
	)
	(segment
		(start 411.495494 -16.090646)
		(end 410.79547 -15.390622)
		(width 0.089408)
		(layer "In4.Cu")
		(net "RMII_SPRNGVLLE_BMC_PCH_RXD1")
	)
	(segment
		(start 374.115838 -27.918156)
		(end 374.448324 -27.585416)
		(width 0.089408)
		(layer "In4.Cu")
		(net "RMII_SPRNGVLLE_BMC_PCH_RXD1")
	)
	(segment
		(start 373.761762 -29.6672)
		(end 374.115838 -29.313124)
		(width 0.089408)
		(layer "In4.Cu")
		(net "RMII_SPRNGVLLE_BMC_PCH_RXD1")
	)
	(segment
		(start 488.061254 -37.8714)
		(end 485.851962 -35.662108)
		(width 0.089408)
		(layer "In4.Cu")
		(net "RMII_SPRNGVLLE_BMC_PCH_RXD1")
	)
	(segment
		(start 491.006638 -39.500048)
		(end 489.37799 -37.8714)
		(width 0.089408)
		(layer "In4.Cu")
		(net "RMII_SPRNGVLLE_BMC_PCH_RXD1")
	)
	(segment
		(start 477.288352 -23.93188)
		(end 475.74708 -22.390608)
		(width 0.089408)
		(layer "In4.Cu")
		(net "RMII_SPRNGVLLE_BMC_PCH_RXD1")
	)
	(segment
		(start 408.038046 -17.704816)
		(end 407.561288 -17.228058)
		(width 0.089408)
		(layer "In4.Cu")
		(net "RMII_SPRNGVLLE_BMC_PCH_RXD1")
	)
	(segment
		(start 406.715976 -18.07337)
		(end 406.589484 -18.07337)
		(width 0.089408)
		(layer "In4.Cu")
		(net "RMII_SPRNGVLLE_BMC_PCH_RXD1")
	)
	(segment
		(start 411.621986 -16.090646)
		(end 411.495494 -16.090646)
		(width 0.089408)
		(layer "In4.Cu")
		(net "RMII_SPRNGVLLE_BMC_PCH_RXD1")
	)
	(segment
		(start 407.192734 -18.550128)
		(end 406.715976 -18.07337)
		(width 0.089408)
		(layer "In4.Cu")
		(net "RMII_SPRNGVLLE_BMC_PCH_RXD1")
	)
	(segment
		(start 496.198398 -38.5826)
		(end 495.779552 -38.5826)
		(width 0.089408)
		(layer "In4.Cu")
		(net "RMII_SPRNGVLLE_BMC_PCH_RXD1")
	)
	(segment
		(start 464.31073 -17.487646)
		(end 464.31073 -18.656808)
		(width 0.089408)
		(layer "In4.Cu")
		(net "RMII_SPRNGVLLE_BMC_PCH_RXD1")
	)
	(segment
		(start 492.6457 -42.0624)
		(end 492.6457 -41.7322)
		(width 0.089408)
		(layer "In4.Cu")
		(net "RMII_SPRNGVLLE_BMC_PCH_RXD1")
	)
	(segment
		(start 411.072838 -16.639794)
		(end 410.781246 -16.931386)
		(width 0.089408)
		(layer "In4.Cu")
		(net "RMII_SPRNGVLLE_BMC_PCH_RXD1")
	)
	(segment
		(start 491.006638 -40.423338)
		(end 491.006638 -39.500048)
		(width 0.089408)
		(layer "In4.Cu")
		(net "RMII_SPRNGVLLE_BMC_PCH_RXD1")
	)
	(segment
		(start 406.29332 -18.496026)
		(end 406.770078 -18.972784)
		(width 0.089408)
		(layer "In4.Cu")
		(net "RMII_SPRNGVLLE_BMC_PCH_RXD1")
	)
	(segment
		(start 495.690144 -40.080692)
		(end 495.600736 -40.1701)
		(width 0.089408)
		(layer "In4.Cu")
		(net "RMII_SPRNGVLLE_BMC_PCH_RXD1")
	)
	(segment
		(start 373.761762 -31.166562)
		(end 373.761762 -29.6672)
		(width 0.089408)
		(layer "In4.Cu")
		(net "RMII_SPRNGVLLE_BMC_PCH_RXD1")
	)
	(segment
		(start 412.47568 -15.11046)
		(end 412.47568 -15.236952)
		(width 0.089408)
		(layer "In4.Cu")
		(net "RMII_SPRNGVLLE_BMC_PCH_RXD1")
	)
	(segment
		(start 482.859334 -34.621724)
		(end 482.859334 -33.647634)
		(width 0.089408)
		(layer "In4.Cu")
		(net "RMII_SPRNGVLLE_BMC_PCH_RXD1")
	)
	(segment
		(start 382.25095 -18.517108)
		(end 391.562844 -18.517108)
		(width 0.089408)
		(layer "In4.Cu")
		(net "RMII_SPRNGVLLE_BMC_PCH_RXD1")
	)
	(segment
		(start 412.47568 -15.236952)
		(end 411.621986 -16.090646)
		(width 0.089408)
		(layer "In4.Cu")
		(net "RMII_SPRNGVLLE_BMC_PCH_RXD1")
	)
	(segment
		(start 471.83548 -15.840202)
		(end 465.958174 -15.840202)
		(width 0.089408)
		(layer "In4.Cu")
		(net "RMII_SPRNGVLLE_BMC_PCH_RXD1")
	)
	(segment
		(start 489.37799 -37.8714)
		(end 488.061254 -37.8714)
		(width 0.089408)
		(layer "In4.Cu")
		(net "RMII_SPRNGVLLE_BMC_PCH_RXD1")
	)
	(segment
		(start 492.6457 -41.7322)
		(end 492.8997 -41.4782)
		(width 0.089408)
		(layer "In4.Cu")
		(net "RMII_SPRNGVLLE_BMC_PCH_RXD1")
	)
	(segment
		(start 448.630548 -13.34008)
		(end 440.328812 -13.34008)
		(width 0.089408)
		(layer "In4.Cu")
		(net "RMII_SPRNGVLLE_BMC_PCH_RXD1")
	)
	(segment
		(start 405.429466 -20.193)
		(end 405.888698 -20.193)
		(width 0.089408)
		(layer "In4.Cu")
		(net "RMII_SPRNGVLLE_BMC_PCH_RXD1")
	)
	(segment
		(start 374.115838 -29.313124)
		(end 374.115838 -27.918156)
		(width 0.089408)
		(layer "In4.Cu")
		(net "RMII_SPRNGVLLE_BMC_PCH_RXD1")
	)
	(segment
		(start 491.30585 -40.72255)
		(end 491.006638 -40.423338)
		(width 0.089408)
		(layer "In4.Cu")
		(net "RMII_SPRNGVLLE_BMC_PCH_RXD1")
	)
	(segment
		(start 493.405668 -44.233592)
		(end 493.495076 -44.323)
		(width 0.089408)
		(layer "In4.Cu")
		(net "RMII_SPRNGVLLE_BMC_PCH_RXD1")
	)
	(segment
		(start 495.600736 -40.1701)
		(end 493.9665 -40.1701)
		(width 0.089408)
		(layer "In4.Cu")
		(net "RMII_SPRNGVLLE_BMC_PCH_RXD1")
	)
	(segment
		(start 481.100892 -25.137872)
		(end 479.8949 -23.93188)
		(width 0.089408)
		(layer "In4.Cu")
		(net "RMII_SPRNGVLLE_BMC_PCH_RXD1")
	)
	(segment
		(start 498.080792 -40.080692)
		(end 497.991384 -40.1701)
		(width 0.089408)
		(layer "In4.Cu")
		(net "RMII_SPRNGVLLE_BMC_PCH_RXD1")
	)
	(segment
		(start 406.770078 -19.167348)
		(end 405.888698 -20.048728)
		(width 0.089408)
		(layer "In4.Cu")
		(net "RMII_SPRNGVLLE_BMC_PCH_RXD1")
	)
	(segment
		(start 485.200706 -35.662108)
		(end 484.463598 -34.925)
		(width 0.089408)
		(layer "In4.Cu")
		(net "RMII_SPRNGVLLE_BMC_PCH_RXD1")
	)
	(segment
		(start 451.9422 -16.937228)
		(end 451.9422 -16.651732)
		(width 0.089408)
		(layer "In4.Cu")
		(net "RMII_SPRNGVLLE_BMC_PCH_RXD1")
	)
	(segment
		(start 410.372814 -15.813278)
		(end 411.072838 -16.513302)
		(width 0.089408)
		(layer "In4.Cu")
		(net "RMII_SPRNGVLLE_BMC_PCH_RXD1")
	)
	(segment
		(start 499.421404 -40.861996)
		(end 499.6434 -40.64)
		(width 0.089408)
		(layer "In4.Cu")
		(net "RMII_SPRNGVLLE_BMC_PCH_RXD1")
	)
	(segment
		(start 413.539432 -14.1732)
		(end 413.024828 -14.687804)
		(width 0.089408)
		(layer "In4.Cu")
		(net "RMII_SPRNGVLLE_BMC_PCH_RXD1")
	)
	(segment
		(start 496.974876 -39.1922)
		(end 496.885468 -39.281608)
		(width 0.089408)
		(layer "In4.Cu")
		(net "RMII_SPRNGVLLE_BMC_PCH_RXD1")
	)
	(segment
		(start 412.055056 -14.689836)
		(end 412.47568 -15.11046)
		(width 0.089408)
		(layer "In4.Cu")
		(net "RMII_SPRNGVLLE_BMC_PCH_RXD1")
	)
	(segment
		(start 407.319226 -18.550128)
		(end 407.192734 -18.550128)
		(width 0.089408)
		(layer "In4.Cu")
		(net "RMII_SPRNGVLLE_BMC_PCH_RXD1")
	)
	(segment
		(start 391.562844 -18.517108)
		(end 391.613644 -18.567908)
		(width 0.089408)
		(layer "In4.Cu")
		(net "RMII_SPRNGVLLE_BMC_PCH_RXD1")
	)
	(segment
		(start 408.164538 -17.704816)
		(end 408.038046 -17.704816)
		(width 0.089408)
		(layer "In4.Cu")
		(net "RMII_SPRNGVLLE_BMC_PCH_RXD1")
	)
	(segment
		(start 499.6434 -40.259508)
		(end 499.553992 -40.1701)
		(width 0.089408)
		(layer "In4.Cu")
		(net "RMII_SPRNGVLLE_BMC_PCH_RXD1")
	)
	(segment
		(start 406.29332 -18.369534)
		(end 406.29332 -18.496026)
		(width 0.089408)
		(layer "In4.Cu")
		(net "RMII_SPRNGVLLE_BMC_PCH_RXD1")
	)
	(segment
		(start 492.49965 -40.72255)
		(end 491.30585 -40.72255)
		(width 0.089408)
		(layer "In4.Cu")
		(net "RMII_SPRNGVLLE_BMC_PCH_RXD1")
	)
	(segment
		(start 496.885468 -39.281608)
		(end 496.885468 -40.080692)
		(width 0.089408)
		(layer "In4.Cu")
		(net "RMII_SPRNGVLLE_BMC_PCH_RXD1")
	)
	(segment
		(start 438.098692 -15.5702)
		(end 422.3004 -15.5702)
		(width 0.089408)
		(layer "In4.Cu")
		(net "RMII_SPRNGVLLE_BMC_PCH_RXD1")
	)
	(segment
		(start 496.885468 -40.080692)
		(end 496.79606 -40.1701)
		(width 0.089408)
		(layer "In4.Cu")
		(net "RMII_SPRNGVLLE_BMC_PCH_RXD1")
	)
	(segment
		(start 497.48313 -39.281608)
		(end 497.393722 -39.1922)
		(width 0.089408)
		(layer "In4.Cu")
		(net "RMII_SPRNGVLLE_BMC_PCH_RXD1")
	)
	(segment
		(start 497.991384 -40.1701)
		(end 497.572538 -40.1701)
		(width 0.089408)
		(layer "In4.Cu")
		(net "RMII_SPRNGVLLE_BMC_PCH_RXD1")
	)
	(segment
		(start 493.913922 -44.323)
		(end 494.00333 -44.233592)
		(width 0.089408)
		(layer "In4.Cu")
		(net "RMII_SPRNGVLLE_BMC_PCH_RXD1")
	)
	(segment
		(start 493.495076 -44.323)
		(end 493.913922 -44.323)
		(width 0.089408)
		(layer "In4.Cu")
		(net "RMII_SPRNGVLLE_BMC_PCH_RXD1")
	)
	(segment
		(start 464.31073 -18.656808)
		(end 463.777838 -19.1897)
		(width 0.089408)
		(layer "In4.Cu")
		(net "RMII_SPRNGVLLE_BMC_PCH_RXD1")
	)
	(segment
		(start 475.74708 -22.390608)
		(end 475.74708 -19.751802)
		(width 0.089408)
		(layer "In4.Cu")
		(net "RMII_SPRNGVLLE_BMC_PCH_RXD1")
	)
	(segment
		(start 496.377214 -40.1701)
		(end 496.287806 -40.080692)
		(width 0.089408)
		(layer "In4.Cu")
		(net "RMII_SPRNGVLLE_BMC_PCH_RXD1")
	)
	(segment
		(start 411.072838 -16.513302)
		(end 411.072838 -16.639794)
		(width 0.089408)
		(layer "In4.Cu")
		(net "RMII_SPRNGVLLE_BMC_PCH_RXD1")
	)
	(segment
		(start 405.019002 -20.603464)
		(end 405.429466 -20.193)
		(width 0.089408)
		(layer "In4.Cu")
		(net "RMII_SPRNGVLLE_BMC_PCH_RXD1")
	)
	(segment
		(start 413.024828 -14.687804)
		(end 412.898336 -14.687804)
		(width 0.089408)
		(layer "In4.Cu")
		(net "RMII_SPRNGVLLE_BMC_PCH_RXD1")
	)
	(segment
		(start 495.779552 -38.5826)
		(end 495.690144 -38.672008)
		(width 0.089408)
		(layer "In4.Cu")
		(net "RMII_SPRNGVLLE_BMC_PCH_RXD1")
	)
	(segment
		(start 479.8949 -23.93188)
		(end 477.288352 -23.93188)
		(width 0.089408)
		(layer "In4.Cu")
		(net "RMII_SPRNGVLLE_BMC_PCH_RXD1")
	)
	(segment
		(start 498.678454 -39.281608)
		(end 498.589046 -39.1922)
		(width 0.089408)
		(layer "In4.Cu")
		(net "RMII_SPRNGVLLE_BMC_PCH_RXD1")
	)
	(segment
		(start 412.35122 -14.26718)
		(end 412.055056 -14.563344)
		(width 0.089408)
		(layer "In4.Cu")
		(net "RMII_SPRNGVLLE_BMC_PCH_RXD1")
	)
	(segment
		(start 496.287806 -40.080692)
		(end 496.287806 -38.672008)
		(width 0.089408)
		(layer "In4.Cu")
		(net "RMII_SPRNGVLLE_BMC_PCH_RXD1")
	)
	(segment
		(start 376.908568 -23.85949)
		(end 382.25095 -18.517108)
		(width 0.089408)
		(layer "In4.Cu")
		(net "RMII_SPRNGVLLE_BMC_PCH_RXD1")
	)
	(segment
		(start 453.844152 -18.83918)
		(end 451.9422 -16.937228)
		(width 0.089408)
		(layer "In4.Cu")
		(net "RMII_SPRNGVLLE_BMC_PCH_RXD1")
	)
	(segment
		(start 496.79606 -40.1701)
		(end 496.377214 -40.1701)
		(width 0.089408)
		(layer "In4.Cu")
		(net "RMII_SPRNGVLLE_BMC_PCH_RXD1")
	)
	(segment
		(start 497.572538 -40.1701)
		(end 497.48313 -40.080692)
		(width 0.089408)
		(layer "In4.Cu")
		(net "RMII_SPRNGVLLE_BMC_PCH_RXD1")
	)
	(segment
		(start 374.015 -31.4198)
		(end 373.761762 -31.166562)
		(width 0.089408)
		(layer "In4.Cu")
		(net "RMII_SPRNGVLLE_BMC_PCH_RXD1")
	)
	(segment
		(start 493.5728 -40.5638)
		(end 492.6584 -40.5638)
		(width 0.089408)
		(layer "In4.Cu")
		(net "RMII_SPRNGVLLE_BMC_PCH_RXD1")
	)
	(segment
		(start 498.080792 -39.281608)
		(end 498.080792 -40.080692)
		(width 0.089408)
		(layer "In4.Cu")
		(net "RMII_SPRNGVLLE_BMC_PCH_RXD1")
	)
	(segment
		(start 498.678454 -40.080692)
		(end 498.678454 -39.281608)
		(width 0.089408)
		(layer "In4.Cu")
		(net "RMII_SPRNGVLLE_BMC_PCH_RXD1")
	)
	(segment
		(start 410.781246 -16.931386)
		(end 408.937968 -16.931386)
		(width 0.089408)
		(layer "In4.Cu")
		(net "RMII_SPRNGVLLE_BMC_PCH_RXD1")
	)
	(segment
		(start 410.79547 -15.390622)
		(end 410.668978 -15.390622)
		(width 0.089408)
		(layer "In4.Cu")
		(net "RMII_SPRNGVLLE_BMC_PCH_RXD1")
	)
	(segment
		(start 482.859334 -33.647634)
		(end 481.100892 -31.889192)
		(width 0.089408)
		(layer "In4.Cu")
		(net "RMII_SPRNGVLLE_BMC_PCH_RXD1")
	)
	(segment
		(start 461.46466 -18.83918)
		(end 453.844152 -18.83918)
		(width 0.089408)
		(layer "In4.Cu")
		(net "RMII_SPRNGVLLE_BMC_PCH_RXD1")
	)
	(segment
		(start 499.553992 -40.1701)
		(end 498.767862 -40.1701)
		(width 0.089408)
		(layer "In4.Cu")
		(net "RMII_SPRNGVLLE_BMC_PCH_RXD1")
	)
	(segment
		(start 493.405668 -41.567608)
		(end 493.405668 -44.233592)
		(width 0.089408)
		(layer "In4.Cu")
		(net "RMII_SPRNGVLLE_BMC_PCH_RXD1")
	)
	(segment
		(start 422.3004 -15.5702)
		(end 420.9034 -14.1732)
		(width 0.089408)
		(layer "In4.Cu")
		(net "RMII_SPRNGVLLE_BMC_PCH_RXD1")
	)
	(segment
		(start 412.898336 -14.687804)
		(end 412.477712 -14.26718)
		(width 0.089408)
		(layer "In4.Cu")
		(net "RMII_SPRNGVLLE_BMC_PCH_RXD1")
	)
	(segment
		(start 483.16261 -34.925)
		(end 482.859334 -34.621724)
		(width 0.089408)
		(layer "In4.Cu")
		(net "RMII_SPRNGVLLE_BMC_PCH_RXD1")
	)
	(segment
		(start 494.00333 -41.897808)
		(end 495.039142 -40.861996)
		(width 0.089408)
		(layer "In4.Cu")
		(net "RMII_SPRNGVLLE_BMC_PCH_RXD1")
	)
	(segment
		(start 407.434796 -17.228058)
		(end 407.138632 -17.524222)
		(width 0.089408)
		(layer "In4.Cu")
		(net "RMII_SPRNGVLLE_BMC_PCH_RXD1")
	)
	(segment
		(start 495.690144 -38.672008)
		(end 495.690144 -40.080692)
		(width 0.089408)
		(layer "In4.Cu")
		(net "RMII_SPRNGVLLE_BMC_PCH_RXD1")
	)
	(segment
		(start 484.463598 -34.925)
		(end 483.16261 -34.925)
		(width 0.089408)
		(layer "In4.Cu")
		(net "RMII_SPRNGVLLE_BMC_PCH_RXD1")
	)
	(segment
		(start 410.668978 -15.390622)
		(end 410.372814 -15.686786)
		(width 0.089408)
		(layer "In4.Cu")
		(net "RMII_SPRNGVLLE_BMC_PCH_RXD1")
	)
	(segment
		(start 374.448324 -27.585416)
		(end 374.79605 -27.585416)
		(width 0.089408)
		(layer "In4.Cu")
		(net "RMII_SPRNGVLLE_BMC_PCH_RXD1")
	)
	(segment
		(start 475.74708 -19.751802)
		(end 471.83548 -15.840202)
		(width 0.089408)
		(layer "In4.Cu")
		(net "RMII_SPRNGVLLE_BMC_PCH_RXD1")
	)
	(segment
		(start 403.249638 -20.603464)
		(end 405.019002 -20.603464)
		(width 0.089408)
		(layer "In4.Cu")
		(net "RMII_SPRNGVLLE_BMC_PCH_RXD1")
	)
	(segment
		(start 481.100892 -31.889192)
		(end 481.100892 -25.137872)
		(width 0.089408)
		(layer "In4.Cu")
		(net "RMII_SPRNGVLLE_BMC_PCH_RXD1")
	)
	(segment
		(start 406.589484 -18.07337)
		(end 406.29332 -18.369534)
		(width 0.089408)
		(layer "In4.Cu")
		(net "RMII_SPRNGVLLE_BMC_PCH_RXD1")
	)
	(segment
		(start 393.346686 -20.251674)
		(end 402.897848 -20.251674)
		(width 0.089408)
		(layer "In4.Cu")
		(net "RMII_SPRNGVLLE_BMC_PCH_RXD1")
	)
	(segment
		(start 492.8997 -41.4782)
		(end 493.31626 -41.4782)
		(width 0.089408)
		(layer "In4.Cu")
		(net "RMII_SPRNGVLLE_BMC_PCH_RXD1")
	)
	(segment
		(start 408.937968 -16.931386)
		(end 408.164538 -17.704816)
		(width 0.089408)
		(layer "In4.Cu")
		(net "RMII_SPRNGVLLE_BMC_PCH_RXD1")
	)
	(segment
		(start 499.6434 -40.64)
		(end 499.6434 -40.259508)
		(width 0.089408)
		(layer "In4.Cu")
		(net "RMII_SPRNGVLLE_BMC_PCH_RXD1")
	)
	(segment
		(start 391.66292 -18.567908)
		(end 393.346686 -20.251674)
		(width 0.089408)
		(layer "In4.Cu")
		(net "RMII_SPRNGVLLE_BMC_PCH_RXD1")
	)
	(segment
		(start 494.00333 -44.233592)
		(end 494.00333 -41.897808)
		(width 0.089408)
		(layer "In4.Cu")
		(net "RMII_SPRNGVLLE_BMC_PCH_RXD1")
	)
	(segment
		(start 440.328812 -13.34008)
		(end 438.098692 -15.5702)
		(width 0.089408)
		(layer "In4.Cu")
		(net "RMII_SPRNGVLLE_BMC_PCH_RXD1")
	)
	(segment
		(start 497.48313 -40.080692)
		(end 497.48313 -39.281608)
		(width 0.089408)
		(layer "In4.Cu")
		(net "RMII_SPRNGVLLE_BMC_PCH_RXD1")
	)
	(segment
		(start 412.055056 -14.563344)
		(end 412.055056 -14.689836)
		(width 0.089408)
		(layer "In4.Cu")
		(net "RMII_SPRNGVLLE_BMC_PCH_RXD1")
	)
	(segment
		(start 496.287806 -38.672008)
		(end 496.198398 -38.5826)
		(width 0.089408)
		(layer "In4.Cu")
		(net "RMII_SPRNGVLLE_BMC_PCH_RXD1")
	)
	(segment
		(start 461.81518 -19.1897)
		(end 461.46466 -18.83918)
		(width 0.089408)
		(layer "In4.Cu")
		(net "RMII_SPRNGVLLE_BMC_PCH_RXD1")
	)
	(segment
		(start 420.9034 -14.1732)
		(end 413.539432 -14.1732)
		(width 0.089408)
		(layer "In4.Cu")
		(net "RMII_SPRNGVLLE_BMC_PCH_RXD1")
	)
	(segment
		(start 407.138632 -17.650714)
		(end 407.61539 -18.127472)
		(width 0.089408)
		(layer "In4.Cu")
		(net "RMII_SPRNGVLLE_BMC_PCH_RXD1")
	)
	(segment
		(start 407.561288 -17.228058)
		(end 407.434796 -17.228058)
		(width 0.089408)
		(layer "In4.Cu")
		(net "RMII_SPRNGVLLE_BMC_PCH_RXD1")
	)
	(segment
		(start 405.888698 -20.048728)
		(end 405.888698 -20.193)
		(width 0.089408)
		(layer "In4.Cu")
		(net "RMII_SPRNGVLLE_BMC_PCH_RXD1")
	)
	(segment
		(start 451.9422 -16.651732)
		(end 448.630548 -13.34008)
		(width 0.089408)
		(layer "In4.Cu")
		(net "RMII_SPRNGVLLE_BMC_PCH_RXD1")
	)
	(segment
		(start 407.138632 -17.524222)
		(end 407.138632 -17.650714)
		(width 0.089408)
		(layer "In4.Cu")
		(net "RMII_SPRNGVLLE_BMC_PCH_RXD1")
	)
	(segment
		(start 407.61539 -18.127472)
		(end 407.61539 -18.253964)
		(width 0.089408)
		(layer "In4.Cu")
		(net "RMII_SPRNGVLLE_BMC_PCH_RXD1")
	)
	(segment
		(start 374.79605 -27.585416)
		(end 376.908568 -25.472898)
		(width 0.089408)
		(layer "In4.Cu")
		(net "RMII_SPRNGVLLE_BMC_PCH_RXD1")
	)
	(segment
		(start 498.589046 -39.1922)
		(end 498.1702 -39.1922)
		(width 0.089408)
		(layer "In4.Cu")
		(net "RMII_SPRNGVLLE_BMC_PCH_RXD1")
	)
	(segment
		(start 410.372814 -15.686786)
		(end 410.372814 -15.813278)
		(width 0.089408)
		(layer "In4.Cu")
		(net "RMII_SPRNGVLLE_BMC_PCH_RXD1")
	)
	(segment
		(start 407.61539 -18.253964)
		(end 407.319226 -18.550128)
		(width 0.089408)
		(layer "In4.Cu")
		(net "RMII_SPRNGVLLE_BMC_PCH_RXD1")
	)
	(segment
		(start 402.897848 -20.251674)
		(end 403.249638 -20.603464)
		(width 0.089408)
		(layer "In4.Cu")
		(net "RMII_SPRNGVLLE_BMC_PCH_RXD1")
	)
	(segment
		(start 391.613644 -18.567908)
		(end 391.66292 -18.567908)
		(width 0.089408)
		(layer "In4.Cu")
		(net "RMII_SPRNGVLLE_BMC_PCH_RXD1")
	)
	(segment
		(start 493.9665 -40.1701)
		(end 493.5728 -40.5638)
		(width 0.089408)
		(layer "In4.Cu")
		(net "RMII_SPRNGVLLE_BMC_PCH_RXD1")
	)
	(segment
		(start 495.039142 -40.861996)
		(end 499.421404 -40.861996)
		(width 0.089408)
		(layer "In4.Cu")
		(net "RMII_SPRNGVLLE_BMC_PCH_RXD1")
	)
	(segment
		(start 493.31626 -41.4782)
		(end 493.405668 -41.567608)
		(width 0.089408)
		(layer "In4.Cu")
		(net "RMII_SPRNGVLLE_BMC_PCH_RXD1")
	)
	(segment
		(start 465.958174 -15.840202)
		(end 464.31073 -17.487646)
		(width 0.089408)
		(layer "In4.Cu")
		(net "RMII_SPRNGVLLE_BMC_PCH_RXD1")
	)
	(segment
		(start 497.393722 -39.1922)
		(end 496.974876 -39.1922)
		(width 0.089408)
		(layer "In4.Cu")
		(net "RMII_SPRNGVLLE_BMC_PCH_RXD1")
	)
	(segment
		(start 463.777838 -19.1897)
		(end 461.81518 -19.1897)
		(width 0.089408)
		(layer "In4.Cu")
		(net "RMII_SPRNGVLLE_BMC_PCH_RXD1")
	)
	(segment
		(start 376.908568 -25.472898)
		(end 376.908568 -23.85949)
		(width 0.089408)
		(layer "In4.Cu")
		(net "RMII_SPRNGVLLE_BMC_PCH_RXD1")
	)
	(segment
		(start 492.6584 -40.5638)
		(end 492.49965 -40.72255)
		(width 0.089408)
		(layer "In4.Cu")
		(net "RMII_SPRNGVLLE_BMC_PCH_RXD1")
	)
	(segment
		(start 498.1702 -39.1922)
		(end 498.080792 -39.281608)
		(width 0.089408)
		(layer "In4.Cu")
		(net "RMII_SPRNGVLLE_BMC_PCH_RXD1")
	)
	(segment
		(start 383.922016 -48.641)
		(end 384.561842 -49.280826)
		(width 0.089408)
		(layer "In11.Cu")
		(net "RMII_SPRNGVLLE_BMC_PCH_RXD1")
	)
	(segment
		(start 374.5992 -32.004)
		(end 374.5992 -34.310574)
		(width 0.089408)
		(layer "In11.Cu")
		(net "RMII_SPRNGVLLE_BMC_PCH_RXD1")
	)
	(segment
		(start 376.56643 -36.277804)
		(end 376.56643 -42.508424)
		(width 0.089408)
		(layer "In11.Cu")
		(net "RMII_SPRNGVLLE_BMC_PCH_RXD1")
	)
	(segment
		(start 394.758164 -80.033368)
		(end 394.758164 -81.936082)
		(width 0.089408)
		(layer "In11.Cu")
		(net "RMII_SPRNGVLLE_BMC_PCH_RXD1")
	)
	(segment
		(start 393.192 -83.502246)
		(end 393.192 -84.165694)
		(width 0.089408)
		(layer "In11.Cu")
		(net "RMII_SPRNGVLLE_BMC_PCH_RXD1")
	)
	(segment
		(start 393.422124 -78.697328)
		(end 394.758164 -80.033368)
		(width 0.089408)
		(layer "In11.Cu")
		(net "RMII_SPRNGVLLE_BMC_PCH_RXD1")
	)
	(segment
		(start 384.561842 -49.280826)
		(end 385.167378 -49.280826)
		(width 0.089408)
		(layer "In11.Cu")
		(net "RMII_SPRNGVLLE_BMC_PCH_RXD1")
	)
	(segment
		(start 374.5992 -34.310574)
		(end 376.56643 -36.277804)
		(width 0.089408)
		(layer "In11.Cu")
		(net "RMII_SPRNGVLLE_BMC_PCH_RXD1")
	)
	(segment
		(start 377.618498 -45.4914)
		(end 377.618498 -46.082458)
		(width 0.089408)
		(layer "In11.Cu")
		(net "RMII_SPRNGVLLE_BMC_PCH_RXD1")
	)
	(segment
		(start 393.954508 -71.091552)
		(end 393.954508 -73.192386)
		(width 0.089408)
		(layer "In11.Cu")
		(net "RMII_SPRNGVLLE_BMC_PCH_RXD1")
	)
	(segment
		(start 386.844032 -52.739798)
		(end 391.16254 -57.058306)
		(width 0.089408)
		(layer "In11.Cu")
		(net "RMII_SPRNGVLLE_BMC_PCH_RXD1")
	)
	(segment
		(start 381.667004 -47.91202)
		(end 382.395984 -48.641)
		(width 0.089408)
		(layer "In11.Cu")
		(net "RMII_SPRNGVLLE_BMC_PCH_RXD1")
	)
	(segment
		(start 377.618498 -46.082458)
		(end 379.44806 -47.91202)
		(width 0.089408)
		(layer "In11.Cu")
		(net "RMII_SPRNGVLLE_BMC_PCH_RXD1")
	)
	(segment
		(start 376.56643 -42.508424)
		(end 377.0884 -43.030394)
		(width 0.089408)
		(layer "In11.Cu")
		(net "RMII_SPRNGVLLE_BMC_PCH_RXD1")
	)
	(segment
		(start 386.844032 -50.974498)
		(end 386.844032 -52.739798)
		(width 0.089408)
		(layer "In11.Cu")
		(net "RMII_SPRNGVLLE_BMC_PCH_RXD1")
	)
	(segment
		(start 394.72235 -66.288158)
		(end 394.72235 -70.32371)
		(width 0.089408)
		(layer "In11.Cu")
		(net "RMII_SPRNGVLLE_BMC_PCH_RXD1")
	)
	(segment
		(start 386.843778 -50.957226)
		(end 386.843778 -50.974244)
		(width 0.089408)
		(layer "In11.Cu")
		(net "RMII_SPRNGVLLE_BMC_PCH_RXD1")
	)
	(segment
		(start 393.422124 -73.72477)
		(end 393.422124 -78.697328)
		(width 0.089408)
		(layer "In11.Cu")
		(net "RMII_SPRNGVLLE_BMC_PCH_RXD1")
	)
	(segment
		(start 390.886696 -61.207396)
		(end 390.886696 -62.452504)
		(width 0.089408)
		(layer "In11.Cu")
		(net "RMII_SPRNGVLLE_BMC_PCH_RXD1")
	)
	(segment
		(start 390.886696 -62.452504)
		(end 394.72235 -66.288158)
		(width 0.089408)
		(layer "In11.Cu")
		(net "RMII_SPRNGVLLE_BMC_PCH_RXD1")
	)
	(segment
		(start 374.015 -31.4198)
		(end 374.5992 -32.004)
		(width 0.089408)
		(layer "In11.Cu")
		(net "RMII_SPRNGVLLE_BMC_PCH_RXD1")
	)
	(segment
		(start 393.954508 -73.192386)
		(end 393.422124 -73.72477)
		(width 0.089408)
		(layer "In11.Cu")
		(net "RMII_SPRNGVLLE_BMC_PCH_RXD1")
	)
	(segment
		(start 377.0884 -44.961302)
		(end 377.618498 -45.4914)
		(width 0.089408)
		(layer "In11.Cu")
		(net "RMII_SPRNGVLLE_BMC_PCH_RXD1")
	)
	(segment
		(start 379.44806 -47.91202)
		(end 381.667004 -47.91202)
		(width 0.089408)
		(layer "In11.Cu")
		(net "RMII_SPRNGVLLE_BMC_PCH_RXD1")
	)
	(segment
		(start 386.843778 -50.974244)
		(end 386.844032 -50.974498)
		(width 0.089408)
		(layer "In11.Cu")
		(net "RMII_SPRNGVLLE_BMC_PCH_RXD1")
	)
	(segment
		(start 382.395984 -48.641)
		(end 383.922016 -48.641)
		(width 0.089408)
		(layer "In11.Cu")
		(net "RMII_SPRNGVLLE_BMC_PCH_RXD1")
	)
	(segment
		(start 377.0884 -43.030394)
		(end 377.0884 -44.961302)
		(width 0.089408)
		(layer "In11.Cu")
		(net "RMII_SPRNGVLLE_BMC_PCH_RXD1")
	)
	(segment
		(start 394.758164 -81.936082)
		(end 393.192 -83.502246)
		(width 0.089408)
		(layer "In11.Cu")
		(net "RMII_SPRNGVLLE_BMC_PCH_RXD1")
	)
	(segment
		(start 391.16254 -57.058306)
		(end 391.16254 -60.931552)
		(width 0.089408)
		(layer "In11.Cu")
		(net "RMII_SPRNGVLLE_BMC_PCH_RXD1")
	)
	(segment
		(start 394.72235 -70.32371)
		(end 393.954508 -71.091552)
		(width 0.089408)
		(layer "In11.Cu")
		(net "RMII_SPRNGVLLE_BMC_PCH_RXD1")
	)
	(segment
		(start 385.167378 -49.280826)
		(end 386.843778 -50.957226)
		(width 0.089408)
		(layer "In11.Cu")
		(net "RMII_SPRNGVLLE_BMC_PCH_RXD1")
	)
	(segment
		(start 391.16254 -60.931552)
		(end 390.886696 -61.207396)
		(width 0.089408)
		(layer "In11.Cu")
		(net "RMII_SPRNGVLLE_BMC_PCH_RXD1")
	)
	(segment
		(start 408.26563 -27.71013)
		(end 407.761948 -27.71013)
		(width 0.10795)
		(layer "F.Cu")
		(net "RMII_SPRNGVLLE_BMC_PCH_RXD0")
	)
	(segment
		(start 388.197598 -86.396322)
		(end 388.197598 -86.826598)
		(width 0.10795)
		(layer "F.Cu")
		(net "RMII_SPRNGVLLE_BMC_PCH_RXD0")
	)
	(segment
		(start 388.197598 -86.826598)
		(end 388.366 -86.995)
		(width 0.10795)
		(layer "F.Cu")
		(net "RMII_SPRNGVLLE_BMC_PCH_RXD0")
	)
	(segment
		(start 392.068812 -83.5533)
		(end 391.109708 -84.512404)
		(width 0.10795)
		(layer "F.Cu")
		(net "RMII_SPRNGVLLE_BMC_PCH_RXD0")
	)
	(segment
		(start 407.504646 -27.474672)
		(end 407.504646 -27.22372)
		(width 0.10795)
		(layer "F.Cu")
		(net "RMII_SPRNGVLLE_BMC_PCH_RXD0")
	)
	(segment
		(start 407.504646 -27.22372)
		(end 407.230326 -26.9494)
		(width 0.10795)
		(layer "F.Cu")
		(net "RMII_SPRNGVLLE_BMC_PCH_RXD0")
	)
	(segment
		(start 393.198096 -81.82483)
		(end 392.7348 -82.288126)
		(width 0.10795)
		(layer "F.Cu")
		(net "RMII_SPRNGVLLE_BMC_PCH_RXD0")
	)
	(segment
		(start 388.453376 -86.140544)
		(end 388.197598 -86.396322)
		(width 0.10795)
		(layer "F.Cu")
		(net "RMII_SPRNGVLLE_BMC_PCH_RXD0")
	)
	(segment
		(start 407.761948 -27.71013)
		(end 407.758138 -27.70632)
		(width 0.10795)
		(layer "F.Cu")
		(net "RMII_SPRNGVLLE_BMC_PCH_RXD0")
	)
	(segment
		(start 392.7348 -83.1596)
		(end 392.3411 -83.5533)
		(width 0.10795)
		(layer "F.Cu")
		(net "RMII_SPRNGVLLE_BMC_PCH_RXD0")
	)
	(segment
		(start 407.230326 -26.9494)
		(end 406.123902 -26.9494)
		(width 0.10795)
		(layer "F.Cu")
		(net "RMII_SPRNGVLLE_BMC_PCH_RXD0")
	)
	(segment
		(start 406.123902 -26.9494)
		(end 405.858218 -26.683716)
		(width 0.10795)
		(layer "F.Cu")
		(net "RMII_SPRNGVLLE_BMC_PCH_RXD0")
	)
	(segment
		(start 406.107646 -23.601172)
		(end 406.107646 -23.060152)
		(width 0.10795)
		(layer "F.Cu")
		(net "RMII_SPRNGVLLE_BMC_PCH_RXD0")
	)
	(segment
		(start 492.72698 -43.0784)
		(end 492.82096 -43.17238)
		(width 0.10795)
		(layer "F.Cu")
		(net "RMII_SPRNGVLLE_BMC_PCH_RXD0")
	)
	(segment
		(start 407.736294 -27.70632)
		(end 407.504646 -27.474672)
		(width 0.10795)
		(layer "F.Cu")
		(net "RMII_SPRNGVLLE_BMC_PCH_RXD0")
	)
	(segment
		(start 392.7348 -82.288126)
		(end 392.7348 -83.1596)
		(width 0.10795)
		(layer "F.Cu")
		(net "RMII_SPRNGVLLE_BMC_PCH_RXD0")
	)
	(segment
		(start 390.721596 -84.512404)
		(end 389.093456 -86.140544)
		(width 0.10795)
		(layer "F.Cu")
		(net "RMII_SPRNGVLLE_BMC_PCH_RXD0")
	)
	(segment
		(start 407.758138 -27.70632)
		(end 407.736294 -27.70632)
		(width 0.10795)
		(layer "F.Cu")
		(net "RMII_SPRNGVLLE_BMC_PCH_RXD0")
	)
	(segment
		(start 388.366 -86.995)
		(end 388.366 -87.3125)
		(width 0.10795)
		(layer "F.Cu")
		(net "RMII_SPRNGVLLE_BMC_PCH_RXD0")
	)
	(segment
		(start 405.858218 -26.683716)
		(end 405.858218 -23.8506)
		(width 0.10795)
		(layer "F.Cu")
		(net "RMII_SPRNGVLLE_BMC_PCH_RXD0")
	)
	(segment
		(start 392.3411 -83.5533)
		(end 392.068812 -83.5533)
		(width 0.10795)
		(layer "F.Cu")
		(net "RMII_SPRNGVLLE_BMC_PCH_RXD0")
	)
	(segment
		(start 391.109708 -84.512404)
		(end 390.721596 -84.512404)
		(width 0.10795)
		(layer "F.Cu")
		(net "RMII_SPRNGVLLE_BMC_PCH_RXD0")
	)
	(segment
		(start 408.690064 -28.134564)
		(end 408.26563 -27.71013)
		(width 0.10795)
		(layer "F.Cu")
		(net "RMII_SPRNGVLLE_BMC_PCH_RXD0")
	)
	(segment
		(start 405.858218 -23.8506)
		(end 406.107646 -23.601172)
		(width 0.10795)
		(layer "F.Cu")
		(net "RMII_SPRNGVLLE_BMC_PCH_RXD0")
	)
	(segment
		(start 389.093456 -86.140544)
		(end 388.453376 -86.140544)
		(width 0.10795)
		(layer "F.Cu")
		(net "RMII_SPRNGVLLE_BMC_PCH_RXD0")
	)
	(segment
		(start 491.9345 -43.0784)
		(end 492.72698 -43.0784)
		(width 0.10795)
		(layer "F.Cu")
		(net "RMII_SPRNGVLLE_BMC_PCH_RXD0")
	)
	(via
		(at 393.198096 -81.82483)
		(size 0.508)
		(drill 0.254)
		(layers "F.Cu" "B.Cu")
		(net "RMII_SPRNGVLLE_BMC_PCH_RXD0")
	)
	(via
		(at 405.858218 -23.8506)
		(size 0.508)
		(drill 0.254)
		(layers "F.Cu" "B.Cu")
		(net "RMII_SPRNGVLLE_BMC_PCH_RXD0")
	)
	(via
		(at 374.1928 -30.0482)
		(size 0.508)
		(drill 0.254)
		(layers "F.Cu" "B.Cu")
		(net "RMII_SPRNGVLLE_BMC_PCH_RXD0")
	)
	(via
		(at 492.82096 -43.17238)
		(size 0.508)
		(drill 0.254)
		(layers "F.Cu" "B.Cu")
		(net "RMII_SPRNGVLLE_BMC_PCH_RXD0")
	)
	(segment
		(start 488.814872 -39.10965)
		(end 490.276896 -39.10965)
		(width 0.089408)
		(layer "In4.Cu")
		(net "RMII_SPRNGVLLE_BMC_PCH_RXD0")
	)
	(segment
		(start 475.201234 -23.58898)
		(end 475.327726 -23.58898)
		(width 0.089408)
		(layer "In4.Cu")
		(net "RMII_SPRNGVLLE_BMC_PCH_RXD0")
	)
	(segment
		(start 475.327726 -23.58898)
		(end 475.81058 -23.106126)
		(width 0.089408)
		(layer "In4.Cu")
		(net "RMII_SPRNGVLLE_BMC_PCH_RXD0")
	)
	(segment
		(start 453.558402 -19.177)
		(end 455.961242 -19.177)
		(width 0.089408)
		(layer "In4.Cu")
		(net "RMII_SPRNGVLLE_BMC_PCH_RXD0")
	)
	(segment
		(start 460.234284 -19.266408)
		(end 460.323692 -19.177)
		(width 0.089408)
		(layer "In4.Cu")
		(net "RMII_SPRNGVLLE_BMC_PCH_RXD0")
	)
	(segment
		(start 457.843636 -19.266408)
		(end 457.933044 -19.177)
		(width 0.089408)
		(layer "In4.Cu")
		(net "RMII_SPRNGVLLE_BMC_PCH_RXD0")
	)
	(segment
		(start 377.72086 -23.94712)
		(end 382.489456 -19.178524)
		(width 0.089408)
		(layer "In4.Cu")
		(net "RMII_SPRNGVLLE_BMC_PCH_RXD0")
	)
	(segment
		(start 407.7462 -19.560032)
		(end 407.32583 -19.139662)
		(width 0.089408)
		(layer "In4.Cu")
		(net "RMII_SPRNGVLLE_BMC_PCH_RXD0")
	)
	(segment
		(start 457.933044 -19.177)
		(end 458.35189 -19.177)
		(width 0.089408)
		(layer "In4.Cu")
		(net "RMII_SPRNGVLLE_BMC_PCH_RXD0")
	)
	(segment
		(start 476.233236 -23.528782)
		(end 475.750382 -24.011636)
		(width 0.089408)
		(layer "In4.Cu")
		(net "RMII_SPRNGVLLE_BMC_PCH_RXD0")
	)
	(segment
		(start 459.03896 -19.266408)
		(end 459.128368 -19.177)
		(width 0.089408)
		(layer "In4.Cu")
		(net "RMII_SPRNGVLLE_BMC_PCH_RXD0")
	)
	(segment
		(start 440.581034 -13.716)
		(end 448.429634 -13.716)
		(width 0.089408)
		(layer "In4.Cu")
		(net "RMII_SPRNGVLLE_BMC_PCH_RXD0")
	)
	(segment
		(start 456.648312 -19.266408)
		(end 456.73772 -19.177)
		(width 0.089408)
		(layer "In4.Cu")
		(net "RMII_SPRNGVLLE_BMC_PCH_RXD0")
	)
	(segment
		(start 483.87 -35.179)
		(end 484.4796 -35.7886)
		(width 0.089408)
		(layer "In4.Cu")
		(net "RMII_SPRNGVLLE_BMC_PCH_RXD0")
	)
	(segment
		(start 391.324338 -19.178524)
		(end 392.3284 -20.182586)
		(width 0.089408)
		(layer "In4.Cu")
		(net "RMII_SPRNGVLLE_BMC_PCH_RXD0")
	)
	(segment
		(start 405.637746 -23.8506)
		(end 405.858218 -23.8506)
		(width 0.089408)
		(layer "In4.Cu")
		(net "RMII_SPRNGVLLE_BMC_PCH_RXD0")
	)
	(segment
		(start 475.937072 -23.106126)
		(end 476.233236 -23.40229)
		(width 0.089408)
		(layer "In4.Cu")
		(net "RMII_SPRNGVLLE_BMC_PCH_RXD0")
	)
	(segment
		(start 479.66122 -24.32558)
		(end 480.7077 -25.37206)
		(width 0.089408)
		(layer "In4.Cu")
		(net "RMII_SPRNGVLLE_BMC_PCH_RXD0")
	)
	(segment
		(start 413.7914 -14.5415)
		(end 420.2557 -14.5415)
		(width 0.089408)
		(layer "In4.Cu")
		(net "RMII_SPRNGVLLE_BMC_PCH_RXD0")
	)
	(segment
		(start 392.3284 -21.5138)
		(end 392.6078 -21.7932)
		(width 0.089408)
		(layer "In4.Cu")
		(net "RMII_SPRNGVLLE_BMC_PCH_RXD0")
	)
	(segment
		(start 405.858218 -23.8506)
		(end 405.858218 -23.074884)
		(width 0.089408)
		(layer "In4.Cu")
		(net "RMII_SPRNGVLLE_BMC_PCH_RXD0")
	)
	(segment
		(start 405.262334 -22.479)
		(end 403.001988 -22.479)
		(width 0.089408)
		(layer "In4.Cu")
		(net "RMII_SPRNGVLLE_BMC_PCH_RXD0")
	)
	(segment
		(start 451.5358 -17.154398)
		(end 453.558402 -19.177)
		(width 0.089408)
		(layer "In4.Cu")
		(net "RMII_SPRNGVLLE_BMC_PCH_RXD0")
	)
	(segment
		(start 374.6754 -28.943046)
		(end 377.72086 -25.897586)
		(width 0.089408)
		(layer "In4.Cu")
		(net "RMII_SPRNGVLLE_BMC_PCH_RXD0")
	)
	(segment
		(start 457.843636 -19.493992)
		(end 457.843636 -19.266408)
		(width 0.089408)
		(layer "In4.Cu")
		(net "RMII_SPRNGVLLE_BMC_PCH_RXD0")
	)
	(segment
		(start 457.754228 -19.5834)
		(end 457.843636 -19.493992)
		(width 0.089408)
		(layer "In4.Cu")
		(net "RMII_SPRNGVLLE_BMC_PCH_RXD0")
	)
	(segment
		(start 460.673196 -19.177)
		(end 462.334102 -20.837906)
		(width 0.089408)
		(layer "In4.Cu")
		(net "RMII_SPRNGVLLE_BMC_PCH_RXD0")
	)
	(segment
		(start 411.0355 -17.2974)
		(end 411.1625 -17.1704)
		(width 0.089408)
		(layer "In4.Cu")
		(net "RMII_SPRNGVLLE_BMC_PCH_RXD0")
	)
	(segment
		(start 480.7077 -31.882588)
		(end 482.636576 -33.811464)
		(width 0.089408)
		(layer "In4.Cu")
		(net "RMII_SPRNGVLLE_BMC_PCH_RXD0")
	)
	(segment
		(start 414.516316 -15.507208)
		(end 414.516316 -15.380716)
		(width 0.089408)
		(layer "In4.Cu")
		(net "RMII_SPRNGVLLE_BMC_PCH_RXD0")
	)
	(segment
		(start 460.144876 -19.5834)
		(end 460.234284 -19.493992)
		(width 0.089408)
		(layer "In4.Cu")
		(net "RMII_SPRNGVLLE_BMC_PCH_RXD0")
	)
	(segment
		(start 456.05065 -19.493992)
		(end 456.140058 -19.5834)
		(width 0.089408)
		(layer "In4.Cu")
		(net "RMII_SPRNGVLLE_BMC_PCH_RXD0")
	)
	(segment
		(start 492.1504 -42.1132)
		(end 492.1504 -42.50182)
		(width 0.089408)
		(layer "In4.Cu")
		(net "RMII_SPRNGVLLE_BMC_PCH_RXD0")
	)
	(segment
		(start 474.90507 -23.166324)
		(end 474.90507 -23.292816)
		(width 0.089408)
		(layer "In4.Cu")
		(net "RMII_SPRNGVLLE_BMC_PCH_RXD0")
	)
	(segment
		(start 475.750382 -24.011636)
		(end 475.750382 -24.138128)
		(width 0.089408)
		(layer "In4.Cu")
		(net "RMII_SPRNGVLLE_BMC_PCH_RXD0")
	)
	(segment
		(start 406.905968 -20.601432)
		(end 407.7462 -19.7612)
		(width 0.089408)
		(layer "In4.Cu")
		(net "RMII_SPRNGVLLE_BMC_PCH_RXD0")
	)
	(segment
		(start 482.636576 -34.89833)
		(end 482.917246 -35.179)
		(width 0.089408)
		(layer "In4.Cu")
		(net "RMII_SPRNGVLLE_BMC_PCH_RXD0")
	)
	(segment
		(start 459.03896 -19.493992)
		(end 459.03896 -19.266408)
		(width 0.089408)
		(layer "In4.Cu")
		(net "RMII_SPRNGVLLE_BMC_PCH_RXD0")
	)
	(segment
		(start 457.335382 -19.5834)
		(end 457.754228 -19.5834)
		(width 0.089408)
		(layer "In4.Cu")
		(net "RMII_SPRNGVLLE_BMC_PCH_RXD0")
	)
	(segment
		(start 484.4796 -35.7886)
		(end 484.4796 -36.510976)
		(width 0.089408)
		(layer "In4.Cu")
		(net "RMII_SPRNGVLLE_BMC_PCH_RXD0")
	)
	(segment
		(start 421.64 -15.9258)
		(end 438.371234 -15.9258)
		(width 0.089408)
		(layer "In4.Cu")
		(net "RMII_SPRNGVLLE_BMC_PCH_RXD0")
	)
	(segment
		(start 487.148632 -38.152832)
		(end 487.457496 -38.461696)
		(width 0.089408)
		(layer "In4.Cu")
		(net "RMII_SPRNGVLLE_BMC_PCH_RXD0")
	)
	(segment
		(start 392.3284 -20.182586)
		(end 392.3284 -21.5138)
		(width 0.089408)
		(layer "In4.Cu")
		(net "RMII_SPRNGVLLE_BMC_PCH_RXD0")
	)
	(segment
		(start 459.547214 -19.177)
		(end 459.636622 -19.266408)
		(width 0.089408)
		(layer "In4.Cu")
		(net "RMII_SPRNGVLLE_BMC_PCH_RXD0")
	)
	(segment
		(start 451.5358 -16.822166)
		(end 451.5358 -17.154398)
		(width 0.089408)
		(layer "In4.Cu")
		(net "RMII_SPRNGVLLE_BMC_PCH_RXD0")
	)
	(segment
		(start 408.584146 -17.78)
		(end 409.066746 -17.2974)
		(width 0.089408)
		(layer "In4.Cu")
		(net "RMII_SPRNGVLLE_BMC_PCH_RXD0")
	)
	(segment
		(start 457.245974 -19.266408)
		(end 457.245974 -19.493992)
		(width 0.089408)
		(layer "In4.Cu")
		(net "RMII_SPRNGVLLE_BMC_PCH_RXD0")
	)
	(segment
		(start 412.32836 -16.72336)
		(end 412.032196 -16.427196)
		(width 0.089408)
		(layer "In4.Cu")
		(net "RMII_SPRNGVLLE_BMC_PCH_RXD0")
	)
	(segment
		(start 476.655892 -23.951438)
		(end 476.782384 -23.951438)
		(width 0.089408)
		(layer "In4.Cu")
		(net "RMII_SPRNGVLLE_BMC_PCH_RXD0")
	)
	(segment
		(start 476.046546 -24.434292)
		(end 476.173038 -24.434292)
		(width 0.089408)
		(layer "In4.Cu")
		(net "RMII_SPRNGVLLE_BMC_PCH_RXD0")
	)
	(segment
		(start 403.001988 -22.479)
		(end 402.640038 -22.11705)
		(width 0.089408)
		(layer "In4.Cu")
		(net "RMII_SPRNGVLLE_BMC_PCH_RXD0")
	)
	(segment
		(start 475.81058 -23.106126)
		(end 475.937072 -23.106126)
		(width 0.089408)
		(layer "In4.Cu")
		(net "RMII_SPRNGVLLE_BMC_PCH_RXD0")
	)
	(segment
		(start 404.882604 -23.095458)
		(end 405.637746 -23.8506)
		(width 0.089408)
		(layer "In4.Cu")
		(net "RMII_SPRNGVLLE_BMC_PCH_RXD0")
	)
	(segment
		(start 411.1625 -17.1704)
		(end 412.853124 -17.1704)
		(width 0.089408)
		(layer "In4.Cu")
		(net "RMII_SPRNGVLLE_BMC_PCH_RXD0")
	)
	(segment
		(start 405.610568 -20.601432)
		(end 406.905968 -20.601432)
		(width 0.089408)
		(layer "In4.Cu")
		(net "RMII_SPRNGVLLE_BMC_PCH_RXD0")
	)
	(segment
		(start 392.6078 -21.7932)
		(end 394.64742 -21.7932)
		(width 0.089408)
		(layer "In4.Cu")
		(net "RMII_SPRNGVLLE_BMC_PCH_RXD0")
	)
	(segment
		(start 420.2557 -14.5415)
		(end 421.64 -15.9258)
		(width 0.089408)
		(layer "In4.Cu")
		(net "RMII_SPRNGVLLE_BMC_PCH_RXD0")
	)
	(segment
		(start 407.32583 -19.01317)
		(end 407.621994 -18.717006)
		(width 0.089408)
		(layer "In4.Cu")
		(net "RMII_SPRNGVLLE_BMC_PCH_RXD0")
	)
	(segment
		(start 490.276896 -39.10965)
		(end 490.6518 -39.484554)
		(width 0.089408)
		(layer "In4.Cu")
		(net "RMII_SPRNGVLLE_BMC_PCH_RXD0")
	)
	(segment
		(start 464.688174 -19.438112)
		(end 464.688174 -17.674082)
		(width 0.089408)
		(layer "In4.Cu")
		(net "RMII_SPRNGVLLE_BMC_PCH_RXD0")
	)
	(segment
		(start 438.371234 -15.9258)
		(end 440.581034 -13.716)
		(width 0.089408)
		(layer "In4.Cu")
		(net "RMII_SPRNGVLLE_BMC_PCH_RXD0")
	)
	(segment
		(start 405.1935 -21.0185)
		(end 405.610568 -20.601432)
		(width 0.089408)
		(layer "In4.Cu")
		(net "RMII_SPRNGVLLE_BMC_PCH_RXD0")
	)
	(segment
		(start 457.245974 -19.493992)
		(end 457.335382 -19.5834)
		(width 0.089408)
		(layer "In4.Cu")
		(net "RMII_SPRNGVLLE_BMC_PCH_RXD0")
	)
	(segment
		(start 476.173038 -24.434292)
		(end 476.655892 -23.951438)
		(width 0.089408)
		(layer "In4.Cu")
		(net "RMII_SPRNGVLLE_BMC_PCH_RXD0")
	)
	(segment
		(start 407.7462 -19.7612)
		(end 407.7462 -19.560032)
		(width 0.089408)
		(layer "In4.Cu")
		(net "RMII_SPRNGVLLE_BMC_PCH_RXD0")
	)
	(segment
		(start 448.429634 -13.716)
		(end 451.5358 -16.822166)
		(width 0.089408)
		(layer "In4.Cu")
		(net "RMII_SPRNGVLLE_BMC_PCH_RXD0")
	)
	(segment
		(start 405.858218 -23.074884)
		(end 405.262334 -22.479)
		(width 0.089408)
		(layer "In4.Cu")
		(net "RMII_SPRNGVLLE_BMC_PCH_RXD0")
	)
	(segment
		(start 409.072842 -18.344642)
		(end 408.584146 -17.855946)
		(width 0.089408)
		(layer "In4.Cu")
		(net "RMII_SPRNGVLLE_BMC_PCH_RXD0")
	)
	(segment
		(start 456.73772 -19.177)
		(end 457.156566 -19.177)
		(width 0.089408)
		(layer "In4.Cu")
		(net "RMII_SPRNGVLLE_BMC_PCH_RXD0")
	)
	(segment
		(start 475.387924 -22.556978)
		(end 475.387924 -22.68347)
		(width 0.089408)
		(layer "In4.Cu")
		(net "RMII_SPRNGVLLE_BMC_PCH_RXD0")
	)
	(segment
		(start 459.636622 -19.266408)
		(end 459.636622 -19.493992)
		(width 0.089408)
		(layer "In4.Cu")
		(net "RMII_SPRNGVLLE_BMC_PCH_RXD0")
	)
	(segment
		(start 456.140058 -19.5834)
		(end 456.558904 -19.5834)
		(width 0.089408)
		(layer "In4.Cu")
		(net "RMII_SPRNGVLLE_BMC_PCH_RXD0")
	)
	(segment
		(start 464.688174 -17.674082)
		(end 466.096858 -16.265398)
		(width 0.089408)
		(layer "In4.Cu")
		(net "RMII_SPRNGVLLE_BMC_PCH_RXD0")
	)
	(segment
		(start 457.156566 -19.177)
		(end 457.245974 -19.266408)
		(width 0.089408)
		(layer "In4.Cu")
		(net "RMII_SPRNGVLLE_BMC_PCH_RXD0")
	)
	(segment
		(start 402.165058 -23.095458)
		(end 404.882604 -23.095458)
		(width 0.089408)
		(layer "In4.Cu")
		(net "RMII_SPRNGVLLE_BMC_PCH_RXD0")
	)
	(segment
		(start 408.269694 -19.238214)
		(end 408.396186 -19.238214)
		(width 0.089408)
		(layer "In4.Cu")
		(net "RMII_SPRNGVLLE_BMC_PCH_RXD0")
	)
	(segment
		(start 407.621994 -18.717006)
		(end 407.748486 -18.717006)
		(width 0.089408)
		(layer "In4.Cu")
		(net "RMII_SPRNGVLLE_BMC_PCH_RXD0")
	)
	(segment
		(start 462.334102 -20.837906)
		(end 463.28838 -20.837906)
		(width 0.089408)
		(layer "In4.Cu")
		(net "RMII_SPRNGVLLE_BMC_PCH_RXD0")
	)
	(segment
		(start 480.7077 -25.37206)
		(end 480.7077 -31.882588)
		(width 0.089408)
		(layer "In4.Cu")
		(net "RMII_SPRNGVLLE_BMC_PCH_RXD0")
	)
	(segment
		(start 492.1504 -42.50182)
		(end 492.82096 -43.17238)
		(width 0.089408)
		(layer "In4.Cu")
		(net "RMII_SPRNGVLLE_BMC_PCH_RXD0")
	)
	(segment
		(start 475.750382 -24.138128)
		(end 476.046546 -24.434292)
		(width 0.089408)
		(layer "In4.Cu")
		(net "RMII_SPRNGVLLE_BMC_PCH_RXD0")
	)
	(segment
		(start 412.454852 -16.72336)
		(end 412.32836 -16.72336)
		(width 0.089408)
		(layer "In4.Cu")
		(net "RMII_SPRNGVLLE_BMC_PCH_RXD0")
	)
	(segment
		(start 456.558904 -19.5834)
		(end 456.648312 -19.493992)
		(width 0.089408)
		(layer "In4.Cu")
		(net "RMII_SPRNGVLLE_BMC_PCH_RXD0")
	)
	(segment
		(start 486.41 -36.7538)
		(end 487.148632 -37.492432)
		(width 0.089408)
		(layer "In4.Cu")
		(net "RMII_SPRNGVLLE_BMC_PCH_RXD0")
	)
	(segment
		(start 456.05065 -19.266408)
		(end 456.05065 -19.493992)
		(width 0.089408)
		(layer "In4.Cu")
		(net "RMII_SPRNGVLLE_BMC_PCH_RXD0")
	)
	(segment
		(start 476.233236 -23.40229)
		(end 476.233236 -23.528782)
		(width 0.089408)
		(layer "In4.Cu")
		(net "RMII_SPRNGVLLE_BMC_PCH_RXD0")
	)
	(segment
		(start 482.636576 -33.811464)
		(end 482.636576 -34.89833)
		(width 0.089408)
		(layer "In4.Cu")
		(net "RMII_SPRNGVLLE_BMC_PCH_RXD0")
	)
	(segment
		(start 476.782384 -23.951438)
		(end 477.156526 -24.32558)
		(width 0.089408)
		(layer "In4.Cu")
		(net "RMII_SPRNGVLLE_BMC_PCH_RXD0")
	)
	(segment
		(start 475.098872 -19.634962)
		(end 475.098872 -22.267926)
		(width 0.089408)
		(layer "In4.Cu")
		(net "RMII_SPRNGVLLE_BMC_PCH_RXD0")
	)
	(segment
		(start 482.917246 -35.179)
		(end 483.87 -35.179)
		(width 0.089408)
		(layer "In4.Cu")
		(net "RMII_SPRNGVLLE_BMC_PCH_RXD0")
	)
	(segment
		(start 402.640038 -21.248116)
		(end 402.869654 -21.0185)
		(width 0.089408)
		(layer "In4.Cu")
		(net "RMII_SPRNGVLLE_BMC_PCH_RXD0")
	)
	(segment
		(start 401.1676 -20.98294)
		(end 401.1676 -22.098)
		(width 0.089408)
		(layer "In4.Cu")
		(net "RMII_SPRNGVLLE_BMC_PCH_RXD0")
	)
	(segment
		(start 458.530706 -19.5834)
		(end 458.949552 -19.5834)
		(width 0.089408)
		(layer "In4.Cu")
		(net "RMII_SPRNGVLLE_BMC_PCH_RXD0")
	)
	(segment
		(start 484.722424 -36.7538)
		(end 486.41 -36.7538)
		(width 0.089408)
		(layer "In4.Cu")
		(net "RMII_SPRNGVLLE_BMC_PCH_RXD0")
	)
	(segment
		(start 374.1928 -30.0482)
		(end 374.6754 -29.5656)
		(width 0.089408)
		(layer "In4.Cu")
		(net "RMII_SPRNGVLLE_BMC_PCH_RXD0")
	)
	(segment
		(start 455.961242 -19.177)
		(end 456.05065 -19.266408)
		(width 0.089408)
		(layer "In4.Cu")
		(net "RMII_SPRNGVLLE_BMC_PCH_RXD0")
	)
	(segment
		(start 458.949552 -19.5834)
		(end 459.03896 -19.493992)
		(width 0.089408)
		(layer "In4.Cu")
		(net "RMII_SPRNGVLLE_BMC_PCH_RXD0")
	)
	(segment
		(start 475.098872 -22.267926)
		(end 475.387924 -22.556978)
		(width 0.089408)
		(layer "In4.Cu")
		(net "RMII_SPRNGVLLE_BMC_PCH_RXD0")
	)
	(segment
		(start 477.156526 -24.32558)
		(end 479.66122 -24.32558)
		(width 0.089408)
		(layer "In4.Cu")
		(net "RMII_SPRNGVLLE_BMC_PCH_RXD0")
	)
	(segment
		(start 402.640038 -22.11705)
		(end 402.640038 -21.248116)
		(width 0.089408)
		(layer "In4.Cu")
		(net "RMII_SPRNGVLLE_BMC_PCH_RXD0")
	)
	(segment
		(start 466.096858 -16.265398)
		(end 471.729308 -16.265398)
		(width 0.089408)
		(layer "In4.Cu")
		(net "RMII_SPRNGVLLE_BMC_PCH_RXD0")
	)
	(segment
		(start 412.032196 -16.427196)
		(end 412.032196 -16.300704)
		(width 0.089408)
		(layer "In4.Cu")
		(net "RMII_SPRNGVLLE_BMC_PCH_RXD0")
	)
	(segment
		(start 412.853124 -17.1704)
		(end 414.516316 -15.507208)
		(width 0.089408)
		(layer "In4.Cu")
		(net "RMII_SPRNGVLLE_BMC_PCH_RXD0")
	)
	(segment
		(start 395.997938 -20.442682)
		(end 400.627342 -20.442682)
		(width 0.089408)
		(layer "In4.Cu")
		(net "RMII_SPRNGVLLE_BMC_PCH_RXD0")
	)
	(segment
		(start 408.584146 -17.855946)
		(end 408.584146 -17.78)
		(width 0.089408)
		(layer "In4.Cu")
		(net "RMII_SPRNGVLLE_BMC_PCH_RXD0")
	)
	(segment
		(start 474.90507 -23.292816)
		(end 475.201234 -23.58898)
		(width 0.089408)
		(layer "In4.Cu")
		(net "RMII_SPRNGVLLE_BMC_PCH_RXD0")
	)
	(segment
		(start 409.072842 -18.561558)
		(end 409.072842 -18.344642)
		(width 0.089408)
		(layer "In4.Cu")
		(net "RMII_SPRNGVLLE_BMC_PCH_RXD0")
	)
	(segment
		(start 459.128368 -19.177)
		(end 459.547214 -19.177)
		(width 0.089408)
		(layer "In4.Cu")
		(net "RMII_SPRNGVLLE_BMC_PCH_RXD0")
	)
	(segment
		(start 490.6518 -39.484554)
		(end 490.6518 -40.6146)
		(width 0.089408)
		(layer "In4.Cu")
		(net "RMII_SPRNGVLLE_BMC_PCH_RXD0")
	)
	(segment
		(start 407.32583 -19.139662)
		(end 407.32583 -19.01317)
		(width 0.089408)
		(layer "In4.Cu")
		(net "RMII_SPRNGVLLE_BMC_PCH_RXD0")
	)
	(segment
		(start 414.09366 -15.084552)
		(end 412.454852 -16.72336)
		(width 0.089408)
		(layer "In4.Cu")
		(net "RMII_SPRNGVLLE_BMC_PCH_RXD0")
	)
	(segment
		(start 408.396186 -19.238214)
		(end 409.072842 -18.561558)
		(width 0.089408)
		(layer "In4.Cu")
		(net "RMII_SPRNGVLLE_BMC_PCH_RXD0")
	)
	(segment
		(start 400.627342 -20.442682)
		(end 401.1676 -20.98294)
		(width 0.089408)
		(layer "In4.Cu")
		(net "RMII_SPRNGVLLE_BMC_PCH_RXD0")
	)
	(segment
		(start 401.1676 -22.098)
		(end 402.165058 -23.095458)
		(width 0.089408)
		(layer "In4.Cu")
		(net "RMII_SPRNGVLLE_BMC_PCH_RXD0")
	)
	(segment
		(start 460.323692 -19.177)
		(end 460.673196 -19.177)
		(width 0.089408)
		(layer "In4.Cu")
		(net "RMII_SPRNGVLLE_BMC_PCH_RXD0")
	)
	(segment
		(start 407.748486 -18.717006)
		(end 408.269694 -19.238214)
		(width 0.089408)
		(layer "In4.Cu")
		(net "RMII_SPRNGVLLE_BMC_PCH_RXD0")
	)
	(segment
		(start 488.166918 -38.461696)
		(end 488.814872 -39.10965)
		(width 0.089408)
		(layer "In4.Cu")
		(net "RMII_SPRNGVLLE_BMC_PCH_RXD0")
	)
	(segment
		(start 414.220152 -15.084552)
		(end 414.09366 -15.084552)
		(width 0.089408)
		(layer "In4.Cu")
		(net "RMII_SPRNGVLLE_BMC_PCH_RXD0")
	)
	(segment
		(start 456.648312 -19.493992)
		(end 456.648312 -19.266408)
		(width 0.089408)
		(layer "In4.Cu")
		(net "RMII_SPRNGVLLE_BMC_PCH_RXD0")
	)
	(segment
		(start 458.441298 -19.266408)
		(end 458.441298 -19.493992)
		(width 0.089408)
		(layer "In4.Cu")
		(net "RMII_SPRNGVLLE_BMC_PCH_RXD0")
	)
	(segment
		(start 460.234284 -19.493992)
		(end 460.234284 -19.266408)
		(width 0.089408)
		(layer "In4.Cu")
		(net "RMII_SPRNGVLLE_BMC_PCH_RXD0")
	)
	(segment
		(start 487.457496 -38.461696)
		(end 488.166918 -38.461696)
		(width 0.089408)
		(layer "In4.Cu")
		(net "RMII_SPRNGVLLE_BMC_PCH_RXD0")
	)
	(segment
		(start 414.516316 -15.380716)
		(end 414.220152 -15.084552)
		(width 0.089408)
		(layer "In4.Cu")
		(net "RMII_SPRNGVLLE_BMC_PCH_RXD0")
	)
	(segment
		(start 374.6754 -29.5656)
		(end 374.6754 -28.943046)
		(width 0.089408)
		(layer "In4.Cu")
		(net "RMII_SPRNGVLLE_BMC_PCH_RXD0")
	)
	(segment
		(start 458.441298 -19.493992)
		(end 458.530706 -19.5834)
		(width 0.089408)
		(layer "In4.Cu")
		(net "RMII_SPRNGVLLE_BMC_PCH_RXD0")
	)
	(segment
		(start 412.032196 -16.300704)
		(end 413.7914 -14.5415)
		(width 0.089408)
		(layer "In4.Cu")
		(net "RMII_SPRNGVLLE_BMC_PCH_RXD0")
	)
	(segment
		(start 394.64742 -21.7932)
		(end 395.997938 -20.442682)
		(width 0.089408)
		(layer "In4.Cu")
		(net "RMII_SPRNGVLLE_BMC_PCH_RXD0")
	)
	(segment
		(start 475.387924 -22.68347)
		(end 474.90507 -23.166324)
		(width 0.089408)
		(layer "In4.Cu")
		(net "RMII_SPRNGVLLE_BMC_PCH_RXD0")
	)
	(segment
		(start 459.636622 -19.493992)
		(end 459.72603 -19.5834)
		(width 0.089408)
		(layer "In4.Cu")
		(net "RMII_SPRNGVLLE_BMC_PCH_RXD0")
	)
	(segment
		(start 459.72603 -19.5834)
		(end 460.144876 -19.5834)
		(width 0.089408)
		(layer "In4.Cu")
		(net "RMII_SPRNGVLLE_BMC_PCH_RXD0")
	)
	(segment
		(start 487.148632 -37.492432)
		(end 487.148632 -38.152832)
		(width 0.089408)
		(layer "In4.Cu")
		(net "RMII_SPRNGVLLE_BMC_PCH_RXD0")
	)
	(segment
		(start 402.869654 -21.0185)
		(end 405.1935 -21.0185)
		(width 0.089408)
		(layer "In4.Cu")
		(net "RMII_SPRNGVLLE_BMC_PCH_RXD0")
	)
	(segment
		(start 409.066746 -17.2974)
		(end 411.0355 -17.2974)
		(width 0.089408)
		(layer "In4.Cu")
		(net "RMII_SPRNGVLLE_BMC_PCH_RXD0")
	)
	(segment
		(start 377.72086 -25.897586)
		(end 377.72086 -23.94712)
		(width 0.089408)
		(layer "In4.Cu")
		(net "RMII_SPRNGVLLE_BMC_PCH_RXD0")
	)
	(segment
		(start 458.35189 -19.177)
		(end 458.441298 -19.266408)
		(width 0.089408)
		(layer "In4.Cu")
		(net "RMII_SPRNGVLLE_BMC_PCH_RXD0")
	)
	(segment
		(start 471.729308 -16.265398)
		(end 475.098872 -19.634962)
		(width 0.089408)
		(layer "In4.Cu")
		(net "RMII_SPRNGVLLE_BMC_PCH_RXD0")
	)
	(segment
		(start 490.6518 -40.6146)
		(end 492.1504 -42.1132)
		(width 0.089408)
		(layer "In4.Cu")
		(net "RMII_SPRNGVLLE_BMC_PCH_RXD0")
	)
	(segment
		(start 484.4796 -36.510976)
		(end 484.722424 -36.7538)
		(width 0.089408)
		(layer "In4.Cu")
		(net "RMII_SPRNGVLLE_BMC_PCH_RXD0")
	)
	(segment
		(start 382.489456 -19.178524)
		(end 391.324338 -19.178524)
		(width 0.089408)
		(layer "In4.Cu")
		(net "RMII_SPRNGVLLE_BMC_PCH_RXD0")
	)
	(segment
		(start 463.28838 -20.837906)
		(end 464.688174 -19.438112)
		(width 0.089408)
		(layer "In4.Cu")
		(net "RMII_SPRNGVLLE_BMC_PCH_RXD0")
	)
	(segment
		(start 373.5197 -30.7213)
		(end 373.5197 -32.743648)
		(width 0.089408)
		(layer "In11.Cu")
		(net "RMII_SPRNGVLLE_BMC_PCH_RXD0")
	)
	(segment
		(start 378.283724 -48.789844)
		(end 381.302768 -48.789844)
		(width 0.089408)
		(layer "In11.Cu")
		(net "RMII_SPRNGVLLE_BMC_PCH_RXD0")
	)
	(segment
		(start 390.008872 -69.079364)
		(end 391.38225 -70.452742)
		(width 0.089408)
		(layer "In11.Cu")
		(net "RMII_SPRNGVLLE_BMC_PCH_RXD0")
	)
	(segment
		(start 374.1928 -30.0482)
		(end 373.5197 -30.7213)
		(width 0.089408)
		(layer "In11.Cu")
		(net "RMII_SPRNGVLLE_BMC_PCH_RXD0")
	)
	(segment
		(start 392.7602 -81.386934)
		(end 393.198096 -81.82483)
		(width 0.089408)
		(layer "In11.Cu")
		(net "RMII_SPRNGVLLE_BMC_PCH_RXD0")
	)
	(segment
		(start 385.966208 -53.104034)
		(end 389.613902 -56.751728)
		(width 0.089408)
		(layer "In11.Cu")
		(net "RMII_SPRNGVLLE_BMC_PCH_RXD0")
	)
	(segment
		(start 389.613902 -56.751728)
		(end 389.613902 -60.7822)
		(width 0.089408)
		(layer "In11.Cu")
		(net "RMII_SPRNGVLLE_BMC_PCH_RXD0")
	)
	(segment
		(start 373.5197 -32.743648)
		(end 373.422164 -32.841184)
		(width 0.089408)
		(layer "In11.Cu")
		(net "RMII_SPRNGVLLE_BMC_PCH_RXD0")
	)
	(segment
		(start 376.09526 -46.60138)
		(end 378.283724 -48.789844)
		(width 0.089408)
		(layer "In11.Cu")
		(net "RMII_SPRNGVLLE_BMC_PCH_RXD0")
	)
	(segment
		(start 384.810508 -50.166016)
		(end 385.966208 -51.321716)
		(width 0.089408)
		(layer "In11.Cu")
		(net "RMII_SPRNGVLLE_BMC_PCH_RXD0")
	)
	(segment
		(start 392.7602 -81.02346)
		(end 392.7602 -81.386934)
		(width 0.089408)
		(layer "In11.Cu")
		(net "RMII_SPRNGVLLE_BMC_PCH_RXD0")
	)
	(segment
		(start 376.09526 -43.279314)
		(end 376.09526 -46.60138)
		(width 0.089408)
		(layer "In11.Cu")
		(net "RMII_SPRNGVLLE_BMC_PCH_RXD0")
	)
	(segment
		(start 391.38225 -70.452742)
		(end 391.38225 -79.64551)
		(width 0.089408)
		(layer "In11.Cu")
		(net "RMII_SPRNGVLLE_BMC_PCH_RXD0")
	)
	(segment
		(start 385.966208 -51.321716)
		(end 385.966208 -53.104034)
		(width 0.089408)
		(layer "In11.Cu")
		(net "RMII_SPRNGVLLE_BMC_PCH_RXD0")
	)
	(segment
		(start 381.302768 -48.789844)
		(end 382.67894 -50.166016)
		(width 0.089408)
		(layer "In11.Cu")
		(net "RMII_SPRNGVLLE_BMC_PCH_RXD0")
	)
	(segment
		(start 375.688606 -36.64204)
		(end 375.688606 -42.87266)
		(width 0.089408)
		(layer "In11.Cu")
		(net "RMII_SPRNGVLLE_BMC_PCH_RXD0")
	)
	(segment
		(start 391.38225 -79.64551)
		(end 392.7602 -81.02346)
		(width 0.089408)
		(layer "In11.Cu")
		(net "RMII_SPRNGVLLE_BMC_PCH_RXD0")
	)
	(segment
		(start 389.613902 -60.7822)
		(end 390.008872 -61.17717)
		(width 0.089408)
		(layer "In11.Cu")
		(net "RMII_SPRNGVLLE_BMC_PCH_RXD0")
	)
	(segment
		(start 382.67894 -50.166016)
		(end 384.810508 -50.166016)
		(width 0.089408)
		(layer "In11.Cu")
		(net "RMII_SPRNGVLLE_BMC_PCH_RXD0")
	)
	(segment
		(start 373.422164 -32.841184)
		(end 373.422164 -34.375598)
		(width 0.089408)
		(layer "In11.Cu")
		(net "RMII_SPRNGVLLE_BMC_PCH_RXD0")
	)
	(segment
		(start 390.008872 -61.17717)
		(end 390.008872 -69.079364)
		(width 0.089408)
		(layer "In11.Cu")
		(net "RMII_SPRNGVLLE_BMC_PCH_RXD0")
	)
	(segment
		(start 375.688606 -42.87266)
		(end 376.09526 -43.279314)
		(width 0.089408)
		(layer "In11.Cu")
		(net "RMII_SPRNGVLLE_BMC_PCH_RXD0")
	)
	(segment
		(start 373.422164 -34.375598)
		(end 375.688606 -36.64204)
		(width 0.089408)
		(layer "In11.Cu")
		(net "RMII_SPRNGVLLE_BMC_PCH_RXD0")
	)
	(segment
		(start 478.703386 -14.63675)
		(end 479.456242 -14.63675)
		(width 0.11684)
		(layer "F.Cu")
		(net "NIC_MDI_SPRV_RJ45_1_DP")
	)
	(segment
		(start 484.660448 -36.274248)
		(end 484.940864 -36.274248)
		(width 0.11684)
		(layer "F.Cu")
		(net "NIC_MDI_SPRV_RJ45_1_DP")
	)
	(segment
		(start 483.500938 -38.969442)
		(end 483.480872 -38.949376)
		(width 0.11684)
		(layer "F.Cu")
		(net "NIC_MDI_SPRV_RJ45_1_DP")
	)
	(segment
		(start 483.480872 -38.949376)
		(end 483.480872 -37.782246)
		(width 0.11684)
		(layer "F.Cu")
		(net "NIC_MDI_SPRV_RJ45_1_DP")
	)
	(segment
		(start 484.508556 -36.754562)
		(end 484.508556 -36.42614)
		(width 0.11684)
		(layer "F.Cu")
		(net "NIC_MDI_SPRV_RJ45_1_DP")
	)
	(segment
		(start 484.508556 -36.42614)
		(end 484.660448 -36.274248)
		(width 0.11684)
		(layer "F.Cu")
		(net "NIC_MDI_SPRV_RJ45_1_DP")
	)
	(segment
		(start 483.500938 -39.5986)
		(end 483.500938 -38.969442)
		(width 0.11684)
		(layer "F.Cu")
		(net "NIC_MDI_SPRV_RJ45_1_DP")
	)
	(segment
		(start 479.456242 -14.63675)
		(end 479.861372 -14.23162)
		(width 0.11684)
		(layer "F.Cu")
		(net "NIC_MDI_SPRV_RJ45_1_DP")
	)
	(segment
		(start 478.545144 -14.478508)
		(end 478.703386 -14.63675)
		(width 0.11684)
		(layer "F.Cu")
		(net "NIC_MDI_SPRV_RJ45_1_DP")
	)
	(segment
		(start 483.480872 -37.782246)
		(end 484.508556 -36.754562)
		(width 0.11684)
		(layer "F.Cu")
		(net "NIC_MDI_SPRV_RJ45_1_DP")
	)
	(via
		(at 484.940864 -36.274248)
		(size 0.508)
		(drill 0.254)
		(layers "F.Cu" "B.Cu")
		(net "NIC_MDI_SPRV_RJ45_1_DP")
	)
	(via
		(at 479.861372 -14.23162)
		(size 0.508)
		(drill 0.254)
		(layers "F.Cu" "B.Cu")
		(net "NIC_MDI_SPRV_RJ45_1_DP")
	)
	(segment
		(start 487.503216 -27.617166)
		(end 487.739944 -27.617166)
		(width 0.102108)
		(layer "In11.Cu")
		(net "NIC_MDI_SPRV_RJ45_1_DP")
	)
	(segment
		(start 481.057712 -15.28064)
		(end 480.359466 -14.582394)
		(width 0.102108)
		(layer "In11.Cu")
		(net "NIC_MDI_SPRV_RJ45_1_DP")
	)
	(segment
		(start 480.359466 -14.582394)
		(end 480.081336 -14.582394)
		(width 0.102108)
		(layer "In11.Cu")
		(net "NIC_MDI_SPRV_RJ45_1_DP")
	)
	(segment
		(start 486.795064 -22.341332)
		(end 486.345738 -21.892006)
		(width 0.102108)
		(layer "In11.Cu")
		(net "NIC_MDI_SPRV_RJ45_1_DP")
	)
	(segment
		(start 486.345738 -21.892006)
		(end 485.656128 -21.892006)
		(width 0.102108)
		(layer "In11.Cu")
		(net "NIC_MDI_SPRV_RJ45_1_DP")
	)
	(segment
		(start 485.365806 -23.551642)
		(end 485.467914 -23.449534)
		(width 0.102108)
		(layer "In11.Cu")
		(net "NIC_MDI_SPRV_RJ45_1_DP")
	)
	(segment
		(start 485.20604 -30.183836)
		(end 485.20604 -29.948632)
		(width 0.102108)
		(layer "In11.Cu")
		(net "NIC_MDI_SPRV_RJ45_1_DP")
	)
	(segment
		(start 485.38765 -29.285946)
		(end 485.130856 -29.029152)
		(width 0.102108)
		(layer "In11.Cu")
		(net "NIC_MDI_SPRV_RJ45_1_DP")
	)
	(segment
		(start 485.656128 -21.892006)
		(end 485.469692 -21.70557)
		(width 0.102108)
		(layer "In11.Cu")
		(net "NIC_MDI_SPRV_RJ45_1_DP")
	)
	(segment
		(start 484.517954 -18.527776)
		(end 484.517954 -16.87195)
		(width 0.102108)
		(layer "In11.Cu")
		(net "NIC_MDI_SPRV_RJ45_1_DP")
	)
	(segment
		(start 487.470704 -17.833594)
		(end 486.71226 -17.833594)
		(width 0.102108)
		(layer "In11.Cu")
		(net "NIC_MDI_SPRV_RJ45_1_DP")
	)
	(segment
		(start 485.853486 -35.689794)
		(end 486.814876 -34.728404)
		(width 0.102108)
		(layer "In11.Cu")
		(net "NIC_MDI_SPRV_RJ45_1_DP")
	)
	(segment
		(start 486.71226 -17.833594)
		(end 486.610152 -17.731486)
		(width 0.102108)
		(layer "In11.Cu")
		(net "NIC_MDI_SPRV_RJ45_1_DP")
	)
	(segment
		(start 484.735632 -36.274248)
		(end 484.639112 -36.177728)
		(width 0.102108)
		(layer "In11.Cu")
		(net "NIC_MDI_SPRV_RJ45_1_DP")
	)
	(segment
		(start 488.088178 -26.517092)
		(end 487.739944 -26.168858)
		(width 0.102108)
		(layer "In11.Cu")
		(net "NIC_MDI_SPRV_RJ45_1_DP")
	)
	(segment
		(start 487.195622 -20.400772)
		(end 486.466896 -19.672046)
		(width 0.102108)
		(layer "In11.Cu")
		(net "NIC_MDI_SPRV_RJ45_1_DP")
	)
	(segment
		(start 486.569004 -19.281902)
		(end 487.470704 -19.281902)
		(width 0.102108)
		(layer "In11.Cu")
		(net "NIC_MDI_SPRV_RJ45_1_DP")
	)
	(segment
		(start 485.74833 -25.53335)
		(end 486.361232 -25.53335)
		(width 0.102108)
		(layer "In11.Cu")
		(net "NIC_MDI_SPRV_RJ45_1_DP")
	)
	(segment
		(start 485.153462 -18.527776)
		(end 485.00157 -18.679668)
		(width 0.102108)
		(layer "In11.Cu")
		(net "NIC_MDI_SPRV_RJ45_1_DP")
	)
	(segment
		(start 485.420416 -30.398212)
		(end 485.20604 -30.183836)
		(width 0.102108)
		(layer "In11.Cu")
		(net "NIC_MDI_SPRV_RJ45_1_DP")
	)
	(segment
		(start 486.466896 -19.38401)
		(end 486.569004 -19.281902)
		(width 0.102108)
		(layer "In11.Cu")
		(net "NIC_MDI_SPRV_RJ45_1_DP")
	)
	(segment
		(start 485.00157 -18.679668)
		(end 484.669846 -18.679668)
		(width 0.102108)
		(layer "In11.Cu")
		(net "NIC_MDI_SPRV_RJ45_1_DP")
	)
	(segment
		(start 486.610152 -17.731486)
		(end 486.610152 -16.5481)
		(width 0.102108)
		(layer "In11.Cu")
		(net "NIC_MDI_SPRV_RJ45_1_DP")
	)
	(segment
		(start 486.711498 -24.425148)
		(end 486.371392 -24.085042)
		(width 0.102108)
		(layer "In11.Cu")
		(net "NIC_MDI_SPRV_RJ45_1_DP")
	)
	(segment
		(start 487.872278 -18.235168)
		(end 487.470704 -17.833594)
		(width 0.102108)
		(layer "In11.Cu")
		(net "NIC_MDI_SPRV_RJ45_1_DP")
	)
	(segment
		(start 484.7463 -35.689794)
		(end 485.853486 -35.689794)
		(width 0.102108)
		(layer "In11.Cu")
		(net "NIC_MDI_SPRV_RJ45_1_DP")
	)
	(segment
		(start 486.371392 -24.085042)
		(end 485.467914 -24.085042)
		(width 0.102108)
		(layer "In11.Cu")
		(net "NIC_MDI_SPRV_RJ45_1_DP")
	)
	(segment
		(start 486.814876 -33.929828)
		(end 487.088688 -33.656016)
		(width 0.102108)
		(layer "In11.Cu")
		(net "NIC_MDI_SPRV_RJ45_1_DP")
	)
	(segment
		(start 487.088688 -31.072328)
		(end 486.85704 -30.84068)
		(width 0.102108)
		(layer "In11.Cu")
		(net "NIC_MDI_SPRV_RJ45_1_DP")
	)
	(segment
		(start 483.444296 -16.434054)
		(end 482.290882 -15.28064)
		(width 0.102108)
		(layer "In11.Cu")
		(net "NIC_MDI_SPRV_RJ45_1_DP")
	)
	(segment
		(start 487.872278 -18.880328)
		(end 487.872278 -18.235168)
		(width 0.102108)
		(layer "In11.Cu")
		(net "NIC_MDI_SPRV_RJ45_1_DP")
	)
	(segment
		(start 486.497122 -30.216602)
		(end 485.83723 -30.216602)
		(width 0.102108)
		(layer "In11.Cu")
		(net "NIC_MDI_SPRV_RJ45_1_DP")
	)
	(segment
		(start 486.610152 -16.5481)
		(end 486.278174 -16.216122)
		(width 0.102108)
		(layer "In11.Cu")
		(net "NIC_MDI_SPRV_RJ45_1_DP")
	)
	(segment
		(start 486.814876 -34.728404)
		(end 486.814876 -33.929828)
		(width 0.102108)
		(layer "In11.Cu")
		(net "NIC_MDI_SPRV_RJ45_1_DP")
	)
	(segment
		(start 486.840022 -28.28036)
		(end 487.503216 -27.617166)
		(width 0.102108)
		(layer "In11.Cu")
		(net "NIC_MDI_SPRV_RJ45_1_DP")
	)
	(segment
		(start 485.83723 -30.216602)
		(end 485.65562 -30.398212)
		(width 0.102108)
		(layer "In11.Cu")
		(net "NIC_MDI_SPRV_RJ45_1_DP")
	)
	(segment
		(start 486.820972 -21.256498)
		(end 487.195622 -20.881848)
		(width 0.102108)
		(layer "In11.Cu")
		(net "NIC_MDI_SPRV_RJ45_1_DP")
	)
	(segment
		(start 486.278174 -16.216122)
		(end 485.493822 -16.216122)
		(width 0.102108)
		(layer "In11.Cu")
		(net "NIC_MDI_SPRV_RJ45_1_DP")
	)
	(segment
		(start 484.517954 -16.87195)
		(end 484.080058 -16.434054)
		(width 0.102108)
		(layer "In11.Cu")
		(net "NIC_MDI_SPRV_RJ45_1_DP")
	)
	(segment
		(start 485.493822 -16.216122)
		(end 485.153462 -16.556482)
		(width 0.102108)
		(layer "In11.Cu")
		(net "NIC_MDI_SPRV_RJ45_1_DP")
	)
	(segment
		(start 484.639112 -35.796982)
		(end 484.7463 -35.689794)
		(width 0.102108)
		(layer "In11.Cu")
		(net "NIC_MDI_SPRV_RJ45_1_DP")
	)
	(segment
		(start 487.088688 -33.656016)
		(end 487.088688 -31.072328)
		(width 0.102108)
		(layer "In11.Cu")
		(net "NIC_MDI_SPRV_RJ45_1_DP")
	)
	(segment
		(start 486.795064 -23.096728)
		(end 486.795064 -22.341332)
		(width 0.102108)
		(layer "In11.Cu")
		(net "NIC_MDI_SPRV_RJ45_1_DP")
	)
	(segment
		(start 485.130856 -27.744166)
		(end 485.257856 -27.617166)
		(width 0.102108)
		(layer "In11.Cu")
		(net "NIC_MDI_SPRV_RJ45_1_DP")
	)
	(segment
		(start 484.940864 -36.274248)
		(end 484.735632 -36.274248)
		(width 0.102108)
		(layer "In11.Cu")
		(net "NIC_MDI_SPRV_RJ45_1_DP")
	)
	(segment
		(start 485.38765 -29.767022)
		(end 485.38765 -29.285946)
		(width 0.102108)
		(layer "In11.Cu")
		(net "NIC_MDI_SPRV_RJ45_1_DP")
	)
	(segment
		(start 484.639112 -36.177728)
		(end 484.639112 -35.796982)
		(width 0.102108)
		(layer "In11.Cu")
		(net "NIC_MDI_SPRV_RJ45_1_DP")
	)
	(segment
		(start 482.290882 -15.28064)
		(end 481.057712 -15.28064)
		(width 0.102108)
		(layer "In11.Cu")
		(net "NIC_MDI_SPRV_RJ45_1_DP")
	)
	(segment
		(start 487.470704 -19.281902)
		(end 487.872278 -18.880328)
		(width 0.102108)
		(layer "In11.Cu")
		(net "NIC_MDI_SPRV_RJ45_1_DP")
	)
	(segment
		(start 480.081336 -14.582394)
		(end 479.861372 -14.36243)
		(width 0.102108)
		(layer "In11.Cu")
		(net "NIC_MDI_SPRV_RJ45_1_DP")
	)
	(segment
		(start 485.646222 -25.635458)
		(end 485.74833 -25.53335)
		(width 0.102108)
		(layer "In11.Cu")
		(net "NIC_MDI_SPRV_RJ45_1_DP")
	)
	(segment
		(start 484.669846 -18.679668)
		(end 484.517954 -18.527776)
		(width 0.102108)
		(layer "In11.Cu")
		(net "NIC_MDI_SPRV_RJ45_1_DP")
	)
	(segment
		(start 486.85704 -30.84068)
		(end 486.85704 -30.57652)
		(width 0.102108)
		(layer "In11.Cu")
		(net "NIC_MDI_SPRV_RJ45_1_DP")
	)
	(segment
		(start 485.467914 -24.085042)
		(end 485.365806 -23.982934)
		(width 0.102108)
		(layer "In11.Cu")
		(net "NIC_MDI_SPRV_RJ45_1_DP")
	)
	(segment
		(start 485.130856 -29.029152)
		(end 485.130856 -27.744166)
		(width 0.102108)
		(layer "In11.Cu")
		(net "NIC_MDI_SPRV_RJ45_1_DP")
	)
	(segment
		(start 486.85704 -30.57652)
		(end 486.497122 -30.216602)
		(width 0.102108)
		(layer "In11.Cu")
		(net "NIC_MDI_SPRV_RJ45_1_DP")
	)
	(segment
		(start 485.365806 -23.982934)
		(end 485.365806 -23.551642)
		(width 0.102108)
		(layer "In11.Cu")
		(net "NIC_MDI_SPRV_RJ45_1_DP")
	)
	(segment
		(start 485.646222 -26.06675)
		(end 485.646222 -25.635458)
		(width 0.102108)
		(layer "In11.Cu")
		(net "NIC_MDI_SPRV_RJ45_1_DP")
	)
	(segment
		(start 487.195622 -20.881848)
		(end 487.195622 -20.400772)
		(width 0.102108)
		(layer "In11.Cu")
		(net "NIC_MDI_SPRV_RJ45_1_DP")
	)
	(segment
		(start 485.153462 -16.556482)
		(end 485.153462 -18.527776)
		(width 0.102108)
		(layer "In11.Cu")
		(net "NIC_MDI_SPRV_RJ45_1_DP")
	)
	(segment
		(start 485.469692 -21.442934)
		(end 485.656128 -21.256498)
		(width 0.102108)
		(layer "In11.Cu")
		(net "NIC_MDI_SPRV_RJ45_1_DP")
	)
	(segment
		(start 485.656128 -21.256498)
		(end 486.820972 -21.256498)
		(width 0.102108)
		(layer "In11.Cu")
		(net "NIC_MDI_SPRV_RJ45_1_DP")
	)
	(segment
		(start 485.65562 -30.398212)
		(end 485.420416 -30.398212)
		(width 0.102108)
		(layer "In11.Cu")
		(net "NIC_MDI_SPRV_RJ45_1_DP")
	)
	(segment
		(start 486.442258 -23.449534)
		(end 486.795064 -23.096728)
		(width 0.102108)
		(layer "In11.Cu")
		(net "NIC_MDI_SPRV_RJ45_1_DP")
	)
	(segment
		(start 484.080058 -16.434054)
		(end 483.444296 -16.434054)
		(width 0.102108)
		(layer "In11.Cu")
		(net "NIC_MDI_SPRV_RJ45_1_DP")
	)
	(segment
		(start 488.088178 -27.268932)
		(end 488.088178 -26.517092)
		(width 0.102108)
		(layer "In11.Cu")
		(net "NIC_MDI_SPRV_RJ45_1_DP")
	)
	(segment
		(start 486.466896 -19.672046)
		(end 486.466896 -19.38401)
		(width 0.102108)
		(layer "In11.Cu")
		(net "NIC_MDI_SPRV_RJ45_1_DP")
	)
	(segment
		(start 485.74833 -26.168858)
		(end 485.646222 -26.06675)
		(width 0.102108)
		(layer "In11.Cu")
		(net "NIC_MDI_SPRV_RJ45_1_DP")
	)
	(segment
		(start 486.230168 -28.28036)
		(end 486.840022 -28.28036)
		(width 0.102108)
		(layer "In11.Cu")
		(net "NIC_MDI_SPRV_RJ45_1_DP")
	)
	(segment
		(start 487.739944 -26.168858)
		(end 485.74833 -26.168858)
		(width 0.102108)
		(layer "In11.Cu")
		(net "NIC_MDI_SPRV_RJ45_1_DP")
	)
	(segment
		(start 485.20604 -29.948632)
		(end 485.38765 -29.767022)
		(width 0.102108)
		(layer "In11.Cu")
		(net "NIC_MDI_SPRV_RJ45_1_DP")
	)
	(segment
		(start 485.257856 -27.617166)
		(end 485.566974 -27.617166)
		(width 0.102108)
		(layer "In11.Cu")
		(net "NIC_MDI_SPRV_RJ45_1_DP")
	)
	(segment
		(start 485.469692 -21.70557)
		(end 485.469692 -21.442934)
		(width 0.102108)
		(layer "In11.Cu")
		(net "NIC_MDI_SPRV_RJ45_1_DP")
	)
	(segment
		(start 479.861372 -14.36243)
		(end 479.861372 -14.23162)
		(width 0.102108)
		(layer "In11.Cu")
		(net "NIC_MDI_SPRV_RJ45_1_DP")
	)
	(segment
		(start 487.739944 -27.617166)
		(end 488.088178 -27.268932)
		(width 0.102108)
		(layer "In11.Cu")
		(net "NIC_MDI_SPRV_RJ45_1_DP")
	)
	(segment
		(start 486.361232 -25.53335)
		(end 486.711498 -25.183084)
		(width 0.102108)
		(layer "In11.Cu")
		(net "NIC_MDI_SPRV_RJ45_1_DP")
	)
	(segment
		(start 485.467914 -23.449534)
		(end 486.442258 -23.449534)
		(width 0.102108)
		(layer "In11.Cu")
		(net "NIC_MDI_SPRV_RJ45_1_DP")
	)
	(segment
		(start 485.566974 -27.617166)
		(end 486.230168 -28.28036)
		(width 0.102108)
		(layer "In11.Cu")
		(net "NIC_MDI_SPRV_RJ45_1_DP")
	)
	(segment
		(start 486.711498 -25.183084)
		(end 486.711498 -24.425148)
		(width 0.102108)
		(layer "In11.Cu")
		(net "NIC_MDI_SPRV_RJ45_1_DP")
	)
	(segment
		(start 484.048816 -36.564062)
		(end 484.048816 -36.35629)
		(width 0.11684)
		(layer "F.Cu")
		(net "NIC_MDI_SPRV_RJ45_1_DN")
	)
	(segment
		(start 478.545144 -15.251938)
		(end 478.700592 -15.09649)
		(width 0.11684)
		(layer "F.Cu")
		(net "NIC_MDI_SPRV_RJ45_1_DN")
	)
	(segment
		(start 484.048816 -36.35629)
		(end 483.966774 -36.274248)
		(width 0.11684)
		(layer "F.Cu")
		(net "NIC_MDI_SPRV_RJ45_1_DN")
	)
	(segment
		(start 483.021132 -38.949376)
		(end 483.001066 -38.969442)
		(width 0.11684)
		(layer "F.Cu")
		(net "NIC_MDI_SPRV_RJ45_1_DN")
	)
	(segment
		(start 483.505764 -37.107114)
		(end 483.021132 -37.591746)
		(width 0.11684)
		(layer "F.Cu")
		(net "NIC_MDI_SPRV_RJ45_1_DN")
	)
	(segment
		(start 483.021132 -37.591746)
		(end 483.021132 -38.949376)
		(width 0.11684)
		(layer "F.Cu")
		(net "NIC_MDI_SPRV_RJ45_1_DN")
	)
	(segment
		(start 483.505764 -37.10686)
		(end 483.505764 -37.107114)
		(width 0.11684)
		(layer "F.Cu")
		(net "NIC_MDI_SPRV_RJ45_1_DN")
	)
	(segment
		(start 478.700592 -15.09649)
		(end 479.456242 -15.09649)
		(width 0.11684)
		(layer "F.Cu")
		(net "NIC_MDI_SPRV_RJ45_1_DN")
	)
	(segment
		(start 483.505764 -37.107114)
		(end 484.048816 -36.564062)
		(width 0.11684)
		(layer "F.Cu")
		(net "NIC_MDI_SPRV_RJ45_1_DN")
	)
	(segment
		(start 483.966774 -36.274248)
		(end 483.67061 -36.274248)
		(width 0.11684)
		(layer "F.Cu")
		(net "NIC_MDI_SPRV_RJ45_1_DN")
	)
	(segment
		(start 483.001066 -38.969442)
		(end 483.001066 -39.5986)
		(width 0.11684)
		(layer "F.Cu")
		(net "NIC_MDI_SPRV_RJ45_1_DN")
	)
	(segment
		(start 479.456242 -15.09649)
		(end 479.861372 -15.50162)
		(width 0.11684)
		(layer "F.Cu")
		(net "NIC_MDI_SPRV_RJ45_1_DN")
	)
	(via
		(at 483.67061 -36.274248)
		(size 0.508)
		(drill 0.254)
		(layers "F.Cu" "B.Cu")
		(net "NIC_MDI_SPRV_RJ45_1_DN")
	)
	(via
		(at 479.861372 -15.50162)
		(size 0.508)
		(drill 0.254)
		(layers "F.Cu" "B.Cu")
		(net "NIC_MDI_SPRV_RJ45_1_DN")
	)
	(via
		(at 483.505764 -37.10686)
		(size 0.508)
		(drill 0.254)
		(layers "F.Cu" "B.Cu")
		(net "NIC_MDI_SPRV_RJ45_1_DN")
	)
	(segment
		(start 479.861372 -15.116048)
		(end 479.861372 -15.50162)
		(width 0.102108)
		(layer "In11.Cu")
		(net "NIC_MDI_SPRV_RJ45_1_DN")
	)
	(segment
		(start 487.302302 -18.239994)
		(end 486.543858 -18.239994)
		(width 0.102108)
		(layer "In11.Cu")
		(net "NIC_MDI_SPRV_RJ45_1_DN")
	)
	(segment
		(start 485.579928 -25.12695)
		(end 486.19283 -25.12695)
		(width 0.102108)
		(layer "In11.Cu")
		(net "NIC_MDI_SPRV_RJ45_1_DN")
	)
	(segment
		(start 484.111554 -18.696178)
		(end 484.111554 -17.040352)
		(width 0.102108)
		(layer "In11.Cu")
		(net "NIC_MDI_SPRV_RJ45_1_DN")
	)
	(segment
		(start 486.060496 -19.840448)
		(end 486.060496 -19.215608)
		(width 0.102108)
		(layer "In11.Cu")
		(net "NIC_MDI_SPRV_RJ45_1_DN")
	)
	(segment
		(start 485.487726 -20.850098)
		(end 486.65257 -20.850098)
		(width 0.102108)
		(layer "In11.Cu")
		(net "NIC_MDI_SPRV_RJ45_1_DN")
	)
	(segment
		(start 482.430328 -15.994888)
		(end 482.12248 -15.68704)
		(width 0.102108)
		(layer "In11.Cu")
		(net "NIC_MDI_SPRV_RJ45_1_DN")
	)
	(segment
		(start 487.302302 -18.875502)
		(end 487.465878 -18.711926)
		(width 0.102108)
		(layer "In11.Cu")
		(net "NIC_MDI_SPRV_RJ45_1_DN")
	)
	(segment
		(start 486.203752 -16.716502)
		(end 486.109772 -16.622522)
		(width 0.102108)
		(layer "In11.Cu")
		(net "NIC_MDI_SPRV_RJ45_1_DN")
	)
	(segment
		(start 486.20299 -24.491442)
		(end 485.299512 -24.491442)
		(width 0.102108)
		(layer "In11.Cu")
		(net "NIC_MDI_SPRV_RJ45_1_DN")
	)
	(segment
		(start 485.063292 -21.274532)
		(end 485.487726 -20.850098)
		(width 0.102108)
		(layer "In11.Cu")
		(net "NIC_MDI_SPRV_RJ45_1_DN")
	)
	(segment
		(start 485.252014 -30.804612)
		(end 484.79964 -30.352238)
		(width 0.102108)
		(layer "In11.Cu")
		(net "NIC_MDI_SPRV_RJ45_1_DN")
	)
	(segment
		(start 485.487726 -22.298406)
		(end 485.063292 -21.873972)
		(width 0.102108)
		(layer "In11.Cu")
		(net "NIC_MDI_SPRV_RJ45_1_DN")
	)
	(segment
		(start 484.724456 -27.575764)
		(end 485.089454 -27.210766)
		(width 0.102108)
		(layer "In11.Cu")
		(net "NIC_MDI_SPRV_RJ45_1_DN")
	)
	(segment
		(start 486.273856 -23.043134)
		(end 486.388664 -22.928326)
		(width 0.102108)
		(layer "In11.Cu")
		(net "NIC_MDI_SPRV_RJ45_1_DN")
	)
	(segment
		(start 486.177336 -22.298406)
		(end 485.487726 -22.298406)
		(width 0.102108)
		(layer "In11.Cu")
		(net "NIC_MDI_SPRV_RJ45_1_DN")
	)
	(segment
		(start 486.789222 -20.569174)
		(end 486.060496 -19.840448)
		(width 0.102108)
		(layer "In11.Cu")
		(net "NIC_MDI_SPRV_RJ45_1_DN")
	)
	(segment
		(start 484.959406 -24.151336)
		(end 484.959406 -23.38324)
		(width 0.102108)
		(layer "In11.Cu")
		(net "NIC_MDI_SPRV_RJ45_1_DN")
	)
	(segment
		(start 487.681778 -26.685494)
		(end 487.571542 -26.575258)
		(width 0.102108)
		(layer "In11.Cu")
		(net "NIC_MDI_SPRV_RJ45_1_DN")
	)
	(segment
		(start 487.571542 -27.210766)
		(end 487.681778 -27.10053)
		(width 0.102108)
		(layer "In11.Cu")
		(net "NIC_MDI_SPRV_RJ45_1_DN")
	)
	(segment
		(start 484.98125 -29.454348)
		(end 484.724456 -29.197554)
		(width 0.102108)
		(layer "In11.Cu")
		(net "NIC_MDI_SPRV_RJ45_1_DN")
	)
	(segment
		(start 484.232712 -35.62858)
		(end 484.577898 -35.283394)
		(width 0.102108)
		(layer "In11.Cu")
		(net "NIC_MDI_SPRV_RJ45_1_DN")
	)
	(segment
		(start 483.67061 -36.274248)
		(end 484.105712 -36.274248)
		(width 0.102108)
		(layer "In11.Cu")
		(net "NIC_MDI_SPRV_RJ45_1_DN")
	)
	(segment
		(start 486.682288 -31.24073)
		(end 486.45064 -31.009082)
		(width 0.102108)
		(layer "In11.Cu")
		(net "NIC_MDI_SPRV_RJ45_1_DN")
	)
	(segment
		(start 485.063292 -21.873972)
		(end 485.063292 -21.274532)
		(width 0.102108)
		(layer "In11.Cu")
		(net "NIC_MDI_SPRV_RJ45_1_DN")
	)
	(segment
		(start 486.39857 -27.87396)
		(end 486.67162 -27.87396)
		(width 0.102108)
		(layer "In11.Cu")
		(net "NIC_MDI_SPRV_RJ45_1_DN")
	)
	(segment
		(start 485.299512 -24.491442)
		(end 484.959406 -24.151336)
		(width 0.102108)
		(layer "In11.Cu")
		(net "NIC_MDI_SPRV_RJ45_1_DN")
	)
	(segment
		(start 486.005632 -30.623002)
		(end 485.824022 -30.804612)
		(width 0.102108)
		(layer "In11.Cu")
		(net "NIC_MDI_SPRV_RJ45_1_DN")
	)
	(segment
		(start 487.465878 -18.40357)
		(end 487.302302 -18.239994)
		(width 0.102108)
		(layer "In11.Cu")
		(net "NIC_MDI_SPRV_RJ45_1_DN")
	)
	(segment
		(start 486.19283 -25.12695)
		(end 486.305098 -25.014682)
		(width 0.102108)
		(layer "In11.Cu")
		(net "NIC_MDI_SPRV_RJ45_1_DN")
	)
	(segment
		(start 484.501444 -19.086068)
		(end 484.111554 -18.696178)
		(width 0.102108)
		(layer "In11.Cu")
		(net "NIC_MDI_SPRV_RJ45_1_DN")
	)
	(segment
		(start 486.388664 -22.509734)
		(end 486.177336 -22.298406)
		(width 0.102108)
		(layer "In11.Cu")
		(net "NIC_MDI_SPRV_RJ45_1_DN")
	)
	(segment
		(start 483.275894 -16.840454)
		(end 483.059232 -16.623792)
		(width 0.102108)
		(layer "In11.Cu")
		(net "NIC_MDI_SPRV_RJ45_1_DN")
	)
	(segment
		(start 486.109772 -16.622522)
		(end 485.662224 -16.622522)
		(width 0.102108)
		(layer "In11.Cu")
		(net "NIC_MDI_SPRV_RJ45_1_DN")
	)
	(segment
		(start 486.203752 -17.899888)
		(end 486.203752 -16.716502)
		(width 0.102108)
		(layer "In11.Cu")
		(net "NIC_MDI_SPRV_RJ45_1_DN")
	)
	(segment
		(start 485.559862 -18.696178)
		(end 485.169972 -19.086068)
		(width 0.102108)
		(layer "In11.Cu")
		(net "NIC_MDI_SPRV_RJ45_1_DN")
	)
	(segment
		(start 486.682288 -33.487614)
		(end 486.682288 -31.24073)
		(width 0.102108)
		(layer "In11.Cu")
		(net "NIC_MDI_SPRV_RJ45_1_DN")
	)
	(segment
		(start 484.79964 -30.352238)
		(end 484.79964 -29.78023)
		(width 0.102108)
		(layer "In11.Cu")
		(net "NIC_MDI_SPRV_RJ45_1_DN")
	)
	(segment
		(start 486.45064 -31.009082)
		(end 486.45064 -30.744922)
		(width 0.102108)
		(layer "In11.Cu")
		(net "NIC_MDI_SPRV_RJ45_1_DN")
	)
	(segment
		(start 482.64699 -16.623792)
		(end 482.430328 -16.40713)
		(width 0.102108)
		(layer "In11.Cu")
		(net "NIC_MDI_SPRV_RJ45_1_DN")
	)
	(segment
		(start 485.239822 -26.235152)
		(end 485.239822 -25.467056)
		(width 0.102108)
		(layer "In11.Cu")
		(net "NIC_MDI_SPRV_RJ45_1_DN")
	)
	(segment
		(start 484.232712 -36.147248)
		(end 484.232712 -35.62858)
		(width 0.102108)
		(layer "In11.Cu")
		(net "NIC_MDI_SPRV_RJ45_1_DN")
	)
	(segment
		(start 484.105712 -36.274248)
		(end 484.232712 -36.147248)
		(width 0.102108)
		(layer "In11.Cu")
		(net "NIC_MDI_SPRV_RJ45_1_DN")
	)
	(segment
		(start 483.911656 -16.840454)
		(end 483.275894 -16.840454)
		(width 0.102108)
		(layer "In11.Cu")
		(net "NIC_MDI_SPRV_RJ45_1_DN")
	)
	(segment
		(start 485.662224 -16.622522)
		(end 485.559862 -16.724884)
		(width 0.102108)
		(layer "In11.Cu")
		(net "NIC_MDI_SPRV_RJ45_1_DN")
	)
	(segment
		(start 485.735376 -27.210766)
		(end 486.39857 -27.87396)
		(width 0.102108)
		(layer "In11.Cu")
		(net "NIC_MDI_SPRV_RJ45_1_DN")
	)
	(segment
		(start 485.299512 -23.043134)
		(end 486.273856 -23.043134)
		(width 0.102108)
		(layer "In11.Cu")
		(net "NIC_MDI_SPRV_RJ45_1_DN")
	)
	(segment
		(start 486.388664 -22.928326)
		(end 486.388664 -22.509734)
		(width 0.102108)
		(layer "In11.Cu")
		(net "NIC_MDI_SPRV_RJ45_1_DN")
	)
	(segment
		(start 485.579928 -26.575258)
		(end 485.239822 -26.235152)
		(width 0.102108)
		(layer "In11.Cu")
		(net "NIC_MDI_SPRV_RJ45_1_DN")
	)
	(segment
		(start 480.88931 -15.68704)
		(end 480.191064 -14.988794)
		(width 0.102108)
		(layer "In11.Cu")
		(net "NIC_MDI_SPRV_RJ45_1_DN")
	)
	(segment
		(start 484.577898 -35.283394)
		(end 485.685084 -35.283394)
		(width 0.102108)
		(layer "In11.Cu")
		(net "NIC_MDI_SPRV_RJ45_1_DN")
	)
	(segment
		(start 485.089454 -27.210766)
		(end 485.735376 -27.210766)
		(width 0.102108)
		(layer "In11.Cu")
		(net "NIC_MDI_SPRV_RJ45_1_DN")
	)
	(segment
		(start 486.67162 -27.87396)
		(end 487.334814 -27.210766)
		(width 0.102108)
		(layer "In11.Cu")
		(net "NIC_MDI_SPRV_RJ45_1_DN")
	)
	(segment
		(start 484.111554 -17.040352)
		(end 483.911656 -16.840454)
		(width 0.102108)
		(layer "In11.Cu")
		(net "NIC_MDI_SPRV_RJ45_1_DN")
	)
	(segment
		(start 486.45064 -30.744922)
		(end 486.32872 -30.623002)
		(width 0.102108)
		(layer "In11.Cu")
		(net "NIC_MDI_SPRV_RJ45_1_DN")
	)
	(segment
		(start 485.559862 -16.724884)
		(end 485.559862 -18.696178)
		(width 0.102108)
		(layer "In11.Cu")
		(net "NIC_MDI_SPRV_RJ45_1_DN")
	)
	(segment
		(start 482.430328 -16.40713)
		(end 482.430328 -15.994888)
		(width 0.102108)
		(layer "In11.Cu")
		(net "NIC_MDI_SPRV_RJ45_1_DN")
	)
	(segment
		(start 487.334814 -27.210766)
		(end 487.571542 -27.210766)
		(width 0.102108)
		(layer "In11.Cu")
		(net "NIC_MDI_SPRV_RJ45_1_DN")
	)
	(segment
		(start 487.681778 -27.10053)
		(end 487.681778 -26.685494)
		(width 0.102108)
		(layer "In11.Cu")
		(net "NIC_MDI_SPRV_RJ45_1_DN")
	)
	(segment
		(start 485.169972 -19.086068)
		(end 484.501444 -19.086068)
		(width 0.102108)
		(layer "In11.Cu")
		(net "NIC_MDI_SPRV_RJ45_1_DN")
	)
	(segment
		(start 487.465878 -18.711926)
		(end 487.465878 -18.40357)
		(width 0.102108)
		(layer "In11.Cu")
		(net "NIC_MDI_SPRV_RJ45_1_DN")
	)
	(segment
		(start 483.059232 -16.623792)
		(end 482.64699 -16.623792)
		(width 0.102108)
		(layer "In11.Cu")
		(net "NIC_MDI_SPRV_RJ45_1_DN")
	)
	(segment
		(start 484.959406 -23.38324)
		(end 485.299512 -23.043134)
		(width 0.102108)
		(layer "In11.Cu")
		(net "NIC_MDI_SPRV_RJ45_1_DN")
	)
	(segment
		(start 486.543858 -18.239994)
		(end 486.203752 -17.899888)
		(width 0.102108)
		(layer "In11.Cu")
		(net "NIC_MDI_SPRV_RJ45_1_DN")
	)
	(segment
		(start 486.305098 -25.014682)
		(end 486.305098 -24.59355)
		(width 0.102108)
		(layer "In11.Cu")
		(net "NIC_MDI_SPRV_RJ45_1_DN")
	)
	(segment
		(start 480.191064 -14.988794)
		(end 479.988626 -14.988794)
		(width 0.102108)
		(layer "In11.Cu")
		(net "NIC_MDI_SPRV_RJ45_1_DN")
	)
	(segment
		(start 485.824022 -30.804612)
		(end 485.252014 -30.804612)
		(width 0.102108)
		(layer "In11.Cu")
		(net "NIC_MDI_SPRV_RJ45_1_DN")
	)
	(segment
		(start 482.12248 -15.68704)
		(end 480.88931 -15.68704)
		(width 0.102108)
		(layer "In11.Cu")
		(net "NIC_MDI_SPRV_RJ45_1_DN")
	)
	(segment
		(start 484.98125 -29.59862)
		(end 484.98125 -29.454348)
		(width 0.102108)
		(layer "In11.Cu")
		(net "NIC_MDI_SPRV_RJ45_1_DN")
	)
	(segment
		(start 486.789222 -20.713446)
		(end 486.789222 -20.569174)
		(width 0.102108)
		(layer "In11.Cu")
		(net "NIC_MDI_SPRV_RJ45_1_DN")
	)
	(segment
		(start 487.571542 -26.575258)
		(end 485.579928 -26.575258)
		(width 0.102108)
		(layer "In11.Cu")
		(net "NIC_MDI_SPRV_RJ45_1_DN")
	)
	(segment
		(start 486.408476 -34.560002)
		(end 486.408476 -33.761426)
		(width 0.102108)
		(layer "In11.Cu")
		(net "NIC_MDI_SPRV_RJ45_1_DN")
	)
	(segment
		(start 486.060496 -19.215608)
		(end 486.400602 -18.875502)
		(width 0.102108)
		(layer "In11.Cu")
		(net "NIC_MDI_SPRV_RJ45_1_DN")
	)
	(segment
		(start 486.65257 -20.850098)
		(end 486.789222 -20.713446)
		(width 0.102108)
		(layer "In11.Cu")
		(net "NIC_MDI_SPRV_RJ45_1_DN")
	)
	(segment
		(start 486.32872 -30.623002)
		(end 486.005632 -30.623002)
		(width 0.102108)
		(layer "In11.Cu")
		(net "NIC_MDI_SPRV_RJ45_1_DN")
	)
	(segment
		(start 486.305098 -24.59355)
		(end 486.20299 -24.491442)
		(width 0.102108)
		(layer "In11.Cu")
		(net "NIC_MDI_SPRV_RJ45_1_DN")
	)
	(segment
		(start 485.685084 -35.283394)
		(end 486.408476 -34.560002)
		(width 0.102108)
		(layer "In11.Cu")
		(net "NIC_MDI_SPRV_RJ45_1_DN")
	)
	(segment
		(start 484.79964 -29.78023)
		(end 484.98125 -29.59862)
		(width 0.102108)
		(layer "In11.Cu")
		(net "NIC_MDI_SPRV_RJ45_1_DN")
	)
	(segment
		(start 479.988626 -14.988794)
		(end 479.861372 -15.116048)
		(width 0.102108)
		(layer "In11.Cu")
		(net "NIC_MDI_SPRV_RJ45_1_DN")
	)
	(segment
		(start 484.724456 -29.197554)
		(end 484.724456 -27.575764)
		(width 0.102108)
		(layer "In11.Cu")
		(net "NIC_MDI_SPRV_RJ45_1_DN")
	)
	(segment
		(start 486.408476 -33.761426)
		(end 486.682288 -33.487614)
		(width 0.102108)
		(layer "In11.Cu")
		(net "NIC_MDI_SPRV_RJ45_1_DN")
	)
	(segment
		(start 485.239822 -25.467056)
		(end 485.579928 -25.12695)
		(width 0.102108)
		(layer "In11.Cu")
		(net "NIC_MDI_SPRV_RJ45_1_DN")
	)
	(segment
		(start 486.400602 -18.875502)
		(end 487.302302 -18.875502)
		(width 0.102108)
		(layer "In11.Cu")
		(net "NIC_MDI_SPRV_RJ45_1_DN")
	)
	(segment
		(start 485.586786 -38.059614)
		(end 485.703626 -37.942774)
		(width 0.11684)
		(layer "F.Cu")
		(net "NIC_MDI_SPRV_RJ45_0_DP")
	)
	(segment
		(start 479.861372 -12.3571)
		(end 479.861372 -11.69162)
		(width 0.11684)
		(layer "F.Cu")
		(net "NIC_MDI_SPRV_RJ45_0_DP")
	)
	(segment
		(start 479.756216 -12.462256)
		(end 479.861372 -12.3571)
		(width 0.11684)
		(layer "F.Cu")
		(net "NIC_MDI_SPRV_RJ45_0_DP")
	)
	(segment
		(start 478.540572 -12.462256)
		(end 479.756216 -12.462256)
		(width 0.11684)
		(layer "F.Cu")
		(net "NIC_MDI_SPRV_RJ45_0_DP")
	)
	(segment
		(start 485.001062 -39.14013)
		(end 484.980742 -39.11981)
		(width 0.11684)
		(layer "F.Cu")
		(net "NIC_MDI_SPRV_RJ45_0_DP")
	)
	(segment
		(start 484.980742 -38.928802)
		(end 485.586786 -38.322758)
		(width 0.11684)
		(layer "F.Cu")
		(net "NIC_MDI_SPRV_RJ45_0_DP")
	)
	(segment
		(start 484.980742 -39.11981)
		(end 484.980742 -38.928802)
		(width 0.11684)
		(layer "F.Cu")
		(net "NIC_MDI_SPRV_RJ45_0_DP")
	)
	(segment
		(start 485.001062 -39.5986)
		(end 485.001062 -39.14013)
		(width 0.11684)
		(layer "F.Cu")
		(net "NIC_MDI_SPRV_RJ45_0_DP")
	)
	(segment
		(start 485.703626 -37.942774)
		(end 486.001568 -37.942774)
		(width 0.11684)
		(layer "F.Cu")
		(net "NIC_MDI_SPRV_RJ45_0_DP")
	)
	(segment
		(start 485.586786 -38.322758)
		(end 485.586786 -38.059614)
		(width 0.11684)
		(layer "F.Cu")
		(net "NIC_MDI_SPRV_RJ45_0_DP")
	)
	(via
		(at 486.001568 -37.942774)
		(size 0.508)
		(drill 0.254)
		(layers "F.Cu" "B.Cu")
		(net "NIC_MDI_SPRV_RJ45_0_DP")
	)
	(via
		(at 479.861372 -11.69162)
		(size 0.508)
		(drill 0.254)
		(layers "F.Cu" "B.Cu")
		(net "NIC_MDI_SPRV_RJ45_0_DP")
	)
	(segment
		(start 490.651546 -25.489408)
		(end 490.651546 -24.721312)
		(width 0.102108)
		(layer "In11.Cu")
		(net "NIC_MDI_SPRV_RJ45_0_DP")
	)
	(segment
		(start 491.267242 -22.637496)
		(end 490.927136 -22.29739)
		(width 0.102108)
		(layer "In11.Cu")
		(net "NIC_MDI_SPRV_RJ45_0_DP")
	)
	(segment
		(start 490.31144 -24.381206)
		(end 489.548424 -24.381206)
		(width 0.102108)
		(layer "In11.Cu")
		(net "NIC_MDI_SPRV_RJ45_0_DP")
	)
	(segment
		(start 490.126528 -27.91333)
		(end 490.876844 -27.91333)
		(width 0.102108)
		(layer "In11.Cu")
		(net "NIC_MDI_SPRV_RJ45_0_DP")
	)
	(segment
		(start 488.914186 -18.380456)
		(end 490.494828 -16.799814)
		(width 0.102108)
		(layer "In11.Cu")
		(net "NIC_MDI_SPRV_RJ45_0_DP")
	)
	(segment
		(start 481.992178 -13.921232)
		(end 481.711254 -14.202156)
		(width 0.102108)
		(layer "In11.Cu")
		(net "NIC_MDI_SPRV_RJ45_0_DP")
	)
	(segment
		(start 489.651294 -32.864044)
		(end 489.311188 -32.523938)
		(width 0.102108)
		(layer "In11.Cu")
		(net "NIC_MDI_SPRV_RJ45_0_DP")
	)
	(segment
		(start 486.498392 -36.868608)
		(end 487.132884 -37.5031)
		(width 0.102108)
		(layer "In11.Cu")
		(net "NIC_MDI_SPRV_RJ45_0_DP")
	)
	(segment
		(start 491.267242 -23.405592)
		(end 491.267242 -22.637496)
		(width 0.102108)
		(layer "In11.Cu")
		(net "NIC_MDI_SPRV_RJ45_0_DP")
	)
	(segment
		(start 481.54209 -13.471144)
		(end 481.54209 -12.990068)
		(width 0.102108)
		(layer "In11.Cu")
		(net "NIC_MDI_SPRV_RJ45_0_DP")
	)
	(segment
		(start 488.649264 -29.390594)
		(end 488.649264 -28.909772)
		(width 0.102108)
		(layer "In11.Cu")
		(net "NIC_MDI_SPRV_RJ45_0_DP")
	)
	(segment
		(start 487.644186 -15.174214)
		(end 483.726236 -15.174214)
		(width 0.102108)
		(layer "In11.Cu")
		(net "NIC_MDI_SPRV_RJ45_0_DP")
	)
	(segment
		(start 485.708198 -37.940996)
		(end 485.581452 -37.813234)
		(width 0.102108)
		(layer "In11.Cu")
		(net "NIC_MDI_SPRV_RJ45_0_DP")
	)
	(segment
		(start 480.681284 -12.129262)
		(end 479.96348 -12.129262)
		(width 0.102108)
		(layer "In11.Cu")
		(net "NIC_MDI_SPRV_RJ45_0_DP")
	)
	(segment
		(start 489.548424 -24.381206)
		(end 489.446316 -24.279098)
		(width 0.102108)
		(layer "In11.Cu")
		(net "NIC_MDI_SPRV_RJ45_0_DP")
	)
	(segment
		(start 488.23499 -16.241268)
		(end 488.132882 -16.13916)
		(width 0.102108)
		(layer "In11.Cu")
		(net "NIC_MDI_SPRV_RJ45_0_DP")
	)
	(segment
		(start 479.96348 -12.129262)
		(end 479.861372 -12.027154)
		(width 0.102108)
		(layer "In11.Cu")
		(net "NIC_MDI_SPRV_RJ45_0_DP")
	)
	(segment
		(start 488.532424 -34.491676)
		(end 488.532424 -34.074354)
		(width 0.102108)
		(layer "In11.Cu")
		(net "NIC_MDI_SPRV_RJ45_0_DP")
	)
	(segment
		(start 485.581452 -37.566854)
		(end 486.279698 -36.868608)
		(width 0.102108)
		(layer "In11.Cu")
		(net "NIC_MDI_SPRV_RJ45_0_DP")
	)
	(segment
		(start 488.678474 -28.184094)
		(end 488.822746 -28.184094)
		(width 0.102108)
		(layer "In11.Cu")
		(net "NIC_MDI_SPRV_RJ45_0_DP")
	)
	(segment
		(start 490.927136 -20.213574)
		(end 489.081064 -20.213574)
		(width 0.102108)
		(layer "In11.Cu")
		(net "NIC_MDI_SPRV_RJ45_0_DP")
	)
	(segment
		(start 486.001568 -37.942774)
		(end 485.708198 -37.940996)
		(width 0.102108)
		(layer "In11.Cu")
		(net "NIC_MDI_SPRV_RJ45_0_DP")
	)
	(segment
		(start 481.54209 -12.990068)
		(end 480.681284 -12.129262)
		(width 0.102108)
		(layer "In11.Cu")
		(net "NIC_MDI_SPRV_RJ45_0_DP")
	)
	(segment
		(start 489.311188 -33.972246)
		(end 489.651294 -33.63214)
		(width 0.102108)
		(layer "In11.Cu")
		(net "NIC_MDI_SPRV_RJ45_0_DP")
	)
	(segment
		(start 491.267242 -21.321776)
		(end 491.267242 -20.55368)
		(width 0.102108)
		(layer "In11.Cu")
		(net "NIC_MDI_SPRV_RJ45_0_DP")
	)
	(segment
		(start 491.22838 -26.805128)
		(end 490.888274 -26.465022)
		(width 0.102108)
		(layer "In11.Cu")
		(net "NIC_MDI_SPRV_RJ45_0_DP")
	)
	(segment
		(start 488.197144 -29.842714)
		(end 488.649264 -29.390594)
		(width 0.102108)
		(layer "In11.Cu")
		(net "NIC_MDI_SPRV_RJ45_0_DP")
	)
	(segment
		(start 488.634532 -33.972246)
		(end 489.311188 -33.972246)
		(width 0.102108)
		(layer "In11.Cu")
		(net "NIC_MDI_SPRV_RJ45_0_DP")
	)
	(segment
		(start 489.446316 -24.279098)
		(end 489.446316 -23.847806)
		(width 0.102108)
		(layer "In11.Cu")
		(net "NIC_MDI_SPRV_RJ45_0_DP")
	)
	(segment
		(start 488.343702 -21.661882)
		(end 490.927136 -21.661882)
		(width 0.102108)
		(layer "In11.Cu")
		(net "NIC_MDI_SPRV_RJ45_0_DP")
	)
	(segment
		(start 489.579666 -28.460192)
		(end 490.126528 -27.91333)
		(width 0.102108)
		(layer "In11.Cu")
		(net "NIC_MDI_SPRV_RJ45_0_DP")
	)
	(segment
		(start 488.15752 -36.477956)
		(end 487.468672 -35.789108)
		(width 0.102108)
		(layer "In11.Cu")
		(net "NIC_MDI_SPRV_RJ45_0_DP")
	)
	(segment
		(start 488.190032 -21.815552)
		(end 488.343702 -21.661882)
		(width 0.102108)
		(layer "In11.Cu")
		(net "NIC_MDI_SPRV_RJ45_0_DP")
	)
	(segment
		(start 490.494828 -16.799814)
		(end 492.801402 -16.799814)
		(width 0.102108)
		(layer "In11.Cu")
		(net "NIC_MDI_SPRV_RJ45_0_DP")
	)
	(segment
		(start 485.581452 -37.813234)
		(end 485.581452 -37.566854)
		(width 0.102108)
		(layer "In11.Cu")
		(net "NIC_MDI_SPRV_RJ45_0_DP")
	)
	(segment
		(start 481.261166 -13.752068)
		(end 481.54209 -13.471144)
		(width 0.102108)
		(layer "In11.Cu")
		(net "NIC_MDI_SPRV_RJ45_0_DP")
	)
	(segment
		(start 488.649264 -28.909772)
		(end 488.373166 -28.633674)
		(width 0.102108)
		(layer "In11.Cu")
		(net "NIC_MDI_SPRV_RJ45_0_DP")
	)
	(segment
		(start 482.473254 -13.921232)
		(end 481.992178 -13.921232)
		(width 0.102108)
		(layer "In11.Cu")
		(net "NIC_MDI_SPRV_RJ45_0_DP")
	)
	(segment
		(start 488.373166 -28.633674)
		(end 488.373166 -28.489402)
		(width 0.102108)
		(layer "In11.Cu")
		(net "NIC_MDI_SPRV_RJ45_0_DP")
	)
	(segment
		(start 489.651294 -33.63214)
		(end 489.651294 -32.864044)
		(width 0.102108)
		(layer "In11.Cu")
		(net "NIC_MDI_SPRV_RJ45_0_DP")
	)
	(segment
		(start 487.468672 -35.789108)
		(end 487.468672 -35.555428)
		(width 0.102108)
		(layer "In11.Cu")
		(net "NIC_MDI_SPRV_RJ45_0_DP")
	)
	(segment
		(start 488.532424 -32.42183)
		(end 488.532424 -31.601918)
		(width 0.102108)
		(layer "In11.Cu")
		(net "NIC_MDI_SPRV_RJ45_0_DP")
	)
	(segment
		(start 488.822746 -28.184094)
		(end 489.098844 -28.460192)
		(width 0.102108)
		(layer "In11.Cu")
		(net "NIC_MDI_SPRV_RJ45_0_DP")
	)
	(segment
		(start 488.197144 -31.266638)
		(end 488.197144 -29.842714)
		(width 0.102108)
		(layer "In11.Cu")
		(net "NIC_MDI_SPRV_RJ45_0_DP")
	)
	(segment
		(start 489.143548 -25.943052)
		(end 489.257086 -25.829514)
		(width 0.102108)
		(layer "In11.Cu")
		(net "NIC_MDI_SPRV_RJ45_0_DP")
	)
	(segment
		(start 489.143548 -26.362914)
		(end 489.143548 -25.943052)
		(width 0.102108)
		(layer "In11.Cu")
		(net "NIC_MDI_SPRV_RJ45_0_DP")
	)
	(segment
		(start 488.15752 -36.958778)
		(end 488.15752 -36.477956)
		(width 0.102108)
		(layer "In11.Cu")
		(net "NIC_MDI_SPRV_RJ45_0_DP")
	)
	(segment
		(start 481.261166 -13.89634)
		(end 481.261166 -13.752068)
		(width 0.102108)
		(layer "In11.Cu")
		(net "NIC_MDI_SPRV_RJ45_0_DP")
	)
	(segment
		(start 488.132882 -16.13916)
		(end 488.132882 -15.66291)
		(width 0.102108)
		(layer "In11.Cu")
		(net "NIC_MDI_SPRV_RJ45_0_DP")
	)
	(segment
		(start 489.311188 -32.523938)
		(end 488.634532 -32.523938)
		(width 0.102108)
		(layer "In11.Cu")
		(net "NIC_MDI_SPRV_RJ45_0_DP")
	)
	(segment
		(start 488.76839 -15.66291)
		(end 488.76839 -16.13916)
		(width 0.102108)
		(layer "In11.Cu")
		(net "NIC_MDI_SPRV_RJ45_0_DP")
	)
	(segment
		(start 488.190032 -22.195282)
		(end 488.190032 -21.815552)
		(width 0.102108)
		(layer "In11.Cu")
		(net "NIC_MDI_SPRV_RJ45_0_DP")
	)
	(segment
		(start 488.532424 -34.074354)
		(end 488.634532 -33.972246)
		(width 0.102108)
		(layer "In11.Cu")
		(net "NIC_MDI_SPRV_RJ45_0_DP")
	)
	(segment
		(start 490.651546 -24.721312)
		(end 490.31144 -24.381206)
		(width 0.102108)
		(layer "In11.Cu")
		(net "NIC_MDI_SPRV_RJ45_0_DP")
	)
	(segment
		(start 490.927136 -22.29739)
		(end 488.29214 -22.29739)
		(width 0.102108)
		(layer "In11.Cu")
		(net "NIC_MDI_SPRV_RJ45_0_DP")
	)
	(segment
		(start 488.132882 -15.66291)
		(end 487.644186 -15.174214)
		(width 0.102108)
		(layer "In11.Cu")
		(net "NIC_MDI_SPRV_RJ45_0_DP")
	)
	(segment
		(start 488.914186 -20.046696)
		(end 488.914186 -18.380456)
		(width 0.102108)
		(layer "In11.Cu")
		(net "NIC_MDI_SPRV_RJ45_0_DP")
	)
	(segment
		(start 481.711254 -14.202156)
		(end 481.566982 -14.202156)
		(width 0.102108)
		(layer "In11.Cu")
		(net "NIC_MDI_SPRV_RJ45_0_DP")
	)
	(segment
		(start 490.888274 -26.465022)
		(end 489.245656 -26.465022)
		(width 0.102108)
		(layer "In11.Cu")
		(net "NIC_MDI_SPRV_RJ45_0_DP")
	)
	(segment
		(start 491.22838 -27.561794)
		(end 491.22838 -26.805128)
		(width 0.102108)
		(layer "In11.Cu")
		(net "NIC_MDI_SPRV_RJ45_0_DP")
	)
	(segment
		(start 487.468672 -35.555428)
		(end 488.532424 -34.491676)
		(width 0.102108)
		(layer "In11.Cu")
		(net "NIC_MDI_SPRV_RJ45_0_DP")
	)
	(segment
		(start 479.861372 -12.027154)
		(end 479.861372 -11.69162)
		(width 0.102108)
		(layer "In11.Cu")
		(net "NIC_MDI_SPRV_RJ45_0_DP")
	)
	(segment
		(start 490.31144 -25.829514)
		(end 490.651546 -25.489408)
		(width 0.102108)
		(layer "In11.Cu")
		(net "NIC_MDI_SPRV_RJ45_0_DP")
	)
	(segment
		(start 489.446316 -23.847806)
		(end 489.548424 -23.745698)
		(width 0.102108)
		(layer "In11.Cu")
		(net "NIC_MDI_SPRV_RJ45_0_DP")
	)
	(segment
		(start 488.532424 -31.601918)
		(end 488.197144 -31.266638)
		(width 0.102108)
		(layer "In11.Cu")
		(net "NIC_MDI_SPRV_RJ45_0_DP")
	)
	(segment
		(start 490.876844 -27.91333)
		(end 491.22838 -27.561794)
		(width 0.102108)
		(layer "In11.Cu")
		(net "NIC_MDI_SPRV_RJ45_0_DP")
	)
	(segment
		(start 493.141508 -15.66291)
		(end 492.801402 -15.322804)
		(width 0.102108)
		(layer "In11.Cu")
		(net "NIC_MDI_SPRV_RJ45_0_DP")
	)
	(segment
		(start 489.257086 -25.829514)
		(end 490.31144 -25.829514)
		(width 0.102108)
		(layer "In11.Cu")
		(net "NIC_MDI_SPRV_RJ45_0_DP")
	)
	(segment
		(start 490.927136 -23.745698)
		(end 491.267242 -23.405592)
		(width 0.102108)
		(layer "In11.Cu")
		(net "NIC_MDI_SPRV_RJ45_0_DP")
	)
	(segment
		(start 490.927136 -21.661882)
		(end 491.267242 -21.321776)
		(width 0.102108)
		(layer "In11.Cu")
		(net "NIC_MDI_SPRV_RJ45_0_DP")
	)
	(segment
		(start 486.279698 -36.868608)
		(end 486.498392 -36.868608)
		(width 0.102108)
		(layer "In11.Cu")
		(net "NIC_MDI_SPRV_RJ45_0_DP")
	)
	(segment
		(start 488.634532 -32.523938)
		(end 488.532424 -32.42183)
		(width 0.102108)
		(layer "In11.Cu")
		(net "NIC_MDI_SPRV_RJ45_0_DP")
	)
	(segment
		(start 488.666282 -16.241268)
		(end 488.23499 -16.241268)
		(width 0.102108)
		(layer "In11.Cu")
		(net "NIC_MDI_SPRV_RJ45_0_DP")
	)
	(segment
		(start 488.373166 -28.489402)
		(end 488.678474 -28.184094)
		(width 0.102108)
		(layer "In11.Cu")
		(net "NIC_MDI_SPRV_RJ45_0_DP")
	)
	(segment
		(start 488.76839 -16.13916)
		(end 488.666282 -16.241268)
		(width 0.102108)
		(layer "In11.Cu")
		(net "NIC_MDI_SPRV_RJ45_0_DP")
	)
	(segment
		(start 489.098844 -28.460192)
		(end 489.579666 -28.460192)
		(width 0.102108)
		(layer "In11.Cu")
		(net "NIC_MDI_SPRV_RJ45_0_DP")
	)
	(segment
		(start 488.29214 -22.29739)
		(end 488.190032 -22.195282)
		(width 0.102108)
		(layer "In11.Cu")
		(net "NIC_MDI_SPRV_RJ45_0_DP")
	)
	(segment
		(start 491.267242 -20.55368)
		(end 490.927136 -20.213574)
		(width 0.102108)
		(layer "In11.Cu")
		(net "NIC_MDI_SPRV_RJ45_0_DP")
	)
	(segment
		(start 489.108496 -15.322804)
		(end 488.76839 -15.66291)
		(width 0.102108)
		(layer "In11.Cu")
		(net "NIC_MDI_SPRV_RJ45_0_DP")
	)
	(segment
		(start 493.141508 -16.459708)
		(end 493.141508 -15.66291)
		(width 0.102108)
		(layer "In11.Cu")
		(net "NIC_MDI_SPRV_RJ45_0_DP")
	)
	(segment
		(start 481.566982 -14.202156)
		(end 481.261166 -13.89634)
		(width 0.102108)
		(layer "In11.Cu")
		(net "NIC_MDI_SPRV_RJ45_0_DP")
	)
	(segment
		(start 489.245656 -26.465022)
		(end 489.143548 -26.362914)
		(width 0.102108)
		(layer "In11.Cu")
		(net "NIC_MDI_SPRV_RJ45_0_DP")
	)
	(segment
		(start 487.613198 -37.5031)
		(end 488.15752 -36.958778)
		(width 0.102108)
		(layer "In11.Cu")
		(net "NIC_MDI_SPRV_RJ45_0_DP")
	)
	(segment
		(start 492.801402 -16.799814)
		(end 493.141508 -16.459708)
		(width 0.102108)
		(layer "In11.Cu")
		(net "NIC_MDI_SPRV_RJ45_0_DP")
	)
	(segment
		(start 489.548424 -23.745698)
		(end 490.927136 -23.745698)
		(width 0.102108)
		(layer "In11.Cu")
		(net "NIC_MDI_SPRV_RJ45_0_DP")
	)
	(segment
		(start 487.132884 -37.5031)
		(end 487.613198 -37.5031)
		(width 0.102108)
		(layer "In11.Cu")
		(net "NIC_MDI_SPRV_RJ45_0_DP")
	)
	(segment
		(start 483.726236 -15.174214)
		(end 482.473254 -13.921232)
		(width 0.102108)
		(layer "In11.Cu")
		(net "NIC_MDI_SPRV_RJ45_0_DP")
	)
	(segment
		(start 489.081064 -20.213574)
		(end 488.914186 -20.046696)
		(width 0.102108)
		(layer "In11.Cu")
		(net "NIC_MDI_SPRV_RJ45_0_DP")
	)
	(segment
		(start 492.801402 -15.322804)
		(end 489.108496 -15.322804)
		(width 0.102108)
		(layer "In11.Cu")
		(net "NIC_MDI_SPRV_RJ45_0_DP")
	)
	(segment
		(start 485.127046 -38.051486)
		(end 485.011222 -37.935662)
		(width 0.11684)
		(layer "F.Cu")
		(net "NIC_MDI_SPRV_RJ45_0_DN")
	)
	(segment
		(start 484.521002 -39.102538)
		(end 484.521002 -38.738302)
		(width 0.11684)
		(layer "F.Cu")
		(net "NIC_MDI_SPRV_RJ45_0_DN")
	)
	(segment
		(start 477.68002 -12.474194)
		(end 478.167446 -12.96162)
		(width 0.11684)
		(layer "F.Cu")
		(net "NIC_MDI_SPRV_RJ45_0_DN")
	)
	(segment
		(start 478.167446 -12.96162)
		(end 479.861372 -12.96162)
		(width 0.11684)
		(layer "F.Cu")
		(net "NIC_MDI_SPRV_RJ45_0_DN")
	)
	(segment
		(start 485.127046 -38.132258)
		(end 485.127046 -38.051486)
		(width 0.11684)
		(layer "F.Cu")
		(net "NIC_MDI_SPRV_RJ45_0_DN")
	)
	(segment
		(start 484.500936 -39.5986)
		(end 484.500936 -39.122604)
		(width 0.11684)
		(layer "F.Cu")
		(net "NIC_MDI_SPRV_RJ45_0_DN")
	)
	(segment
		(start 485.011222 -37.935662)
		(end 484.715058 -37.935662)
		(width 0.11684)
		(layer "F.Cu")
		(net "NIC_MDI_SPRV_RJ45_0_DN")
	)
	(segment
		(start 484.521002 -38.738302)
		(end 485.127046 -38.132258)
		(width 0.11684)
		(layer "F.Cu")
		(net "NIC_MDI_SPRV_RJ45_0_DN")
	)
	(segment
		(start 484.500936 -39.122604)
		(end 484.521002 -39.102538)
		(width 0.11684)
		(layer "F.Cu")
		(net "NIC_MDI_SPRV_RJ45_0_DN")
	)
	(via
		(at 484.715058 -37.935662)
		(size 0.508)
		(drill 0.254)
		(layers "F.Cu" "B.Cu")
		(net "NIC_MDI_SPRV_RJ45_0_DN")
	)
	(via
		(at 479.861372 -12.96162)
		(size 0.508)
		(drill 0.254)
		(layers "F.Cu" "B.Cu")
		(net "NIC_MDI_SPRV_RJ45_0_DN")
	)
	(segment
		(start 482.304852 -14.327632)
		(end 482.16058 -14.327632)
		(width 0.102108)
		(layer "In11.Cu")
		(net "NIC_MDI_SPRV_RJ45_0_DN")
	)
	(segment
		(start 487.783632 -21.64715)
		(end 488.1753 -21.255482)
		(width 0.102108)
		(layer "In11.Cu")
		(net "NIC_MDI_SPRV_RJ45_0_DN")
	)
	(segment
		(start 492.735108 -16.291306)
		(end 492.735108 -15.831312)
		(width 0.102108)
		(layer "In11.Cu")
		(net "NIC_MDI_SPRV_RJ45_0_DN")
	)
	(segment
		(start 490.143038 -25.423114)
		(end 490.245146 -25.321006)
		(width 0.102108)
		(layer "In11.Cu")
		(net "NIC_MDI_SPRV_RJ45_0_DN")
	)
	(segment
		(start 487.726482 -16.307562)
		(end 487.726482 -15.831312)
		(width 0.102108)
		(layer "In11.Cu")
		(net "NIC_MDI_SPRV_RJ45_0_DN")
	)
	(segment
		(start 490.708442 -27.50693)
		(end 490.82198 -27.393392)
		(width 0.102108)
		(layer "In11.Cu")
		(net "NIC_MDI_SPRV_RJ45_0_DN")
	)
	(segment
		(start 492.633 -16.393414)
		(end 492.735108 -16.291306)
		(width 0.102108)
		(layer "In11.Cu")
		(net "NIC_MDI_SPRV_RJ45_0_DN")
	)
	(segment
		(start 488.126024 -32.590232)
		(end 488.126024 -31.77032)
		(width 0.102108)
		(layer "In11.Cu")
		(net "NIC_MDI_SPRV_RJ45_0_DN")
	)
	(segment
		(start 488.912662 -20.619974)
		(end 488.507786 -20.215098)
		(width 0.102108)
		(layer "In11.Cu")
		(net "NIC_MDI_SPRV_RJ45_0_DN")
	)
	(segment
		(start 488.126024 -31.77032)
		(end 487.790744 -31.43504)
		(width 0.102108)
		(layer "In11.Cu")
		(net "NIC_MDI_SPRV_RJ45_0_DN")
	)
	(segment
		(start 490.245146 -25.321006)
		(end 490.245146 -24.889714)
		(width 0.102108)
		(layer "In11.Cu")
		(net "NIC_MDI_SPRV_RJ45_0_DN")
	)
	(segment
		(start 487.790744 -30.870144)
		(end 487.499152 -30.578552)
		(width 0.102108)
		(layer "In11.Cu")
		(net "NIC_MDI_SPRV_RJ45_0_DN")
	)
	(segment
		(start 488.123738 -22.70379)
		(end 487.783632 -22.363684)
		(width 0.102108)
		(layer "In11.Cu")
		(net "NIC_MDI_SPRV_RJ45_0_DN")
	)
	(segment
		(start 489.039916 -23.679404)
		(end 489.380022 -23.339298)
		(width 0.102108)
		(layer "In11.Cu")
		(net "NIC_MDI_SPRV_RJ45_0_DN")
	)
	(segment
		(start 481.39858 -14.608556)
		(end 480.854766 -14.064742)
		(width 0.102108)
		(layer "In11.Cu")
		(net "NIC_MDI_SPRV_RJ45_0_DN")
	)
	(segment
		(start 490.860842 -21.153374)
		(end 490.860842 -20.722082)
		(width 0.102108)
		(layer "In11.Cu")
		(net "NIC_MDI_SPRV_RJ45_0_DN")
	)
	(segment
		(start 487.726482 -15.831312)
		(end 487.475784 -15.580614)
		(width 0.102108)
		(layer "In11.Cu")
		(net "NIC_MDI_SPRV_RJ45_0_DN")
	)
	(segment
		(start 487.790744 -31.43504)
		(end 487.790744 -30.870144)
		(width 0.102108)
		(layer "In11.Cu")
		(net "NIC_MDI_SPRV_RJ45_0_DN")
	)
	(segment
		(start 489.958126 -27.50693)
		(end 490.708442 -27.50693)
		(width 0.102108)
		(layer "In11.Cu")
		(net "NIC_MDI_SPRV_RJ45_0_DN")
	)
	(segment
		(start 490.860842 -23.23719)
		(end 490.860842 -22.805898)
		(width 0.102108)
		(layer "In11.Cu")
		(net "NIC_MDI_SPRV_RJ45_0_DN")
	)
	(segment
		(start 490.245146 -24.889714)
		(end 490.143038 -24.787606)
		(width 0.102108)
		(layer "In11.Cu")
		(net "NIC_MDI_SPRV_RJ45_0_DN")
	)
	(segment
		(start 487.475784 -15.580614)
		(end 483.557834 -15.580614)
		(width 0.102108)
		(layer "In11.Cu")
		(net "NIC_MDI_SPRV_RJ45_0_DN")
	)
	(segment
		(start 490.758734 -22.70379)
		(end 488.123738 -22.70379)
		(width 0.102108)
		(layer "In11.Cu")
		(net "NIC_MDI_SPRV_RJ45_0_DN")
	)
	(segment
		(start 486.666794 -36.462208)
		(end 487.301286 -37.0967)
		(width 0.102108)
		(layer "In11.Cu")
		(net "NIC_MDI_SPRV_RJ45_0_DN")
	)
	(segment
		(start 489.142786 -33.565846)
		(end 489.244894 -33.463738)
		(width 0.102108)
		(layer "In11.Cu")
		(net "NIC_MDI_SPRV_RJ45_0_DN")
	)
	(segment
		(start 488.1753 -21.255482)
		(end 490.758734 -21.255482)
		(width 0.102108)
		(layer "In11.Cu")
		(net "NIC_MDI_SPRV_RJ45_0_DN")
	)
	(segment
		(start 485.175052 -37.804852)
		(end 485.175052 -37.398452)
		(width 0.102108)
		(layer "In11.Cu")
		(net "NIC_MDI_SPRV_RJ45_0_DN")
	)
	(segment
		(start 489.276898 -15.729204)
		(end 489.17479 -15.831312)
		(width 0.102108)
		(layer "In11.Cu")
		(net "NIC_MDI_SPRV_RJ45_0_DN")
	)
	(segment
		(start 488.242864 -29.078174)
		(end 487.966766 -28.802076)
		(width 0.102108)
		(layer "In11.Cu")
		(net "NIC_MDI_SPRV_RJ45_0_DN")
	)
	(segment
		(start 489.244894 -33.463738)
		(end 489.244894 -33.032446)
		(width 0.102108)
		(layer "In11.Cu")
		(net "NIC_MDI_SPRV_RJ45_0_DN")
	)
	(segment
		(start 489.077254 -26.871422)
		(end 488.737148 -26.531316)
		(width 0.102108)
		(layer "In11.Cu")
		(net "NIC_MDI_SPRV_RJ45_0_DN")
	)
	(segment
		(start 480.854766 -13.583666)
		(end 481.13569 -13.302742)
		(width 0.102108)
		(layer "In11.Cu")
		(net "NIC_MDI_SPRV_RJ45_0_DN")
	)
	(segment
		(start 487.966766 -28.321)
		(end 488.510072 -27.777694)
		(width 0.102108)
		(layer "In11.Cu")
		(net "NIC_MDI_SPRV_RJ45_0_DN")
	)
	(segment
		(start 488.737148 -26.531316)
		(end 488.737148 -25.77465)
		(width 0.102108)
		(layer "In11.Cu")
		(net "NIC_MDI_SPRV_RJ45_0_DN")
	)
	(segment
		(start 488.991148 -27.777694)
		(end 489.267246 -28.053792)
		(width 0.102108)
		(layer "In11.Cu")
		(net "NIC_MDI_SPRV_RJ45_0_DN")
	)
	(segment
		(start 490.758734 -23.339298)
		(end 490.860842 -23.23719)
		(width 0.102108)
		(layer "In11.Cu")
		(net "NIC_MDI_SPRV_RJ45_0_DN")
	)
	(segment
		(start 489.380022 -23.339298)
		(end 490.758734 -23.339298)
		(width 0.102108)
		(layer "In11.Cu")
		(net "NIC_MDI_SPRV_RJ45_0_DN")
	)
	(segment
		(start 490.719872 -26.871422)
		(end 489.077254 -26.871422)
		(width 0.102108)
		(layer "In11.Cu")
		(net "NIC_MDI_SPRV_RJ45_0_DN")
	)
	(segment
		(start 488.507786 -20.215098)
		(end 488.507786 -18.212054)
		(width 0.102108)
		(layer "In11.Cu")
		(net "NIC_MDI_SPRV_RJ45_0_DN")
	)
	(segment
		(start 487.444796 -37.0967)
		(end 487.75112 -36.790376)
		(width 0.102108)
		(layer "In11.Cu")
		(net "NIC_MDI_SPRV_RJ45_0_DN")
	)
	(segment
		(start 489.380022 -24.787606)
		(end 489.039916 -24.4475)
		(width 0.102108)
		(layer "In11.Cu")
		(net "NIC_MDI_SPRV_RJ45_0_DN")
	)
	(segment
		(start 487.301286 -37.0967)
		(end 487.444796 -37.0967)
		(width 0.102108)
		(layer "In11.Cu")
		(net "NIC_MDI_SPRV_RJ45_0_DN")
	)
	(segment
		(start 490.326426 -16.393414)
		(end 492.633 -16.393414)
		(width 0.102108)
		(layer "In11.Cu")
		(net "NIC_MDI_SPRV_RJ45_0_DN")
	)
	(segment
		(start 488.46613 -33.565846)
		(end 489.142786 -33.565846)
		(width 0.102108)
		(layer "In11.Cu")
		(net "NIC_MDI_SPRV_RJ45_0_DN")
	)
	(segment
		(start 488.126024 -34.323274)
		(end 488.126024 -33.905952)
		(width 0.102108)
		(layer "In11.Cu")
		(net "NIC_MDI_SPRV_RJ45_0_DN")
	)
	(segment
		(start 488.510072 -27.777694)
		(end 488.991148 -27.777694)
		(width 0.102108)
		(layer "In11.Cu")
		(net "NIC_MDI_SPRV_RJ45_0_DN")
	)
	(segment
		(start 488.242864 -29.222192)
		(end 488.242864 -29.078174)
		(width 0.102108)
		(layer "In11.Cu")
		(net "NIC_MDI_SPRV_RJ45_0_DN")
	)
	(segment
		(start 488.46613 -32.930338)
		(end 488.126024 -32.590232)
		(width 0.102108)
		(layer "In11.Cu")
		(net "NIC_MDI_SPRV_RJ45_0_DN")
	)
	(segment
		(start 480.854766 -14.064742)
		(end 480.854766 -13.583666)
		(width 0.102108)
		(layer "In11.Cu")
		(net "NIC_MDI_SPRV_RJ45_0_DN")
	)
	(segment
		(start 488.126024 -33.905952)
		(end 488.46613 -33.565846)
		(width 0.102108)
		(layer "In11.Cu")
		(net "NIC_MDI_SPRV_RJ45_0_DN")
	)
	(segment
		(start 490.860842 -22.805898)
		(end 490.758734 -22.70379)
		(width 0.102108)
		(layer "In11.Cu")
		(net "NIC_MDI_SPRV_RJ45_0_DN")
	)
	(segment
		(start 479.96348 -12.535662)
		(end 479.861372 -12.63777)
		(width 0.102108)
		(layer "In11.Cu")
		(net "NIC_MDI_SPRV_RJ45_0_DN")
	)
	(segment
		(start 489.17479 -16.307562)
		(end 488.834684 -16.647668)
		(width 0.102108)
		(layer "In11.Cu")
		(net "NIC_MDI_SPRV_RJ45_0_DN")
	)
	(segment
		(start 482.16058 -14.327632)
		(end 481.879656 -14.608556)
		(width 0.102108)
		(layer "In11.Cu")
		(net "NIC_MDI_SPRV_RJ45_0_DN")
	)
	(segment
		(start 489.267246 -28.053792)
		(end 489.411264 -28.053792)
		(width 0.102108)
		(layer "In11.Cu")
		(net "NIC_MDI_SPRV_RJ45_0_DN")
	)
	(segment
		(start 490.758734 -21.255482)
		(end 490.860842 -21.153374)
		(width 0.102108)
		(layer "In11.Cu")
		(net "NIC_MDI_SPRV_RJ45_0_DN")
	)
	(segment
		(start 487.062272 -35.387026)
		(end 488.126024 -34.323274)
		(width 0.102108)
		(layer "In11.Cu")
		(net "NIC_MDI_SPRV_RJ45_0_DN")
	)
	(segment
		(start 481.879656 -14.608556)
		(end 481.39858 -14.608556)
		(width 0.102108)
		(layer "In11.Cu")
		(net "NIC_MDI_SPRV_RJ45_0_DN")
	)
	(segment
		(start 490.143038 -24.787606)
		(end 489.380022 -24.787606)
		(width 0.102108)
		(layer "In11.Cu")
		(net "NIC_MDI_SPRV_RJ45_0_DN")
	)
	(segment
		(start 487.062272 -35.95751)
		(end 487.062272 -35.387026)
		(width 0.102108)
		(layer "In11.Cu")
		(net "NIC_MDI_SPRV_RJ45_0_DN")
	)
	(segment
		(start 487.966766 -28.802076)
		(end 487.966766 -28.321)
		(width 0.102108)
		(layer "In11.Cu")
		(net "NIC_MDI_SPRV_RJ45_0_DN")
	)
	(segment
		(start 488.834684 -16.647668)
		(end 488.066588 -16.647668)
		(width 0.102108)
		(layer "In11.Cu")
		(net "NIC_MDI_SPRV_RJ45_0_DN")
	)
	(segment
		(start 488.066588 -16.647668)
		(end 487.726482 -16.307562)
		(width 0.102108)
		(layer "In11.Cu")
		(net "NIC_MDI_SPRV_RJ45_0_DN")
	)
	(segment
		(start 479.861372 -12.63777)
		(end 479.861372 -12.96162)
		(width 0.102108)
		(layer "In11.Cu")
		(net "NIC_MDI_SPRV_RJ45_0_DN")
	)
	(segment
		(start 489.411264 -28.053792)
		(end 489.958126 -27.50693)
		(width 0.102108)
		(layer "In11.Cu")
		(net "NIC_MDI_SPRV_RJ45_0_DN")
	)
	(segment
		(start 487.790744 -29.674312)
		(end 488.242864 -29.222192)
		(width 0.102108)
		(layer "In11.Cu")
		(net "NIC_MDI_SPRV_RJ45_0_DN")
	)
	(segment
		(start 481.13569 -13.15847)
		(end 480.512882 -12.535662)
		(width 0.102108)
		(layer "In11.Cu")
		(net "NIC_MDI_SPRV_RJ45_0_DN")
	)
	(segment
		(start 487.499152 -30.272228)
		(end 487.790744 -29.980636)
		(width 0.102108)
		(layer "In11.Cu")
		(net "NIC_MDI_SPRV_RJ45_0_DN")
	)
	(segment
		(start 492.735108 -15.831312)
		(end 492.633 -15.729204)
		(width 0.102108)
		(layer "In11.Cu")
		(net "NIC_MDI_SPRV_RJ45_0_DN")
	)
	(segment
		(start 488.507786 -18.212054)
		(end 490.326426 -16.393414)
		(width 0.102108)
		(layer "In11.Cu")
		(net "NIC_MDI_SPRV_RJ45_0_DN")
	)
	(segment
		(start 489.17479 -15.831312)
		(end 489.17479 -16.307562)
		(width 0.102108)
		(layer "In11.Cu")
		(net "NIC_MDI_SPRV_RJ45_0_DN")
	)
	(segment
		(start 490.758734 -20.619974)
		(end 488.912662 -20.619974)
		(width 0.102108)
		(layer "In11.Cu")
		(net "NIC_MDI_SPRV_RJ45_0_DN")
	)
	(segment
		(start 484.715058 -37.935662)
		(end 485.04094 -37.937948)
		(width 0.102108)
		(layer "In11.Cu")
		(net "NIC_MDI_SPRV_RJ45_0_DN")
	)
	(segment
		(start 487.75112 -36.646358)
		(end 487.062272 -35.95751)
		(width 0.102108)
		(layer "In11.Cu")
		(net "NIC_MDI_SPRV_RJ45_0_DN")
	)
	(segment
		(start 487.75112 -36.790376)
		(end 487.75112 -36.646358)
		(width 0.102108)
		(layer "In11.Cu")
		(net "NIC_MDI_SPRV_RJ45_0_DN")
	)
	(segment
		(start 487.499152 -30.578552)
		(end 487.499152 -30.272228)
		(width 0.102108)
		(layer "In11.Cu")
		(net "NIC_MDI_SPRV_RJ45_0_DN")
	)
	(segment
		(start 485.04094 -37.937948)
		(end 485.175052 -37.804852)
		(width 0.102108)
		(layer "In11.Cu")
		(net "NIC_MDI_SPRV_RJ45_0_DN")
	)
	(segment
		(start 487.783632 -22.363684)
		(end 487.783632 -21.64715)
		(width 0.102108)
		(layer "In11.Cu")
		(net "NIC_MDI_SPRV_RJ45_0_DN")
	)
	(segment
		(start 488.737148 -25.77465)
		(end 489.088684 -25.423114)
		(width 0.102108)
		(layer "In11.Cu")
		(net "NIC_MDI_SPRV_RJ45_0_DN")
	)
	(segment
		(start 487.790744 -29.980636)
		(end 487.790744 -29.674312)
		(width 0.102108)
		(layer "In11.Cu")
		(net "NIC_MDI_SPRV_RJ45_0_DN")
	)
	(segment
		(start 483.557834 -15.580614)
		(end 482.304852 -14.327632)
		(width 0.102108)
		(layer "In11.Cu")
		(net "NIC_MDI_SPRV_RJ45_0_DN")
	)
	(segment
		(start 486.111296 -36.462208)
		(end 486.666794 -36.462208)
		(width 0.102108)
		(layer "In11.Cu")
		(net "NIC_MDI_SPRV_RJ45_0_DN")
	)
	(segment
		(start 490.82198 -26.97353)
		(end 490.719872 -26.871422)
		(width 0.102108)
		(layer "In11.Cu")
		(net "NIC_MDI_SPRV_RJ45_0_DN")
	)
	(segment
		(start 489.088684 -25.423114)
		(end 490.143038 -25.423114)
		(width 0.102108)
		(layer "In11.Cu")
		(net "NIC_MDI_SPRV_RJ45_0_DN")
	)
	(segment
		(start 489.039916 -24.4475)
		(end 489.039916 -23.679404)
		(width 0.102108)
		(layer "In11.Cu")
		(net "NIC_MDI_SPRV_RJ45_0_DN")
	)
	(segment
		(start 490.82198 -27.393392)
		(end 490.82198 -26.97353)
		(width 0.102108)
		(layer "In11.Cu")
		(net "NIC_MDI_SPRV_RJ45_0_DN")
	)
	(segment
		(start 489.142786 -32.930338)
		(end 488.46613 -32.930338)
		(width 0.102108)
		(layer "In11.Cu")
		(net "NIC_MDI_SPRV_RJ45_0_DN")
	)
	(segment
		(start 492.633 -15.729204)
		(end 489.276898 -15.729204)
		(width 0.102108)
		(layer "In11.Cu")
		(net "NIC_MDI_SPRV_RJ45_0_DN")
	)
	(segment
		(start 489.244894 -33.032446)
		(end 489.142786 -32.930338)
		(width 0.102108)
		(layer "In11.Cu")
		(net "NIC_MDI_SPRV_RJ45_0_DN")
	)
	(segment
		(start 480.512882 -12.535662)
		(end 479.96348 -12.535662)
		(width 0.102108)
		(layer "In11.Cu")
		(net "NIC_MDI_SPRV_RJ45_0_DN")
	)
	(segment
		(start 481.13569 -13.302742)
		(end 481.13569 -13.15847)
		(width 0.102108)
		(layer "In11.Cu")
		(net "NIC_MDI_SPRV_RJ45_0_DN")
	)
	(segment
		(start 485.175052 -37.398452)
		(end 486.111296 -36.462208)
		(width 0.102108)
		(layer "In11.Cu")
		(net "NIC_MDI_SPRV_RJ45_0_DN")
	)
	(segment
		(start 490.860842 -20.722082)
		(end 490.758734 -20.619974)
		(width 0.102108)
		(layer "In11.Cu")
		(net "NIC_MDI_SPRV_RJ45_0_DN")
	)
	(segment
		(start 488.3912 -49.7967)
		(end 488.3912 -49.5046)
		(width 0.10795)
		(layer "F.Cu")
		(net "PU_JTAG_SPRV_TMS")
	)
	(segment
		(start 488.3912 -49.5046)
		(end 488.061 -49.1744)
		(width 0.10795)
		(layer "F.Cu")
		(net "PU_JTAG_SPRV_TMS")
	)
	(segment
		(start 487.807 -49.1744)
		(end 487.501184 -48.868584)
		(width 0.10795)
		(layer "F.Cu")
		(net "PU_JTAG_SPRV_TMS")
	)
	(segment
		(start 488.061 -49.1744)
		(end 487.807 -49.1744)
		(width 0.10795)
		(layer "F.Cu")
		(net "PU_JTAG_SPRV_TMS")
	)
	(segment
		(start 487.501184 -48.868584)
		(end 487.501184 -48.3362)
		(width 0.10795)
		(layer "F.Cu")
		(net "PU_JTAG_SPRV_TMS")
	)
	(via
		(at 488.061 -49.1744)
		(size 0.508)
		(drill 0.254)
		(layers "F.Cu" "B.Cu")
		(net "PU_JTAG_SPRV_TMS")
	)
	(via
		(at 487.9594 -50.614326)
		(size 0.6604)
		(drill 0.3302)
		(layers "F.Cu" "B.Cu")
		(net "PU_JTAG_SPRV_TMS")
	)
	(segment
		(start 487.9594 -50.614326)
		(end 487.9594 -50.6222)
		(width 0.10795)
		(layer "B.Cu")
		(net "PU_JTAG_SPRV_TMS")
	)
	(segment
		(start 487.9594 -50.6222)
		(end 488.067096 -50.514504)
		(width 0.10795)
		(layer "B.Cu")
		(net "PU_JTAG_SPRV_TMS")
	)
	(segment
		(start 488.067096 -50.514504)
		(end 488.067096 -49.180496)
		(width 0.10795)
		(layer "B.Cu")
		(net "PU_JTAG_SPRV_TMS")
	)
	(segment
		(start 488.067096 -49.180496)
		(end 488.061 -49.1744)
		(width 0.10795)
		(layer "B.Cu")
		(net "PU_JTAG_SPRV_TMS")
	)
	(segment
		(start 489.3818 -41.5036)
		(end 490.1438 -41.5036)
		(width 0.10795)
		(layer "F.Cu")
		(net "PU_JTAG_SPRV_TDO")
	)
	(segment
		(start 489.167932 -41.717468)
		(end 489.3818 -41.5036)
		(width 0.10795)
		(layer "F.Cu")
		(net "PU_JTAG_SPRV_TDO")
	)
	(segment
		(start 490.1438 -41.5036)
		(end 490.601 -41.0464)
		(width 0.10795)
		(layer "F.Cu")
		(net "PU_JTAG_SPRV_TDO")
	)
	(segment
		(start 490.601 -41.0464)
		(end 491.0455 -41.0464)
		(width 0.10795)
		(layer "F.Cu")
		(net "PU_JTAG_SPRV_TDO")
	)
	(segment
		(start 488.6198 -41.717468)
		(end 489.167932 -41.717468)
		(width 0.10795)
		(layer "F.Cu")
		(net "PU_JTAG_SPRV_TDO")
	)
	(via
		(at 490.1438 -41.5036)
		(size 0.508)
		(drill 0.254)
		(layers "F.Cu" "B.Cu")
		(net "PU_JTAG_SPRV_TDO")
	)
	(segment
		(start 481.76434 -49.31156)
		(end 482.001068 -49.074832)
		(width 0.10795)
		(layer "F.Cu")
		(net "PU_JTAG_SPRV_TDI")
	)
	(segment
		(start 481.76434 -49.37252)
		(end 481.76434 -49.31156)
		(width 0.10795)
		(layer "F.Cu")
		(net "PU_JTAG_SPRV_TDI")
	)
	(segment
		(start 482.001068 -49.074832)
		(end 482.001068 -48.3362)
		(width 0.10795)
		(layer "F.Cu")
		(net "PU_JTAG_SPRV_TDI")
	)
	(via
		(at 481.76434 -49.37252)
		(size 0.508)
		(drill 0.254)
		(layers "F.Cu" "B.Cu")
		(net "PU_JTAG_SPRV_TDI")
	)
	(segment
		(start 481.76434 -49.31156)
		(end 482.1555 -48.9204)
		(width 0.10795)
		(layer "B.Cu")
		(net "PU_JTAG_SPRV_TDI")
	)
	(segment
		(start 482.1555 -48.9204)
		(end 482.1555 -48.514)
		(width 0.10795)
		(layer "B.Cu")
		(net "PU_JTAG_SPRV_TDI")
	)
	(segment
		(start 481.76434 -49.37252)
		(end 481.76434 -49.31156)
		(width 0.10795)
		(layer "B.Cu")
		(net "PU_JTAG_SPRV_TDI")
	)
	(segment
		(start 487.0323 -49.7967)
		(end 486.924096 -49.688496)
		(width 0.10795)
		(layer "F.Cu")
		(net "PU_JTAG_SPRV_TCK")
	)
	(segment
		(start 486.924096 -49.1744)
		(end 487.001058 -49.097438)
		(width 0.10795)
		(layer "F.Cu")
		(net "PU_JTAG_SPRV_TCK")
	)
	(segment
		(start 486.924096 -49.688496)
		(end 486.924096 -49.1744)
		(width 0.10795)
		(layer "F.Cu")
		(net "PU_JTAG_SPRV_TCK")
	)
	(segment
		(start 487.001058 -49.097438)
		(end 487.001058 -48.3362)
		(width 0.10795)
		(layer "F.Cu")
		(net "PU_JTAG_SPRV_TCK")
	)
	(segment
		(start 487.6292 -49.7967)
		(end 487.0323 -49.7967)
		(width 0.10795)
		(layer "F.Cu")
		(net "PU_JTAG_SPRV_TCK")
	)
	(via
		(at 486.8418 -49.9618)
		(size 0.6604)
		(drill 0.3302)
		(layers "F.Cu" "B.Cu")
		(net "PU_JTAG_SPRV_TCK")
	)
	(via
		(at 486.924096 -49.1744)
		(size 0.508)
		(drill 0.254)
		(layers "F.Cu" "B.Cu")
		(net "PU_JTAG_SPRV_TCK")
	)
	(segment
		(start 486.924096 -49.879504)
		(end 486.924096 -49.1744)
		(width 0.10795)
		(layer "B.Cu")
		(net "PU_JTAG_SPRV_TCK")
	)
	(segment
		(start 486.8418 -49.9618)
		(end 486.924096 -49.879504)
		(width 0.10795)
		(layer "B.Cu")
		(net "PU_JTAG_SPRV_TCK")
	)
	(segment
		(start 385.811268 -92.521532)
		(end 385.624578 -92.708222)
		(width 0.0889)
		(layer "F.Cu")
		(net "FM_TPM_PRES_N")
	)
	(segment
		(start 386.18795 -90.012266)
		(end 386.142992 -90.012266)
		(width 0.10795)
		(layer "F.Cu")
		(net "FM_TPM_PRES_N")
	)
	(segment
		(start 385.624578 -92.708222)
		(end 385.624578 -92.714318)
		(width 0.0889)
		(layer "F.Cu")
		(net "FM_TPM_PRES_N")
	)
	(segment
		(start 423.090086 -43.334686)
		(end 423.090086 -43.678348)
		(width 0.089408)
		(layer "F.Cu")
		(net "FM_TPM_PRES_N")
	)
	(segment
		(start 385.807966 -93.842586)
		(end 385.807966 -94.104968)
		(width 0.0889)
		(layer "F.Cu")
		(net "FM_TPM_PRES_N")
	)
	(segment
		(start 385.675632 -93.17101)
		(end 385.675632 -93.171772)
		(width 0.0889)
		(layer "F.Cu")
		(net "FM_TPM_PRES_N")
	)
	(segment
		(start 385.675632 -93.171772)
		(end 385.689602 -93.185742)
		(width 0.0889)
		(layer "F.Cu")
		(net "FM_TPM_PRES_N")
	)
	(segment
		(start 385.74726 -90.407998)
		(end 385.74726 -91.147138)
		(width 0.10795)
		(layer "F.Cu")
		(net "FM_TPM_PRES_N")
	)
	(segment
		(start 385.689602 -93.724222)
		(end 385.807966 -93.842586)
		(width 0.0889)
		(layer "F.Cu")
		(net "FM_TPM_PRES_N")
	)
	(segment
		(start 423.090086 -43.678348)
		(end 422.926002 -43.842432)
		(width 0.089408)
		(layer "F.Cu")
		(net "FM_TPM_PRES_N")
	)
	(segment
		(start 385.485132 -94.789752)
		(end 385.484878 -94.790006)
		(width 0.0889)
		(layer "F.Cu")
		(net "FM_TPM_PRES_N")
	)
	(segment
		(start 385.689602 -93.185742)
		(end 385.689602 -93.724222)
		(width 0.0889)
		(layer "F.Cu")
		(net "FM_TPM_PRES_N")
	)
	(segment
		(start 386.188966 -90.012266)
		(end 386.18795 -90.012266)
		(width 0.10795)
		(layer "F.Cu")
		(net "FM_TPM_PRES_N")
	)
	(segment
		(start 385.74726 -91.147138)
		(end 385.811268 -91.211146)
		(width 0.10795)
		(layer "F.Cu")
		(net "FM_TPM_PRES_N")
	)
	(segment
		(start 385.485132 -94.427802)
		(end 385.485132 -94.789752)
		(width 0.0889)
		(layer "F.Cu")
		(net "FM_TPM_PRES_N")
	)
	(segment
		(start 385.811268 -91.759532)
		(end 385.811268 -92.521532)
		(width 0.0889)
		(layer "F.Cu")
		(net "FM_TPM_PRES_N")
	)
	(segment
		(start 385.624578 -92.714318)
		(end 385.586478 -92.752418)
		(width 0.0889)
		(layer "F.Cu")
		(net "FM_TPM_PRES_N")
	)
	(segment
		(start 385.586478 -92.752418)
		(end 385.586478 -93.081856)
		(width 0.0889)
		(layer "F.Cu")
		(net "FM_TPM_PRES_N")
	)
	(segment
		(start 385.586478 -93.081856)
		(end 385.675632 -93.17101)
		(width 0.0889)
		(layer "F.Cu")
		(net "FM_TPM_PRES_N")
	)
	(segment
		(start 385.807966 -94.104968)
		(end 385.485132 -94.427802)
		(width 0.0889)
		(layer "F.Cu")
		(net "FM_TPM_PRES_N")
	)
	(segment
		(start 385.811268 -91.211146)
		(end 385.811268 -91.759532)
		(width 0.10795)
		(layer "F.Cu")
		(net "FM_TPM_PRES_N")
	)
	(segment
		(start 386.08 -89.904316)
		(end 386.08 -88.2015)
		(width 0.10795)
		(layer "F.Cu")
		(net "FM_TPM_PRES_N")
	)
	(segment
		(start 386.18795 -90.012266)
		(end 386.08 -89.904316)
		(width 0.10795)
		(layer "F.Cu")
		(net "FM_TPM_PRES_N")
	)
	(segment
		(start 386.142992 -90.012266)
		(end 385.74726 -90.407998)
		(width 0.10795)
		(layer "F.Cu")
		(net "FM_TPM_PRES_N")
	)
	(via
		(at 439.02884 -18.1102)
		(size 0.6604)
		(drill 0.3302)
		(layers "F.Cu" "B.Cu")
		(net "FM_TPM_PRES_N")
	)
	(via
		(at 386.188966 -90.012266)
		(size 0.508)
		(drill 0.254)
		(layers "F.Cu" "B.Cu")
		(net "FM_TPM_PRES_N")
	)
	(via
		(at 433.98694 -21.620734)
		(size 0.508)
		(drill 0.254)
		(layers "F.Cu" "B.Cu")
		(net "FM_TPM_PRES_N")
	)
	(via
		(at 422.926002 -43.842432)
		(size 0.4572)
		(drill 0.2032)
		(layers "F.Cu" "B.Cu")
		(net "FM_TPM_PRES_N")
	)
	(segment
		(start 445.06134 -18.69694)
		(end 445.06134 -19.07794)
		(width 0.10795)
		(layer "B.Cu")
		(net "FM_TPM_PRES_N")
	)
	(segment
		(start 439.94578 -17.99082)
		(end 444.35522 -17.99082)
		(width 0.10795)
		(layer "B.Cu")
		(net "FM_TPM_PRES_N")
	)
	(segment
		(start 439.02884 -18.1102)
		(end 439.8264 -18.1102)
		(width 0.10795)
		(layer "B.Cu")
		(net "FM_TPM_PRES_N")
	)
	(segment
		(start 436.753 -17.399)
		(end 437.315102 -17.399)
		(width 0.10795)
		(layer "B.Cu")
		(net "FM_TPM_PRES_N")
	)
	(segment
		(start 433.98694 -20.749514)
		(end 436.4736 -18.262854)
		(width 0.10795)
		(layer "B.Cu")
		(net "FM_TPM_PRES_N")
	)
	(segment
		(start 438.026302 -18.1102)
		(end 439.02884 -18.1102)
		(width 0.10795)
		(layer "B.Cu")
		(net "FM_TPM_PRES_N")
	)
	(segment
		(start 439.8264 -18.1102)
		(end 439.94578 -17.99082)
		(width 0.10795)
		(layer "B.Cu")
		(net "FM_TPM_PRES_N")
	)
	(segment
		(start 437.315102 -17.399)
		(end 438.026302 -18.1102)
		(width 0.10795)
		(layer "B.Cu")
		(net "FM_TPM_PRES_N")
	)
	(segment
		(start 436.4736 -17.6784)
		(end 436.753 -17.399)
		(width 0.10795)
		(layer "B.Cu")
		(net "FM_TPM_PRES_N")
	)
	(segment
		(start 433.98694 -21.620734)
		(end 433.98694 -20.749514)
		(width 0.10795)
		(layer "B.Cu")
		(net "FM_TPM_PRES_N")
	)
	(segment
		(start 445.06134 -19.07794)
		(end 445.27216 -19.28876)
		(width 0.10795)
		(layer "B.Cu")
		(net "FM_TPM_PRES_N")
	)
	(segment
		(start 445.27216 -19.28876)
		(end 446.2145 -19.28876)
		(width 0.10795)
		(layer "B.Cu")
		(net "FM_TPM_PRES_N")
	)
	(segment
		(start 444.35522 -17.99082)
		(end 445.06134 -18.69694)
		(width 0.10795)
		(layer "B.Cu")
		(net "FM_TPM_PRES_N")
	)
	(segment
		(start 436.4736 -18.262854)
		(end 436.4736 -17.6784)
		(width 0.10795)
		(layer "B.Cu")
		(net "FM_TPM_PRES_N")
	)
	(segment
		(start 391.7442 -47.1805)
		(end 391.7442 -51.153314)
		(width 0.089408)
		(layer "In2.Cu")
		(net "FM_TPM_PRES_N")
	)
	(segment
		(start 411.476952 -44.589954)
		(end 411.47238 -44.585382)
		(width 0.089408)
		(layer "In2.Cu")
		(net "FM_TPM_PRES_N")
	)
	(segment
		(start 397.1798 -46.3296)
		(end 391.7315 -46.3296)
		(width 0.089408)
		(layer "In2.Cu")
		(net "FM_TPM_PRES_N")
	)
	(segment
		(start 386.928614 -87.10168)
		(end 386.08 -87.950294)
		(width 0.089408)
		(layer "In2.Cu")
		(net "FM_TPM_PRES_N")
	)
	(segment
		(start 389.188198 -75.824842)
		(end 389.188452 -75.825096)
		(width 0.089408)
		(layer "In2.Cu")
		(net "FM_TPM_PRES_N")
	)
	(segment
		(start 387.510528 -85.87105)
		(end 386.928614 -86.452964)
		(width 0.089408)
		(layer "In2.Cu")
		(net "FM_TPM_PRES_N")
	)
	(segment
		(start 388.815072 -77.386942)
		(end 389.149082 -77.720952)
		(width 0.089408)
		(layer "In2.Cu")
		(net "FM_TPM_PRES_N")
	)
	(segment
		(start 418.109654 -44.585382)
		(end 418.105082 -44.589954)
		(width 0.089408)
		(layer "In2.Cu")
		(net "FM_TPM_PRES_N")
	)
	(segment
		(start 389.526272 -68.470272)
		(end 390.400032 -69.344032)
		(width 0.089408)
		(layer "In2.Cu")
		(net "FM_TPM_PRES_N")
	)
	(segment
		(start 418.105082 -44.589954)
		(end 411.476952 -44.589954)
		(width 0.089408)
		(layer "In2.Cu")
		(net "FM_TPM_PRES_N")
	)
	(segment
		(start 410.77134 -44.269406)
		(end 410.771086 -44.269152)
		(width 0.089408)
		(layer "In2.Cu")
		(net "FM_TPM_PRES_N")
	)
	(segment
		(start 386.08 -87.950294)
		(end 386.08 -89.922858)
		(width 0.089408)
		(layer "In2.Cu")
		(net "FM_TPM_PRES_N")
	)
	(segment
		(start 404.253192 -44.5135)
		(end 404.196296 -44.570396)
		(width 0.089408)
		(layer "In2.Cu")
		(net "FM_TPM_PRES_N")
	)
	(segment
		(start 389.188452 -75.983084)
		(end 389.187944 -75.983592)
		(width 0.089408)
		(layer "In2.Cu")
		(net "FM_TPM_PRES_N")
	)
	(segment
		(start 410.771086 -44.269152)
		(end 410.613098 -44.269152)
		(width 0.089408)
		(layer "In2.Cu")
		(net "FM_TPM_PRES_N")
	)
	(segment
		(start 389.149082 -77.720952)
		(end 389.149082 -78.037436)
		(width 0.089408)
		(layer "In2.Cu")
		(net "FM_TPM_PRES_N")
	)
	(segment
		(start 387.872732 -85.87105)
		(end 387.872478 -85.871304)
		(width 0.089408)
		(layer "In2.Cu")
		(net "FM_TPM_PRES_N")
	)
	(segment
		(start 389.149336 -78.819502)
		(end 389.149336 -78.97749)
		(width 0.089408)
		(layer "In2.Cu")
		(net "FM_TPM_PRES_N")
	)
	(segment
		(start 393.55903 -52.968144)
		(end 393.55903 -62.586616)
		(width 0.089408)
		(layer "In2.Cu")
		(net "FM_TPM_PRES_N")
	)
	(segment
		(start 411.463236 -44.585382)
		(end 411.14726 -44.269406)
		(width 0.089408)
		(layer "In2.Cu")
		(net "FM_TPM_PRES_N")
	)
	(segment
		(start 389.188198 -75.666854)
		(end 389.188198 -75.824842)
		(width 0.089408)
		(layer "In2.Cu")
		(net "FM_TPM_PRES_N")
	)
	(segment
		(start 387.872478 -85.871304)
		(end 387.555994 -85.871304)
		(width 0.089408)
		(layer "In2.Cu")
		(net "FM_TPM_PRES_N")
	)
	(segment
		(start 388.809992 -82.756502)
		(end 389.128254 -83.074764)
		(width 0.089408)
		(layer "In2.Cu")
		(net "FM_TPM_PRES_N")
	)
	(segment
		(start 386.08 -89.922858)
		(end 386.169408 -90.012266)
		(width 0.089408)
		(layer "In2.Cu")
		(net "FM_TPM_PRES_N")
	)
	(segment
		(start 389.128508 -83.105498)
		(end 389.128508 -84.675726)
		(width 0.089408)
		(layer "In2.Cu")
		(net "FM_TPM_PRES_N")
	)
	(segment
		(start 420.841932 -44.585128)
		(end 418.831522 -44.585128)
		(width 0.089408)
		(layer "In2.Cu")
		(net "FM_TPM_PRES_N")
	)
	(segment
		(start 391.833862 -64.734186)
		(end 389.526272 -67.041776)
		(width 0.089408)
		(layer "In2.Cu")
		(net "FM_TPM_PRES_N")
	)
	(segment
		(start 387.555994 -85.871304)
		(end 387.55574 -85.87105)
		(width 0.089408)
		(layer "In2.Cu")
		(net "FM_TPM_PRES_N")
	)
	(segment
		(start 389.149082 -79.135732)
		(end 389.148828 -79.135986)
		(width 0.089408)
		(layer "In2.Cu")
		(net "FM_TPM_PRES_N")
	)
	(segment
		(start 389.149082 -78.037436)
		(end 389.148828 -78.03769)
		(width 0.089408)
		(layer "In2.Cu")
		(net "FM_TPM_PRES_N")
	)
	(segment
		(start 404.478998 -44.513754)
		(end 404.478744 -44.5135)
		(width 0.089408)
		(layer "In2.Cu")
		(net "FM_TPM_PRES_N")
	)
	(segment
		(start 389.128254 -83.074764)
		(end 389.128254 -83.105244)
		(width 0.089408)
		(layer "In2.Cu")
		(net "FM_TPM_PRES_N")
	)
	(segment
		(start 389.148828 -79.135986)
		(end 389.148828 -81.846928)
		(width 0.089408)
		(layer "In2.Cu")
		(net "FM_TPM_PRES_N")
	)
	(segment
		(start 410.612844 -44.269406)
		(end 410.460444 -44.269406)
		(width 0.089408)
		(layer "In2.Cu")
		(net "FM_TPM_PRES_N")
	)
	(segment
		(start 404.196296 -44.570396)
		(end 404.057358 -44.570396)
		(width 0.089408)
		(layer "In2.Cu")
		(net "FM_TPM_PRES_N")
	)
	(segment
		(start 388.809992 -82.185764)
		(end 388.809992 -82.756502)
		(width 0.089408)
		(layer "In2.Cu")
		(net "FM_TPM_PRES_N")
	)
	(segment
		(start 389.188452 -75.825096)
		(end 389.188452 -75.983084)
		(width 0.089408)
		(layer "In2.Cu")
		(net "FM_TPM_PRES_N")
	)
	(segment
		(start 411.14726 -44.269406)
		(end 410.77134 -44.269406)
		(width 0.089408)
		(layer "In2.Cu")
		(net "FM_TPM_PRES_N")
	)
	(segment
		(start 410.613098 -44.269152)
		(end 410.612844 -44.269406)
		(width 0.089408)
		(layer "In2.Cu")
		(net "FM_TPM_PRES_N")
	)
	(segment
		(start 410.302202 -44.269152)
		(end 410.0576 -44.513754)
		(width 0.089408)
		(layer "In2.Cu")
		(net "FM_TPM_PRES_N")
	)
	(segment
		(start 410.0576 -44.513754)
		(end 404.478998 -44.513754)
		(width 0.089408)
		(layer "In2.Cu")
		(net "FM_TPM_PRES_N")
	)
	(segment
		(start 390.400032 -69.344032)
		(end 390.400032 -73.386188)
		(width 0.089408)
		(layer "In2.Cu")
		(net "FM_TPM_PRES_N")
	)
	(segment
		(start 389.187944 -75.983592)
		(end 389.187944 -76.013818)
		(width 0.089408)
		(layer "In2.Cu")
		(net "FM_TPM_PRES_N")
	)
	(segment
		(start 391.63244 -47.068232)
		(end 391.63244 -47.06874)
		(width 0.089408)
		(layer "In2.Cu")
		(net "FM_TPM_PRES_N")
	)
	(segment
		(start 389.128508 -84.675726)
		(end 387.933184 -85.87105)
		(width 0.089408)
		(layer "In2.Cu")
		(net "FM_TPM_PRES_N")
	)
	(segment
		(start 389.526272 -67.041776)
		(end 389.526272 -68.470272)
		(width 0.089408)
		(layer "In2.Cu")
		(net "FM_TPM_PRES_N")
	)
	(segment
		(start 386.169408 -90.012266)
		(end 386.188966 -90.012266)
		(width 0.089408)
		(layer "In2.Cu")
		(net "FM_TPM_PRES_N")
	)
	(segment
		(start 389.187944 -74.618088)
		(end 389.187944 -75.6666)
		(width 0.089408)
		(layer "In2.Cu")
		(net "FM_TPM_PRES_N")
	)
	(segment
		(start 389.187944 -75.6666)
		(end 389.188198 -75.666854)
		(width 0.089408)
		(layer "In2.Cu")
		(net "FM_TPM_PRES_N")
	)
	(segment
		(start 418.831268 -44.585382)
		(end 418.109654 -44.585382)
		(width 0.089408)
		(layer "In2.Cu")
		(net "FM_TPM_PRES_N")
	)
	(segment
		(start 402.09597 -46.531784)
		(end 397.381984 -46.531784)
		(width 0.089408)
		(layer "In2.Cu")
		(net "FM_TPM_PRES_N")
	)
	(segment
		(start 391.7315 -46.3296)
		(end 391.414 -46.6471)
		(width 0.089408)
		(layer "In2.Cu")
		(net "FM_TPM_PRES_N")
	)
	(segment
		(start 391.414 -46.6471)
		(end 391.414 -46.849792)
		(width 0.089408)
		(layer "In2.Cu")
		(net "FM_TPM_PRES_N")
	)
	(segment
		(start 391.414 -46.849792)
		(end 391.63244 -47.068232)
		(width 0.089408)
		(layer "In2.Cu")
		(net "FM_TPM_PRES_N")
	)
	(segment
		(start 389.187944 -76.013818)
		(end 388.815072 -76.38669)
		(width 0.089408)
		(layer "In2.Cu")
		(net "FM_TPM_PRES_N")
	)
	(segment
		(start 389.128254 -83.105244)
		(end 389.128508 -83.105498)
		(width 0.089408)
		(layer "In2.Cu")
		(net "FM_TPM_PRES_N")
	)
	(segment
		(start 387.55574 -85.87105)
		(end 387.510528 -85.87105)
		(width 0.089408)
		(layer "In2.Cu")
		(net "FM_TPM_PRES_N")
	)
	(segment
		(start 393.55903 -62.586616)
		(end 391.833862 -64.311784)
		(width 0.089408)
		(layer "In2.Cu")
		(net "FM_TPM_PRES_N")
	)
	(segment
		(start 389.149336 -78.97749)
		(end 389.149082 -78.977744)
		(width 0.089408)
		(layer "In2.Cu")
		(net "FM_TPM_PRES_N")
	)
	(segment
		(start 388.815072 -76.38669)
		(end 388.815072 -77.386942)
		(width 0.089408)
		(layer "In2.Cu")
		(net "FM_TPM_PRES_N")
	)
	(segment
		(start 422.926002 -43.842432)
		(end 422.183052 -44.585382)
		(width 0.089408)
		(layer "In2.Cu")
		(net "FM_TPM_PRES_N")
	)
	(segment
		(start 389.148828 -78.03769)
		(end 389.148828 -78.818994)
		(width 0.089408)
		(layer "In2.Cu")
		(net "FM_TPM_PRES_N")
	)
	(segment
		(start 386.928614 -86.452964)
		(end 386.928614 -87.10168)
		(width 0.089408)
		(layer "In2.Cu")
		(net "FM_TPM_PRES_N")
	)
	(segment
		(start 391.7442 -51.153314)
		(end 393.55903 -52.968144)
		(width 0.089408)
		(layer "In2.Cu")
		(net "FM_TPM_PRES_N")
	)
	(segment
		(start 389.444992 -74.341228)
		(end 389.444992 -74.36104)
		(width 0.089408)
		(layer "In2.Cu")
		(net "FM_TPM_PRES_N")
	)
	(segment
		(start 404.057358 -44.570396)
		(end 402.09597 -46.531784)
		(width 0.089408)
		(layer "In2.Cu")
		(net "FM_TPM_PRES_N")
	)
	(segment
		(start 410.460444 -44.269406)
		(end 410.46019 -44.269152)
		(width 0.089408)
		(layer "In2.Cu")
		(net "FM_TPM_PRES_N")
	)
	(segment
		(start 389.444992 -74.36104)
		(end 389.187944 -74.618088)
		(width 0.089408)
		(layer "In2.Cu")
		(net "FM_TPM_PRES_N")
	)
	(segment
		(start 389.148828 -78.818994)
		(end 389.149336 -78.819502)
		(width 0.089408)
		(layer "In2.Cu")
		(net "FM_TPM_PRES_N")
	)
	(segment
		(start 391.833862 -64.311784)
		(end 391.833862 -64.734186)
		(width 0.089408)
		(layer "In2.Cu")
		(net "FM_TPM_PRES_N")
	)
	(segment
		(start 387.933184 -85.87105)
		(end 387.872732 -85.87105)
		(width 0.089408)
		(layer "In2.Cu")
		(net "FM_TPM_PRES_N")
	)
	(segment
		(start 404.478744 -44.5135)
		(end 404.253192 -44.5135)
		(width 0.089408)
		(layer "In2.Cu")
		(net "FM_TPM_PRES_N")
	)
	(segment
		(start 389.149082 -78.977744)
		(end 389.149082 -79.135732)
		(width 0.089408)
		(layer "In2.Cu")
		(net "FM_TPM_PRES_N")
	)
	(segment
		(start 420.842186 -44.585382)
		(end 420.841932 -44.585128)
		(width 0.089408)
		(layer "In2.Cu")
		(net "FM_TPM_PRES_N")
	)
	(segment
		(start 418.831522 -44.585128)
		(end 418.831268 -44.585382)
		(width 0.089408)
		(layer "In2.Cu")
		(net "FM_TPM_PRES_N")
	)
	(segment
		(start 411.47238 -44.585382)
		(end 411.463236 -44.585382)
		(width 0.089408)
		(layer "In2.Cu")
		(net "FM_TPM_PRES_N")
	)
	(segment
		(start 410.46019 -44.269152)
		(end 410.302202 -44.269152)
		(width 0.089408)
		(layer "In2.Cu")
		(net "FM_TPM_PRES_N")
	)
	(segment
		(start 390.400032 -73.386188)
		(end 389.444992 -74.341228)
		(width 0.089408)
		(layer "In2.Cu")
		(net "FM_TPM_PRES_N")
	)
	(segment
		(start 391.63244 -47.06874)
		(end 391.7442 -47.1805)
		(width 0.089408)
		(layer "In2.Cu")
		(net "FM_TPM_PRES_N")
	)
	(segment
		(start 422.183052 -44.585382)
		(end 420.842186 -44.585382)
		(width 0.089408)
		(layer "In2.Cu")
		(net "FM_TPM_PRES_N")
	)
	(segment
		(start 397.381984 -46.531784)
		(end 397.1798 -46.3296)
		(width 0.089408)
		(layer "In2.Cu")
		(net "FM_TPM_PRES_N")
	)
	(segment
		(start 389.148828 -81.846928)
		(end 388.809992 -82.185764)
		(width 0.089408)
		(layer "In2.Cu")
		(net "FM_TPM_PRES_N")
	)
	(segment
		(start 418.6301 -36.62426)
		(end 418.95522 -36.94938)
		(width 0.089408)
		(layer "In9.Cu")
		(net "FM_TPM_PRES_N")
	)
	(segment
		(start 422.045638 -40.96004)
		(end 422.055036 -40.969438)
		(width 0.089408)
		(layer "In9.Cu")
		(net "FM_TPM_PRES_N")
	)
	(segment
		(start 422.055036 -40.969438)
		(end 422.083484 -40.969438)
		(width 0.089408)
		(layer "In9.Cu")
		(net "FM_TPM_PRES_N")
	)
	(segment
		(start 422.083484 -40.969438)
		(end 422.5163 -41.402254)
		(width 0.089408)
		(layer "In9.Cu")
		(net "FM_TPM_PRES_N")
	)
	(segment
		(start 422.5163 -41.402254)
		(end 422.5163 -43.43273)
		(width 0.089408)
		(layer "In9.Cu")
		(net "FM_TPM_PRES_N")
	)
	(segment
		(start 421.753792 -40.96004)
		(end 422.045638 -40.96004)
		(width 0.089408)
		(layer "In9.Cu")
		(net "FM_TPM_PRES_N")
	)
	(segment
		(start 419.11016 -32.139636)
		(end 418.939218 -32.310578)
		(width 0.089408)
		(layer "In9.Cu")
		(net "FM_TPM_PRES_N")
	)
	(segment
		(start 418.939218 -32.310578)
		(end 418.939218 -33.371282)
		(width 0.089408)
		(layer "In9.Cu")
		(net "FM_TPM_PRES_N")
	)
	(segment
		(start 421.3225 -36.94938)
		(end 421.50792 -37.1348)
		(width 0.089408)
		(layer "In9.Cu")
		(net "FM_TPM_PRES_N")
	)
	(segment
		(start 426.689774 -24.555958)
		(end 425.79925 -25.446482)
		(width 0.089408)
		(layer "In9.Cu")
		(net "FM_TPM_PRES_N")
	)
	(segment
		(start 425.79925 -25.446482)
		(end 425.79925 -26.353262)
		(width 0.089408)
		(layer "In9.Cu")
		(net "FM_TPM_PRES_N")
	)
	(segment
		(start 433.98694 -21.620734)
		(end 434.4924 -22.126194)
		(width 0.089408)
		(layer "In9.Cu")
		(net "FM_TPM_PRES_N")
	)
	(segment
		(start 425.79671 -29.915104)
		(end 423.572178 -32.139636)
		(width 0.089408)
		(layer "In9.Cu")
		(net "FM_TPM_PRES_N")
	)
	(segment
		(start 425.79925 -26.353262)
		(end 425.79671 -26.355802)
		(width 0.089408)
		(layer "In9.Cu")
		(net "FM_TPM_PRES_N")
	)
	(segment
		(start 434.524912 -22.437598)
		(end 434.549804 -22.46249)
		(width 0.089408)
		(layer "In9.Cu")
		(net "FM_TPM_PRES_N")
	)
	(segment
		(start 434.4924 -22.126194)
		(end 434.4924 -22.351492)
		(width 0.089408)
		(layer "In9.Cu")
		(net "FM_TPM_PRES_N")
	)
	(segment
		(start 418.95522 -36.94938)
		(end 421.3225 -36.94938)
		(width 0.089408)
		(layer "In9.Cu")
		(net "FM_TPM_PRES_N")
	)
	(segment
		(start 422.5163 -43.43273)
		(end 422.926002 -43.842432)
		(width 0.089408)
		(layer "In9.Cu")
		(net "FM_TPM_PRES_N")
	)
	(segment
		(start 421.50792 -37.1348)
		(end 421.50792 -40.714168)
		(width 0.089408)
		(layer "In9.Cu")
		(net "FM_TPM_PRES_N")
	)
	(segment
		(start 434.4924 -22.351492)
		(end 434.524912 -22.384004)
		(width 0.089408)
		(layer "In9.Cu")
		(net "FM_TPM_PRES_N")
	)
	(segment
		(start 418.939218 -33.371282)
		(end 418.6301 -33.6804)
		(width 0.089408)
		(layer "In9.Cu")
		(net "FM_TPM_PRES_N")
	)
	(segment
		(start 434.4924 -22.851618)
		(end 434.4924 -23.4188)
		(width 0.089408)
		(layer "In9.Cu")
		(net "FM_TPM_PRES_N")
	)
	(segment
		(start 434.4924 -23.4188)
		(end 433.355242 -24.555958)
		(width 0.089408)
		(layer "In9.Cu")
		(net "FM_TPM_PRES_N")
	)
	(segment
		(start 423.572178 -32.139636)
		(end 419.11016 -32.139636)
		(width 0.089408)
		(layer "In9.Cu")
		(net "FM_TPM_PRES_N")
	)
	(segment
		(start 434.524912 -22.384004)
		(end 434.524912 -22.437598)
		(width 0.089408)
		(layer "In9.Cu")
		(net "FM_TPM_PRES_N")
	)
	(segment
		(start 418.6301 -33.6804)
		(end 418.6301 -36.62426)
		(width 0.089408)
		(layer "In9.Cu")
		(net "FM_TPM_PRES_N")
	)
	(segment
		(start 425.79671 -26.355802)
		(end 425.79671 -29.915104)
		(width 0.089408)
		(layer "In9.Cu")
		(net "FM_TPM_PRES_N")
	)
	(segment
		(start 434.549804 -22.46249)
		(end 434.549804 -22.794214)
		(width 0.089408)
		(layer "In9.Cu")
		(net "FM_TPM_PRES_N")
	)
	(segment
		(start 421.50792 -40.714168)
		(end 421.753792 -40.96004)
		(width 0.089408)
		(layer "In9.Cu")
		(net "FM_TPM_PRES_N")
	)
	(segment
		(start 434.549804 -22.794214)
		(end 434.4924 -22.851618)
		(width 0.089408)
		(layer "In9.Cu")
		(net "FM_TPM_PRES_N")
	)
	(segment
		(start 433.355242 -24.555958)
		(end 426.689774 -24.555958)
		(width 0.089408)
		(layer "In9.Cu")
		(net "FM_TPM_PRES_N")
	)
	(segment
		(start 387.73735 -117.58168)
		(end 388.23265 -117.811804)
		(width 0.10795)
		(layer "F.Cu")
		(net "TP_PCH_RSVD36")
	)
	(via
		(at 388.23265 -117.811804)
		(size 0.508)
		(drill 0.254)
		(layers "F.Cu" "B.Cu")
		(net "TP_PCH_RSVD36")
	)
	(segment
		(start 468.5411 -45.9105)
		(end 468.5411 -47.481998)
		(width 0.10795)
		(layer "F.Cu")
		(net "RST_PCIE_CPU_DEV3_R_N")
	)
	(segment
		(start 468.8078 -45.6438)
		(end 468.5411 -45.9105)
		(width 0.10795)
		(layer "F.Cu")
		(net "RST_PCIE_CPU_DEV3_R_N")
	)
	(via
		(at 468.8078 -45.6438)
		(size 0.508)
		(drill 0.254)
		(layers "F.Cu" "B.Cu")
		(net "RST_PCIE_CPU_DEV3_R_N")
	)
	(segment
		(start 468.63 -45.8216)
		(end 468.63 -46.6725)
		(width 0.10795)
		(layer "B.Cu")
		(net "RST_PCIE_CPU_DEV3_R_N")
	)
	(segment
		(start 468.8078 -45.6438)
		(end 468.63 -45.8216)
		(width 0.10795)
		(layer "B.Cu")
		(net "RST_PCIE_CPU_DEV3_R_N")
	)
	(segment
		(start 379.24105 -73.89495)
		(end 378.744988 -73.89495)
		(width 0.1016)
		(layer "F.Cu")
		(net "RST_PCIE_CPU_DEV3_N")
	)
	(segment
		(start 380.143512 -73.26376)
		(end 379.87224 -73.26376)
		(width 0.1016)
		(layer "F.Cu")
		(net "RST_PCIE_CPU_DEV3_N")
	)
	(segment
		(start 379.87224 -73.26376)
		(end 379.24105 -73.89495)
		(width 0.1016)
		(layer "F.Cu")
		(net "RST_PCIE_CPU_DEV3_N")
	)
	(via
		(at 380.143512 -73.26376)
		(size 0.508)
		(drill 0.254)
		(layers "F.Cu" "B.Cu")
		(net "RST_PCIE_CPU_DEV3_N")
	)
	(via
		(at 432.181 -52.9844)
		(size 0.6604)
		(drill 0.3302)
		(layers "F.Cu" "B.Cu")
		(net "RST_PCIE_CPU_DEV3_N")
	)
	(segment
		(start 400.622008 -65.322196)
		(end 400.621754 -65.321942)
		(width 0.10795)
		(layer "B.Cu")
		(net "RST_PCIE_CPU_DEV3_N")
	)
	(segment
		(start 407.722832 -60.033662)
		(end 411.412436 -60.033662)
		(width 0.10795)
		(layer "B.Cu")
		(net "RST_PCIE_CPU_DEV3_N")
	)
	(segment
		(start 436.701438 -54.936898)
		(end 434.74894 -52.9844)
		(width 0.10795)
		(layer "B.Cu")
		(net "RST_PCIE_CPU_DEV3_N")
	)
	(segment
		(start 406.59939 -61.157104)
		(end 407.722832 -60.033662)
		(width 0.10795)
		(layer "B.Cu")
		(net "RST_PCIE_CPU_DEV3_N")
	)
	(segment
		(start 383.69367 -75.15987)
		(end 385.432046 -75.15987)
		(width 0.10795)
		(layer "B.Cu")
		(net "RST_PCIE_CPU_DEV3_N")
	)
	(segment
		(start 424.766994 -53.921914)
		(end 426.834808 -53.921914)
		(width 0.10795)
		(layer "B.Cu")
		(net "RST_PCIE_CPU_DEV3_N")
	)
	(segment
		(start 423.952162 -53.107082)
		(end 424.766994 -53.921914)
		(width 0.10795)
		(layer "B.Cu")
		(net "RST_PCIE_CPU_DEV3_N")
	)
	(segment
		(start 400.621754 -65.321942)
		(end 400.621754 -64.839342)
		(width 0.10795)
		(layer "B.Cu")
		(net "RST_PCIE_CPU_DEV3_N")
	)
	(segment
		(start 417.784788 -56.902604)
		(end 420.623746 -54.063646)
		(width 0.10795)
		(layer "B.Cu")
		(net "RST_PCIE_CPU_DEV3_N")
	)
	(segment
		(start 400.205702 -66.424048)
		(end 400.205702 -65.933066)
		(width 0.10795)
		(layer "B.Cu")
		(net "RST_PCIE_CPU_DEV3_N")
	)
	(segment
		(start 417.169854 -56.902604)
		(end 417.784788 -56.902604)
		(width 0.10795)
		(layer "B.Cu")
		(net "RST_PCIE_CPU_DEV3_N")
	)
	(segment
		(start 405.19223 -61.14796)
		(end 405.201374 -61.157104)
		(width 0.10795)
		(layer "B.Cu")
		(net "RST_PCIE_CPU_DEV3_N")
	)
	(segment
		(start 468.63 -47.5615)
		(end 468.63 -50.672746)
		(width 0.10795)
		(layer "B.Cu")
		(net "RST_PCIE_CPU_DEV3_N")
	)
	(segment
		(start 401.204938 -63.274194)
		(end 401.204684 -63.27394)
		(width 0.10795)
		(layer "B.Cu")
		(net "RST_PCIE_CPU_DEV3_N")
	)
	(segment
		(start 403.030944 -61.14796)
		(end 405.19223 -61.14796)
		(width 0.10795)
		(layer "B.Cu")
		(net "RST_PCIE_CPU_DEV3_N")
	)
	(segment
		(start 395.073886 -69.20865)
		(end 395.474698 -69.20865)
		(width 0.10795)
		(layer "B.Cu")
		(net "RST_PCIE_CPU_DEV3_N")
	)
	(segment
		(start 388.376414 -72.184006)
		(end 388.40791 -72.184006)
		(width 0.10795)
		(layer "B.Cu")
		(net "RST_PCIE_CPU_DEV3_N")
	)
	(segment
		(start 396.27048 -69.208396)
		(end 396.603474 -69.208396)
		(width 0.10795)
		(layer "B.Cu")
		(net "RST_PCIE_CPU_DEV3_N")
	)
	(segment
		(start 468.63 -50.672746)
		(end 464.365848 -54.936898)
		(width 0.10795)
		(layer "B.Cu")
		(net "RST_PCIE_CPU_DEV3_N")
	)
	(segment
		(start 397.068802 -68.743068)
		(end 397.886682 -68.743068)
		(width 0.10795)
		(layer "B.Cu")
		(net "RST_PCIE_CPU_DEV3_N")
	)
	(segment
		(start 395.474698 -69.20865)
		(end 395.475206 -69.208142)
		(width 0.10795)
		(layer "B.Cu")
		(net "RST_PCIE_CPU_DEV3_N")
	)
	(segment
		(start 395.475206 -69.208142)
		(end 396.270226 -69.208142)
		(width 0.10795)
		(layer "B.Cu")
		(net "RST_PCIE_CPU_DEV3_N")
	)
	(segment
		(start 401.204684 -63.27394)
		(end 401.204684 -62.97422)
		(width 0.10795)
		(layer "B.Cu")
		(net "RST_PCIE_CPU_DEV3_N")
	)
	(segment
		(start 391.412984 -71.658226)
		(end 391.66292 -71.40829)
		(width 0.10795)
		(layer "B.Cu")
		(net "RST_PCIE_CPU_DEV3_N")
	)
	(segment
		(start 380.143512 -73.26376)
		(end 380.621032 -73.74128)
		(width 0.10795)
		(layer "B.Cu")
		(net "RST_PCIE_CPU_DEV3_N")
	)
	(segment
		(start 400.6215 -64.839088)
		(end 400.6215 -64.74079)
		(width 0.10795)
		(layer "B.Cu")
		(net "RST_PCIE_CPU_DEV3_N")
	)
	(segment
		(start 397.886682 -68.743068)
		(end 400.205702 -66.424048)
		(width 0.10795)
		(layer "B.Cu")
		(net "RST_PCIE_CPU_DEV3_N")
	)
	(segment
		(start 464.365848 -54.936898)
		(end 436.701438 -54.936898)
		(width 0.10795)
		(layer "B.Cu")
		(net "RST_PCIE_CPU_DEV3_N")
	)
	(segment
		(start 420.623746 -54.063646)
		(end 421.046656 -54.063646)
		(width 0.10795)
		(layer "B.Cu")
		(net "RST_PCIE_CPU_DEV3_N")
	)
	(segment
		(start 388.93369 -71.658226)
		(end 391.412984 -71.658226)
		(width 0.10795)
		(layer "B.Cu")
		(net "RST_PCIE_CPU_DEV3_N")
	)
	(segment
		(start 392.874246 -71.40829)
		(end 395.073886 -69.20865)
		(width 0.10795)
		(layer "B.Cu")
		(net "RST_PCIE_CPU_DEV3_N")
	)
	(segment
		(start 387.854698 -72.705722)
		(end 388.376414 -72.184006)
		(width 0.10795)
		(layer "B.Cu")
		(net "RST_PCIE_CPU_DEV3_N")
	)
	(segment
		(start 381.328422 -73.74128)
		(end 381.988568 -74.401426)
		(width 0.10795)
		(layer "B.Cu")
		(net "RST_PCIE_CPU_DEV3_N")
	)
	(segment
		(start 380.621032 -73.74128)
		(end 381.328422 -73.74128)
		(width 0.10795)
		(layer "B.Cu")
		(net "RST_PCIE_CPU_DEV3_N")
	)
	(segment
		(start 391.66292 -71.40829)
		(end 392.874246 -71.40829)
		(width 0.10795)
		(layer "B.Cu")
		(net "RST_PCIE_CPU_DEV3_N")
	)
	(segment
		(start 422.00322 -53.107082)
		(end 423.952162 -53.107082)
		(width 0.10795)
		(layer "B.Cu")
		(net "RST_PCIE_CPU_DEV3_N")
	)
	(segment
		(start 381.988568 -74.401426)
		(end 382.935226 -74.401426)
		(width 0.10795)
		(layer "B.Cu")
		(net "RST_PCIE_CPU_DEV3_N")
	)
	(segment
		(start 400.205702 -65.933066)
		(end 400.622008 -65.51676)
		(width 0.10795)
		(layer "B.Cu")
		(net "RST_PCIE_CPU_DEV3_N")
	)
	(segment
		(start 434.74894 -52.9844)
		(end 432.181 -52.9844)
		(width 0.10795)
		(layer "B.Cu")
		(net "RST_PCIE_CPU_DEV3_N")
	)
	(segment
		(start 421.046656 -54.063646)
		(end 422.00322 -53.107082)
		(width 0.10795)
		(layer "B.Cu")
		(net "RST_PCIE_CPU_DEV3_N")
	)
	(segment
		(start 411.412436 -60.033662)
		(end 412.714186 -58.731912)
		(width 0.10795)
		(layer "B.Cu")
		(net "RST_PCIE_CPU_DEV3_N")
	)
	(segment
		(start 387.854698 -72.737218)
		(end 387.854698 -72.705722)
		(width 0.10795)
		(layer "B.Cu")
		(net "RST_PCIE_CPU_DEV3_N")
	)
	(segment
		(start 396.270226 -69.208142)
		(end 396.27048 -69.208396)
		(width 0.10795)
		(layer "B.Cu")
		(net "RST_PCIE_CPU_DEV3_N")
	)
	(segment
		(start 427.772322 -52.9844)
		(end 432.181 -52.9844)
		(width 0.10795)
		(layer "B.Cu")
		(net "RST_PCIE_CPU_DEV3_N")
	)
	(segment
		(start 426.834808 -53.921914)
		(end 427.772322 -52.9844)
		(width 0.10795)
		(layer "B.Cu")
		(net "RST_PCIE_CPU_DEV3_N")
	)
	(segment
		(start 401.204684 -62.97422)
		(end 403.030944 -61.14796)
		(width 0.10795)
		(layer "B.Cu")
		(net "RST_PCIE_CPU_DEV3_N")
	)
	(segment
		(start 385.432046 -75.15987)
		(end 387.854698 -72.737218)
		(width 0.10795)
		(layer "B.Cu")
		(net "RST_PCIE_CPU_DEV3_N")
	)
	(segment
		(start 400.621754 -64.839342)
		(end 400.6215 -64.839088)
		(width 0.10795)
		(layer "B.Cu")
		(net "RST_PCIE_CPU_DEV3_N")
	)
	(segment
		(start 388.40791 -72.184006)
		(end 388.93369 -71.658226)
		(width 0.10795)
		(layer "B.Cu")
		(net "RST_PCIE_CPU_DEV3_N")
	)
	(segment
		(start 401.204938 -64.157352)
		(end 401.204938 -63.274194)
		(width 0.10795)
		(layer "B.Cu")
		(net "RST_PCIE_CPU_DEV3_N")
	)
	(segment
		(start 396.603474 -69.208396)
		(end 397.068802 -68.743068)
		(width 0.10795)
		(layer "B.Cu")
		(net "RST_PCIE_CPU_DEV3_N")
	)
	(segment
		(start 405.201374 -61.157104)
		(end 406.59939 -61.157104)
		(width 0.10795)
		(layer "B.Cu")
		(net "RST_PCIE_CPU_DEV3_N")
	)
	(segment
		(start 382.935226 -74.401426)
		(end 383.69367 -75.15987)
		(width 0.10795)
		(layer "B.Cu")
		(net "RST_PCIE_CPU_DEV3_N")
	)
	(segment
		(start 400.622008 -65.51676)
		(end 400.622008 -65.322196)
		(width 0.10795)
		(layer "B.Cu")
		(net "RST_PCIE_CPU_DEV3_N")
	)
	(segment
		(start 412.714186 -58.731912)
		(end 415.340546 -58.731912)
		(width 0.10795)
		(layer "B.Cu")
		(net "RST_PCIE_CPU_DEV3_N")
	)
	(segment
		(start 400.6215 -64.74079)
		(end 401.204938 -64.157352)
		(width 0.10795)
		(layer "B.Cu")
		(net "RST_PCIE_CPU_DEV3_N")
	)
	(segment
		(start 415.340546 -58.731912)
		(end 417.169854 -56.902604)
		(width 0.10795)
		(layer "B.Cu")
		(net "RST_PCIE_CPU_DEV3_N")
	)
	(segment
		(start 467.5886 -47.329598)
		(end 467.741 -47.481998)
		(width 0.10795)
		(layer "F.Cu")
		(net "RST_PCIE_CPU_DEV2_R_N")
	)
	(segment
		(start 467.5886 -45.6438)
		(end 467.5886 -47.329598)
		(width 0.10795)
		(layer "F.Cu")
		(net "RST_PCIE_CPU_DEV2_R_N")
	)
	(via
		(at 467.5886 -45.6438)
		(size 0.508)
		(drill 0.254)
		(layers "F.Cu" "B.Cu")
		(net "RST_PCIE_CPU_DEV2_R_N")
	)
	(segment
		(start 467.5886 -45.6438)
		(end 467.868 -45.9232)
		(width 0.10795)
		(layer "B.Cu")
		(net "RST_PCIE_CPU_DEV2_R_N")
	)
	(segment
		(start 467.868 -45.9232)
		(end 467.868 -46.6725)
		(width 0.10795)
		(layer "B.Cu")
		(net "RST_PCIE_CPU_DEV2_R_N")
	)
	(segment
		(start 378.9172 -74.2696)
		(end 377.6472 -74.2696)
		(width 0.10795)
		(layer "F.Cu")
		(net "RST_PCIE_CPU_DEV2_N")
	)
	(segment
		(start 377.6472 -74.2696)
		(end 377.27255 -73.89495)
		(width 0.10795)
		(layer "F.Cu")
		(net "RST_PCIE_CPU_DEV2_N")
	)
	(segment
		(start 379.0696 -74.1172)
		(end 378.9172 -74.2696)
		(width 0.10795)
		(layer "F.Cu")
		(net "RST_PCIE_CPU_DEV2_N")
	)
	(segment
		(start 380.996698 -73.275698)
		(end 380.993396 -73.279)
		(width 0.10795)
		(layer "F.Cu")
		(net "RST_PCIE_CPU_DEV2_N")
	)
	(segment
		(start 377.27255 -73.89495)
		(end 377.145042 -73.89495)
		(width 0.10795)
		(layer "F.Cu")
		(net "RST_PCIE_CPU_DEV2_N")
	)
	(segment
		(start 380.993396 -73.279)
		(end 380.8222 -73.279)
		(width 0.10795)
		(layer "F.Cu")
		(net "RST_PCIE_CPU_DEV2_N")
	)
	(segment
		(start 379.984 -74.1172)
		(end 379.0696 -74.1172)
		(width 0.10795)
		(layer "F.Cu")
		(net "RST_PCIE_CPU_DEV2_N")
	)
	(segment
		(start 380.8222 -73.279)
		(end 379.984 -74.1172)
		(width 0.10795)
		(layer "F.Cu")
		(net "RST_PCIE_CPU_DEV2_N")
	)
	(via
		(at 380.996698 -73.275698)
		(size 0.508)
		(drill 0.254)
		(layers "F.Cu" "B.Cu")
		(net "RST_PCIE_CPU_DEV2_N")
	)
	(via
		(at 434.066188 -51.959256)
		(size 0.6604)
		(drill 0.3302)
		(layers "F.Cu" "B.Cu")
		(net "RST_PCIE_CPU_DEV2_N")
	)
	(segment
		(start 436.147464 -48.268128)
		(end 436.147464 -50.210466)
		(width 0.10795)
		(layer "B.Cu")
		(net "RST_PCIE_CPU_DEV2_N")
	)
	(segment
		(start 383.81432 -74.92492)
		(end 385.33451 -74.92492)
		(width 0.10795)
		(layer "B.Cu")
		(net "RST_PCIE_CPU_DEV2_N")
	)
	(segment
		(start 420.52621 -53.828696)
		(end 420.948866 -53.828696)
		(width 0.10795)
		(layer "B.Cu")
		(net "RST_PCIE_CPU_DEV2_N")
	)
	(segment
		(start 411.262322 -59.671712)
		(end 412.57728 -58.356754)
		(width 0.10795)
		(layer "B.Cu")
		(net "RST_PCIE_CPU_DEV2_N")
	)
	(segment
		(start 383.055876 -74.166476)
		(end 383.81432 -74.92492)
		(width 0.10795)
		(layer "B.Cu")
		(net "RST_PCIE_CPU_DEV2_N")
	)
	(segment
		(start 436.45074 -47.96282)
		(end 436.20182 -48.21174)
		(width 0.10795)
		(layer "B.Cu")
		(net "RST_PCIE_CPU_DEV2_N")
	)
	(segment
		(start 396.367762 -68.973192)
		(end 396.368016 -68.973446)
		(width 0.10795)
		(layer "B.Cu")
		(net "RST_PCIE_CPU_DEV2_N")
	)
	(segment
		(start 436.20182 -48.21174)
		(end 436.20182 -48.213772)
		(width 0.10795)
		(layer "B.Cu")
		(net "RST_PCIE_CPU_DEV2_N")
	)
	(segment
		(start 400.386804 -65.419478)
		(end 400.386804 -64.936878)
		(width 0.10795)
		(layer "B.Cu")
		(net "RST_PCIE_CPU_DEV2_N")
	)
	(segment
		(start 400.969988 -63.37173)
		(end 400.969734 -63.371476)
		(width 0.10795)
		(layer "B.Cu")
		(net "RST_PCIE_CPU_DEV2_N")
	)
	(segment
		(start 417.072318 -56.667654)
		(end 417.687252 -56.667654)
		(width 0.10795)
		(layer "B.Cu")
		(net "RST_PCIE_CPU_DEV2_N")
	)
	(segment
		(start 392.378438 -71.169276)
		(end 392.780774 -71.169276)
		(width 0.10795)
		(layer "B.Cu")
		(net "RST_PCIE_CPU_DEV2_N")
	)
	(segment
		(start 436.80126 -47.96282)
		(end 436.45074 -47.96282)
		(width 0.10795)
		(layer "B.Cu")
		(net "RST_PCIE_CPU_DEV2_N")
	)
	(segment
		(start 400.969734 -62.876684)
		(end 402.933408 -60.91301)
		(width 0.10795)
		(layer "B.Cu")
		(net "RST_PCIE_CPU_DEV2_N")
	)
	(segment
		(start 425.544488 -53.020722)
		(end 427.106334 -53.020722)
		(width 0.10795)
		(layer "B.Cu")
		(net "RST_PCIE_CPU_DEV2_N")
	)
	(segment
		(start 407.692352 -59.671712)
		(end 411.262322 -59.671712)
		(width 0.10795)
		(layer "B.Cu")
		(net "RST_PCIE_CPU_DEV2_N")
	)
	(segment
		(start 394.97635 -68.9737)
		(end 395.377162 -68.9737)
		(width 0.10795)
		(layer "B.Cu")
		(net "RST_PCIE_CPU_DEV2_N")
	)
	(segment
		(start 435.38648 -50.97145)
		(end 435.053994 -50.97145)
		(width 0.10795)
		(layer "B.Cu")
		(net "RST_PCIE_CPU_DEV2_N")
	)
	(segment
		(start 391.315448 -71.423276)
		(end 391.565384 -71.17334)
		(width 0.10795)
		(layer "B.Cu")
		(net "RST_PCIE_CPU_DEV2_N")
	)
	(segment
		(start 436.96382 -48.12538)
		(end 436.80126 -47.96282)
		(width 0.10795)
		(layer "B.Cu")
		(net "RST_PCIE_CPU_DEV2_N")
	)
	(segment
		(start 388.310628 -71.948802)
		(end 388.836154 -71.423276)
		(width 0.10795)
		(layer "B.Cu")
		(net "RST_PCIE_CPU_DEV2_N")
	)
	(segment
		(start 417.687252 -56.667654)
		(end 420.52621 -53.828696)
		(width 0.10795)
		(layer "B.Cu")
		(net "RST_PCIE_CPU_DEV2_N")
	)
	(segment
		(start 391.565384 -71.17334)
		(end 392.374374 -71.17334)
		(width 0.10795)
		(layer "B.Cu")
		(net "RST_PCIE_CPU_DEV2_N")
	)
	(segment
		(start 400.969988 -64.059816)
		(end 400.969988 -63.37173)
		(width 0.10795)
		(layer "B.Cu")
		(net "RST_PCIE_CPU_DEV2_N")
	)
	(segment
		(start 399.970752 -66.326512)
		(end 399.970752 -65.83553)
		(width 0.10795)
		(layer "B.Cu")
		(net "RST_PCIE_CPU_DEV2_N")
	)
	(segment
		(start 380.996698 -73.275698)
		(end 381.195326 -73.275698)
		(width 0.10795)
		(layer "B.Cu")
		(net "RST_PCIE_CPU_DEV2_N")
	)
	(segment
		(start 387.619748 -72.639682)
		(end 387.619748 -72.608186)
		(width 0.10795)
		(layer "B.Cu")
		(net "RST_PCIE_CPU_DEV2_N")
	)
	(segment
		(start 400.969734 -63.371476)
		(end 400.969734 -62.876684)
		(width 0.10795)
		(layer "B.Cu")
		(net "RST_PCIE_CPU_DEV2_N")
	)
	(segment
		(start 396.971266 -68.508118)
		(end 397.789146 -68.508118)
		(width 0.10795)
		(layer "B.Cu")
		(net "RST_PCIE_CPU_DEV2_N")
	)
	(segment
		(start 428.1678 -51.959256)
		(end 434.066188 -51.959256)
		(width 0.10795)
		(layer "B.Cu")
		(net "RST_PCIE_CPU_DEV2_N")
	)
	(segment
		(start 382.086104 -74.166476)
		(end 383.055876 -74.166476)
		(width 0.10795)
		(layer "B.Cu")
		(net "RST_PCIE_CPU_DEV2_N")
	)
	(segment
		(start 399.970752 -65.83553)
		(end 400.386804 -65.419478)
		(width 0.10795)
		(layer "B.Cu")
		(net "RST_PCIE_CPU_DEV2_N")
	)
	(segment
		(start 402.933408 -60.91301)
		(end 405.289766 -60.91301)
		(width 0.10795)
		(layer "B.Cu")
		(net "RST_PCIE_CPU_DEV2_N")
	)
	(segment
		(start 436.20182 -48.213772)
		(end 436.147464 -48.268128)
		(width 0.10795)
		(layer "B.Cu")
		(net "RST_PCIE_CPU_DEV2_N")
	)
	(segment
		(start 424.170602 -52.505864)
		(end 425.02963 -52.505864)
		(width 0.10795)
		(layer "B.Cu")
		(net "RST_PCIE_CPU_DEV2_N")
	)
	(segment
		(start 421.90543 -52.872132)
		(end 423.804334 -52.872132)
		(width 0.10795)
		(layer "B.Cu")
		(net "RST_PCIE_CPU_DEV2_N")
	)
	(segment
		(start 400.38655 -64.643254)
		(end 400.969988 -64.059816)
		(width 0.10795)
		(layer "B.Cu")
		(net "RST_PCIE_CPU_DEV2_N")
	)
	(segment
		(start 467.68512 -48.12538)
		(end 436.96382 -48.12538)
		(width 0.10795)
		(layer "B.Cu")
		(net "RST_PCIE_CPU_DEV2_N")
	)
	(segment
		(start 412.57728 -58.356754)
		(end 415.383218 -58.356754)
		(width 0.10795)
		(layer "B.Cu")
		(net "RST_PCIE_CPU_DEV2_N")
	)
	(segment
		(start 387.619748 -72.608186)
		(end 388.279132 -71.948802)
		(width 0.10795)
		(layer "B.Cu")
		(net "RST_PCIE_CPU_DEV2_N")
	)
	(segment
		(start 396.505938 -68.973446)
		(end 396.971266 -68.508118)
		(width 0.10795)
		(layer "B.Cu")
		(net "RST_PCIE_CPU_DEV2_N")
	)
	(segment
		(start 423.804334 -52.872132)
		(end 424.170602 -52.505864)
		(width 0.10795)
		(layer "B.Cu")
		(net "RST_PCIE_CPU_DEV2_N")
	)
	(segment
		(start 385.33451 -74.92492)
		(end 387.619748 -72.639682)
		(width 0.10795)
		(layer "B.Cu")
		(net "RST_PCIE_CPU_DEV2_N")
	)
	(segment
		(start 388.836154 -71.423276)
		(end 391.315448 -71.423276)
		(width 0.10795)
		(layer "B.Cu")
		(net "RST_PCIE_CPU_DEV2_N")
	)
	(segment
		(start 381.195326 -73.275698)
		(end 382.086104 -74.166476)
		(width 0.10795)
		(layer "B.Cu")
		(net "RST_PCIE_CPU_DEV2_N")
	)
	(segment
		(start 420.948866 -53.828696)
		(end 421.90543 -52.872132)
		(width 0.10795)
		(layer "B.Cu")
		(net "RST_PCIE_CPU_DEV2_N")
	)
	(segment
		(start 396.368016 -68.973446)
		(end 396.505938 -68.973446)
		(width 0.10795)
		(layer "B.Cu")
		(net "RST_PCIE_CPU_DEV2_N")
	)
	(segment
		(start 397.789146 -68.508118)
		(end 399.970752 -66.326512)
		(width 0.10795)
		(layer "B.Cu")
		(net "RST_PCIE_CPU_DEV2_N")
	)
	(segment
		(start 467.868 -47.9425)
		(end 467.68512 -48.12538)
		(width 0.10795)
		(layer "B.Cu")
		(net "RST_PCIE_CPU_DEV2_N")
	)
	(segment
		(start 395.377162 -68.9737)
		(end 395.37767 -68.973192)
		(width 0.10795)
		(layer "B.Cu")
		(net "RST_PCIE_CPU_DEV2_N")
	)
	(segment
		(start 392.780774 -71.169276)
		(end 394.97635 -68.9737)
		(width 0.10795)
		(layer "B.Cu")
		(net "RST_PCIE_CPU_DEV2_N")
	)
	(segment
		(start 400.38655 -64.936624)
		(end 400.38655 -64.643254)
		(width 0.10795)
		(layer "B.Cu")
		(net "RST_PCIE_CPU_DEV2_N")
	)
	(segment
		(start 415.383218 -58.356754)
		(end 417.072318 -56.667654)
		(width 0.10795)
		(layer "B.Cu")
		(net "RST_PCIE_CPU_DEV2_N")
	)
	(segment
		(start 405.29891 -60.922154)
		(end 406.44191 -60.922154)
		(width 0.10795)
		(layer "B.Cu")
		(net "RST_PCIE_CPU_DEV2_N")
	)
	(segment
		(start 425.02963 -52.505864)
		(end 425.544488 -53.020722)
		(width 0.10795)
		(layer "B.Cu")
		(net "RST_PCIE_CPU_DEV2_N")
	)
	(segment
		(start 395.37767 -68.973192)
		(end 396.367762 -68.973192)
		(width 0.10795)
		(layer "B.Cu")
		(net "RST_PCIE_CPU_DEV2_N")
	)
	(segment
		(start 400.386804 -64.936878)
		(end 400.38655 -64.936624)
		(width 0.10795)
		(layer "B.Cu")
		(net "RST_PCIE_CPU_DEV2_N")
	)
	(segment
		(start 436.147464 -50.210466)
		(end 435.38648 -50.97145)
		(width 0.10795)
		(layer "B.Cu")
		(net "RST_PCIE_CPU_DEV2_N")
	)
	(segment
		(start 467.868 -47.5615)
		(end 467.868 -47.9425)
		(width 0.10795)
		(layer "B.Cu")
		(net "RST_PCIE_CPU_DEV2_N")
	)
	(segment
		(start 392.374374 -71.17334)
		(end 392.378438 -71.169276)
		(width 0.10795)
		(layer "B.Cu")
		(net "RST_PCIE_CPU_DEV2_N")
	)
	(segment
		(start 406.44191 -60.922154)
		(end 407.692352 -59.671712)
		(width 0.10795)
		(layer "B.Cu")
		(net "RST_PCIE_CPU_DEV2_N")
	)
	(segment
		(start 388.279132 -71.948802)
		(end 388.310628 -71.948802)
		(width 0.10795)
		(layer "B.Cu")
		(net "RST_PCIE_CPU_DEV2_N")
	)
	(segment
		(start 405.289766 -60.91301)
		(end 405.29891 -60.922154)
		(width 0.10795)
		(layer "B.Cu")
		(net "RST_PCIE_CPU_DEV2_N")
	)
	(segment
		(start 435.053994 -50.97145)
		(end 434.066188 -51.959256)
		(width 0.10795)
		(layer "B.Cu")
		(net "RST_PCIE_CPU_DEV2_N")
	)
	(segment
		(start 427.106334 -53.020722)
		(end 428.1678 -51.959256)
		(width 0.10795)
		(layer "B.Cu")
		(net "RST_PCIE_CPU_DEV2_N")
	)
	(segment
		(start 466.939884 -46.036484)
		(end 466.939884 -47.481998)
		(width 0.10795)
		(layer "F.Cu")
		(net "RST_PCIE_CPU_DEV1_R_N")
	)
	(segment
		(start 466.5472 -45.6438)
		(end 466.939884 -46.036484)
		(width 0.10795)
		(layer "F.Cu")
		(net "RST_PCIE_CPU_DEV1_R_N")
	)
	(segment
		(start 466.3694 -45.6438)
		(end 466.5472 -45.6438)
		(width 0.10795)
		(layer "F.Cu")
		(net "RST_PCIE_CPU_DEV1_R_N")
	)
	(segment
		(start 466.939884 -47.481998)
		(end 466.9409 -47.481998)
		(width 0.10795)
		(layer "F.Cu")
		(net "RST_PCIE_CPU_DEV1_R_N")
	)
	(via
		(at 466.3694 -45.6438)
		(size 0.508)
		(drill 0.254)
		(layers "F.Cu" "B.Cu")
		(net "RST_PCIE_CPU_DEV1_R_N")
	)
	(segment
		(start 467.106 -46.08195)
		(end 467.106 -46.6725)
		(width 0.10795)
		(layer "B.Cu")
		(net "RST_PCIE_CPU_DEV1_R_N")
	)
	(segment
		(start 466.66785 -45.6438)
		(end 467.106 -46.08195)
		(width 0.10795)
		(layer "B.Cu")
		(net "RST_PCIE_CPU_DEV1_R_N")
	)
	(segment
		(start 466.3694 -45.6438)
		(end 466.66785 -45.6438)
		(width 0.10795)
		(layer "B.Cu")
		(net "RST_PCIE_CPU_DEV1_R_N")
	)
	(segment
		(start 385.525772 -72.823324)
		(end 385.092448 -72.39)
		(width 0.10795)
		(layer "F.Cu")
		(net "RST_PCIE_CPU_DEV1_N")
	)
	(segment
		(start 384.302 -72.009)
		(end 382.651 -72.009)
		(width 0.10795)
		(layer "F.Cu")
		(net "RST_PCIE_CPU_DEV1_N")
	)
	(segment
		(start 384.683 -72.39)
		(end 384.302 -72.009)
		(width 0.10795)
		(layer "F.Cu")
		(net "RST_PCIE_CPU_DEV1_N")
	)
	(segment
		(start 385.092448 -72.39)
		(end 384.683 -72.39)
		(width 0.10795)
		(layer "F.Cu")
		(net "RST_PCIE_CPU_DEV1_N")
	)
	(segment
		(start 380.828296 -70.186296)
		(end 380.083822 -70.186296)
		(width 0.10795)
		(layer "F.Cu")
		(net "RST_PCIE_CPU_DEV1_N")
	)
	(segment
		(start 382.651 -72.009)
		(end 380.828296 -70.186296)
		(width 0.10795)
		(layer "F.Cu")
		(net "RST_PCIE_CPU_DEV1_N")
	)
	(segment
		(start 380.082044 -70.188074)
		(end 379.038104 -70.188074)
		(width 0.10795)
		(layer "F.Cu")
		(net "RST_PCIE_CPU_DEV1_N")
	)
	(segment
		(start 380.083822 -70.186296)
		(end 380.082044 -70.188074)
		(width 0.10795)
		(layer "F.Cu")
		(net "RST_PCIE_CPU_DEV1_N")
	)
	(segment
		(start 385.573524 -72.823324)
		(end 385.525772 -72.823324)
		(width 0.10795)
		(layer "F.Cu")
		(net "RST_PCIE_CPU_DEV1_N")
	)
	(segment
		(start 379.038104 -70.188074)
		(end 378.744988 -69.894958)
		(width 0.10795)
		(layer "F.Cu")
		(net "RST_PCIE_CPU_DEV1_N")
	)
	(via
		(at 384.683 -72.39)
		(size 0.762)
		(drill 0.381)
		(layers "F.Cu" "B.Cu")
		(net "RST_PCIE_CPU_DEV1_N")
	)
	(via
		(at 385.573524 -72.823324)
		(size 0.508)
		(drill 0.254)
		(layers "F.Cu" "B.Cu")
		(net "RST_PCIE_CPU_DEV1_N")
	)
	(segment
		(start 397.041116 -67.342766)
		(end 397.04137 -67.342512)
		(width 0.10795)
		(layer "B.Cu")
		(net "RST_PCIE_CPU_DEV1_N")
	)
	(segment
		(start 394.474954 -67.80784)
		(end 396.023084 -67.80784)
		(width 0.10795)
		(layer "B.Cu")
		(net "RST_PCIE_CPU_DEV1_N")
	)
	(segment
		(start 428.05223 -51.680364)
		(end 428.065184 -51.680364)
		(width 0.10795)
		(layer "B.Cu")
		(net "RST_PCIE_CPU_DEV1_N")
	)
	(segment
		(start 390.835896 -70.254368)
		(end 391.181844 -69.90842)
		(width 0.10795)
		(layer "B.Cu")
		(net "RST_PCIE_CPU_DEV1_N")
	)
	(segment
		(start 398.8054 -65.843404)
		(end 398.8054 -64.826896)
		(width 0.10795)
		(layer "B.Cu")
		(net "RST_PCIE_CPU_DEV1_N")
	)
	(segment
		(start 425.642024 -52.785772)
		(end 426.946822 -52.785772)
		(width 0.10795)
		(layer "B.Cu")
		(net "RST_PCIE_CPU_DEV1_N")
	)
	(segment
		(start 433.7685 -51.55184)
		(end 434.58384 -50.7365)
		(width 0.10795)
		(layer "B.Cu")
		(net "RST_PCIE_CPU_DEV1_N")
	)
	(segment
		(start 435.912514 -47.87011)
		(end 436.221124 -47.5615)
		(width 0.10795)
		(layer "B.Cu")
		(net "RST_PCIE_CPU_DEV1_N")
	)
	(segment
		(start 424.073066 -52.270914)
		(end 425.127166 -52.270914)
		(width 0.10795)
		(layer "B.Cu")
		(net "RST_PCIE_CPU_DEV1_N")
	)
	(segment
		(start 385.573524 -72.823324)
		(end 386.240528 -72.15632)
		(width 0.10795)
		(layer "B.Cu")
		(net "RST_PCIE_CPU_DEV1_N")
	)
	(segment
		(start 398.8054 -64.826896)
		(end 399.221198 -64.411098)
		(width 0.10795)
		(layer "B.Cu")
		(net "RST_PCIE_CPU_DEV1_N")
	)
	(segment
		(start 405.30653 -59.077606)
		(end 405.334724 -59.1058)
		(width 0.10795)
		(layer "B.Cu")
		(net "RST_PCIE_CPU_DEV1_N")
	)
	(segment
		(start 399.804382 -63.576962)
		(end 399.804382 -62.393576)
		(width 0.10795)
		(layer "B.Cu")
		(net "RST_PCIE_CPU_DEV1_N")
	)
	(segment
		(start 434.58384 -50.7365)
		(end 435.288944 -50.7365)
		(width 0.10795)
		(layer "B.Cu")
		(net "RST_PCIE_CPU_DEV1_N")
	)
	(segment
		(start 426.946822 -52.785772)
		(end 428.05223 -51.680364)
		(width 0.10795)
		(layer "B.Cu")
		(net "RST_PCIE_CPU_DEV1_N")
	)
	(segment
		(start 411.329886 -59.1058)
		(end 412.314136 -58.12155)
		(width 0.10795)
		(layer "B.Cu")
		(net "RST_PCIE_CPU_DEV1_N")
	)
	(segment
		(start 399.221198 -64.160146)
		(end 399.804382 -63.576962)
		(width 0.10795)
		(layer "B.Cu")
		(net "RST_PCIE_CPU_DEV1_N")
	)
	(segment
		(start 423.706798 -52.637182)
		(end 424.073066 -52.270914)
		(width 0.10795)
		(layer "B.Cu")
		(net "RST_PCIE_CPU_DEV1_N")
	)
	(segment
		(start 416.975036 -56.43245)
		(end 417.58997 -56.43245)
		(width 0.10795)
		(layer "B.Cu")
		(net "RST_PCIE_CPU_DEV1_N")
	)
	(segment
		(start 397.04137 -67.342512)
		(end 397.306292 -67.342512)
		(width 0.10795)
		(layer "B.Cu")
		(net "RST_PCIE_CPU_DEV1_N")
	)
	(segment
		(start 403.362414 -59.1058)
		(end 403.390608 -59.077606)
		(width 0.10795)
		(layer "B.Cu")
		(net "RST_PCIE_CPU_DEV1_N")
	)
	(segment
		(start 391.181844 -69.90842)
		(end 392.374374 -69.90842)
		(width 0.10795)
		(layer "B.Cu")
		(net "RST_PCIE_CPU_DEV1_N")
	)
	(segment
		(start 403.390608 -59.077606)
		(end 405.30653 -59.077606)
		(width 0.10795)
		(layer "B.Cu")
		(net "RST_PCIE_CPU_DEV1_N")
	)
	(segment
		(start 435.912514 -50.11293)
		(end 435.912514 -47.87011)
		(width 0.10795)
		(layer "B.Cu")
		(net "RST_PCIE_CPU_DEV1_N")
	)
	(segment
		(start 412.314136 -58.12155)
		(end 415.285936 -58.12155)
		(width 0.10795)
		(layer "B.Cu")
		(net "RST_PCIE_CPU_DEV1_N")
	)
	(segment
		(start 399.804382 -62.393576)
		(end 403.092158 -59.1058)
		(width 0.10795)
		(layer "B.Cu")
		(net "RST_PCIE_CPU_DEV1_N")
	)
	(segment
		(start 387.5532 -70.9676)
		(end 387.5532 -70.4342)
		(width 0.10795)
		(layer "B.Cu")
		(net "RST_PCIE_CPU_DEV1_N")
	)
	(segment
		(start 387.733032 -70.254368)
		(end 390.835896 -70.254368)
		(width 0.10795)
		(layer "B.Cu")
		(net "RST_PCIE_CPU_DEV1_N")
	)
	(segment
		(start 428.193708 -51.55184)
		(end 433.7685 -51.55184)
		(width 0.10795)
		(layer "B.Cu")
		(net "RST_PCIE_CPU_DEV1_N")
	)
	(segment
		(start 386.240528 -72.15632)
		(end 386.36448 -72.15632)
		(width 0.10795)
		(layer "B.Cu")
		(net "RST_PCIE_CPU_DEV1_N")
	)
	(segment
		(start 420.85133 -53.593746)
		(end 421.807894 -52.637182)
		(width 0.10795)
		(layer "B.Cu")
		(net "RST_PCIE_CPU_DEV1_N")
	)
	(segment
		(start 436.221124 -47.5615)
		(end 467.106 -47.5615)
		(width 0.10795)
		(layer "B.Cu")
		(net "RST_PCIE_CPU_DEV1_N")
	)
	(segment
		(start 403.092158 -59.1058)
		(end 403.362414 -59.1058)
		(width 0.10795)
		(layer "B.Cu")
		(net "RST_PCIE_CPU_DEV1_N")
	)
	(segment
		(start 386.36448 -72.15632)
		(end 387.5532 -70.9676)
		(width 0.10795)
		(layer "B.Cu")
		(net "RST_PCIE_CPU_DEV1_N")
	)
	(segment
		(start 405.334724 -59.1058)
		(end 411.329886 -59.1058)
		(width 0.10795)
		(layer "B.Cu")
		(net "RST_PCIE_CPU_DEV1_N")
	)
	(segment
		(start 387.5532 -70.4342)
		(end 387.733032 -70.254368)
		(width 0.10795)
		(layer "B.Cu")
		(net "RST_PCIE_CPU_DEV1_N")
	)
	(segment
		(start 397.306292 -67.342512)
		(end 398.8054 -65.843404)
		(width 0.10795)
		(layer "B.Cu")
		(net "RST_PCIE_CPU_DEV1_N")
	)
	(segment
		(start 417.58997 -56.43245)
		(end 420.428674 -53.593746)
		(width 0.10795)
		(layer "B.Cu")
		(net "RST_PCIE_CPU_DEV1_N")
	)
	(segment
		(start 396.023084 -67.80784)
		(end 396.488158 -67.342766)
		(width 0.10795)
		(layer "B.Cu")
		(net "RST_PCIE_CPU_DEV1_N")
	)
	(segment
		(start 420.428674 -53.593746)
		(end 420.85133 -53.593746)
		(width 0.10795)
		(layer "B.Cu")
		(net "RST_PCIE_CPU_DEV1_N")
	)
	(segment
		(start 415.285936 -58.12155)
		(end 416.975036 -56.43245)
		(width 0.10795)
		(layer "B.Cu")
		(net "RST_PCIE_CPU_DEV1_N")
	)
	(segment
		(start 392.374374 -69.90842)
		(end 394.474954 -67.80784)
		(width 0.10795)
		(layer "B.Cu")
		(net "RST_PCIE_CPU_DEV1_N")
	)
	(segment
		(start 399.221198 -64.411098)
		(end 399.221198 -64.160146)
		(width 0.10795)
		(layer "B.Cu")
		(net "RST_PCIE_CPU_DEV1_N")
	)
	(segment
		(start 421.807894 -52.637182)
		(end 423.706798 -52.637182)
		(width 0.10795)
		(layer "B.Cu")
		(net "RST_PCIE_CPU_DEV1_N")
	)
	(segment
		(start 425.127166 -52.270914)
		(end 425.642024 -52.785772)
		(width 0.10795)
		(layer "B.Cu")
		(net "RST_PCIE_CPU_DEV1_N")
	)
	(segment
		(start 396.488158 -67.342766)
		(end 397.041116 -67.342766)
		(width 0.10795)
		(layer "B.Cu")
		(net "RST_PCIE_CPU_DEV1_N")
	)
	(segment
		(start 428.065184 -51.680364)
		(end 428.193708 -51.55184)
		(width 0.10795)
		(layer "B.Cu")
		(net "RST_PCIE_CPU_DEV1_N")
	)
	(segment
		(start 435.288944 -50.7365)
		(end 435.912514 -50.11293)
		(width 0.10795)
		(layer "B.Cu")
		(net "RST_PCIE_CPU_DEV1_N")
	)
	(segment
		(start 375.144792 -70.295262)
		(end 374.744996 -70.695058)
		(width 0.10795)
		(layer "F.Cu")
		(net "RST_PCIE_CPU_DEV0_N")
	)
	(via
		(at 422.390824 -61.869828)
		(size 0.508)
		(drill 0.254)
		(layers "F.Cu" "B.Cu")
		(net "RST_PCIE_CPU_DEV0_N")
	)
	(via
		(at 482.82606 -121.2088)
		(size 0.508)
		(drill 0.254)
		(layers "F.Cu" "B.Cu")
		(net "RST_PCIE_CPU_DEV0_N")
	)
	(via
		(at 375.144792 -70.295262)
		(size 0.4572)
		(drill 0.2032)
		(layers "F.Cu" "B.Cu")
		(net "RST_PCIE_CPU_DEV0_N")
	)
	(segment
		(start 477.263968 -120.7008)
		(end 476.480632 -120.7008)
		(width 0.10795)
		(layer "B.Cu")
		(net "RST_PCIE_CPU_DEV0_N")
	)
	(segment
		(start 477.771968 -121.2088)
		(end 477.263968 -120.7008)
		(width 0.10795)
		(layer "B.Cu")
		(net "RST_PCIE_CPU_DEV0_N")
	)
	(segment
		(start 476.353632 -120.8278)
		(end 474.345 -120.8278)
		(width 0.10795)
		(layer "B.Cu")
		(net "RST_PCIE_CPU_DEV0_N")
	)
	(segment
		(start 482.82606 -121.2088)
		(end 477.771968 -121.2088)
		(width 0.10795)
		(layer "B.Cu")
		(net "RST_PCIE_CPU_DEV0_N")
	)
	(segment
		(start 476.480632 -120.7008)
		(end 476.353632 -120.8278)
		(width 0.10795)
		(layer "B.Cu")
		(net "RST_PCIE_CPU_DEV0_N")
	)
	(segment
		(start 419.069774 -116.395246)
		(end 417.79825 -115.123722)
		(width 0.089408)
		(layer "In2.Cu")
		(net "RST_PCIE_CPU_DEV0_N")
	)
	(segment
		(start 418.78631 -87.57031)
		(end 418.78631 -86.845394)
		(width 0.089408)
		(layer "In2.Cu")
		(net "RST_PCIE_CPU_DEV0_N")
	)
	(segment
		(start 420.2176 -89.0016)
		(end 418.78631 -87.57031)
		(width 0.089408)
		(layer "In2.Cu")
		(net "RST_PCIE_CPU_DEV0_N")
	)
	(segment
		(start 418.045646 -103.562658)
		(end 418.0459 -103.562404)
		(width 0.089408)
		(layer "In2.Cu")
		(net "RST_PCIE_CPU_DEV0_N")
	)
	(segment
		(start 419.620954 -64.47028)
		(end 421.371522 -62.719712)
		(width 0.089408)
		(layer "In2.Cu")
		(net "RST_PCIE_CPU_DEV0_N")
	)
	(segment
		(start 419.388798 -76.388214)
		(end 419.388798 -76.251816)
		(width 0.089408)
		(layer "In2.Cu")
		(net "RST_PCIE_CPU_DEV0_N")
	)
	(segment
		(start 418.786056 -82.056732)
		(end 418.786056 -76.990956)
		(width 0.089408)
		(layer "In2.Cu")
		(net "RST_PCIE_CPU_DEV0_N")
	)
	(segment
		(start 418.786056 -76.990956)
		(end 419.388798 -76.388214)
		(width 0.089408)
		(layer "In2.Cu")
		(net "RST_PCIE_CPU_DEV0_N")
	)
	(segment
		(start 418.786056 -83.376516)
		(end 418.78631 -83.376262)
		(width 0.089408)
		(layer "In2.Cu")
		(net "RST_PCIE_CPU_DEV0_N")
	)
	(segment
		(start 476.637096 -113.808002)
		(end 475.59595 -112.766856)
		(width 0.089408)
		(layer "In2.Cu")
		(net "RST_PCIE_CPU_DEV0_N")
	)
	(segment
		(start 419.6207 -65.448434)
		(end 419.620954 -65.44818)
		(width 0.089408)
		(layer "In2.Cu")
		(net "RST_PCIE_CPU_DEV0_N")
	)
	(segment
		(start 480.412552 -119.917718)
		(end 480.412552 -118.429786)
		(width 0.089408)
		(layer "In2.Cu")
		(net "RST_PCIE_CPU_DEV0_N")
	)
	(segment
		(start 422.085516 -116.394992)
		(end 421.426386 -116.394992)
		(width 0.089408)
		(layer "In2.Cu")
		(net "RST_PCIE_CPU_DEV0_N")
	)
	(segment
		(start 419.6207 -71.583042)
		(end 419.6207 -65.448434)
		(width 0.089408)
		(layer "In2.Cu")
		(net "RST_PCIE_CPU_DEV0_N")
	)
	(segment
		(start 417.79825 -107.18673)
		(end 418.045392 -106.939588)
		(width 0.089408)
		(layer "In2.Cu")
		(net "RST_PCIE_CPU_DEV0_N")
	)
	(segment
		(start 418.78631 -82.056986)
		(end 418.786056 -82.056732)
		(width 0.089408)
		(layer "In2.Cu")
		(net "RST_PCIE_CPU_DEV0_N")
	)
	(segment
		(start 434.86705 -113.316004)
		(end 434.01488 -112.463834)
		(width 0.089408)
		(layer "In2.Cu")
		(net "RST_PCIE_CPU_DEV0_N")
	)
	(segment
		(start 475.59595 -112.766856)
		(end 440.292744 -112.766856)
		(width 0.089408)
		(layer "In2.Cu")
		(net "RST_PCIE_CPU_DEV0_N")
	)
	(segment
		(start 419.389306 -76.251308)
		(end 419.389306 -75.090528)
		(width 0.089408)
		(layer "In2.Cu")
		(net "RST_PCIE_CPU_DEV0_N")
	)
	(segment
		(start 425.438316 -115.509294)
		(end 422.971214 -115.509294)
		(width 0.089408)
		(layer "In2.Cu")
		(net "RST_PCIE_CPU_DEV0_N")
	)
	(segment
		(start 419.388798 -76.251816)
		(end 419.389306 -76.251308)
		(width 0.089408)
		(layer "In2.Cu")
		(net "RST_PCIE_CPU_DEV0_N")
	)
	(segment
		(start 419.389052 -74.932286)
		(end 419.388798 -74.932032)
		(width 0.089408)
		(layer "In2.Cu")
		(net "RST_PCIE_CPU_DEV0_N")
	)
	(segment
		(start 419.388798 -71.814944)
		(end 419.6207 -71.583042)
		(width 0.089408)
		(layer "In2.Cu")
		(net "RST_PCIE_CPU_DEV0_N")
	)
	(segment
		(start 419.388798 -74.932032)
		(end 419.388798 -71.814944)
		(width 0.089408)
		(layer "In2.Cu")
		(net "RST_PCIE_CPU_DEV0_N")
	)
	(segment
		(start 440.292744 -112.766856)
		(end 439.743596 -113.316004)
		(width 0.089408)
		(layer "In2.Cu")
		(net "RST_PCIE_CPU_DEV0_N")
	)
	(segment
		(start 422.390824 -62.435994)
		(end 422.390824 -61.869828)
		(width 0.089408)
		(layer "In2.Cu")
		(net "RST_PCIE_CPU_DEV0_N")
	)
	(segment
		(start 419.389306 -75.090528)
		(end 419.389052 -75.090274)
		(width 0.089408)
		(layer "In2.Cu")
		(net "RST_PCIE_CPU_DEV0_N")
	)
	(segment
		(start 418.045392 -95.3516)
		(end 420.2176 -93.179392)
		(width 0.089408)
		(layer "In2.Cu")
		(net "RST_PCIE_CPU_DEV0_N")
	)
	(segment
		(start 418.0459 -103.24592)
		(end 418.045392 -103.245412)
		(width 0.089408)
		(layer "In2.Cu")
		(net "RST_PCIE_CPU_DEV0_N")
	)
	(segment
		(start 422.107106 -62.719712)
		(end 422.390824 -62.435994)
		(width 0.089408)
		(layer "In2.Cu")
		(net "RST_PCIE_CPU_DEV0_N")
	)
	(segment
		(start 419.620954 -65.44818)
		(end 419.620954 -64.47028)
		(width 0.089408)
		(layer "In2.Cu")
		(net "RST_PCIE_CPU_DEV0_N")
	)
	(segment
		(start 420.2176 -93.179392)
		(end 420.2176 -89.0016)
		(width 0.089408)
		(layer "In2.Cu")
		(net "RST_PCIE_CPU_DEV0_N")
	)
	(segment
		(start 421.426386 -116.394992)
		(end 421.426132 -116.395246)
		(width 0.089408)
		(layer "In2.Cu")
		(net "RST_PCIE_CPU_DEV0_N")
	)
	(segment
		(start 418.78631 -83.376262)
		(end 418.78631 -82.056986)
		(width 0.089408)
		(layer "In2.Cu")
		(net "RST_PCIE_CPU_DEV0_N")
	)
	(segment
		(start 482.82606 -121.2088)
		(end 481.703634 -121.2088)
		(width 0.089408)
		(layer "In2.Cu")
		(net "RST_PCIE_CPU_DEV0_N")
	)
	(segment
		(start 418.045392 -103.245412)
		(end 418.045392 -95.3516)
		(width 0.089408)
		(layer "In2.Cu")
		(net "RST_PCIE_CPU_DEV0_N")
	)
	(segment
		(start 426.372528 -114.575082)
		(end 425.438316 -115.509294)
		(width 0.089408)
		(layer "In2.Cu")
		(net "RST_PCIE_CPU_DEV0_N")
	)
	(segment
		(start 421.371522 -62.719712)
		(end 422.107106 -62.719712)
		(width 0.089408)
		(layer "In2.Cu")
		(net "RST_PCIE_CPU_DEV0_N")
	)
	(segment
		(start 422.971214 -115.509294)
		(end 422.085516 -116.394992)
		(width 0.089408)
		(layer "In2.Cu")
		(net "RST_PCIE_CPU_DEV0_N")
	)
	(segment
		(start 418.045646 -103.720646)
		(end 418.045646 -103.562658)
		(width 0.089408)
		(layer "In2.Cu")
		(net "RST_PCIE_CPU_DEV0_N")
	)
	(segment
		(start 426.372528 -113.92281)
		(end 426.372528 -114.575082)
		(width 0.089408)
		(layer "In2.Cu")
		(net "RST_PCIE_CPU_DEV0_N")
	)
	(segment
		(start 418.786056 -86.84514)
		(end 418.786056 -83.376516)
		(width 0.089408)
		(layer "In2.Cu")
		(net "RST_PCIE_CPU_DEV0_N")
	)
	(segment
		(start 421.426132 -116.395246)
		(end 419.069774 -116.395246)
		(width 0.089408)
		(layer "In2.Cu")
		(net "RST_PCIE_CPU_DEV0_N")
	)
	(segment
		(start 434.01488 -112.463834)
		(end 427.831504 -112.463834)
		(width 0.089408)
		(layer "In2.Cu")
		(net "RST_PCIE_CPU_DEV0_N")
	)
	(segment
		(start 418.045392 -106.939588)
		(end 418.045392 -103.7209)
		(width 0.089408)
		(layer "In2.Cu")
		(net "RST_PCIE_CPU_DEV0_N")
	)
	(segment
		(start 418.0459 -103.562404)
		(end 418.0459 -103.24592)
		(width 0.089408)
		(layer "In2.Cu")
		(net "RST_PCIE_CPU_DEV0_N")
	)
	(segment
		(start 476.637096 -114.65433)
		(end 476.637096 -113.808002)
		(width 0.089408)
		(layer "In2.Cu")
		(net "RST_PCIE_CPU_DEV0_N")
	)
	(segment
		(start 418.045392 -103.7209)
		(end 418.045646 -103.720646)
		(width 0.089408)
		(layer "In2.Cu")
		(net "RST_PCIE_CPU_DEV0_N")
	)
	(segment
		(start 481.703634 -121.2088)
		(end 480.412552 -119.917718)
		(width 0.089408)
		(layer "In2.Cu")
		(net "RST_PCIE_CPU_DEV0_N")
	)
	(segment
		(start 417.79825 -115.123722)
		(end 417.79825 -107.18673)
		(width 0.089408)
		(layer "In2.Cu")
		(net "RST_PCIE_CPU_DEV0_N")
	)
	(segment
		(start 427.831504 -112.463834)
		(end 426.372528 -113.92281)
		(width 0.089408)
		(layer "In2.Cu")
		(net "RST_PCIE_CPU_DEV0_N")
	)
	(segment
		(start 480.412552 -118.429786)
		(end 476.637096 -114.65433)
		(width 0.089408)
		(layer "In2.Cu")
		(net "RST_PCIE_CPU_DEV0_N")
	)
	(segment
		(start 418.78631 -86.845394)
		(end 418.786056 -86.84514)
		(width 0.089408)
		(layer "In2.Cu")
		(net "RST_PCIE_CPU_DEV0_N")
	)
	(segment
		(start 439.743596 -113.316004)
		(end 434.86705 -113.316004)
		(width 0.089408)
		(layer "In2.Cu")
		(net "RST_PCIE_CPU_DEV0_N")
	)
	(segment
		(start 419.389052 -75.090274)
		(end 419.389052 -74.932286)
		(width 0.089408)
		(layer "In2.Cu")
		(net "RST_PCIE_CPU_DEV0_N")
	)
	(segment
		(start 381.103886 -69.924676)
		(end 381.470662 -70.291452)
		(width 0.089408)
		(layer "In4.Cu")
		(net "RST_PCIE_CPU_DEV0_N")
	)
	(segment
		(start 420.711122 -62.719712)
		(end 422.148 -62.719712)
		(width 0.089408)
		(layer "In4.Cu")
		(net "RST_PCIE_CPU_DEV0_N")
	)
	(segment
		(start 381.470662 -70.291452)
		(end 407.755344 -70.291452)
		(width 0.089408)
		(layer "In4.Cu")
		(net "RST_PCIE_CPU_DEV0_N")
	)
	(segment
		(start 411.30982 -69.55282)
		(end 411.30982 -69.54901)
		(width 0.089408)
		(layer "In4.Cu")
		(net "RST_PCIE_CPU_DEV0_N")
	)
	(segment
		(start 422.148 -62.719712)
		(end 422.390824 -62.476888)
		(width 0.089408)
		(layer "In4.Cu")
		(net "RST_PCIE_CPU_DEV0_N")
	)
	(segment
		(start 375.297954 -70.295262)
		(end 375.718578 -69.874638)
		(width 0.089408)
		(layer "In4.Cu")
		(net "RST_PCIE_CPU_DEV0_N")
	)
	(segment
		(start 407.755344 -70.291452)
		(end 408.162506 -69.88429)
		(width 0.089408)
		(layer "In4.Cu")
		(net "RST_PCIE_CPU_DEV0_N")
	)
	(segment
		(start 415.686748 -67.959986)
		(end 416.473894 -67.17284)
		(width 0.089408)
		(layer "In4.Cu")
		(net "RST_PCIE_CPU_DEV0_N")
	)
	(segment
		(start 376.344942 -69.329808)
		(end 376.552968 -69.121782)
		(width 0.089408)
		(layer "In4.Cu")
		(net "RST_PCIE_CPU_DEV0_N")
	)
	(segment
		(start 377.699524 -69.121782)
		(end 378.502418 -69.924676)
		(width 0.089408)
		(layer "In4.Cu")
		(net "RST_PCIE_CPU_DEV0_N")
	)
	(segment
		(start 410.97835 -69.88429)
		(end 411.30982 -69.55282)
		(width 0.089408)
		(layer "In4.Cu")
		(net "RST_PCIE_CPU_DEV0_N")
	)
	(segment
		(start 411.30982 -69.54901)
		(end 411.882082 -68.976748)
		(width 0.089408)
		(layer "In4.Cu")
		(net "RST_PCIE_CPU_DEV0_N")
	)
	(segment
		(start 378.502418 -69.924676)
		(end 381.103886 -69.924676)
		(width 0.089408)
		(layer "In4.Cu")
		(net "RST_PCIE_CPU_DEV0_N")
	)
	(segment
		(start 414.491932 -68.976748)
		(end 415.508694 -67.959986)
		(width 0.089408)
		(layer "In4.Cu")
		(net "RST_PCIE_CPU_DEV0_N")
	)
	(segment
		(start 376.344942 -69.773038)
		(end 376.344942 -69.329808)
		(width 0.089408)
		(layer "In4.Cu")
		(net "RST_PCIE_CPU_DEV0_N")
	)
	(segment
		(start 422.390824 -62.476888)
		(end 422.390824 -61.869828)
		(width 0.089408)
		(layer "In4.Cu")
		(net "RST_PCIE_CPU_DEV0_N")
	)
	(segment
		(start 376.552968 -69.121782)
		(end 377.699524 -69.121782)
		(width 0.089408)
		(layer "In4.Cu")
		(net "RST_PCIE_CPU_DEV0_N")
	)
	(segment
		(start 375.144792 -70.295262)
		(end 375.297954 -70.295262)
		(width 0.089408)
		(layer "In4.Cu")
		(net "RST_PCIE_CPU_DEV0_N")
	)
	(segment
		(start 411.882082 -68.976748)
		(end 414.491932 -68.976748)
		(width 0.089408)
		(layer "In4.Cu")
		(net "RST_PCIE_CPU_DEV0_N")
	)
	(segment
		(start 416.473894 -66.95694)
		(end 420.711122 -62.719712)
		(width 0.089408)
		(layer "In4.Cu")
		(net "RST_PCIE_CPU_DEV0_N")
	)
	(segment
		(start 408.162506 -69.88429)
		(end 410.97835 -69.88429)
		(width 0.089408)
		(layer "In4.Cu")
		(net "RST_PCIE_CPU_DEV0_N")
	)
	(segment
		(start 416.473894 -67.17284)
		(end 416.473894 -66.95694)
		(width 0.089408)
		(layer "In4.Cu")
		(net "RST_PCIE_CPU_DEV0_N")
	)
	(segment
		(start 415.508694 -67.959986)
		(end 415.686748 -67.959986)
		(width 0.089408)
		(layer "In4.Cu")
		(net "RST_PCIE_CPU_DEV0_N")
	)
	(segment
		(start 376.243342 -69.874638)
		(end 376.344942 -69.773038)
		(width 0.089408)
		(layer "In4.Cu")
		(net "RST_PCIE_CPU_DEV0_N")
	)
	(segment
		(start 375.718578 -69.874638)
		(end 376.243342 -69.874638)
		(width 0.089408)
		(layer "In4.Cu")
		(net "RST_PCIE_CPU_DEV0_N")
	)
	(segment
		(start 384.937508 -116.418106)
		(end 385.26085 -116.094764)
		(width 0.12446)
		(layer "F.Cu")
		(net "P1V05_PCH_STBY_VCCA_XTAL")
	)
	(segment
		(start 384.761486 -116.418106)
		(end 384.937508 -116.418106)
		(width 0.12446)
		(layer "F.Cu")
		(net "P1V05_PCH_STBY_VCCA_XTAL")
	)
	(segment
		(start 384.76555 -115.86464)
		(end 384.5814 -116.04879)
		(width 0.12446)
		(layer "F.Cu")
		(net "P1V05_PCH_STBY_VCCA_XTAL")
	)
	(segment
		(start 384.5814 -116.04879)
		(end 384.5814 -116.23802)
		(width 0.12446)
		(layer "F.Cu")
		(net "P1V05_PCH_STBY_VCCA_XTAL")
	)
	(segment
		(start 384.5814 -116.23802)
		(end 384.761486 -116.418106)
		(width 0.12446)
		(layer "F.Cu")
		(net "P1V05_PCH_STBY_VCCA_XTAL")
	)
	(via
		(at 381.8636 -133.264402)
		(size 0.508)
		(drill 0.254)
		(layers "F.Cu" "B.Cu")
		(net "P1V05_PCH_STBY_VCCA_XTAL")
	)
	(via
		(at 385.26085 -116.094764)
		(size 0.508)
		(drill 0.254)
		(layers "F.Cu" "B.Cu")
		(net "P1V05_PCH_STBY_VCCA_XTAL")
	)
	(via
		(at 370.56949 -130.16738)
		(size 0.508)
		(drill 0.254)
		(layers "F.Cu" "B.Cu")
		(net "P1V05_PCH_STBY_VCCA_XTAL")
	)
	(segment
		(start 378.61748 -127.83566)
		(end 374.42394 -127.83566)
		(width 0.254)
		(layer "In2.Cu")
		(net "P1V05_PCH_STBY_VCCA_XTAL")
	)
	(segment
		(start 372.09476 -127.83566)
		(end 370.57584 -129.35458)
		(width 0.635)
		(layer "In2.Cu")
		(net "P1V05_PCH_STBY_VCCA_XTAL")
	)
	(segment
		(start 385.26085 -116.094764)
		(end 384.5179 -116.524024)
		(width 0.254)
		(layer "In2.Cu")
		(net "P1V05_PCH_STBY_VCCA_XTAL")
	)
	(segment
		(start 384.27025 -118.653814)
		(end 384.27025 -118.686834)
		(width 0.254)
		(layer "In2.Cu")
		(net "P1V05_PCH_STBY_VCCA_XTAL")
	)
	(segment
		(start 370.57584 -130.16738)
		(end 370.56949 -130.16738)
		(width 0.635)
		(layer "In2.Cu")
		(net "P1V05_PCH_STBY_VCCA_XTAL")
	)
	(segment
		(start 384.27025 -116.936774)
		(end 384.27025 -116.969794)
		(width 0.254)
		(layer "In2.Cu")
		(net "P1V05_PCH_STBY_VCCA_XTAL")
	)
	(segment
		(start 384.27025 -123.804934)
		(end 384.27025 -124.062236)
		(width 0.254)
		(layer "In2.Cu")
		(net "P1V05_PCH_STBY_VCCA_XTAL")
	)
	(segment
		(start 370.57584 -129.35458)
		(end 370.57584 -130.16738)
		(width 0.635)
		(layer "In2.Cu")
		(net "P1V05_PCH_STBY_VCCA_XTAL")
	)
	(segment
		(start 384.27025 -124.062236)
		(end 381.891286 -126.4412)
		(width 0.254)
		(layer "In2.Cu")
		(net "P1V05_PCH_STBY_VCCA_XTAL")
	)
	(segment
		(start 374.42394 -127.83566)
		(end 372.09476 -127.83566)
		(width 0.635)
		(layer "In2.Cu")
		(net "P1V05_PCH_STBY_VCCA_XTAL")
	)
	(segment
		(start 381.891286 -126.4412)
		(end 380.01194 -126.4412)
		(width 0.254)
		(layer "In2.Cu")
		(net "P1V05_PCH_STBY_VCCA_XTAL")
	)
	(segment
		(start 380.01194 -126.4412)
		(end 378.61748 -127.83566)
		(width 0.254)
		(layer "In2.Cu")
		(net "P1V05_PCH_STBY_VCCA_XTAL")
	)
	(arc
		(start 384.5179 -120.816624)
		(mid 384.765825 -121.245884)
		(end 384.5179 -121.675144)
		(width 0.254)
		(layer "In2.Cu")
		(net "P1V05_PCH_STBY_VCCA_XTAL")
	)
	(arc
		(start 384.0226 -118.241064)
		(mid 384.199902 -118.415353)
		(end 384.27025 -118.653814)
		(width 0.254)
		(layer "In2.Cu")
		(net "P1V05_PCH_STBY_VCCA_XTAL")
	)
	(arc
		(start 384.5179 -119.958104)
		(mid 384.269975 -120.387364)
		(end 384.5179 -120.816624)
		(width 0.254)
		(layer "In2.Cu")
		(net "P1V05_PCH_STBY_VCCA_XTAL")
	)
	(arc
		(start 384.27025 -116.969794)
		(mid 384.199902 -117.208255)
		(end 384.0226 -117.382544)
		(width 0.254)
		(layer "In2.Cu")
		(net "P1V05_PCH_STBY_VCCA_XTAL")
	)
	(arc
		(start 384.5179 -121.675144)
		(mid 384.269975 -122.104404)
		(end 384.5179 -122.533664)
		(width 0.254)
		(layer "In2.Cu")
		(net "P1V05_PCH_STBY_VCCA_XTAL")
	)
	(arc
		(start 384.5179 -123.392184)
		(mid 384.340598 -123.566473)
		(end 384.27025 -123.804934)
		(width 0.254)
		(layer "In2.Cu")
		(net "P1V05_PCH_STBY_VCCA_XTAL")
	)
	(arc
		(start 384.27025 -118.686834)
		(mid 384.340598 -118.925295)
		(end 384.5179 -119.099584)
		(width 0.254)
		(layer "In2.Cu")
		(net "P1V05_PCH_STBY_VCCA_XTAL")
	)
	(arc
		(start 384.5179 -116.524024)
		(mid 384.340598 -116.698313)
		(end 384.27025 -116.936774)
		(width 0.254)
		(layer "In2.Cu")
		(net "P1V05_PCH_STBY_VCCA_XTAL")
	)
	(arc
		(start 384.5179 -119.099584)
		(mid 384.765825 -119.528844)
		(end 384.5179 -119.958104)
		(width 0.254)
		(layer "In2.Cu")
		(net "P1V05_PCH_STBY_VCCA_XTAL")
	)
	(arc
		(start 384.5179 -122.533664)
		(mid 384.765825 -122.962924)
		(end 384.5179 -123.392184)
		(width 0.254)
		(layer "In2.Cu")
		(net "P1V05_PCH_STBY_VCCA_XTAL")
	)
	(arc
		(start 384.0226 -117.382544)
		(mid 383.774675 -117.811804)
		(end 384.0226 -118.241064)
		(width 0.254)
		(layer "In2.Cu")
		(net "P1V05_PCH_STBY_VCCA_XTAL")
	)
	(segment
		(start 380.819914 -133.985)
		(end 378.5997 -133.985)
		(width 0.254)
		(layer "In11.Cu")
		(net "P1V05_PCH_STBY_VCCA_XTAL")
	)
	(segment
		(start 381.8636 -133.264402)
		(end 381.540512 -133.264402)
		(width 0.254)
		(layer "In11.Cu")
		(net "P1V05_PCH_STBY_VCCA_XTAL")
	)
	(segment
		(start 370.72951 -130.3274)
		(end 370.56949 -130.16738)
		(width 0.254)
		(layer "In11.Cu")
		(net "P1V05_PCH_STBY_VCCA_XTAL")
	)
	(segment
		(start 375.534682 -131.953508)
		(end 374.248934 -131.953508)
		(width 0.254)
		(layer "In11.Cu")
		(net "P1V05_PCH_STBY_VCCA_XTAL")
	)
	(segment
		(start 374.248934 -131.953508)
		(end 372.622826 -130.3274)
		(width 0.254)
		(layer "In11.Cu")
		(net "P1V05_PCH_STBY_VCCA_XTAL")
	)
	(segment
		(start 376.079004 -132.49783)
		(end 375.534682 -131.953508)
		(width 0.254)
		(layer "In11.Cu")
		(net "P1V05_PCH_STBY_VCCA_XTAL")
	)
	(segment
		(start 378.5997 -133.985)
		(end 377.11253 -132.49783)
		(width 0.254)
		(layer "In11.Cu")
		(net "P1V05_PCH_STBY_VCCA_XTAL")
	)
	(segment
		(start 372.622826 -130.3274)
		(end 370.72951 -130.3274)
		(width 0.254)
		(layer "In11.Cu")
		(net "P1V05_PCH_STBY_VCCA_XTAL")
	)
	(segment
		(start 377.11253 -132.49783)
		(end 376.079004 -132.49783)
		(width 0.254)
		(layer "In11.Cu")
		(net "P1V05_PCH_STBY_VCCA_XTAL")
	)
	(segment
		(start 381.540512 -133.264402)
		(end 380.819914 -133.985)
		(width 0.254)
		(layer "In11.Cu")
		(net "P1V05_PCH_STBY_VCCA_XTAL")
	)
	(segment
		(start 386.13715 -115.05565)
		(end 386.058918 -115.133882)
		(width 0.12446)
		(layer "F.Cu")
		(net "P1V05_PCH_STBY_VCCA_PLL0")
	)
	(segment
		(start 385.74345 -115.04549)
		(end 385.74345 -114.66195)
		(width 0.12446)
		(layer "F.Cu")
		(net "P1V05_PCH_STBY_VCCA_PLL0")
	)
	(segment
		(start 386.058918 -115.133882)
		(end 385.831842 -115.133882)
		(width 0.12446)
		(layer "F.Cu")
		(net "P1V05_PCH_STBY_VCCA_PLL0")
	)
	(segment
		(start 385.831842 -115.133882)
		(end 385.74345 -115.04549)
		(width 0.12446)
		(layer "F.Cu")
		(net "P1V05_PCH_STBY_VCCA_PLL0")
	)
	(via
		(at 373.888 -135.128)
		(size 0.6604)
		(drill 0.3302)
		(layers "F.Cu" "B.Cu")
		(net "P1V05_PCH_STBY_VCCA_PLL0")
	)
	(via
		(at 385.74345 -114.66195)
		(size 0.508)
		(drill 0.254)
		(layers "F.Cu" "B.Cu")
		(net "P1V05_PCH_STBY_VCCA_PLL0")
	)
	(via
		(at 375.5898 -135.5598)
		(size 0.508)
		(drill 0.254)
		(layers "F.Cu" "B.Cu")
		(net "P1V05_PCH_STBY_VCCA_PLL0")
	)
	(segment
		(start 375.412 -134.8105)
		(end 375.5898 -134.9883)
		(width 0.254)
		(layer "B.Cu")
		(net "P1V05_PCH_STBY_VCCA_PLL0")
	)
	(segment
		(start 375.5898 -134.9883)
		(end 375.5898 -135.5598)
		(width 0.254)
		(layer "B.Cu")
		(net "P1V05_PCH_STBY_VCCA_PLL0")
	)
	(segment
		(start 374.72366 -128.3081)
		(end 378.806456 -128.3081)
		(width 0.254)
		(layer "In2.Cu")
		(net "P1V05_PCH_STBY_VCCA_PLL0")
	)
	(segment
		(start 373.6213 -128.651)
		(end 374.38076 -128.651)
		(width 0.254)
		(layer "In2.Cu")
		(net "P1V05_PCH_STBY_VCCA_PLL0")
	)
	(segment
		(start 382.188974 -126.7968)
		(end 383.16662 -125.819154)
		(width 0.254)
		(layer "In2.Cu")
		(net "P1V05_PCH_STBY_VCCA_PLL0")
	)
	(segment
		(start 383.16662 -125.819154)
		(end 383.628646 -125.819154)
		(width 0.254)
		(layer "In2.Cu")
		(net "P1V05_PCH_STBY_VCCA_PLL0")
	)
	(segment
		(start 382.089406 -126.896114)
		(end 382.18872 -126.7968)
		(width 0.254)
		(layer "In2.Cu")
		(net "P1V05_PCH_STBY_VCCA_PLL0")
	)
	(segment
		(start 375.5898 -135.5598)
		(end 375.5136 -135.4836)
		(width 0.635)
		(layer "In2.Cu")
		(net "P1V05_PCH_STBY_VCCA_PLL0")
	)
	(segment
		(start 385.74345 -116.054378)
		(end 385.74345 -114.66195)
		(width 0.254)
		(layer "In2.Cu")
		(net "P1V05_PCH_STBY_VCCA_PLL0")
	)
	(segment
		(start 385.75615 -116.094764)
		(end 385.74345 -116.054378)
		(width 0.254)
		(layer "In2.Cu")
		(net "P1V05_PCH_STBY_VCCA_PLL0")
	)
	(segment
		(start 383.628646 -125.819154)
		(end 385.26085 -124.18695)
		(width 0.254)
		(layer "In2.Cu")
		(net "P1V05_PCH_STBY_VCCA_PLL0")
	)
	(segment
		(start 373.05996 -129.21234)
		(end 373.34952 -128.92278)
		(width 0.635)
		(layer "In2.Cu")
		(net "P1V05_PCH_STBY_VCCA_PLL0")
	)
	(segment
		(start 373.05996 -134.43966)
		(end 373.05996 -129.21234)
		(width 0.635)
		(layer "In2.Cu")
		(net "P1V05_PCH_STBY_VCCA_PLL0")
	)
	(segment
		(start 385.26085 -124.18695)
		(end 385.26085 -123.804934)
		(width 0.254)
		(layer "In2.Cu")
		(net "P1V05_PCH_STBY_VCCA_PLL0")
	)
	(segment
		(start 378.806456 -128.3081)
		(end 380.218442 -126.896114)
		(width 0.254)
		(layer "In2.Cu")
		(net "P1V05_PCH_STBY_VCCA_PLL0")
	)
	(segment
		(start 374.1039 -135.4836)
		(end 373.05996 -134.43966)
		(width 0.635)
		(layer "In2.Cu")
		(net "P1V05_PCH_STBY_VCCA_PLL0")
	)
	(segment
		(start 385.26085 -118.686834)
		(end 385.26085 -118.653814)
		(width 0.254)
		(layer "In2.Cu")
		(net "P1V05_PCH_STBY_VCCA_PLL0")
	)
	(segment
		(start 374.38076 -128.651)
		(end 374.72366 -128.3081)
		(width 0.254)
		(layer "In2.Cu")
		(net "P1V05_PCH_STBY_VCCA_PLL0")
	)
	(segment
		(start 382.18872 -126.7968)
		(end 382.188974 -126.7968)
		(width 0.254)
		(layer "In2.Cu")
		(net "P1V05_PCH_STBY_VCCA_PLL0")
	)
	(segment
		(start 373.34952 -128.92278)
		(end 373.6213 -128.651)
		(width 0.254)
		(layer "In2.Cu")
		(net "P1V05_PCH_STBY_VCCA_PLL0")
	)
	(segment
		(start 375.5136 -135.4836)
		(end 374.1039 -135.4836)
		(width 0.635)
		(layer "In2.Cu")
		(net "P1V05_PCH_STBY_VCCA_PLL0")
	)
	(segment
		(start 380.218442 -126.896114)
		(end 382.089406 -126.896114)
		(width 0.254)
		(layer "In2.Cu")
		(net "P1V05_PCH_STBY_VCCA_PLL0")
	)
	(segment
		(start 385.26085 -116.969794)
		(end 385.26085 -116.936774)
		(width 0.254)
		(layer "In2.Cu")
		(net "P1V05_PCH_STBY_VCCA_PLL0")
	)
	(segment
		(start 385.75615 -116.111274)
		(end 385.75615 -116.094764)
		(width 0.254)
		(layer "In2.Cu")
		(net "P1V05_PCH_STBY_VCCA_PLL0")
	)
	(arc
		(start 385.5085 -121.675144)
		(mid 385.756425 -121.245884)
		(end 385.5085 -120.816624)
		(width 0.254)
		(layer "In2.Cu")
		(net "P1V05_PCH_STBY_VCCA_PLL0")
	)
	(arc
		(start 385.5085 -116.524024)
		(mid 385.685802 -116.349735)
		(end 385.75615 -116.111274)
		(width 0.254)
		(layer "In2.Cu")
		(net "P1V05_PCH_STBY_VCCA_PLL0")
	)
	(arc
		(start 385.0132 -118.241064)
		(mid 384.765275 -117.811804)
		(end 385.0132 -117.382544)
		(width 0.254)
		(layer "In2.Cu")
		(net "P1V05_PCH_STBY_VCCA_PLL0")
	)
	(arc
		(start 385.26085 -118.653814)
		(mid 385.190502 -118.415353)
		(end 385.0132 -118.241064)
		(width 0.254)
		(layer "In2.Cu")
		(net "P1V05_PCH_STBY_VCCA_PLL0")
	)
	(arc
		(start 385.5085 -119.958104)
		(mid 385.756425 -119.528844)
		(end 385.5085 -119.099584)
		(width 0.254)
		(layer "In2.Cu")
		(net "P1V05_PCH_STBY_VCCA_PLL0")
	)
	(arc
		(start 385.5085 -122.533664)
		(mid 385.260575 -122.104404)
		(end 385.5085 -121.675144)
		(width 0.254)
		(layer "In2.Cu")
		(net "P1V05_PCH_STBY_VCCA_PLL0")
	)
	(arc
		(start 385.5085 -120.816624)
		(mid 385.260575 -120.387364)
		(end 385.5085 -119.958104)
		(width 0.254)
		(layer "In2.Cu")
		(net "P1V05_PCH_STBY_VCCA_PLL0")
	)
	(arc
		(start 385.0132 -117.382544)
		(mid 385.190502 -117.208255)
		(end 385.26085 -116.969794)
		(width 0.254)
		(layer "In2.Cu")
		(net "P1V05_PCH_STBY_VCCA_PLL0")
	)
	(arc
		(start 385.5085 -119.099584)
		(mid 385.331198 -118.925295)
		(end 385.26085 -118.686834)
		(width 0.254)
		(layer "In2.Cu")
		(net "P1V05_PCH_STBY_VCCA_PLL0")
	)
	(arc
		(start 385.26085 -123.804934)
		(mid 385.331198 -123.566473)
		(end 385.5085 -123.392184)
		(width 0.254)
		(layer "In2.Cu")
		(net "P1V05_PCH_STBY_VCCA_PLL0")
	)
	(arc
		(start 385.26085 -116.936774)
		(mid 385.331198 -116.698313)
		(end 385.5085 -116.524024)
		(width 0.254)
		(layer "In2.Cu")
		(net "P1V05_PCH_STBY_VCCA_PLL0")
	)
	(arc
		(start 385.5085 -123.392184)
		(mid 385.756425 -122.962924)
		(end 385.5085 -122.533664)
		(width 0.254)
		(layer "In2.Cu")
		(net "P1V05_PCH_STBY_VCCA_PLL0")
	)
	(segment
		(start 385.33705 -113.45545)
		(end 384.937 -113.8555)
		(width 0.254)
		(layer "F.Cu")
		(net "P1V05_PCH_STBY_VCCA_PLL1")
	)
	(via
		(at 384.937 -113.8555)
		(size 0.508)
		(drill 0.254)
		(layers "F.Cu" "B.Cu")
		(net "P1V05_PCH_STBY_VCCA_PLL1")
	)
	(via
		(at 378.30252 -138.69162)
		(size 0.508)
		(drill 0.254)
		(layers "F.Cu" "B.Cu")
		(net "P1V05_PCH_STBY_VCCA_PLL1")
	)
	(segment
		(start 369.35156 -133.051296)
		(end 370.170964 -133.8707)
		(width 0.635)
		(layer "In2.Cu")
		(net "P1V05_PCH_STBY_VCCA_PLL1")
	)
	(segment
		(start 374.5484 -127.18796)
		(end 371.07622 -127.18796)
		(width 0.254)
		(layer "In2.Cu")
		(net "P1V05_PCH_STBY_VCCA_PLL1")
	)
	(segment
		(start 377.19762 -136.40816)
		(end 378.30252 -137.51306)
		(width 0.635)
		(layer "In2.Cu")
		(net "P1V05_PCH_STBY_VCCA_PLL1")
	)
	(segment
		(start 384.937 -113.8555)
		(end 384.847084 -113.8555)
		(width 0.254)
		(layer "In2.Cu")
		(net "P1V05_PCH_STBY_VCCA_PLL1")
	)
	(segment
		(start 384.847084 -113.8555)
		(end 384.379978 -114.322606)
		(width 0.254)
		(layer "In2.Cu")
		(net "P1V05_PCH_STBY_VCCA_PLL1")
	)
	(segment
		(start 379.76048 -125.932946)
		(end 378.363226 -127.3302)
		(width 0.254)
		(layer "In2.Cu")
		(net "P1V05_PCH_STBY_VCCA_PLL1")
	)
	(segment
		(start 384.662934 -115.659916)
		(end 384.18516 -116.13769)
		(width 0.254)
		(layer "In2.Cu")
		(net "P1V05_PCH_STBY_VCCA_PLL1")
	)
	(segment
		(start 371.19052 -133.8707)
		(end 373.72798 -136.40816)
		(width 0.635)
		(layer "In2.Cu")
		(net "P1V05_PCH_STBY_VCCA_PLL1")
	)
	(segment
		(start 383.27965 -116.936774)
		(end 383.27965 -116.969794)
		(width 0.254)
		(layer "In2.Cu")
		(net "P1V05_PCH_STBY_VCCA_PLL1")
	)
	(segment
		(start 371.07622 -127.18796)
		(end 370.4717 -127.79248)
		(width 0.254)
		(layer "In2.Cu")
		(net "P1V05_PCH_STBY_VCCA_PLL1")
	)
	(segment
		(start 374.69064 -127.3302)
		(end 374.5484 -127.18796)
		(width 0.254)
		(layer "In2.Cu")
		(net "P1V05_PCH_STBY_VCCA_PLL1")
	)
	(segment
		(start 383.27965 -123.804934)
		(end 383.27965 -124.155962)
		(width 0.254)
		(layer "In2.Cu")
		(net "P1V05_PCH_STBY_VCCA_PLL1")
	)
	(segment
		(start 378.363226 -127.3302)
		(end 374.69064 -127.3302)
		(width 0.254)
		(layer "In2.Cu")
		(net "P1V05_PCH_STBY_VCCA_PLL1")
	)
	(segment
		(start 384.379978 -114.888518)
		(end 384.662934 -115.171474)
		(width 0.254)
		(layer "In2.Cu")
		(net "P1V05_PCH_STBY_VCCA_PLL1")
	)
	(segment
		(start 384.662934 -115.171474)
		(end 384.662934 -115.659916)
		(width 0.254)
		(layer "In2.Cu")
		(net "P1V05_PCH_STBY_VCCA_PLL1")
	)
	(segment
		(start 370.4717 -127.79248)
		(end 369.35156 -128.91262)
		(width 0.635)
		(layer "In2.Cu")
		(net "P1V05_PCH_STBY_VCCA_PLL1")
	)
	(segment
		(start 384.18516 -116.13769)
		(end 383.5273 -116.524024)
		(width 0.254)
		(layer "In2.Cu")
		(net "P1V05_PCH_STBY_VCCA_PLL1")
	)
	(segment
		(start 381.502666 -125.932946)
		(end 379.76048 -125.932946)
		(width 0.254)
		(layer "In2.Cu")
		(net "P1V05_PCH_STBY_VCCA_PLL1")
	)
	(segment
		(start 369.35156 -128.91262)
		(end 369.35156 -133.051296)
		(width 0.635)
		(layer "In2.Cu")
		(net "P1V05_PCH_STBY_VCCA_PLL1")
	)
	(segment
		(start 384.379978 -114.322606)
		(end 384.379978 -114.888518)
		(width 0.254)
		(layer "In2.Cu")
		(net "P1V05_PCH_STBY_VCCA_PLL1")
	)
	(segment
		(start 378.30252 -137.51306)
		(end 378.30252 -138.69162)
		(width 0.635)
		(layer "In2.Cu")
		(net "P1V05_PCH_STBY_VCCA_PLL1")
	)
	(segment
		(start 383.27965 -124.155962)
		(end 381.502666 -125.932946)
		(width 0.254)
		(layer "In2.Cu")
		(net "P1V05_PCH_STBY_VCCA_PLL1")
	)
	(segment
		(start 383.27965 -118.653814)
		(end 383.27965 -118.686834)
		(width 0.254)
		(layer "In2.Cu")
		(net "P1V05_PCH_STBY_VCCA_PLL1")
	)
	(segment
		(start 373.72798 -136.40816)
		(end 377.19762 -136.40816)
		(width 0.635)
		(layer "In2.Cu")
		(net "P1V05_PCH_STBY_VCCA_PLL1")
	)
	(segment
		(start 370.170964 -133.8707)
		(end 371.19052 -133.8707)
		(width 0.635)
		(layer "In2.Cu")
		(net "P1V05_PCH_STBY_VCCA_PLL1")
	)
	(arc
		(start 383.5273 -121.675144)
		(mid 383.279375 -122.104404)
		(end 383.5273 -122.533664)
		(width 0.254)
		(layer "In2.Cu")
		(net "P1V05_PCH_STBY_VCCA_PLL1")
	)
	(arc
		(start 383.5273 -122.533664)
		(mid 383.775225 -122.962924)
		(end 383.5273 -123.392184)
		(width 0.254)
		(layer "In2.Cu")
		(net "P1V05_PCH_STBY_VCCA_PLL1")
	)
	(arc
		(start 383.27965 -116.969794)
		(mid 383.209302 -117.208255)
		(end 383.032 -117.382544)
		(width 0.254)
		(layer "In2.Cu")
		(net "P1V05_PCH_STBY_VCCA_PLL1")
	)
	(arc
		(start 383.5273 -119.099584)
		(mid 383.775225 -119.528844)
		(end 383.5273 -119.958104)
		(width 0.254)
		(layer "In2.Cu")
		(net "P1V05_PCH_STBY_VCCA_PLL1")
	)
	(arc
		(start 383.5273 -119.958104)
		(mid 383.279375 -120.387364)
		(end 383.5273 -120.816624)
		(width 0.254)
		(layer "In2.Cu")
		(net "P1V05_PCH_STBY_VCCA_PLL1")
	)
	(arc
		(start 383.5273 -120.816624)
		(mid 383.775225 -121.245884)
		(end 383.5273 -121.675144)
		(width 0.254)
		(layer "In2.Cu")
		(net "P1V05_PCH_STBY_VCCA_PLL1")
	)
	(arc
		(start 383.5273 -123.392184)
		(mid 383.349998 -123.566473)
		(end 383.27965 -123.804934)
		(width 0.254)
		(layer "In2.Cu")
		(net "P1V05_PCH_STBY_VCCA_PLL1")
	)
	(arc
		(start 383.5273 -116.524024)
		(mid 383.349998 -116.698313)
		(end 383.27965 -116.936774)
		(width 0.254)
		(layer "In2.Cu")
		(net "P1V05_PCH_STBY_VCCA_PLL1")
	)
	(arc
		(start 383.032 -118.241064)
		(mid 383.209302 -118.415353)
		(end 383.27965 -118.653814)
		(width 0.254)
		(layer "In2.Cu")
		(net "P1V05_PCH_STBY_VCCA_PLL1")
	)
	(arc
		(start 383.032 -117.382544)
		(mid 382.784075 -117.811804)
		(end 383.032 -118.241064)
		(width 0.254)
		(layer "In2.Cu")
		(net "P1V05_PCH_STBY_VCCA_PLL1")
	)
	(arc
		(start 383.27965 -118.686834)
		(mid 383.349998 -118.925295)
		(end 383.5273 -119.099584)
		(width 0.254)
		(layer "In2.Cu")
		(net "P1V05_PCH_STBY_VCCA_PLL1")
	)
	(segment
		(start 390.13765 -105.45445)
		(end 390.5377 -105.0544)
		(width 0.10795)
		(layer "F.Cu")
		(net "TP_PCH_RSVD59")
	)
	(via
		(at 390.5377 -105.0544)
		(size 0.508)
		(drill 0.254)
		(layers "F.Cu" "B.Cu")
		(net "TP_PCH_RSVD59")
	)
	(segment
		(start 472.092782 -115.011962)
		(end 472.60002 -115.5192)
		(width 0.10795)
		(layer "F.Cu")
		(net "RMII_BMC_OCP_TXEN")
	)
	(segment
		(start 475.5896 -115.5192)
		(end 475.800928 -115.730528)
		(width 0.10795)
		(layer "F.Cu")
		(net "RMII_BMC_OCP_TXEN")
	)
	(segment
		(start 475.800928 -115.730528)
		(end 475.800928 -116.993162)
		(width 0.10795)
		(layer "F.Cu")
		(net "RMII_BMC_OCP_TXEN")
	)
	(segment
		(start 472.60002 -115.5192)
		(end 475.5896 -115.5192)
		(width 0.10795)
		(layer "F.Cu")
		(net "RMII_BMC_OCP_TXEN")
	)
	(via
		(at 472.092782 -115.011962)
		(size 0.508)
		(drill 0.254)
		(layers "F.Cu" "B.Cu")
		(net "RMII_BMC_OCP_TXEN")
	)
	(via
		(at 472.773248 -116.191284)
		(size 0.6604)
		(drill 0.3302)
		(layers "F.Cu" "B.Cu")
		(net "RMII_BMC_OCP_TXEN")
	)
	(via
		(at 403.82952 -34.252154)
		(size 0.508)
		(drill 0.254)
		(layers "F.Cu" "B.Cu")
		(net "RMII_BMC_OCP_TXEN")
	)
	(segment
		(start 402.59 -34.798)
		(end 402.59 -34.441892)
		(width 0.10795)
		(layer "B.Cu")
		(net "RMII_BMC_OCP_TXEN")
	)
	(segment
		(start 403.82952 -34.252154)
		(end 404.655274 -33.4264)
		(width 0.10795)
		(layer "B.Cu")
		(net "RMII_BMC_OCP_TXEN")
	)
	(segment
		(start 402.931376 -34.100516)
		(end 403.677882 -34.100516)
		(width 0.10795)
		(layer "B.Cu")
		(net "RMII_BMC_OCP_TXEN")
	)
	(segment
		(start 403.677882 -34.100516)
		(end 403.82952 -34.252154)
		(width 0.10795)
		(layer "B.Cu")
		(net "RMII_BMC_OCP_TXEN")
	)
	(segment
		(start 406.787604 -33.886648)
		(end 407.1239 -33.550352)
		(width 0.10795)
		(layer "B.Cu")
		(net "RMII_BMC_OCP_TXEN")
	)
	(segment
		(start 404.655274 -33.4264)
		(end 405.0284 -33.4264)
		(width 0.10795)
		(layer "B.Cu")
		(net "RMII_BMC_OCP_TXEN")
	)
	(segment
		(start 405.0284 -33.6042)
		(end 405.310848 -33.886648)
		(width 0.10795)
		(layer "B.Cu")
		(net "RMII_BMC_OCP_TXEN")
	)
	(segment
		(start 405.0284 -33.4264)
		(end 405.0284 -33.6042)
		(width 0.10795)
		(layer "B.Cu")
		(net "RMII_BMC_OCP_TXEN")
	)
	(segment
		(start 405.310848 -33.886648)
		(end 406.787604 -33.886648)
		(width 0.10795)
		(layer "B.Cu")
		(net "RMII_BMC_OCP_TXEN")
	)
	(segment
		(start 472.092782 -115.011962)
		(end 472.092782 -115.510818)
		(width 0.10795)
		(layer "B.Cu")
		(net "RMII_BMC_OCP_TXEN")
	)
	(segment
		(start 472.092782 -115.510818)
		(end 472.773248 -116.191284)
		(width 0.10795)
		(layer "B.Cu")
		(net "RMII_BMC_OCP_TXEN")
	)
	(segment
		(start 402.59 -34.441892)
		(end 402.931376 -34.100516)
		(width 0.10795)
		(layer "B.Cu")
		(net "RMII_BMC_OCP_TXEN")
	)
	(segment
		(start 407.1239 -33.550352)
		(end 407.654506 -33.550352)
		(width 0.10795)
		(layer "B.Cu")
		(net "RMII_BMC_OCP_TXEN")
	)
	(segment
		(start 419.017958 -47.92218)
		(end 418.399976 -47.304198)
		(width 0.089408)
		(layer "In11.Cu")
		(net "RMII_BMC_OCP_TXEN")
	)
	(segment
		(start 471.796872 -115.011962)
		(end 469.277954 -112.493044)
		(width 0.089408)
		(layer "In11.Cu")
		(net "RMII_BMC_OCP_TXEN")
	)
	(segment
		(start 438.869582 -114.516662)
		(end 438.869582 -114.917982)
		(width 0.089408)
		(layer "In11.Cu")
		(net "RMII_BMC_OCP_TXEN")
	)
	(segment
		(start 418.399976 -47.304198)
		(end 418.399976 -46.948344)
		(width 0.089408)
		(layer "In11.Cu")
		(net "RMII_BMC_OCP_TXEN")
	)
	(segment
		(start 404.379684 -41.121838)
		(end 403.771608 -40.513762)
		(width 0.089408)
		(layer "In11.Cu")
		(net "RMII_BMC_OCP_TXEN")
	)
	(segment
		(start 418.020246 -46.09338)
		(end 417.665408 -45.738542)
		(width 0.089408)
		(layer "In11.Cu")
		(net "RMII_BMC_OCP_TXEN")
	)
	(segment
		(start 417.665408 -45.738542)
		(end 416.52825 -45.738542)
		(width 0.089408)
		(layer "In11.Cu")
		(net "RMII_BMC_OCP_TXEN")
	)
	(segment
		(start 424.872912 -61.045344)
		(end 424.185334 -60.357766)
		(width 0.089408)
		(layer "In11.Cu")
		(net "RMII_BMC_OCP_TXEN")
	)
	(segment
		(start 405.880316 -42.745152)
		(end 405.880316 -42.060114)
		(width 0.089408)
		(layer "In11.Cu")
		(net "RMII_BMC_OCP_TXEN")
	)
	(segment
		(start 423.004742 -55.172102)
		(end 423.004742 -53.549804)
		(width 0.089408)
		(layer "In11.Cu")
		(net "RMII_BMC_OCP_TXEN")
	)
	(segment
		(start 419.436042 -47.92218)
		(end 419.017958 -47.92218)
		(width 0.089408)
		(layer "In11.Cu")
		(net "RMII_BMC_OCP_TXEN")
	)
	(segment
		(start 406.301956 -43.166792)
		(end 405.880316 -42.745152)
		(width 0.089408)
		(layer "In11.Cu")
		(net "RMII_BMC_OCP_TXEN")
	)
	(segment
		(start 418.399976 -46.948344)
		(end 418.020246 -46.568614)
		(width 0.089408)
		(layer "In11.Cu")
		(net "RMII_BMC_OCP_TXEN")
	)
	(segment
		(start 424.185334 -56.352694)
		(end 423.004742 -55.172102)
		(width 0.089408)
		(layer "In11.Cu")
		(net "RMII_BMC_OCP_TXEN")
	)
	(segment
		(start 424.185334 -60.357766)
		(end 424.185334 -56.352694)
		(width 0.089408)
		(layer "In11.Cu")
		(net "RMII_BMC_OCP_TXEN")
	)
	(segment
		(start 418.020246 -46.568614)
		(end 418.020246 -46.09338)
		(width 0.089408)
		(layer "In11.Cu")
		(net "RMII_BMC_OCP_TXEN")
	)
	(segment
		(start 414.67532 -45.132244)
		(end 414.01873 -45.788834)
		(width 0.089408)
		(layer "In11.Cu")
		(net "RMII_BMC_OCP_TXEN")
	)
	(segment
		(start 403.365208 -35.055048)
		(end 403.69617 -34.724086)
		(width 0.089408)
		(layer "In11.Cu")
		(net "RMII_BMC_OCP_TXEN")
	)
	(segment
		(start 429.119792 -117.151912)
		(end 429.119792 -114.575336)
		(width 0.089408)
		(layer "In11.Cu")
		(net "RMII_BMC_OCP_TXEN")
	)
	(segment
		(start 420.106856 -50.651918)
		(end 420.106856 -48.592994)
		(width 0.089408)
		(layer "In11.Cu")
		(net "RMII_BMC_OCP_TXEN")
	)
	(segment
		(start 425.820078 -64.074802)
		(end 424.872912 -63.127636)
		(width 0.089408)
		(layer "In11.Cu")
		(net "RMII_BMC_OCP_TXEN")
	)
	(segment
		(start 424.208448 -77.325474)
		(end 424.208448 -67.543426)
		(width 0.089408)
		(layer "In11.Cu")
		(net "RMII_BMC_OCP_TXEN")
	)
	(segment
		(start 410.71927 -45.53712)
		(end 410.308044 -45.948346)
		(width 0.089408)
		(layer "In11.Cu")
		(net "RMII_BMC_OCP_TXEN")
	)
	(segment
		(start 424.872912 -63.127636)
		(end 424.872912 -61.045344)
		(width 0.089408)
		(layer "In11.Cu")
		(net "RMII_BMC_OCP_TXEN")
	)
	(segment
		(start 420.106856 -48.592994)
		(end 419.436042 -47.92218)
		(width 0.089408)
		(layer "In11.Cu")
		(net "RMII_BMC_OCP_TXEN")
	)
	(segment
		(start 414.01873 -45.788834)
		(end 411.705044 -45.788834)
		(width 0.089408)
		(layer "In11.Cu")
		(net "RMII_BMC_OCP_TXEN")
	)
	(segment
		(start 424.208448 -79.102458)
		(end 424.208448 -78.867254)
		(width 0.089408)
		(layer "In11.Cu")
		(net "RMII_BMC_OCP_TXEN")
	)
	(segment
		(start 430.60493 -118.63705)
		(end 429.119792 -117.151912)
		(width 0.089408)
		(layer "In11.Cu")
		(net "RMII_BMC_OCP_TXEN")
	)
	(segment
		(start 405.880316 -42.060114)
		(end 404.94204 -41.121838)
		(width 0.089408)
		(layer "In11.Cu")
		(net "RMII_BMC_OCP_TXEN")
	)
	(segment
		(start 403.69617 -34.724086)
		(end 403.69617 -34.385504)
		(width 0.089408)
		(layer "In11.Cu")
		(net "RMII_BMC_OCP_TXEN")
	)
	(segment
		(start 469.277954 -112.493044)
		(end 440.8932 -112.493044)
		(width 0.089408)
		(layer "In11.Cu")
		(net "RMII_BMC_OCP_TXEN")
	)
	(segment
		(start 424.208194 -77.325728)
		(end 424.208448 -77.325474)
		(width 0.089408)
		(layer "In11.Cu")
		(net "RMII_BMC_OCP_TXEN")
	)
	(segment
		(start 408.302968 -45.362622)
		(end 407.417778 -44.477432)
		(width 0.089408)
		(layer "In11.Cu")
		(net "RMII_BMC_OCP_TXEN")
	)
	(segment
		(start 407.417778 -44.477432)
		(end 407.417778 -43.648376)
		(width 0.089408)
		(layer "In11.Cu")
		(net "RMII_BMC_OCP_TXEN")
	)
	(segment
		(start 403.771608 -40.513762)
		(end 403.771608 -39.874952)
		(width 0.089408)
		(layer "In11.Cu")
		(net "RMII_BMC_OCP_TXEN")
	)
	(segment
		(start 424.208448 -78.867254)
		(end 424.208194 -78.867)
		(width 0.089408)
		(layer "In11.Cu")
		(net "RMII_BMC_OCP_TXEN")
	)
	(segment
		(start 423.004742 -53.549804)
		(end 420.106856 -50.651918)
		(width 0.089408)
		(layer "In11.Cu")
		(net "RMII_BMC_OCP_TXEN")
	)
	(segment
		(start 409.005024 -45.362622)
		(end 408.302968 -45.362622)
		(width 0.089408)
		(layer "In11.Cu")
		(net "RMII_BMC_OCP_TXEN")
	)
	(segment
		(start 409.590748 -45.948346)
		(end 409.005024 -45.362622)
		(width 0.089408)
		(layer "In11.Cu")
		(net "RMII_BMC_OCP_TXEN")
	)
	(segment
		(start 424.849798 -110.305342)
		(end 424.849798 -79.743808)
		(width 0.089408)
		(layer "In11.Cu")
		(net "RMII_BMC_OCP_TXEN")
	)
	(segment
		(start 429.119792 -114.575336)
		(end 424.849798 -110.305342)
		(width 0.089408)
		(layer "In11.Cu")
		(net "RMII_BMC_OCP_TXEN")
	)
	(segment
		(start 416.52825 -45.738542)
		(end 415.921952 -45.132244)
		(width 0.089408)
		(layer "In11.Cu")
		(net "RMII_BMC_OCP_TXEN")
	)
	(segment
		(start 403.365208 -39.468552)
		(end 403.365208 -35.055048)
		(width 0.089408)
		(layer "In11.Cu")
		(net "RMII_BMC_OCP_TXEN")
	)
	(segment
		(start 415.921952 -45.132244)
		(end 414.67532 -45.132244)
		(width 0.089408)
		(layer "In11.Cu")
		(net "RMII_BMC_OCP_TXEN")
	)
	(segment
		(start 424.208448 -67.543426)
		(end 425.820078 -65.931796)
		(width 0.089408)
		(layer "In11.Cu")
		(net "RMII_BMC_OCP_TXEN")
	)
	(segment
		(start 407.417778 -43.648376)
		(end 406.936194 -43.166792)
		(width 0.089408)
		(layer "In11.Cu")
		(net "RMII_BMC_OCP_TXEN")
	)
	(segment
		(start 411.705044 -45.788834)
		(end 411.45333 -45.53712)
		(width 0.089408)
		(layer "In11.Cu")
		(net "RMII_BMC_OCP_TXEN")
	)
	(segment
		(start 432.813206 -118.63705)
		(end 430.60493 -118.63705)
		(width 0.089408)
		(layer "In11.Cu")
		(net "RMII_BMC_OCP_TXEN")
	)
	(segment
		(start 424.208194 -78.867)
		(end 424.208194 -77.325728)
		(width 0.089408)
		(layer "In11.Cu")
		(net "RMII_BMC_OCP_TXEN")
	)
	(segment
		(start 410.308044 -45.948346)
		(end 409.590748 -45.948346)
		(width 0.089408)
		(layer "In11.Cu")
		(net "RMII_BMC_OCP_TXEN")
	)
	(segment
		(start 440.8932 -112.493044)
		(end 438.869582 -114.516662)
		(width 0.089408)
		(layer "In11.Cu")
		(net "RMII_BMC_OCP_TXEN")
	)
	(segment
		(start 425.820078 -65.931796)
		(end 425.820078 -64.074802)
		(width 0.089408)
		(layer "In11.Cu")
		(net "RMII_BMC_OCP_TXEN")
	)
	(segment
		(start 438.869582 -114.917982)
		(end 438.419494 -115.36807)
		(width 0.089408)
		(layer "In11.Cu")
		(net "RMII_BMC_OCP_TXEN")
	)
	(segment
		(start 424.849798 -79.743808)
		(end 424.208448 -79.102458)
		(width 0.089408)
		(layer "In11.Cu")
		(net "RMII_BMC_OCP_TXEN")
	)
	(segment
		(start 403.771608 -39.874952)
		(end 403.365208 -39.468552)
		(width 0.089408)
		(layer "In11.Cu")
		(net "RMII_BMC_OCP_TXEN")
	)
	(segment
		(start 436.082186 -115.36807)
		(end 432.813206 -118.63705)
		(width 0.089408)
		(layer "In11.Cu")
		(net "RMII_BMC_OCP_TXEN")
	)
	(segment
		(start 403.69617 -34.385504)
		(end 403.82952 -34.252154)
		(width 0.089408)
		(layer "In11.Cu")
		(net "RMII_BMC_OCP_TXEN")
	)
	(segment
		(start 404.94204 -41.121838)
		(end 404.379684 -41.121838)
		(width 0.089408)
		(layer "In11.Cu")
		(net "RMII_BMC_OCP_TXEN")
	)
	(segment
		(start 472.092782 -115.011962)
		(end 471.796872 -115.011962)
		(width 0.089408)
		(layer "In11.Cu")
		(net "RMII_BMC_OCP_TXEN")
	)
	(segment
		(start 411.45333 -45.53712)
		(end 410.71927 -45.53712)
		(width 0.089408)
		(layer "In11.Cu")
		(net "RMII_BMC_OCP_TXEN")
	)
	(segment
		(start 406.936194 -43.166792)
		(end 406.301956 -43.166792)
		(width 0.089408)
		(layer "In11.Cu")
		(net "RMII_BMC_OCP_TXEN")
	)
	(segment
		(start 438.419494 -115.36807)
		(end 436.082186 -115.36807)
		(width 0.089408)
		(layer "In11.Cu")
		(net "RMII_BMC_OCP_TXEN")
	)
	(segment
		(start 404.5712 -29.39034)
		(end 403.819614 -29.39034)
		(width 0.10795)
		(layer "F.Cu")
		(net "RMII_BMC_OCP_TXD1_R")
	)
	(segment
		(start 401.55368 -29.38399)
		(end 401.955508 -29.38399)
		(width 0.10795)
		(layer "F.Cu")
		(net "RMII_BMC_OCP_TXD1_R")
	)
	(segment
		(start 403.819614 -29.39034)
		(end 403.8092 -29.379926)
		(width 0.10795)
		(layer "F.Cu")
		(net "RMII_BMC_OCP_TXD1_R")
	)
	(segment
		(start 403.154388 -29.379926)
		(end 402.807424 -29.379926)
		(width 0.10795)
		(layer "F.Cu")
		(net "RMII_BMC_OCP_TXD1_R")
	)
	(segment
		(start 404.5712 -29.39034)
		(end 405.10206 -29.39034)
		(width 0.10795)
		(layer "F.Cu")
		(net "RMII_BMC_OCP_TXD1_R")
	)
	(segment
		(start 406.387554 -29.0322)
		(end 407.090118 -29.734764)
		(width 0.10795)
		(layer "F.Cu")
		(net "RMII_BMC_OCP_TXD1_R")
	)
	(segment
		(start 402.804884 -29.382466)
		(end 402.382482 -29.382466)
		(width 0.10795)
		(layer "F.Cu")
		(net "RMII_BMC_OCP_TXD1_R")
	)
	(segment
		(start 405.10206 -29.39034)
		(end 405.4602 -29.0322)
		(width 0.10795)
		(layer "F.Cu")
		(net "RMII_BMC_OCP_TXD1_R")
	)
	(segment
		(start 401.955508 -29.38399)
		(end 401.957032 -29.382466)
		(width 0.10795)
		(layer "F.Cu")
		(net "RMII_BMC_OCP_TXD1_R")
	)
	(segment
		(start 403.8092 -29.379926)
		(end 403.154388 -29.379926)
		(width 0.10795)
		(layer "F.Cu")
		(net "RMII_BMC_OCP_TXD1_R")
	)
	(segment
		(start 405.4602 -29.0322)
		(end 406.387554 -29.0322)
		(width 0.10795)
		(layer "F.Cu")
		(net "RMII_BMC_OCP_TXD1_R")
	)
	(segment
		(start 401.957032 -29.382466)
		(end 402.382482 -29.382466)
		(width 0.10795)
		(layer "F.Cu")
		(net "RMII_BMC_OCP_TXD1_R")
	)
	(segment
		(start 402.807424 -29.379926)
		(end 402.804884 -29.382466)
		(width 0.10795)
		(layer "F.Cu")
		(net "RMII_BMC_OCP_TXD1_R")
	)
	(via
		(at 404.5712 -29.39034)
		(size 0.762)
		(drill 0.381)
		(layers "F.Cu" "B.Cu")
		(net "RMII_BMC_OCP_TXD1_R")
	)
	(segment
		(start 401.955 -27.9146)
		(end 402.382482 -28.342082)
		(width 0.10795)
		(layer "F.Cu")
		(net "RMII_BMC_OCP_TXD1")
	)
	(segment
		(start 472.200986 -113.811304)
		(end 472.00185 -113.811304)
		(width 0.10795)
		(layer "F.Cu")
		(net "RMII_BMC_OCP_TXD1")
	)
	(segment
		(start 472.00185 -113.811304)
		(end 471.79992 -113.609374)
		(width 0.10795)
		(layer "F.Cu")
		(net "RMII_BMC_OCP_TXD1")
	)
	(segment
		(start 400.6088 -27.58186)
		(end 401.62226 -27.58186)
		(width 0.10795)
		(layer "F.Cu")
		(net "RMII_BMC_OCP_TXD1")
	)
	(segment
		(start 402.382482 -28.342082)
		(end 402.382482 -28.493466)
		(width 0.10795)
		(layer "F.Cu")
		(net "RMII_BMC_OCP_TXD1")
	)
	(segment
		(start 471.79992 -113.609374)
		(end 471.79992 -112.206532)
		(width 0.10795)
		(layer "F.Cu")
		(net "RMII_BMC_OCP_TXD1")
	)
	(segment
		(start 471.79992 -112.206532)
		(end 471.800936 -112.205516)
		(width 0.10795)
		(layer "F.Cu")
		(net "RMII_BMC_OCP_TXD1")
	)
	(segment
		(start 401.62226 -27.58186)
		(end 401.955 -27.9146)
		(width 0.10795)
		(layer "F.Cu")
		(net "RMII_BMC_OCP_TXD1")
	)
	(via
		(at 400.6088 -27.58186)
		(size 0.762)
		(drill 0.381)
		(layers "F.Cu" "B.Cu")
		(net "RMII_BMC_OCP_TXD1")
	)
	(via
		(at 401.955 -27.9146)
		(size 0.508)
		(drill 0.254)
		(layers "F.Cu" "B.Cu")
		(net "RMII_BMC_OCP_TXD1")
	)
	(via
		(at 472.200986 -113.811304)
		(size 0.508)
		(drill 0.254)
		(layers "F.Cu" "B.Cu")
		(net "RMII_BMC_OCP_TXD1")
	)
	(segment
		(start 424.399456 -77.404722)
		(end 424.399456 -67.622674)
		(width 0.089408)
		(layer "In11.Cu")
		(net "RMII_BMC_OCP_TXD1")
	)
	(segment
		(start 418.211254 -46.489366)
		(end 418.211254 -46.014132)
		(width 0.089408)
		(layer "In11.Cu")
		(net "RMII_BMC_OCP_TXD1")
	)
	(segment
		(start 424.376342 -54.374796)
		(end 420.362634 -50.361088)
		(width 0.089408)
		(layer "In11.Cu")
		(net "RMII_BMC_OCP_TXD1")
	)
	(segment
		(start 406.07107 -41.980866)
		(end 405.021034 -40.93083)
		(width 0.089408)
		(layer "In11.Cu")
		(net "RMII_BMC_OCP_TXD1")
	)
	(segment
		(start 429.3108 -117.072664)
		(end 429.3108 -114.496088)
		(width 0.089408)
		(layer "In11.Cu")
		(net "RMII_BMC_OCP_TXD1")
	)
	(segment
		(start 406.381204 -42.976038)
		(end 406.07107 -42.665904)
		(width 0.089408)
		(layer "In11.Cu")
		(net "RMII_BMC_OCP_TXD1")
	)
	(segment
		(start 414.227518 -45.310044)
		(end 413.939736 -45.597826)
		(width 0.089408)
		(layer "In11.Cu")
		(net "RMII_BMC_OCP_TXD1")
	)
	(segment
		(start 408.426158 -45.171868)
		(end 407.608532 -44.354242)
		(width 0.089408)
		(layer "In11.Cu")
		(net "RMII_BMC_OCP_TXD1")
	)
	(segment
		(start 404.472394 -40.93083)
		(end 403.962616 -40.421052)
		(width 0.089408)
		(layer "In11.Cu")
		(net "RMII_BMC_OCP_TXD1")
	)
	(segment
		(start 418.6174 -46.895512)
		(end 418.211254 -46.489366)
		(width 0.089408)
		(layer "In11.Cu")
		(net "RMII_BMC_OCP_TXD1")
	)
	(segment
		(start 439.355484 -113.729516)
		(end 437.450484 -113.729516)
		(width 0.089408)
		(layer "In11.Cu")
		(net "RMII_BMC_OCP_TXD1")
	)
	(segment
		(start 404.283164 -34.413952)
		(end 404.283164 -34.096706)
		(width 0.089408)
		(layer "In11.Cu")
		(net "RMII_BMC_OCP_TXD1")
	)
	(segment
		(start 407.608532 -43.569128)
		(end 407.015442 -42.976038)
		(width 0.089408)
		(layer "In11.Cu")
		(net "RMII_BMC_OCP_TXD1")
	)
	(segment
		(start 404.37943 -39.336472)
		(end 404.37943 -36.97097)
		(width 0.089408)
		(layer "In11.Cu")
		(net "RMII_BMC_OCP_TXD1")
	)
	(segment
		(start 402.971 -29.64815)
		(end 402.971 -28.9306)
		(width 0.089408)
		(layer "In11.Cu")
		(net "RMII_BMC_OCP_TXD1")
	)
	(segment
		(start 424.399456 -78.788006)
		(end 424.399202 -78.787752)
		(width 0.089408)
		(layer "In11.Cu")
		(net "RMII_BMC_OCP_TXD1")
	)
	(segment
		(start 432.733958 -118.446042)
		(end 430.684178 -118.446042)
		(width 0.089408)
		(layer "In11.Cu")
		(net "RMII_BMC_OCP_TXD1")
	)
	(segment
		(start 404.283164 -34.096706)
		(end 404.05685 -33.870392)
		(width 0.089408)
		(layer "In11.Cu")
		(net "RMII_BMC_OCP_TXD1")
	)
	(segment
		(start 440.79922 -112.28578)
		(end 439.355484 -113.729516)
		(width 0.089408)
		(layer "In11.Cu")
		(net "RMII_BMC_OCP_TXD1")
	)
	(segment
		(start 425.040806 -79.66456)
		(end 424.399456 -79.02321)
		(width 0.089408)
		(layer "In11.Cu")
		(net "RMII_BMC_OCP_TXD1")
	)
	(segment
		(start 417.74491 -45.547788)
		(end 416.607498 -45.547788)
		(width 0.089408)
		(layer "In11.Cu")
		(net "RMII_BMC_OCP_TXD1")
	)
	(segment
		(start 405.214074 -34.850324)
		(end 404.957788 -34.594038)
		(width 0.089408)
		(layer "In11.Cu")
		(net "RMII_BMC_OCP_TXD1")
	)
	(segment
		(start 405.214074 -36.136326)
		(end 405.214074 -34.850324)
		(width 0.089408)
		(layer "In11.Cu")
		(net "RMII_BMC_OCP_TXD1")
	)
	(segment
		(start 426.011086 -66.011044)
		(end 426.011086 -63.995554)
		(width 0.089408)
		(layer "In11.Cu")
		(net "RMII_BMC_OCP_TXD1")
	)
	(segment
		(start 424.399456 -79.02321)
		(end 424.399456 -78.788006)
		(width 0.089408)
		(layer "In11.Cu")
		(net "RMII_BMC_OCP_TXD1")
	)
	(segment
		(start 404.05685 -30.734)
		(end 402.971 -29.64815)
		(width 0.089408)
		(layer "In11.Cu")
		(net "RMII_BMC_OCP_TXD1")
	)
	(segment
		(start 416.607498 -45.547788)
		(end 416.0012 -44.94149)
		(width 0.089408)
		(layer "In11.Cu")
		(net "RMII_BMC_OCP_TXD1")
	)
	(segment
		(start 410.633926 -45.346366)
		(end 410.228796 -45.751496)
		(width 0.089408)
		(layer "In11.Cu")
		(net "RMII_BMC_OCP_TXD1")
	)
	(segment
		(start 469.340946 -112.28578)
		(end 440.79922 -112.28578)
		(width 0.089408)
		(layer "In11.Cu")
		(net "RMII_BMC_OCP_TXD1")
	)
	(segment
		(start 402.971 -28.9306)
		(end 401.955 -27.9146)
		(width 0.089408)
		(layer "In11.Cu")
		(net "RMII_BMC_OCP_TXD1")
	)
	(segment
		(start 420.362634 -50.361088)
		(end 420.362634 -48.578516)
		(width 0.089408)
		(layer "In11.Cu")
		(net "RMII_BMC_OCP_TXD1")
	)
	(segment
		(start 424.399456 -67.622674)
		(end 426.011086 -66.011044)
		(width 0.089408)
		(layer "In11.Cu")
		(net "RMII_BMC_OCP_TXD1")
	)
	(segment
		(start 429.3108 -114.496088)
		(end 425.040806 -110.226094)
		(width 0.089408)
		(layer "In11.Cu")
		(net "RMII_BMC_OCP_TXD1")
	)
	(segment
		(start 403.962616 -39.753286)
		(end 404.37943 -39.336472)
		(width 0.089408)
		(layer "In11.Cu")
		(net "RMII_BMC_OCP_TXD1")
	)
	(segment
		(start 426.011086 -63.995554)
		(end 425.06392 -63.048388)
		(width 0.089408)
		(layer "In11.Cu")
		(net "RMII_BMC_OCP_TXD1")
	)
	(segment
		(start 410.228796 -45.751496)
		(end 409.6639 -45.751496)
		(width 0.089408)
		(layer "In11.Cu")
		(net "RMII_BMC_OCP_TXD1")
	)
	(segment
		(start 407.015442 -42.976038)
		(end 406.381204 -42.976038)
		(width 0.089408)
		(layer "In11.Cu")
		(net "RMII_BMC_OCP_TXD1")
	)
	(segment
		(start 406.07107 -42.665904)
		(end 406.07107 -41.980866)
		(width 0.089408)
		(layer "In11.Cu")
		(net "RMII_BMC_OCP_TXD1")
	)
	(segment
		(start 407.608532 -44.354242)
		(end 407.608532 -43.569128)
		(width 0.089408)
		(layer "In11.Cu")
		(net "RMII_BMC_OCP_TXD1")
	)
	(segment
		(start 411.532578 -45.346366)
		(end 410.633926 -45.346366)
		(width 0.089408)
		(layer "In11.Cu")
		(net "RMII_BMC_OCP_TXD1")
	)
	(segment
		(start 425.040806 -110.226094)
		(end 425.040806 -79.66456)
		(width 0.089408)
		(layer "In11.Cu")
		(net "RMII_BMC_OCP_TXD1")
	)
	(segment
		(start 414.595818 -44.94149)
		(end 414.227518 -45.30979)
		(width 0.089408)
		(layer "In11.Cu")
		(net "RMII_BMC_OCP_TXD1")
	)
	(segment
		(start 424.376342 -60.278518)
		(end 424.376342 -54.374796)
		(width 0.089408)
		(layer "In11.Cu")
		(net "RMII_BMC_OCP_TXD1")
	)
	(segment
		(start 424.399202 -78.787752)
		(end 424.399202 -77.404976)
		(width 0.089408)
		(layer "In11.Cu")
		(net "RMII_BMC_OCP_TXD1")
	)
	(segment
		(start 413.939736 -45.597826)
		(end 411.784038 -45.597826)
		(width 0.089408)
		(layer "In11.Cu")
		(net "RMII_BMC_OCP_TXD1")
	)
	(segment
		(start 472.200986 -113.811304)
		(end 470.86647 -113.811304)
		(width 0.089408)
		(layer "In11.Cu")
		(net "RMII_BMC_OCP_TXD1")
	)
	(segment
		(start 405.021034 -40.93083)
		(end 404.472394 -40.93083)
		(width 0.089408)
		(layer "In11.Cu")
		(net "RMII_BMC_OCP_TXD1")
	)
	(segment
		(start 404.05685 -33.870392)
		(end 404.05685 -30.734)
		(width 0.089408)
		(layer "In11.Cu")
		(net "RMII_BMC_OCP_TXD1")
	)
	(segment
		(start 403.962616 -40.421052)
		(end 403.962616 -39.753286)
		(width 0.089408)
		(layer "In11.Cu")
		(net "RMII_BMC_OCP_TXD1")
	)
	(segment
		(start 425.06392 -60.966096)
		(end 424.376342 -60.278518)
		(width 0.089408)
		(layer "In11.Cu")
		(net "RMII_BMC_OCP_TXD1")
	)
	(segment
		(start 418.6174 -47.251366)
		(end 418.6174 -46.895512)
		(width 0.089408)
		(layer "In11.Cu")
		(net "RMII_BMC_OCP_TXD1")
	)
	(segment
		(start 418.211254 -46.014132)
		(end 417.74491 -45.547788)
		(width 0.089408)
		(layer "In11.Cu")
		(net "RMII_BMC_OCP_TXD1")
	)
	(segment
		(start 416.0012 -44.94149)
		(end 414.595818 -44.94149)
		(width 0.089408)
		(layer "In11.Cu")
		(net "RMII_BMC_OCP_TXD1")
	)
	(segment
		(start 414.227518 -45.30979)
		(end 414.227518 -45.310044)
		(width 0.089408)
		(layer "In11.Cu")
		(net "RMII_BMC_OCP_TXD1")
	)
	(segment
		(start 437.450484 -113.729516)
		(end 432.733958 -118.446042)
		(width 0.089408)
		(layer "In11.Cu")
		(net "RMII_BMC_OCP_TXD1")
	)
	(segment
		(start 470.86647 -113.811304)
		(end 469.340946 -112.28578)
		(width 0.089408)
		(layer "In11.Cu")
		(net "RMII_BMC_OCP_TXD1")
	)
	(segment
		(start 420.362634 -48.578516)
		(end 419.51529 -47.731172)
		(width 0.089408)
		(layer "In11.Cu")
		(net "RMII_BMC_OCP_TXD1")
	)
	(segment
		(start 411.784038 -45.597826)
		(end 411.532578 -45.346366)
		(width 0.089408)
		(layer "In11.Cu")
		(net "RMII_BMC_OCP_TXD1")
	)
	(segment
		(start 404.46325 -34.594038)
		(end 404.283164 -34.413952)
		(width 0.089408)
		(layer "In11.Cu")
		(net "RMII_BMC_OCP_TXD1")
	)
	(segment
		(start 409.6639 -45.751496)
		(end 409.084272 -45.171868)
		(width 0.089408)
		(layer "In11.Cu")
		(net "RMII_BMC_OCP_TXD1")
	)
	(segment
		(start 430.684178 -118.446042)
		(end 429.3108 -117.072664)
		(width 0.089408)
		(layer "In11.Cu")
		(net "RMII_BMC_OCP_TXD1")
	)
	(segment
		(start 404.37943 -36.97097)
		(end 405.214074 -36.136326)
		(width 0.089408)
		(layer "In11.Cu")
		(net "RMII_BMC_OCP_TXD1")
	)
	(segment
		(start 425.06392 -63.048388)
		(end 425.06392 -60.966096)
		(width 0.089408)
		(layer "In11.Cu")
		(net "RMII_BMC_OCP_TXD1")
	)
	(segment
		(start 424.399202 -77.404976)
		(end 424.399456 -77.404722)
		(width 0.089408)
		(layer "In11.Cu")
		(net "RMII_BMC_OCP_TXD1")
	)
	(segment
		(start 404.957788 -34.594038)
		(end 404.46325 -34.594038)
		(width 0.089408)
		(layer "In11.Cu")
		(net "RMII_BMC_OCP_TXD1")
	)
	(segment
		(start 409.084272 -45.171868)
		(end 408.426158 -45.171868)
		(width 0.089408)
		(layer "In11.Cu")
		(net "RMII_BMC_OCP_TXD1")
	)
	(segment
		(start 419.51529 -47.731172)
		(end 419.097206 -47.731172)
		(width 0.089408)
		(layer "In11.Cu")
		(net "RMII_BMC_OCP_TXD1")
	)
	(segment
		(start 419.097206 -47.731172)
		(end 418.6174 -47.251366)
		(width 0.089408)
		(layer "In11.Cu")
		(net "RMII_BMC_OCP_TXD1")
	)
	(segment
		(start 411.09011 -32.934656)
		(end 411.09011 -32.934402)
		(width 0.10795)
		(layer "F.Cu")
		(net "RMII_BMC_OCP_TXD0_R")
	)
	(segment
		(start 411.09011 -32.934402)
		(end 410.690314 -32.534606)
		(width 0.10795)
		(layer "F.Cu")
		(net "RMII_BMC_OCP_TXD0_R")
	)
	(via
		(at 404.49754 -35.679634)
		(size 0.6604)
		(drill 0.3302)
		(layers "F.Cu" "B.Cu")
		(net "RMII_BMC_OCP_TXD0_R")
	)
	(via
		(at 410.690314 -32.534606)
		(size 0.4572)
		(drill 0.2032)
		(layers "F.Cu" "B.Cu")
		(net "RMII_BMC_OCP_TXD0_R")
	)
	(segment
		(start 408.674062 -35.311588)
		(end 408.674062 -32.327088)
		(width 0.10795)
		(layer "B.Cu")
		(net "RMII_BMC_OCP_TXD0_R")
	)
	(segment
		(start 404.919942 -35.679634)
		(end 405.058372 -35.541204)
		(width 0.10795)
		(layer "B.Cu")
		(net "RMII_BMC_OCP_TXD0_R")
	)
	(segment
		(start 409.727654 -33.00603)
		(end 410.03982 -33.00603)
		(width 0.10795)
		(layer "B.Cu")
		(net "RMII_BMC_OCP_TXD0_R")
	)
	(segment
		(start 410.03982 -33.00603)
		(end 410.511244 -32.534606)
		(width 0.10795)
		(layer "B.Cu")
		(net "RMII_BMC_OCP_TXD0_R")
	)
	(segment
		(start 408.674062 -32.327088)
		(end 408.882596 -32.118554)
		(width 0.10795)
		(layer "B.Cu")
		(net "RMII_BMC_OCP_TXD0_R")
	)
	(segment
		(start 409.283916 -32.118554)
		(end 409.496768 -32.331406)
		(width 0.10795)
		(layer "B.Cu")
		(net "RMII_BMC_OCP_TXD0_R")
	)
	(segment
		(start 403.834854 -36.068)
		(end 404.22322 -35.679634)
		(width 0.10795)
		(layer "B.Cu")
		(net "RMII_BMC_OCP_TXD0_R")
	)
	(segment
		(start 410.511244 -32.534606)
		(end 410.690314 -32.534606)
		(width 0.10795)
		(layer "B.Cu")
		(net "RMII_BMC_OCP_TXD0_R")
	)
	(segment
		(start 405.058372 -35.541204)
		(end 406.683464 -35.541204)
		(width 0.10795)
		(layer "B.Cu")
		(net "RMII_BMC_OCP_TXD0_R")
	)
	(segment
		(start 404.49754 -35.679634)
		(end 404.919942 -35.679634)
		(width 0.10795)
		(layer "B.Cu")
		(net "RMII_BMC_OCP_TXD0_R")
	)
	(segment
		(start 403.352 -36.068)
		(end 403.834854 -36.068)
		(width 0.10795)
		(layer "B.Cu")
		(net "RMII_BMC_OCP_TXD0_R")
	)
	(segment
		(start 409.496768 -32.775144)
		(end 409.727654 -33.00603)
		(width 0.10795)
		(layer "B.Cu")
		(net "RMII_BMC_OCP_TXD0_R")
	)
	(segment
		(start 404.22322 -35.679634)
		(end 404.49754 -35.679634)
		(width 0.10795)
		(layer "B.Cu")
		(net "RMII_BMC_OCP_TXD0_R")
	)
	(segment
		(start 408.882596 -32.118554)
		(end 409.283916 -32.118554)
		(width 0.10795)
		(layer "B.Cu")
		(net "RMII_BMC_OCP_TXD0_R")
	)
	(segment
		(start 409.496768 -32.331406)
		(end 409.496768 -32.775144)
		(width 0.10795)
		(layer "B.Cu")
		(net "RMII_BMC_OCP_TXD0_R")
	)
	(segment
		(start 402.986494 -36.068)
		(end 403.352 -36.068)
		(width 0.10795)
		(layer "B.Cu")
		(net "RMII_BMC_OCP_TXD0_R")
	)
	(segment
		(start 402.488146 -35.569652)
		(end 402.986494 -36.068)
		(width 0.10795)
		(layer "B.Cu")
		(net "RMII_BMC_OCP_TXD0_R")
	)
	(segment
		(start 406.683464 -35.541204)
		(end 407.178764 -36.036504)
		(width 0.10795)
		(layer "B.Cu")
		(net "RMII_BMC_OCP_TXD0_R")
	)
	(segment
		(start 407.178764 -36.036504)
		(end 407.949146 -36.036504)
		(width 0.10795)
		(layer "B.Cu")
		(net "RMII_BMC_OCP_TXD0_R")
	)
	(segment
		(start 407.949146 -36.036504)
		(end 408.674062 -35.311588)
		(width 0.10795)
		(layer "B.Cu")
		(net "RMII_BMC_OCP_TXD0_R")
	)
	(segment
		(start 473.236798 -114.98834)
		(end 473.236798 -114.249708)
		(width 0.10795)
		(layer "F.Cu")
		(net "RMII_BMC_OCP_TXD0")
	)
	(segment
		(start 472.600782 -113.613692)
		(end 472.600782 -112.205516)
		(width 0.10795)
		(layer "F.Cu")
		(net "RMII_BMC_OCP_TXD0")
	)
	(segment
		(start 473.236798 -114.249708)
		(end 472.600782 -113.613692)
		(width 0.10795)
		(layer "F.Cu")
		(net "RMII_BMC_OCP_TXD0")
	)
	(via
		(at 403.25548 -34.523934)
		(size 0.508)
		(drill 0.254)
		(layers "F.Cu" "B.Cu")
		(net "RMII_BMC_OCP_TXD0")
	)
	(via
		(at 473.236798 -114.98834)
		(size 0.508)
		(drill 0.254)
		(layers "F.Cu" "B.Cu")
		(net "RMII_BMC_OCP_TXD0")
	)
	(segment
		(start 403.352 -34.620454)
		(end 403.25548 -34.523934)
		(width 0.10795)
		(layer "B.Cu")
		(net "RMII_BMC_OCP_TXD0")
	)
	(segment
		(start 403.352 -35.179)
		(end 403.352 -34.620454)
		(width 0.10795)
		(layer "B.Cu")
		(net "RMII_BMC_OCP_TXD0")
	)
	(segment
		(start 423.994072 -59.96178)
		(end 423.994072 -60.43676)
		(width 0.089408)
		(layer "In11.Cu")
		(net "RMII_BMC_OCP_TXD0")
	)
	(segment
		(start 421.9956 -54.506368)
		(end 423.994326 -56.505094)
		(width 0.089408)
		(layer "In11.Cu")
		(net "RMII_BMC_OCP_TXD0")
	)
	(segment
		(start 409.5115 -46.1391)
		(end 410.4005 -46.1391)
		(width 0.089408)
		(layer "In11.Cu")
		(net "RMII_BMC_OCP_TXD0")
	)
	(segment
		(start 430.464722 -118.828058)
		(end 432.961288 -118.828058)
		(width 0.089408)
		(layer "In11.Cu")
		(net "RMII_BMC_OCP_TXD0")
	)
	(segment
		(start 408.925776 -45.553376)
		(end 409.5115 -46.1391)
		(width 0.089408)
		(layer "In11.Cu")
		(net "RMII_BMC_OCP_TXD0")
	)
	(segment
		(start 417.7792 -46.609)
		(end 418.190172 -47.019972)
		(width 0.089408)
		(layer "In11.Cu")
		(net "RMII_BMC_OCP_TXD0")
	)
	(segment
		(start 418.190172 -47.416212)
		(end 418.935662 -48.161702)
		(width 0.089408)
		(layer "In11.Cu")
		(net "RMII_BMC_OCP_TXD0")
	)
	(segment
		(start 423.994326 -59.961526)
		(end 423.994072 -59.96178)
		(width 0.089408)
		(layer "In11.Cu")
		(net "RMII_BMC_OCP_TXD0")
	)
	(segment
		(start 424.681904 -61.124592)
		(end 424.681904 -63.206884)
		(width 0.089408)
		(layer "In11.Cu")
		(net "RMII_BMC_OCP_TXD0")
	)
	(segment
		(start 424.017186 -67.464432)
		(end 424.017186 -78.946248)
		(width 0.089408)
		(layer "In11.Cu")
		(net "RMII_BMC_OCP_TXD0")
	)
	(segment
		(start 425.62907 -65.852548)
		(end 424.017186 -67.464432)
		(width 0.089408)
		(layer "In11.Cu")
		(net "RMII_BMC_OCP_TXD0")
	)
	(segment
		(start 419.915848 -48.672242)
		(end 419.915848 -50.802794)
		(width 0.089408)
		(layer "In11.Cu")
		(net "RMII_BMC_OCP_TXD0")
	)
	(segment
		(start 423.994326 -56.505094)
		(end 423.994326 -59.961526)
		(width 0.089408)
		(layer "In11.Cu")
		(net "RMII_BMC_OCP_TXD0")
	)
	(segment
		(start 469.198706 -112.684052)
		(end 471.92692 -115.412266)
		(width 0.089408)
		(layer "In11.Cu")
		(net "RMII_BMC_OCP_TXD0")
	)
	(segment
		(start 410.802328 -45.737272)
		(end 411.370272 -45.737272)
		(width 0.089408)
		(layer "In11.Cu")
		(net "RMII_BMC_OCP_TXD0")
	)
	(segment
		(start 411.6324 -45.9994)
		(end 414.20161 -45.9994)
		(width 0.089408)
		(layer "In11.Cu")
		(net "RMII_BMC_OCP_TXD0")
	)
	(segment
		(start 417.39566 -46.609)
		(end 417.7792 -46.609)
		(width 0.089408)
		(layer "In11.Cu")
		(net "RMII_BMC_OCP_TXD0")
	)
	(segment
		(start 404.8633 -41.3131)
		(end 405.689562 -42.139362)
		(width 0.089408)
		(layer "In11.Cu")
		(net "RMII_BMC_OCP_TXD0")
	)
	(segment
		(start 403.25548 -34.523934)
		(end 403.161754 -34.61766)
		(width 0.089408)
		(layer "In11.Cu")
		(net "RMII_BMC_OCP_TXD0")
	)
	(segment
		(start 439.0898 -114.5667)
		(end 440.972448 -112.684052)
		(width 0.089408)
		(layer "In11.Cu")
		(net "RMII_BMC_OCP_TXD0")
	)
	(segment
		(start 403.161754 -34.61766)
		(end 403.161754 -38.879272)
		(width 0.089408)
		(layer "In11.Cu")
		(net "RMII_BMC_OCP_TXD0")
	)
	(segment
		(start 423.994072 -60.43676)
		(end 424.681904 -61.124592)
		(width 0.089408)
		(layer "In11.Cu")
		(net "RMII_BMC_OCP_TXD0")
	)
	(segment
		(start 405.689562 -42.8244)
		(end 406.224232 -43.35907)
		(width 0.089408)
		(layer "In11.Cu")
		(net "RMII_BMC_OCP_TXD0")
	)
	(segment
		(start 414.832038 -45.368972)
		(end 415.827972 -45.368972)
		(width 0.089408)
		(layer "In11.Cu")
		(net "RMII_BMC_OCP_TXD0")
	)
	(segment
		(start 424.681904 -63.206884)
		(end 425.62907 -64.15405)
		(width 0.089408)
		(layer "In11.Cu")
		(net "RMII_BMC_OCP_TXD0")
	)
	(segment
		(start 414.20161 -45.9994)
		(end 414.832038 -45.368972)
		(width 0.089408)
		(layer "In11.Cu")
		(net "RMII_BMC_OCP_TXD0")
	)
	(segment
		(start 472.812872 -115.412266)
		(end 473.236798 -114.98834)
		(width 0.089408)
		(layer "In11.Cu")
		(net "RMII_BMC_OCP_TXD0")
	)
	(segment
		(start 415.827972 -45.368972)
		(end 416.388296 -45.929296)
		(width 0.089408)
		(layer "In11.Cu")
		(net "RMII_BMC_OCP_TXD0")
	)
	(segment
		(start 428.855632 -114.759232)
		(end 428.855632 -117.218968)
		(width 0.089408)
		(layer "In11.Cu")
		(net "RMII_BMC_OCP_TXD0")
	)
	(segment
		(start 439.0898 -114.96802)
		(end 439.0898 -114.5667)
		(width 0.089408)
		(layer "In11.Cu")
		(net "RMII_BMC_OCP_TXD0")
	)
	(segment
		(start 424.65879 -79.823056)
		(end 424.65879 -111.455708)
		(width 0.089408)
		(layer "In11.Cu")
		(net "RMII_BMC_OCP_TXD0")
	)
	(segment
		(start 424.017186 -78.946248)
		(end 424.01744 -78.946502)
		(width 0.089408)
		(layer "In11.Cu")
		(net "RMII_BMC_OCP_TXD0")
	)
	(segment
		(start 402.954744 -39.086282)
		(end 402.954744 -40.29329)
		(width 0.089408)
		(layer "In11.Cu")
		(net "RMII_BMC_OCP_TXD0")
	)
	(segment
		(start 403.974554 -41.3131)
		(end 404.8633 -41.3131)
		(width 0.089408)
		(layer "In11.Cu")
		(net "RMII_BMC_OCP_TXD0")
	)
	(segment
		(start 408.166824 -45.553376)
		(end 408.925776 -45.553376)
		(width 0.089408)
		(layer "In11.Cu")
		(net "RMII_BMC_OCP_TXD0")
	)
	(segment
		(start 419.405308 -48.161702)
		(end 419.915848 -48.672242)
		(width 0.089408)
		(layer "In11.Cu")
		(net "RMII_BMC_OCP_TXD0")
	)
	(segment
		(start 407.227024 -44.613576)
		(end 408.166824 -45.553376)
		(width 0.089408)
		(layer "In11.Cu")
		(net "RMII_BMC_OCP_TXD0")
	)
	(segment
		(start 425.62907 -64.15405)
		(end 425.62907 -65.852548)
		(width 0.089408)
		(layer "In11.Cu")
		(net "RMII_BMC_OCP_TXD0")
	)
	(segment
		(start 424.01744 -78.946502)
		(end 424.01744 -79.181706)
		(width 0.089408)
		(layer "In11.Cu")
		(net "RMII_BMC_OCP_TXD0")
	)
	(segment
		(start 427.330616 -113.234216)
		(end 428.855632 -114.759232)
		(width 0.089408)
		(layer "In11.Cu")
		(net "RMII_BMC_OCP_TXD0")
	)
	(segment
		(start 418.190172 -47.019972)
		(end 418.190172 -47.416212)
		(width 0.089408)
		(layer "In11.Cu")
		(net "RMII_BMC_OCP_TXD0")
	)
	(segment
		(start 402.954744 -40.29329)
		(end 403.974554 -41.3131)
		(width 0.089408)
		(layer "In11.Cu")
		(net "RMII_BMC_OCP_TXD0")
	)
	(segment
		(start 424.01744 -79.181706)
		(end 424.65879 -79.823056)
		(width 0.089408)
		(layer "In11.Cu")
		(net "RMII_BMC_OCP_TXD0")
	)
	(segment
		(start 406.85847 -43.35907)
		(end 407.227024 -43.727624)
		(width 0.089408)
		(layer "In11.Cu")
		(net "RMII_BMC_OCP_TXD0")
	)
	(segment
		(start 440.972448 -112.684052)
		(end 469.198706 -112.684052)
		(width 0.089408)
		(layer "In11.Cu")
		(net "RMII_BMC_OCP_TXD0")
	)
	(segment
		(start 410.4005 -46.1391)
		(end 410.802328 -45.737272)
		(width 0.089408)
		(layer "In11.Cu")
		(net "RMII_BMC_OCP_TXD0")
	)
	(segment
		(start 416.388296 -45.929296)
		(end 416.715956 -45.929296)
		(width 0.089408)
		(layer "In11.Cu")
		(net "RMII_BMC_OCP_TXD0")
	)
	(segment
		(start 426.437298 -113.234216)
		(end 427.330616 -113.234216)
		(width 0.089408)
		(layer "In11.Cu")
		(net "RMII_BMC_OCP_TXD0")
	)
	(segment
		(start 428.855632 -117.218968)
		(end 430.464722 -118.828058)
		(width 0.089408)
		(layer "In11.Cu")
		(net "RMII_BMC_OCP_TXD0")
	)
	(segment
		(start 424.65879 -111.455708)
		(end 426.437298 -113.234216)
		(width 0.089408)
		(layer "In11.Cu")
		(net "RMII_BMC_OCP_TXD0")
	)
	(segment
		(start 416.715956 -45.929296)
		(end 417.39566 -46.609)
		(width 0.089408)
		(layer "In11.Cu")
		(net "RMII_BMC_OCP_TXD0")
	)
	(segment
		(start 418.935662 -48.161702)
		(end 419.405308 -48.161702)
		(width 0.089408)
		(layer "In11.Cu")
		(net "RMII_BMC_OCP_TXD0")
	)
	(segment
		(start 407.227024 -43.727624)
		(end 407.227024 -44.613576)
		(width 0.089408)
		(layer "In11.Cu")
		(net "RMII_BMC_OCP_TXD0")
	)
	(segment
		(start 421.9956 -52.882546)
		(end 421.9956 -54.506368)
		(width 0.089408)
		(layer "In11.Cu")
		(net "RMII_BMC_OCP_TXD0")
	)
	(segment
		(start 432.961288 -118.828058)
		(end 436.230268 -115.559078)
		(width 0.089408)
		(layer "In11.Cu")
		(net "RMII_BMC_OCP_TXD0")
	)
	(segment
		(start 438.498742 -115.559078)
		(end 439.0898 -114.96802)
		(width 0.089408)
		(layer "In11.Cu")
		(net "RMII_BMC_OCP_TXD0")
	)
	(segment
		(start 406.224232 -43.35907)
		(end 406.85847 -43.35907)
		(width 0.089408)
		(layer "In11.Cu")
		(net "RMII_BMC_OCP_TXD0")
	)
	(segment
		(start 471.92692 -115.412266)
		(end 472.812872 -115.412266)
		(width 0.089408)
		(layer "In11.Cu")
		(net "RMII_BMC_OCP_TXD0")
	)
	(segment
		(start 419.915848 -50.802794)
		(end 421.9956 -52.882546)
		(width 0.089408)
		(layer "In11.Cu")
		(net "RMII_BMC_OCP_TXD0")
	)
	(segment
		(start 405.689562 -42.139362)
		(end 405.689562 -42.8244)
		(width 0.089408)
		(layer "In11.Cu")
		(net "RMII_BMC_OCP_TXD0")
	)
	(segment
		(start 403.161754 -38.879272)
		(end 402.954744 -39.086282)
		(width 0.089408)
		(layer "In11.Cu")
		(net "RMII_BMC_OCP_TXD0")
	)
	(segment
		(start 436.230268 -115.559078)
		(end 438.498742 -115.559078)
		(width 0.089408)
		(layer "In11.Cu")
		(net "RMII_BMC_OCP_TXD0")
	)
	(segment
		(start 411.370272 -45.737272)
		(end 411.6324 -45.9994)
		(width 0.089408)
		(layer "In11.Cu")
		(net "RMII_BMC_OCP_TXD0")
	)
	(segment
		(start 408.690064 -28.934664)
		(end 408.290014 -28.534614)
		(width 0.10795)
		(layer "F.Cu")
		(net "RMII_BMC_OCP_RXER")
	)
	(via
		(at 435.873398 -112.9157)
		(size 0.508)
		(drill 0.254)
		(layers "F.Cu" "B.Cu")
		(net "RMII_BMC_OCP_RXER")
	)
	(via
		(at 436.43042 -115.05057)
		(size 0.6604)
		(drill 0.3302)
		(layers "F.Cu" "B.Cu")
		(net "RMII_BMC_OCP_RXER")
	)
	(via
		(at 408.290014 -28.534614)
		(size 0.4572)
		(drill 0.2032)
		(layers "F.Cu" "B.Cu")
		(net "RMII_BMC_OCP_RXER")
	)
	(segment
		(start 470.535 -112.141)
		(end 471.17 -112.141)
		(width 0.10795)
		(layer "B.Cu")
		(net "RMII_BMC_OCP_RXER")
	)
	(segment
		(start 436.04942 -113.091722)
		(end 435.873398 -112.9157)
		(width 0.10795)
		(layer "B.Cu")
		(net "RMII_BMC_OCP_RXER")
	)
	(segment
		(start 435.873398 -112.9157)
		(end 435.873398 -111.694468)
		(width 0.10795)
		(layer "B.Cu")
		(net "RMII_BMC_OCP_RXER")
	)
	(segment
		(start 468.852758 -110.458758)
		(end 470.535 -112.141)
		(width 0.10795)
		(layer "B.Cu")
		(net "RMII_BMC_OCP_RXER")
	)
	(segment
		(start 435.873398 -111.694468)
		(end 437.109108 -110.458758)
		(width 0.10795)
		(layer "B.Cu")
		(net "RMII_BMC_OCP_RXER")
	)
	(segment
		(start 436.04942 -114.032538)
		(end 436.04942 -113.091722)
		(width 0.10795)
		(layer "B.Cu")
		(net "RMII_BMC_OCP_RXER")
	)
	(segment
		(start 436.43042 -114.413538)
		(end 436.04942 -114.032538)
		(width 0.10795)
		(layer "B.Cu")
		(net "RMII_BMC_OCP_RXER")
	)
	(segment
		(start 437.109108 -110.458758)
		(end 468.852758 -110.458758)
		(width 0.10795)
		(layer "B.Cu")
		(net "RMII_BMC_OCP_RXER")
	)
	(segment
		(start 436.43042 -115.05057)
		(end 436.43042 -114.413538)
		(width 0.10795)
		(layer "B.Cu")
		(net "RMII_BMC_OCP_RXER")
	)
	(segment
		(start 408.290014 -28.534614)
		(end 406.894792 -29.929836)
		(width 0.089408)
		(layer "In11.Cu")
		(net "RMII_BMC_OCP_RXER")
	)
	(segment
		(start 425.636944 -62.725808)
		(end 426.584364 -63.673228)
		(width 0.089408)
		(layer "In11.Cu")
		(net "RMII_BMC_OCP_RXER")
	)
	(segment
		(start 426.584364 -63.673228)
		(end 426.584364 -65.138046)
		(width 0.089408)
		(layer "In11.Cu")
		(net "RMII_BMC_OCP_RXER")
	)
	(segment
		(start 412.328614 -44.37888)
		(end 412.440882 -44.491148)
		(width 0.089408)
		(layer "In11.Cu")
		(net "RMII_BMC_OCP_RXER")
	)
	(segment
		(start 422.044622 -49.548542)
		(end 423.392854 -50.896774)
		(width 0.089408)
		(layer "In11.Cu")
		(net "RMII_BMC_OCP_RXER")
	)
	(segment
		(start 434.5178 -111.560102)
		(end 435.873398 -112.9157)
		(width 0.089408)
		(layer "In11.Cu")
		(net "RMII_BMC_OCP_RXER")
	)
	(segment
		(start 420.870634 -46.411134)
		(end 420.870634 -46.94428)
		(width 0.089408)
		(layer "In11.Cu")
		(net "RMII_BMC_OCP_RXER")
	)
	(segment
		(start 424.988736 -60.080144)
		(end 425.636944 -60.728352)
		(width 0.089408)
		(layer "In11.Cu")
		(net "RMII_BMC_OCP_RXER")
	)
	(segment
		(start 424.97248 -78.550262)
		(end 424.97248 -78.785466)
		(width 0.089408)
		(layer "In11.Cu")
		(net "RMII_BMC_OCP_RXER")
	)
	(segment
		(start 424.972226 -77.64272)
		(end 424.972226 -78.550008)
		(width 0.089408)
		(layer "In11.Cu")
		(net "RMII_BMC_OCP_RXER")
	)
	(segment
		(start 424.972226 -78.550008)
		(end 424.97248 -78.550262)
		(width 0.089408)
		(layer "In11.Cu")
		(net "RMII_BMC_OCP_RXER")
	)
	(segment
		(start 426.58411 -66.248788)
		(end 424.97248 -67.860418)
		(width 0.089408)
		(layer "In11.Cu")
		(net "RMII_BMC_OCP_RXER")
	)
	(segment
		(start 414.22828 -44.178728)
		(end 416.239706 -44.178728)
		(width 0.089408)
		(layer "In11.Cu")
		(net "RMII_BMC_OCP_RXER")
	)
	(segment
		(start 425.61383 -79.426816)
		(end 425.61383 -109.98835)
		(width 0.089408)
		(layer "In11.Cu")
		(net "RMII_BMC_OCP_RXER")
	)
	(segment
		(start 422.044622 -48.550322)
		(end 422.044622 -49.548542)
		(width 0.089408)
		(layer "In11.Cu")
		(net "RMII_BMC_OCP_RXER")
	)
	(segment
		(start 425.636944 -60.728352)
		(end 425.636944 -62.725808)
		(width 0.089408)
		(layer "In11.Cu")
		(net "RMII_BMC_OCP_RXER")
	)
	(segment
		(start 406.894792 -32.0929)
		(end 405.872188 -33.115504)
		(width 0.089408)
		(layer "In11.Cu")
		(net "RMII_BMC_OCP_RXER")
	)
	(segment
		(start 420.870634 -46.94428)
		(end 421.322754 -47.3964)
		(width 0.089408)
		(layer "In11.Cu")
		(net "RMII_BMC_OCP_RXER")
	)
	(segment
		(start 424.97248 -77.642466)
		(end 424.972226 -77.64272)
		(width 0.089408)
		(layer "In11.Cu")
		(net "RMII_BMC_OCP_RXER")
	)
	(segment
		(start 420.870888 -46.41088)
		(end 420.870634 -46.411134)
		(width 0.089408)
		(layer "In11.Cu")
		(net "RMII_BMC_OCP_RXER")
	)
	(segment
		(start 426.584364 -65.138046)
		(end 426.58411 -65.1383)
		(width 0.089408)
		(layer "In11.Cu")
		(net "RMII_BMC_OCP_RXER")
	)
	(segment
		(start 408.770836 -43.45051)
		(end 410.582364 -43.45051)
		(width 0.089408)
		(layer "In11.Cu")
		(net "RMII_BMC_OCP_RXER")
	)
	(segment
		(start 424.988736 -53.998622)
		(end 424.988736 -60.080144)
		(width 0.089408)
		(layer "In11.Cu")
		(net "RMII_BMC_OCP_RXER")
	)
	(segment
		(start 416.817556 -44.756578)
		(end 419.660578 -44.756578)
		(width 0.089408)
		(layer "In11.Cu")
		(net "RMII_BMC_OCP_RXER")
	)
	(segment
		(start 405.872188 -33.115504)
		(end 405.872188 -40.543734)
		(width 0.089408)
		(layer "In11.Cu")
		(net "RMII_BMC_OCP_RXER")
	)
	(segment
		(start 405.872188 -40.543734)
		(end 407.07056 -41.742106)
		(width 0.089408)
		(layer "In11.Cu")
		(net "RMII_BMC_OCP_RXER")
	)
	(segment
		(start 425.61383 -109.98835)
		(end 427.185582 -111.560102)
		(width 0.089408)
		(layer "In11.Cu")
		(net "RMII_BMC_OCP_RXER")
	)
	(segment
		(start 426.58411 -65.1383)
		(end 426.58411 -66.248788)
		(width 0.089408)
		(layer "In11.Cu")
		(net "RMII_BMC_OCP_RXER")
	)
	(segment
		(start 420.870888 -46.033436)
		(end 420.870888 -46.41088)
		(width 0.089408)
		(layer "In11.Cu")
		(net "RMII_BMC_OCP_RXER")
	)
	(segment
		(start 423.392854 -52.40274)
		(end 424.988736 -53.998622)
		(width 0.089408)
		(layer "In11.Cu")
		(net "RMII_BMC_OCP_RXER")
	)
	(segment
		(start 407.07056 -41.742868)
		(end 407.97353 -42.645838)
		(width 0.089408)
		(layer "In11.Cu")
		(net "RMII_BMC_OCP_RXER")
	)
	(segment
		(start 412.440882 -44.491148)
		(end 413.91586 -44.491148)
		(width 0.089408)
		(layer "In11.Cu")
		(net "RMII_BMC_OCP_RXER")
	)
	(segment
		(start 416.239706 -44.178728)
		(end 416.817556 -44.756578)
		(width 0.089408)
		(layer "In11.Cu")
		(net "RMII_BMC_OCP_RXER")
	)
	(segment
		(start 424.97248 -78.785466)
		(end 425.61383 -79.426816)
		(width 0.089408)
		(layer "In11.Cu")
		(net "RMII_BMC_OCP_RXER")
	)
	(segment
		(start 420.870634 -46.033182)
		(end 420.870888 -46.033436)
		(width 0.089408)
		(layer "In11.Cu")
		(net "RMII_BMC_OCP_RXER")
	)
	(segment
		(start 424.97248 -67.860418)
		(end 424.97248 -77.642466)
		(width 0.089408)
		(layer "In11.Cu")
		(net "RMII_BMC_OCP_RXER")
	)
	(segment
		(start 423.392854 -50.896774)
		(end 423.392854 -52.40274)
		(width 0.089408)
		(layer "In11.Cu")
		(net "RMII_BMC_OCP_RXER")
	)
	(segment
		(start 408.404314 -43.07586)
		(end 408.404314 -43.083988)
		(width 0.089408)
		(layer "In11.Cu")
		(net "RMII_BMC_OCP_RXER")
	)
	(segment
		(start 410.582364 -43.45051)
		(end 411.510734 -44.37888)
		(width 0.089408)
		(layer "In11.Cu")
		(net "RMII_BMC_OCP_RXER")
	)
	(segment
		(start 407.07056 -41.742106)
		(end 407.07056 -41.742868)
		(width 0.089408)
		(layer "In11.Cu")
		(net "RMII_BMC_OCP_RXER")
	)
	(segment
		(start 421.322754 -47.828454)
		(end 422.044622 -48.550322)
		(width 0.089408)
		(layer "In11.Cu")
		(net "RMII_BMC_OCP_RXER")
	)
	(segment
		(start 407.97353 -42.645838)
		(end 407.974292 -42.645838)
		(width 0.089408)
		(layer "In11.Cu")
		(net "RMII_BMC_OCP_RXER")
	)
	(segment
		(start 419.660578 -44.756578)
		(end 420.870634 -45.966634)
		(width 0.089408)
		(layer "In11.Cu")
		(net "RMII_BMC_OCP_RXER")
	)
	(segment
		(start 408.404314 -43.083988)
		(end 408.770836 -43.45051)
		(width 0.089408)
		(layer "In11.Cu")
		(net "RMII_BMC_OCP_RXER")
	)
	(segment
		(start 406.894792 -29.929836)
		(end 406.894792 -32.0929)
		(width 0.089408)
		(layer "In11.Cu")
		(net "RMII_BMC_OCP_RXER")
	)
	(segment
		(start 411.510734 -44.37888)
		(end 412.328614 -44.37888)
		(width 0.089408)
		(layer "In11.Cu")
		(net "RMII_BMC_OCP_RXER")
	)
	(segment
		(start 407.974292 -42.645838)
		(end 408.404314 -43.07586)
		(width 0.089408)
		(layer "In11.Cu")
		(net "RMII_BMC_OCP_RXER")
	)
	(segment
		(start 427.185582 -111.560102)
		(end 434.5178 -111.560102)
		(width 0.089408)
		(layer "In11.Cu")
		(net "RMII_BMC_OCP_RXER")
	)
	(segment
		(start 420.870634 -45.966634)
		(end 420.870634 -46.033182)
		(width 0.089408)
		(layer "In11.Cu")
		(net "RMII_BMC_OCP_RXER")
	)
	(segment
		(start 413.91586 -44.491148)
		(end 414.22828 -44.178728)
		(width 0.089408)
		(layer "In11.Cu")
		(net "RMII_BMC_OCP_RXER")
	)
	(segment
		(start 421.322754 -47.3964)
		(end 421.322754 -47.828454)
		(width 0.089408)
		(layer "In11.Cu")
		(net "RMII_BMC_OCP_RXER")
	)
	(segment
		(start 409.490164 -30.53461)
		(end 409.090114 -30.13456)
		(width 0.10795)
		(layer "F.Cu")
		(net "RMII_BMC_OCP_RXD1")
	)
	(via
		(at 438.04586 -112.908334)
		(size 0.508)
		(drill 0.254)
		(layers "F.Cu" "B.Cu")
		(net "RMII_BMC_OCP_RXD1")
	)
	(via
		(at 409.090114 -30.13456)
		(size 0.4572)
		(drill 0.2032)
		(layers "F.Cu" "B.Cu")
		(net "RMII_BMC_OCP_RXD1")
	)
	(via
		(at 469.521794 -113.171732)
		(size 0.6604)
		(drill 0.3302)
		(layers "F.Cu" "B.Cu")
		(net "RMII_BMC_OCP_RXD1")
	)
	(segment
		(start 470.662 -116.363242)
		(end 470.662 -116.84)
		(width 0.10795)
		(layer "B.Cu")
		(net "RMII_BMC_OCP_RXD1")
	)
	(segment
		(start 470.903046 -116.122196)
		(end 470.662 -116.363242)
		(width 0.10795)
		(layer "B.Cu")
		(net "RMII_BMC_OCP_RXD1")
	)
	(segment
		(start 438.911746 -112.042448)
		(end 468.39251 -112.042448)
		(width 0.10795)
		(layer "B.Cu")
		(net "RMII_BMC_OCP_RXD1")
	)
	(segment
		(start 468.39251 -112.042448)
		(end 469.521794 -113.171732)
		(width 0.10795)
		(layer "B.Cu")
		(net "RMII_BMC_OCP_RXD1")
	)
	(segment
		(start 438.04586 -112.908334)
		(end 438.911746 -112.042448)
		(width 0.10795)
		(layer "B.Cu")
		(net "RMII_BMC_OCP_RXD1")
	)
	(segment
		(start 470.903046 -114.552984)
		(end 470.903046 -116.122196)
		(width 0.10795)
		(layer "B.Cu")
		(net "RMII_BMC_OCP_RXD1")
	)
	(segment
		(start 469.521794 -113.171732)
		(end 470.903046 -114.552984)
		(width 0.10795)
		(layer "B.Cu")
		(net "RMII_BMC_OCP_RXD1")
	)
	(segment
		(start 416.893502 -44.29252)
		(end 419.736524 -44.29252)
		(width 0.089408)
		(layer "In11.Cu")
		(net "RMII_BMC_OCP_RXD1")
	)
	(segment
		(start 411.684724 -43.490642)
		(end 411.738572 -43.436794)
		(width 0.089408)
		(layer "In11.Cu")
		(net "RMII_BMC_OCP_RXD1")
	)
	(segment
		(start 425.557696 -77.746352)
		(end 426.199046 -78.387702)
		(width 0.089408)
		(layer "In11.Cu")
		(net "RMII_BMC_OCP_RXD1")
	)
	(segment
		(start 426.036232 -53.219096)
		(end 426.036232 -60.2996)
		(width 0.089408)
		(layer "In11.Cu")
		(net "RMII_BMC_OCP_RXD1")
	)
	(segment
		(start 436.112412 -110.974886)
		(end 438.04586 -112.908334)
		(width 0.089408)
		(layer "In11.Cu")
		(net "RMII_BMC_OCP_RXD1")
	)
	(segment
		(start 414.55594 -43.755056)
		(end 416.356038 -43.755056)
		(width 0.089408)
		(layer "In11.Cu")
		(net "RMII_BMC_OCP_RXD1")
	)
	(segment
		(start 426.036232 -60.2996)
		(end 426.22216 -60.485528)
		(width 0.089408)
		(layer "In11.Cu")
		(net "RMII_BMC_OCP_RXD1")
	)
	(segment
		(start 408.680666 -30.544008)
		(end 408.150822 -30.544008)
		(width 0.089408)
		(layer "In11.Cu")
		(net "RMII_BMC_OCP_RXD1")
	)
	(segment
		(start 406.89403 -38.67912)
		(end 406.821386 -38.751764)
		(width 0.089408)
		(layer "In11.Cu")
		(net "RMII_BMC_OCP_RXD1")
	)
	(segment
		(start 406.362408 -36.846256)
		(end 406.273 -36.935664)
		(width 0.089408)
		(layer "In11.Cu")
		(net "RMII_BMC_OCP_RXD1")
	)
	(segment
		(start 406.821386 -39.901368)
		(end 407.114502 -40.194484)
		(width 0.089408)
		(layer "In11.Cu")
		(net "RMII_BMC_OCP_RXD1")
	)
	(segment
		(start 423.430446 -50.106326)
		(end 424.173142 -50.849022)
		(width 0.089408)
		(layer "In11.Cu")
		(net "RMII_BMC_OCP_RXD1")
	)
	(segment
		(start 419.736524 -44.29252)
		(end 421.252396 -45.808392)
		(width 0.089408)
		(layer "In11.Cu")
		(net "RMII_BMC_OCP_RXD1")
	)
	(segment
		(start 414.237678 -43.436794)
		(end 414.55594 -43.755056)
		(width 0.089408)
		(layer "In11.Cu")
		(net "RMII_BMC_OCP_RXD1")
	)
	(segment
		(start 406.273 -36.935664)
		(end 406.273 -37.11448)
		(width 0.089408)
		(layer "In11.Cu")
		(net "RMII_BMC_OCP_RXD1")
	)
	(segment
		(start 408.150822 -30.544008)
		(end 407.370788 -31.324042)
		(width 0.089408)
		(layer "In11.Cu")
		(net "RMII_BMC_OCP_RXD1")
	)
	(segment
		(start 426.22216 -60.485528)
		(end 426.22216 -62.482984)
		(width 0.089408)
		(layer "In11.Cu")
		(net "RMII_BMC_OCP_RXD1")
	)
	(segment
		(start 426.22216 -62.482984)
		(end 427.16958 -63.430404)
		(width 0.089408)
		(layer "In11.Cu")
		(net "RMII_BMC_OCP_RXD1")
	)
	(segment
		(start 410.6672 -42.9768)
		(end 411.181042 -43.490642)
		(width 0.089408)
		(layer "In11.Cu")
		(net "RMII_BMC_OCP_RXD1")
	)
	(segment
		(start 406.253696 -33.274)
		(end 406.253696 -35.37458)
		(width 0.089408)
		(layer "In11.Cu")
		(net "RMII_BMC_OCP_RXD1")
	)
	(segment
		(start 407.370788 -32.156908)
		(end 406.253696 -33.274)
		(width 0.089408)
		(layer "In11.Cu")
		(net "RMII_BMC_OCP_RXD1")
	)
	(segment
		(start 424.173142 -50.849022)
		(end 424.173142 -51.356006)
		(width 0.089408)
		(layer "In11.Cu")
		(net "RMII_BMC_OCP_RXD1")
	)
	(segment
		(start 406.804622 -37.203888)
		(end 406.89403 -37.293296)
		(width 0.089408)
		(layer "In11.Cu")
		(net "RMII_BMC_OCP_RXD1")
	)
	(segment
		(start 426.199046 -109.745526)
		(end 427.428406 -110.974886)
		(width 0.089408)
		(layer "In11.Cu")
		(net "RMII_BMC_OCP_RXD1")
	)
	(segment
		(start 427.428406 -110.974886)
		(end 436.112412 -110.974886)
		(width 0.089408)
		(layer "In11.Cu")
		(net "RMII_BMC_OCP_RXD1")
	)
	(segment
		(start 406.821386 -38.751764)
		(end 406.821386 -39.901368)
		(width 0.089408)
		(layer "In11.Cu")
		(net "RMII_BMC_OCP_RXD1")
	)
	(segment
		(start 421.252396 -46.786038)
		(end 423.430446 -48.964088)
		(width 0.089408)
		(layer "In11.Cu")
		(net "RMII_BMC_OCP_RXD1")
	)
	(segment
		(start 427.16958 -63.430404)
		(end 427.16958 -66.491358)
		(width 0.089408)
		(layer "In11.Cu")
		(net "RMII_BMC_OCP_RXD1")
	)
	(segment
		(start 407.114502 -41.246044)
		(end 408.845258 -42.9768)
		(width 0.089408)
		(layer "In11.Cu")
		(net "RMII_BMC_OCP_RXD1")
	)
	(segment
		(start 407.114502 -40.194484)
		(end 407.114502 -41.246044)
		(width 0.089408)
		(layer "In11.Cu")
		(net "RMII_BMC_OCP_RXD1")
	)
	(segment
		(start 407.370788 -31.324042)
		(end 407.370788 -32.156908)
		(width 0.089408)
		(layer "In11.Cu")
		(net "RMII_BMC_OCP_RXD1")
	)
	(segment
		(start 408.845258 -42.9768)
		(end 410.6672 -42.9768)
		(width 0.089408)
		(layer "In11.Cu")
		(net "RMII_BMC_OCP_RXD1")
	)
	(segment
		(start 427.16958 -66.491358)
		(end 425.557696 -68.103242)
		(width 0.089408)
		(layer "In11.Cu")
		(net "RMII_BMC_OCP_RXD1")
	)
	(segment
		(start 406.253696 -35.37458)
		(end 406.89403 -36.014914)
		(width 0.089408)
		(layer "In11.Cu")
		(net "RMII_BMC_OCP_RXD1")
	)
	(segment
		(start 416.356038 -43.755056)
		(end 416.893502 -44.29252)
		(width 0.089408)
		(layer "In11.Cu")
		(net "RMII_BMC_OCP_RXD1")
	)
	(segment
		(start 406.89403 -36.014914)
		(end 406.89403 -36.756848)
		(width 0.089408)
		(layer "In11.Cu")
		(net "RMII_BMC_OCP_RXD1")
	)
	(segment
		(start 411.181042 -43.490642)
		(end 411.684724 -43.490642)
		(width 0.089408)
		(layer "In11.Cu")
		(net "RMII_BMC_OCP_RXD1")
	)
	(segment
		(start 406.804622 -36.846256)
		(end 406.362408 -36.846256)
		(width 0.089408)
		(layer "In11.Cu")
		(net "RMII_BMC_OCP_RXD1")
	)
	(segment
		(start 424.173142 -51.356006)
		(end 426.036232 -53.219096)
		(width 0.089408)
		(layer "In11.Cu")
		(net "RMII_BMC_OCP_RXD1")
	)
	(segment
		(start 426.199046 -78.387702)
		(end 426.199046 -109.745526)
		(width 0.089408)
		(layer "In11.Cu")
		(net "RMII_BMC_OCP_RXD1")
	)
	(segment
		(start 409.090114 -30.13456)
		(end 408.680666 -30.544008)
		(width 0.089408)
		(layer "In11.Cu")
		(net "RMII_BMC_OCP_RXD1")
	)
	(segment
		(start 411.738572 -43.436794)
		(end 414.237678 -43.436794)
		(width 0.089408)
		(layer "In11.Cu")
		(net "RMII_BMC_OCP_RXD1")
	)
	(segment
		(start 406.273 -37.11448)
		(end 406.362408 -37.203888)
		(width 0.089408)
		(layer "In11.Cu")
		(net "RMII_BMC_OCP_RXD1")
	)
	(segment
		(start 421.252396 -45.808392)
		(end 421.252396 -46.786038)
		(width 0.089408)
		(layer "In11.Cu")
		(net "RMII_BMC_OCP_RXD1")
	)
	(segment
		(start 425.557696 -68.103242)
		(end 425.557696 -77.746352)
		(width 0.089408)
		(layer "In11.Cu")
		(net "RMII_BMC_OCP_RXD1")
	)
	(segment
		(start 406.89403 -37.293296)
		(end 406.89403 -38.67912)
		(width 0.089408)
		(layer "In11.Cu")
		(net "RMII_BMC_OCP_RXD1")
	)
	(segment
		(start 423.430446 -48.964088)
		(end 423.430446 -50.106326)
		(width 0.089408)
		(layer "In11.Cu")
		(net "RMII_BMC_OCP_RXD1")
	)
	(segment
		(start 406.362408 -37.203888)
		(end 406.804622 -37.203888)
		(width 0.089408)
		(layer "In11.Cu")
		(net "RMII_BMC_OCP_RXD1")
	)
	(segment
		(start 406.89403 -36.756848)
		(end 406.804622 -36.846256)
		(width 0.089408)
		(layer "In11.Cu")
		(net "RMII_BMC_OCP_RXD1")
	)
	(segment
		(start 407.090118 -28.134564)
		(end 406.52446 -28.134564)
		(width 0.10795)
		(layer "F.Cu")
		(net "RMII_BMC_OCP_RXD0")
	)
	(via
		(at 437.38546 -112.908334)
		(size 0.508)
		(drill 0.254)
		(layers "F.Cu" "B.Cu")
		(net "RMII_BMC_OCP_RXD0")
	)
	(via
		(at 406.52446 -28.134564)
		(size 0.4572)
		(drill 0.2032)
		(layers "F.Cu" "B.Cu")
		(net "RMII_BMC_OCP_RXD0")
	)
	(via
		(at 471.531188 -115.9256)
		(size 0.6604)
		(drill 0.3302)
		(layers "F.Cu" "B.Cu")
		(net "RMII_BMC_OCP_RXD0")
	)
	(segment
		(start 470.562686 -113.41735)
		(end 470.737438 -113.41735)
		(width 0.10795)
		(layer "B.Cu")
		(net "RMII_BMC_OCP_RXD0")
	)
	(segment
		(start 437.38546 -112.148874)
		(end 438.351676 -111.182658)
		(width 0.10795)
		(layer "B.Cu")
		(net "RMII_BMC_OCP_RXD0")
	)
	(segment
		(start 437.38546 -112.908334)
		(end 437.38546 -112.148874)
		(width 0.10795)
		(layer "B.Cu")
		(net "RMII_BMC_OCP_RXD0")
	)
	(segment
		(start 471.531188 -115.932204)
		(end 471.424 -116.039392)
		(width 0.10795)
		(layer "B.Cu")
		(net "RMII_BMC_OCP_RXD0")
	)
	(segment
		(start 470.737438 -113.41735)
		(end 471.531188 -114.2111)
		(width 0.10795)
		(layer "B.Cu")
		(net "RMII_BMC_OCP_RXD0")
	)
	(segment
		(start 438.351676 -111.182658)
		(end 468.327994 -111.182658)
		(width 0.10795)
		(layer "B.Cu")
		(net "RMII_BMC_OCP_RXD0")
	)
	(segment
		(start 471.531188 -114.2111)
		(end 471.531188 -115.9256)
		(width 0.10795)
		(layer "B.Cu")
		(net "RMII_BMC_OCP_RXD0")
	)
	(segment
		(start 471.531188 -115.9256)
		(end 471.531188 -115.932204)
		(width 0.10795)
		(layer "B.Cu")
		(net "RMII_BMC_OCP_RXD0")
	)
	(segment
		(start 468.327994 -111.182658)
		(end 470.562686 -113.41735)
		(width 0.10795)
		(layer "B.Cu")
		(net "RMII_BMC_OCP_RXD0")
	)
	(segment
		(start 471.424 -116.039392)
		(end 471.424 -116.84)
		(width 0.10795)
		(layer "B.Cu")
		(net "RMII_BMC_OCP_RXD0")
	)
	(segment
		(start 410.301948 -44.269406)
		(end 410.064204 -44.50715)
		(width 0.089408)
		(layer "In11.Cu")
		(net "RMII_BMC_OCP_RXD0")
	)
	(segment
		(start 426.393102 -65.059052)
		(end 426.393356 -65.058798)
		(width 0.089408)
		(layer "In11.Cu")
		(net "RMII_BMC_OCP_RXD0")
	)
	(segment
		(start 425.445936 -60.8076)
		(end 424.782742 -60.144406)
		(width 0.089408)
		(layer "In11.Cu")
		(net "RMII_BMC_OCP_RXD0")
	)
	(segment
		(start 421.853614 -49.62779)
		(end 421.853614 -48.9712)
		(width 0.089408)
		(layer "In11.Cu")
		(net "RMII_BMC_OCP_RXD0")
	)
	(segment
		(start 416.160458 -44.369482)
		(end 414.307528 -44.369482)
		(width 0.089408)
		(layer "In11.Cu")
		(net "RMII_BMC_OCP_RXD0")
	)
	(segment
		(start 405.681434 -33.036256)
		(end 406.6794 -32.03829)
		(width 0.089408)
		(layer "In11.Cu")
		(net "RMII_BMC_OCP_RXD0")
	)
	(segment
		(start 405.117808 -40.323008)
		(end 405.117808 -39.270432)
		(width 0.089408)
		(layer "In11.Cu")
		(net "RMII_BMC_OCP_RXD0")
	)
	(segment
		(start 407.894282 -42.836592)
		(end 405.748744 -40.691054)
		(width 0.089408)
		(layer "In11.Cu")
		(net "RMII_BMC_OCP_RXD0")
	)
	(segment
		(start 425.445936 -62.805056)
		(end 425.445936 -60.8076)
		(width 0.089408)
		(layer "In11.Cu")
		(net "RMII_BMC_OCP_RXD0")
	)
	(segment
		(start 408.21356 -43.155108)
		(end 407.895044 -42.836592)
		(width 0.089408)
		(layer "In11.Cu")
		(net "RMII_BMC_OCP_RXD0")
	)
	(segment
		(start 408.21356 -44.041822)
		(end 408.21356 -43.321732)
		(width 0.089408)
		(layer "In11.Cu")
		(net "RMII_BMC_OCP_RXD0")
	)
	(segment
		(start 408.678888 -44.50715)
		(end 408.21356 -44.041822)
		(width 0.089408)
		(layer "In11.Cu")
		(net "RMII_BMC_OCP_RXD0")
	)
	(segment
		(start 405.681434 -38.706806)
		(end 405.681434 -33.036256)
		(width 0.089408)
		(layer "In11.Cu")
		(net "RMII_BMC_OCP_RXD0")
	)
	(segment
		(start 425.422822 -79.506064)
		(end 424.781472 -78.864714)
		(width 0.089408)
		(layer "In11.Cu")
		(net "RMII_BMC_OCP_RXD0")
	)
	(segment
		(start 408.213814 -43.321478)
		(end 408.213814 -43.16349)
		(width 0.089408)
		(layer "In11.Cu")
		(net "RMII_BMC_OCP_RXD0")
	)
	(segment
		(start 424.781472 -78.62951)
		(end 424.781218 -78.629256)
		(width 0.089408)
		(layer "In11.Cu")
		(net "RMII_BMC_OCP_RXD0")
	)
	(segment
		(start 419.977824 -45.343826)
		(end 419.60038 -44.966382)
		(width 0.089408)
		(layer "In11.Cu")
		(net "RMII_BMC_OCP_RXD0")
	)
	(segment
		(start 437.38546 -112.908334)
		(end 436.946294 -113.3475)
		(width 0.089408)
		(layer "In11.Cu")
		(net "RMII_BMC_OCP_RXD0")
	)
	(segment
		(start 421.853614 -48.9712)
		(end 419.977824 -47.09541)
		(width 0.089408)
		(layer "In11.Cu")
		(net "RMII_BMC_OCP_RXD0")
	)
	(segment
		(start 413.995108 -44.681902)
		(end 412.361634 -44.681902)
		(width 0.089408)
		(layer "In11.Cu")
		(net "RMII_BMC_OCP_RXD0")
	)
	(segment
		(start 412.277814 -44.598082)
		(end 411.39491 -44.598082)
		(width 0.089408)
		(layer "In11.Cu")
		(net "RMII_BMC_OCP_RXD0")
	)
	(segment
		(start 410.064204 -44.50715)
		(end 408.678888 -44.50715)
		(width 0.089408)
		(layer "In11.Cu")
		(net "RMII_BMC_OCP_RXD0")
	)
	(segment
		(start 424.781218 -78.629256)
		(end 424.781218 -77.563472)
		(width 0.089408)
		(layer "In11.Cu")
		(net "RMII_BMC_OCP_RXD0")
	)
	(segment
		(start 406.6794 -28.289504)
		(end 406.52446 -28.134564)
		(width 0.089408)
		(layer "In11.Cu")
		(net "RMII_BMC_OCP_RXD0")
	)
	(segment
		(start 424.782742 -54.062884)
		(end 423.201846 -52.481988)
		(width 0.089408)
		(layer "In11.Cu")
		(net "RMII_BMC_OCP_RXD0")
	)
	(segment
		(start 405.748744 -40.691054)
		(end 405.485854 -40.691054)
		(width 0.089408)
		(layer "In11.Cu")
		(net "RMII_BMC_OCP_RXD0")
	)
	(segment
		(start 426.393356 -63.752476)
		(end 425.445936 -62.805056)
		(width 0.089408)
		(layer "In11.Cu")
		(net "RMII_BMC_OCP_RXD0")
	)
	(segment
		(start 411.066234 -44.269406)
		(end 410.301948 -44.269406)
		(width 0.089408)
		(layer "In11.Cu")
		(net "RMII_BMC_OCP_RXD0")
	)
	(segment
		(start 419.60038 -44.966382)
		(end 416.757358 -44.966382)
		(width 0.089408)
		(layer "In11.Cu")
		(net "RMII_BMC_OCP_RXD0")
	)
	(segment
		(start 423.201846 -52.481988)
		(end 423.201846 -50.976022)
		(width 0.089408)
		(layer "In11.Cu")
		(net "RMII_BMC_OCP_RXD0")
	)
	(segment
		(start 424.781472 -77.563218)
		(end 424.781472 -67.78117)
		(width 0.089408)
		(layer "In11.Cu")
		(net "RMII_BMC_OCP_RXD0")
	)
	(segment
		(start 416.757358 -44.966382)
		(end 416.160458 -44.369482)
		(width 0.089408)
		(layer "In11.Cu")
		(net "RMII_BMC_OCP_RXD0")
	)
	(segment
		(start 411.39491 -44.598082)
		(end 411.066234 -44.269406)
		(width 0.089408)
		(layer "In11.Cu")
		(net "RMII_BMC_OCP_RXD0")
	)
	(segment
		(start 419.977824 -47.09541)
		(end 419.977824 -45.343826)
		(width 0.089408)
		(layer "In11.Cu")
		(net "RMII_BMC_OCP_RXD0")
	)
	(segment
		(start 433.215542 -111.75111)
		(end 427.106334 -111.75111)
		(width 0.089408)
		(layer "In11.Cu")
		(net "RMII_BMC_OCP_RXD0")
	)
	(segment
		(start 426.393356 -65.058798)
		(end 426.393356 -63.752476)
		(width 0.089408)
		(layer "In11.Cu")
		(net "RMII_BMC_OCP_RXD0")
	)
	(segment
		(start 424.781472 -67.78117)
		(end 426.393102 -66.16954)
		(width 0.089408)
		(layer "In11.Cu")
		(net "RMII_BMC_OCP_RXD0")
	)
	(segment
		(start 426.393102 -66.16954)
		(end 426.393102 -65.059052)
		(width 0.089408)
		(layer "In11.Cu")
		(net "RMII_BMC_OCP_RXD0")
	)
	(segment
		(start 425.422822 -110.067598)
		(end 425.422822 -79.506064)
		(width 0.089408)
		(layer "In11.Cu")
		(net "RMII_BMC_OCP_RXD0")
	)
	(segment
		(start 427.106334 -111.75111)
		(end 425.422822 -110.067598)
		(width 0.089408)
		(layer "In11.Cu")
		(net "RMII_BMC_OCP_RXD0")
	)
	(segment
		(start 405.485854 -40.691054)
		(end 405.117808 -40.323008)
		(width 0.089408)
		(layer "In11.Cu")
		(net "RMII_BMC_OCP_RXD0")
	)
	(segment
		(start 436.946294 -113.3475)
		(end 434.811932 -113.3475)
		(width 0.089408)
		(layer "In11.Cu")
		(net "RMII_BMC_OCP_RXD0")
	)
	(segment
		(start 424.781472 -78.864714)
		(end 424.781472 -78.62951)
		(width 0.089408)
		(layer "In11.Cu")
		(net "RMII_BMC_OCP_RXD0")
	)
	(segment
		(start 407.895044 -42.836592)
		(end 407.894282 -42.836592)
		(width 0.089408)
		(layer "In11.Cu")
		(net "RMII_BMC_OCP_RXD0")
	)
	(segment
		(start 424.782742 -60.144406)
		(end 424.782742 -54.062884)
		(width 0.089408)
		(layer "In11.Cu")
		(net "RMII_BMC_OCP_RXD0")
	)
	(segment
		(start 414.307528 -44.369482)
		(end 413.995108 -44.681902)
		(width 0.089408)
		(layer "In11.Cu")
		(net "RMII_BMC_OCP_RXD0")
	)
	(segment
		(start 406.6794 -32.03829)
		(end 406.6794 -28.289504)
		(width 0.089408)
		(layer "In11.Cu")
		(net "RMII_BMC_OCP_RXD0")
	)
	(segment
		(start 405.117808 -39.270432)
		(end 405.681434 -38.706806)
		(width 0.089408)
		(layer "In11.Cu")
		(net "RMII_BMC_OCP_RXD0")
	)
	(segment
		(start 423.201846 -50.976022)
		(end 421.853614 -49.62779)
		(width 0.089408)
		(layer "In11.Cu")
		(net "RMII_BMC_OCP_RXD0")
	)
	(segment
		(start 408.213814 -43.16349)
		(end 408.21356 -43.163236)
		(width 0.089408)
		(layer "In11.Cu")
		(net "RMII_BMC_OCP_RXD0")
	)
	(segment
		(start 408.21356 -43.163236)
		(end 408.21356 -43.155108)
		(width 0.089408)
		(layer "In11.Cu")
		(net "RMII_BMC_OCP_RXD0")
	)
	(segment
		(start 412.361634 -44.681902)
		(end 412.277814 -44.598082)
		(width 0.089408)
		(layer "In11.Cu")
		(net "RMII_BMC_OCP_RXD0")
	)
	(segment
		(start 424.781218 -77.563472)
		(end 424.781472 -77.563218)
		(width 0.089408)
		(layer "In11.Cu")
		(net "RMII_BMC_OCP_RXD0")
	)
	(segment
		(start 408.21356 -43.321732)
		(end 408.213814 -43.321478)
		(width 0.089408)
		(layer "In11.Cu")
		(net "RMII_BMC_OCP_RXD0")
	)
	(segment
		(start 434.811932 -113.3475)
		(end 433.215542 -111.75111)
		(width 0.089408)
		(layer "In11.Cu")
		(net "RMII_BMC_OCP_RXD0")
	)
	(segment
		(start 408.690064 -29.734764)
		(end 408.290014 -29.334714)
		(width 0.10795)
		(layer "F.Cu")
		(net "RMII_BMC_OCP_CRSDV")
	)
	(via
		(at 436.6006 -113.792)
		(size 0.6604)
		(drill 0.3302)
		(layers "F.Cu" "B.Cu")
		(net "RMII_BMC_OCP_CRSDV")
	)
	(via
		(at 436.521098 -112.9157)
		(size 0.508)
		(drill 0.254)
		(layers "F.Cu" "B.Cu")
		(net "RMII_BMC_OCP_CRSDV")
	)
	(via
		(at 408.290014 -29.334714)
		(size 0.4572)
		(drill 0.2032)
		(layers "F.Cu" "B.Cu")
		(net "RMII_BMC_OCP_CRSDV")
	)
	(segment
		(start 436.6006 -112.995202)
		(end 436.521098 -112.9157)
		(width 0.10795)
		(layer "B.Cu")
		(net "RMII_BMC_OCP_CRSDV")
	)
	(segment
		(start 468.478108 -110.820708)
		(end 470.7128 -113.0554)
		(width 0.10795)
		(layer "B.Cu")
		(net "RMII_BMC_OCP_CRSDV")
	)
	(segment
		(start 436.263034 -111.816896)
		(end 437.259222 -110.820708)
		(width 0.10795)
		(layer "B.Cu")
		(net "RMII_BMC_OCP_CRSDV")
	)
	(segment
		(start 436.263034 -112.657636)
		(end 436.263034 -111.816896)
		(width 0.10795)
		(layer "B.Cu")
		(net "RMII_BMC_OCP_CRSDV")
	)
	(segment
		(start 436.6006 -113.792)
		(end 436.6006 -112.995202)
		(width 0.10795)
		(layer "B.Cu")
		(net "RMII_BMC_OCP_CRSDV")
	)
	(segment
		(start 470.7128 -113.0554)
		(end 471.17 -113.0554)
		(width 0.10795)
		(layer "B.Cu")
		(net "RMII_BMC_OCP_CRSDV")
	)
	(segment
		(start 436.521098 -112.9157)
		(end 436.263034 -112.657636)
		(width 0.10795)
		(layer "B.Cu")
		(net "RMII_BMC_OCP_CRSDV")
	)
	(segment
		(start 437.259222 -110.820708)
		(end 468.478108 -110.820708)
		(width 0.10795)
		(layer "B.Cu")
		(net "RMII_BMC_OCP_CRSDV")
	)
	(segment
		(start 406.062942 -40.464486)
		(end 406.062942 -33.194752)
		(width 0.089408)
		(layer "In11.Cu")
		(net "RMII_BMC_OCP_CRSDV")
	)
	(segment
		(start 407.0858 -30.538928)
		(end 408.290014 -29.334714)
		(width 0.089408)
		(layer "In11.Cu")
		(net "RMII_BMC_OCP_CRSDV")
	)
	(segment
		(start 421.061388 -46.490382)
		(end 421.061642 -46.490128)
		(width 0.089408)
		(layer "In11.Cu")
		(net "RMII_BMC_OCP_CRSDV")
	)
	(segment
		(start 436.521098 -112.9157)
		(end 434.872892 -111.267494)
		(width 0.089408)
		(layer "In11.Cu")
		(net "RMII_BMC_OCP_CRSDV")
	)
	(segment
		(start 411.81782 -43.627548)
		(end 411.733238 -43.71213)
		(width 0.089408)
		(layer "In11.Cu")
		(net "RMII_BMC_OCP_CRSDV")
	)
	(segment
		(start 419.72992 -44.555918)
		(end 416.886898 -44.555918)
		(width 0.089408)
		(layer "In11.Cu")
		(net "RMII_BMC_OCP_CRSDV")
	)
	(segment
		(start 421.061642 -45.954188)
		(end 421.061388 -45.953934)
		(width 0.089408)
		(layer "In11.Cu")
		(net "RMII_BMC_OCP_CRSDV")
	)
	(segment
		(start 410.591 -43.18)
		(end 408.778456 -43.18)
		(width 0.089408)
		(layer "In11.Cu")
		(net "RMII_BMC_OCP_CRSDV")
	)
	(segment
		(start 411.733238 -43.71213)
		(end 411.12313 -43.71213)
		(width 0.089408)
		(layer "In11.Cu")
		(net "RMII_BMC_OCP_CRSDV")
	)
	(segment
		(start 412.347918 -43.847004)
		(end 412.128462 -43.627548)
		(width 0.089408)
		(layer "In11.Cu")
		(net "RMII_BMC_OCP_CRSDV")
	)
	(segment
		(start 425.906438 -78.509114)
		(end 425.265088 -77.867764)
		(width 0.089408)
		(layer "In11.Cu")
		(net "RMII_BMC_OCP_CRSDV")
	)
	(segment
		(start 423.685462 -50.775362)
		(end 423.137838 -50.227738)
		(width 0.089408)
		(layer "In11.Cu")
		(net "RMII_BMC_OCP_CRSDV")
	)
	(segment
		(start 425.743624 -53.340508)
		(end 423.685462 -51.282346)
		(width 0.089408)
		(layer "In11.Cu")
		(net "RMII_BMC_OCP_CRSDV")
	)
	(segment
		(start 421.061388 -45.953934)
		(end 421.061388 -45.887386)
		(width 0.089408)
		(layer "In11.Cu")
		(net "RMII_BMC_OCP_CRSDV")
	)
	(segment
		(start 421.061388 -46.865032)
		(end 421.061388 -46.490382)
		(width 0.089408)
		(layer "In11.Cu")
		(net "RMII_BMC_OCP_CRSDV")
	)
	(segment
		(start 413.799782 -44.300394)
		(end 412.58617 -44.300394)
		(width 0.089408)
		(layer "In11.Cu")
		(net "RMII_BMC_OCP_CRSDV")
	)
	(segment
		(start 425.265088 -67.98183)
		(end 426.876972 -66.369946)
		(width 0.089408)
		(layer "In11.Cu")
		(net "RMII_BMC_OCP_CRSDV")
	)
	(segment
		(start 421.615362 -47.707042)
		(end 421.615362 -47.419006)
		(width 0.089408)
		(layer "In11.Cu")
		(net "RMII_BMC_OCP_CRSDV")
	)
	(segment
		(start 414.112202 -43.987974)
		(end 413.799782 -44.300394)
		(width 0.089408)
		(layer "In11.Cu")
		(net "RMII_BMC_OCP_CRSDV")
	)
	(segment
		(start 416.886898 -44.555918)
		(end 416.318954 -43.987974)
		(width 0.089408)
		(layer "In11.Cu")
		(net "RMII_BMC_OCP_CRSDV")
	)
	(segment
		(start 412.128462 -43.627548)
		(end 411.81782 -43.627548)
		(width 0.089408)
		(layer "In11.Cu")
		(net "RMII_BMC_OCP_CRSDV")
	)
	(segment
		(start 434.872892 -111.267494)
		(end 427.306994 -111.267494)
		(width 0.089408)
		(layer "In11.Cu")
		(net "RMII_BMC_OCP_CRSDV")
	)
	(segment
		(start 421.615362 -47.419006)
		(end 421.061388 -46.865032)
		(width 0.089408)
		(layer "In11.Cu")
		(net "RMII_BMC_OCP_CRSDV")
	)
	(segment
		(start 425.929552 -62.604396)
		(end 425.929552 -60.60694)
		(width 0.089408)
		(layer "In11.Cu")
		(net "RMII_BMC_OCP_CRSDV")
	)
	(segment
		(start 416.318954 -43.987974)
		(end 414.112202 -43.987974)
		(width 0.089408)
		(layer "In11.Cu")
		(net "RMII_BMC_OCP_CRSDV")
	)
	(segment
		(start 412.347918 -44.062142)
		(end 412.347918 -43.847004)
		(width 0.089408)
		(layer "In11.Cu")
		(net "RMII_BMC_OCP_CRSDV")
	)
	(segment
		(start 423.137838 -49.229518)
		(end 421.615362 -47.707042)
		(width 0.089408)
		(layer "In11.Cu")
		(net "RMII_BMC_OCP_CRSDV")
	)
	(segment
		(start 423.137838 -50.227738)
		(end 423.137838 -49.229518)
		(width 0.089408)
		(layer "In11.Cu")
		(net "RMII_BMC_OCP_CRSDV")
	)
	(segment
		(start 425.743624 -60.421012)
		(end 425.743624 -53.340508)
		(width 0.089408)
		(layer "In11.Cu")
		(net "RMII_BMC_OCP_CRSDV")
	)
	(segment
		(start 425.929552 -60.60694)
		(end 425.743624 -60.421012)
		(width 0.089408)
		(layer "In11.Cu")
		(net "RMII_BMC_OCP_CRSDV")
	)
	(segment
		(start 406.062942 -33.194752)
		(end 407.0858 -32.171894)
		(width 0.089408)
		(layer "In11.Cu")
		(net "RMII_BMC_OCP_CRSDV")
	)
	(segment
		(start 426.876972 -63.551816)
		(end 425.929552 -62.604396)
		(width 0.089408)
		(layer "In11.Cu")
		(net "RMII_BMC_OCP_CRSDV")
	)
	(segment
		(start 423.685462 -51.282346)
		(end 423.685462 -50.775362)
		(width 0.089408)
		(layer "In11.Cu")
		(net "RMII_BMC_OCP_CRSDV")
	)
	(segment
		(start 421.061388 -45.887386)
		(end 419.72992 -44.555918)
		(width 0.089408)
		(layer "In11.Cu")
		(net "RMII_BMC_OCP_CRSDV")
	)
	(segment
		(start 412.58617 -44.300394)
		(end 412.347918 -44.062142)
		(width 0.089408)
		(layer "In11.Cu")
		(net "RMII_BMC_OCP_CRSDV")
	)
	(segment
		(start 421.061642 -46.490128)
		(end 421.061642 -45.954188)
		(width 0.089408)
		(layer "In11.Cu")
		(net "RMII_BMC_OCP_CRSDV")
	)
	(segment
		(start 408.778456 -43.18)
		(end 406.062942 -40.464486)
		(width 0.089408)
		(layer "In11.Cu")
		(net "RMII_BMC_OCP_CRSDV")
	)
	(segment
		(start 425.265088 -77.867764)
		(end 425.265088 -67.98183)
		(width 0.089408)
		(layer "In11.Cu")
		(net "RMII_BMC_OCP_CRSDV")
	)
	(segment
		(start 407.0858 -32.171894)
		(end 407.0858 -30.538928)
		(width 0.089408)
		(layer "In11.Cu")
		(net "RMII_BMC_OCP_CRSDV")
	)
	(segment
		(start 411.12313 -43.71213)
		(end 410.591 -43.18)
		(width 0.089408)
		(layer "In11.Cu")
		(net "RMII_BMC_OCP_CRSDV")
	)
	(segment
		(start 427.306994 -111.267494)
		(end 425.906438 -109.866938)
		(width 0.089408)
		(layer "In11.Cu")
		(net "RMII_BMC_OCP_CRSDV")
	)
	(segment
		(start 426.876972 -66.369946)
		(end 426.876972 -63.551816)
		(width 0.089408)
		(layer "In11.Cu")
		(net "RMII_BMC_OCP_CRSDV")
	)
	(segment
		(start 425.906438 -109.866938)
		(end 425.906438 -78.509114)
		(width 0.089408)
		(layer "In11.Cu")
		(net "RMII_BMC_OCP_CRSDV")
	)
	(segment
		(start 30.549342 -156.87294)
		(end 30.549342 -155.692856)
		(width 0.4064)
		(layer "F.Cu")
		(net "M_M_VREF")
	)
	(segment
		(start 30.528768 -149.6568)
		(end 30.528768 -148.844)
		(width 0.4064)
		(layer "F.Cu")
		(net "M_M_VREF")
	)
	(segment
		(start 30.549342 -155.692856)
		(end 30.452568 -155.596082)
		(width 0.4064)
		(layer "F.Cu")
		(net "M_M_VREF")
	)
	(segment
		(start 30.528768 -148.844)
		(end 30.452568 -148.7678)
		(width 0.4064)
		(layer "F.Cu")
		(net "M_M_VREF")
	)
	(via
		(at 30.452568 -155.596082)
		(size 0.508)
		(drill 0.254)
		(layers "F.Cu" "B.Cu")
		(net "M_M_VREF")
	)
	(via
		(at 30.452568 -148.7678)
		(size 0.508)
		(drill 0.254)
		(layers "F.Cu" "B.Cu")
		(net "M_M_VREF")
	)
	(segment
		(start 30.549342 -148.671026)
		(end 30.452568 -148.7678)
		(width 0.4064)
		(layer "B.Cu")
		(net "M_M_VREF")
	)
	(segment
		(start 29.563568 -155.448)
		(end 28.674568 -155.448)
		(width 0.4064)
		(layer "B.Cu")
		(net "M_M_VREF")
	)
	(segment
		(start 30.452568 -155.596082)
		(end 30.452568 -154.6352)
		(width 0.4064)
		(layer "B.Cu")
		(net "M_M_VREF")
	)
	(segment
		(start 28.674568 -155.448)
		(end 27.785568 -155.448)
		(width 0.4064)
		(layer "B.Cu")
		(net "M_M_VREF")
	)
	(segment
		(start 30.549342 -147.478496)
		(end 30.549342 -148.671026)
		(width 0.4064)
		(layer "B.Cu")
		(net "M_M_VREF")
	)
	(segment
		(start 30.304486 -155.448)
		(end 30.452568 -155.596082)
		(width 0.4064)
		(layer "B.Cu")
		(net "M_M_VREF")
	)
	(segment
		(start 29.563568 -155.448)
		(end 30.304486 -155.448)
		(width 0.4064)
		(layer "B.Cu")
		(net "M_M_VREF")
	)
	(segment
		(start 30.452568 -151.690832)
		(end 29.845 -152.2984)
		(width 0.4064)
		(layer "In4.Cu")
		(net "M_M_VREF")
	)
	(segment
		(start 30.452568 -154.759914)
		(end 30.452568 -155.596082)
		(width 0.4064)
		(layer "In4.Cu")
		(net "M_M_VREF")
	)
	(segment
		(start 29.845 -154.152346)
		(end 30.452568 -154.759914)
		(width 0.4064)
		(layer "In4.Cu")
		(net "M_M_VREF")
	)
	(segment
		(start 30.452568 -148.7678)
		(end 30.452568 -151.690832)
		(width 0.4064)
		(layer "In4.Cu")
		(net "M_M_VREF")
	)
	(segment
		(start 29.845 -152.2984)
		(end 29.845 -154.152346)
		(width 0.4064)
		(layer "In4.Cu")
		(net "M_M_VREF")
	)
	(segment
		(start 89.211912 -87.784686)
		(end 88.640412 -87.784686)
		(width 0.1016)
		(layer "F.Cu")
		(net "M_M_CPU_VREF")
	)
	(via
		(at 44.350686 -102.618286)
		(size 0.508)
		(drill 0.254)
		(layers "F.Cu" "B.Cu")
		(net "M_M_CPU_VREF")
	)
	(via
		(at 61.787786 -92.291916)
		(size 0.6604)
		(drill 0.3302)
		(layers "F.Cu" "B.Cu")
		(net "M_M_CPU_VREF")
	)
	(via
		(at 26.972768 -153.5684)
		(size 0.508)
		(drill 0.254)
		(layers "F.Cu" "B.Cu")
		(net "M_M_CPU_VREF")
	)
	(via
		(at 88.640412 -87.784686)
		(size 0.508)
		(drill 0.254)
		(layers "F.Cu" "B.Cu")
		(net "M_M_CPU_VREF")
	)
	(segment
		(start 67.694302 -86.233762)
		(end 67.31508 -85.85454)
		(width 0.1524)
		(layer "B.Cu")
		(net "M_M_CPU_VREF")
	)
	(segment
		(start 70.433438 -85.868764)
		(end 70.06844 -86.233762)
		(width 0.1524)
		(layer "B.Cu")
		(net "M_M_CPU_VREF")
	)
	(segment
		(start 73.369678 -86.233762)
		(end 72.911462 -86.233762)
		(width 0.1524)
		(layer "B.Cu")
		(net "M_M_CPU_VREF")
	)
	(segment
		(start 45.389546 -104.152446)
		(end 49.927256 -104.152446)
		(width 0.254)
		(layer "B.Cu")
		(net "M_M_CPU_VREF")
	)
	(segment
		(start 81.593944 -85.37321)
		(end 81.211674 -85.75548)
		(width 0.1524)
		(layer "B.Cu")
		(net "M_M_CPU_VREF")
	)
	(segment
		(start 66.425826 -85.85454)
		(end 64.736726 -87.54364)
		(width 0.254)
		(layer "B.Cu")
		(net "M_M_CPU_VREF")
	)
	(segment
		(start 75.096878 -86.233762)
		(end 74.726038 -86.233762)
		(width 0.1524)
		(layer "B.Cu")
		(net "M_M_CPU_VREF")
	)
	(segment
		(start 72.911462 -86.233762)
		(end 72.546464 -85.868764)
		(width 0.1524)
		(layer "B.Cu")
		(net "M_M_CPU_VREF")
	)
	(segment
		(start 44.350686 -102.618286)
		(end 44.350686 -103.113586)
		(width 0.254)
		(layer "B.Cu")
		(net "M_M_CPU_VREF")
	)
	(segment
		(start 49.927256 -104.152446)
		(end 61.787786 -92.291916)
		(width 0.254)
		(layer "B.Cu")
		(net "M_M_CPU_VREF")
	)
	(segment
		(start 82.086958 -85.37321)
		(end 81.593944 -85.37321)
		(width 0.1524)
		(layer "B.Cu")
		(net "M_M_CPU_VREF")
	)
	(segment
		(start 84.915756 -86.2584)
		(end 84.52612 -85.868764)
		(width 0.1524)
		(layer "B.Cu")
		(net "M_M_CPU_VREF")
	)
	(segment
		(start 83.804506 -86.233762)
		(end 83.174078 -86.233762)
		(width 0.1524)
		(layer "B.Cu")
		(net "M_M_CPU_VREF")
	)
	(segment
		(start 87.603584 -86.729316)
		(end 87.132668 -86.2584)
		(width 0.1524)
		(layer "B.Cu")
		(net "M_M_CPU_VREF")
	)
	(segment
		(start 62.704218 -88.357456)
		(end 62.704218 -91.375484)
		(width 0.254)
		(layer "B.Cu")
		(net "M_M_CPU_VREF")
	)
	(segment
		(start 78.159864 -86.233762)
		(end 77.794866 -85.868764)
		(width 0.1524)
		(layer "B.Cu")
		(net "M_M_CPU_VREF")
	)
	(segment
		(start 26.896568 -154.559)
		(end 26.972768 -154.4828)
		(width 0.254)
		(layer "B.Cu")
		(net "M_M_CPU_VREF")
	)
	(segment
		(start 76.816458 -86.233762)
		(end 76.443078 -86.233762)
		(width 0.1524)
		(layer "B.Cu")
		(net "M_M_CPU_VREF")
	)
	(segment
		(start 88.640412 -87.539576)
		(end 87.830152 -86.729316)
		(width 0.1524)
		(layer "B.Cu")
		(net "M_M_CPU_VREF")
	)
	(segment
		(start 68.223892 -86.233762)
		(end 67.694302 -86.233762)
		(width 0.1524)
		(layer "B.Cu")
		(net "M_M_CPU_VREF")
	)
	(segment
		(start 26.972768 -154.4828)
		(end 26.972768 -153.5684)
		(width 0.254)
		(layer "B.Cu")
		(net "M_M_CPU_VREF")
	)
	(segment
		(start 77.794866 -85.868764)
		(end 77.181456 -85.868764)
		(width 0.1524)
		(layer "B.Cu")
		(net "M_M_CPU_VREF")
	)
	(segment
		(start 76.443078 -86.233762)
		(end 76.07808 -85.868764)
		(width 0.1524)
		(layer "B.Cu")
		(net "M_M_CPU_VREF")
	)
	(segment
		(start 69.091302 -85.750146)
		(end 68.707508 -85.750146)
		(width 0.1524)
		(layer "B.Cu")
		(net "M_M_CPU_VREF")
	)
	(segment
		(start 82.582512 -85.868764)
		(end 82.086958 -85.37321)
		(width 0.1524)
		(layer "B.Cu")
		(net "M_M_CPU_VREF")
	)
	(segment
		(start 88.640412 -87.784686)
		(end 88.640412 -87.539576)
		(width 0.1524)
		(layer "B.Cu")
		(net "M_M_CPU_VREF")
	)
	(segment
		(start 67.31508 -85.85454)
		(end 66.425826 -85.85454)
		(width 0.1524)
		(layer "B.Cu")
		(net "M_M_CPU_VREF")
	)
	(segment
		(start 68.707508 -85.750146)
		(end 68.223892 -86.233762)
		(width 0.1524)
		(layer "B.Cu")
		(net "M_M_CPU_VREF")
	)
	(segment
		(start 70.821804 -85.868764)
		(end 70.433438 -85.868764)
		(width 0.1524)
		(layer "B.Cu")
		(net "M_M_CPU_VREF")
	)
	(segment
		(start 81.211674 -85.75548)
		(end 78.994762 -85.75548)
		(width 0.1524)
		(layer "B.Cu")
		(net "M_M_CPU_VREF")
	)
	(segment
		(start 82.80908 -85.868764)
		(end 82.582512 -85.868764)
		(width 0.1524)
		(layer "B.Cu")
		(net "M_M_CPU_VREF")
	)
	(segment
		(start 87.830152 -86.729316)
		(end 87.603584 -86.729316)
		(width 0.1524)
		(layer "B.Cu")
		(net "M_M_CPU_VREF")
	)
	(segment
		(start 75.461876 -85.868764)
		(end 75.096878 -86.233762)
		(width 0.1524)
		(layer "B.Cu")
		(net "M_M_CPU_VREF")
	)
	(segment
		(start 87.132668 -86.2584)
		(end 86.714076 -86.2584)
		(width 0.1524)
		(layer "B.Cu")
		(net "M_M_CPU_VREF")
	)
	(segment
		(start 72.013572 -85.868764)
		(end 71.648574 -86.233762)
		(width 0.1524)
		(layer "B.Cu")
		(net "M_M_CPU_VREF")
	)
	(segment
		(start 78.994762 -85.75548)
		(end 78.51648 -86.233762)
		(width 0.1524)
		(layer "B.Cu")
		(net "M_M_CPU_VREF")
	)
	(segment
		(start 62.704218 -91.375484)
		(end 61.787786 -92.291916)
		(width 0.254)
		(layer "B.Cu")
		(net "M_M_CPU_VREF")
	)
	(segment
		(start 71.186802 -86.233762)
		(end 70.821804 -85.868764)
		(width 0.1524)
		(layer "B.Cu")
		(net "M_M_CPU_VREF")
	)
	(segment
		(start 74.36104 -85.868764)
		(end 73.734676 -85.868764)
		(width 0.1524)
		(layer "B.Cu")
		(net "M_M_CPU_VREF")
	)
	(segment
		(start 44.350686 -103.113586)
		(end 45.389546 -104.152446)
		(width 0.254)
		(layer "B.Cu")
		(net "M_M_CPU_VREF")
	)
	(segment
		(start 78.51648 -86.233762)
		(end 78.159864 -86.233762)
		(width 0.1524)
		(layer "B.Cu")
		(net "M_M_CPU_VREF")
	)
	(segment
		(start 27.785568 -154.559)
		(end 26.896568 -154.559)
		(width 0.254)
		(layer "B.Cu")
		(net "M_M_CPU_VREF")
	)
	(segment
		(start 73.734676 -85.868764)
		(end 73.369678 -86.233762)
		(width 0.1524)
		(layer "B.Cu")
		(net "M_M_CPU_VREF")
	)
	(segment
		(start 84.52612 -85.868764)
		(end 84.169504 -85.868764)
		(width 0.1524)
		(layer "B.Cu")
		(net "M_M_CPU_VREF")
	)
	(segment
		(start 63.518034 -87.54364)
		(end 62.704218 -88.357456)
		(width 0.254)
		(layer "B.Cu")
		(net "M_M_CPU_VREF")
	)
	(segment
		(start 84.169504 -85.868764)
		(end 83.804506 -86.233762)
		(width 0.1524)
		(layer "B.Cu")
		(net "M_M_CPU_VREF")
	)
	(segment
		(start 71.648574 -86.233762)
		(end 71.186802 -86.233762)
		(width 0.1524)
		(layer "B.Cu")
		(net "M_M_CPU_VREF")
	)
	(segment
		(start 64.736726 -87.54364)
		(end 63.518034 -87.54364)
		(width 0.254)
		(layer "B.Cu")
		(net "M_M_CPU_VREF")
	)
	(segment
		(start 69.574918 -86.233762)
		(end 69.091302 -85.750146)
		(width 0.1524)
		(layer "B.Cu")
		(net "M_M_CPU_VREF")
	)
	(segment
		(start 76.07808 -85.868764)
		(end 75.461876 -85.868764)
		(width 0.1524)
		(layer "B.Cu")
		(net "M_M_CPU_VREF")
	)
	(segment
		(start 85.415628 -86.2584)
		(end 84.915756 -86.2584)
		(width 0.1524)
		(layer "B.Cu")
		(net "M_M_CPU_VREF")
	)
	(segment
		(start 72.546464 -85.868764)
		(end 72.013572 -85.868764)
		(width 0.1524)
		(layer "B.Cu")
		(net "M_M_CPU_VREF")
	)
	(segment
		(start 77.181456 -85.868764)
		(end 76.816458 -86.233762)
		(width 0.1524)
		(layer "B.Cu")
		(net "M_M_CPU_VREF")
	)
	(segment
		(start 86.24316 -86.729316)
		(end 85.886544 -86.729316)
		(width 0.1524)
		(layer "B.Cu")
		(net "M_M_CPU_VREF")
	)
	(segment
		(start 74.726038 -86.233762)
		(end 74.36104 -85.868764)
		(width 0.1524)
		(layer "B.Cu")
		(net "M_M_CPU_VREF")
	)
	(segment
		(start 83.174078 -86.233762)
		(end 82.80908 -85.868764)
		(width 0.1524)
		(layer "B.Cu")
		(net "M_M_CPU_VREF")
	)
	(segment
		(start 86.714076 -86.2584)
		(end 86.24316 -86.729316)
		(width 0.1524)
		(layer "B.Cu")
		(net "M_M_CPU_VREF")
	)
	(segment
		(start 85.886544 -86.729316)
		(end 85.415628 -86.2584)
		(width 0.1524)
		(layer "B.Cu")
		(net "M_M_CPU_VREF")
	)
	(segment
		(start 70.06844 -86.233762)
		(end 69.574918 -86.233762)
		(width 0.1524)
		(layer "B.Cu")
		(net "M_M_CPU_VREF")
	)
	(segment
		(start 28.051506 -152.489662)
		(end 26.972768 -153.5684)
		(width 0.254)
		(layer "In2.Cu")
		(net "M_M_CPU_VREF")
	)
	(segment
		(start 29.76372 -130.167634)
		(end 29.1973 -130.734054)
		(width 0.254)
		(layer "In2.Cu")
		(net "M_M_CPU_VREF")
	)
	(segment
		(start 28.555188 -136.562338)
		(end 28.555188 -143.056102)
		(width 0.254)
		(layer "In2.Cu")
		(net "M_M_CPU_VREF")
	)
	(segment
		(start 36.688522 -110.225078)
		(end 31.113222 -115.800378)
		(width 0.254)
		(layer "In2.Cu")
		(net "M_M_CPU_VREF")
	)
	(segment
		(start 28.051506 -143.559784)
		(end 28.051506 -152.489662)
		(width 0.254)
		(layer "In2.Cu")
		(net "M_M_CPU_VREF")
	)
	(segment
		(start 29.1973 -132.145532)
		(end 29.854398 -132.80263)
		(width 0.254)
		(layer "In2.Cu")
		(net "M_M_CPU_VREF")
	)
	(segment
		(start 31.113222 -127.878586)
		(end 29.76372 -129.228088)
		(width 0.254)
		(layer "In2.Cu")
		(net "M_M_CPU_VREF")
	)
	(segment
		(start 28.555188 -143.056102)
		(end 28.051506 -143.559784)
		(width 0.254)
		(layer "In2.Cu")
		(net "M_M_CPU_VREF")
	)
	(segment
		(start 44.350686 -103.909114)
		(end 38.034722 -110.225078)
		(width 0.254)
		(layer "In2.Cu")
		(net "M_M_CPU_VREF")
	)
	(segment
		(start 44.350686 -102.618286)
		(end 44.350686 -103.909114)
		(width 0.254)
		(layer "In2.Cu")
		(net "M_M_CPU_VREF")
	)
	(segment
		(start 31.113222 -115.800378)
		(end 31.113222 -127.878586)
		(width 0.254)
		(layer "In2.Cu")
		(net "M_M_CPU_VREF")
	)
	(segment
		(start 29.1973 -130.734054)
		(end 29.1973 -132.145532)
		(width 0.254)
		(layer "In2.Cu")
		(net "M_M_CPU_VREF")
	)
	(segment
		(start 29.76372 -129.228088)
		(end 29.76372 -130.167634)
		(width 0.254)
		(layer "In2.Cu")
		(net "M_M_CPU_VREF")
	)
	(segment
		(start 29.854398 -135.263128)
		(end 28.555188 -136.562338)
		(width 0.254)
		(layer "In2.Cu")
		(net "M_M_CPU_VREF")
	)
	(segment
		(start 38.034722 -110.225078)
		(end 36.688522 -110.225078)
		(width 0.254)
		(layer "In2.Cu")
		(net "M_M_CPU_VREF")
	)
	(segment
		(start 29.854398 -132.80263)
		(end 29.854398 -135.263128)
		(width 0.254)
		(layer "In2.Cu")
		(net "M_M_CPU_VREF")
	)
	(segment
		(start 30.549342 -146.070574)
		(end 30.452568 -145.9738)
		(width 0.4064)
		(layer "F.Cu")
		(net "M_L_VREF")
	)
	(segment
		(start 30.477968 -140.0556)
		(end 30.477968 -139.192)
		(width 0.4064)
		(layer "F.Cu")
		(net "M_L_VREF")
	)
	(segment
		(start 30.477968 -139.192)
		(end 30.452568 -139.1666)
		(width 0.4064)
		(layer "F.Cu")
		(net "M_L_VREF")
	)
	(segment
		(start 30.549342 -147.27174)
		(end 30.549342 -146.070574)
		(width 0.4064)
		(layer "F.Cu")
		(net "M_L_VREF")
	)
	(via
		(at 30.452568 -145.9738)
		(size 0.508)
		(drill 0.254)
		(layers "F.Cu" "B.Cu")
		(net "M_L_VREF")
	)
	(via
		(at 30.452568 -139.1666)
		(size 0.508)
		(drill 0.254)
		(layers "F.Cu" "B.Cu")
		(net "M_L_VREF")
	)
	(segment
		(start 30.452568 -145.9738)
		(end 30.27934 -145.9738)
		(width 0.4064)
		(layer "B.Cu")
		(net "M_L_VREF")
	)
	(segment
		(start 29.66974 -145.3642)
		(end 29.436568 -145.3642)
		(width 0.4064)
		(layer "B.Cu")
		(net "M_L_VREF")
	)
	(segment
		(start 30.452568 -144.977612)
		(end 30.452568 -145.9738)
		(width 0.4064)
		(layer "B.Cu")
		(net "M_L_VREF")
	)
	(segment
		(start 29.436568 -145.3642)
		(end 28.547568 -145.3642)
		(width 0.4064)
		(layer "B.Cu")
		(net "M_L_VREF")
	)
	(segment
		(start 30.27934 -145.9738)
		(end 29.66974 -145.3642)
		(width 0.4064)
		(layer "B.Cu")
		(net "M_L_VREF")
	)
	(segment
		(start 28.547568 -145.3642)
		(end 27.658568 -145.3642)
		(width 0.4064)
		(layer "B.Cu")
		(net "M_L_VREF")
	)
	(segment
		(start 30.549342 -139.069826)
		(end 30.452568 -139.1666)
		(width 0.381)
		(layer "B.Cu")
		(net "M_L_VREF")
	)
	(segment
		(start 30.549342 -137.877296)
		(end 30.549342 -139.069826)
		(width 0.381)
		(layer "B.Cu")
		(net "M_L_VREF")
	)
	(segment
		(start 29.1084 -142.4178)
		(end 29.8196 -143.129)
		(width 0.4064)
		(layer "In4.Cu")
		(net "M_L_VREF")
	)
	(segment
		(start 29.1084 -140.510768)
		(end 29.1084 -142.4178)
		(width 0.4064)
		(layer "In4.Cu")
		(net "M_L_VREF")
	)
	(segment
		(start 29.8196 -143.129)
		(end 29.8196 -145.340832)
		(width 0.4064)
		(layer "In4.Cu")
		(net "M_L_VREF")
	)
	(segment
		(start 30.452568 -139.1666)
		(end 29.1084 -140.510768)
		(width 0.4064)
		(layer "In4.Cu")
		(net "M_L_VREF")
	)
	(segment
		(start 29.8196 -145.340832)
		(end 30.452568 -145.9738)
		(width 0.4064)
		(layer "In4.Cu")
		(net "M_L_VREF")
	)
	(segment
		(start 89.211912 -86.794086)
		(end 88.640412 -86.794086)
		(width 0.1016)
		(layer "F.Cu")
		(net "M_L_CPU_VREF")
	)
	(via
		(at 45.133006 -102.643686)
		(size 0.508)
		(drill 0.254)
		(layers "F.Cu" "B.Cu")
		(net "M_L_CPU_VREF")
	)
	(via
		(at 88.640412 -86.794086)
		(size 0.508)
		(drill 0.254)
		(layers "F.Cu" "B.Cu")
		(net "M_L_CPU_VREF")
	)
	(via
		(at 61.90107 -90.016076)
		(size 0.6604)
		(drill 0.3302)
		(layers "F.Cu" "B.Cu")
		(net "M_L_CPU_VREF")
	)
	(via
		(at 26.769568 -143.764)
		(size 0.508)
		(drill 0.254)
		(layers "F.Cu" "B.Cu")
		(net "M_L_CPU_VREF")
	)
	(segment
		(start 63.1698 -86.70798)
		(end 64.39916 -86.70798)
		(width 0.254)
		(layer "B.Cu")
		(net "M_L_CPU_VREF")
	)
	(segment
		(start 70.799198 -84.7598)
		(end 71.28256 -85.243162)
		(width 0.1524)
		(layer "B.Cu")
		(net "M_L_CPU_VREF")
	)
	(segment
		(start 88.212168 -86.120732)
		(end 88.212168 -86.365842)
		(width 0.1524)
		(layer "B.Cu")
		(net "M_L_CPU_VREF")
	)
	(segment
		(start 73.730612 -84.878164)
		(end 74.281284 -84.878164)
		(width 0.1524)
		(layer "B.Cu")
		(net "M_L_CPU_VREF")
	)
	(segment
		(start 87.9602 -85.868764)
		(end 88.212168 -86.120732)
		(width 0.1524)
		(layer "B.Cu")
		(net "M_L_CPU_VREF")
	)
	(segment
		(start 69.107304 -84.878164)
		(end 69.472302 -85.243162)
		(width 0.1524)
		(layer "B.Cu")
		(net "M_L_CPU_VREF")
	)
	(segment
		(start 86.257384 -85.852)
		(end 86.736174 -85.37321)
		(width 0.1524)
		(layer "B.Cu")
		(net "M_L_CPU_VREF")
	)
	(segment
		(start 68.619116 -84.878164)
		(end 69.107304 -84.878164)
		(width 0.1524)
		(layer "B.Cu")
		(net "M_L_CPU_VREF")
	)
	(segment
		(start 85.148674 -85.37321)
		(end 85.38464 -85.37321)
		(width 0.1524)
		(layer "B.Cu")
		(net "M_L_CPU_VREF")
	)
	(segment
		(start 77.257656 -84.7852)
		(end 77.692758 -84.7852)
		(width 0.1524)
		(layer "B.Cu")
		(net "M_L_CPU_VREF")
	)
	(segment
		(start 61.90107 -91.10091)
		(end 49.611534 -103.390446)
		(width 0.254)
		(layer "B.Cu")
		(net "M_L_CPU_VREF")
	)
	(segment
		(start 49.611534 -103.390446)
		(end 45.879766 -103.390446)
		(width 0.254)
		(layer "B.Cu")
		(net "M_L_CPU_VREF")
	)
	(segment
		(start 69.472302 -85.243162)
		(end 69.931534 -85.243162)
		(width 0.1524)
		(layer "B.Cu")
		(net "M_L_CPU_VREF")
	)
	(segment
		(start 83.282282 -85.243162)
		(end 83.671918 -85.243162)
		(width 0.1524)
		(layer "B.Cu")
		(net "M_L_CPU_VREF")
	)
	(segment
		(start 84.547964 -84.7725)
		(end 85.148674 -85.37321)
		(width 0.1524)
		(layer "B.Cu")
		(net "M_L_CPU_VREF")
	)
	(segment
		(start 75.553316 -84.7725)
		(end 75.972416 -84.7725)
		(width 0.1524)
		(layer "B.Cu")
		(net "M_L_CPU_VREF")
	)
	(segment
		(start 84.14258 -84.7725)
		(end 84.547964 -84.7725)
		(width 0.1524)
		(layer "B.Cu")
		(net "M_L_CPU_VREF")
	)
	(segment
		(start 64.39916 -86.70798)
		(end 66.2432 -84.86394)
		(width 0.254)
		(layer "B.Cu")
		(net "M_L_CPU_VREF")
	)
	(segment
		(start 75.082654 -85.243162)
		(end 75.553316 -84.7725)
		(width 0.1524)
		(layer "B.Cu")
		(net "M_L_CPU_VREF")
	)
	(segment
		(start 45.879766 -103.390446)
		(end 45.133006 -102.643686)
		(width 0.254)
		(layer "B.Cu")
		(net "M_L_CPU_VREF")
	)
	(segment
		(start 76.443078 -85.243162)
		(end 76.799694 -85.243162)
		(width 0.1524)
		(layer "B.Cu")
		(net "M_L_CPU_VREF")
	)
	(segment
		(start 71.28256 -85.243162)
		(end 71.657972 -85.243162)
		(width 0.1524)
		(layer "B.Cu")
		(net "M_L_CPU_VREF")
	)
	(segment
		(start 72.141334 -84.7598)
		(end 72.516238 -84.7598)
		(width 0.1524)
		(layer "B.Cu")
		(net "M_L_CPU_VREF")
	)
	(segment
		(start 70.414896 -84.7598)
		(end 70.799198 -84.7598)
		(width 0.1524)
		(layer "B.Cu")
		(net "M_L_CPU_VREF")
	)
	(segment
		(start 61.90107 -90.016076)
		(end 61.90107 -91.10091)
		(width 0.254)
		(layer "B.Cu")
		(net "M_L_CPU_VREF")
	)
	(segment
		(start 85.86343 -85.852)
		(end 86.257384 -85.852)
		(width 0.1524)
		(layer "B.Cu")
		(net "M_L_CPU_VREF")
	)
	(segment
		(start 71.657972 -85.243162)
		(end 72.141334 -84.7598)
		(width 0.1524)
		(layer "B.Cu")
		(net "M_L_CPU_VREF")
	)
	(segment
		(start 81.585054 -84.38261)
		(end 81.95056 -84.38261)
		(width 0.1524)
		(layer "B.Cu")
		(net "M_L_CPU_VREF")
	)
	(segment
		(start 67.43954 -84.86394)
		(end 67.818762 -85.243162)
		(width 0.1524)
		(layer "B.Cu")
		(net "M_L_CPU_VREF")
	)
	(segment
		(start 86.736174 -85.37321)
		(end 87.10168 -85.37321)
		(width 0.1524)
		(layer "B.Cu")
		(net "M_L_CPU_VREF")
	)
	(segment
		(start 78.15072 -85.243162)
		(end 80.23352 -85.243162)
		(width 0.1524)
		(layer "B.Cu")
		(net "M_L_CPU_VREF")
	)
	(segment
		(start 80.615282 -84.8614)
		(end 81.106264 -84.8614)
		(width 0.1524)
		(layer "B.Cu")
		(net "M_L_CPU_VREF")
	)
	(segment
		(start 81.106264 -84.8614)
		(end 81.585054 -84.38261)
		(width 0.1524)
		(layer "B.Cu")
		(net "M_L_CPU_VREF")
	)
	(segment
		(start 77.692758 -84.7852)
		(end 78.15072 -85.243162)
		(width 0.1524)
		(layer "B.Cu")
		(net "M_L_CPU_VREF")
	)
	(segment
		(start 74.281284 -84.878164)
		(end 74.646282 -85.243162)
		(width 0.1524)
		(layer "B.Cu")
		(net "M_L_CPU_VREF")
	)
	(segment
		(start 61.90107 -90.016076)
		(end 61.90107 -87.97671)
		(width 0.254)
		(layer "B.Cu")
		(net "M_L_CPU_VREF")
	)
	(segment
		(start 72.516238 -84.7598)
		(end 72.9996 -85.243162)
		(width 0.1524)
		(layer "B.Cu")
		(net "M_L_CPU_VREF")
	)
	(segment
		(start 66.2432 -84.86394)
		(end 67.43954 -84.86394)
		(width 0.1524)
		(layer "B.Cu")
		(net "M_L_CPU_VREF")
	)
	(segment
		(start 83.671918 -85.243162)
		(end 84.14258 -84.7725)
		(width 0.1524)
		(layer "B.Cu")
		(net "M_L_CPU_VREF")
	)
	(segment
		(start 68.254118 -85.243162)
		(end 68.619116 -84.878164)
		(width 0.1524)
		(layer "B.Cu")
		(net "M_L_CPU_VREF")
	)
	(segment
		(start 73.365614 -85.243162)
		(end 73.730612 -84.878164)
		(width 0.1524)
		(layer "B.Cu")
		(net "M_L_CPU_VREF")
	)
	(segment
		(start 26.769568 -144.4752)
		(end 26.769568 -143.764)
		(width 0.254)
		(layer "B.Cu")
		(net "M_L_CPU_VREF")
	)
	(segment
		(start 80.23352 -85.243162)
		(end 80.615282 -84.8614)
		(width 0.1524)
		(layer "B.Cu")
		(net "M_L_CPU_VREF")
	)
	(segment
		(start 69.931534 -85.243162)
		(end 70.414896 -84.7598)
		(width 0.1524)
		(layer "B.Cu")
		(net "M_L_CPU_VREF")
	)
	(segment
		(start 82.88782 -84.8487)
		(end 83.282282 -85.243162)
		(width 0.1524)
		(layer "B.Cu")
		(net "M_L_CPU_VREF")
	)
	(segment
		(start 67.818762 -85.243162)
		(end 68.254118 -85.243162)
		(width 0.1524)
		(layer "B.Cu")
		(net "M_L_CPU_VREF")
	)
	(segment
		(start 74.646282 -85.243162)
		(end 75.082654 -85.243162)
		(width 0.1524)
		(layer "B.Cu")
		(net "M_L_CPU_VREF")
	)
	(segment
		(start 76.799694 -85.243162)
		(end 77.257656 -84.7852)
		(width 0.1524)
		(layer "B.Cu")
		(net "M_L_CPU_VREF")
	)
	(segment
		(start 81.95056 -84.38261)
		(end 82.41665 -84.8487)
		(width 0.1524)
		(layer "B.Cu")
		(net "M_L_CPU_VREF")
	)
	(segment
		(start 87.10168 -85.37321)
		(end 87.597234 -85.868764)
		(width 0.1524)
		(layer "B.Cu")
		(net "M_L_CPU_VREF")
	)
	(segment
		(start 27.658568 -144.4752)
		(end 26.769568 -144.4752)
		(width 0.254)
		(layer "B.Cu")
		(net "M_L_CPU_VREF")
	)
	(segment
		(start 82.41665 -84.8487)
		(end 82.88782 -84.8487)
		(width 0.1524)
		(layer "B.Cu")
		(net "M_L_CPU_VREF")
	)
	(segment
		(start 88.212168 -86.365842)
		(end 88.640412 -86.794086)
		(width 0.1524)
		(layer "B.Cu")
		(net "M_L_CPU_VREF")
	)
	(segment
		(start 75.972416 -84.7725)
		(end 76.443078 -85.243162)
		(width 0.1524)
		(layer "B.Cu")
		(net "M_L_CPU_VREF")
	)
	(segment
		(start 85.38464 -85.37321)
		(end 85.86343 -85.852)
		(width 0.1524)
		(layer "B.Cu")
		(net "M_L_CPU_VREF")
	)
	(segment
		(start 87.597234 -85.868764)
		(end 87.9602 -85.868764)
		(width 0.1524)
		(layer "B.Cu")
		(net "M_L_CPU_VREF")
	)
	(segment
		(start 61.90107 -87.97671)
		(end 63.1698 -86.70798)
		(width 0.254)
		(layer "B.Cu")
		(net "M_L_CPU_VREF")
	)
	(segment
		(start 72.9996 -85.243162)
		(end 73.365614 -85.243162)
		(width 0.1524)
		(layer "B.Cu")
		(net "M_L_CPU_VREF")
	)
	(segment
		(start 44.74464 -101.84384)
		(end 45.133006 -102.232206)
		(width 0.254)
		(layer "In2.Cu")
		(net "M_L_CPU_VREF")
	)
	(segment
		(start 30.351222 -126.982982)
		(end 30.351222 -115.484656)
		(width 0.254)
		(layer "In2.Cu")
		(net "M_L_CPU_VREF")
	)
	(segment
		(start 45.133006 -102.232206)
		(end 45.133006 -102.643686)
		(width 0.254)
		(layer "In2.Cu")
		(net "M_L_CPU_VREF")
	)
	(segment
		(start 43.369992 -103.801164)
		(end 43.369992 -102.205028)
		(width 0.254)
		(layer "In2.Cu")
		(net "M_L_CPU_VREF")
	)
	(segment
		(start 28.413456 -132.282438)
		(end 28.413456 -128.920748)
		(width 0.254)
		(layer "In2.Cu")
		(net "M_L_CPU_VREF")
	)
	(segment
		(start 43.369992 -102.205028)
		(end 43.73118 -101.84384)
		(width 0.254)
		(layer "In2.Cu")
		(net "M_L_CPU_VREF")
	)
	(segment
		(start 43.73118 -101.84384)
		(end 44.74464 -101.84384)
		(width 0.254)
		(layer "In2.Cu")
		(net "M_L_CPU_VREF")
	)
	(segment
		(start 27.793188 -142.74038)
		(end 27.793188 -132.902706)
		(width 0.254)
		(layer "In2.Cu")
		(net "M_L_CPU_VREF")
	)
	(segment
		(start 37.76726 -109.403896)
		(end 43.369992 -103.801164)
		(width 0.254)
		(layer "In2.Cu")
		(net "M_L_CPU_VREF")
	)
	(segment
		(start 30.351222 -115.484656)
		(end 36.431982 -109.403896)
		(width 0.254)
		(layer "In2.Cu")
		(net "M_L_CPU_VREF")
	)
	(segment
		(start 36.431982 -109.403896)
		(end 37.76726 -109.403896)
		(width 0.254)
		(layer "In2.Cu")
		(net "M_L_CPU_VREF")
	)
	(segment
		(start 26.769568 -143.764)
		(end 27.793188 -142.74038)
		(width 0.254)
		(layer "In2.Cu")
		(net "M_L_CPU_VREF")
	)
	(segment
		(start 28.413456 -128.920748)
		(end 30.351222 -126.982982)
		(width 0.254)
		(layer "In2.Cu")
		(net "M_L_CPU_VREF")
	)
	(segment
		(start 27.793188 -132.902706)
		(end 28.413456 -132.282438)
		(width 0.254)
		(layer "In2.Cu")
		(net "M_L_CPU_VREF")
	)
	(segment
		(start 30.549342 -136.490456)
		(end 30.452568 -136.393682)
		(width 0.4064)
		(layer "F.Cu")
		(net "M_K_VREF")
	)
	(segment
		(start 30.554168 -129.4638)
		(end 30.452568 -129.5654)
		(width 0.4064)
		(layer "F.Cu")
		(net "M_K_VREF")
	)
	(segment
		(start 30.549342 -137.67054)
		(end 30.549342 -136.490456)
		(width 0.4064)
		(layer "F.Cu")
		(net "M_K_VREF")
	)
	(segment
		(start 30.554168 -128.8542)
		(end 30.554168 -129.4638)
		(width 0.4064)
		(layer "F.Cu")
		(net "M_K_VREF")
	)
	(via
		(at 30.452568 -136.393682)
		(size 0.508)
		(drill 0.254)
		(layers "F.Cu" "B.Cu")
		(net "M_K_VREF")
	)
	(via
		(at 30.452568 -129.5654)
		(size 0.508)
		(drill 0.254)
		(layers "F.Cu" "B.Cu")
		(net "M_K_VREF")
	)
	(segment
		(start 29.821886 -135.763)
		(end 29.690568 -135.763)
		(width 0.4064)
		(layer "B.Cu")
		(net "M_K_VREF")
	)
	(segment
		(start 30.554168 -135.3312)
		(end 30.452568 -135.4328)
		(width 0.4064)
		(layer "B.Cu")
		(net "M_K_VREF")
	)
	(segment
		(start 30.452568 -136.393682)
		(end 29.821886 -135.763)
		(width 0.4064)
		(layer "B.Cu")
		(net "M_K_VREF")
	)
	(segment
		(start 27.912568 -135.763)
		(end 28.801568 -135.763)
		(width 0.4064)
		(layer "B.Cu")
		(net "M_K_VREF")
	)
	(segment
		(start 28.801568 -135.763)
		(end 29.690568 -135.763)
		(width 0.4064)
		(layer "B.Cu")
		(net "M_K_VREF")
	)
	(segment
		(start 30.549342 -128.276096)
		(end 30.549342 -129.468626)
		(width 0.381)
		(layer "B.Cu")
		(net "M_K_VREF")
	)
	(segment
		(start 30.549342 -129.468626)
		(end 30.452568 -129.5654)
		(width 0.381)
		(layer "B.Cu")
		(net "M_K_VREF")
	)
	(segment
		(start 30.452568 -135.4328)
		(end 30.452568 -136.393682)
		(width 0.4064)
		(layer "B.Cu")
		(net "M_K_VREF")
	)
	(segment
		(start 29.972 -133.6675)
		(end 29.972 -135.913114)
		(width 0.4064)
		(layer "In4.Cu")
		(net "M_K_VREF")
	)
	(segment
		(start 29.972 -135.913114)
		(end 30.452568 -136.393682)
		(width 0.4064)
		(layer "In4.Cu")
		(net "M_K_VREF")
	)
	(segment
		(start 28.828238 -131.18973)
		(end 28.828238 -132.523738)
		(width 0.4064)
		(layer "In4.Cu")
		(net "M_K_VREF")
	)
	(segment
		(start 28.828238 -132.523738)
		(end 29.972 -133.6675)
		(width 0.4064)
		(layer "In4.Cu")
		(net "M_K_VREF")
	)
	(segment
		(start 30.452568 -129.5654)
		(end 28.828238 -131.18973)
		(width 0.4064)
		(layer "In4.Cu")
		(net "M_K_VREF")
	)
	(segment
		(start 29.591 -2.877312)
		(end 29.897832 -2.877312)
		(width 0.4064)
		(layer "F.Cu")
		(net "M_J_VREF")
	)
	(segment
		(start 30.549342 -2.325878)
		(end 30.549342 -0.821182)
		(width 0.381)
		(layer "F.Cu")
		(net "M_J_VREF")
	)
	(segment
		(start 30.579568 -2.356104)
		(end 30.549342 -2.325878)
		(width 0.381)
		(layer "F.Cu")
		(net "M_J_VREF")
	)
	(segment
		(start 30.342332 -3.321812)
		(end 30.579568 -3.321812)
		(width 0.4064)
		(layer "F.Cu")
		(net "M_J_VREF")
	)
	(segment
		(start 29.897832 -2.877312)
		(end 30.342332 -3.321812)
		(width 0.4064)
		(layer "F.Cu")
		(net "M_J_VREF")
	)
	(segment
		(start 27.813 -2.877312)
		(end 28.702 -2.877312)
		(width 0.4064)
		(layer "F.Cu")
		(net "M_J_VREF")
	)
	(segment
		(start 30.579568 -3.321812)
		(end 30.579568 -2.356104)
		(width 0.381)
		(layer "F.Cu")
		(net "M_J_VREF")
	)
	(segment
		(start 28.702 -2.877312)
		(end 29.591 -2.877312)
		(width 0.4064)
		(layer "F.Cu")
		(net "M_J_VREF")
	)
	(via
		(at 30.549342 -2.325878)
		(size 0.508)
		(drill 0.254)
		(layers "F.Cu" "B.Cu")
		(net "M_J_VREF")
	)
	(segment
		(start 30.452568 1.524)
		(end 30.452568 0.539496)
		(width 0.381)
		(layer "B.Cu")
		(net "M_J_VREF")
	)
	(segment
		(start 30.549342 0.442722)
		(end 30.549342 -1.021842)
		(width 0.381)
		(layer "B.Cu")
		(net "M_J_VREF")
	)
	(segment
		(start 30.452568 0.539496)
		(end 30.549342 0.442722)
		(width 0.381)
		(layer "B.Cu")
		(net "M_J_VREF")
	)
	(segment
		(start 30.549342 -1.021842)
		(end 30.549342 -2.325878)
		(width 0.381)
		(layer "B.Cu")
		(net "M_J_VREF")
	)
	(segment
		(start 26.924 -3.766312)
		(end 26.924 -4.38404)
		(width 0.4064)
		(layer "F.Cu")
		(net "M_J_CPU_VREF")
	)
	(segment
		(start 27.813 -3.766312)
		(end 26.924 -3.766312)
		(width 0.4064)
		(layer "F.Cu")
		(net "M_J_CPU_VREF")
	)
	(segment
		(start 87.494872 -63.019686)
		(end 86.923372 -63.019686)
		(width 0.254)
		(layer "F.Cu")
		(net "M_J_CPU_VREF")
	)
	(via
		(at 86.923372 -63.019686)
		(size 0.508)
		(drill 0.254)
		(layers "F.Cu" "B.Cu")
		(net "M_J_CPU_VREF")
	)
	(via
		(at 29.5148 -17.878298)
		(size 0.508)
		(drill 0.254)
		(layers "F.Cu" "B.Cu")
		(net "M_J_CPU_VREF")
	)
	(via
		(at 26.924 -4.38404)
		(size 0.508)
		(drill 0.254)
		(layers "F.Cu" "B.Cu")
		(net "M_J_CPU_VREF")
	)
	(segment
		(start 29.5148 -17.878298)
		(end 29.591 -17.802098)
		(width 0.508)
		(layer "In2.Cu")
		(net "M_J_CPU_VREF")
	)
	(segment
		(start 29.591 -13.5382)
		(end 28.7274 -12.6746)
		(width 0.508)
		(layer "In2.Cu")
		(net "M_J_CPU_VREF")
	)
	(segment
		(start 27.07513 -4.38404)
		(end 26.924 -4.38404)
		(width 0.508)
		(layer "In2.Cu")
		(net "M_J_CPU_VREF")
	)
	(segment
		(start 28.7274 -6.03631)
		(end 27.07513 -4.38404)
		(width 0.508)
		(layer "In2.Cu")
		(net "M_J_CPU_VREF")
	)
	(segment
		(start 29.591 -17.802098)
		(end 29.591 -13.5382)
		(width 0.508)
		(layer "In2.Cu")
		(net "M_J_CPU_VREF")
	)
	(segment
		(start 28.7274 -12.6746)
		(end 28.7274 -6.03631)
		(width 0.508)
		(layer "In2.Cu")
		(net "M_J_CPU_VREF")
	)
	(segment
		(start 86.923372 -63.019686)
		(end 86.534498 -62.630812)
		(width 0.2286)
		(layer "In9.Cu")
		(net "M_J_CPU_VREF")
	)
	(segment
		(start 67.5386 -53.3654)
		(end 67.5386 -48.84674)
		(width 0.254)
		(layer "In9.Cu")
		(net "M_J_CPU_VREF")
	)
	(segment
		(start 83.958938 -58.862722)
		(end 83.632802 -58.536586)
		(width 0.2286)
		(layer "In9.Cu")
		(net "M_J_CPU_VREF")
	)
	(segment
		(start 80.524858 -56.305704)
		(end 80.524858 -55.890922)
		(width 0.2286)
		(layer "In9.Cu")
		(net "M_J_CPU_VREF")
	)
	(segment
		(start 83.878166 -59.358276)
		(end 83.958938 -59.277504)
		(width 0.2286)
		(layer "In9.Cu")
		(net "M_J_CPU_VREF")
	)
	(segment
		(start 68.326 -54.1528)
		(end 68.0339 -53.8607)
		(width 0.2286)
		(layer "In9.Cu")
		(net "M_J_CPU_VREF")
	)
	(segment
		(start 70.4342 -54.102)
		(end 69.9516 -53.6194)
		(width 0.2286)
		(layer "In9.Cu")
		(net "M_J_CPU_VREF")
	)
	(segment
		(start 80.524858 -55.890922)
		(end 80.198468 -55.564532)
		(width 0.2286)
		(layer "In9.Cu")
		(net "M_J_CPU_VREF")
	)
	(segment
		(start 79.339948 -55.069486)
		(end 79.002128 -55.069486)
		(width 0.2286)
		(layer "In9.Cu")
		(net "M_J_CPU_VREF")
	)
	(segment
		(start 86.534498 -62.330076)
		(end 86.208108 -62.003686)
		(width 0.2286)
		(layer "In9.Cu")
		(net "M_J_CPU_VREF")
	)
	(segment
		(start 75.931522 -53.088032)
		(end 75.613768 -53.088032)
		(width 0.2286)
		(layer "In9.Cu")
		(net "M_J_CPU_VREF")
	)
	(segment
		(start 29.85008 -20.01774)
		(end 28.9052 -19.07286)
		(width 0.254)
		(layer "In9.Cu")
		(net "M_J_CPU_VREF")
	)
	(segment
		(start 73.851262 -53.123338)
		(end 73.3806 -53.594)
		(width 0.2286)
		(layer "In9.Cu")
		(net "M_J_CPU_VREF")
	)
	(segment
		(start 85.595206 -61.313822)
		(end 85.675978 -61.23305)
		(width 0.2286)
		(layer "In9.Cu")
		(net "M_J_CPU_VREF")
	)
	(segment
		(start 74.727054 -53.6194)
		(end 74.195686 -53.088032)
		(width 0.2286)
		(layer "In9.Cu")
		(net "M_J_CPU_VREF")
	)
	(segment
		(start 47.094902 -28.403042)
		(end 46.969426 -28.350972)
		(width 0.254)
		(layer "In9.Cu")
		(net "M_J_CPU_VREF")
	)
	(segment
		(start 76.7715 -53.583332)
		(end 76.426822 -53.583332)
		(width 0.2286)
		(layer "In9.Cu")
		(net "M_J_CPU_VREF")
	)
	(segment
		(start 73.851262 -53.088032)
		(end 73.851262 -53.123338)
		(width 0.2286)
		(layer "In9.Cu")
		(net "M_J_CPU_VREF")
	)
	(segment
		(start 84.986114 -60.517532)
		(end 84.542376 -60.073794)
		(width 0.2286)
		(layer "In9.Cu")
		(net "M_J_CPU_VREF")
	)
	(segment
		(start 35.72256 -20.01774)
		(end 29.85008 -20.01774)
		(width 0.254)
		(layer "In9.Cu")
		(net "M_J_CPU_VREF")
	)
	(segment
		(start 36.68522 -20.9804)
		(end 35.72256 -20.01774)
		(width 0.254)
		(layer "In9.Cu")
		(net "M_J_CPU_VREF")
	)
	(segment
		(start 82.410808 -58.041286)
		(end 81.966816 -57.597294)
		(width 0.2286)
		(layer "In9.Cu")
		(net "M_J_CPU_VREF")
	)
	(segment
		(start 83.294728 -58.536586)
		(end 82.799428 -58.041286)
		(width 0.2286)
		(layer "In9.Cu")
		(net "M_J_CPU_VREF")
	)
	(segment
		(start 81.082642 -57.050686)
		(end 80.719168 -57.050686)
		(width 0.2286)
		(layer "In9.Cu")
		(net "M_J_CPU_VREF")
	)
	(segment
		(start 80.444086 -56.386476)
		(end 80.524858 -56.305704)
		(width 0.2286)
		(layer "In9.Cu")
		(net "M_J_CPU_VREF")
	)
	(segment
		(start 79.834994 -55.564532)
		(end 79.339948 -55.069486)
		(width 0.2286)
		(layer "In9.Cu")
		(net "M_J_CPU_VREF")
	)
	(segment
		(start 75.0824 -53.6194)
		(end 74.727054 -53.6194)
		(width 0.2286)
		(layer "In9.Cu")
		(net "M_J_CPU_VREF")
	)
	(segment
		(start 83.878166 -59.747404)
		(end 83.878166 -59.358276)
		(width 0.2286)
		(layer "In9.Cu")
		(net "M_J_CPU_VREF")
	)
	(segment
		(start 28.9052 -19.07286)
		(end 28.9052 -18.310098)
		(width 0.254)
		(layer "In9.Cu")
		(net "M_J_CPU_VREF")
	)
	(segment
		(start 82.799428 -58.041286)
		(end 82.410808 -58.041286)
		(width 0.2286)
		(layer "In9.Cu")
		(net "M_J_CPU_VREF")
	)
	(segment
		(start 77.318362 -54.130194)
		(end 76.7715 -53.583332)
		(width 0.2286)
		(layer "In9.Cu")
		(net "M_J_CPU_VREF")
	)
	(segment
		(start 37.165026 -24.289766)
		(end 36.68522 -23.80996)
		(width 0.254)
		(layer "In9.Cu")
		(net "M_J_CPU_VREF")
	)
	(segment
		(start 81.966816 -57.597294)
		(end 81.62925 -57.597294)
		(width 0.2286)
		(layer "In9.Cu")
		(net "M_J_CPU_VREF")
	)
	(segment
		(start 78.118208 -54.573932)
		(end 77.67447 -54.130194)
		(width 0.2286)
		(layer "In9.Cu")
		(net "M_J_CPU_VREF")
	)
	(segment
		(start 70.7898 -54.102)
		(end 70.4342 -54.102)
		(width 0.2286)
		(layer "In9.Cu")
		(net "M_J_CPU_VREF")
	)
	(segment
		(start 29.337 -17.878298)
		(end 29.5148 -17.878298)
		(width 0.254)
		(layer "In9.Cu")
		(net "M_J_CPU_VREF")
	)
	(segment
		(start 71.2724 -53.6194)
		(end 70.7898 -54.102)
		(width 0.2286)
		(layer "In9.Cu")
		(net "M_J_CPU_VREF")
	)
	(segment
		(start 67.5386 -48.84674)
		(end 47.094902 -28.403042)
		(width 0.254)
		(layer "In9.Cu")
		(net "M_J_CPU_VREF")
	)
	(segment
		(start 28.9052 -18.310098)
		(end 29.337 -17.878298)
		(width 0.254)
		(layer "In9.Cu")
		(net "M_J_CPU_VREF")
	)
	(segment
		(start 85.675978 -60.843922)
		(end 85.349588 -60.517532)
		(width 0.2286)
		(layer "In9.Cu")
		(net "M_J_CPU_VREF")
	)
	(segment
		(start 86.208108 -62.003686)
		(end 85.870288 -62.003686)
		(width 0.2286)
		(layer "In9.Cu")
		(net "M_J_CPU_VREF")
	)
	(segment
		(start 84.204556 -60.073794)
		(end 83.878166 -59.747404)
		(width 0.2286)
		(layer "In9.Cu")
		(net "M_J_CPU_VREF")
	)
	(segment
		(start 73.025 -53.594)
		(end 72.517 -54.102)
		(width 0.2286)
		(layer "In9.Cu")
		(net "M_J_CPU_VREF")
	)
	(segment
		(start 76.426822 -53.583332)
		(end 75.931522 -53.088032)
		(width 0.2286)
		(layer "In9.Cu")
		(net "M_J_CPU_VREF")
	)
	(segment
		(start 80.719168 -57.050686)
		(end 80.444086 -56.775604)
		(width 0.2286)
		(layer "In9.Cu")
		(net "M_J_CPU_VREF")
	)
	(segment
		(start 80.444086 -56.775604)
		(end 80.444086 -56.386476)
		(width 0.2286)
		(layer "In9.Cu")
		(net "M_J_CPU_VREF")
	)
	(segment
		(start 85.870288 -62.003686)
		(end 85.595206 -61.728604)
		(width 0.2286)
		(layer "In9.Cu")
		(net "M_J_CPU_VREF")
	)
	(segment
		(start 75.613768 -53.088032)
		(end 75.0824 -53.6194)
		(width 0.2286)
		(layer "In9.Cu")
		(net "M_J_CPU_VREF")
	)
	(segment
		(start 72.136 -54.102)
		(end 71.6534 -53.6194)
		(width 0.2286)
		(layer "In9.Cu")
		(net "M_J_CPU_VREF")
	)
	(segment
		(start 69.5706 -53.6194)
		(end 69.0372 -54.1528)
		(width 0.2286)
		(layer "In9.Cu")
		(net "M_J_CPU_VREF")
	)
	(segment
		(start 71.6534 -53.6194)
		(end 71.2724 -53.6194)
		(width 0.2286)
		(layer "In9.Cu")
		(net "M_J_CPU_VREF")
	)
	(segment
		(start 74.195686 -53.088032)
		(end 73.851262 -53.088032)
		(width 0.2286)
		(layer "In9.Cu")
		(net "M_J_CPU_VREF")
	)
	(segment
		(start 73.3806 -53.594)
		(end 73.025 -53.594)
		(width 0.2286)
		(layer "In9.Cu")
		(net "M_J_CPU_VREF")
	)
	(segment
		(start 69.0372 -54.1528)
		(end 68.326 -54.1528)
		(width 0.2286)
		(layer "In9.Cu")
		(net "M_J_CPU_VREF")
	)
	(segment
		(start 83.632802 -58.536586)
		(end 83.294728 -58.536586)
		(width 0.2286)
		(layer "In9.Cu")
		(net "M_J_CPU_VREF")
	)
	(segment
		(start 78.506574 -54.573932)
		(end 78.118208 -54.573932)
		(width 0.2286)
		(layer "In9.Cu")
		(net "M_J_CPU_VREF")
	)
	(segment
		(start 46.969426 -28.350972)
		(end 37.165026 -24.289766)
		(width 0.254)
		(layer "In9.Cu")
		(net "M_J_CPU_VREF")
	)
	(segment
		(start 79.002128 -55.069486)
		(end 78.506574 -54.573932)
		(width 0.2286)
		(layer "In9.Cu")
		(net "M_J_CPU_VREF")
	)
	(segment
		(start 80.198468 -55.564532)
		(end 79.834994 -55.564532)
		(width 0.2286)
		(layer "In9.Cu")
		(net "M_J_CPU_VREF")
	)
	(segment
		(start 36.68522 -23.80996)
		(end 36.68522 -20.9804)
		(width 0.254)
		(layer "In9.Cu")
		(net "M_J_CPU_VREF")
	)
	(segment
		(start 83.958938 -59.277504)
		(end 83.958938 -58.862722)
		(width 0.2286)
		(layer "In9.Cu")
		(net "M_J_CPU_VREF")
	)
	(segment
		(start 81.62925 -57.597294)
		(end 81.082642 -57.050686)
		(width 0.2286)
		(layer "In9.Cu")
		(net "M_J_CPU_VREF")
	)
	(segment
		(start 69.9516 -53.6194)
		(end 69.5706 -53.6194)
		(width 0.2286)
		(layer "In9.Cu")
		(net "M_J_CPU_VREF")
	)
	(segment
		(start 84.542376 -60.073794)
		(end 84.204556 -60.073794)
		(width 0.2286)
		(layer "In9.Cu")
		(net "M_J_CPU_VREF")
	)
	(segment
		(start 85.595206 -61.728604)
		(end 85.595206 -61.313822)
		(width 0.2286)
		(layer "In9.Cu")
		(net "M_J_CPU_VREF")
	)
	(segment
		(start 68.0339 -53.8607)
		(end 67.5386 -53.3654)
		(width 0.254)
		(layer "In9.Cu")
		(net "M_J_CPU_VREF")
	)
	(segment
		(start 85.349588 -60.517532)
		(end 84.986114 -60.517532)
		(width 0.2286)
		(layer "In9.Cu")
		(net "M_J_CPU_VREF")
	)
	(segment
		(start 85.675978 -61.23305)
		(end 85.675978 -60.843922)
		(width 0.2286)
		(layer "In9.Cu")
		(net "M_J_CPU_VREF")
	)
	(segment
		(start 72.517 -54.102)
		(end 72.136 -54.102)
		(width 0.2286)
		(layer "In9.Cu")
		(net "M_J_CPU_VREF")
	)
	(segment
		(start 86.534498 -62.630812)
		(end 86.534498 -62.330076)
		(width 0.2286)
		(layer "In9.Cu")
		(net "M_J_CPU_VREF")
	)
	(segment
		(start 77.67447 -54.130194)
		(end 77.318362 -54.130194)
		(width 0.2286)
		(layer "In9.Cu")
		(net "M_J_CPU_VREF")
	)
	(segment
		(start 27.810968 -12.4841)
		(end 27.785568 -12.5095)
		(width 0.4064)
		(layer "F.Cu")
		(net "M_H_VREF")
	)
	(segment
		(start 30.579568 -12.923012)
		(end 30.210252 -12.923012)
		(width 0.4064)
		(layer "F.Cu")
		(net "M_H_VREF")
	)
	(segment
		(start 30.549342 -11.927078)
		(end 30.579568 -11.957304)
		(width 0.381)
		(layer "F.Cu")
		(net "M_H_VREF")
	)
	(segment
		(start 30.210252 -12.923012)
		(end 29.77134 -12.4841)
		(width 0.4064)
		(layer "F.Cu")
		(net "M_H_VREF")
	)
	(segment
		(start 29.77134 -12.4841)
		(end 29.464 -12.4841)
		(width 0.4064)
		(layer "F.Cu")
		(net "M_H_VREF")
	)
	(segment
		(start 28.575 -12.4841)
		(end 27.810968 -12.4841)
		(width 0.4064)
		(layer "F.Cu")
		(net "M_H_VREF")
	)
	(segment
		(start 30.579568 -11.957304)
		(end 30.579568 -12.923012)
		(width 0.381)
		(layer "F.Cu")
		(net "M_H_VREF")
	)
	(segment
		(start 30.549342 -11.927078)
		(end 30.549342 -10.422382)
		(width 0.381)
		(layer "F.Cu")
		(net "M_H_VREF")
	)
	(segment
		(start 29.464 -12.4841)
		(end 28.575 -12.4841)
		(width 0.4064)
		(layer "F.Cu")
		(net "M_H_VREF")
	)
	(via
		(at 30.549342 -11.927078)
		(size 0.508)
		(drill 0.254)
		(layers "F.Cu" "B.Cu")
		(net "M_H_VREF")
	)
	(segment
		(start 30.549342 -11.927078)
		(end 30.549342 -10.623042)
		(width 0.381)
		(layer "B.Cu")
		(net "M_H_VREF")
	)
	(segment
		(start 30.452568 -9.061704)
		(end 30.452568 -8.122412)
		(width 0.381)
		(layer "B.Cu")
		(net "M_H_VREF")
	)
	(segment
		(start 30.549342 -10.623042)
		(end 30.549342 -9.158478)
		(width 0.381)
		(layer "B.Cu")
		(net "M_H_VREF")
	)
	(segment
		(start 30.549342 -9.158478)
		(end 30.452568 -9.061704)
		(width 0.381)
		(layer "B.Cu")
		(net "M_H_VREF")
	)
	(segment
		(start 87.494872 -64.010286)
		(end 86.923372 -64.010286)
		(width 0.254)
		(layer "F.Cu")
		(net "M_H_CPU_VREF")
	)
	(segment
		(start 26.898092 -14.019276)
		(end 26.898092 -13.3985)
		(width 0.4064)
		(layer "F.Cu")
		(net "M_H_CPU_VREF")
	)
	(segment
		(start 26.898092 -13.3985)
		(end 27.785568 -13.3985)
		(width 0.4064)
		(layer "F.Cu")
		(net "M_H_CPU_VREF")
	)
	(via
		(at 86.923372 -64.010286)
		(size 0.508)
		(drill 0.254)
		(layers "F.Cu" "B.Cu")
		(net "M_H_CPU_VREF")
	)
	(via
		(at 26.898092 -14.019276)
		(size 0.508)
		(drill 0.254)
		(layers "F.Cu" "B.Cu")
		(net "M_H_CPU_VREF")
	)
	(segment
		(start 75.931776 -54.078886)
		(end 76.426822 -54.573932)
		(width 0.2286)
		(layer "In9.Cu")
		(net "M_H_CPU_VREF")
	)
	(segment
		(start 77.67447 -55.120794)
		(end 78.118208 -55.564532)
		(width 0.2286)
		(layer "In9.Cu")
		(net "M_H_CPU_VREF")
	)
	(segment
		(start 29.18714 -20.78228)
		(end 35.07486 -20.78228)
		(width 0.254)
		(layer "In9.Cu")
		(net "M_H_CPU_VREF")
	)
	(segment
		(start 79.585566 -57.27065)
		(end 79.91221 -57.597294)
		(width 0.2286)
		(layer "In9.Cu")
		(net "M_H_CPU_VREF")
	)
	(segment
		(start 79.585566 -56.856376)
		(end 79.585566 -57.27065)
		(width 0.2286)
		(layer "In9.Cu")
		(net "M_H_CPU_VREF")
	)
	(segment
		(start 86.259416 -63.045594)
		(end 86.923118 -63.709296)
		(width 0.2286)
		(layer "In9.Cu")
		(net "M_H_CPU_VREF")
	)
	(segment
		(start 77.311504 -55.120794)
		(end 77.67447 -55.120794)
		(width 0.2286)
		(layer "In9.Cu")
		(net "M_H_CPU_VREF")
	)
	(segment
		(start 69.9262 -54.5846)
		(end 70.4342 -55.0926)
		(width 0.2286)
		(layer "In9.Cu")
		(net "M_H_CPU_VREF")
	)
	(segment
		(start 81.628742 -58.58764)
		(end 81.966816 -58.58764)
		(width 0.2286)
		(layer "In9.Cu")
		(net "M_H_CPU_VREF")
	)
	(segment
		(start 66.58102 -48.99152)
		(end 66.58102 -53.06822)
		(width 0.254)
		(layer "In9.Cu")
		(net "M_H_CPU_VREF")
	)
	(segment
		(start 36.449254 -25.032208)
		(end 46.985936 -29.396436)
		(width 0.254)
		(layer "In9.Cu")
		(net "M_H_CPU_VREF")
	)
	(segment
		(start 73.851262 -54.078886)
		(end 74.195432 -54.078886)
		(width 0.2286)
		(layer "In9.Cu")
		(net "M_H_CPU_VREF")
	)
	(segment
		(start 79.666338 -56.775604)
		(end 79.585566 -56.856376)
		(width 0.2286)
		(layer "In9.Cu")
		(net "M_H_CPU_VREF")
	)
	(segment
		(start 78.506574 -55.564532)
		(end 79.053436 -56.111394)
		(width 0.2286)
		(layer "In9.Cu")
		(net "M_H_CPU_VREF")
	)
	(segment
		(start 68.0974 -54.5846)
		(end 69.9262 -54.5846)
		(width 0.2286)
		(layer "In9.Cu")
		(net "M_H_CPU_VREF")
	)
	(segment
		(start 46.985936 -29.396436)
		(end 66.58102 -48.99152)
		(width 0.254)
		(layer "In9.Cu")
		(net "M_H_CPU_VREF")
	)
	(segment
		(start 80.249776 -57.597294)
		(end 80.693768 -58.041286)
		(width 0.2286)
		(layer "In9.Cu")
		(net "M_H_CPU_VREF")
	)
	(segment
		(start 27.9908 -19.58594)
		(end 29.18714 -20.78228)
		(width 0.254)
		(layer "In9.Cu")
		(net "M_H_CPU_VREF")
	)
	(segment
		(start 85.400896 -62.55004)
		(end 85.89645 -63.045594)
		(width 0.2286)
		(layer "In9.Cu")
		(net "M_H_CPU_VREF")
	)
	(segment
		(start 71.2978 -54.5846)
		(end 71.628 -54.5846)
		(width 0.2286)
		(layer "In9.Cu")
		(net "M_H_CPU_VREF")
	)
	(segment
		(start 73.851262 -54.113938)
		(end 73.851262 -54.078886)
		(width 0.2286)
		(layer "In9.Cu")
		(net "M_H_CPU_VREF")
	)
	(segment
		(start 80.693768 -58.041286)
		(end 81.082388 -58.041286)
		(width 0.2286)
		(layer "In9.Cu")
		(net "M_H_CPU_VREF")
	)
	(segment
		(start 35.32886 -21.03628)
		(end 35.32886 -23.911814)
		(width 0.254)
		(layer "In9.Cu")
		(net "M_H_CPU_VREF")
	)
	(segment
		(start 83.019646 -60.24245)
		(end 83.294728 -60.517532)
		(width 0.2286)
		(layer "In9.Cu")
		(net "M_H_CPU_VREF")
	)
	(segment
		(start 83.100418 -59.358276)
		(end 83.100418 -59.772296)
		(width 0.2286)
		(layer "In9.Cu")
		(net "M_H_CPU_VREF")
	)
	(segment
		(start 35.07486 -20.78228)
		(end 35.32886 -21.03628)
		(width 0.254)
		(layer "In9.Cu")
		(net "M_H_CPU_VREF")
	)
	(segment
		(start 79.91221 -57.597294)
		(end 80.249776 -57.597294)
		(width 0.2286)
		(layer "In9.Cu")
		(net "M_H_CPU_VREF")
	)
	(segment
		(start 86.923118 -64.010032)
		(end 86.923372 -64.010286)
		(width 0.2286)
		(layer "In9.Cu")
		(net "M_H_CPU_VREF")
	)
	(segment
		(start 72.517 -55.0926)
		(end 72.9996 -54.61)
		(width 0.2286)
		(layer "In9.Cu")
		(net "M_H_CPU_VREF")
	)
	(segment
		(start 84.542376 -61.064394)
		(end 84.817458 -61.339476)
		(width 0.2286)
		(layer "In9.Cu")
		(net "M_H_CPU_VREF")
	)
	(segment
		(start 66.58102 -53.06822)
		(end 67.818 -54.3052)
		(width 0.254)
		(layer "In9.Cu")
		(net "M_H_CPU_VREF")
	)
	(segment
		(start 76.426822 -54.573932)
		(end 76.764642 -54.573932)
		(width 0.2286)
		(layer "In9.Cu")
		(net "M_H_CPU_VREF")
	)
	(segment
		(start 84.817458 -61.339476)
		(end 84.817458 -61.75375)
		(width 0.2286)
		(layer "In9.Cu")
		(net "M_H_CPU_VREF")
	)
	(segment
		(start 79.666338 -56.386476)
		(end 79.666338 -56.775604)
		(width 0.2286)
		(layer "In9.Cu")
		(net "M_H_CPU_VREF")
	)
	(segment
		(start 76.764642 -54.573932)
		(end 77.311504 -55.120794)
		(width 0.2286)
		(layer "In9.Cu")
		(net "M_H_CPU_VREF")
	)
	(segment
		(start 67.818 -54.3052)
		(end 68.0974 -54.5846)
		(width 0.2286)
		(layer "In9.Cu")
		(net "M_H_CPU_VREF")
	)
	(segment
		(start 79.391256 -56.111394)
		(end 79.666338 -56.386476)
		(width 0.2286)
		(layer "In9.Cu")
		(net "M_H_CPU_VREF")
	)
	(segment
		(start 27.120596 -14.019276)
		(end 27.9908 -14.88948)
		(width 0.254)
		(layer "In9.Cu")
		(net "M_H_CPU_VREF")
	)
	(segment
		(start 85.89645 -63.045594)
		(end 86.259416 -63.045594)
		(width 0.2286)
		(layer "In9.Cu")
		(net "M_H_CPU_VREF")
	)
	(segment
		(start 83.294728 -60.517532)
		(end 83.657694 -60.517532)
		(width 0.2286)
		(layer "In9.Cu")
		(net "M_H_CPU_VREF")
	)
	(segment
		(start 84.736686 -61.834522)
		(end 84.736686 -62.22365)
		(width 0.2286)
		(layer "In9.Cu")
		(net "M_H_CPU_VREF")
	)
	(segment
		(start 82.825336 -59.083194)
		(end 83.100418 -59.358276)
		(width 0.2286)
		(layer "In9.Cu")
		(net "M_H_CPU_VREF")
	)
	(segment
		(start 72.9996 -54.61)
		(end 73.3552 -54.61)
		(width 0.2286)
		(layer "In9.Cu")
		(net "M_H_CPU_VREF")
	)
	(segment
		(start 71.628 -54.5846)
		(end 72.136 -55.0926)
		(width 0.2286)
		(layer "In9.Cu")
		(net "M_H_CPU_VREF")
	)
	(segment
		(start 86.923118 -63.709296)
		(end 86.923118 -64.010032)
		(width 0.2286)
		(layer "In9.Cu")
		(net "M_H_CPU_VREF")
	)
	(segment
		(start 78.118208 -55.564532)
		(end 78.506574 -55.564532)
		(width 0.2286)
		(layer "In9.Cu")
		(net "M_H_CPU_VREF")
	)
	(segment
		(start 82.46237 -59.083194)
		(end 82.825336 -59.083194)
		(width 0.2286)
		(layer "In9.Cu")
		(net "M_H_CPU_VREF")
	)
	(segment
		(start 83.657694 -60.517532)
		(end 84.204556 -61.064394)
		(width 0.2286)
		(layer "In9.Cu")
		(net "M_H_CPU_VREF")
	)
	(segment
		(start 73.3552 -54.61)
		(end 73.851262 -54.113938)
		(width 0.2286)
		(layer "In9.Cu")
		(net "M_H_CPU_VREF")
	)
	(segment
		(start 72.136 -55.0926)
		(end 72.517 -55.0926)
		(width 0.2286)
		(layer "In9.Cu")
		(net "M_H_CPU_VREF")
	)
	(segment
		(start 35.32886 -23.911814)
		(end 36.449254 -25.032208)
		(width 0.254)
		(layer "In9.Cu")
		(net "M_H_CPU_VREF")
	)
	(segment
		(start 83.100418 -59.772296)
		(end 83.019646 -59.853322)
		(width 0.2286)
		(layer "In9.Cu")
		(net "M_H_CPU_VREF")
	)
	(segment
		(start 79.053436 -56.111394)
		(end 79.391256 -56.111394)
		(width 0.2286)
		(layer "In9.Cu")
		(net "M_H_CPU_VREF")
	)
	(segment
		(start 74.195432 -54.078886)
		(end 74.726546 -54.61)
		(width 0.2286)
		(layer "In9.Cu")
		(net "M_H_CPU_VREF")
	)
	(segment
		(start 83.019646 -59.853322)
		(end 83.019646 -60.24245)
		(width 0.2286)
		(layer "In9.Cu")
		(net "M_H_CPU_VREF")
	)
	(segment
		(start 70.7898 -55.0926)
		(end 71.2978 -54.5846)
		(width 0.2286)
		(layer "In9.Cu")
		(net "M_H_CPU_VREF")
	)
	(segment
		(start 81.966816 -58.58764)
		(end 82.46237 -59.083194)
		(width 0.2286)
		(layer "In9.Cu")
		(net "M_H_CPU_VREF")
	)
	(segment
		(start 84.736686 -62.22365)
		(end 85.063076 -62.55004)
		(width 0.2286)
		(layer "In9.Cu")
		(net "M_H_CPU_VREF")
	)
	(segment
		(start 70.4342 -55.0926)
		(end 70.7898 -55.0926)
		(width 0.2286)
		(layer "In9.Cu")
		(net "M_H_CPU_VREF")
	)
	(segment
		(start 75.0824 -54.61)
		(end 75.613514 -54.078886)
		(width 0.2286)
		(layer "In9.Cu")
		(net "M_H_CPU_VREF")
	)
	(segment
		(start 84.817458 -61.75375)
		(end 84.736686 -61.834522)
		(width 0.2286)
		(layer "In9.Cu")
		(net "M_H_CPU_VREF")
	)
	(segment
		(start 74.726546 -54.61)
		(end 75.0824 -54.61)
		(width 0.2286)
		(layer "In9.Cu")
		(net "M_H_CPU_VREF")
	)
	(segment
		(start 26.898092 -14.019276)
		(end 27.120596 -14.019276)
		(width 0.254)
		(layer "In9.Cu")
		(net "M_H_CPU_VREF")
	)
	(segment
		(start 81.082388 -58.041286)
		(end 81.628742 -58.58764)
		(width 0.2286)
		(layer "In9.Cu")
		(net "M_H_CPU_VREF")
	)
	(segment
		(start 85.063076 -62.55004)
		(end 85.400896 -62.55004)
		(width 0.2286)
		(layer "In9.Cu")
		(net "M_H_CPU_VREF")
	)
	(segment
		(start 27.9908 -14.88948)
		(end 27.9908 -19.58594)
		(width 0.254)
		(layer "In9.Cu")
		(net "M_H_CPU_VREF")
	)
	(segment
		(start 84.204556 -61.064394)
		(end 84.542376 -61.064394)
		(width 0.2286)
		(layer "In9.Cu")
		(net "M_H_CPU_VREF")
	)
	(segment
		(start 75.613514 -54.078886)
		(end 75.931776 -54.078886)
		(width 0.2286)
		(layer "In9.Cu")
		(net "M_H_CPU_VREF")
	)
	(segment
		(start 29.807916 -22.105366)
		(end 29.028136 -22.105366)
		(width 0.4064)
		(layer "F.Cu")
		(net "M_G_VREF")
	)
	(segment
		(start 29.028136 -22.105366)
		(end 28.975304 -22.052534)
		(width 0.4064)
		(layer "F.Cu")
		(net "M_G_VREF")
	)
	(segment
		(start 30.579568 -22.157182)
		(end 30.583378 -22.160992)
		(width 0.4064)
		(layer "F.Cu")
		(net "M_G_VREF")
	)
	(segment
		(start 30.527752 -22.105366)
		(end 30.579568 -22.157182)
		(width 0.4064)
		(layer "F.Cu")
		(net "M_G_VREF")
	)
	(segment
		(start 28.975304 -22.052534)
		(end 28.242006 -22.052534)
		(width 0.4064)
		(layer "F.Cu")
		(net "M_G_VREF")
	)
	(segment
		(start 30.579568 -21.6408)
		(end 30.579568 -22.157182)
		(width 0.381)
		(layer "F.Cu")
		(net "M_G_VREF")
	)
	(segment
		(start 30.549342 -21.417026)
		(end 30.549342 -20.023582)
		(width 0.381)
		(layer "F.Cu")
		(net "M_G_VREF")
	)
	(segment
		(start 30.452568 -21.5138)
		(end 30.579568 -21.6408)
		(width 0.381)
		(layer "F.Cu")
		(net "M_G_VREF")
	)
	(segment
		(start 30.452568 -21.5138)
		(end 30.549342 -21.417026)
		(width 0.381)
		(layer "F.Cu")
		(net "M_G_VREF")
	)
	(segment
		(start 29.807916 -22.105366)
		(end 30.527752 -22.105366)
		(width 0.4064)
		(layer "F.Cu")
		(net "M_G_VREF")
	)
	(via
		(at 30.452568 -21.5138)
		(size 0.508)
		(drill 0.254)
		(layers "F.Cu" "B.Cu")
		(net "M_G_VREF")
	)
	(segment
		(start 30.452568 -21.5138)
		(end 30.549342 -21.417026)
		(width 0.381)
		(layer "B.Cu")
		(net "M_G_VREF")
	)
	(segment
		(start 30.549342 -21.417026)
		(end 30.549342 -20.224242)
		(width 0.381)
		(layer "B.Cu")
		(net "M_G_VREF")
	)
	(segment
		(start 30.549342 -18.841974)
		(end 30.452568 -18.7452)
		(width 0.381)
		(layer "B.Cu")
		(net "M_G_VREF")
	)
	(segment
		(start 30.452568 -18.7452)
		(end 30.452568 -17.723612)
		(width 0.381)
		(layer "B.Cu")
		(net "M_G_VREF")
	)
	(segment
		(start 30.549342 -20.224242)
		(end 30.549342 -18.841974)
		(width 0.381)
		(layer "B.Cu")
		(net "M_G_VREF")
	)
	(segment
		(start 195.549774 -155.692856)
		(end 195.453 -155.596082)
		(width 0.4064)
		(layer "F.Cu")
		(net "M_F_VREF")
	)
	(segment
		(start 195.549774 -156.87294)
		(end 195.549774 -155.692856)
		(width 0.4064)
		(layer "F.Cu")
		(net "M_F_VREF")
	)
	(segment
		(start 195.5292 -149.6568)
		(end 195.5292 -148.844)
		(width 0.4064)
		(layer "F.Cu")
		(net "M_F_VREF")
	)
	(segment
		(start 195.550282 -156.87294)
		(end 195.549774 -156.87294)
		(width 0.4064)
		(layer "F.Cu")
		(net "M_F_VREF")
	)
	(segment
		(start 195.5292 -148.844)
		(end 195.453 -148.7678)
		(width 0.4064)
		(layer "F.Cu")
		(net "M_F_VREF")
	)
	(via
		(at 195.453 -148.7678)
		(size 0.508)
		(drill 0.254)
		(layers "F.Cu" "B.Cu")
		(net "M_F_VREF")
	)
	(via
		(at 195.453 -155.596082)
		(size 0.508)
		(drill 0.254)
		(layers "F.Cu" "B.Cu")
		(net "M_F_VREF")
	)
	(segment
		(start 194.564 -155.448)
		(end 193.675 -155.448)
		(width 0.4064)
		(layer "B.Cu")
		(net "M_F_VREF")
	)
	(segment
		(start 195.549774 -148.671026)
		(end 195.453 -148.7678)
		(width 0.4064)
		(layer "B.Cu")
		(net "M_F_VREF")
	)
	(segment
		(start 195.550282 -147.478496)
		(end 195.549774 -147.478496)
		(width 0.4064)
		(layer "B.Cu")
		(net "M_F_VREF")
	)
	(segment
		(start 195.453 -154.6352)
		(end 195.453 -155.596082)
		(width 0.4064)
		(layer "B.Cu")
		(net "M_F_VREF")
	)
	(segment
		(start 193.675 -155.448)
		(end 192.786 -155.448)
		(width 0.4064)
		(layer "B.Cu")
		(net "M_F_VREF")
	)
	(segment
		(start 195.304918 -155.448)
		(end 194.564 -155.448)
		(width 0.254)
		(layer "B.Cu")
		(net "M_F_VREF")
	)
	(segment
		(start 195.549774 -147.478496)
		(end 195.549774 -148.671026)
		(width 0.4064)
		(layer "B.Cu")
		(net "M_F_VREF")
	)
	(segment
		(start 195.453 -155.596082)
		(end 195.304918 -155.448)
		(width 0.4064)
		(layer "B.Cu")
		(net "M_F_VREF")
	)
	(segment
		(start 194.945 -151.8793)
		(end 194.945 -154.0256)
		(width 0.4064)
		(layer "In2.Cu")
		(net "M_F_VREF")
	)
	(segment
		(start 194.945 -154.0256)
		(end 195.453 -154.5336)
		(width 0.4064)
		(layer "In2.Cu")
		(net "M_F_VREF")
	)
	(segment
		(start 195.453 -148.7678)
		(end 195.453 -151.3713)
		(width 0.4064)
		(layer "In2.Cu")
		(net "M_F_VREF")
	)
	(segment
		(start 195.453 -154.5336)
		(end 195.453 -155.596082)
		(width 0.4064)
		(layer "In2.Cu")
		(net "M_F_VREF")
	)
	(segment
		(start 195.453 -151.3713)
		(end 194.945 -151.8793)
		(width 0.4064)
		(layer "In2.Cu")
		(net "M_F_VREF")
	)
	(segment
		(start 254.212344 -87.784686)
		(end 253.640844 -87.784686)
		(width 0.1016)
		(layer "F.Cu")
		(net "M_F_CPU_VREF")
	)
	(via
		(at 191.9732 -153.5684)
		(size 0.508)
		(drill 0.254)
		(layers "F.Cu" "B.Cu")
		(net "M_F_CPU_VREF")
	)
	(via
		(at 211.4042 -102.327202)
		(size 0.508)
		(drill 0.254)
		(layers "F.Cu" "B.Cu")
		(net "M_F_CPU_VREF")
	)
	(via
		(at 253.640844 -87.784686)
		(size 0.508)
		(drill 0.254)
		(layers "F.Cu" "B.Cu")
		(net "M_F_CPU_VREF")
	)
	(segment
		(start 191.897 -154.559)
		(end 191.9732 -154.4828)
		(width 0.254)
		(layer "B.Cu")
		(net "M_F_CPU_VREF")
	)
	(segment
		(start 191.9732 -154.4828)
		(end 191.9732 -153.5684)
		(width 0.254)
		(layer "B.Cu")
		(net "M_F_CPU_VREF")
	)
	(segment
		(start 192.786 -154.559)
		(end 191.897 -154.559)
		(width 0.254)
		(layer "B.Cu")
		(net "M_F_CPU_VREF")
	)
	(segment
		(start 193.0654 -152.2984)
		(end 191.9732 -153.3906)
		(width 0.254)
		(layer "In2.Cu")
		(net "M_F_CPU_VREF")
	)
	(segment
		(start 202.829922 -110.5662)
		(end 201.3458 -110.5662)
		(width 0.254)
		(layer "In2.Cu")
		(net "M_F_CPU_VREF")
	)
	(segment
		(start 193.31686 -132.258816)
		(end 193.31686 -138.096244)
		(width 0.254)
		(layer "In2.Cu")
		(net "M_F_CPU_VREF")
	)
	(segment
		(start 191.9732 -153.3906)
		(end 191.9732 -153.5684)
		(width 0.254)
		(layer "In2.Cu")
		(net "M_F_CPU_VREF")
	)
	(segment
		(start 211.06892 -102.327202)
		(end 202.829922 -110.5662)
		(width 0.254)
		(layer "In2.Cu")
		(net "M_F_CPU_VREF")
	)
	(segment
		(start 196.2912 -124.8537)
		(end 193.2432 -127.9017)
		(width 0.254)
		(layer "In2.Cu")
		(net "M_F_CPU_VREF")
	)
	(segment
		(start 193.0654 -138.347704)
		(end 193.0654 -152.2984)
		(width 0.254)
		(layer "In2.Cu")
		(net "M_F_CPU_VREF")
	)
	(segment
		(start 193.2432 -127.9017)
		(end 193.2432 -132.185156)
		(width 0.254)
		(layer "In2.Cu")
		(net "M_F_CPU_VREF")
	)
	(segment
		(start 193.31686 -138.096244)
		(end 193.0654 -138.347704)
		(width 0.254)
		(layer "In2.Cu")
		(net "M_F_CPU_VREF")
	)
	(segment
		(start 193.2432 -132.185156)
		(end 193.31686 -132.258816)
		(width 0.254)
		(layer "In2.Cu")
		(net "M_F_CPU_VREF")
	)
	(segment
		(start 211.4042 -102.327202)
		(end 211.06892 -102.327202)
		(width 0.254)
		(layer "In2.Cu")
		(net "M_F_CPU_VREF")
	)
	(segment
		(start 201.3458 -110.5662)
		(end 196.2912 -115.6208)
		(width 0.254)
		(layer "In2.Cu")
		(net "M_F_CPU_VREF")
	)
	(segment
		(start 196.2912 -115.6208)
		(end 196.2912 -124.8537)
		(width 0.254)
		(layer "In2.Cu")
		(net "M_F_CPU_VREF")
	)
	(segment
		(start 249.81789 -91.446604)
		(end 249.4915 -91.772994)
		(width 0.2286)
		(layer "In9.Cu")
		(net "M_F_CPU_VREF")
	)
	(segment
		(start 237.96752 -95.188532)
		(end 237.523782 -94.744794)
		(width 0.2286)
		(layer "In9.Cu")
		(net "M_F_CPU_VREF")
	)
	(segment
		(start 249.737118 -90.95105)
		(end 249.81789 -91.031822)
		(width 0.2286)
		(layer "In9.Cu")
		(net "M_F_CPU_VREF")
	)
	(segment
		(start 249.4915 -91.772994)
		(end 249.15368 -91.772994)
		(width 0.2286)
		(layer "In9.Cu")
		(net "M_F_CPU_VREF")
	)
	(segment
		(start 245.275862 -95.188532)
		(end 244.835426 -95.188532)
		(width 0.2286)
		(layer "In9.Cu")
		(net "M_F_CPU_VREF")
	)
	(segment
		(start 234.3658 -95.188532)
		(end 223.087692 -95.188532)
		(width 0.3048)
		(layer "In9.Cu")
		(net "M_F_CPU_VREF")
	)
	(segment
		(start 253.640844 -87.784686)
		(end 253.25197 -88.17356)
		(width 0.2286)
		(layer "In9.Cu")
		(net "M_F_CPU_VREF")
	)
	(segment
		(start 244.391688 -94.744794)
		(end 244.00256 -94.744794)
		(width 0.2286)
		(layer "In9.Cu")
		(net "M_F_CPU_VREF")
	)
	(segment
		(start 251.233686 -89.791794)
		(end 250.87072 -89.791794)
		(width 0.2286)
		(layer "In9.Cu")
		(net "M_F_CPU_VREF")
	)
	(segment
		(start 244.835426 -95.188532)
		(end 244.391688 -94.744794)
		(width 0.2286)
		(layer "In9.Cu")
		(net "M_F_CPU_VREF")
	)
	(segment
		(start 241.842036 -95.188532)
		(end 241.4016 -95.188532)
		(width 0.2286)
		(layer "In9.Cu")
		(net "M_F_CPU_VREF")
	)
	(segment
		(start 237.134654 -94.744794)
		(end 236.690916 -95.188532)
		(width 0.2286)
		(layer "In9.Cu")
		(net "M_F_CPU_VREF")
	)
	(segment
		(start 236.25048 -95.188532)
		(end 235.806742 -94.744794)
		(width 0.2286)
		(layer "In9.Cu")
		(net "M_F_CPU_VREF")
	)
	(segment
		(start 235.417614 -94.744794)
		(end 234.973876 -95.188532)
		(width 0.2286)
		(layer "In9.Cu")
		(net "M_F_CPU_VREF")
	)
	(segment
		(start 251.72924 -89.29624)
		(end 251.233686 -89.791794)
		(width 0.2286)
		(layer "In9.Cu")
		(net "M_F_CPU_VREF")
	)
	(segment
		(start 239.240822 -94.744794)
		(end 238.851694 -94.744794)
		(width 0.2286)
		(layer "In9.Cu")
		(net "M_F_CPU_VREF")
	)
	(segment
		(start 239.68456 -95.188532)
		(end 239.240822 -94.744794)
		(width 0.2286)
		(layer "In9.Cu")
		(net "M_F_CPU_VREF")
	)
	(segment
		(start 252.06706 -89.29624)
		(end 251.72924 -89.29624)
		(width 0.2286)
		(layer "In9.Cu")
		(net "M_F_CPU_VREF")
	)
	(segment
		(start 242.674902 -94.744794)
		(end 242.285774 -94.744794)
		(width 0.2286)
		(layer "In9.Cu")
		(net "M_F_CPU_VREF")
	)
	(segment
		(start 246.082566 -94.744794)
		(end 245.7196 -94.744794)
		(width 0.2286)
		(layer "In9.Cu")
		(net "M_F_CPU_VREF")
	)
	(segment
		(start 235.806742 -94.744794)
		(end 235.417614 -94.744794)
		(width 0.2286)
		(layer "In9.Cu")
		(net "M_F_CPU_VREF")
	)
	(segment
		(start 249.15368 -91.772994)
		(end 248.709942 -92.216732)
		(width 0.2286)
		(layer "In9.Cu")
		(net "M_F_CPU_VREF")
	)
	(segment
		(start 248.346468 -92.216732)
		(end 248.020078 -92.543122)
		(width 0.2286)
		(layer "In9.Cu")
		(net "M_F_CPU_VREF")
	)
	(segment
		(start 234.973876 -95.188532)
		(end 234.3658 -95.188532)
		(width 0.2286)
		(layer "In9.Cu")
		(net "M_F_CPU_VREF")
	)
	(segment
		(start 243.11864 -95.188532)
		(end 242.674902 -94.744794)
		(width 0.2286)
		(layer "In9.Cu")
		(net "M_F_CPU_VREF")
	)
	(segment
		(start 253.25197 -88.17356)
		(end 253.25197 -88.474804)
		(width 0.2286)
		(layer "In9.Cu")
		(net "M_F_CPU_VREF")
	)
	(segment
		(start 245.7196 -94.744794)
		(end 245.275862 -95.188532)
		(width 0.2286)
		(layer "In9.Cu")
		(net "M_F_CPU_VREF")
	)
	(segment
		(start 248.020078 -92.93225)
		(end 248.10085 -93.013022)
		(width 0.2286)
		(layer "In9.Cu")
		(net "M_F_CPU_VREF")
	)
	(segment
		(start 223.087692 -95.190056)
		(end 215.581738 -102.69601)
		(width 0.3048)
		(layer "In9.Cu")
		(net "M_F_CPU_VREF")
	)
	(segment
		(start 215.581738 -102.69601)
		(end 211.773008 -102.69601)
		(width 0.3048)
		(layer "In9.Cu")
		(net "M_F_CPU_VREF")
	)
	(segment
		(start 211.773008 -102.69601)
		(end 211.4042 -102.327202)
		(width 0.3048)
		(layer "In9.Cu")
		(net "M_F_CPU_VREF")
	)
	(segment
		(start 252.613414 -88.749886)
		(end 252.06706 -89.29624)
		(width 0.2286)
		(layer "In9.Cu")
		(net "M_F_CPU_VREF")
	)
	(segment
		(start 243.558822 -95.188532)
		(end 243.11864 -95.188532)
		(width 0.2286)
		(layer "In9.Cu")
		(net "M_F_CPU_VREF")
	)
	(segment
		(start 252.976888 -88.749886)
		(end 252.613414 -88.749886)
		(width 0.2286)
		(layer "In9.Cu")
		(net "M_F_CPU_VREF")
	)
	(segment
		(start 223.087692 -95.188532)
		(end 223.087692 -95.190056)
		(width 0.3048)
		(layer "In9.Cu")
		(net "M_F_CPU_VREF")
	)
	(segment
		(start 253.25197 -88.474804)
		(end 252.976888 -88.749886)
		(width 0.2286)
		(layer "In9.Cu")
		(net "M_F_CPU_VREF")
	)
	(segment
		(start 241.4016 -95.188532)
		(end 240.957862 -94.744794)
		(width 0.2286)
		(layer "In9.Cu")
		(net "M_F_CPU_VREF")
	)
	(segment
		(start 246.57812 -94.24924)
		(end 246.082566 -94.744794)
		(width 0.2286)
		(layer "In9.Cu")
		(net "M_F_CPU_VREF")
	)
	(segment
		(start 248.10085 -93.427804)
		(end 247.774714 -93.75394)
		(width 0.2286)
		(layer "In9.Cu")
		(net "M_F_CPU_VREF")
	)
	(segment
		(start 240.568734 -94.744794)
		(end 240.124996 -95.188532)
		(width 0.2286)
		(layer "In9.Cu")
		(net "M_F_CPU_VREF")
	)
	(segment
		(start 248.020078 -92.543122)
		(end 248.020078 -92.93225)
		(width 0.2286)
		(layer "In9.Cu")
		(net "M_F_CPU_VREF")
	)
	(segment
		(start 246.94134 -94.24924)
		(end 246.57812 -94.24924)
		(width 0.2286)
		(layer "In9.Cu")
		(net "M_F_CPU_VREF")
	)
	(segment
		(start 244.00256 -94.744794)
		(end 243.558822 -95.188532)
		(width 0.2286)
		(layer "In9.Cu")
		(net "M_F_CPU_VREF")
	)
	(segment
		(start 242.285774 -94.744794)
		(end 241.842036 -95.188532)
		(width 0.2286)
		(layer "In9.Cu")
		(net "M_F_CPU_VREF")
	)
	(segment
		(start 250.063508 -90.235532)
		(end 249.737118 -90.561922)
		(width 0.2286)
		(layer "In9.Cu")
		(net "M_F_CPU_VREF")
	)
	(segment
		(start 247.774714 -93.75394)
		(end 247.43664 -93.75394)
		(width 0.2286)
		(layer "In9.Cu")
		(net "M_F_CPU_VREF")
	)
	(segment
		(start 250.426982 -90.235532)
		(end 250.063508 -90.235532)
		(width 0.2286)
		(layer "In9.Cu")
		(net "M_F_CPU_VREF")
	)
	(segment
		(start 249.81789 -91.031822)
		(end 249.81789 -91.446604)
		(width 0.2286)
		(layer "In9.Cu")
		(net "M_F_CPU_VREF")
	)
	(segment
		(start 248.709942 -92.216732)
		(end 248.346468 -92.216732)
		(width 0.2286)
		(layer "In9.Cu")
		(net "M_F_CPU_VREF")
	)
	(segment
		(start 240.124996 -95.188532)
		(end 239.68456 -95.188532)
		(width 0.2286)
		(layer "In9.Cu")
		(net "M_F_CPU_VREF")
	)
	(segment
		(start 248.10085 -93.013022)
		(end 248.10085 -93.427804)
		(width 0.2286)
		(layer "In9.Cu")
		(net "M_F_CPU_VREF")
	)
	(segment
		(start 247.43664 -93.75394)
		(end 246.94134 -94.24924)
		(width 0.2286)
		(layer "In9.Cu")
		(net "M_F_CPU_VREF")
	)
	(segment
		(start 238.851694 -94.744794)
		(end 238.407956 -95.188532)
		(width 0.2286)
		(layer "In9.Cu")
		(net "M_F_CPU_VREF")
	)
	(segment
		(start 237.523782 -94.744794)
		(end 237.134654 -94.744794)
		(width 0.2286)
		(layer "In9.Cu")
		(net "M_F_CPU_VREF")
	)
	(segment
		(start 236.690916 -95.188532)
		(end 236.25048 -95.188532)
		(width 0.2286)
		(layer "In9.Cu")
		(net "M_F_CPU_VREF")
	)
	(segment
		(start 240.957862 -94.744794)
		(end 240.568734 -94.744794)
		(width 0.2286)
		(layer "In9.Cu")
		(net "M_F_CPU_VREF")
	)
	(segment
		(start 250.87072 -89.791794)
		(end 250.426982 -90.235532)
		(width 0.2286)
		(layer "In9.Cu")
		(net "M_F_CPU_VREF")
	)
	(segment
		(start 249.737118 -90.561922)
		(end 249.737118 -90.95105)
		(width 0.2286)
		(layer "In9.Cu")
		(net "M_F_CPU_VREF")
	)
	(segment
		(start 238.407956 -95.188532)
		(end 237.96752 -95.188532)
		(width 0.2286)
		(layer "In9.Cu")
		(net "M_F_CPU_VREF")
	)
	(segment
		(start 195.550282 -147.27174)
		(end 195.549774 -147.27174)
		(width 0.4064)
		(layer "F.Cu")
		(net "M_E_VREF")
	)
	(segment
		(start 195.549774 -147.27174)
		(end 195.549774 -146.070574)
		(width 0.4064)
		(layer "F.Cu")
		(net "M_E_VREF")
	)
	(segment
		(start 195.4784 -139.192)
		(end 195.453 -139.1666)
		(width 0.4064)
		(layer "F.Cu")
		(net "M_E_VREF")
	)
	(segment
		(start 195.549774 -146.070574)
		(end 195.453 -145.9738)
		(width 0.4064)
		(layer "F.Cu")
		(net "M_E_VREF")
	)
	(segment
		(start 195.4784 -140.0556)
		(end 195.4784 -139.192)
		(width 0.4064)
		(layer "F.Cu")
		(net "M_E_VREF")
	)
	(via
		(at 195.453 -139.1666)
		(size 0.508)
		(drill 0.254)
		(layers "F.Cu" "B.Cu")
		(net "M_E_VREF")
	)
	(via
		(at 195.453 -145.9738)
		(size 0.508)
		(drill 0.254)
		(layers "F.Cu" "B.Cu")
		(net "M_E_VREF")
	)
	(segment
		(start 193.548 -145.3642)
		(end 194.437 -145.3642)
		(width 0.4064)
		(layer "B.Cu")
		(net "M_E_VREF")
	)
	(segment
		(start 192.659 -145.3642)
		(end 193.548 -145.3642)
		(width 0.4064)
		(layer "B.Cu")
		(net "M_E_VREF")
	)
	(segment
		(start 195.549774 -139.069826)
		(end 195.453 -139.1666)
		(width 0.381)
		(layer "B.Cu")
		(net "M_E_VREF")
	)
	(segment
		(start 195.453 -144.977612)
		(end 195.453 -145.9738)
		(width 0.4064)
		(layer "B.Cu")
		(net "M_E_VREF")
	)
	(segment
		(start 195.549774 -137.877296)
		(end 195.549774 -139.069826)
		(width 0.381)
		(layer "B.Cu")
		(net "M_E_VREF")
	)
	(segment
		(start 195.279772 -145.9738)
		(end 195.453 -145.9738)
		(width 0.4064)
		(layer "B.Cu")
		(net "M_E_VREF")
	)
	(segment
		(start 194.670172 -145.3642)
		(end 195.279772 -145.9738)
		(width 0.4064)
		(layer "B.Cu")
		(net "M_E_VREF")
	)
	(segment
		(start 194.437 -145.3642)
		(end 194.670172 -145.3642)
		(width 0.4064)
		(layer "B.Cu")
		(net "M_E_VREF")
	)
	(segment
		(start 195.550282 -137.877296)
		(end 195.549774 -137.877296)
		(width 0.381)
		(layer "B.Cu")
		(net "M_E_VREF")
	)
	(segment
		(start 195.453 -145.9738)
		(end 195.453 -144.754346)
		(width 0.4064)
		(layer "In2.Cu")
		(net "M_E_VREF")
	)
	(segment
		(start 194.8942 -142.671546)
		(end 194.08902 -141.866366)
		(width 0.4064)
		(layer "In2.Cu")
		(net "M_E_VREF")
	)
	(segment
		(start 194.08902 -141.866366)
		(end 194.08902 -140.53058)
		(width 0.4064)
		(layer "In2.Cu")
		(net "M_E_VREF")
	)
	(segment
		(start 194.08902 -140.53058)
		(end 195.453 -139.1666)
		(width 0.4064)
		(layer "In2.Cu")
		(net "M_E_VREF")
	)
	(segment
		(start 195.453 -144.754346)
		(end 194.8942 -144.195546)
		(width 0.4064)
		(layer "In2.Cu")
		(net "M_E_VREF")
	)
	(segment
		(start 194.8942 -144.195546)
		(end 194.8942 -142.671546)
		(width 0.4064)
		(layer "In2.Cu")
		(net "M_E_VREF")
	)
	(segment
		(start 254.212344 -86.794086)
		(end 253.640844 -86.794086)
		(width 0.1016)
		(layer "F.Cu")
		(net "M_E_CPU_VREF")
	)
	(via
		(at 253.640844 -86.794086)
		(size 0.508)
		(drill 0.254)
		(layers "F.Cu" "B.Cu")
		(net "M_E_CPU_VREF")
	)
	(via
		(at 210.2612 -102.327202)
		(size 0.508)
		(drill 0.254)
		(layers "F.Cu" "B.Cu")
		(net "M_E_CPU_VREF")
	)
	(via
		(at 191.77 -143.764)
		(size 0.508)
		(drill 0.254)
		(layers "F.Cu" "B.Cu")
		(net "M_E_CPU_VREF")
	)
	(segment
		(start 192.659 -144.4752)
		(end 191.77 -144.4752)
		(width 0.254)
		(layer "B.Cu")
		(net "M_E_CPU_VREF")
	)
	(segment
		(start 191.77 -144.4752)
		(end 191.77 -143.764)
		(width 0.254)
		(layer "B.Cu")
		(net "M_E_CPU_VREF")
	)
	(segment
		(start 201.029824 -109.8042)
		(end 202.5142 -109.8042)
		(width 0.254)
		(layer "In2.Cu")
		(net "M_E_CPU_VREF")
	)
	(segment
		(start 195.5038 -115.330478)
		(end 200.5838 -110.250478)
		(width 0.254)
		(layer "In2.Cu")
		(net "M_E_CPU_VREF")
	)
	(segment
		(start 202.5142 -109.8042)
		(end 209.991198 -102.327202)
		(width 0.254)
		(layer "In2.Cu")
		(net "M_E_CPU_VREF")
	)
	(segment
		(start 200.5838 -110.250478)
		(end 200.5838 -110.250224)
		(width 0.254)
		(layer "In2.Cu")
		(net "M_E_CPU_VREF")
	)
	(segment
		(start 192.278 -141.7574)
		(end 192.278 -137.795)
		(width 0.254)
		(layer "In2.Cu")
		(net "M_E_CPU_VREF")
	)
	(segment
		(start 192.278 -137.795)
		(end 192.5447 -137.5283)
		(width 0.254)
		(layer "In2.Cu")
		(net "M_E_CPU_VREF")
	)
	(segment
		(start 192.4812 -132.5118)
		(end 192.4812 -126.797816)
		(width 0.254)
		(layer "In2.Cu")
		(net "M_E_CPU_VREF")
	)
	(segment
		(start 195.5038 -123.775216)
		(end 195.5038 -115.330478)
		(width 0.254)
		(layer "In2.Cu")
		(net "M_E_CPU_VREF")
	)
	(segment
		(start 191.77 -142.2654)
		(end 192.278 -141.7574)
		(width 0.254)
		(layer "In2.Cu")
		(net "M_E_CPU_VREF")
	)
	(segment
		(start 200.5838 -110.250224)
		(end 201.029824 -109.8042)
		(width 0.254)
		(layer "In2.Cu")
		(net "M_E_CPU_VREF")
	)
	(segment
		(start 192.5447 -137.5283)
		(end 192.5447 -132.5753)
		(width 0.254)
		(layer "In2.Cu")
		(net "M_E_CPU_VREF")
	)
	(segment
		(start 209.991198 -102.327202)
		(end 210.2612 -102.327202)
		(width 0.254)
		(layer "In2.Cu")
		(net "M_E_CPU_VREF")
	)
	(segment
		(start 192.5447 -132.5753)
		(end 192.4812 -132.5118)
		(width 0.254)
		(layer "In2.Cu")
		(net "M_E_CPU_VREF")
	)
	(segment
		(start 192.4812 -126.797816)
		(end 195.5038 -123.775216)
		(width 0.254)
		(layer "In2.Cu")
		(net "M_E_CPU_VREF")
	)
	(segment
		(start 191.77 -143.764)
		(end 191.77 -142.2654)
		(width 0.254)
		(layer "In2.Cu")
		(net "M_E_CPU_VREF")
	)
	(segment
		(start 246.083074 -93.75394)
		(end 245.694454 -93.75394)
		(width 0.2286)
		(layer "In9.Cu")
		(net "M_E_CPU_VREF")
	)
	(segment
		(start 247.161558 -92.437204)
		(end 247.24233 -92.517976)
		(width 0.2286)
		(layer "In9.Cu")
		(net "M_E_CPU_VREF")
	)
	(segment
		(start 235.392468 -93.75394)
		(end 234.948222 -94.198186)
		(width 0.2286)
		(layer "In9.Cu")
		(net "M_E_CPU_VREF")
	)
	(segment
		(start 233.538014 -94.198186)
		(end 233.4768 -94.2594)
		(width 0.2286)
		(layer "In9.Cu")
		(net "M_E_CPU_VREF")
	)
	(segment
		(start 242.699794 -93.75394)
		(end 242.260628 -93.75394)
		(width 0.2286)
		(layer "In9.Cu")
		(net "M_E_CPU_VREF")
	)
	(segment
		(start 248.95937 -90.536776)
		(end 248.95937 -90.95105)
		(width 0.2286)
		(layer "In9.Cu")
		(net "M_E_CPU_VREF")
	)
	(segment
		(start 214.982806 -101.78161)
		(end 210.806792 -101.78161)
		(width 0.3048)
		(layer "In9.Cu")
		(net "M_E_CPU_VREF")
	)
	(segment
		(start 241.427254 -94.198186)
		(end 240.983008 -93.75394)
		(width 0.2286)
		(layer "In9.Cu")
		(net "M_E_CPU_VREF")
	)
	(segment
		(start 239.710214 -94.198186)
		(end 239.265968 -93.75394)
		(width 0.2286)
		(layer "In9.Cu")
		(net "M_E_CPU_VREF")
	)
	(segment
		(start 250.0122 -89.29624)
		(end 249.516646 -89.791794)
		(width 0.2286)
		(layer "In9.Cu")
		(net "M_E_CPU_VREF")
	)
	(segment
		(start 246.915686 -93.258894)
		(end 246.57812 -93.258894)
		(width 0.2286)
		(layer "In9.Cu")
		(net "M_E_CPU_VREF")
	)
	(segment
		(start 250.87072 -88.801194)
		(end 250.375674 -89.29624)
		(width 0.2286)
		(layer "In9.Cu")
		(net "M_E_CPU_VREF")
	)
	(segment
		(start 251.20854 -88.801194)
		(end 250.87072 -88.801194)
		(width 0.2286)
		(layer "In9.Cu")
		(net "M_E_CPU_VREF")
	)
	(segment
		(start 239.265968 -93.75394)
		(end 238.826548 -93.75394)
		(width 0.2286)
		(layer "In9.Cu")
		(net "M_E_CPU_VREF")
	)
	(segment
		(start 250.375674 -89.29624)
		(end 250.0122 -89.29624)
		(width 0.2286)
		(layer "In9.Cu")
		(net "M_E_CPU_VREF")
	)
	(segment
		(start 247.24233 -92.93225)
		(end 246.915686 -93.258894)
		(width 0.2286)
		(layer "In9.Cu")
		(net "M_E_CPU_VREF")
	)
	(segment
		(start 248.29516 -91.27744)
		(end 247.799606 -91.772994)
		(width 0.2286)
		(layer "In9.Cu")
		(net "M_E_CPU_VREF")
	)
	(segment
		(start 233.4768 -94.2594)
		(end 222.505016 -94.2594)
		(width 0.3048)
		(layer "In9.Cu")
		(net "M_E_CPU_VREF")
	)
	(segment
		(start 248.878598 -90.456004)
		(end 248.95937 -90.536776)
		(width 0.2286)
		(layer "In9.Cu")
		(net "M_E_CPU_VREF")
	)
	(segment
		(start 248.95937 -90.95105)
		(end 248.63298 -91.27744)
		(width 0.2286)
		(layer "In9.Cu")
		(net "M_E_CPU_VREF")
	)
	(segment
		(start 242.260628 -93.75394)
		(end 241.816382 -94.198186)
		(width 0.2286)
		(layer "In9.Cu")
		(net "M_E_CPU_VREF")
	)
	(segment
		(start 237.548928 -93.75394)
		(end 237.109508 -93.75394)
		(width 0.2286)
		(layer "In9.Cu")
		(net "M_E_CPU_VREF")
	)
	(segment
		(start 244.416834 -93.75394)
		(end 243.977414 -93.75394)
		(width 0.2286)
		(layer "In9.Cu")
		(net "M_E_CPU_VREF")
	)
	(segment
		(start 248.63298 -91.27744)
		(end 248.29516 -91.27744)
		(width 0.2286)
		(layer "In9.Cu")
		(net "M_E_CPU_VREF")
	)
	(segment
		(start 237.993174 -94.198186)
		(end 237.548928 -93.75394)
		(width 0.2286)
		(layer "In9.Cu")
		(net "M_E_CPU_VREF")
	)
	(segment
		(start 245.694454 -93.75394)
		(end 245.250208 -94.198186)
		(width 0.2286)
		(layer "In9.Cu")
		(net "M_E_CPU_VREF")
	)
	(segment
		(start 235.831888 -93.75394)
		(end 235.392468 -93.75394)
		(width 0.2286)
		(layer "In9.Cu")
		(net "M_E_CPU_VREF")
	)
	(segment
		(start 253.640844 -86.794086)
		(end 253.25197 -87.18296)
		(width 0.2286)
		(layer "In9.Cu")
		(net "M_E_CPU_VREF")
	)
	(segment
		(start 249.516646 -89.791794)
		(end 249.15368 -89.791794)
		(width 0.2286)
		(layer "In9.Cu")
		(net "M_E_CPU_VREF")
	)
	(segment
		(start 240.543588 -93.75394)
		(end 240.099342 -94.198186)
		(width 0.2286)
		(layer "In9.Cu")
		(net "M_E_CPU_VREF")
	)
	(segment
		(start 243.533168 -94.198186)
		(end 243.14404 -94.198186)
		(width 0.2286)
		(layer "In9.Cu")
		(net "M_E_CPU_VREF")
	)
	(segment
		(start 238.826548 -93.75394)
		(end 238.382302 -94.198186)
		(width 0.2286)
		(layer "In9.Cu")
		(net "M_E_CPU_VREF")
	)
	(segment
		(start 252.118368 -88.254332)
		(end 251.755402 -88.254332)
		(width 0.2286)
		(layer "In9.Cu")
		(net "M_E_CPU_VREF")
	)
	(segment
		(start 247.43664 -91.772994)
		(end 247.161558 -92.048076)
		(width 0.2286)
		(layer "In9.Cu")
		(net "M_E_CPU_VREF")
	)
	(segment
		(start 251.755402 -88.254332)
		(end 251.20854 -88.801194)
		(width 0.2286)
		(layer "In9.Cu")
		(net "M_E_CPU_VREF")
	)
	(segment
		(start 238.382302 -94.198186)
		(end 237.993174 -94.198186)
		(width 0.2286)
		(layer "In9.Cu")
		(net "M_E_CPU_VREF")
	)
	(segment
		(start 237.109508 -93.75394)
		(end 236.665262 -94.198186)
		(width 0.2286)
		(layer "In9.Cu")
		(net "M_E_CPU_VREF")
	)
	(segment
		(start 247.24233 -92.517976)
		(end 247.24233 -92.93225)
		(width 0.2286)
		(layer "In9.Cu")
		(net "M_E_CPU_VREF")
	)
	(segment
		(start 240.983008 -93.75394)
		(end 240.543588 -93.75394)
		(width 0.2286)
		(layer "In9.Cu")
		(net "M_E_CPU_VREF")
	)
	(segment
		(start 210.806792 -101.78161)
		(end 210.2612 -102.327202)
		(width 0.3048)
		(layer "In9.Cu")
		(net "M_E_CPU_VREF")
	)
	(segment
		(start 247.799606 -91.772994)
		(end 247.43664 -91.772994)
		(width 0.2286)
		(layer "In9.Cu")
		(net "M_E_CPU_VREF")
	)
	(segment
		(start 248.878598 -90.066876)
		(end 248.878598 -90.456004)
		(width 0.2286)
		(layer "In9.Cu")
		(net "M_E_CPU_VREF")
	)
	(segment
		(start 252.92558 -87.810594)
		(end 252.562106 -87.810594)
		(width 0.2286)
		(layer "In9.Cu")
		(net "M_E_CPU_VREF")
	)
	(segment
		(start 245.250208 -94.198186)
		(end 244.86108 -94.198186)
		(width 0.2286)
		(layer "In9.Cu")
		(net "M_E_CPU_VREF")
	)
	(segment
		(start 236.276134 -94.198186)
		(end 235.831888 -93.75394)
		(width 0.2286)
		(layer "In9.Cu")
		(net "M_E_CPU_VREF")
	)
	(segment
		(start 253.25197 -87.18296)
		(end 253.25197 -87.484204)
		(width 0.2286)
		(layer "In9.Cu")
		(net "M_E_CPU_VREF")
	)
	(segment
		(start 253.25197 -87.484204)
		(end 252.92558 -87.810594)
		(width 0.2286)
		(layer "In9.Cu")
		(net "M_E_CPU_VREF")
	)
	(segment
		(start 240.099342 -94.198186)
		(end 239.710214 -94.198186)
		(width 0.2286)
		(layer "In9.Cu")
		(net "M_E_CPU_VREF")
	)
	(segment
		(start 246.57812 -93.258894)
		(end 246.083074 -93.75394)
		(width 0.2286)
		(layer "In9.Cu")
		(net "M_E_CPU_VREF")
	)
	(segment
		(start 243.977414 -93.75394)
		(end 243.533168 -94.198186)
		(width 0.2286)
		(layer "In9.Cu")
		(net "M_E_CPU_VREF")
	)
	(segment
		(start 234.948222 -94.198186)
		(end 233.538014 -94.198186)
		(width 0.2286)
		(layer "In9.Cu")
		(net "M_E_CPU_VREF")
	)
	(segment
		(start 243.14404 -94.198186)
		(end 242.699794 -93.75394)
		(width 0.2286)
		(layer "In9.Cu")
		(net "M_E_CPU_VREF")
	)
	(segment
		(start 244.86108 -94.198186)
		(end 244.416834 -93.75394)
		(width 0.2286)
		(layer "In9.Cu")
		(net "M_E_CPU_VREF")
	)
	(segment
		(start 252.562106 -87.810594)
		(end 252.118368 -88.254332)
		(width 0.2286)
		(layer "In9.Cu")
		(net "M_E_CPU_VREF")
	)
	(segment
		(start 241.816382 -94.198186)
		(end 241.427254 -94.198186)
		(width 0.2286)
		(layer "In9.Cu")
		(net "M_E_CPU_VREF")
	)
	(segment
		(start 249.15368 -89.791794)
		(end 248.878598 -90.066876)
		(width 0.2286)
		(layer "In9.Cu")
		(net "M_E_CPU_VREF")
	)
	(segment
		(start 222.505016 -94.2594)
		(end 214.982806 -101.78161)
		(width 0.3048)
		(layer "In9.Cu")
		(net "M_E_CPU_VREF")
	)
	(segment
		(start 247.161558 -92.048076)
		(end 247.161558 -92.437204)
		(width 0.2286)
		(layer "In9.Cu")
		(net "M_E_CPU_VREF")
	)
	(segment
		(start 236.665262 -94.198186)
		(end 236.276134 -94.198186)
		(width 0.2286)
		(layer "In9.Cu")
		(net "M_E_CPU_VREF")
	)
	(segment
		(start 195.549774 -136.490456)
		(end 195.453 -136.393682)
		(width 0.4064)
		(layer "F.Cu")
		(net "M_D_VREF")
	)
	(segment
		(start 195.5546 -130.2512)
		(end 195.5546 -129.667)
		(width 0.4064)
		(layer "F.Cu")
		(net "M_D_VREF")
	)
	(segment
		(start 195.550282 -137.67054)
		(end 195.549774 -137.67054)
		(width 0.4064)
		(layer "F.Cu")
		(net "M_D_VREF")
	)
	(segment
		(start 195.5546 -129.667)
		(end 195.453 -129.5654)
		(width 0.4064)
		(layer "F.Cu")
		(net "M_D_VREF")
	)
	(segment
		(start 195.549774 -137.67054)
		(end 195.549774 -136.490456)
		(width 0.4064)
		(layer "F.Cu")
		(net "M_D_VREF")
	)
	(via
		(at 195.453 -129.5654)
		(size 0.508)
		(drill 0.254)
		(layers "F.Cu" "B.Cu")
		(net "M_D_VREF")
	)
	(via
		(at 195.453 -136.393682)
		(size 0.508)
		(drill 0.254)
		(layers "F.Cu" "B.Cu")
		(net "M_D_VREF")
	)
	(segment
		(start 193.802 -135.763)
		(end 194.691 -135.763)
		(width 0.4064)
		(layer "B.Cu")
		(net "M_D_VREF")
	)
	(segment
		(start 195.453 -135.4328)
		(end 195.453 -136.393682)
		(width 0.4064)
		(layer "B.Cu")
		(net "M_D_VREF")
	)
	(segment
		(start 194.822318 -135.763)
		(end 194.691 -135.763)
		(width 0.4064)
		(layer "B.Cu")
		(net "M_D_VREF")
	)
	(segment
		(start 195.550282 -128.276096)
		(end 195.549774 -128.276096)
		(width 0.381)
		(layer "B.Cu")
		(net "M_D_VREF")
	)
	(segment
		(start 195.453 -136.393682)
		(end 194.822318 -135.763)
		(width 0.4064)
		(layer "B.Cu")
		(net "M_D_VREF")
	)
	(segment
		(start 192.913 -135.763)
		(end 193.802 -135.763)
		(width 0.4064)
		(layer "B.Cu")
		(net "M_D_VREF")
	)
	(segment
		(start 195.549774 -128.276096)
		(end 195.549774 -129.468626)
		(width 0.381)
		(layer "B.Cu")
		(net "M_D_VREF")
	)
	(segment
		(start 195.5546 -135.3312)
		(end 195.453 -135.4328)
		(width 0.4064)
		(layer "B.Cu")
		(net "M_D_VREF")
	)
	(segment
		(start 195.549774 -129.468626)
		(end 195.453 -129.5654)
		(width 0.381)
		(layer "B.Cu")
		(net "M_D_VREF")
	)
	(segment
		(start 194.9704 -134.645146)
		(end 195.453 -135.127746)
		(width 0.4064)
		(layer "In2.Cu")
		(net "M_D_VREF")
	)
	(segment
		(start 195.453 -129.948432)
		(end 194.125596 -131.275836)
		(width 0.4064)
		(layer "In2.Cu")
		(net "M_D_VREF")
	)
	(segment
		(start 195.453 -129.5654)
		(end 195.453 -129.948432)
		(width 0.4064)
		(layer "In2.Cu")
		(net "M_D_VREF")
	)
	(segment
		(start 194.125596 -131.275836)
		(end 194.125596 -131.850638)
		(width 0.4064)
		(layer "In2.Cu")
		(net "M_D_VREF")
	)
	(segment
		(start 195.453 -135.127746)
		(end 195.453 -136.393682)
		(width 0.4064)
		(layer "In2.Cu")
		(net "M_D_VREF")
	)
	(segment
		(start 194.125596 -131.850638)
		(end 194.9704 -132.695442)
		(width 0.4064)
		(layer "In2.Cu")
		(net "M_D_VREF")
	)
	(segment
		(start 194.9704 -132.695442)
		(end 194.9704 -134.645146)
		(width 0.4064)
		(layer "In2.Cu")
		(net "M_D_VREF")
	)
	(segment
		(start 194.9069 -2.8575)
		(end 194.564 -2.8575)
		(width 0.4064)
		(layer "F.Cu")
		(net "M_C_VREF")
	)
	(segment
		(start 195.549774 -2.325878)
		(end 195.58 -2.356104)
		(width 0.381)
		(layer "F.Cu")
		(net "M_C_VREF")
	)
	(segment
		(start 193.675 -2.8575)
		(end 192.786 -2.8575)
		(width 0.4064)
		(layer "F.Cu")
		(net "M_C_VREF")
	)
	(segment
		(start 195.58 -3.321812)
		(end 195.371212 -3.321812)
		(width 0.4064)
		(layer "F.Cu")
		(net "M_C_VREF")
	)
	(segment
		(start 195.371212 -3.321812)
		(end 194.9069 -2.8575)
		(width 0.4064)
		(layer "F.Cu")
		(net "M_C_VREF")
	)
	(segment
		(start 195.549774 -0.821182)
		(end 195.549774 -2.325878)
		(width 0.381)
		(layer "F.Cu")
		(net "M_C_VREF")
	)
	(segment
		(start 195.58 -2.356104)
		(end 195.58 -3.321812)
		(width 0.381)
		(layer "F.Cu")
		(net "M_C_VREF")
	)
	(segment
		(start 195.550282 -0.821182)
		(end 195.549774 -0.821182)
		(width 0.381)
		(layer "F.Cu")
		(net "M_C_VREF")
	)
	(segment
		(start 194.564 -2.8575)
		(end 193.675 -2.8575)
		(width 0.4064)
		(layer "F.Cu")
		(net "M_C_VREF")
	)
	(via
		(at 195.549774 -2.325878)
		(size 0.508)
		(drill 0.254)
		(layers "F.Cu" "B.Cu")
		(net "M_C_VREF")
	)
	(segment
		(start 195.549774 -2.325878)
		(end 195.549774 -1.021842)
		(width 0.381)
		(layer "B.Cu")
		(net "M_C_VREF")
	)
	(segment
		(start 195.549774 -1.021842)
		(end 195.549774 0.442722)
		(width 0.381)
		(layer "B.Cu")
		(net "M_C_VREF")
	)
	(segment
		(start 195.550282 -1.021842)
		(end 195.549774 -1.021842)
		(width 0.381)
		(layer "B.Cu")
		(net "M_C_VREF")
	)
	(segment
		(start 195.453 0.539496)
		(end 195.453 1.524)
		(width 0.381)
		(layer "B.Cu")
		(net "M_C_VREF")
	)
	(segment
		(start 195.549774 0.442722)
		(end 195.453 0.539496)
		(width 0.381)
		(layer "B.Cu")
		(net "M_C_VREF")
	)
	(segment
		(start 192.786 -3.7465)
		(end 192.786 -4.1148)
		(width 0.4064)
		(layer "F.Cu")
		(net "M_C_CPU_VREF")
	)
	(segment
		(start 252.495304 -63.019686)
		(end 251.923804 -63.019686)
		(width 0.254)
		(layer "F.Cu")
		(net "M_C_CPU_VREF")
	)
	(segment
		(start 192.786 -3.7465)
		(end 191.897 -3.7465)
		(width 0.4064)
		(layer "F.Cu")
		(net "M_C_CPU_VREF")
	)
	(segment
		(start 193.0654 -4.3942)
		(end 193.0654 -4.38277)
		(width 0.4064)
		(layer "F.Cu")
		(net "M_C_CPU_VREF")
	)
	(segment
		(start 192.786 -4.1148)
		(end 193.0654 -4.3942)
		(width 0.4064)
		(layer "F.Cu")
		(net "M_C_CPU_VREF")
	)
	(via
		(at 204.33538 -47.450756)
		(size 0.508)
		(drill 0.254)
		(layers "F.Cu" "B.Cu")
		(net "M_C_CPU_VREF")
	)
	(via
		(at 251.923804 -63.019686)
		(size 0.508)
		(drill 0.254)
		(layers "F.Cu" "B.Cu")
		(net "M_C_CPU_VREF")
	)
	(via
		(at 193.0654 -4.38277)
		(size 0.508)
		(drill 0.254)
		(layers "F.Cu" "B.Cu")
		(net "M_C_CPU_VREF")
	)
	(segment
		(start 192.913 -24.152352)
		(end 192.913 -23.749)
		(width 0.254)
		(layer "In2.Cu")
		(net "M_C_CPU_VREF")
	)
	(segment
		(start 193.406776 -4.724146)
		(end 193.0654 -4.38277)
		(width 0.254)
		(layer "In2.Cu")
		(net "M_C_CPU_VREF")
	)
	(segment
		(start 204.33538 -47.450756)
		(end 204.457046 -47.32909)
		(width 0.254)
		(layer "In2.Cu")
		(net "M_C_CPU_VREF")
	)
	(segment
		(start 193.3956 -23.2664)
		(end 193.3956 -20.3962)
		(width 0.254)
		(layer "In2.Cu")
		(net "M_C_CPU_VREF")
	)
	(segment
		(start 204.457046 -47.32909)
		(end 204.457046 -45.859446)
		(width 0.254)
		(layer "In2.Cu")
		(net "M_C_CPU_VREF")
	)
	(segment
		(start 193.406776 -20.385024)
		(end 193.406776 -4.724146)
		(width 0.254)
		(layer "In2.Cu")
		(net "M_C_CPU_VREF")
	)
	(segment
		(start 193.5226 -24.761952)
		(end 192.913 -24.152352)
		(width 0.254)
		(layer "In2.Cu")
		(net "M_C_CPU_VREF")
	)
	(segment
		(start 193.5226 -34.925)
		(end 193.5226 -24.761952)
		(width 0.254)
		(layer "In2.Cu")
		(net "M_C_CPU_VREF")
	)
	(segment
		(start 193.3956 -20.3962)
		(end 193.406776 -20.385024)
		(width 0.254)
		(layer "In2.Cu")
		(net "M_C_CPU_VREF")
	)
	(segment
		(start 192.913 -23.749)
		(end 193.3956 -23.2664)
		(width 0.254)
		(layer "In2.Cu")
		(net "M_C_CPU_VREF")
	)
	(segment
		(start 204.457046 -45.859446)
		(end 193.5226 -34.925)
		(width 0.254)
		(layer "In2.Cu")
		(net "M_C_CPU_VREF")
	)
	(segment
		(start 209.711544 -49.299622)
		(end 209.155792 -49.299622)
		(width 0.254)
		(layer "In7.Cu")
		(net "M_C_CPU_VREF")
	)
	(segment
		(start 245.7196 -57.050686)
		(end 245.444518 -56.775604)
		(width 0.2286)
		(layer "In7.Cu")
		(net "M_C_CPU_VREF")
	)
	(segment
		(start 248.95937 -58.862722)
		(end 248.633234 -58.536586)
		(width 0.2286)
		(layer "In7.Cu")
		(net "M_C_CPU_VREF")
	)
	(segment
		(start 248.29516 -58.536586)
		(end 247.79986 -58.041286)
		(width 0.2286)
		(layer "In7.Cu")
		(net "M_C_CPU_VREF")
	)
	(segment
		(start 242.674902 -54.130194)
		(end 242.318794 -54.130194)
		(width 0.2286)
		(layer "In7.Cu")
		(net "M_C_CPU_VREF")
	)
	(segment
		(start 206.97063 -47.497238)
		(end 204.381862 -47.497238)
		(width 0.254)
		(layer "In7.Cu")
		(net "M_C_CPU_VREF")
	)
	(segment
		(start 230.5431 -50.366676)
		(end 210.778598 -50.366676)
		(width 0.254)
		(layer "In7.Cu")
		(net "M_C_CPU_VREF")
	)
	(segment
		(start 237.993174 -52.64404)
		(end 237.549182 -53.088032)
		(width 0.2286)
		(layer "In7.Cu")
		(net "M_C_CPU_VREF")
	)
	(segment
		(start 209.155792 -49.299622)
		(end 209.155538 -49.299368)
		(width 0.254)
		(layer "In7.Cu")
		(net "M_C_CPU_VREF")
	)
	(segment
		(start 238.407702 -52.64404)
		(end 237.993174 -52.64404)
		(width 0.2286)
		(layer "In7.Cu")
		(net "M_C_CPU_VREF")
	)
	(segment
		(start 251.53493 -62.330076)
		(end 251.20854 -62.003686)
		(width 0.2286)
		(layer "In7.Cu")
		(net "M_C_CPU_VREF")
	)
	(segment
		(start 234.559094 -52.64404)
		(end 234.115102 -53.088032)
		(width 0.2286)
		(layer "In7.Cu")
		(net "M_C_CPU_VREF")
	)
	(segment
		(start 236.690662 -52.64404)
		(end 236.276134 -52.64404)
		(width 0.2286)
		(layer "In7.Cu")
		(net "M_C_CPU_VREF")
	)
	(segment
		(start 237.549182 -53.088032)
		(end 237.134654 -53.088032)
		(width 0.2286)
		(layer "In7.Cu")
		(net "M_C_CPU_VREF")
	)
	(segment
		(start 250.67641 -61.23305)
		(end 250.67641 -60.843922)
		(width 0.2286)
		(layer "In7.Cu")
		(net "M_C_CPU_VREF")
	)
	(segment
		(start 244.835426 -55.564532)
		(end 244.34038 -55.069486)
		(width 0.2286)
		(layer "In7.Cu")
		(net "M_C_CPU_VREF")
	)
	(segment
		(start 248.633234 -58.536586)
		(end 248.29516 -58.536586)
		(width 0.2286)
		(layer "In7.Cu")
		(net "M_C_CPU_VREF")
	)
	(segment
		(start 236.276134 -52.64404)
		(end 235.832142 -53.088032)
		(width 0.2286)
		(layer "In7.Cu")
		(net "M_C_CPU_VREF")
	)
	(segment
		(start 238.851694 -53.088032)
		(end 238.407702 -52.64404)
		(width 0.2286)
		(layer "In7.Cu")
		(net "M_C_CPU_VREF")
	)
	(segment
		(start 237.134654 -53.088032)
		(end 236.690662 -52.64404)
		(width 0.2286)
		(layer "In7.Cu")
		(net "M_C_CPU_VREF")
	)
	(segment
		(start 204.381862 -47.497238)
		(end 204.33538 -47.450756)
		(width 0.254)
		(layer "In7.Cu")
		(net "M_C_CPU_VREF")
	)
	(segment
		(start 240.568734 -53.088032)
		(end 240.124742 -52.64404)
		(width 0.2286)
		(layer "In7.Cu")
		(net "M_C_CPU_VREF")
	)
	(segment
		(start 251.923804 -63.019686)
		(end 251.53493 -62.630812)
		(width 0.2286)
		(layer "In7.Cu")
		(net "M_C_CPU_VREF")
	)
	(segment
		(start 241.427254 -53.583332)
		(end 240.931954 -53.088032)
		(width 0.2286)
		(layer "In7.Cu")
		(net "M_C_CPU_VREF")
	)
	(segment
		(start 250.67641 -60.843922)
		(end 250.35002 -60.517532)
		(width 0.2286)
		(layer "In7.Cu")
		(net "M_C_CPU_VREF")
	)
	(segment
		(start 243.507006 -54.573932)
		(end 243.11864 -54.573932)
		(width 0.2286)
		(layer "In7.Cu")
		(net "M_C_CPU_VREF")
	)
	(segment
		(start 233.425492 -52.81295)
		(end 233.066082 -52.45354)
		(width 0.254)
		(layer "In7.Cu")
		(net "M_C_CPU_VREF")
	)
	(segment
		(start 250.35002 -60.517532)
		(end 249.986546 -60.517532)
		(width 0.2286)
		(layer "In7.Cu")
		(net "M_C_CPU_VREF")
	)
	(segment
		(start 245.52529 -56.305704)
		(end 245.52529 -55.890922)
		(width 0.2286)
		(layer "In7.Cu")
		(net "M_C_CPU_VREF")
	)
	(segment
		(start 233.066082 -52.45354)
		(end 232.629964 -52.45354)
		(width 0.254)
		(layer "In7.Cu")
		(net "M_C_CPU_VREF")
	)
	(segment
		(start 244.34038 -55.069486)
		(end 244.00256 -55.069486)
		(width 0.2286)
		(layer "In7.Cu")
		(net "M_C_CPU_VREF")
	)
	(segment
		(start 251.20854 -62.003686)
		(end 250.87072 -62.003686)
		(width 0.2286)
		(layer "In7.Cu")
		(net "M_C_CPU_VREF")
	)
	(segment
		(start 235.832142 -53.088032)
		(end 235.417614 -53.088032)
		(width 0.2286)
		(layer "In7.Cu")
		(net "M_C_CPU_VREF")
	)
	(segment
		(start 246.083074 -57.050686)
		(end 245.7196 -57.050686)
		(width 0.2286)
		(layer "In7.Cu")
		(net "M_C_CPU_VREF")
	)
	(segment
		(start 246.967248 -57.597294)
		(end 246.629682 -57.597294)
		(width 0.2286)
		(layer "In7.Cu")
		(net "M_C_CPU_VREF")
	)
	(segment
		(start 239.266222 -53.088032)
		(end 238.851694 -53.088032)
		(width 0.2286)
		(layer "In7.Cu")
		(net "M_C_CPU_VREF")
	)
	(segment
		(start 245.52529 -55.890922)
		(end 245.1989 -55.564532)
		(width 0.2286)
		(layer "In7.Cu")
		(net "M_C_CPU_VREF")
	)
	(segment
		(start 249.204988 -60.073794)
		(end 248.878598 -59.747404)
		(width 0.2286)
		(layer "In7.Cu")
		(net "M_C_CPU_VREF")
	)
	(segment
		(start 240.931954 -53.088032)
		(end 240.568734 -53.088032)
		(width 0.2286)
		(layer "In7.Cu")
		(net "M_C_CPU_VREF")
	)
	(segment
		(start 249.542808 -60.073794)
		(end 249.204988 -60.073794)
		(width 0.2286)
		(layer "In7.Cu")
		(net "M_C_CPU_VREF")
	)
	(segment
		(start 251.53493 -62.630812)
		(end 251.53493 -62.330076)
		(width 0.2286)
		(layer "In7.Cu")
		(net "M_C_CPU_VREF")
	)
	(segment
		(start 235.417614 -53.088032)
		(end 234.973622 -52.64404)
		(width 0.2286)
		(layer "In7.Cu")
		(net "M_C_CPU_VREF")
	)
	(segment
		(start 250.595638 -61.728604)
		(end 250.595638 -61.313822)
		(width 0.2286)
		(layer "In7.Cu")
		(net "M_C_CPU_VREF")
	)
	(segment
		(start 241.771932 -53.583332)
		(end 241.427254 -53.583332)
		(width 0.2286)
		(layer "In7.Cu")
		(net "M_C_CPU_VREF")
	)
	(segment
		(start 242.318794 -54.130194)
		(end 241.771932 -53.583332)
		(width 0.2286)
		(layer "In7.Cu")
		(net "M_C_CPU_VREF")
	)
	(segment
		(start 239.710214 -52.64404)
		(end 239.266222 -53.088032)
		(width 0.2286)
		(layer "In7.Cu")
		(net "M_C_CPU_VREF")
	)
	(segment
		(start 249.986546 -60.517532)
		(end 249.542808 -60.073794)
		(width 0.2286)
		(layer "In7.Cu")
		(net "M_C_CPU_VREF")
	)
	(segment
		(start 240.124742 -52.64404)
		(end 239.710214 -52.64404)
		(width 0.2286)
		(layer "In7.Cu")
		(net "M_C_CPU_VREF")
	)
	(segment
		(start 234.973622 -52.64404)
		(end 234.559094 -52.64404)
		(width 0.2286)
		(layer "In7.Cu")
		(net "M_C_CPU_VREF")
	)
	(segment
		(start 247.41124 -58.041286)
		(end 246.967248 -57.597294)
		(width 0.2286)
		(layer "In7.Cu")
		(net "M_C_CPU_VREF")
	)
	(segment
		(start 209.155538 -49.299368)
		(end 208.77276 -49.299368)
		(width 0.254)
		(layer "In7.Cu")
		(net "M_C_CPU_VREF")
	)
	(segment
		(start 210.778598 -50.366676)
		(end 209.711544 -49.299622)
		(width 0.254)
		(layer "In7.Cu")
		(net "M_C_CPU_VREF")
	)
	(segment
		(start 247.79986 -58.041286)
		(end 247.41124 -58.041286)
		(width 0.2286)
		(layer "In7.Cu")
		(net "M_C_CPU_VREF")
	)
	(segment
		(start 234.115102 -53.088032)
		(end 233.700574 -53.088032)
		(width 0.2286)
		(layer "In7.Cu")
		(net "M_C_CPU_VREF")
	)
	(segment
		(start 248.878598 -59.358276)
		(end 248.95937 -59.277504)
		(width 0.2286)
		(layer "In7.Cu")
		(net "M_C_CPU_VREF")
	)
	(segment
		(start 248.95937 -59.277504)
		(end 248.95937 -58.862722)
		(width 0.2286)
		(layer "In7.Cu")
		(net "M_C_CPU_VREF")
	)
	(segment
		(start 243.11864 -54.573932)
		(end 242.674902 -54.130194)
		(width 0.2286)
		(layer "In7.Cu")
		(net "M_C_CPU_VREF")
	)
	(segment
		(start 246.629682 -57.597294)
		(end 246.083074 -57.050686)
		(width 0.2286)
		(layer "In7.Cu")
		(net "M_C_CPU_VREF")
	)
	(segment
		(start 245.444518 -56.386476)
		(end 245.52529 -56.305704)
		(width 0.2286)
		(layer "In7.Cu")
		(net "M_C_CPU_VREF")
	)
	(segment
		(start 208.77276 -49.299368)
		(end 206.97063 -47.497238)
		(width 0.254)
		(layer "In7.Cu")
		(net "M_C_CPU_VREF")
	)
	(segment
		(start 245.1989 -55.564532)
		(end 244.835426 -55.564532)
		(width 0.2286)
		(layer "In7.Cu")
		(net "M_C_CPU_VREF")
	)
	(segment
		(start 232.629964 -52.45354)
		(end 230.5431 -50.366676)
		(width 0.254)
		(layer "In7.Cu")
		(net "M_C_CPU_VREF")
	)
	(segment
		(start 245.444518 -56.775604)
		(end 245.444518 -56.386476)
		(width 0.2286)
		(layer "In7.Cu")
		(net "M_C_CPU_VREF")
	)
	(segment
		(start 250.595638 -61.313822)
		(end 250.67641 -61.23305)
		(width 0.2286)
		(layer "In7.Cu")
		(net "M_C_CPU_VREF")
	)
	(segment
		(start 250.87072 -62.003686)
		(end 250.595638 -61.728604)
		(width 0.2286)
		(layer "In7.Cu")
		(net "M_C_CPU_VREF")
	)
	(segment
		(start 244.00256 -55.069486)
		(end 243.507006 -54.573932)
		(width 0.2286)
		(layer "In7.Cu")
		(net "M_C_CPU_VREF")
	)
	(segment
		(start 233.700574 -53.088032)
		(end 233.425492 -52.81295)
		(width 0.2286)
		(layer "In7.Cu")
		(net "M_C_CPU_VREF")
	)
	(segment
		(start 248.878598 -59.747404)
		(end 248.878598 -59.358276)
		(width 0.2286)
		(layer "In7.Cu")
		(net "M_C_CPU_VREF")
	)
	(segment
		(start 195.549774 -11.927078)
		(end 195.58 -11.957304)
		(width 0.381)
		(layer "F.Cu")
		(net "M_B_VREF")
	)
	(segment
		(start 195.58 -11.957304)
		(end 195.58 -12.923012)
		(width 0.381)
		(layer "F.Cu")
		(net "M_B_VREF")
	)
	(segment
		(start 195.550282 -10.422382)
		(end 195.549774 -10.422382)
		(width 0.381)
		(layer "F.Cu")
		(net "M_B_VREF")
	)
	(segment
		(start 195.166488 -12.5095)
		(end 194.564 -12.5095)
		(width 0.4064)
		(layer "F.Cu")
		(net "M_B_VREF")
	)
	(segment
		(start 195.549774 -10.422382)
		(end 195.549774 -11.927078)
		(width 0.381)
		(layer "F.Cu")
		(net "M_B_VREF")
	)
	(segment
		(start 194.564 -12.5095)
		(end 193.675 -12.5095)
		(width 0.4064)
		(layer "F.Cu")
		(net "M_B_VREF")
	)
	(segment
		(start 193.675 -12.5095)
		(end 192.786 -12.5095)
		(width 0.4064)
		(layer "F.Cu")
		(net "M_B_VREF")
	)
	(segment
		(start 195.58 -12.923012)
		(end 195.166488 -12.5095)
		(width 0.4064)
		(layer "F.Cu")
		(net "M_B_VREF")
	)
	(via
		(at 195.549774 -11.927078)
		(size 0.508)
		(drill 0.254)
		(layers "F.Cu" "B.Cu")
		(net "M_B_VREF")
	)
	(segment
		(start 195.550282 -10.623042)
		(end 195.549774 -10.623042)
		(width 0.381)
		(layer "B.Cu")
		(net "M_B_VREF")
	)
	(segment
		(start 195.549774 -11.927078)
		(end 195.549774 -10.623042)
		(width 0.381)
		(layer "B.Cu")
		(net "M_B_VREF")
	)
	(segment
		(start 195.453 -9.061704)
		(end 195.453 -8.122412)
		(width 0.381)
		(layer "B.Cu")
		(net "M_B_VREF")
	)
	(segment
		(start 195.549774 -10.623042)
		(end 195.549774 -9.158478)
		(width 0.381)
		(layer "B.Cu")
		(net "M_B_VREF")
	)
	(segment
		(start 195.549774 -9.158478)
		(end 195.453 -9.061704)
		(width 0.381)
		(layer "B.Cu")
		(net "M_B_VREF")
	)
	(segment
		(start 191.897 -13.3985)
		(end 191.897 -14.0208)
		(width 0.4064)
		(layer "F.Cu")
		(net "M_B_CPU_VREF")
	)
	(segment
		(start 252.495304 -64.010286)
		(end 251.923804 -64.010286)
		(width 0.254)
		(layer "F.Cu")
		(net "M_B_CPU_VREF")
	)
	(segment
		(start 192.786 -13.3985)
		(end 191.897 -13.3985)
		(width 0.4064)
		(layer "F.Cu")
		(net "M_B_CPU_VREF")
	)
	(via
		(at 203.10348 -47.382938)
		(size 0.508)
		(drill 0.254)
		(layers "F.Cu" "B.Cu")
		(net "M_B_CPU_VREF")
	)
	(via
		(at 191.897 -14.0208)
		(size 0.508)
		(drill 0.254)
		(layers "F.Cu" "B.Cu")
		(net "M_B_CPU_VREF")
	)
	(via
		(at 251.923804 -64.010286)
		(size 0.508)
		(drill 0.254)
		(layers "F.Cu" "B.Cu")
		(net "M_B_CPU_VREF")
	)
	(segment
		(start 192.151 -22.9616)
		(end 192.4304 -22.6822)
		(width 0.254)
		(layer "In2.Cu")
		(net "M_B_CPU_VREF")
	)
	(segment
		(start 192.151 -20.4216)
		(end 192.151 -14.2748)
		(width 0.254)
		(layer "In2.Cu")
		(net "M_B_CPU_VREF")
	)
	(segment
		(start 192.151 -24.468074)
		(end 192.151 -22.9616)
		(width 0.254)
		(layer "In2.Cu")
		(net "M_B_CPU_VREF")
	)
	(segment
		(start 192.7606 -25.077674)
		(end 192.151 -24.468074)
		(width 0.254)
		(layer "In2.Cu")
		(net "M_B_CPU_VREF")
	)
	(segment
		(start 203.523088 -46.96333)
		(end 203.523088 -46.043088)
		(width 0.254)
		(layer "In2.Cu")
		(net "M_B_CPU_VREF")
	)
	(segment
		(start 192.4304 -22.6822)
		(end 192.4304 -20.701)
		(width 0.254)
		(layer "In2.Cu")
		(net "M_B_CPU_VREF")
	)
	(segment
		(start 203.523088 -46.043088)
		(end 192.7606 -35.2806)
		(width 0.254)
		(layer "In2.Cu")
		(net "M_B_CPU_VREF")
	)
	(segment
		(start 192.7606 -35.2806)
		(end 192.7606 -25.077674)
		(width 0.254)
		(layer "In2.Cu")
		(net "M_B_CPU_VREF")
	)
	(segment
		(start 192.151 -14.2748)
		(end 191.897 -14.0208)
		(width 0.254)
		(layer "In2.Cu")
		(net "M_B_CPU_VREF")
	)
	(segment
		(start 203.10348 -47.382938)
		(end 203.523088 -46.96333)
		(width 0.254)
		(layer "In2.Cu")
		(net "M_B_CPU_VREF")
	)
	(segment
		(start 192.4304 -20.701)
		(end 192.151 -20.4216)
		(width 0.254)
		(layer "In2.Cu")
		(net "M_B_CPU_VREF")
	)
	(segment
		(start 248.020078 -59.853322)
		(end 248.020078 -60.24245)
		(width 0.2286)
		(layer "In7.Cu")
		(net "M_B_CPU_VREF")
	)
	(segment
		(start 237.993174 -53.63464)
		(end 238.407448 -53.63464)
		(width 0.2286)
		(layer "In7.Cu")
		(net "M_B_CPU_VREF")
	)
	(segment
		(start 243.11864 -55.564532)
		(end 243.507006 -55.564532)
		(width 0.2286)
		(layer "In7.Cu")
		(net "M_B_CPU_VREF")
	)
	(segment
		(start 242.674902 -55.120794)
		(end 243.11864 -55.564532)
		(width 0.2286)
		(layer "In7.Cu")
		(net "M_B_CPU_VREF")
	)
	(segment
		(start 249.81789 -61.75375)
		(end 249.737118 -61.834522)
		(width 0.2286)
		(layer "In7.Cu")
		(net "M_B_CPU_VREF")
	)
	(segment
		(start 242.311936 -55.120794)
		(end 242.674902 -55.120794)
		(width 0.2286)
		(layer "In7.Cu")
		(net "M_B_CPU_VREF")
	)
	(segment
		(start 249.542808 -61.064394)
		(end 249.81789 -61.339476)
		(width 0.2286)
		(layer "In7.Cu")
		(net "M_B_CPU_VREF")
	)
	(segment
		(start 237.134654 -54.078886)
		(end 237.548928 -54.078886)
		(width 0.2286)
		(layer "In7.Cu")
		(net "M_B_CPU_VREF")
	)
	(segment
		(start 244.66677 -56.775604)
		(end 244.585998 -56.856376)
		(width 0.2286)
		(layer "In7.Cu")
		(net "M_B_CPU_VREF")
	)
	(segment
		(start 233.6292 -54.078886)
		(end 234.114848 -54.078886)
		(width 0.2286)
		(layer "In7.Cu")
		(net "M_B_CPU_VREF")
	)
	(segment
		(start 234.114848 -54.078886)
		(end 234.559094 -53.63464)
		(width 0.2286)
		(layer "In7.Cu")
		(net "M_B_CPU_VREF")
	)
	(segment
		(start 246.629174 -58.58764)
		(end 246.967248 -58.58764)
		(width 0.2286)
		(layer "In7.Cu")
		(net "M_B_CPU_VREF")
	)
	(segment
		(start 244.912642 -57.597294)
		(end 245.250208 -57.597294)
		(width 0.2286)
		(layer "In7.Cu")
		(net "M_B_CPU_VREF")
	)
	(segment
		(start 249.737118 -62.22365)
		(end 250.063508 -62.55004)
		(width 0.2286)
		(layer "In7.Cu")
		(net "M_B_CPU_VREF")
	)
	(segment
		(start 244.66677 -56.386476)
		(end 244.66677 -56.775604)
		(width 0.2286)
		(layer "In7.Cu")
		(net "M_B_CPU_VREF")
	)
	(segment
		(start 250.896882 -63.045594)
		(end 251.259848 -63.045594)
		(width 0.2286)
		(layer "In7.Cu")
		(net "M_B_CPU_VREF")
	)
	(segment
		(start 248.020078 -60.24245)
		(end 248.29516 -60.517532)
		(width 0.2286)
		(layer "In7.Cu")
		(net "M_B_CPU_VREF")
	)
	(segment
		(start 234.973368 -53.63464)
		(end 235.417614 -54.078886)
		(width 0.2286)
		(layer "In7.Cu")
		(net "M_B_CPU_VREF")
	)
	(segment
		(start 236.276134 -53.63464)
		(end 236.690408 -53.63464)
		(width 0.2286)
		(layer "In7.Cu")
		(net "M_B_CPU_VREF")
	)
	(segment
		(start 251.923804 -63.70955)
		(end 251.923804 -64.010286)
		(width 0.2286)
		(layer "In7.Cu")
		(net "M_B_CPU_VREF")
	)
	(segment
		(start 249.737118 -61.834522)
		(end 249.737118 -62.22365)
		(width 0.2286)
		(layer "In7.Cu")
		(net "M_B_CPU_VREF")
	)
	(segment
		(start 209.395822 -50.061622)
		(end 210.462876 -51.128676)
		(width 0.254)
		(layer "In7.Cu")
		(net "M_B_CPU_VREF")
	)
	(segment
		(start 247.825768 -59.083194)
		(end 248.10085 -59.358276)
		(width 0.2286)
		(layer "In7.Cu")
		(net "M_B_CPU_VREF")
	)
	(segment
		(start 230.2002 -51.128676)
		(end 230.564944 -51.49342)
		(width 0.254)
		(layer "In7.Cu")
		(net "M_B_CPU_VREF")
	)
	(segment
		(start 238.407448 -53.63464)
		(end 238.851694 -54.078886)
		(width 0.2286)
		(layer "In7.Cu")
		(net "M_B_CPU_VREF")
	)
	(segment
		(start 244.053868 -56.111394)
		(end 244.391688 -56.111394)
		(width 0.2286)
		(layer "In7.Cu")
		(net "M_B_CPU_VREF")
	)
	(segment
		(start 244.585998 -56.856376)
		(end 244.585998 -57.27065)
		(width 0.2286)
		(layer "In7.Cu")
		(net "M_B_CPU_VREF")
	)
	(segment
		(start 247.462802 -59.083194)
		(end 247.825768 -59.083194)
		(width 0.2286)
		(layer "In7.Cu")
		(net "M_B_CPU_VREF")
	)
	(segment
		(start 230.564944 -51.49342)
		(end 230.58882 -51.49342)
		(width 0.254)
		(layer "In7.Cu")
		(net "M_B_CPU_VREF")
	)
	(segment
		(start 246.08282 -58.041286)
		(end 246.629174 -58.58764)
		(width 0.2286)
		(layer "In7.Cu")
		(net "M_B_CPU_VREF")
	)
	(segment
		(start 245.250208 -57.597294)
		(end 245.6942 -58.041286)
		(width 0.2286)
		(layer "In7.Cu")
		(net "M_B_CPU_VREF")
	)
	(segment
		(start 241.765074 -54.573932)
		(end 242.311936 -55.120794)
		(width 0.2286)
		(layer "In7.Cu")
		(net "M_B_CPU_VREF")
	)
	(segment
		(start 237.548928 -54.078886)
		(end 237.993174 -53.63464)
		(width 0.2286)
		(layer "In7.Cu")
		(net "M_B_CPU_VREF")
	)
	(segment
		(start 250.063508 -62.55004)
		(end 250.401328 -62.55004)
		(width 0.2286)
		(layer "In7.Cu")
		(net "M_B_CPU_VREF")
	)
	(segment
		(start 249.81789 -61.339476)
		(end 249.81789 -61.75375)
		(width 0.2286)
		(layer "In7.Cu")
		(net "M_B_CPU_VREF")
	)
	(segment
		(start 243.507006 -55.564532)
		(end 244.053868 -56.111394)
		(width 0.2286)
		(layer "In7.Cu")
		(net "M_B_CPU_VREF")
	)
	(segment
		(start 251.259848 -63.045594)
		(end 251.923804 -63.70955)
		(width 0.2286)
		(layer "In7.Cu")
		(net "M_B_CPU_VREF")
	)
	(segment
		(start 248.29516 -60.517532)
		(end 248.658126 -60.517532)
		(width 0.2286)
		(layer "In7.Cu")
		(net "M_B_CPU_VREF")
	)
	(segment
		(start 233.174286 -54.078886)
		(end 233.6292 -54.078886)
		(width 0.254)
		(layer "In7.Cu")
		(net "M_B_CPU_VREF")
	)
	(segment
		(start 208.187036 -50.061622)
		(end 209.395822 -50.061622)
		(width 0.254)
		(layer "In7.Cu")
		(net "M_B_CPU_VREF")
	)
	(segment
		(start 238.851694 -54.078886)
		(end 239.265968 -54.078886)
		(width 0.2286)
		(layer "In7.Cu")
		(net "M_B_CPU_VREF")
	)
	(segment
		(start 249.204988 -61.064394)
		(end 249.542808 -61.064394)
		(width 0.2286)
		(layer "In7.Cu")
		(net "M_B_CPU_VREF")
	)
	(segment
		(start 234.559094 -53.63464)
		(end 234.973368 -53.63464)
		(width 0.2286)
		(layer "In7.Cu")
		(net "M_B_CPU_VREF")
	)
	(segment
		(start 235.417614 -54.078886)
		(end 235.831888 -54.078886)
		(width 0.2286)
		(layer "In7.Cu")
		(net "M_B_CPU_VREF")
	)
	(segment
		(start 248.10085 -59.358276)
		(end 248.10085 -59.772296)
		(width 0.2286)
		(layer "In7.Cu")
		(net "M_B_CPU_VREF")
	)
	(segment
		(start 204.00772 -48.287178)
		(end 206.412592 -48.287178)
		(width 0.254)
		(layer "In7.Cu")
		(net "M_B_CPU_VREF")
	)
	(segment
		(start 230.58882 -51.49342)
		(end 233.174286 -54.078886)
		(width 0.254)
		(layer "In7.Cu")
		(net "M_B_CPU_VREF")
	)
	(segment
		(start 203.10348 -47.382938)
		(end 204.00772 -48.287178)
		(width 0.254)
		(layer "In7.Cu")
		(net "M_B_CPU_VREF")
	)
	(segment
		(start 235.831888 -54.078886)
		(end 236.276134 -53.63464)
		(width 0.2286)
		(layer "In7.Cu")
		(net "M_B_CPU_VREF")
	)
	(segment
		(start 245.6942 -58.041286)
		(end 246.08282 -58.041286)
		(width 0.2286)
		(layer "In7.Cu")
		(net "M_B_CPU_VREF")
	)
	(segment
		(start 239.710214 -53.63464)
		(end 240.124488 -53.63464)
		(width 0.2286)
		(layer "In7.Cu")
		(net "M_B_CPU_VREF")
	)
	(segment
		(start 206.412592 -48.287178)
		(end 208.187036 -50.061622)
		(width 0.254)
		(layer "In7.Cu")
		(net "M_B_CPU_VREF")
	)
	(segment
		(start 236.690408 -53.63464)
		(end 237.134654 -54.078886)
		(width 0.2286)
		(layer "In7.Cu")
		(net "M_B_CPU_VREF")
	)
	(segment
		(start 240.568734 -54.078886)
		(end 240.932208 -54.078886)
		(width 0.2286)
		(layer "In7.Cu")
		(net "M_B_CPU_VREF")
	)
	(segment
		(start 248.10085 -59.772296)
		(end 248.020078 -59.853322)
		(width 0.2286)
		(layer "In7.Cu")
		(net "M_B_CPU_VREF")
	)
	(segment
		(start 244.585998 -57.27065)
		(end 244.912642 -57.597294)
		(width 0.2286)
		(layer "In7.Cu")
		(net "M_B_CPU_VREF")
	)
	(segment
		(start 239.265968 -54.078886)
		(end 239.710214 -53.63464)
		(width 0.2286)
		(layer "In7.Cu")
		(net "M_B_CPU_VREF")
	)
	(segment
		(start 248.658126 -60.517532)
		(end 249.204988 -61.064394)
		(width 0.2286)
		(layer "In7.Cu")
		(net "M_B_CPU_VREF")
	)
	(segment
		(start 210.462876 -51.128676)
		(end 230.2002 -51.128676)
		(width 0.254)
		(layer "In7.Cu")
		(net "M_B_CPU_VREF")
	)
	(segment
		(start 240.124488 -53.63464)
		(end 240.568734 -54.078886)
		(width 0.2286)
		(layer "In7.Cu")
		(net "M_B_CPU_VREF")
	)
	(segment
		(start 241.427254 -54.573932)
		(end 241.765074 -54.573932)
		(width 0.2286)
		(layer "In7.Cu")
		(net "M_B_CPU_VREF")
	)
	(segment
		(start 244.391688 -56.111394)
		(end 244.66677 -56.386476)
		(width 0.2286)
		(layer "In7.Cu")
		(net "M_B_CPU_VREF")
	)
	(segment
		(start 240.932208 -54.078886)
		(end 241.427254 -54.573932)
		(width 0.2286)
		(layer "In7.Cu")
		(net "M_B_CPU_VREF")
	)
	(segment
		(start 250.401328 -62.55004)
		(end 250.896882 -63.045594)
		(width 0.2286)
		(layer "In7.Cu")
		(net "M_B_CPU_VREF")
	)
	(segment
		(start 246.967248 -58.58764)
		(end 247.462802 -59.083194)
		(width 0.2286)
		(layer "In7.Cu")
		(net "M_B_CPU_VREF")
	)
	(segment
		(start 195.550282 -20.023582)
		(end 195.549774 -20.023582)
		(width 0.381)
		(layer "F.Cu")
		(net "M_A_VREF")
	)
	(segment
		(start 193.675 -22.507194)
		(end 194.564 -22.507194)
		(width 0.4064)
		(layer "F.Cu")
		(net "M_A_VREF")
	)
	(segment
		(start 192.786 -22.507194)
		(end 193.675 -22.507194)
		(width 0.4064)
		(layer "F.Cu")
		(net "M_A_VREF")
	)
	(segment
		(start 194.564 -22.507194)
		(end 195.481194 -22.507194)
		(width 0.4064)
		(layer "F.Cu")
		(net "M_A_VREF")
	)
	(segment
		(start 195.453 -21.5138)
		(end 195.58 -21.6408)
		(width 0.381)
		(layer "F.Cu")
		(net "M_A_VREF")
	)
	(segment
		(start 195.481194 -22.507194)
		(end 195.58 -22.606)
		(width 0.4064)
		(layer "F.Cu")
		(net "M_A_VREF")
	)
	(segment
		(start 195.58 -21.6408)
		(end 195.58 -22.606)
		(width 0.381)
		(layer "F.Cu")
		(net "M_A_VREF")
	)
	(segment
		(start 195.549774 -20.023582)
		(end 195.549774 -21.417026)
		(width 0.381)
		(layer "F.Cu")
		(net "M_A_VREF")
	)
	(segment
		(start 195.549774 -21.417026)
		(end 195.453 -21.5138)
		(width 0.381)
		(layer "F.Cu")
		(net "M_A_VREF")
	)
	(via
		(at 195.453 -21.5138)
		(size 0.508)
		(drill 0.254)
		(layers "F.Cu" "B.Cu")
		(net "M_A_VREF")
	)
	(segment
		(start 195.453 -18.7452)
		(end 195.549774 -18.841974)
		(width 0.381)
		(layer "B.Cu")
		(net "M_A_VREF")
	)
	(segment
		(start 195.549774 -18.841974)
		(end 195.549774 -20.224242)
		(width 0.381)
		(layer "B.Cu")
		(net "M_A_VREF")
	)
	(segment
		(start 195.549774 -20.224242)
		(end 195.550282 -20.224242)
		(width 0.381)
		(layer "B.Cu")
		(net "M_A_VREF")
	)
	(segment
		(start 195.453 -17.723612)
		(end 195.453 -18.7452)
		(width 0.381)
		(layer "B.Cu")
		(net "M_A_VREF")
	)
	(segment
		(start 195.549774 -21.417026)
		(end 195.549774 -20.224242)
		(width 0.381)
		(layer "B.Cu")
		(net "M_A_VREF")
	)
	(segment
		(start 195.453 -21.5138)
		(end 195.549774 -21.417026)
		(width 0.381)
		(layer "B.Cu")
		(net "M_A_VREF")
	)
	(segment
		(start 412.0388 -45.1358)
		(end 412.257748 -44.916852)
		(width 0.089408)
		(layer "F.Cu")
		(net "IRQ_BMC_PCH_SMI_LPC_N")
	)
	(segment
		(start 402.136864 -109.099604)
		(end 402.58873 -109.099604)
		(width 0.0889)
		(layer "F.Cu")
		(net "IRQ_BMC_PCH_SMI_LPC_N")
	)
	(segment
		(start 412.0388 -45.163486)
		(end 412.0388 -45.1358)
		(width 0.089408)
		(layer "F.Cu")
		(net "IRQ_BMC_PCH_SMI_LPC_N")
	)
	(segment
		(start 391.69975 -117.58168)
		(end 392.19505 -117.811804)
		(width 0.10795)
		(layer "F.Cu")
		(net "IRQ_BMC_PCH_SMI_LPC_N")
	)
	(segment
		(start 412.584646 -44.916852)
		(end 413.118046 -44.383452)
		(width 0.089408)
		(layer "F.Cu")
		(net "IRQ_BMC_PCH_SMI_LPC_N")
	)
	(segment
		(start 402.58873 -109.099604)
		(end 402.71319 -108.975144)
		(width 0.0889)
		(layer "F.Cu")
		(net "IRQ_BMC_PCH_SMI_LPC_N")
	)
	(segment
		(start 412.257748 -44.916852)
		(end 412.584646 -44.916852)
		(width 0.089408)
		(layer "F.Cu")
		(net "IRQ_BMC_PCH_SMI_LPC_N")
	)
	(segment
		(start 413.118046 -42.962576)
		(end 412.690056 -42.534586)
		(width 0.089408)
		(layer "F.Cu")
		(net "IRQ_BMC_PCH_SMI_LPC_N")
	)
	(segment
		(start 401.41398 -108.973874)
		(end 402.011134 -108.973874)
		(width 0.0889)
		(layer "F.Cu")
		(net "IRQ_BMC_PCH_SMI_LPC_N")
	)
	(segment
		(start 403.180296 -108.975144)
		(end 405.34463 -108.975144)
		(width 0.10795)
		(layer "F.Cu")
		(net "IRQ_BMC_PCH_SMI_LPC_N")
	)
	(segment
		(start 402.011134 -108.973874)
		(end 402.136864 -109.099604)
		(width 0.0889)
		(layer "F.Cu")
		(net "IRQ_BMC_PCH_SMI_LPC_N")
	)
	(segment
		(start 407.162 -110.617)
		(end 407.8605 -110.617)
		(width 0.10795)
		(layer "F.Cu")
		(net "IRQ_BMC_PCH_SMI_LPC_N")
	)
	(segment
		(start 402.71319 -108.975144)
		(end 403.180296 -108.975144)
		(width 0.0889)
		(layer "F.Cu")
		(net "IRQ_BMC_PCH_SMI_LPC_N")
	)
	(segment
		(start 412.043118 -45.163486)
		(end 412.0388 -45.163486)
		(width 0.089408)
		(layer "F.Cu")
		(net "IRQ_BMC_PCH_SMI_LPC_N")
	)
	(segment
		(start 413.118046 -44.383452)
		(end 413.118046 -42.962576)
		(width 0.089408)
		(layer "F.Cu")
		(net "IRQ_BMC_PCH_SMI_LPC_N")
	)
	(segment
		(start 405.34463 -108.975144)
		(end 406.974548 -110.605062)
		(width 0.10795)
		(layer "F.Cu")
		(net "IRQ_BMC_PCH_SMI_LPC_N")
	)
	(segment
		(start 406.974548 -110.605062)
		(end 406.974548 -110.617)
		(width 0.10795)
		(layer "F.Cu")
		(net "IRQ_BMC_PCH_SMI_LPC_N")
	)
	(segment
		(start 406.974548 -110.617)
		(end 407.162 -110.617)
		(width 0.10795)
		(layer "F.Cu")
		(net "IRQ_BMC_PCH_SMI_LPC_N")
	)
	(segment
		(start 401.295108 -108.855002)
		(end 401.41398 -108.973874)
		(width 0.0889)
		(layer "F.Cu")
		(net "IRQ_BMC_PCH_SMI_LPC_N")
	)
	(via
		(at 411.469332 -52.487322)
		(size 0.6604)
		(drill 0.3302)
		(layers "F.Cu" "B.Cu")
		(net "IRQ_BMC_PCH_SMI_LPC_N")
	)
	(via
		(at 407.162 -110.617)
		(size 0.508)
		(drill 0.254)
		(layers "F.Cu" "B.Cu")
		(net "IRQ_BMC_PCH_SMI_LPC_N")
	)
	(via
		(at 412.043118 -45.163486)
		(size 0.4572)
		(drill 0.2032)
		(layers "F.Cu" "B.Cu")
		(net "IRQ_BMC_PCH_SMI_LPC_N")
	)
	(via
		(at 392.19505 -117.811804)
		(size 0.508)
		(drill 0.254)
		(layers "F.Cu" "B.Cu")
		(net "IRQ_BMC_PCH_SMI_LPC_N")
	)
	(via
		(at 410.301948 -54.230778)
		(size 0.508)
		(drill 0.254)
		(layers "F.Cu" "B.Cu")
		(net "IRQ_BMC_PCH_SMI_LPC_N")
	)
	(segment
		(start 412.787846 -47.460662)
		(end 412.787846 -51.168808)
		(width 0.10795)
		(layer "B.Cu")
		(net "IRQ_BMC_PCH_SMI_LPC_N")
	)
	(segment
		(start 412.463488 -46.748192)
		(end 412.463488 -47.136304)
		(width 0.10795)
		(layer "B.Cu")
		(net "IRQ_BMC_PCH_SMI_LPC_N")
	)
	(segment
		(start 412.043118 -45.163486)
		(end 412.043118 -46.327822)
		(width 0.10795)
		(layer "B.Cu")
		(net "IRQ_BMC_PCH_SMI_LPC_N")
	)
	(segment
		(start 412.787846 -51.168808)
		(end 411.469332 -52.487322)
		(width 0.10795)
		(layer "B.Cu")
		(net "IRQ_BMC_PCH_SMI_LPC_N")
	)
	(segment
		(start 410.301948 -53.654706)
		(end 410.301948 -54.230778)
		(width 0.10795)
		(layer "B.Cu")
		(net "IRQ_BMC_PCH_SMI_LPC_N")
	)
	(segment
		(start 412.043118 -46.327822)
		(end 412.463488 -46.748192)
		(width 0.10795)
		(layer "B.Cu")
		(net "IRQ_BMC_PCH_SMI_LPC_N")
	)
	(segment
		(start 411.469332 -52.487322)
		(end 410.301948 -53.654706)
		(width 0.10795)
		(layer "B.Cu")
		(net "IRQ_BMC_PCH_SMI_LPC_N")
	)
	(segment
		(start 412.463488 -47.136304)
		(end 412.787846 -47.460662)
		(width 0.10795)
		(layer "B.Cu")
		(net "IRQ_BMC_PCH_SMI_LPC_N")
	)
	(segment
		(start 403.981412 -83.315048)
		(end 402.834348 -82.167984)
		(width 0.089408)
		(layer "In2.Cu")
		(net "IRQ_BMC_PCH_SMI_LPC_N")
	)
	(segment
		(start 402.259292 -92.205048)
		(end 402.259292 -88.676988)
		(width 0.089408)
		(layer "In2.Cu")
		(net "IRQ_BMC_PCH_SMI_LPC_N")
	)
	(segment
		(start 402.7678 -100.5078)
		(end 402.4376 -100.1776)
		(width 0.089408)
		(layer "In2.Cu")
		(net "IRQ_BMC_PCH_SMI_LPC_N")
	)
	(segment
		(start 402.834348 -82.167984)
		(end 402.834348 -81.04886)
		(width 0.089408)
		(layer "In2.Cu")
		(net "IRQ_BMC_PCH_SMI_LPC_N")
	)
	(segment
		(start 402.772626 -92.718382)
		(end 402.259292 -92.205048)
		(width 0.089408)
		(layer "In2.Cu")
		(net "IRQ_BMC_PCH_SMI_LPC_N")
	)
	(segment
		(start 409.906724 -68.201794)
		(end 409.906724 -55.751476)
		(width 0.089408)
		(layer "In2.Cu")
		(net "IRQ_BMC_PCH_SMI_LPC_N")
	)
	(segment
		(start 403.58314 -74.847196)
		(end 404.22195 -74.208386)
		(width 0.089408)
		(layer "In2.Cu")
		(net "IRQ_BMC_PCH_SMI_LPC_N")
	)
	(segment
		(start 403.15896 -87.77732)
		(end 403.857714 -87.77732)
		(width 0.089408)
		(layer "In2.Cu")
		(net "IRQ_BMC_PCH_SMI_LPC_N")
	)
	(segment
		(start 404.5966 -106.0196)
		(end 404.5966 -104.6734)
		(width 0.089408)
		(layer "In2.Cu")
		(net "IRQ_BMC_PCH_SMI_LPC_N")
	)
	(segment
		(start 404.5966 -104.6734)
		(end 404.8506 -104.4194)
		(width 0.089408)
		(layer "In2.Cu")
		(net "IRQ_BMC_PCH_SMI_LPC_N")
	)
	(segment
		(start 402.834348 -81.04886)
		(end 403.131528 -80.75168)
		(width 0.089408)
		(layer "In2.Cu")
		(net "IRQ_BMC_PCH_SMI_LPC_N")
	)
	(segment
		(start 403.402292 -100.5078)
		(end 402.7678 -100.5078)
		(width 0.089408)
		(layer "In2.Cu")
		(net "IRQ_BMC_PCH_SMI_LPC_N")
	)
	(segment
		(start 404.22195 -73.886568)
		(end 409.906724 -68.201794)
		(width 0.089408)
		(layer "In2.Cu")
		(net "IRQ_BMC_PCH_SMI_LPC_N")
	)
	(segment
		(start 404.30831 -83.315048)
		(end 403.981412 -83.315048)
		(width 0.089408)
		(layer "In2.Cu")
		(net "IRQ_BMC_PCH_SMI_LPC_N")
	)
	(segment
		(start 403.671786 -100.777294)
		(end 403.402292 -100.5078)
		(width 0.089408)
		(layer "In2.Cu")
		(net "IRQ_BMC_PCH_SMI_LPC_N")
	)
	(segment
		(start 404.878032 -83.88477)
		(end 404.30831 -83.315048)
		(width 0.089408)
		(layer "In2.Cu")
		(net "IRQ_BMC_PCH_SMI_LPC_N")
	)
	(segment
		(start 409.906724 -55.751476)
		(end 410.301948 -55.356252)
		(width 0.089408)
		(layer "In2.Cu")
		(net "IRQ_BMC_PCH_SMI_LPC_N")
	)
	(segment
		(start 404.5204 -103.4288)
		(end 404.5204 -102.489)
		(width 0.089408)
		(layer "In2.Cu")
		(net "IRQ_BMC_PCH_SMI_LPC_N")
	)
	(segment
		(start 402.772626 -99.334574)
		(end 402.772626 -92.718382)
		(width 0.089408)
		(layer "In2.Cu")
		(net "IRQ_BMC_PCH_SMI_LPC_N")
	)
	(segment
		(start 403.58314 -76.725018)
		(end 403.58314 -74.847196)
		(width 0.089408)
		(layer "In2.Cu")
		(net "IRQ_BMC_PCH_SMI_LPC_N")
	)
	(segment
		(start 403.857714 -87.77732)
		(end 404.878032 -86.757002)
		(width 0.089408)
		(layer "In2.Cu")
		(net "IRQ_BMC_PCH_SMI_LPC_N")
	)
	(segment
		(start 402.4376 -99.6696)
		(end 402.772626 -99.334574)
		(width 0.089408)
		(layer "In2.Cu")
		(net "IRQ_BMC_PCH_SMI_LPC_N")
	)
	(segment
		(start 404.878032 -86.757002)
		(end 404.878032 -83.88477)
		(width 0.089408)
		(layer "In2.Cu")
		(net "IRQ_BMC_PCH_SMI_LPC_N")
	)
	(segment
		(start 404.22195 -74.208386)
		(end 404.22195 -73.886568)
		(width 0.089408)
		(layer "In2.Cu")
		(net "IRQ_BMC_PCH_SMI_LPC_N")
	)
	(segment
		(start 402.488146 -77.978)
		(end 402.488146 -77.820012)
		(width 0.089408)
		(layer "In2.Cu")
		(net "IRQ_BMC_PCH_SMI_LPC_N")
	)
	(segment
		(start 402.4884 -78.580488)
		(end 402.4884 -77.978254)
		(width 0.089408)
		(layer "In2.Cu")
		(net "IRQ_BMC_PCH_SMI_LPC_N")
	)
	(segment
		(start 404.8506 -104.4194)
		(end 404.8506 -103.759)
		(width 0.089408)
		(layer "In2.Cu")
		(net "IRQ_BMC_PCH_SMI_LPC_N")
	)
	(segment
		(start 402.4884 -77.978254)
		(end 402.488146 -77.978)
		(width 0.089408)
		(layer "In2.Cu")
		(net "IRQ_BMC_PCH_SMI_LPC_N")
	)
	(segment
		(start 402.4376 -100.1776)
		(end 402.4376 -99.6696)
		(width 0.089408)
		(layer "In2.Cu")
		(net "IRQ_BMC_PCH_SMI_LPC_N")
	)
	(segment
		(start 403.671786 -101.640386)
		(end 403.671786 -100.777294)
		(width 0.089408)
		(layer "In2.Cu")
		(net "IRQ_BMC_PCH_SMI_LPC_N")
	)
	(segment
		(start 402.488146 -77.820012)
		(end 403.58314 -76.725018)
		(width 0.089408)
		(layer "In2.Cu")
		(net "IRQ_BMC_PCH_SMI_LPC_N")
	)
	(segment
		(start 404.5204 -102.489)
		(end 403.671786 -101.640386)
		(width 0.089408)
		(layer "In2.Cu")
		(net "IRQ_BMC_PCH_SMI_LPC_N")
	)
	(segment
		(start 403.131528 -79.223616)
		(end 402.4884 -78.580488)
		(width 0.089408)
		(layer "In2.Cu")
		(net "IRQ_BMC_PCH_SMI_LPC_N")
	)
	(segment
		(start 406.438608 -109.893608)
		(end 406.438608 -107.861608)
		(width 0.089408)
		(layer "In2.Cu")
		(net "IRQ_BMC_PCH_SMI_LPC_N")
	)
	(segment
		(start 407.162 -110.617)
		(end 406.438608 -109.893608)
		(width 0.089408)
		(layer "In2.Cu")
		(net "IRQ_BMC_PCH_SMI_LPC_N")
	)
	(segment
		(start 403.131528 -80.75168)
		(end 403.131528 -79.223616)
		(width 0.089408)
		(layer "In2.Cu")
		(net "IRQ_BMC_PCH_SMI_LPC_N")
	)
	(segment
		(start 404.8506 -103.759)
		(end 404.5204 -103.4288)
		(width 0.089408)
		(layer "In2.Cu")
		(net "IRQ_BMC_PCH_SMI_LPC_N")
	)
	(segment
		(start 402.259292 -88.676988)
		(end 403.15896 -87.77732)
		(width 0.089408)
		(layer "In2.Cu")
		(net "IRQ_BMC_PCH_SMI_LPC_N")
	)
	(segment
		(start 410.301948 -55.356252)
		(end 410.301948 -54.230778)
		(width 0.089408)
		(layer "In2.Cu")
		(net "IRQ_BMC_PCH_SMI_LPC_N")
	)
	(segment
		(start 406.438608 -107.861608)
		(end 404.5966 -106.0196)
		(width 0.089408)
		(layer "In2.Cu")
		(net "IRQ_BMC_PCH_SMI_LPC_N")
	)
	(segment
		(start 404.563326 -118.29542)
		(end 407.776172 -115.082574)
		(width 0.0889)
		(layer "In4.Cu")
		(net "IRQ_BMC_PCH_SMI_LPC_N")
	)
	(segment
		(start 400.1262 -118.29542)
		(end 404.563326 -118.29542)
		(width 0.0889)
		(layer "In4.Cu")
		(net "IRQ_BMC_PCH_SMI_LPC_N")
	)
	(segment
		(start 398.428718 -117.538246)
		(end 399.369026 -117.538246)
		(width 0.0889)
		(layer "In4.Cu")
		(net "IRQ_BMC_PCH_SMI_LPC_N")
	)
	(segment
		(start 397.197834 -116.910612)
		(end 397.197834 -117.183154)
		(width 0.0889)
		(layer "In4.Cu")
		(net "IRQ_BMC_PCH_SMI_LPC_N")
	)
	(segment
		(start 407.5684 -111.0234)
		(end 407.162 -110.617)
		(width 0.0889)
		(layer "In4.Cu")
		(net "IRQ_BMC_PCH_SMI_LPC_N")
	)
	(segment
		(start 393.281154 -116.973858)
		(end 393.281154 -116.941092)
		(width 0.089408)
		(layer "In4.Cu")
		(net "IRQ_BMC_PCH_SMI_LPC_N")
	)
	(segment
		(start 392.36396 -117.518942)
		(end 392.453368 -117.495066)
		(width 0.089408)
		(layer "In4.Cu")
		(net "IRQ_BMC_PCH_SMI_LPC_N")
	)
	(segment
		(start 407.776172 -115.082574)
		(end 409.097226 -115.082574)
		(width 0.0889)
		(layer "In4.Cu")
		(net "IRQ_BMC_PCH_SMI_LPC_N")
	)
	(segment
		(start 396.515844 -116.524786)
		(end 396.812008 -116.524786)
		(width 0.0889)
		(layer "In4.Cu")
		(net "IRQ_BMC_PCH_SMI_LPC_N")
	)
	(segment
		(start 410.5148 -113.665)
		(end 410.5148 -111.658146)
		(width 0.0889)
		(layer "In4.Cu")
		(net "IRQ_BMC_PCH_SMI_LPC_N")
	)
	(segment
		(start 396.412466 -116.628164)
		(end 396.515844 -116.524786)
		(width 0.0889)
		(layer "In4.Cu")
		(net "IRQ_BMC_PCH_SMI_LPC_N")
	)
	(segment
		(start 392.19505 -117.811804)
		(end 392.36396 -117.518942)
		(width 0.089408)
		(layer "In4.Cu")
		(net "IRQ_BMC_PCH_SMI_LPC_N")
	)
	(segment
		(start 396.812008 -116.524786)
		(end 397.197834 -116.910612)
		(width 0.0889)
		(layer "In4.Cu")
		(net "IRQ_BMC_PCH_SMI_LPC_N")
	)
	(segment
		(start 399.369026 -117.538246)
		(end 400.1262 -118.29542)
		(width 0.0889)
		(layer "In4.Cu")
		(net "IRQ_BMC_PCH_SMI_LPC_N")
	)
	(segment
		(start 410.5148 -111.658146)
		(end 409.880054 -111.0234)
		(width 0.0889)
		(layer "In4.Cu")
		(net "IRQ_BMC_PCH_SMI_LPC_N")
	)
	(segment
		(start 397.427958 -117.413278)
		(end 398.30375 -117.413278)
		(width 0.0889)
		(layer "In4.Cu")
		(net "IRQ_BMC_PCH_SMI_LPC_N")
	)
	(segment
		(start 409.880054 -111.0234)
		(end 407.5684 -111.0234)
		(width 0.0889)
		(layer "In4.Cu")
		(net "IRQ_BMC_PCH_SMI_LPC_N")
	)
	(segment
		(start 409.097226 -115.082574)
		(end 410.5148 -113.665)
		(width 0.0889)
		(layer "In4.Cu")
		(net "IRQ_BMC_PCH_SMI_LPC_N")
	)
	(segment
		(start 397.197834 -117.183154)
		(end 397.427958 -117.413278)
		(width 0.0889)
		(layer "In4.Cu")
		(net "IRQ_BMC_PCH_SMI_LPC_N")
	)
	(segment
		(start 398.30375 -117.413278)
		(end 398.428718 -117.538246)
		(width 0.0889)
		(layer "In4.Cu")
		(net "IRQ_BMC_PCH_SMI_LPC_N")
	)
	(arc
		(start 393.281154 -116.941092)
		(mid 393.337673 -116.747989)
		(end 393.481052 -116.606828)
		(width 0.089408)
		(layer "In4.Cu")
		(net "IRQ_BMC_PCH_SMI_LPC_N")
	)
	(arc
		(start 393.880848 -116.606828)
		(mid 394.17625 -116.685925)
		(end 394.471652 -116.606828)
		(width 0.089408)
		(layer "In4.Cu")
		(net "IRQ_BMC_PCH_SMI_LPC_N")
	)
	(arc
		(start 395.862048 -116.606828)
		(mid 396.134614 -116.685484)
		(end 396.412466 -116.628164)
		(width 0.089408)
		(layer "In4.Cu")
		(net "IRQ_BMC_PCH_SMI_LPC_N")
	)
	(arc
		(start 393.481052 -116.606828)
		(mid 393.68095 -116.553295)
		(end 393.880848 -116.606828)
		(width 0.089408)
		(layer "In4.Cu")
		(net "IRQ_BMC_PCH_SMI_LPC_N")
	)
	(arc
		(start 395.462252 -116.606828)
		(mid 395.66215 -116.553295)
		(end 395.862048 -116.606828)
		(width 0.089408)
		(layer "In4.Cu")
		(net "IRQ_BMC_PCH_SMI_LPC_N")
	)
	(arc
		(start 392.453368 -117.495066)
		(mid 392.723093 -117.543605)
		(end 392.985752 -117.465348)
		(width 0.089408)
		(layer "In4.Cu")
		(net "IRQ_BMC_PCH_SMI_LPC_N")
	)
	(arc
		(start 394.471652 -116.606828)
		(mid 394.67155 -116.553295)
		(end 394.871448 -116.606828)
		(width 0.089408)
		(layer "In4.Cu")
		(net "IRQ_BMC_PCH_SMI_LPC_N")
	)
	(arc
		(start 394.871448 -116.606828)
		(mid 395.16685 -116.685925)
		(end 395.462252 -116.606828)
		(width 0.089408)
		(layer "In4.Cu")
		(net "IRQ_BMC_PCH_SMI_LPC_N")
	)
	(arc
		(start 392.985752 -117.465348)
		(mid 393.197036 -117.257819)
		(end 393.281154 -116.973858)
		(width 0.089408)
		(layer "In4.Cu")
		(net "IRQ_BMC_PCH_SMI_LPC_N")
	)
	(segment
		(start 408.051 -102.9335)
		(end 408.813 -102.9335)
		(width 0.10795)
		(layer "F.Cu")
		(net "FM_GBE_LOM_DISABLE_N")
	)
	(segment
		(start 408.813 -102.9335)
		(end 409.609798 -102.9335)
		(width 0.10795)
		(layer "F.Cu")
		(net "FM_GBE_LOM_DISABLE_N")
	)
	(segment
		(start 374.674892 -98.855022)
		(end 374.16232 -98.34245)
		(width 0.1016)
		(layer "F.Cu")
		(net "FM_GBE_LOM_DISABLE_N")
	)
	(segment
		(start 374.16232 -97.57918)
		(end 374.12676 -97.54362)
		(width 0.1016)
		(layer "F.Cu")
		(net "FM_GBE_LOM_DISABLE_N")
	)
	(segment
		(start 409.609798 -102.9335)
		(end 409.65755 -102.981252)
		(width 0.10795)
		(layer "F.Cu")
		(net "FM_GBE_LOM_DISABLE_N")
	)
	(segment
		(start 407.0604 -103.7336)
		(end 406.7302 -103.7336)
		(width 0.10795)
		(layer "F.Cu")
		(net "FM_GBE_LOM_DISABLE_N")
	)
	(segment
		(start 374.16232 -98.34245)
		(end 374.16232 -97.57918)
		(width 0.1016)
		(layer "F.Cu")
		(net "FM_GBE_LOM_DISABLE_N")
	)
	(segment
		(start 408.051 -102.9335)
		(end 407.8605 -102.9335)
		(width 0.10795)
		(layer "F.Cu")
		(net "FM_GBE_LOM_DISABLE_N")
	)
	(segment
		(start 407.8605 -102.9335)
		(end 407.0604 -103.7336)
		(width 0.10795)
		(layer "F.Cu")
		(net "FM_GBE_LOM_DISABLE_N")
	)
	(via
		(at 409.65755 -102.981252)
		(size 0.508)
		(drill 0.254)
		(layers "F.Cu" "B.Cu")
		(net "FM_GBE_LOM_DISABLE_N")
	)
	(via
		(at 393.6873 -102.74046)
		(size 0.508)
		(drill 0.254)
		(layers "F.Cu" "B.Cu")
		(net "FM_GBE_LOM_DISABLE_N")
	)
	(via
		(at 374.12676 -97.54362)
		(size 0.508)
		(drill 0.254)
		(layers "F.Cu" "B.Cu")
		(net "FM_GBE_LOM_DISABLE_N")
	)
	(via
		(at 374.9421 -97.50044)
		(size 0.6604)
		(drill 0.3302)
		(layers "F.Cu" "B.Cu")
		(net "FM_GBE_LOM_DISABLE_N")
	)
	(segment
		(start 374.9421 -97.50044)
		(end 374.89892 -97.54362)
		(width 0.10795)
		(layer "B.Cu")
		(net "FM_GBE_LOM_DISABLE_N")
	)
	(segment
		(start 374.89892 -97.54362)
		(end 374.12676 -97.54362)
		(width 0.10795)
		(layer "B.Cu")
		(net "FM_GBE_LOM_DISABLE_N")
	)
	(segment
		(start 408.360626 -104.013)
		(end 409.392374 -102.981252)
		(width 0.089408)
		(layer "In4.Cu")
		(net "FM_GBE_LOM_DISABLE_N")
	)
	(segment
		(start 393.6873 -101.823012)
		(end 394.015976 -101.494336)
		(width 0.089408)
		(layer "In4.Cu")
		(net "FM_GBE_LOM_DISABLE_N")
	)
	(segment
		(start 404.3172 -103.4288)
		(end 404.9014 -104.013)
		(width 0.089408)
		(layer "In4.Cu")
		(net "FM_GBE_LOM_DISABLE_N")
	)
	(segment
		(start 394.015976 -101.494336)
		(end 399.563336 -101.494336)
		(width 0.089408)
		(layer "In4.Cu")
		(net "FM_GBE_LOM_DISABLE_N")
	)
	(segment
		(start 399.563336 -101.494336)
		(end 401.4978 -103.4288)
		(width 0.089408)
		(layer "In4.Cu")
		(net "FM_GBE_LOM_DISABLE_N")
	)
	(segment
		(start 404.9014 -104.013)
		(end 408.360626 -104.013)
		(width 0.089408)
		(layer "In4.Cu")
		(net "FM_GBE_LOM_DISABLE_N")
	)
	(segment
		(start 409.392374 -102.981252)
		(end 409.65755 -102.981252)
		(width 0.089408)
		(layer "In4.Cu")
		(net "FM_GBE_LOM_DISABLE_N")
	)
	(segment
		(start 401.4978 -103.4288)
		(end 404.3172 -103.4288)
		(width 0.089408)
		(layer "In4.Cu")
		(net "FM_GBE_LOM_DISABLE_N")
	)
	(segment
		(start 393.6873 -102.74046)
		(end 393.6873 -101.823012)
		(width 0.089408)
		(layer "In4.Cu")
		(net "FM_GBE_LOM_DISABLE_N")
	)
	(segment
		(start 381.804672 -103.887524)
		(end 381.931164 -104.014016)
		(width 0.089408)
		(layer "In9.Cu")
		(net "FM_GBE_LOM_DISABLE_N")
	)
	(segment
		(start 384.189732 -102.32898)
		(end 384.669538 -102.808786)
		(width 0.0889)
		(layer "In9.Cu")
		(net "FM_GBE_LOM_DISABLE_N")
	)
	(segment
		(start 381.39497 -102.92207)
		(end 381.804672 -103.331772)
		(width 0.089408)
		(layer "In9.Cu")
		(net "FM_GBE_LOM_DISABLE_N")
	)
	(segment
		(start 393.6746 -102.74046)
		(end 393.6873 -102.74046)
		(width 0.089408)
		(layer "In9.Cu")
		(net "FM_GBE_LOM_DISABLE_N")
	)
	(segment
		(start 381.69723 -102.06355)
		(end 381.39497 -102.36581)
		(width 0.089408)
		(layer "In9.Cu")
		(net "FM_GBE_LOM_DISABLE_N")
	)
	(segment
		(start 388.697216 -103.770684)
		(end 389.14324 -104.216708)
		(width 0.0889)
		(layer "In9.Cu")
		(net "FM_GBE_LOM_DISABLE_N")
	)
	(segment
		(start 391.03935 -103.21671)
		(end 391.103612 -103.21671)
		(width 0.0889)
		(layer "In9.Cu")
		(net "FM_GBE_LOM_DISABLE_N")
	)
	(segment
		(start 388.697216 -103.419148)
		(end 388.697216 -103.770684)
		(width 0.0889)
		(layer "In9.Cu")
		(net "FM_GBE_LOM_DISABLE_N")
	)
	(segment
		(start 375.4755 -96.92132)
		(end 377.93676 -96.92132)
		(width 0.089408)
		(layer "In9.Cu")
		(net "FM_GBE_LOM_DISABLE_N")
	)
	(segment
		(start 381.39497 -101.20503)
		(end 381.69723 -101.50729)
		(width 0.089408)
		(layer "In9.Cu")
		(net "FM_GBE_LOM_DISABLE_N")
	)
	(segment
		(start 380.89459 -99.97821)
		(end 380.89459 -100.53447)
		(width 0.089408)
		(layer "In9.Cu")
		(net "FM_GBE_LOM_DISABLE_N")
	)
	(segment
		(start 381.804672 -103.331772)
		(end 381.804672 -103.887524)
		(width 0.089408)
		(layer "In9.Cu")
		(net "FM_GBE_LOM_DISABLE_N")
	)
	(segment
		(start 390.292082 -104.216708)
		(end 390.7028 -103.80599)
		(width 0.0889)
		(layer "In9.Cu")
		(net "FM_GBE_LOM_DISABLE_N")
	)
	(segment
		(start 386.351526 -103.155242)
		(end 386.91185 -103.155242)
		(width 0.0889)
		(layer "In9.Cu")
		(net "FM_GBE_LOM_DISABLE_N")
	)
	(segment
		(start 389.14324 -104.216708)
		(end 390.292082 -104.216708)
		(width 0.0889)
		(layer "In9.Cu")
		(net "FM_GBE_LOM_DISABLE_N")
	)
	(segment
		(start 378.222256 -97.206816)
		(end 378.987304 -97.206816)
		(width 0.089408)
		(layer "In9.Cu")
		(net "FM_GBE_LOM_DISABLE_N")
	)
	(segment
		(start 378.987304 -97.206816)
		(end 379.22073 -97.440242)
		(width 0.089408)
		(layer "In9.Cu")
		(net "FM_GBE_LOM_DISABLE_N")
	)
	(segment
		(start 391.120122 -103.2002)
		(end 393.21486 -103.2002)
		(width 0.089408)
		(layer "In9.Cu")
		(net "FM_GBE_LOM_DISABLE_N")
	)
	(segment
		(start 374.8532 -97.54362)
		(end 375.4755 -96.92132)
		(width 0.089408)
		(layer "In9.Cu")
		(net "FM_GBE_LOM_DISABLE_N")
	)
	(segment
		(start 384.669538 -102.808786)
		(end 386.00507 -102.808786)
		(width 0.0889)
		(layer "In9.Cu")
		(net "FM_GBE_LOM_DISABLE_N")
	)
	(segment
		(start 386.934456 -103.132636)
		(end 387.549644 -103.132636)
		(width 0.0889)
		(layer "In9.Cu")
		(net "FM_GBE_LOM_DISABLE_N")
	)
	(segment
		(start 380.40437 -99.12477)
		(end 380.40437 -99.48799)
		(width 0.089408)
		(layer "In9.Cu")
		(net "FM_GBE_LOM_DISABLE_N")
	)
	(segment
		(start 383.37617 -103.09225)
		(end 383.37617 -102.591362)
		(width 0.089408)
		(layer "In9.Cu")
		(net "FM_GBE_LOM_DISABLE_N")
	)
	(segment
		(start 387.549644 -103.132636)
		(end 387.576314 -103.159306)
		(width 0.0889)
		(layer "In9.Cu")
		(net "FM_GBE_LOM_DISABLE_N")
	)
	(segment
		(start 383.638552 -102.32898)
		(end 384.189732 -102.32898)
		(width 0.089408)
		(layer "In9.Cu")
		(net "FM_GBE_LOM_DISABLE_N")
	)
	(segment
		(start 393.21486 -103.2002)
		(end 393.6746 -102.74046)
		(width 0.089408)
		(layer "In9.Cu")
		(net "FM_GBE_LOM_DISABLE_N")
	)
	(segment
		(start 382.454404 -104.014016)
		(end 383.37617 -103.09225)
		(width 0.089408)
		(layer "In9.Cu")
		(net "FM_GBE_LOM_DISABLE_N")
	)
	(segment
		(start 379.22073 -97.57791)
		(end 379.90907 -98.26625)
		(width 0.089408)
		(layer "In9.Cu")
		(net "FM_GBE_LOM_DISABLE_N")
	)
	(segment
		(start 390.7028 -103.617522)
		(end 390.805924 -103.514398)
		(width 0.0889)
		(layer "In9.Cu")
		(net "FM_GBE_LOM_DISABLE_N")
	)
	(segment
		(start 381.931164 -104.014016)
		(end 382.454404 -104.014016)
		(width 0.089408)
		(layer "In9.Cu")
		(net "FM_GBE_LOM_DISABLE_N")
	)
	(segment
		(start 388.437374 -103.159306)
		(end 388.697216 -103.419148)
		(width 0.0889)
		(layer "In9.Cu")
		(net "FM_GBE_LOM_DISABLE_N")
	)
	(segment
		(start 381.39497 -101.03485)
		(end 381.39497 -101.20503)
		(width 0.089408)
		(layer "In9.Cu")
		(net "FM_GBE_LOM_DISABLE_N")
	)
	(segment
		(start 383.37617 -102.591362)
		(end 383.638552 -102.32898)
		(width 0.089408)
		(layer "In9.Cu")
		(net "FM_GBE_LOM_DISABLE_N")
	)
	(segment
		(start 380.40437 -99.48799)
		(end 380.89459 -99.97821)
		(width 0.089408)
		(layer "In9.Cu")
		(net "FM_GBE_LOM_DISABLE_N")
	)
	(segment
		(start 374.12676 -97.54362)
		(end 374.8532 -97.54362)
		(width 0.089408)
		(layer "In9.Cu")
		(net "FM_GBE_LOM_DISABLE_N")
	)
	(segment
		(start 379.90907 -98.62947)
		(end 380.40437 -99.12477)
		(width 0.089408)
		(layer "In9.Cu")
		(net "FM_GBE_LOM_DISABLE_N")
	)
	(segment
		(start 386.00507 -102.808786)
		(end 386.351526 -103.155242)
		(width 0.0889)
		(layer "In9.Cu")
		(net "FM_GBE_LOM_DISABLE_N")
	)
	(segment
		(start 387.576314 -103.159306)
		(end 388.437374 -103.159306)
		(width 0.0889)
		(layer "In9.Cu")
		(net "FM_GBE_LOM_DISABLE_N")
	)
	(segment
		(start 390.7028 -103.80599)
		(end 390.7028 -103.617522)
		(width 0.0889)
		(layer "In9.Cu")
		(net "FM_GBE_LOM_DISABLE_N")
	)
	(segment
		(start 390.805924 -103.450136)
		(end 391.03935 -103.21671)
		(width 0.0889)
		(layer "In9.Cu")
		(net "FM_GBE_LOM_DISABLE_N")
	)
	(segment
		(start 391.103612 -103.21671)
		(end 391.120122 -103.2002)
		(width 0.0889)
		(layer "In9.Cu")
		(net "FM_GBE_LOM_DISABLE_N")
	)
	(segment
		(start 377.93676 -96.92132)
		(end 378.222256 -97.206816)
		(width 0.089408)
		(layer "In9.Cu")
		(net "FM_GBE_LOM_DISABLE_N")
	)
	(segment
		(start 381.39497 -102.36581)
		(end 381.39497 -102.92207)
		(width 0.089408)
		(layer "In9.Cu")
		(net "FM_GBE_LOM_DISABLE_N")
	)
	(segment
		(start 379.90907 -98.26625)
		(end 379.90907 -98.62947)
		(width 0.089408)
		(layer "In9.Cu")
		(net "FM_GBE_LOM_DISABLE_N")
	)
	(segment
		(start 380.89459 -100.53447)
		(end 381.39497 -101.03485)
		(width 0.089408)
		(layer "In9.Cu")
		(net "FM_GBE_LOM_DISABLE_N")
	)
	(segment
		(start 379.22073 -97.440242)
		(end 379.22073 -97.57791)
		(width 0.089408)
		(layer "In9.Cu")
		(net "FM_GBE_LOM_DISABLE_N")
	)
	(segment
		(start 390.805924 -103.514398)
		(end 390.805924 -103.450136)
		(width 0.0889)
		(layer "In9.Cu")
		(net "FM_GBE_LOM_DISABLE_N")
	)
	(segment
		(start 381.69723 -101.50729)
		(end 381.69723 -102.06355)
		(width 0.089408)
		(layer "In9.Cu")
		(net "FM_GBE_LOM_DISABLE_N")
	)
	(segment
		(start 386.91185 -103.155242)
		(end 386.934456 -103.132636)
		(width 0.0889)
		(layer "In9.Cu")
		(net "FM_GBE_LOM_DISABLE_N")
	)
	(segment
		(start 420.69004 -28.934664)
		(end 421.09009 -28.534614)
		(width 0.10795)
		(layer "F.Cu")
		(net "FM_BOARD_SKU_ID0")
	)
	(segment
		(start 393.68095 -98.69424)
		(end 394.17625 -98.464116)
		(width 0.10795)
		(layer "F.Cu")
		(net "FM_BOARD_SKU_ID0")
	)
	(via
		(at 421.09009 -28.534614)
		(size 0.4572)
		(drill 0.2032)
		(layers "F.Cu" "B.Cu")
		(net "FM_BOARD_SKU_ID0")
	)
	(via
		(at 460.9846 -29.6926)
		(size 0.508)
		(drill 0.254)
		(layers "F.Cu" "B.Cu")
		(net "FM_BOARD_SKU_ID0")
	)
	(via
		(at 394.17625 -98.464116)
		(size 0.508)
		(drill 0.254)
		(layers "F.Cu" "B.Cu")
		(net "FM_BOARD_SKU_ID0")
	)
	(via
		(at 429.84039 -24.031448)
		(size 0.508)
		(drill 0.254)
		(layers "F.Cu" "B.Cu")
		(net "FM_BOARD_SKU_ID0")
	)
	(segment
		(start 429.84039 -24.029162)
		(end 429.829722 -24.018494)
		(width 0.10795)
		(layer "B.Cu")
		(net "FM_BOARD_SKU_ID0")
	)
	(segment
		(start 429.84039 -24.031448)
		(end 429.84039 -24.029162)
		(width 0.10795)
		(layer "B.Cu")
		(net "FM_BOARD_SKU_ID0")
	)
	(segment
		(start 429.82515 -24.018494)
		(end 429.7172 -23.910544)
		(width 0.10795)
		(layer "B.Cu")
		(net "FM_BOARD_SKU_ID0")
	)
	(segment
		(start 429.7172 -23.910544)
		(end 429.7172 -23.4188)
		(width 0.10795)
		(layer "B.Cu")
		(net "FM_BOARD_SKU_ID0")
	)
	(segment
		(start 429.829722 -24.018494)
		(end 429.82515 -24.018494)
		(width 0.10795)
		(layer "B.Cu")
		(net "FM_BOARD_SKU_ID0")
	)
	(segment
		(start 429.7172 -23.4188)
		(end 430.4792 -23.4188)
		(width 0.10795)
		(layer "B.Cu")
		(net "FM_BOARD_SKU_ID0")
	)
	(segment
		(start 445.332866 -20.949158)
		(end 447.023236 -20.949158)
		(width 0.089408)
		(layer "In4.Cu")
		(net "FM_BOARD_SKU_ID0")
	)
	(segment
		(start 448.602608 -24.594312)
		(end 449.273676 -24.594312)
		(width 0.089408)
		(layer "In4.Cu")
		(net "FM_BOARD_SKU_ID0")
	)
	(segment
		(start 445.1985 -21.083524)
		(end 445.332866 -20.949158)
		(width 0.089408)
		(layer "In4.Cu")
		(net "FM_BOARD_SKU_ID0")
	)
	(segment
		(start 449.273676 -24.594312)
		(end 452.982838 -28.303474)
		(width 0.089408)
		(layer "In4.Cu")
		(net "FM_BOARD_SKU_ID0")
	)
	(segment
		(start 433.812188 -21.083524)
		(end 445.1985 -21.083524)
		(width 0.089408)
		(layer "In4.Cu")
		(net "FM_BOARD_SKU_ID0")
	)
	(segment
		(start 460.9846 -28.838652)
		(end 460.9846 -29.6926)
		(width 0.089408)
		(layer "In4.Cu")
		(net "FM_BOARD_SKU_ID0")
	)
	(segment
		(start 429.84039 -24.031448)
		(end 429.84039 -24.029162)
		(width 0.089408)
		(layer "In4.Cu")
		(net "FM_BOARD_SKU_ID0")
	)
	(segment
		(start 447.558668 -23.550372)
		(end 448.602608 -24.594312)
		(width 0.089408)
		(layer "In4.Cu")
		(net "FM_BOARD_SKU_ID0")
	)
	(segment
		(start 429.932338 -24.029162)
		(end 430.514252 -23.447248)
		(width 0.089408)
		(layer "In4.Cu")
		(net "FM_BOARD_SKU_ID0")
	)
	(segment
		(start 447.023236 -20.949158)
		(end 447.558668 -21.48459)
		(width 0.089408)
		(layer "In4.Cu")
		(net "FM_BOARD_SKU_ID0")
	)
	(segment
		(start 447.558668 -21.48459)
		(end 447.558668 -23.550372)
		(width 0.089408)
		(layer "In4.Cu")
		(net "FM_BOARD_SKU_ID0")
	)
	(segment
		(start 430.514252 -23.447248)
		(end 431.448464 -23.447248)
		(width 0.089408)
		(layer "In4.Cu")
		(net "FM_BOARD_SKU_ID0")
	)
	(segment
		(start 431.448464 -23.447248)
		(end 433.812188 -21.083524)
		(width 0.089408)
		(layer "In4.Cu")
		(net "FM_BOARD_SKU_ID0")
	)
	(segment
		(start 460.10576 -27.959812)
		(end 460.9846 -28.838652)
		(width 0.089408)
		(layer "In4.Cu")
		(net "FM_BOARD_SKU_ID0")
	)
	(segment
		(start 455.727562 -27.959812)
		(end 460.10576 -27.959812)
		(width 0.089408)
		(layer "In4.Cu")
		(net "FM_BOARD_SKU_ID0")
	)
	(segment
		(start 455.3839 -28.303474)
		(end 455.727562 -27.959812)
		(width 0.089408)
		(layer "In4.Cu")
		(net "FM_BOARD_SKU_ID0")
	)
	(segment
		(start 452.982838 -28.303474)
		(end 455.3839 -28.303474)
		(width 0.089408)
		(layer "In4.Cu")
		(net "FM_BOARD_SKU_ID0")
	)
	(segment
		(start 429.84039 -24.029162)
		(end 429.932338 -24.029162)
		(width 0.089408)
		(layer "In4.Cu")
		(net "FM_BOARD_SKU_ID0")
	)
	(segment
		(start 423.79773 -50.24247)
		(end 422.551098 -50.24247)
		(width 0.089408)
		(layer "In9.Cu")
		(net "FM_BOARD_SKU_ID0")
	)
	(segment
		(start 411.508448 -60.170822)
		(end 411.658562 -60.320936)
		(width 0.089408)
		(layer "In9.Cu")
		(net "FM_BOARD_SKU_ID0")
	)
	(segment
		(start 427.35754 -49.15662)
		(end 424.88358 -49.15662)
		(width 0.089408)
		(layer "In9.Cu")
		(net "FM_BOARD_SKU_ID0")
	)
	(segment
		(start 411.648148 -67.964558)
		(end 411.648148 -67.981576)
		(width 0.089408)
		(layer "In9.Cu")
		(net "FM_BOARD_SKU_ID0")
	)
	(segment
		(start 424.88358 -49.15662)
		(end 423.79773 -50.24247)
		(width 0.089408)
		(layer "In9.Cu")
		(net "FM_BOARD_SKU_ID0")
	)
	(segment
		(start 461.299306 -31.598616)
		(end 461.961484 -32.260794)
		(width 0.089408)
		(layer "In9.Cu")
		(net "FM_BOARD_SKU_ID0")
	)
	(segment
		(start 438.785762 -46.41596)
		(end 437.51373 -47.687992)
		(width 0.089408)
		(layer "In9.Cu")
		(net "FM_BOARD_SKU_ID0")
	)
	(segment
		(start 412.138622 -63.27902)
		(end 412.138622 -66.103754)
		(width 0.089408)
		(layer "In9.Cu")
		(net "FM_BOARD_SKU_ID0")
	)
	(segment
		(start 450.417184 -44.46016)
		(end 450.417184 -45.58792)
		(width 0.089408)
		(layer "In9.Cu")
		(net "FM_BOARD_SKU_ID0")
	)
	(segment
		(start 393.77747 -96.944942)
		(end 394.17625 -97.343722)
		(width 0.089408)
		(layer "In9.Cu")
		(net "FM_BOARD_SKU_ID0")
	)
	(segment
		(start 415.94913 -54.222396)
		(end 415.94913 -54.948074)
		(width 0.089408)
		(layer "In9.Cu")
		(net "FM_BOARD_SKU_ID0")
	)
	(segment
		(start 412.780734 -56.361584)
		(end 412.24708 -56.895238)
		(width 0.089408)
		(layer "In9.Cu")
		(net "FM_BOARD_SKU_ID0")
	)
	(segment
		(start 434.777388 -47.687992)
		(end 432.884072 -49.581308)
		(width 0.089408)
		(layer "In9.Cu")
		(net "FM_BOARD_SKU_ID0")
	)
	(segment
		(start 394.17625 -97.343722)
		(end 394.17625 -98.464116)
		(width 0.089408)
		(layer "In9.Cu")
		(net "FM_BOARD_SKU_ID0")
	)
	(segment
		(start 398.566386 -90.95867)
		(end 397.832326 -90.95867)
		(width 0.089408)
		(layer "In9.Cu")
		(net "FM_BOARD_SKU_ID0")
	)
	(segment
		(start 454.739248 -42.683176)
		(end 453.864726 -43.557698)
		(width 0.089408)
		(layer "In9.Cu")
		(net "FM_BOARD_SKU_ID0")
	)
	(segment
		(start 437.51373 -47.687992)
		(end 434.777388 -47.687992)
		(width 0.089408)
		(layer "In9.Cu")
		(net "FM_BOARD_SKU_ID0")
	)
	(segment
		(start 394.082016 -96.175322)
		(end 393.77747 -96.479868)
		(width 0.089408)
		(layer "In9.Cu")
		(net "FM_BOARD_SKU_ID0")
	)
	(segment
		(start 411.658562 -62.640464)
		(end 412.138876 -63.120778)
		(width 0.089408)
		(layer "In9.Cu")
		(net "FM_BOARD_SKU_ID0")
	)
	(segment
		(start 414.600644 -56.29656)
		(end 414.156906 -56.29656)
		(width 0.089408)
		(layer "In9.Cu")
		(net "FM_BOARD_SKU_ID0")
	)
	(segment
		(start 422.163748 -50.62982)
		(end 422.163748 -51.300634)
		(width 0.089408)
		(layer "In9.Cu")
		(net "FM_BOARD_SKU_ID0")
	)
	(segment
		(start 411.658562 -60.320936)
		(end 411.658562 -62.640464)
		(width 0.089408)
		(layer "In9.Cu")
		(net "FM_BOARD_SKU_ID0")
	)
	(segment
		(start 453.864726 -43.557698)
		(end 452.751444 -43.557698)
		(width 0.089408)
		(layer "In9.Cu")
		(net "FM_BOARD_SKU_ID0")
	)
	(segment
		(start 460.425292 -30.251908)
		(end 460.425292 -31.264098)
		(width 0.089408)
		(layer "In9.Cu")
		(net "FM_BOARD_SKU_ID0")
	)
	(segment
		(start 405.241252 -82.188812)
		(end 402.885148 -84.544916)
		(width 0.089408)
		(layer "In9.Cu")
		(net "FM_BOARD_SKU_ID0")
	)
	(segment
		(start 415.94913 -54.948074)
		(end 414.600644 -56.29656)
		(width 0.089408)
		(layer "In9.Cu")
		(net "FM_BOARD_SKU_ID0")
	)
	(segment
		(start 393.77747 -96.479868)
		(end 393.77747 -96.944942)
		(width 0.089408)
		(layer "In9.Cu")
		(net "FM_BOARD_SKU_ID0")
	)
	(segment
		(start 455.708258 -42.683176)
		(end 454.739248 -42.683176)
		(width 0.089408)
		(layer "In9.Cu")
		(net "FM_BOARD_SKU_ID0")
	)
	(segment
		(start 402.885148 -86.639908)
		(end 398.566386 -90.95867)
		(width 0.089408)
		(layer "In9.Cu")
		(net "FM_BOARD_SKU_ID0")
	)
	(segment
		(start 456.675744 -36.277296)
		(end 456.675744 -41.71569)
		(width 0.089408)
		(layer "In9.Cu")
		(net "FM_BOARD_SKU_ID0")
	)
	(segment
		(start 421.846502 -51.61788)
		(end 420.054532 -51.61788)
		(width 0.089408)
		(layer "In9.Cu")
		(net "FM_BOARD_SKU_ID0")
	)
	(segment
		(start 460.425292 -31.264098)
		(end 460.75981 -31.598616)
		(width 0.089408)
		(layer "In9.Cu")
		(net "FM_BOARD_SKU_ID0")
	)
	(segment
		(start 449.589144 -46.41596)
		(end 438.785762 -46.41596)
		(width 0.089408)
		(layer "In9.Cu")
		(net "FM_BOARD_SKU_ID0")
	)
	(segment
		(start 397.1671 -91.623896)
		(end 397.1671 -92.569538)
		(width 0.089408)
		(layer "In9.Cu")
		(net "FM_BOARD_SKU_ID0")
	)
	(segment
		(start 412.138622 -66.103754)
		(end 411.658562 -66.583814)
		(width 0.089408)
		(layer "In9.Cu")
		(net "FM_BOARD_SKU_ID0")
	)
	(segment
		(start 405.241252 -78.956916)
		(end 405.241252 -82.188812)
		(width 0.089408)
		(layer "In9.Cu")
		(net "FM_BOARD_SKU_ID0")
	)
	(segment
		(start 422.551098 -50.24247)
		(end 422.163748 -50.62982)
		(width 0.089408)
		(layer "In9.Cu")
		(net "FM_BOARD_SKU_ID0")
	)
	(segment
		(start 397.1671 -92.569538)
		(end 394.43787 -95.298768)
		(width 0.089408)
		(layer "In9.Cu")
		(net "FM_BOARD_SKU_ID0")
	)
	(segment
		(start 394.43787 -95.298768)
		(end 394.427202 -95.298768)
		(width 0.089408)
		(layer "In9.Cu")
		(net "FM_BOARD_SKU_ID0")
	)
	(segment
		(start 452.751444 -43.557698)
		(end 452.438008 -43.871134)
		(width 0.089408)
		(layer "In9.Cu")
		(net "FM_BOARD_SKU_ID0")
	)
	(segment
		(start 422.163748 -51.300634)
		(end 421.846502 -51.61788)
		(width 0.089408)
		(layer "In9.Cu")
		(net "FM_BOARD_SKU_ID0")
	)
	(segment
		(start 402.885148 -84.544916)
		(end 402.885148 -86.639908)
		(width 0.089408)
		(layer "In9.Cu")
		(net "FM_BOARD_SKU_ID0")
	)
	(segment
		(start 417.414202 -52.757324)
		(end 415.94913 -54.222396)
		(width 0.089408)
		(layer "In9.Cu")
		(net "FM_BOARD_SKU_ID0")
	)
	(segment
		(start 411.508448 -58.307732)
		(end 411.508448 -60.170822)
		(width 0.089408)
		(layer "In9.Cu")
		(net "FM_BOARD_SKU_ID0")
	)
	(segment
		(start 450.417184 -45.58792)
		(end 449.589144 -46.41596)
		(width 0.089408)
		(layer "In9.Cu")
		(net "FM_BOARD_SKU_ID0")
	)
	(segment
		(start 461.615282 -33.097216)
		(end 461.423258 -33.097216)
		(width 0.089408)
		(layer "In9.Cu")
		(net "FM_BOARD_SKU_ID0")
	)
	(segment
		(start 410.017722 -69.612002)
		(end 410.017722 -69.862192)
		(width 0.089408)
		(layer "In9.Cu")
		(net "FM_BOARD_SKU_ID0")
	)
	(segment
		(start 461.961484 -32.751014)
		(end 461.615282 -33.097216)
		(width 0.089408)
		(layer "In9.Cu")
		(net "FM_BOARD_SKU_ID0")
	)
	(segment
		(start 418.915088 -52.757324)
		(end 417.414202 -52.757324)
		(width 0.089408)
		(layer "In9.Cu")
		(net "FM_BOARD_SKU_ID0")
	)
	(segment
		(start 394.082016 -95.643954)
		(end 394.082016 -96.175322)
		(width 0.089408)
		(layer "In9.Cu")
		(net "FM_BOARD_SKU_ID0")
	)
	(segment
		(start 412.138876 -63.120778)
		(end 412.138876 -63.278766)
		(width 0.089408)
		(layer "In9.Cu")
		(net "FM_BOARD_SKU_ID0")
	)
	(segment
		(start 411.648148 -67.981576)
		(end 410.017722 -69.612002)
		(width 0.089408)
		(layer "In9.Cu")
		(net "FM_BOARD_SKU_ID0")
	)
	(segment
		(start 412.24708 -56.895238)
		(end 412.24708 -57.5691)
		(width 0.089408)
		(layer "In9.Cu")
		(net "FM_BOARD_SKU_ID0")
	)
	(segment
		(start 460.75981 -31.598616)
		(end 461.299306 -31.598616)
		(width 0.089408)
		(layer "In9.Cu")
		(net "FM_BOARD_SKU_ID0")
	)
	(segment
		(start 460.9846 -29.6926)
		(end 460.425292 -30.251908)
		(width 0.089408)
		(layer "In9.Cu")
		(net "FM_BOARD_SKU_ID0")
	)
	(segment
		(start 460.833978 -33.686496)
		(end 460.833978 -34.007044)
		(width 0.089408)
		(layer "In9.Cu")
		(net "FM_BOARD_SKU_ID0")
	)
	(segment
		(start 420.054532 -51.61788)
		(end 418.915088 -52.757324)
		(width 0.089408)
		(layer "In9.Cu")
		(net "FM_BOARD_SKU_ID0")
	)
	(segment
		(start 410.017722 -69.862192)
		(end 405.001476 -74.878438)
		(width 0.089408)
		(layer "In9.Cu")
		(net "FM_BOARD_SKU_ID0")
	)
	(segment
		(start 412.138876 -63.278766)
		(end 412.138622 -63.27902)
		(width 0.089408)
		(layer "In9.Cu")
		(net "FM_BOARD_SKU_ID0")
	)
	(segment
		(start 452.438008 -43.871134)
		(end 451.00621 -43.871134)
		(width 0.089408)
		(layer "In9.Cu")
		(net "FM_BOARD_SKU_ID0")
	)
	(segment
		(start 405.001476 -78.71714)
		(end 405.241252 -78.956916)
		(width 0.089408)
		(layer "In9.Cu")
		(net "FM_BOARD_SKU_ID0")
	)
	(segment
		(start 427.782228 -49.581308)
		(end 427.35754 -49.15662)
		(width 0.089408)
		(layer "In9.Cu")
		(net "FM_BOARD_SKU_ID0")
	)
	(segment
		(start 405.001476 -74.878438)
		(end 405.001476 -78.71714)
		(width 0.089408)
		(layer "In9.Cu")
		(net "FM_BOARD_SKU_ID0")
	)
	(segment
		(start 412.24708 -57.5691)
		(end 411.508448 -58.307732)
		(width 0.089408)
		(layer "In9.Cu")
		(net "FM_BOARD_SKU_ID0")
	)
	(segment
		(start 414.091882 -56.361584)
		(end 412.780734 -56.361584)
		(width 0.089408)
		(layer "In9.Cu")
		(net "FM_BOARD_SKU_ID0")
	)
	(segment
		(start 394.427202 -95.298768)
		(end 394.082016 -95.643954)
		(width 0.089408)
		(layer "In9.Cu")
		(net "FM_BOARD_SKU_ID0")
	)
	(segment
		(start 461.423258 -33.097216)
		(end 460.833978 -33.686496)
		(width 0.089408)
		(layer "In9.Cu")
		(net "FM_BOARD_SKU_ID0")
	)
	(segment
		(start 414.156906 -56.29656)
		(end 414.091882 -56.361584)
		(width 0.089408)
		(layer "In9.Cu")
		(net "FM_BOARD_SKU_ID0")
	)
	(segment
		(start 458.98943 -35.851592)
		(end 457.101448 -35.851592)
		(width 0.089408)
		(layer "In9.Cu")
		(net "FM_BOARD_SKU_ID0")
	)
	(segment
		(start 411.658562 -67.954144)
		(end 411.648148 -67.964558)
		(width 0.089408)
		(layer "In9.Cu")
		(net "FM_BOARD_SKU_ID0")
	)
	(segment
		(start 457.101448 -35.851592)
		(end 456.675744 -36.277296)
		(width 0.089408)
		(layer "In9.Cu")
		(net "FM_BOARD_SKU_ID0")
	)
	(segment
		(start 460.833978 -34.007044)
		(end 458.98943 -35.851592)
		(width 0.089408)
		(layer "In9.Cu")
		(net "FM_BOARD_SKU_ID0")
	)
	(segment
		(start 432.884072 -49.581308)
		(end 427.782228 -49.581308)
		(width 0.089408)
		(layer "In9.Cu")
		(net "FM_BOARD_SKU_ID0")
	)
	(segment
		(start 397.832326 -90.95867)
		(end 397.1671 -91.623896)
		(width 0.089408)
		(layer "In9.Cu")
		(net "FM_BOARD_SKU_ID0")
	)
	(segment
		(start 461.961484 -32.260794)
		(end 461.961484 -32.751014)
		(width 0.089408)
		(layer "In9.Cu")
		(net "FM_BOARD_SKU_ID0")
	)
	(segment
		(start 451.00621 -43.871134)
		(end 450.417184 -44.46016)
		(width 0.089408)
		(layer "In9.Cu")
		(net "FM_BOARD_SKU_ID0")
	)
	(segment
		(start 411.658562 -66.583814)
		(end 411.658562 -67.954144)
		(width 0.089408)
		(layer "In9.Cu")
		(net "FM_BOARD_SKU_ID0")
	)
	(segment
		(start 456.675744 -41.71569)
		(end 455.708258 -42.683176)
		(width 0.089408)
		(layer "In9.Cu")
		(net "FM_BOARD_SKU_ID0")
	)
	(segment
		(start 427.341538 -27.822144)
		(end 422.609772 -27.822144)
		(width 0.089408)
		(layer "In11.Cu")
		(net "FM_BOARD_SKU_ID0")
	)
	(segment
		(start 421.09009 -28.557474)
		(end 421.09009 -28.534614)
		(width 0.089408)
		(layer "In11.Cu")
		(net "FM_BOARD_SKU_ID0")
	)
	(segment
		(start 422.077388 -28.923234)
		(end 421.45585 -28.923234)
		(width 0.089408)
		(layer "In11.Cu")
		(net "FM_BOARD_SKU_ID0")
	)
	(segment
		(start 422.609772 -27.822144)
		(end 422.310306 -28.12161)
		(width 0.089408)
		(layer "In11.Cu")
		(net "FM_BOARD_SKU_ID0")
	)
	(segment
		(start 429.84039 -24.031448)
		(end 429.84039 -25.323292)
		(width 0.089408)
		(layer "In11.Cu")
		(net "FM_BOARD_SKU_ID0")
	)
	(segment
		(start 422.310306 -28.12161)
		(end 422.310306 -28.690316)
		(width 0.089408)
		(layer "In11.Cu")
		(net "FM_BOARD_SKU_ID0")
	)
	(segment
		(start 421.45585 -28.923234)
		(end 421.09009 -28.557474)
		(width 0.089408)
		(layer "In11.Cu")
		(net "FM_BOARD_SKU_ID0")
	)
	(segment
		(start 422.310306 -28.690316)
		(end 422.077388 -28.923234)
		(width 0.089408)
		(layer "In11.Cu")
		(net "FM_BOARD_SKU_ID0")
	)
	(segment
		(start 429.84039 -25.323292)
		(end 427.341538 -27.822144)
		(width 0.089408)
		(layer "In11.Cu")
		(net "FM_BOARD_SKU_ID0")
	)
	(segment
		(start 375.23801 -102.042976)
		(end 374.956324 -102.042976)
		(width 0.0889)
		(layer "F.Cu")
		(net "CLK_100M_MEZZ4_DP")
	)
	(segment
		(start 466.38845 -50.060098)
		(end 466.778848 -49.6697)
		(width 0.127)
		(layer "F.Cu")
		(net "CLK_100M_MEZZ4_DP")
	)
	(segment
		(start 439.273188 -54.973474)
		(end 436.761382 -54.973474)
		(width 0.127)
		(layer "F.Cu")
		(net "CLK_100M_MEZZ4_DP")
	)
	(segment
		(start 375.549922 -102.354888)
		(end 375.23801 -102.042976)
		(width 0.0889)
		(layer "F.Cu")
		(net "CLK_100M_MEZZ4_DP")
	)
	(segment
		(start 422.060878 -68.909692)
		(end 421.67937 -69.2912)
		(width 0.127)
		(layer "F.Cu")
		(net "CLK_100M_MEZZ4_DP")
	)
	(segment
		(start 374.174258 -102.164388)
		(end 373.718836 -102.61981)
		(width 0.0889)
		(layer "F.Cu")
		(net "CLK_100M_MEZZ4_DP")
	)
	(segment
		(start 466.38845 -50.471578)
		(end 466.38845 -50.060098)
		(width 0.127)
		(layer "F.Cu")
		(net "CLK_100M_MEZZ4_DP")
	)
	(segment
		(start 421.110156 -62.503812)
		(end 421.110156 -63.603886)
		(width 0.127)
		(layer "F.Cu")
		(net "CLK_100M_MEZZ4_DP")
	)
	(segment
		(start 469.57869 -49.6697)
		(end 469.9762 -50.06721)
		(width 0.127)
		(layer "F.Cu")
		(net "CLK_100M_MEZZ4_DP")
	)
	(segment
		(start 466.927438 -54.7624)
		(end 466.787738 -54.6227)
		(width 0.127)
		(layer "F.Cu")
		(net "CLK_100M_MEZZ4_DP")
	)
	(segment
		(start 421.110156 -63.603886)
		(end 422.060878 -64.554608)
		(width 0.127)
		(layer "F.Cu")
		(net "CLK_100M_MEZZ4_DP")
	)
	(segment
		(start 436.093108 -54.3052)
		(end 429.857154 -54.3052)
		(width 0.127)
		(layer "F.Cu")
		(net "CLK_100M_MEZZ4_DP")
	)
	(segment
		(start 464.14436 -55.260494)
		(end 447.911474 -55.260494)
		(width 0.127)
		(layer "F.Cu")
		(net "CLK_100M_MEZZ4_DP")
	)
	(segment
		(start 429.857154 -54.3052)
		(end 427.380146 -56.782208)
		(width 0.127)
		(layer "F.Cu")
		(net "CLK_100M_MEZZ4_DP")
	)
	(segment
		(start 422.060878 -64.554608)
		(end 422.060878 -68.909692)
		(width 0.127)
		(layer "F.Cu")
		(net "CLK_100M_MEZZ4_DP")
	)
	(segment
		(start 439.549794 -54.696868)
		(end 439.273188 -54.973474)
		(width 0.127)
		(layer "F.Cu")
		(net "CLK_100M_MEZZ4_DP")
	)
	(segment
		(start 447.911474 -55.260494)
		(end 447.347848 -54.696868)
		(width 0.127)
		(layer "F.Cu")
		(net "CLK_100M_MEZZ4_DP")
	)
	(segment
		(start 466.141054 -51.875944)
		(end 466.141054 -50.718974)
		(width 0.127)
		(layer "F.Cu")
		(net "CLK_100M_MEZZ4_DP")
	)
	(segment
		(start 374.834912 -102.164388)
		(end 374.174258 -102.164388)
		(width 0.0889)
		(layer "F.Cu")
		(net "CLK_100M_MEZZ4_DP")
	)
	(segment
		(start 373.718836 -102.61981)
		(end 373.302022 -102.61981)
		(width 0.0889)
		(layer "F.Cu")
		(net "CLK_100M_MEZZ4_DP")
	)
	(segment
		(start 469.9762 -50.06721)
		(end 469.9762 -52.78628)
		(width 0.127)
		(layer "F.Cu")
		(net "CLK_100M_MEZZ4_DP")
	)
	(segment
		(start 375.92 -102.354888)
		(end 375.549922 -102.354888)
		(width 0.0889)
		(layer "F.Cu")
		(net "CLK_100M_MEZZ4_DP")
	)
	(segment
		(start 426.83176 -56.782208)
		(end 425.953428 -57.66054)
		(width 0.127)
		(layer "F.Cu")
		(net "CLK_100M_MEZZ4_DP")
	)
	(segment
		(start 436.761382 -54.973474)
		(end 436.093108 -54.3052)
		(width 0.127)
		(layer "F.Cu")
		(net "CLK_100M_MEZZ4_DP")
	)
	(segment
		(start 468.00008 -54.7624)
		(end 466.927438 -54.7624)
		(width 0.127)
		(layer "F.Cu")
		(net "CLK_100M_MEZZ4_DP")
	)
	(segment
		(start 427.380146 -56.782208)
		(end 426.83176 -56.782208)
		(width 0.127)
		(layer "F.Cu")
		(net "CLK_100M_MEZZ4_DP")
	)
	(segment
		(start 421.67937 -69.2912)
		(end 421.131492 -69.2912)
		(width 0.127)
		(layer "F.Cu")
		(net "CLK_100M_MEZZ4_DP")
	)
	(segment
		(start 425.953428 -57.66054)
		(end 421.110156 -62.503812)
		(width 0.127)
		(layer "F.Cu")
		(net "CLK_100M_MEZZ4_DP")
	)
	(segment
		(start 466.778848 -49.6697)
		(end 469.57869 -49.6697)
		(width 0.127)
		(layer "F.Cu")
		(net "CLK_100M_MEZZ4_DP")
	)
	(segment
		(start 464.782154 -54.6227)
		(end 464.14436 -55.260494)
		(width 0.127)
		(layer "F.Cu")
		(net "CLK_100M_MEZZ4_DP")
	)
	(segment
		(start 447.347848 -54.696868)
		(end 439.549794 -54.696868)
		(width 0.127)
		(layer "F.Cu")
		(net "CLK_100M_MEZZ4_DP")
	)
	(segment
		(start 466.141054 -50.718974)
		(end 466.38845 -50.471578)
		(width 0.127)
		(layer "F.Cu")
		(net "CLK_100M_MEZZ4_DP")
	)
	(segment
		(start 421.004492 -69.4182)
		(end 421.004492 -69.7738)
		(width 0.127)
		(layer "F.Cu")
		(net "CLK_100M_MEZZ4_DP")
	)
	(segment
		(start 466.787738 -54.6227)
		(end 464.782154 -54.6227)
		(width 0.127)
		(layer "F.Cu")
		(net "CLK_100M_MEZZ4_DP")
	)
	(segment
		(start 421.131492 -69.2912)
		(end 421.004492 -69.4182)
		(width 0.127)
		(layer "F.Cu")
		(net "CLK_100M_MEZZ4_DP")
	)
	(segment
		(start 469.9762 -52.78628)
		(end 468.00008 -54.7624)
		(width 0.127)
		(layer "F.Cu")
		(net "CLK_100M_MEZZ4_DP")
	)
	(segment
		(start 373.302022 -102.61981)
		(end 372.884192 -102.20198)
		(width 0.0889)
		(layer "F.Cu")
		(net "CLK_100M_MEZZ4_DP")
	)
	(segment
		(start 374.956324 -102.042976)
		(end 374.834912 -102.164388)
		(width 0.0889)
		(layer "F.Cu")
		(net "CLK_100M_MEZZ4_DP")
	)
	(via
		(at 425.953428 -57.66054)
		(size 0.508)
		(drill 0.254)
		(layers "F.Cu" "B.Cu")
		(net "CLK_100M_MEZZ4_DP")
	)
	(via
		(at 421.004492 -69.7738)
		(size 0.508)
		(drill 0.254)
		(layers "F.Cu" "B.Cu")
		(net "CLK_100M_MEZZ4_DP")
	)
	(via
		(at 372.884192 -102.20198)
		(size 0.508)
		(drill 0.254)
		(layers "F.Cu" "B.Cu")
		(net "CLK_100M_MEZZ4_DP")
	)
	(segment
		(start 391.183368 -85.0646)
		(end 392.495024 -83.752944)
		(width 0.1143)
		(layer "In4.Cu")
		(net "CLK_100M_MEZZ4_DP")
	)
	(segment
		(start 408.924252 -82.598768)
		(end 411.554676 -82.598768)
		(width 0.1143)
		(layer "In4.Cu")
		(net "CLK_100M_MEZZ4_DP")
	)
	(segment
		(start 371.71122 -98.658934)
		(end 372.49227 -98.658934)
		(width 0.1143)
		(layer "In4.Cu")
		(net "CLK_100M_MEZZ4_DP")
	)
	(segment
		(start 385.720844 -85.424264)
		(end 388.502398 -85.424264)
		(width 0.1143)
		(layer "In4.Cu")
		(net "CLK_100M_MEZZ4_DP")
	)
	(segment
		(start 374.537478 -98.36658)
		(end 375.0183 -97.885758)
		(width 0.1143)
		(layer "In4.Cu")
		(net "CLK_100M_MEZZ4_DP")
	)
	(segment
		(start 372.49227 -98.658934)
		(end 372.784624 -98.36658)
		(width 0.1143)
		(layer "In4.Cu")
		(net "CLK_100M_MEZZ4_DP")
	)
	(segment
		(start 383.14884 -87.996014)
		(end 385.233672 -85.911182)
		(width 0.1143)
		(layer "In4.Cu")
		(net "CLK_100M_MEZZ4_DP")
	)
	(segment
		(start 417.70935 -71.08825)
		(end 419.4937 -69.3039)
		(width 0.1143)
		(layer "In4.Cu")
		(net "CLK_100M_MEZZ4_DP")
	)
	(segment
		(start 376.778774 -93.895926)
		(end 378.367798 -93.895926)
		(width 0.1143)
		(layer "In4.Cu")
		(net "CLK_100M_MEZZ4_DP")
	)
	(segment
		(start 393.741402 -83.752944)
		(end 395.03858 -82.455766)
		(width 0.1143)
		(layer "In4.Cu")
		(net "CLK_100M_MEZZ4_DP")
	)
	(segment
		(start 416.884612 -81.924652)
		(end 417.70935 -81.099914)
		(width 0.1143)
		(layer "In4.Cu")
		(net "CLK_100M_MEZZ4_DP")
	)
	(segment
		(start 395.03858 -82.455766)
		(end 402.14042 -82.455766)
		(width 0.1143)
		(layer "In4.Cu")
		(net "CLK_100M_MEZZ4_DP")
	)
	(segment
		(start 372.409212 -101.727)
		(end 372.06047 -101.727)
		(width 0.1143)
		(layer "In4.Cu")
		(net "CLK_100M_MEZZ4_DP")
	)
	(segment
		(start 379.438154 -88.607646)
		(end 379.636274 -88.409526)
		(width 0.1143)
		(layer "In4.Cu")
		(net "CLK_100M_MEZZ4_DP")
	)
	(segment
		(start 388.862062 -85.0646)
		(end 391.183368 -85.0646)
		(width 0.1143)
		(layer "In4.Cu")
		(net "CLK_100M_MEZZ4_DP")
	)
	(segment
		(start 372.784624 -98.36658)
		(end 374.537478 -98.36658)
		(width 0.1143)
		(layer "In4.Cu")
		(net "CLK_100M_MEZZ4_DP")
	)
	(segment
		(start 372.884192 -102.20198)
		(end 372.409212 -101.727)
		(width 0.1143)
		(layer "In4.Cu")
		(net "CLK_100M_MEZZ4_DP")
	)
	(segment
		(start 385.233672 -85.911182)
		(end 385.720844 -85.424264)
		(width 0.1143)
		(layer "In4.Cu")
		(net "CLK_100M_MEZZ4_DP")
	)
	(segment
		(start 408.91841 -82.60461)
		(end 408.924252 -82.598768)
		(width 0.1143)
		(layer "In4.Cu")
		(net "CLK_100M_MEZZ4_DP")
	)
	(segment
		(start 372.06047 -101.727)
		(end 371.50675 -101.17328)
		(width 0.1143)
		(layer "In4.Cu")
		(net "CLK_100M_MEZZ4_DP")
	)
	(segment
		(start 379.438154 -92.82557)
		(end 379.438154 -88.607646)
		(width 0.1143)
		(layer "In4.Cu")
		(net "CLK_100M_MEZZ4_DP")
	)
	(segment
		(start 405.412448 -81.29778)
		(end 406.713436 -82.598768)
		(width 0.1143)
		(layer "In4.Cu")
		(net "CLK_100M_MEZZ4_DP")
	)
	(segment
		(start 403.298406 -81.29778)
		(end 405.412448 -81.29778)
		(width 0.1143)
		(layer "In4.Cu")
		(net "CLK_100M_MEZZ4_DP")
	)
	(segment
		(start 378.367798 -93.895926)
		(end 379.438154 -92.82557)
		(width 0.1143)
		(layer "In4.Cu")
		(net "CLK_100M_MEZZ4_DP")
	)
	(segment
		(start 419.4937 -69.3039)
		(end 420.534592 -69.3039)
		(width 0.1143)
		(layer "In4.Cu")
		(net "CLK_100M_MEZZ4_DP")
	)
	(segment
		(start 406.713436 -82.598768)
		(end 408.32786 -82.598768)
		(width 0.1143)
		(layer "In4.Cu")
		(net "CLK_100M_MEZZ4_DP")
	)
	(segment
		(start 381.43688 -88.409526)
		(end 381.850392 -87.996014)
		(width 0.1143)
		(layer "In4.Cu")
		(net "CLK_100M_MEZZ4_DP")
	)
	(segment
		(start 408.32786 -82.598768)
		(end 408.333702 -82.60461)
		(width 0.1143)
		(layer "In4.Cu")
		(net "CLK_100M_MEZZ4_DP")
	)
	(segment
		(start 375.0183 -97.885758)
		(end 375.0183 -95.6564)
		(width 0.1143)
		(layer "In4.Cu")
		(net "CLK_100M_MEZZ4_DP")
	)
	(segment
		(start 408.333702 -82.60461)
		(end 408.91841 -82.60461)
		(width 0.1143)
		(layer "In4.Cu")
		(net "CLK_100M_MEZZ4_DP")
	)
	(segment
		(start 412.228792 -81.924652)
		(end 416.884612 -81.924652)
		(width 0.1143)
		(layer "In4.Cu")
		(net "CLK_100M_MEZZ4_DP")
	)
	(segment
		(start 402.14042 -82.455766)
		(end 403.298406 -81.29778)
		(width 0.1143)
		(layer "In4.Cu")
		(net "CLK_100M_MEZZ4_DP")
	)
	(segment
		(start 392.495024 -83.752944)
		(end 393.741402 -83.752944)
		(width 0.1143)
		(layer "In4.Cu")
		(net "CLK_100M_MEZZ4_DP")
	)
	(segment
		(start 371.50675 -101.17328)
		(end 371.50675 -98.863404)
		(width 0.1143)
		(layer "In4.Cu")
		(net "CLK_100M_MEZZ4_DP")
	)
	(segment
		(start 371.50675 -98.863404)
		(end 371.71122 -98.658934)
		(width 0.1143)
		(layer "In4.Cu")
		(net "CLK_100M_MEZZ4_DP")
	)
	(segment
		(start 375.0183 -95.6564)
		(end 376.778774 -93.895926)
		(width 0.1143)
		(layer "In4.Cu")
		(net "CLK_100M_MEZZ4_DP")
	)
	(segment
		(start 411.554676 -82.598768)
		(end 412.228792 -81.924652)
		(width 0.1143)
		(layer "In4.Cu")
		(net "CLK_100M_MEZZ4_DP")
	)
	(segment
		(start 388.502398 -85.424264)
		(end 388.862062 -85.0646)
		(width 0.1143)
		(layer "In4.Cu")
		(net "CLK_100M_MEZZ4_DP")
	)
	(segment
		(start 379.636274 -88.409526)
		(end 381.43688 -88.409526)
		(width 0.1143)
		(layer "In4.Cu")
		(net "CLK_100M_MEZZ4_DP")
	)
	(segment
		(start 417.70935 -81.099914)
		(end 417.70935 -71.08825)
		(width 0.1143)
		(layer "In4.Cu")
		(net "CLK_100M_MEZZ4_DP")
	)
	(segment
		(start 381.850392 -87.996014)
		(end 383.14884 -87.996014)
		(width 0.1143)
		(layer "In4.Cu")
		(net "CLK_100M_MEZZ4_DP")
	)
	(segment
		(start 420.534592 -69.3039)
		(end 421.004492 -69.7738)
		(width 0.1143)
		(layer "In4.Cu")
		(net "CLK_100M_MEZZ4_DP")
	)
	(segment
		(start 372.6434 -102.6668)
		(end 372.4783 -102.5017)
		(width 0.0889)
		(layer "F.Cu")
		(net "CLK_100M_MEZZ4_DN")
	)
	(segment
		(start 372.4783 -102.336346)
		(end 372.343934 -102.20198)
		(width 0.0889)
		(layer "F.Cu")
		(net "CLK_100M_MEZZ4_DN")
	)
	(segment
		(start 373.079518 -102.6668)
		(end 372.6434 -102.6668)
		(width 0.0889)
		(layer "F.Cu")
		(net "CLK_100M_MEZZ4_DN")
	)
	(segment
		(start 463.2452 -54.790594)
		(end 462.8642 -54.790594)
		(width 0.127)
		(layer "F.Cu")
		(net "CLK_100M_MEZZ4_DN")
	)
	(segment
		(start 462.153 -54.790594)
		(end 461.772 -54.790594)
		(width 0.127)
		(layer "F.Cu")
		(net "CLK_100M_MEZZ4_DN")
	)
	(segment
		(start 462.8642 -54.790594)
		(end 462.6991 -54.955694)
		(width 0.127)
		(layer "F.Cu")
		(net "CLK_100M_MEZZ4_DN")
	)
	(segment
		(start 461.6069 -54.955694)
		(end 461.2259 -54.955694)
		(width 0.127)
		(layer "F.Cu")
		(net "CLK_100M_MEZZ4_DN")
	)
	(segment
		(start 450.229478 -54.955694)
		(end 450.064378 -54.790594)
		(width 0.127)
		(layer "F.Cu")
		(net "CLK_100M_MEZZ4_DN")
	)
	(segment
		(start 421.004492 -68.8594)
		(end 421.004492 -68.5038)
		(width 0.127)
		(layer "F.Cu")
		(net "CLK_100M_MEZZ4_DN")
	)
	(segment
		(start 429.730662 -54.0004)
		(end 427.253654 -56.477408)
		(width 0.127)
		(layer "F.Cu")
		(net "CLK_100M_MEZZ4_DN")
	)
	(segment
		(start 420.805356 -63.730378)
		(end 421.756078 -64.6811)
		(width 0.127)
		(layer "F.Cu")
		(net "CLK_100M_MEZZ4_DN")
	)
	(segment
		(start 451.321678 -54.955694)
		(end 451.156578 -54.790594)
		(width 0.127)
		(layer "F.Cu")
		(net "CLK_100M_MEZZ4_DN")
	)
	(segment
		(start 374.686576 -102.448868)
		(end 374.493536 -102.448868)
		(width 0.0889)
		(layer "F.Cu")
		(net "CLK_100M_MEZZ4_DN")
	)
	(segment
		(start 372.4783 -102.5017)
		(end 372.4783 -102.336346)
		(width 0.0889)
		(layer "F.Cu")
		(net "CLK_100M_MEZZ4_DN")
	)
	(segment
		(start 373.223028 -102.81031)
		(end 373.079518 -102.6668)
		(width 0.0889)
		(layer "F.Cu")
		(net "CLK_100M_MEZZ4_DN")
	)
	(segment
		(start 454.598278 -54.955694)
		(end 454.433178 -54.790594)
		(width 0.127)
		(layer "F.Cu")
		(net "CLK_100M_MEZZ4_DN")
	)
	(segment
		(start 453.506078 -54.955694)
		(end 453.340978 -54.790594)
		(width 0.127)
		(layer "F.Cu")
		(net "CLK_100M_MEZZ4_DN")
	)
	(segment
		(start 436.887874 -54.668674)
		(end 436.2196 -54.0004)
		(width 0.127)
		(layer "F.Cu")
		(net "CLK_100M_MEZZ4_DN")
	)
	(segment
		(start 459.9686 -54.790594)
		(end 459.5876 -54.790594)
		(width 0.127)
		(layer "F.Cu")
		(net "CLK_100M_MEZZ4_DN")
	)
	(segment
		(start 373.79783 -102.81031)
		(end 373.223028 -102.81031)
		(width 0.0889)
		(layer "F.Cu")
		(net "CLK_100M_MEZZ4_DN")
	)
	(segment
		(start 453.887078 -54.955694)
		(end 453.506078 -54.955694)
		(width 0.127)
		(layer "F.Cu")
		(net "CLK_100M_MEZZ4_DN")
	)
	(segment
		(start 420.805356 -62.37732)
		(end 420.805356 -63.730378)
		(width 0.127)
		(layer "F.Cu")
		(net "CLK_100M_MEZZ4_DN")
	)
	(segment
		(start 374.493536 -102.448868)
		(end 374.399556 -102.354888)
		(width 0.0889)
		(layer "F.Cu")
		(net "CLK_100M_MEZZ4_DN")
	)
	(segment
		(start 421.131492 -68.9864)
		(end 421.004492 -68.8594)
		(width 0.127)
		(layer "F.Cu")
		(net "CLK_100M_MEZZ4_DN")
	)
	(segment
		(start 452.959978 -54.790594)
		(end 452.794878 -54.955694)
		(width 0.127)
		(layer "F.Cu")
		(net "CLK_100M_MEZZ4_DN")
	)
	(segment
		(start 464.017868 -54.955694)
		(end 463.4103 -54.955694)
		(width 0.127)
		(layer "F.Cu")
		(net "CLK_100M_MEZZ4_DN")
	)
	(segment
		(start 461.2259 -54.955694)
		(end 461.0608 -54.790594)
		(width 0.127)
		(layer "F.Cu")
		(net "CLK_100M_MEZZ4_DN")
	)
	(segment
		(start 375.089928 -102.354888)
		(end 374.780556 -102.354888)
		(width 0.0889)
		(layer "F.Cu")
		(net "CLK_100M_MEZZ4_DN")
	)
	(segment
		(start 421.756078 -64.6811)
		(end 421.756078 -68.7832)
		(width 0.127)
		(layer "F.Cu")
		(net "CLK_100M_MEZZ4_DN")
	)
	(segment
		(start 450.064378 -54.790594)
		(end 449.683378 -54.790594)
		(width 0.127)
		(layer "F.Cu")
		(net "CLK_100M_MEZZ4_DN")
	)
	(segment
		(start 452.413878 -54.955694)
		(end 452.248778 -54.790594)
		(width 0.127)
		(layer "F.Cu")
		(net "CLK_100M_MEZZ4_DN")
	)
	(segment
		(start 424.257724 -58.924952)
		(end 420.805356 -62.37732)
		(width 0.127)
		(layer "F.Cu")
		(net "CLK_100M_MEZZ4_DN")
	)
	(segment
		(start 439.423302 -54.392068)
		(end 439.146696 -54.668674)
		(width 0.127)
		(layer "F.Cu")
		(net "CLK_100M_MEZZ4_DN")
	)
	(segment
		(start 447.47434 -54.392068)
		(end 439.423302 -54.392068)
		(width 0.127)
		(layer "F.Cu")
		(net "CLK_100M_MEZZ4_DN")
	)
	(segment
		(start 466.69325 -50.471578)
		(end 466.69325 -50.18659)
		(width 0.127)
		(layer "F.Cu")
		(net "CLK_100M_MEZZ4_DN")
	)
	(segment
		(start 427.253654 -56.477408)
		(end 426.705268 -56.477408)
		(width 0.127)
		(layer "F.Cu")
		(net "CLK_100M_MEZZ4_DN")
	)
	(segment
		(start 467.05393 -54.4576)
		(end 466.91423 -54.3179)
		(width 0.127)
		(layer "F.Cu")
		(net "CLK_100M_MEZZ4_DN")
	)
	(segment
		(start 449.137278 -54.955694)
		(end 448.972178 -54.790594)
		(width 0.127)
		(layer "F.Cu")
		(net "CLK_100M_MEZZ4_DN")
	)
	(segment
		(start 372.343934 -102.20198)
		(end 372.122192 -102.20198)
		(width 0.0889)
		(layer "F.Cu")
		(net "CLK_100M_MEZZ4_DN")
	)
	(segment
		(start 460.6798 -54.790594)
		(end 460.5147 -54.955694)
		(width 0.127)
		(layer "F.Cu")
		(net "CLK_100M_MEZZ4_DN")
	)
	(segment
		(start 466.90534 -49.9745)
		(end 469.452198 -49.9745)
		(width 0.127)
		(layer "F.Cu")
		(net "CLK_100M_MEZZ4_DN")
	)
	(segment
		(start 454.433178 -54.790594)
		(end 454.052178 -54.790594)
		(width 0.127)
		(layer "F.Cu")
		(net "CLK_100M_MEZZ4_DN")
	)
	(segment
		(start 450.610478 -54.955694)
		(end 450.229478 -54.955694)
		(width 0.127)
		(layer "F.Cu")
		(net "CLK_100M_MEZZ4_DN")
	)
	(segment
		(start 451.867778 -54.790594)
		(end 451.702678 -54.955694)
		(width 0.127)
		(layer "F.Cu")
		(net "CLK_100M_MEZZ4_DN")
	)
	(segment
		(start 451.702678 -54.955694)
		(end 451.321678 -54.955694)
		(width 0.127)
		(layer "F.Cu")
		(net "CLK_100M_MEZZ4_DN")
	)
	(segment
		(start 469.452198 -49.9745)
		(end 469.6714 -50.193702)
		(width 0.127)
		(layer "F.Cu")
		(net "CLK_100M_MEZZ4_DN")
	)
	(segment
		(start 450.775578 -54.790594)
		(end 450.610478 -54.955694)
		(width 0.127)
		(layer "F.Cu")
		(net "CLK_100M_MEZZ4_DN")
	)
	(segment
		(start 421.756078 -68.7832)
		(end 421.552878 -68.9864)
		(width 0.127)
		(layer "F.Cu")
		(net "CLK_100M_MEZZ4_DN")
	)
	(segment
		(start 439.146696 -54.668674)
		(end 436.887874 -54.668674)
		(width 0.127)
		(layer "F.Cu")
		(net "CLK_100M_MEZZ4_DN")
	)
	(segment
		(start 421.552878 -68.9864)
		(end 421.131492 -68.9864)
		(width 0.127)
		(layer "F.Cu")
		(net "CLK_100M_MEZZ4_DN")
	)
	(segment
		(start 466.9409 -51.875944)
		(end 466.9409 -50.719228)
		(width 0.127)
		(layer "F.Cu")
		(net "CLK_100M_MEZZ4_DN")
	)
	(segment
		(start 463.4103 -54.955694)
		(end 463.2452 -54.790594)
		(width 0.127)
		(layer "F.Cu")
		(net "CLK_100M_MEZZ4_DN")
	)
	(segment
		(start 453.340978 -54.790594)
		(end 452.959978 -54.790594)
		(width 0.127)
		(layer "F.Cu")
		(net "CLK_100M_MEZZ4_DN")
	)
	(segment
		(start 452.248778 -54.790594)
		(end 451.867778 -54.790594)
		(width 0.127)
		(layer "F.Cu")
		(net "CLK_100M_MEZZ4_DN")
	)
	(segment
		(start 462.3181 -54.955694)
		(end 462.153 -54.790594)
		(width 0.127)
		(layer "F.Cu")
		(net "CLK_100M_MEZZ4_DN")
	)
	(segment
		(start 461.772 -54.790594)
		(end 461.6069 -54.955694)
		(width 0.127)
		(layer "F.Cu")
		(net "CLK_100M_MEZZ4_DN")
	)
	(segment
		(start 460.5147 -54.955694)
		(end 460.1337 -54.955694)
		(width 0.127)
		(layer "F.Cu")
		(net "CLK_100M_MEZZ4_DN")
	)
	(segment
		(start 466.69325 -50.18659)
		(end 466.90534 -49.9745)
		(width 0.127)
		(layer "F.Cu")
		(net "CLK_100M_MEZZ4_DN")
	)
	(segment
		(start 374.780556 -102.354888)
		(end 374.686576 -102.448868)
		(width 0.0889)
		(layer "F.Cu")
		(net "CLK_100M_MEZZ4_DN")
	)
	(segment
		(start 374.253252 -102.354888)
		(end 373.79783 -102.81031)
		(width 0.0889)
		(layer "F.Cu")
		(net "CLK_100M_MEZZ4_DN")
	)
	(segment
		(start 464.655662 -54.3179)
		(end 464.017868 -54.955694)
		(width 0.127)
		(layer "F.Cu")
		(net "CLK_100M_MEZZ4_DN")
	)
	(segment
		(start 426.705268 -56.477408)
		(end 424.257724 -58.924952)
		(width 0.127)
		(layer "F.Cu")
		(net "CLK_100M_MEZZ4_DN")
	)
	(segment
		(start 461.0608 -54.790594)
		(end 460.6798 -54.790594)
		(width 0.127)
		(layer "F.Cu")
		(net "CLK_100M_MEZZ4_DN")
	)
	(segment
		(start 448.591178 -54.790594)
		(end 448.426078 -54.955694)
		(width 0.127)
		(layer "F.Cu")
		(net "CLK_100M_MEZZ4_DN")
	)
	(segment
		(start 469.6714 -52.659788)
		(end 467.873588 -54.4576)
		(width 0.127)
		(layer "F.Cu")
		(net "CLK_100M_MEZZ4_DN")
	)
	(segment
		(start 452.794878 -54.955694)
		(end 452.413878 -54.955694)
		(width 0.127)
		(layer "F.Cu")
		(net "CLK_100M_MEZZ4_DN")
	)
	(segment
		(start 466.91423 -54.3179)
		(end 464.655662 -54.3179)
		(width 0.127)
		(layer "F.Cu")
		(net "CLK_100M_MEZZ4_DN")
	)
	(segment
		(start 467.873588 -54.4576)
		(end 467.05393 -54.4576)
		(width 0.127)
		(layer "F.Cu")
		(net "CLK_100M_MEZZ4_DN")
	)
	(segment
		(start 460.1337 -54.955694)
		(end 459.9686 -54.790594)
		(width 0.127)
		(layer "F.Cu")
		(net "CLK_100M_MEZZ4_DN")
	)
	(segment
		(start 448.426078 -54.955694)
		(end 448.037966 -54.955694)
		(width 0.127)
		(layer "F.Cu")
		(net "CLK_100M_MEZZ4_DN")
	)
	(segment
		(start 469.6714 -50.193702)
		(end 469.6714 -52.659788)
		(width 0.127)
		(layer "F.Cu")
		(net "CLK_100M_MEZZ4_DN")
	)
	(segment
		(start 454.052178 -54.790594)
		(end 453.887078 -54.955694)
		(width 0.127)
		(layer "F.Cu")
		(net "CLK_100M_MEZZ4_DN")
	)
	(segment
		(start 459.5876 -54.790594)
		(end 459.4225 -54.955694)
		(width 0.127)
		(layer "F.Cu")
		(net "CLK_100M_MEZZ4_DN")
	)
	(segment
		(start 462.6991 -54.955694)
		(end 462.3181 -54.955694)
		(width 0.127)
		(layer "F.Cu")
		(net "CLK_100M_MEZZ4_DN")
	)
	(segment
		(start 436.2196 -54.0004)
		(end 429.730662 -54.0004)
		(width 0.127)
		(layer "F.Cu")
		(net "CLK_100M_MEZZ4_DN")
	)
	(segment
		(start 449.683378 -54.790594)
		(end 449.518278 -54.955694)
		(width 0.127)
		(layer "F.Cu")
		(net "CLK_100M_MEZZ4_DN")
	)
	(segment
		(start 449.518278 -54.955694)
		(end 449.137278 -54.955694)
		(width 0.127)
		(layer "F.Cu")
		(net "CLK_100M_MEZZ4_DN")
	)
	(segment
		(start 448.037966 -54.955694)
		(end 447.47434 -54.392068)
		(width 0.127)
		(layer "F.Cu")
		(net "CLK_100M_MEZZ4_DN")
	)
	(segment
		(start 466.9409 -50.719228)
		(end 466.69325 -50.471578)
		(width 0.127)
		(layer "F.Cu")
		(net "CLK_100M_MEZZ4_DN")
	)
	(segment
		(start 459.4225 -54.955694)
		(end 454.598278 -54.955694)
		(width 0.127)
		(layer "F.Cu")
		(net "CLK_100M_MEZZ4_DN")
	)
	(segment
		(start 448.972178 -54.790594)
		(end 448.591178 -54.790594)
		(width 0.127)
		(layer "F.Cu")
		(net "CLK_100M_MEZZ4_DN")
	)
	(segment
		(start 374.399556 -102.354888)
		(end 374.253252 -102.354888)
		(width 0.0889)
		(layer "F.Cu")
		(net "CLK_100M_MEZZ4_DN")
	)
	(segment
		(start 451.156578 -54.790594)
		(end 450.775578 -54.790594)
		(width 0.127)
		(layer "F.Cu")
		(net "CLK_100M_MEZZ4_DN")
	)
	(via
		(at 424.257724 -58.924952)
		(size 0.508)
		(drill 0.254)
		(layers "F.Cu" "B.Cu")
		(net "CLK_100M_MEZZ4_DN")
	)
	(via
		(at 372.122192 -102.20198)
		(size 0.508)
		(drill 0.254)
		(layers "F.Cu" "B.Cu")
		(net "CLK_100M_MEZZ4_DN")
	)
	(via
		(at 421.004492 -68.5038)
		(size 0.508)
		(drill 0.254)
		(layers "F.Cu" "B.Cu")
		(net "CLK_100M_MEZZ4_DN")
	)
	(segment
		(start 417.41725 -70.967092)
		(end 419.372542 -69.0118)
		(width 0.1143)
		(layer "In4.Cu")
		(net "CLK_100M_MEZZ4_DN")
	)
	(segment
		(start 371.21465 -98.742246)
		(end 371.590062 -98.366834)
		(width 0.1143)
		(layer "In4.Cu")
		(net "CLK_100M_MEZZ4_DN")
	)
	(segment
		(start 379.146054 -92.704412)
		(end 379.146054 -88.486488)
		(width 0.1143)
		(layer "In4.Cu")
		(net "CLK_100M_MEZZ4_DN")
	)
	(segment
		(start 372.122192 -102.20198)
		(end 371.21465 -101.294438)
		(width 0.1143)
		(layer "In4.Cu")
		(net "CLK_100M_MEZZ4_DN")
	)
	(segment
		(start 379.146054 -88.486488)
		(end 379.515116 -88.117426)
		(width 0.1143)
		(layer "In4.Cu")
		(net "CLK_100M_MEZZ4_DN")
	)
	(segment
		(start 378.24664 -93.603826)
		(end 379.146054 -92.704412)
		(width 0.1143)
		(layer "In4.Cu")
		(net "CLK_100M_MEZZ4_DN")
	)
	(segment
		(start 420.496492 -69.0118)
		(end 421.004492 -68.5038)
		(width 0.1143)
		(layer "In4.Cu")
		(net "CLK_100M_MEZZ4_DN")
	)
	(segment
		(start 393.620244 -83.460844)
		(end 394.917422 -82.163666)
		(width 0.1143)
		(layer "In4.Cu")
		(net "CLK_100M_MEZZ4_DN")
	)
	(segment
		(start 408.449018 -82.306668)
		(end 408.45486 -82.31251)
		(width 0.1143)
		(layer "In4.Cu")
		(net "CLK_100M_MEZZ4_DN")
	)
	(segment
		(start 381.729234 -87.703914)
		(end 383.027936 -87.703914)
		(width 0.1143)
		(layer "In4.Cu")
		(net "CLK_100M_MEZZ4_DN")
	)
	(segment
		(start 406.834594 -82.306668)
		(end 408.449018 -82.306668)
		(width 0.1143)
		(layer "In4.Cu")
		(net "CLK_100M_MEZZ4_DN")
	)
	(segment
		(start 402.019262 -82.163666)
		(end 403.177248 -81.00568)
		(width 0.1143)
		(layer "In4.Cu")
		(net "CLK_100M_MEZZ4_DN")
	)
	(segment
		(start 372.663466 -98.07448)
		(end 374.41632 -98.07448)
		(width 0.1143)
		(layer "In4.Cu")
		(net "CLK_100M_MEZZ4_DN")
	)
	(segment
		(start 394.917422 -82.163666)
		(end 402.019262 -82.163666)
		(width 0.1143)
		(layer "In4.Cu")
		(net "CLK_100M_MEZZ4_DN")
	)
	(segment
		(start 416.763454 -81.632552)
		(end 417.41725 -80.978756)
		(width 0.1143)
		(layer "In4.Cu")
		(net "CLK_100M_MEZZ4_DN")
	)
	(segment
		(start 376.657616 -93.603826)
		(end 378.24664 -93.603826)
		(width 0.1143)
		(layer "In4.Cu")
		(net "CLK_100M_MEZZ4_DN")
	)
	(segment
		(start 392.373866 -83.460844)
		(end 393.620244 -83.460844)
		(width 0.1143)
		(layer "In4.Cu")
		(net "CLK_100M_MEZZ4_DN")
	)
	(segment
		(start 383.027936 -87.703914)
		(end 385.599686 -85.132164)
		(width 0.1143)
		(layer "In4.Cu")
		(net "CLK_100M_MEZZ4_DN")
	)
	(segment
		(start 374.41632 -98.07448)
		(end 374.7262 -97.7646)
		(width 0.1143)
		(layer "In4.Cu")
		(net "CLK_100M_MEZZ4_DN")
	)
	(segment
		(start 371.21465 -101.294438)
		(end 371.21465 -98.742246)
		(width 0.1143)
		(layer "In4.Cu")
		(net "CLK_100M_MEZZ4_DN")
	)
	(segment
		(start 405.533606 -81.00568)
		(end 406.834594 -82.306668)
		(width 0.1143)
		(layer "In4.Cu")
		(net "CLK_100M_MEZZ4_DN")
	)
	(segment
		(start 379.515116 -88.117426)
		(end 381.315722 -88.117426)
		(width 0.1143)
		(layer "In4.Cu")
		(net "CLK_100M_MEZZ4_DN")
	)
	(segment
		(start 381.315722 -88.117426)
		(end 381.729234 -87.703914)
		(width 0.1143)
		(layer "In4.Cu")
		(net "CLK_100M_MEZZ4_DN")
	)
	(segment
		(start 374.7262 -97.7646)
		(end 374.7262 -95.535242)
		(width 0.1143)
		(layer "In4.Cu")
		(net "CLK_100M_MEZZ4_DN")
	)
	(segment
		(start 385.599686 -85.132164)
		(end 388.38124 -85.132164)
		(width 0.1143)
		(layer "In4.Cu")
		(net "CLK_100M_MEZZ4_DN")
	)
	(segment
		(start 417.41725 -80.978756)
		(end 417.41725 -70.967092)
		(width 0.1143)
		(layer "In4.Cu")
		(net "CLK_100M_MEZZ4_DN")
	)
	(segment
		(start 408.797252 -82.31251)
		(end 408.803094 -82.306668)
		(width 0.1143)
		(layer "In4.Cu")
		(net "CLK_100M_MEZZ4_DN")
	)
	(segment
		(start 412.107634 -81.632552)
		(end 416.763454 -81.632552)
		(width 0.1143)
		(layer "In4.Cu")
		(net "CLK_100M_MEZZ4_DN")
	)
	(segment
		(start 411.433518 -82.306668)
		(end 412.107634 -81.632552)
		(width 0.1143)
		(layer "In4.Cu")
		(net "CLK_100M_MEZZ4_DN")
	)
	(segment
		(start 419.372542 -69.0118)
		(end 420.496492 -69.0118)
		(width 0.1143)
		(layer "In4.Cu")
		(net "CLK_100M_MEZZ4_DN")
	)
	(segment
		(start 403.177248 -81.00568)
		(end 405.533606 -81.00568)
		(width 0.1143)
		(layer "In4.Cu")
		(net "CLK_100M_MEZZ4_DN")
	)
	(segment
		(start 408.803094 -82.306668)
		(end 411.433518 -82.306668)
		(width 0.1143)
		(layer "In4.Cu")
		(net "CLK_100M_MEZZ4_DN")
	)
	(segment
		(start 408.45486 -82.31251)
		(end 408.797252 -82.31251)
		(width 0.1143)
		(layer "In4.Cu")
		(net "CLK_100M_MEZZ4_DN")
	)
	(segment
		(start 388.740904 -84.7725)
		(end 391.06221 -84.7725)
		(width 0.1143)
		(layer "In4.Cu")
		(net "CLK_100M_MEZZ4_DN")
	)
	(segment
		(start 372.371112 -98.366834)
		(end 372.663466 -98.07448)
		(width 0.1143)
		(layer "In4.Cu")
		(net "CLK_100M_MEZZ4_DN")
	)
	(segment
		(start 374.7262 -95.535242)
		(end 376.657616 -93.603826)
		(width 0.1143)
		(layer "In4.Cu")
		(net "CLK_100M_MEZZ4_DN")
	)
	(segment
		(start 391.06221 -84.7725)
		(end 392.373866 -83.460844)
		(width 0.1143)
		(layer "In4.Cu")
		(net "CLK_100M_MEZZ4_DN")
	)
	(segment
		(start 388.38124 -85.132164)
		(end 388.740904 -84.7725)
		(width 0.1143)
		(layer "In4.Cu")
		(net "CLK_100M_MEZZ4_DN")
	)
	(segment
		(start 371.590062 -98.366834)
		(end 372.371112 -98.366834)
		(width 0.1143)
		(layer "In4.Cu")
		(net "CLK_100M_MEZZ4_DN")
	)
	(segment
		(start 421.022526 -66.865754)
		(end 420.870126 -66.713354)
		(width 0.127)
		(layer "F.Cu")
		(net "CLK_100M_MEZZ3_DP")
	)
	(segment
		(start 421.022526 -67.2084)
		(end 421.022526 -66.865754)
		(width 0.127)
		(layer "F.Cu")
		(net "CLK_100M_MEZZ3_DP")
	)
	(segment
		(start 420.227506 -66.713354)
		(end 419.869366 -66.355214)
		(width 0.127)
		(layer "F.Cu")
		(net "CLK_100M_MEZZ3_DP")
	)
	(segment
		(start 422.088564 -59.79668)
		(end 428.570136 -53.315108)
		(width 0.127)
		(layer "F.Cu")
		(net "CLK_100M_MEZZ3_DP")
	)
	(segment
		(start 434.425344 -52.235354)
		(end 437.859424 -48.801274)
		(width 0.127)
		(layer "F.Cu")
		(net "CLK_100M_MEZZ3_DP")
	)
	(segment
		(start 420.870126 -66.713354)
		(end 420.227506 -66.713354)
		(width 0.127)
		(layer "F.Cu")
		(net "CLK_100M_MEZZ3_DP")
	)
	(segment
		(start 375.549922 -103.354886)
		(end 375.23801 -103.042974)
		(width 0.0889)
		(layer "F.Cu")
		(net "CLK_100M_MEZZ3_DP")
	)
	(segment
		(start 375.92 -103.354886)
		(end 375.549922 -103.354886)
		(width 0.0889)
		(layer "F.Cu")
		(net "CLK_100M_MEZZ3_DP")
	)
	(segment
		(start 373.657368 -103.751126)
		(end 373.43461 -103.528368)
		(width 0.0889)
		(layer "F.Cu")
		(net "CLK_100M_MEZZ3_DP")
	)
	(segment
		(start 419.869366 -66.355214)
		(end 419.869366 -62.015878)
		(width 0.127)
		(layer "F.Cu")
		(net "CLK_100M_MEZZ3_DP")
	)
	(segment
		(start 421.022018 -67.2084)
		(end 421.022526 -67.2084)
		(width 0.127)
		(layer "F.Cu")
		(net "CLK_100M_MEZZ3_DP")
	)
	(segment
		(start 437.859424 -48.801274)
		(end 464.291172 -48.801274)
		(width 0.127)
		(layer "F.Cu")
		(net "CLK_100M_MEZZ3_DP")
	)
	(segment
		(start 374.045734 -103.751126)
		(end 373.657368 -103.751126)
		(width 0.0889)
		(layer "F.Cu")
		(net "CLK_100M_MEZZ3_DP")
	)
	(segment
		(start 373.43461 -103.528368)
		(end 373.431054 -103.528368)
		(width 0.0889)
		(layer "F.Cu")
		(net "CLK_100M_MEZZ3_DP")
	)
	(segment
		(start 464.541108 -48.551338)
		(end 464.541108 -47.481998)
		(width 0.127)
		(layer "F.Cu")
		(net "CLK_100M_MEZZ3_DP")
	)
	(segment
		(start 373.431054 -103.528368)
		(end 373.223028 -103.320342)
		(width 0.0889)
		(layer "F.Cu")
		(net "CLK_100M_MEZZ3_DP")
	)
	(segment
		(start 419.869366 -62.015878)
		(end 422.088564 -59.79668)
		(width 0.127)
		(layer "F.Cu")
		(net "CLK_100M_MEZZ3_DP")
	)
	(segment
		(start 428.570136 -53.315108)
		(end 428.9806 -53.315108)
		(width 0.127)
		(layer "F.Cu")
		(net "CLK_100M_MEZZ3_DP")
	)
	(segment
		(start 430.060354 -52.235354)
		(end 434.425344 -52.235354)
		(width 0.127)
		(layer "F.Cu")
		(net "CLK_100M_MEZZ3_DP")
	)
	(segment
		(start 374.934226 -103.042974)
		(end 374.812814 -103.164386)
		(width 0.0889)
		(layer "F.Cu")
		(net "CLK_100M_MEZZ3_DP")
	)
	(segment
		(start 374.632474 -103.164386)
		(end 374.045734 -103.751126)
		(width 0.0889)
		(layer "F.Cu")
		(net "CLK_100M_MEZZ3_DP")
	)
	(segment
		(start 375.23801 -103.042974)
		(end 374.934226 -103.042974)
		(width 0.0889)
		(layer "F.Cu")
		(net "CLK_100M_MEZZ3_DP")
	)
	(segment
		(start 428.9806 -53.315108)
		(end 430.060354 -52.235354)
		(width 0.127)
		(layer "F.Cu")
		(net "CLK_100M_MEZZ3_DP")
	)
	(segment
		(start 374.812814 -103.164386)
		(end 374.632474 -103.164386)
		(width 0.0889)
		(layer "F.Cu")
		(net "CLK_100M_MEZZ3_DP")
	)
	(segment
		(start 464.291172 -48.801274)
		(end 464.541108 -48.551338)
		(width 0.127)
		(layer "F.Cu")
		(net "CLK_100M_MEZZ3_DP")
	)
	(via
		(at 422.088564 -59.79668)
		(size 0.508)
		(drill 0.254)
		(layers "F.Cu" "B.Cu")
		(net "CLK_100M_MEZZ3_DP")
	)
	(via
		(at 421.022018 -67.2084)
		(size 0.508)
		(drill 0.254)
		(layers "F.Cu" "B.Cu")
		(net "CLK_100M_MEZZ3_DP")
	)
	(via
		(at 373.223028 -103.320342)
		(size 0.508)
		(drill 0.254)
		(layers "F.Cu" "B.Cu")
		(net "CLK_100M_MEZZ3_DP")
	)
	(segment
		(start 381.271018 -94.8817)
		(end 381.613918 -94.8817)
		(width 0.1143)
		(layer "In4.Cu")
		(net "CLK_100M_MEZZ3_DP")
	)
	(segment
		(start 382.646428 -94.328488)
		(end 382.879854 -94.328488)
		(width 0.1143)
		(layer "In4.Cu")
		(net "CLK_100M_MEZZ3_DP")
	)
	(segment
		(start 377.128024 -101.417628)
		(end 377.128024 -100.748084)
		(width 0.1143)
		(layer "In4.Cu")
		(net "CLK_100M_MEZZ3_DP")
	)
	(segment
		(start 421.531034 -66.76898)
		(end 421.398954 -66.6369)
		(width 0.1143)
		(layer "In4.Cu")
		(net "CLK_100M_MEZZ3_DP")
	)
	(segment
		(start 402.650452 -83.515962)
		(end 405.363426 -83.515962)
		(width 0.1143)
		(layer "In4.Cu")
		(net "CLK_100M_MEZZ3_DP")
	)
	(segment
		(start 416.917378 -83.98891)
		(end 418.8968 -82.009488)
		(width 0.1143)
		(layer "In4.Cu")
		(net "CLK_100M_MEZZ3_DP")
	)
	(segment
		(start 381.779018 -95.0468)
		(end 382.161542 -95.0468)
		(width 0.1143)
		(layer "In4.Cu")
		(net "CLK_100M_MEZZ3_DP")
	)
	(segment
		(start 381.613918 -94.8817)
		(end 381.779018 -95.0468)
		(width 0.1143)
		(layer "In4.Cu")
		(net "CLK_100M_MEZZ3_DP")
	)
	(segment
		(start 374.880886 -103.167688)
		(end 375.114312 -103.167688)
		(width 0.1143)
		(layer "In4.Cu")
		(net "CLK_100M_MEZZ3_DP")
	)
	(segment
		(start 374.63857 -103.410004)
		(end 374.880886 -103.167688)
		(width 0.1143)
		(layer "In4.Cu")
		(net "CLK_100M_MEZZ3_DP")
	)
	(segment
		(start 406.41143 -84.563966)
		(end 407.413714 -84.563966)
		(width 0.1143)
		(layer "In4.Cu")
		(net "CLK_100M_MEZZ3_DP")
	)
	(segment
		(start 383.75844 -90.257122)
		(end 383.75844 -89.995502)
		(width 0.1143)
		(layer "In4.Cu")
		(net "CLK_100M_MEZZ3_DP")
	)
	(segment
		(start 374.396 -103.886)
		(end 374.63857 -103.64343)
		(width 0.1143)
		(layer "In4.Cu")
		(net "CLK_100M_MEZZ3_DP")
	)
	(segment
		(start 377.4186 -101.708204)
		(end 377.128024 -101.417628)
		(width 0.1143)
		(layer "In4.Cu")
		(net "CLK_100M_MEZZ3_DP")
	)
	(segment
		(start 383.75844 -90.930222)
		(end 383.59334 -90.765122)
		(width 0.1143)
		(layer "In4.Cu")
		(net "CLK_100M_MEZZ3_DP")
	)
	(segment
		(start 372.988078 -103.555292)
		(end 372.988078 -103.71709)
		(width 0.1143)
		(layer "In4.Cu")
		(net "CLK_100M_MEZZ3_DP")
	)
	(segment
		(start 385.029456 -87.855806)
		(end 385.262882 -87.855806)
		(width 0.1143)
		(layer "In4.Cu")
		(net "CLK_100M_MEZZ3_DP")
	)
	(segment
		(start 377.1138 -95.586296)
		(end 377.653296 -95.0468)
		(width 0.1143)
		(layer "In4.Cu")
		(net "CLK_100M_MEZZ3_DP")
	)
	(segment
		(start 383.36474 -93.610176)
		(end 383.598166 -93.610176)
		(width 0.1143)
		(layer "In4.Cu")
		(net "CLK_100M_MEZZ3_DP")
	)
	(segment
		(start 383.75844 -92.962222)
		(end 383.59334 -92.797122)
		(width 0.1143)
		(layer "In4.Cu")
		(net "CLK_100M_MEZZ3_DP")
	)
	(segment
		(start 405.363426 -83.515962)
		(end 406.41143 -84.563966)
		(width 0.1143)
		(layer "In4.Cu")
		(net "CLK_100M_MEZZ3_DP")
	)
	(segment
		(start 385.262882 -87.855806)
		(end 385.996688 -87.122)
		(width 0.1143)
		(layer "In4.Cu")
		(net "CLK_100M_MEZZ3_DP")
	)
	(segment
		(start 384.786886 -88.331802)
		(end 384.786886 -88.098122)
		(width 0.1143)
		(layer "In4.Cu")
		(net "CLK_100M_MEZZ3_DP")
	)
	(segment
		(start 382.404112 -94.570804)
		(end 382.646428 -94.328488)
		(width 0.1143)
		(layer "In4.Cu")
		(net "CLK_100M_MEZZ3_DP")
	)
	(segment
		(start 383.59334 -91.438222)
		(end 383.75844 -91.273122)
		(width 0.1143)
		(layer "In4.Cu")
		(net "CLK_100M_MEZZ3_DP")
	)
	(segment
		(start 418.8968 -74.92111)
		(end 420.237412 -73.580498)
		(width 0.1143)
		(layer "In4.Cu")
		(net "CLK_100M_MEZZ3_DP")
	)
	(segment
		(start 374.63857 -103.64343)
		(end 374.63857 -103.410004)
		(width 0.1143)
		(layer "In4.Cu")
		(net "CLK_100M_MEZZ3_DP")
	)
	(segment
		(start 377.623324 -98.858324)
		(end 377.1138 -98.3488)
		(width 0.1143)
		(layer "In4.Cu")
		(net "CLK_100M_MEZZ3_DP")
	)
	(segment
		(start 412.214568 -83.98891)
		(end 416.917378 -83.98891)
		(width 0.1143)
		(layer "In4.Cu")
		(net "CLK_100M_MEZZ3_DP")
	)
	(segment
		(start 397.696182 -83.456018)
		(end 400.392392 -83.456018)
		(width 0.1143)
		(layer "In4.Cu")
		(net "CLK_100M_MEZZ3_DP")
	)
	(segment
		(start 411.849824 -83.624166)
		(end 412.214568 -83.98891)
		(width 0.1143)
		(layer "In4.Cu")
		(net "CLK_100M_MEZZ3_DP")
	)
	(segment
		(start 383.122424 -93.852492)
		(end 383.36474 -93.610176)
		(width 0.1143)
		(layer "In4.Cu")
		(net "CLK_100M_MEZZ3_DP")
	)
	(segment
		(start 383.75844 -93.449902)
		(end 383.75844 -92.962222)
		(width 0.1143)
		(layer "In4.Cu")
		(net "CLK_100M_MEZZ3_DP")
	)
	(segment
		(start 394.665962 -85.263482)
		(end 395.888718 -85.263482)
		(width 0.1143)
		(layer "In4.Cu")
		(net "CLK_100M_MEZZ3_DP")
	)
	(segment
		(start 383.59334 -91.781122)
		(end 383.59334 -91.438222)
		(width 0.1143)
		(layer "In4.Cu")
		(net "CLK_100M_MEZZ3_DP")
	)
	(segment
		(start 382.879854 -94.328488)
		(end 383.122424 -94.085918)
		(width 0.1143)
		(layer "In4.Cu")
		(net "CLK_100M_MEZZ3_DP")
	)
	(segment
		(start 383.75844 -91.946222)
		(end 383.59334 -91.781122)
		(width 0.1143)
		(layer "In4.Cu")
		(net "CLK_100M_MEZZ3_DP")
	)
	(segment
		(start 420.237412 -73.580498)
		(end 421.178228 -73.580498)
		(width 0.1143)
		(layer "In4.Cu")
		(net "CLK_100M_MEZZ3_DP")
	)
	(segment
		(start 421.025066 -66.750946)
		(end 421.022018 -67.2084)
		(width 0.1143)
		(layer "In4.Cu")
		(net "CLK_100M_MEZZ3_DP")
	)
	(segment
		(start 375.114312 -103.167688)
		(end 375.7295 -102.5525)
		(width 0.1143)
		(layer "In4.Cu")
		(net "CLK_100M_MEZZ3_DP")
	)
	(segment
		(start 400.392392 -83.456018)
		(end 401.055586 -84.119212)
		(width 0.1143)
		(layer "In4.Cu")
		(net "CLK_100M_MEZZ3_DP")
	)
	(segment
		(start 377.128024 -100.748084)
		(end 377.623324 -100.252784)
		(width 0.1143)
		(layer "In4.Cu")
		(net "CLK_100M_MEZZ3_DP")
	)
	(segment
		(start 377.623324 -100.252784)
		(end 377.623324 -98.858324)
		(width 0.1143)
		(layer "In4.Cu")
		(net "CLK_100M_MEZZ3_DP")
	)
	(segment
		(start 421.398954 -66.6369)
		(end 421.140128 -66.6369)
		(width 0.1143)
		(layer "In4.Cu")
		(net "CLK_100M_MEZZ3_DP")
	)
	(segment
		(start 385.996688 -87.122)
		(end 388.8486 -87.122)
		(width 0.1143)
		(layer "In4.Cu")
		(net "CLK_100M_MEZZ3_DP")
	)
	(segment
		(start 383.75844 -92.289122)
		(end 383.75844 -91.946222)
		(width 0.1143)
		(layer "In4.Cu")
		(net "CLK_100M_MEZZ3_DP")
	)
	(segment
		(start 389.8646 -86.106)
		(end 393.823444 -86.106)
		(width 0.1143)
		(layer "In4.Cu")
		(net "CLK_100M_MEZZ3_DP")
	)
	(segment
		(start 383.59334 -90.765122)
		(end 383.59334 -90.422222)
		(width 0.1143)
		(layer "In4.Cu")
		(net "CLK_100M_MEZZ3_DP")
	)
	(segment
		(start 377.1138 -98.3488)
		(end 377.1138 -95.586296)
		(width 0.1143)
		(layer "In4.Cu")
		(net "CLK_100M_MEZZ3_DP")
	)
	(segment
		(start 381.105918 -95.0468)
		(end 381.271018 -94.8817)
		(width 0.1143)
		(layer "In4.Cu")
		(net "CLK_100M_MEZZ3_DP")
	)
	(segment
		(start 421.178228 -73.580498)
		(end 421.531034 -73.227692)
		(width 0.1143)
		(layer "In4.Cu")
		(net "CLK_100M_MEZZ3_DP")
	)
	(segment
		(start 383.59334 -90.422222)
		(end 383.75844 -90.257122)
		(width 0.1143)
		(layer "In4.Cu")
		(net "CLK_100M_MEZZ3_DP")
	)
	(segment
		(start 376.9868 -102.5525)
		(end 377.4186 -102.1207)
		(width 0.1143)
		(layer "In4.Cu")
		(net "CLK_100M_MEZZ3_DP")
	)
	(segment
		(start 383.59334 -92.797122)
		(end 383.59334 -92.454222)
		(width 0.1143)
		(layer "In4.Cu")
		(net "CLK_100M_MEZZ3_DP")
	)
	(segment
		(start 401.055586 -84.119212)
		(end 402.047202 -84.119212)
		(width 0.1143)
		(layer "In4.Cu")
		(net "CLK_100M_MEZZ3_DP")
	)
	(segment
		(start 407.413714 -84.563966)
		(end 408.353514 -83.624166)
		(width 0.1143)
		(layer "In4.Cu")
		(net "CLK_100M_MEZZ3_DP")
	)
	(segment
		(start 382.161542 -95.0468)
		(end 382.404112 -94.80423)
		(width 0.1143)
		(layer "In4.Cu")
		(net "CLK_100M_MEZZ3_DP")
	)
	(segment
		(start 383.75844 -89.995502)
		(end 384.495802 -89.25814)
		(width 0.1143)
		(layer "In4.Cu")
		(net "CLK_100M_MEZZ3_DP")
	)
	(segment
		(start 418.8968 -82.009488)
		(end 418.8968 -74.92111)
		(width 0.1143)
		(layer "In4.Cu")
		(net "CLK_100M_MEZZ3_DP")
	)
	(segment
		(start 395.888718 -85.263482)
		(end 397.696182 -83.456018)
		(width 0.1143)
		(layer "In4.Cu")
		(net "CLK_100M_MEZZ3_DP")
	)
	(segment
		(start 373.156988 -103.886)
		(end 374.396 -103.886)
		(width 0.1143)
		(layer "In4.Cu")
		(net "CLK_100M_MEZZ3_DP")
	)
	(segment
		(start 383.75844 -91.273122)
		(end 383.75844 -90.930222)
		(width 0.1143)
		(layer "In4.Cu")
		(net "CLK_100M_MEZZ3_DP")
	)
	(segment
		(start 384.495802 -88.622886)
		(end 384.786886 -88.331802)
		(width 0.1143)
		(layer "In4.Cu")
		(net "CLK_100M_MEZZ3_DP")
	)
	(segment
		(start 408.353514 -83.624166)
		(end 411.849824 -83.624166)
		(width 0.1143)
		(layer "In4.Cu")
		(net "CLK_100M_MEZZ3_DP")
	)
	(segment
		(start 384.495802 -89.25814)
		(end 384.495802 -88.622886)
		(width 0.1143)
		(layer "In4.Cu")
		(net "CLK_100M_MEZZ3_DP")
	)
	(segment
		(start 421.140128 -66.6369)
		(end 421.025066 -66.750946)
		(width 0.1143)
		(layer "In4.Cu")
		(net "CLK_100M_MEZZ3_DP")
	)
	(segment
		(start 383.59334 -92.454222)
		(end 383.75844 -92.289122)
		(width 0.1143)
		(layer "In4.Cu")
		(net "CLK_100M_MEZZ3_DP")
	)
	(segment
		(start 402.047202 -84.119212)
		(end 402.650452 -83.515962)
		(width 0.1143)
		(layer "In4.Cu")
		(net "CLK_100M_MEZZ3_DP")
	)
	(segment
		(start 383.122424 -94.085918)
		(end 383.122424 -93.852492)
		(width 0.1143)
		(layer "In4.Cu")
		(net "CLK_100M_MEZZ3_DP")
	)
	(segment
		(start 372.988078 -103.71709)
		(end 373.156988 -103.886)
		(width 0.1143)
		(layer "In4.Cu")
		(net "CLK_100M_MEZZ3_DP")
	)
	(segment
		(start 377.653296 -95.0468)
		(end 381.105918 -95.0468)
		(width 0.1143)
		(layer "In4.Cu")
		(net "CLK_100M_MEZZ3_DP")
	)
	(segment
		(start 373.223028 -103.320342)
		(end 372.988078 -103.555292)
		(width 0.1143)
		(layer "In4.Cu")
		(net "CLK_100M_MEZZ3_DP")
	)
	(segment
		(start 375.7295 -102.5525)
		(end 376.9868 -102.5525)
		(width 0.1143)
		(layer "In4.Cu")
		(net "CLK_100M_MEZZ3_DP")
	)
	(segment
		(start 377.4186 -102.1207)
		(end 377.4186 -101.708204)
		(width 0.1143)
		(layer "In4.Cu")
		(net "CLK_100M_MEZZ3_DP")
	)
	(segment
		(start 393.823444 -86.106)
		(end 394.665962 -85.263482)
		(width 0.1143)
		(layer "In4.Cu")
		(net "CLK_100M_MEZZ3_DP")
	)
	(segment
		(start 421.531034 -73.227692)
		(end 421.531034 -66.76898)
		(width 0.1143)
		(layer "In4.Cu")
		(net "CLK_100M_MEZZ3_DP")
	)
	(segment
		(start 388.8486 -87.122)
		(end 389.8646 -86.106)
		(width 0.1143)
		(layer "In4.Cu")
		(net "CLK_100M_MEZZ3_DP")
	)
	(segment
		(start 383.598166 -93.610176)
		(end 383.75844 -93.449902)
		(width 0.1143)
		(layer "In4.Cu")
		(net "CLK_100M_MEZZ3_DP")
	)
	(segment
		(start 384.786886 -88.098122)
		(end 385.029456 -87.855806)
		(width 0.1143)
		(layer "In4.Cu")
		(net "CLK_100M_MEZZ3_DP")
	)
	(segment
		(start 382.404112 -94.80423)
		(end 382.404112 -94.570804)
		(width 0.1143)
		(layer "In4.Cu")
		(net "CLK_100M_MEZZ3_DP")
	)
	(segment
		(start 430.186846 -52.540154)
		(end 430.628044 -52.540154)
		(width 0.127)
		(layer "F.Cu")
		(net "CLK_100M_MEZZ3_DN")
	)
	(segment
		(start 372.824502 -103.409242)
		(end 372.735602 -103.320342)
		(width 0.0889)
		(layer "F.Cu")
		(net "CLK_100M_MEZZ3_DN")
	)
	(segment
		(start 372.735602 -103.320342)
		(end 372.461028 -103.320342)
		(width 0.0889)
		(layer "F.Cu")
		(net "CLK_100M_MEZZ3_DN")
	)
	(segment
		(start 421.004492 -66.2686)
		(end 420.864538 -66.408554)
		(width 0.127)
		(layer "F.Cu")
		(net "CLK_100M_MEZZ3_DN")
	)
	(segment
		(start 421.005 -65.9638)
		(end 421.004492 -65.964308)
		(width 0.127)
		(layer "F.Cu")
		(net "CLK_100M_MEZZ3_DN")
	)
	(segment
		(start 420.174166 -66.228722)
		(end 420.174166 -62.14237)
		(width 0.127)
		(layer "F.Cu")
		(net "CLK_100M_MEZZ3_DN")
	)
	(segment
		(start 431.174144 -52.705254)
		(end 431.339244 -52.540154)
		(width 0.127)
		(layer "F.Cu")
		(net "CLK_100M_MEZZ3_DN")
	)
	(segment
		(start 372.824502 -103.660702)
		(end 372.824502 -103.409242)
		(width 0.0889)
		(layer "F.Cu")
		(net "CLK_100M_MEZZ3_DN")
	)
	(segment
		(start 375.089928 -103.354886)
		(end 374.711468 -103.354886)
		(width 0.0889)
		(layer "F.Cu")
		(net "CLK_100M_MEZZ3_DN")
	)
	(segment
		(start 421.004492 -65.964308)
		(end 421.004492 -66.2686)
		(width 0.127)
		(layer "F.Cu")
		(net "CLK_100M_MEZZ3_DN")
	)
	(segment
		(start 374.711468 -103.354886)
		(end 374.124728 -103.941626)
		(width 0.0889)
		(layer "F.Cu")
		(net "CLK_100M_MEZZ3_DN")
	)
	(segment
		(start 420.174166 -62.14237)
		(end 420.914576 -61.40196)
		(width 0.127)
		(layer "F.Cu")
		(net "CLK_100M_MEZZ3_DN")
	)
	(segment
		(start 429.107092 -53.619908)
		(end 430.186846 -52.540154)
		(width 0.127)
		(layer "F.Cu")
		(net "CLK_100M_MEZZ3_DN")
	)
	(segment
		(start 430.793144 -52.705254)
		(end 431.174144 -52.705254)
		(width 0.127)
		(layer "F.Cu")
		(net "CLK_100M_MEZZ3_DN")
	)
	(segment
		(start 420.91483 -61.40196)
		(end 420.91483 -61.401706)
		(width 0.127)
		(layer "F.Cu")
		(net "CLK_100M_MEZZ3_DN")
	)
	(segment
		(start 428.696628 -53.619908)
		(end 429.107092 -53.619908)
		(width 0.127)
		(layer "F.Cu")
		(net "CLK_100M_MEZZ3_DN")
	)
	(segment
		(start 465.340954 -48.559466)
		(end 465.340954 -47.481998)
		(width 0.127)
		(layer "F.Cu")
		(net "CLK_100M_MEZZ3_DN")
	)
	(segment
		(start 374.124728 -103.941626)
		(end 373.578374 -103.941626)
		(width 0.0889)
		(layer "F.Cu")
		(net "CLK_100M_MEZZ3_DN")
	)
	(segment
		(start 464.794346 -49.106074)
		(end 465.340954 -48.559466)
		(width 0.127)
		(layer "F.Cu")
		(net "CLK_100M_MEZZ3_DN")
	)
	(segment
		(start 437.985916 -49.106074)
		(end 464.794346 -49.106074)
		(width 0.127)
		(layer "F.Cu")
		(net "CLK_100M_MEZZ3_DN")
	)
	(segment
		(start 431.339244 -52.540154)
		(end 434.551836 -52.540154)
		(width 0.127)
		(layer "F.Cu")
		(net "CLK_100M_MEZZ3_DN")
	)
	(segment
		(start 420.864538 -66.408554)
		(end 420.353998 -66.408554)
		(width 0.127)
		(layer "F.Cu")
		(net "CLK_100M_MEZZ3_DN")
	)
	(segment
		(start 430.628044 -52.540154)
		(end 430.793144 -52.705254)
		(width 0.127)
		(layer "F.Cu")
		(net "CLK_100M_MEZZ3_DN")
	)
	(segment
		(start 420.914576 -61.40196)
		(end 420.91483 -61.40196)
		(width 0.127)
		(layer "F.Cu")
		(net "CLK_100M_MEZZ3_DN")
	)
	(segment
		(start 372.9228 -103.759)
		(end 372.824502 -103.660702)
		(width 0.0889)
		(layer "F.Cu")
		(net "CLK_100M_MEZZ3_DN")
	)
	(segment
		(start 420.91483 -61.401706)
		(end 428.696628 -53.619908)
		(width 0.127)
		(layer "F.Cu")
		(net "CLK_100M_MEZZ3_DN")
	)
	(segment
		(start 373.578374 -103.941626)
		(end 373.395748 -103.759)
		(width 0.0889)
		(layer "F.Cu")
		(net "CLK_100M_MEZZ3_DN")
	)
	(segment
		(start 434.551836 -52.540154)
		(end 437.985916 -49.106074)
		(width 0.127)
		(layer "F.Cu")
		(net "CLK_100M_MEZZ3_DN")
	)
	(segment
		(start 373.395748 -103.759)
		(end 372.9228 -103.759)
		(width 0.0889)
		(layer "F.Cu")
		(net "CLK_100M_MEZZ3_DN")
	)
	(segment
		(start 420.353998 -66.408554)
		(end 420.174166 -66.228722)
		(width 0.127)
		(layer "F.Cu")
		(net "CLK_100M_MEZZ3_DN")
	)
	(via
		(at 421.005 -65.9638)
		(size 0.508)
		(drill 0.254)
		(layers "F.Cu" "B.Cu")
		(net "CLK_100M_MEZZ3_DN")
	)
	(via
		(at 372.461028 -103.320342)
		(size 0.508)
		(drill 0.254)
		(layers "F.Cu" "B.Cu")
		(net "CLK_100M_MEZZ3_DN")
	)
	(via
		(at 420.914576 -61.40196)
		(size 0.508)
		(drill 0.254)
		(layers "F.Cu" "B.Cu")
		(net "CLK_100M_MEZZ3_DN")
	)
	(segment
		(start 377.915424 -100.373942)
		(end 377.915424 -98.737166)
		(width 0.1143)
		(layer "In4.Cu")
		(net "CLK_100M_MEZZ3_DN")
	)
	(segment
		(start 382.696212 -94.925388)
		(end 382.696212 -94.691962)
		(width 0.1143)
		(layer "In4.Cu")
		(net "CLK_100M_MEZZ3_DN")
	)
	(segment
		(start 420.35857 -73.872598)
		(end 421.299386 -73.872598)
		(width 0.1143)
		(layer "In4.Cu")
		(net "CLK_100M_MEZZ3_DN")
	)
	(segment
		(start 384.05308 -93.56852)
		(end 384.05308 -90.11412)
		(width 0.1143)
		(layer "In4.Cu")
		(net "CLK_100M_MEZZ3_DN")
	)
	(segment
		(start 384.787902 -88.744044)
		(end 386.117846 -87.4141)
		(width 0.1143)
		(layer "In4.Cu")
		(net "CLK_100M_MEZZ3_DN")
	)
	(segment
		(start 384.05308 -90.11412)
		(end 384.787902 -89.379298)
		(width 0.1143)
		(layer "In4.Cu")
		(net "CLK_100M_MEZZ3_DN")
	)
	(segment
		(start 396.009876 -85.555582)
		(end 397.81734 -83.748118)
		(width 0.1143)
		(layer "In4.Cu")
		(net "CLK_100M_MEZZ3_DN")
	)
	(segment
		(start 382.696212 -94.691962)
		(end 382.767586 -94.620588)
		(width 0.1143)
		(layer "In4.Cu")
		(net "CLK_100M_MEZZ3_DN")
	)
	(segment
		(start 421.823134 -73.34885)
		(end 421.823134 -66.647822)
		(width 0.1143)
		(layer "In4.Cu")
		(net "CLK_100M_MEZZ3_DN")
	)
	(segment
		(start 411.728666 -83.916266)
		(end 412.09341 -84.28101)
		(width 0.1143)
		(layer "In4.Cu")
		(net "CLK_100M_MEZZ3_DN")
	)
	(segment
		(start 372.695978 -103.838248)
		(end 373.03583 -104.1781)
		(width 0.1143)
		(layer "In4.Cu")
		(net "CLK_100M_MEZZ3_DN")
	)
	(segment
		(start 408.474672 -83.916266)
		(end 411.728666 -83.916266)
		(width 0.1143)
		(layer "In4.Cu")
		(net "CLK_100M_MEZZ3_DN")
	)
	(segment
		(start 383.414524 -93.97365)
		(end 383.485898 -93.902276)
		(width 0.1143)
		(layer "In4.Cu")
		(net "CLK_100M_MEZZ3_DN")
	)
	(segment
		(start 377.107958 -102.8446)
		(end 377.7107 -102.241858)
		(width 0.1143)
		(layer "In4.Cu")
		(net "CLK_100M_MEZZ3_DN")
	)
	(segment
		(start 421.299386 -73.872598)
		(end 421.823134 -73.34885)
		(width 0.1143)
		(layer "In4.Cu")
		(net "CLK_100M_MEZZ3_DN")
	)
	(segment
		(start 421.520112 -66.3448)
		(end 421.134794 -66.3448)
		(width 0.1143)
		(layer "In4.Cu")
		(net "CLK_100M_MEZZ3_DN")
	)
	(segment
		(start 383.485898 -93.902276)
		(end 383.719324 -93.902276)
		(width 0.1143)
		(layer "In4.Cu")
		(net "CLK_100M_MEZZ3_DN")
	)
	(segment
		(start 417.038536 -84.28101)
		(end 419.1889 -82.130646)
		(width 0.1143)
		(layer "In4.Cu")
		(net "CLK_100M_MEZZ3_DN")
	)
	(segment
		(start 402.77161 -83.808062)
		(end 405.242268 -83.808062)
		(width 0.1143)
		(layer "In4.Cu")
		(net "CLK_100M_MEZZ3_DN")
	)
	(segment
		(start 407.534872 -84.856066)
		(end 408.474672 -83.916266)
		(width 0.1143)
		(layer "In4.Cu")
		(net "CLK_100M_MEZZ3_DN")
	)
	(segment
		(start 388.969758 -87.4141)
		(end 389.985758 -86.3981)
		(width 0.1143)
		(layer "In4.Cu")
		(net "CLK_100M_MEZZ3_DN")
	)
	(segment
		(start 397.81734 -83.748118)
		(end 400.271234 -83.748118)
		(width 0.1143)
		(layer "In4.Cu")
		(net "CLK_100M_MEZZ3_DN")
	)
	(segment
		(start 383.001012 -94.620588)
		(end 383.414524 -94.207076)
		(width 0.1143)
		(layer "In4.Cu")
		(net "CLK_100M_MEZZ3_DN")
	)
	(segment
		(start 421.823134 -66.647822)
		(end 421.520112 -66.3448)
		(width 0.1143)
		(layer "In4.Cu")
		(net "CLK_100M_MEZZ3_DN")
	)
	(segment
		(start 377.420124 -100.869242)
		(end 377.915424 -100.373942)
		(width 0.1143)
		(layer "In4.Cu")
		(net "CLK_100M_MEZZ3_DN")
	)
	(segment
		(start 389.985758 -86.3981)
		(end 393.944602 -86.3981)
		(width 0.1143)
		(layer "In4.Cu")
		(net "CLK_100M_MEZZ3_DN")
	)
	(segment
		(start 386.117846 -87.4141)
		(end 388.969758 -87.4141)
		(width 0.1143)
		(layer "In4.Cu")
		(net "CLK_100M_MEZZ3_DN")
	)
	(segment
		(start 377.7107 -102.241858)
		(end 377.7107 -101.587046)
		(width 0.1143)
		(layer "In4.Cu")
		(net "CLK_100M_MEZZ3_DN")
	)
	(segment
		(start 384.787902 -89.379298)
		(end 384.787902 -88.744044)
		(width 0.1143)
		(layer "In4.Cu")
		(net "CLK_100M_MEZZ3_DN")
	)
	(segment
		(start 405.242268 -83.808062)
		(end 406.290272 -84.856066)
		(width 0.1143)
		(layer "In4.Cu")
		(net "CLK_100M_MEZZ3_DN")
	)
	(segment
		(start 400.934428 -84.411312)
		(end 402.16836 -84.411312)
		(width 0.1143)
		(layer "In4.Cu")
		(net "CLK_100M_MEZZ3_DN")
	)
	(segment
		(start 374.517158 -104.1781)
		(end 375.850658 -102.8446)
		(width 0.1143)
		(layer "In4.Cu")
		(net "CLK_100M_MEZZ3_DN")
	)
	(segment
		(start 373.03583 -104.1781)
		(end 374.517158 -104.1781)
		(width 0.1143)
		(layer "In4.Cu")
		(net "CLK_100M_MEZZ3_DN")
	)
	(segment
		(start 393.944602 -86.3981)
		(end 394.78712 -85.555582)
		(width 0.1143)
		(layer "In4.Cu")
		(net "CLK_100M_MEZZ3_DN")
	)
	(segment
		(start 377.7107 -101.587046)
		(end 377.420124 -101.29647)
		(width 0.1143)
		(layer "In4.Cu")
		(net "CLK_100M_MEZZ3_DN")
	)
	(segment
		(start 383.719324 -93.902276)
		(end 384.05308 -93.56852)
		(width 0.1143)
		(layer "In4.Cu")
		(net "CLK_100M_MEZZ3_DN")
	)
	(segment
		(start 377.420124 -101.29647)
		(end 377.420124 -100.869242)
		(width 0.1143)
		(layer "In4.Cu")
		(net "CLK_100M_MEZZ3_DN")
	)
	(segment
		(start 382.2827 -95.3389)
		(end 382.696212 -94.925388)
		(width 0.1143)
		(layer "In4.Cu")
		(net "CLK_100M_MEZZ3_DN")
	)
	(segment
		(start 394.78712 -85.555582)
		(end 396.009876 -85.555582)
		(width 0.1143)
		(layer "In4.Cu")
		(net "CLK_100M_MEZZ3_DN")
	)
	(segment
		(start 377.4059 -95.707454)
		(end 377.774454 -95.3389)
		(width 0.1143)
		(layer "In4.Cu")
		(net "CLK_100M_MEZZ3_DN")
	)
	(segment
		(start 372.461028 -103.320342)
		(end 372.695978 -103.555292)
		(width 0.1143)
		(layer "In4.Cu")
		(net "CLK_100M_MEZZ3_DN")
	)
	(segment
		(start 377.774454 -95.3389)
		(end 382.2827 -95.3389)
		(width 0.1143)
		(layer "In4.Cu")
		(net "CLK_100M_MEZZ3_DN")
	)
	(segment
		(start 419.1889 -75.042268)
		(end 420.35857 -73.872598)
		(width 0.1143)
		(layer "In4.Cu")
		(net "CLK_100M_MEZZ3_DN")
	)
	(segment
		(start 375.850658 -102.8446)
		(end 377.107958 -102.8446)
		(width 0.1143)
		(layer "In4.Cu")
		(net "CLK_100M_MEZZ3_DN")
	)
	(segment
		(start 421.002968 -66.212466)
		(end 421.005 -65.9638)
		(width 0.1143)
		(layer "In4.Cu")
		(net "CLK_100M_MEZZ3_DN")
	)
	(segment
		(start 419.1889 -82.130646)
		(end 419.1889 -75.042268)
		(width 0.1143)
		(layer "In4.Cu")
		(net "CLK_100M_MEZZ3_DN")
	)
	(segment
		(start 406.290272 -84.856066)
		(end 407.534872 -84.856066)
		(width 0.1143)
		(layer "In4.Cu")
		(net "CLK_100M_MEZZ3_DN")
	)
	(segment
		(start 372.695978 -103.555292)
		(end 372.695978 -103.838248)
		(width 0.1143)
		(layer "In4.Cu")
		(net "CLK_100M_MEZZ3_DN")
	)
	(segment
		(start 382.767586 -94.620588)
		(end 383.001012 -94.620588)
		(width 0.1143)
		(layer "In4.Cu")
		(net "CLK_100M_MEZZ3_DN")
	)
	(segment
		(start 421.134794 -66.3448)
		(end 421.002968 -66.212466)
		(width 0.1143)
		(layer "In4.Cu")
		(net "CLK_100M_MEZZ3_DN")
	)
	(segment
		(start 400.271234 -83.748118)
		(end 400.934428 -84.411312)
		(width 0.1143)
		(layer "In4.Cu")
		(net "CLK_100M_MEZZ3_DN")
	)
	(segment
		(start 377.4059 -98.227642)
		(end 377.4059 -95.707454)
		(width 0.1143)
		(layer "In4.Cu")
		(net "CLK_100M_MEZZ3_DN")
	)
	(segment
		(start 377.915424 -98.737166)
		(end 377.4059 -98.227642)
		(width 0.1143)
		(layer "In4.Cu")
		(net "CLK_100M_MEZZ3_DN")
	)
	(segment
		(start 383.414524 -94.207076)
		(end 383.414524 -93.97365)
		(width 0.1143)
		(layer "In4.Cu")
		(net "CLK_100M_MEZZ3_DN")
	)
	(segment
		(start 412.09341 -84.28101)
		(end 417.038536 -84.28101)
		(width 0.1143)
		(layer "In4.Cu")
		(net "CLK_100M_MEZZ3_DN")
	)
	(segment
		(start 402.16836 -84.411312)
		(end 402.77161 -83.808062)
		(width 0.1143)
		(layer "In4.Cu")
		(net "CLK_100M_MEZZ3_DN")
	)
	(segment
		(start 135.382254 -54.913784)
		(end 135.953754 -54.913784)
		(width 0.1143)
		(layer "F.Cu")
		(net "UPI_CPU1_CPU0_P1P1_DP<9>")
	)
	(segment
		(start 295.23182 -58.876438)
		(end 295.80332 -58.876438)
		(width 0.1143)
		(layer "F.Cu")
		(net "UPI_CPU1_CPU0_P1P1_DP<9>")
	)
	(via
		(at 295.80332 -58.876438)
		(size 0.508)
		(drill 0.254)
		(layers "F.Cu" "B.Cu")
		(net "UPI_CPU1_CPU0_P1P1_DP<9>")
	)
	(via
		(at 135.953754 -54.913784)
		(size 0.508)
		(drill 0.254)
		(layers "F.Cu" "B.Cu")
		(net "UPI_CPU1_CPU0_P1P1_DP<9>")
	)
	(segment
		(start 191.82842 -37.34689)
		(end 188.371988 -37.213794)
		(width 0.1143)
		(layer "In9.Cu")
		(net "UPI_CPU1_CPU0_P1P1_DP<9>")
	)
	(segment
		(start 135.077454 -55.009288)
		(end 135.723122 -55.009288)
		(width 0.0889)
		(layer "In9.Cu")
		(net "UPI_CPU1_CPU0_P1P1_DP<9>")
	)
	(segment
		(start 180.47335 -38.730428)
		(end 173.577758 -42.805096)
		(width 0.1143)
		(layer "In9.Cu")
		(net "UPI_CPU1_CPU0_P1P1_DP<9>")
	)
	(segment
		(start 295.45661 -57.685686)
		(end 295.46296 -57.675018)
		(width 0.0889)
		(layer "In9.Cu")
		(net "UPI_CPU1_CPU0_P1P1_DP<9>")
	)
	(segment
		(start 134.215124 -54.513734)
		(end 134.24789 -54.513734)
		(width 0.0889)
		(layer "In9.Cu")
		(net "UPI_CPU1_CPU0_P1P1_DP<9>")
	)
	(segment
		(start 295.451784 -57.694322)
		(end 295.45661 -57.685686)
		(width 0.0889)
		(layer "In9.Cu")
		(net "UPI_CPU1_CPU0_P1P1_DP<9>")
	)
	(segment
		(start 145.842482 -45.131482)
		(end 142.583408 -45.301408)
		(width 0.1143)
		(layer "In9.Cu")
		(net "UPI_CPU1_CPU0_P1P1_DP<9>")
	)
	(segment
		(start 142.583408 -45.301408)
		(end 136.942322 -47.130462)
		(width 0.1143)
		(layer "In9.Cu")
		(net "UPI_CPU1_CPU0_P1P1_DP<9>")
	)
	(segment
		(start 295.451784 -56.703722)
		(end 295.45661 -56.695086)
		(width 0.0889)
		(layer "In9.Cu")
		(net "UPI_CPU1_CPU0_P1P1_DP<9>")
	)
	(segment
		(start 288.122106 -46.218856)
		(end 284.062424 -45.164502)
		(width 0.1143)
		(layer "In9.Cu")
		(net "UPI_CPU1_CPU0_P1P1_DP<9>")
	)
	(segment
		(start 136.942322 -47.130462)
		(end 136.720326 -47.21479)
		(width 0.1143)
		(layer "In9.Cu")
		(net "UPI_CPU1_CPU0_P1P1_DP<9>")
	)
	(segment
		(start 135.271002 -48.67021)
		(end 133.77799 -50.163222)
		(width 0.0889)
		(layer "In9.Cu")
		(net "UPI_CPU1_CPU0_P1P1_DP<9>")
	)
	(segment
		(start 171.772834 -43.536108)
		(end 171.770548 -43.537124)
		(width 0.1143)
		(layer "In9.Cu")
		(net "UPI_CPU1_CPU0_P1P1_DP<9>")
	)
	(segment
		(start 295.45661 -56.695086)
		(end 295.46296 -56.684418)
		(width 0.0889)
		(layer "In9.Cu")
		(net "UPI_CPU1_CPU0_P1P1_DP<9>")
	)
	(segment
		(start 264.600182 -40.480234)
		(end 261.632954 -41.32072)
		(width 0.1143)
		(layer "In9.Cu")
		(net "UPI_CPU1_CPU0_P1P1_DP<9>")
	)
	(segment
		(start 284.062424 -45.164502)
		(end 264.600182 -40.480234)
		(width 0.1143)
		(layer "In9.Cu")
		(net "UPI_CPU1_CPU0_P1P1_DP<9>")
	)
	(segment
		(start 161.042858 -44.701968)
		(end 160.494726 -44.600622)
		(width 0.1143)
		(layer "In9.Cu")
		(net "UPI_CPU1_CPU0_P1P1_DP<9>")
	)
	(segment
		(start 294.494966 -51.016916)
		(end 292.99154 -49.010062)
		(width 0.1143)
		(layer "In9.Cu")
		(net "UPI_CPU1_CPU0_P1P1_DP<9>")
	)
	(segment
		(start 242.930172 -39.545006)
		(end 240.630202 -39.182548)
		(width 0.1143)
		(layer "In9.Cu")
		(net "UPI_CPU1_CPU0_P1P1_DP<9>")
	)
	(segment
		(start 240.630202 -39.182548)
		(end 236.551978 -38.637972)
		(width 0.1143)
		(layer "In9.Cu")
		(net "UPI_CPU1_CPU0_P1P1_DP<9>")
	)
	(segment
		(start 135.271002 -48.59274)
		(end 135.271002 -48.67021)
		(width 0.0889)
		(layer "In9.Cu")
		(net "UPI_CPU1_CPU0_P1P1_DP<9>")
	)
	(segment
		(start 133.718554 -53.217318)
		(end 133.724904 -53.227986)
		(width 0.0889)
		(layer "In9.Cu")
		(net "UPI_CPU1_CPU0_P1P1_DP<9>")
	)
	(segment
		(start 295.45661 -55.704486)
		(end 295.46296 -55.693818)
		(width 0.0889)
		(layer "In9.Cu")
		(net "UPI_CPU1_CPU0_P1P1_DP<9>")
	)
	(segment
		(start 135.7122 -48.15205)
		(end 135.711692 -48.15205)
		(width 0.1143)
		(layer "In9.Cu")
		(net "UPI_CPU1_CPU0_P1P1_DP<9>")
	)
	(segment
		(start 222.396812 -39.836598)
		(end 212.230208 -40.697404)
		(width 0.1143)
		(layer "In9.Cu")
		(net "UPI_CPU1_CPU0_P1P1_DP<9>")
	)
	(segment
		(start 160.494726 -44.600622)
		(end 155.994608 -42.751248)
		(width 0.1143)
		(layer "In9.Cu")
		(net "UPI_CPU1_CPU0_P1P1_DP<9>")
	)
	(segment
		(start 195.070222 -38.566852)
		(end 191.82842 -37.34689)
		(width 0.1143)
		(layer "In9.Cu")
		(net "UPI_CPU1_CPU0_P1P1_DP<9>")
	)
	(segment
		(start 133.724904 -51.646836)
		(end 133.718554 -51.657504)
		(width 0.0889)
		(layer "In9.Cu")
		(net "UPI_CPU1_CPU0_P1P1_DP<9>")
	)
	(segment
		(start 135.711692 -48.15205)
		(end 135.271002 -48.59274)
		(width 0.1143)
		(layer "In9.Cu")
		(net "UPI_CPU1_CPU0_P1P1_DP<9>")
	)
	(segment
		(start 295.451784 -54.722522)
		(end 295.45661 -54.713886)
		(width 0.0889)
		(layer "In9.Cu")
		(net "UPI_CPU1_CPU0_P1P1_DP<9>")
	)
	(segment
		(start 173.577758 -42.805096)
		(end 171.772834 -43.536108)
		(width 0.1143)
		(layer "In9.Cu")
		(net "UPI_CPU1_CPU0_P1P1_DP<9>")
	)
	(segment
		(start 169.61739 -44.313856)
		(end 169.121328 -44.492926)
		(width 0.1143)
		(layer "In9.Cu")
		(net "UPI_CPU1_CPU0_P1P1_DP<9>")
	)
	(segment
		(start 212.230208 -40.697404)
		(end 199.139302 -37.413692)
		(width 0.1143)
		(layer "In9.Cu")
		(net "UPI_CPU1_CPU0_P1P1_DP<9>")
	)
	(segment
		(start 133.77799 -50.163222)
		(end 133.77799 -51.46675)
		(width 0.0889)
		(layer "In9.Cu")
		(net "UPI_CPU1_CPU0_P1P1_DP<9>")
	)
	(segment
		(start 294.494966 -52.4002)
		(end 294.494966 -51.016916)
		(width 0.1143)
		(layer "In9.Cu")
		(net "UPI_CPU1_CPU0_P1P1_DP<9>")
	)
	(segment
		(start 171.770548 -43.537124)
		(end 169.61739 -44.313856)
		(width 0.1143)
		(layer "In9.Cu")
		(net "UPI_CPU1_CPU0_P1P1_DP<9>")
	)
	(segment
		(start 257.700272 -40.786558)
		(end 249.343164 -37.325554)
		(width 0.1143)
		(layer "In9.Cu")
		(net "UPI_CPU1_CPU0_P1P1_DP<9>")
	)
	(segment
		(start 249.343164 -37.325554)
		(end 246.718836 -37.325554)
		(width 0.1143)
		(layer "In9.Cu")
		(net "UPI_CPU1_CPU0_P1P1_DP<9>")
	)
	(segment
		(start 290.624514 -47.045372)
		(end 288.244026 -46.259242)
		(width 0.1143)
		(layer "In9.Cu")
		(net "UPI_CPU1_CPU0_P1P1_DP<9>")
	)
	(segment
		(start 169.121328 -44.492926)
		(end 167.78859 -44.974002)
		(width 0.1143)
		(layer "In9.Cu")
		(net "UPI_CPU1_CPU0_P1P1_DP<9>")
	)
	(segment
		(start 236.551978 -38.637972)
		(end 222.396812 -39.836598)
		(width 0.1143)
		(layer "In9.Cu")
		(net "UPI_CPU1_CPU0_P1P1_DP<9>")
	)
	(segment
		(start 294.59809 -53.628036)
		(end 294.4368 -53.34889)
		(width 0.0889)
		(layer "In9.Cu")
		(net "UPI_CPU1_CPU0_P1P1_DP<9>")
	)
	(segment
		(start 292.99154 -49.010062)
		(end 292.599364 -48.518064)
		(width 0.1143)
		(layer "In9.Cu")
		(net "UPI_CPU1_CPU0_P1P1_DP<9>")
	)
	(segment
		(start 164.907214 -45.51807)
		(end 161.042858 -44.701968)
		(width 0.1143)
		(layer "In9.Cu")
		(net "UPI_CPU1_CPU0_P1P1_DP<9>")
	)
	(segment
		(start 288.244026 -46.259242)
		(end 288.122106 -46.218856)
		(width 0.1143)
		(layer "In9.Cu")
		(net "UPI_CPU1_CPU0_P1P1_DP<9>")
	)
	(segment
		(start 294.4368 -52.458366)
		(end 294.494966 -52.4002)
		(width 0.0889)
		(layer "In9.Cu")
		(net "UPI_CPU1_CPU0_P1P1_DP<9>")
	)
	(segment
		(start 167.78859 -44.974002)
		(end 164.907214 -45.51807)
		(width 0.1143)
		(layer "In9.Cu")
		(net "UPI_CPU1_CPU0_P1P1_DP<9>")
	)
	(segment
		(start 295.80332 -58.876438)
		(end 295.704768 -58.77814)
		(width 0.0889)
		(layer "In9.Cu")
		(net "UPI_CPU1_CPU0_P1P1_DP<9>")
	)
	(segment
		(start 294.4368 -53.34889)
		(end 294.4368 -52.458366)
		(width 0.0889)
		(layer "In9.Cu")
		(net "UPI_CPU1_CPU0_P1P1_DP<9>")
	)
	(segment
		(start 136.720326 -47.21479)
		(end 135.7122 -48.15205)
		(width 0.1143)
		(layer "In9.Cu")
		(net "UPI_CPU1_CPU0_P1P1_DP<9>")
	)
	(segment
		(start 133.72973 -52.6288)
		(end 133.724904 -52.637436)
		(width 0.0889)
		(layer "In9.Cu")
		(net "UPI_CPU1_CPU0_P1P1_DP<9>")
	)
	(segment
		(start 246.718836 -37.325554)
		(end 242.930172 -39.545006)
		(width 0.1143)
		(layer "In9.Cu")
		(net "UPI_CPU1_CPU0_P1P1_DP<9>")
	)
	(segment
		(start 295.45661 -54.713886)
		(end 295.46296 -54.703218)
		(width 0.0889)
		(layer "In9.Cu")
		(net "UPI_CPU1_CPU0_P1P1_DP<9>")
	)
	(segment
		(start 199.139302 -37.413692)
		(end 195.070222 -38.566852)
		(width 0.1143)
		(layer "In9.Cu")
		(net "UPI_CPU1_CPU0_P1P1_DP<9>")
	)
	(segment
		(start 261.632954 -41.32072)
		(end 257.700272 -40.786558)
		(width 0.1143)
		(layer "In9.Cu")
		(net "UPI_CPU1_CPU0_P1P1_DP<9>")
	)
	(segment
		(start 294.59809 -53.627782)
		(end 294.59809 -53.628036)
		(width 0.0889)
		(layer "In9.Cu")
		(net "UPI_CPU1_CPU0_P1P1_DP<9>")
	)
	(segment
		(start 295.451784 -55.713122)
		(end 295.45661 -55.704486)
		(width 0.0889)
		(layer "In9.Cu")
		(net "UPI_CPU1_CPU0_P1P1_DP<9>")
	)
	(segment
		(start 188.371988 -37.213794)
		(end 180.47335 -38.730428)
		(width 0.1143)
		(layer "In9.Cu")
		(net "UPI_CPU1_CPU0_P1P1_DP<9>")
	)
	(segment
		(start 292.599364 -48.518064)
		(end 290.624514 -47.045372)
		(width 0.1143)
		(layer "In9.Cu")
		(net "UPI_CPU1_CPU0_P1P1_DP<9>")
	)
	(segment
		(start 155.994608 -42.751248)
		(end 145.842482 -45.131482)
		(width 0.1143)
		(layer "In9.Cu")
		(net "UPI_CPU1_CPU0_P1P1_DP<9>")
	)
	(segment
		(start 294.957754 -53.827934)
		(end 294.933624 -53.827934)
		(width 0.0889)
		(layer "In9.Cu")
		(net "UPI_CPU1_CPU0_P1P1_DP<9>")
	)
	(arc
		(start 133.724904 -52.637436)
		(mid 133.645682 -52.926554)
		(end 133.718554 -53.217318)
		(width 0.0889)
		(layer "In9.Cu")
		(net "UPI_CPU1_CPU0_P1P1_DP<9>")
	)
	(arc
		(start 295.535858 -58.369962)
		(mid 295.514233 -58.222834)
		(end 295.45661 -58.085736)
		(width 0.0889)
		(layer "In9.Cu")
		(net "UPI_CPU1_CPU0_P1P1_DP<9>")
	)
	(arc
		(start 133.724904 -52.237386)
		(mid 133.778374 -52.432449)
		(end 133.72973 -52.6288)
		(width 0.0889)
		(layer "In9.Cu")
		(net "UPI_CPU1_CPU0_P1P1_DP<9>")
	)
	(arc
		(start 133.724904 -53.227986)
		(mid 133.778403 -53.427884)
		(end 133.724904 -53.627782)
		(width 0.0889)
		(layer "In9.Cu")
		(net "UPI_CPU1_CPU0_P1P1_DP<9>")
	)
	(arc
		(start 134.583424 -54.713886)
		(mid 134.792032 -54.925818)
		(end 135.077454 -55.009288)
		(width 0.0889)
		(layer "In9.Cu")
		(net "UPI_CPU1_CPU0_P1P1_DP<9>")
	)
	(arc
		(start 294.933624 -53.827934)
		(mid 294.739774 -53.771584)
		(end 294.59809 -53.627782)
		(width 0.0889)
		(layer "In9.Cu")
		(net "UPI_CPU1_CPU0_P1P1_DP<9>")
	)
	(arc
		(start 295.46296 -54.703218)
		(mid 295.456783 -54.123286)
		(end 294.957754 -53.827934)
		(width 0.0889)
		(layer "In9.Cu")
		(net "UPI_CPU1_CPU0_P1P1_DP<9>")
	)
	(arc
		(start 295.45661 -56.104536)
		(mid 295.40314 -55.909473)
		(end 295.451784 -55.713122)
		(width 0.0889)
		(layer "In9.Cu")
		(net "UPI_CPU1_CPU0_P1P1_DP<9>")
	)
	(arc
		(start 133.718554 -51.657504)
		(mid 133.645756 -51.948267)
		(end 133.724904 -52.237386)
		(width 0.0889)
		(layer "In9.Cu")
		(net "UPI_CPU1_CPU0_P1P1_DP<9>")
	)
	(arc
		(start 295.45661 -55.113936)
		(mid 295.40314 -54.918873)
		(end 295.451784 -54.722522)
		(width 0.0889)
		(layer "In9.Cu")
		(net "UPI_CPU1_CPU0_P1P1_DP<9>")
	)
	(arc
		(start 295.45661 -57.095136)
		(mid 295.40314 -56.900073)
		(end 295.451784 -56.703722)
		(width 0.0889)
		(layer "In9.Cu")
		(net "UPI_CPU1_CPU0_P1P1_DP<9>")
	)
	(arc
		(start 295.46296 -55.693818)
		(mid 295.535758 -55.403055)
		(end 295.45661 -55.113936)
		(width 0.0889)
		(layer "In9.Cu")
		(net "UPI_CPU1_CPU0_P1P1_DP<9>")
	)
	(arc
		(start 295.704768 -58.77814)
		(mid 295.579719 -58.590851)
		(end 295.535858 -58.369962)
		(width 0.0889)
		(layer "In9.Cu")
		(net "UPI_CPU1_CPU0_P1P1_DP<9>")
	)
	(arc
		(start 133.77799 -51.46675)
		(mid 133.762137 -51.559942)
		(end 133.724904 -51.646836)
		(width 0.0889)
		(layer "In9.Cu")
		(net "UPI_CPU1_CPU0_P1P1_DP<9>")
	)
	(arc
		(start 295.45661 -58.085736)
		(mid 295.40314 -57.890673)
		(end 295.451784 -57.694322)
		(width 0.0889)
		(layer "In9.Cu")
		(net "UPI_CPU1_CPU0_P1P1_DP<9>")
	)
	(arc
		(start 135.723122 -55.009288)
		(mid 135.847929 -54.984462)
		(end 135.953754 -54.913784)
		(width 0.0889)
		(layer "In9.Cu")
		(net "UPI_CPU1_CPU0_P1P1_DP<9>")
	)
	(arc
		(start 134.24789 -54.513734)
		(mid 134.44174 -54.570084)
		(end 134.583424 -54.713886)
		(width 0.0889)
		(layer "In9.Cu")
		(net "UPI_CPU1_CPU0_P1P1_DP<9>")
	)
	(arc
		(start 295.46296 -57.675018)
		(mid 295.535758 -57.384255)
		(end 295.45661 -57.095136)
		(width 0.0889)
		(layer "In9.Cu")
		(net "UPI_CPU1_CPU0_P1P1_DP<9>")
	)
	(arc
		(start 133.724904 -53.627782)
		(mid 133.71965 -54.20929)
		(end 134.215124 -54.513734)
		(width 0.0889)
		(layer "In9.Cu")
		(net "UPI_CPU1_CPU0_P1P1_DP<9>")
	)
	(arc
		(start 295.46296 -56.684418)
		(mid 295.535758 -56.393655)
		(end 295.45661 -56.104536)
		(width 0.0889)
		(layer "In9.Cu")
		(net "UPI_CPU1_CPU0_P1P1_DP<9>")
	)
	(segment
		(start 294.3733 -57.390538)
		(end 294.9448 -57.390538)
		(width 0.1143)
		(layer "F.Cu")
		(net "UPI_CPU1_CPU0_P1P1_DP<8>")
	)
	(segment
		(start 133.665214 -53.923184)
		(end 134.236714 -53.923184)
		(width 0.1143)
		(layer "F.Cu")
		(net "UPI_CPU1_CPU0_P1P1_DP<8>")
	)
	(via
		(at 294.9448 -57.390538)
		(size 0.508)
		(drill 0.254)
		(layers "F.Cu" "B.Cu")
		(net "UPI_CPU1_CPU0_P1P1_DP<8>")
	)
	(via
		(at 134.236714 -53.923184)
		(size 0.508)
		(drill 0.254)
		(layers "F.Cu" "B.Cu")
		(net "UPI_CPU1_CPU0_P1P1_DP<8>")
	)
	(segment
		(start 164.69868 -46.193964)
		(end 161.160206 -45.408342)
		(width 0.1143)
		(layer "In9.Cu")
		(net "UPI_CPU1_CPU0_P1P1_DP<8>")
	)
	(segment
		(start 135.4963 -51.016154)
		(end 135.4963 -51.552856)
		(width 0.0889)
		(layer "In9.Cu")
		(net "UPI_CPU1_CPU0_P1P1_DP<8>")
	)
	(segment
		(start 294.10406 -55.313834)
		(end 294.071294 -55.313834)
		(width 0.0889)
		(layer "In9.Cu")
		(net "UPI_CPU1_CPU0_P1P1_DP<8>")
	)
	(segment
		(start 134.353554 -53.806598)
		(end 134.236714 -53.923184)
		(width 0.0889)
		(layer "In9.Cu")
		(net "UPI_CPU1_CPU0_P1P1_DP<8>")
	)
	(segment
		(start 134.583424 -53.132736)
		(end 134.577074 -53.143404)
		(width 0.0889)
		(layer "In9.Cu")
		(net "UPI_CPU1_CPU0_P1P1_DP<8>")
	)
	(segment
		(start 246.903494 -37.966396)
		(end 243.121434 -40.24376)
		(width 0.1143)
		(layer "In9.Cu")
		(net "UPI_CPU1_CPU0_P1P1_DP<8>")
	)
	(segment
		(start 249.145044 -37.966396)
		(end 246.903494 -37.966396)
		(width 0.1143)
		(layer "In9.Cu")
		(net "UPI_CPU1_CPU0_P1P1_DP<8>")
	)
	(segment
		(start 174.861474 -43.150028)
		(end 168.959276 -45.277024)
		(width 0.1143)
		(layer "In9.Cu")
		(net "UPI_CPU1_CPU0_P1P1_DP<8>")
	)
	(segment
		(start 213.548468 -41.325546)
		(end 212.387434 -41.450006)
		(width 0.1143)
		(layer "In9.Cu")
		(net "UPI_CPU1_CPU0_P1P1_DP<8>")
	)
	(segment
		(start 286.382714 -46.415198)
		(end 264.459466 -41.186608)
		(width 0.1143)
		(layer "In9.Cu")
		(net "UPI_CPU1_CPU0_P1P1_DP<8>")
	)
	(segment
		(start 135.442452 -50.949352)
		(end 135.442452 -50.962306)
		(width 0.0889)
		(layer "In9.Cu")
		(net "UPI_CPU1_CPU0_P1P1_DP<8>")
	)
	(segment
		(start 137.080244 -48.102266)
		(end 135.442452 -49.624996)
		(width 0.1143)
		(layer "In9.Cu")
		(net "UPI_CPU1_CPU0_P1P1_DP<8>")
	)
	(segment
		(start 293.58209 -53.939186)
		(end 293.58209 -53.253132)
		(width 0.0889)
		(layer "In9.Cu")
		(net "UPI_CPU1_CPU0_P1P1_DP<8>")
	)
	(segment
		(start 155.691586 -43.63466)
		(end 144.36979 -46.140878)
		(width 0.1143)
		(layer "In9.Cu")
		(net "UPI_CPU1_CPU0_P1P1_DP<8>")
	)
	(segment
		(start 191.759586 -38.482524)
		(end 188.733684 -38.94074)
		(width 0.1143)
		(layer "In9.Cu")
		(net "UPI_CPU1_CPU0_P1P1_DP<8>")
	)
	(segment
		(start 261.694422 -41.994328)
		(end 257.457702 -41.409112)
		(width 0.1143)
		(layer "In9.Cu")
		(net "UPI_CPU1_CPU0_P1P1_DP<8>")
	)
	(segment
		(start 294.59809 -56.599836)
		(end 294.593264 -56.5912)
		(width 0.0889)
		(layer "In9.Cu")
		(net "UPI_CPU1_CPU0_P1P1_DP<8>")
	)
	(segment
		(start 135.109712 -51.846988)
		(end 135.073644 -51.846988)
		(width 0.0889)
		(layer "In9.Cu")
		(net "UPI_CPU1_CPU0_P1P1_DP<8>")
	)
	(segment
		(start 160.017206 -45.154596)
		(end 156.419804 -43.645836)
		(width 0.1143)
		(layer "In9.Cu")
		(net "UPI_CPU1_CPU0_P1P1_DP<8>")
	)
	(segment
		(start 293.734744 -54.722522)
		(end 293.73957 -54.713886)
		(width 0.0889)
		(layer "In9.Cu")
		(net "UPI_CPU1_CPU0_P1P1_DP<8>")
	)
	(segment
		(start 292.12794 -49.171606)
		(end 290.351972 -47.724822)
		(width 0.1143)
		(layer "In9.Cu")
		(net "UPI_CPU1_CPU0_P1P1_DP<8>")
	)
	(segment
		(start 293.63289 -51.183286)
		(end 292.465252 -49.58334)
		(width 0.1143)
		(layer "In9.Cu")
		(net "UPI_CPU1_CPU0_P1P1_DP<8>")
	)
	(segment
		(start 188.733684 -38.94074)
		(end 188.195712 -39.155624)
		(width 0.1143)
		(layer "In9.Cu")
		(net "UPI_CPU1_CPU0_P1P1_DP<8>")
	)
	(segment
		(start 294.9448 -57.390538)
		(end 294.651684 -57.559448)
		(width 0.0889)
		(layer "In9.Cu")
		(net "UPI_CPU1_CPU0_P1P1_DP<8>")
	)
	(segment
		(start 135.442452 -50.962306)
		(end 135.4963 -51.016154)
		(width 0.0889)
		(layer "In9.Cu")
		(net "UPI_CPU1_CPU0_P1P1_DP<8>")
	)
	(segment
		(start 257.457702 -41.409112)
		(end 249.145044 -37.966396)
		(width 0.1143)
		(layer "In9.Cu")
		(net "UPI_CPU1_CPU0_P1P1_DP<8>")
	)
	(segment
		(start 144.36979 -46.140878)
		(end 141.73327 -46.496986)
		(width 0.1143)
		(layer "In9.Cu")
		(net "UPI_CPU1_CPU0_P1P1_DP<8>")
	)
	(segment
		(start 168.959276 -45.277024)
		(end 168.109392 -45.583348)
		(width 0.1143)
		(layer "In9.Cu")
		(net "UPI_CPU1_CPU0_P1P1_DP<8>")
	)
	(segment
		(start 175.356774 -42.971466)
		(end 174.861474 -43.150028)
		(width 0.1143)
		(layer "In9.Cu")
		(net "UPI_CPU1_CPU0_P1P1_DP<8>")
	)
	(segment
		(start 293.63289 -53.202332)
		(end 293.63289 -53.180234)
		(width 0.0889)
		(layer "In9.Cu")
		(net "UPI_CPU1_CPU0_P1P1_DP<8>")
	)
	(segment
		(start 243.121434 -40.24376)
		(end 236.6264 -39.295324)
		(width 0.1143)
		(layer "In9.Cu")
		(net "UPI_CPU1_CPU0_P1P1_DP<8>")
	)
	(segment
		(start 156.419804 -43.645836)
		(end 156.152088 -43.542204)
		(width 0.1143)
		(layer "In9.Cu")
		(net "UPI_CPU1_CPU0_P1P1_DP<8>")
	)
	(segment
		(start 264.459466 -41.186608)
		(end 261.882636 -41.93413)
		(width 0.1143)
		(layer "In9.Cu")
		(net "UPI_CPU1_CPU0_P1P1_DP<8>")
	)
	(segment
		(start 188.195712 -39.155624)
		(end 182.1942 -40.7924)
		(width 0.1143)
		(layer "In9.Cu")
		(net "UPI_CPU1_CPU0_P1P1_DP<8>")
	)
	(segment
		(start 161.160206 -45.408088)
		(end 160.017206 -45.154596)
		(width 0.1143)
		(layer "In9.Cu")
		(net "UPI_CPU1_CPU0_P1P1_DP<8>")
	)
	(segment
		(start 182.1942 -40.7924)
		(end 181.235604 -40.853614)
		(width 0.1143)
		(layer "In9.Cu")
		(net "UPI_CPU1_CPU0_P1P1_DP<8>")
	)
	(segment
		(start 261.882636 -41.93413)
		(end 261.694422 -41.994328)
		(width 0.1143)
		(layer "In9.Cu")
		(net "UPI_CPU1_CPU0_P1P1_DP<8>")
	)
	(segment
		(start 168.109392 -45.583348)
		(end 164.69868 -46.193964)
		(width 0.1143)
		(layer "In9.Cu")
		(net "UPI_CPU1_CPU0_P1P1_DP<8>")
	)
	(segment
		(start 294.651684 -57.559448)
		(end 294.572944 -57.538112)
		(width 0.0889)
		(layer "In9.Cu")
		(net "UPI_CPU1_CPU0_P1P1_DP<8>")
	)
	(segment
		(start 293.63289 -53.180234)
		(end 293.63289 -51.183286)
		(width 0.1143)
		(layer "In9.Cu")
		(net "UPI_CPU1_CPU0_P1P1_DP<8>")
	)
	(segment
		(start 293.73957 -54.713886)
		(end 293.74592 -54.703218)
		(width 0.0889)
		(layer "In9.Cu")
		(net "UPI_CPU1_CPU0_P1P1_DP<8>")
	)
	(segment
		(start 199.17664 -38.114478)
		(end 194.42176 -39.480744)
		(width 0.1143)
		(layer "In9.Cu")
		(net "UPI_CPU1_CPU0_P1P1_DP<8>")
	)
	(segment
		(start 135.4963 -51.552856)
		(end 135.441944 -51.646836)
		(width 0.0889)
		(layer "In9.Cu")
		(net "UPI_CPU1_CPU0_P1P1_DP<8>")
	)
	(segment
		(start 137.812018 -47.849536)
		(end 137.812018 -47.84979)
		(width 0.1143)
		(layer "In9.Cu")
		(net "UPI_CPU1_CPU0_P1P1_DP<8>")
	)
	(segment
		(start 141.73327 -46.496986)
		(end 137.812018 -47.849536)
		(width 0.1143)
		(layer "In9.Cu")
		(net "UPI_CPU1_CPU0_P1P1_DP<8>")
	)
	(segment
		(start 294.60444 -56.610504)
		(end 294.59809 -56.599836)
		(width 0.0889)
		(layer "In9.Cu")
		(net "UPI_CPU1_CPU0_P1P1_DP<8>")
	)
	(segment
		(start 156.152088 -43.542204)
		(end 155.691586 -43.63466)
		(width 0.1143)
		(layer "In9.Cu")
		(net "UPI_CPU1_CPU0_P1P1_DP<8>")
	)
	(segment
		(start 194.42176 -39.480744)
		(end 191.759586 -38.482524)
		(width 0.1143)
		(layer "In9.Cu")
		(net "UPI_CPU1_CPU0_P1P1_DP<8>")
	)
	(segment
		(start 292.465252 -49.58334)
		(end 292.12794 -49.171606)
		(width 0.1143)
		(layer "In9.Cu")
		(net "UPI_CPU1_CPU0_P1P1_DP<8>")
	)
	(segment
		(start 212.387434 -41.450006)
		(end 199.17664 -38.114478)
		(width 0.1143)
		(layer "In9.Cu")
		(net "UPI_CPU1_CPU0_P1P1_DP<8>")
	)
	(segment
		(start 161.160206 -45.408342)
		(end 161.160206 -45.408088)
		(width 0.1143)
		(layer "In9.Cu")
		(net "UPI_CPU1_CPU0_P1P1_DP<8>")
	)
	(segment
		(start 293.672514 -54.02961)
		(end 293.58209 -53.939186)
		(width 0.0889)
		(layer "In9.Cu")
		(net "UPI_CPU1_CPU0_P1P1_DP<8>")
	)
	(segment
		(start 137.812018 -47.84979)
		(end 137.080244 -48.102266)
		(width 0.1143)
		(layer "In9.Cu")
		(net "UPI_CPU1_CPU0_P1P1_DP<8>")
	)
	(segment
		(start 135.442452 -49.624996)
		(end 135.442452 -50.949352)
		(width 0.1143)
		(layer "In9.Cu")
		(net "UPI_CPU1_CPU0_P1P1_DP<8>")
	)
	(segment
		(start 236.6264 -39.295324)
		(end 213.548468 -41.325546)
		(width 0.1143)
		(layer "In9.Cu")
		(net "UPI_CPU1_CPU0_P1P1_DP<8>")
	)
	(segment
		(start 181.235604 -40.853614)
		(end 175.356774 -42.971466)
		(width 0.1143)
		(layer "In9.Cu")
		(net "UPI_CPU1_CPU0_P1P1_DP<8>")
	)
	(segment
		(start 293.58209 -53.253132)
		(end 293.63289 -53.202332)
		(width 0.0889)
		(layer "In9.Cu")
		(net "UPI_CPU1_CPU0_P1P1_DP<8>")
	)
	(segment
		(start 290.351972 -47.724822)
		(end 286.382714 -46.415198)
		(width 0.1143)
		(layer "In9.Cu")
		(net "UPI_CPU1_CPU0_P1P1_DP<8>")
	)
	(arc
		(start 134.577074 -53.143404)
		(mid 134.520775 -53.288176)
		(end 134.504176 -53.442616)
		(width 0.0889)
		(layer "In9.Cu")
		(net "UPI_CPU1_CPU0_P1P1_DP<8>")
	)
	(arc
		(start 294.59809 -57.190386)
		(mid 294.677312 -56.901268)
		(end 294.60444 -56.610504)
		(width 0.0889)
		(layer "In9.Cu")
		(net "UPI_CPU1_CPU0_P1P1_DP<8>")
	)
	(arc
		(start 293.74592 -54.703218)
		(mid 293.815852 -54.359023)
		(end 293.678102 -54.03596)
		(width 0.0889)
		(layer "In9.Cu")
		(net "UPI_CPU1_CPU0_P1P1_DP<8>")
	)
	(arc
		(start 135.073644 -51.846988)
		(mid 134.578167 -52.151431)
		(end 134.583424 -52.73294)
		(width 0.0889)
		(layer "In9.Cu")
		(net "UPI_CPU1_CPU0_P1P1_DP<8>")
	)
	(arc
		(start 293.678102 -54.03596)
		(mid 293.675319 -54.032775)
		(end 293.672514 -54.02961)
		(width 0.0889)
		(layer "In9.Cu")
		(net "UPI_CPU1_CPU0_P1P1_DP<8>")
	)
	(arc
		(start 294.593264 -56.5912)
		(mid 294.544509 -56.394848)
		(end 294.59809 -56.199786)
		(width 0.0889)
		(layer "In9.Cu")
		(net "UPI_CPU1_CPU0_P1P1_DP<8>")
	)
	(arc
		(start 134.504176 -53.442616)
		(mid 134.465087 -53.6396)
		(end 134.353554 -53.806598)
		(width 0.0889)
		(layer "In9.Cu")
		(net "UPI_CPU1_CPU0_P1P1_DP<8>")
	)
	(arc
		(start 294.071294 -55.313834)
		(mid 293.738376 -55.111843)
		(end 293.734744 -54.722522)
		(width 0.0889)
		(layer "In9.Cu")
		(net "UPI_CPU1_CPU0_P1P1_DP<8>")
	)
	(arc
		(start 135.441944 -51.646836)
		(mid 135.301676 -51.789792)
		(end 135.109712 -51.846988)
		(width 0.0889)
		(layer "In9.Cu")
		(net "UPI_CPU1_CPU0_P1P1_DP<8>")
	)
	(arc
		(start 294.572944 -57.538112)
		(mid 294.552739 -57.4704)
		(end 294.54475 -57.40019)
		(width 0.0889)
		(layer "In9.Cu")
		(net "UPI_CPU1_CPU0_P1P1_DP<8>")
	)
	(arc
		(start 294.59809 -56.199786)
		(mid 294.602419 -55.616614)
		(end 294.10406 -55.313834)
		(width 0.0889)
		(layer "In9.Cu")
		(net "UPI_CPU1_CPU0_P1P1_DP<8>")
	)
	(arc
		(start 294.54475 -57.40019)
		(mid 294.556981 -57.29162)
		(end 294.59809 -57.190386)
		(width 0.0889)
		(layer "In9.Cu")
		(net "UPI_CPU1_CPU0_P1P1_DP<8>")
	)
	(arc
		(start 134.583424 -52.73294)
		(mid 134.636923 -52.932838)
		(end 134.583424 -53.132736)
		(width 0.0889)
		(layer "In9.Cu")
		(net "UPI_CPU1_CPU0_P1P1_DP<8>")
	)
	(segment
		(start 135.382254 -52.932838)
		(end 135.953754 -52.932838)
		(width 0.1143)
		(layer "F.Cu")
		(net "UPI_CPU1_CPU0_P1P1_DP<7>")
	)
	(segment
		(start 294.3733 -60.362338)
		(end 294.9448 -60.362338)
		(width 0.1143)
		(layer "F.Cu")
		(net "UPI_CPU1_CPU0_P1P1_DP<7>")
	)
	(via
		(at 294.9448 -60.362338)
		(size 0.508)
		(drill 0.254)
		(layers "F.Cu" "B.Cu")
		(net "UPI_CPU1_CPU0_P1P1_DP<7>")
	)
	(via
		(at 135.953754 -52.932838)
		(size 0.508)
		(drill 0.254)
		(layers "F.Cu" "B.Cu")
		(net "UPI_CPU1_CPU0_P1P1_DP<7>")
	)
	(segment
		(start 222.396812 -41.529762)
		(end 212.30463 -42.39768)
		(width 0.1143)
		(layer "In9.Cu")
		(net "UPI_CPU1_CPU0_P1P1_DP<7>")
	)
	(segment
		(start 135.966708 -52.532788)
		(end 135.942578 -52.532788)
		(width 0.0889)
		(layer "In9.Cu")
		(net "UPI_CPU1_CPU0_P1P1_DP<7>")
	)
	(segment
		(start 156.051758 -44.530772)
		(end 144.415256 -47.206916)
		(width 0.1143)
		(layer "In9.Cu")
		(net "UPI_CPU1_CPU0_P1P1_DP<7>")
	)
	(segment
		(start 257.20421 -42.371518)
		(end 248.812304 -38.895782)
		(width 0.1143)
		(layer "In9.Cu")
		(net "UPI_CPU1_CPU0_P1P1_DP<7>")
	)
	(segment
		(start 291.613336 -50.120804)
		(end 289.468814 -48.526954)
		(width 0.1143)
		(layer "In9.Cu")
		(net "UPI_CPU1_CPU0_P1P1_DP<7>")
	)
	(segment
		(start 136.017 -53.2892)
		(end 136.017 -52.996084)
		(width 0.0889)
		(layer "In9.Cu")
		(net "UPI_CPU1_CPU0_P1P1_DP<7>")
	)
	(segment
		(start 139.605766 -48.713898)
		(end 139.38504 -48.774604)
		(width 0.1143)
		(layer "In9.Cu")
		(net "UPI_CPU1_CPU0_P1P1_DP<7>")
	)
	(segment
		(start 164.850826 -47.214536)
		(end 159.762698 -46.067218)
		(width 0.1143)
		(layer "In9.Cu")
		(net "UPI_CPU1_CPU0_P1P1_DP<7>")
	)
	(segment
		(start 243.310664 -41.265094)
		(end 236.876844 -40.284654)
		(width 0.1143)
		(layer "In9.Cu")
		(net "UPI_CPU1_CPU0_P1P1_DP<7>")
	)
	(segment
		(start 292.71595 -54.713886)
		(end 292.7096 -54.703218)
		(width 0.0889)
		(layer "In9.Cu")
		(net "UPI_CPU1_CPU0_P1P1_DP<7>")
	)
	(segment
		(start 139.728194 -48.498252)
		(end 139.605766 -48.713898)
		(width 0.1143)
		(layer "In9.Cu")
		(net "UPI_CPU1_CPU0_P1P1_DP<7>")
	)
	(segment
		(start 199.223376 -39.151052)
		(end 190.778638 -42.290746)
		(width 0.1143)
		(layer "In9.Cu")
		(net "UPI_CPU1_CPU0_P1P1_DP<7>")
	)
	(segment
		(start 293.57447 -56.599836)
		(end 293.579296 -56.5912)
		(width 0.0889)
		(layer "In9.Cu")
		(net "UPI_CPU1_CPU0_P1P1_DP<7>")
	)
	(segment
		(start 190.778638 -42.290746)
		(end 187.879736 -41.172384)
		(width 0.1143)
		(layer "In9.Cu")
		(net "UPI_CPU1_CPU0_P1P1_DP<7>")
	)
	(segment
		(start 136.611868 -50.969164)
		(end 136.479026 -51.01463)
		(width 0.0889)
		(layer "In9.Cu")
		(net "UPI_CPU1_CPU0_P1P1_DP<7>")
	)
	(segment
		(start 292.47465 -52.95011)
		(end 292.47465 -52.48783)
		(width 0.1143)
		(layer "In9.Cu")
		(net "UPI_CPU1_CPU0_P1P1_DP<7>")
	)
	(segment
		(start 136.967214 -50.243486)
		(end 136.877806 -50.426112)
		(width 0.0889)
		(layer "In9.Cu")
		(net "UPI_CPU1_CPU0_P1P1_DP<7>")
	)
	(segment
		(start 140.164058 -48.559974)
		(end 139.948412 -48.437546)
		(width 0.1143)
		(layer "In9.Cu")
		(net "UPI_CPU1_CPU0_P1P1_DP<7>")
	)
	(segment
		(start 136.412732 -51.54676)
		(end 136.464548 -51.632612)
		(width 0.0889)
		(layer "In9.Cu")
		(net "UPI_CPU1_CPU0_P1P1_DP<7>")
	)
	(segment
		(start 294.9448 -60.362338)
		(end 294.705024 -59.911742)
		(width 0.0889)
		(layer "In9.Cu")
		(net "UPI_CPU1_CPU0_P1P1_DP<7>")
	)
	(segment
		(start 292.720776 -54.722522)
		(end 292.71595 -54.713886)
		(width 0.0889)
		(layer "In9.Cu")
		(net "UPI_CPU1_CPU0_P1P1_DP<7>")
	)
	(segment
		(start 212.30463 -42.39768)
		(end 199.223376 -39.151052)
		(width 0.1143)
		(layer "In9.Cu")
		(net "UPI_CPU1_CPU0_P1P1_DP<7>")
	)
	(segment
		(start 293.57447 -57.590436)
		(end 293.579296 -57.5818)
		(width 0.0889)
		(layer "In9.Cu")
		(net "UPI_CPU1_CPU0_P1P1_DP<7>")
	)
	(segment
		(start 136.509506 -52.161948)
		(end 136.465564 -52.237386)
		(width 0.0889)
		(layer "In9.Cu")
		(net "UPI_CPU1_CPU0_P1P1_DP<7>")
	)
	(segment
		(start 292.779958 -53.723032)
		(end 292.52545 -53.468524)
		(width 0.0889)
		(layer "In9.Cu")
		(net "UPI_CPU1_CPU0_P1P1_DP<7>")
	)
	(segment
		(start 294.097456 -58.476388)
		(end 294.073326 -58.476388)
		(width 0.0889)
		(layer "In9.Cu")
		(net "UPI_CPU1_CPU0_P1P1_DP<7>")
	)
	(segment
		(start 293.56812 -56.610504)
		(end 293.57447 -56.599836)
		(width 0.0889)
		(layer "In9.Cu")
		(net "UPI_CPU1_CPU0_P1P1_DP<7>")
	)
	(segment
		(start 293.242746 -55.999888)
		(end 293.20998 -55.999888)
		(width 0.0889)
		(layer "In9.Cu")
		(net "UPI_CPU1_CPU0_P1P1_DP<7>")
	)
	(segment
		(start 140.38453 -48.499268)
		(end 140.164058 -48.559974)
		(width 0.1143)
		(layer "In9.Cu")
		(net "UPI_CPU1_CPU0_P1P1_DP<7>")
	)
	(segment
		(start 236.876844 -40.284654)
		(end 222.396812 -41.529762)
		(width 0.1143)
		(layer "In9.Cu")
		(net "UPI_CPU1_CPU0_P1P1_DP<7>")
	)
	(segment
		(start 137.233152 -49.700434)
		(end 137.143744 -49.88306)
		(width 0.0889)
		(layer "In9.Cu")
		(net "UPI_CPU1_CPU0_P1P1_DP<7>")
	)
	(segment
		(start 159.762698 -46.067218)
		(end 156.051758 -44.530772)
		(width 0.1143)
		(layer "In9.Cu")
		(net "UPI_CPU1_CPU0_P1P1_DP<7>")
	)
	(segment
		(start 137.285222 -49.36871)
		(end 137.187686 -49.567846)
		(width 0.0889)
		(layer "In9.Cu")
		(net "UPI_CPU1_CPU0_P1P1_DP<7>")
	)
	(segment
		(start 292.52545 -53.023008)
		(end 292.47465 -52.95011)
		(width 0.0889)
		(layer "In9.Cu")
		(net "UPI_CPU1_CPU0_P1P1_DP<7>")
	)
	(segment
		(start 291.615876 -50.127916)
		(end 291.61359 -50.121058)
		(width 0.1143)
		(layer "In9.Cu")
		(net "UPI_CPU1_CPU0_P1P1_DP<7>")
	)
	(segment
		(start 291.796724 -50.625248)
		(end 291.615876 -50.127916)
		(width 0.1143)
		(layer "In9.Cu")
		(net "UPI_CPU1_CPU0_P1P1_DP<7>")
	)
	(segment
		(start 291.705792 -50.821336)
		(end 291.796978 -50.62601)
		(width 0.1143)
		(layer "In9.Cu")
		(net "UPI_CPU1_CPU0_P1P1_DP<7>")
	)
	(segment
		(start 136.921748 -50.110898)
		(end 136.967214 -50.243486)
		(width 0.0889)
		(layer "In9.Cu")
		(net "UPI_CPU1_CPU0_P1P1_DP<7>")
	)
	(segment
		(start 136.877806 -50.426112)
		(end 136.744964 -50.471578)
		(width 0.0889)
		(layer "In9.Cu")
		(net "UPI_CPU1_CPU0_P1P1_DP<7>")
	)
	(segment
		(start 292.47465 -52.48783)
		(end 292.357556 -52.165758)
		(width 0.1143)
		(layer "In9.Cu")
		(net "UPI_CPU1_CPU0_P1P1_DP<7>")
	)
	(segment
		(start 136.65581 -50.65395)
		(end 136.701276 -50.786538)
		(width 0.0889)
		(layer "In9.Cu")
		(net "UPI_CPU1_CPU0_P1P1_DP<7>")
	)
	(segment
		(start 168.294558 -46.556168)
		(end 164.850826 -47.214536)
		(width 0.1143)
		(layer "In9.Cu")
		(net "UPI_CPU1_CPU0_P1P1_DP<7>")
	)
	(segment
		(start 248.812304 -38.895782)
		(end 247.1928 -38.895782)
		(width 0.1143)
		(layer "In9.Cu")
		(net "UPI_CPU1_CPU0_P1P1_DP<7>")
	)
	(segment
		(start 136.479026 -51.01463)
		(end 136.371584 -51.23434)
		(width 0.0889)
		(layer "In9.Cu")
		(net "UPI_CPU1_CPU0_P1P1_DP<7>")
	)
	(segment
		(start 292.161976 -52.074572)
		(end 292.044628 -51.752246)
		(width 0.1143)
		(layer "In9.Cu")
		(net "UPI_CPU1_CPU0_P1P1_DP<7>")
	)
	(segment
		(start 137.996422 -49.064672)
		(end 137.57148 -49.280826)
		(width 0.1143)
		(layer "In9.Cu")
		(net "UPI_CPU1_CPU0_P1P1_DP<7>")
	)
	(segment
		(start 292.52545 -53.468524)
		(end 292.52545 -53.023008)
		(width 0.0889)
		(layer "In9.Cu")
		(net "UPI_CPU1_CPU0_P1P1_DP<7>")
	)
	(segment
		(start 291.61359 -50.121058)
		(end 291.613336 -50.120804)
		(width 0.1143)
		(layer "In9.Cu")
		(net "UPI_CPU1_CPU0_P1P1_DP<7>")
	)
	(segment
		(start 137.187686 -49.567846)
		(end 137.233152 -49.700434)
		(width 0.0889)
		(layer "In9.Cu")
		(net "UPI_CPU1_CPU0_P1P1_DP<7>")
	)
	(segment
		(start 292.135814 -51.55692)
		(end 292.01872 -51.234848)
		(width 0.1143)
		(layer "In9.Cu")
		(net "UPI_CPU1_CPU0_P1P1_DP<7>")
	)
	(segment
		(start 261.741158 -42.982896)
		(end 257.20421 -42.371518)
		(width 0.1143)
		(layer "In9.Cu")
		(net "UPI_CPU1_CPU0_P1P1_DP<7>")
	)
	(segment
		(start 136.701276 -50.786538)
		(end 136.611868 -50.969164)
		(width 0.0889)
		(layer "In9.Cu")
		(net "UPI_CPU1_CPU0_P1P1_DP<7>")
	)
	(segment
		(start 140.727176 -48.222916)
		(end 140.506958 -48.283622)
		(width 0.1143)
		(layer "In9.Cu")
		(net "UPI_CPU1_CPU0_P1P1_DP<7>")
	)
	(segment
		(start 292.357556 -52.165758)
		(end 292.161976 -52.074572)
		(width 0.1143)
		(layer "In9.Cu")
		(net "UPI_CPU1_CPU0_P1P1_DP<7>")
	)
	(segment
		(start 139.948412 -48.437546)
		(end 139.728194 -48.498252)
		(width 0.1143)
		(layer "In9.Cu")
		(net "UPI_CPU1_CPU0_P1P1_DP<7>")
	)
	(segment
		(start 135.895842 -53.328824)
		(end 136.017 -53.2892)
		(width 0.0889)
		(layer "In9.Cu")
		(net "UPI_CPU1_CPU0_P1P1_DP<7>")
	)
	(segment
		(start 292.71595 -54.123336)
		(end 292.779958 -54.012338)
		(width 0.0889)
		(layer "In9.Cu")
		(net "UPI_CPU1_CPU0_P1P1_DP<7>")
	)
	(segment
		(start 140.506958 -48.283622)
		(end 140.38453 -48.499268)
		(width 0.1143)
		(layer "In9.Cu")
		(net "UPI_CPU1_CPU0_P1P1_DP<7>")
	)
	(segment
		(start 140.942822 -48.345344)
		(end 140.727176 -48.222916)
		(width 0.1143)
		(layer "In9.Cu")
		(net "UPI_CPU1_CPU0_P1P1_DP<7>")
	)
	(segment
		(start 292.044628 -51.752246)
		(end 292.135814 -51.55692)
		(width 0.1143)
		(layer "In9.Cu")
		(net "UPI_CPU1_CPU0_P1P1_DP<7>")
	)
	(segment
		(start 139.169648 -48.652176)
		(end 138.8872 -48.7299)
		(width 0.1143)
		(layer "In9.Cu")
		(net "UPI_CPU1_CPU0_P1P1_DP<7>")
	)
	(segment
		(start 144.415256 -47.206916)
		(end 141.285722 -48.068992)
		(width 0.1143)
		(layer "In9.Cu")
		(net "UPI_CPU1_CPU0_P1P1_DP<7>")
	)
	(segment
		(start 138.093704 -48.948594)
		(end 137.996676 -49.062894)
		(width 0.1143)
		(layer "In9.Cu")
		(net "UPI_CPU1_CPU0_P1P1_DP<7>")
	)
	(segment
		(start 138.8872 -48.7299)
		(end 138.093704 -48.948594)
		(width 0.1143)
		(layer "In9.Cu")
		(net "UPI_CPU1_CPU0_P1P1_DP<7>")
	)
	(segment
		(start 291.796978 -50.62601)
		(end 291.796724 -50.625248)
		(width 0.1143)
		(layer "In9.Cu")
		(net "UPI_CPU1_CPU0_P1P1_DP<7>")
	)
	(segment
		(start 187.879736 -41.172384)
		(end 181.21249 -41.844468)
		(width 0.1143)
		(layer "In9.Cu")
		(net "UPI_CPU1_CPU0_P1P1_DP<7>")
	)
	(segment
		(start 141.163294 -48.284638)
		(end 140.942822 -48.345344)
		(width 0.1143)
		(layer "In9.Cu")
		(net "UPI_CPU1_CPU0_P1P1_DP<7>")
	)
	(segment
		(start 264.6426 -42.211752)
		(end 261.741158 -42.982896)
		(width 0.1143)
		(layer "In9.Cu")
		(net "UPI_CPU1_CPU0_P1P1_DP<7>")
	)
	(segment
		(start 141.285722 -48.068992)
		(end 141.163294 -48.284638)
		(width 0.1143)
		(layer "In9.Cu")
		(net "UPI_CPU1_CPU0_P1P1_DP<7>")
	)
	(segment
		(start 292.779958 -54.012338)
		(end 292.779958 -53.723032)
		(width 0.0889)
		(layer "In9.Cu")
		(net "UPI_CPU1_CPU0_P1P1_DP<7>")
	)
	(segment
		(start 292.01872 -51.234848)
		(end 291.82314 -51.143662)
		(width 0.1143)
		(layer "In9.Cu")
		(net "UPI_CPU1_CPU0_P1P1_DP<7>")
	)
	(segment
		(start 136.371584 -51.23434)
		(end 136.412732 -51.54676)
		(width 0.0889)
		(layer "In9.Cu")
		(net "UPI_CPU1_CPU0_P1P1_DP<7>")
	)
	(segment
		(start 294.42664 -59.087004)
		(end 294.43299 -59.076336)
		(width 0.0889)
		(layer "In9.Cu")
		(net "UPI_CPU1_CPU0_P1P1_DP<7>")
	)
	(segment
		(start 137.143744 -49.88306)
		(end 137.010902 -49.928526)
		(width 0.0889)
		(layer "In9.Cu")
		(net "UPI_CPU1_CPU0_P1P1_DP<7>")
	)
	(segment
		(start 136.017 -52.996084)
		(end 135.953754 -52.932838)
		(width 0.0889)
		(layer "In9.Cu")
		(net "UPI_CPU1_CPU0_P1P1_DP<7>")
	)
	(segment
		(start 247.1928 -38.895782)
		(end 243.310664 -41.265094)
		(width 0.1143)
		(layer "In9.Cu")
		(net "UPI_CPU1_CPU0_P1P1_DP<7>")
	)
	(segment
		(start 137.010902 -49.928526)
		(end 136.921748 -50.110898)
		(width 0.0889)
		(layer "In9.Cu")
		(net "UPI_CPU1_CPU0_P1P1_DP<7>")
	)
	(segment
		(start 181.21249 -41.844468)
		(end 168.294558 -46.556168)
		(width 0.1143)
		(layer "In9.Cu")
		(net "UPI_CPU1_CPU0_P1P1_DP<7>")
	)
	(segment
		(start 293.56812 -57.601104)
		(end 293.57447 -57.590436)
		(width 0.0889)
		(layer "In9.Cu")
		(net "UPI_CPU1_CPU0_P1P1_DP<7>")
	)
	(segment
		(start 291.82314 -51.143662)
		(end 291.705792 -50.821336)
		(width 0.1143)
		(layer "In9.Cu")
		(net "UPI_CPU1_CPU0_P1P1_DP<7>")
	)
	(segment
		(start 137.57148 -49.280826)
		(end 137.483342 -49.26838)
		(width 0.0889)
		(layer "In9.Cu")
		(net "UPI_CPU1_CPU0_P1P1_DP<7>")
	)
	(segment
		(start 139.38504 -48.774604)
		(end 139.169648 -48.652176)
		(width 0.1143)
		(layer "In9.Cu")
		(net "UPI_CPU1_CPU0_P1P1_DP<7>")
	)
	(segment
		(start 136.744964 -50.471578)
		(end 136.65581 -50.65395)
		(width 0.0889)
		(layer "In9.Cu")
		(net "UPI_CPU1_CPU0_P1P1_DP<7>")
	)
	(segment
		(start 289.468814 -48.526954)
		(end 286.231838 -47.363634)
		(width 0.1143)
		(layer "In9.Cu")
		(net "UPI_CPU1_CPU0_P1P1_DP<7>")
	)
	(segment
		(start 137.483342 -49.26838)
		(end 137.285222 -49.36871)
		(width 0.0889)
		(layer "In9.Cu")
		(net "UPI_CPU1_CPU0_P1P1_DP<7>")
	)
	(segment
		(start 286.231838 -47.363634)
		(end 264.6426 -42.211752)
		(width 0.1143)
		(layer "In9.Cu")
		(net "UPI_CPU1_CPU0_P1P1_DP<7>")
	)
	(segment
		(start 137.996676 -49.062894)
		(end 137.996422 -49.064672)
		(width 0.1143)
		(layer "In9.Cu")
		(net "UPI_CPU1_CPU0_P1P1_DP<7>")
	)
	(arc
		(start 136.464548 -51.632612)
		(mid 136.549058 -51.892003)
		(end 136.509506 -52.161948)
		(width 0.0889)
		(layer "In9.Cu")
		(net "UPI_CPU1_CPU0_P1P1_DP<7>")
	)
	(arc
		(start 136.465564 -52.237386)
		(mid 136.254851 -52.450465)
		(end 135.966708 -52.532788)
		(width 0.0889)
		(layer "In9.Cu")
		(net "UPI_CPU1_CPU0_P1P1_DP<7>")
	)
	(arc
		(start 293.57447 -57.190386)
		(mid 293.495248 -56.901268)
		(end 293.56812 -56.610504)
		(width 0.0889)
		(layer "In9.Cu")
		(net "UPI_CPU1_CPU0_P1P1_DP<7>")
	)
	(arc
		(start 294.43299 -59.076336)
		(mid 294.435573 -58.681089)
		(end 294.097456 -58.476388)
		(width 0.0889)
		(layer "In9.Cu")
		(net "UPI_CPU1_CPU0_P1P1_DP<7>")
	)
	(arc
		(start 293.20998 -55.999888)
		(mid 292.711729 -55.697048)
		(end 292.71595 -55.113936)
		(width 0.0889)
		(layer "In9.Cu")
		(net "UPI_CPU1_CPU0_P1P1_DP<7>")
	)
	(arc
		(start 294.073326 -58.476388)
		(mid 293.574445 -58.180951)
		(end 293.56812 -57.601104)
		(width 0.0889)
		(layer "In9.Cu")
		(net "UPI_CPU1_CPU0_P1P1_DP<7>")
	)
	(arc
		(start 292.7096 -54.703218)
		(mid 292.636802 -54.412455)
		(end 292.71595 -54.123336)
		(width 0.0889)
		(layer "In9.Cu")
		(net "UPI_CPU1_CPU0_P1P1_DP<7>")
	)
	(arc
		(start 292.71595 -55.113936)
		(mid 292.76942 -54.918873)
		(end 292.720776 -54.722522)
		(width 0.0889)
		(layer "In9.Cu")
		(net "UPI_CPU1_CPU0_P1P1_DP<7>")
	)
	(arc
		(start 294.43299 -59.666886)
		(mid 294.353768 -59.377768)
		(end 294.42664 -59.087004)
		(width 0.0889)
		(layer "In9.Cu")
		(net "UPI_CPU1_CPU0_P1P1_DP<7>")
	)
	(arc
		(start 293.579296 -57.5818)
		(mid 293.628051 -57.385448)
		(end 293.57447 -57.190386)
		(width 0.0889)
		(layer "In9.Cu")
		(net "UPI_CPU1_CPU0_P1P1_DP<7>")
	)
	(arc
		(start 135.711184 -53.2511)
		(mid 135.798575 -53.301688)
		(end 135.895842 -53.328824)
		(width 0.0889)
		(layer "In9.Cu")
		(net "UPI_CPU1_CPU0_P1P1_DP<7>")
	)
	(arc
		(start 135.942578 -52.532788)
		(mid 135.572827 -52.81012)
		(end 135.711184 -53.2511)
		(width 0.0889)
		(layer "In9.Cu")
		(net "UPI_CPU1_CPU0_P1P1_DP<7>")
	)
	(arc
		(start 293.579296 -56.5912)
		(mid 293.575549 -56.201944)
		(end 293.242746 -55.999888)
		(width 0.0889)
		(layer "In9.Cu")
		(net "UPI_CPU1_CPU0_P1P1_DP<7>")
	)
	(arc
		(start 294.705024 -59.911742)
		(mid 294.549557 -59.810919)
		(end 294.43299 -59.666886)
		(width 0.0889)
		(layer "In9.Cu")
		(net "UPI_CPU1_CPU0_P1P1_DP<7>")
	)
	(segment
		(start 135.382254 -55.904384)
		(end 135.953754 -55.904384)
		(width 0.1143)
		(layer "F.Cu")
		(net "UPI_CPU1_CPU0_P1P1_DP<6>")
	)
	(segment
		(start 293.51478 -59.866784)
		(end 294.08628 -59.866784)
		(width 0.1143)
		(layer "F.Cu")
		(net "UPI_CPU1_CPU0_P1P1_DP<6>")
	)
	(via
		(at 135.953754 -55.904384)
		(size 0.508)
		(drill 0.254)
		(layers "F.Cu" "B.Cu")
		(net "UPI_CPU1_CPU0_P1P1_DP<6>")
	)
	(via
		(at 294.08628 -59.866784)
		(size 0.508)
		(drill 0.254)
		(layers "F.Cu" "B.Cu")
		(net "UPI_CPU1_CPU0_P1P1_DP<6>")
	)
	(segment
		(start 181.734968 -42.176446)
		(end 181.727348 -42.17543)
		(width 0.1143)
		(layer "In9.Cu")
		(net "UPI_CPU1_CPU0_P1P1_DP<6>")
	)
	(segment
		(start 199.250554 -39.586408)
		(end 190.566294 -42.815256)
		(width 0.1143)
		(layer "In9.Cu")
		(net "UPI_CPU1_CPU0_P1P1_DP<6>")
	)
	(segment
		(start 156.133546 -44.946062)
		(end 144.084548 -47.67326)
		(width 0.1143)
		(layer "In9.Cu")
		(net "UPI_CPU1_CPU0_P1P1_DP<6>")
	)
	(segment
		(start 294.08628 -59.866784)
		(end 293.793164 -60.035948)
		(width 0.0889)
		(layer "In9.Cu")
		(net "UPI_CPU1_CPU0_P1P1_DP<6>")
	)
	(segment
		(start 139.409678 -49.61001)
		(end 138.248644 -50.771044)
		(width 0.1143)
		(layer "In9.Cu")
		(net "UPI_CPU1_CPU0_P1P1_DP<6>")
	)
	(segment
		(start 137.385044 -51.706272)
		(end 137.385044 -52.246784)
		(width 0.0889)
		(layer "In9.Cu")
		(net "UPI_CPU1_CPU0_P1P1_DP<6>")
	)
	(segment
		(start 256.67843 -42.83329)
		(end 247.966484 -44.249086)
		(width 0.1143)
		(layer "In9.Cu")
		(net "UPI_CPU1_CPU0_P1P1_DP<6>")
	)
	(segment
		(start 264.536428 -42.60977)
		(end 261.889748 -43.35907)
		(width 0.1143)
		(layer "In9.Cu")
		(net "UPI_CPU1_CPU0_P1P1_DP<6>")
	)
	(segment
		(start 237.085632 -40.701214)
		(end 222.396812 -41.91762)
		(width 0.1143)
		(layer "In9.Cu")
		(net "UPI_CPU1_CPU0_P1P1_DP<6>")
	)
	(segment
		(start 138.248644 -50.842672)
		(end 137.385044 -51.706272)
		(width 0.0889)
		(layer "In9.Cu")
		(net "UPI_CPU1_CPU0_P1P1_DP<6>")
	)
	(segment
		(start 190.566294 -42.815256)
		(end 184.26811 -42.592244)
		(width 0.1143)
		(layer "In9.Cu")
		(net "UPI_CPU1_CPU0_P1P1_DP<6>")
	)
	(segment
		(start 184.26811 -42.592244)
		(end 181.734968 -42.176446)
		(width 0.1143)
		(layer "In9.Cu")
		(net "UPI_CPU1_CPU0_P1P1_DP<6>")
	)
	(segment
		(start 291.194236 -52.795424)
		(end 291.194236 -52.773326)
		(width 0.0889)
		(layer "In9.Cu")
		(net "UPI_CPU1_CPU0_P1P1_DP<6>")
	)
	(segment
		(start 291.495734 -55.009288)
		(end 291.5285 -55.009288)
		(width 0.0889)
		(layer "In9.Cu")
		(net "UPI_CPU1_CPU0_P1P1_DP<6>")
	)
	(segment
		(start 292.38702 -56.304434)
		(end 292.354254 -56.304434)
		(width 0.0889)
		(layer "In9.Cu")
		(net "UPI_CPU1_CPU0_P1P1_DP<6>")
	)
	(segment
		(start 292.8874 -57.601104)
		(end 292.88105 -57.590436)
		(width 0.0889)
		(layer "In9.Cu")
		(net "UPI_CPU1_CPU0_P1P1_DP<6>")
	)
	(segment
		(start 240.967514 -42.766996)
		(end 237.085632 -40.701214)
		(width 0.1143)
		(layer "In9.Cu")
		(net "UPI_CPU1_CPU0_P1P1_DP<6>")
	)
	(segment
		(start 292.88105 -57.590436)
		(end 292.876224 -57.5818)
		(width 0.0889)
		(layer "In9.Cu")
		(net "UPI_CPU1_CPU0_P1P1_DP<6>")
	)
	(segment
		(start 291.194236 -50.37201)
		(end 289.325304 -49.071784)
		(width 0.1143)
		(layer "In9.Cu")
		(net "UPI_CPU1_CPU0_P1P1_DP<6>")
	)
	(segment
		(start 291.143436 -52.846224)
		(end 291.194236 -52.795424)
		(width 0.0889)
		(layer "In9.Cu")
		(net "UPI_CPU1_CPU0_P1P1_DP<6>")
	)
	(segment
		(start 291.143436 -53.481224)
		(end 291.143436 -52.846224)
		(width 0.0889)
		(layer "In9.Cu")
		(net "UPI_CPU1_CPU0_P1P1_DP<6>")
	)
	(segment
		(start 144.084548 -47.67326)
		(end 139.409678 -49.61001)
		(width 0.1143)
		(layer "In9.Cu")
		(net "UPI_CPU1_CPU0_P1P1_DP<6>")
	)
	(segment
		(start 136.300464 -53.723286)
		(end 136.30529 -53.731922)
		(width 0.0889)
		(layer "In9.Cu")
		(net "UPI_CPU1_CPU0_P1P1_DP<6>")
	)
	(segment
		(start 293.793164 -60.035948)
		(end 293.714424 -60.014612)
		(width 0.0889)
		(layer "In9.Cu")
		(net "UPI_CPU1_CPU0_P1P1_DP<6>")
	)
	(segment
		(start 293.734744 -59.675522)
		(end 293.73957 -59.666886)
		(width 0.0889)
		(layer "In9.Cu")
		(net "UPI_CPU1_CPU0_P1P1_DP<6>")
	)
	(segment
		(start 291.53231 -55.809388)
		(end 291.499544 -55.809388)
		(width 0.0889)
		(layer "In9.Cu")
		(net "UPI_CPU1_CPU0_P1P1_DP<6>")
	)
	(segment
		(start 137.385044 -52.246784)
		(end 137.158984 -52.637436)
		(width 0.0889)
		(layer "In9.Cu")
		(net "UPI_CPU1_CPU0_P1P1_DP<6>")
	)
	(segment
		(start 181.727348 -42.17543)
		(end 181.642258 -42.161206)
		(width 0.1143)
		(layer "In9.Cu")
		(net "UPI_CPU1_CPU0_P1P1_DP<6>")
	)
	(segment
		(start 293.24554 -58.780934)
		(end 293.209726 -58.780934)
		(width 0.0889)
		(layer "In9.Cu")
		(net "UPI_CPU1_CPU0_P1P1_DP<6>")
	)
	(segment
		(start 261.889748 -43.35907)
		(end 256.910332 -42.848784)
		(width 0.1143)
		(layer "In9.Cu")
		(net "UPI_CPU1_CPU0_P1P1_DP<6>")
	)
	(segment
		(start 291.864288 -53.849016)
		(end 291.440362 -53.716428)
		(width 0.0889)
		(layer "In9.Cu")
		(net "UPI_CPU1_CPU0_P1P1_DP<6>")
	)
	(segment
		(start 212.208618 -42.761154)
		(end 199.250554 -39.586408)
		(width 0.1143)
		(layer "In9.Cu")
		(net "UPI_CPU1_CPU0_P1P1_DP<6>")
	)
	(segment
		(start 136.057894 -55.800498)
		(end 135.953754 -55.904384)
		(width 0.0889)
		(layer "In9.Cu")
		(net "UPI_CPU1_CPU0_P1P1_DP<6>")
	)
	(segment
		(start 138.248644 -50.771298)
		(end 138.248644 -50.842672)
		(width 0.0889)
		(layer "In9.Cu")
		(net "UPI_CPU1_CPU0_P1P1_DP<6>")
	)
	(segment
		(start 291.440362 -53.716428)
		(end 291.143436 -53.481224)
		(width 0.0889)
		(layer "In9.Cu")
		(net "UPI_CPU1_CPU0_P1P1_DP<6>")
	)
	(segment
		(start 181.642258 -42.161206)
		(end 168.588944 -46.848014)
		(width 0.1143)
		(layer "In9.Cu")
		(net "UPI_CPU1_CPU0_P1P1_DP<6>")
	)
	(segment
		(start 138.248644 -50.771044)
		(end 138.248644 -50.771298)
		(width 0.1143)
		(layer "In9.Cu")
		(net "UPI_CPU1_CPU0_P1P1_DP<6>")
	)
	(segment
		(start 222.396812 -41.91762)
		(end 212.208618 -42.761154)
		(width 0.1143)
		(layer "In9.Cu")
		(net "UPI_CPU1_CPU0_P1P1_DP<6>")
	)
	(segment
		(start 256.910332 -42.848784)
		(end 256.67843 -42.83329)
		(width 0.1143)
		(layer "In9.Cu")
		(net "UPI_CPU1_CPU0_P1P1_DP<6>")
	)
	(segment
		(start 159.715454 -46.429422)
		(end 156.133546 -44.946062)
		(width 0.1143)
		(layer "In9.Cu")
		(net "UPI_CPU1_CPU0_P1P1_DP<6>")
	)
	(segment
		(start 136.300464 -54.713886)
		(end 136.30529 -54.722522)
		(width 0.0889)
		(layer "In9.Cu")
		(net "UPI_CPU1_CPU0_P1P1_DP<6>")
	)
	(segment
		(start 168.588944 -46.848014)
		(end 164.724588 -47.574962)
		(width 0.1143)
		(layer "In9.Cu")
		(net "UPI_CPU1_CPU0_P1P1_DP<6>")
	)
	(segment
		(start 289.325304 -49.071784)
		(end 285.872936 -47.632112)
		(width 0.1143)
		(layer "In9.Cu")
		(net "UPI_CPU1_CPU0_P1P1_DP<6>")
	)
	(segment
		(start 285.872936 -47.632112)
		(end 264.536428 -42.60977)
		(width 0.1143)
		(layer "In9.Cu")
		(net "UPI_CPU1_CPU0_P1P1_DP<6>")
	)
	(segment
		(start 241.096292 -42.835576)
		(end 240.967514 -42.766996)
		(width 0.1143)
		(layer "In9.Cu")
		(net "UPI_CPU1_CPU0_P1P1_DP<6>")
	)
	(segment
		(start 247.966484 -44.249086)
		(end 241.096292 -42.835576)
		(width 0.1143)
		(layer "In9.Cu")
		(net "UPI_CPU1_CPU0_P1P1_DP<6>")
	)
	(segment
		(start 136.830308 -52.837334)
		(end 136.794494 -52.837334)
		(width 0.0889)
		(layer "In9.Cu")
		(net "UPI_CPU1_CPU0_P1P1_DP<6>")
	)
	(segment
		(start 291.194236 -52.773326)
		(end 291.194236 -50.37201)
		(width 0.1143)
		(layer "In9.Cu")
		(net "UPI_CPU1_CPU0_P1P1_DP<6>")
	)
	(segment
		(start 136.294114 -54.703218)
		(end 136.300464 -54.713886)
		(width 0.0889)
		(layer "In9.Cu")
		(net "UPI_CPU1_CPU0_P1P1_DP<6>")
	)
	(segment
		(start 292.02253 -54.123336)
		(end 291.864288 -53.849016)
		(width 0.0889)
		(layer "In9.Cu")
		(net "UPI_CPU1_CPU0_P1P1_DP<6>")
	)
	(segment
		(start 164.724588 -47.574962)
		(end 159.715454 -46.429422)
		(width 0.1143)
		(layer "In9.Cu")
		(net "UPI_CPU1_CPU0_P1P1_DP<6>")
	)
	(arc
		(start 292.354254 -56.304434)
		(mid 292.162612 -56.247268)
		(end 292.02253 -56.104536)
		(width 0.0889)
		(layer "In9.Cu")
		(net "UPI_CPU1_CPU0_P1P1_DP<6>")
	)
	(arc
		(start 136.300464 -55.113936)
		(mid 136.24186 -55.254705)
		(end 136.221216 -55.405782)
		(width 0.0889)
		(layer "In9.Cu")
		(net "UPI_CPU1_CPU0_P1P1_DP<6>")
	)
	(arc
		(start 136.300464 -54.123336)
		(mid 136.221242 -54.412454)
		(end 136.294114 -54.703218)
		(width 0.0889)
		(layer "In9.Cu")
		(net "UPI_CPU1_CPU0_P1P1_DP<6>")
	)
	(arc
		(start 292.876224 -57.5818)
		(mid 292.827469 -57.385448)
		(end 292.88105 -57.190386)
		(width 0.0889)
		(layer "In9.Cu")
		(net "UPI_CPU1_CPU0_P1P1_DP<6>")
	)
	(arc
		(start 292.88105 -58.180986)
		(mid 292.960272 -57.891868)
		(end 292.8874 -57.601104)
		(width 0.0889)
		(layer "In9.Cu")
		(net "UPI_CPU1_CPU0_P1P1_DP<6>")
	)
	(arc
		(start 136.794494 -52.837334)
		(mid 136.296243 -53.140174)
		(end 136.300464 -53.723286)
		(width 0.0889)
		(layer "In9.Cu")
		(net "UPI_CPU1_CPU0_P1P1_DP<6>")
	)
	(arc
		(start 293.70528 -59.744102)
		(mid 293.71842 -59.709128)
		(end 293.734744 -59.675522)
		(width 0.0889)
		(layer "In9.Cu")
		(net "UPI_CPU1_CPU0_P1P1_DP<6>")
	)
	(arc
		(start 292.02888 -54.703218)
		(mid 292.101678 -54.412455)
		(end 292.02253 -54.123336)
		(width 0.0889)
		(layer "In9.Cu")
		(net "UPI_CPU1_CPU0_P1P1_DP<6>")
	)
	(arc
		(start 137.158984 -52.637436)
		(mid 137.02024 -52.779469)
		(end 136.830308 -52.837334)
		(width 0.0889)
		(layer "In9.Cu")
		(net "UPI_CPU1_CPU0_P1P1_DP<6>")
	)
	(arc
		(start 291.5285 -55.009288)
		(mid 291.819321 -54.922701)
		(end 292.02888 -54.703218)
		(width 0.0889)
		(layer "In9.Cu")
		(net "UPI_CPU1_CPU0_P1P1_DP<6>")
	)
	(arc
		(start 293.209726 -58.780934)
		(mid 292.876757 -58.573386)
		(end 292.88105 -58.180986)
		(width 0.0889)
		(layer "In9.Cu")
		(net "UPI_CPU1_CPU0_P1P1_DP<6>")
	)
	(arc
		(start 293.73957 -59.666886)
		(mid 293.743899 -59.083714)
		(end 293.24554 -58.780934)
		(width 0.0889)
		(layer "In9.Cu")
		(net "UPI_CPU1_CPU0_P1P1_DP<6>")
	)
	(arc
		(start 136.30529 -54.722522)
		(mid 136.354045 -54.918874)
		(end 136.300464 -55.113936)
		(width 0.0889)
		(layer "In9.Cu")
		(net "UPI_CPU1_CPU0_P1P1_DP<6>")
	)
	(arc
		(start 292.88105 -57.190386)
		(mid 292.885379 -56.607214)
		(end 292.38702 -56.304434)
		(width 0.0889)
		(layer "In9.Cu")
		(net "UPI_CPU1_CPU0_P1P1_DP<6>")
	)
	(arc
		(start 292.02253 -56.104536)
		(mid 291.815526 -55.893672)
		(end 291.53231 -55.809388)
		(width 0.0889)
		(layer "In9.Cu")
		(net "UPI_CPU1_CPU0_P1P1_DP<6>")
	)
	(arc
		(start 136.221216 -55.405782)
		(mid 136.178821 -55.619388)
		(end 136.057894 -55.800498)
		(width 0.0889)
		(layer "In9.Cu")
		(net "UPI_CPU1_CPU0_P1P1_DP<6>")
	)
	(arc
		(start 291.499544 -55.809388)
		(mid 291.110271 -55.411242)
		(end 291.495734 -55.009288)
		(width 0.0889)
		(layer "In9.Cu")
		(net "UPI_CPU1_CPU0_P1P1_DP<6>")
	)
	(arc
		(start 293.714424 -60.014612)
		(mid 293.686273 -59.880148)
		(end 293.70528 -59.744102)
		(width 0.0889)
		(layer "In9.Cu")
		(net "UPI_CPU1_CPU0_P1P1_DP<6>")
	)
	(arc
		(start 136.30529 -53.731922)
		(mid 136.354045 -53.928274)
		(end 136.300464 -54.123336)
		(width 0.0889)
		(layer "In9.Cu")
		(net "UPI_CPU1_CPU0_P1P1_DP<6>")
	)
	(segment
		(start 291.79774 -57.885584)
		(end 292.36924 -57.885584)
		(width 0.1143)
		(layer "F.Cu")
		(net "UPI_CPU1_CPU0_P1P1_DP<5>")
	)
	(segment
		(start 137.099294 -55.904384)
		(end 137.670794 -55.904384)
		(width 0.1143)
		(layer "F.Cu")
		(net "UPI_CPU1_CPU0_P1P1_DP<5>")
	)
	(via
		(at 137.670794 -55.904384)
		(size 0.508)
		(drill 0.254)
		(layers "F.Cu" "B.Cu")
		(net "UPI_CPU1_CPU0_P1P1_DP<5>")
	)
	(via
		(at 292.36924 -57.885584)
		(size 0.508)
		(drill 0.254)
		(layers "F.Cu" "B.Cu")
		(net "UPI_CPU1_CPU0_P1P1_DP<5>")
	)
	(segment
		(start 290.665916 -56.304434)
		(end 290.461446 -56.304434)
		(width 0.0889)
		(layer "In9.Cu")
		(net "UPI_CPU1_CPU0_P1P1_DP<5>")
	)
	(segment
		(start 291.971222 -57.843166)
		(end 291.973254 -57.828434)
		(width 0.0889)
		(layer "In9.Cu")
		(net "UPI_CPU1_CPU0_P1P1_DP<5>")
	)
	(segment
		(start 156.088588 -45.65015)
		(end 145.75155 -47.971964)
		(width 0.1143)
		(layer "In9.Cu")
		(net "UPI_CPU1_CPU0_P1P1_DP<5>")
	)
	(segment
		(start 168.961054 -47.42053)
		(end 164.852604 -48.265588)
		(width 0.1143)
		(layer "In9.Cu")
		(net "UPI_CPU1_CPU0_P1P1_DP<5>")
	)
	(segment
		(start 290.271708 -52.63134)
		(end 290.271708 -50.720498)
		(width 0.1143)
		(layer "In9.Cu")
		(net "UPI_CPU1_CPU0_P1P1_DP<5>")
	)
	(segment
		(start 199.27697 -40.281352)
		(end 190.785242 -43.465242)
		(width 0.1143)
		(layer "In9.Cu")
		(net "UPI_CPU1_CPU0_P1P1_DP<5>")
	)
	(segment
		(start 290.220908 -56.063896)
		(end 290.220908 -52.704238)
		(width 0.0889)
		(layer "In9.Cu")
		(net "UPI_CPU1_CPU0_P1P1_DP<5>")
	)
	(segment
		(start 137.158984 -54.618636)
		(end 137.152634 -54.629304)
		(width 0.0889)
		(layer "In9.Cu")
		(net "UPI_CPU1_CPU0_P1P1_DP<5>")
	)
	(segment
		(start 181.642766 -42.8879)
		(end 168.961054 -47.42053)
		(width 0.1143)
		(layer "In9.Cu")
		(net "UPI_CPU1_CPU0_P1P1_DP<5>")
	)
	(segment
		(start 222.396812 -42.57548)
		(end 211.98205 -43.429174)
		(width 0.1143)
		(layer "In9.Cu")
		(net "UPI_CPU1_CPU0_P1P1_DP<5>")
	)
	(segment
		(start 145.75155 -47.971964)
		(end 140.904722 -49.979072)
		(width 0.1143)
		(layer "In9.Cu")
		(net "UPI_CPU1_CPU0_P1P1_DP<5>")
	)
	(segment
		(start 236.984286 -41.379902)
		(end 222.396812 -42.57548)
		(width 0.1143)
		(layer "In9.Cu")
		(net "UPI_CPU1_CPU0_P1P1_DP<5>")
	)
	(segment
		(start 292.017704 -57.694322)
		(end 292.02253 -57.685686)
		(width 0.0889)
		(layer "In9.Cu")
		(net "UPI_CPU1_CPU0_P1P1_DP<5>")
	)
	(segment
		(start 285.50743 -48.247808)
		(end 264.660888 -43.29684)
		(width 0.1143)
		(layer "In9.Cu")
		(net "UPI_CPU1_CPU0_P1P1_DP<5>")
	)
	(segment
		(start 137.16381 -54.61)
		(end 137.158984 -54.618636)
		(width 0.0889)
		(layer "In9.Cu")
		(net "UPI_CPU1_CPU0_P1P1_DP<5>")
	)
	(segment
		(start 291.53231 -56.799988)
		(end 291.499544 -56.799988)
		(width 0.0889)
		(layer "In9.Cu")
		(net "UPI_CPU1_CPU0_P1P1_DP<5>")
	)
	(segment
		(start 140.0048 -50.950622)
		(end 138.281664 -52.673758)
		(width 0.0889)
		(layer "In9.Cu")
		(net "UPI_CPU1_CPU0_P1P1_DP<5>")
	)
	(segment
		(start 290.220908 -52.704238)
		(end 290.271708 -52.63134)
		(width 0.0889)
		(layer "In9.Cu")
		(net "UPI_CPU1_CPU0_P1P1_DP<5>")
	)
	(segment
		(start 140.0048 -50.878994)
		(end 140.0048 -50.950622)
		(width 0.0889)
		(layer "In9.Cu")
		(net "UPI_CPU1_CPU0_P1P1_DP<5>")
	)
	(segment
		(start 256.581148 -43.519852)
		(end 247.95099 -44.895262)
		(width 0.1143)
		(layer "In9.Cu")
		(net "UPI_CPU1_CPU0_P1P1_DP<5>")
	)
	(segment
		(start 138.281664 -52.673758)
		(end 138.017504 -53.132736)
		(width 0.0889)
		(layer "In9.Cu")
		(net "UPI_CPU1_CPU0_P1P1_DP<5>")
	)
	(segment
		(start 137.688828 -53.332634)
		(end 137.649204 -53.332634)
		(width 0.0889)
		(layer "In9.Cu")
		(net "UPI_CPU1_CPU0_P1P1_DP<5>")
	)
	(segment
		(start 211.98205 -43.429174)
		(end 199.27697 -40.281352)
		(width 0.1143)
		(layer "In9.Cu")
		(net "UPI_CPU1_CPU0_P1P1_DP<5>")
	)
	(segment
		(start 164.852604 -48.265588)
		(end 159.709612 -47.144686)
		(width 0.1143)
		(layer "In9.Cu")
		(net "UPI_CPU1_CPU0_P1P1_DP<5>")
	)
	(segment
		(start 290.461446 -56.304434)
		(end 290.220908 -56.063896)
		(width 0.0889)
		(layer "In9.Cu")
		(net "UPI_CPU1_CPU0_P1P1_DP<5>")
	)
	(segment
		(start 288.895282 -49.648364)
		(end 285.50743 -48.247808)
		(width 0.1143)
		(layer "In9.Cu")
		(net "UPI_CPU1_CPU0_P1P1_DP<5>")
	)
	(segment
		(start 159.709612 -47.144686)
		(end 156.088588 -45.65015)
		(width 0.1143)
		(layer "In9.Cu")
		(net "UPI_CPU1_CPU0_P1P1_DP<5>")
	)
	(segment
		(start 292.36924 -57.885584)
		(end 292.264846 -57.989978)
		(width 0.0889)
		(layer "In9.Cu")
		(net "UPI_CPU1_CPU0_P1P1_DP<5>")
	)
	(segment
		(start 184.389776 -43.320716)
		(end 181.68747 -42.895012)
		(width 0.1143)
		(layer "In9.Cu")
		(net "UPI_CPU1_CPU0_P1P1_DP<5>")
	)
	(segment
		(start 264.660888 -43.29684)
		(end 261.971536 -44.03217)
		(width 0.1143)
		(layer "In9.Cu")
		(net "UPI_CPU1_CPU0_P1P1_DP<5>")
	)
	(segment
		(start 292.02253 -57.685686)
		(end 292.02888 -57.675018)
		(width 0.0889)
		(layer "In9.Cu")
		(net "UPI_CPU1_CPU0_P1P1_DP<5>")
	)
	(segment
		(start 140.904722 -49.979072)
		(end 140.0048 -50.878994)
		(width 0.1143)
		(layer "In9.Cu")
		(net "UPI_CPU1_CPU0_P1P1_DP<5>")
	)
	(segment
		(start 181.68747 -42.895012)
		(end 181.642766 -42.8879)
		(width 0.1143)
		(layer "In9.Cu")
		(net "UPI_CPU1_CPU0_P1P1_DP<5>")
	)
	(segment
		(start 137.158984 -55.209186)
		(end 137.225278 -55.32374)
		(width 0.0889)
		(layer "In9.Cu")
		(net "UPI_CPU1_CPU0_P1P1_DP<5>")
	)
	(segment
		(start 247.95099 -44.895262)
		(end 240.915444 -43.471846)
		(width 0.1143)
		(layer "In9.Cu")
		(net "UPI_CPU1_CPU0_P1P1_DP<5>")
	)
	(segment
		(start 290.271708 -50.720498)
		(end 288.895282 -49.648364)
		(width 0.1143)
		(layer "In9.Cu")
		(net "UPI_CPU1_CPU0_P1P1_DP<5>")
	)
	(segment
		(start 190.785242 -43.465242)
		(end 184.389776 -43.320716)
		(width 0.1143)
		(layer "In9.Cu")
		(net "UPI_CPU1_CPU0_P1P1_DP<5>")
	)
	(segment
		(start 261.971536 -44.03217)
		(end 256.581148 -43.519852)
		(width 0.1143)
		(layer "In9.Cu")
		(net "UPI_CPU1_CPU0_P1P1_DP<5>")
	)
	(segment
		(start 240.915444 -43.471846)
		(end 236.984286 -41.379902)
		(width 0.1143)
		(layer "In9.Cu")
		(net "UPI_CPU1_CPU0_P1P1_DP<5>")
	)
	(arc
		(start 292.02888 -57.675018)
		(mid 292.024849 -57.098836)
		(end 291.53231 -56.799988)
		(width 0.0889)
		(layer "In9.Cu")
		(net "UPI_CPU1_CPU0_P1P1_DP<5>")
	)
	(arc
		(start 137.158984 -54.218586)
		(mid 137.212454 -54.413649)
		(end 137.16381 -54.61)
		(width 0.0889)
		(layer "In9.Cu")
		(net "UPI_CPU1_CPU0_P1P1_DP<5>")
	)
	(arc
		(start 137.225278 -55.32374)
		(mid 137.429025 -55.628649)
		(end 137.670794 -55.904384)
		(width 0.0889)
		(layer "In9.Cu")
		(net "UPI_CPU1_CPU0_P1P1_DP<5>")
	)
	(arc
		(start 291.16401 -56.599836)
		(mid 290.953657 -56.386864)
		(end 290.665916 -56.304434)
		(width 0.0889)
		(layer "In9.Cu")
		(net "UPI_CPU1_CPU0_P1P1_DP<5>")
	)
	(arc
		(start 137.649204 -53.332634)
		(mid 137.153727 -53.637077)
		(end 137.158984 -54.218586)
		(width 0.0889)
		(layer "In9.Cu")
		(net "UPI_CPU1_CPU0_P1P1_DP<5>")
	)
	(arc
		(start 137.152634 -54.629304)
		(mid 137.079836 -54.920067)
		(end 137.158984 -55.209186)
		(width 0.0889)
		(layer "In9.Cu")
		(net "UPI_CPU1_CPU0_P1P1_DP<5>")
	)
	(arc
		(start 291.499544 -56.799988)
		(mid 291.305694 -56.743638)
		(end 291.16401 -56.599836)
		(width 0.0889)
		(layer "In9.Cu")
		(net "UPI_CPU1_CPU0_P1P1_DP<5>")
	)
	(arc
		(start 138.017504 -53.132736)
		(mid 137.87876 -53.274769)
		(end 137.688828 -53.332634)
		(width 0.0889)
		(layer "In9.Cu")
		(net "UPI_CPU1_CPU0_P1P1_DP<5>")
	)
	(arc
		(start 292.264846 -57.989978)
		(mid 292.065068 -58.022504)
		(end 291.971222 -57.843166)
		(width 0.0889)
		(layer "In9.Cu")
		(net "UPI_CPU1_CPU0_P1P1_DP<5>")
	)
	(arc
		(start 291.973254 -57.828434)
		(mid 291.989514 -57.759401)
		(end 292.017704 -57.694322)
		(width 0.0889)
		(layer "In9.Cu")
		(net "UPI_CPU1_CPU0_P1P1_DP<5>")
	)
	(segment
		(start 291.79774 -58.876438)
		(end 292.36924 -58.876438)
		(width 0.1143)
		(layer "F.Cu")
		(net "UPI_CPU1_CPU0_P1P1_DP<4>")
	)
	(segment
		(start 137.099294 -53.923184)
		(end 137.670794 -53.923184)
		(width 0.1143)
		(layer "F.Cu")
		(net "UPI_CPU1_CPU0_P1P1_DP<4>")
	)
	(via
		(at 137.670794 -53.923184)
		(size 0.508)
		(drill 0.254)
		(layers "F.Cu" "B.Cu")
		(net "UPI_CPU1_CPU0_P1P1_DP<4>")
	)
	(via
		(at 292.36924 -58.876438)
		(size 0.508)
		(drill 0.254)
		(layers "F.Cu" "B.Cu")
		(net "UPI_CPU1_CPU0_P1P1_DP<4>")
	)
	(segment
		(start 181.808374 -43.600624)
		(end 168.768776 -48.18126)
		(width 0.1143)
		(layer "In9.Cu")
		(net "UPI_CPU1_CPU0_P1P1_DP<4>")
	)
	(segment
		(start 290.106608 -57.069228)
		(end 290.106608 -56.940196)
		(width 0.0889)
		(layer "In9.Cu")
		(net "UPI_CPU1_CPU0_P1P1_DP<4>")
	)
	(segment
		(start 264.708894 -43.969686)
		(end 261.986776 -44.71416)
		(width 0.1143)
		(layer "In9.Cu")
		(net "UPI_CPU1_CPU0_P1P1_DP<4>")
	)
	(segment
		(start 138.053318 -54.068218)
		(end 137.9728 -54.068218)
		(width 0.0889)
		(layer "In9.Cu")
		(net "UPI_CPU1_CPU0_P1P1_DP<4>")
	)
	(segment
		(start 141.700758 -51.0159)
		(end 141.195806 -51.0159)
		(width 0.0889)
		(layer "In9.Cu")
		(net "UPI_CPU1_CPU0_P1P1_DP<4>")
	)
	(segment
		(start 191.038226 -44.138342)
		(end 184.291986 -44.015406)
		(width 0.1143)
		(layer "In9.Cu")
		(net "UPI_CPU1_CPU0_P1P1_DP<4>")
	)
	(segment
		(start 168.768776 -48.18126)
		(end 165.015672 -48.98263)
		(width 0.1143)
		(layer "In9.Cu")
		(net "UPI_CPU1_CPU0_P1P1_DP<4>")
	)
	(segment
		(start 292.581584 -59.276234)
		(end 292.351206 -59.276234)
		(width 0.0889)
		(layer "In9.Cu")
		(net "UPI_CPU1_CPU0_P1P1_DP<4>")
	)
	(segment
		(start 146.14525 -49.1871)
		(end 145.62328 -49.1871)
		(width 0.1143)
		(layer "In9.Cu")
		(net "UPI_CPU1_CPU0_P1P1_DP<4>")
	)
	(segment
		(start 145.62328 -49.1871)
		(end 141.97584 -50.697384)
		(width 0.1143)
		(layer "In9.Cu")
		(net "UPI_CPU1_CPU0_P1P1_DP<4>")
	)
	(segment
		(start 247.938798 -45.541438)
		(end 240.648998 -44.066206)
		(width 0.1143)
		(layer "In9.Cu")
		(net "UPI_CPU1_CPU0_P1P1_DP<4>")
	)
	(segment
		(start 184.291986 -44.015406)
		(end 181.808374 -43.600624)
		(width 0.1143)
		(layer "In9.Cu")
		(net "UPI_CPU1_CPU0_P1P1_DP<4>")
	)
	(segment
		(start 289.596322 -52.290218)
		(end 289.506406 -52.200302)
		(width 0.0889)
		(layer "In9.Cu")
		(net "UPI_CPU1_CPU0_P1P1_DP<4>")
	)
	(segment
		(start 289.851846 -56.814466)
		(end 289.729672 -56.692292)
		(width 0.0889)
		(layer "In9.Cu")
		(net "UPI_CPU1_CPU0_P1P1_DP<4>")
	)
	(segment
		(start 138.514582 -53.828188)
		(end 138.514328 -53.827934)
		(width 0.0889)
		(layer "In9.Cu")
		(net "UPI_CPU1_CPU0_P1P1_DP<4>")
	)
	(segment
		(start 289.506406 -52.557934)
		(end 289.596322 -52.468018)
		(width 0.0889)
		(layer "In9.Cu")
		(net "UPI_CPU1_CPU0_P1P1_DP<4>")
	)
	(segment
		(start 211.932266 -44.090336)
		(end 199.238616 -40.985694)
		(width 0.1143)
		(layer "In9.Cu")
		(net "UPI_CPU1_CPU0_P1P1_DP<4>")
	)
	(segment
		(start 141.97584 -50.697384)
		(end 141.802358 -50.870866)
		(width 0.1143)
		(layer "In9.Cu")
		(net "UPI_CPU1_CPU0_P1P1_DP<4>")
	)
	(segment
		(start 141.815058 -50.883566)
		(end 141.815058 -50.9016)
		(width 0.0889)
		(layer "In9.Cu")
		(net "UPI_CPU1_CPU0_P1P1_DP<4>")
	)
	(segment
		(start 292.724332 -59.09437)
		(end 292.724332 -59.133486)
		(width 0.0889)
		(layer "In9.Cu")
		(net "UPI_CPU1_CPU0_P1P1_DP<4>")
	)
	(segment
		(start 137.9728 -54.068218)
		(end 137.670794 -53.923184)
		(width 0.0889)
		(layer "In9.Cu")
		(net "UPI_CPU1_CPU0_P1P1_DP<4>")
	)
	(segment
		(start 289.506406 -52.200302)
		(end 289.506406 -51.669442)
		(width 0.0889)
		(layer "In9.Cu")
		(net "UPI_CPU1_CPU0_P1P1_DP<4>")
	)
	(segment
		(start 256.417318 -44.225718)
		(end 247.938798 -45.541438)
		(width 0.1143)
		(layer "In9.Cu")
		(net "UPI_CPU1_CPU0_P1P1_DP<4>")
	)
	(segment
		(start 199.238616 -40.985694)
		(end 191.038226 -44.138342)
		(width 0.1143)
		(layer "In9.Cu")
		(net "UPI_CPU1_CPU0_P1P1_DP<4>")
	)
	(segment
		(start 222.396812 -43.2308)
		(end 211.932266 -44.090336)
		(width 0.1143)
		(layer "In9.Cu")
		(net "UPI_CPU1_CPU0_P1P1_DP<4>")
	)
	(segment
		(start 156.078682 -46.37913)
		(end 149.187916 -47.927006)
		(width 0.1143)
		(layer "In9.Cu")
		(net "UPI_CPU1_CPU0_P1P1_DP<4>")
	)
	(segment
		(start 140.173456 -52.03825)
		(end 140.001244 -52.454302)
		(width 0.0889)
		(layer "In9.Cu")
		(net "UPI_CPU1_CPU0_P1P1_DP<4>")
	)
	(segment
		(start 290.332414 -57.295034)
		(end 290.106608 -57.069228)
		(width 0.0889)
		(layer "In9.Cu")
		(net "UPI_CPU1_CPU0_P1P1_DP<4>")
	)
	(segment
		(start 140.001244 -52.454302)
		(end 138.942826 -53.51272)
		(width 0.0889)
		(layer "In9.Cu")
		(net "UPI_CPU1_CPU0_P1P1_DP<4>")
	)
	(segment
		(start 289.557206 -51.09972)
		(end 288.210498 -50.138838)
		(width 0.1143)
		(layer "In9.Cu")
		(net "UPI_CPU1_CPU0_P1P1_DP<4>")
	)
	(segment
		(start 141.195806 -51.0159)
		(end 140.173456 -52.03825)
		(width 0.0889)
		(layer "In9.Cu")
		(net "UPI_CPU1_CPU0_P1P1_DP<4>")
	)
	(segment
		(start 141.802358 -50.870866)
		(end 141.815058 -50.883566)
		(width 0.0889)
		(layer "In9.Cu")
		(net "UPI_CPU1_CPU0_P1P1_DP<4>")
	)
	(segment
		(start 141.815058 -50.9016)
		(end 141.700758 -51.0159)
		(width 0.0889)
		(layer "In9.Cu")
		(net "UPI_CPU1_CPU0_P1P1_DP<4>")
	)
	(segment
		(start 261.986776 -44.71416)
		(end 256.69113 -44.243752)
		(width 0.1143)
		(layer "In9.Cu")
		(net "UPI_CPU1_CPU0_P1P1_DP<4>")
	)
	(segment
		(start 290.66998 -57.295034)
		(end 290.332414 -57.295034)
		(width 0.0889)
		(layer "In9.Cu")
		(net "UPI_CPU1_CPU0_P1P1_DP<4>")
	)
	(segment
		(start 289.506406 -51.669442)
		(end 289.557206 -51.618642)
		(width 0.0889)
		(layer "In9.Cu")
		(net "UPI_CPU1_CPU0_P1P1_DP<4>")
	)
	(segment
		(start 138.539728 -53.828188)
		(end 138.514582 -53.828188)
		(width 0.0889)
		(layer "In9.Cu")
		(net "UPI_CPU1_CPU0_P1P1_DP<4>")
	)
	(segment
		(start 290.106608 -56.940196)
		(end 289.980878 -56.814466)
		(width 0.0889)
		(layer "In9.Cu")
		(net "UPI_CPU1_CPU0_P1P1_DP<4>")
	)
	(segment
		(start 149.187916 -47.927006)
		(end 146.14525 -49.1871)
		(width 0.1143)
		(layer "In9.Cu")
		(net "UPI_CPU1_CPU0_P1P1_DP<4>")
	)
	(segment
		(start 159.680148 -47.870364)
		(end 156.078682 -46.37913)
		(width 0.1143)
		(layer "In9.Cu")
		(net "UPI_CPU1_CPU0_P1P1_DP<4>")
	)
	(segment
		(start 289.506406 -52.720748)
		(end 289.506406 -52.557934)
		(width 0.0889)
		(layer "In9.Cu")
		(net "UPI_CPU1_CPU0_P1P1_DP<4>")
	)
	(segment
		(start 256.69113 -44.243752)
		(end 256.417318 -44.225718)
		(width 0.1143)
		(layer "In9.Cu")
		(net "UPI_CPU1_CPU0_P1P1_DP<4>")
	)
	(segment
		(start 289.596322 -52.468018)
		(end 289.596322 -52.290218)
		(width 0.0889)
		(layer "In9.Cu")
		(net "UPI_CPU1_CPU0_P1P1_DP<4>")
	)
	(segment
		(start 165.015672 -48.98263)
		(end 159.680148 -47.870364)
		(width 0.1143)
		(layer "In9.Cu")
		(net "UPI_CPU1_CPU0_P1P1_DP<4>")
	)
	(segment
		(start 289.729672 -52.944014)
		(end 289.506406 -52.720748)
		(width 0.0889)
		(layer "In9.Cu")
		(net "UPI_CPU1_CPU0_P1P1_DP<4>")
	)
	(segment
		(start 289.729672 -56.692292)
		(end 289.729672 -52.944014)
		(width 0.0889)
		(layer "In9.Cu")
		(net "UPI_CPU1_CPU0_P1P1_DP<4>")
	)
	(segment
		(start 292.36924 -58.876438)
		(end 292.5064 -58.876438)
		(width 0.0889)
		(layer "In9.Cu")
		(net "UPI_CPU1_CPU0_P1P1_DP<4>")
	)
	(segment
		(start 138.942826 -53.51272)
		(end 138.876024 -53.628036)
		(width 0.0889)
		(layer "In9.Cu")
		(net "UPI_CPU1_CPU0_P1P1_DP<4>")
	)
	(segment
		(start 288.210498 -50.138838)
		(end 285.571946 -48.988218)
		(width 0.1143)
		(layer "In9.Cu")
		(net "UPI_CPU1_CPU0_P1P1_DP<4>")
	)
	(segment
		(start 240.648998 -44.066206)
		(end 236.848396 -42.043858)
		(width 0.1143)
		(layer "In9.Cu")
		(net "UPI_CPU1_CPU0_P1P1_DP<4>")
	)
	(segment
		(start 289.557206 -51.618642)
		(end 289.557206 -51.09972)
		(width 0.1143)
		(layer "In9.Cu")
		(net "UPI_CPU1_CPU0_P1P1_DP<4>")
	)
	(segment
		(start 289.980878 -56.814466)
		(end 289.851846 -56.814466)
		(width 0.0889)
		(layer "In9.Cu")
		(net "UPI_CPU1_CPU0_P1P1_DP<4>")
	)
	(segment
		(start 285.571946 -48.988218)
		(end 264.708894 -43.969686)
		(width 0.1143)
		(layer "In9.Cu")
		(net "UPI_CPU1_CPU0_P1P1_DP<4>")
	)
	(segment
		(start 291.5285 -58.780934)
		(end 291.492686 -58.780934)
		(width 0.0889)
		(layer "In9.Cu")
		(net "UPI_CPU1_CPU0_P1P1_DP<4>")
	)
	(segment
		(start 236.848396 -42.043858)
		(end 222.396812 -43.2308)
		(width 0.1143)
		(layer "In9.Cu")
		(net "UPI_CPU1_CPU0_P1P1_DP<4>")
	)
	(arc
		(start 291.16401 -58.180986)
		(mid 291.168339 -57.597814)
		(end 290.66998 -57.295034)
		(width 0.0889)
		(layer "In9.Cu")
		(net "UPI_CPU1_CPU0_P1P1_DP<4>")
	)
	(arc
		(start 292.5064 -58.876438)
		(mid 292.660501 -58.940269)
		(end 292.724332 -59.09437)
		(width 0.0889)
		(layer "In9.Cu")
		(net "UPI_CPU1_CPU0_P1P1_DP<4>")
	)
	(arc
		(start 138.514328 -53.827934)
		(mid 138.255961 -53.894635)
		(end 138.053318 -54.068218)
		(width 0.0889)
		(layer "In9.Cu")
		(net "UPI_CPU1_CPU0_P1P1_DP<4>")
	)
	(arc
		(start 292.641782 -59.262772)
		(mid 292.612417 -59.27278)
		(end 292.581584 -59.276234)
		(width 0.0889)
		(layer "In9.Cu")
		(net "UPI_CPU1_CPU0_P1P1_DP<4>")
	)
	(arc
		(start 292.351206 -59.276234)
		(mid 292.161277 -59.218364)
		(end 292.02253 -59.076336)
		(width 0.0889)
		(layer "In9.Cu")
		(net "UPI_CPU1_CPU0_P1P1_DP<4>")
	)
	(arc
		(start 138.876024 -53.628036)
		(mid 138.733981 -53.771948)
		(end 138.539728 -53.828188)
		(width 0.0889)
		(layer "In9.Cu")
		(net "UPI_CPU1_CPU0_P1P1_DP<4>")
	)
	(arc
		(start 292.724332 -59.133486)
		(mid 292.701933 -59.210179)
		(end 292.641782 -59.262772)
		(width 0.0889)
		(layer "In9.Cu")
		(net "UPI_CPU1_CPU0_P1P1_DP<4>")
	)
	(arc
		(start 291.492686 -58.780934)
		(mid 291.159717 -58.573386)
		(end 291.16401 -58.180986)
		(width 0.0889)
		(layer "In9.Cu")
		(net "UPI_CPU1_CPU0_P1P1_DP<4>")
	)
	(arc
		(start 292.02253 -59.076336)
		(mid 291.813922 -58.864404)
		(end 291.5285 -58.780934)
		(width 0.0889)
		(layer "In9.Cu")
		(net "UPI_CPU1_CPU0_P1P1_DP<4>")
	)
	(segment
		(start 290.0807 -58.876438)
		(end 290.6522 -58.876438)
		(width 0.1143)
		(layer "F.Cu")
		(net "UPI_CPU1_CPU0_P1P1_DP<3>")
	)
	(segment
		(start 138.816334 -54.913784)
		(end 139.387834 -54.913784)
		(width 0.1143)
		(layer "F.Cu")
		(net "UPI_CPU1_CPU0_P1P1_DP<3>")
	)
	(via
		(at 290.6522 -58.876438)
		(size 0.508)
		(drill 0.254)
		(layers "F.Cu" "B.Cu")
		(net "UPI_CPU1_CPU0_P1P1_DP<3>")
	)
	(via
		(at 139.387834 -54.913784)
		(size 0.508)
		(drill 0.254)
		(layers "F.Cu" "B.Cu")
		(net "UPI_CPU1_CPU0_P1P1_DP<3>")
	)
	(segment
		(start 286.441642 -50.614072)
		(end 286.380682 -50.435002)
		(width 0.1143)
		(layer "In9.Cu")
		(net "UPI_CPU1_CPU0_P1P1_DP<3>")
	)
	(segment
		(start 285.188914 -49.849278)
		(end 264.785856 -44.966382)
		(width 0.1143)
		(layer "In9.Cu")
		(net "UPI_CPU1_CPU0_P1P1_DP<3>")
	)
	(segment
		(start 286.725868 -50.753264)
		(end 286.441642 -50.614072)
		(width 0.1143)
		(layer "In9.Cu")
		(net "UPI_CPU1_CPU0_P1P1_DP<3>")
	)
	(segment
		(start 240.226596 -44.931076)
		(end 236.624368 -43.018456)
		(width 0.1143)
		(layer "In9.Cu")
		(net "UPI_CPU1_CPU0_P1P1_DP<3>")
	)
	(segment
		(start 164.879274 -49.961038)
		(end 159.780224 -48.937926)
		(width 0.1143)
		(layer "In9.Cu")
		(net "UPI_CPU1_CPU0_P1P1_DP<3>")
	)
	(segment
		(start 285.189168 -49.849278)
		(end 285.188914 -49.849278)
		(width 0.1143)
		(layer "In9.Cu")
		(net "UPI_CPU1_CPU0_P1P1_DP<3>")
	)
	(segment
		(start 191.227456 -45.07484)
		(end 184.303162 -45.002958)
		(width 0.1143)
		(layer "In9.Cu")
		(net "UPI_CPU1_CPU0_P1P1_DP<3>")
	)
	(segment
		(start 236.624368 -43.018456)
		(end 222.396812 -44.236132)
		(width 0.1143)
		(layer "In9.Cu")
		(net "UPI_CPU1_CPU0_P1P1_DP<3>")
	)
	(segment
		(start 247.837452 -46.496224)
		(end 240.226596 -44.931076)
		(width 0.1143)
		(layer "In9.Cu")
		(net "UPI_CPU1_CPU0_P1P1_DP<3>")
	)
	(segment
		(start 139.40917 -54.513734)
		(end 139.376658 -54.513734)
		(width 0.0889)
		(layer "In9.Cu")
		(net "UPI_CPU1_CPU0_P1P1_DP<3>")
	)
	(segment
		(start 142.602712 -51.758342)
		(end 142.3416 -52.0192)
		(width 0.1143)
		(layer "In9.Cu")
		(net "UPI_CPU1_CPU0_P1P1_DP<3>")
	)
	(segment
		(start 139.015978 -55.061612)
		(end 139.048998 -55.14467)
		(width 0.0889)
		(layer "In9.Cu")
		(net "UPI_CPU1_CPU0_P1P1_DP<3>")
	)
	(segment
		(start 150.433278 -48.593756)
		(end 145.133314 -50.787808)
		(width 0.1143)
		(layer "In9.Cu")
		(net "UPI_CPU1_CPU0_P1P1_DP<3>")
	)
	(segment
		(start 288.487104 -52.30495)
		(end 288.487104 -51.881532)
		(width 0.1143)
		(layer "In9.Cu")
		(net "UPI_CPU1_CPU0_P1P1_DP<3>")
	)
	(segment
		(start 195.304918 -43.504104)
		(end 191.33566 -45.036486)
		(width 0.1143)
		(layer "In9.Cu")
		(net "UPI_CPU1_CPU0_P1P1_DP<3>")
	)
	(segment
		(start 288.537904 -52.721764)
		(end 288.537904 -52.377848)
		(width 0.0889)
		(layer "In9.Cu")
		(net "UPI_CPU1_CPU0_P1P1_DP<3>")
	)
	(segment
		(start 143.443706 -51.4096)
		(end 142.602712 -51.758342)
		(width 0.1143)
		(layer "In9.Cu")
		(net "UPI_CPU1_CPU0_P1P1_DP<3>")
	)
	(segment
		(start 288.537904 -52.377848)
		(end 288.487104 -52.327048)
		(width 0.0889)
		(layer "In9.Cu")
		(net "UPI_CPU1_CPU0_P1P1_DP<3>")
	)
	(segment
		(start 144.037558 -51.40325)
		(end 143.842232 -51.322224)
		(width 0.1143)
		(layer "In9.Cu")
		(net "UPI_CPU1_CPU0_P1P1_DP<3>")
	)
	(segment
		(start 141.4018 -51.9684)
		(end 140.9954 -52.3748)
		(width 0.0889)
		(layer "In9.Cu")
		(net "UPI_CPU1_CPU0_P1P1_DP<3>")
	)
	(segment
		(start 288.244026 -51.66106)
		(end 288.157666 -51.582574)
		(width 0.1143)
		(layer "In9.Cu")
		(net "UPI_CPU1_CPU0_P1P1_DP<3>")
	)
	(segment
		(start 195.304918 -43.50385)
		(end 195.304918 -43.504104)
		(width 0.1143)
		(layer "In9.Cu")
		(net "UPI_CPU1_CPU0_P1P1_DP<3>")
	)
	(segment
		(start 211.882482 -45.136054)
		(end 199.274176 -41.971722)
		(width 0.1143)
		(layer "In9.Cu")
		(net "UPI_CPU1_CPU0_P1P1_DP<3>")
	)
	(segment
		(start 140.532358 -53.492654)
		(end 140.026644 -53.998368)
		(width 0.0889)
		(layer "In9.Cu")
		(net "UPI_CPU1_CPU0_P1P1_DP<3>")
	)
	(segment
		(start 288.487104 -52.327048)
		(end 288.487104 -52.30495)
		(width 0.0889)
		(layer "In9.Cu")
		(net "UPI_CPU1_CPU0_P1P1_DP<3>")
	)
	(segment
		(start 144.80159 -51.097688)
		(end 144.59331 -51.011328)
		(width 0.1143)
		(layer "In9.Cu")
		(net "UPI_CPU1_CPU0_P1P1_DP<3>")
	)
	(segment
		(start 141.8844 -52.0192)
		(end 141.8336 -51.9684)
		(width 0.0889)
		(layer "In9.Cu")
		(net "UPI_CPU1_CPU0_P1P1_DP<3>")
	)
	(segment
		(start 222.396812 -44.236132)
		(end 211.882482 -45.136054)
		(width 0.1143)
		(layer "In9.Cu")
		(net "UPI_CPU1_CPU0_P1P1_DP<3>")
	)
	(segment
		(start 287.497266 -50.983896)
		(end 286.90443 -50.692558)
		(width 0.1143)
		(layer "In9.Cu")
		(net "UPI_CPU1_CPU0_P1P1_DP<3>")
	)
	(segment
		(start 264.785856 -44.966382)
		(end 264.698734 -44.988734)
		(width 0.1143)
		(layer "In9.Cu")
		(net "UPI_CPU1_CPU0_P1P1_DP<3>")
	)
	(segment
		(start 288.157666 -51.582574)
		(end 288.003234 -51.590194)
		(width 0.1143)
		(layer "In9.Cu")
		(net "UPI_CPU1_CPU0_P1P1_DP<3>")
	)
	(segment
		(start 144.382236 -51.098704)
		(end 144.30121 -51.29403)
		(width 0.1143)
		(layer "In9.Cu")
		(net "UPI_CPU1_CPU0_P1P1_DP<3>")
	)
	(segment
		(start 140.9954 -52.3748)
		(end 140.532358 -53.492654)
		(width 0.0889)
		(layer "In9.Cu")
		(net "UPI_CPU1_CPU0_P1P1_DP<3>")
	)
	(segment
		(start 140.026644 -53.998368)
		(end 139.899644 -54.218586)
		(width 0.0889)
		(layer "In9.Cu")
		(net "UPI_CPU1_CPU0_P1P1_DP<3>")
	)
	(segment
		(start 145.133314 -50.787808)
		(end 145.046954 -50.996088)
		(width 0.1143)
		(layer "In9.Cu")
		(net "UPI_CPU1_CPU0_P1P1_DP<3>")
	)
	(segment
		(start 262.097266 -45.659294)
		(end 256.487676 -45.169328)
		(width 0.1143)
		(layer "In9.Cu")
		(net "UPI_CPU1_CPU0_P1P1_DP<3>")
	)
	(segment
		(start 142.3416 -52.0192)
		(end 141.906498 -52.0192)
		(width 0.1143)
		(layer "In9.Cu")
		(net "UPI_CPU1_CPU0_P1P1_DP<3>")
	)
	(segment
		(start 145.046954 -50.996088)
		(end 144.80159 -51.097688)
		(width 0.1143)
		(layer "In9.Cu")
		(net "UPI_CPU1_CPU0_P1P1_DP<3>")
	)
	(segment
		(start 289.05962 -57.043066)
		(end 289.05962 -53.24348)
		(width 0.0889)
		(layer "In9.Cu")
		(net "UPI_CPU1_CPU0_P1P1_DP<3>")
	)
	(segment
		(start 287.723072 -51.18862)
		(end 287.497266 -50.983896)
		(width 0.1143)
		(layer "In9.Cu")
		(net "UPI_CPU1_CPU0_P1P1_DP<3>")
	)
	(segment
		(start 143.631158 -51.4096)
		(end 143.443706 -51.4096)
		(width 0.1143)
		(layer "In9.Cu")
		(net "UPI_CPU1_CPU0_P1P1_DP<3>")
	)
	(segment
		(start 159.780224 -48.937926)
		(end 155.923234 -47.340774)
		(width 0.1143)
		(layer "In9.Cu")
		(net "UPI_CPU1_CPU0_P1P1_DP<3>")
	)
	(segment
		(start 155.923234 -47.340774)
		(end 150.433278 -48.593756)
		(width 0.1143)
		(layer "In9.Cu")
		(net "UPI_CPU1_CPU0_P1P1_DP<3>")
	)
	(segment
		(start 191.33566 -45.036486)
		(end 191.227456 -45.07484)
		(width 0.1143)
		(layer "In9.Cu")
		(net "UPI_CPU1_CPU0_P1P1_DP<3>")
	)
	(segment
		(start 184.303162 -45.002958)
		(end 181.810914 -44.655232)
		(width 0.1143)
		(layer "In9.Cu")
		(net "UPI_CPU1_CPU0_P1P1_DP<3>")
	)
	(segment
		(start 286.90443 -50.692558)
		(end 286.725868 -50.753264)
		(width 0.1143)
		(layer "In9.Cu")
		(net "UPI_CPU1_CPU0_P1P1_DP<3>")
	)
	(segment
		(start 290.6522 -58.876438)
		(end 289.80257 -58.026808)
		(width 0.0889)
		(layer "In9.Cu")
		(net "UPI_CPU1_CPU0_P1P1_DP<3>")
	)
	(segment
		(start 288.487104 -51.881532)
		(end 288.244026 -51.66106)
		(width 0.1143)
		(layer "In9.Cu")
		(net "UPI_CPU1_CPU0_P1P1_DP<3>")
	)
	(segment
		(start 141.906498 -52.0192)
		(end 141.8844 -52.0192)
		(width 0.0889)
		(layer "In9.Cu")
		(net "UPI_CPU1_CPU0_P1P1_DP<3>")
	)
	(segment
		(start 287.730438 -51.34229)
		(end 287.723072 -51.18862)
		(width 0.1143)
		(layer "In9.Cu")
		(net "UPI_CPU1_CPU0_P1P1_DP<3>")
	)
	(segment
		(start 143.842232 -51.322224)
		(end 143.631158 -51.4096)
		(width 0.1143)
		(layer "In9.Cu")
		(net "UPI_CPU1_CPU0_P1P1_DP<3>")
	)
	(segment
		(start 289.80257 -58.026808)
		(end 289.80257 -57.786016)
		(width 0.0889)
		(layer "In9.Cu")
		(net "UPI_CPU1_CPU0_P1P1_DP<3>")
	)
	(segment
		(start 139.38758 -55.0799)
		(end 139.387834 -54.913784)
		(width 0.0889)
		(layer "In9.Cu")
		(net "UPI_CPU1_CPU0_P1P1_DP<3>")
	)
	(segment
		(start 144.59331 -51.011328)
		(end 144.382236 -51.098704)
		(width 0.1143)
		(layer "In9.Cu")
		(net "UPI_CPU1_CPU0_P1P1_DP<3>")
	)
	(segment
		(start 288.003234 -51.590194)
		(end 287.730438 -51.34229)
		(width 0.1143)
		(layer "In9.Cu")
		(net "UPI_CPU1_CPU0_P1P1_DP<3>")
	)
	(segment
		(start 289.80257 -57.786016)
		(end 289.05962 -57.043066)
		(width 0.0889)
		(layer "In9.Cu")
		(net "UPI_CPU1_CPU0_P1P1_DP<3>")
	)
	(segment
		(start 256.487676 -45.169328)
		(end 247.837452 -46.496224)
		(width 0.1143)
		(layer "In9.Cu")
		(net "UPI_CPU1_CPU0_P1P1_DP<3>")
	)
	(segment
		(start 169.062146 -49.093374)
		(end 164.879274 -49.961038)
		(width 0.1143)
		(layer "In9.Cu")
		(net "UPI_CPU1_CPU0_P1P1_DP<3>")
	)
	(segment
		(start 289.05962 -53.24348)
		(end 288.537904 -52.721764)
		(width 0.0889)
		(layer "In9.Cu")
		(net "UPI_CPU1_CPU0_P1P1_DP<3>")
	)
	(segment
		(start 264.698734 -44.988734)
		(end 262.097266 -45.659294)
		(width 0.1143)
		(layer "In9.Cu")
		(net "UPI_CPU1_CPU0_P1P1_DP<3>")
	)
	(segment
		(start 181.810914 -44.655232)
		(end 169.062146 -49.093374)
		(width 0.1143)
		(layer "In9.Cu")
		(net "UPI_CPU1_CPU0_P1P1_DP<3>")
	)
	(segment
		(start 141.8336 -51.9684)
		(end 141.4018 -51.9684)
		(width 0.0889)
		(layer "In9.Cu")
		(net "UPI_CPU1_CPU0_P1P1_DP<3>")
	)
	(segment
		(start 199.274176 -41.971722)
		(end 195.304918 -43.50385)
		(width 0.1143)
		(layer "In9.Cu")
		(net "UPI_CPU1_CPU0_P1P1_DP<3>")
	)
	(segment
		(start 144.30121 -51.29403)
		(end 144.037558 -51.40325)
		(width 0.1143)
		(layer "In9.Cu")
		(net "UPI_CPU1_CPU0_P1P1_DP<3>")
	)
	(segment
		(start 286.380682 -50.435002)
		(end 285.189168 -49.849278)
		(width 0.1143)
		(layer "In9.Cu")
		(net "UPI_CPU1_CPU0_P1P1_DP<3>")
	)
	(arc
		(start 139.899644 -54.218586)
		(mid 139.692531 -54.429516)
		(end 139.40917 -54.513734)
		(width 0.0889)
		(layer "In9.Cu")
		(net "UPI_CPU1_CPU0_P1P1_DP<3>")
	)
	(arc
		(start 139.048998 -55.14467)
		(mid 139.245038 -55.252234)
		(end 139.38758 -55.0799)
		(width 0.0889)
		(layer "In9.Cu")
		(net "UPI_CPU1_CPU0_P1P1_DP<3>")
	)
	(arc
		(start 139.376658 -54.513734)
		(mid 139.053628 -54.693787)
		(end 139.015978 -55.061612)
		(width 0.0889)
		(layer "In9.Cu")
		(net "UPI_CPU1_CPU0_P1P1_DP<3>")
	)
	(segment
		(start 291.79774 -60.857384)
		(end 292.36924 -60.857384)
		(width 0.1143)
		(layer "F.Cu")
		(net "UPI_CPU1_CPU0_P1P1_DP<2>")
	)
	(segment
		(start 138.816334 -56.894984)
		(end 139.387834 -56.894984)
		(width 0.1143)
		(layer "F.Cu")
		(net "UPI_CPU1_CPU0_P1P1_DP<2>")
	)
	(via
		(at 292.36924 -60.857384)
		(size 0.508)
		(drill 0.254)
		(layers "F.Cu" "B.Cu")
		(net "UPI_CPU1_CPU0_P1P1_DP<2>")
	)
	(via
		(at 139.387834 -56.894984)
		(size 0.508)
		(drill 0.254)
		(layers "F.Cu" "B.Cu")
		(net "UPI_CPU1_CPU0_P1P1_DP<2>")
	)
	(segment
		(start 292.36924 -60.857384)
		(end 292.36924 -60.51931)
		(width 0.0889)
		(layer "In9.Cu")
		(net "UPI_CPU1_CPU0_P1P1_DP<2>")
	)
	(segment
		(start 140.804138 -54.634384)
		(end 140.758418 -54.713886)
		(width 0.0889)
		(layer "In9.Cu")
		(net "UPI_CPU1_CPU0_P1P1_DP<2>")
	)
	(segment
		(start 236.371384 -43.682158)
		(end 222.396812 -44.892468)
		(width 0.1143)
		(layer "In9.Cu")
		(net "UPI_CPU1_CPU0_P1P1_DP<2>")
	)
	(segment
		(start 282.847796 -49.99863)
		(end 264.89406 -45.611288)
		(width 0.1143)
		(layer "In9.Cu")
		(net "UPI_CPU1_CPU0_P1P1_DP<2>")
	)
	(segment
		(start 184.513474 -45.682408)
		(end 181.9275 -45.406564)
		(width 0.1143)
		(layer "In9.Cu")
		(net "UPI_CPU1_CPU0_P1P1_DP<2>")
	)
	(segment
		(start 288.13887 -56.695086)
		(end 288.13252 -56.684418)
		(width 0.0889)
		(layer "In9.Cu")
		(net "UPI_CPU1_CPU0_P1P1_DP<2>")
	)
	(segment
		(start 190.60922 -45.721778)
		(end 184.513474 -45.682408)
		(width 0.1143)
		(layer "In9.Cu")
		(net "UPI_CPU1_CPU0_P1P1_DP<2>")
	)
	(segment
		(start 164.831522 -50.640488)
		(end 159.905954 -49.710848)
		(width 0.1143)
		(layer "In9.Cu")
		(net "UPI_CPU1_CPU0_P1P1_DP<2>")
	)
	(segment
		(start 247.918986 -47.163482)
		(end 239.77219 -45.48886)
		(width 0.1143)
		(layer "In9.Cu")
		(net "UPI_CPU1_CPU0_P1P1_DP<2>")
	)
	(segment
		(start 264.89406 -45.611288)
		(end 262.12419 -46.341538)
		(width 0.1143)
		(layer "In9.Cu")
		(net "UPI_CPU1_CPU0_P1P1_DP<2>")
	)
	(segment
		(start 151.191976 -49.111154)
		(end 150.225252 -49.423574)
		(width 0.1143)
		(layer "In9.Cu")
		(net "UPI_CPU1_CPU0_P1P1_DP<2>")
	)
	(segment
		(start 283.213048 -50.437288)
		(end 283.200348 -50.294286)
		(width 0.1143)
		(layer "In9.Cu")
		(net "UPI_CPU1_CPU0_P1P1_DP<2>")
	)
	(segment
		(start 150.225252 -49.423574)
		(end 146.934936 -50.788062)
		(width 0.1143)
		(layer "In9.Cu")
		(net "UPI_CPU1_CPU0_P1P1_DP<2>")
	)
	(segment
		(start 139.894818 -55.6006)
		(end 139.899644 -55.609236)
		(width 0.0889)
		(layer "In9.Cu")
		(net "UPI_CPU1_CPU0_P1P1_DP<2>")
	)
	(segment
		(start 142.3162 -53.997098)
		(end 141.092174 -54.346348)
		(width 0.0889)
		(layer "In9.Cu")
		(net "UPI_CPU1_CPU0_P1P1_DP<2>")
	)
	(segment
		(start 288.13887 -55.704486)
		(end 288.13252 -55.693818)
		(width 0.0889)
		(layer "In9.Cu")
		(net "UPI_CPU1_CPU0_P1P1_DP<2>")
	)
	(segment
		(start 284.613096 -51.4858)
		(end 284.438852 -51.332638)
		(width 0.1143)
		(layer "In9.Cu")
		(net "UPI_CPU1_CPU0_P1P1_DP<2>")
	)
	(segment
		(start 288.143696 -55.713122)
		(end 288.13887 -55.704486)
		(width 0.0889)
		(layer "In9.Cu")
		(net "UPI_CPU1_CPU0_P1P1_DP<2>")
	)
	(segment
		(start 287.791398 -52.618386)
		(end 287.665668 -52.492656)
		(width 0.0889)
		(layer "In9.Cu")
		(net "UPI_CPU1_CPU0_P1P1_DP<2>")
	)
	(segment
		(start 181.9275 -45.406564)
		(end 169.519346 -49.681638)
		(width 0.1143)
		(layer "In9.Cu")
		(net "UPI_CPU1_CPU0_P1P1_DP<2>")
	)
	(segment
		(start 145.476214 -51.971956)
		(end 144.363948 -52.791614)
		(width 0.1143)
		(layer "In9.Cu")
		(net "UPI_CPU1_CPU0_P1P1_DP<2>")
	)
	(segment
		(start 287.665668 -52.361592)
		(end 287.341564 -52.037488)
		(width 0.0889)
		(layer "In9.Cu")
		(net "UPI_CPU1_CPU0_P1P1_DP<2>")
	)
	(segment
		(start 144.257522 -52.791614)
		(end 142.3162 -53.997098)
		(width 0.0889)
		(layer "In9.Cu")
		(net "UPI_CPU1_CPU0_P1P1_DP<2>")
	)
	(segment
		(start 140.264134 -55.009288)
		(end 140.231368 -55.009288)
		(width 0.0889)
		(layer "In9.Cu")
		(net "UPI_CPU1_CPU0_P1P1_DP<2>")
	)
	(segment
		(start 288.143696 -56.703722)
		(end 288.13887 -56.695086)
		(width 0.0889)
		(layer "In9.Cu")
		(net "UPI_CPU1_CPU0_P1P1_DP<2>")
	)
	(segment
		(start 291.521134 -59.962034)
		(end 291.497258 -59.962034)
		(width 0.0889)
		(layer "In9.Cu")
		(net "UPI_CPU1_CPU0_P1P1_DP<2>")
	)
	(segment
		(start 288.025332 -53.526944)
		(end 288.025332 -52.721256)
		(width 0.0889)
		(layer "In9.Cu")
		(net "UPI_CPU1_CPU0_P1P1_DP<2>")
	)
	(segment
		(start 292.36924 -60.51931)
		(end 292.304216 -60.454032)
		(width 0.0889)
		(layer "In9.Cu")
		(net "UPI_CPU1_CPU0_P1P1_DP<2>")
	)
	(segment
		(start 145.494756 -51.84902)
		(end 145.476214 -51.971956)
		(width 0.1143)
		(layer "In9.Cu")
		(net "UPI_CPU1_CPU0_P1P1_DP<2>")
	)
	(segment
		(start 146.934936 -50.788062)
		(end 145.494756 -51.84902)
		(width 0.1143)
		(layer "In9.Cu")
		(net "UPI_CPU1_CPU0_P1P1_DP<2>")
	)
	(segment
		(start 285.766764 -51.435)
		(end 285.4325 -51.435)
		(width 0.0889)
		(layer "In9.Cu")
		(net "UPI_CPU1_CPU0_P1P1_DP<2>")
	)
	(segment
		(start 141.092174 -54.346348)
		(end 140.804138 -54.634384)
		(width 0.0889)
		(layer "In9.Cu")
		(net "UPI_CPU1_CPU0_P1P1_DP<2>")
	)
	(segment
		(start 290.670234 -59.466988)
		(end 290.332922 -59.466988)
		(width 0.0889)
		(layer "In9.Cu")
		(net "UPI_CPU1_CPU0_P1P1_DP<2>")
	)
	(segment
		(start 208.216246 -44.963842)
		(end 199.33793 -42.653458)
		(width 0.1143)
		(layer "In9.Cu")
		(net "UPI_CPU1_CPU0_P1P1_DP<2>")
	)
	(segment
		(start 144.363948 -52.791614)
		(end 144.257522 -52.791614)
		(width 0.0889)
		(layer "In9.Cu")
		(net "UPI_CPU1_CPU0_P1P1_DP<2>")
	)
	(segment
		(start 192.324228 -45.389546)
		(end 191.396874 -45.721778)
		(width 0.1143)
		(layer "In9.Cu")
		(net "UPI_CPU1_CPU0_P1P1_DP<2>")
	)
	(segment
		(start 169.519346 -49.681638)
		(end 164.831522 -50.640488)
		(width 0.1143)
		(layer "In9.Cu")
		(net "UPI_CPU1_CPU0_P1P1_DP<2>")
	)
	(segment
		(start 191.396874 -45.721778)
		(end 190.60922 -45.721778)
		(width 0.1143)
		(layer "In9.Cu")
		(net "UPI_CPU1_CPU0_P1P1_DP<2>")
	)
	(segment
		(start 288.143696 -54.722522)
		(end 288.13887 -54.713886)
		(width 0.0889)
		(layer "In9.Cu")
		(net "UPI_CPU1_CPU0_P1P1_DP<2>")
	)
	(segment
		(start 256.251456 -45.84827)
		(end 247.918986 -47.163482)
		(width 0.1143)
		(layer "In9.Cu")
		(net "UPI_CPU1_CPU0_P1P1_DP<2>")
	)
	(segment
		(start 256.59715 -45.870622)
		(end 256.251456 -45.84827)
		(width 0.1143)
		(layer "In9.Cu")
		(net "UPI_CPU1_CPU0_P1P1_DP<2>")
	)
	(segment
		(start 288.143696 -53.731922)
		(end 288.025332 -53.526944)
		(width 0.0889)
		(layer "In9.Cu")
		(net "UPI_CPU1_CPU0_P1P1_DP<2>")
	)
	(segment
		(start 199.33793 -42.653458)
		(end 192.324228 -45.389546)
		(width 0.1143)
		(layer "In9.Cu")
		(net "UPI_CPU1_CPU0_P1P1_DP<2>")
	)
	(segment
		(start 288.025332 -52.721256)
		(end 287.922462 -52.618386)
		(width 0.0889)
		(layer "In9.Cu")
		(net "UPI_CPU1_CPU0_P1P1_DP<2>")
	)
	(segment
		(start 139.899644 -55.609236)
		(end 139.905994 -55.619904)
		(width 0.0889)
		(layer "In9.Cu")
		(net "UPI_CPU1_CPU0_P1P1_DP<2>")
	)
	(segment
		(start 159.905954 -49.710848)
		(end 155.876244 -48.04156)
		(width 0.1143)
		(layer "In9.Cu")
		(net "UPI_CPU1_CPU0_P1P1_DP<2>")
	)
	(segment
		(start 239.77219 -45.48886)
		(end 236.371384 -43.682158)
		(width 0.1143)
		(layer "In9.Cu")
		(net "UPI_CPU1_CPU0_P1P1_DP<2>")
	)
	(segment
		(start 292.304216 -60.454032)
		(end 292.304216 -60.454286)
		(width 0.0889)
		(layer "In9.Cu")
		(net "UPI_CPU1_CPU0_P1P1_DP<2>")
	)
	(segment
		(start 290.332922 -59.466988)
		(end 288.848038 -57.982104)
		(width 0.0889)
		(layer "In9.Cu")
		(net "UPI_CPU1_CPU0_P1P1_DP<2>")
	)
	(segment
		(start 211.807298 -45.809662)
		(end 208.216246 -44.963842)
		(width 0.1143)
		(layer "In9.Cu")
		(net "UPI_CPU1_CPU0_P1P1_DP<2>")
	)
	(segment
		(start 284.438852 -51.332638)
		(end 283.619194 -50.645314)
		(width 0.1143)
		(layer "In9.Cu")
		(net "UPI_CPU1_CPU0_P1P1_DP<2>")
	)
	(segment
		(start 286.369252 -52.037488)
		(end 285.766764 -51.435)
		(width 0.0889)
		(layer "In9.Cu")
		(net "UPI_CPU1_CPU0_P1P1_DP<2>")
	)
	(segment
		(start 285.359602 -51.4858)
		(end 284.613096 -51.4858)
		(width 0.1143)
		(layer "In9.Cu")
		(net "UPI_CPU1_CPU0_P1P1_DP<2>")
	)
	(segment
		(start 288.848038 -57.982104)
		(end 288.65068 -57.982104)
		(width 0.0889)
		(layer "In9.Cu")
		(net "UPI_CPU1_CPU0_P1P1_DP<2>")
	)
	(segment
		(start 283.200348 -50.294286)
		(end 282.847796 -49.99863)
		(width 0.1143)
		(layer "In9.Cu")
		(net "UPI_CPU1_CPU0_P1P1_DP<2>")
	)
	(segment
		(start 222.396812 -44.892468)
		(end 211.807298 -45.809662)
		(width 0.1143)
		(layer "In9.Cu")
		(net "UPI_CPU1_CPU0_P1P1_DP<2>")
	)
	(segment
		(start 155.876244 -48.04156)
		(end 151.191976 -49.111154)
		(width 0.1143)
		(layer "In9.Cu")
		(net "UPI_CPU1_CPU0_P1P1_DP<2>")
	)
	(segment
		(start 285.4325 -51.435)
		(end 285.359602 -51.4858)
		(width 0.0889)
		(layer "In9.Cu")
		(net "UPI_CPU1_CPU0_P1P1_DP<2>")
	)
	(segment
		(start 139.872212 -56.24322)
		(end 139.559284 -56.690514)
		(width 0.0889)
		(layer "In9.Cu")
		(net "UPI_CPU1_CPU0_P1P1_DP<2>")
	)
	(segment
		(start 288.13887 -54.713886)
		(end 288.13252 -54.703218)
		(width 0.0889)
		(layer "In9.Cu")
		(net "UPI_CPU1_CPU0_P1P1_DP<2>")
	)
	(segment
		(start 287.922462 -52.618386)
		(end 287.791398 -52.618386)
		(width 0.0889)
		(layer "In9.Cu")
		(net "UPI_CPU1_CPU0_P1P1_DP<2>")
	)
	(segment
		(start 287.665668 -52.492656)
		(end 287.665668 -52.361592)
		(width 0.0889)
		(layer "In9.Cu")
		(net "UPI_CPU1_CPU0_P1P1_DP<2>")
	)
	(segment
		(start 283.475938 -50.658014)
		(end 283.213048 -50.437288)
		(width 0.1143)
		(layer "In9.Cu")
		(net "UPI_CPU1_CPU0_P1P1_DP<2>")
	)
	(segment
		(start 283.619194 -50.645314)
		(end 283.475938 -50.658014)
		(width 0.1143)
		(layer "In9.Cu")
		(net "UPI_CPU1_CPU0_P1P1_DP<2>")
	)
	(segment
		(start 262.12419 -46.341538)
		(end 256.59715 -45.870622)
		(width 0.1143)
		(layer "In9.Cu")
		(net "UPI_CPU1_CPU0_P1P1_DP<2>")
	)
	(segment
		(start 291.497258 -59.962034)
		(end 291.497766 -59.962288)
		(width 0.0889)
		(layer "In9.Cu")
		(net "UPI_CPU1_CPU0_P1P1_DP<2>")
	)
	(segment
		(start 287.341564 -52.037488)
		(end 286.369252 -52.037488)
		(width 0.0889)
		(layer "In9.Cu")
		(net "UPI_CPU1_CPU0_P1P1_DP<2>")
	)
	(arc
		(start 139.905994 -55.619904)
		(mid 139.978084 -55.936383)
		(end 139.872212 -56.24322)
		(width 0.0889)
		(layer "In9.Cu")
		(net "UPI_CPU1_CPU0_P1P1_DP<2>")
	)
	(arc
		(start 288.13887 -54.123336)
		(mid 288.19234 -53.928273)
		(end 288.143696 -53.731922)
		(width 0.0889)
		(layer "In9.Cu")
		(net "UPI_CPU1_CPU0_P1P1_DP<2>")
	)
	(arc
		(start 139.559284 -56.690514)
		(mid 139.478037 -56.796504)
		(end 139.387834 -56.894984)
		(width 0.0889)
		(layer "In9.Cu")
		(net "UPI_CPU1_CPU0_P1P1_DP<2>")
	)
	(arc
		(start 290.99891 -59.666886)
		(mid 290.860166 -59.524853)
		(end 290.670234 -59.466988)
		(width 0.0889)
		(layer "In9.Cu")
		(net "UPI_CPU1_CPU0_P1P1_DP<2>")
	)
	(arc
		(start 292.262052 -60.447682)
		(mid 292.028457 -60.349451)
		(end 291.85743 -60.16244)
		(width 0.0889)
		(layer "In9.Cu")
		(net "UPI_CPU1_CPU0_P1P1_DP<2>")
	)
	(arc
		(start 140.758418 -54.713886)
		(mid 140.549701 -54.925883)
		(end 140.264134 -55.009288)
		(width 0.0889)
		(layer "In9.Cu")
		(net "UPI_CPU1_CPU0_P1P1_DP<2>")
	)
	(arc
		(start 288.13252 -56.684418)
		(mid 288.059722 -56.393655)
		(end 288.13887 -56.104536)
		(width 0.0889)
		(layer "In9.Cu")
		(net "UPI_CPU1_CPU0_P1P1_DP<2>")
	)
	(arc
		(start 288.13887 -55.113936)
		(mid 288.19234 -54.918873)
		(end 288.143696 -54.722522)
		(width 0.0889)
		(layer "In9.Cu")
		(net "UPI_CPU1_CPU0_P1P1_DP<2>")
	)
	(arc
		(start 291.497766 -59.962288)
		(mid 291.209621 -59.879969)
		(end 290.99891 -59.666886)
		(width 0.0889)
		(layer "In9.Cu")
		(net "UPI_CPU1_CPU0_P1P1_DP<2>")
	)
	(arc
		(start 288.13887 -57.095136)
		(mid 288.19234 -56.900073)
		(end 288.143696 -56.703722)
		(width 0.0889)
		(layer "In9.Cu")
		(net "UPI_CPU1_CPU0_P1P1_DP<2>")
	)
	(arc
		(start 288.13252 -54.703218)
		(mid 288.059722 -54.412455)
		(end 288.13887 -54.123336)
		(width 0.0889)
		(layer "In9.Cu")
		(net "UPI_CPU1_CPU0_P1P1_DP<2>")
	)
	(arc
		(start 140.231368 -55.009288)
		(mid 139.89845 -55.211279)
		(end 139.894818 -55.6006)
		(width 0.0889)
		(layer "In9.Cu")
		(net "UPI_CPU1_CPU0_P1P1_DP<2>")
	)
	(arc
		(start 292.304216 -60.454286)
		(mid 292.283037 -60.4516)
		(end 292.262052 -60.447682)
		(width 0.0889)
		(layer "In9.Cu")
		(net "UPI_CPU1_CPU0_P1P1_DP<2>")
	)
	(arc
		(start 291.85743 -60.16244)
		(mid 291.715439 -60.018348)
		(end 291.521134 -59.962034)
		(width 0.0889)
		(layer "In9.Cu")
		(net "UPI_CPU1_CPU0_P1P1_DP<2>")
	)
	(arc
		(start 288.13887 -56.104536)
		(mid 288.19234 -55.909473)
		(end 288.143696 -55.713122)
		(width 0.0889)
		(layer "In9.Cu")
		(net "UPI_CPU1_CPU0_P1P1_DP<2>")
	)
	(arc
		(start 288.13252 -55.693818)
		(mid 288.059722 -55.403055)
		(end 288.13887 -55.113936)
		(width 0.0889)
		(layer "In9.Cu")
		(net "UPI_CPU1_CPU0_P1P1_DP<2>")
	)
	(arc
		(start 288.65068 -57.982104)
		(mid 288.138998 -57.686277)
		(end 288.13887 -57.095136)
		(width 0.0889)
		(layer "In9.Cu")
		(net "UPI_CPU1_CPU0_P1P1_DP<2>")
	)
	(segment
		(start 290.93922 -60.362338)
		(end 291.51072 -60.362338)
		(width 0.1143)
		(layer "F.Cu")
		(net "UPI_CPU1_CPU0_P1P1_DP<1>")
	)
	(segment
		(start 139.674854 -56.399938)
		(end 140.246354 -56.399938)
		(width 0.1143)
		(layer "F.Cu")
		(net "UPI_CPU1_CPU0_P1P1_DP<1>")
	)
	(via
		(at 140.246354 -56.399938)
		(size 0.508)
		(drill 0.254)
		(layers "F.Cu" "B.Cu")
		(net "UPI_CPU1_CPU0_P1P1_DP<1>")
	)
	(via
		(at 291.51072 -60.362338)
		(size 0.508)
		(drill 0.254)
		(layers "F.Cu" "B.Cu")
		(net "UPI_CPU1_CPU0_P1P1_DP<1>")
	)
	(segment
		(start 193.459354 -45.369988)
		(end 191.468756 -46.088808)
		(width 0.1143)
		(layer "In9.Cu")
		(net "UPI_CPU1_CPU0_P1P1_DP<1>")
	)
	(segment
		(start 144.258284 -54.428136)
		(end 143.858742 -54.590696)
		(width 0.1143)
		(layer "In9.Cu")
		(net "UPI_CPU1_CPU0_P1P1_DP<1>")
	)
	(segment
		(start 147.520914 -52.425854)
		(end 145.6182 -53.593746)
		(width 0.1143)
		(layer "In9.Cu")
		(net "UPI_CPU1_CPU0_P1P1_DP<1>")
	)
	(segment
		(start 145.6182 -53.593746)
		(end 145.6182 -53.593492)
		(width 0.1143)
		(layer "In9.Cu")
		(net "UPI_CPU1_CPU0_P1P1_DP<1>")
	)
	(segment
		(start 199.34555 -43.033442)
		(end 193.459354 -45.369988)
		(width 0.1143)
		(layer "In9.Cu")
		(net "UPI_CPU1_CPU0_P1P1_DP<1>")
	)
	(segment
		(start 145.6182 -53.593492)
		(end 144.258284 -54.428136)
		(width 0.1143)
		(layer "In9.Cu")
		(net "UPI_CPU1_CPU0_P1P1_DP<1>")
	)
	(segment
		(start 291.51072 -60.362338)
		(end 291.056314 -60.362338)
		(width 0.0889)
		(layer "In9.Cu")
		(net "UPI_CPU1_CPU0_P1P1_DP<1>")
	)
	(segment
		(start 142.131288 -55.809388)
		(end 141.952218 -55.809388)
		(width 0.0889)
		(layer "In9.Cu")
		(net "UPI_CPU1_CPU0_P1P1_DP<1>")
	)
	(segment
		(start 287.440624 -57.694322)
		(end 287.44545 -57.685686)
		(width 0.0889)
		(layer "In9.Cu")
		(net "UPI_CPU1_CPU0_P1P1_DP<1>")
	)
	(segment
		(start 287.540954 -53.558186)
		(end 287.542224 -53.556916)
		(width 0.0889)
		(layer "In9.Cu")
		(net "UPI_CPU1_CPU0_P1P1_DP<1>")
	)
	(segment
		(start 264.837926 -46.01845)
		(end 262.2423 -46.721776)
		(width 0.1143)
		(layer "In9.Cu")
		(net "UPI_CPU1_CPU0_P1P1_DP<1>")
	)
	(segment
		(start 285.962852 -52.241704)
		(end 285.494222 -52.241704)
		(width 0.0889)
		(layer "In9.Cu")
		(net "UPI_CPU1_CPU0_P1P1_DP<1>")
	)
	(segment
		(start 181.90083 -45.849794)
		(end 169.43959 -50.08626)
		(width 0.1143)
		(layer "In9.Cu")
		(net "UPI_CPU1_CPU0_P1P1_DP<1>")
	)
	(segment
		(start 143.820896 -54.660546)
		(end 142.584424 -55.163212)
		(width 0.0889)
		(layer "In9.Cu")
		(net "UPI_CPU1_CPU0_P1P1_DP<1>")
	)
	(segment
		(start 143.858742 -54.590696)
		(end 143.820896 -54.660546)
		(width 0.0889)
		(layer "In9.Cu")
		(net "UPI_CPU1_CPU0_P1P1_DP<1>")
	)
	(segment
		(start 169.43959 -50.08626)
		(end 164.907976 -51.077622)
		(width 0.1143)
		(layer "In9.Cu")
		(net "UPI_CPU1_CPU0_P1P1_DP<1>")
	)
	(segment
		(start 287.44545 -54.713886)
		(end 287.4518 -54.703218)
		(width 0.0889)
		(layer "In9.Cu")
		(net "UPI_CPU1_CPU0_P1P1_DP<1>")
	)
	(segment
		(start 236.269784 -44.06392)
		(end 222.396812 -45.260006)
		(width 0.1143)
		(layer "In9.Cu")
		(net "UPI_CPU1_CPU0_P1P1_DP<1>")
	)
	(segment
		(start 287.44545 -57.685686)
		(end 287.4518 -57.675018)
		(width 0.0889)
		(layer "In9.Cu")
		(net "UPI_CPU1_CPU0_P1P1_DP<1>")
	)
	(segment
		(start 287.805114 -58.285634)
		(end 287.777174 -58.285634)
		(width 0.0889)
		(layer "In9.Cu")
		(net "UPI_CPU1_CPU0_P1P1_DP<1>")
	)
	(segment
		(start 285.494222 -52.241704)
		(end 285.443422 -52.190904)
		(width 0.0889)
		(layer "In9.Cu")
		(net "UPI_CPU1_CPU0_P1P1_DP<1>")
	)
	(segment
		(start 151.647398 -49.37379)
		(end 147.520914 -52.425854)
		(width 0.1143)
		(layer "In9.Cu")
		(net "UPI_CPU1_CPU0_P1P1_DP<1>")
	)
	(segment
		(start 290.665916 -60.266834)
		(end 290.425124 -60.266834)
		(width 0.0889)
		(layer "In9.Cu")
		(net "UPI_CPU1_CPU0_P1P1_DP<1>")
	)
	(segment
		(start 211.546186 -46.195488)
		(end 199.34555 -43.033442)
		(width 0.1143)
		(layer "In9.Cu")
		(net "UPI_CPU1_CPU0_P1P1_DP<1>")
	)
	(segment
		(start 285.421324 -52.190904)
		(end 284.343094 -52.190904)
		(width 0.1143)
		(layer "In9.Cu")
		(net "UPI_CPU1_CPU0_P1P1_DP<1>")
	)
	(segment
		(start 284.343094 -52.190904)
		(end 283.56179 -51.4096)
		(width 0.1143)
		(layer "In9.Cu")
		(net "UPI_CPU1_CPU0_P1P1_DP<1>")
	)
	(segment
		(start 222.396812 -45.260006)
		(end 211.546186 -46.195488)
		(width 0.1143)
		(layer "In9.Cu")
		(net "UPI_CPU1_CPU0_P1P1_DP<1>")
	)
	(segment
		(start 287.260792 -52.836572)
		(end 286.55772 -52.836572)
		(width 0.0889)
		(layer "In9.Cu")
		(net "UPI_CPU1_CPU0_P1P1_DP<1>")
	)
	(segment
		(start 287.44545 -56.695086)
		(end 287.4518 -56.684418)
		(width 0.0889)
		(layer "In9.Cu")
		(net "UPI_CPU1_CPU0_P1P1_DP<1>")
	)
	(segment
		(start 279.024588 -49.70272)
		(end 264.837926 -46.01845)
		(width 0.1143)
		(layer "In9.Cu")
		(net "UPI_CPU1_CPU0_P1P1_DP<1>")
	)
	(segment
		(start 286.55772 -52.836572)
		(end 285.962852 -52.241704)
		(width 0.0889)
		(layer "In9.Cu")
		(net "UPI_CPU1_CPU0_P1P1_DP<1>")
	)
	(segment
		(start 287.440624 -53.731922)
		(end 287.540954 -53.558186)
		(width 0.0889)
		(layer "In9.Cu")
		(net "UPI_CPU1_CPU0_P1P1_DP<1>")
	)
	(segment
		(start 164.907976 -51.077622)
		(end 160.111186 -50.169064)
		(width 0.1143)
		(layer "In9.Cu")
		(net "UPI_CPU1_CPU0_P1P1_DP<1>")
	)
	(segment
		(start 239.551464 -45.806106)
		(end 236.269784 -44.06392)
		(width 0.1143)
		(layer "In9.Cu")
		(net "UPI_CPU1_CPU0_P1P1_DP<1>")
	)
	(segment
		(start 160.111186 -50.169064)
		(end 155.904184 -48.428402)
		(width 0.1143)
		(layer "In9.Cu")
		(net "UPI_CPU1_CPU0_P1P1_DP<1>")
	)
	(segment
		(start 287.440624 -54.722522)
		(end 287.44545 -54.713886)
		(width 0.0889)
		(layer "In9.Cu")
		(net "UPI_CPU1_CPU0_P1P1_DP<1>")
	)
	(segment
		(start 184.312814 -46.025816)
		(end 181.90083 -45.849794)
		(width 0.1143)
		(layer "In9.Cu")
		(net "UPI_CPU1_CPU0_P1P1_DP<1>")
	)
	(segment
		(start 287.440624 -56.703722)
		(end 287.44545 -56.695086)
		(width 0.0889)
		(layer "In9.Cu")
		(net "UPI_CPU1_CPU0_P1P1_DP<1>")
	)
	(segment
		(start 140.522198 -55.805324)
		(end 140.246354 -56.399938)
		(width 0.0889)
		(layer "In9.Cu")
		(net "UPI_CPU1_CPU0_P1P1_DP<1>")
	)
	(segment
		(start 262.2423 -46.721776)
		(end 256.358136 -46.21276)
		(width 0.1143)
		(layer "In9.Cu")
		(net "UPI_CPU1_CPU0_P1P1_DP<1>")
	)
	(segment
		(start 287.542224 -53.118004)
		(end 287.260792 -52.836572)
		(width 0.0889)
		(layer "In9.Cu")
		(net "UPI_CPU1_CPU0_P1P1_DP<1>")
	)
	(segment
		(start 288.940494 -58.782204)
		(end 288.652204 -58.782204)
		(width 0.0889)
		(layer "In9.Cu")
		(net "UPI_CPU1_CPU0_P1P1_DP<1>")
	)
	(segment
		(start 287.542224 -53.556916)
		(end 287.542224 -53.118004)
		(width 0.0889)
		(layer "In9.Cu")
		(net "UPI_CPU1_CPU0_P1P1_DP<1>")
	)
	(segment
		(start 247.88368 -47.517304)
		(end 239.551464 -45.806106)
		(width 0.1143)
		(layer "In9.Cu")
		(net "UPI_CPU1_CPU0_P1P1_DP<1>")
	)
	(segment
		(start 191.468756 -46.088808)
		(end 184.312814 -46.025816)
		(width 0.1143)
		(layer "In9.Cu")
		(net "UPI_CPU1_CPU0_P1P1_DP<1>")
	)
	(segment
		(start 142.584424 -55.163212)
		(end 142.34668 -55.612538)
		(width 0.0889)
		(layer "In9.Cu")
		(net "UPI_CPU1_CPU0_P1P1_DP<1>")
	)
	(segment
		(start 287.44545 -55.704486)
		(end 287.4518 -55.693818)
		(width 0.0889)
		(layer "In9.Cu")
		(net "UPI_CPU1_CPU0_P1P1_DP<1>")
	)
	(segment
		(start 290.425124 -60.266834)
		(end 288.940494 -58.782204)
		(width 0.0889)
		(layer "In9.Cu")
		(net "UPI_CPU1_CPU0_P1P1_DP<1>")
	)
	(segment
		(start 287.440624 -55.713122)
		(end 287.44545 -55.704486)
		(width 0.0889)
		(layer "In9.Cu")
		(net "UPI_CPU1_CPU0_P1P1_DP<1>")
	)
	(segment
		(start 281.033474 -51.4096)
		(end 279.024588 -49.70272)
		(width 0.1143)
		(layer "In9.Cu")
		(net "UPI_CPU1_CPU0_P1P1_DP<1>")
	)
	(segment
		(start 283.56179 -51.4096)
		(end 281.033474 -51.4096)
		(width 0.1143)
		(layer "In9.Cu")
		(net "UPI_CPU1_CPU0_P1P1_DP<1>")
	)
	(segment
		(start 285.443422 -52.190904)
		(end 285.421324 -52.190904)
		(width 0.0889)
		(layer "In9.Cu")
		(net "UPI_CPU1_CPU0_P1P1_DP<1>")
	)
	(segment
		(start 256.358136 -46.21276)
		(end 247.88368 -47.517304)
		(width 0.1143)
		(layer "In9.Cu")
		(net "UPI_CPU1_CPU0_P1P1_DP<1>")
	)
	(segment
		(start 155.904184 -48.428402)
		(end 151.647398 -49.37379)
		(width 0.1143)
		(layer "In9.Cu")
		(net "UPI_CPU1_CPU0_P1P1_DP<1>")
	)
	(arc
		(start 287.4518 -55.693818)
		(mid 287.524598 -55.403055)
		(end 287.44545 -55.113936)
		(width 0.0889)
		(layer "In9.Cu")
		(net "UPI_CPU1_CPU0_P1P1_DP<1>")
	)
	(arc
		(start 141.616684 -55.609236)
		(mid 141.104811 -55.313442)
		(end 140.59281 -55.609236)
		(width 0.0889)
		(layer "In9.Cu")
		(net "UPI_CPU1_CPU0_P1P1_DP<1>")
	)
	(arc
		(start 291.056314 -60.362338)
		(mid 290.984657 -60.353982)
		(end 290.916868 -60.329318)
		(width 0.0889)
		(layer "In9.Cu")
		(net "UPI_CPU1_CPU0_P1P1_DP<1>")
	)
	(arc
		(start 287.777174 -58.285634)
		(mid 287.444256 -58.083643)
		(end 287.440624 -57.694322)
		(width 0.0889)
		(layer "In9.Cu")
		(net "UPI_CPU1_CPU0_P1P1_DP<1>")
	)
	(arc
		(start 287.4518 -56.684418)
		(mid 287.524598 -56.393655)
		(end 287.44545 -56.104536)
		(width 0.0889)
		(layer "In9.Cu")
		(net "UPI_CPU1_CPU0_P1P1_DP<1>")
	)
	(arc
		(start 142.34668 -55.612538)
		(mid 142.256021 -55.7296)
		(end 142.131288 -55.809388)
		(width 0.0889)
		(layer "In9.Cu")
		(net "UPI_CPU1_CPU0_P1P1_DP<1>")
	)
	(arc
		(start 288.30397 -58.581036)
		(mid 288.093257 -58.367957)
		(end 287.805114 -58.285634)
		(width 0.0889)
		(layer "In9.Cu")
		(net "UPI_CPU1_CPU0_P1P1_DP<1>")
	)
	(arc
		(start 287.44545 -57.095136)
		(mid 287.39198 -56.900073)
		(end 287.440624 -56.703722)
		(width 0.0889)
		(layer "In9.Cu")
		(net "UPI_CPU1_CPU0_P1P1_DP<1>")
	)
	(arc
		(start 287.44545 -56.104536)
		(mid 287.39198 -55.909473)
		(end 287.440624 -55.713122)
		(width 0.0889)
		(layer "In9.Cu")
		(net "UPI_CPU1_CPU0_P1P1_DP<1>")
	)
	(arc
		(start 287.44545 -54.123336)
		(mid 287.39198 -53.928273)
		(end 287.440624 -53.731922)
		(width 0.0889)
		(layer "In9.Cu")
		(net "UPI_CPU1_CPU0_P1P1_DP<1>")
	)
	(arc
		(start 287.4518 -57.675018)
		(mid 287.524598 -57.384255)
		(end 287.44545 -57.095136)
		(width 0.0889)
		(layer "In9.Cu")
		(net "UPI_CPU1_CPU0_P1P1_DP<1>")
	)
	(arc
		(start 140.59281 -55.609236)
		(mid 140.548775 -55.704138)
		(end 140.522198 -55.805324)
		(width 0.0889)
		(layer "In9.Cu")
		(net "UPI_CPU1_CPU0_P1P1_DP<1>")
	)
	(arc
		(start 287.4518 -54.703218)
		(mid 287.524598 -54.412455)
		(end 287.44545 -54.123336)
		(width 0.0889)
		(layer "In9.Cu")
		(net "UPI_CPU1_CPU0_P1P1_DP<1>")
	)
	(arc
		(start 290.916868 -60.329318)
		(mid 290.794852 -60.284188)
		(end 290.665916 -60.266834)
		(width 0.0889)
		(layer "In9.Cu")
		(net "UPI_CPU1_CPU0_P1P1_DP<1>")
	)
	(arc
		(start 288.652204 -58.782204)
		(mid 288.451143 -58.728284)
		(end 288.30397 -58.581036)
		(width 0.0889)
		(layer "In9.Cu")
		(net "UPI_CPU1_CPU0_P1P1_DP<1>")
	)
	(arc
		(start 287.44545 -55.113936)
		(mid 287.39198 -54.918873)
		(end 287.440624 -54.722522)
		(width 0.0889)
		(layer "In9.Cu")
		(net "UPI_CPU1_CPU0_P1P1_DP<1>")
	)
	(arc
		(start 141.952218 -55.809388)
		(mid 141.758368 -55.753038)
		(end 141.616684 -55.609236)
		(width 0.0889)
		(layer "In9.Cu")
		(net "UPI_CPU1_CPU0_P1P1_DP<1>")
	)
	(segment
		(start 303.529746 -58.381138)
		(end 302.958246 -58.381138)
		(width 0.1143)
		(layer "F.Cu")
		(net "UPI_CPU1_CPU0_P1P1_DP<19>")
	)
	(segment
		(start 125.080268 -54.913784)
		(end 125.651768 -54.913784)
		(width 0.1143)
		(layer "F.Cu")
		(net "UPI_CPU1_CPU0_P1P1_DP<19>")
	)
	(via
		(at 303.529746 -58.381138)
		(size 0.508)
		(drill 0.254)
		(layers "F.Cu" "B.Cu")
		(net "UPI_CPU1_CPU0_P1P1_DP<19>")
	)
	(via
		(at 125.651768 -54.913784)
		(size 0.508)
		(drill 0.254)
		(layers "F.Cu" "B.Cu")
		(net "UPI_CPU1_CPU0_P1P1_DP<19>")
	)
	(segment
		(start 305.605434 -49.775364)
		(end 305.743102 -50.089816)
		(width 0.1143)
		(layer "In9.Cu")
		(net "UPI_CPU1_CPU0_P1P1_DP<19>")
	)
	(segment
		(start 125.273562 -55.29199)
		(end 125.143006 -55.29199)
		(width 0.1143)
		(layer "In9.Cu")
		(net "UPI_CPU1_CPU0_P1P1_DP<19>")
	)
	(segment
		(start 172.54093 -30.938216)
		(end 175.047402 -30.127702)
		(width 0.1143)
		(layer "In9.Cu")
		(net "UPI_CPU1_CPU0_P1P1_DP<19>")
	)
	(segment
		(start 294.364156 -35.844988)
		(end 297.414696 -37.887402)
		(width 0.1143)
		(layer "In9.Cu")
		(net "UPI_CPU1_CPU0_P1P1_DP<19>")
	)
	(segment
		(start 255.859788 -32.908494)
		(end 259.082032 -34.006282)
		(width 0.1143)
		(layer "In9.Cu")
		(net "UPI_CPU1_CPU0_P1P1_DP<19>")
	)
	(segment
		(start 306.318666 -55.076598)
		(end 306.318666 -55.098696)
		(width 0.0889)
		(layer "In9.Cu")
		(net "UPI_CPU1_CPU0_P1P1_DP<19>")
	)
	(segment
		(start 175.047402 -30.127448)
		(end 193.149474 -30.89402)
		(width 0.1143)
		(layer "In9.Cu")
		(net "UPI_CPU1_CPU0_P1P1_DP<19>")
	)
	(segment
		(start 251.819156 -31.23438)
		(end 255.859788 -32.908494)
		(width 0.1143)
		(layer "In9.Cu")
		(net "UPI_CPU1_CPU0_P1P1_DP<19>")
	)
	(segment
		(start 130.684016 -42.62755)
		(end 130.684016 -42.627296)
		(width 0.1143)
		(layer "In9.Cu")
		(net "UPI_CPU1_CPU0_P1P1_DP<19>")
	)
	(segment
		(start 306.14112 -50.997104)
		(end 306.342034 -51.075336)
		(width 0.1143)
		(layer "In9.Cu")
		(net "UPI_CPU1_CPU0_P1P1_DP<19>")
	)
	(segment
		(start 237.04804 -32.126936)
		(end 237.241842 -32.142684)
		(width 0.1143)
		(layer "In9.Cu")
		(net "UPI_CPU1_CPU0_P1P1_DP<19>")
	)
	(segment
		(start 303.390046 -45.345604)
		(end 303.43602 -45.39742)
		(width 0.1143)
		(layer "In9.Cu")
		(net "UPI_CPU1_CPU0_P1P1_DP<19>")
	)
	(segment
		(start 305.257962 -57.790588)
		(end 305.225196 -57.790588)
		(width 0.0889)
		(layer "In9.Cu")
		(net "UPI_CPU1_CPU0_P1P1_DP<19>")
	)
	(segment
		(start 306.116482 -56.304434)
		(end 306.087526 -56.304434)
		(width 0.0889)
		(layer "In9.Cu")
		(net "UPI_CPU1_CPU0_P1P1_DP<19>")
	)
	(segment
		(start 304.75047 -47.446184)
		(end 304.888138 -47.760128)
		(width 0.1143)
		(layer "In9.Cu")
		(net "UPI_CPU1_CPU0_P1P1_DP<19>")
	)
	(segment
		(start 305.683666 -49.574704)
		(end 305.605434 -49.775364)
		(width 0.1143)
		(layer "In9.Cu")
		(net "UPI_CPU1_CPU0_P1P1_DP<19>")
	)
	(segment
		(start 300.331886 -41.895268)
		(end 300.547278 -41.908222)
		(width 0.1143)
		(layer "In9.Cu")
		(net "UPI_CPU1_CPU0_P1P1_DP<19>")
	)
	(segment
		(start 125.651768 -54.913784)
		(end 125.273562 -55.29199)
		(width 0.1143)
		(layer "In9.Cu")
		(net "UPI_CPU1_CPU0_P1P1_DP<19>")
	)
	(segment
		(start 304.888138 -47.760128)
		(end 304.809652 -47.960788)
		(width 0.1143)
		(layer "In9.Cu")
		(net "UPI_CPU1_CPU0_P1P1_DP<19>")
	)
	(segment
		(start 306.369466 -55.149496)
		(end 306.369466 -55.561738)
		(width 0.0889)
		(layer "In9.Cu")
		(net "UPI_CPU1_CPU0_P1P1_DP<19>")
	)
	(segment
		(start 304.49012 -46.85284)
		(end 304.411888 -47.0535)
		(width 0.1143)
		(layer "In9.Cu")
		(net "UPI_CPU1_CPU0_P1P1_DP<19>")
	)
	(segment
		(start 300.104556 -41.638474)
		(end 300.331886 -41.895268)
		(width 0.1143)
		(layer "In9.Cu")
		(net "UPI_CPU1_CPU0_P1P1_DP<19>")
	)
	(segment
		(start 222.396812 -33.214564)
		(end 237.04804 -32.126936)
		(width 0.1143)
		(layer "In9.Cu")
		(net "UPI_CPU1_CPU0_P1P1_DP<19>")
	)
	(segment
		(start 303.832768 -45.615352)
		(end 304.060098 -45.871892)
		(width 0.1143)
		(layer "In9.Cu")
		(net "UPI_CPU1_CPU0_P1P1_DP<19>")
	)
	(segment
		(start 241.38509 -32.704532)
		(end 244.763036 -31.23438)
		(width 0.1143)
		(layer "In9.Cu")
		(net "UPI_CPU1_CPU0_P1P1_DP<19>")
	)
	(segment
		(start 303.17567 -44.873926)
		(end 303.403 -45.130466)
		(width 0.1143)
		(layer "In9.Cu")
		(net "UPI_CPU1_CPU0_P1P1_DP<19>")
	)
	(segment
		(start 306.081684 -50.481992)
		(end 306.003452 -50.682652)
		(width 0.1143)
		(layer "In9.Cu")
		(net "UPI_CPU1_CPU0_P1P1_DP<19>")
	)
	(segment
		(start 302.732948 -44.604178)
		(end 302.960278 -44.860972)
		(width 0.1143)
		(layer "In9.Cu")
		(net "UPI_CPU1_CPU0_P1P1_DP<19>")
	)
	(segment
		(start 300.774608 -42.164762)
		(end 300.761654 -42.3799)
		(width 0.1143)
		(layer "In9.Cu")
		(net "UPI_CPU1_CPU0_P1P1_DP<19>")
	)
	(segment
		(start 195.3641 -31.576264)
		(end 199.117458 -30.550104)
		(width 0.1143)
		(layer "In9.Cu")
		(net "UPI_CPU1_CPU0_P1P1_DP<19>")
	)
	(segment
		(start 259.082032 -34.006282)
		(end 261.509256 -34.580322)
		(width 0.1143)
		(layer "In9.Cu")
		(net "UPI_CPU1_CPU0_P1P1_DP<19>")
	)
	(segment
		(start 300.988984 -42.636694)
		(end 301.204376 -42.649648)
		(width 0.1143)
		(layer "In9.Cu")
		(net "UPI_CPU1_CPU0_P1P1_DP<19>")
	)
	(segment
		(start 302.088804 -43.647614)
		(end 302.07585 -43.862752)
		(width 0.1143)
		(layer "In9.Cu")
		(net "UPI_CPU1_CPU0_P1P1_DP<19>")
	)
	(segment
		(start 132.393436 -40.472868)
		(end 140.432536 -37.161216)
		(width 0.1143)
		(layer "In9.Cu")
		(net "UPI_CPU1_CPU0_P1P1_DP<19>")
	)
	(segment
		(start 301.646082 -43.37812)
		(end 301.861474 -43.391074)
		(width 0.1143)
		(layer "In9.Cu")
		(net "UPI_CPU1_CPU0_P1P1_DP<19>")
	)
	(segment
		(start 301.418752 -43.121326)
		(end 301.646082 -43.37812)
		(width 0.1143)
		(layer "In9.Cu")
		(net "UPI_CPU1_CPU0_P1P1_DP<19>")
	)
	(segment
		(start 304.060098 -45.871892)
		(end 304.49012 -46.85284)
		(width 0.1143)
		(layer "In9.Cu")
		(net "UPI_CPU1_CPU0_P1P1_DP<19>")
	)
	(segment
		(start 264.612374 -33.686242)
		(end 282.17622 -36.440364)
		(width 0.1143)
		(layer "In9.Cu")
		(net "UPI_CPU1_CPU0_P1P1_DP<19>")
	)
	(segment
		(start 130.684016 -42.627296)
		(end 132.393436 -40.472868)
		(width 0.1143)
		(layer "In9.Cu")
		(net "UPI_CPU1_CPU0_P1P1_DP<19>")
	)
	(segment
		(start 282.554172 -36.381944)
		(end 290.07054 -34.987738)
		(width 0.1143)
		(layer "In9.Cu")
		(net "UPI_CPU1_CPU0_P1P1_DP<19>")
	)
	(segment
		(start 304.403252 -58.285634)
		(end 304.375312 -58.285634)
		(width 0.0889)
		(layer "In9.Cu")
		(net "UPI_CPU1_CPU0_P1P1_DP<19>")
	)
	(segment
		(start 301.431706 -42.906188)
		(end 301.418752 -43.121326)
		(width 0.1143)
		(layer "In9.Cu")
		(net "UPI_CPU1_CPU0_P1P1_DP<19>")
	)
	(segment
		(start 175.047402 -30.127702)
		(end 175.047402 -30.127448)
		(width 0.1143)
		(layer "In9.Cu")
		(net "UPI_CPU1_CPU0_P1P1_DP<19>")
	)
	(segment
		(start 305.944016 -50.168048)
		(end 306.081684 -50.481992)
		(width 0.1143)
		(layer "In9.Cu")
		(net "UPI_CPU1_CPU0_P1P1_DP<19>")
	)
	(segment
		(start 302.07585 -43.862752)
		(end 302.30318 -44.119546)
		(width 0.1143)
		(layer "In9.Cu")
		(net "UPI_CPU1_CPU0_P1P1_DP<19>")
	)
	(segment
		(start 306.538884 -51.904392)
		(end 306.740052 -51.982878)
		(width 0.1143)
		(layer "In9.Cu")
		(net "UPI_CPU1_CPU0_P1P1_DP<19>")
	)
	(segment
		(start 124.986796 -54.250336)
		(end 125.973078 -50.506376)
		(width 0.1143)
		(layer "In9.Cu")
		(net "UPI_CPU1_CPU0_P1P1_DP<19>")
	)
	(segment
		(start 125.143006 -55.29199)
		(end 124.986796 -55.13578)
		(width 0.1143)
		(layer "In9.Cu")
		(net "UPI_CPU1_CPU0_P1P1_DP<19>")
	)
	(segment
		(start 304.411888 -47.0535)
		(end 304.549556 -47.367952)
		(width 0.1143)
		(layer "In9.Cu")
		(net "UPI_CPU1_CPU0_P1P1_DP<19>")
	)
	(segment
		(start 302.960278 -44.860972)
		(end 303.17567 -44.873926)
		(width 0.1143)
		(layer "In9.Cu")
		(net "UPI_CPU1_CPU0_P1P1_DP<19>")
	)
	(segment
		(start 125.973078 -47.338234)
		(end 130.684016 -42.62755)
		(width 0.1143)
		(layer "In9.Cu")
		(net "UPI_CPU1_CPU0_P1P1_DP<19>")
	)
	(segment
		(start 303.617376 -45.602398)
		(end 303.832768 -45.615352)
		(width 0.1143)
		(layer "In9.Cu")
		(net "UPI_CPU1_CPU0_P1P1_DP<19>")
	)
	(segment
		(start 305.743102 -50.089816)
		(end 305.944016 -50.168048)
		(width 0.1143)
		(layer "In9.Cu")
		(net "UPI_CPU1_CPU0_P1P1_DP<19>")
	)
	(segment
		(start 304.94732 -48.274986)
		(end 305.148234 -48.353472)
		(width 0.1143)
		(layer "In9.Cu")
		(net "UPI_CPU1_CPU0_P1P1_DP<19>")
	)
	(segment
		(start 125.973078 -50.506376)
		(end 125.973078 -47.338234)
		(width 0.1143)
		(layer "In9.Cu")
		(net "UPI_CPU1_CPU0_P1P1_DP<19>")
	)
	(segment
		(start 244.763036 -31.23438)
		(end 251.819156 -31.23438)
		(width 0.1143)
		(layer "In9.Cu")
		(net "UPI_CPU1_CPU0_P1P1_DP<19>")
	)
	(segment
		(start 306.740052 -51.982878)
		(end 306.893722 -52.333398)
		(width 0.1143)
		(layer "In9.Cu")
		(net "UPI_CPU1_CPU0_P1P1_DP<19>")
	)
	(segment
		(start 303.91227 -58.525918)
		(end 303.822862 -58.550048)
		(width 0.0889)
		(layer "In9.Cu")
		(net "UPI_CPU1_CPU0_P1P1_DP<19>")
	)
	(segment
		(start 304.809652 -47.960788)
		(end 304.94732 -48.274986)
		(width 0.1143)
		(layer "In9.Cu")
		(net "UPI_CPU1_CPU0_P1P1_DP<19>")
	)
	(segment
		(start 199.117458 -30.550104)
		(end 212.297772 -33.964118)
		(width 0.1143)
		(layer "In9.Cu")
		(net "UPI_CPU1_CPU0_P1P1_DP<19>")
	)
	(segment
		(start 306.342034 -51.075336)
		(end 306.479702 -51.38928)
		(width 0.1143)
		(layer "In9.Cu")
		(net "UPI_CPU1_CPU0_P1P1_DP<19>")
	)
	(segment
		(start 140.432536 -37.161216)
		(end 146.768566 -37.461444)
		(width 0.1143)
		(layer "In9.Cu")
		(net "UPI_CPU1_CPU0_P1P1_DP<19>")
	)
	(segment
		(start 306.479702 -51.38928)
		(end 306.401216 -51.590194)
		(width 0.1143)
		(layer "In9.Cu")
		(net "UPI_CPU1_CPU0_P1P1_DP<19>")
	)
	(segment
		(start 302.30318 -44.119546)
		(end 302.518572 -44.1325)
		(width 0.1143)
		(layer "In9.Cu")
		(net "UPI_CPU1_CPU0_P1P1_DP<19>")
	)
	(segment
		(start 162.490658 -33.706308)
		(end 169.446956 -33.156144)
		(width 0.1143)
		(layer "In9.Cu")
		(net "UPI_CPU1_CPU0_P1P1_DP<19>")
	)
	(segment
		(start 303.403 -45.130466)
		(end 303.390046 -45.345604)
		(width 0.1143)
		(layer "In9.Cu")
		(net "UPI_CPU1_CPU0_P1P1_DP<19>")
	)
	(segment
		(start 169.446956 -33.156144)
		(end 172.54093 -30.938216)
		(width 0.1143)
		(layer "In9.Cu")
		(net "UPI_CPU1_CPU0_P1P1_DP<19>")
	)
	(segment
		(start 237.241842 -32.142684)
		(end 241.38509 -32.704532)
		(width 0.1143)
		(layer "In9.Cu")
		(net "UPI_CPU1_CPU0_P1P1_DP<19>")
	)
	(segment
		(start 303.43602 -45.39742)
		(end 303.617376 -45.602398)
		(width 0.1143)
		(layer "In9.Cu")
		(net "UPI_CPU1_CPU0_P1P1_DP<19>")
	)
	(segment
		(start 306.318666 -55.098696)
		(end 306.369466 -55.149496)
		(width 0.0889)
		(layer "In9.Cu")
		(net "UPI_CPU1_CPU0_P1P1_DP<19>")
	)
	(segment
		(start 306.369466 -55.561738)
		(end 306.452016 -55.704486)
		(width 0.0889)
		(layer "In9.Cu")
		(net "UPI_CPU1_CPU0_P1P1_DP<19>")
	)
	(segment
		(start 300.547278 -41.908222)
		(end 300.774608 -42.164762)
		(width 0.1143)
		(layer "In9.Cu")
		(net "UPI_CPU1_CPU0_P1P1_DP<19>")
	)
	(segment
		(start 303.822862 -58.550048)
		(end 303.529746 -58.381138)
		(width 0.0889)
		(layer "In9.Cu")
		(net "UPI_CPU1_CPU0_P1P1_DP<19>")
	)
	(segment
		(start 302.745902 -44.38904)
		(end 302.732948 -44.604178)
		(width 0.1143)
		(layer "In9.Cu")
		(net "UPI_CPU1_CPU0_P1P1_DP<19>")
	)
	(segment
		(start 305.285902 -48.667416)
		(end 305.207416 -48.868076)
		(width 0.1143)
		(layer "In9.Cu")
		(net "UPI_CPU1_CPU0_P1P1_DP<19>")
	)
	(segment
		(start 297.414696 -37.887402)
		(end 298.725336 -39.852346)
		(width 0.1143)
		(layer "In9.Cu")
		(net "UPI_CPU1_CPU0_P1P1_DP<19>")
	)
	(segment
		(start 298.725336 -39.852346)
		(end 300.11751 -41.423336)
		(width 0.1143)
		(layer "In9.Cu")
		(net "UPI_CPU1_CPU0_P1P1_DP<19>")
	)
	(segment
		(start 304.549556 -47.367952)
		(end 304.75047 -47.446184)
		(width 0.1143)
		(layer "In9.Cu")
		(net "UPI_CPU1_CPU0_P1P1_DP<19>")
	)
	(segment
		(start 124.986796 -55.13578)
		(end 124.986796 -54.250336)
		(width 0.1143)
		(layer "In9.Cu")
		(net "UPI_CPU1_CPU0_P1P1_DP<19>")
	)
	(segment
		(start 290.07054 -34.987738)
		(end 294.364156 -35.844988)
		(width 0.1143)
		(layer "In9.Cu")
		(net "UPI_CPU1_CPU0_P1P1_DP<19>")
	)
	(segment
		(start 305.345084 -49.182274)
		(end 305.545998 -49.26076)
		(width 0.1143)
		(layer "In9.Cu")
		(net "UPI_CPU1_CPU0_P1P1_DP<19>")
	)
	(segment
		(start 146.768566 -37.461444)
		(end 162.490658 -33.706308)
		(width 0.1143)
		(layer "In9.Cu")
		(net "UPI_CPU1_CPU0_P1P1_DP<19>")
	)
	(segment
		(start 282.17622 -36.440364)
		(end 282.554172 -36.381944)
		(width 0.1143)
		(layer "In9.Cu")
		(net "UPI_CPU1_CPU0_P1P1_DP<19>")
	)
	(segment
		(start 306.003452 -50.682652)
		(end 306.14112 -50.997104)
		(width 0.1143)
		(layer "In9.Cu")
		(net "UPI_CPU1_CPU0_P1P1_DP<19>")
	)
	(segment
		(start 301.204376 -42.649648)
		(end 301.431706 -42.906188)
		(width 0.1143)
		(layer "In9.Cu")
		(net "UPI_CPU1_CPU0_P1P1_DP<19>")
	)
	(segment
		(start 261.509256 -34.580322)
		(end 264.612374 -33.686242)
		(width 0.1143)
		(layer "In9.Cu")
		(net "UPI_CPU1_CPU0_P1P1_DP<19>")
	)
	(segment
		(start 193.149474 -30.89402)
		(end 195.3641 -31.576264)
		(width 0.1143)
		(layer "In9.Cu")
		(net "UPI_CPU1_CPU0_P1P1_DP<19>")
	)
	(segment
		(start 300.11751 -41.423336)
		(end 300.104556 -41.638474)
		(width 0.1143)
		(layer "In9.Cu")
		(net "UPI_CPU1_CPU0_P1P1_DP<19>")
	)
	(segment
		(start 306.893722 -52.333398)
		(end 306.318666 -54.699408)
		(width 0.1143)
		(layer "In9.Cu")
		(net "UPI_CPU1_CPU0_P1P1_DP<19>")
	)
	(segment
		(start 212.297772 -33.964118)
		(end 222.396812 -33.214564)
		(width 0.1143)
		(layer "In9.Cu")
		(net "UPI_CPU1_CPU0_P1P1_DP<19>")
	)
	(segment
		(start 306.401216 -51.590194)
		(end 306.538884 -51.904392)
		(width 0.1143)
		(layer "In9.Cu")
		(net "UPI_CPU1_CPU0_P1P1_DP<19>")
	)
	(segment
		(start 305.545998 -49.26076)
		(end 305.683666 -49.574704)
		(width 0.1143)
		(layer "In9.Cu")
		(net "UPI_CPU1_CPU0_P1P1_DP<19>")
	)
	(segment
		(start 300.761654 -42.3799)
		(end 300.988984 -42.636694)
		(width 0.1143)
		(layer "In9.Cu")
		(net "UPI_CPU1_CPU0_P1P1_DP<19>")
	)
	(segment
		(start 301.861474 -43.391074)
		(end 302.088804 -43.647614)
		(width 0.1143)
		(layer "In9.Cu")
		(net "UPI_CPU1_CPU0_P1P1_DP<19>")
	)
	(segment
		(start 302.518572 -44.1325)
		(end 302.745902 -44.38904)
		(width 0.1143)
		(layer "In9.Cu")
		(net "UPI_CPU1_CPU0_P1P1_DP<19>")
	)
	(segment
		(start 306.318666 -54.699408)
		(end 306.318666 -55.076598)
		(width 0.1143)
		(layer "In9.Cu")
		(net "UPI_CPU1_CPU0_P1P1_DP<19>")
	)
	(segment
		(start 305.207416 -48.868076)
		(end 305.345084 -49.182274)
		(width 0.1143)
		(layer "In9.Cu")
		(net "UPI_CPU1_CPU0_P1P1_DP<19>")
	)
	(segment
		(start 305.148234 -48.353472)
		(end 305.285902 -48.667416)
		(width 0.1143)
		(layer "In9.Cu")
		(net "UPI_CPU1_CPU0_P1P1_DP<19>")
	)
	(arc
		(start 304.734976 -58.085736)
		(mid 304.594897 -58.228472)
		(end 304.403252 -58.285634)
		(width 0.0889)
		(layer "In9.Cu")
		(net "UPI_CPU1_CPU0_P1P1_DP<19>")
	)
	(arc
		(start 304.375312 -58.285634)
		(mid 304.115836 -58.351909)
		(end 303.91227 -58.525918)
		(width 0.0889)
		(layer "In9.Cu")
		(net "UPI_CPU1_CPU0_P1P1_DP<19>")
	)
	(arc
		(start 305.593496 -57.190386)
		(mid 305.596244 -57.585853)
		(end 305.257962 -57.790588)
		(width 0.0889)
		(layer "In9.Cu")
		(net "UPI_CPU1_CPU0_P1P1_DP<19>")
	)
	(arc
		(start 306.452016 -55.704486)
		(mid 306.454599 -56.099733)
		(end 306.116482 -56.304434)
		(width 0.0889)
		(layer "In9.Cu")
		(net "UPI_CPU1_CPU0_P1P1_DP<19>")
	)
	(arc
		(start 306.087526 -56.304434)
		(mid 305.589275 -56.607274)
		(end 305.593496 -57.190386)
		(width 0.0889)
		(layer "In9.Cu")
		(net "UPI_CPU1_CPU0_P1P1_DP<19>")
	)
	(arc
		(start 305.225196 -57.790588)
		(mid 304.941979 -57.874869)
		(end 304.734976 -58.085736)
		(width 0.0889)
		(layer "In9.Cu")
		(net "UPI_CPU1_CPU0_P1P1_DP<19>")
	)
	(segment
		(start 125.080268 -53.923184)
		(end 125.651768 -53.923184)
		(width 0.1143)
		(layer "F.Cu")
		(net "UPI_CPU1_CPU0_P1P1_DP<18>")
	)
	(segment
		(start 302.099726 -58.876438)
		(end 302.671226 -58.876438)
		(width 0.1143)
		(layer "F.Cu")
		(net "UPI_CPU1_CPU0_P1P1_DP<18>")
	)
	(via
		(at 125.651768 -53.923184)
		(size 0.508)
		(drill 0.254)
		(layers "F.Cu" "B.Cu")
		(net "UPI_CPU1_CPU0_P1P1_DP<18>")
	)
	(via
		(at 302.671226 -58.876438)
		(size 0.508)
		(drill 0.254)
		(layers "F.Cu" "B.Cu")
		(net "UPI_CPU1_CPU0_P1P1_DP<18>")
	)
	(segment
		(start 131.0513 -43.0403)
		(end 133.097016 -40.605202)
		(width 0.1143)
		(layer "In9.Cu")
		(net "UPI_CPU1_CPU0_P1P1_DP<18>")
	)
	(segment
		(start 304.89525 -56.5912)
		(end 304.900076 -56.599836)
		(width 0.0889)
		(layer "In9.Cu")
		(net "UPI_CPU1_CPU0_P1P1_DP<18>")
	)
	(segment
		(start 237.08487 -32.552894)
		(end 241.482626 -33.115758)
		(width 0.1143)
		(layer "In9.Cu")
		(net "UPI_CPU1_CPU0_P1P1_DP<18>")
	)
	(segment
		(start 305.264566 -55.999888)
		(end 305.2318 -55.999888)
		(width 0.0889)
		(layer "In9.Cu")
		(net "UPI_CPU1_CPU0_P1P1_DP<18>")
	)
	(segment
		(start 125.973332 -52.979574)
		(end 126.4539 -52.499006)
		(width 0.0889)
		(layer "In9.Cu")
		(net "UPI_CPU1_CPU0_P1P1_DP<18>")
	)
	(segment
		(start 125.651768 -53.923184)
		(end 125.944884 -54.092348)
		(width 0.0889)
		(layer "In9.Cu")
		(net "UPI_CPU1_CPU0_P1P1_DP<18>")
	)
	(segment
		(start 304.460148 -49.5554)
		(end 305.897788 -53.704998)
		(width 0.1143)
		(layer "In9.Cu")
		(net "UPI_CPU1_CPU0_P1P1_DP<18>")
	)
	(segment
		(start 222.396812 -33.629092)
		(end 236.876336 -32.544004)
		(width 0.1143)
		(layer "In9.Cu")
		(net "UPI_CPU1_CPU0_P1P1_DP<18>")
	)
	(segment
		(start 140.310362 -37.693092)
		(end 147.984972 -37.97681)
		(width 0.1143)
		(layer "In9.Cu")
		(net "UPI_CPU1_CPU0_P1P1_DP<18>")
	)
	(segment
		(start 305.846988 -55.546498)
		(end 305.758596 -55.704486)
		(width 0.0889)
		(layer "In9.Cu")
		(net "UPI_CPU1_CPU0_P1P1_DP<18>")
	)
	(segment
		(start 125.944884 -54.092348)
		(end 126.029212 -54.069488)
		(width 0.0889)
		(layer "In9.Cu")
		(net "UPI_CPU1_CPU0_P1P1_DP<18>")
	)
	(segment
		(start 126.4539 -52.499006)
		(end 126.4539 -52.324)
		(width 0.0889)
		(layer "In9.Cu")
		(net "UPI_CPU1_CPU0_P1P1_DP<18>")
	)
	(segment
		(start 303.547526 -57.981088)
		(end 303.51476 -57.981088)
		(width 0.0889)
		(layer "In9.Cu")
		(net "UPI_CPU1_CPU0_P1P1_DP<18>")
	)
	(segment
		(start 125.973332 -53.584602)
		(end 125.973332 -52.979574)
		(width 0.0889)
		(layer "In9.Cu")
		(net "UPI_CPU1_CPU0_P1P1_DP<18>")
	)
	(segment
		(start 259.422646 -34.567876)
		(end 261.548626 -34.976308)
		(width 0.1143)
		(layer "In9.Cu")
		(net "UPI_CPU1_CPU0_P1P1_DP<18>")
	)
	(segment
		(start 179.569618 -30.74162)
		(end 193.322194 -31.323534)
		(width 0.1143)
		(layer "In9.Cu")
		(net "UPI_CPU1_CPU0_P1P1_DP<18>")
	)
	(segment
		(start 195.391532 -32.02432)
		(end 199.252586 -31.016194)
		(width 0.1143)
		(layer "In9.Cu")
		(net "UPI_CPU1_CPU0_P1P1_DP<18>")
	)
	(segment
		(start 304.900076 -56.599836)
		(end 304.906426 -56.610504)
		(width 0.0889)
		(layer "In9.Cu")
		(net "UPI_CPU1_CPU0_P1P1_DP<18>")
	)
	(segment
		(start 303.183036 -58.180986)
		(end 303.116742 -58.295794)
		(width 0.0889)
		(layer "In9.Cu")
		(net "UPI_CPU1_CPU0_P1P1_DP<18>")
	)
	(segment
		(start 303.421796 -46.901354)
		(end 303.43602 -46.937676)
		(width 0.1143)
		(layer "In9.Cu")
		(net "UPI_CPU1_CPU0_P1P1_DP<18>")
	)
	(segment
		(start 133.097016 -40.605202)
		(end 140.310362 -37.693092)
		(width 0.1143)
		(layer "In9.Cu")
		(net "UPI_CPU1_CPU0_P1P1_DP<18>")
	)
	(segment
		(start 261.548626 -34.976308)
		(end 264.588498 -34.065972)
		(width 0.1143)
		(layer "In9.Cu")
		(net "UPI_CPU1_CPU0_P1P1_DP<18>")
	)
	(segment
		(start 251.594366 -31.57728)
		(end 257.213862 -33.905698)
		(width 0.1143)
		(layer "In9.Cu")
		(net "UPI_CPU1_CPU0_P1P1_DP<18>")
	)
	(segment
		(start 297.117008 -38.128194)
		(end 299.949108 -42.375074)
		(width 0.1143)
		(layer "In9.Cu")
		(net "UPI_CPU1_CPU0_P1P1_DP<18>")
	)
	(segment
		(start 305.897788 -54.15153)
		(end 305.846988 -54.20233)
		(width 0.0889)
		(layer "In9.Cu")
		(net "UPI_CPU1_CPU0_P1P1_DP<18>")
	)
	(segment
		(start 199.252586 -31.016194)
		(end 212.497162 -34.371026)
		(width 0.1143)
		(layer "In9.Cu")
		(net "UPI_CPU1_CPU0_P1P1_DP<18>")
	)
	(segment
		(start 172.633132 -31.392876)
		(end 175.216566 -30.557216)
		(width 0.1143)
		(layer "In9.Cu")
		(net "UPI_CPU1_CPU0_P1P1_DP<18>")
	)
	(segment
		(start 290.296854 -35.41141)
		(end 294.278558 -36.2204)
		(width 0.1143)
		(layer "In9.Cu")
		(net "UPI_CPU1_CPU0_P1P1_DP<18>")
	)
	(segment
		(start 126.4539 -52.324)
		(end 126.4031 -52.2732)
		(width 0.0889)
		(layer "In9.Cu")
		(net "UPI_CPU1_CPU0_P1P1_DP<18>")
	)
	(segment
		(start 282.15844 -36.831778)
		(end 290.296854 -35.41141)
		(width 0.1143)
		(layer "In9.Cu")
		(net "UPI_CPU1_CPU0_P1P1_DP<18>")
	)
	(segment
		(start 257.213862 -33.905698)
		(end 259.422646 -34.567876)
		(width 0.1143)
		(layer "In9.Cu")
		(net "UPI_CPU1_CPU0_P1P1_DP<18>")
	)
	(segment
		(start 294.278558 -36.2204)
		(end 297.117008 -38.128194)
		(width 0.1143)
		(layer "In9.Cu")
		(net "UPI_CPU1_CPU0_P1P1_DP<18>")
	)
	(segment
		(start 169.404792 -33.732216)
		(end 172.633132 -31.392876)
		(width 0.1143)
		(layer "In9.Cu")
		(net "UPI_CPU1_CPU0_P1P1_DP<18>")
	)
	(segment
		(start 126.4031 -52.2732)
		(end 126.4031 -47.6885)
		(width 0.1143)
		(layer "In9.Cu")
		(net "UPI_CPU1_CPU0_P1P1_DP<18>")
	)
	(segment
		(start 305.897788 -53.704998)
		(end 305.897788 -54.129432)
		(width 0.1143)
		(layer "In9.Cu")
		(net "UPI_CPU1_CPU0_P1P1_DP<18>")
	)
	(segment
		(start 244.958616 -31.57728)
		(end 251.594366 -31.57728)
		(width 0.1143)
		(layer "In9.Cu")
		(net "UPI_CPU1_CPU0_P1P1_DP<18>")
	)
	(segment
		(start 305.846988 -54.20233)
		(end 305.846988 -55.546498)
		(width 0.0889)
		(layer "In9.Cu")
		(net "UPI_CPU1_CPU0_P1P1_DP<18>")
	)
	(segment
		(start 164.437822 -34.057336)
		(end 169.404792 -33.732216)
		(width 0.1143)
		(layer "In9.Cu")
		(net "UPI_CPU1_CPU0_P1P1_DP<18>")
	)
	(segment
		(start 193.322194 -31.323534)
		(end 195.391532 -32.02432)
		(width 0.1143)
		(layer "In9.Cu")
		(net "UPI_CPU1_CPU0_P1P1_DP<18>")
	)
	(segment
		(start 305.897788 -54.129432)
		(end 305.897788 -54.15153)
		(width 0.0889)
		(layer "In9.Cu")
		(net "UPI_CPU1_CPU0_P1P1_DP<18>")
	)
	(segment
		(start 304.409856 -57.485534)
		(end 304.37709 -57.485534)
		(width 0.0889)
		(layer "In9.Cu")
		(net "UPI_CPU1_CPU0_P1P1_DP<18>")
	)
	(segment
		(start 126.029212 -54.069488)
		(end 126.105158 -53.93817)
		(width 0.0889)
		(layer "In9.Cu")
		(net "UPI_CPU1_CPU0_P1P1_DP<18>")
	)
	(segment
		(start 126.4031 -47.6885)
		(end 131.0513 -43.0403)
		(width 0.1143)
		(layer "In9.Cu")
		(net "UPI_CPU1_CPU0_P1P1_DP<18>")
	)
	(segment
		(start 236.876336 -32.544004)
		(end 237.08487 -32.552894)
		(width 0.1143)
		(layer "In9.Cu")
		(net "UPI_CPU1_CPU0_P1P1_DP<18>")
	)
	(segment
		(start 264.588498 -34.065972)
		(end 282.15844 -36.831778)
		(width 0.1143)
		(layer "In9.Cu")
		(net "UPI_CPU1_CPU0_P1P1_DP<18>")
	)
	(segment
		(start 175.216566 -30.557216)
		(end 179.569618 -30.74162)
		(width 0.1143)
		(layer "In9.Cu")
		(net "UPI_CPU1_CPU0_P1P1_DP<18>")
	)
	(segment
		(start 147.984972 -37.97681)
		(end 164.437822 -34.057336)
		(width 0.1143)
		(layer "In9.Cu")
		(net "UPI_CPU1_CPU0_P1P1_DP<18>")
	)
	(segment
		(start 299.949108 -42.375074)
		(end 303.421796 -46.901354)
		(width 0.1143)
		(layer "In9.Cu")
		(net "UPI_CPU1_CPU0_P1P1_DP<18>")
	)
	(segment
		(start 241.482626 -33.115758)
		(end 244.958616 -31.57728)
		(width 0.1143)
		(layer "In9.Cu")
		(net "UPI_CPU1_CPU0_P1P1_DP<18>")
	)
	(segment
		(start 212.497162 -34.371026)
		(end 222.396812 -33.629092)
		(width 0.1143)
		(layer "In9.Cu")
		(net "UPI_CPU1_CPU0_P1P1_DP<18>")
	)
	(segment
		(start 126.032768 -53.67655)
		(end 125.973332 -53.584602)
		(width 0.0889)
		(layer "In9.Cu")
		(net "UPI_CPU1_CPU0_P1P1_DP<18>")
	)
	(segment
		(start 303.43602 -46.937676)
		(end 304.460148 -49.5554)
		(width 0.1143)
		(layer "In9.Cu")
		(net "UPI_CPU1_CPU0_P1P1_DP<18>")
	)
	(arc
		(start 303.116742 -58.295794)
		(mid 302.913023 -58.600726)
		(end 302.671226 -58.876438)
		(width 0.0889)
		(layer "In9.Cu")
		(net "UPI_CPU1_CPU0_P1P1_DP<18>")
	)
	(arc
		(start 304.37709 -57.485534)
		(mid 304.18324 -57.541884)
		(end 304.041556 -57.685686)
		(width 0.0889)
		(layer "In9.Cu")
		(net "UPI_CPU1_CPU0_P1P1_DP<18>")
	)
	(arc
		(start 303.51476 -57.981088)
		(mid 303.323118 -58.038254)
		(end 303.183036 -58.180986)
		(width 0.0889)
		(layer "In9.Cu")
		(net "UPI_CPU1_CPU0_P1P1_DP<18>")
	)
	(arc
		(start 304.041556 -57.685686)
		(mid 303.832948 -57.897618)
		(end 303.547526 -57.981088)
		(width 0.0889)
		(layer "In9.Cu")
		(net "UPI_CPU1_CPU0_P1P1_DP<18>")
	)
	(arc
		(start 126.105158 -53.93817)
		(mid 126.088953 -53.801835)
		(end 126.032768 -53.67655)
		(width 0.0889)
		(layer "In9.Cu")
		(net "UPI_CPU1_CPU0_P1P1_DP<18>")
	)
	(arc
		(start 305.758596 -55.704486)
		(mid 305.549988 -55.916418)
		(end 305.264566 -55.999888)
		(width 0.0889)
		(layer "In9.Cu")
		(net "UPI_CPU1_CPU0_P1P1_DP<18>")
	)
	(arc
		(start 305.2318 -55.999888)
		(mid 304.898882 -56.201879)
		(end 304.89525 -56.5912)
		(width 0.0889)
		(layer "In9.Cu")
		(net "UPI_CPU1_CPU0_P1P1_DP<18>")
	)
	(arc
		(start 304.906426 -56.610504)
		(mid 304.902395 -57.186686)
		(end 304.409856 -57.485534)
		(width 0.0889)
		(layer "In9.Cu")
		(net "UPI_CPU1_CPU0_P1P1_DP<18>")
	)
	(segment
		(start 126.797308 -54.913784)
		(end 127.368808 -54.913784)
		(width 0.1143)
		(layer "F.Cu")
		(net "UPI_CPU1_CPU0_P1P1_DP<17>")
	)
	(segment
		(start 301.241206 -59.371484)
		(end 301.812706 -59.371484)
		(width 0.1143)
		(layer "F.Cu")
		(net "UPI_CPU1_CPU0_P1P1_DP<17>")
	)
	(via
		(at 301.812706 -59.371484)
		(size 0.508)
		(drill 0.254)
		(layers "F.Cu" "B.Cu")
		(net "UPI_CPU1_CPU0_P1P1_DP<17>")
	)
	(via
		(at 127.368808 -54.913784)
		(size 0.508)
		(drill 0.254)
		(layers "F.Cu" "B.Cu")
		(net "UPI_CPU1_CPU0_P1P1_DP<17>")
	)
	(segment
		(start 304.370486 -55.313834)
		(end 304.403252 -55.313834)
		(width 0.0889)
		(layer "In9.Cu")
		(net "UPI_CPU1_CPU0_P1P1_DP<17>")
	)
	(segment
		(start 300.946058 -47.060612)
		(end 301.023528 -46.855126)
		(width 0.1143)
		(layer "In9.Cu")
		(net "UPI_CPU1_CPU0_P1P1_DP<17>")
	)
	(segment
		(start 212.111082 -35.422332)
		(end 199.319642 -32.068262)
		(width 0.1143)
		(layer "In9.Cu")
		(net "UPI_CPU1_CPU0_P1P1_DP<17>")
	)
	(segment
		(start 296.29608 -38.735254)
		(end 293.83609 -37.086794)
		(width 0.1143)
		(layer "In9.Cu")
		(net "UPI_CPU1_CPU0_P1P1_DP<17>")
	)
	(segment
		(start 181.970172 -31.850838)
		(end 169.211244 -35.245294)
		(width 0.1143)
		(layer "In9.Cu")
		(net "UPI_CPU1_CPU0_P1P1_DP<17>")
	)
	(segment
		(start 300.537626 -46.157896)
		(end 300.613572 -45.95622)
		(width 0.1143)
		(layer "In9.Cu")
		(net "UPI_CPU1_CPU0_P1P1_DP<17>")
	)
	(segment
		(start 256.146808 -34.563304)
		(end 251.177552 -32.50438)
		(width 0.1143)
		(layer "In9.Cu")
		(net "UPI_CPU1_CPU0_P1P1_DP<17>")
	)
	(segment
		(start 302.159416 -59.171586)
		(end 302.153066 -59.160918)
		(width 0.0889)
		(layer "In9.Cu")
		(net "UPI_CPU1_CPU0_P1P1_DP<17>")
	)
	(segment
		(start 302.820324 -50.193956)
		(end 302.566832 -49.773078)
		(width 0.1143)
		(layer "In9.Cu")
		(net "UPI_CPU1_CPU0_P1P1_DP<17>")
	)
	(segment
		(start 163.7919 -36.176458)
		(end 162.62731 -36.423092)
		(width 0.1143)
		(layer "In9.Cu")
		(net "UPI_CPU1_CPU0_P1P1_DP<17>")
	)
	(segment
		(start 132.83819 -42.786808)
		(end 132.61594 -43.048174)
		(width 0.1143)
		(layer "In9.Cu")
		(net "UPI_CPU1_CPU0_P1P1_DP<17>")
	)
	(segment
		(start 133.480048 -42.03192)
		(end 133.257798 -42.293286)
		(width 0.1143)
		(layer "In9.Cu")
		(net "UPI_CPU1_CPU0_P1P1_DP<17>")
	)
	(segment
		(start 127.354584 -52.288186)
		(end 127.293624 -52.349146)
		(width 0.0889)
		(layer "In9.Cu")
		(net "UPI_CPU1_CPU0_P1P1_DP<17>")
	)
	(segment
		(start 304.82794 -54.952646)
		(end 304.82794 -53.885846)
		(width 0.0889)
		(layer "In9.Cu")
		(net "UPI_CPU1_CPU0_P1P1_DP<17>")
	)
	(segment
		(start 127.293624 -52.349146)
		(end 127.293624 -53.354986)
		(width 0.0889)
		(layer "In9.Cu")
		(net "UPI_CPU1_CPU0_P1P1_DP<17>")
	)
	(segment
		(start 301.497746 -47.900336)
		(end 301.291498 -47.454058)
		(width 0.1143)
		(layer "In9.Cu")
		(net "UPI_CPU1_CPU0_P1P1_DP<17>")
	)
	(segment
		(start 236.782356 -33.55213)
		(end 212.111082 -35.422332)
		(width 0.1143)
		(layer "In9.Cu")
		(net "UPI_CPU1_CPU0_P1P1_DP<17>")
	)
	(segment
		(start 299.567346 -43.643296)
		(end 299.377354 -43.358054)
		(width 0.1143)
		(layer "In9.Cu")
		(net "UPI_CPU1_CPU0_P1P1_DP<17>")
	)
	(segment
		(start 303.508156 -56.799988)
		(end 303.540922 -56.799988)
		(width 0.0889)
		(layer "In9.Cu")
		(net "UPI_CPU1_CPU0_P1P1_DP<17>")
	)
	(segment
		(start 195.228718 -33.10636)
		(end 193.007234 -32.257238)
		(width 0.1143)
		(layer "In9.Cu")
		(net "UPI_CPU1_CPU0_P1P1_DP<17>")
	)
	(segment
		(start 126.996952 -55.061612)
		(end 127.075692 -55.082948)
		(width 0.0889)
		(layer "In9.Cu")
		(net "UPI_CPU1_CPU0_P1P1_DP<17>")
	)
	(segment
		(start 193.007234 -32.257238)
		(end 181.970172 -31.850838)
		(width 0.1143)
		(layer "In9.Cu")
		(net "UPI_CPU1_CPU0_P1P1_DP<17>")
	)
	(segment
		(start 169.211244 -35.245294)
		(end 166.37635 -35.425888)
		(width 0.1143)
		(layer "In9.Cu")
		(net "UPI_CPU1_CPU0_P1P1_DP<17>")
	)
	(segment
		(start 290.178744 -36.41471)
		(end 282.085034 -37.812218)
		(width 0.1143)
		(layer "In9.Cu")
		(net "UPI_CPU1_CPU0_P1P1_DP<17>")
	)
	(segment
		(start 133.04266 -42.310812)
		(end 132.820664 -42.571924)
		(width 0.1143)
		(layer "In9.Cu")
		(net "UPI_CPU1_CPU0_P1P1_DP<17>")
	)
	(segment
		(start 301.023528 -46.855126)
		(end 300.88459 -46.54804)
		(width 0.1143)
		(layer "In9.Cu")
		(net "UPI_CPU1_CPU0_P1P1_DP<17>")
	)
	(segment
		(start 236.877606 -33.55594)
		(end 236.782356 -33.55213)
		(width 0.1143)
		(layer "In9.Cu")
		(net "UPI_CPU1_CPU0_P1P1_DP<17>")
	)
	(segment
		(start 162.62731 -36.423092)
		(end 160.763458 -37.203126)
		(width 0.1143)
		(layer "In9.Cu")
		(net "UPI_CPU1_CPU0_P1P1_DP<17>")
	)
	(segment
		(start 300.88459 -46.54804)
		(end 300.67885 -46.47057)
		(width 0.1143)
		(layer "In9.Cu")
		(net "UPI_CPU1_CPU0_P1P1_DP<17>")
	)
	(segment
		(start 241.726212 -34.15538)
		(end 236.877606 -33.55594)
		(width 0.1143)
		(layer "In9.Cu")
		(net "UPI_CPU1_CPU0_P1P1_DP<17>")
	)
	(segment
		(start 132.61594 -43.048174)
		(end 132.401056 -43.0657)
		(width 0.1143)
		(layer "In9.Cu")
		(net "UPI_CPU1_CPU0_P1P1_DP<17>")
	)
	(segment
		(start 304.734976 -55.113936)
		(end 304.82794 -54.952646)
		(width 0.0889)
		(layer "In9.Cu")
		(net "UPI_CPU1_CPU0_P1P1_DP<17>")
	)
	(segment
		(start 300.67885 -46.47057)
		(end 300.537626 -46.157896)
		(width 0.1143)
		(layer "In9.Cu")
		(net "UPI_CPU1_CPU0_P1P1_DP<17>")
	)
	(segment
		(start 134.729474 -41.100248)
		(end 133.684518 -41.555924)
		(width 0.1143)
		(layer "In9.Cu")
		(net "UPI_CPU1_CPU0_P1P1_DP<17>")
	)
	(segment
		(start 166.37635 -35.425888)
		(end 163.7919 -36.176458)
		(width 0.1143)
		(layer "In9.Cu")
		(net "UPI_CPU1_CPU0_P1P1_DP<17>")
	)
	(segment
		(start 132.401056 -43.0657)
		(end 131.9657 -43.577764)
		(width 0.1143)
		(layer "In9.Cu")
		(net "UPI_CPU1_CPU0_P1P1_DP<17>")
	)
	(segment
		(start 127.354584 -48.187102)
		(end 127.354584 -52.240688)
		(width 0.1143)
		(layer "In9.Cu")
		(net "UPI_CPU1_CPU0_P1P1_DP<17>")
	)
	(segment
		(start 282.085034 -37.812218)
		(end 264.568432 -35.053524)
		(width 0.1143)
		(layer "In9.Cu")
		(net "UPI_CPU1_CPU0_P1P1_DP<17>")
	)
	(segment
		(start 302.159416 -58.581036)
		(end 302.164242 -58.5724)
		(width 0.0889)
		(layer "In9.Cu")
		(net "UPI_CPU1_CPU0_P1P1_DP<17>")
	)
	(segment
		(start 299.377354 -43.358054)
		(end 299.165772 -43.31589)
		(width 0.1143)
		(layer "In9.Cu")
		(net "UPI_CPU1_CPU0_P1P1_DP<17>")
	)
	(segment
		(start 127.004572 -54.092856)
		(end 127.022098 -54.123336)
		(width 0.0889)
		(layer "In9.Cu")
		(net "UPI_CPU1_CPU0_P1P1_DP<17>")
	)
	(segment
		(start 299.796708 -44.150788)
		(end 299.567346 -43.643296)
		(width 0.1143)
		(layer "In9.Cu")
		(net "UPI_CPU1_CPU0_P1P1_DP<17>")
	)
	(segment
		(start 302.105822 -59.540394)
		(end 302.184562 -59.519058)
		(width 0.0889)
		(layer "In9.Cu")
		(net "UPI_CPU1_CPU0_P1P1_DP<17>")
	)
	(segment
		(start 303.668938 -51.50612)
		(end 302.900842 -50.22977)
		(width 0.0889)
		(layer "In9.Cu")
		(net "UPI_CPU1_CPU0_P1P1_DP<17>")
	)
	(segment
		(start 299.861986 -44.665138)
		(end 299.720762 -44.352464)
		(width 0.1143)
		(layer "In9.Cu")
		(net "UPI_CPU1_CPU0_P1P1_DP<17>")
	)
	(segment
		(start 127.022098 -54.713886)
		(end 127.017272 -54.722522)
		(width 0.0889)
		(layer "In9.Cu")
		(net "UPI_CPU1_CPU0_P1P1_DP<17>")
	)
	(segment
		(start 301.291498 -47.454058)
		(end 301.289212 -47.449486)
		(width 0.1143)
		(layer "In9.Cu")
		(net "UPI_CPU1_CPU0_P1P1_DP<17>")
	)
	(segment
		(start 127.354584 -52.240688)
		(end 127.354584 -52.288186)
		(width 0.0889)
		(layer "In9.Cu")
		(net "UPI_CPU1_CPU0_P1P1_DP<17>")
	)
	(segment
		(start 301.289212 -47.449486)
		(end 301.087282 -47.373286)
		(width 0.1143)
		(layer "In9.Cu")
		(net "UPI_CPU1_CPU0_P1P1_DP<17>")
	)
	(segment
		(start 301.087282 -47.373286)
		(end 300.946058 -47.060612)
		(width 0.1143)
		(layer "In9.Cu")
		(net "UPI_CPU1_CPU0_P1P1_DP<17>")
	)
	(segment
		(start 131.9657 -43.577764)
		(end 127.354584 -48.187102)
		(width 0.1143)
		(layer "In9.Cu")
		(net "UPI_CPU1_CPU0_P1P1_DP<17>")
	)
	(segment
		(start 264.568432 -35.053524)
		(end 261.639304 -35.992308)
		(width 0.1143)
		(layer "In9.Cu")
		(net "UPI_CPU1_CPU0_P1P1_DP<17>")
	)
	(segment
		(start 299.165772 -43.31589)
		(end 298.975526 -43.03014)
		(width 0.1143)
		(layer "In9.Cu")
		(net "UPI_CPU1_CPU0_P1P1_DP<17>")
	)
	(segment
		(start 300.270418 -45.567854)
		(end 300.129194 -45.25518)
		(width 0.1143)
		(layer "In9.Cu")
		(net "UPI_CPU1_CPU0_P1P1_DP<17>")
	)
	(segment
		(start 127.075692 -55.082948)
		(end 127.368808 -54.913784)
		(width 0.0889)
		(layer "In9.Cu")
		(net "UPI_CPU1_CPU0_P1P1_DP<17>")
	)
	(segment
		(start 133.684518 -41.555924)
		(end 133.462522 -41.817036)
		(width 0.1143)
		(layer "In9.Cu")
		(net "UPI_CPU1_CPU0_P1P1_DP<17>")
	)
	(segment
		(start 299.017944 -42.818812)
		(end 296.29608 -38.735254)
		(width 0.1143)
		(layer "In9.Cu")
		(net "UPI_CPU1_CPU0_P1P1_DP<17>")
	)
	(segment
		(start 302.566832 -49.773078)
		(end 301.497746 -47.900336)
		(width 0.1143)
		(layer "In9.Cu")
		(net "UPI_CPU1_CPU0_P1P1_DP<17>")
	)
	(segment
		(start 300.613572 -45.95622)
		(end 300.472348 -45.6438)
		(width 0.1143)
		(layer "In9.Cu")
		(net "UPI_CPU1_CPU0_P1P1_DP<17>")
	)
	(segment
		(start 133.462522 -41.817036)
		(end 133.480048 -42.03192)
		(width 0.1143)
		(layer "In9.Cu")
		(net "UPI_CPU1_CPU0_P1P1_DP<17>")
	)
	(segment
		(start 300.20514 -45.053504)
		(end 300.063916 -44.741084)
		(width 0.1143)
		(layer "In9.Cu")
		(net "UPI_CPU1_CPU0_P1P1_DP<17>")
	)
	(segment
		(start 298.975526 -43.03014)
		(end 299.017944 -42.818812)
		(width 0.1143)
		(layer "In9.Cu")
		(net "UPI_CPU1_CPU0_P1P1_DP<17>")
	)
	(segment
		(start 133.257798 -42.293286)
		(end 133.04266 -42.310812)
		(width 0.1143)
		(layer "In9.Cu")
		(net "UPI_CPU1_CPU0_P1P1_DP<17>")
	)
	(segment
		(start 302.653446 -57.295034)
		(end 302.686212 -57.295034)
		(width 0.0889)
		(layer "In9.Cu")
		(net "UPI_CPU1_CPU0_P1P1_DP<17>")
	)
	(segment
		(start 261.639304 -35.992308)
		(end 258.64693 -35.47364)
		(width 0.1143)
		(layer "In9.Cu")
		(net "UPI_CPU1_CPU0_P1P1_DP<17>")
	)
	(segment
		(start 127.028448 -54.703218)
		(end 127.022098 -54.713886)
		(width 0.0889)
		(layer "In9.Cu")
		(net "UPI_CPU1_CPU0_P1P1_DP<17>")
	)
	(segment
		(start 300.063916 -44.741084)
		(end 299.861986 -44.665138)
		(width 0.1143)
		(layer "In9.Cu")
		(net "UPI_CPU1_CPU0_P1P1_DP<17>")
	)
	(segment
		(start 302.8315 -50.212752)
		(end 302.820324 -50.193956)
		(width 0.0889)
		(layer "In9.Cu")
		(net "UPI_CPU1_CPU0_P1P1_DP<17>")
	)
	(segment
		(start 293.83609 -37.086794)
		(end 290.178744 -36.41471)
		(width 0.1143)
		(layer "In9.Cu")
		(net "UPI_CPU1_CPU0_P1P1_DP<17>")
	)
	(segment
		(start 300.472348 -45.6438)
		(end 300.270418 -45.567854)
		(width 0.1143)
		(layer "In9.Cu")
		(net "UPI_CPU1_CPU0_P1P1_DP<17>")
	)
	(segment
		(start 155.15082 -37.756338)
		(end 148.064728 -39.123112)
		(width 0.1143)
		(layer "In9.Cu")
		(net "UPI_CPU1_CPU0_P1P1_DP<17>")
	)
	(segment
		(start 159.935926 -37.228272)
		(end 155.15082 -37.756338)
		(width 0.1143)
		(layer "In9.Cu")
		(net "UPI_CPU1_CPU0_P1P1_DP<17>")
	)
	(segment
		(start 160.763458 -37.203126)
		(end 159.935926 -37.228272)
		(width 0.1143)
		(layer "In9.Cu")
		(net "UPI_CPU1_CPU0_P1P1_DP<17>")
	)
	(segment
		(start 127.293624 -53.354986)
		(end 127.047498 -53.681884)
		(width 0.0889)
		(layer "In9.Cu")
		(net "UPI_CPU1_CPU0_P1P1_DP<17>")
	)
	(segment
		(start 258.64693 -35.47364)
		(end 256.146808 -34.563304)
		(width 0.1143)
		(layer "In9.Cu")
		(net "UPI_CPU1_CPU0_P1P1_DP<17>")
	)
	(segment
		(start 251.177552 -32.50438)
		(end 245.28018 -32.50438)
		(width 0.1143)
		(layer "In9.Cu")
		(net "UPI_CPU1_CPU0_P1P1_DP<17>")
	)
	(segment
		(start 140.767054 -38.734492)
		(end 134.729474 -41.100248)
		(width 0.1143)
		(layer "In9.Cu")
		(net "UPI_CPU1_CPU0_P1P1_DP<17>")
	)
	(segment
		(start 299.720762 -44.352464)
		(end 299.796708 -44.150788)
		(width 0.1143)
		(layer "In9.Cu")
		(net "UPI_CPU1_CPU0_P1P1_DP<17>")
	)
	(segment
		(start 199.319642 -32.068262)
		(end 195.228718 -33.10636)
		(width 0.1143)
		(layer "In9.Cu")
		(net "UPI_CPU1_CPU0_P1P1_DP<17>")
	)
	(segment
		(start 304.82794 -53.885846)
		(end 303.668938 -51.50612)
		(width 0.0889)
		(layer "In9.Cu")
		(net "UPI_CPU1_CPU0_P1P1_DP<17>")
	)
	(segment
		(start 148.064728 -39.123112)
		(end 140.767054 -38.734492)
		(width 0.1143)
		(layer "In9.Cu")
		(net "UPI_CPU1_CPU0_P1P1_DP<17>")
	)
	(segment
		(start 302.900842 -50.22977)
		(end 302.8315 -50.212752)
		(width 0.0889)
		(layer "In9.Cu")
		(net "UPI_CPU1_CPU0_P1P1_DP<17>")
	)
	(segment
		(start 245.28018 -32.50438)
		(end 241.726212 -34.15538)
		(width 0.1143)
		(layer "In9.Cu")
		(net "UPI_CPU1_CPU0_P1P1_DP<17>")
	)
	(segment
		(start 132.820664 -42.571924)
		(end 132.83819 -42.786808)
		(width 0.1143)
		(layer "In9.Cu")
		(net "UPI_CPU1_CPU0_P1P1_DP<17>")
	)
	(segment
		(start 300.129194 -45.25518)
		(end 300.20514 -45.053504)
		(width 0.1143)
		(layer "In9.Cu")
		(net "UPI_CPU1_CPU0_P1P1_DP<17>")
	)
	(segment
		(start 301.812706 -59.371484)
		(end 302.105822 -59.540394)
		(width 0.0889)
		(layer "In9.Cu")
		(net "UPI_CPU1_CPU0_P1P1_DP<17>")
	)
	(arc
		(start 303.876456 -56.199786)
		(mid 303.872127 -55.616614)
		(end 304.370486 -55.313834)
		(width 0.0889)
		(layer "In9.Cu")
		(net "UPI_CPU1_CPU0_P1P1_DP<17>")
	)
	(arc
		(start 127.047498 -53.681884)
		(mid 126.969155 -53.881431)
		(end 127.004572 -54.092856)
		(width 0.0889)
		(layer "In9.Cu")
		(net "UPI_CPU1_CPU0_P1P1_DP<17>")
	)
	(arc
		(start 127.022098 -54.123336)
		(mid 127.10132 -54.412454)
		(end 127.028448 -54.703218)
		(width 0.0889)
		(layer "In9.Cu")
		(net "UPI_CPU1_CPU0_P1P1_DP<17>")
	)
	(arc
		(start 302.686212 -57.295034)
		(mid 302.877854 -57.237868)
		(end 303.017936 -57.095136)
		(width 0.0889)
		(layer "In9.Cu")
		(net "UPI_CPU1_CPU0_P1P1_DP<17>")
	)
	(arc
		(start 302.164242 -58.5724)
		(mid 302.212997 -58.376048)
		(end 302.159416 -58.180986)
		(width 0.0889)
		(layer "In9.Cu")
		(net "UPI_CPU1_CPU0_P1P1_DP<17>")
	)
	(arc
		(start 302.153066 -59.160918)
		(mid 302.080268 -58.870155)
		(end 302.159416 -58.581036)
		(width 0.0889)
		(layer "In9.Cu")
		(net "UPI_CPU1_CPU0_P1P1_DP<17>")
	)
	(arc
		(start 304.403252 -55.313834)
		(mid 304.594894 -55.256668)
		(end 304.734976 -55.113936)
		(width 0.0889)
		(layer "In9.Cu")
		(net "UPI_CPU1_CPU0_P1P1_DP<17>")
	)
	(arc
		(start 303.017936 -57.095136)
		(mid 303.22494 -56.884272)
		(end 303.508156 -56.799988)
		(width 0.0889)
		(layer "In9.Cu")
		(net "UPI_CPU1_CPU0_P1P1_DP<17>")
	)
	(arc
		(start 302.212756 -59.364118)
		(mid 302.198311 -59.264463)
		(end 302.159416 -59.171586)
		(width 0.0889)
		(layer "In9.Cu")
		(net "UPI_CPU1_CPU0_P1P1_DP<17>")
	)
	(arc
		(start 303.540922 -56.799988)
		(mid 303.879091 -56.59519)
		(end 303.876456 -56.199786)
		(width 0.0889)
		(layer "In9.Cu")
		(net "UPI_CPU1_CPU0_P1P1_DP<17>")
	)
	(arc
		(start 302.159416 -58.180986)
		(mid 302.155087 -57.597814)
		(end 302.653446 -57.295034)
		(width 0.0889)
		(layer "In9.Cu")
		(net "UPI_CPU1_CPU0_P1P1_DP<17>")
	)
	(arc
		(start 302.184562 -59.519058)
		(mid 302.206381 -59.442991)
		(end 302.212756 -59.364118)
		(width 0.0889)
		(layer "In9.Cu")
		(net "UPI_CPU1_CPU0_P1P1_DP<17>")
	)
	(arc
		(start 126.968758 -54.914546)
		(mid 126.975917 -54.989409)
		(end 126.996952 -55.061612)
		(width 0.0889)
		(layer "In9.Cu")
		(net "UPI_CPU1_CPU0_P1P1_DP<17>")
	)
	(arc
		(start 127.017272 -54.722522)
		(mid 126.980954 -54.815487)
		(end 126.968758 -54.914546)
		(width 0.0889)
		(layer "In9.Cu")
		(net "UPI_CPU1_CPU0_P1P1_DP<17>")
	)
	(segment
		(start 127.655828 -55.409338)
		(end 128.227328 -55.409338)
		(width 0.1143)
		(layer "F.Cu")
		(net "UPI_CPU1_CPU0_P1P1_DP<16>")
	)
	(segment
		(start 301.241206 -58.381138)
		(end 301.812706 -58.381138)
		(width 0.1143)
		(layer "F.Cu")
		(net "UPI_CPU1_CPU0_P1P1_DP<16>")
	)
	(via
		(at 301.812706 -58.381138)
		(size 0.508)
		(drill 0.254)
		(layers "F.Cu" "B.Cu")
		(net "UPI_CPU1_CPU0_P1P1_DP<16>")
	)
	(via
		(at 128.227328 -55.409338)
		(size 0.508)
		(drill 0.254)
		(layers "F.Cu" "B.Cu")
		(net "UPI_CPU1_CPU0_P1P1_DP<16>")
	)
	(segment
		(start 293.764462 -37.473382)
		(end 290.05403 -36.799774)
		(width 0.1143)
		(layer "In9.Cu")
		(net "UPI_CPU1_CPU0_P1P1_DP<16>")
	)
	(segment
		(start 258.695698 -35.990276)
		(end 250.94692 -32.84728)
		(width 0.1143)
		(layer "In9.Cu")
		(net "UPI_CPU1_CPU0_P1P1_DP<16>")
	)
	(segment
		(start 300.898306 -48.770032)
		(end 300.898306 -48.747934)
		(width 0.0889)
		(layer "In9.Cu")
		(net "UPI_CPU1_CPU0_P1P1_DP<16>")
	)
	(segment
		(start 178.761136 -33.496504)
		(end 178.668426 -33.51403)
		(width 0.1143)
		(layer "In9.Cu")
		(net "UPI_CPU1_CPU0_P1P1_DP<16>")
	)
	(segment
		(start 264.479532 -35.453066)
		(end 261.435596 -36.453064)
		(width 0.1143)
		(layer "In9.Cu")
		(net "UPI_CPU1_CPU0_P1P1_DP<16>")
	)
	(segment
		(start 155.756864 -38.092888)
		(end 148.232876 -39.530782)
		(width 0.1143)
		(layer "In9.Cu")
		(net "UPI_CPU1_CPU0_P1P1_DP<16>")
	)
	(segment
		(start 156.188664 -38.087554)
		(end 155.756864 -38.092888)
		(width 0.1143)
		(layer "In9.Cu")
		(net "UPI_CPU1_CPU0_P1P1_DP<16>")
	)
	(segment
		(start 301.51959 -58.550048)
		(end 301.44085 -58.528712)
		(width 0.0889)
		(layer "In9.Cu")
		(net "UPI_CPU1_CPU0_P1P1_DP<16>")
	)
	(segment
		(start 303.303686 -53.018944)
		(end 303.303686 -52.411376)
		(width 0.0889)
		(layer "In9.Cu")
		(net "UPI_CPU1_CPU0_P1P1_DP<16>")
	)
	(segment
		(start 199.213724 -32.49168)
		(end 195.231004 -33.56356)
		(width 0.1143)
		(layer "In9.Cu")
		(net "UPI_CPU1_CPU0_P1P1_DP<16>")
	)
	(segment
		(start 193.152014 -32.743648)
		(end 187.404248 -32.50946)
		(width 0.1143)
		(layer "In9.Cu")
		(net "UPI_CPU1_CPU0_P1P1_DP<16>")
	)
	(segment
		(start 301.472346 -57.601104)
		(end 301.465996 -57.590436)
		(width 0.0889)
		(layer "In9.Cu")
		(net "UPI_CPU1_CPU0_P1P1_DP<16>")
	)
	(segment
		(start 167.0177 -37.199824)
		(end 164.335714 -37.460682)
		(width 0.1143)
		(layer "In9.Cu")
		(net "UPI_CPU1_CPU0_P1P1_DP<16>")
	)
	(segment
		(start 300.898306 -48.275748)
		(end 298.054522 -42.042334)
		(width 0.1143)
		(layer "In9.Cu")
		(net "UPI_CPU1_CPU0_P1P1_DP<16>")
	)
	(segment
		(start 282.148788 -38.179502)
		(end 264.479532 -35.453066)
		(width 0.1143)
		(layer "In9.Cu")
		(net "UPI_CPU1_CPU0_P1P1_DP<16>")
	)
	(segment
		(start 140.755116 -39.215822)
		(end 134.8867 -41.526206)
		(width 0.1143)
		(layer "In9.Cu")
		(net "UPI_CPU1_CPU0_P1P1_DP<16>")
	)
	(segment
		(start 261.435596 -36.453064)
		(end 258.695698 -35.990276)
		(width 0.1143)
		(layer "In9.Cu")
		(net "UPI_CPU1_CPU0_P1P1_DP<16>")
	)
	(segment
		(start 164.335714 -37.460682)
		(end 159.321754 -38.283896)
		(width 0.1143)
		(layer "In9.Cu")
		(net "UPI_CPU1_CPU0_P1P1_DP<16>")
	)
	(segment
		(start 134.8867 -41.526206)
		(end 127.714248 -48.698658)
		(width 0.1143)
		(layer "In9.Cu")
		(net "UPI_CPU1_CPU0_P1P1_DP<16>")
	)
	(segment
		(start 300.847506 -48.820832)
		(end 300.898306 -48.770032)
		(width 0.0889)
		(layer "In9.Cu")
		(net "UPI_CPU1_CPU0_P1P1_DP<16>")
	)
	(segment
		(start 241.77752 -34.52622)
		(end 236.742986 -33.921446)
		(width 0.1143)
		(layer "In9.Cu")
		(net "UPI_CPU1_CPU0_P1P1_DP<16>")
	)
	(segment
		(start 301.79772 -56.990488)
		(end 301.830486 -56.990488)
		(width 0.0889)
		(layer "In9.Cu")
		(net "UPI_CPU1_CPU0_P1P1_DP<16>")
	)
	(segment
		(start 127.750062 -54.767226)
		(end 128.227328 -55.409338)
		(width 0.0889)
		(layer "In9.Cu")
		(net "UPI_CPU1_CPU0_P1P1_DP<16>")
	)
	(segment
		(start 245.515384 -32.84728)
		(end 241.77752 -34.52622)
		(width 0.1143)
		(layer "In9.Cu")
		(net "UPI_CPU1_CPU0_P1P1_DP<16>")
	)
	(segment
		(start 303.189386 -55.619904)
		(end 303.183036 -55.609236)
		(width 0.0889)
		(layer "In9.Cu")
		(net "UPI_CPU1_CPU0_P1P1_DP<16>")
	)
	(segment
		(start 159.321754 -38.283896)
		(end 156.188664 -38.087554)
		(width 0.1143)
		(layer "In9.Cu")
		(net "UPI_CPU1_CPU0_P1P1_DP<16>")
	)
	(segment
		(start 212.731858 -35.724084)
		(end 212.086952 -35.786314)
		(width 0.1143)
		(layer "In9.Cu")
		(net "UPI_CPU1_CPU0_P1P1_DP<16>")
	)
	(segment
		(start 195.231004 -33.56356)
		(end 193.152014 -32.743648)
		(width 0.1143)
		(layer "In9.Cu")
		(net "UPI_CPU1_CPU0_P1P1_DP<16>")
	)
	(segment
		(start 303.303686 -52.411376)
		(end 302.847756 -51.379882)
		(width 0.0889)
		(layer "In9.Cu")
		(net "UPI_CPU1_CPU0_P1P1_DP<16>")
	)
	(segment
		(start 303.183036 -55.609236)
		(end 303.17821 -55.6006)
		(width 0.0889)
		(layer "In9.Cu")
		(net "UPI_CPU1_CPU0_P1P1_DP<16>")
	)
	(segment
		(start 178.668426 -33.51403)
		(end 169.7736 -35.9918)
		(width 0.1143)
		(layer "In9.Cu")
		(net "UPI_CPU1_CPU0_P1P1_DP<16>")
	)
	(segment
		(start 296.012362 -38.978078)
		(end 293.764462 -37.473382)
		(width 0.1143)
		(layer "In9.Cu")
		(net "UPI_CPU1_CPU0_P1P1_DP<16>")
	)
	(segment
		(start 300.847506 -49.03724)
		(end 300.847506 -48.820832)
		(width 0.0889)
		(layer "In9.Cu")
		(net "UPI_CPU1_CPU0_P1P1_DP<16>")
	)
	(segment
		(start 222.396812 -34.998406)
		(end 212.731858 -35.724084)
		(width 0.1143)
		(layer "In9.Cu")
		(net "UPI_CPU1_CPU0_P1P1_DP<16>")
	)
	(segment
		(start 187.403994 -32.50946)
		(end 178.761136 -33.496504)
		(width 0.1143)
		(layer "In9.Cu")
		(net "UPI_CPU1_CPU0_P1P1_DP<16>")
	)
	(segment
		(start 300.898306 -48.747934)
		(end 300.898306 -48.275748)
		(width 0.1143)
		(layer "In9.Cu")
		(net "UPI_CPU1_CPU0_P1P1_DP<16>")
	)
	(segment
		(start 127.714248 -52.146454)
		(end 127.769112 -52.201318)
		(width 0.0889)
		(layer "In9.Cu")
		(net "UPI_CPU1_CPU0_P1P1_DP<16>")
	)
	(segment
		(start 303.51476 -55.009288)
		(end 303.547526 -55.009288)
		(width 0.0889)
		(layer "In9.Cu")
		(net "UPI_CPU1_CPU0_P1P1_DP<16>")
	)
	(segment
		(start 127.714248 -48.698658)
		(end 127.714248 -52.146454)
		(width 0.1143)
		(layer "In9.Cu")
		(net "UPI_CPU1_CPU0_P1P1_DP<16>")
	)
	(segment
		(start 301.465996 -57.590436)
		(end 301.46117 -57.5818)
		(width 0.0889)
		(layer "In9.Cu")
		(net "UPI_CPU1_CPU0_P1P1_DP<16>")
	)
	(segment
		(start 290.05403 -36.799774)
		(end 282.148788 -38.179502)
		(width 0.1143)
		(layer "In9.Cu")
		(net "UPI_CPU1_CPU0_P1P1_DP<16>")
	)
	(segment
		(start 298.054522 -42.042334)
		(end 296.012362 -38.978078)
		(width 0.1143)
		(layer "In9.Cu")
		(net "UPI_CPU1_CPU0_P1P1_DP<16>")
	)
	(segment
		(start 302.847756 -51.379882)
		(end 300.847506 -49.03724)
		(width 0.0889)
		(layer "In9.Cu")
		(net "UPI_CPU1_CPU0_P1P1_DP<16>")
	)
	(segment
		(start 148.232876 -39.530782)
		(end 140.755116 -39.215822)
		(width 0.1143)
		(layer "In9.Cu")
		(net "UPI_CPU1_CPU0_P1P1_DP<16>")
	)
	(segment
		(start 187.404248 -32.50946)
		(end 187.403994 -32.50946)
		(width 0.1143)
		(layer "In9.Cu")
		(net "UPI_CPU1_CPU0_P1P1_DP<16>")
	)
	(segment
		(start 303.180496 -53.232812)
		(end 303.303686 -53.018944)
		(width 0.0889)
		(layer "In9.Cu")
		(net "UPI_CPU1_CPU0_P1P1_DP<16>")
	)
	(segment
		(start 301.812706 -58.381138)
		(end 301.51959 -58.550048)
		(width 0.0889)
		(layer "In9.Cu")
		(net "UPI_CPU1_CPU0_P1P1_DP<16>")
	)
	(segment
		(start 236.742986 -33.921446)
		(end 222.396812 -34.998406)
		(width 0.1143)
		(layer "In9.Cu")
		(net "UPI_CPU1_CPU0_P1P1_DP<16>")
	)
	(segment
		(start 212.086952 -35.786314)
		(end 199.213724 -32.49168)
		(width 0.1143)
		(layer "In9.Cu")
		(net "UPI_CPU1_CPU0_P1P1_DP<16>")
	)
	(segment
		(start 302.66005 -56.494934)
		(end 302.692816 -56.494934)
		(width 0.0889)
		(layer "In9.Cu")
		(net "UPI_CPU1_CPU0_P1P1_DP<16>")
	)
	(segment
		(start 250.94692 -32.84728)
		(end 245.515384 -32.84728)
		(width 0.1143)
		(layer "In9.Cu")
		(net "UPI_CPU1_CPU0_P1P1_DP<16>")
	)
	(segment
		(start 168.7322 -37.0332)
		(end 167.0177 -37.199824)
		(width 0.1143)
		(layer "In9.Cu")
		(net "UPI_CPU1_CPU0_P1P1_DP<16>")
	)
	(segment
		(start 169.7736 -35.9918)
		(end 168.7322 -37.0332)
		(width 0.1143)
		(layer "In9.Cu")
		(net "UPI_CPU1_CPU0_P1P1_DP<16>")
	)
	(segment
		(start 127.769112 -52.201318)
		(end 127.769112 -53.923692)
		(width 0.0889)
		(layer "In9.Cu")
		(net "UPI_CPU1_CPU0_P1P1_DP<16>")
	)
	(segment
		(start 303.5427 -53.827934)
		(end 303.51857 -53.827934)
		(width 0.0889)
		(layer "In9.Cu")
		(net "UPI_CPU1_CPU0_P1P1_DP<16>")
	)
	(arc
		(start 303.547526 -55.009288)
		(mid 304.120312 -54.416323)
		(end 303.5427 -53.827934)
		(width 0.0889)
		(layer "In9.Cu")
		(net "UPI_CPU1_CPU0_P1P1_DP<16>")
	)
	(arc
		(start 127.715518 -54.123336)
		(mid 127.637236 -54.450406)
		(end 127.750062 -54.767226)
		(width 0.0889)
		(layer "In9.Cu")
		(net "UPI_CPU1_CPU0_P1P1_DP<16>")
	)
	(arc
		(start 301.412656 -58.391044)
		(mid 301.42485 -58.282341)
		(end 301.465996 -58.180986)
		(width 0.0889)
		(layer "In9.Cu")
		(net "UPI_CPU1_CPU0_P1P1_DP<16>")
	)
	(arc
		(start 301.465996 -58.180986)
		(mid 301.545218 -57.891868)
		(end 301.472346 -57.601104)
		(width 0.0889)
		(layer "In9.Cu")
		(net "UPI_CPU1_CPU0_P1P1_DP<16>")
	)
	(arc
		(start 303.51857 -53.827934)
		(mid 303.181794 -53.625606)
		(end 303.180496 -53.232812)
		(width 0.0889)
		(layer "In9.Cu")
		(net "UPI_CPU1_CPU0_P1P1_DP<16>")
	)
	(arc
		(start 303.17821 -55.6006)
		(mid 303.181957 -55.211344)
		(end 303.51476 -55.009288)
		(width 0.0889)
		(layer "In9.Cu")
		(net "UPI_CPU1_CPU0_P1P1_DP<16>")
	)
	(arc
		(start 127.769112 -53.923692)
		(mid 127.755409 -54.027027)
		(end 127.715518 -54.123336)
		(width 0.0889)
		(layer "In9.Cu")
		(net "UPI_CPU1_CPU0_P1P1_DP<16>")
	)
	(arc
		(start 301.830486 -56.990488)
		(mid 302.11591 -56.907021)
		(end 302.324516 -56.695086)
		(width 0.0889)
		(layer "In9.Cu")
		(net "UPI_CPU1_CPU0_P1P1_DP<16>")
	)
	(arc
		(start 301.44085 -58.528712)
		(mid 301.420671 -58.461124)
		(end 301.412656 -58.391044)
		(width 0.0889)
		(layer "In9.Cu")
		(net "UPI_CPU1_CPU0_P1P1_DP<16>")
	)
	(arc
		(start 302.324516 -56.695086)
		(mid 302.466199 -56.551282)
		(end 302.66005 -56.494934)
		(width 0.0889)
		(layer "In9.Cu")
		(net "UPI_CPU1_CPU0_P1P1_DP<16>")
	)
	(arc
		(start 302.692816 -56.494934)
		(mid 303.185206 -56.196001)
		(end 303.189386 -55.619904)
		(width 0.0889)
		(layer "In9.Cu")
		(net "UPI_CPU1_CPU0_P1P1_DP<16>")
	)
	(arc
		(start 301.46117 -57.5818)
		(mid 301.464917 -57.192544)
		(end 301.79772 -56.990488)
		(width 0.0889)
		(layer "In9.Cu")
		(net "UPI_CPU1_CPU0_P1P1_DP<16>")
	)
	(segment
		(start 299.524166 -57.390538)
		(end 300.095666 -57.390538)
		(width 0.1143)
		(layer "F.Cu")
		(net "UPI_CPU1_CPU0_P1P1_DP<15>")
	)
	(segment
		(start 127.655828 -56.399938)
		(end 128.227328 -56.399938)
		(width 0.1143)
		(layer "F.Cu")
		(net "UPI_CPU1_CPU0_P1P1_DP<15>")
	)
	(via
		(at 300.095666 -57.390538)
		(size 0.508)
		(drill 0.254)
		(layers "F.Cu" "B.Cu")
		(net "UPI_CPU1_CPU0_P1P1_DP<15>")
	)
	(via
		(at 128.227328 -56.399938)
		(size 0.508)
		(drill 0.254)
		(layers "F.Cu" "B.Cu")
		(net "UPI_CPU1_CPU0_P1P1_DP<15>")
	)
	(segment
		(start 128.739138 -54.713886)
		(end 128.734312 -54.722522)
		(width 0.0889)
		(layer "In9.Cu")
		(net "UPI_CPU1_CPU0_P1P1_DP<15>")
	)
	(segment
		(start 258.390898 -36.927282)
		(end 250.777502 -33.77438)
		(width 0.1143)
		(layer "In9.Cu")
		(net "UPI_CPU1_CPU0_P1P1_DP<15>")
	)
	(segment
		(start 170.3578 -38.934644)
		(end 170.157394 -38.934644)
		(width 0.1143)
		(layer "In9.Cu")
		(net "UPI_CPU1_CPU0_P1P1_DP<15>")
	)
	(segment
		(start 192.680844 -33.71342)
		(end 187.517278 -33.507934)
		(width 0.1143)
		(layer "In9.Cu")
		(net "UPI_CPU1_CPU0_P1P1_DP<15>")
	)
	(segment
		(start 245.740682 -33.77438)
		(end 242.085622 -35.54603)
		(width 0.1143)
		(layer "In9.Cu")
		(net "UPI_CPU1_CPU0_P1P1_DP<15>")
	)
	(segment
		(start 171.704 -38.8874)
		(end 170.3578 -38.934644)
		(width 0.1143)
		(layer "In9.Cu")
		(net "UPI_CPU1_CPU0_P1P1_DP<15>")
	)
	(segment
		(start 128.734058 -51.818032)
		(end 128.734058 -52.160932)
		(width 0.1143)
		(layer "In9.Cu")
		(net "UPI_CPU1_CPU0_P1P1_DP<15>")
	)
	(segment
		(start 264.54735 -36.429442)
		(end 261.479538 -37.430202)
		(width 0.1143)
		(layer "In9.Cu")
		(net "UPI_CPU1_CPU0_P1P1_DP<15>")
	)
	(segment
		(start 302.159416 -54.618636)
		(end 302.164242 -54.61)
		(width 0.0889)
		(layer "In9.Cu")
		(net "UPI_CPU1_CPU0_P1P1_DP<15>")
	)
	(segment
		(start 128.734058 -51.365404)
		(end 128.821942 -51.453288)
		(width 0.1143)
		(layer "In9.Cu")
		(net "UPI_CPU1_CPU0_P1P1_DP<15>")
	)
	(segment
		(start 300.936406 -56.304434)
		(end 300.969172 -56.304434)
		(width 0.0889)
		(layer "In9.Cu")
		(net "UPI_CPU1_CPU0_P1P1_DP<15>")
	)
	(segment
		(start 165.640512 -38.98646)
		(end 161.123376 -39.038276)
		(width 0.1143)
		(layer "In9.Cu")
		(net "UPI_CPU1_CPU0_P1P1_DP<15>")
	)
	(segment
		(start 298.930822 -47.392844)
		(end 298.801282 -47.075598)
		(width 0.1143)
		(layer "In9.Cu")
		(net "UPI_CPU1_CPU0_P1P1_DP<15>")
	)
	(segment
		(start 296.732198 -42.011346)
		(end 296.542206 -41.726104)
		(width 0.1143)
		(layer "In9.Cu")
		(net "UPI_CPU1_CPU0_P1P1_DP<15>")
	)
	(segment
		(start 301.061628 -51.510184)
		(end 300.217332 -51.010566)
		(width 0.0889)
		(layer "In9.Cu")
		(net "UPI_CPU1_CPU0_P1P1_DP<15>")
	)
	(segment
		(start 298.051728 -45.24121)
		(end 297.852846 -45.157644)
		(width 0.1143)
		(layer "In9.Cu")
		(net "UPI_CPU1_CPU0_P1P1_DP<15>")
	)
	(segment
		(start 296.330624 -41.68394)
		(end 296.140378 -41.39819)
		(width 0.1143)
		(layer "In9.Cu")
		(net "UPI_CPU1_CPU0_P1P1_DP<15>")
	)
	(segment
		(start 299.680376 -49.227232)
		(end 299.175932 -47.992792)
		(width 0.1143)
		(layer "In9.Cu")
		(net "UPI_CPU1_CPU0_P1P1_DP<15>")
	)
	(segment
		(start 175.700944 -36.692078)
		(end 172.3898 -38.735)
		(width 0.1143)
		(layer "In9.Cu")
		(net "UPI_CPU1_CPU0_P1P1_DP<15>")
	)
	(segment
		(start 302.159416 -52.637436)
		(end 302.164242 -52.6288)
		(width 0.0889)
		(layer "In9.Cu")
		(net "UPI_CPU1_CPU0_P1P1_DP<15>")
	)
	(segment
		(start 298.227496 -46.074838)
		(end 298.097702 -45.757084)
		(width 0.1143)
		(layer "In9.Cu")
		(net "UPI_CPU1_CPU0_P1P1_DP<15>")
	)
	(segment
		(start 300.095666 -57.390538)
		(end 300.388782 -57.559448)
		(width 0.0889)
		(layer "In9.Cu")
		(net "UPI_CPU1_CPU0_P1P1_DP<15>")
	)
	(segment
		(start 296.182796 -41.186862)
		(end 295.012364 -39.430706)
		(width 0.1143)
		(layer "In9.Cu")
		(net "UPI_CPU1_CPU0_P1P1_DP<15>")
	)
	(segment
		(start 140.972794 -40.283638)
		(end 135.389112 -42.535856)
		(width 0.1143)
		(layer "In9.Cu")
		(net "UPI_CPU1_CPU0_P1P1_DP<15>")
	)
	(segment
		(start 128.245108 -55.999888)
		(end 128.212342 -55.999888)
		(width 0.0889)
		(layer "In9.Cu")
		(net "UPI_CPU1_CPU0_P1P1_DP<15>")
	)
	(segment
		(start 301.791116 -55.809388)
		(end 301.823882 -55.809388)
		(width 0.0889)
		(layer "In9.Cu")
		(net "UPI_CPU1_CPU0_P1P1_DP<15>")
	)
	(segment
		(start 302.159416 -52.237386)
		(end 302.109378 -52.150518)
		(width 0.0889)
		(layer "In9.Cu")
		(net "UPI_CPU1_CPU0_P1P1_DP<15>")
	)
	(segment
		(start 297.677078 -44.324016)
		(end 297.478196 -44.24045)
		(width 0.1143)
		(layer "In9.Cu")
		(net "UPI_CPU1_CPU0_P1P1_DP<15>")
	)
	(segment
		(start 155.61564 -39.10076)
		(end 148.537676 -40.49395)
		(width 0.1143)
		(layer "In9.Cu")
		(net "UPI_CPU1_CPU0_P1P1_DP<15>")
	)
	(segment
		(start 302.159416 -53.227986)
		(end 302.153066 -53.217318)
		(width 0.0889)
		(layer "In9.Cu")
		(net "UPI_CPU1_CPU0_P1P1_DP<15>")
	)
	(segment
		(start 195.222622 -34.589466)
		(end 192.680844 -33.71342)
		(width 0.1143)
		(layer "In9.Cu")
		(net "UPI_CPU1_CPU0_P1P1_DP<15>")
	)
	(segment
		(start 300.388782 -57.559448)
		(end 300.467522 -57.538112)
		(width 0.0889)
		(layer "In9.Cu")
		(net "UPI_CPU1_CPU0_P1P1_DP<15>")
	)
	(segment
		(start 297.806618 -44.641262)
		(end 297.677078 -44.324016)
		(width 0.1143)
		(layer "In9.Cu")
		(net "UPI_CPU1_CPU0_P1P1_DP<15>")
	)
	(segment
		(start 298.847256 -47.591726)
		(end 298.930822 -47.392844)
		(width 0.1143)
		(layer "In9.Cu")
		(net "UPI_CPU1_CPU0_P1P1_DP<15>")
	)
	(segment
		(start 299.175932 -47.992792)
		(end 298.97705 -47.909226)
		(width 0.1143)
		(layer "In9.Cu")
		(net "UPI_CPU1_CPU0_P1P1_DP<15>")
	)
	(segment
		(start 128.734058 -49.173384)
		(end 128.734058 -51.365404)
		(width 0.1143)
		(layer "In9.Cu")
		(net "UPI_CPU1_CPU0_P1P1_DP<15>")
	)
	(segment
		(start 148.537676 -40.49395)
		(end 147.673822 -40.49395)
		(width 0.1143)
		(layer "In9.Cu")
		(net "UPI_CPU1_CPU0_P1P1_DP<15>")
	)
	(segment
		(start 156.10078 -39.095172)
		(end 155.61564 -39.10076)
		(width 0.1143)
		(layer "In9.Cu")
		(net "UPI_CPU1_CPU0_P1P1_DP<15>")
	)
	(segment
		(start 147.673822 -40.49395)
		(end 140.972794 -40.283638)
		(width 0.1143)
		(layer "In9.Cu")
		(net "UPI_CPU1_CPU0_P1P1_DP<15>")
	)
	(segment
		(start 299.680376 -49.962308)
		(end 299.680376 -49.227232)
		(width 0.1143)
		(layer "In9.Cu")
		(net "UPI_CPU1_CPU0_P1P1_DP<15>")
	)
	(segment
		(start 135.389112 -42.535856)
		(end 128.734058 -49.173384)
		(width 0.1143)
		(layer "In9.Cu")
		(net "UPI_CPU1_CPU0_P1P1_DP<15>")
	)
	(segment
		(start 296.542206 -41.726104)
		(end 296.5196 -41.721532)
		(width 0.1143)
		(layer "In9.Cu")
		(net "UPI_CPU1_CPU0_P1P1_DP<15>")
	)
	(segment
		(start 298.6024 -46.992032)
		(end 298.472606 -46.674532)
		(width 0.1143)
		(layer "In9.Cu")
		(net "UPI_CPU1_CPU0_P1P1_DP<15>")
	)
	(segment
		(start 222.396812 -35.975798)
		(end 212.036152 -36.743132)
		(width 0.1143)
		(layer "In9.Cu")
		(net "UPI_CPU1_CPU0_P1P1_DP<15>")
	)
	(segment
		(start 300.217332 -51.010566)
		(end 299.731176 -50.52441)
		(width 0.0889)
		(layer "In9.Cu")
		(net "UPI_CPU1_CPU0_P1P1_DP<15>")
	)
	(segment
		(start 301.297594 -51.73472)
		(end 301.267114 -51.684428)
		(width 0.0889)
		(layer "In9.Cu")
		(net "UPI_CPU1_CPU0_P1P1_DP<15>")
	)
	(segment
		(start 242.085622 -35.54603)
		(end 236.714538 -34.915348)
		(width 0.1143)
		(layer "In9.Cu")
		(net "UPI_CPU1_CPU0_P1P1_DP<15>")
	)
	(segment
		(start 297.057064 -42.806874)
		(end 296.732198 -42.011346)
		(width 0.1143)
		(layer "In9.Cu")
		(net "UPI_CPU1_CPU0_P1P1_DP<15>")
	)
	(segment
		(start 212.036152 -36.743132)
		(end 199.002142 -33.518602)
		(width 0.1143)
		(layer "In9.Cu")
		(net "UPI_CPU1_CPU0_P1P1_DP<15>")
	)
	(segment
		(start 159.559752 -39.3319)
		(end 156.10078 -39.095172)
		(width 0.1143)
		(layer "In9.Cu")
		(net "UPI_CPU1_CPU0_P1P1_DP<15>")
	)
	(segment
		(start 299.731176 -50.52441)
		(end 299.731176 -50.03546)
		(width 0.0889)
		(layer "In9.Cu")
		(net "UPI_CPU1_CPU0_P1P1_DP<15>")
	)
	(segment
		(start 297.723052 -44.83989)
		(end 297.806618 -44.641262)
		(width 0.1143)
		(layer "In9.Cu")
		(net "UPI_CPU1_CPU0_P1P1_DP<15>")
	)
	(segment
		(start 293.427404 -38.368732)
		(end 290.161726 -37.783008)
		(width 0.1143)
		(layer "In9.Cu")
		(net "UPI_CPU1_CPU0_P1P1_DP<15>")
	)
	(segment
		(start 297.852846 -45.157644)
		(end 297.723052 -44.83989)
		(width 0.1143)
		(layer "In9.Cu")
		(net "UPI_CPU1_CPU0_P1P1_DP<15>")
	)
	(segment
		(start 128.685544 -52.209446)
		(end 128.685544 -53.9242)
		(width 0.0889)
		(layer "In9.Cu")
		(net "UPI_CPU1_CPU0_P1P1_DP<15>")
	)
	(segment
		(start 298.801282 -47.075598)
		(end 298.6024 -46.992032)
		(width 0.1143)
		(layer "In9.Cu")
		(net "UPI_CPU1_CPU0_P1P1_DP<15>")
	)
	(segment
		(start 297.348402 -43.92295)
		(end 297.431714 -43.724322)
		(width 0.1143)
		(layer "In9.Cu")
		(net "UPI_CPU1_CPU0_P1P1_DP<15>")
	)
	(segment
		(start 297.103546 -43.323256)
		(end 296.973752 -43.005756)
		(width 0.1143)
		(layer "In9.Cu")
		(net "UPI_CPU1_CPU0_P1P1_DP<15>")
	)
	(segment
		(start 296.973752 -43.005756)
		(end 297.057064 -42.806874)
		(width 0.1143)
		(layer "In9.Cu")
		(net "UPI_CPU1_CPU0_P1P1_DP<15>")
	)
	(segment
		(start 298.97705 -47.909226)
		(end 298.847256 -47.591726)
		(width 0.1143)
		(layer "In9.Cu")
		(net "UPI_CPU1_CPU0_P1P1_DP<15>")
	)
	(segment
		(start 296.5196 -41.721532)
		(end 296.330624 -41.68394)
		(width 0.1143)
		(layer "In9.Cu")
		(net "UPI_CPU1_CPU0_P1P1_DP<15>")
	)
	(segment
		(start 187.517278 -33.507934)
		(end 179.68087 -34.799524)
		(width 0.1143)
		(layer "In9.Cu")
		(net "UPI_CPU1_CPU0_P1P1_DP<15>")
	)
	(segment
		(start 127.91313 -56.152034)
		(end 127.934212 -56.230774)
		(width 0.0889)
		(layer "In9.Cu")
		(net "UPI_CPU1_CPU0_P1P1_DP<15>")
	)
	(segment
		(start 298.426378 -46.158404)
		(end 298.227496 -46.074838)
		(width 0.1143)
		(layer "In9.Cu")
		(net "UPI_CPU1_CPU0_P1P1_DP<15>")
	)
	(segment
		(start 298.097702 -45.757084)
		(end 298.181268 -45.558456)
		(width 0.1143)
		(layer "In9.Cu")
		(net "UPI_CPU1_CPU0_P1P1_DP<15>")
	)
	(segment
		(start 296.140378 -41.39819)
		(end 296.182796 -41.186862)
		(width 0.1143)
		(layer "In9.Cu")
		(net "UPI_CPU1_CPU0_P1P1_DP<15>")
	)
	(segment
		(start 297.302174 -43.406568)
		(end 297.103546 -43.323256)
		(width 0.1143)
		(layer "In9.Cu")
		(net "UPI_CPU1_CPU0_P1P1_DP<15>")
	)
	(segment
		(start 179.641754 -34.811716)
		(end 175.700944 -36.692078)
		(width 0.1143)
		(layer "In9.Cu")
		(net "UPI_CPU1_CPU0_P1P1_DP<15>")
	)
	(segment
		(start 170.157394 -38.934644)
		(end 165.640512 -38.98646)
		(width 0.1143)
		(layer "In9.Cu")
		(net "UPI_CPU1_CPU0_P1P1_DP<15>")
	)
	(segment
		(start 179.68087 -34.799524)
		(end 179.641754 -34.811716)
		(width 0.1143)
		(layer "In9.Cu")
		(net "UPI_CPU1_CPU0_P1P1_DP<15>")
	)
	(segment
		(start 298.181268 -45.558456)
		(end 298.051728 -45.24121)
		(width 0.1143)
		(layer "In9.Cu")
		(net "UPI_CPU1_CPU0_P1P1_DP<15>")
	)
	(segment
		(start 199.002142 -33.518602)
		(end 195.222622 -34.589466)
		(width 0.1143)
		(layer "In9.Cu")
		(net "UPI_CPU1_CPU0_P1P1_DP<15>")
	)
	(segment
		(start 261.479538 -37.430202)
		(end 258.390898 -36.927282)
		(width 0.1143)
		(layer "In9.Cu")
		(net "UPI_CPU1_CPU0_P1P1_DP<15>")
	)
	(segment
		(start 128.821942 -51.453288)
		(end 128.821942 -51.730148)
		(width 0.1143)
		(layer "In9.Cu")
		(net "UPI_CPU1_CPU0_P1P1_DP<15>")
	)
	(segment
		(start 282.322524 -39.160704)
		(end 264.54735 -36.429442)
		(width 0.1143)
		(layer "In9.Cu")
		(net "UPI_CPU1_CPU0_P1P1_DP<15>")
	)
	(segment
		(start 302.153066 -54.629304)
		(end 302.159416 -54.618636)
		(width 0.0889)
		(layer "In9.Cu")
		(net "UPI_CPU1_CPU0_P1P1_DP<15>")
	)
	(segment
		(start 297.478196 -44.24045)
		(end 297.348402 -43.92295)
		(width 0.1143)
		(layer "In9.Cu")
		(net "UPI_CPU1_CPU0_P1P1_DP<15>")
	)
	(segment
		(start 161.123376 -39.038276)
		(end 159.559752 -39.3319)
		(width 0.1143)
		(layer "In9.Cu")
		(net "UPI_CPU1_CPU0_P1P1_DP<15>")
	)
	(segment
		(start 127.934212 -56.230774)
		(end 128.227328 -56.399938)
		(width 0.0889)
		(layer "In9.Cu")
		(net "UPI_CPU1_CPU0_P1P1_DP<15>")
	)
	(segment
		(start 128.734058 -52.160932)
		(end 128.685544 -52.209446)
		(width 0.0889)
		(layer "In9.Cu")
		(net "UPI_CPU1_CPU0_P1P1_DP<15>")
	)
	(segment
		(start 299.731176 -50.03546)
		(end 299.680376 -49.962308)
		(width 0.0889)
		(layer "In9.Cu")
		(net "UPI_CPU1_CPU0_P1P1_DP<15>")
	)
	(segment
		(start 301.267114 -51.684428)
		(end 301.061628 -51.510184)
		(width 0.0889)
		(layer "In9.Cu")
		(net "UPI_CPU1_CPU0_P1P1_DP<15>")
	)
	(segment
		(start 250.777502 -33.77438)
		(end 245.740682 -33.77438)
		(width 0.1143)
		(layer "In9.Cu")
		(net "UPI_CPU1_CPU0_P1P1_DP<15>")
	)
	(segment
		(start 128.821942 -51.730148)
		(end 128.734058 -51.818032)
		(width 0.1143)
		(layer "In9.Cu")
		(net "UPI_CPU1_CPU0_P1P1_DP<15>")
	)
	(segment
		(start 297.431714 -43.724322)
		(end 297.302174 -43.406568)
		(width 0.1143)
		(layer "In9.Cu")
		(net "UPI_CPU1_CPU0_P1P1_DP<15>")
	)
	(segment
		(start 172.3898 -38.735)
		(end 171.704 -38.8874)
		(width 0.1143)
		(layer "In9.Cu")
		(net "UPI_CPU1_CPU0_P1P1_DP<15>")
	)
	(segment
		(start 236.714538 -34.915348)
		(end 222.396812 -35.975798)
		(width 0.1143)
		(layer "In9.Cu")
		(net "UPI_CPU1_CPU0_P1P1_DP<15>")
	)
	(segment
		(start 298.472606 -46.674532)
		(end 298.555918 -46.47565)
		(width 0.1143)
		(layer "In9.Cu")
		(net "UPI_CPU1_CPU0_P1P1_DP<15>")
	)
	(segment
		(start 290.161726 -37.783008)
		(end 282.322524 -39.160704)
		(width 0.1143)
		(layer "In9.Cu")
		(net "UPI_CPU1_CPU0_P1P1_DP<15>")
	)
	(segment
		(start 128.745488 -54.703218)
		(end 128.739138 -54.713886)
		(width 0.0889)
		(layer "In9.Cu")
		(net "UPI_CPU1_CPU0_P1P1_DP<15>")
	)
	(segment
		(start 298.555918 -46.47565)
		(end 298.426378 -46.158404)
		(width 0.1143)
		(layer "In9.Cu")
		(net "UPI_CPU1_CPU0_P1P1_DP<15>")
	)
	(segment
		(start 295.012364 -39.430706)
		(end 293.427404 -38.368732)
		(width 0.1143)
		(layer "In9.Cu")
		(net "UPI_CPU1_CPU0_P1P1_DP<15>")
	)
	(arc
		(start 128.739138 -55.113936)
		(mid 128.743467 -55.697108)
		(end 128.245108 -55.999888)
		(width 0.0889)
		(layer "In9.Cu")
		(net "UPI_CPU1_CPU0_P1P1_DP<15>")
	)
	(arc
		(start 302.164242 -52.6288)
		(mid 302.212997 -52.432448)
		(end 302.159416 -52.237386)
		(width 0.0889)
		(layer "In9.Cu")
		(net "UPI_CPU1_CPU0_P1P1_DP<15>")
	)
	(arc
		(start 128.685544 -53.9242)
		(mid 128.699312 -54.027272)
		(end 128.739138 -54.123336)
		(width 0.0889)
		(layer "In9.Cu")
		(net "UPI_CPU1_CPU0_P1P1_DP<15>")
	)
	(arc
		(start 302.159416 -53.627782)
		(mid 302.212915 -53.427884)
		(end 302.159416 -53.227986)
		(width 0.0889)
		(layer "In9.Cu")
		(net "UPI_CPU1_CPU0_P1P1_DP<15>")
	)
	(arc
		(start 301.300896 -56.104536)
		(mid 301.5079 -55.893672)
		(end 301.791116 -55.809388)
		(width 0.0889)
		(layer "In9.Cu")
		(net "UPI_CPU1_CPU0_P1P1_DP<15>")
	)
	(arc
		(start 128.734312 -54.722522)
		(mid 128.685557 -54.918874)
		(end 128.739138 -55.113936)
		(width 0.0889)
		(layer "In9.Cu")
		(net "UPI_CPU1_CPU0_P1P1_DP<15>")
	)
	(arc
		(start 300.442376 -57.190386)
		(mid 300.438047 -56.607214)
		(end 300.936406 -56.304434)
		(width 0.0889)
		(layer "In9.Cu")
		(net "UPI_CPU1_CPU0_P1P1_DP<15>")
	)
	(arc
		(start 302.164242 -54.61)
		(mid 302.212997 -54.413648)
		(end 302.159416 -54.218586)
		(width 0.0889)
		(layer "In9.Cu")
		(net "UPI_CPU1_CPU0_P1P1_DP<15>")
	)
	(arc
		(start 128.739138 -54.123336)
		(mid 128.81836 -54.412454)
		(end 128.745488 -54.703218)
		(width 0.0889)
		(layer "In9.Cu")
		(net "UPI_CPU1_CPU0_P1P1_DP<15>")
	)
	(arc
		(start 128.212342 -55.999888)
		(mid 128.046048 -56.043122)
		(end 127.91313 -56.152034)
		(width 0.0889)
		(layer "In9.Cu")
		(net "UPI_CPU1_CPU0_P1P1_DP<15>")
	)
	(arc
		(start 300.467522 -57.538112)
		(mid 300.494765 -57.361373)
		(end 300.442376 -57.190386)
		(width 0.0889)
		(layer "In9.Cu")
		(net "UPI_CPU1_CPU0_P1P1_DP<15>")
	)
	(arc
		(start 300.969172 -56.304434)
		(mid 301.160814 -56.247268)
		(end 301.300896 -56.104536)
		(width 0.0889)
		(layer "In9.Cu")
		(net "UPI_CPU1_CPU0_P1P1_DP<15>")
	)
	(arc
		(start 301.812706 -52.024788)
		(mid 301.517113 -51.947292)
		(end 301.297594 -51.73472)
		(width 0.0889)
		(layer "In9.Cu")
		(net "UPI_CPU1_CPU0_P1P1_DP<15>")
	)
	(arc
		(start 301.823882 -55.809388)
		(mid 302.162051 -55.60459)
		(end 302.159416 -55.209186)
		(width 0.0889)
		(layer "In9.Cu")
		(net "UPI_CPU1_CPU0_P1P1_DP<15>")
	)
	(arc
		(start 302.159416 -55.209186)
		(mid 302.080194 -54.920068)
		(end 302.153066 -54.629304)
		(width 0.0889)
		(layer "In9.Cu")
		(net "UPI_CPU1_CPU0_P1P1_DP<15>")
	)
	(arc
		(start 302.109378 -52.150518)
		(mid 301.973806 -52.057545)
		(end 301.812706 -52.024788)
		(width 0.0889)
		(layer "In9.Cu")
		(net "UPI_CPU1_CPU0_P1P1_DP<15>")
	)
	(arc
		(start 302.159416 -54.218586)
		(mid 302.080285 -53.923184)
		(end 302.159416 -53.627782)
		(width 0.0889)
		(layer "In9.Cu")
		(net "UPI_CPU1_CPU0_P1P1_DP<15>")
	)
	(arc
		(start 302.153066 -53.217318)
		(mid 302.080268 -52.926555)
		(end 302.159416 -52.637436)
		(width 0.0889)
		(layer "In9.Cu")
		(net "UPI_CPU1_CPU0_P1P1_DP<15>")
	)
	(segment
		(start 129.372868 -54.418738)
		(end 129.944368 -54.418738)
		(width 0.1143)
		(layer "F.Cu")
		(net "UPI_CPU1_CPU0_P1P1_DP<14>")
	)
	(segment
		(start 299.524166 -59.371484)
		(end 300.095666 -59.371484)
		(width 0.1143)
		(layer "F.Cu")
		(net "UPI_CPU1_CPU0_P1P1_DP<14>")
	)
	(via
		(at 300.095666 -59.371484)
		(size 0.508)
		(drill 0.254)
		(layers "F.Cu" "B.Cu")
		(net "UPI_CPU1_CPU0_P1P1_DP<14>")
	)
	(via
		(at 129.944368 -54.418738)
		(size 0.508)
		(drill 0.254)
		(layers "F.Cu" "B.Cu")
		(net "UPI_CPU1_CPU0_P1P1_DP<14>")
	)
	(segment
		(start 199.028812 -34.216848)
		(end 198.750682 -34.28619)
		(width 0.1143)
		(layer "In9.Cu")
		(net "UPI_CPU1_CPU0_P1P1_DP<14>")
	)
	(segment
		(start 264.48258 -37.163756)
		(end 264.48258 -37.16401)
		(width 0.1143)
		(layer "In9.Cu")
		(net "UPI_CPU1_CPU0_P1P1_DP<14>")
	)
	(segment
		(start 296.69232 -44.929806)
		(end 296.573194 -44.608496)
		(width 0.1143)
		(layer "In9.Cu")
		(net "UPI_CPU1_CPU0_P1P1_DP<14>")
	)
	(segment
		(start 180.096668 -35.586924)
		(end 180.062886 -35.597592)
		(width 0.1143)
		(layer "In9.Cu")
		(net "UPI_CPU1_CPU0_P1P1_DP<14>")
	)
	(segment
		(start 296.347896 -44.000674)
		(end 296.229024 -43.679364)
		(width 0.1143)
		(layer "In9.Cu")
		(net "UPI_CPU1_CPU0_P1P1_DP<14>")
	)
	(segment
		(start 300.011592 -59.15787)
		(end 299.663358 -58.78449)
		(width 0.0889)
		(layer "In9.Cu")
		(net "UPI_CPU1_CPU0_P1P1_DP<14>")
	)
	(segment
		(start 155.66263 -39.763192)
		(end 148.952966 -41.0972)
		(width 0.1143)
		(layer "In9.Cu")
		(net "UPI_CPU1_CPU0_P1P1_DP<14>")
	)
	(segment
		(start 187.621164 -34.169604)
		(end 180.096668 -35.586924)
		(width 0.1143)
		(layer "In9.Cu")
		(net "UPI_CPU1_CPU0_P1P1_DP<14>")
	)
	(segment
		(start 141.191488 -41.10228)
		(end 135.794242 -43.206162)
		(width 0.1143)
		(layer "In9.Cu")
		(net "UPI_CPU1_CPU0_P1P1_DP<14>")
	)
	(segment
		(start 180.062886 -35.597592)
		(end 178.245008 -36.42741)
		(width 0.1143)
		(layer "In9.Cu")
		(net "UPI_CPU1_CPU0_P1P1_DP<14>")
	)
	(segment
		(start 295.8846 -42.750232)
		(end 295.688512 -42.660062)
		(width 0.1143)
		(layer "In9.Cu")
		(net "UPI_CPU1_CPU0_P1P1_DP<14>")
	)
	(segment
		(start 148.952966 -41.0972)
		(end 148.949664 -41.097962)
		(width 0.1143)
		(layer "In9.Cu")
		(net "UPI_CPU1_CPU0_P1P1_DP<14>")
	)
	(segment
		(start 297.065954 -46.376336)
		(end 296.946828 -46.054518)
		(width 0.1143)
		(layer "In9.Cu")
		(net "UPI_CPU1_CPU0_P1P1_DP<14>")
	)
	(segment
		(start 301.294546 -53.143404)
		(end 301.300896 -53.132736)
		(width 0.0889)
		(layer "In9.Cu")
		(net "UPI_CPU1_CPU0_P1P1_DP<14>")
	)
	(segment
		(start 296.003726 -43.071542)
		(end 295.8846 -42.750232)
		(width 0.1143)
		(layer "In9.Cu")
		(net "UPI_CPU1_CPU0_P1P1_DP<14>")
	)
	(segment
		(start 297.036744 -45.858684)
		(end 296.920158 -45.544994)
		(width 0.1143)
		(layer "In9.Cu")
		(net "UPI_CPU1_CPU0_P1P1_DP<14>")
	)
	(segment
		(start 293.175944 -39.013638)
		(end 289.96259 -38.492176)
		(width 0.1143)
		(layer "In9.Cu")
		(net "UPI_CPU1_CPU0_P1P1_DP<14>")
	)
	(segment
		(start 192.613534 -34.367978)
		(end 187.621164 -34.169604)
		(width 0.1143)
		(layer "In9.Cu")
		(net "UPI_CPU1_CPU0_P1P1_DP<14>")
	)
	(segment
		(start 159.929576 -39.967662)
		(end 159.694626 -40.010334)
		(width 0.1143)
		(layer "In9.Cu")
		(net "UPI_CPU1_CPU0_P1P1_DP<14>")
	)
	(segment
		(start 129.651252 -54.587648)
		(end 129.944368 -54.418738)
		(width 0.0889)
		(layer "In9.Cu")
		(net "UPI_CPU1_CPU0_P1P1_DP<14>")
	)
	(segment
		(start 300.965362 -52.532788)
		(end 300.941232 -52.532788)
		(width 0.0889)
		(layer "In9.Cu")
		(net "UPI_CPU1_CPU0_P1P1_DP<14>")
	)
	(segment
		(start 169.545 -39.646352)
		(end 161.34715 -39.73957)
		(width 0.1143)
		(layer "In9.Cu")
		(net "UPI_CPU1_CPU0_P1P1_DP<14>")
	)
	(segment
		(start 296.25798 -44.196762)
		(end 296.347896 -44.000674)
		(width 0.1143)
		(layer "In9.Cu")
		(net "UPI_CPU1_CPU0_P1P1_DP<14>")
	)
	(segment
		(start 296.72153 -45.447458)
		(end 296.602404 -45.12564)
		(width 0.1143)
		(layer "In9.Cu")
		(net "UPI_CPU1_CPU0_P1P1_DP<14>")
	)
	(segment
		(start 297.262042 -46.466252)
		(end 297.065954 -46.376336)
		(width 0.1143)
		(layer "In9.Cu")
		(net "UPI_CPU1_CPU0_P1P1_DP<14>")
	)
	(segment
		(start 129.572512 -54.566312)
		(end 129.651252 -54.587648)
		(width 0.0889)
		(layer "In9.Cu")
		(net "UPI_CPU1_CPU0_P1P1_DP<14>")
	)
	(segment
		(start 250.59894 -34.40938)
		(end 246.02567 -34.40938)
		(width 0.1143)
		(layer "In9.Cu")
		(net "UPI_CPU1_CPU0_P1P1_DP<14>")
	)
	(segment
		(start 298.649136 -50.20818)
		(end 297.95089 -48.323754)
		(width 0.1143)
		(layer "In9.Cu")
		(net "UPI_CPU1_CPU0_P1P1_DP<14>")
	)
	(segment
		(start 300.110652 -52.037488)
		(end 300.077886 -52.037488)
		(width 0.0889)
		(layer "In9.Cu")
		(net "UPI_CPU1_CPU0_P1P1_DP<14>")
	)
	(segment
		(start 129.578608 -52.070762)
		(end 129.578608 -52.11826)
		(width 0.0889)
		(layer "In9.Cu")
		(net "UPI_CPU1_CPU0_P1P1_DP<14>")
	)
	(segment
		(start 295.337992 -41.274746)
		(end 294.338502 -39.775892)
		(width 0.1143)
		(layer "In9.Cu")
		(net "UPI_CPU1_CPU0_P1P1_DP<14>")
	)
	(segment
		(start 172.593 -39.5478)
		(end 169.545 -39.646352)
		(width 0.1143)
		(layer "In9.Cu")
		(net "UPI_CPU1_CPU0_P1P1_DP<14>")
	)
	(segment
		(start 264.48258 -37.16401)
		(end 264.482326 -37.163756)
		(width 0.1143)
		(layer "In9.Cu")
		(net "UPI_CPU1_CPU0_P1P1_DP<14>")
	)
	(segment
		(start 242.214146 -36.21659)
		(end 236.69879 -35.564064)
		(width 0.1143)
		(layer "In9.Cu")
		(net "UPI_CPU1_CPU0_P1P1_DP<14>")
	)
	(segment
		(start 148.945346 -41.098724)
		(end 147.807172 -41.3258)
		(width 0.1143)
		(layer "In9.Cu")
		(net "UPI_CPU1_CPU0_P1P1_DP<14>")
	)
	(segment
		(start 295.569386 -42.338498)
		(end 295.659556 -42.14241)
		(width 0.1143)
		(layer "In9.Cu")
		(net "UPI_CPU1_CPU0_P1P1_DP<14>")
	)
	(segment
		(start 296.032682 -43.589194)
		(end 295.913556 -43.267376)
		(width 0.1143)
		(layer "In9.Cu")
		(net "UPI_CPU1_CPU0_P1P1_DP<14>")
	)
	(segment
		(start 297.635676 -47.912274)
		(end 297.725592 -47.71644)
		(width 0.1143)
		(layer "In9.Cu")
		(net "UPI_CPU1_CPU0_P1P1_DP<14>")
	)
	(segment
		(start 300.074076 -55.809388)
		(end 300.106842 -55.809388)
		(width 0.0889)
		(layer "In9.Cu")
		(net "UPI_CPU1_CPU0_P1P1_DP<14>")
	)
	(segment
		(start 299.588682 -56.703722)
		(end 299.583856 -56.695086)
		(width 0.0889)
		(layer "In9.Cu")
		(net "UPI_CPU1_CPU0_P1P1_DP<14>")
	)
	(segment
		(start 298.699936 -51.19751)
		(end 298.699936 -50.821336)
		(width 0.0889)
		(layer "In9.Cu")
		(net "UPI_CPU1_CPU0_P1P1_DP<14>")
	)
	(segment
		(start 300.936406 -55.313834)
		(end 300.969172 -55.313834)
		(width 0.0889)
		(layer "In9.Cu")
		(net "UPI_CPU1_CPU0_P1P1_DP<14>")
	)
	(segment
		(start 155.993084 -39.759382)
		(end 155.66263 -39.763192)
		(width 0.1143)
		(layer "In9.Cu")
		(net "UPI_CPU1_CPU0_P1P1_DP<14>")
	)
	(segment
		(start 212.003894 -37.462206)
		(end 199.028812 -34.216848)
		(width 0.1143)
		(layer "In9.Cu")
		(net "UPI_CPU1_CPU0_P1P1_DP<14>")
	)
	(segment
		(start 298.649136 -50.748438)
		(end 298.649136 -50.20818)
		(width 0.1143)
		(layer "In9.Cu")
		(net "UPI_CPU1_CPU0_P1P1_DP<14>")
	)
	(segment
		(start 289.96259 -38.492176)
		(end 282.277566 -39.833296)
		(width 0.1143)
		(layer "In9.Cu")
		(net "UPI_CPU1_CPU0_P1P1_DP<14>")
	)
	(segment
		(start 282.277566 -39.833296)
		(end 264.48258 -37.163756)
		(width 0.1143)
		(layer "In9.Cu")
		(net "UPI_CPU1_CPU0_P1P1_DP<14>")
	)
	(segment
		(start 129.521966 -53.496972)
		(end 129.603754 -53.63845)
		(width 0.0889)
		(layer "In9.Cu")
		(net "UPI_CPU1_CPU0_P1P1_DP<14>")
	)
	(segment
		(start 159.694626 -40.010334)
		(end 155.993084 -39.759382)
		(width 0.1143)
		(layer "In9.Cu")
		(net "UPI_CPU1_CPU0_P1P1_DP<14>")
	)
	(segment
		(start 299.583856 -57.685686)
		(end 299.577506 -57.675018)
		(width 0.0889)
		(layer "In9.Cu")
		(net "UPI_CPU1_CPU0_P1P1_DP<14>")
	)
	(segment
		(start 301.305722 -53.731922)
		(end 301.300896 -53.723286)
		(width 0.0889)
		(layer "In9.Cu")
		(net "UPI_CPU1_CPU0_P1P1_DP<14>")
	)
	(segment
		(start 295.659556 -42.14241)
		(end 295.337992 -41.274746)
		(width 0.1143)
		(layer "In9.Cu")
		(net "UPI_CPU1_CPU0_P1P1_DP<14>")
	)
	(segment
		(start 148.949664 -41.097962)
		(end 148.945346 -41.098724)
		(width 0.1143)
		(layer "In9.Cu")
		(net "UPI_CPU1_CPU0_P1P1_DP<14>")
	)
	(segment
		(start 222.396812 -36.663376)
		(end 212.003894 -37.462206)
		(width 0.1143)
		(layer "In9.Cu")
		(net "UPI_CPU1_CPU0_P1P1_DP<14>")
	)
	(segment
		(start 246.02567 -34.40938)
		(end 242.214146 -36.21659)
		(width 0.1143)
		(layer "In9.Cu")
		(net "UPI_CPU1_CPU0_P1P1_DP<14>")
	)
	(segment
		(start 195.114672 -35.264344)
		(end 195.114672 -35.26409)
		(width 0.1143)
		(layer "In9.Cu")
		(net "UPI_CPU1_CPU0_P1P1_DP<14>")
	)
	(segment
		(start 297.725592 -47.71644)
		(end 297.606466 -47.39513)
		(width 0.1143)
		(layer "In9.Cu")
		(net "UPI_CPU1_CPU0_P1P1_DP<14>")
	)
	(segment
		(start 297.95089 -48.323754)
		(end 297.754802 -48.233838)
		(width 0.1143)
		(layer "In9.Cu")
		(net "UPI_CPU1_CPU0_P1P1_DP<14>")
	)
	(segment
		(start 301.305722 -54.722522)
		(end 301.300896 -54.713886)
		(width 0.0889)
		(layer "In9.Cu")
		(net "UPI_CPU1_CPU0_P1P1_DP<14>")
	)
	(segment
		(start 296.229024 -43.679364)
		(end 296.032682 -43.589194)
		(width 0.1143)
		(layer "In9.Cu")
		(net "UPI_CPU1_CPU0_P1P1_DP<14>")
	)
	(segment
		(start 264.482326 -37.163756)
		(end 261.630922 -38.114478)
		(width 0.1143)
		(layer "In9.Cu")
		(net "UPI_CPU1_CPU0_P1P1_DP<14>")
	)
	(segment
		(start 297.381168 -46.787562)
		(end 297.262042 -46.466252)
		(width 0.1143)
		(layer "In9.Cu")
		(net "UPI_CPU1_CPU0_P1P1_DP<14>")
	)
	(segment
		(start 297.606466 -47.39513)
		(end 297.410378 -47.305214)
		(width 0.1143)
		(layer "In9.Cu")
		(net "UPI_CPU1_CPU0_P1P1_DP<14>")
	)
	(segment
		(start 296.946828 -46.054518)
		(end 297.036744 -45.858684)
		(width 0.1143)
		(layer "In9.Cu")
		(net "UPI_CPU1_CPU0_P1P1_DP<14>")
	)
	(segment
		(start 299.583856 -56.695086)
		(end 299.577506 -56.684418)
		(width 0.0889)
		(layer "In9.Cu")
		(net "UPI_CPU1_CPU0_P1P1_DP<14>")
	)
	(segment
		(start 297.291252 -46.983396)
		(end 297.381168 -46.787562)
		(width 0.1143)
		(layer "In9.Cu")
		(net "UPI_CPU1_CPU0_P1P1_DP<14>")
	)
	(segment
		(start 298.699936 -50.821336)
		(end 298.649136 -50.770536)
		(width 0.0889)
		(layer "In9.Cu")
		(net "UPI_CPU1_CPU0_P1P1_DP<14>")
	)
	(segment
		(start 236.69879 -35.564064)
		(end 222.396812 -36.663376)
		(width 0.1143)
		(layer "In9.Cu")
		(net "UPI_CPU1_CPU0_P1P1_DP<14>")
	)
	(segment
		(start 294.338502 -39.775892)
		(end 293.175944 -39.013638)
		(width 0.1143)
		(layer "In9.Cu")
		(net "UPI_CPU1_CPU0_P1P1_DP<14>")
	)
	(segment
		(start 129.521966 -52.174902)
		(end 129.521966 -53.496972)
		(width 0.0889)
		(layer "In9.Cu")
		(net "UPI_CPU1_CPU0_P1P1_DP<14>")
	)
	(segment
		(start 296.377106 -44.518326)
		(end 296.25798 -44.196762)
		(width 0.1143)
		(layer "In9.Cu")
		(net "UPI_CPU1_CPU0_P1P1_DP<14>")
	)
	(segment
		(start 161.34715 -39.73957)
		(end 159.929576 -39.967662)
		(width 0.1143)
		(layer "In9.Cu")
		(net "UPI_CPU1_CPU0_P1P1_DP<14>")
	)
	(segment
		(start 297.410378 -47.305214)
		(end 297.291252 -46.983396)
		(width 0.1143)
		(layer "In9.Cu")
		(net "UPI_CPU1_CPU0_P1P1_DP<14>")
	)
	(segment
		(start 299.248322 -51.541934)
		(end 299.215556 -51.541934)
		(width 0.0889)
		(layer "In9.Cu")
		(net "UPI_CPU1_CPU0_P1P1_DP<14>")
	)
	(segment
		(start 296.920158 -45.544994)
		(end 296.917618 -45.537374)
		(width 0.1143)
		(layer "In9.Cu")
		(net "UPI_CPU1_CPU0_P1P1_DP<14>")
	)
	(segment
		(start 258.458208 -37.670486)
		(end 250.59894 -34.40938)
		(width 0.1143)
		(layer "In9.Cu")
		(net "UPI_CPU1_CPU0_P1P1_DP<14>")
	)
	(segment
		(start 298.649136 -50.770536)
		(end 298.649136 -50.748438)
		(width 0.0889)
		(layer "In9.Cu")
		(net "UPI_CPU1_CPU0_P1P1_DP<14>")
	)
	(segment
		(start 296.602404 -45.12564)
		(end 296.69232 -44.929806)
		(width 0.1143)
		(layer "In9.Cu")
		(net "UPI_CPU1_CPU0_P1P1_DP<14>")
	)
	(segment
		(start 295.913556 -43.267376)
		(end 296.003726 -43.071542)
		(width 0.1143)
		(layer "In9.Cu")
		(net "UPI_CPU1_CPU0_P1P1_DP<14>")
	)
	(segment
		(start 178.245008 -36.42741)
		(end 172.593 -39.5478)
		(width 0.1143)
		(layer "In9.Cu")
		(net "UPI_CPU1_CPU0_P1P1_DP<14>")
	)
	(segment
		(start 297.754802 -48.233838)
		(end 297.635676 -47.912274)
		(width 0.1143)
		(layer "In9.Cu")
		(net "UPI_CPU1_CPU0_P1P1_DP<14>")
	)
	(segment
		(start 296.917618 -45.537374)
		(end 296.72153 -45.447458)
		(width 0.1143)
		(layer "In9.Cu")
		(net "UPI_CPU1_CPU0_P1P1_DP<14>")
	)
	(segment
		(start 195.20281 -35.29584)
		(end 195.114672 -35.264344)
		(width 0.1143)
		(layer "In9.Cu")
		(net "UPI_CPU1_CPU0_P1P1_DP<14>")
	)
	(segment
		(start 135.794242 -43.206162)
		(end 129.578608 -49.421796)
		(width 0.1143)
		(layer "In9.Cu")
		(net "UPI_CPU1_CPU0_P1P1_DP<14>")
	)
	(segment
		(start 299.588682 -57.694322)
		(end 299.583856 -57.685686)
		(width 0.0889)
		(layer "In9.Cu")
		(net "UPI_CPU1_CPU0_P1P1_DP<14>")
	)
	(segment
		(start 301.300896 -54.713886)
		(end 301.294546 -54.703218)
		(width 0.0889)
		(layer "In9.Cu")
		(net "UPI_CPU1_CPU0_P1P1_DP<14>")
	)
	(segment
		(start 147.595082 -41.314116)
		(end 141.191488 -41.10228)
		(width 0.1143)
		(layer "In9.Cu")
		(net "UPI_CPU1_CPU0_P1P1_DP<14>")
	)
	(segment
		(start 295.688512 -42.660062)
		(end 295.569386 -42.338498)
		(width 0.1143)
		(layer "In9.Cu")
		(net "UPI_CPU1_CPU0_P1P1_DP<14>")
	)
	(segment
		(start 129.578608 -49.421796)
		(end 129.578608 -52.070762)
		(width 0.1143)
		(layer "In9.Cu")
		(net "UPI_CPU1_CPU0_P1P1_DP<14>")
	)
	(segment
		(start 296.573194 -44.608496)
		(end 296.377106 -44.518326)
		(width 0.1143)
		(layer "In9.Cu")
		(net "UPI_CPU1_CPU0_P1P1_DP<14>")
	)
	(segment
		(start 147.807172 -41.3258)
		(end 147.595082 -41.314116)
		(width 0.1143)
		(layer "In9.Cu")
		(net "UPI_CPU1_CPU0_P1P1_DP<14>")
	)
	(segment
		(start 129.578608 -52.11826)
		(end 129.521966 -52.174902)
		(width 0.0889)
		(layer "In9.Cu")
		(net "UPI_CPU1_CPU0_P1P1_DP<14>")
	)
	(segment
		(start 195.114672 -35.26409)
		(end 192.613534 -34.367978)
		(width 0.1143)
		(layer "In9.Cu")
		(net "UPI_CPU1_CPU0_P1P1_DP<14>")
	)
	(segment
		(start 198.750682 -34.28619)
		(end 195.20281 -35.29584)
		(width 0.1143)
		(layer "In9.Cu")
		(net "UPI_CPU1_CPU0_P1P1_DP<14>")
	)
	(segment
		(start 261.630922 -38.114478)
		(end 258.458208 -37.670486)
		(width 0.1143)
		(layer "In9.Cu")
		(net "UPI_CPU1_CPU0_P1P1_DP<14>")
	)
	(arc
		(start 301.294546 -54.703218)
		(mid 301.221748 -54.412455)
		(end 301.300896 -54.123336)
		(width 0.0889)
		(layer "In9.Cu")
		(net "UPI_CPU1_CPU0_P1P1_DP<14>")
	)
	(arc
		(start 299.577506 -57.675018)
		(mid 299.504708 -57.384255)
		(end 299.583856 -57.095136)
		(width 0.0889)
		(layer "In9.Cu")
		(net "UPI_CPU1_CPU0_P1P1_DP<14>")
	)
	(arc
		(start 300.077886 -52.037488)
		(mid 299.792462 -51.954021)
		(end 299.583856 -51.742086)
		(width 0.0889)
		(layer "In9.Cu")
		(net "UPI_CPU1_CPU0_P1P1_DP<14>")
	)
	(arc
		(start 300.941232 -52.532788)
		(mid 300.653087 -52.450469)
		(end 300.442376 -52.237386)
		(width 0.0889)
		(layer "In9.Cu")
		(net "UPI_CPU1_CPU0_P1P1_DP<14>")
	)
	(arc
		(start 301.300896 -53.723286)
		(mid 301.221674 -53.434168)
		(end 301.294546 -53.143404)
		(width 0.0889)
		(layer "In9.Cu")
		(net "UPI_CPU1_CPU0_P1P1_DP<14>")
	)
	(arc
		(start 299.215556 -51.541934)
		(mid 298.908927 -51.442798)
		(end 298.699936 -51.19751)
		(width 0.0889)
		(layer "In9.Cu")
		(net "UPI_CPU1_CPU0_P1P1_DP<14>")
	)
	(arc
		(start 301.300896 -53.132736)
		(mid 301.303479 -52.737489)
		(end 300.965362 -52.532788)
		(width 0.0889)
		(layer "In9.Cu")
		(net "UPI_CPU1_CPU0_P1P1_DP<14>")
	)
	(arc
		(start 300.442376 -52.237386)
		(mid 300.302297 -52.09465)
		(end 300.110652 -52.037488)
		(width 0.0889)
		(layer "In9.Cu")
		(net "UPI_CPU1_CPU0_P1P1_DP<14>")
	)
	(arc
		(start 129.544318 -54.42839)
		(mid 129.552298 -54.498602)
		(end 129.572512 -54.566312)
		(width 0.0889)
		(layer "In9.Cu")
		(net "UPI_CPU1_CPU0_P1P1_DP<14>")
	)
	(arc
		(start 299.663358 -58.78449)
		(mid 299.508374 -58.448222)
		(end 299.583856 -58.085736)
		(width 0.0889)
		(layer "In9.Cu")
		(net "UPI_CPU1_CPU0_P1P1_DP<14>")
	)
	(arc
		(start 300.106842 -55.809388)
		(mid 300.300692 -55.753038)
		(end 300.442376 -55.609236)
		(width 0.0889)
		(layer "In9.Cu")
		(net "UPI_CPU1_CPU0_P1P1_DP<14>")
	)
	(arc
		(start 299.583856 -58.085736)
		(mid 299.637326 -57.890673)
		(end 299.588682 -57.694322)
		(width 0.0889)
		(layer "In9.Cu")
		(net "UPI_CPU1_CPU0_P1P1_DP<14>")
	)
	(arc
		(start 299.577506 -56.684418)
		(mid 299.581537 -56.108236)
		(end 300.074076 -55.809388)
		(width 0.0889)
		(layer "In9.Cu")
		(net "UPI_CPU1_CPU0_P1P1_DP<14>")
	)
	(arc
		(start 129.603754 -53.63845)
		(mid 129.676832 -53.929328)
		(end 129.597658 -54.218586)
		(width 0.0889)
		(layer "In9.Cu")
		(net "UPI_CPU1_CPU0_P1P1_DP<14>")
	)
	(arc
		(start 301.300896 -54.123336)
		(mid 301.354366 -53.928273)
		(end 301.305722 -53.731922)
		(width 0.0889)
		(layer "In9.Cu")
		(net "UPI_CPU1_CPU0_P1P1_DP<14>")
	)
	(arc
		(start 300.442376 -55.609236)
		(mid 300.650984 -55.397304)
		(end 300.936406 -55.313834)
		(width 0.0889)
		(layer "In9.Cu")
		(net "UPI_CPU1_CPU0_P1P1_DP<14>")
	)
	(arc
		(start 129.597658 -54.218586)
		(mid 129.556514 -54.319811)
		(end 129.544318 -54.42839)
		(width 0.0889)
		(layer "In9.Cu")
		(net "UPI_CPU1_CPU0_P1P1_DP<14>")
	)
	(arc
		(start 299.583856 -57.095136)
		(mid 299.637326 -56.900073)
		(end 299.588682 -56.703722)
		(width 0.0889)
		(layer "In9.Cu")
		(net "UPI_CPU1_CPU0_P1P1_DP<14>")
	)
	(arc
		(start 300.095666 -59.371484)
		(mid 300.073878 -59.256714)
		(end 300.011592 -59.15787)
		(width 0.0889)
		(layer "In9.Cu")
		(net "UPI_CPU1_CPU0_P1P1_DP<14>")
	)
	(arc
		(start 300.969172 -55.313834)
		(mid 301.30209 -55.111843)
		(end 301.305722 -54.722522)
		(width 0.0889)
		(layer "In9.Cu")
		(net "UPI_CPU1_CPU0_P1P1_DP<14>")
	)
	(arc
		(start 299.583856 -51.742086)
		(mid 299.442173 -51.598282)
		(end 299.248322 -51.541934)
		(width 0.0889)
		(layer "In9.Cu")
		(net "UPI_CPU1_CPU0_P1P1_DP<14>")
	)
	(segment
		(start 298.665646 -58.876438)
		(end 299.237146 -58.876438)
		(width 0.1143)
		(layer "F.Cu")
		(net "UPI_CPU1_CPU0_P1P1_DP<13>")
	)
	(segment
		(start 130.231388 -54.913784)
		(end 130.802888 -54.913784)
		(width 0.1143)
		(layer "F.Cu")
		(net "UPI_CPU1_CPU0_P1P1_DP<13>")
	)
	(via
		(at 130.802888 -54.913784)
		(size 0.508)
		(drill 0.254)
		(layers "F.Cu" "B.Cu")
		(net "UPI_CPU1_CPU0_P1P1_DP<13>")
	)
	(via
		(at 299.237146 -58.876438)
		(size 0.508)
		(drill 0.254)
		(layers "F.Cu" "B.Cu")
		(net "UPI_CPU1_CPU0_P1P1_DP<13>")
	)
	(segment
		(start 192.438528 -34.708592)
		(end 187.749942 -34.521394)
		(width 0.1143)
		(layer "In9.Cu")
		(net "UPI_CPU1_CPU0_P1P1_DP<13>")
	)
	(segment
		(start 180.137308 -35.957002)
		(end 180.069998 -35.97783)
		(width 0.1143)
		(layer "In9.Cu")
		(net "UPI_CPU1_CPU0_P1P1_DP<13>")
	)
	(segment
		(start 258.632452 -38.102286)
		(end 255.31572 -36.815014)
		(width 0.1143)
		(layer "In9.Cu")
		(net "UPI_CPU1_CPU0_P1P1_DP<13>")
	)
	(segment
		(start 148.081746 -41.742106)
		(end 141.30528 -41.559734)
		(width 0.1143)
		(layer "In9.Cu")
		(net "UPI_CPU1_CPU0_P1P1_DP<13>")
	)
	(segment
		(start 155.727908 -40.114728)
		(end 148.081746 -41.742106)
		(width 0.1143)
		(layer "In9.Cu")
		(net "UPI_CPU1_CPU0_P1P1_DP<13>")
	)
	(segment
		(start 299.755306 -54.629304)
		(end 299.748956 -54.618636)
		(width 0.0889)
		(layer "In9.Cu")
		(net "UPI_CPU1_CPU0_P1P1_DP<13>")
	)
	(segment
		(start 298.890436 -57.685686)
		(end 298.896786 -57.675018)
		(width 0.0889)
		(layer "In9.Cu")
		(net "UPI_CPU1_CPU0_P1P1_DP<13>")
	)
	(segment
		(start 130.284728 -53.217318)
		(end 130.291078 -53.227986)
		(width 0.0889)
		(layer "In9.Cu")
		(net "UPI_CPU1_CPU0_P1P1_DP<13>")
	)
	(segment
		(start 298.890436 -56.695086)
		(end 298.896786 -56.684418)
		(width 0.0889)
		(layer "In9.Cu")
		(net "UPI_CPU1_CPU0_P1P1_DP<13>")
	)
	(segment
		(start 222.396812 -37.069776)
		(end 212.012022 -37.858446)
		(width 0.1143)
		(layer "In9.Cu")
		(net "UPI_CPU1_CPU0_P1P1_DP<13>")
	)
	(segment
		(start 298.88561 -57.694322)
		(end 298.890436 -57.685686)
		(width 0.0889)
		(layer "In9.Cu")
		(net "UPI_CPU1_CPU0_P1P1_DP<13>")
	)
	(segment
		(start 171.381166 -40.143684)
		(end 170.342814 -40.1066)
		(width 0.1143)
		(layer "In9.Cu")
		(net "UPI_CPU1_CPU0_P1P1_DP<13>")
	)
	(segment
		(start 195.1228 -35.701986)
		(end 192.438528 -34.708592)
		(width 0.1143)
		(layer "In9.Cu")
		(net "UPI_CPU1_CPU0_P1P1_DP<13>")
	)
	(segment
		(start 298.94403 -59.045348)
		(end 298.86529 -59.024012)
		(width 0.0889)
		(layer "In9.Cu")
		(net "UPI_CPU1_CPU0_P1P1_DP<13>")
	)
	(segment
		(start 178.560476 -36.668456)
		(end 172.724064 -39.927784)
		(width 0.1143)
		(layer "In9.Cu")
		(net "UPI_CPU1_CPU0_P1P1_DP<13>")
	)
	(segment
		(start 298.017946 -51.133502)
		(end 298.017946 -51.111404)
		(width 0.0889)
		(layer "In9.Cu")
		(net "UPI_CPU1_CPU0_P1P1_DP<13>")
	)
	(segment
		(start 199.059292 -34.600388)
		(end 195.1228 -35.701986)
		(width 0.1143)
		(layer "In9.Cu")
		(net "UPI_CPU1_CPU0_P1P1_DP<13>")
	)
	(segment
		(start 255.31572 -36.815014)
		(end 250.359418 -34.761932)
		(width 0.1143)
		(layer "In9.Cu")
		(net "UPI_CPU1_CPU0_P1P1_DP<13>")
	)
	(segment
		(start 298.400216 -51.846988)
		(end 298.36364 -51.846988)
		(width 0.0889)
		(layer "In9.Cu")
		(net "UPI_CPU1_CPU0_P1P1_DP<13>")
	)
	(segment
		(start 300.08068 -54.018688)
		(end 300.10862 -54.018688)
		(width 0.0889)
		(layer "In9.Cu")
		(net "UPI_CPU1_CPU0_P1P1_DP<13>")
	)
	(segment
		(start 178.581558 -36.65728)
		(end 178.560476 -36.668456)
		(width 0.1143)
		(layer "In9.Cu")
		(net "UPI_CPU1_CPU0_P1P1_DP<13>")
	)
	(segment
		(start 298.017946 -49.643538)
		(end 295.578784 -46.580044)
		(width 0.1143)
		(layer "In9.Cu")
		(net "UPI_CPU1_CPU0_P1P1_DP<13>")
	)
	(segment
		(start 180.069998 -35.97783)
		(end 178.581558 -36.65728)
		(width 0.1143)
		(layer "In9.Cu")
		(net "UPI_CPU1_CPU0_P1P1_DP<13>")
	)
	(segment
		(start 236.773466 -35.978084)
		(end 222.396812 -37.069776)
		(width 0.1143)
		(layer "In9.Cu")
		(net "UPI_CPU1_CPU0_P1P1_DP<13>")
	)
	(segment
		(start 297.967146 -51.184302)
		(end 298.017946 -51.133502)
		(width 0.0889)
		(layer "In9.Cu")
		(net "UPI_CPU1_CPU0_P1P1_DP<13>")
	)
	(segment
		(start 299.2501 -52.342034)
		(end 299.22216 -52.342034)
		(width 0.0889)
		(layer "In9.Cu")
		(net "UPI_CPU1_CPU0_P1P1_DP<13>")
	)
	(segment
		(start 141.30528 -41.559734)
		(end 135.97255 -43.706542)
		(width 0.1143)
		(layer "In9.Cu")
		(net "UPI_CPU1_CPU0_P1P1_DP<13>")
	)
	(segment
		(start 135.97255 -43.706542)
		(end 130.275584 -49.403508)
		(width 0.1143)
		(layer "In9.Cu")
		(net "UPI_CPU1_CPU0_P1P1_DP<13>")
	)
	(segment
		(start 300.113446 -52.837334)
		(end 300.077632 -52.837334)
		(width 0.0889)
		(layer "In9.Cu")
		(net "UPI_CPU1_CPU0_P1P1_DP<13>")
	)
	(segment
		(start 159.808164 -40.47998)
		(end 155.727908 -40.114728)
		(width 0.1143)
		(layer "In9.Cu")
		(net "UPI_CPU1_CPU0_P1P1_DP<13>")
	)
	(segment
		(start 130.344418 -51.883818)
		(end 130.344418 -52.44592)
		(width 0.0889)
		(layer "In9.Cu")
		(net "UPI_CPU1_CPU0_P1P1_DP<13>")
	)
	(segment
		(start 130.275584 -51.814984)
		(end 130.344418 -51.883818)
		(width 0.0889)
		(layer "In9.Cu")
		(net "UPI_CPU1_CPU0_P1P1_DP<13>")
	)
	(segment
		(start 298.017946 -51.111404)
		(end 298.017946 -49.643538)
		(width 0.1143)
		(layer "In9.Cu")
		(net "UPI_CPU1_CPU0_P1P1_DP<13>")
	)
	(segment
		(start 291.996114 -44.507658)
		(end 291.022532 -44.179998)
		(width 0.1143)
		(layer "In9.Cu")
		(net "UPI_CPU1_CPU0_P1P1_DP<13>")
	)
	(segment
		(start 297.967146 -51.651662)
		(end 297.967146 -51.184302)
		(width 0.0889)
		(layer "In9.Cu")
		(net "UPI_CPU1_CPU0_P1P1_DP<13>")
	)
	(segment
		(start 170.342814 -40.1066)
		(end 168.9862 -40.1066)
		(width 0.1143)
		(layer "In9.Cu")
		(net "UPI_CPU1_CPU0_P1P1_DP<13>")
	)
	(segment
		(start 187.749942 -34.521394)
		(end 180.137308 -35.957002)
		(width 0.1143)
		(layer "In9.Cu")
		(net "UPI_CPU1_CPU0_P1P1_DP<13>")
	)
	(segment
		(start 291.022532 -44.179998)
		(end 264.430764 -37.603938)
		(width 0.1143)
		(layer "In9.Cu")
		(net "UPI_CPU1_CPU0_P1P1_DP<13>")
	)
	(segment
		(start 161.699702 -40.211756)
		(end 159.808164 -40.47998)
		(width 0.1143)
		(layer "In9.Cu")
		(net "UPI_CPU1_CPU0_P1P1_DP<13>")
	)
	(segment
		(start 130.275584 -49.403508)
		(end 130.275584 -51.814984)
		(width 0.1143)
		(layer "In9.Cu")
		(net "UPI_CPU1_CPU0_P1P1_DP<13>")
	)
	(segment
		(start 168.9862 -40.1066)
		(end 161.699702 -40.211756)
		(width 0.1143)
		(layer "In9.Cu")
		(net "UPI_CPU1_CPU0_P1P1_DP<13>")
	)
	(segment
		(start 299.237146 -58.876438)
		(end 298.94403 -59.045348)
		(width 0.0889)
		(layer "In9.Cu")
		(net "UPI_CPU1_CPU0_P1P1_DP<13>")
	)
	(segment
		(start 298.00677 -51.691286)
		(end 297.967146 -51.651662)
		(width 0.0889)
		(layer "In9.Cu")
		(net "UPI_CPU1_CPU0_P1P1_DP<13>")
	)
	(segment
		(start 295.578784 -46.580044)
		(end 291.996114 -44.507658)
		(width 0.1143)
		(layer "In9.Cu")
		(net "UPI_CPU1_CPU0_P1P1_DP<13>")
	)
	(segment
		(start 299.748956 -54.618636)
		(end 299.74413 -54.61)
		(width 0.0889)
		(layer "In9.Cu")
		(net "UPI_CPU1_CPU0_P1P1_DP<13>")
	)
	(segment
		(start 246.08536 -34.761932)
		(end 242.289584 -36.595304)
		(width 0.1143)
		(layer "In9.Cu")
		(net "UPI_CPU1_CPU0_P1P1_DP<13>")
	)
	(segment
		(start 242.289584 -36.595304)
		(end 236.773466 -35.978084)
		(width 0.1143)
		(layer "In9.Cu")
		(net "UPI_CPU1_CPU0_P1P1_DP<13>")
	)
	(segment
		(start 298.88561 -56.703722)
		(end 298.890436 -56.695086)
		(width 0.0889)
		(layer "In9.Cu")
		(net "UPI_CPU1_CPU0_P1P1_DP<13>")
	)
	(segment
		(start 212.012022 -37.858446)
		(end 199.059292 -34.600388)
		(width 0.1143)
		(layer "In9.Cu")
		(net "UPI_CPU1_CPU0_P1P1_DP<13>")
	)
	(segment
		(start 264.430764 -37.603938)
		(end 261.710932 -38.515036)
		(width 0.1143)
		(layer "In9.Cu")
		(net "UPI_CPU1_CPU0_P1P1_DP<13>")
	)
	(segment
		(start 130.291078 -54.218586)
		(end 130.35661 -54.332124)
		(width 0.0889)
		(layer "In9.Cu")
		(net "UPI_CPU1_CPU0_P1P1_DP<13>")
	)
	(segment
		(start 250.359418 -34.761932)
		(end 246.08536 -34.761932)
		(width 0.1143)
		(layer "In9.Cu")
		(net "UPI_CPU1_CPU0_P1P1_DP<13>")
	)
	(segment
		(start 261.710932 -38.515036)
		(end 258.632452 -38.102286)
		(width 0.1143)
		(layer "In9.Cu")
		(net "UPI_CPU1_CPU0_P1P1_DP<13>")
	)
	(segment
		(start 172.724064 -39.927784)
		(end 171.381166 -40.143684)
		(width 0.1143)
		(layer "In9.Cu")
		(net "UPI_CPU1_CPU0_P1P1_DP<13>")
	)
	(segment
		(start 299.22597 -55.504334)
		(end 299.258736 -55.504334)
		(width 0.0889)
		(layer "In9.Cu")
		(net "UPI_CPU1_CPU0_P1P1_DP<13>")
	)
	(arc
		(start 298.837096 -58.876946)
		(mid 298.850562 -58.773228)
		(end 298.890436 -58.67654)
		(width 0.0889)
		(layer "In9.Cu")
		(net "UPI_CPU1_CPU0_P1P1_DP<13>")
	)
	(arc
		(start 298.890436 -52.142136)
		(mid 298.683432 -51.931272)
		(end 298.400216 -51.846988)
		(width 0.0889)
		(layer "In9.Cu")
		(net "UPI_CPU1_CPU0_P1P1_DP<13>")
	)
	(arc
		(start 298.36364 -51.846988)
		(mid 298.17048 -51.802881)
		(end 298.00677 -51.691286)
		(width 0.0889)
		(layer "In9.Cu")
		(net "UPI_CPU1_CPU0_P1P1_DP<13>")
	)
	(arc
		(start 130.291078 -52.637436)
		(mid 130.211856 -52.926554)
		(end 130.284728 -53.217318)
		(width 0.0889)
		(layer "In9.Cu")
		(net "UPI_CPU1_CPU0_P1P1_DP<13>")
	)
	(arc
		(start 298.890436 -56.104536)
		(mid 298.887688 -55.709069)
		(end 299.22597 -55.504334)
		(width 0.0889)
		(layer "In9.Cu")
		(net "UPI_CPU1_CPU0_P1P1_DP<13>")
	)
	(arc
		(start 299.748956 -52.637436)
		(mid 299.538243 -52.424357)
		(end 299.2501 -52.342034)
		(width 0.0889)
		(layer "In9.Cu")
		(net "UPI_CPU1_CPU0_P1P1_DP<13>")
	)
	(arc
		(start 300.077632 -52.837334)
		(mid 299.887703 -52.779464)
		(end 299.748956 -52.637436)
		(width 0.0889)
		(layer "In9.Cu")
		(net "UPI_CPU1_CPU0_P1P1_DP<13>")
	)
	(arc
		(start 298.86529 -59.024012)
		(mid 298.844255 -58.951809)
		(end 298.837096 -58.876946)
		(width 0.0889)
		(layer "In9.Cu")
		(net "UPI_CPU1_CPU0_P1P1_DP<13>")
	)
	(arc
		(start 130.35661 -54.332124)
		(mid 130.560684 -54.637581)
		(end 130.802888 -54.913784)
		(width 0.0889)
		(layer "In9.Cu")
		(net "UPI_CPU1_CPU0_P1P1_DP<13>")
	)
	(arc
		(start 298.890436 -58.67654)
		(mid 298.969567 -58.381138)
		(end 298.890436 -58.085736)
		(width 0.0889)
		(layer "In9.Cu")
		(net "UPI_CPU1_CPU0_P1P1_DP<13>")
	)
	(arc
		(start 130.291078 -53.227986)
		(mid 130.344577 -53.427884)
		(end 130.291078 -53.627782)
		(width 0.0889)
		(layer "In9.Cu")
		(net "UPI_CPU1_CPU0_P1P1_DP<13>")
	)
	(arc
		(start 298.890436 -58.085736)
		(mid 298.836966 -57.890673)
		(end 298.88561 -57.694322)
		(width 0.0889)
		(layer "In9.Cu")
		(net "UPI_CPU1_CPU0_P1P1_DP<13>")
	)
	(arc
		(start 298.890436 -57.095136)
		(mid 298.836966 -56.900073)
		(end 298.88561 -56.703722)
		(width 0.0889)
		(layer "In9.Cu")
		(net "UPI_CPU1_CPU0_P1P1_DP<13>")
	)
	(arc
		(start 298.896786 -57.675018)
		(mid 298.969584 -57.384255)
		(end 298.890436 -57.095136)
		(width 0.0889)
		(layer "In9.Cu")
		(net "UPI_CPU1_CPU0_P1P1_DP<13>")
	)
	(arc
		(start 298.896786 -56.684418)
		(mid 298.969584 -56.393655)
		(end 298.890436 -56.104536)
		(width 0.0889)
		(layer "In9.Cu")
		(net "UPI_CPU1_CPU0_P1P1_DP<13>")
	)
	(arc
		(start 299.22216 -52.342034)
		(mid 299.030518 -52.284868)
		(end 298.890436 -52.142136)
		(width 0.0889)
		(layer "In9.Cu")
		(net "UPI_CPU1_CPU0_P1P1_DP<13>")
	)
	(arc
		(start 299.258736 -55.504334)
		(mid 299.751126 -55.205401)
		(end 299.755306 -54.629304)
		(width 0.0889)
		(layer "In9.Cu")
		(net "UPI_CPU1_CPU0_P1P1_DP<13>")
	)
	(arc
		(start 130.291078 -53.627782)
		(mid 130.211947 -53.923184)
		(end 130.291078 -54.218586)
		(width 0.0889)
		(layer "In9.Cu")
		(net "UPI_CPU1_CPU0_P1P1_DP<13>")
	)
	(arc
		(start 130.344418 -52.44592)
		(mid 130.329856 -52.545054)
		(end 130.291078 -52.637436)
		(width 0.0889)
		(layer "In9.Cu")
		(net "UPI_CPU1_CPU0_P1P1_DP<13>")
	)
	(arc
		(start 299.74413 -54.61)
		(mid 299.747877 -54.220744)
		(end 300.08068 -54.018688)
		(width 0.0889)
		(layer "In9.Cu")
		(net "UPI_CPU1_CPU0_P1P1_DP<13>")
	)
	(arc
		(start 300.10862 -54.018688)
		(mid 300.686359 -53.4303)
		(end 300.113446 -52.837334)
		(width 0.0889)
		(layer "In9.Cu")
		(net "UPI_CPU1_CPU0_P1P1_DP<13>")
	)
	(segment
		(start 131.089908 -53.427884)
		(end 131.661154 -53.427884)
		(width 0.1143)
		(layer "F.Cu")
		(net "UPI_CPU1_CPU0_P1P1_DP<12>")
	)
	(segment
		(start 131.661154 -53.427884)
		(end 131.661408 -53.42763)
		(width 0.1143)
		(layer "F.Cu")
		(net "UPI_CPU1_CPU0_P1P1_DP<12>")
	)
	(segment
		(start 297.807126 -57.390538)
		(end 298.378626 -57.390538)
		(width 0.1143)
		(layer "F.Cu")
		(net "UPI_CPU1_CPU0_P1P1_DP<12>")
	)
	(via
		(at 298.378626 -57.390538)
		(size 0.508)
		(drill 0.254)
		(layers "F.Cu" "B.Cu")
		(net "UPI_CPU1_CPU0_P1P1_DP<12>")
	)
	(via
		(at 131.661408 -53.42763)
		(size 0.508)
		(drill 0.254)
		(layers "F.Cu" "B.Cu")
		(net "UPI_CPU1_CPU0_P1P1_DP<12>")
	)
	(segment
		(start 137.687558 -44.48556)
		(end 138.007852 -44.362624)
		(width 0.1143)
		(layer "In9.Cu")
		(net "UPI_CPU1_CPU0_P1P1_DP<12>")
	)
	(segment
		(start 143.593058 -42.926762)
		(end 143.746982 -42.775886)
		(width 0.1143)
		(layer "In9.Cu")
		(net "UPI_CPU1_CPU0_P1P1_DP<12>")
	)
	(segment
		(start 143.250158 -42.92346)
		(end 143.593058 -42.926762)
		(width 0.1143)
		(layer "In9.Cu")
		(net "UPI_CPU1_CPU0_P1P1_DP<12>")
	)
	(segment
		(start 180.04409 -36.99129)
		(end 187.99302 -35.469068)
		(width 0.1143)
		(layer "In9.Cu")
		(net "UPI_CPU1_CPU0_P1P1_DP<12>")
	)
	(segment
		(start 297.502326 -52.533042)
		(end 297.53814 -52.533042)
		(width 0.0889)
		(layer "In9.Cu")
		(net "UPI_CPU1_CPU0_P1P1_DP<12>")
	)
	(segment
		(start 137.083038 -44.71797)
		(end 137.170668 -44.520866)
		(width 0.1143)
		(layer "In9.Cu")
		(net "UPI_CPU1_CPU0_P1P1_DP<12>")
	)
	(segment
		(start 139.537186 -43.775122)
		(end 139.85748 -43.652186)
		(width 0.1143)
		(layer "In9.Cu")
		(net "UPI_CPU1_CPU0_P1P1_DP<12>")
	)
	(segment
		(start 161.89452 -41.15562)
		(end 168.471596 -41.15562)
		(width 0.1143)
		(layer "In9.Cu")
		(net "UPI_CPU1_CPU0_P1P1_DP<12>")
	)
	(segment
		(start 254.613156 -37.583872)
		(end 258.346194 -39.009828)
		(width 0.1143)
		(layer "In9.Cu")
		(net "UPI_CPU1_CPU0_P1P1_DP<12>")
	)
	(segment
		(start 136.565894 -44.753276)
		(end 136.762744 -44.840906)
		(width 0.1143)
		(layer "In9.Cu")
		(net "UPI_CPU1_CPU0_P1P1_DP<12>")
	)
	(segment
		(start 296.93235 -50.3428)
		(end 296.93235 -51.679856)
		(width 0.1143)
		(layer "In9.Cu")
		(net "UPI_CPU1_CPU0_P1P1_DP<12>")
	)
	(segment
		(start 172.83176 -40.986456)
		(end 180.04409 -36.99129)
		(width 0.1143)
		(layer "In9.Cu")
		(net "UPI_CPU1_CPU0_P1P1_DP<12>")
	)
	(segment
		(start 140.26515 -43.3324)
		(end 140.462 -43.42003)
		(width 0.1143)
		(layer "In9.Cu")
		(net "UPI_CPU1_CPU0_P1P1_DP<12>")
	)
	(segment
		(start 242.496594 -37.641022)
		(end 246.298466 -35.69843)
		(width 0.1143)
		(layer "In9.Cu")
		(net "UPI_CPU1_CPU0_P1P1_DP<12>")
	)
	(segment
		(start 297.866816 -55.704486)
		(end 297.871642 -55.713122)
		(width 0.0889)
		(layer "In9.Cu")
		(net "UPI_CPU1_CPU0_P1P1_DP<12>")
	)
	(segment
		(start 142.108428 -42.759376)
		(end 142.259304 -42.913554)
		(width 0.1143)
		(layer "In9.Cu")
		(net "UPI_CPU1_CPU0_P1P1_DP<12>")
	)
	(segment
		(start 142.602458 -42.916856)
		(end 142.756382 -42.76598)
		(width 0.1143)
		(layer "In9.Cu")
		(net "UPI_CPU1_CPU0_P1P1_DP<12>")
	)
	(segment
		(start 140.782294 -43.297094)
		(end 140.869924 -43.09999)
		(width 0.1143)
		(layer "In9.Cu")
		(net "UPI_CPU1_CPU0_P1P1_DP<12>")
	)
	(segment
		(start 155.866338 -41.061132)
		(end 159.862774 -41.51122)
		(width 0.1143)
		(layer "In9.Cu")
		(net "UPI_CPU1_CPU0_P1P1_DP<12>")
	)
	(segment
		(start 138.932666 -44.007532)
		(end 139.020296 -43.810174)
		(width 0.1143)
		(layer "In9.Cu")
		(net "UPI_CPU1_CPU0_P1P1_DP<12>")
	)
	(segment
		(start 138.612372 -44.130468)
		(end 138.8872 -44.025058)
		(width 0.1143)
		(layer "In9.Cu")
		(net "UPI_CPU1_CPU0_P1P1_DP<12>")
	)
	(segment
		(start 298.357036 -53.028088)
		(end 298.39666 -53.028088)
		(width 0.0889)
		(layer "In9.Cu")
		(net "UPI_CPU1_CPU0_P1P1_DP<12>")
	)
	(segment
		(start 192.22974 -35.638232)
		(end 195.07835 -36.736274)
		(width 0.1143)
		(layer "In9.Cu")
		(net "UPI_CPU1_CPU0_P1P1_DP<12>")
	)
	(segment
		(start 297.976798 -56.833516)
		(end 297.976798 -56.833262)
		(width 0.0889)
		(layer "In9.Cu")
		(net "UPI_CPU1_CPU0_P1P1_DP<12>")
	)
	(segment
		(start 297.976798 -56.833262)
		(end 298.11218 -56.958738)
		(width 0.0889)
		(layer "In9.Cu")
		(net "UPI_CPU1_CPU0_P1P1_DP<12>")
	)
	(segment
		(start 139.020296 -43.810174)
		(end 139.340336 -43.687492)
		(width 0.1143)
		(layer "In9.Cu")
		(net "UPI_CPU1_CPU0_P1P1_DP<12>")
	)
	(segment
		(start 131.314698 -52.637436)
		(end 131.266184 -52.553108)
		(width 0.0889)
		(layer "In9.Cu")
		(net "UPI_CPU1_CPU0_P1P1_DP<12>")
	)
	(segment
		(start 136.245854 -44.876212)
		(end 136.565894 -44.753276)
		(width 0.1143)
		(layer "In9.Cu")
		(net "UPI_CPU1_CPU0_P1P1_DP<12>")
	)
	(segment
		(start 250.060968 -35.69843)
		(end 254.613156 -37.583872)
		(width 0.1143)
		(layer "In9.Cu")
		(net "UPI_CPU1_CPU0_P1P1_DP<12>")
	)
	(segment
		(start 264.434066 -38.605714)
		(end 290.33343 -45.001434)
		(width 0.1143)
		(layer "In9.Cu")
		(net "UPI_CPU1_CPU0_P1P1_DP<12>")
	)
	(segment
		(start 138.415522 -44.042838)
		(end 138.612372 -44.130468)
		(width 0.1143)
		(layer "In9.Cu")
		(net "UPI_CPU1_CPU0_P1P1_DP<12>")
	)
	(segment
		(start 296.93235 -51.679856)
		(end 296.93235 -51.701954)
		(width 0.0889)
		(layer "In9.Cu")
		(net "UPI_CPU1_CPU0_P1P1_DP<12>")
	)
	(segment
		(start 137.170668 -44.520866)
		(end 137.490708 -44.39793)
		(width 0.1143)
		(layer "In9.Cu")
		(net "UPI_CPU1_CPU0_P1P1_DP<12>")
	)
	(segment
		(start 142.756382 -42.76598)
		(end 143.099028 -42.769282)
		(width 0.1143)
		(layer "In9.Cu")
		(net "UPI_CPU1_CPU0_P1P1_DP<12>")
	)
	(segment
		(start 294.47363 -47.261018)
		(end 296.93235 -50.3428)
		(width 0.1143)
		(layer "In9.Cu")
		(net "UPI_CPU1_CPU0_P1P1_DP<12>")
	)
	(segment
		(start 136.762744 -44.840906)
		(end 137.083038 -44.71797)
		(width 0.1143)
		(layer "In9.Cu")
		(net "UPI_CPU1_CPU0_P1P1_DP<12>")
	)
	(segment
		(start 261.814818 -39.490396)
		(end 264.434066 -38.605714)
		(width 0.1143)
		(layer "In9.Cu")
		(net "UPI_CPU1_CPU0_P1P1_DP<12>")
	)
	(segment
		(start 141.765782 -42.756074)
		(end 142.108428 -42.759376)
		(width 0.1143)
		(layer "In9.Cu")
		(net "UPI_CPU1_CPU0_P1P1_DP<12>")
	)
	(segment
		(start 211.818728 -38.82009)
		(end 222.396812 -38.03015)
		(width 0.1143)
		(layer "In9.Cu")
		(net "UPI_CPU1_CPU0_P1P1_DP<12>")
	)
	(segment
		(start 296.98315 -51.752754)
		(end 296.98315 -52.188364)
		(width 0.0889)
		(layer "In9.Cu")
		(net "UPI_CPU1_CPU0_P1P1_DP<12>")
	)
	(segment
		(start 258.346194 -39.009828)
		(end 261.814818 -39.490396)
		(width 0.1143)
		(layer "In9.Cu")
		(net "UPI_CPU1_CPU0_P1P1_DP<12>")
	)
	(segment
		(start 140.462 -43.42003)
		(end 140.782294 -43.297094)
		(width 0.1143)
		(layer "In9.Cu")
		(net "UPI_CPU1_CPU0_P1P1_DP<12>")
	)
	(segment
		(start 195.07835 -36.736274)
		(end 199.1614 -35.591496)
		(width 0.1143)
		(layer "In9.Cu")
		(net "UPI_CPU1_CPU0_P1P1_DP<12>")
	)
	(segment
		(start 140.869924 -43.09999)
		(end 141.765782 -42.756074)
		(width 0.1143)
		(layer "In9.Cu")
		(net "UPI_CPU1_CPU0_P1P1_DP<12>")
	)
	(segment
		(start 236.697266 -36.962334)
		(end 242.496594 -37.641022)
		(width 0.1143)
		(layer "In9.Cu")
		(net "UPI_CPU1_CPU0_P1P1_DP<12>")
	)
	(segment
		(start 147.823936 -42.815764)
		(end 155.866338 -41.061132)
		(width 0.1143)
		(layer "In9.Cu")
		(net "UPI_CPU1_CPU0_P1P1_DP<12>")
	)
	(segment
		(start 138.095482 -44.16552)
		(end 138.415522 -44.042838)
		(width 0.1143)
		(layer "In9.Cu")
		(net "UPI_CPU1_CPU0_P1P1_DP<12>")
	)
	(segment
		(start 131.432554 -49.689512)
		(end 136.245854 -44.876212)
		(width 0.1143)
		(layer "In9.Cu")
		(net "UPI_CPU1_CPU0_P1P1_DP<12>")
	)
	(segment
		(start 142.259304 -42.913554)
		(end 142.602458 -42.916856)
		(width 0.1143)
		(layer "In9.Cu")
		(net "UPI_CPU1_CPU0_P1P1_DP<12>")
	)
	(segment
		(start 222.396812 -38.03015)
		(end 236.697266 -36.962334)
		(width 0.1143)
		(layer "In9.Cu")
		(net "UPI_CPU1_CPU0_P1P1_DP<12>")
	)
	(segment
		(start 296.93235 -51.701954)
		(end 296.98315 -51.752754)
		(width 0.0889)
		(layer "In9.Cu")
		(net "UPI_CPU1_CPU0_P1P1_DP<12>")
	)
	(segment
		(start 298.389802 -54.818788)
		(end 298.357036 -54.818788)
		(width 0.0889)
		(layer "In9.Cu")
		(net "UPI_CPU1_CPU0_P1P1_DP<12>")
	)
	(segment
		(start 168.99763 -41.148)
		(end 170.893486 -41.148)
		(width 0.1143)
		(layer "In9.Cu")
		(net "UPI_CPU1_CPU0_P1P1_DP<12>")
	)
	(segment
		(start 168.471596 -41.15562)
		(end 168.99763 -41.148)
		(width 0.1143)
		(layer "In9.Cu")
		(net "UPI_CPU1_CPU0_P1P1_DP<12>")
	)
	(segment
		(start 159.862774 -41.51122)
		(end 161.89452 -41.15562)
		(width 0.1143)
		(layer "In9.Cu")
		(net "UPI_CPU1_CPU0_P1P1_DP<12>")
	)
	(segment
		(start 187.99302 -35.469068)
		(end 192.22974 -35.638232)
		(width 0.1143)
		(layer "In9.Cu")
		(net "UPI_CPU1_CPU0_P1P1_DP<12>")
	)
	(segment
		(start 138.007852 -44.362624)
		(end 138.095482 -44.16552)
		(width 0.1143)
		(layer "In9.Cu")
		(net "UPI_CPU1_CPU0_P1P1_DP<12>")
	)
	(segment
		(start 131.381754 -51.301142)
		(end 131.381754 -51.096926)
		(width 0.0889)
		(layer "In9.Cu")
		(net "UPI_CPU1_CPU0_P1P1_DP<12>")
	)
	(segment
		(start 294.362886 -47.150274)
		(end 294.47363 -47.261018)
		(width 0.1143)
		(layer "In9.Cu")
		(net "UPI_CPU1_CPU0_P1P1_DP<12>")
	)
	(segment
		(start 291.616892 -45.43933)
		(end 294.362886 -47.150274)
		(width 0.1143)
		(layer "In9.Cu")
		(net "UPI_CPU1_CPU0_P1P1_DP<12>")
	)
	(segment
		(start 131.432554 -51.024028)
		(end 131.432554 -49.689512)
		(width 0.1143)
		(layer "In9.Cu")
		(net "UPI_CPU1_CPU0_P1P1_DP<12>")
	)
	(segment
		(start 246.298466 -35.69843)
		(end 250.060968 -35.69843)
		(width 0.1143)
		(layer "In9.Cu")
		(net "UPI_CPU1_CPU0_P1P1_DP<12>")
	)
	(segment
		(start 139.85748 -43.652186)
		(end 139.94511 -43.455082)
		(width 0.1143)
		(layer "In9.Cu")
		(net "UPI_CPU1_CPU0_P1P1_DP<12>")
	)
	(segment
		(start 143.746982 -42.775886)
		(end 147.823936 -42.815764)
		(width 0.1143)
		(layer "In9.Cu")
		(net "UPI_CPU1_CPU0_P1P1_DP<12>")
	)
	(segment
		(start 143.099028 -42.769282)
		(end 143.250158 -42.92346)
		(width 0.1143)
		(layer "In9.Cu")
		(net "UPI_CPU1_CPU0_P1P1_DP<12>")
	)
	(segment
		(start 297.860466 -55.693818)
		(end 297.866816 -55.704486)
		(width 0.0889)
		(layer "In9.Cu")
		(net "UPI_CPU1_CPU0_P1P1_DP<12>")
	)
	(segment
		(start 131.227322 -52.046378)
		(end 131.381754 -51.301142)
		(width 0.0889)
		(layer "In9.Cu")
		(net "UPI_CPU1_CPU0_P1P1_DP<12>")
	)
	(segment
		(start 139.94511 -43.455082)
		(end 140.26515 -43.3324)
		(width 0.1143)
		(layer "In9.Cu")
		(net "UPI_CPU1_CPU0_P1P1_DP<12>")
	)
	(segment
		(start 131.432554 -51.046126)
		(end 131.432554 -51.024028)
		(width 0.0889)
		(layer "In9.Cu")
		(net "UPI_CPU1_CPU0_P1P1_DP<12>")
	)
	(segment
		(start 138.8872 -44.025058)
		(end 138.932666 -44.007532)
		(width 0.1143)
		(layer "In9.Cu")
		(net "UPI_CPU1_CPU0_P1P1_DP<12>")
	)
	(segment
		(start 290.33343 -45.001434)
		(end 291.616892 -45.43933)
		(width 0.1143)
		(layer "In9.Cu")
		(net "UPI_CPU1_CPU0_P1P1_DP<12>")
	)
	(segment
		(start 199.1614 -35.591496)
		(end 211.818728 -38.82009)
		(width 0.1143)
		(layer "In9.Cu")
		(net "UPI_CPU1_CPU0_P1P1_DP<12>")
	)
	(segment
		(start 137.490708 -44.39793)
		(end 137.687558 -44.48556)
		(width 0.1143)
		(layer "In9.Cu")
		(net "UPI_CPU1_CPU0_P1P1_DP<12>")
	)
	(segment
		(start 131.227322 -52.258976)
		(end 131.227322 -52.046378)
		(width 0.0889)
		(layer "In9.Cu")
		(net "UPI_CPU1_CPU0_P1P1_DP<12>")
	)
	(segment
		(start 131.381754 -51.096926)
		(end 131.432554 -51.046126)
		(width 0.0889)
		(layer "In9.Cu")
		(net "UPI_CPU1_CPU0_P1P1_DP<12>")
	)
	(segment
		(start 131.661408 -53.42763)
		(end 131.55422 -53.32095)
		(width 0.0889)
		(layer "In9.Cu")
		(net "UPI_CPU1_CPU0_P1P1_DP<12>")
	)
	(segment
		(start 170.893486 -41.148)
		(end 172.83176 -40.986456)
		(width 0.1143)
		(layer "In9.Cu")
		(net "UPI_CPU1_CPU0_P1P1_DP<12>")
	)
	(segment
		(start 139.340336 -43.687492)
		(end 139.537186 -43.775122)
		(width 0.1143)
		(layer "In9.Cu")
		(net "UPI_CPU1_CPU0_P1P1_DP<12>")
	)
	(arc
		(start 297.976798 -56.833008)
		(mid 297.976798 -56.833262)
		(end 297.976798 -56.833516)
		(width 0.0889)
		(layer "In9.Cu")
		(net "UPI_CPU1_CPU0_P1P1_DP<12>")
	)
	(arc
		(start 297.866816 -56.104536)
		(mid 297.794291 -56.488053)
		(end 297.976798 -56.833008)
		(width 0.0889)
		(layer "In9.Cu")
		(net "UPI_CPU1_CPU0_P1P1_DP<12>")
	)
	(arc
		(start 298.357036 -54.818788)
		(mid 297.864646 -55.117721)
		(end 297.860466 -55.693818)
		(width 0.0889)
		(layer "In9.Cu")
		(net "UPI_CPU1_CPU0_P1P1_DP<12>")
	)
	(arc
		(start 131.55422 -53.32095)
		(mid 131.435556 -53.143217)
		(end 131.393946 -52.9336)
		(width 0.0889)
		(layer "In9.Cu")
		(net "UPI_CPU1_CPU0_P1P1_DP<12>")
	)
	(arc
		(start 298.725336 -53.627782)
		(mid 298.646205 -53.923184)
		(end 298.725336 -54.218586)
		(width 0.0889)
		(layer "In9.Cu")
		(net "UPI_CPU1_CPU0_P1P1_DP<12>")
	)
	(arc
		(start 297.871642 -55.713122)
		(mid 297.920397 -55.909474)
		(end 297.866816 -56.104536)
		(width 0.0889)
		(layer "In9.Cu")
		(net "UPI_CPU1_CPU0_P1P1_DP<12>")
	)
	(arc
		(start 297.866816 -52.73294)
		(mid 298.07382 -52.943804)
		(end 298.357036 -53.028088)
		(width 0.0889)
		(layer "In9.Cu")
		(net "UPI_CPU1_CPU0_P1P1_DP<12>")
	)
	(arc
		(start 296.98315 -52.188364)
		(mid 297.193602 -52.434708)
		(end 297.502326 -52.533042)
		(width 0.0889)
		(layer "In9.Cu")
		(net "UPI_CPU1_CPU0_P1P1_DP<12>")
	)
	(arc
		(start 131.393946 -52.9336)
		(mid 131.373854 -52.780292)
		(end 131.314698 -52.637436)
		(width 0.0889)
		(layer "In9.Cu")
		(net "UPI_CPU1_CPU0_P1P1_DP<12>")
	)
	(arc
		(start 297.53814 -52.533042)
		(mid 297.728069 -52.590912)
		(end 297.866816 -52.73294)
		(width 0.0889)
		(layer "In9.Cu")
		(net "UPI_CPU1_CPU0_P1P1_DP<12>")
	)
	(arc
		(start 298.11218 -56.958738)
		(mid 298.274801 -57.156501)
		(end 298.378626 -57.390538)
		(width 0.0889)
		(layer "In9.Cu")
		(net "UPI_CPU1_CPU0_P1P1_DP<12>")
	)
	(arc
		(start 298.725336 -54.218586)
		(mid 298.728084 -54.614053)
		(end 298.389802 -54.818788)
		(width 0.0889)
		(layer "In9.Cu")
		(net "UPI_CPU1_CPU0_P1P1_DP<12>")
	)
	(arc
		(start 298.39666 -53.028088)
		(mid 298.729576 -53.23554)
		(end 298.725336 -53.627782)
		(width 0.0889)
		(layer "In9.Cu")
		(net "UPI_CPU1_CPU0_P1P1_DP<12>")
	)
	(arc
		(start 131.241546 -52.479702)
		(mid 131.231014 -52.369559)
		(end 131.227322 -52.258976)
		(width 0.0889)
		(layer "In9.Cu")
		(net "UPI_CPU1_CPU0_P1P1_DP<12>")
	)
	(arc
		(start 131.266184 -52.553108)
		(mid 131.250216 -52.51763)
		(end 131.241546 -52.479702)
		(width 0.0889)
		(layer "In9.Cu")
		(net "UPI_CPU1_CPU0_P1P1_DP<12>")
	)
	(segment
		(start 131.089908 -54.418738)
		(end 131.661408 -54.418738)
		(width 0.1143)
		(layer "F.Cu")
		(net "UPI_CPU1_CPU0_P1P1_DP<11>")
	)
	(segment
		(start 296.948606 -56.894984)
		(end 297.520106 -56.894984)
		(width 0.1143)
		(layer "F.Cu")
		(net "UPI_CPU1_CPU0_P1P1_DP<11>")
	)
	(via
		(at 131.661408 -54.418738)
		(size 0.508)
		(drill 0.254)
		(layers "F.Cu" "B.Cu")
		(net "UPI_CPU1_CPU0_P1P1_DP<11>")
	)
	(via
		(at 297.520106 -56.894984)
		(size 0.508)
		(drill 0.254)
		(layers "F.Cu" "B.Cu")
		(net "UPI_CPU1_CPU0_P1P1_DP<11>")
	)
	(segment
		(start 246.378222 -36.047172)
		(end 242.715288 -38.03269)
		(width 0.1143)
		(layer "In9.Cu")
		(net "UPI_CPU1_CPU0_P1P1_DP<11>")
	)
	(segment
		(start 142.651734 -43.359832)
		(end 142.360142 -43.36034)
		(width 0.1143)
		(layer "In9.Cu")
		(net "UPI_CPU1_CPU0_P1P1_DP<11>")
	)
	(segment
		(start 136.438386 -45.362622)
		(end 132.018278 -49.782984)
		(width 0.1143)
		(layer "In9.Cu")
		(net "UPI_CPU1_CPU0_P1P1_DP<11>")
	)
	(segment
		(start 173.30801 -41.299384)
		(end 170.799506 -41.69283)
		(width 0.1143)
		(layer "In9.Cu")
		(net "UPI_CPU1_CPU0_P1P1_DP<11>")
	)
	(segment
		(start 261.732014 -39.901368)
		(end 258.293108 -39.4208)
		(width 0.1143)
		(layer "In9.Cu")
		(net "UPI_CPU1_CPU0_P1P1_DP<11>")
	)
	(segment
		(start 131.978146 -54.16042)
		(end 131.95427 -54.249828)
		(width 0.0889)
		(layer "In9.Cu")
		(net "UPI_CPU1_CPU0_P1P1_DP<11>")
	)
	(segment
		(start 132.018278 -49.782984)
		(end 132.018278 -51.296824)
		(width 0.1143)
		(layer "In9.Cu")
		(net "UPI_CPU1_CPU0_P1P1_DP<11>")
	)
	(segment
		(start 242.715288 -38.03269)
		(end 236.599984 -37.324792)
		(width 0.1143)
		(layer "In9.Cu")
		(net "UPI_CPU1_CPU0_P1P1_DP<11>")
	)
	(segment
		(start 296.258996 -52.434744)
		(end 296.258996 -51.918108)
		(width 0.0889)
		(layer "In9.Cu")
		(net "UPI_CPU1_CPU0_P1P1_DP<11>")
	)
	(segment
		(start 180.270912 -37.349684)
		(end 173.30801 -41.299384)
		(width 0.1143)
		(layer "In9.Cu")
		(net "UPI_CPU1_CPU0_P1P1_DP<11>")
	)
	(segment
		(start 132.018278 -51.296824)
		(end 132.061966 -51.340512)
		(width 0.0889)
		(layer "In9.Cu")
		(net "UPI_CPU1_CPU0_P1P1_DP<11>")
	)
	(segment
		(start 132.007864 -53.627782)
		(end 132.001514 -53.63845)
		(width 0.0889)
		(layer "In9.Cu")
		(net "UPI_CPU1_CPU0_P1P1_DP<11>")
	)
	(segment
		(start 166.901368 -41.49852)
		(end 165.511734 -41.519094)
		(width 0.1143)
		(layer "In9.Cu")
		(net "UPI_CPU1_CPU0_P1P1_DP<11>")
	)
	(segment
		(start 297.227244 -57.063894)
		(end 297.148504 -57.042558)
		(width 0.0889)
		(layer "In9.Cu")
		(net "UPI_CPU1_CPU0_P1P1_DP<11>")
	)
	(segment
		(start 236.599984 -37.324792)
		(end 222.396812 -38.457632)
		(width 0.1143)
		(layer "In9.Cu")
		(net "UPI_CPU1_CPU0_P1P1_DP<11>")
	)
	(segment
		(start 297.520106 -54.513734)
		(end 297.541696 -54.513734)
		(width 0.0889)
		(layer "In9.Cu")
		(net "UPI_CPU1_CPU0_P1P1_DP<11>")
	)
	(segment
		(start 187.984638 -35.879024)
		(end 180.270912 -37.349684)
		(width 0.1143)
		(layer "In9.Cu")
		(net "UPI_CPU1_CPU0_P1P1_DP<11>")
	)
	(segment
		(start 131.95427 -54.249828)
		(end 131.661408 -54.418738)
		(width 0.0889)
		(layer "In9.Cu")
		(net "UPI_CPU1_CPU0_P1P1_DP<11>")
	)
	(segment
		(start 161.982658 -41.573196)
		(end 159.854392 -42.006774)
		(width 0.1143)
		(layer "In9.Cu")
		(net "UPI_CPU1_CPU0_P1P1_DP<11>")
	)
	(segment
		(start 258.293108 -39.4208)
		(end 254.880872 -38.091618)
		(width 0.1143)
		(layer "In9.Cu")
		(net "UPI_CPU1_CPU0_P1P1_DP<11>")
	)
	(segment
		(start 291.606224 -45.903134)
		(end 289.351212 -45.144182)
		(width 0.1143)
		(layer "In9.Cu")
		(net "UPI_CPU1_CPU0_P1P1_DP<11>")
	)
	(segment
		(start 222.396812 -38.457632)
		(end 211.999322 -39.286942)
		(width 0.1143)
		(layer "In9.Cu")
		(net "UPI_CPU1_CPU0_P1P1_DP<11>")
	)
	(segment
		(start 296.309796 -51.867308)
		(end 296.309796 -51.84521)
		(width 0.0889)
		(layer "In9.Cu")
		(net "UPI_CPU1_CPU0_P1P1_DP<11>")
	)
	(segment
		(start 254.880872 -38.091618)
		(end 249.945144 -36.047172)
		(width 0.1143)
		(layer "In9.Cu")
		(net "UPI_CPU1_CPU0_P1P1_DP<11>")
	)
	(segment
		(start 211.999322 -39.286942)
		(end 199.17791 -35.974528)
		(width 0.1143)
		(layer "In9.Cu")
		(net "UPI_CPU1_CPU0_P1P1_DP<11>")
	)
	(segment
		(start 132.061966 -52.385976)
		(end 132.061204 -52.443126)
		(width 0.0889)
		(layer "In9.Cu")
		(net "UPI_CPU1_CPU0_P1P1_DP<11>")
	)
	(segment
		(start 296.309796 -51.84521)
		(end 296.309796 -50.461164)
		(width 0.1143)
		(layer "In9.Cu")
		(net "UPI_CPU1_CPU0_P1P1_DP<11>")
	)
	(segment
		(start 296.258996 -51.918108)
		(end 296.309796 -51.867308)
		(width 0.0889)
		(layer "In9.Cu")
		(net "UPI_CPU1_CPU0_P1P1_DP<11>")
	)
	(segment
		(start 142.360142 -43.36034)
		(end 142.311374 -43.36034)
		(width 0.1143)
		(layer "In9.Cu")
		(net "UPI_CPU1_CPU0_P1P1_DP<11>")
	)
	(segment
		(start 159.854392 -42.006774)
		(end 156.145738 -41.467786)
		(width 0.1143)
		(layer "In9.Cu")
		(net "UPI_CPU1_CPU0_P1P1_DP<11>")
	)
	(segment
		(start 132.061966 -51.340512)
		(end 132.061966 -52.385976)
		(width 0.0889)
		(layer "In9.Cu")
		(net "UPI_CPU1_CPU0_P1P1_DP<11>")
	)
	(segment
		(start 293.844218 -47.418244)
		(end 291.606224 -45.903134)
		(width 0.1143)
		(layer "In9.Cu")
		(net "UPI_CPU1_CPU0_P1P1_DP<11>")
	)
	(segment
		(start 155.868878 -41.436544)
		(end 146.985228 -43.433746)
		(width 0.1143)
		(layer "In9.Cu")
		(net "UPI_CPU1_CPU0_P1P1_DP<11>")
	)
	(segment
		(start 264.443972 -39.021766)
		(end 261.732014 -39.901368)
		(width 0.1143)
		(layer "In9.Cu")
		(net "UPI_CPU1_CPU0_P1P1_DP<11>")
	)
	(segment
		(start 170.799506 -41.69283)
		(end 166.901368 -41.49852)
		(width 0.1143)
		(layer "In9.Cu")
		(net "UPI_CPU1_CPU0_P1P1_DP<11>")
	)
	(segment
		(start 288.244026 -44.845224)
		(end 288.210498 -44.83608)
		(width 0.1143)
		(layer "In9.Cu")
		(net "UPI_CPU1_CPU0_P1P1_DP<11>")
	)
	(segment
		(start 249.945144 -36.047172)
		(end 246.378222 -36.047172)
		(width 0.1143)
		(layer "In9.Cu")
		(net "UPI_CPU1_CPU0_P1P1_DP<11>")
	)
	(segment
		(start 297.17365 -55.704486)
		(end 297.18254 -55.689246)
		(width 0.0889)
		(layer "In9.Cu")
		(net "UPI_CPU1_CPU0_P1P1_DP<11>")
	)
	(segment
		(start 146.985228 -43.433746)
		(end 142.651734 -43.359832)
		(width 0.1143)
		(layer "In9.Cu")
		(net "UPI_CPU1_CPU0_P1P1_DP<11>")
	)
	(segment
		(start 288.210498 -44.83608)
		(end 264.443972 -39.021766)
		(width 0.1143)
		(layer "In9.Cu")
		(net "UPI_CPU1_CPU0_P1P1_DP<11>")
	)
	(segment
		(start 199.17791 -35.974528)
		(end 194.987926 -37.121846)
		(width 0.1143)
		(layer "In9.Cu")
		(net "UPI_CPU1_CPU0_P1P1_DP<11>")
	)
	(segment
		(start 296.309796 -50.461164)
		(end 293.844218 -47.418244)
		(width 0.1143)
		(layer "In9.Cu")
		(net "UPI_CPU1_CPU0_P1P1_DP<11>")
	)
	(segment
		(start 192.262252 -36.049712)
		(end 187.984638 -35.879024)
		(width 0.1143)
		(layer "In9.Cu")
		(net "UPI_CPU1_CPU0_P1P1_DP<11>")
	)
	(segment
		(start 289.351212 -45.144182)
		(end 288.244026 -44.845224)
		(width 0.1143)
		(layer "In9.Cu")
		(net "UPI_CPU1_CPU0_P1P1_DP<11>")
	)
	(segment
		(start 297.17365 -56.695086)
		(end 297.18254 -56.679846)
		(width 0.0889)
		(layer "In9.Cu")
		(net "UPI_CPU1_CPU0_P1P1_DP<11>")
	)
	(segment
		(start 165.511734 -41.519094)
		(end 161.982658 -41.573196)
		(width 0.1143)
		(layer "In9.Cu")
		(net "UPI_CPU1_CPU0_P1P1_DP<11>")
	)
	(segment
		(start 142.311374 -43.36034)
		(end 136.438386 -45.362622)
		(width 0.1143)
		(layer "In9.Cu")
		(net "UPI_CPU1_CPU0_P1P1_DP<11>")
	)
	(segment
		(start 297.17365 -54.713886)
		(end 297.176952 -54.708044)
		(width 0.0889)
		(layer "In9.Cu")
		(net "UPI_CPU1_CPU0_P1P1_DP<11>")
	)
	(segment
		(start 132.001514 -53.217318)
		(end 132.007864 -53.227986)
		(width 0.0889)
		(layer "In9.Cu")
		(net "UPI_CPU1_CPU0_P1P1_DP<11>")
	)
	(segment
		(start 156.145738 -41.467786)
		(end 155.868878 -41.436544)
		(width 0.1143)
		(layer "In9.Cu")
		(net "UPI_CPU1_CPU0_P1P1_DP<11>")
	)
	(segment
		(start 297.520106 -56.894984)
		(end 297.227244 -57.063894)
		(width 0.0889)
		(layer "In9.Cu")
		(net "UPI_CPU1_CPU0_P1P1_DP<11>")
	)
	(segment
		(start 194.987926 -37.121846)
		(end 192.262252 -36.049712)
		(width 0.1143)
		(layer "In9.Cu")
		(net "UPI_CPU1_CPU0_P1P1_DP<11>")
	)
	(segment
		(start 296.67962 -52.837334)
		(end 296.643806 -52.837334)
		(width 0.0889)
		(layer "In9.Cu")
		(net "UPI_CPU1_CPU0_P1P1_DP<11>")
	)
	(segment
		(start 297.541696 -53.332634)
		(end 297.507914 -53.332634)
		(width 0.0889)
		(layer "In9.Cu")
		(net "UPI_CPU1_CPU0_P1P1_DP<11>")
	)
	(arc
		(start 297.12031 -56.895492)
		(mid 297.133783 -56.791779)
		(end 297.17365 -56.695086)
		(width 0.0889)
		(layer "In9.Cu")
		(net "UPI_CPU1_CPU0_P1P1_DP<11>")
	)
	(arc
		(start 297.18254 -55.689246)
		(mid 297.252937 -55.400295)
		(end 297.17365 -55.113682)
		(width 0.0889)
		(layer "In9.Cu")
		(net "UPI_CPU1_CPU0_P1P1_DP<11>")
	)
	(arc
		(start 297.17365 -53.132736)
		(mid 296.965042 -52.920804)
		(end 296.67962 -52.837334)
		(width 0.0889)
		(layer "In9.Cu")
		(net "UPI_CPU1_CPU0_P1P1_DP<11>")
	)
	(arc
		(start 132.007864 -53.227986)
		(mid 132.061397 -53.427884)
		(end 132.007864 -53.627782)
		(width 0.0889)
		(layer "In9.Cu")
		(net "UPI_CPU1_CPU0_P1P1_DP<11>")
	)
	(arc
		(start 296.643806 -52.837334)
		(mid 296.370574 -52.713255)
		(end 296.258996 -52.434744)
		(width 0.0889)
		(layer "In9.Cu")
		(net "UPI_CPU1_CPU0_P1P1_DP<11>")
	)
	(arc
		(start 297.18254 -56.679846)
		(mid 297.252937 -56.390895)
		(end 297.17365 -56.104282)
		(width 0.0889)
		(layer "In9.Cu")
		(net "UPI_CPU1_CPU0_P1P1_DP<11>")
	)
	(arc
		(start 297.17365 -56.104282)
		(mid 297.120117 -55.904384)
		(end 297.17365 -55.704486)
		(width 0.0889)
		(layer "In9.Cu")
		(net "UPI_CPU1_CPU0_P1P1_DP<11>")
	)
	(arc
		(start 132.007864 -52.637436)
		(mid 131.928642 -52.926554)
		(end 132.001514 -53.217318)
		(width 0.0889)
		(layer "In9.Cu")
		(net "UPI_CPU1_CPU0_P1P1_DP<11>")
	)
	(arc
		(start 297.541696 -54.513734)
		(mid 297.824913 -54.429453)
		(end 298.031916 -54.218586)
		(width 0.0889)
		(layer "In9.Cu")
		(net "UPI_CPU1_CPU0_P1P1_DP<11>")
	)
	(arc
		(start 297.17365 -55.113682)
		(mid 297.120117 -54.913784)
		(end 297.17365 -54.713886)
		(width 0.0889)
		(layer "In9.Cu")
		(net "UPI_CPU1_CPU0_P1P1_DP<11>")
	)
	(arc
		(start 297.176952 -54.708044)
		(mid 297.322918 -54.565645)
		(end 297.520106 -54.513734)
		(width 0.0889)
		(layer "In9.Cu")
		(net "UPI_CPU1_CPU0_P1P1_DP<11>")
	)
	(arc
		(start 297.507914 -53.332634)
		(mid 297.314811 -53.276115)
		(end 297.17365 -53.132736)
		(width 0.0889)
		(layer "In9.Cu")
		(net "UPI_CPU1_CPU0_P1P1_DP<11>")
	)
	(arc
		(start 132.061204 -52.443126)
		(mid 132.046961 -52.54369)
		(end 132.007864 -52.637436)
		(width 0.0889)
		(layer "In9.Cu")
		(net "UPI_CPU1_CPU0_P1P1_DP<11>")
	)
	(arc
		(start 298.031916 -54.218586)
		(mid 298.111047 -53.923184)
		(end 298.031916 -53.627782)
		(width 0.0889)
		(layer "In9.Cu")
		(net "UPI_CPU1_CPU0_P1P1_DP<11>")
	)
	(arc
		(start 132.001514 -53.63845)
		(mid 131.928997 -53.896716)
		(end 131.978146 -54.16042)
		(width 0.0889)
		(layer "In9.Cu")
		(net "UPI_CPU1_CPU0_P1P1_DP<11>")
	)
	(arc
		(start 298.031916 -53.627782)
		(mid 297.824912 -53.416918)
		(end 297.541696 -53.332634)
		(width 0.0889)
		(layer "In9.Cu")
		(net "UPI_CPU1_CPU0_P1P1_DP<11>")
	)
	(arc
		(start 297.148504 -57.042558)
		(mid 297.127456 -56.970357)
		(end 297.12031 -56.895492)
		(width 0.0889)
		(layer "In9.Cu")
		(net "UPI_CPU1_CPU0_P1P1_DP<11>")
	)
	(segment
		(start 132.806694 -54.418738)
		(end 133.378194 -54.418738)
		(width 0.1143)
		(layer "F.Cu")
		(net "UPI_CPU1_CPU0_P1P1_DP<10>")
	)
	(segment
		(start 296.948606 -57.885584)
		(end 297.520106 -57.885584)
		(width 0.1143)
		(layer "F.Cu")
		(net "UPI_CPU1_CPU0_P1P1_DP<10>")
	)
	(via
		(at 133.378194 -54.418738)
		(size 0.508)
		(drill 0.254)
		(layers "F.Cu" "B.Cu")
		(net "UPI_CPU1_CPU0_P1P1_DP<10>")
	)
	(via
		(at 297.520106 -57.885584)
		(size 0.508)
		(drill 0.254)
		(layers "F.Cu" "B.Cu")
		(net "UPI_CPU1_CPU0_P1P1_DP<10>")
	)
	(segment
		(start 242.8113 -38.786308)
		(end 236.54131 -37.967158)
		(width 0.1143)
		(layer "In9.Cu")
		(net "UPI_CPU1_CPU0_P1P1_DP<10>")
	)
	(segment
		(start 192.042542 -36.710366)
		(end 188.091318 -36.555172)
		(width 0.1143)
		(layer "In9.Cu")
		(net "UPI_CPU1_CPU0_P1P1_DP<10>")
	)
	(segment
		(start 286.847026 -45.155612)
		(end 264.462514 -39.732966)
		(width 0.1143)
		(layer "In9.Cu")
		(net "UPI_CPU1_CPU0_P1P1_DP<10>")
	)
	(segment
		(start 296.32148 -55.619904)
		(end 296.31513 -55.609236)
		(width 0.0889)
		(layer "In9.Cu")
		(net "UPI_CPU1_CPU0_P1P1_DP<10>")
	)
	(segment
		(start 295.539414 -52.075842)
		(end 295.590214 -52.002944)
		(width 0.0889)
		(layer "In9.Cu")
		(net "UPI_CPU1_CPU0_P1P1_DP<10>")
	)
	(segment
		(start 261.541768 -40.631872)
		(end 258.0513 -40.155622)
		(width 0.1143)
		(layer "In9.Cu")
		(net "UPI_CPU1_CPU0_P1P1_DP<10>")
	)
	(segment
		(start 180.466492 -38.026594)
		(end 178.820826 -38.880288)
		(width 0.1143)
		(layer "In9.Cu")
		(net "UPI_CPU1_CPU0_P1P1_DP<10>")
	)
	(segment
		(start 133.86054 -49.098962)
		(end 133.86054 -49.170844)
		(width 0.0889)
		(layer "In9.Cu")
		(net "UPI_CPU1_CPU0_P1P1_DP<10>")
	)
	(segment
		(start 291.127688 -46.488858)
		(end 288.244026 -45.53712)
		(width 0.1143)
		(layer "In9.Cu")
		(net "UPI_CPU1_CPU0_P1P1_DP<10>")
	)
	(segment
		(start 295.45661 -52.73294)
		(end 295.539414 -52.589684)
		(width 0.0889)
		(layer "In9.Cu")
		(net "UPI_CPU1_CPU0_P1P1_DP<10>")
	)
	(segment
		(start 295.590214 -51.186588)
		(end 293.39032 -48.12919)
		(width 0.1143)
		(layer "In9.Cu")
		(net "UPI_CPU1_CPU0_P1P1_DP<10>")
	)
	(segment
		(start 136.659874 -46.299628)
		(end 133.86054 -49.098962)
		(width 0.1143)
		(layer "In9.Cu")
		(net "UPI_CPU1_CPU0_P1P1_DP<10>")
	)
	(segment
		(start 178.820826 -38.880288)
		(end 173.500542 -42.04081)
		(width 0.1143)
		(layer "In9.Cu")
		(net "UPI_CPU1_CPU0_P1P1_DP<10>")
	)
	(segment
		(start 246.54256 -36.688268)
		(end 242.8113 -38.786308)
		(width 0.1143)
		(layer "In9.Cu")
		(net "UPI_CPU1_CPU0_P1P1_DP<10>")
	)
	(segment
		(start 297.792902 -58.285634)
		(end 297.520106 -58.285634)
		(width 0.0889)
		(layer "In9.Cu")
		(net "UPI_CPU1_CPU0_P1P1_DP<10>")
	)
	(segment
		(start 296.31513 -56.599836)
		(end 296.310304 -56.5912)
		(width 0.0889)
		(layer "In9.Cu")
		(net "UPI_CPU1_CPU0_P1P1_DP<10>")
	)
	(segment
		(start 236.54131 -37.967158)
		(end 222.396812 -39.117524)
		(width 0.1143)
		(layer "In9.Cu")
		(net "UPI_CPU1_CPU0_P1P1_DP<10>")
	)
	(segment
		(start 295.590214 -52.002944)
		(end 295.590214 -51.186588)
		(width 0.1143)
		(layer "In9.Cu")
		(net "UPI_CPU1_CPU0_P1P1_DP<10>")
	)
	(segment
		(start 293.39032 -48.12919)
		(end 291.127688 -46.488858)
		(width 0.1143)
		(layer "In9.Cu")
		(net "UPI_CPU1_CPU0_P1P1_DP<10>")
	)
	(segment
		(start 296.31513 -54.618636)
		(end 296.310304 -54.61)
		(width 0.0889)
		(layer "In9.Cu")
		(net "UPI_CPU1_CPU0_P1P1_DP<10>")
	)
	(segment
		(start 146.601942 -44.266104)
		(end 142.348458 -44.363386)
		(width 0.1143)
		(layer "In9.Cu")
		(net "UPI_CPU1_CPU0_P1P1_DP<10>")
	)
	(segment
		(start 288.092896 -45.487336)
		(end 286.847026 -45.155612)
		(width 0.1143)
		(layer "In9.Cu")
		(net "UPI_CPU1_CPU0_P1P1_DP<10>")
	)
	(segment
		(start 155.900882 -42.085514)
		(end 146.601942 -44.266104)
		(width 0.1143)
		(layer "In9.Cu")
		(net "UPI_CPU1_CPU0_P1P1_DP<10>")
	)
	(segment
		(start 297.520106 -57.885584)
		(end 297.792902 -57.885584)
		(width 0.0889)
		(layer "In9.Cu")
		(net "UPI_CPU1_CPU0_P1P1_DP<10>")
	)
	(segment
		(start 193.536824 -37.288216)
		(end 192.042542 -36.710366)
		(width 0.1143)
		(layer "In9.Cu")
		(net "UPI_CPU1_CPU0_P1P1_DP<10>")
	)
	(segment
		(start 295.82491 -53.332634)
		(end 295.785286 -53.332634)
		(width 0.0889)
		(layer "In9.Cu")
		(net "UPI_CPU1_CPU0_P1P1_DP<10>")
	)
	(segment
		(start 161.801048 -42.349928)
		(end 160.156906 -42.715942)
		(width 0.1143)
		(layer "In9.Cu")
		(net "UPI_CPU1_CPU0_P1P1_DP<10>")
	)
	(segment
		(start 160.156906 -42.715942)
		(end 155.900882 -42.085514)
		(width 0.1143)
		(layer "In9.Cu")
		(net "UPI_CPU1_CPU0_P1P1_DP<10>")
	)
	(segment
		(start 132.866384 -53.132736)
		(end 132.860034 -53.143404)
		(width 0.0889)
		(layer "In9.Cu")
		(net "UPI_CPU1_CPU0_P1P1_DP<10>")
	)
	(segment
		(start 173.500542 -42.04081)
		(end 170.897296 -42.605706)
		(width 0.1143)
		(layer "In9.Cu")
		(net "UPI_CPU1_CPU0_P1P1_DP<10>")
	)
	(segment
		(start 296.31513 -55.609236)
		(end 296.310304 -55.6006)
		(width 0.0889)
		(layer "In9.Cu")
		(net "UPI_CPU1_CPU0_P1P1_DP<10>")
	)
	(segment
		(start 295.539414 -52.589684)
		(end 295.539414 -52.075842)
		(width 0.0889)
		(layer "In9.Cu")
		(net "UPI_CPU1_CPU0_P1P1_DP<10>")
	)
	(segment
		(start 195.031106 -37.865558)
		(end 193.536824 -37.287962)
		(width 0.1143)
		(layer "In9.Cu")
		(net "UPI_CPU1_CPU0_P1P1_DP<10>")
	)
	(segment
		(start 133.86054 -49.170844)
		(end 133.860794 -49.171098)
		(width 0.0889)
		(layer "In9.Cu")
		(net "UPI_CPU1_CPU0_P1P1_DP<10>")
	)
	(segment
		(start 166.875206 -42.273474)
		(end 161.801048 -42.349928)
		(width 0.1143)
		(layer "In9.Cu")
		(net "UPI_CPU1_CPU0_P1P1_DP<10>")
	)
	(segment
		(start 297.176952 -58.091324)
		(end 297.17365 -58.085482)
		(width 0.0889)
		(layer "In9.Cu")
		(net "UPI_CPU1_CPU0_P1P1_DP<10>")
	)
	(segment
		(start 296.686732 -57.790588)
		(end 296.650664 -57.790588)
		(width 0.0889)
		(layer "In9.Cu")
		(net "UPI_CPU1_CPU0_P1P1_DP<10>")
	)
	(segment
		(start 132.787898 -50.244248)
		(end 132.787898 -51.4731)
		(width 0.0889)
		(layer "In9.Cu")
		(net "UPI_CPU1_CPU0_P1P1_DP<10>")
	)
	(segment
		(start 288.244026 -45.53712)
		(end 288.092896 -45.487336)
		(width 0.1143)
		(layer "In9.Cu")
		(net "UPI_CPU1_CPU0_P1P1_DP<10>")
	)
	(segment
		(start 296.32148 -54.629304)
		(end 296.31513 -54.618636)
		(width 0.0889)
		(layer "In9.Cu")
		(net "UPI_CPU1_CPU0_P1P1_DP<10>")
	)
	(segment
		(start 170.897296 -42.605706)
		(end 166.875206 -42.273474)
		(width 0.1143)
		(layer "In9.Cu")
		(net "UPI_CPU1_CPU0_P1P1_DP<10>")
	)
	(segment
		(start 264.462514 -39.732966)
		(end 261.541768 -40.631872)
		(width 0.1143)
		(layer "In9.Cu")
		(net "UPI_CPU1_CPU0_P1P1_DP<10>")
	)
	(segment
		(start 296.32148 -56.610504)
		(end 296.31513 -56.599836)
		(width 0.0889)
		(layer "In9.Cu")
		(net "UPI_CPU1_CPU0_P1P1_DP<10>")
	)
	(segment
		(start 249.675142 -36.688268)
		(end 246.54256 -36.688268)
		(width 0.1143)
		(layer "In9.Cu")
		(net "UPI_CPU1_CPU0_P1P1_DP<10>")
	)
	(segment
		(start 222.396812 -39.117524)
		(end 211.945728 -39.967408)
		(width 0.1143)
		(layer "In9.Cu")
		(net "UPI_CPU1_CPU0_P1P1_DP<10>")
	)
	(segment
		(start 199.075294 -36.68522)
		(end 195.031106 -37.865558)
		(width 0.1143)
		(layer "In9.Cu")
		(net "UPI_CPU1_CPU0_P1P1_DP<10>")
	)
	(segment
		(start 188.091318 -36.555172)
		(end 182.3466 -37.663882)
		(width 0.1143)
		(layer "In9.Cu")
		(net "UPI_CPU1_CPU0_P1P1_DP<10>")
	)
	(segment
		(start 182.3466 -37.663882)
		(end 180.466492 -38.026594)
		(width 0.1143)
		(layer "In9.Cu")
		(net "UPI_CPU1_CPU0_P1P1_DP<10>")
	)
	(segment
		(start 193.536824 -37.287962)
		(end 193.536824 -37.288216)
		(width 0.1143)
		(layer "In9.Cu")
		(net "UPI_CPU1_CPU0_P1P1_DP<10>")
	)
	(segment
		(start 132.866384 -53.723286)
		(end 132.933186 -53.838856)
		(width 0.0889)
		(layer "In9.Cu")
		(net "UPI_CPU1_CPU0_P1P1_DP<10>")
	)
	(segment
		(start 133.860794 -49.171098)
		(end 132.787898 -50.244248)
		(width 0.0889)
		(layer "In9.Cu")
		(net "UPI_CPU1_CPU0_P1P1_DP<10>")
	)
	(segment
		(start 258.0513 -40.155622)
		(end 249.675142 -36.688268)
		(width 0.1143)
		(layer "In9.Cu")
		(net "UPI_CPU1_CPU0_P1P1_DP<10>")
	)
	(segment
		(start 211.945728 -39.967408)
		(end 199.075294 -36.68522)
		(width 0.1143)
		(layer "In9.Cu")
		(net "UPI_CPU1_CPU0_P1P1_DP<10>")
	)
	(segment
		(start 142.348458 -44.363386)
		(end 136.659874 -46.299628)
		(width 0.1143)
		(layer "In9.Cu")
		(net "UPI_CPU1_CPU0_P1P1_DP<10>")
	)
	(arc
		(start 297.520106 -58.285634)
		(mid 297.322945 -58.233675)
		(end 297.176952 -58.091324)
		(width 0.0889)
		(layer "In9.Cu")
		(net "UPI_CPU1_CPU0_P1P1_DP<10>")
	)
	(arc
		(start 132.866384 -52.73294)
		(mid 132.919883 -52.932838)
		(end 132.866384 -53.132736)
		(width 0.0889)
		(layer "In9.Cu")
		(net "UPI_CPU1_CPU0_P1P1_DP<10>")
	)
	(arc
		(start 296.31513 -57.190386)
		(mid 296.394352 -56.901268)
		(end 296.32148 -56.610504)
		(width 0.0889)
		(layer "In9.Cu")
		(net "UPI_CPU1_CPU0_P1P1_DP<10>")
	)
	(arc
		(start 295.452546 -53.12537)
		(mid 295.403203 -52.928632)
		(end 295.45661 -52.73294)
		(width 0.0889)
		(layer "In9.Cu")
		(net "UPI_CPU1_CPU0_P1P1_DP<10>")
	)
	(arc
		(start 296.31513 -55.209186)
		(mid 296.394352 -54.920068)
		(end 296.32148 -54.629304)
		(width 0.0889)
		(layer "In9.Cu")
		(net "UPI_CPU1_CPU0_P1P1_DP<10>")
	)
	(arc
		(start 296.310304 -56.5912)
		(mid 296.261549 -56.394848)
		(end 296.31513 -56.199786)
		(width 0.0889)
		(layer "In9.Cu")
		(net "UPI_CPU1_CPU0_P1P1_DP<10>")
	)
	(arc
		(start 297.792902 -57.885584)
		(mid 297.993054 -58.085736)
		(end 297.792902 -58.285634)
		(width 0.0889)
		(layer "In9.Cu")
		(net "UPI_CPU1_CPU0_P1P1_DP<10>")
	)
	(arc
		(start 296.31513 -54.218586)
		(mid 296.320384 -53.637078)
		(end 295.82491 -53.332634)
		(width 0.0889)
		(layer "In9.Cu")
		(net "UPI_CPU1_CPU0_P1P1_DP<10>")
	)
	(arc
		(start 295.785286 -53.332634)
		(mid 295.591774 -53.272559)
		(end 295.452546 -53.12537)
		(width 0.0889)
		(layer "In9.Cu")
		(net "UPI_CPU1_CPU0_P1P1_DP<10>")
	)
	(arc
		(start 296.310304 -55.6006)
		(mid 296.261549 -55.404248)
		(end 296.31513 -55.209186)
		(width 0.0889)
		(layer "In9.Cu")
		(net "UPI_CPU1_CPU0_P1P1_DP<10>")
	)
	(arc
		(start 296.310304 -54.61)
		(mid 296.261549 -54.413648)
		(end 296.31513 -54.218586)
		(width 0.0889)
		(layer "In9.Cu")
		(net "UPI_CPU1_CPU0_P1P1_DP<10>")
	)
	(arc
		(start 296.650664 -57.790588)
		(mid 296.312495 -57.58579)
		(end 296.31513 -57.190386)
		(width 0.0889)
		(layer "In9.Cu")
		(net "UPI_CPU1_CPU0_P1P1_DP<10>")
	)
	(arc
		(start 297.17365 -58.085482)
		(mid 296.968029 -57.875559)
		(end 296.686732 -57.790588)
		(width 0.0889)
		(layer "In9.Cu")
		(net "UPI_CPU1_CPU0_P1P1_DP<10>")
	)
	(arc
		(start 132.866384 -51.74234)
		(mid 132.919883 -51.942238)
		(end 132.866384 -52.142136)
		(width 0.0889)
		(layer "In9.Cu")
		(net "UPI_CPU1_CPU0_P1P1_DP<10>")
	)
	(arc
		(start 296.31513 -56.199786)
		(mid 296.394352 -55.910668)
		(end 296.32148 -55.619904)
		(width 0.0889)
		(layer "In9.Cu")
		(net "UPI_CPU1_CPU0_P1P1_DP<10>")
	)
	(arc
		(start 132.860034 -53.143404)
		(mid 132.787236 -53.434167)
		(end 132.866384 -53.723286)
		(width 0.0889)
		(layer "In9.Cu")
		(net "UPI_CPU1_CPU0_P1P1_DP<10>")
	)
	(arc
		(start 132.787898 -51.4731)
		(mid 132.789016 -51.491282)
		(end 132.790692 -51.509422)
		(width 0.0889)
		(layer "In9.Cu")
		(net "UPI_CPU1_CPU0_P1P1_DP<10>")
	)
	(arc
		(start 132.866384 -52.142136)
		(mid 132.787253 -52.437538)
		(end 132.866384 -52.73294)
		(width 0.0889)
		(layer "In9.Cu")
		(net "UPI_CPU1_CPU0_P1P1_DP<10>")
	)
	(arc
		(start 132.790692 -51.509422)
		(mid 132.816348 -51.629841)
		(end 132.866384 -51.74234)
		(width 0.0889)
		(layer "In9.Cu")
		(net "UPI_CPU1_CPU0_P1P1_DP<10>")
	)
	(arc
		(start 132.933186 -53.838856)
		(mid 133.136693 -54.143376)
		(end 133.378194 -54.418738)
		(width 0.0889)
		(layer "In9.Cu")
		(net "UPI_CPU1_CPU0_P1P1_DP<10>")
	)
	(segment
		(start 140.533374 -56.894984)
		(end 141.104874 -56.894984)
		(width 0.1143)
		(layer "F.Cu")
		(net "UPI_CPU1_CPU0_P1P1_DP<0>")
	)
	(segment
		(start 290.93922 -61.352938)
		(end 291.51072 -61.352938)
		(width 0.1143)
		(layer "F.Cu")
		(net "UPI_CPU1_CPU0_P1P1_DP<0>")
	)
	(via
		(at 141.104874 -56.894984)
		(size 0.508)
		(drill 0.254)
		(layers "F.Cu" "B.Cu")
		(net "UPI_CPU1_CPU0_P1P1_DP<0>")
	)
	(via
		(at 291.51072 -61.352938)
		(size 0.508)
		(drill 0.254)
		(layers "F.Cu" "B.Cu")
		(net "UPI_CPU1_CPU0_P1P1_DP<0>")
	)
	(segment
		(start 286.59328 -56.610504)
		(end 286.58693 -56.599836)
		(width 0.0889)
		(layer "In9.Cu")
		(net "UPI_CPU1_CPU0_P1P1_DP<0>")
	)
	(segment
		(start 149.826726 -51.59121)
		(end 149.554946 -52.054252)
		(width 0.1143)
		(layer "In9.Cu")
		(net "UPI_CPU1_CPU0_P1P1_DP<0>")
	)
	(segment
		(start 286.58693 -56.599836)
		(end 286.582104 -56.5912)
		(width 0.0889)
		(layer "In9.Cu")
		(net "UPI_CPU1_CPU0_P1P1_DP<0>")
	)
	(segment
		(start 175.70196 -48.653446)
		(end 175.70069 -48.653954)
		(width 0.1143)
		(layer "In9.Cu")
		(net "UPI_CPU1_CPU0_P1P1_DP<0>")
	)
	(segment
		(start 286.58693 -57.590436)
		(end 286.582104 -57.5818)
		(width 0.0889)
		(layer "In9.Cu")
		(net "UPI_CPU1_CPU0_P1P1_DP<0>")
	)
	(segment
		(start 287.79216 -59.276488)
		(end 287.791906 -59.276234)
		(width 0.0889)
		(layer "In9.Cu")
		(net "UPI_CPU1_CPU0_P1P1_DP<0>")
	)
	(segment
		(start 239.39119 -46.467776)
		(end 236.118908 -44.729654)
		(width 0.1143)
		(layer "In9.Cu")
		(net "UPI_CPU1_CPU0_P1P1_DP<0>")
	)
	(segment
		(start 285.358586 -53.081428)
		(end 281.307286 -53.081428)
		(width 0.1143)
		(layer "In9.Cu")
		(net "UPI_CPU1_CPU0_P1P1_DP<0>")
	)
	(segment
		(start 143.722344 -56.000396)
		(end 142.994126 -56.303418)
		(width 0.0889)
		(layer "In9.Cu")
		(net "UPI_CPU1_CPU0_P1P1_DP<0>")
	)
	(segment
		(start 149.554946 -52.054252)
		(end 144.046448 -55.810658)
		(width 0.1143)
		(layer "In9.Cu")
		(net "UPI_CPU1_CPU0_P1P1_DP<0>")
	)
	(segment
		(start 286.58693 -54.618636)
		(end 286.582104 -54.61)
		(width 0.0889)
		(layer "In9.Cu")
		(net "UPI_CPU1_CPU0_P1P1_DP<0>")
	)
	(segment
		(start 165.071298 -51.796696)
		(end 160.089342 -50.883566)
		(width 0.1143)
		(layer "In9.Cu")
		(net "UPI_CPU1_CPU0_P1P1_DP<0>")
	)
	(segment
		(start 287.791906 -59.276234)
		(end 287.774126 -59.276234)
		(width 0.0889)
		(layer "In9.Cu")
		(net "UPI_CPU1_CPU0_P1P1_DP<0>")
	)
	(segment
		(start 289.95878 -60.795154)
		(end 289.95878 -60.651136)
		(width 0.0889)
		(layer "In9.Cu")
		(net "UPI_CPU1_CPU0_P1P1_DP<0>")
	)
	(segment
		(start 286.519366 -53.51145)
		(end 286.503364 -53.495448)
		(width 0.0889)
		(layer "In9.Cu")
		(net "UPI_CPU1_CPU0_P1P1_DP<0>")
	)
	(segment
		(start 169.529506 -50.767234)
		(end 165.071298 -51.796696)
		(width 0.1143)
		(layer "In9.Cu")
		(net "UPI_CPU1_CPU0_P1P1_DP<0>")
	)
	(segment
		(start 286.95142 -58.780934)
		(end 286.915606 -58.780934)
		(width 0.0889)
		(layer "In9.Cu")
		(net "UPI_CPU1_CPU0_P1P1_DP<0>")
	)
	(segment
		(start 236.118908 -44.729654)
		(end 222.396812 -45.918374)
		(width 0.1143)
		(layer "In9.Cu")
		(net "UPI_CPU1_CPU0_P1P1_DP<0>")
	)
	(segment
		(start 247.794272 -48.19142)
		(end 239.39119 -46.467776)
		(width 0.1143)
		(layer "In9.Cu")
		(net "UPI_CPU1_CPU0_P1P1_DP<0>")
	)
	(segment
		(start 286.59328 -54.629304)
		(end 286.58693 -54.618636)
		(width 0.0889)
		(layer "In9.Cu")
		(net "UPI_CPU1_CPU0_P1P1_DP<0>")
	)
	(segment
		(start 143.749268 -55.934356)
		(end 143.722344 -56.000396)
		(width 0.0889)
		(layer "In9.Cu")
		(net "UPI_CPU1_CPU0_P1P1_DP<0>")
	)
	(segment
		(start 286.59328 -55.619904)
		(end 286.58693 -55.609236)
		(width 0.0889)
		(layer "In9.Cu")
		(net "UPI_CPU1_CPU0_P1P1_DP<0>")
	)
	(segment
		(start 211.483194 -46.863762)
		(end 199.415908 -43.724576)
		(width 0.1143)
		(layer "In9.Cu")
		(net "UPI_CPU1_CPU0_P1P1_DP<0>")
	)
	(segment
		(start 278.4475 -50.221642)
		(end 264.730738 -46.747176)
		(width 0.1143)
		(layer "In9.Cu")
		(net "UPI_CPU1_CPU0_P1P1_DP<0>")
	)
	(segment
		(start 181.926484 -46.602904)
		(end 179.569618 -47.379382)
		(width 0.1143)
		(layer "In9.Cu")
		(net "UPI_CPU1_CPU0_P1P1_DP<0>")
	)
	(segment
		(start 175.70069 -48.653954)
		(end 169.529506 -50.767234)
		(width 0.1143)
		(layer "In9.Cu")
		(net "UPI_CPU1_CPU0_P1P1_DP<0>")
	)
	(segment
		(start 286.58693 -55.609236)
		(end 286.582104 -55.6006)
		(width 0.0889)
		(layer "In9.Cu")
		(net "UPI_CPU1_CPU0_P1P1_DP<0>")
	)
	(segment
		(start 286.592772 -53.63845)
		(end 286.519366 -53.51145)
		(width 0.0889)
		(layer "In9.Cu")
		(net "UPI_CPU1_CPU0_P1P1_DP<0>")
	)
	(segment
		(start 286.503364 -53.495448)
		(end 286.502602 -53.495448)
		(width 0.0889)
		(layer "In9.Cu")
		(net "UPI_CPU1_CPU0_P1P1_DP<0>")
	)
	(segment
		(start 144.046448 -55.810658)
		(end 143.769588 -55.925974)
		(width 0.1143)
		(layer "In9.Cu")
		(net "UPI_CPU1_CPU0_P1P1_DP<0>")
	)
	(segment
		(start 142.994126 -56.303418)
		(end 142.689326 -56.305958)
		(width 0.0889)
		(layer "In9.Cu")
		(net "UPI_CPU1_CPU0_P1P1_DP<0>")
	)
	(segment
		(start 286.139382 -53.132228)
		(end 285.431484 -53.132228)
		(width 0.0889)
		(layer "In9.Cu")
		(net "UPI_CPU1_CPU0_P1P1_DP<0>")
	)
	(segment
		(start 285.431484 -53.132228)
		(end 285.380684 -53.081428)
		(width 0.0889)
		(layer "In9.Cu")
		(net "UPI_CPU1_CPU0_P1P1_DP<0>")
	)
	(segment
		(start 262.387334 -47.409608)
		(end 256.863596 -46.899068)
		(width 0.1143)
		(layer "In9.Cu")
		(net "UPI_CPU1_CPU0_P1P1_DP<0>")
	)
	(segment
		(start 285.380684 -53.081428)
		(end 285.358586 -53.081428)
		(width 0.0889)
		(layer "In9.Cu")
		(net "UPI_CPU1_CPU0_P1P1_DP<0>")
	)
	(segment
		(start 289.724846 -60.56122)
		(end 288.935668 -59.772042)
		(width 0.0889)
		(layer "In9.Cu")
		(net "UPI_CPU1_CPU0_P1P1_DP<0>")
	)
	(segment
		(start 192.7987 -46.293278)
		(end 191.554862 -46.749716)
		(width 0.1143)
		(layer "In9.Cu")
		(net "UPI_CPU1_CPU0_P1P1_DP<0>")
	)
	(segment
		(start 179.569618 -47.379382)
		(end 175.710088 -48.650906)
		(width 0.1143)
		(layer "In9.Cu")
		(net "UPI_CPU1_CPU0_P1P1_DP<0>")
	)
	(segment
		(start 264.730738 -46.747176)
		(end 262.387334 -47.409608)
		(width 0.1143)
		(layer "In9.Cu")
		(net "UPI_CPU1_CPU0_P1P1_DP<0>")
	)
	(segment
		(start 286.59328 -57.601104)
		(end 286.58693 -57.590436)
		(width 0.0889)
		(layer "In9.Cu")
		(net "UPI_CPU1_CPU0_P1P1_DP<0>")
	)
	(segment
		(start 175.706532 -48.651922)
		(end 175.705516 -48.652176)
		(width 0.1143)
		(layer "In9.Cu")
		(net "UPI_CPU1_CPU0_P1P1_DP<0>")
	)
	(segment
		(start 155.80741 -49.110392)
		(end 152.101296 -49.934622)
		(width 0.1143)
		(layer "In9.Cu")
		(net "UPI_CPU1_CPU0_P1P1_DP<0>")
	)
	(segment
		(start 141.162786 -57.29097)
		(end 141.104874 -57.233058)
		(width 0.0889)
		(layer "In9.Cu")
		(net "UPI_CPU1_CPU0_P1P1_DP<0>")
	)
	(segment
		(start 184.82183 -46.706028)
		(end 181.926484 -46.602904)
		(width 0.1143)
		(layer "In9.Cu")
		(net "UPI_CPU1_CPU0_P1P1_DP<0>")
	)
	(segment
		(start 192.798954 -46.293024)
		(end 192.7987 -46.293278)
		(width 0.1143)
		(layer "In9.Cu")
		(net "UPI_CPU1_CPU0_P1P1_DP<0>")
	)
	(segment
		(start 175.710088 -48.650906)
		(end 175.706532 -48.651922)
		(width 0.1143)
		(layer "In9.Cu")
		(net "UPI_CPU1_CPU0_P1P1_DP<0>")
	)
	(segment
		(start 191.554862 -46.749716)
		(end 184.82183 -46.706028)
		(width 0.1143)
		(layer "In9.Cu")
		(net "UPI_CPU1_CPU0_P1P1_DP<0>")
	)
	(segment
		(start 142.13713 -56.799988)
		(end 141.941804 -56.799988)
		(width 0.0889)
		(layer "In9.Cu")
		(net "UPI_CPU1_CPU0_P1P1_DP<0>")
	)
	(segment
		(start 286.502602 -53.495448)
		(end 286.139382 -53.132228)
		(width 0.0889)
		(layer "In9.Cu")
		(net "UPI_CPU1_CPU0_P1P1_DP<0>")
	)
	(segment
		(start 199.415908 -43.724576)
		(end 194.042284 -45.836586)
		(width 0.1143)
		(layer "In9.Cu")
		(net "UPI_CPU1_CPU0_P1P1_DP<0>")
	)
	(segment
		(start 143.769588 -55.925974)
		(end 143.749268 -55.934356)
		(width 0.0889)
		(layer "In9.Cu")
		(net "UPI_CPU1_CPU0_P1P1_DP<0>")
	)
	(segment
		(start 289.95878 -60.651136)
		(end 289.868864 -60.56122)
		(width 0.0889)
		(layer "In9.Cu")
		(net "UPI_CPU1_CPU0_P1P1_DP<0>")
	)
	(segment
		(start 291.521896 -61.752988)
		(end 291.499544 -61.752988)
		(width 0.0889)
		(layer "In9.Cu")
		(net "UPI_CPU1_CPU0_P1P1_DP<0>")
	)
	(segment
		(start 289.868864 -60.56122)
		(end 289.724846 -60.56122)
		(width 0.0889)
		(layer "In9.Cu")
		(net "UPI_CPU1_CPU0_P1P1_DP<0>")
	)
	(segment
		(start 290.42106 -61.257434)
		(end 289.95878 -60.795154)
		(width 0.0889)
		(layer "In9.Cu")
		(net "UPI_CPU1_CPU0_P1P1_DP<0>")
	)
	(segment
		(start 281.307286 -53.081428)
		(end 278.4475 -50.221642)
		(width 0.1143)
		(layer "In9.Cu")
		(net "UPI_CPU1_CPU0_P1P1_DP<0>")
	)
	(segment
		(start 256.227834 -46.85792)
		(end 250.012962 -47.8028)
		(width 0.1143)
		(layer "In9.Cu")
		(net "UPI_CPU1_CPU0_P1P1_DP<0>")
	)
	(segment
		(start 175.705516 -48.652176)
		(end 175.70196 -48.653446)
		(width 0.1143)
		(layer "In9.Cu")
		(net "UPI_CPU1_CPU0_P1P1_DP<0>")
	)
	(segment
		(start 256.863596 -46.899068)
		(end 256.227834 -46.85792)
		(width 0.1143)
		(layer "In9.Cu")
		(net "UPI_CPU1_CPU0_P1P1_DP<0>")
	)
	(segment
		(start 194.042284 -45.836586)
		(end 192.798954 -46.293024)
		(width 0.1143)
		(layer "In9.Cu")
		(net "UPI_CPU1_CPU0_P1P1_DP<0>")
	)
	(segment
		(start 291.51072 -61.352938)
		(end 291.803836 -61.521848)
		(width 0.0889)
		(layer "In9.Cu")
		(net "UPI_CPU1_CPU0_P1P1_DP<0>")
	)
	(segment
		(start 250.012962 -47.8028)
		(end 247.794272 -48.19142)
		(width 0.1143)
		(layer "In9.Cu")
		(net "UPI_CPU1_CPU0_P1P1_DP<0>")
	)
	(segment
		(start 290.665916 -61.257434)
		(end 290.42106 -61.257434)
		(width 0.0889)
		(layer "In9.Cu")
		(net "UPI_CPU1_CPU0_P1P1_DP<0>")
	)
	(segment
		(start 288.935668 -59.772042)
		(end 288.650426 -59.772042)
		(width 0.0889)
		(layer "In9.Cu")
		(net "UPI_CPU1_CPU0_P1P1_DP<0>")
	)
	(segment
		(start 160.089342 -50.883566)
		(end 155.80741 -49.110392)
		(width 0.1143)
		(layer "In9.Cu")
		(net "UPI_CPU1_CPU0_P1P1_DP<0>")
	)
	(segment
		(start 222.396812 -45.918374)
		(end 211.483194 -46.863762)
		(width 0.1143)
		(layer "In9.Cu")
		(net "UPI_CPU1_CPU0_P1P1_DP<0>")
	)
	(segment
		(start 291.803836 -61.521848)
		(end 291.824918 -61.600588)
		(width 0.0889)
		(layer "In9.Cu")
		(net "UPI_CPU1_CPU0_P1P1_DP<0>")
	)
	(segment
		(start 141.104874 -57.233058)
		(end 141.104874 -56.894984)
		(width 0.0889)
		(layer "In9.Cu")
		(net "UPI_CPU1_CPU0_P1P1_DP<0>")
	)
	(segment
		(start 287.814258 -59.276488)
		(end 287.79216 -59.276488)
		(width 0.0889)
		(layer "In9.Cu")
		(net "UPI_CPU1_CPU0_P1P1_DP<0>")
	)
	(segment
		(start 152.101296 -49.934622)
		(end 149.826726 -51.59121)
		(width 0.1143)
		(layer "In9.Cu")
		(net "UPI_CPU1_CPU0_P1P1_DP<0>")
	)
	(arc
		(start 291.824918 -61.600588)
		(mid 291.816202 -61.611025)
		(end 291.807138 -61.621162)
		(width 0.0889)
		(layer "In9.Cu")
		(net "UPI_CPU1_CPU0_P1P1_DP<0>")
	)
	(arc
		(start 287.774126 -59.276234)
		(mid 287.584197 -59.218364)
		(end 287.44545 -59.076336)
		(width 0.0889)
		(layer "In9.Cu")
		(net "UPI_CPU1_CPU0_P1P1_DP<0>")
	)
	(arc
		(start 287.44545 -59.076336)
		(mid 287.236842 -58.864404)
		(end 286.95142 -58.780934)
		(width 0.0889)
		(layer "In9.Cu")
		(net "UPI_CPU1_CPU0_P1P1_DP<0>")
	)
	(arc
		(start 286.582104 -57.5818)
		(mid 286.533349 -57.385448)
		(end 286.58693 -57.190386)
		(width 0.0889)
		(layer "In9.Cu")
		(net "UPI_CPU1_CPU0_P1P1_DP<0>")
	)
	(arc
		(start 142.689326 -56.305958)
		(mid 142.491797 -56.422816)
		(end 142.349474 -56.602884)
		(width 0.0889)
		(layer "In9.Cu")
		(net "UPI_CPU1_CPU0_P1P1_DP<0>")
	)
	(arc
		(start 286.58693 -55.209186)
		(mid 286.666152 -54.920068)
		(end 286.59328 -54.629304)
		(width 0.0889)
		(layer "In9.Cu")
		(net "UPI_CPU1_CPU0_P1P1_DP<0>")
	)
	(arc
		(start 286.58693 -57.190386)
		(mid 286.666152 -56.901268)
		(end 286.59328 -56.610504)
		(width 0.0889)
		(layer "In9.Cu")
		(net "UPI_CPU1_CPU0_P1P1_DP<0>")
	)
	(arc
		(start 286.582104 -55.6006)
		(mid 286.533349 -55.404248)
		(end 286.58693 -55.209186)
		(width 0.0889)
		(layer "In9.Cu")
		(net "UPI_CPU1_CPU0_P1P1_DP<0>")
	)
	(arc
		(start 286.58693 -56.199786)
		(mid 286.666152 -55.910668)
		(end 286.59328 -55.619904)
		(width 0.0889)
		(layer "In9.Cu")
		(net "UPI_CPU1_CPU0_P1P1_DP<0>")
	)
	(arc
		(start 286.58693 -54.218586)
		(mid 286.665905 -53.929297)
		(end 286.592772 -53.63845)
		(width 0.0889)
		(layer "In9.Cu")
		(net "UPI_CPU1_CPU0_P1P1_DP<0>")
	)
	(arc
		(start 286.582104 -56.5912)
		(mid 286.533349 -56.394848)
		(end 286.58693 -56.199786)
		(width 0.0889)
		(layer "In9.Cu")
		(net "UPI_CPU1_CPU0_P1P1_DP<0>")
	)
	(arc
		(start 286.915606 -58.780934)
		(mid 286.582637 -58.573386)
		(end 286.58693 -58.180986)
		(width 0.0889)
		(layer "In9.Cu")
		(net "UPI_CPU1_CPU0_P1P1_DP<0>")
	)
	(arc
		(start 286.58693 -58.180986)
		(mid 286.666152 -57.891868)
		(end 286.59328 -57.601104)
		(width 0.0889)
		(layer "In9.Cu")
		(net "UPI_CPU1_CPU0_P1P1_DP<0>")
	)
	(arc
		(start 142.349474 -56.602884)
		(mid 142.260153 -56.719593)
		(end 142.13713 -56.799988)
		(width 0.0889)
		(layer "In9.Cu")
		(net "UPI_CPU1_CPU0_P1P1_DP<0>")
	)
	(arc
		(start 291.499544 -61.752988)
		(mid 291.305694 -61.696638)
		(end 291.16401 -61.552836)
		(width 0.0889)
		(layer "In9.Cu")
		(net "UPI_CPU1_CPU0_P1P1_DP<0>")
	)
	(arc
		(start 291.753798 -61.670438)
		(mid 291.644347 -61.729963)
		(end 291.521896 -61.752988)
		(width 0.0889)
		(layer "In9.Cu")
		(net "UPI_CPU1_CPU0_P1P1_DP<0>")
	)
	(arc
		(start 291.16401 -61.552836)
		(mid 290.953657 -61.339864)
		(end 290.665916 -61.257434)
		(width 0.0889)
		(layer "In9.Cu")
		(net "UPI_CPU1_CPU0_P1P1_DP<0>")
	)
	(arc
		(start 291.80663 -61.621924)
		(mid 291.781303 -61.647367)
		(end 291.753798 -61.670438)
		(width 0.0889)
		(layer "In9.Cu")
		(net "UPI_CPU1_CPU0_P1P1_DP<0>")
	)
	(arc
		(start 288.30397 -59.571636)
		(mid 288.097216 -59.360817)
		(end 287.814258 -59.276488)
		(width 0.0889)
		(layer "In9.Cu")
		(net "UPI_CPU1_CPU0_P1P1_DP<0>")
	)
	(arc
		(start 141.451584 -57.095136)
		(mid 141.329639 -57.226168)
		(end 141.162786 -57.29097)
		(width 0.0889)
		(layer "In9.Cu")
		(net "UPI_CPU1_CPU0_P1P1_DP<0>")
	)
	(arc
		(start 291.807138 -61.621162)
		(mid 291.806884 -61.621543)
		(end 291.80663 -61.621924)
		(width 0.0889)
		(layer "In9.Cu")
		(net "UPI_CPU1_CPU0_P1P1_DP<0>")
	)
	(arc
		(start 288.650426 -59.772042)
		(mid 288.450315 -59.718288)
		(end 288.30397 -59.571636)
		(width 0.0889)
		(layer "In9.Cu")
		(net "UPI_CPU1_CPU0_P1P1_DP<0>")
	)
	(arc
		(start 141.941804 -56.799988)
		(mid 141.658587 -56.884269)
		(end 141.451584 -57.095136)
		(width 0.0889)
		(layer "In9.Cu")
		(net "UPI_CPU1_CPU0_P1P1_DP<0>")
	)
	(arc
		(start 286.582104 -54.61)
		(mid 286.533349 -54.413648)
		(end 286.58693 -54.218586)
		(width 0.0889)
		(layer "In9.Cu")
		(net "UPI_CPU1_CPU0_P1P1_DP<0>")
	)
	(segment
		(start 294.3733 -58.381138)
		(end 294.9448 -58.381138)
		(width 0.1143)
		(layer "F.Cu")
		(net "UPI_CPU1_CPU0_P1P1_DN<9>")
	)
	(segment
		(start 134.523734 -54.418738)
		(end 135.095234 -54.418738)
		(width 0.1143)
		(layer "F.Cu")
		(net "UPI_CPU1_CPU0_P1P1_DN<9>")
	)
	(via
		(at 135.095234 -54.418738)
		(size 0.508)
		(drill 0.254)
		(layers "F.Cu" "B.Cu")
		(net "UPI_CPU1_CPU0_P1P1_DN<9>")
	)
	(via
		(at 294.9448 -58.381138)
		(size 0.508)
		(drill 0.254)
		(layers "F.Cu" "B.Cu")
		(net "UPI_CPU1_CPU0_P1P1_DN<9>")
	)
	(segment
		(start 137.98169 -47.100744)
		(end 137.8839 -47.292768)
		(width 0.1143)
		(layer "In9.Cu")
		(net "UPI_CPU1_CPU0_P1P1_DN<9>")
	)
	(segment
		(start 261.654036 -41.618408)
		(end 257.62331 -41.071038)
		(width 0.1143)
		(layer "In9.Cu")
		(net "UPI_CPU1_CPU0_P1P1_DN<9>")
	)
	(segment
		(start 133.890004 -53.723286)
		(end 133.885178 -53.731922)
		(width 0.0889)
		(layer "In9.Cu")
		(net "UPI_CPU1_CPU0_P1P1_DN<9>")
	)
	(segment
		(start 135.382 -54.7624)
		(end 135.444992 -54.699408)
		(width 0.0889)
		(layer "In9.Cu")
		(net "UPI_CPU1_CPU0_P1P1_DN<9>")
	)
	(segment
		(start 134.060692 -50.900584)
		(end 134.060692 -51.07813)
		(width 0.0889)
		(layer "In9.Cu")
		(net "UPI_CPU1_CPU0_P1P1_DN<9>")
	)
	(segment
		(start 142.637002 -45.591222)
		(end 141.75105 -45.878496)
		(width 0.1143)
		(layer "In9.Cu")
		(net "UPI_CPU1_CPU0_P1P1_DN<9>")
	)
	(segment
		(start 292.394386 -48.729646)
		(end 290.487862 -47.308008)
		(width 0.1143)
		(layer "In9.Cu")
		(net "UPI_CPU1_CPU0_P1P1_DN<9>")
	)
	(segment
		(start 133.96849 -51.170332)
		(end 133.96849 -51.471068)
		(width 0.0889)
		(layer "In9.Cu")
		(net "UPI_CPU1_CPU0_P1P1_DN<9>")
	)
	(segment
		(start 135.477758 -48.799496)
		(end 135.46963 -48.807624)
		(width 0.0889)
		(layer "In9.Cu")
		(net "UPI_CPU1_CPU0_P1P1_DN<9>")
	)
	(segment
		(start 135.403082 -48.807624)
		(end 135.190992 -49.019714)
		(width 0.0889)
		(layer "In9.Cu")
		(net "UPI_CPU1_CPU0_P1P1_DN<9>")
	)
	(segment
		(start 294.2463 -53.399944)
		(end 294.2463 -52.45481)
		(width 0.0889)
		(layer "In9.Cu")
		(net "UPI_CPU1_CPU0_P1P1_DN<9>")
	)
	(segment
		(start 155.970224 -43.057064)
		(end 145.883884 -45.422058)
		(width 0.1143)
		(layer "In9.Cu")
		(net "UPI_CPU1_CPU0_P1P1_DN<9>")
	)
	(segment
		(start 134.509002 -49.701704)
		(end 134.383272 -49.827434)
		(width 0.0889)
		(layer "In9.Cu")
		(net "UPI_CPU1_CPU0_P1P1_DN<9>")
	)
	(segment
		(start 134.105142 -50.105564)
		(end 133.96849 -50.242216)
		(width 0.0889)
		(layer "In9.Cu")
		(net "UPI_CPU1_CPU0_P1P1_DN<9>")
	)
	(segment
		(start 135.46963 -48.807624)
		(end 135.403082 -48.807624)
		(width 0.0889)
		(layer "In9.Cu")
		(net "UPI_CPU1_CPU0_P1P1_DN<9>")
	)
	(segment
		(start 139.441936 -46.787562)
		(end 139.250166 -46.689518)
		(width 0.1143)
		(layer "In9.Cu")
		(net "UPI_CPU1_CPU0_P1P1_DN<9>")
	)
	(segment
		(start 195.057268 -38.874192)
		(end 191.769746 -37.636958)
		(width 0.1143)
		(layer "In9.Cu")
		(net "UPI_CPU1_CPU0_P1P1_DN<9>")
	)
	(segment
		(start 191.769746 -37.636958)
		(end 188.39434 -37.507164)
		(width 0.1143)
		(layer "In9.Cu")
		(net "UPI_CPU1_CPU0_P1P1_DN<9>")
	)
	(segment
		(start 140.384276 -46.482)
		(end 140.192506 -46.383956)
		(width 0.1143)
		(layer "In9.Cu")
		(net "UPI_CPU1_CPU0_P1P1_DN<9>")
	)
	(segment
		(start 171.879514 -43.808396)
		(end 169.716704 -44.588684)
		(width 0.1143)
		(layer "In9.Cu")
		(net "UPI_CPU1_CPU0_P1P1_DN<9>")
	)
	(segment
		(start 169.716704 -44.588684)
		(end 169.220642 -44.767754)
		(width 0.1143)
		(layer "In9.Cu")
		(net "UPI_CPU1_CPU0_P1P1_DN<9>")
	)
	(segment
		(start 137.557256 -47.398686)
		(end 137.365486 -47.300642)
		(width 0.1143)
		(layer "In9.Cu")
		(net "UPI_CPU1_CPU0_P1P1_DN<9>")
	)
	(segment
		(start 295.29151 -57.590436)
		(end 295.296336 -57.5818)
		(width 0.0889)
		(layer "In9.Cu")
		(net "UPI_CPU1_CPU0_P1P1_DN<9>")
	)
	(segment
		(start 294.202866 -51.114198)
		(end 292.760146 -49.188878)
		(width 0.1143)
		(layer "In9.Cu")
		(net "UPI_CPU1_CPU0_P1P1_DN<9>")
	)
	(segment
		(start 167.865806 -45.256704)
		(end 164.903912 -45.816012)
		(width 0.1143)
		(layer "In9.Cu")
		(net "UPI_CPU1_CPU0_P1P1_DN<9>")
	)
	(segment
		(start 134.625334 -49.701704)
		(end 134.509002 -49.701704)
		(width 0.0889)
		(layer "In9.Cu")
		(net "UPI_CPU1_CPU0_P1P1_DN<9>")
	)
	(segment
		(start 135.328914 -54.418992)
		(end 135.095234 -54.418738)
		(width 0.0889)
		(layer "In9.Cu")
		(net "UPI_CPU1_CPU0_P1P1_DN<9>")
	)
	(segment
		(start 138.82624 -46.987206)
		(end 138.499596 -47.093124)
		(width 0.1143)
		(layer "In9.Cu")
		(net "UPI_CPU1_CPU0_P1P1_DN<9>")
	)
	(segment
		(start 142.979394 -45.573442)
		(end 142.637002 -45.591222)
		(width 0.1143)
		(layer "In9.Cu")
		(net "UPI_CPU1_CPU0_P1P1_DN<9>")
	)
	(segment
		(start 134.060692 -51.07813)
		(end 133.96849 -51.170332)
		(width 0.0889)
		(layer "In9.Cu")
		(net "UPI_CPU1_CPU0_P1P1_DN<9>")
	)
	(segment
		(start 173.707552 -43.067732)
		(end 171.887134 -43.805094)
		(width 0.1143)
		(layer "In9.Cu")
		(net "UPI_CPU1_CPU0_P1P1_DN<9>")
	)
	(segment
		(start 143.48206 -45.699934)
		(end 143.139414 -45.717714)
		(width 0.1143)
		(layer "In9.Cu")
		(net "UPI_CPU1_CPU0_P1P1_DN<9>")
	)
	(segment
		(start 143.139414 -45.717714)
		(end 142.979394 -45.573442)
		(width 0.1143)
		(layer "In9.Cu")
		(net "UPI_CPU1_CPU0_P1P1_DN<9>")
	)
	(segment
		(start 188.39434 -37.507164)
		(end 180.578252 -39.007796)
		(width 0.1143)
		(layer "In9.Cu")
		(net "UPI_CPU1_CPU0_P1P1_DN<9>")
	)
	(segment
		(start 246.798338 -37.617654)
		(end 242.98783 -39.849806)
		(width 0.1143)
		(layer "In9.Cu")
		(net "UPI_CPU1_CPU0_P1P1_DN<9>")
	)
	(segment
		(start 295.28516 -57.601104)
		(end 295.29151 -57.590436)
		(width 0.0889)
		(layer "In9.Cu")
		(net "UPI_CPU1_CPU0_P1P1_DN<9>")
	)
	(segment
		(start 222.396812 -40.129968)
		(end 212.206332 -40.992806)
		(width 0.1143)
		(layer "In9.Cu")
		(net "UPI_CPU1_CPU0_P1P1_DN<9>")
	)
	(segment
		(start 141.326616 -46.176438)
		(end 141.134846 -46.078394)
		(width 0.1143)
		(layer "In9.Cu")
		(net "UPI_CPU1_CPU0_P1P1_DN<9>")
	)
	(segment
		(start 294.202866 -52.4002)
		(end 294.202866 -51.114198)
		(width 0.1143)
		(layer "In9.Cu")
		(net "UPI_CPU1_CPU0_P1P1_DN<9>")
	)
	(segment
		(start 133.890004 -53.132736)
		(end 133.896354 -53.143404)
		(width 0.0889)
		(layer "In9.Cu")
		(net "UPI_CPU1_CPU0_P1P1_DN<9>")
	)
	(segment
		(start 134.244842 -50.105564)
		(end 134.105142 -50.105564)
		(width 0.0889)
		(layer "In9.Cu")
		(net "UPI_CPU1_CPU0_P1P1_DN<9>")
	)
	(segment
		(start 242.98783 -39.849806)
		(end 240.588038 -39.471854)
		(width 0.1143)
		(layer "In9.Cu")
		(net "UPI_CPU1_CPU0_P1P1_DN<9>")
	)
	(segment
		(start 137.8839 -47.292768)
		(end 137.557256 -47.398686)
		(width 0.1143)
		(layer "In9.Cu")
		(net "UPI_CPU1_CPU0_P1P1_DN<9>")
	)
	(segment
		(start 143.626332 -45.53966)
		(end 143.48206 -45.699934)
		(width 0.1143)
		(layer "In9.Cu")
		(net "UPI_CPU1_CPU0_P1P1_DN<9>")
	)
	(segment
		(start 295.237916 -58.550048)
		(end 295.316656 -58.528712)
		(width 0.0889)
		(layer "In9.Cu")
		(net "UPI_CPU1_CPU0_P1P1_DN<9>")
	)
	(segment
		(start 257.62331 -41.071038)
		(end 249.284998 -37.617654)
		(width 0.1143)
		(layer "In9.Cu")
		(net "UPI_CPU1_CPU0_P1P1_DN<9>")
	)
	(segment
		(start 212.206332 -40.992806)
		(end 199.143874 -37.716206)
		(width 0.1143)
		(layer "In9.Cu")
		(net "UPI_CPU1_CPU0_P1P1_DN<9>")
	)
	(segment
		(start 140.192506 -46.383956)
		(end 139.86637 -46.48962)
		(width 0.1143)
		(layer "In9.Cu")
		(net "UPI_CPU1_CPU0_P1P1_DN<9>")
	)
	(segment
		(start 133.96849 -50.808382)
		(end 134.060692 -50.900584)
		(width 0.0889)
		(layer "In9.Cu")
		(net "UPI_CPU1_CPU0_P1P1_DN<9>")
	)
	(segment
		(start 134.787132 -49.423574)
		(end 134.787132 -49.539906)
		(width 0.0889)
		(layer "In9.Cu")
		(net "UPI_CPU1_CPU0_P1P1_DN<9>")
	)
	(segment
		(start 139.86637 -46.48962)
		(end 139.76858 -46.681644)
		(width 0.1143)
		(layer "In9.Cu")
		(net "UPI_CPU1_CPU0_P1P1_DN<9>")
	)
	(segment
		(start 294.2463 -52.45481)
		(end 294.202866 -52.411376)
		(width 0.0889)
		(layer "In9.Cu")
		(net "UPI_CPU1_CPU0_P1P1_DN<9>")
	)
	(segment
		(start 171.887134 -43.805094)
		(end 171.879514 -43.808396)
		(width 0.1143)
		(layer "In9.Cu")
		(net "UPI_CPU1_CPU0_P1P1_DN<9>")
	)
	(segment
		(start 141.134846 -46.078394)
		(end 140.80871 -46.184058)
		(width 0.1143)
		(layer "In9.Cu")
		(net "UPI_CPU1_CPU0_P1P1_DN<9>")
	)
	(segment
		(start 160.985962 -44.988734)
		(end 160.411668 -44.882562)
		(width 0.1143)
		(layer "In9.Cu")
		(net "UPI_CPU1_CPU0_P1P1_DN<9>")
	)
	(segment
		(start 135.190992 -49.019714)
		(end 135.190992 -49.11979)
		(width 0.0889)
		(layer "In9.Cu")
		(net "UPI_CPU1_CPU0_P1P1_DN<9>")
	)
	(segment
		(start 133.890004 -51.742086)
		(end 133.885178 -51.750722)
		(width 0.0889)
		(layer "In9.Cu")
		(net "UPI_CPU1_CPU0_P1P1_DN<9>")
	)
	(segment
		(start 294.959786 -54.018688)
		(end 294.931846 -54.018688)
		(width 0.0889)
		(layer "In9.Cu")
		(net "UPI_CPU1_CPU0_P1P1_DN<9>")
	)
	(segment
		(start 138.92403 -46.795182)
		(end 138.82624 -46.987206)
		(width 0.1143)
		(layer "In9.Cu")
		(net "UPI_CPU1_CPU0_P1P1_DN<9>")
	)
	(segment
		(start 134.383272 -49.967134)
		(end 134.244842 -50.105564)
		(width 0.0889)
		(layer "In9.Cu")
		(net "UPI_CPU1_CPU0_P1P1_DN<9>")
	)
	(segment
		(start 134.221728 -54.323234)
		(end 134.254494 -54.323234)
		(width 0.0889)
		(layer "In9.Cu")
		(net "UPI_CPU1_CPU0_P1P1_DN<9>")
	)
	(segment
		(start 169.220642 -44.767754)
		(end 167.865806 -45.256704)
		(width 0.1143)
		(layer "In9.Cu")
		(net "UPI_CPU1_CPU0_P1P1_DN<9>")
	)
	(segment
		(start 290.487862 -47.308008)
		(end 288.039556 -46.499272)
		(width 0.1143)
		(layer "In9.Cu")
		(net "UPI_CPU1_CPU0_P1P1_DN<9>")
	)
	(segment
		(start 141.65326 -46.07052)
		(end 141.326616 -46.176438)
		(width 0.1143)
		(layer "In9.Cu")
		(net "UPI_CPU1_CPU0_P1P1_DN<9>")
	)
	(segment
		(start 295.28516 -55.619904)
		(end 295.29151 -55.609236)
		(width 0.0889)
		(layer "In9.Cu")
		(net "UPI_CPU1_CPU0_P1P1_DN<9>")
	)
	(segment
		(start 135.084058 -54.818788)
		(end 135.245856 -54.818788)
		(width 0.0889)
		(layer "In9.Cu")
		(net "UPI_CPU1_CPU0_P1P1_DN<9>")
	)
	(segment
		(start 164.903912 -45.816012)
		(end 160.985962 -44.988734)
		(width 0.1143)
		(layer "In9.Cu")
		(net "UPI_CPU1_CPU0_P1P1_DN<9>")
	)
	(segment
		(start 135.911082 -48.366172)
		(end 135.477758 -48.799496)
		(width 0.1143)
		(layer "In9.Cu")
		(net "UPI_CPU1_CPU0_P1P1_DN<9>")
	)
	(segment
		(start 240.588038 -39.471854)
		(end 236.544866 -38.93185)
		(width 0.1143)
		(layer "In9.Cu")
		(net "UPI_CPU1_CPU0_P1P1_DN<9>")
	)
	(segment
		(start 138.307826 -46.99508)
		(end 137.98169 -47.100744)
		(width 0.1143)
		(layer "In9.Cu")
		(net "UPI_CPU1_CPU0_P1P1_DN<9>")
	)
	(segment
		(start 295.29151 -56.599836)
		(end 295.296336 -56.5912)
		(width 0.0889)
		(layer "In9.Cu")
		(net "UPI_CPU1_CPU0_P1P1_DN<9>")
	)
	(segment
		(start 295.29151 -54.618636)
		(end 295.296336 -54.61)
		(width 0.0889)
		(layer "In9.Cu")
		(net "UPI_CPU1_CPU0_P1P1_DN<9>")
	)
	(segment
		(start 264.606278 -40.78224)
		(end 261.654036 -41.618408)
		(width 0.1143)
		(layer "In9.Cu")
		(net "UPI_CPU1_CPU0_P1P1_DN<9>")
	)
	(segment
		(start 141.75105 -45.878496)
		(end 141.65326 -46.07052)
		(width 0.1143)
		(layer "In9.Cu")
		(net "UPI_CPU1_CPU0_P1P1_DN<9>")
	)
	(segment
		(start 295.29151 -55.609236)
		(end 295.296336 -55.6006)
		(width 0.0889)
		(layer "In9.Cu")
		(net "UPI_CPU1_CPU0_P1P1_DN<9>")
	)
	(segment
		(start 134.383272 -49.827434)
		(end 134.383272 -49.967134)
		(width 0.0889)
		(layer "In9.Cu")
		(net "UPI_CPU1_CPU0_P1P1_DN<9>")
	)
	(segment
		(start 139.250166 -46.689518)
		(end 138.92403 -46.795182)
		(width 0.1143)
		(layer "In9.Cu")
		(net "UPI_CPU1_CPU0_P1P1_DN<9>")
	)
	(segment
		(start 137.03935 -47.406306)
		(end 136.877552 -47.467774)
		(width 0.1143)
		(layer "In9.Cu")
		(net "UPI_CPU1_CPU0_P1P1_DN<9>")
	)
	(segment
		(start 160.411668 -44.882562)
		(end 155.970224 -43.057064)
		(width 0.1143)
		(layer "In9.Cu")
		(net "UPI_CPU1_CPU0_P1P1_DN<9>")
	)
	(segment
		(start 136.877552 -47.467774)
		(end 135.911082 -48.366172)
		(width 0.1143)
		(layer "In9.Cu")
		(net "UPI_CPU1_CPU0_P1P1_DN<9>")
	)
	(segment
		(start 133.96849 -50.242216)
		(end 133.96849 -50.808382)
		(width 0.0889)
		(layer "In9.Cu")
		(net "UPI_CPU1_CPU0_P1P1_DN<9>")
	)
	(segment
		(start 288.039556 -46.499272)
		(end 283.991558 -45.447966)
		(width 0.1143)
		(layer "In9.Cu")
		(net "UPI_CPU1_CPU0_P1P1_DN<9>")
	)
	(segment
		(start 236.544866 -38.93185)
		(end 222.396812 -40.129968)
		(width 0.1143)
		(layer "In9.Cu")
		(net "UPI_CPU1_CPU0_P1P1_DN<9>")
	)
	(segment
		(start 292.760146 -49.188878)
		(end 292.394386 -48.729646)
		(width 0.1143)
		(layer "In9.Cu")
		(net "UPI_CPU1_CPU0_P1P1_DN<9>")
	)
	(segment
		(start 138.499596 -47.093124)
		(end 138.307826 -46.99508)
		(width 0.1143)
		(layer "In9.Cu")
		(net "UPI_CPU1_CPU0_P1P1_DN<9>")
	)
	(segment
		(start 283.991558 -45.447966)
		(end 264.606278 -40.78224)
		(width 0.1143)
		(layer "In9.Cu")
		(net "UPI_CPU1_CPU0_P1P1_DN<9>")
	)
	(segment
		(start 249.284998 -37.617654)
		(end 246.798338 -37.617654)
		(width 0.1143)
		(layer "In9.Cu")
		(net "UPI_CPU1_CPU0_P1P1_DN<9>")
	)
	(segment
		(start 139.76858 -46.681644)
		(end 139.441936 -46.787562)
		(width 0.1143)
		(layer "In9.Cu")
		(net "UPI_CPU1_CPU0_P1P1_DN<9>")
	)
	(segment
		(start 135.012938 -49.297844)
		(end 134.912862 -49.297844)
		(width 0.0889)
		(layer "In9.Cu")
		(net "UPI_CPU1_CPU0_P1P1_DN<9>")
	)
	(segment
		(start 140.71092 -46.376082)
		(end 140.384276 -46.482)
		(width 0.1143)
		(layer "In9.Cu")
		(net "UPI_CPU1_CPU0_P1P1_DN<9>")
	)
	(segment
		(start 180.578252 -39.007796)
		(end 173.707552 -43.067732)
		(width 0.1143)
		(layer "In9.Cu")
		(net "UPI_CPU1_CPU0_P1P1_DN<9>")
	)
	(segment
		(start 199.143874 -37.716206)
		(end 195.057268 -38.874192)
		(width 0.1143)
		(layer "In9.Cu")
		(net "UPI_CPU1_CPU0_P1P1_DN<9>")
	)
	(segment
		(start 294.9448 -58.381138)
		(end 295.237916 -58.550048)
		(width 0.0889)
		(layer "In9.Cu")
		(net "UPI_CPU1_CPU0_P1P1_DN<9>")
	)
	(segment
		(start 294.43299 -53.723286)
		(end 294.2463 -53.399944)
		(width 0.0889)
		(layer "In9.Cu")
		(net "UPI_CPU1_CPU0_P1P1_DN<9>")
	)
	(segment
		(start 135.190992 -49.11979)
		(end 135.012938 -49.297844)
		(width 0.0889)
		(layer "In9.Cu")
		(net "UPI_CPU1_CPU0_P1P1_DN<9>")
	)
	(segment
		(start 295.28516 -56.610504)
		(end 295.29151 -56.599836)
		(width 0.0889)
		(layer "In9.Cu")
		(net "UPI_CPU1_CPU0_P1P1_DN<9>")
	)
	(segment
		(start 140.80871 -46.184058)
		(end 140.71092 -46.376082)
		(width 0.1143)
		(layer "In9.Cu")
		(net "UPI_CPU1_CPU0_P1P1_DN<9>")
	)
	(segment
		(start 294.202866 -52.411376)
		(end 294.202866 -52.4002)
		(width 0.0889)
		(layer "In9.Cu")
		(net "UPI_CPU1_CPU0_P1P1_DN<9>")
	)
	(segment
		(start 134.787132 -49.539906)
		(end 134.625334 -49.701704)
		(width 0.0889)
		(layer "In9.Cu")
		(net "UPI_CPU1_CPU0_P1P1_DN<9>")
	)
	(segment
		(start 295.28516 -54.629304)
		(end 295.29151 -54.618636)
		(width 0.0889)
		(layer "In9.Cu")
		(net "UPI_CPU1_CPU0_P1P1_DN<9>")
	)
	(segment
		(start 134.912862 -49.297844)
		(end 134.787132 -49.423574)
		(width 0.0889)
		(layer "In9.Cu")
		(net "UPI_CPU1_CPU0_P1P1_DN<9>")
	)
	(segment
		(start 137.365486 -47.300642)
		(end 137.03935 -47.406306)
		(width 0.1143)
		(layer "In9.Cu")
		(net "UPI_CPU1_CPU0_P1P1_DN<9>")
	)
	(segment
		(start 145.883884 -45.422058)
		(end 143.626332 -45.53966)
		(width 0.1143)
		(layer "In9.Cu")
		(net "UPI_CPU1_CPU0_P1P1_DN<9>")
	)
	(arc
		(start 133.885178 -53.731922)
		(mid 133.888925 -54.121178)
		(end 134.221728 -54.323234)
		(width 0.0889)
		(layer "In9.Cu")
		(net "UPI_CPU1_CPU0_P1P1_DN<9>")
	)
	(arc
		(start 295.296336 -55.6006)
		(mid 295.345091 -55.404248)
		(end 295.29151 -55.209186)
		(width 0.0889)
		(layer "In9.Cu")
		(net "UPI_CPU1_CPU0_P1P1_DN<9>")
	)
	(arc
		(start 295.29151 -57.190386)
		(mid 295.212288 -56.901268)
		(end 295.28516 -56.610504)
		(width 0.0889)
		(layer "In9.Cu")
		(net "UPI_CPU1_CPU0_P1P1_DN<9>")
	)
	(arc
		(start 133.890004 -52.142136)
		(mid 133.969135 -52.437538)
		(end 133.890004 -52.73294)
		(width 0.0889)
		(layer "In9.Cu")
		(net "UPI_CPU1_CPU0_P1P1_DN<9>")
	)
	(arc
		(start 133.96849 -51.471068)
		(mid 133.945652 -51.611326)
		(end 133.890004 -51.742086)
		(width 0.0889)
		(layer "In9.Cu")
		(net "UPI_CPU1_CPU0_P1P1_DN<9>")
	)
	(arc
		(start 295.316656 -58.528712)
		(mid 295.343899 -58.351973)
		(end 295.29151 -58.180986)
		(width 0.0889)
		(layer "In9.Cu")
		(net "UPI_CPU1_CPU0_P1P1_DN<9>")
	)
	(arc
		(start 295.29151 -56.199786)
		(mid 295.212288 -55.910668)
		(end 295.28516 -55.619904)
		(width 0.0889)
		(layer "In9.Cu")
		(net "UPI_CPU1_CPU0_P1P1_DN<9>")
	)
	(arc
		(start 134.748524 -54.618636)
		(mid 134.890207 -54.76244)
		(end 135.084058 -54.818788)
		(width 0.0889)
		(layer "In9.Cu")
		(net "UPI_CPU1_CPU0_P1P1_DN<9>")
	)
	(arc
		(start 134.254494 -54.323234)
		(mid 134.539918 -54.406701)
		(end 134.748524 -54.618636)
		(width 0.0889)
		(layer "In9.Cu")
		(net "UPI_CPU1_CPU0_P1P1_DN<9>")
	)
	(arc
		(start 135.245856 -54.818788)
		(mid 135.319535 -54.804132)
		(end 135.382 -54.7624)
		(width 0.0889)
		(layer "In9.Cu")
		(net "UPI_CPU1_CPU0_P1P1_DN<9>")
	)
	(arc
		(start 295.296336 -56.5912)
		(mid 295.345091 -56.394848)
		(end 295.29151 -56.199786)
		(width 0.0889)
		(layer "In9.Cu")
		(net "UPI_CPU1_CPU0_P1P1_DN<9>")
	)
	(arc
		(start 135.444992 -54.699408)
		(mid 135.480503 -54.520475)
		(end 135.328914 -54.418992)
		(width 0.0889)
		(layer "In9.Cu")
		(net "UPI_CPU1_CPU0_P1P1_DN<9>")
	)
	(arc
		(start 133.896354 -53.143404)
		(mid 133.969152 -53.434167)
		(end 133.890004 -53.723286)
		(width 0.0889)
		(layer "In9.Cu")
		(net "UPI_CPU1_CPU0_P1P1_DN<9>")
	)
	(arc
		(start 133.885178 -51.750722)
		(mid 133.836423 -51.947074)
		(end 133.890004 -52.142136)
		(width 0.0889)
		(layer "In9.Cu")
		(net "UPI_CPU1_CPU0_P1P1_DN<9>")
	)
	(arc
		(start 295.29151 -58.180986)
		(mid 295.212288 -57.891868)
		(end 295.28516 -57.601104)
		(width 0.0889)
		(layer "In9.Cu")
		(net "UPI_CPU1_CPU0_P1P1_DN<9>")
	)
	(arc
		(start 295.29151 -55.209186)
		(mid 295.212288 -54.920068)
		(end 295.28516 -54.629304)
		(width 0.0889)
		(layer "In9.Cu")
		(net "UPI_CPU1_CPU0_P1P1_DN<9>")
	)
	(arc
		(start 133.890004 -52.73294)
		(mid 133.836505 -52.932838)
		(end 133.890004 -53.132736)
		(width 0.0889)
		(layer "In9.Cu")
		(net "UPI_CPU1_CPU0_P1P1_DN<9>")
	)
	(arc
		(start 294.931846 -54.018688)
		(mid 294.643701 -53.936369)
		(end 294.43299 -53.723286)
		(width 0.0889)
		(layer "In9.Cu")
		(net "UPI_CPU1_CPU0_P1P1_DN<9>")
	)
	(arc
		(start 295.296336 -57.5818)
		(mid 295.345091 -57.385448)
		(end 295.29151 -57.190386)
		(width 0.0889)
		(layer "In9.Cu")
		(net "UPI_CPU1_CPU0_P1P1_DN<9>")
	)
	(arc
		(start 295.296336 -54.61)
		(mid 295.292589 -54.220744)
		(end 294.959786 -54.018688)
		(width 0.0889)
		(layer "In9.Cu")
		(net "UPI_CPU1_CPU0_P1P1_DN<9>")
	)
	(segment
		(start 293.51478 -57.885584)
		(end 294.08628 -57.885584)
		(width 0.1143)
		(layer "F.Cu")
		(net "UPI_CPU1_CPU0_P1P1_DN<8>")
	)
	(segment
		(start 134.523734 -53.427884)
		(end 135.095234 -53.427884)
		(width 0.1143)
		(layer "F.Cu")
		(net "UPI_CPU1_CPU0_P1P1_DN<8>")
	)
	(via
		(at 294.08628 -57.885584)
		(size 0.508)
		(drill 0.254)
		(layers "F.Cu" "B.Cu")
		(net "UPI_CPU1_CPU0_P1P1_DN<8>")
	)
	(via
		(at 135.095234 -53.427884)
		(size 0.508)
		(drill 0.254)
		(layers "F.Cu" "B.Cu")
		(net "UPI_CPU1_CPU0_P1P1_DN<8>")
	)
	(segment
		(start 264.466832 -41.488868)
		(end 261.96798 -42.213784)
		(width 0.1143)
		(layer "In9.Cu")
		(net "UPI_CPU1_CPU0_P1P1_DN<8>")
	)
	(segment
		(start 134.754874 -53.217318)
		(end 134.748524 -53.227986)
		(width 0.0889)
		(layer "In9.Cu")
		(net "UPI_CPU1_CPU0_P1P1_DN<8>")
	)
	(segment
		(start 294.43299 -56.695086)
		(end 294.42664 -56.684418)
		(width 0.0889)
		(layer "In9.Cu")
		(net "UPI_CPU1_CPU0_P1P1_DN<8>")
	)
	(segment
		(start 213.576916 -41.616376)
		(end 212.366606 -41.74617)
		(width 0.1143)
		(layer "In9.Cu")
		(net "UPI_CPU1_CPU0_P1P1_DN<8>")
	)
	(segment
		(start 236.618018 -39.589456)
		(end 213.576916 -41.616376)
		(width 0.1143)
		(layer "In9.Cu")
		(net "UPI_CPU1_CPU0_P1P1_DN<8>")
	)
	(segment
		(start 141.058392 -47.200312)
		(end 140.86459 -47.105824)
		(width 0.1143)
		(layer "In9.Cu")
		(net "UPI_CPU1_CPU0_P1P1_DN<8>")
	)
	(segment
		(start 188.288676 -39.433246)
		(end 182.24246 -41.082214)
		(width 0.1143)
		(layer "In9.Cu")
		(net "UPI_CPU1_CPU0_P1P1_DN<8>")
	)
	(segment
		(start 140.86459 -47.105824)
		(end 140.540486 -47.217584)
		(width 0.1143)
		(layer "In9.Cu")
		(net "UPI_CPU1_CPU0_P1P1_DN<8>")
	)
	(segment
		(start 261.96798 -42.213784)
		(end 261.720076 -42.293032)
		(width 0.1143)
		(layer "In9.Cu")
		(net "UPI_CPU1_CPU0_P1P1_DN<8>")
	)
	(segment
		(start 243.182648 -40.548052)
		(end 236.618018 -39.589456)
		(width 0.1143)
		(layer "In9.Cu")
		(net "UPI_CPU1_CPU0_P1P1_DN<8>")
	)
	(segment
		(start 155.752038 -43.920664)
		(end 144.421098 -46.428914)
		(width 0.1143)
		(layer "In9.Cu")
		(net "UPI_CPU1_CPU0_P1P1_DN<8>")
	)
	(segment
		(start 257.380486 -41.693338)
		(end 249.086878 -38.258496)
		(width 0.1143)
		(layer "In9.Cu")
		(net "UPI_CPU1_CPU0_P1P1_DN<8>")
	)
	(segment
		(start 135.734552 -50.949352)
		(end 135.6868 -50.997104)
		(width 0.0889)
		(layer "In9.Cu")
		(net "UPI_CPU1_CPU0_P1P1_DN<8>")
	)
	(segment
		(start 140.446252 -47.41164)
		(end 140.121894 -47.5234)
		(width 0.1143)
		(layer "In9.Cu")
		(net "UPI_CPU1_CPU0_P1P1_DN<8>")
	)
	(segment
		(start 156.310076 -43.916854)
		(end 156.12618 -43.84548)
		(width 0.1143)
		(layer "In9.Cu")
		(net "UPI_CPU1_CPU0_P1P1_DN<8>")
	)
	(segment
		(start 292.72357 -50.691288)
		(end 292.756844 -50.478436)
		(width 0.1143)
		(layer "In9.Cu")
		(net "UPI_CPU1_CPU0_P1P1_DN<8>")
	)
	(segment
		(start 249.086878 -38.258496)
		(end 246.984774 -38.258496)
		(width 0.1143)
		(layer "In9.Cu")
		(net "UPI_CPU1_CPU0_P1P1_DN<8>")
	)
	(segment
		(start 134.743698 -52.6288)
		(end 134.748524 -52.637436)
		(width 0.0889)
		(layer "In9.Cu")
		(net "UPI_CPU1_CPU0_P1P1_DN<8>")
	)
	(segment
		(start 293.18839 -51.77409)
		(end 293.34079 -51.62169)
		(width 0.1143)
		(layer "In9.Cu")
		(net "UPI_CPU1_CPU0_P1P1_DN<8>")
	)
	(segment
		(start 293.34079 -51.27879)
		(end 293.13886 -51.00193)
		(width 0.1143)
		(layer "In9.Cu")
		(net "UPI_CPU1_CPU0_P1P1_DN<8>")
	)
	(segment
		(start 292.9255 -50.968656)
		(end 292.72357 -50.691288)
		(width 0.1143)
		(layer "In9.Cu")
		(net "UPI_CPU1_CPU0_P1P1_DN<8>")
	)
	(segment
		(start 293.34079 -51.62169)
		(end 293.34079 -51.27879)
		(width 0.1143)
		(layer "In9.Cu")
		(net "UPI_CPU1_CPU0_P1P1_DN<8>")
	)
	(segment
		(start 141.476984 -46.894496)
		(end 141.38275 -47.088552)
		(width 0.1143)
		(layer "In9.Cu")
		(net "UPI_CPU1_CPU0_P1P1_DN<8>")
	)
	(segment
		(start 292.234112 -49.762156)
		(end 291.920422 -49.379632)
		(width 0.1143)
		(layer "In9.Cu")
		(net "UPI_CPU1_CPU0_P1P1_DN<8>")
	)
	(segment
		(start 135.113014 -52.037488)
		(end 135.080248 -52.037488)
		(width 0.0889)
		(layer "In9.Cu")
		(net "UPI_CPU1_CPU0_P1P1_DN<8>")
	)
	(segment
		(start 293.34079 -52.26939)
		(end 293.18839 -52.11699)
		(width 0.1143)
		(layer "In9.Cu")
		(net "UPI_CPU1_CPU0_P1P1_DN<8>")
	)
	(segment
		(start 291.369242 -49.127156)
		(end 291.103304 -48.910494)
		(width 0.1143)
		(layer "In9.Cu")
		(net "UPI_CPU1_CPU0_P1P1_DN<8>")
	)
	(segment
		(start 292.756844 -50.478436)
		(end 292.234112 -49.762156)
		(width 0.1143)
		(layer "In9.Cu")
		(net "UPI_CPU1_CPU0_P1P1_DN<8>")
	)
	(segment
		(start 135.6868 -50.997104)
		(end 135.6868 -51.60391)
		(width 0.0889)
		(layer "In9.Cu")
		(net "UPI_CPU1_CPU0_P1P1_DN<8>")
	)
	(segment
		(start 138.100816 -48.22063)
		(end 137.907014 -48.126142)
		(width 0.1143)
		(layer "In9.Cu")
		(net "UPI_CPU1_CPU0_P1P1_DN<8>")
	)
	(segment
		(start 144.421098 -46.428914)
		(end 141.801088 -46.782736)
		(width 0.1143)
		(layer "In9.Cu")
		(net "UPI_CPU1_CPU0_P1P1_DN<8>")
	)
	(segment
		(start 168.185338 -45.866812)
		(end 164.692584 -46.491906)
		(width 0.1143)
		(layer "In9.Cu")
		(net "UPI_CPU1_CPU0_P1P1_DN<8>")
	)
	(segment
		(start 134.802118 -53.596794)
		(end 135.095234 -53.427884)
		(width 0.0889)
		(layer "In9.Cu")
		(net "UPI_CPU1_CPU0_P1P1_DN<8>")
	)
	(segment
		(start 261.720076 -42.293032)
		(end 257.380486 -41.693338)
		(width 0.1143)
		(layer "In9.Cu")
		(net "UPI_CPU1_CPU0_P1P1_DN<8>")
	)
	(segment
		(start 293.56812 -54.629304)
		(end 293.57447 -54.618636)
		(width 0.0889)
		(layer "In9.Cu")
		(net "UPI_CPU1_CPU0_P1P1_DN<8>")
	)
	(segment
		(start 139.13612 -47.863506)
		(end 138.942318 -47.769018)
		(width 0.1143)
		(layer "In9.Cu")
		(net "UPI_CPU1_CPU0_P1P1_DN<8>")
	)
	(segment
		(start 138.425174 -48.10887)
		(end 138.100816 -48.22063)
		(width 0.1143)
		(layer "In9.Cu")
		(net "UPI_CPU1_CPU0_P1P1_DN<8>")
	)
	(segment
		(start 164.692584 -46.491906)
		(end 159.928306 -45.43425)
		(width 0.1143)
		(layer "In9.Cu")
		(net "UPI_CPU1_CPU0_P1P1_DN<8>")
	)
	(segment
		(start 293.39159 -53.253132)
		(end 293.34079 -53.202332)
		(width 0.0889)
		(layer "In9.Cu")
		(net "UPI_CPU1_CPU0_P1P1_DN<8>")
	)
	(segment
		(start 182.24246 -41.082214)
		(end 181.295548 -41.142666)
		(width 0.1143)
		(layer "In9.Cu")
		(net "UPI_CPU1_CPU0_P1P1_DN<8>")
	)
	(segment
		(start 175.455834 -43.246548)
		(end 174.945802 -43.430444)
		(width 0.1143)
		(layer "In9.Cu")
		(net "UPI_CPU1_CPU0_P1P1_DN<8>")
	)
	(segment
		(start 140.540486 -47.217584)
		(end 140.446252 -47.41164)
		(width 0.1143)
		(layer "In9.Cu")
		(net "UPI_CPU1_CPU0_P1P1_DN<8>")
	)
	(segment
		(start 293.532814 -54.159404)
		(end 293.39159 -54.01818)
		(width 0.0889)
		(layer "In9.Cu")
		(net "UPI_CPU1_CPU0_P1P1_DN<8>")
	)
	(segment
		(start 293.34079 -53.202332)
		(end 293.34079 -53.180234)
		(width 0.0889)
		(layer "In9.Cu")
		(net "UPI_CPU1_CPU0_P1P1_DN<8>")
	)
	(segment
		(start 294.097456 -55.504334)
		(end 294.06469 -55.504334)
		(width 0.0889)
		(layer "In9.Cu")
		(net "UPI_CPU1_CPU0_P1P1_DN<8>")
	)
	(segment
		(start 169.058336 -45.552106)
		(end 168.185338 -45.866812)
		(width 0.1143)
		(layer "In9.Cu")
		(net "UPI_CPU1_CPU0_P1P1_DN<8>")
	)
	(segment
		(start 212.366606 -41.74617)
		(end 199.181466 -38.417246)
		(width 0.1143)
		(layer "In9.Cu")
		(net "UPI_CPU1_CPU0_P1P1_DN<8>")
	)
	(segment
		(start 181.295548 -41.142666)
		(end 175.455834 -43.246548)
		(width 0.1143)
		(layer "In9.Cu")
		(net "UPI_CPU1_CPU0_P1P1_DN<8>")
	)
	(segment
		(start 293.13886 -51.00193)
		(end 292.9255 -50.968656)
		(width 0.1143)
		(layer "In9.Cu")
		(net "UPI_CPU1_CPU0_P1P1_DN<8>")
	)
	(segment
		(start 169.058336 -45.551852)
		(end 169.058336 -45.552106)
		(width 0.1143)
		(layer "In9.Cu")
		(net "UPI_CPU1_CPU0_P1P1_DN<8>")
	)
	(segment
		(start 293.39159 -54.01818)
		(end 293.39159 -53.253132)
		(width 0.0889)
		(layer "In9.Cu")
		(net "UPI_CPU1_CPU0_P1P1_DN<8>")
	)
	(segment
		(start 138.8872 -47.788068)
		(end 138.519662 -47.914814)
		(width 0.1143)
		(layer "In9.Cu")
		(net "UPI_CPU1_CPU0_P1P1_DN<8>")
	)
	(segment
		(start 294.437816 -56.703722)
		(end 294.43299 -56.695086)
		(width 0.0889)
		(layer "In9.Cu")
		(net "UPI_CPU1_CPU0_P1P1_DN<8>")
	)
	(segment
		(start 194.409568 -39.788338)
		(end 191.72809 -38.782752)
		(width 0.1143)
		(layer "In9.Cu")
		(net "UPI_CPU1_CPU0_P1P1_DN<8>")
	)
	(segment
		(start 156.12618 -43.84548)
		(end 155.752038 -43.920664)
		(width 0.1143)
		(layer "In9.Cu")
		(net "UPI_CPU1_CPU0_P1P1_DN<8>")
	)
	(segment
		(start 137.907014 -48.126142)
		(end 137.233914 -48.358298)
		(width 0.1143)
		(layer "In9.Cu")
		(net "UPI_CPU1_CPU0_P1P1_DN<8>")
	)
	(segment
		(start 290.209224 -47.985426)
		(end 286.302958 -46.69663)
		(width 0.1143)
		(layer "In9.Cu")
		(net "UPI_CPU1_CPU0_P1P1_DN<8>")
	)
	(segment
		(start 135.6868 -51.60391)
		(end 135.607044 -51.742086)
		(width 0.0889)
		(layer "In9.Cu")
		(net "UPI_CPU1_CPU0_P1P1_DN<8>")
	)
	(segment
		(start 291.920422 -49.379632)
		(end 291.583618 -49.105312)
		(width 0.1143)
		(layer "In9.Cu")
		(net "UPI_CPU1_CPU0_P1P1_DN<8>")
	)
	(segment
		(start 139.460478 -47.751492)
		(end 139.13612 -47.863506)
		(width 0.1143)
		(layer "In9.Cu")
		(net "UPI_CPU1_CPU0_P1P1_DN<8>")
	)
	(segment
		(start 140.121894 -47.5234)
		(end 139.928092 -47.428912)
		(width 0.1143)
		(layer "In9.Cu")
		(net "UPI_CPU1_CPU0_P1P1_DN<8>")
	)
	(segment
		(start 135.734552 -49.752504)
		(end 135.734552 -50.949352)
		(width 0.1143)
		(layer "In9.Cu")
		(net "UPI_CPU1_CPU0_P1P1_DN<8>")
	)
	(segment
		(start 191.72809 -38.782752)
		(end 188.8109 -39.224712)
		(width 0.1143)
		(layer "In9.Cu")
		(net "UPI_CPU1_CPU0_P1P1_DN<8>")
	)
	(segment
		(start 137.233914 -48.358298)
		(end 135.734552 -49.752504)
		(width 0.1143)
		(layer "In9.Cu")
		(net "UPI_CPU1_CPU0_P1P1_DN<8>")
	)
	(segment
		(start 294.08628 -57.885584)
		(end 294.203374 -57.768744)
		(width 0.0889)
		(layer "In9.Cu")
		(net "UPI_CPU1_CPU0_P1P1_DN<8>")
	)
	(segment
		(start 174.945802 -43.430444)
		(end 169.058336 -45.551852)
		(width 0.1143)
		(layer "In9.Cu")
		(net "UPI_CPU1_CPU0_P1P1_DN<8>")
	)
	(segment
		(start 246.984774 -38.258496)
		(end 243.182648 -40.548052)
		(width 0.1143)
		(layer "In9.Cu")
		(net "UPI_CPU1_CPU0_P1P1_DN<8>")
	)
	(segment
		(start 291.583618 -49.105312)
		(end 291.369242 -49.127156)
		(width 0.1143)
		(layer "In9.Cu")
		(net "UPI_CPU1_CPU0_P1P1_DN<8>")
	)
	(segment
		(start 293.34079 -53.180234)
		(end 293.34079 -52.26939)
		(width 0.1143)
		(layer "In9.Cu")
		(net "UPI_CPU1_CPU0_P1P1_DN<8>")
	)
	(segment
		(start 199.181466 -38.417246)
		(end 194.409568 -39.788338)
		(width 0.1143)
		(layer "In9.Cu")
		(net "UPI_CPU1_CPU0_P1P1_DN<8>")
	)
	(segment
		(start 134.723378 -53.575458)
		(end 134.802118 -53.596794)
		(width 0.0889)
		(layer "In9.Cu")
		(net "UPI_CPU1_CPU0_P1P1_DN<8>")
	)
	(segment
		(start 139.554966 -47.557436)
		(end 139.460478 -47.751492)
		(width 0.1143)
		(layer "In9.Cu")
		(net "UPI_CPU1_CPU0_P1P1_DN<8>")
	)
	(segment
		(start 159.928306 -45.43425)
		(end 156.310076 -43.916854)
		(width 0.1143)
		(layer "In9.Cu")
		(net "UPI_CPU1_CPU0_P1P1_DN<8>")
	)
	(segment
		(start 291.103304 -48.910494)
		(end 291.081206 -48.695864)
		(width 0.1143)
		(layer "In9.Cu")
		(net "UPI_CPU1_CPU0_P1P1_DN<8>")
	)
	(segment
		(start 138.942318 -47.769018)
		(end 138.8872 -47.788068)
		(width 0.1143)
		(layer "In9.Cu")
		(net "UPI_CPU1_CPU0_P1P1_DN<8>")
	)
	(segment
		(start 188.8109 -39.224712)
		(end 188.288676 -39.433246)
		(width 0.1143)
		(layer "In9.Cu")
		(net "UPI_CPU1_CPU0_P1P1_DN<8>")
	)
	(segment
		(start 141.801088 -46.782736)
		(end 141.476984 -46.894496)
		(width 0.1143)
		(layer "In9.Cu")
		(net "UPI_CPU1_CPU0_P1P1_DN<8>")
	)
	(segment
		(start 141.38275 -47.088552)
		(end 141.058392 -47.200312)
		(width 0.1143)
		(layer "In9.Cu")
		(net "UPI_CPU1_CPU0_P1P1_DN<8>")
	)
	(segment
		(start 286.302958 -46.69663)
		(end 264.466832 -41.488868)
		(width 0.1143)
		(layer "In9.Cu")
		(net "UPI_CPU1_CPU0_P1P1_DN<8>")
	)
	(segment
		(start 293.57447 -54.618636)
		(end 293.579296 -54.61)
		(width 0.0889)
		(layer "In9.Cu")
		(net "UPI_CPU1_CPU0_P1P1_DN<8>")
	)
	(segment
		(start 138.519662 -47.914814)
		(end 138.425174 -48.10887)
		(width 0.1143)
		(layer "In9.Cu")
		(net "UPI_CPU1_CPU0_P1P1_DN<8>")
	)
	(segment
		(start 291.081206 -48.695864)
		(end 290.209224 -47.985426)
		(width 0.1143)
		(layer "In9.Cu")
		(net "UPI_CPU1_CPU0_P1P1_DN<8>")
	)
	(segment
		(start 293.18839 -52.11699)
		(end 293.18839 -51.77409)
		(width 0.1143)
		(layer "In9.Cu")
		(net "UPI_CPU1_CPU0_P1P1_DN<8>")
	)
	(segment
		(start 139.928092 -47.428912)
		(end 139.554966 -47.557436)
		(width 0.1143)
		(layer "In9.Cu")
		(net "UPI_CPU1_CPU0_P1P1_DN<8>")
	)
	(arc
		(start 294.06469 -55.504334)
		(mid 293.5723 -55.205401)
		(end 293.56812 -54.629304)
		(width 0.0889)
		(layer "In9.Cu")
		(net "UPI_CPU1_CPU0_P1P1_DN<8>")
	)
	(arc
		(start 135.080248 -52.037488)
		(mid 134.74733 -52.239479)
		(end 134.743698 -52.6288)
		(width 0.0889)
		(layer "In9.Cu")
		(net "UPI_CPU1_CPU0_P1P1_DN<8>")
	)
	(arc
		(start 294.43299 -56.104536)
		(mid 294.435738 -55.709069)
		(end 294.097456 -55.504334)
		(width 0.0889)
		(layer "In9.Cu")
		(net "UPI_CPU1_CPU0_P1P1_DN<8>")
	)
	(arc
		(start 294.203374 -57.768744)
		(mid 294.314874 -57.601733)
		(end 294.353996 -57.404762)
		(width 0.0889)
		(layer "In9.Cu")
		(net "UPI_CPU1_CPU0_P1P1_DN<8>")
	)
	(arc
		(start 294.353996 -57.404762)
		(mid 294.372152 -57.244502)
		(end 294.43299 -57.095136)
		(width 0.0889)
		(layer "In9.Cu")
		(net "UPI_CPU1_CPU0_P1P1_DN<8>")
	)
	(arc
		(start 134.748524 -53.227986)
		(mid 134.707419 -53.329214)
		(end 134.695184 -53.43779)
		(width 0.0889)
		(layer "In9.Cu")
		(net "UPI_CPU1_CPU0_P1P1_DN<8>")
	)
	(arc
		(start 294.43299 -57.095136)
		(mid 294.48646 -56.900073)
		(end 294.437816 -56.703722)
		(width 0.0889)
		(layer "In9.Cu")
		(net "UPI_CPU1_CPU0_P1P1_DN<8>")
	)
	(arc
		(start 293.579296 -54.61)
		(mid 293.625974 -54.377475)
		(end 293.532814 -54.159404)
		(width 0.0889)
		(layer "In9.Cu")
		(net "UPI_CPU1_CPU0_P1P1_DN<8>")
	)
	(arc
		(start 135.607044 -51.742086)
		(mid 135.398436 -51.954018)
		(end 135.113014 -52.037488)
		(width 0.0889)
		(layer "In9.Cu")
		(net "UPI_CPU1_CPU0_P1P1_DN<8>")
	)
	(arc
		(start 134.748524 -52.637436)
		(mid 134.827746 -52.926554)
		(end 134.754874 -53.217318)
		(width 0.0889)
		(layer "In9.Cu")
		(net "UPI_CPU1_CPU0_P1P1_DN<8>")
	)
	(arc
		(start 134.695184 -53.43779)
		(mid 134.703188 -53.507872)
		(end 134.723378 -53.575458)
		(width 0.0889)
		(layer "In9.Cu")
		(net "UPI_CPU1_CPU0_P1P1_DN<8>")
	)
	(arc
		(start 294.42664 -56.684418)
		(mid 294.353842 -56.393655)
		(end 294.43299 -56.104536)
		(width 0.0889)
		(layer "In9.Cu")
		(net "UPI_CPU1_CPU0_P1P1_DN<8>")
	)
	(segment
		(start 135.382254 -53.923184)
		(end 135.953754 -53.923184)
		(width 0.1143)
		(layer "F.Cu")
		(net "UPI_CPU1_CPU0_P1P1_DN<7>")
	)
	(segment
		(start 294.3733 -59.371484)
		(end 294.9448 -59.371484)
		(width 0.1143)
		(layer "F.Cu")
		(net "UPI_CPU1_CPU0_P1P1_DN<7>")
	)
	(via
		(at 135.953754 -53.923184)
		(size 0.508)
		(drill 0.254)
		(layers "F.Cu" "B.Cu")
		(net "UPI_CPU1_CPU0_P1P1_DN<7>")
	)
	(via
		(at 294.9448 -59.371484)
		(size 0.508)
		(drill 0.254)
		(layers "F.Cu" "B.Cu")
		(net "UPI_CPU1_CPU0_P1P1_DN<7>")
	)
	(segment
		(start 257.280918 -42.087038)
		(end 248.87047 -38.603682)
		(width 0.1143)
		(layer "In9.Cu")
		(net "UPI_CPU1_CPU0_P1P1_DN<7>")
	)
	(segment
		(start 286.315404 -47.083218)
		(end 264.63879 -41.910508)
		(width 0.1143)
		(layer "In9.Cu")
		(net "UPI_CPU1_CPU0_P1P1_DN<7>")
	)
	(segment
		(start 295.0718 -59.69)
		(end 295.0464 -59.7662)
		(width 0.0889)
		(layer "In9.Cu")
		(net "UPI_CPU1_CPU0_P1P1_DN<7>")
	)
	(segment
		(start 295.0464 -59.7662)
		(end 294.886888 -59.76747)
		(width 0.0889)
		(layer "In9.Cu")
		(net "UPI_CPU1_CPU0_P1P1_DN<7>")
	)
	(segment
		(start 293.734744 -57.694322)
		(end 293.73957 -57.685686)
		(width 0.0889)
		(layer "In9.Cu")
		(net "UPI_CPU1_CPU0_P1P1_DN<7>")
	)
	(segment
		(start 159.851344 -45.787564)
		(end 156.077158 -44.224956)
		(width 0.1143)
		(layer "In9.Cu")
		(net "UPI_CPU1_CPU0_P1P1_DN<7>")
	)
	(segment
		(start 292.970458 -53.644038)
		(end 292.71595 -53.38953)
		(width 0.0889)
		(layer "In9.Cu")
		(net "UPI_CPU1_CPU0_P1P1_DN<7>")
	)
	(segment
		(start 168.21658 -46.273466)
		(end 164.855652 -46.916086)
		(width 0.1143)
		(layer "In9.Cu")
		(net "UPI_CPU1_CPU0_P1P1_DN<7>")
	)
	(segment
		(start 137.809478 -48.831754)
		(end 137.443464 -49.017936)
		(width 0.1143)
		(layer "In9.Cu")
		(net "UPI_CPU1_CPU0_P1P1_DN<7>")
	)
	(segment
		(start 292.88105 -54.618636)
		(end 292.876224 -54.61)
		(width 0.0889)
		(layer "In9.Cu")
		(net "UPI_CPU1_CPU0_P1P1_DN<7>")
	)
	(segment
		(start 292.970458 -54.063392)
		(end 292.970458 -53.644038)
		(width 0.0889)
		(layer "In9.Cu")
		(net "UPI_CPU1_CPU0_P1P1_DN<7>")
	)
	(segment
		(start 137.928858 -48.690784)
		(end 137.809478 -48.831754)
		(width 0.1143)
		(layer "In9.Cu")
		(net "UPI_CPU1_CPU0_P1P1_DN<7>")
	)
	(segment
		(start 164.855652 -46.916086)
		(end 159.851344 -45.787564)
		(width 0.1143)
		(layer "In9.Cu")
		(net "UPI_CPU1_CPU0_P1P1_DN<7>")
	)
	(segment
		(start 190.78067 -41.978326)
		(end 187.919868 -40.874696)
		(width 0.1143)
		(layer "In9.Cu")
		(net "UPI_CPU1_CPU0_P1P1_DN<7>")
	)
	(segment
		(start 291.858192 -49.938432)
		(end 289.643058 -48.292512)
		(width 0.1143)
		(layer "In9.Cu")
		(net "UPI_CPU1_CPU0_P1P1_DN<7>")
	)
	(segment
		(start 181.146704 -41.557448)
		(end 168.21658 -46.273466)
		(width 0.1143)
		(layer "In9.Cu")
		(net "UPI_CPU1_CPU0_P1P1_DN<7>")
	)
	(segment
		(start 248.87047 -38.603682)
		(end 247.110504 -38.603682)
		(width 0.1143)
		(layer "In9.Cu")
		(net "UPI_CPU1_CPU0_P1P1_DN<7>")
	)
	(segment
		(start 292.88105 -54.218586)
		(end 292.970458 -54.063392)
		(width 0.0889)
		(layer "In9.Cu")
		(net "UPI_CPU1_CPU0_P1P1_DN<7>")
	)
	(segment
		(start 137.396982 -49.098454)
		(end 137.141966 -49.22774)
		(width 0.0889)
		(layer "In9.Cu")
		(net "UPI_CPU1_CPU0_P1P1_DN<7>")
	)
	(segment
		(start 292.76675 -52.95011)
		(end 292.76675 -52.436268)
		(width 0.1143)
		(layer "In9.Cu")
		(net "UPI_CPU1_CPU0_P1P1_DN<7>")
	)
	(segment
		(start 261.722362 -42.685462)
		(end 257.280918 -42.087038)
		(width 0.1143)
		(layer "In9.Cu")
		(net "UPI_CPU1_CPU0_P1P1_DN<7>")
	)
	(segment
		(start 137.141966 -49.22774)
		(end 136.174988 -51.201828)
		(width 0.0889)
		(layer "In9.Cu")
		(net "UPI_CPU1_CPU0_P1P1_DN<7>")
	)
	(segment
		(start 289.56762 -48.251618)
		(end 286.315404 -47.083218)
		(width 0.1143)
		(layer "In9.Cu")
		(net "UPI_CPU1_CPU0_P1P1_DN<7>")
	)
	(segment
		(start 292.71595 -53.38953)
		(end 292.71595 -53.023008)
		(width 0.0889)
		(layer "In9.Cu")
		(net "UPI_CPU1_CPU0_P1P1_DN<7>")
	)
	(segment
		(start 247.110504 -38.603682)
		(end 243.24945 -40.96004)
		(width 0.1143)
		(layer "In9.Cu")
		(net "UPI_CPU1_CPU0_P1P1_DN<7>")
	)
	(segment
		(start 135.96874 -52.342034)
		(end 135.9408 -52.342034)
		(width 0.0889)
		(layer "In9.Cu")
		(net "UPI_CPU1_CPU0_P1P1_DN<7>")
	)
	(segment
		(start 156.077158 -44.224956)
		(end 144.343628 -46.923452)
		(width 0.1143)
		(layer "In9.Cu")
		(net "UPI_CPU1_CPU0_P1P1_DN<7>")
	)
	(segment
		(start 293.73957 -57.685686)
		(end 293.74592 -57.675018)
		(width 0.0889)
		(layer "In9.Cu")
		(net "UPI_CPU1_CPU0_P1P1_DN<7>")
	)
	(segment
		(start 199.206104 -38.845744)
		(end 190.78067 -41.978326)
		(width 0.1143)
		(layer "In9.Cu")
		(net "UPI_CPU1_CPU0_P1P1_DN<7>")
	)
	(segment
		(start 292.71595 -53.023008)
		(end 292.76675 -52.95011)
		(width 0.0889)
		(layer "In9.Cu")
		(net "UPI_CPU1_CPU0_P1P1_DN<7>")
	)
	(segment
		(start 243.24945 -40.96004)
		(end 236.886496 -39.990522)
		(width 0.1143)
		(layer "In9.Cu")
		(net "UPI_CPU1_CPU0_P1P1_DN<7>")
	)
	(segment
		(start 137.4013 -49.096168)
		(end 137.396982 -49.098454)
		(width 0.0889)
		(layer "In9.Cu")
		(net "UPI_CPU1_CPU0_P1P1_DN<7>")
	)
	(segment
		(start 292.8874 -54.629304)
		(end 292.88105 -54.618636)
		(width 0.0889)
		(layer "In9.Cu")
		(net "UPI_CPU1_CPU0_P1P1_DN<7>")
	)
	(segment
		(start 222.396812 -41.236392)
		(end 212.327998 -42.102278)
		(width 0.1143)
		(layer "In9.Cu")
		(net "UPI_CPU1_CPU0_P1P1_DN<7>")
	)
	(segment
		(start 289.643058 -48.292512)
		(end 289.56762 -48.251618)
		(width 0.1143)
		(layer "In9.Cu")
		(net "UPI_CPU1_CPU0_P1P1_DN<7>")
	)
	(segment
		(start 293.734744 -56.703722)
		(end 293.73957 -56.695086)
		(width 0.0889)
		(layer "In9.Cu")
		(net "UPI_CPU1_CPU0_P1P1_DN<7>")
	)
	(segment
		(start 293.73957 -56.695086)
		(end 293.74592 -56.684418)
		(width 0.0889)
		(layer "In9.Cu")
		(net "UPI_CPU1_CPU0_P1P1_DN<7>")
	)
	(segment
		(start 294.9448 -59.371484)
		(end 295.0972 -59.5376)
		(width 0.0889)
		(layer "In9.Cu")
		(net "UPI_CPU1_CPU0_P1P1_DN<7>")
	)
	(segment
		(start 135.595614 -53.402738)
		(end 135.953754 -53.923184)
		(width 0.0889)
		(layer "In9.Cu")
		(net "UPI_CPU1_CPU0_P1P1_DN<7>")
	)
	(segment
		(start 136.174988 -51.201828)
		(end 136.22909 -51.611276)
		(width 0.0889)
		(layer "In9.Cu")
		(net "UPI_CPU1_CPU0_P1P1_DN<7>")
	)
	(segment
		(start 293.24935 -55.809388)
		(end 293.216584 -55.809388)
		(width 0.0889)
		(layer "In9.Cu")
		(net "UPI_CPU1_CPU0_P1P1_DN<7>")
	)
	(segment
		(start 187.919868 -40.874696)
		(end 181.146704 -41.557448)
		(width 0.1143)
		(layer "In9.Cu")
		(net "UPI_CPU1_CPU0_P1P1_DN<7>")
	)
	(segment
		(start 294.099234 -58.285634)
		(end 294.071294 -58.285634)
		(width 0.0889)
		(layer "In9.Cu")
		(net "UPI_CPU1_CPU0_P1P1_DN<7>")
	)
	(segment
		(start 136.22909 -51.611276)
		(end 136.30148 -51.731164)
		(width 0.0889)
		(layer "In9.Cu")
		(net "UPI_CPU1_CPU0_P1P1_DN<7>")
	)
	(segment
		(start 292.76675 -52.436268)
		(end 291.858192 -49.938432)
		(width 0.1143)
		(layer "In9.Cu")
		(net "UPI_CPU1_CPU0_P1P1_DN<7>")
	)
	(segment
		(start 295.0972 -59.5376)
		(end 295.0718 -59.69)
		(width 0.0889)
		(layer "In9.Cu")
		(net "UPI_CPU1_CPU0_P1P1_DN<7>")
	)
	(segment
		(start 264.63879 -41.910508)
		(end 261.722362 -42.685462)
		(width 0.1143)
		(layer "In9.Cu")
		(net "UPI_CPU1_CPU0_P1P1_DN<7>")
	)
	(segment
		(start 294.59809 -59.171586)
		(end 294.60444 -59.160918)
		(width 0.0889)
		(layer "In9.Cu")
		(net "UPI_CPU1_CPU0_P1P1_DN<7>")
	)
	(segment
		(start 212.327998 -42.102278)
		(end 199.206104 -38.845744)
		(width 0.1143)
		(layer "In9.Cu")
		(net "UPI_CPU1_CPU0_P1P1_DN<7>")
	)
	(segment
		(start 144.343628 -46.923452)
		(end 137.928858 -48.690784)
		(width 0.1143)
		(layer "In9.Cu")
		(net "UPI_CPU1_CPU0_P1P1_DN<7>")
	)
	(segment
		(start 137.443464 -49.017936)
		(end 137.4013 -49.096168)
		(width 0.0889)
		(layer "In9.Cu")
		(net "UPI_CPU1_CPU0_P1P1_DN<7>")
	)
	(segment
		(start 236.886496 -39.990522)
		(end 222.396812 -41.236392)
		(width 0.1143)
		(layer "In9.Cu")
		(net "UPI_CPU1_CPU0_P1P1_DN<7>")
	)
	(segment
		(start 136.336532 -52.079906)
		(end 136.300464 -52.142136)
		(width 0.0889)
		(layer "In9.Cu")
		(net "UPI_CPU1_CPU0_P1P1_DN<7>")
	)
	(arc
		(start 294.886888 -59.76747)
		(mid 294.833664 -59.755906)
		(end 294.782494 -59.737244)
		(width 0.0889)
		(layer "In9.Cu")
		(net "UPI_CPU1_CPU0_P1P1_DN<7>")
	)
	(arc
		(start 293.74592 -57.675018)
		(mid 293.818718 -57.384255)
		(end 293.73957 -57.095136)
		(width 0.0889)
		(layer "In9.Cu")
		(net "UPI_CPU1_CPU0_P1P1_DN<7>")
	)
	(arc
		(start 136.300464 -52.142136)
		(mid 136.160385 -52.284872)
		(end 135.96874 -52.342034)
		(width 0.0889)
		(layer "In9.Cu")
		(net "UPI_CPU1_CPU0_P1P1_DN<7>")
	)
	(arc
		(start 294.60444 -59.160918)
		(mid 294.598263 -58.580986)
		(end 294.099234 -58.285634)
		(width 0.0889)
		(layer "In9.Cu")
		(net "UPI_CPU1_CPU0_P1P1_DN<7>")
	)
	(arc
		(start 293.74592 -56.684418)
		(mid 293.741889 -56.108236)
		(end 293.24935 -55.809388)
		(width 0.0889)
		(layer "In9.Cu")
		(net "UPI_CPU1_CPU0_P1P1_DN<7>")
	)
	(arc
		(start 292.88105 -55.209186)
		(mid 292.960272 -54.920068)
		(end 292.8874 -54.629304)
		(width 0.0889)
		(layer "In9.Cu")
		(net "UPI_CPU1_CPU0_P1P1_DN<7>")
	)
	(arc
		(start 293.216584 -55.809388)
		(mid 292.878415 -55.60459)
		(end 292.88105 -55.209186)
		(width 0.0889)
		(layer "In9.Cu")
		(net "UPI_CPU1_CPU0_P1P1_DN<7>")
	)
	(arc
		(start 135.9408 -52.342034)
		(mid 135.391822 -52.749945)
		(end 135.595614 -53.402738)
		(width 0.0889)
		(layer "In9.Cu")
		(net "UPI_CPU1_CPU0_P1P1_DN<7>")
	)
	(arc
		(start 294.071294 -58.285634)
		(mid 293.738376 -58.083643)
		(end 293.734744 -57.694322)
		(width 0.0889)
		(layer "In9.Cu")
		(net "UPI_CPU1_CPU0_P1P1_DN<7>")
	)
	(arc
		(start 294.782494 -59.737244)
		(mid 294.677134 -59.669086)
		(end 294.59809 -59.571636)
		(width 0.0889)
		(layer "In9.Cu")
		(net "UPI_CPU1_CPU0_P1P1_DN<7>")
	)
	(arc
		(start 292.876224 -54.61)
		(mid 292.827469 -54.413648)
		(end 292.88105 -54.218586)
		(width 0.0889)
		(layer "In9.Cu")
		(net "UPI_CPU1_CPU0_P1P1_DN<7>")
	)
	(arc
		(start 136.30148 -51.731164)
		(mid 136.35849 -51.901566)
		(end 136.336532 -52.079906)
		(width 0.0889)
		(layer "In9.Cu")
		(net "UPI_CPU1_CPU0_P1P1_DN<7>")
	)
	(arc
		(start 294.59809 -59.571636)
		(mid 294.544591 -59.371628)
		(end 294.59809 -59.171586)
		(width 0.0889)
		(layer "In9.Cu")
		(net "UPI_CPU1_CPU0_P1P1_DN<7>")
	)
	(arc
		(start 293.73957 -57.095136)
		(mid 293.6861 -56.900073)
		(end 293.734744 -56.703722)
		(width 0.0889)
		(layer "In9.Cu")
		(net "UPI_CPU1_CPU0_P1P1_DN<7>")
	)
	(segment
		(start 136.240774 -55.409338)
		(end 136.812274 -55.409338)
		(width 0.1143)
		(layer "F.Cu")
		(net "UPI_CPU1_CPU0_P1P1_DN<6>")
	)
	(segment
		(start 292.65626 -60.362338)
		(end 293.22776 -60.362338)
		(width 0.1143)
		(layer "F.Cu")
		(net "UPI_CPU1_CPU0_P1P1_DN<6>")
	)
	(via
		(at 293.22776 -60.362338)
		(size 0.508)
		(drill 0.254)
		(layers "F.Cu" "B.Cu")
		(net "UPI_CPU1_CPU0_P1P1_DN<6>")
	)
	(via
		(at 136.812274 -55.409338)
		(size 0.508)
		(drill 0.254)
		(layers "F.Cu" "B.Cu")
		(net "UPI_CPU1_CPU0_P1P1_DN<6>")
	)
	(segment
		(start 144.173448 -47.95266)
		(end 142.502636 -48.64481)
		(width 0.1143)
		(layer "In9.Cu")
		(net "UPI_CPU1_CPU0_P1P1_DN<6>")
	)
	(segment
		(start 136.834372 -53.027834)
		(end 136.812274 -53.027834)
		(width 0.0889)
		(layer "In9.Cu")
		(net "UPI_CPU1_CPU0_P1P1_DN<6>")
	)
	(segment
		(start 159.6263 -46.708822)
		(end 156.107384 -45.251624)
		(width 0.1143)
		(layer "In9.Cu")
		(net "UPI_CPU1_CPU0_P1P1_DN<6>")
	)
	(segment
		(start 140.525246 -49.654206)
		(end 140.313664 -49.741836)
		(width 0.1143)
		(layer "In9.Cu")
		(net "UPI_CPU1_CPU0_P1P1_DN<6>")
	)
	(segment
		(start 142.502636 -48.64481)
		(end 142.428976 -48.822864)
		(width 0.1143)
		(layer "In9.Cu")
		(net "UPI_CPU1_CPU0_P1P1_DN<6>")
	)
	(segment
		(start 136.460738 -54.61)
		(end 136.465564 -54.618636)
		(width 0.0889)
		(layer "In9.Cu")
		(net "UPI_CPU1_CPU0_P1P1_DN<6>")
	)
	(segment
		(start 256.6924 -43.127168)
		(end 247.960388 -44.546266)
		(width 0.1143)
		(layer "In9.Cu")
		(net "UPI_CPU1_CPU0_P1P1_DN<6>")
	)
	(segment
		(start 290.724336 -52.143406)
		(end 290.902136 -51.965606)
		(width 0.1143)
		(layer "In9.Cu")
		(net "UPI_CPU1_CPU0_P1P1_DN<6>")
	)
	(segment
		(start 137.575544 -52.298092)
		(end 137.324084 -52.73294)
		(width 0.0889)
		(layer "In9.Cu")
		(net "UPI_CPU1_CPU0_P1P1_DN<6>")
	)
	(segment
		(start 138.4554 -50.9778)
		(end 138.38301 -50.9778)
		(width 0.0889)
		(layer "In9.Cu")
		(net "UPI_CPU1_CPU0_P1P1_DN<6>")
	)
	(segment
		(start 140.619988 -49.425098)
		(end 140.525246 -49.654206)
		(width 0.1143)
		(layer "In9.Cu")
		(net "UPI_CPU1_CPU0_P1P1_DN<6>")
	)
	(segment
		(start 142.428976 -48.822864)
		(end 142.14475 -48.940212)
		(width 0.1143)
		(layer "In9.Cu")
		(net "UPI_CPU1_CPU0_P1P1_DN<6>")
	)
	(segment
		(start 138.003026 -51.357784)
		(end 138.003026 -51.497738)
		(width 0.0889)
		(layer "In9.Cu")
		(net "UPI_CPU1_CPU0_P1P1_DN<6>")
	)
	(segment
		(start 290.902136 -52.773326)
		(end 290.902136 -52.547266)
		(width 0.1143)
		(layer "In9.Cu")
		(net "UPI_CPU1_CPU0_P1P1_DN<6>")
	)
	(segment
		(start 136.465564 -54.618636)
		(end 136.471914 -54.629304)
		(width 0.0889)
		(layer "In9.Cu")
		(net "UPI_CPU1_CPU0_P1P1_DN<6>")
	)
	(segment
		(start 137.575544 -51.785266)
		(end 137.575544 -52.298092)
		(width 0.0889)
		(layer "In9.Cu")
		(net "UPI_CPU1_CPU0_P1P1_DN<6>")
	)
	(segment
		(start 290.902136 -51.739546)
		(end 290.724336 -51.561746)
		(width 0.1143)
		(layer "In9.Cu")
		(net "UPI_CPU1_CPU0_P1P1_DN<6>")
	)
	(segment
		(start 139.575286 -49.857914)
		(end 139.244578 -50.188622)
		(width 0.1143)
		(layer "In9.Cu")
		(net "UPI_CPU1_CPU0_P1P1_DN<6>")
	)
	(segment
		(start 290.724336 -51.335686)
		(end 290.902136 -51.157886)
		(width 0.1143)
		(layer "In9.Cu")
		(net "UPI_CPU1_CPU0_P1P1_DN<6>")
	)
	(segment
		(start 141.408658 -49.0982)
		(end 141.313916 -49.327308)
		(width 0.1143)
		(layer "In9.Cu")
		(net "UPI_CPU1_CPU0_P1P1_DN<6>")
	)
	(segment
		(start 136.812274 -53.027834)
		(end 136.81202 -53.028088)
		(width 0.0889)
		(layer "In9.Cu")
		(net "UPI_CPU1_CPU0_P1P1_DN<6>")
	)
	(segment
		(start 290.952936 -53.573426)
		(end 290.952936 -52.846224)
		(width 0.0889)
		(layer "In9.Cu")
		(net "UPI_CPU1_CPU0_P1P1_DN<6>")
	)
	(segment
		(start 137.859262 -51.641756)
		(end 137.719054 -51.641756)
		(width 0.0889)
		(layer "In9.Cu")
		(net "UPI_CPU1_CPU0_P1P1_DN<6>")
	)
	(segment
		(start 164.718746 -47.873412)
		(end 159.6263 -46.708822)
		(width 0.1143)
		(layer "In9.Cu")
		(net "UPI_CPU1_CPU0_P1P1_DN<6>")
	)
	(segment
		(start 290.902136 -52.547266)
		(end 290.724336 -52.369466)
		(width 0.1143)
		(layer "In9.Cu")
		(net "UPI_CPU1_CPU0_P1P1_DN<6>")
	)
	(segment
		(start 212.18525 -43.056302)
		(end 199.268334 -39.891716)
		(width 0.1143)
		(layer "In9.Cu")
		(net "UPI_CPU1_CPU0_P1P1_DN<6>")
	)
	(segment
		(start 292.71595 -57.685686)
		(end 292.7096 -57.675018)
		(width 0.0889)
		(layer "In9.Cu")
		(net "UPI_CPU1_CPU0_P1P1_DN<6>")
	)
	(segment
		(start 292.720776 -57.694322)
		(end 292.71595 -57.685686)
		(width 0.0889)
		(layer "In9.Cu")
		(net "UPI_CPU1_CPU0_P1P1_DN<6>")
	)
	(segment
		(start 290.902136 -50.524664)
		(end 289.18408 -49.329594)
		(width 0.1143)
		(layer "In9.Cu")
		(net "UPI_CPU1_CPU0_P1P1_DN<6>")
	)
	(segment
		(start 290.952936 -52.846224)
		(end 290.902136 -52.795424)
		(width 0.0889)
		(layer "In9.Cu")
		(net "UPI_CPU1_CPU0_P1P1_DN<6>")
	)
	(segment
		(start 290.902136 -51.965606)
		(end 290.902136 -51.739546)
		(width 0.1143)
		(layer "In9.Cu")
		(net "UPI_CPU1_CPU0_P1P1_DN<6>")
	)
	(segment
		(start 291.349684 -53.887878)
		(end 290.952936 -53.573426)
		(width 0.0889)
		(layer "In9.Cu")
		(net "UPI_CPU1_CPU0_P1P1_DN<6>")
	)
	(segment
		(start 291.48913 -54.818788)
		(end 291.521896 -54.818788)
		(width 0.0889)
		(layer "In9.Cu")
		(net "UPI_CPU1_CPU0_P1P1_DN<6>")
	)
	(segment
		(start 136.440418 -55.556912)
		(end 136.519158 -55.578248)
		(width 0.0889)
		(layer "In9.Cu")
		(net "UPI_CPU1_CPU0_P1P1_DN<6>")
	)
	(segment
		(start 199.268334 -39.891716)
		(end 190.613792 -43.109388)
		(width 0.1143)
		(layer "In9.Cu")
		(net "UPI_CPU1_CPU0_P1P1_DN<6>")
	)
	(segment
		(start 291.736272 -54.008782)
		(end 291.349684 -53.887878)
		(width 0.0889)
		(layer "In9.Cu")
		(net "UPI_CPU1_CPU0_P1P1_DN<6>")
	)
	(segment
		(start 156.107384 -45.251624)
		(end 144.173448 -47.95266)
		(width 0.1143)
		(layer "In9.Cu")
		(net "UPI_CPU1_CPU0_P1P1_DN<6>")
	)
	(segment
		(start 140.08481 -49.64684)
		(end 139.575286 -49.857914)
		(width 0.1143)
		(layer "In9.Cu")
		(net "UPI_CPU1_CPU0_P1P1_DN<6>")
	)
	(segment
		(start 247.960388 -44.546266)
		(end 240.996216 -43.113452)
		(width 0.1143)
		(layer "In9.Cu")
		(net "UPI_CPU1_CPU0_P1P1_DN<6>")
	)
	(segment
		(start 292.380416 -56.494934)
		(end 292.34765 -56.494934)
		(width 0.0889)
		(layer "In9.Cu")
		(net "UPI_CPU1_CPU0_P1P1_DN<6>")
	)
	(segment
		(start 136.519158 -55.578248)
		(end 136.812274 -55.409338)
		(width 0.0889)
		(layer "In9.Cu")
		(net "UPI_CPU1_CPU0_P1P1_DN<6>")
	)
	(segment
		(start 141.313916 -49.327308)
		(end 141.102588 -49.414938)
		(width 0.1143)
		(layer "In9.Cu")
		(net "UPI_CPU1_CPU0_P1P1_DN<6>")
	)
	(segment
		(start 141.967204 -48.866806)
		(end 141.408658 -49.0982)
		(width 0.1143)
		(layer "In9.Cu")
		(net "UPI_CPU1_CPU0_P1P1_DN<6>")
	)
	(segment
		(start 261.915656 -43.655488)
		(end 256.885694 -43.140122)
		(width 0.1143)
		(layer "In9.Cu")
		(net "UPI_CPU1_CPU0_P1P1_DN<6>")
	)
	(segment
		(start 140.87348 -49.320196)
		(end 140.619988 -49.425098)
		(width 0.1143)
		(layer "In9.Cu")
		(net "UPI_CPU1_CPU0_P1P1_DN<6>")
	)
	(segment
		(start 290.724336 -51.561746)
		(end 290.724336 -51.335686)
		(width 0.1143)
		(layer "In9.Cu")
		(net "UPI_CPU1_CPU0_P1P1_DN<6>")
	)
	(segment
		(start 140.313664 -49.741836)
		(end 140.08481 -49.64684)
		(width 0.1143)
		(layer "In9.Cu")
		(net "UPI_CPU1_CPU0_P1P1_DN<6>")
	)
	(segment
		(start 138.003026 -51.497738)
		(end 137.859262 -51.641756)
		(width 0.0889)
		(layer "In9.Cu")
		(net "UPI_CPU1_CPU0_P1P1_DN<6>")
	)
	(segment
		(start 136.81202 -53.028088)
		(end 136.79424 -53.028088)
		(width 0.0889)
		(layer "In9.Cu")
		(net "UPI_CPU1_CPU0_P1P1_DN<6>")
	)
	(segment
		(start 293.22776 -60.362338)
		(end 293.52367 -59.685682)
		(width 0.0889)
		(layer "In9.Cu")
		(net "UPI_CPU1_CPU0_P1P1_DN<6>")
	)
	(segment
		(start 222.396812 -42.210736)
		(end 212.18525 -43.056302)
		(width 0.1143)
		(layer "In9.Cu")
		(net "UPI_CPU1_CPU0_P1P1_DN<6>")
	)
	(segment
		(start 181.669436 -42.461942)
		(end 168.665906 -47.13097)
		(width 0.1143)
		(layer "In9.Cu")
		(net "UPI_CPU1_CPU0_P1P1_DN<6>")
	)
	(segment
		(start 290.902136 -51.157886)
		(end 290.902136 -50.524664)
		(width 0.1143)
		(layer "In9.Cu")
		(net "UPI_CPU1_CPU0_P1P1_DN<6>")
	)
	(segment
		(start 139.08278 -50.598578)
		(end 138.834622 -50.598578)
		(width 0.1143)
		(layer "In9.Cu")
		(net "UPI_CPU1_CPU0_P1P1_DN<6>")
	)
	(segment
		(start 139.244578 -50.43678)
		(end 139.08278 -50.598578)
		(width 0.1143)
		(layer "In9.Cu")
		(net "UPI_CPU1_CPU0_P1P1_DN<6>")
	)
	(segment
		(start 237.024164 -40.99941)
		(end 222.396812 -42.210736)
		(width 0.1143)
		(layer "In9.Cu")
		(net "UPI_CPU1_CPU0_P1P1_DN<6>")
	)
	(segment
		(start 138.38301 -50.9778)
		(end 138.003026 -51.357784)
		(width 0.0889)
		(layer "In9.Cu")
		(net "UPI_CPU1_CPU0_P1P1_DN<6>")
	)
	(segment
		(start 190.613792 -43.109388)
		(end 184.239154 -42.883582)
		(width 0.1143)
		(layer "In9.Cu")
		(net "UPI_CPU1_CPU0_P1P1_DN<6>")
	)
	(segment
		(start 256.885694 -43.140122)
		(end 256.6924 -43.127168)
		(width 0.1143)
		(layer "In9.Cu")
		(net "UPI_CPU1_CPU0_P1P1_DN<6>")
	)
	(segment
		(start 290.902136 -52.795424)
		(end 290.902136 -52.773326)
		(width 0.0889)
		(layer "In9.Cu")
		(net "UPI_CPU1_CPU0_P1P1_DN<6>")
	)
	(segment
		(start 141.102588 -49.414938)
		(end 140.87348 -49.320196)
		(width 0.1143)
		(layer "In9.Cu")
		(net "UPI_CPU1_CPU0_P1P1_DN<6>")
	)
	(segment
		(start 285.782766 -47.911004)
		(end 264.543286 -42.911522)
		(width 0.1143)
		(layer "In9.Cu")
		(net "UPI_CPU1_CPU0_P1P1_DN<6>")
	)
	(segment
		(start 142.14475 -48.940212)
		(end 141.967204 -48.866806)
		(width 0.1143)
		(layer "In9.Cu")
		(net "UPI_CPU1_CPU0_P1P1_DN<6>")
	)
	(segment
		(start 289.18408 -49.329594)
		(end 285.782766 -47.911004)
		(width 0.1143)
		(layer "In9.Cu")
		(net "UPI_CPU1_CPU0_P1P1_DN<6>")
	)
	(segment
		(start 264.543286 -42.911522)
		(end 261.915656 -43.655488)
		(width 0.1143)
		(layer "In9.Cu")
		(net "UPI_CPU1_CPU0_P1P1_DN<6>")
	)
	(segment
		(start 139.244578 -50.188622)
		(end 139.244578 -50.43678)
		(width 0.1143)
		(layer "In9.Cu")
		(net "UPI_CPU1_CPU0_P1P1_DN<6>")
	)
	(segment
		(start 184.239154 -42.883582)
		(end 181.669436 -42.461942)
		(width 0.1143)
		(layer "In9.Cu")
		(net "UPI_CPU1_CPU0_P1P1_DN<6>")
	)
	(segment
		(start 240.996216 -43.113452)
		(end 237.024164 -40.99941)
		(width 0.1143)
		(layer "In9.Cu")
		(net "UPI_CPU1_CPU0_P1P1_DN<6>")
	)
	(segment
		(start 137.719054 -51.641756)
		(end 137.575544 -51.785266)
		(width 0.0889)
		(layer "In9.Cu")
		(net "UPI_CPU1_CPU0_P1P1_DN<6>")
	)
	(segment
		(start 168.665906 -47.13097)
		(end 164.718746 -47.873412)
		(width 0.1143)
		(layer "In9.Cu")
		(net "UPI_CPU1_CPU0_P1P1_DN<6>")
	)
	(segment
		(start 138.834622 -50.598578)
		(end 138.4554 -50.9778)
		(width 0.1143)
		(layer "In9.Cu")
		(net "UPI_CPU1_CPU0_P1P1_DN<6>")
	)
	(segment
		(start 290.724336 -52.369466)
		(end 290.724336 -52.143406)
		(width 0.1143)
		(layer "In9.Cu")
		(net "UPI_CPU1_CPU0_P1P1_DN<6>")
	)
	(segment
		(start 291.85743 -54.21884)
		(end 291.85743 -54.218586)
		(width 0.0889)
		(layer "In9.Cu")
		(net "UPI_CPU1_CPU0_P1P1_DN<6>")
	)
	(segment
		(start 291.85743 -54.218586)
		(end 291.736272 -54.008782)
		(width 0.0889)
		(layer "In9.Cu")
		(net "UPI_CPU1_CPU0_P1P1_DN<6>")
	)
	(segment
		(start 291.525706 -55.999888)
		(end 291.49294 -55.999888)
		(width 0.0889)
		(layer "In9.Cu")
		(net "UPI_CPU1_CPU0_P1P1_DN<6>")
	)
	(segment
		(start 293.245794 -58.971688)
		(end 293.20617 -58.971688)
		(width 0.0889)
		(layer "In9.Cu")
		(net "UPI_CPU1_CPU0_P1P1_DN<6>")
	)
	(arc
		(start 136.79424 -53.028088)
		(mid 136.461324 -53.23554)
		(end 136.465564 -53.627782)
		(width 0.0889)
		(layer "In9.Cu")
		(net "UPI_CPU1_CPU0_P1P1_DN<6>")
	)
	(arc
		(start 292.34765 -56.494934)
		(mid 292.064433 -56.410653)
		(end 291.85743 -56.199786)
		(width 0.0889)
		(layer "In9.Cu")
		(net "UPI_CPU1_CPU0_P1P1_DN<6>")
	)
	(arc
		(start 293.52367 -59.685682)
		(mid 293.546047 -59.627189)
		(end 293.57447 -59.571382)
		(width 0.0889)
		(layer "In9.Cu")
		(net "UPI_CPU1_CPU0_P1P1_DN<6>")
	)
	(arc
		(start 136.465564 -55.209186)
		(mid 136.413144 -55.380171)
		(end 136.440418 -55.556912)
		(width 0.0889)
		(layer "In9.Cu")
		(net "UPI_CPU1_CPU0_P1P1_DN<6>")
	)
	(arc
		(start 291.861494 -54.61127)
		(mid 291.910837 -54.414532)
		(end 291.85743 -54.21884)
		(width 0.0889)
		(layer "In9.Cu")
		(net "UPI_CPU1_CPU0_P1P1_DN<6>")
	)
	(arc
		(start 136.471914 -54.629304)
		(mid 136.544712 -54.920067)
		(end 136.465564 -55.209186)
		(width 0.0889)
		(layer "In9.Cu")
		(net "UPI_CPU1_CPU0_P1P1_DN<6>")
	)
	(arc
		(start 292.71595 -57.095136)
		(mid 292.718698 -56.699669)
		(end 292.380416 -56.494934)
		(width 0.0889)
		(layer "In9.Cu")
		(net "UPI_CPU1_CPU0_P1P1_DN<6>")
	)
	(arc
		(start 136.465564 -54.218586)
		(mid 136.412094 -54.413649)
		(end 136.460738 -54.61)
		(width 0.0889)
		(layer "In9.Cu")
		(net "UPI_CPU1_CPU0_P1P1_DN<6>")
	)
	(arc
		(start 136.465564 -53.627782)
		(mid 136.544695 -53.923184)
		(end 136.465564 -54.218586)
		(width 0.0889)
		(layer "In9.Cu")
		(net "UPI_CPU1_CPU0_P1P1_DN<6>")
	)
	(arc
		(start 293.57447 -59.571382)
		(mid 293.578715 -59.179137)
		(end 293.245794 -58.971688)
		(width 0.0889)
		(layer "In9.Cu")
		(net "UPI_CPU1_CPU0_P1P1_DN<6>")
	)
	(arc
		(start 292.71595 -58.085736)
		(mid 292.76942 -57.890673)
		(end 292.720776 -57.694322)
		(width 0.0889)
		(layer "In9.Cu")
		(net "UPI_CPU1_CPU0_P1P1_DN<6>")
	)
	(arc
		(start 291.521896 -54.818788)
		(mid 291.719347 -54.760264)
		(end 291.861494 -54.61127)
		(width 0.0889)
		(layer "In9.Cu")
		(net "UPI_CPU1_CPU0_P1P1_DN<6>")
	)
	(arc
		(start 291.85743 -56.199786)
		(mid 291.717351 -56.05705)
		(end 291.525706 -55.999888)
		(width 0.0889)
		(layer "In9.Cu")
		(net "UPI_CPU1_CPU0_P1P1_DN<6>")
	)
	(arc
		(start 291.49294 -55.999888)
		(mid 290.919659 -55.411242)
		(end 291.48913 -54.818788)
		(width 0.0889)
		(layer "In9.Cu")
		(net "UPI_CPU1_CPU0_P1P1_DN<6>")
	)
	(arc
		(start 137.324084 -52.73294)
		(mid 137.117279 -52.94358)
		(end 136.834372 -53.027834)
		(width 0.0889)
		(layer "In9.Cu")
		(net "UPI_CPU1_CPU0_P1P1_DN<6>")
	)
	(arc
		(start 293.20617 -58.971688)
		(mid 292.710693 -58.667245)
		(end 292.71595 -58.085736)
		(width 0.0889)
		(layer "In9.Cu")
		(net "UPI_CPU1_CPU0_P1P1_DN<6>")
	)
	(arc
		(start 292.7096 -57.675018)
		(mid 292.636802 -57.384255)
		(end 292.71595 -57.095136)
		(width 0.0889)
		(layer "In9.Cu")
		(net "UPI_CPU1_CPU0_P1P1_DN<6>")
	)
	(segment
		(start 290.93922 -58.381138)
		(end 291.51072 -58.381138)
		(width 0.1143)
		(layer "F.Cu")
		(net "UPI_CPU1_CPU0_P1P1_DN<5>")
	)
	(segment
		(start 137.099294 -54.913784)
		(end 137.670794 -54.913784)
		(width 0.1143)
		(layer "F.Cu")
		(net "UPI_CPU1_CPU0_P1P1_DN<5>")
	)
	(via
		(at 291.51072 -58.381138)
		(size 0.508)
		(drill 0.254)
		(layers "F.Cu" "B.Cu")
		(net "UPI_CPU1_CPU0_P1P1_DN<5>")
	)
	(via
		(at 137.670794 -54.913784)
		(size 0.508)
		(drill 0.254)
		(layers "F.Cu" "B.Cu")
		(net "UPI_CPU1_CPU0_P1P1_DN<5>")
	)
	(segment
		(start 144.375124 -48.858424)
		(end 144.280128 -49.087532)
		(width 0.1143)
		(layer "In9.Cu")
		(net "UPI_CPU1_CPU0_P1P1_DN<5>")
	)
	(segment
		(start 156.062426 -45.955458)
		(end 145.840196 -48.251618)
		(width 0.1143)
		(layer "In9.Cu")
		(net "UPI_CPU1_CPU0_P1P1_DN<5>")
	)
	(segment
		(start 289.979608 -50.863246)
		(end 288.746946 -49.903126)
		(width 0.1143)
		(layer "In9.Cu")
		(net "UPI_CPU1_CPU0_P1P1_DN<5>")
	)
	(segment
		(start 143.839692 -49.080166)
		(end 143.628618 -49.167542)
		(width 0.1143)
		(layer "In9.Cu")
		(net "UPI_CPU1_CPU0_P1P1_DN<5>")
	)
	(segment
		(start 291.85108 -57.601104)
		(end 291.85743 -57.590436)
		(width 0.0889)
		(layer "In9.Cu")
		(net "UPI_CPU1_CPU0_P1P1_DN<5>")
	)
	(segment
		(start 290.663376 -56.494934)
		(end 290.382452 -56.494934)
		(width 0.0889)
		(layer "In9.Cu")
		(net "UPI_CPU1_CPU0_P1P1_DN<5>")
	)
	(segment
		(start 181.68747 -43.190668)
		(end 181.671976 -43.188382)
		(width 0.1143)
		(layer "In9.Cu")
		(net "UPI_CPU1_CPU0_P1P1_DN<5>")
	)
	(segment
		(start 145.840196 -48.251618)
		(end 145.121376 -48.549306)
		(width 0.1143)
		(layer "In9.Cu")
		(net "UPI_CPU1_CPU0_P1P1_DN<5>")
	)
	(segment
		(start 184.363614 -43.612308)
		(end 181.68747 -43.190668)
		(width 0.1143)
		(layer "In9.Cu")
		(net "UPI_CPU1_CPU0_P1P1_DN<5>")
	)
	(segment
		(start 247.944894 -45.192188)
		(end 240.815622 -43.749976)
		(width 0.1143)
		(layer "In9.Cu")
		(net "UPI_CPU1_CPU0_P1P1_DN<5>")
	)
	(segment
		(start 290.030408 -56.14289)
		(end 290.030408 -52.700428)
		(width 0.0889)
		(layer "In9.Cu")
		(net "UPI_CPU1_CPU0_P1P1_DN<5>")
	)
	(segment
		(start 142.882112 -49.47666)
		(end 142.787116 -49.705768)
		(width 0.1143)
		(layer "In9.Cu")
		(net "UPI_CPU1_CPU0_P1P1_DN<5>")
	)
	(segment
		(start 142.34668 -49.698402)
		(end 142.135606 -49.785778)
		(width 0.1143)
		(layer "In9.Cu")
		(net "UPI_CPU1_CPU0_P1P1_DN<5>")
	)
	(segment
		(start 138.825986 -52.539392)
		(end 138.700256 -52.665122)
		(width 0.0889)
		(layer "In9.Cu")
		(net "UPI_CPU1_CPU0_P1P1_DN<5>")
	)
	(segment
		(start 141.07033 -50.226976)
		(end 140.243306 -51.054)
		(width 0.1143)
		(layer "In9.Cu")
		(net "UPI_CPU1_CPU0_P1P1_DN<5>")
	)
	(segment
		(start 190.835026 -43.758612)
		(end 184.363614 -43.612308)
		(width 0.1143)
		(layer "In9.Cu")
		(net "UPI_CPU1_CPU0_P1P1_DN<5>")
	)
	(segment
		(start 164.850826 -48.564292)
		(end 159.621982 -47.424594)
		(width 0.1143)
		(layer "In9.Cu")
		(net "UPI_CPU1_CPU0_P1P1_DN<5>")
	)
	(segment
		(start 143.322294 -49.48428)
		(end 143.093186 -49.389284)
		(width 0.1143)
		(layer "In9.Cu")
		(net "UPI_CPU1_CPU0_P1P1_DN<5>")
	)
	(segment
		(start 291.51072 -58.381138)
		(end 291.791644 -57.7596)
		(width 0.0889)
		(layer "In9.Cu")
		(net "UPI_CPU1_CPU0_P1P1_DN<5>")
	)
	(segment
		(start 145.026634 -48.778414)
		(end 144.815306 -48.866044)
		(width 0.1143)
		(layer "In9.Cu")
		(net "UPI_CPU1_CPU0_P1P1_DN<5>")
	)
	(segment
		(start 137.324084 -54.713886)
		(end 137.319258 -54.722522)
		(width 0.0889)
		(layer "In9.Cu")
		(net "UPI_CPU1_CPU0_P1P1_DN<5>")
	)
	(segment
		(start 142.575788 -49.793398)
		(end 142.34668 -49.698402)
		(width 0.1143)
		(layer "In9.Cu")
		(net "UPI_CPU1_CPU0_P1P1_DN<5>")
	)
	(segment
		(start 138.559794 -52.665122)
		(end 138.434318 -52.790598)
		(width 0.0889)
		(layer "In9.Cu")
		(net "UPI_CPU1_CPU0_P1P1_DN<5>")
	)
	(segment
		(start 199.29475 -40.586914)
		(end 190.835026 -43.758612)
		(width 0.1143)
		(layer "In9.Cu")
		(net "UPI_CPU1_CPU0_P1P1_DN<5>")
	)
	(segment
		(start 256.590546 -43.814238)
		(end 247.944894 -45.192188)
		(width 0.1143)
		(layer "In9.Cu")
		(net "UPI_CPU1_CPU0_P1P1_DN<5>")
	)
	(segment
		(start 291.85743 -57.590436)
		(end 291.862256 -57.5818)
		(width 0.0889)
		(layer "In9.Cu")
		(net "UPI_CPU1_CPU0_P1P1_DN<5>")
	)
	(segment
		(start 159.621982 -47.424594)
		(end 156.062426 -45.955458)
		(width 0.1143)
		(layer "In9.Cu")
		(net "UPI_CPU1_CPU0_P1P1_DN<5>")
	)
	(segment
		(start 139.217654 -52.147724)
		(end 139.091924 -52.273454)
		(width 0.0889)
		(layer "In9.Cu")
		(net "UPI_CPU1_CPU0_P1P1_DN<5>")
	)
	(segment
		(start 181.67096 -43.188128)
		(end 169.04081 -47.70247)
		(width 0.1143)
		(layer "In9.Cu")
		(net "UPI_CPU1_CPU0_P1P1_DN<5>")
	)
	(segment
		(start 143.533622 -49.39665)
		(end 143.322294 -49.48428)
		(width 0.1143)
		(layer "In9.Cu")
		(net "UPI_CPU1_CPU0_P1P1_DN<5>")
	)
	(segment
		(start 222.396812 -42.868596)
		(end 211.958174 -43.724322)
		(width 0.1143)
		(layer "In9.Cu")
		(net "UPI_CPU1_CPU0_P1P1_DN<5>")
	)
	(segment
		(start 289.979608 -52.649628)
		(end 289.979608 -50.863246)
		(width 0.1143)
		(layer "In9.Cu")
		(net "UPI_CPU1_CPU0_P1P1_DN<5>")
	)
	(segment
		(start 291.525706 -56.990488)
		(end 291.49294 -56.990488)
		(width 0.0889)
		(layer "In9.Cu")
		(net "UPI_CPU1_CPU0_P1P1_DN<5>")
	)
	(segment
		(start 137.658348 -53.523134)
		(end 137.65276 -53.523388)
		(width 0.0889)
		(layer "In9.Cu")
		(net "UPI_CPU1_CPU0_P1P1_DN<5>")
	)
	(segment
		(start 169.04081 -47.70247)
		(end 169.040048 -47.702724)
		(width 0.1143)
		(layer "In9.Cu")
		(net "UPI_CPU1_CPU0_P1P1_DN<5>")
	)
	(segment
		(start 144.280128 -49.087532)
		(end 144.0688 -49.175162)
		(width 0.1143)
		(layer "In9.Cu")
		(net "UPI_CPU1_CPU0_P1P1_DN<5>")
	)
	(segment
		(start 138.825986 -52.39893)
		(end 138.825986 -52.539392)
		(width 0.0889)
		(layer "In9.Cu")
		(net "UPI_CPU1_CPU0_P1P1_DN<5>")
	)
	(segment
		(start 141.829282 -50.102516)
		(end 141.600174 -50.00752)
		(width 0.1143)
		(layer "In9.Cu")
		(net "UPI_CPU1_CPU0_P1P1_DN<5>")
	)
	(segment
		(start 290.382452 -56.494934)
		(end 290.030408 -56.14289)
		(width 0.0889)
		(layer "In9.Cu")
		(net "UPI_CPU1_CPU0_P1P1_DN<5>")
	)
	(segment
		(start 142.135606 -49.785778)
		(end 142.04061 -50.014886)
		(width 0.1143)
		(layer "In9.Cu")
		(net "UPI_CPU1_CPU0_P1P1_DN<5>")
	)
	(segment
		(start 140.170916 -51.054)
		(end 139.217654 -52.007262)
		(width 0.0889)
		(layer "In9.Cu")
		(net "UPI_CPU1_CPU0_P1P1_DN<5>")
	)
	(segment
		(start 211.958174 -43.724322)
		(end 199.29475 -40.586914)
		(width 0.1143)
		(layer "In9.Cu")
		(net "UPI_CPU1_CPU0_P1P1_DN<5>")
	)
	(segment
		(start 290.030408 -52.700428)
		(end 289.979608 -52.649628)
		(width 0.0889)
		(layer "In9.Cu")
		(net "UPI_CPU1_CPU0_P1P1_DN<5>")
	)
	(segment
		(start 138.700256 -52.665122)
		(end 138.559794 -52.665122)
		(width 0.0889)
		(layer "In9.Cu")
		(net "UPI_CPU1_CPU0_P1P1_DN<5>")
	)
	(segment
		(start 137.68832 -55.30977)
		(end 137.77722 -55.22087)
		(width 0.0889)
		(layer "In9.Cu")
		(net "UPI_CPU1_CPU0_P1P1_DN<5>")
	)
	(segment
		(start 144.586198 -48.771048)
		(end 144.375124 -48.858424)
		(width 0.1143)
		(layer "In9.Cu")
		(net "UPI_CPU1_CPU0_P1P1_DN<5>")
	)
	(segment
		(start 139.217654 -52.007262)
		(end 139.217654 -52.147724)
		(width 0.0889)
		(layer "In9.Cu")
		(net "UPI_CPU1_CPU0_P1P1_DN<5>")
	)
	(segment
		(start 261.996936 -44.32808)
		(end 256.590546 -43.814238)
		(width 0.1143)
		(layer "In9.Cu")
		(net "UPI_CPU1_CPU0_P1P1_DN<5>")
	)
	(segment
		(start 141.600174 -50.00752)
		(end 141.07033 -50.226976)
		(width 0.1143)
		(layer "In9.Cu")
		(net "UPI_CPU1_CPU0_P1P1_DN<5>")
	)
	(segment
		(start 264.665968 -43.598338)
		(end 261.996936 -44.32808)
		(width 0.1143)
		(layer "In9.Cu")
		(net "UPI_CPU1_CPU0_P1P1_DN<5>")
	)
	(segment
		(start 144.815306 -48.866044)
		(end 144.586198 -48.771048)
		(width 0.1143)
		(layer "In9.Cu")
		(net "UPI_CPU1_CPU0_P1P1_DN<5>")
	)
	(segment
		(start 169.040048 -47.702724)
		(end 164.850826 -48.564292)
		(width 0.1143)
		(layer "In9.Cu")
		(net "UPI_CPU1_CPU0_P1P1_DN<5>")
	)
	(segment
		(start 143.628618 -49.167542)
		(end 143.533622 -49.39665)
		(width 0.1143)
		(layer "In9.Cu")
		(net "UPI_CPU1_CPU0_P1P1_DN<5>")
	)
	(segment
		(start 138.434318 -52.790598)
		(end 138.182858 -53.227986)
		(width 0.0889)
		(layer "In9.Cu")
		(net "UPI_CPU1_CPU0_P1P1_DN<5>")
	)
	(segment
		(start 142.04061 -50.014886)
		(end 141.829282 -50.102516)
		(width 0.1143)
		(layer "In9.Cu")
		(net "UPI_CPU1_CPU0_P1P1_DN<5>")
	)
	(segment
		(start 143.093186 -49.389284)
		(end 142.882112 -49.47666)
		(width 0.1143)
		(layer "In9.Cu")
		(net "UPI_CPU1_CPU0_P1P1_DN<5>")
	)
	(segment
		(start 288.746946 -49.903126)
		(end 285.41726 -48.5267)
		(width 0.1143)
		(layer "In9.Cu")
		(net "UPI_CPU1_CPU0_P1P1_DN<5>")
	)
	(segment
		(start 181.671976 -43.188382)
		(end 181.67096 -43.188128)
		(width 0.1143)
		(layer "In9.Cu")
		(net "UPI_CPU1_CPU0_P1P1_DN<5>")
	)
	(segment
		(start 236.922818 -41.678098)
		(end 222.396812 -42.868596)
		(width 0.1143)
		(layer "In9.Cu")
		(net "UPI_CPU1_CPU0_P1P1_DN<5>")
	)
	(segment
		(start 137.77722 -55.02021)
		(end 137.670794 -54.913784)
		(width 0.0889)
		(layer "In9.Cu")
		(net "UPI_CPU1_CPU0_P1P1_DN<5>")
	)
	(segment
		(start 142.787116 -49.705768)
		(end 142.575788 -49.793398)
		(width 0.1143)
		(layer "In9.Cu")
		(net "UPI_CPU1_CPU0_P1P1_DN<5>")
	)
	(segment
		(start 137.77722 -55.22087)
		(end 137.77722 -55.02021)
		(width 0.0889)
		(layer "In9.Cu")
		(net "UPI_CPU1_CPU0_P1P1_DN<5>")
	)
	(segment
		(start 140.243306 -51.054)
		(end 140.170916 -51.054)
		(width 0.0889)
		(layer "In9.Cu")
		(net "UPI_CPU1_CPU0_P1P1_DN<5>")
	)
	(segment
		(start 137.612882 -55.30977)
		(end 137.68832 -55.30977)
		(width 0.0889)
		(layer "In9.Cu")
		(net "UPI_CPU1_CPU0_P1P1_DN<5>")
	)
	(segment
		(start 137.692892 -53.523134)
		(end 137.658348 -53.523134)
		(width 0.0889)
		(layer "In9.Cu")
		(net "UPI_CPU1_CPU0_P1P1_DN<5>")
	)
	(segment
		(start 145.121376 -48.549306)
		(end 145.026634 -48.778414)
		(width 0.1143)
		(layer "In9.Cu")
		(net "UPI_CPU1_CPU0_P1P1_DN<5>")
	)
	(segment
		(start 240.815622 -43.749976)
		(end 236.922818 -41.678098)
		(width 0.1143)
		(layer "In9.Cu")
		(net "UPI_CPU1_CPU0_P1P1_DN<5>")
	)
	(segment
		(start 285.41726 -48.5267)
		(end 264.665968 -43.598338)
		(width 0.1143)
		(layer "In9.Cu")
		(net "UPI_CPU1_CPU0_P1P1_DN<5>")
	)
	(segment
		(start 138.951462 -52.273454)
		(end 138.825986 -52.39893)
		(width 0.0889)
		(layer "In9.Cu")
		(net "UPI_CPU1_CPU0_P1P1_DN<5>")
	)
	(segment
		(start 137.330434 -54.703218)
		(end 137.324084 -54.713886)
		(width 0.0889)
		(layer "In9.Cu")
		(net "UPI_CPU1_CPU0_P1P1_DN<5>")
	)
	(segment
		(start 139.091924 -52.273454)
		(end 138.951462 -52.273454)
		(width 0.0889)
		(layer "In9.Cu")
		(net "UPI_CPU1_CPU0_P1P1_DN<5>")
	)
	(segment
		(start 144.0688 -49.175162)
		(end 143.839692 -49.080166)
		(width 0.1143)
		(layer "In9.Cu")
		(net "UPI_CPU1_CPU0_P1P1_DN<5>")
	)
	(arc
		(start 291.862256 -57.5818)
		(mid 291.858509 -57.192544)
		(end 291.525706 -56.990488)
		(width 0.0889)
		(layer "In9.Cu")
		(net "UPI_CPU1_CPU0_P1P1_DN<5>")
	)
	(arc
		(start 290.99891 -56.695086)
		(mid 290.857227 -56.551282)
		(end 290.663376 -56.494934)
		(width 0.0889)
		(layer "In9.Cu")
		(net "UPI_CPU1_CPU0_P1P1_DN<5>")
	)
	(arc
		(start 137.324084 -54.123336)
		(mid 137.403306 -54.412454)
		(end 137.330434 -54.703218)
		(width 0.0889)
		(layer "In9.Cu")
		(net "UPI_CPU1_CPU0_P1P1_DN<5>")
	)
	(arc
		(start 137.319258 -54.722522)
		(mid 137.270782 -54.91876)
		(end 137.324338 -55.113682)
		(width 0.0889)
		(layer "In9.Cu")
		(net "UPI_CPU1_CPU0_P1P1_DN<5>")
	)
	(arc
		(start 291.49294 -56.990488)
		(mid 291.207516 -56.907021)
		(end 290.99891 -56.695086)
		(width 0.0889)
		(layer "In9.Cu")
		(net "UPI_CPU1_CPU0_P1P1_DN<5>")
	)
	(arc
		(start 137.324338 -55.113682)
		(mid 137.446125 -55.244808)
		(end 137.612882 -55.30977)
		(width 0.0889)
		(layer "In9.Cu")
		(net "UPI_CPU1_CPU0_P1P1_DN<5>")
	)
	(arc
		(start 137.65276 -53.523388)
		(mid 137.319791 -53.730936)
		(end 137.324084 -54.123336)
		(width 0.0889)
		(layer "In9.Cu")
		(net "UPI_CPU1_CPU0_P1P1_DN<5>")
	)
	(arc
		(start 138.182858 -53.227986)
		(mid 137.975995 -53.438871)
		(end 137.692892 -53.523134)
		(width 0.0889)
		(layer "In9.Cu")
		(net "UPI_CPU1_CPU0_P1P1_DN<5>")
	)
	(arc
		(start 291.791644 -57.7596)
		(mid 291.815674 -57.67822)
		(end 291.85108 -57.601104)
		(width 0.0889)
		(layer "In9.Cu")
		(net "UPI_CPU1_CPU0_P1P1_DN<5>")
	)
	(segment
		(start 137.957814 -54.418738)
		(end 138.529314 -54.418738)
		(width 0.1143)
		(layer "F.Cu")
		(net "UPI_CPU1_CPU0_P1P1_DN<4>")
	)
	(segment
		(start 292.65626 -59.371484)
		(end 293.22776 -59.371484)
		(width 0.1143)
		(layer "F.Cu")
		(net "UPI_CPU1_CPU0_P1P1_DN<4>")
	)
	(via
		(at 138.529314 -54.418738)
		(size 0.508)
		(drill 0.254)
		(layers "F.Cu" "B.Cu")
		(net "UPI_CPU1_CPU0_P1P1_DN<4>")
	)
	(via
		(at 293.22776 -59.371484)
		(size 0.508)
		(drill 0.254)
		(layers "F.Cu" "B.Cu")
		(net "UPI_CPU1_CPU0_P1P1_DN<4>")
	)
	(segment
		(start 289.539172 -56.771286)
		(end 289.539172 -53.023008)
		(width 0.0889)
		(layer "In9.Cu")
		(net "UPI_CPU1_CPU0_P1P1_DN<4>")
	)
	(segment
		(start 181.834282 -43.90136)
		(end 168.848024 -48.4632)
		(width 0.1143)
		(layer "In9.Cu")
		(net "UPI_CPU1_CPU0_P1P1_DN<4>")
	)
	(segment
		(start 149.276562 -48.20666)
		(end 146.203416 -49.4792)
		(width 0.1143)
		(layer "In9.Cu")
		(net "UPI_CPU1_CPU0_P1P1_DN<4>")
	)
	(segment
		(start 140.263372 -52.461668)
		(end 139.095226 -53.629814)
		(width 0.0889)
		(layer "In9.Cu")
		(net "UPI_CPU1_CPU0_P1P1_DN<4>")
	)
	(segment
		(start 144.976088 -49.941226)
		(end 144.771364 -49.856136)
		(width 0.1143)
		(layer "In9.Cu")
		(net "UPI_CPU1_CPU0_P1P1_DN<4>")
	)
	(segment
		(start 139.095226 -53.629814)
		(end 139.041124 -53.72354)
		(width 0.0889)
		(layer "In9.Cu")
		(net "UPI_CPU1_CPU0_P1P1_DN<4>")
	)
	(segment
		(start 264.713466 -44.271438)
		(end 262.013192 -45.009816)
		(width 0.1143)
		(layer "In9.Cu")
		(net "UPI_CPU1_CPU0_P1P1_DN<4>")
	)
	(segment
		(start 142.8877 -50.63617)
		(end 142.792958 -50.865278)
		(width 0.1143)
		(layer "In9.Cu")
		(net "UPI_CPU1_CPU0_P1P1_DN<4>")
	)
	(segment
		(start 293.22776 -59.371484)
		(end 292.736778 -59.466734)
		(width 0.0889)
		(layer "In9.Cu")
		(net "UPI_CPU1_CPU0_P1P1_DN<4>")
	)
	(segment
		(start 288.244026 -50.52187)
		(end 288.065718 -50.394616)
		(width 0.1143)
		(layer "In9.Cu")
		(net "UPI_CPU1_CPU0_P1P1_DN<4>")
	)
	(segment
		(start 256.430272 -44.519342)
		(end 247.93194 -45.83811)
		(width 0.1143)
		(layer "In9.Cu")
		(net "UPI_CPU1_CPU0_P1P1_DN<4>")
	)
	(segment
		(start 145.221706 -49.839372)
		(end 144.976088 -49.941226)
		(width 0.1143)
		(layer "In9.Cu")
		(net "UPI_CPU1_CPU0_P1P1_DN<4>")
	)
	(segment
		(start 138.542014 -54.018688)
		(end 138.514328 -54.018688)
		(width 0.0889)
		(layer "In9.Cu")
		(net "UPI_CPU1_CPU0_P1P1_DN<4>")
	)
	(segment
		(start 191.089788 -44.431712)
		(end 184.265062 -44.307252)
		(width 0.1143)
		(layer "In9.Cu")
		(net "UPI_CPU1_CPU0_P1P1_DN<4>")
	)
	(segment
		(start 143.327882 -50.64379)
		(end 143.098774 -50.548794)
		(width 0.1143)
		(layer "In9.Cu")
		(net "UPI_CPU1_CPU0_P1P1_DN<4>")
	)
	(segment
		(start 247.93194 -45.83811)
		(end 240.549176 -44.344336)
		(width 0.1143)
		(layer "In9.Cu")
		(net "UPI_CPU1_CPU0_P1P1_DN<4>")
	)
	(segment
		(start 140.335 -52.1462)
		(end 140.263372 -52.319174)
		(width 0.0889)
		(layer "In9.Cu")
		(net "UPI_CPU1_CPU0_P1P1_DN<4>")
	)
	(segment
		(start 184.265062 -44.307252)
		(end 181.834282 -43.90136)
		(width 0.1143)
		(layer "In9.Cu")
		(net "UPI_CPU1_CPU0_P1P1_DN<4>")
	)
	(segment
		(start 138.215116 -54.170834)
		(end 138.236198 -54.249574)
		(width 0.0889)
		(layer "In9.Cu")
		(net "UPI_CPU1_CPU0_P1P1_DN<4>")
	)
	(segment
		(start 292.736778 -59.466734)
		(end 292.347142 -59.466734)
		(width 0.0889)
		(layer "In9.Cu")
		(net "UPI_CPU1_CPU0_P1P1_DN<4>")
	)
	(segment
		(start 211.760054 -44.349162)
		(end 199.258174 -41.291256)
		(width 0.1143)
		(layer "In9.Cu")
		(net "UPI_CPU1_CPU0_P1P1_DN<4>")
	)
	(segment
		(start 288.80435 -51.123596)
		(end 288.600388 -50.978054)
		(width 0.1143)
		(layer "In9.Cu")
		(net "UPI_CPU1_CPU0_P1P1_DN<4>")
	)
	(segment
		(start 289.539172 -53.023008)
		(end 289.315906 -52.799742)
		(width 0.0889)
		(layer "In9.Cu")
		(net "UPI_CPU1_CPU0_P1P1_DN<4>")
	)
	(segment
		(start 141.2748 -51.2064)
		(end 140.335 -52.1462)
		(width 0.0889)
		(layer "In9.Cu")
		(net "UPI_CPU1_CPU0_P1P1_DN<4>")
	)
	(segment
		(start 290.25342 -57.485534)
		(end 289.539172 -56.771286)
		(width 0.0889)
		(layer "In9.Cu")
		(net "UPI_CPU1_CPU0_P1P1_DN<4>")
	)
	(segment
		(start 199.258174 -41.291256)
		(end 191.089788 -44.431712)
		(width 0.1143)
		(layer "In9.Cu")
		(net "UPI_CPU1_CPU0_P1P1_DN<4>")
	)
	(segment
		(start 291.528754 -58.971688)
		(end 291.48913 -58.971688)
		(width 0.0889)
		(layer "In9.Cu")
		(net "UPI_CPU1_CPU0_P1P1_DN<4>")
	)
	(segment
		(start 143.634206 -50.327052)
		(end 143.53921 -50.55616)
		(width 0.1143)
		(layer "In9.Cu")
		(net "UPI_CPU1_CPU0_P1P1_DN<4>")
	)
	(segment
		(start 222.396812 -43.523916)
		(end 211.908898 -44.385484)
		(width 0.1143)
		(layer "In9.Cu")
		(net "UPI_CPU1_CPU0_P1P1_DN<4>")
	)
	(segment
		(start 289.315906 -52.799742)
		(end 289.315906 -51.669442)
		(width 0.0889)
		(layer "In9.Cu")
		(net "UPI_CPU1_CPU0_P1P1_DN<4>")
	)
	(segment
		(start 285.478728 -49.266348)
		(end 264.713466 -44.271438)
		(width 0.1143)
		(layer "In9.Cu")
		(net "UPI_CPU1_CPU0_P1P1_DN<4>")
	)
	(segment
		(start 168.848024 -48.4632)
		(end 165.016434 -49.281334)
		(width 0.1143)
		(layer "In9.Cu")
		(net "UPI_CPU1_CPU0_P1P1_DN<4>")
	)
	(segment
		(start 142.58163 -50.952908)
		(end 142.352522 -50.857912)
		(width 0.1143)
		(layer "In9.Cu")
		(net "UPI_CPU1_CPU0_P1P1_DN<4>")
	)
	(segment
		(start 143.84528 -50.239676)
		(end 143.634206 -50.327052)
		(width 0.1143)
		(layer "In9.Cu")
		(net "UPI_CPU1_CPU0_P1P1_DN<4>")
	)
	(segment
		(start 159.593788 -48.15078)
		(end 156.05252 -46.684692)
		(width 0.1143)
		(layer "In9.Cu")
		(net "UPI_CPU1_CPU0_P1P1_DN<4>")
	)
	(segment
		(start 141.779752 -51.2064)
		(end 141.2748 -51.2064)
		(width 0.0889)
		(layer "In9.Cu")
		(net "UPI_CPU1_CPU0_P1P1_DN<4>")
	)
	(segment
		(start 146.203416 -49.4792)
		(end 145.681446 -49.4792)
		(width 0.1143)
		(layer "In9.Cu")
		(net "UPI_CPU1_CPU0_P1P1_DN<4>")
	)
	(segment
		(start 142.352522 -50.857912)
		(end 142.141448 -50.945288)
		(width 0.1143)
		(layer "In9.Cu")
		(net "UPI_CPU1_CPU0_P1P1_DN<4>")
	)
	(segment
		(start 142.009114 -51.077622)
		(end 141.90853 -51.077622)
		(width 0.0889)
		(layer "In9.Cu")
		(net "UPI_CPU1_CPU0_P1P1_DN<4>")
	)
	(segment
		(start 262.013192 -45.009816)
		(end 256.668524 -44.53509)
		(width 0.1143)
		(layer "In9.Cu")
		(net "UPI_CPU1_CPU0_P1P1_DN<4>")
	)
	(segment
		(start 289.265106 -51.250342)
		(end 289.033966 -51.085242)
		(width 0.1143)
		(layer "In9.Cu")
		(net "UPI_CPU1_CPU0_P1P1_DN<4>")
	)
	(segment
		(start 144.074388 -50.334672)
		(end 143.84528 -50.239676)
		(width 0.1143)
		(layer "In9.Cu")
		(net "UPI_CPU1_CPU0_P1P1_DN<4>")
	)
	(segment
		(start 144.285716 -50.247042)
		(end 144.074388 -50.334672)
		(width 0.1143)
		(layer "In9.Cu")
		(net "UPI_CPU1_CPU0_P1P1_DN<4>")
	)
	(segment
		(start 142.141448 -50.945288)
		(end 142.009114 -51.077622)
		(width 0.1143)
		(layer "In9.Cu")
		(net "UPI_CPU1_CPU0_P1P1_DN<4>")
	)
	(segment
		(start 143.53921 -50.55616)
		(end 143.327882 -50.64379)
		(width 0.1143)
		(layer "In9.Cu")
		(net "UPI_CPU1_CPU0_P1P1_DN<4>")
	)
	(segment
		(start 288.600388 -50.978054)
		(end 288.562034 -50.748692)
		(width 0.1143)
		(layer "In9.Cu")
		(net "UPI_CPU1_CPU0_P1P1_DN<4>")
	)
	(segment
		(start 288.065718 -50.394616)
		(end 285.478728 -49.266348)
		(width 0.1143)
		(layer "In9.Cu")
		(net "UPI_CPU1_CPU0_P1P1_DN<4>")
	)
	(segment
		(start 156.05252 -46.684692)
		(end 149.276562 -48.20666)
		(width 0.1143)
		(layer "In9.Cu")
		(net "UPI_CPU1_CPU0_P1P1_DN<4>")
	)
	(segment
		(start 256.668524 -44.53509)
		(end 256.430272 -44.519342)
		(width 0.1143)
		(layer "In9.Cu")
		(net "UPI_CPU1_CPU0_P1P1_DN<4>")
	)
	(segment
		(start 289.033712 -51.085242)
		(end 288.80435 -51.123596)
		(width 0.1143)
		(layer "In9.Cu")
		(net "UPI_CPU1_CPU0_P1P1_DN<4>")
	)
	(segment
		(start 143.098774 -50.548794)
		(end 142.8877 -50.63617)
		(width 0.1143)
		(layer "In9.Cu")
		(net "UPI_CPU1_CPU0_P1P1_DN<4>")
	)
	(segment
		(start 290.666678 -57.485534)
		(end 290.25342 -57.485534)
		(width 0.0889)
		(layer "In9.Cu")
		(net "UPI_CPU1_CPU0_P1P1_DN<4>")
	)
	(segment
		(start 289.033966 -51.085242)
		(end 289.033712 -51.085242)
		(width 0.1143)
		(layer "In9.Cu")
		(net "UPI_CPU1_CPU0_P1P1_DN<4>")
	)
	(segment
		(start 240.549176 -44.344336)
		(end 236.786928 -42.342054)
		(width 0.1143)
		(layer "In9.Cu")
		(net "UPI_CPU1_CPU0_P1P1_DN<4>")
	)
	(segment
		(start 144.771364 -49.856136)
		(end 144.380712 -50.017934)
		(width 0.1143)
		(layer "In9.Cu")
		(net "UPI_CPU1_CPU0_P1P1_DN<4>")
	)
	(segment
		(start 142.792958 -50.865278)
		(end 142.58163 -50.952908)
		(width 0.1143)
		(layer "In9.Cu")
		(net "UPI_CPU1_CPU0_P1P1_DN<4>")
	)
	(segment
		(start 211.908898 -44.385484)
		(end 211.760054 -44.349162)
		(width 0.1143)
		(layer "In9.Cu")
		(net "UPI_CPU1_CPU0_P1P1_DN<4>")
	)
	(segment
		(start 140.263372 -52.319174)
		(end 140.263372 -52.461668)
		(width 0.0889)
		(layer "In9.Cu")
		(net "UPI_CPU1_CPU0_P1P1_DN<4>")
	)
	(segment
		(start 145.681446 -49.4792)
		(end 145.306542 -49.634394)
		(width 0.1143)
		(layer "In9.Cu")
		(net "UPI_CPU1_CPU0_P1P1_DN<4>")
	)
	(segment
		(start 289.315906 -51.669442)
		(end 289.265106 -51.618642)
		(width 0.0889)
		(layer "In9.Cu")
		(net "UPI_CPU1_CPU0_P1P1_DN<4>")
	)
	(segment
		(start 145.306542 -49.634394)
		(end 145.221706 -49.839372)
		(width 0.1143)
		(layer "In9.Cu")
		(net "UPI_CPU1_CPU0_P1P1_DN<4>")
	)
	(segment
		(start 288.562034 -50.748692)
		(end 288.244026 -50.52187)
		(width 0.1143)
		(layer "In9.Cu")
		(net "UPI_CPU1_CPU0_P1P1_DN<4>")
	)
	(segment
		(start 144.380712 -50.017934)
		(end 144.285716 -50.247042)
		(width 0.1143)
		(layer "In9.Cu")
		(net "UPI_CPU1_CPU0_P1P1_DN<4>")
	)
	(segment
		(start 289.265106 -51.618642)
		(end 289.265106 -51.250342)
		(width 0.1143)
		(layer "In9.Cu")
		(net "UPI_CPU1_CPU0_P1P1_DN<4>")
	)
	(segment
		(start 141.90853 -51.077622)
		(end 141.779752 -51.2064)
		(width 0.0889)
		(layer "In9.Cu")
		(net "UPI_CPU1_CPU0_P1P1_DN<4>")
	)
	(segment
		(start 138.236198 -54.249574)
		(end 138.529314 -54.418738)
		(width 0.0889)
		(layer "In9.Cu")
		(net "UPI_CPU1_CPU0_P1P1_DN<4>")
	)
	(segment
		(start 165.016434 -49.281334)
		(end 159.593788 -48.15078)
		(width 0.1143)
		(layer "In9.Cu")
		(net "UPI_CPU1_CPU0_P1P1_DN<4>")
	)
	(segment
		(start 236.786928 -42.342054)
		(end 222.396812 -43.523916)
		(width 0.1143)
		(layer "In9.Cu")
		(net "UPI_CPU1_CPU0_P1P1_DN<4>")
	)
	(arc
		(start 292.347142 -59.466734)
		(mid 292.064238 -59.382315)
		(end 291.85743 -59.171586)
		(width 0.0889)
		(layer "In9.Cu")
		(net "UPI_CPU1_CPU0_P1P1_DN<4>")
	)
	(arc
		(start 139.041124 -53.72354)
		(mid 138.830271 -53.936595)
		(end 138.542014 -54.018688)
		(width 0.0889)
		(layer "In9.Cu")
		(net "UPI_CPU1_CPU0_P1P1_DN<4>")
	)
	(arc
		(start 138.514328 -54.018688)
		(mid 138.348034 -54.061922)
		(end 138.215116 -54.170834)
		(width 0.0889)
		(layer "In9.Cu")
		(net "UPI_CPU1_CPU0_P1P1_DN<4>")
	)
	(arc
		(start 291.85743 -59.171586)
		(mid 291.718686 -59.029553)
		(end 291.528754 -58.971688)
		(width 0.0889)
		(layer "In9.Cu")
		(net "UPI_CPU1_CPU0_P1P1_DN<4>")
	)
	(arc
		(start 291.48913 -58.971688)
		(mid 290.993653 -58.667245)
		(end 290.99891 -58.085736)
		(width 0.0889)
		(layer "In9.Cu")
		(net "UPI_CPU1_CPU0_P1P1_DN<4>")
	)
	(arc
		(start 290.99891 -58.085736)
		(mid 291.00246 -57.691711)
		(end 290.666678 -57.485534)
		(width 0.0889)
		(layer "In9.Cu")
		(net "UPI_CPU1_CPU0_P1P1_DN<4>")
	)
	(segment
		(start 137.957814 -55.409338)
		(end 138.529314 -55.409338)
		(width 0.1143)
		(layer "F.Cu")
		(net "UPI_CPU1_CPU0_P1P1_DN<3>")
	)
	(segment
		(start 290.0807 -57.885584)
		(end 290.6522 -57.885584)
		(width 0.1143)
		(layer "F.Cu")
		(net "UPI_CPU1_CPU0_P1P1_DN<3>")
	)
	(via
		(at 290.6522 -57.885584)
		(size 0.508)
		(drill 0.254)
		(layers "F.Cu" "B.Cu")
		(net "UPI_CPU1_CPU0_P1P1_DN<3>")
	)
	(via
		(at 138.529314 -55.409338)
		(size 0.508)
		(drill 0.254)
		(layers "F.Cu" "B.Cu")
		(net "UPI_CPU1_CPU0_P1P1_DN<3>")
	)
	(segment
		(start 141.322806 -51.7779)
		(end 140.833856 -52.26685)
		(width 0.0889)
		(layer "In9.Cu")
		(net "UPI_CPU1_CPU0_P1P1_DN<3>")
	)
	(segment
		(start 289.25012 -56.964072)
		(end 289.25012 -53.164486)
		(width 0.0889)
		(layer "In9.Cu")
		(net "UPI_CPU1_CPU0_P1P1_DN<3>")
	)
	(segment
		(start 159.865822 -48.657002)
		(end 155.948888 -47.035212)
		(width 0.1143)
		(layer "In9.Cu")
		(net "UPI_CPU1_CPU0_P1P1_DN<3>")
	)
	(segment
		(start 168.984168 -48.81118)
		(end 164.878258 -49.662842)
		(width 0.1143)
		(layer "In9.Cu")
		(net "UPI_CPU1_CPU0_P1P1_DN<3>")
	)
	(segment
		(start 141.906498 -51.7271)
		(end 141.8844 -51.7271)
		(width 0.0889)
		(layer "In9.Cu")
		(net "UPI_CPU1_CPU0_P1P1_DN<3>")
	)
	(segment
		(start 236.685328 -42.720006)
		(end 222.396812 -43.942762)
		(width 0.1143)
		(layer "In9.Cu")
		(net "UPI_CPU1_CPU0_P1P1_DN<3>")
	)
	(segment
		(start 141.8844 -51.7271)
		(end 141.8336 -51.7779)
		(width 0.0889)
		(layer "In9.Cu")
		(net "UPI_CPU1_CPU0_P1P1_DN<3>")
	)
	(segment
		(start 184.325006 -44.710858)
		(end 181.78145 -44.35602)
		(width 0.1143)
		(layer "In9.Cu")
		(net "UPI_CPU1_CPU0_P1P1_DN<3>")
	)
	(segment
		(start 139.40536 -54.323234)
		(end 139.370054 -54.323234)
		(width 0.0889)
		(layer "In9.Cu")
		(net "UPI_CPU1_CPU0_P1P1_DN<3>")
	)
	(segment
		(start 289.25012 -53.164486)
		(end 288.728404 -52.64277)
		(width 0.0889)
		(layer "In9.Cu")
		(net "UPI_CPU1_CPU0_P1P1_DN<3>")
	)
	(segment
		(start 199.254872 -41.665652)
		(end 191.234314 -44.762166)
		(width 0.1143)
		(layer "In9.Cu")
		(net "UPI_CPU1_CPU0_P1P1_DN<3>")
	)
	(segment
		(start 264.783316 -44.665392)
		(end 262.072882 -45.363892)
		(width 0.1143)
		(layer "In9.Cu")
		(net "UPI_CPU1_CPU0_P1P1_DN<3>")
	)
	(segment
		(start 288.264092 -51.284632)
		(end 288.244026 -51.266344)
		(width 0.1143)
		(layer "In9.Cu")
		(net "UPI_CPU1_CPU0_P1P1_DN<3>")
	)
	(segment
		(start 222.396812 -43.942762)
		(end 211.906358 -44.840652)
		(width 0.1143)
		(layer "In9.Cu")
		(net "UPI_CPU1_CPU0_P1P1_DN<3>")
	)
	(segment
		(start 290.414456 -58.3692)
		(end 289.99307 -57.947814)
		(width 0.0889)
		(layer "In9.Cu")
		(net "UPI_CPU1_CPU0_P1P1_DN<3>")
	)
	(segment
		(start 256.478024 -44.875196)
		(end 247.845072 -46.199298)
		(width 0.1143)
		(layer "In9.Cu")
		(net "UPI_CPU1_CPU0_P1P1_DN<3>")
	)
	(segment
		(start 289.99307 -57.947814)
		(end 289.99307 -57.707022)
		(width 0.0889)
		(layer "In9.Cu")
		(net "UPI_CPU1_CPU0_P1P1_DN<3>")
	)
	(segment
		(start 288.779204 -52.30495)
		(end 288.779204 -51.751992)
		(width 0.1143)
		(layer "In9.Cu")
		(net "UPI_CPU1_CPU0_P1P1_DN<3>")
	)
	(segment
		(start 290.6522 -57.885584)
		(end 290.6522 -58.293)
		(width 0.0889)
		(layer "In9.Cu")
		(net "UPI_CPU1_CPU0_P1P1_DN<3>")
	)
	(segment
		(start 164.878258 -49.662842)
		(end 159.865822 -48.657002)
		(width 0.1143)
		(layer "In9.Cu")
		(net "UPI_CPU1_CPU0_P1P1_DN<3>")
	)
	(segment
		(start 285.288736 -49.572672)
		(end 264.783316 -44.665392)
		(width 0.1143)
		(layer "In9.Cu")
		(net "UPI_CPU1_CPU0_P1P1_DN<3>")
	)
	(segment
		(start 141.8336 -51.7779)
		(end 141.322806 -51.7779)
		(width 0.0889)
		(layer "In9.Cu")
		(net "UPI_CPU1_CPU0_P1P1_DN<3>")
	)
	(segment
		(start 140.370814 -53.384704)
		(end 139.87399 -53.881274)
		(width 0.0889)
		(layer "In9.Cu")
		(net "UPI_CPU1_CPU0_P1P1_DN<3>")
	)
	(segment
		(start 288.779204 -51.751992)
		(end 288.264346 -51.284632)
		(width 0.1143)
		(layer "In9.Cu")
		(net "UPI_CPU1_CPU0_P1P1_DN<3>")
	)
	(segment
		(start 155.948888 -47.035212)
		(end 150.344378 -48.314356)
		(width 0.1143)
		(layer "In9.Cu")
		(net "UPI_CPU1_CPU0_P1P1_DN<3>")
	)
	(segment
		(start 287.663128 -50.739802)
		(end 285.288736 -49.572672)
		(width 0.1143)
		(layer "In9.Cu")
		(net "UPI_CPU1_CPU0_P1P1_DN<3>")
	)
	(segment
		(start 288.779204 -52.327048)
		(end 288.779204 -52.30495)
		(width 0.0889)
		(layer "In9.Cu")
		(net "UPI_CPU1_CPU0_P1P1_DN<3>")
	)
	(segment
		(start 140.833856 -52.26685)
		(end 140.370814 -53.384704)
		(width 0.0889)
		(layer "In9.Cu")
		(net "UPI_CPU1_CPU0_P1P1_DN<3>")
	)
	(segment
		(start 138.636248 -55.302404)
		(end 138.529314 -55.409338)
		(width 0.0889)
		(layer "In9.Cu")
		(net "UPI_CPU1_CPU0_P1P1_DN<3>")
	)
	(segment
		(start 191.234314 -44.762166)
		(end 191.177926 -44.781978)
		(width 0.1143)
		(layer "In9.Cu")
		(net "UPI_CPU1_CPU0_P1P1_DN<3>")
	)
	(segment
		(start 150.344378 -48.314356)
		(end 143.572992 -51.1175)
		(width 0.1143)
		(layer "In9.Cu")
		(net "UPI_CPU1_CPU0_P1P1_DN<3>")
	)
	(segment
		(start 262.072882 -45.363892)
		(end 256.478024 -44.875196)
		(width 0.1143)
		(layer "In9.Cu")
		(net "UPI_CPU1_CPU0_P1P1_DN<3>")
	)
	(segment
		(start 181.78145 -44.35602)
		(end 168.984168 -48.81118)
		(width 0.1143)
		(layer "In9.Cu")
		(net "UPI_CPU1_CPU0_P1P1_DN<3>")
	)
	(segment
		(start 139.87399 -53.881274)
		(end 139.734544 -54.123336)
		(width 0.0889)
		(layer "In9.Cu")
		(net "UPI_CPU1_CPU0_P1P1_DN<3>")
	)
	(segment
		(start 290.576 -58.3692)
		(end 290.414456 -58.3692)
		(width 0.0889)
		(layer "In9.Cu")
		(net "UPI_CPU1_CPU0_P1P1_DN<3>")
	)
	(segment
		(start 247.845072 -46.199298)
		(end 240.326672 -44.6532)
		(width 0.1143)
		(layer "In9.Cu")
		(net "UPI_CPU1_CPU0_P1P1_DN<3>")
	)
	(segment
		(start 288.244026 -51.266344)
		(end 287.663128 -50.739802)
		(width 0.1143)
		(layer "In9.Cu")
		(net "UPI_CPU1_CPU0_P1P1_DN<3>")
	)
	(segment
		(start 288.264346 -51.284632)
		(end 288.264092 -51.284632)
		(width 0.1143)
		(layer "In9.Cu")
		(net "UPI_CPU1_CPU0_P1P1_DN<3>")
	)
	(segment
		(start 290.6522 -58.293)
		(end 290.576 -58.3692)
		(width 0.0889)
		(layer "In9.Cu")
		(net "UPI_CPU1_CPU0_P1P1_DN<3>")
	)
	(segment
		(start 142.220442 -51.7271)
		(end 141.906498 -51.7271)
		(width 0.1143)
		(layer "In9.Cu")
		(net "UPI_CPU1_CPU0_P1P1_DN<3>")
	)
	(segment
		(start 289.99307 -57.707022)
		(end 289.25012 -56.964072)
		(width 0.0889)
		(layer "In9.Cu")
		(net "UPI_CPU1_CPU0_P1P1_DN<3>")
	)
	(segment
		(start 288.728404 -52.64277)
		(end 288.728404 -52.377848)
		(width 0.0889)
		(layer "In9.Cu")
		(net "UPI_CPU1_CPU0_P1P1_DN<3>")
	)
	(segment
		(start 191.177926 -44.781978)
		(end 184.325006 -44.710858)
		(width 0.1143)
		(layer "In9.Cu")
		(net "UPI_CPU1_CPU0_P1P1_DN<3>")
	)
	(segment
		(start 211.906358 -44.840652)
		(end 199.254872 -41.665652)
		(width 0.1143)
		(layer "In9.Cu")
		(net "UPI_CPU1_CPU0_P1P1_DN<3>")
	)
	(segment
		(start 236.77372 -42.766996)
		(end 236.685328 -42.720006)
		(width 0.1143)
		(layer "In9.Cu")
		(net "UPI_CPU1_CPU0_P1P1_DN<3>")
	)
	(segment
		(start 240.326672 -44.6532)
		(end 236.77372 -42.766996)
		(width 0.1143)
		(layer "In9.Cu")
		(net "UPI_CPU1_CPU0_P1P1_DN<3>")
	)
	(segment
		(start 142.437104 -51.510438)
		(end 142.220442 -51.7271)
		(width 0.1143)
		(layer "In9.Cu")
		(net "UPI_CPU1_CPU0_P1P1_DN<3>")
	)
	(segment
		(start 143.38554 -51.1175)
		(end 142.437104 -51.510438)
		(width 0.1143)
		(layer "In9.Cu")
		(net "UPI_CPU1_CPU0_P1P1_DN<3>")
	)
	(segment
		(start 143.572992 -51.1175)
		(end 143.38554 -51.1175)
		(width 0.1143)
		(layer "In9.Cu")
		(net "UPI_CPU1_CPU0_P1P1_DN<3>")
	)
	(segment
		(start 288.728404 -52.377848)
		(end 288.779204 -52.327048)
		(width 0.0889)
		(layer "In9.Cu")
		(net "UPI_CPU1_CPU0_P1P1_DN<3>")
	)
	(arc
		(start 139.734544 -54.123336)
		(mid 139.595551 -54.265416)
		(end 139.40536 -54.323234)
		(width 0.0889)
		(layer "In9.Cu")
		(net "UPI_CPU1_CPU0_P1P1_DN<3>")
	)
	(arc
		(start 139.370054 -54.323234)
		(mid 138.963309 -54.502626)
		(end 138.796776 -54.9148)
		(width 0.0889)
		(layer "In9.Cu")
		(net "UPI_CPU1_CPU0_P1P1_DN<3>")
	)
	(arc
		(start 138.796776 -54.9148)
		(mid 138.755052 -55.124561)
		(end 138.636248 -55.302404)
		(width 0.0889)
		(layer "In9.Cu")
		(net "UPI_CPU1_CPU0_P1P1_DN<3>")
	)
	(segment
		(start 138.816334 -55.904384)
		(end 139.387834 -55.904384)
		(width 0.1143)
		(layer "F.Cu")
		(net "UPI_CPU1_CPU0_P1P1_DN<2>")
	)
	(segment
		(start 291.79774 -59.866784)
		(end 292.36924 -59.866784)
		(width 0.1143)
		(layer "F.Cu")
		(net "UPI_CPU1_CPU0_P1P1_DN<2>")
	)
	(via
		(at 292.36924 -59.866784)
		(size 0.508)
		(drill 0.254)
		(layers "F.Cu" "B.Cu")
		(net "UPI_CPU1_CPU0_P1P1_DN<2>")
	)
	(via
		(at 139.387834 -55.904384)
		(size 0.508)
		(drill 0.254)
		(layers "F.Cu" "B.Cu")
		(net "UPI_CPU1_CPU0_P1P1_DN<2>")
	)
	(segment
		(start 199.31888 -42.346626)
		(end 192.211452 -45.11929)
		(width 0.1143)
		(layer "In9.Cu")
		(net "UPI_CPU1_CPU0_P1P1_DN<2>")
	)
	(segment
		(start 192.211452 -45.11929)
		(end 191.344296 -45.429678)
		(width 0.1143)
		(layer "In9.Cu")
		(net "UPI_CPU1_CPU0_P1P1_DN<2>")
	)
	(segment
		(start 288.31032 -55.619904)
		(end 288.30397 -55.609236)
		(width 0.0889)
		(layer "In9.Cu")
		(net "UPI_CPU1_CPU0_P1P1_DN<2>")
	)
	(segment
		(start 169.44213 -49.39919)
		(end 164.829236 -50.342546)
		(width 0.1143)
		(layer "In9.Cu")
		(net "UPI_CPU1_CPU0_P1P1_DN<2>")
	)
	(segment
		(start 144.182084 -52.613814)
		(end 144.156938 -52.629308)
		(width 0.0889)
		(layer "In9.Cu")
		(net "UPI_CPU1_CPU0_P1P1_DN<2>")
	)
	(segment
		(start 282.983432 -49.730914)
		(end 265.061446 -45.351446)
		(width 0.1143)
		(layer "In9.Cu")
		(net "UPI_CPU1_CPU0_P1P1_DN<2>")
	)
	(segment
		(start 191.344296 -45.429678)
		(end 190.610236 -45.429678)
		(width 0.1143)
		(layer "In9.Cu")
		(net "UPI_CPU1_CPU0_P1P1_DN<2>")
	)
	(segment
		(start 139.715748 -56.133746)
		(end 139.664694 -56.206644)
		(width 0.0889)
		(layer "In9.Cu")
		(net "UPI_CPU1_CPU0_P1P1_DN<2>")
	)
	(segment
		(start 291.523674 -59.771534)
		(end 291.499544 -59.771534)
		(width 0.0889)
		(layer "In9.Cu")
		(net "UPI_CPU1_CPU0_P1P1_DN<2>")
	)
	(segment
		(start 284.629098 -51.110896)
		(end 283.388054 -50.070258)
		(width 0.1143)
		(layer "In9.Cu")
		(net "UPI_CPU1_CPU0_P1P1_DN<2>")
	)
	(segment
		(start 265.061446 -45.351446)
		(end 264.891266 -45.30979)
		(width 0.1143)
		(layer "In9.Cu")
		(net "UPI_CPU1_CPU0_P1P1_DN<2>")
	)
	(segment
		(start 286.448246 -51.846988)
		(end 285.845758 -51.2445)
		(width 0.0889)
		(layer "In9.Cu")
		(net "UPI_CPU1_CPU0_P1P1_DN<2>")
	)
	(segment
		(start 285.4325 -51.2445)
		(end 285.359602 -51.1937)
		(width 0.0889)
		(layer "In9.Cu")
		(net "UPI_CPU1_CPU0_P1P1_DN<2>")
	)
	(segment
		(start 140.260832 -54.818788)
		(end 140.224764 -54.818788)
		(width 0.0889)
		(layer "In9.Cu")
		(net "UPI_CPU1_CPU0_P1P1_DN<2>")
	)
	(segment
		(start 288.244026 -53.524404)
		(end 288.215832 -53.475636)
		(width 0.0889)
		(layer "In9.Cu")
		(net "UPI_CPU1_CPU0_P1P1_DN<2>")
	)
	(segment
		(start 287.420558 -51.846988)
		(end 286.448246 -51.846988)
		(width 0.0889)
		(layer "In9.Cu")
		(net "UPI_CPU1_CPU0_P1P1_DN<2>")
	)
	(segment
		(start 181.893718 -45.10913)
		(end 181.831996 -45.130212)
		(width 0.1143)
		(layer "In9.Cu")
		(net "UPI_CPU1_CPU0_P1P1_DN<2>")
	)
	(segment
		(start 290.411916 -59.276488)
		(end 288.927032 -57.791604)
		(width 0.0889)
		(layer "In9.Cu")
		(net "UPI_CPU1_CPU0_P1P1_DN<2>")
	)
	(segment
		(start 151.114506 -48.829214)
		(end 150.12416 -49.149254)
		(width 0.1143)
		(layer "In9.Cu")
		(net "UPI_CPU1_CPU0_P1P1_DN<2>")
	)
	(segment
		(start 139.387834 -56.119522)
		(end 139.387834 -55.904384)
		(width 0.0889)
		(layer "In9.Cu")
		(net "UPI_CPU1_CPU0_P1P1_DN<2>")
	)
	(segment
		(start 144.156938 -52.629308)
		(end 144.156938 -52.629816)
		(width 0.0889)
		(layer "In9.Cu")
		(net "UPI_CPU1_CPU0_P1P1_DN<2>")
	)
	(segment
		(start 288.30397 -56.599836)
		(end 288.299144 -56.5912)
		(width 0.0889)
		(layer "In9.Cu")
		(net "UPI_CPU1_CPU0_P1P1_DN<2>")
	)
	(segment
		(start 184.529984 -45.390308)
		(end 184.36971 -45.37329)
		(width 0.1143)
		(layer "In9.Cu")
		(net "UPI_CPU1_CPU0_P1P1_DN<2>")
	)
	(segment
		(start 288.30397 -55.609236)
		(end 288.299144 -55.6006)
		(width 0.0889)
		(layer "In9.Cu")
		(net "UPI_CPU1_CPU0_P1P1_DN<2>")
	)
	(segment
		(start 140.651484 -54.517544)
		(end 140.593064 -54.618636)
		(width 0.0889)
		(layer "In9.Cu")
		(net "UPI_CPU1_CPU0_P1P1_DN<2>")
	)
	(segment
		(start 290.670234 -59.276488)
		(end 290.411916 -59.276488)
		(width 0.0889)
		(layer "In9.Cu")
		(net "UPI_CPU1_CPU0_P1P1_DN<2>")
	)
	(segment
		(start 247.925844 -46.866556)
		(end 239.872266 -45.210984)
		(width 0.1143)
		(layer "In9.Cu")
		(net "UPI_CPU1_CPU0_P1P1_DN<2>")
	)
	(segment
		(start 181.831996 -45.130212)
		(end 181.831996 -45.130466)
		(width 0.1143)
		(layer "In9.Cu")
		(net "UPI_CPU1_CPU0_P1P1_DN<2>")
	)
	(segment
		(start 211.828634 -45.514514)
		(end 208.286604 -44.680124)
		(width 0.1143)
		(layer "In9.Cu")
		(net "UPI_CPU1_CPU0_P1P1_DN<2>")
	)
	(segment
		(start 184.36971 -45.37329)
		(end 181.893718 -45.10913)
		(width 0.1143)
		(layer "In9.Cu")
		(net "UPI_CPU1_CPU0_P1P1_DN<2>")
	)
	(segment
		(start 190.610236 -45.429678)
		(end 184.529984 -45.390308)
		(width 0.1143)
		(layer "In9.Cu")
		(net "UPI_CPU1_CPU0_P1P1_DN<2>")
	)
	(segment
		(start 288.31032 -54.629304)
		(end 288.30397 -54.618636)
		(width 0.0889)
		(layer "In9.Cu")
		(net "UPI_CPU1_CPU0_P1P1_DN<2>")
	)
	(segment
		(start 164.829236 -50.342546)
		(end 159.990282 -49.429416)
		(width 0.1143)
		(layer "In9.Cu")
		(net "UPI_CPU1_CPU0_P1P1_DN<2>")
	)
	(segment
		(start 288.31032 -56.610504)
		(end 288.30397 -56.599836)
		(width 0.0889)
		(layer "In9.Cu")
		(net "UPI_CPU1_CPU0_P1P1_DN<2>")
	)
	(segment
		(start 140.992352 -54.176676)
		(end 140.651484 -54.517544)
		(width 0.0889)
		(layer "In9.Cu")
		(net "UPI_CPU1_CPU0_P1P1_DN<2>")
	)
	(segment
		(start 239.872266 -45.210984)
		(end 236.432344 -43.383454)
		(width 0.1143)
		(layer "In9.Cu")
		(net "UPI_CPU1_CPU0_P1P1_DN<2>")
	)
	(segment
		(start 146.790156 -50.531776)
		(end 145.223738 -51.685444)
		(width 0.1143)
		(layer "In9.Cu")
		(net "UPI_CPU1_CPU0_P1P1_DN<2>")
	)
	(segment
		(start 285.845758 -51.2445)
		(end 285.4325 -51.2445)
		(width 0.0889)
		(layer "In9.Cu")
		(net "UPI_CPU1_CPU0_P1P1_DN<2>")
	)
	(segment
		(start 284.723332 -51.1937)
		(end 284.629098 -51.110896)
		(width 0.1143)
		(layer "In9.Cu")
		(net "UPI_CPU1_CPU0_P1P1_DN<2>")
	)
	(segment
		(start 256.618994 -45.579284)
		(end 256.237994 -45.554646)
		(width 0.1143)
		(layer "In9.Cu")
		(net "UPI_CPU1_CPU0_P1P1_DN<2>")
	)
	(segment
		(start 145.205196 -51.808634)
		(end 144.1958 -52.5526)
		(width 0.1143)
		(layer "In9.Cu")
		(net "UPI_CPU1_CPU0_P1P1_DN<2>")
	)
	(segment
		(start 181.831996 -45.130466)
		(end 169.44213 -49.39919)
		(width 0.1143)
		(layer "In9.Cu")
		(net "UPI_CPU1_CPU0_P1P1_DN<2>")
	)
	(segment
		(start 144.156938 -52.629816)
		(end 142.238222 -53.821076)
		(width 0.0889)
		(layer "In9.Cu")
		(net "UPI_CPU1_CPU0_P1P1_DN<2>")
	)
	(segment
		(start 145.223738 -51.685444)
		(end 145.205196 -51.808634)
		(width 0.1143)
		(layer "In9.Cu")
		(net "UPI_CPU1_CPU0_P1P1_DN<2>")
	)
	(segment
		(start 208.286604 -44.680124)
		(end 199.31888 -42.346626)
		(width 0.1143)
		(layer "In9.Cu")
		(net "UPI_CPU1_CPU0_P1P1_DN<2>")
	)
	(segment
		(start 144.1958 -52.600098)
		(end 144.182084 -52.613814)
		(width 0.0889)
		(layer "In9.Cu")
		(net "UPI_CPU1_CPU0_P1P1_DN<2>")
	)
	(segment
		(start 288.215832 -52.642262)
		(end 287.420558 -51.846988)
		(width 0.0889)
		(layer "In9.Cu")
		(net "UPI_CPU1_CPU0_P1P1_DN<2>")
	)
	(segment
		(start 288.30397 -54.618636)
		(end 288.299144 -54.61)
		(width 0.0889)
		(layer "In9.Cu")
		(net "UPI_CPU1_CPU0_P1P1_DN<2>")
	)
	(segment
		(start 222.396812 -44.599098)
		(end 211.828634 -45.514514)
		(width 0.1143)
		(layer "In9.Cu")
		(net "UPI_CPU1_CPU0_P1P1_DN<2>")
	)
	(segment
		(start 292.36924 -59.866784)
		(end 292.4048 -60.1472)
		(width 0.0889)
		(layer "In9.Cu")
		(net "UPI_CPU1_CPU0_P1P1_DN<2>")
	)
	(segment
		(start 159.990282 -49.429416)
		(end 155.901898 -47.735998)
		(width 0.1143)
		(layer "In9.Cu")
		(net "UPI_CPU1_CPU0_P1P1_DN<2>")
	)
	(segment
		(start 288.309812 -53.63845)
		(end 288.244026 -53.524404)
		(width 0.0889)
		(layer "In9.Cu")
		(net "UPI_CPU1_CPU0_P1P1_DN<2>")
	)
	(segment
		(start 144.1958 -52.5526)
		(end 144.1958 -52.600098)
		(width 0.0889)
		(layer "In9.Cu")
		(net "UPI_CPU1_CPU0_P1P1_DN<2>")
	)
	(segment
		(start 283.388054 -50.070258)
		(end 283.3878 -50.070258)
		(width 0.1143)
		(layer "In9.Cu")
		(net "UPI_CPU1_CPU0_P1P1_DN<2>")
	)
	(segment
		(start 262.098536 -46.046136)
		(end 256.618994 -45.579284)
		(width 0.1143)
		(layer "In9.Cu")
		(net "UPI_CPU1_CPU0_P1P1_DN<2>")
	)
	(segment
		(start 256.237994 -45.554646)
		(end 247.925844 -46.866556)
		(width 0.1143)
		(layer "In9.Cu")
		(net "UPI_CPU1_CPU0_P1P1_DN<2>")
	)
	(segment
		(start 139.728194 -55.693818)
		(end 139.734544 -55.704486)
		(width 0.0889)
		(layer "In9.Cu")
		(net "UPI_CPU1_CPU0_P1P1_DN<2>")
	)
	(segment
		(start 292.4048 -60.1472)
		(end 292.296596 -60.26023)
		(width 0.0889)
		(layer "In9.Cu")
		(net "UPI_CPU1_CPU0_P1P1_DN<2>")
	)
	(segment
		(start 290.67379 -59.276234)
		(end 290.670234 -59.276488)
		(width 0.0889)
		(layer "In9.Cu")
		(net "UPI_CPU1_CPU0_P1P1_DN<2>")
	)
	(segment
		(start 155.901898 -47.735998)
		(end 151.114506 -48.829214)
		(width 0.1143)
		(layer "In9.Cu")
		(net "UPI_CPU1_CPU0_P1P1_DN<2>")
	)
	(segment
		(start 288.215832 -53.475636)
		(end 288.215832 -52.642262)
		(width 0.0889)
		(layer "In9.Cu")
		(net "UPI_CPU1_CPU0_P1P1_DN<2>")
	)
	(segment
		(start 288.927032 -57.791604)
		(end 288.650934 -57.791604)
		(width 0.0889)
		(layer "In9.Cu")
		(net "UPI_CPU1_CPU0_P1P1_DN<2>")
	)
	(segment
		(start 283.3878 -50.070258)
		(end 282.983432 -49.730914)
		(width 0.1143)
		(layer "In9.Cu")
		(net "UPI_CPU1_CPU0_P1P1_DN<2>")
	)
	(segment
		(start 139.734544 -55.704486)
		(end 139.73937 -55.713122)
		(width 0.0889)
		(layer "In9.Cu")
		(net "UPI_CPU1_CPU0_P1P1_DN<2>")
	)
	(segment
		(start 150.12416 -49.149254)
		(end 146.790156 -50.531776)
		(width 0.1143)
		(layer "In9.Cu")
		(net "UPI_CPU1_CPU0_P1P1_DN<2>")
	)
	(segment
		(start 142.238222 -53.821076)
		(end 140.992352 -54.176676)
		(width 0.0889)
		(layer "In9.Cu")
		(net "UPI_CPU1_CPU0_P1P1_DN<2>")
	)
	(segment
		(start 236.432344 -43.383454)
		(end 222.396812 -44.599098)
		(width 0.1143)
		(layer "In9.Cu")
		(net "UPI_CPU1_CPU0_P1P1_DN<2>")
	)
	(segment
		(start 285.359602 -51.1937)
		(end 284.723332 -51.1937)
		(width 0.1143)
		(layer "In9.Cu")
		(net "UPI_CPU1_CPU0_P1P1_DN<2>")
	)
	(segment
		(start 264.891266 -45.30979)
		(end 262.098536 -46.046136)
		(width 0.1143)
		(layer "In9.Cu")
		(net "UPI_CPU1_CPU0_P1P1_DN<2>")
	)
	(arc
		(start 288.299144 -55.6006)
		(mid 288.250389 -55.404248)
		(end 288.30397 -55.209186)
		(width 0.0889)
		(layer "In9.Cu")
		(net "UPI_CPU1_CPU0_P1P1_DN<2>")
	)
	(arc
		(start 139.73937 -55.713122)
		(mid 139.787404 -55.926799)
		(end 139.715748 -56.133746)
		(width 0.0889)
		(layer "In9.Cu")
		(net "UPI_CPU1_CPU0_P1P1_DN<2>")
	)
	(arc
		(start 288.30397 -56.199786)
		(mid 288.383192 -55.910668)
		(end 288.31032 -55.619904)
		(width 0.0889)
		(layer "In9.Cu")
		(net "UPI_CPU1_CPU0_P1P1_DN<2>")
	)
	(arc
		(start 288.299144 -56.5912)
		(mid 288.250389 -56.394848)
		(end 288.30397 -56.199786)
		(width 0.0889)
		(layer "In9.Cu")
		(net "UPI_CPU1_CPU0_P1P1_DN<2>")
	)
	(arc
		(start 288.30397 -57.190386)
		(mid 288.383192 -56.901268)
		(end 288.31032 -56.610504)
		(width 0.0889)
		(layer "In9.Cu")
		(net "UPI_CPU1_CPU0_P1P1_DN<2>")
	)
	(arc
		(start 291.499544 -59.771534)
		(mid 291.305694 -59.715184)
		(end 291.16401 -59.571382)
		(width 0.0889)
		(layer "In9.Cu")
		(net "UPI_CPU1_CPU0_P1P1_DN<2>")
	)
	(arc
		(start 292.296596 -60.26023)
		(mid 292.138321 -60.19369)
		(end 292.02253 -60.066936)
		(width 0.0889)
		(layer "In9.Cu")
		(net "UPI_CPU1_CPU0_P1P1_DN<2>")
	)
	(arc
		(start 288.30397 -55.209186)
		(mid 288.383192 -54.920068)
		(end 288.31032 -54.629304)
		(width 0.0889)
		(layer "In9.Cu")
		(net "UPI_CPU1_CPU0_P1P1_DN<2>")
	)
	(arc
		(start 288.650934 -57.791604)
		(mid 288.304024 -57.591111)
		(end 288.30397 -57.190386)
		(width 0.0889)
		(layer "In9.Cu")
		(net "UPI_CPU1_CPU0_P1P1_DN<2>")
	)
	(arc
		(start 140.224764 -54.818788)
		(mid 139.732374 -55.117721)
		(end 139.728194 -55.693818)
		(width 0.0889)
		(layer "In9.Cu")
		(net "UPI_CPU1_CPU0_P1P1_DN<2>")
	)
	(arc
		(start 288.30397 -54.218586)
		(mid 288.382945 -53.929297)
		(end 288.309812 -53.63845)
		(width 0.0889)
		(layer "In9.Cu")
		(net "UPI_CPU1_CPU0_P1P1_DN<2>")
	)
	(arc
		(start 288.299144 -54.61)
		(mid 288.250389 -54.413648)
		(end 288.30397 -54.218586)
		(width 0.0889)
		(layer "In9.Cu")
		(net "UPI_CPU1_CPU0_P1P1_DN<2>")
	)
	(arc
		(start 291.16401 -59.571382)
		(mid 290.957006 -59.360518)
		(end 290.67379 -59.276234)
		(width 0.0889)
		(layer "In9.Cu")
		(net "UPI_CPU1_CPU0_P1P1_DN<2>")
	)
	(arc
		(start 140.593064 -54.618636)
		(mid 140.452796 -54.761592)
		(end 140.260832 -54.818788)
		(width 0.0889)
		(layer "In9.Cu")
		(net "UPI_CPU1_CPU0_P1P1_DN<2>")
	)
	(arc
		(start 292.02253 -60.066936)
		(mid 291.811817 -59.853857)
		(end 291.523674 -59.771534)
		(width 0.0889)
		(layer "In9.Cu")
		(net "UPI_CPU1_CPU0_P1P1_DN<2>")
	)
	(arc
		(start 139.664694 -56.206644)
		(mid 139.494313 -56.264637)
		(end 139.387834 -56.119522)
		(width 0.0889)
		(layer "In9.Cu")
		(net "UPI_CPU1_CPU0_P1P1_DN<2>")
	)
	(segment
		(start 290.0807 -60.857384)
		(end 290.6522 -60.857384)
		(width 0.1143)
		(layer "F.Cu")
		(net "UPI_CPU1_CPU0_P1P1_DN<1>")
	)
	(segment
		(start 140.533374 -55.904384)
		(end 141.104874 -55.904384)
		(width 0.1143)
		(layer "F.Cu")
		(net "UPI_CPU1_CPU0_P1P1_DN<1>")
	)
	(via
		(at 290.6522 -60.857384)
		(size 0.508)
		(drill 0.254)
		(layers "F.Cu" "B.Cu")
		(net "UPI_CPU1_CPU0_P1P1_DN<1>")
	)
	(via
		(at 141.104874 -55.904384)
		(size 0.508)
		(drill 0.254)
		(layers "F.Cu" "B.Cu")
		(net "UPI_CPU1_CPU0_P1P1_DN<1>")
	)
	(segment
		(start 142.720568 -55.313834)
		(end 142.515082 -55.701692)
		(width 0.0889)
		(layer "In9.Cu")
		(net "UPI_CPU1_CPU0_P1P1_DN<1>")
	)
	(segment
		(start 280.926032 -51.7017)
		(end 278.886412 -49.968658)
		(width 0.1143)
		(layer "In9.Cu")
		(net "UPI_CPU1_CPU0_P1P1_DN<1>")
	)
	(segment
		(start 143.13916 -55.245508)
		(end 142.984728 -55.308246)
		(width 0.0889)
		(layer "In9.Cu")
		(net "UPI_CPU1_CPU0_P1P1_DN<1>")
	)
	(segment
		(start 143.19123 -55.122318)
		(end 143.13916 -55.245508)
		(width 0.0889)
		(layer "In9.Cu")
		(net "UPI_CPU1_CPU0_P1P1_DN<1>")
	)
	(segment
		(start 142.861538 -55.25643)
		(end 142.720568 -55.313834)
		(width 0.0889)
		(layer "In9.Cu")
		(net "UPI_CPU1_CPU0_P1P1_DN<1>")
	)
	(segment
		(start 145.275046 -54.146958)
		(end 144.389348 -54.690518)
		(width 0.1143)
		(layer "In9.Cu")
		(net "UPI_CPU1_CPU0_P1P1_DN<1>")
	)
	(segment
		(start 286.478726 -53.027072)
		(end 285.883858 -52.432204)
		(width 0.0889)
		(layer "In9.Cu")
		(net "UPI_CPU1_CPU0_P1P1_DN<1>")
	)
	(segment
		(start 287.274 -55.619904)
		(end 287.28035 -55.609236)
		(width 0.0889)
		(layer "In9.Cu")
		(net "UPI_CPU1_CPU0_P1P1_DN<1>")
	)
	(segment
		(start 287.351724 -53.504846)
		(end 287.351724 -53.196998)
		(width 0.0889)
		(layer "In9.Cu")
		(net "UPI_CPU1_CPU0_P1P1_DN<1>")
	)
	(segment
		(start 290.34613 -60.457334)
		(end 288.8615 -58.972704)
		(width 0.0889)
		(layer "In9.Cu")
		(net "UPI_CPU1_CPU0_P1P1_DN<1>")
	)
	(segment
		(start 193.562986 -45.643292)
		(end 191.51854 -46.381416)
		(width 0.1143)
		(layer "In9.Cu")
		(net "UPI_CPU1_CPU0_P1P1_DN<1>")
	)
	(segment
		(start 145.71726 -54.06644)
		(end 145.49882 -54.200806)
		(width 0.1143)
		(layer "In9.Cu")
		(net "UPI_CPU1_CPU0_P1P1_DN<1>")
	)
	(segment
		(start 164.912294 -51.375818)
		(end 160.027112 -50.45075)
		(width 0.1143)
		(layer "In9.Cu")
		(net "UPI_CPU1_CPU0_P1P1_DN<1>")
	)
	(segment
		(start 287.79089 -58.476388)
		(end 287.779206 -58.476388)
		(width 0.0889)
		(layer "In9.Cu")
		(net "UPI_CPU1_CPU0_P1P1_DN<1>")
	)
	(segment
		(start 181.938676 -46.14545)
		(end 169.518076 -50.3682)
		(width 0.1143)
		(layer "In9.Cu")
		(net "UPI_CPU1_CPU0_P1P1_DN<1>")
	)
	(segment
		(start 290.6522 -60.857384)
		(end 290.846256 -60.857384)
		(width 0.0889)
		(layer "In9.Cu")
		(net "UPI_CPU1_CPU0_P1P1_DN<1>")
	)
	(segment
		(start 143.968724 -54.86146)
		(end 143.902176 -54.833266)
		(width 0.0889)
		(layer "In9.Cu")
		(net "UPI_CPU1_CPU0_P1P1_DN<1>")
	)
	(segment
		(start 140.758164 -55.704486)
		(end 140.753338 -55.713122)
		(width 0.0889)
		(layer "In9.Cu")
		(net "UPI_CPU1_CPU0_P1P1_DN<1>")
	)
	(segment
		(start 155.877514 -48.73371)
		(end 151.77135 -49.64557)
		(width 0.1143)
		(layer "In9.Cu")
		(net "UPI_CPU1_CPU0_P1P1_DN<1>")
	)
	(segment
		(start 287.28035 -57.590436)
		(end 287.285176 -57.5818)
		(width 0.0889)
		(layer "In9.Cu")
		(net "UPI_CPU1_CPU0_P1P1_DN<1>")
	)
	(segment
		(start 145.49882 -54.200806)
		(end 145.275046 -54.146958)
		(width 0.1143)
		(layer "In9.Cu")
		(net "UPI_CPU1_CPU0_P1P1_DN<1>")
	)
	(segment
		(start 287.274508 -53.63845)
		(end 287.351724 -53.504846)
		(width 0.0889)
		(layer "In9.Cu")
		(net "UPI_CPU1_CPU0_P1P1_DN<1>")
	)
	(segment
		(start 140.890498 -56.119268)
		(end 140.891006 -56.119268)
		(width 0.0889)
		(layer "In9.Cu")
		(net "UPI_CPU1_CPU0_P1P1_DN<1>")
	)
	(segment
		(start 143.902176 -54.833266)
		(end 143.19123 -55.122318)
		(width 0.0889)
		(layer "In9.Cu")
		(net "UPI_CPU1_CPU0_P1P1_DN<1>")
	)
	(segment
		(start 239.451388 -46.083982)
		(end 236.208824 -44.362624)
		(width 0.1143)
		(layer "In9.Cu")
		(net "UPI_CPU1_CPU0_P1P1_DN<1>")
	)
	(segment
		(start 184.300876 -46.317916)
		(end 181.938676 -46.14545)
		(width 0.1143)
		(layer "In9.Cu")
		(net "UPI_CPU1_CPU0_P1P1_DN<1>")
	)
	(segment
		(start 222.396812 -45.553376)
		(end 211.521294 -46.49089)
		(width 0.1143)
		(layer "In9.Cu")
		(net "UPI_CPU1_CPU0_P1P1_DN<1>")
	)
	(segment
		(start 169.518076 -50.3682)
		(end 164.912294 -51.375818)
		(width 0.1143)
		(layer "In9.Cu")
		(net "UPI_CPU1_CPU0_P1P1_DN<1>")
	)
	(segment
		(start 199.3646 -43.340274)
		(end 193.562986 -45.643292)
		(width 0.1143)
		(layer "In9.Cu")
		(net "UPI_CPU1_CPU0_P1P1_DN<1>")
	)
	(segment
		(start 287.274 -57.601104)
		(end 287.28035 -57.590436)
		(width 0.0889)
		(layer "In9.Cu")
		(net "UPI_CPU1_CPU0_P1P1_DN<1>")
	)
	(segment
		(start 285.883858 -52.432204)
		(end 285.494222 -52.432204)
		(width 0.0889)
		(layer "In9.Cu")
		(net "UPI_CPU1_CPU0_P1P1_DN<1>")
	)
	(segment
		(start 147.68449 -52.668424)
		(end 145.771108 -53.842666)
		(width 0.1143)
		(layer "In9.Cu")
		(net "UPI_CPU1_CPU0_P1P1_DN<1>")
	)
	(segment
		(start 285.494222 -52.432204)
		(end 285.443422 -52.483004)
		(width 0.0889)
		(layer "In9.Cu")
		(net "UPI_CPU1_CPU0_P1P1_DN<1>")
	)
	(segment
		(start 142.984728 -55.308246)
		(end 142.861538 -55.25643)
		(width 0.0889)
		(layer "In9.Cu")
		(net "UPI_CPU1_CPU0_P1P1_DN<1>")
	)
	(segment
		(start 285.421324 -52.483004)
		(end 284.221936 -52.483004)
		(width 0.1143)
		(layer "In9.Cu")
		(net "UPI_CPU1_CPU0_P1P1_DN<1>")
	)
	(segment
		(start 288.8615 -58.972704)
		(end 288.652458 -58.972704)
		(width 0.0889)
		(layer "In9.Cu")
		(net "UPI_CPU1_CPU0_P1P1_DN<1>")
	)
	(segment
		(start 285.443422 -52.483004)
		(end 285.421324 -52.483004)
		(width 0.0889)
		(layer "In9.Cu")
		(net "UPI_CPU1_CPU0_P1P1_DN<1>")
	)
	(segment
		(start 278.886412 -49.968658)
		(end 264.83945 -46.32071)
		(width 0.1143)
		(layer "In9.Cu")
		(net "UPI_CPU1_CPU0_P1P1_DN<1>")
	)
	(segment
		(start 290.663376 -60.457334)
		(end 290.34613 -60.457334)
		(width 0.0889)
		(layer "In9.Cu")
		(net "UPI_CPU1_CPU0_P1P1_DN<1>")
	)
	(segment
		(start 287.351724 -53.196998)
		(end 287.181798 -53.027072)
		(width 0.0889)
		(layer "In9.Cu")
		(net "UPI_CPU1_CPU0_P1P1_DN<1>")
	)
	(segment
		(start 191.51854 -46.381416)
		(end 184.300876 -46.317916)
		(width 0.1143)
		(layer "In9.Cu")
		(net "UPI_CPU1_CPU0_P1P1_DN<1>")
	)
	(segment
		(start 140.891006 -56.119268)
		(end 141.075664 -56.01335)
		(width 0.0889)
		(layer "In9.Cu")
		(net "UPI_CPU1_CPU0_P1P1_DN<1>")
	)
	(segment
		(start 160.027112 -50.45075)
		(end 155.877514 -48.73371)
		(width 0.1143)
		(layer "In9.Cu")
		(net "UPI_CPU1_CPU0_P1P1_DN<1>")
	)
	(segment
		(start 287.181798 -53.027072)
		(end 286.478726 -53.027072)
		(width 0.0889)
		(layer "In9.Cu")
		(net "UPI_CPU1_CPU0_P1P1_DN<1>")
	)
	(segment
		(start 287.28035 -54.618636)
		(end 287.285176 -54.61)
		(width 0.0889)
		(layer "In9.Cu")
		(net "UPI_CPU1_CPU0_P1P1_DN<1>")
	)
	(segment
		(start 287.274 -56.610504)
		(end 287.28035 -56.599836)
		(width 0.0889)
		(layer "In9.Cu")
		(net "UPI_CPU1_CPU0_P1P1_DN<1>")
	)
	(segment
		(start 283.440632 -51.7017)
		(end 280.926032 -51.7017)
		(width 0.1143)
		(layer "In9.Cu")
		(net "UPI_CPU1_CPU0_P1P1_DN<1>")
	)
	(segment
		(start 236.208824 -44.362624)
		(end 222.396812 -45.553376)
		(width 0.1143)
		(layer "In9.Cu")
		(net "UPI_CPU1_CPU0_P1P1_DN<1>")
	)
	(segment
		(start 287.28035 -55.609236)
		(end 287.285176 -55.6006)
		(width 0.0889)
		(layer "In9.Cu")
		(net "UPI_CPU1_CPU0_P1P1_DN<1>")
	)
	(segment
		(start 287.274 -54.629304)
		(end 287.28035 -54.618636)
		(width 0.0889)
		(layer "In9.Cu")
		(net "UPI_CPU1_CPU0_P1P1_DN<1>")
	)
	(segment
		(start 264.83945 -46.32071)
		(end 262.268716 -47.017432)
		(width 0.1143)
		(layer "In9.Cu")
		(net "UPI_CPU1_CPU0_P1P1_DN<1>")
	)
	(segment
		(start 144.389348 -54.690518)
		(end 143.968724 -54.86146)
		(width 0.1143)
		(layer "In9.Cu")
		(net "UPI_CPU1_CPU0_P1P1_DN<1>")
	)
	(segment
		(start 287.791144 -58.476134)
		(end 287.79089 -58.476388)
		(width 0.0889)
		(layer "In9.Cu")
		(net "UPI_CPU1_CPU0_P1P1_DN<1>")
	)
	(segment
		(start 284.221936 -52.483004)
		(end 283.440632 -51.7017)
		(width 0.1143)
		(layer "In9.Cu")
		(net "UPI_CPU1_CPU0_P1P1_DN<1>")
	)
	(segment
		(start 145.771108 -53.842666)
		(end 145.71726 -54.06644)
		(width 0.1143)
		(layer "In9.Cu")
		(net "UPI_CPU1_CPU0_P1P1_DN<1>")
	)
	(segment
		(start 287.802574 -58.476134)
		(end 287.791144 -58.476134)
		(width 0.0889)
		(layer "In9.Cu")
		(net "UPI_CPU1_CPU0_P1P1_DN<1>")
	)
	(segment
		(start 141.075664 -56.01335)
		(end 141.104874 -55.904384)
		(width 0.0889)
		(layer "In9.Cu")
		(net "UPI_CPU1_CPU0_P1P1_DN<1>")
	)
	(segment
		(start 256.367788 -46.506892)
		(end 247.876314 -47.81423)
		(width 0.1143)
		(layer "In9.Cu")
		(net "UPI_CPU1_CPU0_P1P1_DN<1>")
	)
	(segment
		(start 290.966652 -60.609734)
		(end 290.966398 -60.609734)
		(width 0.0889)
		(layer "In9.Cu")
		(net "UPI_CPU1_CPU0_P1P1_DN<1>")
	)
	(segment
		(start 142.166086 -55.999888)
		(end 141.949678 -55.999888)
		(width 0.0889)
		(layer "In9.Cu")
		(net "UPI_CPU1_CPU0_P1P1_DN<1>")
	)
	(segment
		(start 287.28035 -56.599836)
		(end 287.285176 -56.5912)
		(width 0.0889)
		(layer "In9.Cu")
		(net "UPI_CPU1_CPU0_P1P1_DN<1>")
	)
	(segment
		(start 151.77135 -49.64557)
		(end 147.68449 -52.668424)
		(width 0.1143)
		(layer "In9.Cu")
		(net "UPI_CPU1_CPU0_P1P1_DN<1>")
	)
	(segment
		(start 211.521294 -46.49089)
		(end 199.3646 -43.340274)
		(width 0.1143)
		(layer "In9.Cu")
		(net "UPI_CPU1_CPU0_P1P1_DN<1>")
	)
	(segment
		(start 247.876314 -47.81423)
		(end 239.451388 -46.083982)
		(width 0.1143)
		(layer "In9.Cu")
		(net "UPI_CPU1_CPU0_P1P1_DN<1>")
	)
	(segment
		(start 262.268716 -47.017432)
		(end 256.367788 -46.506892)
		(width 0.1143)
		(layer "In9.Cu")
		(net "UPI_CPU1_CPU0_P1P1_DN<1>")
	)
	(arc
		(start 141.949678 -55.999888)
		(mid 141.661991 -55.917367)
		(end 141.451584 -55.704486)
		(width 0.0889)
		(layer "In9.Cu")
		(net "UPI_CPU1_CPU0_P1P1_DN<1>")
	)
	(arc
		(start 287.285176 -54.61)
		(mid 287.333931 -54.413648)
		(end 287.28035 -54.218586)
		(width 0.0889)
		(layer "In9.Cu")
		(net "UPI_CPU1_CPU0_P1P1_DN<1>")
	)
	(arc
		(start 140.753338 -55.713122)
		(mid 140.726626 -55.773315)
		(end 140.710158 -55.837074)
		(width 0.0889)
		(layer "In9.Cu")
		(net "UPI_CPU1_CPU0_P1P1_DN<1>")
	)
	(arc
		(start 142.515082 -55.701692)
		(mid 142.368982 -55.884026)
		(end 142.166086 -55.999888)
		(width 0.0889)
		(layer "In9.Cu")
		(net "UPI_CPU1_CPU0_P1P1_DN<1>")
	)
	(arc
		(start 287.285176 -55.6006)
		(mid 287.333931 -55.404248)
		(end 287.28035 -55.209186)
		(width 0.0889)
		(layer "In9.Cu")
		(net "UPI_CPU1_CPU0_P1P1_DN<1>")
	)
	(arc
		(start 290.966398 -60.609734)
		(mid 290.90501 -60.547324)
		(end 290.831524 -60.499752)
		(width 0.0889)
		(layer "In9.Cu")
		(net "UPI_CPU1_CPU0_P1P1_DN<1>")
	)
	(arc
		(start 287.285176 -57.5818)
		(mid 287.333931 -57.385448)
		(end 287.28035 -57.190386)
		(width 0.0889)
		(layer "In9.Cu")
		(net "UPI_CPU1_CPU0_P1P1_DN<1>")
	)
	(arc
		(start 288.13887 -58.676286)
		(mid 287.996827 -58.532374)
		(end 287.802574 -58.476134)
		(width 0.0889)
		(layer "In9.Cu")
		(net "UPI_CPU1_CPU0_P1P1_DN<1>")
	)
	(arc
		(start 287.28035 -57.190386)
		(mid 287.201128 -56.901268)
		(end 287.274 -56.610504)
		(width 0.0889)
		(layer "In9.Cu")
		(net "UPI_CPU1_CPU0_P1P1_DN<1>")
	)
	(arc
		(start 287.285176 -56.5912)
		(mid 287.333931 -56.394848)
		(end 287.28035 -56.199786)
		(width 0.0889)
		(layer "In9.Cu")
		(net "UPI_CPU1_CPU0_P1P1_DN<1>")
	)
	(arc
		(start 287.28035 -55.209186)
		(mid 287.201128 -54.920068)
		(end 287.274 -54.629304)
		(width 0.0889)
		(layer "In9.Cu")
		(net "UPI_CPU1_CPU0_P1P1_DN<1>")
	)
	(arc
		(start 141.451584 -55.704486)
		(mid 141.104874 -55.504175)
		(end 140.758164 -55.704486)
		(width 0.0889)
		(layer "In9.Cu")
		(net "UPI_CPU1_CPU0_P1P1_DN<1>")
	)
	(arc
		(start 290.846256 -60.857384)
		(mid 290.98399 -60.771213)
		(end 290.966652 -60.609734)
		(width 0.0889)
		(layer "In9.Cu")
		(net "UPI_CPU1_CPU0_P1P1_DN<1>")
	)
	(arc
		(start 290.831524 -60.499752)
		(mid 290.749773 -60.469339)
		(end 290.663376 -60.457334)
		(width 0.0889)
		(layer "In9.Cu")
		(net "UPI_CPU1_CPU0_P1P1_DN<1>")
	)
	(arc
		(start 140.710158 -55.837074)
		(mid 140.745889 -56.012935)
		(end 140.890498 -56.119268)
		(width 0.0889)
		(layer "In9.Cu")
		(net "UPI_CPU1_CPU0_P1P1_DN<1>")
	)
	(arc
		(start 287.28035 -56.199786)
		(mid 287.201128 -55.910668)
		(end 287.274 -55.619904)
		(width 0.0889)
		(layer "In9.Cu")
		(net "UPI_CPU1_CPU0_P1P1_DN<1>")
	)
	(arc
		(start 287.779206 -58.476388)
		(mid 287.280325 -58.180951)
		(end 287.274 -57.601104)
		(width 0.0889)
		(layer "In9.Cu")
		(net "UPI_CPU1_CPU0_P1P1_DN<1>")
	)
	(arc
		(start 287.28035 -54.218586)
		(mid 287.201375 -53.929297)
		(end 287.274508 -53.63845)
		(width 0.0889)
		(layer "In9.Cu")
		(net "UPI_CPU1_CPU0_P1P1_DN<1>")
	)
	(arc
		(start 288.652458 -58.972704)
		(mid 288.355855 -58.893427)
		(end 288.13887 -58.676286)
		(width 0.0889)
		(layer "In9.Cu")
		(net "UPI_CPU1_CPU0_P1P1_DN<1>")
	)
	(segment
		(start 303.816766 -58.876438)
		(end 304.388266 -58.876438)
		(width 0.1143)
		(layer "F.Cu")
		(net "UPI_CPU1_CPU0_P1P1_DN<19>")
	)
	(segment
		(start 125.080268 -55.904384)
		(end 125.651768 -55.904384)
		(width 0.1143)
		(layer "F.Cu")
		(net "UPI_CPU1_CPU0_P1P1_DN<19>")
	)
	(via
		(at 304.388266 -58.876438)
		(size 0.508)
		(drill 0.254)
		(layers "F.Cu" "B.Cu")
		(net "UPI_CPU1_CPU0_P1P1_DN<19>")
	)
	(via
		(at 125.651768 -55.904384)
		(size 0.508)
		(drill 0.254)
		(layers "F.Cu" "B.Cu")
		(net "UPI_CPU1_CPU0_P1P1_DN<19>")
	)
	(segment
		(start 212.324188 -33.669224)
		(end 222.396812 -32.921448)
		(width 0.1143)
		(layer "In9.Cu")
		(net "UPI_CPU1_CPU0_P1P1_DN<19>")
	)
	(segment
		(start 304.40122 -58.476388)
		(end 304.37709 -58.476388)
		(width 0.0889)
		(layer "In9.Cu")
		(net "UPI_CPU1_CPU0_P1P1_DN<19>")
	)
	(segment
		(start 146.74088 -37.167566)
		(end 162.444938 -33.416748)
		(width 0.1143)
		(layer "In9.Cu")
		(net "UPI_CPU1_CPU0_P1P1_DN<19>")
	)
	(segment
		(start 199.115426 -30.24759)
		(end 212.324188 -33.66897)
		(width 0.1143)
		(layer "In9.Cu")
		(net "UPI_CPU1_CPU0_P1P1_DN<19>")
	)
	(segment
		(start 304.074068 -58.628788)
		(end 304.09515 -58.707528)
		(width 0.0889)
		(layer "In9.Cu")
		(net "UPI_CPU1_CPU0_P1P1_DN<19>")
	)
	(segment
		(start 130.465576 -42.432478)
		(end 132.211826 -40.231568)
		(width 0.1143)
		(layer "In9.Cu")
		(net "UPI_CPU1_CPU0_P1P1_DN<19>")
	)
	(segment
		(start 175.007524 -29.833316)
		(end 193.199512 -30.603698)
		(width 0.1143)
		(layer "In9.Cu")
		(net "UPI_CPU1_CPU0_P1P1_DN<19>")
	)
	(segment
		(start 125.680978 -47.217076)
		(end 130.465576 -42.432478)
		(width 0.1143)
		(layer "In9.Cu")
		(net "UPI_CPU1_CPU0_P1P1_DN<19>")
	)
	(segment
		(start 125.021848 -55.58409)
		(end 124.694696 -55.256938)
		(width 0.1143)
		(layer "In9.Cu")
		(net "UPI_CPU1_CPU0_P1P1_DN<19>")
	)
	(segment
		(start 195.368926 -31.271972)
		(end 199.115426 -30.24759)
		(width 0.1143)
		(layer "In9.Cu")
		(net "UPI_CPU1_CPU0_P1P1_DN<19>")
	)
	(segment
		(start 125.651768 -55.904384)
		(end 125.331474 -55.58409)
		(width 0.1143)
		(layer "In9.Cu")
		(net "UPI_CPU1_CPU0_P1P1_DN<19>")
	)
	(segment
		(start 125.680724 -50.46853)
		(end 125.680978 -50.468276)
		(width 0.1143)
		(layer "In9.Cu")
		(net "UPI_CPU1_CPU0_P1P1_DN<19>")
	)
	(segment
		(start 125.331474 -55.58409)
		(end 125.021848 -55.58409)
		(width 0.1143)
		(layer "In9.Cu")
		(net "UPI_CPU1_CPU0_P1P1_DN<19>")
	)
	(segment
		(start 124.694696 -55.256938)
		(end 124.694696 -54.21249)
		(width 0.1143)
		(layer "In9.Cu")
		(net "UPI_CPU1_CPU0_P1P1_DN<19>")
	)
	(segment
		(start 294.478456 -35.569906)
		(end 297.62577 -37.676836)
		(width 0.1143)
		(layer "In9.Cu")
		(net "UPI_CPU1_CPU0_P1P1_DN<19>")
	)
	(segment
		(start 237.273338 -31.852108)
		(end 241.343434 -32.40405)
		(width 0.1143)
		(layer "In9.Cu")
		(net "UPI_CPU1_CPU0_P1P1_DN<19>")
	)
	(segment
		(start 298.957238 -39.67353)
		(end 304.309272 -45.712634)
		(width 0.1143)
		(layer "In9.Cu")
		(net "UPI_CPU1_CPU0_P1P1_DN<19>")
	)
	(segment
		(start 169.342816 -32.871156)
		(end 172.40758 -30.674056)
		(width 0.1143)
		(layer "In9.Cu")
		(net "UPI_CPU1_CPU0_P1P1_DN<19>")
	)
	(segment
		(start 306.123086 -56.494934)
		(end 306.09413 -56.494934)
		(width 0.0889)
		(layer "In9.Cu")
		(net "UPI_CPU1_CPU0_P1P1_DN<19>")
	)
	(segment
		(start 259.163058 -33.725104)
		(end 261.50189 -34.278316)
		(width 0.1143)
		(layer "In9.Cu")
		(net "UPI_CPU1_CPU0_P1P1_DN<19>")
	)
	(segment
		(start 251.877322 -30.94228)
		(end 255.962912 -32.634936)
		(width 0.1143)
		(layer "In9.Cu")
		(net "UPI_CPU1_CPU0_P1P1_DN<19>")
	)
	(segment
		(start 305.264566 -57.981088)
		(end 305.2318 -57.981088)
		(width 0.0889)
		(layer "In9.Cu")
		(net "UPI_CPU1_CPU0_P1P1_DN<19>")
	)
	(segment
		(start 306.610766 -55.098696)
		(end 306.559966 -55.149496)
		(width 0.0889)
		(layer "In9.Cu")
		(net "UPI_CPU1_CPU0_P1P1_DN<19>")
	)
	(segment
		(start 132.211826 -40.231568)
		(end 140.381482 -36.866322)
		(width 0.1143)
		(layer "In9.Cu")
		(net "UPI_CPU1_CPU0_P1P1_DN<19>")
	)
	(segment
		(start 172.40758 -30.674056)
		(end 175.007524 -29.833316)
		(width 0.1143)
		(layer "In9.Cu")
		(net "UPI_CPU1_CPU0_P1P1_DN<19>")
	)
	(segment
		(start 306.610766 -55.076598)
		(end 306.610766 -55.098696)
		(width 0.0889)
		(layer "In9.Cu")
		(net "UPI_CPU1_CPU0_P1P1_DN<19>")
	)
	(segment
		(start 307.201062 -52.306474)
		(end 306.610766 -54.73446)
		(width 0.1143)
		(layer "In9.Cu")
		(net "UPI_CPU1_CPU0_P1P1_DN<19>")
	)
	(segment
		(start 237.049056 -31.83382)
		(end 237.273338 -31.852108)
		(width 0.1143)
		(layer "In9.Cu")
		(net "UPI_CPU1_CPU0_P1P1_DN<19>")
	)
	(segment
		(start 222.396812 -32.921448)
		(end 237.049056 -31.83382)
		(width 0.1143)
		(layer "In9.Cu")
		(net "UPI_CPU1_CPU0_P1P1_DN<19>")
	)
	(segment
		(start 212.324188 -33.66897)
		(end 212.324188 -33.669224)
		(width 0.1143)
		(layer "In9.Cu")
		(net "UPI_CPU1_CPU0_P1P1_DN<19>")
	)
	(segment
		(start 282.176474 -36.144708)
		(end 282.505404 -36.093654)
		(width 0.1143)
		(layer "In9.Cu")
		(net "UPI_CPU1_CPU0_P1P1_DN<19>")
	)
	(segment
		(start 306.559966 -55.510176)
		(end 306.617116 -55.609236)
		(width 0.0889)
		(layer "In9.Cu")
		(net "UPI_CPU1_CPU0_P1P1_DN<19>")
	)
	(segment
		(start 244.702076 -30.94228)
		(end 251.877322 -30.94228)
		(width 0.1143)
		(layer "In9.Cu")
		(net "UPI_CPU1_CPU0_P1P1_DN<19>")
	)
	(segment
		(start 297.62577 -37.676836)
		(end 298.957238 -39.67353)
		(width 0.1143)
		(layer "In9.Cu")
		(net "UPI_CPU1_CPU0_P1P1_DN<19>")
	)
	(segment
		(start 261.50189 -34.278316)
		(end 264.593578 -33.387538)
		(width 0.1143)
		(layer "In9.Cu")
		(net "UPI_CPU1_CPU0_P1P1_DN<19>")
	)
	(segment
		(start 124.694696 -54.21249)
		(end 125.680724 -50.46853)
		(width 0.1143)
		(layer "In9.Cu")
		(net "UPI_CPU1_CPU0_P1P1_DN<19>")
	)
	(segment
		(start 162.444938 -33.416748)
		(end 169.342816 -32.871156)
		(width 0.1143)
		(layer "In9.Cu")
		(net "UPI_CPU1_CPU0_P1P1_DN<19>")
	)
	(segment
		(start 306.559966 -55.149496)
		(end 306.559966 -55.510176)
		(width 0.0889)
		(layer "In9.Cu")
		(net "UPI_CPU1_CPU0_P1P1_DN<19>")
	)
	(segment
		(start 264.593578 -33.387538)
		(end 282.176474 -36.144708)
		(width 0.1143)
		(layer "In9.Cu")
		(net "UPI_CPU1_CPU0_P1P1_DN<19>")
	)
	(segment
		(start 282.505404 -36.093654)
		(end 290.072572 -34.69005)
		(width 0.1143)
		(layer "In9.Cu")
		(net "UPI_CPU1_CPU0_P1P1_DN<19>")
	)
	(segment
		(start 255.962912 -32.634936)
		(end 259.163058 -33.725104)
		(width 0.1143)
		(layer "In9.Cu")
		(net "UPI_CPU1_CPU0_P1P1_DN<19>")
	)
	(segment
		(start 125.680978 -50.468276)
		(end 125.680978 -47.217076)
		(width 0.1143)
		(layer "In9.Cu")
		(net "UPI_CPU1_CPU0_P1P1_DN<19>")
	)
	(segment
		(start 193.199512 -30.603698)
		(end 195.368926 -31.271972)
		(width 0.1143)
		(layer "In9.Cu")
		(net "UPI_CPU1_CPU0_P1P1_DN<19>")
	)
	(segment
		(start 290.072572 -34.69005)
		(end 294.478456 -35.569906)
		(width 0.1143)
		(layer "In9.Cu")
		(net "UPI_CPU1_CPU0_P1P1_DN<19>")
	)
	(segment
		(start 306.610766 -54.73446)
		(end 306.610766 -55.076598)
		(width 0.1143)
		(layer "In9.Cu")
		(net "UPI_CPU1_CPU0_P1P1_DN<19>")
	)
	(segment
		(start 241.343434 -32.40405)
		(end 244.702076 -30.94228)
		(width 0.1143)
		(layer "In9.Cu")
		(net "UPI_CPU1_CPU0_P1P1_DN<19>")
	)
	(segment
		(start 304.09515 -58.707528)
		(end 304.388266 -58.876438)
		(width 0.0889)
		(layer "In9.Cu")
		(net "UPI_CPU1_CPU0_P1P1_DN<19>")
	)
	(segment
		(start 140.381482 -36.866322)
		(end 146.74088 -37.167566)
		(width 0.1143)
		(layer "In9.Cu")
		(net "UPI_CPU1_CPU0_P1P1_DN<19>")
	)
	(segment
		(start 304.309272 -45.712634)
		(end 307.201062 -52.306474)
		(width 0.1143)
		(layer "In9.Cu")
		(net "UPI_CPU1_CPU0_P1P1_DN<19>")
	)
	(arc
		(start 304.37709 -58.476388)
		(mid 304.208653 -58.518921)
		(end 304.074068 -58.628788)
		(width 0.0889)
		(layer "In9.Cu")
		(net "UPI_CPU1_CPU0_P1P1_DN<19>")
	)
	(arc
		(start 306.09413 -56.494934)
		(mid 305.755961 -56.699732)
		(end 305.758596 -57.095136)
		(width 0.0889)
		(layer "In9.Cu")
		(net "UPI_CPU1_CPU0_P1P1_DN<19>")
	)
	(arc
		(start 306.617116 -55.609236)
		(mid 306.621281 -56.192189)
		(end 306.123086 -56.494934)
		(width 0.0889)
		(layer "In9.Cu")
		(net "UPI_CPU1_CPU0_P1P1_DN<19>")
	)
	(arc
		(start 304.900076 -58.180986)
		(mid 304.689363 -58.394065)
		(end 304.40122 -58.476388)
		(width 0.0889)
		(layer "In9.Cu")
		(net "UPI_CPU1_CPU0_P1P1_DN<19>")
	)
	(arc
		(start 305.758596 -57.095136)
		(mid 305.762925 -57.678308)
		(end 305.264566 -57.981088)
		(width 0.0889)
		(layer "In9.Cu")
		(net "UPI_CPU1_CPU0_P1P1_DN<19>")
	)
	(arc
		(start 305.2318 -57.981088)
		(mid 305.040158 -58.038254)
		(end 304.900076 -58.180986)
		(width 0.0889)
		(layer "In9.Cu")
		(net "UPI_CPU1_CPU0_P1P1_DN<19>")
	)
	(segment
		(start 125.938788 -54.418738)
		(end 126.510288 -54.418738)
		(width 0.1143)
		(layer "F.Cu")
		(net "UPI_CPU1_CPU0_P1P1_DN<18>")
	)
	(segment
		(start 302.099726 -57.885584)
		(end 302.671226 -57.885584)
		(width 0.1143)
		(layer "F.Cu")
		(net "UPI_CPU1_CPU0_P1P1_DN<18>")
	)
	(via
		(at 302.671226 -57.885584)
		(size 0.508)
		(drill 0.254)
		(layers "F.Cu" "B.Cu")
		(net "UPI_CPU1_CPU0_P1P1_DN<18>")
	)
	(via
		(at 126.510288 -54.418738)
		(size 0.508)
		(drill 0.254)
		(layers "F.Cu" "B.Cu")
		(net "UPI_CPU1_CPU0_P1P1_DN<18>")
	)
	(segment
		(start 304.531014 -50.653188)
		(end 304.956972 -51.882548)
		(width 0.1143)
		(layer "In9.Cu")
		(net "UPI_CPU1_CPU0_P1P1_DN<18>")
	)
	(segment
		(start 299.711364 -42.545254)
		(end 300.721522 -43.86199)
		(width 0.1143)
		(layer "In9.Cu")
		(net "UPI_CPU1_CPU0_P1P1_DN<18>")
	)
	(segment
		(start 304.224436 -50.23485)
		(end 304.336704 -50.558954)
		(width 0.1143)
		(layer "In9.Cu")
		(net "UPI_CPU1_CPU0_P1P1_DN<18>")
	)
	(segment
		(start 303.43602 -48.1584)
		(end 303.500028 -48.322484)
		(width 0.1143)
		(layer "In9.Cu")
		(net "UPI_CPU1_CPU0_P1P1_DN<18>")
	)
	(segment
		(start 282.112974 -37.120322)
		(end 282.112974 -37.120576)
		(width 0.1143)
		(layer "In9.Cu")
		(net "UPI_CPU1_CPU0_P1P1_DN<18>")
	)
	(segment
		(start 212.471254 -34.66592)
		(end 222.396812 -33.922208)
		(width 0.1143)
		(layer "In9.Cu")
		(net "UPI_CPU1_CPU0_P1P1_DN<18>")
	)
	(segment
		(start 264.608564 -34.36493)
		(end 282.112974 -37.120322)
		(width 0.1143)
		(layer "In9.Cu")
		(net "UPI_CPU1_CPU0_P1P1_DN<18>")
	)
	(segment
		(start 303.375314 -48.002952)
		(end 303.43602 -48.1584)
		(width 0.1143)
		(layer "In9.Cu")
		(net "UPI_CPU1_CPU0_P1P1_DN<18>")
	)
	(segment
		(start 302.321976 -45.948346)
		(end 302.561752 -46.260766)
		(width 0.1143)
		(layer "In9.Cu")
		(net "UPI_CPU1_CPU0_P1P1_DN<18>")
	)
	(segment
		(start 305.656488 -54.20233)
		(end 305.656488 -54.679342)
		(width 0.0889)
		(layer "In9.Cu")
		(net "UPI_CPU1_CPU0_P1P1_DN<18>")
	)
	(segment
		(start 175.25619 -30.851602)
		(end 175.256444 -30.851348)
		(width 0.1143)
		(layer "In9.Cu")
		(net "UPI_CPU1_CPU0_P1P1_DN<18>")
	)
	(segment
		(start 305.575716 -55.002938)
		(end 305.656488 -55.08371)
		(width 0.0889)
		(layer "In9.Cu")
		(net "UPI_CPU1_CPU0_P1P1_DN<18>")
	)
	(segment
		(start 305.605688 -54.129432)
		(end 305.605688 -54.15153)
		(width 0.0889)
		(layer "In9.Cu")
		(net "UPI_CPU1_CPU0_P1P1_DN<18>")
	)
	(segment
		(start 304.31867 -50.040794)
		(end 304.224436 -50.23485)
		(width 0.1143)
		(layer "In9.Cu")
		(net "UPI_CPU1_CPU0_P1P1_DN<18>")
	)
	(segment
		(start 305.656488 -54.679342)
		(end 305.575716 -54.760114)
		(width 0.0889)
		(layer "In9.Cu")
		(net "UPI_CPU1_CPU0_P1P1_DN<18>")
	)
	(segment
		(start 301.116238 -44.376086)
		(end 301.324772 -44.64812)
		(width 0.1143)
		(layer "In9.Cu")
		(net "UPI_CPU1_CPU0_P1P1_DN<18>")
	)
	(segment
		(start 290.29279 -35.708844)
		(end 294.16375 -36.495228)
		(width 0.1143)
		(layer "In9.Cu")
		(net "UPI_CPU1_CPU0_P1P1_DN<18>")
	)
	(segment
		(start 126.6444 -52.324)
		(end 126.6952 -52.2732)
		(width 0.0889)
		(layer "In9.Cu")
		(net "UPI_CPU1_CPU0_P1P1_DN<18>")
	)
	(segment
		(start 164.48151 -34.347404)
		(end 169.507916 -34.01822)
		(width 0.1143)
		(layer "In9.Cu")
		(net "UPI_CPU1_CPU0_P1P1_DN<18>")
	)
	(segment
		(start 301.296832 -44.861988)
		(end 301.505366 -45.134276)
		(width 0.1143)
		(layer "In9.Cu")
		(net "UPI_CPU1_CPU0_P1P1_DN<18>")
	)
	(segment
		(start 303.822608 -48.728122)
		(end 303.736248 -48.925734)
		(width 0.1143)
		(layer "In9.Cu")
		(net "UPI_CPU1_CPU0_P1P1_DN<18>")
	)
	(segment
		(start 301.505366 -45.134276)
		(end 301.71898 -45.162216)
		(width 0.1143)
		(layer "In9.Cu")
		(net "UPI_CPU1_CPU0_P1P1_DN<18>")
	)
	(segment
		(start 245.020592 -31.86938)
		(end 251.5362 -31.86938)
		(width 0.1143)
		(layer "In9.Cu")
		(net "UPI_CPU1_CPU0_P1P1_DN<18>")
	)
	(segment
		(start 126.192788 -53.572918)
		(end 126.163832 -53.528214)
		(width 0.0889)
		(layer "In9.Cu")
		(net "UPI_CPU1_CPU0_P1P1_DN<18>")
	)
	(segment
		(start 126.163832 -53.058568)
		(end 126.6444 -52.578)
		(width 0.0889)
		(layer "In9.Cu")
		(net "UPI_CPU1_CPU0_P1P1_DN<18>")
	)
	(segment
		(start 193.268092 -31.613856)
		(end 195.38061 -32.32912)
		(width 0.1143)
		(layer "In9.Cu")
		(net "UPI_CPU1_CPU0_P1P1_DN<18>")
	)
	(segment
		(start 126.6444 -52.578)
		(end 126.6444 -52.324)
		(width 0.0889)
		(layer "In9.Cu")
		(net "UPI_CPU1_CPU0_P1P1_DN<18>")
	)
	(segment
		(start 304.403252 -57.295034)
		(end 304.370486 -57.295034)
		(width 0.0889)
		(layer "In9.Cu")
		(net "UPI_CPU1_CPU0_P1P1_DN<18>")
	)
	(segment
		(start 169.507916 -34.01822)
		(end 172.767244 -31.656782)
		(width 0.1143)
		(layer "In9.Cu")
		(net "UPI_CPU1_CPU0_P1P1_DN<18>")
	)
	(segment
		(start 303.43602 -47.739808)
		(end 303.461674 -47.80534)
		(width 0.1143)
		(layer "In9.Cu")
		(net "UPI_CPU1_CPU0_P1P1_DN<18>")
	)
	(segment
		(start 303.500028 -48.322484)
		(end 303.697894 -48.408844)
		(width 0.1143)
		(layer "In9.Cu")
		(net "UPI_CPU1_CPU0_P1P1_DN<18>")
	)
	(segment
		(start 302.742092 -46.746414)
		(end 302.956214 -46.774354)
		(width 0.1143)
		(layer "In9.Cu")
		(net "UPI_CPU1_CPU0_P1P1_DN<18>")
	)
	(segment
		(start 282.16098 -37.127942)
		(end 290.29279 -35.708844)
		(width 0.1143)
		(layer "In9.Cu")
		(net "UPI_CPU1_CPU0_P1P1_DN<18>")
	)
	(segment
		(start 257.115818 -34.181288)
		(end 259.352796 -34.852102)
		(width 0.1143)
		(layer "In9.Cu")
		(net "UPI_CPU1_CPU0_P1P1_DN<18>")
	)
	(segment
		(start 303.164748 -47.046388)
		(end 303.43602 -47.739808)
		(width 0.1143)
		(layer "In9.Cu")
		(net "UPI_CPU1_CPU0_P1P1_DN<18>")
	)
	(segment
		(start 304.862738 -52.076604)
		(end 304.975006 -52.400708)
		(width 0.1143)
		(layer "In9.Cu")
		(net "UPI_CPU1_CPU0_P1P1_DN<18>")
	)
	(segment
		(start 251.5362 -31.86938)
		(end 257.115818 -34.181288)
		(width 0.1143)
		(layer "In9.Cu")
		(net "UPI_CPU1_CPU0_P1P1_DN<18>")
	)
	(segment
		(start 179.569618 -31.033974)
		(end 193.268092 -31.613856)
		(width 0.1143)
		(layer "In9.Cu")
		(net "UPI_CPU1_CPU0_P1P1_DN<18>")
	)
	(segment
		(start 305.605688 -53.755036)
		(end 305.605688 -54.129432)
		(width 0.1143)
		(layer "In9.Cu")
		(net "UPI_CPU1_CPU0_P1P1_DN<18>")
	)
	(segment
		(start 172.767244 -31.656782)
		(end 175.25619 -30.851602)
		(width 0.1143)
		(layer "In9.Cu")
		(net "UPI_CPU1_CPU0_P1P1_DN<18>")
	)
	(segment
		(start 131.266946 -43.238166)
		(end 133.274054 -40.849042)
		(width 0.1143)
		(layer "In9.Cu")
		(net "UPI_CPU1_CPU0_P1P1_DN<18>")
	)
	(segment
		(start 300.902116 -44.348146)
		(end 301.116238 -44.376086)
		(width 0.1143)
		(layer "In9.Cu")
		(net "UPI_CPU1_CPU0_P1P1_DN<18>")
	)
	(segment
		(start 236.881162 -32.836612)
		(end 237.059978 -32.844232)
		(width 0.1143)
		(layer "In9.Cu")
		(net "UPI_CPU1_CPU0_P1P1_DN<18>")
	)
	(segment
		(start 301.928022 -45.434758)
		(end 301.899828 -45.647864)
		(width 0.1143)
		(layer "In9.Cu")
		(net "UPI_CPU1_CPU0_P1P1_DN<18>")
	)
	(segment
		(start 294.16375 -36.495228)
		(end 296.905934 -38.338506)
		(width 0.1143)
		(layer "In9.Cu")
		(net "UPI_CPU1_CPU0_P1P1_DN<18>")
	)
	(segment
		(start 140.361924 -37.987478)
		(end 148.013928 -38.270434)
		(width 0.1143)
		(layer "In9.Cu")
		(net "UPI_CPU1_CPU0_P1P1_DN<18>")
	)
	(segment
		(start 301.71898 -45.162216)
		(end 301.928022 -45.434758)
		(width 0.1143)
		(layer "In9.Cu")
		(net "UPI_CPU1_CPU0_P1P1_DN<18>")
	)
	(segment
		(start 305.605688 -54.15153)
		(end 305.656488 -54.20233)
		(width 0.0889)
		(layer "In9.Cu")
		(net "UPI_CPU1_CPU0_P1P1_DN<18>")
	)
	(segment
		(start 195.38061 -32.32912)
		(end 199.253602 -31.317946)
		(width 0.1143)
		(layer "In9.Cu")
		(net "UPI_CPU1_CPU0_P1P1_DN<18>")
	)
	(segment
		(start 302.561752 -46.260766)
		(end 302.533558 -46.474126)
		(width 0.1143)
		(layer "In9.Cu")
		(net "UPI_CPU1_CPU0_P1P1_DN<18>")
	)
	(segment
		(start 304.728626 -56.684418)
		(end 304.734976 -56.695086)
		(width 0.0889)
		(layer "In9.Cu")
		(net "UPI_CPU1_CPU0_P1P1_DN<18>")
	)
	(segment
		(start 261.563866 -35.27679)
		(end 264.608564 -34.36493)
		(width 0.1143)
		(layer "In9.Cu")
		(net "UPI_CPU1_CPU0_P1P1_DN<18>")
	)
	(segment
		(start 133.274054 -40.849042)
		(end 140.361924 -37.987478)
		(width 0.1143)
		(layer "In9.Cu")
		(net "UPI_CPU1_CPU0_P1P1_DN<18>")
	)
	(segment
		(start 302.956214 -46.774354)
		(end 303.164748 -47.046388)
		(width 0.1143)
		(layer "In9.Cu")
		(net "UPI_CPU1_CPU0_P1P1_DN<18>")
	)
	(segment
		(start 282.112974 -37.120576)
		(end 282.16098 -37.127942)
		(width 0.1143)
		(layer "In9.Cu")
		(net "UPI_CPU1_CPU0_P1P1_DN<18>")
	)
	(segment
		(start 296.905934 -38.338506)
		(end 299.711364 -42.545254)
		(width 0.1143)
		(layer "In9.Cu")
		(net "UPI_CPU1_CPU0_P1P1_DN<18>")
	)
	(segment
		(start 305.575716 -54.760114)
		(end 305.575716 -55.002938)
		(width 0.0889)
		(layer "In9.Cu")
		(net "UPI_CPU1_CPU0_P1P1_DN<18>")
	)
	(segment
		(start 148.013928 -38.270434)
		(end 164.48151 -34.347404)
		(width 0.1143)
		(layer "In9.Cu")
		(net "UPI_CPU1_CPU0_P1P1_DN<18>")
	)
	(segment
		(start 304.734976 -56.695086)
		(end 304.739802 -56.703722)
		(width 0.0889)
		(layer "In9.Cu")
		(net "UPI_CPU1_CPU0_P1P1_DN<18>")
	)
	(segment
		(start 300.693582 -44.075858)
		(end 300.902116 -44.348146)
		(width 0.1143)
		(layer "In9.Cu")
		(net "UPI_CPU1_CPU0_P1P1_DN<18>")
	)
	(segment
		(start 304.975006 -52.400708)
		(end 305.169316 -52.494942)
		(width 0.1143)
		(layer "In9.Cu")
		(net "UPI_CPU1_CPU0_P1P1_DN<18>")
	)
	(segment
		(start 222.396812 -33.922208)
		(end 236.881162 -32.836612)
		(width 0.1143)
		(layer "In9.Cu")
		(net "UPI_CPU1_CPU0_P1P1_DN<18>")
	)
	(segment
		(start 305.169316 -52.494942)
		(end 305.605688 -53.755036)
		(width 0.1143)
		(layer "In9.Cu")
		(net "UPI_CPU1_CPU0_P1P1_DN<18>")
	)
	(segment
		(start 304.336704 -50.558954)
		(end 304.531014 -50.653188)
		(width 0.1143)
		(layer "In9.Cu")
		(net "UPI_CPU1_CPU0_P1P1_DN<18>")
	)
	(segment
		(start 126.6952 -47.809912)
		(end 131.266946 -43.238166)
		(width 0.1143)
		(layer "In9.Cu")
		(net "UPI_CPU1_CPU0_P1P1_DN<18>")
	)
	(segment
		(start 175.256444 -30.851348)
		(end 179.569618 -31.033974)
		(width 0.1143)
		(layer "In9.Cu")
		(net "UPI_CPU1_CPU0_P1P1_DN<18>")
	)
	(segment
		(start 126.163832 -53.528214)
		(end 126.163832 -53.058568)
		(width 0.0889)
		(layer "In9.Cu")
		(net "UPI_CPU1_CPU0_P1P1_DN<18>")
	)
	(segment
		(start 300.721522 -43.86199)
		(end 300.693582 -44.075858)
		(width 0.1143)
		(layer "In9.Cu")
		(net "UPI_CPU1_CPU0_P1P1_DN<18>")
	)
	(segment
		(start 303.860962 -49.245266)
		(end 304.058828 -49.331626)
		(width 0.1143)
		(layer "In9.Cu")
		(net "UPI_CPU1_CPU0_P1P1_DN<18>")
	)
	(segment
		(start 237.059978 -32.844232)
		(end 241.526314 -33.415986)
		(width 0.1143)
		(layer "In9.Cu")
		(net "UPI_CPU1_CPU0_P1P1_DN<18>")
	)
	(segment
		(start 304.956972 -51.882548)
		(end 304.862738 -52.076604)
		(width 0.1143)
		(layer "In9.Cu")
		(net "UPI_CPU1_CPU0_P1P1_DN<18>")
	)
	(segment
		(start 305.656488 -55.496714)
		(end 305.593496 -55.609236)
		(width 0.0889)
		(layer "In9.Cu")
		(net "UPI_CPU1_CPU0_P1P1_DN<18>")
	)
	(segment
		(start 303.540922 -57.790588)
		(end 303.508156 -57.790588)
		(width 0.0889)
		(layer "In9.Cu")
		(net "UPI_CPU1_CPU0_P1P1_DN<18>")
	)
	(segment
		(start 304.183542 -49.650904)
		(end 304.31867 -50.040794)
		(width 0.1143)
		(layer "In9.Cu")
		(net "UPI_CPU1_CPU0_P1P1_DN<18>")
	)
	(segment
		(start 302.533558 -46.474126)
		(end 302.742092 -46.746414)
		(width 0.1143)
		(layer "In9.Cu")
		(net "UPI_CPU1_CPU0_P1P1_DN<18>")
	)
	(segment
		(start 301.324772 -44.64812)
		(end 301.296832 -44.861988)
		(width 0.1143)
		(layer "In9.Cu")
		(net "UPI_CPU1_CPU0_P1P1_DN<18>")
	)
	(segment
		(start 259.352796 -34.852102)
		(end 261.563866 -35.27679)
		(width 0.1143)
		(layer "In9.Cu")
		(net "UPI_CPU1_CPU0_P1P1_DN<18>")
	)
	(segment
		(start 305.257962 -55.809388)
		(end 305.225196 -55.809388)
		(width 0.0889)
		(layer "In9.Cu")
		(net "UPI_CPU1_CPU0_P1P1_DN<18>")
	)
	(segment
		(start 303.697894 -48.408844)
		(end 303.822608 -48.728122)
		(width 0.1143)
		(layer "In9.Cu")
		(net "UPI_CPU1_CPU0_P1P1_DN<18>")
	)
	(segment
		(start 199.253602 -31.317946)
		(end 212.471254 -34.66592)
		(width 0.1143)
		(layer "In9.Cu")
		(net "UPI_CPU1_CPU0_P1P1_DN<18>")
	)
	(segment
		(start 304.058828 -49.331626)
		(end 304.183542 -49.650904)
		(width 0.1143)
		(layer "In9.Cu")
		(net "UPI_CPU1_CPU0_P1P1_DN<18>")
	)
	(segment
		(start 303.736248 -48.925734)
		(end 303.860962 -49.245266)
		(width 0.1143)
		(layer "In9.Cu")
		(net "UPI_CPU1_CPU0_P1P1_DN<18>")
	)
	(segment
		(start 126.6952 -52.2732)
		(end 126.6952 -47.809912)
		(width 0.1143)
		(layer "In9.Cu")
		(net "UPI_CPU1_CPU0_P1P1_DN<18>")
	)
	(segment
		(start 126.510288 -54.418738)
		(end 126.402846 -54.311296)
		(width 0.0889)
		(layer "In9.Cu")
		(net "UPI_CPU1_CPU0_P1P1_DN<18>")
	)
	(segment
		(start 301.899828 -45.647864)
		(end 302.108616 -45.920152)
		(width 0.1143)
		(layer "In9.Cu")
		(net "UPI_CPU1_CPU0_P1P1_DN<18>")
	)
	(segment
		(start 241.526314 -33.415986)
		(end 245.020592 -31.86938)
		(width 0.1143)
		(layer "In9.Cu")
		(net "UPI_CPU1_CPU0_P1P1_DN<18>")
	)
	(segment
		(start 303.461674 -47.80534)
		(end 303.43602 -47.864014)
		(width 0.1143)
		(layer "In9.Cu")
		(net "UPI_CPU1_CPU0_P1P1_DN<18>")
	)
	(segment
		(start 302.108616 -45.920152)
		(end 302.321976 -45.948346)
		(width 0.1143)
		(layer "In9.Cu")
		(net "UPI_CPU1_CPU0_P1P1_DN<18>")
	)
	(segment
		(start 305.656488 -55.08371)
		(end 305.656488 -55.496714)
		(width 0.0889)
		(layer "In9.Cu")
		(net "UPI_CPU1_CPU0_P1P1_DN<18>")
	)
	(segment
		(start 303.43602 -47.864014)
		(end 303.375314 -48.002952)
		(width 0.1143)
		(layer "In9.Cu")
		(net "UPI_CPU1_CPU0_P1P1_DN<18>")
	)
	(arc
		(start 303.508156 -57.790588)
		(mid 303.224939 -57.874869)
		(end 303.017936 -58.085736)
		(width 0.0889)
		(layer "In9.Cu")
		(net "UPI_CPU1_CPU0_P1P1_DN<18>")
	)
	(arc
		(start 303.017936 -58.085736)
		(mid 302.937147 -58.184841)
		(end 302.829214 -58.253376)
		(width 0.0889)
		(layer "In9.Cu")
		(net "UPI_CPU1_CPU0_P1P1_DN<18>")
	)
	(arc
		(start 305.593496 -55.609236)
		(mid 305.451813 -55.75304)
		(end 305.257962 -55.809388)
		(width 0.0889)
		(layer "In9.Cu")
		(net "UPI_CPU1_CPU0_P1P1_DN<18>")
	)
	(arc
		(start 305.225196 -55.809388)
		(mid 304.732806 -56.108321)
		(end 304.728626 -56.684418)
		(width 0.0889)
		(layer "In9.Cu")
		(net "UPI_CPU1_CPU0_P1P1_DN<18>")
	)
	(arc
		(start 303.876456 -57.590436)
		(mid 303.734773 -57.73424)
		(end 303.540922 -57.790588)
		(width 0.0889)
		(layer "In9.Cu")
		(net "UPI_CPU1_CPU0_P1P1_DN<18>")
	)
	(arc
		(start 304.370486 -57.295034)
		(mid 304.085062 -57.378501)
		(end 303.876456 -57.590436)
		(width 0.0889)
		(layer "In9.Cu")
		(net "UPI_CPU1_CPU0_P1P1_DN<18>")
	)
	(arc
		(start 302.829214 -58.253376)
		(mid 302.566324 -58.148474)
		(end 302.671226 -57.885584)
		(width 0.0889)
		(layer "In9.Cu")
		(net "UPI_CPU1_CPU0_P1P1_DN<18>")
	)
	(arc
		(start 304.739802 -56.703722)
		(mid 304.736055 -57.092978)
		(end 304.403252 -57.295034)
		(width 0.0889)
		(layer "In9.Cu")
		(net "UPI_CPU1_CPU0_P1P1_DN<18>")
	)
	(arc
		(start 126.402846 -54.311296)
		(mid 126.311581 -54.166044)
		(end 126.292356 -53.995574)
		(width 0.0889)
		(layer "In9.Cu")
		(net "UPI_CPU1_CPU0_P1P1_DN<18>")
	)
	(arc
		(start 126.292356 -53.995574)
		(mid 126.279226 -53.775612)
		(end 126.192788 -53.572918)
		(width 0.0889)
		(layer "In9.Cu")
		(net "UPI_CPU1_CPU0_P1P1_DN<18>")
	)
	(segment
		(start 125.938788 -55.409338)
		(end 126.510288 -55.409338)
		(width 0.1143)
		(layer "F.Cu")
		(net "UPI_CPU1_CPU0_P1P1_DN<17>")
	)
	(segment
		(start 302.099726 -59.866784)
		(end 302.671226 -59.866784)
		(width 0.1143)
		(layer "F.Cu")
		(net "UPI_CPU1_CPU0_P1P1_DN<17>")
	)
	(via
		(at 126.510288 -55.409338)
		(size 0.508)
		(drill 0.254)
		(layers "F.Cu" "B.Cu")
		(net "UPI_CPU1_CPU0_P1P1_DN<17>")
	)
	(via
		(at 302.671226 -59.866784)
		(size 0.508)
		(drill 0.254)
		(layers "F.Cu" "B.Cu")
		(net "UPI_CPU1_CPU0_P1P1_DN<17>")
	)
	(segment
		(start 127.103124 -52.281328)
		(end 127.103124 -53.291232)
		(width 0.0889)
		(layer "In9.Cu")
		(net "UPI_CPU1_CPU0_P1P1_DN<17>")
	)
	(segment
		(start 212.137752 -35.127184)
		(end 199.320912 -31.76651)
		(width 0.1143)
		(layer "In9.Cu")
		(net "UPI_CPU1_CPU0_P1P1_DN<17>")
	)
	(segment
		(start 282.082748 -37.516054)
		(end 264.545318 -34.754058)
		(width 0.1143)
		(layer "In9.Cu")
		(net "UPI_CPU1_CPU0_P1P1_DN<17>")
	)
	(segment
		(start 290.180268 -36.117784)
		(end 282.082748 -37.516054)
		(width 0.1143)
		(layer "In9.Cu")
		(net "UPI_CPU1_CPU0_P1P1_DN<17>")
	)
	(segment
		(start 127.062484 -48.065944)
		(end 127.062484 -52.240688)
		(width 0.1143)
		(layer "In9.Cu")
		(net "UPI_CPU1_CPU0_P1P1_DN<17>")
	)
	(segment
		(start 195.246498 -32.800036)
		(end 193.066416 -31.966916)
		(width 0.1143)
		(layer "In9.Cu")
		(net "UPI_CPU1_CPU0_P1P1_DN<17>")
	)
	(segment
		(start 127.062484 -52.240688)
		(end 127.103124 -52.281328)
		(width 0.0889)
		(layer "In9.Cu")
		(net "UPI_CPU1_CPU0_P1P1_DN<17>")
	)
	(segment
		(start 303.064418 -50.131726)
		(end 303.081944 -50.061876)
		(width 0.0889)
		(layer "In9.Cu")
		(net "UPI_CPU1_CPU0_P1P1_DN<17>")
	)
	(segment
		(start 148.044662 -38.829234)
		(end 140.719302 -38.439344)
		(width 0.1143)
		(layer "In9.Cu")
		(net "UPI_CPU1_CPU0_P1P1_DN<17>")
	)
	(segment
		(start 241.678968 -33.855152)
		(end 236.900974 -33.264348)
		(width 0.1143)
		(layer "In9.Cu")
		(net "UPI_CPU1_CPU0_P1P1_DN<17>")
	)
	(segment
		(start 302.330866 -59.087004)
		(end 302.324516 -59.076336)
		(width 0.0889)
		(layer "In9.Cu")
		(net "UPI_CPU1_CPU0_P1P1_DN<17>")
	)
	(segment
		(start 134.617714 -40.830246)
		(end 133.505702 -41.315132)
		(width 0.1143)
		(layer "In9.Cu")
		(net "UPI_CPU1_CPU0_P1P1_DN<17>")
	)
	(segment
		(start 304.37709 -55.504334)
		(end 304.406554 -55.504334)
		(width 0.0889)
		(layer "In9.Cu")
		(net "UPI_CPU1_CPU0_P1P1_DN<17>")
	)
	(segment
		(start 166.325804 -35.136328)
		(end 163.72078 -35.89274)
		(width 0.1143)
		(layer "In9.Cu")
		(net "UPI_CPU1_CPU0_P1P1_DN<17>")
	)
	(segment
		(start 305.01844 -53.841904)
		(end 303.83607 -51.414172)
		(width 0.0889)
		(layer "In9.Cu")
		(net "UPI_CPU1_CPU0_P1P1_DN<17>")
	)
	(segment
		(start 126.856998 -54.618636)
		(end 126.850648 -54.629304)
		(width 0.0889)
		(layer "In9.Cu")
		(net "UPI_CPU1_CPU0_P1P1_DN<17>")
	)
	(segment
		(start 181.937406 -31.557214)
		(end 169.164 -34.95548)
		(width 0.1143)
		(layer "In9.Cu")
		(net "UPI_CPU1_CPU0_P1P1_DN<17>")
	)
	(segment
		(start 159.927036 -36.935918)
		(end 159.903668 -36.93795)
		(width 0.1143)
		(layer "In9.Cu")
		(net "UPI_CPU1_CPU0_P1P1_DN<17>")
	)
	(segment
		(start 301.758604 -47.768002)
		(end 299.824394 -43.502072)
		(width 0.1143)
		(layer "In9.Cu")
		(net "UPI_CPU1_CPU0_P1P1_DN<17>")
	)
	(segment
		(start 163.72078 -35.89274)
		(end 162.539934 -36.14293)
		(width 0.1143)
		(layer "In9.Cu")
		(net "UPI_CPU1_CPU0_P1P1_DN<17>")
	)
	(segment
		(start 162.539934 -36.14293)
		(end 160.700466 -36.91255)
		(width 0.1143)
		(layer "In9.Cu")
		(net "UPI_CPU1_CPU0_P1P1_DN<17>")
	)
	(segment
		(start 302.66005 -57.485534)
		(end 302.692816 -57.485534)
		(width 0.0889)
		(layer "In9.Cu")
		(net "UPI_CPU1_CPU0_P1P1_DN<17>")
	)
	(segment
		(start 160.700466 -36.91255)
		(end 159.927036 -36.935918)
		(width 0.1143)
		(layer "In9.Cu")
		(net "UPI_CPU1_CPU0_P1P1_DN<17>")
	)
	(segment
		(start 126.861824 -54.61)
		(end 126.856998 -54.618636)
		(width 0.0889)
		(layer "In9.Cu")
		(net "UPI_CPU1_CPU0_P1P1_DN<17>")
	)
	(segment
		(start 303.081944 -50.061876)
		(end 303.070514 -50.04308)
		(width 0.0889)
		(layer "In9.Cu")
		(net "UPI_CPU1_CPU0_P1P1_DN<17>")
	)
	(segment
		(start 195.246498 -32.80029)
		(end 195.246498 -32.800036)
		(width 0.1143)
		(layer "In9.Cu")
		(net "UPI_CPU1_CPU0_P1P1_DN<17>")
	)
	(segment
		(start 258.722368 -35.190176)
		(end 256.252726 -34.290762)
		(width 0.1143)
		(layer "In9.Cu")
		(net "UPI_CPU1_CPU0_P1P1_DN<17>")
	)
	(segment
		(start 159.903668 -36.93795)
		(end 155.107132 -37.467032)
		(width 0.1143)
		(layer "In9.Cu")
		(net "UPI_CPU1_CPU0_P1P1_DN<17>")
	)
	(segment
		(start 256.252726 -34.290762)
		(end 251.235718 -32.21228)
		(width 0.1143)
		(layer "In9.Cu")
		(net "UPI_CPU1_CPU0_P1P1_DN<17>")
	)
	(segment
		(start 169.164 -34.95548)
		(end 166.325804 -35.136328)
		(width 0.1143)
		(layer "In9.Cu")
		(net "UPI_CPU1_CPU0_P1P1_DN<17>")
	)
	(segment
		(start 245.21541 -32.21228)
		(end 241.678968 -33.855152)
		(width 0.1143)
		(layer "In9.Cu")
		(net "UPI_CPU1_CPU0_P1P1_DN<17>")
	)
	(segment
		(start 133.505702 -41.315132)
		(end 131.75107 -43.378882)
		(width 0.1143)
		(layer "In9.Cu")
		(net "UPI_CPU1_CPU0_P1P1_DN<17>")
	)
	(segment
		(start 126.617222 -55.302404)
		(end 126.510288 -55.409338)
		(width 0.0889)
		(layer "In9.Cu")
		(net "UPI_CPU1_CPU0_P1P1_DN<17>")
	)
	(segment
		(start 302.671226 -59.866784)
		(end 302.580294 -59.775852)
		(width 0.0889)
		(layer "In9.Cu")
		(net "UPI_CPU1_CPU0_P1P1_DN<17>")
	)
	(segment
		(start 199.320912 -31.76651)
		(end 195.246498 -32.80029)
		(width 0.1143)
		(layer "In9.Cu")
		(net "UPI_CPU1_CPU0_P1P1_DN<17>")
	)
	(segment
		(start 303.83607 -51.414172)
		(end 303.43602 -50.7492)
		(width 0.0889)
		(layer "In9.Cu")
		(net "UPI_CPU1_CPU0_P1P1_DN<17>")
	)
	(segment
		(start 296.507154 -38.524688)
		(end 293.948612 -36.810188)
		(width 0.1143)
		(layer "In9.Cu")
		(net "UPI_CPU1_CPU0_P1P1_DN<17>")
	)
	(segment
		(start 264.545318 -34.754058)
		(end 261.618476 -35.69208)
		(width 0.1143)
		(layer "In9.Cu")
		(net "UPI_CPU1_CPU0_P1P1_DN<17>")
	)
	(segment
		(start 304.900076 -55.209186)
		(end 305.01844 -55.0037)
		(width 0.0889)
		(layer "In9.Cu")
		(net "UPI_CPU1_CPU0_P1P1_DN<17>")
	)
	(segment
		(start 148.044662 -38.829488)
		(end 148.044662 -38.829234)
		(width 0.1143)
		(layer "In9.Cu")
		(net "UPI_CPU1_CPU0_P1P1_DN<17>")
	)
	(segment
		(start 127.103124 -53.291232)
		(end 126.895098 -53.56733)
		(width 0.0889)
		(layer "In9.Cu")
		(net "UPI_CPU1_CPU0_P1P1_DN<17>")
	)
	(segment
		(start 302.8188 -49.62525)
		(end 301.758604 -47.768002)
		(width 0.1143)
		(layer "In9.Cu")
		(net "UPI_CPU1_CPU0_P1P1_DN<17>")
	)
	(segment
		(start 303.51476 -56.990488)
		(end 303.547526 -56.990488)
		(width 0.0889)
		(layer "In9.Cu")
		(net "UPI_CPU1_CPU0_P1P1_DN<17>")
	)
	(segment
		(start 126.835662 -54.181502)
		(end 126.856998 -54.218586)
		(width 0.0889)
		(layer "In9.Cu")
		(net "UPI_CPU1_CPU0_P1P1_DN<17>")
	)
	(segment
		(start 299.824394 -43.502072)
		(end 296.507154 -38.524688)
		(width 0.1143)
		(layer "In9.Cu")
		(net "UPI_CPU1_CPU0_P1P1_DN<17>")
	)
	(segment
		(start 155.107132 -37.467032)
		(end 148.044662 -38.829488)
		(width 0.1143)
		(layer "In9.Cu")
		(net "UPI_CPU1_CPU0_P1P1_DN<17>")
	)
	(segment
		(start 193.066416 -31.966916)
		(end 181.937406 -31.557214)
		(width 0.1143)
		(layer "In9.Cu")
		(net "UPI_CPU1_CPU0_P1P1_DN<17>")
	)
	(segment
		(start 293.948612 -36.810188)
		(end 290.180268 -36.117784)
		(width 0.1143)
		(layer "In9.Cu")
		(net "UPI_CPU1_CPU0_P1P1_DN<17>")
	)
	(segment
		(start 140.719302 -38.439344)
		(end 134.617714 -40.830246)
		(width 0.1143)
		(layer "In9.Cu")
		(net "UPI_CPU1_CPU0_P1P1_DN<17>")
	)
	(segment
		(start 305.01844 -55.0037)
		(end 305.01844 -53.841904)
		(width 0.0889)
		(layer "In9.Cu")
		(net "UPI_CPU1_CPU0_P1P1_DN<17>")
	)
	(segment
		(start 303.070514 -50.04308)
		(end 302.8188 -49.62525)
		(width 0.1143)
		(layer "In9.Cu")
		(net "UPI_CPU1_CPU0_P1P1_DN<17>")
	)
	(segment
		(start 303.43602 -50.7492)
		(end 303.064418 -50.131726)
		(width 0.0889)
		(layer "In9.Cu")
		(net "UPI_CPU1_CPU0_P1P1_DN<17>")
	)
	(segment
		(start 261.618476 -35.69208)
		(end 258.722368 -35.190176)
		(width 0.1143)
		(layer "In9.Cu")
		(net "UPI_CPU1_CPU0_P1P1_DN<17>")
	)
	(segment
		(start 251.235718 -32.21228)
		(end 245.21541 -32.21228)
		(width 0.1143)
		(layer "In9.Cu")
		(net "UPI_CPU1_CPU0_P1P1_DN<17>")
	)
	(segment
		(start 236.777022 -33.259522)
		(end 212.137752 -35.127184)
		(width 0.1143)
		(layer "In9.Cu")
		(net "UPI_CPU1_CPU0_P1P1_DN<17>")
	)
	(segment
		(start 131.75107 -43.378882)
		(end 127.062484 -48.065944)
		(width 0.1143)
		(layer "In9.Cu")
		(net "UPI_CPU1_CPU0_P1P1_DN<17>")
	)
	(segment
		(start 236.900974 -33.264348)
		(end 236.777022 -33.259522)
		(width 0.1143)
		(layer "In9.Cu")
		(net "UPI_CPU1_CPU0_P1P1_DN<17>")
	)
	(arc
		(start 302.580294 -59.775852)
		(mid 302.451718 -59.585341)
		(end 302.403764 -59.360562)
		(width 0.0889)
		(layer "In9.Cu")
		(net "UPI_CPU1_CPU0_P1P1_DN<17>")
	)
	(arc
		(start 304.406554 -55.504334)
		(mid 304.691601 -55.420806)
		(end 304.900076 -55.209186)
		(width 0.0889)
		(layer "In9.Cu")
		(net "UPI_CPU1_CPU0_P1P1_DN<17>")
	)
	(arc
		(start 302.403764 -59.360562)
		(mid 302.383945 -59.219351)
		(end 302.330866 -59.087004)
		(width 0.0889)
		(layer "In9.Cu")
		(net "UPI_CPU1_CPU0_P1P1_DN<17>")
	)
	(arc
		(start 302.324516 -58.67654)
		(mid 302.403647 -58.381138)
		(end 302.324516 -58.085736)
		(width 0.0889)
		(layer "In9.Cu")
		(net "UPI_CPU1_CPU0_P1P1_DN<17>")
	)
	(arc
		(start 304.041556 -56.104536)
		(mid 304.038808 -55.709069)
		(end 304.37709 -55.504334)
		(width 0.0889)
		(layer "In9.Cu")
		(net "UPI_CPU1_CPU0_P1P1_DN<17>")
	)
	(arc
		(start 126.850648 -54.629304)
		(mid 126.796131 -54.767436)
		(end 126.77775 -54.9148)
		(width 0.0889)
		(layer "In9.Cu")
		(net "UPI_CPU1_CPU0_P1P1_DN<17>")
	)
	(arc
		(start 126.77775 -54.9148)
		(mid 126.736026 -55.124561)
		(end 126.617222 -55.302404)
		(width 0.0889)
		(layer "In9.Cu")
		(net "UPI_CPU1_CPU0_P1P1_DN<17>")
	)
	(arc
		(start 302.324516 -59.076336)
		(mid 302.271017 -58.876438)
		(end 302.324516 -58.67654)
		(width 0.0889)
		(layer "In9.Cu")
		(net "UPI_CPU1_CPU0_P1P1_DN<17>")
	)
	(arc
		(start 303.547526 -56.990488)
		(mid 304.045777 -56.687648)
		(end 304.041556 -56.104536)
		(width 0.0889)
		(layer "In9.Cu")
		(net "UPI_CPU1_CPU0_P1P1_DN<17>")
	)
	(arc
		(start 302.324516 -58.085736)
		(mid 302.321768 -57.690269)
		(end 302.66005 -57.485534)
		(width 0.0889)
		(layer "In9.Cu")
		(net "UPI_CPU1_CPU0_P1P1_DN<17>")
	)
	(arc
		(start 303.183036 -57.190386)
		(mid 303.323115 -57.04765)
		(end 303.51476 -56.990488)
		(width 0.0889)
		(layer "In9.Cu")
		(net "UPI_CPU1_CPU0_P1P1_DN<17>")
	)
	(arc
		(start 126.895098 -53.56733)
		(mid 126.779086 -53.866072)
		(end 126.835662 -54.181502)
		(width 0.0889)
		(layer "In9.Cu")
		(net "UPI_CPU1_CPU0_P1P1_DN<17>")
	)
	(arc
		(start 302.692816 -57.485534)
		(mid 302.976033 -57.401253)
		(end 303.183036 -57.190386)
		(width 0.0889)
		(layer "In9.Cu")
		(net "UPI_CPU1_CPU0_P1P1_DN<17>")
	)
	(arc
		(start 126.856998 -54.218586)
		(mid 126.910468 -54.413649)
		(end 126.861824 -54.61)
		(width 0.0889)
		(layer "In9.Cu")
		(net "UPI_CPU1_CPU0_P1P1_DN<17>")
	)
	(segment
		(start 300.382686 -58.876438)
		(end 300.954186 -58.876438)
		(width 0.1143)
		(layer "F.Cu")
		(net "UPI_CPU1_CPU0_P1P1_DN<16>")
	)
	(segment
		(start 127.655828 -54.418738)
		(end 128.227328 -54.418738)
		(width 0.1143)
		(layer "F.Cu")
		(net "UPI_CPU1_CPU0_P1P1_DN<16>")
	)
	(via
		(at 300.954186 -58.876438)
		(size 0.508)
		(drill 0.254)
		(layers "F.Cu" "B.Cu")
		(net "UPI_CPU1_CPU0_P1P1_DN<16>")
	)
	(via
		(at 128.227328 -54.418738)
		(size 0.508)
		(drill 0.254)
		(layers "F.Cu" "B.Cu")
		(net "UPI_CPU1_CPU0_P1P1_DN<16>")
	)
	(segment
		(start 298.407582 -43.520614)
		(end 298.205398 -43.44543)
		(width 0.1143)
		(layer "In9.Cu")
		(net "UPI_CPU1_CPU0_P1P1_DN<16>")
	)
	(segment
		(start 236.736382 -34.21507)
		(end 222.396812 -35.291522)
		(width 0.1143)
		(layer "In9.Cu")
		(net "UPI_CPU1_CPU0_P1P1_DN<16>")
	)
	(segment
		(start 178.804824 -33.785556)
		(end 178.734974 -33.798764)
		(width 0.1143)
		(layer "In9.Cu")
		(net "UPI_CPU1_CPU0_P1P1_DN<16>")
	)
	(segment
		(start 128.006348 -52.193952)
		(end 127.959612 -52.240688)
		(width 0.0889)
		(layer "In9.Cu")
		(net "UPI_CPU1_CPU0_P1P1_DN<16>")
	)
	(segment
		(start 128.239012 -54.818788)
		(end 128.286002 -54.751732)
		(width 0.0889)
		(layer "In9.Cu")
		(net "UPI_CPU1_CPU0_P1P1_DN<16>")
	)
	(segment
		(start 299.708316 -46.738794)
		(end 299.783754 -46.536864)
		(width 0.1143)
		(layer "In9.Cu")
		(net "UPI_CPU1_CPU0_P1P1_DN<16>")
	)
	(segment
		(start 300.606206 -48.747934)
		(end 300.606206 -48.339756)
		(width 0.1143)
		(layer "In9.Cu")
		(net "UPI_CPU1_CPU0_P1P1_DN<16>")
	)
	(segment
		(start 298.474384 -44.034456)
		(end 298.549822 -43.832526)
		(width 0.1143)
		(layer "In9.Cu")
		(net "UPI_CPU1_CPU0_P1P1_DN<16>")
	)
	(segment
		(start 128.035812 -52.48402)
		(end 128.035812 -52.6161)
		(width 0.0889)
		(layer "In9.Cu")
		(net "UPI_CPU1_CPU0_P1P1_DN<16>")
	)
	(segment
		(start 298.549822 -43.832526)
		(end 298.407582 -43.520614)
		(width 0.1143)
		(layer "In9.Cu")
		(net "UPI_CPU1_CPU0_P1P1_DN<16>")
	)
	(segment
		(start 127.959612 -53.12918)
		(end 127.959612 -53.923946)
		(width 0.0889)
		(layer "In9.Cu")
		(net "UPI_CPU1_CPU0_P1P1_DN<16>")
	)
	(segment
		(start 297.797474 -42.183812)
		(end 297.607482 -41.89857)
		(width 0.1143)
		(layer "In9.Cu")
		(net "UPI_CPU1_CPU0_P1P1_DN<16>")
	)
	(segment
		(start 299.230288 -45.323506)
		(end 299.028104 -45.248322)
		(width 0.1143)
		(layer "In9.Cu")
		(net "UPI_CPU1_CPU0_P1P1_DN<16>")
	)
	(segment
		(start 261.458202 -36.753292)
		(end 258.615434 -36.272978)
		(width 0.1143)
		(layer "In9.Cu")
		(net "UPI_CPU1_CPU0_P1P1_DN<16>")
	)
	(segment
		(start 303.113186 -52.967636)
		(end 303.113186 -52.451762)
		(width 0.0889)
		(layer "In9.Cu")
		(net "UPI_CPU1_CPU0_P1P1_DN<16>")
	)
	(segment
		(start 135.05053 -41.775888)
		(end 128.006348 -48.819816)
		(width 0.1143)
		(layer "In9.Cu")
		(net "UPI_CPU1_CPU0_P1P1_DN<16>")
	)
	(segment
		(start 282.151582 -38.475666)
		(end 264.50417 -35.752532)
		(width 0.1143)
		(layer "In9.Cu")
		(net "UPI_CPU1_CPU0_P1P1_DN<16>")
	)
	(segment
		(start 298.063158 -43.13301)
		(end 298.138342 -42.93108)
		(width 0.1143)
		(layer "In9.Cu")
		(net "UPI_CPU1_CPU0_P1P1_DN<16>")
	)
	(segment
		(start 298.818808 -44.42206)
		(end 298.616624 -44.346876)
		(width 0.1143)
		(layer "In9.Cu")
		(net "UPI_CPU1_CPU0_P1P1_DN<16>")
	)
	(segment
		(start 140.804646 -39.510462)
		(end 135.05053 -41.775888)
		(width 0.1143)
		(layer "In9.Cu")
		(net "UPI_CPU1_CPU0_P1P1_DN<16>")
	)
	(segment
		(start 295.801288 -39.188644)
		(end 293.652448 -37.749988)
		(width 0.1143)
		(layer "In9.Cu")
		(net "UPI_CPU1_CPU0_P1P1_DN<16>")
	)
	(segment
		(start 301.305722 -57.694322)
		(end 301.300896 -57.685686)
		(width 0.0889)
		(layer "In9.Cu")
		(net "UPI_CPU1_CPU0_P1P1_DN<16>")
	)
	(segment
		(start 300.463966 -48.027844)
		(end 300.261782 -47.952406)
		(width 0.1143)
		(layer "In9.Cu")
		(net "UPI_CPU1_CPU0_P1P1_DN<16>")
	)
	(segment
		(start 293.652448 -37.749988)
		(end 290.053014 -37.0967)
		(width 0.1143)
		(layer "In9.Cu")
		(net "UPI_CPU1_CPU0_P1P1_DN<16>")
	)
	(segment
		(start 298.138342 -42.93108)
		(end 297.797474 -42.183812)
		(width 0.1143)
		(layer "In9.Cu")
		(net "UPI_CPU1_CPU0_P1P1_DN<16>")
	)
	(segment
		(start 302.653446 -56.304434)
		(end 302.686212 -56.304434)
		(width 0.0889)
		(layer "In9.Cu")
		(net "UPI_CPU1_CPU0_P1P1_DN<16>")
	)
	(segment
		(start 300.05274 -47.126398)
		(end 299.850556 -47.051214)
		(width 0.1143)
		(layer "In9.Cu")
		(net "UPI_CPU1_CPU0_P1P1_DN<16>")
	)
	(segment
		(start 127.959612 -52.240688)
		(end 127.959612 -52.40782)
		(width 0.0889)
		(layer "In9.Cu")
		(net "UPI_CPU1_CPU0_P1P1_DN<16>")
	)
	(segment
		(start 199.215502 -32.79394)
		(end 195.213732 -33.8709)
		(width 0.1143)
		(layer "In9.Cu")
		(net "UPI_CPU1_CPU0_P1P1_DN<16>")
	)
	(segment
		(start 298.616624 -44.346876)
		(end 298.474384 -44.034456)
		(width 0.1143)
		(layer "In9.Cu")
		(net "UPI_CPU1_CPU0_P1P1_DN<16>")
	)
	(segment
		(start 303.011586 -53.143404)
		(end 303.113186 -52.967636)
		(width 0.0889)
		(layer "In9.Cu")
		(net "UPI_CPU1_CPU0_P1P1_DN<16>")
	)
	(segment
		(start 299.372528 -45.635418)
		(end 299.230288 -45.323506)
		(width 0.1143)
		(layer "In9.Cu")
		(net "UPI_CPU1_CPU0_P1P1_DN<16>")
	)
	(segment
		(start 299.29709 -45.837348)
		(end 299.372528 -45.635418)
		(width 0.1143)
		(layer "In9.Cu")
		(net "UPI_CPU1_CPU0_P1P1_DN<16>")
	)
	(segment
		(start 298.205398 -43.44543)
		(end 298.063158 -43.13301)
		(width 0.1143)
		(layer "In9.Cu")
		(net "UPI_CPU1_CPU0_P1P1_DN<16>")
	)
	(segment
		(start 301.300896 -57.685686)
		(end 301.294546 -57.675018)
		(width 0.0889)
		(layer "In9.Cu")
		(net "UPI_CPU1_CPU0_P1P1_DN<16>")
	)
	(segment
		(start 212.757004 -36.015168)
		(end 212.064092 -36.082224)
		(width 0.1143)
		(layer "In9.Cu")
		(net "UPI_CPU1_CPU0_P1P1_DN<16>")
	)
	(segment
		(start 303.022762 -55.713122)
		(end 303.017936 -55.704486)
		(width 0.0889)
		(layer "In9.Cu")
		(net "UPI_CPU1_CPU0_P1P1_DN<16>")
	)
	(segment
		(start 297.607482 -41.89857)
		(end 297.3959 -41.856406)
		(width 0.1143)
		(layer "In9.Cu")
		(net "UPI_CPU1_CPU0_P1P1_DN<16>")
	)
	(segment
		(start 127.959612 -52.6923)
		(end 127.959612 -52.8193)
		(width 0.0889)
		(layer "In9.Cu")
		(net "UPI_CPU1_CPU0_P1P1_DN<16>")
	)
	(segment
		(start 187.414662 -32.802322)
		(end 178.804824 -33.785556)
		(width 0.1143)
		(layer "In9.Cu")
		(net "UPI_CPU1_CPU0_P1P1_DN<16>")
	)
	(segment
		(start 300.657006 -49.107598)
		(end 300.657006 -48.820832)
		(width 0.0889)
		(layer "In9.Cu")
		(net "UPI_CPU1_CPU0_P1P1_DN<16>")
	)
	(segment
		(start 300.606206 -48.339756)
		(end 300.463966 -48.027844)
		(width 0.1143)
		(layer "In9.Cu")
		(net "UPI_CPU1_CPU0_P1P1_DN<16>")
	)
	(segment
		(start 297.3959 -41.856406)
		(end 297.205654 -41.570656)
		(width 0.1143)
		(layer "In9.Cu")
		(net "UPI_CPU1_CPU0_P1P1_DN<16>")
	)
	(segment
		(start 128.035812 -52.8955)
		(end 128.035812 -53.05298)
		(width 0.0889)
		(layer "In9.Cu")
		(net "UPI_CPU1_CPU0_P1P1_DN<16>")
	)
	(segment
		(start 299.028104 -45.248322)
		(end 298.885864 -44.935902)
		(width 0.1143)
		(layer "In9.Cu")
		(net "UPI_CPU1_CPU0_P1P1_DN<16>")
	)
	(segment
		(start 148.254466 -39.824152)
		(end 140.804646 -39.510462)
		(width 0.1143)
		(layer "In9.Cu")
		(net "UPI_CPU1_CPU0_P1P1_DN<16>")
	)
	(segment
		(start 300.19498 -47.43831)
		(end 300.05274 -47.126398)
		(width 0.1143)
		(layer "In9.Cu")
		(net "UPI_CPU1_CPU0_P1P1_DN<16>")
	)
	(segment
		(start 156.181298 -38.379908)
		(end 155.78455 -38.384988)
		(width 0.1143)
		(layer "In9.Cu")
		(net "UPI_CPU1_CPU0_P1P1_DN<16>")
	)
	(segment
		(start 297.205654 -41.570656)
		(end 297.248072 -41.359328)
		(width 0.1143)
		(layer "In9.Cu")
		(net "UPI_CPU1_CPU0_P1P1_DN<16>")
	)
	(segment
		(start 245.578122 -33.13938)
		(end 241.82324 -34.82594)
		(width 0.1143)
		(layer "In9.Cu")
		(net "UPI_CPU1_CPU0_P1P1_DN<16>")
	)
	(segment
		(start 303.508156 -54.818788)
		(end 303.540922 -54.818788)
		(width 0.0889)
		(layer "In9.Cu")
		(net "UPI_CPU1_CPU0_P1P1_DN<16>")
	)
	(segment
		(start 128.035812 -53.05298)
		(end 127.959612 -53.12918)
		(width 0.0889)
		(layer "In9.Cu")
		(net "UPI_CPU1_CPU0_P1P1_DN<16>")
	)
	(segment
		(start 127.959612 -52.8193)
		(end 128.035812 -52.8955)
		(width 0.0889)
		(layer "In9.Cu")
		(net "UPI_CPU1_CPU0_P1P1_DN<16>")
	)
	(segment
		(start 303.113186 -52.451762)
		(end 302.684688 -51.482498)
		(width 0.0889)
		(layer "In9.Cu")
		(net "UPI_CPU1_CPU0_P1P1_DN<16>")
	)
	(segment
		(start 302.684688 -51.482498)
		(end 300.657006 -49.107598)
		(width 0.0889)
		(layer "In9.Cu")
		(net "UPI_CPU1_CPU0_P1P1_DN<16>")
	)
	(segment
		(start 300.261782 -47.952406)
		(end 300.119542 -47.64024)
		(width 0.1143)
		(layer "In9.Cu")
		(net "UPI_CPU1_CPU0_P1P1_DN<16>")
	)
	(segment
		(start 155.78455 -38.384988)
		(end 148.254466 -39.824152)
		(width 0.1143)
		(layer "In9.Cu")
		(net "UPI_CPU1_CPU0_P1P1_DN<16>")
	)
	(segment
		(start 128.286002 -54.751732)
		(end 128.227328 -54.418738)
		(width 0.0889)
		(layer "In9.Cu")
		(net "UPI_CPU1_CPU0_P1P1_DN<16>")
	)
	(segment
		(start 300.954186 -58.876438)
		(end 301.07128 -58.75909)
		(width 0.0889)
		(layer "In9.Cu")
		(net "UPI_CPU1_CPU0_P1P1_DN<16>")
	)
	(segment
		(start 290.053014 -37.0967)
		(end 282.151582 -38.475666)
		(width 0.1143)
		(layer "In9.Cu")
		(net "UPI_CPU1_CPU0_P1P1_DN<16>")
	)
	(segment
		(start 128.006348 -48.819816)
		(end 128.006348 -52.146454)
		(width 0.1143)
		(layer "In9.Cu")
		(net "UPI_CPU1_CPU0_P1P1_DN<16>")
	)
	(segment
		(start 128.006348 -52.146454)
		(end 128.006348 -52.193952)
		(width 0.0889)
		(layer "In9.Cu")
		(net "UPI_CPU1_CPU0_P1P1_DN<16>")
	)
	(segment
		(start 303.544732 -54.018688)
		(end 303.516792 -54.018688)
		(width 0.0889)
		(layer "In9.Cu")
		(net "UPI_CPU1_CPU0_P1P1_DN<16>")
	)
	(segment
		(start 167.046148 -37.490654)
		(end 164.37356 -37.750496)
		(width 0.1143)
		(layer "In9.Cu")
		(net "UPI_CPU1_CPU0_P1P1_DN<16>")
	)
	(segment
		(start 264.50417 -35.752532)
		(end 264.50417 -35.752786)
		(width 0.1143)
		(layer "In9.Cu")
		(net "UPI_CPU1_CPU0_P1P1_DN<16>")
	)
	(segment
		(start 222.396812 -35.291522)
		(end 212.757004 -36.015168)
		(width 0.1143)
		(layer "In9.Cu")
		(net "UPI_CPU1_CPU0_P1P1_DN<16>")
	)
	(segment
		(start 300.606206 -48.770032)
		(end 300.606206 -48.747934)
		(width 0.0889)
		(layer "In9.Cu")
		(net "UPI_CPU1_CPU0_P1P1_DN<16>")
	)
	(segment
		(start 212.064092 -36.082224)
		(end 199.215502 -32.79394)
		(width 0.1143)
		(layer "In9.Cu")
		(net "UPI_CPU1_CPU0_P1P1_DN<16>")
	)
	(segment
		(start 298.885864 -44.935902)
		(end 298.961048 -44.733972)
		(width 0.1143)
		(layer "In9.Cu")
		(net "UPI_CPU1_CPU0_P1P1_DN<16>")
	)
	(segment
		(start 298.961048 -44.733972)
		(end 298.818808 -44.42206)
		(width 0.1143)
		(layer "In9.Cu")
		(net "UPI_CPU1_CPU0_P1P1_DN<16>")
	)
	(segment
		(start 128.035812 -52.6161)
		(end 127.959612 -52.6923)
		(width 0.0889)
		(layer "In9.Cu")
		(net "UPI_CPU1_CPU0_P1P1_DN<16>")
	)
	(segment
		(start 127.959612 -52.40782)
		(end 128.035812 -52.48402)
		(width 0.0889)
		(layer "In9.Cu")
		(net "UPI_CPU1_CPU0_P1P1_DN<16>")
	)
	(segment
		(start 250.88977 -33.13938)
		(end 245.578122 -33.13938)
		(width 0.1143)
		(layer "In9.Cu")
		(net "UPI_CPU1_CPU0_P1P1_DN<16>")
	)
	(segment
		(start 241.82324 -34.82594)
		(end 236.736382 -34.21507)
		(width 0.1143)
		(layer "In9.Cu")
		(net "UPI_CPU1_CPU0_P1P1_DN<16>")
	)
	(segment
		(start 299.850556 -47.051214)
		(end 299.708316 -46.738794)
		(width 0.1143)
		(layer "In9.Cu")
		(net "UPI_CPU1_CPU0_P1P1_DN<16>")
	)
	(segment
		(start 178.734974 -33.798764)
		(end 169.926 -36.252658)
		(width 0.1143)
		(layer "In9.Cu")
		(net "UPI_CPU1_CPU0_P1P1_DN<16>")
	)
	(segment
		(start 159.336486 -38.57752)
		(end 156.181298 -38.379908)
		(width 0.1143)
		(layer "In9.Cu")
		(net "UPI_CPU1_CPU0_P1P1_DN<16>")
	)
	(segment
		(start 297.248072 -41.359328)
		(end 295.801288 -39.188644)
		(width 0.1143)
		(layer "In9.Cu")
		(net "UPI_CPU1_CPU0_P1P1_DN<16>")
	)
	(segment
		(start 299.783754 -46.536864)
		(end 299.641514 -46.224952)
		(width 0.1143)
		(layer "In9.Cu")
		(net "UPI_CPU1_CPU0_P1P1_DN<16>")
	)
	(segment
		(start 264.50417 -35.752786)
		(end 261.458202 -36.753292)
		(width 0.1143)
		(layer "In9.Cu")
		(net "UPI_CPU1_CPU0_P1P1_DN<16>")
	)
	(segment
		(start 301.791116 -56.799988)
		(end 301.823882 -56.799988)
		(width 0.0889)
		(layer "In9.Cu")
		(net "UPI_CPU1_CPU0_P1P1_DN<16>")
	)
	(segment
		(start 303.017936 -55.704486)
		(end 303.011586 -55.693818)
		(width 0.0889)
		(layer "In9.Cu")
		(net "UPI_CPU1_CPU0_P1P1_DN<16>")
	)
	(segment
		(start 195.213732 -33.8709)
		(end 193.0908 -33.033716)
		(width 0.1143)
		(layer "In9.Cu")
		(net "UPI_CPU1_CPU0_P1P1_DN<16>")
	)
	(segment
		(start 164.37356 -37.750496)
		(end 159.336486 -38.57752)
		(width 0.1143)
		(layer "In9.Cu")
		(net "UPI_CPU1_CPU0_P1P1_DN<16>")
	)
	(segment
		(start 300.119542 -47.64024)
		(end 300.19498 -47.43831)
		(width 0.1143)
		(layer "In9.Cu")
		(net "UPI_CPU1_CPU0_P1P1_DN<16>")
	)
	(segment
		(start 299.641514 -46.224952)
		(end 299.43933 -46.149768)
		(width 0.1143)
		(layer "In9.Cu")
		(net "UPI_CPU1_CPU0_P1P1_DN<16>")
	)
	(segment
		(start 299.43933 -46.149768)
		(end 299.29709 -45.837348)
		(width 0.1143)
		(layer "In9.Cu")
		(net "UPI_CPU1_CPU0_P1P1_DN<16>")
	)
	(segment
		(start 193.0908 -33.033716)
		(end 187.414662 -32.802322)
		(width 0.1143)
		(layer "In9.Cu")
		(net "UPI_CPU1_CPU0_P1P1_DN<16>")
	)
	(segment
		(start 169.926 -36.252658)
		(end 168.864788 -37.31387)
		(width 0.1143)
		(layer "In9.Cu")
		(net "UPI_CPU1_CPU0_P1P1_DN<16>")
	)
	(segment
		(start 168.864788 -37.31387)
		(end 167.046148 -37.490654)
		(width 0.1143)
		(layer "In9.Cu")
		(net "UPI_CPU1_CPU0_P1P1_DN<16>")
	)
	(segment
		(start 300.657006 -48.820832)
		(end 300.606206 -48.770032)
		(width 0.0889)
		(layer "In9.Cu")
		(net "UPI_CPU1_CPU0_P1P1_DN<16>")
	)
	(segment
		(start 258.615434 -36.272978)
		(end 250.88977 -33.13938)
		(width 0.1143)
		(layer "In9.Cu")
		(net "UPI_CPU1_CPU0_P1P1_DN<16>")
	)
	(arc
		(start 127.903986 -54.654704)
		(mid 128.020568 -54.761492)
		(end 128.169416 -54.814724)
		(width 0.0889)
		(layer "In9.Cu")
		(net "UPI_CPU1_CPU0_P1P1_DN<16>")
	)
	(arc
		(start 127.880618 -54.218586)
		(mid 127.827564 -54.440121)
		(end 127.903986 -54.654704)
		(width 0.0889)
		(layer "In9.Cu")
		(net "UPI_CPU1_CPU0_P1P1_DN<16>")
	)
	(arc
		(start 128.169416 -54.814724)
		(mid 128.204126 -54.818272)
		(end 128.239012 -54.818788)
		(width 0.0889)
		(layer "In9.Cu")
		(net "UPI_CPU1_CPU0_P1P1_DN<16>")
	)
	(arc
		(start 301.300896 -58.085736)
		(mid 301.354366 -57.890673)
		(end 301.305722 -57.694322)
		(width 0.0889)
		(layer "In9.Cu")
		(net "UPI_CPU1_CPU0_P1P1_DN<16>")
	)
	(arc
		(start 301.294546 -57.675018)
		(mid 301.298577 -57.098836)
		(end 301.791116 -56.799988)
		(width 0.0889)
		(layer "In9.Cu")
		(net "UPI_CPU1_CPU0_P1P1_DN<16>")
	)
	(arc
		(start 301.07128 -58.75909)
		(mid 301.182713 -58.592458)
		(end 301.221902 -58.39587)
		(width 0.0889)
		(layer "In9.Cu")
		(net "UPI_CPU1_CPU0_P1P1_DN<16>")
	)
	(arc
		(start 301.823882 -56.799988)
		(mid 302.017732 -56.743638)
		(end 302.159416 -56.599836)
		(width 0.0889)
		(layer "In9.Cu")
		(net "UPI_CPU1_CPU0_P1P1_DN<16>")
	)
	(arc
		(start 303.011586 -55.693818)
		(mid 303.015617 -55.117636)
		(end 303.508156 -54.818788)
		(width 0.0889)
		(layer "In9.Cu")
		(net "UPI_CPU1_CPU0_P1P1_DN<16>")
	)
	(arc
		(start 302.159416 -56.599836)
		(mid 302.368024 -56.387904)
		(end 302.653446 -56.304434)
		(width 0.0889)
		(layer "In9.Cu")
		(net "UPI_CPU1_CPU0_P1P1_DN<16>")
	)
	(arc
		(start 303.540922 -54.818788)
		(mid 303.929948 -54.420642)
		(end 303.544732 -54.018688)
		(width 0.0889)
		(layer "In9.Cu")
		(net "UPI_CPU1_CPU0_P1P1_DN<16>")
	)
	(arc
		(start 303.516792 -54.018688)
		(mid 303.017911 -53.723251)
		(end 303.011586 -53.143404)
		(width 0.0889)
		(layer "In9.Cu")
		(net "UPI_CPU1_CPU0_P1P1_DN<16>")
	)
	(arc
		(start 302.686212 -56.304434)
		(mid 303.01913 -56.102443)
		(end 303.022762 -55.713122)
		(width 0.0889)
		(layer "In9.Cu")
		(net "UPI_CPU1_CPU0_P1P1_DN<16>")
	)
	(arc
		(start 127.959612 -53.923946)
		(mid 127.939454 -54.07645)
		(end 127.880618 -54.218586)
		(width 0.0889)
		(layer "In9.Cu")
		(net "UPI_CPU1_CPU0_P1P1_DN<16>")
	)
	(arc
		(start 301.221902 -58.39587)
		(mid 301.239984 -58.235345)
		(end 301.300896 -58.085736)
		(width 0.0889)
		(layer "In9.Cu")
		(net "UPI_CPU1_CPU0_P1P1_DN<16>")
	)
	(segment
		(start 126.797308 -55.904384)
		(end 127.368808 -55.904384)
		(width 0.1143)
		(layer "F.Cu")
		(net "UPI_CPU1_CPU0_P1P1_DN<15>")
	)
	(segment
		(start 300.382686 -57.885584)
		(end 300.954186 -57.885584)
		(width 0.1143)
		(layer "F.Cu")
		(net "UPI_CPU1_CPU0_P1P1_DN<15>")
	)
	(via
		(at 300.954186 -57.885584)
		(size 0.508)
		(drill 0.254)
		(layers "F.Cu" "B.Cu")
		(net "UPI_CPU1_CPU0_P1P1_DN<15>")
	)
	(via
		(at 127.368808 -55.904384)
		(size 0.508)
		(drill 0.254)
		(layers "F.Cu" "B.Cu")
		(net "UPI_CPU1_CPU0_P1P1_DN<15>")
	)
	(segment
		(start 128.441958 -52.160932)
		(end 128.495044 -52.214018)
		(width 0.0889)
		(layer "In9.Cu")
		(net "UPI_CPU1_CPU0_P1P1_DN<15>")
	)
	(segment
		(start 300.66107 -57.716674)
		(end 300.637194 -57.62752)
		(width 0.0889)
		(layer "In9.Cu")
		(net "UPI_CPU1_CPU0_P1P1_DN<15>")
	)
	(segment
		(start 299.972476 -49.978564)
		(end 299.972476 -49.169828)
		(width 0.1143)
		(layer "In9.Cu")
		(net "UPI_CPU1_CPU0_P1P1_DN<15>")
	)
	(segment
		(start 128.441958 -49.051972)
		(end 128.441958 -52.160932)
		(width 0.1143)
		(layer "In9.Cu")
		(net "UPI_CPU1_CPU0_P1P1_DN<15>")
	)
	(segment
		(start 170.34764 -38.642544)
		(end 170.154092 -38.642544)
		(width 0.1143)
		(layer "In9.Cu")
		(net "UPI_CPU1_CPU0_P1P1_DN<15>")
	)
	(segment
		(start 156.108908 -38.802818)
		(end 155.585414 -38.808914)
		(width 0.1143)
		(layer "In9.Cu")
		(net "UPI_CPU1_CPU0_P1P1_DN<15>")
	)
	(segment
		(start 179.61356 -34.514536)
		(end 179.535074 -34.53892)
		(width 0.1143)
		(layer "In9.Cu")
		(net "UPI_CPU1_CPU0_P1P1_DN<15>")
	)
	(segment
		(start 299.921676 -50.445416)
		(end 299.921676 -50.051462)
		(width 0.0889)
		(layer "In9.Cu")
		(net "UPI_CPU1_CPU0_P1P1_DN<15>")
	)
	(segment
		(start 282.319222 -38.86454)
		(end 264.522966 -36.129976)
		(width 0.1143)
		(layer "In9.Cu")
		(net "UPI_CPU1_CPU0_P1P1_DN<15>")
	)
	(segment
		(start 198.997062 -33.216342)
		(end 195.231258 -34.283396)
		(width 0.1143)
		(layer "In9.Cu")
		(net "UPI_CPU1_CPU0_P1P1_DN<15>")
	)
	(segment
		(start 258.471416 -36.644326)
		(end 250.835668 -33.48228)
		(width 0.1143)
		(layer "In9.Cu")
		(net "UPI_CPU1_CPU0_P1P1_DN<15>")
	)
	(segment
		(start 128.495044 -52.214018)
		(end 128.495044 -53.317902)
		(width 0.0889)
		(layer "In9.Cu")
		(net "UPI_CPU1_CPU0_P1P1_DN<15>")
	)
	(segment
		(start 128.404366 -53.603398)
		(end 128.495044 -53.694076)
		(width 0.0889)
		(layer "In9.Cu")
		(net "UPI_CPU1_CPU0_P1P1_DN<15>")
	)
	(segment
		(start 159.54248 -39.037768)
		(end 156.108908 -38.802818)
		(width 0.1143)
		(layer "In9.Cu")
		(net "UPI_CPU1_CPU0_P1P1_DN<15>")
	)
	(segment
		(start 302.324516 -52.142136)
		(end 302.26381 -52.036726)
		(width 0.0889)
		(layer "In9.Cu")
		(net "UPI_CPU1_CPU0_P1P1_DN<15>")
	)
	(segment
		(start 245.673372 -33.48228)
		(end 242.034822 -35.245802)
		(width 0.1143)
		(layer "In9.Cu")
		(net "UPI_CPU1_CPU0_P1P1_DN<15>")
	)
	(segment
		(start 147.680172 -40.20185)
		(end 140.92047 -39.989506)
		(width 0.1143)
		(layer "In9.Cu")
		(net "UPI_CPU1_CPU0_P1P1_DN<15>")
	)
	(segment
		(start 187.499244 -33.214818)
		(end 179.61356 -34.514536)
		(width 0.1143)
		(layer "In9.Cu")
		(net "UPI_CPU1_CPU0_P1P1_DN<15>")
	)
	(segment
		(start 161.09442 -38.74643)
		(end 159.54248 -39.037768)
		(width 0.1143)
		(layer "In9.Cu")
		(net "UPI_CPU1_CPU0_P1P1_DN<15>")
	)
	(segment
		(start 301.460662 -51.63566)
		(end 301.41418 -51.558952)
		(width 0.0889)
		(layer "In9.Cu")
		(net "UPI_CPU1_CPU0_P1P1_DN<15>")
	)
	(segment
		(start 302.31969 -53.731922)
		(end 302.324516 -53.723286)
		(width 0.0889)
		(layer "In9.Cu")
		(net "UPI_CPU1_CPU0_P1P1_DN<15>")
	)
	(segment
		(start 301.79772 -55.999888)
		(end 301.830486 -55.999888)
		(width 0.0889)
		(layer "In9.Cu")
		(net "UPI_CPU1_CPU0_P1P1_DN<15>")
	)
	(segment
		(start 300.94301 -56.494934)
		(end 300.975776 -56.494934)
		(width 0.0889)
		(layer "In9.Cu")
		(net "UPI_CPU1_CPU0_P1P1_DN<15>")
	)
	(segment
		(start 128.578864 -54.61)
		(end 128.574038 -54.618636)
		(width 0.0889)
		(layer "In9.Cu")
		(net "UPI_CPU1_CPU0_P1P1_DN<15>")
	)
	(segment
		(start 171.666916 -38.596316)
		(end 170.34764 -38.642544)
		(width 0.1143)
		(layer "In9.Cu")
		(net "UPI_CPU1_CPU0_P1P1_DN<15>")
	)
	(segment
		(start 140.92047 -39.989506)
		(end 135.224774 -42.286936)
		(width 0.1143)
		(layer "In9.Cu")
		(net "UPI_CPU1_CPU0_P1P1_DN<15>")
	)
	(segment
		(start 290.162234 -37.486336)
		(end 282.319222 -38.86454)
		(width 0.1143)
		(layer "In9.Cu")
		(net "UPI_CPU1_CPU0_P1P1_DN<15>")
	)
	(segment
		(start 148.508974 -40.20185)
		(end 147.680172 -40.20185)
		(width 0.1143)
		(layer "In9.Cu")
		(net "UPI_CPU1_CPU0_P1P1_DN<15>")
	)
	(segment
		(start 250.835668 -33.48228)
		(end 245.673372 -33.48228)
		(width 0.1143)
		(layer "In9.Cu")
		(net "UPI_CPU1_CPU0_P1P1_DN<15>")
	)
	(segment
		(start 302.324516 -54.713886)
		(end 302.330866 -54.703218)
		(width 0.0889)
		(layer "In9.Cu")
		(net "UPI_CPU1_CPU0_P1P1_DN<15>")
	)
	(segment
		(start 301.172626 -51.354482)
		(end 300.335188 -50.858674)
		(width 0.0889)
		(layer "In9.Cu")
		(net "UPI_CPU1_CPU0_P1P1_DN<15>")
	)
	(segment
		(start 172.278294 -38.460426)
		(end 171.666916 -38.596316)
		(width 0.1143)
		(layer "In9.Cu")
		(net "UPI_CPU1_CPU0_P1P1_DN<15>")
	)
	(segment
		(start 179.535074 -34.53892)
		(end 175.57496 -36.428172)
		(width 0.1143)
		(layer "In9.Cu")
		(net "UPI_CPU1_CPU0_P1P1_DN<15>")
	)
	(segment
		(start 128.495044 -53.317902)
		(end 128.404366 -53.40858)
		(width 0.0889)
		(layer "In9.Cu")
		(net "UPI_CPU1_CPU0_P1P1_DN<15>")
	)
	(segment
		(start 170.154092 -38.642544)
		(end 161.09442 -38.74643)
		(width 0.1143)
		(layer "In9.Cu")
		(net "UPI_CPU1_CPU0_P1P1_DN<15>")
	)
	(segment
		(start 222.396812 -35.682682)
		(end 212.061044 -36.448238)
		(width 0.1143)
		(layer "In9.Cu")
		(net "UPI_CPU1_CPU0_P1P1_DN<15>")
	)
	(segment
		(start 236.720888 -34.621724)
		(end 222.396812 -35.682682)
		(width 0.1143)
		(layer "In9.Cu")
		(net "UPI_CPU1_CPU0_P1P1_DN<15>")
	)
	(segment
		(start 299.921676 -50.051462)
		(end 299.972476 -49.978564)
		(width 0.0889)
		(layer "In9.Cu")
		(net "UPI_CPU1_CPU0_P1P1_DN<15>")
	)
	(segment
		(start 261.456424 -37.130482)
		(end 258.471416 -36.644326)
		(width 0.1143)
		(layer "In9.Cu")
		(net "UPI_CPU1_CPU0_P1P1_DN<15>")
	)
	(segment
		(start 301.41418 -51.558952)
		(end 301.172626 -51.354482)
		(width 0.0889)
		(layer "In9.Cu")
		(net "UPI_CPU1_CPU0_P1P1_DN<15>")
	)
	(segment
		(start 300.335188 -50.858674)
		(end 299.921676 -50.445416)
		(width 0.0889)
		(layer "In9.Cu")
		(net "UPI_CPU1_CPU0_P1P1_DN<15>")
	)
	(segment
		(start 264.522966 -36.129976)
		(end 261.456424 -37.130482)
		(width 0.1143)
		(layer "In9.Cu")
		(net "UPI_CPU1_CPU0_P1P1_DN<15>")
	)
	(segment
		(start 300.954186 -57.885584)
		(end 300.66107 -57.716674)
		(width 0.0889)
		(layer "In9.Cu")
		(net "UPI_CPU1_CPU0_P1P1_DN<15>")
	)
	(segment
		(start 128.238504 -55.809388)
		(end 128.205738 -55.809388)
		(width 0.0889)
		(layer "In9.Cu")
		(net "UPI_CPU1_CPU0_P1P1_DN<15>")
	)
	(segment
		(start 155.585414 -38.808914)
		(end 148.508974 -40.20185)
		(width 0.1143)
		(layer "In9.Cu")
		(net "UPI_CPU1_CPU0_P1P1_DN<15>")
	)
	(segment
		(start 128.574038 -54.618636)
		(end 128.567688 -54.629304)
		(width 0.0889)
		(layer "In9.Cu")
		(net "UPI_CPU1_CPU0_P1P1_DN<15>")
	)
	(segment
		(start 128.495044 -53.694076)
		(end 128.495044 -53.924454)
		(width 0.0889)
		(layer "In9.Cu")
		(net "UPI_CPU1_CPU0_P1P1_DN<15>")
	)
	(segment
		(start 302.31969 -54.722522)
		(end 302.324516 -54.713886)
		(width 0.0889)
		(layer "In9.Cu")
		(net "UPI_CPU1_CPU0_P1P1_DN<15>")
	)
	(segment
		(start 295.223438 -39.22014)
		(end 293.539164 -38.091872)
		(width 0.1143)
		(layer "In9.Cu")
		(net "UPI_CPU1_CPU0_P1P1_DN<15>")
	)
	(segment
		(start 135.224774 -42.286936)
		(end 128.441958 -49.051972)
		(width 0.1143)
		(layer "In9.Cu")
		(net "UPI_CPU1_CPU0_P1P1_DN<15>")
	)
	(segment
		(start 127.530352 -56.066182)
		(end 127.368808 -55.904384)
		(width 0.0889)
		(layer "In9.Cu")
		(net "UPI_CPU1_CPU0_P1P1_DN<15>")
	)
	(segment
		(start 195.231258 -34.283396)
		(end 192.735454 -33.423098)
		(width 0.1143)
		(layer "In9.Cu")
		(net "UPI_CPU1_CPU0_P1P1_DN<15>")
	)
	(segment
		(start 212.061044 -36.448238)
		(end 198.997062 -33.216342)
		(width 0.1143)
		(layer "In9.Cu")
		(net "UPI_CPU1_CPU0_P1P1_DN<15>")
	)
	(segment
		(start 175.547528 -36.443412)
		(end 172.278294 -38.460426)
		(width 0.1143)
		(layer "In9.Cu")
		(net "UPI_CPU1_CPU0_P1P1_DN<15>")
	)
	(segment
		(start 175.57496 -36.428172)
		(end 175.547528 -36.443412)
		(width 0.1143)
		(layer "In9.Cu")
		(net "UPI_CPU1_CPU0_P1P1_DN<15>")
	)
	(segment
		(start 293.539164 -38.091872)
		(end 290.162234 -37.486336)
		(width 0.1143)
		(layer "In9.Cu")
		(net "UPI_CPU1_CPU0_P1P1_DN<15>")
	)
	(segment
		(start 299.972476 -49.169828)
		(end 296.991532 -41.873678)
		(width 0.1143)
		(layer "In9.Cu")
		(net "UPI_CPU1_CPU0_P1P1_DN<15>")
	)
	(segment
		(start 302.330866 -53.143404)
		(end 302.324516 -53.132736)
		(width 0.0889)
		(layer "In9.Cu")
		(net "UPI_CPU1_CPU0_P1P1_DN<15>")
	)
	(segment
		(start 296.991532 -41.873678)
		(end 295.223438 -39.22014)
		(width 0.1143)
		(layer "In9.Cu")
		(net "UPI_CPU1_CPU0_P1P1_DN<15>")
	)
	(segment
		(start 242.034822 -35.245802)
		(end 236.720888 -34.621724)
		(width 0.1143)
		(layer "In9.Cu")
		(net "UPI_CPU1_CPU0_P1P1_DN<15>")
	)
	(segment
		(start 192.735454 -33.423098)
		(end 187.499244 -33.214818)
		(width 0.1143)
		(layer "In9.Cu")
		(net "UPI_CPU1_CPU0_P1P1_DN<15>")
	)
	(segment
		(start 128.404366 -53.40858)
		(end 128.404366 -53.603398)
		(width 0.0889)
		(layer "In9.Cu")
		(net "UPI_CPU1_CPU0_P1P1_DN<15>")
	)
	(arc
		(start 301.465996 -56.199786)
		(mid 301.606075 -56.05705)
		(end 301.79772 -55.999888)
		(width 0.0889)
		(layer "In9.Cu")
		(net "UPI_CPU1_CPU0_P1P1_DN<15>")
	)
	(arc
		(start 128.205738 -55.809388)
		(mid 127.951073 -55.877417)
		(end 127.751332 -56.049418)
		(width 0.0889)
		(layer "In9.Cu")
		(net "UPI_CPU1_CPU0_P1P1_DN<15>")
	)
	(arc
		(start 302.324516 -54.123336)
		(mid 302.271046 -53.928273)
		(end 302.31969 -53.731922)
		(width 0.0889)
		(layer "In9.Cu")
		(net "UPI_CPU1_CPU0_P1P1_DN<15>")
	)
	(arc
		(start 300.975776 -56.494934)
		(mid 301.258993 -56.410653)
		(end 301.465996 -56.199786)
		(width 0.0889)
		(layer "In9.Cu")
		(net "UPI_CPU1_CPU0_P1P1_DN<15>")
	)
	(arc
		(start 302.324516 -53.723286)
		(mid 302.403738 -53.434168)
		(end 302.330866 -53.143404)
		(width 0.0889)
		(layer "In9.Cu")
		(net "UPI_CPU1_CPU0_P1P1_DN<15>")
	)
	(arc
		(start 302.26381 -52.036726)
		(mid 302.059934 -51.887226)
		(end 301.812706 -51.834288)
		(width 0.0889)
		(layer "In9.Cu")
		(net "UPI_CPU1_CPU0_P1P1_DN<15>")
	)
	(arc
		(start 128.574038 -55.209186)
		(mid 128.576786 -55.604653)
		(end 128.238504 -55.809388)
		(width 0.0889)
		(layer "In9.Cu")
		(net "UPI_CPU1_CPU0_P1P1_DN<15>")
	)
	(arc
		(start 300.637194 -57.62752)
		(mid 300.685754 -57.357795)
		(end 300.607476 -57.095136)
		(width 0.0889)
		(layer "In9.Cu")
		(net "UPI_CPU1_CPU0_P1P1_DN<15>")
	)
	(arc
		(start 300.607476 -57.095136)
		(mid 300.604728 -56.699669)
		(end 300.94301 -56.494934)
		(width 0.0889)
		(layer "In9.Cu")
		(net "UPI_CPU1_CPU0_P1P1_DN<15>")
	)
	(arc
		(start 302.330866 -54.703218)
		(mid 302.403664 -54.412455)
		(end 302.324516 -54.123336)
		(width 0.0889)
		(layer "In9.Cu")
		(net "UPI_CPU1_CPU0_P1P1_DN<15>")
	)
	(arc
		(start 128.495044 -53.924454)
		(mid 128.515267 -54.076696)
		(end 128.574038 -54.218586)
		(width 0.0889)
		(layer "In9.Cu")
		(net "UPI_CPU1_CPU0_P1P1_DN<15>")
	)
	(arc
		(start 128.574038 -54.218586)
		(mid 128.627508 -54.413649)
		(end 128.578864 -54.61)
		(width 0.0889)
		(layer "In9.Cu")
		(net "UPI_CPU1_CPU0_P1P1_DN<15>")
	)
	(arc
		(start 302.324516 -55.113936)
		(mid 302.271046 -54.918873)
		(end 302.31969 -54.722522)
		(width 0.0889)
		(layer "In9.Cu")
		(net "UPI_CPU1_CPU0_P1P1_DN<15>")
	)
	(arc
		(start 128.567688 -54.629304)
		(mid 128.49489 -54.920067)
		(end 128.574038 -55.209186)
		(width 0.0889)
		(layer "In9.Cu")
		(net "UPI_CPU1_CPU0_P1P1_DN<15>")
	)
	(arc
		(start 127.751332 -56.049418)
		(mid 127.644717 -56.108446)
		(end 127.530352 -56.066182)
		(width 0.0889)
		(layer "In9.Cu")
		(net "UPI_CPU1_CPU0_P1P1_DN<15>")
	)
	(arc
		(start 301.812706 -51.834288)
		(mid 301.610633 -51.781147)
		(end 301.460662 -51.63566)
		(width 0.0889)
		(layer "In9.Cu")
		(net "UPI_CPU1_CPU0_P1P1_DN<15>")
	)
	(arc
		(start 302.324516 -53.132736)
		(mid 302.271017 -52.932838)
		(end 302.324516 -52.73294)
		(width 0.0889)
		(layer "In9.Cu")
		(net "UPI_CPU1_CPU0_P1P1_DN<15>")
	)
	(arc
		(start 302.324516 -52.73294)
		(mid 302.403647 -52.437538)
		(end 302.324516 -52.142136)
		(width 0.0889)
		(layer "In9.Cu")
		(net "UPI_CPU1_CPU0_P1P1_DN<15>")
	)
	(arc
		(start 301.830486 -55.999888)
		(mid 302.328737 -55.697048)
		(end 302.324516 -55.113936)
		(width 0.0889)
		(layer "In9.Cu")
		(net "UPI_CPU1_CPU0_P1P1_DN<15>")
	)
	(segment
		(start 299.524166 -58.381138)
		(end 300.095666 -58.381138)
		(width 0.1143)
		(layer "F.Cu")
		(net "UPI_CPU1_CPU0_P1P1_DN<14>")
	)
	(segment
		(start 128.514348 -54.913784)
		(end 129.085848 -54.913784)
		(width 0.1143)
		(layer "F.Cu")
		(net "UPI_CPU1_CPU0_P1P1_DN<14>")
	)
	(via
		(at 300.095666 -58.381138)
		(size 0.508)
		(drill 0.254)
		(layers "F.Cu" "B.Cu")
		(net "UPI_CPU1_CPU0_P1P1_DN<14>")
	)
	(via
		(at 129.085848 -54.913784)
		(size 0.508)
		(drill 0.254)
		(layers "F.Cu" "B.Cu")
		(net "UPI_CPU1_CPU0_P1P1_DN<14>")
	)
	(segment
		(start 129.43332 -53.724302)
		(end 129.437384 -53.731922)
		(width 0.0889)
		(layer "In9.Cu")
		(net "UPI_CPU1_CPU0_P1P1_DN<14>")
	)
	(segment
		(start 293.284148 -38.735254)
		(end 289.960812 -38.195758)
		(width 0.1143)
		(layer "In9.Cu")
		(net "UPI_CPU1_CPU0_P1P1_DN<14>")
	)
	(segment
		(start 258.535678 -37.38626)
		(end 250.65736 -34.11728)
		(width 0.1143)
		(layer "In9.Cu")
		(net "UPI_CPU1_CPU0_P1P1_DN<14>")
	)
	(segment
		(start 222.323152 -36.375848)
		(end 212.028786 -37.167312)
		(width 0.1143)
		(layer "In9.Cu")
		(net "UPI_CPU1_CPU0_P1P1_DN<14>")
	)
	(segment
		(start 195.21297 -34.989008)
		(end 192.669922 -34.077656)
		(width 0.1143)
		(layer "In9.Cu")
		(net "UPI_CPU1_CPU0_P1P1_DN<14>")
	)
	(segment
		(start 298.890436 -50.821336)
		(end 298.941236 -50.770536)
		(width 0.0889)
		(layer "In9.Cu")
		(net "UPI_CPU1_CPU0_P1P1_DN<14>")
	)
	(segment
		(start 199.029066 -33.915604)
		(end 198.675498 -34.003742)
		(width 0.1143)
		(layer "In9.Cu")
		(net "UPI_CPU1_CPU0_P1P1_DN<14>")
	)
	(segment
		(start 129.331466 -52.11572)
		(end 129.331466 -53.54828)
		(width 0.0889)
		(layer "In9.Cu")
		(net "UPI_CPU1_CPU0_P1P1_DN<14>")
	)
	(segment
		(start 147.786344 -41.031922)
		(end 147.608036 -41.02227)
		(width 0.1143)
		(layer "In9.Cu")
		(net "UPI_CPU1_CPU0_P1P1_DN<14>")
	)
	(segment
		(start 148.891498 -40.811196)
		(end 148.891244 -40.81145)
		(width 0.1143)
		(layer "In9.Cu")
		(net "UPI_CPU1_CPU0_P1P1_DN<14>")
	)
	(segment
		(start 180.025802 -35.302952)
		(end 179.958238 -35.324034)
		(width 0.1143)
		(layer "In9.Cu")
		(net "UPI_CPU1_CPU0_P1P1_DN<14>")
	)
	(segment
		(start 198.675498 -34.003742)
		(end 195.21297 -34.989008)
		(width 0.1143)
		(layer "In9.Cu")
		(net "UPI_CPU1_CPU0_P1P1_DN<14>")
	)
	(segment
		(start 297.194478 -45.442886)
		(end 297.191938 -45.435266)
		(width 0.1143)
		(layer "In9.Cu")
		(net "UPI_CPU1_CPU0_P1P1_DN<14>")
	)
	(segment
		(start 178.103784 -36.171632)
		(end 172.513244 -39.257986)
		(width 0.1143)
		(layer "In9.Cu")
		(net "UPI_CPU1_CPU0_P1P1_DN<14>")
	)
	(segment
		(start 289.960812 -38.195758)
		(end 282.27401 -39.537386)
		(width 0.1143)
		(layer "In9.Cu")
		(net "UPI_CPU1_CPU0_P1P1_DN<14>")
	)
	(segment
		(start 245.959884 -34.11728)
		(end 242.16487 -35.916616)
		(width 0.1143)
		(layer "In9.Cu")
		(net "UPI_CPU1_CPU0_P1P1_DN<14>")
	)
	(segment
		(start 294.54856 -39.56431)
		(end 293.284148 -38.735254)
		(width 0.1143)
		(layer "In9.Cu")
		(net "UPI_CPU1_CPU0_P1P1_DN<14>")
	)
	(segment
		(start 156.001212 -39.467028)
		(end 155.63215 -39.471346)
		(width 0.1143)
		(layer "In9.Cu")
		(net "UPI_CPU1_CPU0_P1P1_DN<14>")
	)
	(segment
		(start 300.96714 -52.342034)
		(end 300.9392 -52.342034)
		(width 0.0889)
		(layer "In9.Cu")
		(net "UPI_CPU1_CPU0_P1P1_DN<14>")
	)
	(segment
		(start 298.890436 -51.151536)
		(end 298.890436 -50.821336)
		(width 0.0889)
		(layer "In9.Cu")
		(net "UPI_CPU1_CPU0_P1P1_DN<14>")
	)
	(segment
		(start 300.058328 -58.780172)
		(end 300.037754 -58.777124)
		(width 0.0889)
		(layer "In9.Cu")
		(net "UPI_CPU1_CPU0_P1P1_DN<14>")
	)
	(segment
		(start 169.535602 -39.354252)
		(end 169.24655 -39.357554)
		(width 0.1143)
		(layer "In9.Cu")
		(net "UPI_CPU1_CPU0_P1P1_DN<14>")
	)
	(segment
		(start 192.669922 -34.077656)
		(end 187.599574 -33.876234)
		(width 0.1143)
		(layer "In9.Cu")
		(net "UPI_CPU1_CPU0_P1P1_DN<14>")
	)
	(segment
		(start 129.286508 -52.070762)
		(end 129.331466 -52.11572)
		(width 0.0889)
		(layer "In9.Cu")
		(net "UPI_CPU1_CPU0_P1P1_DN<14>")
	)
	(segment
		(start 301.465996 -53.227986)
		(end 301.472346 -53.217318)
		(width 0.0889)
		(layer "In9.Cu")
		(net "UPI_CPU1_CPU0_P1P1_DN<14>")
	)
	(segment
		(start 298.941236 -50.15484)
		(end 297.194478 -45.442886)
		(width 0.1143)
		(layer "In9.Cu")
		(net "UPI_CPU1_CPU0_P1P1_DN<14>")
	)
	(segment
		(start 300.94301 -55.504334)
		(end 300.975776 -55.504334)
		(width 0.0889)
		(layer "In9.Cu")
		(net "UPI_CPU1_CPU0_P1P1_DN<14>")
	)
	(segment
		(start 299.755306 -57.601104)
		(end 299.748956 -57.590436)
		(width 0.0889)
		(layer "In9.Cu")
		(net "UPI_CPU1_CPU0_P1P1_DN<14>")
	)
	(segment
		(start 300.08068 -55.999888)
		(end 300.113446 -55.999888)
		(width 0.0889)
		(layer "In9.Cu")
		(net "UPI_CPU1_CPU0_P1P1_DN<14>")
	)
	(segment
		(start 301.465996 -54.618636)
		(end 301.46117 -54.61)
		(width 0.0889)
		(layer "In9.Cu")
		(net "UPI_CPU1_CPU0_P1P1_DN<14>")
	)
	(segment
		(start 299.755306 -56.610504)
		(end 299.748956 -56.599836)
		(width 0.0889)
		(layer "In9.Cu")
		(net "UPI_CPU1_CPU0_P1P1_DN<14>")
	)
	(segment
		(start 300.095666 -58.381138)
		(end 300.204124 -58.489596)
		(width 0.0889)
		(layer "In9.Cu")
		(net "UPI_CPU1_CPU0_P1P1_DN<14>")
	)
	(segment
		(start 135.63092 -42.956226)
		(end 129.286508 -49.300638)
		(width 0.1143)
		(layer "In9.Cu")
		(net "UPI_CPU1_CPU0_P1P1_DN<14>")
	)
	(segment
		(start 129.331466 -53.54828)
		(end 129.43332 -53.724302)
		(width 0.0889)
		(layer "In9.Cu")
		(net "UPI_CPU1_CPU0_P1P1_DN<14>")
	)
	(segment
		(start 172.513244 -39.257986)
		(end 169.535602 -39.354252)
		(width 0.1143)
		(layer "In9.Cu")
		(net "UPI_CPU1_CPU0_P1P1_DN<14>")
	)
	(segment
		(start 264.456672 -36.86429)
		(end 261.60349 -37.81552)
		(width 0.1143)
		(layer "In9.Cu")
		(net "UPI_CPU1_CPU0_P1P1_DN<14>")
	)
	(segment
		(start 236.704886 -35.27044)
		(end 222.396812 -36.37026)
		(width 0.1143)
		(layer "In9.Cu")
		(net "UPI_CPU1_CPU0_P1P1_DN<14>")
	)
	(segment
		(start 187.599574 -33.876234)
		(end 180.025802 -35.302952)
		(width 0.1143)
		(layer "In9.Cu")
		(net "UPI_CPU1_CPU0_P1P1_DN<14>")
	)
	(segment
		(start 242.16487 -35.916616)
		(end 236.704886 -35.27044)
		(width 0.1143)
		(layer "In9.Cu")
		(net "UPI_CPU1_CPU0_P1P1_DN<14>")
	)
	(segment
		(start 178.123596 -36.161472)
		(end 178.103784 -36.171632)
		(width 0.1143)
		(layer "In9.Cu")
		(net "UPI_CPU1_CPU0_P1P1_DN<14>")
	)
	(segment
		(start 299.748956 -57.590436)
		(end 299.74413 -57.5818)
		(width 0.0889)
		(layer "In9.Cu")
		(net "UPI_CPU1_CPU0_P1P1_DN<14>")
	)
	(segment
		(start 299.748956 -56.599836)
		(end 299.74413 -56.5912)
		(width 0.0889)
		(layer "In9.Cu")
		(net "UPI_CPU1_CPU0_P1P1_DN<14>")
	)
	(segment
		(start 148.891498 -40.81145)
		(end 148.891498 -40.811196)
		(width 0.1143)
		(layer "In9.Cu")
		(net "UPI_CPU1_CPU0_P1P1_DN<14>")
	)
	(segment
		(start 261.60349 -37.81552)
		(end 258.535678 -37.38626)
		(width 0.1143)
		(layer "In9.Cu")
		(net "UPI_CPU1_CPU0_P1P1_DN<14>")
	)
	(segment
		(start 298.941236 -50.748438)
		(end 298.941236 -50.15484)
		(width 0.1143)
		(layer "In9.Cu")
		(net "UPI_CPU1_CPU0_P1P1_DN<14>")
	)
	(segment
		(start 297.191938 -45.435266)
		(end 295.60012 -41.141142)
		(width 0.1143)
		(layer "In9.Cu")
		(net "UPI_CPU1_CPU0_P1P1_DN<14>")
	)
	(segment
		(start 299.254926 -51.351434)
		(end 299.22216 -51.351434)
		(width 0.0889)
		(layer "In9.Cu")
		(net "UPI_CPU1_CPU0_P1P1_DN<14>")
	)
	(segment
		(start 129.202942 -54.796944)
		(end 129.085848 -54.913784)
		(width 0.0889)
		(layer "In9.Cu")
		(net "UPI_CPU1_CPU0_P1P1_DN<14>")
	)
	(segment
		(start 179.958238 -35.324034)
		(end 178.123596 -36.161472)
		(width 0.1143)
		(layer "In9.Cu")
		(net "UPI_CPU1_CPU0_P1P1_DN<14>")
	)
	(segment
		(start 141.141196 -40.808148)
		(end 135.63092 -42.956226)
		(width 0.1143)
		(layer "In9.Cu")
		(net "UPI_CPU1_CPU0_P1P1_DN<14>")
	)
	(segment
		(start 148.89607 -40.810434)
		(end 148.891498 -40.81145)
		(width 0.1143)
		(layer "In9.Cu")
		(net "UPI_CPU1_CPU0_P1P1_DN<14>")
	)
	(segment
		(start 250.65736 -34.11728)
		(end 245.959884 -34.11728)
		(width 0.1143)
		(layer "In9.Cu")
		(net "UPI_CPU1_CPU0_P1P1_DN<14>")
	)
	(segment
		(start 301.472346 -54.629304)
		(end 301.465996 -54.618636)
		(width 0.0889)
		(layer "In9.Cu")
		(net "UPI_CPU1_CPU0_P1P1_DN<14>")
	)
	(segment
		(start 282.27401 -39.537386)
		(end 264.456672 -36.86429)
		(width 0.1143)
		(layer "In9.Cu")
		(net "UPI_CPU1_CPU0_P1P1_DN<14>")
	)
	(segment
		(start 298.941236 -50.770536)
		(end 298.941236 -50.748438)
		(width 0.0889)
		(layer "In9.Cu")
		(net "UPI_CPU1_CPU0_P1P1_DN<14>")
	)
	(segment
		(start 159.678116 -39.716202)
		(end 156.001212 -39.467028)
		(width 0.1143)
		(layer "In9.Cu")
		(net "UPI_CPU1_CPU0_P1P1_DN<14>")
	)
	(segment
		(start 147.608036 -41.02227)
		(end 141.141196 -40.808148)
		(width 0.1143)
		(layer "In9.Cu")
		(net "UPI_CPU1_CPU0_P1P1_DN<14>")
	)
	(segment
		(start 155.63215 -39.471346)
		(end 148.89607 -40.810434)
		(width 0.1143)
		(layer "In9.Cu")
		(net "UPI_CPU1_CPU0_P1P1_DN<14>")
	)
	(segment
		(start 169.24655 -39.357554)
		(end 161.322258 -39.44747)
		(width 0.1143)
		(layer "In9.Cu")
		(net "UPI_CPU1_CPU0_P1P1_DN<14>")
	)
	(segment
		(start 222.396812 -36.37026)
		(end 222.323152 -36.375848)
		(width 0.1143)
		(layer "In9.Cu")
		(net "UPI_CPU1_CPU0_P1P1_DN<14>")
	)
	(segment
		(start 295.60012 -41.141142)
		(end 294.54856 -39.56431)
		(width 0.1143)
		(layer "In9.Cu")
		(net "UPI_CPU1_CPU0_P1P1_DN<14>")
	)
	(segment
		(start 161.322258 -39.44747)
		(end 159.8803 -39.679626)
		(width 0.1143)
		(layer "In9.Cu")
		(net "UPI_CPU1_CPU0_P1P1_DN<14>")
	)
	(segment
		(start 159.8803 -39.679626)
		(end 159.678116 -39.716202)
		(width 0.1143)
		(layer "In9.Cu")
		(net "UPI_CPU1_CPU0_P1P1_DN<14>")
	)
	(segment
		(start 148.888196 -40.811958)
		(end 147.786344 -41.031922)
		(width 0.1143)
		(layer "In9.Cu")
		(net "UPI_CPU1_CPU0_P1P1_DN<14>")
	)
	(segment
		(start 212.028786 -37.167312)
		(end 199.029066 -33.915604)
		(width 0.1143)
		(layer "In9.Cu")
		(net "UPI_CPU1_CPU0_P1P1_DN<14>")
	)
	(segment
		(start 129.286508 -49.300638)
		(end 129.286508 -52.070762)
		(width 0.1143)
		(layer "In9.Cu")
		(net "UPI_CPU1_CPU0_P1P1_DN<14>")
	)
	(segment
		(start 300.117256 -51.846988)
		(end 300.08449 -51.846988)
		(width 0.0889)
		(layer "In9.Cu")
		(net "UPI_CPU1_CPU0_P1P1_DN<14>")
	)
	(segment
		(start 148.891244 -40.81145)
		(end 148.888196 -40.811958)
		(width 0.1143)
		(layer "In9.Cu")
		(net "UPI_CPU1_CPU0_P1P1_DN<14>")
	)
	(arc
		(start 301.465996 -53.627782)
		(mid 301.412497 -53.427884)
		(end 301.465996 -53.227986)
		(width 0.0889)
		(layer "In9.Cu")
		(net "UPI_CPU1_CPU0_P1P1_DN<14>")
	)
	(arc
		(start 300.607476 -55.704486)
		(mid 300.749159 -55.560682)
		(end 300.94301 -55.504334)
		(width 0.0889)
		(layer "In9.Cu")
		(net "UPI_CPU1_CPU0_P1P1_DN<14>")
	)
	(arc
		(start 300.204124 -58.489596)
		(mid 300.236124 -58.687574)
		(end 300.058328 -58.780172)
		(width 0.0889)
		(layer "In9.Cu")
		(net "UPI_CPU1_CPU0_P1P1_DN<14>")
	)
	(arc
		(start 300.037754 -58.777124)
		(mid 299.909944 -58.735632)
		(end 299.803058 -58.654188)
		(width 0.0889)
		(layer "In9.Cu")
		(net "UPI_CPU1_CPU0_P1P1_DN<14>")
	)
	(arc
		(start 299.803058 -58.654188)
		(mid 299.698028 -58.426522)
		(end 299.748956 -58.180986)
		(width 0.0889)
		(layer "In9.Cu")
		(net "UPI_CPU1_CPU0_P1P1_DN<14>")
	)
	(arc
		(start 129.353564 -54.432962)
		(mid 129.314475 -54.629946)
		(end 129.202942 -54.796944)
		(width 0.0889)
		(layer "In9.Cu")
		(net "UPI_CPU1_CPU0_P1P1_DN<14>")
	)
	(arc
		(start 300.113446 -55.999888)
		(mid 300.39887 -55.916421)
		(end 300.607476 -55.704486)
		(width 0.0889)
		(layer "In9.Cu")
		(net "UPI_CPU1_CPU0_P1P1_DN<14>")
	)
	(arc
		(start 299.748956 -51.646836)
		(mid 299.540348 -51.434904)
		(end 299.254926 -51.351434)
		(width 0.0889)
		(layer "In9.Cu")
		(net "UPI_CPU1_CPU0_P1P1_DN<14>")
	)
	(arc
		(start 301.46117 -54.61)
		(mid 301.412415 -54.413648)
		(end 301.465996 -54.218586)
		(width 0.0889)
		(layer "In9.Cu")
		(net "UPI_CPU1_CPU0_P1P1_DN<14>")
	)
	(arc
		(start 301.465996 -54.218586)
		(mid 301.545127 -53.923184)
		(end 301.465996 -53.627782)
		(width 0.0889)
		(layer "In9.Cu")
		(net "UPI_CPU1_CPU0_P1P1_DN<14>")
	)
	(arc
		(start 299.22216 -51.351434)
		(mid 299.030518 -51.294268)
		(end 298.890436 -51.151536)
		(width 0.0889)
		(layer "In9.Cu")
		(net "UPI_CPU1_CPU0_P1P1_DN<14>")
	)
	(arc
		(start 300.607476 -52.142136)
		(mid 300.400472 -51.931272)
		(end 300.117256 -51.846988)
		(width 0.0889)
		(layer "In9.Cu")
		(net "UPI_CPU1_CPU0_P1P1_DN<14>")
	)
	(arc
		(start 301.472346 -53.217318)
		(mid 301.466169 -52.637386)
		(end 300.96714 -52.342034)
		(width 0.0889)
		(layer "In9.Cu")
		(net "UPI_CPU1_CPU0_P1P1_DN<14>")
	)
	(arc
		(start 300.975776 -55.504334)
		(mid 301.468166 -55.205401)
		(end 301.472346 -54.629304)
		(width 0.0889)
		(layer "In9.Cu")
		(net "UPI_CPU1_CPU0_P1P1_DN<14>")
	)
	(arc
		(start 299.748956 -57.190386)
		(mid 299.828178 -56.901268)
		(end 299.755306 -56.610504)
		(width 0.0889)
		(layer "In9.Cu")
		(net "UPI_CPU1_CPU0_P1P1_DN<14>")
	)
	(arc
		(start 300.9392 -52.342034)
		(mid 300.747558 -52.284868)
		(end 300.607476 -52.142136)
		(width 0.0889)
		(layer "In9.Cu")
		(net "UPI_CPU1_CPU0_P1P1_DN<14>")
	)
	(arc
		(start 300.08449 -51.846988)
		(mid 299.89064 -51.790638)
		(end 299.748956 -51.646836)
		(width 0.0889)
		(layer "In9.Cu")
		(net "UPI_CPU1_CPU0_P1P1_DN<14>")
	)
	(arc
		(start 129.432558 -54.123336)
		(mid 129.371753 -54.27271)
		(end 129.353564 -54.432962)
		(width 0.0889)
		(layer "In9.Cu")
		(net "UPI_CPU1_CPU0_P1P1_DN<14>")
	)
	(arc
		(start 299.74413 -56.5912)
		(mid 299.747877 -56.201944)
		(end 300.08068 -55.999888)
		(width 0.0889)
		(layer "In9.Cu")
		(net "UPI_CPU1_CPU0_P1P1_DN<14>")
	)
	(arc
		(start 129.437384 -53.731922)
		(mid 129.486139 -53.928274)
		(end 129.432558 -54.123336)
		(width 0.0889)
		(layer "In9.Cu")
		(net "UPI_CPU1_CPU0_P1P1_DN<14>")
	)
	(arc
		(start 299.74413 -57.5818)
		(mid 299.695375 -57.385448)
		(end 299.748956 -57.190386)
		(width 0.0889)
		(layer "In9.Cu")
		(net "UPI_CPU1_CPU0_P1P1_DN<14>")
	)
	(arc
		(start 299.748956 -58.180986)
		(mid 299.828178 -57.891868)
		(end 299.755306 -57.601104)
		(width 0.0889)
		(layer "In9.Cu")
		(net "UPI_CPU1_CPU0_P1P1_DN<14>")
	)
	(segment
		(start 297.807126 -59.371484)
		(end 298.378626 -59.371484)
		(width 0.1143)
		(layer "F.Cu")
		(net "UPI_CPU1_CPU0_P1P1_DN<13>")
	)
	(segment
		(start 130.231388 -53.923184)
		(end 130.802888 -53.923184)
		(width 0.1143)
		(layer "F.Cu")
		(net "UPI_CPU1_CPU0_P1P1_DN<13>")
	)
	(via
		(at 130.802888 -53.923184)
		(size 0.508)
		(drill 0.254)
		(layers "F.Cu" "B.Cu")
		(net "UPI_CPU1_CPU0_P1P1_DN<13>")
	)
	(via
		(at 298.378626 -59.371484)
		(size 0.508)
		(drill 0.254)
		(layers "F.Cu" "B.Cu")
		(net "UPI_CPU1_CPU0_P1P1_DN<13>")
	)
	(segment
		(start 139.81303 -42.475404)
		(end 139.728702 -42.673778)
		(width 0.1143)
		(layer "In9.Cu")
		(net "UPI_CPU1_CPU0_P1P1_DN<13>")
	)
	(segment
		(start 161.722562 -40.503602)
		(end 159.815784 -40.774112)
		(width 0.1143)
		(layer "In9.Cu")
		(net "UPI_CPU1_CPU0_P1P1_DN<13>")
	)
	(segment
		(start 137.890758 -43.413934)
		(end 137.572242 -43.54195)
		(width 0.1143)
		(layer "In9.Cu")
		(net "UPI_CPU1_CPU0_P1P1_DN<13>")
	)
	(segment
		(start 130.456178 -53.723286)
		(end 130.451352 -53.731922)
		(width 0.0889)
		(layer "In9.Cu")
		(net "UPI_CPU1_CPU0_P1P1_DN<13>")
	)
	(segment
		(start 136.65327 -43.912028)
		(end 136.45515 -43.827446)
		(width 0.1143)
		(layer "In9.Cu")
		(net "UPI_CPU1_CPU0_P1P1_DN<13>")
	)
	(segment
		(start 255.206754 -37.086286)
		(end 250.301252 -35.054032)
		(width 0.1143)
		(layer "In9.Cu")
		(net "UPI_CPU1_CPU0_P1P1_DN<13>")
	)
	(segment
		(start 298.396152 -52.037488)
		(end 298.360084 -52.037488)
		(width 0.0889)
		(layer "In9.Cu")
		(net "UPI_CPU1_CPU0_P1P1_DN<13>")
	)
	(segment
		(start 136.45515 -43.827446)
		(end 136.137142 -43.955462)
		(width 0.1143)
		(layer "In9.Cu")
		(net "UPI_CPU1_CPU0_P1P1_DN<13>")
	)
	(segment
		(start 298.725336 -56.599836)
		(end 298.730162 -56.5912)
		(width 0.0889)
		(layer "In9.Cu")
		(net "UPI_CPU1_CPU0_P1P1_DN<13>")
	)
	(segment
		(start 199.063356 -34.902648)
		(end 195.110354 -36.009072)
		(width 0.1143)
		(layer "In9.Cu")
		(net "UPI_CPU1_CPU0_P1P1_DN<13>")
	)
	(segment
		(start 140.131546 -42.347642)
		(end 139.81303 -42.475404)
		(width 0.1143)
		(layer "In9.Cu")
		(net "UPI_CPU1_CPU0_P1P1_DN<13>")
	)
	(segment
		(start 142.348458 -41.880282)
		(end 142.191994 -42.028618)
		(width 0.1143)
		(layer "In9.Cu")
		(net "UPI_CPU1_CPU0_P1P1_DN<13>")
	)
	(segment
		(start 142.83944 -42.046144)
		(end 142.691104 -41.889426)
		(width 0.1143)
		(layer "In9.Cu")
		(net "UPI_CPU1_CPU0_P1P1_DN<13>")
	)
	(segment
		(start 261.73938 -38.81374)
		(end 258.5593 -38.387274)
		(width 0.1143)
		(layer "In9.Cu")
		(net "UPI_CPU1_CPU0_P1P1_DN<13>")
	)
	(segment
		(start 137.975086 -43.215306)
		(end 137.890758 -43.413934)
		(width 0.1143)
		(layer "In9.Cu")
		(net "UPI_CPU1_CPU0_P1P1_DN<13>")
	)
	(segment
		(start 130.92049 -54.040532)
		(end 130.802888 -53.923184)
		(width 0.0889)
		(layer "In9.Cu")
		(net "UPI_CPU1_CPU0_P1P1_DN<13>")
	)
	(segment
		(start 179.44719 -36.583112)
		(end 179.44719 -36.58362)
		(width 0.1143)
		(layer "In9.Cu")
		(net "UPI_CPU1_CPU0_P1P1_DN<13>")
	)
	(segment
		(start 143.338804 -41.906952)
		(end 143.18234 -42.055288)
		(width 0.1143)
		(layer "In9.Cu")
		(net "UPI_CPU1_CPU0_P1P1_DN<13>")
	)
	(segment
		(start 130.567684 -51.814984)
		(end 130.567684 -51.837082)
		(width 0.0889)
		(layer "In9.Cu")
		(net "UPI_CPU1_CPU0_P1P1_DN<13>")
	)
	(segment
		(start 180.20792 -36.241228)
		(end 180.174138 -36.251388)
		(width 0.1143)
		(layer "In9.Cu")
		(net "UPI_CPU1_CPU0_P1P1_DN<13>")
	)
	(segment
		(start 242.340892 -36.895024)
		(end 236.768132 -36.271454)
		(width 0.1143)
		(layer "In9.Cu")
		(net "UPI_CPU1_CPU0_P1P1_DN<13>")
	)
	(segment
		(start 141.358112 -41.853612)
		(end 140.73251 -42.105326)
		(width 0.1143)
		(layer "In9.Cu")
		(net "UPI_CPU1_CPU0_P1P1_DN<13>")
	)
	(segment
		(start 130.534918 -51.869848)
		(end 130.534918 -52.447698)
		(width 0.0889)
		(layer "In9.Cu")
		(net "UPI_CPU1_CPU0_P1P1_DN<13>")
	)
	(segment
		(start 250.301252 -35.054032)
		(end 246.152416 -35.054032)
		(width 0.1143)
		(layer "In9.Cu")
		(net "UPI_CPU1_CPU0_P1P1_DN<13>")
	)
	(segment
		(start 142.691104 -41.889426)
		(end 142.348458 -41.880282)
		(width 0.1143)
		(layer "In9.Cu")
		(net "UPI_CPU1_CPU0_P1P1_DN<13>")
	)
	(segment
		(start 138.80973 -43.043856)
		(end 138.491214 -43.171872)
		(width 0.1143)
		(layer "In9.Cu")
		(net "UPI_CPU1_CPU0_P1P1_DN<13>")
	)
	(segment
		(start 298.718986 -57.601104)
		(end 298.725336 -57.590436)
		(width 0.0889)
		(layer "In9.Cu")
		(net "UPI_CPU1_CPU0_P1P1_DN<13>")
	)
	(segment
		(start 168.988486 -40.3987)
		(end 161.722562 -40.503602)
		(width 0.1143)
		(layer "In9.Cu")
		(net "UPI_CPU1_CPU0_P1P1_DN<13>")
	)
	(segment
		(start 290.940744 -44.460922)
		(end 264.442956 -37.907976)
		(width 0.1143)
		(layer "In9.Cu")
		(net "UPI_CPU1_CPU0_P1P1_DN<13>")
	)
	(segment
		(start 137.056114 -43.585384)
		(end 136.971786 -43.784012)
		(width 0.1143)
		(layer "In9.Cu")
		(net "UPI_CPU1_CPU0_P1P1_DN<13>")
	)
	(segment
		(start 172.8216 -40.2082)
		(end 171.3992 -40.4368)
		(width 0.1143)
		(layer "In9.Cu")
		(net "UPI_CPU1_CPU0_P1P1_DN<13>")
	)
	(segment
		(start 299.588682 -54.722522)
		(end 299.583856 -54.713886)
		(width 0.0889)
		(layer "In9.Cu")
		(net "UPI_CPU1_CPU0_P1P1_DN<13>")
	)
	(segment
		(start 300.082712 -53.827934)
		(end 300.106842 -53.827934)
		(width 0.0889)
		(layer "In9.Cu")
		(net "UPI_CPU1_CPU0_P1P1_DN<13>")
	)
	(segment
		(start 300.1137 -53.028088)
		(end 300.074076 -53.028088)
		(width 0.0889)
		(layer "In9.Cu")
		(net "UPI_CPU1_CPU0_P1P1_DN<13>")
	)
	(segment
		(start 246.152416 -35.054032)
		(end 242.340892 -36.895024)
		(width 0.1143)
		(layer "In9.Cu")
		(net "UPI_CPU1_CPU0_P1P1_DN<13>")
	)
	(segment
		(start 222.396812 -37.362892)
		(end 211.986876 -38.15334)
		(width 0.1143)
		(layer "In9.Cu")
		(net "UPI_CPU1_CPU0_P1P1_DN<13>")
	)
	(segment
		(start 170.3324 -40.3987)
		(end 168.988486 -40.3987)
		(width 0.1143)
		(layer "In9.Cu")
		(net "UPI_CPU1_CPU0_P1P1_DN<13>")
	)
	(segment
		(start 138.491214 -43.171872)
		(end 138.293094 -43.08729)
		(width 0.1143)
		(layer "In9.Cu")
		(net "UPI_CPU1_CPU0_P1P1_DN<13>")
	)
	(segment
		(start 298.725336 -57.590436)
		(end 298.730162 -57.5818)
		(width 0.0889)
		(layer "In9.Cu")
		(net "UPI_CPU1_CPU0_P1P1_DN<13>")
	)
	(segment
		(start 187.771532 -34.814764)
		(end 180.20792 -36.241228)
		(width 0.1143)
		(layer "In9.Cu")
		(net "UPI_CPU1_CPU0_P1P1_DN<13>")
	)
	(segment
		(start 236.768132 -36.271454)
		(end 222.396812 -37.362892)
		(width 0.1143)
		(layer "In9.Cu")
		(net "UPI_CPU1_CPU0_P1P1_DN<13>")
	)
	(segment
		(start 141.700758 -41.862756)
		(end 141.358112 -41.853612)
		(width 0.1143)
		(layer "In9.Cu")
		(net "UPI_CPU1_CPU0_P1P1_DN<13>")
	)
	(segment
		(start 192.380616 -34.99866)
		(end 187.771532 -34.814764)
		(width 0.1143)
		(layer "In9.Cu")
		(net "UPI_CPU1_CPU0_P1P1_DN<13>")
	)
	(segment
		(start 141.849094 -42.019474)
		(end 141.700758 -41.862756)
		(width 0.1143)
		(layer "In9.Cu")
		(net "UPI_CPU1_CPU0_P1P1_DN<13>")
	)
	(segment
		(start 155.745688 -40.409622)
		(end 148.10867 -42.035222)
		(width 0.1143)
		(layer "In9.Cu")
		(net "UPI_CPU1_CPU0_P1P1_DN<13>")
	)
	(segment
		(start 130.567684 -51.837082)
		(end 130.534918 -51.869848)
		(width 0.0889)
		(layer "In9.Cu")
		(net "UPI_CPU1_CPU0_P1P1_DN<13>")
	)
	(segment
		(start 297.725846 -51.133502)
		(end 297.725846 -51.111404)
		(width 0.0889)
		(layer "In9.Cu")
		(net "UPI_CPU1_CPU0_P1P1_DN<13>")
	)
	(segment
		(start 130.744976 -54.31917)
		(end 130.77825 -54.323996)
		(width 0.0889)
		(layer "In9.Cu")
		(net "UPI_CPU1_CPU0_P1P1_DN<13>")
	)
	(segment
		(start 137.374122 -43.457368)
		(end 137.056114 -43.585384)
		(width 0.1143)
		(layer "In9.Cu")
		(net "UPI_CPU1_CPU0_P1P1_DN<13>")
	)
	(segment
		(start 136.971786 -43.784012)
		(end 136.65327 -43.912028)
		(width 0.1143)
		(layer "In9.Cu")
		(net "UPI_CPU1_CPU0_P1P1_DN<13>")
	)
	(segment
		(start 211.986876 -38.15334)
		(end 199.063356 -34.902648)
		(width 0.1143)
		(layer "In9.Cu")
		(net "UPI_CPU1_CPU0_P1P1_DN<13>")
	)
	(segment
		(start 297.725846 -49.745646)
		(end 295.384728 -46.805342)
		(width 0.1143)
		(layer "In9.Cu")
		(net "UPI_CPU1_CPU0_P1P1_DN<13>")
	)
	(segment
		(start 130.456178 -53.132736)
		(end 130.462528 -53.143404)
		(width 0.0889)
		(layer "In9.Cu")
		(net "UPI_CPU1_CPU0_P1P1_DN<13>")
	)
	(segment
		(start 195.110354 -36.009072)
		(end 192.380616 -34.99866)
		(width 0.1143)
		(layer "In9.Cu")
		(net "UPI_CPU1_CPU0_P1P1_DN<13>")
	)
	(segment
		(start 136.137142 -43.955462)
		(end 130.567684 -49.52492)
		(width 0.1143)
		(layer "In9.Cu")
		(net "UPI_CPU1_CPU0_P1P1_DN<13>")
	)
	(segment
		(start 159.815784 -40.774112)
		(end 155.745688 -40.409622)
		(width 0.1143)
		(layer "In9.Cu")
		(net "UPI_CPU1_CPU0_P1P1_DN<13>")
	)
	(segment
		(start 297.871896 -51.82616)
		(end 297.776646 -51.730656)
		(width 0.0889)
		(layer "In9.Cu")
		(net "UPI_CPU1_CPU0_P1P1_DN<13>")
	)
	(segment
		(start 298.725336 -58.581036)
		(end 298.730162 -58.5724)
		(width 0.0889)
		(layer "In9.Cu")
		(net "UPI_CPU1_CPU0_P1P1_DN<13>")
	)
	(segment
		(start 139.41044 -42.801794)
		(end 139.21232 -42.717466)
		(width 0.1143)
		(layer "In9.Cu")
		(net "UPI_CPU1_CPU0_P1P1_DN<13>")
	)
	(segment
		(start 140.329666 -42.431716)
		(end 140.131546 -42.347642)
		(width 0.1143)
		(layer "In9.Cu")
		(net "UPI_CPU1_CPU0_P1P1_DN<13>")
	)
	(segment
		(start 138.8872 -42.860976)
		(end 138.80973 -43.043856)
		(width 0.1143)
		(layer "In9.Cu")
		(net "UPI_CPU1_CPU0_P1P1_DN<13>")
	)
	(segment
		(start 130.456178 -52.732686)
		(end 130.456178 -52.73294)
		(width 0.0889)
		(layer "In9.Cu")
		(net "UPI_CPU1_CPU0_P1P1_DN<13>")
	)
	(segment
		(start 143.18234 -42.055288)
		(end 142.83944 -42.046144)
		(width 0.1143)
		(layer "In9.Cu")
		(net "UPI_CPU1_CPU0_P1P1_DN<13>")
	)
	(segment
		(start 180.174138 -36.251388)
		(end 179.44719 -36.583112)
		(width 0.1143)
		(layer "In9.Cu")
		(net "UPI_CPU1_CPU0_P1P1_DN<13>")
	)
	(segment
		(start 137.572242 -43.54195)
		(end 137.374122 -43.457368)
		(width 0.1143)
		(layer "In9.Cu")
		(net "UPI_CPU1_CPU0_P1P1_DN<13>")
	)
	(segment
		(start 299.248322 -52.532788)
		(end 299.224192 -52.532788)
		(width 0.0889)
		(layer "In9.Cu")
		(net "UPI_CPU1_CPU0_P1P1_DN<13>")
	)
	(segment
		(start 142.191994 -42.028618)
		(end 141.849094 -42.019474)
		(width 0.1143)
		(layer "In9.Cu")
		(net "UPI_CPU1_CPU0_P1P1_DN<13>")
	)
	(segment
		(start 295.384728 -46.805342)
		(end 291.87521 -44.775374)
		(width 0.1143)
		(layer "In9.Cu")
		(net "UPI_CPU1_CPU0_P1P1_DN<13>")
	)
	(segment
		(start 299.219366 -55.313834)
		(end 299.252132 -55.313834)
		(width 0.0889)
		(layer "In9.Cu")
		(net "UPI_CPU1_CPU0_P1P1_DN<13>")
	)
	(segment
		(start 140.647928 -42.3037)
		(end 140.329666 -42.431716)
		(width 0.1143)
		(layer "In9.Cu")
		(net "UPI_CPU1_CPU0_P1P1_DN<13>")
	)
	(segment
		(start 148.10867 -42.035222)
		(end 143.338804 -41.906952)
		(width 0.1143)
		(layer "In9.Cu")
		(net "UPI_CPU1_CPU0_P1P1_DN<13>")
	)
	(segment
		(start 130.567684 -49.52492)
		(end 130.567684 -51.814984)
		(width 0.1143)
		(layer "In9.Cu")
		(net "UPI_CPU1_CPU0_P1P1_DN<13>")
	)
	(segment
		(start 297.725846 -51.111404)
		(end 297.725846 -49.745646)
		(width 0.1143)
		(layer "In9.Cu")
		(net "UPI_CPU1_CPU0_P1P1_DN<13>")
	)
	(segment
		(start 291.87521 -44.775374)
		(end 290.940744 -44.460922)
		(width 0.1143)
		(layer "In9.Cu")
		(net "UPI_CPU1_CPU0_P1P1_DN<13>")
	)
	(segment
		(start 264.442956 -37.907976)
		(end 261.73938 -38.81374)
		(width 0.1143)
		(layer "In9.Cu")
		(net "UPI_CPU1_CPU0_P1P1_DN<13>")
	)
	(segment
		(start 139.21232 -42.717466)
		(end 138.893804 -42.845482)
		(width 0.1143)
		(layer "In9.Cu")
		(net "UPI_CPU1_CPU0_P1P1_DN<13>")
	)
	(segment
		(start 297.776646 -51.184302)
		(end 297.725846 -51.133502)
		(width 0.0889)
		(layer "In9.Cu")
		(net "UPI_CPU1_CPU0_P1P1_DN<13>")
	)
	(segment
		(start 171.3992 -40.4368)
		(end 170.3324 -40.3987)
		(width 0.1143)
		(layer "In9.Cu")
		(net "UPI_CPU1_CPU0_P1P1_DN<13>")
	)
	(segment
		(start 178.70297 -36.923472)
		(end 172.8216 -40.2082)
		(width 0.1143)
		(layer "In9.Cu")
		(net "UPI_CPU1_CPU0_P1P1_DN<13>")
	)
	(segment
		(start 299.583856 -54.713886)
		(end 299.577506 -54.703218)
		(width 0.0889)
		(layer "In9.Cu")
		(net "UPI_CPU1_CPU0_P1P1_DN<13>")
	)
	(segment
		(start 297.776646 -51.730656)
		(end 297.776646 -51.184302)
		(width 0.0889)
		(layer "In9.Cu")
		(net "UPI_CPU1_CPU0_P1P1_DN<13>")
	)
	(segment
		(start 298.378626 -59.371484)
		(end 298.485814 -59.26455)
		(width 0.0889)
		(layer "In9.Cu")
		(net "UPI_CPU1_CPU0_P1P1_DN<13>")
	)
	(segment
		(start 140.73251 -42.105326)
		(end 140.647928 -42.3037)
		(width 0.1143)
		(layer "In9.Cu")
		(net "UPI_CPU1_CPU0_P1P1_DN<13>")
	)
	(segment
		(start 138.893804 -42.845482)
		(end 138.8872 -42.860976)
		(width 0.1143)
		(layer "In9.Cu")
		(net "UPI_CPU1_CPU0_P1P1_DN<13>")
	)
	(segment
		(start 139.728702 -42.673778)
		(end 139.41044 -42.801794)
		(width 0.1143)
		(layer "In9.Cu")
		(net "UPI_CPU1_CPU0_P1P1_DN<13>")
	)
	(segment
		(start 179.44719 -36.58362)
		(end 178.70297 -36.923472)
		(width 0.1143)
		(layer "In9.Cu")
		(net "UPI_CPU1_CPU0_P1P1_DN<13>")
	)
	(segment
		(start 138.293094 -43.08729)
		(end 137.975086 -43.215306)
		(width 0.1143)
		(layer "In9.Cu")
		(net "UPI_CPU1_CPU0_P1P1_DN<13>")
	)
	(segment
		(start 258.5593 -38.387274)
		(end 255.206754 -37.086286)
		(width 0.1143)
		(layer "In9.Cu")
		(net "UPI_CPU1_CPU0_P1P1_DN<13>")
	)
	(segment
		(start 298.718986 -56.610504)
		(end 298.725336 -56.599836)
		(width 0.0889)
		(layer "In9.Cu")
		(net "UPI_CPU1_CPU0_P1P1_DN<13>")
	)
	(arc
		(start 299.577506 -54.703218)
		(mid 299.583683 -54.123286)
		(end 300.082712 -53.827934)
		(width 0.0889)
		(layer "In9.Cu")
		(net "UPI_CPU1_CPU0_P1P1_DN<13>")
	)
	(arc
		(start 298.646088 -58.8772)
		(mid 298.66618 -58.723892)
		(end 298.725336 -58.581036)
		(width 0.0889)
		(layer "In9.Cu")
		(net "UPI_CPU1_CPU0_P1P1_DN<13>")
	)
	(arc
		(start 130.456178 -52.73294)
		(mid 130.402679 -52.932838)
		(end 130.456178 -53.132736)
		(width 0.0889)
		(layer "In9.Cu")
		(net "UPI_CPU1_CPU0_P1P1_DN<13>")
	)
	(arc
		(start 300.074076 -53.028088)
		(mid 299.790859 -52.943807)
		(end 299.583856 -52.73294)
		(width 0.0889)
		(layer "In9.Cu")
		(net "UPI_CPU1_CPU0_P1P1_DN<13>")
	)
	(arc
		(start 298.485814 -59.26455)
		(mid 298.604478 -59.086817)
		(end 298.646088 -58.8772)
		(width 0.0889)
		(layer "In9.Cu")
		(net "UPI_CPU1_CPU0_P1P1_DN<13>")
	)
	(arc
		(start 300.106842 -53.827934)
		(mid 300.496104 -53.431315)
		(end 300.1137 -53.028088)
		(width 0.0889)
		(layer "In9.Cu")
		(net "UPI_CPU1_CPU0_P1P1_DN<13>")
	)
	(arc
		(start 299.583856 -52.73294)
		(mid 299.442173 -52.589136)
		(end 299.248322 -52.532788)
		(width 0.0889)
		(layer "In9.Cu")
		(net "UPI_CPU1_CPU0_P1P1_DN<13>")
	)
	(arc
		(start 299.252132 -55.313834)
		(mid 299.58505 -55.111843)
		(end 299.588682 -54.722522)
		(width 0.0889)
		(layer "In9.Cu")
		(net "UPI_CPU1_CPU0_P1P1_DN<13>")
	)
	(arc
		(start 298.725336 -57.190386)
		(mid 298.646114 -56.901268)
		(end 298.718986 -56.610504)
		(width 0.0889)
		(layer "In9.Cu")
		(net "UPI_CPU1_CPU0_P1P1_DN<13>")
	)
	(arc
		(start 130.462528 -53.143404)
		(mid 130.535326 -53.434167)
		(end 130.456178 -53.723286)
		(width 0.0889)
		(layer "In9.Cu")
		(net "UPI_CPU1_CPU0_P1P1_DN<13>")
	)
	(arc
		(start 130.534918 -52.447698)
		(mid 130.513643 -52.595188)
		(end 130.456178 -52.732686)
		(width 0.0889)
		(layer "In9.Cu")
		(net "UPI_CPU1_CPU0_P1P1_DN<13>")
	)
	(arc
		(start 298.730162 -57.5818)
		(mid 298.778917 -57.385448)
		(end 298.725336 -57.190386)
		(width 0.0889)
		(layer "In9.Cu")
		(net "UPI_CPU1_CPU0_P1P1_DN<13>")
	)
	(arc
		(start 298.725336 -52.237386)
		(mid 298.586343 -52.095306)
		(end 298.396152 -52.037488)
		(width 0.0889)
		(layer "In9.Cu")
		(net "UPI_CPU1_CPU0_P1P1_DN<13>")
	)
	(arc
		(start 298.730162 -58.5724)
		(mid 298.778917 -58.376048)
		(end 298.725336 -58.180986)
		(width 0.0889)
		(layer "In9.Cu")
		(net "UPI_CPU1_CPU0_P1P1_DN<13>")
	)
	(arc
		(start 130.451352 -53.731922)
		(mid 130.402566 -53.928274)
		(end 130.456178 -54.123336)
		(width 0.0889)
		(layer "In9.Cu")
		(net "UPI_CPU1_CPU0_P1P1_DN<13>")
	)
	(arc
		(start 130.456178 -54.123336)
		(mid 130.578115 -54.254369)
		(end 130.744976 -54.31917)
		(width 0.0889)
		(layer "In9.Cu")
		(net "UPI_CPU1_CPU0_P1P1_DN<13>")
	)
	(arc
		(start 299.224192 -52.532788)
		(mid 298.936047 -52.450469)
		(end 298.725336 -52.237386)
		(width 0.0889)
		(layer "In9.Cu")
		(net "UPI_CPU1_CPU0_P1P1_DN<13>")
	)
	(arc
		(start 298.725336 -56.199786)
		(mid 298.721007 -55.616614)
		(end 299.219366 -55.313834)
		(width 0.0889)
		(layer "In9.Cu")
		(net "UPI_CPU1_CPU0_P1P1_DN<13>")
	)
	(arc
		(start 298.725336 -58.180986)
		(mid 298.646114 -57.891868)
		(end 298.718986 -57.601104)
		(width 0.0889)
		(layer "In9.Cu")
		(net "UPI_CPU1_CPU0_P1P1_DN<13>")
	)
	(arc
		(start 298.360084 -52.037488)
		(mid 298.095882 -51.978284)
		(end 297.871896 -51.82616)
		(width 0.0889)
		(layer "In9.Cu")
		(net "UPI_CPU1_CPU0_P1P1_DN<13>")
	)
	(arc
		(start 130.77825 -54.323996)
		(mid 130.951731 -54.233599)
		(end 130.92049 -54.040532)
		(width 0.0889)
		(layer "In9.Cu")
		(net "UPI_CPU1_CPU0_P1P1_DN<13>")
	)
	(arc
		(start 298.730162 -56.5912)
		(mid 298.778917 -56.394848)
		(end 298.725336 -56.199786)
		(width 0.0889)
		(layer "In9.Cu")
		(net "UPI_CPU1_CPU0_P1P1_DN<13>")
	)
	(segment
		(start 130.231388 -52.932838)
		(end 130.802888 -52.932838)
		(width 0.1143)
		(layer "F.Cu")
		(net "UPI_CPU1_CPU0_P1P1_DN<12>")
	)
	(segment
		(start 297.807126 -56.399938)
		(end 298.378626 -56.399938)
		(width 0.1143)
		(layer "F.Cu")
		(net "UPI_CPU1_CPU0_P1P1_DN<12>")
	)
	(via
		(at 298.378626 -56.399938)
		(size 0.508)
		(drill 0.254)
		(layers "F.Cu" "B.Cu")
		(net "UPI_CPU1_CPU0_P1P1_DN<12>")
	)
	(via
		(at 130.802888 -52.932838)
		(size 0.508)
		(drill 0.254)
		(layers "F.Cu" "B.Cu")
		(net "UPI_CPU1_CPU0_P1P1_DN<12>")
	)
	(segment
		(start 298.038266 -55.619904)
		(end 298.031916 -55.609236)
		(width 0.0889)
		(layer "In9.Cu")
		(net "UPI_CPU1_CPU0_P1P1_DN<12>")
	)
	(segment
		(start 168.995344 -40.8559)
		(end 168.46931 -40.86352)
		(width 0.1143)
		(layer "In9.Cu")
		(net "UPI_CPU1_CPU0_P1P1_DN<12>")
	)
	(segment
		(start 298.378626 -56.399938)
		(end 298.431204 -56.44896)
		(width 0.0889)
		(layer "In9.Cu")
		(net "UPI_CPU1_CPU0_P1P1_DN<12>")
	)
	(segment
		(start 242.442492 -37.34054)
		(end 236.703362 -36.66871)
		(width 0.1143)
		(layer "In9.Cu")
		(net "UPI_CPU1_CPU0_P1P1_DN<12>")
	)
	(segment
		(start 131.036822 -52.02682)
		(end 131.036822 -52.25923)
		(width 0.0889)
		(layer "In9.Cu")
		(net "UPI_CPU1_CPU0_P1P1_DN<12>")
	)
	(segment
		(start 131.140454 -51.046126)
		(end 131.191254 -51.096926)
		(width 0.0889)
		(layer "In9.Cu")
		(net "UPI_CPU1_CPU0_P1P1_DN<12>")
	)
	(segment
		(start 161.86912 -40.86352)
		(end 159.85363 -41.216072)
		(width 0.1143)
		(layer "In9.Cu")
		(net "UPI_CPU1_CPU0_P1P1_DN<12>")
	)
	(segment
		(start 291.742876 -45.173646)
		(end 290.415726 -44.720764)
		(width 0.1143)
		(layer "In9.Cu")
		(net "UPI_CPU1_CPU0_P1P1_DN<12>")
	)
	(segment
		(start 294.683942 -47.057818)
		(end 294.54602 -46.919896)
		(width 0.1143)
		(layer "In9.Cu")
		(net "UPI_CPU1_CPU0_P1P1_DN<12>")
	)
	(segment
		(start 131.175252 -53.080412)
		(end 131.096004 -53.101748)
		(width 0.0889)
		(layer "In9.Cu")
		(net "UPI_CPU1_CPU0_P1P1_DN<12>")
	)
	(segment
		(start 131.174744 -53.080412)
		(end 131.175252 -53.080412)
		(width 0.0889)
		(layer "In9.Cu")
		(net "UPI_CPU1_CPU0_P1P1_DN<12>")
	)
	(segment
		(start 195.092828 -36.42868)
		(end 192.289684 -35.348164)
		(width 0.1143)
		(layer "In9.Cu")
		(net "UPI_CPU1_CPU0_P1P1_DN<12>")
	)
	(segment
		(start 170.881294 -40.8559)
		(end 168.995344 -40.8559)
		(width 0.1143)
		(layer "In9.Cu")
		(net "UPI_CPU1_CPU0_P1P1_DN<12>")
	)
	(segment
		(start 290.415726 -44.720764)
		(end 264.421366 -38.301676)
		(width 0.1143)
		(layer "In9.Cu")
		(net "UPI_CPU1_CPU0_P1P1_DN<12>")
	)
	(segment
		(start 298.36364 -55.009288)
		(end 298.396406 -55.009288)
		(width 0.0889)
		(layer "In9.Cu")
		(net "UPI_CPU1_CPU0_P1P1_DN<12>")
	)
	(segment
		(start 298.396406 -52.837334)
		(end 298.360592 -52.837334)
		(width 0.0889)
		(layer "In9.Cu")
		(net "UPI_CPU1_CPU0_P1P1_DN<12>")
	)
	(segment
		(start 131.096004 -53.101748)
		(end 130.802888 -52.932838)
		(width 0.0889)
		(layer "In9.Cu")
		(net "UPI_CPU1_CPU0_P1P1_DN<12>")
	)
	(segment
		(start 131.191254 -51.281584)
		(end 131.036822 -52.02682)
		(width 0.0889)
		(layer "In9.Cu")
		(net "UPI_CPU1_CPU0_P1P1_DN<12>")
	)
	(segment
		(start 172.744892 -40.700452)
		(end 170.881294 -40.8559)
		(width 0.1143)
		(layer "In9.Cu")
		(net "UPI_CPU1_CPU0_P1P1_DN<12>")
	)
	(segment
		(start 294.54602 -46.919896)
		(end 291.742876 -45.173646)
		(width 0.1143)
		(layer "In9.Cu")
		(net "UPI_CPU1_CPU0_P1P1_DN<12>")
	)
	(segment
		(start 250.119134 -35.40633)
		(end 246.228108 -35.40633)
		(width 0.1143)
		(layer "In9.Cu")
		(net "UPI_CPU1_CPU0_P1P1_DN<12>")
	)
	(segment
		(start 131.140454 -51.024028)
		(end 131.140454 -51.046126)
		(width 0.0889)
		(layer "In9.Cu")
		(net "UPI_CPU1_CPU0_P1P1_DN<12>")
	)
	(segment
		(start 261.786624 -39.191438)
		(end 258.419346 -38.72484)
		(width 0.1143)
		(layer "In9.Cu")
		(net "UPI_CPU1_CPU0_P1P1_DN<12>")
	)
	(segment
		(start 258.419346 -38.72484)
		(end 254.721106 -37.312346)
		(width 0.1143)
		(layer "In9.Cu")
		(net "UPI_CPU1_CPU0_P1P1_DN<12>")
	)
	(segment
		(start 141.71295 -42.463212)
		(end 136.08304 -44.625514)
		(width 0.1143)
		(layer "In9.Cu")
		(net "UPI_CPU1_CPU0_P1P1_DN<12>")
	)
	(segment
		(start 297.22445 -51.679856)
		(end 297.22445 -50.239422)
		(width 0.1143)
		(layer "In9.Cu")
		(net "UPI_CPU1_CPU0_P1P1_DN<12>")
	)
	(segment
		(start 294.705532 -47.082202)
		(end 294.683942 -47.057818)
		(width 0.1143)
		(layer "In9.Cu")
		(net "UPI_CPU1_CPU0_P1P1_DN<12>")
	)
	(segment
		(start 297.17365 -51.752754)
		(end 297.22445 -51.701954)
		(width 0.0889)
		(layer "In9.Cu")
		(net "UPI_CPU1_CPU0_P1P1_DN<12>")
	)
	(segment
		(start 297.22445 -50.239422)
		(end 294.705532 -47.082202)
		(width 0.1143)
		(layer "In9.Cu")
		(net "UPI_CPU1_CPU0_P1P1_DN<12>")
	)
	(segment
		(start 211.844636 -38.525196)
		(end 199.157844 -35.288982)
		(width 0.1143)
		(layer "In9.Cu")
		(net "UPI_CPU1_CPU0_P1P1_DN<12>")
	)
	(segment
		(start 136.08304 -44.625514)
		(end 131.140454 -49.568354)
		(width 0.1143)
		(layer "In9.Cu")
		(net "UPI_CPU1_CPU0_P1P1_DN<12>")
	)
	(segment
		(start 297.541696 -52.342288)
		(end 297.507914 -52.342288)
		(width 0.0889)
		(layer "In9.Cu")
		(net "UPI_CPU1_CPU0_P1P1_DN<12>")
	)
	(segment
		(start 236.703362 -36.66871)
		(end 222.396812 -37.737034)
		(width 0.1143)
		(layer "In9.Cu")
		(net "UPI_CPU1_CPU0_P1P1_DN<12>")
	)
	(segment
		(start 131.140454 -49.568354)
		(end 131.140454 -51.024028)
		(width 0.1143)
		(layer "In9.Cu")
		(net "UPI_CPU1_CPU0_P1P1_DN<12>")
	)
	(segment
		(start 222.396812 -37.737034)
		(end 211.844636 -38.525196)
		(width 0.1143)
		(layer "In9.Cu")
		(net "UPI_CPU1_CPU0_P1P1_DN<12>")
	)
	(segment
		(start 168.46931 -40.86352)
		(end 161.86912 -40.86352)
		(width 0.1143)
		(layer "In9.Cu")
		(net "UPI_CPU1_CPU0_P1P1_DN<12>")
	)
	(segment
		(start 298.031916 -55.609236)
		(end 298.02709 -55.6006)
		(width 0.0889)
		(layer "In9.Cu")
		(net "UPI_CPU1_CPU0_P1P1_DN<12>")
	)
	(segment
		(start 254.721106 -37.312346)
		(end 250.119134 -35.40633)
		(width 0.1143)
		(layer "In9.Cu")
		(net "UPI_CPU1_CPU0_P1P1_DN<12>")
	)
	(segment
		(start 155.851098 -40.765222)
		(end 147.793964 -42.523156)
		(width 0.1143)
		(layer "In9.Cu")
		(net "UPI_CPU1_CPU0_P1P1_DN<12>")
	)
	(segment
		(start 199.157844 -35.288982)
		(end 195.092828 -36.42868)
		(width 0.1143)
		(layer "In9.Cu")
		(net "UPI_CPU1_CPU0_P1P1_DN<12>")
	)
	(segment
		(start 297.22445 -51.701954)
		(end 297.22445 -51.679856)
		(width 0.0889)
		(layer "In9.Cu")
		(net "UPI_CPU1_CPU0_P1P1_DN<12>")
	)
	(segment
		(start 179.943252 -36.71316)
		(end 172.744892 -40.700452)
		(width 0.1143)
		(layer "In9.Cu")
		(net "UPI_CPU1_CPU0_P1P1_DN<12>")
	)
	(segment
		(start 131.149598 -52.732686)
		(end 131.149852 -52.73294)
		(width 0.0889)
		(layer "In9.Cu")
		(net "UPI_CPU1_CPU0_P1P1_DN<12>")
	)
	(segment
		(start 131.101084 -52.648358)
		(end 131.149598 -52.732686)
		(width 0.0889)
		(layer "In9.Cu")
		(net "UPI_CPU1_CPU0_P1P1_DN<12>")
	)
	(segment
		(start 298.88561 -53.731922)
		(end 298.890436 -53.723286)
		(width 0.0889)
		(layer "In9.Cu")
		(net "UPI_CPU1_CPU0_P1P1_DN<12>")
	)
	(segment
		(start 187.971176 -35.175698)
		(end 179.943252 -36.71316)
		(width 0.1143)
		(layer "In9.Cu")
		(net "UPI_CPU1_CPU0_P1P1_DN<12>")
	)
	(segment
		(start 147.793964 -42.523156)
		(end 141.71295 -42.463212)
		(width 0.1143)
		(layer "In9.Cu")
		(net "UPI_CPU1_CPU0_P1P1_DN<12>")
	)
	(segment
		(start 131.191254 -51.096926)
		(end 131.191254 -51.281584)
		(width 0.0889)
		(layer "In9.Cu")
		(net "UPI_CPU1_CPU0_P1P1_DN<12>")
	)
	(segment
		(start 297.17365 -52.14239)
		(end 297.17365 -51.752754)
		(width 0.0889)
		(layer "In9.Cu")
		(net "UPI_CPU1_CPU0_P1P1_DN<12>")
	)
	(segment
		(start 246.228108 -35.40633)
		(end 242.442492 -37.34054)
		(width 0.1143)
		(layer "In9.Cu")
		(net "UPI_CPU1_CPU0_P1P1_DN<12>")
	)
	(segment
		(start 264.421366 -38.301676)
		(end 261.786624 -39.191438)
		(width 0.1143)
		(layer "In9.Cu")
		(net "UPI_CPU1_CPU0_P1P1_DN<12>")
	)
	(segment
		(start 192.289684 -35.348164)
		(end 187.971176 -35.175698)
		(width 0.1143)
		(layer "In9.Cu")
		(net "UPI_CPU1_CPU0_P1P1_DN<12>")
	)
	(segment
		(start 298.158154 -56.741568)
		(end 298.106338 -56.693308)
		(width 0.0889)
		(layer "In9.Cu")
		(net "UPI_CPU1_CPU0_P1P1_DN<12>")
	)
	(segment
		(start 159.85363 -41.216072)
		(end 155.851098 -40.765222)
		(width 0.1143)
		(layer "In9.Cu")
		(net "UPI_CPU1_CPU0_P1P1_DN<12>")
	)
	(arc
		(start 298.02709 -55.6006)
		(mid 298.030837 -55.211344)
		(end 298.36364 -55.009288)
		(width 0.0889)
		(layer "In9.Cu")
		(net "UPI_CPU1_CPU0_P1P1_DN<12>")
	)
	(arc
		(start 298.890436 -54.123336)
		(mid 298.836966 -53.928273)
		(end 298.88561 -53.731922)
		(width 0.0889)
		(layer "In9.Cu")
		(net "UPI_CPU1_CPU0_P1P1_DN<12>")
	)
	(arc
		(start 298.431204 -56.44896)
		(mid 298.441047 -56.73173)
		(end 298.158154 -56.741568)
		(width 0.0889)
		(layer "In9.Cu")
		(net "UPI_CPU1_CPU0_P1P1_DN<12>")
	)
	(arc
		(start 298.106338 -56.693308)
		(mid 297.982835 -56.459573)
		(end 298.031916 -56.199786)
		(width 0.0889)
		(layer "In9.Cu")
		(net "UPI_CPU1_CPU0_P1P1_DN<12>")
	)
	(arc
		(start 298.360592 -52.837334)
		(mid 298.170663 -52.779464)
		(end 298.031916 -52.637436)
		(width 0.0889)
		(layer "In9.Cu")
		(net "UPI_CPU1_CPU0_P1P1_DN<12>")
	)
	(arc
		(start 297.507914 -52.342288)
		(mid 297.314811 -52.285769)
		(end 297.17365 -52.14239)
		(width 0.0889)
		(layer "In9.Cu")
		(net "UPI_CPU1_CPU0_P1P1_DN<12>")
	)
	(arc
		(start 298.396406 -55.009288)
		(mid 298.894657 -54.706448)
		(end 298.890436 -54.123336)
		(width 0.0889)
		(layer "In9.Cu")
		(net "UPI_CPU1_CPU0_P1P1_DN<12>")
	)
	(arc
		(start 298.890436 -53.723286)
		(mid 298.894765 -53.140114)
		(end 298.396406 -52.837334)
		(width 0.0889)
		(layer "In9.Cu")
		(net "UPI_CPU1_CPU0_P1P1_DN<12>")
	)
	(arc
		(start 131.149852 -52.73294)
		(mid 131.202047 -52.903819)
		(end 131.174744 -53.080412)
		(width 0.0889)
		(layer "In9.Cu")
		(net "UPI_CPU1_CPU0_P1P1_DN<12>")
	)
	(arc
		(start 298.031916 -56.199786)
		(mid 298.111138 -55.910668)
		(end 298.038266 -55.619904)
		(width 0.0889)
		(layer "In9.Cu")
		(net "UPI_CPU1_CPU0_P1P1_DN<12>")
	)
	(arc
		(start 131.036822 -52.25923)
		(mid 131.040783 -52.381644)
		(end 131.052316 -52.503578)
		(width 0.0889)
		(layer "In9.Cu")
		(net "UPI_CPU1_CPU0_P1P1_DN<12>")
	)
	(arc
		(start 298.031916 -52.637436)
		(mid 297.824912 -52.426572)
		(end 297.541696 -52.342288)
		(width 0.0889)
		(layer "In9.Cu")
		(net "UPI_CPU1_CPU0_P1P1_DN<12>")
	)
	(arc
		(start 131.052316 -52.503578)
		(mid 131.069489 -52.578397)
		(end 131.101084 -52.648358)
		(width 0.0889)
		(layer "In9.Cu")
		(net "UPI_CPU1_CPU0_P1P1_DN<12>")
	)
	(segment
		(start 296.66184 -57.390538)
		(end 296.09034 -57.390538)
		(width 0.1143)
		(layer "F.Cu")
		(net "UPI_CPU1_CPU0_P1P1_DN<11>")
	)
	(segment
		(start 131.948174 -53.923184)
		(end 132.519674 -53.923184)
		(width 0.1143)
		(layer "F.Cu")
		(net "UPI_CPU1_CPU0_P1P1_DN<11>")
	)
	(via
		(at 296.66184 -57.390538)
		(size 0.508)
		(drill 0.254)
		(layers "F.Cu" "B.Cu")
		(net "UPI_CPU1_CPU0_P1P1_DN<11>")
	)
	(via
		(at 132.519674 -53.923184)
		(size 0.508)
		(drill 0.254)
		(layers "F.Cu" "B.Cu")
		(net "UPI_CPU1_CPU0_P1P1_DN<11>")
	)
	(segment
		(start 142.649448 -43.652186)
		(end 142.360396 -43.65244)
		(width 0.1143)
		(layer "In9.Cu")
		(net "UPI_CPU1_CPU0_P1P1_DN<11>")
	)
	(segment
		(start 143.956024 -43.675046)
		(end 143.613124 -43.66895)
		(width 0.1143)
		(layer "In9.Cu")
		(net "UPI_CPU1_CPU0_P1P1_DN<11>")
	)
	(segment
		(start 137.859262 -45.187108)
		(end 137.534904 -45.297598)
		(width 0.1143)
		(layer "In9.Cu")
		(net "UPI_CPU1_CPU0_P1P1_DN<11>")
	)
	(segment
		(start 156.108654 -41.7576)
		(end 155.885134 -41.732454)
		(width 0.1143)
		(layer "In9.Cu")
		(net "UPI_CPU1_CPU0_P1P1_DN<11>")
	)
	(segment
		(start 296.017696 -50.564796)
		(end 293.644574 -47.635922)
		(width 0.1143)
		(layer "In9.Cu")
		(net "UPI_CPU1_CPU0_P1P1_DN<11>")
	)
	(segment
		(start 138.79703 -44.867322)
		(end 138.472672 -44.977812)
		(width 0.1143)
		(layer "In9.Cu")
		(net "UPI_CPU1_CPU0_P1P1_DN<11>")
	)
	(segment
		(start 236.59465 -37.618416)
		(end 222.396812 -38.750748)
		(width 0.1143)
		(layer "In9.Cu")
		(net "UPI_CPU1_CPU0_P1P1_DN<11>")
	)
	(segment
		(start 297.53814 -53.523388)
		(end 297.502326 -53.523388)
		(width 0.0889)
		(layer "In9.Cu")
		(net "UPI_CPU1_CPU0_P1P1_DN<11>")
	)
	(segment
		(start 132.310378 -49.904142)
		(end 132.310378 -51.322224)
		(width 0.1143)
		(layer "In9.Cu")
		(net "UPI_CPU1_CPU0_P1P1_DN<11>")
	)
	(segment
		(start 132.252466 -51.86172)
		(end 132.252466 -51.98872)
		(width 0.0889)
		(layer "In9.Cu")
		(net "UPI_CPU1_CPU0_P1P1_DN<11>")
	)
	(segment
		(start 138.472672 -44.977812)
		(end 138.377676 -45.17136)
		(width 0.1143)
		(layer "In9.Cu")
		(net "UPI_CPU1_CPU0_P1P1_DN<11>")
	)
	(segment
		(start 289.266376 -45.423836)
		(end 288.1376 -45.119036)
		(width 0.1143)
		(layer "In9.Cu")
		(net "UPI_CPU1_CPU0_P1P1_DN<11>")
	)
	(segment
		(start 132.148072 -54.070758)
		(end 132.226812 -54.092094)
		(width 0.0889)
		(layer "In9.Cu")
		(net "UPI_CPU1_CPU0_P1P1_DN<11>")
	)
	(segment
		(start 140.253212 -44.532042)
		(end 139.928346 -44.642532)
		(width 0.1143)
		(layer "In9.Cu")
		(net "UPI_CPU1_CPU0_P1P1_DN<11>")
	)
	(segment
		(start 143.613124 -43.66895)
		(end 143.487394 -43.79087)
		(width 0.1143)
		(layer "In9.Cu")
		(net "UPI_CPU1_CPU0_P1P1_DN<11>")
	)
	(segment
		(start 139.734798 -44.547536)
		(end 139.41044 -44.658026)
		(width 0.1143)
		(layer "In9.Cu")
		(net "UPI_CPU1_CPU0_P1P1_DN<11>")
	)
	(segment
		(start 138.377676 -45.17136)
		(end 138.05281 -45.282104)
		(width 0.1143)
		(layer "In9.Cu")
		(net "UPI_CPU1_CPU0_P1P1_DN<11>")
	)
	(segment
		(start 162.014408 -41.865042)
		(end 159.862774 -42.303192)
		(width 0.1143)
		(layer "In9.Cu")
		(net "UPI_CPU1_CPU0_P1P1_DN<11>")
	)
	(segment
		(start 180.37302 -37.627814)
		(end 173.4058 -41.5798)
		(width 0.1143)
		(layer "In9.Cu")
		(net "UPI_CPU1_CPU0_P1P1_DN<11>")
	)
	(segment
		(start 211.973668 -39.58209)
		(end 199.180196 -36.277042)
		(width 0.1143)
		(layer "In9.Cu")
		(net "UPI_CPU1_CPU0_P1P1_DN<11>")
	)
	(segment
		(start 132.252466 -51.53152)
		(end 132.354066 -51.63312)
		(width 0.0889)
		(layer "In9.Cu")
		(net "UPI_CPU1_CPU0_P1P1_DN<11>")
	)
	(segment
		(start 139.41044 -44.658026)
		(end 139.315444 -44.851574)
		(width 0.1143)
		(layer "In9.Cu")
		(net "UPI_CPU1_CPU0_P1P1_DN<11>")
	)
	(segment
		(start 143.02232 -43.65879)
		(end 142.649448 -43.652186)
		(width 0.1143)
		(layer "In9.Cu")
		(net "UPI_CPU1_CPU0_P1P1_DN<11>")
	)
	(segment
		(start 188.006482 -36.172394)
		(end 180.37302 -37.627814)
		(width 0.1143)
		(layer "In9.Cu")
		(net "UPI_CPU1_CPU0_P1P1_DN<11>")
	)
	(segment
		(start 264.455148 -39.325296)
		(end 261.758176 -40.200072)
		(width 0.1143)
		(layer "In9.Cu")
		(net "UPI_CPU1_CPU0_P1P1_DN<11>")
	)
	(segment
		(start 132.252466 -52.31892)
		(end 132.252466 -52.44592)
		(width 0.0889)
		(layer "In9.Cu")
		(net "UPI_CPU1_CPU0_P1P1_DN<11>")
	)
	(segment
		(start 296.017696 -51.867308)
		(end 296.017696 -51.84521)
		(width 0.0889)
		(layer "In9.Cu")
		(net "UPI_CPU1_CPU0_P1P1_DN<11>")
	)
	(segment
		(start 296.068496 -51.918108)
		(end 296.017696 -51.867308)
		(width 0.0889)
		(layer "In9.Cu")
		(net "UPI_CPU1_CPU0_P1P1_DN<11>")
	)
	(segment
		(start 249.886978 -36.339272)
		(end 246.45239 -36.339272)
		(width 0.1143)
		(layer "In9.Cu")
		(net "UPI_CPU1_CPU0_P1P1_DN<11>")
	)
	(segment
		(start 296.068496 -52.434744)
		(end 296.068496 -51.918108)
		(width 0.0889)
		(layer "In9.Cu")
		(net "UPI_CPU1_CPU0_P1P1_DN<11>")
	)
	(segment
		(start 159.862774 -42.303192)
		(end 156.108654 -41.7576)
		(width 0.1143)
		(layer "In9.Cu")
		(net "UPI_CPU1_CPU0_P1P1_DN<11>")
	)
	(segment
		(start 143.143986 -43.784774)
		(end 143.02232 -43.65879)
		(width 0.1143)
		(layer "In9.Cu")
		(net "UPI_CPU1_CPU0_P1P1_DN<11>")
	)
	(segment
		(start 296.999406 -54.633876)
		(end 297.008296 -54.618636)
		(width 0.0889)
		(layer "In9.Cu")
		(net "UPI_CPU1_CPU0_P1P1_DN<11>")
	)
	(segment
		(start 170.815 -41.9862)
		(end 166.88689 -41.790366)
		(width 0.1143)
		(layer "In9.Cu")
		(net "UPI_CPU1_CPU0_P1P1_DN<11>")
	)
	(segment
		(start 136.921494 -45.506894)
		(end 136.597136 -45.617384)
		(width 0.1143)
		(layer "In9.Cu")
		(net "UPI_CPU1_CPU0_P1P1_DN<11>")
	)
	(segment
		(start 132.354066 -51.76012)
		(end 132.252466 -51.86172)
		(width 0.0889)
		(layer "In9.Cu")
		(net "UPI_CPU1_CPU0_P1P1_DN<11>")
	)
	(segment
		(start 258.21894 -39.705534)
		(end 254.771906 -38.36289)
		(width 0.1143)
		(layer "In9.Cu")
		(net "UPI_CPU1_CPU0_P1P1_DN<11>")
	)
	(segment
		(start 155.885134 -41.732454)
		(end 147.0152 -43.726608)
		(width 0.1143)
		(layer "In9.Cu")
		(net "UPI_CPU1_CPU0_P1P1_DN<11>")
	)
	(segment
		(start 293.644574 -47.635922)
		(end 291.47516 -46.167548)
		(width 0.1143)
		(layer "In9.Cu")
		(net "UPI_CPU1_CPU0_P1P1_DN<11>")
	)
	(segment
		(start 140.672566 -44.22775)
		(end 140.348208 -44.33824)
		(width 0.1143)
		(layer "In9.Cu")
		(net "UPI_CPU1_CPU0_P1P1_DN<11>")
	)
	(segment
		(start 136.597136 -45.617384)
		(end 132.310378 -49.904142)
		(width 0.1143)
		(layer "In9.Cu")
		(net "UPI_CPU1_CPU0_P1P1_DN<11>")
	)
	(segment
		(start 143.487394 -43.79087)
		(end 143.143986 -43.784774)
		(width 0.1143)
		(layer "In9.Cu")
		(net "UPI_CPU1_CPU0_P1P1_DN<11>")
	)
	(segment
		(start 296.999406 -55.624476)
		(end 297.008296 -55.609236)
		(width 0.0889)
		(layer "In9.Cu")
		(net "UPI_CPU1_CPU0_P1P1_DN<11>")
	)
	(segment
		(start 288.1376 -45.119036)
		(end 264.455148 -39.325296)
		(width 0.1143)
		(layer "In9.Cu")
		(net "UPI_CPU1_CPU0_P1P1_DN<11>")
	)
	(segment
		(start 140.348208 -44.33824)
		(end 140.253212 -44.532042)
		(width 0.1143)
		(layer "In9.Cu")
		(net "UPI_CPU1_CPU0_P1P1_DN<11>")
	)
	(segment
		(start 132.310378 -51.344322)
		(end 132.252466 -51.402234)
		(width 0.0889)
		(layer "In9.Cu")
		(net "UPI_CPU1_CPU0_P1P1_DN<11>")
	)
	(segment
		(start 199.180196 -36.277042)
		(end 194.971416 -37.42944)
		(width 0.1143)
		(layer "In9.Cu")
		(net "UPI_CPU1_CPU0_P1P1_DN<11>")
	)
	(segment
		(start 142.360396 -43.65244)
		(end 141.285976 -44.018708)
		(width 0.1143)
		(layer "In9.Cu")
		(net "UPI_CPU1_CPU0_P1P1_DN<11>")
	)
	(segment
		(start 246.45239 -36.339272)
		(end 242.773454 -38.33368)
		(width 0.1143)
		(layer "In9.Cu")
		(net "UPI_CPU1_CPU0_P1P1_DN<11>")
	)
	(segment
		(start 132.252466 -51.402234)
		(end 132.252466 -51.53152)
		(width 0.0889)
		(layer "In9.Cu")
		(net "UPI_CPU1_CPU0_P1P1_DN<11>")
	)
	(segment
		(start 132.173218 -53.132736)
		(end 132.179568 -53.143404)
		(width 0.0889)
		(layer "In9.Cu")
		(net "UPI_CPU1_CPU0_P1P1_DN<11>")
	)
	(segment
		(start 138.8872 -44.911518)
		(end 138.79703 -44.867322)
		(width 0.1143)
		(layer "In9.Cu")
		(net "UPI_CPU1_CPU0_P1P1_DN<11>")
	)
	(segment
		(start 141.285976 -44.018708)
		(end 141.19098 -44.212256)
		(width 0.1143)
		(layer "In9.Cu")
		(net "UPI_CPU1_CPU0_P1P1_DN<11>")
	)
	(segment
		(start 296.017696 -51.84521)
		(end 296.017696 -50.564796)
		(width 0.1143)
		(layer "In9.Cu")
		(net "UPI_CPU1_CPU0_P1P1_DN<11>")
	)
	(segment
		(start 222.396812 -38.750748)
		(end 211.973668 -39.58209)
		(width 0.1143)
		(layer "In9.Cu")
		(net "UPI_CPU1_CPU0_P1P1_DN<11>")
	)
	(segment
		(start 296.66184 -57.390538)
		(end 296.767758 -57.284366)
		(width 0.0889)
		(layer "In9.Cu")
		(net "UPI_CPU1_CPU0_P1P1_DN<11>")
	)
	(segment
		(start 138.05281 -45.282104)
		(end 137.859262 -45.187108)
		(width 0.1143)
		(layer "In9.Cu")
		(net "UPI_CPU1_CPU0_P1P1_DN<11>")
	)
	(segment
		(start 132.354066 -52.09032)
		(end 132.354066 -52.21732)
		(width 0.0889)
		(layer "In9.Cu")
		(net "UPI_CPU1_CPU0_P1P1_DN<11>")
	)
	(segment
		(start 296.66565 -53.027834)
		(end 296.639742 -53.027834)
		(width 0.0889)
		(layer "In9.Cu")
		(net "UPI_CPU1_CPU0_P1P1_DN<11>")
	)
	(segment
		(start 144.546828 -43.685206)
		(end 144.421098 -43.807126)
		(width 0.1143)
		(layer "In9.Cu")
		(net "UPI_CPU1_CPU0_P1P1_DN<11>")
	)
	(segment
		(start 132.252466 -51.98872)
		(end 132.354066 -52.09032)
		(width 0.0889)
		(layer "In9.Cu")
		(net "UPI_CPU1_CPU0_P1P1_DN<11>")
	)
	(segment
		(start 132.334 -54.030372)
		(end 132.519674 -53.923184)
		(width 0.0889)
		(layer "In9.Cu")
		(net "UPI_CPU1_CPU0_P1P1_DN<11>")
	)
	(segment
		(start 261.758176 -40.200072)
		(end 258.21894 -39.705534)
		(width 0.1143)
		(layer "In9.Cu")
		(net "UPI_CPU1_CPU0_P1P1_DN<11>")
	)
	(segment
		(start 194.971416 -37.42944)
		(end 192.201292 -36.33978)
		(width 0.1143)
		(layer "In9.Cu")
		(net "UPI_CPU1_CPU0_P1P1_DN<11>")
	)
	(segment
		(start 166.88689 -41.790366)
		(end 162.014408 -41.865042)
		(width 0.1143)
		(layer "In9.Cu")
		(net "UPI_CPU1_CPU0_P1P1_DN<11>")
	)
	(segment
		(start 138.990578 -44.962318)
		(end 138.8872 -44.911518)
		(width 0.1143)
		(layer "In9.Cu")
		(net "UPI_CPU1_CPU0_P1P1_DN<11>")
	)
	(segment
		(start 132.354066 -52.21732)
		(end 132.252466 -52.31892)
		(width 0.0889)
		(layer "In9.Cu")
		(net "UPI_CPU1_CPU0_P1P1_DN<11>")
	)
	(segment
		(start 137.439908 -45.491146)
		(end 137.115042 -45.60189)
		(width 0.1143)
		(layer "In9.Cu")
		(net "UPI_CPU1_CPU0_P1P1_DN<11>")
	)
	(segment
		(start 140.866114 -44.322746)
		(end 140.672566 -44.22775)
		(width 0.1143)
		(layer "In9.Cu")
		(net "UPI_CPU1_CPU0_P1P1_DN<11>")
	)
	(segment
		(start 291.47516 -46.167548)
		(end 289.266376 -45.423836)
		(width 0.1143)
		(layer "In9.Cu")
		(net "UPI_CPU1_CPU0_P1P1_DN<11>")
	)
	(segment
		(start 254.771906 -38.36289)
		(end 249.886978 -36.339272)
		(width 0.1143)
		(layer "In9.Cu")
		(net "UPI_CPU1_CPU0_P1P1_DN<11>")
	)
	(segment
		(start 147.0152 -43.726608)
		(end 144.546828 -43.685206)
		(width 0.1143)
		(layer "In9.Cu")
		(net "UPI_CPU1_CPU0_P1P1_DN<11>")
	)
	(segment
		(start 296.999406 -56.615076)
		(end 297.008296 -56.599836)
		(width 0.0889)
		(layer "In9.Cu")
		(net "UPI_CPU1_CPU0_P1P1_DN<11>")
	)
	(segment
		(start 242.773454 -38.33368)
		(end 236.59465 -37.618416)
		(width 0.1143)
		(layer "In9.Cu")
		(net "UPI_CPU1_CPU0_P1P1_DN<11>")
	)
	(segment
		(start 144.07769 -43.80103)
		(end 143.956024 -43.675046)
		(width 0.1143)
		(layer "In9.Cu")
		(net "UPI_CPU1_CPU0_P1P1_DN<11>")
	)
	(segment
		(start 139.928346 -44.642532)
		(end 139.734798 -44.547536)
		(width 0.1143)
		(layer "In9.Cu")
		(net "UPI_CPU1_CPU0_P1P1_DN<11>")
	)
	(segment
		(start 144.421098 -43.807126)
		(end 144.07769 -43.80103)
		(width 0.1143)
		(layer "In9.Cu")
		(net "UPI_CPU1_CPU0_P1P1_DN<11>")
	)
	(segment
		(start 132.226812 -54.092094)
		(end 132.334 -54.030372)
		(width 0.0889)
		(layer "In9.Cu")
		(net "UPI_CPU1_CPU0_P1P1_DN<11>")
	)
	(segment
		(start 192.201292 -36.33978)
		(end 188.006482 -36.172394)
		(width 0.1143)
		(layer "In9.Cu")
		(net "UPI_CPU1_CPU0_P1P1_DN<11>")
	)
	(segment
		(start 137.534904 -45.297598)
		(end 137.439908 -45.491146)
		(width 0.1143)
		(layer "In9.Cu")
		(net "UPI_CPU1_CPU0_P1P1_DN<11>")
	)
	(segment
		(start 139.315444 -44.851574)
		(end 138.990578 -44.962318)
		(width 0.1143)
		(layer "In9.Cu")
		(net "UPI_CPU1_CPU0_P1P1_DN<11>")
	)
	(segment
		(start 173.4058 -41.5798)
		(end 170.815 -41.9862)
		(width 0.1143)
		(layer "In9.Cu")
		(net "UPI_CPU1_CPU0_P1P1_DN<11>")
	)
	(segment
		(start 137.115042 -45.60189)
		(end 136.921494 -45.506894)
		(width 0.1143)
		(layer "In9.Cu")
		(net "UPI_CPU1_CPU0_P1P1_DN<11>")
	)
	(segment
		(start 141.19098 -44.212256)
		(end 140.866114 -44.322746)
		(width 0.1143)
		(layer "In9.Cu")
		(net "UPI_CPU1_CPU0_P1P1_DN<11>")
	)
	(segment
		(start 132.310378 -51.322224)
		(end 132.310378 -51.344322)
		(width 0.0889)
		(layer "In9.Cu")
		(net "UPI_CPU1_CPU0_P1P1_DN<11>")
	)
	(segment
		(start 297.502326 -54.323234)
		(end 297.535092 -54.323234)
		(width 0.0889)
		(layer "In9.Cu")
		(net "UPI_CPU1_CPU0_P1P1_DN<11>")
	)
	(segment
		(start 132.354066 -51.63312)
		(end 132.354066 -51.76012)
		(width 0.0889)
		(layer "In9.Cu")
		(net "UPI_CPU1_CPU0_P1P1_DN<11>")
	)
	(segment
		(start 296.674032 -53.028088)
		(end 296.66565 -53.027834)
		(width 0.0889)
		(layer "In9.Cu")
		(net "UPI_CPU1_CPU0_P1P1_DN<11>")
	)
	(segment
		(start 297.871642 -53.731922)
		(end 297.866816 -53.723286)
		(width 0.0889)
		(layer "In9.Cu")
		(net "UPI_CPU1_CPU0_P1P1_DN<11>")
	)
	(arc
		(start 297.008296 -53.227986)
		(mid 296.867139 -53.084601)
		(end 296.674032 -53.028088)
		(width 0.0889)
		(layer "In9.Cu")
		(net "UPI_CPU1_CPU0_P1P1_DN<11>")
	)
	(arc
		(start 297.008296 -55.609236)
		(mid 297.061829 -55.409338)
		(end 297.008296 -55.20944)
		(width 0.0889)
		(layer "In9.Cu")
		(net "UPI_CPU1_CPU0_P1P1_DN<11>")
	)
	(arc
		(start 297.008296 -56.20004)
		(mid 296.929107 -55.913425)
		(end 296.999406 -55.624476)
		(width 0.0889)
		(layer "In9.Cu")
		(net "UPI_CPU1_CPU0_P1P1_DN<11>")
	)
	(arc
		(start 132.173218 -52.73294)
		(mid 132.119685 -52.932838)
		(end 132.173218 -53.132736)
		(width 0.0889)
		(layer "In9.Cu")
		(net "UPI_CPU1_CPU0_P1P1_DN<11>")
	)
	(arc
		(start 296.639742 -53.027834)
		(mid 296.23443 -52.846526)
		(end 296.068496 -52.434744)
		(width 0.0889)
		(layer "In9.Cu")
		(net "UPI_CPU1_CPU0_P1P1_DN<11>")
	)
	(arc
		(start 297.008296 -56.599836)
		(mid 297.061829 -56.399938)
		(end 297.008296 -56.20004)
		(width 0.0889)
		(layer "In9.Cu")
		(net "UPI_CPU1_CPU0_P1P1_DN<11>")
	)
	(arc
		(start 297.008296 -55.20944)
		(mid 296.929107 -54.922825)
		(end 296.999406 -54.633876)
		(width 0.0889)
		(layer "In9.Cu")
		(net "UPI_CPU1_CPU0_P1P1_DN<11>")
	)
	(arc
		(start 132.179568 -53.143404)
		(mid 132.252366 -53.434167)
		(end 132.173218 -53.723286)
		(width 0.0889)
		(layer "In9.Cu")
		(net "UPI_CPU1_CPU0_P1P1_DN<11>")
	)
	(arc
		(start 297.866816 -54.123336)
		(mid 297.920286 -53.928273)
		(end 297.871642 -53.731922)
		(width 0.0889)
		(layer "In9.Cu")
		(net "UPI_CPU1_CPU0_P1P1_DN<11>")
	)
	(arc
		(start 296.767758 -57.284366)
		(mid 296.8869 -57.106197)
		(end 296.928794 -56.896)
		(width 0.0889)
		(layer "In9.Cu")
		(net "UPI_CPU1_CPU0_P1P1_DN<11>")
	)
	(arc
		(start 296.928794 -56.896)
		(mid 296.946626 -56.751146)
		(end 296.999406 -56.615076)
		(width 0.0889)
		(layer "In9.Cu")
		(net "UPI_CPU1_CPU0_P1P1_DN<11>")
	)
	(arc
		(start 132.173218 -53.723286)
		(mid 132.12085 -53.894135)
		(end 132.148072 -54.070758)
		(width 0.0889)
		(layer "In9.Cu")
		(net "UPI_CPU1_CPU0_P1P1_DN<11>")
	)
	(arc
		(start 297.008296 -54.618636)
		(mid 297.216904 -54.406704)
		(end 297.502326 -54.323234)
		(width 0.0889)
		(layer "In9.Cu")
		(net "UPI_CPU1_CPU0_P1P1_DN<11>")
	)
	(arc
		(start 297.535092 -54.323234)
		(mid 297.726734 -54.266068)
		(end 297.866816 -54.123336)
		(width 0.0889)
		(layer "In9.Cu")
		(net "UPI_CPU1_CPU0_P1P1_DN<11>")
	)
	(arc
		(start 297.866816 -53.723286)
		(mid 297.728072 -53.581253)
		(end 297.53814 -53.523388)
		(width 0.0889)
		(layer "In9.Cu")
		(net "UPI_CPU1_CPU0_P1P1_DN<11>")
	)
	(arc
		(start 297.502326 -53.523388)
		(mid 297.216902 -53.439921)
		(end 297.008296 -53.227986)
		(width 0.0889)
		(layer "In9.Cu")
		(net "UPI_CPU1_CPU0_P1P1_DN<11>")
	)
	(arc
		(start 132.252466 -52.44592)
		(mid 132.231236 -52.594512)
		(end 132.173218 -52.73294)
		(width 0.0889)
		(layer "In9.Cu")
		(net "UPI_CPU1_CPU0_P1P1_DN<11>")
	)
	(segment
		(start 297.807126 -58.381138)
		(end 298.378626 -58.381138)
		(width 0.1143)
		(layer "F.Cu")
		(net "UPI_CPU1_CPU0_P1P1_DN<10>")
	)
	(segment
		(start 132.806694 -53.427884)
		(end 133.378194 -53.427884)
		(width 0.1143)
		(layer "F.Cu")
		(net "UPI_CPU1_CPU0_P1P1_DN<10>")
	)
	(via
		(at 133.378194 -53.427884)
		(size 0.508)
		(drill 0.254)
		(layers "F.Cu" "B.Cu")
		(net "UPI_CPU1_CPU0_P1P1_DN<10>")
	)
	(via
		(at 298.378626 -58.381138)
		(size 0.508)
		(drill 0.254)
		(layers "F.Cu" "B.Cu")
		(net "UPI_CPU1_CPU0_P1P1_DN<10>")
	)
	(segment
		(start 137.756138 -46.235112)
		(end 137.661142 -46.42866)
		(width 0.1143)
		(layer "In9.Cu")
		(net "UPI_CPU1_CPU0_P1P1_DN<10>")
	)
	(segment
		(start 257.974338 -40.440102)
		(end 249.616976 -36.980368)
		(width 0.1143)
		(layer "In9.Cu")
		(net "UPI_CPU1_CPU0_P1P1_DN<10>")
	)
	(segment
		(start 296.15003 -54.713886)
		(end 296.14368 -54.703218)
		(width 0.0889)
		(layer "In9.Cu")
		(net "UPI_CPU1_CPU0_P1P1_DN<10>")
	)
	(segment
		(start 249.616976 -36.980368)
		(end 246.619268 -36.980368)
		(width 0.1143)
		(layer "In9.Cu")
		(net "UPI_CPU1_CPU0_P1P1_DN<10>")
	)
	(segment
		(start 296.154856 -56.703722)
		(end 296.15003 -56.695086)
		(width 0.0889)
		(layer "In9.Cu")
		(net "UPI_CPU1_CPU0_P1P1_DN<10>")
	)
	(segment
		(start 199.080374 -36.988242)
		(end 197.135242 -37.555932)
		(width 0.1143)
		(layer "In9.Cu")
		(net "UPI_CPU1_CPU0_P1P1_DN<10>")
	)
	(segment
		(start 133.35635 -50.076354)
		(end 133.235954 -50.19675)
		(width 0.0889)
		(layer "In9.Cu")
		(net "UPI_CPU1_CPU0_P1P1_DN<10>")
	)
	(segment
		(start 138.274044 -46.219872)
		(end 138.080496 -46.124876)
		(width 0.1143)
		(layer "In9.Cu")
		(net "UPI_CPU1_CPU0_P1P1_DN<10>")
	)
	(segment
		(start 197.135242 -37.555932)
		(end 197.135242 -37.555678)
		(width 0.1143)
		(layer "In9.Cu")
		(net "UPI_CPU1_CPU0_P1P1_DN<10>")
	)
	(segment
		(start 143.37792 -44.784772)
		(end 143.03502 -44.792646)
		(width 0.1143)
		(layer "In9.Cu")
		(net "UPI_CPU1_CPU0_P1P1_DN<10>")
	)
	(segment
		(start 141.17066 -45.233844)
		(end 140.977366 -45.138848)
		(width 0.1143)
		(layer "In9.Cu")
		(net "UPI_CPU1_CPU0_P1P1_DN<10>")
	)
	(segment
		(start 211.923122 -40.263318)
		(end 199.080374 -36.988242)
		(width 0.1143)
		(layer "In9.Cu")
		(net "UPI_CPU1_CPU0_P1P1_DN<10>")
	)
	(segment
		(start 191.982598 -37.000688)
		(end 188.11367 -36.848542)
		(width 0.1143)
		(layer "In9.Cu")
		(net "UPI_CPU1_CPU0_P1P1_DN<10>")
	)
	(segment
		(start 133.079998 -50.9778)
		(end 133.079998 -51.1302)
		(width 0.0889)
		(layer "In9.Cu")
		(net "UPI_CPU1_CPU0_P1P1_DN<10>")
	)
	(segment
		(start 182.401718 -37.950648)
		(end 180.56352 -38.305486)
		(width 0.1143)
		(layer "In9.Cu")
		(net "UPI_CPU1_CPU0_P1P1_DN<10>")
	)
	(segment
		(start 288.244026 -45.844968)
		(end 288.009584 -45.767498)
		(width 0.1143)
		(layer "In9.Cu")
		(net "UPI_CPU1_CPU0_P1P1_DN<10>")
	)
	(segment
		(start 236.534198 -38.261036)
		(end 222.396812 -39.411148)
		(width 0.1143)
		(layer "In9.Cu")
		(net "UPI_CPU1_CPU0_P1P1_DN<10>")
	)
	(segment
		(start 180.56352 -38.305486)
		(end 178.962812 -39.135812)
		(width 0.1143)
		(layer "In9.Cu")
		(net "UPI_CPU1_CPU0_P1P1_DN<10>")
	)
	(segment
		(start 141.495526 -45.123354)
		(end 141.17066 -45.233844)
		(width 0.1143)
		(layer "In9.Cu")
		(net "UPI_CPU1_CPU0_P1P1_DN<10>")
	)
	(segment
		(start 295.29151 -52.637436)
		(end 295.348914 -52.538122)
		(width 0.0889)
		(layer "In9.Cu")
		(net "UPI_CPU1_CPU0_P1P1_DN<10>")
	)
	(segment
		(start 296.66184 -57.981088)
		(end 296.64406 -57.981088)
		(width 0.0889)
		(layer "In9.Cu")
		(net "UPI_CPU1_CPU0_P1P1_DN<10>")
	)
	(segment
		(start 132.978398 -50.323242)
		(end 132.978398 -50.8762)
		(width 0.0889)
		(layer "In9.Cu")
		(net "UPI_CPU1_CPU0_P1P1_DN<10>")
	)
	(segment
		(start 295.348914 -52.063396)
		(end 295.298114 -51.990498)
		(width 0.0889)
		(layer "In9.Cu")
		(net "UPI_CPU1_CPU0_P1P1_DN<10>")
	)
	(segment
		(start 293.180516 -48.338232)
		(end 290.992814 -46.752256)
		(width 0.1143)
		(layer "In9.Cu")
		(net "UPI_CPU1_CPU0_P1P1_DN<10>")
	)
	(segment
		(start 133.59511 -49.837594)
		(end 133.464046 -49.837594)
		(width 0.0889)
		(layer "In9.Cu")
		(net "UPI_CPU1_CPU0_P1P1_DN<10>")
	)
	(segment
		(start 140.02639 -45.462444)
		(end 139.631928 -45.596556)
		(width 0.1143)
		(layer "In9.Cu")
		(net "UPI_CPU1_CPU0_P1P1_DN<10>")
	)
	(segment
		(start 133.320282 -53.82387)
		(end 133.378194 -53.765958)
		(width 0.0889)
		(layer "In9.Cu")
		(net "UPI_CPU1_CPU0_P1P1_DN<10>")
	)
	(segment
		(start 264.471658 -40.035988)
		(end 261.566152 -40.930068)
		(width 0.1143)
		(layer "In9.Cu")
		(net "UPI_CPU1_CPU0_P1P1_DN<10>")
	)
	(segment
		(start 132.978398 -51.2318)
		(end 132.978398 -51.464718)
		(width 0.0889)
		(layer "In9.Cu")
		(net "UPI_CPU1_CPU0_P1P1_DN<10>")
	)
	(segment
		(start 142.400782 -44.65447)
		(end 141.590522 -44.93006)
		(width 0.1143)
		(layer "In9.Cu")
		(net "UPI_CPU1_CPU0_P1P1_DN<10>")
	)
	(segment
		(start 195.017898 -38.173914)
		(end 191.982598 -37.000434)
		(width 0.1143)
		(layer "In9.Cu")
		(net "UPI_CPU1_CPU0_P1P1_DN<10>")
	)
	(segment
		(start 140.639546 -45.253656)
		(end 140.544804 -45.44695)
		(width 0.1143)
		(layer "In9.Cu")
		(net "UPI_CPU1_CPU0_P1P1_DN<10>")
	)
	(segment
		(start 261.566152 -40.930068)
		(end 257.974338 -40.440102)
		(width 0.1143)
		(layer "In9.Cu")
		(net "UPI_CPU1_CPU0_P1P1_DN<10>")
	)
	(segment
		(start 173.609 -42.3164)
		(end 170.9166 -42.9006)
		(width 0.1143)
		(layer "In9.Cu")
		(net "UPI_CPU1_CPU0_P1P1_DN<10>")
	)
	(segment
		(start 138.080496 -46.124876)
		(end 137.756138 -46.235112)
		(width 0.1143)
		(layer "In9.Cu")
		(net "UPI_CPU1_CPU0_P1P1_DN<10>")
	)
	(segment
		(start 138.693906 -45.915834)
		(end 138.59891 -46.109382)
		(width 0.1143)
		(layer "In9.Cu")
		(net "UPI_CPU1_CPU0_P1P1_DN<10>")
	)
	(segment
		(start 222.396812 -39.411148)
		(end 211.923122 -40.263318)
		(width 0.1143)
		(layer "In9.Cu")
		(net "UPI_CPU1_CPU0_P1P1_DN<10>")
	)
	(segment
		(start 137.142728 -46.4439)
		(end 136.81837 -46.55439)
		(width 0.1143)
		(layer "In9.Cu")
		(net "UPI_CPU1_CPU0_P1P1_DN<10>")
	)
	(segment
		(start 295.298114 -51.990498)
		(end 295.298114 -51.280822)
		(width 0.1143)
		(layer "In9.Cu")
		(net "UPI_CPU1_CPU0_P1P1_DN<10>")
	)
	(segment
		(start 155.913328 -42.382694)
		(end 146.639026 -44.557442)
		(width 0.1143)
		(layer "In9.Cu")
		(net "UPI_CPU1_CPU0_P1P1_DN<10>")
	)
	(segment
		(start 141.590522 -44.93006)
		(end 141.495526 -45.123354)
		(width 0.1143)
		(layer "In9.Cu")
		(net "UPI_CPU1_CPU0_P1P1_DN<10>")
	)
	(segment
		(start 133.995922 -49.305718)
		(end 133.71576 -49.58588)
		(width 0.0889)
		(layer "In9.Cu")
		(net "UPI_CPU1_CPU0_P1P1_DN<10>")
	)
	(segment
		(start 178.962812 -39.135812)
		(end 173.609 -42.3164)
		(width 0.1143)
		(layer "In9.Cu")
		(net "UPI_CPU1_CPU0_P1P1_DN<10>")
	)
	(segment
		(start 138.59891 -46.109382)
		(end 138.274044 -46.219872)
		(width 0.1143)
		(layer "In9.Cu")
		(net "UPI_CPU1_CPU0_P1P1_DN<10>")
	)
	(segment
		(start 295.821354 -53.523388)
		(end 295.78554 -53.523388)
		(width 0.0889)
		(layer "In9.Cu")
		(net "UPI_CPU1_CPU0_P1P1_DN<10>")
	)
	(segment
		(start 134.067042 -49.305718)
		(end 133.995922 -49.305718)
		(width 0.0889)
		(layer "In9.Cu")
		(net "UPI_CPU1_CPU0_P1P1_DN<10>")
	)
	(segment
		(start 133.464046 -49.837594)
		(end 133.35635 -49.94529)
		(width 0.0889)
		(layer "In9.Cu")
		(net "UPI_CPU1_CPU0_P1P1_DN<10>")
	)
	(segment
		(start 140.544804 -45.44695)
		(end 140.219938 -45.55744)
		(width 0.1143)
		(layer "In9.Cu")
		(net "UPI_CPU1_CPU0_P1P1_DN<10>")
	)
	(segment
		(start 191.982598 -37.000434)
		(end 191.982598 -37.000688)
		(width 0.1143)
		(layer "In9.Cu")
		(net "UPI_CPU1_CPU0_P1P1_DN<10>")
	)
	(segment
		(start 133.037834 -53.217318)
		(end 133.031484 -53.227986)
		(width 0.0889)
		(layer "In9.Cu")
		(net "UPI_CPU1_CPU0_P1P1_DN<10>")
	)
	(segment
		(start 296.154856 -54.722522)
		(end 296.15003 -54.713886)
		(width 0.0889)
		(layer "In9.Cu")
		(net "UPI_CPU1_CPU0_P1P1_DN<10>")
	)
	(segment
		(start 290.992814 -46.752256)
		(end 288.244026 -45.844968)
		(width 0.1143)
		(layer "In9.Cu")
		(net "UPI_CPU1_CPU0_P1P1_DN<10>")
	)
	(segment
		(start 143.03502 -44.792646)
		(end 142.879064 -44.643802)
		(width 0.1143)
		(layer "In9.Cu")
		(net "UPI_CPU1_CPU0_P1P1_DN<10>")
	)
	(segment
		(start 137.661142 -46.42866)
		(end 137.336276 -46.53915)
		(width 0.1143)
		(layer "In9.Cu")
		(net "UPI_CPU1_CPU0_P1P1_DN<10>")
	)
	(segment
		(start 286.775144 -45.438822)
		(end 264.471658 -40.035988)
		(width 0.1143)
		(layer "In9.Cu")
		(net "UPI_CPU1_CPU0_P1P1_DN<10>")
	)
	(segment
		(start 197.135242 -37.555678)
		(end 195.017898 -38.173914)
		(width 0.1143)
		(layer "In9.Cu")
		(net "UPI_CPU1_CPU0_P1P1_DN<10>")
	)
	(segment
		(start 139.018518 -45.805598)
		(end 138.693906 -45.915834)
		(width 0.1143)
		(layer "In9.Cu")
		(net "UPI_CPU1_CPU0_P1P1_DN<10>")
	)
	(segment
		(start 288.009584 -45.767498)
		(end 286.775144 -45.438822)
		(width 0.1143)
		(layer "In9.Cu")
		(net "UPI_CPU1_CPU0_P1P1_DN<10>")
	)
	(segment
		(start 170.9166 -42.9006)
		(end 166.85133 -42.564812)
		(width 0.1143)
		(layer "In9.Cu")
		(net "UPI_CPU1_CPU0_P1P1_DN<10>")
	)
	(segment
		(start 297.008296 -58.18124)
		(end 297.004994 -58.175398)
		(width 0.0889)
		(layer "In9.Cu")
		(net "UPI_CPU1_CPU0_P1P1_DN<10>")
	)
	(segment
		(start 132.978398 -50.8762)
		(end 133.079998 -50.9778)
		(width 0.0889)
		(layer "In9.Cu")
		(net "UPI_CPU1_CPU0_P1P1_DN<10>")
	)
	(segment
		(start 140.219938 -45.55744)
		(end 140.02639 -45.462444)
		(width 0.1143)
		(layer "In9.Cu")
		(net "UPI_CPU1_CPU0_P1P1_DN<10>")
	)
	(segment
		(start 296.15003 -56.695086)
		(end 296.14368 -56.684418)
		(width 0.0889)
		(layer "In9.Cu")
		(net "UPI_CPU1_CPU0_P1P1_DN<10>")
	)
	(segment
		(start 160.167574 -43.012868)
		(end 155.913328 -42.382694)
		(width 0.1143)
		(layer "In9.Cu")
		(net "UPI_CPU1_CPU0_P1P1_DN<10>")
	)
	(segment
		(start 188.11367 -36.848542)
		(end 182.401718 -37.950648)
		(width 0.1143)
		(layer "In9.Cu")
		(net "UPI_CPU1_CPU0_P1P1_DN<10>")
	)
	(segment
		(start 295.348914 -52.538122)
		(end 295.348914 -52.063396)
		(width 0.0889)
		(layer "In9.Cu")
		(net "UPI_CPU1_CPU0_P1P1_DN<10>")
	)
	(segment
		(start 133.079998 -51.1302)
		(end 132.978398 -51.2318)
		(width 0.0889)
		(layer "In9.Cu")
		(net "UPI_CPU1_CPU0_P1P1_DN<10>")
	)
	(segment
		(start 161.835338 -42.641774)
		(end 160.167574 -43.012868)
		(width 0.1143)
		(layer "In9.Cu")
		(net "UPI_CPU1_CPU0_P1P1_DN<10>")
	)
	(segment
		(start 133.235954 -50.19675)
		(end 133.10489 -50.19675)
		(width 0.0889)
		(layer "In9.Cu")
		(net "UPI_CPU1_CPU0_P1P1_DN<10>")
	)
	(segment
		(start 296.154856 -55.713122)
		(end 296.15003 -55.704486)
		(width 0.0889)
		(layer "In9.Cu")
		(net "UPI_CPU1_CPU0_P1P1_DN<10>")
	)
	(segment
		(start 242.86972 -39.088822)
		(end 236.534198 -38.261036)
		(width 0.1143)
		(layer "In9.Cu")
		(net "UPI_CPU1_CPU0_P1P1_DN<10>")
	)
	(segment
		(start 166.85133 -42.564812)
		(end 161.835338 -42.641774)
		(width 0.1143)
		(layer "In9.Cu")
		(net "UPI_CPU1_CPU0_P1P1_DN<10>")
	)
	(segment
		(start 139.631928 -45.596556)
		(end 139.536678 -45.790104)
		(width 0.1143)
		(layer "In9.Cu")
		(net "UPI_CPU1_CPU0_P1P1_DN<10>")
	)
	(segment
		(start 143.526764 -44.628562)
		(end 143.37792 -44.784772)
		(width 0.1143)
		(layer "In9.Cu")
		(net "UPI_CPU1_CPU0_P1P1_DN<10>")
	)
	(segment
		(start 133.35635 -49.94529)
		(end 133.35635 -50.076354)
		(width 0.0889)
		(layer "In9.Cu")
		(net "UPI_CPU1_CPU0_P1P1_DN<10>")
	)
	(segment
		(start 146.639026 -44.557442)
		(end 143.526764 -44.628562)
		(width 0.1143)
		(layer "In9.Cu")
		(net "UPI_CPU1_CPU0_P1P1_DN<10>")
	)
	(segment
		(start 140.977366 -45.138848)
		(end 140.639546 -45.253656)
		(width 0.1143)
		(layer "In9.Cu")
		(net "UPI_CPU1_CPU0_P1P1_DN<10>")
	)
	(segment
		(start 139.211812 -45.900594)
		(end 139.018518 -45.805598)
		(width 0.1143)
		(layer "In9.Cu")
		(net "UPI_CPU1_CPU0_P1P1_DN<10>")
	)
	(segment
		(start 133.378194 -53.765958)
		(end 133.378194 -53.427884)
		(width 0.0889)
		(layer "In9.Cu")
		(net "UPI_CPU1_CPU0_P1P1_DN<10>")
	)
	(segment
		(start 137.336276 -46.53915)
		(end 137.142728 -46.4439)
		(width 0.1143)
		(layer "In9.Cu")
		(net "UPI_CPU1_CPU0_P1P1_DN<10>")
	)
	(segment
		(start 133.71576 -49.716944)
		(end 133.59511 -49.837594)
		(width 0.0889)
		(layer "In9.Cu")
		(net "UPI_CPU1_CPU0_P1P1_DN<10>")
	)
	(segment
		(start 298.148756 -58.476388)
		(end 297.502326 -58.476388)
		(width 0.0889)
		(layer "In9.Cu")
		(net "UPI_CPU1_CPU0_P1P1_DN<10>")
	)
	(segment
		(start 139.536678 -45.790104)
		(end 139.211812 -45.900594)
		(width 0.1143)
		(layer "In9.Cu")
		(net "UPI_CPU1_CPU0_P1P1_DN<10>")
	)
	(segment
		(start 136.81837 -46.55439)
		(end 134.067042 -49.305718)
		(width 0.1143)
		(layer "In9.Cu")
		(net "UPI_CPU1_CPU0_P1P1_DN<10>")
	)
	(segment
		(start 246.619268 -36.980368)
		(end 242.86972 -39.088822)
		(width 0.1143)
		(layer "In9.Cu")
		(net "UPI_CPU1_CPU0_P1P1_DN<10>")
	)
	(segment
		(start 296.15003 -55.704486)
		(end 296.14368 -55.693818)
		(width 0.0889)
		(layer "In9.Cu")
		(net "UPI_CPU1_CPU0_P1P1_DN<10>")
	)
	(segment
		(start 295.298114 -51.280822)
		(end 293.180516 -48.338232)
		(width 0.1143)
		(layer "In9.Cu")
		(net "UPI_CPU1_CPU0_P1P1_DN<10>")
	)
	(segment
		(start 133.71576 -49.58588)
		(end 133.71576 -49.716944)
		(width 0.0889)
		(layer "In9.Cu")
		(net "UPI_CPU1_CPU0_P1P1_DN<10>")
	)
	(segment
		(start 142.879064 -44.643802)
		(end 142.400782 -44.65447)
		(width 0.1143)
		(layer "In9.Cu")
		(net "UPI_CPU1_CPU0_P1P1_DN<10>")
	)
	(segment
		(start 133.10489 -50.19675)
		(end 132.978398 -50.323242)
		(width 0.0889)
		(layer "In9.Cu")
		(net "UPI_CPU1_CPU0_P1P1_DN<10>")
	)
	(arc
		(start 296.64406 -57.981088)
		(mid 296.145809 -57.678248)
		(end 296.15003 -57.095136)
		(width 0.0889)
		(layer "In9.Cu")
		(net "UPI_CPU1_CPU0_P1P1_DN<10>")
	)
	(arc
		(start 297.502326 -58.476388)
		(mid 297.216964 -58.393)
		(end 297.008296 -58.18124)
		(width 0.0889)
		(layer "In9.Cu")
		(net "UPI_CPU1_CPU0_P1P1_DN<10>")
	)
	(arc
		(start 296.14368 -56.684418)
		(mid 296.070882 -56.393655)
		(end 296.15003 -56.104536)
		(width 0.0889)
		(layer "In9.Cu")
		(net "UPI_CPU1_CPU0_P1P1_DN<10>")
	)
	(arc
		(start 133.031484 -51.646836)
		(mid 133.110615 -51.942238)
		(end 133.031484 -52.23764)
		(width 0.0889)
		(layer "In9.Cu")
		(net "UPI_CPU1_CPU0_P1P1_DN<10>")
	)
	(arc
		(start 298.378626 -58.381138)
		(mid 298.273161 -58.451608)
		(end 298.148756 -58.476388)
		(width 0.0889)
		(layer "In9.Cu")
		(net "UPI_CPU1_CPU0_P1P1_DN<10>")
	)
	(arc
		(start 296.14368 -54.703218)
		(mid 296.070882 -54.412455)
		(end 296.15003 -54.123336)
		(width 0.0889)
		(layer "In9.Cu")
		(net "UPI_CPU1_CPU0_P1P1_DN<10>")
	)
	(arc
		(start 296.15003 -55.113936)
		(mid 296.2035 -54.918873)
		(end 296.154856 -54.722522)
		(width 0.0889)
		(layer "In9.Cu")
		(net "UPI_CPU1_CPU0_P1P1_DN<10>")
	)
	(arc
		(start 133.031484 -53.628036)
		(mid 133.153421 -53.759069)
		(end 133.320282 -53.82387)
		(width 0.0889)
		(layer "In9.Cu")
		(net "UPI_CPU1_CPU0_P1P1_DN<10>")
	)
	(arc
		(start 295.28516 -53.217318)
		(mid 295.212362 -52.926555)
		(end 295.29151 -52.637436)
		(width 0.0889)
		(layer "In9.Cu")
		(net "UPI_CPU1_CPU0_P1P1_DN<10>")
	)
	(arc
		(start 133.031484 -52.637436)
		(mid 133.110706 -52.926554)
		(end 133.037834 -53.217318)
		(width 0.0889)
		(layer "In9.Cu")
		(net "UPI_CPU1_CPU0_P1P1_DN<10>")
	)
	(arc
		(start 297.004994 -58.175398)
		(mid 296.859028 -58.032999)
		(end 296.66184 -57.981088)
		(width 0.0889)
		(layer "In9.Cu")
		(net "UPI_CPU1_CPU0_P1P1_DN<10>")
	)
	(arc
		(start 296.14368 -55.693818)
		(mid 296.070882 -55.403055)
		(end 296.15003 -55.113936)
		(width 0.0889)
		(layer "In9.Cu")
		(net "UPI_CPU1_CPU0_P1P1_DN<10>")
	)
	(arc
		(start 133.031484 -53.227986)
		(mid 132.977824 -53.428028)
		(end 133.031484 -53.628036)
		(width 0.0889)
		(layer "In9.Cu")
		(net "UPI_CPU1_CPU0_P1P1_DN<10>")
	)
	(arc
		(start 132.98043 -51.489356)
		(mid 132.997705 -51.570774)
		(end 133.031484 -51.646836)
		(width 0.0889)
		(layer "In9.Cu")
		(net "UPI_CPU1_CPU0_P1P1_DN<10>")
	)
	(arc
		(start 296.15003 -57.095136)
		(mid 296.2035 -56.900073)
		(end 296.154856 -56.703722)
		(width 0.0889)
		(layer "In9.Cu")
		(net "UPI_CPU1_CPU0_P1P1_DN<10>")
	)
	(arc
		(start 296.15003 -54.123336)
		(mid 296.15444 -53.730873)
		(end 295.821354 -53.523388)
		(width 0.0889)
		(layer "In9.Cu")
		(net "UPI_CPU1_CPU0_P1P1_DN<10>")
	)
	(arc
		(start 133.031484 -52.23764)
		(mid 132.977985 -52.437538)
		(end 133.031484 -52.637436)
		(width 0.0889)
		(layer "In9.Cu")
		(net "UPI_CPU1_CPU0_P1P1_DN<10>")
	)
	(arc
		(start 296.15003 -56.104536)
		(mid 296.2035 -55.909473)
		(end 296.154856 -55.713122)
		(width 0.0889)
		(layer "In9.Cu")
		(net "UPI_CPU1_CPU0_P1P1_DN<10>")
	)
	(arc
		(start 132.978398 -51.464718)
		(mid 132.979224 -51.477053)
		(end 132.98043 -51.489356)
		(width 0.0889)
		(layer "In9.Cu")
		(net "UPI_CPU1_CPU0_P1P1_DN<10>")
	)
	(arc
		(start 295.78554 -53.523388)
		(mid 295.494719 -53.436801)
		(end 295.28516 -53.217318)
		(width 0.0889)
		(layer "In9.Cu")
		(net "UPI_CPU1_CPU0_P1P1_DN<10>")
	)
	(segment
		(start 140.533374 -57.885584)
		(end 141.104874 -57.885584)
		(width 0.1143)
		(layer "F.Cu")
		(net "UPI_CPU1_CPU0_P1P1_DN<0>")
	)
	(segment
		(start 291.79774 -61.847984)
		(end 292.36924 -61.847984)
		(width 0.1143)
		(layer "F.Cu")
		(net "UPI_CPU1_CPU0_P1P1_DN<0>")
	)
	(via
		(at 292.36924 -61.847984)
		(size 0.508)
		(drill 0.254)
		(layers "F.Cu" "B.Cu")
		(net "UPI_CPU1_CPU0_P1P1_DN<0>")
	)
	(via
		(at 141.104874 -57.885584)
		(size 0.508)
		(drill 0.254)
		(layers "F.Cu" "B.Cu")
		(net "UPI_CPU1_CPU0_P1P1_DN<0>")
	)
	(segment
		(start 160.006284 -51.165506)
		(end 155.78074 -49.4157)
		(width 0.1143)
		(layer "In9.Cu")
		(net "UPI_CPU1_CPU0_P1P1_DN<0>")
	)
	(segment
		(start 286.426656 -54.722522)
		(end 286.42183 -54.713886)
		(width 0.0889)
		(layer "In9.Cu")
		(net "UPI_CPU1_CPU0_P1P1_DN<0>")
	)
	(segment
		(start 141.104874 -57.54751)
		(end 141.104874 -57.885584)
		(width 0.0889)
		(layer "In9.Cu")
		(net "UPI_CPU1_CPU0_P1P1_DN<0>")
	)
	(segment
		(start 286.426656 -56.703722)
		(end 286.42183 -56.695086)
		(width 0.0889)
		(layer "In9.Cu")
		(net "UPI_CPU1_CPU0_P1P1_DN<0>")
	)
	(segment
		(start 194.14617 -46.10989)
		(end 191.605916 -47.042324)
		(width 0.1143)
		(layer "In9.Cu")
		(net "UPI_CPU1_CPU0_P1P1_DN<0>")
	)
	(segment
		(start 290.342066 -61.447934)
		(end 288.856674 -59.962542)
		(width 0.0889)
		(layer "In9.Cu")
		(net "UPI_CPU1_CPU0_P1P1_DN<0>")
	)
	(segment
		(start 285.358586 -53.373528)
		(end 281.186128 -53.373528)
		(width 0.1143)
		(layer "In9.Cu")
		(net "UPI_CPU1_CPU0_P1P1_DN<0>")
	)
	(segment
		(start 236.057948 -45.028358)
		(end 222.396812 -46.211744)
		(width 0.1143)
		(layer "In9.Cu")
		(net "UPI_CPU1_CPU0_P1P1_DN<0>")
	)
	(segment
		(start 143.881856 -56.195722)
		(end 143.861536 -56.204104)
		(width 0.0889)
		(layer "In9.Cu")
		(net "UPI_CPU1_CPU0_P1P1_DN<0>")
	)
	(segment
		(start 150.04796 -51.791616)
		(end 149.773894 -52.258722)
		(width 0.1143)
		(layer "In9.Cu")
		(net "UPI_CPU1_CPU0_P1P1_DN<0>")
	)
	(segment
		(start 292.36924 -61.847984)
		(end 291.87013 -61.821822)
		(width 0.0889)
		(layer "In9.Cu")
		(net "UPI_CPU1_CPU0_P1P1_DN<0>")
	)
	(segment
		(start 290.663376 -61.447934)
		(end 290.342066 -61.447934)
		(width 0.0889)
		(layer "In9.Cu")
		(net "UPI_CPU1_CPU0_P1P1_DN<0>")
	)
	(segment
		(start 247.789954 -48.488854)
		(end 239.291114 -46.745652)
		(width 0.1143)
		(layer "In9.Cu")
		(net "UPI_CPU1_CPU0_P1P1_DN<0>")
	)
	(segment
		(start 211.458302 -47.159164)
		(end 199.43445 -44.031408)
		(width 0.1143)
		(layer "In9.Cu")
		(net "UPI_CPU1_CPU0_P1P1_DN<0>")
	)
	(segment
		(start 264.734802 -47.04969)
		(end 262.414512 -47.705518)
		(width 0.1143)
		(layer "In9.Cu")
		(net "UPI_CPU1_CPU0_P1P1_DN<0>")
	)
	(segment
		(start 143.032988 -56.493918)
		(end 142.726918 -56.496458)
		(width 0.0889)
		(layer "In9.Cu")
		(net "UPI_CPU1_CPU0_P1P1_DN<0>")
	)
	(segment
		(start 286.42183 -56.695086)
		(end 286.41548 -56.684418)
		(width 0.0889)
		(layer "In9.Cu")
		(net "UPI_CPU1_CPU0_P1P1_DN<0>")
	)
	(segment
		(start 288.856674 -59.962542)
		(end 288.65068 -59.962542)
		(width 0.0889)
		(layer "In9.Cu")
		(net "UPI_CPU1_CPU0_P1P1_DN<0>")
	)
	(segment
		(start 286.426656 -53.731922)
		(end 286.367982 -53.630322)
		(width 0.0889)
		(layer "In9.Cu")
		(net "UPI_CPU1_CPU0_P1P1_DN<0>")
	)
	(segment
		(start 256.840736 -47.190406)
		(end 256.240534 -47.151544)
		(width 0.1143)
		(layer "In9.Cu")
		(net "UPI_CPU1_CPU0_P1P1_DN<0>")
	)
	(segment
		(start 286.426656 -55.713122)
		(end 286.42183 -55.704486)
		(width 0.0889)
		(layer "In9.Cu")
		(net "UPI_CPU1_CPU0_P1P1_DN<0>")
	)
	(segment
		(start 286.426656 -57.694322)
		(end 286.42183 -57.685686)
		(width 0.0889)
		(layer "In9.Cu")
		(net "UPI_CPU1_CPU0_P1P1_DN<0>")
	)
	(segment
		(start 196.789802 -45.07103)
		(end 194.14617 -46.10989)
		(width 0.1143)
		(layer "In9.Cu")
		(net "UPI_CPU1_CPU0_P1P1_DN<0>")
	)
	(segment
		(start 286.060388 -53.322728)
		(end 285.431484 -53.322728)
		(width 0.0889)
		(layer "In9.Cu")
		(net "UPI_CPU1_CPU0_P1P1_DN<0>")
	)
	(segment
		(start 256.240534 -47.151544)
		(end 250.060206 -48.09109)
		(width 0.1143)
		(layer "In9.Cu")
		(net "UPI_CPU1_CPU0_P1P1_DN<0>")
	)
	(segment
		(start 191.605916 -47.042324)
		(end 184.815734 -46.998128)
		(width 0.1143)
		(layer "In9.Cu")
		(net "UPI_CPU1_CPU0_P1P1_DN<0>")
	)
	(segment
		(start 286.42183 -54.713886)
		(end 286.41548 -54.703218)
		(width 0.0889)
		(layer "In9.Cu")
		(net "UPI_CPU1_CPU0_P1P1_DN<0>")
	)
	(segment
		(start 152.223978 -50.206656)
		(end 150.04796 -51.791616)
		(width 0.1143)
		(layer "In9.Cu")
		(net "UPI_CPU1_CPU0_P1P1_DN<0>")
	)
	(segment
		(start 175.793908 -48.930814)
		(end 169.610024 -51.048666)
		(width 0.1143)
		(layer "In9.Cu")
		(net "UPI_CPU1_CPU0_P1P1_DN<0>")
	)
	(segment
		(start 196.789802 -45.070776)
		(end 196.789802 -45.07103)
		(width 0.1143)
		(layer "In9.Cu")
		(net "UPI_CPU1_CPU0_P1P1_DN<0>")
	)
	(segment
		(start 199.43445 -44.031408)
		(end 196.789802 -45.070776)
		(width 0.1143)
		(layer "In9.Cu")
		(net "UPI_CPU1_CPU0_P1P1_DN<0>")
	)
	(segment
		(start 142.174722 -56.990488)
		(end 141.948408 -56.990488)
		(width 0.0889)
		(layer "In9.Cu")
		(net "UPI_CPU1_CPU0_P1P1_DN<0>")
	)
	(segment
		(start 179.569618 -47.686976)
		(end 175.801528 -48.928274)
		(width 0.1143)
		(layer "In9.Cu")
		(net "UPI_CPU1_CPU0_P1P1_DN<0>")
	)
	(segment
		(start 149.773894 -52.258722)
		(end 144.186402 -56.068976)
		(width 0.1143)
		(layer "In9.Cu")
		(net "UPI_CPU1_CPU0_P1P1_DN<0>")
	)
	(segment
		(start 285.431484 -53.322728)
		(end 285.380684 -53.373528)
		(width 0.0889)
		(layer "In9.Cu")
		(net "UPI_CPU1_CPU0_P1P1_DN<0>")
	)
	(segment
		(start 286.367982 -53.630322)
		(end 286.060388 -53.322728)
		(width 0.0889)
		(layer "In9.Cu")
		(net "UPI_CPU1_CPU0_P1P1_DN<0>")
	)
	(segment
		(start 144.186402 -56.068976)
		(end 143.881856 -56.195722)
		(width 0.1143)
		(layer "In9.Cu")
		(net "UPI_CPU1_CPU0_P1P1_DN<0>")
	)
	(segment
		(start 165.078156 -52.095146)
		(end 160.006284 -51.165506)
		(width 0.1143)
		(layer "In9.Cu")
		(net "UPI_CPU1_CPU0_P1P1_DN<0>")
	)
	(segment
		(start 281.186128 -53.373528)
		(end 278.29764 -50.485294)
		(width 0.1143)
		(layer "In9.Cu")
		(net "UPI_CPU1_CPU0_P1P1_DN<0>")
	)
	(segment
		(start 286.951674 -58.971688)
		(end 286.91205 -58.971688)
		(width 0.0889)
		(layer "In9.Cu")
		(net "UPI_CPU1_CPU0_P1P1_DN<0>")
	)
	(segment
		(start 262.414512 -47.705518)
		(end 256.840736 -47.190406)
		(width 0.1143)
		(layer "In9.Cu")
		(net "UPI_CPU1_CPU0_P1P1_DN<0>")
	)
	(segment
		(start 169.610024 -51.048666)
		(end 165.078156 -52.095146)
		(width 0.1143)
		(layer "In9.Cu")
		(net "UPI_CPU1_CPU0_P1P1_DN<0>")
	)
	(segment
		(start 175.801528 -48.928274)
		(end 175.79594 -48.930306)
		(width 0.1143)
		(layer "In9.Cu")
		(net "UPI_CPU1_CPU0_P1P1_DN<0>")
	)
	(segment
		(start 184.815734 -46.998128)
		(end 181.968394 -46.896782)
		(width 0.1143)
		(layer "In9.Cu")
		(net "UPI_CPU1_CPU0_P1P1_DN<0>")
	)
	(segment
		(start 175.79594 -48.930306)
		(end 175.793908 -48.930814)
		(width 0.1143)
		(layer "In9.Cu")
		(net "UPI_CPU1_CPU0_P1P1_DN<0>")
	)
	(segment
		(start 250.060206 -48.09109)
		(end 247.789954 -48.488854)
		(width 0.1143)
		(layer "In9.Cu")
		(net "UPI_CPU1_CPU0_P1P1_DN<0>")
	)
	(segment
		(start 239.291114 -46.745652)
		(end 236.057948 -45.028358)
		(width 0.1143)
		(layer "In9.Cu")
		(net "UPI_CPU1_CPU0_P1P1_DN<0>")
	)
	(segment
		(start 286.42183 -57.685686)
		(end 286.41548 -57.675018)
		(width 0.0889)
		(layer "In9.Cu")
		(net "UPI_CPU1_CPU0_P1P1_DN<0>")
	)
	(segment
		(start 143.795242 -56.176418)
		(end 143.032988 -56.493918)
		(width 0.0889)
		(layer "In9.Cu")
		(net "UPI_CPU1_CPU0_P1P1_DN<0>")
	)
	(segment
		(start 287.810194 -59.466988)
		(end 287.77438 -59.466988)
		(width 0.0889)
		(layer "In9.Cu")
		(net "UPI_CPU1_CPU0_P1P1_DN<0>")
	)
	(segment
		(start 155.78074 -49.4157)
		(end 152.223978 -50.206656)
		(width 0.1143)
		(layer "In9.Cu")
		(net "UPI_CPU1_CPU0_P1P1_DN<0>")
	)
	(segment
		(start 285.380684 -53.373528)
		(end 285.358586 -53.373528)
		(width 0.0889)
		(layer "In9.Cu")
		(net "UPI_CPU1_CPU0_P1P1_DN<0>")
	)
	(segment
		(start 181.968394 -46.896782)
		(end 179.569618 -47.686976)
		(width 0.1143)
		(layer "In9.Cu")
		(net "UPI_CPU1_CPU0_P1P1_DN<0>")
	)
	(segment
		(start 141.169898 -57.482486)
		(end 141.104874 -57.54751)
		(width 0.0889)
		(layer "In9.Cu")
		(net "UPI_CPU1_CPU0_P1P1_DN<0>")
	)
	(segment
		(start 143.861536 -56.204104)
		(end 143.795242 -56.176418)
		(width 0.0889)
		(layer "In9.Cu")
		(net "UPI_CPU1_CPU0_P1P1_DN<0>")
	)
	(segment
		(start 286.42183 -55.704486)
		(end 286.41548 -55.693818)
		(width 0.0889)
		(layer "In9.Cu")
		(net "UPI_CPU1_CPU0_P1P1_DN<0>")
	)
	(segment
		(start 278.29764 -50.485294)
		(end 264.734802 -47.04969)
		(width 0.1143)
		(layer "In9.Cu")
		(net "UPI_CPU1_CPU0_P1P1_DN<0>")
	)
	(segment
		(start 291.5285 -61.943488)
		(end 291.49294 -61.943488)
		(width 0.0889)
		(layer "In9.Cu")
		(net "UPI_CPU1_CPU0_P1P1_DN<0>")
	)
	(segment
		(start 222.396812 -46.211744)
		(end 211.458302 -47.159164)
		(width 0.1143)
		(layer "In9.Cu")
		(net "UPI_CPU1_CPU0_P1P1_DN<0>")
	)
	(arc
		(start 288.65068 -59.962542)
		(mid 288.355148 -59.883314)
		(end 288.13887 -59.666886)
		(width 0.0889)
		(layer "In9.Cu")
		(net "UPI_CPU1_CPU0_P1P1_DN<0>")
	)
	(arc
		(start 291.87013 -61.821822)
		(mid 291.708878 -61.9095)
		(end 291.5285 -61.943488)
		(width 0.0889)
		(layer "In9.Cu")
		(net "UPI_CPU1_CPU0_P1P1_DN<0>")
	)
	(arc
		(start 141.616684 -57.190386)
		(mid 141.428156 -57.389759)
		(end 141.169898 -57.482486)
		(width 0.0889)
		(layer "In9.Cu")
		(net "UPI_CPU1_CPU0_P1P1_DN<0>")
	)
	(arc
		(start 286.41548 -57.675018)
		(mid 286.342682 -57.384255)
		(end 286.42183 -57.095136)
		(width 0.0889)
		(layer "In9.Cu")
		(net "UPI_CPU1_CPU0_P1P1_DN<0>")
	)
	(arc
		(start 286.42183 -56.104536)
		(mid 286.4753 -55.909473)
		(end 286.426656 -55.713122)
		(width 0.0889)
		(layer "In9.Cu")
		(net "UPI_CPU1_CPU0_P1P1_DN<0>")
	)
	(arc
		(start 290.99891 -61.648086)
		(mid 290.857227 -61.504282)
		(end 290.663376 -61.447934)
		(width 0.0889)
		(layer "In9.Cu")
		(net "UPI_CPU1_CPU0_P1P1_DN<0>")
	)
	(arc
		(start 288.13887 -59.666886)
		(mid 288.000126 -59.524853)
		(end 287.810194 -59.466988)
		(width 0.0889)
		(layer "In9.Cu")
		(net "UPI_CPU1_CPU0_P1P1_DN<0>")
	)
	(arc
		(start 286.42183 -57.095136)
		(mid 286.4753 -56.900073)
		(end 286.426656 -56.703722)
		(width 0.0889)
		(layer "In9.Cu")
		(net "UPI_CPU1_CPU0_P1P1_DN<0>")
	)
	(arc
		(start 286.41548 -56.684418)
		(mid 286.342682 -56.393655)
		(end 286.42183 -56.104536)
		(width 0.0889)
		(layer "In9.Cu")
		(net "UPI_CPU1_CPU0_P1P1_DN<0>")
	)
	(arc
		(start 291.49294 -61.943488)
		(mid 291.207516 -61.860021)
		(end 290.99891 -61.648086)
		(width 0.0889)
		(layer "In9.Cu")
		(net "UPI_CPU1_CPU0_P1P1_DN<0>")
	)
	(arc
		(start 142.726918 -56.496458)
		(mid 142.606166 -56.576671)
		(end 142.518384 -56.692038)
		(width 0.0889)
		(layer "In9.Cu")
		(net "UPI_CPU1_CPU0_P1P1_DN<0>")
	)
	(arc
		(start 286.41548 -55.693818)
		(mid 286.342682 -55.403055)
		(end 286.42183 -55.113936)
		(width 0.0889)
		(layer "In9.Cu")
		(net "UPI_CPU1_CPU0_P1P1_DN<0>")
	)
	(arc
		(start 141.948408 -56.990488)
		(mid 141.756766 -57.047654)
		(end 141.616684 -57.190386)
		(width 0.0889)
		(layer "In9.Cu")
		(net "UPI_CPU1_CPU0_P1P1_DN<0>")
	)
	(arc
		(start 286.42183 -58.085736)
		(mid 286.4753 -57.890673)
		(end 286.426656 -57.694322)
		(width 0.0889)
		(layer "In9.Cu")
		(net "UPI_CPU1_CPU0_P1P1_DN<0>")
	)
	(arc
		(start 287.28035 -59.171586)
		(mid 287.141606 -59.029553)
		(end 286.951674 -58.971688)
		(width 0.0889)
		(layer "In9.Cu")
		(net "UPI_CPU1_CPU0_P1P1_DN<0>")
	)
	(arc
		(start 287.77438 -59.466988)
		(mid 287.488956 -59.383521)
		(end 287.28035 -59.171586)
		(width 0.0889)
		(layer "In9.Cu")
		(net "UPI_CPU1_CPU0_P1P1_DN<0>")
	)
	(arc
		(start 286.42183 -54.123336)
		(mid 286.4753 -53.928273)
		(end 286.426656 -53.731922)
		(width 0.0889)
		(layer "In9.Cu")
		(net "UPI_CPU1_CPU0_P1P1_DN<0>")
	)
	(arc
		(start 286.91205 -58.971688)
		(mid 286.416573 -58.667245)
		(end 286.42183 -58.085736)
		(width 0.0889)
		(layer "In9.Cu")
		(net "UPI_CPU1_CPU0_P1P1_DN<0>")
	)
	(arc
		(start 286.41548 -54.703218)
		(mid 286.342682 -54.412455)
		(end 286.42183 -54.123336)
		(width 0.0889)
		(layer "In9.Cu")
		(net "UPI_CPU1_CPU0_P1P1_DN<0>")
	)
	(arc
		(start 142.518384 -56.692038)
		(mid 142.374567 -56.873513)
		(end 142.174722 -56.990488)
		(width 0.0889)
		(layer "In9.Cu")
		(net "UPI_CPU1_CPU0_P1P1_DN<0>")
	)
	(arc
		(start 286.42183 -55.113936)
		(mid 286.4753 -54.918873)
		(end 286.426656 -54.722522)
		(width 0.0889)
		(layer "In9.Cu")
		(net "UPI_CPU1_CPU0_P1P1_DN<0>")
	)
	(segment
		(start 142.075916 -65.810384)
		(end 141.9352 -65.9511)
		(width 0.0889)
		(layer "F.Cu")
		(net "UPI_CPU1_CPU0_P0P0_DP<9>")
	)
	(segment
		(start 142.250414 -65.810384)
		(end 142.075916 -65.810384)
		(width 0.0889)
		(layer "F.Cu")
		(net "UPI_CPU1_CPU0_P0P0_DP<9>")
	)
	(segment
		(start 145.9738 -66.0908)
		(end 146.2024 -65.8622)
		(width 0.0889)
		(layer "F.Cu")
		(net "UPI_CPU1_CPU0_P0P0_DP<9>")
	)
	(segment
		(start 141.9352 -66.121534)
		(end 142.0241 -66.210434)
		(width 0.0889)
		(layer "F.Cu")
		(net "UPI_CPU1_CPU0_P0P0_DP<9>")
	)
	(segment
		(start 142.70736 -66.0908)
		(end 145.9738 -66.0908)
		(width 0.0889)
		(layer "F.Cu")
		(net "UPI_CPU1_CPU0_P0P0_DP<9>")
	)
	(segment
		(start 142.587726 -66.210434)
		(end 142.70736 -66.0908)
		(width 0.0889)
		(layer "F.Cu")
		(net "UPI_CPU1_CPU0_P0P0_DP<9>")
	)
	(segment
		(start 142.0241 -66.210434)
		(end 142.587726 -66.210434)
		(width 0.0889)
		(layer "F.Cu")
		(net "UPI_CPU1_CPU0_P0P0_DP<9>")
	)
	(segment
		(start 141.9352 -65.9511)
		(end 141.9352 -66.121534)
		(width 0.0889)
		(layer "F.Cu")
		(net "UPI_CPU1_CPU0_P0P0_DP<9>")
	)
	(segment
		(start 301.241206 -67.296538)
		(end 301.812706 -67.296538)
		(width 0.1143)
		(layer "F.Cu")
		(net "UPI_CPU1_CPU0_P0P0_DP<9>")
	)
	(via
		(at 301.812706 -67.296538)
		(size 0.508)
		(drill 0.254)
		(layers "F.Cu" "B.Cu")
		(net "UPI_CPU1_CPU0_P0P0_DP<9>")
	)
	(via
		(at 146.2024 -65.8622)
		(size 0.508)
		(drill 0.254)
		(layers "F.Cu" "B.Cu")
		(net "UPI_CPU1_CPU0_P0P0_DP<9>")
	)
	(segment
		(start 160.175448 -98.763582)
		(end 160.326324 -98.861372)
		(width 0.1143)
		(layer "B.Cu")
		(net "UPI_CPU1_CPU0_P0P0_DP<9>")
	)
	(segment
		(start 303.544732 -68.877688)
		(end 303.511966 -68.877688)
		(width 0.0889)
		(layer "B.Cu")
		(net "UPI_CPU1_CPU0_P0P0_DP<9>")
	)
	(segment
		(start 204.395832 -116.781834)
		(end 207.660494 -116.995702)
		(width 0.1143)
		(layer "B.Cu")
		(net "UPI_CPU1_CPU0_P0P0_DP<9>")
	)
	(segment
		(start 251.091954 -114.064796)
		(end 251.23267 -114.176048)
		(width 0.1143)
		(layer "B.Cu")
		(net "UPI_CPU1_CPU0_P0P0_DP<9>")
	)
	(segment
		(start 160.62198 -100.253038)
		(end 160.669478 -100.476812)
		(width 0.1143)
		(layer "B.Cu")
		(net "UPI_CPU1_CPU0_P0P0_DP<9>")
	)
	(segment
		(start 253.426214 -113.790984)
		(end 253.567184 -113.902236)
		(width 0.1143)
		(layer "B.Cu")
		(net "UPI_CPU1_CPU0_P0P0_DP<9>")
	)
	(segment
		(start 160.373822 -99.085146)
		(end 160.275778 -99.235768)
		(width 0.1143)
		(layer "B.Cu")
		(net "UPI_CPU1_CPU0_P0P0_DP<9>")
	)
	(segment
		(start 303.398428 -113.279174)
		(end 303.43602 -113.265966)
		(width 0.1143)
		(layer "B.Cu")
		(net "UPI_CPU1_CPU0_P0P0_DP<9>")
	)
	(segment
		(start 306.108608 -69.374258)
		(end 306.102258 -69.374258)
		(width 0.0889)
		(layer "B.Cu")
		(net "UPI_CPU1_CPU0_P0P0_DP<9>")
	)
	(segment
		(start 253.199138 -113.817654)
		(end 253.426214 -113.790984)
		(width 0.1143)
		(layer "B.Cu")
		(net "UPI_CPU1_CPU0_P0P0_DP<9>")
	)
	(segment
		(start 161.25825 -102.62362)
		(end 161.788094 -103.278178)
		(width 0.1143)
		(layer "B.Cu")
		(net "UPI_CPU1_CPU0_P0P0_DP<9>")
	)
	(segment
		(start 283.094684 -114.8588)
		(end 285.836614 -114.310414)
		(width 0.1143)
		(layer "B.Cu")
		(net "UPI_CPU1_CPU0_P0P0_DP<9>")
	)
	(segment
		(start 175.363378 -112.869218)
		(end 179.569618 -113.133124)
		(width 0.1143)
		(layer "B.Cu")
		(net "UPI_CPU1_CPU0_P0P0_DP<9>")
	)
	(segment
		(start 308.073806 -70.8025)
		(end 307.159406 -69.8881)
		(width 0.0889)
		(layer "B.Cu")
		(net "UPI_CPU1_CPU0_P0P0_DP<9>")
	)
	(segment
		(start 306.506372 -69.666866)
		(end 306.452016 -69.572886)
		(width 0.0889)
		(layer "B.Cu")
		(net "UPI_CPU1_CPU0_P0P0_DP<9>")
	)
	(segment
		(start 160.817306 -101.172518)
		(end 160.719516 -101.32314)
		(width 0.1143)
		(layer "B.Cu")
		(net "UPI_CPU1_CPU0_P0P0_DP<9>")
	)
	(segment
		(start 309.308246 -70.8025)
		(end 308.073806 -70.8025)
		(width 0.0889)
		(layer "B.Cu")
		(net "UPI_CPU1_CPU0_P0P0_DP<9>")
	)
	(segment
		(start 322.00215 -96.704404)
		(end 318.730376 -88.525096)
		(width 0.1143)
		(layer "B.Cu")
		(net "UPI_CPU1_CPU0_P0P0_DP<9>")
	)
	(segment
		(start 160.275778 -99.235768)
		(end 160.323276 -99.459288)
		(width 0.1143)
		(layer "B.Cu")
		(net "UPI_CPU1_CPU0_P0P0_DP<9>")
	)
	(segment
		(start 248.90476 -114.449098)
		(end 250.753118 -114.232436)
		(width 0.1143)
		(layer "B.Cu")
		(net "UPI_CPU1_CPU0_P0P0_DP<9>")
	)
	(segment
		(start 309.333646 -70.8279)
		(end 309.308246 -70.8025)
		(width 0.0889)
		(layer "B.Cu")
		(net "UPI_CPU1_CPU0_P0P0_DP<9>")
	)
	(segment
		(start 179.569618 -113.133124)
		(end 185.427366 -113.500408)
		(width 0.1143)
		(layer "B.Cu")
		(net "UPI_CPU1_CPU0_P0P0_DP<9>")
	)
	(segment
		(start 161.788094 -103.278178)
		(end 169.330116 -108.754164)
		(width 0.1143)
		(layer "B.Cu")
		(net "UPI_CPU1_CPU0_P0P0_DP<9>")
	)
	(segment
		(start 160.42386 -99.931728)
		(end 160.471104 -100.155248)
		(width 0.1143)
		(layer "B.Cu")
		(net "UPI_CPU1_CPU0_P0P0_DP<9>")
	)
	(segment
		(start 160.474152 -99.557078)
		(end 160.52165 -99.781106)
		(width 0.1143)
		(layer "B.Cu")
		(net "UPI_CPU1_CPU0_P0P0_DP<9>")
	)
	(segment
		(start 302.682402 -68.382134)
		(end 302.649636 -68.382134)
		(width 0.0889)
		(layer "B.Cu")
		(net "UPI_CPU1_CPU0_P0P0_DP<9>")
	)
	(segment
		(start 292.126924 -115.58651)
		(end 303.398428 -113.279174)
		(width 0.1143)
		(layer "B.Cu")
		(net "UPI_CPU1_CPU0_P0P0_DP<9>")
	)
	(segment
		(start 306.727606 -69.8881)
		(end 306.506372 -69.666866)
		(width 0.0889)
		(layer "B.Cu")
		(net "UPI_CPU1_CPU0_P0P0_DP<9>")
	)
	(segment
		(start 291.125402 -115.38331)
		(end 292.126924 -115.58651)
		(width 0.1143)
		(layer "B.Cu")
		(net "UPI_CPU1_CPU0_P0P0_DP<9>")
	)
	(segment
		(start 215.1634 -115.489228)
		(end 226.050094 -113.303558)
		(width 0.1143)
		(layer "B.Cu")
		(net "UPI_CPU1_CPU0_P0P0_DP<9>")
	)
	(segment
		(start 252.398784 -113.91138)
		(end 252.626114 -113.88471)
		(width 0.1143)
		(layer "B.Cu")
		(net "UPI_CPU1_CPU0_P0P0_DP<9>")
	)
	(segment
		(start 304.399442 -69.372734)
		(end 304.366676 -69.372734)
		(width 0.0889)
		(layer "B.Cu")
		(net "UPI_CPU1_CPU0_P0P0_DP<9>")
	)
	(segment
		(start 305.268884 -69.868034)
		(end 305.22926 -69.868034)
		(width 0.0889)
		(layer "B.Cu")
		(net "UPI_CPU1_CPU0_P0P0_DP<9>")
	)
	(segment
		(start 207.660494 -116.995702)
		(end 215.1634 -115.489228)
		(width 0.1143)
		(layer "B.Cu")
		(net "UPI_CPU1_CPU0_P0P0_DP<9>")
	)
	(segment
		(start 250.864624 -114.091466)
		(end 251.091954 -114.064796)
		(width 0.1143)
		(layer "B.Cu")
		(net "UPI_CPU1_CPU0_P0P0_DP<9>")
	)
	(segment
		(start 262.896858 -112.80902)
		(end 283.094684 -114.8588)
		(width 0.1143)
		(layer "B.Cu")
		(net "UPI_CPU1_CPU0_P0P0_DP<9>")
	)
	(segment
		(start 321.890898 -100.18014)
		(end 321.945 -98.4885)
		(width 0.1143)
		(layer "B.Cu")
		(net "UPI_CPU1_CPU0_P0P0_DP<9>")
	)
	(segment
		(start 253.087632 -113.958878)
		(end 253.199138 -113.817654)
		(width 0.1143)
		(layer "B.Cu")
		(net "UPI_CPU1_CPU0_P0P0_DP<9>")
	)
	(segment
		(start 309.62346 -70.8279)
		(end 309.333646 -70.8279)
		(width 0.1143)
		(layer "B.Cu")
		(net "UPI_CPU1_CPU0_P0P0_DP<9>")
	)
	(segment
		(start 160.571688 -100.627434)
		(end 160.618932 -100.850954)
		(width 0.1143)
		(layer "B.Cu")
		(net "UPI_CPU1_CPU0_P0P0_DP<9>")
	)
	(segment
		(start 160.902142 -102.183692)
		(end 161.25825 -102.62362)
		(width 0.1143)
		(layer "B.Cu")
		(net "UPI_CPU1_CPU0_P0P0_DP<9>")
	)
	(segment
		(start 160.618932 -100.850954)
		(end 160.769808 -100.948744)
		(width 0.1143)
		(layer "B.Cu")
		(net "UPI_CPU1_CPU0_P0P0_DP<9>")
	)
	(segment
		(start 251.23267 -114.176048)
		(end 252.287532 -114.052604)
		(width 0.1143)
		(layer "B.Cu")
		(net "UPI_CPU1_CPU0_P0P0_DP<9>")
	)
	(segment
		(start 305.22926 -69.868034)
		(end 305.229006 -69.868288)
		(width 0.0889)
		(layer "B.Cu")
		(net "UPI_CPU1_CPU0_P0P0_DP<9>")
	)
	(segment
		(start 314.028074 -72.437498)
		(end 309.62346 -70.8279)
		(width 0.1143)
		(layer "B.Cu")
		(net "UPI_CPU1_CPU0_P0P0_DP<9>")
	)
	(segment
		(start 160.719516 -101.32314)
		(end 160.902142 -102.183692)
		(width 0.1143)
		(layer "B.Cu")
		(net "UPI_CPU1_CPU0_P0P0_DP<9>")
	)
	(segment
		(start 307.951632 -111.687864)
		(end 311.627266 -109.718856)
		(width 0.1143)
		(layer "B.Cu")
		(net "UPI_CPU1_CPU0_P0P0_DP<9>")
	)
	(segment
		(start 252.626114 -113.88471)
		(end 252.767084 -113.996216)
		(width 0.1143)
		(layer "B.Cu")
		(net "UPI_CPU1_CPU0_P0P0_DP<9>")
	)
	(segment
		(start 171.051982 -110.805722)
		(end 173.820074 -112.403636)
		(width 0.1143)
		(layer "B.Cu")
		(net "UPI_CPU1_CPU0_P0P0_DP<9>")
	)
	(segment
		(start 146.2024 -65.8622)
		(end 146.390106 -66.049906)
		(width 0.1143)
		(layer "B.Cu")
		(net "UPI_CPU1_CPU0_P0P0_DP<9>")
	)
	(segment
		(start 160.52165 -99.781106)
		(end 160.42386 -99.931728)
		(width 0.1143)
		(layer "B.Cu")
		(net "UPI_CPU1_CPU0_P0P0_DP<9>")
	)
	(segment
		(start 252.767084 -113.996216)
		(end 253.087632 -113.958878)
		(width 0.1143)
		(layer "B.Cu")
		(net "UPI_CPU1_CPU0_P0P0_DP<9>")
	)
	(segment
		(start 285.836614 -114.310414)
		(end 291.125402 -115.38331)
		(width 0.1143)
		(layer "B.Cu")
		(net "UPI_CPU1_CPU0_P0P0_DP<9>")
	)
	(segment
		(start 253.567184 -113.902236)
		(end 262.896858 -112.80902)
		(width 0.1143)
		(layer "B.Cu")
		(net "UPI_CPU1_CPU0_P0P0_DP<9>")
	)
	(segment
		(start 194.69735 -117.489478)
		(end 198.04126 -117.636036)
		(width 0.1143)
		(layer "B.Cu")
		(net "UPI_CPU1_CPU0_P0P0_DP<9>")
	)
	(segment
		(start 147.813776 -66.049906)
		(end 150.701248 -68.937378)
		(width 0.1143)
		(layer "B.Cu")
		(net "UPI_CPU1_CPU0_P0P0_DP<9>")
	)
	(segment
		(start 303.43602 -113.265966)
		(end 307.951632 -111.687864)
		(width 0.1143)
		(layer "B.Cu")
		(net "UPI_CPU1_CPU0_P0P0_DP<9>")
	)
	(segment
		(start 226.050094 -113.303558)
		(end 248.90476 -114.449098)
		(width 0.1143)
		(layer "B.Cu")
		(net "UPI_CPU1_CPU0_P0P0_DP<9>")
	)
	(segment
		(start 160.323276 -99.459288)
		(end 160.474152 -99.557078)
		(width 0.1143)
		(layer "B.Cu")
		(net "UPI_CPU1_CPU0_P0P0_DP<9>")
	)
	(segment
		(start 185.427366 -113.500408)
		(end 187.564268 -115.090956)
		(width 0.1143)
		(layer "B.Cu")
		(net "UPI_CPU1_CPU0_P0P0_DP<9>")
	)
	(segment
		(start 160.471104 -100.155248)
		(end 160.62198 -100.253038)
		(width 0.1143)
		(layer "B.Cu")
		(net "UPI_CPU1_CPU0_P0P0_DP<9>")
	)
	(segment
		(start 302.088296 -67.888866)
		(end 302.074326 -67.804538)
		(width 0.0889)
		(layer "B.Cu")
		(net "UPI_CPU1_CPU0_P0P0_DP<9>")
	)
	(segment
		(start 311.627266 -109.718856)
		(end 321.890898 -100.18014)
		(width 0.1143)
		(layer "B.Cu")
		(net "UPI_CPU1_CPU0_P0P0_DP<9>")
	)
	(segment
		(start 321.945 -98.4885)
		(end 321.9704 -97.696274)
		(width 0.1143)
		(layer "B.Cu")
		(net "UPI_CPU1_CPU0_P0P0_DP<9>")
	)
	(segment
		(start 155.37688 -92.325444)
		(end 159.907478 -97.502218)
		(width 0.1143)
		(layer "B.Cu")
		(net "UPI_CPU1_CPU0_P0P0_DP<9>")
	)
	(segment
		(start 307.159406 -69.8881)
		(end 306.727606 -69.8881)
		(width 0.0889)
		(layer "B.Cu")
		(net "UPI_CPU1_CPU0_P0P0_DP<9>")
	)
	(segment
		(start 159.907478 -97.502218)
		(end 160.175448 -98.763582)
		(width 0.1143)
		(layer "B.Cu")
		(net "UPI_CPU1_CPU0_P0P0_DP<9>")
	)
	(segment
		(start 252.287532 -114.052604)
		(end 252.398784 -113.91138)
		(width 0.1143)
		(layer "B.Cu")
		(net "UPI_CPU1_CPU0_P0P0_DP<9>")
	)
	(segment
		(start 169.330116 -108.754164)
		(end 171.051982 -110.805722)
		(width 0.1143)
		(layer "B.Cu")
		(net "UPI_CPU1_CPU0_P0P0_DP<9>")
	)
	(segment
		(start 160.769808 -100.948744)
		(end 160.817306 -101.172518)
		(width 0.1143)
		(layer "B.Cu")
		(net "UPI_CPU1_CPU0_P0P0_DP<9>")
	)
	(segment
		(start 321.9704 -97.696274)
		(end 322.00215 -96.704404)
		(width 0.1143)
		(layer "B.Cu")
		(net "UPI_CPU1_CPU0_P0P0_DP<9>")
	)
	(segment
		(start 318.558926 -81.915)
		(end 318.522096 -80.499966)
		(width 0.1143)
		(layer "B.Cu")
		(net "UPI_CPU1_CPU0_P0P0_DP<9>")
	)
	(segment
		(start 160.669478 -100.476812)
		(end 160.571688 -100.627434)
		(width 0.1143)
		(layer "B.Cu")
		(net "UPI_CPU1_CPU0_P0P0_DP<9>")
	)
	(segment
		(start 160.326324 -98.861372)
		(end 160.373822 -99.085146)
		(width 0.1143)
		(layer "B.Cu")
		(net "UPI_CPU1_CPU0_P0P0_DP<9>")
	)
	(segment
		(start 198.04126 -117.636036)
		(end 204.395832 -116.781834)
		(width 0.1143)
		(layer "B.Cu")
		(net "UPI_CPU1_CPU0_P0P0_DP<9>")
	)
	(segment
		(start 150.701248 -68.937378)
		(end 155.37688 -92.325444)
		(width 0.1143)
		(layer "B.Cu")
		(net "UPI_CPU1_CPU0_P0P0_DP<9>")
	)
	(segment
		(start 173.820074 -112.403636)
		(end 175.363378 -112.869218)
		(width 0.1143)
		(layer "B.Cu")
		(net "UPI_CPU1_CPU0_P0P0_DP<9>")
	)
	(segment
		(start 146.390106 -66.049906)
		(end 147.813776 -66.049906)
		(width 0.1143)
		(layer "B.Cu")
		(net "UPI_CPU1_CPU0_P0P0_DP<9>")
	)
	(segment
		(start 250.753118 -114.232436)
		(end 250.864624 -114.091466)
		(width 0.1143)
		(layer "B.Cu")
		(net "UPI_CPU1_CPU0_P0P0_DP<9>")
	)
	(segment
		(start 318.522096 -80.499966)
		(end 314.028074 -72.437498)
		(width 0.1143)
		(layer "B.Cu")
		(net "UPI_CPU1_CPU0_P0P0_DP<9>")
	)
	(segment
		(start 187.564268 -115.090956)
		(end 194.69735 -117.489478)
		(width 0.1143)
		(layer "B.Cu")
		(net "UPI_CPU1_CPU0_P0P0_DP<9>")
	)
	(segment
		(start 318.730376 -88.525096)
		(end 318.558926 -81.915)
		(width 0.1143)
		(layer "B.Cu")
		(net "UPI_CPU1_CPU0_P0P0_DP<9>")
	)
	(arc
		(start 304.366676 -69.372734)
		(mid 304.083459 -69.288453)
		(end 303.876456 -69.077586)
		(width 0.0889)
		(layer "B.Cu")
		(net "UPI_CPU1_CPU0_P0P0_DP<9>")
	)
	(arc
		(start 306.102258 -69.374258)
		(mid 305.903774 -69.427476)
		(end 305.758596 -69.572886)
		(width 0.0889)
		(layer "B.Cu")
		(net "UPI_CPU1_CPU0_P0P0_DP<9>")
	)
	(arc
		(start 306.452016 -69.572886)
		(mid 306.306914 -69.427598)
		(end 306.108608 -69.374258)
		(width 0.0889)
		(layer "B.Cu")
		(net "UPI_CPU1_CPU0_P0P0_DP<9>")
	)
	(arc
		(start 303.876456 -69.077586)
		(mid 303.736377 -68.93485)
		(end 303.544732 -68.877688)
		(width 0.0889)
		(layer "B.Cu")
		(net "UPI_CPU1_CPU0_P0P0_DP<9>")
	)
	(arc
		(start 304.734976 -69.572886)
		(mid 304.593293 -69.429082)
		(end 304.399442 -69.372734)
		(width 0.0889)
		(layer "B.Cu")
		(net "UPI_CPU1_CPU0_P0P0_DP<9>")
	)
	(arc
		(start 305.758596 -69.572886)
		(mid 305.551842 -69.783705)
		(end 305.268884 -69.868034)
		(width 0.0889)
		(layer "B.Cu")
		(net "UPI_CPU1_CPU0_P0P0_DP<9>")
	)
	(arc
		(start 303.511966 -68.877688)
		(mid 303.226542 -68.794221)
		(end 303.017936 -68.582286)
		(width 0.0889)
		(layer "B.Cu")
		(net "UPI_CPU1_CPU0_P0P0_DP<9>")
	)
	(arc
		(start 305.229006 -69.868288)
		(mid 304.943582 -69.784821)
		(end 304.734976 -69.572886)
		(width 0.0889)
		(layer "B.Cu")
		(net "UPI_CPU1_CPU0_P0P0_DP<9>")
	)
	(arc
		(start 302.649636 -68.382134)
		(mid 302.281127 -68.235474)
		(end 302.088296 -67.888866)
		(width 0.0889)
		(layer "B.Cu")
		(net "UPI_CPU1_CPU0_P0P0_DP<9>")
	)
	(arc
		(start 302.074326 -67.804538)
		(mid 301.983192 -67.530107)
		(end 301.812706 -67.296538)
		(width 0.0889)
		(layer "B.Cu")
		(net "UPI_CPU1_CPU0_P0P0_DP<9>")
	)
	(arc
		(start 303.017936 -68.582286)
		(mid 302.876253 -68.438482)
		(end 302.682402 -68.382134)
		(width 0.0889)
		(layer "B.Cu")
		(net "UPI_CPU1_CPU0_P0P0_DP<9>")
	)
	(segment
		(start 140.533374 -64.819784)
		(end 141.104874 -64.819784)
		(width 0.1143)
		(layer "F.Cu")
		(net "UPI_CPU1_CPU0_P0P0_DP<8>")
	)
	(segment
		(start 301.241206 -69.277738)
		(end 301.812706 -69.277738)
		(width 0.1143)
		(layer "F.Cu")
		(net "UPI_CPU1_CPU0_P0P0_DP<8>")
	)
	(via
		(at 317.52794 -85.38718)
		(size 0.508)
		(drill 0.254)
		(layers "F.Cu" "B.Cu")
		(net "UPI_CPU1_CPU0_P0P0_DP<8>")
	)
	(via
		(at 141.104874 -64.819784)
		(size 0.508)
		(drill 0.254)
		(layers "F.Cu" "B.Cu")
		(net "UPI_CPU1_CPU0_P0P0_DP<8>")
	)
	(via
		(at 301.812706 -69.277738)
		(size 0.508)
		(drill 0.254)
		(layers "F.Cu" "B.Cu")
		(net "UPI_CPU1_CPU0_P0P0_DP<8>")
	)
	(segment
		(start 207.59801 -116.021358)
		(end 225.976688 -112.330992)
		(width 0.1143)
		(layer "B.Cu")
		(net "UPI_CPU1_CPU0_P0P0_DP<8>")
	)
	(segment
		(start 163.625276 -103.412036)
		(end 163.810188 -103.546402)
		(width 0.1143)
		(layer "B.Cu")
		(net "UPI_CPU1_CPU0_P0P0_DP<8>")
	)
	(segment
		(start 174.34433 -111.534702)
		(end 175.577754 -111.90732)
		(width 0.1143)
		(layer "B.Cu")
		(net "UPI_CPU1_CPU0_P0P0_DP<8>")
	)
	(segment
		(start 161.73196 -100.71608)
		(end 161.882836 -100.81387)
		(width 0.1143)
		(layer "B.Cu")
		(net "UPI_CPU1_CPU0_P0P0_DP<8>")
	)
	(segment
		(start 144.044416 -64.768984)
		(end 144.0688 -64.7446)
		(width 0.0889)
		(layer "B.Cu")
		(net "UPI_CPU1_CPU0_P0P0_DP<8>")
	)
	(segment
		(start 164.172646 -103.652574)
		(end 164.20084 -103.830374)
		(width 0.1143)
		(layer "B.Cu")
		(net "UPI_CPU1_CPU0_P0P0_DP<8>")
	)
	(segment
		(start 162.474148 -102.575868)
		(end 162.65906 -102.710234)
		(width 0.1143)
		(layer "B.Cu")
		(net "UPI_CPU1_CPU0_P0P0_DP<8>")
	)
	(segment
		(start 185.422794 -112.530636)
		(end 187.92444 -114.394234)
		(width 0.1143)
		(layer "B.Cu")
		(net "UPI_CPU1_CPU0_P0P0_DP<8>")
	)
	(segment
		(start 164.20084 -103.830374)
		(end 164.385752 -103.96474)
		(width 0.1143)
		(layer "B.Cu")
		(net "UPI_CPU1_CPU0_P0P0_DP<8>")
	)
	(segment
		(start 320.867532 -96.884236)
		(end 319.165732 -92.629482)
		(width 0.1143)
		(layer "B.Cu")
		(net "UPI_CPU1_CPU0_P0P0_DP<8>")
	)
	(segment
		(start 308.346348 -71.9582)
		(end 306.898548 -70.5104)
		(width 0.0889)
		(layer "B.Cu")
		(net "UPI_CPU1_CPU0_P0P0_DP<8>")
	)
	(segment
		(start 310.219852 -72.206866)
		(end 309.915052 -72.102218)
		(width 0.0889)
		(layer "B.Cu")
		(net "UPI_CPU1_CPU0_P0P0_DP<8>")
	)
	(segment
		(start 313.304174 -73.421494)
		(end 310.25592 -72.246744)
		(width 0.1143)
		(layer "B.Cu")
		(net "UPI_CPU1_CPU0_P0P0_DP<8>")
	)
	(segment
		(start 163.411916 -103.100124)
		(end 163.597082 -103.23449)
		(width 0.1143)
		(layer "B.Cu")
		(net "UPI_CPU1_CPU0_P0P0_DP<8>")
	)
	(segment
		(start 143.673576 -64.768984)
		(end 144.044416 -64.768984)
		(width 0.0889)
		(layer "B.Cu")
		(net "UPI_CPU1_CPU0_P0P0_DP<8>")
	)
	(segment
		(start 163.021518 -102.816406)
		(end 163.049712 -102.993952)
		(width 0.1143)
		(layer "B.Cu")
		(net "UPI_CPU1_CPU0_P0P0_DP<8>")
	)
	(segment
		(start 161.832544 -101.188266)
		(end 161.94786 -101.731826)
		(width 0.1143)
		(layer "B.Cu")
		(net "UPI_CPU1_CPU0_P0P0_DP<8>")
	)
	(segment
		(start 258.424172 -111.382048)
		(end 282.852876 -113.86185)
		(width 0.1143)
		(layer "B.Cu")
		(net "UPI_CPU1_CPU0_P0P0_DP<8>")
	)
	(segment
		(start 310.984392 -108.912152)
		(end 320.778124 -99.68865)
		(width 0.1143)
		(layer "B.Cu")
		(net "UPI_CPU1_CPU0_P0P0_DP<8>")
	)
	(segment
		(start 248.056146 -108.29417)
		(end 258.424172 -111.382048)
		(width 0.1143)
		(layer "B.Cu")
		(net "UPI_CPU1_CPU0_P0P0_DP<8>")
	)
	(segment
		(start 291.125402 -114.576352)
		(end 292.174676 -114.789966)
		(width 0.1143)
		(layer "B.Cu")
		(net "UPI_CPU1_CPU0_P0P0_DP<8>")
	)
	(segment
		(start 318.909446 -92.32392)
		(end 318.978788 -92.162122)
		(width 0.1143)
		(layer "B.Cu")
		(net "UPI_CPU1_CPU0_P0P0_DP<8>")
	)
	(segment
		(start 164.563044 -103.936546)
		(end 164.74821 -104.070912)
		(width 0.1143)
		(layer "B.Cu")
		(net "UPI_CPU1_CPU0_P0P0_DP<8>")
	)
	(segment
		(start 198.037958 -116.863622)
		(end 205.395576 -115.87734)
		(width 0.1143)
		(layer "B.Cu")
		(net "UPI_CPU1_CPU0_P0P0_DP<8>")
	)
	(segment
		(start 141.334236 -64.724788)
		(end 141.981682 -64.724788)
		(width 0.0889)
		(layer "B.Cu")
		(net "UPI_CPU1_CPU0_P0P0_DP<8>")
	)
	(segment
		(start 308.882288 -72.051164)
		(end 308.683152 -72.051164)
		(width 0.0889)
		(layer "B.Cu")
		(net "UPI_CPU1_CPU0_P0P0_DP<8>")
	)
	(segment
		(start 302.682402 -69.372734)
		(end 302.649636 -69.372734)
		(width 0.0889)
		(layer "B.Cu")
		(net "UPI_CPU1_CPU0_P0P0_DP<8>")
	)
	(segment
		(start 169.994834 -108.040678)
		(end 171.595542 -109.947456)
		(width 0.1143)
		(layer "B.Cu")
		(net "UPI_CPU1_CPU0_P0P0_DP<8>")
	)
	(segment
		(start 162.65906 -102.710234)
		(end 162.836352 -102.68204)
		(width 0.1143)
		(layer "B.Cu")
		(net "UPI_CPU1_CPU0_P0P0_DP<8>")
	)
	(segment
		(start 175.577754 -111.90732)
		(end 185.422794 -112.530636)
		(width 0.1143)
		(layer "B.Cu")
		(net "UPI_CPU1_CPU0_P0P0_DP<8>")
	)
	(segment
		(start 235.85678 -112.826292)
		(end 247.53443 -108.313728)
		(width 0.1143)
		(layer "B.Cu")
		(net "UPI_CPU1_CPU0_P0P0_DP<8>")
	)
	(segment
		(start 162.836352 -102.68204)
		(end 163.021518 -102.816406)
		(width 0.1143)
		(layer "B.Cu")
		(net "UPI_CPU1_CPU0_P0P0_DP<8>")
	)
	(segment
		(start 306.2732 -70.363334)
		(end 306.09413 -70.363334)
		(width 0.0889)
		(layer "B.Cu")
		(net "UPI_CPU1_CPU0_P0P0_DP<8>")
	)
	(segment
		(start 247.53443 -108.313728)
		(end 248.056146 -108.29417)
		(width 0.1143)
		(layer "B.Cu")
		(net "UPI_CPU1_CPU0_P0P0_DP<8>")
	)
	(segment
		(start 310.25592 -72.246744)
		(end 310.219852 -72.206866)
		(width 0.0889)
		(layer "B.Cu")
		(net "UPI_CPU1_CPU0_P0P0_DP<8>")
	)
	(segment
		(start 164.74821 -104.070912)
		(end 164.776404 -104.248458)
		(width 0.1143)
		(layer "B.Cu")
		(net "UPI_CPU1_CPU0_P0P0_DP<8>")
	)
	(segment
		(start 317.52794 -85.38718)
		(end 317.40856 -80.784954)
		(width 0.1143)
		(layer "B.Cu")
		(net "UPI_CPU1_CPU0_P0P0_DP<8>")
	)
	(segment
		(start 187.92444 -114.394234)
		(end 194.880484 -116.733574)
		(width 0.1143)
		(layer "B.Cu")
		(net "UPI_CPU1_CPU0_P0P0_DP<8>")
	)
	(segment
		(start 163.361624 -103.107998)
		(end 163.411916 -103.100124)
		(width 0.1143)
		(layer "B.Cu")
		(net "UPI_CPU1_CPU0_P0P0_DP<8>")
	)
	(segment
		(start 317.40856 -80.784954)
		(end 313.304174 -73.421494)
		(width 0.1143)
		(layer "B.Cu")
		(net "UPI_CPU1_CPU0_P0P0_DP<8>")
	)
	(segment
		(start 162.068256 -102.075488)
		(end 162.474148 -102.575868)
		(width 0.1143)
		(layer "B.Cu")
		(net "UPI_CPU1_CPU0_P0P0_DP<8>")
	)
	(segment
		(start 165.515798 -104.785668)
		(end 169.994834 -108.040678)
		(width 0.1143)
		(layer "B.Cu")
		(net "UPI_CPU1_CPU0_P0P0_DP<8>")
	)
	(segment
		(start 163.049712 -102.993952)
		(end 163.234624 -103.128318)
		(width 0.1143)
		(layer "B.Cu")
		(net "UPI_CPU1_CPU0_P0P0_DP<8>")
	)
	(segment
		(start 225.976688 -112.330992)
		(end 235.85678 -112.826292)
		(width 0.1143)
		(layer "B.Cu")
		(net "UPI_CPU1_CPU0_P0P0_DP<8>")
	)
	(segment
		(start 303.54778 -69.868288)
		(end 303.511966 -69.868288)
		(width 0.0889)
		(layer "B.Cu")
		(net "UPI_CPU1_CPU0_P0P0_DP<8>")
	)
	(segment
		(start 171.595542 -109.947456)
		(end 174.34433 -111.534702)
		(width 0.1143)
		(layer "B.Cu")
		(net "UPI_CPU1_CPU0_P0P0_DP<8>")
	)
	(segment
		(start 163.234624 -103.128318)
		(end 163.361624 -103.107998)
		(width 0.1143)
		(layer "B.Cu")
		(net "UPI_CPU1_CPU0_P0P0_DP<8>")
	)
	(segment
		(start 292.174676 -114.789966)
		(end 302.445928 -112.669574)
		(width 0.1143)
		(layer "B.Cu")
		(net "UPI_CPU1_CPU0_P0P0_DP<8>")
	)
	(segment
		(start 164.385752 -103.96474)
		(end 164.563044 -103.936546)
		(width 0.1143)
		(layer "B.Cu")
		(net "UPI_CPU1_CPU0_P0P0_DP<8>")
	)
	(segment
		(start 163.810188 -103.546402)
		(end 163.98748 -103.518208)
		(width 0.1143)
		(layer "B.Cu")
		(net "UPI_CPU1_CPU0_P0P0_DP<8>")
	)
	(segment
		(start 147.61591 -64.7446)
		(end 151.43353 -68.56222)
		(width 0.1143)
		(layer "B.Cu")
		(net "UPI_CPU1_CPU0_P0P0_DP<8>")
	)
	(segment
		(start 301.870618 -68.881752)
		(end 301.812706 -68.939664)
		(width 0.0889)
		(layer "B.Cu")
		(net "UPI_CPU1_CPU0_P0P0_DP<8>")
	)
	(segment
		(start 308.975252 -71.9582)
		(end 308.882288 -72.051164)
		(width 0.0889)
		(layer "B.Cu")
		(net "UPI_CPU1_CPU0_P0P0_DP<8>")
	)
	(segment
		(start 301.812706 -68.939664)
		(end 301.812706 -69.277738)
		(width 0.0889)
		(layer "B.Cu")
		(net "UPI_CPU1_CPU0_P0P0_DP<8>")
	)
	(segment
		(start 306.703476 -111.150146)
		(end 310.984392 -108.912152)
		(width 0.1143)
		(layer "B.Cu")
		(net "UPI_CPU1_CPU0_P0P0_DP<8>")
	)
	(segment
		(start 319.165732 -92.629482)
		(end 319.003934 -92.56014)
		(width 0.1143)
		(layer "B.Cu")
		(net "UPI_CPU1_CPU0_P0P0_DP<8>")
	)
	(segment
		(start 205.395576 -115.87734)
		(end 207.597248 -116.021358)
		(width 0.1143)
		(layer "B.Cu")
		(net "UPI_CPU1_CPU0_P0P0_DP<8>")
	)
	(segment
		(start 309.20309 -71.9582)
		(end 308.975252 -71.9582)
		(width 0.0889)
		(layer "B.Cu")
		(net "UPI_CPU1_CPU0_P0P0_DP<8>")
	)
	(segment
		(start 143.213836 -65.228724)
		(end 143.673576 -64.768984)
		(width 0.0889)
		(layer "B.Cu")
		(net "UPI_CPU1_CPU0_P0P0_DP<8>")
	)
	(segment
		(start 282.852876 -113.86185)
		(end 285.257748 -113.381282)
		(width 0.1143)
		(layer "B.Cu")
		(net "UPI_CPU1_CPU0_P0P0_DP<8>")
	)
	(segment
		(start 161.94786 -101.731826)
		(end 162.068256 -102.075488)
		(width 0.1143)
		(layer "B.Cu")
		(net "UPI_CPU1_CPU0_P0P0_DP<8>")
	)
	(segment
		(start 308.590188 -71.9582)
		(end 308.346348 -71.9582)
		(width 0.0889)
		(layer "B.Cu")
		(net "UPI_CPU1_CPU0_P0P0_DP<8>")
	)
	(segment
		(start 320.778124 -99.68865)
		(end 320.867532 -96.884236)
		(width 0.1143)
		(layer "B.Cu")
		(net "UPI_CPU1_CPU0_P0P0_DP<8>")
	)
	(segment
		(start 304.399442 -70.363334)
		(end 304.366676 -70.363334)
		(width 0.0889)
		(layer "B.Cu")
		(net "UPI_CPU1_CPU0_P0P0_DP<8>")
	)
	(segment
		(start 302.445928 -112.669574)
		(end 306.703476 -111.150146)
		(width 0.1143)
		(layer "B.Cu")
		(net "UPI_CPU1_CPU0_P0P0_DP<8>")
	)
	(segment
		(start 319.003934 -92.56014)
		(end 318.909446 -92.32392)
		(width 0.1143)
		(layer "B.Cu")
		(net "UPI_CPU1_CPU0_P0P0_DP<8>")
	)
	(segment
		(start 161.002472 -97.284286)
		(end 161.73196 -100.71608)
		(width 0.1143)
		(layer "B.Cu")
		(net "UPI_CPU1_CPU0_P0P0_DP<8>")
	)
	(segment
		(start 156.046424 -91.621102)
		(end 161.002472 -97.284286)
		(width 0.1143)
		(layer "B.Cu")
		(net "UPI_CPU1_CPU0_P0P0_DP<8>")
	)
	(segment
		(start 142.836392 -65.228724)
		(end 143.213836 -65.228724)
		(width 0.0889)
		(layer "B.Cu")
		(net "UPI_CPU1_CPU0_P0P0_DP<8>")
	)
	(segment
		(start 163.98748 -103.518208)
		(end 164.172646 -103.652574)
		(width 0.1143)
		(layer "B.Cu")
		(net "UPI_CPU1_CPU0_P0P0_DP<8>")
	)
	(segment
		(start 194.880484 -116.733574)
		(end 198.037958 -116.863368)
		(width 0.1143)
		(layer "B.Cu")
		(net "UPI_CPU1_CPU0_P0P0_DP<8>")
	)
	(segment
		(start 151.43353 -68.56222)
		(end 156.046424 -91.621102)
		(width 0.1143)
		(layer "B.Cu")
		(net "UPI_CPU1_CPU0_P0P0_DP<8>")
	)
	(segment
		(start 198.037958 -116.863368)
		(end 198.037958 -116.863622)
		(width 0.1143)
		(layer "B.Cu")
		(net "UPI_CPU1_CPU0_P0P0_DP<8>")
	)
	(segment
		(start 161.930334 -101.037644)
		(end 161.832544 -101.188266)
		(width 0.1143)
		(layer "B.Cu")
		(net "UPI_CPU1_CPU0_P0P0_DP<8>")
	)
	(segment
		(start 308.683152 -72.051164)
		(end 308.590188 -71.9582)
		(width 0.0889)
		(layer "B.Cu")
		(net "UPI_CPU1_CPU0_P0P0_DP<8>")
	)
	(segment
		(start 306.420266 -70.5104)
		(end 306.2732 -70.363334)
		(width 0.0889)
		(layer "B.Cu")
		(net "UPI_CPU1_CPU0_P0P0_DP<8>")
	)
	(segment
		(start 306.898548 -70.5104)
		(end 306.420266 -70.5104)
		(width 0.0889)
		(layer "B.Cu")
		(net "UPI_CPU1_CPU0_P0P0_DP<8>")
	)
	(segment
		(start 144.0688 -64.7446)
		(end 144.07896 -64.7446)
		(width 0.0889)
		(layer "B.Cu")
		(net "UPI_CPU1_CPU0_P0P0_DP<8>")
	)
	(segment
		(start 144.07896 -64.7446)
		(end 147.61591 -64.7446)
		(width 0.1143)
		(layer "B.Cu")
		(net "UPI_CPU1_CPU0_P0P0_DP<8>")
	)
	(segment
		(start 161.882836 -100.81387)
		(end 161.930334 -101.037644)
		(width 0.1143)
		(layer "B.Cu")
		(net "UPI_CPU1_CPU0_P0P0_DP<8>")
	)
	(segment
		(start 309.915052 -72.102218)
		(end 309.20309 -71.9582)
		(width 0.0889)
		(layer "B.Cu")
		(net "UPI_CPU1_CPU0_P0P0_DP<8>")
	)
	(segment
		(start 207.597248 -116.021358)
		(end 207.59801 -116.021358)
		(width 0.1143)
		(layer "B.Cu")
		(net "UPI_CPU1_CPU0_P0P0_DP<8>")
	)
	(segment
		(start 285.257748 -113.381282)
		(end 291.125402 -114.576352)
		(width 0.1143)
		(layer "B.Cu")
		(net "UPI_CPU1_CPU0_P0P0_DP<8>")
	)
	(segment
		(start 318.978788 -92.162122)
		(end 317.615316 -88.752934)
		(width 0.1143)
		(layer "B.Cu")
		(net "UPI_CPU1_CPU0_P0P0_DP<8>")
	)
	(segment
		(start 317.615316 -88.752934)
		(end 317.52794 -85.38718)
		(width 0.1143)
		(layer "B.Cu")
		(net "UPI_CPU1_CPU0_P0P0_DP<8>")
	)
	(segment
		(start 163.597082 -103.23449)
		(end 163.625276 -103.412036)
		(width 0.1143)
		(layer "B.Cu")
		(net "UPI_CPU1_CPU0_P0P0_DP<8>")
	)
	(segment
		(start 164.776404 -104.248458)
		(end 165.515798 -104.785668)
		(width 0.1143)
		(layer "B.Cu")
		(net "UPI_CPU1_CPU0_P0P0_DP<8>")
	)
	(arc
		(start 141.104874 -64.819784)
		(mid 141.210106 -64.74947)
		(end 141.334236 -64.724788)
		(width 0.0889)
		(layer "B.Cu")
		(net "UPI_CPU1_CPU0_P0P0_DP<8>")
	)
	(arc
		(start 142.475204 -65.019936)
		(mid 142.627839 -65.172687)
		(end 142.836392 -65.228724)
		(width 0.0889)
		(layer "B.Cu")
		(net "UPI_CPU1_CPU0_P0P0_DP<8>")
	)
	(arc
		(start 305.758596 -70.563486)
		(mid 305.246786 -70.859025)
		(end 304.734976 -70.563486)
		(width 0.0889)
		(layer "B.Cu")
		(net "UPI_CPU1_CPU0_P0P0_DP<8>")
	)
	(arc
		(start 303.017936 -69.572886)
		(mid 302.876253 -69.429082)
		(end 302.682402 -69.372734)
		(width 0.0889)
		(layer "B.Cu")
		(net "UPI_CPU1_CPU0_P0P0_DP<8>")
	)
	(arc
		(start 306.09413 -70.363334)
		(mid 305.90028 -70.419684)
		(end 305.758596 -70.563486)
		(width 0.0889)
		(layer "B.Cu")
		(net "UPI_CPU1_CPU0_P0P0_DP<8>")
	)
	(arc
		(start 302.649636 -69.372734)
		(mid 302.366419 -69.288453)
		(end 302.159416 -69.077586)
		(width 0.0889)
		(layer "B.Cu")
		(net "UPI_CPU1_CPU0_P0P0_DP<8>")
	)
	(arc
		(start 303.876456 -70.068186)
		(mid 303.737712 -69.926153)
		(end 303.54778 -69.868288)
		(width 0.0889)
		(layer "B.Cu")
		(net "UPI_CPU1_CPU0_P0P0_DP<8>")
	)
	(arc
		(start 304.366676 -70.363334)
		(mid 304.083459 -70.279053)
		(end 303.876456 -70.068186)
		(width 0.0889)
		(layer "B.Cu")
		(net "UPI_CPU1_CPU0_P0P0_DP<8>")
	)
	(arc
		(start 302.159416 -69.077586)
		(mid 302.037471 -68.946554)
		(end 301.870618 -68.881752)
		(width 0.0889)
		(layer "B.Cu")
		(net "UPI_CPU1_CPU0_P0P0_DP<8>")
	)
	(arc
		(start 141.981682 -64.724788)
		(mid 142.266729 -64.808316)
		(end 142.475204 -65.019936)
		(width 0.0889)
		(layer "B.Cu")
		(net "UPI_CPU1_CPU0_P0P0_DP<8>")
	)
	(arc
		(start 303.511966 -69.868288)
		(mid 303.226542 -69.784821)
		(end 303.017936 -69.572886)
		(width 0.0889)
		(layer "B.Cu")
		(net "UPI_CPU1_CPU0_P0P0_DP<8>")
	)
	(arc
		(start 304.734976 -70.563486)
		(mid 304.593293 -70.419682)
		(end 304.399442 -70.363334)
		(width 0.0889)
		(layer "B.Cu")
		(net "UPI_CPU1_CPU0_P0P0_DP<8>")
	)
	(segment
		(start 300.382686 -68.782184)
		(end 300.954186 -68.782184)
		(width 0.1143)
		(layer "F.Cu")
		(net "UPI_CPU1_CPU0_P0P0_DP<7>")
	)
	(segment
		(start 141.391894 -64.324738)
		(end 141.963394 -64.324738)
		(width 0.1143)
		(layer "F.Cu")
		(net "UPI_CPU1_CPU0_P0P0_DP<7>")
	)
	(via
		(at 300.954186 -68.782184)
		(size 0.508)
		(drill 0.254)
		(layers "F.Cu" "B.Cu")
		(net "UPI_CPU1_CPU0_P0P0_DP<7>")
	)
	(via
		(at 141.963394 -64.324738)
		(size 0.508)
		(drill 0.254)
		(layers "F.Cu" "B.Cu")
		(net "UPI_CPU1_CPU0_P0P0_DP<7>")
	)
	(via
		(at 162.079432 -97.883472)
		(size 0.508)
		(drill 0.254)
		(layers "F.Cu" "B.Cu")
		(net "UPI_CPU1_CPU0_P0P0_DP<7>")
	)
	(segment
		(start 144.52346 -63.942722)
		(end 144.49806 -63.917322)
		(width 0.0889)
		(layer "B.Cu")
		(net "UPI_CPU1_CPU0_P0P0_DP<7>")
	)
	(segment
		(start 316.897258 -95.465646)
		(end 316.836298 -93.118686)
		(width 0.1143)
		(layer "B.Cu")
		(net "UPI_CPU1_CPU0_P0P0_DP<7>")
	)
	(segment
		(start 308.4322 -72.7456)
		(end 308.397148 -72.7456)
		(width 0.0889)
		(layer "B.Cu")
		(net "UPI_CPU1_CPU0_P0P0_DP<7>")
	)
	(segment
		(start 151.916638 -68.28663)
		(end 147.57273 -63.942722)
		(width 0.1143)
		(layer "B.Cu")
		(net "UPI_CPU1_CPU0_P0P0_DP<7>")
	)
	(segment
		(start 141.963394 -63.986664)
		(end 141.963394 -64.324738)
		(width 0.0889)
		(layer "B.Cu")
		(net "UPI_CPU1_CPU0_P0P0_DP<7>")
	)
	(segment
		(start 306.405026 -110.516924)
		(end 310.45277 -108.210096)
		(width 0.1143)
		(layer "B.Cu")
		(net "UPI_CPU1_CPU0_P0P0_DP<7>")
	)
	(segment
		(start 162.079432 -97.883472)
		(end 161.913062 -97.222564)
		(width 0.1143)
		(layer "B.Cu")
		(net "UPI_CPU1_CPU0_P0P0_DP<7>")
	)
	(segment
		(start 308.5846 -72.898)
		(end 308.4322 -72.7456)
		(width 0.1143)
		(layer "B.Cu")
		(net "UPI_CPU1_CPU0_P0P0_DP<7>")
	)
	(segment
		(start 300.971966 -69.182234)
		(end 300.9392 -69.182234)
		(width 0.0889)
		(layer "B.Cu")
		(net "UPI_CPU1_CPU0_P0P0_DP<7>")
	)
	(segment
		(start 286.161734 -112.447578)
		(end 290.481258 -109.168184)
		(width 0.1143)
		(layer "B.Cu")
		(net "UPI_CPU1_CPU0_P0P0_DP<7>")
	)
	(segment
		(start 206.376778 -115.213638)
		(end 207.54848 -115.290346)
		(width 0.1143)
		(layer "B.Cu")
		(net "UPI_CPU1_CPU0_P0P0_DP<7>")
	)
	(segment
		(start 194.988434 -116.207032)
		(end 197.988174 -116.33708)
		(width 0.1143)
		(layer "B.Cu")
		(net "UPI_CPU1_CPU0_P0P0_DP<7>")
	)
	(segment
		(start 316.521338 -80.99298)
		(end 312.688732 -74.116184)
		(width 0.1143)
		(layer "B.Cu")
		(net "UPI_CPU1_CPU0_P0P0_DP<7>")
	)
	(segment
		(start 308.397148 -72.7456)
		(end 307.921914 -72.270366)
		(width 0.0889)
		(layer "B.Cu")
		(net "UPI_CPU1_CPU0_P0P0_DP<7>")
	)
	(segment
		(start 306.161186 -71.163688)
		(end 306.10429 -71.163688)
		(width 0.0889)
		(layer "B.Cu")
		(net "UPI_CPU1_CPU0_P0P0_DP<7>")
	)
	(segment
		(start 303.5427 -70.668134)
		(end 303.51857 -70.668134)
		(width 0.0889)
		(layer "B.Cu")
		(net "UPI_CPU1_CPU0_P0P0_DP<7>")
	)
	(segment
		(start 304.401982 -71.163434)
		(end 304.37328 -71.163434)
		(width 0.0889)
		(layer "B.Cu")
		(net "UPI_CPU1_CPU0_P0P0_DP<7>")
	)
	(segment
		(start 185.718196 -111.819436)
		(end 186.003946 -111.837724)
		(width 0.1143)
		(layer "B.Cu")
		(net "UPI_CPU1_CPU0_P0P0_DP<7>")
	)
	(segment
		(start 189.324742 -114.302286)
		(end 194.988434 -116.207032)
		(width 0.1143)
		(layer "B.Cu")
		(net "UPI_CPU1_CPU0_P0P0_DP<7>")
	)
	(segment
		(start 162.800284 -100.748592)
		(end 166.010082 -104.061514)
		(width 0.1143)
		(layer "B.Cu")
		(net "UPI_CPU1_CPU0_P0P0_DP<7>")
	)
	(segment
		(start 316.836298 -93.118686)
		(end 316.836552 -93.118686)
		(width 0.1143)
		(layer "B.Cu")
		(net "UPI_CPU1_CPU0_P0P0_DP<7>")
	)
	(segment
		(start 143.762222 -63.917322)
		(end 143.25981 -64.419734)
		(width 0.0889)
		(layer "B.Cu")
		(net "UPI_CPU1_CPU0_P0P0_DP<7>")
	)
	(segment
		(start 235.739432 -112.09274)
		(end 246.967756 -107.753658)
		(width 0.1143)
		(layer "B.Cu")
		(net "UPI_CPU1_CPU0_P0P0_DP<7>")
	)
	(segment
		(start 290.481258 -109.168184)
		(end 291.125402 -109.021372)
		(width 0.1143)
		(layer "B.Cu")
		(net "UPI_CPU1_CPU0_P0P0_DP<7>")
	)
	(segment
		(start 178.17084 -111.339884)
		(end 185.718196 -111.819436)
		(width 0.1143)
		(layer "B.Cu")
		(net "UPI_CPU1_CPU0_P0P0_DP<7>")
	)
	(segment
		(start 162.079432 -97.883472)
		(end 162.800284 -100.748592)
		(width 0.1143)
		(layer "B.Cu")
		(net "UPI_CPU1_CPU0_P0P0_DP<7>")
	)
	(segment
		(start 142.02537 -63.924688)
		(end 141.963394 -63.986664)
		(width 0.0889)
		(layer "B.Cu")
		(net "UPI_CPU1_CPU0_P0P0_DP<7>")
	)
	(segment
		(start 316.836552 -93.118686)
		(end 316.538864 -81.664048)
		(width 0.1143)
		(layer "B.Cu")
		(net "UPI_CPU1_CPU0_P0P0_DP<7>")
	)
	(segment
		(start 305.24704 -71.658988)
		(end 305.246532 -71.658988)
		(width 0.0889)
		(layer "B.Cu")
		(net "UPI_CPU1_CPU0_P0P0_DP<7>")
	)
	(segment
		(start 161.913062 -97.222564)
		(end 156.450284 -90.979752)
		(width 0.1143)
		(layer "B.Cu")
		(net "UPI_CPU1_CPU0_P0P0_DP<7>")
	)
	(segment
		(start 300.764956 -68.782184)
		(end 300.954186 -68.782184)
		(width 0.0889)
		(layer "B.Cu")
		(net "UPI_CPU1_CPU0_P0P0_DP<7>")
	)
	(segment
		(start 301.834296 -69.677534)
		(end 301.794672 -69.677534)
		(width 0.0889)
		(layer "B.Cu")
		(net "UPI_CPU1_CPU0_P0P0_DP<7>")
	)
	(segment
		(start 175.442372 -108.831126)
		(end 178.17084 -111.339884)
		(width 0.1143)
		(layer "B.Cu")
		(net "UPI_CPU1_CPU0_P0P0_DP<7>")
	)
	(segment
		(start 207.54848 -115.290346)
		(end 225.92284 -111.600742)
		(width 0.1143)
		(layer "B.Cu")
		(net "UPI_CPU1_CPU0_P0P0_DP<7>")
	)
	(segment
		(start 316.538356 -81.663794)
		(end 316.521338 -80.99298)
		(width 0.1143)
		(layer "B.Cu")
		(net "UPI_CPU1_CPU0_P0P0_DP<7>")
	)
	(segment
		(start 316.177676 -96.467676)
		(end 316.897258 -95.465646)
		(width 0.1143)
		(layer "B.Cu")
		(net "UPI_CPU1_CPU0_P0P0_DP<7>")
	)
	(segment
		(start 310.48071 -108.18114)
		(end 314.184284 -104.329738)
		(width 0.1143)
		(layer "B.Cu")
		(net "UPI_CPU1_CPU0_P0P0_DP<7>")
	)
	(segment
		(start 246.967756 -107.753658)
		(end 248.611898 -107.69219)
		(width 0.1143)
		(layer "B.Cu")
		(net "UPI_CPU1_CPU0_P0P0_DP<7>")
	)
	(segment
		(start 310.45277 -108.210096)
		(end 310.48071 -108.18114)
		(width 0.1143)
		(layer "B.Cu")
		(net "UPI_CPU1_CPU0_P0P0_DP<7>")
	)
	(segment
		(start 188.442346 -113.195862)
		(end 188.9252 -113.801398)
		(width 0.1143)
		(layer "B.Cu")
		(net "UPI_CPU1_CPU0_P0P0_DP<7>")
	)
	(segment
		(start 303.633632 -111.384842)
		(end 306.405026 -110.516924)
		(width 0.1143)
		(layer "B.Cu")
		(net "UPI_CPU1_CPU0_P0P0_DP<7>")
	)
	(segment
		(start 144.49806 -63.917322)
		(end 143.762222 -63.917322)
		(width 0.0889)
		(layer "B.Cu")
		(net "UPI_CPU1_CPU0_P0P0_DP<7>")
	)
	(segment
		(start 282.777946 -113.123726)
		(end 286.161734 -112.447578)
		(width 0.1143)
		(layer "B.Cu")
		(net "UPI_CPU1_CPU0_P0P0_DP<7>")
	)
	(segment
		(start 307.92166 -72.270366)
		(end 307.310282 -71.658988)
		(width 0.0889)
		(layer "B.Cu")
		(net "UPI_CPU1_CPU0_P0P0_DP<7>")
	)
	(segment
		(start 314.184284 -104.329738)
		(end 315.174122 -99.224846)
		(width 0.1143)
		(layer "B.Cu")
		(net "UPI_CPU1_CPU0_P0P0_DP<7>")
	)
	(segment
		(start 186.003946 -111.837724)
		(end 188.442346 -113.195862)
		(width 0.1143)
		(layer "B.Cu")
		(net "UPI_CPU1_CPU0_P0P0_DP<7>")
	)
	(segment
		(start 142.130272 -63.924688)
		(end 142.02537 -63.924688)
		(width 0.0889)
		(layer "B.Cu")
		(net "UPI_CPU1_CPU0_P0P0_DP<7>")
	)
	(segment
		(start 315.43879 -97.496884)
		(end 316.177676 -96.467676)
		(width 0.1143)
		(layer "B.Cu")
		(net "UPI_CPU1_CPU0_P0P0_DP<7>")
	)
	(segment
		(start 156.450284 -90.979752)
		(end 151.916638 -68.28663)
		(width 0.1143)
		(layer "B.Cu")
		(net "UPI_CPU1_CPU0_P0P0_DP<7>")
	)
	(segment
		(start 258.61137 -110.671102)
		(end 282.777946 -113.123726)
		(width 0.1143)
		(layer "B.Cu")
		(net "UPI_CPU1_CPU0_P0P0_DP<7>")
	)
	(segment
		(start 248.611898 -107.69219)
		(end 258.61137 -110.671102)
		(width 0.1143)
		(layer "B.Cu")
		(net "UPI_CPU1_CPU0_P0P0_DP<7>")
	)
	(segment
		(start 143.25981 -64.419734)
		(end 142.696438 -64.419734)
		(width 0.0889)
		(layer "B.Cu")
		(net "UPI_CPU1_CPU0_P0P0_DP<7>")
	)
	(segment
		(start 312.688732 -74.116184)
		(end 309.355236 -72.898)
		(width 0.1143)
		(layer "B.Cu")
		(net "UPI_CPU1_CPU0_P0P0_DP<7>")
	)
	(segment
		(start 316.538864 -81.664048)
		(end 316.538356 -81.663794)
		(width 0.1143)
		(layer "B.Cu")
		(net "UPI_CPU1_CPU0_P0P0_DP<7>")
	)
	(segment
		(start 315.174122 -99.224846)
		(end 315.43879 -97.496884)
		(width 0.1143)
		(layer "B.Cu")
		(net "UPI_CPU1_CPU0_P0P0_DP<7>")
	)
	(segment
		(start 169.769536 -106.890058)
		(end 175.442372 -108.831126)
		(width 0.1143)
		(layer "B.Cu")
		(net "UPI_CPU1_CPU0_P0P0_DP<7>")
	)
	(segment
		(start 292.143688 -108.789216)
		(end 303.633632 -111.384842)
		(width 0.1143)
		(layer "B.Cu")
		(net "UPI_CPU1_CPU0_P0P0_DP<7>")
	)
	(segment
		(start 309.355236 -72.898)
		(end 308.5846 -72.898)
		(width 0.1143)
		(layer "B.Cu")
		(net "UPI_CPU1_CPU0_P0P0_DP<7>")
	)
	(segment
		(start 307.921914 -72.270366)
		(end 307.92166 -72.270366)
		(width 0.0889)
		(layer "B.Cu")
		(net "UPI_CPU1_CPU0_P0P0_DP<7>")
	)
	(segment
		(start 300.765464 -69.13499)
		(end 300.686978 -69.092826)
		(width 0.0889)
		(layer "B.Cu")
		(net "UPI_CPU1_CPU0_P0P0_DP<7>")
	)
	(segment
		(start 302.692816 -70.172834)
		(end 302.66005 -70.172834)
		(width 0.0889)
		(layer "B.Cu")
		(net "UPI_CPU1_CPU0_P0P0_DP<7>")
	)
	(segment
		(start 225.92284 -111.600742)
		(end 235.739432 -112.09274)
		(width 0.1143)
		(layer "B.Cu")
		(net "UPI_CPU1_CPU0_P0P0_DP<7>")
	)
	(segment
		(start 166.010082 -104.061514)
		(end 169.769536 -106.890058)
		(width 0.1143)
		(layer "B.Cu")
		(net "UPI_CPU1_CPU0_P0P0_DP<7>")
	)
	(segment
		(start 147.57273 -63.942722)
		(end 144.52346 -63.942722)
		(width 0.1143)
		(layer "B.Cu")
		(net "UPI_CPU1_CPU0_P0P0_DP<7>")
	)
	(segment
		(start 291.125402 -109.021372)
		(end 292.143688 -108.789216)
		(width 0.1143)
		(layer "B.Cu")
		(net "UPI_CPU1_CPU0_P0P0_DP<7>")
	)
	(segment
		(start 197.988174 -116.33708)
		(end 206.376778 -115.213638)
		(width 0.1143)
		(layer "B.Cu")
		(net "UPI_CPU1_CPU0_P0P0_DP<7>")
	)
	(segment
		(start 188.9252 -113.801398)
		(end 189.324742 -114.302286)
		(width 0.1143)
		(layer "B.Cu")
		(net "UPI_CPU1_CPU0_P0P0_DP<7>")
	)
	(segment
		(start 142.34668 -64.121538)
		(end 142.346426 -64.121792)
		(width 0.0889)
		(layer "B.Cu")
		(net "UPI_CPU1_CPU0_P0P0_DP<7>")
	)
	(segment
		(start 307.310282 -71.658988)
		(end 306.872132 -71.658988)
		(width 0.0889)
		(layer "B.Cu")
		(net "UPI_CPU1_CPU0_P0P0_DP<7>")
	)
	(arc
		(start 301.794672 -69.677534)
		(mid 301.604743 -69.619664)
		(end 301.465996 -69.477636)
		(width 0.0889)
		(layer "B.Cu")
		(net "UPI_CPU1_CPU0_P0P0_DP<7>")
	)
	(arc
		(start 303.51857 -70.668134)
		(mid 303.32472 -70.611784)
		(end 303.183036 -70.467982)
		(width 0.0889)
		(layer "B.Cu")
		(net "UPI_CPU1_CPU0_P0P0_DP<7>")
	)
	(arc
		(start 304.37328 -71.163434)
		(mid 304.181638 -71.106268)
		(end 304.041556 -70.963536)
		(width 0.0889)
		(layer "B.Cu")
		(net "UPI_CPU1_CPU0_P0P0_DP<7>")
	)
	(arc
		(start 305.593496 -71.458836)
		(mid 305.447114 -71.6054)
		(end 305.24704 -71.658988)
		(width 0.0889)
		(layer "B.Cu")
		(net "UPI_CPU1_CPU0_P0P0_DP<7>")
	)
	(arc
		(start 305.246532 -71.658988)
		(mid 305.046491 -71.605343)
		(end 304.900076 -71.458836)
		(width 0.0889)
		(layer "B.Cu")
		(net "UPI_CPU1_CPU0_P0P0_DP<7>")
	)
	(arc
		(start 302.324516 -69.972682)
		(mid 302.117512 -69.761818)
		(end 301.834296 -69.677534)
		(width 0.0889)
		(layer "B.Cu")
		(net "UPI_CPU1_CPU0_P0P0_DP<7>")
	)
	(arc
		(start 300.9392 -69.182234)
		(mid 300.849642 -69.168505)
		(end 300.765464 -69.13499)
		(width 0.0889)
		(layer "B.Cu")
		(net "UPI_CPU1_CPU0_P0P0_DP<7>")
	)
	(arc
		(start 306.872132 -71.658988)
		(mid 306.747376 -71.579226)
		(end 306.65674 -71.462138)
		(width 0.0889)
		(layer "B.Cu")
		(net "UPI_CPU1_CPU0_P0P0_DP<7>")
	)
	(arc
		(start 303.183036 -70.467982)
		(mid 302.976032 -70.257118)
		(end 302.692816 -70.172834)
		(width 0.0889)
		(layer "B.Cu")
		(net "UPI_CPU1_CPU0_P0P0_DP<7>")
	)
	(arc
		(start 142.346426 -64.121792)
		(mid 142.255482 -64.004449)
		(end 142.130272 -63.924688)
		(width 0.0889)
		(layer "B.Cu")
		(net "UPI_CPU1_CPU0_P0P0_DP<7>")
	)
	(arc
		(start 306.65674 -71.462138)
		(mid 306.450389 -71.244131)
		(end 306.161186 -71.163688)
		(width 0.0889)
		(layer "B.Cu")
		(net "UPI_CPU1_CPU0_P0P0_DP<7>")
	)
	(arc
		(start 304.900076 -71.458836)
		(mid 304.689723 -71.245864)
		(end 304.401982 -71.163434)
		(width 0.0889)
		(layer "B.Cu")
		(net "UPI_CPU1_CPU0_P0P0_DP<7>")
	)
	(arc
		(start 301.465996 -69.477636)
		(mid 301.257388 -69.265704)
		(end 300.971966 -69.182234)
		(width 0.0889)
		(layer "B.Cu")
		(net "UPI_CPU1_CPU0_P0P0_DP<7>")
	)
	(arc
		(start 300.686978 -69.092826)
		(mid 300.604809 -68.907085)
		(end 300.764956 -68.782184)
		(width 0.0889)
		(layer "B.Cu")
		(net "UPI_CPU1_CPU0_P0P0_DP<7>")
	)
	(arc
		(start 304.041556 -70.963536)
		(mid 303.830843 -70.750457)
		(end 303.5427 -70.668134)
		(width 0.0889)
		(layer "B.Cu")
		(net "UPI_CPU1_CPU0_P0P0_DP<7>")
	)
	(arc
		(start 306.10429 -71.163688)
		(mid 305.809353 -71.242837)
		(end 305.593496 -71.458836)
		(width 0.0889)
		(layer "B.Cu")
		(net "UPI_CPU1_CPU0_P0P0_DP<7>")
	)
	(arc
		(start 302.66005 -70.172834)
		(mid 302.4662 -70.116484)
		(end 302.324516 -69.972682)
		(width 0.0889)
		(layer "B.Cu")
		(net "UPI_CPU1_CPU0_P0P0_DP<7>")
	)
	(arc
		(start 142.696438 -64.419734)
		(mid 142.493085 -64.304028)
		(end 142.34668 -64.121538)
		(width 0.0889)
		(layer "B.Cu")
		(net "UPI_CPU1_CPU0_P0P0_DP<7>")
	)
	(segment
		(start 302.099726 -70.763384)
		(end 302.671226 -70.763384)
		(width 0.1143)
		(layer "F.Cu")
		(net "UPI_CPU1_CPU0_P0P0_DP<6>")
	)
	(segment
		(start 140.533374 -63.829184)
		(end 141.104874 -63.829184)
		(width 0.1143)
		(layer "F.Cu")
		(net "UPI_CPU1_CPU0_P0P0_DP<6>")
	)
	(via
		(at 302.671226 -70.763384)
		(size 0.508)
		(drill 0.254)
		(layers "F.Cu" "B.Cu")
		(net "UPI_CPU1_CPU0_P0P0_DP<6>")
	)
	(via
		(at 315.584586 -87.576152)
		(size 0.508)
		(drill 0.254)
		(layers "F.Cu" "B.Cu")
		(net "UPI_CPU1_CPU0_P0P0_DP<6>")
	)
	(via
		(at 141.104874 -63.829184)
		(size 0.508)
		(drill 0.254)
		(layers "F.Cu" "B.Cu")
		(net "UPI_CPU1_CPU0_P0P0_DP<6>")
	)
	(segment
		(start 141.093698 -63.429134)
		(end 141.123162 -63.429134)
		(width 0.0889)
		(layer "B.Cu")
		(net "UPI_CPU1_CPU0_P0P0_DP<6>")
	)
	(segment
		(start 147.39112 -62.6745)
		(end 152.620218 -67.903852)
		(width 0.1143)
		(layer "B.Cu")
		(net "UPI_CPU1_CPU0_P0P0_DP<6>")
	)
	(segment
		(start 309.85841 -107.352084)
		(end 313.222894 -103.908352)
		(width 0.1143)
		(layer "B.Cu")
		(net "UPI_CPU1_CPU0_P0P0_DP<6>")
	)
	(segment
		(start 157.085792 -90.23604)
		(end 162.986466 -96.979232)
		(width 0.1143)
		(layer "B.Cu")
		(net "UPI_CPU1_CPU0_P0P0_DP<6>")
	)
	(segment
		(start 314.77077 -80.122522)
		(end 311.935622 -75.037442)
		(width 0.1143)
		(layer "B.Cu")
		(net "UPI_CPU1_CPU0_P0P0_DP<6>")
	)
	(segment
		(start 315.479938 -83.546442)
		(end 314.77077 -80.122522)
		(width 0.1143)
		(layer "B.Cu")
		(net "UPI_CPU1_CPU0_P0P0_DP<6>")
	)
	(segment
		(start 305.443636 -72.649588)
		(end 305.23561 -72.649588)
		(width 0.0889)
		(layer "B.Cu")
		(net "UPI_CPU1_CPU0_P0P0_DP<6>")
	)
	(segment
		(start 142.52575 -62.64275)
		(end 142.5575 -62.6745)
		(width 0.0889)
		(layer "B.Cu")
		(net "UPI_CPU1_CPU0_P0P0_DP<6>")
	)
	(segment
		(start 314.155836 -99.356672)
		(end 314.499752 -96.883728)
		(width 0.1143)
		(layer "B.Cu")
		(net "UPI_CPU1_CPU0_P0P0_DP<6>")
	)
	(segment
		(start 289.452304 -108.536994)
		(end 292.210998 -107.965748)
		(width 0.1143)
		(layer "B.Cu")
		(net "UPI_CPU1_CPU0_P0P0_DP<6>")
	)
	(segment
		(start 142.5575 -62.6745)
		(end 142.568676 -62.6745)
		(width 0.0889)
		(layer "B.Cu")
		(net "UPI_CPU1_CPU0_P0P0_DP<6>")
	)
	(segment
		(start 313.222894 -103.908352)
		(end 314.155836 -99.356672)
		(width 0.1143)
		(layer "B.Cu")
		(net "UPI_CPU1_CPU0_P0P0_DP<6>")
	)
	(segment
		(start 235.580428 -111.115856)
		(end 246.402606 -106.936286)
		(width 0.1143)
		(layer "B.Cu")
		(net "UPI_CPU1_CPU0_P0P0_DP<6>")
	)
	(segment
		(start 314.499752 -96.883728)
		(end 315.779912 -95.101156)
		(width 0.1143)
		(layer "B.Cu")
		(net "UPI_CPU1_CPU0_P0P0_DP<6>")
	)
	(segment
		(start 225.851212 -110.628176)
		(end 235.580428 -111.115856)
		(width 0.1143)
		(layer "B.Cu")
		(net "UPI_CPU1_CPU0_P0P0_DP<6>")
	)
	(segment
		(start 178.57343 -110.395766)
		(end 186.353704 -110.883446)
		(width 0.1143)
		(layer "B.Cu")
		(net "UPI_CPU1_CPU0_P0P0_DP<6>")
	)
	(segment
		(start 307.806344 -73.550272)
		(end 307.79085 -73.534778)
		(width 0.0889)
		(layer "B.Cu")
		(net "UPI_CPU1_CPU0_P0P0_DP<6>")
	)
	(segment
		(start 306.691284 -72.47128)
		(end 306.622196 -72.362568)
		(width 0.0889)
		(layer "B.Cu")
		(net "UPI_CPU1_CPU0_P0P0_DP<6>")
	)
	(segment
		(start 308.93131 -73.9394)
		(end 308.2036 -73.9394)
		(width 0.1143)
		(layer "B.Cu")
		(net "UPI_CPU1_CPU0_P0P0_DP<6>")
	)
	(segment
		(start 302.5521 -70.763384)
		(end 302.671226 -70.763384)
		(width 0.0889)
		(layer "B.Cu")
		(net "UPI_CPU1_CPU0_P0P0_DP<6>")
	)
	(segment
		(start 303.551336 -71.658988)
		(end 303.51857 -71.658988)
		(width 0.0889)
		(layer "B.Cu")
		(net "UPI_CPU1_CPU0_P0P0_DP<6>")
	)
	(segment
		(start 287.628838 -109.999272)
		(end 289.452304 -108.536994)
		(width 0.1143)
		(layer "B.Cu")
		(net "UPI_CPU1_CPU0_P0P0_DP<6>")
	)
	(segment
		(start 315.584586 -87.576152)
		(end 315.479938 -83.546442)
		(width 0.1143)
		(layer "B.Cu")
		(net "UPI_CPU1_CPU0_P0P0_DP<6>")
	)
	(segment
		(start 306.691284 -72.471026)
		(end 306.691284 -72.47128)
		(width 0.0889)
		(layer "B.Cu")
		(net "UPI_CPU1_CPU0_P0P0_DP<6>")
	)
	(segment
		(start 167.845486 -104.23144)
		(end 170.229276 -106.02468)
		(width 0.1143)
		(layer "B.Cu")
		(net "UPI_CPU1_CPU0_P0P0_DP<6>")
	)
	(segment
		(start 197.930516 -115.57127)
		(end 207.28178 -114.316764)
		(width 0.1143)
		(layer "B.Cu")
		(net "UPI_CPU1_CPU0_P0P0_DP<6>")
	)
	(segment
		(start 207.28178 -114.316764)
		(end 207.509618 -114.310668)
		(width 0.1143)
		(layer "B.Cu")
		(net "UPI_CPU1_CPU0_P0P0_DP<6>")
	)
	(segment
		(start 311.935622 -75.037442)
		(end 308.93131 -73.9394)
		(width 0.1143)
		(layer "B.Cu")
		(net "UPI_CPU1_CPU0_P0P0_DP<6>")
	)
	(segment
		(start 163.657026 -99.645724)
		(end 165.451028 -101.74986)
		(width 0.1143)
		(layer "B.Cu")
		(net "UPI_CPU1_CPU0_P0P0_DP<6>")
	)
	(segment
		(start 249.146568 -106.834178)
		(end 258.744212 -109.692186)
		(width 0.1143)
		(layer "B.Cu")
		(net "UPI_CPU1_CPU0_P0P0_DP<6>")
	)
	(segment
		(start 188.834014 -112.265206)
		(end 189.987428 -113.70691)
		(width 0.1143)
		(layer "B.Cu")
		(net "UPI_CPU1_CPU0_P0P0_DP<6>")
	)
	(segment
		(start 142.568676 -62.6745)
		(end 147.39112 -62.6745)
		(width 0.1143)
		(layer "B.Cu")
		(net "UPI_CPU1_CPU0_P0P0_DP<6>")
	)
	(segment
		(start 282.675584 -112.142016)
		(end 285.71444 -111.53394)
		(width 0.1143)
		(layer "B.Cu")
		(net "UPI_CPU1_CPU0_P0P0_DP<6>")
	)
	(segment
		(start 207.509618 -114.310668)
		(end 225.851212 -110.628176)
		(width 0.1143)
		(layer "B.Cu")
		(net "UPI_CPU1_CPU0_P0P0_DP<6>")
	)
	(segment
		(start 246.402606 -106.936286)
		(end 249.146568 -106.834178)
		(width 0.1143)
		(layer "B.Cu")
		(net "UPI_CPU1_CPU0_P0P0_DP<6>")
	)
	(segment
		(start 304.406046 -72.154034)
		(end 304.37328 -72.154034)
		(width 0.0889)
		(layer "B.Cu")
		(net "UPI_CPU1_CPU0_P0P0_DP<6>")
	)
	(segment
		(start 189.987428 -113.70691)
		(end 195.172584 -115.450874)
		(width 0.1143)
		(layer "B.Cu")
		(net "UPI_CPU1_CPU0_P0P0_DP<6>")
	)
	(segment
		(start 303.8602 -110.371636)
		(end 305.554888 -109.899196)
		(width 0.1143)
		(layer "B.Cu")
		(net "UPI_CPU1_CPU0_P0P0_DP<6>")
	)
	(segment
		(start 142.46733 -62.64275)
		(end 142.52575 -62.64275)
		(width 0.0889)
		(layer "B.Cu")
		(net "UPI_CPU1_CPU0_P0P0_DP<6>")
	)
	(segment
		(start 186.353704 -110.883446)
		(end 188.834014 -112.265206)
		(width 0.1143)
		(layer "B.Cu")
		(net "UPI_CPU1_CPU0_P0P0_DP<6>")
	)
	(segment
		(start 152.620218 -67.903852)
		(end 157.085792 -90.23604)
		(width 0.1143)
		(layer "B.Cu")
		(net "UPI_CPU1_CPU0_P0P0_DP<6>")
	)
	(segment
		(start 302.689006 -71.163434)
		(end 302.5521 -71.163434)
		(width 0.0889)
		(layer "B.Cu")
		(net "UPI_CPU1_CPU0_P0P0_DP<6>")
	)
	(segment
		(start 307.178202 -72.957944)
		(end 306.691284 -72.471026)
		(width 0.0889)
		(layer "B.Cu")
		(net "UPI_CPU1_CPU0_P0P0_DP<6>")
	)
	(segment
		(start 307.754782 -73.534778)
		(end 307.178202 -72.958198)
		(width 0.0889)
		(layer "B.Cu")
		(net "UPI_CPU1_CPU0_P0P0_DP<6>")
	)
	(segment
		(start 175.948086 -107.981496)
		(end 178.57343 -110.395766)
		(width 0.1143)
		(layer "B.Cu")
		(net "UPI_CPU1_CPU0_P0P0_DP<6>")
	)
	(segment
		(start 307.79085 -73.534778)
		(end 307.754782 -73.534778)
		(width 0.0889)
		(layer "B.Cu")
		(net "UPI_CPU1_CPU0_P0P0_DP<6>")
	)
	(segment
		(start 305.554888 -109.899196)
		(end 309.85841 -107.352084)
		(width 0.1143)
		(layer "B.Cu")
		(net "UPI_CPU1_CPU0_P0P0_DP<6>")
	)
	(segment
		(start 307.178202 -72.958198)
		(end 307.178202 -72.957944)
		(width 0.0889)
		(layer "B.Cu")
		(net "UPI_CPU1_CPU0_P0P0_DP<6>")
	)
	(segment
		(start 165.451028 -101.74986)
		(end 167.845486 -104.23144)
		(width 0.1143)
		(layer "B.Cu")
		(net "UPI_CPU1_CPU0_P0P0_DP<6>")
	)
	(segment
		(start 306.136294 -72.179434)
		(end 305.98237 -72.190864)
		(width 0.0889)
		(layer "B.Cu")
		(net "UPI_CPU1_CPU0_P0P0_DP<6>")
	)
	(segment
		(start 141.104874 -63.829184)
		(end 141.104874 -63.995046)
		(width 0.0889)
		(layer "B.Cu")
		(net "UPI_CPU1_CPU0_P0P0_DP<6>")
	)
	(segment
		(start 285.71444 -111.53394)
		(end 287.628838 -109.999018)
		(width 0.1143)
		(layer "B.Cu")
		(net "UPI_CPU1_CPU0_P0P0_DP<6>")
	)
	(segment
		(start 258.744212 -109.692186)
		(end 282.675584 -112.142016)
		(width 0.1143)
		(layer "B.Cu")
		(net "UPI_CPU1_CPU0_P0P0_DP<6>")
	)
	(segment
		(start 162.986466 -96.979232)
		(end 163.657026 -99.645724)
		(width 0.1143)
		(layer "B.Cu")
		(net "UPI_CPU1_CPU0_P0P0_DP<6>")
	)
	(segment
		(start 315.779912 -95.101156)
		(end 315.584586 -87.576152)
		(width 0.1143)
		(layer "B.Cu")
		(net "UPI_CPU1_CPU0_P0P0_DP<6>")
	)
	(segment
		(start 292.210998 -107.965748)
		(end 303.8602 -110.371636)
		(width 0.1143)
		(layer "B.Cu")
		(net "UPI_CPU1_CPU0_P0P0_DP<6>")
	)
	(segment
		(start 140.765784 -64.059816)
		(end 140.733018 -63.977012)
		(width 0.0889)
		(layer "B.Cu")
		(net "UPI_CPU1_CPU0_P0P0_DP<6>")
	)
	(segment
		(start 287.628838 -109.999018)
		(end 287.628838 -109.999272)
		(width 0.1143)
		(layer "B.Cu")
		(net "UPI_CPU1_CPU0_P0P0_DP<6>")
	)
	(segment
		(start 308.2036 -73.9394)
		(end 307.806344 -73.550272)
		(width 0.1143)
		(layer "B.Cu")
		(net "UPI_CPU1_CPU0_P0P0_DP<6>")
	)
	(segment
		(start 195.172584 -115.450874)
		(end 197.930516 -115.57127)
		(width 0.1143)
		(layer "B.Cu")
		(net "UPI_CPU1_CPU0_P0P0_DP<6>")
	)
	(segment
		(start 170.229276 -106.02468)
		(end 175.948086 -107.981496)
		(width 0.1143)
		(layer "B.Cu")
		(net "UPI_CPU1_CPU0_P0P0_DP<6>")
	)
	(arc
		(start 303.183036 -71.458836)
		(mid 302.974428 -71.246904)
		(end 302.689006 -71.163434)
		(width 0.0889)
		(layer "B.Cu")
		(net "UPI_CPU1_CPU0_P0P0_DP<6>")
	)
	(arc
		(start 303.51857 -71.658988)
		(mid 303.32472 -71.602638)
		(end 303.183036 -71.458836)
		(width 0.0889)
		(layer "B.Cu")
		(net "UPI_CPU1_CPU0_P0P0_DP<6>")
	)
	(arc
		(start 140.733018 -63.977012)
		(mid 140.770803 -63.609277)
		(end 141.093698 -63.429134)
		(width 0.0889)
		(layer "B.Cu")
		(net "UPI_CPU1_CPU0_P0P0_DP<6>")
	)
	(arc
		(start 141.104874 -63.995046)
		(mid 140.96209 -64.167691)
		(end 140.765784 -64.059816)
		(width 0.0889)
		(layer "B.Cu")
		(net "UPI_CPU1_CPU0_P0P0_DP<6>")
	)
	(arc
		(start 141.123162 -63.429134)
		(mid 141.408209 -63.345606)
		(end 141.616684 -63.133986)
		(width 0.0889)
		(layer "B.Cu")
		(net "UPI_CPU1_CPU0_P0P0_DP<6>")
	)
	(arc
		(start 305.98237 -72.190864)
		(mid 305.781205 -72.300552)
		(end 305.63185 -72.474328)
		(width 0.0889)
		(layer "B.Cu")
		(net "UPI_CPU1_CPU0_P0P0_DP<6>")
	)
	(arc
		(start 304.041556 -71.954136)
		(mid 303.834552 -71.743272)
		(end 303.551336 -71.658988)
		(width 0.0889)
		(layer "B.Cu")
		(net "UPI_CPU1_CPU0_P0P0_DP<6>")
	)
	(arc
		(start 304.900076 -72.449436)
		(mid 304.691468 -72.237504)
		(end 304.406046 -72.154034)
		(width 0.0889)
		(layer "B.Cu")
		(net "UPI_CPU1_CPU0_P0P0_DP<6>")
	)
	(arc
		(start 305.23561 -72.649588)
		(mid 305.04176 -72.593238)
		(end 304.900076 -72.449436)
		(width 0.0889)
		(layer "B.Cu")
		(net "UPI_CPU1_CPU0_P0P0_DP<6>")
	)
	(arc
		(start 141.616684 -63.133986)
		(mid 141.976192 -62.774412)
		(end 142.46733 -62.64275)
		(width 0.0889)
		(layer "B.Cu")
		(net "UPI_CPU1_CPU0_P0P0_DP<6>")
	)
	(arc
		(start 302.5521 -71.163434)
		(mid 302.352202 -70.963536)
		(end 302.5521 -70.763384)
		(width 0.0889)
		(layer "B.Cu")
		(net "UPI_CPU1_CPU0_P0P0_DP<6>")
	)
	(arc
		(start 305.63185 -72.474328)
		(mid 305.550658 -72.57583)
		(end 305.443636 -72.649588)
		(width 0.0889)
		(layer "B.Cu")
		(net "UPI_CPU1_CPU0_P0P0_DP<6>")
	)
	(arc
		(start 304.37328 -72.154034)
		(mid 304.181638 -72.096868)
		(end 304.041556 -71.954136)
		(width 0.0889)
		(layer "B.Cu")
		(net "UPI_CPU1_CPU0_P0P0_DP<6>")
	)
	(arc
		(start 306.622196 -72.362568)
		(mid 306.399431 -72.217417)
		(end 306.136294 -72.179434)
		(width 0.0889)
		(layer "B.Cu")
		(net "UPI_CPU1_CPU0_P0P0_DP<6>")
	)
	(segment
		(start 143.32458 -62.248034)
		(end 143.77162 -62.248034)
		(width 0.0889)
		(layer "F.Cu")
		(net "UPI_CPU1_CPU0_P0P0_DP<5>")
	)
	(segment
		(start 143.255746 -62.1792)
		(end 143.32458 -62.248034)
		(width 0.0889)
		(layer "F.Cu")
		(net "UPI_CPU1_CPU0_P0P0_DP<5>")
	)
	(segment
		(start 142.232634 -62.248034)
		(end 143.06042 -62.248034)
		(width 0.0889)
		(layer "F.Cu")
		(net "UPI_CPU1_CPU0_P0P0_DP<5>")
	)
	(segment
		(start 141.391894 -62.343538)
		(end 141.54658 -62.498224)
		(width 0.0889)
		(layer "F.Cu")
		(net "UPI_CPU1_CPU0_P0P0_DP<5>")
	)
	(segment
		(start 143.77162 -62.248034)
		(end 143.813022 -62.206632)
		(width 0.0889)
		(layer "F.Cu")
		(net "UPI_CPU1_CPU0_P0P0_DP<5>")
	)
	(segment
		(start 143.129254 -62.1792)
		(end 143.255746 -62.1792)
		(width 0.0889)
		(layer "F.Cu")
		(net "UPI_CPU1_CPU0_P0P0_DP<5>")
	)
	(segment
		(start 143.813022 -62.11951)
		(end 143.541496 -61.847984)
		(width 0.0889)
		(layer "F.Cu")
		(net "UPI_CPU1_CPU0_P0P0_DP<5>")
	)
	(segment
		(start 302.099726 -71.753984)
		(end 302.671226 -71.753984)
		(width 0.1143)
		(layer "F.Cu")
		(net "UPI_CPU1_CPU0_P0P0_DP<5>")
	)
	(segment
		(start 143.813022 -62.206632)
		(end 143.813022 -62.11951)
		(width 0.0889)
		(layer "F.Cu")
		(net "UPI_CPU1_CPU0_P0P0_DP<5>")
	)
	(segment
		(start 143.06042 -62.248034)
		(end 143.129254 -62.1792)
		(width 0.0889)
		(layer "F.Cu")
		(net "UPI_CPU1_CPU0_P0P0_DP<5>")
	)
	(via
		(at 143.541496 -61.847984)
		(size 0.508)
		(drill 0.254)
		(layers "F.Cu" "B.Cu")
		(net "UPI_CPU1_CPU0_P0P0_DP<5>")
	)
	(via
		(at 302.671226 -71.753984)
		(size 0.508)
		(drill 0.254)
		(layers "F.Cu" "B.Cu")
		(net "UPI_CPU1_CPU0_P0P0_DP<5>")
	)
	(via
		(at 314.177934 -85.675978)
		(size 0.508)
		(drill 0.254)
		(layers "F.Cu" "B.Cu")
		(net "UPI_CPU1_CPU0_P0P0_DP<5>")
	)
	(arc
		(start 141.54658 -62.498224)
		(mid 141.66642 -62.543099)
		(end 141.77899 -62.482222)
		(width 0.0889)
		(layer "F.Cu")
		(net "UPI_CPU1_CPU0_P0P0_DP<5>")
	)
	(arc
		(start 141.77899 -62.482222)
		(mid 141.979216 -62.313623)
		(end 142.232634 -62.248034)
		(width 0.0889)
		(layer "F.Cu")
		(net "UPI_CPU1_CPU0_P0P0_DP<5>")
	)
	(segment
		(start 143.7259 -61.662056)
		(end 143.7259 -61.465206)
		(width 0.0889)
		(layer "B.Cu")
		(net "UPI_CPU1_CPU0_P0P0_DP<5>")
	)
	(segment
		(start 313.472068 -81.296002)
		(end 313.380374 -81.437226)
		(width 0.1143)
		(layer "B.Cu")
		(net "UPI_CPU1_CPU0_P0P0_DP<5>")
	)
	(segment
		(start 313.428634 -81.661254)
		(end 313.570112 -81.752694)
		(width 0.1143)
		(layer "B.Cu")
		(net "UPI_CPU1_CPU0_P0P0_DP<5>")
	)
	(segment
		(start 171.512992 -105.054654)
		(end 171.753784 -105.13695)
		(width 0.1143)
		(layer "B.Cu")
		(net "UPI_CPU1_CPU0_P0P0_DP<5>")
	)
	(segment
		(start 187.89904 -110.487968)
		(end 189.720982 -110.649258)
		(width 0.1143)
		(layer "B.Cu")
		(net "UPI_CPU1_CPU0_P0P0_DP<5>")
	)
	(segment
		(start 170.340528 -104.448356)
		(end 170.516296 -104.444546)
		(width 0.1143)
		(layer "B.Cu")
		(net "UPI_CPU1_CPU0_P0P0_DP<5>")
	)
	(segment
		(start 171.831 -105.295446)
		(end 176.581308 -106.9213)
		(width 0.1143)
		(layer "B.Cu")
		(net "UPI_CPU1_CPU0_P0P0_DP<5>")
	)
	(segment
		(start 288.42589 -107.655106)
		(end 292.151308 -106.910886)
		(width 0.1143)
		(layer "B.Cu")
		(net "UPI_CPU1_CPU0_P0P0_DP<5>")
	)
	(segment
		(start 303.43983 -109.168692)
		(end 305.174904 -108.697014)
		(width 0.1143)
		(layer "B.Cu")
		(net "UPI_CPU1_CPU0_P0P0_DP<5>")
	)
	(segment
		(start 313.325764 -80.615282)
		(end 313.23407 -80.756506)
		(width 0.1143)
		(layer "B.Cu")
		(net "UPI_CPU1_CPU0_P0P0_DP<5>")
	)
	(segment
		(start 245.808246 -105.86466)
		(end 249.64263 -105.721658)
		(width 0.1143)
		(layer "B.Cu")
		(net "UPI_CPU1_CPU0_P0P0_DP<5>")
	)
	(segment
		(start 305.978306 -74.325734)
		(end 306.456334 -74.325734)
		(width 0.0889)
		(layer "B.Cu")
		(net "UPI_CPU1_CPU0_P0P0_DP<5>")
	)
	(segment
		(start 313.23407 -80.756506)
		(end 313.28233 -80.980534)
		(width 0.1143)
		(layer "B.Cu")
		(net "UPI_CPU1_CPU0_P0P0_DP<5>")
	)
	(segment
		(start 146.0246 -61.215524)
		(end 147.45208 -61.215524)
		(width 0.1143)
		(layer "B.Cu")
		(net "UPI_CPU1_CPU0_P0P0_DP<5>")
	)
	(segment
		(start 143.541496 -61.847984)
		(end 143.7259 -61.662056)
		(width 0.0889)
		(layer "B.Cu")
		(net "UPI_CPU1_CPU0_P0P0_DP<5>")
	)
	(segment
		(start 258.969002 -108.49864)
		(end 282.109164 -110.847124)
		(width 0.1143)
		(layer "B.Cu")
		(net "UPI_CPU1_CPU0_P0P0_DP<5>")
	)
	(segment
		(start 313.672982 -82.798666)
		(end 313.721242 -83.022694)
		(width 0.1143)
		(layer "B.Cu")
		(net "UPI_CPU1_CPU0_P0P0_DP<5>")
	)
	(segment
		(start 285.440628 -110.18139)
		(end 288.42589 -107.655106)
		(width 0.1143)
		(layer "B.Cu")
		(net "UPI_CPU1_CPU0_P0P0_DP<5>")
	)
	(segment
		(start 164.11829 -96.436434)
		(end 167.789352 -102.004622)
		(width 0.1143)
		(layer "B.Cu")
		(net "UPI_CPU1_CPU0_P0P0_DP<5>")
	)
	(segment
		(start 167.789352 -102.004622)
		(end 170.340528 -104.448356)
		(width 0.1143)
		(layer "B.Cu")
		(net "UPI_CPU1_CPU0_P0P0_DP<5>")
	)
	(segment
		(start 170.699938 -104.620314)
		(end 170.703748 -104.79659)
		(width 0.1143)
		(layer "B.Cu")
		(net "UPI_CPU1_CPU0_P0P0_DP<5>")
	)
	(segment
		(start 146.002248 -61.2267)
		(end 146.013424 -61.215524)
		(width 0.0889)
		(layer "B.Cu")
		(net "UPI_CPU1_CPU0_P0P0_DP<5>")
	)
	(segment
		(start 190.655194 -110.485174)
		(end 192.043812 -111.08944)
		(width 0.1143)
		(layer "B.Cu")
		(net "UPI_CPU1_CPU0_P0P0_DP<5>")
	)
	(segment
		(start 309.574692 -75.616308)
		(end 309.78856 -75.692508)
		(width 0.1143)
		(layer "B.Cu")
		(net "UPI_CPU1_CPU0_P0P0_DP<5>")
	)
	(segment
		(start 309.000906 -75.30973)
		(end 309.01259 -75.343512)
		(width 0.0889)
		(layer "B.Cu")
		(net "UPI_CPU1_CPU0_P0P0_DP<5>")
	)
	(segment
		(start 313.867546 -83.703414)
		(end 314.006738 -83.793584)
		(width 0.1143)
		(layer "B.Cu")
		(net "UPI_CPU1_CPU0_P0P0_DP<5>")
	)
	(segment
		(start 306.456334 -74.325734)
		(end 307.218334 -75.087734)
		(width 0.0889)
		(layer "B.Cu")
		(net "UPI_CPU1_CPU0_P0P0_DP<5>")
	)
	(segment
		(start 282.109164 -110.847124)
		(end 285.440628 -110.18139)
		(width 0.1143)
		(layer "B.Cu")
		(net "UPI_CPU1_CPU0_P0P0_DP<5>")
	)
	(segment
		(start 308.543706 -75.087734)
		(end 309.000906 -75.30973)
		(width 0.0889)
		(layer "B.Cu")
		(net "UPI_CPU1_CPU0_P0P0_DP<5>")
	)
	(segment
		(start 313.721242 -83.022694)
		(end 313.86272 -83.114134)
		(width 0.1143)
		(layer "B.Cu")
		(net "UPI_CPU1_CPU0_P0P0_DP<5>")
	)
	(segment
		(start 153.552144 -67.315588)
		(end 157.971998 -89.412826)
		(width 0.1143)
		(layer "B.Cu")
		(net "UPI_CPU1_CPU0_P0P0_DP<5>")
	)
	(segment
		(start 313.526678 -82.117946)
		(end 313.574938 -82.341974)
		(width 0.1143)
		(layer "B.Cu")
		(net "UPI_CPU1_CPU0_P0P0_DP<5>")
	)
	(segment
		(start 304.366676 -73.335134)
		(end 304.399442 -73.335134)
		(width 0.0889)
		(layer "B.Cu")
		(net "UPI_CPU1_CPU0_P0P0_DP<5>")
	)
	(segment
		(start 197.845934 -114.562128)
		(end 204.59192 -113.658396)
		(width 0.1143)
		(layer "B.Cu")
		(net "UPI_CPU1_CPU0_P0P0_DP<5>")
	)
	(segment
		(start 189.720982 -110.649258)
		(end 190.655194 -110.485174)
		(width 0.1143)
		(layer "B.Cu")
		(net "UPI_CPU1_CPU0_P0P0_DP<5>")
	)
	(segment
		(start 146.013424 -61.215524)
		(end 146.0246 -61.215524)
		(width 0.0889)
		(layer "B.Cu")
		(net "UPI_CPU1_CPU0_P0P0_DP<5>")
	)
	(segment
		(start 314.006738 -83.793584)
		(end 314.14593 -84.442046)
		(width 0.1143)
		(layer "B.Cu")
		(net "UPI_CPU1_CPU0_P0P0_DP<5>")
	)
	(segment
		(start 313.605164 -81.915)
		(end 313.618372 -81.976722)
		(width 0.1143)
		(layer "B.Cu")
		(net "UPI_CPU1_CPU0_P0P0_DP<5>")
	)
	(segment
		(start 305.229006 -73.830688)
		(end 305.413664 -73.830688)
		(width 0.0889)
		(layer "B.Cu")
		(net "UPI_CPU1_CPU0_P0P0_DP<5>")
	)
	(segment
		(start 309.78856 -75.692508)
		(end 309.788814 -75.692508)
		(width 0.1143)
		(layer "B.Cu")
		(net "UPI_CPU1_CPU0_P0P0_DP<5>")
	)
	(segment
		(start 312.408062 -101.82479)
		(end 313.00166 -98.60534)
		(width 0.1143)
		(layer "B.Cu")
		(net "UPI_CPU1_CPU0_P0P0_DP<5>")
	)
	(segment
		(start 302.906684 -72.178926)
		(end 302.953674 -72.38238)
		(width 0.0889)
		(layer "B.Cu")
		(net "UPI_CPU1_CPU0_P0P0_DP<5>")
	)
	(segment
		(start 313.618372 -81.976722)
		(end 313.526678 -82.117946)
		(width 0.1143)
		(layer "B.Cu")
		(net "UPI_CPU1_CPU0_P0P0_DP<5>")
	)
	(segment
		(start 309.01259 -75.343512)
		(end 309.032402 -75.353164)
		(width 0.0889)
		(layer "B.Cu")
		(net "UPI_CPU1_CPU0_P0P0_DP<5>")
	)
	(segment
		(start 314.14593 -84.442046)
		(end 314.177934 -85.675978)
		(width 0.1143)
		(layer "B.Cu")
		(net "UPI_CPU1_CPU0_P0P0_DP<5>")
	)
	(segment
		(start 303.511966 -72.840088)
		(end 303.544732 -72.840088)
		(width 0.0889)
		(layer "B.Cu")
		(net "UPI_CPU1_CPU0_P0P0_DP<5>")
	)
	(segment
		(start 313.236102 -80.197452)
		(end 313.325764 -80.615282)
		(width 0.1143)
		(layer "B.Cu")
		(net "UPI_CPU1_CPU0_P0P0_DP<5>")
	)
	(segment
		(start 170.516296 -104.444546)
		(end 170.699938 -104.620314)
		(width 0.1143)
		(layer "B.Cu")
		(net "UPI_CPU1_CPU0_P0P0_DP<5>")
	)
	(segment
		(start 157.971998 -89.412826)
		(end 164.11829 -96.436434)
		(width 0.1143)
		(layer "B.Cu")
		(net "UPI_CPU1_CPU0_P0P0_DP<5>")
	)
	(segment
		(start 310.002428 -75.768708)
		(end 311.399428 -76.90104)
		(width 0.1143)
		(layer "B.Cu")
		(net "UPI_CPU1_CPU0_P0P0_DP<5>")
	)
	(segment
		(start 195.66001 -114.465608)
		(end 197.845934 -114.562128)
		(width 0.1143)
		(layer "B.Cu")
		(net "UPI_CPU1_CPU0_P0P0_DP<5>")
	)
	(segment
		(start 309.032402 -75.353164)
		(end 309.574692 -75.616308)
		(width 0.1143)
		(layer "B.Cu")
		(net "UPI_CPU1_CPU0_P0P0_DP<5>")
	)
	(segment
		(start 313.574938 -82.341974)
		(end 313.716416 -82.433414)
		(width 0.1143)
		(layer "B.Cu")
		(net "UPI_CPU1_CPU0_P0P0_DP<5>")
	)
	(segment
		(start 314.411614 -94.671896)
		(end 314.177934 -85.675978)
		(width 0.1143)
		(layer "B.Cu")
		(net "UPI_CPU1_CPU0_P0P0_DP<5>")
	)
	(segment
		(start 313.91098 -83.338162)
		(end 313.819286 -83.479386)
		(width 0.1143)
		(layer "B.Cu")
		(net "UPI_CPU1_CPU0_P0P0_DP<5>")
	)
	(segment
		(start 249.64263 -105.721658)
		(end 258.969002 -108.49864)
		(width 0.1143)
		(layer "B.Cu")
		(net "UPI_CPU1_CPU0_P0P0_DP<5>")
	)
	(segment
		(start 309.788814 -75.692508)
		(end 310.002428 -75.768708)
		(width 0.1143)
		(layer "B.Cu")
		(net "UPI_CPU1_CPU0_P0P0_DP<5>")
	)
	(segment
		(start 313.716416 -82.433414)
		(end 313.764676 -82.657442)
		(width 0.1143)
		(layer "B.Cu")
		(net "UPI_CPU1_CPU0_P0P0_DP<5>")
	)
	(segment
		(start 312.047382 -103.326946)
		(end 312.408062 -101.82479)
		(width 0.1143)
		(layer "B.Cu")
		(net "UPI_CPU1_CPU0_P0P0_DP<5>")
	)
	(segment
		(start 313.380374 -81.437226)
		(end 313.428634 -81.661254)
		(width 0.1143)
		(layer "B.Cu")
		(net "UPI_CPU1_CPU0_P0P0_DP<5>")
	)
	(segment
		(start 313.764676 -82.657442)
		(end 313.672982 -82.798666)
		(width 0.1143)
		(layer "B.Cu")
		(net "UPI_CPU1_CPU0_P0P0_DP<5>")
	)
	(segment
		(start 171.355004 -105.132124)
		(end 171.512992 -105.054654)
		(width 0.1143)
		(layer "B.Cu")
		(net "UPI_CPU1_CPU0_P0P0_DP<5>")
	)
	(segment
		(start 313.032648 -79.8322)
		(end 313.236102 -80.197452)
		(width 0.1143)
		(layer "B.Cu")
		(net "UPI_CPU1_CPU0_P0P0_DP<5>")
	)
	(segment
		(start 313.819286 -83.479386)
		(end 313.867546 -83.703414)
		(width 0.1143)
		(layer "B.Cu")
		(net "UPI_CPU1_CPU0_P0P0_DP<5>")
	)
	(segment
		(start 225.739452 -109.412024)
		(end 235.384594 -109.895386)
		(width 0.1143)
		(layer "B.Cu")
		(net "UPI_CPU1_CPU0_P0P0_DP<5>")
	)
	(segment
		(start 147.45208 -61.215524)
		(end 153.552144 -67.315588)
		(width 0.1143)
		(layer "B.Cu")
		(net "UPI_CPU1_CPU0_P0P0_DP<5>")
	)
	(segment
		(start 313.28233 -80.980534)
		(end 313.423808 -81.071974)
		(width 0.1143)
		(layer "B.Cu")
		(net "UPI_CPU1_CPU0_P0P0_DP<5>")
	)
	(segment
		(start 307.218334 -75.087734)
		(end 308.543706 -75.087734)
		(width 0.0889)
		(layer "B.Cu")
		(net "UPI_CPU1_CPU0_P0P0_DP<5>")
	)
	(segment
		(start 313.86272 -83.114134)
		(end 313.91098 -83.338162)
		(width 0.1143)
		(layer "B.Cu")
		(net "UPI_CPU1_CPU0_P0P0_DP<5>")
	)
	(segment
		(start 313.423808 -81.071974)
		(end 313.472068 -81.296002)
		(width 0.1143)
		(layer "B.Cu")
		(net "UPI_CPU1_CPU0_P0P0_DP<5>")
	)
	(segment
		(start 171.753784 -105.13695)
		(end 171.831 -105.295446)
		(width 0.1143)
		(layer "B.Cu")
		(net "UPI_CPU1_CPU0_P0P0_DP<5>")
	)
	(segment
		(start 170.703748 -104.79659)
		(end 170.887136 -104.972104)
		(width 0.1143)
		(layer "B.Cu")
		(net "UPI_CPU1_CPU0_P0P0_DP<5>")
	)
	(segment
		(start 170.887136 -104.972104)
		(end 171.355004 -105.132124)
		(width 0.1143)
		(layer "B.Cu")
		(net "UPI_CPU1_CPU0_P0P0_DP<5>")
	)
	(segment
		(start 313.00166 -98.60534)
		(end 313.290458 -96.233996)
		(width 0.1143)
		(layer "B.Cu")
		(net "UPI_CPU1_CPU0_P0P0_DP<5>")
	)
	(segment
		(start 309.075836 -106.393996)
		(end 312.047382 -103.326946)
		(width 0.1143)
		(layer "B.Cu")
		(net "UPI_CPU1_CPU0_P0P0_DP<5>")
	)
	(segment
		(start 313.570112 -81.752694)
		(end 313.605164 -81.915)
		(width 0.1143)
		(layer "B.Cu")
		(net "UPI_CPU1_CPU0_P0P0_DP<5>")
	)
	(segment
		(start 143.7259 -61.465206)
		(end 143.964406 -61.2267)
		(width 0.0889)
		(layer "B.Cu")
		(net "UPI_CPU1_CPU0_P0P0_DP<5>")
	)
	(segment
		(start 311.399428 -76.90104)
		(end 313.032648 -79.8322)
		(width 0.1143)
		(layer "B.Cu")
		(net "UPI_CPU1_CPU0_P0P0_DP<5>")
	)
	(segment
		(start 305.174904 -108.697014)
		(end 309.075836 -106.393996)
		(width 0.1143)
		(layer "B.Cu")
		(net "UPI_CPU1_CPU0_P0P0_DP<5>")
	)
	(segment
		(start 204.59192 -113.658396)
		(end 225.739452 -109.412024)
		(width 0.1143)
		(layer "B.Cu")
		(net "UPI_CPU1_CPU0_P0P0_DP<5>")
	)
	(segment
		(start 235.384594 -109.895386)
		(end 245.808246 -105.86466)
		(width 0.1143)
		(layer "B.Cu")
		(net "UPI_CPU1_CPU0_P0P0_DP<5>")
	)
	(segment
		(start 313.290458 -96.233996)
		(end 314.411614 -94.671896)
		(width 0.1143)
		(layer "B.Cu")
		(net "UPI_CPU1_CPU0_P0P0_DP<5>")
	)
	(segment
		(start 176.581308 -106.9213)
		(end 179.077366 -109.215936)
		(width 0.1143)
		(layer "B.Cu")
		(net "UPI_CPU1_CPU0_P0P0_DP<5>")
	)
	(segment
		(start 194.66433 -114.207544)
		(end 195.66001 -114.465608)
		(width 0.1143)
		(layer "B.Cu")
		(net "UPI_CPU1_CPU0_P0P0_DP<5>")
	)
	(segment
		(start 186.530742 -109.683296)
		(end 187.89904 -110.487968)
		(width 0.1143)
		(layer "B.Cu")
		(net "UPI_CPU1_CPU0_P0P0_DP<5>")
	)
	(segment
		(start 192.043812 -111.08944)
		(end 194.66433 -114.207544)
		(width 0.1143)
		(layer "B.Cu")
		(net "UPI_CPU1_CPU0_P0P0_DP<5>")
	)
	(segment
		(start 179.077366 -109.215936)
		(end 186.530742 -109.683296)
		(width 0.1143)
		(layer "B.Cu")
		(net "UPI_CPU1_CPU0_P0P0_DP<5>")
	)
	(segment
		(start 143.964406 -61.2267)
		(end 146.002248 -61.2267)
		(width 0.0889)
		(layer "B.Cu")
		(net "UPI_CPU1_CPU0_P0P0_DP<5>")
	)
	(segment
		(start 292.151308 -106.910886)
		(end 303.43983 -109.168692)
		(width 0.1143)
		(layer "B.Cu")
		(net "UPI_CPU1_CPU0_P0P0_DP<5>")
	)
	(arc
		(start 304.734976 -73.535286)
		(mid 304.943584 -73.747218)
		(end 305.229006 -73.830688)
		(width 0.0889)
		(layer "B.Cu")
		(net "UPI_CPU1_CPU0_P0P0_DP<5>")
	)
	(arc
		(start 305.629818 -74.027792)
		(mid 305.775743 -74.209879)
		(end 305.978306 -74.325734)
		(width 0.0889)
		(layer "B.Cu")
		(net "UPI_CPU1_CPU0_P0P0_DP<5>")
	)
	(arc
		(start 303.544732 -72.840088)
		(mid 303.736374 -72.897254)
		(end 303.876456 -73.039986)
		(width 0.0889)
		(layer "B.Cu")
		(net "UPI_CPU1_CPU0_P0P0_DP<5>")
	)
	(arc
		(start 302.953674 -72.38238)
		(mid 303.154765 -72.706477)
		(end 303.511966 -72.840088)
		(width 0.0889)
		(layer "B.Cu")
		(net "UPI_CPU1_CPU0_P0P0_DP<5>")
	)
	(arc
		(start 304.399442 -73.335134)
		(mid 304.593292 -73.391484)
		(end 304.734976 -73.535286)
		(width 0.0889)
		(layer "B.Cu")
		(net "UPI_CPU1_CPU0_P0P0_DP<5>")
	)
	(arc
		(start 302.671226 -71.753984)
		(mid 302.818849 -71.949896)
		(end 302.906684 -72.178926)
		(width 0.0889)
		(layer "B.Cu")
		(net "UPI_CPU1_CPU0_P0P0_DP<5>")
	)
	(arc
		(start 305.413664 -73.830688)
		(mid 305.538865 -73.910459)
		(end 305.629818 -74.027792)
		(width 0.0889)
		(layer "B.Cu")
		(net "UPI_CPU1_CPU0_P0P0_DP<5>")
	)
	(arc
		(start 303.876456 -73.039986)
		(mid 304.08346 -73.25085)
		(end 304.366676 -73.335134)
		(width 0.0889)
		(layer "B.Cu")
		(net "UPI_CPU1_CPU0_P0P0_DP<5>")
	)
	(segment
		(start 141.391894 -61.352938)
		(end 141.963394 -61.352938)
		(width 0.1143)
		(layer "F.Cu")
		(net "UPI_CPU1_CPU0_P0P0_DP<4>")
	)
	(segment
		(start 302.099726 -73.735184)
		(end 302.671226 -73.735184)
		(width 0.1143)
		(layer "F.Cu")
		(net "UPI_CPU1_CPU0_P0P0_DP<4>")
	)
	(via
		(at 302.671226 -73.735184)
		(size 0.508)
		(drill 0.254)
		(layers "F.Cu" "B.Cu")
		(net "UPI_CPU1_CPU0_P0P0_DP<4>")
	)
	(via
		(at 141.963394 -61.352938)
		(size 0.508)
		(drill 0.254)
		(layers "F.Cu" "B.Cu")
		(net "UPI_CPU1_CPU0_P0P0_DP<4>")
	)
	(via
		(at 313.242706 -93.017848)
		(size 0.508)
		(drill 0.254)
		(layers "F.Cu" "B.Cu")
		(net "UPI_CPU1_CPU0_P0P0_DP<4>")
	)
	(segment
		(start 203.091288 -113.085118)
		(end 203.333604 -112.924082)
		(width 0.1143)
		(layer "B.Cu")
		(net "UPI_CPU1_CPU0_P0P0_DP<4>")
	)
	(segment
		(start 259.165598 -107.54614)
		(end 281.846528 -109.84738)
		(width 0.1143)
		(layer "B.Cu")
		(net "UPI_CPU1_CPU0_P0P0_DP<4>")
	)
	(segment
		(start 312.3565 -82.657188)
		(end 312.496454 -82.743802)
		(width 0.1143)
		(layer "B.Cu")
		(net "UPI_CPU1_CPU0_P0P0_DP<4>")
	)
	(segment
		(start 307.693822 -76.115926)
		(end 307.934614 -76.115926)
		(width 0.0889)
		(layer "B.Cu")
		(net "UPI_CPU1_CPU0_P0P0_DP<4>")
	)
	(segment
		(start 304.366676 -74.325734)
		(end 304.402744 -74.325734)
		(width 0.0889)
		(layer "B.Cu")
		(net "UPI_CPU1_CPU0_P0P0_DP<4>")
	)
	(segment
		(start 311.10047 -102.888288)
		(end 311.52592 -101.221286)
		(width 0.1143)
		(layer "B.Cu")
		(net "UPI_CPU1_CPU0_P0P0_DP<4>")
	)
	(segment
		(start 141.963394 -61.352938)
		(end 141.813026 -61.352938)
		(width 0.0889)
		(layer "B.Cu")
		(net "UPI_CPU1_CPU0_P0P0_DP<4>")
	)
	(segment
		(start 308.295548 -76.141326)
		(end 308.371494 -76.141834)
		(width 0.1143)
		(layer "B.Cu")
		(net "UPI_CPU1_CPU0_P0P0_DP<4>")
	)
	(segment
		(start 192.481962 -110.320074)
		(end 195.394072 -113.38814)
		(width 0.1143)
		(layer "B.Cu")
		(net "UPI_CPU1_CPU0_P0P0_DP<4>")
	)
	(segment
		(start 308.219602 -76.14158)
		(end 308.219856 -76.141326)
		(width 0.1143)
		(layer "B.Cu")
		(net "UPI_CPU1_CPU0_P0P0_DP<4>")
	)
	(segment
		(start 304.793142 -107.805982)
		(end 308.459378 -105.626916)
		(width 0.1143)
		(layer "B.Cu")
		(net "UPI_CPU1_CPU0_P0P0_DP<4>")
	)
	(segment
		(start 312.18251 -81.399634)
		(end 312.23458 -81.622392)
		(width 0.1143)
		(layer "B.Cu")
		(net "UPI_CPU1_CPU0_P0P0_DP<4>")
	)
	(segment
		(start 311.990486 -81.089754)
		(end 312.042556 -81.31302)
		(width 0.1143)
		(layer "B.Cu")
		(net "UPI_CPU1_CPU0_P0P0_DP<4>")
	)
	(segment
		(start 311.749948 -79.8322)
		(end 311.868058 -80.04429)
		(width 0.1143)
		(layer "B.Cu")
		(net "UPI_CPU1_CPU0_P0P0_DP<4>")
	)
	(segment
		(start 312.391552 -82.294476)
		(end 312.30443 -82.433922)
		(width 0.1143)
		(layer "B.Cu")
		(net "UPI_CPU1_CPU0_P0P0_DP<4>")
	)
	(segment
		(start 144.367758 -60.0329)
		(end 146.442176 -60.0329)
		(width 0.1143)
		(layer "B.Cu")
		(net "UPI_CPU1_CPU0_P0P0_DP<4>")
	)
	(segment
		(start 190.861696 -108.789724)
		(end 192.481962 -110.320074)
		(width 0.1143)
		(layer "B.Cu")
		(net "UPI_CPU1_CPU0_P0P0_DP<4>")
	)
	(segment
		(start 307.982112 -76.141326)
		(end 308.21884 -76.141326)
		(width 0.1143)
		(layer "B.Cu")
		(net "UPI_CPU1_CPU0_P0P0_DP<4>")
	)
	(segment
		(start 305.993038 -75.316334)
		(end 306.4002 -75.316334)
		(width 0.0889)
		(layer "B.Cu")
		(net "UPI_CPU1_CPU0_P0P0_DP<4>")
	)
	(segment
		(start 303.43602 -108.180378)
		(end 304.793142 -107.805982)
		(width 0.1143)
		(layer "B.Cu")
		(net "UPI_CPU1_CPU0_P0P0_DP<4>")
	)
	(segment
		(start 189.516258 -108.316014)
		(end 190.861696 -108.789724)
		(width 0.1143)
		(layer "B.Cu")
		(net "UPI_CPU1_CPU0_P0P0_DP<4>")
	)
	(segment
		(start 312.496454 -82.743802)
		(end 312.548524 -82.96656)
		(width 0.1143)
		(layer "B.Cu")
		(net "UPI_CPU1_CPU0_P0P0_DP<4>")
	)
	(segment
		(start 310.539638 -77.660754)
		(end 311.749948 -79.8322)
		(width 0.1143)
		(layer "B.Cu")
		(net "UPI_CPU1_CPU0_P0P0_DP<4>")
	)
	(segment
		(start 225.668078 -108.439458)
		(end 235.227876 -108.918756)
		(width 0.1143)
		(layer "B.Cu")
		(net "UPI_CPU1_CPU0_P0P0_DP<4>")
	)
	(segment
		(start 143.796512 -60.057284)
		(end 144.336516 -60.057284)
		(width 0.0889)
		(layer "B.Cu")
		(net "UPI_CPU1_CPU0_P0P0_DP<4>")
	)
	(segment
		(start 311.868058 -80.04429)
		(end 311.920382 -80.274922)
		(width 0.1143)
		(layer "B.Cu")
		(net "UPI_CPU1_CPU0_P0P0_DP<4>")
	)
	(segment
		(start 306.4002 -75.316334)
		(end 307.693822 -76.115926)
		(width 0.0889)
		(layer "B.Cu")
		(net "UPI_CPU1_CPU0_P0P0_DP<4>")
	)
	(segment
		(start 312.618374 -83.77809)
		(end 312.670444 -84.001356)
		(width 0.1143)
		(layer "B.Cu")
		(net "UPI_CPU1_CPU0_P0P0_DP<4>")
	)
	(segment
		(start 144.3609 -60.0329)
		(end 144.367758 -60.0329)
		(width 0.0889)
		(layer "B.Cu")
		(net "UPI_CPU1_CPU0_P0P0_DP<4>")
	)
	(segment
		(start 312.077608 -80.950308)
		(end 311.990486 -81.089754)
		(width 0.1143)
		(layer "B.Cu")
		(net "UPI_CPU1_CPU0_P0P0_DP<4>")
	)
	(segment
		(start 179.480972 -108.27131)
		(end 184.428892 -108.582206)
		(width 0.1143)
		(layer "B.Cu")
		(net "UPI_CPU1_CPU0_P0P0_DP<4>")
	)
	(segment
		(start 312.827416 -84.67344)
		(end 312.96737 -84.760054)
		(width 0.1143)
		(layer "B.Cu")
		(net "UPI_CPU1_CPU0_P0P0_DP<4>")
	)
	(segment
		(start 142.32255 -61.530992)
		(end 143.796512 -60.057284)
		(width 0.0889)
		(layer "B.Cu")
		(net "UPI_CPU1_CPU0_P0P0_DP<4>")
	)
	(segment
		(start 142.30985 -61.552836)
		(end 142.32255 -61.530992)
		(width 0.0889)
		(layer "B.Cu")
		(net "UPI_CPU1_CPU0_P0P0_DP<4>")
	)
	(segment
		(start 312.548524 -82.96656)
		(end 312.461402 -83.106006)
		(width 0.1143)
		(layer "B.Cu")
		(net "UPI_CPU1_CPU0_P0P0_DP<4>")
	)
	(segment
		(start 154.359102 -66.964052)
		(end 158.729172 -88.808814)
		(width 0.1143)
		(layer "B.Cu")
		(net "UPI_CPU1_CPU0_P0P0_DP<4>")
	)
	(segment
		(start 312.339482 -82.071718)
		(end 312.391552 -82.294476)
		(width 0.1143)
		(layer "B.Cu")
		(net "UPI_CPU1_CPU0_P0P0_DP<4>")
	)
	(segment
		(start 141.87932 -61.753242)
		(end 141.961108 -61.753242)
		(width 0.0889)
		(layer "B.Cu")
		(net "UPI_CPU1_CPU0_P0P0_DP<4>")
	)
	(segment
		(start 312.705496 -83.638644)
		(end 312.618374 -83.77809)
		(width 0.1143)
		(layer "B.Cu")
		(net "UPI_CPU1_CPU0_P0P0_DP<4>")
	)
	(segment
		(start 312.010806 -98.491548)
		(end 312.340498 -95.63608)
		(width 0.1143)
		(layer "B.Cu")
		(net "UPI_CPU1_CPU0_P0P0_DP<4>")
	)
	(segment
		(start 302.671226 -73.735184)
		(end 302.671226 -73.39711)
		(width 0.0889)
		(layer "B.Cu")
		(net "UPI_CPU1_CPU0_P0P0_DP<4>")
	)
	(segment
		(start 146.442176 -60.0329)
		(end 146.613626 -60.20435)
		(width 0.1143)
		(layer "B.Cu")
		(net "UPI_CPU1_CPU0_P0P0_DP<4>")
	)
	(segment
		(start 184.428892 -108.582206)
		(end 189.516258 -108.316014)
		(width 0.1143)
		(layer "B.Cu")
		(net "UPI_CPU1_CPU0_P0P0_DP<4>")
	)
	(segment
		(start 235.227876 -108.918756)
		(end 245.039642 -105.126028)
		(width 0.1143)
		(layer "B.Cu")
		(net "UPI_CPU1_CPU0_P0P0_DP<4>")
	)
	(segment
		(start 312.199528 -81.985104)
		(end 312.339482 -82.071718)
		(width 0.1143)
		(layer "B.Cu")
		(net "UPI_CPU1_CPU0_P0P0_DP<4>")
	)
	(segment
		(start 312.775346 -84.450174)
		(end 312.827416 -84.67344)
		(width 0.1143)
		(layer "B.Cu")
		(net "UPI_CPU1_CPU0_P0P0_DP<4>")
	)
	(segment
		(start 312.810398 -84.08797)
		(end 312.862468 -84.310728)
		(width 0.1143)
		(layer "B.Cu")
		(net "UPI_CPU1_CPU0_P0P0_DP<4>")
	)
	(segment
		(start 312.862468 -84.310728)
		(end 312.775346 -84.450174)
		(width 0.1143)
		(layer "B.Cu")
		(net "UPI_CPU1_CPU0_P0P0_DP<4>")
	)
	(segment
		(start 313.1566 -89.7001)
		(end 313.242706 -93.017848)
		(width 0.1143)
		(layer "B.Cu")
		(net "UPI_CPU1_CPU0_P0P0_DP<4>")
	)
	(segment
		(start 308.371494 -76.141834)
		(end 310.539638 -77.660754)
		(width 0.1143)
		(layer "B.Cu")
		(net "UPI_CPU1_CPU0_P0P0_DP<4>")
	)
	(segment
		(start 250.374404 -104.927654)
		(end 259.165598 -107.54614)
		(width 0.1143)
		(layer "B.Cu")
		(net "UPI_CPU1_CPU0_P0P0_DP<4>")
	)
	(segment
		(start 173.426882 -104.818942)
		(end 177.089054 -106.073194)
		(width 0.1143)
		(layer "B.Cu")
		(net "UPI_CPU1_CPU0_P0P0_DP<4>")
	)
	(segment
		(start 312.042556 -81.31302)
		(end 312.18251 -81.399634)
		(width 0.1143)
		(layer "B.Cu")
		(net "UPI_CPU1_CPU0_P0P0_DP<4>")
	)
	(segment
		(start 291.125402 -106.331258)
		(end 292.330378 -106.090466)
		(width 0.1143)
		(layer "B.Cu")
		(net "UPI_CPU1_CPU0_P0P0_DP<4>")
	)
	(segment
		(start 308.21884 -76.141326)
		(end 308.219602 -76.14158)
		(width 0.1143)
		(layer "B.Cu")
		(net "UPI_CPU1_CPU0_P0P0_DP<4>")
	)
	(segment
		(start 307.960014 -76.141326)
		(end 307.982112 -76.141326)
		(width 0.0889)
		(layer "B.Cu")
		(net "UPI_CPU1_CPU0_P0P0_DP<4>")
	)
	(segment
		(start 287.559496 -107.043982)
		(end 291.125402 -106.331258)
		(width 0.1143)
		(layer "B.Cu")
		(net "UPI_CPU1_CPU0_P0P0_DP<4>")
	)
	(segment
		(start 312.183272 -81.915)
		(end 312.199528 -81.985104)
		(width 0.1143)
		(layer "B.Cu")
		(net "UPI_CPU1_CPU0_P0P0_DP<4>")
	)
	(segment
		(start 197.795388 -113.794032)
		(end 203.091288 -113.085118)
		(width 0.1143)
		(layer "B.Cu")
		(net "UPI_CPU1_CPU0_P0P0_DP<4>")
	)
	(segment
		(start 313.256422 -93.546422)
		(end 313.242706 -93.017848)
		(width 0.1143)
		(layer "B.Cu")
		(net "UPI_CPU1_CPU0_P0P0_DP<4>")
	)
	(segment
		(start 312.025538 -80.72755)
		(end 312.077608 -80.950308)
		(width 0.1143)
		(layer "B.Cu")
		(net "UPI_CPU1_CPU0_P0P0_DP<4>")
	)
	(segment
		(start 146.613626 -60.20435)
		(end 147.599146 -60.20435)
		(width 0.1143)
		(layer "B.Cu")
		(net "UPI_CPU1_CPU0_P0P0_DP<4>")
	)
	(segment
		(start 144.336516 -60.057284)
		(end 144.3609 -60.0329)
		(width 0.0889)
		(layer "B.Cu")
		(net "UPI_CPU1_CPU0_P0P0_DP<4>")
	)
	(segment
		(start 311.833514 -80.41767)
		(end 311.885584 -80.640936)
		(width 0.1143)
		(layer "B.Cu")
		(net "UPI_CPU1_CPU0_P0P0_DP<4>")
	)
	(segment
		(start 170.699684 -103.452168)
		(end 173.426882 -104.818942)
		(width 0.1143)
		(layer "B.Cu")
		(net "UPI_CPU1_CPU0_P0P0_DP<4>")
	)
	(segment
		(start 311.921144 -80.27797)
		(end 311.833514 -80.41767)
		(width 0.1143)
		(layer "B.Cu")
		(net "UPI_CPU1_CPU0_P0P0_DP<4>")
	)
	(segment
		(start 307.934614 -76.115926)
		(end 307.960014 -76.141326)
		(width 0.0889)
		(layer "B.Cu")
		(net "UPI_CPU1_CPU0_P0P0_DP<4>")
	)
	(segment
		(start 311.920382 -80.274922)
		(end 311.921144 -80.27797)
		(width 0.1143)
		(layer "B.Cu")
		(net "UPI_CPU1_CPU0_P0P0_DP<4>")
	)
	(segment
		(start 196.054472 -113.719356)
		(end 197.795388 -113.794032)
		(width 0.1143)
		(layer "B.Cu")
		(net "UPI_CPU1_CPU0_P0P0_DP<4>")
	)
	(segment
		(start 308.459378 -105.626916)
		(end 311.10047 -102.888288)
		(width 0.1143)
		(layer "B.Cu")
		(net "UPI_CPU1_CPU0_P0P0_DP<4>")
	)
	(segment
		(start 304.918364 -74.84364)
		(end 305.993038 -75.316334)
		(width 0.0889)
		(layer "B.Cu")
		(net "UPI_CPU1_CPU0_P0P0_DP<4>")
	)
	(segment
		(start 312.96737 -84.760054)
		(end 313.035696 -85.051646)
		(width 0.1143)
		(layer "B.Cu")
		(net "UPI_CPU1_CPU0_P0P0_DP<4>")
	)
	(segment
		(start 312.30443 -82.433922)
		(end 312.3565 -82.657188)
		(width 0.1143)
		(layer "B.Cu")
		(net "UPI_CPU1_CPU0_P0P0_DP<4>")
	)
	(segment
		(start 195.394072 -113.38814)
		(end 196.054472 -113.719356)
		(width 0.1143)
		(layer "B.Cu")
		(net "UPI_CPU1_CPU0_P0P0_DP<4>")
	)
	(segment
		(start 312.23458 -81.622392)
		(end 312.147458 -81.761838)
		(width 0.1143)
		(layer "B.Cu")
		(net "UPI_CPU1_CPU0_P0P0_DP<4>")
	)
	(segment
		(start 312.670444 -84.001356)
		(end 312.810398 -84.08797)
		(width 0.1143)
		(layer "B.Cu")
		(net "UPI_CPU1_CPU0_P0P0_DP<4>")
	)
	(segment
		(start 281.846528 -109.84738)
		(end 285.023306 -109.211872)
		(width 0.1143)
		(layer "B.Cu")
		(net "UPI_CPU1_CPU0_P0P0_DP<4>")
	)
	(segment
		(start 302.671226 -73.39711)
		(end 302.729138 -73.339198)
		(width 0.0889)
		(layer "B.Cu")
		(net "UPI_CPU1_CPU0_P0P0_DP<4>")
	)
	(segment
		(start 312.513472 -83.329272)
		(end 312.653426 -83.415886)
		(width 0.1143)
		(layer "B.Cu")
		(net "UPI_CPU1_CPU0_P0P0_DP<4>")
	)
	(segment
		(start 312.340498 -95.63608)
		(end 313.276996 -94.33179)
		(width 0.1143)
		(layer "B.Cu")
		(net "UPI_CPU1_CPU0_P0P0_DP<4>")
	)
	(segment
		(start 285.023306 -109.211872)
		(end 287.559496 -107.043982)
		(width 0.1143)
		(layer "B.Cu")
		(net "UPI_CPU1_CPU0_P0P0_DP<4>")
	)
	(segment
		(start 168.537382 -101.380798)
		(end 170.699684 -103.452168)
		(width 0.1143)
		(layer "B.Cu")
		(net "UPI_CPU1_CPU0_P0P0_DP<4>")
	)
	(segment
		(start 311.885584 -80.640936)
		(end 312.025538 -80.72755)
		(width 0.1143)
		(layer "B.Cu")
		(net "UPI_CPU1_CPU0_P0P0_DP<4>")
	)
	(segment
		(start 245.039642 -105.126028)
		(end 250.374404 -104.927654)
		(width 0.1143)
		(layer "B.Cu")
		(net "UPI_CPU1_CPU0_P0P0_DP<4>")
	)
	(segment
		(start 311.52592 -101.221286)
		(end 312.010806 -98.491548)
		(width 0.1143)
		(layer "B.Cu")
		(net "UPI_CPU1_CPU0_P0P0_DP<4>")
	)
	(segment
		(start 312.147458 -81.761838)
		(end 312.183272 -81.915)
		(width 0.1143)
		(layer "B.Cu")
		(net "UPI_CPU1_CPU0_P0P0_DP<4>")
	)
	(segment
		(start 312.461402 -83.106006)
		(end 312.513472 -83.329272)
		(width 0.1143)
		(layer "B.Cu")
		(net "UPI_CPU1_CPU0_P0P0_DP<4>")
	)
	(segment
		(start 303.158398 -108.256832)
		(end 303.43602 -108.180378)
		(width 0.1143)
		(layer "B.Cu")
		(net "UPI_CPU1_CPU0_P0P0_DP<4>")
	)
	(segment
		(start 203.333604 -112.924082)
		(end 225.668078 -108.439458)
		(width 0.1143)
		(layer "B.Cu")
		(net "UPI_CPU1_CPU0_P0P0_DP<4>")
	)
	(segment
		(start 308.219856 -76.141326)
		(end 308.295548 -76.141326)
		(width 0.1143)
		(layer "B.Cu")
		(net "UPI_CPU1_CPU0_P0P0_DP<4>")
	)
	(segment
		(start 147.599146 -60.20435)
		(end 154.359102 -66.964052)
		(width 0.1143)
		(layer "B.Cu")
		(net "UPI_CPU1_CPU0_P0P0_DP<4>")
	)
	(segment
		(start 313.262518 -93.7768)
		(end 313.256422 -93.546422)
		(width 0.1143)
		(layer "B.Cu")
		(net "UPI_CPU1_CPU0_P0P0_DP<4>")
	)
	(segment
		(start 304.734976 -74.525886)
		(end 304.918364 -74.84364)
		(width 0.0889)
		(layer "B.Cu")
		(net "UPI_CPU1_CPU0_P0P0_DP<4>")
	)
	(segment
		(start 164.889942 -95.848932)
		(end 168.537382 -101.380798)
		(width 0.1143)
		(layer "B.Cu")
		(net "UPI_CPU1_CPU0_P0P0_DP<4>")
	)
	(segment
		(start 177.089054 -106.073194)
		(end 179.480972 -108.27131)
		(width 0.1143)
		(layer "B.Cu")
		(net "UPI_CPU1_CPU0_P0P0_DP<4>")
	)
	(segment
		(start 292.330378 -106.090466)
		(end 303.158398 -108.256832)
		(width 0.1143)
		(layer "B.Cu")
		(net "UPI_CPU1_CPU0_P0P0_DP<4>")
	)
	(segment
		(start 303.511966 -73.830688)
		(end 303.544732 -73.830688)
		(width 0.0889)
		(layer "B.Cu")
		(net "UPI_CPU1_CPU0_P0P0_DP<4>")
	)
	(segment
		(start 158.729172 -88.808814)
		(end 164.889942 -95.848932)
		(width 0.1143)
		(layer "B.Cu")
		(net "UPI_CPU1_CPU0_P0P0_DP<4>")
	)
	(segment
		(start 313.035696 -85.051646)
		(end 313.1566 -89.7001)
		(width 0.1143)
		(layer "B.Cu")
		(net "UPI_CPU1_CPU0_P0P0_DP<4>")
	)
	(segment
		(start 313.276996 -94.33179)
		(end 313.262518 -93.7768)
		(width 0.1143)
		(layer "B.Cu")
		(net "UPI_CPU1_CPU0_P0P0_DP<4>")
	)
	(segment
		(start 312.653426 -83.415886)
		(end 312.705496 -83.638644)
		(width 0.1143)
		(layer "B.Cu")
		(net "UPI_CPU1_CPU0_P0P0_DP<4>")
	)
	(arc
		(start 141.6812 -61.6712)
		(mid 141.772098 -61.731936)
		(end 141.87932 -61.753242)
		(width 0.0889)
		(layer "B.Cu")
		(net "UPI_CPU1_CPU0_P0P0_DP<4>")
	)
	(arc
		(start 303.017936 -73.535286)
		(mid 303.226544 -73.747218)
		(end 303.511966 -73.830688)
		(width 0.0889)
		(layer "B.Cu")
		(net "UPI_CPU1_CPU0_P0P0_DP<4>")
	)
	(arc
		(start 141.961108 -61.753242)
		(mid 142.162486 -61.700043)
		(end 142.30985 -61.552836)
		(width 0.0889)
		(layer "B.Cu")
		(net "UPI_CPU1_CPU0_P0P0_DP<4>")
	)
	(arc
		(start 141.813026 -61.352938)
		(mid 141.640782 -61.468028)
		(end 141.6812 -61.6712)
		(width 0.0889)
		(layer "B.Cu")
		(net "UPI_CPU1_CPU0_P0P0_DP<4>")
	)
	(arc
		(start 303.544732 -73.830688)
		(mid 303.736374 -73.887854)
		(end 303.876456 -74.030586)
		(width 0.0889)
		(layer "B.Cu")
		(net "UPI_CPU1_CPU0_P0P0_DP<4>")
	)
	(arc
		(start 304.402744 -74.325734)
		(mid 304.594761 -74.382842)
		(end 304.734976 -74.525886)
		(width 0.0889)
		(layer "B.Cu")
		(net "UPI_CPU1_CPU0_P0P0_DP<4>")
	)
	(arc
		(start 302.729138 -73.339198)
		(mid 302.896039 -73.404098)
		(end 303.017936 -73.535286)
		(width 0.0889)
		(layer "B.Cu")
		(net "UPI_CPU1_CPU0_P0P0_DP<4>")
	)
	(arc
		(start 303.876456 -74.030586)
		(mid 304.08346 -74.24145)
		(end 304.366676 -74.325734)
		(width 0.0889)
		(layer "B.Cu")
		(net "UPI_CPU1_CPU0_P0P0_DP<4>")
	)
	(segment
		(start 141.391894 -60.362338)
		(end 141.654022 -60.362338)
		(width 0.0889)
		(layer "F.Cu")
		(net "UPI_CPU1_CPU0_P0P0_DP<3>")
	)
	(segment
		(start 143.54302 -60.262516)
		(end 143.554704 -60.250832)
		(width 0.0889)
		(layer "F.Cu")
		(net "UPI_CPU1_CPU0_P0P0_DP<3>")
	)
	(segment
		(start 143.554704 -60.250832)
		(end 144.976088 -60.250832)
		(width 0.1143)
		(layer "F.Cu")
		(net "UPI_CPU1_CPU0_P0P0_DP<3>")
	)
	(segment
		(start 144.976088 -60.250832)
		(end 146.306794 -58.920126)
		(width 0.1143)
		(layer "F.Cu")
		(net "UPI_CPU1_CPU0_P0P0_DP<3>")
	)
	(segment
		(start 300.382686 -69.772784)
		(end 300.954186 -69.772784)
		(width 0.1143)
		(layer "F.Cu")
		(net "UPI_CPU1_CPU0_P0P0_DP<3>")
	)
	(segment
		(start 141.866874 -60.306204)
		(end 141.866874 -60.306458)
		(width 0.0889)
		(layer "F.Cu")
		(net "UPI_CPU1_CPU0_P0P0_DP<3>")
	)
	(segment
		(start 146.557746 -58.920126)
		(end 146.773646 -58.704226)
		(width 0.1143)
		(layer "F.Cu")
		(net "UPI_CPU1_CPU0_P0P0_DP<3>")
	)
	(segment
		(start 146.306794 -58.920126)
		(end 146.557746 -58.920126)
		(width 0.1143)
		(layer "F.Cu")
		(net "UPI_CPU1_CPU0_P0P0_DP<3>")
	)
	(segment
		(start 142.033244 -60.262516)
		(end 143.54302 -60.262516)
		(width 0.0889)
		(layer "F.Cu")
		(net "UPI_CPU1_CPU0_P0P0_DP<3>")
	)
	(via
		(at 300.954186 -69.772784)
		(size 0.508)
		(drill 0.254)
		(layers "F.Cu" "B.Cu")
		(net "UPI_CPU1_CPU0_P0P0_DP<3>")
	)
	(via
		(at 312.09361 -92.192602)
		(size 0.508)
		(drill 0.254)
		(layers "F.Cu" "B.Cu")
		(net "UPI_CPU1_CPU0_P0P0_DP<3>")
	)
	(via
		(at 146.773646 -58.704226)
		(size 0.508)
		(drill 0.254)
		(layers "F.Cu" "B.Cu")
		(net "UPI_CPU1_CPU0_P0P0_DP<3>")
	)
	(arc
		(start 141.654022 -60.362338)
		(mid 141.764086 -60.348066)
		(end 141.866874 -60.306204)
		(width 0.0889)
		(layer "F.Cu")
		(net "UPI_CPU1_CPU0_P0P0_DP<3>")
	)
	(arc
		(start 141.866874 -60.306458)
		(mid 141.947194 -60.27365)
		(end 142.033244 -60.262516)
		(width 0.0889)
		(layer "F.Cu")
		(net "UPI_CPU1_CPU0_P0P0_DP<3>")
	)
	(segment
		(start 177.93081 -105.532682)
		(end 177.93081 -105.532936)
		(width 0.1143)
		(layer "B.Cu")
		(net "UPI_CPU1_CPU0_P0P0_DP<3>")
	)
	(segment
		(start 311.203594 -95.298768)
		(end 312.140346 -93.994224)
		(width 0.1143)
		(layer "B.Cu")
		(net "UPI_CPU1_CPU0_P0P0_DP<3>")
	)
	(segment
		(start 235.070904 -107.94238)
		(end 244.311424 -104.372156)
		(width 0.1143)
		(layer "B.Cu")
		(net "UPI_CPU1_CPU0_P0P0_DP<3>")
	)
	(segment
		(start 307.613812 -77.164946)
		(end 307.412136 -77.1144)
		(width 0.0889)
		(layer "B.Cu")
		(net "UPI_CPU1_CPU0_P0P0_DP<3>")
	)
	(segment
		(start 292.134544 -105.244646)
		(end 302.816514 -107.380532)
		(width 0.1143)
		(layer "B.Cu")
		(net "UPI_CPU1_CPU0_P0P0_DP<3>")
	)
	(segment
		(start 187.36564 -107.354878)
		(end 189.902084 -107.582208)
		(width 0.1143)
		(layer "B.Cu")
		(net "UPI_CPU1_CPU0_P0P0_DP<3>")
	)
	(segment
		(start 312.09361 -92.192602)
		(end 311.94248 -86.37778)
		(width 0.1143)
		(layer "B.Cu")
		(net "UPI_CPU1_CPU0_P0P0_DP<3>")
	)
	(segment
		(start 308.16931 -77.190346)
		(end 308.048152 -77.190346)
		(width 0.1143)
		(layer "B.Cu")
		(net "UPI_CPU1_CPU0_P0P0_DP<3>")
	)
	(segment
		(start 177.080418 -104.75087)
		(end 177.245772 -104.743504)
		(width 0.1143)
		(layer "B.Cu")
		(net "UPI_CPU1_CPU0_P0P0_DP<3>")
	)
	(segment
		(start 177.414428 -104.898698)
		(end 177.421286 -105.064306)
		(width 0.1143)
		(layer "B.Cu")
		(net "UPI_CPU1_CPU0_P0P0_DP<3>")
	)
	(segment
		(start 301.305722 -70.572122)
		(end 301.037244 -70.091808)
		(width 0.0889)
		(layer "B.Cu")
		(net "UPI_CPU1_CPU0_P0P0_DP<3>")
	)
	(segment
		(start 310.762396 -81.227676)
		(end 310.851042 -81.087976)
		(width 0.1143)
		(layer "B.Cu")
		(net "UPI_CPU1_CPU0_P0P0_DP<3>")
	)
	(segment
		(start 225.59772 -107.466892)
		(end 235.070904 -107.94238)
		(width 0.1143)
		(layer "B.Cu")
		(net "UPI_CPU1_CPU0_P0P0_DP<3>")
	)
	(segment
		(start 259.31241 -106.580686)
		(end 281.779472 -108.843572)
		(width 0.1143)
		(layer "B.Cu")
		(net "UPI_CPU1_CPU0_P0P0_DP<3>")
	)
	(segment
		(start 192.15862 -108.447332)
		(end 194.855592 -111.709962)
		(width 0.1143)
		(layer "B.Cu")
		(net "UPI_CPU1_CPU0_P0P0_DP<3>")
	)
	(segment
		(start 310.800496 -80.865726)
		(end 310.800242 -80.86471)
		(width 0.1143)
		(layer "B.Cu")
		(net "UPI_CPU1_CPU0_P0P0_DP<3>")
	)
	(segment
		(start 195.751196 -112.653318)
		(end 196.29755 -112.964722)
		(width 0.1143)
		(layer "B.Cu")
		(net "UPI_CPU1_CPU0_P0P0_DP<3>")
	)
	(segment
		(start 310.609488 -80.55356)
		(end 310.698134 -80.41386)
		(width 0.1143)
		(layer "B.Cu")
		(net "UPI_CPU1_CPU0_P0P0_DP<3>")
	)
	(segment
		(start 146.96694 -58.89752)
		(end 147.72767 -58.89752)
		(width 0.1143)
		(layer "B.Cu")
		(net "UPI_CPU1_CPU0_P0P0_DP<3>")
	)
	(segment
		(start 154.989276 -66.159126)
		(end 159.37357 -88.075516)
		(width 0.1143)
		(layer "B.Cu")
		(net "UPI_CPU1_CPU0_P0P0_DP<3>")
	)
	(segment
		(start 310.851042 -81.087976)
		(end 310.800496 -80.865726)
		(width 0.1143)
		(layer "B.Cu")
		(net "UPI_CPU1_CPU0_P0P0_DP<3>")
	)
	(segment
		(start 169.326052 -100.796598)
		(end 170.998642 -102.398576)
		(width 0.1143)
		(layer "B.Cu")
		(net "UPI_CPU1_CPU0_P0P0_DP<3>")
	)
	(segment
		(start 159.37357 -88.075516)
		(end 165.728396 -95.33763)
		(width 0.1143)
		(layer "B.Cu")
		(net "UPI_CPU1_CPU0_P0P0_DP<3>")
	)
	(segment
		(start 281.779472 -108.843572)
		(end 284.556454 -108.275882)
		(width 0.1143)
		(layer "B.Cu")
		(net "UPI_CPU1_CPU0_P0P0_DP<3>")
	)
	(segment
		(start 310.918352 -81.915)
		(end 310.915304 -81.901792)
		(width 0.1143)
		(layer "B.Cu")
		(net "UPI_CPU1_CPU0_P0P0_DP<3>")
	)
	(segment
		(start 194.855592 -111.709962)
		(end 195.751196 -112.653318)
		(width 0.1143)
		(layer "B.Cu")
		(net "UPI_CPU1_CPU0_P0P0_DP<3>")
	)
	(segment
		(start 182.650384 -107.429046)
		(end 186.270138 -107.354878)
		(width 0.1143)
		(layer "B.Cu")
		(net "UPI_CPU1_CPU0_P0P0_DP<3>")
	)
	(segment
		(start 147.72767 -58.89752)
		(end 154.989276 -66.159126)
		(width 0.1143)
		(layer "B.Cu")
		(net "UPI_CPU1_CPU0_P0P0_DP<3>")
	)
	(segment
		(start 176.570894 -104.282494)
		(end 176.736248 -104.275128)
		(width 0.1143)
		(layer "B.Cu")
		(net "UPI_CPU1_CPU0_P0P0_DP<3>")
	)
	(segment
		(start 170.998642 -102.398576)
		(end 171.847256 -102.86619)
		(width 0.1143)
		(layer "B.Cu")
		(net "UPI_CPU1_CPU0_P0P0_DP<3>")
	)
	(segment
		(start 189.902084 -107.582208)
		(end 190.683134 -107.826302)
		(width 0.1143)
		(layer "B.Cu")
		(net "UPI_CPU1_CPU0_P0P0_DP<3>")
	)
	(segment
		(start 302.816514 -107.380532)
		(end 304.405538 -106.939334)
		(width 0.1143)
		(layer "B.Cu")
		(net "UPI_CPU1_CPU0_P0P0_DP<3>")
	)
	(segment
		(start 190.683134 -107.826302)
		(end 192.15862 -108.447332)
		(width 0.1143)
		(layer "B.Cu")
		(net "UPI_CPU1_CPU0_P0P0_DP<3>")
	)
	(segment
		(start 176.736248 -104.275128)
		(end 176.904904 -104.430322)
		(width 0.1143)
		(layer "B.Cu")
		(net "UPI_CPU1_CPU0_P0P0_DP<3>")
	)
	(segment
		(start 312.140346 -93.994224)
		(end 312.09869 -92.38869)
		(width 0.1143)
		(layer "B.Cu")
		(net "UPI_CPU1_CPU0_P0P0_DP<3>")
	)
	(segment
		(start 310.698134 -80.41386)
		(end 310.634126 -80.13192)
		(width 0.1143)
		(layer "B.Cu")
		(net "UPI_CPU1_CPU0_P0P0_DP<3>")
	)
	(segment
		(start 303.544732 -74.821288)
		(end 303.511966 -74.821288)
		(width 0.0889)
		(layer "B.Cu")
		(net "UPI_CPU1_CPU0_P0P0_DP<3>")
	)
	(segment
		(start 310.660542 -80.77708)
		(end 310.609488 -80.55356)
		(width 0.1143)
		(layer "B.Cu")
		(net "UPI_CPU1_CPU0_P0P0_DP<3>")
	)
	(segment
		(start 171.847256 -102.86619)
		(end 176.192688 -103.935022)
		(width 0.1143)
		(layer "B.Cu")
		(net "UPI_CPU1_CPU0_P0P0_DP<3>")
	)
	(segment
		(start 244.311424 -104.372156)
		(end 251.044964 -104.119172)
		(width 0.1143)
		(layer "B.Cu")
		(net "UPI_CPU1_CPU0_P0P0_DP<3>")
	)
	(segment
		(start 197.719188 -113.026444)
		(end 202.36561 -112.40643)
		(width 0.1143)
		(layer "B.Cu")
		(net "UPI_CPU1_CPU0_P0P0_DP<3>")
	)
	(segment
		(start 304.455576 -75.31481)
		(end 304.412904 -75.316334)
		(width 0.0889)
		(layer "B.Cu")
		(net "UPI_CPU1_CPU0_P0P0_DP<3>")
	)
	(segment
		(start 302.153066 -73.450704)
		(end 302.159416 -73.440036)
		(width 0.0889)
		(layer "B.Cu")
		(net "UPI_CPU1_CPU0_P0P0_DP<3>")
	)
	(segment
		(start 304.412904 -75.316334)
		(end 304.366676 -75.316334)
		(width 0.0889)
		(layer "B.Cu")
		(net "UPI_CPU1_CPU0_P0P0_DP<3>")
	)
	(segment
		(start 177.421286 -105.064306)
		(end 177.589942 -105.219246)
		(width 0.1143)
		(layer "B.Cu")
		(net "UPI_CPU1_CPU0_P0P0_DP<3>")
	)
	(segment
		(start 311.068212 -82.575908)
		(end 311.156858 -82.436208)
		(width 0.1143)
		(layer "B.Cu")
		(net "UPI_CPU1_CPU0_P0P0_DP<3>")
	)
	(segment
		(start 176.911762 -104.59593)
		(end 177.080418 -104.75087)
		(width 0.1143)
		(layer "B.Cu")
		(net "UPI_CPU1_CPU0_P0P0_DP<3>")
	)
	(segment
		(start 302.159416 -72.449436)
		(end 302.164242 -72.4408)
		(width 0.0889)
		(layer "B.Cu")
		(net "UPI_CPU1_CPU0_P0P0_DP<3>")
	)
	(segment
		(start 311.156858 -82.436208)
		(end 311.106058 -82.212942)
		(width 0.1143)
		(layer "B.Cu")
		(net "UPI_CPU1_CPU0_P0P0_DP<3>")
	)
	(segment
		(start 311.00395 -81.762092)
		(end 310.95315 -81.538826)
		(width 0.1143)
		(layer "B.Cu")
		(net "UPI_CPU1_CPU0_P0P0_DP<3>")
	)
	(segment
		(start 311.106058 -82.212942)
		(end 310.966358 -82.125312)
		(width 0.1143)
		(layer "B.Cu")
		(net "UPI_CPU1_CPU0_P0P0_DP<3>")
	)
	(segment
		(start 302.159416 -73.440036)
		(end 302.164242 -73.4314)
		(width 0.0889)
		(layer "B.Cu")
		(net "UPI_CPU1_CPU0_P0P0_DP<3>")
	)
	(segment
		(start 302.682402 -74.325734)
		(end 302.649636 -74.325734)
		(width 0.0889)
		(layer "B.Cu")
		(net "UPI_CPU1_CPU0_P0P0_DP<3>")
	)
	(segment
		(start 307.412136 -77.1144)
		(end 305.642264 -76.256134)
		(width 0.0889)
		(layer "B.Cu")
		(net "UPI_CPU1_CPU0_P0P0_DP<3>")
	)
	(segment
		(start 305.642264 -76.256134)
		(end 305.441858 -75.991974)
		(width 0.0889)
		(layer "B.Cu")
		(net "UPI_CPU1_CPU0_P0P0_DP<3>")
	)
	(segment
		(start 301.827692 -71.849488)
		(end 301.794926 -71.849488)
		(width 0.0889)
		(layer "B.Cu")
		(net "UPI_CPU1_CPU0_P0P0_DP<3>")
	)
	(segment
		(start 310.591708 -100.764086)
		(end 311.203594 -95.298768)
		(width 0.1143)
		(layer "B.Cu")
		(net "UPI_CPU1_CPU0_P0P0_DP<3>")
	)
	(segment
		(start 307.815488 -104.857042)
		(end 310.190134 -102.283768)
		(width 0.1143)
		(layer "B.Cu")
		(net "UPI_CPU1_CPU0_P0P0_DP<3>")
	)
	(segment
		(start 311.119266 -82.799428)
		(end 311.068212 -82.575908)
		(width 0.1143)
		(layer "B.Cu")
		(net "UPI_CPU1_CPU0_P0P0_DP<3>")
	)
	(segment
		(start 284.556454 -108.275882)
		(end 286.6136 -106.43997)
		(width 0.1143)
		(layer "B.Cu")
		(net "UPI_CPU1_CPU0_P0P0_DP<3>")
	)
	(segment
		(start 196.29755 -112.964722)
		(end 197.719188 -113.026444)
		(width 0.1143)
		(layer "B.Cu")
		(net "UPI_CPU1_CPU0_P0P0_DP<3>")
	)
	(segment
		(start 308.048152 -77.190346)
		(end 308.026054 -77.190346)
		(width 0.0889)
		(layer "B.Cu")
		(net "UPI_CPU1_CPU0_P0P0_DP<3>")
	)
	(segment
		(start 310.634126 -80.13192)
		(end 309.614062 -78.302358)
		(width 0.1143)
		(layer "B.Cu")
		(net "UPI_CPU1_CPU0_P0P0_DP<3>")
	)
	(segment
		(start 202.95489 -112.01273)
		(end 225.59772 -107.466892)
		(width 0.1143)
		(layer "B.Cu")
		(net "UPI_CPU1_CPU0_P0P0_DP<3>")
	)
	(segment
		(start 311.94248 -86.37778)
		(end 311.928764 -85.84057)
		(width 0.1143)
		(layer "B.Cu")
		(net "UPI_CPU1_CPU0_P0P0_DP<3>")
	)
	(segment
		(start 177.589942 -105.219246)
		(end 177.755296 -105.21188)
		(width 0.1143)
		(layer "B.Cu")
		(net "UPI_CPU1_CPU0_P0P0_DP<3>")
	)
	(segment
		(start 310.190134 -102.283768)
		(end 310.591708 -100.764086)
		(width 0.1143)
		(layer "B.Cu")
		(net "UPI_CPU1_CPU0_P0P0_DP<3>")
	)
	(segment
		(start 305.441858 -75.991974)
		(end 304.455576 -75.31481)
		(width 0.0889)
		(layer "B.Cu")
		(net "UPI_CPU1_CPU0_P0P0_DP<3>")
	)
	(segment
		(start 311.928764 -85.84057)
		(end 311.258712 -82.887058)
		(width 0.1143)
		(layer "B.Cu")
		(net "UPI_CPU1_CPU0_P0P0_DP<3>")
	)
	(segment
		(start 177.923952 -105.367074)
		(end 177.93081 -105.532682)
		(width 0.1143)
		(layer "B.Cu")
		(net "UPI_CPU1_CPU0_P0P0_DP<3>")
	)
	(segment
		(start 176.904904 -104.430322)
		(end 176.911762 -104.59593)
		(width 0.1143)
		(layer "B.Cu")
		(net "UPI_CPU1_CPU0_P0P0_DP<3>")
	)
	(segment
		(start 165.728396 -95.33763)
		(end 169.326052 -100.796598)
		(width 0.1143)
		(layer "B.Cu")
		(net "UPI_CPU1_CPU0_P0P0_DP<3>")
	)
	(segment
		(start 310.915304 -81.901792)
		(end 311.00395 -81.762092)
		(width 0.1143)
		(layer "B.Cu")
		(net "UPI_CPU1_CPU0_P0P0_DP<3>")
	)
	(segment
		(start 309.614062 -78.302358)
		(end 308.16931 -77.190346)
		(width 0.1143)
		(layer "B.Cu")
		(net "UPI_CPU1_CPU0_P0P0_DP<3>")
	)
	(segment
		(start 310.95315 -81.538826)
		(end 310.81345 -81.451196)
		(width 0.1143)
		(layer "B.Cu")
		(net "UPI_CPU1_CPU0_P0P0_DP<3>")
	)
	(segment
		(start 202.36561 -112.40643)
		(end 202.95489 -112.01273)
		(width 0.1143)
		(layer "B.Cu")
		(net "UPI_CPU1_CPU0_P0P0_DP<3>")
	)
	(segment
		(start 186.270138 -107.354878)
		(end 187.36564 -107.354878)
		(width 0.1143)
		(layer "B.Cu")
		(net "UPI_CPU1_CPU0_P0P0_DP<3>")
	)
	(segment
		(start 286.6136 -106.43997)
		(end 292.134544 -105.244646)
		(width 0.1143)
		(layer "B.Cu")
		(net "UPI_CPU1_CPU0_P0P0_DP<3>")
	)
	(segment
		(start 177.755296 -105.21188)
		(end 177.783236 -105.237534)
		(width 0.1143)
		(layer "B.Cu")
		(net "UPI_CPU1_CPU0_P0P0_DP<3>")
	)
	(segment
		(start 177.783236 -105.237534)
		(end 177.923952 -105.367074)
		(width 0.1143)
		(layer "B.Cu")
		(net "UPI_CPU1_CPU0_P0P0_DP<3>")
	)
	(segment
		(start 177.93081 -105.532936)
		(end 179.50434 -106.979466)
		(width 0.1143)
		(layer "B.Cu")
		(net "UPI_CPU1_CPU0_P0P0_DP<3>")
	)
	(segment
		(start 310.81345 -81.451196)
		(end 310.762396 -81.227676)
		(width 0.1143)
		(layer "B.Cu")
		(net "UPI_CPU1_CPU0_P0P0_DP<3>")
	)
	(segment
		(start 177.245772 -104.743504)
		(end 177.414428 -104.898698)
		(width 0.1143)
		(layer "B.Cu")
		(net "UPI_CPU1_CPU0_P0P0_DP<3>")
	)
	(segment
		(start 179.829714 -107.109768)
		(end 181.358032 -107.413806)
		(width 0.1143)
		(layer "B.Cu")
		(net "UPI_CPU1_CPU0_P0P0_DP<3>")
	)
	(segment
		(start 251.044964 -104.119172)
		(end 259.31241 -106.580686)
		(width 0.1143)
		(layer "B.Cu")
		(net "UPI_CPU1_CPU0_P0P0_DP<3>")
	)
	(segment
		(start 179.50434 -106.979466)
		(end 179.829714 -107.109768)
		(width 0.1143)
		(layer "B.Cu")
		(net "UPI_CPU1_CPU0_P0P0_DP<3>")
	)
	(segment
		(start 176.192688 -103.935022)
		(end 176.570894 -104.282494)
		(width 0.1143)
		(layer "B.Cu")
		(net "UPI_CPU1_CPU0_P0P0_DP<3>")
	)
	(segment
		(start 308.026054 -77.190346)
		(end 308.000654 -77.164946)
		(width 0.0889)
		(layer "B.Cu")
		(net "UPI_CPU1_CPU0_P0P0_DP<3>")
	)
	(segment
		(start 304.405538 -106.939334)
		(end 307.6956 -104.930194)
		(width 0.1143)
		(layer "B.Cu")
		(net "UPI_CPU1_CPU0_P0P0_DP<3>")
	)
	(segment
		(start 310.966358 -82.125312)
		(end 310.918352 -81.915)
		(width 0.1143)
		(layer "B.Cu")
		(net "UPI_CPU1_CPU0_P0P0_DP<3>")
	)
	(segment
		(start 308.000654 -77.164946)
		(end 307.613812 -77.164946)
		(width 0.0889)
		(layer "B.Cu")
		(net "UPI_CPU1_CPU0_P0P0_DP<3>")
	)
	(segment
		(start 311.258712 -82.887058)
		(end 311.119266 -82.799428)
		(width 0.1143)
		(layer "B.Cu")
		(net "UPI_CPU1_CPU0_P0P0_DP<3>")
	)
	(segment
		(start 312.09869 -92.38869)
		(end 312.09361 -92.192602)
		(width 0.1143)
		(layer "B.Cu")
		(net "UPI_CPU1_CPU0_P0P0_DP<3>")
	)
	(segment
		(start 310.800242 -80.86471)
		(end 310.660542 -80.77708)
		(width 0.1143)
		(layer "B.Cu")
		(net "UPI_CPU1_CPU0_P0P0_DP<3>")
	)
	(segment
		(start 302.153066 -72.460104)
		(end 302.159416 -72.449436)
		(width 0.0889)
		(layer "B.Cu")
		(net "UPI_CPU1_CPU0_P0P0_DP<3>")
	)
	(segment
		(start 307.6956 -104.930194)
		(end 307.815488 -104.857042)
		(width 0.1143)
		(layer "B.Cu")
		(net "UPI_CPU1_CPU0_P0P0_DP<3>")
	)
	(segment
		(start 146.773646 -58.704226)
		(end 146.96694 -58.89752)
		(width 0.1143)
		(layer "B.Cu")
		(net "UPI_CPU1_CPU0_P0P0_DP<3>")
	)
	(segment
		(start 181.358032 -107.413806)
		(end 182.650384 -107.429046)
		(width 0.1143)
		(layer "B.Cu")
		(net "UPI_CPU1_CPU0_P0P0_DP<3>")
	)
	(arc
		(start 302.164242 -72.4408)
		(mid 302.160495 -72.051544)
		(end 301.827692 -71.849488)
		(width 0.0889)
		(layer "B.Cu")
		(net "UPI_CPU1_CPU0_P0P0_DP<3>")
	)
	(arc
		(start 302.649636 -74.325734)
		(mid 302.157246 -74.026801)
		(end 302.153066 -73.450704)
		(width 0.0889)
		(layer "B.Cu")
		(net "UPI_CPU1_CPU0_P0P0_DP<3>")
	)
	(arc
		(start 303.511966 -74.821288)
		(mid 303.226542 -74.737821)
		(end 303.017936 -74.525886)
		(width 0.0889)
		(layer "B.Cu")
		(net "UPI_CPU1_CPU0_P0P0_DP<3>")
	)
	(arc
		(start 303.017936 -74.525886)
		(mid 302.876253 -74.382082)
		(end 302.682402 -74.325734)
		(width 0.0889)
		(layer "B.Cu")
		(net "UPI_CPU1_CPU0_P0P0_DP<3>")
	)
	(arc
		(start 302.159416 -73.039986)
		(mid 302.080194 -72.750868)
		(end 302.153066 -72.460104)
		(width 0.0889)
		(layer "B.Cu")
		(net "UPI_CPU1_CPU0_P0P0_DP<3>")
	)
	(arc
		(start 301.300896 -70.963536)
		(mid 301.354366 -70.768473)
		(end 301.305722 -70.572122)
		(width 0.0889)
		(layer "B.Cu")
		(net "UPI_CPU1_CPU0_P0P0_DP<3>")
	)
	(arc
		(start 304.366676 -75.316334)
		(mid 304.083459 -75.232053)
		(end 303.876456 -75.021186)
		(width 0.0889)
		(layer "B.Cu")
		(net "UPI_CPU1_CPU0_P0P0_DP<3>")
	)
	(arc
		(start 303.876456 -75.021186)
		(mid 303.736377 -74.87845)
		(end 303.544732 -74.821288)
		(width 0.0889)
		(layer "B.Cu")
		(net "UPI_CPU1_CPU0_P0P0_DP<3>")
	)
	(arc
		(start 301.037244 -70.091808)
		(mid 300.975252 -69.93762)
		(end 300.954186 -69.772784)
		(width 0.0889)
		(layer "B.Cu")
		(net "UPI_CPU1_CPU0_P0P0_DP<3>")
	)
	(arc
		(start 302.164242 -73.4314)
		(mid 302.212997 -73.235048)
		(end 302.159416 -73.039986)
		(width 0.0889)
		(layer "B.Cu")
		(net "UPI_CPU1_CPU0_P0P0_DP<3>")
	)
	(arc
		(start 301.794926 -71.849488)
		(mid 301.296675 -71.546648)
		(end 301.300896 -70.963536)
		(width 0.0889)
		(layer "B.Cu")
		(net "UPI_CPU1_CPU0_P0P0_DP<3>")
	)
	(segment
		(start 141.376908 -59.962288)
		(end 141.401546 -59.962288)
		(width 0.0889)
		(layer "F.Cu")
		(net "UPI_CPU1_CPU0_P0P0_DP<2>")
	)
	(segment
		(start 141.401546 -59.962288)
		(end 141.4018 -59.962034)
		(width 0.0889)
		(layer "F.Cu")
		(net "UPI_CPU1_CPU0_P0P0_DP<2>")
	)
	(segment
		(start 142.042134 -59.458098)
		(end 143.41094 -59.458098)
		(width 0.0889)
		(layer "F.Cu")
		(net "UPI_CPU1_CPU0_P0P0_DP<2>")
	)
	(segment
		(start 144.736566 -58.634376)
		(end 144.914112 -58.811922)
		(width 0.1143)
		(layer "F.Cu")
		(net "UPI_CPU1_CPU0_P0P0_DP<2>")
	)
	(segment
		(start 143.725138 -59.47918)
		(end 144.569942 -58.634376)
		(width 0.1143)
		(layer "F.Cu")
		(net "UPI_CPU1_CPU0_P0P0_DP<2>")
	)
	(segment
		(start 300.382686 -71.753984)
		(end 300.954186 -71.753984)
		(width 0.1143)
		(layer "F.Cu")
		(net "UPI_CPU1_CPU0_P0P0_DP<2>")
	)
	(segment
		(start 144.569942 -58.634376)
		(end 144.736566 -58.634376)
		(width 0.1143)
		(layer "F.Cu")
		(net "UPI_CPU1_CPU0_P0P0_DP<2>")
	)
	(segment
		(start 141.929104 -59.617356)
		(end 141.929104 -59.571128)
		(width 0.0889)
		(layer "F.Cu")
		(net "UPI_CPU1_CPU0_P0P0_DP<2>")
	)
	(segment
		(start 141.4018 -59.962034)
		(end 141.40561 -59.962034)
		(width 0.0889)
		(layer "F.Cu")
		(net "UPI_CPU1_CPU0_P0P0_DP<2>")
	)
	(segment
		(start 143.41094 -59.458098)
		(end 143.432022 -59.47918)
		(width 0.0889)
		(layer "F.Cu")
		(net "UPI_CPU1_CPU0_P0P0_DP<2>")
	)
	(segment
		(start 143.432022 -59.47918)
		(end 143.725138 -59.47918)
		(width 0.1143)
		(layer "F.Cu")
		(net "UPI_CPU1_CPU0_P0P0_DP<2>")
	)
	(segment
		(start 140.979398 -60.275978)
		(end 141.045184 -60.162186)
		(width 0.0889)
		(layer "F.Cu")
		(net "UPI_CPU1_CPU0_P0P0_DP<2>")
	)
	(via
		(at 144.914112 -58.811922)
		(size 0.508)
		(drill 0.254)
		(layers "F.Cu" "B.Cu")
		(net "UPI_CPU1_CPU0_P0P0_DP<2>")
	)
	(via
		(at 300.954186 -71.753984)
		(size 0.508)
		(drill 0.254)
		(layers "F.Cu" "B.Cu")
		(net "UPI_CPU1_CPU0_P0P0_DP<2>")
	)
	(via
		(at 310.757062 -85.424772)
		(size 0.508)
		(drill 0.254)
		(layers "F.Cu" "B.Cu")
		(net "UPI_CPU1_CPU0_P0P0_DP<2>")
	)
	(arc
		(start 141.06525 -60.130944)
		(mid 141.201405 -60.010268)
		(end 141.376908 -59.962288)
		(width 0.0889)
		(layer "F.Cu")
		(net "UPI_CPU1_CPU0_P0P0_DP<2>")
	)
	(arc
		(start 140.533374 -60.857384)
		(mid 140.775434 -60.581294)
		(end 140.979398 -60.275978)
		(width 0.0889)
		(layer "F.Cu")
		(net "UPI_CPU1_CPU0_P0P0_DP<2>")
	)
	(arc
		(start 141.045184 -60.162186)
		(mid 141.054853 -60.146331)
		(end 141.06525 -60.130944)
		(width 0.0889)
		(layer "F.Cu")
		(net "UPI_CPU1_CPU0_P0P0_DP<2>")
	)
	(arc
		(start 141.929104 -59.571128)
		(mid 141.96221 -59.491204)
		(end 142.042134 -59.458098)
		(width 0.0889)
		(layer "F.Cu")
		(net "UPI_CPU1_CPU0_P0P0_DP<2>")
	)
	(arc
		(start 141.40561 -59.962034)
		(mid 141.7168 -59.864813)
		(end 141.929104 -59.617356)
		(width 0.0889)
		(layer "F.Cu")
		(net "UPI_CPU1_CPU0_P0P0_DP<2>")
	)
	(segment
		(start 304.98034 -76.429616)
		(end 304.855118 -76.441808)
		(width 0.0889)
		(layer "B.Cu")
		(net "UPI_CPU1_CPU0_P0P0_DP<2>")
	)
	(segment
		(start 300.954186 -71.41591)
		(end 300.954186 -71.753984)
		(width 0.0889)
		(layer "B.Cu")
		(net "UPI_CPU1_CPU0_P0P0_DP<2>")
	)
	(segment
		(start 307.723286 -77.932534)
		(end 307.687472 -77.932534)
		(width 0.0889)
		(layer "B.Cu")
		(net "UPI_CPU1_CPU0_P0P0_DP<2>")
	)
	(segment
		(start 234.954826 -107.208574)
		(end 243.635276 -103.856282)
		(width 0.1143)
		(layer "B.Cu")
		(net "UPI_CPU1_CPU0_P0P0_DP<2>")
	)
	(segment
		(start 195.290186 -111.407448)
		(end 195.543932 -111.67491)
		(width 0.1143)
		(layer "B.Cu")
		(net "UPI_CPU1_CPU0_P0P0_DP<2>")
	)
	(segment
		(start 144.911572 -58.758328)
		(end 145.054828 -58.599832)
		(width 0.0889)
		(layer "B.Cu")
		(net "UPI_CPU1_CPU0_P0P0_DP<2>")
	)
	(segment
		(start 146.1516 -58.199274)
		(end 146.344894 -58.00598)
		(width 0.0889)
		(layer "B.Cu")
		(net "UPI_CPU1_CPU0_P0P0_DP<2>")
	)
	(segment
		(start 145.905474 -58.4454)
		(end 146.0246 -58.4454)
		(width 0.0889)
		(layer "B.Cu")
		(net "UPI_CPU1_CPU0_P0P0_DP<2>")
	)
	(segment
		(start 309.945278 -81.915)
		(end 309.465726 -79.84109)
		(width 0.1143)
		(layer "B.Cu")
		(net "UPI_CPU1_CPU0_P0P0_DP<2>")
	)
	(segment
		(start 303.868582 -75.621388)
		(end 303.515268 -75.621388)
		(width 0.0889)
		(layer "B.Cu")
		(net "UPI_CPU1_CPU0_P0P0_DP<2>")
	)
	(segment
		(start 311.08142 -86.82736)
		(end 310.895238 -86.02218)
		(width 0.1143)
		(layer "B.Cu")
		(net "UPI_CPU1_CPU0_P0P0_DP<2>")
	)
	(segment
		(start 196.560694 -112.453166)
		(end 197.69709 -112.502442)
		(width 0.1143)
		(layer "B.Cu")
		(net "UPI_CPU1_CPU0_P0P0_DP<2>")
	)
	(segment
		(start 144.914112 -58.811922)
		(end 144.911572 -58.758328)
		(width 0.0889)
		(layer "B.Cu")
		(net "UPI_CPU1_CPU0_P0P0_DP<2>")
	)
	(segment
		(start 291.125402 -104.913176)
		(end 292.144196 -104.709468)
		(width 0.1143)
		(layer "B.Cu")
		(net "UPI_CPU1_CPU0_P0P0_DP<2>")
	)
	(segment
		(start 310.308752 -95.038418)
		(end 311.214516 -93.7768)
		(width 0.1143)
		(layer "B.Cu")
		(net "UPI_CPU1_CPU0_P0P0_DP<2>")
	)
	(segment
		(start 195.54571 -111.676688)
		(end 196.06133 -112.21974)
		(width 0.1143)
		(layer "B.Cu")
		(net "UPI_CPU1_CPU0_P0P0_DP<2>")
	)
	(segment
		(start 311.259728 -93.713808)
		(end 311.236614 -92.825062)
		(width 0.1143)
		(layer "B.Cu")
		(net "UPI_CPU1_CPU0_P0P0_DP<2>")
	)
	(segment
		(start 311.214516 -93.7768)
		(end 311.259728 -93.713808)
		(width 0.1143)
		(layer "B.Cu")
		(net "UPI_CPU1_CPU0_P0P0_DP<2>")
	)
	(segment
		(start 305.980592 -76.937108)
		(end 305.802792 -76.924154)
		(width 0.0889)
		(layer "B.Cu")
		(net "UPI_CPU1_CPU0_P0P0_DP<2>")
	)
	(segment
		(start 305.519074 -76.994512)
		(end 305.128422 -76.668884)
		(width 0.0889)
		(layer "B.Cu")
		(net "UPI_CPU1_CPU0_P0P0_DP<2>")
	)
	(segment
		(start 305.128422 -76.668884)
		(end 305.1175 -76.543916)
		(width 0.0889)
		(layer "B.Cu")
		(net "UPI_CPU1_CPU0_P0P0_DP<2>")
	)
	(segment
		(start 145.147284 -58.569098)
		(end 145.781776 -58.569098)
		(width 0.0889)
		(layer "B.Cu")
		(net "UPI_CPU1_CPU0_P0P0_DP<2>")
	)
	(segment
		(start 305.1175 -76.543916)
		(end 304.98034 -76.429616)
		(width 0.0889)
		(layer "B.Cu")
		(net "UPI_CPU1_CPU0_P0P0_DP<2>")
	)
	(segment
		(start 307.687472 -77.932534)
		(end 307.330602 -77.575664)
		(width 0.0889)
		(layer "B.Cu")
		(net "UPI_CPU1_CPU0_P0P0_DP<2>")
	)
	(segment
		(start 148.227796 -58.61939)
		(end 148.227796 -58.65495)
		(width 0.0889)
		(layer "B.Cu")
		(net "UPI_CPU1_CPU0_P0P0_DP<2>")
	)
	(segment
		(start 225.54311 -106.736896)
		(end 234.954826 -107.208574)
		(width 0.1143)
		(layer "B.Cu")
		(net "UPI_CPU1_CPU0_P0P0_DP<2>")
	)
	(segment
		(start 251.7013 -103.55707)
		(end 259.418582 -105.855008)
		(width 0.1143)
		(layer "B.Cu")
		(net "UPI_CPU1_CPU0_P0P0_DP<2>")
	)
	(segment
		(start 202.671426 -111.329216)
		(end 225.54311 -106.736896)
		(width 0.1143)
		(layer "B.Cu")
		(net "UPI_CPU1_CPU0_P0P0_DP<2>")
	)
	(segment
		(start 186.525408 -106.51363)
		(end 186.553856 -106.5149)
		(width 0.1143)
		(layer "B.Cu")
		(net "UPI_CPU1_CPU0_P0P0_DP<2>")
	)
	(segment
		(start 310.895238 -86.02218)
		(end 310.757062 -85.424772)
		(width 0.1143)
		(layer "B.Cu")
		(net "UPI_CPU1_CPU0_P0P0_DP<2>")
	)
	(segment
		(start 195.543932 -111.67491)
		(end 195.54571 -111.676688)
		(width 0.1143)
		(layer "B.Cu")
		(net "UPI_CPU1_CPU0_P0P0_DP<2>")
	)
	(segment
		(start 309.4609 -79.8322)
		(end 309.257192 -79.466694)
		(width 0.1143)
		(layer "B.Cu")
		(net "UPI_CPU1_CPU0_P0P0_DP<2>")
	)
	(segment
		(start 300.971966 -72.154034)
		(end 300.9392 -72.154034)
		(width 0.0889)
		(layer "B.Cu")
		(net "UPI_CPU1_CPU0_P0P0_DP<2>")
	)
	(segment
		(start 301.472346 -73.450704)
		(end 301.465996 -73.440036)
		(width 0.0889)
		(layer "B.Cu")
		(net "UPI_CPU1_CPU0_P0P0_DP<2>")
	)
	(segment
		(start 304.296572 -75.861164)
		(end 304.159412 -75.746864)
		(width 0.0889)
		(layer "B.Cu")
		(net "UPI_CPU1_CPU0_P0P0_DP<2>")
	)
	(segment
		(start 166.85006 -95.720154)
		(end 169.891964 -100.333048)
		(width 0.1143)
		(layer "B.Cu")
		(net "UPI_CPU1_CPU0_P0P0_DP<2>")
	)
	(segment
		(start 309.407814 -101.994462)
		(end 309.726584 -101.010974)
		(width 0.1143)
		(layer "B.Cu")
		(net "UPI_CPU1_CPU0_P0P0_DP<2>")
	)
	(segment
		(start 182.7784 -106.1212)
		(end 184.7088 -106.4006)
		(width 0.1143)
		(layer "B.Cu")
		(net "UPI_CPU1_CPU0_P0P0_DP<2>")
	)
	(segment
		(start 311.102502 -87.646002)
		(end 311.08142 -86.82736)
		(width 0.1143)
		(layer "B.Cu")
		(net "UPI_CPU1_CPU0_P0P0_DP<2>")
	)
	(segment
		(start 155.47594 -65.903348)
		(end 159.838136 -87.7062)
		(width 0.1143)
		(layer "B.Cu")
		(net "UPI_CPU1_CPU0_P0P0_DP<2>")
	)
	(segment
		(start 145.781776 -58.569098)
		(end 145.905474 -58.4454)
		(width 0.0889)
		(layer "B.Cu")
		(net "UPI_CPU1_CPU0_P0P0_DP<2>")
	)
	(segment
		(start 304.717958 -76.327508)
		(end 304.707036 -76.20254)
		(width 0.0889)
		(layer "B.Cu")
		(net "UPI_CPU1_CPU0_P0P0_DP<2>")
	)
	(segment
		(start 197.69709 -112.502442)
		(end 201.721212 -111.963962)
		(width 0.1143)
		(layer "B.Cu")
		(net "UPI_CPU1_CPU0_P0P0_DP<2>")
	)
	(segment
		(start 302.555402 -106.792522)
		(end 304.306478 -106.35742)
		(width 0.1143)
		(layer "B.Cu")
		(net "UPI_CPU1_CPU0_P0P0_DP<2>")
	)
	(segment
		(start 305.707034 -77.007974)
		(end 305.519074 -76.994512)
		(width 0.0889)
		(layer "B.Cu")
		(net "UPI_CPU1_CPU0_P0P0_DP<2>")
	)
	(segment
		(start 284.14726 -107.619546)
		(end 285.996888 -106.009948)
		(width 0.1143)
		(layer "B.Cu")
		(net "UPI_CPU1_CPU0_P0P0_DP<2>")
	)
	(segment
		(start 148.227796 -58.65495)
		(end 148.235924 -58.663078)
		(width 0.0889)
		(layer "B.Cu")
		(net "UPI_CPU1_CPU0_P0P0_DP<2>")
	)
	(segment
		(start 305.802792 -76.924154)
		(end 305.707034 -77.007974)
		(width 0.0889)
		(layer "B.Cu")
		(net "UPI_CPU1_CPU0_P0P0_DP<2>")
	)
	(segment
		(start 304.159412 -75.746864)
		(end 304.03419 -75.759056)
		(width 0.0889)
		(layer "B.Cu")
		(net "UPI_CPU1_CPU0_P0P0_DP<2>")
	)
	(segment
		(start 311.20207 -91.49207)
		(end 311.102502 -87.646002)
		(width 0.1143)
		(layer "B.Cu")
		(net "UPI_CPU1_CPU0_P0P0_DP<2>")
	)
	(segment
		(start 310.757062 -85.424772)
		(end 309.945278 -81.915)
		(width 0.1143)
		(layer "B.Cu")
		(net "UPI_CPU1_CPU0_P0P0_DP<2>")
	)
	(segment
		(start 306.836064 -104.841548)
		(end 309.407814 -101.994462)
		(width 0.1143)
		(layer "B.Cu")
		(net "UPI_CPU1_CPU0_P0P0_DP<2>")
	)
	(segment
		(start 306.314856 -77.0509)
		(end 306.06365 -77.03312)
		(width 0.0889)
		(layer "B.Cu")
		(net "UPI_CPU1_CPU0_P0P0_DP<2>")
	)
	(segment
		(start 181.30393 -105.336594)
		(end 182.7784 -106.1212)
		(width 0.1143)
		(layer "B.Cu")
		(net "UPI_CPU1_CPU0_P0P0_DP<2>")
	)
	(segment
		(start 147.614386 -58.00598)
		(end 148.227796 -58.61939)
		(width 0.0889)
		(layer "B.Cu")
		(net "UPI_CPU1_CPU0_P0P0_DP<2>")
	)
	(segment
		(start 302.689006 -75.125834)
		(end 302.65624 -75.125834)
		(width 0.0889)
		(layer "B.Cu")
		(net "UPI_CPU1_CPU0_P0P0_DP<2>")
	)
	(segment
		(start 304.855118 -76.441808)
		(end 304.717958 -76.327508)
		(width 0.0889)
		(layer "B.Cu")
		(net "UPI_CPU1_CPU0_P0P0_DP<2>")
	)
	(segment
		(start 172.12056 -102.165658)
		(end 178.318668 -103.689658)
		(width 0.1143)
		(layer "B.Cu")
		(net "UPI_CPU1_CPU0_P0P0_DP<2>")
	)
	(segment
		(start 301.834296 -74.630788)
		(end 301.80153 -74.630788)
		(width 0.0889)
		(layer "B.Cu")
		(net "UPI_CPU1_CPU0_P0P0_DP<2>")
	)
	(segment
		(start 304.569876 -76.08824)
		(end 304.444654 -76.100432)
		(width 0.0889)
		(layer "B.Cu")
		(net "UPI_CPU1_CPU0_P0P0_DP<2>")
	)
	(segment
		(start 184.7088 -106.4006)
		(end 186.525408 -106.51363)
		(width 0.1143)
		(layer "B.Cu")
		(net "UPI_CPU1_CPU0_P0P0_DP<2>")
	)
	(segment
		(start 301.465996 -73.440036)
		(end 301.46117 -73.4314)
		(width 0.0889)
		(layer "B.Cu")
		(net "UPI_CPU1_CPU0_P0P0_DP<2>")
	)
	(segment
		(start 180.656738 -105.095294)
		(end 181.30393 -105.336594)
		(width 0.1143)
		(layer "B.Cu")
		(net "UPI_CPU1_CPU0_P0P0_DP<2>")
	)
	(segment
		(start 307.330602 -77.575664)
		(end 306.314856 -77.0509)
		(width 0.0889)
		(layer "B.Cu")
		(net "UPI_CPU1_CPU0_P0P0_DP<2>")
	)
	(segment
		(start 306.06365 -77.03312)
		(end 305.980592 -76.937108)
		(width 0.0889)
		(layer "B.Cu")
		(net "UPI_CPU1_CPU0_P0P0_DP<2>")
	)
	(segment
		(start 304.03419 -75.759056)
		(end 303.868582 -75.621388)
		(width 0.0889)
		(layer "B.Cu")
		(net "UPI_CPU1_CPU0_P0P0_DP<2>")
	)
	(segment
		(start 285.996888 -106.009948)
		(end 289.060382 -105.325926)
		(width 0.1143)
		(layer "B.Cu")
		(net "UPI_CPU1_CPU0_P0P0_DP<2>")
	)
	(segment
		(start 289.060382 -105.325926)
		(end 291.125402 -104.913176)
		(width 0.1143)
		(layer "B.Cu")
		(net "UPI_CPU1_CPU0_P0P0_DP<2>")
	)
	(segment
		(start 146.0246 -58.4454)
		(end 146.1516 -58.3184)
		(width 0.0889)
		(layer "B.Cu")
		(net "UPI_CPU1_CPU0_P0P0_DP<2>")
	)
	(segment
		(start 309.726584 -101.010974)
		(end 310.308752 -95.038418)
		(width 0.1143)
		(layer "B.Cu")
		(net "UPI_CPU1_CPU0_P0P0_DP<2>")
	)
	(segment
		(start 309.465726 -79.84109)
		(end 309.4609 -79.8322)
		(width 0.1143)
		(layer "B.Cu")
		(net "UPI_CPU1_CPU0_P0P0_DP<2>")
	)
	(segment
		(start 281.61996 -108.091224)
		(end 284.14726 -107.619546)
		(width 0.1143)
		(layer "B.Cu")
		(net "UPI_CPU1_CPU0_P0P0_DP<2>")
	)
	(segment
		(start 192.334388 -107.720892)
		(end 195.290186 -111.407448)
		(width 0.1143)
		(layer "B.Cu")
		(net "UPI_CPU1_CPU0_P0P0_DP<2>")
	)
	(segment
		(start 148.235924 -58.663078)
		(end 155.47594 -65.903348)
		(width 0.1143)
		(layer "B.Cu")
		(net "UPI_CPU1_CPU0_P0P0_DP<2>")
	)
	(segment
		(start 311.236614 -92.825062)
		(end 311.23636 -92.824808)
		(width 0.1143)
		(layer "B.Cu")
		(net "UPI_CPU1_CPU0_P0P0_DP<2>")
	)
	(segment
		(start 178.318668 -103.689658)
		(end 180.656738 -105.095294)
		(width 0.1143)
		(layer "B.Cu")
		(net "UPI_CPU1_CPU0_P0P0_DP<2>")
	)
	(segment
		(start 146.344894 -58.00598)
		(end 147.614386 -58.00598)
		(width 0.0889)
		(layer "B.Cu")
		(net "UPI_CPU1_CPU0_P0P0_DP<2>")
	)
	(segment
		(start 186.9059 -106.5149)
		(end 191.139064 -107.273598)
		(width 0.1143)
		(layer "B.Cu")
		(net "UPI_CPU1_CPU0_P0P0_DP<2>")
	)
	(segment
		(start 304.707036 -76.20254)
		(end 304.569876 -76.08824)
		(width 0.0889)
		(layer "B.Cu")
		(net "UPI_CPU1_CPU0_P0P0_DP<2>")
	)
	(segment
		(start 191.139064 -107.273598)
		(end 192.334388 -107.720892)
		(width 0.1143)
		(layer "B.Cu")
		(net "UPI_CPU1_CPU0_P0P0_DP<2>")
	)
	(segment
		(start 146.1516 -58.3184)
		(end 146.1516 -58.199274)
		(width 0.0889)
		(layer "B.Cu")
		(net "UPI_CPU1_CPU0_P0P0_DP<2>")
	)
	(segment
		(start 311.23636 -92.824808)
		(end 311.20207 -91.49207)
		(width 0.1143)
		(layer "B.Cu")
		(net "UPI_CPU1_CPU0_P0P0_DP<2>")
	)
	(segment
		(start 201.721212 -111.963962)
		(end 202.671426 -111.329216)
		(width 0.1143)
		(layer "B.Cu")
		(net "UPI_CPU1_CPU0_P0P0_DP<2>")
	)
	(segment
		(start 304.444654 -76.100432)
		(end 304.307494 -75.986132)
		(width 0.0889)
		(layer "B.Cu")
		(net "UPI_CPU1_CPU0_P0P0_DP<2>")
	)
	(segment
		(start 169.891964 -100.333048)
		(end 171.379388 -101.75748)
		(width 0.1143)
		(layer "B.Cu")
		(net "UPI_CPU1_CPU0_P0P0_DP<2>")
	)
	(segment
		(start 159.838136 -87.7062)
		(end 166.85006 -95.720154)
		(width 0.1143)
		(layer "B.Cu")
		(net "UPI_CPU1_CPU0_P0P0_DP<2>")
	)
	(segment
		(start 304.307494 -75.986132)
		(end 304.296572 -75.861164)
		(width 0.0889)
		(layer "B.Cu")
		(net "UPI_CPU1_CPU0_P0P0_DP<2>")
	)
	(segment
		(start 259.418582 -105.855008)
		(end 281.61996 -108.091224)
		(width 0.1143)
		(layer "B.Cu")
		(net "UPI_CPU1_CPU0_P0P0_DP<2>")
	)
	(segment
		(start 145.054828 -58.599832)
		(end 145.147284 -58.569098)
		(width 0.0889)
		(layer "B.Cu")
		(net "UPI_CPU1_CPU0_P0P0_DP<2>")
	)
	(segment
		(start 300.896274 -71.357998)
		(end 300.954186 -71.41591)
		(width 0.0889)
		(layer "B.Cu")
		(net "UPI_CPU1_CPU0_P0P0_DP<2>")
	)
	(segment
		(start 292.144196 -104.709468)
		(end 302.555402 -106.792522)
		(width 0.1143)
		(layer "B.Cu")
		(net "UPI_CPU1_CPU0_P0P0_DP<2>")
	)
	(segment
		(start 186.553856 -106.5149)
		(end 186.9059 -106.5149)
		(width 0.1143)
		(layer "B.Cu")
		(net "UPI_CPU1_CPU0_P0P0_DP<2>")
	)
	(segment
		(start 171.379388 -101.75748)
		(end 172.12056 -102.165658)
		(width 0.1143)
		(layer "B.Cu")
		(net "UPI_CPU1_CPU0_P0P0_DP<2>")
	)
	(segment
		(start 309.257192 -79.466694)
		(end 307.723286 -77.932534)
		(width 0.1143)
		(layer "B.Cu")
		(net "UPI_CPU1_CPU0_P0P0_DP<2>")
	)
	(segment
		(start 304.306478 -106.35742)
		(end 306.836064 -104.841548)
		(width 0.1143)
		(layer "B.Cu")
		(net "UPI_CPU1_CPU0_P0P0_DP<2>")
	)
	(segment
		(start 243.635276 -103.856282)
		(end 251.7013 -103.55707)
		(width 0.1143)
		(layer "B.Cu")
		(net "UPI_CPU1_CPU0_P0P0_DP<2>")
	)
	(segment
		(start 196.06133 -112.21974)
		(end 196.560694 -112.453166)
		(width 0.1143)
		(layer "B.Cu")
		(net "UPI_CPU1_CPU0_P0P0_DP<2>")
	)
	(arc
		(start 301.46117 -73.4314)
		(mid 301.412415 -73.235048)
		(end 301.465996 -73.039986)
		(width 0.0889)
		(layer "B.Cu")
		(net "UPI_CPU1_CPU0_P0P0_DP<2>")
	)
	(arc
		(start 302.65624 -75.125834)
		(mid 302.464598 -75.068668)
		(end 302.324516 -74.925936)
		(width 0.0889)
		(layer "B.Cu")
		(net "UPI_CPU1_CPU0_P0P0_DP<2>")
	)
	(arc
		(start 300.9392 -72.154034)
		(mid 300.605678 -71.951409)
		(end 300.603158 -71.561198)
		(width 0.0889)
		(layer "B.Cu")
		(net "UPI_CPU1_CPU0_P0P0_DP<2>")
	)
	(arc
		(start 303.515268 -75.621388)
		(mid 303.323251 -75.56428)
		(end 303.183036 -75.421236)
		(width 0.0889)
		(layer "B.Cu")
		(net "UPI_CPU1_CPU0_P0P0_DP<2>")
	)
	(arc
		(start 301.465996 -73.039986)
		(mid 301.470325 -72.456814)
		(end 300.971966 -72.154034)
		(width 0.0889)
		(layer "B.Cu")
		(net "UPI_CPU1_CPU0_P0P0_DP<2>")
	)
	(arc
		(start 303.183036 -75.421236)
		(mid 302.974428 -75.209304)
		(end 302.689006 -75.125834)
		(width 0.0889)
		(layer "B.Cu")
		(net "UPI_CPU1_CPU0_P0P0_DP<2>")
	)
	(arc
		(start 301.80153 -74.630788)
		(mid 301.463361 -74.42599)
		(end 301.465996 -74.030586)
		(width 0.0889)
		(layer "B.Cu")
		(net "UPI_CPU1_CPU0_P0P0_DP<2>")
	)
	(arc
		(start 302.324516 -74.925936)
		(mid 302.117512 -74.715072)
		(end 301.834296 -74.630788)
		(width 0.0889)
		(layer "B.Cu")
		(net "UPI_CPU1_CPU0_P0P0_DP<2>")
	)
	(arc
		(start 301.465996 -74.030586)
		(mid 301.545218 -73.741468)
		(end 301.472346 -73.450704)
		(width 0.0889)
		(layer "B.Cu")
		(net "UPI_CPU1_CPU0_P0P0_DP<2>")
	)
	(arc
		(start 300.603158 -71.561198)
		(mid 300.72581 -71.425093)
		(end 300.896274 -71.357998)
		(width 0.0889)
		(layer "B.Cu")
		(net "UPI_CPU1_CPU0_P0P0_DP<2>")
	)
	(segment
		(start 142.250414 -57.885584)
		(end 142.90802 -57.885584)
		(width 0.1143)
		(layer "F.Cu")
		(net "UPI_CPU1_CPU0_P0P0_DP<1>")
	)
	(segment
		(start 299.524166 -72.249538)
		(end 300.095666 -72.249538)
		(width 0.1143)
		(layer "F.Cu")
		(net "UPI_CPU1_CPU0_P0P0_DP<1>")
	)
	(via
		(at 152.196546 -61.110876)
		(size 0.508)
		(drill 0.254)
		(layers "F.Cu" "B.Cu")
		(net "UPI_CPU1_CPU0_P0P0_DP<1>")
	)
	(via
		(at 300.095666 -72.249538)
		(size 0.508)
		(drill 0.254)
		(layers "F.Cu" "B.Cu")
		(net "UPI_CPU1_CPU0_P0P0_DP<1>")
	)
	(via
		(at 142.90802 -57.885584)
		(size 0.508)
		(drill 0.254)
		(layers "F.Cu" "B.Cu")
		(net "UPI_CPU1_CPU0_P0P0_DP<1>")
	)
	(segment
		(start 308.362858 -82.098388)
		(end 308.362604 -82.097372)
		(width 0.1143)
		(layer "B.Cu")
		(net "UPI_CPU1_CPU0_P0P0_DP<1>")
	)
	(segment
		(start 280.04389 -106.25836)
		(end 280.047954 -106.257344)
		(width 0.1143)
		(layer "B.Cu")
		(net "UPI_CPU1_CPU0_P0P0_DP<1>")
	)
	(segment
		(start 306.394612 -78.276196)
		(end 305.97094 -78.300834)
		(width 0.0889)
		(layer "B.Cu")
		(net "UPI_CPU1_CPU0_P0P0_DP<1>")
	)
	(segment
		(start 302.412654 -105.733088)
		(end 304.127916 -105.276142)
		(width 0.1143)
		(layer "B.Cu")
		(net "UPI_CPU1_CPU0_P0P0_DP<1>")
	)
	(segment
		(start 185.027316 -105.338372)
		(end 186.450986 -105.388918)
		(width 0.1143)
		(layer "B.Cu")
		(net "UPI_CPU1_CPU0_P0P0_DP<1>")
	)
	(segment
		(start 148.689568 -57.603898)
		(end 148.653246 -57.603898)
		(width 0.0889)
		(layer "B.Cu")
		(net "UPI_CPU1_CPU0_P0P0_DP<1>")
	)
	(segment
		(start 309.667402 -90.825828)
		(end 309.78856 -90.69832)
		(width 0.1143)
		(layer "B.Cu")
		(net "UPI_CPU1_CPU0_P0P0_DP<1>")
	)
	(segment
		(start 302.682402 -76.306934)
		(end 302.649636 -76.306934)
		(width 0.0889)
		(layer "B.Cu")
		(net "UPI_CPU1_CPU0_P0P0_DP<1>")
	)
	(segment
		(start 283.719016 -105.702862)
		(end 284.639766 -105.538524)
		(width 0.1143)
		(layer "B.Cu")
		(net "UPI_CPU1_CPU0_P0P0_DP<1>")
	)
	(segment
		(start 308.239414 -81.63941)
		(end 307.754528 -79.826866)
		(width 0.1143)
		(layer "B.Cu")
		(net "UPI_CPU1_CPU0_P0P0_DP<1>")
	)
	(segment
		(start 281.031696 -106.503216)
		(end 281.29738 -106.098848)
		(width 0.1143)
		(layer "B.Cu")
		(net "UPI_CPU1_CPU0_P0P0_DP<1>")
	)
	(segment
		(start 300.442376 -74.430636)
		(end 300.447202 -74.422)
		(width 0.0889)
		(layer "B.Cu")
		(net "UPI_CPU1_CPU0_P0P0_DP<1>")
	)
	(segment
		(start 281.452828 -106.06659)
		(end 281.454606 -106.063796)
		(width 0.1143)
		(layer "B.Cu")
		(net "UPI_CPU1_CPU0_P0P0_DP<1>")
	)
	(segment
		(start 241.028982 -103.76789)
		(end 242.852956 -103.062786)
		(width 0.1143)
		(layer "B.Cu")
		(net "UPI_CPU1_CPU0_P0P0_DP<1>")
	)
	(segment
		(start 308.760876 -84.0486)
		(end 308.700932 -83.827112)
		(width 0.1143)
		(layer "B.Cu")
		(net "UPI_CPU1_CPU0_P0P0_DP<1>")
	)
	(segment
		(start 309.693056 -91.811348)
		(end 309.687214 -91.582494)
		(width 0.1143)
		(layer "B.Cu")
		(net "UPI_CPU1_CPU0_P0P0_DP<1>")
	)
	(segment
		(start 300.442376 -73.440036)
		(end 300.447202 -73.4314)
		(width 0.0889)
		(layer "B.Cu")
		(net "UPI_CPU1_CPU0_P0P0_DP<1>")
	)
	(segment
		(start 308.211982 -101.477572)
		(end 308.433216 -100.769928)
		(width 0.1143)
		(layer "B.Cu")
		(net "UPI_CPU1_CPU0_P0P0_DP<1>")
	)
	(segment
		(start 292.102286 -103.6701)
		(end 302.412654 -105.733088)
		(width 0.1143)
		(layer "B.Cu")
		(net "UPI_CPU1_CPU0_P0P0_DP<1>")
	)
	(segment
		(start 304.127916 -105.276142)
		(end 305.680364 -104.32034)
		(width 0.1143)
		(layer "B.Cu")
		(net "UPI_CPU1_CPU0_P0P0_DP<1>")
	)
	(segment
		(start 243.41328 -102.846124)
		(end 252.431296 -102.510844)
		(width 0.1143)
		(layer "B.Cu")
		(net "UPI_CPU1_CPU0_P0P0_DP<1>")
	)
	(segment
		(start 309.85714 -93.333062)
		(end 309.820818 -91.932506)
		(width 0.1143)
		(layer "B.Cu")
		(net "UPI_CPU1_CPU0_P0P0_DP<1>")
	)
	(segment
		(start 309.802022 -91.20124)
		(end 309.674006 -91.080082)
		(width 0.1143)
		(layer "B.Cu")
		(net "UPI_CPU1_CPU0_P0P0_DP<1>")
	)
	(segment
		(start 197.024498 -111.467138)
		(end 197.634606 -111.493808)
		(width 0.1143)
		(layer "B.Cu")
		(net "UPI_CPU1_CPU0_P0P0_DP<1>")
	)
	(segment
		(start 148.653246 -57.603898)
		(end 148.227288 -57.17794)
		(width 0.0889)
		(layer "B.Cu")
		(net "UPI_CPU1_CPU0_P0P0_DP<1>")
	)
	(segment
		(start 160.762188 -87.129366)
		(end 168.428162 -95.89008)
		(width 0.1143)
		(layer "B.Cu")
		(net "UPI_CPU1_CPU0_P0P0_DP<1>")
	)
	(segment
		(start 308.605174 -82.997802)
		(end 308.545738 -82.777584)
		(width 0.1143)
		(layer "B.Cu")
		(net "UPI_CPU1_CPU0_P0P0_DP<1>")
	)
	(segment
		(start 309.113174 -94.369128)
		(end 309.85714 -93.333062)
		(width 0.1143)
		(layer "B.Cu")
		(net "UPI_CPU1_CPU0_P0P0_DP<1>")
	)
	(segment
		(start 181.189122 -103.748332)
		(end 182.255922 -104.182926)
		(width 0.1143)
		(layer "B.Cu")
		(net "UPI_CPU1_CPU0_P0P0_DP<1>")
	)
	(segment
		(start 304.409856 -77.297534)
		(end 304.366676 -77.297534)
		(width 0.0889)
		(layer "B.Cu")
		(net "UPI_CPU1_CPU0_P0P0_DP<1>")
	)
	(segment
		(start 197.634606 -111.493808)
		(end 200.903586 -111.055658)
		(width 0.1143)
		(layer "B.Cu")
		(net "UPI_CPU1_CPU0_P0P0_DP<1>")
	)
	(segment
		(start 172.563028 -101.026468)
		(end 179.499768 -102.73284)
		(width 0.1143)
		(layer "B.Cu")
		(net "UPI_CPU1_CPU0_P0P0_DP<1>")
	)
	(segment
		(start 282.25242 -105.921048)
		(end 282.598622 -106.162602)
		(width 0.1143)
		(layer "B.Cu")
		(net "UPI_CPU1_CPU0_P0P0_DP<1>")
	)
	(segment
		(start 252.431296 -102.510844)
		(end 257.597148 -104.049068)
		(width 0.1143)
		(layer "B.Cu")
		(net "UPI_CPU1_CPU0_P0P0_DP<1>")
	)
	(segment
		(start 143.90497 -58.22569)
		(end 143.087344 -58.22569)
		(width 0.0889)
		(layer "B.Cu")
		(net "UPI_CPU1_CPU0_P0P0_DP<1>")
	)
	(segment
		(start 283.565092 -106.290872)
		(end 283.512006 -106.000042)
		(width 0.1143)
		(layer "B.Cu")
		(net "UPI_CPU1_CPU0_P0P0_DP<1>")
	)
	(segment
		(start 304.494946 -77.294486)
		(end 304.409856 -77.297534)
		(width 0.0889)
		(layer "B.Cu")
		(net "UPI_CPU1_CPU0_P0P0_DP<1>")
	)
	(segment
		(start 152.196546 -61.110876)
		(end 156.399992 -65.314322)
		(width 0.1143)
		(layer "B.Cu")
		(net "UPI_CPU1_CPU0_P0P0_DP<1>")
	)
	(segment
		(start 307.6956 -79.744062)
		(end 307.37175 -79.289402)
		(width 0.1143)
		(layer "B.Cu")
		(net "UPI_CPU1_CPU0_P0P0_DP<1>")
	)
	(segment
		(start 307.37175 -79.289402)
		(end 306.902104 -78.819756)
		(width 0.1143)
		(layer "B.Cu")
		(net "UPI_CPU1_CPU0_P0P0_DP<1>")
	)
	(segment
		(start 308.883812 -84.506308)
		(end 308.970934 -84.356194)
		(width 0.1143)
		(layer "B.Cu")
		(net "UPI_CPU1_CPU0_P0P0_DP<1>")
	)
	(segment
		(start 308.911498 -84.135976)
		(end 308.911244 -84.13496)
		(width 0.1143)
		(layer "B.Cu")
		(net "UPI_CPU1_CPU0_P0P0_DP<1>")
	)
	(segment
		(start 308.395116 -82.690208)
		(end 308.335172 -82.46872)
		(width 0.1143)
		(layer "B.Cu")
		(net "UPI_CPU1_CPU0_P0P0_DP<1>")
	)
	(segment
		(start 300.436026 -73.450704)
		(end 300.442376 -73.440036)
		(width 0.0889)
		(layer "B.Cu")
		(net "UPI_CPU1_CPU0_P0P0_DP<1>")
	)
	(segment
		(start 186.450986 -105.388918)
		(end 191.906398 -106.360468)
		(width 0.1143)
		(layer "B.Cu")
		(net "UPI_CPU1_CPU0_P0P0_DP<1>")
	)
	(segment
		(start 309.694072 -87.047832)
		(end 309.09387 -84.814156)
		(width 0.1143)
		(layer "B.Cu")
		(net "UPI_CPU1_CPU0_P0P0_DP<1>")
	)
	(segment
		(start 243.3828 -102.857808)
		(end 243.41328 -102.846124)
		(width 0.1143)
		(layer "B.Cu")
		(net "UPI_CPU1_CPU0_P0P0_DP<1>")
	)
	(segment
		(start 280.149554 -106.236008)
		(end 280.668984 -106.578146)
		(width 0.1143)
		(layer "B.Cu")
		(net "UPI_CPU1_CPU0_P0P0_DP<1>")
	)
	(segment
		(start 284.639766 -105.538524)
		(end 284.64002 -105.53827)
		(width 0.1143)
		(layer "B.Cu")
		(net "UPI_CPU1_CPU0_P0P0_DP<1>")
	)
	(segment
		(start 285.169864 -105.056178)
		(end 291.125402 -103.865426)
		(width 0.1143)
		(layer "B.Cu")
		(net "UPI_CPU1_CPU0_P0P0_DP<1>")
	)
	(segment
		(start 309.09387 -84.814156)
		(end 308.943756 -84.727542)
		(width 0.1143)
		(layer "B.Cu")
		(net "UPI_CPU1_CPU0_P0P0_DP<1>")
	)
	(segment
		(start 280.668984 -106.578146)
		(end 281.031696 -106.503216)
		(width 0.1143)
		(layer "B.Cu")
		(net "UPI_CPU1_CPU0_P0P0_DP<1>")
	)
	(segment
		(start 301.827692 -75.811888)
		(end 301.794926 -75.811888)
		(width 0.0889)
		(layer "B.Cu")
		(net "UPI_CPU1_CPU0_P0P0_DP<1>")
	)
	(segment
		(start 284.64002 -105.53827)
		(end 285.169864 -105.056178)
		(width 0.1143)
		(layer "B.Cu")
		(net "UPI_CPU1_CPU0_P0P0_DP<1>")
	)
	(segment
		(start 168.428162 -95.89008)
		(end 170.832018 -99.537266)
		(width 0.1143)
		(layer "B.Cu")
		(net "UPI_CPU1_CPU0_P0P0_DP<1>")
	)
	(segment
		(start 300.965362 -75.316334)
		(end 300.932596 -75.316334)
		(width 0.0889)
		(layer "B.Cu")
		(net "UPI_CPU1_CPU0_P0P0_DP<1>")
	)
	(segment
		(start 308.788054 -83.676998)
		(end 308.728364 -83.455764)
		(width 0.1143)
		(layer "B.Cu")
		(net "UPI_CPU1_CPU0_P0P0_DP<1>")
	)
	(segment
		(start 308.577996 -83.369404)
		(end 308.518052 -83.147916)
		(width 0.1143)
		(layer "B.Cu")
		(net "UPI_CPU1_CPU0_P0P0_DP<1>")
	)
	(segment
		(start 281.454606 -106.063796)
		(end 282.25242 -105.921048)
		(width 0.1143)
		(layer "B.Cu")
		(net "UPI_CPU1_CPU0_P0P0_DP<1>")
	)
	(segment
		(start 170.832018 -99.537266)
		(end 172.14977 -100.799138)
		(width 0.1143)
		(layer "B.Cu")
		(net "UPI_CPU1_CPU0_P0P0_DP<1>")
	)
	(segment
		(start 182.996078 -104.661462)
		(end 185.027316 -105.338372)
		(width 0.1143)
		(layer "B.Cu")
		(net "UPI_CPU1_CPU0_P0P0_DP<1>")
	)
	(segment
		(start 191.906398 -106.360468)
		(end 192.820798 -106.646726)
		(width 0.1143)
		(layer "B.Cu")
		(net "UPI_CPU1_CPU0_P0P0_DP<1>")
	)
	(segment
		(start 303.544732 -76.802488)
		(end 303.511966 -76.802488)
		(width 0.0889)
		(layer "B.Cu")
		(net "UPI_CPU1_CPU0_P0P0_DP<1>")
	)
	(segment
		(start 300.436026 -74.441304)
		(end 300.442376 -74.430636)
		(width 0.0889)
		(layer "B.Cu")
		(net "UPI_CPU1_CPU0_P0P0_DP<1>")
	)
	(segment
		(start 283.512006 -106.000042)
		(end 283.719016 -105.702862)
		(width 0.1143)
		(layer "B.Cu")
		(net "UPI_CPU1_CPU0_P0P0_DP<1>")
	)
	(segment
		(start 309.820818 -91.932506)
		(end 309.693056 -91.811348)
		(width 0.1143)
		(layer "B.Cu")
		(net "UPI_CPU1_CPU0_P0P0_DP<1>")
	)
	(segment
		(start 307.754528 -79.826866)
		(end 307.6956 -79.744062)
		(width 0.1143)
		(layer "B.Cu")
		(net "UPI_CPU1_CPU0_P0P0_DP<1>")
	)
	(segment
		(start 308.433216 -100.769928)
		(end 309.113174 -94.369128)
		(width 0.1143)
		(layer "B.Cu")
		(net "UPI_CPU1_CPU0_P0P0_DP<1>")
	)
	(segment
		(start 304.49901 -77.294232)
		(end 304.494946 -77.294486)
		(width 0.0889)
		(layer "B.Cu")
		(net "UPI_CPU1_CPU0_P0P0_DP<1>")
	)
	(segment
		(start 259.919724 -104.507538)
		(end 279.053544 -106.435906)
		(width 0.1143)
		(layer "B.Cu")
		(net "UPI_CPU1_CPU0_P0P0_DP<1>")
	)
	(segment
		(start 308.545484 -82.776568)
		(end 308.395116 -82.690208)
		(width 0.1143)
		(layer "B.Cu")
		(net "UPI_CPU1_CPU0_P0P0_DP<1>")
	)
	(segment
		(start 308.212236 -82.011012)
		(end 308.152292 -81.789524)
		(width 0.1143)
		(layer "B.Cu")
		(net "UPI_CPU1_CPU0_P0P0_DP<1>")
	)
	(segment
		(start 182.255922 -104.182926)
		(end 182.296816 -104.204516)
		(width 0.1143)
		(layer "B.Cu")
		(net "UPI_CPU1_CPU0_P0P0_DP<1>")
	)
	(segment
		(start 280.047954 -106.257344)
		(end 280.049478 -106.25709)
		(width 0.1143)
		(layer "B.Cu")
		(net "UPI_CPU1_CPU0_P0P0_DP<1>")
	)
	(segment
		(start 242.852956 -103.062786)
		(end 243.3828 -102.857808)
		(width 0.1143)
		(layer "B.Cu")
		(net "UPI_CPU1_CPU0_P0P0_DP<1>")
	)
	(segment
		(start 308.700932 -83.827112)
		(end 308.788054 -83.676998)
		(width 0.1143)
		(layer "B.Cu")
		(net "UPI_CPU1_CPU0_P0P0_DP<1>")
	)
	(segment
		(start 305.680364 -104.32034)
		(end 308.211982 -101.477572)
		(width 0.1143)
		(layer "B.Cu")
		(net "UPI_CPU1_CPU0_P0P0_DP<1>")
	)
	(segment
		(start 225.45167 -105.52176)
		(end 230.857044 -105.792778)
		(width 0.1143)
		(layer "B.Cu")
		(net "UPI_CPU1_CPU0_P0P0_DP<1>")
	)
	(segment
		(start 200.903586 -111.055658)
		(end 202.20051 -110.189518)
		(width 0.1143)
		(layer "B.Cu")
		(net "UPI_CPU1_CPU0_P0P0_DP<1>")
	)
	(segment
		(start 308.152292 -81.789524)
		(end 308.239414 -81.63941)
		(width 0.1143)
		(layer "B.Cu")
		(net "UPI_CPU1_CPU0_P0P0_DP<1>")
	)
	(segment
		(start 309.808372 -91.454986)
		(end 309.802022 -91.20124)
		(width 0.1143)
		(layer "B.Cu")
		(net "UPI_CPU1_CPU0_P0P0_DP<1>")
	)
	(segment
		(start 308.518052 -83.147916)
		(end 308.605174 -82.997802)
		(width 0.1143)
		(layer "B.Cu")
		(net "UPI_CPU1_CPU0_P0P0_DP<1>")
	)
	(segment
		(start 192.820798 -106.646726)
		(end 196.207634 -110.890558)
		(width 0.1143)
		(layer "B.Cu")
		(net "UPI_CPU1_CPU0_P0P0_DP<1>")
	)
	(segment
		(start 309.78856 -90.69832)
		(end 309.694072 -87.047832)
		(width 0.1143)
		(layer "B.Cu")
		(net "UPI_CPU1_CPU0_P0P0_DP<1>")
	)
	(segment
		(start 308.335172 -82.46872)
		(end 308.422294 -82.318606)
		(width 0.1143)
		(layer "B.Cu")
		(net "UPI_CPU1_CPU0_P0P0_DP<1>")
	)
	(segment
		(start 308.911244 -84.13496)
		(end 308.760876 -84.0486)
		(width 0.1143)
		(layer "B.Cu")
		(net "UPI_CPU1_CPU0_P0P0_DP<1>")
	)
	(segment
		(start 156.399992 -65.314322)
		(end 160.762188 -87.129366)
		(width 0.1143)
		(layer "B.Cu")
		(net "UPI_CPU1_CPU0_P0P0_DP<1>")
	)
	(segment
		(start 308.545738 -82.777584)
		(end 308.545484 -82.776568)
		(width 0.1143)
		(layer "B.Cu")
		(net "UPI_CPU1_CPU0_P0P0_DP<1>")
	)
	(segment
		(start 308.422294 -82.318606)
		(end 308.362858 -82.098388)
		(width 0.1143)
		(layer "B.Cu")
		(net "UPI_CPU1_CPU0_P0P0_DP<1>")
	)
	(segment
		(start 281.29738 -106.098848)
		(end 281.452828 -106.06659)
		(width 0.1143)
		(layer "B.Cu")
		(net "UPI_CPU1_CPU0_P0P0_DP<1>")
	)
	(segment
		(start 280.013664 -106.26471)
		(end 280.04389 -106.25836)
		(width 0.1143)
		(layer "B.Cu")
		(net "UPI_CPU1_CPU0_P0P0_DP<1>")
	)
	(segment
		(start 182.296816 -104.204516)
		(end 182.996078 -104.661462)
		(width 0.1143)
		(layer "B.Cu")
		(net "UPI_CPU1_CPU0_P0P0_DP<1>")
	)
	(segment
		(start 308.362604 -82.097372)
		(end 308.212236 -82.011012)
		(width 0.1143)
		(layer "B.Cu")
		(net "UPI_CPU1_CPU0_P0P0_DP<1>")
	)
	(segment
		(start 279.053544 -106.435906)
		(end 280.013664 -106.26471)
		(width 0.1143)
		(layer "B.Cu")
		(net "UPI_CPU1_CPU0_P0P0_DP<1>")
	)
	(segment
		(start 172.14977 -100.799138)
		(end 172.563028 -101.026468)
		(width 0.1143)
		(layer "B.Cu")
		(net "UPI_CPU1_CPU0_P0P0_DP<1>")
	)
	(segment
		(start 257.597148 -104.049068)
		(end 259.919724 -104.507538)
		(width 0.1143)
		(layer "B.Cu")
		(net "UPI_CPU1_CPU0_P0P0_DP<1>")
	)
	(segment
		(start 144.95272 -57.17794)
		(end 143.90497 -58.22569)
		(width 0.0889)
		(layer "B.Cu")
		(net "UPI_CPU1_CPU0_P0P0_DP<1>")
	)
	(segment
		(start 282.651708 -106.45521)
		(end 282.83027 -106.578654)
		(width 0.1143)
		(layer "B.Cu")
		(net "UPI_CPU1_CPU0_P0P0_DP<1>")
	)
	(segment
		(start 142.908528 -58.046874)
		(end 142.90802 -57.885584)
		(width 0.0889)
		(layer "B.Cu")
		(net "UPI_CPU1_CPU0_P0P0_DP<1>")
	)
	(segment
		(start 282.598622 -106.162602)
		(end 282.651708 -106.45521)
		(width 0.1143)
		(layer "B.Cu")
		(net "UPI_CPU1_CPU0_P0P0_DP<1>")
	)
	(segment
		(start 306.902104 -78.783688)
		(end 306.394612 -78.276196)
		(width 0.0889)
		(layer "B.Cu")
		(net "UPI_CPU1_CPU0_P0P0_DP<1>")
	)
	(segment
		(start 309.687214 -91.582494)
		(end 309.808372 -91.454986)
		(width 0.1143)
		(layer "B.Cu")
		(net "UPI_CPU1_CPU0_P0P0_DP<1>")
	)
	(segment
		(start 179.499768 -102.73284)
		(end 181.189122 -103.748332)
		(width 0.1143)
		(layer "B.Cu")
		(net "UPI_CPU1_CPU0_P0P0_DP<1>")
	)
	(segment
		(start 308.728364 -83.455764)
		(end 308.577996 -83.369404)
		(width 0.1143)
		(layer "B.Cu")
		(net "UPI_CPU1_CPU0_P0P0_DP<1>")
	)
	(segment
		(start 305.47564 -78.08722)
		(end 304.49901 -77.294232)
		(width 0.0889)
		(layer "B.Cu")
		(net "UPI_CPU1_CPU0_P0P0_DP<1>")
	)
	(segment
		(start 309.674006 -91.080082)
		(end 309.667402 -90.825828)
		(width 0.1143)
		(layer "B.Cu")
		(net "UPI_CPU1_CPU0_P0P0_DP<1>")
	)
	(segment
		(start 202.20051 -110.189518)
		(end 225.45167 -105.52176)
		(width 0.1143)
		(layer "B.Cu")
		(net "UPI_CPU1_CPU0_P0P0_DP<1>")
	)
	(segment
		(start 152.196546 -61.110876)
		(end 148.689568 -57.603898)
		(width 0.1143)
		(layer "B.Cu")
		(net "UPI_CPU1_CPU0_P0P0_DP<1>")
	)
	(segment
		(start 196.550788 -111.252)
		(end 197.024498 -111.467138)
		(width 0.1143)
		(layer "B.Cu")
		(net "UPI_CPU1_CPU0_P0P0_DP<1>")
	)
	(segment
		(start 196.207634 -110.890558)
		(end 196.550788 -111.252)
		(width 0.1143)
		(layer "B.Cu")
		(net "UPI_CPU1_CPU0_P0P0_DP<1>")
	)
	(segment
		(start 308.970934 -84.356194)
		(end 308.911498 -84.135976)
		(width 0.1143)
		(layer "B.Cu")
		(net "UPI_CPU1_CPU0_P0P0_DP<1>")
	)
	(segment
		(start 308.943756 -84.727542)
		(end 308.883812 -84.506308)
		(width 0.1143)
		(layer "B.Cu")
		(net "UPI_CPU1_CPU0_P0P0_DP<1>")
	)
	(segment
		(start 306.902104 -78.819756)
		(end 306.902104 -78.783688)
		(width 0.0889)
		(layer "B.Cu")
		(net "UPI_CPU1_CPU0_P0P0_DP<1>")
	)
	(segment
		(start 143.087344 -58.22569)
		(end 142.908528 -58.046874)
		(width 0.0889)
		(layer "B.Cu")
		(net "UPI_CPU1_CPU0_P0P0_DP<1>")
	)
	(segment
		(start 305.97094 -78.300834)
		(end 305.47564 -78.08722)
		(width 0.0889)
		(layer "B.Cu")
		(net "UPI_CPU1_CPU0_P0P0_DP<1>")
	)
	(segment
		(start 280.049478 -106.25709)
		(end 280.149554 -106.236008)
		(width 0.1143)
		(layer "B.Cu")
		(net "UPI_CPU1_CPU0_P0P0_DP<1>")
	)
	(segment
		(start 148.227288 -57.17794)
		(end 144.95272 -57.17794)
		(width 0.0889)
		(layer "B.Cu")
		(net "UPI_CPU1_CPU0_P0P0_DP<1>")
	)
	(segment
		(start 230.857044 -105.792778)
		(end 241.028982 -103.76789)
		(width 0.1143)
		(layer "B.Cu")
		(net "UPI_CPU1_CPU0_P0P0_DP<1>")
	)
	(segment
		(start 282.83027 -106.578654)
		(end 283.442156 -106.46918)
		(width 0.1143)
		(layer "B.Cu")
		(net "UPI_CPU1_CPU0_P0P0_DP<1>")
	)
	(segment
		(start 283.442156 -106.46918)
		(end 283.565092 -106.290872)
		(width 0.1143)
		(layer "B.Cu")
		(net "UPI_CPU1_CPU0_P0P0_DP<1>")
	)
	(segment
		(start 291.125402 -103.865426)
		(end 292.102286 -103.6701)
		(width 0.1143)
		(layer "B.Cu")
		(net "UPI_CPU1_CPU0_P0P0_DP<1>")
	)
	(arc
		(start 300.442376 -74.030586)
		(mid 300.363154 -73.741468)
		(end 300.436026 -73.450704)
		(width 0.0889)
		(layer "B.Cu")
		(net "UPI_CPU1_CPU0_P0P0_DP<1>")
	)
	(arc
		(start 302.159416 -76.011786)
		(mid 302.019337 -75.86905)
		(end 301.827692 -75.811888)
		(width 0.0889)
		(layer "B.Cu")
		(net "UPI_CPU1_CPU0_P0P0_DP<1>")
	)
	(arc
		(start 303.017936 -76.507086)
		(mid 302.876253 -76.363282)
		(end 302.682402 -76.306934)
		(width 0.0889)
		(layer "B.Cu")
		(net "UPI_CPU1_CPU0_P0P0_DP<1>")
	)
	(arc
		(start 300.447202 -74.422)
		(mid 300.495957 -74.225648)
		(end 300.442376 -74.030586)
		(width 0.0889)
		(layer "B.Cu")
		(net "UPI_CPU1_CPU0_P0P0_DP<1>")
	)
	(arc
		(start 303.511966 -76.802488)
		(mid 303.226542 -76.719021)
		(end 303.017936 -76.507086)
		(width 0.0889)
		(layer "B.Cu")
		(net "UPI_CPU1_CPU0_P0P0_DP<1>")
	)
	(arc
		(start 301.794926 -75.811888)
		(mid 301.509502 -75.728421)
		(end 301.300896 -75.516486)
		(width 0.0889)
		(layer "B.Cu")
		(net "UPI_CPU1_CPU0_P0P0_DP<1>")
	)
	(arc
		(start 300.442376 -73.039986)
		(mid 300.247338 -72.654273)
		(end 300.095666 -72.249538)
		(width 0.0889)
		(layer "B.Cu")
		(net "UPI_CPU1_CPU0_P0P0_DP<1>")
	)
	(arc
		(start 301.300896 -75.516486)
		(mid 301.159213 -75.372682)
		(end 300.965362 -75.316334)
		(width 0.0889)
		(layer "B.Cu")
		(net "UPI_CPU1_CPU0_P0P0_DP<1>")
	)
	(arc
		(start 300.447202 -73.4314)
		(mid 300.495957 -73.235048)
		(end 300.442376 -73.039986)
		(width 0.0889)
		(layer "B.Cu")
		(net "UPI_CPU1_CPU0_P0P0_DP<1>")
	)
	(arc
		(start 303.876456 -77.002386)
		(mid 303.736377 -76.85965)
		(end 303.544732 -76.802488)
		(width 0.0889)
		(layer "B.Cu")
		(net "UPI_CPU1_CPU0_P0P0_DP<1>")
	)
	(arc
		(start 302.649636 -76.306934)
		(mid 302.366419 -76.222653)
		(end 302.159416 -76.011786)
		(width 0.0889)
		(layer "B.Cu")
		(net "UPI_CPU1_CPU0_P0P0_DP<1>")
	)
	(arc
		(start 304.366676 -77.297534)
		(mid 304.083459 -77.213253)
		(end 303.876456 -77.002386)
		(width 0.0889)
		(layer "B.Cu")
		(net "UPI_CPU1_CPU0_P0P0_DP<1>")
	)
	(arc
		(start 300.932596 -75.316334)
		(mid 300.440206 -75.017401)
		(end 300.436026 -74.441304)
		(width 0.0889)
		(layer "B.Cu")
		(net "UPI_CPU1_CPU0_P0P0_DP<1>")
	)
	(segment
		(start 300.382686 -61.847984)
		(end 300.954186 -61.847984)
		(width 0.1143)
		(layer "F.Cu")
		(net "UPI_CPU1_CPU0_P0P0_DP<19>")
	)
	(segment
		(start 139.674854 -74.230738)
		(end 140.246354 -74.23023)
		(width 0.1143)
		(layer "F.Cu")
		(net "UPI_CPU1_CPU0_P0P0_DP<19>")
	)
	(via
		(at 300.954186 -61.847984)
		(size 0.508)
		(drill 0.254)
		(layers "F.Cu" "B.Cu")
		(net "UPI_CPU1_CPU0_P0P0_DP<19>")
	)
	(via
		(at 140.246354 -74.23023)
		(size 0.508)
		(drill 0.254)
		(layers "F.Cu" "B.Cu")
		(net "UPI_CPU1_CPU0_P0P0_DP<19>")
	)
	(segment
		(start 310.108854 -58.61812)
		(end 309.931054 -58.61812)
		(width 0.0889)
		(layer "B.Cu")
		(net "UPI_CPU1_CPU0_P0P0_DP<19>")
	)
	(segment
		(start 309.372254 -58.61812)
		(end 309.270654 -58.51652)
		(width 0.0889)
		(layer "B.Cu")
		(net "UPI_CPU1_CPU0_P0P0_DP<19>")
	)
	(segment
		(start 300.58233 -61.995812)
		(end 300.66107 -62.017148)
		(width 0.0889)
		(layer "B.Cu")
		(net "UPI_CPU1_CPU0_P0P0_DP<19>")
	)
	(segment
		(start 308.533038 -59.194954)
		(end 308.381908 -59.346084)
		(width 0.0889)
		(layer "B.Cu")
		(net "UPI_CPU1_CPU0_P0P0_DP<19>")
	)
	(segment
		(start 306.123086 -59.466988)
		(end 306.087526 -59.466988)
		(width 0.0889)
		(layer "B.Cu")
		(net "UPI_CPU1_CPU0_P0P0_DP<19>")
	)
	(segment
		(start 305.26482 -58.971688)
		(end 305.228752 -58.971688)
		(width 0.0889)
		(layer "B.Cu")
		(net "UPI_CPU1_CPU0_P0P0_DP<19>")
	)
	(segment
		(start 249.564144 -124.17171)
		(end 263.228582 -122.570494)
		(width 0.1143)
		(layer "B.Cu")
		(net "UPI_CPU1_CPU0_P0P0_DP<19>")
	)
	(segment
		(start 144.25422 -78.96987)
		(end 145.06956 -83.048856)
		(width 0.1143)
		(layer "B.Cu")
		(net "UPI_CPU1_CPU0_P0P0_DP<19>")
	)
	(segment
		(start 153.413714 -112.618774)
		(end 156.659834 -114.923824)
		(width 0.1143)
		(layer "B.Cu")
		(net "UPI_CPU1_CPU0_P0P0_DP<19>")
	)
	(segment
		(start 308.658514 -58.95086)
		(end 308.533038 -59.076336)
		(width 0.0889)
		(layer "B.Cu")
		(net "UPI_CPU1_CPU0_P0P0_DP<19>")
	)
	(segment
		(start 303.5427 -59.962288)
		(end 303.51476 -59.962288)
		(width 0.0889)
		(layer "B.Cu")
		(net "UPI_CPU1_CPU0_P0P0_DP<19>")
	)
	(segment
		(start 330.162154 -85.979762)
		(end 329.65644 -77.437234)
		(width 0.1143)
		(layer "B.Cu")
		(net "UPI_CPU1_CPU0_P0P0_DP<19>")
	)
	(segment
		(start 225.59899 -123.29414)
		(end 228.508306 -123.115324)
		(width 0.1143)
		(layer "B.Cu")
		(net "UPI_CPU1_CPU0_P0P0_DP<19>")
	)
	(segment
		(start 228.508306 -123.115324)
		(end 249.564144 -124.17171)
		(width 0.1143)
		(layer "B.Cu")
		(net "UPI_CPU1_CPU0_P0P0_DP<19>")
	)
	(segment
		(start 309.651654 -58.51652)
		(end 309.550054 -58.61812)
		(width 0.0889)
		(layer "B.Cu")
		(net "UPI_CPU1_CPU0_P0P0_DP<19>")
	)
	(segment
		(start 308.26329 -59.346084)
		(end 308.137814 -59.47156)
		(width 0.0889)
		(layer "B.Cu")
		(net "UPI_CPU1_CPU0_P0P0_DP<19>")
	)
	(segment
		(start 173.580044 -122.578876)
		(end 180.86578 -124.314712)
		(width 0.1143)
		(layer "B.Cu")
		(net "UPI_CPU1_CPU0_P0P0_DP<19>")
	)
	(segment
		(start 145.66138 -103.688642)
		(end 152.144984 -111.554006)
		(width 0.1143)
		(layer "B.Cu")
		(net "UPI_CPU1_CPU0_P0P0_DP<19>")
	)
	(segment
		(start 160.716976 -117.337586)
		(end 163.315142 -118.360952)
		(width 0.1143)
		(layer "B.Cu")
		(net "UPI_CPU1_CPU0_P0P0_DP<19>")
	)
	(segment
		(start 141.699996 -74.059796)
		(end 142.302484 -74.662538)
		(width 0.1143)
		(layer "B.Cu")
		(net "UPI_CPU1_CPU0_P0P0_DP<19>")
	)
	(segment
		(start 309.829454 -58.51652)
		(end 309.651654 -58.51652)
		(width 0.0889)
		(layer "B.Cu")
		(net "UPI_CPU1_CPU0_P0P0_DP<19>")
	)
	(segment
		(start 312.636916 -58.54192)
		(end 310.6928 -58.54192)
		(width 0.1143)
		(layer "B.Cu")
		(net "UPI_CPU1_CPU0_P0P0_DP<19>")
	)
	(segment
		(start 143.641572 -97.456752)
		(end 144.450816 -101.504242)
		(width 0.1143)
		(layer "B.Cu")
		(net "UPI_CPU1_CPU0_P0P0_DP<19>")
	)
	(segment
		(start 309.550054 -58.61812)
		(end 309.372254 -58.61812)
		(width 0.0889)
		(layer "B.Cu")
		(net "UPI_CPU1_CPU0_P0P0_DP<19>")
	)
	(segment
		(start 308.533038 -59.076336)
		(end 308.533038 -59.194954)
		(width 0.0889)
		(layer "B.Cu")
		(net "UPI_CPU1_CPU0_P0P0_DP<19>")
	)
	(segment
		(start 307.130958 -58.971434)
		(end 307.130958 -58.971688)
		(width 0.0889)
		(layer "B.Cu")
		(net "UPI_CPU1_CPU0_P0P0_DP<19>")
	)
	(segment
		(start 201.772012 -126.308612)
		(end 208.425034 -126.742698)
		(width 0.1143)
		(layer "B.Cu")
		(net "UPI_CPU1_CPU0_P0P0_DP<19>")
	)
	(segment
		(start 308.928262 -58.681112)
		(end 308.928262 -58.79973)
		(width 0.0889)
		(layer "B.Cu")
		(net "UPI_CPU1_CPU0_P0P0_DP<19>")
	)
	(segment
		(start 333.272638 -94.719394)
		(end 332.163166 -91.945968)
		(width 0.1143)
		(layer "B.Cu")
		(net "UPI_CPU1_CPU0_P0P0_DP<19>")
	)
	(segment
		(start 307.13172 -58.971434)
		(end 307.130958 -58.971434)
		(width 0.0889)
		(layer "B.Cu")
		(net "UPI_CPU1_CPU0_P0P0_DP<19>")
	)
	(segment
		(start 263.228582 -122.570494)
		(end 284.614112 -124.744226)
		(width 0.1143)
		(layer "B.Cu")
		(net "UPI_CPU1_CPU0_P0P0_DP<19>")
	)
	(segment
		(start 145.06956 -83.048856)
		(end 145.020284 -86.26856)
		(width 0.1143)
		(layer "B.Cu")
		(net "UPI_CPU1_CPU0_P0P0_DP<19>")
	)
	(segment
		(start 309.931054 -58.61812)
		(end 309.829454 -58.51652)
		(width 0.0889)
		(layer "B.Cu")
		(net "UPI_CPU1_CPU0_P0P0_DP<19>")
	)
	(segment
		(start 163.315142 -118.360952)
		(end 165.844474 -119.164608)
		(width 0.1143)
		(layer "B.Cu")
		(net "UPI_CPU1_CPU0_P0P0_DP<19>")
	)
	(segment
		(start 307.130958 -58.971688)
		(end 306.945792 -58.971688)
		(width 0.0889)
		(layer "B.Cu")
		(net "UPI_CPU1_CPU0_P0P0_DP<19>")
	)
	(segment
		(start 284.614112 -124.744226)
		(end 284.614112 -124.74448)
		(width 0.1143)
		(layer "B.Cu")
		(net "UPI_CPU1_CPU0_P0P0_DP<19>")
	)
	(segment
		(start 165.844474 -119.164608)
		(end 167.225472 -119.7737)
		(width 0.1143)
		(layer "B.Cu")
		(net "UPI_CPU1_CPU0_P0P0_DP<19>")
	)
	(segment
		(start 145.020284 -86.26856)
		(end 144.034002 -95.497396)
		(width 0.1143)
		(layer "B.Cu")
		(net "UPI_CPU1_CPU0_P0P0_DP<19>")
	)
	(segment
		(start 284.614112 -124.74448)
		(end 290.961064 -123.47448)
		(width 0.1143)
		(layer "B.Cu")
		(net "UPI_CPU1_CPU0_P0P0_DP<19>")
	)
	(segment
		(start 301.830486 -60.952888)
		(end 301.79772 -60.952888)
		(width 0.0889)
		(layer "B.Cu")
		(net "UPI_CPU1_CPU0_P0P0_DP<19>")
	)
	(segment
		(start 140.870432 -74.3712)
		(end 141.181836 -74.059796)
		(width 0.1143)
		(layer "B.Cu")
		(net "UPI_CPU1_CPU0_P0P0_DP<19>")
	)
	(segment
		(start 302.692816 -60.457334)
		(end 302.66005 -60.457334)
		(width 0.0889)
		(layer "B.Cu")
		(net "UPI_CPU1_CPU0_P0P0_DP<19>")
	)
	(segment
		(start 309.270654 -58.51652)
		(end 309.092854 -58.51652)
		(width 0.0889)
		(layer "B.Cu")
		(net "UPI_CPU1_CPU0_P0P0_DP<19>")
	)
	(segment
		(start 308.777132 -58.95086)
		(end 308.658514 -58.95086)
		(width 0.0889)
		(layer "B.Cu")
		(net "UPI_CPU1_CPU0_P0P0_DP<19>")
	)
	(segment
		(start 300.975776 -61.447934)
		(end 300.94301 -61.447934)
		(width 0.0889)
		(layer "B.Cu")
		(net "UPI_CPU1_CPU0_P0P0_DP<19>")
	)
	(segment
		(start 315.550296 -59.747912)
		(end 312.666634 -58.554366)
		(width 0.1143)
		(layer "B.Cu")
		(net "UPI_CPU1_CPU0_P0P0_DP<19>")
	)
	(segment
		(start 307.63845 -59.47156)
		(end 307.360574 -59.193684)
		(width 0.0889)
		(layer "B.Cu")
		(net "UPI_CPU1_CPU0_P0P0_DP<19>")
	)
	(segment
		(start 304.406046 -59.466988)
		(end 304.370232 -59.466988)
		(width 0.0889)
		(layer "B.Cu")
		(net "UPI_CPU1_CPU0_P0P0_DP<19>")
	)
	(segment
		(start 308.928262 -58.79973)
		(end 308.777132 -58.95086)
		(width 0.0889)
		(layer "B.Cu")
		(net "UPI_CPU1_CPU0_P0P0_DP<19>")
	)
	(segment
		(start 319.766188 -116.959634)
		(end 332.95971 -104.527096)
		(width 0.1143)
		(layer "B.Cu")
		(net "UPI_CPU1_CPU0_P0P0_DP<19>")
	)
	(segment
		(start 322.254626 -64.155828)
		(end 315.550296 -59.747912)
		(width 0.1143)
		(layer "B.Cu")
		(net "UPI_CPU1_CPU0_P0P0_DP<19>")
	)
	(segment
		(start 156.659834 -114.923824)
		(end 160.716976 -117.337586)
		(width 0.1143)
		(layer "B.Cu")
		(net "UPI_CPU1_CPU0_P0P0_DP<19>")
	)
	(segment
		(start 142.302484 -74.662538)
		(end 144.25422 -78.96987)
		(width 0.1143)
		(layer "B.Cu")
		(net "UPI_CPU1_CPU0_P0P0_DP<19>")
	)
	(segment
		(start 300.66107 -62.017148)
		(end 300.954186 -61.847984)
		(width 0.0889)
		(layer "B.Cu")
		(net "UPI_CPU1_CPU0_P0P0_DP<19>")
	)
	(segment
		(start 308.137814 -59.47156)
		(end 307.63845 -59.47156)
		(width 0.0889)
		(layer "B.Cu")
		(net "UPI_CPU1_CPU0_P0P0_DP<19>")
	)
	(segment
		(start 141.181836 -74.059796)
		(end 141.699996 -74.059796)
		(width 0.1143)
		(layer "B.Cu")
		(net "UPI_CPU1_CPU0_P0P0_DP<19>")
	)
	(segment
		(start 329.65644 -77.437234)
		(end 322.254626 -64.155828)
		(width 0.1143)
		(layer "B.Cu")
		(net "UPI_CPU1_CPU0_P0P0_DP<19>")
	)
	(segment
		(start 332.95971 -104.527096)
		(end 333.272638 -94.719394)
		(width 0.1143)
		(layer "B.Cu")
		(net "UPI_CPU1_CPU0_P0P0_DP<19>")
	)
	(segment
		(start 332.163166 -91.945968)
		(end 330.162154 -85.979762)
		(width 0.1143)
		(layer "B.Cu")
		(net "UPI_CPU1_CPU0_P0P0_DP<19>")
	)
	(segment
		(start 310.645302 -58.51652)
		(end 310.210454 -58.51652)
		(width 0.0889)
		(layer "B.Cu")
		(net "UPI_CPU1_CPU0_P0P0_DP<19>")
	)
	(segment
		(start 310.210454 -58.51652)
		(end 310.108854 -58.61812)
		(width 0.0889)
		(layer "B.Cu")
		(net "UPI_CPU1_CPU0_P0P0_DP<19>")
	)
	(segment
		(start 308.381908 -59.346084)
		(end 308.26329 -59.346084)
		(width 0.0889)
		(layer "B.Cu")
		(net "UPI_CPU1_CPU0_P0P0_DP<19>")
	)
	(segment
		(start 291.125402 -123.507246)
		(end 293.016686 -123.885706)
		(width 0.1143)
		(layer "B.Cu")
		(net "UPI_CPU1_CPU0_P0P0_DP<19>")
	)
	(segment
		(start 290.961064 -123.47448)
		(end 291.125402 -123.507246)
		(width 0.1143)
		(layer "B.Cu")
		(net "UPI_CPU1_CPU0_P0P0_DP<19>")
	)
	(segment
		(start 301.836582 -123.37161)
		(end 310.148224 -121.709434)
		(width 0.1143)
		(layer "B.Cu")
		(net "UPI_CPU1_CPU0_P0P0_DP<19>")
	)
	(segment
		(start 312.666634 -58.554366)
		(end 312.636916 -58.54192)
		(width 0.1143)
		(layer "B.Cu")
		(net "UPI_CPU1_CPU0_P0P0_DP<19>")
	)
	(segment
		(start 144.034002 -95.497396)
		(end 143.641572 -97.456752)
		(width 0.1143)
		(layer "B.Cu")
		(net "UPI_CPU1_CPU0_P0P0_DP<19>")
	)
	(segment
		(start 299.7708 -123.745498)
		(end 301.836582 -123.37161)
		(width 0.1143)
		(layer "B.Cu")
		(net "UPI_CPU1_CPU0_P0P0_DP<19>")
	)
	(segment
		(start 167.225472 -119.7737)
		(end 170.30573 -121.551954)
		(width 0.1143)
		(layer "B.Cu")
		(net "UPI_CPU1_CPU0_P0P0_DP<19>")
	)
	(segment
		(start 172.27804 -122.30608)
		(end 173.580044 -122.578876)
		(width 0.1143)
		(layer "B.Cu")
		(net "UPI_CPU1_CPU0_P0P0_DP<19>")
	)
	(segment
		(start 296.742612 -123.140216)
		(end 299.7708 -123.745498)
		(width 0.1143)
		(layer "B.Cu")
		(net "UPI_CPU1_CPU0_P0P0_DP<19>")
	)
	(segment
		(start 144.450816 -101.504242)
		(end 145.66138 -103.688642)
		(width 0.1143)
		(layer "B.Cu")
		(net "UPI_CPU1_CPU0_P0P0_DP<19>")
	)
	(segment
		(start 293.016686 -123.885706)
		(end 296.742612 -123.140216)
		(width 0.1143)
		(layer "B.Cu")
		(net "UPI_CPU1_CPU0_P0P0_DP<19>")
	)
	(segment
		(start 307.360574 -59.193684)
		(end 307.347112 -59.168284)
		(width 0.0889)
		(layer "B.Cu")
		(net "UPI_CPU1_CPU0_P0P0_DP<19>")
	)
	(segment
		(start 180.86578 -124.314712)
		(end 192.033144 -126.463552)
		(width 0.1143)
		(layer "B.Cu")
		(net "UPI_CPU1_CPU0_P0P0_DP<19>")
	)
	(segment
		(start 192.033144 -126.463552)
		(end 198.518018 -126.745492)
		(width 0.1143)
		(layer "B.Cu")
		(net "UPI_CPU1_CPU0_P0P0_DP<19>")
	)
	(segment
		(start 310.148224 -121.709434)
		(end 319.766188 -116.959634)
		(width 0.1143)
		(layer "B.Cu")
		(net "UPI_CPU1_CPU0_P0P0_DP<19>")
	)
	(segment
		(start 140.387324 -74.3712)
		(end 140.870432 -74.3712)
		(width 0.1143)
		(layer "B.Cu")
		(net "UPI_CPU1_CPU0_P0P0_DP<19>")
	)
	(segment
		(start 208.425034 -126.742698)
		(end 225.59899 -123.29414)
		(width 0.1143)
		(layer "B.Cu")
		(net "UPI_CPU1_CPU0_P0P0_DP<19>")
	)
	(segment
		(start 310.6928 -58.54192)
		(end 310.645302 -58.51652)
		(width 0.0889)
		(layer "B.Cu")
		(net "UPI_CPU1_CPU0_P0P0_DP<19>")
	)
	(segment
		(start 309.092854 -58.51652)
		(end 308.928262 -58.681112)
		(width 0.0889)
		(layer "B.Cu")
		(net "UPI_CPU1_CPU0_P0P0_DP<19>")
	)
	(segment
		(start 140.246354 -74.23023)
		(end 140.387324 -74.3712)
		(width 0.1143)
		(layer "B.Cu")
		(net "UPI_CPU1_CPU0_P0P0_DP<19>")
	)
	(segment
		(start 198.518018 -126.745492)
		(end 201.772012 -126.308612)
		(width 0.1143)
		(layer "B.Cu")
		(net "UPI_CPU1_CPU0_P0P0_DP<19>")
	)
	(segment
		(start 152.144984 -111.554006)
		(end 153.413714 -112.618774)
		(width 0.1143)
		(layer "B.Cu")
		(net "UPI_CPU1_CPU0_P0P0_DP<19>")
	)
	(segment
		(start 170.30573 -121.551954)
		(end 172.27804 -122.30608)
		(width 0.1143)
		(layer "B.Cu")
		(net "UPI_CPU1_CPU0_P0P0_DP<19>")
	)
	(arc
		(start 303.51476 -59.962288)
		(mid 303.323118 -60.019454)
		(end 303.183036 -60.162186)
		(width 0.0889)
		(layer "B.Cu")
		(net "UPI_CPU1_CPU0_P0P0_DP<19>")
	)
	(arc
		(start 304.041556 -59.666886)
		(mid 303.830843 -59.879965)
		(end 303.5427 -59.962288)
		(width 0.0889)
		(layer "B.Cu")
		(net "UPI_CPU1_CPU0_P0P0_DP<19>")
	)
	(arc
		(start 305.593496 -59.171586)
		(mid 305.454752 -59.029553)
		(end 305.26482 -58.971688)
		(width 0.0889)
		(layer "B.Cu")
		(net "UPI_CPU1_CPU0_P0P0_DP<19>")
	)
	(arc
		(start 304.900076 -59.171586)
		(mid 304.691468 -59.383518)
		(end 304.406046 -59.466988)
		(width 0.0889)
		(layer "B.Cu")
		(net "UPI_CPU1_CPU0_P0P0_DP<19>")
	)
	(arc
		(start 301.465996 -61.152786)
		(mid 301.258992 -61.36365)
		(end 300.975776 -61.447934)
		(width 0.0889)
		(layer "B.Cu")
		(net "UPI_CPU1_CPU0_P0P0_DP<19>")
	)
	(arc
		(start 302.324516 -60.657486)
		(mid 302.115908 -60.869418)
		(end 301.830486 -60.952888)
		(width 0.0889)
		(layer "B.Cu")
		(net "UPI_CPU1_CPU0_P0P0_DP<19>")
	)
	(arc
		(start 300.94301 -61.447934)
		(mid 300.648707 -61.589724)
		(end 300.557946 -61.90361)
		(width 0.0889)
		(layer "B.Cu")
		(net "UPI_CPU1_CPU0_P0P0_DP<19>")
	)
	(arc
		(start 302.66005 -60.457334)
		(mid 302.4662 -60.513684)
		(end 302.324516 -60.657486)
		(width 0.0889)
		(layer "B.Cu")
		(net "UPI_CPU1_CPU0_P0P0_DP<19>")
	)
	(arc
		(start 303.183036 -60.162186)
		(mid 302.976032 -60.37305)
		(end 302.692816 -60.457334)
		(width 0.0889)
		(layer "B.Cu")
		(net "UPI_CPU1_CPU0_P0P0_DP<19>")
	)
	(arc
		(start 301.79772 -60.952888)
		(mid 301.606078 -61.010054)
		(end 301.465996 -61.152786)
		(width 0.0889)
		(layer "B.Cu")
		(net "UPI_CPU1_CPU0_P0P0_DP<19>")
	)
	(arc
		(start 307.347112 -59.168284)
		(mid 307.256453 -59.051222)
		(end 307.13172 -58.971434)
		(width 0.0889)
		(layer "B.Cu")
		(net "UPI_CPU1_CPU0_P0P0_DP<19>")
	)
	(arc
		(start 306.617116 -59.171586)
		(mid 306.408508 -59.383518)
		(end 306.123086 -59.466988)
		(width 0.0889)
		(layer "B.Cu")
		(net "UPI_CPU1_CPU0_P0P0_DP<19>")
	)
	(arc
		(start 300.557946 -61.90361)
		(mid 300.567393 -61.950436)
		(end 300.58233 -61.995812)
		(width 0.0889)
		(layer "B.Cu")
		(net "UPI_CPU1_CPU0_P0P0_DP<19>")
	)
	(arc
		(start 306.087526 -59.466988)
		(mid 305.802102 -59.383521)
		(end 305.593496 -59.171586)
		(width 0.0889)
		(layer "B.Cu")
		(net "UPI_CPU1_CPU0_P0P0_DP<19>")
	)
	(arc
		(start 306.945792 -58.971688)
		(mid 306.755863 -59.029558)
		(end 306.617116 -59.171586)
		(width 0.0889)
		(layer "B.Cu")
		(net "UPI_CPU1_CPU0_P0P0_DP<19>")
	)
	(arc
		(start 304.370232 -59.466988)
		(mid 304.180303 -59.524858)
		(end 304.041556 -59.666886)
		(width 0.0889)
		(layer "B.Cu")
		(net "UPI_CPU1_CPU0_P0P0_DP<19>")
	)
	(arc
		(start 305.228752 -58.971688)
		(mid 305.038823 -59.029558)
		(end 304.900076 -59.171586)
		(width 0.0889)
		(layer "B.Cu")
		(net "UPI_CPU1_CPU0_P0P0_DP<19>")
	)
	(segment
		(start 141.603222 -73.256648)
		(end 141.952472 -73.256648)
		(width 0.1143)
		(layer "F.Cu")
		(net "UPI_CPU1_CPU0_P0P0_DP<18>")
	)
	(segment
		(start 141.465808 -73.119234)
		(end 141.603222 -73.256648)
		(width 0.1143)
		(layer "F.Cu")
		(net "UPI_CPU1_CPU0_P0P0_DP<18>")
	)
	(segment
		(start 141.952472 -73.256648)
		(end 142.464536 -72.744584)
		(width 0.1143)
		(layer "F.Cu")
		(net "UPI_CPU1_CPU0_P0P0_DP<18>")
	)
	(segment
		(start 301.241206 -62.343538)
		(end 301.812706 -62.343538)
		(width 0.1143)
		(layer "F.Cu")
		(net "UPI_CPU1_CPU0_P0P0_DP<18>")
	)
	(segment
		(start 140.533374 -72.744584)
		(end 140.908024 -73.119234)
		(width 0.1143)
		(layer "F.Cu")
		(net "UPI_CPU1_CPU0_P0P0_DP<18>")
	)
	(segment
		(start 140.908024 -73.119234)
		(end 141.465808 -73.119234)
		(width 0.1143)
		(layer "F.Cu")
		(net "UPI_CPU1_CPU0_P0P0_DP<18>")
	)
	(via
		(at 142.464536 -72.744584)
		(size 0.508)
		(drill 0.254)
		(layers "F.Cu" "B.Cu")
		(net "UPI_CPU1_CPU0_P0P0_DP<18>")
	)
	(via
		(at 301.812706 -62.343538)
		(size 0.508)
		(drill 0.254)
		(layers "F.Cu" "B.Cu")
		(net "UPI_CPU1_CPU0_P0P0_DP<18>")
	)
	(segment
		(start 309.902352 -120.724168)
		(end 319.336166 -115.993926)
		(width 0.1143)
		(layer "B.Cu")
		(net "UPI_CPU1_CPU0_P0P0_DP<18>")
	)
	(segment
		(start 304.409856 -60.457334)
		(end 304.37709 -60.457334)
		(width 0.0889)
		(layer "B.Cu")
		(net "UPI_CPU1_CPU0_P0P0_DP<18>")
	)
	(segment
		(start 145.25625 -100.93579)
		(end 146.484594 -103.151178)
		(width 0.1143)
		(layer "B.Cu")
		(net "UPI_CPU1_CPU0_P0P0_DP<18>")
	)
	(segment
		(start 299.27677 -122.863356)
		(end 309.902352 -120.724168)
		(width 0.1143)
		(layer "B.Cu")
		(net "UPI_CPU1_CPU0_P0P0_DP<18>")
	)
	(segment
		(start 170.705272 -120.665494)
		(end 173.385734 -121.47423)
		(width 0.1143)
		(layer "B.Cu")
		(net "UPI_CPU1_CPU0_P0P0_DP<18>")
	)
	(segment
		(start 331.724 -104.31907)
		(end 331.849476 -104.200706)
		(width 0.1143)
		(layer "B.Cu")
		(net "UPI_CPU1_CPU0_P0P0_DP<18>")
	)
	(segment
		(start 142.464536 -72.970136)
		(end 142.57655 -73.08215)
		(width 0.1143)
		(layer "B.Cu")
		(net "UPI_CPU1_CPU0_P0P0_DP<18>")
	)
	(segment
		(start 164.206936 -117.514116)
		(end 164.36721 -117.432582)
		(width 0.1143)
		(layer "B.Cu")
		(net "UPI_CPU1_CPU0_P0P0_DP<18>")
	)
	(segment
		(start 146.484594 -103.151178)
		(end 152.875742 -110.903766)
		(width 0.1143)
		(layer "B.Cu")
		(net "UPI_CPU1_CPU0_P0P0_DP<18>")
	)
	(segment
		(start 314.995814 -60.723526)
		(end 312.408824 -59.6519)
		(width 0.1143)
		(layer "B.Cu")
		(net "UPI_CPU1_CPU0_P0P0_DP<18>")
	)
	(segment
		(start 158.231078 -114.44478)
		(end 158.268416 -114.620548)
		(width 0.1143)
		(layer "B.Cu")
		(net "UPI_CPU1_CPU0_P0P0_DP<18>")
	)
	(segment
		(start 154.013408 -111.858044)
		(end 156.073602 -113.195608)
		(width 0.1143)
		(layer "B.Cu")
		(net "UPI_CPU1_CPU0_P0P0_DP<18>")
	)
	(segment
		(start 159.110172 -115.151916)
		(end 159.708088 -115.490244)
		(width 0.1143)
		(layer "B.Cu")
		(net "UPI_CPU1_CPU0_P0P0_DP<18>")
	)
	(segment
		(start 310.6928 -59.6519)
		(end 310.670702 -59.6519)
		(width 0.0889)
		(layer "B.Cu")
		(net "UPI_CPU1_CPU0_P0P0_DP<18>")
	)
	(segment
		(start 166.479982 -118.226332)
		(end 170.705272 -120.665494)
		(width 0.1143)
		(layer "B.Cu")
		(net "UPI_CPU1_CPU0_P0P0_DP<18>")
	)
	(segment
		(start 290.57092 -122.533156)
		(end 291.125402 -122.643138)
		(width 0.1143)
		(layer "B.Cu")
		(net "UPI_CPU1_CPU0_P0P0_DP<18>")
	)
	(segment
		(start 162.85464 -117.072664)
		(end 163.01466 -116.991384)
		(width 0.1143)
		(layer "B.Cu")
		(net "UPI_CPU1_CPU0_P0P0_DP<18>")
	)
	(segment
		(start 164.36721 -117.432582)
		(end 164.584634 -117.503448)
		(width 0.1143)
		(layer "B.Cu")
		(net "UPI_CPU1_CPU0_P0P0_DP<18>")
	)
	(segment
		(start 296.635932 -122.333766)
		(end 299.27677 -122.863356)
		(width 0.1143)
		(layer "B.Cu")
		(net "UPI_CPU1_CPU0_P0P0_DP<18>")
	)
	(segment
		(start 331.47 -93.230192)
		(end 330.454762 -90.69197)
		(width 0.1143)
		(layer "B.Cu")
		(net "UPI_CPU1_CPU0_P0P0_DP<18>")
	)
	(segment
		(start 143.255238 -73.399142)
		(end 143.531082 -73.823322)
		(width 0.1143)
		(layer "B.Cu")
		(net "UPI_CPU1_CPU0_P0P0_DP<18>")
	)
	(segment
		(start 160.080452 -115.55476)
		(end 160.128458 -115.727988)
		(width 0.1143)
		(layer "B.Cu")
		(net "UPI_CPU1_CPU0_P0P0_DP<18>")
	)
	(segment
		(start 159.708088 -115.490244)
		(end 159.881316 -115.442238)
		(width 0.1143)
		(layer "B.Cu")
		(net "UPI_CPU1_CPU0_P0P0_DP<18>")
	)
	(segment
		(start 321.40906 -64.940688)
		(end 314.995814 -60.723526)
		(width 0.1143)
		(layer "B.Cu")
		(net "UPI_CPU1_CPU0_P0P0_DP<18>")
	)
	(segment
		(start 201.763122 -125.338332)
		(end 208.359248 -125.768862)
		(width 0.1143)
		(layer "B.Cu")
		(net "UPI_CPU1_CPU0_P0P0_DP<18>")
	)
	(segment
		(start 330.453746 -90.688922)
		(end 329.860656 -89.205816)
		(width 0.1143)
		(layer "B.Cu")
		(net "UPI_CPU1_CPU0_P0P0_DP<18>")
	)
	(segment
		(start 291.125402 -122.643138)
		(end 293.116254 -123.0376)
		(width 0.1143)
		(layer "B.Cu")
		(net "UPI_CPU1_CPU0_P0P0_DP<18>")
	)
	(segment
		(start 157.26664 -113.970308)
		(end 157.442408 -113.93297)
		(width 0.1143)
		(layer "B.Cu")
		(net "UPI_CPU1_CPU0_P0P0_DP<18>")
	)
	(segment
		(start 163.361624 -117.238272)
		(end 163.530788 -117.29339)
		(width 0.1143)
		(layer "B.Cu")
		(net "UPI_CPU1_CPU0_P0P0_DP<18>")
	)
	(segment
		(start 301.877984 -61.940186)
		(end 301.812706 -62.005464)
		(width 0.0889)
		(layer "B.Cu")
		(net "UPI_CPU1_CPU0_P0P0_DP<18>")
	)
	(segment
		(start 160.06572 -115.546378)
		(end 160.080452 -115.55476)
		(width 0.1143)
		(layer "B.Cu")
		(net "UPI_CPU1_CPU0_P0P0_DP<18>")
	)
	(segment
		(start 164.666168 -117.663976)
		(end 165.503098 -117.936772)
		(width 0.1143)
		(layer "B.Cu")
		(net "UPI_CPU1_CPU0_P0P0_DP<18>")
	)
	(segment
		(start 163.232338 -117.06225)
		(end 163.313618 -117.222524)
		(width 0.1143)
		(layer "B.Cu")
		(net "UPI_CPU1_CPU0_P0P0_DP<18>")
	)
	(segment
		(start 301.812706 -62.005464)
		(end 301.812706 -62.343538)
		(width 0.0889)
		(layer "B.Cu")
		(net "UPI_CPU1_CPU0_P0P0_DP<18>")
	)
	(segment
		(start 145.266918 -78.343506)
		(end 146.52752 -84.6455)
		(width 0.1143)
		(layer "B.Cu")
		(net "UPI_CPU1_CPU0_P0P0_DP<18>")
	)
	(segment
		(start 328.592434 -79.8322)
		(end 328.537824 -77.731874)
		(width 0.1143)
		(layer "B.Cu")
		(net "UPI_CPU1_CPU0_P0P0_DP<18>")
	)
	(segment
		(start 319.336166 -115.993926)
		(end 331.47 -104.558338)
		(width 0.1143)
		(layer "B.Cu")
		(net "UPI_CPU1_CPU0_P0P0_DP<18>")
	)
	(segment
		(start 307.329586 -60.10402)
		(end 307.1876 -59.962034)
		(width 0.0889)
		(layer "B.Cu")
		(net "UPI_CPU1_CPU0_P0P0_DP<18>")
	)
	(segment
		(start 332.14564 -94.918784)
		(end 331.688694 -93.7768)
		(width 0.1143)
		(layer "B.Cu")
		(net "UPI_CPU1_CPU0_P0P0_DP<18>")
	)
	(segment
		(start 307.1876 -59.962034)
		(end 306.953412 -59.962034)
		(width 0.0889)
		(layer "B.Cu")
		(net "UPI_CPU1_CPU0_P0P0_DP<18>")
	)
	(segment
		(start 323.352414 -68.4276)
		(end 321.40906 -64.940688)
		(width 0.1143)
		(layer "B.Cu")
		(net "UPI_CPU1_CPU0_P0P0_DP<18>")
	)
	(segment
		(start 163.01466 -116.991384)
		(end 163.232338 -117.06225)
		(width 0.1143)
		(layer "B.Cu")
		(net "UPI_CPU1_CPU0_P0P0_DP<18>")
	)
	(segment
		(start 142.464536 -72.744584)
		(end 142.464536 -72.970136)
		(width 0.1143)
		(layer "B.Cu")
		(net "UPI_CPU1_CPU0_P0P0_DP<18>")
	)
	(segment
		(start 263.07796 -121.582434)
		(end 284.45968 -123.755404)
		(width 0.1143)
		(layer "B.Cu")
		(net "UPI_CPU1_CPU0_P0P0_DP<18>")
	)
	(segment
		(start 306.126896 -60.457334)
		(end 306.083716 -60.457334)
		(width 0.0889)
		(layer "B.Cu")
		(net "UPI_CPU1_CPU0_P0P0_DP<18>")
	)
	(segment
		(start 152.875742 -110.903766)
		(end 154.013408 -111.858044)
		(width 0.1143)
		(layer "B.Cu")
		(net "UPI_CPU1_CPU0_P0P0_DP<18>")
	)
	(segment
		(start 146.52752 -88.767158)
		(end 144.675098 -98.030538)
		(width 0.1143)
		(layer "B.Cu")
		(net "UPI_CPU1_CPU0_P0P0_DP<18>")
	)
	(segment
		(start 163.691062 -117.211856)
		(end 163.908486 -117.282722)
		(width 0.1143)
		(layer "B.Cu")
		(net "UPI_CPU1_CPU0_P0P0_DP<18>")
	)
	(segment
		(start 163.989766 -117.44325)
		(end 164.206936 -117.514116)
		(width 0.1143)
		(layer "B.Cu")
		(net "UPI_CPU1_CPU0_P0P0_DP<18>")
	)
	(segment
		(start 157.634432 -114.05743)
		(end 157.67177 -114.233198)
		(width 0.1143)
		(layer "B.Cu")
		(net "UPI_CPU1_CPU0_P0P0_DP<18>")
	)
	(segment
		(start 164.584634 -117.503448)
		(end 164.666168 -117.663976)
		(width 0.1143)
		(layer "B.Cu")
		(net "UPI_CPU1_CPU0_P0P0_DP<18>")
	)
	(segment
		(start 142.938246 -73.08215)
		(end 143.255238 -73.399142)
		(width 0.1143)
		(layer "B.Cu")
		(net "UPI_CPU1_CPU0_P0P0_DP<18>")
	)
	(segment
		(start 198.48576 -125.77572)
		(end 201.763122 -125.338332)
		(width 0.1143)
		(layer "B.Cu")
		(net "UPI_CPU1_CPU0_P0P0_DP<18>")
	)
	(segment
		(start 157.863286 -114.357658)
		(end 158.039054 -114.32032)
		(width 0.1143)
		(layer "B.Cu")
		(net "UPI_CPU1_CPU0_P0P0_DP<18>")
	)
	(segment
		(start 158.926276 -115.047776)
		(end 159.110172 -115.151916)
		(width 0.1143)
		(layer "B.Cu")
		(net "UPI_CPU1_CPU0_P0P0_DP<18>")
	)
	(segment
		(start 157.442408 -113.93297)
		(end 157.634432 -114.05743)
		(width 0.1143)
		(layer "B.Cu")
		(net "UPI_CPU1_CPU0_P0P0_DP<18>")
	)
	(segment
		(start 309.062374 -59.6265)
		(end 308.584854 -60.10402)
		(width 0.0889)
		(layer "B.Cu")
		(net "UPI_CPU1_CPU0_P0P0_DP<18>")
	)
	(segment
		(start 303.547526 -60.952888)
		(end 303.51476 -60.952888)
		(width 0.0889)
		(layer "B.Cu")
		(net "UPI_CPU1_CPU0_P0P0_DP<18>")
	)
	(segment
		(start 157.67177 -114.233198)
		(end 157.863286 -114.357658)
		(width 0.1143)
		(layer "B.Cu")
		(net "UPI_CPU1_CPU0_P0P0_DP<18>")
	)
	(segment
		(start 163.530788 -117.29339)
		(end 163.691062 -117.211856)
		(width 0.1143)
		(layer "B.Cu")
		(net "UPI_CPU1_CPU0_P0P0_DP<18>")
	)
	(segment
		(start 144.675098 -98.030538)
		(end 145.25625 -100.93579)
		(width 0.1143)
		(layer "B.Cu")
		(net "UPI_CPU1_CPU0_P0P0_DP<18>")
	)
	(segment
		(start 331.688694 -93.7768)
		(end 331.47 -93.230192)
		(width 0.1143)
		(layer "B.Cu")
		(net "UPI_CPU1_CPU0_P0P0_DP<18>")
	)
	(segment
		(start 156.669994 -113.582958)
		(end 156.845762 -113.54562)
		(width 0.1143)
		(layer "B.Cu")
		(net "UPI_CPU1_CPU0_P0P0_DP<18>")
	)
	(segment
		(start 158.268416 -114.620548)
		(end 158.36138 -114.681)
		(width 0.1143)
		(layer "B.Cu")
		(net "UPI_CPU1_CPU0_P0P0_DP<18>")
	)
	(segment
		(start 165.503098 -117.936772)
		(end 166.479982 -118.226332)
		(width 0.1143)
		(layer "B.Cu")
		(net "UPI_CPU1_CPU0_P0P0_DP<18>")
	)
	(segment
		(start 302.692816 -61.447934)
		(end 302.66005 -61.447934)
		(width 0.0889)
		(layer "B.Cu")
		(net "UPI_CPU1_CPU0_P0P0_DP<18>")
	)
	(segment
		(start 328.764646 -86.465664)
		(end 328.592434 -79.8322)
		(width 0.1143)
		(layer "B.Cu")
		(net "UPI_CPU1_CPU0_P0P0_DP<18>")
	)
	(segment
		(start 331.849476 -104.200706)
		(end 332.14564 -94.918784)
		(width 0.1143)
		(layer "B.Cu")
		(net "UPI_CPU1_CPU0_P0P0_DP<18>")
	)
	(segment
		(start 249.5423 -123.20143)
		(end 263.07796 -121.582434)
		(width 0.1143)
		(layer "B.Cu")
		(net "UPI_CPU1_CPU0_P0P0_DP<18>")
	)
	(segment
		(start 156.44114 -113.28273)
		(end 156.478478 -113.458498)
		(width 0.1143)
		(layer "B.Cu")
		(net "UPI_CPU1_CPU0_P0P0_DP<18>")
	)
	(segment
		(start 331.47 -104.558338)
		(end 331.724 -104.31907)
		(width 0.1143)
		(layer "B.Cu")
		(net "UPI_CPU1_CPU0_P0P0_DP<18>")
	)
	(segment
		(start 157.075124 -113.845848)
		(end 157.26664 -113.970308)
		(width 0.1143)
		(layer "B.Cu")
		(net "UPI_CPU1_CPU0_P0P0_DP<18>")
	)
	(segment
		(start 156.073602 -113.195608)
		(end 156.249116 -113.15827)
		(width 0.1143)
		(layer "B.Cu")
		(net "UPI_CPU1_CPU0_P0P0_DP<18>")
	)
	(segment
		(start 173.385734 -121.47423)
		(end 182.059072 -122.018552)
		(width 0.1143)
		(layer "B.Cu")
		(net "UPI_CPU1_CPU0_P0P0_DP<18>")
	)
	(segment
		(start 312.408824 -59.6519)
		(end 310.6928 -59.6519)
		(width 0.1143)
		(layer "B.Cu")
		(net "UPI_CPU1_CPU0_P0P0_DP<18>")
	)
	(segment
		(start 156.845762 -113.54562)
		(end 157.037786 -113.67008)
		(width 0.1143)
		(layer "B.Cu")
		(net "UPI_CPU1_CPU0_P0P0_DP<18>")
	)
	(segment
		(start 159.881316 -115.442238)
		(end 160.06572 -115.546378)
		(width 0.1143)
		(layer "B.Cu")
		(net "UPI_CPU1_CPU0_P0P0_DP<18>")
	)
	(segment
		(start 284.45968 -123.755404)
		(end 290.57092 -122.533156)
		(width 0.1143)
		(layer "B.Cu")
		(net "UPI_CPU1_CPU0_P0P0_DP<18>")
	)
	(segment
		(start 192.447164 -125.512576)
		(end 198.48576 -125.77572)
		(width 0.1143)
		(layer "B.Cu")
		(net "UPI_CPU1_CPU0_P0P0_DP<18>")
	)
	(segment
		(start 310.645302 -59.6265)
		(end 309.062374 -59.6265)
		(width 0.0889)
		(layer "B.Cu")
		(net "UPI_CPU1_CPU0_P0P0_DP<18>")
	)
	(segment
		(start 310.670702 -59.6519)
		(end 310.645302 -59.6265)
		(width 0.0889)
		(layer "B.Cu")
		(net "UPI_CPU1_CPU0_P0P0_DP<18>")
	)
	(segment
		(start 146.52752 -84.6455)
		(end 146.52752 -88.767158)
		(width 0.1143)
		(layer "B.Cu")
		(net "UPI_CPU1_CPU0_P0P0_DP<18>")
	)
	(segment
		(start 330.454762 -90.69197)
		(end 330.453746 -90.688922)
		(width 0.1143)
		(layer "B.Cu")
		(net "UPI_CPU1_CPU0_P0P0_DP<18>")
	)
	(segment
		(start 156.478478 -113.458498)
		(end 156.669994 -113.582958)
		(width 0.1143)
		(layer "B.Cu")
		(net "UPI_CPU1_CPU0_P0P0_DP<18>")
	)
	(segment
		(start 163.313618 -117.222524)
		(end 163.361624 -117.238272)
		(width 0.1143)
		(layer "B.Cu")
		(net "UPI_CPU1_CPU0_P0P0_DP<18>")
	)
	(segment
		(start 293.116254 -123.0376)
		(end 296.635932 -122.333766)
		(width 0.1143)
		(layer "B.Cu")
		(net "UPI_CPU1_CPU0_P0P0_DP<18>")
	)
	(segment
		(start 160.128458 -115.727988)
		(end 162.028886 -116.803424)
		(width 0.1143)
		(layer "B.Cu")
		(net "UPI_CPU1_CPU0_P0P0_DP<18>")
	)
	(segment
		(start 305.261772 -59.962288)
		(end 305.2318 -59.962288)
		(width 0.0889)
		(layer "B.Cu")
		(net "UPI_CPU1_CPU0_P0P0_DP<18>")
	)
	(segment
		(start 158.36138 -114.681)
		(end 158.926276 -115.047776)
		(width 0.1143)
		(layer "B.Cu")
		(net "UPI_CPU1_CPU0_P0P0_DP<18>")
	)
	(segment
		(start 142.57655 -73.08215)
		(end 142.938246 -73.08215)
		(width 0.1143)
		(layer "B.Cu")
		(net "UPI_CPU1_CPU0_P0P0_DP<18>")
	)
	(segment
		(start 308.584854 -60.10402)
		(end 307.329586 -60.10402)
		(width 0.0889)
		(layer "B.Cu")
		(net "UPI_CPU1_CPU0_P0P0_DP<18>")
	)
	(segment
		(start 162.028886 -116.803424)
		(end 162.85464 -117.072664)
		(width 0.1143)
		(layer "B.Cu")
		(net "UPI_CPU1_CPU0_P0P0_DP<18>")
	)
	(segment
		(start 158.039054 -114.32032)
		(end 158.231078 -114.44478)
		(width 0.1143)
		(layer "B.Cu")
		(net "UPI_CPU1_CPU0_P0P0_DP<18>")
	)
	(segment
		(start 156.249116 -113.15827)
		(end 156.44114 -113.28273)
		(width 0.1143)
		(layer "B.Cu")
		(net "UPI_CPU1_CPU0_P0P0_DP<18>")
	)
	(segment
		(start 226.818444 -122.06224)
		(end 249.5423 -123.20143)
		(width 0.1143)
		(layer "B.Cu")
		(net "UPI_CPU1_CPU0_P0P0_DP<18>")
	)
	(segment
		(start 208.359248 -125.768862)
		(end 226.818444 -122.06224)
		(width 0.1143)
		(layer "B.Cu")
		(net "UPI_CPU1_CPU0_P0P0_DP<18>")
	)
	(segment
		(start 182.059072 -122.018552)
		(end 192.447164 -125.512576)
		(width 0.1143)
		(layer "B.Cu")
		(net "UPI_CPU1_CPU0_P0P0_DP<18>")
	)
	(segment
		(start 328.93 -86.879176)
		(end 328.764646 -86.465664)
		(width 0.1143)
		(layer "B.Cu")
		(net "UPI_CPU1_CPU0_P0P0_DP<18>")
	)
	(segment
		(start 163.908486 -117.282722)
		(end 163.989766 -117.44325)
		(width 0.1143)
		(layer "B.Cu")
		(net "UPI_CPU1_CPU0_P0P0_DP<18>")
	)
	(segment
		(start 143.531082 -73.823322)
		(end 145.266918 -78.343506)
		(width 0.1143)
		(layer "B.Cu")
		(net "UPI_CPU1_CPU0_P0P0_DP<18>")
	)
	(segment
		(start 328.537824 -77.731874)
		(end 323.352414 -68.4276)
		(width 0.1143)
		(layer "B.Cu")
		(net "UPI_CPU1_CPU0_P0P0_DP<18>")
	)
	(segment
		(start 157.037786 -113.67008)
		(end 157.075124 -113.845848)
		(width 0.1143)
		(layer "B.Cu")
		(net "UPI_CPU1_CPU0_P0P0_DP<18>")
	)
	(segment
		(start 329.860656 -89.205816)
		(end 328.93 -86.879176)
		(width 0.1143)
		(layer "B.Cu")
		(net "UPI_CPU1_CPU0_P0P0_DP<18>")
	)
	(arc
		(start 304.041556 -60.657486)
		(mid 303.832948 -60.869418)
		(end 303.547526 -60.952888)
		(width 0.0889)
		(layer "B.Cu")
		(net "UPI_CPU1_CPU0_P0P0_DP<18>")
	)
	(arc
		(start 306.083716 -60.457334)
		(mid 305.800499 -60.373053)
		(end 305.593496 -60.162186)
		(width 0.0889)
		(layer "B.Cu")
		(net "UPI_CPU1_CPU0_P0P0_DP<18>")
	)
	(arc
		(start 305.593496 -60.162186)
		(mid 305.453417 -60.01945)
		(end 305.261772 -59.962288)
		(width 0.0889)
		(layer "B.Cu")
		(net "UPI_CPU1_CPU0_P0P0_DP<18>")
	)
	(arc
		(start 306.94884 -59.962288)
		(mid 306.757198 -60.019454)
		(end 306.617116 -60.162186)
		(width 0.0889)
		(layer "B.Cu")
		(net "UPI_CPU1_CPU0_P0P0_DP<18>")
	)
	(arc
		(start 302.324516 -61.648086)
		(mid 302.136093 -61.84739)
		(end 301.877984 -61.940186)
		(width 0.0889)
		(layer "B.Cu")
		(net "UPI_CPU1_CPU0_P0P0_DP<18>")
	)
	(arc
		(start 304.900076 -60.162186)
		(mid 304.693072 -60.37305)
		(end 304.409856 -60.457334)
		(width 0.0889)
		(layer "B.Cu")
		(net "UPI_CPU1_CPU0_P0P0_DP<18>")
	)
	(arc
		(start 303.183036 -61.152786)
		(mid 302.976032 -61.36365)
		(end 302.692816 -61.447934)
		(width 0.0889)
		(layer "B.Cu")
		(net "UPI_CPU1_CPU0_P0P0_DP<18>")
	)
	(arc
		(start 304.37709 -60.457334)
		(mid 304.18324 -60.513684)
		(end 304.041556 -60.657486)
		(width 0.0889)
		(layer "B.Cu")
		(net "UPI_CPU1_CPU0_P0P0_DP<18>")
	)
	(arc
		(start 302.66005 -61.447934)
		(mid 302.4662 -61.504284)
		(end 302.324516 -61.648086)
		(width 0.0889)
		(layer "B.Cu")
		(net "UPI_CPU1_CPU0_P0P0_DP<18>")
	)
	(arc
		(start 306.953412 -59.962034)
		(mid 306.951126 -59.962154)
		(end 306.94884 -59.962288)
		(width 0.0889)
		(layer "B.Cu")
		(net "UPI_CPU1_CPU0_P0P0_DP<18>")
	)
	(arc
		(start 303.51476 -60.952888)
		(mid 303.323118 -61.010054)
		(end 303.183036 -61.152786)
		(width 0.0889)
		(layer "B.Cu")
		(net "UPI_CPU1_CPU0_P0P0_DP<18>")
	)
	(arc
		(start 306.617116 -60.162186)
		(mid 306.410112 -60.37305)
		(end 306.126896 -60.457334)
		(width 0.0889)
		(layer "B.Cu")
		(net "UPI_CPU1_CPU0_P0P0_DP<18>")
	)
	(arc
		(start 305.2318 -59.962288)
		(mid 305.040158 -60.019454)
		(end 304.900076 -60.162186)
		(width 0.0889)
		(layer "B.Cu")
		(net "UPI_CPU1_CPU0_P0P0_DP<18>")
	)
	(segment
		(start 141.391894 -72.249538)
		(end 142.039594 -72.249538)
		(width 0.1143)
		(layer "F.Cu")
		(net "UPI_CPU1_CPU0_P0P0_DP<17>")
	)
	(segment
		(start 303.529746 -61.352938)
		(end 302.958246 -61.352938)
		(width 0.1143)
		(layer "F.Cu")
		(net "UPI_CPU1_CPU0_P0P0_DP<17>")
	)
	(via
		(at 142.039594 -72.249538)
		(size 0.508)
		(drill 0.254)
		(layers "F.Cu" "B.Cu")
		(net "UPI_CPU1_CPU0_P0P0_DP<17>")
	)
	(via
		(at 303.529746 -61.352938)
		(size 0.508)
		(drill 0.254)
		(layers "F.Cu" "B.Cu")
		(net "UPI_CPU1_CPU0_P0P0_DP<17>")
	)
	(segment
		(start 304.403252 -61.257434)
		(end 304.370486 -61.257434)
		(width 0.0889)
		(layer "B.Cu")
		(net "UPI_CPU1_CPU0_P0P0_DP<17>")
	)
	(segment
		(start 309.005986 -61.257434)
		(end 308.5973 -61.257434)
		(width 0.0889)
		(layer "B.Cu")
		(net "UPI_CPU1_CPU0_P0P0_DP<17>")
	)
	(segment
		(start 144.513046 -74.726546)
		(end 144.58188 -74.875644)
		(width 0.1143)
		(layer "B.Cu")
		(net "UPI_CPU1_CPU0_P0P0_DP<17>")
	)
	(segment
		(start 143.888714 -73.317608)
		(end 144.516602 -74.673206)
		(width 0.0889)
		(layer "B.Cu")
		(net "UPI_CPU1_CPU0_P0P0_DP<17>")
	)
	(segment
		(start 263.07796 -120.852692)
		(end 284.373574 -123.01601)
		(width 0.1143)
		(layer "B.Cu")
		(net "UPI_CPU1_CPU0_P0P0_DP<17>")
	)
	(segment
		(start 192.582546 -124.791724)
		(end 198.341488 -125.04293)
		(width 0.1143)
		(layer "B.Cu")
		(net "UPI_CPU1_CPU0_P0P0_DP<17>")
	)
	(segment
		(start 308.3179 -61.155834)
		(end 308.2163 -61.257434)
		(width 0.0889)
		(layer "B.Cu")
		(net "UPI_CPU1_CPU0_P0P0_DP<17>")
	)
	(segment
		(start 147.049998 -102.672388)
		(end 153.4541 -110.440978)
		(width 0.1143)
		(layer "B.Cu")
		(net "UPI_CPU1_CPU0_P0P0_DP<17>")
	)
	(segment
		(start 299.581824 -122.00509)
		(end 309.764684 -119.963184)
		(width 0.1143)
		(layer "B.Cu")
		(net "UPI_CPU1_CPU0_P0P0_DP<17>")
	)
	(segment
		(start 145.598642 -98.370644)
		(end 146.12493 -101.0031)
		(width 0.1143)
		(layer "B.Cu")
		(net "UPI_CPU1_CPU0_P0P0_DP<17>")
	)
	(segment
		(start 145.690844 -77.275182)
		(end 147.753832 -87.593424)
		(width 0.1143)
		(layer "B.Cu")
		(net "UPI_CPU1_CPU0_P0P0_DP<17>")
	)
	(segment
		(start 319.035684 -115.2652)
		(end 330.976224 -104.016302)
		(width 0.1143)
		(layer "B.Cu")
		(net "UPI_CPU1_CPU0_P0P0_DP<17>")
	)
	(segment
		(start 182.19928 -121.299732)
		(end 192.582546 -124.791724)
		(width 0.1143)
		(layer "B.Cu")
		(net "UPI_CPU1_CPU0_P0P0_DP<17>")
	)
	(segment
		(start 142.039594 -72.249538)
		(end 141.718538 -72.249538)
		(width 0.0889)
		(layer "B.Cu")
		(net "UPI_CPU1_CPU0_P0P0_DP<17>")
	)
	(segment
		(start 155.893008 -112.169956)
		(end 159.878014 -113.928144)
		(width 0.1143)
		(layer "B.Cu")
		(net "UPI_CPU1_CPU0_P0P0_DP<17>")
	)
	(segment
		(start 310.6928 -60.5282)
		(end 310.6674 -60.5536)
		(width 0.0889)
		(layer "B.Cu")
		(net "UPI_CPU1_CPU0_P0P0_DP<17>")
	)
	(segment
		(start 159.878014 -113.928144)
		(end 162.568636 -114.287554)
		(width 0.1143)
		(layer "B.Cu")
		(net "UPI_CPU1_CPU0_P0P0_DP<17>")
	)
	(segment
		(start 293.158418 -122.496834)
		(end 297.601894 -121.608088)
		(width 0.1143)
		(layer "B.Cu")
		(net "UPI_CPU1_CPU0_P0P0_DP<17>")
	)
	(segment
		(start 142.515844 -71.944738)
		(end 143.888714 -73.317608)
		(width 0.0889)
		(layer "B.Cu")
		(net "UPI_CPU1_CPU0_P0P0_DP<17>")
	)
	(segment
		(start 162.568636 -114.287554)
		(end 163.031678 -114.461798)
		(width 0.1143)
		(layer "B.Cu")
		(net "UPI_CPU1_CPU0_P0P0_DP<17>")
	)
	(segment
		(start 144.516602 -74.673206)
		(end 144.513046 -74.726546)
		(width 0.0889)
		(layer "B.Cu")
		(net "UPI_CPU1_CPU0_P0P0_DP<17>")
	)
	(segment
		(start 173.517052 -120.754902)
		(end 182.19928 -121.299732)
		(width 0.1143)
		(layer "B.Cu")
		(net "UPI_CPU1_CPU0_P0P0_DP<17>")
	)
	(segment
		(start 284.373574 -123.01601)
		(end 290.060888 -121.878598)
		(width 0.1143)
		(layer "B.Cu")
		(net "UPI_CPU1_CPU0_P0P0_DP<17>")
	)
	(segment
		(start 309.131462 -60.997084)
		(end 309.131462 -61.131958)
		(width 0.0889)
		(layer "B.Cu")
		(net "UPI_CPU1_CPU0_P0P0_DP<17>")
	)
	(segment
		(start 164.84092 -116.44122)
		(end 170.995086 -119.993918)
		(width 0.1143)
		(layer "B.Cu")
		(net "UPI_CPU1_CPU0_P0P0_DP<17>")
	)
	(segment
		(start 153.4541 -110.440978)
		(end 154.425142 -111.25581)
		(width 0.1143)
		(layer "B.Cu")
		(net "UPI_CPU1_CPU0_P0P0_DP<17>")
	)
	(segment
		(start 327.660762 -77.964284)
		(end 320.745866 -65.555876)
		(width 0.1143)
		(layer "B.Cu")
		(net "UPI_CPU1_CPU0_P0P0_DP<17>")
	)
	(segment
		(start 198.341488 -125.04293)
		(end 201.672952 -124.604526)
		(width 0.1143)
		(layer "B.Cu")
		(net "UPI_CPU1_CPU0_P0P0_DP<17>")
	)
	(segment
		(start 297.601894 -121.608088)
		(end 299.581824 -122.00509)
		(width 0.1143)
		(layer "B.Cu")
		(net "UPI_CPU1_CPU0_P0P0_DP<17>")
	)
	(segment
		(start 327.886822 -86.661498)
		(end 327.660762 -77.964284)
		(width 0.1143)
		(layer "B.Cu")
		(net "UPI_CPU1_CPU0_P0P0_DP<17>")
	)
	(segment
		(start 290.060888 -121.878598)
		(end 293.158418 -122.496834)
		(width 0.1143)
		(layer "B.Cu")
		(net "UPI_CPU1_CPU0_P0P0_DP<17>")
	)
	(segment
		(start 309.70982 -60.5536)
		(end 309.40121 -60.86221)
		(width 0.0889)
		(layer "B.Cu")
		(net "UPI_CPU1_CPU0_P0P0_DP<17>")
	)
	(segment
		(start 330.976224 -104.016302)
		(end 331.260704 -95.095314)
		(width 0.1143)
		(layer "B.Cu")
		(net "UPI_CPU1_CPU0_P0P0_DP<17>")
	)
	(segment
		(start 331.260704 -95.095314)
		(end 327.886822 -86.661498)
		(width 0.1143)
		(layer "B.Cu")
		(net "UPI_CPU1_CPU0_P0P0_DP<17>")
	)
	(segment
		(start 306.120292 -61.257434)
		(end 306.09032 -61.257434)
		(width 0.0889)
		(layer "B.Cu")
		(net "UPI_CPU1_CPU0_P0P0_DP<17>")
	)
	(segment
		(start 307.167026 -60.762388)
		(end 306.942236 -60.762388)
		(width 0.0889)
		(layer "B.Cu")
		(net "UPI_CPU1_CPU0_P0P0_DP<17>")
	)
	(segment
		(start 309.266336 -60.86221)
		(end 309.131462 -60.997084)
		(width 0.0889)
		(layer "B.Cu")
		(net "UPI_CPU1_CPU0_P0P0_DP<17>")
	)
	(segment
		(start 309.131462 -61.131958)
		(end 309.005986 -61.257434)
		(width 0.0889)
		(layer "B.Cu")
		(net "UPI_CPU1_CPU0_P0P0_DP<17>")
	)
	(segment
		(start 305.268376 -60.762388)
		(end 305.225196 -60.762388)
		(width 0.0889)
		(layer "B.Cu")
		(net "UPI_CPU1_CPU0_P0P0_DP<17>")
	)
	(segment
		(start 147.753832 -87.593424)
		(end 145.598642 -98.370644)
		(width 0.1143)
		(layer "B.Cu")
		(net "UPI_CPU1_CPU0_P0P0_DP<17>")
	)
	(segment
		(start 154.425142 -111.25581)
		(end 155.893008 -112.169956)
		(width 0.1143)
		(layer "B.Cu")
		(net "UPI_CPU1_CPU0_P0P0_DP<17>")
	)
	(segment
		(start 144.58188 -74.875644)
		(end 145.690844 -77.275182)
		(width 0.1143)
		(layer "B.Cu")
		(net "UPI_CPU1_CPU0_P0P0_DP<17>")
	)
	(segment
		(start 303.215548 -61.600588)
		(end 303.23663 -61.521848)
		(width 0.0889)
		(layer "B.Cu")
		(net "UPI_CPU1_CPU0_P0P0_DP<17>")
	)
	(segment
		(start 308.2163 -61.257434)
		(end 307.731668 -61.257434)
		(width 0.0889)
		(layer "B.Cu")
		(net "UPI_CPU1_CPU0_P0P0_DP<17>")
	)
	(segment
		(start 308.5973 -61.257434)
		(end 308.4957 -61.155834)
		(width 0.0889)
		(layer "B.Cu")
		(net "UPI_CPU1_CPU0_P0P0_DP<17>")
	)
	(segment
		(start 309.40121 -60.86221)
		(end 309.266336 -60.86221)
		(width 0.0889)
		(layer "B.Cu")
		(net "UPI_CPU1_CPU0_P0P0_DP<17>")
	)
	(segment
		(start 308.4957 -61.155834)
		(end 308.3179 -61.155834)
		(width 0.0889)
		(layer "B.Cu")
		(net "UPI_CPU1_CPU0_P0P0_DP<17>")
	)
	(segment
		(start 303.43602 -61.40704)
		(end 303.529746 -61.352938)
		(width 0.0889)
		(layer "B.Cu")
		(net "UPI_CPU1_CPU0_P0P0_DP<17>")
	)
	(segment
		(start 312.205878 -60.5282)
		(end 310.6928 -60.5282)
		(width 0.1143)
		(layer "B.Cu")
		(net "UPI_CPU1_CPU0_P0P0_DP<17>")
	)
	(segment
		(start 320.745866 -65.555876)
		(end 314.61583 -61.52515)
		(width 0.1143)
		(layer "B.Cu")
		(net "UPI_CPU1_CPU0_P0P0_DP<17>")
	)
	(segment
		(start 141.718538 -72.249538)
		(end 141.6304 -72.1614)
		(width 0.0889)
		(layer "B.Cu")
		(net "UPI_CPU1_CPU0_P0P0_DP<17>")
	)
	(segment
		(start 201.672952 -124.604526)
		(end 208.30794 -125.038612)
		(width 0.1143)
		(layer "B.Cu")
		(net "UPI_CPU1_CPU0_P0P0_DP<17>")
	)
	(segment
		(start 314.61583 -61.52515)
		(end 312.205878 -60.5282)
		(width 0.1143)
		(layer "B.Cu")
		(net "UPI_CPU1_CPU0_P0P0_DP<17>")
	)
	(segment
		(start 146.12493 -101.0031)
		(end 147.049998 -102.672388)
		(width 0.1143)
		(layer "B.Cu")
		(net "UPI_CPU1_CPU0_P0P0_DP<17>")
	)
	(segment
		(start 141.6304 -71.9836)
		(end 141.764512 -71.849488)
		(width 0.0889)
		(layer "B.Cu")
		(net "UPI_CPU1_CPU0_P0P0_DP<17>")
	)
	(segment
		(start 310.6674 -60.5536)
		(end 309.70982 -60.5536)
		(width 0.0889)
		(layer "B.Cu")
		(net "UPI_CPU1_CPU0_P0P0_DP<17>")
	)
	(segment
		(start 309.764684 -119.963184)
		(end 319.035684 -115.2652)
		(width 0.1143)
		(layer "B.Cu")
		(net "UPI_CPU1_CPU0_P0P0_DP<17>")
	)
	(segment
		(start 208.30794 -125.038612)
		(end 226.761294 -121.332244)
		(width 0.1143)
		(layer "B.Cu")
		(net "UPI_CPU1_CPU0_P0P0_DP<17>")
	)
	(segment
		(start 249.430032 -122.468894)
		(end 263.07796 -120.852692)
		(width 0.1143)
		(layer "B.Cu")
		(net "UPI_CPU1_CPU0_P0P0_DP<17>")
	)
	(segment
		(start 163.031678 -114.461798)
		(end 164.84092 -116.44122)
		(width 0.1143)
		(layer "B.Cu")
		(net "UPI_CPU1_CPU0_P0P0_DP<17>")
	)
	(segment
		(start 226.761294 -121.332244)
		(end 249.430032 -122.468894)
		(width 0.1143)
		(layer "B.Cu")
		(net "UPI_CPU1_CPU0_P0P0_DP<17>")
	)
	(segment
		(start 303.23663 -61.521848)
		(end 303.43602 -61.40704)
		(width 0.0889)
		(layer "B.Cu")
		(net "UPI_CPU1_CPU0_P0P0_DP<17>")
	)
	(segment
		(start 141.6304 -72.1614)
		(end 141.6304 -71.9836)
		(width 0.0889)
		(layer "B.Cu")
		(net "UPI_CPU1_CPU0_P0P0_DP<17>")
	)
	(segment
		(start 142.28572 -71.849488)
		(end 142.515844 -71.944738)
		(width 0.0889)
		(layer "B.Cu")
		(net "UPI_CPU1_CPU0_P0P0_DP<17>")
	)
	(segment
		(start 170.995086 -119.993918)
		(end 173.517052 -120.754902)
		(width 0.1143)
		(layer "B.Cu")
		(net "UPI_CPU1_CPU0_P0P0_DP<17>")
	)
	(segment
		(start 141.764512 -71.849488)
		(end 142.28572 -71.849488)
		(width 0.0889)
		(layer "B.Cu")
		(net "UPI_CPU1_CPU0_P0P0_DP<17>")
	)
	(arc
		(start 303.517808 -61.752988)
		(mid 303.349804 -61.710285)
		(end 303.215548 -61.600588)
		(width 0.0889)
		(layer "B.Cu")
		(net "UPI_CPU1_CPU0_P0P0_DP<17>")
	)
	(arc
		(start 303.876456 -61.552836)
		(mid 303.735242 -61.696466)
		(end 303.541938 -61.752988)
		(width 0.0889)
		(layer "B.Cu")
		(net "UPI_CPU1_CPU0_P0P0_DP<17>")
	)
	(arc
		(start 306.452016 -61.057536)
		(mid 306.311937 -61.200272)
		(end 306.120292 -61.257434)
		(width 0.0889)
		(layer "B.Cu")
		(net "UPI_CPU1_CPU0_P0P0_DP<17>")
	)
	(arc
		(start 306.09032 -61.257434)
		(mid 305.898678 -61.200268)
		(end 305.758596 -61.057536)
		(width 0.0889)
		(layer "B.Cu")
		(net "UPI_CPU1_CPU0_P0P0_DP<17>")
	)
	(arc
		(start 304.734976 -61.057536)
		(mid 304.594897 -61.200272)
		(end 304.403252 -61.257434)
		(width 0.0889)
		(layer "B.Cu")
		(net "UPI_CPU1_CPU0_P0P0_DP<17>")
	)
	(arc
		(start 306.942236 -60.762388)
		(mid 306.659019 -60.846669)
		(end 306.452016 -61.057536)
		(width 0.0889)
		(layer "B.Cu")
		(net "UPI_CPU1_CPU0_P0P0_DP<17>")
	)
	(arc
		(start 305.758596 -61.057536)
		(mid 305.551592 -60.846672)
		(end 305.268376 -60.762388)
		(width 0.0889)
		(layer "B.Cu")
		(net "UPI_CPU1_CPU0_P0P0_DP<17>")
	)
	(arc
		(start 305.225196 -60.762388)
		(mid 304.941979 -60.846669)
		(end 304.734976 -61.057536)
		(width 0.0889)
		(layer "B.Cu")
		(net "UPI_CPU1_CPU0_P0P0_DP<17>")
	)
	(arc
		(start 304.370486 -61.257434)
		(mid 304.085062 -61.340901)
		(end 303.876456 -61.552836)
		(width 0.0889)
		(layer "B.Cu")
		(net "UPI_CPU1_CPU0_P0P0_DP<17>")
	)
	(arc
		(start 307.515514 -61.06033)
		(mid 307.369589 -60.878243)
		(end 307.167026 -60.762388)
		(width 0.0889)
		(layer "B.Cu")
		(net "UPI_CPU1_CPU0_P0P0_DP<17>")
	)
	(arc
		(start 303.541938 -61.752988)
		(mid 303.529873 -61.753166)
		(end 303.517808 -61.752988)
		(width 0.0889)
		(layer "B.Cu")
		(net "UPI_CPU1_CPU0_P0P0_DP<17>")
	)
	(arc
		(start 307.731668 -61.257434)
		(mid 307.606467 -61.177663)
		(end 307.515514 -61.06033)
		(width 0.0889)
		(layer "B.Cu")
		(net "UPI_CPU1_CPU0_P0P0_DP<17>")
	)
	(segment
		(start 303.529746 -62.343538)
		(end 302.958246 -62.343538)
		(width 0.1143)
		(layer "F.Cu")
		(net "UPI_CPU1_CPU0_P0P0_DP<16>")
	)
	(segment
		(start 139.674854 -71.258938)
		(end 140.246354 -71.258938)
		(width 0.1143)
		(layer "F.Cu")
		(net "UPI_CPU1_CPU0_P0P0_DP<16>")
	)
	(via
		(at 140.246354 -71.258938)
		(size 0.508)
		(drill 0.254)
		(layers "F.Cu" "B.Cu")
		(net "UPI_CPU1_CPU0_P0P0_DP<16>")
	)
	(via
		(at 303.529746 -62.343538)
		(size 0.508)
		(drill 0.254)
		(layers "F.Cu" "B.Cu")
		(net "UPI_CPU1_CPU0_P0P0_DP<16>")
	)
	(segment
		(start 145.061686 -73.558654)
		(end 145.061686 -73.522586)
		(width 0.0889)
		(layer "B.Cu")
		(net "UPI_CPU1_CPU0_P0P0_DP<16>")
	)
	(segment
		(start 310.960262 -61.667898)
		(end 310.98236 -61.667898)
		(width 0.0889)
		(layer "B.Cu")
		(net "UPI_CPU1_CPU0_P0P0_DP<16>")
	)
	(segment
		(start 140.53947 -71.089774)
		(end 140.246354 -71.258938)
		(width 0.0889)
		(layer "B.Cu")
		(net "UPI_CPU1_CPU0_P0P0_DP<16>")
	)
	(segment
		(start 208.233772 -124.06122)
		(end 201.688954 -123.63577)
		(width 0.1143)
		(layer "B.Cu")
		(net "UPI_CPU1_CPU0_P0P0_DP<16>")
	)
	(segment
		(start 142.217648 -70.858888)
		(end 141.948154 -70.858888)
		(width 0.0889)
		(layer "B.Cu")
		(net "UPI_CPU1_CPU0_P0P0_DP<16>")
	)
	(segment
		(start 147.217384 -100.978462)
		(end 146.727672 -98.529648)
		(width 0.1143)
		(layer "B.Cu")
		(net "UPI_CPU1_CPU0_P0P0_DP<16>")
	)
	(segment
		(start 314.028582 -62.479682)
		(end 319.872614 -66.32194)
		(width 0.1143)
		(layer "B.Cu")
		(net "UPI_CPU1_CPU0_P0P0_DP<16>")
	)
	(segment
		(start 310.138318 -62.248288)
		(end 310.693308 -61.693298)
		(width 0.0889)
		(layer "B.Cu")
		(net "UPI_CPU1_CPU0_P0P0_DP<16>")
	)
	(segment
		(start 198.397368 -124.075952)
		(end 192.759838 -123.830588)
		(width 0.1143)
		(layer "B.Cu")
		(net "UPI_CPU1_CPU0_P0P0_DP<16>")
	)
	(segment
		(start 160.407604 -112.868964)
		(end 156.6926 -111.45266)
		(width 0.1143)
		(layer "B.Cu")
		(net "UPI_CPU1_CPU0_P0P0_DP<16>")
	)
	(segment
		(start 326.77481 -86.868)
		(end 326.775064 -86.873588)
		(width 0.1143)
		(layer "B.Cu")
		(net "UPI_CPU1_CPU0_P0P0_DP<16>")
	)
	(segment
		(start 217.486992 -122.204226)
		(end 217.486992 -122.204734)
		(width 0.1143)
		(layer "B.Cu")
		(net "UPI_CPU1_CPU0_P0P0_DP<16>")
	)
	(segment
		(start 140.628878 -71.113904)
		(end 140.53947 -71.089774)
		(width 0.0889)
		(layer "B.Cu")
		(net "UPI_CPU1_CPU0_P0P0_DP<16>")
	)
	(segment
		(start 310.693308 -61.693298)
		(end 310.934862 -61.693298)
		(width 0.0889)
		(layer "B.Cu")
		(net "UPI_CPU1_CPU0_P0P0_DP<16>")
	)
	(segment
		(start 163.696904 -113.637314)
		(end 163.474908 -113.432082)
		(width 0.1143)
		(layer "B.Cu")
		(net "UPI_CPU1_CPU0_P0P0_DP<16>")
	)
	(segment
		(start 305.225196 -61.752988)
		(end 305.268376 -61.752988)
		(width 0.0889)
		(layer "B.Cu")
		(net "UPI_CPU1_CPU0_P0P0_DP<16>")
	)
	(segment
		(start 312.066432 -61.667898)
		(end 314.028582 -62.479682)
		(width 0.1143)
		(layer "B.Cu")
		(net "UPI_CPU1_CPU0_P0P0_DP<16>")
	)
	(segment
		(start 163.361624 -113.356898)
		(end 163.18738 -113.241074)
		(width 0.1143)
		(layer "B.Cu")
		(net "UPI_CPU1_CPU0_P0P0_DP<16>")
	)
	(segment
		(start 297.951906 -120.672606)
		(end 293.064184 -121.65076)
		(width 0.1143)
		(layer "B.Cu")
		(net "UPI_CPU1_CPU0_P0P0_DP<16>")
	)
	(segment
		(start 310.053736 -118.732808)
		(end 299.154088 -120.913398)
		(width 0.1143)
		(layer "B.Cu")
		(net "UPI_CPU1_CPU0_P0P0_DP<16>")
	)
	(segment
		(start 226.680014 -120.359424)
		(end 217.486992 -122.204226)
		(width 0.1143)
		(layer "B.Cu")
		(net "UPI_CPU1_CPU0_P0P0_DP<16>")
	)
	(segment
		(start 328.43724 -91.029536)
		(end 328.43724 -91.030044)
		(width 0.1143)
		(layer "B.Cu")
		(net "UPI_CPU1_CPU0_P0P0_DP<16>")
	)
	(segment
		(start 163.474908 -113.432082)
		(end 163.361624 -113.356898)
		(width 0.1143)
		(layer "B.Cu")
		(net "UPI_CPU1_CPU0_P0P0_DP<16>")
	)
	(segment
		(start 156.634434 -111.430562)
		(end 156.564838 -111.403892)
		(width 0.1143)
		(layer "B.Cu")
		(net "UPI_CPU1_CPU0_P0P0_DP<16>")
	)
	(segment
		(start 148.723604 -88.552274)
		(end 146.194018 -75.900788)
		(width 0.1143)
		(layer "B.Cu")
		(net "UPI_CPU1_CPU0_P0P0_DP<16>")
	)
	(segment
		(start 163.18738 -113.241074)
		(end 160.407604 -112.868964)
		(width 0.1143)
		(layer "B.Cu")
		(net "UPI_CPU1_CPU0_P0P0_DP<16>")
	)
	(segment
		(start 329.53579 -93.7768)
		(end 330.134468 -95.273368)
		(width 0.1143)
		(layer "B.Cu")
		(net "UPI_CPU1_CPU0_P0P0_DP<16>")
	)
	(segment
		(start 299.154088 -120.913398)
		(end 297.951906 -120.672606)
		(width 0.1143)
		(layer "B.Cu")
		(net "UPI_CPU1_CPU0_P0P0_DP<16>")
	)
	(segment
		(start 329.869546 -103.58882)
		(end 318.713612 -114.09807)
		(width 0.1143)
		(layer "B.Cu")
		(net "UPI_CPU1_CPU0_P0P0_DP<16>")
	)
	(segment
		(start 182.388002 -120.342152)
		(end 173.777148 -119.801894)
		(width 0.1143)
		(layer "B.Cu")
		(net "UPI_CPU1_CPU0_P0P0_DP<16>")
	)
	(segment
		(start 141.78661 -70.925944)
		(end 141.656562 -71.055992)
		(width 0.0889)
		(layer "B.Cu")
		(net "UPI_CPU1_CPU0_P0P0_DP<16>")
	)
	(segment
		(start 303.822862 -62.512448)
		(end 303.91227 -62.488318)
		(width 0.0889)
		(layer "B.Cu")
		(net "UPI_CPU1_CPU0_P0P0_DP<16>")
	)
	(segment
		(start 263.07161 -119.87911)
		(end 249.397012 -121.49836)
		(width 0.1143)
		(layer "B.Cu")
		(net "UPI_CPU1_CPU0_P0P0_DP<16>")
	)
	(segment
		(start 146.727672 -98.529648)
		(end 148.723604 -88.552274)
		(width 0.1143)
		(layer "B.Cu")
		(net "UPI_CPU1_CPU0_P0P0_DP<16>")
	)
	(segment
		(start 165.46322 -115.682268)
		(end 163.92017 -113.843054)
		(width 0.1143)
		(layer "B.Cu")
		(net "UPI_CPU1_CPU0_P0P0_DP<16>")
	)
	(segment
		(start 330.134468 -95.273368)
		(end 329.869546 -103.58882)
		(width 0.1143)
		(layer "B.Cu")
		(net "UPI_CPU1_CPU0_P0P0_DP<16>")
	)
	(segment
		(start 192.759838 -123.830588)
		(end 182.388002 -120.342152)
		(width 0.1143)
		(layer "B.Cu")
		(net "UPI_CPU1_CPU0_P0P0_DP<16>")
	)
	(segment
		(start 303.529746 -62.343538)
		(end 303.822862 -62.512448)
		(width 0.0889)
		(layer "B.Cu")
		(net "UPI_CPU1_CPU0_P0P0_DP<16>")
	)
	(segment
		(start 291.125402 -121.263156)
		(end 289.656012 -120.969278)
		(width 0.1143)
		(layer "B.Cu")
		(net "UPI_CPU1_CPU0_P0P0_DP<16>")
	)
	(segment
		(start 328.32294 -90.743532)
		(end 328.43724 -91.029536)
		(width 0.1143)
		(layer "B.Cu")
		(net "UPI_CPU1_CPU0_P0P0_DP<16>")
	)
	(segment
		(start 284.315916 -122.037348)
		(end 263.07161 -119.87911)
		(width 0.1143)
		(layer "B.Cu")
		(net "UPI_CPU1_CPU0_P0P0_DP<16>")
	)
	(segment
		(start 249.397012 -121.49836)
		(end 226.680014 -120.359424)
		(width 0.1143)
		(layer "B.Cu")
		(net "UPI_CPU1_CPU0_P0P0_DP<16>")
	)
	(segment
		(start 201.688954 -123.63577)
		(end 198.397368 -124.075952)
		(width 0.1143)
		(layer "B.Cu")
		(net "UPI_CPU1_CPU0_P0P0_DP<16>")
	)
	(segment
		(start 306.10048 -62.248288)
		(end 310.138318 -62.248288)
		(width 0.0889)
		(layer "B.Cu")
		(net "UPI_CPU1_CPU0_P0P0_DP<16>")
	)
	(segment
		(start 141.308074 -71.353934)
		(end 141.083284 -71.353934)
		(width 0.0889)
		(layer "B.Cu")
		(net "UPI_CPU1_CPU0_P0P0_DP<16>")
	)
	(segment
		(start 293.064184 -121.65076)
		(end 291.125402 -121.263156)
		(width 0.1143)
		(layer "B.Cu")
		(net "UPI_CPU1_CPU0_P0P0_DP<16>")
	)
	(segment
		(start 145.061686 -73.522586)
		(end 142.858744 -71.319644)
		(width 0.0889)
		(layer "B.Cu")
		(net "UPI_CPU1_CPU0_P0P0_DP<16>")
	)
	(segment
		(start 156.564838 -111.403892)
		(end 154.185874 -109.792262)
		(width 0.1143)
		(layer "B.Cu")
		(net "UPI_CPU1_CPU0_P0P0_DP<16>")
	)
	(segment
		(start 328.43724 -91.030044)
		(end 329.53579 -93.7768)
		(width 0.1143)
		(layer "B.Cu")
		(net "UPI_CPU1_CPU0_P0P0_DP<16>")
	)
	(segment
		(start 142.858744 -71.319644)
		(end 142.550642 -71.191882)
		(width 0.0889)
		(layer "B.Cu")
		(net "UPI_CPU1_CPU0_P0P0_DP<16>")
	)
	(segment
		(start 142.550642 -71.191882)
		(end 142.217648 -70.858888)
		(width 0.0889)
		(layer "B.Cu")
		(net "UPI_CPU1_CPU0_P0P0_DP<16>")
	)
	(segment
		(start 310.934862 -61.693298)
		(end 310.960262 -61.667898)
		(width 0.0889)
		(layer "B.Cu")
		(net "UPI_CPU1_CPU0_P0P0_DP<16>")
	)
	(segment
		(start 289.656012 -120.969278)
		(end 284.315916 -122.037348)
		(width 0.1143)
		(layer "B.Cu")
		(net "UPI_CPU1_CPU0_P0P0_DP<16>")
	)
	(segment
		(start 145.07718 -73.574148)
		(end 145.061686 -73.558654)
		(width 0.0889)
		(layer "B.Cu")
		(net "UPI_CPU1_CPU0_P0P0_DP<16>")
	)
	(segment
		(start 217.486992 -122.204734)
		(end 208.233772 -124.06122)
		(width 0.1143)
		(layer "B.Cu")
		(net "UPI_CPU1_CPU0_P0P0_DP<16>")
	)
	(segment
		(start 326.59193 -79.8322)
		(end 326.77481 -86.868)
		(width 0.1143)
		(layer "B.Cu")
		(net "UPI_CPU1_CPU0_P0P0_DP<16>")
	)
	(segment
		(start 326.775064 -86.873588)
		(end 328.32294 -90.743532)
		(width 0.1143)
		(layer "B.Cu")
		(net "UPI_CPU1_CPU0_P0P0_DP<16>")
	)
	(segment
		(start 319.872614 -66.32194)
		(end 321.046094 -68.4276)
		(width 0.1143)
		(layer "B.Cu")
		(net "UPI_CPU1_CPU0_P0P0_DP<16>")
	)
	(segment
		(start 171.30649 -119.055896)
		(end 165.46322 -115.682268)
		(width 0.1143)
		(layer "B.Cu")
		(net "UPI_CPU1_CPU0_P0P0_DP<16>")
	)
	(segment
		(start 321.046094 -68.4276)
		(end 326.122284 -77.53604)
		(width 0.1143)
		(layer "B.Cu")
		(net "UPI_CPU1_CPU0_P0P0_DP<16>")
	)
	(segment
		(start 163.697158 -113.637314)
		(end 163.696904 -113.637314)
		(width 0.1143)
		(layer "B.Cu")
		(net "UPI_CPU1_CPU0_P0P0_DP<16>")
	)
	(segment
		(start 304.370486 -62.248034)
		(end 304.403252 -62.248034)
		(width 0.0889)
		(layer "B.Cu")
		(net "UPI_CPU1_CPU0_P0P0_DP<16>")
	)
	(segment
		(start 173.777148 -119.801894)
		(end 171.30649 -119.055896)
		(width 0.1143)
		(layer "B.Cu")
		(net "UPI_CPU1_CPU0_P0P0_DP<16>")
	)
	(segment
		(start 147.827746 -102.079298)
		(end 147.217384 -100.978462)
		(width 0.1143)
		(layer "B.Cu")
		(net "UPI_CPU1_CPU0_P0P0_DP<16>")
	)
	(segment
		(start 146.194018 -75.900788)
		(end 145.32864 -73.825608)
		(width 0.1143)
		(layer "B.Cu")
		(net "UPI_CPU1_CPU0_P0P0_DP<16>")
	)
	(segment
		(start 318.713612 -114.09807)
		(end 310.053736 -118.732808)
		(width 0.1143)
		(layer "B.Cu")
		(net "UPI_CPU1_CPU0_P0P0_DP<16>")
	)
	(segment
		(start 326.122284 -77.53604)
		(end 326.552306 -78.307946)
		(width 0.1143)
		(layer "B.Cu")
		(net "UPI_CPU1_CPU0_P0P0_DP<16>")
	)
	(segment
		(start 310.98236 -61.667898)
		(end 312.066432 -61.667898)
		(width 0.1143)
		(layer "B.Cu")
		(net "UPI_CPU1_CPU0_P0P0_DP<16>")
	)
	(segment
		(start 154.185874 -109.792262)
		(end 147.827746 -102.079298)
		(width 0.1143)
		(layer "B.Cu")
		(net "UPI_CPU1_CPU0_P0P0_DP<16>")
	)
	(segment
		(start 163.92017 -113.843054)
		(end 163.697158 -113.637314)
		(width 0.1143)
		(layer "B.Cu")
		(net "UPI_CPU1_CPU0_P0P0_DP<16>")
	)
	(segment
		(start 156.6926 -111.45266)
		(end 156.634434 -111.430562)
		(width 0.1143)
		(layer "B.Cu")
		(net "UPI_CPU1_CPU0_P0P0_DP<16>")
	)
	(segment
		(start 326.552306 -78.307946)
		(end 326.59193 -79.8322)
		(width 0.1143)
		(layer "B.Cu")
		(net "UPI_CPU1_CPU0_P0P0_DP<16>")
	)
	(segment
		(start 145.32864 -73.825608)
		(end 145.07718 -73.574148)
		(width 0.1143)
		(layer "B.Cu")
		(net "UPI_CPU1_CPU0_P0P0_DP<16>")
	)
	(arc
		(start 303.91227 -62.488318)
		(mid 304.11368 -62.315365)
		(end 304.370486 -62.248034)
		(width 0.0889)
		(layer "B.Cu")
		(net "UPI_CPU1_CPU0_P0P0_DP<16>")
	)
	(arc
		(start 305.268376 -61.752988)
		(mid 305.551593 -61.837269)
		(end 305.758596 -62.048136)
		(width 0.0889)
		(layer "B.Cu")
		(net "UPI_CPU1_CPU0_P0P0_DP<16>")
	)
	(arc
		(start 141.948154 -70.858888)
		(mid 141.860712 -70.876357)
		(end 141.78661 -70.925944)
		(width 0.0889)
		(layer "B.Cu")
		(net "UPI_CPU1_CPU0_P0P0_DP<16>")
	)
	(arc
		(start 304.403252 -62.248034)
		(mid 304.594894 -62.190868)
		(end 304.734976 -62.048136)
		(width 0.0889)
		(layer "B.Cu")
		(net "UPI_CPU1_CPU0_P0P0_DP<16>")
	)
	(arc
		(start 305.758596 -62.048136)
		(mid 305.903044 -62.193467)
		(end 306.10048 -62.248288)
		(width 0.0889)
		(layer "B.Cu")
		(net "UPI_CPU1_CPU0_P0P0_DP<16>")
	)
	(arc
		(start 141.656562 -71.055992)
		(mid 141.510637 -71.238079)
		(end 141.308074 -71.353934)
		(width 0.0889)
		(layer "B.Cu")
		(net "UPI_CPU1_CPU0_P0P0_DP<16>")
	)
	(arc
		(start 141.083284 -71.353934)
		(mid 140.828619 -71.285905)
		(end 140.628878 -71.113904)
		(width 0.0889)
		(layer "B.Cu")
		(net "UPI_CPU1_CPU0_P0P0_DP<16>")
	)
	(arc
		(start 304.734976 -62.048136)
		(mid 304.94198 -61.837272)
		(end 305.225196 -61.752988)
		(width 0.0889)
		(layer "B.Cu")
		(net "UPI_CPU1_CPU0_P0P0_DP<16>")
	)
	(segment
		(start 138.816334 -69.772784)
		(end 139.387834 -69.772784)
		(width 0.1143)
		(layer "F.Cu")
		(net "UPI_CPU1_CPU0_P0P0_DP<15>")
	)
	(segment
		(start 303.529746 -64.324738)
		(end 302.958246 -64.324738)
		(width 0.1143)
		(layer "F.Cu")
		(net "UPI_CPU1_CPU0_P0P0_DP<15>")
	)
	(via
		(at 303.529746 -64.324738)
		(size 0.508)
		(drill 0.254)
		(layers "F.Cu" "B.Cu")
		(net "UPI_CPU1_CPU0_P0P0_DP<15>")
	)
	(via
		(at 139.387834 -69.772784)
		(size 0.508)
		(drill 0.254)
		(layers "F.Cu" "B.Cu")
		(net "UPI_CPU1_CPU0_P0P0_DP<15>")
	)
	(segment
		(start 174.007526 -118.605046)
		(end 182.622444 -119.145304)
		(width 0.1143)
		(layer "B.Cu")
		(net "UPI_CPU1_CPU0_P0P0_DP<15>")
	)
	(segment
		(start 161.912554 -111.850678)
		(end 162.277552 -111.899192)
		(width 0.1143)
		(layer "B.Cu")
		(net "UPI_CPU1_CPU0_P0P0_DP<15>")
	)
	(segment
		(start 148.537676 -96.222566)
		(end 148.537676 -96.22282)
		(width 0.1143)
		(layer "B.Cu")
		(net "UPI_CPU1_CPU0_P0P0_DP<15>")
	)
	(segment
		(start 141.093698 -70.172834)
		(end 141.104874 -70.172834)
		(width 0.0889)
		(layer "B.Cu")
		(net "UPI_CPU1_CPU0_P0P0_DP<15>")
	)
	(segment
		(start 148.677376 -95.524066)
		(end 148.776944 -95.673672)
		(width 0.1143)
		(layer "B.Cu")
		(net "UPI_CPU1_CPU0_P0P0_DP<15>")
	)
	(segment
		(start 161.434018 -111.78667)
		(end 161.576766 -111.67745)
		(width 0.1143)
		(layer "B.Cu")
		(net "UPI_CPU1_CPU0_P0P0_DP<15>")
	)
	(segment
		(start 143.525494 -70.485)
		(end 146.310604 -73.27011)
		(width 0.0889)
		(layer "B.Cu")
		(net "UPI_CPU1_CPU0_P0P0_DP<15>")
	)
	(segment
		(start 159.232092 -110.96879)
		(end 159.306768 -111.132366)
		(width 0.1143)
		(layer "B.Cu")
		(net "UPI_CPU1_CPU0_P0P0_DP<15>")
	)
	(segment
		(start 139.617704 -69.677534)
		(end 140.267944 -69.677534)
		(width 0.0889)
		(layer "B.Cu")
		(net "UPI_CPU1_CPU0_P0P0_DP<15>")
	)
	(segment
		(start 300.070012 -119.478044)
		(end 309.677562 -117.556788)
		(width 0.1143)
		(layer "B.Cu")
		(net "UPI_CPU1_CPU0_P0P0_DP<15>")
	)
	(segment
		(start 309.677562 -117.556788)
		(end 316.203076 -114.06505)
		(width 0.1143)
		(layer "B.Cu")
		(net "UPI_CPU1_CPU0_P0P0_DP<15>")
	)
	(segment
		(start 325.200264 -78.648052)
		(end 325.132192 -78.526132)
		(width 0.1143)
		(layer "B.Cu")
		(net "UPI_CPU1_CPU0_P0P0_DP<15>")
	)
	(segment
		(start 166.084504 -114.340132)
		(end 166.370508 -114.681)
		(width 0.1143)
		(layer "B.Cu")
		(net "UPI_CPU1_CPU0_P0P0_DP<15>")
	)
	(segment
		(start 148.86178 -94.602554)
		(end 148.817076 -94.826582)
		(width 0.1143)
		(layer "B.Cu")
		(net "UPI_CPU1_CPU0_P0P0_DP<15>")
	)
	(segment
		(start 162.4203 -111.790226)
		(end 162.647122 -111.820452)
		(width 0.1143)
		(layer "B.Cu")
		(net "UPI_CPU1_CPU0_P0P0_DP<15>")
	)
	(segment
		(start 158.85414 -110.96371)
		(end 159.017462 -110.889034)
		(width 0.1143)
		(layer "B.Cu")
		(net "UPI_CPU1_CPU0_P0P0_DP<15>")
	)
	(segment
		(start 328.764392 -95.513398)
		(end 327.275444 -91.791028)
		(width 0.1143)
		(layer "B.Cu")
		(net "UPI_CPU1_CPU0_P0P0_DP<15>")
	)
	(segment
		(start 148.817076 -94.826582)
		(end 148.916644 -94.975934)
		(width 0.1143)
		(layer "B.Cu")
		(net "UPI_CPU1_CPU0_P0P0_DP<15>")
	)
	(segment
		(start 161.576766 -111.67745)
		(end 161.803588 -111.707676)
		(width 0.1143)
		(layer "B.Cu")
		(net "UPI_CPU1_CPU0_P0P0_DP<15>")
	)
	(segment
		(start 291.125402 -120.232932)
		(end 292.459664 -120.50014)
		(width 0.1143)
		(layer "B.Cu")
		(net "UPI_CPU1_CPU0_P0P0_DP<15>")
	)
	(segment
		(start 327.09231 -91.33332)
		(end 327.090786 -91.328748)
		(width 0.1143)
		(layer "B.Cu")
		(net "UPI_CPU1_CPU0_P0P0_DP<15>")
	)
	(segment
		(start 148.72208 -95.300038)
		(end 148.677376 -95.524066)
		(width 0.1143)
		(layer "B.Cu")
		(net "UPI_CPU1_CPU0_P0P0_DP<15>")
	)
	(segment
		(start 148.776944 -95.673672)
		(end 148.73224 -95.897954)
		(width 0.1143)
		(layer "B.Cu")
		(net "UPI_CPU1_CPU0_P0P0_DP<15>")
	)
	(segment
		(start 142.484094 -69.977)
		(end 142.903702 -70.396608)
		(width 0.0889)
		(layer "B.Cu")
		(net "UPI_CPU1_CPU0_P0P0_DP<15>")
	)
	(segment
		(start 249.268742 -120.280938)
		(end 263.070086 -118.663212)
		(width 0.1143)
		(layer "B.Cu")
		(net "UPI_CPU1_CPU0_P0P0_DP<15>")
	)
	(segment
		(start 148.756624 -101.261672)
		(end 155.091892 -108.946696)
		(width 0.1143)
		(layer "B.Cu")
		(net "UPI_CPU1_CPU0_P0P0_DP<15>")
	)
	(segment
		(start 141.503146 -70.053962)
		(end 141.580108 -69.977)
		(width 0.0889)
		(layer "B.Cu")
		(net "UPI_CPU1_CPU0_P0P0_DP<15>")
	)
	(segment
		(start 328.524108 -103.047038)
		(end 328.764392 -95.513398)
		(width 0.1143)
		(layer "B.Cu")
		(net "UPI_CPU1_CPU0_P0P0_DP<15>")
	)
	(segment
		(start 284.14599 -120.803924)
		(end 289.065208 -119.820182)
		(width 0.1143)
		(layer "B.Cu")
		(net "UPI_CPU1_CPU0_P0P0_DP<15>")
	)
	(segment
		(start 303.595024 -63.921386)
		(end 303.529746 -63.986664)
		(width 0.0889)
		(layer "B.Cu")
		(net "UPI_CPU1_CPU0_P0P0_DP<15>")
	)
	(segment
		(start 149.108414 -93.368114)
		(end 149.095968 -93.431614)
		(width 0.1143)
		(layer "B.Cu")
		(net "UPI_CPU1_CPU0_P0P0_DP<15>")
	)
	(segment
		(start 316.203076 -114.06505)
		(end 318.1985 -112.184942)
		(width 0.1143)
		(layer "B.Cu")
		(net "UPI_CPU1_CPU0_P0P0_DP<15>")
	)
	(segment
		(start 165.114224 -113.184178)
		(end 165.773862 -113.970308)
		(width 0.1143)
		(layer "B.Cu")
		(net "UPI_CPU1_CPU0_P0P0_DP<15>")
	)
	(segment
		(start 325.421752 -87.156798)
		(end 325.285354 -81.915)
		(width 0.1143)
		(layer "B.Cu")
		(net "UPI_CPU1_CPU0_P0P0_DP<15>")
	)
	(segment
		(start 292.459664 -120.50014)
		(end 298.817792 -119.2276)
		(width 0.1143)
		(layer "B.Cu")
		(net "UPI_CPU1_CPU0_P0P0_DP<15>")
	)
	(segment
		(start 318.1985 -112.184942)
		(end 318.243204 -112.142778)
		(width 0.1143)
		(layer "B.Cu")
		(net "UPI_CPU1_CPU0_P0P0_DP<15>")
	)
	(segment
		(start 327.275444 -91.791028)
		(end 327.09485 -91.33967)
		(width 0.1143)
		(layer "B.Cu")
		(net "UPI_CPU1_CPU0_P0P0_DP<15>")
	)
	(segment
		(start 142.903702 -70.396608)
		(end 143.117062 -70.485)
		(width 0.0889)
		(layer "B.Cu")
		(net "UPI_CPU1_CPU0_P0P0_DP<15>")
	)
	(segment
		(start 148.560282 -100.907342)
		(end 148.756624 -101.261672)
		(width 0.1143)
		(layer "B.Cu")
		(net "UPI_CPU1_CPU0_P0P0_DP<15>")
	)
	(segment
		(start 146.536664 -73.460864)
		(end 146.53641 -73.460864)
		(width 0.1143)
		(layer "B.Cu")
		(net "UPI_CPU1_CPU0_P0P0_DP<15>")
	)
	(segment
		(start 149.056344 -94.27845)
		(end 149.011386 -94.502986)
		(width 0.1143)
		(layer "B.Cu")
		(net "UPI_CPU1_CPU0_P0P0_DP<15>")
	)
	(segment
		(start 304.409856 -63.429134)
		(end 304.37709 -63.429134)
		(width 0.0889)
		(layer "B.Cu")
		(net "UPI_CPU1_CPU0_P0P0_DP<15>")
	)
	(segment
		(start 159.142684 -110.935516)
		(end 159.232092 -110.96879)
		(width 0.1143)
		(layer "B.Cu")
		(net "UPI_CPU1_CPU0_P0P0_DP<15>")
	)
	(segment
		(start 310.648858 -63.00089)
		(end 310.448706 -63.201042)
		(width 0.0889)
		(layer "B.Cu")
		(net "UPI_CPU1_CPU0_P0P0_DP<15>")
	)
	(segment
		(start 148.871686 -95.20047)
		(end 148.72208 -95.300038)
		(width 0.1143)
		(layer "B.Cu")
		(net "UPI_CPU1_CPU0_P0P0_DP<15>")
	)
	(segment
		(start 263.070086 -118.663212)
		(end 284.14599 -120.803924)
		(width 0.1143)
		(layer "B.Cu")
		(net "UPI_CPU1_CPU0_P0P0_DP<15>")
	)
	(segment
		(start 310.448706 -63.201042)
		(end 307.500782 -63.201042)
		(width 0.0889)
		(layer "B.Cu")
		(net "UPI_CPU1_CPU0_P0P0_DP<15>")
	)
	(segment
		(start 160.861502 -111.710216)
		(end 161.434018 -111.78667)
		(width 0.1143)
		(layer "B.Cu")
		(net "UPI_CPU1_CPU0_P0P0_DP<15>")
	)
	(segment
		(start 149.011386 -94.502986)
		(end 148.86178 -94.602554)
		(width 0.1143)
		(layer "B.Cu")
		(net "UPI_CPU1_CPU0_P0P0_DP<15>")
	)
	(segment
		(start 149.001226 -93.90507)
		(end 148.956522 -94.129098)
		(width 0.1143)
		(layer "B.Cu")
		(net "UPI_CPU1_CPU0_P0P0_DP<15>")
	)
	(segment
		(start 325.132192 -78.526132)
		(end 318.872616 -67.294506)
		(width 0.1143)
		(layer "B.Cu")
		(net "UPI_CPU1_CPU0_P0P0_DP<15>")
	)
	(segment
		(start 149.19579 -93.580966)
		(end 149.150832 -93.805502)
		(width 0.1143)
		(layer "B.Cu")
		(net "UPI_CPU1_CPU0_P0P0_DP<15>")
	)
	(segment
		(start 149.150832 -93.805502)
		(end 149.001226 -93.90507)
		(width 0.1143)
		(layer "B.Cu")
		(net "UPI_CPU1_CPU0_P0P0_DP<15>")
	)
	(segment
		(start 146.34591 -73.27011)
		(end 146.536664 -73.460864)
		(width 0.1143)
		(layer "B.Cu")
		(net "UPI_CPU1_CPU0_P0P0_DP<15>")
	)
	(segment
		(start 311.101232 -63.00089)
		(end 310.648858 -63.00089)
		(width 0.0889)
		(layer "B.Cu")
		(net "UPI_CPU1_CPU0_P0P0_DP<15>")
	)
	(segment
		(start 148.956522 -94.129098)
		(end 149.056344 -94.27845)
		(width 0.1143)
		(layer "B.Cu")
		(net "UPI_CPU1_CPU0_P0P0_DP<15>")
	)
	(segment
		(start 148.582634 -95.997776)
		(end 148.537676 -96.222566)
		(width 0.1143)
		(layer "B.Cu")
		(net "UPI_CPU1_CPU0_P0P0_DP<15>")
	)
	(segment
		(start 182.622444 -119.145304)
		(end 192.984374 -122.630184)
		(width 0.1143)
		(layer "B.Cu")
		(net "UPI_CPU1_CPU0_P0P0_DP<15>")
	)
	(segment
		(start 159.306768 -111.132366)
		(end 159.712406 -111.282988)
		(width 0.1143)
		(layer "B.Cu")
		(net "UPI_CPU1_CPU0_P0P0_DP<15>")
	)
	(segment
		(start 311.126632 -63.02629)
		(end 311.101232 -63.00089)
		(width 0.0889)
		(layer "B.Cu")
		(net "UPI_CPU1_CPU0_P0P0_DP<15>")
	)
	(segment
		(start 162.756088 -111.963454)
		(end 163.742116 -112.095026)
		(width 0.1143)
		(layer "B.Cu")
		(net "UPI_CPU1_CPU0_P0P0_DP<15>")
	)
	(segment
		(start 311.787032 -63.02629)
		(end 311.14873 -63.02629)
		(width 0.1143)
		(layer "B.Cu")
		(net "UPI_CPU1_CPU0_P0P0_DP<15>")
	)
	(segment
		(start 166.581074 -114.931698)
		(end 171.777914 -117.931946)
		(width 0.1143)
		(layer "B.Cu")
		(net "UPI_CPU1_CPU0_P0P0_DP<15>")
	)
	(segment
		(start 171.777914 -117.931946)
		(end 174.007526 -118.605046)
		(width 0.1143)
		(layer "B.Cu")
		(net "UPI_CPU1_CPU0_P0P0_DP<15>")
	)
	(segment
		(start 327.09485 -91.33967)
		(end 327.094088 -91.337892)
		(width 0.1143)
		(layer "B.Cu")
		(net "UPI_CPU1_CPU0_P0P0_DP<15>")
	)
	(segment
		(start 148.73224 -95.897954)
		(end 148.582634 -95.997776)
		(width 0.1143)
		(layer "B.Cu")
		(net "UPI_CPU1_CPU0_P0P0_DP<15>")
	)
	(segment
		(start 307.500782 -63.201042)
		(end 307.233828 -62.934088)
		(width 0.0889)
		(layer "B.Cu")
		(net "UPI_CPU1_CPU0_P0P0_DP<15>")
	)
	(segment
		(start 166.099998 -114.161062)
		(end 166.084504 -114.340132)
		(width 0.1143)
		(layer "B.Cu")
		(net "UPI_CPU1_CPU0_P0P0_DP<15>")
	)
	(segment
		(start 160.165034 -111.45139)
		(end 160.861502 -111.710216)
		(width 0.1143)
		(layer "B.Cu")
		(net "UPI_CPU1_CPU0_P0P0_DP<15>")
	)
	(segment
		(start 192.984374 -122.630184)
		(end 198.34098 -122.86361)
		(width 0.1143)
		(layer "B.Cu")
		(net "UPI_CPU1_CPU0_P0P0_DP<15>")
	)
	(segment
		(start 327.093072 -91.335352)
		(end 327.09231 -91.33332)
		(width 0.1143)
		(layer "B.Cu")
		(net "UPI_CPU1_CPU0_P0P0_DP<15>")
	)
	(segment
		(start 148.916644 -94.975934)
		(end 148.871686 -95.20047)
		(width 0.1143)
		(layer "B.Cu")
		(net "UPI_CPU1_CPU0_P0P0_DP<15>")
	)
	(segment
		(start 159.017462 -110.889034)
		(end 159.110172 -110.923324)
		(width 0.1143)
		(layer "B.Cu")
		(net "UPI_CPU1_CPU0_P0P0_DP<15>")
	)
	(segment
		(start 318.872616 -67.294506)
		(end 313.399424 -63.69558)
		(width 0.1143)
		(layer "B.Cu")
		(net "UPI_CPU1_CPU0_P0P0_DP<15>")
	)
	(segment
		(start 289.065208 -119.820182)
		(end 291.125402 -120.232932)
		(width 0.1143)
		(layer "B.Cu")
		(net "UPI_CPU1_CPU0_P0P0_DP<15>")
	)
	(segment
		(start 208.157572 -122.843544)
		(end 226.58197 -119.143526)
		(width 0.1143)
		(layer "B.Cu")
		(net "UPI_CPU1_CPU0_P0P0_DP<15>")
	)
	(segment
		(start 303.529746 -63.986664)
		(end 303.529746 -64.324738)
		(width 0.0889)
		(layer "B.Cu")
		(net "UPI_CPU1_CPU0_P0P0_DP<15>")
	)
	(segment
		(start 141.580108 -69.977)
		(end 142.484094 -69.977)
		(width 0.0889)
		(layer "B.Cu")
		(net "UPI_CPU1_CPU0_P0P0_DP<15>")
	)
	(segment
		(start 155.091892 -108.946696)
		(end 157.286452 -110.381034)
		(width 0.1143)
		(layer "B.Cu")
		(net "UPI_CPU1_CPU0_P0P0_DP<15>")
	)
	(segment
		(start 148.537676 -96.22282)
		(end 148.080476 -98.50882)
		(width 0.1143)
		(layer "B.Cu")
		(net "UPI_CPU1_CPU0_P0P0_DP<15>")
	)
	(segment
		(start 162.647122 -111.820452)
		(end 162.756088 -111.963454)
		(width 0.1143)
		(layer "B.Cu")
		(net "UPI_CPU1_CPU0_P0P0_DP<15>")
	)
	(segment
		(start 162.277552 -111.899192)
		(end 162.4203 -111.790226)
		(width 0.1143)
		(layer "B.Cu")
		(net "UPI_CPU1_CPU0_P0P0_DP<15>")
	)
	(segment
		(start 325.285354 -81.915)
		(end 325.200264 -78.648052)
		(width 0.1143)
		(layer "B.Cu")
		(net "UPI_CPU1_CPU0_P0P0_DP<15>")
	)
	(segment
		(start 159.110172 -110.923324)
		(end 159.142684 -110.935516)
		(width 0.1143)
		(layer "B.Cu")
		(net "UPI_CPU1_CPU0_P0P0_DP<15>")
	)
	(segment
		(start 149.095968 -93.431614)
		(end 149.19579 -93.580966)
		(width 0.1143)
		(layer "B.Cu")
		(net "UPI_CPU1_CPU0_P0P0_DP<15>")
	)
	(segment
		(start 146.310604 -73.27011)
		(end 146.34591 -73.27011)
		(width 0.0889)
		(layer "B.Cu")
		(net "UPI_CPU1_CPU0_P0P0_DP<15>")
	)
	(segment
		(start 159.875728 -111.208312)
		(end 160.090358 -111.287814)
		(width 0.1143)
		(layer "B.Cu")
		(net "UPI_CPU1_CPU0_P0P0_DP<15>")
	)
	(segment
		(start 307.233828 -62.934088)
		(end 305.2318 -62.934088)
		(width 0.0889)
		(layer "B.Cu")
		(net "UPI_CPU1_CPU0_P0P0_DP<15>")
	)
	(segment
		(start 161.803588 -111.707676)
		(end 161.912554 -111.850678)
		(width 0.1143)
		(layer "B.Cu")
		(net "UPI_CPU1_CPU0_P0P0_DP<15>")
	)
	(segment
		(start 148.080476 -98.50882)
		(end 148.560282 -100.907342)
		(width 0.1143)
		(layer "B.Cu")
		(net "UPI_CPU1_CPU0_P0P0_DP<15>")
	)
	(segment
		(start 165.773862 -113.970308)
		(end 165.953186 -113.985802)
		(width 0.1143)
		(layer "B.Cu")
		(net "UPI_CPU1_CPU0_P0P0_DP<15>")
	)
	(segment
		(start 143.117062 -70.485)
		(end 143.525494 -70.485)
		(width 0.0889)
		(layer "B.Cu")
		(net "UPI_CPU1_CPU0_P0P0_DP<15>")
	)
	(segment
		(start 298.817792 -119.2276)
		(end 300.070012 -119.478044)
		(width 0.1143)
		(layer "B.Cu")
		(net "UPI_CPU1_CPU0_P0P0_DP<15>")
	)
	(segment
		(start 318.243204 -112.142778)
		(end 319.101216 -111.923068)
		(width 0.1143)
		(layer "B.Cu")
		(net "UPI_CPU1_CPU0_P0P0_DP<15>")
	)
	(segment
		(start 160.090358 -111.287814)
		(end 160.165034 -111.45139)
		(width 0.1143)
		(layer "B.Cu")
		(net "UPI_CPU1_CPU0_P0P0_DP<15>")
	)
	(segment
		(start 311.14873 -63.02629)
		(end 311.126632 -63.02629)
		(width 0.0889)
		(layer "B.Cu")
		(net "UPI_CPU1_CPU0_P0P0_DP<15>")
	)
	(segment
		(start 165.953186 -113.985802)
		(end 166.099998 -114.161062)
		(width 0.1143)
		(layer "B.Cu")
		(net "UPI_CPU1_CPU0_P0P0_DP<15>")
	)
	(segment
		(start 146.53641 -73.460864)
		(end 146.77898 -73.70318)
		(width 0.1143)
		(layer "B.Cu")
		(net "UPI_CPU1_CPU0_P0P0_DP<15>")
	)
	(segment
		(start 319.101216 -111.923068)
		(end 328.524108 -103.047038)
		(width 0.1143)
		(layer "B.Cu")
		(net "UPI_CPU1_CPU0_P0P0_DP<15>")
	)
	(segment
		(start 149.90953 -89.362026)
		(end 149.108414 -93.368114)
		(width 0.1143)
		(layer "B.Cu")
		(net "UPI_CPU1_CPU0_P0P0_DP<15>")
	)
	(segment
		(start 198.34098 -122.86361)
		(end 201.644758 -122.421904)
		(width 0.1143)
		(layer "B.Cu")
		(net "UPI_CPU1_CPU0_P0P0_DP<15>")
	)
	(segment
		(start 146.77898 -73.70318)
		(end 149.90953 -89.362026)
		(width 0.1143)
		(layer "B.Cu")
		(net "UPI_CPU1_CPU0_P0P0_DP<15>")
	)
	(segment
		(start 201.644758 -122.421904)
		(end 208.157572 -122.843544)
		(width 0.1143)
		(layer "B.Cu")
		(net "UPI_CPU1_CPU0_P0P0_DP<15>")
	)
	(segment
		(start 327.090786 -91.328748)
		(end 325.421752 -87.156798)
		(width 0.1143)
		(layer "B.Cu")
		(net "UPI_CPU1_CPU0_P0P0_DP<15>")
	)
	(segment
		(start 159.712406 -111.282988)
		(end 159.875728 -111.208312)
		(width 0.1143)
		(layer "B.Cu")
		(net "UPI_CPU1_CPU0_P0P0_DP<15>")
	)
	(segment
		(start 226.58197 -119.143526)
		(end 249.268742 -120.280938)
		(width 0.1143)
		(layer "B.Cu")
		(net "UPI_CPU1_CPU0_P0P0_DP<15>")
	)
	(segment
		(start 157.286452 -110.381034)
		(end 158.85414 -110.96371)
		(width 0.1143)
		(layer "B.Cu")
		(net "UPI_CPU1_CPU0_P0P0_DP<15>")
	)
	(segment
		(start 313.399424 -63.69558)
		(end 311.787032 -63.02629)
		(width 0.1143)
		(layer "B.Cu")
		(net "UPI_CPU1_CPU0_P0P0_DP<15>")
	)
	(segment
		(start 163.742116 -112.095026)
		(end 165.114224 -113.184178)
		(width 0.1143)
		(layer "B.Cu")
		(net "UPI_CPU1_CPU0_P0P0_DP<15>")
	)
	(segment
		(start 327.094088 -91.337892)
		(end 327.093072 -91.335352)
		(width 0.1143)
		(layer "B.Cu")
		(net "UPI_CPU1_CPU0_P0P0_DP<15>")
	)
	(segment
		(start 166.370508 -114.681)
		(end 166.581074 -114.931698)
		(width 0.1143)
		(layer "B.Cu")
		(net "UPI_CPU1_CPU0_P0P0_DP<15>")
	)
	(arc
		(start 141.104874 -70.172834)
		(mid 141.312698 -70.142494)
		(end 141.503146 -70.053962)
		(width 0.0889)
		(layer "B.Cu")
		(net "UPI_CPU1_CPU0_P0P0_DP<15>")
	)
	(arc
		(start 304.041556 -63.629286)
		(mid 303.853133 -63.82859)
		(end 303.595024 -63.921386)
		(width 0.0889)
		(layer "B.Cu")
		(net "UPI_CPU1_CPU0_P0P0_DP<15>")
	)
	(arc
		(start 139.387834 -69.772784)
		(mid 139.493299 -69.702314)
		(end 139.617704 -69.677534)
		(width 0.0889)
		(layer "B.Cu")
		(net "UPI_CPU1_CPU0_P0P0_DP<15>")
	)
	(arc
		(start 304.900076 -63.133986)
		(mid 304.693072 -63.34485)
		(end 304.409856 -63.429134)
		(width 0.0889)
		(layer "B.Cu")
		(net "UPI_CPU1_CPU0_P0P0_DP<15>")
	)
	(arc
		(start 305.2318 -62.934088)
		(mid 305.040158 -62.991254)
		(end 304.900076 -63.133986)
		(width 0.0889)
		(layer "B.Cu")
		(net "UPI_CPU1_CPU0_P0P0_DP<15>")
	)
	(arc
		(start 304.37709 -63.429134)
		(mid 304.18324 -63.485484)
		(end 304.041556 -63.629286)
		(width 0.0889)
		(layer "B.Cu")
		(net "UPI_CPU1_CPU0_P0P0_DP<15>")
	)
	(arc
		(start 140.758164 -69.972682)
		(mid 140.899847 -70.116486)
		(end 141.093698 -70.172834)
		(width 0.0889)
		(layer "B.Cu")
		(net "UPI_CPU1_CPU0_P0P0_DP<15>")
	)
	(arc
		(start 140.267944 -69.677534)
		(mid 140.551161 -69.761815)
		(end 140.758164 -69.972682)
		(width 0.0889)
		(layer "B.Cu")
		(net "UPI_CPU1_CPU0_P0P0_DP<15>")
	)
	(segment
		(start 302.099726 -63.829184)
		(end 302.671226 -63.829184)
		(width 0.1143)
		(layer "F.Cu")
		(net "UPI_CPU1_CPU0_P0P0_DP<14>")
	)
	(segment
		(start 139.674854 -69.277738)
		(end 140.246354 -69.277738)
		(width 0.1143)
		(layer "F.Cu")
		(net "UPI_CPU1_CPU0_P0P0_DP<14>")
	)
	(via
		(at 149.694646 -85.27542)
		(size 0.508)
		(drill 0.254)
		(layers "F.Cu" "B.Cu")
		(net "UPI_CPU1_CPU0_P0P0_DP<14>")
	)
	(via
		(at 302.671226 -63.829184)
		(size 0.508)
		(drill 0.254)
		(layers "F.Cu" "B.Cu")
		(net "UPI_CPU1_CPU0_P0P0_DP<14>")
	)
	(via
		(at 140.246354 -69.277738)
		(size 0.508)
		(drill 0.254)
		(layers "F.Cu" "B.Cu")
		(net "UPI_CPU1_CPU0_P0P0_DP<14>")
	)
	(segment
		(start 304.403252 -64.229234)
		(end 304.370486 -64.229234)
		(width 0.0889)
		(layer "B.Cu")
		(net "UPI_CPU1_CPU0_P0P0_DP<14>")
	)
	(segment
		(start 193.2178 -121.91365)
		(end 198.334884 -122.131836)
		(width 0.1143)
		(layer "B.Cu")
		(net "UPI_CPU1_CPU0_P0P0_DP<14>")
	)
	(segment
		(start 182.762652 -118.42623)
		(end 193.118486 -121.909332)
		(width 0.1143)
		(layer "B.Cu")
		(net "UPI_CPU1_CPU0_P0P0_DP<14>")
	)
	(segment
		(start 310.3626 -63.926974)
		(end 310.261 -63.825374)
		(width 0.0889)
		(layer "B.Cu")
		(net "UPI_CPU1_CPU0_P0P0_DP<14>")
	)
	(segment
		(start 309.414672 -116.856764)
		(end 315.754004 -113.463578)
		(width 0.1143)
		(layer "B.Cu")
		(net "UPI_CPU1_CPU0_P0P0_DP<14>")
	)
	(segment
		(start 142.141194 -68.877688)
		(end 141.945868 -68.877688)
		(width 0.0889)
		(layer "B.Cu")
		(net "UPI_CPU1_CPU0_P0P0_DP<14>")
	)
	(segment
		(start 198.334884 -122.131836)
		(end 201.623422 -121.690892)
		(width 0.1143)
		(layer "B.Cu")
		(net "UPI_CPU1_CPU0_P0P0_DP<14>")
	)
	(segment
		(start 288.244026 -119.214646)
		(end 288.473388 -119.168672)
		(width 0.1143)
		(layer "B.Cu")
		(net "UPI_CPU1_CPU0_P0P0_DP<14>")
	)
	(segment
		(start 307.217318 -64.724788)
		(end 306.95265 -64.724788)
		(width 0.0889)
		(layer "B.Cu")
		(net "UPI_CPU1_CPU0_P0P0_DP<14>")
	)
	(segment
		(start 305.257962 -63.734188)
		(end 305.225196 -63.734188)
		(width 0.0889)
		(layer "B.Cu")
		(net "UPI_CPU1_CPU0_P0P0_DP<14>")
	)
	(segment
		(start 149.36978 -100.790756)
		(end 155.714446 -108.487718)
		(width 0.1143)
		(layer "B.Cu")
		(net "UPI_CPU1_CPU0_P0P0_DP<14>")
	)
	(segment
		(start 327.8124 -95.500698)
		(end 324.550024 -87.343234)
		(width 0.1143)
		(layer "B.Cu")
		(net "UPI_CPU1_CPU0_P0P0_DP<14>")
	)
	(segment
		(start 145.7325 -71.9201)
		(end 143.4846 -69.6722)
		(width 0.0889)
		(layer "B.Cu")
		(net "UPI_CPU1_CPU0_P0P0_DP<14>")
	)
	(segment
		(start 155.714446 -108.487718)
		(end 158.36138 -110.0074)
		(width 0.1143)
		(layer "B.Cu")
		(net "UPI_CPU1_CPU0_P0P0_DP<14>")
	)
	(segment
		(start 310.261 -63.825374)
		(end 310.08828 -63.825374)
		(width 0.0889)
		(layer "B.Cu")
		(net "UPI_CPU1_CPU0_P0P0_DP<14>")
	)
	(segment
		(start 172.054774 -117.253766)
		(end 174.149258 -117.885972)
		(width 0.1143)
		(layer "B.Cu")
		(net "UPI_CPU1_CPU0_P0P0_DP<14>")
	)
	(segment
		(start 162.761168 -110.469934)
		(end 166.293038 -113.037366)
		(width 0.1143)
		(layer "B.Cu")
		(net "UPI_CPU1_CPU0_P0P0_DP<14>")
	)
	(segment
		(start 145.9992 -71.95185)
		(end 145.96745 -71.9201)
		(width 0.0889)
		(layer "B.Cu")
		(net "UPI_CPU1_CPU0_P0P0_DP<14>")
	)
	(segment
		(start 324.33006 -78.869286)
		(end 318.22898 -67.923156)
		(width 0.1143)
		(layer "B.Cu")
		(net "UPI_CPU1_CPU0_P0P0_DP<14>")
	)
	(segment
		(start 142.935706 -69.6722)
		(end 142.141194 -68.877688)
		(width 0.0889)
		(layer "B.Cu")
		(net "UPI_CPU1_CPU0_P0P0_DP<14>")
	)
	(segment
		(start 310.6928 -63.901574)
		(end 310.6674 -63.926974)
		(width 0.0889)
		(layer "B.Cu")
		(net "UPI_CPU1_CPU0_P0P0_DP<14>")
	)
	(segment
		(start 193.118486 -121.909332)
		(end 193.2178 -121.91365)
		(width 0.1143)
		(layer "B.Cu")
		(net "UPI_CPU1_CPU0_P0P0_DP<14>")
	)
	(segment
		(start 309.14848 -63.825374)
		(end 309.04688 -63.926974)
		(width 0.0889)
		(layer "B.Cu")
		(net "UPI_CPU1_CPU0_P0P0_DP<14>")
	)
	(segment
		(start 166.293038 -113.037366)
		(end 167.739822 -114.762788)
		(width 0.1143)
		(layer "B.Cu")
		(net "UPI_CPU1_CPU0_P0P0_DP<14>")
	)
	(segment
		(start 310.08828 -63.825374)
		(end 309.98668 -63.926974)
		(width 0.0889)
		(layer "B.Cu")
		(net "UPI_CPU1_CPU0_P0P0_DP<14>")
	)
	(segment
		(start 308.675532 -63.926974)
		(end 308.353206 -64.2493)
		(width 0.0889)
		(layer "B.Cu")
		(net "UPI_CPU1_CPU0_P0P0_DP<14>")
	)
	(segment
		(start 309.3974 -63.926974)
		(end 309.2958 -63.825374)
		(width 0.0889)
		(layer "B.Cu")
		(net "UPI_CPU1_CPU0_P0P0_DP<14>")
	)
	(segment
		(start 288.473388 -119.168672)
		(end 291.125402 -119.699024)
		(width 0.1143)
		(layer "B.Cu")
		(net "UPI_CPU1_CPU0_P0P0_DP<14>")
	)
	(segment
		(start 140.246354 -68.939664)
		(end 140.246354 -69.277738)
		(width 0.0889)
		(layer "B.Cu")
		(net "UPI_CPU1_CPU0_P0P0_DP<14>")
	)
	(segment
		(start 146.39925 -71.95185)
		(end 145.9992 -71.95185)
		(width 0.1143)
		(layer "B.Cu")
		(net "UPI_CPU1_CPU0_P0P0_DP<14>")
	)
	(segment
		(start 318.664336 -111.186976)
		(end 327.655682 -102.714298)
		(width 0.1143)
		(layer "B.Cu")
		(net "UPI_CPU1_CPU0_P0P0_DP<14>")
	)
	(segment
		(start 307.692806 -64.2493)
		(end 307.217318 -64.724788)
		(width 0.0889)
		(layer "B.Cu")
		(net "UPI_CPU1_CPU0_P0P0_DP<14>")
	)
	(segment
		(start 318.22898 -67.923156)
		(end 313.103006 -64.552576)
		(width 0.1143)
		(layer "B.Cu")
		(net "UPI_CPU1_CPU0_P0P0_DP<14>")
	)
	(segment
		(start 148.938742 -98.636836)
		(end 149.36978 -100.790756)
		(width 0.1143)
		(layer "B.Cu")
		(net "UPI_CPU1_CPU0_P0P0_DP<14>")
	)
	(segment
		(start 299.015658 -118.639336)
		(end 299.764704 -118.786656)
		(width 0.1143)
		(layer "B.Cu")
		(net "UPI_CPU1_CPU0_P0P0_DP<14>")
	)
	(segment
		(start 150.652988 -90.06713)
		(end 148.938742 -98.636836)
		(width 0.1143)
		(layer "B.Cu")
		(net "UPI_CPU1_CPU0_P0P0_DP<14>")
	)
	(segment
		(start 313.103006 -64.552576)
		(end 311.527952 -63.901574)
		(width 0.1143)
		(layer "B.Cu")
		(net "UPI_CPU1_CPU0_P0P0_DP<14>")
	)
	(segment
		(start 158.36138 -110.0074)
		(end 162.761168 -110.469934)
		(width 0.1143)
		(layer "B.Cu")
		(net "UPI_CPU1_CPU0_P0P0_DP<14>")
	)
	(segment
		(start 302.36668 -64.004952)
		(end 302.671226 -63.829184)
		(width 0.0889)
		(layer "B.Cu")
		(net "UPI_CPU1_CPU0_P0P0_DP<14>")
	)
	(segment
		(start 311.527952 -63.901574)
		(end 310.6928 -63.901574)
		(width 0.1143)
		(layer "B.Cu")
		(net "UPI_CPU1_CPU0_P0P0_DP<14>")
	)
	(segment
		(start 249.243596 -119.552466)
		(end 263.064244 -117.932454)
		(width 0.1143)
		(layer "B.Cu")
		(net "UPI_CPU1_CPU0_P0P0_DP<14>")
	)
	(segment
		(start 309.04688 -63.926974)
		(end 308.675532 -63.926974)
		(width 0.0889)
		(layer "B.Cu")
		(net "UPI_CPU1_CPU0_P0P0_DP<14>")
	)
	(segment
		(start 309.98668 -63.926974)
		(end 309.3974 -63.926974)
		(width 0.0889)
		(layer "B.Cu")
		(net "UPI_CPU1_CPU0_P0P0_DP<14>")
	)
	(segment
		(start 306.130198 -63.238888)
		(end 306.080414 -63.238888)
		(width 0.0889)
		(layer "B.Cu")
		(net "UPI_CPU1_CPU0_P0P0_DP<14>")
	)
	(segment
		(start 324.409054 -81.915)
		(end 324.341744 -79.31658)
		(width 0.1143)
		(layer "B.Cu")
		(net "UPI_CPU1_CPU0_P0P0_DP<14>")
	)
	(segment
		(start 141.126464 -69.372734)
		(end 141.083284 -69.372734)
		(width 0.0889)
		(layer "B.Cu")
		(net "UPI_CPU1_CPU0_P0P0_DP<14>")
	)
	(segment
		(start 291.125402 -119.699024)
		(end 292.421818 -119.958358)
		(width 0.1143)
		(layer "B.Cu")
		(net "UPI_CPU1_CPU0_P0P0_DP<14>")
	)
	(segment
		(start 309.2958 -63.825374)
		(end 309.14848 -63.825374)
		(width 0.0889)
		(layer "B.Cu")
		(net "UPI_CPU1_CPU0_P0P0_DP<14>")
	)
	(segment
		(start 147.187158 -72.739758)
		(end 146.39925 -71.95185)
		(width 0.1143)
		(layer "B.Cu")
		(net "UPI_CPU1_CPU0_P0P0_DP<14>")
	)
	(segment
		(start 292.421818 -119.958358)
		(end 299.015658 -118.639336)
		(width 0.1143)
		(layer "B.Cu")
		(net "UPI_CPU1_CPU0_P0P0_DP<14>")
	)
	(segment
		(start 310.6674 -63.926974)
		(end 310.3626 -63.926974)
		(width 0.0889)
		(layer "B.Cu")
		(net "UPI_CPU1_CPU0_P0P0_DP<14>")
	)
	(segment
		(start 140.304266 -68.881752)
		(end 140.246354 -68.939664)
		(width 0.0889)
		(layer "B.Cu")
		(net "UPI_CPU1_CPU0_P0P0_DP<14>")
	)
	(segment
		(start 201.623422 -121.690892)
		(end 208.006696 -122.107452)
		(width 0.1143)
		(layer "B.Cu")
		(net "UPI_CPU1_CPU0_P0P0_DP<14>")
	)
	(segment
		(start 315.754004 -113.463578)
		(end 317.9699 -111.375698)
		(width 0.1143)
		(layer "B.Cu")
		(net "UPI_CPU1_CPU0_P0P0_DP<14>")
	)
	(segment
		(start 327.880218 -95.67037)
		(end 327.8124 -95.500698)
		(width 0.1143)
		(layer "B.Cu")
		(net "UPI_CPU1_CPU0_P0P0_DP<14>")
	)
	(segment
		(start 167.739822 -114.762788)
		(end 172.054774 -117.253766)
		(width 0.1143)
		(layer "B.Cu")
		(net "UPI_CPU1_CPU0_P0P0_DP<14>")
	)
	(segment
		(start 208.006696 -122.107452)
		(end 226.430332 -118.408704)
		(width 0.1143)
		(layer "B.Cu")
		(net "UPI_CPU1_CPU0_P0P0_DP<14>")
	)
	(segment
		(start 324.341744 -79.31658)
		(end 324.33006 -78.869286)
		(width 0.1143)
		(layer "B.Cu")
		(net "UPI_CPU1_CPU0_P0P0_DP<14>")
	)
	(segment
		(start 284.013656 -120.06072)
		(end 288.244026 -119.214646)
		(width 0.1143)
		(layer "B.Cu")
		(net "UPI_CPU1_CPU0_P0P0_DP<14>")
	)
	(segment
		(start 174.149258 -117.885972)
		(end 182.762652 -118.42623)
		(width 0.1143)
		(layer "B.Cu")
		(net "UPI_CPU1_CPU0_P0P0_DP<14>")
	)
	(segment
		(start 145.96745 -71.9201)
		(end 145.7325 -71.9201)
		(width 0.0889)
		(layer "B.Cu")
		(net "UPI_CPU1_CPU0_P0P0_DP<14>")
	)
	(segment
		(start 308.353206 -64.2493)
		(end 307.692806 -64.2493)
		(width 0.0889)
		(layer "B.Cu")
		(net "UPI_CPU1_CPU0_P0P0_DP<14>")
	)
	(segment
		(start 318.1985 -111.313468)
		(end 318.664336 -111.186976)
		(width 0.1143)
		(layer "B.Cu")
		(net "UPI_CPU1_CPU0_P0P0_DP<14>")
	)
	(segment
		(start 317.9699 -111.375698)
		(end 318.1985 -111.313468)
		(width 0.1143)
		(layer "B.Cu")
		(net "UPI_CPU1_CPU0_P0P0_DP<14>")
	)
	(segment
		(start 324.550024 -87.343234)
		(end 324.409054 -81.915)
		(width 0.1143)
		(layer "B.Cu")
		(net "UPI_CPU1_CPU0_P0P0_DP<14>")
	)
	(segment
		(start 302.349916 -64.06769)
		(end 302.36668 -64.004952)
		(width 0.0889)
		(layer "B.Cu")
		(net "UPI_CPU1_CPU0_P0P0_DP<14>")
	)
	(segment
		(start 302.689006 -64.229234)
		(end 302.65624 -64.229234)
		(width 0.0889)
		(layer "B.Cu")
		(net "UPI_CPU1_CPU0_P0P0_DP<14>")
	)
	(segment
		(start 263.064244 -117.932454)
		(end 284.013656 -120.06072)
		(width 0.1143)
		(layer "B.Cu")
		(net "UPI_CPU1_CPU0_P0P0_DP<14>")
	)
	(segment
		(start 299.764704 -118.786656)
		(end 309.414672 -116.856764)
		(width 0.1143)
		(layer "B.Cu")
		(net "UPI_CPU1_CPU0_P0P0_DP<14>")
	)
	(segment
		(start 226.430332 -118.408704)
		(end 249.243596 -119.552466)
		(width 0.1143)
		(layer "B.Cu")
		(net "UPI_CPU1_CPU0_P0P0_DP<14>")
	)
	(segment
		(start 149.694646 -85.27542)
		(end 147.187158 -72.739758)
		(width 0.1143)
		(layer "B.Cu")
		(net "UPI_CPU1_CPU0_P0P0_DP<14>")
	)
	(segment
		(start 327.655682 -102.714298)
		(end 327.880218 -95.67037)
		(width 0.1143)
		(layer "B.Cu")
		(net "UPI_CPU1_CPU0_P0P0_DP<14>")
	)
	(segment
		(start 143.4846 -69.6722)
		(end 142.935706 -69.6722)
		(width 0.0889)
		(layer "B.Cu")
		(net "UPI_CPU1_CPU0_P0P0_DP<14>")
	)
	(segment
		(start 149.694646 -85.27542)
		(end 150.652988 -90.06713)
		(width 0.1143)
		(layer "B.Cu")
		(net "UPI_CPU1_CPU0_P0P0_DP<14>")
	)
	(arc
		(start 140.593064 -69.077586)
		(mid 140.471119 -68.946554)
		(end 140.304266 -68.881752)
		(width 0.0889)
		(layer "B.Cu")
		(net "UPI_CPU1_CPU0_P0P0_DP<14>")
	)
	(arc
		(start 306.95265 -64.724788)
		(mid 306.614481 -64.51999)
		(end 306.617116 -64.124586)
		(width 0.0889)
		(layer "B.Cu")
		(net "UPI_CPU1_CPU0_P0P0_DP<14>")
	)
	(arc
		(start 302.65624 -64.229234)
		(mid 302.484714 -64.183289)
		(end 302.349916 -64.06769)
		(width 0.0889)
		(layer "B.Cu")
		(net "UPI_CPU1_CPU0_P0P0_DP<14>")
	)
	(arc
		(start 305.593496 -63.534036)
		(mid 305.451813 -63.67784)
		(end 305.257962 -63.734188)
		(width 0.0889)
		(layer "B.Cu")
		(net "UPI_CPU1_CPU0_P0P0_DP<14>")
	)
	(arc
		(start 306.617116 -64.124586)
		(mid 306.623169 -63.544527)
		(end 306.130198 -63.238888)
		(width 0.0889)
		(layer "B.Cu")
		(net "UPI_CPU1_CPU0_P0P0_DP<14>")
	)
	(arc
		(start 303.183036 -64.524636)
		(mid 302.974428 -64.312704)
		(end 302.689006 -64.229234)
		(width 0.0889)
		(layer "B.Cu")
		(net "UPI_CPU1_CPU0_P0P0_DP<14>")
	)
	(arc
		(start 303.876456 -64.524636)
		(mid 303.529746 -64.724947)
		(end 303.183036 -64.524636)
		(width 0.0889)
		(layer "B.Cu")
		(net "UPI_CPU1_CPU0_P0P0_DP<14>")
	)
	(arc
		(start 141.083284 -69.372734)
		(mid 140.800067 -69.288453)
		(end 140.593064 -69.077586)
		(width 0.0889)
		(layer "B.Cu")
		(net "UPI_CPU1_CPU0_P0P0_DP<14>")
	)
	(arc
		(start 305.225196 -63.734188)
		(mid 304.941979 -63.818469)
		(end 304.734976 -64.029336)
		(width 0.0889)
		(layer "B.Cu")
		(net "UPI_CPU1_CPU0_P0P0_DP<14>")
	)
	(arc
		(start 304.734976 -64.029336)
		(mid 304.594897 -64.172072)
		(end 304.403252 -64.229234)
		(width 0.0889)
		(layer "B.Cu")
		(net "UPI_CPU1_CPU0_P0P0_DP<14>")
	)
	(arc
		(start 141.945868 -68.877688)
		(mid 141.755626 -68.935423)
		(end 141.616684 -69.077586)
		(width 0.0889)
		(layer "B.Cu")
		(net "UPI_CPU1_CPU0_P0P0_DP<14>")
	)
	(arc
		(start 306.080414 -63.238888)
		(mid 305.799052 -63.323934)
		(end 305.593496 -63.534036)
		(width 0.0889)
		(layer "B.Cu")
		(net "UPI_CPU1_CPU0_P0P0_DP<14>")
	)
	(arc
		(start 141.616684 -69.077586)
		(mid 141.40968 -69.28845)
		(end 141.126464 -69.372734)
		(width 0.0889)
		(layer "B.Cu")
		(net "UPI_CPU1_CPU0_P0P0_DP<14>")
	)
	(arc
		(start 304.370486 -64.229234)
		(mid 304.085062 -64.312701)
		(end 303.876456 -64.524636)
		(width 0.0889)
		(layer "B.Cu")
		(net "UPI_CPU1_CPU0_P0P0_DP<14>")
	)
	(segment
		(start 302.099726 -64.819784)
		(end 302.671226 -64.819784)
		(width 0.1143)
		(layer "F.Cu")
		(net "UPI_CPU1_CPU0_P0P0_DP<13>")
	)
	(segment
		(start 140.533374 -68.782184)
		(end 141.104874 -68.782184)
		(width 0.1143)
		(layer "F.Cu")
		(net "UPI_CPU1_CPU0_P0P0_DP<13>")
	)
	(via
		(at 141.104874 -68.782184)
		(size 0.508)
		(drill 0.254)
		(layers "F.Cu" "B.Cu")
		(net "UPI_CPU1_CPU0_P0P0_DP<13>")
	)
	(via
		(at 302.671226 -64.819784)
		(size 0.508)
		(drill 0.254)
		(layers "F.Cu" "B.Cu")
		(net "UPI_CPU1_CPU0_P0P0_DP<13>")
	)
	(segment
		(start 146.020536 -70.56755)
		(end 145.996406 -70.59041)
		(width 0.0889)
		(layer "B.Cu")
		(net "UPI_CPU1_CPU0_P0P0_DP<13>")
	)
	(segment
		(start 317.181484 -68.863718)
		(end 322.79971 -78.943708)
		(width 0.1143)
		(layer "B.Cu")
		(net "UPI_CPU1_CPU0_P0P0_DP<13>")
	)
	(segment
		(start 151.814022 -90.747596)
		(end 147.989036 -71.62546)
		(width 0.1143)
		(layer "B.Cu")
		(net "UPI_CPU1_CPU0_P0P0_DP<13>")
	)
	(segment
		(start 152.138126 -102.04704)
		(end 151.959056 -102.029768)
		(width 0.1143)
		(layer "B.Cu")
		(net "UPI_CPU1_CPU0_P0P0_DP<13>")
	)
	(segment
		(start 326.509126 -95.953834)
		(end 326.3646 -100.480114)
		(width 0.1143)
		(layer "B.Cu")
		(net "UPI_CPU1_CPU0_P0P0_DP<13>")
	)
	(segment
		(start 182.998364 -117.229636)
		(end 174.452534 -116.693442)
		(width 0.1143)
		(layer "B.Cu")
		(net "UPI_CPU1_CPU0_P0P0_DP<13>")
	)
	(segment
		(start 300.156626 -117.46103)
		(end 299.443902 -117.320568)
		(width 0.1143)
		(layer "B.Cu")
		(net "UPI_CPU1_CPU0_P0P0_DP<13>")
	)
	(segment
		(start 226.336098 -117.193822)
		(end 215.1634 -119.43715)
		(width 0.1143)
		(layer "B.Cu")
		(net "UPI_CPU1_CPU0_P0P0_DP<13>")
	)
	(segment
		(start 249.20194 -118.339616)
		(end 226.336098 -117.193822)
		(width 0.1143)
		(layer "B.Cu")
		(net "UPI_CPU1_CPU0_P0P0_DP<13>")
	)
	(segment
		(start 153.689812 -103.92918)
		(end 153.544524 -103.75265)
		(width 0.1143)
		(layer "B.Cu")
		(net "UPI_CPU1_CPU0_P0P0_DP<13>")
	)
	(segment
		(start 158.469076 -108.644436)
		(end 156.508958 -107.54868)
		(width 0.1143)
		(layer "B.Cu")
		(net "UPI_CPU1_CPU0_P0P0_DP<13>")
	)
	(segment
		(start 163.109402 -109.131608)
		(end 158.469076 -108.644436)
		(width 0.1143)
		(layer "B.Cu")
		(net "UPI_CPU1_CPU0_P0P0_DP<13>")
	)
	(segment
		(start 313.50204 -66.444368)
		(end 313.538362 -66.62039)
		(width 0.1143)
		(layer "B.Cu")
		(net "UPI_CPU1_CPU0_P0P0_DP<13>")
	)
	(segment
		(start 198.250556 -120.922542)
		(end 193.340736 -120.70842)
		(width 0.1143)
		(layer "B.Cu")
		(net "UPI_CPU1_CPU0_P0P0_DP<13>")
	)
	(segment
		(start 201.57821 -120.477534)
		(end 198.250556 -120.922542)
		(width 0.1143)
		(layer "B.Cu")
		(net "UPI_CPU1_CPU0_P0P0_DP<13>")
	)
	(segment
		(start 152.767538 -103.010208)
		(end 152.784556 -102.831392)
		(width 0.1143)
		(layer "B.Cu")
		(net "UPI_CPU1_CPU0_P0P0_DP<13>")
	)
	(segment
		(start 151.959056 -102.029768)
		(end 151.245316 -101.164136)
		(width 0.1143)
		(layer "B.Cu")
		(net "UPI_CPU1_CPU0_P0P0_DP<13>")
	)
	(segment
		(start 305.2318 -64.915288)
		(end 305.261772 -64.915288)
		(width 0.0889)
		(layer "B.Cu")
		(net "UPI_CPU1_CPU0_P0P0_DP<13>")
	)
	(segment
		(start 308.996334 -115.69319)
		(end 300.156626 -117.46103)
		(width 0.1143)
		(layer "B.Cu")
		(net "UPI_CPU1_CPU0_P0P0_DP<13>")
	)
	(segment
		(start 310.38546 -65.260474)
		(end 311.197752 -65.260474)
		(width 0.1143)
		(layer "B.Cu")
		(net "UPI_CPU1_CPU0_P0P0_DP<13>")
	)
	(segment
		(start 143.23314 -68.6943)
		(end 142.427706 -67.888866)
		(width 0.0889)
		(layer "B.Cu")
		(net "UPI_CPU1_CPU0_P0P0_DP<13>")
	)
	(segment
		(start 287.63468 -117.964458)
		(end 283.496512 -118.79199)
		(width 0.1143)
		(layer "B.Cu")
		(net "UPI_CPU1_CPU0_P0P0_DP<13>")
	)
	(segment
		(start 153.091896 -103.203756)
		(end 152.912826 -103.186484)
		(width 0.1143)
		(layer "B.Cu")
		(net "UPI_CPU1_CPU0_P0P0_DP<13>")
	)
	(segment
		(start 146.930872 -70.56755)
		(end 146.020536 -70.56755)
		(width 0.1143)
		(layer "B.Cu")
		(net "UPI_CPU1_CPU0_P0P0_DP<13>")
	)
	(segment
		(start 313.13501 -66.355214)
		(end 313.311032 -66.318892)
		(width 0.1143)
		(layer "B.Cu")
		(net "UPI_CPU1_CPU0_P0P0_DP<13>")
	)
	(segment
		(start 304.37709 -65.410334)
		(end 304.409856 -65.410334)
		(width 0.0889)
		(layer "B.Cu")
		(net "UPI_CPU1_CPU0_P0P0_DP<13>")
	)
	(segment
		(start 307.296312 -65.905888)
		(end 307.967126 -65.235074)
		(width 0.0889)
		(layer "B.Cu")
		(net "UPI_CPU1_CPU0_P0P0_DP<13>")
	)
	(segment
		(start 152.912826 -103.186484)
		(end 152.767538 -103.010208)
		(width 0.1143)
		(layer "B.Cu")
		(net "UPI_CPU1_CPU0_P0P0_DP<13>")
	)
	(segment
		(start 291.125402 -118.662196)
		(end 287.63468 -117.964458)
		(width 0.1143)
		(layer "B.Cu")
		(net "UPI_CPU1_CPU0_P0P0_DP<13>")
	)
	(segment
		(start 151.24557 -101.164136)
		(end 150.531576 -100.29825)
		(width 0.1143)
		(layer "B.Cu")
		(net "UPI_CPU1_CPU0_P0P0_DP<13>")
	)
	(segment
		(start 314.862718 -112.55375)
		(end 308.996334 -115.69319)
		(width 0.1143)
		(layer "B.Cu")
		(net "UPI_CPU1_CPU0_P0P0_DP<13>")
	)
	(segment
		(start 153.672794 -104.107996)
		(end 153.689812 -103.92918)
		(width 0.1143)
		(layer "B.Cu")
		(net "UPI_CPU1_CPU0_P0P0_DP<13>")
	)
	(segment
		(start 153.544524 -103.75265)
		(end 153.365454 -103.735378)
		(width 0.1143)
		(layer "B.Cu")
		(net "UPI_CPU1_CPU0_P0P0_DP<13>")
	)
	(segment
		(start 302.964342 -64.988948)
		(end 302.988218 -65.078356)
		(width 0.0889)
		(layer "B.Cu")
		(net "UPI_CPU1_CPU0_P0P0_DP<13>")
	)
	(segment
		(start 322.973192 -79.254858)
		(end 323.04228 -81.915)
		(width 0.1143)
		(layer "B.Cu")
		(net "UPI_CPU1_CPU0_P0P0_DP<13>")
	)
	(segment
		(start 151.256746 -93.533976)
		(end 151.315674 -93.23832)
		(width 0.1143)
		(layer "B.Cu")
		(net "UPI_CPU1_CPU0_P0P0_DP<13>")
	)
	(segment
		(start 215.1634 -119.43715)
		(end 207.921098 -120.8913)
		(width 0.1143)
		(layer "B.Cu")
		(net "UPI_CPU1_CPU0_P0P0_DP<13>")
	)
	(segment
		(start 306.083716 -65.410334)
		(end 306.116482 -65.410334)
		(width 0.0889)
		(layer "B.Cu")
		(net "UPI_CPU1_CPU0_P0P0_DP<13>")
	)
	(segment
		(start 310.363362 -65.260474)
		(end 310.38546 -65.260474)
		(width 0.0889)
		(layer "B.Cu")
		(net "UPI_CPU1_CPU0_P0P0_DP<13>")
	)
	(segment
		(start 314.132722 -67.011296)
		(end 314.323984 -67.137026)
		(width 0.1143)
		(layer "B.Cu")
		(net "UPI_CPU1_CPU0_P0P0_DP<13>")
	)
	(segment
		(start 326.310498 -102.174548)
		(end 318.07023 -109.93882)
		(width 0.1143)
		(layer "B.Cu")
		(net "UPI_CPU1_CPU0_P0P0_DP<13>")
	)
	(segment
		(start 147.989036 -71.62546)
		(end 146.930872 -70.56755)
		(width 0.1143)
		(layer "B.Cu")
		(net "UPI_CPU1_CPU0_P0P0_DP<13>")
	)
	(segment
		(start 152.283414 -102.22357)
		(end 152.138126 -102.04704)
		(width 0.1143)
		(layer "B.Cu")
		(net "UPI_CPU1_CPU0_P0P0_DP<13>")
	)
	(segment
		(start 193.340736 -120.70842)
		(end 193.2178 -120.667018)
		(width 0.1143)
		(layer "B.Cu")
		(net "UPI_CPU1_CPU0_P0P0_DP<13>")
	)
	(segment
		(start 291.92982 -118.822978)
		(end 291.125402 -118.662196)
		(width 0.1143)
		(layer "B.Cu")
		(net "UPI_CPU1_CPU0_P0P0_DP<13>")
	)
	(segment
		(start 312.943748 -66.229484)
		(end 313.13501 -66.355214)
		(width 0.1143)
		(layer "B.Cu")
		(net "UPI_CPU1_CPU0_P0P0_DP<13>")
	)
	(segment
		(start 172.460666 -116.092224)
		(end 168.528492 -113.82121)
		(width 0.1143)
		(layer "B.Cu")
		(net "UPI_CPU1_CPU0_P0P0_DP<13>")
	)
	(segment
		(start 151.245316 -101.164136)
		(end 151.24557 -101.164136)
		(width 0.1143)
		(layer "B.Cu")
		(net "UPI_CPU1_CPU0_P0P0_DP<13>")
	)
	(segment
		(start 303.511966 -65.905888)
		(end 303.547526 -65.905888)
		(width 0.0889)
		(layer "B.Cu")
		(net "UPI_CPU1_CPU0_P0P0_DP<13>")
	)
	(segment
		(start 311.197752 -65.260474)
		(end 312.42 -65.732914)
		(width 0.1143)
		(layer "B.Cu")
		(net "UPI_CPU1_CPU0_P0P0_DP<13>")
	)
	(segment
		(start 153.237184 -103.380286)
		(end 153.091896 -103.203756)
		(width 0.1143)
		(layer "B.Cu")
		(net "UPI_CPU1_CPU0_P0P0_DP<13>")
	)
	(segment
		(start 263.0551 -116.716048)
		(end 249.20194 -118.339616)
		(width 0.1143)
		(layer "B.Cu")
		(net "UPI_CPU1_CPU0_P0P0_DP<13>")
	)
	(segment
		(start 313.905392 -66.709798)
		(end 314.0964 -66.835274)
		(width 0.1143)
		(layer "B.Cu")
		(net "UPI_CPU1_CPU0_P0P0_DP<13>")
	)
	(segment
		(start 313.311032 -66.318892)
		(end 313.50204 -66.444368)
		(width 0.1143)
		(layer "B.Cu")
		(net "UPI_CPU1_CPU0_P0P0_DP<13>")
	)
	(segment
		(start 302.671226 -64.819784)
		(end 302.964342 -64.988948)
		(width 0.0889)
		(layer "B.Cu")
		(net "UPI_CPU1_CPU0_P0P0_DP<13>")
	)
	(segment
		(start 307.967126 -65.235074)
		(end 310.337962 -65.235074)
		(width 0.0889)
		(layer "B.Cu")
		(net "UPI_CPU1_CPU0_P0P0_DP<13>")
	)
	(segment
		(start 143.919194 -68.6943)
		(end 143.23314 -68.6943)
		(width 0.0889)
		(layer "B.Cu")
		(net "UPI_CPU1_CPU0_P0P0_DP<13>")
	)
	(segment
		(start 150.217886 -98.728784)
		(end 151.256746 -93.533976)
		(width 0.1143)
		(layer "B.Cu")
		(net "UPI_CPU1_CPU0_P0P0_DP<13>")
	)
	(segment
		(start 141.963394 -67.696588)
		(end 141.941804 -67.696588)
		(width 0.0889)
		(layer "B.Cu")
		(net "UPI_CPU1_CPU0_P0P0_DP<13>")
	)
	(segment
		(start 145.815304 -70.59041)
		(end 143.919194 -68.6943)
		(width 0.0889)
		(layer "B.Cu")
		(net "UPI_CPU1_CPU0_P0P0_DP<13>")
	)
	(segment
		(start 152.639268 -102.654608)
		(end 152.460198 -102.63759)
		(width 0.1143)
		(layer "B.Cu")
		(net "UPI_CPU1_CPU0_P0P0_DP<13>")
	)
	(segment
		(start 312.42 -65.732914)
		(end 312.907426 -66.053462)
		(width 0.1143)
		(layer "B.Cu")
		(net "UPI_CPU1_CPU0_P0P0_DP<13>")
	)
	(segment
		(start 153.220166 -103.559102)
		(end 153.237184 -103.380286)
		(width 0.1143)
		(layer "B.Cu")
		(net "UPI_CPU1_CPU0_P0P0_DP<13>")
	)
	(segment
		(start 141.20876 -68.678298)
		(end 141.104874 -68.782184)
		(width 0.0889)
		(layer "B.Cu")
		(net "UPI_CPU1_CPU0_P0P0_DP<13>")
	)
	(segment
		(start 326.3646 -95.592646)
		(end 326.509126 -95.953834)
		(width 0.1143)
		(layer "B.Cu")
		(net "UPI_CPU1_CPU0_P0P0_DP<13>")
	)
	(segment
		(start 207.921098 -120.8913)
		(end 201.57821 -120.477534)
		(width 0.1143)
		(layer "B.Cu")
		(net "UPI_CPU1_CPU0_P0P0_DP<13>")
	)
	(segment
		(start 322.79971 -78.943708)
		(end 322.973192 -79.254858)
		(width 0.1143)
		(layer "B.Cu")
		(net "UPI_CPU1_CPU0_P0P0_DP<13>")
	)
	(segment
		(start 317.133986 -110.4138)
		(end 314.862718 -112.55375)
		(width 0.1143)
		(layer "B.Cu")
		(net "UPI_CPU1_CPU0_P0P0_DP<13>")
	)
	(segment
		(start 306.563014 -65.802764)
		(end 306.839874 -65.905888)
		(width 0.0889)
		(layer "B.Cu")
		(net "UPI_CPU1_CPU0_P0P0_DP<13>")
	)
	(segment
		(start 153.365454 -103.735378)
		(end 153.220166 -103.559102)
		(width 0.1143)
		(layer "B.Cu")
		(net "UPI_CPU1_CPU0_P0P0_DP<13>")
	)
	(segment
		(start 150.531576 -100.29825)
		(end 150.217886 -98.728784)
		(width 0.1143)
		(layer "B.Cu")
		(net "UPI_CPU1_CPU0_P0P0_DP<13>")
	)
	(segment
		(start 174.452534 -116.693442)
		(end 172.460666 -116.092224)
		(width 0.1143)
		(layer "B.Cu")
		(net "UPI_CPU1_CPU0_P0P0_DP<13>")
	)
	(segment
		(start 314.0964 -66.835274)
		(end 314.132722 -67.011296)
		(width 0.1143)
		(layer "B.Cu")
		(net "UPI_CPU1_CPU0_P0P0_DP<13>")
	)
	(segment
		(start 193.2178 -120.667018)
		(end 182.998364 -117.229636)
		(width 0.1143)
		(layer "B.Cu")
		(net "UPI_CPU1_CPU0_P0P0_DP<13>")
	)
	(segment
		(start 152.266396 -102.402386)
		(end 152.283414 -102.22357)
		(width 0.1143)
		(layer "B.Cu")
		(net "UPI_CPU1_CPU0_P0P0_DP<13>")
	)
	(segment
		(start 166.914068 -111.89716)
		(end 163.109402 -109.131608)
		(width 0.1143)
		(layer "B.Cu")
		(net "UPI_CPU1_CPU0_P0P0_DP<13>")
	)
	(segment
		(start 313.729624 -66.74612)
		(end 313.905392 -66.709798)
		(width 0.1143)
		(layer "B.Cu")
		(net "UPI_CPU1_CPU0_P0P0_DP<13>")
	)
	(segment
		(start 306.839874 -65.905888)
		(end 307.296312 -65.905888)
		(width 0.0889)
		(layer "B.Cu")
		(net "UPI_CPU1_CPU0_P0P0_DP<13>")
	)
	(segment
		(start 310.337962 -65.235074)
		(end 310.363362 -65.260474)
		(width 0.0889)
		(layer "B.Cu")
		(net "UPI_CPU1_CPU0_P0P0_DP<13>")
	)
	(segment
		(start 323.191378 -87.660988)
		(end 326.3646 -95.592646)
		(width 0.1143)
		(layer "B.Cu")
		(net "UPI_CPU1_CPU0_P0P0_DP<13>")
	)
	(segment
		(start 313.538362 -66.62039)
		(end 313.729624 -66.74612)
		(width 0.1143)
		(layer "B.Cu")
		(net "UPI_CPU1_CPU0_P0P0_DP<13>")
	)
	(segment
		(start 314.323984 -67.137026)
		(end 314.499752 -67.100704)
		(width 0.1143)
		(layer "B.Cu")
		(net "UPI_CPU1_CPU0_P0P0_DP<13>")
	)
	(segment
		(start 326.3646 -100.480114)
		(end 326.310498 -102.174548)
		(width 0.1143)
		(layer "B.Cu")
		(net "UPI_CPU1_CPU0_P0P0_DP<13>")
	)
	(segment
		(start 314.499752 -67.100704)
		(end 317.181484 -68.863718)
		(width 0.1143)
		(layer "B.Cu")
		(net "UPI_CPU1_CPU0_P0P0_DP<13>")
	)
	(segment
		(start 156.508958 -107.54868)
		(end 153.672794 -104.107996)
		(width 0.1143)
		(layer "B.Cu")
		(net "UPI_CPU1_CPU0_P0P0_DP<13>")
	)
	(segment
		(start 312.907426 -66.053462)
		(end 312.943748 -66.229484)
		(width 0.1143)
		(layer "B.Cu")
		(net "UPI_CPU1_CPU0_P0P0_DP<13>")
	)
	(segment
		(start 152.784556 -102.831392)
		(end 152.639268 -102.654608)
		(width 0.1143)
		(layer "B.Cu")
		(net "UPI_CPU1_CPU0_P0P0_DP<13>")
	)
	(segment
		(start 283.496512 -118.79199)
		(end 263.0551 -116.716048)
		(width 0.1143)
		(layer "B.Cu")
		(net "UPI_CPU1_CPU0_P0P0_DP<13>")
	)
	(segment
		(start 151.315674 -93.23832)
		(end 151.814022 -90.747596)
		(width 0.1143)
		(layer "B.Cu")
		(net "UPI_CPU1_CPU0_P0P0_DP<13>")
	)
	(segment
		(start 145.996406 -70.59041)
		(end 145.815304 -70.59041)
		(width 0.0889)
		(layer "B.Cu")
		(net "UPI_CPU1_CPU0_P0P0_DP<13>")
	)
	(segment
		(start 323.04228 -81.915)
		(end 323.191378 -87.660988)
		(width 0.1143)
		(layer "B.Cu")
		(net "UPI_CPU1_CPU0_P0P0_DP<13>")
	)
	(segment
		(start 168.528492 -113.82121)
		(end 166.914068 -111.89716)
		(width 0.1143)
		(layer "B.Cu")
		(net "UPI_CPU1_CPU0_P0P0_DP<13>")
	)
	(segment
		(start 152.460198 -102.63759)
		(end 152.266396 -102.402386)
		(width 0.1143)
		(layer "B.Cu")
		(net "UPI_CPU1_CPU0_P0P0_DP<13>")
	)
	(segment
		(start 142.427706 -67.888866)
		(end 142.427706 -67.888612)
		(width 0.0889)
		(layer "B.Cu")
		(net "UPI_CPU1_CPU0_P0P0_DP<13>")
	)
	(segment
		(start 318.07023 -109.93882)
		(end 317.133986 -110.4138)
		(width 0.1143)
		(layer "B.Cu")
		(net "UPI_CPU1_CPU0_P0P0_DP<13>")
	)
	(segment
		(start 306.452016 -65.610486)
		(end 306.563014 -65.802764)
		(width 0.0889)
		(layer "B.Cu")
		(net "UPI_CPU1_CPU0_P0P0_DP<13>")
	)
	(segment
		(start 299.443902 -117.320568)
		(end 291.92982 -118.822978)
		(width 0.1143)
		(layer "B.Cu")
		(net "UPI_CPU1_CPU0_P0P0_DP<13>")
	)
	(arc
		(start 304.409856 -65.410334)
		(mid 304.693073 -65.326053)
		(end 304.900076 -65.115186)
		(width 0.0889)
		(layer "B.Cu")
		(net "UPI_CPU1_CPU0_P0P0_DP<13>")
	)
	(arc
		(start 302.988218 -65.078356)
		(mid 303.030197 -65.631316)
		(end 303.511966 -65.905888)
		(width 0.0889)
		(layer "B.Cu")
		(net "UPI_CPU1_CPU0_P0P0_DP<13>")
	)
	(arc
		(start 142.427706 -67.888612)
		(mid 142.214634 -67.746461)
		(end 141.963394 -67.696588)
		(width 0.0889)
		(layer "B.Cu")
		(net "UPI_CPU1_CPU0_P0P0_DP<13>")
	)
	(arc
		(start 303.547526 -65.905888)
		(mid 303.83295 -65.822421)
		(end 304.041556 -65.610486)
		(width 0.0889)
		(layer "B.Cu")
		(net "UPI_CPU1_CPU0_P0P0_DP<13>")
	)
	(arc
		(start 305.593496 -65.115186)
		(mid 305.8005 -65.32605)
		(end 306.083716 -65.410334)
		(width 0.0889)
		(layer "B.Cu")
		(net "UPI_CPU1_CPU0_P0P0_DP<13>")
	)
	(arc
		(start 141.372336 -68.283328)
		(mid 141.329819 -68.497074)
		(end 141.20876 -68.678298)
		(width 0.0889)
		(layer "B.Cu")
		(net "UPI_CPU1_CPU0_P0P0_DP<13>")
	)
	(arc
		(start 304.041556 -65.610486)
		(mid 304.183239 -65.466682)
		(end 304.37709 -65.410334)
		(width 0.0889)
		(layer "B.Cu")
		(net "UPI_CPU1_CPU0_P0P0_DP<13>")
	)
	(arc
		(start 141.941804 -67.696588)
		(mid 141.539293 -67.875612)
		(end 141.372336 -68.283328)
		(width 0.0889)
		(layer "B.Cu")
		(net "UPI_CPU1_CPU0_P0P0_DP<13>")
	)
	(arc
		(start 304.900076 -65.115186)
		(mid 305.040155 -64.97245)
		(end 305.2318 -64.915288)
		(width 0.0889)
		(layer "B.Cu")
		(net "UPI_CPU1_CPU0_P0P0_DP<13>")
	)
	(arc
		(start 305.261772 -64.915288)
		(mid 305.453414 -64.972454)
		(end 305.593496 -65.115186)
		(width 0.0889)
		(layer "B.Cu")
		(net "UPI_CPU1_CPU0_P0P0_DP<13>")
	)
	(arc
		(start 306.116482 -65.410334)
		(mid 306.310332 -65.466684)
		(end 306.452016 -65.610486)
		(width 0.0889)
		(layer "B.Cu")
		(net "UPI_CPU1_CPU0_P0P0_DP<13>")
	)
	(segment
		(start 142.43812 -68.382134)
		(end 142.666466 -68.382134)
		(width 0.0889)
		(layer "F.Cu")
		(net "UPI_CPU1_CPU0_P0P0_DP<12>")
	)
	(segment
		(start 143.769334 -67.8561)
		(end 143.999204 -68.08597)
		(width 0.0889)
		(layer "F.Cu")
		(net "UPI_CPU1_CPU0_P0P0_DP<12>")
	)
	(segment
		(start 142.250414 -68.56984)
		(end 142.43812 -68.382134)
		(width 0.0889)
		(layer "F.Cu")
		(net "UPI_CPU1_CPU0_P0P0_DP<12>")
	)
	(segment
		(start 142.250414 -68.782184)
		(end 142.250414 -68.56984)
		(width 0.0889)
		(layer "F.Cu")
		(net "UPI_CPU1_CPU0_P0P0_DP<12>")
	)
	(segment
		(start 143.1925 -67.8561)
		(end 143.769334 -67.8561)
		(width 0.0889)
		(layer "F.Cu")
		(net "UPI_CPU1_CPU0_P0P0_DP<12>")
	)
	(segment
		(start 142.666466 -68.382134)
		(end 143.1925 -67.8561)
		(width 0.0889)
		(layer "F.Cu")
		(net "UPI_CPU1_CPU0_P0P0_DP<12>")
	)
	(segment
		(start 303.816766 -65.810384)
		(end 304.388266 -65.810384)
		(width 0.1143)
		(layer "F.Cu")
		(net "UPI_CPU1_CPU0_P0P0_DP<12>")
	)
	(via
		(at 143.999204 -68.08597)
		(size 0.508)
		(drill 0.254)
		(layers "F.Cu" "B.Cu")
		(net "UPI_CPU1_CPU0_P0P0_DP<12>")
	)
	(via
		(at 152.544272 -91.365832)
		(size 0.508)
		(drill 0.254)
		(layers "F.Cu" "B.Cu")
		(net "UPI_CPU1_CPU0_P0P0_DP<12>")
	)
	(via
		(at 304.388266 -65.810384)
		(size 0.508)
		(drill 0.254)
		(layers "F.Cu" "B.Cu")
		(net "UPI_CPU1_CPU0_P0P0_DP<12>")
	)
	(segment
		(start 308.4068 -66.0273)
		(end 309.427626 -66.0273)
		(width 0.0889)
		(layer "B.Cu")
		(net "UPI_CPU1_CPU0_P0P0_DP<12>")
	)
	(segment
		(start 156.6926 -101.840538)
		(end 155.82519 -97.613216)
		(width 0.1143)
		(layer "B.Cu")
		(net "UPI_CPU1_CPU0_P0P0_DP<12>")
	)
	(segment
		(start 169.003218 -113.256822)
		(end 168.852088 -113.076482)
		(width 0.1143)
		(layer "B.Cu")
		(net "UPI_CPU1_CPU0_P0P0_DP<12>")
	)
	(segment
		(start 144.958054 -68.8086)
		(end 144.8308 -68.681346)
		(width 0.0889)
		(layer "B.Cu")
		(net "UPI_CPU1_CPU0_P0P0_DP<12>")
	)
	(segment
		(start 145.2626 -69.1134)
		(end 145.2626 -68.9864)
		(width 0.0889)
		(layer "B.Cu")
		(net "UPI_CPU1_CPU0_P0P0_DP<12>")
	)
	(segment
		(start 307.611526 -66.210434)
		(end 307.79466 -66.0273)
		(width 0.0889)
		(layer "B.Cu")
		(net "UPI_CPU1_CPU0_P0P0_DP<12>")
	)
	(segment
		(start 144.454372 -68.175632)
		(end 144.36471 -68.08597)
		(width 0.0889)
		(layer "B.Cu")
		(net "UPI_CPU1_CPU0_P0P0_DP<12>")
	)
	(segment
		(start 307.79466 -66.0273)
		(end 308.0512 -66.0273)
		(width 0.0889)
		(layer "B.Cu")
		(net "UPI_CPU1_CPU0_P0P0_DP<12>")
	)
	(segment
		(start 156.980636 -103.244142)
		(end 156.6926 -101.840538)
		(width 0.1143)
		(layer "B.Cu")
		(net "UPI_CPU1_CPU0_P0P0_DP<12>")
	)
	(segment
		(start 144.36471 -68.08597)
		(end 143.999204 -68.08597)
		(width 0.0889)
		(layer "B.Cu")
		(net "UPI_CPU1_CPU0_P0P0_DP<12>")
	)
	(segment
		(start 148.44268 -70.856856)
		(end 147.251928 -69.66585)
		(width 0.1143)
		(layer "B.Cu")
		(net "UPI_CPU1_CPU0_P0P0_DP<12>")
	)
	(segment
		(start 306.09032 -66.210434)
		(end 307.611526 -66.210434)
		(width 0.0889)
		(layer "B.Cu")
		(net "UPI_CPU1_CPU0_P0P0_DP<12>")
	)
	(segment
		(start 174.679102 -115.98021)
		(end 172.660564 -115.370356)
		(width 0.1143)
		(layer "B.Cu")
		(net "UPI_CPU1_CPU0_P0P0_DP<12>")
	)
	(segment
		(start 168.852088 -113.076482)
		(end 168.851834 -113.076736)
		(width 0.1143)
		(layer "B.Cu")
		(net "UPI_CPU1_CPU0_P0P0_DP<12>")
	)
	(segment
		(start 325.626222 -96.066864)
		(end 325.444104 -101.783134)
		(width 0.1143)
		(layer "B.Cu")
		(net "UPI_CPU1_CPU0_P0P0_DP<12>")
	)
	(segment
		(start 291.125402 -118.117112)
		(end 287.1216 -117.31625)
		(width 0.1143)
		(layer "B.Cu")
		(net "UPI_CPU1_CPU0_P0P0_DP<12>")
	)
	(segment
		(start 207.87233 -120.160542)
		(end 201.5236 -119.746014)
		(width 0.1143)
		(layer "B.Cu")
		(net "UPI_CPU1_CPU0_P0P0_DP<12>")
	)
	(segment
		(start 310.92902 -67.302126)
		(end 311.573164 -67.648328)
		(width 0.1143)
		(layer "B.Cu")
		(net "UPI_CPU1_CPU0_P0P0_DP<12>")
	)
	(segment
		(start 287.109662 -117.313964)
		(end 283.414724 -118.053104)
		(width 0.1143)
		(layer "B.Cu")
		(net "UPI_CPU1_CPU0_P0P0_DP<12>")
	)
	(segment
		(start 183.137048 -116.510562)
		(end 174.679102 -115.98021)
		(width 0.1143)
		(layer "B.Cu")
		(net "UPI_CPU1_CPU0_P0P0_DP<12>")
	)
	(segment
		(start 283.414724 -118.053104)
		(end 263.047988 -115.985544)
		(width 0.1143)
		(layer "B.Cu")
		(net "UPI_CPU1_CPU0_P0P0_DP<12>")
	)
	(segment
		(start 308.954424 -114.883438)
		(end 291.951918 -118.282466)
		(width 0.1143)
		(layer "B.Cu")
		(net "UPI_CPU1_CPU0_P0P0_DP<12>")
	)
	(segment
		(start 308.1528 -65.9257)
		(end 308.3052 -65.9257)
		(width 0.0889)
		(layer "B.Cu")
		(net "UPI_CPU1_CPU0_P0P0_DP<12>")
	)
	(segment
		(start 145.2626 -68.9864)
		(end 145.0848 -68.8086)
		(width 0.0889)
		(layer "B.Cu")
		(net "UPI_CPU1_CPU0_P0P0_DP<12>")
	)
	(segment
		(start 160.758378 -106.487722)
		(end 159.71647 -105.730548)
		(width 0.1143)
		(layer "B.Cu")
		(net "UPI_CPU1_CPU0_P0P0_DP<12>")
	)
	(segment
		(start 317.4238 -109.340142)
		(end 316.97295 -109.564678)
		(width 0.1143)
		(layer "B.Cu")
		(net "UPI_CPU1_CPU0_P0P0_DP<12>")
	)
	(segment
		(start 215.1634 -118.696486)
		(end 207.87233 -120.160542)
		(width 0.1143)
		(layer "B.Cu")
		(net "UPI_CPU1_CPU0_P0P0_DP<12>")
	)
	(segment
		(start 322.53428 -88.33612)
		(end 323.953632 -91.884246)
		(width 0.1143)
		(layer "B.Cu")
		(net "UPI_CPU1_CPU0_P0P0_DP<12>")
	)
	(segment
		(start 146.216878 -69.6468)
		(end 145.92554 -69.6468)
		(width 0.0889)
		(layer "B.Cu")
		(net "UPI_CPU1_CPU0_P0P0_DP<12>")
	)
	(segment
		(start 145.3896 -69.2404)
		(end 145.2626 -69.1134)
		(width 0.0889)
		(layer "B.Cu")
		(net "UPI_CPU1_CPU0_P0P0_DP<12>")
	)
	(segment
		(start 312.287412 -67.965828)
		(end 312.289444 -67.966844)
		(width 0.1143)
		(layer "B.Cu")
		(net "UPI_CPU1_CPU0_P0P0_DP<12>")
	)
	(segment
		(start 323.953632 -91.884246)
		(end 323.953378 -91.884246)
		(width 0.1143)
		(layer "B.Cu")
		(net "UPI_CPU1_CPU0_P0P0_DP<12>")
	)
	(segment
		(start 144.558258 -68.409312)
		(end 144.454372 -68.305426)
		(width 0.0889)
		(layer "B.Cu")
		(net "UPI_CPU1_CPU0_P0P0_DP<12>")
	)
	(segment
		(start 147.251928 -69.66585)
		(end 146.247104 -69.66585)
		(width 0.1143)
		(layer "B.Cu")
		(net "UPI_CPU1_CPU0_P0P0_DP<12>")
	)
	(segment
		(start 167.330882 -111.263684)
		(end 160.758378 -106.487722)
		(width 0.1143)
		(layer "B.Cu")
		(net "UPI_CPU1_CPU0_P0P0_DP<12>")
	)
	(segment
		(start 155.82519 -97.613216)
		(end 153.191718 -94.60357)
		(width 0.1143)
		(layer "B.Cu")
		(net "UPI_CPU1_CPU0_P0P0_DP<12>")
	)
	(segment
		(start 226.282504 -116.463572)
		(end 215.1634 -118.696486)
		(width 0.1143)
		(layer "B.Cu")
		(net "UPI_CPU1_CPU0_P0P0_DP<12>")
	)
	(segment
		(start 159.71647 -105.730548)
		(end 159.142684 -105.021888)
		(width 0.1143)
		(layer "B.Cu")
		(net "UPI_CPU1_CPU0_P0P0_DP<12>")
	)
	(segment
		(start 313.551062 -68.4276)
		(end 316.540642 -69.519292)
		(width 0.1143)
		(layer "B.Cu")
		(net "UPI_CPU1_CPU0_P0P0_DP<12>")
	)
	(segment
		(start 291.951918 -118.282466)
		(end 291.125402 -118.117112)
		(width 0.1143)
		(layer "B.Cu")
		(net "UPI_CPU1_CPU0_P0P0_DP<12>")
	)
	(segment
		(start 314.447936 -111.943642)
		(end 308.954424 -114.883438)
		(width 0.1143)
		(layer "B.Cu")
		(net "UPI_CPU1_CPU0_P0P0_DP<12>")
	)
	(segment
		(start 304.09515 -65.979548)
		(end 304.074068 -66.058288)
		(width 0.0889)
		(layer "B.Cu")
		(net "UPI_CPU1_CPU0_P0P0_DP<12>")
	)
	(segment
		(start 308.0512 -66.0273)
		(end 308.1528 -65.9257)
		(width 0.0889)
		(layer "B.Cu")
		(net "UPI_CPU1_CPU0_P0P0_DP<12>")
	)
	(segment
		(start 144.8308 -68.681346)
		(end 144.8308 -68.55206)
		(width 0.0889)
		(layer "B.Cu")
		(net "UPI_CPU1_CPU0_P0P0_DP<12>")
	)
	(segment
		(start 153.191718 -94.60357)
		(end 152.544272 -91.365832)
		(width 0.1143)
		(layer "B.Cu")
		(net "UPI_CPU1_CPU0_P0P0_DP<12>")
	)
	(segment
		(start 201.5236 -119.746014)
		(end 198.14413 -120.18899)
		(width 0.1143)
		(layer "B.Cu")
		(net "UPI_CPU1_CPU0_P0P0_DP<12>")
	)
	(segment
		(start 304.388266 -65.810384)
		(end 304.09515 -65.979548)
		(width 0.0889)
		(layer "B.Cu")
		(net "UPI_CPU1_CPU0_P0P0_DP<12>")
	)
	(segment
		(start 310.503316 -67.102736)
		(end 310.87441 -67.30238)
		(width 0.0889)
		(layer "B.Cu")
		(net "UPI_CPU1_CPU0_P0P0_DP<12>")
	)
	(segment
		(start 144.688052 -68.409312)
		(end 144.558258 -68.409312)
		(width 0.0889)
		(layer "B.Cu")
		(net "UPI_CPU1_CPU0_P0P0_DP<12>")
	)
	(segment
		(start 308.3052 -65.9257)
		(end 308.4068 -66.0273)
		(width 0.0889)
		(layer "B.Cu")
		(net "UPI_CPU1_CPU0_P0P0_DP<12>")
	)
	(segment
		(start 304.37328 -66.210434)
		(end 304.403252 -66.210434)
		(width 0.0889)
		(layer "B.Cu")
		(net "UPI_CPU1_CPU0_P0P0_DP<12>")
	)
	(segment
		(start 146.235928 -69.66585)
		(end 146.216878 -69.6468)
		(width 0.0889)
		(layer "B.Cu")
		(net "UPI_CPU1_CPU0_P0P0_DP<12>")
	)
	(segment
		(start 168.851834 -113.076736)
		(end 167.330882 -111.263684)
		(width 0.1143)
		(layer "B.Cu")
		(net "UPI_CPU1_CPU0_P0P0_DP<12>")
	)
	(segment
		(start 144.8308 -68.55206)
		(end 144.688052 -68.409312)
		(width 0.0889)
		(layer "B.Cu")
		(net "UPI_CPU1_CPU0_P0P0_DP<12>")
	)
	(segment
		(start 287.1216 -117.31625)
		(end 287.11144 -117.314218)
		(width 0.1143)
		(layer "B.Cu")
		(net "UPI_CPU1_CPU0_P0P0_DP<12>")
	)
	(segment
		(start 152.544272 -91.365832)
		(end 148.44268 -70.856856)
		(width 0.1143)
		(layer "B.Cu")
		(net "UPI_CPU1_CPU0_P0P0_DP<12>")
	)
	(segment
		(start 312.289444 -67.966844)
		(end 313.551062 -68.4276)
		(width 0.1143)
		(layer "B.Cu")
		(net "UPI_CPU1_CPU0_P0P0_DP<12>")
	)
	(segment
		(start 309.427626 -66.0273)
		(end 310.503316 -67.102736)
		(width 0.0889)
		(layer "B.Cu")
		(net "UPI_CPU1_CPU0_P0P0_DP<12>")
	)
	(segment
		(start 322.315332 -87.788496)
		(end 322.53428 -88.33612)
		(width 0.1143)
		(layer "B.Cu")
		(net "UPI_CPU1_CPU0_P0P0_DP<12>")
	)
	(segment
		(start 146.247104 -69.66585)
		(end 146.235928 -69.66585)
		(width 0.0889)
		(layer "B.Cu")
		(net "UPI_CPU1_CPU0_P0P0_DP<12>")
	)
	(segment
		(start 198.14413 -120.18899)
		(end 193.47561 -119.987568)
		(width 0.1143)
		(layer "B.Cu")
		(net "UPI_CPU1_CPU0_P0P0_DP<12>")
	)
	(segment
		(start 144.454372 -68.305426)
		(end 144.454372 -68.175632)
		(width 0.0889)
		(layer "B.Cu")
		(net "UPI_CPU1_CPU0_P0P0_DP<12>")
	)
	(segment
		(start 322.10883 -79.8322)
		(end 322.162932 -81.915)
		(width 0.1143)
		(layer "B.Cu")
		(net "UPI_CPU1_CPU0_P0P0_DP<12>")
	)
	(segment
		(start 158.874206 -104.690418)
		(end 156.980636 -103.244142)
		(width 0.1143)
		(layer "B.Cu")
		(net "UPI_CPU1_CPU0_P0P0_DP<12>")
	)
	(segment
		(start 305.225196 -65.715388)
		(end 305.268376 -65.715388)
		(width 0.0889)
		(layer "B.Cu")
		(net "UPI_CPU1_CPU0_P0P0_DP<12>")
	)
	(segment
		(start 193.47561 -119.987568)
		(end 183.137048 -116.510562)
		(width 0.1143)
		(layer "B.Cu")
		(net "UPI_CPU1_CPU0_P0P0_DP<12>")
	)
	(segment
		(start 145.0848 -68.8086)
		(end 144.958054 -68.8086)
		(width 0.0889)
		(layer "B.Cu")
		(net "UPI_CPU1_CPU0_P0P0_DP<12>")
	)
	(segment
		(start 263.047988 -115.985544)
		(end 249.177048 -117.611144)
		(width 0.1143)
		(layer "B.Cu")
		(net "UPI_CPU1_CPU0_P0P0_DP<12>")
	)
	(segment
		(start 159.142684 -105.021888)
		(end 158.874206 -104.690418)
		(width 0.1143)
		(layer "B.Cu")
		(net "UPI_CPU1_CPU0_P0P0_DP<12>")
	)
	(segment
		(start 249.177048 -117.611144)
		(end 226.282504 -116.463572)
		(width 0.1143)
		(layer "B.Cu")
		(net "UPI_CPU1_CPU0_P0P0_DP<12>")
	)
	(segment
		(start 287.11144 -117.314218)
		(end 287.109662 -117.313964)
		(width 0.1143)
		(layer "B.Cu")
		(net "UPI_CPU1_CPU0_P0P0_DP<12>")
	)
	(segment
		(start 145.92554 -69.6468)
		(end 145.51914 -69.2404)
		(width 0.0889)
		(layer "B.Cu")
		(net "UPI_CPU1_CPU0_P0P0_DP<12>")
	)
	(segment
		(start 311.573164 -67.648328)
		(end 312.287412 -67.965828)
		(width 0.1143)
		(layer "B.Cu")
		(net "UPI_CPU1_CPU0_P0P0_DP<12>")
	)
	(segment
		(start 310.87441 -67.30238)
		(end 310.874664 -67.30238)
		(width 0.0889)
		(layer "B.Cu")
		(net "UPI_CPU1_CPU0_P0P0_DP<12>")
	)
	(segment
		(start 310.874664 -67.30238)
		(end 310.92902 -67.302126)
		(width 0.0889)
		(layer "B.Cu")
		(net "UPI_CPU1_CPU0_P0P0_DP<12>")
	)
	(segment
		(start 323.953378 -91.884246)
		(end 325.626222 -96.066864)
		(width 0.1143)
		(layer "B.Cu")
		(net "UPI_CPU1_CPU0_P0P0_DP<12>")
	)
	(segment
		(start 322.09994 -79.494126)
		(end 322.10883 -79.8322)
		(width 0.1143)
		(layer "B.Cu")
		(net "UPI_CPU1_CPU0_P0P0_DP<12>")
	)
	(segment
		(start 325.444104 -101.783134)
		(end 317.4238 -109.340142)
		(width 0.1143)
		(layer "B.Cu")
		(net "UPI_CPU1_CPU0_P0P0_DP<12>")
	)
	(segment
		(start 172.660564 -115.370356)
		(end 169.003218 -113.256822)
		(width 0.1143)
		(layer "B.Cu")
		(net "UPI_CPU1_CPU0_P0P0_DP<12>")
	)
	(segment
		(start 145.51914 -69.2404)
		(end 145.3896 -69.2404)
		(width 0.0889)
		(layer "B.Cu")
		(net "UPI_CPU1_CPU0_P0P0_DP<12>")
	)
	(segment
		(start 316.97295 -109.564678)
		(end 314.447936 -111.943642)
		(width 0.1143)
		(layer "B.Cu")
		(net "UPI_CPU1_CPU0_P0P0_DP<12>")
	)
	(segment
		(start 316.540642 -69.519292)
		(end 322.09994 -79.494126)
		(width 0.1143)
		(layer "B.Cu")
		(net "UPI_CPU1_CPU0_P0P0_DP<12>")
	)
	(segment
		(start 322.162932 -81.915)
		(end 322.315332 -87.788496)
		(width 0.1143)
		(layer "B.Cu")
		(net "UPI_CPU1_CPU0_P0P0_DP<12>")
	)
	(arc
		(start 305.268376 -65.715388)
		(mid 305.551593 -65.799669)
		(end 305.758596 -66.010536)
		(width 0.0889)
		(layer "B.Cu")
		(net "UPI_CPU1_CPU0_P0P0_DP<12>")
	)
	(arc
		(start 305.758596 -66.010536)
		(mid 305.898675 -66.153272)
		(end 306.09032 -66.210434)
		(width 0.0889)
		(layer "B.Cu")
		(net "UPI_CPU1_CPU0_P0P0_DP<12>")
	)
	(arc
		(start 304.074068 -66.058288)
		(mid 304.206949 -66.167271)
		(end 304.37328 -66.210434)
		(width 0.0889)
		(layer "B.Cu")
		(net "UPI_CPU1_CPU0_P0P0_DP<12>")
	)
	(arc
		(start 304.734976 -66.010536)
		(mid 304.94198 -65.799672)
		(end 305.225196 -65.715388)
		(width 0.0889)
		(layer "B.Cu")
		(net "UPI_CPU1_CPU0_P0P0_DP<12>")
	)
	(arc
		(start 304.403252 -66.210434)
		(mid 304.594894 -66.153268)
		(end 304.734976 -66.010536)
		(width 0.0889)
		(layer "B.Cu")
		(net "UPI_CPU1_CPU0_P0P0_DP<12>")
	)
	(segment
		(start 302.099726 -66.800984)
		(end 302.671226 -66.800984)
		(width 0.1143)
		(layer "F.Cu")
		(net "UPI_CPU1_CPU0_P0P0_DP<11>")
	)
	(segment
		(start 139.674854 -67.296538)
		(end 140.246354 -67.296538)
		(width 0.1143)
		(layer "F.Cu")
		(net "UPI_CPU1_CPU0_P0P0_DP<11>")
	)
	(via
		(at 302.671226 -66.800984)
		(size 0.508)
		(drill 0.254)
		(layers "F.Cu" "B.Cu")
		(net "UPI_CPU1_CPU0_P0P0_DP<11>")
	)
	(via
		(at 140.246354 -67.296538)
		(size 0.508)
		(drill 0.254)
		(layers "F.Cu" "B.Cu")
		(net "UPI_CPU1_CPU0_P0P0_DP<11>")
	)
	(segment
		(start 194.339718 -119.005096)
		(end 198.159878 -119.171974)
		(width 0.1143)
		(layer "B.Cu")
		(net "UPI_CPU1_CPU0_P0P0_DP<11>")
	)
	(segment
		(start 309.053992 -66.8528)
		(end 308.1274 -66.8528)
		(width 0.0889)
		(layer "B.Cu")
		(net "UPI_CPU1_CPU0_P0P0_DP<11>")
	)
	(segment
		(start 158.01848 -100.466906)
		(end 157.91942 -100.61702)
		(width 0.1143)
		(layer "B.Cu")
		(net "UPI_CPU1_CPU0_P0P0_DP<11>")
	)
	(segment
		(start 157.875478 -99.770184)
		(end 157.776672 -99.920044)
		(width 0.1143)
		(layer "B.Cu")
		(net "UPI_CPU1_CPU0_P0P0_DP<11>")
	)
	(segment
		(start 173.1391 -114.248692)
		(end 174.899066 -114.78006)
		(width 0.1143)
		(layer "B.Cu")
		(net "UPI_CPU1_CPU0_P0P0_DP<11>")
	)
	(segment
		(start 159.82442 -103.942134)
		(end 159.824674 -103.942642)
		(width 0.1143)
		(layer "B.Cu")
		(net "UPI_CPU1_CPU0_P0P0_DP<11>")
	)
	(segment
		(start 309.903114 -67.820286)
		(end 309.7784 -67.695572)
		(width 0.0889)
		(layer "B.Cu")
		(net "UPI_CPU1_CPU0_P0P0_DP<11>")
	)
	(segment
		(start 198.159878 -119.172228)
		(end 202.456542 -118.594886)
		(width 0.1143)
		(layer "B.Cu")
		(net "UPI_CPU1_CPU0_P0P0_DP<11>")
	)
	(segment
		(start 157.686502 -98.849434)
		(end 157.732476 -99.073462)
		(width 0.1143)
		(layer "B.Cu")
		(net "UPI_CPU1_CPU0_P0P0_DP<11>")
	)
	(segment
		(start 309.3974 -67.196208)
		(end 309.053992 -66.8528)
		(width 0.0889)
		(layer "B.Cu")
		(net "UPI_CPU1_CPU0_P0P0_DP<11>")
	)
	(segment
		(start 291.841174 -117.228874)
		(end 306.47386 -114.304064)
		(width 0.1143)
		(layer "B.Cu")
		(net "UPI_CPU1_CPU0_P0P0_DP<11>")
	)
	(segment
		(start 306.47386 -114.304064)
		(end 309.46217 -113.232184)
		(width 0.1143)
		(layer "B.Cu")
		(net "UPI_CPU1_CPU0_P0P0_DP<11>")
	)
	(segment
		(start 324.100952 -101.177344)
		(end 324.2564 -96.307402)
		(width 0.1143)
		(layer "B.Cu")
		(net "UPI_CPU1_CPU0_P0P0_DP<11>")
	)
	(segment
		(start 141.75486 -66.6623)
		(end 144.107154 -66.6623)
		(width 0.0889)
		(layer "B.Cu")
		(net "UPI_CPU1_CPU0_P0P0_DP<11>")
	)
	(segment
		(start 158.11627 -100.943664)
		(end 158.16199 -101.167946)
		(width 0.1143)
		(layer "B.Cu")
		(net "UPI_CPU1_CPU0_P0P0_DP<11>")
	)
	(segment
		(start 141.451584 -67.001136)
		(end 141.500098 -66.916808)
		(width 0.0889)
		(layer "B.Cu")
		(net "UPI_CPU1_CPU0_P0P0_DP<11>")
	)
	(segment
		(start 283.256228 -116.821966)
		(end 286.525462 -116.16817)
		(width 0.1143)
		(layer "B.Cu")
		(net "UPI_CPU1_CPU0_P0P0_DP<11>")
	)
	(segment
		(start 309.5244 -67.437)
		(end 309.3974 -67.31)
		(width 0.0889)
		(layer "B.Cu")
		(net "UPI_CPU1_CPU0_P0P0_DP<11>")
	)
	(segment
		(start 306.654454 -67.032378)
		(end 306.617116 -67.096386)
		(width 0.0889)
		(layer "B.Cu")
		(net "UPI_CPU1_CPU0_P0P0_DP<11>")
	)
	(segment
		(start 157.490668 -98.5266)
		(end 157.536388 -98.750374)
		(width 0.1143)
		(layer "B.Cu")
		(net "UPI_CPU1_CPU0_P0P0_DP<11>")
	)
	(segment
		(start 146.064224 -68.28155)
		(end 147.407376 -68.28155)
		(width 0.1143)
		(layer "B.Cu")
		(net "UPI_CPU1_CPU0_P0P0_DP<11>")
	)
	(segment
		(start 185.477404 -115.443254)
		(end 185.718196 -115.622324)
		(width 0.1143)
		(layer "B.Cu")
		(net "UPI_CPU1_CPU0_P0P0_DP<11>")
	)
	(segment
		(start 226.199192 -115.24869)
		(end 249.137932 -116.398802)
		(width 0.1143)
		(layer "B.Cu")
		(net "UPI_CPU1_CPU0_P0P0_DP<11>")
	)
	(segment
		(start 154.096212 -93.80093)
		(end 157.2641 -97.4217)
		(width 0.1143)
		(layer "B.Cu")
		(net "UPI_CPU1_CPU0_P0P0_DP<11>")
	)
	(segment
		(start 147.407376 -68.28155)
		(end 149.391624 -70.265544)
		(width 0.1143)
		(layer "B.Cu")
		(net "UPI_CPU1_CPU0_P0P0_DP<11>")
	)
	(segment
		(start 324.2564 -96.307402)
		(end 320.960242 -88.067134)
		(width 0.1143)
		(layer "B.Cu")
		(net "UPI_CPU1_CPU0_P0P0_DP<11>")
	)
	(segment
		(start 140.476986 -67.201034)
		(end 141.1224 -67.201034)
		(width 0.0889)
		(layer "B.Cu")
		(net "UPI_CPU1_CPU0_P0P0_DP<11>")
	)
	(segment
		(start 262.90016 -114.75466)
		(end 283.256228 -116.821966)
		(width 0.1143)
		(layer "B.Cu")
		(net "UPI_CPU1_CPU0_P0P0_DP<11>")
	)
	(segment
		(start 202.456542 -118.594886)
		(end 207.79105 -118.943374)
		(width 0.1143)
		(layer "B.Cu")
		(net "UPI_CPU1_CPU0_P0P0_DP<11>")
	)
	(segment
		(start 304.409856 -67.391534)
		(end 304.366676 -67.391534)
		(width 0.0889)
		(layer "B.Cu")
		(net "UPI_CPU1_CPU0_P0P0_DP<11>")
	)
	(segment
		(start 158.16199 -101.167946)
		(end 158.063184 -101.317806)
		(width 0.1143)
		(layer "B.Cu")
		(net "UPI_CPU1_CPU0_P0P0_DP<11>")
	)
	(segment
		(start 158.32328 -102.588314)
		(end 159.57931 -103.639874)
		(width 0.1143)
		(layer "B.Cu")
		(net "UPI_CPU1_CPU0_P0P0_DP<11>")
	)
	(segment
		(start 215.1634 -117.46357)
		(end 226.199192 -115.24869)
		(width 0.1143)
		(layer "B.Cu")
		(net "UPI_CPU1_CPU0_P0P0_DP<11>")
	)
	(segment
		(start 309.46217 -113.232184)
		(end 313.728608 -110.949486)
		(width 0.1143)
		(layer "B.Cu")
		(net "UPI_CPU1_CPU0_P0P0_DP<11>")
	)
	(segment
		(start 306.790344 -66.896488)
		(end 306.654454 -67.032378)
		(width 0.0889)
		(layer "B.Cu")
		(net "UPI_CPU1_CPU0_P0P0_DP<11>")
	)
	(segment
		(start 157.732476 -99.073462)
		(end 157.63367 -99.223322)
		(width 0.1143)
		(layer "B.Cu")
		(net "UPI_CPU1_CPU0_P0P0_DP<11>")
	)
	(segment
		(start 157.39364 -98.053652)
		(end 157.543754 -98.152458)
		(width 0.1143)
		(layer "B.Cu")
		(net "UPI_CPU1_CPU0_P0P0_DP<11>")
	)
	(segment
		(start 157.822392 -100.143818)
		(end 157.972506 -100.242878)
		(width 0.1143)
		(layer "B.Cu")
		(net "UPI_CPU1_CPU0_P0P0_DP<11>")
	)
	(segment
		(start 159.824674 -103.942642)
		(end 160.529778 -104.813608)
		(width 0.1143)
		(layer "B.Cu")
		(net "UPI_CPU1_CPU0_P0P0_DP<11>")
	)
	(segment
		(start 310.388254 -68.23583)
		(end 310.388 -68.235576)
		(width 0.0889)
		(layer "B.Cu")
		(net "UPI_CPU1_CPU0_P0P0_DP<11>")
	)
	(segment
		(start 157.536388 -98.750374)
		(end 157.686502 -98.849434)
		(width 0.1143)
		(layer "B.Cu")
		(net "UPI_CPU1_CPU0_P0P0_DP<11>")
	)
	(segment
		(start 207.79105 -118.943374)
		(end 215.1634 -117.46357)
		(width 0.1143)
		(layer "B.Cu")
		(net "UPI_CPU1_CPU0_P0P0_DP<11>")
	)
	(segment
		(start 309.7784 -67.577208)
		(end 309.638192 -67.437)
		(width 0.0889)
		(layer "B.Cu")
		(net "UPI_CPU1_CPU0_P0P0_DP<11>")
	)
	(segment
		(start 144.107154 -66.6623)
		(end 145.745454 -68.3006)
		(width 0.0889)
		(layer "B.Cu")
		(net "UPI_CPU1_CPU0_P0P0_DP<11>")
	)
	(segment
		(start 159.57931 -103.639874)
		(end 159.82442 -103.942134)
		(width 0.1143)
		(layer "B.Cu")
		(net "UPI_CPU1_CPU0_P0P0_DP<11>")
	)
	(segment
		(start 157.91942 -100.61702)
		(end 157.965902 -100.844858)
		(width 0.1143)
		(layer "B.Cu")
		(net "UPI_CPU1_CPU0_P0P0_DP<11>")
	)
	(segment
		(start 157.2641 -97.4217)
		(end 157.39364 -98.053652)
		(width 0.1143)
		(layer "B.Cu")
		(net "UPI_CPU1_CPU0_P0P0_DP<11>")
	)
	(segment
		(start 185.718196 -115.622324)
		(end 186.904122 -116.50472)
		(width 0.1143)
		(layer "B.Cu")
		(net "UPI_CPU1_CPU0_P0P0_DP<11>")
	)
	(segment
		(start 169.79138 -112.315752)
		(end 173.1391 -114.248692)
		(width 0.1143)
		(layer "B.Cu")
		(net "UPI_CPU1_CPU0_P0P0_DP<11>")
	)
	(segment
		(start 157.965902 -100.844858)
		(end 158.11627 -100.943664)
		(width 0.1143)
		(layer "B.Cu")
		(net "UPI_CPU1_CPU0_P0P0_DP<11>")
	)
	(segment
		(start 198.159878 -119.171974)
		(end 198.159878 -119.172228)
		(width 0.1143)
		(layer "B.Cu")
		(net "UPI_CPU1_CPU0_P0P0_DP<11>")
	)
	(segment
		(start 305.261772 -66.896488)
		(end 305.2318 -66.896488)
		(width 0.0889)
		(layer "B.Cu")
		(net "UPI_CPU1_CPU0_P0P0_DP<11>")
	)
	(segment
		(start 320.960242 -88.067134)
		(end 320.800222 -81.915)
		(width 0.1143)
		(layer "B.Cu")
		(net "UPI_CPU1_CPU0_P0P0_DP<11>")
	)
	(segment
		(start 160.529778 -104.813608)
		(end 168.129966 -110.33506)
		(width 0.1143)
		(layer "B.Cu")
		(net "UPI_CPU1_CPU0_P0P0_DP<11>")
	)
	(segment
		(start 311.154572 -69.002402)
		(end 310.484266 -68.331842)
		(width 0.1143)
		(layer "B.Cu")
		(net "UPI_CPU1_CPU0_P0P0_DP<11>")
	)
	(segment
		(start 158.063184 -101.317806)
		(end 158.32328 -102.588314)
		(width 0.1143)
		(layer "B.Cu")
		(net "UPI_CPU1_CPU0_P0P0_DP<11>")
	)
	(segment
		(start 302.729138 -66.404998)
		(end 302.671226 -66.46291)
		(width 0.0889)
		(layer "B.Cu")
		(net "UPI_CPU1_CPU0_P0P0_DP<11>")
	)
	(segment
		(start 291.125402 -117.086126)
		(end 291.841174 -117.228874)
		(width 0.1143)
		(layer "B.Cu")
		(net "UPI_CPU1_CPU0_P0P0_DP<11>")
	)
	(segment
		(start 286.525462 -116.16817)
		(end 291.125402 -117.086126)
		(width 0.1143)
		(layer "B.Cu")
		(net "UPI_CPU1_CPU0_P0P0_DP<11>")
	)
	(segment
		(start 149.391624 -70.265544)
		(end 152.90292 -87.831676)
		(width 0.1143)
		(layer "B.Cu")
		(net "UPI_CPU1_CPU0_P0P0_DP<11>")
	)
	(segment
		(start 157.589728 -98.37674)
		(end 157.490668 -98.5266)
		(width 0.1143)
		(layer "B.Cu")
		(net "UPI_CPU1_CPU0_P0P0_DP<11>")
	)
	(segment
		(start 310.484266 -68.331842)
		(end 310.388254 -68.23583)
		(width 0.1143)
		(layer "B.Cu")
		(net "UPI_CPU1_CPU0_P0P0_DP<11>")
	)
	(segment
		(start 320.800222 -81.915)
		(end 320.747898 -79.897986)
		(width 0.1143)
		(layer "B.Cu")
		(net "UPI_CPU1_CPU0_P0P0_DP<11>")
	)
	(segment
		(start 306.126896 -67.391534)
		(end 306.083716 -67.391534)
		(width 0.0889)
		(layer "B.Cu")
		(net "UPI_CPU1_CPU0_P0P0_DP<11>")
	)
	(segment
		(start 309.638192 -67.437)
		(end 309.5244 -67.437)
		(width 0.0889)
		(layer "B.Cu")
		(net "UPI_CPU1_CPU0_P0P0_DP<11>")
	)
	(segment
		(start 141.500098 -66.916808)
		(end 141.75486 -66.6623)
		(width 0.0889)
		(layer "B.Cu")
		(net "UPI_CPU1_CPU0_P0P0_DP<11>")
	)
	(segment
		(start 157.829504 -99.546156)
		(end 157.875478 -99.770184)
		(width 0.1143)
		(layer "B.Cu")
		(net "UPI_CPU1_CPU0_P0P0_DP<11>")
	)
	(segment
		(start 309.3974 -67.31)
		(end 309.3974 -67.196208)
		(width 0.0889)
		(layer "B.Cu")
		(net "UPI_CPU1_CPU0_P0P0_DP<11>")
	)
	(segment
		(start 157.543754 -98.152458)
		(end 157.589728 -98.37674)
		(width 0.1143)
		(layer "B.Cu")
		(net "UPI_CPU1_CPU0_P0P0_DP<11>")
	)
	(segment
		(start 249.137932 -116.398802)
		(end 262.90016 -114.75466)
		(width 0.1143)
		(layer "B.Cu")
		(net "UPI_CPU1_CPU0_P0P0_DP<11>")
	)
	(segment
		(start 168.129966 -110.33506)
		(end 169.79138 -112.315752)
		(width 0.1143)
		(layer "B.Cu")
		(net "UPI_CPU1_CPU0_P0P0_DP<11>")
	)
	(segment
		(start 303.544732 -66.896488)
		(end 303.511966 -66.896488)
		(width 0.0889)
		(layer "B.Cu")
		(net "UPI_CPU1_CPU0_P0P0_DP<11>")
	)
	(segment
		(start 308.083712 -66.896488)
		(end 306.790344 -66.896488)
		(width 0.0889)
		(layer "B.Cu")
		(net "UPI_CPU1_CPU0_P0P0_DP<11>")
	)
	(segment
		(start 157.63367 -99.223322)
		(end 157.67939 -99.447096)
		(width 0.1143)
		(layer "B.Cu")
		(net "UPI_CPU1_CPU0_P0P0_DP<11>")
	)
	(segment
		(start 309.7784 -67.695572)
		(end 309.7784 -67.577208)
		(width 0.0889)
		(layer "B.Cu")
		(net "UPI_CPU1_CPU0_P0P0_DP<11>")
	)
	(segment
		(start 315.574934 -70.616826)
		(end 311.154572 -69.002402)
		(width 0.1143)
		(layer "B.Cu")
		(net "UPI_CPU1_CPU0_P0P0_DP<11>")
	)
	(segment
		(start 302.671226 -66.46291)
		(end 302.671226 -66.800984)
		(width 0.0889)
		(layer "B.Cu")
		(net "UPI_CPU1_CPU0_P0P0_DP<11>")
	)
	(segment
		(start 152.90292 -87.831676)
		(end 154.096212 -93.80093)
		(width 0.1143)
		(layer "B.Cu")
		(net "UPI_CPU1_CPU0_P0P0_DP<11>")
	)
	(segment
		(start 313.728608 -110.949486)
		(end 324.100952 -101.177344)
		(width 0.1143)
		(layer "B.Cu")
		(net "UPI_CPU1_CPU0_P0P0_DP<11>")
	)
	(segment
		(start 186.904122 -116.50472)
		(end 194.339718 -119.005096)
		(width 0.1143)
		(layer "B.Cu")
		(net "UPI_CPU1_CPU0_P0P0_DP<11>")
	)
	(segment
		(start 157.776672 -99.920044)
		(end 157.822392 -100.143818)
		(width 0.1143)
		(layer "B.Cu")
		(net "UPI_CPU1_CPU0_P0P0_DP<11>")
	)
	(segment
		(start 145.745454 -68.3006)
		(end 146.045174 -68.3006)
		(width 0.0889)
		(layer "B.Cu")
		(net "UPI_CPU1_CPU0_P0P0_DP<11>")
	)
	(segment
		(start 174.899066 -114.78006)
		(end 185.477404 -115.443254)
		(width 0.1143)
		(layer "B.Cu")
		(net "UPI_CPU1_CPU0_P0P0_DP<11>")
	)
	(segment
		(start 157.67939 -99.447096)
		(end 157.829504 -99.546156)
		(width 0.1143)
		(layer "B.Cu")
		(net "UPI_CPU1_CPU0_P0P0_DP<11>")
	)
	(segment
		(start 308.1274 -66.8528)
		(end 308.083712 -66.896488)
		(width 0.0889)
		(layer "B.Cu")
		(net "UPI_CPU1_CPU0_P0P0_DP<11>")
	)
	(segment
		(start 320.747898 -79.897986)
		(end 315.574934 -70.616826)
		(width 0.1143)
		(layer "B.Cu")
		(net "UPI_CPU1_CPU0_P0P0_DP<11>")
	)
	(segment
		(start 146.045174 -68.3006)
		(end 146.064224 -68.28155)
		(width 0.0889)
		(layer "B.Cu")
		(net "UPI_CPU1_CPU0_P0P0_DP<11>")
	)
	(segment
		(start 310.021478 -67.820286)
		(end 309.903114 -67.820286)
		(width 0.0889)
		(layer "B.Cu")
		(net "UPI_CPU1_CPU0_P0P0_DP<11>")
	)
	(segment
		(start 157.972506 -100.242878)
		(end 158.01848 -100.466906)
		(width 0.1143)
		(layer "B.Cu")
		(net "UPI_CPU1_CPU0_P0P0_DP<11>")
	)
	(segment
		(start 310.388 -68.186808)
		(end 310.021478 -67.820286)
		(width 0.0889)
		(layer "B.Cu")
		(net "UPI_CPU1_CPU0_P0P0_DP<11>")
	)
	(segment
		(start 310.388 -68.235576)
		(end 310.388 -68.186808)
		(width 0.0889)
		(layer "B.Cu")
		(net "UPI_CPU1_CPU0_P0P0_DP<11>")
	)
	(arc
		(start 141.1224 -67.201034)
		(mid 141.312642 -67.143299)
		(end 141.451584 -67.001136)
		(width 0.0889)
		(layer "B.Cu")
		(net "UPI_CPU1_CPU0_P0P0_DP<11>")
	)
	(arc
		(start 140.246354 -67.296538)
		(mid 140.352169 -67.225835)
		(end 140.476986 -67.201034)
		(width 0.0889)
		(layer "B.Cu")
		(net "UPI_CPU1_CPU0_P0P0_DP<11>")
	)
	(arc
		(start 305.593496 -67.096386)
		(mid 305.453417 -66.95365)
		(end 305.261772 -66.896488)
		(width 0.0889)
		(layer "B.Cu")
		(net "UPI_CPU1_CPU0_P0P0_DP<11>")
	)
	(arc
		(start 305.2318 -66.896488)
		(mid 305.040158 -66.953654)
		(end 304.900076 -67.096386)
		(width 0.0889)
		(layer "B.Cu")
		(net "UPI_CPU1_CPU0_P0P0_DP<11>")
	)
	(arc
		(start 304.366676 -67.391534)
		(mid 304.083459 -67.307253)
		(end 303.876456 -67.096386)
		(width 0.0889)
		(layer "B.Cu")
		(net "UPI_CPU1_CPU0_P0P0_DP<11>")
	)
	(arc
		(start 304.900076 -67.096386)
		(mid 304.693072 -67.30725)
		(end 304.409856 -67.391534)
		(width 0.0889)
		(layer "B.Cu")
		(net "UPI_CPU1_CPU0_P0P0_DP<11>")
	)
	(arc
		(start 306.083716 -67.391534)
		(mid 305.800499 -67.307253)
		(end 305.593496 -67.096386)
		(width 0.0889)
		(layer "B.Cu")
		(net "UPI_CPU1_CPU0_P0P0_DP<11>")
	)
	(arc
		(start 303.017936 -66.601086)
		(mid 302.896045 -66.46989)
		(end 302.729138 -66.404998)
		(width 0.0889)
		(layer "B.Cu")
		(net "UPI_CPU1_CPU0_P0P0_DP<11>")
	)
	(arc
		(start 303.876456 -67.096386)
		(mid 303.736377 -66.95365)
		(end 303.544732 -66.896488)
		(width 0.0889)
		(layer "B.Cu")
		(net "UPI_CPU1_CPU0_P0P0_DP<11>")
	)
	(arc
		(start 303.511966 -66.896488)
		(mid 303.226542 -66.813021)
		(end 303.017936 -66.601086)
		(width 0.0889)
		(layer "B.Cu")
		(net "UPI_CPU1_CPU0_P0P0_DP<11>")
	)
	(arc
		(start 306.617116 -67.096386)
		(mid 306.410112 -67.30725)
		(end 306.126896 -67.391534)
		(width 0.0889)
		(layer "B.Cu")
		(net "UPI_CPU1_CPU0_P0P0_DP<11>")
	)
	(segment
		(start 140.533374 -66.800984)
		(end 141.104874 -66.800984)
		(width 0.1143)
		(layer "F.Cu")
		(net "UPI_CPU1_CPU0_P0P0_DP<10>")
	)
	(segment
		(start 301.241206 -66.305938)
		(end 301.812706 -66.305938)
		(width 0.1143)
		(layer "F.Cu")
		(net "UPI_CPU1_CPU0_P0P0_DP<10>")
	)
	(via
		(at 141.104874 -66.800984)
		(size 0.508)
		(drill 0.254)
		(layers "F.Cu" "B.Cu")
		(net "UPI_CPU1_CPU0_P0P0_DP<10>")
	)
	(via
		(at 146.33321 -67.45605)
		(size 0.508)
		(drill 0.254)
		(layers "F.Cu" "B.Cu")
		(net "UPI_CPU1_CPU0_P0P0_DP<10>")
	)
	(via
		(at 301.812706 -66.305938)
		(size 0.508)
		(drill 0.254)
		(layers "F.Cu" "B.Cu")
		(net "UPI_CPU1_CPU0_P0P0_DP<10>")
	)
	(segment
		(start 309.232046 -112.524032)
		(end 312.803286 -110.612174)
		(width 0.1143)
		(layer "B.Cu")
		(net "UPI_CPU1_CPU0_P0P0_DP<10>")
	)
	(segment
		(start 215.1634 -116.722144)
		(end 226.13874 -114.518186)
		(width 0.1143)
		(layer "B.Cu")
		(net "UPI_CPU1_CPU0_P0P0_DP<10>")
	)
	(segment
		(start 303.551336 -67.696588)
		(end 303.51857 -67.696588)
		(width 0.0889)
		(layer "B.Cu")
		(net "UPI_CPU1_CPU0_P0P0_DP<10>")
	)
	(segment
		(start 323.234304 -100.785676)
		(end 323.373242 -96.434148)
		(width 0.1143)
		(layer "B.Cu")
		(net "UPI_CPU1_CPU0_P0P0_DP<10>")
	)
	(segment
		(start 145.923254 -67.437)
		(end 145.475706 -67.437)
		(width 0.0889)
		(layer "B.Cu")
		(net "UPI_CPU1_CPU0_P0P0_DP<10>")
	)
	(segment
		(start 175.052482 -114.061494)
		(end 179.569618 -114.344704)
		(width 0.1143)
		(layer "B.Cu")
		(net "UPI_CPU1_CPU0_P0P0_DP<10>")
	)
	(segment
		(start 187.199016 -116.040916)
		(end 194.474084 -118.48719)
		(width 0.1143)
		(layer "B.Cu")
		(net "UPI_CPU1_CPU0_P0P0_DP<10>")
	)
	(segment
		(start 320.812922 -90.057478)
		(end 320.085466 -88.245696)
		(width 0.1143)
		(layer "B.Cu")
		(net "UPI_CPU1_CPU0_P0P0_DP<10>")
	)
	(segment
		(start 203.476098 -117.933978)
		(end 207.743552 -118.212108)
		(width 0.1143)
		(layer "B.Cu")
		(net "UPI_CPU1_CPU0_P0P0_DP<10>")
	)
	(segment
		(start 173.42485 -113.571274)
		(end 175.052482 -114.061494)
		(width 0.1143)
		(layer "B.Cu")
		(net "UPI_CPU1_CPU0_P0P0_DP<10>")
	)
	(segment
		(start 286.032194 -115.515644)
		(end 291.125402 -116.534184)
		(width 0.1143)
		(layer "B.Cu")
		(net "UPI_CPU1_CPU0_P0P0_DP<10>")
	)
	(segment
		(start 170.266614 -111.75111)
		(end 173.42485 -113.571274)
		(width 0.1143)
		(layer "B.Cu")
		(net "UPI_CPU1_CPU0_P0P0_DP<10>")
	)
	(segment
		(start 321.711828 -92.296488)
		(end 321.712082 -92.296488)
		(width 0.1143)
		(layer "B.Cu")
		(net "UPI_CPU1_CPU0_P0P0_DP<10>")
	)
	(segment
		(start 194.474084 -118.48719)
		(end 198.094092 -118.645178)
		(width 0.1143)
		(layer "B.Cu")
		(net "UPI_CPU1_CPU0_P0P0_DP<10>")
	)
	(segment
		(start 319.722754 -79.8322)
		(end 314.988956 -71.338186)
		(width 0.1143)
		(layer "B.Cu")
		(net "UPI_CPU1_CPU0_P0P0_DP<10>")
	)
	(segment
		(start 160.94075 -104.166924)
		(end 168.530016 -109.681772)
		(width 0.1143)
		(layer "B.Cu")
		(net "UPI_CPU1_CPU0_P0P0_DP<10>")
	)
	(segment
		(start 305.030124 -114.031268)
		(end 309.232046 -112.524032)
		(width 0.1143)
		(layer "B.Cu")
		(net "UPI_CPU1_CPU0_P0P0_DP<10>")
	)
	(segment
		(start 301.7139 -66.305938)
		(end 301.812706 -66.305938)
		(width 0.0889)
		(layer "B.Cu")
		(net "UPI_CPU1_CPU0_P0P0_DP<10>")
	)
	(segment
		(start 187.121546 -116.014754)
		(end 187.199016 -116.040916)
		(width 0.1143)
		(layer "B.Cu")
		(net "UPI_CPU1_CPU0_P0P0_DP<10>")
	)
	(segment
		(start 323.373242 -96.434148)
		(end 321.711828 -92.296488)
		(width 0.1143)
		(layer "B.Cu")
		(net "UPI_CPU1_CPU0_P0P0_DP<10>")
	)
	(segment
		(start 301.834296 -66.705988)
		(end 301.7139 -66.705988)
		(width 0.0889)
		(layer "B.Cu")
		(net "UPI_CPU1_CPU0_P0P0_DP<10>")
	)
	(segment
		(start 170.238928 -111.718344)
		(end 170.266614 -111.75111)
		(width 0.1143)
		(layer "B.Cu")
		(net "UPI_CPU1_CPU0_P0P0_DP<10>")
	)
	(segment
		(start 308.784498 -69.276722)
		(end 308.21884 -68.711064)
		(width 0.1143)
		(layer "B.Cu")
		(net "UPI_CPU1_CPU0_P0P0_DP<10>")
	)
	(segment
		(start 154.503882 -93.163898)
		(end 158.292038 -97.49282)
		(width 0.1143)
		(layer "B.Cu")
		(net "UPI_CPU1_CPU0_P0P0_DP<10>")
	)
	(segment
		(start 149.775926 -69.521832)
		(end 154.503882 -93.163898)
		(width 0.1143)
		(layer "B.Cu")
		(net "UPI_CPU1_CPU0_P0P0_DP<10>")
	)
	(segment
		(start 309.817516 -69.449188)
		(end 308.784498 -69.276722)
		(width 0.1143)
		(layer "B.Cu")
		(net "UPI_CPU1_CPU0_P0P0_DP<10>")
	)
	(segment
		(start 283.187394 -116.08435)
		(end 286.032194 -115.515644)
		(width 0.1143)
		(layer "B.Cu")
		(net "UPI_CPU1_CPU0_P0P0_DP<10>")
	)
	(segment
		(start 198.094092 -118.645178)
		(end 203.476098 -117.933978)
		(width 0.1143)
		(layer "B.Cu")
		(net "UPI_CPU1_CPU0_P0P0_DP<10>")
	)
	(segment
		(start 307.252878 -67.671188)
		(end 307.23078 -67.671188)
		(width 0.0889)
		(layer "B.Cu")
		(net "UPI_CPU1_CPU0_P0P0_DP<10>")
	)
	(segment
		(start 291.817298 -116.672614)
		(end 305.030124 -114.031268)
		(width 0.1143)
		(layer "B.Cu")
		(net "UPI_CPU1_CPU0_P0P0_DP<10>")
	)
	(segment
		(start 141.7701 -66.3575)
		(end 141.548358 -66.3575)
		(width 0.0889)
		(layer "B.Cu")
		(net "UPI_CPU1_CPU0_P0P0_DP<10>")
	)
	(segment
		(start 146.33321 -67.45605)
		(end 145.949924 -67.45605)
		(width 0.1143)
		(layer "B.Cu")
		(net "UPI_CPU1_CPU0_P0P0_DP<10>")
	)
	(segment
		(start 308.21884 -68.711064)
		(end 308.21884 -68.201286)
		(width 0.1143)
		(layer "B.Cu")
		(net "UPI_CPU1_CPU0_P0P0_DP<10>")
	)
	(segment
		(start 168.530016 -109.681772)
		(end 170.239182 -111.718344)
		(width 0.1143)
		(layer "B.Cu")
		(net "UPI_CPU1_CPU0_P0P0_DP<10>")
	)
	(segment
		(start 307.688742 -67.671188)
		(end 307.252878 -67.671188)
		(width 0.1143)
		(layer "B.Cu")
		(net "UPI_CPU1_CPU0_P0P0_DP<10>")
	)
	(segment
		(start 226.13874 -114.518186)
		(end 249.032776 -115.666012)
		(width 0.1143)
		(layer "B.Cu")
		(net "UPI_CPU1_CPU0_P0P0_DP<10>")
	)
	(segment
		(start 291.125402 -116.534184)
		(end 291.817298 -116.672614)
		(width 0.1143)
		(layer "B.Cu")
		(net "UPI_CPU1_CPU0_P0P0_DP<10>")
	)
	(segment
		(start 262.90016 -114.024664)
		(end 283.187394 -116.08435)
		(width 0.1143)
		(layer "B.Cu")
		(net "UPI_CPU1_CPU0_P0P0_DP<10>")
	)
	(segment
		(start 302.689006 -67.201034)
		(end 302.65624 -67.201034)
		(width 0.0889)
		(layer "B.Cu")
		(net "UPI_CPU1_CPU0_P0P0_DP<10>")
	)
	(segment
		(start 145.475706 -67.437)
		(end 144.281906 -66.2432)
		(width 0.0889)
		(layer "B.Cu")
		(net "UPI_CPU1_CPU0_P0P0_DP<10>")
	)
	(segment
		(start 141.548358 -66.3575)
		(end 141.104874 -66.800984)
		(width 0.0889)
		(layer "B.Cu")
		(net "UPI_CPU1_CPU0_P0P0_DP<10>")
	)
	(segment
		(start 307.20538 -67.696588)
		(end 306.963572 -67.696588)
		(width 0.0889)
		(layer "B.Cu")
		(net "UPI_CPU1_CPU0_P0P0_DP<10>")
	)
	(segment
		(start 207.743552 -118.212108)
		(end 215.1634 -116.722144)
		(width 0.1143)
		(layer "B.Cu")
		(net "UPI_CPU1_CPU0_P0P0_DP<10>")
	)
	(segment
		(start 179.569618 -114.344704)
		(end 185.366152 -114.708178)
		(width 0.1143)
		(layer "B.Cu")
		(net "UPI_CPU1_CPU0_P0P0_DP<10>")
	)
	(segment
		(start 307.23078 -67.671188)
		(end 307.20538 -67.696588)
		(width 0.0889)
		(layer "B.Cu")
		(net "UPI_CPU1_CPU0_P0P0_DP<10>")
	)
	(segment
		(start 314.988956 -71.338186)
		(end 309.817516 -69.449188)
		(width 0.1143)
		(layer "B.Cu")
		(net "UPI_CPU1_CPU0_P0P0_DP<10>")
	)
	(segment
		(start 304.403252 -68.191634)
		(end 304.37328 -68.191634)
		(width 0.0889)
		(layer "B.Cu")
		(net "UPI_CPU1_CPU0_P0P0_DP<10>")
	)
	(segment
		(start 145.942304 -67.45605)
		(end 145.923254 -67.437)
		(width 0.0889)
		(layer "B.Cu")
		(net "UPI_CPU1_CPU0_P0P0_DP<10>")
	)
	(segment
		(start 321.712082 -92.296488)
		(end 320.812922 -90.057478)
		(width 0.1143)
		(layer "B.Cu")
		(net "UPI_CPU1_CPU0_P0P0_DP<10>")
	)
	(segment
		(start 158.292038 -97.49282)
		(end 159.226758 -102.050342)
		(width 0.1143)
		(layer "B.Cu")
		(net "UPI_CPU1_CPU0_P0P0_DP<10>")
	)
	(segment
		(start 305.265074 -67.696588)
		(end 305.225196 -67.696588)
		(width 0.0889)
		(layer "B.Cu")
		(net "UPI_CPU1_CPU0_P0P0_DP<10>")
	)
	(segment
		(start 159.226758 -102.050342)
		(end 160.94075 -104.166924)
		(width 0.1143)
		(layer "B.Cu")
		(net "UPI_CPU1_CPU0_P0P0_DP<10>")
	)
	(segment
		(start 308.21884 -68.201286)
		(end 307.688742 -67.671188)
		(width 0.1143)
		(layer "B.Cu")
		(net "UPI_CPU1_CPU0_P0P0_DP<10>")
	)
	(segment
		(start 312.803286 -110.612174)
		(end 323.234304 -100.785676)
		(width 0.1143)
		(layer "B.Cu")
		(net "UPI_CPU1_CPU0_P0P0_DP<10>")
	)
	(segment
		(start 319.920874 -81.915)
		(end 319.873884 -80.103472)
		(width 0.1143)
		(layer "B.Cu")
		(net "UPI_CPU1_CPU0_P0P0_DP<10>")
	)
	(segment
		(start 185.366152 -114.708178)
		(end 187.121546 -116.014754)
		(width 0.1143)
		(layer "B.Cu")
		(net "UPI_CPU1_CPU0_P0P0_DP<10>")
	)
	(segment
		(start 147.710398 -67.45605)
		(end 149.775926 -69.521832)
		(width 0.1143)
		(layer "B.Cu")
		(net "UPI_CPU1_CPU0_P0P0_DP<10>")
	)
	(segment
		(start 145.949924 -67.45605)
		(end 145.942304 -67.45605)
		(width 0.0889)
		(layer "B.Cu")
		(net "UPI_CPU1_CPU0_P0P0_DP<10>")
	)
	(segment
		(start 144.281906 -66.2432)
		(end 141.8844 -66.2432)
		(width 0.0889)
		(layer "B.Cu")
		(net "UPI_CPU1_CPU0_P0P0_DP<10>")
	)
	(segment
		(start 306.107084 -68.190872)
		(end 306.103528 -68.190872)
		(width 0.0889)
		(layer "B.Cu")
		(net "UPI_CPU1_CPU0_P0P0_DP<10>")
	)
	(segment
		(start 249.032776 -115.666012)
		(end 262.90016 -114.024664)
		(width 0.1143)
		(layer "B.Cu")
		(net "UPI_CPU1_CPU0_P0P0_DP<10>")
	)
	(segment
		(start 320.085466 -88.245696)
		(end 319.920874 -81.915)
		(width 0.1143)
		(layer "B.Cu")
		(net "UPI_CPU1_CPU0_P0P0_DP<10>")
	)
	(segment
		(start 146.33321 -67.45605)
		(end 147.710398 -67.45605)
		(width 0.1143)
		(layer "B.Cu")
		(net "UPI_CPU1_CPU0_P0P0_DP<10>")
	)
	(segment
		(start 141.8844 -66.2432)
		(end 141.7701 -66.3575)
		(width 0.0889)
		(layer "B.Cu")
		(net "UPI_CPU1_CPU0_P0P0_DP<10>")
	)
	(segment
		(start 170.239182 -111.718344)
		(end 170.238928 -111.718344)
		(width 0.1143)
		(layer "B.Cu")
		(net "UPI_CPU1_CPU0_P0P0_DP<10>")
	)
	(segment
		(start 319.873884 -80.103472)
		(end 319.722754 -79.8322)
		(width 0.1143)
		(layer "B.Cu")
		(net "UPI_CPU1_CPU0_P0P0_DP<10>")
	)
	(arc
		(start 304.37328 -68.191634)
		(mid 304.181638 -68.134468)
		(end 304.041556 -67.991736)
		(width 0.0889)
		(layer "B.Cu")
		(net "UPI_CPU1_CPU0_P0P0_DP<10>")
	)
	(arc
		(start 306.103528 -68.190872)
		(mid 305.90442 -68.13749)
		(end 305.758596 -67.991736)
		(width 0.0889)
		(layer "B.Cu")
		(net "UPI_CPU1_CPU0_P0P0_DP<10>")
	)
	(arc
		(start 304.041556 -67.991736)
		(mid 303.834552 -67.780872)
		(end 303.551336 -67.696588)
		(width 0.0889)
		(layer "B.Cu")
		(net "UPI_CPU1_CPU0_P0P0_DP<10>")
	)
	(arc
		(start 304.734976 -67.991736)
		(mid 304.594897 -68.134472)
		(end 304.403252 -68.191634)
		(width 0.0889)
		(layer "B.Cu")
		(net "UPI_CPU1_CPU0_P0P0_DP<10>")
	)
	(arc
		(start 305.758596 -67.991736)
		(mid 305.550177 -67.780023)
		(end 305.265074 -67.696588)
		(width 0.0889)
		(layer "B.Cu")
		(net "UPI_CPU1_CPU0_P0P0_DP<10>")
	)
	(arc
		(start 302.65624 -67.201034)
		(mid 302.464598 -67.143868)
		(end 302.324516 -67.001136)
		(width 0.0889)
		(layer "B.Cu")
		(net "UPI_CPU1_CPU0_P0P0_DP<10>")
	)
	(arc
		(start 303.51857 -67.696588)
		(mid 303.32472 -67.640238)
		(end 303.183036 -67.496436)
		(width 0.0889)
		(layer "B.Cu")
		(net "UPI_CPU1_CPU0_P0P0_DP<10>")
	)
	(arc
		(start 301.7139 -66.705988)
		(mid 301.514002 -66.50609)
		(end 301.7139 -66.305938)
		(width 0.0889)
		(layer "B.Cu")
		(net "UPI_CPU1_CPU0_P0P0_DP<10>")
	)
	(arc
		(start 306.452016 -67.991736)
		(mid 306.306264 -68.137614)
		(end 306.107084 -68.190872)
		(width 0.0889)
		(layer "B.Cu")
		(net "UPI_CPU1_CPU0_P0P0_DP<10>")
	)
	(arc
		(start 306.963572 -67.696588)
		(mid 306.668203 -67.775546)
		(end 306.452016 -67.991736)
		(width 0.0889)
		(layer "B.Cu")
		(net "UPI_CPU1_CPU0_P0P0_DP<10>")
	)
	(arc
		(start 303.183036 -67.496436)
		(mid 302.974428 -67.284504)
		(end 302.689006 -67.201034)
		(width 0.0889)
		(layer "B.Cu")
		(net "UPI_CPU1_CPU0_P0P0_DP<10>")
	)
	(arc
		(start 305.225196 -67.696588)
		(mid 304.941979 -67.780869)
		(end 304.734976 -67.991736)
		(width 0.0889)
		(layer "B.Cu")
		(net "UPI_CPU1_CPU0_P0P0_DP<10>")
	)
	(arc
		(start 302.324516 -67.001136)
		(mid 302.117512 -66.790272)
		(end 301.834296 -66.705988)
		(width 0.0889)
		(layer "B.Cu")
		(net "UPI_CPU1_CPU0_P0P0_DP<10>")
	)
	(segment
		(start 141.391894 -57.390538)
		(end 141.963394 -57.390538)
		(width 0.1143)
		(layer "F.Cu")
		(net "UPI_CPU1_CPU0_P0P0_DP<0>")
	)
	(segment
		(start 299.524166 -71.258938)
		(end 300.095666 -71.258938)
		(width 0.1143)
		(layer "F.Cu")
		(net "UPI_CPU1_CPU0_P0P0_DP<0>")
	)
	(via
		(at 300.095666 -71.258938)
		(size 0.508)
		(drill 0.254)
		(layers "F.Cu" "B.Cu")
		(net "UPI_CPU1_CPU0_P0P0_DP<0>")
	)
	(via
		(at 141.963394 -57.390538)
		(size 0.508)
		(drill 0.254)
		(layers "F.Cu" "B.Cu")
		(net "UPI_CPU1_CPU0_P0P0_DP<0>")
	)
	(segment
		(start 142.637002 -57.486296)
		(end 143.967962 -57.486296)
		(width 0.0889)
		(layer "B.Cu")
		(net "UPI_CPU1_CPU0_P0P0_DP<0>")
	)
	(segment
		(start 228.336094 -104.683052)
		(end 228.357684 -104.250236)
		(width 0.1143)
		(layer "B.Cu")
		(net "UPI_CPU1_CPU0_P0P0_DP<0>")
	)
	(segment
		(start 193.002916 -106.018076)
		(end 196.510402 -109.922564)
		(width 0.1143)
		(layer "B.Cu")
		(net "UPI_CPU1_CPU0_P0P0_DP<0>")
	)
	(segment
		(start 144.720818 -56.73344)
		(end 148.636736 -56.73344)
		(width 0.0889)
		(layer "B.Cu")
		(net "UPI_CPU1_CPU0_P0P0_DP<0>")
	)
	(segment
		(start 196.510402 -109.922564)
		(end 199.105012 -110.660434)
		(width 0.1143)
		(layer "B.Cu")
		(net "UPI_CPU1_CPU0_P0P0_DP<0>")
	)
	(segment
		(start 300.971966 -76.116434)
		(end 300.9392 -76.116434)
		(width 0.0889)
		(layer "B.Cu")
		(net "UPI_CPU1_CPU0_P0P0_DP<0>")
	)
	(segment
		(start 228.357684 -104.250236)
		(end 228.477318 -104.142032)
		(width 0.1143)
		(layer "B.Cu")
		(net "UPI_CPU1_CPU0_P0P0_DP<0>")
	)
	(segment
		(start 200.459086 -110.479586)
		(end 201.920856 -109.502956)
		(width 0.1143)
		(layer "B.Cu")
		(net "UPI_CPU1_CPU0_P0P0_DP<0>")
	)
	(segment
		(start 241.245898 -101.94925)
		(end 242.52301 -101.464618)
		(width 0.1143)
		(layer "B.Cu")
		(net "UPI_CPU1_CPU0_P0P0_DP<0>")
	)
	(segment
		(start 254.72009 -101.474016)
		(end 256.421382 -101.73843)
		(width 0.1143)
		(layer "B.Cu")
		(net "UPI_CPU1_CPU0_P0P0_DP<0>")
	)
	(segment
		(start 185.434986 -104.666796)
		(end 193.002916 -106.018076)
		(width 0.1143)
		(layer "B.Cu")
		(net "UPI_CPU1_CPU0_P0P0_DP<0>")
	)
	(segment
		(start 257.770122 -103.286306)
		(end 258.11734 -103.1875)
		(width 0.1143)
		(layer "B.Cu")
		(net "UPI_CPU1_CPU0_P0P0_DP<0>")
	)
	(segment
		(start 304.420778 -78.096872)
		(end 304.403252 -78.097634)
		(width 0.0889)
		(layer "B.Cu")
		(net "UPI_CPU1_CPU0_P0P0_DP<0>")
	)
	(segment
		(start 228.477318 -104.142032)
		(end 229.176326 -104.177338)
		(width 0.1143)
		(layer "B.Cu")
		(net "UPI_CPU1_CPU0_P0P0_DP<0>")
	)
	(segment
		(start 299.755306 -72.460104)
		(end 299.748956 -72.449436)
		(width 0.0889)
		(layer "B.Cu")
		(net "UPI_CPU1_CPU0_P0P0_DP<0>")
	)
	(segment
		(start 299.778674 -71.517002)
		(end 299.80255 -71.427848)
		(width 0.0889)
		(layer "B.Cu")
		(net "UPI_CPU1_CPU0_P0P0_DP<0>")
	)
	(segment
		(start 245.735348 -101.567234)
		(end 247.475756 -100.916486)
		(width 0.1143)
		(layer "B.Cu")
		(net "UPI_CPU1_CPU0_P0P0_DP<0>")
	)
	(segment
		(start 257.368802 -103.062786)
		(end 257.770122 -103.286306)
		(width 0.1143)
		(layer "B.Cu")
		(net "UPI_CPU1_CPU0_P0P0_DP<0>")
	)
	(segment
		(start 302.689006 -77.107034)
		(end 302.65624 -77.107034)
		(width 0.0889)
		(layer "B.Cu")
		(net "UPI_CPU1_CPU0_P0P0_DP<0>")
	)
	(segment
		(start 171.607988 -99.251516)
		(end 173.022006 -100.392738)
		(width 0.1143)
		(layer "B.Cu")
		(net "UPI_CPU1_CPU0_P0P0_DP<0>")
	)
	(segment
		(start 215.1634 -106.842814)
		(end 225.379026 -104.790494)
		(width 0.1143)
		(layer "B.Cu")
		(net "UPI_CPU1_CPU0_P0P0_DP<0>")
	)
	(segment
		(start 303.551336 -77.602588)
		(end 303.51857 -77.602588)
		(width 0.0889)
		(layer "B.Cu")
		(net "UPI_CPU1_CPU0_P0P0_DP<0>")
	)
	(segment
		(start 259.779516 -103.608378)
		(end 278.725122 -105.529634)
		(width 0.1143)
		(layer "B.Cu")
		(net "UPI_CPU1_CPU0_P0P0_DP<0>")
	)
	(segment
		(start 252.391418 -101.717602)
		(end 254.72009 -101.474016)
		(width 0.1143)
		(layer "B.Cu")
		(net "UPI_CPU1_CPU0_P0P0_DP<0>")
	)
	(segment
		(start 308.69763 -91.33459)
		(end 308.77002 -89.06002)
		(width 0.1143)
		(layer "B.Cu")
		(net "UPI_CPU1_CPU0_P0P0_DP<0>")
	)
	(segment
		(start 283.317442 -104.611932)
		(end 284.017212 -104.750362)
		(width 0.1143)
		(layer "B.Cu")
		(net "UPI_CPU1_CPU0_P0P0_DP<0>")
	)
	(segment
		(start 308.77002 -89.06002)
		(end 308.819042 -87.517224)
		(width 0.1143)
		(layer "B.Cu")
		(net "UPI_CPU1_CPU0_P0P0_DP<0>")
	)
	(segment
		(start 230.626666 -105.053384)
		(end 238.441484 -103.46563)
		(width 0.1143)
		(layer "B.Cu")
		(net "UPI_CPU1_CPU0_P0P0_DP<0>")
	)
	(segment
		(start 307.738272 -100.404676)
		(end 308.69763 -91.33459)
		(width 0.1143)
		(layer "B.Cu")
		(net "UPI_CPU1_CPU0_P0P0_DP<0>")
	)
	(segment
		(start 240.640616 -102.554786)
		(end 241.245898 -101.94925)
		(width 0.1143)
		(layer "B.Cu")
		(net "UPI_CPU1_CPU0_P0P0_DP<0>")
	)
	(segment
		(start 256.99974 -102.060502)
		(end 257.04419 -102.215696)
		(width 0.1143)
		(layer "B.Cu")
		(net "UPI_CPU1_CPU0_P0P0_DP<0>")
	)
	(segment
		(start 306.90566 -82.75574)
		(end 306.529994 -81.915)
		(width 0.1143)
		(layer "B.Cu")
		(net "UPI_CPU1_CPU0_P0P0_DP<0>")
	)
	(segment
		(start 258.186936 -103.062786)
		(end 258.276598 -102.902004)
		(width 0.1143)
		(layer "B.Cu")
		(net "UPI_CPU1_CPU0_P0P0_DP<0>")
	)
	(segment
		(start 169.645838 -96.275398)
		(end 171.607988 -99.251516)
		(width 0.1143)
		(layer "B.Cu")
		(net "UPI_CPU1_CPU0_P0P0_DP<0>")
	)
	(segment
		(start 300.117256 -75.621388)
		(end 300.08449 -75.621388)
		(width 0.0889)
		(layer "B.Cu")
		(net "UPI_CPU1_CPU0_P0P0_DP<0>")
	)
	(segment
		(start 229.176326 -104.177338)
		(end 229.284276 -104.296718)
		(width 0.1143)
		(layer "B.Cu")
		(net "UPI_CPU1_CPU0_P0P0_DP<0>")
	)
	(segment
		(start 291.125402 -103.32974)
		(end 292.140386 -103.126794)
		(width 0.1143)
		(layer "B.Cu")
		(net "UPI_CPU1_CPU0_P0P0_DP<0>")
	)
	(segment
		(start 173.022006 -100.392738)
		(end 179.775358 -102.052628)
		(width 0.1143)
		(layer "B.Cu")
		(net "UPI_CPU1_CPU0_P0P0_DP<0>")
	)
	(segment
		(start 299.748956 -72.449436)
		(end 299.74413 -72.4408)
		(width 0.0889)
		(layer "B.Cu")
		(net "UPI_CPU1_CPU0_P0P0_DP<0>")
	)
	(segment
		(start 148.9202 -57.052464)
		(end 156.890974 -65.023238)
		(width 0.1143)
		(layer "B.Cu")
		(net "UPI_CPU1_CPU0_P0P0_DP<0>")
	)
	(segment
		(start 228.068124 -104.925622)
		(end 228.336094 -104.683052)
		(width 0.1143)
		(layer "B.Cu")
		(net "UPI_CPU1_CPU0_P0P0_DP<0>")
	)
	(segment
		(start 305.92014 -80.179672)
		(end 305.89474 -80.154272)
		(width 0.0889)
		(layer "B.Cu")
		(net "UPI_CPU1_CPU0_P0P0_DP<0>")
	)
	(segment
		(start 304.72888 -78.142084)
		(end 304.420778 -78.096872)
		(width 0.0889)
		(layer "B.Cu")
		(net "UPI_CPU1_CPU0_P0P0_DP<0>")
	)
	(segment
		(start 299.755306 -74.441304)
		(end 299.748956 -74.430636)
		(width 0.0889)
		(layer "B.Cu")
		(net "UPI_CPU1_CPU0_P0P0_DP<0>")
	)
	(segment
		(start 305.89474 -79.216758)
		(end 305.462432 -78.537308)
		(width 0.0889)
		(layer "B.Cu")
		(net "UPI_CPU1_CPU0_P0P0_DP<0>")
	)
	(segment
		(start 181.227476 -102.925626)
		(end 185.434986 -104.666796)
		(width 0.1143)
		(layer "B.Cu")
		(net "UPI_CPU1_CPU0_P0P0_DP<0>")
	)
	(segment
		(start 307.157374 -84.604352)
		(end 307.01488 -83.55838)
		(width 0.1143)
		(layer "B.Cu")
		(net "UPI_CPU1_CPU0_P0P0_DP<0>")
	)
	(segment
		(start 307.01488 -83.55838)
		(end 306.90566 -82.75574)
		(width 0.1143)
		(layer "B.Cu")
		(net "UPI_CPU1_CPU0_P0P0_DP<0>")
	)
	(segment
		(start 308.819042 -87.517224)
		(end 308.009798 -85.763354)
		(width 0.1143)
		(layer "B.Cu")
		(net "UPI_CPU1_CPU0_P0P0_DP<0>")
	)
	(segment
		(start 249.45086 -100.842064)
		(end 252.391418 -101.717602)
		(width 0.1143)
		(layer "B.Cu")
		(net "UPI_CPU1_CPU0_P0P0_DP<0>")
	)
	(segment
		(start 156.890974 -65.023238)
		(end 161.213546 -86.6394)
		(width 0.1143)
		(layer "B.Cu")
		(net "UPI_CPU1_CPU0_P0P0_DP<0>")
	)
	(segment
		(start 257.04419 -102.215696)
		(end 256.884932 -102.501192)
		(width 0.1143)
		(layer "B.Cu")
		(net "UPI_CPU1_CPU0_P0P0_DP<0>")
	)
	(segment
		(start 305.462432 -78.537308)
		(end 304.72888 -78.142084)
		(width 0.0889)
		(layer "B.Cu")
		(net "UPI_CPU1_CPU0_P0P0_DP<0>")
	)
	(segment
		(start 141.963394 -57.390538)
		(end 142.541244 -57.390538)
		(width 0.0889)
		(layer "B.Cu")
		(net "UPI_CPU1_CPU0_P0P0_DP<0>")
	)
	(segment
		(start 148.636736 -56.73344)
		(end 148.9202 -57.016904)
		(width 0.0889)
		(layer "B.Cu")
		(net "UPI_CPU1_CPU0_P0P0_DP<0>")
	)
	(segment
		(start 258.800092 -103.062786)
		(end 259.779516 -103.608378)
		(width 0.1143)
		(layer "B.Cu")
		(net "UPI_CPU1_CPU0_P0P0_DP<0>")
	)
	(segment
		(start 305.89474 -80.154272)
		(end 305.89474 -79.216758)
		(width 0.0889)
		(layer "B.Cu")
		(net "UPI_CPU1_CPU0_P0P0_DP<0>")
	)
	(segment
		(start 304.660554 -104.329738)
		(end 307.541676 -101.047804)
		(width 0.1143)
		(layer "B.Cu")
		(net "UPI_CPU1_CPU0_P0P0_DP<0>")
	)
	(segment
		(start 299.80255 -71.427848)
		(end 300.095666 -71.258938)
		(width 0.0889)
		(layer "B.Cu")
		(net "UPI_CPU1_CPU0_P0P0_DP<0>")
	)
	(segment
		(start 225.379026 -104.790494)
		(end 228.068124 -104.925622)
		(width 0.1143)
		(layer "B.Cu")
		(net "UPI_CPU1_CPU0_P0P0_DP<0>")
	)
	(segment
		(start 306.529994 -81.915)
		(end 305.92014 -80.550766)
		(width 0.1143)
		(layer "B.Cu")
		(net "UPI_CPU1_CPU0_P0P0_DP<0>")
	)
	(segment
		(start 229.284276 -104.296718)
		(end 229.262686 -104.729534)
		(width 0.1143)
		(layer "B.Cu")
		(net "UPI_CPU1_CPU0_P0P0_DP<0>")
	)
	(segment
		(start 238.441484 -103.46563)
		(end 240.640616 -102.554786)
		(width 0.1143)
		(layer "B.Cu")
		(net "UPI_CPU1_CPU0_P0P0_DP<0>")
	)
	(segment
		(start 299.755306 -73.450704)
		(end 299.748956 -73.440036)
		(width 0.0889)
		(layer "B.Cu")
		(net "UPI_CPU1_CPU0_P0P0_DP<0>")
	)
	(segment
		(start 258.431538 -102.857554)
		(end 258.800092 -103.062786)
		(width 0.1143)
		(layer "B.Cu")
		(net "UPI_CPU1_CPU0_P0P0_DP<0>")
	)
	(segment
		(start 247.475756 -100.916486)
		(end 249.45086 -100.842064)
		(width 0.1143)
		(layer "B.Cu")
		(net "UPI_CPU1_CPU0_P0P0_DP<0>")
	)
	(segment
		(start 148.9202 -57.016904)
		(end 148.9202 -57.052464)
		(width 0.0889)
		(layer "B.Cu")
		(net "UPI_CPU1_CPU0_P0P0_DP<0>")
	)
	(segment
		(start 305.92014 -80.550766)
		(end 305.92014 -80.179672)
		(width 0.1143)
		(layer "B.Cu")
		(net "UPI_CPU1_CPU0_P0P0_DP<0>")
	)
	(segment
		(start 256.421382 -101.73843)
		(end 256.99974 -102.060502)
		(width 0.1143)
		(layer "B.Cu")
		(net "UPI_CPU1_CPU0_P0P0_DP<0>")
	)
	(segment
		(start 307.541676 -101.047804)
		(end 307.6956 -100.544376)
		(width 0.1143)
		(layer "B.Cu")
		(net "UPI_CPU1_CPU0_P0P0_DP<0>")
	)
	(segment
		(start 307.6956 -100.544376)
		(end 307.738272 -100.404676)
		(width 0.1143)
		(layer "B.Cu")
		(net "UPI_CPU1_CPU0_P0P0_DP<0>")
	)
	(segment
		(start 258.11734 -103.1875)
		(end 258.186936 -103.062786)
		(width 0.1143)
		(layer "B.Cu")
		(net "UPI_CPU1_CPU0_P0P0_DP<0>")
	)
	(segment
		(start 143.967962 -57.486296)
		(end 144.720818 -56.73344)
		(width 0.0889)
		(layer "B.Cu")
		(net "UPI_CPU1_CPU0_P0P0_DP<0>")
	)
	(segment
		(start 179.775358 -102.052628)
		(end 181.227476 -102.925626)
		(width 0.1143)
		(layer "B.Cu")
		(net "UPI_CPU1_CPU0_P0P0_DP<0>")
	)
	(segment
		(start 256.884932 -102.501192)
		(end 256.983738 -102.84841)
		(width 0.1143)
		(layer "B.Cu")
		(net "UPI_CPU1_CPU0_P0P0_DP<0>")
	)
	(segment
		(start 258.276598 -102.902004)
		(end 258.431538 -102.857554)
		(width 0.1143)
		(layer "B.Cu")
		(net "UPI_CPU1_CPU0_P0P0_DP<0>")
	)
	(segment
		(start 256.983738 -102.84841)
		(end 257.368802 -103.062786)
		(width 0.1143)
		(layer "B.Cu")
		(net "UPI_CPU1_CPU0_P0P0_DP<0>")
	)
	(segment
		(start 307.384196 -85.088222)
		(end 307.157374 -84.604352)
		(width 0.1143)
		(layer "B.Cu")
		(net "UPI_CPU1_CPU0_P0P0_DP<0>")
	)
	(segment
		(start 284.017212 -104.750362)
		(end 291.125402 -103.32974)
		(width 0.1143)
		(layer "B.Cu")
		(net "UPI_CPU1_CPU0_P0P0_DP<0>")
	)
	(segment
		(start 301.834296 -76.611988)
		(end 301.80153 -76.611988)
		(width 0.0889)
		(layer "B.Cu")
		(net "UPI_CPU1_CPU0_P0P0_DP<0>")
	)
	(segment
		(start 304.301906 -104.549448)
		(end 304.660554 -104.329738)
		(width 0.1143)
		(layer "B.Cu")
		(net "UPI_CPU1_CPU0_P0P0_DP<0>")
	)
	(segment
		(start 299.748956 -74.430636)
		(end 299.74413 -74.422)
		(width 0.0889)
		(layer "B.Cu")
		(net "UPI_CPU1_CPU0_P0P0_DP<0>")
	)
	(segment
		(start 242.52301 -101.464618)
		(end 245.735348 -101.567234)
		(width 0.1143)
		(layer "B.Cu")
		(net "UPI_CPU1_CPU0_P0P0_DP<0>")
	)
	(segment
		(start 229.262686 -104.729534)
		(end 229.50551 -104.997504)
		(width 0.1143)
		(layer "B.Cu")
		(net "UPI_CPU1_CPU0_P0P0_DP<0>")
	)
	(segment
		(start 201.920856 -109.502956)
		(end 215.1634 -106.842814)
		(width 0.1143)
		(layer "B.Cu")
		(net "UPI_CPU1_CPU0_P0P0_DP<0>")
	)
	(segment
		(start 308.009798 -85.763354)
		(end 307.384196 -85.088222)
		(width 0.1143)
		(layer "B.Cu")
		(net "UPI_CPU1_CPU0_P0P0_DP<0>")
	)
	(segment
		(start 292.140386 -103.126794)
		(end 302.08474 -105.115614)
		(width 0.1143)
		(layer "B.Cu")
		(net "UPI_CPU1_CPU0_P0P0_DP<0>")
	)
	(segment
		(start 229.50551 -104.997504)
		(end 230.626666 -105.053384)
		(width 0.1143)
		(layer "B.Cu")
		(net "UPI_CPU1_CPU0_P0P0_DP<0>")
	)
	(segment
		(start 161.213546 -86.6394)
		(end 169.645838 -96.275398)
		(width 0.1143)
		(layer "B.Cu")
		(net "UPI_CPU1_CPU0_P0P0_DP<0>")
	)
	(segment
		(start 199.105012 -110.660434)
		(end 200.459086 -110.479586)
		(width 0.1143)
		(layer "B.Cu")
		(net "UPI_CPU1_CPU0_P0P0_DP<0>")
	)
	(segment
		(start 278.725122 -105.529634)
		(end 283.317442 -104.611932)
		(width 0.1143)
		(layer "B.Cu")
		(net "UPI_CPU1_CPU0_P0P0_DP<0>")
	)
	(segment
		(start 302.08474 -105.115614)
		(end 304.301906 -104.549448)
		(width 0.1143)
		(layer "B.Cu")
		(net "UPI_CPU1_CPU0_P0P0_DP<0>")
	)
	(segment
		(start 299.748956 -73.440036)
		(end 299.74413 -73.4314)
		(width 0.0889)
		(layer "B.Cu")
		(net "UPI_CPU1_CPU0_P0P0_DP<0>")
	)
	(segment
		(start 142.541244 -57.390538)
		(end 142.637002 -57.486296)
		(width 0.0889)
		(layer "B.Cu")
		(net "UPI_CPU1_CPU0_P0P0_DP<0>")
	)
	(arc
		(start 299.748956 -72.049386)
		(mid 299.827293 -71.78673)
		(end 299.778674 -71.517002)
		(width 0.0889)
		(layer "B.Cu")
		(net "UPI_CPU1_CPU0_P0P0_DP<0>")
	)
	(arc
		(start 299.748956 -74.030586)
		(mid 299.828178 -73.741468)
		(end 299.755306 -73.450704)
		(width 0.0889)
		(layer "B.Cu")
		(net "UPI_CPU1_CPU0_P0P0_DP<0>")
	)
	(arc
		(start 299.74413 -73.4314)
		(mid 299.695375 -73.235048)
		(end 299.748956 -73.039986)
		(width 0.0889)
		(layer "B.Cu")
		(net "UPI_CPU1_CPU0_P0P0_DP<0>")
	)
	(arc
		(start 303.51857 -77.602588)
		(mid 303.32472 -77.546238)
		(end 303.183036 -77.402436)
		(width 0.0889)
		(layer "B.Cu")
		(net "UPI_CPU1_CPU0_P0P0_DP<0>")
	)
	(arc
		(start 301.465996 -76.411836)
		(mid 301.257388 -76.199904)
		(end 300.971966 -76.116434)
		(width 0.0889)
		(layer "B.Cu")
		(net "UPI_CPU1_CPU0_P0P0_DP<0>")
	)
	(arc
		(start 300.08449 -75.621388)
		(mid 299.746321 -75.41659)
		(end 299.748956 -75.021186)
		(width 0.0889)
		(layer "B.Cu")
		(net "UPI_CPU1_CPU0_P0P0_DP<0>")
	)
	(arc
		(start 300.607476 -75.916536)
		(mid 300.400472 -75.705672)
		(end 300.117256 -75.621388)
		(width 0.0889)
		(layer "B.Cu")
		(net "UPI_CPU1_CPU0_P0P0_DP<0>")
	)
	(arc
		(start 300.9392 -76.116434)
		(mid 300.747558 -76.059268)
		(end 300.607476 -75.916536)
		(width 0.0889)
		(layer "B.Cu")
		(net "UPI_CPU1_CPU0_P0P0_DP<0>")
	)
	(arc
		(start 304.403252 -78.097634)
		(mid 304.194618 -78.047962)
		(end 304.041556 -77.897736)
		(width 0.0889)
		(layer "B.Cu")
		(net "UPI_CPU1_CPU0_P0P0_DP<0>")
	)
	(arc
		(start 299.748956 -73.039986)
		(mid 299.828178 -72.750868)
		(end 299.755306 -72.460104)
		(width 0.0889)
		(layer "B.Cu")
		(net "UPI_CPU1_CPU0_P0P0_DP<0>")
	)
	(arc
		(start 301.80153 -76.611988)
		(mid 301.60768 -76.555638)
		(end 301.465996 -76.411836)
		(width 0.0889)
		(layer "B.Cu")
		(net "UPI_CPU1_CPU0_P0P0_DP<0>")
	)
	(arc
		(start 299.74413 -72.4408)
		(mid 299.695375 -72.244448)
		(end 299.748956 -72.049386)
		(width 0.0889)
		(layer "B.Cu")
		(net "UPI_CPU1_CPU0_P0P0_DP<0>")
	)
	(arc
		(start 303.183036 -77.402436)
		(mid 302.974428 -77.190504)
		(end 302.689006 -77.107034)
		(width 0.0889)
		(layer "B.Cu")
		(net "UPI_CPU1_CPU0_P0P0_DP<0>")
	)
	(arc
		(start 302.324516 -76.907136)
		(mid 302.117512 -76.696272)
		(end 301.834296 -76.611988)
		(width 0.0889)
		(layer "B.Cu")
		(net "UPI_CPU1_CPU0_P0P0_DP<0>")
	)
	(arc
		(start 302.65624 -77.107034)
		(mid 302.464598 -77.049868)
		(end 302.324516 -76.907136)
		(width 0.0889)
		(layer "B.Cu")
		(net "UPI_CPU1_CPU0_P0P0_DP<0>")
	)
	(arc
		(start 299.748956 -75.021186)
		(mid 299.828178 -74.732068)
		(end 299.755306 -74.441304)
		(width 0.0889)
		(layer "B.Cu")
		(net "UPI_CPU1_CPU0_P0P0_DP<0>")
	)
	(arc
		(start 299.74413 -74.422)
		(mid 299.695375 -74.225648)
		(end 299.748956 -74.030586)
		(width 0.0889)
		(layer "B.Cu")
		(net "UPI_CPU1_CPU0_P0P0_DP<0>")
	)
	(arc
		(start 304.041556 -77.897736)
		(mid 303.834552 -77.686872)
		(end 303.551336 -77.602588)
		(width 0.0889)
		(layer "B.Cu")
		(net "UPI_CPU1_CPU0_P0P0_DP<0>")
	)
	(segment
		(start 302.099726 -67.791584)
		(end 302.671226 -67.791584)
		(width 0.1143)
		(layer "F.Cu")
		(net "UPI_CPU1_CPU0_P0P0_DN<9>")
	)
	(segment
		(start 141.85011 -66.305938)
		(end 141.945106 -66.400934)
		(width 0.0889)
		(layer "F.Cu")
		(net "UPI_CPU1_CPU0_P0P0_DN<9>")
	)
	(segment
		(start 142.786354 -66.2813)
		(end 145.9865 -66.2813)
		(width 0.0889)
		(layer "F.Cu")
		(net "UPI_CPU1_CPU0_P0P0_DN<9>")
	)
	(segment
		(start 141.945106 -66.400934)
		(end 142.66672 -66.400934)
		(width 0.0889)
		(layer "F.Cu")
		(net "UPI_CPU1_CPU0_P0P0_DN<9>")
	)
	(segment
		(start 141.391894 -66.305938)
		(end 141.85011 -66.305938)
		(width 0.0889)
		(layer "F.Cu")
		(net "UPI_CPU1_CPU0_P0P0_DN<9>")
	)
	(segment
		(start 142.66672 -66.400934)
		(end 142.786354 -66.2813)
		(width 0.0889)
		(layer "F.Cu")
		(net "UPI_CPU1_CPU0_P0P0_DN<9>")
	)
	(segment
		(start 145.9865 -66.2813)
		(end 146.2024 -66.4972)
		(width 0.0889)
		(layer "F.Cu")
		(net "UPI_CPU1_CPU0_P0P0_DN<9>")
	)
	(via
		(at 161.070798 -102.775766)
		(size 0.508)
		(drill 0.254)
		(layers "F.Cu" "B.Cu")
		(net "UPI_CPU1_CPU0_P0P0_DN<9>")
	)
	(via
		(at 146.2024 -66.4972)
		(size 0.508)
		(drill 0.254)
		(layers "F.Cu" "B.Cu")
		(net "UPI_CPU1_CPU0_P0P0_DN<9>")
	)
	(via
		(at 302.671226 -67.791584)
		(size 0.508)
		(drill 0.254)
		(layers "F.Cu" "B.Cu")
		(net "UPI_CPU1_CPU0_P0P0_DN<9>")
	)
	(segment
		(start 146.408394 -66.291206)
		(end 146.2024 -66.4972)
		(width 0.1143)
		(layer "B.Cu")
		(net "UPI_CPU1_CPU0_P0P0_DN<9>")
	)
	(segment
		(start 150.478744 -69.056504)
		(end 147.7137 -66.291206)
		(width 0.1143)
		(layer "B.Cu")
		(net "UPI_CPU1_CPU0_P0P0_DN<9>")
	)
	(segment
		(start 262.898636 -113.051844)
		(end 283.106368 -115.10264)
		(width 0.1143)
		(layer "B.Cu")
		(net "UPI_CPU1_CPU0_P0P0_DN<9>")
	)
	(segment
		(start 306.8066 -69.6976)
		(end 306.658772 -69.549772)
		(width 0.0889)
		(layer "B.Cu")
		(net "UPI_CPU1_CPU0_P0P0_DN<9>")
	)
	(segment
		(start 308.1528 -70.612)
		(end 307.975 -70.4342)
		(width 0.0889)
		(layer "B.Cu")
		(net "UPI_CPU1_CPU0_P0P0_DN<9>")
	)
	(segment
		(start 291.125402 -115.62969)
		(end 292.127178 -115.83289)
		(width 0.1143)
		(layer "B.Cu")
		(net "UPI_CPU1_CPU0_P0P0_DN<9>")
	)
	(segment
		(start 308.61 -70.612)
		(end 308.5084 -70.5104)
		(width 0.0889)
		(layer "B.Cu")
		(net "UPI_CPU1_CPU0_P0P0_DN<9>")
	)
	(segment
		(start 306.108354 -69.183758)
		(end 306.102258 -69.183758)
		(width 0.0889)
		(layer "B.Cu")
		(net "UPI_CPU1_CPU0_P0P0_DN<9>")
	)
	(segment
		(start 308.862984 -70.511416)
		(end 308.7624 -70.612)
		(width 0.0889)
		(layer "B.Cu")
		(net "UPI_CPU1_CPU0_P0P0_DN<9>")
	)
	(segment
		(start 322.244974 -96.661732)
		(end 318.97066 -88.475566)
		(width 0.1143)
		(layer "B.Cu")
		(net "UPI_CPU1_CPU0_P0P0_DN<9>")
	)
	(segment
		(start 304.406046 -69.182234)
		(end 304.37328 -69.182234)
		(width 0.0889)
		(layer "B.Cu")
		(net "UPI_CPU1_CPU0_P0P0_DN<9>")
	)
	(segment
		(start 308.5084 -70.5104)
		(end 308.3814 -70.5104)
		(width 0.0889)
		(layer "B.Cu")
		(net "UPI_CPU1_CPU0_P0P0_DN<9>")
	)
	(segment
		(start 311.768744 -109.916976)
		(end 322.12915 -100.288598)
		(width 0.1143)
		(layer "B.Cu")
		(net "UPI_CPU1_CPU0_P0P0_DN<9>")
	)
	(segment
		(start 308.2798 -70.612)
		(end 308.1528 -70.612)
		(width 0.0889)
		(layer "B.Cu")
		(net "UPI_CPU1_CPU0_P0P0_DN<9>")
	)
	(segment
		(start 198.052182 -117.878098)
		(end 204.404214 -117.024404)
		(width 0.1143)
		(layer "B.Cu")
		(net "UPI_CPU1_CPU0_P0P0_DN<9>")
	)
	(segment
		(start 292.127178 -115.83289)
		(end 303.43602 -113.51768)
		(width 0.1143)
		(layer "B.Cu")
		(net "UPI_CPU1_CPU0_P0P0_DN<9>")
	)
	(segment
		(start 204.404214 -117.024404)
		(end 207.67675 -117.23878)
		(width 0.1143)
		(layer "B.Cu")
		(net "UPI_CPU1_CPU0_P0P0_DN<9>")
	)
	(segment
		(start 162.993832 -104.451912)
		(end 169.037 -108.839508)
		(width 0.1143)
		(layer "B.Cu")
		(net "UPI_CPU1_CPU0_P0P0_DN<9>")
	)
	(segment
		(start 161.13633 -102.856538)
		(end 161.620454 -103.454708)
		(width 0.1143)
		(layer "B.Cu")
		(net "UPI_CPU1_CPU0_P0P0_DN<9>")
	)
	(segment
		(start 169.037 -108.839508)
		(end 169.164254 -108.931964)
		(width 0.1143)
		(layer "B.Cu")
		(net "UPI_CPU1_CPU0_P0P0_DN<9>")
	)
	(segment
		(start 309.142384 -70.610984)
		(end 309.042816 -70.511416)
		(width 0.0889)
		(layer "B.Cu")
		(net "UPI_CPU1_CPU0_P0P0_DN<9>")
	)
	(segment
		(start 307.975 -70.4342)
		(end 307.975 -70.3072)
		(width 0.0889)
		(layer "B.Cu")
		(net "UPI_CPU1_CPU0_P0P0_DN<9>")
	)
	(segment
		(start 309.3466 -70.5866)
		(end 309.322216 -70.610984)
		(width 0.0889)
		(layer "B.Cu")
		(net "UPI_CPU1_CPU0_P0P0_DN<9>")
	)
	(segment
		(start 309.68442 -70.593204)
		(end 309.68315 -70.5866)
		(width 0.1143)
		(layer "B.Cu")
		(net "UPI_CPU1_CPU0_P0P0_DN<9>")
	)
	(segment
		(start 322.12915 -100.288598)
		(end 322.179188 -98.722688)
		(width 0.1143)
		(layer "B.Cu")
		(net "UPI_CPU1_CPU0_P0P0_DN<9>")
	)
	(segment
		(start 285.83636 -114.556794)
		(end 291.125402 -115.62969)
		(width 0.1143)
		(layer "B.Cu")
		(net "UPI_CPU1_CPU0_P0P0_DN<9>")
	)
	(segment
		(start 307.975 -70.3072)
		(end 307.848 -70.1802)
		(width 0.0889)
		(layer "B.Cu")
		(net "UPI_CPU1_CPU0_P0P0_DN<9>")
	)
	(segment
		(start 306.658772 -69.549772)
		(end 306.617116 -69.477636)
		(width 0.0889)
		(layer "B.Cu")
		(net "UPI_CPU1_CPU0_P0P0_DN<9>")
	)
	(segment
		(start 283.106368 -115.10264)
		(end 285.83636 -114.556794)
		(width 0.1143)
		(layer "B.Cu")
		(net "UPI_CPU1_CPU0_P0P0_DN<9>")
	)
	(segment
		(start 161.070798 -102.775766)
		(end 160.678114 -102.290626)
		(width 0.1143)
		(layer "B.Cu")
		(net "UPI_CPU1_CPU0_P0P0_DN<9>")
	)
	(segment
		(start 303.43602 -113.51768)
		(end 303.46269 -113.512346)
		(width 0.1143)
		(layer "B.Cu")
		(net "UPI_CPU1_CPU0_P0P0_DN<9>")
	)
	(segment
		(start 305.26482 -69.677534)
		(end 305.228752 -69.677534)
		(width 0.0889)
		(layer "B.Cu")
		(net "UPI_CPU1_CPU0_P0P0_DN<9>")
	)
	(segment
		(start 303.46269 -113.512346)
		(end 308.049168 -111.909606)
		(width 0.1143)
		(layer "B.Cu")
		(net "UPI_CPU1_CPU0_P0P0_DN<9>")
	)
	(segment
		(start 194.652646 -117.729254)
		(end 198.052182 -117.878098)
		(width 0.1143)
		(layer "B.Cu")
		(net "UPI_CPU1_CPU0_P0P0_DN<9>")
	)
	(segment
		(start 302.689006 -68.191634)
		(end 302.65624 -68.191634)
		(width 0.0889)
		(layer "B.Cu")
		(net "UPI_CPU1_CPU0_P0P0_DN<9>")
	)
	(segment
		(start 147.7137 -66.291206)
		(end 146.408394 -66.291206)
		(width 0.1143)
		(layer "B.Cu")
		(net "UPI_CPU1_CPU0_P0P0_DN<9>")
	)
	(segment
		(start 318.800226 -81.915)
		(end 318.761872 -80.434434)
		(width 0.1143)
		(layer "B.Cu")
		(net "UPI_CPU1_CPU0_P0P0_DN<9>")
	)
	(segment
		(start 179.569618 -113.374932)
		(end 185.340752 -113.736882)
		(width 0.1143)
		(layer "B.Cu")
		(net "UPI_CPU1_CPU0_P0P0_DN<9>")
	)
	(segment
		(start 226.068128 -113.546128)
		(end 248.912888 -114.69116)
		(width 0.1143)
		(layer "B.Cu")
		(net "UPI_CPU1_CPU0_P0P0_DN<9>")
	)
	(segment
		(start 308.049168 -111.909606)
		(end 311.768744 -109.916976)
		(width 0.1143)
		(layer "B.Cu")
		(net "UPI_CPU1_CPU0_P0P0_DN<9>")
	)
	(segment
		(start 169.164254 -108.931964)
		(end 170.894248 -110.993682)
		(width 0.1143)
		(layer "B.Cu")
		(net "UPI_CPU1_CPU0_P0P0_DN<9>")
	)
	(segment
		(start 161.070798 -102.775766)
		(end 161.13633 -102.856538)
		(width 0.1143)
		(layer "B.Cu")
		(net "UPI_CPU1_CPU0_P0P0_DN<9>")
	)
	(segment
		(start 318.97066 -88.475566)
		(end 318.800226 -81.915)
		(width 0.1143)
		(layer "B.Cu")
		(net "UPI_CPU1_CPU0_P0P0_DN<9>")
	)
	(segment
		(start 302.37811 -67.622674)
		(end 302.671226 -67.791584)
		(width 0.0889)
		(layer "B.Cu")
		(net "UPI_CPU1_CPU0_P0P0_DN<9>")
	)
	(segment
		(start 307.721 -70.1802)
		(end 307.2384 -69.6976)
		(width 0.0889)
		(layer "B.Cu")
		(net "UPI_CPU1_CPU0_P0P0_DN<9>")
	)
	(segment
		(start 314.195206 -72.24141)
		(end 309.68442 -70.593204)
		(width 0.1143)
		(layer "B.Cu")
		(net "UPI_CPU1_CPU0_P0P0_DN<9>")
	)
	(segment
		(start 172.410882 -111.868966)
		(end 173.723554 -112.626648)
		(width 0.1143)
		(layer "B.Cu")
		(net "UPI_CPU1_CPU0_P0P0_DN<9>")
	)
	(segment
		(start 161.620454 -103.454708)
		(end 162.993832 -104.451912)
		(width 0.1143)
		(layer "B.Cu")
		(net "UPI_CPU1_CPU0_P0P0_DN<9>")
	)
	(segment
		(start 187.450984 -115.307618)
		(end 194.652646 -117.729254)
		(width 0.1143)
		(layer "B.Cu")
		(net "UPI_CPU1_CPU0_P0P0_DN<9>")
	)
	(segment
		(start 307.2384 -69.6976)
		(end 306.8066 -69.6976)
		(width 0.0889)
		(layer "B.Cu")
		(net "UPI_CPU1_CPU0_P0P0_DN<9>")
	)
	(segment
		(start 309.042816 -70.511416)
		(end 308.862984 -70.511416)
		(width 0.0889)
		(layer "B.Cu")
		(net "UPI_CPU1_CPU0_P0P0_DN<9>")
	)
	(segment
		(start 207.67675 -117.23878)
		(end 215.1634 -115.735608)
		(width 0.1143)
		(layer "B.Cu")
		(net "UPI_CPU1_CPU0_P0P0_DN<9>")
	)
	(segment
		(start 175.320452 -113.108486)
		(end 179.569618 -113.374932)
		(width 0.1143)
		(layer "B.Cu")
		(net "UPI_CPU1_CPU0_P0P0_DN<9>")
	)
	(segment
		(start 173.723554 -112.626648)
		(end 175.320452 -113.108486)
		(width 0.1143)
		(layer "B.Cu")
		(net "UPI_CPU1_CPU0_P0P0_DN<9>")
	)
	(segment
		(start 308.7624 -70.612)
		(end 308.61 -70.612)
		(width 0.0889)
		(layer "B.Cu")
		(net "UPI_CPU1_CPU0_P0P0_DN<9>")
	)
	(segment
		(start 187.199016 -115.120166)
		(end 187.450984 -115.307618)
		(width 0.1143)
		(layer "B.Cu")
		(net "UPI_CPU1_CPU0_P0P0_DN<9>")
	)
	(segment
		(start 248.912888 -114.69116)
		(end 262.898636 -113.051844)
		(width 0.1143)
		(layer "B.Cu")
		(net "UPI_CPU1_CPU0_P0P0_DN<9>")
	)
	(segment
		(start 160.678114 -102.290626)
		(end 159.684212 -97.613978)
		(width 0.1143)
		(layer "B.Cu")
		(net "UPI_CPU1_CPU0_P0P0_DN<9>")
	)
	(segment
		(start 322.179188 -98.722688)
		(end 322.244974 -96.661732)
		(width 0.1143)
		(layer "B.Cu")
		(net "UPI_CPU1_CPU0_P0P0_DN<9>")
	)
	(segment
		(start 155.152852 -92.435934)
		(end 150.478744 -69.056504)
		(width 0.1143)
		(layer "B.Cu")
		(net "UPI_CPU1_CPU0_P0P0_DN<9>")
	)
	(segment
		(start 159.684212 -97.613978)
		(end 155.152852 -92.435934)
		(width 0.1143)
		(layer "B.Cu")
		(net "UPI_CPU1_CPU0_P0P0_DN<9>")
	)
	(segment
		(start 307.848 -70.1802)
		(end 307.721 -70.1802)
		(width 0.0889)
		(layer "B.Cu")
		(net "UPI_CPU1_CPU0_P0P0_DN<9>")
	)
	(segment
		(start 185.340752 -113.736882)
		(end 187.199016 -115.120166)
		(width 0.1143)
		(layer "B.Cu")
		(net "UPI_CPU1_CPU0_P0P0_DN<9>")
	)
	(segment
		(start 309.68315 -70.5866)
		(end 309.3466 -70.5866)
		(width 0.1143)
		(layer "B.Cu")
		(net "UPI_CPU1_CPU0_P0P0_DN<9>")
	)
	(segment
		(start 303.551336 -68.687188)
		(end 303.51857 -68.687188)
		(width 0.0889)
		(layer "B.Cu")
		(net "UPI_CPU1_CPU0_P0P0_DN<9>")
	)
	(segment
		(start 309.322216 -70.610984)
		(end 309.142384 -70.610984)
		(width 0.0889)
		(layer "B.Cu")
		(net "UPI_CPU1_CPU0_P0P0_DN<9>")
	)
	(segment
		(start 308.3814 -70.5104)
		(end 308.2798 -70.612)
		(width 0.0889)
		(layer "B.Cu")
		(net "UPI_CPU1_CPU0_P0P0_DN<9>")
	)
	(segment
		(start 318.761872 -80.434434)
		(end 314.195206 -72.24141)
		(width 0.1143)
		(layer "B.Cu")
		(net "UPI_CPU1_CPU0_P0P0_DN<9>")
	)
	(segment
		(start 302.29937 -67.64401)
		(end 302.37811 -67.622674)
		(width 0.0889)
		(layer "B.Cu")
		(net "UPI_CPU1_CPU0_P0P0_DN<9>")
	)
	(segment
		(start 170.894248 -110.993682)
		(end 172.410882 -111.868966)
		(width 0.1143)
		(layer "B.Cu")
		(net "UPI_CPU1_CPU0_P0P0_DN<9>")
	)
	(segment
		(start 215.1634 -115.735608)
		(end 226.068128 -113.546128)
		(width 0.1143)
		(layer "B.Cu")
		(net "UPI_CPU1_CPU0_P0P0_DN<9>")
	)
	(arc
		(start 303.51857 -68.687188)
		(mid 303.32472 -68.630838)
		(end 303.183036 -68.487036)
		(width 0.0889)
		(layer "B.Cu")
		(net "UPI_CPU1_CPU0_P0P0_DN<9>")
	)
	(arc
		(start 304.900076 -69.477636)
		(mid 304.691468 -69.265704)
		(end 304.406046 -69.182234)
		(width 0.0889)
		(layer "B.Cu")
		(net "UPI_CPU1_CPU0_P0P0_DN<9>")
	)
	(arc
		(start 304.041556 -68.982336)
		(mid 303.834552 -68.771472)
		(end 303.551336 -68.687188)
		(width 0.0889)
		(layer "B.Cu")
		(net "UPI_CPU1_CPU0_P0P0_DN<9>")
	)
	(arc
		(start 306.617116 -69.477636)
		(mid 306.402133 -69.26248)
		(end 306.108354 -69.183758)
		(width 0.0889)
		(layer "B.Cu")
		(net "UPI_CPU1_CPU0_P0P0_DN<9>")
	)
	(arc
		(start 305.593496 -69.477636)
		(mid 305.454752 -69.619669)
		(end 305.26482 -69.677534)
		(width 0.0889)
		(layer "B.Cu")
		(net "UPI_CPU1_CPU0_P0P0_DN<9>")
	)
	(arc
		(start 306.102258 -69.183758)
		(mid 305.808498 -69.262513)
		(end 305.593496 -69.477636)
		(width 0.0889)
		(layer "B.Cu")
		(net "UPI_CPU1_CPU0_P0P0_DN<9>")
	)
	(arc
		(start 303.183036 -68.487036)
		(mid 302.974428 -68.275104)
		(end 302.689006 -68.191634)
		(width 0.0889)
		(layer "B.Cu")
		(net "UPI_CPU1_CPU0_P0P0_DN<9>")
	)
	(arc
		(start 305.228752 -69.677534)
		(mid 305.038823 -69.619664)
		(end 304.900076 -69.477636)
		(width 0.0889)
		(layer "B.Cu")
		(net "UPI_CPU1_CPU0_P0P0_DN<9>")
	)
	(arc
		(start 302.27651 -67.857624)
		(mid 302.273338 -67.749254)
		(end 302.29937 -67.64401)
		(width 0.0889)
		(layer "B.Cu")
		(net "UPI_CPU1_CPU0_P0P0_DN<9>")
	)
	(arc
		(start 304.37328 -69.182234)
		(mid 304.181638 -69.125068)
		(end 304.041556 -68.982336)
		(width 0.0889)
		(layer "B.Cu")
		(net "UPI_CPU1_CPU0_P0P0_DN<9>")
	)
	(arc
		(start 302.65624 -68.191634)
		(mid 302.406953 -68.092207)
		(end 302.27651 -67.857624)
		(width 0.0889)
		(layer "B.Cu")
		(net "UPI_CPU1_CPU0_P0P0_DN<9>")
	)
	(segment
		(start 301.241206 -68.287138)
		(end 301.812706 -68.287138)
		(width 0.1143)
		(layer "F.Cu")
		(net "UPI_CPU1_CPU0_P0P0_DN<8>")
	)
	(segment
		(start 141.391894 -65.315338)
		(end 141.963394 -65.315338)
		(width 0.1143)
		(layer "F.Cu")
		(net "UPI_CPU1_CPU0_P0P0_DN<8>")
	)
	(via
		(at 301.812706 -68.287138)
		(size 0.508)
		(drill 0.254)
		(layers "F.Cu" "B.Cu")
		(net "UPI_CPU1_CPU0_P0P0_DN<8>")
	)
	(via
		(at 141.963394 -65.315338)
		(size 0.508)
		(drill 0.254)
		(layers "F.Cu" "B.Cu")
		(net "UPI_CPU1_CPU0_P0P0_DN<8>")
	)
	(segment
		(start 161.854134 -102.194868)
		(end 162.306508 -102.752652)
		(width 0.1143)
		(layer "B.Cu")
		(net "UPI_CPU1_CPU0_P0P0_DN<8>")
	)
	(segment
		(start 187.810902 -114.610896)
		(end 194.836288 -116.97335)
		(width 0.1143)
		(layer "B.Cu")
		(net "UPI_CPU1_CPU0_P0P0_DN<8>")
	)
	(segment
		(start 311.12587 -109.11078)
		(end 321.016122 -99.796092)
		(width 0.1143)
		(layer "B.Cu")
		(net "UPI_CPU1_CPU0_P0P0_DN<8>")
	)
	(segment
		(start 321.110356 -96.841564)
		(end 318.1985 -89.560908)
		(width 0.1143)
		(layer "B.Cu")
		(net "UPI_CPU1_CPU0_P0P0_DN<8>")
	)
	(segment
		(start 306.49926 -70.3199)
		(end 306.352194 -70.172834)
		(width 0.0889)
		(layer "B.Cu")
		(net "UPI_CPU1_CPU0_P0P0_DN<8>")
	)
	(segment
		(start 318.1985 -89.560908)
		(end 317.8556 -88.703404)
		(width 0.1143)
		(layer "B.Cu")
		(net "UPI_CPU1_CPU0_P0P0_DN<8>")
	)
	(segment
		(start 144.081754 -64.9859)
		(end 147.515834 -64.9859)
		(width 0.1143)
		(layer "B.Cu")
		(net "UPI_CPU1_CPU0_P0P0_DN<8>")
	)
	(segment
		(start 306.800504 -111.371888)
		(end 311.12587 -109.11078)
		(width 0.1143)
		(layer "B.Cu")
		(net "UPI_CPU1_CPU0_P0P0_DN<8>")
	)
	(segment
		(start 175.534574 -112.146588)
		(end 185.335926 -112.76711)
		(width 0.1143)
		(layer "B.Cu")
		(net "UPI_CPU1_CPU0_P0P0_DN<8>")
	)
	(segment
		(start 194.836288 -116.97335)
		(end 198.049134 -117.105684)
		(width 0.1143)
		(layer "B.Cu")
		(net "UPI_CPU1_CPU0_P0P0_DN<8>")
	)
	(segment
		(start 309.96509 -71.917814)
		(end 309.222394 -71.7677)
		(width 0.0889)
		(layer "B.Cu")
		(net "UPI_CPU1_CPU0_P0P0_DN<8>")
	)
	(segment
		(start 310.334406 -72.018144)
		(end 310.28132 -72.026526)
		(width 0.0889)
		(layer "B.Cu")
		(net "UPI_CPU1_CPU0_P0P0_DN<8>")
	)
	(segment
		(start 304.409856 -70.172834)
		(end 304.37709 -70.172834)
		(width 0.0889)
		(layer "B.Cu")
		(net "UPI_CPU1_CPU0_P0P0_DN<8>")
	)
	(segment
		(start 171.438062 -110.135162)
		(end 174.24781 -111.757714)
		(width 0.1143)
		(layer "B.Cu")
		(net "UPI_CPU1_CPU0_P0P0_DN<8>")
	)
	(segment
		(start 317.648336 -80.719422)
		(end 313.472576 -73.227438)
		(width 0.1143)
		(layer "B.Cu")
		(net "UPI_CPU1_CPU0_P0P0_DN<8>")
	)
	(segment
		(start 247.583706 -108.553504)
		(end 248.025412 -108.536994)
		(width 0.1143)
		(layer "B.Cu")
		(net "UPI_CPU1_CPU0_P0P0_DN<8>")
	)
	(segment
		(start 309.222394 -71.7677)
		(end 308.425342 -71.7677)
		(width 0.0889)
		(layer "B.Cu")
		(net "UPI_CPU1_CPU0_P0P0_DN<8>")
	)
	(segment
		(start 311.866534 -72.60844)
		(end 310.334406 -72.018144)
		(width 0.1143)
		(layer "B.Cu")
		(net "UPI_CPU1_CPU0_P0P0_DN<8>")
	)
	(segment
		(start 313.472576 -73.227438)
		(end 311.866534 -72.608694)
		(width 0.1143)
		(layer "B.Cu")
		(net "UPI_CPU1_CPU0_P0P0_DN<8>")
	)
	(segment
		(start 258.377182 -111.620046)
		(end 282.86456 -114.10569)
		(width 0.1143)
		(layer "B.Cu")
		(net "UPI_CPU1_CPU0_P0P0_DN<8>")
	)
	(segment
		(start 285.25724 -113.627662)
		(end 291.125402 -114.822732)
		(width 0.1143)
		(layer "B.Cu")
		(net "UPI_CPU1_CPU0_P0P0_DN<8>")
	)
	(segment
		(start 185.335926 -112.76711)
		(end 187.810902 -114.610896)
		(width 0.1143)
		(layer "B.Cu")
		(net "UPI_CPU1_CPU0_P0P0_DN<8>")
	)
	(segment
		(start 162.306508 -102.752652)
		(end 169.828972 -108.218478)
		(width 0.1143)
		(layer "B.Cu")
		(net "UPI_CPU1_CPU0_P0P0_DN<8>")
	)
	(segment
		(start 292.17493 -115.036346)
		(end 302.511206 -112.902492)
		(width 0.1143)
		(layer "B.Cu")
		(net "UPI_CPU1_CPU0_P0P0_DN<8>")
	)
	(segment
		(start 308.425342 -71.7677)
		(end 306.977542 -70.3199)
		(width 0.0889)
		(layer "B.Cu")
		(net "UPI_CPU1_CPU0_P0P0_DN<8>")
	)
	(segment
		(start 248.025412 -108.536994)
		(end 258.377182 -111.620046)
		(width 0.1143)
		(layer "B.Cu")
		(net "UPI_CPU1_CPU0_P0P0_DN<8>")
	)
	(segment
		(start 141.8463 -64.915288)
		(end 141.97838 -64.915288)
		(width 0.0889)
		(layer "B.Cu")
		(net "UPI_CPU1_CPU0_P0P0_DN<8>")
	)
	(segment
		(start 311.866534 -72.608694)
		(end 311.866534 -72.60844)
		(width 0.1143)
		(layer "B.Cu")
		(net "UPI_CPU1_CPU0_P0P0_DN<8>")
	)
	(segment
		(start 302.689006 -69.182234)
		(end 302.65624 -69.182234)
		(width 0.0889)
		(layer "B.Cu")
		(net "UPI_CPU1_CPU0_P0P0_DN<8>")
	)
	(segment
		(start 235.895896 -113.069878)
		(end 247.583706 -108.553504)
		(width 0.1143)
		(layer "B.Cu")
		(net "UPI_CPU1_CPU0_P0P0_DN<8>")
	)
	(segment
		(start 198.049134 -117.105684)
		(end 205.403704 -116.11991)
		(width 0.1143)
		(layer "B.Cu")
		(net "UPI_CPU1_CPU0_P0P0_DN<8>")
	)
	(segment
		(start 143.29283 -65.419224)
		(end 143.75257 -64.959484)
		(width 0.0889)
		(layer "B.Cu")
		(net "UPI_CPU1_CPU0_P0P0_DN<8>")
	)
	(segment
		(start 321.016122 -99.796092)
		(end 321.110356 -96.841564)
		(width 0.1143)
		(layer "B.Cu")
		(net "UPI_CPU1_CPU0_P0P0_DN<8>")
	)
	(segment
		(start 155.822396 -91.731592)
		(end 160.779206 -97.396046)
		(width 0.1143)
		(layer "B.Cu")
		(net "UPI_CPU1_CPU0_P0P0_DN<8>")
	)
	(segment
		(start 301.87773 -68.690236)
		(end 301.812706 -68.625212)
		(width 0.0889)
		(layer "B.Cu")
		(net "UPI_CPU1_CPU0_P0P0_DN<8>")
	)
	(segment
		(start 142.836138 -65.419224)
		(end 143.29283 -65.419224)
		(width 0.0889)
		(layer "B.Cu")
		(net "UPI_CPU1_CPU0_P0P0_DN<8>")
	)
	(segment
		(start 306.977542 -70.3199)
		(end 306.49926 -70.3199)
		(width 0.0889)
		(layer "B.Cu")
		(net "UPI_CPU1_CPU0_P0P0_DN<8>")
	)
	(segment
		(start 151.211026 -68.681346)
		(end 155.822396 -91.731592)
		(width 0.1143)
		(layer "B.Cu")
		(net "UPI_CPU1_CPU0_P0P0_DN<8>")
	)
	(segment
		(start 143.75257 -64.959484)
		(end 144.055338 -64.959484)
		(width 0.0889)
		(layer "B.Cu")
		(net "UPI_CPU1_CPU0_P0P0_DN<8>")
	)
	(segment
		(start 291.125402 -114.822732)
		(end 292.17493 -115.036346)
		(width 0.1143)
		(layer "B.Cu")
		(net "UPI_CPU1_CPU0_P0P0_DN<8>")
	)
	(segment
		(start 317.8556 -88.703404)
		(end 317.648336 -80.719422)
		(width 0.1143)
		(layer "B.Cu")
		(net "UPI_CPU1_CPU0_P0P0_DN<8>")
	)
	(segment
		(start 306.352194 -70.172834)
		(end 306.083716 -70.172834)
		(width 0.0889)
		(layer "B.Cu")
		(net "UPI_CPU1_CPU0_P0P0_DN<8>")
	)
	(segment
		(start 141.963394 -65.315338)
		(end 141.8463 -65.315338)
		(width 0.0889)
		(layer "B.Cu")
		(net "UPI_CPU1_CPU0_P0P0_DN<8>")
	)
	(segment
		(start 144.055338 -64.959484)
		(end 144.081754 -64.9859)
		(width 0.0889)
		(layer "B.Cu")
		(net "UPI_CPU1_CPU0_P0P0_DN<8>")
	)
	(segment
		(start 161.714942 -101.797104)
		(end 161.854134 -102.194868)
		(width 0.1143)
		(layer "B.Cu")
		(net "UPI_CPU1_CPU0_P0P0_DN<8>")
	)
	(segment
		(start 174.24781 -111.757714)
		(end 175.534574 -112.146588)
		(width 0.1143)
		(layer "B.Cu")
		(net "UPI_CPU1_CPU0_P0P0_DN<8>")
	)
	(segment
		(start 302.511206 -112.902492)
		(end 306.800504 -111.371888)
		(width 0.1143)
		(layer "B.Cu")
		(net "UPI_CPU1_CPU0_P0P0_DN<8>")
	)
	(segment
		(start 303.551336 -69.677534)
		(end 303.511712 -69.677534)
		(width 0.0889)
		(layer "B.Cu")
		(net "UPI_CPU1_CPU0_P0P0_DN<8>")
	)
	(segment
		(start 205.403704 -116.11991)
		(end 207.614012 -116.264436)
		(width 0.1143)
		(layer "B.Cu")
		(net "UPI_CPU1_CPU0_P0P0_DN<8>")
	)
	(segment
		(start 147.515834 -64.9859)
		(end 151.211026 -68.681346)
		(width 0.1143)
		(layer "B.Cu")
		(net "UPI_CPU1_CPU0_P0P0_DN<8>")
	)
	(segment
		(start 160.779206 -97.396046)
		(end 161.714942 -101.797104)
		(width 0.1143)
		(layer "B.Cu")
		(net "UPI_CPU1_CPU0_P0P0_DN<8>")
	)
	(segment
		(start 207.614012 -116.264436)
		(end 225.994722 -112.573562)
		(width 0.1143)
		(layer "B.Cu")
		(net "UPI_CPU1_CPU0_P0P0_DN<8>")
	)
	(segment
		(start 282.86456 -114.10569)
		(end 285.25724 -113.627662)
		(width 0.1143)
		(layer "B.Cu")
		(net "UPI_CPU1_CPU0_P0P0_DN<8>")
	)
	(segment
		(start 310.28132 -72.026526)
		(end 309.96509 -71.917814)
		(width 0.0889)
		(layer "B.Cu")
		(net "UPI_CPU1_CPU0_P0P0_DN<8>")
	)
	(segment
		(start 169.828972 -108.218478)
		(end 171.438062 -110.135162)
		(width 0.1143)
		(layer "B.Cu")
		(net "UPI_CPU1_CPU0_P0P0_DN<8>")
	)
	(segment
		(start 301.812706 -68.625212)
		(end 301.812706 -68.287138)
		(width 0.0889)
		(layer "B.Cu")
		(net "UPI_CPU1_CPU0_P0P0_DN<8>")
	)
	(segment
		(start 225.994722 -112.573562)
		(end 235.895896 -113.069878)
		(width 0.1143)
		(layer "B.Cu")
		(net "UPI_CPU1_CPU0_P0P0_DN<8>")
	)
	(arc
		(start 302.65624 -69.182234)
		(mid 302.464598 -69.125068)
		(end 302.324516 -68.982336)
		(width 0.0889)
		(layer "B.Cu")
		(net "UPI_CPU1_CPU0_P0P0_DN<8>")
	)
	(arc
		(start 304.37709 -70.172834)
		(mid 304.18324 -70.116484)
		(end 304.041556 -69.972682)
		(width 0.0889)
		(layer "B.Cu")
		(net "UPI_CPU1_CPU0_P0P0_DN<8>")
	)
	(arc
		(start 302.324516 -68.982336)
		(mid 302.135988 -68.782963)
		(end 301.87773 -68.690236)
		(width 0.0889)
		(layer "B.Cu")
		(net "UPI_CPU1_CPU0_P0P0_DN<8>")
	)
	(arc
		(start 142.310104 -65.115186)
		(mid 142.5324 -65.337677)
		(end 142.836138 -65.419224)
		(width 0.0889)
		(layer "B.Cu")
		(net "UPI_CPU1_CPU0_P0P0_DN<8>")
	)
	(arc
		(start 303.511712 -69.677534)
		(mid 303.321783 -69.619664)
		(end 303.183036 -69.477636)
		(width 0.0889)
		(layer "B.Cu")
		(net "UPI_CPU1_CPU0_P0P0_DN<8>")
	)
	(arc
		(start 304.041556 -69.972682)
		(mid 303.834552 -69.761818)
		(end 303.551336 -69.677534)
		(width 0.0889)
		(layer "B.Cu")
		(net "UPI_CPU1_CPU0_P0P0_DN<8>")
	)
	(arc
		(start 306.083716 -70.172834)
		(mid 305.800499 -70.257115)
		(end 305.593496 -70.467982)
		(width 0.0889)
		(layer "B.Cu")
		(net "UPI_CPU1_CPU0_P0P0_DN<8>")
	)
	(arc
		(start 303.183036 -69.477636)
		(mid 302.974428 -69.265704)
		(end 302.689006 -69.182234)
		(width 0.0889)
		(layer "B.Cu")
		(net "UPI_CPU1_CPU0_P0P0_DN<8>")
	)
	(arc
		(start 305.593496 -70.467982)
		(mid 305.246786 -70.668293)
		(end 304.900076 -70.467982)
		(width 0.0889)
		(layer "B.Cu")
		(net "UPI_CPU1_CPU0_P0P0_DN<8>")
	)
	(arc
		(start 304.900076 -70.467982)
		(mid 304.693072 -70.257118)
		(end 304.409856 -70.172834)
		(width 0.0889)
		(layer "B.Cu")
		(net "UPI_CPU1_CPU0_P0P0_DN<8>")
	)
	(arc
		(start 141.8463 -65.315338)
		(mid 141.646402 -65.11544)
		(end 141.8463 -64.915288)
		(width 0.0889)
		(layer "B.Cu")
		(net "UPI_CPU1_CPU0_P0P0_DN<8>")
	)
	(arc
		(start 141.97838 -64.915288)
		(mid 142.170022 -64.972454)
		(end 142.310104 -65.115186)
		(width 0.0889)
		(layer "B.Cu")
		(net "UPI_CPU1_CPU0_P0P0_DN<8>")
	)
	(segment
		(start 141.391894 -63.334138)
		(end 141.963394 -63.334138)
		(width 0.1143)
		(layer "F.Cu")
		(net "UPI_CPU1_CPU0_P0P0_DN<7>")
	)
	(segment
		(start 299.524166 -69.277738)
		(end 300.095666 -69.277738)
		(width 0.1143)
		(layer "F.Cu")
		(net "UPI_CPU1_CPU0_P0P0_DN<7>")
	)
	(via
		(at 300.095666 -69.277738)
		(size 0.508)
		(drill 0.254)
		(layers "F.Cu" "B.Cu")
		(net "UPI_CPU1_CPU0_P0P0_DN<7>")
	)
	(via
		(at 316.595252 -93.128084)
		(size 0.508)
		(drill 0.254)
		(layers "F.Cu" "B.Cu")
		(net "UPI_CPU1_CPU0_P0P0_DN<7>")
	)
	(via
		(at 141.963394 -63.334138)
		(size 0.508)
		(drill 0.254)
		(layers "F.Cu" "B.Cu")
		(net "UPI_CPU1_CPU0_P0P0_DN<7>")
	)
	(segment
		(start 163.916106 -101.553264)
		(end 164.092636 -101.735636)
		(width 0.1143)
		(layer "B.Cu")
		(net "UPI_CPU1_CPU0_P0P0_DN<7>")
	)
	(segment
		(start 316.595252 -93.128084)
		(end 316.301374 -81.815178)
		(width 0.1143)
		(layer "B.Cu")
		(net "UPI_CPU1_CPU0_P0P0_DN<7>")
	)
	(segment
		(start 307.55336 -72.17156)
		(end 307.231288 -71.849488)
		(width 0.0889)
		(layer "B.Cu")
		(net "UPI_CPU1_CPU0_P0P0_DN<7>")
	)
	(segment
		(start 316.301374 -81.815178)
		(end 316.300866 -81.814924)
		(width 0.1143)
		(layer "B.Cu")
		(net "UPI_CPU1_CPU0_P0P0_DN<7>")
	)
	(segment
		(start 305.247294 -71.849488)
		(end 305.246278 -71.849488)
		(width 0.0889)
		(layer "B.Cu")
		(net "UPI_CPU1_CPU0_P0P0_DN<7>")
	)
	(segment
		(start 282.766262 -112.879886)
		(end 286.05988 -112.221518)
		(width 0.1143)
		(layer "B.Cu")
		(net "UPI_CPU1_CPU0_P0P0_DN<7>")
	)
	(segment
		(start 286.05988 -112.221518)
		(end 290.376864 -108.94441)
		(width 0.1143)
		(layer "B.Cu")
		(net "UPI_CPU1_CPU0_P0P0_DN<7>")
	)
	(segment
		(start 303.544732 -70.858888)
		(end 303.516792 -70.858888)
		(width 0.0889)
		(layer "B.Cu")
		(net "UPI_CPU1_CPU0_P0P0_DN<7>")
	)
	(segment
		(start 309.31231 -73.1393)
		(end 308.484524 -73.1393)
		(width 0.1143)
		(layer "B.Cu")
		(net "UPI_CPU1_CPU0_P0P0_DN<7>")
	)
	(segment
		(start 165.496494 -103.184706)
		(end 166.170356 -103.879904)
		(width 0.1143)
		(layer "B.Cu")
		(net "UPI_CPU1_CPU0_P0P0_DN<7>")
	)
	(segment
		(start 308.484524 -73.1393)
		(end 308.2798 -72.934576)
		(width 0.1143)
		(layer "B.Cu")
		(net "UPI_CPU1_CPU0_P0P0_DN<7>")
	)
	(segment
		(start 316.653926 -95.390716)
		(end 316.595252 -93.128084)
		(width 0.1143)
		(layer "B.Cu")
		(net "UPI_CPU1_CPU0_P0P0_DN<7>")
	)
	(segment
		(start 306.160932 -71.354188)
		(end 306.104544 -71.354188)
		(width 0.0889)
		(layer "B.Cu")
		(net "UPI_CPU1_CPU0_P0P0_DN<7>")
	)
	(segment
		(start 316.004702 -96.294702)
		(end 316.653926 -95.390716)
		(width 0.1143)
		(layer "B.Cu")
		(net "UPI_CPU1_CPU0_P0P0_DN<7>")
	)
	(segment
		(start 206.36865 -114.971068)
		(end 207.532224 -115.047268)
		(width 0.1143)
		(layer "B.Cu")
		(net "UPI_CPU1_CPU0_P0P0_DN<7>")
	)
	(segment
		(start 143.180816 -64.229234)
		(end 143.683228 -63.726822)
		(width 0.0889)
		(layer "B.Cu")
		(net "UPI_CPU1_CPU0_P0P0_DN<7>")
	)
	(segment
		(start 142.02537 -63.734188)
		(end 142.166594 -63.734188)
		(width 0.0889)
		(layer "B.Cu")
		(net "UPI_CPU1_CPU0_P0P0_DN<7>")
	)
	(segment
		(start 292.143434 -108.541566)
		(end 303.623472 -111.13516)
		(width 0.1143)
		(layer "B.Cu")
		(net "UPI_CPU1_CPU0_P0P0_DN<7>")
	)
	(segment
		(start 144.52346 -63.701422)
		(end 147.672806 -63.701422)
		(width 0.1143)
		(layer "B.Cu")
		(net "UPI_CPU1_CPU0_P0P0_DN<7>")
	)
	(segment
		(start 164.795708 -102.282244)
		(end 164.972492 -102.46487)
		(width 0.1143)
		(layer "B.Cu")
		(net "UPI_CPU1_CPU0_P0P0_DN<7>")
	)
	(segment
		(start 310.30291 -108.017564)
		(end 313.960764 -104.21366)
		(width 0.1143)
		(layer "B.Cu")
		(net "UPI_CPU1_CPU0_P0P0_DN<7>")
	)
	(segment
		(start 315.781182 -80.160622)
		(end 312.5216 -74.312018)
		(width 0.1143)
		(layer "B.Cu")
		(net "UPI_CPU1_CPU0_P0P0_DN<7>")
	)
	(segment
		(start 308.110382 -72.728582)
		(end 307.992018 -72.728582)
		(width 0.0889)
		(layer "B.Cu")
		(net "UPI_CPU1_CPU0_P0P0_DN<7>")
	)
	(segment
		(start 144.49806 -63.726822)
		(end 144.52346 -63.701422)
		(width 0.0889)
		(layer "B.Cu")
		(net "UPI_CPU1_CPU0_P0P0_DN<7>")
	)
	(segment
		(start 312.5216 -74.312018)
		(end 309.31231 -73.1393)
		(width 0.1143)
		(layer "B.Cu")
		(net "UPI_CPU1_CPU0_P0P0_DN<7>")
	)
	(segment
		(start 307.668422 -72.40524)
		(end 307.55336 -72.290178)
		(width 0.0889)
		(layer "B.Cu")
		(net "UPI_CPU1_CPU0_P0P0_DN<7>")
	)
	(segment
		(start 142.731236 -64.229234)
		(end 143.180816 -64.229234)
		(width 0.0889)
		(layer "B.Cu")
		(net "UPI_CPU1_CPU0_P0P0_DN<7>")
	)
	(segment
		(start 246.91848 -107.513882)
		(end 248.642632 -107.449366)
		(width 0.1143)
		(layer "B.Cu")
		(net "UPI_CPU1_CPU0_P0P0_DN<7>")
	)
	(segment
		(start 306.307998 -110.29442)
		(end 310.30291 -108.017564)
		(width 0.1143)
		(layer "B.Cu")
		(net "UPI_CPU1_CPU0_P0P0_DN<7>")
	)
	(segment
		(start 162.89655 -99.631246)
		(end 162.958526 -99.87788)
		(width 0.1143)
		(layer "B.Cu")
		(net "UPI_CPU1_CPU0_P0P0_DN<7>")
	)
	(segment
		(start 156.634434 -90.669618)
		(end 156.674312 -90.869262)
		(width 0.1143)
		(layer "B.Cu")
		(net "UPI_CPU1_CPU0_P0P0_DN<7>")
	)
	(segment
		(start 290.376864 -108.94441)
		(end 291.125402 -108.773722)
		(width 0.1143)
		(layer "B.Cu")
		(net "UPI_CPU1_CPU0_P0P0_DN<7>")
	)
	(segment
		(start 304.399442 -71.353934)
		(end 304.366676 -71.353934)
		(width 0.0889)
		(layer "B.Cu")
		(net "UPI_CPU1_CPU0_P0P0_DN<7>")
	)
	(segment
		(start 164.268912 -101.73843)
		(end 164.445696 -101.921056)
		(width 0.1143)
		(layer "B.Cu")
		(net "UPI_CPU1_CPU0_P0P0_DN<7>")
	)
	(segment
		(start 307.876702 -72.613266)
		(end 307.876702 -72.494902)
		(width 0.0889)
		(layer "B.Cu")
		(net "UPI_CPU1_CPU0_P0P0_DN<7>")
	)
	(segment
		(start 141.963394 -63.334138)
		(end 141.963394 -63.672212)
		(width 0.0889)
		(layer "B.Cu")
		(net "UPI_CPU1_CPU0_P0P0_DN<7>")
	)
	(segment
		(start 301.83074 -69.868288)
		(end 301.794926 -69.868288)
		(width 0.0889)
		(layer "B.Cu")
		(net "UPI_CPU1_CPU0_P0P0_DN<7>")
	)
	(segment
		(start 162.133026 -97.107248)
		(end 162.313366 -97.824544)
		(width 0.1143)
		(layer "B.Cu")
		(net "UPI_CPU1_CPU0_P0P0_DN<7>")
	)
	(segment
		(start 189.469268 -114.096038)
		(end 195.033138 -115.967256)
		(width 0.1143)
		(layer "B.Cu")
		(net "UPI_CPU1_CPU0_P0P0_DN<7>")
	)
	(segment
		(start 162.958526 -99.87788)
		(end 162.868356 -100.028756)
		(width 0.1143)
		(layer "B.Cu")
		(net "UPI_CPU1_CPU0_P0P0_DN<7>")
	)
	(segment
		(start 316.300866 -81.814924)
		(end 316.281562 -81.058512)
		(width 0.1143)
		(layer "B.Cu")
		(net "UPI_CPU1_CPU0_P0P0_DN<7>")
	)
	(segment
		(start 291.125402 -108.773722)
		(end 292.143434 -108.541566)
		(width 0.1143)
		(layer "B.Cu")
		(net "UPI_CPU1_CPU0_P0P0_DN<7>")
	)
	(segment
		(start 315.20892 -97.403158)
		(end 316.004702 -96.294702)
		(width 0.1143)
		(layer "B.Cu")
		(net "UPI_CPU1_CPU0_P0P0_DN<7>")
	)
	(segment
		(start 302.682402 -70.363334)
		(end 302.649636 -70.363334)
		(width 0.0889)
		(layer "B.Cu")
		(net "UPI_CPU1_CPU0_P0P0_DN<7>")
	)
	(segment
		(start 207.532224 -115.047268)
		(end 225.904806 -111.358172)
		(width 0.1143)
		(layer "B.Cu")
		(net "UPI_CPU1_CPU0_P0P0_DN<7>")
	)
	(segment
		(start 307.78704 -72.40524)
		(end 307.668422 -72.40524)
		(width 0.0889)
		(layer "B.Cu")
		(net "UPI_CPU1_CPU0_P0P0_DN<7>")
	)
	(segment
		(start 163.742116 -101.194616)
		(end 163.9189 -101.377242)
		(width 0.1143)
		(layer "B.Cu")
		(net "UPI_CPU1_CPU0_P0P0_DN<7>")
	)
	(segment
		(start 141.963394 -63.672212)
		(end 142.02537 -63.734188)
		(width 0.0889)
		(layer "B.Cu")
		(net "UPI_CPU1_CPU0_P0P0_DN<7>")
	)
	(segment
		(start 313.960764 -104.21366)
		(end 314.936124 -99.183444)
		(width 0.1143)
		(layer "B.Cu")
		(net "UPI_CPU1_CPU0_P0P0_DN<7>")
	)
	(segment
		(start 308.2798 -72.934576)
		(end 308.2798 -72.898)
		(width 0.0889)
		(layer "B.Cu")
		(net "UPI_CPU1_CPU0_P0P0_DN<7>")
	)
	(segment
		(start 164.619432 -102.27945)
		(end 164.795708 -102.282244)
		(width 0.1143)
		(layer "B.Cu")
		(net "UPI_CPU1_CPU0_P0P0_DN<7>")
	)
	(segment
		(start 163.9189 -101.377242)
		(end 163.916106 -101.553264)
		(width 0.1143)
		(layer "B.Cu")
		(net "UPI_CPU1_CPU0_P0P0_DN<7>")
	)
	(segment
		(start 178.271424 -111.104426)
		(end 186.073796 -111.600234)
		(width 0.1143)
		(layer "B.Cu")
		(net "UPI_CPU1_CPU0_P0P0_DN<7>")
	)
	(segment
		(start 314.936124 -99.183444)
		(end 315.20892 -97.403158)
		(width 0.1143)
		(layer "B.Cu")
		(net "UPI_CPU1_CPU0_P0P0_DN<7>")
	)
	(segment
		(start 165.322504 -102.826058)
		(end 165.499288 -103.008684)
		(width 0.1143)
		(layer "B.Cu")
		(net "UPI_CPU1_CPU0_P0P0_DN<7>")
	)
	(segment
		(start 164.969698 -102.640892)
		(end 165.146228 -102.823264)
		(width 0.1143)
		(layer "B.Cu")
		(net "UPI_CPU1_CPU0_P0P0_DN<7>")
	)
	(segment
		(start 300.965362 -69.372734)
		(end 300.325028 -69.372734)
		(width 0.0889)
		(layer "B.Cu")
		(net "UPI_CPU1_CPU0_P0P0_DN<7>")
	)
	(segment
		(start 162.313366 -97.824544)
		(end 162.74542 -99.540822)
		(width 0.1143)
		(layer "B.Cu")
		(net "UPI_CPU1_CPU0_P0P0_DN<7>")
	)
	(segment
		(start 235.700316 -111.849154)
		(end 246.91848 -107.513882)
		(width 0.1143)
		(layer "B.Cu")
		(net "UPI_CPU1_CPU0_P0P0_DN<7>")
	)
	(segment
		(start 165.146228 -102.823264)
		(end 165.322504 -102.826058)
		(width 0.1143)
		(layer "B.Cu")
		(net "UPI_CPU1_CPU0_P0P0_DN<7>")
	)
	(segment
		(start 164.442902 -102.097078)
		(end 164.619432 -102.27945)
		(width 0.1143)
		(layer "B.Cu")
		(net "UPI_CPU1_CPU0_P0P0_DN<7>")
	)
	(segment
		(start 248.642632 -107.449366)
		(end 258.65836 -110.433104)
		(width 0.1143)
		(layer "B.Cu")
		(net "UPI_CPU1_CPU0_P0P0_DN<7>")
	)
	(segment
		(start 165.499288 -103.008684)
		(end 165.496494 -103.184706)
		(width 0.1143)
		(layer "B.Cu")
		(net "UPI_CPU1_CPU0_P0P0_DN<7>")
	)
	(segment
		(start 164.092636 -101.735636)
		(end 164.268912 -101.73843)
		(width 0.1143)
		(layer "B.Cu")
		(net "UPI_CPU1_CPU0_P0P0_DN<7>")
	)
	(segment
		(start 178.271424 -111.104172)
		(end 178.271424 -111.104426)
		(width 0.1143)
		(layer "B.Cu")
		(net "UPI_CPU1_CPU0_P0P0_DN<7>")
	)
	(segment
		(start 195.033138 -115.967256)
		(end 197.977252 -116.095018)
		(width 0.1143)
		(layer "B.Cu")
		(net "UPI_CPU1_CPU0_P0P0_DN<7>")
	)
	(segment
		(start 175.56861 -108.619036)
		(end 178.271424 -111.104172)
		(width 0.1143)
		(layer "B.Cu")
		(net "UPI_CPU1_CPU0_P0P0_DN<7>")
	)
	(segment
		(start 307.876702 -72.494902)
		(end 307.78704 -72.40524)
		(width 0.0889)
		(layer "B.Cu")
		(net "UPI_CPU1_CPU0_P0P0_DN<7>")
	)
	(segment
		(start 162.868356 -100.028756)
		(end 163.018724 -100.626926)
		(width 0.1143)
		(layer "B.Cu")
		(net "UPI_CPU1_CPU0_P0P0_DN<7>")
	)
	(segment
		(start 162.74542 -99.540822)
		(end 162.89655 -99.631246)
		(width 0.1143)
		(layer "B.Cu")
		(net "UPI_CPU1_CPU0_P0P0_DN<7>")
	)
	(segment
		(start 163.018724 -100.626926)
		(end 163.566094 -101.191822)
		(width 0.1143)
		(layer "B.Cu")
		(net "UPI_CPU1_CPU0_P0P0_DN<7>")
	)
	(segment
		(start 147.672806 -63.701422)
		(end 152.139142 -68.167504)
		(width 0.1143)
		(layer "B.Cu")
		(net "UPI_CPU1_CPU0_P0P0_DN<7>")
	)
	(segment
		(start 258.65836 -110.433104)
		(end 282.766262 -112.879886)
		(width 0.1143)
		(layer "B.Cu")
		(net "UPI_CPU1_CPU0_P0P0_DN<7>")
	)
	(segment
		(start 307.992018 -72.728582)
		(end 307.876702 -72.613266)
		(width 0.0889)
		(layer "B.Cu")
		(net "UPI_CPU1_CPU0_P0P0_DN<7>")
	)
	(segment
		(start 164.445696 -101.921056)
		(end 164.442902 -102.097078)
		(width 0.1143)
		(layer "B.Cu")
		(net "UPI_CPU1_CPU0_P0P0_DN<7>")
	)
	(segment
		(start 186.073796 -111.600234)
		(end 188.60135 -113.008156)
		(width 0.1143)
		(layer "B.Cu")
		(net "UPI_CPU1_CPU0_P0P0_DN<7>")
	)
	(segment
		(start 166.170356 -103.879904)
		(end 169.88409 -106.673904)
		(width 0.1143)
		(layer "B.Cu")
		(net "UPI_CPU1_CPU0_P0P0_DN<7>")
	)
	(segment
		(start 143.683228 -63.726822)
		(end 144.49806 -63.726822)
		(width 0.0889)
		(layer "B.Cu")
		(net "UPI_CPU1_CPU0_P0P0_DN<7>")
	)
	(segment
		(start 225.904806 -111.358172)
		(end 235.700316 -111.849154)
		(width 0.1143)
		(layer "B.Cu")
		(net "UPI_CPU1_CPU0_P0P0_DN<7>")
	)
	(segment
		(start 316.026292 -80.600296)
		(end 315.85662 -80.552036)
		(width 0.1143)
		(layer "B.Cu")
		(net "UPI_CPU1_CPU0_P0P0_DN<7>")
	)
	(segment
		(start 315.732922 -80.33004)
		(end 315.781182 -80.160622)
		(width 0.1143)
		(layer "B.Cu")
		(net "UPI_CPU1_CPU0_P0P0_DN<7>")
	)
	(segment
		(start 152.139142 -68.167504)
		(end 156.634434 -90.669618)
		(width 0.1143)
		(layer "B.Cu")
		(net "UPI_CPU1_CPU0_P0P0_DN<7>")
	)
	(segment
		(start 306.307744 -110.29442)
		(end 306.307998 -110.29442)
		(width 0.1143)
		(layer "B.Cu")
		(net "UPI_CPU1_CPU0_P0P0_DN<7>")
	)
	(segment
		(start 316.281562 -81.058512)
		(end 316.026292 -80.600296)
		(width 0.1143)
		(layer "B.Cu")
		(net "UPI_CPU1_CPU0_P0P0_DN<7>")
	)
	(segment
		(start 308.2798 -72.898)
		(end 308.110382 -72.728582)
		(width 0.0889)
		(layer "B.Cu")
		(net "UPI_CPU1_CPU0_P0P0_DN<7>")
	)
	(segment
		(start 169.88409 -106.673904)
		(end 175.56861 -108.619036)
		(width 0.1143)
		(layer "B.Cu")
		(net "UPI_CPU1_CPU0_P0P0_DN<7>")
	)
	(segment
		(start 156.674312 -90.869262)
		(end 162.133026 -97.107248)
		(width 0.1143)
		(layer "B.Cu")
		(net "UPI_CPU1_CPU0_P0P0_DN<7>")
	)
	(segment
		(start 307.55336 -72.290178)
		(end 307.55336 -72.17156)
		(width 0.0889)
		(layer "B.Cu")
		(net "UPI_CPU1_CPU0_P0P0_DN<7>")
	)
	(segment
		(start 163.566094 -101.191822)
		(end 163.742116 -101.194616)
		(width 0.1143)
		(layer "B.Cu")
		(net "UPI_CPU1_CPU0_P0P0_DN<7>")
	)
	(segment
		(start 188.60135 -113.008156)
		(end 189.469268 -114.096038)
		(width 0.1143)
		(layer "B.Cu")
		(net "UPI_CPU1_CPU0_P0P0_DN<7>")
	)
	(segment
		(start 307.231288 -71.849488)
		(end 306.837334 -71.849488)
		(width 0.0889)
		(layer "B.Cu")
		(net "UPI_CPU1_CPU0_P0P0_DN<7>")
	)
	(segment
		(start 303.623472 -111.13516)
		(end 306.307744 -110.29442)
		(width 0.1143)
		(layer "B.Cu")
		(net "UPI_CPU1_CPU0_P0P0_DN<7>")
	)
	(segment
		(start 315.85662 -80.552036)
		(end 315.732922 -80.33004)
		(width 0.1143)
		(layer "B.Cu")
		(net "UPI_CPU1_CPU0_P0P0_DN<7>")
	)
	(segment
		(start 197.977252 -116.095018)
		(end 206.36865 -114.971068)
		(width 0.1143)
		(layer "B.Cu")
		(net "UPI_CPU1_CPU0_P0P0_DN<7>")
	)
	(segment
		(start 164.972492 -102.46487)
		(end 164.969698 -102.640892)
		(width 0.1143)
		(layer "B.Cu")
		(net "UPI_CPU1_CPU0_P0P0_DN<7>")
	)
	(arc
		(start 306.837334 -71.849488)
		(mid 306.634436 -71.733628)
		(end 306.488338 -71.551292)
		(width 0.0889)
		(layer "B.Cu")
		(net "UPI_CPU1_CPU0_P0P0_DN<7>")
	)
	(arc
		(start 303.017936 -70.563486)
		(mid 302.876253 -70.419682)
		(end 302.682402 -70.363334)
		(width 0.0889)
		(layer "B.Cu")
		(net "UPI_CPU1_CPU0_P0P0_DN<7>")
	)
	(arc
		(start 304.366676 -71.353934)
		(mid 304.083459 -71.269653)
		(end 303.876456 -71.058786)
		(width 0.0889)
		(layer "B.Cu")
		(net "UPI_CPU1_CPU0_P0P0_DN<7>")
	)
	(arc
		(start 302.159416 -70.068186)
		(mid 302.020672 -69.926153)
		(end 301.83074 -69.868288)
		(width 0.0889)
		(layer "B.Cu")
		(net "UPI_CPU1_CPU0_P0P0_DN<7>")
	)
	(arc
		(start 306.104544 -71.354188)
		(mid 305.904771 -71.407757)
		(end 305.758596 -71.554086)
		(width 0.0889)
		(layer "B.Cu")
		(net "UPI_CPU1_CPU0_P0P0_DN<7>")
	)
	(arc
		(start 301.794926 -69.868288)
		(mid 301.509502 -69.784821)
		(end 301.300896 -69.572886)
		(width 0.0889)
		(layer "B.Cu")
		(net "UPI_CPU1_CPU0_P0P0_DN<7>")
	)
	(arc
		(start 303.516792 -70.858888)
		(mid 303.228647 -70.776569)
		(end 303.017936 -70.563486)
		(width 0.0889)
		(layer "B.Cu")
		(net "UPI_CPU1_CPU0_P0P0_DN<7>")
	)
	(arc
		(start 142.515082 -64.03213)
		(mid 142.606026 -64.149473)
		(end 142.731236 -64.229234)
		(width 0.0889)
		(layer "B.Cu")
		(net "UPI_CPU1_CPU0_P0P0_DN<7>")
	)
	(arc
		(start 305.246278 -71.849488)
		(mid 304.951015 -71.770337)
		(end 304.734976 -71.554086)
		(width 0.0889)
		(layer "B.Cu")
		(net "UPI_CPU1_CPU0_P0P0_DN<7>")
	)
	(arc
		(start 303.876456 -71.058786)
		(mid 303.736377 -70.91605)
		(end 303.544732 -70.858888)
		(width 0.0889)
		(layer "B.Cu")
		(net "UPI_CPU1_CPU0_P0P0_DN<7>")
	)
	(arc
		(start 306.488338 -71.551292)
		(mid 306.351996 -71.407307)
		(end 306.160932 -71.354188)
		(width 0.0889)
		(layer "B.Cu")
		(net "UPI_CPU1_CPU0_P0P0_DN<7>")
	)
	(arc
		(start 301.300896 -69.572886)
		(mid 301.159213 -69.429082)
		(end 300.965362 -69.372734)
		(width 0.0889)
		(layer "B.Cu")
		(net "UPI_CPU1_CPU0_P0P0_DN<7>")
	)
	(arc
		(start 142.166594 -63.734188)
		(mid 142.369188 -63.850006)
		(end 142.515082 -64.03213)
		(width 0.0889)
		(layer "B.Cu")
		(net "UPI_CPU1_CPU0_P0P0_DN<7>")
	)
	(arc
		(start 302.649636 -70.363334)
		(mid 302.366419 -70.279053)
		(end 302.159416 -70.068186)
		(width 0.0889)
		(layer "B.Cu")
		(net "UPI_CPU1_CPU0_P0P0_DN<7>")
	)
	(arc
		(start 304.734976 -71.554086)
		(mid 304.593293 -71.410282)
		(end 304.399442 -71.353934)
		(width 0.0889)
		(layer "B.Cu")
		(net "UPI_CPU1_CPU0_P0P0_DN<7>")
	)
	(arc
		(start 305.758596 -71.554086)
		(mid 305.542533 -71.770295)
		(end 305.247294 -71.849488)
		(width 0.0889)
		(layer "B.Cu")
		(net "UPI_CPU1_CPU0_P0P0_DN<7>")
	)
	(arc
		(start 300.325028 -69.372734)
		(mid 300.200902 -69.348044)
		(end 300.095666 -69.277738)
		(width 0.0889)
		(layer "B.Cu")
		(net "UPI_CPU1_CPU0_P0P0_DN<7>")
	)
	(segment
		(start 301.241206 -71.258938)
		(end 301.812706 -71.258938)
		(width 0.1143)
		(layer "F.Cu")
		(net "UPI_CPU1_CPU0_P0P0_DN<6>")
	)
	(segment
		(start 139.674854 -64.324738)
		(end 140.246354 -64.324738)
		(width 0.1143)
		(layer "F.Cu")
		(net "UPI_CPU1_CPU0_P0P0_DN<6>")
	)
	(via
		(at 140.246354 -64.324738)
		(size 0.508)
		(drill 0.254)
		(layers "F.Cu" "B.Cu")
		(net "UPI_CPU1_CPU0_P0P0_DN<6>")
	)
	(via
		(at 301.812706 -71.258938)
		(size 0.508)
		(drill 0.254)
		(layers "F.Cu" "B.Cu")
		(net "UPI_CPU1_CPU0_P0P0_DN<6>")
	)
	(segment
		(start 163.69284 -98.797872)
		(end 163.84397 -98.888042)
		(width 0.1143)
		(layer "B.Cu")
		(net "UPI_CPU1_CPU0_P0P0_DN<6>")
	)
	(segment
		(start 314.605924 -80.516222)
		(end 314.541916 -80.207866)
		(width 0.1143)
		(layer "B.Cu")
		(net "UPI_CPU1_CPU0_P0P0_DN<6>")
	)
	(segment
		(start 147.291298 -62.432946)
		(end 147.490942 -62.432946)
		(width 0.1143)
		(layer "B.Cu")
		(net "UPI_CPU1_CPU0_P0P0_DN<6>")
	)
	(segment
		(start 142.568676 -62.4332)
		(end 147.291044 -62.4332)
		(width 0.1143)
		(layer "B.Cu")
		(net "UPI_CPU1_CPU0_P0P0_DN<6>")
	)
	(segment
		(start 235.541312 -110.87227)
		(end 246.35333 -106.69651)
		(width 0.1143)
		(layer "B.Cu")
		(net "UPI_CPU1_CPU0_P0P0_DN<6>")
	)
	(segment
		(start 142.5448 -62.4332)
		(end 142.568676 -62.4332)
		(width 0.0889)
		(layer "B.Cu")
		(net "UPI_CPU1_CPU0_P0P0_DN<6>")
	)
	(segment
		(start 314.714128 -81.653634)
		(end 314.66282 -81.404714)
		(width 0.1143)
		(layer "B.Cu")
		(net "UPI_CPU1_CPU0_P0P0_DN<6>")
	)
	(segment
		(start 313.917838 -99.315778)
		(end 314.268866 -96.791526)
		(width 0.1143)
		(layer "B.Cu")
		(net "UPI_CPU1_CPU0_P0P0_DN<6>")
	)
	(segment
		(start 168.006014 -104.04983)
		(end 170.34383 -105.808526)
		(width 0.1143)
		(layer "B.Cu")
		(net "UPI_CPU1_CPU0_P0P0_DN<6>")
	)
	(segment
		(start 306.8574 -73.0504)
		(end 306.7304 -72.9234)
		(width 0.0889)
		(layer "B.Cu")
		(net "UPI_CPU1_CPU0_P0P0_DN<6>")
	)
	(segment
		(start 282.6639 -111.898176)
		(end 285.609284 -111.308896)
		(width 0.1143)
		(layer "B.Cu")
		(net "UPI_CPU1_CPU0_P0P0_DN<6>")
	)
	(segment
		(start 305.48453 -72.840088)
		(end 305.229006 -72.840088)
		(width 0.0889)
		(layer "B.Cu")
		(net "UPI_CPU1_CPU0_P0P0_DN<6>")
	)
	(segment
		(start 313.000644 -103.790496)
		(end 313.917838 -99.315778)
		(width 0.1143)
		(layer "B.Cu")
		(net "UPI_CPU1_CPU0_P0P0_DN<6>")
	)
	(segment
		(start 152.842722 -67.784726)
		(end 157.30982 -90.12555)
		(width 0.1143)
		(layer "B.Cu")
		(net "UPI_CPU1_CPU0_P0P0_DN<6>")
	)
	(segment
		(start 314.560712 -80.912462)
		(end 314.50915 -80.663542)
		(width 0.1143)
		(layer "B.Cu")
		(net "UPI_CPU1_CPU0_P0P0_DN<6>")
	)
	(segment
		(start 142.52575 -62.45225)
		(end 142.5448 -62.4332)
		(width 0.0889)
		(layer "B.Cu")
		(net "UPI_CPU1_CPU0_P0P0_DN<6>")
	)
	(segment
		(start 285.609284 -111.308896)
		(end 289.346386 -108.312204)
		(width 0.1143)
		(layer "B.Cu")
		(net "UPI_CPU1_CPU0_P0P0_DN<6>")
	)
	(segment
		(start 307.1622 -73.211944)
		(end 307.000656 -73.0504)
		(width 0.0889)
		(layer "B.Cu")
		(net "UPI_CPU1_CPU0_P0P0_DN<6>")
	)
	(segment
		(start 315.015118 -82.491834)
		(end 314.867798 -82.39506)
		(width 0.1143)
		(layer "B.Cu")
		(net "UPI_CPU1_CPU0_P0P0_DN<6>")
	)
	(segment
		(start 307.1622 -73.355454)
		(end 307.1622 -73.211944)
		(width 0.0889)
		(layer "B.Cu")
		(net "UPI_CPU1_CPU0_P0P0_DN<6>")
	)
	(segment
		(start 307.289454 -73.4822)
		(end 307.1622 -73.355454)
		(width 0.0889)
		(layer "B.Cu")
		(net "UPI_CPU1_CPU0_P0P0_DN<6>")
	)
	(segment
		(start 225.833178 -110.385606)
		(end 235.541312 -110.87227)
		(width 0.1143)
		(layer "B.Cu")
		(net "UPI_CPU1_CPU0_P0P0_DN<6>")
	)
	(segment
		(start 307.620162 -73.705466)
		(end 307.620162 -73.669906)
		(width 0.0889)
		(layer "B.Cu")
		(net "UPI_CPU1_CPU0_P0P0_DN<6>")
	)
	(segment
		(start 142.46733 -62.45225)
		(end 142.52575 -62.45225)
		(width 0.0889)
		(layer "B.Cu")
		(net "UPI_CPU1_CPU0_P0P0_DN<6>")
	)
	(segment
		(start 176.074324 -107.769406)
		(end 178.674014 -110.160054)
		(width 0.1143)
		(layer "B.Cu")
		(net "UPI_CPU1_CPU0_P0P0_DN<6>")
	)
	(segment
		(start 306.541678 -72.591168)
		(end 306.473606 -72.484488)
		(width 0.0889)
		(layer "B.Cu")
		(net "UPI_CPU1_CPU0_P0P0_DN<6>")
	)
	(segment
		(start 163.815776 -99.285806)
		(end 163.877498 -99.531932)
		(width 0.1143)
		(layer "B.Cu")
		(net "UPI_CPU1_CPU0_P0P0_DN<6>")
	)
	(segment
		(start 307.620162 -73.669906)
		(end 307.432456 -73.4822)
		(width 0.0889)
		(layer "B.Cu")
		(net "UPI_CPU1_CPU0_P0P0_DN<6>")
	)
	(segment
		(start 157.30982 -90.12555)
		(end 163.20643 -96.863916)
		(width 0.1143)
		(layer "B.Cu")
		(net "UPI_CPU1_CPU0_P0P0_DN<6>")
	)
	(segment
		(start 303.544732 -71.849488)
		(end 303.511966 -71.849488)
		(width 0.0889)
		(layer "B.Cu")
		(net "UPI_CPU1_CPU0_P0P0_DN<6>")
	)
	(segment
		(start 314.75934 -81.257648)
		(end 314.708032 -81.008982)
		(width 0.1143)
		(layer "B.Cu")
		(net "UPI_CPU1_CPU0_P0P0_DN<6>")
	)
	(segment
		(start 308.105302 -74.1807)
		(end 307.635656 -73.72096)
		(width 0.1143)
		(layer "B.Cu")
		(net "UPI_CPU1_CPU0_P0P0_DN<6>")
	)
	(segment
		(start 307.635656 -73.72096)
		(end 307.620162 -73.705466)
		(width 0.0889)
		(layer "B.Cu")
		(net "UPI_CPU1_CPU0_P0P0_DN<6>")
	)
	(segment
		(start 314.541916 -80.207866)
		(end 311.76849 -75.233276)
		(width 0.1143)
		(layer "B.Cu")
		(net "UPI_CPU1_CPU0_P0P0_DN<6>")
	)
	(segment
		(start 188.993018 -112.077246)
		(end 190.1317 -113.500662)
		(width 0.1143)
		(layer "B.Cu")
		(net "UPI_CPU1_CPU0_P0P0_DN<6>")
	)
	(segment
		(start 246.35333 -106.69651)
		(end 249.177302 -106.591354)
		(width 0.1143)
		(layer "B.Cu")
		(net "UPI_CPU1_CPU0_P0P0_DN<6>")
	)
	(segment
		(start 306.150518 -72.369934)
		(end 306.021232 -72.379332)
		(width 0.0889)
		(layer "B.Cu")
		(net "UPI_CPU1_CPU0_P0P0_DN<6>")
	)
	(segment
		(start 289.346386 -108.312204)
		(end 292.210998 -107.719114)
		(width 0.1143)
		(layer "B.Cu")
		(net "UPI_CPU1_CPU0_P0P0_DN<6>")
	)
	(segment
		(start 314.867798 -82.39506)
		(end 314.81649 -82.14614)
		(width 0.1143)
		(layer "B.Cu")
		(net "UPI_CPU1_CPU0_P0P0_DN<6>")
	)
	(segment
		(start 315.066426 -82.7405)
		(end 315.015118 -82.491834)
		(width 0.1143)
		(layer "B.Cu")
		(net "UPI_CPU1_CPU0_P0P0_DN<6>")
	)
	(segment
		(start 308.888384 -74.1807)
		(end 308.105302 -74.1807)
		(width 0.1143)
		(layer "B.Cu")
		(net "UPI_CPU1_CPU0_P0P0_DN<6>")
	)
	(segment
		(start 195.217288 -115.211098)
		(end 197.919594 -115.329208)
		(width 0.1143)
		(layer "B.Cu")
		(net "UPI_CPU1_CPU0_P0P0_DN<6>")
	)
	(segment
		(start 147.490942 -62.432946)
		(end 152.842722 -67.784726)
		(width 0.1143)
		(layer "B.Cu")
		(net "UPI_CPU1_CPU0_P0P0_DN<6>")
	)
	(segment
		(start 311.76849 -75.233276)
		(end 308.888384 -74.1807)
		(width 0.1143)
		(layer "B.Cu")
		(net "UPI_CPU1_CPU0_P0P0_DN<6>")
	)
	(segment
		(start 314.91301 -81.999074)
		(end 314.861702 -81.750408)
		(width 0.1143)
		(layer "B.Cu")
		(net "UPI_CPU1_CPU0_P0P0_DN<6>")
	)
	(segment
		(start 314.50915 -80.663542)
		(end 314.605924 -80.516222)
		(width 0.1143)
		(layer "B.Cu")
		(net "UPI_CPU1_CPU0_P0P0_DN<6>")
	)
	(segment
		(start 292.210998 -107.719114)
		(end 303.851818 -110.123224)
		(width 0.1143)
		(layer "B.Cu")
		(net "UPI_CPU1_CPU0_P0P0_DN<6>")
	)
	(segment
		(start 302.682402 -71.353934)
		(end 302.042068 -71.353934)
		(width 0.0889)
		(layer "B.Cu")
		(net "UPI_CPU1_CPU0_P0P0_DN<6>")
	)
	(segment
		(start 315.53658 -95.026226)
		(end 315.239146 -83.574382)
		(width 0.1143)
		(layer "B.Cu")
		(net "UPI_CPU1_CPU0_P0P0_DN<6>")
	)
	(segment
		(start 140.246354 -64.324738)
		(end 140.516864 -63.769748)
		(width 0.0889)
		(layer "B.Cu")
		(net "UPI_CPU1_CPU0_P0P0_DN<6>")
	)
	(segment
		(start 249.177302 -106.591354)
		(end 258.791456 -109.454442)
		(width 0.1143)
		(layer "B.Cu")
		(net "UPI_CPU1_CPU0_P0P0_DN<6>")
	)
	(segment
		(start 314.708032 -81.008982)
		(end 314.560712 -80.912462)
		(width 0.1143)
		(layer "B.Cu")
		(net "UPI_CPU1_CPU0_P0P0_DN<6>")
	)
	(segment
		(start 314.861702 -81.750408)
		(end 314.714128 -81.653634)
		(width 0.1143)
		(layer "B.Cu")
		(net "UPI_CPU1_CPU0_P0P0_DN<6>")
	)
	(segment
		(start 163.905946 -99.134676)
		(end 163.815776 -99.285806)
		(width 0.1143)
		(layer "B.Cu")
		(net "UPI_CPU1_CPU0_P0P0_DN<6>")
	)
	(segment
		(start 258.791456 -109.454442)
		(end 282.6639 -111.898176)
		(width 0.1143)
		(layer "B.Cu")
		(net "UPI_CPU1_CPU0_P0P0_DN<6>")
	)
	(segment
		(start 315.239146 -83.574382)
		(end 315.168534 -83.23326)
		(width 0.1143)
		(layer "B.Cu")
		(net "UPI_CPU1_CPU0_P0P0_DN<6>")
	)
	(segment
		(start 303.851818 -110.123224)
		(end 305.459384 -109.675168)
		(width 0.1143)
		(layer "B.Cu")
		(net "UPI_CPU1_CPU0_P0P0_DN<6>")
	)
	(segment
		(start 306.7304 -72.9234)
		(end 306.7304 -72.77989)
		(width 0.0889)
		(layer "B.Cu")
		(net "UPI_CPU1_CPU0_P0P0_DN<6>")
	)
	(segment
		(start 315.168534 -83.23326)
		(end 315.021214 -83.136486)
		(width 0.1143)
		(layer "B.Cu")
		(net "UPI_CPU1_CPU0_P0P0_DN<6>")
	)
	(segment
		(start 309.708042 -107.160568)
		(end 313.000644 -103.790496)
		(width 0.1143)
		(layer "B.Cu")
		(net "UPI_CPU1_CPU0_P0P0_DN<6>")
	)
	(segment
		(start 178.674014 -110.160054)
		(end 186.4233 -110.645956)
		(width 0.1143)
		(layer "B.Cu")
		(net "UPI_CPU1_CPU0_P0P0_DN<6>")
	)
	(segment
		(start 165.629844 -101.587554)
		(end 168.006014 -104.04983)
		(width 0.1143)
		(layer "B.Cu")
		(net "UPI_CPU1_CPU0_P0P0_DN<6>")
	)
	(segment
		(start 197.919594 -115.329208)
		(end 207.262476 -114.075718)
		(width 0.1143)
		(layer "B.Cu")
		(net "UPI_CPU1_CPU0_P0P0_DN<6>")
	)
	(segment
		(start 315.021214 -83.136486)
		(end 314.969906 -82.887566)
		(width 0.1143)
		(layer "B.Cu")
		(net "UPI_CPU1_CPU0_P0P0_DN<6>")
	)
	(segment
		(start 163.20643 -96.863916)
		(end 163.69284 -98.797872)
		(width 0.1143)
		(layer "B.Cu")
		(net "UPI_CPU1_CPU0_P0P0_DN<6>")
	)
	(segment
		(start 314.81649 -82.14614)
		(end 314.91301 -81.999074)
		(width 0.1143)
		(layer "B.Cu")
		(net "UPI_CPU1_CPU0_P0P0_DN<6>")
	)
	(segment
		(start 314.969906 -82.887566)
		(end 315.066426 -82.7405)
		(width 0.1143)
		(layer "B.Cu")
		(net "UPI_CPU1_CPU0_P0P0_DN<6>")
	)
	(segment
		(start 163.84397 -98.888042)
		(end 163.905946 -99.134676)
		(width 0.1143)
		(layer "B.Cu")
		(net "UPI_CPU1_CPU0_P0P0_DN<6>")
	)
	(segment
		(start 304.399442 -72.344534)
		(end 304.366676 -72.344534)
		(width 0.0889)
		(layer "B.Cu")
		(net "UPI_CPU1_CPU0_P0P0_DN<6>")
	)
	(segment
		(start 314.66282 -81.404714)
		(end 314.75934 -81.257648)
		(width 0.1143)
		(layer "B.Cu")
		(net "UPI_CPU1_CPU0_P0P0_DN<6>")
	)
	(segment
		(start 307.000656 -73.0504)
		(end 306.8574 -73.0504)
		(width 0.0889)
		(layer "B.Cu")
		(net "UPI_CPU1_CPU0_P0P0_DN<6>")
	)
	(segment
		(start 207.262476 -114.075718)
		(end 207.482694 -114.069876)
		(width 0.1143)
		(layer "B.Cu")
		(net "UPI_CPU1_CPU0_P0P0_DN<6>")
	)
	(segment
		(start 314.268866 -96.791526)
		(end 315.53658 -95.026226)
		(width 0.1143)
		(layer "B.Cu")
		(net "UPI_CPU1_CPU0_P0P0_DN<6>")
	)
	(segment
		(start 141.087094 -63.238634)
		(end 141.11986 -63.238634)
		(width 0.0889)
		(layer "B.Cu")
		(net "UPI_CPU1_CPU0_P0P0_DN<6>")
	)
	(segment
		(start 190.1317 -113.500662)
		(end 195.217288 -115.211098)
		(width 0.1143)
		(layer "B.Cu")
		(net "UPI_CPU1_CPU0_P0P0_DN<6>")
	)
	(segment
		(start 306.7304 -72.77989)
		(end 306.541678 -72.591168)
		(width 0.0889)
		(layer "B.Cu")
		(net "UPI_CPU1_CPU0_P0P0_DN<6>")
	)
	(segment
		(start 170.34383 -105.808526)
		(end 176.074324 -107.769406)
		(width 0.1143)
		(layer "B.Cu")
		(net "UPI_CPU1_CPU0_P0P0_DN<6>")
	)
	(segment
		(start 163.877498 -99.531932)
		(end 165.629844 -101.587554)
		(width 0.1143)
		(layer "B.Cu")
		(net "UPI_CPU1_CPU0_P0P0_DN<6>")
	)
	(segment
		(start 147.291044 -62.4332)
		(end 147.291298 -62.432946)
		(width 0.1143)
		(layer "B.Cu")
		(net "UPI_CPU1_CPU0_P0P0_DN<6>")
	)
	(segment
		(start 305.459384 -109.675168)
		(end 309.708042 -107.160568)
		(width 0.1143)
		(layer "B.Cu")
		(net "UPI_CPU1_CPU0_P0P0_DN<6>")
	)
	(segment
		(start 186.4233 -110.645956)
		(end 188.993018 -112.077246)
		(width 0.1143)
		(layer "B.Cu")
		(net "UPI_CPU1_CPU0_P0P0_DN<6>")
	)
	(segment
		(start 307.432456 -73.4822)
		(end 307.289454 -73.4822)
		(width 0.0889)
		(layer "B.Cu")
		(net "UPI_CPU1_CPU0_P0P0_DN<6>")
	)
	(segment
		(start 207.482694 -114.069876)
		(end 225.833178 -110.385606)
		(width 0.1143)
		(layer "B.Cu")
		(net "UPI_CPU1_CPU0_P0P0_DN<6>")
	)
	(arc
		(start 306.021232 -72.379332)
		(mid 305.89256 -72.45583)
		(end 305.796442 -72.570594)
		(width 0.0889)
		(layer "B.Cu")
		(net "UPI_CPU1_CPU0_P0P0_DN<6>")
	)
	(arc
		(start 302.042068 -71.353934)
		(mid 301.917942 -71.329244)
		(end 301.812706 -71.258938)
		(width 0.0889)
		(layer "B.Cu")
		(net "UPI_CPU1_CPU0_P0P0_DN<6>")
	)
	(arc
		(start 141.451584 -63.038736)
		(mid 141.880863 -62.609358)
		(end 142.46733 -62.45225)
		(width 0.0889)
		(layer "B.Cu")
		(net "UPI_CPU1_CPU0_P0P0_DN<6>")
	)
	(arc
		(start 141.11986 -63.238634)
		(mid 141.311502 -63.181468)
		(end 141.451584 -63.038736)
		(width 0.0889)
		(layer "B.Cu")
		(net "UPI_CPU1_CPU0_P0P0_DN<6>")
	)
	(arc
		(start 304.734976 -72.544686)
		(mid 304.593293 -72.400882)
		(end 304.399442 -72.344534)
		(width 0.0889)
		(layer "B.Cu")
		(net "UPI_CPU1_CPU0_P0P0_DN<6>")
	)
	(arc
		(start 303.876456 -72.049386)
		(mid 303.736377 -71.90665)
		(end 303.544732 -71.849488)
		(width 0.0889)
		(layer "B.Cu")
		(net "UPI_CPU1_CPU0_P0P0_DN<6>")
	)
	(arc
		(start 303.511966 -71.849488)
		(mid 303.226542 -71.766021)
		(end 303.017936 -71.554086)
		(width 0.0889)
		(layer "B.Cu")
		(net "UPI_CPU1_CPU0_P0P0_DN<6>")
	)
	(arc
		(start 306.473606 -72.484488)
		(mid 306.324076 -72.393324)
		(end 306.150518 -72.369934)
		(width 0.0889)
		(layer "B.Cu")
		(net "UPI_CPU1_CPU0_P0P0_DN<6>")
	)
	(arc
		(start 304.366676 -72.344534)
		(mid 304.083459 -72.260253)
		(end 303.876456 -72.049386)
		(width 0.0889)
		(layer "B.Cu")
		(net "UPI_CPU1_CPU0_P0P0_DN<6>")
	)
	(arc
		(start 305.796442 -72.570594)
		(mid 305.662888 -72.731262)
		(end 305.48453 -72.840088)
		(width 0.0889)
		(layer "B.Cu")
		(net "UPI_CPU1_CPU0_P0P0_DN<6>")
	)
	(arc
		(start 140.516864 -63.769748)
		(mid 140.702008 -63.396873)
		(end 141.087094 -63.238634)
		(width 0.0889)
		(layer "B.Cu")
		(net "UPI_CPU1_CPU0_P0P0_DN<6>")
	)
	(arc
		(start 303.017936 -71.554086)
		(mid 302.876253 -71.410282)
		(end 302.682402 -71.353934)
		(width 0.0889)
		(layer "B.Cu")
		(net "UPI_CPU1_CPU0_P0P0_DN<6>")
	)
	(arc
		(start 305.229006 -72.840088)
		(mid 304.943582 -72.756621)
		(end 304.734976 -72.544686)
		(width 0.0889)
		(layer "B.Cu")
		(net "UPI_CPU1_CPU0_P0P0_DN<6>")
	)
	(segment
		(start 144.003522 -62.285626)
		(end 144.003522 -62.079378)
		(width 0.0889)
		(layer "F.Cu")
		(net "UPI_CPU1_CPU0_P0P0_DN<5>")
	)
	(segment
		(start 144.003522 -62.079378)
		(end 144.238472 -61.844428)
		(width 0.0889)
		(layer "F.Cu")
		(net "UPI_CPU1_CPU0_P0P0_DN<5>")
	)
	(segment
		(start 141.96314 -62.672976)
		(end 141.940026 -62.586362)
		(width 0.0889)
		(layer "F.Cu")
		(net "UPI_CPU1_CPU0_P0P0_DN<5>")
	)
	(segment
		(start 142.239238 -62.438534)
		(end 143.850614 -62.438534)
		(width 0.0889)
		(layer "F.Cu")
		(net "UPI_CPU1_CPU0_P0P0_DN<5>")
	)
	(segment
		(start 142.250414 -62.838584)
		(end 141.96314 -62.672976)
		(width 0.0889)
		(layer "F.Cu")
		(net "UPI_CPU1_CPU0_P0P0_DN<5>")
	)
	(segment
		(start 143.850614 -62.438534)
		(end 144.003522 -62.285626)
		(width 0.0889)
		(layer "F.Cu")
		(net "UPI_CPU1_CPU0_P0P0_DN<5>")
	)
	(segment
		(start 303.529746 -72.249538)
		(end 302.958246 -72.249538)
		(width 0.1143)
		(layer "F.Cu")
		(net "UPI_CPU1_CPU0_P0P0_DN<5>")
	)
	(via
		(at 314.57265 -91.57462)
		(size 0.508)
		(drill 0.254)
		(layers "F.Cu" "B.Cu")
		(net "UPI_CPU1_CPU0_P0P0_DN<5>")
	)
	(via
		(at 144.238472 -61.844428)
		(size 0.508)
		(drill 0.254)
		(layers "F.Cu" "B.Cu")
		(net "UPI_CPU1_CPU0_P0P0_DN<5>")
	)
	(via
		(at 303.529746 -72.249538)
		(size 0.508)
		(drill 0.254)
		(layers "F.Cu" "B.Cu")
		(net "UPI_CPU1_CPU0_P0P0_DN<5>")
	)
	(arc
		(start 141.940026 -62.586362)
		(mid 142.073495 -62.479803)
		(end 142.239238 -62.438534)
		(width 0.0889)
		(layer "F.Cu")
		(net "UPI_CPU1_CPU0_P0P0_DN<5>")
	)
	(segment
		(start 157.74797 -89.523316)
		(end 163.925758 -96.582992)
		(width 0.1143)
		(layer "B.Cu")
		(net "UPI_CPU1_CPU0_P0P0_DN<5>")
	)
	(segment
		(start 306.535328 -74.135234)
		(end 306.771294 -74.3712)
		(width 0.0889)
		(layer "B.Cu")
		(net "UPI_CPU1_CPU0_P0P0_DN<5>")
	)
	(segment
		(start 145.2753 -61.5188)
		(end 145.3769 -61.4172)
		(width 0.0889)
		(layer "B.Cu")
		(net "UPI_CPU1_CPU0_P0P0_DN<5>")
	)
	(segment
		(start 178.976782 -109.451648)
		(end 186.458098 -109.920532)
		(width 0.1143)
		(layer "B.Cu")
		(net "UPI_CPU1_CPU0_P0P0_DN<5>")
	)
	(segment
		(start 187.823602 -110.72368)
		(end 189.731396 -110.89259)
		(width 0.1143)
		(layer "B.Cu")
		(net "UPI_CPU1_CPU0_P0P0_DN<5>")
	)
	(segment
		(start 145.1483 -61.5188)
		(end 145.2753 -61.5188)
		(width 0.0889)
		(layer "B.Cu")
		(net "UPI_CPU1_CPU0_P0P0_DN<5>")
	)
	(segment
		(start 143.9164 -61.5442)
		(end 144.0434 -61.4172)
		(width 0.0889)
		(layer "B.Cu")
		(net "UPI_CPU1_CPU0_P0P0_DN<5>")
	)
	(segment
		(start 147.352004 -61.456824)
		(end 153.32964 -67.434714)
		(width 0.1143)
		(layer "B.Cu")
		(net "UPI_CPU1_CPU0_P0P0_DN<5>")
	)
	(segment
		(start 146.0246 -61.456824)
		(end 147.352004 -61.456824)
		(width 0.1143)
		(layer "B.Cu")
		(net "UPI_CPU1_CPU0_P0P0_DN<5>")
	)
	(segment
		(start 307.526182 -74.795634)
		(end 307.653182 -74.795634)
		(width 0.0889)
		(layer "B.Cu")
		(net "UPI_CPU1_CPU0_P0P0_DN<5>")
	)
	(segment
		(start 309.137812 -75.135994)
		(end 309.668164 -75.393296)
		(width 0.1143)
		(layer "B.Cu")
		(net "UPI_CPU1_CPU0_P0P0_DN<5>")
	)
	(segment
		(start 285.549086 -110.405926)
		(end 288.534348 -107.879642)
		(width 0.1143)
		(layer "B.Cu")
		(net "UPI_CPU1_CPU0_P0P0_DN<5>")
	)
	(segment
		(start 314.654946 -94.746826)
		(end 314.57265 -91.57462)
		(width 0.1143)
		(layer "B.Cu")
		(net "UPI_CPU1_CPU0_P0P0_DN<5>")
	)
	(segment
		(start 191.895476 -111.288068)
		(end 194.528948 -114.42192)
		(width 0.1143)
		(layer "B.Cu")
		(net "UPI_CPU1_CPU0_P0P0_DN<5>")
	)
	(segment
		(start 304.37328 -73.144634)
		(end 304.406046 -73.144634)
		(width 0.0889)
		(layer "B.Cu")
		(net "UPI_CPU1_CPU0_P0P0_DN<5>")
	)
	(segment
		(start 307.754782 -74.897234)
		(end 307.957982 -74.897234)
		(width 0.0889)
		(layer "B.Cu")
		(net "UPI_CPU1_CPU0_P0P0_DN<5>")
	)
	(segment
		(start 311.587642 -76.742798)
		(end 311.889902 -77.285342)
		(width 0.1143)
		(layer "B.Cu")
		(net "UPI_CPU1_CPU0_P0P0_DN<5>")
	)
	(segment
		(start 307.957982 -74.897234)
		(end 308.057042 -74.798174)
		(width 0.0889)
		(layer "B.Cu")
		(net "UPI_CPU1_CPU0_P0P0_DN<5>")
	)
	(segment
		(start 306.883054 -74.3712)
		(end 307.0352 -74.523854)
		(width 0.0889)
		(layer "B.Cu")
		(net "UPI_CPU1_CPU0_P0P0_DN<5>")
	)
	(segment
		(start 145.3769 -61.4172)
		(end 145.5039 -61.4172)
		(width 0.0889)
		(layer "B.Cu")
		(net "UPI_CPU1_CPU0_P0P0_DN<5>")
	)
	(segment
		(start 235.42371 -110.139226)
		(end 245.857776 -106.104436)
		(width 0.1143)
		(layer "B.Cu")
		(net "UPI_CPU1_CPU0_P0P0_DN<5>")
	)
	(segment
		(start 314.386722 -84.413344)
		(end 314.57265 -91.57462)
		(width 0.1143)
		(layer "B.Cu")
		(net "UPI_CPU1_CPU0_P0P0_DN<5>")
	)
	(segment
		(start 145.8341 -61.4172)
		(end 145.984976 -61.4172)
		(width 0.0889)
		(layer "B.Cu")
		(net "UPI_CPU1_CPU0_P0P0_DN<5>")
	)
	(segment
		(start 291.125402 -107.36199)
		(end 292.151308 -107.157012)
		(width 0.1143)
		(layer "B.Cu")
		(net "UPI_CPU1_CPU0_P0P0_DN<5>")
	)
	(segment
		(start 306.014628 -74.135234)
		(end 306.535328 -74.135234)
		(width 0.0889)
		(layer "B.Cu")
		(net "UPI_CPU1_CPU0_P0P0_DN<5>")
	)
	(segment
		(start 314.572142 -94.862142)
		(end 314.654946 -94.746826)
		(width 0.1143)
		(layer "B.Cu")
		(net "UPI_CPU1_CPU0_P0P0_DN<5>")
	)
	(segment
		(start 308.587648 -74.897234)
		(end 309.08371 -75.138026)
		(width 0.0889)
		(layer "B.Cu")
		(net "UPI_CPU1_CPU0_P0P0_DN<5>")
	)
	(segment
		(start 308.057042 -74.798174)
		(end 308.260242 -74.798174)
		(width 0.0889)
		(layer "B.Cu")
		(net "UPI_CPU1_CPU0_P0P0_DN<5>")
	)
	(segment
		(start 305.23815 -108.930186)
		(end 305.269646 -108.92155)
		(width 0.1143)
		(layer "B.Cu")
		(net "UPI_CPU1_CPU0_P0P0_DN<5>")
	)
	(segment
		(start 303.448212 -109.416596)
		(end 305.23815 -108.929932)
		(width 0.1143)
		(layer "B.Cu")
		(net "UPI_CPU1_CPU0_P0P0_DN<5>")
	)
	(segment
		(start 305.23561 -73.640188)
		(end 305.449986 -73.640188)
		(width 0.0889)
		(layer "B.Cu")
		(net "UPI_CPU1_CPU0_P0P0_DN<5>")
	)
	(segment
		(start 307.0352 -74.634852)
		(end 307.297582 -74.897234)
		(width 0.0889)
		(layer "B.Cu")
		(net "UPI_CPU1_CPU0_P0P0_DN<5>")
	)
	(segment
		(start 312.644282 -101.874828)
		(end 313.24042 -98.641916)
		(width 0.1143)
		(layer "B.Cu")
		(net "UPI_CPU1_CPU0_P0P0_DN<5>")
	)
	(segment
		(start 313.309254 -79.8322)
		(end 313.464702 -80.111346)
		(width 0.1143)
		(layer "B.Cu")
		(net "UPI_CPU1_CPU0_P0P0_DN<5>")
	)
	(segment
		(start 292.151308 -107.157012)
		(end 303.43602 -109.414056)
		(width 0.1143)
		(layer "B.Cu")
		(net "UPI_CPU1_CPU0_P0P0_DN<5>")
	)
	(segment
		(start 195.623942 -114.705638)
		(end 197.856602 -114.80419)
		(width 0.1143)
		(layer "B.Cu")
		(net "UPI_CPU1_CPU0_P0P0_DN<5>")
	)
	(segment
		(start 309.137558 -75.13574)
		(end 309.137812 -75.135994)
		(width 0.0889)
		(layer "B.Cu")
		(net "UPI_CPU1_CPU0_P0P0_DN<5>")
	)
	(segment
		(start 163.925758 -96.582992)
		(end 167.602662 -102.160324)
		(width 0.1143)
		(layer "B.Cu")
		(net "UPI_CPU1_CPU0_P0P0_DN<5>")
	)
	(segment
		(start 311.889902 -77.285342)
		(end 313.309254 -79.8322)
		(width 0.1143)
		(layer "B.Cu")
		(net "UPI_CPU1_CPU0_P0P0_DN<5>")
	)
	(segment
		(start 309.226712 -106.585512)
		(end 312.266838 -103.447596)
		(width 0.1143)
		(layer "B.Cu")
		(net "UPI_CPU1_CPU0_P0P0_DN<5>")
	)
	(segment
		(start 308.260242 -74.798174)
		(end 308.359302 -74.897234)
		(width 0.0889)
		(layer "B.Cu")
		(net "UPI_CPU1_CPU0_P0P0_DN<5>")
	)
	(segment
		(start 312.266838 -103.447596)
		(end 312.644282 -101.874828)
		(width 0.1143)
		(layer "B.Cu")
		(net "UPI_CPU1_CPU0_P0P0_DN<5>")
	)
	(segment
		(start 305.23815 -108.929932)
		(end 305.23815 -108.930186)
		(width 0.1143)
		(layer "B.Cu")
		(net "UPI_CPU1_CPU0_P0P0_DN<5>")
	)
	(segment
		(start 307.0352 -74.523854)
		(end 307.0352 -74.634852)
		(width 0.0889)
		(layer "B.Cu")
		(net "UPI_CPU1_CPU0_P0P0_DN<5>")
	)
	(segment
		(start 144.064228 -61.844428)
		(end 143.9164 -61.6966)
		(width 0.0889)
		(layer "B.Cu")
		(net "UPI_CPU1_CPU0_P0P0_DN<5>")
	)
	(segment
		(start 145.984976 -61.4172)
		(end 146.0246 -61.456824)
		(width 0.0889)
		(layer "B.Cu")
		(net "UPI_CPU1_CPU0_P0P0_DN<5>")
	)
	(segment
		(start 145.7325 -61.5188)
		(end 145.8341 -61.4172)
		(width 0.0889)
		(layer "B.Cu")
		(net "UPI_CPU1_CPU0_P0P0_DN<5>")
	)
	(segment
		(start 303.43602 -109.414056)
		(end 303.448212 -109.416596)
		(width 0.1143)
		(layer "B.Cu")
		(net "UPI_CPU1_CPU0_P0P0_DN<5>")
	)
	(segment
		(start 145.6055 -61.5188)
		(end 145.7325 -61.5188)
		(width 0.0889)
		(layer "B.Cu")
		(net "UPI_CPU1_CPU0_P0P0_DN<5>")
	)
	(segment
		(start 309.668164 -75.393296)
		(end 310.122316 -75.555094)
		(width 0.1143)
		(layer "B.Cu")
		(net "UPI_CPU1_CPU0_P0P0_DN<5>")
	)
	(segment
		(start 307.297582 -74.897234)
		(end 307.424582 -74.897234)
		(width 0.0889)
		(layer "B.Cu")
		(net "UPI_CPU1_CPU0_P0P0_DN<5>")
	)
	(segment
		(start 313.522614 -96.32442)
		(end 314.572142 -94.862142)
		(width 0.1143)
		(layer "B.Cu")
		(net "UPI_CPU1_CPU0_P0P0_DN<5>")
	)
	(segment
		(start 176.45507 -107.13339)
		(end 178.976782 -109.451648)
		(width 0.1143)
		(layer "B.Cu")
		(net "UPI_CPU1_CPU0_P0P0_DN<5>")
	)
	(segment
		(start 145.5039 -61.4172)
		(end 145.6055 -61.5188)
		(width 0.0889)
		(layer "B.Cu")
		(net "UPI_CPU1_CPU0_P0P0_DN<5>")
	)
	(segment
		(start 143.9164 -61.6966)
		(end 143.9164 -61.5442)
		(width 0.0889)
		(layer "B.Cu")
		(net "UPI_CPU1_CPU0_P0P0_DN<5>")
	)
	(segment
		(start 313.85129 -81.915)
		(end 314.386722 -84.413344)
		(width 0.1143)
		(layer "B.Cu")
		(net "UPI_CPU1_CPU0_P0P0_DN<5>")
	)
	(segment
		(start 145.0467 -61.4172)
		(end 145.1483 -61.5188)
		(width 0.0889)
		(layer "B.Cu")
		(net "UPI_CPU1_CPU0_P0P0_DN<5>")
	)
	(segment
		(start 309.117746 -75.126088)
		(end 309.137558 -75.13574)
		(width 0.0889)
		(layer "B.Cu")
		(net "UPI_CPU1_CPU0_P0P0_DN<5>")
	)
	(segment
		(start 308.359302 -74.897234)
		(end 308.587648 -74.897234)
		(width 0.0889)
		(layer "B.Cu")
		(net "UPI_CPU1_CPU0_P0P0_DN<5>")
	)
	(segment
		(start 303.23663 -72.080374)
		(end 303.15789 -72.10171)
		(width 0.0889)
		(layer "B.Cu")
		(net "UPI_CPU1_CPU0_P0P0_DN<5>")
	)
	(segment
		(start 153.32964 -67.434714)
		(end 157.74797 -89.523316)
		(width 0.1143)
		(layer "B.Cu")
		(net "UPI_CPU1_CPU0_P0P0_DN<5>")
	)
	(segment
		(start 309.08371 -75.138026)
		(end 309.117746 -75.126088)
		(width 0.0889)
		(layer "B.Cu")
		(net "UPI_CPU1_CPU0_P0P0_DN<5>")
	)
	(segment
		(start 258.922012 -108.736638)
		(end 282.120848 -111.090964)
		(width 0.1143)
		(layer "B.Cu")
		(net "UPI_CPU1_CPU0_P0P0_DN<5>")
	)
	(segment
		(start 197.856602 -114.80419)
		(end 204.631544 -113.896648)
		(width 0.1143)
		(layer "B.Cu")
		(net "UPI_CPU1_CPU0_P0P0_DN<5>")
	)
	(segment
		(start 310.122316 -75.555094)
		(end 311.587642 -76.742798)
		(width 0.1143)
		(layer "B.Cu")
		(net "UPI_CPU1_CPU0_P0P0_DN<5>")
	)
	(segment
		(start 282.120848 -111.090964)
		(end 285.549086 -110.405926)
		(width 0.1143)
		(layer "B.Cu")
		(net "UPI_CPU1_CPU0_P0P0_DN<5>")
	)
	(segment
		(start 307.424582 -74.897234)
		(end 307.526182 -74.795634)
		(width 0.0889)
		(layer "B.Cu")
		(net "UPI_CPU1_CPU0_P0P0_DN<5>")
	)
	(segment
		(start 305.269646 -108.92155)
		(end 309.226712 -106.585512)
		(width 0.1143)
		(layer "B.Cu")
		(net "UPI_CPU1_CPU0_P0P0_DN<5>")
	)
	(segment
		(start 186.458098 -109.920532)
		(end 187.823602 -110.72368)
		(width 0.1143)
		(layer "B.Cu")
		(net "UPI_CPU1_CPU0_P0P0_DN<5>")
	)
	(segment
		(start 245.857776 -106.104436)
		(end 249.611896 -105.964482)
		(width 0.1143)
		(layer "B.Cu")
		(net "UPI_CPU1_CPU0_P0P0_DN<5>")
	)
	(segment
		(start 170.758612 -105.183178)
		(end 176.45507 -107.13339)
		(width 0.1143)
		(layer "B.Cu")
		(net "UPI_CPU1_CPU0_P0P0_DN<5>")
	)
	(segment
		(start 204.631544 -113.896648)
		(end 225.757486 -109.654594)
		(width 0.1143)
		(layer "B.Cu")
		(net "UPI_CPU1_CPU0_P0P0_DN<5>")
	)
	(segment
		(start 313.24042 -98.641916)
		(end 313.522614 -96.32442)
		(width 0.1143)
		(layer "B.Cu")
		(net "UPI_CPU1_CPU0_P0P0_DN<5>")
	)
	(segment
		(start 307.653182 -74.795634)
		(end 307.754782 -74.897234)
		(width 0.0889)
		(layer "B.Cu")
		(net "UPI_CPU1_CPU0_P0P0_DN<5>")
	)
	(segment
		(start 303.529746 -72.249538)
		(end 303.23663 -72.080374)
		(width 0.0889)
		(layer "B.Cu")
		(net "UPI_CPU1_CPU0_P0P0_DN<5>")
	)
	(segment
		(start 313.464702 -80.111346)
		(end 313.85129 -81.915)
		(width 0.1143)
		(layer "B.Cu")
		(net "UPI_CPU1_CPU0_P0P0_DN<5>")
	)
	(segment
		(start 194.528948 -114.42192)
		(end 195.623942 -114.705638)
		(width 0.1143)
		(layer "B.Cu")
		(net "UPI_CPU1_CPU0_P0P0_DN<5>")
	)
	(segment
		(start 303.51857 -72.649588)
		(end 303.551336 -72.649588)
		(width 0.0889)
		(layer "B.Cu")
		(net "UPI_CPU1_CPU0_P0P0_DN<5>")
	)
	(segment
		(start 189.731396 -110.89259)
		(end 190.625476 -110.735618)
		(width 0.1143)
		(layer "B.Cu")
		(net "UPI_CPU1_CPU0_P0P0_DN<5>")
	)
	(segment
		(start 144.0434 -61.4172)
		(end 145.0467 -61.4172)
		(width 0.0889)
		(layer "B.Cu")
		(net "UPI_CPU1_CPU0_P0P0_DN<5>")
	)
	(segment
		(start 225.757486 -109.654594)
		(end 235.42371 -110.139226)
		(width 0.1143)
		(layer "B.Cu")
		(net "UPI_CPU1_CPU0_P0P0_DN<5>")
	)
	(segment
		(start 306.771294 -74.3712)
		(end 306.883054 -74.3712)
		(width 0.0889)
		(layer "B.Cu")
		(net "UPI_CPU1_CPU0_P0P0_DN<5>")
	)
	(segment
		(start 190.625476 -110.735618)
		(end 191.895476 -111.288068)
		(width 0.1143)
		(layer "B.Cu")
		(net "UPI_CPU1_CPU0_P0P0_DN<5>")
	)
	(segment
		(start 249.611896 -105.964482)
		(end 258.922012 -108.736638)
		(width 0.1143)
		(layer "B.Cu")
		(net "UPI_CPU1_CPU0_P0P0_DN<5>")
	)
	(segment
		(start 288.534348 -107.879642)
		(end 291.125402 -107.36199)
		(width 0.1143)
		(layer "B.Cu")
		(net "UPI_CPU1_CPU0_P0P0_DN<5>")
	)
	(segment
		(start 167.602662 -102.160324)
		(end 170.758612 -105.183178)
		(width 0.1143)
		(layer "B.Cu")
		(net "UPI_CPU1_CPU0_P0P0_DN<5>")
	)
	(segment
		(start 144.238472 -61.844428)
		(end 144.064228 -61.844428)
		(width 0.0889)
		(layer "B.Cu")
		(net "UPI_CPU1_CPU0_P0P0_DN<5>")
	)
	(arc
		(start 303.551336 -72.649588)
		(mid 303.834553 -72.733869)
		(end 304.041556 -72.944736)
		(width 0.0889)
		(layer "B.Cu")
		(net "UPI_CPU1_CPU0_P0P0_DN<5>")
	)
	(arc
		(start 305.798474 -73.93813)
		(mid 305.889418 -74.055473)
		(end 306.014628 -74.135234)
		(width 0.0889)
		(layer "B.Cu")
		(net "UPI_CPU1_CPU0_P0P0_DN<5>")
	)
	(arc
		(start 304.406046 -73.144634)
		(mid 304.69147 -73.228101)
		(end 304.900076 -73.440036)
		(width 0.0889)
		(layer "B.Cu")
		(net "UPI_CPU1_CPU0_P0P0_DN<5>")
	)
	(arc
		(start 304.900076 -73.440036)
		(mid 305.041759 -73.58384)
		(end 305.23561 -73.640188)
		(width 0.0889)
		(layer "B.Cu")
		(net "UPI_CPU1_CPU0_P0P0_DN<5>")
	)
	(arc
		(start 303.139856 -72.339454)
		(mid 303.276255 -72.559232)
		(end 303.51857 -72.649588)
		(width 0.0889)
		(layer "B.Cu")
		(net "UPI_CPU1_CPU0_P0P0_DN<5>")
	)
	(arc
		(start 305.449986 -73.640188)
		(mid 305.65258 -73.756006)
		(end 305.798474 -73.93813)
		(width 0.0889)
		(layer "B.Cu")
		(net "UPI_CPU1_CPU0_P0P0_DN<5>")
	)
	(arc
		(start 304.041556 -72.944736)
		(mid 304.181635 -73.087472)
		(end 304.37328 -73.144634)
		(width 0.0889)
		(layer "B.Cu")
		(net "UPI_CPU1_CPU0_P0P0_DN<5>")
	)
	(arc
		(start 303.15789 -72.10171)
		(mid 303.130752 -72.219209)
		(end 303.139856 -72.339454)
		(width 0.0889)
		(layer "B.Cu")
		(net "UPI_CPU1_CPU0_P0P0_DN<5>")
	)
	(segment
		(start 140.533374 -61.847984)
		(end 141.104874 -61.847984)
		(width 0.1143)
		(layer "F.Cu")
		(net "UPI_CPU1_CPU0_P0P0_DN<4>")
	)
	(segment
		(start 302.099726 -72.744584)
		(end 302.671226 -72.744584)
		(width 0.1143)
		(layer "F.Cu")
		(net "UPI_CPU1_CPU0_P0P0_DN<4>")
	)
	(via
		(at 141.104874 -61.847984)
		(size 0.508)
		(drill 0.254)
		(layers "F.Cu" "B.Cu")
		(net "UPI_CPU1_CPU0_P0P0_DN<4>")
	)
	(via
		(at 302.671226 -72.744584)
		(size 0.508)
		(drill 0.254)
		(layers "F.Cu" "B.Cu")
		(net "UPI_CPU1_CPU0_P0P0_DN<4>")
	)
	(segment
		(start 144.347184 -60.247784)
		(end 144.3736 -60.2742)
		(width 0.0889)
		(layer "B.Cu")
		(net "UPI_CPU1_CPU0_P0P0_DN<4>")
	)
	(segment
		(start 313.484006 -93.011498)
		(end 313.404504 -89.948004)
		(width 0.1143)
		(layer "B.Cu")
		(net "UPI_CPU1_CPU0_P0P0_DN<4>")
	)
	(segment
		(start 189.481206 -108.5596)
		(end 190.733172 -109.000544)
		(width 0.1143)
		(layer "B.Cu")
		(net "UPI_CPU1_CPU0_P0P0_DN<4>")
	)
	(segment
		(start 303.551336 -73.640188)
		(end 303.51857 -73.640188)
		(width 0.0889)
		(layer "B.Cu")
		(net "UPI_CPU1_CPU0_P0P0_DN<4>")
	)
	(segment
		(start 176.962816 -106.285284)
		(end 179.380388 -108.507022)
		(width 0.1143)
		(layer "B.Cu")
		(net "UPI_CPU1_CPU0_P0P0_DN<4>")
	)
	(segment
		(start 308.447948 -75.900534)
		(end 308.220618 -75.900026)
		(width 0.1143)
		(layer "B.Cu")
		(net "UPI_CPU1_CPU0_P0P0_DN<4>")
	)
	(segment
		(start 179.380388 -108.507022)
		(end 184.427622 -108.824014)
		(width 0.1143)
		(layer "B.Cu")
		(net "UPI_CPU1_CPU0_P0P0_DN<4>")
	)
	(segment
		(start 142.475204 -61.648086)
		(end 143.875506 -60.247784)
		(width 0.0889)
		(layer "B.Cu")
		(net "UPI_CPU1_CPU0_P0P0_DN<4>")
	)
	(segment
		(start 154.136598 -67.083178)
		(end 158.505144 -88.919304)
		(width 0.1143)
		(layer "B.Cu")
		(net "UPI_CPU1_CPU0_P0P0_DN<4>")
	)
	(segment
		(start 311.76214 -101.27234)
		(end 312.2295 -98.6409)
		(width 0.1143)
		(layer "B.Cu")
		(net "UPI_CPU1_CPU0_P0P0_DN<4>")
	)
	(segment
		(start 146.3421 -60.2742)
		(end 146.51355 -60.44565)
		(width 0.1143)
		(layer "B.Cu")
		(net "UPI_CPU1_CPU0_P0P0_DN<4>")
	)
	(segment
		(start 307.960014 -75.900026)
		(end 307.934614 -75.925426)
		(width 0.0889)
		(layer "B.Cu")
		(net "UPI_CPU1_CPU0_P0P0_DN<4>")
	)
	(segment
		(start 307.982112 -75.900026)
		(end 307.960014 -75.900026)
		(width 0.0889)
		(layer "B.Cu")
		(net "UPI_CPU1_CPU0_P0P0_DN<4>")
	)
	(segment
		(start 310.723534 -77.494892)
		(end 308.447948 -75.900534)
		(width 0.1143)
		(layer "B.Cu")
		(net "UPI_CPU1_CPU0_P0P0_DN<4>")
	)
	(segment
		(start 313.404504 -89.948004)
		(end 313.276488 -85.020658)
		(width 0.1143)
		(layer "B.Cu")
		(net "UPI_CPU1_CPU0_P0P0_DN<4>")
	)
	(segment
		(start 313.50458 -93.79458)
		(end 313.504072 -93.7768)
		(width 0.1143)
		(layer "B.Cu")
		(net "UPI_CPU1_CPU0_P0P0_DN<4>")
	)
	(segment
		(start 312.573162 -95.725996)
		(end 313.520328 -94.40672)
		(width 0.1143)
		(layer "B.Cu")
		(net "UPI_CPU1_CPU0_P0P0_DN<4>")
	)
	(segment
		(start 245.088918 -105.365804)
		(end 250.34367 -105.170478)
		(width 0.1143)
		(layer "B.Cu")
		(net "UPI_CPU1_CPU0_P0P0_DN<4>")
	)
	(segment
		(start 195.992496 -113.95837)
		(end 197.80631 -114.036094)
		(width 0.1143)
		(layer "B.Cu")
		(net "UPI_CPU1_CPU0_P0P0_DN<4>")
	)
	(segment
		(start 195.248022 -113.58499)
		(end 195.992496 -113.95837)
		(width 0.1143)
		(layer "B.Cu")
		(net "UPI_CPU1_CPU0_P0P0_DN<4>")
	)
	(segment
		(start 302.736504 -73.147936)
		(end 302.671226 -73.082658)
		(width 0.0889)
		(layer "B.Cu")
		(net "UPI_CPU1_CPU0_P0P0_DN<4>")
	)
	(segment
		(start 147.49907 -60.44565)
		(end 154.136598 -67.083178)
		(width 0.1143)
		(layer "B.Cu")
		(net "UPI_CPU1_CPU0_P0P0_DN<4>")
	)
	(segment
		(start 311.318656 -103.009954)
		(end 311.76214 -101.27234)
		(width 0.1143)
		(layer "B.Cu")
		(net "UPI_CPU1_CPU0_P0P0_DN<4>")
	)
	(segment
		(start 291.125402 -106.577384)
		(end 292.330378 -106.336592)
		(width 0.1143)
		(layer "B.Cu")
		(net "UPI_CPU1_CPU0_P0P0_DN<4>")
	)
	(segment
		(start 144.3736 -60.2742)
		(end 146.3421 -60.2742)
		(width 0.1143)
		(layer "B.Cu")
		(net "UPI_CPU1_CPU0_P0P0_DN<4>")
	)
	(segment
		(start 170.558968 -103.651558)
		(end 173.333156 -105.042208)
		(width 0.1143)
		(layer "B.Cu")
		(net "UPI_CPU1_CPU0_P0P0_DN<4>")
	)
	(segment
		(start 203.17841 -113.31702)
		(end 203.427584 -113.151412)
		(width 0.1143)
		(layer "B.Cu")
		(net "UPI_CPU1_CPU0_P0P0_DN<4>")
	)
	(segment
		(start 250.34367 -105.170478)
		(end 259.118608 -107.784138)
		(width 0.1143)
		(layer "B.Cu")
		(net "UPI_CPU1_CPU0_P0P0_DN<4>")
	)
	(segment
		(start 307.934614 -75.925426)
		(end 307.748178 -75.925426)
		(width 0.0889)
		(layer "B.Cu")
		(net "UPI_CPU1_CPU0_P0P0_DN<4>")
	)
	(segment
		(start 143.875506 -60.247784)
		(end 144.347184 -60.247784)
		(width 0.0889)
		(layer "B.Cu")
		(net "UPI_CPU1_CPU0_P0P0_DN<4>")
	)
	(segment
		(start 304.888646 -108.03001)
		(end 308.610762 -105.817924)
		(width 0.1143)
		(layer "B.Cu")
		(net "UPI_CPU1_CPU0_P0P0_DN<4>")
	)
	(segment
		(start 292.330378 -106.336592)
		(end 303.167288 -108.504736)
		(width 0.1143)
		(layer "B.Cu")
		(net "UPI_CPU1_CPU0_P0P0_DN<4>")
	)
	(segment
		(start 308.220618 -75.900026)
		(end 307.982112 -75.900026)
		(width 0.1143)
		(layer "B.Cu")
		(net "UPI_CPU1_CPU0_P0P0_DN<4>")
	)
	(segment
		(start 312.095388 -79.956406)
		(end 312.026046 -79.8322)
		(width 0.1143)
		(layer "B.Cu")
		(net "UPI_CPU1_CPU0_P0P0_DN<4>")
	)
	(segment
		(start 285.132526 -109.436408)
		(end 287.668462 -107.268518)
		(width 0.1143)
		(layer "B.Cu")
		(net "UPI_CPU1_CPU0_P0P0_DN<4>")
	)
	(segment
		(start 197.80631 -114.036094)
		(end 203.17841 -113.31702)
		(width 0.1143)
		(layer "B.Cu")
		(net "UPI_CPU1_CPU0_P0P0_DN<4>")
	)
	(segment
		(start 168.350692 -101.5365)
		(end 170.558968 -103.651558)
		(width 0.1143)
		(layer "B.Cu")
		(net "UPI_CPU1_CPU0_P0P0_DN<4>")
	)
	(segment
		(start 312.24982 -98.5266)
		(end 312.573162 -95.725996)
		(width 0.1143)
		(layer "B.Cu")
		(net "UPI_CPU1_CPU0_P0P0_DN<4>")
	)
	(segment
		(start 287.668462 -107.268518)
		(end 291.125402 -106.577384)
		(width 0.1143)
		(layer "B.Cu")
		(net "UPI_CPU1_CPU0_P0P0_DN<4>")
	)
	(segment
		(start 304.406046 -74.135234)
		(end 304.37328 -74.135234)
		(width 0.0889)
		(layer "B.Cu")
		(net "UPI_CPU1_CPU0_P0P0_DN<4>")
	)
	(segment
		(start 190.733172 -109.000544)
		(end 192.311274 -110.49127)
		(width 0.1143)
		(layer "B.Cu")
		(net "UPI_CPU1_CPU0_P0P0_DN<4>")
	)
	(segment
		(start 259.118608 -107.784138)
		(end 281.858212 -110.09122)
		(width 0.1143)
		(layer "B.Cu")
		(net "UPI_CPU1_CPU0_P0P0_DN<4>")
	)
	(segment
		(start 312.026046 -79.8322)
		(end 310.723534 -77.494892)
		(width 0.1143)
		(layer "B.Cu")
		(net "UPI_CPU1_CPU0_P0P0_DN<4>")
	)
	(segment
		(start 192.311274 -110.49127)
		(end 195.248022 -113.58499)
		(width 0.1143)
		(layer "B.Cu")
		(net "UPI_CPU1_CPU0_P0P0_DN<4>")
	)
	(segment
		(start 235.266992 -109.162342)
		(end 245.088918 -105.365804)
		(width 0.1143)
		(layer "B.Cu")
		(net "UPI_CPU1_CPU0_P0P0_DN<4>")
	)
	(segment
		(start 184.427622 -108.824014)
		(end 189.481206 -108.5596)
		(width 0.1143)
		(layer "B.Cu")
		(net "UPI_CPU1_CPU0_P0P0_DN<4>")
	)
	(segment
		(start 312.55208 -81.915)
		(end 312.095388 -79.956406)
		(width 0.1143)
		(layer "B.Cu")
		(net "UPI_CPU1_CPU0_P0P0_DN<4>")
	)
	(segment
		(start 313.504072 -93.7768)
		(end 313.484006 -93.011498)
		(width 0.1143)
		(layer "B.Cu")
		(net "UPI_CPU1_CPU0_P0P0_DN<4>")
	)
	(segment
		(start 313.276488 -85.020658)
		(end 312.55208 -81.915)
		(width 0.1143)
		(layer "B.Cu")
		(net "UPI_CPU1_CPU0_P0P0_DN<4>")
	)
	(segment
		(start 303.167288 -108.504736)
		(end 304.888646 -108.03001)
		(width 0.1143)
		(layer "B.Cu")
		(net "UPI_CPU1_CPU0_P0P0_DN<4>")
	)
	(segment
		(start 225.686112 -108.682028)
		(end 235.266992 -109.162342)
		(width 0.1143)
		(layer "B.Cu")
		(net "UPI_CPU1_CPU0_P0P0_DN<4>")
	)
	(segment
		(start 302.671226 -73.082658)
		(end 302.671226 -72.744584)
		(width 0.0889)
		(layer "B.Cu")
		(net "UPI_CPU1_CPU0_P0P0_DN<4>")
	)
	(segment
		(start 141.336776 -61.943996)
		(end 141.960346 -61.943996)
		(width 0.0889)
		(layer "B.Cu")
		(net "UPI_CPU1_CPU0_P0P0_DN<4>")
	)
	(segment
		(start 306.454556 -75.125834)
		(end 306.03317 -75.125834)
		(width 0.0889)
		(layer "B.Cu")
		(net "UPI_CPU1_CPU0_P0P0_DN<4>")
	)
	(segment
		(start 203.427584 -113.151412)
		(end 225.686112 -108.682028)
		(width 0.1143)
		(layer "B.Cu")
		(net "UPI_CPU1_CPU0_P0P0_DN<4>")
	)
	(segment
		(start 164.69741 -95.99549)
		(end 168.350692 -101.5365)
		(width 0.1143)
		(layer "B.Cu")
		(net "UPI_CPU1_CPU0_P0P0_DN<4>")
	)
	(segment
		(start 305.052222 -74.694288)
		(end 304.900076 -74.430636)
		(width 0.0889)
		(layer "B.Cu")
		(net "UPI_CPU1_CPU0_P0P0_DN<4>")
	)
	(segment
		(start 173.333156 -105.042208)
		(end 176.962816 -106.285284)
		(width 0.1143)
		(layer "B.Cu")
		(net "UPI_CPU1_CPU0_P0P0_DN<4>")
	)
	(segment
		(start 312.2295 -98.6409)
		(end 312.24982 -98.5266)
		(width 0.1143)
		(layer "B.Cu")
		(net "UPI_CPU1_CPU0_P0P0_DN<4>")
	)
	(segment
		(start 307.748178 -75.925426)
		(end 306.454556 -75.125834)
		(width 0.0889)
		(layer "B.Cu")
		(net "UPI_CPU1_CPU0_P0P0_DN<4>")
	)
	(segment
		(start 281.858212 -110.09122)
		(end 285.132526 -109.436408)
		(width 0.1143)
		(layer "B.Cu")
		(net "UPI_CPU1_CPU0_P0P0_DN<4>")
	)
	(segment
		(start 158.505144 -88.919304)
		(end 164.69741 -95.99549)
		(width 0.1143)
		(layer "B.Cu")
		(net "UPI_CPU1_CPU0_P0P0_DN<4>")
	)
	(segment
		(start 313.520328 -94.40672)
		(end 313.50458 -93.79458)
		(width 0.1143)
		(layer "B.Cu")
		(net "UPI_CPU1_CPU0_P0P0_DN<4>")
	)
	(segment
		(start 308.610762 -105.817924)
		(end 311.318656 -103.009954)
		(width 0.1143)
		(layer "B.Cu")
		(net "UPI_CPU1_CPU0_P0P0_DN<4>")
	)
	(segment
		(start 146.51355 -60.44565)
		(end 147.49907 -60.44565)
		(width 0.1143)
		(layer "B.Cu")
		(net "UPI_CPU1_CPU0_P0P0_DN<4>")
	)
	(segment
		(start 306.03317 -75.125834)
		(end 305.052222 -74.694288)
		(width 0.0889)
		(layer "B.Cu")
		(net "UPI_CPU1_CPU0_P0P0_DN<4>")
	)
	(arc
		(start 304.900076 -74.430636)
		(mid 304.691468 -74.218704)
		(end 304.406046 -74.135234)
		(width 0.0889)
		(layer "B.Cu")
		(net "UPI_CPU1_CPU0_P0P0_DN<4>")
	)
	(arc
		(start 141.104874 -61.847984)
		(mid 141.211272 -61.919077)
		(end 141.336776 -61.943996)
		(width 0.0889)
		(layer "B.Cu")
		(net "UPI_CPU1_CPU0_P0P0_DN<4>")
	)
	(arc
		(start 304.37328 -74.135234)
		(mid 304.181638 -74.078068)
		(end 304.041556 -73.935336)
		(width 0.0889)
		(layer "B.Cu")
		(net "UPI_CPU1_CPU0_P0P0_DN<4>")
	)
	(arc
		(start 141.960346 -61.943996)
		(mid 142.257615 -61.865385)
		(end 142.475204 -61.648086)
		(width 0.0889)
		(layer "B.Cu")
		(net "UPI_CPU1_CPU0_P0P0_DN<4>")
	)
	(arc
		(start 303.183036 -73.440036)
		(mid 302.994613 -73.240732)
		(end 302.736504 -73.147936)
		(width 0.0889)
		(layer "B.Cu")
		(net "UPI_CPU1_CPU0_P0P0_DN<4>")
	)
	(arc
		(start 303.51857 -73.640188)
		(mid 303.32472 -73.583838)
		(end 303.183036 -73.440036)
		(width 0.0889)
		(layer "B.Cu")
		(net "UPI_CPU1_CPU0_P0P0_DN<4>")
	)
	(arc
		(start 304.041556 -73.935336)
		(mid 303.834552 -73.724472)
		(end 303.551336 -73.640188)
		(width 0.0889)
		(layer "B.Cu")
		(net "UPI_CPU1_CPU0_P0P0_DN<4>")
	)
	(segment
		(start 301.241206 -70.268084)
		(end 301.812706 -70.268084)
		(width 0.1143)
		(layer "F.Cu")
		(net "UPI_CPU1_CPU0_P0P0_DN<3>")
	)
	(segment
		(start 141.927834 -60.671456)
		(end 141.908276 -60.598304)
		(width 0.0889)
		(layer "F.Cu")
		(net "UPI_CPU1_CPU0_P0P0_DN<3>")
	)
	(segment
		(start 145.076164 -60.492132)
		(end 146.40687 -59.161426)
		(width 0.1143)
		(layer "F.Cu")
		(net "UPI_CPU1_CPU0_P0P0_DN<3>")
	)
	(segment
		(start 142.250414 -60.857384)
		(end 141.927834 -60.671456)
		(width 0.0889)
		(layer "F.Cu")
		(net "UPI_CPU1_CPU0_P0P0_DN<3>")
	)
	(segment
		(start 146.40687 -59.161426)
		(end 146.563588 -59.161426)
		(width 0.1143)
		(layer "F.Cu")
		(net "UPI_CPU1_CPU0_P0P0_DN<3>")
	)
	(segment
		(start 143.515588 -60.453016)
		(end 143.554704 -60.492132)
		(width 0.0889)
		(layer "F.Cu")
		(net "UPI_CPU1_CPU0_P0P0_DN<3>")
	)
	(segment
		(start 143.554704 -60.492132)
		(end 145.076164 -60.492132)
		(width 0.1143)
		(layer "F.Cu")
		(net "UPI_CPU1_CPU0_P0P0_DN<3>")
	)
	(segment
		(start 146.563588 -59.161426)
		(end 146.769328 -59.367166)
		(width 0.1143)
		(layer "F.Cu")
		(net "UPI_CPU1_CPU0_P0P0_DN<3>")
	)
	(segment
		(start 142.03299 -60.453016)
		(end 143.515588 -60.453016)
		(width 0.0889)
		(layer "F.Cu")
		(net "UPI_CPU1_CPU0_P0P0_DN<3>")
	)
	(via
		(at 146.769328 -59.367166)
		(size 0.508)
		(drill 0.254)
		(layers "F.Cu" "B.Cu")
		(net "UPI_CPU1_CPU0_P0P0_DN<3>")
	)
	(via
		(at 312.184034 -86.371684)
		(size 0.508)
		(drill 0.254)
		(layers "F.Cu" "B.Cu")
		(net "UPI_CPU1_CPU0_P0P0_DN<3>")
	)
	(via
		(at 301.812706 -70.268084)
		(size 0.508)
		(drill 0.254)
		(layers "F.Cu" "B.Cu")
		(net "UPI_CPU1_CPU0_P0P0_DN<3>")
	)
	(arc
		(start 141.908276 -60.598304)
		(mid 141.913134 -60.526149)
		(end 141.961108 -60.472066)
		(width 0.0889)
		(layer "F.Cu")
		(net "UPI_CPU1_CPU0_P0P0_DN<3>")
	)
	(arc
		(start 141.961108 -60.472066)
		(mid 141.995802 -60.457824)
		(end 142.03299 -60.453016)
		(width 0.0889)
		(layer "F.Cu")
		(net "UPI_CPU1_CPU0_P0P0_DN<3>")
	)
	(segment
		(start 312.346848 -92.636848)
		(end 312.33491 -92.186252)
		(width 0.1143)
		(layer "B.Cu")
		(net "UPI_CPU1_CPU0_P0P0_DN<3>")
	)
	(segment
		(start 309.800752 -78.141322)
		(end 308.251606 -76.949046)
		(width 0.1143)
		(layer "B.Cu")
		(net "UPI_CPU1_CPU0_P0P0_DN<3>")
	)
	(segment
		(start 306.83073 -76.520548)
		(end 306.670456 -76.442316)
		(width 0.0889)
		(layer "B.Cu")
		(net "UPI_CPU1_CPU0_P0P0_DN<3>")
	)
	(segment
		(start 307.6956 -105.21315)
		(end 307.96992 -105.04551)
		(width 0.1143)
		(layer "B.Cu")
		(net "UPI_CPU1_CPU0_P0P0_DN<3>")
	)
	(segment
		(start 301.834296 -71.658988)
		(end 301.80153 -71.658988)
		(width 0.0889)
		(layer "B.Cu")
		(net "UPI_CPU1_CPU0_P0P0_DN<3>")
	)
	(segment
		(start 305.575208 -75.852274)
		(end 305.041554 -75.485752)
		(width 0.0889)
		(layer "B.Cu")
		(net "UPI_CPU1_CPU0_P0P0_DN<3>")
	)
	(segment
		(start 312.383932 -94.069154)
		(end 312.346848 -92.636848)
		(width 0.1143)
		(layer "B.Cu")
		(net "UPI_CPU1_CPU0_P0P0_DN<3>")
	)
	(segment
		(start 159.110172 -87.989156)
		(end 159.149542 -88.186006)
		(width 0.1143)
		(layer "B.Cu")
		(net "UPI_CPU1_CPU0_P0P0_DN<3>")
	)
	(segment
		(start 292.136576 -105.49128)
		(end 302.825658 -107.62869)
		(width 0.1143)
		(layer "B.Cu")
		(net "UPI_CPU1_CPU0_P0P0_DN<3>")
	)
	(segment
		(start 312.33491 -92.186252)
		(end 312.184034 -86.371684)
		(width 0.1143)
		(layer "B.Cu")
		(net "UPI_CPU1_CPU0_P0P0_DN<3>")
	)
	(segment
		(start 308.048152 -76.949046)
		(end 308.026054 -76.949046)
		(width 0.0889)
		(layer "B.Cu")
		(net "UPI_CPU1_CPU0_P0P0_DN<3>")
	)
	(segment
		(start 251.01423 -104.361996)
		(end 259.26542 -106.818684)
		(width 0.1143)
		(layer "B.Cu")
		(net "UPI_CPU1_CPU0_P0P0_DN<3>")
	)
	(segment
		(start 189.85484 -107.82046)
		(end 190.600076 -108.053378)
		(width 0.1143)
		(layer "B.Cu")
		(net "UPI_CPU1_CPU0_P0P0_DN<3>")
	)
	(segment
		(start 305.017932 -75.35799)
		(end 304.87112 -75.256898)
		(width 0.0889)
		(layer "B.Cu")
		(net "UPI_CPU1_CPU0_P0P0_DN<3>")
	)
	(segment
		(start 190.600076 -108.053378)
		(end 192.010284 -108.646722)
		(width 0.1143)
		(layer "B.Cu")
		(net "UPI_CPU1_CPU0_P0P0_DN<3>")
	)
	(segment
		(start 301.44085 -70.12051)
		(end 301.51959 -70.099174)
		(width 0.0889)
		(layer "B.Cu")
		(net "UPI_CPU1_CPU0_P0P0_DN<3>")
	)
	(segment
		(start 194.674744 -111.870236)
		(end 195.600574 -112.845596)
		(width 0.1143)
		(layer "B.Cu")
		(net "UPI_CPU1_CPU0_P0P0_DN<3>")
	)
	(segment
		(start 310.40832 -102.403402)
		(end 310.829706 -100.808536)
		(width 0.1143)
		(layer "B.Cu")
		(net "UPI_CPU1_CPU0_P0P0_DN<3>")
	)
	(segment
		(start 259.26542 -106.818684)
		(end 281.791918 -109.087412)
		(width 0.1143)
		(layer "B.Cu")
		(net "UPI_CPU1_CPU0_P0P0_DN<3>")
	)
	(segment
		(start 309.18023 -103.734108)
		(end 310.40832 -102.403402)
		(width 0.1143)
		(layer "B.Cu")
		(net "UPI_CPU1_CPU0_P0P0_DN<3>")
	)
	(segment
		(start 307.311806 -76.754228)
		(end 307.151532 -76.675996)
		(width 0.0889)
		(layer "B.Cu")
		(net "UPI_CPU1_CPU0_P0P0_DN<3>")
	)
	(segment
		(start 306.871878 -76.640182)
		(end 306.83073 -76.520548)
		(width 0.0889)
		(layer "B.Cu")
		(net "UPI_CPU1_CPU0_P0P0_DN<3>")
	)
	(segment
		(start 203.049378 -112.24006)
		(end 225.615754 -107.709462)
		(width 0.1143)
		(layer "B.Cu")
		(net "UPI_CPU1_CPU0_P0P0_DN<3>")
	)
	(segment
		(start 311.436512 -95.38843)
		(end 312.383932 -94.069154)
		(width 0.1143)
		(layer "B.Cu")
		(net "UPI_CPU1_CPU0_P0P0_DN<3>")
	)
	(segment
		(start 310.861964 -80.044544)
		(end 310.7436 -79.8322)
		(width 0.1143)
		(layer "B.Cu")
		(net "UPI_CPU1_CPU0_P0P0_DN<3>")
	)
	(segment
		(start 176.407318 -104.46004)
		(end 176.407318 -104.460294)
		(width 0.1143)
		(layer "B.Cu")
		(net "UPI_CPU1_CPU0_P0P0_DN<3>")
	)
	(segment
		(start 147.627594 -59.13882)
		(end 154.766772 -66.278252)
		(width 0.1143)
		(layer "B.Cu")
		(net "UPI_CPU1_CPU0_P0P0_DN<3>")
	)
	(segment
		(start 307.032152 -76.71816)
		(end 306.871878 -76.640182)
		(width 0.0889)
		(layer "B.Cu")
		(net "UPI_CPU1_CPU0_P0P0_DN<3>")
	)
	(segment
		(start 202.45324 -112.638332)
		(end 203.049378 -112.24006)
		(width 0.1143)
		(layer "B.Cu")
		(net "UPI_CPU1_CPU0_P0P0_DN<3>")
	)
	(segment
		(start 304.511964 -75.122024)
		(end 304.406554 -75.12558)
		(width 0.0889)
		(layer "B.Cu")
		(net "UPI_CPU1_CPU0_P0P0_DN<3>")
	)
	(segment
		(start 309.18023 -103.734362)
		(end 309.18023 -103.734108)
		(width 0.1143)
		(layer "B.Cu")
		(net "UPI_CPU1_CPU0_P0P0_DN<3>")
	)
	(segment
		(start 302.689006 -74.135234)
		(end 302.65624 -74.135234)
		(width 0.0889)
		(layer "B.Cu")
		(net "UPI_CPU1_CPU0_P0P0_DN<3>")
	)
	(segment
		(start 179.76088 -107.342178)
		(end 181.332886 -107.654852)
		(width 0.1143)
		(layer "B.Cu")
		(net "UPI_CPU1_CPU0_P0P0_DN<3>")
	)
	(segment
		(start 304.502566 -107.162854)
		(end 307.6956 -105.21315)
		(width 0.1143)
		(layer "B.Cu")
		(net "UPI_CPU1_CPU0_P0P0_DN<3>")
	)
	(segment
		(start 146.997674 -59.13882)
		(end 147.627594 -59.13882)
		(width 0.1143)
		(layer "B.Cu")
		(net "UPI_CPU1_CPU0_P0P0_DN<3>")
	)
	(segment
		(start 307.637434 -76.974446)
		(end 307.477922 -76.934314)
		(width 0.0889)
		(layer "B.Cu")
		(net "UPI_CPU1_CPU0_P0P0_DN<3>")
	)
	(segment
		(start 302.825658 -107.62869)
		(end 304.502566 -107.162854)
		(width 0.1143)
		(layer "B.Cu")
		(net "UPI_CPU1_CPU0_P0P0_DN<3>")
	)
	(segment
		(start 176.074832 -104.154732)
		(end 176.407318 -104.46004)
		(width 0.1143)
		(layer "B.Cu")
		(net "UPI_CPU1_CPU0_P0P0_DN<3>")
	)
	(segment
		(start 171.75861 -103.093012)
		(end 176.074832 -104.154732)
		(width 0.1143)
		(layer "B.Cu")
		(net "UPI_CPU1_CPU0_P0P0_DN<3>")
	)
	(segment
		(start 302.31969 -72.553322)
		(end 302.324516 -72.544686)
		(width 0.0889)
		(layer "B.Cu")
		(net "UPI_CPU1_CPU0_P0P0_DN<3>")
	)
	(segment
		(start 304.743358 -75.281028)
		(end 304.511964 -75.122024)
		(width 0.0889)
		(layer "B.Cu")
		(net "UPI_CPU1_CPU0_P0P0_DN<3>")
	)
	(segment
		(start 306.18938 -76.208636)
		(end 306.07 -76.2508)
		(width 0.0889)
		(layer "B.Cu")
		(net "UPI_CPU1_CPU0_P0P0_DN<3>")
	)
	(segment
		(start 281.791918 -109.087412)
		(end 284.668722 -108.499402)
		(width 0.1143)
		(layer "B.Cu")
		(net "UPI_CPU1_CPU0_P0P0_DN<3>")
	)
	(segment
		(start 225.615754 -107.709462)
		(end 235.11002 -108.185966)
		(width 0.1143)
		(layer "B.Cu")
		(net "UPI_CPU1_CPU0_P0P0_DN<3>")
	)
	(segment
		(start 170.85437 -102.594918)
		(end 171.75861 -103.093012)
		(width 0.1143)
		(layer "B.Cu")
		(net "UPI_CPU1_CPU0_P0P0_DN<3>")
	)
	(segment
		(start 307.352954 -76.873608)
		(end 307.311806 -76.754228)
		(width 0.0889)
		(layer "B.Cu")
		(net "UPI_CPU1_CPU0_P0P0_DN<3>")
	)
	(segment
		(start 286.726884 -106.662474)
		(end 292.136576 -105.49128)
		(width 0.1143)
		(layer "B.Cu")
		(net "UPI_CPU1_CPU0_P0P0_DN<3>")
	)
	(segment
		(start 306.551076 -76.48448)
		(end 306.390802 -76.406502)
		(width 0.0889)
		(layer "B.Cu")
		(net "UPI_CPU1_CPU0_P0P0_DN<3>")
	)
	(segment
		(start 307.477922 -76.934314)
		(end 307.352954 -76.873608)
		(width 0.0889)
		(layer "B.Cu")
		(net "UPI_CPU1_CPU0_P0P0_DN<3>")
	)
	(segment
		(start 304.4063 -75.125834)
		(end 304.37328 -75.125834)
		(width 0.0889)
		(layer "B.Cu")
		(net "UPI_CPU1_CPU0_P0P0_DN<3>")
	)
	(segment
		(start 196.228716 -113.203482)
		(end 197.73011 -113.268506)
		(width 0.1143)
		(layer "B.Cu")
		(net "UPI_CPU1_CPU0_P0P0_DN<3>")
	)
	(segment
		(start 305.766724 -76.104496)
		(end 305.575208 -75.852274)
		(width 0.0889)
		(layer "B.Cu")
		(net "UPI_CPU1_CPU0_P0P0_DN<3>")
	)
	(segment
		(start 195.600574 -112.845596)
		(end 196.228716 -113.203482)
		(width 0.1143)
		(layer "B.Cu")
		(net "UPI_CPU1_CPU0_P0P0_DN<3>")
	)
	(segment
		(start 307.96992 -105.04551)
		(end 309.18023 -103.734362)
		(width 0.1143)
		(layer "B.Cu")
		(net "UPI_CPU1_CPU0_P0P0_DN<3>")
	)
	(segment
		(start 306.670456 -76.442316)
		(end 306.551076 -76.48448)
		(width 0.0889)
		(layer "B.Cu")
		(net "UPI_CPU1_CPU0_P0P0_DN<3>")
	)
	(segment
		(start 146.769328 -59.367166)
		(end 146.997674 -59.13882)
		(width 0.1143)
		(layer "B.Cu")
		(net "UPI_CPU1_CPU0_P0P0_DN<3>")
	)
	(segment
		(start 308.026054 -76.949046)
		(end 308.000654 -76.974446)
		(width 0.0889)
		(layer "B.Cu")
		(net "UPI_CPU1_CPU0_P0P0_DN<3>")
	)
	(segment
		(start 304.406554 -75.12558)
		(end 304.4063 -75.125834)
		(width 0.0889)
		(layer "B.Cu")
		(net "UPI_CPU1_CPU0_P0P0_DN<3>")
	)
	(segment
		(start 310.829706 -100.808536)
		(end 311.436512 -95.38843)
		(width 0.1143)
		(layer "B.Cu")
		(net "UPI_CPU1_CPU0_P0P0_DN<3>")
	)
	(segment
		(start 302.324516 -72.544686)
		(end 302.330866 -72.534018)
		(width 0.0889)
		(layer "B.Cu")
		(net "UPI_CPU1_CPU0_P0P0_DN<3>")
	)
	(segment
		(start 179.37353 -107.187238)
		(end 179.76088 -107.342178)
		(width 0.1143)
		(layer "B.Cu")
		(net "UPI_CPU1_CPU0_P0P0_DN<3>")
	)
	(segment
		(start 182.6514 -107.6706)
		(end 186.275218 -107.596178)
		(width 0.1143)
		(layer "B.Cu")
		(net "UPI_CPU1_CPU0_P0P0_DN<3>")
	)
	(segment
		(start 186.275218 -107.596178)
		(end 187.354718 -107.596178)
		(width 0.1143)
		(layer "B.Cu")
		(net "UPI_CPU1_CPU0_P0P0_DN<3>")
	)
	(segment
		(start 302.324516 -73.535286)
		(end 302.330866 -73.524618)
		(width 0.0889)
		(layer "B.Cu")
		(net "UPI_CPU1_CPU0_P0P0_DN<3>")
	)
	(segment
		(start 303.551336 -74.630788)
		(end 303.51857 -74.630788)
		(width 0.0889)
		(layer "B.Cu")
		(net "UPI_CPU1_CPU0_P0P0_DN<3>")
	)
	(segment
		(start 187.354718 -107.596178)
		(end 189.85484 -107.82046)
		(width 0.1143)
		(layer "B.Cu")
		(net "UPI_CPU1_CPU0_P0P0_DN<3>")
	)
	(segment
		(start 306.07 -76.2508)
		(end 305.766724 -76.104496)
		(width 0.0889)
		(layer "B.Cu")
		(net "UPI_CPU1_CPU0_P0P0_DN<3>")
	)
	(segment
		(start 176.407318 -104.460294)
		(end 179.37353 -107.187238)
		(width 0.1143)
		(layer "B.Cu")
		(net "UPI_CPU1_CPU0_P0P0_DN<3>")
	)
	(segment
		(start 302.31969 -73.543922)
		(end 302.324516 -73.535286)
		(width 0.0889)
		(layer "B.Cu")
		(net "UPI_CPU1_CPU0_P0P0_DN<3>")
	)
	(segment
		(start 244.360954 -104.611932)
		(end 251.01423 -104.361996)
		(width 0.1143)
		(layer "B.Cu")
		(net "UPI_CPU1_CPU0_P0P0_DN<3>")
	)
	(segment
		(start 181.332886 -107.654852)
		(end 182.6514 -107.6706)
		(width 0.1143)
		(layer "B.Cu")
		(net "UPI_CPU1_CPU0_P0P0_DN<3>")
	)
	(segment
		(start 308.251606 -76.949046)
		(end 308.048152 -76.949046)
		(width 0.1143)
		(layer "B.Cu")
		(net "UPI_CPU1_CPU0_P0P0_DN<3>")
	)
	(segment
		(start 301.51959 -70.099174)
		(end 301.812706 -70.268084)
		(width 0.0889)
		(layer "B.Cu")
		(net "UPI_CPU1_CPU0_P0P0_DN<3>")
	)
	(segment
		(start 197.73011 -113.268506)
		(end 202.45324 -112.638332)
		(width 0.1143)
		(layer "B.Cu")
		(net "UPI_CPU1_CPU0_P0P0_DN<3>")
	)
	(segment
		(start 312.184034 -86.371684)
		(end 312.169556 -85.810344)
		(width 0.1143)
		(layer "B.Cu")
		(net "UPI_CPU1_CPU0_P0P0_DN<3>")
	)
	(segment
		(start 307.151532 -76.675996)
		(end 307.032152 -76.71816)
		(width 0.0889)
		(layer "B.Cu")
		(net "UPI_CPU1_CPU0_P0P0_DN<3>")
	)
	(segment
		(start 154.766772 -66.278252)
		(end 159.110172 -87.989156)
		(width 0.1143)
		(layer "B.Cu")
		(net "UPI_CPU1_CPU0_P0P0_DN<3>")
	)
	(segment
		(start 284.668722 -108.499402)
		(end 286.726884 -106.662474)
		(width 0.1143)
		(layer "B.Cu")
		(net "UPI_CPU1_CPU0_P0P0_DN<3>")
	)
	(segment
		(start 306.390802 -76.406502)
		(end 306.349654 -76.286868)
		(width 0.0889)
		(layer "B.Cu")
		(net "UPI_CPU1_CPU0_P0P0_DN<3>")
	)
	(segment
		(start 310.7436 -79.8322)
		(end 309.800752 -78.141322)
		(width 0.1143)
		(layer "B.Cu")
		(net "UPI_CPU1_CPU0_P0P0_DN<3>")
	)
	(segment
		(start 165.535864 -95.484188)
		(end 169.139362 -100.9523)
		(width 0.1143)
		(layer "B.Cu")
		(net "UPI_CPU1_CPU0_P0P0_DN<3>")
	)
	(segment
		(start 308.000654 -76.974446)
		(end 307.637434 -76.974446)
		(width 0.0889)
		(layer "B.Cu")
		(net "UPI_CPU1_CPU0_P0P0_DN<3>")
	)
	(segment
		(start 159.149542 -88.186006)
		(end 165.535864 -95.484188)
		(width 0.1143)
		(layer "B.Cu")
		(net "UPI_CPU1_CPU0_P0P0_DN<3>")
	)
	(segment
		(start 235.11002 -108.185966)
		(end 244.360954 -104.611932)
		(width 0.1143)
		(layer "B.Cu")
		(net "UPI_CPU1_CPU0_P0P0_DN<3>")
	)
	(segment
		(start 312.169556 -85.810344)
		(end 310.861964 -80.044544)
		(width 0.1143)
		(layer "B.Cu")
		(net "UPI_CPU1_CPU0_P0P0_DN<3>")
	)
	(segment
		(start 169.139362 -100.9523)
		(end 170.85437 -102.594918)
		(width 0.1143)
		(layer "B.Cu")
		(net "UPI_CPU1_CPU0_P0P0_DN<3>")
	)
	(segment
		(start 192.010284 -108.646722)
		(end 194.674744 -111.870236)
		(width 0.1143)
		(layer "B.Cu")
		(net "UPI_CPU1_CPU0_P0P0_DN<3>")
	)
	(segment
		(start 306.349654 -76.286868)
		(end 306.18938 -76.208636)
		(width 0.0889)
		(layer "B.Cu")
		(net "UPI_CPU1_CPU0_P0P0_DN<3>")
	)
	(segment
		(start 305.041554 -75.485752)
		(end 305.017932 -75.35799)
		(width 0.0889)
		(layer "B.Cu")
		(net "UPI_CPU1_CPU0_P0P0_DN<3>")
	)
	(segment
		(start 304.87112 -75.256898)
		(end 304.743358 -75.281028)
		(width 0.0889)
		(layer "B.Cu")
		(net "UPI_CPU1_CPU0_P0P0_DN<3>")
	)
	(arc
		(start 301.465996 -71.058786)
		(mid 301.545127 -70.763384)
		(end 301.465996 -70.467982)
		(width 0.0889)
		(layer "B.Cu")
		(net "UPI_CPU1_CPU0_P0P0_DN<3>")
	)
	(arc
		(start 302.324516 -72.944736)
		(mid 302.271046 -72.749673)
		(end 302.31969 -72.553322)
		(width 0.0889)
		(layer "B.Cu")
		(net "UPI_CPU1_CPU0_P0P0_DN<3>")
	)
	(arc
		(start 301.80153 -71.658988)
		(mid 301.463361 -71.45419)
		(end 301.465996 -71.058786)
		(width 0.0889)
		(layer "B.Cu")
		(net "UPI_CPU1_CPU0_P0P0_DN<3>")
	)
	(arc
		(start 303.51857 -74.630788)
		(mid 303.32472 -74.574438)
		(end 303.183036 -74.430636)
		(width 0.0889)
		(layer "B.Cu")
		(net "UPI_CPU1_CPU0_P0P0_DN<3>")
	)
	(arc
		(start 302.65624 -74.135234)
		(mid 302.323322 -73.933243)
		(end 302.31969 -73.543922)
		(width 0.0889)
		(layer "B.Cu")
		(net "UPI_CPU1_CPU0_P0P0_DN<3>")
	)
	(arc
		(start 301.465996 -70.467982)
		(mid 301.413662 -70.297133)
		(end 301.44085 -70.12051)
		(width 0.0889)
		(layer "B.Cu")
		(net "UPI_CPU1_CPU0_P0P0_DN<3>")
	)
	(arc
		(start 304.041556 -74.925936)
		(mid 303.834552 -74.715072)
		(end 303.551336 -74.630788)
		(width 0.0889)
		(layer "B.Cu")
		(net "UPI_CPU1_CPU0_P0P0_DN<3>")
	)
	(arc
		(start 302.330866 -72.534018)
		(mid 302.326835 -71.957836)
		(end 301.834296 -71.658988)
		(width 0.0889)
		(layer "B.Cu")
		(net "UPI_CPU1_CPU0_P0P0_DN<3>")
	)
	(arc
		(start 302.330866 -73.524618)
		(mid 302.403664 -73.233855)
		(end 302.324516 -72.944736)
		(width 0.0889)
		(layer "B.Cu")
		(net "UPI_CPU1_CPU0_P0P0_DN<3>")
	)
	(arc
		(start 303.183036 -74.430636)
		(mid 302.974428 -74.218704)
		(end 302.689006 -74.135234)
		(width 0.0889)
		(layer "B.Cu")
		(net "UPI_CPU1_CPU0_P0P0_DN<3>")
	)
	(arc
		(start 304.37328 -75.125834)
		(mid 304.181638 -75.068668)
		(end 304.041556 -74.925936)
		(width 0.0889)
		(layer "B.Cu")
		(net "UPI_CPU1_CPU0_P0P0_DN<3>")
	)
	(segment
		(start 144.469866 -58.393076)
		(end 144.65935 -58.393076)
		(width 0.1143)
		(layer "F.Cu")
		(net "UPI_CPU1_CPU0_P0P0_DN<2>")
	)
	(segment
		(start 140.835126 -60.143898)
		(end 140.880084 -60.066682)
		(width 0.0889)
		(layer "F.Cu")
		(net "UPI_CPU1_CPU0_P0P0_DN<2>")
	)
	(segment
		(start 140.631418 -60.182506)
		(end 140.648944 -60.192666)
		(width 0.0889)
		(layer "F.Cu")
		(net "UPI_CPU1_CPU0_P0P0_DN<2>")
	)
	(segment
		(start 143.441674 -59.23788)
		(end 143.452596 -59.23788)
		(width 0.0889)
		(layer "F.Cu")
		(net "UPI_CPU1_CPU0_P0P0_DN<2>")
	)
	(segment
		(start 141.738604 -59.571382)
		(end 141.738604 -59.571128)
		(width 0.0889)
		(layer "F.Cu")
		(net "UPI_CPU1_CPU0_P0P0_DN<2>")
	)
	(segment
		(start 140.533374 -59.866784)
		(end 140.533374 -60.012072)
		(width 0.0889)
		(layer "F.Cu")
		(net "UPI_CPU1_CPU0_P0P0_DN<2>")
	)
	(segment
		(start 141.37894 -59.771534)
		(end 141.40307 -59.771534)
		(width 0.0889)
		(layer "F.Cu")
		(net "UPI_CPU1_CPU0_P0P0_DN<2>")
	)
	(segment
		(start 144.65935 -58.393076)
		(end 144.882616 -58.16981)
		(width 0.1143)
		(layer "F.Cu")
		(net "UPI_CPU1_CPU0_P0P0_DN<2>")
	)
	(segment
		(start 143.411956 -59.267598)
		(end 143.441674 -59.23788)
		(width 0.0889)
		(layer "F.Cu")
		(net "UPI_CPU1_CPU0_P0P0_DN<2>")
	)
	(segment
		(start 140.909802 -60.020708)
		(end 140.909548 -60.020708)
		(width 0.0889)
		(layer "F.Cu")
		(net "UPI_CPU1_CPU0_P0P0_DN<2>")
	)
	(segment
		(start 300.382686 -70.763384)
		(end 300.954186 -70.763384)
		(width 0.1143)
		(layer "F.Cu")
		(net "UPI_CPU1_CPU0_P0P0_DN<2>")
	)
	(segment
		(start 143.625062 -59.23788)
		(end 144.469866 -58.393076)
		(width 0.1143)
		(layer "F.Cu")
		(net "UPI_CPU1_CPU0_P0P0_DN<2>")
	)
	(segment
		(start 142.042134 -59.267598)
		(end 143.411956 -59.267598)
		(width 0.0889)
		(layer "F.Cu")
		(net "UPI_CPU1_CPU0_P0P0_DN<2>")
	)
	(segment
		(start 143.452596 -59.23788)
		(end 143.625062 -59.23788)
		(width 0.1143)
		(layer "F.Cu")
		(net "UPI_CPU1_CPU0_P0P0_DN<2>")
	)
	(via
		(at 144.882616 -58.16981)
		(size 0.508)
		(drill 0.254)
		(layers "F.Cu" "B.Cu")
		(net "UPI_CPU1_CPU0_P0P0_DN<2>")
	)
	(via
		(at 310.995314 -92.831158)
		(size 0.508)
		(drill 0.254)
		(layers "F.Cu" "B.Cu")
		(net "UPI_CPU1_CPU0_P0P0_DN<2>")
	)
	(via
		(at 300.954186 -70.763384)
		(size 0.508)
		(drill 0.254)
		(layers "F.Cu" "B.Cu")
		(net "UPI_CPU1_CPU0_P0P0_DN<2>")
	)
	(arc
		(start 140.909548 -60.020708)
		(mid 141.114661 -59.840412)
		(end 141.37894 -59.771534)
		(width 0.0889)
		(layer "F.Cu")
		(net "UPI_CPU1_CPU0_P0P0_DN<2>")
	)
	(arc
		(start 140.533374 -60.012072)
		(mid 140.559638 -60.110376)
		(end 140.631418 -60.182506)
		(width 0.0889)
		(layer "F.Cu")
		(net "UPI_CPU1_CPU0_P0P0_DN<2>")
	)
	(arc
		(start 140.880084 -60.066682)
		(mid 140.894411 -60.043351)
		(end 140.909802 -60.020708)
		(width 0.0889)
		(layer "F.Cu")
		(net "UPI_CPU1_CPU0_P0P0_DN<2>")
	)
	(arc
		(start 141.40307 -59.771534)
		(mid 141.59692 -59.715184)
		(end 141.738604 -59.571382)
		(width 0.0889)
		(layer "F.Cu")
		(net "UPI_CPU1_CPU0_P0P0_DN<2>")
	)
	(arc
		(start 141.738604 -59.571128)
		(mid 141.827506 -59.3565)
		(end 142.042134 -59.267598)
		(width 0.0889)
		(layer "F.Cu")
		(net "UPI_CPU1_CPU0_P0P0_DN<2>")
	)
	(arc
		(start 140.648944 -60.192666)
		(mid 140.752082 -60.206742)
		(end 140.835126 -60.143898)
		(width 0.0889)
		(layer "F.Cu")
		(net "UPI_CPU1_CPU0_P0P0_DN<2>")
	)
	(segment
		(start 233.182922 -106.87812)
		(end 234.91571 -106.964988)
		(width 0.1143)
		(layer "B.Cu")
		(net "UPI_CPU1_CPU0_P0P0_DN<2>")
	)
	(segment
		(start 281.6098 -107.847638)
		(end 282.21686 -107.734354)
		(width 0.1143)
		(layer "B.Cu")
		(net "UPI_CPU1_CPU0_P0P0_DN<2>")
	)
	(segment
		(start 289.010344 -105.089706)
		(end 291.125402 -104.66705)
		(width 0.1143)
		(layer "B.Cu")
		(net "UPI_CPU1_CPU0_P0P0_DN<2>")
	)
	(segment
		(start 238.384334 -105.625392)
		(end 238.455708 -105.464356)
		(width 0.1143)
		(layer "B.Cu")
		(net "UPI_CPU1_CPU0_P0P0_DN<2>")
	)
	(segment
		(start 280.86177 -107.7722)
		(end 280.997914 -107.660694)
		(width 0.1143)
		(layer "B.Cu")
		(net "UPI_CPU1_CPU0_P0P0_DN<2>")
	)
	(segment
		(start 238.010192 -105.636568)
		(end 238.171228 -105.707688)
		(width 0.1143)
		(layer "B.Cu")
		(net "UPI_CPU1_CPU0_P0P0_DN<2>")
	)
	(segment
		(start 233.064812 -106.74731)
		(end 233.182922 -106.87812)
		(width 0.1143)
		(layer "B.Cu")
		(net "UPI_CPU1_CPU0_P0P0_DN<2>")
	)
	(segment
		(start 311.016396 -93.638878)
		(end 310.995314 -92.831158)
		(width 0.1143)
		(layer "B.Cu")
		(net "UPI_CPU1_CPU0_P0P0_DN<2>")
	)
	(segment
		(start 310.660034 -86.07679)
		(end 309.697628 -81.915)
		(width 0.1143)
		(layer "B.Cu")
		(net "UPI_CPU1_CPU0_P0P0_DN<2>")
	)
	(segment
		(start 301.827692 -74.821288)
		(end 301.794926 -74.821288)
		(width 0.0889)
		(layer "B.Cu")
		(net "UPI_CPU1_CPU0_P0P0_DN<2>")
	)
	(segment
		(start 167.042592 -95.573596)
		(end 170.078654 -100.177346)
		(width 0.1143)
		(layer "B.Cu")
		(net "UPI_CPU1_CPU0_P0P0_DN<2>")
	)
	(segment
		(start 171.52366 -101.561138)
		(end 172.209206 -101.938836)
		(width 0.1143)
		(layer "B.Cu")
		(net "UPI_CPU1_CPU0_P0P0_DN<2>")
	)
	(segment
		(start 251.732034 -103.314246)
		(end 259.465572 -105.61701)
		(width 0.1143)
		(layer "B.Cu")
		(net "UPI_CPU1_CPU0_P0P0_DN<2>")
	)
	(segment
		(start 191.203326 -107.039664)
		(end 192.4812 -107.5182)
		(width 0.1143)
		(layer "B.Cu")
		(net "UPI_CPU1_CPU0_P0P0_DN<2>")
	)
	(segment
		(start 309.062628 -79.61376)
		(end 307.552598 -78.103222)
		(width 0.1143)
		(layer "B.Cu")
		(net "UPI_CPU1_CPU0_P0P0_DN<2>")
	)
	(segment
		(start 146.2659 -57.81548)
		(end 147.69338 -57.81548)
		(width 0.0889)
		(layer "B.Cu")
		(net "UPI_CPU1_CPU0_P0P0_DN<2>")
	)
	(segment
		(start 238.830104 -105.45318)
		(end 243.586 -103.616506)
		(width 0.1143)
		(layer "B.Cu")
		(net "UPI_CPU1_CPU0_P0P0_DN<2>")
	)
	(segment
		(start 181.417214 -105.123488)
		(end 182.8546 -105.888282)
		(width 0.1143)
		(layer "B.Cu")
		(net "UPI_CPU1_CPU0_P0P0_DN<2>")
	)
	(segment
		(start 201.633582 -111.73206)
		(end 202.576938 -111.101886)
		(width 0.1143)
		(layer "B.Cu")
		(net "UPI_CPU1_CPU0_P0P0_DN<2>")
	)
	(segment
		(start 309.184294 -79.8322)
		(end 309.062628 -79.61376)
		(width 0.1143)
		(layer "B.Cu")
		(net "UPI_CPU1_CPU0_P0P0_DN<2>")
	)
	(segment
		(start 310.840628 -86.858094)
		(end 310.660034 -86.07679)
		(width 0.1143)
		(layer "B.Cu")
		(net "UPI_CPU1_CPU0_P0P0_DN<2>")
	)
	(segment
		(start 279.28316 -107.612942)
		(end 279.283414 -107.612942)
		(width 0.1143)
		(layer "B.Cu")
		(net "UPI_CPU1_CPU0_P0P0_DN<2>")
	)
	(segment
		(start 145.11401 -58.37936)
		(end 145.116296 -58.378598)
		(width 0.0889)
		(layer "B.Cu")
		(net "UPI_CPU1_CPU0_P0P0_DN<2>")
	)
	(segment
		(start 309.48884 -100.961444)
		(end 310.074818 -94.95028)
		(width 0.1143)
		(layer "B.Cu")
		(net "UPI_CPU1_CPU0_P0P0_DN<2>")
	)
	(segment
		(start 282.541472 -107.546902)
		(end 282.686506 -107.64647)
		(width 0.1143)
		(layer "B.Cu")
		(net "UPI_CPU1_CPU0_P0P0_DN<2>")
	)
	(segment
		(start 310.074818 -94.95028)
		(end 310.917336 -93.7768)
		(width 0.1143)
		(layer "B.Cu")
		(net "UPI_CPU1_CPU0_P0P0_DN<2>")
	)
	(segment
		(start 182.8546 -105.888282)
		(end 184.733692 -106.160316)
		(width 0.1143)
		(layer "B.Cu")
		(net "UPI_CPU1_CPU0_P0P0_DN<2>")
	)
	(segment
		(start 259.465572 -105.61701)
		(end 277.632922 -107.446826)
		(width 0.1143)
		(layer "B.Cu")
		(net "UPI_CPU1_CPU0_P0P0_DN<2>")
	)
	(segment
		(start 186.553856 -106.2736)
		(end 186.92749 -106.2736)
		(width 0.1143)
		(layer "B.Cu")
		(net "UPI_CPU1_CPU0_P0P0_DN<2>")
	)
	(segment
		(start 300.965362 -72.344534)
		(end 300.932596 -72.344534)
		(width 0.0889)
		(layer "B.Cu")
		(net "UPI_CPU1_CPU0_P0P0_DN<2>")
	)
	(segment
		(start 310.917336 -93.7768)
		(end 311.016396 -93.638878)
		(width 0.1143)
		(layer "B.Cu")
		(net "UPI_CPU1_CPU0_P0P0_DN<2>")
	)
	(segment
		(start 186.92749 -106.2736)
		(end 191.203326 -107.039664)
		(width 0.1143)
		(layer "B.Cu")
		(net "UPI_CPU1_CPU0_P0P0_DN<2>")
	)
	(segment
		(start 202.576938 -111.101886)
		(end 225.525076 -106.494326)
		(width 0.1143)
		(layer "B.Cu")
		(net "UPI_CPU1_CPU0_P0P0_DN<2>")
	)
	(segment
		(start 282.818078 -107.621832)
		(end 284.038294 -107.394248)
		(width 0.1143)
		(layer "B.Cu")
		(net "UPI_CPU1_CPU0_P0P0_DN<2>")
	)
	(segment
		(start 310.854598 -87.398098)
		(end 310.840628 -86.858094)
		(width 0.1143)
		(layer "B.Cu")
		(net "UPI_CPU1_CPU0_P0P0_DN<2>")
	)
	(segment
		(start 305.444398 -77.18044)
		(end 303.799494 -75.811888)
		(width 0.0889)
		(layer "B.Cu")
		(net "UPI_CPU1_CPU0_P0P0_DN<2>")
	)
	(segment
		(start 309.238142 -79.92872)
		(end 309.184294 -79.8322)
		(width 0.1143)
		(layer "B.Cu")
		(net "UPI_CPU1_CPU0_P0P0_DN<2>")
	)
	(segment
		(start 155.698444 -65.784222)
		(end 160.062164 -87.59571)
		(width 0.1143)
		(layer "B.Cu")
		(net "UPI_CPU1_CPU0_P0P0_DN<2>")
	)
	(segment
		(start 144.882616 -58.16981)
		(end 145.11401 -58.37936)
		(width 0.0889)
		(layer "B.Cu")
		(net "UPI_CPU1_CPU0_P0P0_DN<2>")
	)
	(segment
		(start 302.549814 -106.545126)
		(end 304.21326 -106.131868)
		(width 0.1143)
		(layer "B.Cu")
		(net "UPI_CPU1_CPU0_P0P0_DN<2>")
	)
	(segment
		(start 307.21681 -77.731366)
		(end 306.262278 -77.238352)
		(width 0.0889)
		(layer "B.Cu")
		(net "UPI_CPU1_CPU0_P0P0_DN<2>")
	)
	(segment
		(start 180.762148 -104.876854)
		(end 181.388258 -105.110026)
		(width 0.1143)
		(layer "B.Cu")
		(net "UPI_CPU1_CPU0_P0P0_DN<2>")
	)
	(segment
		(start 238.669068 -105.381806)
		(end 238.830104 -105.45318)
		(width 0.1143)
		(layer "B.Cu")
		(net "UPI_CPU1_CPU0_P0P0_DN<2>")
	)
	(segment
		(start 282.21686 -107.734354)
		(end 282.316428 -107.589066)
		(width 0.1143)
		(layer "B.Cu")
		(net "UPI_CPU1_CPU0_P0P0_DN<2>")
	)
	(segment
		(start 306.262278 -77.238352)
		(end 305.444398 -77.18044)
		(width 0.0889)
		(layer "B.Cu")
		(net "UPI_CPU1_CPU0_P0P0_DN<2>")
	)
	(segment
		(start 310.954166 -91.244166)
		(end 310.854598 -87.398098)
		(width 0.1143)
		(layer "B.Cu")
		(net "UPI_CPU1_CPU0_P0P0_DN<2>")
	)
	(segment
		(start 238.171228 -105.707688)
		(end 238.384334 -105.625392)
		(width 0.1143)
		(layer "B.Cu")
		(net "UPI_CPU1_CPU0_P0P0_DN<2>")
	)
	(segment
		(start 234.91571 -106.964988)
		(end 237.725458 -105.8799)
		(width 0.1143)
		(layer "B.Cu")
		(net "UPI_CPU1_CPU0_P0P0_DN<2>")
	)
	(segment
		(start 301.300896 -73.535286)
		(end 301.294546 -73.524618)
		(width 0.0889)
		(layer "B.Cu")
		(net "UPI_CPU1_CPU0_P0P0_DN<2>")
	)
	(segment
		(start 196.619368 -112.214152)
		(end 197.686168 -112.26038)
		(width 0.1143)
		(layer "B.Cu")
		(net "UPI_CPU1_CPU0_P0P0_DN<2>")
	)
	(segment
		(start 230.220012 -106.72953)
		(end 232.705656 -106.85399)
		(width 0.1143)
		(layer "B.Cu")
		(net "UPI_CPU1_CPU0_P0P0_DN<2>")
	)
	(segment
		(start 232.836212 -106.73588)
		(end 233.064812 -106.74731)
		(width 0.1143)
		(layer "B.Cu")
		(net "UPI_CPU1_CPU0_P0P0_DN<2>")
	)
	(segment
		(start 279.283414 -107.612942)
		(end 279.456134 -107.630468)
		(width 0.1143)
		(layer "B.Cu")
		(net "UPI_CPU1_CPU0_P0P0_DN<2>")
	)
	(segment
		(start 195.472304 -111.248444)
		(end 195.719192 -111.50854)
		(width 0.1143)
		(layer "B.Cu")
		(net "UPI_CPU1_CPU0_P0P0_DN<2>")
	)
	(segment
		(start 181.388258 -105.110026)
		(end 181.417214 -105.123488)
		(width 0.1143)
		(layer "B.Cu")
		(net "UPI_CPU1_CPU0_P0P0_DN<2>")
	)
	(segment
		(start 279.931622 -107.678474)
		(end 280.158952 -107.701334)
		(width 0.1143)
		(layer "B.Cu")
		(net "UPI_CPU1_CPU0_P0P0_DN<2>")
	)
	(segment
		(start 232.705656 -106.85399)
		(end 232.836212 -106.73588)
		(width 0.1143)
		(layer "B.Cu")
		(net "UPI_CPU1_CPU0_P0P0_DN<2>")
	)
	(segment
		(start 280.29535 -107.589828)
		(end 280.523188 -107.612942)
		(width 0.1143)
		(layer "B.Cu")
		(net "UPI_CPU1_CPU0_P0P0_DN<2>")
	)
	(segment
		(start 280.63444 -107.74934)
		(end 280.86177 -107.7722)
		(width 0.1143)
		(layer "B.Cu")
		(net "UPI_CPU1_CPU0_P0P0_DN<2>")
	)
	(segment
		(start 160.062164 -87.59571)
		(end 167.042592 -95.573596)
		(width 0.1143)
		(layer "B.Cu")
		(net "UPI_CPU1_CPU0_P0P0_DN<2>")
	)
	(segment
		(start 225.525076 -106.494326)
		(end 230.220012 -106.729276)
		(width 0.1143)
		(layer "B.Cu")
		(net "UPI_CPU1_CPU0_P0P0_DN<2>")
	)
	(segment
		(start 237.796832 -105.718864)
		(end 238.010192 -105.636568)
		(width 0.1143)
		(layer "B.Cu")
		(net "UPI_CPU1_CPU0_P0P0_DN<2>")
	)
	(segment
		(start 279.456134 -107.630468)
		(end 279.592532 -107.518962)
		(width 0.1143)
		(layer "B.Cu")
		(net "UPI_CPU1_CPU0_P0P0_DN<2>")
	)
	(segment
		(start 192.4812 -107.5182)
		(end 195.472304 -111.248444)
		(width 0.1143)
		(layer "B.Cu")
		(net "UPI_CPU1_CPU0_P0P0_DN<2>")
	)
	(segment
		(start 148.406612 -58.49239)
		(end 155.698444 -65.784222)
		(width 0.1143)
		(layer "B.Cu")
		(net "UPI_CPU1_CPU0_P0P0_DN<2>")
	)
	(segment
		(start 145.116296 -58.378598)
		(end 145.702782 -58.378598)
		(width 0.0889)
		(layer "B.Cu")
		(net "UPI_CPU1_CPU0_P0P0_DN<2>")
	)
	(segment
		(start 302.682402 -75.316334)
		(end 302.649636 -75.316334)
		(width 0.0889)
		(layer "B.Cu")
		(net "UPI_CPU1_CPU0_P0P0_DN<2>")
	)
	(segment
		(start 307.552598 -78.067154)
		(end 307.21681 -77.731366)
		(width 0.0889)
		(layer "B.Cu")
		(net "UPI_CPU1_CPU0_P0P0_DN<2>")
	)
	(segment
		(start 300.436026 -71.469504)
		(end 300.537626 -71.298816)
		(width 0.0889)
		(layer "B.Cu")
		(net "UPI_CPU1_CPU0_P0P0_DN<2>")
	)
	(segment
		(start 279.82037 -107.542076)
		(end 279.931622 -107.678474)
		(width 0.1143)
		(layer "B.Cu")
		(net "UPI_CPU1_CPU0_P0P0_DN<2>")
	)
	(segment
		(start 184.733692 -106.160316)
		(end 186.553856 -106.2736)
		(width 0.1143)
		(layer "B.Cu")
		(net "UPI_CPU1_CPU0_P0P0_DN<2>")
	)
	(segment
		(start 292.144196 -104.463342)
		(end 302.549814 -106.545126)
		(width 0.1143)
		(layer "B.Cu")
		(net "UPI_CPU1_CPU0_P0P0_DN<2>")
	)
	(segment
		(start 195.719192 -111.50854)
		(end 195.72097 -111.510318)
		(width 0.1143)
		(layer "B.Cu")
		(net "UPI_CPU1_CPU0_P0P0_DN<2>")
	)
	(segment
		(start 284.038294 -107.394248)
		(end 285.88462 -105.787698)
		(width 0.1143)
		(layer "B.Cu")
		(net "UPI_CPU1_CPU0_P0P0_DN<2>")
	)
	(segment
		(start 279.592532 -107.518962)
		(end 279.68321 -107.528106)
		(width 0.1143)
		(layer "B.Cu")
		(net "UPI_CPU1_CPU0_P0P0_DN<2>")
	)
	(segment
		(start 301.305722 -73.543922)
		(end 301.300896 -73.535286)
		(width 0.0889)
		(layer "B.Cu")
		(net "UPI_CPU1_CPU0_P0P0_DN<2>")
	)
	(segment
		(start 237.725458 -105.8799)
		(end 237.796832 -105.718864)
		(width 0.1143)
		(layer "B.Cu")
		(net "UPI_CPU1_CPU0_P0P0_DN<2>")
	)
	(segment
		(start 277.633176 -107.446826)
		(end 279.28316 -107.612942)
		(width 0.1143)
		(layer "B.Cu")
		(net "UPI_CPU1_CPU0_P0P0_DN<2>")
	)
	(segment
		(start 291.125402 -104.66705)
		(end 292.144196 -104.463342)
		(width 0.1143)
		(layer "B.Cu")
		(net "UPI_CPU1_CPU0_P0P0_DN<2>")
	)
	(segment
		(start 170.078654 -100.177346)
		(end 171.52366 -101.561138)
		(width 0.1143)
		(layer "B.Cu")
		(net "UPI_CPU1_CPU0_P0P0_DN<2>")
	)
	(segment
		(start 281.337004 -107.820206)
		(end 281.6098 -107.847638)
		(width 0.1143)
		(layer "B.Cu")
		(net "UPI_CPU1_CPU0_P0P0_DN<2>")
	)
	(segment
		(start 172.209206 -101.938836)
		(end 178.411886 -103.463852)
		(width 0.1143)
		(layer "B.Cu")
		(net "UPI_CPU1_CPU0_P0P0_DN<2>")
	)
	(segment
		(start 148.37029 -58.49239)
		(end 148.406612 -58.49239)
		(width 0.0889)
		(layer "B.Cu")
		(net "UPI_CPU1_CPU0_P0P0_DN<2>")
	)
	(segment
		(start 280.523188 -107.612942)
		(end 280.63444 -107.74934)
		(width 0.1143)
		(layer "B.Cu")
		(net "UPI_CPU1_CPU0_P0P0_DN<2>")
	)
	(segment
		(start 309.697628 -81.915)
		(end 309.238142 -79.92872)
		(width 0.1143)
		(layer "B.Cu")
		(net "UPI_CPU1_CPU0_P0P0_DN<2>")
	)
	(segment
		(start 196.205094 -112.02035)
		(end 196.619368 -112.214152)
		(width 0.1143)
		(layer "B.Cu")
		(net "UPI_CPU1_CPU0_P0P0_DN<2>")
	)
	(segment
		(start 243.586 -103.616506)
		(end 251.732034 -103.314246)
		(width 0.1143)
		(layer "B.Cu")
		(net "UPI_CPU1_CPU0_P0P0_DN<2>")
	)
	(segment
		(start 303.799494 -75.811888)
		(end 303.511966 -75.811888)
		(width 0.0889)
		(layer "B.Cu")
		(net "UPI_CPU1_CPU0_P0P0_DN<2>")
	)
	(segment
		(start 285.88462 -105.787698)
		(end 289.010344 -105.089706)
		(width 0.1143)
		(layer "B.Cu")
		(net "UPI_CPU1_CPU0_P0P0_DN<2>")
	)
	(segment
		(start 280.997914 -107.660694)
		(end 281.225752 -107.683808)
		(width 0.1143)
		(layer "B.Cu")
		(net "UPI_CPU1_CPU0_P0P0_DN<2>")
	)
	(segment
		(start 279.68321 -107.528106)
		(end 279.683464 -107.528106)
		(width 0.1143)
		(layer "B.Cu")
		(net "UPI_CPU1_CPU0_P0P0_DN<2>")
	)
	(segment
		(start 307.552598 -78.103222)
		(end 307.552598 -78.067154)
		(width 0.0889)
		(layer "B.Cu")
		(net "UPI_CPU1_CPU0_P0P0_DN<2>")
	)
	(segment
		(start 282.316428 -107.589066)
		(end 282.541472 -107.546902)
		(width 0.1143)
		(layer "B.Cu")
		(net "UPI_CPU1_CPU0_P0P0_DN<2>")
	)
	(segment
		(start 277.632922 -107.446826)
		(end 277.633176 -107.446826)
		(width 0.1143)
		(layer "B.Cu")
		(net "UPI_CPU1_CPU0_P0P0_DN<2>")
	)
	(segment
		(start 230.220012 -106.729276)
		(end 230.220012 -106.72953)
		(width 0.1143)
		(layer "B.Cu")
		(net "UPI_CPU1_CPU0_P0P0_DN<2>")
	)
	(segment
		(start 309.193946 -101.870764)
		(end 309.48884 -100.961444)
		(width 0.1143)
		(layer "B.Cu")
		(net "UPI_CPU1_CPU0_P0P0_DN<2>")
	)
	(segment
		(start 147.69338 -57.81548)
		(end 148.37029 -58.49239)
		(width 0.0889)
		(layer "B.Cu")
		(net "UPI_CPU1_CPU0_P0P0_DN<2>")
	)
	(segment
		(start 310.995314 -92.831158)
		(end 310.954166 -91.244166)
		(width 0.1143)
		(layer "B.Cu")
		(net "UPI_CPU1_CPU0_P0P0_DN<2>")
	)
	(segment
		(start 282.686506 -107.64647)
		(end 282.818078 -107.621832)
		(width 0.1143)
		(layer "B.Cu")
		(net "UPI_CPU1_CPU0_P0P0_DN<2>")
	)
	(segment
		(start 279.683464 -107.528106)
		(end 279.82037 -107.542076)
		(width 0.1143)
		(layer "B.Cu")
		(net "UPI_CPU1_CPU0_P0P0_DN<2>")
	)
	(segment
		(start 306.681124 -104.65308)
		(end 309.193946 -101.870764)
		(width 0.1143)
		(layer "B.Cu")
		(net "UPI_CPU1_CPU0_P0P0_DN<2>")
	)
	(segment
		(start 304.21326 -106.131868)
		(end 306.681124 -104.65308)
		(width 0.1143)
		(layer "B.Cu")
		(net "UPI_CPU1_CPU0_P0P0_DN<2>")
	)
	(segment
		(start 145.702782 -58.378598)
		(end 146.2659 -57.81548)
		(width 0.0889)
		(layer "B.Cu")
		(net "UPI_CPU1_CPU0_P0P0_DN<2>")
	)
	(segment
		(start 238.455708 -105.464356)
		(end 238.669068 -105.381806)
		(width 0.1143)
		(layer "B.Cu")
		(net "UPI_CPU1_CPU0_P0P0_DN<2>")
	)
	(segment
		(start 197.686168 -112.26038)
		(end 201.633582 -111.73206)
		(width 0.1143)
		(layer "B.Cu")
		(net "UPI_CPU1_CPU0_P0P0_DN<2>")
	)
	(segment
		(start 281.225752 -107.683808)
		(end 281.337004 -107.820206)
		(width 0.1143)
		(layer "B.Cu")
		(net "UPI_CPU1_CPU0_P0P0_DN<2>")
	)
	(segment
		(start 195.72097 -111.510318)
		(end 196.205094 -112.02035)
		(width 0.1143)
		(layer "B.Cu")
		(net "UPI_CPU1_CPU0_P0P0_DN<2>")
	)
	(segment
		(start 280.158952 -107.701334)
		(end 280.29535 -107.589828)
		(width 0.1143)
		(layer "B.Cu")
		(net "UPI_CPU1_CPU0_P0P0_DN<2>")
	)
	(segment
		(start 178.411886 -103.463852)
		(end 180.762148 -104.876854)
		(width 0.1143)
		(layer "B.Cu")
		(net "UPI_CPU1_CPU0_P0P0_DN<2>")
	)
	(arc
		(start 303.511966 -75.811888)
		(mid 303.226542 -75.728421)
		(end 303.017936 -75.516486)
		(width 0.0889)
		(layer "B.Cu")
		(net "UPI_CPU1_CPU0_P0P0_DN<2>")
	)
	(arc
		(start 300.932596 -72.344534)
		(mid 300.440206 -72.045601)
		(end 300.436026 -71.469504)
		(width 0.0889)
		(layer "B.Cu")
		(net "UPI_CPU1_CPU0_P0P0_DN<2>")
	)
	(arc
		(start 300.537626 -71.298816)
		(mid 300.729256 -71.018147)
		(end 300.954186 -70.763384)
		(width 0.0889)
		(layer "B.Cu")
		(net "UPI_CPU1_CPU0_P0P0_DN<2>")
	)
	(arc
		(start 302.649636 -75.316334)
		(mid 302.366419 -75.232053)
		(end 302.159416 -75.021186)
		(width 0.0889)
		(layer "B.Cu")
		(net "UPI_CPU1_CPU0_P0P0_DN<2>")
	)
	(arc
		(start 301.794926 -74.821288)
		(mid 301.296675 -74.518448)
		(end 301.300896 -73.935336)
		(width 0.0889)
		(layer "B.Cu")
		(net "UPI_CPU1_CPU0_P0P0_DN<2>")
	)
	(arc
		(start 303.017936 -75.516486)
		(mid 302.876253 -75.372682)
		(end 302.682402 -75.316334)
		(width 0.0889)
		(layer "B.Cu")
		(net "UPI_CPU1_CPU0_P0P0_DN<2>")
	)
	(arc
		(start 301.294546 -73.524618)
		(mid 301.221748 -73.233855)
		(end 301.300896 -72.944736)
		(width 0.0889)
		(layer "B.Cu")
		(net "UPI_CPU1_CPU0_P0P0_DN<2>")
	)
	(arc
		(start 301.300896 -72.944736)
		(mid 301.303644 -72.549269)
		(end 300.965362 -72.344534)
		(width 0.0889)
		(layer "B.Cu")
		(net "UPI_CPU1_CPU0_P0P0_DN<2>")
	)
	(arc
		(start 302.159416 -75.021186)
		(mid 302.019337 -74.87845)
		(end 301.827692 -74.821288)
		(width 0.0889)
		(layer "B.Cu")
		(net "UPI_CPU1_CPU0_P0P0_DN<2>")
	)
	(arc
		(start 301.300896 -73.935336)
		(mid 301.354366 -73.740273)
		(end 301.305722 -73.543922)
		(width 0.0889)
		(layer "B.Cu")
		(net "UPI_CPU1_CPU0_P0P0_DN<2>")
	)
	(segment
		(start 300.382686 -72.744584)
		(end 300.954186 -72.744584)
		(width 0.1143)
		(layer "F.Cu")
		(net "UPI_CPU1_CPU0_P0P0_DN<1>")
	)
	(segment
		(start 142.894812 -58.876438)
		(end 142.91056 -58.86069)
		(width 0.1143)
		(layer "F.Cu")
		(net "UPI_CPU1_CPU0_P0P0_DN<1>")
	)
	(segment
		(start 142.250414 -58.876438)
		(end 142.894812 -58.876438)
		(width 0.1143)
		(layer "F.Cu")
		(net "UPI_CPU1_CPU0_P0P0_DN<1>")
	)
	(via
		(at 142.91056 -58.86069)
		(size 0.508)
		(drill 0.254)
		(layers "F.Cu" "B.Cu")
		(net "UPI_CPU1_CPU0_P0P0_DN<1>")
	)
	(via
		(at 300.954186 -72.744584)
		(size 0.508)
		(drill 0.254)
		(layers "F.Cu" "B.Cu")
		(net "UPI_CPU1_CPU0_P0P0_DN<1>")
	)
	(segment
		(start 306.46878 -78.08087)
		(end 306.004976 -78.107794)
		(width 0.0889)
		(layer "B.Cu")
		(net "UPI_CPU1_CPU0_P0P0_DN<1>")
	)
	(segment
		(start 280.099262 -106.493564)
		(end 280.100786 -106.49331)
		(width 0.1143)
		(layer "B.Cu")
		(net "UPI_CPU1_CPU0_P0P0_DN<1>")
	)
	(segment
		(start 309.93461 -87.01278)
		(end 307.976524 -79.722218)
		(width 0.1143)
		(layer "B.Cu")
		(net "UPI_CPU1_CPU0_P0P0_DN<1>")
	)
	(segment
		(start 184.984136 -105.578402)
		(end 186.426094 -105.62971)
		(width 0.1143)
		(layer "B.Cu")
		(net "UPI_CPU1_CPU0_P0P0_DN<1>")
	)
	(segment
		(start 284.121352 -105.87609)
		(end 284.751018 -105.763822)
		(width 0.1143)
		(layer "B.Cu")
		(net "UPI_CPU1_CPU0_P0P0_DN<1>")
	)
	(segment
		(start 143.036798 -58.41619)
		(end 143.983964 -58.41619)
		(width 0.0889)
		(layer "B.Cu")
		(net "UPI_CPU1_CPU0_P0P0_DN<1>")
	)
	(segment
		(start 179.40655 -102.958646)
		(end 181.080664 -103.964994)
		(width 0.1143)
		(layer "B.Cu")
		(net "UPI_CPU1_CPU0_P0P0_DN<1>")
	)
	(segment
		(start 302.420528 -105.980992)
		(end 304.224436 -105.500424)
		(width 0.1143)
		(layer "B.Cu")
		(net "UPI_CPU1_CPU0_P0P0_DN<1>")
	)
	(segment
		(start 170.645328 -99.692968)
		(end 172.005498 -100.99548)
		(width 0.1143)
		(layer "B.Cu")
		(net "UPI_CPU1_CPU0_P0P0_DN<1>")
	)
	(segment
		(start 308.670706 -100.819204)
		(end 309.3466 -94.458028)
		(width 0.1143)
		(layer "B.Cu")
		(net "UPI_CPU1_CPU0_P0P0_DN<1>")
	)
	(segment
		(start 148.148294 -57.36844)
		(end 148.51888 -57.739026)
		(width 0.0889)
		(layer "B.Cu")
		(net "UPI_CPU1_CPU0_P0P0_DN<1>")
	)
	(segment
		(start 303.551336 -76.611988)
		(end 303.51857 -76.611988)
		(width 0.0889)
		(layer "B.Cu")
		(net "UPI_CPU1_CPU0_P0P0_DN<1>")
	)
	(segment
		(start 280.619708 -106.834686)
		(end 281.178508 -106.71937)
		(width 0.1143)
		(layer "B.Cu")
		(net "UPI_CPU1_CPU0_P0P0_DN<1>")
	)
	(segment
		(start 142.909798 -58.54319)
		(end 143.036798 -58.41619)
		(width 0.0889)
		(layer "B.Cu")
		(net "UPI_CPU1_CPU0_P0P0_DN<1>")
	)
	(segment
		(start 142.91056 -58.86069)
		(end 142.909798 -58.54319)
		(width 0.0889)
		(layer "B.Cu")
		(net "UPI_CPU1_CPU0_P0P0_DN<1>")
	)
	(segment
		(start 241.096546 -104.000554)
		(end 243.3828 -103.116634)
		(width 0.1143)
		(layer "B.Cu")
		(net "UPI_CPU1_CPU0_P0P0_DN<1>")
	)
	(segment
		(start 307.556662 -79.132938)
		(end 307.072792 -78.649068)
		(width 0.1143)
		(layer "B.Cu")
		(net "UPI_CPU1_CPU0_P0P0_DN<1>")
	)
	(segment
		(start 282.380436 -106.313478)
		(end 282.432252 -106.596942)
		(width 0.1143)
		(layer "B.Cu")
		(net "UPI_CPU1_CPU0_P0P0_DN<1>")
	)
	(segment
		(start 168.23563 -96.036638)
		(end 170.645328 -99.692968)
		(width 0.1143)
		(layer "B.Cu")
		(net "UPI_CPU1_CPU0_P0P0_DN<1>")
	)
	(segment
		(start 257.539236 -104.283764)
		(end 259.884164 -104.746552)
		(width 0.1143)
		(layer "B.Cu")
		(net "UPI_CPU1_CPU0_P0P0_DN<1>")
	)
	(segment
		(start 283.859986 -105.922826)
		(end 284.121098 -105.87609)
		(width 0.1143)
		(layer "B.Cu")
		(net "UPI_CPU1_CPU0_P0P0_DN<1>")
	)
	(segment
		(start 300.60265 -73.543922)
		(end 300.607476 -73.535286)
		(width 0.0889)
		(layer "B.Cu")
		(net "UPI_CPU1_CPU0_P0P0_DN<1>")
	)
	(segment
		(start 285.282894 -105.279698)
		(end 291.125402 -104.111552)
		(width 0.1143)
		(layer "B.Cu")
		(net "UPI_CPU1_CPU0_P0P0_DN<1>")
	)
	(segment
		(start 268.2494 -105.589578)
		(end 279.062688 -106.679492)
		(width 0.1143)
		(layer "B.Cu")
		(net "UPI_CPU1_CPU0_P0P0_DN<1>")
	)
	(segment
		(start 309.3466 -94.458028)
		(end 310.100472 -93.407992)
		(width 0.1143)
		(layer "B.Cu")
		(net "UPI_CPU1_CPU0_P0P0_DN<1>")
	)
	(segment
		(start 182.89016 -104.880664)
		(end 184.984136 -105.578402)
		(width 0.1143)
		(layer "B.Cu")
		(net "UPI_CPU1_CPU0_P0P0_DN<1>")
	)
	(segment
		(start 192.67805 -106.85526)
		(end 196.018912 -111.040926)
		(width 0.1143)
		(layer "B.Cu")
		(net "UPI_CPU1_CPU0_P0P0_DN<1>")
	)
	(segment
		(start 196.967348 -111.706406)
		(end 197.645528 -111.73587)
		(width 0.1143)
		(layer "B.Cu")
		(net "UPI_CPU1_CPU0_P0P0_DN<1>")
	)
	(segment
		(start 279.062688 -106.679492)
		(end 280.058622 -106.501946)
		(width 0.1143)
		(layer "B.Cu")
		(net "UPI_CPU1_CPU0_P0P0_DN<1>")
	)
	(segment
		(start 191.304926 -106.498644)
		(end 191.834516 -106.590846)
		(width 0.1143)
		(layer "B.Cu")
		(net "UPI_CPU1_CPU0_P0P0_DN<1>")
	)
	(segment
		(start 300.607476 -73.535286)
		(end 300.613826 -73.524618)
		(width 0.0889)
		(layer "B.Cu")
		(net "UPI_CPU1_CPU0_P0P0_DN<1>")
	)
	(segment
		(start 280.100786 -106.49331)
		(end 280.100786 -106.493056)
		(width 0.1143)
		(layer "B.Cu")
		(net "UPI_CPU1_CPU0_P0P0_DN<1>")
	)
	(segment
		(start 281.444446 -106.315002)
		(end 281.59329 -106.284014)
		(width 0.1143)
		(layer "B.Cu")
		(net "UPI_CPU1_CPU0_P0P0_DN<1>")
	)
	(segment
		(start 182.174134 -104.412796)
		(end 182.89016 -104.880664)
		(width 0.1143)
		(layer "B.Cu")
		(net "UPI_CPU1_CPU0_P0P0_DN<1>")
	)
	(segment
		(start 148.51888 -57.774586)
		(end 156.177488 -65.433448)
		(width 0.1143)
		(layer "B.Cu")
		(net "UPI_CPU1_CPU0_P0P0_DN<1>")
	)
	(segment
		(start 281.59329 -106.284014)
		(end 282.196286 -106.176318)
		(width 0.1143)
		(layer "B.Cu")
		(net "UPI_CPU1_CPU0_P0P0_DN<1>")
	)
	(segment
		(start 284.751018 -105.763822)
		(end 285.282894 -105.279698)
		(width 0.1143)
		(layer "B.Cu")
		(net "UPI_CPU1_CPU0_P0P0_DN<1>")
	)
	(segment
		(start 145.031714 -57.36844)
		(end 148.148294 -57.36844)
		(width 0.0889)
		(layer "B.Cu")
		(net "UPI_CPU1_CPU0_P0P0_DN<1>")
	)
	(segment
		(start 305.575208 -77.922628)
		(end 304.561494 -77.09916)
		(width 0.0889)
		(layer "B.Cu")
		(net "UPI_CPU1_CPU0_P0P0_DN<1>")
	)
	(segment
		(start 280.058622 -106.501946)
		(end 280.094182 -106.49458)
		(width 0.1143)
		(layer "B.Cu")
		(net "UPI_CPU1_CPU0_P0P0_DN<1>")
	)
	(segment
		(start 291.125402 -104.111552)
		(end 292.102286 -103.916226)
		(width 0.1143)
		(layer "B.Cu")
		(net "UPI_CPU1_CPU0_P0P0_DN<1>")
	)
	(segment
		(start 280.100786 -106.493056)
		(end 280.619708 -106.834686)
		(width 0.1143)
		(layer "B.Cu")
		(net "UPI_CPU1_CPU0_P0P0_DN<1>")
	)
	(segment
		(start 307.036978 -78.649068)
		(end 306.46878 -78.08087)
		(width 0.0889)
		(layer "B.Cu")
		(net "UPI_CPU1_CPU0_P0P0_DN<1>")
	)
	(segment
		(start 191.834516 -106.590846)
		(end 192.67805 -106.85526)
		(width 0.1143)
		(layer "B.Cu")
		(net "UPI_CPU1_CPU0_P0P0_DN<1>")
	)
	(segment
		(start 292.102286 -103.916226)
		(end 302.420528 -105.980992)
		(width 0.1143)
		(layer "B.Cu")
		(net "UPI_CPU1_CPU0_P0P0_DN<1>")
	)
	(segment
		(start 172.474636 -101.25329)
		(end 179.40655 -102.958646)
		(width 0.1143)
		(layer "B.Cu")
		(net "UPI_CPU1_CPU0_P0P0_DN<1>")
	)
	(segment
		(start 307.072792 -78.649068)
		(end 307.036978 -78.649068)
		(width 0.0889)
		(layer "B.Cu")
		(net "UPI_CPU1_CPU0_P0P0_DN<1>")
	)
	(segment
		(start 283.583888 -106.689144)
		(end 283.820616 -106.345736)
		(width 0.1143)
		(layer "B.Cu")
		(net "UPI_CPU1_CPU0_P0P0_DN<1>")
	)
	(segment
		(start 282.196286 -106.176318)
		(end 282.378912 -106.303572)
		(width 0.1143)
		(layer "B.Cu")
		(net "UPI_CPU1_CPU0_P0P0_DN<1>")
	)
	(segment
		(start 230.874824 -106.035348)
		(end 241.096546 -104.000554)
		(width 0.1143)
		(layer "B.Cu")
		(net "UPI_CPU1_CPU0_P0P0_DN<1>")
	)
	(segment
		(start 310.100472 -93.407992)
		(end 309.93461 -87.01278)
		(width 0.1143)
		(layer "B.Cu")
		(net "UPI_CPU1_CPU0_P0P0_DN<1>")
	)
	(segment
		(start 300.971966 -75.125834)
		(end 300.9392 -75.125834)
		(width 0.0889)
		(layer "B.Cu")
		(net "UPI_CPU1_CPU0_P0P0_DN<1>")
	)
	(segment
		(start 172.005498 -100.99548)
		(end 172.474636 -101.25329)
		(width 0.1143)
		(layer "B.Cu")
		(net "UPI_CPU1_CPU0_P0P0_DN<1>")
	)
	(segment
		(start 282.774898 -106.833924)
		(end 283.583888 -106.689144)
		(width 0.1143)
		(layer "B.Cu")
		(net "UPI_CPU1_CPU0_P0P0_DN<1>")
	)
	(segment
		(start 284.121098 -105.87609)
		(end 284.121352 -105.87609)
		(width 0.1143)
		(layer "B.Cu")
		(net "UPI_CPU1_CPU0_P0P0_DN<1>")
	)
	(segment
		(start 304.224436 -105.500424)
		(end 305.837082 -104.507284)
		(width 0.1143)
		(layer "B.Cu")
		(net "UPI_CPU1_CPU0_P0P0_DN<1>")
	)
	(segment
		(start 283.78912 -106.173778)
		(end 283.76753 -106.055414)
		(width 0.1143)
		(layer "B.Cu")
		(net "UPI_CPU1_CPU0_P0P0_DN<1>")
	)
	(segment
		(start 306.004976 -78.107794)
		(end 305.575208 -77.922628)
		(width 0.0889)
		(layer "B.Cu")
		(net "UPI_CPU1_CPU0_P0P0_DN<1>")
	)
	(segment
		(start 283.78912 -106.174032)
		(end 283.78912 -106.173778)
		(width 0.1143)
		(layer "B.Cu")
		(net "UPI_CPU1_CPU0_P0P0_DN<1>")
	)
	(segment
		(start 200.991216 -111.28756)
		(end 202.294998 -110.416848)
		(width 0.1143)
		(layer "B.Cu")
		(net "UPI_CPU1_CPU0_P0P0_DN<1>")
	)
	(segment
		(start 308.426866 -101.599238)
		(end 308.670706 -100.819204)
		(width 0.1143)
		(layer "B.Cu")
		(net "UPI_CPU1_CPU0_P0P0_DN<1>")
	)
	(segment
		(start 182.153814 -104.402128)
		(end 182.174134 -104.412796)
		(width 0.1143)
		(layer "B.Cu")
		(net "UPI_CPU1_CPU0_P0P0_DN<1>")
	)
	(segment
		(start 196.40804 -111.452406)
		(end 196.967348 -111.706406)
		(width 0.1143)
		(layer "B.Cu")
		(net "UPI_CPU1_CPU0_P0P0_DN<1>")
	)
	(segment
		(start 181.080664 -103.964994)
		(end 182.153814 -104.402128)
		(width 0.1143)
		(layer "B.Cu")
		(net "UPI_CPU1_CPU0_P0P0_DN<1>")
	)
	(segment
		(start 268.248638 -105.589578)
		(end 268.2494 -105.589578)
		(width 0.1143)
		(layer "B.Cu")
		(net "UPI_CPU1_CPU0_P0P0_DN<1>")
	)
	(segment
		(start 307.976524 -79.722218)
		(end 307.6956 -79.32801)
		(width 0.1143)
		(layer "B.Cu")
		(net "UPI_CPU1_CPU0_P0P0_DN<1>")
	)
	(segment
		(start 196.032374 -111.056674)
		(end 196.40804 -111.452406)
		(width 0.1143)
		(layer "B.Cu")
		(net "UPI_CPU1_CPU0_P0P0_DN<1>")
	)
	(segment
		(start 259.884164 -104.746552)
		(end 268.248638 -105.589578)
		(width 0.1143)
		(layer "B.Cu")
		(net "UPI_CPU1_CPU0_P0P0_DN<1>")
	)
	(segment
		(start 282.432252 -106.596942)
		(end 282.774898 -106.833924)
		(width 0.1143)
		(layer "B.Cu")
		(net "UPI_CPU1_CPU0_P0P0_DN<1>")
	)
	(segment
		(start 304.485548 -77.103986)
		(end 304.4063 -77.107034)
		(width 0.0889)
		(layer "B.Cu")
		(net "UPI_CPU1_CPU0_P0P0_DN<1>")
	)
	(segment
		(start 283.76753 -106.055414)
		(end 283.859986 -105.922826)
		(width 0.1143)
		(layer "B.Cu")
		(net "UPI_CPU1_CPU0_P0P0_DN<1>")
	)
	(segment
		(start 280.094182 -106.49458)
		(end 280.094944 -106.494326)
		(width 0.1143)
		(layer "B.Cu")
		(net "UPI_CPU1_CPU0_P0P0_DN<1>")
	)
	(segment
		(start 143.983964 -58.41619)
		(end 145.031714 -57.36844)
		(width 0.0889)
		(layer "B.Cu")
		(net "UPI_CPU1_CPU0_P0P0_DN<1>")
	)
	(segment
		(start 302.689006 -76.116434)
		(end 302.65624 -76.116434)
		(width 0.0889)
		(layer "B.Cu")
		(net "UPI_CPU1_CPU0_P0P0_DN<1>")
	)
	(segment
		(start 304.561494 -77.09916)
		(end 304.485548 -77.103986)
		(width 0.0889)
		(layer "B.Cu")
		(net "UPI_CPU1_CPU0_P0P0_DN<1>")
	)
	(segment
		(start 243.3828 -103.116634)
		(end 243.462556 -103.0859)
		(width 0.1143)
		(layer "B.Cu")
		(net "UPI_CPU1_CPU0_P0P0_DN<1>")
	)
	(segment
		(start 148.51888 -57.739026)
		(end 148.51888 -57.774586)
		(width 0.0889)
		(layer "B.Cu")
		(net "UPI_CPU1_CPU0_P0P0_DN<1>")
	)
	(segment
		(start 307.6956 -79.32801)
		(end 307.556662 -79.132938)
		(width 0.1143)
		(layer "B.Cu")
		(net "UPI_CPU1_CPU0_P0P0_DN<1>")
	)
	(segment
		(start 156.177488 -65.433448)
		(end 160.53816 -87.239856)
		(width 0.1143)
		(layer "B.Cu")
		(net "UPI_CPU1_CPU0_P0P0_DN<1>")
	)
	(segment
		(start 280.096722 -106.494072)
		(end 280.099262 -106.493564)
		(width 0.1143)
		(layer "B.Cu")
		(net "UPI_CPU1_CPU0_P0P0_DN<1>")
	)
	(segment
		(start 282.378912 -106.303572)
		(end 282.380436 -106.313478)
		(width 0.1143)
		(layer "B.Cu")
		(net "UPI_CPU1_CPU0_P0P0_DN<1>")
	)
	(segment
		(start 243.462556 -103.0859)
		(end 252.400562 -102.753668)
		(width 0.1143)
		(layer "B.Cu")
		(net "UPI_CPU1_CPU0_P0P0_DN<1>")
	)
	(segment
		(start 252.400562 -102.753668)
		(end 257.539236 -104.283764)
		(width 0.1143)
		(layer "B.Cu")
		(net "UPI_CPU1_CPU0_P0P0_DN<1>")
	)
	(segment
		(start 202.294998 -110.416848)
		(end 225.469704 -105.76433)
		(width 0.1143)
		(layer "B.Cu")
		(net "UPI_CPU1_CPU0_P0P0_DN<1>")
	)
	(segment
		(start 160.53816 -87.239856)
		(end 168.23563 -96.036638)
		(width 0.1143)
		(layer "B.Cu")
		(net "UPI_CPU1_CPU0_P0P0_DN<1>")
	)
	(segment
		(start 301.834296 -75.621388)
		(end 301.80153 -75.621388)
		(width 0.0889)
		(layer "B.Cu")
		(net "UPI_CPU1_CPU0_P0P0_DN<1>")
	)
	(segment
		(start 300.607476 -74.525886)
		(end 300.613826 -74.515218)
		(width 0.0889)
		(layer "B.Cu")
		(net "UPI_CPU1_CPU0_P0P0_DN<1>")
	)
	(segment
		(start 280.094944 -106.494326)
		(end 280.096722 -106.494072)
		(width 0.1143)
		(layer "B.Cu")
		(net "UPI_CPU1_CPU0_P0P0_DN<1>")
	)
	(segment
		(start 196.018912 -111.040926)
		(end 196.032374 -111.056674)
		(width 0.1143)
		(layer "B.Cu")
		(net "UPI_CPU1_CPU0_P0P0_DN<1>")
	)
	(segment
		(start 197.645528 -111.73587)
		(end 200.991216 -111.28756)
		(width 0.1143)
		(layer "B.Cu")
		(net "UPI_CPU1_CPU0_P0P0_DN<1>")
	)
	(segment
		(start 305.837082 -104.507284)
		(end 308.426866 -101.599238)
		(width 0.1143)
		(layer "B.Cu")
		(net "UPI_CPU1_CPU0_P0P0_DN<1>")
	)
	(segment
		(start 186.426094 -105.62971)
		(end 191.304926 -106.498644)
		(width 0.1143)
		(layer "B.Cu")
		(net "UPI_CPU1_CPU0_P0P0_DN<1>")
	)
	(segment
		(start 283.820616 -106.345736)
		(end 283.78912 -106.174032)
		(width 0.1143)
		(layer "B.Cu")
		(net "UPI_CPU1_CPU0_P0P0_DN<1>")
	)
	(segment
		(start 225.469704 -105.76433)
		(end 230.874824 -106.035348)
		(width 0.1143)
		(layer "B.Cu")
		(net "UPI_CPU1_CPU0_P0P0_DN<1>")
	)
	(segment
		(start 300.60265 -74.534522)
		(end 300.607476 -74.525886)
		(width 0.0889)
		(layer "B.Cu")
		(net "UPI_CPU1_CPU0_P0P0_DN<1>")
	)
	(segment
		(start 281.178508 -106.71937)
		(end 281.444446 -106.315002)
		(width 0.1143)
		(layer "B.Cu")
		(net "UPI_CPU1_CPU0_P0P0_DN<1>")
	)
	(segment
		(start 304.4063 -77.107034)
		(end 304.37328 -77.107034)
		(width 0.0889)
		(layer "B.Cu")
		(net "UPI_CPU1_CPU0_P0P0_DN<1>")
	)
	(arc
		(start 300.554136 -72.7456)
		(mid 300.753779 -72.545449)
		(end 300.954186 -72.744584)
		(width 0.0889)
		(layer "B.Cu")
		(net "UPI_CPU1_CPU0_P0P0_DN<1>")
	)
	(arc
		(start 302.324516 -75.916536)
		(mid 302.117512 -75.705672)
		(end 301.834296 -75.621388)
		(width 0.0889)
		(layer "B.Cu")
		(net "UPI_CPU1_CPU0_P0P0_DN<1>")
	)
	(arc
		(start 303.183036 -76.411836)
		(mid 302.974428 -76.199904)
		(end 302.689006 -76.116434)
		(width 0.0889)
		(layer "B.Cu")
		(net "UPI_CPU1_CPU0_P0P0_DN<1>")
	)
	(arc
		(start 301.80153 -75.621388)
		(mid 301.60768 -75.565038)
		(end 301.465996 -75.421236)
		(width 0.0889)
		(layer "B.Cu")
		(net "UPI_CPU1_CPU0_P0P0_DN<1>")
	)
	(arc
		(start 304.041556 -76.907136)
		(mid 303.834552 -76.696272)
		(end 303.551336 -76.611988)
		(width 0.0889)
		(layer "B.Cu")
		(net "UPI_CPU1_CPU0_P0P0_DN<1>")
	)
	(arc
		(start 300.613826 -73.524618)
		(mid 300.686624 -73.233855)
		(end 300.607476 -72.944736)
		(width 0.0889)
		(layer "B.Cu")
		(net "UPI_CPU1_CPU0_P0P0_DN<1>")
	)
	(arc
		(start 301.465996 -75.421236)
		(mid 301.257388 -75.209304)
		(end 300.971966 -75.125834)
		(width 0.0889)
		(layer "B.Cu")
		(net "UPI_CPU1_CPU0_P0P0_DN<1>")
	)
	(arc
		(start 300.607476 -73.935336)
		(mid 300.554006 -73.740273)
		(end 300.60265 -73.543922)
		(width 0.0889)
		(layer "B.Cu")
		(net "UPI_CPU1_CPU0_P0P0_DN<1>")
	)
	(arc
		(start 303.51857 -76.611988)
		(mid 303.32472 -76.555638)
		(end 303.183036 -76.411836)
		(width 0.0889)
		(layer "B.Cu")
		(net "UPI_CPU1_CPU0_P0P0_DN<1>")
	)
	(arc
		(start 300.607476 -72.944736)
		(mid 300.567768 -72.848661)
		(end 300.554136 -72.7456)
		(width 0.0889)
		(layer "B.Cu")
		(net "UPI_CPU1_CPU0_P0P0_DN<1>")
	)
	(arc
		(start 304.37328 -77.107034)
		(mid 304.181638 -77.049868)
		(end 304.041556 -76.907136)
		(width 0.0889)
		(layer "B.Cu")
		(net "UPI_CPU1_CPU0_P0P0_DN<1>")
	)
	(arc
		(start 302.65624 -76.116434)
		(mid 302.464598 -76.059268)
		(end 302.324516 -75.916536)
		(width 0.0889)
		(layer "B.Cu")
		(net "UPI_CPU1_CPU0_P0P0_DN<1>")
	)
	(arc
		(start 300.613826 -74.515218)
		(mid 300.686624 -74.224455)
		(end 300.607476 -73.935336)
		(width 0.0889)
		(layer "B.Cu")
		(net "UPI_CPU1_CPU0_P0P0_DN<1>")
	)
	(arc
		(start 300.9392 -75.125834)
		(mid 300.606282 -74.923843)
		(end 300.60265 -74.534522)
		(width 0.0889)
		(layer "B.Cu")
		(net "UPI_CPU1_CPU0_P0P0_DN<1>")
	)
	(segment
		(start 299.524166 -62.343538)
		(end 300.095666 -62.343538)
		(width 0.1143)
		(layer "F.Cu")
		(net "UPI_CPU1_CPU0_P0P0_DN<19>")
	)
	(segment
		(start 140.533374 -74.725784)
		(end 141.181074 -74.725784)
		(width 0.1143)
		(layer "F.Cu")
		(net "UPI_CPU1_CPU0_P0P0_DN<19>")
	)
	(via
		(at 141.181074 -74.725784)
		(size 0.508)
		(drill 0.254)
		(layers "F.Cu" "B.Cu")
		(net "UPI_CPU1_CPU0_P0P0_DN<19>")
	)
	(via
		(at 300.095666 -62.343538)
		(size 0.508)
		(drill 0.254)
		(layers "F.Cu" "B.Cu")
		(net "UPI_CPU1_CPU0_P0P0_DN<19>")
	)
	(segment
		(start 170.20159 -121.770648)
		(end 172.209714 -122.53849)
		(width 0.1143)
		(layer "B.Cu")
		(net "UPI_CPU1_CPU0_P0P0_DN<19>")
	)
	(segment
		(start 160.610296 -117.55501)
		(end 161.564574 -117.930676)
		(width 0.1143)
		(layer "B.Cu")
		(net "UPI_CPU1_CPU0_P0P0_DN<19>")
	)
	(segment
		(start 156.528008 -115.126262)
		(end 156.634434 -115.189508)
		(width 0.1143)
		(layer "B.Cu")
		(net "UPI_CPU1_CPU0_P0P0_DN<19>")
	)
	(segment
		(start 310.22671 -121.940066)
		(end 319.90538 -117.16004)
		(width 0.1143)
		(layer "B.Cu")
		(net "UPI_CPU1_CPU0_P0P0_DN<19>")
	)
	(segment
		(start 143.395446 -97.456752)
		(end 144.221454 -101.588316)
		(width 0.1143)
		(layer "B.Cu")
		(net "UPI_CPU1_CPU0_P0P0_DN<19>")
	)
	(segment
		(start 144.022826 -79.044292)
		(end 144.827752 -83.070954)
		(width 0.1143)
		(layer "B.Cu")
		(net "UPI_CPU1_CPU0_P0P0_DN<19>")
	)
	(segment
		(start 192.00495 -126.70409)
		(end 198.52894 -126.987554)
		(width 0.1143)
		(layer "B.Cu")
		(net "UPI_CPU1_CPU0_P0P0_DN<19>")
	)
	(segment
		(start 301.823882 -60.762388)
		(end 301.791116 -60.762388)
		(width 0.0889)
		(layer "B.Cu")
		(net "UPI_CPU1_CPU0_P0P0_DN<19>")
	)
	(segment
		(start 293.016686 -124.131832)
		(end 296.742612 -123.386342)
		(width 0.1143)
		(layer "B.Cu")
		(net "UPI_CPU1_CPU0_P0P0_DN<19>")
	)
	(segment
		(start 198.52894 -126.987554)
		(end 201.780394 -126.551182)
		(width 0.1143)
		(layer "B.Cu")
		(net "UPI_CPU1_CPU0_P0P0_DN<19>")
	)
	(segment
		(start 303.540922 -59.771534)
		(end 303.516792 -59.771534)
		(width 0.0889)
		(layer "B.Cu")
		(net "UPI_CPU1_CPU0_P0P0_DN<19>")
	)
	(segment
		(start 312.684922 -58.30062)
		(end 310.6928 -58.30062)
		(width 0.1143)
		(layer "B.Cu")
		(net "UPI_CPU1_CPU0_P0P0_DN<19>")
	)
	(segment
		(start 307.166518 -58.780934)
		(end 306.946046 -58.780934)
		(width 0.0889)
		(layer "B.Cu")
		(net "UPI_CPU1_CPU0_P0P0_DN<19>")
	)
	(segment
		(start 332.389734 -91.862656)
		(end 330.401168 -85.933534)
		(width 0.1143)
		(layer "B.Cu")
		(net "UPI_CPU1_CPU0_P0P0_DN<19>")
	)
	(segment
		(start 312.729118 -58.318908)
		(end 312.729118 -58.318654)
		(width 0.1143)
		(layer "B.Cu")
		(net "UPI_CPU1_CPU0_P0P0_DN<19>")
	)
	(segment
		(start 145.460974 -103.82504)
		(end 151.972772 -111.724694)
		(width 0.1143)
		(layer "B.Cu")
		(net "UPI_CPU1_CPU0_P0P0_DN<19>")
	)
	(segment
		(start 291.125402 -123.753372)
		(end 293.016686 -124.131832)
		(width 0.1143)
		(layer "B.Cu")
		(net "UPI_CPU1_CPU0_P0P0_DN<19>")
	)
	(segment
		(start 141.281912 -74.301096)
		(end 141.59992 -74.301096)
		(width 0.1143)
		(layer "B.Cu")
		(net "UPI_CPU1_CPU0_P0P0_DN<19>")
	)
	(segment
		(start 151.972772 -111.724694)
		(end 153.265886 -112.810036)
		(width 0.1143)
		(layer "B.Cu")
		(net "UPI_CPU1_CPU0_P0P0_DN<19>")
	)
	(segment
		(start 310.645302 -58.32602)
		(end 309.01386 -58.32602)
		(width 0.0889)
		(layer "B.Cu")
		(net "UPI_CPU1_CPU0_P0P0_DN<19>")
	)
	(segment
		(start 141.181074 -74.401934)
		(end 141.281912 -74.301096)
		(width 0.1143)
		(layer "B.Cu")
		(net "UPI_CPU1_CPU0_P0P0_DN<19>")
	)
	(segment
		(start 333.515462 -94.676722)
		(end 332.389734 -91.862656)
		(width 0.1143)
		(layer "B.Cu")
		(net "UPI_CPU1_CPU0_P0P0_DN<19>")
	)
	(segment
		(start 228.509576 -123.357132)
		(end 249.572272 -124.413772)
		(width 0.1143)
		(layer "B.Cu")
		(net "UPI_CPU1_CPU0_P0P0_DN<19>")
	)
	(segment
		(start 284.625796 -124.98832)
		(end 290.961064 -123.720606)
		(width 0.1143)
		(layer "B.Cu")
		(net "UPI_CPU1_CPU0_P0P0_DN<19>")
	)
	(segment
		(start 180.81498 -124.550678)
		(end 192.00495 -126.70409)
		(width 0.1143)
		(layer "B.Cu")
		(net "UPI_CPU1_CPU0_P0P0_DN<19>")
	)
	(segment
		(start 300.969172 -61.257434)
		(end 300.936406 -61.257434)
		(width 0.0889)
		(layer "B.Cu")
		(net "UPI_CPU1_CPU0_P0P0_DN<19>")
	)
	(segment
		(start 144.827752 -83.070954)
		(end 144.778984 -86.253828)
		(width 0.1143)
		(layer "B.Cu")
		(net "UPI_CPU1_CPU0_P0P0_DN<19>")
	)
	(segment
		(start 312.851546 -58.369454)
		(end 312.729118 -58.318908)
		(width 0.1143)
		(layer "B.Cu")
		(net "UPI_CPU1_CPU0_P0P0_DN<19>")
	)
	(segment
		(start 263.23036 -122.813318)
		(end 284.625796 -124.98832)
		(width 0.1143)
		(layer "B.Cu")
		(net "UPI_CPU1_CPU0_P0P0_DN<19>")
	)
	(segment
		(start 172.209714 -122.53849)
		(end 173.527212 -122.814588)
		(width 0.1143)
		(layer "B.Cu")
		(net "UPI_CPU1_CPU0_P0P0_DN<19>")
	)
	(segment
		(start 312.729118 -58.318654)
		(end 312.684922 -58.30062)
		(width 0.1143)
		(layer "B.Cu")
		(net "UPI_CPU1_CPU0_P0P0_DN<19>")
	)
	(segment
		(start 308.05882 -59.28106)
		(end 307.717444 -59.28106)
		(width 0.0889)
		(layer "B.Cu")
		(net "UPI_CPU1_CPU0_P0P0_DN<19>")
	)
	(segment
		(start 165.758876 -119.390922)
		(end 167.115998 -119.989346)
		(width 0.1143)
		(layer "B.Cu")
		(net "UPI_CPU1_CPU0_P0P0_DN<19>")
	)
	(segment
		(start 333.443072 -96.947228)
		(end 333.515462 -94.676722)
		(width 0.1143)
		(layer "B.Cu")
		(net "UPI_CPU1_CPU0_P0P0_DN<19>")
	)
	(segment
		(start 302.686212 -60.266834)
		(end 302.653446 -60.266834)
		(width 0.0889)
		(layer "B.Cu")
		(net "UPI_CPU1_CPU0_P0P0_DN<19>")
	)
	(segment
		(start 249.572272 -124.413772)
		(end 263.23036 -122.813318)
		(width 0.1143)
		(layer "B.Cu")
		(net "UPI_CPU1_CPU0_P0P0_DN<19>")
	)
	(segment
		(start 173.527212 -122.814588)
		(end 180.81498 -124.550678)
		(width 0.1143)
		(layer "B.Cu")
		(net "UPI_CPU1_CPU0_P0P0_DN<19>")
	)
	(segment
		(start 167.115998 -119.989346)
		(end 170.20159 -121.770648)
		(width 0.1143)
		(layer "B.Cu")
		(net "UPI_CPU1_CPU0_P0P0_DN<19>")
	)
	(segment
		(start 141.181074 -74.725784)
		(end 141.181074 -74.401934)
		(width 0.1143)
		(layer "B.Cu")
		(net "UPI_CPU1_CPU0_P0P0_DN<19>")
	)
	(segment
		(start 299.768514 -123.99137)
		(end 301.881794 -123.608846)
		(width 0.1143)
		(layer "B.Cu")
		(net "UPI_CPU1_CPU0_P0P0_DN<19>")
	)
	(segment
		(start 143.794988 -95.46082)
		(end 143.395446 -97.456752)
		(width 0.1143)
		(layer "B.Cu")
		(net "UPI_CPU1_CPU0_P0P0_DN<19>")
	)
	(segment
		(start 301.881794 -123.608846)
		(end 310.22671 -121.940066)
		(width 0.1143)
		(layer "B.Cu")
		(net "UPI_CPU1_CPU0_P0P0_DN<19>")
	)
	(segment
		(start 156.634434 -115.189508)
		(end 160.610296 -117.55501)
		(width 0.1143)
		(layer "B.Cu")
		(net "UPI_CPU1_CPU0_P0P0_DN<19>")
	)
	(segment
		(start 290.961064 -123.720606)
		(end 291.125402 -123.753372)
		(width 0.1143)
		(layer "B.Cu")
		(net "UPI_CPU1_CPU0_P0P0_DN<19>")
	)
	(segment
		(start 315.663834 -59.533536)
		(end 312.851546 -58.369454)
		(width 0.1143)
		(layer "B.Cu")
		(net "UPI_CPU1_CPU0_P0P0_DN<19>")
	)
	(segment
		(start 322.436744 -63.98641)
		(end 315.663834 -59.533536)
		(width 0.1143)
		(layer "B.Cu")
		(net "UPI_CPU1_CPU0_P0P0_DN<19>")
	)
	(segment
		(start 296.742612 -123.386342)
		(end 299.768514 -123.99137)
		(width 0.1143)
		(layer "B.Cu")
		(net "UPI_CPU1_CPU0_P0P0_DN<19>")
	)
	(segment
		(start 309.01386 -58.32602)
		(end 308.05882 -59.28106)
		(width 0.0889)
		(layer "B.Cu")
		(net "UPI_CPU1_CPU0_P0P0_DN<19>")
	)
	(segment
		(start 306.12334 -59.276234)
		(end 306.087272 -59.276234)
		(width 0.0889)
		(layer "B.Cu")
		(net "UPI_CPU1_CPU0_P0P0_DN<19>")
	)
	(segment
		(start 141.59992 -74.301096)
		(end 142.100554 -74.802238)
		(width 0.1143)
		(layer "B.Cu")
		(net "UPI_CPU1_CPU0_P0P0_DN<19>")
	)
	(segment
		(start 330.401168 -85.933534)
		(end 329.894184 -77.367892)
		(width 0.1143)
		(layer "B.Cu")
		(net "UPI_CPU1_CPU0_P0P0_DN<19>")
	)
	(segment
		(start 161.564574 -117.930676)
		(end 163.23437 -118.588536)
		(width 0.1143)
		(layer "B.Cu")
		(net "UPI_CPU1_CPU0_P0P0_DN<19>")
	)
	(segment
		(start 144.778984 -86.253828)
		(end 143.794988 -95.46082)
		(width 0.1143)
		(layer "B.Cu")
		(net "UPI_CPU1_CPU0_P0P0_DN<19>")
	)
	(segment
		(start 310.6928 -58.30062)
		(end 310.645302 -58.32602)
		(width 0.0889)
		(layer "B.Cu")
		(net "UPI_CPU1_CPU0_P0P0_DN<19>")
	)
	(segment
		(start 208.44129 -126.985776)
		(end 225.630232 -123.53417)
		(width 0.1143)
		(layer "B.Cu")
		(net "UPI_CPU1_CPU0_P0P0_DN<19>")
	)
	(segment
		(start 300.36897 -61.93028)
		(end 300.095666 -62.343538)
		(width 0.0889)
		(layer "B.Cu")
		(net "UPI_CPU1_CPU0_P0P0_DN<19>")
	)
	(segment
		(start 329.894184 -77.367892)
		(end 322.436744 -63.98641)
		(width 0.1143)
		(layer "B.Cu")
		(net "UPI_CPU1_CPU0_P0P0_DN<19>")
	)
	(segment
		(start 153.265886 -112.810036)
		(end 156.528008 -115.126262)
		(width 0.1143)
		(layer "B.Cu")
		(net "UPI_CPU1_CPU0_P0P0_DN<19>")
	)
	(segment
		(start 333.197962 -104.634538)
		(end 333.443072 -96.947228)
		(width 0.1143)
		(layer "B.Cu")
		(net "UPI_CPU1_CPU0_P0P0_DN<19>")
	)
	(segment
		(start 305.264566 -58.780934)
		(end 305.229006 -58.780934)
		(width 0.0889)
		(layer "B.Cu")
		(net "UPI_CPU1_CPU0_P0P0_DN<19>")
	)
	(segment
		(start 142.100554 -74.802238)
		(end 144.022826 -79.044292)
		(width 0.1143)
		(layer "B.Cu")
		(net "UPI_CPU1_CPU0_P0P0_DN<19>")
	)
	(segment
		(start 144.221454 -101.588316)
		(end 145.460974 -103.82504)
		(width 0.1143)
		(layer "B.Cu")
		(net "UPI_CPU1_CPU0_P0P0_DN<19>")
	)
	(segment
		(start 319.90538 -117.16004)
		(end 333.197962 -104.634538)
		(width 0.1143)
		(layer "B.Cu")
		(net "UPI_CPU1_CPU0_P0P0_DN<19>")
	)
	(segment
		(start 307.717444 -59.28106)
		(end 307.515514 -59.07913)
		(width 0.0889)
		(layer "B.Cu")
		(net "UPI_CPU1_CPU0_P0P0_DN<19>")
	)
	(segment
		(start 201.780394 -126.551182)
		(end 208.44129 -126.985776)
		(width 0.1143)
		(layer "B.Cu")
		(net "UPI_CPU1_CPU0_P0P0_DN<19>")
	)
	(segment
		(start 163.23437 -118.588536)
		(end 165.758876 -119.390922)
		(width 0.1143)
		(layer "B.Cu")
		(net "UPI_CPU1_CPU0_P0P0_DN<19>")
	)
	(segment
		(start 304.4063 -59.276234)
		(end 304.366676 -59.276234)
		(width 0.0889)
		(layer "B.Cu")
		(net "UPI_CPU1_CPU0_P0P0_DN<19>")
	)
	(segment
		(start 225.630232 -123.53417)
		(end 228.509576 -123.357132)
		(width 0.1143)
		(layer "B.Cu")
		(net "UPI_CPU1_CPU0_P0P0_DN<19>")
	)
	(arc
		(start 303.876456 -59.571382)
		(mid 303.734773 -59.715186)
		(end 303.540922 -59.771534)
		(width 0.0889)
		(layer "B.Cu")
		(net "UPI_CPU1_CPU0_P0P0_DN<19>")
	)
	(arc
		(start 301.300896 -61.057536)
		(mid 301.160817 -61.200272)
		(end 300.969172 -61.257434)
		(width 0.0889)
		(layer "B.Cu")
		(net "UPI_CPU1_CPU0_P0P0_DN<19>")
	)
	(arc
		(start 300.936406 -61.257434)
		(mid 300.502449 -61.467207)
		(end 300.36897 -61.93028)
		(width 0.0889)
		(layer "B.Cu")
		(net "UPI_CPU1_CPU0_P0P0_DN<19>")
	)
	(arc
		(start 302.653446 -60.266834)
		(mid 302.368022 -60.350301)
		(end 302.159416 -60.562236)
		(width 0.0889)
		(layer "B.Cu")
		(net "UPI_CPU1_CPU0_P0P0_DN<19>")
	)
	(arc
		(start 305.229006 -58.780934)
		(mid 304.943582 -58.864401)
		(end 304.734976 -59.076336)
		(width 0.0889)
		(layer "B.Cu")
		(net "UPI_CPU1_CPU0_P0P0_DN<19>")
	)
	(arc
		(start 303.017936 -60.066936)
		(mid 302.877857 -60.209672)
		(end 302.686212 -60.266834)
		(width 0.0889)
		(layer "B.Cu")
		(net "UPI_CPU1_CPU0_P0P0_DN<19>")
	)
	(arc
		(start 303.516792 -59.771534)
		(mid 303.228647 -59.853853)
		(end 303.017936 -60.066936)
		(width 0.0889)
		(layer "B.Cu")
		(net "UPI_CPU1_CPU0_P0P0_DN<19>")
	)
	(arc
		(start 304.734976 -59.076336)
		(mid 304.596232 -59.218369)
		(end 304.4063 -59.276234)
		(width 0.0889)
		(layer "B.Cu")
		(net "UPI_CPU1_CPU0_P0P0_DN<19>")
	)
	(arc
		(start 301.791116 -60.762388)
		(mid 301.507899 -60.846669)
		(end 301.300896 -61.057536)
		(width 0.0889)
		(layer "B.Cu")
		(net "UPI_CPU1_CPU0_P0P0_DN<19>")
	)
	(arc
		(start 305.758596 -59.076336)
		(mid 305.549988 -58.864404)
		(end 305.264566 -58.780934)
		(width 0.0889)
		(layer "B.Cu")
		(net "UPI_CPU1_CPU0_P0P0_DN<19>")
	)
	(arc
		(start 302.159416 -60.562236)
		(mid 302.017733 -60.70604)
		(end 301.823882 -60.762388)
		(width 0.0889)
		(layer "B.Cu")
		(net "UPI_CPU1_CPU0_P0P0_DN<19>")
	)
	(arc
		(start 306.452016 -59.076336)
		(mid 306.313272 -59.218369)
		(end 306.12334 -59.276234)
		(width 0.0889)
		(layer "B.Cu")
		(net "UPI_CPU1_CPU0_P0P0_DN<19>")
	)
	(arc
		(start 306.946046 -58.780934)
		(mid 306.660622 -58.864401)
		(end 306.452016 -59.076336)
		(width 0.0889)
		(layer "B.Cu")
		(net "UPI_CPU1_CPU0_P0P0_DN<19>")
	)
	(arc
		(start 304.366676 -59.276234)
		(mid 304.083459 -59.360515)
		(end 303.876456 -59.571382)
		(width 0.0889)
		(layer "B.Cu")
		(net "UPI_CPU1_CPU0_P0P0_DN<19>")
	)
	(arc
		(start 306.087272 -59.276234)
		(mid 305.897343 -59.218364)
		(end 305.758596 -59.076336)
		(width 0.0889)
		(layer "B.Cu")
		(net "UPI_CPU1_CPU0_P0P0_DN<19>")
	)
	(arc
		(start 307.515514 -59.07913)
		(mid 307.369414 -58.896796)
		(end 307.166518 -58.780934)
		(width 0.0889)
		(layer "B.Cu")
		(net "UPI_CPU1_CPU0_P0P0_DN<19>")
	)
	(segment
		(start 301.241206 -61.352938)
		(end 301.812706 -61.352938)
		(width 0.1143)
		(layer "F.Cu")
		(net "UPI_CPU1_CPU0_P0P0_DN<18>")
	)
	(segment
		(start 140.533374 -73.735184)
		(end 140.533374 -73.56856)
		(width 0.1143)
		(layer "F.Cu")
		(net "UPI_CPU1_CPU0_P0P0_DN<18>")
	)
	(segment
		(start 141.503146 -73.497948)
		(end 142.2273 -73.497948)
		(width 0.1143)
		(layer "F.Cu")
		(net "UPI_CPU1_CPU0_P0P0_DN<18>")
	)
	(segment
		(start 141.365732 -73.360534)
		(end 141.503146 -73.497948)
		(width 0.1143)
		(layer "F.Cu")
		(net "UPI_CPU1_CPU0_P0P0_DN<18>")
	)
	(segment
		(start 140.533374 -73.56856)
		(end 140.7414 -73.360534)
		(width 0.1143)
		(layer "F.Cu")
		(net "UPI_CPU1_CPU0_P0P0_DN<18>")
	)
	(segment
		(start 140.7414 -73.360534)
		(end 141.365732 -73.360534)
		(width 0.1143)
		(layer "F.Cu")
		(net "UPI_CPU1_CPU0_P0P0_DN<18>")
	)
	(segment
		(start 142.2273 -73.497948)
		(end 142.464536 -73.735184)
		(width 0.1143)
		(layer "F.Cu")
		(net "UPI_CPU1_CPU0_P0P0_DN<18>")
	)
	(via
		(at 301.812706 -61.352938)
		(size 0.508)
		(drill 0.254)
		(layers "F.Cu" "B.Cu")
		(net "UPI_CPU1_CPU0_P0P0_DN<18>")
	)
	(via
		(at 142.464536 -73.735184)
		(size 0.508)
		(drill 0.254)
		(layers "F.Cu" "B.Cu")
		(net "UPI_CPU1_CPU0_P0P0_DN<18>")
	)
	(segment
		(start 308.50586 -59.91352)
		(end 307.40858 -59.91352)
		(width 0.0889)
		(layer "B.Cu")
		(net "UPI_CPU1_CPU0_P0P0_DN<18>")
	)
	(segment
		(start 315.109352 -60.50915)
		(end 312.45683 -59.4106)
		(width 0.1143)
		(layer "B.Cu")
		(net "UPI_CPU1_CPU0_P0P0_DN<18>")
	)
	(segment
		(start 158.801054 -115.254278)
		(end 161.931096 -117.02542)
		(width 0.1143)
		(layer "B.Cu")
		(net "UPI_CPU1_CPU0_P0P0_DN<18>")
	)
	(segment
		(start 310.68264 -59.436)
		(end 308.98338 -59.436)
		(width 0.0889)
		(layer "B.Cu")
		(net "UPI_CPU1_CPU0_P0P0_DN<18>")
	)
	(segment
		(start 284.471364 -123.999244)
		(end 290.571174 -122.779282)
		(width 0.1143)
		(layer "B.Cu")
		(net "UPI_CPU1_CPU0_P0P0_DN<18>")
	)
	(segment
		(start 328.7776 -77.666342)
		(end 323.628766 -68.4276)
		(width 0.1143)
		(layer "B.Cu")
		(net "UPI_CPU1_CPU0_P0P0_DN<18>")
	)
	(segment
		(start 330.681584 -90.608912)
		(end 330.680568 -90.605864)
		(width 0.1143)
		(layer "B.Cu")
		(net "UPI_CPU1_CPU0_P0P0_DN<18>")
	)
	(segment
		(start 161.931096 -117.02542)
		(end 165.431216 -118.167404)
		(width 0.1143)
		(layer "B.Cu")
		(net "UPI_CPU1_CPU0_P0P0_DN<18>")
	)
	(segment
		(start 332.388464 -94.876112)
		(end 331.94879 -93.7768)
		(width 0.1143)
		(layer "B.Cu")
		(net "UPI_CPU1_CPU0_P0P0_DN<18>")
	)
	(segment
		(start 173.342808 -121.713498)
		(end 182.012336 -122.257566)
		(width 0.1143)
		(layer "B.Cu")
		(net "UPI_CPU1_CPU0_P0P0_DN<18>")
	)
	(segment
		(start 182.012336 -122.257566)
		(end 192.40246 -125.752352)
		(width 0.1143)
		(layer "B.Cu")
		(net "UPI_CPU1_CPU0_P0P0_DN<18>")
	)
	(segment
		(start 303.540922 -60.762388)
		(end 303.508156 -60.762388)
		(width 0.0889)
		(layer "B.Cu")
		(net "UPI_CPU1_CPU0_P0P0_DN<18>")
	)
	(segment
		(start 208.375504 -126.01194)
		(end 226.836478 -122.30481)
		(width 0.1143)
		(layer "B.Cu")
		(net "UPI_CPU1_CPU0_P0P0_DN<18>")
	)
	(segment
		(start 145.034254 -78.410816)
		(end 146.28622 -84.66963)
		(width 0.1143)
		(layer "B.Cu")
		(net "UPI_CPU1_CPU0_P0P0_DN<18>")
	)
	(segment
		(start 306.120292 -60.266834)
		(end 306.09032 -60.266834)
		(width 0.0889)
		(layer "B.Cu")
		(net "UPI_CPU1_CPU0_P0P0_DN<18>")
	)
	(segment
		(start 146.284188 -103.287576)
		(end 152.70353 -111.074454)
		(width 0.1143)
		(layer "B.Cu")
		(net "UPI_CPU1_CPU0_P0P0_DN<18>")
	)
	(segment
		(start 263.079992 -121.825258)
		(end 284.471364 -123.999244)
		(width 0.1143)
		(layer "B.Cu")
		(net "UPI_CPU1_CPU0_P0P0_DN<18>")
	)
	(segment
		(start 143.314928 -73.933558)
		(end 145.034254 -78.410816)
		(width 0.1143)
		(layer "B.Cu")
		(net "UPI_CPU1_CPU0_P0P0_DN<18>")
	)
	(segment
		(start 323.628766 -68.4276)
		(end 321.591178 -64.77127)
		(width 0.1143)
		(layer "B.Cu")
		(net "UPI_CPU1_CPU0_P0P0_DN<18>")
	)
	(segment
		(start 310.70804 -59.4106)
		(end 310.68264 -59.436)
		(width 0.0889)
		(layer "B.Cu")
		(net "UPI_CPU1_CPU0_P0P0_DN<18>")
	)
	(segment
		(start 166.38397 -118.449598)
		(end 170.608752 -120.888506)
		(width 0.1143)
		(layer "B.Cu")
		(net "UPI_CPU1_CPU0_P0P0_DN<18>")
	)
	(segment
		(start 144.428972 -98.030538)
		(end 145.026888 -101.019864)
		(width 0.1143)
		(layer "B.Cu")
		(net "UPI_CPU1_CPU0_P0P0_DN<18>")
	)
	(segment
		(start 304.403252 -60.266834)
		(end 304.370486 -60.266834)
		(width 0.0889)
		(layer "B.Cu")
		(net "UPI_CPU1_CPU0_P0P0_DN<18>")
	)
	(segment
		(start 291.125402 -122.88901)
		(end 293.116508 -123.283726)
		(width 0.1143)
		(layer "B.Cu")
		(net "UPI_CPU1_CPU0_P0P0_DN<18>")
	)
	(segment
		(start 226.836478 -122.30481)
		(end 249.550682 -123.443492)
		(width 0.1143)
		(layer "B.Cu")
		(net "UPI_CPU1_CPU0_P0P0_DN<18>")
	)
	(segment
		(start 143.066516 -73.55205)
		(end 143.314928 -73.933558)
		(width 0.1143)
		(layer "B.Cu")
		(net "UPI_CPU1_CPU0_P0P0_DN<18>")
	)
	(segment
		(start 142.464536 -73.435464)
		(end 142.57655 -73.32345)
		(width 0.1143)
		(layer "B.Cu")
		(net "UPI_CPU1_CPU0_P0P0_DN<18>")
	)
	(segment
		(start 145.026888 -101.019864)
		(end 146.284188 -103.287576)
		(width 0.1143)
		(layer "B.Cu")
		(net "UPI_CPU1_CPU0_P0P0_DN<18>")
	)
	(segment
		(start 308.98338 -59.436)
		(end 308.50586 -59.91352)
		(width 0.0889)
		(layer "B.Cu")
		(net "UPI_CPU1_CPU0_P0P0_DN<18>")
	)
	(segment
		(start 329.00493 -86.416134)
		(end 328.93 -83.530186)
		(width 0.1143)
		(layer "B.Cu")
		(net "UPI_CPU1_CPU0_P0P0_DN<18>")
	)
	(segment
		(start 302.686212 -61.257434)
		(end 302.653446 -61.257434)
		(width 0.0889)
		(layer "B.Cu")
		(net "UPI_CPU1_CPU0_P0P0_DN<18>")
	)
	(segment
		(start 307.40858 -59.91352)
		(end 307.266594 -59.771534)
		(width 0.0889)
		(layer "B.Cu")
		(net "UPI_CPU1_CPU0_P0P0_DN<18>")
	)
	(segment
		(start 170.608752 -120.888506)
		(end 173.342808 -121.713498)
		(width 0.1143)
		(layer "B.Cu")
		(net "UPI_CPU1_CPU0_P0P0_DN<18>")
	)
	(segment
		(start 293.116508 -123.283726)
		(end 296.635932 -122.579892)
		(width 0.1143)
		(layer "B.Cu")
		(net "UPI_CPU1_CPU0_P0P0_DN<18>")
	)
	(segment
		(start 330.680568 -90.605864)
		(end 329.14971 -86.778338)
		(width 0.1143)
		(layer "B.Cu")
		(net "UPI_CPU1_CPU0_P0P0_DN<18>")
	)
	(segment
		(start 328.93 -83.530186)
		(end 328.833988 -79.8322)
		(width 0.1143)
		(layer "B.Cu")
		(net "UPI_CPU1_CPU0_P0P0_DN<18>")
	)
	(segment
		(start 142.464536 -73.735184)
		(end 142.464536 -73.435464)
		(width 0.1143)
		(layer "B.Cu")
		(net "UPI_CPU1_CPU0_P0P0_DN<18>")
	)
	(segment
		(start 332.087728 -104.308148)
		(end 332.388464 -94.876112)
		(width 0.1143)
		(layer "B.Cu")
		(net "UPI_CPU1_CPU0_P0P0_DN<18>")
	)
	(segment
		(start 329.14971 -86.778338)
		(end 329.14971 -86.778084)
		(width 0.1143)
		(layer "B.Cu")
		(net "UPI_CPU1_CPU0_P0P0_DN<18>")
	)
	(segment
		(start 290.571174 -122.779282)
		(end 291.125402 -122.88901)
		(width 0.1143)
		(layer "B.Cu")
		(net "UPI_CPU1_CPU0_P0P0_DN<18>")
	)
	(segment
		(start 201.77125 -125.580902)
		(end 208.375504 -126.01194)
		(width 0.1143)
		(layer "B.Cu")
		(net "UPI_CPU1_CPU0_P0P0_DN<18>")
	)
	(segment
		(start 165.431216 -118.167404)
		(end 166.38397 -118.449598)
		(width 0.1143)
		(layer "B.Cu")
		(net "UPI_CPU1_CPU0_P0P0_DN<18>")
	)
	(segment
		(start 319.47612 -116.194078)
		(end 332.087728 -104.308148)
		(width 0.1143)
		(layer "B.Cu")
		(net "UPI_CPU1_CPU0_P0P0_DN<18>")
	)
	(segment
		(start 142.83817 -73.32345)
		(end 143.066516 -73.55205)
		(width 0.1143)
		(layer "B.Cu")
		(net "UPI_CPU1_CPU0_P0P0_DN<18>")
	)
	(segment
		(start 152.70353 -111.074454)
		(end 153.86939 -112.052608)
		(width 0.1143)
		(layer "B.Cu")
		(net "UPI_CPU1_CPU0_P0P0_DN<18>")
	)
	(segment
		(start 307.266594 -59.771534)
		(end 306.950872 -59.771534)
		(width 0.0889)
		(layer "B.Cu")
		(net "UPI_CPU1_CPU0_P0P0_DN<18>")
	)
	(segment
		(start 146.28622 -88.743028)
		(end 144.428972 -98.030538)
		(width 0.1143)
		(layer "B.Cu")
		(net "UPI_CPU1_CPU0_P0P0_DN<18>")
	)
	(segment
		(start 192.40246 -125.752352)
		(end 192.4812 -125.755908)
		(width 0.1143)
		(layer "B.Cu")
		(net "UPI_CPU1_CPU0_P0P0_DN<18>")
	)
	(segment
		(start 309.9816 -120.954546)
		(end 319.47612 -116.194078)
		(width 0.1143)
		(layer "B.Cu")
		(net "UPI_CPU1_CPU0_P0P0_DN<18>")
	)
	(segment
		(start 249.550682 -123.443492)
		(end 263.079992 -121.825258)
		(width 0.1143)
		(layer "B.Cu")
		(net "UPI_CPU1_CPU0_P0P0_DN<18>")
	)
	(segment
		(start 192.4812 -125.755908)
		(end 198.496428 -126.017782)
		(width 0.1143)
		(layer "B.Cu")
		(net "UPI_CPU1_CPU0_P0P0_DN<18>")
	)
	(segment
		(start 328.833988 -79.8322)
		(end 328.7776 -77.666342)
		(width 0.1143)
		(layer "B.Cu")
		(net "UPI_CPU1_CPU0_P0P0_DN<18>")
	)
	(segment
		(start 331.94879 -93.7768)
		(end 330.681584 -90.608912)
		(width 0.1143)
		(layer "B.Cu")
		(net "UPI_CPU1_CPU0_P0P0_DN<18>")
	)
	(segment
		(start 301.870618 -61.748924)
		(end 301.812706 -61.691012)
		(width 0.0889)
		(layer "B.Cu")
		(net "UPI_CPU1_CPU0_P0P0_DN<18>")
	)
	(segment
		(start 296.635932 -122.579892)
		(end 299.27677 -123.109736)
		(width 0.1143)
		(layer "B.Cu")
		(net "UPI_CPU1_CPU0_P0P0_DN<18>")
	)
	(segment
		(start 142.57655 -73.32345)
		(end 142.83817 -73.32345)
		(width 0.1143)
		(layer "B.Cu")
		(net "UPI_CPU1_CPU0_P0P0_DN<18>")
	)
	(segment
		(start 329.14971 -86.778084)
		(end 329.00493 -86.416134)
		(width 0.1143)
		(layer "B.Cu")
		(net "UPI_CPU1_CPU0_P0P0_DN<18>")
	)
	(segment
		(start 153.86939 -112.052608)
		(end 158.801054 -115.254278)
		(width 0.1143)
		(layer "B.Cu")
		(net "UPI_CPU1_CPU0_P0P0_DN<18>")
	)
	(segment
		(start 198.496428 -126.017782)
		(end 201.77125 -125.580902)
		(width 0.1143)
		(layer "B.Cu")
		(net "UPI_CPU1_CPU0_P0P0_DN<18>")
	)
	(segment
		(start 301.812706 -61.691012)
		(end 301.812706 -61.352938)
		(width 0.0889)
		(layer "B.Cu")
		(net "UPI_CPU1_CPU0_P0P0_DN<18>")
	)
	(segment
		(start 321.591178 -64.77127)
		(end 315.109352 -60.50915)
		(width 0.1143)
		(layer "B.Cu")
		(net "UPI_CPU1_CPU0_P0P0_DN<18>")
	)
	(segment
		(start 146.28622 -84.66963)
		(end 146.28622 -88.743028)
		(width 0.1143)
		(layer "B.Cu")
		(net "UPI_CPU1_CPU0_P0P0_DN<18>")
	)
	(segment
		(start 312.45683 -59.4106)
		(end 310.70804 -59.4106)
		(width 0.1143)
		(layer "B.Cu")
		(net "UPI_CPU1_CPU0_P0P0_DN<18>")
	)
	(segment
		(start 299.27677 -123.109736)
		(end 309.9816 -120.954546)
		(width 0.1143)
		(layer "B.Cu")
		(net "UPI_CPU1_CPU0_P0P0_DN<18>")
	)
	(arc
		(start 306.09032 -60.266834)
		(mid 305.898678 -60.209668)
		(end 305.758596 -60.066936)
		(width 0.0889)
		(layer "B.Cu")
		(net "UPI_CPU1_CPU0_P0P0_DN<18>")
	)
	(arc
		(start 305.758596 -60.066936)
		(mid 305.551809 -59.856203)
		(end 305.268884 -59.771788)
		(width 0.0889)
		(layer "B.Cu")
		(net "UPI_CPU1_CPU0_P0P0_DN<18>")
	)
	(arc
		(start 303.017936 -61.057536)
		(mid 302.877857 -61.200272)
		(end 302.686212 -61.257434)
		(width 0.0889)
		(layer "B.Cu")
		(net "UPI_CPU1_CPU0_P0P0_DN<18>")
	)
	(arc
		(start 306.452016 -60.066936)
		(mid 306.311937 -60.209672)
		(end 306.120292 -60.266834)
		(width 0.0889)
		(layer "B.Cu")
		(net "UPI_CPU1_CPU0_P0P0_DN<18>")
	)
	(arc
		(start 303.876456 -60.562236)
		(mid 303.734773 -60.70604)
		(end 303.540922 -60.762388)
		(width 0.0889)
		(layer "B.Cu")
		(net "UPI_CPU1_CPU0_P0P0_DN<18>")
	)
	(arc
		(start 303.508156 -60.762388)
		(mid 303.224939 -60.846669)
		(end 303.017936 -61.057536)
		(width 0.0889)
		(layer "B.Cu")
		(net "UPI_CPU1_CPU0_P0P0_DN<18>")
	)
	(arc
		(start 306.950872 -59.771534)
		(mid 306.662727 -59.853853)
		(end 306.452016 -60.066936)
		(width 0.0889)
		(layer "B.Cu")
		(net "UPI_CPU1_CPU0_P0P0_DN<18>")
	)
	(arc
		(start 302.159416 -61.552836)
		(mid 302.037525 -61.684032)
		(end 301.870618 -61.748924)
		(width 0.0889)
		(layer "B.Cu")
		(net "UPI_CPU1_CPU0_P0P0_DN<18>")
	)
	(arc
		(start 304.370486 -60.266834)
		(mid 304.085062 -60.350301)
		(end 303.876456 -60.562236)
		(width 0.0889)
		(layer "B.Cu")
		(net "UPI_CPU1_CPU0_P0P0_DN<18>")
	)
	(arc
		(start 304.734976 -60.066936)
		(mid 304.594897 -60.209672)
		(end 304.403252 -60.266834)
		(width 0.0889)
		(layer "B.Cu")
		(net "UPI_CPU1_CPU0_P0P0_DN<18>")
	)
	(arc
		(start 305.268884 -59.771788)
		(mid 305.246786 -59.771375)
		(end 305.224688 -59.771788)
		(width 0.0889)
		(layer "B.Cu")
		(net "UPI_CPU1_CPU0_P0P0_DN<18>")
	)
	(arc
		(start 302.653446 -61.257434)
		(mid 302.368022 -61.340901)
		(end 302.159416 -61.552836)
		(width 0.0889)
		(layer "B.Cu")
		(net "UPI_CPU1_CPU0_P0P0_DN<18>")
	)
	(arc
		(start 305.224688 -59.771788)
		(mid 304.941752 -59.856184)
		(end 304.734976 -60.066936)
		(width 0.0889)
		(layer "B.Cu")
		(net "UPI_CPU1_CPU0_P0P0_DN<18>")
	)
	(segment
		(start 140.533374 -71.753984)
		(end 141.104874 -71.753984)
		(width 0.1143)
		(layer "F.Cu")
		(net "UPI_CPU1_CPU0_P0P0_DN<17>")
	)
	(segment
		(start 302.099726 -61.847984)
		(end 302.671226 -61.847984)
		(width 0.1143)
		(layer "F.Cu")
		(net "UPI_CPU1_CPU0_P0P0_DN<17>")
	)
	(via
		(at 147.487386 -85.030056)
		(size 0.508)
		(drill 0.254)
		(layers "F.Cu" "B.Cu")
		(net "UPI_CPU1_CPU0_P0P0_DN<17>")
	)
	(via
		(at 302.671226 -61.847984)
		(size 0.508)
		(drill 0.254)
		(layers "F.Cu" "B.Cu")
		(net "UPI_CPU1_CPU0_P0P0_DN<17>")
	)
	(via
		(at 141.104874 -71.753984)
		(size 0.508)
		(drill 0.254)
		(layers "F.Cu" "B.Cu")
		(net "UPI_CPU1_CPU0_P0P0_DN<17>")
	)
	(segment
		(start 146.567398 -94.759018)
		(end 146.664934 -94.905576)
		(width 0.1143)
		(layer "B.Cu")
		(net "UPI_CPU1_CPU0_P0P0_DN<17>")
	)
	(segment
		(start 249.421904 -122.226832)
		(end 263.075928 -120.609868)
		(width 0.1143)
		(layer "B.Cu")
		(net "UPI_CPU1_CPU0_P0P0_DN<17>")
	)
	(segment
		(start 146.354292 -100.919026)
		(end 147.250404 -102.53599)
		(width 0.1143)
		(layer "B.Cu")
		(net "UPI_CPU1_CPU0_P0P0_DN<17>")
	)
	(segment
		(start 154.567382 -111.059722)
		(end 156.006292 -111.955834)
		(width 0.1143)
		(layer "B.Cu")
		(net "UPI_CPU1_CPU0_P0P0_DN<17>")
	)
	(segment
		(start 306.126896 -61.447934)
		(end 306.083716 -61.447934)
		(width 0.0889)
		(layer "B.Cu")
		(net "UPI_CPU1_CPU0_P0P0_DN<17>")
	)
	(segment
		(start 201.665078 -124.361956)
		(end 208.291684 -124.795534)
		(width 0.1143)
		(layer "B.Cu")
		(net "UPI_CPU1_CPU0_P0P0_DN<17>")
	)
	(segment
		(start 147.013168 -92.531692)
		(end 147.110704 -92.67825)
		(width 0.1143)
		(layer "B.Cu")
		(net "UPI_CPU1_CPU0_P0P0_DN<17>")
	)
	(segment
		(start 147.06092 -92.927424)
		(end 146.914108 -93.025214)
		(width 0.1143)
		(layer "B.Cu")
		(net "UPI_CPU1_CPU0_P0P0_DN<17>")
	)
	(segment
		(start 159.944054 -113.693448)
		(end 160.19653 -113.726976)
		(width 0.1143)
		(layer "B.Cu")
		(net "UPI_CPU1_CPU0_P0P0_DN<17>")
	)
	(segment
		(start 146.664934 -94.905576)
		(end 146.61515 -95.15475)
		(width 0.1143)
		(layer "B.Cu")
		(net "UPI_CPU1_CPU0_P0P0_DN<17>")
	)
	(segment
		(start 304.409856 -61.447934)
		(end 304.37709 -61.447934)
		(width 0.0889)
		(layer "B.Cu")
		(net "UPI_CPU1_CPU0_P0P0_DN<17>")
	)
	(segment
		(start 147.487386 -85.030056)
		(end 147.999958 -87.593424)
		(width 0.1143)
		(layer "B.Cu")
		(net "UPI_CPU1_CPU0_P0P0_DN<17>")
	)
	(segment
		(start 146.418808 -95.50146)
		(end 146.516344 -95.648018)
		(width 0.1143)
		(layer "B.Cu")
		(net "UPI_CPU1_CPU0_P0P0_DN<17>")
	)
	(segment
		(start 142.32382 -71.658988)
		(end 141.685518 -71.658988)
		(width 0.0889)
		(layer "B.Cu")
		(net "UPI_CPU1_CPU0_P0P0_DN<17>")
	)
	(segment
		(start 163.17087 -114.256312)
		(end 164.994082 -116.25072)
		(width 0.1143)
		(layer "B.Cu")
		(net "UPI_CPU1_CPU0_P0P0_DN<17>")
	)
	(segment
		(start 146.813524 -94.163134)
		(end 146.76374 -94.412308)
		(width 0.1143)
		(layer "B.Cu")
		(net "UPI_CPU1_CPU0_P0P0_DN<17>")
	)
	(segment
		(start 331.01788 -95.137986)
		(end 328.991976 -90.074496)
		(width 0.1143)
		(layer "B.Cu")
		(net "UPI_CPU1_CPU0_P0P0_DN<17>")
	)
	(segment
		(start 327.646538 -86.711028)
		(end 327.420986 -78.029816)
		(width 0.1143)
		(layer "B.Cu")
		(net "UPI_CPU1_CPU0_P0P0_DN<17>")
	)
	(segment
		(start 164.994082 -116.25072)
		(end 171.091606 -119.770906)
		(width 0.1143)
		(layer "B.Cu")
		(net "UPI_CPU1_CPU0_P0P0_DN<17>")
	)
	(segment
		(start 147.250404 -102.53599)
		(end 153.626312 -110.27029)
		(width 0.1143)
		(layer "B.Cu")
		(net "UPI_CPU1_CPU0_P0P0_DN<17>")
	)
	(segment
		(start 146.270218 -96.243902)
		(end 146.367754 -96.39046)
		(width 0.1143)
		(layer "B.Cu")
		(net "UPI_CPU1_CPU0_P0P0_DN<17>")
	)
	(segment
		(start 291.125402 -121.844816)
		(end 293.158418 -122.250708)
		(width 0.1143)
		(layer "B.Cu")
		(net "UPI_CPU1_CPU0_P0P0_DN<17>")
	)
	(segment
		(start 290.060888 -121.632472)
		(end 291.125402 -121.844816)
		(width 0.1143)
		(layer "B.Cu")
		(net "UPI_CPU1_CPU0_P0P0_DN<17>")
	)
	(segment
		(start 192.62725 -124.551948)
		(end 198.33082 -124.800868)
		(width 0.1143)
		(layer "B.Cu")
		(net "UPI_CPU1_CPU0_P0P0_DN<17>")
	)
	(segment
		(start 144.689576 -74.593196)
		(end 144.047464 -73.206864)
		(width 0.0889)
		(layer "B.Cu")
		(net "UPI_CPU1_CPU0_P0P0_DN<17>")
	)
	(segment
		(start 146.61515 -95.15475)
		(end 146.468592 -95.25254)
		(width 0.1143)
		(layer "B.Cu")
		(net "UPI_CPU1_CPU0_P0P0_DN<17>")
	)
	(segment
		(start 153.626312 -110.27029)
		(end 154.567382 -111.059722)
		(width 0.1143)
		(layer "B.Cu")
		(net "UPI_CPU1_CPU0_P0P0_DN<17>")
	)
	(segment
		(start 226.74326 -121.089674)
		(end 249.421904 -122.226832)
		(width 0.1143)
		(layer "B.Cu")
		(net "UPI_CPU1_CPU0_P0P0_DN<17>")
	)
	(segment
		(start 161.0868 -113.720372)
		(end 161.338768 -113.7539)
		(width 0.1143)
		(layer "B.Cu")
		(net "UPI_CPU1_CPU0_P0P0_DN<17>")
	)
	(segment
		(start 330.737972 -103.90886)
		(end 331.01788 -95.137986)
		(width 0.1143)
		(layer "B.Cu")
		(net "UPI_CPU1_CPU0_P0P0_DN<17>")
	)
	(segment
		(start 147.20951 -92.184982)
		(end 147.062698 -92.282772)
		(width 0.1143)
		(layer "B.Cu")
		(net "UPI_CPU1_CPU0_P0P0_DN<17>")
	)
	(segment
		(start 297.601894 -121.361962)
		(end 299.581824 -121.758964)
		(width 0.1143)
		(layer "B.Cu")
		(net "UPI_CPU1_CPU0_P0P0_DN<17>")
	)
	(segment
		(start 147.062698 -92.282772)
		(end 147.013168 -92.531692)
		(width 0.1143)
		(layer "B.Cu")
		(net "UPI_CPU1_CPU0_P0P0_DN<17>")
	)
	(segment
		(start 326.779636 -76.878688)
		(end 320.563748 -65.725294)
		(width 0.1143)
		(layer "B.Cu")
		(net "UPI_CPU1_CPU0_P0P0_DN<17>")
	)
	(segment
		(start 160.695386 -113.793778)
		(end 160.9471 -113.827306)
		(width 0.1143)
		(layer "B.Cu")
		(net "UPI_CPU1_CPU0_P0P0_DN<17>")
	)
	(segment
		(start 312.157872 -60.7695)
		(end 310.6928 -60.7695)
		(width 0.1143)
		(layer "B.Cu")
		(net "UPI_CPU1_CPU0_P0P0_DN<17>")
	)
	(segment
		(start 173.559978 -120.515634)
		(end 182.246016 -121.060718)
		(width 0.1143)
		(layer "B.Cu")
		(net "UPI_CPU1_CPU0_P0P0_DN<17>")
	)
	(segment
		(start 147.487386 -85.030056)
		(end 145.921984 -77.199998)
		(width 0.1143)
		(layer "B.Cu")
		(net "UPI_CPU1_CPU0_P0P0_DN<17>")
	)
	(segment
		(start 146.715988 -94.016576)
		(end 146.813524 -94.163134)
		(width 0.1143)
		(layer "B.Cu")
		(net "UPI_CPU1_CPU0_P0P0_DN<17>")
	)
	(segment
		(start 309.08498 -61.447934)
		(end 307.69687 -61.447934)
		(width 0.0889)
		(layer "B.Cu")
		(net "UPI_CPU1_CPU0_P0P0_DN<17>")
	)
	(segment
		(start 146.516344 -95.648018)
		(end 146.46656 -95.897446)
		(width 0.1143)
		(layer "B.Cu")
		(net "UPI_CPU1_CPU0_P0P0_DN<17>")
	)
	(segment
		(start 161.338768 -113.7539)
		(end 161.445702 -113.894108)
		(width 0.1143)
		(layer "B.Cu")
		(net "UPI_CPU1_CPU0_P0P0_DN<17>")
	)
	(segment
		(start 310.6674 -60.7441)
		(end 309.788814 -60.7441)
		(width 0.0889)
		(layer "B.Cu")
		(net "UPI_CPU1_CPU0_P0P0_DN<17>")
	)
	(segment
		(start 171.091606 -119.770906)
		(end 173.559978 -120.515634)
		(width 0.1143)
		(layer "B.Cu")
		(net "UPI_CPU1_CPU0_P0P0_DN<17>")
	)
	(segment
		(start 303.547526 -61.943488)
		(end 303.511966 -61.943488)
		(width 0.0889)
		(layer "B.Cu")
		(net "UPI_CPU1_CPU0_P0P0_DN<17>")
	)
	(segment
		(start 146.320002 -95.994982)
		(end 146.270218 -96.243902)
		(width 0.1143)
		(layer "B.Cu")
		(net "UPI_CPU1_CPU0_P0P0_DN<17>")
	)
	(segment
		(start 162.627818 -114.051842)
		(end 163.17087 -114.256312)
		(width 0.1143)
		(layer "B.Cu")
		(net "UPI_CPU1_CPU0_P0P0_DN<17>")
	)
	(segment
		(start 144.723104 -74.605388)
		(end 144.689576 -74.593196)
		(width 0.0889)
		(layer "B.Cu")
		(net "UPI_CPU1_CPU0_P0P0_DN<17>")
	)
	(segment
		(start 144.047464 -73.206864)
		(end 142.623794 -71.783194)
		(width 0.0889)
		(layer "B.Cu")
		(net "UPI_CPU1_CPU0_P0P0_DN<17>")
	)
	(segment
		(start 146.367754 -96.39046)
		(end 146.31797 -96.639634)
		(width 0.1143)
		(layer "B.Cu")
		(net "UPI_CPU1_CPU0_P0P0_DN<17>")
	)
	(segment
		(start 263.075928 -120.609868)
		(end 284.36189 -122.77217)
		(width 0.1143)
		(layer "B.Cu")
		(net "UPI_CPU1_CPU0_P0P0_DN<17>")
	)
	(segment
		(start 309.684928 -119.73306)
		(end 318.895476 -115.065556)
		(width 0.1143)
		(layer "B.Cu")
		(net "UPI_CPU1_CPU0_P0P0_DN<17>")
	)
	(segment
		(start 147.110704 -92.67825)
		(end 147.06092 -92.927424)
		(width 0.1143)
		(layer "B.Cu")
		(net "UPI_CPU1_CPU0_P0P0_DN<17>")
	)
	(segment
		(start 320.563748 -65.725294)
		(end 314.502292 -61.739526)
		(width 0.1143)
		(layer "B.Cu")
		(net "UPI_CPU1_CPU0_P0P0_DN<17>")
	)
	(segment
		(start 302.964342 -61.679074)
		(end 302.671226 -61.847984)
		(width 0.0889)
		(layer "B.Cu")
		(net "UPI_CPU1_CPU0_P0P0_DN<17>")
	)
	(segment
		(start 160.336484 -113.620042)
		(end 160.588452 -113.653824)
		(width 0.1143)
		(layer "B.Cu")
		(net "UPI_CPU1_CPU0_P0P0_DN<17>")
	)
	(segment
		(start 160.588452 -113.653824)
		(end 160.695386 -113.793778)
		(width 0.1143)
		(layer "B.Cu")
		(net "UPI_CPU1_CPU0_P0P0_DN<17>")
	)
	(segment
		(start 146.962114 -93.420692)
		(end 146.91233 -93.669866)
		(width 0.1143)
		(layer "B.Cu")
		(net "UPI_CPU1_CPU0_P0P0_DN<17>")
	)
	(segment
		(start 307.347112 -61.149738)
		(end 307.346858 -61.149992)
		(width 0.0889)
		(layer "B.Cu")
		(net "UPI_CPU1_CPU0_P0P0_DN<17>")
	)
	(segment
		(start 310.6928 -60.7695)
		(end 310.6674 -60.7441)
		(width 0.0889)
		(layer "B.Cu")
		(net "UPI_CPU1_CPU0_P0P0_DN<17>")
	)
	(segment
		(start 146.914108 -93.025214)
		(end 146.864578 -93.274134)
		(width 0.1143)
		(layer "B.Cu")
		(net "UPI_CPU1_CPU0_P0P0_DN<17>")
	)
	(segment
		(start 145.844768 -98.370644)
		(end 146.354292 -100.919026)
		(width 0.1143)
		(layer "B.Cu")
		(net "UPI_CPU1_CPU0_P0P0_DN<17>")
	)
	(segment
		(start 147.999958 -87.593424)
		(end 147.161504 -91.78925)
		(width 0.1143)
		(layer "B.Cu")
		(net "UPI_CPU1_CPU0_P0P0_DN<17>")
	)
	(segment
		(start 144.801082 -74.774552)
		(end 144.732248 -74.625454)
		(width 0.1143)
		(layer "B.Cu")
		(net "UPI_CPU1_CPU0_P0P0_DN<17>")
	)
	(segment
		(start 327.420986 -78.029816)
		(end 326.779636 -76.878688)
		(width 0.1143)
		(layer "B.Cu")
		(net "UPI_CPU1_CPU0_P0P0_DN<17>")
	)
	(segment
		(start 314.502292 -61.739526)
		(end 312.157872 -60.7695)
		(width 0.1143)
		(layer "B.Cu")
		(net "UPI_CPU1_CPU0_P0P0_DN<17>")
	)
	(segment
		(start 307.130704 -60.952888)
		(end 306.94884 -60.952888)
		(width 0.0889)
		(layer "B.Cu")
		(net "UPI_CPU1_CPU0_P0P0_DN<17>")
	)
	(segment
		(start 156.006292 -111.955834)
		(end 159.944054 -113.693448)
		(width 0.1143)
		(layer "B.Cu")
		(net "UPI_CPU1_CPU0_P0P0_DN<17>")
	)
	(segment
		(start 145.921984 -77.199998)
		(end 144.801082 -74.774552)
		(width 0.1143)
		(layer "B.Cu")
		(net "UPI_CPU1_CPU0_P0P0_DN<17>")
	)
	(segment
		(start 146.91233 -93.669866)
		(end 146.765772 -93.767656)
		(width 0.1143)
		(layer "B.Cu")
		(net "UPI_CPU1_CPU0_P0P0_DN<17>")
	)
	(segment
		(start 293.158418 -122.250708)
		(end 297.601894 -121.361962)
		(width 0.1143)
		(layer "B.Cu")
		(net "UPI_CPU1_CPU0_P0P0_DN<17>")
	)
	(segment
		(start 284.36189 -122.77217)
		(end 290.060888 -121.632472)
		(width 0.1143)
		(layer "B.Cu")
		(net "UPI_CPU1_CPU0_P0P0_DN<17>")
	)
	(segment
		(start 144.732248 -74.625454)
		(end 144.723104 -74.605388)
		(width 0.0889)
		(layer "B.Cu")
		(net "UPI_CPU1_CPU0_P0P0_DN<17>")
	)
	(segment
		(start 198.33082 -124.800868)
		(end 201.665078 -124.361956)
		(width 0.1143)
		(layer "B.Cu")
		(net "UPI_CPU1_CPU0_P0P0_DN<17>")
	)
	(segment
		(start 160.9471 -113.827306)
		(end 161.0868 -113.720372)
		(width 0.1143)
		(layer "B.Cu")
		(net "UPI_CPU1_CPU0_P0P0_DN<17>")
	)
	(segment
		(start 141.590522 -71.753984)
		(end 141.104874 -71.753984)
		(width 0.0889)
		(layer "B.Cu")
		(net "UPI_CPU1_CPU0_P0P0_DN<17>")
	)
	(segment
		(start 328.991976 -90.074496)
		(end 327.646538 -86.711028)
		(width 0.1143)
		(layer "B.Cu")
		(net "UPI_CPU1_CPU0_P0P0_DN<17>")
	)
	(segment
		(start 146.76374 -94.412308)
		(end 146.617182 -94.510098)
		(width 0.1143)
		(layer "B.Cu")
		(net "UPI_CPU1_CPU0_P0P0_DN<17>")
	)
	(segment
		(start 303.05375 -61.703204)
		(end 302.964342 -61.679074)
		(width 0.0889)
		(layer "B.Cu")
		(net "UPI_CPU1_CPU0_P0P0_DN<17>")
	)
	(segment
		(start 305.261772 -60.952888)
		(end 305.2318 -60.952888)
		(width 0.0889)
		(layer "B.Cu")
		(net "UPI_CPU1_CPU0_P0P0_DN<17>")
	)
	(segment
		(start 146.765772 -93.767656)
		(end 146.715988 -94.016576)
		(width 0.1143)
		(layer "B.Cu")
		(net "UPI_CPU1_CPU0_P0P0_DN<17>")
	)
	(segment
		(start 147.161504 -91.78925)
		(end 147.259294 -91.935808)
		(width 0.1143)
		(layer "B.Cu")
		(net "UPI_CPU1_CPU0_P0P0_DN<17>")
	)
	(segment
		(start 146.171412 -96.737424)
		(end 145.844768 -98.370644)
		(width 0.1143)
		(layer "B.Cu")
		(net "UPI_CPU1_CPU0_P0P0_DN<17>")
	)
	(segment
		(start 141.685518 -71.658988)
		(end 141.590522 -71.753984)
		(width 0.0889)
		(layer "B.Cu")
		(net "UPI_CPU1_CPU0_P0P0_DN<17>")
	)
	(segment
		(start 146.468592 -95.25254)
		(end 146.418808 -95.50146)
		(width 0.1143)
		(layer "B.Cu")
		(net "UPI_CPU1_CPU0_P0P0_DN<17>")
	)
	(segment
		(start 309.788814 -60.7441)
		(end 309.08498 -61.447934)
		(width 0.0889)
		(layer "B.Cu")
		(net "UPI_CPU1_CPU0_P0P0_DN<17>")
	)
	(segment
		(start 146.31797 -96.639634)
		(end 146.171412 -96.737424)
		(width 0.1143)
		(layer "B.Cu")
		(net "UPI_CPU1_CPU0_P0P0_DN<17>")
	)
	(segment
		(start 192.4812 -124.502926)
		(end 192.62725 -124.551948)
		(width 0.1143)
		(layer "B.Cu")
		(net "UPI_CPU1_CPU0_P0P0_DN<17>")
	)
	(segment
		(start 299.581824 -121.758964)
		(end 309.684928 -119.73306)
		(width 0.1143)
		(layer "B.Cu")
		(net "UPI_CPU1_CPU0_P0P0_DN<17>")
	)
	(segment
		(start 182.246016 -121.060718)
		(end 192.4812 -124.502926)
		(width 0.1143)
		(layer "B.Cu")
		(net "UPI_CPU1_CPU0_P0P0_DN<17>")
	)
	(segment
		(start 142.623794 -71.783194)
		(end 142.32382 -71.658988)
		(width 0.0889)
		(layer "B.Cu")
		(net "UPI_CPU1_CPU0_P0P0_DN<17>")
	)
	(segment
		(start 160.19653 -113.726976)
		(end 160.336484 -113.620042)
		(width 0.1143)
		(layer "B.Cu")
		(net "UPI_CPU1_CPU0_P0P0_DN<17>")
	)
	(segment
		(start 146.864578 -93.274134)
		(end 146.962114 -93.420692)
		(width 0.1143)
		(layer "B.Cu")
		(net "UPI_CPU1_CPU0_P0P0_DN<17>")
	)
	(segment
		(start 208.291684 -124.795534)
		(end 226.74326 -121.089674)
		(width 0.1143)
		(layer "B.Cu")
		(net "UPI_CPU1_CPU0_P0P0_DN<17>")
	)
	(segment
		(start 147.259294 -91.935808)
		(end 147.20951 -92.184982)
		(width 0.1143)
		(layer "B.Cu")
		(net "UPI_CPU1_CPU0_P0P0_DN<17>")
	)
	(segment
		(start 161.445702 -113.894108)
		(end 162.627818 -114.051842)
		(width 0.1143)
		(layer "B.Cu")
		(net "UPI_CPU1_CPU0_P0P0_DN<17>")
	)
	(segment
		(start 146.46656 -95.897446)
		(end 146.320002 -95.994982)
		(width 0.1143)
		(layer "B.Cu")
		(net "UPI_CPU1_CPU0_P0P0_DN<17>")
	)
	(segment
		(start 146.617182 -94.510098)
		(end 146.567398 -94.759018)
		(width 0.1143)
		(layer "B.Cu")
		(net "UPI_CPU1_CPU0_P0P0_DN<17>")
	)
	(segment
		(start 318.895476 -115.065556)
		(end 330.737972 -103.90886)
		(width 0.1143)
		(layer "B.Cu")
		(net "UPI_CPU1_CPU0_P0P0_DN<17>")
	)
	(arc
		(start 306.083716 -61.447934)
		(mid 305.800499 -61.363653)
		(end 305.593496 -61.152786)
		(width 0.0889)
		(layer "B.Cu")
		(net "UPI_CPU1_CPU0_P0P0_DN<17>")
	)
	(arc
		(start 307.346858 -61.149992)
		(mid 307.255914 -61.032649)
		(end 307.130704 -60.952888)
		(width 0.0889)
		(layer "B.Cu")
		(net "UPI_CPU1_CPU0_P0P0_DN<17>")
	)
	(arc
		(start 306.94884 -60.952888)
		(mid 306.757198 -61.010054)
		(end 306.617116 -61.152786)
		(width 0.0889)
		(layer "B.Cu")
		(net "UPI_CPU1_CPU0_P0P0_DN<17>")
	)
	(arc
		(start 306.617116 -61.152786)
		(mid 306.410112 -61.36365)
		(end 306.126896 -61.447934)
		(width 0.0889)
		(layer "B.Cu")
		(net "UPI_CPU1_CPU0_P0P0_DN<17>")
	)
	(arc
		(start 305.593496 -61.152786)
		(mid 305.453417 -61.01005)
		(end 305.261772 -60.952888)
		(width 0.0889)
		(layer "B.Cu")
		(net "UPI_CPU1_CPU0_P0P0_DN<17>")
	)
	(arc
		(start 303.511966 -61.943488)
		(mid 303.255144 -61.876187)
		(end 303.05375 -61.703204)
		(width 0.0889)
		(layer "B.Cu")
		(net "UPI_CPU1_CPU0_P0P0_DN<17>")
	)
	(arc
		(start 304.37709 -61.447934)
		(mid 304.18324 -61.504284)
		(end 304.041556 -61.648086)
		(width 0.0889)
		(layer "B.Cu")
		(net "UPI_CPU1_CPU0_P0P0_DN<17>")
	)
	(arc
		(start 304.900076 -61.152786)
		(mid 304.693072 -61.36365)
		(end 304.409856 -61.447934)
		(width 0.0889)
		(layer "B.Cu")
		(net "UPI_CPU1_CPU0_P0P0_DN<17>")
	)
	(arc
		(start 305.2318 -60.952888)
		(mid 305.040158 -61.010054)
		(end 304.900076 -61.152786)
		(width 0.0889)
		(layer "B.Cu")
		(net "UPI_CPU1_CPU0_P0P0_DN<17>")
	)
	(arc
		(start 304.041556 -61.648086)
		(mid 303.832948 -61.860018)
		(end 303.547526 -61.943488)
		(width 0.0889)
		(layer "B.Cu")
		(net "UPI_CPU1_CPU0_P0P0_DN<17>")
	)
	(arc
		(start 307.69687 -61.447934)
		(mid 307.493517 -61.332228)
		(end 307.347112 -61.149738)
		(width 0.0889)
		(layer "B.Cu")
		(net "UPI_CPU1_CPU0_P0P0_DN<17>")
	)
	(segment
		(start 140.533374 -70.763384)
		(end 141.104874 -70.763384)
		(width 0.1143)
		(layer "F.Cu")
		(net "UPI_CPU1_CPU0_P0P0_DN<16>")
	)
	(segment
		(start 303.816766 -62.838584)
		(end 304.388266 -62.838584)
		(width 0.1143)
		(layer "F.Cu")
		(net "UPI_CPU1_CPU0_P0P0_DN<16>")
	)
	(via
		(at 304.388266 -62.838584)
		(size 0.508)
		(drill 0.254)
		(layers "F.Cu" "B.Cu")
		(net "UPI_CPU1_CPU0_P0P0_DN<16>")
	)
	(via
		(at 141.104874 -70.763384)
		(size 0.508)
		(drill 0.254)
		(layers "F.Cu" "B.Cu")
		(net "UPI_CPU1_CPU0_P0P0_DN<16>")
	)
	(via
		(at 148.381974 -91.492832)
		(size 0.508)
		(drill 0.254)
		(layers "F.Cu" "B.Cu")
		(net "UPI_CPU1_CPU0_P0P0_DN<16>")
	)
	(segment
		(start 298.730162 -120.582436)
		(end 299.154088 -120.667272)
		(width 0.1143)
		(layer "B.Cu")
		(net "UPI_CPU1_CPU0_P0P0_DN<16>")
	)
	(segment
		(start 284.304232 -121.793508)
		(end 289.656012 -120.723152)
		(width 0.1143)
		(layer "B.Cu")
		(net "UPI_CPU1_CPU0_P0P0_DN<16>")
	)
	(segment
		(start 307.665374 -62.483238)
		(end 307.620924 -62.438788)
		(width 0.0889)
		(layer "B.Cu")
		(net "UPI_CPU1_CPU0_P0P0_DN<16>")
	)
	(segment
		(start 310.217312 -62.438788)
		(end 309.043324 -62.438788)
		(width 0.0889)
		(layer "B.Cu")
		(net "UPI_CPU1_CPU0_P0P0_DN<16>")
	)
	(segment
		(start 308.198774 -62.483238)
		(end 308.154324 -62.438788)
		(width 0.0889)
		(layer "B.Cu")
		(net "UPI_CPU1_CPU0_P0P0_DN<16>")
	)
	(segment
		(start 156.6926 -111.194088)
		(end 160.467548 -112.633252)
		(width 0.1143)
		(layer "B.Cu")
		(net "UPI_CPU1_CPU0_P0P0_DN<16>")
	)
	(segment
		(start 299.681646 -120.432068)
		(end 299.906182 -120.38711)
		(width 0.1143)
		(layer "B.Cu")
		(net "UPI_CPU1_CPU0_P0P0_DN<16>")
	)
	(segment
		(start 328.212958 -91.118944)
		(end 328.1426 -90.942922)
		(width 0.1143)
		(layer "B.Cu")
		(net "UPI_CPU1_CPU0_P0P0_DN<16>")
	)
	(segment
		(start 308.465474 -62.483238)
		(end 308.465474 -62.483492)
		(width 0.0889)
		(layer "B.Cu")
		(net "UPI_CPU1_CPU0_P0P0_DN<16>")
	)
	(segment
		(start 326.31253 -78.373478)
		(end 320.769488 -68.4276)
		(width 0.1143)
		(layer "B.Cu")
		(net "UPI_CPU1_CPU0_P0P0_DN<16>")
	)
	(segment
		(start 147.574762 -95.527114)
		(end 147.67433 -95.67672)
		(width 0.1143)
		(layer "B.Cu")
		(net "UPI_CPU1_CPU0_P0P0_DN<16>")
	)
	(segment
		(start 148.038312 -93.210634)
		(end 147.993608 -93.434662)
		(width 0.1143)
		(layer "B.Cu")
		(net "UPI_CPU1_CPU0_P0P0_DN<16>")
	)
	(segment
		(start 313.915044 -62.694058)
		(end 312.018426 -61.909198)
		(width 0.1143)
		(layer "B.Cu")
		(net "UPI_CPU1_CPU0_P0P0_DN<16>")
	)
	(segment
		(start 263.069578 -119.636286)
		(end 284.304232 -121.793508)
		(width 0.1143)
		(layer "B.Cu")
		(net "UPI_CPU1_CPU0_P0P0_DN<16>")
	)
	(segment
		(start 147.619466 -95.303086)
		(end 147.574762 -95.527114)
		(width 0.1143)
		(layer "B.Cu")
		(net "UPI_CPU1_CPU0_P0P0_DN<16>")
	)
	(segment
		(start 147.759166 -94.605602)
		(end 147.714462 -94.82963)
		(width 0.1143)
		(layer "B.Cu")
		(net "UPI_CPU1_CPU0_P0P0_DN<16>")
	)
	(segment
		(start 147.769072 -95.203518)
		(end 147.619466 -95.303086)
		(width 0.1143)
		(layer "B.Cu")
		(net "UPI_CPU1_CPU0_P0P0_DN<16>")
	)
	(segment
		(start 328.1426 -90.942922)
		(end 328.137266 -90.929206)
		(width 0.1143)
		(layer "B.Cu")
		(net "UPI_CPU1_CPU0_P0P0_DN<16>")
	)
	(segment
		(start 298.630594 -120.43283)
		(end 298.730162 -120.582436)
		(width 0.1143)
		(layer "B.Cu")
		(net "UPI_CPU1_CPU0_P0P0_DN<16>")
	)
	(segment
		(start 308.509924 -62.438788)
		(end 308.465474 -62.483238)
		(width 0.0889)
		(layer "B.Cu")
		(net "UPI_CPU1_CPU0_P0P0_DN<16>")
	)
	(segment
		(start 147.854162 -94.132146)
		(end 147.95373 -94.281498)
		(width 0.1143)
		(layer "B.Cu")
		(net "UPI_CPU1_CPU0_P0P0_DN<16>")
	)
	(segment
		(start 308.776624 -62.527942)
		(end 308.734968 -62.486032)
		(width 0.0889)
		(layer "B.Cu")
		(net "UPI_CPU1_CPU0_P0P0_DN<16>")
	)
	(segment
		(start 147.908772 -94.506034)
		(end 147.759166 -94.605602)
		(width 0.1143)
		(layer "B.Cu")
		(net "UPI_CPU1_CPU0_P0P0_DN<16>")
	)
	(segment
		(start 140.790676 -71.011288)
		(end 140.811758 -70.932548)
		(width 0.0889)
		(layer "B.Cu")
		(net "UPI_CPU1_CPU0_P0P0_DN<16>")
	)
	(segment
		(start 147.993608 -93.434662)
		(end 148.09343 -93.584014)
		(width 0.1143)
		(layer "B.Cu")
		(net "UPI_CPU1_CPU0_P0P0_DN<16>")
	)
	(segment
		(start 308.954424 -62.527942)
		(end 308.776624 -62.527942)
		(width 0.0889)
		(layer "B.Cu")
		(net "UPI_CPU1_CPU0_P0P0_DN<16>")
	)
	(segment
		(start 145.247614 -73.403206)
		(end 145.23212 -73.387712)
		(width 0.0889)
		(layer "B.Cu")
		(net "UPI_CPU1_CPU0_P0P0_DN<16>")
	)
	(segment
		(start 163.361624 -113.067084)
		(end 163.624514 -113.241582)
		(width 0.1143)
		(layer "B.Cu")
		(net "UPI_CPU1_CPU0_P0P0_DN<16>")
	)
	(segment
		(start 307.932074 -62.483238)
		(end 307.932074 -62.483492)
		(width 0.0889)
		(layer "B.Cu")
		(net "UPI_CPU1_CPU0_P0P0_DN<16>")
	)
	(segment
		(start 312.018426 -61.909198)
		(end 310.98236 -61.909198)
		(width 0.1143)
		(layer "B.Cu")
		(net "UPI_CPU1_CPU0_P0P0_DN<16>")
	)
	(segment
		(start 299.906182 -120.38711)
		(end 300.055534 -120.486932)
		(width 0.1143)
		(layer "B.Cu")
		(net "UPI_CPU1_CPU0_P0P0_DN<16>")
	)
	(segment
		(start 147.310602 -96.845628)
		(end 146.973798 -98.529648)
		(width 0.1143)
		(layer "B.Cu")
		(net "UPI_CPU1_CPU0_P0P0_DN<16>")
	)
	(segment
		(start 148.133054 -92.737178)
		(end 148.232876 -92.88653)
		(width 0.1143)
		(layer "B.Cu")
		(net "UPI_CPU1_CPU0_P0P0_DN<16>")
	)
	(segment
		(start 308.998874 -62.483238)
		(end 308.998874 -62.483492)
		(width 0.0889)
		(layer "B.Cu")
		(net "UPI_CPU1_CPU0_P0P0_DN<16>")
	)
	(segment
		(start 148.186648 -92.469208)
		(end 148.133054 -92.737178)
		(width 0.1143)
		(layer "B.Cu")
		(net "UPI_CPU1_CPU0_P0P0_DN<16>")
	)
	(segment
		(start 146.426174 -75.829922)
		(end 145.551398 -73.732644)
		(width 0.1143)
		(layer "B.Cu")
		(net "UPI_CPU1_CPU0_P0P0_DN<16>")
	)
	(segment
		(start 310.960262 -61.909198)
		(end 310.934862 -61.883798)
		(width 0.0889)
		(layer "B.Cu")
		(net "UPI_CPU1_CPU0_P0P0_DN<16>")
	)
	(segment
		(start 147.95373 -94.281498)
		(end 147.908772 -94.506034)
		(width 0.1143)
		(layer "B.Cu")
		(net "UPI_CPU1_CPU0_P0P0_DN<16>")
	)
	(segment
		(start 147.629626 -95.901002)
		(end 147.479766 -96.00057)
		(width 0.1143)
		(layer "B.Cu")
		(net "UPI_CPU1_CPU0_P0P0_DN<16>")
	)
	(segment
		(start 142.658592 -71.030338)
		(end 142.296642 -70.668388)
		(width 0.0889)
		(layer "B.Cu")
		(net "UPI_CPU1_CPU0_P0P0_DN<16>")
	)
	(segment
		(start 198.386446 -123.83389)
		(end 201.680572 -123.3932)
		(width 0.1143)
		(layer "B.Cu")
		(net "UPI_CPU1_CPU0_P0P0_DN<16>")
	)
	(segment
		(start 299.582078 -120.581674)
		(end 299.681646 -120.432068)
		(width 0.1143)
		(layer "B.Cu")
		(net "UPI_CPU1_CPU0_P0P0_DN<16>")
	)
	(segment
		(start 307.620924 -62.438788)
		(end 306.092352 -62.438788)
		(width 0.0889)
		(layer "B.Cu")
		(net "UPI_CPU1_CPU0_P0P0_DN<16>")
	)
	(segment
		(start 148.381974 -91.492832)
		(end 148.384768 -91.478608)
		(width 0.1143)
		(layer "B.Cu")
		(net "UPI_CPU1_CPU0_P0P0_DN<16>")
	)
	(segment
		(start 156.677106 -111.188246)
		(end 156.6926 -111.194088)
		(width 0.1143)
		(layer "B.Cu")
		(net "UPI_CPU1_CPU0_P0P0_DN<16>")
	)
	(segment
		(start 326.533256 -86.872318)
		(end 326.350376 -79.8322)
		(width 0.1143)
		(layer "B.Cu")
		(net "UPI_CPU1_CPU0_P0P0_DN<16>")
	)
	(segment
		(start 319.690496 -66.491358)
		(end 313.915044 -62.694058)
		(width 0.1143)
		(layer "B.Cu")
		(net "UPI_CPU1_CPU0_P0P0_DN<16>")
	)
	(segment
		(start 147.81403 -94.978982)
		(end 147.769072 -95.203518)
		(width 0.1143)
		(layer "B.Cu")
		(net "UPI_CPU1_CPU0_P0P0_DN<16>")
	)
	(segment
		(start 148.380958 -92.145104)
		(end 148.336254 -92.369386)
		(width 0.1143)
		(layer "B.Cu")
		(net "UPI_CPU1_CPU0_P0P0_DN<16>")
	)
	(segment
		(start 154.349958 -109.611922)
		(end 156.677106 -111.188246)
		(width 0.1143)
		(layer "B.Cu")
		(net "UPI_CPU1_CPU0_P0P0_DN<16>")
	)
	(segment
		(start 297.951906 -120.42648)
		(end 298.256706 -120.48744)
		(width 0.1143)
		(layer "B.Cu")
		(net "UPI_CPU1_CPU0_P0P0_DN<16>")
	)
	(segment
		(start 310.772302 -61.883798)
		(end 310.217312 -62.438788)
		(width 0.0889)
		(layer "B.Cu")
		(net "UPI_CPU1_CPU0_P0P0_DN<16>")
	)
	(segment
		(start 163.624514 -113.241582)
		(end 164.095176 -113.676176)
		(width 0.1143)
		(layer "B.Cu")
		(net "UPI_CPU1_CPU0_P0P0_DN<16>")
	)
	(segment
		(start 148.384768 -91.478608)
		(end 148.96973 -88.552274)
		(width 0.1143)
		(layer "B.Cu")
		(net "UPI_CPU1_CPU0_P0P0_DN<16>")
	)
	(segment
		(start 226.66198 -120.116854)
		(end 249.388884 -121.256298)
		(width 0.1143)
		(layer "B.Cu")
		(net "UPI_CPU1_CPU0_P0P0_DN<16>")
	)
	(segment
		(start 308.198774 -62.483492)
		(end 308.198774 -62.483238)
		(width 0.0889)
		(layer "B.Cu")
		(net "UPI_CPU1_CPU0_P0P0_DN<16>")
	)
	(segment
		(start 163.274502 -113.009172)
		(end 163.361624 -113.067084)
		(width 0.1143)
		(layer "B.Cu")
		(net "UPI_CPU1_CPU0_P0P0_DN<16>")
	)
	(segment
		(start 148.96973 -88.552274)
		(end 146.426174 -75.829922)
		(width 0.1143)
		(layer "B.Cu")
		(net "UPI_CPU1_CPU0_P0P0_DN<16>")
	)
	(segment
		(start 182.434992 -120.103138)
		(end 192.804542 -123.590812)
		(width 0.1143)
		(layer "B.Cu")
		(net "UPI_CPU1_CPU0_P0P0_DN<16>")
	)
	(segment
		(start 141.495272 -70.953122)
		(end 141.48816 -70.966838)
		(width 0.0889)
		(layer "B.Cu")
		(net "UPI_CPU1_CPU0_P0P0_DN<16>")
	)
	(segment
		(start 307.709824 -62.527942)
		(end 307.665374 -62.483492)
		(width 0.0889)
		(layer "B.Cu")
		(net "UPI_CPU1_CPU0_P0P0_DN<16>")
	)
	(segment
		(start 308.734968 -62.486032)
		(end 308.732174 -62.483492)
		(width 0.0889)
		(layer "B.Cu")
		(net "UPI_CPU1_CPU0_P0P0_DN<16>")
	)
	(segment
		(start 308.154324 -62.438788)
		(end 307.976524 -62.438788)
		(width 0.0889)
		(layer "B.Cu")
		(net "UPI_CPU1_CPU0_P0P0_DN<16>")
	)
	(segment
		(start 147.714462 -94.82963)
		(end 147.81403 -94.978982)
		(width 0.1143)
		(layer "B.Cu")
		(net "UPI_CPU1_CPU0_P0P0_DN<16>")
	)
	(segment
		(start 165.620954 -115.494308)
		(end 171.40301 -118.832884)
		(width 0.1143)
		(layer "B.Cu")
		(net "UPI_CPU1_CPU0_P0P0_DN<16>")
	)
	(segment
		(start 304.09515 -62.669674)
		(end 304.388266 -62.838584)
		(width 0.0889)
		(layer "B.Cu")
		(net "UPI_CPU1_CPU0_P0P0_DN<16>")
	)
	(segment
		(start 148.336254 -92.369386)
		(end 148.186648 -92.469208)
		(width 0.1143)
		(layer "B.Cu")
		(net "UPI_CPU1_CPU0_P0P0_DN<16>")
	)
	(segment
		(start 309.043324 -62.438788)
		(end 308.998874 -62.483238)
		(width 0.0889)
		(layer "B.Cu")
		(net "UPI_CPU1_CPU0_P0P0_DN<16>")
	)
	(segment
		(start 318.571372 -113.900458)
		(end 329.631294 -103.481378)
		(width 0.1143)
		(layer "B.Cu")
		(net "UPI_CPU1_CPU0_P0P0_DN<16>")
	)
	(segment
		(start 142.966694 -71.1581)
		(end 142.658592 -71.030338)
		(width 0.0889)
		(layer "B.Cu")
		(net "UPI_CPU1_CPU0_P0P0_DN<16>")
	)
	(segment
		(start 148.28139 -91.995752)
		(end 148.380958 -92.145104)
		(width 0.1143)
		(layer "B.Cu")
		(net "UPI_CPU1_CPU0_P0P0_DN<16>")
	)
	(segment
		(start 310.934862 -61.883798)
		(end 310.772302 -61.883798)
		(width 0.0889)
		(layer "B.Cu")
		(net "UPI_CPU1_CPU0_P0P0_DN<16>")
	)
	(segment
		(start 308.243224 -62.527942)
		(end 308.198774 -62.483492)
		(width 0.0889)
		(layer "B.Cu")
		(net "UPI_CPU1_CPU0_P0P0_DN<16>")
	)
	(segment
		(start 145.551398 -73.732644)
		(end 145.551398 -73.706736)
		(width 0.1143)
		(layer "B.Cu")
		(net "UPI_CPU1_CPU0_P0P0_DN<16>")
	)
	(segment
		(start 148.187918 -93.111066)
		(end 148.038312 -93.210634)
		(width 0.1143)
		(layer "B.Cu")
		(net "UPI_CPU1_CPU0_P0P0_DN<16>")
	)
	(segment
		(start 326.533256 -86.872572)
		(end 326.533256 -86.872318)
		(width 0.1143)
		(layer "B.Cu")
		(net "UPI_CPU1_CPU0_P0P0_DN<16>")
	)
	(segment
		(start 171.40301 -118.832884)
		(end 173.820074 -119.562626)
		(width 0.1143)
		(layer "B.Cu")
		(net "UPI_CPU1_CPU0_P0P0_DN<16>")
	)
	(segment
		(start 298.406058 -120.387872)
		(end 298.630594 -120.43283)
		(width 0.1143)
		(layer "B.Cu")
		(net "UPI_CPU1_CPU0_P0P0_DN<16>")
	)
	(segment
		(start 148.232876 -92.88653)
		(end 148.187918 -93.111066)
		(width 0.1143)
		(layer "B.Cu")
		(net "UPI_CPU1_CPU0_P0P0_DN<16>")
	)
	(segment
		(start 307.665374 -62.483492)
		(end 307.665374 -62.483238)
		(width 0.0889)
		(layer "B.Cu")
		(net "UPI_CPU1_CPU0_P0P0_DN<16>")
	)
	(segment
		(start 326.350376 -79.8322)
		(end 326.31253 -78.373478)
		(width 0.1143)
		(layer "B.Cu")
		(net "UPI_CPU1_CPU0_P0P0_DN<16>")
	)
	(segment
		(start 298.256706 -120.48744)
		(end 298.406058 -120.387872)
		(width 0.1143)
		(layer "B.Cu")
		(net "UPI_CPU1_CPU0_P0P0_DN<16>")
	)
	(segment
		(start 304.409856 -62.438534)
		(end 304.37709 -62.438534)
		(width 0.0889)
		(layer "B.Cu")
		(net "UPI_CPU1_CPU0_P0P0_DN<16>")
	)
	(segment
		(start 293.064184 -121.404634)
		(end 297.951906 -120.42648)
		(width 0.1143)
		(layer "B.Cu")
		(net "UPI_CPU1_CPU0_P0P0_DN<16>")
	)
	(segment
		(start 208.217516 -123.818142)
		(end 226.66198 -120.116854)
		(width 0.1143)
		(layer "B.Cu")
		(net "UPI_CPU1_CPU0_P0P0_DN<16>")
	)
	(segment
		(start 289.656012 -120.723152)
		(end 291.125402 -121.01703)
		(width 0.1143)
		(layer "B.Cu")
		(net "UPI_CPU1_CPU0_P0P0_DN<16>")
	)
	(segment
		(start 300.055534 -120.486932)
		(end 309.971186 -118.502938)
		(width 0.1143)
		(layer "B.Cu")
		(net "UPI_CPU1_CPU0_P0P0_DN<16>")
	)
	(segment
		(start 305.261772 -61.943488)
		(end 305.2318 -61.943488)
		(width 0.0889)
		(layer "B.Cu")
		(net "UPI_CPU1_CPU0_P0P0_DN<16>")
	)
	(segment
		(start 148.381974 -91.492832)
		(end 148.28139 -91.995752)
		(width 0.1143)
		(layer "B.Cu")
		(net "UPI_CPU1_CPU0_P0P0_DN<16>")
	)
	(segment
		(start 145.23212 -73.387712)
		(end 145.19656 -73.387966)
		(width 0.0889)
		(layer "B.Cu")
		(net "UPI_CPU1_CPU0_P0P0_DN<16>")
	)
	(segment
		(start 329.631294 -103.481378)
		(end 329.891644 -95.31604)
		(width 0.1143)
		(layer "B.Cu")
		(net "UPI_CPU1_CPU0_P0P0_DN<16>")
	)
	(segment
		(start 145.551398 -73.706736)
		(end 145.247614 -73.403206)
		(width 0.1143)
		(layer "B.Cu")
		(net "UPI_CPU1_CPU0_P0P0_DN<16>")
	)
	(segment
		(start 141.651736 -70.79107)
		(end 141.51102 -70.93204)
		(width 0.0889)
		(layer "B.Cu")
		(net "UPI_CPU1_CPU0_P0P0_DN<16>")
	)
	(segment
		(start 310.98236 -61.909198)
		(end 310.960262 -61.909198)
		(width 0.0889)
		(layer "B.Cu")
		(net "UPI_CPU1_CPU0_P0P0_DN<16>")
	)
	(segment
		(start 308.732174 -62.483238)
		(end 308.687724 -62.438788)
		(width 0.0889)
		(layer "B.Cu")
		(net "UPI_CPU1_CPU0_P0P0_DN<16>")
	)
	(segment
		(start 147.446746 -100.894388)
		(end 148.028152 -101.9429)
		(width 0.1143)
		(layer "B.Cu")
		(net "UPI_CPU1_CPU0_P0P0_DN<16>")
	)
	(segment
		(start 147.898866 -93.908118)
		(end 147.854162 -94.132146)
		(width 0.1143)
		(layer "B.Cu")
		(net "UPI_CPU1_CPU0_P0P0_DN<16>")
	)
	(segment
		(start 140.811758 -70.932548)
		(end 141.104874 -70.763384)
		(width 0.0889)
		(layer "B.Cu")
		(net "UPI_CPU1_CPU0_P0P0_DN<16>")
	)
	(segment
		(start 147.479766 -96.00057)
		(end 147.405598 -96.372172)
		(width 0.1143)
		(layer "B.Cu")
		(net "UPI_CPU1_CPU0_P0P0_DN<16>")
	)
	(segment
		(start 328.213212 -91.119706)
		(end 328.212958 -91.118944)
		(width 0.1143)
		(layer "B.Cu")
		(net "UPI_CPU1_CPU0_P0P0_DN<16>")
	)
	(segment
		(start 299.154088 -120.667272)
		(end 299.582078 -120.581674)
		(width 0.1143)
		(layer "B.Cu")
		(net "UPI_CPU1_CPU0_P0P0_DN<16>")
	)
	(segment
		(start 147.460208 -96.74606)
		(end 147.310602 -96.845628)
		(width 0.1143)
		(layer "B.Cu")
		(net "UPI_CPU1_CPU0_P0P0_DN<16>")
	)
	(segment
		(start 307.887624 -62.527942)
		(end 307.709824 -62.527942)
		(width 0.0889)
		(layer "B.Cu")
		(net "UPI_CPU1_CPU0_P0P0_DN<16>")
	)
	(segment
		(start 164.095176 -113.676176)
		(end 165.620954 -115.494308)
		(width 0.1143)
		(layer "B.Cu")
		(net "UPI_CPU1_CPU0_P0P0_DN<16>")
	)
	(segment
		(start 249.388884 -121.256298)
		(end 263.069578 -119.636286)
		(width 0.1143)
		(layer "B.Cu")
		(net "UPI_CPU1_CPU0_P0P0_DN<16>")
	)
	(segment
		(start 192.804542 -123.590812)
		(end 198.386446 -123.83389)
		(width 0.1143)
		(layer "B.Cu")
		(net "UPI_CPU1_CPU0_P0P0_DN<16>")
	)
	(segment
		(start 148.048472 -93.80855)
		(end 147.898866 -93.908118)
		(width 0.1143)
		(layer "B.Cu")
		(net "UPI_CPU1_CPU0_P0P0_DN<16>")
	)
	(segment
		(start 147.405598 -96.372172)
		(end 147.505166 -96.521524)
		(width 0.1143)
		(layer "B.Cu")
		(net "UPI_CPU1_CPU0_P0P0_DN<16>")
	)
	(segment
		(start 147.67433 -95.67672)
		(end 147.629626 -95.901002)
		(width 0.1143)
		(layer "B.Cu")
		(net "UPI_CPU1_CPU0_P0P0_DN<16>")
	)
	(segment
		(start 309.971186 -118.502938)
		(end 318.571372 -113.900458)
		(width 0.1143)
		(layer "B.Cu")
		(net "UPI_CPU1_CPU0_P0P0_DN<16>")
	)
	(segment
		(start 308.998874 -62.483492)
		(end 308.954424 -62.527942)
		(width 0.0889)
		(layer "B.Cu")
		(net "UPI_CPU1_CPU0_P0P0_DN<16>")
	)
	(segment
		(start 308.421024 -62.527942)
		(end 308.243224 -62.527942)
		(width 0.0889)
		(layer "B.Cu")
		(net "UPI_CPU1_CPU0_P0P0_DN<16>")
	)
	(segment
		(start 308.687724 -62.438788)
		(end 308.509924 -62.438788)
		(width 0.0889)
		(layer "B.Cu")
		(net "UPI_CPU1_CPU0_P0P0_DN<16>")
	)
	(segment
		(start 328.137266 -90.929206)
		(end 326.53478 -86.923118)
		(width 0.1143)
		(layer "B.Cu")
		(net "UPI_CPU1_CPU0_P0P0_DN<16>")
	)
	(segment
		(start 308.732174 -62.483492)
		(end 308.732174 -62.483238)
		(width 0.0889)
		(layer "B.Cu")
		(net "UPI_CPU1_CPU0_P0P0_DN<16>")
	)
	(segment
		(start 329.891644 -95.31604)
		(end 328.213212 -91.119706)
		(width 0.1143)
		(layer "B.Cu")
		(net "UPI_CPU1_CPU0_P0P0_DN<16>")
	)
	(segment
		(start 201.680572 -123.3932)
		(end 208.217516 -123.818142)
		(width 0.1143)
		(layer "B.Cu")
		(net "UPI_CPU1_CPU0_P0P0_DN<16>")
	)
	(segment
		(start 142.296642 -70.668388)
		(end 141.948154 -70.668388)
		(width 0.0889)
		(layer "B.Cu")
		(net "UPI_CPU1_CPU0_P0P0_DN<16>")
	)
	(segment
		(start 308.465474 -62.483492)
		(end 308.421024 -62.527942)
		(width 0.0889)
		(layer "B.Cu")
		(net "UPI_CPU1_CPU0_P0P0_DN<16>")
	)
	(segment
		(start 148.028152 -101.9429)
		(end 154.349958 -109.611922)
		(width 0.1143)
		(layer "B.Cu")
		(net "UPI_CPU1_CPU0_P0P0_DN<16>")
	)
	(segment
		(start 145.19656 -73.387966)
		(end 142.966694 -71.1581)
		(width 0.0889)
		(layer "B.Cu")
		(net "UPI_CPU1_CPU0_P0P0_DN<16>")
	)
	(segment
		(start 326.53351 -86.877144)
		(end 326.533256 -86.872572)
		(width 0.1143)
		(layer "B.Cu")
		(net "UPI_CPU1_CPU0_P0P0_DN<16>")
	)
	(segment
		(start 304.074068 -62.590934)
		(end 304.09515 -62.669674)
		(width 0.0889)
		(layer "B.Cu")
		(net "UPI_CPU1_CPU0_P0P0_DN<16>")
	)
	(segment
		(start 148.09343 -93.584014)
		(end 148.048472 -93.80855)
		(width 0.1143)
		(layer "B.Cu")
		(net "UPI_CPU1_CPU0_P0P0_DN<16>")
	)
	(segment
		(start 147.505166 -96.521524)
		(end 147.460208 -96.74606)
		(width 0.1143)
		(layer "B.Cu")
		(net "UPI_CPU1_CPU0_P0P0_DN<16>")
	)
	(segment
		(start 146.973798 -98.529648)
		(end 147.446746 -100.894388)
		(width 0.1143)
		(layer "B.Cu")
		(net "UPI_CPU1_CPU0_P0P0_DN<16>")
	)
	(segment
		(start 291.125402 -121.01703)
		(end 293.064184 -121.404634)
		(width 0.1143)
		(layer "B.Cu")
		(net "UPI_CPU1_CPU0_P0P0_DN<16>")
	)
	(segment
		(start 320.769488 -68.4276)
		(end 319.690496 -66.491358)
		(width 0.1143)
		(layer "B.Cu")
		(net "UPI_CPU1_CPU0_P0P0_DN<16>")
	)
	(segment
		(start 173.820074 -119.562626)
		(end 182.434992 -120.103138)
		(width 0.1143)
		(layer "B.Cu")
		(net "UPI_CPU1_CPU0_P0P0_DN<16>")
	)
	(segment
		(start 141.273022 -71.163434)
		(end 141.089888 -71.163434)
		(width 0.0889)
		(layer "B.Cu")
		(net "UPI_CPU1_CPU0_P0P0_DN<16>")
	)
	(segment
		(start 326.53478 -86.923118)
		(end 326.53351 -86.877144)
		(width 0.1143)
		(layer "B.Cu")
		(net "UPI_CPU1_CPU0_P0P0_DN<16>")
	)
	(segment
		(start 160.467548 -112.633252)
		(end 163.274502 -113.009172)
		(width 0.1143)
		(layer "B.Cu")
		(net "UPI_CPU1_CPU0_P0P0_DN<16>")
	)
	(segment
		(start 307.932074 -62.483492)
		(end 307.887624 -62.527942)
		(width 0.0889)
		(layer "B.Cu")
		(net "UPI_CPU1_CPU0_P0P0_DN<16>")
	)
	(segment
		(start 307.976524 -62.438788)
		(end 307.932074 -62.483238)
		(width 0.0889)
		(layer "B.Cu")
		(net "UPI_CPU1_CPU0_P0P0_DN<16>")
	)
	(arc
		(start 141.48816 -70.966838)
		(mid 141.397585 -71.083731)
		(end 141.273022 -71.163434)
		(width 0.0889)
		(layer "B.Cu")
		(net "UPI_CPU1_CPU0_P0P0_DN<16>")
	)
	(arc
		(start 304.37709 -62.438534)
		(mid 304.208653 -62.481067)
		(end 304.074068 -62.590934)
		(width 0.0889)
		(layer "B.Cu")
		(net "UPI_CPU1_CPU0_P0P0_DN<16>")
	)
	(arc
		(start 141.089888 -71.163434)
		(mid 140.923594 -71.1202)
		(end 140.790676 -71.011288)
		(width 0.0889)
		(layer "B.Cu")
		(net "UPI_CPU1_CPU0_P0P0_DN<16>")
	)
	(arc
		(start 141.51102 -70.93204)
		(mid 141.502367 -70.941999)
		(end 141.495272 -70.953122)
		(width 0.0889)
		(layer "B.Cu")
		(net "UPI_CPU1_CPU0_P0P0_DN<16>")
	)
	(arc
		(start 304.900076 -62.143386)
		(mid 304.693072 -62.35425)
		(end 304.409856 -62.438534)
		(width 0.0889)
		(layer "B.Cu")
		(net "UPI_CPU1_CPU0_P0P0_DN<16>")
	)
	(arc
		(start 141.948154 -70.668388)
		(mid 141.787757 -70.700275)
		(end 141.651736 -70.79107)
		(width 0.0889)
		(layer "B.Cu")
		(net "UPI_CPU1_CPU0_P0P0_DN<16>")
	)
	(arc
		(start 305.2318 -61.943488)
		(mid 305.040158 -62.000654)
		(end 304.900076 -62.143386)
		(width 0.0889)
		(layer "B.Cu")
		(net "UPI_CPU1_CPU0_P0P0_DN<16>")
	)
	(arc
		(start 306.092352 -62.438788)
		(mid 305.804207 -62.356469)
		(end 305.593496 -62.143386)
		(width 0.0889)
		(layer "B.Cu")
		(net "UPI_CPU1_CPU0_P0P0_DN<16>")
	)
	(arc
		(start 305.593496 -62.143386)
		(mid 305.453417 -62.00065)
		(end 305.261772 -61.943488)
		(width 0.0889)
		(layer "B.Cu")
		(net "UPI_CPU1_CPU0_P0P0_DN<16>")
	)
	(segment
		(start 303.529746 -63.334138)
		(end 302.958246 -63.334138)
		(width 0.1143)
		(layer "F.Cu")
		(net "UPI_CPU1_CPU0_P0P0_DN<15>")
	)
	(segment
		(start 139.674854 -70.268084)
		(end 140.246354 -70.268084)
		(width 0.1143)
		(layer "F.Cu")
		(net "UPI_CPU1_CPU0_P0P0_DN<15>")
	)
	(via
		(at 148.871686 -93.32087)
		(size 0.508)
		(drill 0.254)
		(layers "F.Cu" "B.Cu")
		(net "UPI_CPU1_CPU0_P0P0_DN<15>")
	)
	(via
		(at 303.529746 -63.334138)
		(size 0.508)
		(drill 0.254)
		(layers "F.Cu" "B.Cu")
		(net "UPI_CPU1_CPU0_P0P0_DN<15>")
	)
	(via
		(at 140.246354 -70.268084)
		(size 0.508)
		(drill 0.254)
		(layers "F.Cu" "B.Cu")
		(net "UPI_CPU1_CPU0_P0P0_DN<15>")
	)
	(segment
		(start 328.93 -95.277686)
		(end 328.329798 -93.7768)
		(width 0.1143)
		(layer "B.Cu")
		(net "UPI_CPU1_CPU0_P0P0_DN<15>")
	)
	(segment
		(start 327.461118 -91.605354)
		(end 327.319132 -91.250262)
		(width 0.1143)
		(layer "B.Cu")
		(net "UPI_CPU1_CPU0_P0P0_DN<15>")
	)
	(segment
		(start 311.126632 -62.78499)
		(end 311.101232 -62.81039)
		(width 0.0889)
		(layer "B.Cu")
		(net "UPI_CPU1_CPU0_P0P0_DN<15>")
	)
	(segment
		(start 311.101232 -62.81039)
		(end 310.569864 -62.81039)
		(width 0.0889)
		(layer "B.Cu")
		(net "UPI_CPU1_CPU0_P0P0_DN<15>")
	)
	(segment
		(start 327.318878 -91.2495)
		(end 327.317354 -91.24569)
		(width 0.1143)
		(layer "B.Cu")
		(net "UPI_CPU1_CPU0_P0P0_DN<15>")
	)
	(segment
		(start 327.317354 -91.24569)
		(end 327.316592 -91.243658)
		(width 0.1143)
		(layer "B.Cu")
		(net "UPI_CPU1_CPU0_P0P0_DN<15>")
	)
	(segment
		(start 327.316338 -91.242896)
		(end 325.662036 -87.107268)
		(width 0.1143)
		(layer "B.Cu")
		(net "UPI_CPU1_CPU0_P0P0_DN<15>")
	)
	(segment
		(start 146.174968 -73.440798)
		(end 146.174968 -73.404222)
		(width 0.0889)
		(layer "B.Cu")
		(net "UPI_CPU1_CPU0_P0P0_DN<15>")
	)
	(segment
		(start 310.569864 -62.81039)
		(end 310.369712 -63.010542)
		(width 0.0889)
		(layer "B.Cu")
		(net "UPI_CPU1_CPU0_P0P0_DN<15>")
	)
	(segment
		(start 171.681394 -118.154958)
		(end 173.9646 -118.844314)
		(width 0.1143)
		(layer "B.Cu")
		(net "UPI_CPU1_CPU0_P0P0_DN<15>")
	)
	(segment
		(start 312.685938 -63.137796)
		(end 312.685684 -63.137542)
		(width 0.1143)
		(layer "B.Cu")
		(net "UPI_CPU1_CPU0_P0P0_DN<15>")
	)
	(segment
		(start 318.1985 -112.516666)
		(end 318.363346 -112.361218)
		(width 0.1143)
		(layer "B.Cu")
		(net "UPI_CPU1_CPU0_P0P0_DN<15>")
	)
	(segment
		(start 154.929078 -109.12856)
		(end 157.176978 -110.59795)
		(width 0.1143)
		(layer "B.Cu")
		(net "UPI_CPU1_CPU0_P0P0_DN<15>")
	)
	(segment
		(start 263.071864 -118.906036)
		(end 284.157674 -121.047764)
		(width 0.1143)
		(layer "B.Cu")
		(net "UPI_CPU1_CPU0_P0P0_DN<15>")
	)
	(segment
		(start 291.125402 -120.479058)
		(end 292.459664 -120.746266)
		(width 0.1143)
		(layer "B.Cu")
		(net "UPI_CPU1_CPU0_P0P0_DN<15>")
	)
	(segment
		(start 148.556218 -101.39807)
		(end 154.929078 -109.12856)
		(width 0.1143)
		(layer "B.Cu")
		(net "UPI_CPU1_CPU0_P0P0_DN<15>")
	)
	(segment
		(start 249.27687 -120.523)
		(end 263.071864 -118.906036)
		(width 0.1143)
		(layer "B.Cu")
		(net "UPI_CPU1_CPU0_P0P0_DN<15>")
	)
	(segment
		(start 307.579776 -63.010542)
		(end 307.312822 -62.743588)
		(width 0.0889)
		(layer "B.Cu")
		(net "UPI_CPU1_CPU0_P0P0_DN<15>")
	)
	(segment
		(start 327.319132 -91.250262)
		(end 327.318878 -91.2495)
		(width 0.1143)
		(layer "B.Cu")
		(net "UPI_CPU1_CPU0_P0P0_DN<15>")
	)
	(segment
		(start 292.459664 -120.746266)
		(end 298.817792 -119.473726)
		(width 0.1143)
		(layer "B.Cu")
		(net "UPI_CPU1_CPU0_P0P0_DN<15>")
	)
	(segment
		(start 303.587658 -63.730124)
		(end 303.529746 -63.672212)
		(width 0.0889)
		(layer "B.Cu")
		(net "UPI_CPU1_CPU0_P0P0_DN<15>")
	)
	(segment
		(start 303.529746 -63.672212)
		(end 303.529746 -63.334138)
		(width 0.0889)
		(layer "B.Cu")
		(net "UPI_CPU1_CPU0_P0P0_DN<15>")
	)
	(segment
		(start 318.363346 -112.361218)
		(end 319.221358 -112.141508)
		(width 0.1143)
		(layer "B.Cu")
		(net "UPI_CPU1_CPU0_P0P0_DN<15>")
	)
	(segment
		(start 312.685684 -63.137542)
		(end 312.685684 -63.137796)
		(width 0.1143)
		(layer "B.Cu")
		(net "UPI_CPU1_CPU0_P0P0_DN<15>")
	)
	(segment
		(start 147.83435 -98.50882)
		(end 148.33092 -100.99167)
		(width 0.1143)
		(layer "B.Cu")
		(net "UPI_CPU1_CPU0_P0P0_DN<15>")
	)
	(segment
		(start 327.316592 -91.243658)
		(end 327.316338 -91.242896)
		(width 0.1143)
		(layer "B.Cu")
		(net "UPI_CPU1_CPU0_P0P0_DN<15>")
	)
	(segment
		(start 143.68526 -71.041006)
		(end 143.68526 -70.91426)
		(width 0.0889)
		(layer "B.Cu")
		(net "UPI_CPU1_CPU0_P0P0_DN<15>")
	)
	(segment
		(start 325.309738 -78.348586)
		(end 319.054734 -67.125088)
		(width 0.1143)
		(layer "B.Cu")
		(net "UPI_CPU1_CPU0_P0P0_DN<15>")
	)
	(segment
		(start 164.944806 -113.358168)
		(end 166.42334 -115.119658)
		(width 0.1143)
		(layer "B.Cu")
		(net "UPI_CPU1_CPU0_P0P0_DN<15>")
	)
	(segment
		(start 325.526908 -81.915)
		(end 325.44004 -78.58252)
		(width 0.1143)
		(layer "B.Cu")
		(net "UPI_CPU1_CPU0_P0P0_DN<15>")
	)
	(segment
		(start 142.4051 -70.1675)
		(end 141.659102 -70.1675)
		(width 0.0889)
		(layer "B.Cu")
		(net "UPI_CPU1_CPU0_P0P0_DN<15>")
	)
	(segment
		(start 328.93 -97.893886)
		(end 329.007216 -95.470726)
		(width 0.1143)
		(layer "B.Cu")
		(net "UPI_CPU1_CPU0_P0P0_DN<15>")
	)
	(segment
		(start 143.68526 -70.91426)
		(end 143.4465 -70.6755)
		(width 0.0889)
		(layer "B.Cu")
		(net "UPI_CPU1_CPU0_P0P0_DN<15>")
	)
	(segment
		(start 310.369712 -63.010542)
		(end 307.579776 -63.010542)
		(width 0.0889)
		(layer "B.Cu")
		(net "UPI_CPU1_CPU0_P0P0_DN<15>")
	)
	(segment
		(start 142.795752 -70.558152)
		(end 142.4051 -70.1675)
		(width 0.0889)
		(layer "B.Cu")
		(net "UPI_CPU1_CPU0_P0P0_DN<15>")
	)
	(segment
		(start 319.054734 -67.125088)
		(end 313.513216 -63.481204)
		(width 0.1143)
		(layer "B.Cu")
		(net "UPI_CPU1_CPU0_P0P0_DN<15>")
	)
	(segment
		(start 312.685684 -63.137796)
		(end 311.835038 -62.78499)
		(width 0.1143)
		(layer "B.Cu")
		(net "UPI_CPU1_CPU0_P0P0_DN<15>")
	)
	(segment
		(start 309.760366 -117.786404)
		(end 316.345316 -114.262662)
		(width 0.1143)
		(layer "B.Cu")
		(net "UPI_CPU1_CPU0_P0P0_DN<15>")
	)
	(segment
		(start 143.4465 -70.6755)
		(end 143.078962 -70.6755)
		(width 0.0889)
		(layer "B.Cu")
		(net "UPI_CPU1_CPU0_P0P0_DN<15>")
	)
	(segment
		(start 141.659102 -70.1675)
		(end 141.624812 -70.20179)
		(width 0.0889)
		(layer "B.Cu")
		(net "UPI_CPU1_CPU0_P0P0_DN<15>")
	)
	(segment
		(start 298.817792 -119.473726)
		(end 300.070012 -119.72417)
		(width 0.1143)
		(layer "B.Cu")
		(net "UPI_CPU1_CPU0_P0P0_DN<15>")
	)
	(segment
		(start 146.556476 -73.822306)
		(end 146.174968 -73.440798)
		(width 0.1143)
		(layer "B.Cu")
		(net "UPI_CPU1_CPU0_P0P0_DN<15>")
	)
	(segment
		(start 160.802828 -111.945928)
		(end 163.361624 -112.287558)
		(width 0.1143)
		(layer "B.Cu")
		(net "UPI_CPU1_CPU0_P0P0_DN<15>")
	)
	(segment
		(start 143.078962 -70.6755)
		(end 142.795752 -70.558152)
		(width 0.0889)
		(layer "B.Cu")
		(net "UPI_CPU1_CPU0_P0P0_DN<15>")
	)
	(segment
		(start 146.174968 -73.404222)
		(end 143.963898 -71.193152)
		(width 0.0889)
		(layer "B.Cu")
		(net "UPI_CPU1_CPU0_P0P0_DN<15>")
	)
	(segment
		(start 316.345316 -114.262662)
		(end 318.1985 -112.516666)
		(width 0.1143)
		(layer "B.Cu")
		(net "UPI_CPU1_CPU0_P0P0_DN<15>")
	)
	(segment
		(start 328.1426 -93.308932)
		(end 327.461118 -91.605354)
		(width 0.1143)
		(layer "B.Cu")
		(net "UPI_CPU1_CPU0_P0P0_DN<15>")
	)
	(segment
		(start 325.662036 -87.107268)
		(end 325.526908 -81.915)
		(width 0.1143)
		(layer "B.Cu")
		(net "UPI_CPU1_CPU0_P0P0_DN<15>")
	)
	(segment
		(start 201.65314 -122.664474)
		(end 208.173828 -123.086622)
		(width 0.1143)
		(layer "B.Cu")
		(net "UPI_CPU1_CPU0_P0P0_DN<15>")
	)
	(segment
		(start 284.157674 -121.047764)
		(end 289.065208 -120.066308)
		(width 0.1143)
		(layer "B.Cu")
		(net "UPI_CPU1_CPU0_P0P0_DN<15>")
	)
	(segment
		(start 192.93967 -122.86996)
		(end 198.351902 -123.105672)
		(width 0.1143)
		(layer "B.Cu")
		(net "UPI_CPU1_CPU0_P0P0_DN<15>")
	)
	(segment
		(start 328.329798 -93.7768)
		(end 328.1426 -93.308932)
		(width 0.1143)
		(layer "B.Cu")
		(net "UPI_CPU1_CPU0_P0P0_DN<15>")
	)
	(segment
		(start 300.070012 -119.72417)
		(end 309.760366 -117.786404)
		(width 0.1143)
		(layer "B.Cu")
		(net "UPI_CPU1_CPU0_P0P0_DN<15>")
	)
	(segment
		(start 141.104874 -70.363334)
		(end 141.083284 -70.363334)
		(width 0.0889)
		(layer "B.Cu")
		(net "UPI_CPU1_CPU0_P0P0_DN<15>")
	)
	(segment
		(start 143.837406 -71.193152)
		(end 143.68526 -71.041006)
		(width 0.0889)
		(layer "B.Cu")
		(net "UPI_CPU1_CPU0_P0P0_DN<15>")
	)
	(segment
		(start 143.963898 -71.193152)
		(end 143.837406 -71.193152)
		(width 0.0889)
		(layer "B.Cu")
		(net "UPI_CPU1_CPU0_P0P0_DN<15>")
	)
	(segment
		(start 149.663404 -89.362026)
		(end 146.556476 -73.822306)
		(width 0.1143)
		(layer "B.Cu")
		(net "UPI_CPU1_CPU0_P0P0_DN<15>")
	)
	(segment
		(start 182.575708 -119.384318)
		(end 192.93967 -122.86996)
		(width 0.1143)
		(layer "B.Cu")
		(net "UPI_CPU1_CPU0_P0P0_DN<15>")
	)
	(segment
		(start 325.44004 -78.58252)
		(end 325.309738 -78.348586)
		(width 0.1143)
		(layer "B.Cu")
		(net "UPI_CPU1_CPU0_P0P0_DN<15>")
	)
	(segment
		(start 289.065208 -120.066308)
		(end 291.125402 -120.479058)
		(width 0.1143)
		(layer "B.Cu")
		(net "UPI_CPU1_CPU0_P0P0_DN<15>")
	)
	(segment
		(start 140.264388 -69.868288)
		(end 140.073888 -69.868288)
		(width 0.0889)
		(layer "B.Cu")
		(net "UPI_CPU1_CPU0_P0P0_DN<15>")
	)
	(segment
		(start 163.644072 -112.325404)
		(end 164.944806 -113.358168)
		(width 0.1143)
		(layer "B.Cu")
		(net "UPI_CPU1_CPU0_P0P0_DN<15>")
	)
	(segment
		(start 313.513216 -63.481204)
		(end 312.685938 -63.137796)
		(width 0.1143)
		(layer "B.Cu")
		(net "UPI_CPU1_CPU0_P0P0_DN<15>")
	)
	(segment
		(start 311.835038 -62.78499)
		(end 311.14873 -62.78499)
		(width 0.1143)
		(layer "B.Cu")
		(net "UPI_CPU1_CPU0_P0P0_DN<15>")
	)
	(segment
		(start 148.33092 -100.99167)
		(end 148.556218 -101.39807)
		(width 0.1143)
		(layer "B.Cu")
		(net "UPI_CPU1_CPU0_P0P0_DN<15>")
	)
	(segment
		(start 198.351902 -123.105672)
		(end 201.65314 -122.664474)
		(width 0.1143)
		(layer "B.Cu")
		(net "UPI_CPU1_CPU0_P0P0_DN<15>")
	)
	(segment
		(start 328.76236 -103.15448)
		(end 328.93 -97.893886)
		(width 0.1143)
		(layer "B.Cu")
		(net "UPI_CPU1_CPU0_P0P0_DN<15>")
	)
	(segment
		(start 157.176978 -110.59795)
		(end 160.802828 -111.945928)
		(width 0.1143)
		(layer "B.Cu")
		(net "UPI_CPU1_CPU0_P0P0_DN<15>")
	)
	(segment
		(start 329.007216 -95.470726)
		(end 328.93 -95.277686)
		(width 0.1143)
		(layer "B.Cu")
		(net "UPI_CPU1_CPU0_P0P0_DN<15>")
	)
	(segment
		(start 208.173828 -123.086622)
		(end 226.600004 -119.386096)
		(width 0.1143)
		(layer "B.Cu")
		(net "UPI_CPU1_CPU0_P0P0_DN<15>")
	)
	(segment
		(start 140.125196 -70.268084)
		(end 140.246354 -70.268084)
		(width 0.0889)
		(layer "B.Cu")
		(net "UPI_CPU1_CPU0_P0P0_DN<15>")
	)
	(segment
		(start 307.312822 -62.743588)
		(end 305.228498 -62.743588)
		(width 0.0889)
		(layer "B.Cu")
		(net "UPI_CPU1_CPU0_P0P0_DN<15>")
	)
	(segment
		(start 148.871686 -93.32087)
		(end 149.663404 -89.362026)
		(width 0.1143)
		(layer "B.Cu")
		(net "UPI_CPU1_CPU0_P0P0_DN<15>")
	)
	(segment
		(start 311.14873 -62.78499)
		(end 311.126632 -62.78499)
		(width 0.0889)
		(layer "B.Cu")
		(net "UPI_CPU1_CPU0_P0P0_DN<15>")
	)
	(segment
		(start 166.42334 -115.119658)
		(end 171.681394 -118.154958)
		(width 0.1143)
		(layer "B.Cu")
		(net "UPI_CPU1_CPU0_P0P0_DN<15>")
	)
	(segment
		(start 304.403252 -63.238634)
		(end 304.370486 -63.238634)
		(width 0.0889)
		(layer "B.Cu")
		(net "UPI_CPU1_CPU0_P0P0_DN<15>")
	)
	(segment
		(start 226.600004 -119.386096)
		(end 249.27687 -120.523)
		(width 0.1143)
		(layer "B.Cu")
		(net "UPI_CPU1_CPU0_P0P0_DN<15>")
	)
	(segment
		(start 163.361624 -112.287558)
		(end 163.644072 -112.325404)
		(width 0.1143)
		(layer "B.Cu")
		(net "UPI_CPU1_CPU0_P0P0_DN<15>")
	)
	(segment
		(start 148.871686 -93.32087)
		(end 147.83435 -98.50882)
		(width 0.1143)
		(layer "B.Cu")
		(net "UPI_CPU1_CPU0_P0P0_DN<15>")
	)
	(segment
		(start 319.221358 -112.141508)
		(end 328.76236 -103.15448)
		(width 0.1143)
		(layer "B.Cu")
		(net "UPI_CPU1_CPU0_P0P0_DN<15>")
	)
	(segment
		(start 173.9646 -118.844314)
		(end 182.575708 -119.384318)
		(width 0.1143)
		(layer "B.Cu")
		(net "UPI_CPU1_CPU0_P0P0_DN<15>")
	)
	(arc
		(start 140.593064 -70.068186)
		(mid 140.45432 -69.926153)
		(end 140.264388 -69.868288)
		(width 0.0889)
		(layer "B.Cu")
		(net "UPI_CPU1_CPU0_P0P0_DN<15>")
	)
	(arc
		(start 141.624812 -70.20179)
		(mid 141.616209 -70.207681)
		(end 141.60754 -70.213474)
		(width 0.0889)
		(layer "B.Cu")
		(net "UPI_CPU1_CPU0_P0P0_DN<15>")
	)
	(arc
		(start 139.899644 -70.042532)
		(mid 139.965707 -70.202021)
		(end 140.125196 -70.268084)
		(width 0.0889)
		(layer "B.Cu")
		(net "UPI_CPU1_CPU0_P0P0_DN<15>")
	)
	(arc
		(start 304.734976 -63.038736)
		(mid 304.594897 -63.181472)
		(end 304.403252 -63.238634)
		(width 0.0889)
		(layer "B.Cu")
		(net "UPI_CPU1_CPU0_P0P0_DN<15>")
	)
	(arc
		(start 140.073888 -69.868288)
		(mid 139.950679 -69.919323)
		(end 139.899644 -70.042532)
		(width 0.0889)
		(layer "B.Cu")
		(net "UPI_CPU1_CPU0_P0P0_DN<15>")
	)
	(arc
		(start 303.876456 -63.534036)
		(mid 303.754565 -63.665232)
		(end 303.587658 -63.730124)
		(width 0.0889)
		(layer "B.Cu")
		(net "UPI_CPU1_CPU0_P0P0_DN<15>")
	)
	(arc
		(start 305.228498 -62.743588)
		(mid 304.943451 -62.827116)
		(end 304.734976 -63.038736)
		(width 0.0889)
		(layer "B.Cu")
		(net "UPI_CPU1_CPU0_P0P0_DN<15>")
	)
	(arc
		(start 141.60754 -70.213474)
		(mid 141.367141 -70.325066)
		(end 141.104874 -70.363334)
		(width 0.0889)
		(layer "B.Cu")
		(net "UPI_CPU1_CPU0_P0P0_DN<15>")
	)
	(arc
		(start 304.370486 -63.238634)
		(mid 304.085062 -63.322101)
		(end 303.876456 -63.534036)
		(width 0.0889)
		(layer "B.Cu")
		(net "UPI_CPU1_CPU0_P0P0_DN<15>")
	)
	(arc
		(start 141.083284 -70.363334)
		(mid 140.800067 -70.279053)
		(end 140.593064 -70.068186)
		(width 0.0889)
		(layer "B.Cu")
		(net "UPI_CPU1_CPU0_P0P0_DN<15>")
	)
	(segment
		(start 139.674854 -68.287138)
		(end 140.246354 -68.287138)
		(width 0.1143)
		(layer "F.Cu")
		(net "UPI_CPU1_CPU0_P0P0_DN<14>")
	)
	(segment
		(start 301.241206 -64.324738)
		(end 301.812706 -64.324738)
		(width 0.1143)
		(layer "F.Cu")
		(net "UPI_CPU1_CPU0_P0P0_DN<14>")
	)
	(via
		(at 301.812706 -64.324738)
		(size 0.508)
		(drill 0.254)
		(layers "F.Cu" "B.Cu")
		(net "UPI_CPU1_CPU0_P0P0_DN<14>")
	)
	(via
		(at 140.246354 -68.287138)
		(size 0.508)
		(drill 0.254)
		(layers "F.Cu" "B.Cu")
		(net "UPI_CPU1_CPU0_P0P0_DN<14>")
	)
	(segment
		(start 158.437326 -109.772704)
		(end 162.85083 -110.236508)
		(width 0.1143)
		(layer "B.Cu")
		(net "UPI_CPU1_CPU0_P0P0_DN<14>")
	)
	(segment
		(start 263.062466 -117.68963)
		(end 284.001972 -119.81688)
		(width 0.1143)
		(layer "B.Cu")
		(net "UPI_CPU1_CPU0_P0P0_DN<14>")
	)
	(segment
		(start 312.989468 -64.766952)
		(end 311.479946 -64.142874)
		(width 0.1143)
		(layer "B.Cu")
		(net "UPI_CPU1_CPU0_P0P0_DN<14>")
	)
	(segment
		(start 207.99044 -121.864374)
		(end 226.412298 -118.166134)
		(width 0.1143)
		(layer "B.Cu")
		(net "UPI_CPU1_CPU0_P0P0_DN<14>")
	)
	(segment
		(start 318.54267 -110.969806)
		(end 327.41743 -102.606856)
		(width 0.1143)
		(layer "B.Cu")
		(net "UPI_CPU1_CPU0_P0P0_DN<14>")
	)
	(segment
		(start 149.59457 -100.684076)
		(end 155.872688 -108.300266)
		(width 0.1143)
		(layer "B.Cu")
		(net "UPI_CPU1_CPU0_P0P0_DN<14>")
	)
	(segment
		(start 162.85083 -110.236508)
		(end 166.4589 -112.859566)
		(width 0.1143)
		(layer "B.Cu")
		(net "UPI_CPU1_CPU0_P0P0_DN<14>")
	)
	(segment
		(start 149.824948 -96.086168)
		(end 149.675088 -96.185736)
		(width 0.1143)
		(layer "B.Cu")
		(net "UPI_CPU1_CPU0_P0P0_DN<14>")
	)
	(segment
		(start 305.264566 -63.924688)
		(end 305.2318 -63.924688)
		(width 0.0889)
		(layer "B.Cu")
		(net "UPI_CPU1_CPU0_P0P0_DN<14>")
	)
	(segment
		(start 284.001972 -119.81688)
		(end 288.244026 -118.96852)
		(width 0.1143)
		(layer "B.Cu")
		(net "UPI_CPU1_CPU0_P0P0_DN<14>")
	)
	(segment
		(start 324.30974 -87.392764)
		(end 324.1675 -81.915)
		(width 0.1143)
		(layer "B.Cu")
		(net "UPI_CPU1_CPU0_P0P0_DN<14>")
	)
	(segment
		(start 318.046862 -68.092574)
		(end 312.989468 -64.766952)
		(width 0.1143)
		(layer "B.Cu")
		(net "UPI_CPU1_CPU0_P0P0_DN<14>")
	)
	(segment
		(start 307.7718 -64.4398)
		(end 307.296312 -64.915288)
		(width 0.0889)
		(layer "B.Cu")
		(net "UPI_CPU1_CPU0_P0P0_DN<14>")
	)
	(segment
		(start 198.323962 -121.889774)
		(end 201.61504 -121.448322)
		(width 0.1143)
		(layer "B.Cu")
		(net "UPI_CPU1_CPU0_P0P0_DN<14>")
	)
	(segment
		(start 150.104094 -94.6912)
		(end 149.954488 -94.790768)
		(width 0.1143)
		(layer "B.Cu")
		(net "UPI_CPU1_CPU0_P0P0_DN<14>")
	)
	(segment
		(start 140.246354 -68.625212)
		(end 140.311378 -68.690236)
		(width 0.0889)
		(layer "B.Cu")
		(net "UPI_CPU1_CPU0_P0P0_DN<14>")
	)
	(segment
		(start 149.184868 -98.636836)
		(end 149.389846 -99.660456)
		(width 0.1143)
		(layer "B.Cu")
		(net "UPI_CPU1_CPU0_P0P0_DN<14>")
	)
	(segment
		(start 167.897556 -114.574828)
		(end 172.151294 -117.030754)
		(width 0.1143)
		(layer "B.Cu")
		(net "UPI_CPU1_CPU0_P0P0_DN<14>")
	)
	(segment
		(start 324.090284 -78.934818)
		(end 318.046862 -68.092574)
		(width 0.1143)
		(layer "B.Cu")
		(net "UPI_CPU1_CPU0_P0P0_DN<14>")
	)
	(segment
		(start 315.611764 -113.265966)
		(end 317.848234 -111.158528)
		(width 0.1143)
		(layer "B.Cu")
		(net "UPI_CPU1_CPU0_P0P0_DN<14>")
	)
	(segment
		(start 310.6674 -64.117474)
		(end 308.754526 -64.117474)
		(width 0.0889)
		(layer "B.Cu")
		(net "UPI_CPU1_CPU0_P0P0_DN<14>")
	)
	(segment
		(start 299.764196 -118.54053)
		(end 309.332122 -116.626894)
		(width 0.1143)
		(layer "B.Cu")
		(net "UPI_CPU1_CPU0_P0P0_DN<14>")
	)
	(segment
		(start 140.246354 -68.287138)
		(end 140.246354 -68.625212)
		(width 0.0889)
		(layer "B.Cu")
		(net "UPI_CPU1_CPU0_P0P0_DN<14>")
	)
	(segment
		(start 150.233634 -93.3958)
		(end 150.18893 -93.619828)
		(width 0.1143)
		(layer "B.Cu")
		(net "UPI_CPU1_CPU0_P0P0_DN<14>")
	)
	(segment
		(start 317.848234 -111.158528)
		(end 318.54267 -110.969806)
		(width 0.1143)
		(layer "B.Cu")
		(net "UPI_CPU1_CPU0_P0P0_DN<14>")
	)
	(segment
		(start 143.563594 -69.4817)
		(end 145.811494 -71.7296)
		(width 0.0889)
		(layer "B.Cu")
		(net "UPI_CPU1_CPU0_P0P0_DN<14>")
	)
	(segment
		(start 149.62632 -96.430338)
		(end 149.725888 -96.57969)
		(width 0.1143)
		(layer "B.Cu")
		(net "UPI_CPU1_CPU0_P0P0_DN<14>")
	)
	(segment
		(start 150.243794 -93.993716)
		(end 150.094188 -94.093284)
		(width 0.1143)
		(layer "B.Cu")
		(net "UPI_CPU1_CPU0_P0P0_DN<14>")
	)
	(segment
		(start 327.637394 -95.713042)
		(end 326.413622 -92.65285)
		(width 0.1143)
		(layer "B.Cu")
		(net "UPI_CPU1_CPU0_P0P0_DN<14>")
	)
	(segment
		(start 149.964394 -95.388684)
		(end 149.814788 -95.488252)
		(width 0.1143)
		(layer "B.Cu")
		(net "UPI_CPU1_CPU0_P0P0_DN<14>")
	)
	(segment
		(start 150.009352 -95.164148)
		(end 149.964394 -95.388684)
		(width 0.1143)
		(layer "B.Cu")
		(net "UPI_CPU1_CPU0_P0P0_DN<14>")
	)
	(segment
		(start 288.473388 -118.922546)
		(end 291.125402 -119.452898)
		(width 0.1143)
		(layer "B.Cu")
		(net "UPI_CPU1_CPU0_P0P0_DN<14>")
	)
	(segment
		(start 324.106286 -79.552038)
		(end 324.090284 -78.934818)
		(width 0.1143)
		(layer "B.Cu")
		(net "UPI_CPU1_CPU0_P0P0_DN<14>")
	)
	(segment
		(start 150.049484 -94.317312)
		(end 150.149052 -94.466664)
		(width 0.1143)
		(layer "B.Cu")
		(net "UPI_CPU1_CPU0_P0P0_DN<14>")
	)
	(segment
		(start 149.954488 -94.790768)
		(end 149.909784 -95.014796)
		(width 0.1143)
		(layer "B.Cu")
		(net "UPI_CPU1_CPU0_P0P0_DN<14>")
	)
	(segment
		(start 150.288752 -93.76918)
		(end 150.243794 -93.993716)
		(width 0.1143)
		(layer "B.Cu")
		(net "UPI_CPU1_CPU0_P0P0_DN<14>")
	)
	(segment
		(start 302.117252 -64.14897)
		(end 301.812706 -64.324738)
		(width 0.0889)
		(layer "B.Cu")
		(net "UPI_CPU1_CPU0_P0P0_DN<14>")
	)
	(segment
		(start 302.186594 -64.167766)
		(end 302.117252 -64.14897)
		(width 0.0889)
		(layer "B.Cu")
		(net "UPI_CPU1_CPU0_P0P0_DN<14>")
	)
	(segment
		(start 150.38324 -93.296232)
		(end 150.233634 -93.3958)
		(width 0.1143)
		(layer "B.Cu")
		(net "UPI_CPU1_CPU0_P0P0_DN<14>")
	)
	(segment
		(start 201.61504 -121.448322)
		(end 207.99044 -121.864374)
		(width 0.1143)
		(layer "B.Cu")
		(net "UPI_CPU1_CPU0_P0P0_DN<14>")
	)
	(segment
		(start 327.41743 -102.606856)
		(end 327.637394 -95.713042)
		(width 0.1143)
		(layer "B.Cu")
		(net "UPI_CPU1_CPU0_P0P0_DN<14>")
	)
	(segment
		(start 174.192184 -117.646704)
		(end 182.809388 -118.187216)
		(width 0.1143)
		(layer "B.Cu")
		(net "UPI_CPU1_CPU0_P0P0_DN<14>")
	)
	(segment
		(start 150.567644 -92.374212)
		(end 150.522686 -92.598748)
		(width 0.1143)
		(layer "B.Cu")
		(net "UPI_CPU1_CPU0_P0P0_DN<14>")
	)
	(segment
		(start 141.942058 -68.687188)
		(end 142.220188 -68.687188)
		(width 0.0889)
		(layer "B.Cu")
		(net "UPI_CPU1_CPU0_P0P0_DN<14>")
	)
	(segment
		(start 145.9992 -71.71055)
		(end 146.499326 -71.71055)
		(width 0.1143)
		(layer "B.Cu")
		(net "UPI_CPU1_CPU0_P0P0_DN<14>")
	)
	(segment
		(start 324.1675 -81.915)
		(end 324.106286 -79.552038)
		(width 0.1143)
		(layer "B.Cu")
		(net "UPI_CPU1_CPU0_P0P0_DN<14>")
	)
	(segment
		(start 182.809388 -118.187216)
		(end 193.162936 -121.669556)
		(width 0.1143)
		(layer "B.Cu")
		(net "UPI_CPU1_CPU0_P0P0_DN<14>")
	)
	(segment
		(start 149.814788 -95.488252)
		(end 149.770084 -95.71228)
		(width 0.1143)
		(layer "B.Cu")
		(net "UPI_CPU1_CPU0_P0P0_DN<14>")
	)
	(segment
		(start 143.0147 -69.4817)
		(end 143.563594 -69.4817)
		(width 0.0889)
		(layer "B.Cu")
		(net "UPI_CPU1_CPU0_P0P0_DN<14>")
	)
	(segment
		(start 299.01515 -118.39321)
		(end 299.764196 -118.54053)
		(width 0.1143)
		(layer "B.Cu")
		(net "UPI_CPU1_CPU0_P0P0_DN<14>")
	)
	(segment
		(start 308.4322 -64.4398)
		(end 307.7718 -64.4398)
		(width 0.0889)
		(layer "B.Cu")
		(net "UPI_CPU1_CPU0_P0P0_DN<14>")
	)
	(segment
		(start 150.37308 -92.698316)
		(end 150.328376 -92.922344)
		(width 0.1143)
		(layer "B.Cu")
		(net "UPI_CPU1_CPU0_P0P0_DN<14>")
	)
	(segment
		(start 150.149052 -94.466664)
		(end 150.104094 -94.6912)
		(width 0.1143)
		(layer "B.Cu")
		(net "UPI_CPU1_CPU0_P0P0_DN<14>")
	)
	(segment
		(start 309.332122 -116.626894)
		(end 315.611764 -113.265966)
		(width 0.1143)
		(layer "B.Cu")
		(net "UPI_CPU1_CPU0_P0P0_DN<14>")
	)
	(segment
		(start 149.725888 -96.57969)
		(end 149.681184 -96.804226)
		(width 0.1143)
		(layer "B.Cu")
		(net "UPI_CPU1_CPU0_P0P0_DN<14>")
	)
	(segment
		(start 147.409662 -72.620632)
		(end 149.93112 -85.227922)
		(width 0.1143)
		(layer "B.Cu")
		(net "UPI_CPU1_CPU0_P0P0_DN<14>")
	)
	(segment
		(start 145.968974 -71.7296)
		(end 145.988024 -71.71055)
		(width 0.0889)
		(layer "B.Cu")
		(net "UPI_CPU1_CPU0_P0P0_DN<14>")
	)
	(segment
		(start 306.12334 -63.429388)
		(end 306.087272 -63.429388)
		(width 0.0889)
		(layer "B.Cu")
		(net "UPI_CPU1_CPU0_P0P0_DN<14>")
	)
	(segment
		(start 150.328376 -92.922344)
		(end 150.428198 -93.071696)
		(width 0.1143)
		(layer "B.Cu")
		(net "UPI_CPU1_CPU0_P0P0_DN<14>")
	)
	(segment
		(start 145.988024 -71.71055)
		(end 145.9992 -71.71055)
		(width 0.0889)
		(layer "B.Cu")
		(net "UPI_CPU1_CPU0_P0P0_DN<14>")
	)
	(segment
		(start 149.93112 -85.227922)
		(end 150.899114 -90.06713)
		(width 0.1143)
		(layer "B.Cu")
		(net "UPI_CPU1_CPU0_P0P0_DN<14>")
	)
	(segment
		(start 150.094188 -94.093284)
		(end 150.049484 -94.317312)
		(width 0.1143)
		(layer "B.Cu")
		(net "UPI_CPU1_CPU0_P0P0_DN<14>")
	)
	(segment
		(start 308.754526 -64.117474)
		(end 308.4322 -64.4398)
		(width 0.0889)
		(layer "B.Cu")
		(net "UPI_CPU1_CPU0_P0P0_DN<14>")
	)
	(segment
		(start 172.151294 -117.030754)
		(end 174.192184 -117.646704)
		(width 0.1143)
		(layer "B.Cu")
		(net "UPI_CPU1_CPU0_P0P0_DN<14>")
	)
	(segment
		(start 149.389846 -99.66071)
		(end 149.59457 -100.684076)
		(width 0.1143)
		(layer "B.Cu")
		(net "UPI_CPU1_CPU0_P0P0_DN<14>")
	)
	(segment
		(start 150.899114 -90.06713)
		(end 150.467822 -92.22486)
		(width 0.1143)
		(layer "B.Cu")
		(net "UPI_CPU1_CPU0_P0P0_DN<14>")
	)
	(segment
		(start 291.125402 -119.452898)
		(end 292.421818 -119.712232)
		(width 0.1143)
		(layer "B.Cu")
		(net "UPI_CPU1_CPU0_P0P0_DN<14>")
	)
	(segment
		(start 149.531578 -96.903794)
		(end 149.184868 -98.636836)
		(width 0.1143)
		(layer "B.Cu")
		(net "UPI_CPU1_CPU0_P0P0_DN<14>")
	)
	(segment
		(start 146.499326 -71.71055)
		(end 147.409662 -72.620632)
		(width 0.1143)
		(layer "B.Cu")
		(net "UPI_CPU1_CPU0_P0P0_DN<14>")
	)
	(segment
		(start 193.162936 -121.669556)
		(end 198.323962 -121.889774)
		(width 0.1143)
		(layer "B.Cu")
		(net "UPI_CPU1_CPU0_P0P0_DN<14>")
	)
	(segment
		(start 150.428198 -93.071696)
		(end 150.38324 -93.296232)
		(width 0.1143)
		(layer "B.Cu")
		(net "UPI_CPU1_CPU0_P0P0_DN<14>")
	)
	(segment
		(start 150.467822 -92.22486)
		(end 150.567644 -92.374212)
		(width 0.1143)
		(layer "B.Cu")
		(net "UPI_CPU1_CPU0_P0P0_DN<14>")
	)
	(segment
		(start 155.872688 -108.300266)
		(end 158.437326 -109.772704)
		(width 0.1143)
		(layer "B.Cu")
		(net "UPI_CPU1_CPU0_P0P0_DN<14>")
	)
	(segment
		(start 292.421818 -119.712232)
		(end 299.01515 -118.39321)
		(width 0.1143)
		(layer "B.Cu")
		(net "UPI_CPU1_CPU0_P0P0_DN<14>")
	)
	(segment
		(start 310.6928 -64.142874)
		(end 310.6674 -64.117474)
		(width 0.0889)
		(layer "B.Cu")
		(net "UPI_CPU1_CPU0_P0P0_DN<14>")
	)
	(segment
		(start 149.389846 -99.660456)
		(end 149.389846 -99.66071)
		(width 0.1143)
		(layer "B.Cu")
		(net "UPI_CPU1_CPU0_P0P0_DN<14>")
	)
	(segment
		(start 149.909784 -95.014796)
		(end 150.009352 -95.164148)
		(width 0.1143)
		(layer "B.Cu")
		(net "UPI_CPU1_CPU0_P0P0_DN<14>")
	)
	(segment
		(start 226.412298 -118.166134)
		(end 249.235468 -119.310404)
		(width 0.1143)
		(layer "B.Cu")
		(net "UPI_CPU1_CPU0_P0P0_DN<14>")
	)
	(segment
		(start 145.811494 -71.7296)
		(end 145.968974 -71.7296)
		(width 0.0889)
		(layer "B.Cu")
		(net "UPI_CPU1_CPU0_P0P0_DN<14>")
	)
	(segment
		(start 307.296312 -64.915288)
		(end 306.946046 -64.915288)
		(width 0.0889)
		(layer "B.Cu")
		(net "UPI_CPU1_CPU0_P0P0_DN<14>")
	)
	(segment
		(start 288.244026 -118.96852)
		(end 288.473388 -118.922546)
		(width 0.1143)
		(layer "B.Cu")
		(net "UPI_CPU1_CPU0_P0P0_DN<14>")
	)
	(segment
		(start 149.869652 -95.861632)
		(end 149.824948 -96.086168)
		(width 0.1143)
		(layer "B.Cu")
		(net "UPI_CPU1_CPU0_P0P0_DN<14>")
	)
	(segment
		(start 141.089888 -69.182234)
		(end 141.11986 -69.182234)
		(width 0.0889)
		(layer "B.Cu")
		(net "UPI_CPU1_CPU0_P0P0_DN<14>")
	)
	(segment
		(start 304.409856 -64.419734)
		(end 304.37709 -64.419734)
		(width 0.0889)
		(layer "B.Cu")
		(net "UPI_CPU1_CPU0_P0P0_DN<14>")
	)
	(segment
		(start 142.220188 -68.687188)
		(end 143.0147 -69.4817)
		(width 0.0889)
		(layer "B.Cu")
		(net "UPI_CPU1_CPU0_P0P0_DN<14>")
	)
	(segment
		(start 150.18893 -93.619828)
		(end 150.288752 -93.76918)
		(width 0.1143)
		(layer "B.Cu")
		(net "UPI_CPU1_CPU0_P0P0_DN<14>")
	)
	(segment
		(start 302.682402 -64.419734)
		(end 302.649636 -64.419734)
		(width 0.0889)
		(layer "B.Cu")
		(net "UPI_CPU1_CPU0_P0P0_DN<14>")
	)
	(segment
		(start 150.522686 -92.598748)
		(end 150.37308 -92.698316)
		(width 0.1143)
		(layer "B.Cu")
		(net "UPI_CPU1_CPU0_P0P0_DN<14>")
	)
	(segment
		(start 326.413622 -92.65285)
		(end 324.30974 -87.392764)
		(width 0.1143)
		(layer "B.Cu")
		(net "UPI_CPU1_CPU0_P0P0_DN<14>")
	)
	(segment
		(start 149.675088 -96.185736)
		(end 149.62632 -96.430338)
		(width 0.1143)
		(layer "B.Cu")
		(net "UPI_CPU1_CPU0_P0P0_DN<14>")
	)
	(segment
		(start 149.770084 -95.71228)
		(end 149.869652 -95.861632)
		(width 0.1143)
		(layer "B.Cu")
		(net "UPI_CPU1_CPU0_P0P0_DN<14>")
	)
	(segment
		(start 149.681184 -96.804226)
		(end 149.531578 -96.903794)
		(width 0.1143)
		(layer "B.Cu")
		(net "UPI_CPU1_CPU0_P0P0_DN<14>")
	)
	(segment
		(start 311.479946 -64.142874)
		(end 310.6928 -64.142874)
		(width 0.1143)
		(layer "B.Cu")
		(net "UPI_CPU1_CPU0_P0P0_DN<14>")
	)
	(segment
		(start 166.4589 -112.859566)
		(end 167.897556 -114.574828)
		(width 0.1143)
		(layer "B.Cu")
		(net "UPI_CPU1_CPU0_P0P0_DN<14>")
	)
	(segment
		(start 249.235468 -119.310404)
		(end 263.062466 -117.68963)
		(width 0.1143)
		(layer "B.Cu")
		(net "UPI_CPU1_CPU0_P0P0_DN<14>")
	)
	(arc
		(start 303.017936 -64.619886)
		(mid 302.876253 -64.476082)
		(end 302.682402 -64.419734)
		(width 0.0889)
		(layer "B.Cu")
		(net "UPI_CPU1_CPU0_P0P0_DN<14>")
	)
	(arc
		(start 141.11986 -69.182234)
		(mid 141.311502 -69.125068)
		(end 141.451584 -68.982336)
		(width 0.0889)
		(layer "B.Cu")
		(net "UPI_CPU1_CPU0_P0P0_DN<14>")
	)
	(arc
		(start 306.946046 -64.915288)
		(mid 306.447795 -64.612448)
		(end 306.452016 -64.029336)
		(width 0.0889)
		(layer "B.Cu")
		(net "UPI_CPU1_CPU0_P0P0_DN<14>")
	)
	(arc
		(start 302.649636 -64.419734)
		(mid 302.388479 -64.348224)
		(end 302.186594 -64.167766)
		(width 0.0889)
		(layer "B.Cu")
		(net "UPI_CPU1_CPU0_P0P0_DN<14>")
	)
	(arc
		(start 304.900076 -64.124586)
		(mid 304.693072 -64.33545)
		(end 304.409856 -64.419734)
		(width 0.0889)
		(layer "B.Cu")
		(net "UPI_CPU1_CPU0_P0P0_DN<14>")
	)
	(arc
		(start 140.758164 -68.982336)
		(mid 140.898243 -69.125072)
		(end 141.089888 -69.182234)
		(width 0.0889)
		(layer "B.Cu")
		(net "UPI_CPU1_CPU0_P0P0_DN<14>")
	)
	(arc
		(start 140.311378 -68.690236)
		(mid 140.569648 -68.782944)
		(end 140.758164 -68.982336)
		(width 0.0889)
		(layer "B.Cu")
		(net "UPI_CPU1_CPU0_P0P0_DN<14>")
	)
	(arc
		(start 306.452016 -64.029336)
		(mid 306.456426 -63.636873)
		(end 306.12334 -63.429388)
		(width 0.0889)
		(layer "B.Cu")
		(net "UPI_CPU1_CPU0_P0P0_DN<14>")
	)
	(arc
		(start 304.041556 -64.619886)
		(mid 303.529746 -64.915553)
		(end 303.017936 -64.619886)
		(width 0.0889)
		(layer "B.Cu")
		(net "UPI_CPU1_CPU0_P0P0_DN<14>")
	)
	(arc
		(start 141.451584 -68.982336)
		(mid 141.658697 -68.771406)
		(end 141.942058 -68.687188)
		(width 0.0889)
		(layer "B.Cu")
		(net "UPI_CPU1_CPU0_P0P0_DN<14>")
	)
	(arc
		(start 306.087272 -63.429388)
		(mid 305.897343 -63.487258)
		(end 305.758596 -63.629286)
		(width 0.0889)
		(layer "B.Cu")
		(net "UPI_CPU1_CPU0_P0P0_DN<14>")
	)
	(arc
		(start 305.2318 -63.924688)
		(mid 305.040158 -63.981854)
		(end 304.900076 -64.124586)
		(width 0.0889)
		(layer "B.Cu")
		(net "UPI_CPU1_CPU0_P0P0_DN<14>")
	)
	(arc
		(start 305.758596 -63.629286)
		(mid 305.549988 -63.841218)
		(end 305.264566 -63.924688)
		(width 0.0889)
		(layer "B.Cu")
		(net "UPI_CPU1_CPU0_P0P0_DN<14>")
	)
	(arc
		(start 304.37709 -64.419734)
		(mid 304.18324 -64.476084)
		(end 304.041556 -64.619886)
		(width 0.0889)
		(layer "B.Cu")
		(net "UPI_CPU1_CPU0_P0P0_DN<14>")
	)
	(segment
		(start 141.391894 -68.287138)
		(end 141.963394 -68.287138)
		(width 0.1143)
		(layer "F.Cu")
		(net "UPI_CPU1_CPU0_P0P0_DN<13>")
	)
	(segment
		(start 303.529746 -65.315338)
		(end 302.958246 -65.315338)
		(width 0.1143)
		(layer "F.Cu")
		(net "UPI_CPU1_CPU0_P0P0_DN<13>")
	)
	(via
		(at 151.0792 -93.191076)
		(size 0.508)
		(drill 0.254)
		(layers "F.Cu" "B.Cu")
		(net "UPI_CPU1_CPU0_P0P0_DN<13>")
	)
	(via
		(at 141.963394 -68.287138)
		(size 0.508)
		(drill 0.254)
		(layers "F.Cu" "B.Cu")
		(net "UPI_CPU1_CPU0_P0P0_DN<13>")
	)
	(via
		(at 303.529746 -65.315338)
		(size 0.508)
		(drill 0.254)
		(layers "F.Cu" "B.Cu")
		(net "UPI_CPU1_CPU0_P0P0_DN<13>")
	)
	(segment
		(start 307.655722 -65.276984)
		(end 307.888132 -65.044574)
		(width 0.0889)
		(layer "B.Cu")
		(net "UPI_CPU1_CPU0_P0P0_DN<13>")
	)
	(segment
		(start 318.210438 -110.138464)
		(end 318.1985 -110.14456)
		(width 0.1143)
		(layer "B.Cu")
		(net "UPI_CPU1_CPU0_P0P0_DN<13>")
	)
	(segment
		(start 323.431662 -87.611458)
		(end 326.75195 -95.911162)
		(width 0.1143)
		(layer "B.Cu")
		(net "UPI_CPU1_CPU0_P0P0_DN<13>")
	)
	(segment
		(start 201.586338 -120.720104)
		(end 198.261478 -121.164604)
		(width 0.1143)
		(layer "B.Cu")
		(net "UPI_CPU1_CPU0_P0P0_DN<13>")
	)
	(segment
		(start 156.351478 -107.737402)
		(end 153.486612 -104.261666)
		(width 0.1143)
		(layer "B.Cu")
		(net "UPI_CPU1_CPU0_P0P0_DN<13>")
	)
	(segment
		(start 307.217318 -65.715388)
		(end 307.389784 -65.542922)
		(width 0.0889)
		(layer "B.Cu")
		(net "UPI_CPU1_CPU0_P0P0_DN<13>")
	)
	(segment
		(start 307.888132 -65.044574)
		(end 308.305962 -65.044574)
		(width 0.0889)
		(layer "B.Cu")
		(net "UPI_CPU1_CPU0_P0P0_DN<13>")
	)
	(segment
		(start 141.963394 -67.887088)
		(end 141.948408 -67.887088)
		(width 0.0889)
		(layer "B.Cu")
		(net "UPI_CPU1_CPU0_P0P0_DN<13>")
	)
	(segment
		(start 172.364146 -116.315236)
		(end 168.370758 -114.00917)
		(width 0.1143)
		(layer "B.Cu")
		(net "UPI_CPU1_CPU0_P0P0_DN<13>")
	)
	(segment
		(start 303.23663 -65.146174)
		(end 303.15789 -65.16751)
		(width 0.0889)
		(layer "B.Cu")
		(net "UPI_CPU1_CPU0_P0P0_DN<13>")
	)
	(segment
		(start 323.212968 -79.189326)
		(end 323.283834 -81.915)
		(width 0.1143)
		(layer "B.Cu")
		(net "UPI_CPU1_CPU0_P0P0_DN<13>")
	)
	(segment
		(start 309.321962 -65.044574)
		(end 309.423562 -64.942974)
		(width 0.0889)
		(layer "B.Cu")
		(net "UPI_CPU1_CPU0_P0P0_DN<13>")
	)
	(segment
		(start 309.169562 -65.044574)
		(end 309.321962 -65.044574)
		(width 0.0889)
		(layer "B.Cu")
		(net "UPI_CPU1_CPU0_P0P0_DN<13>")
	)
	(segment
		(start 309.931562 -64.942974)
		(end 310.083962 -64.942974)
		(width 0.0889)
		(layer "B.Cu")
		(net "UPI_CPU1_CPU0_P0P0_DN<13>")
	)
	(segment
		(start 150.306786 -100.40493)
		(end 149.97176 -98.728784)
		(width 0.1143)
		(layer "B.Cu")
		(net "UPI_CPU1_CPU0_P0P0_DN<13>")
	)
	(segment
		(start 145.73631 -70.78091)
		(end 145.184368 -70.228968)
		(width 0.0889)
		(layer "B.Cu")
		(net "UPI_CPU1_CPU0_P0P0_DN<13>")
	)
	(segment
		(start 144.950688 -70.113652)
		(end 144.950688 -69.995288)
		(width 0.0889)
		(layer "B.Cu")
		(net "UPI_CPU1_CPU0_P0P0_DN<13>")
	)
	(segment
		(start 311.242964 -65.019174)
		(end 312.530998 -65.517014)
		(width 0.1143)
		(layer "B.Cu")
		(net "UPI_CPU1_CPU0_P0P0_DN<13>")
	)
	(segment
		(start 310.337962 -65.044574)
		(end 310.363362 -65.019174)
		(width 0.0889)
		(layer "B.Cu")
		(net "UPI_CPU1_CPU0_P0P0_DN<13>")
	)
	(segment
		(start 309.575962 -64.942974)
		(end 309.677562 -65.044574)
		(width 0.0889)
		(layer "B.Cu")
		(net "UPI_CPU1_CPU0_P0P0_DN<13>")
	)
	(segment
		(start 166.748206 -112.07496)
		(end 163.01974 -109.365034)
		(width 0.1143)
		(layer "B.Cu")
		(net "UPI_CPU1_CPU0_P0P0_DN<13>")
	)
	(segment
		(start 305.225196 -64.724788)
		(end 305.268376 -64.724788)
		(width 0.0889)
		(layer "B.Cu")
		(net "UPI_CPU1_CPU0_P0P0_DN<13>")
	)
	(segment
		(start 144.399 -69.4436)
		(end 144.280636 -69.4436)
		(width 0.0889)
		(layer "B.Cu")
		(net "UPI_CPU1_CPU0_P0P0_DN<13>")
	)
	(segment
		(start 310.38546 -65.019174)
		(end 311.242964 -65.019174)
		(width 0.1143)
		(layer "B.Cu")
		(net "UPI_CPU1_CPU0_P0P0_DN<13>")
	)
	(segment
		(start 323.283834 -81.915)
		(end 323.431662 -87.611458)
		(width 0.1143)
		(layer "B.Cu")
		(net "UPI_CPU1_CPU0_P0P0_DN<13>")
	)
	(segment
		(start 144.8054 -69.85)
		(end 144.687036 -69.85)
		(width 0.0889)
		(layer "B.Cu")
		(net "UPI_CPU1_CPU0_P0P0_DN<13>")
	)
	(segment
		(start 308.661562 -65.044574)
		(end 308.813962 -65.044574)
		(width 0.0889)
		(layer "B.Cu")
		(net "UPI_CPU1_CPU0_P0P0_DN<13>")
	)
	(segment
		(start 309.078884 -115.92306)
		(end 300.15688 -117.707156)
		(width 0.1143)
		(layer "B.Cu")
		(net "UPI_CPU1_CPU0_P0P0_DN<13>")
	)
	(segment
		(start 306.617116 -65.515236)
		(end 306.693824 -65.648078)
		(width 0.0889)
		(layer "B.Cu")
		(net "UPI_CPU1_CPU0_P0P0_DN<13>")
	)
	(segment
		(start 147.766532 -71.744586)
		(end 146.830796 -70.80885)
		(width 0.1143)
		(layer "B.Cu")
		(net "UPI_CPU1_CPU0_P0P0_DN<13>")
	)
	(segment
		(start 207.937354 -121.134378)
		(end 201.586338 -120.720104)
		(width 0.1143)
		(layer "B.Cu")
		(net "UPI_CPU1_CPU0_P0P0_DN<13>")
	)
	(segment
		(start 326.54875 -102.28199)
		(end 318.210438 -110.138464)
		(width 0.1143)
		(layer "B.Cu")
		(net "UPI_CPU1_CPU0_P0P0_DN<13>")
	)
	(segment
		(start 151.020018 -93.486732)
		(end 151.0792 -93.191076)
		(width 0.1143)
		(layer "B.Cu")
		(net "UPI_CPU1_CPU0_P0P0_DN<13>")
	)
	(segment
		(start 193.296032 -120.948196)
		(end 193.2178 -120.92178)
		(width 0.1143)
		(layer "B.Cu")
		(net "UPI_CPU1_CPU0_P0P0_DN<13>")
	)
	(segment
		(start 308.305962 -65.044574)
		(end 308.407562 -64.942974)
		(width 0.0889)
		(layer "B.Cu")
		(net "UPI_CPU1_CPU0_P0P0_DN<13>")
	)
	(segment
		(start 303.529746 -65.315338)
		(end 303.23663 -65.146174)
		(width 0.0889)
		(layer "B.Cu")
		(net "UPI_CPU1_CPU0_P0P0_DN<13>")
	)
	(segment
		(start 145.184368 -70.228968)
		(end 145.066004 -70.228968)
		(width 0.0889)
		(layer "B.Cu")
		(net "UPI_CPU1_CPU0_P0P0_DN<13>")
	)
	(segment
		(start 309.423562 -64.942974)
		(end 309.575962 -64.942974)
		(width 0.0889)
		(layer "B.Cu")
		(net "UPI_CPU1_CPU0_P0P0_DN<13>")
	)
	(segment
		(start 310.185562 -65.044574)
		(end 310.337962 -65.044574)
		(width 0.0889)
		(layer "B.Cu")
		(net "UPI_CPU1_CPU0_P0P0_DN<13>")
	)
	(segment
		(start 198.261478 -121.164604)
		(end 193.296032 -120.948196)
		(width 0.1143)
		(layer "B.Cu")
		(net "UPI_CPU1_CPU0_P0P0_DN<13>")
	)
	(segment
		(start 141.591538 -68.434712)
		(end 141.670278 -68.456048)
		(width 0.0889)
		(layer "B.Cu")
		(net "UPI_CPU1_CPU0_P0P0_DN<13>")
	)
	(segment
		(start 263.056878 -116.958872)
		(end 249.210068 -118.581678)
		(width 0.1143)
		(layer "B.Cu")
		(net "UPI_CPU1_CPU0_P0P0_DN<13>")
	)
	(segment
		(start 174.409608 -116.93271)
		(end 172.364146 -116.315236)
		(width 0.1143)
		(layer "B.Cu")
		(net "UPI_CPU1_CPU0_P0P0_DN<13>")
	)
	(segment
		(start 158.3944 -108.879386)
		(end 156.351478 -107.737402)
		(width 0.1143)
		(layer "B.Cu")
		(net "UPI_CPU1_CPU0_P0P0_DN<13>")
	)
	(segment
		(start 310.363362 -65.019174)
		(end 310.38546 -65.019174)
		(width 0.0889)
		(layer "B.Cu")
		(net "UPI_CPU1_CPU0_P0P0_DN<13>")
	)
	(segment
		(start 291.125402 -118.908322)
		(end 287.63468 -118.210584)
		(width 0.1143)
		(layer "B.Cu")
		(net "UPI_CPU1_CPU0_P0P0_DN<13>")
	)
	(segment
		(start 145.066004 -70.228968)
		(end 144.950688 -70.113652)
		(width 0.0889)
		(layer "B.Cu")
		(net "UPI_CPU1_CPU0_P0P0_DN<13>")
	)
	(segment
		(start 146.830796 -70.80885)
		(end 145.993104 -70.80885)
		(width 0.1143)
		(layer "B.Cu")
		(net "UPI_CPU1_CPU0_P0P0_DN<13>")
	)
	(segment
		(start 304.370486 -65.219834)
		(end 304.403252 -65.219834)
		(width 0.0889)
		(layer "B.Cu")
		(net "UPI_CPU1_CPU0_P0P0_DN<13>")
	)
	(segment
		(start 306.874418 -65.715388)
		(end 307.217318 -65.715388)
		(width 0.0889)
		(layer "B.Cu")
		(net "UPI_CPU1_CPU0_P0P0_DN<13>")
	)
	(segment
		(start 307.389784 -65.402714)
		(end 307.515514 -65.276984)
		(width 0.0889)
		(layer "B.Cu")
		(net "UPI_CPU1_CPU0_P0P0_DN<13>")
	)
	(segment
		(start 312.530998 -65.517014)
		(end 314.632594 -66.898774)
		(width 0.1143)
		(layer "B.Cu")
		(net "UPI_CPU1_CPU0_P0P0_DN<13>")
	)
	(segment
		(start 163.01974 -109.365034)
		(end 158.3944 -108.879386)
		(width 0.1143)
		(layer "B.Cu")
		(net "UPI_CPU1_CPU0_P0P0_DN<13>")
	)
	(segment
		(start 308.407562 -64.942974)
		(end 308.559962 -64.942974)
		(width 0.0889)
		(layer "B.Cu")
		(net "UPI_CPU1_CPU0_P0P0_DN<13>")
	)
	(segment
		(start 308.559962 -64.942974)
		(end 308.661562 -65.044574)
		(width 0.0889)
		(layer "B.Cu")
		(net "UPI_CPU1_CPU0_P0P0_DN<13>")
	)
	(segment
		(start 149.97176 -98.728784)
		(end 151.020018 -93.486732)
		(width 0.1143)
		(layer "B.Cu")
		(net "UPI_CPU1_CPU0_P0P0_DN<13>")
	)
	(segment
		(start 144.5514 -69.714364)
		(end 144.5514 -69.596)
		(width 0.0889)
		(layer "B.Cu")
		(net "UPI_CPU1_CPU0_P0P0_DN<13>")
	)
	(segment
		(start 151.0792 -93.191076)
		(end 151.567896 -90.747596)
		(width 0.1143)
		(layer "B.Cu")
		(net "UPI_CPU1_CPU0_P0P0_DN<13>")
	)
	(segment
		(start 308.915562 -64.942974)
		(end 309.067962 -64.942974)
		(width 0.0889)
		(layer "B.Cu")
		(net "UPI_CPU1_CPU0_P0P0_DN<13>")
	)
	(segment
		(start 144.145 -69.307964)
		(end 144.145 -69.1896)
		(width 0.0889)
		(layer "B.Cu")
		(net "UPI_CPU1_CPU0_P0P0_DN<13>")
	)
	(segment
		(start 193.2178 -120.92178)
		(end 182.951374 -117.46865)
		(width 0.1143)
		(layer "B.Cu")
		(net "UPI_CPU1_CPU0_P0P0_DN<13>")
	)
	(segment
		(start 145.993104 -70.80885)
		(end 145.965164 -70.78091)
		(width 0.0889)
		(layer "B.Cu")
		(net "UPI_CPU1_CPU0_P0P0_DN<13>")
	)
	(segment
		(start 143.154146 -68.8848)
		(end 142.292832 -68.023486)
		(width 0.0889)
		(layer "B.Cu")
		(net "UPI_CPU1_CPU0_P0P0_DN<13>")
	)
	(segment
		(start 317.274194 -110.613444)
		(end 315.004958 -112.751362)
		(width 0.1143)
		(layer "B.Cu")
		(net "UPI_CPU1_CPU0_P0P0_DN<13>")
	)
	(segment
		(start 153.486104 -104.261666)
		(end 150.306786 -100.40493)
		(width 0.1143)
		(layer "B.Cu")
		(net "UPI_CPU1_CPU0_P0P0_DN<13>")
	)
	(segment
		(start 287.63468 -118.210584)
		(end 283.508196 -119.03583)
		(width 0.1143)
		(layer "B.Cu")
		(net "UPI_CPU1_CPU0_P0P0_DN<13>")
	)
	(segment
		(start 300.15688 -117.707156)
		(end 299.44441 -117.566694)
		(width 0.1143)
		(layer "B.Cu")
		(net "UPI_CPU1_CPU0_P0P0_DN<13>")
	)
	(segment
		(start 310.083962 -64.942974)
		(end 310.185562 -65.044574)
		(width 0.0889)
		(layer "B.Cu")
		(net "UPI_CPU1_CPU0_P0P0_DN<13>")
	)
	(segment
		(start 182.951374 -117.46865)
		(end 174.409608 -116.93271)
		(width 0.1143)
		(layer "B.Cu")
		(net "UPI_CPU1_CPU0_P0P0_DN<13>")
	)
	(segment
		(start 299.44441 -117.566694)
		(end 291.92982 -119.069104)
		(width 0.1143)
		(layer "B.Cu")
		(net "UPI_CPU1_CPU0_P0P0_DN<13>")
	)
	(segment
		(start 145.965164 -70.78091)
		(end 145.73631 -70.78091)
		(width 0.0889)
		(layer "B.Cu")
		(net "UPI_CPU1_CPU0_P0P0_DN<13>")
	)
	(segment
		(start 309.067962 -64.942974)
		(end 309.169562 -65.044574)
		(width 0.0889)
		(layer "B.Cu")
		(net "UPI_CPU1_CPU0_P0P0_DN<13>")
	)
	(segment
		(start 151.567896 -90.747596)
		(end 147.766532 -71.744586)
		(width 0.1143)
		(layer "B.Cu")
		(net "UPI_CPU1_CPU0_P0P0_DN<13>")
	)
	(segment
		(start 144.950688 -69.995288)
		(end 144.8054 -69.85)
		(width 0.0889)
		(layer "B.Cu")
		(net "UPI_CPU1_CPU0_P0P0_DN<13>")
	)
	(segment
		(start 249.210068 -118.581678)
		(end 226.354132 -117.436392)
		(width 0.1143)
		(layer "B.Cu")
		(net "UPI_CPU1_CPU0_P0P0_DN<13>")
	)
	(segment
		(start 307.515514 -65.276984)
		(end 307.655722 -65.276984)
		(width 0.0889)
		(layer "B.Cu")
		(net "UPI_CPU1_CPU0_P0P0_DN<13>")
	)
	(segment
		(start 143.8402 -68.8848)
		(end 143.154146 -68.8848)
		(width 0.0889)
		(layer "B.Cu")
		(net "UPI_CPU1_CPU0_P0P0_DN<13>")
	)
	(segment
		(start 226.354132 -117.436392)
		(end 215.1634 -119.68353)
		(width 0.1143)
		(layer "B.Cu")
		(net "UPI_CPU1_CPU0_P0P0_DN<13>")
	)
	(segment
		(start 315.004958 -112.751362)
		(end 309.078884 -115.92306)
		(width 0.1143)
		(layer "B.Cu")
		(net "UPI_CPU1_CPU0_P0P0_DN<13>")
	)
	(segment
		(start 314.632594 -66.898774)
		(end 314.63234 -66.899028)
		(width 0.1143)
		(layer "B.Cu")
		(net "UPI_CPU1_CPU0_P0P0_DN<13>")
	)
	(segment
		(start 144.687036 -69.85)
		(end 144.5514 -69.714364)
		(width 0.0889)
		(layer "B.Cu")
		(net "UPI_CPU1_CPU0_P0P0_DN<13>")
	)
	(segment
		(start 168.370758 -114.00917)
		(end 166.748206 -112.07496)
		(width 0.1143)
		(layer "B.Cu")
		(net "UPI_CPU1_CPU0_P0P0_DN<13>")
	)
	(segment
		(start 318.1985 -110.14456)
		(end 317.274194 -110.613444)
		(width 0.1143)
		(layer "B.Cu")
		(net "UPI_CPU1_CPU0_P0P0_DN<13>")
	)
	(segment
		(start 215.1634 -119.68353)
		(end 207.937354 -121.134378)
		(width 0.1143)
		(layer "B.Cu")
		(net "UPI_CPU1_CPU0_P0P0_DN<13>")
	)
	(segment
		(start 306.09032 -65.219834)
		(end 306.119022 -65.219834)
		(width 0.0889)
		(layer "B.Cu")
		(net "UPI_CPU1_CPU0_P0P0_DN<13>")
	)
	(segment
		(start 317.363602 -68.6943)
		(end 323.212968 -79.189326)
		(width 0.1143)
		(layer "B.Cu")
		(net "UPI_CPU1_CPU0_P0P0_DN<13>")
	)
	(segment
		(start 144.280636 -69.4436)
		(end 144.145 -69.307964)
		(width 0.0889)
		(layer "B.Cu")
		(net "UPI_CPU1_CPU0_P0P0_DN<13>")
	)
	(segment
		(start 308.813962 -65.044574)
		(end 308.915562 -64.942974)
		(width 0.0889)
		(layer "B.Cu")
		(net "UPI_CPU1_CPU0_P0P0_DN<13>")
	)
	(segment
		(start 307.389784 -65.542922)
		(end 307.389784 -65.402714)
		(width 0.0889)
		(layer "B.Cu")
		(net "UPI_CPU1_CPU0_P0P0_DN<13>")
	)
	(segment
		(start 153.486612 -104.261666)
		(end 153.486104 -104.261666)
		(width 0.1143)
		(layer "B.Cu")
		(net "UPI_CPU1_CPU0_P0P0_DN<13>")
	)
	(segment
		(start 291.92982 -119.069104)
		(end 291.125402 -118.908322)
		(width 0.1143)
		(layer "B.Cu")
		(net "UPI_CPU1_CPU0_P0P0_DN<13>")
	)
	(segment
		(start 144.145 -69.1896)
		(end 143.8402 -68.8848)
		(width 0.0889)
		(layer "B.Cu")
		(net "UPI_CPU1_CPU0_P0P0_DN<13>")
	)
	(segment
		(start 326.75195 -95.911162)
		(end 326.54875 -102.28199)
		(width 0.1143)
		(layer "B.Cu")
		(net "UPI_CPU1_CPU0_P0P0_DN<13>")
	)
	(segment
		(start 144.5514 -69.596)
		(end 144.399 -69.4436)
		(width 0.0889)
		(layer "B.Cu")
		(net "UPI_CPU1_CPU0_P0P0_DN<13>")
	)
	(segment
		(start 141.670278 -68.456048)
		(end 141.963394 -68.287138)
		(width 0.0889)
		(layer "B.Cu")
		(net "UPI_CPU1_CPU0_P0P0_DN<13>")
	)
	(segment
		(start 309.677562 -65.044574)
		(end 309.829962 -65.044574)
		(width 0.0889)
		(layer "B.Cu")
		(net "UPI_CPU1_CPU0_P0P0_DN<13>")
	)
	(segment
		(start 283.508196 -119.03583)
		(end 263.056878 -116.958872)
		(width 0.1143)
		(layer "B.Cu")
		(net "UPI_CPU1_CPU0_P0P0_DN<13>")
	)
	(segment
		(start 309.829962 -65.044574)
		(end 309.931562 -64.942974)
		(width 0.0889)
		(layer "B.Cu")
		(net "UPI_CPU1_CPU0_P0P0_DN<13>")
	)
	(segment
		(start 314.63234 -66.899028)
		(end 317.363602 -68.6943)
		(width 0.1143)
		(layer "B.Cu")
		(net "UPI_CPU1_CPU0_P0P0_DN<13>")
	)
	(segment
		(start 306.693824 -65.648078)
		(end 306.874418 -65.715388)
		(width 0.0889)
		(layer "B.Cu")
		(net "UPI_CPU1_CPU0_P0P0_DN<13>")
	)
	(arc
		(start 305.268376 -64.724788)
		(mid 305.551593 -64.809069)
		(end 305.758596 -65.019936)
		(width 0.0889)
		(layer "B.Cu")
		(net "UPI_CPU1_CPU0_P0P0_DN<13>")
	)
	(arc
		(start 304.734976 -65.019936)
		(mid 304.94198 -64.809072)
		(end 305.225196 -64.724788)
		(width 0.0889)
		(layer "B.Cu")
		(net "UPI_CPU1_CPU0_P0P0_DN<13>")
	)
	(arc
		(start 141.563344 -68.284598)
		(mid 141.570212 -68.361013)
		(end 141.591538 -68.434712)
		(width 0.0889)
		(layer "B.Cu")
		(net "UPI_CPU1_CPU0_P0P0_DN<13>")
	)
	(arc
		(start 306.119022 -65.219834)
		(mid 306.406709 -65.302355)
		(end 306.617116 -65.515236)
		(width 0.0889)
		(layer "B.Cu")
		(net "UPI_CPU1_CPU0_P0P0_DN<13>")
	)
	(arc
		(start 304.403252 -65.219834)
		(mid 304.594894 -65.162668)
		(end 304.734976 -65.019936)
		(width 0.0889)
		(layer "B.Cu")
		(net "UPI_CPU1_CPU0_P0P0_DN<13>")
	)
	(arc
		(start 303.876456 -65.515236)
		(mid 304.085064 -65.303304)
		(end 304.370486 -65.219834)
		(width 0.0889)
		(layer "B.Cu")
		(net "UPI_CPU1_CPU0_P0P0_DN<13>")
	)
	(arc
		(start 305.758596 -65.019936)
		(mid 305.898675 -65.162672)
		(end 306.09032 -65.219834)
		(width 0.0889)
		(layer "B.Cu")
		(net "UPI_CPU1_CPU0_P0P0_DN<13>")
	)
	(arc
		(start 303.517808 -65.715134)
		(mid 303.529873 -65.71532)
		(end 303.541938 -65.715134)
		(width 0.0889)
		(layer "B.Cu")
		(net "UPI_CPU1_CPU0_P0P0_DN<13>")
	)
	(arc
		(start 303.15789 -65.16751)
		(mid 303.195451 -65.534861)
		(end 303.517808 -65.715134)
		(width 0.0889)
		(layer "B.Cu")
		(net "UPI_CPU1_CPU0_P0P0_DN<13>")
	)
	(arc
		(start 141.948408 -67.887088)
		(mid 141.676109 -68.008582)
		(end 141.563344 -68.284598)
		(width 0.0889)
		(layer "B.Cu")
		(net "UPI_CPU1_CPU0_P0P0_DN<13>")
	)
	(arc
		(start 142.292832 -68.023486)
		(mid 142.141656 -67.9226)
		(end 141.963394 -67.887088)
		(width 0.0889)
		(layer "B.Cu")
		(net "UPI_CPU1_CPU0_P0P0_DN<13>")
	)
	(arc
		(start 303.541938 -65.715134)
		(mid 303.735215 -65.658696)
		(end 303.876456 -65.515236)
		(width 0.0889)
		(layer "B.Cu")
		(net "UPI_CPU1_CPU0_P0P0_DN<13>")
	)
	(segment
		(start 142.250414 -67.791584)
		(end 142.250414 -68.00596)
		(width 0.0889)
		(layer "F.Cu")
		(net "UPI_CPU1_CPU0_P0P0_DN<12>")
	)
	(segment
		(start 142.587472 -68.191634)
		(end 143.113506 -67.6656)
		(width 0.0889)
		(layer "F.Cu")
		(net "UPI_CPU1_CPU0_P0P0_DN<12>")
	)
	(segment
		(start 142.436088 -68.191634)
		(end 142.587472 -68.191634)
		(width 0.0889)
		(layer "F.Cu")
		(net "UPI_CPU1_CPU0_P0P0_DN<12>")
	)
	(segment
		(start 143.784574 -67.6656)
		(end 143.999204 -67.45097)
		(width 0.0889)
		(layer "F.Cu")
		(net "UPI_CPU1_CPU0_P0P0_DN<12>")
	)
	(segment
		(start 143.113506 -67.6656)
		(end 143.784574 -67.6656)
		(width 0.0889)
		(layer "F.Cu")
		(net "UPI_CPU1_CPU0_P0P0_DN<12>")
	)
	(segment
		(start 303.529746 -66.305938)
		(end 302.958246 -66.305938)
		(width 0.1143)
		(layer "F.Cu")
		(net "UPI_CPU1_CPU0_P0P0_DN<12>")
	)
	(segment
		(start 142.250414 -68.00596)
		(end 142.436088 -68.191634)
		(width 0.0889)
		(layer "F.Cu")
		(net "UPI_CPU1_CPU0_P0P0_DN<12>")
	)
	(via
		(at 143.999204 -67.45097)
		(size 0.508)
		(drill 0.254)
		(layers "F.Cu" "B.Cu")
		(net "UPI_CPU1_CPU0_P0P0_DN<12>")
	)
	(via
		(at 303.529746 -66.305938)
		(size 0.508)
		(drill 0.254)
		(layers "F.Cu" "B.Cu")
		(net "UPI_CPU1_CPU0_P0P0_DN<12>")
	)
	(segment
		(start 157.199076 -103.106982)
		(end 157.101794 -102.631748)
		(width 0.1143)
		(layer "B.Cu")
		(net "UPI_CPU1_CPU0_P0P0_DN<12>")
	)
	(segment
		(start 156.623004 -99.667314)
		(end 156.57703 -99.443032)
		(width 0.1143)
		(layer "B.Cu")
		(net "UPI_CPU1_CPU0_P0P0_DN<12>")
	)
	(segment
		(start 287.109662 -117.067838)
		(end 283.40304 -117.809264)
		(width 0.1143)
		(layer "B.Cu")
		(net "UPI_CPU1_CPU0_P0P0_DN<12>")
	)
	(segment
		(start 157.011878 -101.561138)
		(end 156.861764 -101.462078)
		(width 0.1143)
		(layer "B.Cu")
		(net "UPI_CPU1_CPU0_P0P0_DN<12>")
	)
	(segment
		(start 169.037 -112.921288)
		(end 167.496744 -111.085884)
		(width 0.1143)
		(layer "B.Cu")
		(net "UPI_CPU1_CPU0_P0P0_DN<12>")
	)
	(segment
		(start 283.40304 -117.809264)
		(end 263.04621 -115.74272)
		(width 0.1143)
		(layer "B.Cu")
		(net "UPI_CPU1_CPU0_P0P0_DN<12>")
	)
	(segment
		(start 174.722282 -115.740942)
		(end 172.757084 -115.147344)
		(width 0.1143)
		(layer "B.Cu")
		(net "UPI_CPU1_CPU0_P0P0_DN<12>")
	)
	(segment
		(start 156.57703 -99.443032)
		(end 156.426916 -99.344226)
		(width 0.1143)
		(layer "B.Cu")
		(net "UPI_CPU1_CPU0_P0P0_DN<12>")
	)
	(segment
		(start 159.88411 -105.554018)
		(end 159.560006 -105.153968)
		(width 0.1143)
		(layer "B.Cu")
		(net "UPI_CPU1_CPU0_P0P0_DN<12>")
	)
	(segment
		(start 317.284354 -109.13999)
		(end 316.833504 -109.364526)
		(width 0.1143)
		(layer "B.Cu")
		(net "UPI_CPU1_CPU0_P0P0_DN<12>")
	)
	(segment
		(start 322.075048 -87.838026)
		(end 322.348606 -88.521794)
		(width 0.1143)
		(layer "B.Cu")
		(net "UPI_CPU1_CPU0_P0P0_DN<12>")
	)
	(segment
		(start 303.822862 -66.136774)
		(end 303.91227 -66.160904)
		(width 0.0889)
		(layer "B.Cu")
		(net "UPI_CPU1_CPU0_P0P0_DN<12>")
	)
	(segment
		(start 291.951918 -118.03634)
		(end 291.125402 -117.870986)
		(width 0.1143)
		(layer "B.Cu")
		(net "UPI_CPU1_CPU0_P0P0_DN<12>")
	)
	(segment
		(start 310.388254 -67.257422)
		(end 310.78424 -67.470274)
		(width 0.0889)
		(layer "B.Cu")
		(net "UPI_CPU1_CPU0_P0P0_DN<12>")
	)
	(segment
		(start 306.083716 -66.400934)
		(end 307.69052 -66.400934)
		(width 0.0889)
		(layer "B.Cu")
		(net "UPI_CPU1_CPU0_P0P0_DN<12>")
	)
	(segment
		(start 325.205852 -101.675692)
		(end 317.284354 -109.13999)
		(width 0.1143)
		(layer "B.Cu")
		(net "UPI_CPU1_CPU0_P0P0_DN<12>")
	)
	(segment
		(start 310.81472 -67.514978)
		(end 311.466992 -67.865244)
		(width 0.1143)
		(layer "B.Cu")
		(net "UPI_CPU1_CPU0_P0P0_DN<12>")
	)
	(segment
		(start 159.110172 -104.59847)
		(end 159.043624 -104.516174)
		(width 0.1143)
		(layer "B.Cu")
		(net "UPI_CPU1_CPU0_P0P0_DN<12>")
	)
	(segment
		(start 307.69052 -66.400934)
		(end 307.873654 -66.2178)
		(width 0.0889)
		(layer "B.Cu")
		(net "UPI_CPU1_CPU0_P0P0_DN<12>")
	)
	(segment
		(start 157.004512 -102.1588)
		(end 156.958792 -101.935026)
		(width 0.1143)
		(layer "B.Cu")
		(net "UPI_CPU1_CPU0_P0P0_DN<12>")
	)
	(segment
		(start 156.861764 -101.462078)
		(end 156.810202 -101.210618)
		(width 0.1143)
		(layer "B.Cu")
		(net "UPI_CPU1_CPU0_P0P0_DN<12>")
	)
	(segment
		(start 310.813704 -67.51447)
		(end 310.81472 -67.514978)
		(width 0.1143)
		(layer "B.Cu")
		(net "UPI_CPU1_CPU0_P0P0_DN<12>")
	)
	(segment
		(start 156.524198 -99.817174)
		(end 156.623004 -99.667314)
		(width 0.1143)
		(layer "B.Cu")
		(net "UPI_CPU1_CPU0_P0P0_DN<12>")
	)
	(segment
		(start 156.048964 -97.502218)
		(end 153.415746 -94.49308)
		(width 0.1143)
		(layer "B.Cu")
		(net "UPI_CPU1_CPU0_P0P0_DN<12>")
	)
	(segment
		(start 316.37351 -69.71538)
		(end 321.860164 -79.559658)
		(width 0.1143)
		(layer "B.Cu")
		(net "UPI_CPU1_CPU0_P0P0_DN<12>")
	)
	(segment
		(start 156.634434 -100.083366)
		(end 156.569918 -100.040948)
		(width 0.1143)
		(layer "B.Cu")
		(net "UPI_CPU1_CPU0_P0P0_DN<12>")
	)
	(segment
		(start 156.426916 -99.344226)
		(end 156.371036 -99.070922)
		(width 0.1143)
		(layer "B.Cu")
		(net "UPI_CPU1_CPU0_P0P0_DN<12>")
	)
	(segment
		(start 307.873654 -66.2178)
		(end 309.348632 -66.2178)
		(width 0.0889)
		(layer "B.Cu")
		(net "UPI_CPU1_CPU0_P0P0_DN<12>")
	)
	(segment
		(start 146.215354 -69.4563)
		(end 146.004534 -69.4563)
		(width 0.0889)
		(layer "B.Cu")
		(net "UPI_CPU1_CPU0_P0P0_DN<12>")
	)
	(segment
		(start 183.183784 -116.271548)
		(end 174.722282 -115.740942)
		(width 0.1143)
		(layer "B.Cu")
		(net "UPI_CPU1_CPU0_P0P0_DN<12>")
	)
	(segment
		(start 193.520314 -119.747792)
		(end 193.2178 -119.645938)
		(width 0.1143)
		(layer "B.Cu")
		(net "UPI_CPU1_CPU0_P0P0_DN<12>")
	)
	(segment
		(start 287.1216 -117.070124)
		(end 287.109662 -117.067838)
		(width 0.1143)
		(layer "B.Cu")
		(net "UPI_CPU1_CPU0_P0P0_DN<12>")
	)
	(segment
		(start 303.529746 -66.305938)
		(end 303.822862 -66.136774)
		(width 0.0889)
		(layer "B.Cu")
		(net "UPI_CPU1_CPU0_P0P0_DN<12>")
	)
	(segment
		(start 316.833504 -109.364526)
		(end 314.305696 -111.74603)
		(width 0.1143)
		(layer "B.Cu")
		(net "UPI_CPU1_CPU0_P0P0_DN<12>")
	)
	(segment
		(start 146.247104 -69.42455)
		(end 146.215354 -69.4563)
		(width 0.0889)
		(layer "B.Cu")
		(net "UPI_CPU1_CPU0_P0P0_DN<12>")
	)
	(segment
		(start 156.273754 -98.597974)
		(end 156.048964 -97.502218)
		(width 0.1143)
		(layer "B.Cu")
		(net "UPI_CPU1_CPU0_P0P0_DN<12>")
	)
	(segment
		(start 263.04621 -115.74272)
		(end 249.16892 -117.369082)
		(width 0.1143)
		(layer "B.Cu")
		(net "UPI_CPU1_CPU0_P0P0_DN<12>")
	)
	(segment
		(start 156.76626 -100.364036)
		(end 156.720286 -100.139754)
		(width 0.1143)
		(layer "B.Cu")
		(net "UPI_CPU1_CPU0_P0P0_DN<12>")
	)
	(segment
		(start 157.15488 -102.25786)
		(end 157.004512 -102.1588)
		(width 0.1143)
		(layer "B.Cu")
		(net "UPI_CPU1_CPU0_P0P0_DN<12>")
	)
	(segment
		(start 156.371036 -99.070922)
		(end 156.469842 -98.921062)
		(width 0.1143)
		(layer "B.Cu")
		(net "UPI_CPU1_CPU0_P0P0_DN<12>")
	)
	(segment
		(start 207.856074 -119.917464)
		(end 201.515726 -119.503444)
		(width 0.1143)
		(layer "B.Cu")
		(net "UPI_CPU1_CPU0_P0P0_DN<12>")
	)
	(segment
		(start 159.142684 -104.638602)
		(end 159.110172 -104.59847)
		(width 0.1143)
		(layer "B.Cu")
		(net "UPI_CPU1_CPU0_P0P0_DN<12>")
	)
	(segment
		(start 321.867276 -79.8322)
		(end 321.921378 -81.915)
		(width 0.1143)
		(layer "B.Cu")
		(net "UPI_CPU1_CPU0_P0P0_DN<12>")
	)
	(segment
		(start 312.189114 -68.187316)
		(end 312.846974 -68.4276)
		(width 0.1143)
		(layer "B.Cu")
		(net "UPI_CPU1_CPU0_P0P0_DN<12>")
	)
	(segment
		(start 159.560006 -105.153968)
		(end 159.142684 -104.638602)
		(width 0.1143)
		(layer "B.Cu")
		(net "UPI_CPU1_CPU0_P0P0_DN<12>")
	)
	(segment
		(start 156.569918 -100.040948)
		(end 156.524198 -99.817174)
		(width 0.1143)
		(layer "B.Cu")
		(net "UPI_CPU1_CPU0_P0P0_DN<12>")
	)
	(segment
		(start 160.06572 -105.686098)
		(end 159.88411 -105.554018)
		(width 0.1143)
		(layer "B.Cu")
		(net "UPI_CPU1_CPU0_P0P0_DN<12>")
	)
	(segment
		(start 322.348606 -88.521794)
		(end 325.383398 -96.109536)
		(width 0.1143)
		(layer "B.Cu")
		(net "UPI_CPU1_CPU0_P0P0_DN<12>")
	)
	(segment
		(start 156.863288 -100.836476)
		(end 156.71292 -100.73767)
		(width 0.1143)
		(layer "B.Cu")
		(net "UPI_CPU1_CPU0_P0P0_DN<12>")
	)
	(segment
		(start 321.921378 -81.915)
		(end 322.075048 -87.838026)
		(width 0.1143)
		(layer "B.Cu")
		(net "UPI_CPU1_CPU0_P0P0_DN<12>")
	)
	(segment
		(start 156.71292 -100.73767)
		(end 156.6672 -100.513896)
		(width 0.1143)
		(layer "B.Cu")
		(net "UPI_CPU1_CPU0_P0P0_DN<12>")
	)
	(segment
		(start 157.057852 -101.785166)
		(end 157.011878 -101.561138)
		(width 0.1143)
		(layer "B.Cu")
		(net "UPI_CPU1_CPU0_P0P0_DN<12>")
	)
	(segment
		(start 169.160952 -113.069116)
		(end 169.037 -112.921288)
		(width 0.1143)
		(layer "B.Cu")
		(net "UPI_CPU1_CPU0_P0P0_DN<12>")
	)
	(segment
		(start 148.665184 -70.73773)
		(end 147.352004 -69.42455)
		(width 0.1143)
		(layer "B.Cu")
		(net "UPI_CPU1_CPU0_P0P0_DN<12>")
	)
	(segment
		(start 172.757084 -115.147344)
		(end 169.160952 -113.069116)
		(width 0.1143)
		(layer "B.Cu")
		(net "UPI_CPU1_CPU0_P0P0_DN<12>")
	)
	(segment
		(start 159.043624 -104.516174)
		(end 157.199076 -103.106982)
		(width 0.1143)
		(layer "B.Cu")
		(net "UPI_CPU1_CPU0_P0P0_DN<12>")
	)
	(segment
		(start 146.004534 -69.4563)
		(end 143.999204 -67.45097)
		(width 0.0889)
		(layer "B.Cu")
		(net "UPI_CPU1_CPU0_P0P0_DN<12>")
	)
	(segment
		(start 325.383398 -96.109536)
		(end 325.205852 -101.675692)
		(width 0.1143)
		(layer "B.Cu")
		(net "UPI_CPU1_CPU0_P0P0_DN<12>")
	)
	(segment
		(start 314.305696 -111.74603)
		(end 308.871874 -114.653568)
		(width 0.1143)
		(layer "B.Cu")
		(net "UPI_CPU1_CPU0_P0P0_DN<12>")
	)
	(segment
		(start 156.909008 -101.060758)
		(end 156.863288 -100.836476)
		(width 0.1143)
		(layer "B.Cu")
		(net "UPI_CPU1_CPU0_P0P0_DN<12>")
	)
	(segment
		(start 311.466992 -67.865244)
		(end 312.189114 -68.187316)
		(width 0.1143)
		(layer "B.Cu")
		(net "UPI_CPU1_CPU0_P0P0_DN<12>")
	)
	(segment
		(start 198.133462 -119.946928)
		(end 193.520314 -119.747792)
		(width 0.1143)
		(layer "B.Cu")
		(net "UPI_CPU1_CPU0_P0P0_DN<12>")
	)
	(segment
		(start 309.348632 -66.2178)
		(end 310.388254 -67.257422)
		(width 0.0889)
		(layer "B.Cu")
		(net "UPI_CPU1_CPU0_P0P0_DN<12>")
	)
	(segment
		(start 215.1634 -118.450106)
		(end 207.856074 -119.917464)
		(width 0.1143)
		(layer "B.Cu")
		(net "UPI_CPU1_CPU0_P0P0_DN<12>")
	)
	(segment
		(start 156.6672 -100.513896)
		(end 156.76626 -100.364036)
		(width 0.1143)
		(layer "B.Cu")
		(net "UPI_CPU1_CPU0_P0P0_DN<12>")
	)
	(segment
		(start 156.423868 -98.69678)
		(end 156.273754 -98.597974)
		(width 0.1143)
		(layer "B.Cu")
		(net "UPI_CPU1_CPU0_P0P0_DN<12>")
	)
	(segment
		(start 304.366676 -66.400934)
		(end 304.409856 -66.400934)
		(width 0.0889)
		(layer "B.Cu")
		(net "UPI_CPU1_CPU0_P0P0_DN<12>")
	)
	(segment
		(start 226.26447 -116.221002)
		(end 215.1634 -118.450106)
		(width 0.1143)
		(layer "B.Cu")
		(net "UPI_CPU1_CPU0_P0P0_DN<12>")
	)
	(segment
		(start 156.469842 -98.921062)
		(end 156.423868 -98.69678)
		(width 0.1143)
		(layer "B.Cu")
		(net "UPI_CPU1_CPU0_P0P0_DN<12>")
	)
	(segment
		(start 312.846974 -68.4276)
		(end 316.37351 -69.71538)
		(width 0.1143)
		(layer "B.Cu")
		(net "UPI_CPU1_CPU0_P0P0_DN<12>")
	)
	(segment
		(start 156.810202 -101.210618)
		(end 156.909008 -101.060758)
		(width 0.1143)
		(layer "B.Cu")
		(net "UPI_CPU1_CPU0_P0P0_DN<12>")
	)
	(segment
		(start 157.101794 -102.631748)
		(end 157.2006 -102.481888)
		(width 0.1143)
		(layer "B.Cu")
		(net "UPI_CPU1_CPU0_P0P0_DN<12>")
	)
	(segment
		(start 156.720286 -100.139754)
		(end 156.634434 -100.083366)
		(width 0.1143)
		(layer "B.Cu")
		(net "UPI_CPU1_CPU0_P0P0_DN<12>")
	)
	(segment
		(start 156.958792 -101.935026)
		(end 157.057852 -101.785166)
		(width 0.1143)
		(layer "B.Cu")
		(net "UPI_CPU1_CPU0_P0P0_DN<12>")
	)
	(segment
		(start 305.2318 -65.905888)
		(end 305.261772 -65.905888)
		(width 0.0889)
		(layer "B.Cu")
		(net "UPI_CPU1_CPU0_P0P0_DN<12>")
	)
	(segment
		(start 310.78424 -67.470274)
		(end 310.813704 -67.51447)
		(width 0.0889)
		(layer "B.Cu")
		(net "UPI_CPU1_CPU0_P0P0_DN<12>")
	)
	(segment
		(start 201.515726 -119.503444)
		(end 198.133462 -119.946928)
		(width 0.1143)
		(layer "B.Cu")
		(net "UPI_CPU1_CPU0_P0P0_DN<12>")
	)
	(segment
		(start 308.871874 -114.653568)
		(end 291.951918 -118.03634)
		(width 0.1143)
		(layer "B.Cu")
		(net "UPI_CPU1_CPU0_P0P0_DN<12>")
	)
	(segment
		(start 193.2178 -119.645938)
		(end 183.183784 -116.271548)
		(width 0.1143)
		(layer "B.Cu")
		(net "UPI_CPU1_CPU0_P0P0_DN<12>")
	)
	(segment
		(start 152.780746 -91.318334)
		(end 148.665184 -70.73773)
		(width 0.1143)
		(layer "B.Cu")
		(net "UPI_CPU1_CPU0_P0P0_DN<12>")
	)
	(segment
		(start 291.125402 -117.870986)
		(end 287.1216 -117.070124)
		(width 0.1143)
		(layer "B.Cu")
		(net "UPI_CPU1_CPU0_P0P0_DN<12>")
	)
	(segment
		(start 153.415746 -94.49308)
		(end 152.780746 -91.318334)
		(width 0.1143)
		(layer "B.Cu")
		(net "UPI_CPU1_CPU0_P0P0_DN<12>")
	)
	(segment
		(start 321.860164 -79.559658)
		(end 321.867276 -79.8322)
		(width 0.1143)
		(layer "B.Cu")
		(net "UPI_CPU1_CPU0_P0P0_DN<12>")
	)
	(segment
		(start 249.16892 -117.369082)
		(end 226.26447 -116.221002)
		(width 0.1143)
		(layer "B.Cu")
		(net "UPI_CPU1_CPU0_P0P0_DN<12>")
	)
	(segment
		(start 167.496744 -111.085884)
		(end 160.06572 -105.686098)
		(width 0.1143)
		(layer "B.Cu")
		(net "UPI_CPU1_CPU0_P0P0_DN<12>")
	)
	(segment
		(start 147.352004 -69.42455)
		(end 146.247104 -69.42455)
		(width 0.1143)
		(layer "B.Cu")
		(net "UPI_CPU1_CPU0_P0P0_DN<12>")
	)
	(segment
		(start 157.2006 -102.481888)
		(end 157.15488 -102.25786)
		(width 0.1143)
		(layer "B.Cu")
		(net "UPI_CPU1_CPU0_P0P0_DN<12>")
	)
	(arc
		(start 305.261772 -65.905888)
		(mid 305.453414 -65.963054)
		(end 305.593496 -66.105786)
		(width 0.0889)
		(layer "B.Cu")
		(net "UPI_CPU1_CPU0_P0P0_DN<12>")
	)
	(arc
		(start 305.593496 -66.105786)
		(mid 305.8005 -66.31665)
		(end 306.083716 -66.400934)
		(width 0.0889)
		(layer "B.Cu")
		(net "UPI_CPU1_CPU0_P0P0_DN<12>")
	)
	(arc
		(start 303.91227 -66.160904)
		(mid 304.112015 -66.332898)
		(end 304.366676 -66.400934)
		(width 0.0889)
		(layer "B.Cu")
		(net "UPI_CPU1_CPU0_P0P0_DN<12>")
	)
	(arc
		(start 304.900076 -66.105786)
		(mid 305.040155 -65.96305)
		(end 305.2318 -65.905888)
		(width 0.0889)
		(layer "B.Cu")
		(net "UPI_CPU1_CPU0_P0P0_DN<12>")
	)
	(arc
		(start 304.409856 -66.400934)
		(mid 304.693073 -66.316653)
		(end 304.900076 -66.105786)
		(width 0.0889)
		(layer "B.Cu")
		(net "UPI_CPU1_CPU0_P0P0_DN<12>")
	)
	(segment
		(start 302.099726 -65.810384)
		(end 302.671226 -65.810384)
		(width 0.1143)
		(layer "F.Cu")
		(net "UPI_CPU1_CPU0_P0P0_DN<11>")
	)
	(segment
		(start 140.533374 -67.791584)
		(end 141.104874 -67.791584)
		(width 0.1143)
		(layer "F.Cu")
		(net "UPI_CPU1_CPU0_P0P0_DN<11>")
	)
	(via
		(at 141.104874 -67.791584)
		(size 0.508)
		(drill 0.254)
		(layers "F.Cu" "B.Cu")
		(net "UPI_CPU1_CPU0_P0P0_DN<11>")
	)
	(via
		(at 302.671226 -65.810384)
		(size 0.508)
		(drill 0.254)
		(layers "F.Cu" "B.Cu")
		(net "UPI_CPU1_CPU0_P0P0_DN<11>")
	)
	(via
		(at 152.666446 -87.879174)
		(size 0.508)
		(drill 0.254)
		(layers "F.Cu" "B.Cu")
		(net "UPI_CPU1_CPU0_P0P0_DN<11>")
	)
	(segment
		(start 152.666446 -87.879174)
		(end 149.16912 -70.38467)
		(width 0.1143)
		(layer "B.Cu")
		(net "UPI_CPU1_CPU0_P0P0_DN<11>")
	)
	(segment
		(start 198.332598 -119.392446)
		(end 198.1708 -119.41429)
		(width 0.1143)
		(layer "B.Cu")
		(net "UPI_CPU1_CPU0_P0P0_DN<11>")
	)
	(segment
		(start 146.043904 -68.52285)
		(end 146.012154 -68.4911)
		(width 0.0889)
		(layer "B.Cu")
		(net "UPI_CPU1_CPU0_P0P0_DN<11>")
	)
	(segment
		(start 141.833854 -66.8528)
		(end 141.652752 -67.033902)
		(width 0.0889)
		(layer "B.Cu")
		(net "UPI_CPU1_CPU0_P0P0_DN<11>")
	)
	(segment
		(start 141.126464 -67.391534)
		(end 140.888466 -67.391534)
		(width 0.0889)
		(layer "B.Cu")
		(net "UPI_CPU1_CPU0_P0P0_DN<11>")
	)
	(segment
		(start 324.499224 -96.26473)
		(end 324.339204 -101.284786)
		(width 0.1143)
		(layer "B.Cu")
		(net "UPI_CPU1_CPU0_P0P0_DN<11>")
	)
	(segment
		(start 207.807306 -119.186452)
		(end 202.464924 -118.837456)
		(width 0.1143)
		(layer "B.Cu")
		(net "UPI_CPU1_CPU0_P0P0_DN<11>")
	)
	(segment
		(start 186.790838 -116.721382)
		(end 185.39079 -115.679728)
		(width 0.1143)
		(layer "B.Cu")
		(net "UPI_CPU1_CPU0_P0P0_DN<11>")
	)
	(segment
		(start 304.37328 -67.201034)
		(end 304.403252 -67.201034)
		(width 0.0889)
		(layer "B.Cu")
		(net "UPI_CPU1_CPU0_P0P0_DN<11>")
	)
	(segment
		(start 141.652752 -67.033902)
		(end 141.616684 -67.096386)
		(width 0.0889)
		(layer "B.Cu")
		(net "UPI_CPU1_CPU0_P0P0_DN<11>")
	)
	(segment
		(start 308.004718 -66.705988)
		(end 308.048406 -66.6623)
		(width 0.0889)
		(layer "B.Cu")
		(net "UPI_CPU1_CPU0_P0P0_DN<11>")
	)
	(segment
		(start 291.841174 -117.475)
		(end 291.125402 -117.332252)
		(width 0.1143)
		(layer "B.Cu")
		(net "UPI_CPU1_CPU0_P0P0_DN<11>")
	)
	(segment
		(start 262.902192 -114.997484)
		(end 249.146314 -116.640864)
		(width 0.1143)
		(layer "B.Cu")
		(net "UPI_CPU1_CPU0_P0P0_DN<11>")
	)
	(segment
		(start 302.671226 -66.148458)
		(end 302.736504 -66.213736)
		(width 0.0889)
		(layer "B.Cu")
		(net "UPI_CPU1_CPU0_P0P0_DN<11>")
	)
	(segment
		(start 198.1708 -119.41429)
		(end 194.295014 -119.244872)
		(width 0.1143)
		(layer "B.Cu")
		(net "UPI_CPU1_CPU0_P0P0_DN<11>")
	)
	(segment
		(start 320.987674 -79.8322)
		(end 321.041776 -81.915)
		(width 0.1143)
		(layer "B.Cu")
		(net "UPI_CPU1_CPU0_P0P0_DN<11>")
	)
	(segment
		(start 306.502308 -66.91503)
		(end 306.71135 -66.705988)
		(width 0.0889)
		(layer "B.Cu")
		(net "UPI_CPU1_CPU0_P0P0_DN<11>")
	)
	(segment
		(start 185.39079 -115.679728)
		(end 174.85614 -115.019328)
		(width 0.1143)
		(layer "B.Cu")
		(net "UPI_CPU1_CPU0_P0P0_DN<11>")
	)
	(segment
		(start 249.146314 -116.640864)
		(end 226.217226 -115.49126)
		(width 0.1143)
		(layer "B.Cu")
		(net "UPI_CPU1_CPU0_P0P0_DN<11>")
	)
	(segment
		(start 147.3073 -68.52285)
		(end 146.064224 -68.52285)
		(width 0.1143)
		(layer "B.Cu")
		(net "UPI_CPU1_CPU0_P0P0_DN<11>")
	)
	(segment
		(start 169.633646 -112.503712)
		(end 167.96385 -110.51286)
		(width 0.1143)
		(layer "B.Cu")
		(net "UPI_CPU1_CPU0_P0P0_DN<11>")
	)
	(segment
		(start 306.45227 -67.000882)
		(end 306.45227 -67.000628)
		(width 0.0889)
		(layer "B.Cu")
		(net "UPI_CPU1_CPU0_P0P0_DN<11>")
	)
	(segment
		(start 308.048406 -66.6623)
		(end 309.132986 -66.6623)
		(width 0.0889)
		(layer "B.Cu")
		(net "UPI_CPU1_CPU0_P0P0_DN<11>")
	)
	(segment
		(start 194.295014 -119.244872)
		(end 186.790838 -116.721382)
		(width 0.1143)
		(layer "B.Cu")
		(net "UPI_CPU1_CPU0_P0P0_DN<11>")
	)
	(segment
		(start 310.558942 -68.065142)
		(end 311.287668 -68.793868)
		(width 0.1143)
		(layer "B.Cu")
		(net "UPI_CPU1_CPU0_P0P0_DN<11>")
	)
	(segment
		(start 302.671226 -65.810384)
		(end 302.671226 -66.148458)
		(width 0.0889)
		(layer "B.Cu")
		(net "UPI_CPU1_CPU0_P0P0_DN<11>")
	)
	(segment
		(start 153.872184 -93.91142)
		(end 152.666446 -87.879174)
		(width 0.1143)
		(layer "B.Cu")
		(net "UPI_CPU1_CPU0_P0P0_DN<11>")
	)
	(segment
		(start 311.287668 -68.793868)
		(end 315.742066 -70.420738)
		(width 0.1143)
		(layer "B.Cu")
		(net "UPI_CPU1_CPU0_P0P0_DN<11>")
	)
	(segment
		(start 313.870848 -111.147098)
		(end 309.560468 -113.453418)
		(width 0.1143)
		(layer "B.Cu")
		(net "UPI_CPU1_CPU0_P0P0_DN<11>")
	)
	(segment
		(start 310.535828 -68.065142)
		(end 310.558942 -68.065142)
		(width 0.0889)
		(layer "B.Cu")
		(net "UPI_CPU1_CPU0_P0P0_DN<11>")
	)
	(segment
		(start 149.16912 -70.38467)
		(end 147.3073 -68.52285)
		(width 0.1143)
		(layer "B.Cu")
		(net "UPI_CPU1_CPU0_P0P0_DN<11>")
	)
	(segment
		(start 226.217226 -115.49126)
		(end 215.1634 -117.70995)
		(width 0.1143)
		(layer "B.Cu")
		(net "UPI_CPU1_CPU0_P0P0_DN<11>")
	)
	(segment
		(start 283.267912 -117.065806)
		(end 262.902192 -114.997484)
		(width 0.1143)
		(layer "B.Cu")
		(net "UPI_CPU1_CPU0_P0P0_DN<11>")
	)
	(segment
		(start 306.53863 -114.537236)
		(end 291.841174 -117.475)
		(width 0.1143)
		(layer "B.Cu")
		(net "UPI_CPU1_CPU0_P0P0_DN<11>")
	)
	(segment
		(start 306.09032 -67.201034)
		(end 306.122832 -67.201034)
		(width 0.0889)
		(layer "B.Cu")
		(net "UPI_CPU1_CPU0_P0P0_DN<11>")
	)
	(segment
		(start 174.85614 -115.019328)
		(end 173.04258 -114.471704)
		(width 0.1143)
		(layer "B.Cu")
		(net "UPI_CPU1_CPU0_P0P0_DN<11>")
	)
	(segment
		(start 146.064224 -68.52285)
		(end 146.043904 -68.52285)
		(width 0.0889)
		(layer "B.Cu")
		(net "UPI_CPU1_CPU0_P0P0_DN<11>")
	)
	(segment
		(start 306.452524 -67.000374)
		(end 306.502308 -66.91503)
		(width 0.0889)
		(layer "B.Cu")
		(net "UPI_CPU1_CPU0_P0P0_DN<11>")
	)
	(segment
		(start 173.04258 -114.471704)
		(end 169.633646 -112.503712)
		(width 0.1143)
		(layer "B.Cu")
		(net "UPI_CPU1_CPU0_P0P0_DN<11>")
	)
	(segment
		(start 159.40659 -103.810054)
		(end 158.103824 -102.719378)
		(width 0.1143)
		(layer "B.Cu")
		(net "UPI_CPU1_CPU0_P0P0_DN<11>")
	)
	(segment
		(start 306.71135 -66.705988)
		(end 308.004718 -66.705988)
		(width 0.0889)
		(layer "B.Cu")
		(net "UPI_CPU1_CPU0_P0P0_DN<11>")
	)
	(segment
		(start 309.560468 -113.453418)
		(end 306.53863 -114.537236)
		(width 0.1143)
		(layer "B.Cu")
		(net "UPI_CPU1_CPU0_P0P0_DN<11>")
	)
	(segment
		(start 160.362138 -104.990138)
		(end 159.40659 -103.810054)
		(width 0.1143)
		(layer "B.Cu")
		(net "UPI_CPU1_CPU0_P0P0_DN<11>")
	)
	(segment
		(start 321.200526 -88.017604)
		(end 324.499224 -96.26473)
		(width 0.1143)
		(layer "B.Cu")
		(net "UPI_CPU1_CPU0_P0P0_DN<11>")
	)
	(segment
		(start 309.132986 -66.6623)
		(end 310.535828 -68.065142)
		(width 0.0889)
		(layer "B.Cu")
		(net "UPI_CPU1_CPU0_P0P0_DN<11>")
	)
	(segment
		(start 215.1634 -117.70995)
		(end 207.807306 -119.186452)
		(width 0.1143)
		(layer "B.Cu")
		(net "UPI_CPU1_CPU0_P0P0_DN<11>")
	)
	(segment
		(start 157.040326 -97.532698)
		(end 153.872184 -93.91142)
		(width 0.1143)
		(layer "B.Cu")
		(net "UPI_CPU1_CPU0_P0P0_DN<11>")
	)
	(segment
		(start 158.103824 -102.719378)
		(end 157.040326 -97.532698)
		(width 0.1143)
		(layer "B.Cu")
		(net "UPI_CPU1_CPU0_P0P0_DN<11>")
	)
	(segment
		(start 306.45227 -67.000628)
		(end 306.452524 -67.000374)
		(width 0.0889)
		(layer "B.Cu")
		(net "UPI_CPU1_CPU0_P0P0_DN<11>")
	)
	(segment
		(start 141.045184 -67.791584)
		(end 141.104874 -67.791584)
		(width 0.0889)
		(layer "B.Cu")
		(net "UPI_CPU1_CPU0_P0P0_DN<11>")
	)
	(segment
		(start 167.96385 -110.51286)
		(end 160.362138 -104.990138)
		(width 0.1143)
		(layer "B.Cu")
		(net "UPI_CPU1_CPU0_P0P0_DN<11>")
	)
	(segment
		(start 306.452016 -67.001136)
		(end 306.45227 -67.000882)
		(width 0.0889)
		(layer "B.Cu")
		(net "UPI_CPU1_CPU0_P0P0_DN<11>")
	)
	(segment
		(start 145.66646 -68.4911)
		(end 144.02816 -66.8528)
		(width 0.0889)
		(layer "B.Cu")
		(net "UPI_CPU1_CPU0_P0P0_DN<11>")
	)
	(segment
		(start 291.125402 -117.332252)
		(end 286.525462 -116.414296)
		(width 0.1143)
		(layer "B.Cu")
		(net "UPI_CPU1_CPU0_P0P0_DN<11>")
	)
	(segment
		(start 303.51857 -66.705988)
		(end 303.551336 -66.705988)
		(width 0.0889)
		(layer "B.Cu")
		(net "UPI_CPU1_CPU0_P0P0_DN<11>")
	)
	(segment
		(start 324.339204 -101.284786)
		(end 313.870848 -111.147098)
		(width 0.1143)
		(layer "B.Cu")
		(net "UPI_CPU1_CPU0_P0P0_DN<11>")
	)
	(segment
		(start 144.02816 -66.8528)
		(end 141.833854 -66.8528)
		(width 0.0889)
		(layer "B.Cu")
		(net "UPI_CPU1_CPU0_P0P0_DN<11>")
	)
	(segment
		(start 286.525462 -116.414296)
		(end 283.267912 -117.065806)
		(width 0.1143)
		(layer "B.Cu")
		(net "UPI_CPU1_CPU0_P0P0_DN<11>")
	)
	(segment
		(start 315.742066 -70.420738)
		(end 320.987674 -79.8322)
		(width 0.1143)
		(layer "B.Cu")
		(net "UPI_CPU1_CPU0_P0P0_DN<11>")
	)
	(segment
		(start 305.225196 -66.705988)
		(end 305.268376 -66.705988)
		(width 0.0889)
		(layer "B.Cu")
		(net "UPI_CPU1_CPU0_P0P0_DN<11>")
	)
	(segment
		(start 321.041776 -81.915)
		(end 321.200526 -88.017604)
		(width 0.1143)
		(layer "B.Cu")
		(net "UPI_CPU1_CPU0_P0P0_DN<11>")
	)
	(segment
		(start 202.464924 -118.837456)
		(end 198.332598 -119.392446)
		(width 0.1143)
		(layer "B.Cu")
		(net "UPI_CPU1_CPU0_P0P0_DN<11>")
	)
	(segment
		(start 146.012154 -68.4911)
		(end 145.66646 -68.4911)
		(width 0.0889)
		(layer "B.Cu")
		(net "UPI_CPU1_CPU0_P0P0_DN<11>")
	)
	(arc
		(start 305.268376 -66.705988)
		(mid 305.551593 -66.790269)
		(end 305.758596 -67.001136)
		(width 0.0889)
		(layer "B.Cu")
		(net "UPI_CPU1_CPU0_P0P0_DN<11>")
	)
	(arc
		(start 304.403252 -67.201034)
		(mid 304.594894 -67.143868)
		(end 304.734976 -67.001136)
		(width 0.0889)
		(layer "B.Cu")
		(net "UPI_CPU1_CPU0_P0P0_DN<11>")
	)
	(arc
		(start 141.616684 -67.096386)
		(mid 141.40968 -67.30725)
		(end 141.126464 -67.391534)
		(width 0.0889)
		(layer "B.Cu")
		(net "UPI_CPU1_CPU0_P0P0_DN<11>")
	)
	(arc
		(start 303.551336 -66.705988)
		(mid 303.834553 -66.790269)
		(end 304.041556 -67.001136)
		(width 0.0889)
		(layer "B.Cu")
		(net "UPI_CPU1_CPU0_P0P0_DN<11>")
	)
	(arc
		(start 305.758596 -67.001136)
		(mid 305.898675 -67.143872)
		(end 306.09032 -67.201034)
		(width 0.0889)
		(layer "B.Cu")
		(net "UPI_CPU1_CPU0_P0P0_DN<11>")
	)
	(arc
		(start 306.122832 -67.201034)
		(mid 306.313074 -67.143299)
		(end 306.452016 -67.001136)
		(width 0.0889)
		(layer "B.Cu")
		(net "UPI_CPU1_CPU0_P0P0_DN<11>")
	)
	(arc
		(start 304.734976 -67.001136)
		(mid 304.94198 -66.790272)
		(end 305.225196 -66.705988)
		(width 0.0889)
		(layer "B.Cu")
		(net "UPI_CPU1_CPU0_P0P0_DN<11>")
	)
	(arc
		(start 140.888466 -67.391534)
		(mid 140.802435 -67.427169)
		(end 140.7668 -67.5132)
		(width 0.0889)
		(layer "B.Cu")
		(net "UPI_CPU1_CPU0_P0P0_DN<11>")
	)
	(arc
		(start 303.183036 -66.505836)
		(mid 303.324719 -66.64964)
		(end 303.51857 -66.705988)
		(width 0.0889)
		(layer "B.Cu")
		(net "UPI_CPU1_CPU0_P0P0_DN<11>")
	)
	(arc
		(start 304.041556 -67.001136)
		(mid 304.181635 -67.143872)
		(end 304.37328 -67.201034)
		(width 0.0889)
		(layer "B.Cu")
		(net "UPI_CPU1_CPU0_P0P0_DN<11>")
	)
	(arc
		(start 302.736504 -66.213736)
		(mid 302.994641 -66.30649)
		(end 303.183036 -66.505836)
		(width 0.0889)
		(layer "B.Cu")
		(net "UPI_CPU1_CPU0_P0P0_DN<11>")
	)
	(arc
		(start 140.7668 -67.5132)
		(mid 140.848337 -67.710047)
		(end 141.045184 -67.791584)
		(width 0.0889)
		(layer "B.Cu")
		(net "UPI_CPU1_CPU0_P0P0_DN<11>")
	)
	(segment
		(start 300.382686 -66.800984)
		(end 300.954186 -66.800984)
		(width 0.1143)
		(layer "F.Cu")
		(net "UPI_CPU1_CPU0_P0P0_DN<10>")
	)
	(segment
		(start 140.533374 -65.810384)
		(end 141.104874 -65.810384)
		(width 0.1143)
		(layer "F.Cu")
		(net "UPI_CPU1_CPU0_P0P0_DN<10>")
	)
	(via
		(at 300.954186 -66.800984)
		(size 0.508)
		(drill 0.254)
		(layers "F.Cu" "B.Cu")
		(net "UPI_CPU1_CPU0_P0P0_DN<10>")
	)
	(via
		(at 141.104874 -65.810384)
		(size 0.508)
		(drill 0.254)
		(layers "F.Cu" "B.Cu")
		(net "UPI_CPU1_CPU0_P0P0_DN<10>")
	)
	(segment
		(start 311.598818 -70.356984)
		(end 311.436004 -70.43293)
		(width 0.1143)
		(layer "B.Cu")
		(net "UPI_CPU1_CPU0_P0P0_DN<10>")
	)
	(segment
		(start 145.5547 -67.2465)
		(end 145.918174 -67.2465)
		(width 0.0889)
		(layer "B.Cu")
		(net "UPI_CPU1_CPU0_P0P0_DN<10>")
	)
	(segment
		(start 147.810474 -67.21475)
		(end 149.99843 -69.402706)
		(width 0.1143)
		(layer "B.Cu")
		(net "UPI_CPU1_CPU0_P0P0_DN<10>")
	)
	(segment
		(start 312.661046 -110.414562)
		(end 322.996052 -100.678234)
		(width 0.1143)
		(layer "B.Cu")
		(net "UPI_CPU1_CPU0_P0P0_DN<10>")
	)
	(segment
		(start 283.17571 -115.84051)
		(end 286.032194 -115.269518)
		(width 0.1143)
		(layer "B.Cu")
		(net "UPI_CPU1_CPU0_P0P0_DN<10>")
	)
	(segment
		(start 307.97754 -68.81114)
		(end 307.97754 -68.301362)
		(width 0.1143)
		(layer "B.Cu")
		(net "UPI_CPU1_CPU0_P0P0_DN<10>")
	)
	(segment
		(start 311.22112 -70.354444)
		(end 311.145428 -70.191376)
		(width 0.1143)
		(layer "B.Cu")
		(net "UPI_CPU1_CPU0_P0P0_DN<10>")
	)
	(segment
		(start 158.515812 -97.381822)
		(end 158.81604 -98.846132)
		(width 0.1143)
		(layer "B.Cu")
		(net "UPI_CPU1_CPU0_P0P0_DN<10>")
	)
	(segment
		(start 168.695878 -109.503972)
		(end 170.424094 -111.56315)
		(width 0.1143)
		(layer "B.Cu")
		(net "UPI_CPU1_CPU0_P0P0_DN<10>")
	)
	(segment
		(start 312.104024 -70.67677)
		(end 311.88914 -70.598284)
		(width 0.1143)
		(layer "B.Cu")
		(net "UPI_CPU1_CPU0_P0P0_DN<10>")
	)
	(segment
		(start 159.298132 -100.562918)
		(end 159.199326 -100.712778)
		(width 0.1143)
		(layer "B.Cu")
		(net "UPI_CPU1_CPU0_P0P0_DN<10>")
	)
	(segment
		(start 304.965354 -113.798096)
		(end 309.133748 -112.302798)
		(width 0.1143)
		(layer "B.Cu")
		(net "UPI_CPU1_CPU0_P0P0_DN<10>")
	)
	(segment
		(start 308.66842 -69.50202)
		(end 307.97754 -68.81114)
		(width 0.1143)
		(layer "B.Cu")
		(net "UPI_CPU1_CPU0_P0P0_DN<10>")
	)
	(segment
		(start 159.056324 -100.016056)
		(end 159.102044 -100.23983)
		(width 0.1143)
		(layer "B.Cu")
		(net "UPI_CPU1_CPU0_P0P0_DN<10>")
	)
	(segment
		(start 307.23078 -67.912488)
		(end 307.20538 -67.887088)
		(width 0.0889)
		(layer "B.Cu")
		(net "UPI_CPU1_CPU0_P0P0_DN<10>")
	)
	(segment
		(start 159.142684 -99.805236)
		(end 159.15513 -99.866196)
		(width 0.1143)
		(layer "B.Cu")
		(net "UPI_CPU1_CPU0_P0P0_DN<10>")
	)
	(segment
		(start 310.489346 -70.086982)
		(end 310.413654 -69.923914)
		(width 0.1143)
		(layer "B.Cu")
		(net "UPI_CPU1_CPU0_P0P0_DN<10>")
	)
	(segment
		(start 309.755794 -69.68363)
		(end 308.66842 -69.50202)
		(width 0.1143)
		(layer "B.Cu")
		(net "UPI_CPU1_CPU0_P0P0_DN<10>")
	)
	(segment
		(start 141.805406 -66.0527)
		(end 144.3609 -66.0527)
		(width 0.0889)
		(layer "B.Cu")
		(net "UPI_CPU1_CPU0_P0P0_DN<10>")
	)
	(segment
		(start 226.120706 -114.275616)
		(end 249.024648 -115.42395)
		(width 0.1143)
		(layer "B.Cu")
		(net "UPI_CPU1_CPU0_P0P0_DN<10>")
	)
	(segment
		(start 170.424094 -111.56315)
		(end 173.52137 -113.348008)
		(width 0.1143)
		(layer "B.Cu")
		(net "UPI_CPU1_CPU0_P0P0_DN<10>")
	)
	(segment
		(start 173.52137 -113.348008)
		(end 175.095408 -113.822226)
		(width 0.1143)
		(layer "B.Cu")
		(net "UPI_CPU1_CPU0_P0P0_DN<10>")
	)
	(segment
		(start 305.261772 -67.887088)
		(end 305.2318 -67.887088)
		(width 0.0889)
		(layer "B.Cu")
		(net "UPI_CPU1_CPU0_P0P0_DN<10>")
	)
	(segment
		(start 291.125402 -116.288058)
		(end 291.817298 -116.426488)
		(width 0.1143)
		(layer "B.Cu")
		(net "UPI_CPU1_CPU0_P0P0_DN<10>")
	)
	(segment
		(start 185.452766 -114.471704)
		(end 187.23483 -115.798092)
		(width 0.1143)
		(layer "B.Cu")
		(net "UPI_CPU1_CPU0_P0P0_DN<10>")
	)
	(segment
		(start 314.821824 -71.534274)
		(end 312.267092 -70.601078)
		(width 0.1143)
		(layer "B.Cu")
		(net "UPI_CPU1_CPU0_P0P0_DN<10>")
	)
	(segment
		(start 158.966154 -98.945192)
		(end 159.012128 -99.16922)
		(width 0.1143)
		(layer "B.Cu")
		(net "UPI_CPU1_CPU0_P0P0_DN<10>")
	)
	(segment
		(start 303.544732 -67.887088)
		(end 303.511966 -67.887088)
		(width 0.0889)
		(layer "B.Cu")
		(net "UPI_CPU1_CPU0_P0P0_DN<10>")
	)
	(segment
		(start 159.10941 -99.642168)
		(end 159.110172 -99.645978)
		(width 0.1143)
		(layer "B.Cu")
		(net "UPI_CPU1_CPU0_P0P0_DN<10>")
	)
	(segment
		(start 311.88914 -70.598284)
		(end 311.813448 -70.435216)
		(width 0.1143)
		(layer "B.Cu")
		(net "UPI_CPU1_CPU0_P0P0_DN<10>")
	)
	(segment
		(start 159.199326 -100.712778)
		(end 159.245046 -100.936552)
		(width 0.1143)
		(layer "B.Cu")
		(net "UPI_CPU1_CPU0_P0P0_DN<10>")
	)
	(segment
		(start 158.959042 -99.543108)
		(end 159.10941 -99.642168)
		(width 0.1143)
		(layer "B.Cu")
		(net "UPI_CPU1_CPU0_P0P0_DN<10>")
	)
	(segment
		(start 149.99843 -69.402706)
		(end 154.72791 -93.053408)
		(width 0.1143)
		(layer "B.Cu")
		(net "UPI_CPU1_CPU0_P0P0_DN<10>")
	)
	(segment
		(start 207.727296 -117.96903)
		(end 215.1634 -116.475764)
		(width 0.1143)
		(layer "B.Cu")
		(net "UPI_CPU1_CPU0_P0P0_DN<10>")
	)
	(segment
		(start 309.133748 -112.302798)
		(end 312.661046 -110.414562)
		(width 0.1143)
		(layer "B.Cu")
		(net "UPI_CPU1_CPU0_P0P0_DN<10>")
	)
	(segment
		(start 159.012128 -99.16922)
		(end 158.913322 -99.319334)
		(width 0.1143)
		(layer "B.Cu")
		(net "UPI_CPU1_CPU0_P0P0_DN<10>")
	)
	(segment
		(start 311.813448 -70.435216)
		(end 311.598818 -70.356984)
		(width 0.1143)
		(layer "B.Cu")
		(net "UPI_CPU1_CPU0_P0P0_DN<10>")
	)
	(segment
		(start 159.102044 -100.23983)
		(end 159.110172 -100.245164)
		(width 0.1143)
		(layer "B.Cu")
		(net "UPI_CPU1_CPU0_P0P0_DN<10>")
	)
	(segment
		(start 198.083424 -118.403116)
		(end 203.46797 -117.691408)
		(width 0.1143)
		(layer "B.Cu")
		(net "UPI_CPU1_CPU0_P0P0_DN<10>")
	)
	(segment
		(start 141.691106 -66.167)
		(end 141.805406 -66.0527)
		(width 0.0889)
		(layer "B.Cu")
		(net "UPI_CPU1_CPU0_P0P0_DN<10>")
	)
	(segment
		(start 154.72791 -93.053408)
		(end 158.515812 -97.381822)
		(width 0.1143)
		(layer "B.Cu")
		(net "UPI_CPU1_CPU0_P0P0_DN<10>")
	)
	(segment
		(start 307.97754 -68.301362)
		(end 307.588666 -67.912488)
		(width 0.1143)
		(layer "B.Cu")
		(net "UPI_CPU1_CPU0_P0P0_DN<10>")
	)
	(segment
		(start 215.1634 -116.475764)
		(end 226.120706 -114.275616)
		(width 0.1143)
		(layer "B.Cu")
		(net "UPI_CPU1_CPU0_P0P0_DN<10>")
	)
	(segment
		(start 187.23483 -115.798092)
		(end 194.518788 -118.247414)
		(width 0.1143)
		(layer "B.Cu")
		(net "UPI_CPU1_CPU0_P0P0_DN<10>")
	)
	(segment
		(start 310.70423 -70.165468)
		(end 310.489346 -70.086982)
		(width 0.1143)
		(layer "B.Cu")
		(net "UPI_CPU1_CPU0_P0P0_DN<10>")
	)
	(segment
		(start 175.095408 -113.822226)
		(end 179.569618 -114.102896)
		(width 0.1143)
		(layer "B.Cu")
		(net "UPI_CPU1_CPU0_P0P0_DN<10>")
	)
	(segment
		(start 159.252158 -100.33889)
		(end 159.298132 -100.562918)
		(width 0.1143)
		(layer "B.Cu")
		(net "UPI_CPU1_CPU0_P0P0_DN<10>")
	)
	(segment
		(start 311.436004 -70.43293)
		(end 311.22112 -70.354444)
		(width 0.1143)
		(layer "B.Cu")
		(net "UPI_CPU1_CPU0_P0P0_DN<10>")
	)
	(segment
		(start 159.142684 -99.884992)
		(end 159.110172 -99.934268)
		(width 0.1143)
		(layer "B.Cu")
		(net "UPI_CPU1_CPU0_P0P0_DN<10>")
	)
	(segment
		(start 322.996052 -100.678234)
		(end 323.130418 -96.477074)
		(width 0.1143)
		(layer "B.Cu")
		(net "UPI_CPU1_CPU0_P0P0_DN<10>")
	)
	(segment
		(start 141.104874 -65.810384)
		(end 141.46149 -66.167)
		(width 0.0889)
		(layer "B.Cu")
		(net "UPI_CPU1_CPU0_P0P0_DN<10>")
	)
	(segment
		(start 306.107338 -68.381372)
		(end 306.103274 -68.381372)
		(width 0.0889)
		(layer "B.Cu")
		(net "UPI_CPU1_CPU0_P0P0_DN<10>")
	)
	(segment
		(start 194.518788 -118.247414)
		(end 198.083424 -118.403116)
		(width 0.1143)
		(layer "B.Cu")
		(net "UPI_CPU1_CPU0_P0P0_DN<10>")
	)
	(segment
		(start 158.81604 -98.846132)
		(end 158.966154 -98.945192)
		(width 0.1143)
		(layer "B.Cu")
		(net "UPI_CPU1_CPU0_P0P0_DN<10>")
	)
	(segment
		(start 286.032194 -115.269518)
		(end 291.125402 -116.288058)
		(width 0.1143)
		(layer "B.Cu")
		(net "UPI_CPU1_CPU0_P0P0_DN<10>")
	)
	(segment
		(start 144.3609 -66.0527)
		(end 145.5547 -67.2465)
		(width 0.0889)
		(layer "B.Cu")
		(net "UPI_CPU1_CPU0_P0P0_DN<10>")
	)
	(segment
		(start 203.46797 -117.691408)
		(end 207.727296 -117.96903)
		(width 0.1143)
		(layer "B.Cu")
		(net "UPI_CPU1_CPU0_P0P0_DN<10>")
	)
	(segment
		(start 310.413654 -69.923914)
		(end 309.755794 -69.68363)
		(width 0.1143)
		(layer "B.Cu")
		(net "UPI_CPU1_CPU0_P0P0_DN<10>")
	)
	(segment
		(start 319.845182 -88.29548)
		(end 319.679574 -81.915)
		(width 0.1143)
		(layer "B.Cu")
		(net "UPI_CPU1_CPU0_P0P0_DN<10>")
	)
	(segment
		(start 307.20538 -67.887088)
		(end 306.963318 -67.887088)
		(width 0.0889)
		(layer "B.Cu")
		(net "UPI_CPU1_CPU0_P0P0_DN<10>")
	)
	(segment
		(start 310.867298 -70.089776)
		(end 310.70423 -70.165468)
		(width 0.1143)
		(layer "B.Cu")
		(net "UPI_CPU1_CPU0_P0P0_DN<10>")
	)
	(segment
		(start 159.39516 -101.035612)
		(end 159.441134 -101.25964)
		(width 0.1143)
		(layer "B.Cu")
		(net "UPI_CPU1_CPU0_P0P0_DN<10>")
	)
	(segment
		(start 159.15513 -99.866196)
		(end 159.142684 -99.884992)
		(width 0.1143)
		(layer "B.Cu")
		(net "UPI_CPU1_CPU0_P0P0_DN<10>")
	)
	(segment
		(start 159.110172 -99.645978)
		(end 159.142684 -99.805236)
		(width 0.1143)
		(layer "B.Cu")
		(net "UPI_CPU1_CPU0_P0P0_DN<10>")
	)
	(segment
		(start 311.145428 -70.191376)
		(end 310.867298 -70.089776)
		(width 0.1143)
		(layer "B.Cu")
		(net "UPI_CPU1_CPU0_P0P0_DN<10>")
	)
	(segment
		(start 145.949924 -67.21475)
		(end 147.810474 -67.21475)
		(width 0.1143)
		(layer "B.Cu")
		(net "UPI_CPU1_CPU0_P0P0_DN<10>")
	)
	(segment
		(start 291.817298 -116.426488)
		(end 304.965354 -113.798096)
		(width 0.1143)
		(layer "B.Cu")
		(net "UPI_CPU1_CPU0_P0P0_DN<10>")
	)
	(segment
		(start 301.830232 -66.896488)
		(end 301.184818 -66.896488)
		(width 0.0889)
		(layer "B.Cu")
		(net "UPI_CPU1_CPU0_P0P0_DN<10>")
	)
	(segment
		(start 159.110172 -100.245164)
		(end 159.142684 -100.266754)
		(width 0.1143)
		(layer "B.Cu")
		(net "UPI_CPU1_CPU0_P0P0_DN<10>")
	)
	(segment
		(start 323.130418 -96.477074)
		(end 322.79971 -95.653352)
		(width 0.1143)
		(layer "B.Cu")
		(net "UPI_CPU1_CPU0_P0P0_DN<10>")
	)
	(segment
		(start 179.569618 -114.102896)
		(end 185.452766 -114.471704)
		(width 0.1143)
		(layer "B.Cu")
		(net "UPI_CPU1_CPU0_P0P0_DN<10>")
	)
	(segment
		(start 262.898128 -113.78184)
		(end 283.17571 -115.84051)
		(width 0.1143)
		(layer "B.Cu")
		(net "UPI_CPU1_CPU0_P0P0_DN<10>")
	)
	(segment
		(start 312.267092 -70.601078)
		(end 312.104024 -70.67677)
		(width 0.1143)
		(layer "B.Cu")
		(net "UPI_CPU1_CPU0_P0P0_DN<10>")
	)
	(segment
		(start 307.252878 -67.912488)
		(end 307.23078 -67.912488)
		(width 0.0889)
		(layer "B.Cu")
		(net "UPI_CPU1_CPU0_P0P0_DN<10>")
	)
	(segment
		(start 304.409856 -68.382134)
		(end 304.366676 -68.382134)
		(width 0.0889)
		(layer "B.Cu")
		(net "UPI_CPU1_CPU0_P0P0_DN<10>")
	)
	(segment
		(start 319.634108 -80.169004)
		(end 314.821824 -71.534274)
		(width 0.1143)
		(layer "B.Cu")
		(net "UPI_CPU1_CPU0_P0P0_DN<10>")
	)
	(segment
		(start 159.441134 -101.25964)
		(end 159.342074 -101.409754)
		(width 0.1143)
		(layer "B.Cu")
		(net "UPI_CPU1_CPU0_P0P0_DN<10>")
	)
	(segment
		(start 159.245046 -100.936552)
		(end 159.39516 -101.035612)
		(width 0.1143)
		(layer "B.Cu")
		(net "UPI_CPU1_CPU0_P0P0_DN<10>")
	)
	(segment
		(start 249.024648 -115.42395)
		(end 262.898128 -113.78184)
		(width 0.1143)
		(layer "B.Cu")
		(net "UPI_CPU1_CPU0_P0P0_DN<10>")
	)
	(segment
		(start 141.46149 -66.167)
		(end 141.691106 -66.167)
		(width 0.0889)
		(layer "B.Cu")
		(net "UPI_CPU1_CPU0_P0P0_DN<10>")
	)
	(segment
		(start 161.10839 -103.990394)
		(end 168.695878 -109.503972)
		(width 0.1143)
		(layer "B.Cu")
		(net "UPI_CPU1_CPU0_P0P0_DN<10>")
	)
	(segment
		(start 307.588666 -67.912488)
		(end 307.252878 -67.912488)
		(width 0.1143)
		(layer "B.Cu")
		(net "UPI_CPU1_CPU0_P0P0_DN<10>")
	)
	(segment
		(start 158.913322 -99.319334)
		(end 158.959042 -99.543108)
		(width 0.1143)
		(layer "B.Cu")
		(net "UPI_CPU1_CPU0_P0P0_DN<10>")
	)
	(segment
		(start 145.918174 -67.2465)
		(end 145.949924 -67.21475)
		(width 0.0889)
		(layer "B.Cu")
		(net "UPI_CPU1_CPU0_P0P0_DN<10>")
	)
	(segment
		(start 302.682402 -67.391534)
		(end 302.649636 -67.391534)
		(width 0.0889)
		(layer "B.Cu")
		(net "UPI_CPU1_CPU0_P0P0_DN<10>")
	)
	(segment
		(start 159.342074 -101.409754)
		(end 159.451548 -101.94417)
		(width 0.1143)
		(layer "B.Cu")
		(net "UPI_CPU1_CPU0_P0P0_DN<10>")
	)
	(segment
		(start 319.679574 -81.915)
		(end 319.634108 -80.169004)
		(width 0.1143)
		(layer "B.Cu")
		(net "UPI_CPU1_CPU0_P0P0_DN<10>")
	)
	(segment
		(start 159.451548 -101.94417)
		(end 161.10839 -103.990394)
		(width 0.1143)
		(layer "B.Cu")
		(net "UPI_CPU1_CPU0_P0P0_DN<10>")
	)
	(segment
		(start 159.142684 -100.266754)
		(end 159.252158 -100.33889)
		(width 0.1143)
		(layer "B.Cu")
		(net "UPI_CPU1_CPU0_P0P0_DN<10>")
	)
	(segment
		(start 322.79971 -95.653352)
		(end 319.845182 -88.29548)
		(width 0.1143)
		(layer "B.Cu")
		(net "UPI_CPU1_CPU0_P0P0_DN<10>")
	)
	(segment
		(start 159.110172 -99.934268)
		(end 159.056324 -100.016056)
		(width 0.1143)
		(layer "B.Cu")
		(net "UPI_CPU1_CPU0_P0P0_DN<10>")
	)
	(arc
		(start 305.593496 -68.086986)
		(mid 305.453417 -67.94425)
		(end 305.261772 -67.887088)
		(width 0.0889)
		(layer "B.Cu")
		(net "UPI_CPU1_CPU0_P0P0_DN<10>")
	)
	(arc
		(start 305.2318 -67.887088)
		(mid 305.040158 -67.944254)
		(end 304.900076 -68.086986)
		(width 0.0889)
		(layer "B.Cu")
		(net "UPI_CPU1_CPU0_P0P0_DN<10>")
	)
	(arc
		(start 304.900076 -68.086986)
		(mid 304.693072 -68.29785)
		(end 304.409856 -68.382134)
		(width 0.0889)
		(layer "B.Cu")
		(net "UPI_CPU1_CPU0_P0P0_DN<10>")
	)
	(arc
		(start 306.103274 -68.381372)
		(mid 305.808944 -68.302485)
		(end 305.593496 -68.086986)
		(width 0.0889)
		(layer "B.Cu")
		(net "UPI_CPU1_CPU0_P0P0_DN<10>")
	)
	(arc
		(start 303.511966 -67.887088)
		(mid 303.226542 -67.803621)
		(end 303.017936 -67.591686)
		(width 0.0889)
		(layer "B.Cu")
		(net "UPI_CPU1_CPU0_P0P0_DN<10>")
	)
	(arc
		(start 302.159416 -67.096386)
		(mid 302.020423 -66.954306)
		(end 301.830232 -66.896488)
		(width 0.0889)
		(layer "B.Cu")
		(net "UPI_CPU1_CPU0_P0P0_DN<10>")
	)
	(arc
		(start 306.617116 -68.086986)
		(mid 306.401682 -68.30251)
		(end 306.107338 -68.381372)
		(width 0.0889)
		(layer "B.Cu")
		(net "UPI_CPU1_CPU0_P0P0_DN<10>")
	)
	(arc
		(start 303.017936 -67.591686)
		(mid 302.876253 -67.447882)
		(end 302.682402 -67.391534)
		(width 0.0889)
		(layer "B.Cu")
		(net "UPI_CPU1_CPU0_P0P0_DN<10>")
	)
	(arc
		(start 302.649636 -67.391534)
		(mid 302.366419 -67.307253)
		(end 302.159416 -67.096386)
		(width 0.0889)
		(layer "B.Cu")
		(net "UPI_CPU1_CPU0_P0P0_DN<10>")
	)
	(arc
		(start 306.963318 -67.887088)
		(mid 306.763459 -67.940668)
		(end 306.617116 -68.086986)
		(width 0.0889)
		(layer "B.Cu")
		(net "UPI_CPU1_CPU0_P0P0_DN<10>")
	)
	(arc
		(start 304.366676 -68.382134)
		(mid 304.083459 -68.297853)
		(end 303.876456 -68.086986)
		(width 0.0889)
		(layer "B.Cu")
		(net "UPI_CPU1_CPU0_P0P0_DN<10>")
	)
	(arc
		(start 303.876456 -68.086986)
		(mid 303.736377 -67.94425)
		(end 303.544732 -67.887088)
		(width 0.0889)
		(layer "B.Cu")
		(net "UPI_CPU1_CPU0_P0P0_DN<10>")
	)
	(arc
		(start 301.184818 -66.896488)
		(mid 301.060011 -66.871662)
		(end 300.954186 -66.800984)
		(width 0.0889)
		(layer "B.Cu")
		(net "UPI_CPU1_CPU0_P0P0_DN<10>")
	)
	(segment
		(start 298.665646 -71.753984)
		(end 299.237146 -71.753984)
		(width 0.1143)
		(layer "F.Cu")
		(net "UPI_CPU1_CPU0_P0P0_DN<0>")
	)
	(segment
		(start 142.250414 -56.894984)
		(end 142.904464 -56.894984)
		(width 0.1143)
		(layer "F.Cu")
		(net "UPI_CPU1_CPU0_P0P0_DN<0>")
	)
	(via
		(at 142.904464 -56.894984)
		(size 0.508)
		(drill 0.254)
		(layers "F.Cu" "B.Cu")
		(net "UPI_CPU1_CPU0_P0P0_DN<0>")
	)
	(via
		(at 299.237146 -71.753984)
		(size 0.508)
		(drill 0.254)
		(layers "F.Cu" "B.Cu")
		(net "UPI_CPU1_CPU0_P0P0_DN<0>")
	)
	(segment
		(start 304.503328 -104.143048)
		(end 307.32603 -100.927662)
		(width 0.1143)
		(layer "B.Cu")
		(net "UPI_CPU1_CPU0_P0P0_DN<0>")
	)
	(segment
		(start 242.48237 -101.221794)
		(end 245.69547 -101.32441)
		(width 0.1143)
		(layer "B.Cu")
		(net "UPI_CPU1_CPU0_P0P0_DN<0>")
	)
	(segment
		(start 284.016958 -104.504236)
		(end 285.271464 -104.253538)
		(width 0.1143)
		(layer "B.Cu")
		(net "UPI_CPU1_CPU0_P0P0_DN<0>")
	)
	(segment
		(start 257.303778 -102.245668)
		(end 257.14452 -102.531418)
		(width 0.1143)
		(layer "B.Cu")
		(net "UPI_CPU1_CPU0_P0P0_DN<0>")
	)
	(segment
		(start 292.140386 -102.880668)
		(end 298.288456 -104.110028)
		(width 0.1143)
		(layer "B.Cu")
		(net "UPI_CPU1_CPU0_P0P0_DN<0>")
	)
	(segment
		(start 258.114292 -102.69728)
		(end 258.46151 -102.597712)
		(width 0.1143)
		(layer "B.Cu")
		(net "UPI_CPU1_CPU0_P0P0_DN<0>")
	)
	(segment
		(start 185.503058 -104.433624)
		(end 193.127122 -105.79481)
		(width 0.1143)
		(layer "B.Cu")
		(net "UPI_CPU1_CPU0_P0P0_DN<0>")
	)
	(segment
		(start 201.826368 -109.275626)
		(end 215.1634 -106.596434)
		(width 0.1143)
		(layer "B.Cu")
		(net "UPI_CPU1_CPU0_P0P0_DN<0>")
	)
	(segment
		(start 307.500528 -100.356416)
		(end 308.135782 -94.348046)
		(width 0.1143)
		(layer "B.Cu")
		(net "UPI_CPU1_CPU0_P0P0_DN<0>")
	)
	(segment
		(start 305.610514 -79.567278)
		(end 305.65725 -79.520542)
		(width 0.0889)
		(layer "B.Cu")
		(net "UPI_CPU1_CPU0_P0P0_DN<0>")
	)
	(segment
		(start 299.609002 -71.60641)
		(end 299.530262 -71.585074)
		(width 0.0889)
		(layer "B.Cu")
		(net "UPI_CPU1_CPU0_P0P0_DN<0>")
	)
	(segment
		(start 300.329854 -104.51846)
		(end 302.078136 -104.867964)
		(width 0.1143)
		(layer "B.Cu")
		(net "UPI_CPU1_CPU0_P0P0_DN<0>")
	)
	(segment
		(start 171.788836 -99.087178)
		(end 173.131988 -100.170996)
		(width 0.1143)
		(layer "B.Cu")
		(net "UPI_CPU1_CPU0_P0P0_DN<0>")
	)
	(segment
		(start 149.04339 -56.8706)
		(end 149.079966 -56.8706)
		(width 0.0889)
		(layer "B.Cu")
		(net "UPI_CPU1_CPU0_P0P0_DN<0>")
	)
	(segment
		(start 257.204464 -101.897942)
		(end 257.303778 -102.245668)
		(width 0.1143)
		(layer "B.Cu")
		(net "UPI_CPU1_CPU0_P0P0_DN<0>")
	)
	(segment
		(start 308.046882 -93.980762)
		(end 308.186582 -93.867732)
		(width 0.1143)
		(layer "B.Cu")
		(net "UPI_CPU1_CPU0_P0P0_DN<0>")
	)
	(segment
		(start 305.70424 -79.83855)
		(end 305.657504 -79.791814)
		(width 0.0889)
		(layer "B.Cu")
		(net "UPI_CPU1_CPU0_P0P0_DN<0>")
	)
	(segment
		(start 229.508812 -104.64165)
		(end 229.61727 -104.761284)
		(width 0.1143)
		(layer "B.Cu")
		(net "UPI_CPU1_CPU0_P0P0_DN<0>")
	)
	(segment
		(start 161.437574 -86.52891)
		(end 169.83837 -96.12884)
		(width 0.1143)
		(layer "B.Cu")
		(net "UPI_CPU1_CPU0_P0P0_DN<0>")
	)
	(segment
		(start 238.370618 -103.233728)
		(end 240.50371 -102.350062)
		(width 0.1143)
		(layer "B.Cu")
		(net "UPI_CPU1_CPU0_P0P0_DN<0>")
	)
	(segment
		(start 142.715996 -57.295796)
		(end 143.888968 -57.295796)
		(width 0.0889)
		(layer "B.Cu")
		(net "UPI_CPU1_CPU0_P0P0_DN<0>")
	)
	(segment
		(start 305.70424 -79.272384)
		(end 305.32832 -78.68158)
		(width 0.0889)
		(layer "B.Cu")
		(net "UPI_CPU1_CPU0_P0P0_DN<0>")
	)
	(segment
		(start 305.70424 -79.473806)
		(end 305.70424 -79.272384)
		(width 0.0889)
		(layer "B.Cu")
		(net "UPI_CPU1_CPU0_P0P0_DN<0>")
	)
	(segment
		(start 307.6956 -85.77961)
		(end 307.181504 -85.224874)
		(width 0.1143)
		(layer "B.Cu")
		(net "UPI_CPU1_CPU0_P0P0_DN<0>")
	)
	(segment
		(start 300.110652 -75.811888)
		(end 300.077886 -75.811888)
		(width 0.0889)
		(layer "B.Cu")
		(net "UPI_CPU1_CPU0_P0P0_DN<0>")
	)
	(segment
		(start 308.535832 -88.825832)
		(end 308.575964 -87.5665)
		(width 0.1143)
		(layer "B.Cu")
		(net "UPI_CPU1_CPU0_P0P0_DN<0>")
	)
	(segment
		(start 241.111786 -101.741986)
		(end 242.48237 -101.221794)
		(width 0.1143)
		(layer "B.Cu")
		(net "UPI_CPU1_CPU0_P0P0_DN<0>")
	)
	(segment
		(start 257.800348 -103.026718)
		(end 257.955034 -102.982522)
		(width 0.1143)
		(layer "B.Cu")
		(net "UPI_CPU1_CPU0_P0P0_DN<0>")
	)
	(segment
		(start 305.65725 -79.520542)
		(end 305.657504 -79.520542)
		(width 0.0889)
		(layer "B.Cu")
		(net "UPI_CPU1_CPU0_P0P0_DN<0>")
	)
	(segment
		(start 302.682402 -77.297534)
		(end 302.649636 -77.297534)
		(width 0.0889)
		(layer "B.Cu")
		(net "UPI_CPU1_CPU0_P0P0_DN<0>")
	)
	(segment
		(start 258.46151 -102.597712)
		(end 259.296408 -103.062786)
		(width 0.1143)
		(layer "B.Cu")
		(net "UPI_CPU1_CPU0_P0P0_DN<0>")
	)
	(segment
		(start 196.643498 -109.709458)
		(end 199.122792 -110.414562)
		(width 0.1143)
		(layer "B.Cu")
		(net "UPI_CPU1_CPU0_P0P0_DN<0>")
	)
	(segment
		(start 298.435014 -104.012492)
		(end 298.659296 -104.057196)
		(width 0.1143)
		(layer "B.Cu")
		(net "UPI_CPU1_CPU0_P0P0_DN<0>")
	)
	(segment
		(start 300.232318 -104.371902)
		(end 300.329854 -104.51846)
		(width 0.1143)
		(layer "B.Cu")
		(net "UPI_CPU1_CPU0_P0P0_DN<0>")
	)
	(segment
		(start 227.98024 -104.679496)
		(end 228.099874 -104.571038)
		(width 0.1143)
		(layer "B.Cu")
		(net "UPI_CPU1_CPU0_P0P0_DN<0>")
	)
	(segment
		(start 148.71573 -56.54294)
		(end 149.04339 -56.8706)
		(width 0.0889)
		(layer "B.Cu")
		(net "UPI_CPU1_CPU0_P0P0_DN<0>")
	)
	(segment
		(start 307.32603 -100.927662)
		(end 307.500528 -100.356416)
		(width 0.1143)
		(layer "B.Cu")
		(net "UPI_CPU1_CPU0_P0P0_DN<0>")
	)
	(segment
		(start 142.904464 -56.894984)
		(end 142.749016 -56.894984)
		(width 0.0889)
		(layer "B.Cu")
		(net "UPI_CPU1_CPU0_P0P0_DN<0>")
	)
	(segment
		(start 157.113478 -64.904112)
		(end 161.437574 -86.52891)
		(width 0.1143)
		(layer "B.Cu")
		(net "UPI_CPU1_CPU0_P0P0_DN<0>")
	)
	(segment
		(start 305.65725 -79.791814)
		(end 305.610514 -79.745078)
		(width 0.0889)
		(layer "B.Cu")
		(net "UPI_CPU1_CPU0_P0P0_DN<0>")
	)
	(segment
		(start 240.50371 -102.350062)
		(end 241.111786 -101.741986)
		(width 0.1143)
		(layer "B.Cu")
		(net "UPI_CPU1_CPU0_P0P0_DN<0>")
	)
	(segment
		(start 228.099874 -104.571038)
		(end 228.121718 -104.138222)
		(width 0.1143)
		(layer "B.Cu")
		(net "UPI_CPU1_CPU0_P0P0_DN<0>")
	)
	(segment
		(start 143.888968 -57.295796)
		(end 144.641824 -56.54294)
		(width 0.0889)
		(layer "B.Cu")
		(net "UPI_CPU1_CPU0_P0P0_DN<0>")
	)
	(segment
		(start 308.022752 -94.208346)
		(end 308.046882 -93.980762)
		(width 0.1143)
		(layer "B.Cu")
		(net "UPI_CPU1_CPU0_P0P0_DN<0>")
	)
	(segment
		(start 298.288456 -104.110028)
		(end 298.435014 -104.012492)
		(width 0.1143)
		(layer "B.Cu")
		(net "UPI_CPU1_CPU0_P0P0_DN<0>")
	)
	(segment
		(start 259.85343 -103.373174)
		(end 278.713438 -105.285794)
		(width 0.1143)
		(layer "B.Cu")
		(net "UPI_CPU1_CPU0_P0P0_DN<0>")
	)
	(segment
		(start 285.363158 -104.11587)
		(end 285.643066 -104.05999)
		(width 0.1143)
		(layer "B.Cu")
		(net "UPI_CPU1_CPU0_P0P0_DN<0>")
	)
	(segment
		(start 228.389434 -103.895906)
		(end 229.28834 -103.941118)
		(width 0.1143)
		(layer "B.Cu")
		(net "UPI_CPU1_CPU0_P0P0_DN<0>")
	)
	(segment
		(start 254.726948 -101.230684)
		(end 256.501138 -101.506528)
		(width 0.1143)
		(layer "B.Cu")
		(net "UPI_CPU1_CPU0_P0P0_DN<0>")
	)
	(segment
		(start 229.530656 -104.208834)
		(end 229.508812 -104.64165)
		(width 0.1143)
		(layer "B.Cu")
		(net "UPI_CPU1_CPU0_P0P0_DN<0>")
	)
	(segment
		(start 304.206656 -104.324404)
		(end 304.503074 -104.143048)
		(width 0.1143)
		(layer "B.Cu")
		(net "UPI_CPU1_CPU0_P0P0_DN<0>")
	)
	(segment
		(start 252.414278 -101.472492)
		(end 254.726948 -101.230684)
		(width 0.1143)
		(layer "B.Cu")
		(net "UPI_CPU1_CPU0_P0P0_DN<0>")
	)
	(segment
		(start 285.78048 -104.151684)
		(end 291.125402 -103.083614)
		(width 0.1143)
		(layer "B.Cu")
		(net "UPI_CPU1_CPU0_P0P0_DN<0>")
	)
	(segment
		(start 173.131988 -100.170996)
		(end 179.868576 -101.826822)
		(width 0.1143)
		(layer "B.Cu")
		(net "UPI_CPU1_CPU0_P0P0_DN<0>")
	)
	(segment
		(start 300.007782 -104.326944)
		(end 300.232318 -104.371902)
		(width 0.1143)
		(layer "B.Cu")
		(net "UPI_CPU1_CPU0_P0P0_DN<0>")
	)
	(segment
		(start 225.360992 -104.547924)
		(end 227.98024 -104.679496)
		(width 0.1143)
		(layer "B.Cu")
		(net "UPI_CPU1_CPU0_P0P0_DN<0>")
	)
	(segment
		(start 299.588682 -73.543922)
		(end 299.583856 -73.535286)
		(width 0.0889)
		(layer "B.Cu")
		(net "UPI_CPU1_CPU0_P0P0_DN<0>")
	)
	(segment
		(start 299.588682 -72.553322)
		(end 299.583856 -72.544686)
		(width 0.0889)
		(layer "B.Cu")
		(net "UPI_CPU1_CPU0_P0P0_DN<0>")
	)
	(segment
		(start 299.583856 -73.535286)
		(end 299.577506 -73.524618)
		(width 0.0889)
		(layer "B.Cu")
		(net "UPI_CPU1_CPU0_P0P0_DN<0>")
	)
	(segment
		(start 169.83837 -96.12884)
		(end 171.788836 -99.087178)
		(width 0.1143)
		(layer "B.Cu")
		(net "UPI_CPU1_CPU0_P0P0_DN<0>")
	)
	(segment
		(start 302.078136 -104.867964)
		(end 304.206656 -104.324404)
		(width 0.1143)
		(layer "B.Cu")
		(net "UPI_CPU1_CPU0_P0P0_DN<0>")
	)
	(segment
		(start 299.588682 -74.534522)
		(end 299.583856 -74.525886)
		(width 0.0889)
		(layer "B.Cu")
		(net "UPI_CPU1_CPU0_P0P0_DN<0>")
	)
	(segment
		(start 305.610514 -79.745078)
		(end 305.610514 -79.567278)
		(width 0.0889)
		(layer "B.Cu")
		(net "UPI_CPU1_CPU0_P0P0_DN<0>")
	)
	(segment
		(start 259.296408 -103.062786)
		(end 259.85343 -103.373174)
		(width 0.1143)
		(layer "B.Cu")
		(net "UPI_CPU1_CPU0_P0P0_DN<0>")
	)
	(segment
		(start 179.868576 -101.826822)
		(end 181.336442 -102.709472)
		(width 0.1143)
		(layer "B.Cu")
		(net "UPI_CPU1_CPU0_P0P0_DN<0>")
	)
	(segment
		(start 281.491944 -104.73055)
		(end 281.58186 -104.595676)
		(width 0.1143)
		(layer "B.Cu")
		(net "UPI_CPU1_CPU0_P0P0_DN<0>")
	)
	(segment
		(start 304.503074 -104.143048)
		(end 304.503328 -104.143048)
		(width 0.1143)
		(layer "B.Cu")
		(net "UPI_CPU1_CPU0_P0P0_DN<0>")
	)
	(segment
		(start 281.83078 -104.545892)
		(end 281.9654 -104.635808)
		(width 0.1143)
		(layer "B.Cu")
		(net "UPI_CPU1_CPU0_P0P0_DN<0>")
	)
	(segment
		(start 144.641824 -56.54294)
		(end 148.71573 -56.54294)
		(width 0.0889)
		(layer "B.Cu")
		(net "UPI_CPU1_CPU0_P0P0_DN<0>")
	)
	(segment
		(start 299.861478 -104.424734)
		(end 300.007782 -104.326944)
		(width 0.1143)
		(layer "B.Cu")
		(net "UPI_CPU1_CPU0_P0P0_DN<0>")
	)
	(segment
		(start 305.70424 -80.154272)
		(end 305.70424 -79.83855)
		(width 0.0889)
		(layer "B.Cu")
		(net "UPI_CPU1_CPU0_P0P0_DN<0>")
	)
	(segment
		(start 281.58186 -104.595676)
		(end 281.83078 -104.545892)
		(width 0.1143)
		(layer "B.Cu")
		(net "UPI_CPU1_CPU0_P0P0_DN<0>")
	)
	(segment
		(start 285.271464 -104.253538)
		(end 285.363158 -104.11587)
		(width 0.1143)
		(layer "B.Cu")
		(net "UPI_CPU1_CPU0_P0P0_DN<0>")
	)
	(segment
		(start 142.749016 -56.894984)
		(end 142.622016 -57.021984)
		(width 0.0889)
		(layer "B.Cu")
		(net "UPI_CPU1_CPU0_P0P0_DN<0>")
	)
	(segment
		(start 305.67884 -80.179672)
		(end 305.70424 -80.154272)
		(width 0.0889)
		(layer "B.Cu")
		(net "UPI_CPU1_CPU0_P0P0_DN<0>")
	)
	(segment
		(start 306.670964 -82.822288)
		(end 306.26558 -81.915)
		(width 0.1143)
		(layer "B.Cu")
		(net "UPI_CPU1_CPU0_P0P0_DN<0>")
	)
	(segment
		(start 306.923186 -84.67344)
		(end 306.73294 -83.27644)
		(width 0.1143)
		(layer "B.Cu")
		(net "UPI_CPU1_CPU0_P0P0_DN<0>")
	)
	(segment
		(start 245.69547 -101.32441)
		(end 247.42775 -100.67671)
		(width 0.1143)
		(layer "B.Cu")
		(net "UPI_CPU1_CPU0_P0P0_DN<0>")
	)
	(segment
		(start 303.544732 -77.793088)
		(end 303.511966 -77.793088)
		(width 0.0889)
		(layer "B.Cu")
		(net "UPI_CPU1_CPU0_P0P0_DN<0>")
	)
	(segment
		(start 291.125402 -103.083614)
		(end 292.140386 -102.880668)
		(width 0.1143)
		(layer "B.Cu")
		(net "UPI_CPU1_CPU0_P0P0_DN<0>")
	)
	(segment
		(start 308.196234 -93.7768)
		(end 308.456584 -91.317826)
		(width 0.1143)
		(layer "B.Cu")
		(net "UPI_CPU1_CPU0_P0P0_DN<0>")
	)
	(segment
		(start 285.643066 -104.05999)
		(end 285.78048 -104.151684)
		(width 0.1143)
		(layer "B.Cu")
		(net "UPI_CPU1_CPU0_P0P0_DN<0>")
	)
	(segment
		(start 305.67884 -80.602328)
		(end 305.67884 -80.179672)
		(width 0.1143)
		(layer "B.Cu")
		(net "UPI_CPU1_CPU0_P0P0_DN<0>")
	)
	(segment
		(start 308.135782 -94.348046)
		(end 308.022752 -94.208346)
		(width 0.1143)
		(layer "B.Cu")
		(net "UPI_CPU1_CPU0_P0P0_DN<0>")
	)
	(segment
		(start 298.659296 -104.057196)
		(end 298.757086 -104.204008)
		(width 0.1143)
		(layer "B.Cu")
		(net "UPI_CPU1_CPU0_P0P0_DN<0>")
	)
	(segment
		(start 308.186582 -93.867732)
		(end 308.196234 -93.7768)
		(width 0.1143)
		(layer "B.Cu")
		(net "UPI_CPU1_CPU0_P0P0_DN<0>")
	)
	(segment
		(start 200.371456 -110.247684)
		(end 201.826368 -109.275626)
		(width 0.1143)
		(layer "B.Cu")
		(net "UPI_CPU1_CPU0_P0P0_DN<0>")
	)
	(segment
		(start 305.32832 -78.68158)
		(end 304.66792 -78.32598)
		(width 0.0889)
		(layer "B.Cu")
		(net "UPI_CPU1_CPU0_P0P0_DN<0>")
	)
	(segment
		(start 308.575964 -87.5665)
		(end 307.806598 -85.899498)
		(width 0.1143)
		(layer "B.Cu")
		(net "UPI_CPU1_CPU0_P0P0_DN<0>")
	)
	(segment
		(start 301.827692 -76.802488)
		(end 301.794926 -76.802488)
		(width 0.0889)
		(layer "B.Cu")
		(net "UPI_CPU1_CPU0_P0P0_DN<0>")
	)
	(segment
		(start 307.181504 -85.224874)
		(end 306.923186 -84.67344)
		(width 0.1143)
		(layer "B.Cu")
		(net "UPI_CPU1_CPU0_P0P0_DN<0>")
	)
	(segment
		(start 298.757086 -104.204008)
		(end 299.861478 -104.424734)
		(width 0.1143)
		(layer "B.Cu")
		(net "UPI_CPU1_CPU0_P0P0_DN<0>")
	)
	(segment
		(start 215.1634 -106.596434)
		(end 225.360992 -104.547924)
		(width 0.1143)
		(layer "B.Cu")
		(net "UPI_CPU1_CPU0_P0P0_DN<0>")
	)
	(segment
		(start 281.9654 -104.635808)
		(end 283.317188 -104.365806)
		(width 0.1143)
		(layer "B.Cu")
		(net "UPI_CPU1_CPU0_P0P0_DN<0>")
	)
	(segment
		(start 142.622016 -57.021984)
		(end 142.622016 -57.201816)
		(width 0.0889)
		(layer "B.Cu")
		(net "UPI_CPU1_CPU0_P0P0_DN<0>")
	)
	(segment
		(start 193.127122 -105.79481)
		(end 196.643498 -109.709458)
		(width 0.1143)
		(layer "B.Cu")
		(net "UPI_CPU1_CPU0_P0P0_DN<0>")
	)
	(segment
		(start 278.713438 -105.285794)
		(end 281.491944 -104.73055)
		(width 0.1143)
		(layer "B.Cu")
		(net "UPI_CPU1_CPU0_P0P0_DN<0>")
	)
	(segment
		(start 307.806598 -85.899498)
		(end 307.6956 -85.77961)
		(width 0.1143)
		(layer "B.Cu")
		(net "UPI_CPU1_CPU0_P0P0_DN<0>")
	)
	(segment
		(start 305.657504 -79.791814)
		(end 305.65725 -79.791814)
		(width 0.0889)
		(layer "B.Cu")
		(net "UPI_CPU1_CPU0_P0P0_DN<0>")
	)
	(segment
		(start 257.188462 -102.686104)
		(end 257.800348 -103.026718)
		(width 0.1143)
		(layer "B.Cu")
		(net "UPI_CPU1_CPU0_P0P0_DN<0>")
	)
	(segment
		(start 149.079966 -56.8706)
		(end 157.113478 -64.904112)
		(width 0.1143)
		(layer "B.Cu")
		(net "UPI_CPU1_CPU0_P0P0_DN<0>")
	)
	(segment
		(start 229.61727 -104.761284)
		(end 230.608378 -104.810814)
		(width 0.1143)
		(layer "B.Cu")
		(net "UPI_CPU1_CPU0_P0P0_DN<0>")
	)
	(segment
		(start 299.583856 -72.544686)
		(end 299.577506 -72.534018)
		(width 0.0889)
		(layer "B.Cu")
		(net "UPI_CPU1_CPU0_P0P0_DN<0>")
	)
	(segment
		(start 228.121718 -104.138222)
		(end 228.389434 -103.895906)
		(width 0.1143)
		(layer "B.Cu")
		(net "UPI_CPU1_CPU0_P0P0_DN<0>")
	)
	(segment
		(start 229.28834 -103.941118)
		(end 229.530656 -104.208834)
		(width 0.1143)
		(layer "B.Cu")
		(net "UPI_CPU1_CPU0_P0P0_DN<0>")
	)
	(segment
		(start 306.26558 -81.915)
		(end 305.67884 -80.602328)
		(width 0.1143)
		(layer "B.Cu")
		(net "UPI_CPU1_CPU0_P0P0_DN<0>")
	)
	(segment
		(start 249.481594 -100.59924)
		(end 252.414278 -101.472492)
		(width 0.1143)
		(layer "B.Cu")
		(net "UPI_CPU1_CPU0_P0P0_DN<0>")
	)
	(segment
		(start 305.657504 -79.520542)
		(end 305.70424 -79.473806)
		(width 0.0889)
		(layer "B.Cu")
		(net "UPI_CPU1_CPU0_P0P0_DN<0>")
	)
	(segment
		(start 230.608378 -104.810814)
		(end 238.370618 -103.233728)
		(width 0.1143)
		(layer "B.Cu")
		(net "UPI_CPU1_CPU0_P0P0_DN<0>")
	)
	(segment
		(start 181.336442 -102.709472)
		(end 185.503058 -104.433624)
		(width 0.1143)
		(layer "B.Cu")
		(net "UPI_CPU1_CPU0_P0P0_DN<0>")
	)
	(segment
		(start 256.501138 -101.506528)
		(end 257.204464 -101.897942)
		(width 0.1143)
		(layer "B.Cu")
		(net "UPI_CPU1_CPU0_P0P0_DN<0>")
	)
	(segment
		(start 199.122792 -110.414562)
		(end 200.371456 -110.247684)
		(width 0.1143)
		(layer "B.Cu")
		(net "UPI_CPU1_CPU0_P0P0_DN<0>")
	)
	(segment
		(start 283.317188 -104.365806)
		(end 284.016958 -104.504236)
		(width 0.1143)
		(layer "B.Cu")
		(net "UPI_CPU1_CPU0_P0P0_DN<0>")
	)
	(segment
		(start 308.456584 -91.317826)
		(end 308.535832 -88.825832)
		(width 0.1143)
		(layer "B.Cu")
		(net "UPI_CPU1_CPU0_P0P0_DN<0>")
	)
	(segment
		(start 142.622016 -57.201816)
		(end 142.715996 -57.295796)
		(width 0.0889)
		(layer "B.Cu")
		(net "UPI_CPU1_CPU0_P0P0_DN<0>")
	)
	(segment
		(start 306.73294 -83.27644)
		(end 306.670964 -82.822288)
		(width 0.1143)
		(layer "B.Cu")
		(net "UPI_CPU1_CPU0_P0P0_DN<0>")
	)
	(segment
		(start 257.955034 -102.982522)
		(end 258.114292 -102.69728)
		(width 0.1143)
		(layer "B.Cu")
		(net "UPI_CPU1_CPU0_P0P0_DN<0>")
	)
	(segment
		(start 299.530262 -71.585074)
		(end 299.237146 -71.753984)
		(width 0.0889)
		(layer "B.Cu")
		(net "UPI_CPU1_CPU0_P0P0_DN<0>")
	)
	(segment
		(start 299.583856 -74.525886)
		(end 299.577506 -74.515218)
		(width 0.0889)
		(layer "B.Cu")
		(net "UPI_CPU1_CPU0_P0P0_DN<0>")
	)
	(segment
		(start 247.42775 -100.67671)
		(end 249.481594 -100.59924)
		(width 0.1143)
		(layer "B.Cu")
		(net "UPI_CPU1_CPU0_P0P0_DN<0>")
	)
	(segment
		(start 304.66792 -78.32598)
		(end 304.410364 -78.288134)
		(width 0.0889)
		(layer "B.Cu")
		(net "UPI_CPU1_CPU0_P0P0_DN<0>")
	)
	(segment
		(start 300.965362 -76.306934)
		(end 300.932596 -76.306934)
		(width 0.0889)
		(layer "B.Cu")
		(net "UPI_CPU1_CPU0_P0P0_DN<0>")
	)
	(segment
		(start 257.14452 -102.531418)
		(end 257.188462 -102.686104)
		(width 0.1143)
		(layer "B.Cu")
		(net "UPI_CPU1_CPU0_P0P0_DN<0>")
	)
	(arc
		(start 299.583856 -74.925936)
		(mid 299.637326 -74.730873)
		(end 299.588682 -74.534522)
		(width 0.0889)
		(layer "B.Cu")
		(net "UPI_CPU1_CPU0_P0P0_DN<0>")
	)
	(arc
		(start 300.442376 -76.011786)
		(mid 300.302297 -75.86905)
		(end 300.110652 -75.811888)
		(width 0.0889)
		(layer "B.Cu")
		(net "UPI_CPU1_CPU0_P0P0_DN<0>")
	)
	(arc
		(start 299.583856 -73.935336)
		(mid 299.637326 -73.740273)
		(end 299.588682 -73.543922)
		(width 0.0889)
		(layer "B.Cu")
		(net "UPI_CPU1_CPU0_P0P0_DN<0>")
	)
	(arc
		(start 299.577506 -73.524618)
		(mid 299.504708 -73.233855)
		(end 299.583856 -72.944736)
		(width 0.0889)
		(layer "B.Cu")
		(net "UPI_CPU1_CPU0_P0P0_DN<0>")
	)
	(arc
		(start 303.876456 -77.992986)
		(mid 303.736377 -77.85025)
		(end 303.544732 -77.793088)
		(width 0.0889)
		(layer "B.Cu")
		(net "UPI_CPU1_CPU0_P0P0_DN<0>")
	)
	(arc
		(start 302.159416 -77.002386)
		(mid 302.019337 -76.85965)
		(end 301.827692 -76.802488)
		(width 0.0889)
		(layer "B.Cu")
		(net "UPI_CPU1_CPU0_P0P0_DN<0>")
	)
	(arc
		(start 299.577506 -74.515218)
		(mid 299.504708 -74.224455)
		(end 299.583856 -73.935336)
		(width 0.0889)
		(layer "B.Cu")
		(net "UPI_CPU1_CPU0_P0P0_DN<0>")
	)
	(arc
		(start 299.583856 -72.944736)
		(mid 299.637326 -72.749673)
		(end 299.588682 -72.553322)
		(width 0.0889)
		(layer "B.Cu")
		(net "UPI_CPU1_CPU0_P0P0_DN<0>")
	)
	(arc
		(start 299.577506 -72.534018)
		(mid 299.504708 -72.243255)
		(end 299.583856 -71.954136)
		(width 0.0889)
		(layer "B.Cu")
		(net "UPI_CPU1_CPU0_P0P0_DN<0>")
	)
	(arc
		(start 301.794926 -76.802488)
		(mid 301.509502 -76.719021)
		(end 301.300896 -76.507086)
		(width 0.0889)
		(layer "B.Cu")
		(net "UPI_CPU1_CPU0_P0P0_DN<0>")
	)
	(arc
		(start 303.511966 -77.793088)
		(mid 303.226542 -77.709621)
		(end 303.017936 -77.497686)
		(width 0.0889)
		(layer "B.Cu")
		(net "UPI_CPU1_CPU0_P0P0_DN<0>")
	)
	(arc
		(start 299.583856 -71.954136)
		(mid 299.636276 -71.783151)
		(end 299.609002 -71.60641)
		(width 0.0889)
		(layer "B.Cu")
		(net "UPI_CPU1_CPU0_P0P0_DN<0>")
	)
	(arc
		(start 300.077886 -75.811888)
		(mid 299.579635 -75.509048)
		(end 299.583856 -74.925936)
		(width 0.0889)
		(layer "B.Cu")
		(net "UPI_CPU1_CPU0_P0P0_DN<0>")
	)
	(arc
		(start 301.300896 -76.507086)
		(mid 301.159213 -76.363282)
		(end 300.965362 -76.306934)
		(width 0.0889)
		(layer "B.Cu")
		(net "UPI_CPU1_CPU0_P0P0_DN<0>")
	)
	(arc
		(start 302.649636 -77.297534)
		(mid 302.366419 -77.213253)
		(end 302.159416 -77.002386)
		(width 0.0889)
		(layer "B.Cu")
		(net "UPI_CPU1_CPU0_P0P0_DN<0>")
	)
	(arc
		(start 303.017936 -77.497686)
		(mid 302.876253 -77.353882)
		(end 302.682402 -77.297534)
		(width 0.0889)
		(layer "B.Cu")
		(net "UPI_CPU1_CPU0_P0P0_DN<0>")
	)
	(arc
		(start 300.932596 -76.306934)
		(mid 300.649379 -76.222653)
		(end 300.442376 -76.011786)
		(width 0.0889)
		(layer "B.Cu")
		(net "UPI_CPU1_CPU0_P0P0_DN<0>")
	)
	(arc
		(start 304.410364 -78.288134)
		(mid 304.102372 -78.21479)
		(end 303.876456 -77.992986)
		(width 0.0889)
		(layer "B.Cu")
		(net "UPI_CPU1_CPU0_P0P0_DN<0>")
	)
	(segment
		(start 131.948174 -57.885584)
		(end 132.519674 -57.885584)
		(width 0.1143)
		(layer "F.Cu")
		(net "UPI_CPU0_CPU1_P1P1_DP<9>")
	)
	(segment
		(start 297.807126 -54.418738)
		(end 298.378626 -54.418738)
		(width 0.1143)
		(layer "F.Cu")
		(net "UPI_CPU0_CPU1_P1P1_DP<9>")
	)
	(via
		(at 298.378626 -54.418738)
		(size 0.508)
		(drill 0.254)
		(layers "F.Cu" "B.Cu")
		(net "UPI_CPU0_CPU1_P1P1_DP<9>")
	)
	(via
		(at 132.519674 -57.885584)
		(size 0.508)
		(drill 0.254)
		(layers "F.Cu" "B.Cu")
		(net "UPI_CPU0_CPU1_P1P1_DP<9>")
	)
	(segment
		(start 131.309872 -54.61)
		(end 131.314698 -54.618636)
		(width 0.0889)
		(layer "B.Cu")
		(net "UPI_CPU0_CPU1_P1P1_DP<9>")
	)
	(segment
		(start 250.585478 -37.010086)
		(end 248.006362 -36.494212)
		(width 0.1143)
		(layer "B.Cu")
		(net "UPI_CPU0_CPU1_P1P1_DP<9>")
	)
	(segment
		(start 209.014314 -38.889432)
		(end 205.740508 -37.025072)
		(width 0.1143)
		(layer "B.Cu")
		(net "UPI_CPU0_CPU1_P1P1_DP<9>")
	)
	(segment
		(start 164.405818 -39.83736)
		(end 161.876994 -39.331392)
		(width 0.1143)
		(layer "B.Cu")
		(net "UPI_CPU0_CPU1_P1P1_DP<9>")
	)
	(segment
		(start 131.314698 -55.609236)
		(end 131.321048 -55.619904)
		(width 0.0889)
		(layer "B.Cu")
		(net "UPI_CPU0_CPU1_P1P1_DP<9>")
	)
	(segment
		(start 290.638484 -44.323762)
		(end 287.423098 -41.944544)
		(width 0.1143)
		(layer "B.Cu")
		(net "UPI_CPU0_CPU1_P1P1_DP<9>")
	)
	(segment
		(start 295.635426 -46.492922)
		(end 295.350184 -46.30293)
		(width 0.1143)
		(layer "B.Cu")
		(net "UPI_CPU0_CPU1_P1P1_DP<9>")
	)
	(segment
		(start 294.18407 -45.647356)
		(end 294.155876 -45.506386)
		(width 0.1143)
		(layer "B.Cu")
		(net "UPI_CPU0_CPU1_P1P1_DP<9>")
	)
	(segment
		(start 141.85392 -42.450004)
		(end 140.084556 -42.79392)
		(width 0.1143)
		(layer "B.Cu")
		(net "UPI_CPU0_CPU1_P1P1_DP<9>")
	)
	(segment
		(start 131.7244 -51.115468)
		(end 131.7244 -51.689762)
		(width 0.0889)
		(layer "B.Cu")
		(net "UPI_CPU0_CPU1_P1P1_DP<9>")
	)
	(segment
		(start 131.309872 -55.6006)
		(end 131.314698 -55.609236)
		(width 0.0889)
		(layer "B.Cu")
		(net "UPI_CPU0_CPU1_P1P1_DP<9>")
	)
	(segment
		(start 296.97807 -49.714658)
		(end 296.846244 -49.398174)
		(width 0.1143)
		(layer "B.Cu")
		(net "UPI_CPU0_CPU1_P1P1_DP<9>")
	)
	(segment
		(start 297.632374 -51.547014)
		(end 297.486832 -51.034188)
		(width 0.0889)
		(layer "B.Cu")
		(net "UPI_CPU0_CPU1_P1P1_DP<9>")
	)
	(segment
		(start 297.055286 -50.164238)
		(end 296.92346 -49.8475)
		(width 0.1143)
		(layer "B.Cu")
		(net "UPI_CPU0_CPU1_P1P1_DP<9>")
	)
	(segment
		(start 297.320716 -50.53711)
		(end 297.320462 -50.536094)
		(width 0.1143)
		(layer "B.Cu")
		(net "UPI_CPU0_CPU1_P1P1_DP<9>")
	)
	(segment
		(start 154.561286 -39.665148)
		(end 152.958292 -40.016176)
		(width 0.1143)
		(layer "B.Cu")
		(net "UPI_CPU0_CPU1_P1P1_DP<9>")
	)
	(segment
		(start 293.416228 -45.013118)
		(end 293.129716 -44.82211)
		(width 0.1143)
		(layer "B.Cu")
		(net "UPI_CPU0_CPU1_P1P1_DP<9>")
	)
	(segment
		(start 292.33749 -44.7675)
		(end 292.257734 -44.647612)
		(width 0.1143)
		(layer "B.Cu")
		(net "UPI_CPU0_CPU1_P1P1_DP<9>")
	)
	(segment
		(start 294.46982 -45.837602)
		(end 294.18407 -45.647356)
		(width 0.1143)
		(layer "B.Cu")
		(net "UPI_CPU0_CPU1_P1P1_DP<9>")
	)
	(segment
		(start 196.855842 -35.248088)
		(end 190.64859 -35.580574)
		(width 0.1143)
		(layer "B.Cu")
		(net "UPI_CPU0_CPU1_P1P1_DP<9>")
	)
	(segment
		(start 253.069344 -37.935662)
		(end 250.585478 -37.010086)
		(width 0.1143)
		(layer "B.Cu")
		(net "UPI_CPU0_CPU1_P1P1_DP<9>")
	)
	(segment
		(start 280.175462 -42.275252)
		(end 260.30428 -38.300914)
		(width 0.1143)
		(layer "B.Cu")
		(net "UPI_CPU0_CPU1_P1P1_DP<9>")
	)
	(segment
		(start 260.30428 -38.300914)
		(end 256.799334 -37.835586)
		(width 0.1143)
		(layer "B.Cu")
		(net "UPI_CPU0_CPU1_P1P1_DP<9>")
	)
	(segment
		(start 295.934638 -47.211488)
		(end 295.635426 -46.492922)
		(width 0.1143)
		(layer "B.Cu")
		(net "UPI_CPU0_CPU1_P1P1_DP<9>")
	)
	(segment
		(start 161.876994 -39.331392)
		(end 158.79953 -40.489124)
		(width 0.1143)
		(layer "B.Cu")
		(net "UPI_CPU0_CPU1_P1P1_DP<9>")
	)
	(segment
		(start 294.923718 -46.14037)
		(end 294.895778 -45.999654)
		(width 0.1143)
		(layer "B.Cu")
		(net "UPI_CPU0_CPU1_P1P1_DP<9>")
	)
	(segment
		(start 294.610536 -45.809662)
		(end 294.46982 -45.837602)
		(width 0.1143)
		(layer "B.Cu")
		(net "UPI_CPU0_CPU1_P1P1_DP<9>")
	)
	(segment
		(start 293.444168 -45.153834)
		(end 293.416228 -45.013118)
		(width 0.1143)
		(layer "B.Cu")
		(net "UPI_CPU0_CPU1_P1P1_DP<9>")
	)
	(segment
		(start 239.06734 -39.624)
		(end 226.064572 -42.224452)
		(width 0.1143)
		(layer "B.Cu")
		(net "UPI_CPU0_CPU1_P1P1_DP<9>")
	)
	(segment
		(start 293.729918 -45.344334)
		(end 293.444168 -45.153834)
		(width 0.1143)
		(layer "B.Cu")
		(net "UPI_CPU0_CPU1_P1P1_DP<9>")
	)
	(segment
		(start 143.448786 -42.100246)
		(end 141.85392 -42.450004)
		(width 0.1143)
		(layer "B.Cu")
		(net "UPI_CPU0_CPU1_P1P1_DP<9>")
	)
	(segment
		(start 295.880028 -47.34433)
		(end 295.934638 -47.211488)
		(width 0.1143)
		(layer "B.Cu")
		(net "UPI_CPU0_CPU1_P1P1_DP<9>")
	)
	(segment
		(start 132.519166 -58.28538)
		(end 132.880354 -58.28538)
		(width 0.0889)
		(layer "B.Cu")
		(net "UPI_CPU0_CPU1_P1P1_DP<9>")
	)
	(segment
		(start 297.188382 -50.218848)
		(end 297.055286 -50.164238)
		(width 0.1143)
		(layer "B.Cu")
		(net "UPI_CPU0_CPU1_P1P1_DP<9>")
	)
	(segment
		(start 254.24003 -37.913056)
		(end 253.069344 -37.935662)
		(width 0.1143)
		(layer "B.Cu")
		(net "UPI_CPU0_CPU1_P1P1_DP<9>")
	)
	(segment
		(start 297.788076 -51.702462)
		(end 297.632374 -51.547014)
		(width 0.0889)
		(layer "B.Cu")
		(net "UPI_CPU0_CPU1_P1P1_DP<9>")
	)
	(segment
		(start 293.870634 -45.316394)
		(end 293.729918 -45.344334)
		(width 0.1143)
		(layer "B.Cu")
		(net "UPI_CPU0_CPU1_P1P1_DP<9>")
	)
	(segment
		(start 131.7498 -51.06797)
		(end 131.7498 -51.090068)
		(width 0.0889)
		(layer "B.Cu")
		(net "UPI_CPU0_CPU1_P1P1_DP<9>")
	)
	(segment
		(start 171.19473 -40.082978)
		(end 166.942262 -39.204138)
		(width 0.1143)
		(layer "B.Cu")
		(net "UPI_CPU0_CPU1_P1P1_DP<9>")
	)
	(segment
		(start 187.64631 -36.008056)
		(end 185.68797 -35.588194)
		(width 0.1143)
		(layer "B.Cu")
		(net "UPI_CPU0_CPU1_P1P1_DP<9>")
	)
	(segment
		(start 294.895778 -45.999654)
		(end 294.610536 -45.809662)
		(width 0.1143)
		(layer "B.Cu")
		(net "UPI_CPU0_CPU1_P1P1_DP<9>")
	)
	(segment
		(start 134.406894 -48.054006)
		(end 131.7498 -50.7111)
		(width 0.1143)
		(layer "B.Cu")
		(net "UPI_CPU0_CPU1_P1P1_DP<9>")
	)
	(segment
		(start 131.502912 -51.91125)
		(end 131.308348 -52.24907)
		(width 0.0889)
		(layer "B.Cu")
		(net "UPI_CPU0_CPU1_P1P1_DP<9>")
	)
	(segment
		(start 292.257734 -44.647612)
		(end 290.638484 -44.323762)
		(width 0.1143)
		(layer "B.Cu")
		(net "UPI_CPU0_CPU1_P1P1_DP<9>")
	)
	(segment
		(start 205.740508 -37.025072)
		(end 196.855842 -35.248088)
		(width 0.1143)
		(layer "B.Cu")
		(net "UPI_CPU0_CPU1_P1P1_DP<9>")
	)
	(segment
		(start 152.958292 -40.016176)
		(end 143.448786 -42.100246)
		(width 0.1143)
		(layer "B.Cu")
		(net "UPI_CPU0_CPU1_P1P1_DP<9>")
	)
	(segment
		(start 158.79953 -40.489124)
		(end 154.561286 -39.665148)
		(width 0.1143)
		(layer "B.Cu")
		(net "UPI_CPU0_CPU1_P1P1_DP<9>")
	)
	(segment
		(start 190.64859 -35.580574)
		(end 187.64631 -36.008056)
		(width 0.1143)
		(layer "B.Cu")
		(net "UPI_CPU0_CPU1_P1P1_DP<9>")
	)
	(segment
		(start 254.48133 -37.913056)
		(end 254.24003 -37.913056)
		(width 0.1143)
		(layer "B.Cu")
		(net "UPI_CPU0_CPU1_P1P1_DP<9>")
	)
	(segment
		(start 297.933618 -53.838856)
		(end 297.866816 -53.723286)
		(width 0.0889)
		(layer "B.Cu")
		(net "UPI_CPU0_CPU1_P1P1_DP<9>")
	)
	(segment
		(start 296.14495 -47.715678)
		(end 296.011854 -47.661068)
		(width 0.1143)
		(layer "B.Cu")
		(net "UPI_CPU0_CPU1_P1P1_DP<9>")
	)
	(segment
		(start 294.155876 -45.506386)
		(end 293.870634 -45.316394)
		(width 0.1143)
		(layer "B.Cu")
		(net "UPI_CPU0_CPU1_P1P1_DP<9>")
	)
	(segment
		(start 296.713148 -49.343564)
		(end 296.581322 -49.026826)
		(width 0.1143)
		(layer "B.Cu")
		(net "UPI_CPU0_CPU1_P1P1_DP<9>")
	)
	(segment
		(start 182.977536 -36.145724)
		(end 172.498512 -39.735506)
		(width 0.1143)
		(layer "B.Cu")
		(net "UPI_CPU0_CPU1_P1P1_DP<9>")
	)
	(segment
		(start 297.451272 -50.996342)
		(end 297.320716 -50.53711)
		(width 0.1143)
		(layer "B.Cu")
		(net "UPI_CPU0_CPU1_P1P1_DP<9>")
	)
	(segment
		(start 131.314698 -56.599836)
		(end 131.321048 -56.610504)
		(width 0.0889)
		(layer "B.Cu")
		(net "UPI_CPU0_CPU1_P1P1_DP<9>")
	)
	(segment
		(start 131.650232 -57.790588)
		(end 131.6863 -57.790588)
		(width 0.0889)
		(layer "B.Cu")
		(net "UPI_CPU0_CPU1_P1P1_DP<9>")
	)
	(segment
		(start 241.941604 -37.70757)
		(end 239.06734 -39.624)
		(width 0.1143)
		(layer "B.Cu")
		(net "UPI_CPU0_CPU1_P1P1_DP<9>")
	)
	(segment
		(start 131.7498 -50.7111)
		(end 131.7498 -51.06797)
		(width 0.1143)
		(layer "B.Cu")
		(net "UPI_CPU0_CPU1_P1P1_DP<9>")
	)
	(segment
		(start 248.006362 -36.494212)
		(end 241.941604 -37.70757)
		(width 0.1143)
		(layer "B.Cu")
		(net "UPI_CPU0_CPU1_P1P1_DP<9>")
	)
	(segment
		(start 131.7244 -51.689762)
		(end 131.502912 -51.91125)
		(width 0.0889)
		(layer "B.Cu")
		(net "UPI_CPU0_CPU1_P1P1_DP<9>")
	)
	(segment
		(start 296.5196 -48.614838)
		(end 296.14495 -47.715678)
		(width 0.1143)
		(layer "B.Cu")
		(net "UPI_CPU0_CPU1_P1P1_DP<9>")
	)
	(segment
		(start 131.661408 -54.018434)
		(end 131.656582 -54.018434)
		(width 0.0889)
		(layer "B.Cu")
		(net "UPI_CPU0_CPU1_P1P1_DP<9>")
	)
	(segment
		(start 296.635932 -48.893984)
		(end 296.5196 -48.614838)
		(width 0.1143)
		(layer "B.Cu")
		(net "UPI_CPU0_CPU1_P1P1_DP<9>")
	)
	(segment
		(start 131.314698 -54.618636)
		(end 131.321048 -54.629304)
		(width 0.0889)
		(layer "B.Cu")
		(net "UPI_CPU0_CPU1_P1P1_DP<9>")
	)
	(segment
		(start 297.866816 -52.73294)
		(end 297.866562 -52.732686)
		(width 0.0889)
		(layer "B.Cu")
		(net "UPI_CPU0_CPU1_P1P1_DP<9>")
	)
	(segment
		(start 292.793674 -44.755054)
		(end 292.67404 -44.834556)
		(width 0.1143)
		(layer "B.Cu")
		(net "UPI_CPU0_CPU1_P1P1_DP<9>")
	)
	(segment
		(start 166.942262 -39.204138)
		(end 164.405818 -39.83736)
		(width 0.1143)
		(layer "B.Cu")
		(net "UPI_CPU0_CPU1_P1P1_DP<9>")
	)
	(segment
		(start 210.95081 -39.201598)
		(end 209.014314 -38.889432)
		(width 0.1143)
		(layer "B.Cu")
		(net "UPI_CPU0_CPU1_P1P1_DP<9>")
	)
	(segment
		(start 292.67404 -44.834556)
		(end 292.33749 -44.7675)
		(width 0.1143)
		(layer "B.Cu")
		(net "UPI_CPU0_CPU1_P1P1_DP<9>")
	)
	(segment
		(start 131.7498 -51.090068)
		(end 131.7244 -51.115468)
		(width 0.0889)
		(layer "B.Cu")
		(net "UPI_CPU0_CPU1_P1P1_DP<9>")
	)
	(segment
		(start 296.846244 -49.398174)
		(end 296.713148 -49.343564)
		(width 0.1143)
		(layer "B.Cu")
		(net "UPI_CPU0_CPU1_P1P1_DP<9>")
	)
	(segment
		(start 297.457114 -51.017678)
		(end 297.451272 -50.996342)
		(width 0.0889)
		(layer "B.Cu")
		(net "UPI_CPU0_CPU1_P1P1_DP<9>")
	)
	(segment
		(start 297.788076 -52.426362)
		(end 297.788076 -51.702462)
		(width 0.0889)
		(layer "B.Cu")
		(net "UPI_CPU0_CPU1_P1P1_DP<9>")
	)
	(segment
		(start 226.064572 -42.224452)
		(end 222.396812 -41.4909)
		(width 0.1143)
		(layer "B.Cu")
		(net "UPI_CPU0_CPU1_P1P1_DP<9>")
	)
	(segment
		(start 297.320462 -50.536094)
		(end 297.320208 -50.535332)
		(width 0.1143)
		(layer "B.Cu")
		(net "UPI_CPU0_CPU1_P1P1_DP<9>")
	)
	(segment
		(start 295.350184 -46.30293)
		(end 295.209468 -46.33087)
		(width 0.1143)
		(layer "B.Cu")
		(net "UPI_CPU0_CPU1_P1P1_DP<9>")
	)
	(segment
		(start 296.581322 -49.026826)
		(end 296.635932 -48.893984)
		(width 0.1143)
		(layer "B.Cu")
		(net "UPI_CPU0_CPU1_P1P1_DP<9>")
	)
	(segment
		(start 172.498512 -39.735506)
		(end 171.19473 -40.082978)
		(width 0.1143)
		(layer "B.Cu")
		(net "UPI_CPU0_CPU1_P1P1_DP<9>")
	)
	(segment
		(start 256.799334 -37.835586)
		(end 254.48133 -37.913056)
		(width 0.1143)
		(layer "B.Cu")
		(net "UPI_CPU0_CPU1_P1P1_DP<9>")
	)
	(segment
		(start 296.011854 -47.661068)
		(end 295.880028 -47.34433)
		(width 0.1143)
		(layer "B.Cu")
		(net "UPI_CPU0_CPU1_P1P1_DP<9>")
	)
	(segment
		(start 136.17702 -45.429932)
		(end 134.406894 -48.054006)
		(width 0.1143)
		(layer "B.Cu")
		(net "UPI_CPU0_CPU1_P1P1_DP<9>")
	)
	(segment
		(start 295.209468 -46.33087)
		(end 294.923718 -46.14037)
		(width 0.1143)
		(layer "B.Cu")
		(net "UPI_CPU0_CPU1_P1P1_DP<9>")
	)
	(segment
		(start 185.68797 -35.588194)
		(end 182.977536 -36.145724)
		(width 0.1143)
		(layer "B.Cu")
		(net "UPI_CPU0_CPU1_P1P1_DP<9>")
	)
	(segment
		(start 132.173218 -58.085482)
		(end 132.17652 -58.091324)
		(width 0.0889)
		(layer "B.Cu")
		(net "UPI_CPU0_CPU1_P1P1_DP<9>")
	)
	(segment
		(start 287.423098 -41.944544)
		(end 280.175462 -42.275252)
		(width 0.1143)
		(layer "B.Cu")
		(net "UPI_CPU0_CPU1_P1P1_DP<9>")
	)
	(segment
		(start 297.866562 -52.732686)
		(end 297.866816 -52.732686)
		(width 0.0889)
		(layer "B.Cu")
		(net "UPI_CPU0_CPU1_P1P1_DP<9>")
	)
	(segment
		(start 293.129716 -44.82211)
		(end 292.793674 -44.755054)
		(width 0.1143)
		(layer "B.Cu")
		(net "UPI_CPU0_CPU1_P1P1_DP<9>")
	)
	(segment
		(start 140.084556 -42.79392)
		(end 136.17702 -45.429932)
		(width 0.1143)
		(layer "B.Cu")
		(net "UPI_CPU0_CPU1_P1P1_DP<9>")
	)
	(segment
		(start 297.320208 -50.535332)
		(end 297.188382 -50.218848)
		(width 0.1143)
		(layer "B.Cu")
		(net "UPI_CPU0_CPU1_P1P1_DP<9>")
	)
	(segment
		(start 132.74675 -57.885584)
		(end 132.519674 -57.885584)
		(width 0.0889)
		(layer "B.Cu")
		(net "UPI_CPU0_CPU1_P1P1_DP<9>")
	)
	(segment
		(start 222.396812 -41.4909)
		(end 210.95081 -39.201598)
		(width 0.1143)
		(layer "B.Cu")
		(net "UPI_CPU0_CPU1_P1P1_DP<9>")
	)
	(segment
		(start 296.92346 -49.8475)
		(end 296.97807 -49.714658)
		(width 0.1143)
		(layer "B.Cu")
		(net "UPI_CPU0_CPU1_P1P1_DP<9>")
	)
	(segment
		(start 297.860466 -53.143404)
		(end 297.866816 -53.132736)
		(width 0.0889)
		(layer "B.Cu")
		(net "UPI_CPU0_CPU1_P1P1_DP<9>")
	)
	(segment
		(start 131.309872 -56.5912)
		(end 131.314698 -56.599836)
		(width 0.0889)
		(layer "B.Cu")
		(net "UPI_CPU0_CPU1_P1P1_DP<9>")
	)
	(segment
		(start 297.486832 -51.034188)
		(end 297.457114 -51.017678)
		(width 0.0889)
		(layer "B.Cu")
		(net "UPI_CPU0_CPU1_P1P1_DP<9>")
	)
	(arc
		(start 131.314698 -56.199786)
		(mid 131.261228 -56.394849)
		(end 131.309872 -56.5912)
		(width 0.0889)
		(layer "B.Cu")
		(net "UPI_CPU0_CPU1_P1P1_DP<9>")
	)
	(arc
		(start 131.679188 -52.83708)
		(mid 132.251223 -53.393223)
		(end 131.747768 -54.012338)
		(width 0.0889)
		(layer "B.Cu")
		(net "UPI_CPU0_CPU1_P1P1_DP<9>")
	)
	(arc
		(start 131.321048 -56.610504)
		(mid 131.393846 -56.901267)
		(end 131.314698 -57.190386)
		(width 0.0889)
		(layer "B.Cu")
		(net "UPI_CPU0_CPU1_P1P1_DP<9>")
	)
	(arc
		(start 297.866816 -53.723286)
		(mid 297.787594 -53.434168)
		(end 297.860466 -53.143404)
		(width 0.0889)
		(layer "B.Cu")
		(net "UPI_CPU0_CPU1_P1P1_DP<9>")
	)
	(arc
		(start 131.6863 -57.790588)
		(mid 131.9676 -57.875554)
		(end 132.173218 -58.085482)
		(width 0.0889)
		(layer "B.Cu")
		(net "UPI_CPU0_CPU1_P1P1_DP<9>")
	)
	(arc
		(start 131.261358 -52.425346)
		(mid 131.369139 -52.710444)
		(end 131.646422 -52.83708)
		(width 0.0889)
		(layer "B.Cu")
		(net "UPI_CPU0_CPU1_P1P1_DP<9>")
	)
	(arc
		(start 132.17652 -58.091324)
		(mid 132.322276 -58.233495)
		(end 132.519166 -58.28538)
		(width 0.0889)
		(layer "B.Cu")
		(net "UPI_CPU0_CPU1_P1P1_DP<9>")
	)
	(arc
		(start 131.321048 -54.629304)
		(mid 131.393846 -54.920067)
		(end 131.314698 -55.209186)
		(width 0.0889)
		(layer "B.Cu")
		(net "UPI_CPU0_CPU1_P1P1_DP<9>")
	)
	(arc
		(start 298.378626 -54.418738)
		(mid 298.137139 -54.143365)
		(end 297.933618 -53.838856)
		(width 0.0889)
		(layer "B.Cu")
		(net "UPI_CPU0_CPU1_P1P1_DP<9>")
	)
	(arc
		(start 131.321048 -55.619904)
		(mid 131.393846 -55.910667)
		(end 131.314698 -56.199786)
		(width 0.0889)
		(layer "B.Cu")
		(net "UPI_CPU0_CPU1_P1P1_DP<9>")
	)
	(arc
		(start 131.656582 -54.018434)
		(mid 131.316044 -54.216277)
		(end 131.309872 -54.61)
		(width 0.0889)
		(layer "B.Cu")
		(net "UPI_CPU0_CPU1_P1P1_DP<9>")
	)
	(arc
		(start 297.866816 -53.132736)
		(mid 297.920315 -52.932838)
		(end 297.866816 -52.73294)
		(width 0.0889)
		(layer "B.Cu")
		(net "UPI_CPU0_CPU1_P1P1_DP<9>")
	)
	(arc
		(start 132.880354 -58.28538)
		(mid 132.974467 -58.246397)
		(end 133.01345 -58.152284)
		(width 0.0889)
		(layer "B.Cu")
		(net "UPI_CPU0_CPU1_P1P1_DP<9>")
	)
	(arc
		(start 131.308348 -52.24907)
		(mid 131.274604 -52.334477)
		(end 131.261358 -52.425346)
		(width 0.0889)
		(layer "B.Cu")
		(net "UPI_CPU0_CPU1_P1P1_DP<9>")
	)
	(arc
		(start 131.314698 -55.209186)
		(mid 131.261228 -55.404249)
		(end 131.309872 -55.6006)
		(width 0.0889)
		(layer "B.Cu")
		(net "UPI_CPU0_CPU1_P1P1_DP<9>")
	)
	(arc
		(start 131.747768 -54.012338)
		(mid 131.704695 -54.016909)
		(end 131.661408 -54.018434)
		(width 0.0889)
		(layer "B.Cu")
		(net "UPI_CPU0_CPU1_P1P1_DP<9>")
	)
	(arc
		(start 131.646422 -52.83708)
		(mid 131.662805 -52.837391)
		(end 131.679188 -52.83708)
		(width 0.0889)
		(layer "B.Cu")
		(net "UPI_CPU0_CPU1_P1P1_DP<9>")
	)
	(arc
		(start 297.866816 -52.732686)
		(mid 297.806548 -52.584894)
		(end 297.788076 -52.426362)
		(width 0.0889)
		(layer "B.Cu")
		(net "UPI_CPU0_CPU1_P1P1_DP<9>")
	)
	(arc
		(start 131.314698 -57.190386)
		(mid 131.31195 -57.585853)
		(end 131.650232 -57.790588)
		(width 0.0889)
		(layer "B.Cu")
		(net "UPI_CPU0_CPU1_P1P1_DP<9>")
	)
	(arc
		(start 133.01345 -58.152284)
		(mid 132.935335 -57.963699)
		(end 132.74675 -57.885584)
		(width 0.0889)
		(layer "B.Cu")
		(net "UPI_CPU0_CPU1_P1P1_DP<9>")
	)
	(segment
		(start 131.089908 -57.390538)
		(end 131.661408 -57.390538)
		(width 0.1143)
		(layer "F.Cu")
		(net "UPI_CPU0_CPU1_P1P1_DP<8>")
	)
	(segment
		(start 296.948606 -53.923184)
		(end 297.520106 -53.923184)
		(width 0.1143)
		(layer "F.Cu")
		(net "UPI_CPU0_CPU1_P1P1_DP<8>")
	)
	(via
		(at 131.661408 -57.390538)
		(size 0.508)
		(drill 0.254)
		(layers "F.Cu" "B.Cu")
		(net "UPI_CPU0_CPU1_P1P1_DP<8>")
	)
	(via
		(at 297.520106 -53.923184)
		(size 0.508)
		(drill 0.254)
		(layers "F.Cu" "B.Cu")
		(net "UPI_CPU0_CPU1_P1P1_DP<8>")
	)
	(segment
		(start 132.682488 -51.006756)
		(end 135.10768 -48.581564)
		(width 0.1143)
		(layer "B.Cu")
		(net "UPI_CPU0_CPU1_P1P1_DP<8>")
	)
	(segment
		(start 256.595626 -38.587426)
		(end 260.657848 -39.118794)
		(width 0.1143)
		(layer "B.Cu")
		(net "UPI_CPU0_CPU1_P1P1_DP<8>")
	)
	(segment
		(start 222.396812 -42.255186)
		(end 226.149916 -43.005756)
		(width 0.1143)
		(layer "B.Cu")
		(net "UPI_CPU0_CPU1_P1P1_DP<8>")
	)
	(segment
		(start 287.165288 -42.684446)
		(end 287.438338 -42.85234)
		(width 0.1143)
		(layer "B.Cu")
		(net "UPI_CPU0_CPU1_P1P1_DP<8>")
	)
	(segment
		(start 132.707888 -52.459128)
		(end 132.707888 -51.928014)
		(width 0.0889)
		(layer "B.Cu")
		(net "UPI_CPU0_CPU1_P1P1_DP<8>")
	)
	(segment
		(start 186.458098 -36.76142)
		(end 190.798704 -36.140898)
		(width 0.1143)
		(layer "B.Cu")
		(net "UPI_CPU0_CPU1_P1P1_DP<8>")
	)
	(segment
		(start 182.12054 -37.20719)
		(end 185.241692 -36.468812)
		(width 0.1143)
		(layer "B.Cu")
		(net "UPI_CPU0_CPU1_P1P1_DP<8>")
	)
	(segment
		(start 167.340534 -40.08882)
		(end 171.461938 -40.889682)
		(width 0.1143)
		(layer "B.Cu")
		(net "UPI_CPU0_CPU1_P1P1_DP<8>")
	)
	(segment
		(start 291.994844 -45.249592)
		(end 294.432482 -46.914054)
		(width 0.1143)
		(layer "B.Cu")
		(net "UPI_CPU0_CPU1_P1P1_DP<8>")
	)
	(segment
		(start 280.248106 -43.03649)
		(end 287.165288 -42.684446)
		(width 0.1143)
		(layer "B.Cu")
		(net "UPI_CPU0_CPU1_P1P1_DP<8>")
	)
	(segment
		(start 296.47769 -50.800254)
		(end 296.487342 -50.820066)
		(width 0.0889)
		(layer "B.Cu")
		(net "UPI_CPU0_CPU1_P1P1_DP<8>")
	)
	(segment
		(start 251.865892 -38.2016)
		(end 253.131828 -38.723316)
		(width 0.1143)
		(layer "B.Cu")
		(net "UPI_CPU0_CPU1_P1P1_DP<8>")
	)
	(segment
		(start 196.863462 -35.787838)
		(end 205.36027 -37.487098)
		(width 0.1143)
		(layer "B.Cu")
		(net "UPI_CPU0_CPU1_P1P1_DP<8>")
	)
	(segment
		(start 296.403522 -50.648108)
		(end 296.47769 -50.800254)
		(width 0.1143)
		(layer "B.Cu")
		(net "UPI_CPU0_CPU1_P1P1_DP<8>")
	)
	(segment
		(start 210.95081 -39.966138)
		(end 210.96224 -39.96817)
		(width 0.1143)
		(layer "B.Cu")
		(net "UPI_CPU0_CPU1_P1P1_DP<8>")
	)
	(segment
		(start 242.601242 -38.107366)
		(end 248.006108 -37.025834)
		(width 0.1143)
		(layer "B.Cu")
		(net "UPI_CPU0_CPU1_P1P1_DP<8>")
	)
	(segment
		(start 132.682488 -51.880516)
		(end 132.682488 -51.006756)
		(width 0.1143)
		(layer "B.Cu")
		(net "UPI_CPU0_CPU1_P1P1_DP<8>")
	)
	(segment
		(start 287.438338 -42.85234)
		(end 290.44011 -44.849796)
		(width 0.1143)
		(layer "B.Cu")
		(net "UPI_CPU0_CPU1_P1P1_DP<8>")
	)
	(segment
		(start 190.798704 -36.140898)
		(end 196.863462 -35.787838)
		(width 0.1143)
		(layer "B.Cu")
		(net "UPI_CPU0_CPU1_P1P1_DP<8>")
	)
	(segment
		(start 296.5196 -50.926238)
		(end 297.182032 -52.008278)
		(width 0.0889)
		(layer "B.Cu")
		(net "UPI_CPU0_CPU1_P1P1_DP<8>")
	)
	(segment
		(start 296.487342 -50.820066)
		(end 296.475404 -50.854102)
		(width 0.0889)
		(layer "B.Cu")
		(net "UPI_CPU0_CPU1_P1P1_DP<8>")
	)
	(segment
		(start 297.252898 -52.387246)
		(end 297.25239 -52.445412)
		(width 0.0889)
		(layer "B.Cu")
		(net "UPI_CPU0_CPU1_P1P1_DP<8>")
	)
	(segment
		(start 136.810496 -46.056804)
		(end 140.072618 -43.856402)
		(width 0.1143)
		(layer "B.Cu")
		(net "UPI_CPU0_CPU1_P1P1_DP<8>")
	)
	(segment
		(start 297.227244 -54.092094)
		(end 297.520106 -53.923184)
		(width 0.0889)
		(layer "B.Cu")
		(net "UPI_CPU0_CPU1_P1P1_DP<8>")
	)
	(segment
		(start 132.860034 -53.143404)
		(end 132.866384 -53.132736)
		(width 0.0889)
		(layer "B.Cu")
		(net "UPI_CPU0_CPU1_P1P1_DP<8>")
	)
	(segment
		(start 297.252898 -52.2605)
		(end 297.252898 -52.387246)
		(width 0.0889)
		(layer "B.Cu")
		(net "UPI_CPU0_CPU1_P1P1_DP<8>")
	)
	(segment
		(start 131.760468 -57.023762)
		(end 132.007864 -56.599836)
		(width 0.0889)
		(layer "B.Cu")
		(net "UPI_CPU0_CPU1_P1P1_DP<8>")
	)
	(segment
		(start 163.059618 -40.551354)
		(end 164.374576 -40.814244)
		(width 0.1143)
		(layer "B.Cu")
		(net "UPI_CPU0_CPU1_P1P1_DP<8>")
	)
	(segment
		(start 132.682488 -51.902614)
		(end 132.682488 -51.880516)
		(width 0.0889)
		(layer "B.Cu")
		(net "UPI_CPU0_CPU1_P1P1_DP<8>")
	)
	(segment
		(start 154.717242 -40.463216)
		(end 158.874714 -41.27119)
		(width 0.1143)
		(layer "B.Cu")
		(net "UPI_CPU0_CPU1_P1P1_DP<8>")
	)
	(segment
		(start 205.36027 -37.487098)
		(end 209.033618 -39.678356)
		(width 0.1143)
		(layer "B.Cu")
		(net "UPI_CPU0_CPU1_P1P1_DP<8>")
	)
	(segment
		(start 210.96224 -39.96817)
		(end 222.396812 -42.255186)
		(width 0.1143)
		(layer "B.Cu")
		(net "UPI_CPU0_CPU1_P1P1_DP<8>")
	)
	(segment
		(start 226.149916 -43.005756)
		(end 239.149382 -40.407844)
		(width 0.1143)
		(layer "B.Cu")
		(net "UPI_CPU0_CPU1_P1P1_DP<8>")
	)
	(segment
		(start 171.461938 -40.889682)
		(end 176.791112 -39.048436)
		(width 0.1143)
		(layer "B.Cu")
		(net "UPI_CPU0_CPU1_P1P1_DP<8>")
	)
	(segment
		(start 260.657848 -39.118794)
		(end 280.248106 -43.03649)
		(width 0.1143)
		(layer "B.Cu")
		(net "UPI_CPU0_CPU1_P1P1_DP<8>")
	)
	(segment
		(start 239.149382 -40.407844)
		(end 242.601242 -38.107366)
		(width 0.1143)
		(layer "B.Cu")
		(net "UPI_CPU0_CPU1_P1P1_DP<8>")
	)
	(segment
		(start 294.432482 -46.914054)
		(end 295.494964 -48.519842)
		(width 0.1143)
		(layer "B.Cu")
		(net "UPI_CPU0_CPU1_P1P1_DP<8>")
	)
	(segment
		(start 161.625788 -40.264588)
		(end 163.059618 -40.5511)
		(width 0.1143)
		(layer "B.Cu")
		(net "UPI_CPU0_CPU1_P1P1_DP<8>")
	)
	(segment
		(start 290.44011 -44.849796)
		(end 291.994844 -45.249592)
		(width 0.1143)
		(layer "B.Cu")
		(net "UPI_CPU0_CPU1_P1P1_DP<8>")
	)
	(segment
		(start 248.006108 -37.025834)
		(end 250.322334 -37.48913)
		(width 0.1143)
		(layer "B.Cu")
		(net "UPI_CPU0_CPU1_P1P1_DP<8>")
	)
	(segment
		(start 132.707888 -51.928014)
		(end 132.682488 -51.902614)
		(width 0.0889)
		(layer "B.Cu")
		(net "UPI_CPU0_CPU1_P1P1_DP<8>")
	)
	(segment
		(start 253.131828 -38.723316)
		(end 256.595626 -38.587426)
		(width 0.1143)
		(layer "B.Cu")
		(net "UPI_CPU0_CPU1_P1P1_DP<8>")
	)
	(segment
		(start 209.033618 -39.678356)
		(end 210.95081 -39.966138)
		(width 0.1143)
		(layer "B.Cu")
		(net "UPI_CPU0_CPU1_P1P1_DP<8>")
	)
	(segment
		(start 164.374576 -40.814244)
		(end 167.340534 -40.08882)
		(width 0.1143)
		(layer "B.Cu")
		(net "UPI_CPU0_CPU1_P1P1_DP<8>")
	)
	(segment
		(start 297.173396 -52.732686)
		(end 297.17365 -52.73294)
		(width 0.0889)
		(layer "B.Cu")
		(net "UPI_CPU0_CPU1_P1P1_DP<8>")
	)
	(segment
		(start 131.998974 -55.624476)
		(end 132.007864 -55.609236)
		(width 0.0889)
		(layer "B.Cu")
		(net "UPI_CPU0_CPU1_P1P1_DP<8>")
	)
	(segment
		(start 185.241692 -36.468812)
		(end 186.458098 -36.76142)
		(width 0.1143)
		(layer "B.Cu")
		(net "UPI_CPU0_CPU1_P1P1_DP<8>")
	)
	(segment
		(start 296.475404 -50.854102)
		(end 296.5196 -50.926238)
		(width 0.0889)
		(layer "B.Cu")
		(net "UPI_CPU0_CPU1_P1P1_DP<8>")
	)
	(segment
		(start 132.87121 -53.731922)
		(end 132.866384 -53.723286)
		(width 0.0889)
		(layer "B.Cu")
		(net "UPI_CPU0_CPU1_P1P1_DP<8>")
	)
	(segment
		(start 135.10768 -48.581564)
		(end 136.810496 -46.056804)
		(width 0.1143)
		(layer "B.Cu")
		(net "UPI_CPU0_CPU1_P1P1_DP<8>")
	)
	(segment
		(start 297.182032 -52.008278)
		(end 297.252898 -52.2605)
		(width 0.0889)
		(layer "B.Cu")
		(net "UPI_CPU0_CPU1_P1P1_DP<8>")
	)
	(segment
		(start 158.874714 -41.27119)
		(end 161.625788 -40.264588)
		(width 0.1143)
		(layer "B.Cu")
		(net "UPI_CPU0_CPU1_P1P1_DP<8>")
	)
	(segment
		(start 297.148504 -54.070758)
		(end 297.227244 -54.092094)
		(width 0.0889)
		(layer "B.Cu")
		(net "UPI_CPU0_CPU1_P1P1_DP<8>")
	)
	(segment
		(start 132.501894 -54.323234)
		(end 132.53466 -54.323234)
		(width 0.0889)
		(layer "B.Cu")
		(net "UPI_CPU0_CPU1_P1P1_DP<8>")
	)
	(segment
		(start 140.072618 -43.856402)
		(end 154.717242 -40.463216)
		(width 0.1143)
		(layer "B.Cu")
		(net "UPI_CPU0_CPU1_P1P1_DP<8>")
	)
	(segment
		(start 132.866384 -52.73294)
		(end 132.707888 -52.459128)
		(width 0.0889)
		(layer "B.Cu")
		(net "UPI_CPU0_CPU1_P1P1_DP<8>")
	)
	(segment
		(start 163.059618 -40.5511)
		(end 163.059618 -40.551354)
		(width 0.1143)
		(layer "B.Cu")
		(net "UPI_CPU0_CPU1_P1P1_DP<8>")
	)
	(segment
		(start 297.17365 -53.132736)
		(end 297.18 -53.143404)
		(width 0.0889)
		(layer "B.Cu")
		(net "UPI_CPU0_CPU1_P1P1_DP<8>")
	)
	(segment
		(start 176.791112 -39.048436)
		(end 176.791112 -39.04869)
		(width 0.1143)
		(layer "B.Cu")
		(net "UPI_CPU0_CPU1_P1P1_DP<8>")
	)
	(segment
		(start 250.322334 -37.48913)
		(end 251.865892 -38.2016)
		(width 0.1143)
		(layer "B.Cu")
		(net "UPI_CPU0_CPU1_P1P1_DP<8>")
	)
	(segment
		(start 176.791112 -39.04869)
		(end 182.12054 -37.20719)
		(width 0.1143)
		(layer "B.Cu")
		(net "UPI_CPU0_CPU1_P1P1_DP<8>")
	)
	(segment
		(start 295.494964 -48.519842)
		(end 296.403522 -50.648108)
		(width 0.1143)
		(layer "B.Cu")
		(net "UPI_CPU0_CPU1_P1P1_DP<8>")
	)
	(arc
		(start 297.25239 -52.445412)
		(mid 297.231309 -52.594114)
		(end 297.173396 -52.732686)
		(width 0.0889)
		(layer "B.Cu")
		(net "UPI_CPU0_CPU1_P1P1_DP<8>")
	)
	(arc
		(start 132.007864 -56.20004)
		(mid 131.928675 -55.913425)
		(end 131.998974 -55.624476)
		(width 0.0889)
		(layer "B.Cu")
		(net "UPI_CPU0_CPU1_P1P1_DP<8>")
	)
	(arc
		(start 297.18 -53.143404)
		(mid 297.252798 -53.434167)
		(end 297.17365 -53.723286)
		(width 0.0889)
		(layer "B.Cu")
		(net "UPI_CPU0_CPU1_P1P1_DP<8>")
	)
	(arc
		(start 132.866384 -53.723286)
		(mid 132.787162 -53.434168)
		(end 132.860034 -53.143404)
		(width 0.0889)
		(layer "B.Cu")
		(net "UPI_CPU0_CPU1_P1P1_DP<8>")
	)
	(arc
		(start 297.17365 -52.73294)
		(mid 297.120117 -52.932838)
		(end 297.17365 -53.132736)
		(width 0.0889)
		(layer "B.Cu")
		(net "UPI_CPU0_CPU1_P1P1_DP<8>")
	)
	(arc
		(start 132.866384 -53.132736)
		(mid 132.919883 -52.932838)
		(end 132.866384 -52.73294)
		(width 0.0889)
		(layer "B.Cu")
		(net "UPI_CPU0_CPU1_P1P1_DP<8>")
	)
	(arc
		(start 132.007864 -55.609236)
		(mid 132.061397 -55.409338)
		(end 132.007864 -55.20944)
		(width 0.0889)
		(layer "B.Cu")
		(net "UPI_CPU0_CPU1_P1P1_DP<8>")
	)
	(arc
		(start 132.007864 -55.20944)
		(mid 132.003339 -54.626099)
		(end 132.501894 -54.323234)
		(width 0.0889)
		(layer "B.Cu")
		(net "UPI_CPU0_CPU1_P1P1_DP<8>")
	)
	(arc
		(start 132.53466 -54.323234)
		(mid 132.867578 -54.121243)
		(end 132.87121 -53.731922)
		(width 0.0889)
		(layer "B.Cu")
		(net "UPI_CPU0_CPU1_P1P1_DP<8>")
	)
	(arc
		(start 131.661408 -57.390538)
		(mid 131.686565 -57.200564)
		(end 131.760468 -57.023762)
		(width 0.0889)
		(layer "B.Cu")
		(net "UPI_CPU0_CPU1_P1P1_DP<8>")
	)
	(arc
		(start 297.17365 -53.723286)
		(mid 297.121282 -53.894135)
		(end 297.148504 -54.070758)
		(width 0.0889)
		(layer "B.Cu")
		(net "UPI_CPU0_CPU1_P1P1_DP<8>")
	)
	(arc
		(start 132.007864 -56.599836)
		(mid 132.061397 -56.399938)
		(end 132.007864 -56.20004)
		(width 0.0889)
		(layer "B.Cu")
		(net "UPI_CPU0_CPU1_P1P1_DP<8>")
	)
	(segment
		(start 132.806694 -57.390538)
		(end 133.378194 -57.390538)
		(width 0.1143)
		(layer "F.Cu")
		(net "UPI_CPU0_CPU1_P1P1_DP<7>")
	)
	(segment
		(start 296.66184 -53.427884)
		(end 296.09034 -53.427884)
		(width 0.1143)
		(layer "F.Cu")
		(net "UPI_CPU0_CPU1_P1P1_DP<7>")
	)
	(via
		(at 133.378194 -57.390538)
		(size 0.508)
		(drill 0.254)
		(layers "F.Cu" "B.Cu")
		(net "UPI_CPU0_CPU1_P1P1_DP<7>")
	)
	(via
		(at 296.66184 -53.427884)
		(size 0.508)
		(drill 0.254)
		(layers "F.Cu" "B.Cu")
		(net "UPI_CPU0_CPU1_P1P1_DP<7>")
	)
	(segment
		(start 256.404618 -39.661846)
		(end 260.989064 -40.203628)
		(width 0.1143)
		(layer "B.Cu")
		(net "UPI_CPU0_CPU1_P1P1_DP<7>")
	)
	(segment
		(start 296.201592 -52.028598)
		(end 296.26179 -52.450238)
		(width 0.0889)
		(layer "B.Cu")
		(net "UPI_CPU0_CPU1_P1P1_DP<7>")
	)
	(segment
		(start 279.552146 -43.899836)
		(end 280.069544 -44.018454)
		(width 0.1143)
		(layer "B.Cu")
		(net "UPI_CPU0_CPU1_P1P1_DP<7>")
	)
	(segment
		(start 208.516728 -40.499284)
		(end 222.396812 -43.248326)
		(width 0.1143)
		(layer "B.Cu")
		(net "UPI_CPU0_CPU1_P1P1_DP<7>")
	)
	(segment
		(start 261.12978 -40.21455)
		(end 279.545288 -43.898058)
		(width 0.1143)
		(layer "B.Cu")
		(net "UPI_CPU0_CPU1_P1P1_DP<7>")
	)
	(segment
		(start 239.691164 -41.302178)
		(end 243.622322 -38.681152)
		(width 0.1143)
		(layer "B.Cu")
		(net "UPI_CPU0_CPU1_P1P1_DP<7>")
	)
	(segment
		(start 132.866384 -55.704486)
		(end 132.860034 -55.693818)
		(width 0.0889)
		(layer "B.Cu")
		(net "UPI_CPU0_CPU1_P1P1_DP<7>")
	)
	(segment
		(start 180.857906 -38.667944)
		(end 185.1025 -37.523928)
		(width 0.1143)
		(layer "B.Cu")
		(net "UPI_CPU0_CPU1_P1P1_DP<7>")
	)
	(segment
		(start 296.394378 -52.9336)
		(end 296.66184 -53.427884)
		(width 0.0889)
		(layer "B.Cu")
		(net "UPI_CPU0_CPU1_P1P1_DP<7>")
	)
	(segment
		(start 136.231376 -49.07534)
		(end 137.60704 -47.035974)
		(width 0.1143)
		(layer "B.Cu")
		(net "UPI_CPU0_CPU1_P1P1_DP<7>")
	)
	(segment
		(start 186.489594 -37.776658)
		(end 186.501278 -37.778944)
		(width 0.1143)
		(layer "B.Cu")
		(net "UPI_CPU0_CPU1_P1P1_DP<7>")
	)
	(segment
		(start 133.724904 -52.637436)
		(end 133.72973 -52.6288)
		(width 0.0889)
		(layer "B.Cu")
		(net "UPI_CPU0_CPU1_P1P1_DP<7>")
	)
	(segment
		(start 186.50204 -37.778944)
		(end 190.72987 -36.933632)
		(width 0.1143)
		(layer "B.Cu")
		(net "UPI_CPU0_CPU1_P1P1_DP<7>")
	)
	(segment
		(start 135.13181 -50.211228)
		(end 135.147304 -50.159666)
		(width 0.0889)
		(layer "B.Cu")
		(net "UPI_CPU0_CPU1_P1P1_DP<7>")
	)
	(segment
		(start 252.649228 -39.728648)
		(end 256.404618 -39.661846)
		(width 0.1143)
		(layer "B.Cu")
		(net "UPI_CPU0_CPU1_P1P1_DP<7>")
	)
	(segment
		(start 293.629334 -48.24095)
		(end 295.395142 -50.889916)
		(width 0.1143)
		(layer "B.Cu")
		(net "UPI_CPU0_CPU1_P1P1_DP<7>")
	)
	(segment
		(start 290.081716 -45.602398)
		(end 290.652962 -45.741082)
		(width 0.1143)
		(layer "B.Cu")
		(net "UPI_CPU0_CPU1_P1P1_DP<7>")
	)
	(segment
		(start 280.069544 -44.018454)
		(end 287.142682 -43.671998)
		(width 0.1143)
		(layer "B.Cu")
		(net "UPI_CPU0_CPU1_P1P1_DP<7>")
	)
	(segment
		(start 186.48934 -37.776912)
		(end 186.489594 -37.776658)
		(width 0.1143)
		(layer "B.Cu")
		(net "UPI_CPU0_CPU1_P1P1_DP<7>")
	)
	(segment
		(start 133.356604 -54.818788)
		(end 133.38937 -54.818788)
		(width 0.0889)
		(layer "B.Cu")
		(net "UPI_CPU0_CPU1_P1P1_DP<7>")
	)
	(segment
		(start 295.402 -50.9524)
		(end 296.056812 -51.750214)
		(width 0.0889)
		(layer "B.Cu")
		(net "UPI_CPU0_CPU1_P1P1_DP<7>")
	)
	(segment
		(start 140.748258 -44.917106)
		(end 141.336014 -44.800012)
		(width 0.1143)
		(layer "B.Cu")
		(net "UPI_CPU0_CPU1_P1P1_DP<7>")
	)
	(segment
		(start 290.652962 -45.741082)
		(end 290.653216 -45.74159)
		(width 0.1143)
		(layer "B.Cu")
		(net "UPI_CPU0_CPU1_P1P1_DP<7>")
	)
	(segment
		(start 137.60704 -47.035974)
		(end 140.748258 -44.917106)
		(width 0.1143)
		(layer "B.Cu")
		(net "UPI_CPU0_CPU1_P1P1_DP<7>")
	)
	(segment
		(start 293.629334 -48.241204)
		(end 293.629334 -48.24095)
		(width 0.1143)
		(layer "B.Cu")
		(net "UPI_CPU0_CPU1_P1P1_DP<7>")
	)
	(segment
		(start 260.989064 -40.203628)
		(end 261.12978 -40.21455)
		(width 0.1143)
		(layer "B.Cu")
		(net "UPI_CPU0_CPU1_P1P1_DP<7>")
	)
	(segment
		(start 167.3606 -41.094152)
		(end 171.731432 -42.074338)
		(width 0.1143)
		(layer "B.Cu")
		(net "UPI_CPU0_CPU1_P1P1_DP<7>")
	)
	(segment
		(start 248.00814 -37.80409)
		(end 249.89409 -38.18128)
		(width 0.1143)
		(layer "B.Cu")
		(net "UPI_CPU0_CPU1_P1P1_DP<7>")
	)
	(segment
		(start 226.19462 -44.00042)
		(end 239.691164 -41.302178)
		(width 0.1143)
		(layer "B.Cu")
		(net "UPI_CPU0_CPU1_P1P1_DP<7>")
	)
	(segment
		(start 222.396812 -43.248326)
		(end 226.19462 -44.00042)
		(width 0.1143)
		(layer "B.Cu")
		(net "UPI_CPU0_CPU1_P1P1_DP<7>")
	)
	(segment
		(start 293.024814 -47.333408)
		(end 293.629334 -48.241204)
		(width 0.1143)
		(layer "B.Cu")
		(net "UPI_CPU0_CPU1_P1P1_DP<7>")
	)
	(segment
		(start 133.813804 -51.529234)
		(end 135.13181 -50.211228)
		(width 0.0889)
		(layer "B.Cu")
		(net "UPI_CPU0_CPU1_P1P1_DP<7>")
	)
	(segment
		(start 295.402 -50.896774)
		(end 295.402 -50.9524)
		(width 0.0889)
		(layer "B.Cu")
		(net "UPI_CPU0_CPU1_P1P1_DP<7>")
	)
	(segment
		(start 155.006802 -41.504108)
		(end 159.142684 -42.308018)
		(width 0.1143)
		(layer "B.Cu")
		(net "UPI_CPU0_CPU1_P1P1_DP<7>")
	)
	(segment
		(start 186.501278 -37.778944)
		(end 186.50204 -37.778944)
		(width 0.1143)
		(layer "B.Cu")
		(net "UPI_CPU0_CPU1_P1P1_DP<7>")
	)
	(segment
		(start 290.653216 -45.74159)
		(end 291.32022 -45.903642)
		(width 0.1143)
		(layer "B.Cu")
		(net "UPI_CPU0_CPU1_P1P1_DP<7>")
	)
	(segment
		(start 295.395142 -50.889916)
		(end 295.402 -50.896774)
		(width 0.0889)
		(layer "B.Cu")
		(net "UPI_CPU0_CPU1_P1P1_DP<7>")
	)
	(segment
		(start 164.569902 -41.830244)
		(end 167.3606 -41.094152)
		(width 0.1143)
		(layer "B.Cu")
		(net "UPI_CPU0_CPU1_P1P1_DP<7>")
	)
	(segment
		(start 133.724904 -53.227986)
		(end 133.718554 -53.217318)
		(width 0.0889)
		(layer "B.Cu")
		(net "UPI_CPU0_CPU1_P1P1_DP<7>")
	)
	(segment
		(start 141.336014 -44.800012)
		(end 155.006802 -41.504108)
		(width 0.1143)
		(layer "B.Cu")
		(net "UPI_CPU0_CPU1_P1P1_DP<7>")
	)
	(segment
		(start 161.709608 -41.270682)
		(end 164.516562 -41.831768)
		(width 0.1143)
		(layer "B.Cu")
		(net "UPI_CPU0_CPU1_P1P1_DP<7>")
	)
	(segment
		(start 287.142682 -43.671998)
		(end 290.081716 -45.602398)
		(width 0.1143)
		(layer "B.Cu")
		(net "UPI_CPU0_CPU1_P1P1_DP<7>")
	)
	(segment
		(start 159.142684 -42.308018)
		(end 159.198056 -42.318686)
		(width 0.1143)
		(layer "B.Cu")
		(net "UPI_CPU0_CPU1_P1P1_DP<7>")
	)
	(segment
		(start 196.898514 -36.58235)
		(end 204.879702 -38.178486)
		(width 0.1143)
		(layer "B.Cu")
		(net "UPI_CPU0_CPU1_P1P1_DP<7>")
	)
	(segment
		(start 190.72987 -36.933632)
		(end 196.898514 -36.58235)
		(width 0.1143)
		(layer "B.Cu")
		(net "UPI_CPU0_CPU1_P1P1_DP<7>")
	)
	(segment
		(start 279.545288 -43.898058)
		(end 279.552146 -43.899836)
		(width 0.1143)
		(layer "B.Cu")
		(net "UPI_CPU0_CPU1_P1P1_DP<7>")
	)
	(segment
		(start 249.89409 -38.18128)
		(end 252.649228 -39.728648)
		(width 0.1143)
		(layer "B.Cu")
		(net "UPI_CPU0_CPU1_P1P1_DP<7>")
	)
	(segment
		(start 164.516562 -41.831768)
		(end 164.569902 -41.830244)
		(width 0.1143)
		(layer "B.Cu")
		(net "UPI_CPU0_CPU1_P1P1_DP<7>")
	)
	(segment
		(start 243.622322 -38.681152)
		(end 248.00814 -37.80409)
		(width 0.1143)
		(layer "B.Cu")
		(net "UPI_CPU0_CPU1_P1P1_DP<7>")
	)
	(segment
		(start 159.198056 -42.318686)
		(end 161.709608 -41.270682)
		(width 0.1143)
		(layer "B.Cu")
		(net "UPI_CPU0_CPU1_P1P1_DP<7>")
	)
	(segment
		(start 171.731432 -42.074338)
		(end 180.857906 -38.667944)
		(width 0.1143)
		(layer "B.Cu")
		(net "UPI_CPU0_CPU1_P1P1_DP<7>")
	)
	(segment
		(start 133.378194 -57.390538)
		(end 132.92963 -56.784494)
		(width 0.0889)
		(layer "B.Cu")
		(net "UPI_CPU0_CPU1_P1P1_DP<7>")
	)
	(segment
		(start 132.87121 -55.713122)
		(end 132.866384 -55.704486)
		(width 0.0889)
		(layer "B.Cu")
		(net "UPI_CPU0_CPU1_P1P1_DP<7>")
	)
	(segment
		(start 185.1025 -37.523928)
		(end 186.48934 -37.776912)
		(width 0.1143)
		(layer "B.Cu")
		(net "UPI_CPU0_CPU1_P1P1_DP<7>")
	)
	(segment
		(start 135.147304 -50.159666)
		(end 136.231376 -49.07534)
		(width 0.1143)
		(layer "B.Cu")
		(net "UPI_CPU0_CPU1_P1P1_DP<7>")
	)
	(segment
		(start 296.056812 -51.750214)
		(end 296.201592 -52.028598)
		(width 0.0889)
		(layer "B.Cu")
		(net "UPI_CPU0_CPU1_P1P1_DP<7>")
	)
	(segment
		(start 291.32022 -45.903642)
		(end 293.024814 -47.333408)
		(width 0.1143)
		(layer "B.Cu")
		(net "UPI_CPU0_CPU1_P1P1_DP<7>")
	)
	(segment
		(start 204.879702 -38.178486)
		(end 208.516728 -40.499284)
		(width 0.1143)
		(layer "B.Cu")
		(net "UPI_CPU0_CPU1_P1P1_DP<7>")
	)
	(arc
		(start 133.724904 -53.627782)
		(mid 133.778403 -53.427884)
		(end 133.724904 -53.227986)
		(width 0.0889)
		(layer "B.Cu")
		(net "UPI_CPU0_CPU1_P1P1_DP<7>")
	)
	(arc
		(start 133.38937 -54.818788)
		(mid 133.727539 -54.61399)
		(end 133.724904 -54.218586)
		(width 0.0889)
		(layer "B.Cu")
		(net "UPI_CPU0_CPU1_P1P1_DP<7>")
	)
	(arc
		(start 132.866384 -56.104536)
		(mid 132.919854 -55.909473)
		(end 132.87121 -55.713122)
		(width 0.0889)
		(layer "B.Cu")
		(net "UPI_CPU0_CPU1_P1P1_DP<7>")
	)
	(arc
		(start 132.860034 -55.693818)
		(mid 132.864065 -55.117636)
		(end 133.356604 -54.818788)
		(width 0.0889)
		(layer "B.Cu")
		(net "UPI_CPU0_CPU1_P1P1_DP<7>")
	)
	(arc
		(start 133.724904 -52.237386)
		(mid 133.650375 -51.868374)
		(end 133.813804 -51.529234)
		(width 0.0889)
		(layer "B.Cu")
		(net "UPI_CPU0_CPU1_P1P1_DP<7>")
	)
	(arc
		(start 132.92963 -56.784494)
		(mid 132.789886 -56.454588)
		(end 132.866384 -56.104536)
		(width 0.0889)
		(layer "B.Cu")
		(net "UPI_CPU0_CPU1_P1P1_DP<7>")
	)
	(arc
		(start 133.724904 -54.218586)
		(mid 133.645773 -53.923184)
		(end 133.724904 -53.627782)
		(width 0.0889)
		(layer "B.Cu")
		(net "UPI_CPU0_CPU1_P1P1_DP<7>")
	)
	(arc
		(start 296.31513 -52.637436)
		(mid 296.374296 -52.78029)
		(end 296.394378 -52.9336)
		(width 0.0889)
		(layer "B.Cu")
		(net "UPI_CPU0_CPU1_P1P1_DP<7>")
	)
	(arc
		(start 296.26179 -52.450238)
		(mid 296.276886 -52.547137)
		(end 296.31513 -52.637436)
		(width 0.0889)
		(layer "B.Cu")
		(net "UPI_CPU0_CPU1_P1P1_DP<7>")
	)
	(arc
		(start 133.72973 -52.6288)
		(mid 133.778485 -52.432448)
		(end 133.724904 -52.237386)
		(width 0.0889)
		(layer "B.Cu")
		(net "UPI_CPU0_CPU1_P1P1_DP<7>")
	)
	(arc
		(start 133.718554 -53.217318)
		(mid 133.645756 -52.926555)
		(end 133.724904 -52.637436)
		(width 0.0889)
		(layer "B.Cu")
		(net "UPI_CPU0_CPU1_P1P1_DP<7>")
	)
	(segment
		(start 133.665214 -58.876438)
		(end 134.236714 -58.876438)
		(width 0.1143)
		(layer "F.Cu")
		(net "UPI_CPU0_CPU1_P1P1_DP<6>")
	)
	(segment
		(start 295.23182 -54.913784)
		(end 295.80332 -54.913784)
		(width 0.1143)
		(layer "F.Cu")
		(net "UPI_CPU0_CPU1_P1P1_DP<6>")
	)
	(via
		(at 134.236714 -58.876438)
		(size 0.508)
		(drill 0.254)
		(layers "F.Cu" "B.Cu")
		(net "UPI_CPU0_CPU1_P1P1_DP<6>")
	)
	(via
		(at 152.843738 -43.402504)
		(size 0.508)
		(drill 0.254)
		(layers "F.Cu" "B.Cu")
		(net "UPI_CPU0_CPU1_P1P1_DP<6>")
	)
	(via
		(at 295.80332 -54.913784)
		(size 0.508)
		(drill 0.254)
		(layers "F.Cu" "B.Cu")
		(net "UPI_CPU0_CPU1_P1P1_DP<6>")
	)
	(segment
		(start 258.821174 -41.293796)
		(end 258.821174 -41.29405)
		(width 0.1143)
		(layer "B.Cu")
		(net "UPI_CPU0_CPU1_P1P1_DP<6>")
	)
	(segment
		(start 287.01746 -44.92371)
		(end 287.1216 -44.990004)
		(width 0.1143)
		(layer "B.Cu")
		(net "UPI_CPU0_CPU1_P1P1_DP<6>")
	)
	(segment
		(start 244.841522 -39.481252)
		(end 248.003568 -38.8493)
		(width 0.1143)
		(layer "B.Cu")
		(net "UPI_CPU0_CPU1_P1P1_DP<6>")
	)
	(segment
		(start 291.564568 -47.802292)
		(end 292.508432 -49.011332)
		(width 0.1143)
		(layer "B.Cu")
		(net "UPI_CPU0_CPU1_P1P1_DP<6>")
	)
	(segment
		(start 136.814814 -50.46345)
		(end 137.52703 -49.751234)
		(width 0.1143)
		(layer "B.Cu")
		(net "UPI_CPU0_CPU1_P1P1_DP<6>")
	)
	(segment
		(start 280.006298 -45.255942)
		(end 287.01746 -44.92371)
		(width 0.1143)
		(layer "B.Cu")
		(net "UPI_CPU0_CPU1_P1P1_DP<6>")
	)
	(segment
		(start 136.070594 -51.30419)
		(end 136.196324 -51.17846)
		(width 0.0889)
		(layer "B.Cu")
		(net "UPI_CPU0_CPU1_P1P1_DP<6>")
	)
	(segment
		(start 186.000136 -40.138096)
		(end 189.496954 -39.399464)
		(width 0.1143)
		(layer "B.Cu")
		(net "UPI_CPU0_CPU1_P1P1_DP<6>")
	)
	(segment
		(start 208.16062 -41.66108)
		(end 222.396812 -44.508166)
		(width 0.1143)
		(layer "B.Cu")
		(net "UPI_CPU0_CPU1_P1P1_DP<6>")
	)
	(segment
		(start 290.421822 -46.87951)
		(end 291.564568 -47.802292)
		(width 0.1143)
		(layer "B.Cu")
		(net "UPI_CPU0_CPU1_P1P1_DP<6>")
	)
	(segment
		(start 138.918442 -47.917608)
		(end 139.059412 -47.94504)
		(width 0.1143)
		(layer "B.Cu")
		(net "UPI_CPU0_CPU1_P1P1_DP<6>")
	)
	(segment
		(start 192.31991 -37.907722)
		(end 196.981572 -37.623242)
		(width 0.1143)
		(layer "B.Cu")
		(net "UPI_CPU0_CPU1_P1P1_DP<6>")
	)
	(segment
		(start 136.79932 -50.478944)
		(end 136.814814 -50.46345)
		(width 0.0889)
		(layer "B.Cu")
		(net "UPI_CPU0_CPU1_P1P1_DP<6>")
	)
	(segment
		(start 135.080248 -52.037488)
		(end 135.113014 -52.037488)
		(width 0.0889)
		(layer "B.Cu")
		(net "UPI_CPU0_CPU1_P1P1_DP<6>")
	)
	(segment
		(start 293.857426 -50.823114)
		(end 294.000174 -50.837592)
		(width 0.1143)
		(layer "B.Cu")
		(net "UPI_CPU0_CPU1_P1P1_DP<6>")
	)
	(segment
		(start 134.236714 -58.876438)
		(end 133.943598 -59.045348)
		(width 0.0889)
		(layer "B.Cu")
		(net "UPI_CPU0_CPU1_P1P1_DP<6>")
	)
	(segment
		(start 134.754874 -54.629304)
		(end 134.748524 -54.618636)
		(width 0.0889)
		(layer "B.Cu")
		(net "UPI_CPU0_CPU1_P1P1_DP<6>")
	)
	(segment
		(start 189.78753 -39.212012)
		(end 190.689738 -38.62959)
		(width 0.1143)
		(layer "B.Cu")
		(net "UPI_CPU0_CPU1_P1P1_DP<6>")
	)
	(segment
		(start 136.580372 -50.794412)
		(end 136.580372 -50.661824)
		(width 0.0889)
		(layer "B.Cu")
		(net "UPI_CPU0_CPU1_P1P1_DP<6>")
	)
	(segment
		(start 136.580372 -50.661824)
		(end 136.763252 -50.478944)
		(width 0.0889)
		(layer "B.Cu")
		(net "UPI_CPU0_CPU1_P1P1_DP<6>")
	)
	(segment
		(start 138.634216 -48.109378)
		(end 138.918442 -47.917608)
		(width 0.1143)
		(layer "B.Cu")
		(net "UPI_CPU0_CPU1_P1P1_DP<6>")
	)
	(segment
		(start 289.870134 -46.736762)
		(end 290.421822 -46.87951)
		(width 0.1143)
		(layer "B.Cu")
		(net "UPI_CPU0_CPU1_P1P1_DP<6>")
	)
	(segment
		(start 165.003988 -43.062144)
		(end 165.730428 -42.883836)
		(width 0.1143)
		(layer "B.Cu")
		(net "UPI_CPU0_CPU1_P1P1_DP<6>")
	)
	(segment
		(start 139.79652 -47.447708)
		(end 140.081 -47.255684)
		(width 0.1143)
		(layer "B.Cu")
		(net "UPI_CPU0_CPU1_P1P1_DP<6>")
	)
	(segment
		(start 152.843738 -43.402504)
		(end 155.263088 -42.792904)
		(width 0.1143)
		(layer "B.Cu")
		(net "UPI_CPU0_CPU1_P1P1_DP<6>")
	)
	(segment
		(start 140.081 -47.255684)
		(end 140.108432 -47.114714)
		(width 0.1143)
		(layer "B.Cu")
		(net "UPI_CPU0_CPU1_P1P1_DP<6>")
	)
	(segment
		(start 294.35806 -51.208178)
		(end 295.34485 -52.194714)
		(width 0.0889)
		(layer "B.Cu")
		(net "UPI_CPU0_CPU1_P1P1_DP<6>")
	)
	(segment
		(start 140.392658 -46.923198)
		(end 140.533628 -46.950376)
		(width 0.1143)
		(layer "B.Cu")
		(net "UPI_CPU0_CPU1_P1P1_DP<6>")
	)
	(segment
		(start 141.298676 -46.31182)
		(end 152.843738 -43.402504)
		(width 0.1143)
		(layer "B.Cu")
		(net "UPI_CPU0_CPU1_P1P1_DP<6>")
	)
	(segment
		(start 133.885178 -56.703722)
		(end 133.890004 -56.695086)
		(width 0.0889)
		(layer "B.Cu")
		(net "UPI_CPU0_CPU1_P1P1_DP<6>")
	)
	(segment
		(start 140.533628 -46.950376)
		(end 140.818108 -46.758606)
		(width 0.1143)
		(layer "B.Cu")
		(net "UPI_CPU0_CPU1_P1P1_DP<6>")
	)
	(segment
		(start 294.21709 -51.103022)
		(end 294.307006 -51.192938)
		(width 0.1143)
		(layer "B.Cu")
		(net "UPI_CPU0_CPU1_P1P1_DP<6>")
	)
	(segment
		(start 293.640256 -50.55743)
		(end 293.857426 -50.823114)
		(width 0.1143)
		(layer "B.Cu")
		(net "UPI_CPU0_CPU1_P1P1_DP<6>")
	)
	(segment
		(start 240.28273 -42.520108)
		(end 244.841522 -39.481252)
		(width 0.1143)
		(layer "B.Cu")
		(net "UPI_CPU0_CPU1_P1P1_DP<6>")
	)
	(segment
		(start 226.370388 -45.302678)
		(end 240.28273 -42.520108)
		(width 0.1143)
		(layer "B.Cu")
		(net "UPI_CPU0_CPU1_P1P1_DP<6>")
	)
	(segment
		(start 133.890004 -57.685686)
		(end 133.896354 -57.675018)
		(width 0.0889)
		(layer "B.Cu")
		(net "UPI_CPU0_CPU1_P1P1_DP<6>")
	)
	(segment
		(start 134.748524 -54.618636)
		(end 134.743698 -54.61)
		(width 0.0889)
		(layer "B.Cu")
		(net "UPI_CPU0_CPU1_P1P1_DP<6>")
	)
	(segment
		(start 293.65448 -50.414428)
		(end 293.640256 -50.55743)
		(width 0.1143)
		(layer "B.Cu")
		(net "UPI_CPU0_CPU1_P1P1_DP<6>")
	)
	(segment
		(start 161.876232 -42.54373)
		(end 164.73043 -43.114214)
		(width 0.1143)
		(layer "B.Cu")
		(net "UPI_CPU0_CPU1_P1P1_DP<6>")
	)
	(segment
		(start 294.000174 -50.837592)
		(end 294.21709 -51.103022)
		(width 0.1143)
		(layer "B.Cu")
		(net "UPI_CPU0_CPU1_P1P1_DP<6>")
	)
	(segment
		(start 138.05154 -49.155096)
		(end 138.024108 -49.014126)
		(width 0.1143)
		(layer "B.Cu")
		(net "UPI_CPU0_CPU1_P1P1_DP<6>")
	)
	(segment
		(start 136.196324 -51.17846)
		(end 136.196324 -51.045872)
		(width 0.0889)
		(layer "B.Cu")
		(net "UPI_CPU0_CPU1_P1P1_DP<6>")
	)
	(segment
		(start 171.030646 -43.456352)
		(end 181.440836 -41.377362)
		(width 0.1143)
		(layer "B.Cu")
		(net "UPI_CPU0_CPU1_P1P1_DP<6>")
	)
	(segment
		(start 222.396812 -44.508166)
		(end 226.370388 -45.302678)
		(width 0.1143)
		(layer "B.Cu")
		(net "UPI_CPU0_CPU1_P1P1_DP<6>")
	)
	(segment
		(start 136.763252 -50.478944)
		(end 136.79932 -50.478944)
		(width 0.0889)
		(layer "B.Cu")
		(net "UPI_CPU0_CPU1_P1P1_DP<6>")
	)
	(segment
		(start 189.496954 -39.399464)
		(end 189.78753 -39.212012)
		(width 0.1143)
		(layer "B.Cu")
		(net "UPI_CPU0_CPU1_P1P1_DP<6>")
	)
	(segment
		(start 140.818108 -46.758606)
		(end 140.84554 -46.617382)
		(width 0.1143)
		(layer "B.Cu")
		(net "UPI_CPU0_CPU1_P1P1_DP<6>")
	)
	(segment
		(start 164.73043 -43.114214)
		(end 165.003988 -43.062144)
		(width 0.1143)
		(layer "B.Cu")
		(net "UPI_CPU0_CPU1_P1P1_DP<6>")
	)
	(segment
		(start 139.65555 -47.42053)
		(end 139.79652 -47.447708)
		(width 0.1143)
		(layer "B.Cu")
		(net "UPI_CPU0_CPU1_P1P1_DP<6>")
	)
	(segment
		(start 136.454642 -50.920142)
		(end 136.580372 -50.794412)
		(width 0.0889)
		(layer "B.Cu")
		(net "UPI_CPU0_CPU1_P1P1_DP<6>")
	)
	(segment
		(start 138.024108 -49.014126)
		(end 138.634216 -48.109378)
		(width 0.1143)
		(layer "B.Cu")
		(net "UPI_CPU0_CPU1_P1P1_DP<6>")
	)
	(segment
		(start 252.621542 -41.189402)
		(end 258.821174 -41.293796)
		(width 0.1143)
		(layer "B.Cu")
		(net "UPI_CPU0_CPU1_P1P1_DP<6>")
	)
	(segment
		(start 295.29151 -54.218586)
		(end 295.357042 -54.332124)
		(width 0.0889)
		(layer "B.Cu")
		(net "UPI_CPU0_CPU1_P1P1_DP<6>")
	)
	(segment
		(start 133.943598 -59.045348)
		(end 133.864858 -59.024012)
		(width 0.0889)
		(layer "B.Cu")
		(net "UPI_CPU0_CPU1_P1P1_DP<6>")
	)
	(segment
		(start 292.508432 -49.011332)
		(end 293.65448 -50.414428)
		(width 0.1143)
		(layer "B.Cu")
		(net "UPI_CPU0_CPU1_P1P1_DP<6>")
	)
	(segment
		(start 135.113014 -52.837334)
		(end 135.0772 -52.837334)
		(width 0.0889)
		(layer "B.Cu")
		(net "UPI_CPU0_CPU1_P1P1_DP<6>")
	)
	(segment
		(start 294.307006 -51.192938)
		(end 294.3225 -51.208432)
		(width 0.0889)
		(layer "B.Cu")
		(net "UPI_CPU0_CPU1_P1P1_DP<6>")
	)
	(segment
		(start 136.322054 -50.920142)
		(end 136.454642 -50.920142)
		(width 0.0889)
		(layer "B.Cu")
		(net "UPI_CPU0_CPU1_P1P1_DP<6>")
	)
	(segment
		(start 139.371324 -47.612046)
		(end 139.65555 -47.42053)
		(width 0.1143)
		(layer "B.Cu")
		(net "UPI_CPU0_CPU1_P1P1_DP<6>")
	)
	(segment
		(start 133.890004 -56.695086)
		(end 133.896354 -56.684418)
		(width 0.0889)
		(layer "B.Cu")
		(net "UPI_CPU0_CPU1_P1P1_DP<6>")
	)
	(segment
		(start 135.080248 -54.018688)
		(end 135.108188 -54.018688)
		(width 0.0889)
		(layer "B.Cu")
		(net "UPI_CPU0_CPU1_P1P1_DP<6>")
	)
	(segment
		(start 140.108432 -47.114714)
		(end 140.392658 -46.923198)
		(width 0.1143)
		(layer "B.Cu")
		(net "UPI_CPU0_CPU1_P1P1_DP<6>")
	)
	(segment
		(start 196.981572 -37.623242)
		(end 204.258926 -39.078916)
		(width 0.1143)
		(layer "B.Cu")
		(net "UPI_CPU0_CPU1_P1P1_DP<6>")
	)
	(segment
		(start 294.3225 -51.208432)
		(end 294.35806 -51.208178)
		(width 0.0889)
		(layer "B.Cu")
		(net "UPI_CPU0_CPU1_P1P1_DP<6>")
	)
	(segment
		(start 295.34485 -52.194714)
		(end 295.34485 -52.44592)
		(width 0.0889)
		(layer "B.Cu")
		(net "UPI_CPU0_CPU1_P1P1_DP<6>")
	)
	(segment
		(start 137.85977 -49.439576)
		(end 138.05154 -49.155096)
		(width 0.1143)
		(layer "B.Cu")
		(net "UPI_CPU0_CPU1_P1P1_DP<6>")
	)
	(segment
		(start 165.730428 -42.883836)
		(end 167.151812 -42.440352)
		(width 0.1143)
		(layer "B.Cu")
		(net "UPI_CPU0_CPU1_P1P1_DP<6>")
	)
	(segment
		(start 261.300468 -41.486328)
		(end 279.26284 -45.078904)
		(width 0.1143)
		(layer "B.Cu")
		(net "UPI_CPU0_CPU1_P1P1_DP<6>")
	)
	(segment
		(start 167.151812 -42.440352)
		(end 171.030646 -43.456352)
		(width 0.1143)
		(layer "B.Cu")
		(net "UPI_CPU0_CPU1_P1P1_DP<6>")
	)
	(segment
		(start 204.258926 -39.078916)
		(end 208.16062 -41.66108)
		(width 0.1143)
		(layer "B.Cu")
		(net "UPI_CPU0_CPU1_P1P1_DP<6>")
	)
	(segment
		(start 135.607044 -51.742086)
		(end 135.753348 -51.488848)
		(width 0.0889)
		(layer "B.Cu")
		(net "UPI_CPU0_CPU1_P1P1_DP<6>")
	)
	(segment
		(start 155.263088 -42.792904)
		(end 159.384492 -43.59402)
		(width 0.1143)
		(layer "B.Cu")
		(net "UPI_CPU0_CPU1_P1P1_DP<6>")
	)
	(segment
		(start 139.343892 -47.753016)
		(end 139.371324 -47.612046)
		(width 0.1143)
		(layer "B.Cu")
		(net "UPI_CPU0_CPU1_P1P1_DP<6>")
	)
	(segment
		(start 135.938006 -51.30419)
		(end 136.070594 -51.30419)
		(width 0.0889)
		(layer "B.Cu")
		(net "UPI_CPU0_CPU1_P1P1_DP<6>")
	)
	(segment
		(start 137.52703 -49.751234)
		(end 137.718546 -49.467008)
		(width 0.1143)
		(layer "B.Cu")
		(net "UPI_CPU0_CPU1_P1P1_DP<6>")
	)
	(segment
		(start 279.26284 -45.078904)
		(end 280.006298 -45.255942)
		(width 0.1143)
		(layer "B.Cu")
		(net "UPI_CPU0_CPU1_P1P1_DP<6>")
	)
	(segment
		(start 190.689738 -38.62959)
		(end 192.31991 -37.907722)
		(width 0.1143)
		(layer "B.Cu")
		(net "UPI_CPU0_CPU1_P1P1_DP<6>")
	)
	(segment
		(start 133.885178 -57.694322)
		(end 133.890004 -57.685686)
		(width 0.0889)
		(layer "B.Cu")
		(net "UPI_CPU0_CPU1_P1P1_DP<6>")
	)
	(segment
		(start 249.120914 -39.07282)
		(end 252.621542 -41.189402)
		(width 0.1143)
		(layer "B.Cu")
		(net "UPI_CPU0_CPU1_P1P1_DP<6>")
	)
	(segment
		(start 139.059412 -47.94504)
		(end 139.343892 -47.753016)
		(width 0.1143)
		(layer "B.Cu")
		(net "UPI_CPU0_CPU1_P1P1_DP<6>")
	)
	(segment
		(start 135.753348 -51.488848)
		(end 135.938006 -51.30419)
		(width 0.0889)
		(layer "B.Cu")
		(net "UPI_CPU0_CPU1_P1P1_DP<6>")
	)
	(segment
		(start 140.84554 -46.617382)
		(end 141.298676 -46.31182)
		(width 0.1143)
		(layer "B.Cu")
		(net "UPI_CPU0_CPU1_P1P1_DP<6>")
	)
	(segment
		(start 287.1216 -44.990004)
		(end 289.870134 -46.736762)
		(width 0.1143)
		(layer "B.Cu")
		(net "UPI_CPU0_CPU1_P1P1_DP<6>")
	)
	(segment
		(start 137.718546 -49.467008)
		(end 137.85977 -49.439576)
		(width 0.1143)
		(layer "B.Cu")
		(net "UPI_CPU0_CPU1_P1P1_DP<6>")
	)
	(segment
		(start 295.28516 -53.217318)
		(end 295.29151 -53.227986)
		(width 0.0889)
		(layer "B.Cu")
		(net "UPI_CPU0_CPU1_P1P1_DP<6>")
	)
	(segment
		(start 181.440836 -41.377362)
		(end 186.000136 -40.138096)
		(width 0.1143)
		(layer "B.Cu")
		(net "UPI_CPU0_CPU1_P1P1_DP<6>")
	)
	(segment
		(start 248.003568 -38.8493)
		(end 249.120914 -39.07282)
		(width 0.1143)
		(layer "B.Cu")
		(net "UPI_CPU0_CPU1_P1P1_DP<6>")
	)
	(segment
		(start 136.196324 -51.045872)
		(end 136.322054 -50.920142)
		(width 0.0889)
		(layer "B.Cu")
		(net "UPI_CPU0_CPU1_P1P1_DP<6>")
	)
	(segment
		(start 134.225538 -55.504334)
		(end 134.258304 -55.504334)
		(width 0.0889)
		(layer "B.Cu")
		(net "UPI_CPU0_CPU1_P1P1_DP<6>")
	)
	(segment
		(start 159.384492 -43.59402)
		(end 161.876232 -42.54373)
		(width 0.1143)
		(layer "B.Cu")
		(net "UPI_CPU0_CPU1_P1P1_DP<6>")
	)
	(segment
		(start 258.821174 -41.29405)
		(end 261.300468 -41.486328)
		(width 0.1143)
		(layer "B.Cu")
		(net "UPI_CPU0_CPU1_P1P1_DP<6>")
	)
	(arc
		(start 133.896354 -56.684418)
		(mid 133.969152 -56.393655)
		(end 133.890004 -56.104536)
		(width 0.0889)
		(layer "B.Cu")
		(net "UPI_CPU0_CPU1_P1P1_DP<6>")
	)
	(arc
		(start 295.29151 -52.637436)
		(mid 295.212288 -52.926554)
		(end 295.28516 -53.217318)
		(width 0.0889)
		(layer "B.Cu")
		(net "UPI_CPU0_CPU1_P1P1_DP<6>")
	)
	(arc
		(start 133.890004 -58.085736)
		(mid 133.836534 -57.890673)
		(end 133.885178 -57.694322)
		(width 0.0889)
		(layer "B.Cu")
		(net "UPI_CPU0_CPU1_P1P1_DP<6>")
	)
	(arc
		(start 134.743698 -54.61)
		(mid 134.747445 -54.220744)
		(end 135.080248 -54.018688)
		(width 0.0889)
		(layer "B.Cu")
		(net "UPI_CPU0_CPU1_P1P1_DP<6>")
	)
	(arc
		(start 135.0772 -52.837334)
		(mid 134.694792 -52.43601)
		(end 135.080248 -52.037488)
		(width 0.0889)
		(layer "B.Cu")
		(net "UPI_CPU0_CPU1_P1P1_DP<6>")
	)
	(arc
		(start 134.258304 -55.504334)
		(mid 134.750694 -55.205401)
		(end 134.754874 -54.629304)
		(width 0.0889)
		(layer "B.Cu")
		(net "UPI_CPU0_CPU1_P1P1_DP<6>")
	)
	(arc
		(start 295.34485 -52.44592)
		(mid 295.330288 -52.545054)
		(end 295.29151 -52.637436)
		(width 0.0889)
		(layer "B.Cu")
		(net "UPI_CPU0_CPU1_P1P1_DP<6>")
	)
	(arc
		(start 135.113014 -52.037488)
		(mid 135.398438 -51.954021)
		(end 135.607044 -51.742086)
		(width 0.0889)
		(layer "B.Cu")
		(net "UPI_CPU0_CPU1_P1P1_DP<6>")
	)
	(arc
		(start 133.896354 -57.675018)
		(mid 133.969152 -57.384255)
		(end 133.890004 -57.095136)
		(width 0.0889)
		(layer "B.Cu")
		(net "UPI_CPU0_CPU1_P1P1_DP<6>")
	)
	(arc
		(start 295.29151 -53.227986)
		(mid 295.345009 -53.427884)
		(end 295.29151 -53.627782)
		(width 0.0889)
		(layer "B.Cu")
		(net "UPI_CPU0_CPU1_P1P1_DP<6>")
	)
	(arc
		(start 135.108188 -54.018688)
		(mid 135.685927 -53.4303)
		(end 135.113014 -52.837334)
		(width 0.0889)
		(layer "B.Cu")
		(net "UPI_CPU0_CPU1_P1P1_DP<6>")
	)
	(arc
		(start 295.29151 -53.627782)
		(mid 295.212379 -53.923184)
		(end 295.29151 -54.218586)
		(width 0.0889)
		(layer "B.Cu")
		(net "UPI_CPU0_CPU1_P1P1_DP<6>")
	)
	(arc
		(start 133.890004 -57.095136)
		(mid 133.836534 -56.900073)
		(end 133.885178 -56.703722)
		(width 0.0889)
		(layer "B.Cu")
		(net "UPI_CPU0_CPU1_P1P1_DP<6>")
	)
	(arc
		(start 133.864858 -59.024012)
		(mid 133.837624 -58.847382)
		(end 133.890004 -58.67654)
		(width 0.0889)
		(layer "B.Cu")
		(net "UPI_CPU0_CPU1_P1P1_DP<6>")
	)
	(arc
		(start 133.890004 -56.104536)
		(mid 133.887256 -55.709069)
		(end 134.225538 -55.504334)
		(width 0.0889)
		(layer "B.Cu")
		(net "UPI_CPU0_CPU1_P1P1_DP<6>")
	)
	(arc
		(start 295.357042 -54.332124)
		(mid 295.561116 -54.637581)
		(end 295.80332 -54.913784)
		(width 0.0889)
		(layer "B.Cu")
		(net "UPI_CPU0_CPU1_P1P1_DP<6>")
	)
	(arc
		(start 133.890004 -58.67654)
		(mid 133.969135 -58.381138)
		(end 133.890004 -58.085736)
		(width 0.0889)
		(layer "B.Cu")
		(net "UPI_CPU0_CPU1_P1P1_DP<6>")
	)
	(segment
		(start 294.3733 -54.418738)
		(end 294.9448 -54.418738)
		(width 0.1143)
		(layer "F.Cu")
		(net "UPI_CPU0_CPU1_P1P1_DP<5>")
	)
	(segment
		(start 134.523734 -59.371484)
		(end 135.095234 -59.371484)
		(width 0.1143)
		(layer "F.Cu")
		(net "UPI_CPU0_CPU1_P1P1_DP<5>")
	)
	(via
		(at 294.9448 -54.418738)
		(size 0.508)
		(drill 0.254)
		(layers "F.Cu" "B.Cu")
		(net "UPI_CPU0_CPU1_P1P1_DP<5>")
	)
	(via
		(at 135.095234 -59.371484)
		(size 0.508)
		(drill 0.254)
		(layers "F.Cu" "B.Cu")
		(net "UPI_CPU0_CPU1_P1P1_DP<5>")
	)
	(segment
		(start 253.541784 -43.462194)
		(end 253.345696 -42.4815)
		(width 0.1143)
		(layer "B.Cu")
		(net "UPI_CPU0_CPU1_P1P1_DP<5>")
	)
	(segment
		(start 252.535182 -42.64406)
		(end 252.73127 -43.6245)
		(width 0.1143)
		(layer "B.Cu")
		(net "UPI_CPU0_CPU1_P1P1_DP<5>")
	)
	(segment
		(start 280.016458 -46.091602)
		(end 287.03524 -45.657262)
		(width 0.1143)
		(layer "B.Cu")
		(net "UPI_CPU0_CPU1_P1P1_DP<5>")
	)
	(segment
		(start 290.524692 -47.949104)
		(end 292.520116 -50.490628)
		(width 0.1143)
		(layer "B.Cu")
		(net "UPI_CPU0_CPU1_P1P1_DP<5>")
	)
	(segment
		(start 292.520116 -50.490628)
		(end 292.528244 -50.498756)
		(width 0.0889)
		(layer "B.Cu")
		(net "UPI_CPU0_CPU1_P1P1_DP<5>")
	)
	(segment
		(start 155.648152 -43.633898)
		(end 166.586408 -45.838872)
		(width 0.1143)
		(layer "B.Cu")
		(net "UPI_CPU0_CPU1_P1P1_DP<5>")
	)
	(segment
		(start 136.300464 -54.713886)
		(end 136.294114 -54.703218)
		(width 0.0889)
		(layer "B.Cu")
		(net "UPI_CPU0_CPU1_P1P1_DP<5>")
	)
	(segment
		(start 292.519354 -50.522886)
		(end 292.519354 -50.526442)
		(width 0.0889)
		(layer "B.Cu")
		(net "UPI_CPU0_CPU1_P1P1_DP<5>")
	)
	(segment
		(start 253.452122 -43.596306)
		(end 253.541784 -43.462194)
		(width 0.1143)
		(layer "B.Cu")
		(net "UPI_CPU0_CPU1_P1P1_DP<5>")
	)
	(segment
		(start 251.358654 -44.015406)
		(end 251.448316 -43.881294)
		(width 0.1143)
		(layer "B.Cu")
		(net "UPI_CPU0_CPU1_P1P1_DP<5>")
	)
	(segment
		(start 294.572944 -54.566312)
		(end 294.651684 -54.587648)
		(width 0.0889)
		(layer "B.Cu")
		(net "UPI_CPU0_CPU1_P1P1_DP<5>")
	)
	(segment
		(start 294.5384 -53.194712)
		(end 294.5384 -53.524658)
		(width 0.0889)
		(layer "B.Cu")
		(net "UPI_CPU0_CPU1_P1P1_DP<5>")
	)
	(segment
		(start 254.327914 -42.0243)
		(end 254.62865 -42.22496)
		(width 0.1143)
		(layer "B.Cu")
		(net "UPI_CPU0_CPU1_P1P1_DP<5>")
	)
	(segment
		(start 135.935974 -55.313834)
		(end 135.96874 -55.313834)
		(width 0.0889)
		(layer "B.Cu")
		(net "UPI_CPU0_CPU1_P1P1_DP<5>")
	)
	(segment
		(start 254.824738 -43.2054)
		(end 254.95885 -43.295062)
		(width 0.1143)
		(layer "B.Cu")
		(net "UPI_CPU0_CPU1_P1P1_DP<5>")
	)
	(segment
		(start 248.130822 -44.661328)
		(end 251.358654 -44.015406)
		(width 0.1143)
		(layer "B.Cu")
		(net "UPI_CPU0_CPU1_P1P1_DP<5>")
	)
	(segment
		(start 240.926366 -43.220132)
		(end 248.130822 -44.661328)
		(width 0.1143)
		(layer "B.Cu")
		(net "UPI_CPU0_CPU1_P1P1_DP<5>")
	)
	(segment
		(start 138.018012 -51.102514)
		(end 138.018012 -51.10226)
		(width 0.1143)
		(layer "B.Cu")
		(net "UPI_CPU0_CPU1_P1P1_DP<5>")
	)
	(segment
		(start 251.452634 -42.599864)
		(end 252.234446 -42.4434)
		(width 0.1143)
		(layer "B.Cu")
		(net "UPI_CPU0_CPU1_P1P1_DP<5>")
	)
	(segment
		(start 226.535488 -46.09846)
		(end 240.926366 -43.220132)
		(width 0.1143)
		(layer "B.Cu")
		(net "UPI_CPU0_CPU1_P1P1_DP<5>")
	)
	(segment
		(start 252.73127 -43.6245)
		(end 252.865382 -43.713908)
		(width 0.1143)
		(layer "B.Cu")
		(net "UPI_CPU0_CPU1_P1P1_DP<5>")
	)
	(segment
		(start 134.583424 -56.695086)
		(end 134.577074 -56.684418)
		(width 0.0889)
		(layer "B.Cu")
		(net "UPI_CPU0_CPU1_P1P1_DP<5>")
	)
	(segment
		(start 186.90082 -40.917876)
		(end 188.265054 -41.008808)
		(width 0.1143)
		(layer "B.Cu")
		(net "UPI_CPU0_CPU1_P1P1_DP<5>")
	)
	(segment
		(start 188.265054 -41.008808)
		(end 190.21679 -39.715694)
		(width 0.1143)
		(layer "B.Cu")
		(net "UPI_CPU0_CPU1_P1P1_DP<5>")
	)
	(segment
		(start 136.30529 -54.722522)
		(end 136.300464 -54.713886)
		(width 0.0889)
		(layer "B.Cu")
		(net "UPI_CPU0_CPU1_P1P1_DP<5>")
	)
	(segment
		(start 260.496304 -42.187876)
		(end 280.016458 -46.091602)
		(width 0.1143)
		(layer "B.Cu")
		(net "UPI_CPU0_CPU1_P1P1_DP<5>")
	)
	(segment
		(start 251.448316 -43.881294)
		(end 251.252228 -42.9006)
		(width 0.1143)
		(layer "B.Cu")
		(net "UPI_CPU0_CPU1_P1P1_DP<5>")
	)
	(segment
		(start 135.073644 -55.809388)
		(end 135.10641 -55.809388)
		(width 0.0889)
		(layer "B.Cu")
		(net "UPI_CPU0_CPU1_P1P1_DP<5>")
	)
	(segment
		(start 134.58825 -56.703722)
		(end 134.583424 -56.695086)
		(width 0.0889)
		(layer "B.Cu")
		(net "UPI_CPU0_CPU1_P1P1_DP<5>")
	)
	(segment
		(start 137.960354 -51.201574)
		(end 138.018012 -51.102514)
		(width 0.1143)
		(layer "B.Cu")
		(net "UPI_CPU0_CPU1_P1P1_DP<5>")
	)
	(segment
		(start 292.528244 -50.513996)
		(end 292.519354 -50.522886)
		(width 0.0889)
		(layer "B.Cu")
		(net "UPI_CPU0_CPU1_P1P1_DP<5>")
	)
	(segment
		(start 136.794494 -52.837334)
		(end 136.830308 -52.837334)
		(width 0.0889)
		(layer "B.Cu")
		(net "UPI_CPU0_CPU1_P1P1_DP<5>")
	)
	(segment
		(start 253.546102 -42.180764)
		(end 254.327914 -42.0243)
		(width 0.1143)
		(layer "B.Cu")
		(net "UPI_CPU0_CPU1_P1P1_DP<5>")
	)
	(segment
		(start 203.595986 -39.49065)
		(end 207.92313 -42.375582)
		(width 0.1143)
		(layer "B.Cu")
		(net "UPI_CPU0_CPU1_P1P1_DP<5>")
	)
	(segment
		(start 294.5384 -53.524658)
		(end 294.59809 -53.627782)
		(width 0.0889)
		(layer "B.Cu")
		(net "UPI_CPU0_CPU1_P1P1_DP<5>")
	)
	(segment
		(start 171.45254 -44.136818)
		(end 183.477662 -41.731946)
		(width 0.1143)
		(layer "B.Cu")
		(net "UPI_CPU0_CPU1_P1P1_DP<5>")
	)
	(segment
		(start 287.03524 -45.657262)
		(end 290.331144 -47.638208)
		(width 0.1143)
		(layer "B.Cu")
		(net "UPI_CPU0_CPU1_P1P1_DP<5>")
	)
	(segment
		(start 251.252228 -42.9006)
		(end 251.452634 -42.599864)
		(width 0.1143)
		(layer "B.Cu")
		(net "UPI_CPU0_CPU1_P1P1_DP<5>")
	)
	(segment
		(start 252.865382 -43.713908)
		(end 253.452122 -43.596306)
		(width 0.1143)
		(layer "B.Cu")
		(net "UPI_CPU0_CPU1_P1P1_DP<5>")
	)
	(segment
		(start 207.92313 -42.375582)
		(end 226.535488 -46.09846)
		(width 0.1143)
		(layer "B.Cu")
		(net "UPI_CPU0_CPU1_P1P1_DP<5>")
	)
	(segment
		(start 252.234446 -42.4434)
		(end 252.535182 -42.64406)
		(width 0.1143)
		(layer "B.Cu")
		(net "UPI_CPU0_CPU1_P1P1_DP<5>")
	)
	(segment
		(start 190.875666 -39.295832)
		(end 192.530222 -38.611302)
		(width 0.1143)
		(layer "B.Cu")
		(net "UPI_CPU0_CPU1_P1P1_DP<5>")
	)
	(segment
		(start 253.345696 -42.4815)
		(end 253.546102 -42.180764)
		(width 0.1143)
		(layer "B.Cu")
		(net "UPI_CPU0_CPU1_P1P1_DP<5>")
	)
	(segment
		(start 183.477662 -41.731946)
		(end 186.90082 -40.917876)
		(width 0.1143)
		(layer "B.Cu")
		(net "UPI_CPU0_CPU1_P1P1_DP<5>")
	)
	(segment
		(start 190.21679 -39.715694)
		(end 190.875666 -39.295832)
		(width 0.1143)
		(layer "B.Cu")
		(net "UPI_CPU0_CPU1_P1P1_DP<5>")
	)
	(segment
		(start 192.530222 -38.611302)
		(end 196.925184 -38.156388)
		(width 0.1143)
		(layer "B.Cu")
		(net "UPI_CPU0_CPU1_P1P1_DP<5>")
	)
	(segment
		(start 294.651684 -54.587648)
		(end 294.9448 -54.418738)
		(width 0.0889)
		(layer "B.Cu")
		(net "UPI_CPU0_CPU1_P1P1_DP<5>")
	)
	(segment
		(start 139.755372 -48.514)
		(end 139.755626 -48.514254)
		(width 0.1143)
		(layer "B.Cu")
		(net "UPI_CPU0_CPU1_P1P1_DP<5>")
	)
	(segment
		(start 134.969758 -59.078622)
		(end 134.68731 -58.809128)
		(width 0.0889)
		(layer "B.Cu")
		(net "UPI_CPU0_CPU1_P1P1_DP<5>")
	)
	(segment
		(start 134.583424 -57.685686)
		(end 134.577074 -57.675018)
		(width 0.0889)
		(layer "B.Cu")
		(net "UPI_CPU0_CPU1_P1P1_DP<5>")
	)
	(segment
		(start 254.62865 -42.22496)
		(end 254.824738 -43.2054)
		(width 0.1143)
		(layer "B.Cu")
		(net "UPI_CPU0_CPU1_P1P1_DP<5>")
	)
	(segment
		(start 137.949432 -51.220624)
		(end 137.960354 -51.201574)
		(width 0.0889)
		(layer "B.Cu")
		(net "UPI_CPU0_CPU1_P1P1_DP<5>")
	)
	(segment
		(start 196.925184 -38.156388)
		(end 203.595986 -39.49065)
		(width 0.1143)
		(layer "B.Cu")
		(net "UPI_CPU0_CPU1_P1P1_DP<5>")
	)
	(segment
		(start 254.95885 -43.295062)
		(end 260.496304 -42.187876)
		(width 0.1143)
		(layer "B.Cu")
		(net "UPI_CPU0_CPU1_P1P1_DP<5>")
	)
	(segment
		(start 290.331144 -47.638208)
		(end 290.524692 -47.949104)
		(width 0.1143)
		(layer "B.Cu")
		(net "UPI_CPU0_CPU1_P1P1_DP<5>")
	)
	(segment
		(start 138.018012 -51.10226)
		(end 139.755372 -48.514)
		(width 0.1143)
		(layer "B.Cu")
		(net "UPI_CPU0_CPU1_P1P1_DP<5>")
	)
	(segment
		(start 134.58825 -57.694322)
		(end 134.583424 -57.685686)
		(width 0.0889)
		(layer "B.Cu")
		(net "UPI_CPU0_CPU1_P1P1_DP<5>")
	)
	(segment
		(start 141.949424 -47.03572)
		(end 155.648152 -43.633898)
		(width 0.1143)
		(layer "B.Cu")
		(net "UPI_CPU0_CPU1_P1P1_DP<5>")
	)
	(segment
		(start 137.158984 -52.637436)
		(end 137.95883 -51.255168)
		(width 0.0889)
		(layer "B.Cu")
		(net "UPI_CPU0_CPU1_P1P1_DP<5>")
	)
	(segment
		(start 292.519354 -50.526442)
		(end 293.756842 -51.76393)
		(width 0.0889)
		(layer "B.Cu")
		(net "UPI_CPU0_CPU1_P1P1_DP<5>")
	)
	(segment
		(start 166.586408 -45.838872)
		(end 171.45254 -44.136818)
		(width 0.1143)
		(layer "B.Cu")
		(net "UPI_CPU0_CPU1_P1P1_DP<5>")
	)
	(segment
		(start 136.30529 -53.731922)
		(end 136.300464 -53.723286)
		(width 0.0889)
		(layer "B.Cu")
		(net "UPI_CPU0_CPU1_P1P1_DP<5>")
	)
	(segment
		(start 292.528244 -50.498756)
		(end 292.528244 -50.513996)
		(width 0.0889)
		(layer "B.Cu")
		(net "UPI_CPU0_CPU1_P1P1_DP<5>")
	)
	(segment
		(start 293.756842 -51.76393)
		(end 294.5384 -53.194712)
		(width 0.0889)
		(layer "B.Cu")
		(net "UPI_CPU0_CPU1_P1P1_DP<5>")
	)
	(segment
		(start 137.95883 -51.255168)
		(end 137.949432 -51.220624)
		(width 0.0889)
		(layer "B.Cu")
		(net "UPI_CPU0_CPU1_P1P1_DP<5>")
	)
	(segment
		(start 139.755626 -48.514254)
		(end 141.949424 -47.03572)
		(width 0.1143)
		(layer "B.Cu")
		(net "UPI_CPU0_CPU1_P1P1_DP<5>")
	)
	(arc
		(start 136.830308 -52.837334)
		(mid 137.020237 -52.779464)
		(end 137.158984 -52.637436)
		(width 0.0889)
		(layer "B.Cu")
		(net "UPI_CPU0_CPU1_P1P1_DP<5>")
	)
	(arc
		(start 136.300464 -54.123336)
		(mid 136.353934 -53.928273)
		(end 136.30529 -53.731922)
		(width 0.0889)
		(layer "B.Cu")
		(net "UPI_CPU0_CPU1_P1P1_DP<5>")
	)
	(arc
		(start 294.59809 -53.627782)
		(mid 294.677255 -53.923184)
		(end 294.59809 -54.218586)
		(width 0.0889)
		(layer "B.Cu")
		(net "UPI_CPU0_CPU1_P1P1_DP<5>")
	)
	(arc
		(start 134.583424 -58.085736)
		(mid 134.636894 -57.890673)
		(end 134.58825 -57.694322)
		(width 0.0889)
		(layer "B.Cu")
		(net "UPI_CPU0_CPU1_P1P1_DP<5>")
	)
	(arc
		(start 135.095234 -59.371484)
		(mid 135.062482 -59.212213)
		(end 134.969758 -59.078622)
		(width 0.0889)
		(layer "B.Cu")
		(net "UPI_CPU0_CPU1_P1P1_DP<5>")
	)
	(arc
		(start 135.441944 -55.609236)
		(mid 135.650552 -55.397304)
		(end 135.935974 -55.313834)
		(width 0.0889)
		(layer "B.Cu")
		(net "UPI_CPU0_CPU1_P1P1_DP<5>")
	)
	(arc
		(start 135.10641 -55.809388)
		(mid 135.30026 -55.753038)
		(end 135.441944 -55.609236)
		(width 0.0889)
		(layer "B.Cu")
		(net "UPI_CPU0_CPU1_P1P1_DP<5>")
	)
	(arc
		(start 134.577074 -56.684418)
		(mid 134.581105 -56.108236)
		(end 135.073644 -55.809388)
		(width 0.0889)
		(layer "B.Cu")
		(net "UPI_CPU0_CPU1_P1P1_DP<5>")
	)
	(arc
		(start 134.68731 -58.809128)
		(mid 134.510169 -58.465412)
		(end 134.583424 -58.085736)
		(width 0.0889)
		(layer "B.Cu")
		(net "UPI_CPU0_CPU1_P1P1_DP<5>")
	)
	(arc
		(start 135.96874 -55.313834)
		(mid 136.301658 -55.111843)
		(end 136.30529 -54.722522)
		(width 0.0889)
		(layer "B.Cu")
		(net "UPI_CPU0_CPU1_P1P1_DP<5>")
	)
	(arc
		(start 294.59809 -54.218586)
		(mid 294.54567 -54.389571)
		(end 294.572944 -54.566312)
		(width 0.0889)
		(layer "B.Cu")
		(net "UPI_CPU0_CPU1_P1P1_DP<5>")
	)
	(arc
		(start 136.294114 -54.703218)
		(mid 136.221316 -54.412455)
		(end 136.300464 -54.123336)
		(width 0.0889)
		(layer "B.Cu")
		(net "UPI_CPU0_CPU1_P1P1_DP<5>")
	)
	(arc
		(start 134.583424 -57.095136)
		(mid 134.636894 -56.900073)
		(end 134.58825 -56.703722)
		(width 0.0889)
		(layer "B.Cu")
		(net "UPI_CPU0_CPU1_P1P1_DP<5>")
	)
	(arc
		(start 134.577074 -57.675018)
		(mid 134.504276 -57.384255)
		(end 134.583424 -57.095136)
		(width 0.0889)
		(layer "B.Cu")
		(net "UPI_CPU0_CPU1_P1P1_DP<5>")
	)
	(arc
		(start 136.300464 -53.723286)
		(mid 136.296135 -53.140114)
		(end 136.794494 -52.837334)
		(width 0.0889)
		(layer "B.Cu")
		(net "UPI_CPU0_CPU1_P1P1_DP<5>")
	)
	(segment
		(start 134.523734 -57.390538)
		(end 135.095234 -57.390538)
		(width 0.1143)
		(layer "F.Cu")
		(net "UPI_CPU0_CPU1_P1P1_DP<4>")
	)
	(segment
		(start 292.65626 -56.399938)
		(end 293.22776 -56.399938)
		(width 0.1143)
		(layer "F.Cu")
		(net "UPI_CPU0_CPU1_P1P1_DP<4>")
	)
	(via
		(at 135.095234 -57.390538)
		(size 0.508)
		(drill 0.254)
		(layers "F.Cu" "B.Cu")
		(net "UPI_CPU0_CPU1_P1P1_DP<4>")
	)
	(via
		(at 293.22776 -56.399938)
		(size 0.508)
		(drill 0.254)
		(layers "F.Cu" "B.Cu")
		(net "UPI_CPU0_CPU1_P1P1_DP<4>")
	)
	(segment
		(start 172.595794 -44.910248)
		(end 184.325768 -42.563542)
		(width 0.1143)
		(layer "B.Cu")
		(net "UPI_CPU0_CPU1_P1P1_DP<4>")
	)
	(segment
		(start 142.346172 -49.446942)
		(end 142.18158 -49.335944)
		(width 0.1143)
		(layer "B.Cu")
		(net "UPI_CPU0_CPU1_P1P1_DP<4>")
	)
	(segment
		(start 188.891926 -42.615612)
		(end 188.9252 -42.5831)
		(width 0.1143)
		(layer "B.Cu")
		(net "UPI_CPU0_CPU1_P1P1_DP<4>")
	)
	(segment
		(start 138.145774 -52.64277)
		(end 138.145774 -52.427886)
		(width 0.0889)
		(layer "B.Cu")
		(net "UPI_CPU0_CPU1_P1P1_DP<4>")
	)
	(segment
		(start 145.853658 -47.606966)
		(end 146.10334 -47.171356)
		(width 0.1143)
		(layer "B.Cu")
		(net "UPI_CPU0_CPU1_P1P1_DP<4>")
	)
	(segment
		(start 139.545568 -51.615086)
		(end 140.191236 -50.658776)
		(width 0.1143)
		(layer "B.Cu")
		(net "UPI_CPU0_CPU1_P1P1_DP<4>")
	)
	(segment
		(start 145.500344 -47.702978)
		(end 145.853658 -47.606966)
		(width 0.1143)
		(layer "B.Cu")
		(net "UPI_CPU0_CPU1_P1P1_DP<4>")
	)
	(segment
		(start 248.054368 -45.74413)
		(end 260.597142 -43.23588)
		(width 0.1143)
		(layer "B.Cu")
		(net "UPI_CPU0_CPU1_P1P1_DP<4>")
	)
	(segment
		(start 138.145774 -52.427886)
		(end 138.6205 -51.95316)
		(width 0.0889)
		(layer "B.Cu")
		(net "UPI_CPU0_CPU1_P1P1_DP<4>")
	)
	(segment
		(start 190.903098 -42.638218)
		(end 193.893948 -40.307514)
		(width 0.1143)
		(layer "B.Cu")
		(net "UPI_CPU0_CPU1_P1P1_DP<4>")
	)
	(segment
		(start 142.189962 -48.208692)
		(end 142.759176 -48.096932)
		(width 0.1143)
		(layer "B.Cu")
		(net "UPI_CPU0_CPU1_P1P1_DP<4>")
	)
	(segment
		(start 135.095234 -57.390538)
		(end 135.38835 -57.559448)
		(width 0.0889)
		(layer "B.Cu")
		(net "UPI_CPU0_CPU1_P1P1_DP<4>")
	)
	(segment
		(start 293.74592 -54.702456)
		(end 293.734744 -54.722522)
		(width 0.0889)
		(layer "B.Cu")
		(net "UPI_CPU0_CPU1_P1P1_DP<4>")
	)
	(segment
		(start 184.325768 -42.563542)
		(end 188.891926 -42.615612)
		(width 0.1143)
		(layer "B.Cu")
		(net "UPI_CPU0_CPU1_P1P1_DP<4>")
	)
	(segment
		(start 197.515734 -39.061644)
		(end 202.868276 -40.132508)
		(width 0.1143)
		(layer "B.Cu")
		(net "UPI_CPU0_CPU1_P1P1_DP<4>")
	)
	(segment
		(start 142.18158 -49.335944)
		(end 142.18158 -49.33569)
		(width 0.1143)
		(layer "B.Cu")
		(net "UPI_CPU0_CPU1_P1P1_DP<4>")
	)
	(segment
		(start 202.868276 -40.132508)
		(end 207.978502 -43.34129)
		(width 0.1143)
		(layer "B.Cu")
		(net "UPI_CPU0_CPU1_P1P1_DP<4>")
	)
	(segment
		(start 292.713664 -51.802538)
		(end 292.913816 -52.115974)
		(width 0.1143)
		(layer "B.Cu")
		(net "UPI_CPU0_CPU1_P1P1_DP<4>")
	)
	(segment
		(start 137.152634 -54.629304)
		(end 137.158984 -54.618636)
		(width 0.0889)
		(layer "B.Cu")
		(net "UPI_CPU0_CPU1_P1P1_DP<4>")
	)
	(segment
		(start 291.640006 -51.1175)
		(end 292.713664 -51.802538)
		(width 0.1143)
		(layer "B.Cu")
		(net "UPI_CPU0_CPU1_P1P1_DP<4>")
	)
	(segment
		(start 292.913816 -52.115974)
		(end 292.9255 -52.134516)
		(width 0.0889)
		(layer "B.Cu")
		(net "UPI_CPU0_CPU1_P1P1_DP<4>")
	)
	(segment
		(start 292.9255 -52.134516)
		(end 292.917372 -52.169568)
		(width 0.0889)
		(layer "B.Cu")
		(net "UPI_CPU0_CPU1_P1P1_DP<4>")
	)
	(segment
		(start 142.02664 -50.047906)
		(end 142.104618 -50.03292)
		(width 0.1143)
		(layer "B.Cu")
		(net "UPI_CPU0_CPU1_P1P1_DP<4>")
	)
	(segment
		(start 148.37664 -46.927516)
		(end 148.557742 -46.610778)
		(width 0.1143)
		(layer "B.Cu")
		(net "UPI_CPU0_CPU1_P1P1_DP<4>")
	)
	(segment
		(start 142.18158 -49.33569)
		(end 142.017242 -49.224946)
		(width 0.1143)
		(layer "B.Cu")
		(net "UPI_CPU0_CPU1_P1P1_DP<4>")
	)
	(segment
		(start 142.024608 -50.048414)
		(end 142.02664 -50.047906)
		(width 0.1143)
		(layer "B.Cu")
		(net "UPI_CPU0_CPU1_P1P1_DP<4>")
	)
	(segment
		(start 189.865254 -41.778428)
		(end 190.11773 -42.036746)
		(width 0.1143)
		(layer "B.Cu")
		(net "UPI_CPU0_CPU1_P1P1_DP<4>")
	)
	(segment
		(start 286.990282 -46.635162)
		(end 287.1216 -46.71822)
		(width 0.1143)
		(layer "B.Cu")
		(net "UPI_CPU0_CPU1_P1P1_DP<4>")
	)
	(segment
		(start 194.4878 -39.918386)
		(end 197.515734 -39.061644)
		(width 0.1143)
		(layer "B.Cu")
		(net "UPI_CPU0_CPU1_P1P1_DP<4>")
	)
	(segment
		(start 142.104618 -50.03292)
		(end 142.380716 -49.623472)
		(width 0.1143)
		(layer "B.Cu")
		(net "UPI_CPU0_CPU1_P1P1_DP<4>")
	)
	(segment
		(start 190.11773 -42.036746)
		(end 190.112142 -42.515536)
		(width 0.1143)
		(layer "B.Cu")
		(net "UPI_CPU0_CPU1_P1P1_DP<4>")
	)
	(segment
		(start 226.737926 -47.164498)
		(end 240.947702 -44.322746)
		(width 0.1143)
		(layer "B.Cu")
		(net "UPI_CPU0_CPU1_P1P1_DP<4>")
	)
	(segment
		(start 293.685976 -53.376576)
		(end 293.685976 -53.923692)
		(width 0.0889)
		(layer "B.Cu")
		(net "UPI_CPU0_CPU1_P1P1_DP<4>")
	)
	(segment
		(start 140.191236 -50.658776)
		(end 140.09624 -50.168556)
		(width 0.1143)
		(layer "B.Cu")
		(net "UPI_CPU0_CPU1_P1P1_DP<4>")
	)
	(segment
		(start 137.648696 -53.332888)
		(end 137.685272 -53.332888)
		(width 0.0889)
		(layer "B.Cu")
		(net "UPI_CPU0_CPU1_P1P1_DP<4>")
	)
	(segment
		(start 188.9252 -42.5831)
		(end 189.006988 -42.502836)
		(width 0.1143)
		(layer "B.Cu")
		(net "UPI_CPU0_CPU1_P1P1_DP<4>")
	)
	(segment
		(start 137.158984 -54.618636)
		(end 137.16381 -54.61)
		(width 0.0889)
		(layer "B.Cu")
		(net "UPI_CPU0_CPU1_P1P1_DP<4>")
	)
	(segment
		(start 189.012576 -42.0243)
		(end 189.271148 -41.77157)
		(width 0.1143)
		(layer "B.Cu")
		(net "UPI_CPU0_CPU1_P1P1_DP<4>")
	)
	(segment
		(start 145.009108 -47.4218)
		(end 145.500344 -47.702978)
		(width 0.1143)
		(layer "B.Cu")
		(net "UPI_CPU0_CPU1_P1P1_DP<4>")
	)
	(segment
		(start 141.946122 -50.063654)
		(end 142.024608 -50.048414)
		(width 0.1143)
		(layer "B.Cu")
		(net "UPI_CPU0_CPU1_P1P1_DP<4>")
	)
	(segment
		(start 139.410948 -51.749706)
		(end 139.545568 -51.615086)
		(width 0.1143)
		(layer "B.Cu")
		(net "UPI_CPU0_CPU1_P1P1_DP<4>")
	)
	(segment
		(start 189.006988 -42.502836)
		(end 189.012576 -42.0243)
		(width 0.1143)
		(layer "B.Cu")
		(net "UPI_CPU0_CPU1_P1P1_DP<4>")
	)
	(segment
		(start 143.661638 -48.359568)
		(end 144.134332 -47.659798)
		(width 0.1143)
		(layer "B.Cu")
		(net "UPI_CPU0_CPU1_P1P1_DP<4>")
	)
	(segment
		(start 141.902434 -48.634904)
		(end 142.189962 -48.208692)
		(width 0.1143)
		(layer "B.Cu")
		(net "UPI_CPU0_CPU1_P1P1_DP<4>")
	)
	(segment
		(start 190.224664 -42.630598)
		(end 190.903098 -42.638218)
		(width 0.1143)
		(layer "B.Cu")
		(net "UPI_CPU0_CPU1_P1P1_DP<4>")
	)
	(segment
		(start 280.048208 -47.124874)
		(end 286.990282 -46.635162)
		(width 0.1143)
		(layer "B.Cu")
		(net "UPI_CPU0_CPU1_P1P1_DP<4>")
	)
	(segment
		(start 190.112142 -42.515536)
		(end 190.224664 -42.630598)
		(width 0.1143)
		(layer "B.Cu")
		(net "UPI_CPU0_CPU1_P1P1_DP<4>")
	)
	(segment
		(start 135.935974 -56.304434)
		(end 135.96874 -56.304434)
		(width 0.0889)
		(layer "B.Cu")
		(net "UPI_CPU0_CPU1_P1P1_DP<4>")
	)
	(segment
		(start 292.917372 -52.169568)
		(end 293.685976 -53.376576)
		(width 0.0889)
		(layer "B.Cu")
		(net "UPI_CPU0_CPU1_P1P1_DP<4>")
	)
	(segment
		(start 140.574014 -49.461674)
		(end 140.946632 -49.389284)
		(width 0.1143)
		(layer "B.Cu")
		(net "UPI_CPU0_CPU1_P1P1_DP<4>")
	)
	(segment
		(start 189.271148 -41.77157)
		(end 189.78753 -41.777412)
		(width 0.1143)
		(layer "B.Cu")
		(net "UPI_CPU0_CPU1_P1P1_DP<4>")
	)
	(segment
		(start 147.287742 -46.84903)
		(end 147.731226 -47.10303)
		(width 0.1143)
		(layer "B.Cu")
		(net "UPI_CPU0_CPU1_P1P1_DP<4>")
	)
	(segment
		(start 207.978502 -43.34129)
		(end 211.200746 -44.055538)
		(width 0.1143)
		(layer "B.Cu")
		(net "UPI_CPU0_CPU1_P1P1_DP<4>")
	)
	(segment
		(start 135.38835 -57.559448)
		(end 135.46709 -57.538112)
		(width 0.0889)
		(layer "B.Cu")
		(net "UPI_CPU0_CPU1_P1P1_DP<4>")
	)
	(segment
		(start 155.683966 -44.672504)
		(end 166.534338 -46.910752)
		(width 0.1143)
		(layer "B.Cu")
		(net "UPI_CPU0_CPU1_P1P1_DP<4>")
	)
	(segment
		(start 260.597142 -43.23588)
		(end 280.048208 -47.124874)
		(width 0.1143)
		(layer "B.Cu")
		(net "UPI_CPU0_CPU1_P1P1_DP<4>")
	)
	(segment
		(start 193.893948 -40.307514)
		(end 194.4878 -39.918386)
		(width 0.1143)
		(layer "B.Cu")
		(net "UPI_CPU0_CPU1_P1P1_DP<4>")
	)
	(segment
		(start 222.396812 -46.295818)
		(end 226.737926 -47.164498)
		(width 0.1143)
		(layer "B.Cu")
		(net "UPI_CPU0_CPU1_P1P1_DP<4>")
	)
	(segment
		(start 142.759176 -48.096932)
		(end 143.265144 -48.438054)
		(width 0.1143)
		(layer "B.Cu")
		(net "UPI_CPU0_CPU1_P1P1_DP<4>")
	)
	(segment
		(start 146.10334 -47.171356)
		(end 147.287742 -46.84903)
		(width 0.1143)
		(layer "B.Cu")
		(net "UPI_CPU0_CPU1_P1P1_DP<4>")
	)
	(segment
		(start 138.636248 -51.901598)
		(end 138.78814 -51.749706)
		(width 0.1143)
		(layer "B.Cu")
		(net "UPI_CPU0_CPU1_P1P1_DP<4>")
	)
	(segment
		(start 287.1216 -46.71822)
		(end 289.373818 -48.14189)
		(width 0.1143)
		(layer "B.Cu")
		(net "UPI_CPU0_CPU1_P1P1_DP<4>")
	)
	(segment
		(start 143.265144 -48.438054)
		(end 143.661638 -48.359568)
		(width 0.1143)
		(layer "B.Cu")
		(net "UPI_CPU0_CPU1_P1P1_DP<4>")
	)
	(segment
		(start 142.017242 -49.224946)
		(end 141.902434 -48.634904)
		(width 0.1143)
		(layer "B.Cu")
		(net "UPI_CPU0_CPU1_P1P1_DP<4>")
	)
	(segment
		(start 136.790684 -55.809388)
		(end 136.82345 -55.809388)
		(width 0.0889)
		(layer "B.Cu")
		(net "UPI_CPU0_CPU1_P1P1_DP<4>")
	)
	(segment
		(start 140.09624 -50.168556)
		(end 140.574014 -49.461674)
		(width 0.1143)
		(layer "B.Cu")
		(net "UPI_CPU0_CPU1_P1P1_DP<4>")
	)
	(segment
		(start 142.380716 -49.623472)
		(end 142.346172 -49.446942)
		(width 0.1143)
		(layer "B.Cu")
		(net "UPI_CPU0_CPU1_P1P1_DP<4>")
	)
	(segment
		(start 148.557742 -46.610778)
		(end 155.683966 -44.672504)
		(width 0.1143)
		(layer "B.Cu")
		(net "UPI_CPU0_CPU1_P1P1_DP<4>")
	)
	(segment
		(start 211.200746 -44.055538)
		(end 222.396812 -46.295818)
		(width 0.1143)
		(layer "B.Cu")
		(net "UPI_CPU0_CPU1_P1P1_DP<4>")
	)
	(segment
		(start 140.946632 -49.389284)
		(end 141.946122 -50.063654)
		(width 0.1143)
		(layer "B.Cu")
		(net "UPI_CPU0_CPU1_P1P1_DP<4>")
	)
	(segment
		(start 138.6205 -51.917346)
		(end 138.636248 -51.901598)
		(width 0.0889)
		(layer "B.Cu")
		(net "UPI_CPU0_CPU1_P1P1_DP<4>")
	)
	(segment
		(start 138.78814 -51.749706)
		(end 139.410948 -51.749706)
		(width 0.1143)
		(layer "B.Cu")
		(net "UPI_CPU0_CPU1_P1P1_DP<4>")
	)
	(segment
		(start 138.6205 -51.95316)
		(end 138.6205 -51.917346)
		(width 0.0889)
		(layer "B.Cu")
		(net "UPI_CPU0_CPU1_P1P1_DP<4>")
	)
	(segment
		(start 290.255198 -49.474374)
		(end 291.640006 -51.1175)
		(width 0.1143)
		(layer "B.Cu")
		(net "UPI_CPU0_CPU1_P1P1_DP<4>")
	)
	(segment
		(start 189.78753 -41.777412)
		(end 189.865254 -41.778428)
		(width 0.1143)
		(layer "B.Cu")
		(net "UPI_CPU0_CPU1_P1P1_DP<4>")
	)
	(segment
		(start 293.24554 -55.999888)
		(end 293.212774 -55.999888)
		(width 0.0889)
		(layer "B.Cu")
		(net "UPI_CPU0_CPU1_P1P1_DP<4>")
	)
	(segment
		(start 144.134332 -47.659798)
		(end 145.009108 -47.4218)
		(width 0.1143)
		(layer "B.Cu")
		(net "UPI_CPU0_CPU1_P1P1_DP<4>")
	)
	(segment
		(start 138.14552 -52.642516)
		(end 138.145774 -52.64277)
		(width 0.0889)
		(layer "B.Cu")
		(net "UPI_CPU0_CPU1_P1P1_DP<4>")
	)
	(segment
		(start 292.913562 -56.152034)
		(end 292.934644 -56.230774)
		(width 0.0889)
		(layer "B.Cu")
		(net "UPI_CPU0_CPU1_P1P1_DP<4>")
	)
	(segment
		(start 240.947702 -44.322746)
		(end 248.054368 -45.74413)
		(width 0.1143)
		(layer "B.Cu")
		(net "UPI_CPU0_CPU1_P1P1_DP<4>")
	)
	(segment
		(start 292.934644 -56.230774)
		(end 293.22776 -56.399938)
		(width 0.0889)
		(layer "B.Cu")
		(net "UPI_CPU0_CPU1_P1P1_DP<4>")
	)
	(segment
		(start 147.731226 -47.10303)
		(end 148.37664 -46.927516)
		(width 0.1143)
		(layer "B.Cu")
		(net "UPI_CPU0_CPU1_P1P1_DP<4>")
	)
	(segment
		(start 289.373818 -48.14189)
		(end 290.255198 -49.474374)
		(width 0.1143)
		(layer "B.Cu")
		(net "UPI_CPU0_CPU1_P1P1_DP<4>")
	)
	(segment
		(start 166.534338 -46.910752)
		(end 172.595794 -44.910248)
		(width 0.1143)
		(layer "B.Cu")
		(net "UPI_CPU0_CPU1_P1P1_DP<4>")
	)
	(segment
		(start 293.746682 -54.701186)
		(end 293.74592 -54.702456)
		(width 0.0889)
		(layer "B.Cu")
		(net "UPI_CPU0_CPU1_P1P1_DP<4>")
	)
	(arc
		(start 293.73957 -55.113936)
		(mid 293.743899 -55.697108)
		(end 293.24554 -55.999888)
		(width 0.0889)
		(layer "B.Cu")
		(net "UPI_CPU0_CPU1_P1P1_DP<4>")
	)
	(arc
		(start 293.212774 -55.999888)
		(mid 293.04648 -56.043122)
		(end 292.913562 -56.152034)
		(width 0.0889)
		(layer "B.Cu")
		(net "UPI_CPU0_CPU1_P1P1_DP<4>")
	)
	(arc
		(start 135.96874 -56.304434)
		(mid 136.160382 -56.247268)
		(end 136.300464 -56.104536)
		(width 0.0889)
		(layer "B.Cu")
		(net "UPI_CPU0_CPU1_P1P1_DP<4>")
	)
	(arc
		(start 293.685976 -53.923692)
		(mid 293.699679 -54.027027)
		(end 293.73957 -54.123336)
		(width 0.0889)
		(layer "B.Cu")
		(net "UPI_CPU0_CPU1_P1P1_DP<4>")
	)
	(arc
		(start 137.16381 -54.61)
		(mid 137.212565 -54.413648)
		(end 137.158984 -54.218586)
		(width 0.0889)
		(layer "B.Cu")
		(net "UPI_CPU0_CPU1_P1P1_DP<4>")
	)
	(arc
		(start 136.82345 -55.809388)
		(mid 137.161619 -55.60459)
		(end 137.158984 -55.209186)
		(width 0.0889)
		(layer "B.Cu")
		(net "UPI_CPU0_CPU1_P1P1_DP<4>")
	)
	(arc
		(start 135.46709 -57.538112)
		(mid 135.494333 -57.361373)
		(end 135.441944 -57.190386)
		(width 0.0889)
		(layer "B.Cu")
		(net "UPI_CPU0_CPU1_P1P1_DP<4>")
	)
	(arc
		(start 136.300464 -56.104536)
		(mid 136.507468 -55.893672)
		(end 136.790684 -55.809388)
		(width 0.0889)
		(layer "B.Cu")
		(net "UPI_CPU0_CPU1_P1P1_DP<4>")
	)
	(arc
		(start 137.158984 -54.218586)
		(mid 137.153771 -53.637519)
		(end 137.648696 -53.332888)
		(width 0.0889)
		(layer "B.Cu")
		(net "UPI_CPU0_CPU1_P1P1_DP<4>")
	)
	(arc
		(start 138.021822 -53.12537)
		(mid 138.114122 -52.891742)
		(end 138.14552 -52.642516)
		(width 0.0889)
		(layer "B.Cu")
		(net "UPI_CPU0_CPU1_P1P1_DP<4>")
	)
	(arc
		(start 293.73957 -54.123336)
		(mid 293.818531 -54.411318)
		(end 293.746682 -54.701186)
		(width 0.0889)
		(layer "B.Cu")
		(net "UPI_CPU0_CPU1_P1P1_DP<4>")
	)
	(arc
		(start 137.158984 -55.209186)
		(mid 137.079762 -54.920068)
		(end 137.152634 -54.629304)
		(width 0.0889)
		(layer "B.Cu")
		(net "UPI_CPU0_CPU1_P1P1_DP<4>")
	)
	(arc
		(start 293.734744 -54.722522)
		(mid 293.685989 -54.918874)
		(end 293.73957 -55.113936)
		(width 0.0889)
		(layer "B.Cu")
		(net "UPI_CPU0_CPU1_P1P1_DP<4>")
	)
	(arc
		(start 135.441944 -57.190386)
		(mid 135.437615 -56.607214)
		(end 135.935974 -56.304434)
		(width 0.0889)
		(layer "B.Cu")
		(net "UPI_CPU0_CPU1_P1P1_DP<4>")
	)
	(arc
		(start 137.685272 -53.332888)
		(mid 137.880935 -53.273559)
		(end 138.021822 -53.12537)
		(width 0.0889)
		(layer "B.Cu")
		(net "UPI_CPU0_CPU1_P1P1_DP<4>")
	)
	(segment
		(start 292.65626 -55.409338)
		(end 293.22776 -55.409338)
		(width 0.1143)
		(layer "F.Cu")
		(net "UPI_CPU0_CPU1_P1P1_DP<3>")
	)
	(segment
		(start 136.240774 -58.381138)
		(end 136.812274 -58.381138)
		(width 0.1143)
		(layer "F.Cu")
		(net "UPI_CPU0_CPU1_P1P1_DP<3>")
	)
	(via
		(at 136.812274 -58.381138)
		(size 0.508)
		(drill 0.254)
		(layers "F.Cu" "B.Cu")
		(net "UPI_CPU0_CPU1_P1P1_DP<3>")
	)
	(via
		(at 293.22776 -55.409338)
		(size 0.508)
		(drill 0.254)
		(layers "F.Cu" "B.Cu")
		(net "UPI_CPU0_CPU1_P1P1_DP<3>")
	)
	(segment
		(start 146.714718 -48.861726)
		(end 146.743928 -48.702722)
		(width 0.1143)
		(layer "B.Cu")
		(net "UPI_CPU0_CPU1_P1P1_DP<3>")
	)
	(segment
		(start 260.136132 -45.44568)
		(end 259.99694 -44.807632)
		(width 0.1143)
		(layer "B.Cu")
		(net "UPI_CPU0_CPU1_P1P1_DP<3>")
	)
	(segment
		(start 291.693346 -52.694586)
		(end 291.72916 -52.694586)
		(width 0.0889)
		(layer "B.Cu")
		(net "UPI_CPU0_CPU1_P1P1_DP<3>")
	)
	(segment
		(start 136.797288 -56.990488)
		(end 136.830054 -56.990488)
		(width 0.0889)
		(layer "B.Cu")
		(net "UPI_CPU0_CPU1_P1P1_DP<3>")
	)
	(segment
		(start 140.916152 -53.182774)
		(end 140.977366 -52.86121)
		(width 0.1143)
		(layer "B.Cu")
		(net "UPI_CPU0_CPU1_P1P1_DP<3>")
	)
	(segment
		(start 257.969512 -45.53204)
		(end 257.910584 -45.262038)
		(width 0.1143)
		(layer "B.Cu")
		(net "UPI_CPU0_CPU1_P1P1_DP<3>")
	)
	(segment
		(start 141.805152 -51.381406)
		(end 142.423388 -51.496214)
		(width 0.1143)
		(layer "B.Cu")
		(net "UPI_CPU0_CPU1_P1P1_DP<3>")
	)
	(segment
		(start 145.133314 -50.780696)
		(end 145.199354 -50.425604)
		(width 0.1143)
		(layer "B.Cu")
		(net "UPI_CPU0_CPU1_P1P1_DP<3>")
	)
	(segment
		(start 136.812274 -58.488326)
		(end 136.69391 -58.60669)
		(width 0.0889)
		(layer "B.Cu")
		(net "UPI_CPU0_CPU1_P1P1_DP<3>")
	)
	(segment
		(start 281.8384 -48.772318)
		(end 282.634182 -48.717454)
		(width 0.1143)
		(layer "B.Cu")
		(net "UPI_CPU0_CPU1_P1P1_DP<3>")
	)
	(segment
		(start 138.188954 -55.619904)
		(end 138.182604 -55.609236)
		(width 0.0889)
		(layer "B.Cu")
		(net "UPI_CPU0_CPU1_P1P1_DP<3>")
	)
	(segment
		(start 226.856036 -48.42129)
		(end 240.832132 -45.626274)
		(width 0.1143)
		(layer "B.Cu")
		(net "UPI_CPU0_CPU1_P1P1_DP<3>")
	)
	(segment
		(start 140.473684 -53.353462)
		(end 140.499084 -53.378862)
		(width 0.0889)
		(layer "B.Cu")
		(net "UPI_CPU0_CPU1_P1P1_DP<3>")
	)
	(segment
		(start 146.854672 -49.064418)
		(end 146.714718 -48.861726)
		(width 0.1143)
		(layer "B.Cu")
		(net "UPI_CPU0_CPU1_P1P1_DP<3>")
	)
	(segment
		(start 152.502362 -46.86427)
		(end 152.502616 -46.86427)
		(width 0.1143)
		(layer "B.Cu")
		(net "UPI_CPU0_CPU1_P1P1_DP<3>")
	)
	(segment
		(start 139.96162 -53.353462)
		(end 140.055092 -53.446934)
		(width 0.0889)
		(layer "B.Cu")
		(net "UPI_CPU0_CPU1_P1P1_DP<3>")
	)
	(segment
		(start 144.607026 -49.363376)
		(end 145.099532 -49.024794)
		(width 0.1143)
		(layer "B.Cu")
		(net "UPI_CPU0_CPU1_P1P1_DP<3>")
	)
	(segment
		(start 287.93694 -48.511206)
		(end 289.38093 -50.29073)
		(width 0.1143)
		(layer "B.Cu")
		(net "UPI_CPU0_CPU1_P1P1_DP<3>")
	)
	(segment
		(start 140.055092 -53.446934)
		(end 140.232892 -53.446934)
		(width 0.0889)
		(layer "B.Cu")
		(net "UPI_CPU0_CPU1_P1P1_DP<3>")
	)
	(segment
		(start 281.554682 -48.364394)
		(end 281.56662 -48.534574)
		(width 0.1143)
		(layer "B.Cu")
		(net "UPI_CPU0_CPU1_P1P1_DP<3>")
	)
	(segment
		(start 291.326824 -52.328064)
		(end 291.693346 -52.694586)
		(width 0.1143)
		(layer "B.Cu")
		(net "UPI_CPU0_CPU1_P1P1_DP<3>")
	)
	(segment
		(start 136.422892 -58.509916)
		(end 136.414002 -58.421016)
		(width 0.0889)
		(layer "B.Cu")
		(net "UPI_CPU0_CPU1_P1P1_DP<3>")
	)
	(segment
		(start 146.743928 -48.702722)
		(end 147.19681 -48.391318)
		(width 0.1143)
		(layer "B.Cu")
		(net "UPI_CPU0_CPU1_P1P1_DP<3>")
	)
	(segment
		(start 139.419076 -53.353462)
		(end 139.512548 -53.446934)
		(width 0.0889)
		(layer "B.Cu")
		(net "UPI_CPU0_CPU1_P1P1_DP<3>")
	)
	(segment
		(start 287.467802 -48.419766)
		(end 287.638236 -48.362616)
		(width 0.1143)
		(layer "B.Cu")
		(net "UPI_CPU0_CPU1_P1P1_DP<3>")
	)
	(segment
		(start 222.396812 -47.529242)
		(end 226.856036 -48.42129)
		(width 0.1143)
		(layer "B.Cu")
		(net "UPI_CPU0_CPU1_P1P1_DP<3>")
	)
	(segment
		(start 287.638236 -48.362616)
		(end 287.93694 -48.511206)
		(width 0.1143)
		(layer "B.Cu")
		(net "UPI_CPU0_CPU1_P1P1_DP<3>")
	)
	(segment
		(start 147.42287 -48.433482)
		(end 147.62861 -48.732948)
		(width 0.1143)
		(layer "B.Cu")
		(net "UPI_CPU0_CPU1_P1P1_DP<3>")
	)
	(segment
		(start 194.804284 -41.274492)
		(end 197.58152 -40.139112)
		(width 0.1143)
		(layer "B.Cu")
		(net "UPI_CPU0_CPU1_P1P1_DP<3>")
	)
	(segment
		(start 291.324792 -52.326286)
		(end 291.326824 -52.328064)
		(width 0.1143)
		(layer "B.Cu")
		(net "UPI_CPU0_CPU1_P1P1_DP<3>")
	)
	(segment
		(start 262.508238 -45.369734)
		(end 262.5725 -45.026072)
		(width 0.1143)
		(layer "B.Cu")
		(net "UPI_CPU0_CPU1_P1P1_DP<3>")
	)
	(segment
		(start 136.812274 -58.381138)
		(end 136.812274 -58.488326)
		(width 0.0889)
		(layer "B.Cu")
		(net "UPI_CPU0_CPU1_P1P1_DP<3>")
	)
	(segment
		(start 144.4752 -51.233324)
		(end 145.133314 -50.780696)
		(width 0.1143)
		(layer "B.Cu")
		(net "UPI_CPU0_CPU1_P1P1_DP<3>")
	)
	(segment
		(start 257.99796 -45.126148)
		(end 258.582922 -44.998894)
		(width 0.1143)
		(layer "B.Cu")
		(net "UPI_CPU0_CPU1_P1P1_DP<3>")
	)
	(segment
		(start 136.465564 -57.590436)
		(end 136.460738 -57.5818)
		(width 0.0889)
		(layer "B.Cu")
		(net "UPI_CPU0_CPU1_P1P1_DP<3>")
	)
	(segment
		(start 136.471914 -57.601104)
		(end 136.465564 -57.590436)
		(width 0.0889)
		(layer "B.Cu")
		(net "UPI_CPU0_CPU1_P1P1_DP<3>")
	)
	(segment
		(start 279.929336 -48.361854)
		(end 281.43327 -48.258222)
		(width 0.1143)
		(layer "B.Cu")
		(net "UPI_CPU0_CPU1_P1P1_DP<3>")
	)
	(segment
		(start 149.507448 -47.750984)
		(end 149.507956 -47.75073)
		(width 0.1143)
		(layer "B.Cu")
		(net "UPI_CPU0_CPU1_P1P1_DP<3>")
	)
	(segment
		(start 152.502616 -46.86427)
		(end 155.497784 -45.977302)
		(width 0.1143)
		(layer "B.Cu")
		(net "UPI_CPU0_CPU1_P1P1_DP<3>")
	)
	(segment
		(start 248.9073 -47.105062)
		(end 256.496566 -45.453046)
		(width 0.1143)
		(layer "B.Cu")
		(net "UPI_CPU0_CPU1_P1P1_DP<3>")
	)
	(segment
		(start 144.577562 -49.521872)
		(end 144.607026 -49.363376)
		(width 0.1143)
		(layer "B.Cu")
		(net "UPI_CPU0_CPU1_P1P1_DP<3>")
	)
	(segment
		(start 145.199354 -50.425604)
		(end 144.577562 -49.521872)
		(width 0.1143)
		(layer "B.Cu")
		(net "UPI_CPU0_CPU1_P1P1_DP<3>")
	)
	(segment
		(start 258.857496 -45.72381)
		(end 259.16128 -45.919644)
		(width 0.1143)
		(layer "B.Cu")
		(net "UPI_CPU0_CPU1_P1P1_DP<3>")
	)
	(segment
		(start 142.423388 -51.496214)
		(end 143.635222 -50.663602)
		(width 0.1143)
		(layer "B.Cu")
		(net "UPI_CPU0_CPU1_P1P1_DP<3>")
	)
	(segment
		(start 281.56662 -48.534574)
		(end 281.8384 -48.772318)
		(width 0.1143)
		(layer "B.Cu")
		(net "UPI_CPU0_CPU1_P1P1_DP<3>")
	)
	(segment
		(start 207.490822 -44.547536)
		(end 222.396812 -47.529242)
		(width 0.1143)
		(layer "B.Cu")
		(net "UPI_CPU0_CPU1_P1P1_DP<3>")
	)
	(segment
		(start 256.99466 -46.006004)
		(end 257.773932 -45.835824)
		(width 0.1143)
		(layer "B.Cu")
		(net "UPI_CPU0_CPU1_P1P1_DP<3>")
	)
	(segment
		(start 140.977366 -52.86121)
		(end 140.974318 -52.856892)
		(width 0.1143)
		(layer "B.Cu")
		(net "UPI_CPU0_CPU1_P1P1_DP<3>")
	)
	(segment
		(start 197.58152 -40.139112)
		(end 202.28814 -41.079166)
		(width 0.1143)
		(layer "B.Cu")
		(net "UPI_CPU0_CPU1_P1P1_DP<3>")
	)
	(segment
		(start 286.688784 -47.890176)
		(end 287.1216 -48.105568)
		(width 0.1143)
		(layer "B.Cu")
		(net "UPI_CPU0_CPU1_P1P1_DP<3>")
	)
	(segment
		(start 257.910584 -45.262038)
		(end 257.99796 -45.126148)
		(width 0.1143)
		(layer "B.Cu")
		(net "UPI_CPU0_CPU1_P1P1_DP<3>")
	)
	(segment
		(start 172.650404 -46.167548)
		(end 184.55259 -43.78706)
		(width 0.1143)
		(layer "B.Cu")
		(net "UPI_CPU0_CPU1_P1P1_DP<3>")
	)
	(segment
		(start 145.099532 -49.024794)
		(end 145.258536 -49.054258)
		(width 0.1143)
		(layer "B.Cu")
		(net "UPI_CPU0_CPU1_P1P1_DP<3>")
	)
	(segment
		(start 147.62861 -48.732948)
		(end 147.983448 -48.798988)
		(width 0.1143)
		(layer "B.Cu")
		(net "UPI_CPU0_CPU1_P1P1_DP<3>")
	)
	(segment
		(start 261.426706 -45.426884)
		(end 262.210042 -45.57395)
		(width 0.1143)
		(layer "B.Cu")
		(net "UPI_CPU0_CPU1_P1P1_DP<3>")
	)
	(segment
		(start 257.773932 -45.835824)
		(end 257.969512 -45.53204)
		(width 0.1143)
		(layer "B.Cu")
		(net "UPI_CPU0_CPU1_P1P1_DP<3>")
	)
	(segment
		(start 259.16128 -45.919644)
		(end 259.940552 -45.749464)
		(width 0.1143)
		(layer "B.Cu")
		(net "UPI_CPU0_CPU1_P1P1_DP<3>")
	)
	(segment
		(start 139.300458 -53.353462)
		(end 139.419076 -53.353462)
		(width 0.0889)
		(layer "B.Cu")
		(net "UPI_CPU0_CPU1_P1P1_DP<3>")
	)
	(segment
		(start 145.767806 -49.795684)
		(end 146.11477 -49.859692)
		(width 0.1143)
		(layer "B.Cu")
		(net "UPI_CPU0_CPU1_P1P1_DP<3>")
	)
	(segment
		(start 155.497784 -45.977302)
		(end 166.449756 -48.246792)
		(width 0.1143)
		(layer "B.Cu")
		(net "UPI_CPU0_CPU1_P1P1_DP<3>")
	)
	(segment
		(start 248.9073 -47.104808)
		(end 248.9073 -47.105062)
		(width 0.1143)
		(layer "B.Cu")
		(net "UPI_CPU0_CPU1_P1P1_DP<3>")
	)
	(segment
		(start 283.563314 -48.112172)
		(end 283.947616 -48.447452)
		(width 0.1143)
		(layer "B.Cu")
		(net "UPI_CPU0_CPU1_P1P1_DP<3>")
	)
	(segment
		(start 147.983448 -48.798988)
		(end 149.507448 -47.750984)
		(width 0.1143)
		(layer "B.Cu")
		(net "UPI_CPU0_CPU1_P1P1_DP<3>")
	)
	(segment
		(start 140.232892 -53.446934)
		(end 140.326364 -53.353462)
		(width 0.0889)
		(layer "B.Cu")
		(net "UPI_CPU0_CPU1_P1P1_DP<3>")
	)
	(segment
		(start 259.940552 -45.749464)
		(end 260.136132 -45.44568)
		(width 0.1143)
		(layer "B.Cu")
		(net "UPI_CPU0_CPU1_P1P1_DP<3>")
	)
	(segment
		(start 146.11477 -49.859692)
		(end 146.794474 -49.39284)
		(width 0.1143)
		(layer "B.Cu")
		(net "UPI_CPU0_CPU1_P1P1_DP<3>")
	)
	(segment
		(start 260.084316 -44.671742)
		(end 260.68528 -44.540932)
		(width 0.1143)
		(layer "B.Cu")
		(net "UPI_CPU0_CPU1_P1P1_DP<3>")
	)
	(segment
		(start 291.72916 -52.694586)
		(end 292.769544 -53.73497)
		(width 0.0889)
		(layer "B.Cu")
		(net "UPI_CPU0_CPU1_P1P1_DP<3>")
	)
	(segment
		(start 285.946088 -48.068484)
		(end 286.174434 -48.052736)
		(width 0.1143)
		(layer "B.Cu")
		(net "UPI_CPU0_CPU1_P1P1_DP<3>")
	)
	(segment
		(start 261.19836 -44.636944)
		(end 261.289292 -44.769786)
		(width 0.1143)
		(layer "B.Cu")
		(net "UPI_CPU0_CPU1_P1P1_DP<3>")
	)
	(segment
		(start 287.262824 -48.318166)
		(end 287.467802 -48.419766)
		(width 0.1143)
		(layer "B.Cu")
		(net "UPI_CPU0_CPU1_P1P1_DP<3>")
	)
	(segment
		(start 149.507956 -47.75073)
		(end 152.502362 -46.86427)
		(width 0.1143)
		(layer "B.Cu")
		(net "UPI_CPU0_CPU1_P1P1_DP<3>")
	)
	(segment
		(start 292.750494 -54.767226)
		(end 293.22776 -55.409338)
		(width 0.0889)
		(layer "B.Cu")
		(net "UPI_CPU0_CPU1_P1P1_DP<3>")
	)
	(segment
		(start 261.221982 -45.128942)
		(end 261.426706 -45.426884)
		(width 0.1143)
		(layer "B.Cu")
		(net "UPI_CPU0_CPU1_P1P1_DP<3>")
	)
	(segment
		(start 191.208406 -43.85691)
		(end 194.804284 -41.274492)
		(width 0.1143)
		(layer "B.Cu")
		(net "UPI_CPU0_CPU1_P1P1_DP<3>")
	)
	(segment
		(start 282.871926 -48.444658)
		(end 282.860242 -48.274732)
		(width 0.1143)
		(layer "B.Cu")
		(net "UPI_CPU0_CPU1_P1P1_DP<3>")
	)
	(segment
		(start 137.659618 -56.494934)
		(end 137.692384 -56.494934)
		(width 0.0889)
		(layer "B.Cu")
		(net "UPI_CPU0_CPU1_P1P1_DP<3>")
	)
	(segment
		(start 260.68528 -44.540932)
		(end 261.19836 -44.636944)
		(width 0.1143)
		(layer "B.Cu")
		(net "UPI_CPU0_CPU1_P1P1_DP<3>")
	)
	(segment
		(start 287.205674 -48.147478)
		(end 287.262824 -48.318166)
		(width 0.1143)
		(layer "B.Cu")
		(net "UPI_CPU0_CPU1_P1P1_DP<3>")
	)
	(segment
		(start 146.794474 -49.39284)
		(end 146.854672 -49.064418)
		(width 0.1143)
		(layer "B.Cu")
		(net "UPI_CPU0_CPU1_P1P1_DP<3>")
	)
	(segment
		(start 140.974318 -52.856892)
		(end 141.167358 -51.81981)
		(width 0.1143)
		(layer "B.Cu")
		(net "UPI_CPU0_CPU1_P1P1_DP<3>")
	)
	(segment
		(start 139.690348 -53.446934)
		(end 139.78382 -53.353462)
		(width 0.0889)
		(layer "B.Cu")
		(net "UPI_CPU0_CPU1_P1P1_DP<3>")
	)
	(segment
		(start 140.678916 -53.378862)
		(end 140.916152 -53.182774)
		(width 0.1143)
		(layer "B.Cu")
		(net "UPI_CPU0_CPU1_P1P1_DP<3>")
	)
	(segment
		(start 139.192762 -53.461158)
		(end 139.300458 -53.353462)
		(width 0.0889)
		(layer "B.Cu")
		(net "UPI_CPU0_CPU1_P1P1_DP<3>")
	)
	(segment
		(start 283.947616 -48.447452)
		(end 284.589982 -48.403256)
		(width 0.1143)
		(layer "B.Cu")
		(net "UPI_CPU0_CPU1_P1P1_DP<3>")
	)
	(segment
		(start 256.690876 -45.81017)
		(end 256.99466 -46.006004)
		(width 0.1143)
		(layer "B.Cu")
		(net "UPI_CPU0_CPU1_P1P1_DP<3>")
	)
	(segment
		(start 139.036298 -53.731922)
		(end 139.192762 -53.461158)
		(width 0.0889)
		(layer "B.Cu")
		(net "UPI_CPU0_CPU1_P1P1_DP<3>")
	)
	(segment
		(start 284.589982 -48.403256)
		(end 284.93339 -48.010318)
		(width 0.1143)
		(layer "B.Cu")
		(net "UPI_CPU0_CPU1_P1P1_DP<3>")
	)
	(segment
		(start 248.526808 -47.165006)
		(end 248.9073 -47.104808)
		(width 0.1143)
		(layer "B.Cu")
		(net "UPI_CPU0_CPU1_P1P1_DP<3>")
	)
	(segment
		(start 147.19681 -48.391318)
		(end 147.42287 -48.433482)
		(width 0.1143)
		(layer "B.Cu")
		(net "UPI_CPU0_CPU1_P1P1_DP<3>")
	)
	(segment
		(start 140.326364 -53.353462)
		(end 140.473684 -53.353462)
		(width 0.0889)
		(layer "B.Cu")
		(net "UPI_CPU0_CPU1_P1P1_DP<3>")
	)
	(segment
		(start 143.793972 -50.693066)
		(end 144.120362 -51.167284)
		(width 0.1143)
		(layer "B.Cu")
		(net "UPI_CPU0_CPU1_P1P1_DP<3>")
	)
	(segment
		(start 259.99694 -44.807632)
		(end 260.084316 -44.671742)
		(width 0.1143)
		(layer "B.Cu")
		(net "UPI_CPU0_CPU1_P1P1_DP<3>")
	)
	(segment
		(start 261.289292 -44.769786)
		(end 261.221982 -45.128942)
		(width 0.1143)
		(layer "B.Cu")
		(net "UPI_CPU0_CPU1_P1P1_DP<3>")
	)
	(segment
		(start 145.258536 -49.054258)
		(end 145.767806 -49.795684)
		(width 0.1143)
		(layer "B.Cu")
		(net "UPI_CPU0_CPU1_P1P1_DP<3>")
	)
	(segment
		(start 282.860242 -48.274732)
		(end 282.96616 -48.15332)
		(width 0.1143)
		(layer "B.Cu")
		(net "UPI_CPU0_CPU1_P1P1_DP<3>")
	)
	(segment
		(start 282.634182 -48.717454)
		(end 282.871926 -48.444658)
		(width 0.1143)
		(layer "B.Cu")
		(net "UPI_CPU0_CPU1_P1P1_DP<3>")
	)
	(segment
		(start 284.93339 -48.010318)
		(end 285.810706 -47.950374)
		(width 0.1143)
		(layer "B.Cu")
		(net "UPI_CPU0_CPU1_P1P1_DP<3>")
	)
	(segment
		(start 141.167358 -51.81981)
		(end 141.805152 -51.381406)
		(width 0.1143)
		(layer "B.Cu")
		(net "UPI_CPU0_CPU1_P1P1_DP<3>")
	)
	(segment
		(start 262.706104 -44.935902)
		(end 279.929336 -48.361854)
		(width 0.1143)
		(layer "B.Cu")
		(net "UPI_CPU0_CPU1_P1P1_DP<3>")
	)
	(segment
		(start 256.631948 -45.539914)
		(end 256.690876 -45.81017)
		(width 0.1143)
		(layer "B.Cu")
		(net "UPI_CPU0_CPU1_P1P1_DP<3>")
	)
	(segment
		(start 282.96616 -48.15332)
		(end 283.563314 -48.112172)
		(width 0.1143)
		(layer "B.Cu")
		(net "UPI_CPU0_CPU1_P1P1_DP<3>")
	)
	(segment
		(start 285.810706 -47.950374)
		(end 285.946088 -48.068484)
		(width 0.1143)
		(layer "B.Cu")
		(net "UPI_CPU0_CPU1_P1P1_DP<3>")
	)
	(segment
		(start 202.28814 -41.079166)
		(end 207.490822 -44.547536)
		(width 0.1143)
		(layer "B.Cu")
		(net "UPI_CPU0_CPU1_P1P1_DP<3>")
	)
	(segment
		(start 262.210042 -45.57395)
		(end 262.508238 -45.369734)
		(width 0.1143)
		(layer "B.Cu")
		(net "UPI_CPU0_CPU1_P1P1_DP<3>")
	)
	(segment
		(start 140.499084 -53.378862)
		(end 140.678916 -53.378862)
		(width 0.1143)
		(layer "B.Cu")
		(net "UPI_CPU0_CPU1_P1P1_DP<3>")
	)
	(segment
		(start 240.832132 -45.626274)
		(end 248.526808 -47.165006)
		(width 0.1143)
		(layer "B.Cu")
		(net "UPI_CPU0_CPU1_P1P1_DP<3>")
	)
	(segment
		(start 286.292544 -47.9171)
		(end 286.688784 -47.890176)
		(width 0.1143)
		(layer "B.Cu")
		(net "UPI_CPU0_CPU1_P1P1_DP<3>")
	)
	(segment
		(start 139.512548 -53.446934)
		(end 139.690348 -53.446934)
		(width 0.0889)
		(layer "B.Cu")
		(net "UPI_CPU0_CPU1_P1P1_DP<3>")
	)
	(segment
		(start 291.32276 -52.324254)
		(end 291.324792 -52.326286)
		(width 0.1143)
		(layer "B.Cu")
		(net "UPI_CPU0_CPU1_P1P1_DP<3>")
	)
	(segment
		(start 184.55259 -43.78706)
		(end 191.208406 -43.85691)
		(width 0.1143)
		(layer "B.Cu")
		(net "UPI_CPU0_CPU1_P1P1_DP<3>")
	)
	(segment
		(start 256.496566 -45.453046)
		(end 256.631948 -45.539914)
		(width 0.1143)
		(layer "B.Cu")
		(net "UPI_CPU0_CPU1_P1P1_DP<3>")
	)
	(segment
		(start 287.1216 -48.105568)
		(end 287.205674 -48.147478)
		(width 0.1143)
		(layer "B.Cu")
		(net "UPI_CPU0_CPU1_P1P1_DP<3>")
	)
	(segment
		(start 281.43327 -48.258222)
		(end 281.554682 -48.364394)
		(width 0.1143)
		(layer "B.Cu")
		(net "UPI_CPU0_CPU1_P1P1_DP<3>")
	)
	(segment
		(start 258.718304 -45.085762)
		(end 258.857496 -45.72381)
		(width 0.1143)
		(layer "B.Cu")
		(net "UPI_CPU0_CPU1_P1P1_DP<3>")
	)
	(segment
		(start 143.635222 -50.663602)
		(end 143.793972 -50.693066)
		(width 0.1143)
		(layer "B.Cu")
		(net "UPI_CPU0_CPU1_P1P1_DP<3>")
	)
	(segment
		(start 292.769544 -53.844952)
		(end 292.76929 -53.923946)
		(width 0.0889)
		(layer "B.Cu")
		(net "UPI_CPU0_CPU1_P1P1_DP<3>")
	)
	(segment
		(start 292.769544 -53.73497)
		(end 292.769544 -53.844952)
		(width 0.0889)
		(layer "B.Cu")
		(net "UPI_CPU0_CPU1_P1P1_DP<3>")
	)
	(segment
		(start 138.182604 -55.609236)
		(end 138.177778 -55.6006)
		(width 0.0889)
		(layer "B.Cu")
		(net "UPI_CPU0_CPU1_P1P1_DP<3>")
	)
	(segment
		(start 258.582922 -44.998894)
		(end 258.718304 -45.085762)
		(width 0.1143)
		(layer "B.Cu")
		(net "UPI_CPU0_CPU1_P1P1_DP<3>")
	)
	(segment
		(start 166.449756 -48.246792)
		(end 172.650404 -46.167548)
		(width 0.1143)
		(layer "B.Cu")
		(net "UPI_CPU0_CPU1_P1P1_DP<3>")
	)
	(segment
		(start 139.78382 -53.353462)
		(end 139.96162 -53.353462)
		(width 0.0889)
		(layer "B.Cu")
		(net "UPI_CPU0_CPU1_P1P1_DP<3>")
	)
	(segment
		(start 144.120362 -51.167284)
		(end 144.4752 -51.233324)
		(width 0.1143)
		(layer "B.Cu")
		(net "UPI_CPU0_CPU1_P1P1_DP<3>")
	)
	(segment
		(start 262.5725 -45.026072)
		(end 262.706104 -44.935902)
		(width 0.1143)
		(layer "B.Cu")
		(net "UPI_CPU0_CPU1_P1P1_DP<3>")
	)
	(segment
		(start 138.514328 -55.009288)
		(end 138.547094 -55.009288)
		(width 0.0889)
		(layer "B.Cu")
		(net "UPI_CPU0_CPU1_P1P1_DP<3>")
	)
	(segment
		(start 286.174434 -48.052736)
		(end 286.292544 -47.9171)
		(width 0.1143)
		(layer "B.Cu")
		(net "UPI_CPU0_CPU1_P1P1_DP<3>")
	)
	(segment
		(start 289.38093 -50.29073)
		(end 291.32276 -52.324254)
		(width 0.1143)
		(layer "B.Cu")
		(net "UPI_CPU0_CPU1_P1P1_DP<3>")
	)
	(arc
		(start 137.324084 -56.695086)
		(mid 137.465767 -56.551282)
		(end 137.659618 -56.494934)
		(width 0.0889)
		(layer "B.Cu")
		(net "UPI_CPU0_CPU1_P1P1_DP<3>")
	)
	(arc
		(start 136.465564 -58.180986)
		(mid 136.544786 -57.891868)
		(end 136.471914 -57.601104)
		(width 0.0889)
		(layer "B.Cu")
		(net "UPI_CPU0_CPU1_P1P1_DP<3>")
	)
	(arc
		(start 136.460738 -57.5818)
		(mid 136.464485 -57.192544)
		(end 136.797288 -56.990488)
		(width 0.0889)
		(layer "B.Cu")
		(net "UPI_CPU0_CPU1_P1P1_DP<3>")
	)
	(arc
		(start 292.76929 -53.923946)
		(mid 292.755693 -54.027138)
		(end 292.71595 -54.123336)
		(width 0.0889)
		(layer "B.Cu")
		(net "UPI_CPU0_CPU1_P1P1_DP<3>")
	)
	(arc
		(start 136.830054 -56.990488)
		(mid 137.115478 -56.907021)
		(end 137.324084 -56.695086)
		(width 0.0889)
		(layer "B.Cu")
		(net "UPI_CPU0_CPU1_P1P1_DP<3>")
	)
	(arc
		(start 136.414002 -58.421016)
		(mid 136.412396 -58.399327)
		(end 136.41197 -58.377582)
		(width 0.0889)
		(layer "B.Cu")
		(net "UPI_CPU0_CPU1_P1P1_DP<3>")
	)
	(arc
		(start 138.547094 -55.009288)
		(mid 139.045345 -54.706448)
		(end 139.041124 -54.123336)
		(width 0.0889)
		(layer "B.Cu")
		(net "UPI_CPU0_CPU1_P1P1_DP<3>")
	)
	(arc
		(start 137.692384 -56.494934)
		(mid 138.184774 -56.196001)
		(end 138.188954 -55.619904)
		(width 0.0889)
		(layer "B.Cu")
		(net "UPI_CPU0_CPU1_P1P1_DP<3>")
	)
	(arc
		(start 136.41197 -58.377582)
		(mid 136.426056 -58.27582)
		(end 136.465564 -58.180986)
		(width 0.0889)
		(layer "B.Cu")
		(net "UPI_CPU0_CPU1_P1P1_DP<3>")
	)
	(arc
		(start 139.041124 -54.123336)
		(mid 138.987654 -53.928273)
		(end 139.036298 -53.731922)
		(width 0.0889)
		(layer "B.Cu")
		(net "UPI_CPU0_CPU1_P1P1_DP<3>")
	)
	(arc
		(start 292.71595 -54.123336)
		(mid 292.637668 -54.450406)
		(end 292.750494 -54.767226)
		(width 0.0889)
		(layer "B.Cu")
		(net "UPI_CPU0_CPU1_P1P1_DP<3>")
	)
	(arc
		(start 136.69391 -58.60669)
		(mid 136.527843 -58.644019)
		(end 136.422892 -58.509916)
		(width 0.0889)
		(layer "B.Cu")
		(net "UPI_CPU0_CPU1_P1P1_DP<3>")
	)
	(arc
		(start 138.177778 -55.6006)
		(mid 138.181525 -55.211344)
		(end 138.514328 -55.009288)
		(width 0.0889)
		(layer "B.Cu")
		(net "UPI_CPU0_CPU1_P1P1_DP<3>")
	)
	(segment
		(start 136.240774 -59.371484)
		(end 136.812274 -59.371484)
		(width 0.1143)
		(layer "F.Cu")
		(net "UPI_CPU0_CPU1_P1P1_DP<2>")
	)
	(segment
		(start 291.79774 -54.913784)
		(end 292.36924 -54.913784)
		(width 0.1143)
		(layer "F.Cu")
		(net "UPI_CPU0_CPU1_P1P1_DP<2>")
	)
	(via
		(at 292.36924 -54.913784)
		(size 0.508)
		(drill 0.254)
		(layers "F.Cu" "B.Cu")
		(net "UPI_CPU0_CPU1_P1P1_DP<2>")
	)
	(via
		(at 136.812274 -59.371484)
		(size 0.508)
		(drill 0.254)
		(layers "F.Cu" "B.Cu")
		(net "UPI_CPU0_CPU1_P1P1_DP<2>")
	)
	(segment
		(start 140.750036 -54.346348)
		(end 140.925804 -54.170834)
		(width 0.0889)
		(layer "B.Cu")
		(net "UPI_CPU0_CPU1_P1P1_DP<2>")
	)
	(segment
		(start 257.332226 -46.694344)
		(end 258.129278 -46.665896)
		(width 0.1143)
		(layer "B.Cu")
		(net "UPI_CPU0_CPU1_P1P1_DP<2>")
	)
	(segment
		(start 136.90219 -59.4614)
		(end 137.077958 -59.4614)
		(width 0.0889)
		(layer "B.Cu")
		(net "UPI_CPU0_CPU1_P1P1_DP<2>")
	)
	(segment
		(start 260.57479 -48.192436)
		(end 260.692392 -48.302418)
		(width 0.1143)
		(layer "B.Cu")
		(net "UPI_CPU0_CPU1_P1P1_DP<2>")
	)
	(segment
		(start 142.897098 -53.382672)
		(end 145.969228 -51.311556)
		(width 0.1143)
		(layer "B.Cu")
		(net "UPI_CPU0_CPU1_P1P1_DP<2>")
	)
	(segment
		(start 156.1592 -46.973998)
		(end 166.91483 -49.124108)
		(width 0.1143)
		(layer "B.Cu")
		(net "UPI_CPU0_CPU1_P1P1_DP<2>")
	)
	(segment
		(start 291.511228 -53.827934)
		(end 291.523674 -53.827934)
		(width 0.0889)
		(layer "B.Cu")
		(net "UPI_CPU0_CPU1_P1P1_DP<2>")
	)
	(segment
		(start 291.126418 -53.443124)
		(end 291.511228 -53.827934)
		(width 0.0889)
		(layer "B.Cu")
		(net "UPI_CPU0_CPU1_P1P1_DP<2>")
	)
	(segment
		(start 146.336258 -50.757836)
		(end 147.318476 -50.095404)
		(width 0.1143)
		(layer "B.Cu")
		(net "UPI_CPU0_CPU1_P1P1_DP<2>")
	)
	(segment
		(start 259.465826 -46.61916)
		(end 260.262878 -46.590712)
		(width 0.1143)
		(layer "B.Cu")
		(net "UPI_CPU0_CPU1_P1P1_DP<2>")
	)
	(segment
		(start 254.49149 -47.30115)
		(end 254.738378 -47.037244)
		(width 0.1143)
		(layer "B.Cu")
		(net "UPI_CPU0_CPU1_P1P1_DP<2>")
	)
	(segment
		(start 255.53543 -47.008796)
		(end 255.799336 -47.255684)
		(width 0.1143)
		(layer "B.Cu")
		(net "UPI_CPU0_CPU1_P1P1_DP<2>")
	)
	(segment
		(start 152.190704 -47.804832)
		(end 156.1592 -46.973998)
		(width 0.1143)
		(layer "B.Cu")
		(net "UPI_CPU0_CPU1_P1P1_DP<2>")
	)
	(segment
		(start 262.325612 -48.24476)
		(end 262.800592 -48.041052)
		(width 0.1143)
		(layer "B.Cu")
		(net "UPI_CPU0_CPU1_P1P1_DP<2>")
	)
	(segment
		(start 266.008358 -46.403768)
		(end 281.562048 -49.51476)
		(width 0.1143)
		(layer "B.Cu")
		(net "UPI_CPU0_CPU1_P1P1_DP<2>")
	)
	(segment
		(start 195.283836 -41.901364)
		(end 197.842124 -40.742616)
		(width 0.1143)
		(layer "B.Cu")
		(net "UPI_CPU0_CPU1_P1P1_DP<2>")
	)
	(segment
		(start 260.526784 -46.8376)
		(end 260.57479 -48.192436)
		(width 0.1143)
		(layer "B.Cu")
		(net "UPI_CPU0_CPU1_P1P1_DP<2>")
	)
	(segment
		(start 283.721302 -49.45126)
		(end 285.291784 -49.041304)
		(width 0.1143)
		(layer "B.Cu")
		(net "UPI_CPU0_CPU1_P1P1_DP<2>")
	)
	(segment
		(start 262.800592 -48.041052)
		(end 262.98652 -47.575216)
		(width 0.1143)
		(layer "B.Cu")
		(net "UPI_CPU0_CPU1_P1P1_DP<2>")
	)
	(segment
		(start 291.126418 -52.905406)
		(end 291.126418 -53.443124)
		(width 0.0889)
		(layer "B.Cu")
		(net "UPI_CPU0_CPU1_P1P1_DP<2>")
	)
	(segment
		(start 172.95622 -46.865286)
		(end 184.619392 -44.53255)
		(width 0.1143)
		(layer "B.Cu")
		(net "UPI_CPU0_CPU1_P1P1_DP<2>")
	)
	(segment
		(start 255.94691 -48.21047)
		(end 257.014218 -48.173132)
		(width 0.1143)
		(layer "B.Cu")
		(net "UPI_CPU0_CPU1_P1P1_DP<2>")
	)
	(segment
		(start 248.838212 -47.798228)
		(end 250.146058 -47.536354)
		(width 0.1143)
		(layer "B.Cu")
		(net "UPI_CPU0_CPU1_P1P1_DP<2>")
	)
	(segment
		(start 137.1854 -59.353958)
		(end 137.1854 -59.270646)
		(width 0.0889)
		(layer "B.Cu")
		(net "UPI_CPU0_CPU1_P1P1_DP<2>")
	)
	(segment
		(start 258.129278 -46.665896)
		(end 258.393184 -46.912784)
		(width 0.1143)
		(layer "B.Cu")
		(net "UPI_CPU0_CPU1_P1P1_DP<2>")
	)
	(segment
		(start 290.387278 -52.130198)
		(end 290.387278 -52.166266)
		(width 0.0889)
		(layer "B.Cu")
		(net "UPI_CPU0_CPU1_P1P1_DP<2>")
	)
	(segment
		(start 197.842124 -40.742616)
		(end 201.797412 -41.53281)
		(width 0.1143)
		(layer "B.Cu")
		(net "UPI_CPU0_CPU1_P1P1_DP<2>")
	)
	(segment
		(start 140.224764 -54.818788)
		(end 140.260832 -54.818788)
		(width 0.0889)
		(layer "B.Cu")
		(net "UPI_CPU0_CPU1_P1P1_DP<2>")
	)
	(segment
		(start 255.799336 -47.255684)
		(end 255.8288 -48.100488)
		(width 0.1143)
		(layer "B.Cu")
		(net "UPI_CPU0_CPU1_P1P1_DP<2>")
	)
	(segment
		(start 292.02253 -54.713886)
		(end 292.017704 -54.722522)
		(width 0.0889)
		(layer "B.Cu")
		(net "UPI_CPU0_CPU1_P1P1_DP<2>")
	)
	(segment
		(start 290.387278 -52.166266)
		(end 291.126418 -52.905406)
		(width 0.0889)
		(layer "B.Cu")
		(net "UPI_CPU0_CPU1_P1P1_DP<2>")
	)
	(segment
		(start 286.57042 -48.955452)
		(end 287.591754 -49.33442)
		(width 0.1143)
		(layer "B.Cu")
		(net "UPI_CPU0_CPU1_P1P1_DP<2>")
	)
	(segment
		(start 191.163956 -44.555918)
		(end 195.248784 -41.920414)
		(width 0.1143)
		(layer "B.Cu")
		(net "UPI_CPU0_CPU1_P1P1_DP<2>")
	)
	(segment
		(start 287.591754 -49.33442)
		(end 290.387278 -52.130198)
		(width 0.1143)
		(layer "B.Cu")
		(net "UPI_CPU0_CPU1_P1P1_DP<2>")
	)
	(segment
		(start 166.91483 -49.124108)
		(end 172.95622 -46.865286)
		(width 0.1143)
		(layer "B.Cu")
		(net "UPI_CPU0_CPU1_P1P1_DP<2>")
	)
	(segment
		(start 260.262878 -46.590712)
		(end 260.526784 -46.8376)
		(width 0.1143)
		(layer "B.Cu")
		(net "UPI_CPU0_CPU1_P1P1_DP<2>")
	)
	(segment
		(start 257.085592 -46.958504)
		(end 257.332226 -46.694344)
		(width 0.1143)
		(layer "B.Cu")
		(net "UPI_CPU0_CPU1_P1P1_DP<2>")
	)
	(segment
		(start 137.653014 -57.295034)
		(end 137.68578 -57.295034)
		(width 0.0889)
		(layer "B.Cu")
		(net "UPI_CPU0_CPU1_P1P1_DP<2>")
	)
	(segment
		(start 184.619392 -44.53255)
		(end 191.163956 -44.555918)
		(width 0.1143)
		(layer "B.Cu")
		(net "UPI_CPU0_CPU1_P1P1_DP<2>")
	)
	(segment
		(start 150.56104 -48.215804)
		(end 152.190704 -47.804832)
		(width 0.1143)
		(layer "B.Cu")
		(net "UPI_CPU0_CPU1_P1P1_DP<2>")
	)
	(segment
		(start 260.692392 -48.302418)
		(end 262.325612 -48.24476)
		(width 0.1143)
		(layer "B.Cu")
		(net "UPI_CPU0_CPU1_P1P1_DP<2>")
	)
	(segment
		(start 258.449826 -48.517048)
		(end 258.567428 -48.62703)
		(width 0.1143)
		(layer "B.Cu")
		(net "UPI_CPU0_CPU1_P1P1_DP<2>")
	)
	(segment
		(start 264.338816 -47.119286)
		(end 266.008358 -46.403768)
		(width 0.1143)
		(layer "B.Cu")
		(net "UPI_CPU0_CPU1_P1P1_DP<2>")
	)
	(segment
		(start 263.768332 -46.07687)
		(end 264.189464 -47.059342)
		(width 0.1143)
		(layer "B.Cu")
		(net "UPI_CPU0_CPU1_P1P1_DP<2>")
	)
	(segment
		(start 195.248784 -41.920414)
		(end 195.283836 -41.901364)
		(width 0.1143)
		(layer "B.Cu")
		(net "UPI_CPU0_CPU1_P1P1_DP<2>")
	)
	(segment
		(start 263.432544 -45.942758)
		(end 263.768332 -46.07687)
		(width 0.1143)
		(layer "B.Cu")
		(net "UPI_CPU0_CPU1_P1P1_DP<2>")
	)
	(segment
		(start 141.895576 -54.170834)
		(end 141.920976 -54.145434)
		(width 0.0889)
		(layer "B.Cu")
		(net "UPI_CPU0_CPU1_P1P1_DP<2>")
	)
	(segment
		(start 137.158984 -59.171586)
		(end 137.152634 -59.160918)
		(width 0.0889)
		(layer "B.Cu")
		(net "UPI_CPU0_CPU1_P1P1_DP<2>")
	)
	(segment
		(start 142.134336 -54.145434)
		(end 142.897098 -53.382672)
		(width 0.1143)
		(layer "B.Cu")
		(net "UPI_CPU0_CPU1_P1P1_DP<2>")
	)
	(segment
		(start 137.158984 -58.581036)
		(end 137.16381 -58.5724)
		(width 0.0889)
		(layer "B.Cu")
		(net "UPI_CPU0_CPU1_P1P1_DP<2>")
	)
	(segment
		(start 292.02888 -54.703218)
		(end 292.02253 -54.713886)
		(width 0.0889)
		(layer "B.Cu")
		(net "UPI_CPU0_CPU1_P1P1_DP<2>")
	)
	(segment
		(start 222.396812 -48.26889)
		(end 226.94392 -49.178464)
		(width 0.1143)
		(layer "B.Cu")
		(net "UPI_CPU0_CPU1_P1P1_DP<2>")
	)
	(segment
		(start 281.562048 -49.51476)
		(end 283.721302 -49.45126)
		(width 0.1143)
		(layer "B.Cu")
		(net "UPI_CPU0_CPU1_P1P1_DP<2>")
	)
	(segment
		(start 291.997384 -55.061612)
		(end 292.076124 -55.082948)
		(width 0.0889)
		(layer "B.Cu")
		(net "UPI_CPU0_CPU1_P1P1_DP<2>")
	)
	(segment
		(start 241.342672 -46.298866)
		(end 248.838212 -47.798228)
		(width 0.1143)
		(layer "B.Cu")
		(net "UPI_CPU0_CPU1_P1P1_DP<2>")
	)
	(segment
		(start 264.189464 -47.059342)
		(end 264.338816 -47.119286)
		(width 0.1143)
		(layer "B.Cu")
		(net "UPI_CPU0_CPU1_P1P1_DP<2>")
	)
	(segment
		(start 141.920976 -54.145434)
		(end 142.134336 -54.145434)
		(width 0.1143)
		(layer "B.Cu")
		(net "UPI_CPU0_CPU1_P1P1_DP<2>")
	)
	(segment
		(start 147.318476 -50.095404)
		(end 147.96897 -49.96307)
		(width 0.1143)
		(layer "B.Cu")
		(net "UPI_CPU0_CPU1_P1P1_DP<2>")
	)
	(segment
		(start 262.98652 -47.575216)
		(end 262.565388 -46.592744)
		(width 0.1143)
		(layer "B.Cu")
		(net "UPI_CPU0_CPU1_P1P1_DP<2>")
	)
	(segment
		(start 140.593064 -54.618636)
		(end 140.750036 -54.346348)
		(width 0.0889)
		(layer "B.Cu")
		(net "UPI_CPU0_CPU1_P1P1_DP<2>")
	)
	(segment
		(start 207.402176 -45.269404)
		(end 222.396812 -48.26889)
		(width 0.1143)
		(layer "B.Cu")
		(net "UPI_CPU0_CPU1_P1P1_DP<2>")
	)
	(segment
		(start 145.969228 -51.311556)
		(end 146.336258 -50.757836)
		(width 0.1143)
		(layer "B.Cu")
		(net "UPI_CPU0_CPU1_P1P1_DP<2>")
	)
	(segment
		(start 258.393184 -46.912784)
		(end 258.449826 -48.517048)
		(width 0.1143)
		(layer "B.Cu")
		(net "UPI_CPU0_CPU1_P1P1_DP<2>")
	)
	(segment
		(start 250.146058 -47.536354)
		(end 253.638558 -48.290988)
		(width 0.1143)
		(layer "B.Cu")
		(net "UPI_CPU0_CPU1_P1P1_DP<2>")
	)
	(segment
		(start 147.96897 -49.96307)
		(end 150.56104 -48.215804)
		(width 0.1143)
		(layer "B.Cu")
		(net "UPI_CPU0_CPU1_P1P1_DP<2>")
	)
	(segment
		(start 259.165598 -48.605948)
		(end 259.27558 -48.488092)
		(width 0.1143)
		(layer "B.Cu")
		(net "UPI_CPU0_CPU1_P1P1_DP<2>")
	)
	(segment
		(start 201.797412 -41.53281)
		(end 207.402176 -45.269404)
		(width 0.1143)
		(layer "B.Cu")
		(net "UPI_CPU0_CPU1_P1P1_DP<2>")
	)
	(segment
		(start 255.8288 -48.100488)
		(end 255.94691 -48.21047)
		(width 0.1143)
		(layer "B.Cu")
		(net "UPI_CPU0_CPU1_P1P1_DP<2>")
	)
	(segment
		(start 259.219192 -46.883574)
		(end 259.465826 -46.61916)
		(width 0.1143)
		(layer "B.Cu")
		(net "UPI_CPU0_CPU1_P1P1_DP<2>")
	)
	(segment
		(start 253.638558 -48.290988)
		(end 254.411226 -48.264064)
		(width 0.1143)
		(layer "B.Cu")
		(net "UPI_CPU0_CPU1_P1P1_DP<2>")
	)
	(segment
		(start 262.565388 -46.592744)
		(end 262.6995 -46.256956)
		(width 0.1143)
		(layer "B.Cu")
		(net "UPI_CPU0_CPU1_P1P1_DP<2>")
	)
	(segment
		(start 254.521208 -48.145954)
		(end 254.49149 -47.30115)
		(width 0.1143)
		(layer "B.Cu")
		(net "UPI_CPU0_CPU1_P1P1_DP<2>")
	)
	(segment
		(start 137.077958 -59.4614)
		(end 137.1854 -59.353958)
		(width 0.0889)
		(layer "B.Cu")
		(net "UPI_CPU0_CPU1_P1P1_DP<2>")
	)
	(segment
		(start 136.812274 -59.371484)
		(end 136.90219 -59.4614)
		(width 0.0889)
		(layer "B.Cu")
		(net "UPI_CPU0_CPU1_P1P1_DP<2>")
	)
	(segment
		(start 254.411226 -48.264064)
		(end 254.521208 -48.145954)
		(width 0.1143)
		(layer "B.Cu")
		(net "UPI_CPU0_CPU1_P1P1_DP<2>")
	)
	(segment
		(start 257.1242 -48.05553)
		(end 257.085592 -46.958504)
		(width 0.1143)
		(layer "B.Cu")
		(net "UPI_CPU0_CPU1_P1P1_DP<2>")
	)
	(segment
		(start 139.370054 -55.313834)
		(end 139.40282 -55.313834)
		(width 0.0889)
		(layer "B.Cu")
		(net "UPI_CPU0_CPU1_P1P1_DP<2>")
	)
	(segment
		(start 285.291784 -49.041304)
		(end 286.57042 -48.955452)
		(width 0.1143)
		(layer "B.Cu")
		(net "UPI_CPU0_CPU1_P1P1_DP<2>")
	)
	(segment
		(start 262.6995 -46.256956)
		(end 263.432544 -45.942758)
		(width 0.1143)
		(layer "B.Cu")
		(net "UPI_CPU0_CPU1_P1P1_DP<2>")
	)
	(segment
		(start 138.507724 -56.799988)
		(end 138.54049 -56.799988)
		(width 0.0889)
		(layer "B.Cu")
		(net "UPI_CPU0_CPU1_P1P1_DP<2>")
	)
	(segment
		(start 258.567428 -48.62703)
		(end 259.165598 -48.605948)
		(width 0.1143)
		(layer "B.Cu")
		(net "UPI_CPU0_CPU1_P1P1_DP<2>")
	)
	(segment
		(start 254.738378 -47.037244)
		(end 255.53543 -47.008796)
		(width 0.1143)
		(layer "B.Cu")
		(net "UPI_CPU0_CPU1_P1P1_DP<2>")
	)
	(segment
		(start 226.94392 -49.178464)
		(end 241.342672 -46.298866)
		(width 0.1143)
		(layer "B.Cu")
		(net "UPI_CPU0_CPU1_P1P1_DP<2>")
	)
	(segment
		(start 292.076124 -55.082948)
		(end 292.36924 -54.913784)
		(width 0.0889)
		(layer "B.Cu")
		(net "UPI_CPU0_CPU1_P1P1_DP<2>")
	)
	(segment
		(start 140.925804 -54.170834)
		(end 141.895576 -54.170834)
		(width 0.0889)
		(layer "B.Cu")
		(net "UPI_CPU0_CPU1_P1P1_DP<2>")
	)
	(segment
		(start 257.014218 -48.173132)
		(end 257.1242 -48.05553)
		(width 0.1143)
		(layer "B.Cu")
		(net "UPI_CPU0_CPU1_P1P1_DP<2>")
	)
	(segment
		(start 259.27558 -48.488092)
		(end 259.219192 -46.883574)
		(width 0.1143)
		(layer "B.Cu")
		(net "UPI_CPU0_CPU1_P1P1_DP<2>")
	)
	(arc
		(start 138.54049 -56.799988)
		(mid 138.878659 -56.59519)
		(end 138.876024 -56.199786)
		(width 0.0889)
		(layer "B.Cu")
		(net "UPI_CPU0_CPU1_P1P1_DP<2>")
	)
	(arc
		(start 291.523674 -53.827934)
		(mid 292.022555 -54.123371)
		(end 292.02888 -54.703218)
		(width 0.0889)
		(layer "B.Cu")
		(net "UPI_CPU0_CPU1_P1P1_DP<2>")
	)
	(arc
		(start 291.96919 -54.914546)
		(mid 291.976349 -54.989409)
		(end 291.997384 -55.061612)
		(width 0.0889)
		(layer "B.Cu")
		(net "UPI_CPU0_CPU1_P1P1_DP<2>")
	)
	(arc
		(start 292.017704 -54.722522)
		(mid 291.981386 -54.815487)
		(end 291.96919 -54.914546)
		(width 0.0889)
		(layer "B.Cu")
		(net "UPI_CPU0_CPU1_P1P1_DP<2>")
	)
	(arc
		(start 138.876024 -56.199786)
		(mid 138.871695 -55.616614)
		(end 139.370054 -55.313834)
		(width 0.0889)
		(layer "B.Cu")
		(net "UPI_CPU0_CPU1_P1P1_DP<2>")
	)
	(arc
		(start 137.16381 -58.5724)
		(mid 137.212565 -58.376048)
		(end 137.158984 -58.180986)
		(width 0.0889)
		(layer "B.Cu")
		(net "UPI_CPU0_CPU1_P1P1_DP<2>")
	)
	(arc
		(start 140.260832 -54.818788)
		(mid 140.452849 -54.76168)
		(end 140.593064 -54.618636)
		(width 0.0889)
		(layer "B.Cu")
		(net "UPI_CPU0_CPU1_P1P1_DP<2>")
	)
	(arc
		(start 139.734544 -55.113936)
		(mid 139.941548 -54.903072)
		(end 140.224764 -54.818788)
		(width 0.0889)
		(layer "B.Cu")
		(net "UPI_CPU0_CPU1_P1P1_DP<2>")
	)
	(arc
		(start 137.68578 -57.295034)
		(mid 137.877422 -57.237868)
		(end 138.017504 -57.095136)
		(width 0.0889)
		(layer "B.Cu")
		(net "UPI_CPU0_CPU1_P1P1_DP<2>")
	)
	(arc
		(start 139.40282 -55.313834)
		(mid 139.594462 -55.256668)
		(end 139.734544 -55.113936)
		(width 0.0889)
		(layer "B.Cu")
		(net "UPI_CPU0_CPU1_P1P1_DP<2>")
	)
	(arc
		(start 137.158984 -58.180986)
		(mid 137.154655 -57.597814)
		(end 137.653014 -57.295034)
		(width 0.0889)
		(layer "B.Cu")
		(net "UPI_CPU0_CPU1_P1P1_DP<2>")
	)
	(arc
		(start 137.1854 -59.270646)
		(mid 137.178673 -59.219391)
		(end 137.158984 -59.171586)
		(width 0.0889)
		(layer "B.Cu")
		(net "UPI_CPU0_CPU1_P1P1_DP<2>")
	)
	(arc
		(start 137.152634 -59.160918)
		(mid 137.079836 -58.870155)
		(end 137.158984 -58.581036)
		(width 0.0889)
		(layer "B.Cu")
		(net "UPI_CPU0_CPU1_P1P1_DP<2>")
	)
	(arc
		(start 138.017504 -57.095136)
		(mid 138.224508 -56.884272)
		(end 138.507724 -56.799988)
		(width 0.0889)
		(layer "B.Cu")
		(net "UPI_CPU0_CPU1_P1P1_DP<2>")
	)
	(segment
		(start 137.099294 -58.876438)
		(end 137.670794 -58.876438)
		(width 0.1143)
		(layer "F.Cu")
		(net "UPI_CPU0_CPU1_P1P1_DP<1>")
	)
	(segment
		(start 290.93922 -54.418738)
		(end 291.51072 -54.418738)
		(width 0.1143)
		(layer "F.Cu")
		(net "UPI_CPU0_CPU1_P1P1_DP<1>")
	)
	(via
		(at 170.528234 -49.10074)
		(size 0.508)
		(drill 0.254)
		(layers "F.Cu" "B.Cu")
		(net "UPI_CPU0_CPU1_P1P1_DP<1>")
	)
	(via
		(at 137.670794 -58.876438)
		(size 0.508)
		(drill 0.254)
		(layers "F.Cu" "B.Cu")
		(net "UPI_CPU0_CPU1_P1P1_DP<1>")
	)
	(via
		(at 291.51072 -54.418738)
		(size 0.508)
		(drill 0.254)
		(layers "F.Cu" "B.Cu")
		(net "UPI_CPU0_CPU1_P1P1_DP<1>")
	)
	(segment
		(start 248.982738 -48.852074)
		(end 248.204736 -48.93183)
		(width 0.1143)
		(layer "B.Cu")
		(net "UPI_CPU0_CPU1_P1P1_DP<1>")
	)
	(segment
		(start 201.06767 -42.415206)
		(end 198.359014 -41.873424)
		(width 0.1143)
		(layer "B.Cu")
		(net "UPI_CPU0_CPU1_P1P1_DP<1>")
	)
	(segment
		(start 151.686514 -49.189386)
		(end 148.866352 -51.101498)
		(width 0.1143)
		(layer "B.Cu")
		(net "UPI_CPU0_CPU1_P1P1_DP<1>")
	)
	(segment
		(start 270.546068 -50.219356)
		(end 270.345662 -49.918874)
		(width 0.1143)
		(layer "B.Cu")
		(net "UPI_CPU0_CPU1_P1P1_DP<1>")
	)
	(segment
		(start 279.16632 -50.57267)
		(end 278.775414 -50.833782)
		(width 0.1143)
		(layer "B.Cu")
		(net "UPI_CPU0_CPU1_P1P1_DP<1>")
	)
	(segment
		(start 267.789152 -48.182784)
		(end 267.654786 -48.272446)
		(width 0.1143)
		(layer "B.Cu")
		(net "UPI_CPU0_CPU1_P1P1_DP<1>")
	)
	(segment
		(start 284.127956 -51.181762)
		(end 283.626306 -51.557682)
		(width 0.1143)
		(layer "B.Cu")
		(net "UPI_CPU0_CPU1_P1P1_DP<1>")
	)
	(segment
		(start 267.33881 -49.853596)
		(end 267.038582 -50.054002)
		(width 0.1143)
		(layer "B.Cu")
		(net "UPI_CPU0_CPU1_P1P1_DP<1>")
	)
	(segment
		(start 269.748762 -48.691038)
		(end 269.524226 -49.814226)
		(width 0.1143)
		(layer "B.Cu")
		(net "UPI_CPU0_CPU1_P1P1_DP<1>")
	)
	(segment
		(start 268.379448 -50.164746)
		(end 268.179042 -49.864264)
		(width 0.1143)
		(layer "B.Cu")
		(net "UPI_CPU0_CPU1_P1P1_DP<1>")
	)
	(segment
		(start 196.070474 -42.859198)
		(end 191.666114 -45.804074)
		(width 0.1143)
		(layer "B.Cu")
		(net "UPI_CPU0_CPU1_P1P1_DP<1>")
	)
	(segment
		(start 142.600426 -55.54091)
		(end 142.600426 -55.540656)
		(width 0.0889)
		(layer "B.Cu")
		(net "UPI_CPU0_CPU1_P1P1_DP<1>")
	)
	(segment
		(start 274.18411 -50.992024)
		(end 273.402552 -50.835814)
		(width 0.1143)
		(layer "B.Cu")
		(net "UPI_CPU0_CPU1_P1P1_DP<1>")
	)
	(segment
		(start 142.925038 -55.345838)
		(end 142.600426 -55.54091)
		(width 0.0889)
		(layer "B.Cu")
		(net "UPI_CPU0_CPU1_P1P1_DP<1>")
	)
	(segment
		(start 270.345662 -49.918874)
		(end 270.558514 -48.852836)
		(width 0.1143)
		(layer "B.Cu")
		(net "UPI_CPU0_CPU1_P1P1_DP<1>")
	)
	(segment
		(start 268.179042 -49.864264)
		(end 268.411198 -48.701198)
		(width 0.1143)
		(layer "B.Cu")
		(net "UPI_CPU0_CPU1_P1P1_DP<1>")
	)
	(segment
		(start 274.484846 -50.791364)
		(end 274.18411 -50.992024)
		(width 0.1143)
		(layer "B.Cu")
		(net "UPI_CPU0_CPU1_P1P1_DP<1>")
	)
	(segment
		(start 148.51507 -51.634898)
		(end 146.182334 -53.216556)
		(width 0.1143)
		(layer "B.Cu")
		(net "UPI_CPU0_CPU1_P1P1_DP<1>")
	)
	(segment
		(start 268.374876 -48.299878)
		(end 267.789152 -48.182784)
		(width 0.1143)
		(layer "B.Cu")
		(net "UPI_CPU0_CPU1_P1P1_DP<1>")
	)
	(segment
		(start 273.402552 -50.835814)
		(end 273.201892 -50.535078)
		(width 0.1143)
		(layer "B.Cu")
		(net "UPI_CPU0_CPU1_P1P1_DP<1>")
	)
	(segment
		(start 146.182334 -53.216556)
		(end 146.063462 -53.193696)
		(width 0.1143)
		(layer "B.Cu")
		(net "UPI_CPU0_CPU1_P1P1_DP<1>")
	)
	(segment
		(start 265.13155 -48.149764)
		(end 264.072116 -49.000156)
		(width 0.1143)
		(layer "B.Cu")
		(net "UPI_CPU0_CPU1_P1P1_DP<1>")
	)
	(segment
		(start 191.666114 -45.804074)
		(end 184.734708 -45.750988)
		(width 0.1143)
		(layer "B.Cu")
		(net "UPI_CPU0_CPU1_P1P1_DP<1>")
	)
	(segment
		(start 267.038582 -50.054002)
		(end 266.255246 -49.897284)
		(width 0.1143)
		(layer "B.Cu")
		(net "UPI_CPU0_CPU1_P1P1_DP<1>")
	)
	(segment
		(start 274.8407 -49.591468)
		(end 274.706842 -49.680876)
		(width 0.1143)
		(layer "B.Cu")
		(net "UPI_CPU0_CPU1_P1P1_DP<1>")
	)
	(segment
		(start 266.255246 -49.897284)
		(end 266.05484 -49.596802)
		(width 0.1143)
		(layer "B.Cu")
		(net "UPI_CPU0_CPU1_P1P1_DP<1>")
	)
	(segment
		(start 268.411198 -48.701198)
		(end 268.464538 -48.434244)
		(width 0.1143)
		(layer "B.Cu")
		(net "UPI_CPU0_CPU1_P1P1_DP<1>")
	)
	(segment
		(start 275.7932 -49.782222)
		(end 274.8407 -49.591468)
		(width 0.1143)
		(layer "B.Cu")
		(net "UPI_CPU0_CPU1_P1P1_DP<1>")
	)
	(segment
		(start 184.734708 -45.750988)
		(end 173.307756 -48.035972)
		(width 0.1143)
		(layer "B.Cu")
		(net "UPI_CPU0_CPU1_P1P1_DP<1>")
	)
	(segment
		(start 271.629632 -50.175668)
		(end 271.329404 -50.376074)
		(width 0.1143)
		(layer "B.Cu")
		(net "UPI_CPU0_CPU1_P1P1_DP<1>")
	)
	(segment
		(start 264.193274 -49.332388)
		(end 264.137394 -49.842928)
		(width 0.1143)
		(layer "B.Cu")
		(net "UPI_CPU0_CPU1_P1P1_DP<1>")
	)
	(segment
		(start 273.423634 -49.42459)
		(end 273.333972 -49.290478)
		(width 0.1143)
		(layer "B.Cu")
		(net "UPI_CPU0_CPU1_P1P1_DP<1>")
	)
	(segment
		(start 146.063462 -53.193696)
		(end 144.75841 -54.078378)
		(width 0.1143)
		(layer "B.Cu")
		(net "UPI_CPU0_CPU1_P1P1_DP<1>")
	)
	(segment
		(start 289.78098 -53.166518)
		(end 288.849562 -52.2351)
		(width 0.0889)
		(layer "B.Cu")
		(net "UPI_CPU0_CPU1_P1P1_DP<1>")
	)
	(segment
		(start 284.748732 -50.71618)
		(end 284.51429 -50.891948)
		(width 0.1143)
		(layer "B.Cu")
		(net "UPI_CPU0_CPU1_P1P1_DP<1>")
	)
	(segment
		(start 140.264134 -56.990488)
		(end 140.231368 -56.990488)
		(width 0.0889)
		(layer "B.Cu")
		(net "UPI_CPU0_CPU1_P1P1_DP<1>")
	)
	(segment
		(start 284.51429 -50.891948)
		(end 284.48889 -51.070002)
		(width 0.1143)
		(layer "B.Cu")
		(net "UPI_CPU0_CPU1_P1P1_DP<1>")
	)
	(segment
		(start 271.977104 -49.019968)
		(end 271.842738 -49.10963)
		(width 0.1143)
		(layer "B.Cu")
		(net "UPI_CPU0_CPU1_P1P1_DP<1>")
	)
	(segment
		(start 269.462758 -50.121058)
		(end 269.162784 -50.321464)
		(width 0.1143)
		(layer "B.Cu")
		(net "UPI_CPU0_CPU1_P1P1_DP<1>")
	)
	(segment
		(start 281.83713 -51.914806)
		(end 281.212036 -51.790092)
		(width 0.1143)
		(layer "B.Cu")
		(net "UPI_CPU0_CPU1_P1P1_DP<1>")
	)
	(segment
		(start 270.468852 -48.71847)
		(end 269.883128 -48.601376)
		(width 0.1143)
		(layer "B.Cu")
		(net "UPI_CPU0_CPU1_P1P1_DP<1>")
	)
	(segment
		(start 285.109666 -50.60442)
		(end 284.926532 -50.74158)
		(width 0.1143)
		(layer "B.Cu")
		(net "UPI_CPU0_CPU1_P1P1_DP<1>")
	)
	(segment
		(start 143.453866 -55.346854)
		(end 142.925038 -55.345838)
		(width 0.0889)
		(layer "B.Cu")
		(net "UPI_CPU0_CPU1_P1P1_DP<1>")
	)
	(segment
		(start 222.396812 -49.501552)
		(end 207.111854 -46.444662)
		(width 0.1143)
		(layer "B.Cu")
		(net "UPI_CPU0_CPU1_P1P1_DP<1>")
	)
	(segment
		(start 291.281358 -54.513734)
		(end 290.149026 -54.513734)
		(width 0.0889)
		(layer "B.Cu")
		(net "UPI_CPU0_CPU1_P1P1_DP<1>")
	)
	(segment
		(start 141.126464 -56.494934)
		(end 141.093698 -56.494934)
		(width 0.0889)
		(layer "B.Cu")
		(net "UPI_CPU0_CPU1_P1P1_DP<1>")
	)
	(segment
		(start 249.458226 -48.803306)
		(end 249.346974 -48.939958)
		(width 0.1143)
		(layer "B.Cu")
		(net "UPI_CPU0_CPU1_P1P1_DP<1>")
	)
	(segment
		(start 288.719006 -52.2351)
		(end 288.422334 -51.938428)
		(width 0.0889)
		(layer "B.Cu")
		(net "UPI_CPU0_CPU1_P1P1_DP<1>")
	)
	(segment
		(start 278.775414 -50.833782)
		(end 277.940516 -50.666904)
		(width 0.1143)
		(layer "B.Cu")
		(net "UPI_CPU0_CPU1_P1P1_DP<1>")
	)
	(segment
		(start 266.370562 -48.015652)
		(end 266.2809 -47.881286)
		(width 0.1143)
		(layer "B.Cu")
		(net "UPI_CPU0_CPU1_P1P1_DP<1>")
	)
	(segment
		(start 170.528234 -49.100994)
		(end 167.126158 -50.404014)
		(width 0.1143)
		(layer "B.Cu")
		(net "UPI_CPU0_CPU1_P1P1_DP<1>")
	)
	(segment
		(start 279.480264 -50.63617)
		(end 279.16632 -50.57267)
		(width 0.1143)
		(layer "B.Cu")
		(net "UPI_CPU0_CPU1_P1P1_DP<1>")
	)
	(segment
		(start 285.317946 -50.28946)
		(end 285.135066 -50.426366)
		(width 0.1143)
		(layer "B.Cu")
		(net "UPI_CPU0_CPU1_P1P1_DP<1>")
	)
	(segment
		(start 142.600426 -55.540656)
		(end 142.515082 -55.701692)
		(width 0.0889)
		(layer "B.Cu")
		(net "UPI_CPU0_CPU1_P1P1_DP<1>")
	)
	(segment
		(start 267.654786 -48.272446)
		(end 267.33881 -49.853596)
		(width 0.1143)
		(layer "B.Cu")
		(net "UPI_CPU0_CPU1_P1P1_DP<1>")
	)
	(segment
		(start 262.099552 -50.378614)
		(end 261.396988 -50.63109)
		(width 0.1143)
		(layer "B.Cu")
		(net "UPI_CPU0_CPU1_P1P1_DP<1>")
	)
	(segment
		(start 144.75841 -54.078378)
		(end 144.531588 -54.3052)
		(width 0.1143)
		(layer "B.Cu")
		(net "UPI_CPU0_CPU1_P1P1_DP<1>")
	)
	(segment
		(start 287.12414 -50.682144)
		(end 287.1216 -50.68062)
		(width 0.1143)
		(layer "B.Cu")
		(net "UPI_CPU0_CPU1_P1P1_DP<1>")
	)
	(segment
		(start 198.359014 -41.873424)
		(end 196.070474 -42.859198)
		(width 0.1143)
		(layer "B.Cu")
		(net "UPI_CPU0_CPU1_P1P1_DP<1>")
	)
	(segment
		(start 268.464538 -48.434244)
		(end 268.374876 -48.299878)
		(width 0.1143)
		(layer "B.Cu")
		(net "UPI_CPU0_CPU1_P1P1_DP<1>")
	)
	(segment
		(start 285.793434 -50.138584)
		(end 285.317946 -50.28946)
		(width 0.1143)
		(layer "B.Cu")
		(net "UPI_CPU0_CPU1_P1P1_DP<1>")
	)
	(segment
		(start 227.538026 -50.529744)
		(end 222.396812 -49.501552)
		(width 0.1143)
		(layer "B.Cu")
		(net "UPI_CPU0_CPU1_P1P1_DP<1>")
	)
	(segment
		(start 173.307756 -48.035972)
		(end 170.528488 -49.10074)
		(width 0.1143)
		(layer "B.Cu")
		(net "UPI_CPU0_CPU1_P1P1_DP<1>")
	)
	(segment
		(start 289.78098 -54.145688)
		(end 289.78098 -53.166518)
		(width 0.0889)
		(layer "B.Cu")
		(net "UPI_CPU0_CPU1_P1P1_DP<1>")
	)
	(segment
		(start 276.82825 -50.189638)
		(end 275.947378 -50.013362)
		(width 0.1143)
		(layer "B.Cu")
		(net "UPI_CPU0_CPU1_P1P1_DP<1>")
	)
	(segment
		(start 274.706842 -49.680876)
		(end 274.484846 -50.791364)
		(width 0.1143)
		(layer "B.Cu")
		(net "UPI_CPU0_CPU1_P1P1_DP<1>")
	)
	(segment
		(start 277.074884 -50.024284)
		(end 276.82825 -50.189638)
		(width 0.1143)
		(layer "B.Cu")
		(net "UPI_CPU0_CPU1_P1P1_DP<1>")
	)
	(segment
		(start 256.838196 -49.732946)
		(end 255.985518 -50.066702)
		(width 0.1143)
		(layer "B.Cu")
		(net "UPI_CPU0_CPU1_P1P1_DP<1>")
	)
	(segment
		(start 263.034018 -49.979326)
		(end 262.649462 -49.937162)
		(width 0.1143)
		(layer "B.Cu")
		(net "UPI_CPU0_CPU1_P1P1_DP<1>")
	)
	(segment
		(start 255.985518 -50.066702)
		(end 255.013206 -50.057558)
		(width 0.1143)
		(layer "B.Cu")
		(net "UPI_CPU0_CPU1_P1P1_DP<1>")
	)
	(segment
		(start 144.531588 -54.3052)
		(end 144.49552 -54.3052)
		(width 0.0889)
		(layer "B.Cu")
		(net "UPI_CPU0_CPU1_P1P1_DP<1>")
	)
	(segment
		(start 284.48889 -51.070002)
		(end 284.305756 -51.207162)
		(width 0.1143)
		(layer "B.Cu")
		(net "UPI_CPU0_CPU1_P1P1_DP<1>")
	)
	(segment
		(start 170.528488 -49.10074)
		(end 170.528234 -49.10074)
		(width 0.1143)
		(layer "B.Cu")
		(net "UPI_CPU0_CPU1_P1P1_DP<1>")
	)
	(segment
		(start 271.329404 -50.376074)
		(end 270.546068 -50.219356)
		(width 0.1143)
		(layer "B.Cu")
		(net "UPI_CPU0_CPU1_P1P1_DP<1>")
	)
	(segment
		(start 287.1216 -50.68062)
		(end 286.338772 -50.219102)
		(width 0.1143)
		(layer "B.Cu")
		(net "UPI_CPU0_CPU1_P1P1_DP<1>")
	)
	(segment
		(start 264.072116 -49.000156)
		(end 264.05459 -49.160176)
		(width 0.1143)
		(layer "B.Cu")
		(net "UPI_CPU0_CPU1_P1P1_DP<1>")
	)
	(segment
		(start 269.524226 -49.814226)
		(end 269.462758 -50.121058)
		(width 0.1143)
		(layer "B.Cu")
		(net "UPI_CPU0_CPU1_P1P1_DP<1>")
	)
	(segment
		(start 139.409424 -57.485534)
		(end 139.376658 -57.485534)
		(width 0.0889)
		(layer "B.Cu")
		(net "UPI_CPU0_CPU1_P1P1_DP<1>")
	)
	(segment
		(start 138.547094 -57.981088)
		(end 138.514328 -57.981088)
		(width 0.0889)
		(layer "B.Cu")
		(net "UPI_CPU0_CPU1_P1P1_DP<1>")
	)
	(segment
		(start 283.626306 -51.557682)
		(end 281.83713 -51.914806)
		(width 0.1143)
		(layer "B.Cu")
		(net "UPI_CPU0_CPU1_P1P1_DP<1>")
	)
	(segment
		(start 248.204736 -48.93183)
		(end 241.203734 -47.56277)
		(width 0.1143)
		(layer "B.Cu")
		(net "UPI_CPU0_CPU1_P1P1_DP<1>")
	)
	(segment
		(start 288.849562 -52.2351)
		(end 288.719006 -52.2351)
		(width 0.0889)
		(layer "B.Cu")
		(net "UPI_CPU0_CPU1_P1P1_DP<1>")
	)
	(segment
		(start 265.954002 -47.816008)
		(end 265.846306 -47.813468)
		(width 0.1143)
		(layer "B.Cu")
		(net "UPI_CPU0_CPU1_P1P1_DP<1>")
	)
	(segment
		(start 269.883128 -48.601376)
		(end 269.748762 -48.691038)
		(width 0.1143)
		(layer "B.Cu")
		(net "UPI_CPU0_CPU1_P1P1_DP<1>")
	)
	(segment
		(start 262.649462 -49.937162)
		(end 262.099552 -50.378614)
		(width 0.1143)
		(layer "B.Cu")
		(net "UPI_CPU0_CPU1_P1P1_DP<1>")
	)
	(segment
		(start 235.900976 -48.62322)
		(end 227.538026 -50.529744)
		(width 0.1143)
		(layer "B.Cu")
		(net "UPI_CPU0_CPU1_P1P1_DP<1>")
	)
	(segment
		(start 241.203734 -47.56277)
		(end 235.900976 -48.62322)
		(width 0.1143)
		(layer "B.Cu")
		(net "UPI_CPU0_CPU1_P1P1_DP<1>")
	)
	(segment
		(start 285.135066 -50.426366)
		(end 285.109666 -50.60442)
		(width 0.1143)
		(layer "B.Cu")
		(net "UPI_CPU0_CPU1_P1P1_DP<1>")
	)
	(segment
		(start 271.842738 -49.10963)
		(end 271.629632 -50.175668)
		(width 0.1143)
		(layer "B.Cu")
		(net "UPI_CPU0_CPU1_P1P1_DP<1>")
	)
	(segment
		(start 266.2809 -47.881286)
		(end 265.954002 -47.816008)
		(width 0.1143)
		(layer "B.Cu")
		(net "UPI_CPU0_CPU1_P1P1_DP<1>")
	)
	(segment
		(start 250.580906 -48.688244)
		(end 249.458226 -48.803306)
		(width 0.1143)
		(layer "B.Cu")
		(net "UPI_CPU0_CPU1_P1P1_DP<1>")
	)
	(segment
		(start 290.149026 -54.513734)
		(end 289.78098 -54.145688)
		(width 0.0889)
		(layer "B.Cu")
		(net "UPI_CPU0_CPU1_P1P1_DP<1>")
	)
	(segment
		(start 269.162784 -50.321464)
		(end 268.379448 -50.164746)
		(width 0.1143)
		(layer "B.Cu")
		(net "UPI_CPU0_CPU1_P1P1_DP<1>")
	)
	(segment
		(start 261.396988 -50.63109)
		(end 256.838196 -49.732946)
		(width 0.1143)
		(layer "B.Cu")
		(net "UPI_CPU0_CPU1_P1P1_DP<1>")
	)
	(segment
		(start 148.866352 -51.101498)
		(end 148.51507 -51.634898)
		(width 0.1143)
		(layer "B.Cu")
		(net "UPI_CPU0_CPU1_P1P1_DP<1>")
	)
	(segment
		(start 275.947378 -50.013362)
		(end 275.7932 -49.782222)
		(width 0.1143)
		(layer "B.Cu")
		(net "UPI_CPU0_CPU1_P1P1_DP<1>")
	)
	(segment
		(start 273.333972 -49.290478)
		(end 271.977104 -49.019968)
		(width 0.1143)
		(layer "B.Cu")
		(net "UPI_CPU0_CPU1_P1P1_DP<1>")
	)
	(segment
		(start 263.683242 -50.207672)
		(end 263.172956 -50.151792)
		(width 0.1143)
		(layer "B.Cu")
		(net "UPI_CPU0_CPU1_P1P1_DP<1>")
	)
	(segment
		(start 249.346974 -48.939958)
		(end 249.11939 -48.963326)
		(width 0.1143)
		(layer "B.Cu")
		(net "UPI_CPU0_CPU1_P1P1_DP<1>")
	)
	(segment
		(start 138.182604 -58.180986)
		(end 138.11631 -58.295794)
		(width 0.0889)
		(layer "B.Cu")
		(net "UPI_CPU0_CPU1_P1P1_DP<1>")
	)
	(segment
		(start 170.528234 -49.10074)
		(end 170.528234 -49.100994)
		(width 0.1143)
		(layer "B.Cu")
		(net "UPI_CPU0_CPU1_P1P1_DP<1>")
	)
	(segment
		(start 284.305756 -51.207162)
		(end 284.127956 -51.181762)
		(width 0.1143)
		(layer "B.Cu")
		(net "UPI_CPU0_CPU1_P1P1_DP<1>")
	)
	(segment
		(start 277.579328 -50.125122)
		(end 277.074884 -50.024284)
		(width 0.1143)
		(layer "B.Cu")
		(net "UPI_CPU0_CPU1_P1P1_DP<1>")
	)
	(segment
		(start 156.323284 -48.262032)
		(end 151.686514 -49.189386)
		(width 0.1143)
		(layer "B.Cu")
		(net "UPI_CPU0_CPU1_P1P1_DP<1>")
	)
	(segment
		(start 265.846306 -47.813468)
		(end 265.13155 -48.149764)
		(width 0.1143)
		(layer "B.Cu")
		(net "UPI_CPU0_CPU1_P1P1_DP<1>")
	)
	(segment
		(start 249.11939 -48.963326)
		(end 248.982738 -48.852074)
		(width 0.1143)
		(layer "B.Cu")
		(net "UPI_CPU0_CPU1_P1P1_DP<1>")
	)
	(segment
		(start 273.201892 -50.535078)
		(end 273.423634 -49.42459)
		(width 0.1143)
		(layer "B.Cu")
		(net "UPI_CPU0_CPU1_P1P1_DP<1>")
	)
	(segment
		(start 288.380678 -51.938428)
		(end 287.12414 -50.682144)
		(width 0.1143)
		(layer "B.Cu")
		(net "UPI_CPU0_CPU1_P1P1_DP<1>")
	)
	(segment
		(start 264.05459 -49.160176)
		(end 264.193274 -49.332388)
		(width 0.1143)
		(layer "B.Cu")
		(net "UPI_CPU0_CPU1_P1P1_DP<1>")
	)
	(segment
		(start 144.49552 -54.3052)
		(end 143.453866 -55.346854)
		(width 0.0889)
		(layer "B.Cu")
		(net "UPI_CPU0_CPU1_P1P1_DP<1>")
	)
	(segment
		(start 255.013206 -50.057558)
		(end 250.580906 -48.688244)
		(width 0.1143)
		(layer "B.Cu")
		(net "UPI_CPU0_CPU1_P1P1_DP<1>")
	)
	(segment
		(start 270.558514 -48.852836)
		(end 270.468852 -48.71847)
		(width 0.1143)
		(layer "B.Cu")
		(net "UPI_CPU0_CPU1_P1P1_DP<1>")
	)
	(segment
		(start 286.338772 -50.219102)
		(end 285.793434 -50.138584)
		(width 0.1143)
		(layer "B.Cu")
		(net "UPI_CPU0_CPU1_P1P1_DP<1>")
	)
	(segment
		(start 207.111854 -46.444662)
		(end 201.06767 -42.415206)
		(width 0.1143)
		(layer "B.Cu")
		(net "UPI_CPU0_CPU1_P1P1_DP<1>")
	)
	(segment
		(start 284.926532 -50.74158)
		(end 284.748732 -50.71618)
		(width 0.1143)
		(layer "B.Cu")
		(net "UPI_CPU0_CPU1_P1P1_DP<1>")
	)
	(segment
		(start 277.940516 -50.666904)
		(end 277.579328 -50.125122)
		(width 0.1143)
		(layer "B.Cu")
		(net "UPI_CPU0_CPU1_P1P1_DP<1>")
	)
	(segment
		(start 266.05484 -49.596802)
		(end 266.370562 -48.015652)
		(width 0.1143)
		(layer "B.Cu")
		(net "UPI_CPU0_CPU1_P1P1_DP<1>")
	)
	(segment
		(start 167.126158 -50.404014)
		(end 156.323284 -48.262032)
		(width 0.1143)
		(layer "B.Cu")
		(net "UPI_CPU0_CPU1_P1P1_DP<1>")
	)
	(segment
		(start 288.422334 -51.938428)
		(end 288.380678 -51.938428)
		(width 0.0889)
		(layer "B.Cu")
		(net "UPI_CPU0_CPU1_P1P1_DP<1>")
	)
	(segment
		(start 264.137394 -49.842928)
		(end 263.683242 -50.207672)
		(width 0.1143)
		(layer "B.Cu")
		(net "UPI_CPU0_CPU1_P1P1_DP<1>")
	)
	(segment
		(start 281.212036 -51.790092)
		(end 279.480264 -50.63617)
		(width 0.1143)
		(layer "B.Cu")
		(net "UPI_CPU0_CPU1_P1P1_DP<1>")
	)
	(segment
		(start 263.172956 -50.151792)
		(end 263.034018 -49.979326)
		(width 0.1143)
		(layer "B.Cu")
		(net "UPI_CPU0_CPU1_P1P1_DP<1>")
	)
	(segment
		(start 142.166086 -55.999888)
		(end 141.948408 -55.999888)
		(width 0.0889)
		(layer "B.Cu")
		(net "UPI_CPU0_CPU1_P1P1_DP<1>")
	)
	(arc
		(start 140.231368 -56.990488)
		(mid 140.039726 -57.047654)
		(end 139.899644 -57.190386)
		(width 0.0889)
		(layer "B.Cu")
		(net "UPI_CPU0_CPU1_P1P1_DP<1>")
	)
	(arc
		(start 138.11631 -58.295794)
		(mid 137.91257 -58.600708)
		(end 137.670794 -58.876438)
		(width 0.0889)
		(layer "B.Cu")
		(net "UPI_CPU0_CPU1_P1P1_DP<1>")
	)
	(arc
		(start 139.376658 -57.485534)
		(mid 139.182808 -57.541884)
		(end 139.041124 -57.685686)
		(width 0.0889)
		(layer "B.Cu")
		(net "UPI_CPU0_CPU1_P1P1_DP<1>")
	)
	(arc
		(start 140.758164 -56.695086)
		(mid 140.549556 -56.907018)
		(end 140.264134 -56.990488)
		(width 0.0889)
		(layer "B.Cu")
		(net "UPI_CPU0_CPU1_P1P1_DP<1>")
	)
	(arc
		(start 141.948408 -55.999888)
		(mid 141.756766 -56.057054)
		(end 141.616684 -56.199786)
		(width 0.0889)
		(layer "B.Cu")
		(net "UPI_CPU0_CPU1_P1P1_DP<1>")
	)
	(arc
		(start 142.515082 -55.701692)
		(mid 142.368982 -55.884026)
		(end 142.166086 -55.999888)
		(width 0.0889)
		(layer "B.Cu")
		(net "UPI_CPU0_CPU1_P1P1_DP<1>")
	)
	(arc
		(start 291.51072 -54.418738)
		(mid 291.405488 -54.489052)
		(end 291.281358 -54.513734)
		(width 0.0889)
		(layer "B.Cu")
		(net "UPI_CPU0_CPU1_P1P1_DP<1>")
	)
	(arc
		(start 139.899644 -57.190386)
		(mid 139.69264 -57.40125)
		(end 139.409424 -57.485534)
		(width 0.0889)
		(layer "B.Cu")
		(net "UPI_CPU0_CPU1_P1P1_DP<1>")
	)
	(arc
		(start 141.616684 -56.199786)
		(mid 141.40968 -56.41065)
		(end 141.126464 -56.494934)
		(width 0.0889)
		(layer "B.Cu")
		(net "UPI_CPU0_CPU1_P1P1_DP<1>")
	)
	(arc
		(start 139.041124 -57.685686)
		(mid 138.832516 -57.897618)
		(end 138.547094 -57.981088)
		(width 0.0889)
		(layer "B.Cu")
		(net "UPI_CPU0_CPU1_P1P1_DP<1>")
	)
	(arc
		(start 138.514328 -57.981088)
		(mid 138.322686 -58.038254)
		(end 138.182604 -58.180986)
		(width 0.0889)
		(layer "B.Cu")
		(net "UPI_CPU0_CPU1_P1P1_DP<1>")
	)
	(arc
		(start 141.093698 -56.494934)
		(mid 140.899848 -56.551284)
		(end 140.758164 -56.695086)
		(width 0.0889)
		(layer "B.Cu")
		(net "UPI_CPU0_CPU1_P1P1_DP<1>")
	)
	(segment
		(start 305.533806 -57.885584)
		(end 306.105306 -57.885584)
		(width 0.1143)
		(layer "F.Cu")
		(net "UPI_CPU0_CPU1_P1P1_DP<19>")
	)
	(segment
		(start 126.797308 -61.847984)
		(end 127.368808 -61.847984)
		(width 0.1143)
		(layer "F.Cu")
		(net "UPI_CPU0_CPU1_P1P1_DP<19>")
	)
	(via
		(at 127.368808 -61.847984)
		(size 0.508)
		(drill 0.254)
		(layers "F.Cu" "B.Cu")
		(net "UPI_CPU0_CPU1_P1P1_DP<19>")
	)
	(via
		(at 306.105306 -57.885584)
		(size 0.508)
		(drill 0.254)
		(layers "F.Cu" "B.Cu")
		(net "UPI_CPU0_CPU1_P1P1_DP<19>")
	)
	(segment
		(start 180.126132 -23.512526)
		(end 181.410102 -23.476458)
		(width 0.1143)
		(layer "B.Cu")
		(net "UPI_CPU0_CPU1_P1P1_DP<19>")
	)
	(segment
		(start 307.51272 -37.62756)
		(end 307.6956 -38.542214)
		(width 0.1143)
		(layer "B.Cu")
		(net "UPI_CPU0_CPU1_P1P1_DP<19>")
	)
	(segment
		(start 212.36813 -28.888182)
		(end 222.396812 -30.97149)
		(width 0.1143)
		(layer "B.Cu")
		(net "UPI_CPU0_CPU1_P1P1_DP<19>")
	)
	(segment
		(start 209.296 -28.83789)
		(end 209.634582 -28.972764)
		(width 0.1143)
		(layer "B.Cu")
		(net "UPI_CPU0_CPU1_P1P1_DP<19>")
	)
	(segment
		(start 186.690508 -24.926798)
		(end 189.72784 -25.077928)
		(width 0.1143)
		(layer "B.Cu")
		(net "UPI_CPU0_CPU1_P1P1_DP<19>")
	)
	(segment
		(start 209.011774 -28.72486)
		(end 209.296 -28.83789)
		(width 0.1143)
		(layer "B.Cu")
		(net "UPI_CPU0_CPU1_P1P1_DP<19>")
	)
	(segment
		(start 307.6956 -56.103012)
		(end 307.509418 -56.22036)
		(width 0.1143)
		(layer "B.Cu")
		(net "UPI_CPU0_CPU1_P1P1_DP<19>")
	)
	(segment
		(start 166.458138 -24.491696)
		(end 170.64355 -25.305766)
		(width 0.1143)
		(layer "B.Cu")
		(net "UPI_CPU0_CPU1_P1P1_DP<19>")
	)
	(segment
		(start 254.34163 -26.782522)
		(end 280.226516 -31.95955)
		(width 0.1143)
		(layer "B.Cu")
		(net "UPI_CPU0_CPU1_P1P1_DP<19>")
	)
	(segment
		(start 309.348124 -51.898296)
		(end 308.657244 -55.354982)
		(width 0.1143)
		(layer "B.Cu")
		(net "UPI_CPU0_CPU1_P1P1_DP<19>")
	)
	(segment
		(start 119.908574 -39.815516)
		(end 121.882662 -36.88969)
		(width 0.1143)
		(layer "B.Cu")
		(net "UPI_CPU0_CPU1_P1P1_DP<19>")
	)
	(segment
		(start 121.426224 -55.713122)
		(end 121.421398 -55.704486)
		(width 0.0889)
		(layer "B.Cu")
		(net "UPI_CPU0_CPU1_P1P1_DP<19>")
	)
	(segment
		(start 121.421398 -56.695086)
		(end 121.415048 -56.684418)
		(width 0.0889)
		(layer "B.Cu")
		(net "UPI_CPU0_CPU1_P1P1_DP<19>")
	)
	(segment
		(start 125.662944 -61.447934)
		(end 124.77496 -61.447934)
		(width 0.0889)
		(layer "B.Cu")
		(net "UPI_CPU0_CPU1_P1P1_DP<19>")
	)
	(segment
		(start 176.5046 -24.0284)
		(end 179.69611 -23.593806)
		(width 0.1143)
		(layer "B.Cu")
		(net "UPI_CPU0_CPU1_P1P1_DP<19>")
	)
	(segment
		(start 280.226516 -31.95955)
		(end 292.237668 -29.55798)
		(width 0.1143)
		(layer "B.Cu")
		(net "UPI_CPU0_CPU1_P1P1_DP<19>")
	)
	(segment
		(start 307.509418 -56.22036)
		(end 307.224176 -56.505602)
		(width 0.1143)
		(layer "B.Cu")
		(net "UPI_CPU0_CPU1_P1P1_DP<19>")
	)
	(segment
		(start 118.9609 -50.798476)
		(end 118.9355 -50.750978)
		(width 0.0889)
		(layer "B.Cu")
		(net "UPI_CPU0_CPU1_P1P1_DP<19>")
	)
	(segment
		(start 306.772564 -56.921146)
		(end 306.617116 -57.190386)
		(width 0.0889)
		(layer "B.Cu")
		(net "UPI_CPU0_CPU1_P1P1_DP<19>")
	)
	(segment
		(start 211.781644 -28.78709)
		(end 212.36813 -28.888182)
		(width 0.1143)
		(layer "B.Cu")
		(net "UPI_CPU0_CPU1_P1P1_DP<19>")
	)
	(segment
		(start 306.437284 -57.383934)
		(end 306.105306 -57.885584)
		(width 0.0889)
		(layer "B.Cu")
		(net "UPI_CPU0_CPU1_P1P1_DP<19>")
	)
	(segment
		(start 118.9355 -50.750978)
		(end 118.9355 -44.823888)
		(width 0.1143)
		(layer "B.Cu")
		(net "UPI_CPU0_CPU1_P1P1_DP<19>")
	)
	(segment
		(start 249.586496 -27.640026)
		(end 254.34163 -26.782522)
		(width 0.1143)
		(layer "B.Cu")
		(net "UPI_CPU0_CPU1_P1P1_DP<19>")
	)
	(segment
		(start 292.237668 -29.55798)
		(end 298.773342 -30.864556)
		(width 0.1143)
		(layer "B.Cu")
		(net "UPI_CPU0_CPU1_P1P1_DP<19>")
	)
	(segment
		(start 222.396812 -30.97149)
		(end 225.545142 -31.62554)
		(width 0.1143)
		(layer "B.Cu")
		(net "UPI_CPU0_CPU1_P1P1_DP<19>")
	)
	(segment
		(start 189.72784 -25.077928)
		(end 191.559434 -26.81478)
		(width 0.1143)
		(layer "B.Cu")
		(net "UPI_CPU0_CPU1_P1P1_DP<19>")
	)
	(segment
		(start 308.657244 -55.354982)
		(end 308.28869 -55.729632)
		(width 0.1143)
		(layer "B.Cu")
		(net "UPI_CPU0_CPU1_P1P1_DP<19>")
	)
	(segment
		(start 145.762472 -28.615386)
		(end 163.230306 -25.053798)
		(width 0.1143)
		(layer "B.Cu")
		(net "UPI_CPU0_CPU1_P1P1_DP<19>")
	)
	(segment
		(start 121.421398 -57.685686)
		(end 121.415048 -57.675018)
		(width 0.0889)
		(layer "B.Cu")
		(net "UPI_CPU0_CPU1_P1P1_DP<19>")
	)
	(segment
		(start 298.773342 -30.864556)
		(end 307.51272 -37.62756)
		(width 0.1143)
		(layer "B.Cu")
		(net "UPI_CPU0_CPU1_P1P1_DP<19>")
	)
	(segment
		(start 307.6956 -38.542214)
		(end 309.574184 -47.936658)
		(width 0.1143)
		(layer "B.Cu")
		(net "UPI_CPU0_CPU1_P1P1_DP<19>")
	)
	(segment
		(start 143.347694 -29.796994)
		(end 145.762472 -28.615386)
		(width 0.1143)
		(layer "B.Cu")
		(net "UPI_CPU0_CPU1_P1P1_DP<19>")
	)
	(segment
		(start 124.279914 -60.952888)
		(end 123.632468 -60.952888)
		(width 0.0889)
		(layer "B.Cu")
		(net "UPI_CPU0_CPU1_P1P1_DP<19>")
	)
	(segment
		(start 118.9609 -51.04003)
		(end 118.9609 -50.798476)
		(width 0.0889)
		(layer "B.Cu")
		(net "UPI_CPU0_CPU1_P1P1_DP<19>")
	)
	(segment
		(start 308.28869 -55.729632)
		(end 307.6956 -56.103012)
		(width 0.1143)
		(layer "B.Cu")
		(net "UPI_CPU0_CPU1_P1P1_DP<19>")
	)
	(segment
		(start 127.368808 -61.847984)
		(end 127.161544 -61.847984)
		(width 0.0889)
		(layer "B.Cu")
		(net "UPI_CPU0_CPU1_P1P1_DP<19>")
	)
	(segment
		(start 179.69611 -23.593806)
		(end 180.126132 -23.512526)
		(width 0.1143)
		(layer "B.Cu")
		(net "UPI_CPU0_CPU1_P1P1_DP<19>")
	)
	(segment
		(start 208.323688 -28.475178)
		(end 209.011774 -28.72486)
		(width 0.1143)
		(layer "B.Cu")
		(net "UPI_CPU0_CPU1_P1P1_DP<19>")
	)
	(segment
		(start 121.882662 -36.88969)
		(end 127.962914 -32.78759)
		(width 0.1143)
		(layer "B.Cu")
		(net "UPI_CPU0_CPU1_P1P1_DP<19>")
	)
	(segment
		(start 118.9355 -44.823888)
		(end 119.908574 -39.815516)
		(width 0.1143)
		(layer "B.Cu")
		(net "UPI_CPU0_CPU1_P1P1_DP<19>")
	)
	(segment
		(start 126.7841 -61.943488)
		(end 126.496572 -61.943488)
		(width 0.0889)
		(layer "B.Cu")
		(net "UPI_CPU0_CPU1_P1P1_DP<19>")
	)
	(segment
		(start 163.230306 -25.053798)
		(end 166.458138 -24.491696)
		(width 0.1143)
		(layer "B.Cu")
		(net "UPI_CPU0_CPU1_P1P1_DP<19>")
	)
	(segment
		(start 307.224176 -56.505602)
		(end 307.172614 -56.521096)
		(width 0.0889)
		(layer "B.Cu")
		(net "UPI_CPU0_CPU1_P1P1_DP<19>")
	)
	(segment
		(start 307.172614 -56.521096)
		(end 306.772564 -56.921146)
		(width 0.0889)
		(layer "B.Cu")
		(net "UPI_CPU0_CPU1_P1P1_DP<19>")
	)
	(segment
		(start 225.545142 -31.62554)
		(end 236.883956 -29.358336)
		(width 0.1143)
		(layer "B.Cu")
		(net "UPI_CPU0_CPU1_P1P1_DP<19>")
	)
	(segment
		(start 209.634582 -28.972764)
		(end 211.781644 -28.78709)
		(width 0.1143)
		(layer "B.Cu")
		(net "UPI_CPU0_CPU1_P1P1_DP<19>")
	)
	(segment
		(start 191.559434 -26.81478)
		(end 194.050412 -26.865072)
		(width 0.1143)
		(layer "B.Cu")
		(net "UPI_CPU0_CPU1_P1P1_DP<19>")
	)
	(segment
		(start 243.64315 -28.828746)
		(end 249.586496 -27.640026)
		(width 0.1143)
		(layer "B.Cu")
		(net "UPI_CPU0_CPU1_P1P1_DP<19>")
	)
	(segment
		(start 121.415048 -59.087004)
		(end 121.421398 -59.076336)
		(width 0.0889)
		(layer "B.Cu")
		(net "UPI_CPU0_CPU1_P1P1_DP<19>")
	)
	(segment
		(start 122.802904 -60.457334)
		(end 122.770138 -60.457334)
		(width 0.0889)
		(layer "B.Cu")
		(net "UPI_CPU0_CPU1_P1P1_DP<19>")
	)
	(segment
		(start 120.560084 -54.213506)
		(end 118.9609 -51.04003)
		(width 0.0889)
		(layer "B.Cu")
		(net "UPI_CPU0_CPU1_P1P1_DP<19>")
	)
	(segment
		(start 121.426224 -56.703722)
		(end 121.421398 -56.695086)
		(width 0.0889)
		(layer "B.Cu")
		(net "UPI_CPU0_CPU1_P1P1_DP<19>")
	)
	(segment
		(start 124.77496 -61.447934)
		(end 124.279914 -60.952888)
		(width 0.0889)
		(layer "B.Cu")
		(net "UPI_CPU0_CPU1_P1P1_DP<19>")
	)
	(segment
		(start 194.050666 -26.865072)
		(end 196.542152 -26.915364)
		(width 0.1143)
		(layer "B.Cu")
		(net "UPI_CPU0_CPU1_P1P1_DP<19>")
	)
	(segment
		(start 194.050412 -26.865072)
		(end 194.050666 -26.865072)
		(width 0.1143)
		(layer "B.Cu")
		(net "UPI_CPU0_CPU1_P1P1_DP<19>")
	)
	(segment
		(start 181.410102 -23.476458)
		(end 186.690508 -24.926798)
		(width 0.1143)
		(layer "B.Cu")
		(net "UPI_CPU0_CPU1_P1P1_DP<19>")
	)
	(segment
		(start 309.574184 -47.936658)
		(end 309.348124 -51.898296)
		(width 0.1143)
		(layer "B.Cu")
		(net "UPI_CPU0_CPU1_P1P1_DP<19>")
	)
	(segment
		(start 121.426224 -57.694322)
		(end 121.421398 -57.685686)
		(width 0.0889)
		(layer "B.Cu")
		(net "UPI_CPU0_CPU1_P1P1_DP<19>")
	)
	(segment
		(start 174.264574 -24.620982)
		(end 176.5046 -24.0284)
		(width 0.1143)
		(layer "B.Cu")
		(net "UPI_CPU0_CPU1_P1P1_DP<19>")
	)
	(segment
		(start 121.948194 -59.962288)
		(end 121.920254 -59.962288)
		(width 0.0889)
		(layer "B.Cu")
		(net "UPI_CPU0_CPU1_P1P1_DP<19>")
	)
	(segment
		(start 196.542152 -26.915364)
		(end 197.174358 -26.985214)
		(width 0.1143)
		(layer "B.Cu")
		(net "UPI_CPU0_CPU1_P1P1_DP<19>")
	)
	(segment
		(start 238.93907 -29.769562)
		(end 243.64315 -28.828746)
		(width 0.1143)
		(layer "B.Cu")
		(net "UPI_CPU0_CPU1_P1P1_DP<19>")
	)
	(segment
		(start 236.883956 -29.358336)
		(end 238.93907 -29.769562)
		(width 0.1143)
		(layer "B.Cu")
		(net "UPI_CPU0_CPU1_P1P1_DP<19>")
	)
	(segment
		(start 127.962914 -32.78759)
		(end 143.347694 -29.796994)
		(width 0.1143)
		(layer "B.Cu")
		(net "UPI_CPU0_CPU1_P1P1_DP<19>")
	)
	(segment
		(start 121.421398 -55.704486)
		(end 121.415048 -55.693818)
		(width 0.0889)
		(layer "B.Cu")
		(net "UPI_CPU0_CPU1_P1P1_DP<19>")
	)
	(segment
		(start 121.089166 -54.513734)
		(end 121.053352 -54.513734)
		(width 0.0889)
		(layer "B.Cu")
		(net "UPI_CPU0_CPU1_P1P1_DP<19>")
	)
	(segment
		(start 197.174358 -26.985214)
		(end 208.323688 -28.475178)
		(width 0.1143)
		(layer "B.Cu")
		(net "UPI_CPU0_CPU1_P1P1_DP<19>")
	)
	(segment
		(start 170.64355 -25.305766)
		(end 174.264574 -24.620982)
		(width 0.1143)
		(layer "B.Cu")
		(net "UPI_CPU0_CPU1_P1P1_DP<19>")
	)
	(arc
		(start 122.279918 -60.162186)
		(mid 122.139839 -60.01945)
		(end 121.948194 -59.962288)
		(width 0.0889)
		(layer "B.Cu")
		(net "UPI_CPU0_CPU1_P1P1_DP<19>")
	)
	(arc
		(start 121.421398 -56.104536)
		(mid 121.474868 -55.909473)
		(end 121.426224 -55.713122)
		(width 0.0889)
		(layer "B.Cu")
		(net "UPI_CPU0_CPU1_P1P1_DP<19>")
	)
	(arc
		(start 121.421398 -59.076336)
		(mid 121.474897 -58.876438)
		(end 121.421398 -58.67654)
		(width 0.0889)
		(layer "B.Cu")
		(net "UPI_CPU0_CPU1_P1P1_DP<19>")
	)
	(arc
		(start 121.415048 -55.693818)
		(mid 121.34225 -55.403055)
		(end 121.421398 -55.113936)
		(width 0.0889)
		(layer "B.Cu")
		(net "UPI_CPU0_CPU1_P1P1_DP<19>")
	)
	(arc
		(start 121.421398 -58.67654)
		(mid 121.342267 -58.381138)
		(end 121.421398 -58.085736)
		(width 0.0889)
		(layer "B.Cu")
		(net "UPI_CPU0_CPU1_P1P1_DP<19>")
	)
	(arc
		(start 121.421398 -57.095136)
		(mid 121.474868 -56.900073)
		(end 121.426224 -56.703722)
		(width 0.0889)
		(layer "B.Cu")
		(net "UPI_CPU0_CPU1_P1P1_DP<19>")
	)
	(arc
		(start 121.415048 -56.684418)
		(mid 121.34225 -56.393655)
		(end 121.421398 -56.104536)
		(width 0.0889)
		(layer "B.Cu")
		(net "UPI_CPU0_CPU1_P1P1_DP<19>")
	)
	(arc
		(start 123.138438 -60.657486)
		(mid 122.996755 -60.513682)
		(end 122.802904 -60.457334)
		(width 0.0889)
		(layer "B.Cu")
		(net "UPI_CPU0_CPU1_P1P1_DP<19>")
	)
	(arc
		(start 121.415048 -57.675018)
		(mid 121.34225 -57.384255)
		(end 121.421398 -57.095136)
		(width 0.0889)
		(layer "B.Cu")
		(net "UPI_CPU0_CPU1_P1P1_DP<19>")
	)
	(arc
		(start 126.496572 -61.943488)
		(mid 126.208885 -61.860967)
		(end 125.998478 -61.648086)
		(width 0.0889)
		(layer "B.Cu")
		(net "UPI_CPU0_CPU1_P1P1_DP<19>")
	)
	(arc
		(start 306.617116 -57.190386)
		(mid 306.538135 -57.297316)
		(end 306.437284 -57.383934)
		(width 0.0889)
		(layer "B.Cu")
		(net "UPI_CPU0_CPU1_P1P1_DP<19>")
	)
	(arc
		(start 123.632468 -60.952888)
		(mid 123.347044 -60.869421)
		(end 123.138438 -60.657486)
		(width 0.0889)
		(layer "B.Cu")
		(net "UPI_CPU0_CPU1_P1P1_DP<19>")
	)
	(arc
		(start 121.053352 -54.513734)
		(mid 120.767514 -54.42801)
		(end 120.560084 -54.213506)
		(width 0.0889)
		(layer "B.Cu")
		(net "UPI_CPU0_CPU1_P1P1_DP<19>")
	)
	(arc
		(start 121.920254 -59.962288)
		(mid 121.421373 -59.666851)
		(end 121.415048 -59.087004)
		(width 0.0889)
		(layer "B.Cu")
		(net "UPI_CPU0_CPU1_P1P1_DP<19>")
	)
	(arc
		(start 125.998478 -61.648086)
		(mid 125.856795 -61.504282)
		(end 125.662944 -61.447934)
		(width 0.0889)
		(layer "B.Cu")
		(net "UPI_CPU0_CPU1_P1P1_DP<19>")
	)
	(arc
		(start 121.421398 -58.085736)
		(mid 121.474868 -57.890673)
		(end 121.426224 -57.694322)
		(width 0.0889)
		(layer "B.Cu")
		(net "UPI_CPU0_CPU1_P1P1_DP<19>")
	)
	(arc
		(start 127.161544 -61.847984)
		(mid 127.06067 -61.860564)
		(end 126.965964 -61.897514)
		(width 0.0889)
		(layer "B.Cu")
		(net "UPI_CPU0_CPU1_P1P1_DP<19>")
	)
	(arc
		(start 121.421398 -55.113936)
		(mid 121.424948 -54.719911)
		(end 121.089166 -54.513734)
		(width 0.0889)
		(layer "B.Cu")
		(net "UPI_CPU0_CPU1_P1P1_DP<19>")
	)
	(arc
		(start 122.770138 -60.457334)
		(mid 122.486921 -60.373053)
		(end 122.279918 -60.162186)
		(width 0.0889)
		(layer "B.Cu")
		(net "UPI_CPU0_CPU1_P1P1_DP<19>")
	)
	(arc
		(start 126.965964 -61.897514)
		(mid 126.877903 -61.93185)
		(end 126.7841 -61.943488)
		(width 0.0889)
		(layer "B.Cu")
		(net "UPI_CPU0_CPU1_P1P1_DP<19>")
	)
	(segment
		(start 305.533806 -55.904384)
		(end 306.105306 -55.904384)
		(width 0.1143)
		(layer "F.Cu")
		(net "UPI_CPU0_CPU1_P1P1_DP<18>")
	)
	(segment
		(start 125.080268 -60.857384)
		(end 125.651768 -60.857384)
		(width 0.1143)
		(layer "F.Cu")
		(net "UPI_CPU0_CPU1_P1P1_DP<18>")
	)
	(via
		(at 125.651768 -60.857384)
		(size 0.508)
		(drill 0.254)
		(layers "F.Cu" "B.Cu")
		(net "UPI_CPU0_CPU1_P1P1_DP<18>")
	)
	(via
		(at 306.105306 -55.904384)
		(size 0.508)
		(drill 0.254)
		(layers "F.Cu" "B.Cu")
		(net "UPI_CPU0_CPU1_P1P1_DP<18>")
	)
	(segment
		(start 170.954954 -26.592784)
		(end 176.61255 -25.057354)
		(width 0.1143)
		(layer "B.Cu")
		(net "UPI_CPU0_CPU1_P1P1_DP<18>")
	)
	(segment
		(start 306.01412 -55.262526)
		(end 306.01285 -55.264304)
		(width 0.0889)
		(layer "B.Cu")
		(net "UPI_CPU0_CPU1_P1P1_DP<18>")
	)
	(segment
		(start 306.236116 -54.823614)
		(end 306.01412 -55.262526)
		(width 0.0889)
		(layer "B.Cu")
		(net "UPI_CPU0_CPU1_P1P1_DP<18>")
	)
	(segment
		(start 122.279918 -55.609236)
		(end 122.284744 -55.6006)
		(width 0.0889)
		(layer "B.Cu")
		(net "UPI_CPU0_CPU1_P1P1_DP<18>")
	)
	(segment
		(start 250.752864 -28.410916)
		(end 252.657864 -28.330144)
		(width 0.1143)
		(layer "B.Cu")
		(net "UPI_CPU0_CPU1_P1P1_DP<18>")
	)
	(segment
		(start 308.395116 -48.627284)
		(end 308.374796 -49.15154)
		(width 0.1143)
		(layer "B.Cu")
		(net "UPI_CPU0_CPU1_P1P1_DP<18>")
	)
	(segment
		(start 125.944884 -60.688474)
		(end 125.965966 -60.609734)
		(width 0.0889)
		(layer "B.Cu")
		(net "UPI_CPU0_CPU1_P1P1_DP<18>")
	)
	(segment
		(start 121.319036 -39.749476)
		(end 122.621294 -37.818568)
		(width 0.1143)
		(layer "B.Cu")
		(net "UPI_CPU0_CPU1_P1P1_DP<18>")
	)
	(segment
		(start 209.296 -29.796486)
		(end 209.631788 -29.919676)
		(width 0.1143)
		(layer "B.Cu")
		(net "UPI_CPU0_CPU1_P1P1_DP<18>")
	)
	(segment
		(start 306.597558 -54.307232)
		(end 306.477416 -54.346602)
		(width 0.0889)
		(layer "B.Cu")
		(net "UPI_CPU0_CPU1_P1P1_DP<18>")
	)
	(segment
		(start 120.08866 -50.29708)
		(end 120.08866 -50.274982)
		(width 0.0889)
		(layer "B.Cu")
		(net "UPI_CPU0_CPU1_P1P1_DP<18>")
	)
	(segment
		(start 289.037014 -31.2039)
		(end 291.96538 -30.550104)
		(width 0.1143)
		(layer "B.Cu")
		(net "UPI_CPU0_CPU1_P1P1_DP<18>")
	)
	(segment
		(start 306.638198 -54.02834)
		(end 306.678076 -54.148228)
		(width 0.0889)
		(layer "B.Cu")
		(net "UPI_CPU0_CPU1_P1P1_DP<18>")
	)
	(segment
		(start 225.256344 -32.635698)
		(end 225.393504 -32.672528)
		(width 0.1143)
		(layer "B.Cu")
		(net "UPI_CPU0_CPU1_P1P1_DP<18>")
	)
	(segment
		(start 120.11406 -50.78857)
		(end 120.11406 -50.32248)
		(width 0.0889)
		(layer "B.Cu")
		(net "UPI_CPU0_CPU1_P1P1_DP<18>")
	)
	(segment
		(start 127.725678 -34.375598)
		(end 127.725932 -34.375598)
		(width 0.1143)
		(layer "B.Cu")
		(net "UPI_CPU0_CPU1_P1P1_DP<18>")
	)
	(segment
		(start 306.396898 -54.505352)
		(end 306.436776 -54.62524)
		(width 0.0889)
		(layer "B.Cu")
		(net "UPI_CPU0_CPU1_P1P1_DP<18>")
	)
	(segment
		(start 236.876082 -30.376114)
		(end 238.901732 -30.781244)
		(width 0.1143)
		(layer "B.Cu")
		(net "UPI_CPU0_CPU1_P1P1_DP<18>")
	)
	(segment
		(start 124.690124 -60.457334)
		(end 124.194824 -59.962034)
		(width 0.0889)
		(layer "B.Cu")
		(net "UPI_CPU0_CPU1_P1P1_DP<18>")
	)
	(segment
		(start 298.422314 -31.986474)
		(end 306.520596 -38.479476)
		(width 0.1143)
		(layer "B.Cu")
		(net "UPI_CPU0_CPU1_P1P1_DP<18>")
	)
	(segment
		(start 238.901732 -30.781244)
		(end 248.663714 -28.828746)
		(width 0.1143)
		(layer "B.Cu")
		(net "UPI_CPU0_CPU1_P1P1_DP<18>")
	)
	(segment
		(start 308.374796 -49.15154)
		(end 307.6956 -51.707034)
		(width 0.1143)
		(layer "B.Cu")
		(net "UPI_CPU0_CPU1_P1P1_DP<18>")
	)
	(segment
		(start 125.651768 -60.857384)
		(end 125.944884 -60.688474)
		(width 0.0889)
		(layer "B.Cu")
		(net "UPI_CPU0_CPU1_P1P1_DP<18>")
	)
	(segment
		(start 181.427882 -24.501602)
		(end 186.579764 -25.951434)
		(width 0.1143)
		(layer "B.Cu")
		(net "UPI_CPU0_CPU1_P1P1_DP<18>")
	)
	(segment
		(start 306.436776 -54.62524)
		(end 306.356258 -54.784244)
		(width 0.0889)
		(layer "B.Cu")
		(net "UPI_CPU0_CPU1_P1P1_DP<18>")
	)
	(segment
		(start 123.637548 -59.962034)
		(end 123.637294 -59.962288)
		(width 0.0889)
		(layer "B.Cu")
		(net "UPI_CPU0_CPU1_P1P1_DP<18>")
	)
	(segment
		(start 186.579764 -25.951434)
		(end 191.163702 -27.732736)
		(width 0.1143)
		(layer "B.Cu")
		(net "UPI_CPU0_CPU1_P1P1_DP<18>")
	)
	(segment
		(start 306.012596 -55.264558)
		(end 305.75377 -55.713122)
		(width 0.0889)
		(layer "B.Cu")
		(net "UPI_CPU0_CPU1_P1P1_DP<18>")
	)
	(segment
		(start 307.170074 -52.991258)
		(end 307.161184 -53.011578)
		(width 0.0889)
		(layer "B.Cu")
		(net "UPI_CPU0_CPU1_P1P1_DP<18>")
	)
	(segment
		(start 122.279918 -58.581036)
		(end 122.284744 -58.5724)
		(width 0.0889)
		(layer "B.Cu")
		(net "UPI_CPU0_CPU1_P1P1_DP<18>")
	)
	(segment
		(start 291.96538 -30.550104)
		(end 298.422314 -31.986474)
		(width 0.1143)
		(layer "B.Cu")
		(net "UPI_CPU0_CPU1_P1P1_DP<18>")
	)
	(segment
		(start 208.547208 -29.522166)
		(end 209.296 -29.796486)
		(width 0.1143)
		(layer "B.Cu")
		(net "UPI_CPU0_CPU1_P1P1_DP<18>")
	)
	(segment
		(start 156.271214 -28.43784)
		(end 157.628082 -27.690826)
		(width 0.1143)
		(layer "B.Cu")
		(net "UPI_CPU0_CPU1_P1P1_DP<18>")
	)
	(segment
		(start 120.08866 -50.274982)
		(end 120.08866 -46.07941)
		(width 0.1143)
		(layer "B.Cu")
		(net "UPI_CPU0_CPU1_P1P1_DP<18>")
	)
	(segment
		(start 252.657864 -28.330144)
		(end 254.525018 -27.82697)
		(width 0.1143)
		(layer "B.Cu")
		(net "UPI_CPU0_CPU1_P1P1_DP<18>")
	)
	(segment
		(start 307.161184 -53.011578)
		(end 307.12791 -53.024532)
		(width 0.0889)
		(layer "B.Cu")
		(net "UPI_CPU0_CPU1_P1P1_DP<18>")
	)
	(segment
		(start 307.63972 -51.917346)
		(end 307.170074 -52.991258)
		(width 0.1143)
		(layer "B.Cu")
		(net "UPI_CPU0_CPU1_P1P1_DP<18>")
	)
	(segment
		(start 122.273568 -57.601104)
		(end 122.279918 -57.590436)
		(width 0.0889)
		(layer "B.Cu")
		(net "UPI_CPU0_CPU1_P1P1_DP<18>")
	)
	(segment
		(start 120.08866 -46.07941)
		(end 121.319036 -39.749476)
		(width 0.1143)
		(layer "B.Cu")
		(net "UPI_CPU0_CPU1_P1P1_DP<18>")
	)
	(segment
		(start 222.396812 -32.034734)
		(end 225.256344 -32.635698)
		(width 0.1143)
		(layer "B.Cu")
		(net "UPI_CPU0_CPU1_P1P1_DP<18>")
	)
	(segment
		(start 307.12791 -53.024532)
		(end 307.01615 -53.280818)
		(width 0.0889)
		(layer "B.Cu")
		(net "UPI_CPU0_CPU1_P1P1_DP<18>")
	)
	(segment
		(start 120.11406 -50.32248)
		(end 120.08866 -50.29708)
		(width 0.0889)
		(layer "B.Cu")
		(net "UPI_CPU0_CPU1_P1P1_DP<18>")
	)
	(segment
		(start 307.01615 -53.280818)
		(end 306.638198 -54.02834)
		(width 0.0889)
		(layer "B.Cu")
		(net "UPI_CPU0_CPU1_P1P1_DP<18>")
	)
	(segment
		(start 209.631788 -29.919676)
		(end 211.901786 -29.829506)
		(width 0.1143)
		(layer "B.Cu")
		(net "UPI_CPU0_CPU1_P1P1_DP<18>")
	)
	(segment
		(start 120.178322 -50.987198)
		(end 120.11406 -50.78857)
		(width 0.0889)
		(layer "B.Cu")
		(net "UPI_CPU0_CPU1_P1P1_DP<18>")
	)
	(segment
		(start 122.278648 -54.620922)
		(end 122.28576 -54.608984)
		(width 0.0889)
		(layer "B.Cu")
		(net "UPI_CPU0_CPU1_P1P1_DP<18>")
	)
	(segment
		(start 122.809762 -59.466988)
		(end 122.773948 -59.466988)
		(width 0.0889)
		(layer "B.Cu")
		(net "UPI_CPU0_CPU1_P1P1_DP<18>")
	)
	(segment
		(start 157.628082 -27.690826)
		(end 166.887652 -25.77973)
		(width 0.1143)
		(layer "B.Cu")
		(net "UPI_CPU0_CPU1_P1P1_DP<18>")
	)
	(segment
		(start 124.194824 -59.962034)
		(end 123.637548 -59.962034)
		(width 0.0889)
		(layer "B.Cu")
		(net "UPI_CPU0_CPU1_P1P1_DP<18>")
	)
	(segment
		(start 211.901786 -29.829506)
		(end 222.396812 -32.034734)
		(width 0.1143)
		(layer "B.Cu")
		(net "UPI_CPU0_CPU1_P1P1_DP<18>")
	)
	(segment
		(start 154.931872 -29.175456)
		(end 154.946604 -29.167328)
		(width 0.1143)
		(layer "B.Cu")
		(net "UPI_CPU0_CPU1_P1P1_DP<18>")
	)
	(segment
		(start 305.73345 -56.052212)
		(end 305.81219 -56.073548)
		(width 0.0889)
		(layer "B.Cu")
		(net "UPI_CPU0_CPU1_P1P1_DP<18>")
	)
	(segment
		(start 128.508252 -33.84804)
		(end 150.246842 -29.621988)
		(width 0.1143)
		(layer "B.Cu")
		(net "UPI_CPU0_CPU1_P1P1_DP<18>")
	)
	(segment
		(start 195.873624 -27.669236)
		(end 197.122542 -27.823668)
		(width 0.1143)
		(layer "B.Cu")
		(net "UPI_CPU0_CPU1_P1P1_DP<18>")
	)
	(segment
		(start 306.520596 -38.479476)
		(end 308.395116 -48.627284)
		(width 0.1143)
		(layer "B.Cu")
		(net "UPI_CPU0_CPU1_P1P1_DP<18>")
	)
	(segment
		(start 125.662944 -60.457334)
		(end 124.690124 -60.457334)
		(width 0.0889)
		(layer "B.Cu")
		(net "UPI_CPU0_CPU1_P1P1_DP<18>")
	)
	(segment
		(start 156.27096 -28.43784)
		(end 156.271214 -28.43784)
		(width 0.1143)
		(layer "B.Cu")
		(net "UPI_CPU0_CPU1_P1P1_DP<18>")
	)
	(segment
		(start 306.678076 -54.148228)
		(end 306.597558 -54.307232)
		(width 0.0889)
		(layer "B.Cu")
		(net "UPI_CPU0_CPU1_P1P1_DP<18>")
	)
	(segment
		(start 166.887652 -25.77973)
		(end 170.954954 -26.592784)
		(width 0.1143)
		(layer "B.Cu")
		(net "UPI_CPU0_CPU1_P1P1_DP<18>")
	)
	(segment
		(start 248.663714 -28.828746)
		(end 250.752864 -28.410916)
		(width 0.1143)
		(layer "B.Cu")
		(net "UPI_CPU0_CPU1_P1P1_DP<18>")
	)
	(segment
		(start 122.272806 -54.631336)
		(end 122.278648 -54.620922)
		(width 0.0889)
		(layer "B.Cu")
		(net "UPI_CPU0_CPU1_P1P1_DP<18>")
	)
	(segment
		(start 122.279918 -57.590436)
		(end 122.284744 -57.5818)
		(width 0.0889)
		(layer "B.Cu")
		(net "UPI_CPU0_CPU1_P1P1_DP<18>")
	)
	(segment
		(start 280.221182 -32.967168)
		(end 289.037014 -31.2039)
		(width 0.1143)
		(layer "B.Cu")
		(net "UPI_CPU0_CPU1_P1P1_DP<18>")
	)
	(segment
		(start 176.61255 -25.057354)
		(end 181.427882 -24.501602)
		(width 0.1143)
		(layer "B.Cu")
		(net "UPI_CPU0_CPU1_P1P1_DP<18>")
	)
	(segment
		(start 154.946604 -29.167328)
		(end 154.94635 -29.167328)
		(width 0.1143)
		(layer "B.Cu")
		(net "UPI_CPU0_CPU1_P1P1_DP<18>")
	)
	(segment
		(start 122.273568 -55.619904)
		(end 122.279918 -55.609236)
		(width 0.0889)
		(layer "B.Cu")
		(net "UPI_CPU0_CPU1_P1P1_DP<18>")
	)
	(segment
		(start 152.29967 -28.932886)
		(end 154.931872 -29.175456)
		(width 0.1143)
		(layer "B.Cu")
		(net "UPI_CPU0_CPU1_P1P1_DP<18>")
	)
	(segment
		(start 259.532882 -28.828746)
		(end 280.221182 -32.967168)
		(width 0.1143)
		(layer "B.Cu")
		(net "UPI_CPU0_CPU1_P1P1_DP<18>")
	)
	(segment
		(start 191.163702 -27.732736)
		(end 195.873624 -27.669236)
		(width 0.1143)
		(layer "B.Cu")
		(net "UPI_CPU0_CPU1_P1P1_DP<18>")
	)
	(segment
		(start 154.94635 -29.167328)
		(end 156.27096 -28.43784)
		(width 0.1143)
		(layer "B.Cu")
		(net "UPI_CPU0_CPU1_P1P1_DP<18>")
	)
	(segment
		(start 122.621294 -37.818568)
		(end 127.725678 -34.375598)
		(width 0.1143)
		(layer "B.Cu")
		(net "UPI_CPU0_CPU1_P1P1_DP<18>")
	)
	(segment
		(start 197.122542 -27.823668)
		(end 208.547208 -29.522166)
		(width 0.1143)
		(layer "B.Cu")
		(net "UPI_CPU0_CPU1_P1P1_DP<18>")
	)
	(segment
		(start 225.393504 -32.672528)
		(end 236.876082 -30.376114)
		(width 0.1143)
		(layer "B.Cu")
		(net "UPI_CPU0_CPU1_P1P1_DP<18>")
	)
	(segment
		(start 121.421398 -53.723286)
		(end 121.304304 -53.520848)
		(width 0.0889)
		(layer "B.Cu")
		(net "UPI_CPU0_CPU1_P1P1_DP<18>")
	)
	(segment
		(start 150.246842 -29.621988)
		(end 152.29967 -28.932886)
		(width 0.1143)
		(layer "B.Cu")
		(net "UPI_CPU0_CPU1_P1P1_DP<18>")
	)
	(segment
		(start 306.01285 -55.264304)
		(end 306.012596 -55.264558)
		(width 0.0889)
		(layer "B.Cu")
		(net "UPI_CPU0_CPU1_P1P1_DP<18>")
	)
	(segment
		(start 127.725932 -34.375598)
		(end 128.508252 -33.84804)
		(width 0.1143)
		(layer "B.Cu")
		(net "UPI_CPU0_CPU1_P1P1_DP<18>")
	)
	(segment
		(start 307.6956 -51.707034)
		(end 307.63972 -51.917346)
		(width 0.1143)
		(layer "B.Cu")
		(net "UPI_CPU0_CPU1_P1P1_DP<18>")
	)
	(segment
		(start 306.477416 -54.346602)
		(end 306.396898 -54.505352)
		(width 0.0889)
		(layer "B.Cu")
		(net "UPI_CPU0_CPU1_P1P1_DP<18>")
	)
	(segment
		(start 122.279918 -56.599836)
		(end 122.284744 -56.5912)
		(width 0.0889)
		(layer "B.Cu")
		(net "UPI_CPU0_CPU1_P1P1_DP<18>")
	)
	(segment
		(start 305.81219 -56.073548)
		(end 306.105306 -55.904384)
		(width 0.0889)
		(layer "B.Cu")
		(net "UPI_CPU0_CPU1_P1P1_DP<18>")
	)
	(segment
		(start 254.525018 -27.82697)
		(end 259.532882 -28.828746)
		(width 0.1143)
		(layer "B.Cu")
		(net "UPI_CPU0_CPU1_P1P1_DP<18>")
	)
	(segment
		(start 306.356258 -54.784244)
		(end 306.236116 -54.823614)
		(width 0.0889)
		(layer "B.Cu")
		(net "UPI_CPU0_CPU1_P1P1_DP<18>")
	)
	(segment
		(start 122.273568 -56.610504)
		(end 122.279918 -56.599836)
		(width 0.0889)
		(layer "B.Cu")
		(net "UPI_CPU0_CPU1_P1P1_DP<18>")
	)
	(arc
		(start 122.284744 -58.5724)
		(mid 122.333499 -58.376048)
		(end 122.279918 -58.180986)
		(width 0.0889)
		(layer "B.Cu")
		(net "UPI_CPU0_CPU1_P1P1_DP<18>")
	)
	(arc
		(start 125.965966 -60.609734)
		(mid 125.831404 -60.499822)
		(end 125.662944 -60.457334)
		(width 0.0889)
		(layer "B.Cu")
		(net "UPI_CPU0_CPU1_P1P1_DP<18>")
	)
	(arc
		(start 122.773948 -59.466988)
		(mid 122.275697 -59.164148)
		(end 122.279918 -58.581036)
		(width 0.0889)
		(layer "B.Cu")
		(net "UPI_CPU0_CPU1_P1P1_DP<18>")
	)
	(arc
		(start 122.284744 -56.5912)
		(mid 122.333499 -56.394848)
		(end 122.279918 -56.199786)
		(width 0.0889)
		(layer "B.Cu")
		(net "UPI_CPU0_CPU1_P1P1_DP<18>")
	)
	(arc
		(start 123.138438 -59.666886)
		(mid 122.999694 -59.524853)
		(end 122.809762 -59.466988)
		(width 0.0889)
		(layer "B.Cu")
		(net "UPI_CPU0_CPU1_P1P1_DP<18>")
	)
	(arc
		(start 122.284744 -55.6006)
		(mid 122.333499 -55.404248)
		(end 122.279918 -55.209186)
		(width 0.0889)
		(layer "B.Cu")
		(net "UPI_CPU0_CPU1_P1P1_DP<18>")
	)
	(arc
		(start 121.933208 -54.018434)
		(mid 121.637721 -53.939486)
		(end 121.421398 -53.723286)
		(width 0.0889)
		(layer "B.Cu")
		(net "UPI_CPU0_CPU1_P1P1_DP<18>")
	)
	(arc
		(start 122.279918 -55.209186)
		(mid 122.200957 -54.921204)
		(end 122.272806 -54.631336)
		(width 0.0889)
		(layer "B.Cu")
		(net "UPI_CPU0_CPU1_P1P1_DP<18>")
	)
	(arc
		(start 122.284744 -57.5818)
		(mid 122.333499 -57.385448)
		(end 122.279918 -57.190386)
		(width 0.0889)
		(layer "B.Cu")
		(net "UPI_CPU0_CPU1_P1P1_DP<18>")
	)
	(arc
		(start 122.279918 -56.199786)
		(mid 122.200696 -55.910668)
		(end 122.273568 -55.619904)
		(width 0.0889)
		(layer "B.Cu")
		(net "UPI_CPU0_CPU1_P1P1_DP<18>")
	)
	(arc
		(start 122.279918 -57.190386)
		(mid 122.200696 -56.901268)
		(end 122.273568 -56.610504)
		(width 0.0889)
		(layer "B.Cu")
		(net "UPI_CPU0_CPU1_P1P1_DP<18>")
	)
	(arc
		(start 123.637294 -59.962288)
		(mid 123.349149 -59.879969)
		(end 123.138438 -59.666886)
		(width 0.0889)
		(layer "B.Cu")
		(net "UPI_CPU0_CPU1_P1P1_DP<18>")
	)
	(arc
		(start 121.304304 -53.520848)
		(mid 120.674717 -52.28362)
		(end 120.178322 -50.987198)
		(width 0.0889)
		(layer "B.Cu")
		(net "UPI_CPU0_CPU1_P1P1_DP<18>")
	)
	(arc
		(start 122.28576 -54.608984)
		(mid 122.277068 -54.213687)
		(end 121.933208 -54.018434)
		(width 0.0889)
		(layer "B.Cu")
		(net "UPI_CPU0_CPU1_P1P1_DP<18>")
	)
	(arc
		(start 305.75377 -55.713122)
		(mid 305.705857 -55.880407)
		(end 305.73345 -56.052212)
		(width 0.0889)
		(layer "B.Cu")
		(net "UPI_CPU0_CPU1_P1P1_DP<18>")
	)
	(arc
		(start 122.279918 -58.180986)
		(mid 122.200696 -57.891868)
		(end 122.273568 -57.601104)
		(width 0.0889)
		(layer "B.Cu")
		(net "UPI_CPU0_CPU1_P1P1_DP<18>")
	)
	(segment
		(start 303.816766 -56.894984)
		(end 304.388266 -56.894984)
		(width 0.1143)
		(layer "F.Cu")
		(net "UPI_CPU0_CPU1_P1P1_DP<17>")
	)
	(segment
		(start 126.797308 -60.857384)
		(end 127.368808 -60.857384)
		(width 0.1143)
		(layer "F.Cu")
		(net "UPI_CPU0_CPU1_P1P1_DP<17>")
	)
	(via
		(at 304.388266 -56.894984)
		(size 0.508)
		(drill 0.254)
		(layers "F.Cu" "B.Cu")
		(net "UPI_CPU0_CPU1_P1P1_DP<17>")
	)
	(via
		(at 127.368808 -60.857384)
		(size 0.508)
		(drill 0.254)
		(layers "F.Cu" "B.Cu")
		(net "UPI_CPU0_CPU1_P1P1_DP<17>")
	)
	(segment
		(start 179.596288 -27.093926)
		(end 183.388 -26.1112)
		(width 0.1143)
		(layer "B.Cu")
		(net "UPI_CPU0_CPU1_P1P1_DP<17>")
	)
	(segment
		(start 208.400142 -30.416754)
		(end 209.296 -30.754066)
		(width 0.1143)
		(layer "B.Cu")
		(net "UPI_CPU0_CPU1_P1P1_DP<17>")
	)
	(segment
		(start 209.296 -30.754066)
		(end 209.504788 -30.832806)
		(width 0.1143)
		(layer "B.Cu")
		(net "UPI_CPU0_CPU1_P1P1_DP<17>")
	)
	(segment
		(start 304.900076 -55.609236)
		(end 304.906426 -55.619904)
		(width 0.0889)
		(layer "B.Cu")
		(net "UPI_CPU0_CPU1_P1P1_DP<17>")
	)
	(segment
		(start 160.792922 -28.16098)
		(end 167.4241 -26.90368)
		(width 0.1143)
		(layer "B.Cu")
		(net "UPI_CPU0_CPU1_P1P1_DP<17>")
	)
	(segment
		(start 125.669802 -59.466988)
		(end 124.781564 -59.466988)
		(width 0.0889)
		(layer "B.Cu")
		(net "UPI_CPU0_CPU1_P1P1_DP<17>")
	)
	(segment
		(start 122.368818 -51.665124)
		(end 122.368818 -51.208686)
		(width 0.1143)
		(layer "B.Cu")
		(net "UPI_CPU0_CPU1_P1P1_DP<17>")
	)
	(segment
		(start 170.732196 -27.56535)
		(end 170.73372 -27.565604)
		(width 0.1143)
		(layer "B.Cu")
		(net "UPI_CPU0_CPU1_P1P1_DP<17>")
	)
	(segment
		(start 238.802418 -31.764986)
		(end 250.717558 -29.381704)
		(width 0.1143)
		(layer "B.Cu")
		(net "UPI_CPU0_CPU1_P1P1_DP<17>")
	)
	(segment
		(start 304.872644 -56.24322)
		(end 304.559716 -56.690514)
		(width 0.0889)
		(layer "B.Cu")
		(net "UPI_CPU0_CPU1_P1P1_DP<17>")
	)
	(segment
		(start 150.570946 -30.68701)
		(end 153.649426 -30.848554)
		(width 0.1143)
		(layer "B.Cu")
		(net "UPI_CPU0_CPU1_P1P1_DP<17>")
	)
	(segment
		(start 123.143264 -55.713122)
		(end 123.138438 -55.704486)
		(width 0.0889)
		(layer "B.Cu")
		(net "UPI_CPU0_CPU1_P1P1_DP<17>")
	)
	(segment
		(start 305.714146 -52.622704)
		(end 305.677062 -52.661566)
		(width 0.0889)
		(layer "B.Cu")
		(net "UPI_CPU0_CPU1_P1P1_DP<17>")
	)
	(segment
		(start 176.963578 -27.497532)
		(end 179.596288 -27.093926)
		(width 0.1143)
		(layer "B.Cu")
		(net "UPI_CPU0_CPU1_P1P1_DP<17>")
	)
	(segment
		(start 297.999658 -33.059878)
		(end 305.135026 -38.845998)
		(width 0.1143)
		(layer "B.Cu")
		(net "UPI_CPU0_CPU1_P1P1_DP<17>")
	)
	(segment
		(start 123.563126 -38.542976)
		(end 128.989582 -34.882582)
		(width 0.1143)
		(layer "B.Cu")
		(net "UPI_CPU0_CPU1_P1P1_DP<17>")
	)
	(segment
		(start 127.368808 -60.857384)
		(end 127.175768 -60.579)
		(width 0.0889)
		(layer "B.Cu")
		(net "UPI_CPU0_CPU1_P1P1_DP<17>")
	)
	(segment
		(start 123.138438 -54.713886)
		(end 123.132088 -54.703218)
		(width 0.0889)
		(layer "B.Cu")
		(net "UPI_CPU0_CPU1_P1P1_DP<17>")
	)
	(segment
		(start 127.175768 -60.579)
		(end 127.004318 -60.331858)
		(width 0.0889)
		(layer "B.Cu")
		(net "UPI_CPU0_CPU1_P1P1_DP<17>")
	)
	(segment
		(start 236.913928 -31.387034)
		(end 238.802418 -31.764986)
		(width 0.1143)
		(layer "B.Cu")
		(net "UPI_CPU0_CPU1_P1P1_DP<17>")
	)
	(segment
		(start 254.89408 -28.89123)
		(end 280.272744 -33.96742)
		(width 0.1143)
		(layer "B.Cu")
		(net "UPI_CPU0_CPU1_P1P1_DP<17>")
	)
	(segment
		(start 250.717558 -29.381704)
		(end 252.754638 -29.401262)
		(width 0.1143)
		(layer "B.Cu")
		(net "UPI_CPU0_CPU1_P1P1_DP<17>")
	)
	(segment
		(start 305.04003 -54.967378)
		(end 304.900076 -55.20944)
		(width 0.0889)
		(layer "B.Cu")
		(net "UPI_CPU0_CPU1_P1P1_DP<17>")
	)
	(segment
		(start 155.9433 -30.682438)
		(end 156.654754 -30.540452)
		(width 0.1143)
		(layer "B.Cu")
		(net "UPI_CPU0_CPU1_P1P1_DP<17>")
	)
	(segment
		(start 305.677062 -52.661566)
		(end 305.04003 -54.967378)
		(width 0.0889)
		(layer "B.Cu")
		(net "UPI_CPU0_CPU1_P1P1_DP<17>")
	)
	(segment
		(start 123.138438 -57.685686)
		(end 123.132088 -57.675018)
		(width 0.0889)
		(layer "B.Cu")
		(net "UPI_CPU0_CPU1_P1P1_DP<17>")
	)
	(segment
		(start 306.636928 -50.07991)
		(end 306.01539 -51.971956)
		(width 0.1143)
		(layer "B.Cu")
		(net "UPI_CPU0_CPU1_P1P1_DP<17>")
	)
	(segment
		(start 124.781564 -59.466988)
		(end 124.28601 -58.971434)
		(width 0.0889)
		(layer "B.Cu")
		(net "UPI_CPU0_CPU1_P1P1_DP<17>")
	)
	(segment
		(start 291.967412 -31.628334)
		(end 297.999658 -33.059878)
		(width 0.1143)
		(layer "B.Cu")
		(net "UPI_CPU0_CPU1_P1P1_DP<17>")
	)
	(segment
		(start 172.130974 -27.60853)
		(end 176.963578 -27.497532)
		(width 0.1143)
		(layer "B.Cu")
		(net "UPI_CPU0_CPU1_P1P1_DP<17>")
	)
	(segment
		(start 225.318828 -33.706054)
		(end 236.913928 -31.387034)
		(width 0.1143)
		(layer "B.Cu")
		(net "UPI_CPU0_CPU1_P1P1_DP<17>")
	)
	(segment
		(start 196.087238 -28.46832)
		(end 197.35673 -28.641548)
		(width 0.1143)
		(layer "B.Cu")
		(net "UPI_CPU0_CPU1_P1P1_DP<17>")
	)
	(segment
		(start 123.628912 -58.971434)
		(end 123.628658 -58.971688)
		(width 0.0889)
		(layer "B.Cu")
		(net "UPI_CPU0_CPU1_P1P1_DP<17>")
	)
	(segment
		(start 185.196734 -26.5684)
		(end 185.425842 -26.64587)
		(width 0.1143)
		(layer "B.Cu")
		(net "UPI_CPU0_CPU1_P1P1_DP<17>")
	)
	(segment
		(start 126.525274 -59.962288)
		(end 126.497334 -59.962288)
		(width 0.0889)
		(layer "B.Cu")
		(net "UPI_CPU0_CPU1_P1P1_DP<17>")
	)
	(segment
		(start 306.01539 -51.971956)
		(end 305.821842 -52.234084)
		(width 0.1143)
		(layer "B.Cu")
		(net "UPI_CPU0_CPU1_P1P1_DP<17>")
	)
	(segment
		(start 183.388 -26.1112)
		(end 185.196734 -26.5684)
		(width 0.1143)
		(layer "B.Cu")
		(net "UPI_CPU0_CPU1_P1P1_DP<17>")
	)
	(segment
		(start 305.821842 -52.234084)
		(end 305.714146 -52.622704)
		(width 0.1143)
		(layer "B.Cu")
		(net "UPI_CPU0_CPU1_P1P1_DP<17>")
	)
	(segment
		(start 122.394218 -51.690524)
		(end 122.368818 -51.665124)
		(width 0.0889)
		(layer "B.Cu")
		(net "UPI_CPU0_CPU1_P1P1_DP<17>")
	)
	(segment
		(start 123.143264 -57.694322)
		(end 123.138438 -57.685686)
		(width 0.0889)
		(layer "B.Cu")
		(net "UPI_CPU0_CPU1_P1P1_DP<17>")
	)
	(segment
		(start 304.89525 -55.6006)
		(end 304.900076 -55.609236)
		(width 0.0889)
		(layer "B.Cu")
		(net "UPI_CPU0_CPU1_P1P1_DP<17>")
	)
	(segment
		(start 121.324878 -45.834554)
		(end 122.409458 -40.253666)
		(width 0.1143)
		(layer "B.Cu")
		(net "UPI_CPU0_CPU1_P1P1_DP<17>")
	)
	(segment
		(start 305.135026 -38.845998)
		(end 306.788566 -47.850552)
		(width 0.1143)
		(layer "B.Cu")
		(net "UPI_CPU0_CPU1_P1P1_DP<17>")
	)
	(segment
		(start 211.50326 -30.853888)
		(end 212.846666 -31.041594)
		(width 0.1143)
		(layer "B.Cu")
		(net "UPI_CPU0_CPU1_P1P1_DP<17>")
	)
	(segment
		(start 122.368818 -51.208686)
		(end 121.324878 -45.834554)
		(width 0.1143)
		(layer "B.Cu")
		(net "UPI_CPU0_CPU1_P1P1_DP<17>")
	)
	(segment
		(start 156.654754 -30.540452)
		(end 160.792922 -28.16098)
		(width 0.1143)
		(layer "B.Cu")
		(net "UPI_CPU0_CPU1_P1P1_DP<17>")
	)
	(segment
		(start 153.649426 -30.848554)
		(end 155.9433 -30.682438)
		(width 0.1143)
		(layer "B.Cu")
		(net "UPI_CPU0_CPU1_P1P1_DP<17>")
	)
	(segment
		(start 212.846666 -31.041594)
		(end 222.396812 -33.07461)
		(width 0.1143)
		(layer "B.Cu")
		(net "UPI_CPU0_CPU1_P1P1_DP<17>")
	)
	(segment
		(start 123.138438 -56.695086)
		(end 123.132088 -56.684418)
		(width 0.0889)
		(layer "B.Cu")
		(net "UPI_CPU0_CPU1_P1P1_DP<17>")
	)
	(segment
		(start 124.28601 -58.971434)
		(end 123.628912 -58.971434)
		(width 0.0889)
		(layer "B.Cu")
		(net "UPI_CPU0_CPU1_P1P1_DP<17>")
	)
	(segment
		(start 123.138438 -55.704486)
		(end 123.132088 -55.693818)
		(width 0.0889)
		(layer "B.Cu")
		(net "UPI_CPU0_CPU1_P1P1_DP<17>")
	)
	(segment
		(start 185.425842 -26.64587)
		(end 191.225424 -28.60167)
		(width 0.1143)
		(layer "B.Cu")
		(net "UPI_CPU0_CPU1_P1P1_DP<17>")
	)
	(segment
		(start 170.73372 -27.565604)
		(end 172.130974 -27.60853)
		(width 0.1143)
		(layer "B.Cu")
		(net "UPI_CPU0_CPU1_P1P1_DP<17>")
	)
	(segment
		(start 123.004834 -53.492146)
		(end 122.394218 -52.072032)
		(width 0.0889)
		(layer "B.Cu")
		(net "UPI_CPU0_CPU1_P1P1_DP<17>")
	)
	(segment
		(start 222.396812 -33.07461)
		(end 225.150426 -33.660842)
		(width 0.1143)
		(layer "B.Cu")
		(net "UPI_CPU0_CPU1_P1P1_DP<17>")
	)
	(segment
		(start 197.35673 -28.641548)
		(end 208.400142 -30.416754)
		(width 0.1143)
		(layer "B.Cu")
		(net "UPI_CPU0_CPU1_P1P1_DP<17>")
	)
	(segment
		(start 123.143264 -56.703722)
		(end 123.138438 -56.695086)
		(width 0.0889)
		(layer "B.Cu")
		(net "UPI_CPU0_CPU1_P1P1_DP<17>")
	)
	(segment
		(start 122.409458 -40.253666)
		(end 123.563126 -38.542976)
		(width 0.1143)
		(layer "B.Cu")
		(net "UPI_CPU0_CPU1_P1P1_DP<17>")
	)
	(segment
		(start 122.394218 -52.072032)
		(end 122.394218 -51.690524)
		(width 0.0889)
		(layer "B.Cu")
		(net "UPI_CPU0_CPU1_P1P1_DP<17>")
	)
	(segment
		(start 128.989582 -34.882582)
		(end 150.570946 -30.68701)
		(width 0.1143)
		(layer "B.Cu")
		(net "UPI_CPU0_CPU1_P1P1_DP<17>")
	)
	(segment
		(start 252.754638 -29.401262)
		(end 254.89408 -28.89123)
		(width 0.1143)
		(layer "B.Cu")
		(net "UPI_CPU0_CPU1_P1P1_DP<17>")
	)
	(segment
		(start 191.225424 -28.60167)
		(end 196.087238 -28.46832)
		(width 0.1143)
		(layer "B.Cu")
		(net "UPI_CPU0_CPU1_P1P1_DP<17>")
	)
	(segment
		(start 306.788566 -47.850552)
		(end 306.636928 -50.07991)
		(width 0.1143)
		(layer "B.Cu")
		(net "UPI_CPU0_CPU1_P1P1_DP<17>")
	)
	(segment
		(start 123.143264 -53.731922)
		(end 123.004834 -53.492146)
		(width 0.0889)
		(layer "B.Cu")
		(net "UPI_CPU0_CPU1_P1P1_DP<17>")
	)
	(segment
		(start 123.143264 -54.722522)
		(end 123.138438 -54.713886)
		(width 0.0889)
		(layer "B.Cu")
		(net "UPI_CPU0_CPU1_P1P1_DP<17>")
	)
	(segment
		(start 280.272744 -33.96742)
		(end 291.967412 -31.628334)
		(width 0.1143)
		(layer "B.Cu")
		(net "UPI_CPU0_CPU1_P1P1_DP<17>")
	)
	(segment
		(start 225.150426 -33.660842)
		(end 225.318828 -33.706054)
		(width 0.1143)
		(layer "B.Cu")
		(net "UPI_CPU0_CPU1_P1P1_DP<17>")
	)
	(segment
		(start 209.504788 -30.832806)
		(end 211.50326 -30.853888)
		(width 0.1143)
		(layer "B.Cu")
		(net "UPI_CPU0_CPU1_P1P1_DP<17>")
	)
	(segment
		(start 167.4241 -26.90368)
		(end 170.732196 -27.56535)
		(width 0.1143)
		(layer "B.Cu")
		(net "UPI_CPU0_CPU1_P1P1_DP<17>")
	)
	(arc
		(start 123.138438 -54.123336)
		(mid 123.191908 -53.928273)
		(end 123.143264 -53.731922)
		(width 0.0889)
		(layer "B.Cu")
		(net "UPI_CPU0_CPU1_P1P1_DP<17>")
	)
	(arc
		(start 123.138438 -55.113936)
		(mid 123.191908 -54.918873)
		(end 123.143264 -54.722522)
		(width 0.0889)
		(layer "B.Cu")
		(net "UPI_CPU0_CPU1_P1P1_DP<17>")
	)
	(arc
		(start 304.906426 -55.619904)
		(mid 304.978516 -55.936383)
		(end 304.872644 -56.24322)
		(width 0.0889)
		(layer "B.Cu")
		(net "UPI_CPU0_CPU1_P1P1_DP<17>")
	)
	(arc
		(start 125.998478 -59.666886)
		(mid 125.859734 -59.524853)
		(end 125.669802 -59.466988)
		(width 0.0889)
		(layer "B.Cu")
		(net "UPI_CPU0_CPU1_P1P1_DP<17>")
	)
	(arc
		(start 126.856998 -60.162186)
		(mid 126.716919 -60.01945)
		(end 126.525274 -59.962288)
		(width 0.0889)
		(layer "B.Cu")
		(net "UPI_CPU0_CPU1_P1P1_DP<17>")
	)
	(arc
		(start 304.559716 -56.690514)
		(mid 304.478469 -56.796504)
		(end 304.388266 -56.894984)
		(width 0.0889)
		(layer "B.Cu")
		(net "UPI_CPU0_CPU1_P1P1_DP<17>")
	)
	(arc
		(start 123.138438 -58.085736)
		(mid 123.191908 -57.890673)
		(end 123.143264 -57.694322)
		(width 0.0889)
		(layer "B.Cu")
		(net "UPI_CPU0_CPU1_P1P1_DP<17>")
	)
	(arc
		(start 123.132088 -54.703218)
		(mid 123.05929 -54.412455)
		(end 123.138438 -54.123336)
		(width 0.0889)
		(layer "B.Cu")
		(net "UPI_CPU0_CPU1_P1P1_DP<17>")
	)
	(arc
		(start 123.138438 -57.095136)
		(mid 123.191908 -56.900073)
		(end 123.143264 -56.703722)
		(width 0.0889)
		(layer "B.Cu")
		(net "UPI_CPU0_CPU1_P1P1_DP<17>")
	)
	(arc
		(start 127.004318 -60.331858)
		(mid 126.922541 -60.254073)
		(end 126.856998 -60.162186)
		(width 0.0889)
		(layer "B.Cu")
		(net "UPI_CPU0_CPU1_P1P1_DP<17>")
	)
	(arc
		(start 123.132088 -57.675018)
		(mid 123.05929 -57.384255)
		(end 123.138438 -57.095136)
		(width 0.0889)
		(layer "B.Cu")
		(net "UPI_CPU0_CPU1_P1P1_DP<17>")
	)
	(arc
		(start 123.132088 -55.693818)
		(mid 123.05929 -55.403055)
		(end 123.138438 -55.113936)
		(width 0.0889)
		(layer "B.Cu")
		(net "UPI_CPU0_CPU1_P1P1_DP<17>")
	)
	(arc
		(start 123.132088 -56.684418)
		(mid 123.05929 -56.393655)
		(end 123.138438 -56.104536)
		(width 0.0889)
		(layer "B.Cu")
		(net "UPI_CPU0_CPU1_P1P1_DP<17>")
	)
	(arc
		(start 123.138438 -56.104536)
		(mid 123.191908 -55.909473)
		(end 123.143264 -55.713122)
		(width 0.0889)
		(layer "B.Cu")
		(net "UPI_CPU0_CPU1_P1P1_DP<17>")
	)
	(arc
		(start 126.497334 -59.962288)
		(mid 126.209189 -59.879969)
		(end 125.998478 -59.666886)
		(width 0.0889)
		(layer "B.Cu")
		(net "UPI_CPU0_CPU1_P1P1_DP<17>")
	)
	(arc
		(start 123.628658 -58.971688)
		(mid 123.133181 -58.667245)
		(end 123.138438 -58.085736)
		(width 0.0889)
		(layer "B.Cu")
		(net "UPI_CPU0_CPU1_P1P1_DP<17>")
	)
	(arc
		(start 304.900076 -55.20944)
		(mid 304.846608 -55.404391)
		(end 304.89525 -55.6006)
		(width 0.0889)
		(layer "B.Cu")
		(net "UPI_CPU0_CPU1_P1P1_DP<17>")
	)
	(segment
		(start 125.080268 -58.876438)
		(end 125.651768 -58.876438)
		(width 0.1143)
		(layer "F.Cu")
		(net "UPI_CPU0_CPU1_P1P1_DP<16>")
	)
	(segment
		(start 303.816766 -54.913784)
		(end 304.388266 -54.913784)
		(width 0.1143)
		(layer "F.Cu")
		(net "UPI_CPU0_CPU1_P1P1_DP<16>")
	)
	(via
		(at 125.651768 -58.876438)
		(size 0.508)
		(drill 0.254)
		(layers "F.Cu" "B.Cu")
		(net "UPI_CPU0_CPU1_P1P1_DP<16>")
	)
	(via
		(at 304.388266 -54.913784)
		(size 0.508)
		(drill 0.254)
		(layers "F.Cu" "B.Cu")
		(net "UPI_CPU0_CPU1_P1P1_DP<16>")
	)
	(segment
		(start 122.598942 -45.780452)
		(end 123.60148 -40.62349)
		(width 0.1143)
		(layer "B.Cu")
		(net "UPI_CPU0_CPU1_P1P1_DP<16>")
	)
	(segment
		(start 123.534424 -52.154582)
		(end 123.534424 -51.422046)
		(width 0.0889)
		(layer "B.Cu")
		(net "UPI_CPU0_CPU1_P1P1_DP<16>")
	)
	(segment
		(start 305.56581 -49.4665)
		(end 305.202082 -51.313588)
		(width 0.1143)
		(layer "B.Cu")
		(net "UPI_CPU0_CPU1_P1P1_DP<16>")
	)
	(segment
		(start 249.910346 -30.323536)
		(end 252.750574 -30.390338)
		(width 0.1143)
		(layer "B.Cu")
		(net "UPI_CPU0_CPU1_P1P1_DP<16>")
	)
	(segment
		(start 304.09515 -55.082948)
		(end 304.388266 -54.913784)
		(width 0.0889)
		(layer "B.Cu")
		(net "UPI_CPU0_CPU1_P1P1_DP<16>")
	)
	(segment
		(start 125.651768 -58.876438)
		(end 125.251718 -58.476388)
		(width 0.0889)
		(layer "B.Cu")
		(net "UPI_CPU0_CPU1_P1P1_DP<16>")
	)
	(segment
		(start 304.727864 -52.520088)
		(end 304.653442 -52.68214)
		(width 0.0889)
		(layer "B.Cu")
		(net "UPI_CPU0_CPU1_P1P1_DP<16>")
	)
	(segment
		(start 305.045618 -51.657504)
		(end 305.011836 -51.66995)
		(width 0.0889)
		(layer "B.Cu")
		(net "UPI_CPU0_CPU1_P1P1_DP<16>")
	)
	(segment
		(start 304.132742 -53.565298)
		(end 304.043588 -53.719476)
		(width 0.0889)
		(layer "B.Cu")
		(net "UPI_CPU0_CPU1_P1P1_DP<16>")
	)
	(segment
		(start 304.45456 -52.89042)
		(end 304.501804 -53.01488)
		(width 0.0889)
		(layer "B.Cu")
		(net "UPI_CPU0_CPU1_P1P1_DP<16>")
	)
	(segment
		(start 123.509024 -50.976022)
		(end 122.598942 -45.780452)
		(width 0.1143)
		(layer "B.Cu")
		(net "UPI_CPU0_CPU1_P1P1_DP<16>")
	)
	(segment
		(start 209.9056 -31.866332)
		(end 211.911184 -31.917132)
		(width 0.1143)
		(layer "B.Cu")
		(net "UPI_CPU0_CPU1_P1P1_DP<16>")
	)
	(segment
		(start 151.217122 -31.708852)
		(end 154.692604 -32.378142)
		(width 0.1143)
		(layer "B.Cu")
		(net "UPI_CPU0_CPU1_P1P1_DP<16>")
	)
	(segment
		(start 161.068766 -29.16047)
		(end 167.304466 -27.913076)
		(width 0.1143)
		(layer "B.Cu")
		(net "UPI_CPU0_CPU1_P1P1_DP<16>")
	)
	(segment
		(start 123.60148 -40.62349)
		(end 124.502672 -39.28745)
		(width 0.1143)
		(layer "B.Cu")
		(net "UPI_CPU0_CPU1_P1P1_DP<16>")
	)
	(segment
		(start 124.05614 -53.101748)
		(end 123.534424 -52.154582)
		(width 0.0889)
		(layer "B.Cu")
		(net "UPI_CPU0_CPU1_P1P1_DP<16>")
	)
	(segment
		(start 304.653442 -52.68214)
		(end 304.528728 -52.728368)
		(width 0.0889)
		(layer "B.Cu")
		(net "UPI_CPU0_CPU1_P1P1_DP<16>")
	)
	(segment
		(start 196.163692 -29.277056)
		(end 197.09638 -29.41447)
		(width 0.1143)
		(layer "B.Cu")
		(net "UPI_CPU0_CPU1_P1P1_DP<16>")
	)
	(segment
		(start 161.068766 -29.160216)
		(end 161.068766 -29.16047)
		(width 0.1143)
		(layer "B.Cu")
		(net "UPI_CPU0_CPU1_P1P1_DP<16>")
	)
	(segment
		(start 124.502672 -39.28745)
		(end 126.985522 -37.612574)
		(width 0.1143)
		(layer "B.Cu")
		(net "UPI_CPU0_CPU1_P1P1_DP<16>")
	)
	(segment
		(start 304.528728 -52.728368)
		(end 304.45456 -52.89042)
		(width 0.0889)
		(layer "B.Cu")
		(net "UPI_CPU0_CPU1_P1P1_DP<16>")
	)
	(segment
		(start 280.268934 -34.961068)
		(end 291.829744 -32.648906)
		(width 0.1143)
		(layer "B.Cu")
		(net "UPI_CPU0_CPU1_P1P1_DP<16>")
	)
	(segment
		(start 222.396812 -34.140902)
		(end 225.18116 -34.741866)
		(width 0.1143)
		(layer "B.Cu")
		(net "UPI_CPU0_CPU1_P1P1_DP<16>")
	)
	(segment
		(start 291.829744 -32.648906)
		(end 297.543474 -34.108644)
		(width 0.1143)
		(layer "B.Cu")
		(net "UPI_CPU0_CPU1_P1P1_DP<16>")
	)
	(segment
		(start 190.433452 -29.480764)
		(end 196.163692 -29.277056)
		(width 0.1143)
		(layer "B.Cu")
		(net "UPI_CPU0_CPU1_P1P1_DP<16>")
	)
	(segment
		(start 124.05614 -57.612026)
		(end 124.05614 -53.101748)
		(width 0.0889)
		(layer "B.Cu")
		(net "UPI_CPU0_CPU1_P1P1_DP<16>")
	)
	(segment
		(start 129.470658 -35.936174)
		(end 151.217122 -31.708852)
		(width 0.1143)
		(layer "B.Cu")
		(net "UPI_CPU0_CPU1_P1P1_DP<16>")
	)
	(segment
		(start 161.027364 -29.168598)
		(end 161.068766 -29.160216)
		(width 0.1143)
		(layer "B.Cu")
		(net "UPI_CPU0_CPU1_P1P1_DP<16>")
	)
	(segment
		(start 183.906414 -27.276298)
		(end 185.522108 -27.746706)
		(width 0.1143)
		(layer "B.Cu")
		(net "UPI_CPU0_CPU1_P1P1_DP<16>")
	)
	(segment
		(start 238.357156 -32.635698)
		(end 249.910346 -30.323536)
		(width 0.1143)
		(layer "B.Cu")
		(net "UPI_CPU0_CPU1_P1P1_DP<16>")
	)
	(segment
		(start 123.534424 -51.422046)
		(end 123.509024 -51.396646)
		(width 0.0889)
		(layer "B.Cu")
		(net "UPI_CPU0_CPU1_P1P1_DP<16>")
	)
	(segment
		(start 167.304466 -27.913076)
		(end 170.631612 -28.578556)
		(width 0.1143)
		(layer "B.Cu")
		(net "UPI_CPU0_CPU1_P1P1_DP<16>")
	)
	(segment
		(start 170.631612 -28.578556)
		(end 176.53381 -28.575254)
		(width 0.1143)
		(layer "B.Cu")
		(net "UPI_CPU0_CPU1_P1P1_DP<16>")
	)
	(segment
		(start 305.583082 -48.285146)
		(end 305.56581 -49.4665)
		(width 0.1143)
		(layer "B.Cu")
		(net "UPI_CPU0_CPU1_P1P1_DP<16>")
	)
	(segment
		(start 304.041556 -54.713886)
		(end 304.03673 -54.722522)
		(width 0.0889)
		(layer "B.Cu")
		(net "UPI_CPU0_CPU1_P1P1_DP<16>")
	)
	(segment
		(start 124.920502 -58.476388)
		(end 124.05614 -57.612026)
		(width 0.0889)
		(layer "B.Cu")
		(net "UPI_CPU0_CPU1_P1P1_DP<16>")
	)
	(segment
		(start 297.543474 -34.108644)
		(end 304.126138 -39.528242)
		(width 0.1143)
		(layer "B.Cu")
		(net "UPI_CPU0_CPU1_P1P1_DP<16>")
	)
	(segment
		(start 208.370424 -31.339028)
		(end 209.9056 -31.866332)
		(width 0.1143)
		(layer "B.Cu")
		(net "UPI_CPU0_CPU1_P1P1_DP<16>")
	)
	(segment
		(start 304.126138 -39.528242)
		(end 305.583082 -48.285146)
		(width 0.1143)
		(layer "B.Cu")
		(net "UPI_CPU0_CPU1_P1P1_DP<16>")
	)
	(segment
		(start 305.011836 -51.66995)
		(end 304.90668 -51.900836)
		(width 0.0889)
		(layer "B.Cu")
		(net "UPI_CPU0_CPU1_P1P1_DP<16>")
	)
	(segment
		(start 211.911184 -31.917132)
		(end 212.51291 -32.008064)
		(width 0.1143)
		(layer "B.Cu")
		(net "UPI_CPU0_CPU1_P1P1_DP<16>")
	)
	(segment
		(start 126.985776 -37.612574)
		(end 129.470658 -35.936174)
		(width 0.1143)
		(layer "B.Cu")
		(net "UPI_CPU0_CPU1_P1P1_DP<16>")
	)
	(segment
		(start 304.180748 -53.490114)
		(end 304.132742 -53.565298)
		(width 0.0889)
		(layer "B.Cu")
		(net "UPI_CPU0_CPU1_P1P1_DP<16>")
	)
	(segment
		(start 304.879502 -52.187348)
		(end 304.754788 -52.233576)
		(width 0.0889)
		(layer "B.Cu")
		(net "UPI_CPU0_CPU1_P1P1_DP<16>")
	)
	(segment
		(start 176.53381 -28.575254)
		(end 179.920646 -28.025598)
		(width 0.1143)
		(layer "B.Cu")
		(net "UPI_CPU0_CPU1_P1P1_DP<16>")
	)
	(segment
		(start 304.501804 -53.01488)
		(end 304.427382 -53.176932)
		(width 0.0889)
		(layer "B.Cu")
		(net "UPI_CPU0_CPU1_P1P1_DP<16>")
	)
	(segment
		(start 304.953924 -52.025296)
		(end 304.879502 -52.187348)
		(width 0.0889)
		(layer "B.Cu")
		(net "UPI_CPU0_CPU1_P1P1_DP<16>")
	)
	(segment
		(start 304.90668 -51.900836)
		(end 304.953924 -52.025296)
		(width 0.0889)
		(layer "B.Cu")
		(net "UPI_CPU0_CPU1_P1P1_DP<16>")
	)
	(segment
		(start 304.68062 -52.395628)
		(end 304.727864 -52.520088)
		(width 0.0889)
		(layer "B.Cu")
		(net "UPI_CPU0_CPU1_P1P1_DP<16>")
	)
	(segment
		(start 185.522108 -27.746706)
		(end 190.433452 -29.480764)
		(width 0.1143)
		(layer "B.Cu")
		(net "UPI_CPU0_CPU1_P1P1_DP<16>")
	)
	(segment
		(start 305.054762 -51.637438)
		(end 305.045618 -51.657504)
		(width 0.0889)
		(layer "B.Cu")
		(net "UPI_CPU0_CPU1_P1P1_DP<16>")
	)
	(segment
		(start 252.750574 -30.390338)
		(end 255.376172 -29.982414)
		(width 0.1143)
		(layer "B.Cu")
		(net "UPI_CPU0_CPU1_P1P1_DP<16>")
	)
	(segment
		(start 236.794294 -32.399478)
		(end 238.357156 -32.635698)
		(width 0.1143)
		(layer "B.Cu")
		(net "UPI_CPU0_CPU1_P1P1_DP<16>")
	)
	(segment
		(start 304.043588 -53.719476)
		(end 304.03673 -53.731922)
		(width 0.0889)
		(layer "B.Cu")
		(net "UPI_CPU0_CPU1_P1P1_DP<16>")
	)
	(segment
		(start 154.692604 -32.378142)
		(end 156.126942 -32.122618)
		(width 0.1143)
		(layer "B.Cu")
		(net "UPI_CPU0_CPU1_P1P1_DP<16>")
	)
	(segment
		(start 179.920646 -28.025598)
		(end 183.906414 -27.276298)
		(width 0.1143)
		(layer "B.Cu")
		(net "UPI_CPU0_CPU1_P1P1_DP<16>")
	)
	(segment
		(start 305.202082 -51.313588)
		(end 305.054762 -51.637438)
		(width 0.1143)
		(layer "B.Cu")
		(net "UPI_CPU0_CPU1_P1P1_DP<16>")
	)
	(segment
		(start 197.09638 -29.41447)
		(end 208.370424 -31.339028)
		(width 0.1143)
		(layer "B.Cu")
		(net "UPI_CPU0_CPU1_P1P1_DP<16>")
	)
	(segment
		(start 125.251718 -58.476388)
		(end 124.920502 -58.476388)
		(width 0.0889)
		(layer "B.Cu")
		(net "UPI_CPU0_CPU1_P1P1_DP<16>")
	)
	(segment
		(start 304.01641 -55.061612)
		(end 304.09515 -55.082948)
		(width 0.0889)
		(layer "B.Cu")
		(net "UPI_CPU0_CPU1_P1P1_DP<16>")
	)
	(segment
		(start 212.51291 -32.008064)
		(end 222.396812 -34.140902)
		(width 0.1143)
		(layer "B.Cu")
		(net "UPI_CPU0_CPU1_P1P1_DP<16>")
	)
	(segment
		(start 304.754788 -52.233576)
		(end 304.68062 -52.395628)
		(width 0.0889)
		(layer "B.Cu")
		(net "UPI_CPU0_CPU1_P1P1_DP<16>")
	)
	(segment
		(start 304.427382 -53.176932)
		(end 304.302922 -53.22316)
		(width 0.0889)
		(layer "B.Cu")
		(net "UPI_CPU0_CPU1_P1P1_DP<16>")
	)
	(segment
		(start 304.047906 -54.703218)
		(end 304.041556 -54.713886)
		(width 0.0889)
		(layer "B.Cu")
		(net "UPI_CPU0_CPU1_P1P1_DP<16>")
	)
	(segment
		(start 225.37547 -34.795968)
		(end 236.794294 -32.399478)
		(width 0.1143)
		(layer "B.Cu")
		(net "UPI_CPU0_CPU1_P1P1_DP<16>")
	)
	(segment
		(start 255.376172 -29.982414)
		(end 280.268934 -34.961068)
		(width 0.1143)
		(layer "B.Cu")
		(net "UPI_CPU0_CPU1_P1P1_DP<16>")
	)
	(segment
		(start 304.302922 -53.22316)
		(end 304.180748 -53.490114)
		(width 0.0889)
		(layer "B.Cu")
		(net "UPI_CPU0_CPU1_P1P1_DP<16>")
	)
	(segment
		(start 123.509024 -51.374548)
		(end 123.509024 -50.976022)
		(width 0.1143)
		(layer "B.Cu")
		(net "UPI_CPU0_CPU1_P1P1_DP<16>")
	)
	(segment
		(start 126.985522 -37.612574)
		(end 126.985776 -37.612574)
		(width 0.1143)
		(layer "B.Cu")
		(net "UPI_CPU0_CPU1_P1P1_DP<16>")
	)
	(segment
		(start 156.126942 -32.122618)
		(end 161.027364 -29.168598)
		(width 0.1143)
		(layer "B.Cu")
		(net "UPI_CPU0_CPU1_P1P1_DP<16>")
	)
	(segment
		(start 225.18116 -34.741866)
		(end 225.37547 -34.795968)
		(width 0.1143)
		(layer "B.Cu")
		(net "UPI_CPU0_CPU1_P1P1_DP<16>")
	)
	(segment
		(start 123.509024 -51.396646)
		(end 123.509024 -51.374548)
		(width 0.0889)
		(layer "B.Cu")
		(net "UPI_CPU0_CPU1_P1P1_DP<16>")
	)
	(arc
		(start 304.03673 -54.722522)
		(mid 303.988817 -54.889807)
		(end 304.01641 -55.061612)
		(width 0.0889)
		(layer "B.Cu")
		(net "UPI_CPU0_CPU1_P1P1_DP<16>")
	)
	(arc
		(start 304.041556 -54.123336)
		(mid 304.120778 -54.412454)
		(end 304.047906 -54.703218)
		(width 0.0889)
		(layer "B.Cu")
		(net "UPI_CPU0_CPU1_P1P1_DP<16>")
	)
	(arc
		(start 304.03673 -53.731922)
		(mid 303.987975 -53.928274)
		(end 304.041556 -54.123336)
		(width 0.0889)
		(layer "B.Cu")
		(net "UPI_CPU0_CPU1_P1P1_DP<16>")
	)
	(segment
		(start 126.797308 -58.876438)
		(end 127.368808 -58.876438)
		(width 0.1143)
		(layer "F.Cu")
		(net "UPI_CPU0_CPU1_P1P1_DP<15>")
	)
	(segment
		(start 302.099726 -53.923184)
		(end 302.671226 -53.923184)
		(width 0.1143)
		(layer "F.Cu")
		(net "UPI_CPU0_CPU1_P1P1_DP<15>")
	)
	(via
		(at 302.671226 -53.923184)
		(size 0.508)
		(drill 0.254)
		(layers "F.Cu" "B.Cu")
		(net "UPI_CPU0_CPU1_P1P1_DP<15>")
	)
	(via
		(at 127.368808 -58.876438)
		(size 0.508)
		(drill 0.254)
		(layers "F.Cu" "B.Cu")
		(net "UPI_CPU0_CPU1_P1P1_DP<15>")
	)
	(segment
		(start 125.021086 -46.978062)
		(end 125.286262 -46.760892)
		(width 0.1143)
		(layer "B.Cu")
		(net "UPI_CPU0_CPU1_P1P1_DP<15>")
	)
	(segment
		(start 303.813464 -46.721522)
		(end 303.960784 -46.824392)
		(width 0.1143)
		(layer "B.Cu")
		(net "UPI_CPU0_CPU1_P1P1_DP<15>")
	)
	(segment
		(start 303.610264 -45.57014)
		(end 303.650142 -45.795438)
		(width 0.1143)
		(layer "B.Cu")
		(net "UPI_CPU0_CPU1_P1P1_DP<15>")
	)
	(segment
		(start 125.708918 -46.414436)
		(end 125.974094 -46.197266)
		(width 0.1143)
		(layer "B.Cu")
		(net "UPI_CPU0_CPU1_P1P1_DP<15>")
	)
	(segment
		(start 124.759466 -51.97348)
		(end 124.83973 -51.893216)
		(width 0.0889)
		(layer "B.Cu")
		(net "UPI_CPU0_CPU1_P1P1_DP<15>")
	)
	(segment
		(start 304.230024 -48.35144)
		(end 303.43602 -50.940208)
		(width 0.1143)
		(layer "B.Cu")
		(net "UPI_CPU0_CPU1_P1P1_DP<15>")
	)
	(segment
		(start 303.43602 -51.624484)
		(end 303.228756 -52.651406)
		(width 0.0889)
		(layer "B.Cu")
		(net "UPI_CPU0_CPU1_P1P1_DP<15>")
	)
	(segment
		(start 303.228756 -52.651406)
		(end 303.105312 -52.981352)
		(width 0.0889)
		(layer "B.Cu")
		(net "UPI_CPU0_CPU1_P1P1_DP<15>")
	)
	(segment
		(start 124.759466 -52.12588)
		(end 124.759466 -51.97348)
		(width 0.0889)
		(layer "B.Cu")
		(net "UPI_CPU0_CPU1_P1P1_DP<15>")
	)
	(segment
		(start 174.005748 -30.132274)
		(end 176.780444 -29.831284)
		(width 0.1143)
		(layer "B.Cu")
		(net "UPI_CPU0_CPU1_P1P1_DP<15>")
	)
	(segment
		(start 237.876588 -33.766252)
		(end 249.311922 -31.478982)
		(width 0.1143)
		(layer "B.Cu")
		(net "UPI_CPU0_CPU1_P1P1_DP<15>")
	)
	(segment
		(start 127.349504 -45.070014)
		(end 127.492506 -45.084238)
		(width 0.1143)
		(layer "B.Cu")
		(net "UPI_CPU0_CPU1_P1P1_DP<15>")
	)
	(segment
		(start 183.779668 -28.568904)
		(end 184.659524 -28.76677)
		(width 0.1143)
		(layer "B.Cu")
		(net "UPI_CPU0_CPU1_P1P1_DP<15>")
	)
	(segment
		(start 154.94381 -33.680146)
		(end 156.516578 -33.394396)
		(width 0.1143)
		(layer "B.Cu")
		(net "UPI_CPU0_CPU1_P1P1_DP<15>")
	)
	(segment
		(start 225.247962 -36.063936)
		(end 236.84865 -33.650936)
		(width 0.1143)
		(layer "B.Cu")
		(net "UPI_CPU0_CPU1_P1P1_DP<15>")
	)
	(segment
		(start 124.861066 -52.37988)
		(end 124.861066 -52.22748)
		(width 0.0889)
		(layer "B.Cu")
		(net "UPI_CPU0_CPU1_P1P1_DP<15>")
	)
	(segment
		(start 124.861066 -53.39588)
		(end 124.861066 -53.24348)
		(width 0.0889)
		(layer "B.Cu")
		(net "UPI_CPU0_CPU1_P1P1_DP<15>")
	)
	(segment
		(start 127.070358 -45.430186)
		(end 127.084328 -45.287184)
		(width 0.1143)
		(layer "B.Cu")
		(net "UPI_CPU0_CPU1_P1P1_DP<15>")
	)
	(segment
		(start 127.492506 -45.084238)
		(end 127.757936 -44.86656)
		(width 0.1143)
		(layer "B.Cu")
		(net "UPI_CPU0_CPU1_P1P1_DP<15>")
	)
	(segment
		(start 303.4538 -51.536346)
		(end 303.43602 -51.624484)
		(width 0.0889)
		(layer "B.Cu")
		(net "UPI_CPU0_CPU1_P1P1_DP<15>")
	)
	(segment
		(start 303.567592 -44.597066)
		(end 303.464722 -44.744132)
		(width 0.1143)
		(layer "B.Cu")
		(net "UPI_CPU0_CPU1_P1P1_DP<15>")
	)
	(segment
		(start 127.607822 -59.276234)
		(end 127.350774 -59.276234)
		(width 0.0889)
		(layer "B.Cu")
		(net "UPI_CPU0_CPU1_P1P1_DP<15>")
	)
	(segment
		(start 303.4538 -51.140614)
		(end 303.4538 -51.536346)
		(width 0.0889)
		(layer "B.Cu")
		(net "UPI_CPU0_CPU1_P1P1_DP<15>")
	)
	(segment
		(start 124.759466 -52.63388)
		(end 124.759466 -52.48148)
		(width 0.0889)
		(layer "B.Cu")
		(net "UPI_CPU0_CPU1_P1P1_DP<15>")
	)
	(segment
		(start 137.349484 -36.158932)
		(end 151.567896 -33.039558)
		(width 0.1143)
		(layer "B.Cu")
		(net "UPI_CPU0_CPU1_P1P1_DP<15>")
	)
	(segment
		(start 126.382526 -45.993812)
		(end 126.39675 -45.85081)
		(width 0.1143)
		(layer "B.Cu")
		(net "UPI_CPU0_CPU1_P1P1_DP<15>")
	)
	(segment
		(start 303.105312 -52.981352)
		(end 303.011586 -53.143404)
		(width 0.0889)
		(layer "B.Cu")
		(net "UPI_CPU0_CPU1_P1P1_DP<15>")
	)
	(segment
		(start 171.287948 -31.096966)
		(end 172.602144 -30.898338)
		(width 0.1143)
		(layer "B.Cu")
		(net "UPI_CPU0_CPU1_P1P1_DP<15>")
	)
	(segment
		(start 124.86513 -51.562)
		(end 124.86513 -47.908972)
		(width 0.1143)
		(layer "B.Cu")
		(net "UPI_CPU0_CPU1_P1P1_DP<15>")
	)
	(segment
		(start 303.651666 -45.072554)
		(end 303.713388 -45.423074)
		(width 0.1143)
		(layer "B.Cu")
		(net "UPI_CPU0_CPU1_P1P1_DP<15>")
	)
	(segment
		(start 131.630166 -39.905686)
		(end 137.11936 -36.203382)
		(width 0.1143)
		(layer "B.Cu")
		(net "UPI_CPU0_CPU1_P1P1_DP<15>")
	)
	(segment
		(start 124.83973 -51.5874)
		(end 124.86513 -51.562)
		(width 0.0889)
		(layer "B.Cu")
		(net "UPI_CPU0_CPU1_P1P1_DP<15>")
	)
	(segment
		(start 211.674964 -33.187386)
		(end 222.396812 -35.45967)
		(width 0.1143)
		(layer "B.Cu")
		(net "UPI_CPU0_CPU1_P1P1_DP<15>")
	)
	(segment
		(start 303.43602 -43.850306)
		(end 303.567592 -44.597066)
		(width 0.1143)
		(layer "B.Cu")
		(net "UPI_CPU0_CPU1_P1P1_DP<15>")
	)
	(segment
		(start 253.078742 -31.647892)
		(end 255.658874 -31.286196)
		(width 0.1143)
		(layer "B.Cu")
		(net "UPI_CPU0_CPU1_P1P1_DP<15>")
	)
	(segment
		(start 249.311922 -31.478982)
		(end 253.078742 -31.647892)
		(width 0.1143)
		(layer "B.Cu")
		(net "UPI_CPU0_CPU1_P1P1_DP<15>")
	)
	(segment
		(start 166.32936 -30.105096)
		(end 171.287948 -31.096966)
		(width 0.1143)
		(layer "B.Cu")
		(net "UPI_CPU0_CPU1_P1P1_DP<15>")
	)
	(segment
		(start 125.452124 -57.295034)
		(end 124.759466 -56.602376)
		(width 0.0889)
		(layer "B.Cu")
		(net "UPI_CPU0_CPU1_P1P1_DP<15>")
	)
	(segment
		(start 304.026824 -47.19955)
		(end 303.9237 -47.346616)
		(width 0.1143)
		(layer "B.Cu")
		(net "UPI_CPU0_CPU1_P1P1_DP<15>")
	)
	(segment
		(start 124.861066 -52.88788)
		(end 124.861066 -52.73548)
		(width 0.0889)
		(layer "B.Cu")
		(net "UPI_CPU0_CPU1_P1P1_DP<15>")
	)
	(segment
		(start 302.964342 -54.092348)
		(end 302.671226 -53.923184)
		(width 0.0889)
		(layer "B.Cu")
		(net "UPI_CPU0_CPU1_P1P1_DP<15>")
	)
	(segment
		(start 125.286262 -46.760892)
		(end 125.429264 -46.775116)
		(width 0.1143)
		(layer "B.Cu")
		(net "UPI_CPU0_CPU1_P1P1_DP<15>")
	)
	(segment
		(start 176.780444 -29.831284)
		(end 183.779668 -28.568904)
		(width 0.1143)
		(layer "B.Cu")
		(net "UPI_CPU0_CPU1_P1P1_DP<15>")
	)
	(segment
		(start 126.661926 -45.63364)
		(end 126.804928 -45.647864)
		(width 0.1143)
		(layer "B.Cu")
		(net "UPI_CPU0_CPU1_P1P1_DP<15>")
	)
	(segment
		(start 126.117096 -46.21149)
		(end 126.382526 -45.993812)
		(width 0.1143)
		(layer "B.Cu")
		(net "UPI_CPU0_CPU1_P1P1_DP<15>")
	)
	(segment
		(start 296.766488 -35.376612)
		(end 302.84039 -40.470074)
		(width 0.1143)
		(layer "B.Cu")
		(net "UPI_CPU0_CPU1_P1P1_DP<15>")
	)
	(segment
		(start 125.694694 -46.557438)
		(end 125.708918 -46.414436)
		(width 0.1143)
		(layer "B.Cu")
		(net "UPI_CPU0_CPU1_P1P1_DP<15>")
	)
	(segment
		(start 296.506392 -35.306)
		(end 296.5196 -35.309556)
		(width 0.1143)
		(layer "B.Cu")
		(net "UPI_CPU0_CPU1_P1P1_DP<15>")
	)
	(segment
		(start 125.429264 -46.775116)
		(end 125.694694 -46.557438)
		(width 0.1143)
		(layer "B.Cu")
		(net "UPI_CPU0_CPU1_P1P1_DP<15>")
	)
	(segment
		(start 124.759466 -56.602376)
		(end 124.759466 -53.49748)
		(width 0.0889)
		(layer "B.Cu")
		(net "UPI_CPU0_CPU1_P1P1_DP<15>")
	)
	(segment
		(start 156.516578 -33.394396)
		(end 159.757872 -31.4198)
		(width 0.1143)
		(layer "B.Cu")
		(net "UPI_CPU0_CPU1_P1P1_DP<15>")
	)
	(segment
		(start 197.48627 -30.599126)
		(end 197.486778 -30.599126)
		(width 0.1143)
		(layer "B.Cu")
		(net "UPI_CPU0_CPU1_P1P1_DP<15>")
	)
	(segment
		(start 126.528068 -58.780934)
		(end 126.492254 -58.780934)
		(width 0.0889)
		(layer "B.Cu")
		(net "UPI_CPU0_CPU1_P1P1_DP<15>")
	)
	(segment
		(start 303.797462 -45.898562)
		(end 303.87671 -46.348904)
		(width 0.1143)
		(layer "B.Cu")
		(net "UPI_CPU0_CPU1_P1P1_DP<15>")
	)
	(segment
		(start 124.861066 -53.24348)
		(end 124.759466 -53.14188)
		(width 0.0889)
		(layer "B.Cu")
		(net "UPI_CPU0_CPU1_P1P1_DP<15>")
	)
	(segment
		(start 129.132584 -43.608498)
		(end 131.630166 -39.905686)
		(width 0.1143)
		(layer "B.Cu")
		(net "UPI_CPU0_CPU1_P1P1_DP<15>")
	)
	(segment
		(start 126.39675 -45.85081)
		(end 126.661926 -45.63364)
		(width 0.1143)
		(layer "B.Cu")
		(net "UPI_CPU0_CPU1_P1P1_DP<15>")
	)
	(segment
		(start 126.804928 -45.647864)
		(end 127.070358 -45.430186)
		(width 0.1143)
		(layer "B.Cu")
		(net "UPI_CPU0_CPU1_P1P1_DP<15>")
	)
	(segment
		(start 303.87671 -46.348904)
		(end 303.77384 -46.49597)
		(width 0.1143)
		(layer "B.Cu")
		(net "UPI_CPU0_CPU1_P1P1_DP<15>")
	)
	(segment
		(start 303.650142 -45.795438)
		(end 303.797462 -45.898562)
		(width 0.1143)
		(layer "B.Cu")
		(net "UPI_CPU0_CPU1_P1P1_DP<15>")
	)
	(segment
		(start 160.300416 -31.311342)
		(end 166.32936 -30.105096)
		(width 0.1143)
		(layer "B.Cu")
		(net "UPI_CPU0_CPU1_P1P1_DP<15>")
	)
	(segment
		(start 127.084328 -45.287184)
		(end 127.349504 -45.070014)
		(width 0.1143)
		(layer "B.Cu")
		(net "UPI_CPU0_CPU1_P1P1_DP<15>")
	)
	(segment
		(start 197.486778 -30.599126)
		(end 197.489826 -30.599888)
		(width 0.1143)
		(layer "B.Cu")
		(net "UPI_CPU0_CPU1_P1P1_DP<15>")
	)
	(segment
		(start 304.110898 -47.675038)
		(end 304.230024 -48.35144)
		(width 0.1143)
		(layer "B.Cu")
		(net "UPI_CPU0_CPU1_P1P1_DP<15>")
	)
	(segment
		(start 303.963578 -47.571914)
		(end 304.110898 -47.675038)
		(width 0.1143)
		(layer "B.Cu")
		(net "UPI_CPU0_CPU1_P1P1_DP<15>")
	)
	(segment
		(start 197.491858 -30.600142)
		(end 207.921352 -32.44342)
		(width 0.1143)
		(layer "B.Cu")
		(net "UPI_CPU0_CPU1_P1P1_DP<15>")
	)
	(segment
		(start 124.861066 -52.73548)
		(end 124.759466 -52.63388)
		(width 0.0889)
		(layer "B.Cu")
		(net "UPI_CPU0_CPU1_P1P1_DP<15>")
	)
	(segment
		(start 124.759466 -52.48148)
		(end 124.861066 -52.37988)
		(width 0.0889)
		(layer "B.Cu")
		(net "UPI_CPU0_CPU1_P1P1_DP<15>")
	)
	(segment
		(start 303.429924 -51.116738)
		(end 303.4538 -51.140614)
		(width 0.0889)
		(layer "B.Cu")
		(net "UPI_CPU0_CPU1_P1P1_DP<15>")
	)
	(segment
		(start 303.043082 -54.071012)
		(end 302.964342 -54.092348)
		(width 0.0889)
		(layer "B.Cu")
		(net "UPI_CPU0_CPU1_P1P1_DP<15>")
	)
	(segment
		(start 303.77384 -46.49597)
		(end 303.813464 -46.721522)
		(width 0.1143)
		(layer "B.Cu")
		(net "UPI_CPU0_CPU1_P1P1_DP<15>")
	)
	(segment
		(start 184.659524 -28.76677)
		(end 189.72276 -30.524704)
		(width 0.1143)
		(layer "B.Cu")
		(net "UPI_CPU0_CPU1_P1P1_DP<15>")
	)
	(segment
		(start 127.757936 -44.86656)
		(end 127.77216 -44.723558)
		(width 0.1143)
		(layer "B.Cu")
		(net "UPI_CPU0_CPU1_P1P1_DP<15>")
	)
	(segment
		(start 125.974094 -46.197266)
		(end 126.117096 -46.21149)
		(width 0.1143)
		(layer "B.Cu")
		(net "UPI_CPU0_CPU1_P1P1_DP<15>")
	)
	(segment
		(start 127.368808 -58.876438)
		(end 127.709168 -59.072526)
		(width 0.0889)
		(layer "B.Cu")
		(net "UPI_CPU0_CPU1_P1P1_DP<15>")
	)
	(segment
		(start 291.498528 -33.948116)
		(end 296.506392 -35.306)
		(width 0.1143)
		(layer "B.Cu")
		(net "UPI_CPU0_CPU1_P1P1_DP<15>")
	)
	(segment
		(start 137.11936 -36.203382)
		(end 137.349484 -36.158932)
		(width 0.1143)
		(layer "B.Cu")
		(net "UPI_CPU0_CPU1_P1P1_DP<15>")
	)
	(segment
		(start 303.960784 -46.824392)
		(end 304.026824 -47.19955)
		(width 0.1143)
		(layer "B.Cu")
		(net "UPI_CPU0_CPU1_P1P1_DP<15>")
	)
	(segment
		(start 303.43602 -50.940208)
		(end 303.429924 -50.96002)
		(width 0.1143)
		(layer "B.Cu")
		(net "UPI_CPU0_CPU1_P1P1_DP<15>")
	)
	(segment
		(start 159.757872 -31.4198)
		(end 159.82696 -31.406084)
		(width 0.1143)
		(layer "B.Cu")
		(net "UPI_CPU0_CPU1_P1P1_DP<15>")
	)
	(segment
		(start 209.724752 -33.09239)
		(end 211.674964 -33.187386)
		(width 0.1143)
		(layer "B.Cu")
		(net "UPI_CPU0_CPU1_P1P1_DP<15>")
	)
	(segment
		(start 124.861066 -52.22748)
		(end 124.759466 -52.12588)
		(width 0.0889)
		(layer "B.Cu")
		(net "UPI_CPU0_CPU1_P1P1_DP<15>")
	)
	(segment
		(start 222.396812 -35.45967)
		(end 225.247962 -36.063936)
		(width 0.1143)
		(layer "B.Cu")
		(net "UPI_CPU0_CPU1_P1P1_DP<15>")
	)
	(segment
		(start 303.017936 -53.723286)
		(end 303.022762 -53.731922)
		(width 0.0889)
		(layer "B.Cu")
		(net "UPI_CPU0_CPU1_P1P1_DP<15>")
	)
	(segment
		(start 124.83973 -51.893216)
		(end 124.83973 -51.5874)
		(width 0.0889)
		(layer "B.Cu")
		(net "UPI_CPU0_CPU1_P1P1_DP<15>")
	)
	(segment
		(start 303.429924 -50.96002)
		(end 303.429924 -51.116738)
		(width 0.1143)
		(layer "B.Cu")
		(net "UPI_CPU0_CPU1_P1P1_DP<15>")
	)
	(segment
		(start 302.84039 -40.470074)
		(end 303.43602 -43.850306)
		(width 0.1143)
		(layer "B.Cu")
		(net "UPI_CPU0_CPU1_P1P1_DP<15>")
	)
	(segment
		(start 189.72276 -30.524704)
		(end 196.379592 -30.423612)
		(width 0.1143)
		(layer "B.Cu")
		(net "UPI_CPU0_CPU1_P1P1_DP<15>")
	)
	(segment
		(start 280.233374 -36.20135)
		(end 291.498528 -33.948116)
		(width 0.1143)
		(layer "B.Cu")
		(net "UPI_CPU0_CPU1_P1P1_DP<15>")
	)
	(segment
		(start 127.77216 -44.723558)
		(end 129.132584 -43.608498)
		(width 0.1143)
		(layer "B.Cu")
		(net "UPI_CPU0_CPU1_P1P1_DP<15>")
	)
	(segment
		(start 255.658874 -31.286196)
		(end 280.233374 -36.20135)
		(width 0.1143)
		(layer "B.Cu")
		(net "UPI_CPU0_CPU1_P1P1_DP<15>")
	)
	(segment
		(start 303.464722 -44.744132)
		(end 303.504346 -44.969684)
		(width 0.1143)
		(layer "B.Cu")
		(net "UPI_CPU0_CPU1_P1P1_DP<15>")
	)
	(segment
		(start 303.9237 -47.346616)
		(end 303.963578 -47.571914)
		(width 0.1143)
		(layer "B.Cu")
		(net "UPI_CPU0_CPU1_P1P1_DP<15>")
	)
	(segment
		(start 160.200848 -31.460948)
		(end 160.300416 -31.311342)
		(width 0.1143)
		(layer "B.Cu")
		(net "UPI_CPU0_CPU1_P1P1_DP<15>")
	)
	(segment
		(start 303.713388 -45.423074)
		(end 303.610264 -45.57014)
		(width 0.1143)
		(layer "B.Cu")
		(net "UPI_CPU0_CPU1_P1P1_DP<15>")
	)
	(segment
		(start 207.921352 -32.44342)
		(end 209.724752 -33.09239)
		(width 0.1143)
		(layer "B.Cu")
		(net "UPI_CPU0_CPU1_P1P1_DP<15>")
	)
	(segment
		(start 124.759466 -53.49748)
		(end 124.861066 -53.39588)
		(width 0.0889)
		(layer "B.Cu")
		(net "UPI_CPU0_CPU1_P1P1_DP<15>")
	)
	(segment
		(start 303.504346 -44.969684)
		(end 303.651666 -45.072554)
		(width 0.1143)
		(layer "B.Cu")
		(net "UPI_CPU0_CPU1_P1P1_DP<15>")
	)
	(segment
		(start 197.489826 -30.599888)
		(end 197.491858 -30.600142)
		(width 0.1143)
		(layer "B.Cu")
		(net "UPI_CPU0_CPU1_P1P1_DP<15>")
	)
	(segment
		(start 159.976312 -31.505906)
		(end 160.200848 -31.460948)
		(width 0.1143)
		(layer "B.Cu")
		(net "UPI_CPU0_CPU1_P1P1_DP<15>")
	)
	(segment
		(start 124.759466 -53.14188)
		(end 124.759466 -52.98948)
		(width 0.0889)
		(layer "B.Cu")
		(net "UPI_CPU0_CPU1_P1P1_DP<15>")
	)
	(segment
		(start 124.86513 -47.908972)
		(end 125.021086 -46.978062)
		(width 0.1143)
		(layer "B.Cu")
		(net "UPI_CPU0_CPU1_P1P1_DP<15>")
	)
	(segment
		(start 124.759466 -52.98948)
		(end 124.861066 -52.88788)
		(width 0.0889)
		(layer "B.Cu")
		(net "UPI_CPU0_CPU1_P1P1_DP<15>")
	)
	(segment
		(start 236.84865 -33.650936)
		(end 237.876588 -33.766252)
		(width 0.1143)
		(layer "B.Cu")
		(net "UPI_CPU0_CPU1_P1P1_DP<15>")
	)
	(segment
		(start 296.5196 -35.309556)
		(end 296.766488 -35.376612)
		(width 0.1143)
		(layer "B.Cu")
		(net "UPI_CPU0_CPU1_P1P1_DP<15>")
	)
	(segment
		(start 172.602144 -30.898338)
		(end 174.005748 -30.132274)
		(width 0.1143)
		(layer "B.Cu")
		(net "UPI_CPU0_CPU1_P1P1_DP<15>")
	)
	(segment
		(start 151.567896 -33.039558)
		(end 154.94381 -33.680146)
		(width 0.1143)
		(layer "B.Cu")
		(net "UPI_CPU0_CPU1_P1P1_DP<15>")
	)
	(segment
		(start 127.709168 -59.072526)
		(end 127.723392 -59.125866)
		(width 0.0889)
		(layer "B.Cu")
		(net "UPI_CPU0_CPU1_P1P1_DP<15>")
	)
	(segment
		(start 125.669548 -57.295034)
		(end 125.452124 -57.295034)
		(width 0.0889)
		(layer "B.Cu")
		(net "UPI_CPU0_CPU1_P1P1_DP<15>")
	)
	(segment
		(start 196.379592 -30.423612)
		(end 197.48627 -30.599126)
		(width 0.1143)
		(layer "B.Cu")
		(net "UPI_CPU0_CPU1_P1P1_DP<15>")
	)
	(segment
		(start 159.82696 -31.406084)
		(end 159.976312 -31.505906)
		(width 0.1143)
		(layer "B.Cu")
		(net "UPI_CPU0_CPU1_P1P1_DP<15>")
	)
	(arc
		(start 127.723392 -59.125866)
		(mid 127.702628 -59.229489)
		(end 127.607822 -59.276234)
		(width 0.0889)
		(layer "B.Cu")
		(net "UPI_CPU0_CPU1_P1P1_DP<15>")
	)
	(arc
		(start 126.492254 -58.780934)
		(mid 126.159285 -58.573386)
		(end 126.163578 -58.180986)
		(width 0.0889)
		(layer "B.Cu")
		(net "UPI_CPU0_CPU1_P1P1_DP<15>")
	)
	(arc
		(start 303.06264 -54.005988)
		(mid 303.054247 -54.038917)
		(end 303.043082 -54.071012)
		(width 0.0889)
		(layer "B.Cu")
		(net "UPI_CPU0_CPU1_P1P1_DP<15>")
	)
	(arc
		(start 127.022098 -59.076336)
		(mid 126.81349 -58.864404)
		(end 126.528068 -58.780934)
		(width 0.0889)
		(layer "B.Cu")
		(net "UPI_CPU0_CPU1_P1P1_DP<15>")
	)
	(arc
		(start 303.011586 -53.143404)
		(mid 302.938788 -53.434167)
		(end 303.017936 -53.723286)
		(width 0.0889)
		(layer "B.Cu")
		(net "UPI_CPU0_CPU1_P1P1_DP<15>")
	)
	(arc
		(start 126.163578 -58.180986)
		(mid 126.167907 -57.597814)
		(end 125.669548 -57.295034)
		(width 0.0889)
		(layer "B.Cu")
		(net "UPI_CPU0_CPU1_P1P1_DP<15>")
	)
	(arc
		(start 303.022762 -53.731922)
		(mid 303.067116 -53.865395)
		(end 303.06264 -54.005988)
		(width 0.0889)
		(layer "B.Cu")
		(net "UPI_CPU0_CPU1_P1P1_DP<15>")
	)
	(arc
		(start 127.350774 -59.276234)
		(mid 127.160845 -59.218364)
		(end 127.022098 -59.076336)
		(width 0.0889)
		(layer "B.Cu")
		(net "UPI_CPU0_CPU1_P1P1_DP<15>")
	)
	(segment
		(start 126.797308 -57.885584)
		(end 127.368808 -57.885584)
		(width 0.1143)
		(layer "F.Cu")
		(net "UPI_CPU0_CPU1_P1P1_DP<14>")
	)
	(segment
		(start 302.099726 -55.904384)
		(end 302.671226 -55.904384)
		(width 0.1143)
		(layer "F.Cu")
		(net "UPI_CPU0_CPU1_P1P1_DP<14>")
	)
	(via
		(at 127.368808 -57.885584)
		(size 0.508)
		(drill 0.254)
		(layers "F.Cu" "B.Cu")
		(net "UPI_CPU0_CPU1_P1P1_DP<14>")
	)
	(via
		(at 302.671226 -55.904384)
		(size 0.508)
		(drill 0.254)
		(layers "F.Cu" "B.Cu")
		(net "UPI_CPU0_CPU1_P1P1_DP<14>")
	)
	(segment
		(start 302.099218 -44.163488)
		(end 302.18126 -44.045632)
		(width 0.1143)
		(layer "B.Cu")
		(net "UPI_CPU0_CPU1_P1P1_DP<14>")
	)
	(segment
		(start 302.791114 -48.001428)
		(end 302.730154 -47.663862)
		(width 0.1143)
		(layer "B.Cu")
		(net "UPI_CPU0_CPU1_P1P1_DP<14>")
	)
	(segment
		(start 208.41843 -33.592516)
		(end 207.88503 -33.391094)
		(width 0.1143)
		(layer "B.Cu")
		(net "UPI_CPU0_CPU1_P1P1_DP<14>")
	)
	(segment
		(start 183.662828 -29.607256)
		(end 167.503094 -32.9692)
		(width 0.1143)
		(layer "B.Cu")
		(net "UPI_CPU0_CPU1_P1P1_DP<14>")
	)
	(segment
		(start 132.375656 -40.776652)
		(end 132.334 -40.838374)
		(width 0.1143)
		(layer "B.Cu")
		(net "UPI_CPU0_CPU1_P1P1_DP<14>")
	)
	(segment
		(start 302.654462 -46.670722)
		(end 302.593756 -46.33341)
		(width 0.1143)
		(layer "B.Cu")
		(net "UPI_CPU0_CPU1_P1P1_DP<14>")
	)
	(segment
		(start 301.866046 -42.295572)
		(end 301.658274 -41.140888)
		(width 0.1143)
		(layer "B.Cu")
		(net "UPI_CPU0_CPU1_P1P1_DP<14>")
	)
	(segment
		(start 301.784004 -42.413428)
		(end 301.866046 -42.295572)
		(width 0.1143)
		(layer "B.Cu")
		(net "UPI_CPU0_CPU1_P1P1_DP<14>")
	)
	(segment
		(start 209.56524 -34.055558)
		(end 208.41843 -33.592516)
		(width 0.1143)
		(layer "B.Cu")
		(net "UPI_CPU0_CPU1_P1P1_DP<14>")
	)
	(segment
		(start 125.97257 -52.08397)
		(end 125.97257 -52.106068)
		(width 0.0889)
		(layer "B.Cu")
		(net "UPI_CPU0_CPU1_P1P1_DP<14>")
	)
	(segment
		(start 302.57242 -46.788832)
		(end 302.654462 -46.670722)
		(width 0.1143)
		(layer "B.Cu")
		(net "UPI_CPU0_CPU1_P1P1_DP<14>")
	)
	(segment
		(start 126.996952 -58.033412)
		(end 127.075692 -58.054748)
		(width 0.0889)
		(layer "B.Cu")
		(net "UPI_CPU0_CPU1_P1P1_DP<14>")
	)
	(segment
		(start 196.234558 -31.191454)
		(end 189.55766 -31.456884)
		(width 0.1143)
		(layer "B.Cu")
		(net "UPI_CPU0_CPU1_P1P1_DP<14>")
	)
	(segment
		(start 302.256952 -45.038772)
		(end 302.338994 -44.920662)
		(width 0.1143)
		(layer "B.Cu")
		(net "UPI_CPU0_CPU1_P1P1_DP<14>")
	)
	(segment
		(start 302.338994 -44.920662)
		(end 302.278288 -44.58335)
		(width 0.1143)
		(layer "B.Cu")
		(net "UPI_CPU0_CPU1_P1P1_DP<14>")
	)
	(segment
		(start 211.351622 -34.185606)
		(end 209.56524 -34.055558)
		(width 0.1143)
		(layer "B.Cu")
		(net "UPI_CPU0_CPU1_P1P1_DP<14>")
	)
	(segment
		(start 302.159416 -53.227986)
		(end 302.153066 -53.217318)
		(width 0.0889)
		(layer "B.Cu")
		(net "UPI_CPU0_CPU1_P1P1_DP<14>")
	)
	(segment
		(start 238.573564 -34.415476)
		(end 237.4519 -34.709354)
		(width 0.1143)
		(layer "B.Cu")
		(net "UPI_CPU0_CPU1_P1P1_DP<14>")
	)
	(segment
		(start 126.07417 -50.40757)
		(end 126.07417 -50.75047)
		(width 0.1143)
		(layer "B.Cu")
		(net "UPI_CPU0_CPU1_P1P1_DP<14>")
	)
	(segment
		(start 125.97257 -48.42129)
		(end 125.97257 -50.30597)
		(width 0.1143)
		(layer "B.Cu")
		(net "UPI_CPU0_CPU1_P1P1_DP<14>")
	)
	(segment
		(start 302.429672 -50.511964)
		(end 302.96993 -48.420782)
		(width 0.1143)
		(layer "B.Cu")
		(net "UPI_CPU0_CPU1_P1P1_DP<14>")
	)
	(segment
		(start 302.436022 -45.45838)
		(end 302.317912 -45.376338)
		(width 0.1143)
		(layer "B.Cu")
		(net "UPI_CPU0_CPU1_P1P1_DP<14>")
	)
	(segment
		(start 125.250702 -56.134508)
		(end 125.420628 -56.304434)
		(width 0.0889)
		(layer "B.Cu")
		(net "UPI_CPU0_CPU1_P1P1_DP<14>")
	)
	(segment
		(start 296.362374 -36.500308)
		(end 291.195506 -35.05835)
		(width 0.1143)
		(layer "B.Cu")
		(net "UPI_CPU0_CPU1_P1P1_DP<14>")
	)
	(segment
		(start 302.730154 -47.663862)
		(end 302.812196 -47.545752)
		(width 0.1143)
		(layer "B.Cu")
		(net "UPI_CPU0_CPU1_P1P1_DP<14>")
	)
	(segment
		(start 302.593756 -46.33341)
		(end 302.475646 -46.251368)
		(width 0.1143)
		(layer "B.Cu")
		(net "UPI_CPU0_CPU1_P1P1_DP<14>")
	)
	(segment
		(start 152.655524 -34.24047)
		(end 137.621772 -37.237924)
		(width 0.1143)
		(layer "B.Cu")
		(net "UPI_CPU0_CPU1_P1P1_DP<14>")
	)
	(segment
		(start 302.377602 -50.800254)
		(end 302.427894 -50.520854)
		(width 0.1143)
		(layer "B.Cu")
		(net "UPI_CPU0_CPU1_P1P1_DP<14>")
	)
	(segment
		(start 126.07417 -50.75047)
		(end 125.97257 -50.85207)
		(width 0.1143)
		(layer "B.Cu")
		(net "UPI_CPU0_CPU1_P1P1_DP<14>")
	)
	(segment
		(start 160.922462 -33.30702)
		(end 159.59328 -33.386014)
		(width 0.1143)
		(layer "B.Cu")
		(net "UPI_CPU0_CPU1_P1P1_DP<14>")
	)
	(segment
		(start 302.160178 -44.501308)
		(end 302.099218 -44.163488)
		(width 0.1143)
		(layer "B.Cu")
		(net "UPI_CPU0_CPU1_P1P1_DP<14>")
	)
	(segment
		(start 252.459744 -32.777176)
		(end 248.34977 -32.468058)
		(width 0.1143)
		(layer "B.Cu")
		(net "UPI_CPU0_CPU1_P1P1_DP<14>")
	)
	(segment
		(start 125.97257 -50.30597)
		(end 126.07417 -50.40757)
		(width 0.1143)
		(layer "B.Cu")
		(net "UPI_CPU0_CPU1_P1P1_DP<14>")
	)
	(segment
		(start 302.023526 -43.170602)
		(end 301.96282 -42.83329)
		(width 0.1143)
		(layer "B.Cu")
		(net "UPI_CPU0_CPU1_P1P1_DP<14>")
	)
	(segment
		(start 302.159416 -52.237386)
		(end 302.090328 -52.117752)
		(width 0.0889)
		(layer "B.Cu")
		(net "UPI_CPU0_CPU1_P1P1_DP<14>")
	)
	(segment
		(start 184.04332 -29.693108)
		(end 183.662828 -29.607256)
		(width 0.1143)
		(layer "B.Cu")
		(net "UPI_CPU0_CPU1_P1P1_DP<14>")
	)
	(segment
		(start 302.18126 -44.045632)
		(end 302.120554 -43.70832)
		(width 0.1143)
		(layer "B.Cu")
		(net "UPI_CPU0_CPU1_P1P1_DP<14>")
	)
	(segment
		(start 301.941738 -43.288458)
		(end 302.023526 -43.170602)
		(width 0.1143)
		(layer "B.Cu")
		(net "UPI_CPU0_CPU1_P1P1_DP<14>")
	)
	(segment
		(start 302.317912 -45.376338)
		(end 302.256952 -45.038772)
		(width 0.1143)
		(layer "B.Cu")
		(net "UPI_CPU0_CPU1_P1P1_DP<14>")
	)
	(segment
		(start 302.159416 -54.618636)
		(end 302.164242 -54.61)
		(width 0.0889)
		(layer "B.Cu")
		(net "UPI_CPU0_CPU1_P1P1_DP<14>")
	)
	(segment
		(start 302.159416 -52.637436)
		(end 302.164242 -52.6288)
		(width 0.0889)
		(layer "B.Cu")
		(net "UPI_CPU0_CPU1_P1P1_DP<14>")
	)
	(segment
		(start 279.936956 -37.247576)
		(end 256.30505 -32.520636)
		(width 0.1143)
		(layer "B.Cu")
		(net "UPI_CPU0_CPU1_P1P1_DP<14>")
	)
	(segment
		(start 127.022098 -57.685686)
		(end 127.017272 -57.694322)
		(width 0.0889)
		(layer "B.Cu")
		(net "UPI_CPU0_CPU1_P1P1_DP<14>")
	)
	(segment
		(start 302.475646 -46.251368)
		(end 302.414686 -45.913802)
		(width 0.1143)
		(layer "B.Cu")
		(net "UPI_CPU0_CPU1_P1P1_DP<14>")
	)
	(segment
		(start 127.028448 -57.675018)
		(end 127.022098 -57.685686)
		(width 0.0889)
		(layer "B.Cu")
		(net "UPI_CPU0_CPU1_P1P1_DP<14>")
	)
	(segment
		(start 163.350194 -32.732218)
		(end 160.922462 -33.30702)
		(width 0.1143)
		(layer "B.Cu")
		(net "UPI_CPU0_CPU1_P1P1_DP<14>")
	)
	(segment
		(start 189.55766 -31.456884)
		(end 184.04332 -29.693108)
		(width 0.1143)
		(layer "B.Cu")
		(net "UPI_CPU0_CPU1_P1P1_DP<14>")
	)
	(segment
		(start 157.264608 -34.471864)
		(end 155.21559 -34.727388)
		(width 0.1143)
		(layer "B.Cu")
		(net "UPI_CPU0_CPU1_P1P1_DP<14>")
	)
	(segment
		(start 302.75149 -47.20844)
		(end 302.63338 -47.126398)
		(width 0.1143)
		(layer "B.Cu")
		(net "UPI_CPU0_CPU1_P1P1_DP<14>")
	)
	(segment
		(start 126.07417 -51.29657)
		(end 126.07417 -51.63947)
		(width 0.1143)
		(layer "B.Cu")
		(net "UPI_CPU0_CPU1_P1P1_DP<14>")
	)
	(segment
		(start 125.250702 -53.72862)
		(end 125.250702 -56.134508)
		(width 0.0889)
		(layer "B.Cu")
		(net "UPI_CPU0_CPU1_P1P1_DP<14>")
	)
	(segment
		(start 129.80289 -44.59097)
		(end 125.97257 -48.42129)
		(width 0.1143)
		(layer "B.Cu")
		(net "UPI_CPU0_CPU1_P1P1_DP<14>")
	)
	(segment
		(start 301.96282 -42.83329)
		(end 301.84471 -42.751248)
		(width 0.1143)
		(layer "B.Cu")
		(net "UPI_CPU0_CPU1_P1P1_DP<14>")
	)
	(segment
		(start 302.39462 -50.851562)
		(end 302.373792 -50.822098)
		(width 0.0889)
		(layer "B.Cu")
		(net "UPI_CPU0_CPU1_P1P1_DP<14>")
	)
	(segment
		(start 302.414686 -45.913802)
		(end 302.496728 -45.795692)
		(width 0.1143)
		(layer "B.Cu")
		(net "UPI_CPU0_CPU1_P1P1_DP<14>")
	)
	(segment
		(start 237.4519 -34.709354)
		(end 236.886242 -34.646108)
		(width 0.1143)
		(layer "B.Cu")
		(net "UPI_CPU0_CPU1_P1P1_DP<14>")
	)
	(segment
		(start 302.002444 -43.626278)
		(end 301.941738 -43.288458)
		(width 0.1143)
		(layer "B.Cu")
		(net "UPI_CPU0_CPU1_P1P1_DP<14>")
	)
	(segment
		(start 167.503094 -32.9692)
		(end 165.659308 -33.19399)
		(width 0.1143)
		(layer "B.Cu")
		(net "UPI_CPU0_CPU1_P1P1_DP<14>")
	)
	(segment
		(start 301.84471 -42.751248)
		(end 301.784004 -42.413428)
		(width 0.1143)
		(layer "B.Cu")
		(net "UPI_CPU0_CPU1_P1P1_DP<14>")
	)
	(segment
		(start 197.216014 -31.356554)
		(end 196.234558 -31.191454)
		(width 0.1143)
		(layer "B.Cu")
		(net "UPI_CPU0_CPU1_P1P1_DP<14>")
	)
	(segment
		(start 302.120554 -43.70832)
		(end 302.002444 -43.626278)
		(width 0.1143)
		(layer "B.Cu")
		(net "UPI_CPU0_CPU1_P1P1_DP<14>")
	)
	(segment
		(start 302.627284 -55.78348)
		(end 302.217582 -55.293006)
		(width 0.0889)
		(layer "B.Cu")
		(net "UPI_CPU0_CPU1_P1P1_DP<14>")
	)
	(segment
		(start 302.496728 -45.795692)
		(end 302.436022 -45.45838)
		(width 0.1143)
		(layer "B.Cu")
		(net "UPI_CPU0_CPU1_P1P1_DP<14>")
	)
	(segment
		(start 125.97257 -50.85207)
		(end 125.97257 -51.19497)
		(width 0.1143)
		(layer "B.Cu")
		(net "UPI_CPU0_CPU1_P1P1_DP<14>")
	)
	(segment
		(start 137.621772 -37.237924)
		(end 132.375656 -40.776652)
		(width 0.1143)
		(layer "B.Cu")
		(net "UPI_CPU0_CPU1_P1P1_DP<14>")
	)
	(segment
		(start 225.290634 -37.095938)
		(end 225.012758 -37.029644)
		(width 0.1143)
		(layer "B.Cu")
		(net "UPI_CPU0_CPU1_P1P1_DP<14>")
	)
	(segment
		(start 302.090328 -52.117752)
		(end 302.08601 -51.898804)
		(width 0.0889)
		(layer "B.Cu")
		(net "UPI_CPU0_CPU1_P1P1_DP<14>")
	)
	(segment
		(start 302.278288 -44.58335)
		(end 302.160178 -44.501308)
		(width 0.1143)
		(layer "B.Cu")
		(net "UPI_CPU0_CPU1_P1P1_DP<14>")
	)
	(segment
		(start 132.334 -40.838374)
		(end 129.80289 -44.59097)
		(width 0.1143)
		(layer "B.Cu")
		(net "UPI_CPU0_CPU1_P1P1_DP<14>")
	)
	(segment
		(start 125.97257 -52.106068)
		(end 125.94717 -52.131468)
		(width 0.0889)
		(layer "B.Cu")
		(net "UPI_CPU0_CPU1_P1P1_DP<14>")
	)
	(segment
		(start 302.427894 -50.520854)
		(end 302.429672 -50.511964)
		(width 0.1143)
		(layer "B.Cu")
		(net "UPI_CPU0_CPU1_P1P1_DP<14>")
	)
	(segment
		(start 302.909224 -48.08347)
		(end 302.791114 -48.001428)
		(width 0.1143)
		(layer "B.Cu")
		(net "UPI_CPU0_CPU1_P1P1_DP<14>")
	)
	(segment
		(start 248.34977 -32.468058)
		(end 238.573564 -34.415476)
		(width 0.1143)
		(layer "B.Cu")
		(net "UPI_CPU0_CPU1_P1P1_DP<14>")
	)
	(segment
		(start 291.195506 -35.05835)
		(end 289.790124 -35.276536)
		(width 0.1143)
		(layer "B.Cu")
		(net "UPI_CPU0_CPU1_P1P1_DP<14>")
	)
	(segment
		(start 165.659308 -33.19399)
		(end 163.350194 -32.732218)
		(width 0.1143)
		(layer "B.Cu")
		(net "UPI_CPU0_CPU1_P1P1_DP<14>")
	)
	(segment
		(start 256.30505 -32.520636)
		(end 252.459744 -32.777176)
		(width 0.1143)
		(layer "B.Cu")
		(net "UPI_CPU0_CPU1_P1P1_DP<14>")
	)
	(segment
		(start 302.08601 -51.898804)
		(end 302.261016 -51.594766)
		(width 0.0889)
		(layer "B.Cu")
		(net "UPI_CPU0_CPU1_P1P1_DP<14>")
	)
	(segment
		(start 302.373792 -50.822098)
		(end 302.377602 -50.800254)
		(width 0.0889)
		(layer "B.Cu")
		(net "UPI_CPU0_CPU1_P1P1_DP<14>")
	)
	(segment
		(start 125.97257 -51.74107)
		(end 125.97257 -52.08397)
		(width 0.1143)
		(layer "B.Cu")
		(net "UPI_CPU0_CPU1_P1P1_DP<14>")
	)
	(segment
		(start 127.075692 -58.054748)
		(end 127.368808 -57.885584)
		(width 0.0889)
		(layer "B.Cu")
		(net "UPI_CPU0_CPU1_P1P1_DP<14>")
	)
	(segment
		(start 302.261016 -51.594766)
		(end 302.39462 -50.851562)
		(width 0.0889)
		(layer "B.Cu")
		(net "UPI_CPU0_CPU1_P1P1_DP<14>")
	)
	(segment
		(start 125.94717 -53.032152)
		(end 125.250702 -53.72862)
		(width 0.0889)
		(layer "B.Cu")
		(net "UPI_CPU0_CPU1_P1P1_DP<14>")
	)
	(segment
		(start 302.96993 -48.420782)
		(end 302.909224 -48.08347)
		(width 0.1143)
		(layer "B.Cu")
		(net "UPI_CPU0_CPU1_P1P1_DP<14>")
	)
	(segment
		(start 126.499112 -56.799988)
		(end 126.531878 -56.799988)
		(width 0.0889)
		(layer "B.Cu")
		(net "UPI_CPU0_CPU1_P1P1_DP<14>")
	)
	(segment
		(start 236.886242 -34.646108)
		(end 225.290634 -37.095938)
		(width 0.1143)
		(layer "B.Cu")
		(net "UPI_CPU0_CPU1_P1P1_DP<14>")
	)
	(segment
		(start 302.153066 -54.629304)
		(end 302.159416 -54.618636)
		(width 0.0889)
		(layer "B.Cu")
		(net "UPI_CPU0_CPU1_P1P1_DP<14>")
	)
	(segment
		(start 125.94717 -52.131468)
		(end 125.94717 -53.032152)
		(width 0.0889)
		(layer "B.Cu")
		(net "UPI_CPU0_CPU1_P1P1_DP<14>")
	)
	(segment
		(start 302.812196 -47.545752)
		(end 302.75149 -47.20844)
		(width 0.1143)
		(layer "B.Cu")
		(net "UPI_CPU0_CPU1_P1P1_DP<14>")
	)
	(segment
		(start 207.88503 -33.391094)
		(end 197.216014 -31.356554)
		(width 0.1143)
		(layer "B.Cu")
		(net "UPI_CPU0_CPU1_P1P1_DP<14>")
	)
	(segment
		(start 125.97257 -51.19497)
		(end 126.07417 -51.29657)
		(width 0.1143)
		(layer "B.Cu")
		(net "UPI_CPU0_CPU1_P1P1_DP<14>")
	)
	(segment
		(start 125.420628 -56.304434)
		(end 125.669548 -56.304434)
		(width 0.0889)
		(layer "B.Cu")
		(net "UPI_CPU0_CPU1_P1P1_DP<14>")
	)
	(segment
		(start 155.21559 -34.727388)
		(end 152.655524 -34.24047)
		(width 0.1143)
		(layer "B.Cu")
		(net "UPI_CPU0_CPU1_P1P1_DP<14>")
	)
	(segment
		(start 302.63338 -47.126398)
		(end 302.57242 -46.788832)
		(width 0.1143)
		(layer "B.Cu")
		(net "UPI_CPU0_CPU1_P1P1_DP<14>")
	)
	(segment
		(start 225.012758 -37.029644)
		(end 211.351622 -34.185606)
		(width 0.1143)
		(layer "B.Cu")
		(net "UPI_CPU0_CPU1_P1P1_DP<14>")
	)
	(segment
		(start 301.658274 -41.140888)
		(end 296.362374 -36.500308)
		(width 0.1143)
		(layer "B.Cu")
		(net "UPI_CPU0_CPU1_P1P1_DP<14>")
	)
	(segment
		(start 289.790124 -35.276536)
		(end 279.936956 -37.247576)
		(width 0.1143)
		(layer "B.Cu")
		(net "UPI_CPU0_CPU1_P1P1_DP<14>")
	)
	(segment
		(start 126.07417 -51.63947)
		(end 125.97257 -51.74107)
		(width 0.1143)
		(layer "B.Cu")
		(net "UPI_CPU0_CPU1_P1P1_DP<14>")
	)
	(segment
		(start 159.59328 -33.386014)
		(end 157.264608 -34.471864)
		(width 0.1143)
		(layer "B.Cu")
		(net "UPI_CPU0_CPU1_P1P1_DP<14>")
	)
	(arc
		(start 302.159416 -54.218586)
		(mid 302.080285 -53.923184)
		(end 302.159416 -53.627782)
		(width 0.0889)
		(layer "B.Cu")
		(net "UPI_CPU0_CPU1_P1P1_DP<14>")
	)
	(arc
		(start 302.164242 -54.61)
		(mid 302.212997 -54.413648)
		(end 302.159416 -54.218586)
		(width 0.0889)
		(layer "B.Cu")
		(net "UPI_CPU0_CPU1_P1P1_DP<14>")
	)
	(arc
		(start 126.531878 -56.799988)
		(mid 127.024268 -57.098921)
		(end 127.028448 -57.675018)
		(width 0.0889)
		(layer "B.Cu")
		(net "UPI_CPU0_CPU1_P1P1_DP<14>")
	)
	(arc
		(start 302.159416 -53.627782)
		(mid 302.212915 -53.427884)
		(end 302.159416 -53.227986)
		(width 0.0889)
		(layer "B.Cu")
		(net "UPI_CPU0_CPU1_P1P1_DP<14>")
	)
	(arc
		(start 126.163578 -56.599836)
		(mid 126.305261 -56.74364)
		(end 126.499112 -56.799988)
		(width 0.0889)
		(layer "B.Cu")
		(net "UPI_CPU0_CPU1_P1P1_DP<14>")
	)
	(arc
		(start 302.217582 -55.293006)
		(mid 302.082881 -54.971133)
		(end 302.153066 -54.629304)
		(width 0.0889)
		(layer "B.Cu")
		(net "UPI_CPU0_CPU1_P1P1_DP<14>")
	)
	(arc
		(start 302.153066 -53.217318)
		(mid 302.080268 -52.926555)
		(end 302.159416 -52.637436)
		(width 0.0889)
		(layer "B.Cu")
		(net "UPI_CPU0_CPU1_P1P1_DP<14>")
	)
	(arc
		(start 125.669548 -56.304434)
		(mid 125.954972 -56.387901)
		(end 126.163578 -56.599836)
		(width 0.0889)
		(layer "B.Cu")
		(net "UPI_CPU0_CPU1_P1P1_DP<14>")
	)
	(arc
		(start 302.164242 -52.6288)
		(mid 302.212997 -52.432448)
		(end 302.159416 -52.237386)
		(width 0.0889)
		(layer "B.Cu")
		(net "UPI_CPU0_CPU1_P1P1_DP<14>")
	)
	(arc
		(start 302.671226 -55.904384)
		(mid 302.659908 -55.840057)
		(end 302.627284 -55.78348)
		(width 0.0889)
		(layer "B.Cu")
		(net "UPI_CPU0_CPU1_P1P1_DP<14>")
	)
	(arc
		(start 127.017272 -57.694322)
		(mid 126.969359 -57.861607)
		(end 126.996952 -58.033412)
		(width 0.0889)
		(layer "B.Cu")
		(net "UPI_CPU0_CPU1_P1P1_DP<14>")
	)
	(segment
		(start 127.655828 -60.362338)
		(end 128.227328 -60.362338)
		(width 0.1143)
		(layer "F.Cu")
		(net "UPI_CPU0_CPU1_P1P1_DP<13>")
	)
	(segment
		(start 301.241206 -55.409338)
		(end 301.812706 -55.409338)
		(width 0.1143)
		(layer "F.Cu")
		(net "UPI_CPU0_CPU1_P1P1_DP<13>")
	)
	(via
		(at 128.227328 -60.362338)
		(size 0.508)
		(drill 0.254)
		(layers "F.Cu" "B.Cu")
		(net "UPI_CPU0_CPU1_P1P1_DP<13>")
	)
	(via
		(at 301.812706 -55.409338)
		(size 0.508)
		(drill 0.254)
		(layers "F.Cu" "B.Cu")
		(net "UPI_CPU0_CPU1_P1P1_DP<13>")
	)
	(segment
		(start 295.645332 -37.005006)
		(end 300.647354 -41.50487)
		(width 0.1143)
		(layer "B.Cu")
		(net "UPI_CPU0_CPU1_P1P1_DP<13>")
	)
	(segment
		(start 169.04716 -33.517586)
		(end 170.9166 -33.2486)
		(width 0.1143)
		(layer "B.Cu")
		(net "UPI_CPU0_CPU1_P1P1_DP<13>")
	)
	(segment
		(start 301.77105 -50.080926)
		(end 301.769272 -50.103024)
		(width 0.0889)
		(layer "B.Cu")
		(net "UPI_CPU0_CPU1_P1P1_DP<13>")
	)
	(segment
		(start 279.937464 -37.98697)
		(end 291.276786 -35.718496)
		(width 0.1143)
		(layer "B.Cu")
		(net "UPI_CPU0_CPU1_P1P1_DP<13>")
	)
	(segment
		(start 196.620892 -31.79953)
		(end 207.949038 -34.064956)
		(width 0.1143)
		(layer "B.Cu")
		(net "UPI_CPU0_CPU1_P1P1_DP<13>")
	)
	(segment
		(start 126.941072 -52.220876)
		(end 126.915672 -52.195476)
		(width 0.0889)
		(layer "B.Cu")
		(net "UPI_CPU0_CPU1_P1P1_DP<13>")
	)
	(segment
		(start 126.915672 -48.718978)
		(end 130.694938 -44.939458)
		(width 0.1143)
		(layer "B.Cu")
		(net "UPI_CPU0_CPU1_P1P1_DP<13>")
	)
	(segment
		(start 301.720758 -50.382678)
		(end 301.620174 -50.779426)
		(width 0.0889)
		(layer "B.Cu")
		(net "UPI_CPU0_CPU1_P1P1_DP<13>")
	)
	(segment
		(start 301.472346 -53.217318)
		(end 301.465996 -53.227986)
		(width 0.0889)
		(layer "B.Cu")
		(net "UPI_CPU0_CPU1_P1P1_DP<13>")
	)
	(segment
		(start 126.915672 -52.195476)
		(end 126.915672 -52.173378)
		(width 0.0889)
		(layer "B.Cu")
		(net "UPI_CPU0_CPU1_P1P1_DP<13>")
	)
	(segment
		(start 187.919106 -31.690818)
		(end 189.585854 -32.264858)
		(width 0.1143)
		(layer "B.Cu")
		(net "UPI_CPU0_CPU1_P1P1_DP<13>")
	)
	(segment
		(start 128.227328 -60.362338)
		(end 128.523238 -59.685682)
		(width 0.0889)
		(layer "B.Cu")
		(net "UPI_CPU0_CPU1_P1P1_DP<13>")
	)
	(segment
		(start 189.585854 -32.264858)
		(end 196.620892 -31.79953)
		(width 0.1143)
		(layer "B.Cu")
		(net "UPI_CPU0_CPU1_P1P1_DP<13>")
	)
	(segment
		(start 238.414814 -35.01136)
		(end 248.27865 -33.038542)
		(width 0.1143)
		(layer "B.Cu")
		(net "UPI_CPU0_CPU1_P1P1_DP<13>")
	)
	(segment
		(start 160.036256 -34.24555)
		(end 163.610544 -33.531302)
		(width 0.1143)
		(layer "B.Cu")
		(net "UPI_CPU0_CPU1_P1P1_DP<13>")
	)
	(segment
		(start 153.284682 -35.112198)
		(end 155.111196 -35.469322)
		(width 0.1143)
		(layer "B.Cu")
		(net "UPI_CPU0_CPU1_P1P1_DP<13>")
	)
	(segment
		(start 222.396812 -37.286438)
		(end 225.356928 -37.878512)
		(width 0.1143)
		(layer "B.Cu")
		(net "UPI_CPU0_CPU1_P1P1_DP<13>")
	)
	(segment
		(start 130.694938 -44.939458)
		(end 132.941568 -41.60901)
		(width 0.1143)
		(layer "B.Cu")
		(net "UPI_CPU0_CPU1_P1P1_DP<13>")
	)
	(segment
		(start 155.111196 -35.469322)
		(end 157.407356 -35.203384)
		(width 0.1143)
		(layer "B.Cu")
		(net "UPI_CPU0_CPU1_P1P1_DP<13>")
	)
	(segment
		(start 291.276786 -35.718496)
		(end 295.645332 -37.005006)
		(width 0.1143)
		(layer "B.Cu")
		(net "UPI_CPU0_CPU1_P1P1_DP<13>")
	)
	(segment
		(start 127.379984 -56.494934)
		(end 127.347218 -56.494934)
		(width 0.0889)
		(layer "B.Cu")
		(net "UPI_CPU0_CPU1_P1P1_DP<13>")
	)
	(segment
		(start 252.634242 -33.572196)
		(end 256.303526 -33.259522)
		(width 0.1143)
		(layer "B.Cu")
		(net "UPI_CPU0_CPU1_P1P1_DP<13>")
	)
	(segment
		(start 211.243672 -35.056064)
		(end 222.396812 -37.286438)
		(width 0.1143)
		(layer "B.Cu")
		(net "UPI_CPU0_CPU1_P1P1_DP<13>")
	)
	(segment
		(start 127.001524 -53.154834)
		(end 126.941072 -52.60467)
		(width 0.0889)
		(layer "B.Cu")
		(net "UPI_CPU0_CPU1_P1P1_DP<13>")
	)
	(segment
		(start 237.973108 -35.306)
		(end 238.414814 -35.01136)
		(width 0.1143)
		(layer "B.Cu")
		(net "UPI_CPU0_CPU1_P1P1_DP<13>")
	)
	(segment
		(start 126.941072 -52.60467)
		(end 126.941072 -52.220876)
		(width 0.0889)
		(layer "B.Cu")
		(net "UPI_CPU0_CPU1_P1P1_DP<13>")
	)
	(segment
		(start 128.245362 -58.971688)
		(end 128.205738 -58.971688)
		(width 0.0889)
		(layer "B.Cu")
		(net "UPI_CPU0_CPU1_P1P1_DP<13>")
	)
	(segment
		(start 150.910544 -35.616388)
		(end 153.284682 -35.112198)
		(width 0.1143)
		(layer "B.Cu")
		(net "UPI_CPU0_CPU1_P1P1_DP<13>")
	)
	(segment
		(start 301.917608 -48.303434)
		(end 301.77105 -50.080926)
		(width 0.1143)
		(layer "B.Cu")
		(net "UPI_CPU0_CPU1_P1P1_DP<13>")
	)
	(segment
		(start 166.19982 -34.009076)
		(end 169.04716 -33.517586)
		(width 0.1143)
		(layer "B.Cu")
		(net "UPI_CPU0_CPU1_P1P1_DP<13>")
	)
	(segment
		(start 301.46117 -52.6288)
		(end 301.465996 -52.637436)
		(width 0.0889)
		(layer "B.Cu")
		(net "UPI_CPU0_CPU1_P1P1_DP<13>")
	)
	(segment
		(start 163.610544 -33.531302)
		(end 166.099744 -34.029142)
		(width 0.1143)
		(layer "B.Cu")
		(net "UPI_CPU0_CPU1_P1P1_DP<13>")
	)
	(segment
		(start 157.407356 -35.203384)
		(end 159.437578 -34.288476)
		(width 0.1143)
		(layer "B.Cu")
		(net "UPI_CPU0_CPU1_P1P1_DP<13>")
	)
	(segment
		(start 301.44085 -55.556912)
		(end 301.51959 -55.578248)
		(width 0.0889)
		(layer "B.Cu")
		(net "UPI_CPU0_CPU1_P1P1_DP<13>")
	)
	(segment
		(start 138.29284 -37.99967)
		(end 150.910544 -35.616388)
		(width 0.1143)
		(layer "B.Cu")
		(net "UPI_CPU0_CPU1_P1P1_DP<13>")
	)
	(segment
		(start 172.83303 -33.187132)
		(end 183.645556 -30.36189)
		(width 0.1143)
		(layer "B.Cu")
		(net "UPI_CPU0_CPU1_P1P1_DP<13>")
	)
	(segment
		(start 166.099744 -34.029142)
		(end 166.19982 -34.009076)
		(width 0.1143)
		(layer "B.Cu")
		(net "UPI_CPU0_CPU1_P1P1_DP<13>")
	)
	(segment
		(start 301.769272 -50.103024)
		(end 301.74184 -50.126138)
		(width 0.0889)
		(layer "B.Cu")
		(net "UPI_CPU0_CPU1_P1P1_DP<13>")
	)
	(segment
		(start 126.899416 -53.56098)
		(end 127.001524 -53.428646)
		(width 0.0889)
		(layer "B.Cu")
		(net "UPI_CPU0_CPU1_P1P1_DP<13>")
	)
	(segment
		(start 301.465996 -54.618636)
		(end 301.472346 -54.629304)
		(width 0.0889)
		(layer "B.Cu")
		(net "UPI_CPU0_CPU1_P1P1_DP<13>")
	)
	(segment
		(start 208.839054 -34.429192)
		(end 208.839562 -34.429192)
		(width 0.1143)
		(layer "B.Cu")
		(net "UPI_CPU0_CPU1_P1P1_DP<13>")
	)
	(segment
		(start 248.27865 -33.038542)
		(end 252.634242 -33.572196)
		(width 0.1143)
		(layer "B.Cu")
		(net "UPI_CPU0_CPU1_P1P1_DP<13>")
	)
	(segment
		(start 126.856998 -54.218586)
		(end 126.832614 -54.176168)
		(width 0.0889)
		(layer "B.Cu")
		(net "UPI_CPU0_CPU1_P1P1_DP<13>")
	)
	(segment
		(start 159.437578 -34.288476)
		(end 160.036256 -34.24555)
		(width 0.1143)
		(layer "B.Cu")
		(net "UPI_CPU0_CPU1_P1P1_DP<13>")
	)
	(segment
		(start 225.356928 -37.878512)
		(end 237.867698 -35.376358)
		(width 0.1143)
		(layer "B.Cu")
		(net "UPI_CPU0_CPU1_P1P1_DP<13>")
	)
	(segment
		(start 301.74184 -50.126138)
		(end 301.720758 -50.382678)
		(width 0.0889)
		(layer "B.Cu")
		(net "UPI_CPU0_CPU1_P1P1_DP<13>")
	)
	(segment
		(start 207.949038 -34.064956)
		(end 208.839054 -34.429192)
		(width 0.1143)
		(layer "B.Cu")
		(net "UPI_CPU0_CPU1_P1P1_DP<13>")
	)
	(segment
		(start 301.46117 -54.61)
		(end 301.465996 -54.618636)
		(width 0.0889)
		(layer "B.Cu")
		(net "UPI_CPU0_CPU1_P1P1_DP<13>")
	)
	(segment
		(start 301.620174 -50.779426)
		(end 301.433484 -51.239674)
		(width 0.0889)
		(layer "B.Cu")
		(net "UPI_CPU0_CPU1_P1P1_DP<13>")
	)
	(segment
		(start 170.9166 -33.2486)
		(end 172.83303 -33.187132)
		(width 0.1143)
		(layer "B.Cu")
		(net "UPI_CPU0_CPU1_P1P1_DP<13>")
	)
	(segment
		(start 183.645556 -30.36189)
		(end 187.919106 -31.690818)
		(width 0.1143)
		(layer "B.Cu")
		(net "UPI_CPU0_CPU1_P1P1_DP<13>")
	)
	(segment
		(start 126.525274 -55.999888)
		(end 126.492508 -55.999888)
		(width 0.0889)
		(layer "B.Cu")
		(net "UPI_CPU0_CPU1_P1P1_DP<13>")
	)
	(segment
		(start 127.001524 -53.428646)
		(end 127.001524 -53.154834)
		(width 0.0889)
		(layer "B.Cu")
		(net "UPI_CPU0_CPU1_P1P1_DP<13>")
	)
	(segment
		(start 127.715518 -57.685686)
		(end 127.709168 -57.675018)
		(width 0.0889)
		(layer "B.Cu")
		(net "UPI_CPU0_CPU1_P1P1_DP<13>")
	)
	(segment
		(start 237.867698 -35.376358)
		(end 237.973108 -35.306)
		(width 0.1143)
		(layer "B.Cu")
		(net "UPI_CPU0_CPU1_P1P1_DP<13>")
	)
	(segment
		(start 208.839562 -34.429192)
		(end 209.730086 -34.793682)
		(width 0.1143)
		(layer "B.Cu")
		(net "UPI_CPU0_CPU1_P1P1_DP<13>")
	)
	(segment
		(start 300.647354 -41.50487)
		(end 301.917608 -48.303434)
		(width 0.1143)
		(layer "B.Cu")
		(net "UPI_CPU0_CPU1_P1P1_DP<13>")
	)
	(segment
		(start 301.509684 -52.161948)
		(end 301.465996 -52.237386)
		(width 0.0889)
		(layer "B.Cu")
		(net "UPI_CPU0_CPU1_P1P1_DP<13>")
	)
	(segment
		(start 126.488698 -54.818788)
		(end 126.521464 -54.818788)
		(width 0.0889)
		(layer "B.Cu")
		(net "UPI_CPU0_CPU1_P1P1_DP<13>")
	)
	(segment
		(start 132.941568 -41.60901)
		(end 138.29284 -37.99967)
		(width 0.1143)
		(layer "B.Cu")
		(net "UPI_CPU0_CPU1_P1P1_DP<13>")
	)
	(segment
		(start 256.303526 -33.259522)
		(end 279.937464 -37.98697)
		(width 0.1143)
		(layer "B.Cu")
		(net "UPI_CPU0_CPU1_P1P1_DP<13>")
	)
	(segment
		(start 127.720344 -57.694322)
		(end 127.715518 -57.685686)
		(width 0.0889)
		(layer "B.Cu")
		(net "UPI_CPU0_CPU1_P1P1_DP<13>")
	)
	(segment
		(start 126.915672 -52.173378)
		(end 126.915672 -48.718978)
		(width 0.1143)
		(layer "B.Cu")
		(net "UPI_CPU0_CPU1_P1P1_DP<13>")
	)
	(segment
		(start 301.51959 -55.578248)
		(end 301.812706 -55.409338)
		(width 0.0889)
		(layer "B.Cu")
		(net "UPI_CPU0_CPU1_P1P1_DP<13>")
	)
	(segment
		(start 209.730086 -34.793682)
		(end 211.243672 -35.056064)
		(width 0.1143)
		(layer "B.Cu")
		(net "UPI_CPU0_CPU1_P1P1_DP<13>")
	)
	(arc
		(start 126.521464 -54.818788)
		(mid 126.859633 -54.61399)
		(end 126.856998 -54.218586)
		(width 0.0889)
		(layer "B.Cu")
		(net "UPI_CPU0_CPU1_P1P1_DP<13>")
	)
	(arc
		(start 301.433484 -51.239674)
		(mid 301.402775 -51.439729)
		(end 301.46498 -51.632358)
		(width 0.0889)
		(layer "B.Cu")
		(net "UPI_CPU0_CPU1_P1P1_DP<13>")
	)
	(arc
		(start 301.465996 -52.237386)
		(mid 301.412526 -52.432449)
		(end 301.46117 -52.6288)
		(width 0.0889)
		(layer "B.Cu")
		(net "UPI_CPU0_CPU1_P1P1_DP<13>")
	)
	(arc
		(start 128.523238 -59.685682)
		(mid 128.545615 -59.627189)
		(end 128.574038 -59.571382)
		(width 0.0889)
		(layer "B.Cu")
		(net "UPI_CPU0_CPU1_P1P1_DP<13>")
	)
	(arc
		(start 128.205738 -58.971688)
		(mid 127.710261 -58.667245)
		(end 127.715518 -58.085736)
		(width 0.0889)
		(layer "B.Cu")
		(net "UPI_CPU0_CPU1_P1P1_DP<13>")
	)
	(arc
		(start 127.709168 -57.675018)
		(mid 127.63637 -57.384255)
		(end 127.715518 -57.095136)
		(width 0.0889)
		(layer "B.Cu")
		(net "UPI_CPU0_CPU1_P1P1_DP<13>")
	)
	(arc
		(start 301.465996 -55.209186)
		(mid 301.424909 -55.310292)
		(end 301.412656 -55.418736)
		(width 0.0889)
		(layer "B.Cu")
		(net "UPI_CPU0_CPU1_P1P1_DP<13>")
	)
	(arc
		(start 126.492508 -55.999888)
		(mid 125.919473 -55.411242)
		(end 126.488698 -54.818788)
		(width 0.0889)
		(layer "B.Cu")
		(net "UPI_CPU0_CPU1_P1P1_DP<13>")
	)
	(arc
		(start 127.715518 -57.095136)
		(mid 127.718266 -56.699669)
		(end 127.379984 -56.494934)
		(width 0.0889)
		(layer "B.Cu")
		(net "UPI_CPU0_CPU1_P1P1_DP<13>")
	)
	(arc
		(start 301.412656 -55.418736)
		(mid 301.420611 -55.489078)
		(end 301.44085 -55.556912)
		(width 0.0889)
		(layer "B.Cu")
		(net "UPI_CPU0_CPU1_P1P1_DP<13>")
	)
	(arc
		(start 301.465996 -52.637436)
		(mid 301.545218 -52.926554)
		(end 301.472346 -53.217318)
		(width 0.0889)
		(layer "B.Cu")
		(net "UPI_CPU0_CPU1_P1P1_DP<13>")
	)
	(arc
		(start 127.715518 -58.085736)
		(mid 127.768988 -57.890673)
		(end 127.720344 -57.694322)
		(width 0.0889)
		(layer "B.Cu")
		(net "UPI_CPU0_CPU1_P1P1_DP<13>")
	)
	(arc
		(start 301.465996 -53.627782)
		(mid 301.545127 -53.923184)
		(end 301.465996 -54.218586)
		(width 0.0889)
		(layer "B.Cu")
		(net "UPI_CPU0_CPU1_P1P1_DP<13>")
	)
	(arc
		(start 126.832614 -54.176168)
		(mid 126.779395 -53.85917)
		(end 126.899416 -53.56098)
		(width 0.0889)
		(layer "B.Cu")
		(net "UPI_CPU0_CPU1_P1P1_DP<13>")
	)
	(arc
		(start 128.574038 -59.571382)
		(mid 128.578283 -59.179137)
		(end 128.245362 -58.971688)
		(width 0.0889)
		(layer "B.Cu")
		(net "UPI_CPU0_CPU1_P1P1_DP<13>")
	)
	(arc
		(start 301.472346 -54.629304)
		(mid 301.545144 -54.920067)
		(end 301.465996 -55.209186)
		(width 0.0889)
		(layer "B.Cu")
		(net "UPI_CPU0_CPU1_P1P1_DP<13>")
	)
	(arc
		(start 301.465996 -54.218586)
		(mid 301.412526 -54.413649)
		(end 301.46117 -54.61)
		(width 0.0889)
		(layer "B.Cu")
		(net "UPI_CPU0_CPU1_P1P1_DP<13>")
	)
	(arc
		(start 301.465996 -53.227986)
		(mid 301.412497 -53.427884)
		(end 301.465996 -53.627782)
		(width 0.0889)
		(layer "B.Cu")
		(net "UPI_CPU0_CPU1_P1P1_DP<13>")
	)
	(arc
		(start 126.856998 -56.199786)
		(mid 126.716919 -56.05705)
		(end 126.525274 -55.999888)
		(width 0.0889)
		(layer "B.Cu")
		(net "UPI_CPU0_CPU1_P1P1_DP<13>")
	)
	(arc
		(start 127.347218 -56.494934)
		(mid 127.064001 -56.410653)
		(end 126.856998 -56.199786)
		(width 0.0889)
		(layer "B.Cu")
		(net "UPI_CPU0_CPU1_P1P1_DP<13>")
	)
	(arc
		(start 301.46498 -51.632358)
		(mid 301.549504 -51.891913)
		(end 301.509684 -52.161948)
		(width 0.0889)
		(layer "B.Cu")
		(net "UPI_CPU0_CPU1_P1P1_DP<13>")
	)
	(segment
		(start 129.372868 -59.371484)
		(end 129.944368 -59.371484)
		(width 0.1143)
		(layer "F.Cu")
		(net "UPI_CPU0_CPU1_P1P1_DP<12>")
	)
	(segment
		(start 300.382686 -53.923184)
		(end 300.954186 -53.923184)
		(width 0.1143)
		(layer "F.Cu")
		(net "UPI_CPU0_CPU1_P1P1_DP<12>")
	)
	(via
		(at 164.996114 -35.069018)
		(size 0.508)
		(drill 0.254)
		(layers "F.Cu" "B.Cu")
		(net "UPI_CPU0_CPU1_P1P1_DP<12>")
	)
	(via
		(at 300.954186 -53.923184)
		(size 0.508)
		(drill 0.254)
		(layers "F.Cu" "B.Cu")
		(net "UPI_CPU0_CPU1_P1P1_DP<12>")
	)
	(via
		(at 129.944368 -59.371484)
		(size 0.508)
		(drill 0.254)
		(layers "F.Cu" "B.Cu")
		(net "UPI_CPU0_CPU1_P1P1_DP<12>")
	)
	(segment
		(start 154.769058 -36.645342)
		(end 153.640536 -36.426394)
		(width 0.1143)
		(layer "B.Cu")
		(net "UPI_CPU0_CPU1_P1P1_DP<12>")
	)
	(segment
		(start 297.972988 -41.461944)
		(end 298.116752 -41.467278)
		(width 0.1143)
		(layer "B.Cu")
		(net "UPI_CPU0_CPU1_P1P1_DP<12>")
	)
	(segment
		(start 159.870648 -35.535362)
		(end 159.759396 -35.554666)
		(width 0.1143)
		(layer "B.Cu")
		(net "UPI_CPU0_CPU1_P1P1_DP<12>")
	)
	(segment
		(start 173.742858 -34.382456)
		(end 173.782228 -34.37509)
		(width 0.1143)
		(layer "B.Cu")
		(net "UPI_CPU0_CPU1_P1P1_DP<12>")
	)
	(segment
		(start 189.005464 -33.349184)
		(end 196.763132 -32.871918)
		(width 0.1143)
		(layer "B.Cu")
		(net "UPI_CPU0_CPU1_P1P1_DP<12>")
	)
	(segment
		(start 299.269404 -43.977814)
		(end 299.356018 -44.309792)
		(width 0.1143)
		(layer "B.Cu")
		(net "UPI_CPU0_CPU1_P1P1_DP<12>")
	)
	(segment
		(start 128.745488 -56.684418)
		(end 128.739138 -56.695086)
		(width 0.0889)
		(layer "B.Cu")
		(net "UPI_CPU0_CPU1_P1P1_DP<12>")
	)
	(segment
		(start 300.029626 -46.890686)
		(end 300.153832 -46.96333)
		(width 0.1143)
		(layer "B.Cu")
		(net "UPI_CPU0_CPU1_P1P1_DP<12>")
	)
	(segment
		(start 128.745488 -57.675018)
		(end 128.739138 -57.685686)
		(width 0.0889)
		(layer "B.Cu")
		(net "UPI_CPU0_CPU1_P1P1_DP<12>")
	)
	(segment
		(start 299.580554 -45.17009)
		(end 299.70476 -45.242734)
		(width 0.1143)
		(layer "B.Cu")
		(net "UPI_CPU0_CPU1_P1P1_DP<12>")
	)
	(segment
		(start 209.697066 -36.137342)
		(end 210.952334 -36.233354)
		(width 0.1143)
		(layer "B.Cu")
		(net "UPI_CPU0_CPU1_P1P1_DP<12>")
	)
	(segment
		(start 128.739138 -57.685686)
		(end 128.734312 -57.694322)
		(width 0.0889)
		(layer "B.Cu")
		(net "UPI_CPU0_CPU1_P1P1_DP<12>")
	)
	(segment
		(start 210.974432 -36.236656)
		(end 222.396812 -38.521386)
		(width 0.1143)
		(layer "B.Cu")
		(net "UPI_CPU0_CPU1_P1P1_DP<12>")
	)
	(segment
		(start 156.725874 -36.783772)
		(end 155.89758 -36.864036)
		(width 0.1143)
		(layer "B.Cu")
		(net "UPI_CPU0_CPU1_P1P1_DP<12>")
	)
	(segment
		(start 300.015656 -46.434756)
		(end 299.943012 -46.558708)
		(width 0.1143)
		(layer "B.Cu")
		(net "UPI_CPU0_CPU1_P1P1_DP<12>")
	)
	(segment
		(start 299.480224 -44.382436)
		(end 299.566584 -44.71416)
		(width 0.1143)
		(layer "B.Cu")
		(net "UPI_CPU0_CPU1_P1P1_DP<12>")
	)
	(segment
		(start 130.113532 -59.664346)
		(end 129.944368 -59.371484)
		(width 0.0889)
		(layer "B.Cu")
		(net "UPI_CPU0_CPU1_P1P1_DP<12>")
	)
	(segment
		(start 128.282446 -52.810664)
		(end 127.993394 -53.099716)
		(width 0.0889)
		(layer "B.Cu")
		(net "UPI_CPU0_CPU1_P1P1_DP<12>")
	)
	(segment
		(start 299.356018 -44.309792)
		(end 299.480224 -44.382436)
		(width 0.1143)
		(layer "B.Cu")
		(net "UPI_CPU0_CPU1_P1P1_DP<12>")
	)
	(segment
		(start 279.953974 -39.221918)
		(end 291.493194 -36.914074)
		(width 0.1143)
		(layer "B.Cu")
		(net "UPI_CPU0_CPU1_P1P1_DP<12>")
	)
	(segment
		(start 168.039542 -34.965132)
		(end 173.742858 -34.382456)
		(width 0.1143)
		(layer "B.Cu")
		(net "UPI_CPU0_CPU1_P1P1_DP<12>")
	)
	(segment
		(start 299.80509 -46.030388)
		(end 299.929296 -46.103032)
		(width 0.1143)
		(layer "B.Cu")
		(net "UPI_CPU0_CPU1_P1P1_DP<12>")
	)
	(segment
		(start 300.167548 -47.419006)
		(end 300.254162 -47.750984)
		(width 0.1143)
		(layer "B.Cu")
		(net "UPI_CPU0_CPU1_P1P1_DP<12>")
	)
	(segment
		(start 298.72178 -42.118534)
		(end 298.955206 -42.369486)
		(width 0.1143)
		(layer "B.Cu")
		(net "UPI_CPU0_CPU1_P1P1_DP<12>")
	)
	(segment
		(start 300.153832 -46.96333)
		(end 300.240192 -47.295054)
		(width 0.1143)
		(layer "B.Cu")
		(net "UPI_CPU0_CPU1_P1P1_DP<12>")
	)
	(segment
		(start 154.769312 -36.645342)
		(end 154.769058 -36.645342)
		(width 0.1143)
		(layer "B.Cu")
		(net "UPI_CPU0_CPU1_P1P1_DP<12>")
	)
	(segment
		(start 300.464728 -48.155352)
		(end 300.468792 -50.141886)
		(width 0.1143)
		(layer "B.Cu")
		(net "UPI_CPU0_CPU1_P1P1_DP<12>")
	)
	(segment
		(start 133.86816 -42.682414)
		(end 131.804664 -45.741336)
		(width 0.1143)
		(layer "B.Cu")
		(net "UPI_CPU0_CPU1_P1P1_DP<12>")
	)
	(segment
		(start 294.814752 -37.914072)
		(end 297.744642 -41.066974)
		(width 0.1143)
		(layer "B.Cu")
		(net "UPI_CPU0_CPU1_P1P1_DP<12>")
	)
	(segment
		(start 300.4947 -53.30444)
		(end 300.922436 -53.833268)
		(width 0.0889)
		(layer "B.Cu")
		(net "UPI_CPU0_CPU1_P1P1_DP<12>")
	)
	(segment
		(start 127.993394 -54.02326)
		(end 127.880618 -54.218586)
		(width 0.0889)
		(layer "B.Cu")
		(net "UPI_CPU0_CPU1_P1P1_DP<12>")
	)
	(segment
		(start 299.49394 -44.838112)
		(end 299.580554 -45.17009)
		(width 0.1143)
		(layer "B.Cu")
		(net "UPI_CPU0_CPU1_P1P1_DP<12>")
	)
	(segment
		(start 297.739308 -41.210484)
		(end 297.972988 -41.461944)
		(width 0.1143)
		(layer "B.Cu")
		(net "UPI_CPU0_CPU1_P1P1_DP<12>")
	)
	(segment
		(start 130.092196 -59.74334)
		(end 130.113532 -59.664346)
		(width 0.0889)
		(layer "B.Cu")
		(net "UPI_CPU0_CPU1_P1P1_DP<12>")
	)
	(segment
		(start 248.221246 -34.081212)
		(end 253.13767 -34.85261)
		(width 0.1143)
		(layer "B.Cu")
		(net "UPI_CPU0_CPU1_P1P1_DP<12>")
	)
	(segment
		(start 153.640536 -36.426394)
		(end 138.77163 -39.37508)
		(width 0.1143)
		(layer "B.Cu")
		(net "UPI_CPU0_CPU1_P1P1_DP<12>")
	)
	(segment
		(start 128.307846 -52.442872)
		(end 128.307846 -52.46497)
		(width 0.0889)
		(layer "B.Cu")
		(net "UPI_CPU0_CPU1_P1P1_DP<12>")
	)
	(segment
		(start 173.782228 -34.37509)
		(end 183.656478 -31.672784)
		(width 0.1143)
		(layer "B.Cu")
		(net "UPI_CPU0_CPU1_P1P1_DP<12>")
	)
	(segment
		(start 256.383282 -34.507424)
		(end 279.953974 -39.221918)
		(width 0.1143)
		(layer "B.Cu")
		(net "UPI_CPU0_CPU1_P1P1_DP<12>")
	)
	(segment
		(start 291.493194 -36.914074)
		(end 294.814752 -37.914072)
		(width 0.1143)
		(layer "B.Cu")
		(net "UPI_CPU0_CPU1_P1P1_DP<12>")
	)
	(segment
		(start 128.739138 -56.695086)
		(end 128.734312 -56.703722)
		(width 0.0889)
		(layer "B.Cu")
		(net "UPI_CPU0_CPU1_P1P1_DP<12>")
	)
	(segment
		(start 298.57827 -42.1132)
		(end 298.72178 -42.118534)
		(width 0.1143)
		(layer "B.Cu")
		(net "UPI_CPU0_CPU1_P1P1_DP<12>")
	)
	(segment
		(start 155.89758 -36.864036)
		(end 154.769312 -36.645342)
		(width 0.1143)
		(layer "B.Cu")
		(net "UPI_CPU0_CPU1_P1P1_DP<12>")
	)
	(segment
		(start 300.468792 -50.141886)
		(end 300.468792 -50.163984)
		(width 0.0889)
		(layer "B.Cu")
		(net "UPI_CPU0_CPU1_P1P1_DP<12>")
	)
	(segment
		(start 298.349924 -41.71823)
		(end 298.34459 -41.86174)
		(width 0.1143)
		(layer "B.Cu")
		(net "UPI_CPU0_CPU1_P1P1_DP<12>")
	)
	(segment
		(start 127.993394 -53.099716)
		(end 127.993394 -54.02326)
		(width 0.0889)
		(layer "B.Cu")
		(net "UPI_CPU0_CPU1_P1P1_DP<12>")
	)
	(segment
		(start 300.494192 -50.188876)
		(end 300.495716 -50.34153)
		(width 0.0889)
		(layer "B.Cu")
		(net "UPI_CPU0_CPU1_P1P1_DP<12>")
	)
	(segment
		(start 167.222678 -35.129978)
		(end 168.039542 -34.965132)
		(width 0.1143)
		(layer "B.Cu")
		(net "UPI_CPU0_CPU1_P1P1_DP<12>")
	)
	(segment
		(start 299.131482 -43.449494)
		(end 299.255688 -43.522138)
		(width 0.1143)
		(layer "B.Cu")
		(net "UPI_CPU0_CPU1_P1P1_DP<12>")
	)
	(segment
		(start 300.468792 -50.163984)
		(end 300.494192 -50.188876)
		(width 0.0889)
		(layer "B.Cu")
		(net "UPI_CPU0_CPU1_P1P1_DP<12>")
	)
	(segment
		(start 299.79112 -45.574458)
		(end 299.718476 -45.69841)
		(width 0.1143)
		(layer "B.Cu")
		(net "UPI_CPU0_CPU1_P1P1_DP<12>")
	)
	(segment
		(start 237.835186 -36.740338)
		(end 239.08258 -35.908996)
		(width 0.1143)
		(layer "B.Cu")
		(net "UPI_CPU0_CPU1_P1P1_DP<12>")
	)
	(segment
		(start 225.664014 -39.174928)
		(end 237.835186 -36.740338)
		(width 0.1143)
		(layer "B.Cu")
		(net "UPI_CPU0_CPU1_P1P1_DP<12>")
	)
	(segment
		(start 299.566584 -44.71416)
		(end 299.49394 -44.838112)
		(width 0.1143)
		(layer "B.Cu")
		(net "UPI_CPU0_CPU1_P1P1_DP<12>")
	)
	(segment
		(start 166.262812 -35.32251)
		(end 167.222678 -35.129978)
		(width 0.1143)
		(layer "B.Cu")
		(net "UPI_CPU0_CPU1_P1P1_DP<12>")
	)
	(segment
		(start 299.117766 -42.993564)
		(end 299.045122 -43.117516)
		(width 0.1143)
		(layer "B.Cu")
		(net "UPI_CPU0_CPU1_P1P1_DP<12>")
	)
	(segment
		(start 300.442376 -51.646836)
		(end 300.436026 -51.657504)
		(width 0.0889)
		(layer "B.Cu")
		(net "UPI_CPU0_CPU1_P1P1_DP<12>")
	)
	(segment
		(start 129.604008 -59.160918)
		(end 129.597658 -59.171586)
		(width 0.0889)
		(layer "B.Cu")
		(net "UPI_CPU0_CPU1_P1P1_DP<12>")
	)
	(segment
		(start 299.718476 -45.69841)
		(end 299.80509 -46.030388)
		(width 0.1143)
		(layer "B.Cu")
		(net "UPI_CPU0_CPU1_P1P1_DP<12>")
	)
	(segment
		(start 298.955206 -42.369486)
		(end 299.117766 -42.993564)
		(width 0.1143)
		(layer "B.Cu")
		(net "UPI_CPU0_CPU1_P1P1_DP<12>")
	)
	(segment
		(start 210.952334 -36.233354)
		(end 210.974432 -36.236656)
		(width 0.1143)
		(layer "B.Cu")
		(net "UPI_CPU0_CPU1_P1P1_DP<12>")
	)
	(segment
		(start 300.447202 -52.6288)
		(end 300.442376 -52.637436)
		(width 0.0889)
		(layer "B.Cu")
		(net "UPI_CPU0_CPU1_P1P1_DP<12>")
	)
	(segment
		(start 128.216152 -55.809388)
		(end 128.248918 -55.809388)
		(width 0.0889)
		(layer "B.Cu")
		(net "UPI_CPU0_CPU1_P1P1_DP<12>")
	)
	(segment
		(start 299.255688 -43.522138)
		(end 299.342048 -43.853862)
		(width 0.1143)
		(layer "B.Cu")
		(net "UPI_CPU0_CPU1_P1P1_DP<12>")
	)
	(segment
		(start 128.282446 -52.49037)
		(end 128.282446 -52.810664)
		(width 0.0889)
		(layer "B.Cu")
		(net "UPI_CPU0_CPU1_P1P1_DP<12>")
	)
	(segment
		(start 299.342048 -43.853862)
		(end 299.269404 -43.977814)
		(width 0.1143)
		(layer "B.Cu")
		(net "UPI_CPU0_CPU1_P1P1_DP<12>")
	)
	(segment
		(start 299.929296 -46.103032)
		(end 300.015656 -46.434756)
		(width 0.1143)
		(layer "B.Cu")
		(net "UPI_CPU0_CPU1_P1P1_DP<12>")
	)
	(segment
		(start 298.34459 -41.86174)
		(end 298.57827 -42.1132)
		(width 0.1143)
		(layer "B.Cu")
		(net "UPI_CPU0_CPU1_P1P1_DP<12>")
	)
	(segment
		(start 138.77163 -39.37508)
		(end 133.86816 -42.682414)
		(width 0.1143)
		(layer "B.Cu")
		(net "UPI_CPU0_CPU1_P1P1_DP<12>")
	)
	(segment
		(start 298.116752 -41.467278)
		(end 298.349924 -41.71823)
		(width 0.1143)
		(layer "B.Cu")
		(net "UPI_CPU0_CPU1_P1P1_DP<12>")
	)
	(segment
		(start 128.307846 -52.46497)
		(end 128.282446 -52.49037)
		(width 0.0889)
		(layer "B.Cu")
		(net "UPI_CPU0_CPU1_P1P1_DP<12>")
	)
	(segment
		(start 183.656478 -31.672784)
		(end 189.005464 -33.349184)
		(width 0.1143)
		(layer "B.Cu")
		(net "UPI_CPU0_CPU1_P1P1_DP<12>")
	)
	(segment
		(start 164.996114 -35.069018)
		(end 163.631372 -34.795968)
		(width 0.1143)
		(layer "B.Cu")
		(net "UPI_CPU0_CPU1_P1P1_DP<12>")
	)
	(segment
		(start 131.804664 -45.741336)
		(end 128.307846 -49.237646)
		(width 0.1143)
		(layer "B.Cu")
		(net "UPI_CPU0_CPU1_P1P1_DP<12>")
	)
	(segment
		(start 253.13767 -34.85261)
		(end 256.383282 -34.507424)
		(width 0.1143)
		(layer "B.Cu")
		(net "UPI_CPU0_CPU1_P1P1_DP<12>")
	)
	(segment
		(start 129.886456 -59.76747)
		(end 129.978912 -59.780932)
		(width 0.0889)
		(layer "B.Cu")
		(net "UPI_CPU0_CPU1_P1P1_DP<12>")
	)
	(segment
		(start 299.045122 -43.117516)
		(end 299.131482 -43.449494)
		(width 0.1143)
		(layer "B.Cu")
		(net "UPI_CPU0_CPU1_P1P1_DP<12>")
	)
	(segment
		(start 196.763132 -32.871918)
		(end 206.855568 -34.890456)
		(width 0.1143)
		(layer "B.Cu")
		(net "UPI_CPU0_CPU1_P1P1_DP<12>")
	)
	(segment
		(start 129.070862 -58.285634)
		(end 129.098802 -58.285634)
		(width 0.0889)
		(layer "B.Cu")
		(net "UPI_CPU0_CPU1_P1P1_DP<12>")
	)
	(segment
		(start 239.08258 -35.908996)
		(end 248.221246 -34.081212)
		(width 0.1143)
		(layer "B.Cu")
		(net "UPI_CPU0_CPU1_P1P1_DP<12>")
	)
	(segment
		(start 222.396812 -38.521386)
		(end 225.664014 -39.174928)
		(width 0.1143)
		(layer "B.Cu")
		(net "UPI_CPU0_CPU1_P1P1_DP<12>")
	)
	(segment
		(start 300.254162 -47.750984)
		(end 300.378368 -47.823628)
		(width 0.1143)
		(layer "B.Cu")
		(net "UPI_CPU0_CPU1_P1P1_DP<12>")
	)
	(segment
		(start 297.744642 -41.066974)
		(end 297.739308 -41.210484)
		(width 0.1143)
		(layer "B.Cu")
		(net "UPI_CPU0_CPU1_P1P1_DP<12>")
	)
	(segment
		(start 127.880618 -54.618636)
		(end 127.886968 -54.629304)
		(width 0.0889)
		(layer "B.Cu")
		(net "UPI_CPU0_CPU1_P1P1_DP<12>")
	)
	(segment
		(start 164.996114 -35.069018)
		(end 166.262812 -35.32251)
		(width 0.1143)
		(layer "B.Cu")
		(net "UPI_CPU0_CPU1_P1P1_DP<12>")
	)
	(segment
		(start 206.855568 -34.890456)
		(end 209.697066 -36.137342)
		(width 0.1143)
		(layer "B.Cu")
		(net "UPI_CPU0_CPU1_P1P1_DP<12>")
	)
	(segment
		(start 299.943012 -46.558708)
		(end 300.029626 -46.890686)
		(width 0.1143)
		(layer "B.Cu")
		(net "UPI_CPU0_CPU1_P1P1_DP<12>")
	)
	(segment
		(start 300.378368 -47.823628)
		(end 300.464728 -48.155352)
		(width 0.1143)
		(layer "B.Cu")
		(net "UPI_CPU0_CPU1_P1P1_DP<12>")
	)
	(segment
		(start 127.875792 -54.61)
		(end 127.880618 -54.618636)
		(width 0.0889)
		(layer "B.Cu")
		(net "UPI_CPU0_CPU1_P1P1_DP<12>")
	)
	(segment
		(start 128.307846 -49.237646)
		(end 128.307846 -52.442872)
		(width 0.1143)
		(layer "B.Cu")
		(net "UPI_CPU0_CPU1_P1P1_DP<12>")
	)
	(segment
		(start 299.70476 -45.242734)
		(end 299.79112 -45.574458)
		(width 0.1143)
		(layer "B.Cu")
		(net "UPI_CPU0_CPU1_P1P1_DP<12>")
	)
	(segment
		(start 300.495716 -50.34153)
		(end 300.495716 -51.45786)
		(width 0.0889)
		(layer "B.Cu")
		(net "UPI_CPU0_CPU1_P1P1_DP<12>")
	)
	(segment
		(start 300.240192 -47.295054)
		(end 300.167548 -47.419006)
		(width 0.1143)
		(layer "B.Cu")
		(net "UPI_CPU0_CPU1_P1P1_DP<12>")
	)
	(segment
		(start 163.631372 -34.795968)
		(end 159.870648 -35.535362)
		(width 0.1143)
		(layer "B.Cu")
		(net "UPI_CPU0_CPU1_P1P1_DP<12>")
	)
	(segment
		(start 159.759396 -35.554666)
		(end 156.725874 -36.783772)
		(width 0.1143)
		(layer "B.Cu")
		(net "UPI_CPU0_CPU1_P1P1_DP<12>")
	)
	(arc
		(start 300.436026 -51.657504)
		(mid 300.363228 -51.948267)
		(end 300.442376 -52.237386)
		(width 0.0889)
		(layer "B.Cu")
		(net "UPI_CPU0_CPU1_P1P1_DP<12>")
	)
	(arc
		(start 127.880618 -54.218586)
		(mid 127.827148 -54.413649)
		(end 127.875792 -54.61)
		(width 0.0889)
		(layer "B.Cu")
		(net "UPI_CPU0_CPU1_P1P1_DP<12>")
	)
	(arc
		(start 300.442376 -52.637436)
		(mid 300.365055 -52.979055)
		(end 300.4947 -53.30444)
		(width 0.0889)
		(layer "B.Cu")
		(net "UPI_CPU0_CPU1_P1P1_DP<12>")
	)
	(arc
		(start 128.734312 -56.703722)
		(mid 128.685557 -56.900074)
		(end 128.739138 -57.095136)
		(width 0.0889)
		(layer "B.Cu")
		(net "UPI_CPU0_CPU1_P1P1_DP<12>")
	)
	(arc
		(start 129.597658 -59.171586)
		(mid 129.564339 -59.496962)
		(end 129.784856 -59.738514)
		(width 0.0889)
		(layer "B.Cu")
		(net "UPI_CPU0_CPU1_P1P1_DP<12>")
	)
	(arc
		(start 128.739138 -57.095136)
		(mid 128.81836 -57.384254)
		(end 128.745488 -57.675018)
		(width 0.0889)
		(layer "B.Cu")
		(net "UPI_CPU0_CPU1_P1P1_DP<12>")
	)
	(arc
		(start 128.734312 -57.694322)
		(mid 128.738059 -58.083578)
		(end 129.070862 -58.285634)
		(width 0.0889)
		(layer "B.Cu")
		(net "UPI_CPU0_CPU1_P1P1_DP<12>")
	)
	(arc
		(start 300.922436 -53.833268)
		(mid 300.946047 -53.875498)
		(end 300.954186 -53.923184)
		(width 0.0889)
		(layer "B.Cu")
		(net "UPI_CPU0_CPU1_P1P1_DP<12>")
	)
	(arc
		(start 129.098802 -58.285634)
		(mid 129.597683 -58.581071)
		(end 129.604008 -59.160918)
		(width 0.0889)
		(layer "B.Cu")
		(net "UPI_CPU0_CPU1_P1P1_DP<12>")
	)
	(arc
		(start 300.442376 -52.237386)
		(mid 300.495846 -52.432449)
		(end 300.447202 -52.6288)
		(width 0.0889)
		(layer "B.Cu")
		(net "UPI_CPU0_CPU1_P1P1_DP<12>")
	)
	(arc
		(start 129.784856 -59.738514)
		(mid 129.834697 -59.756357)
		(end 129.886456 -59.76747)
		(width 0.0889)
		(layer "B.Cu")
		(net "UPI_CPU0_CPU1_P1P1_DP<12>")
	)
	(arc
		(start 300.495716 -51.45786)
		(mid 300.494483 -51.478861)
		(end 300.49216 -51.49977)
		(width 0.0889)
		(layer "B.Cu")
		(net "UPI_CPU0_CPU1_P1P1_DP<12>")
	)
	(arc
		(start 300.49216 -51.49977)
		(mid 300.474472 -51.575742)
		(end 300.442376 -51.646836)
		(width 0.0889)
		(layer "B.Cu")
		(net "UPI_CPU0_CPU1_P1P1_DP<12>")
	)
	(arc
		(start 128.248918 -55.809388)
		(mid 128.741308 -56.108321)
		(end 128.745488 -56.684418)
		(width 0.0889)
		(layer "B.Cu")
		(net "UPI_CPU0_CPU1_P1P1_DP<12>")
	)
	(arc
		(start 129.978912 -59.780932)
		(mid 130.03998 -59.7755)
		(end 130.092196 -59.74334)
		(width 0.0889)
		(layer "B.Cu")
		(net "UPI_CPU0_CPU1_P1P1_DP<12>")
	)
	(arc
		(start 127.886968 -54.629304)
		(mid 127.959766 -54.920067)
		(end 127.880618 -55.209186)
		(width 0.0889)
		(layer "B.Cu")
		(net "UPI_CPU0_CPU1_P1P1_DP<12>")
	)
	(arc
		(start 127.880618 -55.209186)
		(mid 127.87787 -55.604653)
		(end 128.216152 -55.809388)
		(width 0.0889)
		(layer "B.Cu")
		(net "UPI_CPU0_CPU1_P1P1_DP<12>")
	)
	(segment
		(start 128.514348 -57.885584)
		(end 129.085848 -57.885584)
		(width 0.1143)
		(layer "F.Cu")
		(net "UPI_CPU0_CPU1_P1P1_DP<11>")
	)
	(segment
		(start 299.524166 -53.427884)
		(end 300.095666 -53.427884)
		(width 0.1143)
		(layer "F.Cu")
		(net "UPI_CPU0_CPU1_P1P1_DP<11>")
	)
	(via
		(at 300.095666 -53.427884)
		(size 0.508)
		(drill 0.254)
		(layers "F.Cu" "B.Cu")
		(net "UPI_CPU0_CPU1_P1P1_DP<11>")
	)
	(via
		(at 129.085848 -57.885584)
		(size 0.508)
		(drill 0.254)
		(layers "F.Cu" "B.Cu")
		(net "UPI_CPU0_CPU1_P1P1_DP<11>")
	)
	(segment
		(start 291.399468 -37.675566)
		(end 286.849058 -38.585902)
		(width 0.1143)
		(layer "B.Cu")
		(net "UPI_CPU0_CPU1_P1P1_DP<11>")
	)
	(segment
		(start 167.80256 -36.834826)
		(end 167.589962 -36.792408)
		(width 0.1143)
		(layer "B.Cu")
		(net "UPI_CPU0_CPU1_P1P1_DP<11>")
	)
	(segment
		(start 129.432558 -56.695086)
		(end 129.437384 -56.703722)
		(width 0.0889)
		(layer "B.Cu")
		(net "UPI_CPU0_CPU1_P1P1_DP<11>")
	)
	(segment
		(start 253.486412 -35.683444)
		(end 248.2088 -34.646362)
		(width 0.1143)
		(layer "B.Cu")
		(net "UPI_CPU0_CPU1_P1P1_DP<11>")
	)
	(segment
		(start 286.849058 -38.585902)
		(end 286.841438 -38.58768)
		(width 0.1143)
		(layer "B.Cu")
		(net "UPI_CPU0_CPU1_P1P1_DP<11>")
	)
	(segment
		(start 299.721016 -49.337722)
		(end 299.683678 -49.273968)
		(width 0.1143)
		(layer "B.Cu")
		(net "UPI_CPU0_CPU1_P1P1_DP<11>")
	)
	(segment
		(start 129.2098 -49.79924)
		(end 129.2098 -51.976528)
		(width 0.1143)
		(layer "B.Cu")
		(net "UPI_CPU0_CPU1_P1P1_DP<11>")
	)
	(segment
		(start 132.470398 -46.299882)
		(end 132.334 -46.446186)
		(width 0.1143)
		(layer "B.Cu")
		(net "UPI_CPU0_CPU1_P1P1_DP<11>")
	)
	(segment
		(start 299.748956 -51.646836)
		(end 299.74413 -51.6382)
		(width 0.0889)
		(layer "B.Cu")
		(net "UPI_CPU0_CPU1_P1P1_DP<11>")
	)
	(segment
		(start 293.53129 -38.102032)
		(end 291.399468 -37.675566)
		(width 0.1143)
		(layer "B.Cu")
		(net "UPI_CPU0_CPU1_P1P1_DP<11>")
	)
	(segment
		(start 134.380986 -43.46702)
		(end 132.470398 -46.299882)
		(width 0.1143)
		(layer "B.Cu")
		(net "UPI_CPU0_CPU1_P1P1_DP<11>")
	)
	(segment
		(start 299.748956 -53.227986)
		(end 299.755306 -53.217318)
		(width 0.0889)
		(layer "B.Cu")
		(net "UPI_CPU0_CPU1_P1P1_DP<11>")
	)
	(segment
		(start 129.202942 -57.768744)
		(end 129.085848 -57.885584)
		(width 0.0889)
		(layer "B.Cu")
		(net "UPI_CPU0_CPU1_P1P1_DP<11>")
	)
	(segment
		(start 299.755306 -51.657504)
		(end 299.748956 -51.646836)
		(width 0.0889)
		(layer "B.Cu")
		(net "UPI_CPU0_CPU1_P1P1_DP<11>")
	)
	(segment
		(start 188.517784 -33.922716)
		(end 187.249562 -33.58515)
		(width 0.1143)
		(layer "B.Cu")
		(net "UPI_CPU0_CPU1_P1P1_DP<11>")
	)
	(segment
		(start 247.508014 -34.763964)
		(end 239.728248 -36.319968)
		(width 0.1143)
		(layer "B.Cu")
		(net "UPI_CPU0_CPU1_P1P1_DP<11>")
	)
	(segment
		(start 175.106584 -35.028124)
		(end 170.213782 -35.605466)
		(width 0.1143)
		(layer "B.Cu")
		(net "UPI_CPU0_CPU1_P1P1_DP<11>")
	)
	(segment
		(start 168.237408 -36.898834)
		(end 167.80256 -36.834826)
		(width 0.1143)
		(layer "B.Cu")
		(net "UPI_CPU0_CPU1_P1P1_DP<11>")
	)
	(segment
		(start 210.998562 -36.984432)
		(end 209.410554 -36.748466)
		(width 0.1143)
		(layer "B.Cu")
		(net "UPI_CPU0_CPU1_P1P1_DP<11>")
	)
	(segment
		(start 128.490472 -53.574696)
		(end 128.490472 -54.073552)
		(width 0.0889)
		(layer "B.Cu")
		(net "UPI_CPU0_CPU1_P1P1_DP<11>")
	)
	(segment
		(start 129.2098 -51.976528)
		(end 129.2098 -51.998626)
		(width 0.0889)
		(layer "B.Cu")
		(net "UPI_CPU0_CPU1_P1P1_DP<11>")
	)
	(segment
		(start 222.396812 -39.264336)
		(end 210.998562 -36.984432)
		(width 0.1143)
		(layer "B.Cu")
		(net "UPI_CPU0_CPU1_P1P1_DP<11>")
	)
	(segment
		(start 169.055288 -36.710874)
		(end 168.237408 -36.898834)
		(width 0.1143)
		(layer "B.Cu")
		(net "UPI_CPU0_CPU1_P1P1_DP<11>")
	)
	(segment
		(start 129.2352 -52.024026)
		(end 129.2352 -52.829968)
		(width 0.0889)
		(layer "B.Cu")
		(net "UPI_CPU0_CPU1_P1P1_DP<11>")
	)
	(segment
		(start 206.400146 -35.343592)
		(end 196.817996 -33.42767)
		(width 0.1143)
		(layer "B.Cu")
		(net "UPI_CPU0_CPU1_P1P1_DP<11>")
	)
	(segment
		(start 258.975352 -35.76574)
		(end 256.53873 -35.35934)
		(width 0.1143)
		(layer "B.Cu")
		(net "UPI_CPU0_CPU1_P1P1_DP<11>")
	)
	(segment
		(start 239.728248 -36.319968)
		(end 237.67288 -37.559488)
		(width 0.1143)
		(layer "B.Cu")
		(net "UPI_CPU0_CPU1_P1P1_DP<11>")
	)
	(segment
		(start 183.777636 -32.657542)
		(end 175.106584 -35.028124)
		(width 0.1143)
		(layer "B.Cu")
		(net "UPI_CPU0_CPU1_P1P1_DP<11>")
	)
	(segment
		(start 139.1539 -40.248332)
		(end 134.380986 -43.46702)
		(width 0.1143)
		(layer "B.Cu")
		(net "UPI_CPU0_CPU1_P1P1_DP<11>")
	)
	(segment
		(start 294.761666 -38.921944)
		(end 293.53129 -38.102032)
		(width 0.1143)
		(layer "B.Cu")
		(net "UPI_CPU0_CPU1_P1P1_DP<11>")
	)
	(segment
		(start 167.589962 -36.792408)
		(end 164.299646 -37.535866)
		(width 0.1143)
		(layer "B.Cu")
		(net "UPI_CPU0_CPU1_P1P1_DP<11>")
	)
	(segment
		(start 286.841438 -38.58768)
		(end 279.963626 -39.963344)
		(width 0.1143)
		(layer "B.Cu")
		(net "UPI_CPU0_CPU1_P1P1_DP<11>")
	)
	(segment
		(start 132.334 -46.446186)
		(end 129.2098 -49.79924)
		(width 0.1143)
		(layer "B.Cu")
		(net "UPI_CPU0_CPU1_P1P1_DP<11>")
	)
	(segment
		(start 164.299646 -37.535866)
		(end 161.620454 -37.00018)
		(width 0.1143)
		(layer "B.Cu")
		(net "UPI_CPU0_CPU1_P1P1_DP<11>")
	)
	(segment
		(start 299.748956 -52.637436)
		(end 299.74413 -52.6288)
		(width 0.0889)
		(layer "B.Cu")
		(net "UPI_CPU0_CPU1_P1P1_DP<11>")
	)
	(segment
		(start 129.426208 -56.684418)
		(end 129.432558 -56.695086)
		(width 0.0889)
		(layer "B.Cu")
		(net "UPI_CPU0_CPU1_P1P1_DP<11>")
	)
	(segment
		(start 139.312142 -40.221662)
		(end 139.1539 -40.248332)
		(width 0.1143)
		(layer "B.Cu")
		(net "UPI_CPU0_CPU1_P1P1_DP<11>")
	)
	(segment
		(start 279.963626 -39.963344)
		(end 258.975352 -35.76574)
		(width 0.1143)
		(layer "B.Cu")
		(net "UPI_CPU0_CPU1_P1P1_DP<11>")
	)
	(segment
		(start 161.620454 -37.00018)
		(end 158.433262 -38.10508)
		(width 0.1143)
		(layer "B.Cu")
		(net "UPI_CPU0_CPU1_P1P1_DP<11>")
	)
	(segment
		(start 209.410554 -36.748466)
		(end 209.296 -36.695126)
		(width 0.1143)
		(layer "B.Cu")
		(net "UPI_CPU0_CPU1_P1P1_DP<11>")
	)
	(segment
		(start 170.213782 -35.605466)
		(end 169.055288 -36.710874)
		(width 0.1143)
		(layer "B.Cu")
		(net "UPI_CPU0_CPU1_P1P1_DP<11>")
	)
	(segment
		(start 299.721016 -50.161698)
		(end 299.721016 -50.1396)
		(width 0.0889)
		(layer "B.Cu")
		(net "UPI_CPU0_CPU1_P1P1_DP<11>")
	)
	(segment
		(start 299.683678 -49.273968)
		(end 297.960034 -42.88155)
		(width 0.1143)
		(layer "B.Cu")
		(net "UPI_CPU0_CPU1_P1P1_DP<11>")
	)
	(segment
		(start 128.578864 -54.61)
		(end 128.574038 -54.618636)
		(width 0.0889)
		(layer "B.Cu")
		(net "UPI_CPU0_CPU1_P1P1_DP<11>")
	)
	(segment
		(start 129.2352 -52.829968)
		(end 128.490472 -53.574696)
		(width 0.0889)
		(layer "B.Cu")
		(net "UPI_CPU0_CPU1_P1P1_DP<11>")
	)
	(segment
		(start 299.695616 -51.4604)
		(end 299.695616 -50.187098)
		(width 0.0889)
		(layer "B.Cu")
		(net "UPI_CPU0_CPU1_P1P1_DP<11>")
	)
	(segment
		(start 158.433262 -38.10508)
		(end 153.89098 -37.222176)
		(width 0.1143)
		(layer "B.Cu")
		(net "UPI_CPU0_CPU1_P1P1_DP<11>")
	)
	(segment
		(start 248.2088 -34.646362)
		(end 247.508014 -34.763964)
		(width 0.1143)
		(layer "B.Cu")
		(net "UPI_CPU0_CPU1_P1P1_DP<11>")
	)
	(segment
		(start 225.77171 -39.939468)
		(end 222.396812 -39.264336)
		(width 0.1143)
		(layer "B.Cu")
		(net "UPI_CPU0_CPU1_P1P1_DP<11>")
	)
	(segment
		(start 128.574038 -54.618636)
		(end 128.567688 -54.629304)
		(width 0.0889)
		(layer "B.Cu")
		(net "UPI_CPU0_CPU1_P1P1_DP<11>")
	)
	(segment
		(start 196.817996 -33.42767)
		(end 188.517784 -33.922716)
		(width 0.1143)
		(layer "B.Cu")
		(net "UPI_CPU0_CPU1_P1P1_DP<11>")
	)
	(segment
		(start 299.80255 -53.596794)
		(end 299.72381 -53.575458)
		(width 0.0889)
		(layer "B.Cu")
		(net "UPI_CPU0_CPU1_P1P1_DP<11>")
	)
	(segment
		(start 129.2098 -51.998626)
		(end 129.2352 -52.024026)
		(width 0.0889)
		(layer "B.Cu")
		(net "UPI_CPU0_CPU1_P1P1_DP<11>")
	)
	(segment
		(start 128.490472 -54.073552)
		(end 128.574038 -54.218586)
		(width 0.0889)
		(layer "B.Cu")
		(net "UPI_CPU0_CPU1_P1P1_DP<11>")
	)
	(segment
		(start 300.095666 -53.427884)
		(end 299.80255 -53.596794)
		(width 0.0889)
		(layer "B.Cu")
		(net "UPI_CPU0_CPU1_P1P1_DP<11>")
	)
	(segment
		(start 153.89098 -37.222176)
		(end 139.312142 -40.221662)
		(width 0.1143)
		(layer "B.Cu")
		(net "UPI_CPU0_CPU1_P1P1_DP<11>")
	)
	(segment
		(start 187.249562 -33.58515)
		(end 183.777636 -32.657542)
		(width 0.1143)
		(layer "B.Cu")
		(net "UPI_CPU0_CPU1_P1P1_DP<11>")
	)
	(segment
		(start 256.53873 -35.35934)
		(end 253.486412 -35.683444)
		(width 0.1143)
		(layer "B.Cu")
		(net "UPI_CPU0_CPU1_P1P1_DP<11>")
	)
	(segment
		(start 299.695616 -50.187098)
		(end 299.721016 -50.161698)
		(width 0.0889)
		(layer "B.Cu")
		(net "UPI_CPU0_CPU1_P1P1_DP<11>")
	)
	(segment
		(start 299.721016 -50.1396)
		(end 299.721016 -49.337722)
		(width 0.1143)
		(layer "B.Cu")
		(net "UPI_CPU0_CPU1_P1P1_DP<11>")
	)
	(segment
		(start 237.67288 -37.559488)
		(end 225.77171 -39.939468)
		(width 0.1143)
		(layer "B.Cu")
		(net "UPI_CPU0_CPU1_P1P1_DP<11>")
	)
	(segment
		(start 297.960034 -42.88155)
		(end 294.761666 -38.921944)
		(width 0.1143)
		(layer "B.Cu")
		(net "UPI_CPU0_CPU1_P1P1_DP<11>")
	)
	(segment
		(start 129.064258 -55.504334)
		(end 129.097024 -55.504334)
		(width 0.0889)
		(layer "B.Cu")
		(net "UPI_CPU0_CPU1_P1P1_DP<11>")
	)
	(segment
		(start 209.296 -36.695126)
		(end 206.400146 -35.343592)
		(width 0.1143)
		(layer "B.Cu")
		(net "UPI_CPU0_CPU1_P1P1_DP<11>")
	)
	(arc
		(start 299.72381 -53.575458)
		(mid 299.7019 -53.498891)
		(end 299.695616 -53.419502)
		(width 0.0889)
		(layer "B.Cu")
		(net "UPI_CPU0_CPU1_P1P1_DP<11>")
	)
	(arc
		(start 129.437384 -56.703722)
		(mid 129.486139 -56.900074)
		(end 129.432558 -57.095136)
		(width 0.0889)
		(layer "B.Cu")
		(net "UPI_CPU0_CPU1_P1P1_DP<11>")
	)
	(arc
		(start 128.567688 -54.629304)
		(mid 128.571719 -55.205486)
		(end 129.064258 -55.504334)
		(width 0.0889)
		(layer "B.Cu")
		(net "UPI_CPU0_CPU1_P1P1_DP<11>")
	)
	(arc
		(start 129.432558 -57.095136)
		(mid 129.371753 -57.24451)
		(end 129.353564 -57.404762)
		(width 0.0889)
		(layer "B.Cu")
		(net "UPI_CPU0_CPU1_P1P1_DP<11>")
	)
	(arc
		(start 299.695616 -53.419502)
		(mid 299.710178 -53.320368)
		(end 299.748956 -53.227986)
		(width 0.0889)
		(layer "B.Cu")
		(net "UPI_CPU0_CPU1_P1P1_DP<11>")
	)
	(arc
		(start 129.097024 -55.504334)
		(mid 129.435193 -55.709132)
		(end 129.432558 -56.104536)
		(width 0.0889)
		(layer "B.Cu")
		(net "UPI_CPU0_CPU1_P1P1_DP<11>")
	)
	(arc
		(start 129.432558 -56.104536)
		(mid 129.353336 -56.393654)
		(end 129.426208 -56.684418)
		(width 0.0889)
		(layer "B.Cu")
		(net "UPI_CPU0_CPU1_P1P1_DP<11>")
	)
	(arc
		(start 129.353564 -57.404762)
		(mid 129.314475 -57.601746)
		(end 129.202942 -57.768744)
		(width 0.0889)
		(layer "B.Cu")
		(net "UPI_CPU0_CPU1_P1P1_DP<11>")
	)
	(arc
		(start 299.748956 -52.237386)
		(mid 299.828178 -51.948268)
		(end 299.755306 -51.657504)
		(width 0.0889)
		(layer "B.Cu")
		(net "UPI_CPU0_CPU1_P1P1_DP<11>")
	)
	(arc
		(start 128.574038 -54.218586)
		(mid 128.627508 -54.413649)
		(end 128.578864 -54.61)
		(width 0.0889)
		(layer "B.Cu")
		(net "UPI_CPU0_CPU1_P1P1_DP<11>")
	)
	(arc
		(start 299.755306 -53.217318)
		(mid 299.828104 -52.926555)
		(end 299.748956 -52.637436)
		(width 0.0889)
		(layer "B.Cu")
		(net "UPI_CPU0_CPU1_P1P1_DP<11>")
	)
	(arc
		(start 299.74413 -51.6382)
		(mid 299.709484 -51.552133)
		(end 299.695616 -51.4604)
		(width 0.0889)
		(layer "B.Cu")
		(net "UPI_CPU0_CPU1_P1P1_DP<11>")
	)
	(arc
		(start 299.74413 -52.6288)
		(mid 299.695375 -52.432448)
		(end 299.748956 -52.237386)
		(width 0.0889)
		(layer "B.Cu")
		(net "UPI_CPU0_CPU1_P1P1_DP<11>")
	)
	(segment
		(start 130.231388 -58.876438)
		(end 130.802888 -58.876438)
		(width 0.1143)
		(layer "F.Cu")
		(net "UPI_CPU0_CPU1_P1P1_DP<10>")
	)
	(segment
		(start 300.382686 -54.913784)
		(end 300.954186 -54.913784)
		(width 0.1143)
		(layer "F.Cu")
		(net "UPI_CPU0_CPU1_P1P1_DP<10>")
	)
	(via
		(at 300.954186 -54.913784)
		(size 0.508)
		(drill 0.254)
		(layers "F.Cu" "B.Cu")
		(net "UPI_CPU0_CPU1_P1P1_DP<10>")
	)
	(via
		(at 130.802888 -58.876438)
		(size 0.508)
		(drill 0.254)
		(layers "F.Cu" "B.Cu")
		(net "UPI_CPU0_CPU1_P1P1_DP<10>")
	)
	(segment
		(start 169.022776 -38.615366)
		(end 169.023284 -38.61562)
		(width 0.1143)
		(layer "B.Cu")
		(net "UPI_CPU0_CPU1_P1P1_DP<10>")
	)
	(segment
		(start 161.711386 -38.269418)
		(end 164.362638 -38.79977)
		(width 0.1143)
		(layer "B.Cu")
		(net "UPI_CPU0_CPU1_P1P1_DP<10>")
	)
	(segment
		(start 295.62679 -42.66565)
		(end 295.740328 -42.864532)
		(width 0.1143)
		(layer "B.Cu")
		(net "UPI_CPU0_CPU1_P1P1_DP<10>")
	)
	(segment
		(start 186.518804 -34.756598)
		(end 187.88634 -35.072066)
		(width 0.1143)
		(layer "B.Cu")
		(net "UPI_CPU0_CPU1_P1P1_DP<10>")
	)
	(segment
		(start 292.054534 -38.839394)
		(end 293.129716 -39.054532)
		(width 0.1143)
		(layer "B.Cu")
		(net "UPI_CPU0_CPU1_P1P1_DP<10>")
	)
	(segment
		(start 296.670476 -44.976288)
		(end 297.040554 -46.133766)
		(width 0.1143)
		(layer "B.Cu")
		(net "UPI_CPU0_CPU1_P1P1_DP<10>")
	)
	(segment
		(start 295.674034 -42.492422)
		(end 295.62679 -42.66565)
		(width 0.1143)
		(layer "B.Cu")
		(net "UPI_CPU0_CPU1_P1P1_DP<10>")
	)
	(segment
		(start 171.239942 -39.053008)
		(end 185.04408 -34.416746)
		(width 0.1143)
		(layer "B.Cu")
		(net "UPI_CPU0_CPU1_P1P1_DP<10>")
	)
	(segment
		(start 130.5941 -50.294286)
		(end 133.426962 -47.461424)
		(width 0.1143)
		(layer "B.Cu")
		(net "UPI_CPU0_CPU1_P1P1_DP<10>")
	)
	(segment
		(start 130.5687 -52.30368)
		(end 130.5687 -51.4223)
		(width 0.0889)
		(layer "B.Cu")
		(net "UPI_CPU0_CPU1_P1P1_DP<10>")
	)
	(segment
		(start 297.25747 -46.811184)
		(end 297.175174 -46.97095)
		(width 0.1143)
		(layer "B.Cu")
		(net "UPI_CPU0_CPU1_P1P1_DP<10>")
	)
	(segment
		(start 297.511978 -48.023018)
		(end 297.671744 -48.105314)
		(width 0.1143)
		(layer "B.Cu")
		(net "UPI_CPU0_CPU1_P1P1_DP<10>")
	)
	(segment
		(start 164.362638 -38.79977)
		(end 166.920164 -38.20033)
		(width 0.1143)
		(layer "B.Cu")
		(net "UPI_CPU0_CPU1_P1P1_DP<10>")
	)
	(segment
		(start 139.517628 -41.701974)
		(end 154.468322 -38.57371)
		(width 0.1143)
		(layer "B.Cu")
		(net "UPI_CPU0_CPU1_P1P1_DP<10>")
	)
	(segment
		(start 187.88634 -35.072066)
		(end 190.59525 -34.807906)
		(width 0.1143)
		(layer "B.Cu")
		(net "UPI_CPU0_CPU1_P1P1_DP<10>")
	)
	(segment
		(start 225.846386 -41.187116)
		(end 238.647224 -38.627558)
		(width 0.1143)
		(layer "B.Cu")
		(net "UPI_CPU0_CPU1_P1P1_DP<10>")
	)
	(segment
		(start 295.740328 -42.864532)
		(end 295.91381 -42.911776)
		(width 0.1143)
		(layer "B.Cu")
		(net "UPI_CPU0_CPU1_P1P1_DP<10>")
	)
	(segment
		(start 295.321228 -41.874694)
		(end 295.273984 -42.047922)
		(width 0.1143)
		(layer "B.Cu")
		(net "UPI_CPU0_CPU1_P1P1_DP<10>")
	)
	(segment
		(start 130.451352 -54.722522)
		(end 130.456178 -54.713886)
		(width 0.0889)
		(layer "B.Cu")
		(net "UPI_CPU0_CPU1_P1P1_DP<10>")
	)
	(segment
		(start 222.396812 -40.497252)
		(end 225.846386 -41.187116)
		(width 0.1143)
		(layer "B.Cu")
		(net "UPI_CPU0_CPU1_P1P1_DP<10>")
	)
	(segment
		(start 297.175174 -46.97095)
		(end 297.245024 -47.188882)
		(width 0.1143)
		(layer "B.Cu")
		(net "UPI_CPU0_CPU1_P1P1_DP<10>")
	)
	(segment
		(start 298.730162 -52.6288)
		(end 298.725336 -52.637436)
		(width 0.0889)
		(layer "B.Cu")
		(net "UPI_CPU0_CPU1_P1P1_DP<10>")
	)
	(segment
		(start 280.029412 -41.24452)
		(end 292.054534 -38.839394)
		(width 0.1143)
		(layer "B.Cu")
		(net "UPI_CPU0_CPU1_P1P1_DP<10>")
	)
	(segment
		(start 297.040554 -46.133766)
		(end 296.958512 -46.293278)
		(width 0.1143)
		(layer "B.Cu")
		(net "UPI_CPU0_CPU1_P1P1_DP<10>")
	)
	(segment
		(start 185.04408 -34.416746)
		(end 186.51855 -34.756598)
		(width 0.1143)
		(layer "B.Cu")
		(net "UPI_CPU0_CPU1_P1P1_DP<10>")
	)
	(segment
		(start 130.451352 -55.713122)
		(end 130.456178 -55.704486)
		(width 0.0889)
		(layer "B.Cu")
		(net "UPI_CPU0_CPU1_P1P1_DP<10>")
	)
	(segment
		(start 293.129716 -39.054532)
		(end 293.857934 -39.539418)
		(width 0.1143)
		(layer "B.Cu")
		(net "UPI_CPU0_CPU1_P1P1_DP<10>")
	)
	(segment
		(start 298.778422 -51.2826)
		(end 298.778422 -51.46675)
		(width 0.0889)
		(layer "B.Cu")
		(net "UPI_CPU0_CPU1_P1P1_DP<10>")
	)
	(segment
		(start 295.387268 -42.246804)
		(end 295.56075 -42.294048)
		(width 0.1143)
		(layer "B.Cu")
		(net "UPI_CPU0_CPU1_P1P1_DP<10>")
	)
	(segment
		(start 186.51855 -34.756598)
		(end 186.518804 -34.756598)
		(width 0.1143)
		(layer "B.Cu")
		(net "UPI_CPU0_CPU1_P1P1_DP<10>")
	)
	(segment
		(start 259.29971 -37.098224)
		(end 280.029412 -41.24452)
		(width 0.1143)
		(layer "B.Cu")
		(net "UPI_CPU0_CPU1_P1P1_DP<10>")
	)
	(segment
		(start 296.958512 -46.293278)
		(end 297.028108 -46.51121)
		(width 0.1143)
		(layer "B.Cu")
		(net "UPI_CPU0_CPU1_P1P1_DP<10>")
	)
	(segment
		(start 190.59525 -34.807906)
		(end 196.88937 -34.47034)
		(width 0.1143)
		(layer "B.Cu")
		(net "UPI_CPU0_CPU1_P1P1_DP<10>")
	)
	(segment
		(start 205.99273 -36.291266)
		(end 209.108294 -37.902134)
		(width 0.1143)
		(layer "B.Cu")
		(net "UPI_CPU0_CPU1_P1P1_DP<10>")
	)
	(segment
		(start 299.215556 -54.513734)
		(end 299.248322 -54.513734)
		(width 0.0889)
		(layer "B.Cu")
		(net "UPI_CPU0_CPU1_P1P1_DP<10>")
	)
	(segment
		(start 166.920164 -38.20033)
		(end 169.022776 -38.615366)
		(width 0.1143)
		(layer "B.Cu")
		(net "UPI_CPU0_CPU1_P1P1_DP<10>")
	)
	(segment
		(start 209.108294 -37.902134)
		(end 210.975956 -38.21303)
		(width 0.1143)
		(layer "B.Cu")
		(net "UPI_CPU0_CPU1_P1P1_DP<10>")
	)
	(segment
		(start 130.456178 -52.73294)
		(end 130.468624 -52.711604)
		(width 0.0889)
		(layer "B.Cu")
		(net "UPI_CPU0_CPU1_P1P1_DP<10>")
	)
	(segment
		(start 297.028108 -46.51121)
		(end 297.187874 -46.593506)
		(width 0.1143)
		(layer "B.Cu")
		(net "UPI_CPU0_CPU1_P1P1_DP<10>")
	)
	(segment
		(start 297.245024 -47.188882)
		(end 297.40479 -47.271178)
		(width 0.1143)
		(layer "B.Cu")
		(net "UPI_CPU0_CPU1_P1P1_DP<10>")
	)
	(segment
		(start 135.470392 -44.43222)
		(end 139.517628 -41.701974)
		(width 0.1143)
		(layer "B.Cu")
		(net "UPI_CPU0_CPU1_P1P1_DP<10>")
	)
	(segment
		(start 238.647224 -38.627558)
		(end 240.880392 -37.138356)
		(width 0.1143)
		(layer "B.Cu")
		(net "UPI_CPU0_CPU1_P1P1_DP<10>")
	)
	(segment
		(start 300.68774 -54.913784)
		(end 300.954186 -54.913784)
		(width 0.0889)
		(layer "B.Cu")
		(net "UPI_CPU0_CPU1_P1P1_DP<10>")
	)
	(segment
		(start 130.5941 -51.3969)
		(end 130.5941 -50.294286)
		(width 0.1143)
		(layer "B.Cu")
		(net "UPI_CPU0_CPU1_P1P1_DP<10>")
	)
	(segment
		(start 296.5196 -44.808902)
		(end 296.55389 -44.916344)
		(width 0.1143)
		(layer "B.Cu")
		(net "UPI_CPU0_CPU1_P1P1_DP<10>")
	)
	(segment
		(start 169.023284 -38.61562)
		(end 171.239942 -39.053008)
		(width 0.1143)
		(layer "B.Cu")
		(net "UPI_CPU0_CPU1_P1P1_DP<10>")
	)
	(segment
		(start 296.463466 -44.63288)
		(end 296.5196 -44.808902)
		(width 0.1143)
		(layer "B.Cu")
		(net "UPI_CPU0_CPU1_P1P1_DP<10>")
	)
	(segment
		(start 297.949874 -48.974756)
		(end 298.46016 -50.230532)
		(width 0.1143)
		(layer "B.Cu")
		(net "UPI_CPU0_CPU1_P1P1_DP<10>")
	)
	(segment
		(start 251.511816 -36.416996)
		(end 253.241556 -36.958778)
		(width 0.1143)
		(layer "B.Cu")
		(net "UPI_CPU0_CPU1_P1P1_DP<10>")
	)
	(segment
		(start 298.46016 -50.230532)
		(end 298.501054 -50.265076)
		(width 0.0889)
		(layer "B.Cu")
		(net "UPI_CPU0_CPU1_P1P1_DP<10>")
	)
	(segment
		(start 295.56075 -42.294048)
		(end 295.674034 -42.492422)
		(width 0.1143)
		(layer "B.Cu")
		(net "UPI_CPU0_CPU1_P1P1_DP<10>")
	)
	(segment
		(start 256.62636 -36.791392)
		(end 259.29971 -37.098224)
		(width 0.1143)
		(layer "B.Cu")
		(net "UPI_CPU0_CPU1_P1P1_DP<10>")
	)
	(segment
		(start 240.880392 -37.138356)
		(end 247.998488 -35.71494)
		(width 0.1143)
		(layer "B.Cu")
		(net "UPI_CPU0_CPU1_P1P1_DP<10>")
	)
	(segment
		(start 158.817818 -39.419276)
		(end 161.711386 -38.269418)
		(width 0.1143)
		(layer "B.Cu")
		(net "UPI_CPU0_CPU1_P1P1_DP<10>")
	)
	(segment
		(start 247.998488 -35.71494)
		(end 251.511816 -36.416996)
		(width 0.1143)
		(layer "B.Cu")
		(net "UPI_CPU0_CPU1_P1P1_DP<10>")
	)
	(segment
		(start 297.524424 -47.64532)
		(end 297.442128 -47.804832)
		(width 0.1143)
		(layer "B.Cu")
		(net "UPI_CPU0_CPU1_P1P1_DP<10>")
	)
	(segment
		(start 154.468322 -38.57371)
		(end 158.817818 -39.419276)
		(width 0.1143)
		(layer "B.Cu")
		(net "UPI_CPU0_CPU1_P1P1_DP<10>")
	)
	(segment
		(start 297.40479 -47.271178)
		(end 297.524424 -47.64532)
		(width 0.1143)
		(layer "B.Cu")
		(net "UPI_CPU0_CPU1_P1P1_DP<10>")
	)
	(segment
		(start 293.857934 -39.539418)
		(end 294.82796 -41.011094)
		(width 0.1143)
		(layer "B.Cu")
		(net "UPI_CPU0_CPU1_P1P1_DP<10>")
	)
	(segment
		(start 294.82796 -41.011094)
		(end 295.321228 -41.874694)
		(width 0.1143)
		(layer "B.Cu")
		(net "UPI_CPU0_CPU1_P1P1_DP<10>")
	)
	(segment
		(start 210.975956 -38.21303)
		(end 222.396812 -40.497252)
		(width 0.1143)
		(layer "B.Cu")
		(net "UPI_CPU0_CPU1_P1P1_DP<10>")
	)
	(segment
		(start 296.5196 -44.52366)
		(end 296.463466 -44.63288)
		(width 0.1143)
		(layer "B.Cu")
		(net "UPI_CPU0_CPU1_P1P1_DP<10>")
	)
	(segment
		(start 297.671744 -48.105314)
		(end 297.949874 -48.974756)
		(width 0.1143)
		(layer "B.Cu")
		(net "UPI_CPU0_CPU1_P1P1_DP<10>")
	)
	(segment
		(start 130.456178 -54.713886)
		(end 130.462528 -54.703218)
		(width 0.0889)
		(layer "B.Cu")
		(net "UPI_CPU0_CPU1_P1P1_DP<10>")
	)
	(segment
		(start 196.88937 -34.47034)
		(end 205.99273 -36.291266)
		(width 0.1143)
		(layer "B.Cu")
		(net "UPI_CPU0_CPU1_P1P1_DP<10>")
	)
	(segment
		(start 296.5196 -44.504356)
		(end 296.52341 -44.516294)
		(width 0.1143)
		(layer "B.Cu")
		(net "UPI_CPU0_CPU1_P1P1_DP<10>")
	)
	(segment
		(start 298.718986 -53.217318)
		(end 298.725336 -53.227986)
		(width 0.0889)
		(layer "B.Cu")
		(net "UPI_CPU0_CPU1_P1P1_DP<10>")
	)
	(segment
		(start 130.462528 -53.143404)
		(end 130.456178 -53.132736)
		(width 0.0889)
		(layer "B.Cu")
		(net "UPI_CPU0_CPU1_P1P1_DP<10>")
	)
	(segment
		(start 253.241556 -36.958778)
		(end 256.62636 -36.791392)
		(width 0.1143)
		(layer "B.Cu")
		(net "UPI_CPU0_CPU1_P1P1_DP<10>")
	)
	(segment
		(start 130.456178 -55.704486)
		(end 130.462528 -55.693818)
		(width 0.0889)
		(layer "B.Cu")
		(net "UPI_CPU0_CPU1_P1P1_DP<10>")
	)
	(segment
		(start 130.451352 -56.703722)
		(end 130.456178 -56.695086)
		(width 0.0889)
		(layer "B.Cu")
		(net "UPI_CPU0_CPU1_P1P1_DP<10>")
	)
	(segment
		(start 130.456178 -56.695086)
		(end 130.462528 -56.684418)
		(width 0.0889)
		(layer "B.Cu")
		(net "UPI_CPU0_CPU1_P1P1_DP<10>")
	)
	(segment
		(start 130.5687 -51.4223)
		(end 130.5941 -51.3969)
		(width 0.0889)
		(layer "B.Cu")
		(net "UPI_CPU0_CPU1_P1P1_DP<10>")
	)
	(segment
		(start 297.442128 -47.804832)
		(end 297.511978 -48.023018)
		(width 0.1143)
		(layer "B.Cu")
		(net "UPI_CPU0_CPU1_P1P1_DP<10>")
	)
	(segment
		(start 300.077886 -55.009288)
		(end 300.246034 -55.009288)
		(width 0.0889)
		(layer "B.Cu")
		(net "UPI_CPU0_CPU1_P1P1_DP<10>")
	)
	(segment
		(start 296.52341 -44.516294)
		(end 296.5196 -44.52366)
		(width 0.1143)
		(layer "B.Cu")
		(net "UPI_CPU0_CPU1_P1P1_DP<10>")
	)
	(segment
		(start 297.187874 -46.593506)
		(end 297.25747 -46.811184)
		(width 0.1143)
		(layer "B.Cu")
		(net "UPI_CPU0_CPU1_P1P1_DP<10>")
	)
	(segment
		(start 298.634912 -50.64379)
		(end 298.778422 -51.2826)
		(width 0.0889)
		(layer "B.Cu")
		(net "UPI_CPU0_CPU1_P1P1_DP<10>")
	)
	(segment
		(start 296.133012 -43.29557)
		(end 296.5196 -44.504356)
		(width 0.1143)
		(layer "B.Cu")
		(net "UPI_CPU0_CPU1_P1P1_DP<10>")
	)
	(segment
		(start 130.451352 -53.731922)
		(end 130.456178 -53.723286)
		(width 0.0889)
		(layer "B.Cu")
		(net "UPI_CPU0_CPU1_P1P1_DP<10>")
	)
	(segment
		(start 130.456178 -57.685686)
		(end 130.462528 -57.675018)
		(width 0.0889)
		(layer "B.Cu")
		(net "UPI_CPU0_CPU1_P1P1_DP<10>")
	)
	(segment
		(start 130.451352 -57.694322)
		(end 130.456178 -57.685686)
		(width 0.0889)
		(layer "B.Cu")
		(net "UPI_CPU0_CPU1_P1P1_DP<10>")
	)
	(segment
		(start 298.725336 -51.646836)
		(end 298.718986 -51.657504)
		(width 0.0889)
		(layer "B.Cu")
		(net "UPI_CPU0_CPU1_P1P1_DP<10>")
	)
	(segment
		(start 295.273984 -42.047922)
		(end 295.387268 -42.246804)
		(width 0.1143)
		(layer "B.Cu")
		(net "UPI_CPU0_CPU1_P1P1_DP<10>")
	)
	(segment
		(start 133.426962 -47.461424)
		(end 135.470392 -44.43222)
		(width 0.1143)
		(layer "B.Cu")
		(net "UPI_CPU0_CPU1_P1P1_DP<10>")
	)
	(segment
		(start 296.55389 -44.916344)
		(end 296.670476 -44.976288)
		(width 0.1143)
		(layer "B.Cu")
		(net "UPI_CPU0_CPU1_P1P1_DP<10>")
	)
	(segment
		(start 295.91381 -42.911776)
		(end 296.133012 -43.29557)
		(width 0.1143)
		(layer "B.Cu")
		(net "UPI_CPU0_CPU1_P1P1_DP<10>")
	)
	(segment
		(start 298.501054 -50.265076)
		(end 298.634912 -50.64379)
		(width 0.0889)
		(layer "B.Cu")
		(net "UPI_CPU0_CPU1_P1P1_DP<10>")
	)
	(arc
		(start 298.725336 -52.637436)
		(mid 298.646114 -52.926554)
		(end 298.718986 -53.217318)
		(width 0.0889)
		(layer "B.Cu")
		(net "UPI_CPU0_CPU1_P1P1_DP<10>")
	)
	(arc
		(start 300.246034 -55.009288)
		(mid 300.350247 -54.998255)
		(end 300.449742 -54.965346)
		(width 0.0889)
		(layer "B.Cu")
		(net "UPI_CPU0_CPU1_P1P1_DP<10>")
	)
	(arc
		(start 130.456178 -54.123336)
		(mid 130.402708 -53.928273)
		(end 130.451352 -53.731922)
		(width 0.0889)
		(layer "B.Cu")
		(net "UPI_CPU0_CPU1_P1P1_DP<10>")
	)
	(arc
		(start 130.456178 -55.113936)
		(mid 130.402708 -54.918873)
		(end 130.451352 -54.722522)
		(width 0.0889)
		(layer "B.Cu")
		(net "UPI_CPU0_CPU1_P1P1_DP<10>")
	)
	(arc
		(start 130.462528 -57.675018)
		(mid 130.535326 -57.384255)
		(end 130.456178 -57.095136)
		(width 0.0889)
		(layer "B.Cu")
		(net "UPI_CPU0_CPU1_P1P1_DP<10>")
	)
	(arc
		(start 298.778422 -51.46675)
		(mid 298.762569 -51.559942)
		(end 298.725336 -51.646836)
		(width 0.0889)
		(layer "B.Cu")
		(net "UPI_CPU0_CPU1_P1P1_DP<10>")
	)
	(arc
		(start 130.462528 -54.703218)
		(mid 130.535326 -54.412455)
		(end 130.456178 -54.123336)
		(width 0.0889)
		(layer "B.Cu")
		(net "UPI_CPU0_CPU1_P1P1_DP<10>")
	)
	(arc
		(start 130.456178 -57.095136)
		(mid 130.402708 -56.900073)
		(end 130.451352 -56.703722)
		(width 0.0889)
		(layer "B.Cu")
		(net "UPI_CPU0_CPU1_P1P1_DP<10>")
	)
	(arc
		(start 299.583856 -54.713886)
		(mid 299.792464 -54.925818)
		(end 300.077886 -55.009288)
		(width 0.0889)
		(layer "B.Cu")
		(net "UPI_CPU0_CPU1_P1P1_DP<10>")
	)
	(arc
		(start 130.468624 -52.711604)
		(mid 130.54334 -52.513694)
		(end 130.5687 -52.30368)
		(width 0.0889)
		(layer "B.Cu")
		(net "UPI_CPU0_CPU1_P1P1_DP<10>")
	)
	(arc
		(start 298.725336 -53.627782)
		(mid 298.720082 -54.20929)
		(end 299.215556 -54.513734)
		(width 0.0889)
		(layer "B.Cu")
		(net "UPI_CPU0_CPU1_P1P1_DP<10>")
	)
	(arc
		(start 130.456178 -53.132736)
		(mid 130.402679 -52.932838)
		(end 130.456178 -52.73294)
		(width 0.0889)
		(layer "B.Cu")
		(net "UPI_CPU0_CPU1_P1P1_DP<10>")
	)
	(arc
		(start 130.529076 -58.467752)
		(mid 130.524939 -58.27058)
		(end 130.456178 -58.085736)
		(width 0.0889)
		(layer "B.Cu")
		(net "UPI_CPU0_CPU1_P1P1_DP<10>")
	)
	(arc
		(start 130.456178 -58.085736)
		(mid 130.402708 -57.890673)
		(end 130.451352 -57.694322)
		(width 0.0889)
		(layer "B.Cu")
		(net "UPI_CPU0_CPU1_P1P1_DP<10>")
	)
	(arc
		(start 299.248322 -54.513734)
		(mid 299.442172 -54.570084)
		(end 299.583856 -54.713886)
		(width 0.0889)
		(layer "B.Cu")
		(net "UPI_CPU0_CPU1_P1P1_DP<10>")
	)
	(arc
		(start 130.456178 -53.723286)
		(mid 130.5354 -53.434168)
		(end 130.462528 -53.143404)
		(width 0.0889)
		(layer "B.Cu")
		(net "UPI_CPU0_CPU1_P1P1_DP<10>")
	)
	(arc
		(start 300.449742 -54.965346)
		(mid 300.565983 -54.926839)
		(end 300.68774 -54.913784)
		(width 0.0889)
		(layer "B.Cu")
		(net "UPI_CPU0_CPU1_P1P1_DP<10>")
	)
	(arc
		(start 130.802888 -58.876438)
		(mid 130.587208 -58.724923)
		(end 130.529076 -58.467752)
		(width 0.0889)
		(layer "B.Cu")
		(net "UPI_CPU0_CPU1_P1P1_DP<10>")
	)
	(arc
		(start 130.456178 -56.104536)
		(mid 130.402708 -55.909473)
		(end 130.451352 -55.713122)
		(width 0.0889)
		(layer "B.Cu")
		(net "UPI_CPU0_CPU1_P1P1_DP<10>")
	)
	(arc
		(start 298.725336 -52.237386)
		(mid 298.778806 -52.432449)
		(end 298.730162 -52.6288)
		(width 0.0889)
		(layer "B.Cu")
		(net "UPI_CPU0_CPU1_P1P1_DP<10>")
	)
	(arc
		(start 130.462528 -55.693818)
		(mid 130.535326 -55.403055)
		(end 130.456178 -55.113936)
		(width 0.0889)
		(layer "B.Cu")
		(net "UPI_CPU0_CPU1_P1P1_DP<10>")
	)
	(arc
		(start 298.725336 -53.227986)
		(mid 298.778835 -53.427884)
		(end 298.725336 -53.627782)
		(width 0.0889)
		(layer "B.Cu")
		(net "UPI_CPU0_CPU1_P1P1_DP<10>")
	)
	(arc
		(start 298.718986 -51.657504)
		(mid 298.646188 -51.948267)
		(end 298.725336 -52.237386)
		(width 0.0889)
		(layer "B.Cu")
		(net "UPI_CPU0_CPU1_P1P1_DP<10>")
	)
	(arc
		(start 130.462528 -56.684418)
		(mid 130.535326 -56.393655)
		(end 130.456178 -56.104536)
		(width 0.0889)
		(layer "B.Cu")
		(net "UPI_CPU0_CPU1_P1P1_DP<10>")
	)
	(segment
		(start 290.0807 -55.904384)
		(end 290.6522 -55.904384)
		(width 0.1143)
		(layer "F.Cu")
		(net "UPI_CPU0_CPU1_P1P1_DP<0>")
	)
	(segment
		(start 138.816334 -58.876438)
		(end 139.387834 -58.876438)
		(width 0.1143)
		(layer "F.Cu")
		(net "UPI_CPU0_CPU1_P1P1_DP<0>")
	)
	(via
		(at 290.6522 -55.904384)
		(size 0.508)
		(drill 0.254)
		(layers "F.Cu" "B.Cu")
		(net "UPI_CPU0_CPU1_P1P1_DP<0>")
	)
	(via
		(at 139.387834 -58.876438)
		(size 0.508)
		(drill 0.254)
		(layers "F.Cu" "B.Cu")
		(net "UPI_CPU0_CPU1_P1P1_DP<0>")
	)
	(segment
		(start 243.266468 -49.588928)
		(end 243.287042 -49.605946)
		(width 0.1143)
		(layer "B.Cu")
		(net "UPI_CPU0_CPU1_P1P1_DP<0>")
	)
	(segment
		(start 286.688276 -53.0606)
		(end 286.720788 -53.028088)
		(width 0.0889)
		(layer "B.Cu")
		(net "UPI_CPU0_CPU1_P1P1_DP<0>")
	)
	(segment
		(start 274.141184 -52.014374)
		(end 274.722336 -51.87569)
		(width 0.1143)
		(layer "B.Cu")
		(net "UPI_CPU0_CPU1_P1P1_DP<0>")
	)
	(segment
		(start 145.153888 -55.244746)
		(end 145.40357 -55.590694)
		(width 0.1143)
		(layer "B.Cu")
		(net "UPI_CPU0_CPU1_P1P1_DP<0>")
	)
	(segment
		(start 289.1409 -54.393084)
		(end 290.232084 -55.484268)
		(width 0.0889)
		(layer "B.Cu")
		(net "UPI_CPU0_CPU1_P1P1_DP<0>")
	)
	(segment
		(start 173.658276 -48.970438)
		(end 184.638442 -46.80204)
		(width 0.1143)
		(layer "B.Cu")
		(net "UPI_CPU0_CPU1_P1P1_DP<0>")
	)
	(segment
		(start 264.99947 -50.950622)
		(end 265.630914 -51.077114)
		(width 0.1143)
		(layer "B.Cu")
		(net "UPI_CPU0_CPU1_P1P1_DP<0>")
	)
	(segment
		(start 250.719844 -50.994056)
		(end 250.975368 -50.673)
		(width 0.1143)
		(layer "B.Cu")
		(net "UPI_CPU0_CPU1_P1P1_DP<0>")
	)
	(segment
		(start 240.97107 -48.67656)
		(end 241.023902 -48.676052)
		(width 0.1143)
		(layer "B.Cu")
		(net "UPI_CPU0_CPU1_P1P1_DP<0>")
	)
	(segment
		(start 257.2258 -50.824384)
		(end 260.856984 -51.550824)
		(width 0.1143)
		(layer "B.Cu")
		(net "UPI_CPU0_CPU1_P1P1_DP<0>")
	)
	(segment
		(start 281.63647 -53.437282)
		(end 281.97302 -53.504592)
		(width 0.1143)
		(layer "B.Cu")
		(net "UPI_CPU0_CPU1_P1P1_DP<0>")
	)
	(segment
		(start 236.472476 -49.678336)
		(end 238.516668 -49.26965)
		(width 0.1143)
		(layer "B.Cu")
		(net "UPI_CPU0_CPU1_P1P1_DP<0>")
	)
	(segment
		(start 184.639458 -46.801786)
		(end 184.64022 -46.801532)
		(width 0.1143)
		(layer "B.Cu")
		(net "UPI_CPU0_CPU1_P1P1_DP<0>")
	)
	(segment
		(start 284.572202 -52.321714)
		(end 284.673294 -52.19573)
		(width 0.1143)
		(layer "B.Cu")
		(net "UPI_CPU0_CPU1_P1P1_DP<0>")
	)
	(segment
		(start 248.962418 -52.27193)
		(end 250.373134 -51.340766)
		(width 0.1143)
		(layer "B.Cu")
		(net "UPI_CPU0_CPU1_P1P1_DP<0>")
	)
	(segment
		(start 272.991072 -53.606446)
		(end 274.078954 -53.347366)
		(width 0.1143)
		(layer "B.Cu")
		(net "UPI_CPU0_CPU1_P1P1_DP<0>")
	)
	(segment
		(start 280.475436 -53.10124)
		(end 281.556714 -53.317394)
		(width 0.1143)
		(layer "B.Cu")
		(net "UPI_CPU0_CPU1_P1P1_DP<0>")
	)
	(segment
		(start 167.499538 -51.57089)
		(end 173.658276 -48.970438)
		(width 0.1143)
		(layer "B.Cu")
		(net "UPI_CPU0_CPU1_P1P1_DP<0>")
	)
	(segment
		(start 227.914962 -51.59375)
		(end 228.065838 -51.591972)
		(width 0.1143)
		(layer "B.Cu")
		(net "UPI_CPU0_CPU1_P1P1_DP<0>")
	)
	(segment
		(start 274.268184 -53.040026)
		(end 274.056602 -52.151788)
		(width 0.1143)
		(layer "B.Cu")
		(net "UPI_CPU0_CPU1_P1P1_DP<0>")
	)
	(segment
		(start 147.180808 -53.880512)
		(end 147.390358 -53.914294)
		(width 0.1143)
		(layer "B.Cu")
		(net "UPI_CPU0_CPU1_P1P1_DP<0>")
	)
	(segment
		(start 160.8709 -50.258218)
		(end 167.499538 -51.57089)
		(width 0.1143)
		(layer "B.Cu")
		(net "UPI_CPU0_CPU1_P1P1_DP<0>")
	)
	(segment
		(start 243.293138 -49.610772)
		(end 245.569994 -52.090574)
		(width 0.1143)
		(layer "B.Cu")
		(net "UPI_CPU0_CPU1_P1P1_DP<0>")
	)
	(segment
		(start 156.097224 -49.313084)
		(end 160.8709 -50.258218)
		(width 0.1143)
		(layer "B.Cu")
		(net "UPI_CPU0_CPU1_P1P1_DP<0>")
	)
	(segment
		(start 262.759698 -51.911504)
		(end 263.878314 -51.16576)
		(width 0.1143)
		(layer "B.Cu")
		(net "UPI_CPU0_CPU1_P1P1_DP<0>")
	)
	(segment
		(start 279.305258 -52.182268)
		(end 279.856438 -52.072032)
		(width 0.1143)
		(layer "B.Cu")
		(net "UPI_CPU0_CPU1_P1P1_DP<0>")
	)
	(segment
		(start 141.948408 -56.990488)
		(end 142.174722 -56.990488)
		(width 0.0889)
		(layer "B.Cu")
		(net "UPI_CPU0_CPU1_P1P1_DP<0>")
	)
	(segment
		(start 247.232678 -52.696618)
		(end 248.962418 -52.27193)
		(width 0.1143)
		(layer "B.Cu")
		(net "UPI_CPU0_CPU1_P1P1_DP<0>")
	)
	(segment
		(start 145.760186 -55.648352)
		(end 146.407886 -55.180484)
		(width 0.1143)
		(layer "B.Cu")
		(net "UPI_CPU0_CPU1_P1P1_DP<0>")
	)
	(segment
		(start 148.938996 -52.763674)
		(end 149.147784 -52.79771)
		(width 0.1143)
		(layer "B.Cu")
		(net "UPI_CPU0_CPU1_P1P1_DP<0>")
	)
	(segment
		(start 266.341352 -50.935128)
		(end 266.781026 -51.023012)
		(width 0.1143)
		(layer "B.Cu")
		(net "UPI_CPU0_CPU1_P1P1_DP<0>")
	)
	(segment
		(start 279.215596 -52.31638)
		(end 279.305258 -52.182268)
		(width 0.1143)
		(layer "B.Cu")
		(net "UPI_CPU0_CPU1_P1P1_DP<0>")
	)
	(segment
		(start 283.649674 -53.458618)
		(end 283.990542 -53.420518)
		(width 0.1143)
		(layer "B.Cu")
		(net "UPI_CPU0_CPU1_P1P1_DP<0>")
	)
	(segment
		(start 238.52124 -49.268634)
		(end 240.97107 -48.67656)
		(width 0.1143)
		(layer "B.Cu")
		(net "UPI_CPU0_CPU1_P1P1_DP<0>")
	)
	(segment
		(start 250.373134 -51.340766)
		(end 250.719844 -50.994056)
		(width 0.1143)
		(layer "B.Cu")
		(net "UPI_CPU0_CPU1_P1P1_DP<0>")
	)
	(segment
		(start 145.40357 -55.590694)
		(end 145.760186 -55.648352)
		(width 0.1143)
		(layer "B.Cu")
		(net "UPI_CPU0_CPU1_P1P1_DP<0>")
	)
	(segment
		(start 264.952988 -50.950622)
		(end 264.99947 -50.950622)
		(width 0.1143)
		(layer "B.Cu")
		(net "UPI_CPU0_CPU1_P1P1_DP<0>")
	)
	(segment
		(start 200.64857 -43.115992)
		(end 207.15478 -47.438818)
		(width 0.1143)
		(layer "B.Cu")
		(net "UPI_CPU0_CPU1_P1P1_DP<0>")
	)
	(segment
		(start 148.51126 -53.229002)
		(end 148.539962 -53.05171)
		(width 0.1143)
		(layer "B.Cu")
		(net "UPI_CPU0_CPU1_P1P1_DP<0>")
	)
	(segment
		(start 272.539714 -53.316124)
		(end 272.991072 -53.606446)
		(width 0.1143)
		(layer "B.Cu")
		(net "UPI_CPU0_CPU1_P1P1_DP<0>")
	)
	(segment
		(start 288.823146 -53.0098)
		(end 289.1409 -53.327554)
		(width 0.0889)
		(layer "B.Cu")
		(net "UPI_CPU0_CPU1_P1P1_DP<0>")
	)
	(segment
		(start 277.323042 -51.67503)
		(end 277.41245 -51.80965)
		(width 0.1143)
		(layer "B.Cu")
		(net "UPI_CPU0_CPU1_P1P1_DP<0>")
	)
	(segment
		(start 285.467298 -52.897024)
		(end 285.749238 -53.122576)
		(width 0.1143)
		(layer "B.Cu")
		(net "UPI_CPU0_CPU1_P1P1_DP<0>")
	)
	(segment
		(start 246.372634 -52.679092)
		(end 247.232678 -52.696618)
		(width 0.1143)
		(layer "B.Cu")
		(net "UPI_CPU0_CPU1_P1P1_DP<0>")
	)
	(segment
		(start 192.116456 -46.859444)
		(end 196.4055 -43.592242)
		(width 0.1143)
		(layer "B.Cu")
		(net "UPI_CPU0_CPU1_P1P1_DP<0>")
	)
	(segment
		(start 276.603206 -51.64709)
		(end 276.737826 -51.557682)
		(width 0.1143)
		(layer "B.Cu")
		(net "UPI_CPU0_CPU1_P1P1_DP<0>")
	)
	(segment
		(start 146.407886 -55.180484)
		(end 146.465798 -54.82463)
		(width 0.1143)
		(layer "B.Cu")
		(net "UPI_CPU0_CPU1_P1P1_DP<0>")
	)
	(segment
		(start 184.64022 -46.801532)
		(end 184.894982 -46.75124)
		(width 0.1143)
		(layer "B.Cu")
		(net "UPI_CPU0_CPU1_P1P1_DP<0>")
	)
	(segment
		(start 274.722336 -51.87569)
		(end 274.85975 -51.960272)
		(width 0.1143)
		(layer "B.Cu")
		(net "UPI_CPU0_CPU1_P1P1_DP<0>")
	)
	(segment
		(start 284.080458 -53.30825)
		(end 284.421072 -53.270404)
		(width 0.1143)
		(layer "B.Cu")
		(net "UPI_CPU0_CPU1_P1P1_DP<0>")
	)
	(segment
		(start 146.465798 -54.82463)
		(end 146.3294 -54.635654)
		(width 0.1143)
		(layer "B.Cu")
		(net "UPI_CPU0_CPU1_P1P1_DP<0>")
	)
	(segment
		(start 274.85975 -51.960272)
		(end 275.071332 -52.84851)
		(width 0.1143)
		(layer "B.Cu")
		(net "UPI_CPU0_CPU1_P1P1_DP<0>")
	)
	(segment
		(start 277.41245 -51.80965)
		(end 277.208996 -52.827428)
		(width 0.1143)
		(layer "B.Cu")
		(net "UPI_CPU0_CPU1_P1P1_DP<0>")
	)
	(segment
		(start 147.390358 -53.914294)
		(end 148.226272 -55.071518)
		(width 0.1143)
		(layer "B.Cu")
		(net "UPI_CPU0_CPU1_P1P1_DP<0>")
	)
	(segment
		(start 270.145764 -51.187096)
		(end 270.897604 -51.337464)
		(width 0.1143)
		(layer "B.Cu")
		(net "UPI_CPU0_CPU1_P1P1_DP<0>")
	)
	(segment
		(start 287.307274 -53.028088)
		(end 288.581084 -53.0098)
		(width 0.0889)
		(layer "B.Cu")
		(net "UPI_CPU0_CPU1_P1P1_DP<0>")
	)
	(segment
		(start 139.094718 -58.707528)
		(end 139.073636 -58.628788)
		(width 0.0889)
		(layer "B.Cu")
		(net "UPI_CPU0_CPU1_P1P1_DP<0>")
	)
	(segment
		(start 282.428696 -53.491892)
		(end 283.537406 -53.368702)
		(width 0.1143)
		(layer "B.Cu")
		(net "UPI_CPU0_CPU1_P1P1_DP<0>")
	)
	(segment
		(start 142.518384 -56.692038)
		(end 142.715234 -56.495188)
		(width 0.0889)
		(layer "B.Cu")
		(net "UPI_CPU0_CPU1_P1P1_DP<0>")
	)
	(segment
		(start 141.623034 -57.601104)
		(end 141.616684 -57.590436)
		(width 0.0889)
		(layer "B.Cu")
		(net "UPI_CPU0_CPU1_P1P1_DP<0>")
	)
	(segment
		(start 144.818608 -55.346092)
		(end 144.99463 -55.219092)
		(width 0.1143)
		(layer "B.Cu")
		(net "UPI_CPU0_CPU1_P1P1_DP<0>")
	)
	(segment
		(start 284.673294 -52.19573)
		(end 285.266892 -52.129182)
		(width 0.1143)
		(layer "B.Cu")
		(net "UPI_CPU0_CPU1_P1P1_DP<0>")
	)
	(segment
		(start 261.282688 -51.834288)
		(end 262.214106 -52.020724)
		(width 0.1143)
		(layer "B.Cu")
		(net "UPI_CPU0_CPU1_P1P1_DP<0>")
	)
	(segment
		(start 285.266892 -52.129182)
		(end 285.392876 -52.230274)
		(width 0.1143)
		(layer "B.Cu")
		(net "UPI_CPU0_CPU1_P1P1_DP<0>")
	)
	(segment
		(start 286.301434 -53.0606)
		(end 286.688276 -53.0606)
		(width 0.1143)
		(layer "B.Cu")
		(net "UPI_CPU0_CPU1_P1P1_DP<0>")
	)
	(segment
		(start 141.616684 -57.590436)
		(end 141.611858 -57.5818)
		(width 0.0889)
		(layer "B.Cu")
		(net "UPI_CPU0_CPU1_P1P1_DP<0>")
	)
	(segment
		(start 284.421072 -53.270404)
		(end 284.646624 -52.988464)
		(width 0.1143)
		(layer "B.Cu")
		(net "UPI_CPU0_CPU1_P1P1_DP<0>")
	)
	(segment
		(start 271.730724 -52.116736)
		(end 271.955006 -52.375816)
		(width 0.1143)
		(layer "B.Cu")
		(net "UPI_CPU0_CPU1_P1P1_DP<0>")
	)
	(segment
		(start 252.317504 -50.673)
		(end 254.837438 -51.302412)
		(width 0.1143)
		(layer "B.Cu")
		(net "UPI_CPU0_CPU1_P1P1_DP<0>")
	)
	(segment
		(start 150.625556 -53.043074)
		(end 150.683214 -52.686712)
		(width 0.1143)
		(layer "B.Cu")
		(net "UPI_CPU0_CPU1_P1P1_DP<0>")
	)
	(segment
		(start 268.21638 -51.572668)
		(end 270.145764 -51.187096)
		(width 0.1143)
		(layer "B.Cu")
		(net "UPI_CPU0_CPU1_P1P1_DP<0>")
	)
	(segment
		(start 207.15478 -47.438818)
		(end 227.914962 -51.59375)
		(width 0.1143)
		(layer "B.Cu")
		(net "UPI_CPU0_CPU1_P1P1_DP<0>")
	)
	(segment
		(start 139.387834 -58.876438)
		(end 139.094718 -58.707528)
		(width 0.0889)
		(layer "B.Cu")
		(net "UPI_CPU0_CPU1_P1P1_DP<0>")
	)
	(segment
		(start 263.878314 -51.16576)
		(end 264.952988 -50.950622)
		(width 0.1143)
		(layer "B.Cu")
		(net "UPI_CPU0_CPU1_P1P1_DP<0>")
	)
	(segment
		(start 245.569994 -52.090574)
		(end 245.606316 -52.122832)
		(width 0.1143)
		(layer "B.Cu")
		(net "UPI_CPU0_CPU1_P1P1_DP<0>")
	)
	(segment
		(start 142.715234 -56.495188)
		(end 143.631666 -56.495188)
		(width 0.0889)
		(layer "B.Cu")
		(net "UPI_CPU0_CPU1_P1P1_DP<0>")
	)
	(segment
		(start 279.365456 -53.062886)
		(end 279.215596 -52.31638)
		(width 0.1143)
		(layer "B.Cu")
		(net "UPI_CPU0_CPU1_P1P1_DP<0>")
	)
	(segment
		(start 265.630914 -51.077114)
		(end 266.341352 -50.935128)
		(width 0.1143)
		(layer "B.Cu")
		(net "UPI_CPU0_CPU1_P1P1_DP<0>")
	)
	(segment
		(start 143.631666 -56.495188)
		(end 144.63395 -55.492904)
		(width 0.0889)
		(layer "B.Cu")
		(net "UPI_CPU0_CPU1_P1P1_DP<0>")
	)
	(segment
		(start 149.621494 -53.453792)
		(end 149.977856 -53.510942)
		(width 0.1143)
		(layer "B.Cu")
		(net "UPI_CPU0_CPU1_P1P1_DP<0>")
	)
	(segment
		(start 270.897604 -51.337464)
		(end 271.21739 -51.524408)
		(width 0.1143)
		(layer "B.Cu")
		(net "UPI_CPU0_CPU1_P1P1_DP<0>")
	)
	(segment
		(start 144.669764 -55.492904)
		(end 144.685258 -55.47741)
		(width 0.0889)
		(layer "B.Cu")
		(net "UPI_CPU0_CPU1_P1P1_DP<0>")
	)
	(segment
		(start 150.00224 -51.743864)
		(end 150.027894 -51.584606)
		(width 0.1143)
		(layer "B.Cu")
		(net "UPI_CPU0_CPU1_P1P1_DP<0>")
	)
	(segment
		(start 243.29136 -49.609502)
		(end 243.292376 -49.610264)
		(width 0.1143)
		(layer "B.Cu")
		(net "UPI_CPU0_CPU1_P1P1_DP<0>")
	)
	(segment
		(start 290.4744 -55.484268)
		(end 290.6522 -55.662068)
		(width 0.0889)
		(layer "B.Cu")
		(net "UPI_CPU0_CPU1_P1P1_DP<0>")
	)
	(segment
		(start 184.638442 -46.80204)
		(end 184.639458 -46.801786)
		(width 0.1143)
		(layer "B.Cu")
		(net "UPI_CPU0_CPU1_P1P1_DP<0>")
	)
	(segment
		(start 266.781026 -51.023012)
		(end 267.344144 -51.398424)
		(width 0.1143)
		(layer "B.Cu")
		(net "UPI_CPU0_CPU1_P1P1_DP<0>")
	)
	(segment
		(start 275.071332 -52.84851)
		(end 275.378926 -53.03774)
		(width 0.1143)
		(layer "B.Cu")
		(net "UPI_CPU0_CPU1_P1P1_DP<0>")
	)
	(segment
		(start 238.516668 -49.26965)
		(end 238.52124 -49.268634)
		(width 0.1143)
		(layer "B.Cu")
		(net "UPI_CPU0_CPU1_P1P1_DP<0>")
	)
	(segment
		(start 281.556714 -53.317394)
		(end 281.63647 -53.437282)
		(width 0.1143)
		(layer "B.Cu")
		(net "UPI_CPU0_CPU1_P1P1_DP<0>")
	)
	(segment
		(start 148.58238 -55.128922)
		(end 149.186646 -54.69255)
		(width 0.1143)
		(layer "B.Cu")
		(net "UPI_CPU0_CPU1_P1P1_DP<0>")
	)
	(segment
		(start 198.481442 -42.681906)
		(end 200.64857 -43.115992)
		(width 0.1143)
		(layer "B.Cu")
		(net "UPI_CPU0_CPU1_P1P1_DP<0>")
	)
	(segment
		(start 243.28882 -49.60747)
		(end 243.29136 -49.609502)
		(width 0.1143)
		(layer "B.Cu")
		(net "UPI_CPU0_CPU1_P1P1_DP<0>")
	)
	(segment
		(start 274.078954 -53.347366)
		(end 274.268184 -53.040026)
		(width 0.1143)
		(layer "B.Cu")
		(net "UPI_CPU0_CPU1_P1P1_DP<0>")
	)
	(segment
		(start 144.80413 -55.358538)
		(end 144.818608 -55.346092)
		(width 0.1143)
		(layer "B.Cu")
		(net "UPI_CPU0_CPU1_P1P1_DP<0>")
	)
	(segment
		(start 267.344144 -51.398424)
		(end 268.21638 -51.572668)
		(width 0.1143)
		(layer "B.Cu")
		(net "UPI_CPU0_CPU1_P1P1_DP<0>")
	)
	(segment
		(start 152.054814 -50.121312)
		(end 156.097224 -49.313084)
		(width 0.1143)
		(layer "B.Cu")
		(net "UPI_CPU0_CPU1_P1P1_DP<0>")
	)
	(segment
		(start 149.147784 -52.79771)
		(end 149.621494 -53.453792)
		(width 0.1143)
		(layer "B.Cu")
		(net "UPI_CPU0_CPU1_P1P1_DP<0>")
	)
	(segment
		(start 149.256496 -54.261258)
		(end 148.51126 -53.229002)
		(width 0.1143)
		(layer "B.Cu")
		(net "UPI_CPU0_CPU1_P1P1_DP<0>")
	)
	(segment
		(start 283.537406 -53.368702)
		(end 283.649674 -53.458618)
		(width 0.1143)
		(layer "B.Cu")
		(net "UPI_CPU0_CPU1_P1P1_DP<0>")
	)
	(segment
		(start 276.737826 -51.557682)
		(end 277.323042 -51.67503)
		(width 0.1143)
		(layer "B.Cu")
		(net "UPI_CPU0_CPU1_P1P1_DP<0>")
	)
	(segment
		(start 242.123722 -48.909986)
		(end 243.266468 -49.588928)
		(width 0.1143)
		(layer "B.Cu")
		(net "UPI_CPU0_CPU1_P1P1_DP<0>")
	)
	(segment
		(start 275.378926 -53.03774)
		(end 275.957792 -52.899564)
		(width 0.1143)
		(layer "B.Cu")
		(net "UPI_CPU0_CPU1_P1P1_DP<0>")
	)
	(segment
		(start 262.214106 -52.020724)
		(end 262.759698 -51.911504)
		(width 0.1143)
		(layer "B.Cu")
		(net "UPI_CPU0_CPU1_P1P1_DP<0>")
	)
	(segment
		(start 149.977856 -53.510942)
		(end 150.625556 -53.043074)
		(width 0.1143)
		(layer "B.Cu")
		(net "UPI_CPU0_CPU1_P1P1_DP<0>")
	)
	(segment
		(start 278.244808 -53.547264)
		(end 279.164542 -53.363368)
		(width 0.1143)
		(layer "B.Cu")
		(net "UPI_CPU0_CPU1_P1P1_DP<0>")
	)
	(segment
		(start 285.392876 -52.230274)
		(end 285.467298 -52.897024)
		(width 0.1143)
		(layer "B.Cu")
		(net "UPI_CPU0_CPU1_P1P1_DP<0>")
	)
	(segment
		(start 280.031952 -52.188872)
		(end 280.1747 -52.900834)
		(width 0.1143)
		(layer "B.Cu")
		(net "UPI_CPU0_CPU1_P1P1_DP<0>")
	)
	(segment
		(start 271.372838 -51.703732)
		(end 271.362678 -51.846988)
		(width 0.1143)
		(layer "B.Cu")
		(net "UPI_CPU0_CPU1_P1P1_DP<0>")
	)
	(segment
		(start 139.376658 -58.476388)
		(end 139.400788 -58.476388)
		(width 0.0889)
		(layer "B.Cu")
		(net "UPI_CPU0_CPU1_P1P1_DP<0>")
	)
	(segment
		(start 148.226272 -55.071518)
		(end 148.58238 -55.128922)
		(width 0.1143)
		(layer "B.Cu")
		(net "UPI_CPU0_CPU1_P1P1_DP<0>")
	)
	(segment
		(start 260.856984 -51.550824)
		(end 261.282688 -51.834288)
		(width 0.1143)
		(layer "B.Cu")
		(net "UPI_CPU0_CPU1_P1P1_DP<0>")
	)
	(segment
		(start 228.065838 -51.591972)
		(end 236.472476 -49.678336)
		(width 0.1143)
		(layer "B.Cu")
		(net "UPI_CPU0_CPU1_P1P1_DP<0>")
	)
	(segment
		(start 146.3294 -54.635654)
		(end 146.355054 -54.476904)
		(width 0.1143)
		(layer "B.Cu")
		(net "UPI_CPU0_CPU1_P1P1_DP<0>")
	)
	(segment
		(start 280.1747 -52.900834)
		(end 280.475436 -53.10124)
		(width 0.1143)
		(layer "B.Cu")
		(net "UPI_CPU0_CPU1_P1P1_DP<0>")
	)
	(segment
		(start 289.1409 -53.327554)
		(end 289.1409 -54.393084)
		(width 0.0889)
		(layer "B.Cu")
		(net "UPI_CPU0_CPU1_P1P1_DP<0>")
	)
	(segment
		(start 271.587214 -52.106576)
		(end 271.730724 -52.116736)
		(width 0.1143)
		(layer "B.Cu")
		(net "UPI_CPU0_CPU1_P1P1_DP<0>")
	)
	(segment
		(start 150.027894 -51.584606)
		(end 152.054814 -50.121312)
		(width 0.1143)
		(layer "B.Cu")
		(net "UPI_CPU0_CPU1_P1P1_DP<0>")
	)
	(segment
		(start 290.6522 -55.662068)
		(end 290.6522 -55.904384)
		(width 0.0889)
		(layer "B.Cu")
		(net "UPI_CPU0_CPU1_P1P1_DP<0>")
	)
	(segment
		(start 146.355054 -54.476904)
		(end 147.180808 -53.880512)
		(width 0.1143)
		(layer "B.Cu")
		(net "UPI_CPU0_CPU1_P1P1_DP<0>")
	)
	(segment
		(start 149.186646 -54.69255)
		(end 149.256496 -54.261258)
		(width 0.1143)
		(layer "B.Cu")
		(net "UPI_CPU0_CPU1_P1P1_DP<0>")
	)
	(segment
		(start 150.683214 -52.686712)
		(end 150.00224 -51.743864)
		(width 0.1143)
		(layer "B.Cu")
		(net "UPI_CPU0_CPU1_P1P1_DP<0>")
	)
	(segment
		(start 290.232084 -55.484268)
		(end 290.4744 -55.484268)
		(width 0.0889)
		(layer "B.Cu")
		(net "UPI_CPU0_CPU1_P1P1_DP<0>")
	)
	(segment
		(start 275.957792 -52.899564)
		(end 276.413468 -52.595526)
		(width 0.1143)
		(layer "B.Cu")
		(net "UPI_CPU0_CPU1_P1P1_DP<0>")
	)
	(segment
		(start 283.990542 -53.420518)
		(end 284.080458 -53.30825)
		(width 0.1143)
		(layer "B.Cu")
		(net "UPI_CPU0_CPU1_P1P1_DP<0>")
	)
	(segment
		(start 279.164542 -53.363368)
		(end 279.365456 -53.062886)
		(width 0.1143)
		(layer "B.Cu")
		(net "UPI_CPU0_CPU1_P1P1_DP<0>")
	)
	(segment
		(start 271.955006 -52.375816)
		(end 272.539714 -53.316124)
		(width 0.1143)
		(layer "B.Cu")
		(net "UPI_CPU0_CPU1_P1P1_DP<0>")
	)
	(segment
		(start 196.4055 -43.592242)
		(end 198.481442 -42.681906)
		(width 0.1143)
		(layer "B.Cu")
		(net "UPI_CPU0_CPU1_P1P1_DP<0>")
	)
	(segment
		(start 284.646624 -52.988464)
		(end 284.572202 -52.321714)
		(width 0.1143)
		(layer "B.Cu")
		(net "UPI_CPU0_CPU1_P1P1_DP<0>")
	)
	(segment
		(start 241.023902 -48.676052)
		(end 242.123722 -48.909986)
		(width 0.1143)
		(layer "B.Cu")
		(net "UPI_CPU0_CPU1_P1P1_DP<0>")
	)
	(segment
		(start 286.720788 -53.028088)
		(end 287.307274 -53.028088)
		(width 0.0889)
		(layer "B.Cu")
		(net "UPI_CPU0_CPU1_P1P1_DP<0>")
	)
	(segment
		(start 250.975368 -50.673)
		(end 252.317504 -50.673)
		(width 0.1143)
		(layer "B.Cu")
		(net "UPI_CPU0_CPU1_P1P1_DP<0>")
	)
	(segment
		(start 285.749238 -53.122576)
		(end 286.301434 -53.0606)
		(width 0.1143)
		(layer "B.Cu")
		(net "UPI_CPU0_CPU1_P1P1_DP<0>")
	)
	(segment
		(start 144.685258 -55.47741)
		(end 144.80413 -55.358538)
		(width 0.1143)
		(layer "B.Cu")
		(net "UPI_CPU0_CPU1_P1P1_DP<0>")
	)
	(segment
		(start 279.856438 -52.072032)
		(end 280.031952 -52.188872)
		(width 0.1143)
		(layer "B.Cu")
		(net "UPI_CPU0_CPU1_P1P1_DP<0>")
	)
	(segment
		(start 184.894982 -46.75124)
		(end 192.116456 -46.859444)
		(width 0.1143)
		(layer "B.Cu")
		(net "UPI_CPU0_CPU1_P1P1_DP<0>")
	)
	(segment
		(start 254.837438 -51.302412)
		(end 257.2258 -50.824384)
		(width 0.1143)
		(layer "B.Cu")
		(net "UPI_CPU0_CPU1_P1P1_DP<0>")
	)
	(segment
		(start 144.63395 -55.492904)
		(end 144.669764 -55.492904)
		(width 0.0889)
		(layer "B.Cu")
		(net "UPI_CPU0_CPU1_P1P1_DP<0>")
	)
	(segment
		(start 276.413468 -52.595526)
		(end 276.603206 -51.64709)
		(width 0.1143)
		(layer "B.Cu")
		(net "UPI_CPU0_CPU1_P1P1_DP<0>")
	)
	(segment
		(start 277.603458 -53.41874)
		(end 278.244808 -53.547264)
		(width 0.1143)
		(layer "B.Cu")
		(net "UPI_CPU0_CPU1_P1P1_DP<0>")
	)
	(segment
		(start 271.362678 -51.846988)
		(end 271.587214 -52.106576)
		(width 0.1143)
		(layer "B.Cu")
		(net "UPI_CPU0_CPU1_P1P1_DP<0>")
	)
	(segment
		(start 144.99463 -55.219092)
		(end 145.153888 -55.244746)
		(width 0.1143)
		(layer "B.Cu")
		(net "UPI_CPU0_CPU1_P1P1_DP<0>")
	)
	(segment
		(start 243.287042 -49.605946)
		(end 243.28882 -49.60747)
		(width 0.1143)
		(layer "B.Cu")
		(net "UPI_CPU0_CPU1_P1P1_DP<0>")
	)
	(segment
		(start 274.056602 -52.151788)
		(end 274.141184 -52.014374)
		(width 0.1143)
		(layer "B.Cu")
		(net "UPI_CPU0_CPU1_P1P1_DP<0>")
	)
	(segment
		(start 148.539962 -53.05171)
		(end 148.938996 -52.763674)
		(width 0.1143)
		(layer "B.Cu")
		(net "UPI_CPU0_CPU1_P1P1_DP<0>")
	)
	(segment
		(start 243.292376 -49.610264)
		(end 243.293138 -49.610772)
		(width 0.1143)
		(layer "B.Cu")
		(net "UPI_CPU0_CPU1_P1P1_DP<0>")
	)
	(segment
		(start 288.581084 -53.0098)
		(end 288.823146 -53.0098)
		(width 0.0889)
		(layer "B.Cu")
		(net "UPI_CPU0_CPU1_P1P1_DP<0>")
	)
	(segment
		(start 277.208996 -52.827428)
		(end 277.603458 -53.41874)
		(width 0.1143)
		(layer "B.Cu")
		(net "UPI_CPU0_CPU1_P1P1_DP<0>")
	)
	(segment
		(start 282.092654 -53.424836)
		(end 282.428696 -53.491892)
		(width 0.1143)
		(layer "B.Cu")
		(net "UPI_CPU0_CPU1_P1P1_DP<0>")
	)
	(segment
		(start 140.231368 -57.981088)
		(end 140.26134 -57.981088)
		(width 0.0889)
		(layer "B.Cu")
		(net "UPI_CPU0_CPU1_P1P1_DP<0>")
	)
	(segment
		(start 281.97302 -53.504592)
		(end 282.092654 -53.424836)
		(width 0.1143)
		(layer "B.Cu")
		(net "UPI_CPU0_CPU1_P1P1_DP<0>")
	)
	(segment
		(start 271.21739 -51.524408)
		(end 271.372838 -51.703732)
		(width 0.1143)
		(layer "B.Cu")
		(net "UPI_CPU0_CPU1_P1P1_DP<0>")
	)
	(segment
		(start 245.606316 -52.122832)
		(end 246.372634 -52.679092)
		(width 0.1143)
		(layer "B.Cu")
		(net "UPI_CPU0_CPU1_P1P1_DP<0>")
	)
	(arc
		(start 142.174722 -56.990488)
		(mid 142.374605 -56.873556)
		(end 142.518384 -56.692038)
		(width 0.0889)
		(layer "B.Cu")
		(net "UPI_CPU0_CPU1_P1P1_DP<0>")
	)
	(arc
		(start 141.082522 -58.476388)
		(mid 141.104747 -58.476811)
		(end 141.126972 -58.476388)
		(width 0.0889)
		(layer "B.Cu")
		(net "UPI_CPU0_CPU1_P1P1_DP<0>")
	)
	(arc
		(start 139.400788 -58.476388)
		(mid 139.688933 -58.394069)
		(end 139.899644 -58.180986)
		(width 0.0889)
		(layer "B.Cu")
		(net "UPI_CPU0_CPU1_P1P1_DP<0>")
	)
	(arc
		(start 140.26134 -57.981088)
		(mid 140.452982 -58.038254)
		(end 140.593064 -58.180986)
		(width 0.0889)
		(layer "B.Cu")
		(net "UPI_CPU0_CPU1_P1P1_DP<0>")
	)
	(arc
		(start 141.126972 -58.476388)
		(mid 141.619263 -58.177199)
		(end 141.623034 -57.601104)
		(width 0.0889)
		(layer "B.Cu")
		(net "UPI_CPU0_CPU1_P1P1_DP<0>")
	)
	(arc
		(start 139.899644 -58.180986)
		(mid 140.039723 -58.03825)
		(end 140.231368 -57.981088)
		(width 0.0889)
		(layer "B.Cu")
		(net "UPI_CPU0_CPU1_P1P1_DP<0>")
	)
	(arc
		(start 139.073636 -58.628788)
		(mid 139.208198 -58.518876)
		(end 139.376658 -58.476388)
		(width 0.0889)
		(layer "B.Cu")
		(net "UPI_CPU0_CPU1_P1P1_DP<0>")
	)
	(arc
		(start 140.593064 -58.180986)
		(mid 140.799691 -58.391832)
		(end 141.082522 -58.476388)
		(width 0.0889)
		(layer "B.Cu")
		(net "UPI_CPU0_CPU1_P1P1_DP<0>")
	)
	(arc
		(start 141.611858 -57.5818)
		(mid 141.615605 -57.192544)
		(end 141.948408 -56.990488)
		(width 0.0889)
		(layer "B.Cu")
		(net "UPI_CPU0_CPU1_P1P1_DP<0>")
	)
	(segment
		(start 132.806694 -58.381138)
		(end 133.378194 -58.381138)
		(width 0.1143)
		(layer "F.Cu")
		(net "UPI_CPU0_CPU1_P1P1_DN<9>")
	)
	(segment
		(start 297.807126 -53.427884)
		(end 298.378626 -53.427884)
		(width 0.1143)
		(layer "F.Cu")
		(net "UPI_CPU0_CPU1_P1P1_DN<9>")
	)
	(via
		(at 152.90673 -39.780464)
		(size 0.508)
		(drill 0.254)
		(layers "F.Cu" "B.Cu")
		(net "UPI_CPU0_CPU1_P1P1_DN<9>")
	)
	(via
		(at 298.378626 -53.427884)
		(size 0.508)
		(drill 0.254)
		(layers "F.Cu" "B.Cu")
		(net "UPI_CPU0_CPU1_P1P1_DN<9>")
	)
	(via
		(at 133.378194 -58.381138)
		(size 0.508)
		(drill 0.254)
		(layers "F.Cu" "B.Cu")
		(net "UPI_CPU0_CPU1_P1P1_DN<9>")
	)
	(segment
		(start 298.064682 -52.072794)
		(end 298.064682 -51.914806)
		(width 0.0889)
		(layer "B.Cu")
		(net "UPI_CPU0_CPU1_P1P1_DN<9>")
	)
	(segment
		(start 134.219696 -47.899574)
		(end 131.5085 -50.611024)
		(width 0.1143)
		(layer "B.Cu")
		(net "UPI_CPU0_CPU1_P1P1_DN<9>")
	)
	(segment
		(start 287.497774 -41.699434)
		(end 280.194004 -42.032682)
		(width 0.1143)
		(layer "B.Cu")
		(net "UPI_CPU0_CPU1_P1P1_DN<9>")
	)
	(segment
		(start 132.008626 -58.181748)
		(end 132.011674 -58.187082)
		(width 0.0889)
		(layer "B.Cu")
		(net "UPI_CPU0_CPU1_P1P1_DN<9>")
	)
	(segment
		(start 131.636516 -53.02758)
		(end 131.661408 -53.02758)
		(width 0.0889)
		(layer "B.Cu")
		(net "UPI_CPU0_CPU1_P1P1_DN<9>")
	)
	(segment
		(start 254.473456 -37.671756)
		(end 254.235204 -37.671502)
		(width 0.1143)
		(layer "B.Cu")
		(net "UPI_CPU0_CPU1_P1P1_DN<9>")
	)
	(segment
		(start 297.545506 -50.443638)
		(end 297.542966 -50.442368)
		(width 0.1143)
		(layer "B.Cu")
		(net "UPI_CPU0_CPU1_P1P1_DN<9>")
	)
	(segment
		(start 185.688986 -35.34156)
		(end 182.913782 -35.912298)
		(width 0.1143)
		(layer "B.Cu")
		(net "UPI_CPU0_CPU1_P1P1_DN<9>")
	)
	(segment
		(start 205.826106 -36.795964)
		(end 196.873368 -35.005264)
		(width 0.1143)
		(layer "B.Cu")
		(net "UPI_CPU0_CPU1_P1P1_DN<9>")
	)
	(segment
		(start 131.5339 -51.610768)
		(end 131.533646 -51.610768)
		(width 0.0889)
		(layer "B.Cu")
		(net "UPI_CPU0_CPU1_P1P1_DN<9>")
	)
	(segment
		(start 131.5085 -51.06797)
		(end 131.5085 -51.090068)
		(width 0.0889)
		(layer "B.Cu")
		(net "UPI_CPU0_CPU1_P1P1_DN<9>")
	)
	(segment
		(start 152.90673 -39.780464)
		(end 143.397224 -41.864534)
		(width 0.1143)
		(layer "B.Cu")
		(net "UPI_CPU0_CPU1_P1P1_DN<9>")
	)
	(segment
		(start 297.8023 -51.447192)
		(end 297.670982 -50.984658)
		(width 0.0889)
		(layer "B.Cu")
		(net "UPI_CPU0_CPU1_P1P1_DN<9>")
	)
	(segment
		(start 132.005578 -58.176668)
		(end 132.008626 -58.181748)
		(width 0.0889)
		(layer "B.Cu")
		(net "UPI_CPU0_CPU1_P1P1_DN<9>")
	)
	(segment
		(start 298.064682 -51.914806)
		(end 297.978576 -51.8287)
		(width 0.0889)
		(layer "B.Cu")
		(net "UPI_CPU0_CPU1_P1P1_DN<9>")
	)
	(segment
		(start 131.661408 -53.827934)
		(end 131.648454 -53.827934)
		(width 0.0889)
		(layer "B.Cu")
		(net "UPI_CPU0_CPU1_P1P1_DN<9>")
	)
	(segment
		(start 166.937182 -38.956488)
		(end 164.399976 -39.589964)
		(width 0.1143)
		(layer "B.Cu")
		(net "UPI_CPU0_CPU1_P1P1_DN<9>")
	)
	(segment
		(start 187.654946 -35.762946)
		(end 185.688986 -35.34156)
		(width 0.1143)
		(layer "B.Cu")
		(net "UPI_CPU0_CPU1_P1P1_DN<9>")
	)
	(segment
		(start 131.350258 -51.794156)
		(end 131.143248 -52.152296)
		(width 0.0889)
		(layer "B.Cu")
		(net "UPI_CPU0_CPU1_P1P1_DN<9>")
	)
	(segment
		(start 297.978576 -52.428394)
		(end 297.978576 -52.1589)
		(width 0.0889)
		(layer "B.Cu")
		(net "UPI_CPU0_CPU1_P1P1_DN<9>")
	)
	(segment
		(start 241.84737 -37.48024)
		(end 238.973106 -39.39667)
		(width 0.1143)
		(layer "B.Cu")
		(net "UPI_CPU0_CPU1_P1P1_DN<9>")
	)
	(segment
		(start 297.978576 -51.8287)
		(end 297.978576 -51.623468)
		(width 0.0889)
		(layer "B.Cu")
		(net "UPI_CPU0_CPU1_P1P1_DN<9>")
	)
	(segment
		(start 131.143248 -55.693818)
		(end 131.149598 -55.704486)
		(width 0.0889)
		(layer "B.Cu")
		(net "UPI_CPU0_CPU1_P1P1_DN<9>")
	)
	(segment
		(start 238.973106 -39.39667)
		(end 226.064572 -41.978326)
		(width 0.1143)
		(layer "B.Cu")
		(net "UPI_CPU0_CPU1_P1P1_DN<9>")
	)
	(segment
		(start 131.533646 -51.610768)
		(end 131.350258 -51.794156)
		(width 0.0889)
		(layer "B.Cu")
		(net "UPI_CPU0_CPU1_P1P1_DN<9>")
	)
	(segment
		(start 143.397224 -41.864534)
		(end 141.804898 -42.21353)
		(width 0.1143)
		(layer "B.Cu")
		(net "UPI_CPU0_CPU1_P1P1_DN<9>")
	)
	(segment
		(start 209.095848 -38.658038)
		(end 205.826106 -36.795964)
		(width 0.1143)
		(layer "B.Cu")
		(net "UPI_CPU0_CPU1_P1P1_DN<9>")
	)
	(segment
		(start 164.399976 -39.589964)
		(end 161.856674 -39.081202)
		(width 0.1143)
		(layer "B.Cu")
		(net "UPI_CPU0_CPU1_P1P1_DN<9>")
	)
	(segment
		(start 260.343904 -38.062662)
		(end 256.811272 -37.593524)
		(width 0.1143)
		(layer "B.Cu")
		(net "UPI_CPU0_CPU1_P1P1_DN<9>")
	)
	(segment
		(start 139.990322 -42.566336)
		(end 136.00303 -45.255942)
		(width 0.1143)
		(layer "B.Cu")
		(net "UPI_CPU0_CPU1_P1P1_DN<9>")
	)
	(segment
		(start 196.873368 -35.005264)
		(end 190.624968 -35.340036)
		(width 0.1143)
		(layer "B.Cu")
		(net "UPI_CPU0_CPU1_P1P1_DN<9>")
	)
	(segment
		(start 131.5085 -51.090068)
		(end 131.5339 -51.115468)
		(width 0.0889)
		(layer "B.Cu")
		(net "UPI_CPU0_CPU1_P1P1_DN<9>")
	)
	(segment
		(start 297.978576 -52.1589)
		(end 298.064682 -52.072794)
		(width 0.0889)
		(layer "B.Cu")
		(net "UPI_CPU0_CPU1_P1P1_DN<9>")
	)
	(segment
		(start 132.518912 -58.47588)
		(end 132.880608 -58.47588)
		(width 0.0889)
		(layer "B.Cu")
		(net "UPI_CPU0_CPU1_P1P1_DN<9>")
	)
	(segment
		(start 254.477266 -37.671756)
		(end 254.473456 -37.671756)
		(width 0.1143)
		(layer "B.Cu")
		(net "UPI_CPU0_CPU1_P1P1_DN<9>")
	)
	(segment
		(start 253.110746 -37.693346)
		(end 250.651772 -36.777168)
		(width 0.1143)
		(layer "B.Cu")
		(net "UPI_CPU0_CPU1_P1P1_DN<9>")
	)
	(segment
		(start 297.542966 -50.442368)
		(end 295.830244 -46.332394)
		(width 0.1143)
		(layer "B.Cu")
		(net "UPI_CPU0_CPU1_P1P1_DN<9>")
	)
	(segment
		(start 226.064572 -41.978326)
		(end 210.993736 -38.963854)
		(width 0.1143)
		(layer "B.Cu")
		(net "UPI_CPU0_CPU1_P1P1_DN<9>")
	)
	(segment
		(start 190.624968 -35.340036)
		(end 187.654946 -35.762946)
		(width 0.1143)
		(layer "B.Cu")
		(net "UPI_CPU0_CPU1_P1P1_DN<9>")
	)
	(segment
		(start 298.378626 -53.765958)
		(end 298.320714 -53.82387)
		(width 0.0889)
		(layer "B.Cu")
		(net "UPI_CPU0_CPU1_P1P1_DN<9>")
	)
	(segment
		(start 132.007864 -53.227986)
		(end 132.01269 -53.236622)
		(width 0.0889)
		(layer "B.Cu")
		(net "UPI_CPU0_CPU1_P1P1_DN<9>")
	)
	(segment
		(start 131.5085 -50.611024)
		(end 131.5085 -51.06797)
		(width 0.1143)
		(layer "B.Cu")
		(net "UPI_CPU0_CPU1_P1P1_DN<9>")
	)
	(segment
		(start 293.22395 -44.59478)
		(end 290.738814 -44.097448)
		(width 0.1143)
		(layer "B.Cu")
		(net "UPI_CPU0_CPU1_P1P1_DN<9>")
	)
	(segment
		(start 210.993736 -38.963854)
		(end 209.095848 -38.658038)
		(width 0.1143)
		(layer "B.Cu")
		(net "UPI_CPU0_CPU1_P1P1_DN<9>")
	)
	(segment
		(start 280.194004 -42.032682)
		(end 260.343904 -38.062662)
		(width 0.1143)
		(layer "B.Cu")
		(net "UPI_CPU0_CPU1_P1P1_DN<9>")
	)
	(segment
		(start 297.670982 -50.984658)
		(end 297.689524 -50.951892)
		(width 0.0889)
		(layer "B.Cu")
		(net "UPI_CPU0_CPU1_P1P1_DN<9>")
	)
	(segment
		(start 297.683428 -50.930302)
		(end 297.545506 -50.443638)
		(width 0.1143)
		(layer "B.Cu")
		(net "UPI_CPU0_CPU1_P1P1_DN<9>")
	)
	(segment
		(start 254.235204 -37.671502)
		(end 253.110746 -37.693346)
		(width 0.1143)
		(layer "B.Cu")
		(net "UPI_CPU0_CPU1_P1P1_DN<9>")
	)
	(segment
		(start 158.778448 -40.239188)
		(end 154.558238 -39.418514)
		(width 0.1143)
		(layer "B.Cu")
		(net "UPI_CPU0_CPU1_P1P1_DN<9>")
	)
	(segment
		(start 131.143248 -56.684418)
		(end 131.149598 -56.695086)
		(width 0.0889)
		(layer "B.Cu")
		(net "UPI_CPU0_CPU1_P1P1_DN<9>")
	)
	(segment
		(start 297.689524 -50.951892)
		(end 297.683428 -50.930302)
		(width 0.0889)
		(layer "B.Cu")
		(net "UPI_CPU0_CPU1_P1P1_DN<9>")
	)
	(segment
		(start 248.006362 -36.248086)
		(end 241.84737 -37.48024)
		(width 0.1143)
		(layer "B.Cu")
		(net "UPI_CPU0_CPU1_P1P1_DN<9>")
	)
	(segment
		(start 132.880608 -58.47588)
		(end 133.148324 -58.476388)
		(width 0.0889)
		(layer "B.Cu")
		(net "UPI_CPU0_CPU1_P1P1_DN<9>")
	)
	(segment
		(start 182.913782 -35.912298)
		(end 172.428154 -39.504366)
		(width 0.1143)
		(layer "B.Cu")
		(net "UPI_CPU0_CPU1_P1P1_DN<9>")
	)
	(segment
		(start 290.738814 -44.097448)
		(end 287.497774 -41.699434)
		(width 0.1143)
		(layer "B.Cu")
		(net "UPI_CPU0_CPU1_P1P1_DN<9>")
	)
	(segment
		(start 131.643628 -57.981088)
		(end 131.661408 -57.981088)
		(width 0.0889)
		(layer "B.Cu")
		(net "UPI_CPU0_CPU1_P1P1_DN<9>")
	)
	(segment
		(start 297.978576 -51.623468)
		(end 297.8023 -51.447192)
		(width 0.0889)
		(layer "B.Cu")
		(net "UPI_CPU0_CPU1_P1P1_DN<9>")
	)
	(segment
		(start 131.149598 -55.704486)
		(end 131.154424 -55.713122)
		(width 0.0889)
		(layer "B.Cu")
		(net "UPI_CPU0_CPU1_P1P1_DN<9>")
	)
	(segment
		(start 298.031916 -53.227986)
		(end 298.038266 -53.217318)
		(width 0.0889)
		(layer "B.Cu")
		(net "UPI_CPU0_CPU1_P1P1_DN<9>")
	)
	(segment
		(start 250.651772 -36.777168)
		(end 248.006362 -36.248086)
		(width 0.1143)
		(layer "B.Cu")
		(net "UPI_CPU0_CPU1_P1P1_DN<9>")
	)
	(segment
		(start 132.004562 -58.175398)
		(end 132.005578 -58.176668)
		(width 0.0889)
		(layer "B.Cu")
		(net "UPI_CPU0_CPU1_P1P1_DN<9>")
	)
	(segment
		(start 131.143248 -54.703218)
		(end 131.149598 -54.713886)
		(width 0.0889)
		(layer "B.Cu")
		(net "UPI_CPU0_CPU1_P1P1_DN<9>")
	)
	(segment
		(start 132.001768 -53.217572)
		(end 132.007864 -53.227986)
		(width 0.0889)
		(layer "B.Cu")
		(net "UPI_CPU0_CPU1_P1P1_DN<9>")
	)
	(segment
		(start 154.558238 -39.418514)
		(end 152.90673 -39.780464)
		(width 0.1143)
		(layer "B.Cu")
		(net "UPI_CPU0_CPU1_P1P1_DN<9>")
	)
	(segment
		(start 131.149598 -54.713886)
		(end 131.154424 -54.722522)
		(width 0.0889)
		(layer "B.Cu")
		(net "UPI_CPU0_CPU1_P1P1_DN<9>")
	)
	(segment
		(start 136.00303 -45.255942)
		(end 134.219696 -47.899574)
		(width 0.1143)
		(layer "B.Cu")
		(net "UPI_CPU0_CPU1_P1P1_DN<9>")
	)
	(segment
		(start 295.830244 -46.332394)
		(end 293.22395 -44.59478)
		(width 0.1143)
		(layer "B.Cu")
		(net "UPI_CPU0_CPU1_P1P1_DN<9>")
	)
	(segment
		(start 298.378626 -53.427884)
		(end 298.378626 -53.765958)
		(width 0.0889)
		(layer "B.Cu")
		(net "UPI_CPU0_CPU1_P1P1_DN<9>")
	)
	(segment
		(start 131.149598 -56.695086)
		(end 131.154424 -56.703722)
		(width 0.0889)
		(layer "B.Cu")
		(net "UPI_CPU0_CPU1_P1P1_DN<9>")
	)
	(segment
		(start 256.811272 -37.593524)
		(end 254.477266 -37.671756)
		(width 0.1143)
		(layer "B.Cu")
		(net "UPI_CPU0_CPU1_P1P1_DN<9>")
	)
	(segment
		(start 161.856674 -39.081202)
		(end 158.778448 -40.239188)
		(width 0.1143)
		(layer "B.Cu")
		(net "UPI_CPU0_CPU1_P1P1_DN<9>")
	)
	(segment
		(start 171.187618 -39.835074)
		(end 166.937182 -38.956488)
		(width 0.1143)
		(layer "B.Cu")
		(net "UPI_CPU0_CPU1_P1P1_DN<9>")
	)
	(segment
		(start 141.804898 -42.21353)
		(end 139.990322 -42.566336)
		(width 0.1143)
		(layer "B.Cu")
		(net "UPI_CPU0_CPU1_P1P1_DN<9>")
	)
	(segment
		(start 172.428154 -39.504366)
		(end 171.187618 -39.835074)
		(width 0.1143)
		(layer "B.Cu")
		(net "UPI_CPU0_CPU1_P1P1_DN<9>")
	)
	(segment
		(start 131.5339 -51.115468)
		(end 131.5339 -51.610768)
		(width 0.0889)
		(layer "B.Cu")
		(net "UPI_CPU0_CPU1_P1P1_DN<9>")
	)
	(arc
		(start 131.149598 -56.104536)
		(mid 131.070376 -56.393654)
		(end 131.143248 -56.684418)
		(width 0.0889)
		(layer "B.Cu")
		(net "UPI_CPU0_CPU1_P1P1_DN<9>")
	)
	(arc
		(start 132.01269 -53.236622)
		(mid 132.00524 -53.632245)
		(end 131.661408 -53.827934)
		(width 0.0889)
		(layer "B.Cu")
		(net "UPI_CPU0_CPU1_P1P1_DN<9>")
	)
	(arc
		(start 131.154424 -56.703722)
		(mid 131.203179 -56.900074)
		(end 131.149598 -57.095136)
		(width 0.0889)
		(layer "B.Cu")
		(net "UPI_CPU0_CPU1_P1P1_DN<9>")
	)
	(arc
		(start 131.143248 -52.152296)
		(mid 131.146305 -52.727259)
		(end 131.636516 -53.02758)
		(width 0.0889)
		(layer "B.Cu")
		(net "UPI_CPU0_CPU1_P1P1_DN<9>")
	)
	(arc
		(start 298.031916 -52.637436)
		(mid 297.990866 -52.53658)
		(end 297.978576 -52.428394)
		(width 0.0889)
		(layer "B.Cu")
		(net "UPI_CPU0_CPU1_P1P1_DN<9>")
	)
	(arc
		(start 131.661408 -53.02758)
		(mid 131.856299 -53.078299)
		(end 132.001768 -53.217572)
		(width 0.0889)
		(layer "B.Cu")
		(net "UPI_CPU0_CPU1_P1P1_DN<9>")
	)
	(arc
		(start 131.661408 -57.981088)
		(mid 131.858569 -58.033047)
		(end 132.004562 -58.175398)
		(width 0.0889)
		(layer "B.Cu")
		(net "UPI_CPU0_CPU1_P1P1_DN<9>")
	)
	(arc
		(start 131.648454 -53.827934)
		(mid 131.149573 -54.123371)
		(end 131.143248 -54.703218)
		(width 0.0889)
		(layer "B.Cu")
		(net "UPI_CPU0_CPU1_P1P1_DN<9>")
	)
	(arc
		(start 298.320714 -53.82387)
		(mid 298.018299 -53.60246)
		(end 298.031916 -53.227986)
		(width 0.0889)
		(layer "B.Cu")
		(net "UPI_CPU0_CPU1_P1P1_DN<9>")
	)
	(arc
		(start 131.154424 -55.713122)
		(mid 131.203179 -55.909474)
		(end 131.149598 -56.104536)
		(width 0.0889)
		(layer "B.Cu")
		(net "UPI_CPU0_CPU1_P1P1_DN<9>")
	)
	(arc
		(start 132.011674 -58.187082)
		(mid 132.2271 -58.398562)
		(end 132.518912 -58.47588)
		(width 0.0889)
		(layer "B.Cu")
		(net "UPI_CPU0_CPU1_P1P1_DN<9>")
	)
	(arc
		(start 131.149598 -57.095136)
		(mid 131.145269 -57.678308)
		(end 131.643628 -57.981088)
		(width 0.0889)
		(layer "B.Cu")
		(net "UPI_CPU0_CPU1_P1P1_DN<9>")
	)
	(arc
		(start 131.149598 -55.113936)
		(mid 131.070376 -55.403054)
		(end 131.143248 -55.693818)
		(width 0.0889)
		(layer "B.Cu")
		(net "UPI_CPU0_CPU1_P1P1_DN<9>")
	)
	(arc
		(start 131.154424 -54.722522)
		(mid 131.203179 -54.918874)
		(end 131.149598 -55.113936)
		(width 0.0889)
		(layer "B.Cu")
		(net "UPI_CPU0_CPU1_P1P1_DN<9>")
	)
	(arc
		(start 133.148324 -58.476388)
		(mid 133.272742 -58.45164)
		(end 133.378194 -58.381138)
		(width 0.0889)
		(layer "B.Cu")
		(net "UPI_CPU0_CPU1_P1P1_DN<9>")
	)
	(arc
		(start 298.038266 -53.217318)
		(mid 298.111064 -52.926555)
		(end 298.031916 -52.637436)
		(width 0.0889)
		(layer "B.Cu")
		(net "UPI_CPU0_CPU1_P1P1_DN<9>")
	)
	(segment
		(start 296.66184 -54.418738)
		(end 296.09034 -54.418738)
		(width 0.1143)
		(layer "F.Cu")
		(net "UPI_CPU0_CPU1_P1P1_DN<8>")
	)
	(segment
		(start 131.948174 -56.894984)
		(end 132.519674 -56.894984)
		(width 0.1143)
		(layer "F.Cu")
		(net "UPI_CPU0_CPU1_P1P1_DN<8>")
	)
	(via
		(at 296.66184 -54.418738)
		(size 0.508)
		(drill 0.254)
		(layers "F.Cu" "B.Cu")
		(net "UPI_CPU0_CPU1_P1P1_DN<8>")
	)
	(via
		(at 132.519674 -56.894984)
		(size 0.508)
		(drill 0.254)
		(layers "F.Cu" "B.Cu")
		(net "UPI_CPU0_CPU1_P1P1_DN<8>")
	)
	(segment
		(start 190.822834 -36.381436)
		(end 196.846444 -36.030662)
		(width 0.1143)
		(layer "B.Cu")
		(net "UPI_CPU0_CPU1_P1P1_DN<8>")
	)
	(segment
		(start 295.915588 -50.37963)
		(end 296.049192 -50.433224)
		(width 0.1143)
		(layer "B.Cu")
		(net "UPI_CPU0_CPU1_P1P1_DN<8>")
	)
	(segment
		(start 132.173218 -55.704486)
		(end 132.182108 -55.689246)
		(width 0.0889)
		(layer "B.Cu")
		(net "UPI_CPU0_CPU1_P1P1_DN<8>")
	)
	(segment
		(start 138.00582 -45.541946)
		(end 138.14679 -45.569124)
		(width 0.1143)
		(layer "B.Cu")
		(net "UPI_CPU0_CPU1_P1P1_DN<8>")
	)
	(segment
		(start 205.272386 -37.715698)
		(end 208.950814 -39.910004)
		(width 0.1143)
		(layer "B.Cu")
		(net "UPI_CPU0_CPU1_P1P1_DN<8>")
	)
	(segment
		(start 164.37991 -41.06164)
		(end 167.346376 -40.335962)
		(width 0.1143)
		(layer "B.Cu")
		(net "UPI_CPU0_CPU1_P1P1_DN<8>")
	)
	(segment
		(start 287.308036 -43.055794)
		(end 290.340288 -45.07357)
		(width 0.1143)
		(layer "B.Cu")
		(net "UPI_CPU0_CPU1_P1P1_DN<8>")
	)
	(segment
		(start 295.780968 -50.064162)
		(end 295.915588 -50.37963)
		(width 0.1143)
		(layer "B.Cu")
		(net "UPI_CPU0_CPU1_P1P1_DN<8>")
	)
	(segment
		(start 296.260774 -50.906172)
		(end 296.26052 -50.906172)
		(width 0.1143)
		(layer "B.Cu")
		(net "UPI_CPU0_CPU1_P1P1_DN<8>")
	)
	(segment
		(start 185.241184 -36.71697)
		(end 186.446414 -37.007038)
		(width 0.1143)
		(layer "B.Cu")
		(net "UPI_CPU0_CPU1_P1P1_DN<8>")
	)
	(segment
		(start 297.062398 -52.385468)
		(end 297.061636 -52.443126)
		(width 0.0889)
		(layer "B.Cu")
		(net "UPI_CPU0_CPU1_P1P1_DN<8>")
	)
	(segment
		(start 294.790622 -47.893224)
		(end 294.762174 -48.034194)
		(width 0.1143)
		(layer "B.Cu")
		(net "UPI_CPU0_CPU1_P1P1_DN<8>")
	)
	(segment
		(start 132.923788 -51.107086)
		(end 133.166104 -50.86477)
		(width 0.1143)
		(layer "B.Cu")
		(net "UPI_CPU0_CPU1_P1P1_DN<8>")
	)
	(segment
		(start 137.409682 -46.066456)
		(end 137.694162 -45.874432)
		(width 0.1143)
		(layer "B.Cu")
		(net "UPI_CPU0_CPU1_P1P1_DN<8>")
	)
	(segment
		(start 295.699942 -49.615598)
		(end 295.834562 -49.930812)
		(width 0.1143)
		(layer "B.Cu")
		(net "UPI_CPU0_CPU1_P1P1_DN<8>")
	)
	(segment
		(start 297.001946 -53.217318)
		(end 297.008296 -53.227986)
		(width 0.0889)
		(layer "B.Cu")
		(net "UPI_CPU0_CPU1_P1P1_DN<8>")
	)
	(segment
		(start 280.230326 -43.27906)
		(end 287.10255 -42.929302)
		(width 0.1143)
		(layer "B.Cu")
		(net "UPI_CPU0_CPU1_P1P1_DN<8>")
	)
	(segment
		(start 132.226812 -57.063894)
		(end 132.148072 -57.042558)
		(width 0.0889)
		(layer "B.Cu")
		(net "UPI_CPU0_CPU1_P1P1_DN<8>")
	)
	(segment
		(start 132.519674 -54.513734)
		(end 132.541264 -54.513734)
		(width 0.0889)
		(layer "B.Cu")
		(net "UPI_CPU0_CPU1_P1P1_DN<8>")
	)
	(segment
		(start 295.28135 -48.634904)
		(end 295.485312 -49.113186)
		(width 0.1143)
		(layer "B.Cu")
		(net "UPI_CPU0_CPU1_P1P1_DN<8>")
	)
	(segment
		(start 133.031484 -52.637436)
		(end 133.03123 -52.637436)
		(width 0.0889)
		(layer "B.Cu")
		(net "UPI_CPU0_CPU1_P1P1_DN<8>")
	)
	(segment
		(start 167.346376 -40.335962)
		(end 171.479464 -41.13911)
		(width 0.1143)
		(layer "B.Cu")
		(net "UPI_CPU0_CPU1_P1P1_DN<8>")
	)
	(segment
		(start 296.183812 -50.748438)
		(end 296.260774 -50.906172)
		(width 0.1143)
		(layer "B.Cu")
		(net "UPI_CPU0_CPU1_P1P1_DN<8>")
	)
	(segment
		(start 297.005756 -52.08524)
		(end 297.062398 -52.286916)
		(width 0.0889)
		(layer "B.Cu")
		(net "UPI_CPU0_CPU1_P1P1_DN<8>")
	)
	(segment
		(start 137.268712 -46.039278)
		(end 137.409682 -46.066456)
		(width 0.1143)
		(layer "B.Cu")
		(net "UPI_CPU0_CPU1_P1P1_DN<8>")
	)
	(segment
		(start 295.431972 -49.246282)
		(end 295.566592 -49.562004)
		(width 0.1143)
		(layer "B.Cu")
		(net "UPI_CPU0_CPU1_P1P1_DN<8>")
	)
	(segment
		(start 291.893752 -45.472858)
		(end 294.257222 -47.086774)
		(width 0.1143)
		(layer "B.Cu")
		(net "UPI_CPU0_CPU1_P1P1_DN<8>")
	)
	(segment
		(start 208.950814 -39.910004)
		(end 210.911694 -40.20439)
		(width 0.1143)
		(layer "B.Cu")
		(net "UPI_CPU0_CPU1_P1P1_DN<8>")
	)
	(segment
		(start 138.883898 -45.072046)
		(end 138.8872 -45.06976)
		(width 0.1143)
		(layer "B.Cu")
		(net "UPI_CPU0_CPU1_P1P1_DN<8>")
	)
	(segment
		(start 287.1216 -42.940986)
		(end 287.308036 -43.055794)
		(width 0.1143)
		(layer "B.Cu")
		(net "UPI_CPU0_CPU1_P1P1_DN<8>")
	)
	(segment
		(start 133.794754 -50.23612)
		(end 133.938518 -50.23612)
		(width 0.1143)
		(layer "B.Cu")
		(net "UPI_CPU0_CPU1_P1P1_DN<8>")
	)
	(segment
		(start 133.938518 -50.23612)
		(end 134.181088 -49.993296)
		(width 0.1143)
		(layer "B.Cu")
		(net "UPI_CPU0_CPU1_P1P1_DN<8>")
	)
	(segment
		(start 136.984486 -46.230794)
		(end 137.268712 -46.039278)
		(width 0.1143)
		(layer "B.Cu")
		(net "UPI_CPU0_CPU1_P1P1_DN<8>")
	)
	(segment
		(start 226.149916 -43.251882)
		(end 239.243616 -40.635428)
		(width 0.1143)
		(layer "B.Cu")
		(net "UPI_CPU0_CPU1_P1P1_DN<8>")
	)
	(segment
		(start 133.552438 -50.478436)
		(end 133.794754 -50.23612)
		(width 0.1143)
		(layer "B.Cu")
		(net "UPI_CPU0_CPU1_P1P1_DN<8>")
	)
	(segment
		(start 250.24715 -37.72027)
		(end 251.769372 -38.422834)
		(width 0.1143)
		(layer "B.Cu")
		(net "UPI_CPU0_CPU1_P1P1_DN<8>")
	)
	(segment
		(start 296.26052 -50.906172)
		(end 296.270172 -50.925984)
		(width 0.0889)
		(layer "B.Cu")
		(net "UPI_CPU0_CPU1_P1P1_DN<8>")
	)
	(segment
		(start 138.458702 -45.23613)
		(end 138.742928 -45.044614)
		(width 0.1143)
		(layer "B.Cu")
		(net "UPI_CPU0_CPU1_P1P1_DN<8>")
	)
	(segment
		(start 134.181088 -49.849786)
		(end 135.294878 -48.735996)
		(width 0.1143)
		(layer "B.Cu")
		(net "UPI_CPU0_CPU1_P1P1_DN<8>")
	)
	(segment
		(start 134.181088 -49.993296)
		(end 134.181088 -49.849786)
		(width 0.1143)
		(layer "B.Cu")
		(net "UPI_CPU0_CPU1_P1P1_DN<8>")
	)
	(segment
		(start 171.479464 -41.13911)
		(end 182.18785 -37.439346)
		(width 0.1143)
		(layer "B.Cu")
		(net "UPI_CPU0_CPU1_P1P1_DN<8>")
	)
	(segment
		(start 287.10255 -42.929302)
		(end 287.1216 -42.940986)
		(width 0.1143)
		(layer "B.Cu")
		(net "UPI_CPU0_CPU1_P1P1_DN<8>")
	)
	(segment
		(start 158.894526 -41.520872)
		(end 159.205168 -41.407334)
		(width 0.1143)
		(layer "B.Cu")
		(net "UPI_CPU0_CPU1_P1P1_DN<8>")
	)
	(segment
		(start 295.092374 -48.349154)
		(end 295.28135 -48.634904)
		(width 0.1143)
		(layer "B.Cu")
		(net "UPI_CPU0_CPU1_P1P1_DN<8>")
	)
	(segment
		(start 132.923788 -51.902614)
		(end 132.923788 -51.880516)
		(width 0.0889)
		(layer "B.Cu")
		(net "UPI_CPU0_CPU1_P1P1_DN<8>")
	)
	(segment
		(start 297.008296 -53.627782)
		(end 297.001946 -53.63845)
		(width 0.0889)
		(layer "B.Cu")
		(net "UPI_CPU0_CPU1_P1P1_DN<8>")
	)
	(segment
		(start 296.270172 -50.925984)
		(end 296.30243 -50.936906)
		(width 0.0889)
		(layer "B.Cu")
		(net "UPI_CPU0_CPU1_P1P1_DN<8>")
	)
	(segment
		(start 132.898388 -52.40782)
		(end 132.898388 -51.928014)
		(width 0.0889)
		(layer "B.Cu")
		(net "UPI_CPU0_CPU1_P1P1_DN<8>")
	)
	(segment
		(start 138.8872 -45.06976)
		(end 139.168378 -44.880022)
		(width 0.1143)
		(layer "B.Cu")
		(net "UPI_CPU0_CPU1_P1P1_DN<8>")
	)
	(segment
		(start 196.846444 -36.030662)
		(end 205.272386 -37.715698)
		(width 0.1143)
		(layer "B.Cu")
		(net "UPI_CPU0_CPU1_P1P1_DN<8>")
	)
	(segment
		(start 133.03123 -52.637436)
		(end 132.898388 -52.40782)
		(width 0.0889)
		(layer "B.Cu")
		(net "UPI_CPU0_CPU1_P1P1_DN<8>")
	)
	(segment
		(start 253.088648 -38.966648)
		(end 256.584704 -38.829488)
		(width 0.1143)
		(layer "B.Cu")
		(net "UPI_CPU0_CPU1_P1P1_DN<8>")
	)
	(segment
		(start 294.257222 -47.086774)
		(end 294.790622 -47.893224)
		(width 0.1143)
		(layer "B.Cu")
		(net "UPI_CPU0_CPU1_P1P1_DN<8>")
	)
	(segment
		(start 132.898388 -51.928014)
		(end 132.923788 -51.902614)
		(width 0.0889)
		(layer "B.Cu")
		(net "UPI_CPU0_CPU1_P1P1_DN<8>")
	)
	(segment
		(start 159.205168 -41.407588)
		(end 161.645092 -40.514778)
		(width 0.1143)
		(layer "B.Cu")
		(net "UPI_CPU0_CPU1_P1P1_DN<8>")
	)
	(segment
		(start 138.43127 -45.377354)
		(end 138.458702 -45.23613)
		(width 0.1143)
		(layer "B.Cu")
		(net "UPI_CPU0_CPU1_P1P1_DN<8>")
	)
	(segment
		(start 140.170662 -44.081446)
		(end 154.72156 -40.710104)
		(width 0.1143)
		(layer "B.Cu")
		(net "UPI_CPU0_CPU1_P1P1_DN<8>")
	)
	(segment
		(start 133.031484 -53.227986)
		(end 133.037834 -53.217318)
		(width 0.0889)
		(layer "B.Cu")
		(net "UPI_CPU0_CPU1_P1P1_DN<8>")
	)
	(segment
		(start 210.911694 -40.20439)
		(end 210.917536 -40.205406)
		(width 0.1143)
		(layer "B.Cu")
		(net "UPI_CPU0_CPU1_P1P1_DN<8>")
	)
	(segment
		(start 132.173218 -56.695086)
		(end 132.182108 -56.679846)
		(width 0.0889)
		(layer "B.Cu")
		(net "UPI_CPU0_CPU1_P1P1_DN<8>")
	)
	(segment
		(start 296.978578 -54.16042)
		(end 296.954702 -54.249828)
		(width 0.0889)
		(layer "B.Cu")
		(net "UPI_CPU0_CPU1_P1P1_DN<8>")
	)
	(segment
		(start 186.446414 -37.007038)
		(end 190.822834 -36.381436)
		(width 0.1143)
		(layer "B.Cu")
		(net "UPI_CPU0_CPU1_P1P1_DN<8>")
	)
	(segment
		(start 133.166104 -50.86477)
		(end 133.309868 -50.86477)
		(width 0.1143)
		(layer "B.Cu")
		(net "UPI_CPU0_CPU1_P1P1_DN<8>")
	)
	(segment
		(start 132.519674 -56.894984)
		(end 132.334 -57.002172)
		(width 0.0889)
		(layer "B.Cu")
		(net "UPI_CPU0_CPU1_P1P1_DN<8>")
	)
	(segment
		(start 295.566592 -49.562004)
		(end 295.699942 -49.615598)
		(width 0.1143)
		(layer "B.Cu")
		(net "UPI_CPU0_CPU1_P1P1_DN<8>")
	)
	(segment
		(start 133.552438 -50.621946)
		(end 133.552438 -50.478436)
		(width 0.1143)
		(layer "B.Cu")
		(net "UPI_CPU0_CPU1_P1P1_DN<8>")
	)
	(segment
		(start 260.618478 -39.357046)
		(end 280.230326 -43.27906)
		(width 0.1143)
		(layer "B.Cu")
		(net "UPI_CPU0_CPU1_P1P1_DN<8>")
	)
	(segment
		(start 138.14679 -45.569124)
		(end 138.43127 -45.377354)
		(width 0.1143)
		(layer "B.Cu")
		(net "UPI_CPU0_CPU1_P1P1_DN<8>")
	)
	(segment
		(start 290.340288 -45.07357)
		(end 291.893752 -45.472858)
		(width 0.1143)
		(layer "B.Cu")
		(net "UPI_CPU0_CPU1_P1P1_DN<8>")
	)
	(segment
		(start 161.645092 -40.514778)
		(end 164.37991 -41.06164)
		(width 0.1143)
		(layer "B.Cu")
		(net "UPI_CPU0_CPU1_P1P1_DN<8>")
	)
	(segment
		(start 159.205168 -41.407334)
		(end 159.205168 -41.407588)
		(width 0.1143)
		(layer "B.Cu")
		(net "UPI_CPU0_CPU1_P1P1_DN<8>")
	)
	(segment
		(start 251.769372 -38.422834)
		(end 253.088648 -38.966648)
		(width 0.1143)
		(layer "B.Cu")
		(net "UPI_CPU0_CPU1_P1P1_DN<8>")
	)
	(segment
		(start 139.19581 -44.739052)
		(end 140.170662 -44.081446)
		(width 0.1143)
		(layer "B.Cu")
		(net "UPI_CPU0_CPU1_P1P1_DN<8>")
	)
	(segment
		(start 132.334 -57.002172)
		(end 132.226812 -57.063894)
		(width 0.0889)
		(layer "B.Cu")
		(net "UPI_CPU0_CPU1_P1P1_DN<8>")
	)
	(segment
		(start 294.951404 -48.320452)
		(end 295.092374 -48.349154)
		(width 0.1143)
		(layer "B.Cu")
		(net "UPI_CPU0_CPU1_P1P1_DN<8>")
	)
	(segment
		(start 182.18785 -37.439346)
		(end 185.241184 -36.71697)
		(width 0.1143)
		(layer "B.Cu")
		(net "UPI_CPU0_CPU1_P1P1_DN<8>")
	)
	(segment
		(start 295.485312 -49.113186)
		(end 295.431972 -49.246282)
		(width 0.1143)
		(layer "B.Cu")
		(net "UPI_CPU0_CPU1_P1P1_DN<8>")
	)
	(segment
		(start 297.062398 -52.286916)
		(end 297.062398 -52.385468)
		(width 0.0889)
		(layer "B.Cu")
		(net "UPI_CPU0_CPU1_P1P1_DN<8>")
	)
	(segment
		(start 242.695476 -38.334696)
		(end 248.006108 -37.27196)
		(width 0.1143)
		(layer "B.Cu")
		(net "UPI_CPU0_CPU1_P1P1_DN<8>")
	)
	(segment
		(start 296.049192 -50.433224)
		(end 296.183812 -50.748438)
		(width 0.1143)
		(layer "B.Cu")
		(net "UPI_CPU0_CPU1_P1P1_DN<8>")
	)
	(segment
		(start 138.742928 -45.044614)
		(end 138.883898 -45.072046)
		(width 0.1143)
		(layer "B.Cu")
		(net "UPI_CPU0_CPU1_P1P1_DN<8>")
	)
	(segment
		(start 296.30243 -50.936906)
		(end 297.005756 -52.08524)
		(width 0.0889)
		(layer "B.Cu")
		(net "UPI_CPU0_CPU1_P1P1_DN<8>")
	)
	(segment
		(start 248.006108 -37.27196)
		(end 250.24715 -37.72027)
		(width 0.1143)
		(layer "B.Cu")
		(net "UPI_CPU0_CPU1_P1P1_DN<8>")
	)
	(segment
		(start 154.72156 -40.710104)
		(end 158.894526 -41.520872)
		(width 0.1143)
		(layer "B.Cu")
		(net "UPI_CPU0_CPU1_P1P1_DN<8>")
	)
	(segment
		(start 139.168378 -44.880022)
		(end 139.19581 -44.739052)
		(width 0.1143)
		(layer "B.Cu")
		(net "UPI_CPU0_CPU1_P1P1_DN<8>")
	)
	(segment
		(start 295.834562 -49.930812)
		(end 295.780968 -50.064162)
		(width 0.1143)
		(layer "B.Cu")
		(net "UPI_CPU0_CPU1_P1P1_DN<8>")
	)
	(segment
		(start 137.721594 -45.733462)
		(end 138.00582 -45.541946)
		(width 0.1143)
		(layer "B.Cu")
		(net "UPI_CPU0_CPU1_P1P1_DN<8>")
	)
	(segment
		(start 133.309868 -50.86477)
		(end 133.552438 -50.621946)
		(width 0.1143)
		(layer "B.Cu")
		(net "UPI_CPU0_CPU1_P1P1_DN<8>")
	)
	(segment
		(start 135.294878 -48.735996)
		(end 136.984486 -46.230794)
		(width 0.1143)
		(layer "B.Cu")
		(net "UPI_CPU0_CPU1_P1P1_DN<8>")
	)
	(segment
		(start 296.954702 -54.249828)
		(end 296.66184 -54.418738)
		(width 0.0889)
		(layer "B.Cu")
		(net "UPI_CPU0_CPU1_P1P1_DN<8>")
	)
	(segment
		(start 294.762174 -48.034194)
		(end 294.951404 -48.320452)
		(width 0.1143)
		(layer "B.Cu")
		(net "UPI_CPU0_CPU1_P1P1_DN<8>")
	)
	(segment
		(start 256.584704 -38.829488)
		(end 260.618478 -39.357046)
		(width 0.1143)
		(layer "B.Cu")
		(net "UPI_CPU0_CPU1_P1P1_DN<8>")
	)
	(segment
		(start 239.243616 -40.635428)
		(end 242.695476 -38.334696)
		(width 0.1143)
		(layer "B.Cu")
		(net "UPI_CPU0_CPU1_P1P1_DN<8>")
	)
	(segment
		(start 210.917536 -40.205406)
		(end 222.396812 -42.501312)
		(width 0.1143)
		(layer "B.Cu")
		(net "UPI_CPU0_CPU1_P1P1_DN<8>")
	)
	(segment
		(start 137.694162 -45.874432)
		(end 137.721594 -45.733462)
		(width 0.1143)
		(layer "B.Cu")
		(net "UPI_CPU0_CPU1_P1P1_DN<8>")
	)
	(segment
		(start 222.396812 -42.501312)
		(end 226.149916 -43.251882)
		(width 0.1143)
		(layer "B.Cu")
		(net "UPI_CPU0_CPU1_P1P1_DN<8>")
	)
	(segment
		(start 132.923788 -51.880516)
		(end 132.923788 -51.107086)
		(width 0.1143)
		(layer "B.Cu")
		(net "UPI_CPU0_CPU1_P1P1_DN<8>")
	)
	(arc
		(start 297.001946 -53.63845)
		(mid 296.929429 -53.896716)
		(end 296.978578 -54.16042)
		(width 0.0889)
		(layer "B.Cu")
		(net "UPI_CPU0_CPU1_P1P1_DN<8>")
	)
	(arc
		(start 297.008296 -52.637436)
		(mid 296.929074 -52.926554)
		(end 297.001946 -53.217318)
		(width 0.0889)
		(layer "B.Cu")
		(net "UPI_CPU0_CPU1_P1P1_DN<8>")
	)
	(arc
		(start 297.008296 -53.227986)
		(mid 297.061829 -53.427884)
		(end 297.008296 -53.627782)
		(width 0.0889)
		(layer "B.Cu")
		(net "UPI_CPU0_CPU1_P1P1_DN<8>")
	)
	(arc
		(start 132.173218 -56.104282)
		(mid 132.119685 -55.904384)
		(end 132.173218 -55.704486)
		(width 0.0889)
		(layer "B.Cu")
		(net "UPI_CPU0_CPU1_P1P1_DN<8>")
	)
	(arc
		(start 133.031484 -53.627782)
		(mid 132.977985 -53.427884)
		(end 133.031484 -53.227986)
		(width 0.0889)
		(layer "B.Cu")
		(net "UPI_CPU0_CPU1_P1P1_DN<8>")
	)
	(arc
		(start 132.173218 -55.113682)
		(mid 132.173301 -54.713741)
		(end 132.519674 -54.513734)
		(width 0.0889)
		(layer "B.Cu")
		(net "UPI_CPU0_CPU1_P1P1_DN<8>")
	)
	(arc
		(start 132.182108 -55.689246)
		(mid 132.252505 -55.400295)
		(end 132.173218 -55.113682)
		(width 0.0889)
		(layer "B.Cu")
		(net "UPI_CPU0_CPU1_P1P1_DN<8>")
	)
	(arc
		(start 132.182108 -56.679846)
		(mid 132.252505 -56.390895)
		(end 132.173218 -56.104282)
		(width 0.0889)
		(layer "B.Cu")
		(net "UPI_CPU0_CPU1_P1P1_DN<8>")
	)
	(arc
		(start 133.037834 -53.217318)
		(mid 133.110632 -52.926555)
		(end 133.031484 -52.637436)
		(width 0.0889)
		(layer "B.Cu")
		(net "UPI_CPU0_CPU1_P1P1_DN<8>")
	)
	(arc
		(start 132.148072 -57.042558)
		(mid 132.120786 -56.86593)
		(end 132.173218 -56.695086)
		(width 0.0889)
		(layer "B.Cu")
		(net "UPI_CPU0_CPU1_P1P1_DN<8>")
	)
	(arc
		(start 132.541264 -54.513734)
		(mid 133.036741 -54.209291)
		(end 133.031484 -53.627782)
		(width 0.0889)
		(layer "B.Cu")
		(net "UPI_CPU0_CPU1_P1P1_DN<8>")
	)
	(arc
		(start 297.061636 -52.443126)
		(mid 297.047393 -52.54369)
		(end 297.008296 -52.637436)
		(width 0.0889)
		(layer "B.Cu")
		(net "UPI_CPU0_CPU1_P1P1_DN<8>")
	)
	(segment
		(start 132.806694 -56.399938)
		(end 133.378194 -56.399938)
		(width 0.1143)
		(layer "F.Cu")
		(net "UPI_CPU0_CPU1_P1P1_DN<7>")
	)
	(segment
		(start 295.23182 -52.932838)
		(end 295.80332 -52.932838)
		(width 0.1143)
		(layer "F.Cu")
		(net "UPI_CPU0_CPU1_P1P1_DN<7>")
	)
	(via
		(at 133.378194 -56.399938)
		(size 0.508)
		(drill 0.254)
		(layers "F.Cu" "B.Cu")
		(net "UPI_CPU0_CPU1_P1P1_DN<7>")
	)
	(via
		(at 295.80332 -52.932838)
		(size 0.508)
		(drill 0.254)
		(layers "F.Cu" "B.Cu")
		(net "UPI_CPU0_CPU1_P1P1_DN<7>")
	)
	(segment
		(start 171.748704 -42.325544)
		(end 180.931566 -38.898068)
		(width 0.1143)
		(layer "B.Cu")
		(net "UPI_CPU0_CPU1_P1P1_DN<7>")
	)
	(segment
		(start 164.495988 -42.07383)
		(end 164.604954 -42.070782)
		(width 0.1143)
		(layer "B.Cu")
		(net "UPI_CPU0_CPU1_P1P1_DN<7>")
	)
	(segment
		(start 180.931566 -38.898068)
		(end 185.11266 -37.771324)
		(width 0.1143)
		(layer "B.Cu")
		(net "UPI_CPU0_CPU1_P1P1_DN<7>")
	)
	(segment
		(start 294.17645 -49.680368)
		(end 294.31742 -49.708562)
		(width 0.1143)
		(layer "B.Cu")
		(net "UPI_CPU0_CPU1_P1P1_DN<7>")
	)
	(segment
		(start 296.017442 -52.08778)
		(end 296.071798 -52.469288)
		(width 0.0889)
		(layer "B.Cu")
		(net "UPI_CPU0_CPU1_P1P1_DN<7>")
	)
	(segment
		(start 138.912092 -46.569376)
		(end 139.196572 -46.377606)
		(width 0.1143)
		(layer "B.Cu")
		(net "UPI_CPU0_CPU1_P1P1_DN<7>")
	)
	(segment
		(start 139.961112 -45.73905)
		(end 140.843 -45.144436)
		(width 0.1143)
		(layer "B.Cu")
		(net "UPI_CPU0_CPU1_P1P1_DN<7>")
	)
	(segment
		(start 196.881496 -36.825174)
		(end 204.788008 -38.406324)
		(width 0.1143)
		(layer "B.Cu")
		(net "UPI_CPU0_CPU1_P1P1_DN<7>")
	)
	(segment
		(start 295.194228 -51.023774)
		(end 295.20769 -51.023774)
		(width 0.0889)
		(layer "B.Cu")
		(net "UPI_CPU0_CPU1_P1P1_DN<7>")
	)
	(segment
		(start 295.74998 -51.677062)
		(end 295.896792 -51.855878)
		(width 0.0889)
		(layer "B.Cu")
		(net "UPI_CPU0_CPU1_P1P1_DN<7>")
	)
	(segment
		(start 294.014144 -49.253902)
		(end 293.98595 -49.394872)
		(width 0.1143)
		(layer "B.Cu")
		(net "UPI_CPU0_CPU1_P1P1_DN<7>")
	)
	(segment
		(start 138.034014 -47.03953)
		(end 138.174984 -47.066708)
		(width 0.1143)
		(layer "B.Cu")
		(net "UPI_CPU0_CPU1_P1P1_DN<7>")
	)
	(segment
		(start 134.760462 -50.99177)
		(end 134.760462 -50.85207)
		(width 0.0889)
		(layer "B.Cu")
		(net "UPI_CPU0_CPU1_P1P1_DN<7>")
	)
	(segment
		(start 138.486896 -46.733714)
		(end 138.771122 -46.542198)
		(width 0.1143)
		(layer "B.Cu")
		(net "UPI_CPU0_CPU1_P1P1_DN<7>")
	)
	(segment
		(start 294.479472 -50.13452)
		(end 294.669718 -50.42027)
		(width 0.1143)
		(layer "B.Cu")
		(net "UPI_CPU0_CPU1_P1P1_DN<7>")
	)
	(segment
		(start 243.716556 -38.908482)
		(end 248.00814 -38.050216)
		(width 0.1143)
		(layer "B.Cu")
		(net "UPI_CPU0_CPU1_P1P1_DN<7>")
	)
	(segment
		(start 161.7345 -41.521888)
		(end 164.495988 -42.07383)
		(width 0.1143)
		(layer "B.Cu")
		(net "UPI_CPU0_CPU1_P1P1_DN<7>")
	)
	(segment
		(start 222.396812 -43.494452)
		(end 226.19462 -44.246546)
		(width 0.1143)
		(layer "B.Cu")
		(net "UPI_CPU0_CPU1_P1P1_DN<7>")
	)
	(segment
		(start 159.22371 -42.569638)
		(end 161.7345 -41.521888)
		(width 0.1143)
		(layer "B.Cu")
		(net "UPI_CPU0_CPU1_P1P1_DN<7>")
	)
	(segment
		(start 140.843 -45.144436)
		(end 141.38783 -45.035978)
		(width 0.1143)
		(layer "B.Cu")
		(net "UPI_CPU0_CPU1_P1P1_DN<7>")
	)
	(segment
		(start 287.07588 -43.917108)
		(end 289.983926 -45.827188)
		(width 0.1143)
		(layer "B.Cu")
		(net "UPI_CPU0_CPU1_P1P1_DN<7>")
	)
	(segment
		(start 137.78103 -47.209964)
		(end 138.034014 -47.03953)
		(width 0.1143)
		(layer "B.Cu")
		(net "UPI_CPU0_CPU1_P1P1_DN<7>")
	)
	(segment
		(start 239.785398 -41.529508)
		(end 243.716556 -38.908482)
		(width 0.1143)
		(layer "B.Cu")
		(net "UPI_CPU0_CPU1_P1P1_DN<7>")
	)
	(segment
		(start 260.965442 -40.443912)
		(end 261.09676 -40.454072)
		(width 0.1143)
		(layer "B.Cu")
		(net "UPI_CPU0_CPU1_P1P1_DN<7>")
	)
	(segment
		(start 138.771122 -46.542198)
		(end 138.912092 -46.569376)
		(width 0.1143)
		(layer "B.Cu")
		(net "UPI_CPU0_CPU1_P1P1_DN<7>")
	)
	(segment
		(start 139.50823 -46.044866)
		(end 139.6492 -46.072298)
		(width 0.1143)
		(layer "B.Cu")
		(net "UPI_CPU0_CPU1_P1P1_DN<7>")
	)
	(segment
		(start 134.369302 -51.24323)
		(end 134.495032 -51.1175)
		(width 0.0889)
		(layer "B.Cu")
		(net "UPI_CPU0_CPU1_P1P1_DN<7>")
	)
	(segment
		(start 134.369302 -51.38293)
		(end 134.369302 -51.24323)
		(width 0.0889)
		(layer "B.Cu")
		(net "UPI_CPU0_CPU1_P1P1_DN<7>")
	)
	(segment
		(start 155.01239 -41.75125)
		(end 159.22371 -42.569638)
		(width 0.1143)
		(layer "B.Cu")
		(net "UPI_CPU0_CPU1_P1P1_DN<7>")
	)
	(segment
		(start 186.501532 -38.025324)
		(end 190.760604 -37.173662)
		(width 0.1143)
		(layer "B.Cu")
		(net "UPI_CPU0_CPU1_P1P1_DN<7>")
	)
	(segment
		(start 295.511474 -51.515518)
		(end 295.635172 -51.666394)
		(width 0.0889)
		(layer "B.Cu")
		(net "UPI_CPU0_CPU1_P1P1_DN<7>")
	)
	(segment
		(start 139.196572 -46.377606)
		(end 139.224004 -46.236382)
		(width 0.1143)
		(layer "B.Cu")
		(net "UPI_CPU0_CPU1_P1P1_DN<7>")
	)
	(segment
		(start 292.84295 -47.496222)
		(end 294.014144 -49.253902)
		(width 0.1143)
		(layer "B.Cu")
		(net "UPI_CPU0_CPU1_P1P1_DN<7>")
	)
	(segment
		(start 294.31742 -49.708562)
		(end 294.507412 -49.993804)
		(width 0.1143)
		(layer "B.Cu")
		(net "UPI_CPU0_CPU1_P1P1_DN<7>")
	)
	(segment
		(start 167.365172 -41.342564)
		(end 171.748704 -42.325544)
		(width 0.1143)
		(layer "B.Cu")
		(net "UPI_CPU0_CPU1_P1P1_DN<7>")
	)
	(segment
		(start 133.94944 -51.663092)
		(end 134.103872 -51.50866)
		(width 0.0889)
		(layer "B.Cu")
		(net "UPI_CPU0_CPU1_P1P1_DN<7>")
	)
	(segment
		(start 133.896354 -53.143404)
		(end 133.890004 -53.132736)
		(width 0.0889)
		(layer "B.Cu")
		(net "UPI_CPU0_CPU1_P1P1_DN<7>")
	)
	(segment
		(start 133.363208 -55.009288)
		(end 133.395974 -55.009288)
		(width 0.0889)
		(layer "B.Cu")
		(net "UPI_CPU0_CPU1_P1P1_DN<7>")
	)
	(segment
		(start 249.809254 -38.410642)
		(end 249.810016 -38.410896)
		(width 0.1143)
		(layer "B.Cu")
		(net "UPI_CPU0_CPU1_P1P1_DN<7>")
	)
	(segment
		(start 139.224004 -46.236382)
		(end 139.50823 -46.044866)
		(width 0.1143)
		(layer "B.Cu")
		(net "UPI_CPU0_CPU1_P1P1_DN<7>")
	)
	(segment
		(start 135.151622 -50.60061)
		(end 135.151622 -50.46091)
		(width 0.0889)
		(layer "B.Cu")
		(net "UPI_CPU0_CPU1_P1P1_DN<7>")
	)
	(segment
		(start 136.418574 -49.229772)
		(end 137.78103 -47.209964)
		(width 0.1143)
		(layer "B.Cu")
		(net "UPI_CPU0_CPU1_P1P1_DN<7>")
	)
	(segment
		(start 279.491186 -44.133516)
		(end 279.494742 -44.134532)
		(width 0.1143)
		(layer "B.Cu")
		(net "UPI_CPU0_CPU1_P1P1_DN<7>")
	)
	(segment
		(start 204.788008 -38.406324)
		(end 208.425034 -40.727376)
		(width 0.1143)
		(layer "B.Cu")
		(net "UPI_CPU0_CPU1_P1P1_DN<7>")
	)
	(segment
		(start 138.459464 -46.874684)
		(end 138.486896 -46.733714)
		(width 0.1143)
		(layer "B.Cu")
		(net "UPI_CPU0_CPU1_P1P1_DN<7>")
	)
	(segment
		(start 133.885178 -53.731922)
		(end 133.890004 -53.723286)
		(width 0.0889)
		(layer "B.Cu")
		(net "UPI_CPU0_CPU1_P1P1_DN<7>")
	)
	(segment
		(start 190.760604 -37.173662)
		(end 196.881496 -36.825174)
		(width 0.1143)
		(layer "B.Cu")
		(net "UPI_CPU0_CPU1_P1P1_DN<7>")
	)
	(segment
		(start 133.037834 -55.619904)
		(end 133.031484 -55.609236)
		(width 0.0889)
		(layer "B.Cu")
		(net "UPI_CPU0_CPU1_P1P1_DN<7>")
	)
	(segment
		(start 296.05478 -53.127148)
		(end 296.006012 -53.140356)
		(width 0.0889)
		(layer "B.Cu")
		(net "UPI_CPU0_CPU1_P1P1_DN<7>")
	)
	(segment
		(start 139.6492 -46.072298)
		(end 139.93368 -45.880274)
		(width 0.1143)
		(layer "B.Cu")
		(net "UPI_CPU0_CPU1_P1P1_DN<7>")
	)
	(segment
		(start 248.00814 -38.050216)
		(end 249.809254 -38.410642)
		(width 0.1143)
		(layer "B.Cu")
		(net "UPI_CPU0_CPU1_P1P1_DN<7>")
	)
	(segment
		(start 294.669718 -50.42027)
		(end 294.810688 -50.44821)
		(width 0.1143)
		(layer "B.Cu")
		(net "UPI_CPU0_CPU1_P1P1_DN<7>")
	)
	(segment
		(start 134.634732 -51.1175)
		(end 134.760462 -50.99177)
		(width 0.0889)
		(layer "B.Cu")
		(net "UPI_CPU0_CPU1_P1P1_DN<7>")
	)
	(segment
		(start 293.98595 -49.394872)
		(end 294.17645 -49.680368)
		(width 0.1143)
		(layer "B.Cu")
		(net "UPI_CPU0_CPU1_P1P1_DN<7>")
	)
	(segment
		(start 135.286496 -50.326036)
		(end 135.337804 -50.310542)
		(width 0.0889)
		(layer "B.Cu")
		(net "UPI_CPU0_CPU1_P1P1_DN<7>")
	)
	(segment
		(start 279.494742 -44.134532)
		(end 280.048208 -44.261278)
		(width 0.1143)
		(layer "B.Cu")
		(net "UPI_CPU0_CPU1_P1P1_DN<7>")
	)
	(segment
		(start 291.20846 -46.124876)
		(end 292.84295 -47.496222)
		(width 0.1143)
		(layer "B.Cu")
		(net "UPI_CPU0_CPU1_P1P1_DN<7>")
	)
	(segment
		(start 256.392426 -39.903654)
		(end 260.965442 -40.443912)
		(width 0.1143)
		(layer "B.Cu")
		(net "UPI_CPU0_CPU1_P1P1_DN<7>")
	)
	(segment
		(start 134.103872 -51.50866)
		(end 134.243572 -51.50866)
		(width 0.0889)
		(layer "B.Cu")
		(net "UPI_CPU0_CPU1_P1P1_DN<7>")
	)
	(segment
		(start 295.896792 -51.855878)
		(end 296.017442 -52.08778)
		(width 0.0889)
		(layer "B.Cu")
		(net "UPI_CPU0_CPU1_P1P1_DN<7>")
	)
	(segment
		(start 252.588014 -39.971218)
		(end 256.392426 -39.903654)
		(width 0.1143)
		(layer "B.Cu")
		(net "UPI_CPU0_CPU1_P1P1_DN<7>")
	)
	(segment
		(start 261.09676 -40.454072)
		(end 279.491186 -44.133516)
		(width 0.1143)
		(layer "B.Cu")
		(net "UPI_CPU0_CPU1_P1P1_DN<7>")
	)
	(segment
		(start 249.810016 -38.410896)
		(end 252.588014 -39.971218)
		(width 0.1143)
		(layer "B.Cu")
		(net "UPI_CPU0_CPU1_P1P1_DN<7>")
	)
	(segment
		(start 134.495032 -51.1175)
		(end 134.634732 -51.1175)
		(width 0.0889)
		(layer "B.Cu")
		(net "UPI_CPU0_CPU1_P1P1_DN<7>")
	)
	(segment
		(start 135.025892 -50.72634)
		(end 135.151622 -50.60061)
		(width 0.0889)
		(layer "B.Cu")
		(net "UPI_CPU0_CPU1_P1P1_DN<7>")
	)
	(segment
		(start 296.15003 -52.732686)
		(end 296.149776 -52.732686)
		(width 0.0889)
		(layer "B.Cu")
		(net "UPI_CPU0_CPU1_P1P1_DN<7>")
	)
	(segment
		(start 295.242488 -51.058572)
		(end 295.523158 -51.400964)
		(width 0.0889)
		(layer "B.Cu")
		(net "UPI_CPU0_CPU1_P1P1_DN<7>")
	)
	(segment
		(start 164.604954 -42.070782)
		(end 167.365172 -41.342564)
		(width 0.1143)
		(layer "B.Cu")
		(net "UPI_CPU0_CPU1_P1P1_DN<7>")
	)
	(segment
		(start 295.832276 -53.04028)
		(end 295.80332 -52.932838)
		(width 0.0889)
		(layer "B.Cu")
		(net "UPI_CPU0_CPU1_P1P1_DN<7>")
	)
	(segment
		(start 139.93368 -45.880274)
		(end 139.961112 -45.73905)
		(width 0.1143)
		(layer "B.Cu")
		(net "UPI_CPU0_CPU1_P1P1_DN<7>")
	)
	(segment
		(start 133.378194 -56.399938)
		(end 133.378194 -56.738012)
		(width 0.0889)
		(layer "B.Cu")
		(net "UPI_CPU0_CPU1_P1P1_DN<7>")
	)
	(segment
		(start 208.425034 -40.727376)
		(end 222.396812 -43.494452)
		(width 0.1143)
		(layer "B.Cu")
		(net "UPI_CPU0_CPU1_P1P1_DN<7>")
	)
	(segment
		(start 135.337804 -50.310542)
		(end 136.418574 -49.229772)
		(width 0.1143)
		(layer "B.Cu")
		(net "UPI_CPU0_CPU1_P1P1_DN<7>")
	)
	(segment
		(start 134.886192 -50.72634)
		(end 135.025892 -50.72634)
		(width 0.0889)
		(layer "B.Cu")
		(net "UPI_CPU0_CPU1_P1P1_DN<7>")
	)
	(segment
		(start 280.048208 -44.261278)
		(end 287.07588 -43.917108)
		(width 0.1143)
		(layer "B.Cu")
		(net "UPI_CPU0_CPU1_P1P1_DN<7>")
	)
	(segment
		(start 226.19462 -44.246546)
		(end 239.785398 -41.529508)
		(width 0.1143)
		(layer "B.Cu")
		(net "UPI_CPU0_CPU1_P1P1_DN<7>")
	)
	(segment
		(start 295.20769 -51.023774)
		(end 295.242488 -51.058572)
		(width 0.0889)
		(layer "B.Cu")
		(net "UPI_CPU0_CPU1_P1P1_DN<7>")
	)
	(segment
		(start 289.983926 -45.827188)
		(end 291.20846 -46.124876)
		(width 0.1143)
		(layer "B.Cu")
		(net "UPI_CPU0_CPU1_P1P1_DN<7>")
	)
	(segment
		(start 296.149776 -52.732686)
		(end 296.15003 -52.73294)
		(width 0.0889)
		(layer "B.Cu")
		(net "UPI_CPU0_CPU1_P1P1_DN<7>")
	)
	(segment
		(start 295.523158 -51.400964)
		(end 295.511474 -51.515518)
		(width 0.0889)
		(layer "B.Cu")
		(net "UPI_CPU0_CPU1_P1P1_DN<7>")
	)
	(segment
		(start 294.507412 -49.993804)
		(end 294.479472 -50.13452)
		(width 0.1143)
		(layer "B.Cu")
		(net "UPI_CPU0_CPU1_P1P1_DN<7>")
	)
	(segment
		(start 296.006012 -53.140356)
		(end 295.832276 -53.04028)
		(width 0.0889)
		(layer "B.Cu")
		(net "UPI_CPU0_CPU1_P1P1_DN<7>")
	)
	(segment
		(start 295.635172 -51.666394)
		(end 295.74998 -51.677062)
		(width 0.0889)
		(layer "B.Cu")
		(net "UPI_CPU0_CPU1_P1P1_DN<7>")
	)
	(segment
		(start 141.38783 -45.035978)
		(end 155.01239 -41.75125)
		(width 0.1143)
		(layer "B.Cu")
		(net "UPI_CPU0_CPU1_P1P1_DN<7>")
	)
	(segment
		(start 134.760462 -50.85207)
		(end 134.886192 -50.72634)
		(width 0.0889)
		(layer "B.Cu")
		(net "UPI_CPU0_CPU1_P1P1_DN<7>")
	)
	(segment
		(start 134.243572 -51.50866)
		(end 134.369302 -51.38293)
		(width 0.0889)
		(layer "B.Cu")
		(net "UPI_CPU0_CPU1_P1P1_DN<7>")
	)
	(segment
		(start 133.031484 -55.609236)
		(end 133.026658 -55.6006)
		(width 0.0889)
		(layer "B.Cu")
		(net "UPI_CPU0_CPU1_P1P1_DN<7>")
	)
	(segment
		(start 133.378194 -56.738012)
		(end 133.320282 -56.795924)
		(width 0.0889)
		(layer "B.Cu")
		(net "UPI_CPU0_CPU1_P1P1_DN<7>")
	)
	(segment
		(start 138.174984 -47.066708)
		(end 138.459464 -46.874684)
		(width 0.1143)
		(layer "B.Cu")
		(net "UPI_CPU0_CPU1_P1P1_DN<7>")
	)
	(segment
		(start 135.151622 -50.46091)
		(end 135.286496 -50.326036)
		(width 0.0889)
		(layer "B.Cu")
		(net "UPI_CPU0_CPU1_P1P1_DN<7>")
	)
	(segment
		(start 294.810688 -50.44821)
		(end 295.194228 -51.023774)
		(width 0.1143)
		(layer "B.Cu")
		(net "UPI_CPU0_CPU1_P1P1_DN<7>")
	)
	(segment
		(start 185.11266 -37.771324)
		(end 186.501532 -38.025324)
		(width 0.1143)
		(layer "B.Cu")
		(net "UPI_CPU0_CPU1_P1P1_DN<7>")
	)
	(arc
		(start 133.320282 -56.795924)
		(mid 133.185054 -56.75038)
		(end 133.07441 -56.660288)
		(width 0.0889)
		(layer "B.Cu")
		(net "UPI_CPU0_CPU1_P1P1_DN<7>")
	)
	(arc
		(start 133.890004 -52.73294)
		(mid 133.969135 -52.437538)
		(end 133.890004 -52.142136)
		(width 0.0889)
		(layer "B.Cu")
		(net "UPI_CPU0_CPU1_P1P1_DN<7>")
	)
	(arc
		(start 133.890004 -53.132736)
		(mid 133.836505 -52.932838)
		(end 133.890004 -52.73294)
		(width 0.0889)
		(layer "B.Cu")
		(net "UPI_CPU0_CPU1_P1P1_DN<7>")
	)
	(arc
		(start 133.890004 -54.123336)
		(mid 133.836534 -53.928273)
		(end 133.885178 -53.731922)
		(width 0.0889)
		(layer "B.Cu")
		(net "UPI_CPU0_CPU1_P1P1_DN<7>")
	)
	(arc
		(start 133.07441 -56.660288)
		(mid 132.979736 -56.436859)
		(end 133.031484 -56.199786)
		(width 0.0889)
		(layer "B.Cu")
		(net "UPI_CPU0_CPU1_P1P1_DN<7>")
	)
	(arc
		(start 133.026658 -55.6006)
		(mid 133.030405 -55.211344)
		(end 133.363208 -55.009288)
		(width 0.0889)
		(layer "B.Cu")
		(net "UPI_CPU0_CPU1_P1P1_DN<7>")
	)
	(arc
		(start 296.15003 -52.73294)
		(mid 296.189844 -52.829511)
		(end 296.20337 -52.933092)
		(width 0.0889)
		(layer "B.Cu")
		(net "UPI_CPU0_CPU1_P1P1_DN<7>")
	)
	(arc
		(start 133.890004 -53.723286)
		(mid 133.969226 -53.434168)
		(end 133.896354 -53.143404)
		(width 0.0889)
		(layer "B.Cu")
		(net "UPI_CPU0_CPU1_P1P1_DN<7>")
	)
	(arc
		(start 133.031484 -56.199786)
		(mid 133.110706 -55.910668)
		(end 133.037834 -55.619904)
		(width 0.0889)
		(layer "B.Cu")
		(net "UPI_CPU0_CPU1_P1P1_DN<7>")
	)
	(arc
		(start 296.071798 -52.469288)
		(mid 296.095407 -52.605591)
		(end 296.15003 -52.732686)
		(width 0.0889)
		(layer "B.Cu")
		(net "UPI_CPU0_CPU1_P1P1_DN<7>")
	)
	(arc
		(start 296.20337 -52.933092)
		(mid 296.161873 -53.055206)
		(end 296.05478 -53.127148)
		(width 0.0889)
		(layer "B.Cu")
		(net "UPI_CPU0_CPU1_P1P1_DN<7>")
	)
	(arc
		(start 133.395974 -55.009288)
		(mid 133.894225 -54.706448)
		(end 133.890004 -54.123336)
		(width 0.0889)
		(layer "B.Cu")
		(net "UPI_CPU0_CPU1_P1P1_DN<7>")
	)
	(arc
		(start 133.890004 -52.142136)
		(mid 133.839428 -51.89266)
		(end 133.94944 -51.663092)
		(width 0.0889)
		(layer "B.Cu")
		(net "UPI_CPU0_CPU1_P1P1_DN<7>")
	)
	(segment
		(start 132.806694 -59.371484)
		(end 133.378194 -59.371484)
		(width 0.1143)
		(layer "F.Cu")
		(net "UPI_CPU0_CPU1_P1P1_DN<6>")
	)
	(segment
		(start 295.23182 -53.923184)
		(end 295.80332 -53.923184)
		(width 0.1143)
		(layer "F.Cu")
		(net "UPI_CPU0_CPU1_P1P1_DN<6>")
	)
	(via
		(at 133.378194 -59.371484)
		(size 0.508)
		(drill 0.254)
		(layers "F.Cu" "B.Cu")
		(net "UPI_CPU0_CPU1_P1P1_DN<6>")
	)
	(via
		(at 295.80332 -53.923184)
		(size 0.508)
		(drill 0.254)
		(layers "F.Cu" "B.Cu")
		(net "UPI_CPU0_CPU1_P1P1_DN<6>")
	)
	(segment
		(start 152.876504 -43.144948)
		(end 155.25623 -42.545508)
		(width 0.1143)
		(layer "B.Cu")
		(net "UPI_CPU0_CPU1_P1P1_DN<6>")
	)
	(segment
		(start 240.188496 -42.292778)
		(end 244.747288 -39.253922)
		(width 0.1143)
		(layer "B.Cu")
		(net "UPI_CPU0_CPU1_P1P1_DN<6>")
	)
	(segment
		(start 135.441944 -51.646836)
		(end 135.600694 -51.371754)
		(width 0.0889)
		(layer "B.Cu")
		(net "UPI_CPU0_CPU1_P1P1_DN<6>")
	)
	(segment
		(start 291.737796 -47.631858)
		(end 292.697154 -48.86071)
		(width 0.1143)
		(layer "B.Cu")
		(net "UPI_CPU0_CPU1_P1P1_DN<6>")
	)
	(segment
		(start 287.082484 -44.678854)
		(end 289.967416 -46.51248)
		(width 0.1143)
		(layer "B.Cu")
		(net "UPI_CPU0_CPU1_P1P1_DN<6>")
	)
	(segment
		(start 135.113268 -53.028088)
		(end 135.073644 -53.028088)
		(width 0.0889)
		(layer "B.Cu")
		(net "UPI_CPU0_CPU1_P1P1_DN<6>")
	)
	(segment
		(start 135.073644 -51.846988)
		(end 135.109712 -51.846988)
		(width 0.0889)
		(layer "B.Cu")
		(net "UPI_CPU0_CPU1_P1P1_DN<6>")
	)
	(segment
		(start 295.53535 -52.11572)
		(end 295.53535 -52.447698)
		(width 0.0889)
		(layer "B.Cu")
		(net "UPI_CPU0_CPU1_P1P1_DN<6>")
	)
	(segment
		(start 280.028904 -45.013118)
		(end 287.082484 -44.678854)
		(width 0.1143)
		(layer "B.Cu")
		(net "UPI_CPU0_CPU1_P1P1_DN<6>")
	)
	(segment
		(start 295.45661 -52.732686)
		(end 295.45661 -52.73294)
		(width 0.0889)
		(layer "B.Cu")
		(net "UPI_CPU0_CPU1_P1P1_DN<6>")
	)
	(segment
		(start 294.477694 -51.02225)
		(end 294.493188 -51.037744)
		(width 0.0889)
		(layer "B.Cu")
		(net "UPI_CPU0_CPU1_P1P1_DN<6>")
	)
	(segment
		(start 295.681654 -54.304438)
		(end 295.681654 -54.304692)
		(width 0.0889)
		(layer "B.Cu")
		(net "UPI_CPU0_CPU1_P1P1_DN<6>")
	)
	(segment
		(start 133.724904 -56.599836)
		(end 133.72973 -56.5912)
		(width 0.0889)
		(layer "B.Cu")
		(net "UPI_CPU0_CPU1_P1P1_DN<6>")
	)
	(segment
		(start 161.850832 -42.292524)
		(end 163.949888 -42.711878)
		(width 0.1143)
		(layer "B.Cu")
		(net "UPI_CPU0_CPU1_P1P1_DN<6>")
	)
	(segment
		(start 133.440932 -59.309)
		(end 133.485382 -59.26455)
		(width 0.0889)
		(layer "B.Cu")
		(net "UPI_CPU0_CPU1_P1P1_DN<6>")
	)
	(segment
		(start 167.14597 -42.189146)
		(end 171.038012 -43.208702)
		(width 0.1143)
		(layer "B.Cu")
		(net "UPI_CPU0_CPU1_P1P1_DN<6>")
	)
	(segment
		(start 196.998082 -37.380418)
		(end 204.352652 -38.851332)
		(width 0.1143)
		(layer "B.Cu")
		(net "UPI_CPU0_CPU1_P1P1_DN<6>")
	)
	(segment
		(start 290.53282 -46.658784)
		(end 291.737796 -47.631858)
		(width 0.1143)
		(layer "B.Cu")
		(net "UPI_CPU0_CPU1_P1P1_DN<6>")
	)
	(segment
		(start 181.385464 -41.142158)
		(end 185.943494 -39.9034)
		(width 0.1143)
		(layer "B.Cu")
		(net "UPI_CPU0_CPU1_P1P1_DN<6>")
	)
	(segment
		(start 295.45661 -53.132736)
		(end 295.46296 -53.143404)
		(width 0.0889)
		(layer "B.Cu")
		(net "UPI_CPU0_CPU1_P1P1_DN<6>")
	)
	(segment
		(start 133.718554 -56.610504)
		(end 133.724904 -56.599836)
		(width 0.0889)
		(layer "B.Cu")
		(net "UPI_CPU0_CPU1_P1P1_DN<6>")
	)
	(segment
		(start 133.718554 -57.601104)
		(end 133.724904 -57.590436)
		(width 0.0889)
		(layer "B.Cu")
		(net "UPI_CPU0_CPU1_P1P1_DN<6>")
	)
	(segment
		(start 133.724904 -58.581036)
		(end 133.72973 -58.5724)
		(width 0.0889)
		(layer "B.Cu")
		(net "UPI_CPU0_CPU1_P1P1_DN<6>")
	)
	(segment
		(start 226.370388 -45.056552)
		(end 240.188496 -42.292778)
		(width 0.1143)
		(layer "B.Cu")
		(net "UPI_CPU0_CPU1_P1P1_DN<6>")
	)
	(segment
		(start 261.333488 -41.246806)
		(end 279.314402 -44.842938)
		(width 0.1143)
		(layer "B.Cu")
		(net "UPI_CPU0_CPU1_P1P1_DN<6>")
	)
	(segment
		(start 248.003568 -38.603174)
		(end 249.209814 -38.84422)
		(width 0.1143)
		(layer "B.Cu")
		(net "UPI_CPU0_CPU1_P1P1_DN<6>")
	)
	(segment
		(start 141.198854 -46.088046)
		(end 152.784556 -43.168062)
		(width 0.1143)
		(layer "B.Cu")
		(net "UPI_CPU0_CPU1_P1P1_DN<6>")
	)
	(segment
		(start 134.583424 -54.713886)
		(end 134.577074 -54.703218)
		(width 0.0889)
		(layer "B.Cu")
		(net "UPI_CPU0_CPU1_P1P1_DN<6>")
	)
	(segment
		(start 165.665658 -42.651172)
		(end 167.14597 -42.189146)
		(width 0.1143)
		(layer "B.Cu")
		(net "UPI_CPU0_CPU1_P1P1_DN<6>")
	)
	(segment
		(start 204.352652 -38.851332)
		(end 208.254346 -41.433496)
		(width 0.1143)
		(layer "B.Cu")
		(net "UPI_CPU0_CPU1_P1P1_DN<6>")
	)
	(segment
		(start 244.747288 -39.253922)
		(end 248.003568 -38.603174)
		(width 0.1143)
		(layer "B.Cu")
		(net "UPI_CPU0_CPU1_P1P1_DN<6>")
	)
	(segment
		(start 190.574676 -38.416484)
		(end 192.261744 -37.669216)
		(width 0.1143)
		(layer "B.Cu")
		(net "UPI_CPU0_CPU1_P1P1_DN<6>")
	)
	(segment
		(start 164.731446 -42.868342)
		(end 164.95268 -42.826178)
		(width 0.1143)
		(layer "B.Cu")
		(net "UPI_CPU0_CPU1_P1P1_DN<6>")
	)
	(segment
		(start 164.95268 -42.826178)
		(end 165.665658 -42.651172)
		(width 0.1143)
		(layer "B.Cu")
		(net "UPI_CPU0_CPU1_P1P1_DN<6>")
	)
	(segment
		(start 171.038012 -43.208702)
		(end 181.385464 -41.142158)
		(width 0.1143)
		(layer "B.Cu")
		(net "UPI_CPU0_CPU1_P1P1_DN<6>")
	)
	(segment
		(start 138.460226 -47.935388)
		(end 141.198854 -46.088046)
		(width 0.1143)
		(layer "B.Cu")
		(net "UPI_CPU0_CPU1_P1P1_DN<6>")
	)
	(segment
		(start 294.396414 -50.94097)
		(end 294.477694 -51.02225)
		(width 0.1143)
		(layer "B.Cu")
		(net "UPI_CPU0_CPU1_P1P1_DN<6>")
	)
	(segment
		(start 294.493188 -51.073812)
		(end 295.53535 -52.11572)
		(width 0.0889)
		(layer "B.Cu")
		(net "UPI_CPU0_CPU1_P1P1_DN<6>")
	)
	(segment
		(start 292.697154 -48.86071)
		(end 294.396414 -50.94097)
		(width 0.1143)
		(layer "B.Cu")
		(net "UPI_CPU0_CPU1_P1P1_DN<6>")
	)
	(segment
		(start 295.872154 -53.992018)
		(end 295.80332 -53.923184)
		(width 0.0889)
		(layer "B.Cu")
		(net "UPI_CPU0_CPU1_P1P1_DN<6>")
	)
	(segment
		(start 258.825238 -41.052496)
		(end 258.832604 -41.052496)
		(width 0.1143)
		(layer "B.Cu")
		(net "UPI_CPU0_CPU1_P1P1_DN<6>")
	)
	(segment
		(start 135.600694 -51.371754)
		(end 135.600948 -51.371754)
		(width 0.0889)
		(layer "B.Cu")
		(net "UPI_CPU0_CPU1_P1P1_DN<6>")
	)
	(segment
		(start 152.784556 -43.168062)
		(end 152.876504 -43.144948)
		(width 0.1143)
		(layer "B.Cu")
		(net "UPI_CPU0_CPU1_P1P1_DN<6>")
	)
	(segment
		(start 159.35833 -43.343068)
		(end 161.850832 -42.292524)
		(width 0.1143)
		(layer "B.Cu")
		(net "UPI_CPU0_CPU1_P1P1_DN<6>")
	)
	(segment
		(start 133.724904 -57.590436)
		(end 133.72973 -57.5818)
		(width 0.0889)
		(layer "B.Cu")
		(net "UPI_CPU0_CPU1_P1P1_DN<6>")
	)
	(segment
		(start 189.403482 -39.172388)
		(end 190.574676 -38.416484)
		(width 0.1143)
		(layer "B.Cu")
		(net "UPI_CPU0_CPU1_P1P1_DN<6>")
	)
	(segment
		(start 136.628632 -50.308256)
		(end 136.644126 -50.292762)
		(width 0.0889)
		(layer "B.Cu")
		(net "UPI_CPU0_CPU1_P1P1_DN<6>")
	)
	(segment
		(start 252.69063 -40.949118)
		(end 258.825238 -41.052496)
		(width 0.1143)
		(layer "B.Cu")
		(net "UPI_CPU0_CPU1_P1P1_DN<6>")
	)
	(segment
		(start 295.45661 -53.723286)
		(end 295.451784 -53.731922)
		(width 0.0889)
		(layer "B.Cu")
		(net "UPI_CPU0_CPU1_P1P1_DN<6>")
	)
	(segment
		(start 279.314402 -44.842938)
		(end 280.028904 -45.013118)
		(width 0.1143)
		(layer "B.Cu")
		(net "UPI_CPU0_CPU1_P1P1_DN<6>")
	)
	(segment
		(start 208.254346 -41.433496)
		(end 222.396812 -44.261786)
		(width 0.1143)
		(layer "B.Cu")
		(net "UPI_CPU0_CPU1_P1P1_DN<6>")
	)
	(segment
		(start 222.396812 -44.261786)
		(end 226.370388 -45.056552)
		(width 0.1143)
		(layer "B.Cu")
		(net "UPI_CPU0_CPU1_P1P1_DN<6>")
	)
	(segment
		(start 294.493188 -51.037744)
		(end 294.493188 -51.073812)
		(width 0.0889)
		(layer "B.Cu")
		(net "UPI_CPU0_CPU1_P1P1_DN<6>")
	)
	(segment
		(start 134.58825 -54.722522)
		(end 134.583424 -54.713886)
		(width 0.0889)
		(layer "B.Cu")
		(net "UPI_CPU0_CPU1_P1P1_DN<6>")
	)
	(segment
		(start 135.600948 -51.371754)
		(end 136.628632 -50.34407)
		(width 0.0889)
		(layer "B.Cu")
		(net "UPI_CPU0_CPU1_P1P1_DN<6>")
	)
	(segment
		(start 136.644126 -50.292762)
		(end 137.339832 -49.596802)
		(width 0.1143)
		(layer "B.Cu")
		(net "UPI_CPU0_CPU1_P1P1_DN<6>")
	)
	(segment
		(start 135.08228 -53.827934)
		(end 135.10641 -53.827934)
		(width 0.0889)
		(layer "B.Cu")
		(net "UPI_CPU0_CPU1_P1P1_DN<6>")
	)
	(segment
		(start 163.949888 -42.711878)
		(end 164.731446 -42.868342)
		(width 0.1143)
		(layer "B.Cu")
		(net "UPI_CPU0_CPU1_P1P1_DN<6>")
	)
	(segment
		(start 136.628632 -50.34407)
		(end 136.628632 -50.308256)
		(width 0.0889)
		(layer "B.Cu")
		(net "UPI_CPU0_CPU1_P1P1_DN<6>")
	)
	(segment
		(start 133.378194 -59.371484)
		(end 133.440932 -59.309)
		(width 0.0889)
		(layer "B.Cu")
		(net "UPI_CPU0_CPU1_P1P1_DN<6>")
	)
	(segment
		(start 155.25623 -42.545508)
		(end 159.35833 -43.343068)
		(width 0.1143)
		(layer "B.Cu")
		(net "UPI_CPU0_CPU1_P1P1_DN<6>")
	)
	(segment
		(start 134.218934 -55.313834)
		(end 134.2517 -55.313834)
		(width 0.0889)
		(layer "B.Cu")
		(net "UPI_CPU0_CPU1_P1P1_DN<6>")
	)
	(segment
		(start 192.261744 -37.669216)
		(end 196.998082 -37.380418)
		(width 0.1143)
		(layer "B.Cu")
		(net "UPI_CPU0_CPU1_P1P1_DN<6>")
	)
	(segment
		(start 258.832604 -41.052496)
		(end 261.333488 -41.246806)
		(width 0.1143)
		(layer "B.Cu")
		(net "UPI_CPU0_CPU1_P1P1_DN<6>")
	)
	(segment
		(start 137.339832 -49.596802)
		(end 138.460226 -47.935388)
		(width 0.1143)
		(layer "B.Cu")
		(net "UPI_CPU0_CPU1_P1P1_DN<6>")
	)
	(segment
		(start 289.967416 -46.51248)
		(end 290.53282 -46.658784)
		(width 0.1143)
		(layer "B.Cu")
		(net "UPI_CPU0_CPU1_P1P1_DN<6>")
	)
	(segment
		(start 249.209814 -38.84422)
		(end 252.69063 -40.949118)
		(width 0.1143)
		(layer "B.Cu")
		(net "UPI_CPU0_CPU1_P1P1_DN<6>")
	)
	(segment
		(start 185.943494 -39.9034)
		(end 189.403482 -39.172388)
		(width 0.1143)
		(layer "B.Cu")
		(net "UPI_CPU0_CPU1_P1P1_DN<6>")
	)
	(arc
		(start 135.10641 -53.827934)
		(mid 135.495672 -53.431315)
		(end 135.113268 -53.028088)
		(width 0.0889)
		(layer "B.Cu")
		(net "UPI_CPU0_CPU1_P1P1_DN<6>")
	)
	(arc
		(start 133.724904 -56.199786)
		(mid 133.720575 -55.616614)
		(end 134.218934 -55.313834)
		(width 0.0889)
		(layer "B.Cu")
		(net "UPI_CPU0_CPU1_P1P1_DN<6>")
	)
	(arc
		(start 134.2517 -55.313834)
		(mid 134.584618 -55.111843)
		(end 134.58825 -54.722522)
		(width 0.0889)
		(layer "B.Cu")
		(net "UPI_CPU0_CPU1_P1P1_DN<6>")
	)
	(arc
		(start 133.724904 -58.180986)
		(mid 133.645682 -57.891868)
		(end 133.718554 -57.601104)
		(width 0.0889)
		(layer "B.Cu")
		(net "UPI_CPU0_CPU1_P1P1_DN<6>")
	)
	(arc
		(start 133.72973 -57.5818)
		(mid 133.778485 -57.385448)
		(end 133.724904 -57.190386)
		(width 0.0889)
		(layer "B.Cu")
		(net "UPI_CPU0_CPU1_P1P1_DN<6>")
	)
	(arc
		(start 295.53535 -52.447698)
		(mid 295.514075 -52.595188)
		(end 295.45661 -52.732686)
		(width 0.0889)
		(layer "B.Cu")
		(net "UPI_CPU0_CPU1_P1P1_DN<6>")
	)
	(arc
		(start 134.577074 -54.703218)
		(mid 134.583251 -54.123286)
		(end 135.08228 -53.827934)
		(width 0.0889)
		(layer "B.Cu")
		(net "UPI_CPU0_CPU1_P1P1_DN<6>")
	)
	(arc
		(start 295.46296 -53.143404)
		(mid 295.535758 -53.434167)
		(end 295.45661 -53.723286)
		(width 0.0889)
		(layer "B.Cu")
		(net "UPI_CPU0_CPU1_P1P1_DN<6>")
	)
	(arc
		(start 295.45661 -54.123336)
		(mid 295.552219 -54.234903)
		(end 295.681654 -54.304438)
		(width 0.0889)
		(layer "B.Cu")
		(net "UPI_CPU0_CPU1_P1P1_DN<6>")
	)
	(arc
		(start 295.45661 -52.73294)
		(mid 295.403111 -52.932838)
		(end 295.45661 -53.132736)
		(width 0.0889)
		(layer "B.Cu")
		(net "UPI_CPU0_CPU1_P1P1_DN<6>")
	)
	(arc
		(start 133.72973 -58.5724)
		(mid 133.778485 -58.376048)
		(end 133.724904 -58.180986)
		(width 0.0889)
		(layer "B.Cu")
		(net "UPI_CPU0_CPU1_P1P1_DN<6>")
	)
	(arc
		(start 295.451784 -53.731922)
		(mid 295.402998 -53.928274)
		(end 295.45661 -54.123336)
		(width 0.0889)
		(layer "B.Cu")
		(net "UPI_CPU0_CPU1_P1P1_DN<6>")
	)
	(arc
		(start 295.681654 -54.304692)
		(mid 295.90004 -54.223237)
		(end 295.872154 -53.992018)
		(width 0.0889)
		(layer "B.Cu")
		(net "UPI_CPU0_CPU1_P1P1_DN<6>")
	)
	(arc
		(start 135.073644 -53.028088)
		(mid 134.504289 -52.437538)
		(end 135.073644 -51.846988)
		(width 0.0889)
		(layer "B.Cu")
		(net "UPI_CPU0_CPU1_P1P1_DN<6>")
	)
	(arc
		(start 133.724904 -57.190386)
		(mid 133.645682 -56.901268)
		(end 133.718554 -56.610504)
		(width 0.0889)
		(layer "B.Cu")
		(net "UPI_CPU0_CPU1_P1P1_DN<6>")
	)
	(arc
		(start 133.645656 -58.8772)
		(mid 133.665748 -58.723892)
		(end 133.724904 -58.581036)
		(width 0.0889)
		(layer "B.Cu")
		(net "UPI_CPU0_CPU1_P1P1_DN<6>")
	)
	(arc
		(start 135.109712 -51.846988)
		(mid 135.301729 -51.78988)
		(end 135.441944 -51.646836)
		(width 0.0889)
		(layer "B.Cu")
		(net "UPI_CPU0_CPU1_P1P1_DN<6>")
	)
	(arc
		(start 133.485382 -59.26455)
		(mid 133.604046 -59.086817)
		(end 133.645656 -58.8772)
		(width 0.0889)
		(layer "B.Cu")
		(net "UPI_CPU0_CPU1_P1P1_DN<6>")
	)
	(arc
		(start 133.72973 -56.5912)
		(mid 133.778485 -56.394848)
		(end 133.724904 -56.199786)
		(width 0.0889)
		(layer "B.Cu")
		(net "UPI_CPU0_CPU1_P1P1_DN<6>")
	)
	(segment
		(start 134.523734 -58.381138)
		(end 135.095234 -58.381138)
		(width 0.1143)
		(layer "F.Cu")
		(net "UPI_CPU0_CPU1_P1P1_DN<5>")
	)
	(segment
		(start 293.51478 -54.913784)
		(end 294.08628 -54.913784)
		(width 0.1143)
		(layer "F.Cu")
		(net "UPI_CPU0_CPU1_P1P1_DN<5>")
	)
	(via
		(at 170.443398 -44.745402)
		(size 0.508)
		(drill 0.254)
		(layers "F.Cu" "B.Cu")
		(net "UPI_CPU0_CPU1_P1P1_DN<5>")
	)
	(via
		(at 135.095234 -58.381138)
		(size 0.508)
		(drill 0.254)
		(layers "F.Cu" "B.Cu")
		(net "UPI_CPU0_CPU1_P1P1_DN<5>")
	)
	(via
		(at 294.08628 -54.913784)
		(size 0.508)
		(drill 0.254)
		(layers "F.Cu" "B.Cu")
		(net "UPI_CPU0_CPU1_P1P1_DN<5>")
	)
	(segment
		(start 240.926366 -43.466258)
		(end 248.130822 -44.907454)
		(width 0.1143)
		(layer "B.Cu")
		(net "UPI_CPU0_CPU1_P1P1_DN<5>")
	)
	(segment
		(start 134.743698 -56.5912)
		(end 134.748524 -56.599836)
		(width 0.0889)
		(layer "B.Cu")
		(net "UPI_CPU0_CPU1_P1P1_DN<5>")
	)
	(segment
		(start 171.516294 -44.370244)
		(end 183.529224 -41.967912)
		(width 0.1143)
		(layer "B.Cu")
		(net "UPI_CPU0_CPU1_P1P1_DN<5>")
	)
	(segment
		(start 251.508514 -42.9514)
		(end 251.598176 -42.817034)
		(width 0.1143)
		(layer "B.Cu")
		(net "UPI_CPU0_CPU1_P1P1_DN<5>")
	)
	(segment
		(start 138.4173 -50.940208)
		(end 138.227054 -51.223672)
		(width 0.1143)
		(layer "B.Cu")
		(net "UPI_CPU0_CPU1_P1P1_DN<5>")
	)
	(segment
		(start 185.225182 -41.56456)
		(end 185.225182 -41.564814)
		(width 0.1143)
		(layer "B.Cu")
		(net "UPI_CPU0_CPU1_P1P1_DN<5>")
	)
	(segment
		(start 294.379396 -54.744874)
		(end 294.08628 -54.913784)
		(width 0.0889)
		(layer "B.Cu")
		(net "UPI_CPU0_CPU1_P1P1_DN<5>")
	)
	(segment
		(start 138.559032 -50.911506)
		(end 138.418062 -50.939192)
		(width 0.1143)
		(layer "B.Cu")
		(net "UPI_CPU0_CPU1_P1P1_DN<5>")
	)
	(segment
		(start 290.326572 -48.088042)
		(end 291.78123 -49.940464)
		(width 0.1143)
		(layer "B.Cu")
		(net "UPI_CPU0_CPU1_P1P1_DN<5>")
	)
	(segment
		(start 139.409424 -49.462944)
		(end 139.218416 -49.747424)
		(width 0.1143)
		(layer "B.Cu")
		(net "UPI_CPU0_CPU1_P1P1_DN<5>")
	)
	(segment
		(start 134.743698 -57.5818)
		(end 134.748524 -57.590436)
		(width 0.0889)
		(layer "B.Cu")
		(net "UPI_CPU0_CPU1_P1P1_DN<5>")
	)
	(segment
		(start 291.78123 -49.940464)
		(end 291.763958 -50.082958)
		(width 0.1143)
		(layer "B.Cu")
		(net "UPI_CPU0_CPU1_P1P1_DN<5>")
	)
	(segment
		(start 290.157154 -47.8155)
		(end 290.319968 -48.076866)
		(width 0.1143)
		(layer "B.Cu")
		(net "UPI_CPU0_CPU1_P1P1_DN<5>")
	)
	(segment
		(start 140.639546 -48.332136)
		(end 140.354812 -48.523906)
		(width 0.1143)
		(layer "B.Cu")
		(net "UPI_CPU0_CPU1_P1P1_DN<5>")
	)
	(segment
		(start 291.763958 -50.082958)
		(end 291.976048 -50.35296)
		(width 0.1143)
		(layer "B.Cu")
		(net "UPI_CPU0_CPU1_P1P1_DN<5>")
	)
	(segment
		(start 135.113014 -55.999888)
		(end 135.080248 -55.999888)
		(width 0.0889)
		(layer "B.Cu")
		(net "UPI_CPU0_CPU1_P1P1_DN<5>")
	)
	(segment
		(start 291.976048 -50.35296)
		(end 292.118796 -50.370232)
		(width 0.1143)
		(layer "B.Cu")
		(net "UPI_CPU0_CPU1_P1P1_DN<5>")
	)
	(segment
		(start 253.597664 -43.813476)
		(end 253.79807 -43.512994)
		(width 0.1143)
		(layer "B.Cu")
		(net "UPI_CPU0_CPU1_P1P1_DN<5>")
	)
	(segment
		(start 138.750548 -50.626518)
		(end 138.559032 -50.911506)
		(width 0.1143)
		(layer "B.Cu")
		(net "UPI_CPU0_CPU1_P1P1_DN<5>")
	)
	(segment
		(start 186.92114 -41.161208)
		(end 188.330332 -41.255188)
		(width 0.1143)
		(layer "B.Cu")
		(net "UPI_CPU0_CPU1_P1P1_DN<5>")
	)
	(segment
		(start 252.814582 -43.970448)
		(end 253.597664 -43.813476)
		(width 0.1143)
		(layer "B.Cu")
		(net "UPI_CPU0_CPU1_P1P1_DN<5>")
	)
	(segment
		(start 134.748524 -56.599836)
		(end 134.754874 -56.610504)
		(width 0.0889)
		(layer "B.Cu")
		(net "UPI_CPU0_CPU1_P1P1_DN<5>")
	)
	(segment
		(start 140.213842 -48.496474)
		(end 139.929616 -48.68799)
		(width 0.1143)
		(layer "B.Cu")
		(net "UPI_CPU0_CPU1_P1P1_DN<5>")
	)
	(segment
		(start 292.330378 -50.639726)
		(end 292.330378 -50.642266)
		(width 0.1143)
		(layer "B.Cu")
		(net "UPI_CPU0_CPU1_P1P1_DN<5>")
	)
	(segment
		(start 292.384734 -50.661316)
		(end 293.602664 -51.879246)
		(width 0.0889)
		(layer "B.Cu")
		(net "UPI_CPU0_CPU1_P1P1_DN<5>")
	)
	(segment
		(start 203.501752 -39.71798)
		(end 207.828896 -42.602912)
		(width 0.1143)
		(layer "B.Cu")
		(net "UPI_CPU0_CPU1_P1P1_DN<5>")
	)
	(segment
		(start 140.354812 -48.523906)
		(end 140.213842 -48.496474)
		(width 0.1143)
		(layer "B.Cu")
		(net "UPI_CPU0_CPU1_P1P1_DN<5>")
	)
	(segment
		(start 138.722862 -50.485548)
		(end 138.750548 -50.626518)
		(width 0.1143)
		(layer "B.Cu")
		(net "UPI_CPU0_CPU1_P1P1_DN<5>")
	)
	(segment
		(start 139.550394 -49.435004)
		(end 139.409424 -49.462944)
		(width 0.1143)
		(layer "B.Cu")
		(net "UPI_CPU0_CPU1_P1P1_DN<5>")
	)
	(segment
		(start 188.330332 -41.255188)
		(end 190.348362 -39.918386)
		(width 0.1143)
		(layer "B.Cu")
		(net "UPI_CPU0_CPU1_P1P1_DN<5>")
	)
	(segment
		(start 141.092174 -48.027082)
		(end 140.951204 -47.99965)
		(width 0.1143)
		(layer "B.Cu")
		(net "UPI_CPU0_CPU1_P1P1_DN<5>")
	)
	(segment
		(start 248.130822 -44.907454)
		(end 251.504196 -44.232576)
		(width 0.1143)
		(layer "B.Cu")
		(net "UPI_CPU0_CPU1_P1P1_DN<5>")
	)
	(segment
		(start 260.496304 -42.434002)
		(end 279.999948 -46.334426)
		(width 0.1143)
		(layer "B.Cu")
		(net "UPI_CPU0_CPU1_P1P1_DN<5>")
	)
	(segment
		(start 136.460738 -54.61)
		(end 136.465564 -54.618636)
		(width 0.0889)
		(layer "B.Cu")
		(net "UPI_CPU0_CPU1_P1P1_DN<5>")
	)
	(segment
		(start 294.433244 -54.123082)
		(end 294.43299 -54.123336)
		(width 0.0889)
		(layer "B.Cu")
		(net "UPI_CPU0_CPU1_P1P1_DN<5>")
	)
	(segment
		(start 254.90805 -43.551348)
		(end 260.496304 -42.434002)
		(width 0.1143)
		(layer "B.Cu")
		(net "UPI_CPU0_CPU1_P1P1_DN<5>")
	)
	(segment
		(start 138.16965 -51.322732)
		(end 138.158728 -51.341782)
		(width 0.0889)
		(layer "B.Cu")
		(net "UPI_CPU0_CPU1_P1P1_DN<5>")
	)
	(segment
		(start 155.65374 -43.881294)
		(end 142.048992 -47.259748)
		(width 0.1143)
		(layer "B.Cu")
		(net "UPI_CPU0_CPU1_P1P1_DN<5>")
	)
	(segment
		(start 254.607568 -43.350942)
		(end 254.90805 -43.551348)
		(width 0.1143)
		(layer "B.Cu")
		(net "UPI_CPU0_CPU1_P1P1_DN<5>")
	)
	(segment
		(start 279.999948 -46.334426)
		(end 286.974534 -45.90288)
		(width 0.1143)
		(layer "B.Cu")
		(net "UPI_CPU0_CPU1_P1P1_DN<5>")
	)
	(segment
		(start 135.037322 -58.777124)
		(end 135.125714 -58.790078)
		(width 0.0889)
		(layer "B.Cu")
		(net "UPI_CPU0_CPU1_P1P1_DN<5>")
	)
	(segment
		(start 139.05484 -50.173128)
		(end 138.91387 -50.201068)
		(width 0.1143)
		(layer "B.Cu")
		(net "UPI_CPU0_CPU1_P1P1_DN<5>")
	)
	(segment
		(start 226.535488 -46.344586)
		(end 240.926366 -43.466258)
		(width 0.1143)
		(layer "B.Cu")
		(net "UPI_CPU0_CPU1_P1P1_DN<5>")
	)
	(segment
		(start 192.589912 -38.847776)
		(end 196.913754 -38.400228)
		(width 0.1143)
		(layer "B.Cu")
		(net "UPI_CPU0_CPU1_P1P1_DN<5>")
	)
	(segment
		(start 139.929616 -48.68799)
		(end 139.71397 -49.0093)
		(width 0.1143)
		(layer "B.Cu")
		(net "UPI_CPU0_CPU1_P1P1_DN<5>")
	)
	(segment
		(start 170.443398 -44.745402)
		(end 166.60368 -46.088554)
		(width 0.1143)
		(layer "B.Cu")
		(net "UPI_CPU0_CPU1_P1P1_DN<5>")
	)
	(segment
		(start 138.227054 -51.223672)
		(end 138.16965 -51.322732)
		(width 0.1143)
		(layer "B.Cu")
		(net "UPI_CPU0_CPU1_P1P1_DN<5>")
	)
	(segment
		(start 253.79807 -43.512994)
		(end 253.601982 -42.5323)
		(width 0.1143)
		(layer "B.Cu")
		(net "UPI_CPU0_CPU1_P1P1_DN<5>")
	)
	(segment
		(start 254.277114 -42.280586)
		(end 254.41148 -42.370248)
		(width 0.1143)
		(layer "B.Cu")
		(net "UPI_CPU0_CPU1_P1P1_DN<5>")
	)
	(segment
		(start 190.989458 -39.509954)
		(end 192.589912 -38.847776)
		(width 0.1143)
		(layer "B.Cu")
		(net "UPI_CPU0_CPU1_P1P1_DN<5>")
	)
	(segment
		(start 139.218416 -49.747424)
		(end 139.246102 -49.888394)
		(width 0.1143)
		(layer "B.Cu")
		(net "UPI_CPU0_CPU1_P1P1_DN<5>")
	)
	(segment
		(start 294.3479 -53.57622)
		(end 294.43299 -53.723286)
		(width 0.0889)
		(layer "B.Cu")
		(net "UPI_CPU0_CPU1_P1P1_DN<5>")
	)
	(segment
		(start 254.41148 -42.370248)
		(end 254.607568 -43.350942)
		(width 0.1143)
		(layer "B.Cu")
		(net "UPI_CPU0_CPU1_P1P1_DN<5>")
	)
	(segment
		(start 293.602664 -51.879246)
		(end 294.3479 -53.24348)
		(width 0.0889)
		(layer "B.Cu")
		(net "UPI_CPU0_CPU1_P1P1_DN<5>")
	)
	(segment
		(start 251.504196 -44.232576)
		(end 251.704602 -43.932094)
		(width 0.1143)
		(layer "B.Cu")
		(net "UPI_CPU0_CPU1_P1P1_DN<5>")
	)
	(segment
		(start 138.158728 -51.341782)
		(end 138.123676 -51.350926)
		(width 0.0889)
		(layer "B.Cu")
		(net "UPI_CPU0_CPU1_P1P1_DN<5>")
	)
	(segment
		(start 252.5141 -43.770042)
		(end 252.814582 -43.970448)
		(width 0.1143)
		(layer "B.Cu")
		(net "UPI_CPU0_CPU1_P1P1_DN<5>")
	)
	(segment
		(start 140.951204 -47.99965)
		(end 140.666978 -48.191166)
		(width 0.1143)
		(layer "B.Cu")
		(net "UPI_CPU0_CPU1_P1P1_DN<5>")
	)
	(segment
		(start 207.828896 -42.602912)
		(end 226.535488 -46.344586)
		(width 0.1143)
		(layer "B.Cu")
		(net "UPI_CPU0_CPU1_P1P1_DN<5>")
	)
	(segment
		(start 196.913754 -38.400228)
		(end 203.501752 -39.71798)
		(width 0.1143)
		(layer "B.Cu")
		(net "UPI_CPU0_CPU1_P1P1_DN<5>")
	)
	(segment
		(start 252.183646 -42.699686)
		(end 252.318012 -42.789348)
		(width 0.1143)
		(layer "B.Cu")
		(net "UPI_CPU0_CPU1_P1P1_DN<5>")
	)
	(segment
		(start 138.123676 -51.350926)
		(end 137.324084 -52.73294)
		(width 0.0889)
		(layer "B.Cu")
		(net "UPI_CPU0_CPU1_P1P1_DN<5>")
	)
	(segment
		(start 170.443398 -44.745402)
		(end 171.516294 -44.370244)
		(width 0.1143)
		(layer "B.Cu")
		(net "UPI_CPU0_CPU1_P1P1_DN<5>")
	)
	(segment
		(start 190.348362 -39.918386)
		(end 190.989458 -39.509954)
		(width 0.1143)
		(layer "B.Cu")
		(net "UPI_CPU0_CPU1_P1P1_DN<5>")
	)
	(segment
		(start 185.225182 -41.564814)
		(end 186.92114 -41.161208)
		(width 0.1143)
		(layer "B.Cu")
		(net "UPI_CPU0_CPU1_P1P1_DN<5>")
	)
	(segment
		(start 135.975344 -55.504334)
		(end 135.942578 -55.504334)
		(width 0.0889)
		(layer "B.Cu")
		(net "UPI_CPU0_CPU1_P1P1_DN<5>")
	)
	(segment
		(start 139.246102 -49.888394)
		(end 139.05484 -50.173128)
		(width 0.1143)
		(layer "B.Cu")
		(net "UPI_CPU0_CPU1_P1P1_DN<5>")
	)
	(segment
		(start 139.71397 -49.0093)
		(end 139.741656 -49.15027)
		(width 0.1143)
		(layer "B.Cu")
		(net "UPI_CPU0_CPU1_P1P1_DN<5>")
	)
	(segment
		(start 136.833864 -53.028088)
		(end 136.79424 -53.028088)
		(width 0.0889)
		(layer "B.Cu")
		(net "UPI_CPU0_CPU1_P1P1_DN<5>")
	)
	(segment
		(start 138.91387 -50.201068)
		(end 138.722862 -50.485548)
		(width 0.1143)
		(layer "B.Cu")
		(net "UPI_CPU0_CPU1_P1P1_DN<5>")
	)
	(segment
		(start 139.741656 -49.15027)
		(end 139.550394 -49.435004)
		(width 0.1143)
		(layer "B.Cu")
		(net "UPI_CPU0_CPU1_P1P1_DN<5>")
	)
	(segment
		(start 292.118796 -50.370232)
		(end 292.330378 -50.639726)
		(width 0.1143)
		(layer "B.Cu")
		(net "UPI_CPU0_CPU1_P1P1_DN<5>")
	)
	(segment
		(start 253.691644 -42.397934)
		(end 254.277114 -42.280586)
		(width 0.1143)
		(layer "B.Cu")
		(net "UPI_CPU0_CPU1_P1P1_DN<5>")
	)
	(segment
		(start 252.318012 -42.789348)
		(end 252.5141 -43.770042)
		(width 0.1143)
		(layer "B.Cu")
		(net "UPI_CPU0_CPU1_P1P1_DN<5>")
	)
	(segment
		(start 140.666978 -48.191166)
		(end 140.639546 -48.332136)
		(width 0.1143)
		(layer "B.Cu")
		(net "UPI_CPU0_CPU1_P1P1_DN<5>")
	)
	(segment
		(start 135.252206 -58.53811)
		(end 135.095234 -58.381138)
		(width 0.0889)
		(layer "B.Cu")
		(net "UPI_CPU0_CPU1_P1P1_DN<5>")
	)
	(segment
		(start 251.704602 -43.932094)
		(end 251.508514 -42.9514)
		(width 0.1143)
		(layer "B.Cu")
		(net "UPI_CPU0_CPU1_P1P1_DN<5>")
	)
	(segment
		(start 290.319968 -48.076866)
		(end 290.326572 -48.088042)
		(width 0.1143)
		(layer "B.Cu")
		(net "UPI_CPU0_CPU1_P1P1_DN<5>")
	)
	(segment
		(start 141.40434 -47.694088)
		(end 141.376908 -47.835312)
		(width 0.1143)
		(layer "B.Cu")
		(net "UPI_CPU0_CPU1_P1P1_DN<5>")
	)
	(segment
		(start 183.529224 -41.967912)
		(end 185.225182 -41.56456)
		(width 0.1143)
		(layer "B.Cu")
		(net "UPI_CPU0_CPU1_P1P1_DN<5>")
	)
	(segment
		(start 251.598176 -42.817034)
		(end 252.183646 -42.699686)
		(width 0.1143)
		(layer "B.Cu")
		(net "UPI_CPU0_CPU1_P1P1_DN<5>")
	)
	(segment
		(start 138.418062 -50.939192)
		(end 138.4173 -50.940208)
		(width 0.1143)
		(layer "B.Cu")
		(net "UPI_CPU0_CPU1_P1P1_DN<5>")
	)
	(segment
		(start 141.376908 -47.835312)
		(end 141.092174 -48.027082)
		(width 0.1143)
		(layer "B.Cu")
		(net "UPI_CPU0_CPU1_P1P1_DN<5>")
	)
	(segment
		(start 166.60368 -46.088554)
		(end 155.65374 -43.881294)
		(width 0.1143)
		(layer "B.Cu")
		(net "UPI_CPU0_CPU1_P1P1_DN<5>")
	)
	(segment
		(start 292.349428 -50.661316)
		(end 292.384734 -50.661316)
		(width 0.0889)
		(layer "B.Cu")
		(net "UPI_CPU0_CPU1_P1P1_DN<5>")
	)
	(segment
		(start 134.748524 -57.590436)
		(end 134.754874 -57.601104)
		(width 0.0889)
		(layer "B.Cu")
		(net "UPI_CPU0_CPU1_P1P1_DN<5>")
	)
	(segment
		(start 294.3479 -53.24348)
		(end 294.3479 -53.57622)
		(width 0.0889)
		(layer "B.Cu")
		(net "UPI_CPU0_CPU1_P1P1_DN<5>")
	)
	(segment
		(start 294.403272 -54.65572)
		(end 294.379396 -54.744874)
		(width 0.0889)
		(layer "B.Cu")
		(net "UPI_CPU0_CPU1_P1P1_DN<5>")
	)
	(segment
		(start 142.048992 -47.259748)
		(end 141.40434 -47.694088)
		(width 0.1143)
		(layer "B.Cu")
		(net "UPI_CPU0_CPU1_P1P1_DN<5>")
	)
	(segment
		(start 292.330378 -50.642266)
		(end 292.349428 -50.661316)
		(width 0.1143)
		(layer "B.Cu")
		(net "UPI_CPU0_CPU1_P1P1_DN<5>")
	)
	(segment
		(start 253.601982 -42.5323)
		(end 253.691644 -42.397934)
		(width 0.1143)
		(layer "B.Cu")
		(net "UPI_CPU0_CPU1_P1P1_DN<5>")
	)
	(segment
		(start 286.974534 -45.90288)
		(end 290.157154 -47.8155)
		(width 0.1143)
		(layer "B.Cu")
		(net "UPI_CPU0_CPU1_P1P1_DN<5>")
	)
	(segment
		(start 136.465564 -54.618636)
		(end 136.471914 -54.629304)
		(width 0.0889)
		(layer "B.Cu")
		(net "UPI_CPU0_CPU1_P1P1_DN<5>")
	)
	(arc
		(start 134.748524 -57.190386)
		(mid 134.695054 -57.385449)
		(end 134.743698 -57.5818)
		(width 0.0889)
		(layer "B.Cu")
		(net "UPI_CPU0_CPU1_P1P1_DN<5>")
	)
	(arc
		(start 135.080248 -55.999888)
		(mid 134.74733 -56.201879)
		(end 134.743698 -56.5912)
		(width 0.0889)
		(layer "B.Cu")
		(net "UPI_CPU0_CPU1_P1P1_DN<5>")
	)
	(arc
		(start 135.942578 -55.504334)
		(mid 135.748728 -55.560684)
		(end 135.607044 -55.704486)
		(width 0.0889)
		(layer "B.Cu")
		(net "UPI_CPU0_CPU1_P1P1_DN<5>")
	)
	(arc
		(start 134.754874 -57.601104)
		(mid 134.827672 -57.891867)
		(end 134.748524 -58.180986)
		(width 0.0889)
		(layer "B.Cu")
		(net "UPI_CPU0_CPU1_P1P1_DN<5>")
	)
	(arc
		(start 136.465564 -53.627782)
		(mid 136.544695 -53.923184)
		(end 136.465564 -54.218586)
		(width 0.0889)
		(layer "B.Cu")
		(net "UPI_CPU0_CPU1_P1P1_DN<5>")
	)
	(arc
		(start 294.43299 -53.723286)
		(mid 294.48665 -53.923155)
		(end 294.433244 -54.123082)
		(width 0.0889)
		(layer "B.Cu")
		(net "UPI_CPU0_CPU1_P1P1_DN<5>")
	)
	(arc
		(start 134.748524 -58.180986)
		(mid 134.698955 -58.438203)
		(end 134.819136 -58.670952)
		(width 0.0889)
		(layer "B.Cu")
		(net "UPI_CPU0_CPU1_P1P1_DN<5>")
	)
	(arc
		(start 137.324084 -52.73294)
		(mid 137.11708 -52.943804)
		(end 136.833864 -53.028088)
		(width 0.0889)
		(layer "B.Cu")
		(net "UPI_CPU0_CPU1_P1P1_DN<5>")
	)
	(arc
		(start 294.43299 -54.123336)
		(mid 294.354653 -54.385992)
		(end 294.403272 -54.65572)
		(width 0.0889)
		(layer "B.Cu")
		(net "UPI_CPU0_CPU1_P1P1_DN<5>")
	)
	(arc
		(start 134.819136 -58.670952)
		(mid 134.919996 -58.740947)
		(end 135.037322 -58.777124)
		(width 0.0889)
		(layer "B.Cu")
		(net "UPI_CPU0_CPU1_P1P1_DN<5>")
	)
	(arc
		(start 135.607044 -55.704486)
		(mid 135.398436 -55.916418)
		(end 135.113014 -55.999888)
		(width 0.0889)
		(layer "B.Cu")
		(net "UPI_CPU0_CPU1_P1P1_DN<5>")
	)
	(arc
		(start 136.79424 -53.028088)
		(mid 136.461324 -53.23554)
		(end 136.465564 -53.627782)
		(width 0.0889)
		(layer "B.Cu")
		(net "UPI_CPU0_CPU1_P1P1_DN<5>")
	)
	(arc
		(start 136.465564 -54.218586)
		(mid 136.412094 -54.413649)
		(end 136.460738 -54.61)
		(width 0.0889)
		(layer "B.Cu")
		(net "UPI_CPU0_CPU1_P1P1_DN<5>")
	)
	(arc
		(start 134.754874 -56.610504)
		(mid 134.827672 -56.901267)
		(end 134.748524 -57.190386)
		(width 0.0889)
		(layer "B.Cu")
		(net "UPI_CPU0_CPU1_P1P1_DN<5>")
	)
	(arc
		(start 135.125714 -58.790078)
		(mid 135.279854 -58.709695)
		(end 135.252206 -58.53811)
		(width 0.0889)
		(layer "B.Cu")
		(net "UPI_CPU0_CPU1_P1P1_DN<5>")
	)
	(arc
		(start 136.471914 -54.629304)
		(mid 136.467883 -55.205486)
		(end 135.975344 -55.504334)
		(width 0.0889)
		(layer "B.Cu")
		(net "UPI_CPU0_CPU1_P1P1_DN<5>")
	)
	(segment
		(start 135.382254 -57.885584)
		(end 135.953754 -57.885584)
		(width 0.1143)
		(layer "F.Cu")
		(net "UPI_CPU0_CPU1_P1P1_DN<4>")
	)
	(segment
		(start 291.79774 -55.904384)
		(end 292.36924 -55.904384)
		(width 0.1143)
		(layer "F.Cu")
		(net "UPI_CPU0_CPU1_P1P1_DN<4>")
	)
	(via
		(at 165.679628 -46.980856)
		(size 0.508)
		(drill 0.254)
		(layers "F.Cu" "B.Cu")
		(net "UPI_CPU0_CPU1_P1P1_DN<4>")
	)
	(via
		(at 292.36924 -55.904384)
		(size 0.508)
		(drill 0.254)
		(layers "F.Cu" "B.Cu")
		(net "UPI_CPU0_CPU1_P1P1_DN<4>")
	)
	(via
		(at 135.953754 -57.885584)
		(size 0.508)
		(drill 0.254)
		(layers "F.Cu" "B.Cu")
		(net "UPI_CPU0_CPU1_P1P1_DN<4>")
	)
	(segment
		(start 165.679628 -46.980856)
		(end 166.548816 -47.16018)
		(width 0.1143)
		(layer "B.Cu")
		(net "UPI_CPU0_CPU1_P1P1_DN<4>")
	)
	(segment
		(start 189.87516 -42.134028)
		(end 189.869572 -42.612818)
		(width 0.1143)
		(layer "B.Cu")
		(net "UPI_CPU0_CPU1_P1P1_DN<4>")
	)
	(segment
		(start 147.697952 -47.362364)
		(end 147.254468 -47.108364)
		(width 0.1143)
		(layer "B.Cu")
		(net "UPI_CPU0_CPU1_P1P1_DN<4>")
	)
	(segment
		(start 142.334234 -48.42637)
		(end 142.158466 -48.686974)
		(width 0.1143)
		(layer "B.Cu")
		(net "UPI_CPU0_CPU1_P1P1_DN<4>")
	)
	(segment
		(start 226.737926 -47.410624)
		(end 240.947702 -44.568872)
		(width 0.1143)
		(layer "B.Cu")
		(net "UPI_CPU0_CPU1_P1P1_DN<4>")
	)
	(segment
		(start 285.60522 -47.077122)
		(end 285.699454 -46.968156)
		(width 0.1143)
		(layer "B.Cu")
		(net "UPI_CPU0_CPU1_P1P1_DN<4>")
	)
	(segment
		(start 135.636762 -57.62752)
		(end 135.660638 -57.716674)
		(width 0.0889)
		(layer "B.Cu")
		(net "UPI_CPU0_CPU1_P1P1_DN<4>")
	)
	(segment
		(start 292.530784 -56.066182)
		(end 292.36924 -55.904384)
		(width 0.0889)
		(layer "B.Cu")
		(net "UPI_CPU0_CPU1_P1P1_DN<4>")
	)
	(segment
		(start 282.331668 -47.2059)
		(end 283.888688 -47.096426)
		(width 0.1143)
		(layer "B.Cu")
		(net "UPI_CPU0_CPU1_P1P1_DN<4>")
	)
	(segment
		(start 290.061396 -49.619408)
		(end 291.47897 -51.301396)
		(width 0.1143)
		(layer "B.Cu")
		(net "UPI_CPU0_CPU1_P1P1_DN<4>")
	)
	(segment
		(start 142.071598 -50.285396)
		(end 142.070836 -50.285396)
		(width 0.1143)
		(layer "B.Cu")
		(net "UPI_CPU0_CPU1_P1P1_DN<4>")
	)
	(segment
		(start 292.538912 -51.97729)
		(end 292.709854 -52.245768)
		(width 0.1143)
		(layer "B.Cu")
		(net "UPI_CPU0_CPU1_P1P1_DN<4>")
	)
	(segment
		(start 189.247272 -42.605706)
		(end 189.25286 -42.12717)
		(width 0.1143)
		(layer "B.Cu")
		(net "UPI_CPU0_CPU1_P1P1_DN<4>")
	)
	(segment
		(start 138.888216 -51.991006)
		(end 138.806936 -52.072286)
		(width 0.1143)
		(layer "B.Cu")
		(net "UPI_CPU0_CPU1_P1P1_DN<4>")
	)
	(segment
		(start 136.830054 -55.999888)
		(end 136.797288 -55.999888)
		(width 0.0889)
		(layer "B.Cu")
		(net "UPI_CPU0_CPU1_P1P1_DN<4>")
	)
	(segment
		(start 166.548816 -47.16018)
		(end 172.657516 -45.144182)
		(width 0.1143)
		(layer "B.Cu")
		(net "UPI_CPU0_CPU1_P1P1_DN<4>")
	)
	(segment
		(start 293.241222 -53.033422)
		(end 293.213282 -53.158644)
		(width 0.0889)
		(layer "B.Cu")
		(net "UPI_CPU0_CPU1_P1P1_DN<4>")
	)
	(segment
		(start 189.78753 -42.044366)
		(end 189.87516 -42.134028)
		(width 0.1143)
		(layer "B.Cu")
		(net "UPI_CPU0_CPU1_P1P1_DN<4>")
	)
	(segment
		(start 142.235174 -49.080674)
		(end 142.564358 -49.30267)
		(width 0.1143)
		(layer "B.Cu")
		(net "UPI_CPU0_CPU1_P1P1_DN<4>")
	)
	(segment
		(start 142.564358 -49.30267)
		(end 142.636748 -49.675542)
		(width 0.1143)
		(layer "B.Cu")
		(net "UPI_CPU0_CPU1_P1P1_DN<4>")
	)
	(segment
		(start 165.679628 -46.980856)
		(end 155.691586 -44.920662)
		(width 0.1143)
		(layer "B.Cu")
		(net "UPI_CPU0_CPU1_P1P1_DN<4>")
	)
	(segment
		(start 137.688574 -53.523388)
		(end 137.65276 -53.523388)
		(width 0.0889)
		(layer "B.Cu")
		(net "UPI_CPU0_CPU1_P1P1_DN<4>")
	)
	(segment
		(start 137.330434 -54.703218)
		(end 137.324084 -54.713886)
		(width 0.0889)
		(layer "B.Cu")
		(net "UPI_CPU0_CPU1_P1P1_DN<4>")
	)
	(segment
		(start 140.718032 -49.679606)
		(end 140.352272 -50.22088)
		(width 0.1143)
		(layer "B.Cu")
		(net "UPI_CPU0_CPU1_P1P1_DN<4>")
	)
	(segment
		(start 143.213582 -48.69434)
		(end 142.70736 -48.353218)
		(width 0.1143)
		(layer "B.Cu")
		(net "UPI_CPU0_CPU1_P1P1_DN<4>")
	)
	(segment
		(start 194.589146 -40.140636)
		(end 197.525386 -39.309802)
		(width 0.1143)
		(layer "B.Cu")
		(net "UPI_CPU0_CPU1_P1P1_DN<4>")
	)
	(segment
		(start 138.791442 -52.08778)
		(end 138.755374 -52.08778)
		(width 0.0889)
		(layer "B.Cu")
		(net "UPI_CPU0_CPU1_P1P1_DN<4>")
	)
	(segment
		(start 293.238936 -55.809388)
		(end 293.20617 -55.809388)
		(width 0.0889)
		(layer "B.Cu")
		(net "UPI_CPU0_CPU1_P1P1_DN<4>")
	)
	(segment
		(start 291.789104 -51.499262)
		(end 291.820346 -51.63947)
		(width 0.1143)
		(layer "B.Cu")
		(net "UPI_CPU0_CPU1_P1P1_DN<4>")
	)
	(segment
		(start 142.24889 -50.251106)
		(end 142.111476 -50.277522)
		(width 0.1143)
		(layer "B.Cu")
		(net "UPI_CPU0_CPU1_P1P1_DN<4>")
	)
	(segment
		(start 284.433518 -47.057818)
		(end 285.15437 -47.007018)
		(width 0.1143)
		(layer "B.Cu")
		(net "UPI_CPU0_CPU1_P1P1_DN<4>")
	)
	(segment
		(start 286.041338 -46.94428)
		(end 286.149796 -47.038514)
		(width 0.1143)
		(layer "B.Cu")
		(net "UPI_CPU0_CPU1_P1P1_DN<4>")
	)
	(segment
		(start 172.657516 -45.144182)
		(end 179.569618 -43.761406)
		(width 0.1143)
		(layer "B.Cu")
		(net "UPI_CPU0_CPU1_P1P1_DN<4>")
	)
	(segment
		(start 146.263106 -47.378112)
		(end 146.013424 -47.813722)
		(width 0.1143)
		(layer "B.Cu")
		(net "UPI_CPU0_CPU1_P1P1_DN<4>")
	)
	(segment
		(start 188.989208 -42.858182)
		(end 189.247272 -42.605706)
		(width 0.1143)
		(layer "B.Cu")
		(net "UPI_CPU0_CPU1_P1P1_DN<4>")
	)
	(segment
		(start 211.150962 -44.291758)
		(end 222.396812 -46.541944)
		(width 0.1143)
		(layer "B.Cu")
		(net "UPI_CPU0_CPU1_P1P1_DN<4>")
	)
	(segment
		(start 292.24986 -51.79314)
		(end 292.538912 -51.97729)
		(width 0.1143)
		(layer "B.Cu")
		(net "UPI_CPU0_CPU1_P1P1_DN<4>")
	)
	(segment
		(start 286.586422 -46.905672)
		(end 286.928306 -46.881542)
		(width 0.1143)
		(layer "B.Cu")
		(net "UPI_CPU0_CPU1_P1P1_DN<4>")
	)
	(segment
		(start 281.895296 -47.338742)
		(end 282.237688 -47.314612)
		(width 0.1143)
		(layer "B.Cu")
		(net "UPI_CPU0_CPU1_P1P1_DN<4>")
	)
	(segment
		(start 142.158466 -48.686974)
		(end 142.235174 -49.080674)
		(width 0.1143)
		(layer "B.Cu")
		(net "UPI_CPU0_CPU1_P1P1_DN<4>")
	)
	(segment
		(start 260.597142 -43.482006)
		(end 280.032714 -47.367952)
		(width 0.1143)
		(layer "B.Cu")
		(net "UPI_CPU0_CPU1_P1P1_DN<4>")
	)
	(segment
		(start 140.894562 -49.645316)
		(end 140.718032 -49.679606)
		(width 0.1143)
		(layer "B.Cu")
		(net "UPI_CPU0_CPU1_P1P1_DN<4>")
	)
	(segment
		(start 292.92423 -52.705)
		(end 293.020242 -52.855622)
		(width 0.0889)
		(layer "B.Cu")
		(net "UPI_CPU0_CPU1_P1P1_DN<4>")
	)
	(segment
		(start 143.806164 -48.577246)
		(end 143.213582 -48.69434)
		(width 0.1143)
		(layer "B.Cu")
		(net "UPI_CPU0_CPU1_P1P1_DN<4>")
	)
	(segment
		(start 137.324084 -54.713886)
		(end 137.319258 -54.722522)
		(width 0.0889)
		(layer "B.Cu")
		(net "UPI_CPU0_CPU1_P1P1_DN<4>")
	)
	(segment
		(start 286.492188 -47.014384)
		(end 286.586422 -46.905418)
		(width 0.1143)
		(layer "B.Cu")
		(net "UPI_CPU0_CPU1_P1P1_DN<4>")
	)
	(segment
		(start 293.145464 -52.883308)
		(end 293.241222 -53.033422)
		(width 0.0889)
		(layer "B.Cu")
		(net "UPI_CPU0_CPU1_P1P1_DN<4>")
	)
	(segment
		(start 285.15437 -47.007018)
		(end 285.262828 -47.101252)
		(width 0.1143)
		(layer "B.Cu")
		(net "UPI_CPU0_CPU1_P1P1_DN<4>")
	)
	(segment
		(start 189.869572 -42.612818)
		(end 190.122048 -42.870882)
		(width 0.1143)
		(layer "B.Cu")
		(net "UPI_CPU0_CPU1_P1P1_DN<4>")
	)
	(segment
		(start 293.579296 -54.61)
		(end 293.57447 -54.618636)
		(width 0.0889)
		(layer "B.Cu")
		(net "UPI_CPU0_CPU1_P1P1_DN<4>")
	)
	(segment
		(start 142.111476 -50.277522)
		(end 142.111476 -50.277776)
		(width 0.1143)
		(layer "B.Cu")
		(net "UPI_CPU0_CPU1_P1P1_DN<4>")
	)
	(segment
		(start 194.034664 -40.50411)
		(end 194.589146 -40.140636)
		(width 0.1143)
		(layer "B.Cu")
		(net "UPI_CPU0_CPU1_P1P1_DN<4>")
	)
	(segment
		(start 142.636748 -49.675542)
		(end 142.24889 -50.251106)
		(width 0.1143)
		(layer "B.Cu")
		(net "UPI_CPU0_CPU1_P1P1_DN<4>")
	)
	(segment
		(start 148.717762 -46.817534)
		(end 148.53666 -47.134272)
		(width 0.1143)
		(layer "B.Cu")
		(net "UPI_CPU0_CPU1_P1P1_DN<4>")
	)
	(segment
		(start 240.947702 -44.568872)
		(end 248.054368 -45.990256)
		(width 0.1143)
		(layer "B.Cu")
		(net "UPI_CPU0_CPU1_P1P1_DN<4>")
	)
	(segment
		(start 292.709854 -52.245768)
		(end 292.721538 -52.26431)
		(width 0.0889)
		(layer "B.Cu")
		(net "UPI_CPU0_CPU1_P1P1_DN<4>")
	)
	(segment
		(start 189.25286 -42.12717)
		(end 189.36843 -42.01414)
		(width 0.1143)
		(layer "B.Cu")
		(net "UPI_CPU0_CPU1_P1P1_DN<4>")
	)
	(segment
		(start 145.46707 -47.962312)
		(end 144.976088 -47.681134)
		(width 0.1143)
		(layer "B.Cu")
		(net "UPI_CPU0_CPU1_P1P1_DN<4>")
	)
	(segment
		(start 189.762384 -42.018712)
		(end 189.78753 -42.044366)
		(width 0.1143)
		(layer "B.Cu")
		(net "UPI_CPU0_CPU1_P1P1_DN<4>")
	)
	(segment
		(start 286.928306 -46.881542)
		(end 289.200844 -48.31842)
		(width 0.1143)
		(layer "B.Cu")
		(net "UPI_CPU0_CPU1_P1P1_DN<4>")
	)
	(segment
		(start 138.336274 -52.50688)
		(end 138.336274 -52.642516)
		(width 0.0889)
		(layer "B.Cu")
		(net "UPI_CPU0_CPU1_P1P1_DN<4>")
	)
	(segment
		(start 248.054368 -45.990256)
		(end 260.597142 -43.482006)
		(width 0.1143)
		(layer "B.Cu")
		(net "UPI_CPU0_CPU1_P1P1_DN<4>")
	)
	(segment
		(start 280.032714 -47.367952)
		(end 281.786838 -47.244508)
		(width 0.1143)
		(layer "B.Cu")
		(net "UPI_CPU0_CPU1_P1P1_DN<4>")
	)
	(segment
		(start 282.237688 -47.314612)
		(end 282.331668 -47.2059)
		(width 0.1143)
		(layer "B.Cu")
		(net "UPI_CPU0_CPU1_P1P1_DN<4>")
	)
	(segment
		(start 189.36843 -42.01414)
		(end 189.762384 -42.018712)
		(width 0.1143)
		(layer "B.Cu")
		(net "UPI_CPU0_CPU1_P1P1_DN<4>")
	)
	(segment
		(start 135.660638 -57.716674)
		(end 135.953754 -57.885584)
		(width 0.0889)
		(layer "B.Cu")
		(net "UPI_CPU0_CPU1_P1P1_DN<4>")
	)
	(segment
		(start 144.976088 -47.681134)
		(end 144.284192 -47.869348)
		(width 0.1143)
		(layer "B.Cu")
		(net "UPI_CPU0_CPU1_P1P1_DN<4>")
	)
	(segment
		(start 207.885538 -43.567858)
		(end 211.150962 -44.291758)
		(width 0.1143)
		(layer "B.Cu")
		(net "UPI_CPU0_CPU1_P1P1_DN<4>")
	)
	(segment
		(start 139.511024 -51.991006)
		(end 138.888216 -51.991006)
		(width 0.1143)
		(layer "B.Cu")
		(net "UPI_CPU0_CPU1_P1P1_DN<4>")
	)
	(segment
		(start 140.447268 -50.7111)
		(end 139.732766 -51.769518)
		(width 0.1143)
		(layer "B.Cu")
		(net "UPI_CPU0_CPU1_P1P1_DN<4>")
	)
	(segment
		(start 138.755374 -52.08778)
		(end 138.336274 -52.50688)
		(width 0.0889)
		(layer "B.Cu")
		(net "UPI_CPU0_CPU1_P1P1_DN<4>")
	)
	(segment
		(start 190.984886 -42.880534)
		(end 194.034664 -40.50411)
		(width 0.1143)
		(layer "B.Cu")
		(net "UPI_CPU0_CPU1_P1P1_DN<4>")
	)
	(segment
		(start 281.786838 -47.244508)
		(end 281.895296 -47.338742)
		(width 0.1143)
		(layer "B.Cu")
		(net "UPI_CPU0_CPU1_P1P1_DN<4>")
	)
	(segment
		(start 285.699454 -46.968156)
		(end 286.041338 -46.94428)
		(width 0.1143)
		(layer "B.Cu")
		(net "UPI_CPU0_CPU1_P1P1_DN<4>")
	)
	(segment
		(start 188.9252 -42.85742)
		(end 188.989208 -42.858182)
		(width 0.1143)
		(layer "B.Cu")
		(net "UPI_CPU0_CPU1_P1P1_DN<4>")
	)
	(segment
		(start 141.894052 -50.319686)
		(end 140.894562 -49.645316)
		(width 0.1143)
		(layer "B.Cu")
		(net "UPI_CPU0_CPU1_P1P1_DN<4>")
	)
	(segment
		(start 292.95217 -52.579778)
		(end 292.92423 -52.705)
		(width 0.0889)
		(layer "B.Cu")
		(net "UPI_CPU0_CPU1_P1P1_DN<4>")
	)
	(segment
		(start 292.75659 -52.27193)
		(end 292.95217 -52.579778)
		(width 0.0889)
		(layer "B.Cu")
		(net "UPI_CPU0_CPU1_P1P1_DN<4>")
	)
	(segment
		(start 286.586422 -46.905418)
		(end 286.586422 -46.905672)
		(width 0.1143)
		(layer "B.Cu")
		(net "UPI_CPU0_CPU1_P1P1_DN<4>")
	)
	(segment
		(start 155.691586 -44.920662)
		(end 148.717762 -46.817534)
		(width 0.1143)
		(layer "B.Cu")
		(net "UPI_CPU0_CPU1_P1P1_DN<4>")
	)
	(segment
		(start 291.820346 -51.63947)
		(end 292.109652 -51.824128)
		(width 0.1143)
		(layer "B.Cu")
		(net "UPI_CPU0_CPU1_P1P1_DN<4>")
	)
	(segment
		(start 293.213282 -53.158644)
		(end 293.309294 -53.309266)
		(width 0.0889)
		(layer "B.Cu")
		(net "UPI_CPU0_CPU1_P1P1_DN<4>")
	)
	(segment
		(start 285.262828 -47.101252)
		(end 285.60522 -47.077122)
		(width 0.1143)
		(layer "B.Cu")
		(net "UPI_CPU0_CPU1_P1P1_DN<4>")
	)
	(segment
		(start 286.149796 -47.038514)
		(end 286.492188 -47.014384)
		(width 0.1143)
		(layer "B.Cu")
		(net "UPI_CPU0_CPU1_P1P1_DN<4>")
	)
	(segment
		(start 222.396812 -46.541944)
		(end 226.737926 -47.410624)
		(width 0.1143)
		(layer "B.Cu")
		(net "UPI_CPU0_CPU1_P1P1_DN<4>")
	)
	(segment
		(start 140.352272 -50.22088)
		(end 140.447268 -50.7111)
		(width 0.1143)
		(layer "B.Cu")
		(net "UPI_CPU0_CPU1_P1P1_DN<4>")
	)
	(segment
		(start 146.013424 -47.813722)
		(end 145.46707 -47.962312)
		(width 0.1143)
		(layer "B.Cu")
		(net "UPI_CPU0_CPU1_P1P1_DN<4>")
	)
	(segment
		(start 147.254468 -47.108364)
		(end 146.263106 -47.378112)
		(width 0.1143)
		(layer "B.Cu")
		(net "UPI_CPU0_CPU1_P1P1_DN<4>")
	)
	(segment
		(start 284.339284 -47.16653)
		(end 284.433518 -47.057818)
		(width 0.1143)
		(layer "B.Cu")
		(net "UPI_CPU0_CPU1_P1P1_DN<4>")
	)
	(segment
		(start 197.525386 -39.309802)
		(end 202.777344 -40.3606)
		(width 0.1143)
		(layer "B.Cu")
		(net "UPI_CPU0_CPU1_P1P1_DN<4>")
	)
	(segment
		(start 293.57447 -54.618636)
		(end 293.56812 -54.629304)
		(width 0.0889)
		(layer "B.Cu")
		(net "UPI_CPU0_CPU1_P1P1_DN<4>")
	)
	(segment
		(start 139.732766 -51.769518)
		(end 139.511024 -51.991006)
		(width 0.1143)
		(layer "B.Cu")
		(net "UPI_CPU0_CPU1_P1P1_DN<4>")
	)
	(segment
		(start 293.309294 -53.309266)
		(end 293.434516 -53.336952)
		(width 0.0889)
		(layer "B.Cu")
		(net "UPI_CPU0_CPU1_P1P1_DN<4>")
	)
	(segment
		(start 142.070836 -50.285396)
		(end 141.894052 -50.319686)
		(width 0.1143)
		(layer "B.Cu")
		(net "UPI_CPU0_CPU1_P1P1_DN<4>")
	)
	(segment
		(start 292.721538 -52.26431)
		(end 292.75659 -52.27193)
		(width 0.0889)
		(layer "B.Cu")
		(net "UPI_CPU0_CPU1_P1P1_DN<4>")
	)
	(segment
		(start 138.806936 -52.072286)
		(end 138.791442 -52.08778)
		(width 0.0889)
		(layer "B.Cu")
		(net "UPI_CPU0_CPU1_P1P1_DN<4>")
	)
	(segment
		(start 283.888688 -47.096426)
		(end 283.997146 -47.19066)
		(width 0.1143)
		(layer "B.Cu")
		(net "UPI_CPU0_CPU1_P1P1_DN<4>")
	)
	(segment
		(start 190.122048 -42.870882)
		(end 190.984886 -42.880534)
		(width 0.1143)
		(layer "B.Cu")
		(net "UPI_CPU0_CPU1_P1P1_DN<4>")
	)
	(segment
		(start 144.284192 -47.869348)
		(end 143.806164 -48.577246)
		(width 0.1143)
		(layer "B.Cu")
		(net "UPI_CPU0_CPU1_P1P1_DN<4>")
	)
	(segment
		(start 293.495476 -53.432202)
		(end 293.495476 -53.923946)
		(width 0.0889)
		(layer "B.Cu")
		(net "UPI_CPU0_CPU1_P1P1_DN<4>")
	)
	(segment
		(start 292.109652 -51.824128)
		(end 292.24986 -51.79314)
		(width 0.1143)
		(layer "B.Cu")
		(net "UPI_CPU0_CPU1_P1P1_DN<4>")
	)
	(segment
		(start 135.975344 -56.494934)
		(end 135.942578 -56.494934)
		(width 0.0889)
		(layer "B.Cu")
		(net "UPI_CPU0_CPU1_P1P1_DN<4>")
	)
	(segment
		(start 202.777344 -40.3606)
		(end 207.885538 -43.567858)
		(width 0.1143)
		(layer "B.Cu")
		(net "UPI_CPU0_CPU1_P1P1_DN<4>")
	)
	(segment
		(start 293.434516 -53.336952)
		(end 293.495476 -53.432202)
		(width 0.0889)
		(layer "B.Cu")
		(net "UPI_CPU0_CPU1_P1P1_DN<4>")
	)
	(segment
		(start 142.70736 -48.353218)
		(end 142.334234 -48.42637)
		(width 0.1143)
		(layer "B.Cu")
		(net "UPI_CPU0_CPU1_P1P1_DN<4>")
	)
	(segment
		(start 148.53666 -47.134272)
		(end 147.697952 -47.362364)
		(width 0.1143)
		(layer "B.Cu")
		(net "UPI_CPU0_CPU1_P1P1_DN<4>")
	)
	(segment
		(start 291.47897 -51.301396)
		(end 291.789104 -51.499262)
		(width 0.1143)
		(layer "B.Cu")
		(net "UPI_CPU0_CPU1_P1P1_DN<4>")
	)
	(segment
		(start 179.569618 -43.761406)
		(end 184.348374 -42.80535)
		(width 0.1143)
		(layer "B.Cu")
		(net "UPI_CPU0_CPU1_P1P1_DN<4>")
	)
	(segment
		(start 142.111476 -50.277776)
		(end 142.071598 -50.285396)
		(width 0.1143)
		(layer "B.Cu")
		(net "UPI_CPU0_CPU1_P1P1_DN<4>")
	)
	(segment
		(start 184.348374 -42.80535)
		(end 188.9252 -42.85742)
		(width 0.1143)
		(layer "B.Cu")
		(net "UPI_CPU0_CPU1_P1P1_DN<4>")
	)
	(segment
		(start 283.997146 -47.19066)
		(end 284.339284 -47.16653)
		(width 0.1143)
		(layer "B.Cu")
		(net "UPI_CPU0_CPU1_P1P1_DN<4>")
	)
	(segment
		(start 289.200844 -48.31842)
		(end 290.061396 -49.619408)
		(width 0.1143)
		(layer "B.Cu")
		(net "UPI_CPU0_CPU1_P1P1_DN<4>")
	)
	(segment
		(start 293.020242 -52.855622)
		(end 293.145464 -52.883308)
		(width 0.0889)
		(layer "B.Cu")
		(net "UPI_CPU0_CPU1_P1P1_DN<4>")
	)
	(arc
		(start 136.465564 -56.199786)
		(mid 136.25856 -56.41065)
		(end 135.975344 -56.494934)
		(width 0.0889)
		(layer "B.Cu")
		(net "UPI_CPU0_CPU1_P1P1_DN<4>")
	)
	(arc
		(start 137.65276 -53.523388)
		(mid 137.319791 -53.730936)
		(end 137.324084 -54.123336)
		(width 0.0889)
		(layer "B.Cu")
		(net "UPI_CPU0_CPU1_P1P1_DN<4>")
	)
	(arc
		(start 137.319258 -54.722522)
		(mid 137.270503 -54.918874)
		(end 137.324084 -55.113936)
		(width 0.0889)
		(layer "B.Cu")
		(net "UPI_CPU0_CPU1_P1P1_DN<4>")
	)
	(arc
		(start 136.797288 -55.999888)
		(mid 136.605646 -56.057054)
		(end 136.465564 -56.199786)
		(width 0.0889)
		(layer "B.Cu")
		(net "UPI_CPU0_CPU1_P1P1_DN<4>")
	)
	(arc
		(start 292.751764 -56.049418)
		(mid 292.645149 -56.108446)
		(end 292.530784 -56.066182)
		(width 0.0889)
		(layer "B.Cu")
		(net "UPI_CPU0_CPU1_P1P1_DN<4>")
	)
	(arc
		(start 293.495476 -53.923946)
		(mid 293.515634 -54.07645)
		(end 293.57447 -54.218586)
		(width 0.0889)
		(layer "B.Cu")
		(net "UPI_CPU0_CPU1_P1P1_DN<4>")
	)
	(arc
		(start 293.57447 -55.209186)
		(mid 293.577218 -55.604653)
		(end 293.238936 -55.809388)
		(width 0.0889)
		(layer "B.Cu")
		(net "UPI_CPU0_CPU1_P1P1_DN<4>")
	)
	(arc
		(start 135.942578 -56.494934)
		(mid 135.604409 -56.699732)
		(end 135.607044 -57.095136)
		(width 0.0889)
		(layer "B.Cu")
		(net "UPI_CPU0_CPU1_P1P1_DN<4>")
	)
	(arc
		(start 138.336274 -52.642516)
		(mid 138.298852 -52.939203)
		(end 138.188954 -53.217318)
		(width 0.0889)
		(layer "B.Cu")
		(net "UPI_CPU0_CPU1_P1P1_DN<4>")
	)
	(arc
		(start 135.607044 -57.095136)
		(mid 135.685381 -57.357792)
		(end 135.636762 -57.62752)
		(width 0.0889)
		(layer "B.Cu")
		(net "UPI_CPU0_CPU1_P1P1_DN<4>")
	)
	(arc
		(start 293.57447 -54.218586)
		(mid 293.62794 -54.413649)
		(end 293.579296 -54.61)
		(width 0.0889)
		(layer "B.Cu")
		(net "UPI_CPU0_CPU1_P1P1_DN<4>")
	)
	(arc
		(start 138.188954 -53.217318)
		(mid 137.979439 -53.436872)
		(end 137.688574 -53.523388)
		(width 0.0889)
		(layer "B.Cu")
		(net "UPI_CPU0_CPU1_P1P1_DN<4>")
	)
	(arc
		(start 137.324084 -55.113936)
		(mid 137.328413 -55.697108)
		(end 136.830054 -55.999888)
		(width 0.0889)
		(layer "B.Cu")
		(net "UPI_CPU0_CPU1_P1P1_DN<4>")
	)
	(arc
		(start 293.56812 -54.629304)
		(mid 293.495322 -54.920067)
		(end 293.57447 -55.209186)
		(width 0.0889)
		(layer "B.Cu")
		(net "UPI_CPU0_CPU1_P1P1_DN<4>")
	)
	(arc
		(start 293.20617 -55.809388)
		(mid 292.951505 -55.877417)
		(end 292.751764 -56.049418)
		(width 0.0889)
		(layer "B.Cu")
		(net "UPI_CPU0_CPU1_P1P1_DN<4>")
	)
	(arc
		(start 137.324084 -54.123336)
		(mid 137.403306 -54.412454)
		(end 137.330434 -54.703218)
		(width 0.0889)
		(layer "B.Cu")
		(net "UPI_CPU0_CPU1_P1P1_DN<4>")
	)
	(segment
		(start 135.382254 -58.876438)
		(end 135.953754 -58.876438)
		(width 0.1143)
		(layer "F.Cu")
		(net "UPI_CPU0_CPU1_P1P1_DN<3>")
	)
	(segment
		(start 292.65626 -54.418738)
		(end 293.22776 -54.418738)
		(width 0.1143)
		(layer "F.Cu")
		(net "UPI_CPU0_CPU1_P1P1_DN<3>")
	)
	(via
		(at 293.22776 -54.418738)
		(size 0.508)
		(drill 0.254)
		(layers "F.Cu" "B.Cu")
		(net "UPI_CPU0_CPU1_P1P1_DN<3>")
	)
	(via
		(at 135.953754 -58.876438)
		(size 0.508)
		(drill 0.254)
		(layers "F.Cu" "B.Cu")
		(net "UPI_CPU0_CPU1_P1P1_DN<3>")
	)
	(via
		(at 161.047176 -46.88078)
		(size 0.508)
		(drill 0.254)
		(layers "F.Cu" "B.Cu")
		(net "UPI_CPU0_CPU1_P1P1_DN<3>")
	)
	(segment
		(start 226.856036 -48.175164)
		(end 240.832132 -45.380148)
		(width 0.1143)
		(layer "B.Cu")
		(net "UPI_CPU0_CPU1_P1P1_DN<3>")
	)
	(segment
		(start 282.51785 -48.483266)
		(end 282.624276 -48.361346)
		(width 0.1143)
		(layer "B.Cu")
		(net "UPI_CPU0_CPU1_P1P1_DN<3>")
	)
	(segment
		(start 146.575018 -49.2506)
		(end 146.060414 -49.604168)
		(width 0.1143)
		(layer "B.Cu")
		(net "UPI_CPU0_CPU1_P1P1_DN<3>")
	)
	(segment
		(start 261.47776 -45.07484)
		(end 261.5692 -45.207936)
		(width 0.1143)
		(layer "B.Cu")
		(net "UPI_CPU0_CPU1_P1P1_DN<3>")
	)
	(segment
		(start 291.864034 -52.559966)
		(end 292.960044 -53.655976)
		(width 0.0889)
		(layer "B.Cu")
		(net "UPI_CPU0_CPU1_P1P1_DN<3>")
	)
	(segment
		(start 155.48737 -45.728636)
		(end 149.402546 -47.530258)
		(width 0.1143)
		(layer "B.Cu")
		(net "UPI_CPU0_CPU1_P1P1_DN<3>")
	)
	(segment
		(start 262.654542 -44.679362)
		(end 279.94483 -48.118776)
		(width 0.1143)
		(layer "B.Cu")
		(net "UPI_CPU0_CPU1_P1P1_DN<3>")
	)
	(segment
		(start 259.207762 -45.662342)
		(end 259.791454 -45.534834)
		(width 0.1143)
		(layer "B.Cu")
		(net "UPI_CPU0_CPU1_P1P1_DN<3>")
	)
	(segment
		(start 136.05637 -58.773822)
		(end 135.953754 -58.876438)
		(width 0.0889)
		(layer "B.Cu")
		(net "UPI_CPU0_CPU1_P1P1_DN<3>")
	)
	(segment
		(start 138.017504 -55.704486)
		(end 138.02233 -55.713122)
		(width 0.0889)
		(layer "B.Cu")
		(net "UPI_CPU0_CPU1_P1P1_DN<3>")
	)
	(segment
		(start 288.091372 -48.31842)
		(end 288.244026 -48.506634)
		(width 0.1143)
		(layer "B.Cu")
		(net "UPI_CPU0_CPU1_P1P1_DN<3>")
	)
	(segment
		(start 138.54049 -54.818788)
		(end 138.507724 -54.818788)
		(width 0.0889)
		(layer "B.Cu")
		(net "UPI_CPU0_CPU1_P1P1_DN<3>")
	)
	(segment
		(start 140.570458 -53.137562)
		(end 140.499084 -53.137562)
		(width 0.0889)
		(layer "B.Cu")
		(net "UPI_CPU0_CPU1_P1P1_DN<3>")
	)
	(segment
		(start 139.040362 -53.344064)
		(end 138.870182 -53.63845)
		(width 0.0889)
		(layer "B.Cu")
		(net "UPI_CPU0_CPU1_P1P1_DN<3>")
	)
	(segment
		(start 207.521556 -44.277788)
		(end 207.585056 -44.320206)
		(width 0.1143)
		(layer "B.Cu")
		(net "UPI_CPU0_CPU1_P1P1_DN<3>")
	)
	(segment
		(start 257.71221 -45.485558)
		(end 257.653282 -45.215556)
		(width 0.1143)
		(layer "B.Cu")
		(net "UPI_CPU0_CPU1_P1P1_DN<3>")
	)
	(segment
		(start 248.531888 -46.919896)
		(end 248.855992 -46.868842)
		(width 0.1143)
		(layer "B.Cu")
		(net "UPI_CPU0_CPU1_P1P1_DN<3>")
	)
	(segment
		(start 140.948156 -51.677316)
		(end 140.736574 -52.813458)
		(width 0.1143)
		(layer "B.Cu")
		(net "UPI_CPU0_CPU1_P1P1_DN<3>")
	)
	(segment
		(start 202.382374 -40.851582)
		(end 207.521556 -44.277788)
		(width 0.1143)
		(layer "B.Cu")
		(net "UPI_CPU0_CPU1_P1P1_DN<3>")
	)
	(segment
		(start 259.858002 -44.577)
		(end 259.935218 -44.457112)
		(width 0.1143)
		(layer "B.Cu")
		(net "UPI_CPU0_CPU1_P1P1_DN<3>")
	)
	(segment
		(start 281.800554 -48.418242)
		(end 281.921966 -48.524414)
		(width 0.1143)
		(layer "B.Cu")
		(net "UPI_CPU0_CPU1_P1P1_DN<3>")
	)
	(segment
		(start 136.82345 -56.799988)
		(end 136.790684 -56.799988)
		(width 0.0889)
		(layer "B.Cu")
		(net "UPI_CPU0_CPU1_P1P1_DN<3>")
	)
	(segment
		(start 144.262602 -50.948082)
		(end 143.936212 -50.473864)
		(width 0.1143)
		(layer "B.Cu")
		(net "UPI_CPU0_CPU1_P1P1_DN<3>")
	)
	(segment
		(start 222.396812 -47.283116)
		(end 226.856036 -48.175164)
		(width 0.1143)
		(layer "B.Cu")
		(net "UPI_CPU0_CPU1_P1P1_DN<3>")
	)
	(segment
		(start 258.62915 -44.741846)
		(end 258.932934 -44.93641)
		(width 0.1143)
		(layer "B.Cu")
		(net "UPI_CPU0_CPU1_P1P1_DN<3>")
	)
	(segment
		(start 293.239444 -54.818788)
		(end 293.286434 -54.751732)
		(width 0.0889)
		(layer "B.Cu")
		(net "UPI_CPU0_CPU1_P1P1_DN<3>")
	)
	(segment
		(start 282.612592 -48.19142)
		(end 282.849828 -47.919386)
		(width 0.1143)
		(layer "B.Cu")
		(net "UPI_CPU0_CPU1_P1P1_DN<3>")
	)
	(segment
		(start 240.832132 -45.380148)
		(end 248.531888 -46.919896)
		(width 0.1143)
		(layer "B.Cu")
		(net "UPI_CPU0_CPU1_P1P1_DN<3>")
	)
	(segment
		(start 149.402546 -47.530004)
		(end 149.402292 -47.530258)
		(width 0.1143)
		(layer "B.Cu")
		(net "UPI_CPU0_CPU1_P1P1_DN<3>")
	)
	(segment
		(start 289.562286 -50.131218)
		(end 291.497512 -52.157376)
		(width 0.1143)
		(layer "B.Cu")
		(net "UPI_CPU0_CPU1_P1P1_DN<3>")
	)
	(segment
		(start 261.5692 -45.207936)
		(end 262.156194 -45.318172)
		(width 0.1143)
		(layer "B.Cu")
		(net "UPI_CPU0_CPU1_P1P1_DN<3>")
	)
	(segment
		(start 149.402292 -47.530258)
		(end 147.929092 -48.54321)
		(width 0.1143)
		(layer "B.Cu")
		(net "UPI_CPU0_CPU1_P1P1_DN<3>")
	)
	(segment
		(start 140.72108 -52.916582)
		(end 140.695172 -53.051964)
		(width 0.1143)
		(layer "B.Cu")
		(net "UPI_CPU0_CPU1_P1P1_DN<3>")
	)
	(segment
		(start 191.131698 -43.614594)
		(end 194.686428 -41.06164)
		(width 0.1143)
		(layer "B.Cu")
		(net "UPI_CPU0_CPU1_P1P1_DN<3>")
	)
	(segment
		(start 140.592048 -53.137562)
		(end 140.570458 -53.137562)
		(width 0.1143)
		(layer "B.Cu")
		(net "UPI_CPU0_CPU1_P1P1_DN<3>")
	)
	(segment
		(start 147.142454 -48.135794)
		(end 146.524472 -48.560482)
		(width 0.1143)
		(layer "B.Cu")
		(net "UPI_CPU0_CPU1_P1P1_DN<3>")
	)
	(segment
		(start 258.932934 -44.93641)
		(end 259.072126 -45.574966)
		(width 0.1143)
		(layer "B.Cu")
		(net "UPI_CPU0_CPU1_P1P1_DN<3>")
	)
	(segment
		(start 256.905506 -45.661326)
		(end 257.041142 -45.748702)
		(width 0.1143)
		(layer "B.Cu")
		(net "UPI_CPU0_CPU1_P1P1_DN<3>")
	)
	(segment
		(start 149.402546 -47.530258)
		(end 149.402546 -47.530004)
		(width 0.1143)
		(layer "B.Cu")
		(net "UPI_CPU0_CPU1_P1P1_DN<3>")
	)
	(segment
		(start 161.047176 -46.88078)
		(end 155.48737 -45.728636)
		(width 0.1143)
		(layer "B.Cu")
		(net "UPI_CPU0_CPU1_P1P1_DN<3>")
	)
	(segment
		(start 141.750796 -51.125882)
		(end 140.948156 -51.677316)
		(width 0.1143)
		(layer "B.Cu")
		(net "UPI_CPU0_CPU1_P1P1_DN<3>")
	)
	(segment
		(start 145.045176 -48.76927)
		(end 144.387824 -49.220882)
		(width 0.1143)
		(layer "B.Cu")
		(net "UPI_CPU0_CPU1_P1P1_DN<3>")
	)
	(segment
		(start 140.473684 -53.162962)
		(end 139.221464 -53.162962)
		(width 0.0889)
		(layer "B.Cu")
		(net "UPI_CPU0_CPU1_P1P1_DN<3>")
	)
	(segment
		(start 261.54507 -44.715938)
		(end 261.47776 -45.07484)
		(width 0.1143)
		(layer "B.Cu")
		(net "UPI_CPU0_CPU1_P1P1_DN<3>")
	)
	(segment
		(start 172.588174 -45.933868)
		(end 184.529984 -43.545252)
		(width 0.1143)
		(layer "B.Cu")
		(net "UPI_CPU0_CPU1_P1P1_DN<3>")
	)
	(segment
		(start 146.599148 -49.119282)
		(end 146.575018 -49.2506)
		(width 0.1143)
		(layer "B.Cu")
		(net "UPI_CPU0_CPU1_P1P1_DN<3>")
	)
	(segment
		(start 257.848862 -44.911518)
		(end 258.62915 -44.741846)
		(width 0.1143)
		(layer "B.Cu")
		(net "UPI_CPU0_CPU1_P1P1_DN<3>")
	)
	(segment
		(start 144.943576 -50.47996)
		(end 144.914112 -50.638202)
		(width 0.1143)
		(layer "B.Cu")
		(net "UPI_CPU0_CPU1_P1P1_DN<3>")
	)
	(segment
		(start 136.300464 -57.685686)
		(end 136.30529 -57.694322)
		(width 0.0889)
		(layer "B.Cu")
		(net "UPI_CPU0_CPU1_P1P1_DN<3>")
	)
	(segment
		(start 207.585056 -44.320206)
		(end 222.396812 -47.283116)
		(width 0.1143)
		(layer "B.Cu")
		(net "UPI_CPU0_CPU1_P1P1_DN<3>")
	)
	(segment
		(start 146.459194 -48.91659)
		(end 146.599148 -49.119282)
		(width 0.1143)
		(layer "B.Cu")
		(net "UPI_CPU0_CPU1_P1P1_DN<3>")
	)
	(segment
		(start 248.855992 -46.868842)
		(end 256.542794 -45.195998)
		(width 0.1143)
		(layer "B.Cu")
		(net "UPI_CPU0_CPU1_P1P1_DN<3>")
	)
	(segment
		(start 262.156194 -45.318172)
		(end 262.28929 -45.226986)
		(width 0.1143)
		(layer "B.Cu")
		(net "UPI_CPU0_CPU1_P1P1_DN<3>")
	)
	(segment
		(start 136.294114 -57.675018)
		(end 136.300464 -57.685686)
		(width 0.0889)
		(layer "B.Cu")
		(net "UPI_CPU0_CPU1_P1P1_DN<3>")
	)
	(segment
		(start 257.653282 -45.215556)
		(end 257.848862 -44.911518)
		(width 0.1143)
		(layer "B.Cu")
		(net "UPI_CPU0_CPU1_P1P1_DN<3>")
	)
	(segment
		(start 259.935218 -44.457112)
		(end 260.681724 -44.294552)
		(width 0.1143)
		(layer "B.Cu")
		(net "UPI_CPU0_CPU1_P1P1_DN<3>")
	)
	(segment
		(start 291.864034 -52.523898)
		(end 291.864034 -52.559966)
		(width 0.0889)
		(layer "B.Cu")
		(net "UPI_CPU0_CPU1_P1P1_DN<3>")
	)
	(segment
		(start 194.686428 -41.06164)
		(end 197.55739 -39.88816)
		(width 0.1143)
		(layer "B.Cu")
		(net "UPI_CPU0_CPU1_P1P1_DN<3>")
	)
	(segment
		(start 140.736574 -52.813458)
		(end 140.736828 -52.813458)
		(width 0.1143)
		(layer "B.Cu")
		(net "UPI_CPU0_CPU1_P1P1_DN<3>")
	)
	(segment
		(start 284.817312 -47.776384)
		(end 286.737806 -47.644812)
		(width 0.1143)
		(layer "B.Cu")
		(net "UPI_CPU0_CPU1_P1P1_DN<3>")
	)
	(segment
		(start 257.624834 -45.621194)
		(end 257.71221 -45.485558)
		(width 0.1143)
		(layer "B.Cu")
		(net "UPI_CPU0_CPU1_P1P1_DN<3>")
	)
	(segment
		(start 281.788616 -48.248062)
		(end 281.800554 -48.418242)
		(width 0.1143)
		(layer "B.Cu")
		(net "UPI_CPU0_CPU1_P1P1_DN<3>")
	)
	(segment
		(start 140.695172 -53.051964)
		(end 140.592048 -53.137562)
		(width 0.1143)
		(layer "B.Cu")
		(net "UPI_CPU0_CPU1_P1P1_DN<3>")
	)
	(segment
		(start 146.060414 -49.604168)
		(end 145.910046 -49.576482)
		(width 0.1143)
		(layer "B.Cu")
		(net "UPI_CPU0_CPU1_P1P1_DN<3>")
	)
	(segment
		(start 259.739638 -44.76115)
		(end 259.858002 -44.577)
		(width 0.1143)
		(layer "B.Cu")
		(net "UPI_CPU0_CPU1_P1P1_DN<3>")
	)
	(segment
		(start 166.43477 -47.99711)
		(end 172.588174 -45.933868)
		(width 0.1143)
		(layer "B.Cu")
		(net "UPI_CPU0_CPU1_P1P1_DN<3>")
	)
	(segment
		(start 147.929092 -48.54321)
		(end 147.771104 -48.513746)
		(width 0.1143)
		(layer "B.Cu")
		(net "UPI_CPU0_CPU1_P1P1_DN<3>")
	)
	(segment
		(start 138.011154 -55.693818)
		(end 138.017504 -55.704486)
		(width 0.0889)
		(layer "B.Cu")
		(net "UPI_CPU0_CPU1_P1P1_DN<3>")
	)
	(segment
		(start 147.771104 -48.513746)
		(end 147.56511 -48.21428)
		(width 0.1143)
		(layer "B.Cu")
		(net "UPI_CPU0_CPU1_P1P1_DN<3>")
	)
	(segment
		(start 286.737806 -47.644812)
		(end 288.091372 -48.31842)
		(width 0.1143)
		(layer "B.Cu")
		(net "UPI_CPU0_CPU1_P1P1_DN<3>")
	)
	(segment
		(start 145.910046 -49.576482)
		(end 145.40103 -48.835056)
		(width 0.1143)
		(layer "B.Cu")
		(net "UPI_CPU0_CPU1_P1P1_DN<3>")
	)
	(segment
		(start 283.646626 -47.864522)
		(end 284.030928 -48.199802)
		(width 0.1143)
		(layer "B.Cu")
		(net "UPI_CPU0_CPU1_P1P1_DN<3>")
	)
	(segment
		(start 142.369032 -51.240436)
		(end 141.750796 -51.125882)
		(width 0.1143)
		(layer "B.Cu")
		(net "UPI_CPU0_CPU1_P1P1_DN<3>")
	)
	(segment
		(start 161.047176 -46.88078)
		(end 166.43477 -47.99711)
		(width 0.1143)
		(layer "B.Cu")
		(net "UPI_CPU0_CPU1_P1P1_DN<3>")
	)
	(segment
		(start 143.936212 -50.473864)
		(end 143.580866 -50.408078)
		(width 0.1143)
		(layer "B.Cu")
		(net "UPI_CPU0_CPU1_P1P1_DN<3>")
	)
	(segment
		(start 282.624276 -48.361346)
		(end 282.612592 -48.19142)
		(width 0.1143)
		(layer "B.Cu")
		(net "UPI_CPU0_CPU1_P1P1_DN<3>")
	)
	(segment
		(start 259.072126 -45.574966)
		(end 259.207762 -45.662342)
		(width 0.1143)
		(layer "B.Cu")
		(net "UPI_CPU0_CPU1_P1P1_DN<3>")
	)
	(segment
		(start 259.87883 -45.399198)
		(end 259.739638 -44.76115)
		(width 0.1143)
		(layer "B.Cu")
		(net "UPI_CPU0_CPU1_P1P1_DN<3>")
	)
	(segment
		(start 144.387824 -49.220882)
		(end 144.321784 -49.576228)
		(width 0.1143)
		(layer "B.Cu")
		(net "UPI_CPU0_CPU1_P1P1_DN<3>")
	)
	(segment
		(start 282.849828 -47.919386)
		(end 283.646626 -47.864522)
		(width 0.1143)
		(layer "B.Cu")
		(net "UPI_CPU0_CPU1_P1P1_DN<3>")
	)
	(segment
		(start 261.341108 -44.417996)
		(end 261.450074 -44.577)
		(width 0.1143)
		(layer "B.Cu")
		(net "UPI_CPU0_CPU1_P1P1_DN<3>")
	)
	(segment
		(start 139.221464 -53.162962)
		(end 139.040362 -53.344064)
		(width 0.0889)
		(layer "B.Cu")
		(net "UPI_CPU0_CPU1_P1P1_DN<3>")
	)
	(segment
		(start 184.529984 -43.545252)
		(end 191.131698 -43.614594)
		(width 0.1143)
		(layer "B.Cu")
		(net "UPI_CPU0_CPU1_P1P1_DN<3>")
	)
	(segment
		(start 291.497512 -52.157376)
		(end 291.864034 -52.523898)
		(width 0.1143)
		(layer "B.Cu")
		(net "UPI_CPU0_CPU1_P1P1_DN<3>")
	)
	(segment
		(start 145.40103 -48.835056)
		(end 145.045176 -48.76927)
		(width 0.1143)
		(layer "B.Cu")
		(net "UPI_CPU0_CPU1_P1P1_DN<3>")
	)
	(segment
		(start 262.28929 -45.226986)
		(end 262.353552 -44.882308)
		(width 0.1143)
		(layer "B.Cu")
		(net "UPI_CPU0_CPU1_P1P1_DN<3>")
	)
	(segment
		(start 279.94483 -48.118776)
		(end 281.516836 -48.010318)
		(width 0.1143)
		(layer "B.Cu")
		(net "UPI_CPU0_CPU1_P1P1_DN<3>")
	)
	(segment
		(start 292.960044 -53.655976)
		(end 292.960044 -53.923946)
		(width 0.0889)
		(layer "B.Cu")
		(net "UPI_CPU0_CPU1_P1P1_DN<3>")
	)
	(segment
		(start 144.321784 -49.576228)
		(end 144.943576 -50.47996)
		(width 0.1143)
		(layer "B.Cu")
		(net "UPI_CPU0_CPU1_P1P1_DN<3>")
	)
	(segment
		(start 284.030928 -48.199802)
		(end 284.473904 -48.169322)
		(width 0.1143)
		(layer "B.Cu")
		(net "UPI_CPU0_CPU1_P1P1_DN<3>")
	)
	(segment
		(start 146.524472 -48.560482)
		(end 146.459194 -48.91659)
		(width 0.1143)
		(layer "B.Cu")
		(net "UPI_CPU0_CPU1_P1P1_DN<3>")
	)
	(segment
		(start 261.450074 -44.577)
		(end 261.54507 -44.715938)
		(width 0.1143)
		(layer "B.Cu")
		(net "UPI_CPU0_CPU1_P1P1_DN<3>")
	)
	(segment
		(start 281.921966 -48.524414)
		(end 282.51785 -48.483266)
		(width 0.1143)
		(layer "B.Cu")
		(net "UPI_CPU0_CPU1_P1P1_DN<3>")
	)
	(segment
		(start 137.68578 -56.304434)
		(end 137.653014 -56.304434)
		(width 0.0889)
		(layer "B.Cu")
		(net "UPI_CPU0_CPU1_P1P1_DN<3>")
	)
	(segment
		(start 144.914112 -50.638202)
		(end 144.420844 -50.977546)
		(width 0.1143)
		(layer "B.Cu")
		(net "UPI_CPU0_CPU1_P1P1_DN<3>")
	)
	(segment
		(start 257.041142 -45.748702)
		(end 257.624834 -45.621194)
		(width 0.1143)
		(layer "B.Cu")
		(net "UPI_CPU0_CPU1_P1P1_DN<3>")
	)
	(segment
		(start 140.499084 -53.137562)
		(end 140.473684 -53.162962)
		(width 0.0889)
		(layer "B.Cu")
		(net "UPI_CPU0_CPU1_P1P1_DN<3>")
	)
	(segment
		(start 260.681724 -44.294552)
		(end 261.341108 -44.417996)
		(width 0.1143)
		(layer "B.Cu")
		(net "UPI_CPU0_CPU1_P1P1_DN<3>")
	)
	(segment
		(start 284.473904 -48.169322)
		(end 284.817312 -47.776384)
		(width 0.1143)
		(layer "B.Cu")
		(net "UPI_CPU0_CPU1_P1P1_DN<3>")
	)
	(segment
		(start 147.56511 -48.21428)
		(end 147.142454 -48.135794)
		(width 0.1143)
		(layer "B.Cu")
		(net "UPI_CPU0_CPU1_P1P1_DN<3>")
	)
	(segment
		(start 140.736828 -52.813458)
		(end 140.718286 -52.913026)
		(width 0.1143)
		(layer "B.Cu")
		(net "UPI_CPU0_CPU1_P1P1_DN<3>")
	)
	(segment
		(start 288.244026 -48.506634)
		(end 289.562286 -50.131218)
		(width 0.1143)
		(layer "B.Cu")
		(net "UPI_CPU0_CPU1_P1P1_DN<3>")
	)
	(segment
		(start 293.286434 -54.751732)
		(end 293.22776 -54.418738)
		(width 0.0889)
		(layer "B.Cu")
		(net "UPI_CPU0_CPU1_P1P1_DN<3>")
	)
	(segment
		(start 143.580866 -50.408078)
		(end 142.369032 -51.240436)
		(width 0.1143)
		(layer "B.Cu")
		(net "UPI_CPU0_CPU1_P1P1_DN<3>")
	)
	(segment
		(start 256.846578 -45.390562)
		(end 256.905506 -45.661326)
		(width 0.1143)
		(layer "B.Cu")
		(net "UPI_CPU0_CPU1_P1P1_DN<3>")
	)
	(segment
		(start 256.542794 -45.195998)
		(end 256.846578 -45.390562)
		(width 0.1143)
		(layer "B.Cu")
		(net "UPI_CPU0_CPU1_P1P1_DN<3>")
	)
	(segment
		(start 281.516836 -48.010318)
		(end 281.788616 -48.248062)
		(width 0.1143)
		(layer "B.Cu")
		(net "UPI_CPU0_CPU1_P1P1_DN<3>")
	)
	(segment
		(start 262.353552 -44.882308)
		(end 262.654542 -44.679362)
		(width 0.1143)
		(layer "B.Cu")
		(net "UPI_CPU0_CPU1_P1P1_DN<3>")
	)
	(segment
		(start 140.718286 -52.913026)
		(end 140.72108 -52.916582)
		(width 0.1143)
		(layer "B.Cu")
		(net "UPI_CPU0_CPU1_P1P1_DN<3>")
	)
	(segment
		(start 259.791454 -45.534834)
		(end 259.87883 -45.399198)
		(width 0.1143)
		(layer "B.Cu")
		(net "UPI_CPU0_CPU1_P1P1_DN<3>")
	)
	(segment
		(start 197.55739 -39.88816)
		(end 202.382374 -40.851582)
		(width 0.1143)
		(layer "B.Cu")
		(net "UPI_CPU0_CPU1_P1P1_DN<3>")
	)
	(segment
		(start 144.420844 -50.977546)
		(end 144.262602 -50.948082)
		(width 0.1143)
		(layer "B.Cu")
		(net "UPI_CPU0_CPU1_P1P1_DN<3>")
	)
	(arc
		(start 292.88105 -54.218586)
		(mid 292.827996 -54.440121)
		(end 292.904418 -54.654704)
		(width 0.0889)
		(layer "B.Cu")
		(net "UPI_CPU0_CPU1_P1P1_DN<3>")
	)
	(arc
		(start 136.30529 -57.694322)
		(mid 136.354045 -57.890674)
		(end 136.300464 -58.085736)
		(width 0.0889)
		(layer "B.Cu")
		(net "UPI_CPU0_CPU1_P1P1_DN<3>")
	)
	(arc
		(start 293.169848 -54.814724)
		(mid 293.204558 -54.818272)
		(end 293.239444 -54.818788)
		(width 0.0889)
		(layer "B.Cu")
		(net "UPI_CPU0_CPU1_P1P1_DN<3>")
	)
	(arc
		(start 138.507724 -54.818788)
		(mid 138.015334 -55.117721)
		(end 138.011154 -55.693818)
		(width 0.0889)
		(layer "B.Cu")
		(net "UPI_CPU0_CPU1_P1P1_DN<3>")
	)
	(arc
		(start 136.790684 -56.799988)
		(mid 136.298294 -57.098921)
		(end 136.294114 -57.675018)
		(width 0.0889)
		(layer "B.Cu")
		(net "UPI_CPU0_CPU1_P1P1_DN<3>")
	)
	(arc
		(start 138.02233 -55.713122)
		(mid 138.018583 -56.102378)
		(end 137.68578 -56.304434)
		(width 0.0889)
		(layer "B.Cu")
		(net "UPI_CPU0_CPU1_P1P1_DN<3>")
	)
	(arc
		(start 136.300464 -58.085736)
		(mid 136.242069 -58.225643)
		(end 136.221216 -58.375804)
		(width 0.0889)
		(layer "B.Cu")
		(net "UPI_CPU0_CPU1_P1P1_DN<3>")
	)
	(arc
		(start 292.904418 -54.654704)
		(mid 293.021 -54.761492)
		(end 293.169848 -54.814724)
		(width 0.0889)
		(layer "B.Cu")
		(net "UPI_CPU0_CPU1_P1P1_DN<3>")
	)
	(arc
		(start 137.158984 -56.599836)
		(mid 137.017301 -56.74364)
		(end 136.82345 -56.799988)
		(width 0.0889)
		(layer "B.Cu")
		(net "UPI_CPU0_CPU1_P1P1_DN<3>")
	)
	(arc
		(start 138.876024 -54.218586)
		(mid 138.878772 -54.614053)
		(end 138.54049 -54.818788)
		(width 0.0889)
		(layer "B.Cu")
		(net "UPI_CPU0_CPU1_P1P1_DN<3>")
	)
	(arc
		(start 137.653014 -56.304434)
		(mid 137.36759 -56.387901)
		(end 137.158984 -56.599836)
		(width 0.0889)
		(layer "B.Cu")
		(net "UPI_CPU0_CPU1_P1P1_DN<3>")
	)
	(arc
		(start 292.960044 -53.923946)
		(mid 292.939886 -54.07645)
		(end 292.88105 -54.218586)
		(width 0.0889)
		(layer "B.Cu")
		(net "UPI_CPU0_CPU1_P1P1_DN<3>")
	)
	(arc
		(start 138.870182 -53.63845)
		(mid 138.796947 -53.929298)
		(end 138.876024 -54.218586)
		(width 0.0889)
		(layer "B.Cu")
		(net "UPI_CPU0_CPU1_P1P1_DN<3>")
	)
	(arc
		(start 136.221216 -58.375804)
		(mid 136.178371 -58.591203)
		(end 136.05637 -58.773822)
		(width 0.0889)
		(layer "B.Cu")
		(net "UPI_CPU0_CPU1_P1P1_DN<3>")
	)
	(segment
		(start 290.93922 -55.409338)
		(end 291.51072 -55.409338)
		(width 0.1143)
		(layer "F.Cu")
		(net "UPI_CPU0_CPU1_P1P1_DN<2>")
	)
	(segment
		(start 137.099294 -59.866784)
		(end 137.670794 -59.866784)
		(width 0.1143)
		(layer "F.Cu")
		(net "UPI_CPU0_CPU1_P1P1_DN<2>")
	)
	(via
		(at 137.670794 -59.866784)
		(size 0.508)
		(drill 0.254)
		(layers "F.Cu" "B.Cu")
		(net "UPI_CPU0_CPU1_P1P1_DN<2>")
	)
	(via
		(at 291.51072 -55.409338)
		(size 0.508)
		(drill 0.254)
		(layers "F.Cu" "B.Cu")
		(net "UPI_CPU0_CPU1_P1P1_DN<2>")
	)
	(segment
		(start 141.895576 -54.361334)
		(end 141.920976 -54.386734)
		(width 0.0889)
		(layer "B.Cu")
		(net "UPI_CPU0_CPU1_P1P1_DN<2>")
	)
	(segment
		(start 285.121858 -49.335436)
		(end 285.330646 -49.280572)
		(width 0.1143)
		(layer "B.Cu")
		(net "UPI_CPU0_CPU1_P1P1_DN<2>")
	)
	(segment
		(start 264.006838 -47.24654)
		(end 264.342118 -47.380652)
		(width 0.1143)
		(layer "B.Cu")
		(net "UPI_CPU0_CPU1_P1P1_DN<2>")
	)
	(segment
		(start 137.377678 -59.697874)
		(end 137.353802 -59.608466)
		(width 0.0889)
		(layer "B.Cu")
		(net "UPI_CPU0_CPU1_P1P1_DN<2>")
	)
	(segment
		(start 184.64276 -44.774104)
		(end 191.234822 -44.797726)
		(width 0.1143)
		(layer "B.Cu")
		(net "UPI_CPU0_CPU1_P1P1_DN<2>")
	)
	(segment
		(start 141.52626 -54.406038)
		(end 141.570964 -54.361334)
		(width 0.0889)
		(layer "B.Cu")
		(net "UPI_CPU0_CPU1_P1P1_DN<2>")
	)
	(segment
		(start 191.234822 -44.797726)
		(end 195.379848 -42.123106)
		(width 0.1143)
		(layer "B.Cu")
		(net "UPI_CPU0_CPU1_P1P1_DN<2>")
	)
	(segment
		(start 207.307942 -45.496734)
		(end 222.396812 -48.515016)
		(width 0.1143)
		(layer "B.Cu")
		(net "UPI_CPU0_CPU1_P1P1_DN<2>")
	)
	(segment
		(start 141.259052 -54.406038)
		(end 141.259052 -54.406292)
		(width 0.0889)
		(layer "B.Cu")
		(net "UPI_CPU0_CPU1_P1P1_DN<2>")
	)
	(segment
		(start 263.585706 -46.264068)
		(end 264.006838 -47.24654)
		(width 0.1143)
		(layer "B.Cu")
		(net "UPI_CPU0_CPU1_P1P1_DN<2>")
	)
	(segment
		(start 290.529264 -52.577746)
		(end 290.529264 -52.704492)
		(width 0.0889)
		(layer "B.Cu")
		(net "UPI_CPU0_CPU1_P1P1_DN<2>")
	)
	(segment
		(start 263.247886 -47.571914)
		(end 262.826754 -46.589442)
		(width 0.1143)
		(layer "B.Cu")
		(net "UPI_CPU0_CPU1_P1P1_DN<2>")
	)
	(segment
		(start 263.435846 -46.204124)
		(end 263.585706 -46.264068)
		(width 0.1143)
		(layer "B.Cu")
		(net "UPI_CPU0_CPU1_P1P1_DN<2>")
	)
	(segment
		(start 257.369056 -48.14697)
		(end 257.330448 -47.050198)
		(width 0.1143)
		(layer "B.Cu")
		(net "UPI_CPU0_CPU1_P1P1_DN<2>")
	)
	(segment
		(start 289.88639 -51.97094)
		(end 290.216336 -52.300886)
		(width 0.1143)
		(layer "B.Cu")
		(net "UPI_CPU0_CPU1_P1P1_DN<2>")
	)
	(segment
		(start 197.87108 -40.994584)
		(end 201.703178 -41.76014)
		(width 0.1143)
		(layer "B.Cu")
		(net "UPI_CPU0_CPU1_P1P1_DN<2>")
	)
	(segment
		(start 290.935918 -53.522118)
		(end 291.432234 -54.018434)
		(width 0.0889)
		(layer "B.Cu")
		(net "UPI_CPU0_CPU1_P1P1_DN<2>")
	)
	(segment
		(start 258.475988 -48.871886)
		(end 259.274056 -48.843692)
		(width 0.1143)
		(layer "B.Cu")
		(net "UPI_CPU0_CPU1_P1P1_DN<2>")
	)
	(segment
		(start 137.670794 -59.866784)
		(end 137.377678 -59.697874)
		(width 0.0889)
		(layer "B.Cu")
		(net "UPI_CPU0_CPU1_P1P1_DN<2>")
	)
	(segment
		(start 146.51101 -50.931064)
		(end 147.413726 -50.32248)
		(width 0.1143)
		(layer "B.Cu")
		(net "UPI_CPU0_CPU1_P1P1_DN<2>")
	)
	(segment
		(start 289.88639 -51.970686)
		(end 289.88639 -51.97094)
		(width 0.1143)
		(layer "B.Cu")
		(net "UPI_CPU0_CPU1_P1P1_DN<2>")
	)
	(segment
		(start 287.45815 -49.542446)
		(end 289.88639 -51.970686)
		(width 0.1143)
		(layer "B.Cu")
		(net "UPI_CPU0_CPU1_P1P1_DN<2>")
	)
	(segment
		(start 284.71876 -49.440592)
		(end 284.833314 -49.507902)
		(width 0.1143)
		(layer "B.Cu")
		(net "UPI_CPU0_CPU1_P1P1_DN<2>")
	)
	(segment
		(start 290.782248 -52.83073)
		(end 290.935918 -52.9844)
		(width 0.0889)
		(layer "B.Cu")
		(net "UPI_CPU0_CPU1_P1P1_DN<2>")
	)
	(segment
		(start 291.617654 -55.302404)
		(end 291.51072 -55.409338)
		(width 0.0889)
		(layer "B.Cu")
		(net "UPI_CPU0_CPU1_P1P1_DN<2>")
	)
	(segment
		(start 286.53486 -49.1998)
		(end 287.45815 -49.542446)
		(width 0.1143)
		(layer "B.Cu")
		(net "UPI_CPU0_CPU1_P1P1_DN<2>")
	)
	(segment
		(start 140.90269 -54.463442)
		(end 141.004798 -54.361334)
		(width 0.0889)
		(layer "B.Cu")
		(net "UPI_CPU0_CPU1_P1P1_DN<2>")
	)
	(segment
		(start 226.94392 -49.42459)
		(end 241.342672 -46.544992)
		(width 0.1143)
		(layer "B.Cu")
		(net "UPI_CPU0_CPU1_P1P1_DN<2>")
	)
	(segment
		(start 258.037584 -46.910752)
		(end 258.15544 -47.020988)
		(width 0.1143)
		(layer "B.Cu")
		(net "UPI_CPU0_CPU1_P1P1_DN<2>")
	)
	(segment
		(start 290.252404 -52.300886)
		(end 290.529264 -52.577746)
		(width 0.0889)
		(layer "B.Cu")
		(net "UPI_CPU0_CPU1_P1P1_DN<2>")
	)
	(segment
		(start 255.443736 -47.253652)
		(end 255.561592 -47.363888)
		(width 0.1143)
		(layer "B.Cu")
		(net "UPI_CPU0_CPU1_P1P1_DN<2>")
	)
	(segment
		(start 284.474158 -49.504854)
		(end 284.71876 -49.440592)
		(width 0.1143)
		(layer "B.Cu")
		(net "UPI_CPU0_CPU1_P1P1_DN<2>")
	)
	(segment
		(start 266.03452 -46.655228)
		(end 278.977598 -49.24425)
		(width 0.1143)
		(layer "B.Cu")
		(net "UPI_CPU0_CPU1_P1P1_DN<2>")
	)
	(segment
		(start 291.432234 -54.018434)
		(end 291.521388 -54.018434)
		(width 0.0889)
		(layer "B.Cu")
		(net "UPI_CPU0_CPU1_P1P1_DN<2>")
	)
	(segment
		(start 259.274056 -48.843692)
		(end 259.520436 -48.579532)
		(width 0.1143)
		(layer "B.Cu")
		(net "UPI_CPU0_CPU1_P1P1_DN<2>")
	)
	(segment
		(start 166.934896 -49.374298)
		(end 173.022514 -47.098204)
		(width 0.1143)
		(layer "B.Cu")
		(net "UPI_CPU0_CPU1_P1P1_DN<2>")
	)
	(segment
		(start 259.464048 -46.975014)
		(end 259.574284 -46.856904)
		(width 0.1143)
		(layer "B.Cu")
		(net "UPI_CPU0_CPU1_P1P1_DN<2>")
	)
	(segment
		(start 141.920976 -54.386734)
		(end 142.234666 -54.386734)
		(width 0.1143)
		(layer "B.Cu")
		(net "UPI_CPU0_CPU1_P1P1_DN<2>")
	)
	(segment
		(start 141.214348 -54.361334)
		(end 141.259052 -54.406038)
		(width 0.0889)
		(layer "B.Cu")
		(net "UPI_CPU0_CPU1_P1P1_DN<2>")
	)
	(segment
		(start 290.655502 -52.83073)
		(end 290.782248 -52.83073)
		(width 0.0889)
		(layer "B.Cu")
		(net "UPI_CPU0_CPU1_P1P1_DN<2>")
	)
	(segment
		(start 290.529264 -52.704492)
		(end 290.655502 -52.83073)
		(width 0.0889)
		(layer "B.Cu")
		(net "UPI_CPU0_CPU1_P1P1_DN<2>")
	)
	(segment
		(start 260.600698 -48.547274)
		(end 262.379206 -48.484536)
		(width 0.1143)
		(layer "B.Cu")
		(net "UPI_CPU0_CPU1_P1P1_DN<2>")
	)
	(segment
		(start 141.259052 -54.406292)
		(end 141.303756 -54.450996)
		(width 0.0889)
		(layer "B.Cu")
		(net "UPI_CPU0_CPU1_P1P1_DN<2>")
	)
	(segment
		(start 141.004798 -54.361334)
		(end 141.214348 -54.361334)
		(width 0.0889)
		(layer "B.Cu")
		(net "UPI_CPU0_CPU1_P1P1_DN<2>")
	)
	(segment
		(start 281.541728 -49.756822)
		(end 283.755846 -49.691798)
		(width 0.1143)
		(layer "B.Cu")
		(net "UPI_CPU0_CPU1_P1P1_DN<2>")
	)
	(segment
		(start 139.376658 -55.504334)
		(end 139.409424 -55.504334)
		(width 0.0889)
		(layer "B.Cu")
		(net "UPI_CPU0_CPU1_P1P1_DN<2>")
	)
	(segment
		(start 201.703178 -41.76014)
		(end 207.307942 -45.496734)
		(width 0.1143)
		(layer "B.Cu")
		(net "UPI_CPU0_CPU1_P1P1_DN<2>")
	)
	(segment
		(start 152.24506 -48.040036)
		(end 156.160216 -47.220378)
		(width 0.1143)
		(layer "B.Cu")
		(net "UPI_CPU0_CPU1_P1P1_DN<2>")
	)
	(segment
		(start 255.591056 -48.208692)
		(end 255.855216 -48.455326)
		(width 0.1143)
		(layer "B.Cu")
		(net "UPI_CPU0_CPU1_P1P1_DN<2>")
	)
	(segment
		(start 141.570964 -54.361334)
		(end 141.895576 -54.361334)
		(width 0.0889)
		(layer "B.Cu")
		(net "UPI_CPU0_CPU1_P1P1_DN<2>")
	)
	(segment
		(start 147.413726 -50.32248)
		(end 148.06422 -50.190146)
		(width 0.1143)
		(layer "B.Cu")
		(net "UPI_CPU0_CPU1_P1P1_DN<2>")
	)
	(segment
		(start 283.755846 -49.691798)
		(end 284.064202 -49.611788)
		(width 0.1143)
		(layer "B.Cu")
		(net "UPI_CPU0_CPU1_P1P1_DN<2>")
	)
	(segment
		(start 141.481556 -54.450996)
		(end 141.52626 -54.406292)
		(width 0.0889)
		(layer "B.Cu")
		(net "UPI_CPU0_CPU1_P1P1_DN<2>")
	)
	(segment
		(start 257.330448 -47.050198)
		(end 257.440684 -46.932088)
		(width 0.1143)
		(layer "B.Cu")
		(net "UPI_CPU0_CPU1_P1P1_DN<2>")
	)
	(segment
		(start 137.342626 -59.107324)
		(end 137.324084 -59.076336)
		(width 0.0889)
		(layer "B.Cu")
		(net "UPI_CPU0_CPU1_P1P1_DN<2>")
	)
	(segment
		(start 257.440684 -46.932088)
		(end 258.037584 -46.910752)
		(width 0.1143)
		(layer "B.Cu")
		(net "UPI_CPU0_CPU1_P1P1_DN<2>")
	)
	(segment
		(start 140.758164 -54.713886)
		(end 140.90269 -54.463442)
		(width 0.0889)
		(layer "B.Cu")
		(net "UPI_CPU0_CPU1_P1P1_DN<2>")
	)
	(segment
		(start 262.886698 -46.439582)
		(end 263.435846 -46.204124)
		(width 0.1143)
		(layer "B.Cu")
		(net "UPI_CPU0_CPU1_P1P1_DN<2>")
	)
	(segment
		(start 284.833314 -49.507902)
		(end 285.055056 -49.449736)
		(width 0.1143)
		(layer "B.Cu")
		(net "UPI_CPU0_CPU1_P1P1_DN<2>")
	)
	(segment
		(start 254.736346 -47.392844)
		(end 254.846582 -47.274988)
		(width 0.1143)
		(layer "B.Cu")
		(net "UPI_CPU0_CPU1_P1P1_DN<2>")
	)
	(segment
		(start 258.15544 -47.020988)
		(end 258.211828 -48.625506)
		(width 0.1143)
		(layer "B.Cu")
		(net "UPI_CPU0_CPU1_P1P1_DN<2>")
	)
	(segment
		(start 148.06422 -50.190146)
		(end 150.660862 -48.439578)
		(width 0.1143)
		(layer "B.Cu")
		(net "UPI_CPU0_CPU1_P1P1_DN<2>")
	)
	(segment
		(start 254.51943 -48.501808)
		(end 254.766064 -48.237648)
		(width 0.1143)
		(layer "B.Cu")
		(net "UPI_CPU0_CPU1_P1P1_DN<2>")
	)
	(segment
		(start 291.85743 -54.618636)
		(end 291.85108 -54.629304)
		(width 0.0889)
		(layer "B.Cu")
		(net "UPI_CPU0_CPU1_P1P1_DN<2>")
	)
	(segment
		(start 146.14398 -51.484784)
		(end 146.51101 -50.931064)
		(width 0.1143)
		(layer "B.Cu")
		(net "UPI_CPU0_CPU1_P1P1_DN<2>")
	)
	(segment
		(start 284.404816 -49.623472)
		(end 284.474158 -49.504854)
		(width 0.1143)
		(layer "B.Cu")
		(net "UPI_CPU0_CPU1_P1P1_DN<2>")
	)
	(segment
		(start 260.337046 -48.30064)
		(end 260.600698 -48.547274)
		(width 0.1143)
		(layer "B.Cu")
		(net "UPI_CPU0_CPU1_P1P1_DN<2>")
	)
	(segment
		(start 285.055056 -49.449736)
		(end 285.121858 -49.335436)
		(width 0.1143)
		(layer "B.Cu")
		(net "UPI_CPU0_CPU1_P1P1_DN<2>")
	)
	(segment
		(start 250.14428 -47.782988)
		(end 253.616968 -48.533304)
		(width 0.1143)
		(layer "B.Cu")
		(net "UPI_CPU0_CPU1_P1P1_DN<2>")
	)
	(segment
		(start 258.211828 -48.625506)
		(end 258.475988 -48.871886)
		(width 0.1143)
		(layer "B.Cu")
		(net "UPI_CPU0_CPU1_P1P1_DN<2>")
	)
	(segment
		(start 173.022514 -47.098204)
		(end 184.64276 -44.774104)
		(width 0.1143)
		(layer "B.Cu")
		(net "UPI_CPU0_CPU1_P1P1_DN<2>")
	)
	(segment
		(start 138.514328 -56.990488)
		(end 138.547094 -56.990488)
		(width 0.0889)
		(layer "B.Cu")
		(net "UPI_CPU0_CPU1_P1P1_DN<2>")
	)
	(segment
		(start 255.561592 -47.363888)
		(end 255.591056 -48.208692)
		(width 0.1143)
		(layer "B.Cu")
		(net "UPI_CPU0_CPU1_P1P1_DN<2>")
	)
	(segment
		(start 279.04186 -49.341024)
		(end 279.266396 -49.386236)
		(width 0.1143)
		(layer "B.Cu")
		(net "UPI_CPU0_CPU1_P1P1_DN<2>")
	)
	(segment
		(start 143.05153 -53.56987)
		(end 146.14398 -51.484784)
		(width 0.1143)
		(layer "B.Cu")
		(net "UPI_CPU0_CPU1_P1P1_DN<2>")
	)
	(segment
		(start 255.855216 -48.455326)
		(end 257.122676 -48.41113)
		(width 0.1143)
		(layer "B.Cu")
		(net "UPI_CPU0_CPU1_P1P1_DN<2>")
	)
	(segment
		(start 248.838212 -48.044354)
		(end 250.14428 -47.782988)
		(width 0.1143)
		(layer "B.Cu")
		(net "UPI_CPU0_CPU1_P1P1_DN<2>")
	)
	(segment
		(start 241.342672 -46.544992)
		(end 248.838212 -48.044354)
		(width 0.1143)
		(layer "B.Cu")
		(net "UPI_CPU0_CPU1_P1P1_DN<2>")
	)
	(segment
		(start 260.171184 -46.835568)
		(end 260.28904 -46.945804)
		(width 0.1143)
		(layer "B.Cu")
		(net "UPI_CPU0_CPU1_P1P1_DN<2>")
	)
	(segment
		(start 279.36317 -49.321466)
		(end 281.541728 -49.756822)
		(width 0.1143)
		(layer "B.Cu")
		(net "UPI_CPU0_CPU1_P1P1_DN<2>")
	)
	(segment
		(start 142.234666 -54.386734)
		(end 143.05153 -53.56987)
		(width 0.1143)
		(layer "B.Cu")
		(net "UPI_CPU0_CPU1_P1P1_DN<2>")
	)
	(segment
		(start 257.122676 -48.41113)
		(end 257.369056 -48.14697)
		(width 0.1143)
		(layer "B.Cu")
		(net "UPI_CPU0_CPU1_P1P1_DN<2>")
	)
	(segment
		(start 156.160216 -47.220378)
		(end 166.934896 -49.374298)
		(width 0.1143)
		(layer "B.Cu")
		(net "UPI_CPU0_CPU1_P1P1_DN<2>")
	)
	(segment
		(start 290.935918 -52.9844)
		(end 290.935918 -53.522118)
		(width 0.0889)
		(layer "B.Cu")
		(net "UPI_CPU0_CPU1_P1P1_DN<2>")
	)
	(segment
		(start 259.520436 -48.579532)
		(end 259.464048 -46.975014)
		(width 0.1143)
		(layer "B.Cu")
		(net "UPI_CPU0_CPU1_P1P1_DN<2>")
	)
	(segment
		(start 264.342118 -47.380652)
		(end 266.03452 -46.655228)
		(width 0.1143)
		(layer "B.Cu")
		(net "UPI_CPU0_CPU1_P1P1_DN<2>")
	)
	(segment
		(start 262.98779 -48.223678)
		(end 263.247886 -47.571914)
		(width 0.1143)
		(layer "B.Cu")
		(net "UPI_CPU0_CPU1_P1P1_DN<2>")
	)
	(segment
		(start 284.064202 -49.611788)
		(end 284.183074 -49.681638)
		(width 0.1143)
		(layer "B.Cu")
		(net "UPI_CPU0_CPU1_P1P1_DN<2>")
	)
	(segment
		(start 141.52626 -54.406292)
		(end 141.52626 -54.406038)
		(width 0.0889)
		(layer "B.Cu")
		(net "UPI_CPU0_CPU1_P1P1_DN<2>")
	)
	(segment
		(start 150.660862 -48.439578)
		(end 152.24506 -48.040036)
		(width 0.1143)
		(layer "B.Cu")
		(net "UPI_CPU0_CPU1_P1P1_DN<2>")
	)
	(segment
		(start 290.216336 -52.300886)
		(end 290.252404 -52.300886)
		(width 0.0889)
		(layer "B.Cu")
		(net "UPI_CPU0_CPU1_P1P1_DN<2>")
	)
	(segment
		(start 291.862256 -54.61)
		(end 291.85743 -54.618636)
		(width 0.0889)
		(layer "B.Cu")
		(net "UPI_CPU0_CPU1_P1P1_DN<2>")
	)
	(segment
		(start 141.303756 -54.450996)
		(end 141.481556 -54.450996)
		(width 0.0889)
		(layer "B.Cu")
		(net "UPI_CPU0_CPU1_P1P1_DN<2>")
	)
	(segment
		(start 195.383404 -42.121582)
		(end 197.87108 -40.994584)
		(width 0.1143)
		(layer "B.Cu")
		(net "UPI_CPU0_CPU1_P1P1_DN<2>")
	)
	(segment
		(start 137.659618 -57.485534)
		(end 137.692384 -57.485534)
		(width 0.0889)
		(layer "B.Cu")
		(net "UPI_CPU0_CPU1_P1P1_DN<2>")
	)
	(segment
		(start 260.28904 -46.945804)
		(end 260.337046 -48.30064)
		(width 0.1143)
		(layer "B.Cu")
		(net "UPI_CPU0_CPU1_P1P1_DN<2>")
	)
	(segment
		(start 279.266396 -49.386236)
		(end 279.36317 -49.321466)
		(width 0.1143)
		(layer "B.Cu")
		(net "UPI_CPU0_CPU1_P1P1_DN<2>")
	)
	(segment
		(start 222.396812 -48.515016)
		(end 226.94392 -49.42459)
		(width 0.1143)
		(layer "B.Cu")
		(net "UPI_CPU0_CPU1_P1P1_DN<2>")
	)
	(segment
		(start 284.183074 -49.681638)
		(end 284.404816 -49.623472)
		(width 0.1143)
		(layer "B.Cu")
		(net "UPI_CPU0_CPU1_P1P1_DN<2>")
	)
	(segment
		(start 254.846582 -47.274988)
		(end 255.443736 -47.253652)
		(width 0.1143)
		(layer "B.Cu")
		(net "UPI_CPU0_CPU1_P1P1_DN<2>")
	)
	(segment
		(start 195.379848 -42.123106)
		(end 195.383404 -42.121582)
		(width 0.1143)
		(layer "B.Cu")
		(net "UPI_CPU0_CPU1_P1P1_DN<2>")
	)
	(segment
		(start 278.977598 -49.24425)
		(end 279.04186 -49.341024)
		(width 0.1143)
		(layer "B.Cu")
		(net "UPI_CPU0_CPU1_P1P1_DN<2>")
	)
	(segment
		(start 262.379206 -48.484536)
		(end 262.98779 -48.223678)
		(width 0.1143)
		(layer "B.Cu")
		(net "UPI_CPU0_CPU1_P1P1_DN<2>")
	)
	(segment
		(start 253.616968 -48.533304)
		(end 254.51943 -48.501808)
		(width 0.1143)
		(layer "B.Cu")
		(net "UPI_CPU0_CPU1_P1P1_DN<2>")
	)
	(segment
		(start 140.231368 -55.009288)
		(end 140.264134 -55.009288)
		(width 0.0889)
		(layer "B.Cu")
		(net "UPI_CPU0_CPU1_P1P1_DN<2>")
	)
	(segment
		(start 137.36701 -59.173364)
		(end 137.342626 -59.107324)
		(width 0.0889)
		(layer "B.Cu")
		(net "UPI_CPU0_CPU1_P1P1_DN<2>")
	)
	(segment
		(start 254.766064 -48.237648)
		(end 254.736346 -47.392844)
		(width 0.1143)
		(layer "B.Cu")
		(net "UPI_CPU0_CPU1_P1P1_DN<2>")
	)
	(segment
		(start 259.574284 -46.856904)
		(end 260.171184 -46.835568)
		(width 0.1143)
		(layer "B.Cu")
		(net "UPI_CPU0_CPU1_P1P1_DN<2>")
	)
	(segment
		(start 285.330646 -49.280572)
		(end 286.53486 -49.1998)
		(width 0.1143)
		(layer "B.Cu")
		(net "UPI_CPU0_CPU1_P1P1_DN<2>")
	)
	(segment
		(start 262.826754 -46.589442)
		(end 262.886698 -46.439582)
		(width 0.1143)
		(layer "B.Cu")
		(net "UPI_CPU0_CPU1_P1P1_DN<2>")
	)
	(arc
		(start 139.899644 -55.209186)
		(mid 140.039723 -55.06645)
		(end 140.231368 -55.009288)
		(width 0.0889)
		(layer "B.Cu")
		(net "UPI_CPU0_CPU1_P1P1_DN<2>")
	)
	(arc
		(start 137.324084 -58.085736)
		(mid 137.321336 -57.690269)
		(end 137.659618 -57.485534)
		(width 0.0889)
		(layer "B.Cu")
		(net "UPI_CPU0_CPU1_P1P1_DN<2>")
	)
	(arc
		(start 138.182604 -57.190386)
		(mid 138.322683 -57.04765)
		(end 138.514328 -56.990488)
		(width 0.0889)
		(layer "B.Cu")
		(net "UPI_CPU0_CPU1_P1P1_DN<2>")
	)
	(arc
		(start 140.264134 -55.009288)
		(mid 140.549558 -54.925821)
		(end 140.758164 -54.713886)
		(width 0.0889)
		(layer "B.Cu")
		(net "UPI_CPU0_CPU1_P1P1_DN<2>")
	)
	(arc
		(start 291.525706 -54.018688)
		(mid 291.858624 -54.220679)
		(end 291.862256 -54.61)
		(width 0.0889)
		(layer "B.Cu")
		(net "UPI_CPU0_CPU1_P1P1_DN<2>")
	)
	(arc
		(start 138.547094 -56.990488)
		(mid 139.045345 -56.687648)
		(end 139.041124 -56.104536)
		(width 0.0889)
		(layer "B.Cu")
		(net "UPI_CPU0_CPU1_P1P1_DN<2>")
	)
	(arc
		(start 291.778182 -54.9148)
		(mid 291.736458 -55.124561)
		(end 291.617654 -55.302404)
		(width 0.0889)
		(layer "B.Cu")
		(net "UPI_CPU0_CPU1_P1P1_DN<2>")
	)
	(arc
		(start 137.324084 -58.67654)
		(mid 137.403215 -58.381138)
		(end 137.324084 -58.085736)
		(width 0.0889)
		(layer "B.Cu")
		(net "UPI_CPU0_CPU1_P1P1_DN<2>")
	)
	(arc
		(start 137.324084 -59.076336)
		(mid 137.270585 -58.876438)
		(end 137.324084 -58.67654)
		(width 0.0889)
		(layer "B.Cu")
		(net "UPI_CPU0_CPU1_P1P1_DN<2>")
	)
	(arc
		(start 291.521388 -54.018434)
		(mid 291.523547 -54.018555)
		(end 291.525706 -54.018688)
		(width 0.0889)
		(layer "B.Cu")
		(net "UPI_CPU0_CPU1_P1P1_DN<2>")
	)
	(arc
		(start 291.85108 -54.629304)
		(mid 291.796563 -54.767436)
		(end 291.778182 -54.9148)
		(width 0.0889)
		(layer "B.Cu")
		(net "UPI_CPU0_CPU1_P1P1_DN<2>")
	)
	(arc
		(start 137.692384 -57.485534)
		(mid 137.975601 -57.401253)
		(end 138.182604 -57.190386)
		(width 0.0889)
		(layer "B.Cu")
		(net "UPI_CPU0_CPU1_P1P1_DN<2>")
	)
	(arc
		(start 137.353802 -59.608466)
		(mid 137.402472 -59.392195)
		(end 137.36701 -59.173364)
		(width 0.0889)
		(layer "B.Cu")
		(net "UPI_CPU0_CPU1_P1P1_DN<2>")
	)
	(arc
		(start 139.041124 -56.104536)
		(mid 139.038376 -55.709069)
		(end 139.376658 -55.504334)
		(width 0.0889)
		(layer "B.Cu")
		(net "UPI_CPU0_CPU1_P1P1_DN<2>")
	)
	(arc
		(start 139.409424 -55.504334)
		(mid 139.692641 -55.420053)
		(end 139.899644 -55.209186)
		(width 0.0889)
		(layer "B.Cu")
		(net "UPI_CPU0_CPU1_P1P1_DN<2>")
	)
	(segment
		(start 137.099294 -57.885584)
		(end 137.670794 -57.885584)
		(width 0.1143)
		(layer "F.Cu")
		(net "UPI_CPU0_CPU1_P1P1_DN<1>")
	)
	(segment
		(start 290.0807 -53.923184)
		(end 290.6522 -53.923184)
		(width 0.1143)
		(layer "F.Cu")
		(net "UPI_CPU0_CPU1_P1P1_DN<1>")
	)
	(via
		(at 137.670794 -57.885584)
		(size 0.508)
		(drill 0.254)
		(layers "F.Cu" "B.Cu")
		(net "UPI_CPU0_CPU1_P1P1_DN<1>")
	)
	(via
		(at 290.6522 -53.923184)
		(size 0.508)
		(drill 0.254)
		(layers "F.Cu" "B.Cu")
		(net "UPI_CPU0_CPU1_P1P1_DN<1>")
	)
	(segment
		(start 143.792956 -54.609492)
		(end 143.637 -54.765448)
		(width 0.0889)
		(layer "B.Cu")
		(net "UPI_CPU0_CPU1_P1P1_DN<1>")
	)
	(segment
		(start 142.87246 -55.155084)
		(end 142.456916 -55.404512)
		(width 0.0889)
		(layer "B.Cu")
		(net "UPI_CPU0_CPU1_P1P1_DN<1>")
	)
	(segment
		(start 201.161904 -42.187876)
		(end 198.332598 -41.621964)
		(width 0.1143)
		(layer "B.Cu")
		(net "UPI_CPU0_CPU1_P1P1_DN<1>")
	)
	(segment
		(start 289.97148 -53.087524)
		(end 289.45332 -52.569364)
		(width 0.0889)
		(layer "B.Cu")
		(net "UPI_CPU0_CPU1_P1P1_DN<1>")
	)
	(segment
		(start 286.420814 -49.9872)
		(end 285.773622 -49.891696)
		(width 0.1143)
		(layer "B.Cu")
		(net "UPI_CPU0_CPU1_P1P1_DN<1>")
	)
	(segment
		(start 255.941068 -49.824894)
		(end 255.050798 -49.816512)
		(width 0.1143)
		(layer "B.Cu")
		(net "UPI_CPU0_CPU1_P1P1_DN<1>")
	)
	(segment
		(start 255.050798 -49.816512)
		(end 250.605036 -48.443134)
		(width 0.1143)
		(layer "B.Cu")
		(net "UPI_CPU0_CPU1_P1P1_DN<1>")
	)
	(segment
		(start 198.332598 -41.621964)
		(end 195.95465 -42.646346)
		(width 0.1143)
		(layer "B.Cu")
		(net "UPI_CPU0_CPU1_P1P1_DN<1>")
	)
	(segment
		(start 285.205932 -50.071782)
		(end 283.525214 -51.331622)
		(width 0.1143)
		(layer "B.Cu")
		(net "UPI_CPU0_CPU1_P1P1_DN<1>")
	)
	(segment
		(start 248.215658 -48.68799)
		(end 248.215658 -48.687736)
		(width 0.1143)
		(layer "B.Cu")
		(net "UPI_CPU0_CPU1_P1P1_DN<1>")
	)
	(segment
		(start 274.489672 -49.535588)
		(end 274.267676 -50.646076)
		(width 0.1143)
		(layer "B.Cu")
		(net "UPI_CPU0_CPU1_P1P1_DN<1>")
	)
	(segment
		(start 281.30627 -51.562508)
		(end 279.574752 -50.40884)
		(width 0.1143)
		(layer "B.Cu")
		(net "UPI_CPU0_CPU1_P1P1_DN<1>")
	)
	(segment
		(start 273.458178 -50.484278)
		(end 273.67992 -49.37379)
		(width 0.1143)
		(layer "B.Cu")
		(net "UPI_CPU0_CPU1_P1P1_DN<1>")
	)
	(segment
		(start 263.160002 -49.750218)
		(end 262.57631 -49.68621)
		(width 0.1143)
		(layer "B.Cu")
		(net "UPI_CPU0_CPU1_P1P1_DN<1>")
	)
	(segment
		(start 146.010884 -52.937664)
		(end 144.603978 -53.891434)
		(width 0.1143)
		(layer "B.Cu")
		(net "UPI_CPU0_CPU1_P1P1_DN<1>")
	)
	(segment
		(start 268.720824 -48.383444)
		(end 268.520164 -48.082708)
		(width 0.1143)
		(layer "B.Cu")
		(net "UPI_CPU0_CPU1_P1P1_DN<1>")
	)
	(segment
		(start 195.95465 -42.646346)
		(end 191.593724 -45.562012)
		(width 0.1143)
		(layer "B.Cu")
		(net "UPI_CPU0_CPU1_P1P1_DN<1>")
	)
	(segment
		(start 262.57631 -49.68621)
		(end 261.979918 -50.165)
		(width 0.1143)
		(layer "B.Cu")
		(net "UPI_CPU0_CPU1_P1P1_DN<1>")
	)
	(segment
		(start 276.777196 -49.933098)
		(end 276.09292 -49.796192)
		(width 0.1143)
		(layer "B.Cu")
		(net "UPI_CPU0_CPU1_P1P1_DN<1>")
	)
	(segment
		(start 265.794998 -47.570644)
		(end 265.002772 -47.943516)
		(width 0.1143)
		(layer "B.Cu")
		(net "UPI_CPU0_CPU1_P1P1_DN<1>")
	)
	(segment
		(start 278.724614 -50.577496)
		(end 278.086058 -50.449734)
		(width 0.1143)
		(layer "B.Cu")
		(net "UPI_CPU0_CPU1_P1P1_DN<1>")
	)
	(segment
		(start 274.13331 -50.735738)
		(end 273.54784 -50.618644)
		(width 0.1143)
		(layer "B.Cu")
		(net "UPI_CPU0_CPU1_P1P1_DN<1>")
	)
	(segment
		(start 289.199574 -52.315618)
		(end 288.928556 -52.0446)
		(width 0.0889)
		(layer "B.Cu")
		(net "UPI_CPU0_CPU1_P1P1_DN<1>")
	)
	(segment
		(start 248.215658 -48.687736)
		(end 241.203988 -47.31639)
		(width 0.1143)
		(layer "B.Cu")
		(net "UPI_CPU0_CPU1_P1P1_DN<1>")
	)
	(segment
		(start 276.09292 -49.796192)
		(end 275.938742 -49.565052)
		(width 0.1143)
		(layer "B.Cu")
		(net "UPI_CPU0_CPU1_P1P1_DN<1>")
	)
	(segment
		(start 268.520164 -48.082708)
		(end 267.738352 -47.926498)
		(width 0.1143)
		(layer "B.Cu")
		(net "UPI_CPU0_CPU1_P1P1_DN<1>")
	)
	(segment
		(start 191.593724 -45.562012)
		(end 184.711848 -45.509434)
		(width 0.1143)
		(layer "B.Cu")
		(net "UPI_CPU0_CPU1_P1P1_DN<1>")
	)
	(segment
		(start 271.926304 -48.763682)
		(end 271.625568 -48.964342)
		(width 0.1143)
		(layer "B.Cu")
		(net "UPI_CPU0_CPU1_P1P1_DN<1>")
	)
	(segment
		(start 148.33981 -51.461924)
		(end 146.129756 -52.960524)
		(width 0.1143)
		(layer "B.Cu")
		(net "UPI_CPU0_CPU1_P1P1_DN<1>")
	)
	(segment
		(start 266.626848 -47.964852)
		(end 266.426188 -47.664116)
		(width 0.1143)
		(layer "B.Cu")
		(net "UPI_CPU0_CPU1_P1P1_DN<1>")
	)
	(segment
		(start 274.7899 -49.335182)
		(end 274.489672 -49.535588)
		(width 0.1143)
		(layer "B.Cu")
		(net "UPI_CPU0_CPU1_P1P1_DN<1>")
	)
	(segment
		(start 278.086058 -50.449734)
		(end 277.72487 -49.907952)
		(width 0.1143)
		(layer "B.Cu")
		(net "UPI_CPU0_CPU1_P1P1_DN<1>")
	)
	(segment
		(start 151.591264 -48.962056)
		(end 148.691092 -50.928524)
		(width 0.1143)
		(layer "B.Cu")
		(net "UPI_CPU0_CPU1_P1P1_DN<1>")
	)
	(segment
		(start 290.6522 -53.923184)
		(end 290.783518 -53.923184)
		(width 0.0889)
		(layer "B.Cu")
		(net "UPI_CPU0_CPU1_P1P1_DN<1>")
	)
	(segment
		(start 137.670794 -58.093102)
		(end 137.670794 -57.885584)
		(width 0.0889)
		(layer "B.Cu")
		(net "UPI_CPU0_CPU1_P1P1_DN<1>")
	)
	(segment
		(start 138.54049 -57.790588)
		(end 138.507724 -57.790588)
		(width 0.0889)
		(layer "B.Cu")
		(net "UPI_CPU0_CPU1_P1P1_DN<1>")
	)
	(segment
		(start 241.203988 -47.31639)
		(end 235.853478 -48.386238)
		(width 0.1143)
		(layer "B.Cu")
		(net "UPI_CPU0_CPU1_P1P1_DN<1>")
	)
	(segment
		(start 279.115774 -50.31613)
		(end 278.724614 -50.577496)
		(width 0.1143)
		(layer "B.Cu")
		(net "UPI_CPU0_CPU1_P1P1_DN<1>")
	)
	(segment
		(start 140.25753 -56.799988)
		(end 140.224764 -56.799988)
		(width 0.0889)
		(layer "B.Cu")
		(net "UPI_CPU0_CPU1_P1P1_DN<1>")
	)
	(segment
		(start 156.32303 -48.015906)
		(end 151.591264 -48.962056)
		(width 0.1143)
		(layer "B.Cu")
		(net "UPI_CPU0_CPU1_P1P1_DN<1>")
	)
	(segment
		(start 290.22802 -54.323234)
		(end 289.97148 -54.066694)
		(width 0.0889)
		(layer "B.Cu")
		(net "UPI_CPU0_CPU1_P1P1_DN<1>")
	)
	(segment
		(start 250.605036 -48.443134)
		(end 248.215658 -48.68799)
		(width 0.1143)
		(layer "B.Cu")
		(net "UPI_CPU0_CPU1_P1P1_DN<1>")
	)
	(segment
		(start 263.942322 -49.405794)
		(end 263.908286 -49.717198)
		(width 0.1143)
		(layer "B.Cu")
		(net "UPI_CPU0_CPU1_P1P1_DN<1>")
	)
	(segment
		(start 270.69161 -50.002186)
		(end 270.601948 -49.868074)
		(width 0.1143)
		(layer "B.Cu")
		(net "UPI_CPU0_CPU1_P1P1_DN<1>")
	)
	(segment
		(start 271.625568 -48.964342)
		(end 271.412462 -50.03038)
		(width 0.1143)
		(layer "B.Cu")
		(net "UPI_CPU0_CPU1_P1P1_DN<1>")
	)
	(segment
		(start 270.61414 -48.5013)
		(end 269.832328 -48.34509)
		(width 0.1143)
		(layer "B.Cu")
		(net "UPI_CPU0_CPU1_P1P1_DN<1>")
	)
	(segment
		(start 268.52499 -49.947576)
		(end 268.435328 -49.813464)
		(width 0.1143)
		(layer "B.Cu")
		(net "UPI_CPU0_CPU1_P1P1_DN<1>")
	)
	(segment
		(start 267.437616 -48.127158)
		(end 267.12164 -49.708308)
		(width 0.1143)
		(layer "B.Cu")
		(net "UPI_CPU0_CPU1_P1P1_DN<1>")
	)
	(segment
		(start 235.853478 -48.386238)
		(end 235.847382 -48.387762)
		(width 0.1143)
		(layer "B.Cu")
		(net "UPI_CPU0_CPU1_P1P1_DN<1>")
	)
	(segment
		(start 143.637 -54.765448)
		(end 143.637508 -54.893718)
		(width 0.0889)
		(layer "B.Cu")
		(net "UPI_CPU0_CPU1_P1P1_DN<1>")
	)
	(segment
		(start 270.8148 -48.802036)
		(end 270.61414 -48.5013)
		(width 0.1143)
		(layer "B.Cu")
		(net "UPI_CPU0_CPU1_P1P1_DN<1>")
	)
	(segment
		(start 289.45332 -52.441348)
		(end 289.32759 -52.315618)
		(width 0.0889)
		(layer "B.Cu")
		(net "UPI_CPU0_CPU1_P1P1_DN<1>")
	)
	(segment
		(start 266.400788 -49.680114)
		(end 266.311126 -49.546002)
		(width 0.1143)
		(layer "B.Cu")
		(net "UPI_CPU0_CPU1_P1P1_DN<1>")
	)
	(segment
		(start 285.773622 -49.891696)
		(end 285.205932 -50.071782)
		(width 0.1143)
		(layer "B.Cu")
		(net "UPI_CPU0_CPU1_P1P1_DN<1>")
	)
	(segment
		(start 222.396812 -49.255426)
		(end 207.206088 -46.217332)
		(width 0.1143)
		(layer "B.Cu")
		(net "UPI_CPU0_CPU1_P1P1_DN<1>")
	)
	(segment
		(start 227.534724 -50.282856)
		(end 222.396812 -49.255426)
		(width 0.1143)
		(layer "B.Cu")
		(net "UPI_CPU0_CPU1_P1P1_DN<1>")
	)
	(segment
		(start 288.928556 -52.0446)
		(end 288.798 -52.0446)
		(width 0.0889)
		(layer "B.Cu")
		(net "UPI_CPU0_CPU1_P1P1_DN<1>")
	)
	(segment
		(start 289.45332 -52.569364)
		(end 289.45332 -52.441348)
		(width 0.0889)
		(layer "B.Cu")
		(net "UPI_CPU0_CPU1_P1P1_DN<1>")
	)
	(segment
		(start 290.783518 -54.323234)
		(end 290.22802 -54.323234)
		(width 0.0889)
		(layer "B.Cu")
		(net "UPI_CPU0_CPU1_P1P1_DN<1>")
	)
	(segment
		(start 207.206088 -46.217332)
		(end 201.161904 -42.187876)
		(width 0.1143)
		(layer "B.Cu")
		(net "UPI_CPU0_CPU1_P1P1_DN<1>")
	)
	(segment
		(start 143.375126 -55.1561)
		(end 142.87246 -55.155084)
		(width 0.0889)
		(layer "B.Cu")
		(net "UPI_CPU0_CPU1_P1P1_DN<1>")
	)
	(segment
		(start 269.318994 -49.608994)
		(end 269.245588 -49.97577)
		(width 0.1143)
		(layer "B.Cu")
		(net "UPI_CPU0_CPU1_P1P1_DN<1>")
	)
	(segment
		(start 143.637508 -54.893718)
		(end 143.375126 -55.1561)
		(width 0.0889)
		(layer "B.Cu")
		(net "UPI_CPU0_CPU1_P1P1_DN<1>")
	)
	(segment
		(start 263.843008 -48.874426)
		(end 263.803638 -49.233836)
		(width 0.1143)
		(layer "B.Cu")
		(net "UPI_CPU0_CPU1_P1P1_DN<1>")
	)
	(segment
		(start 263.908286 -49.717198)
		(end 263.61009 -49.95672)
		(width 0.1143)
		(layer "B.Cu")
		(net "UPI_CPU0_CPU1_P1P1_DN<1>")
	)
	(segment
		(start 261.378192 -50.381408)
		(end 256.815844 -49.482502)
		(width 0.1143)
		(layer "B.Cu")
		(net "UPI_CPU0_CPU1_P1P1_DN<1>")
	)
	(segment
		(start 235.847382 -48.387762)
		(end 227.534724 -50.282856)
		(width 0.1143)
		(layer "B.Cu")
		(net "UPI_CPU0_CPU1_P1P1_DN<1>")
	)
	(segment
		(start 146.129756 -52.960524)
		(end 146.110198 -52.956714)
		(width 0.1143)
		(layer "B.Cu")
		(net "UPI_CPU0_CPU1_P1P1_DN<1>")
	)
	(segment
		(start 266.311126 -49.546002)
		(end 266.626848 -47.964852)
		(width 0.1143)
		(layer "B.Cu")
		(net "UPI_CPU0_CPU1_P1P1_DN<1>")
	)
	(segment
		(start 184.711848 -45.509434)
		(end 173.240446 -47.803308)
		(width 0.1143)
		(layer "B.Cu")
		(net "UPI_CPU0_CPU1_P1P1_DN<1>")
	)
	(segment
		(start 277.72487 -49.907952)
		(end 277.02383 -49.767998)
		(width 0.1143)
		(layer "B.Cu")
		(net "UPI_CPU0_CPU1_P1P1_DN<1>")
	)
	(segment
		(start 261.979918 -50.165)
		(end 261.378192 -50.381408)
		(width 0.1143)
		(layer "B.Cu")
		(net "UPI_CPU0_CPU1_P1P1_DN<1>")
	)
	(segment
		(start 274.267676 -50.646076)
		(end 274.13331 -50.735738)
		(width 0.1143)
		(layer "B.Cu")
		(net "UPI_CPU0_CPU1_P1P1_DN<1>")
	)
	(segment
		(start 275.938742 -49.565052)
		(end 274.7899 -49.335182)
		(width 0.1143)
		(layer "B.Cu")
		(net "UPI_CPU0_CPU1_P1P1_DN<1>")
	)
	(segment
		(start 271.278604 -50.119788)
		(end 270.69161 -50.002186)
		(width 0.1143)
		(layer "B.Cu")
		(net "UPI_CPU0_CPU1_P1P1_DN<1>")
	)
	(segment
		(start 167.104822 -50.15357)
		(end 156.32303 -48.015906)
		(width 0.1143)
		(layer "B.Cu")
		(net "UPI_CPU0_CPU1_P1P1_DN<1>")
	)
	(segment
		(start 279.574752 -50.40884)
		(end 279.115774 -50.31613)
		(width 0.1143)
		(layer "B.Cu")
		(net "UPI_CPU0_CPU1_P1P1_DN<1>")
	)
	(segment
		(start 288.551366 -51.797966)
		(end 288.551366 -51.76774)
		(width 0.0889)
		(layer "B.Cu")
		(net "UPI_CPU0_CPU1_P1P1_DN<1>")
	)
	(segment
		(start 142.456916 -55.404512)
		(end 142.34668 -55.612538)
		(width 0.0889)
		(layer "B.Cu")
		(net "UPI_CPU0_CPU1_P1P1_DN<1>")
	)
	(segment
		(start 144.353026 -54.1782)
		(end 143.92148 -54.609746)
		(width 0.0889)
		(layer "B.Cu")
		(net "UPI_CPU0_CPU1_P1P1_DN<1>")
	)
	(segment
		(start 144.603978 -53.891434)
		(end 144.353026 -54.142386)
		(width 0.1143)
		(layer "B.Cu")
		(net "UPI_CPU0_CPU1_P1P1_DN<1>")
	)
	(segment
		(start 269.245588 -49.97577)
		(end 269.111984 -50.065178)
		(width 0.1143)
		(layer "B.Cu")
		(net "UPI_CPU0_CPU1_P1P1_DN<1>")
	)
	(segment
		(start 146.07032 -52.949094)
		(end 146.010884 -52.937664)
		(width 0.1143)
		(layer "B.Cu")
		(net "UPI_CPU0_CPU1_P1P1_DN<1>")
	)
	(segment
		(start 265.980672 -47.575216)
		(end 265.794998 -47.570644)
		(width 0.1143)
		(layer "B.Cu")
		(net "UPI_CPU0_CPU1_P1P1_DN<1>")
	)
	(segment
		(start 142.131288 -55.809388)
		(end 141.941804 -55.809388)
		(width 0.0889)
		(layer "B.Cu")
		(net "UPI_CPU0_CPU1_P1P1_DN<1>")
	)
	(segment
		(start 263.298432 -49.922684)
		(end 263.160002 -49.750218)
		(width 0.1143)
		(layer "B.Cu")
		(net "UPI_CPU0_CPU1_P1P1_DN<1>")
	)
	(segment
		(start 267.738352 -47.926498)
		(end 267.677138 -47.967138)
		(width 0.1143)
		(layer "B.Cu")
		(net "UPI_CPU0_CPU1_P1P1_DN<1>")
	)
	(segment
		(start 289.32759 -52.315618)
		(end 289.199574 -52.315618)
		(width 0.0889)
		(layer "B.Cu")
		(net "UPI_CPU0_CPU1_P1P1_DN<1>")
	)
	(segment
		(start 139.40282 -57.295034)
		(end 139.370054 -57.295034)
		(width 0.0889)
		(layer "B.Cu")
		(net "UPI_CPU0_CPU1_P1P1_DN<1>")
	)
	(segment
		(start 263.803638 -49.233836)
		(end 263.942322 -49.405794)
		(width 0.1143)
		(layer "B.Cu")
		(net "UPI_CPU0_CPU1_P1P1_DN<1>")
	)
	(segment
		(start 270.601948 -49.868074)
		(end 270.8148 -48.802036)
		(width 0.1143)
		(layer "B.Cu")
		(net "UPI_CPU0_CPU1_P1P1_DN<1>")
	)
	(segment
		(start 143.92148 -54.609746)
		(end 143.792956 -54.609492)
		(width 0.0889)
		(layer "B.Cu")
		(net "UPI_CPU0_CPU1_P1P1_DN<1>")
	)
	(segment
		(start 267.12164 -49.708308)
		(end 266.987782 -49.797716)
		(width 0.1143)
		(layer "B.Cu")
		(net "UPI_CPU0_CPU1_P1P1_DN<1>")
	)
	(segment
		(start 289.97148 -54.066694)
		(end 289.97148 -53.087524)
		(width 0.0889)
		(layer "B.Cu")
		(net "UPI_CPU0_CPU1_P1P1_DN<1>")
	)
	(segment
		(start 269.531592 -48.54575)
		(end 269.318994 -49.608994)
		(width 0.1143)
		(layer "B.Cu")
		(net "UPI_CPU0_CPU1_P1P1_DN<1>")
	)
	(segment
		(start 173.240446 -47.803308)
		(end 167.104822 -50.15357)
		(width 0.1143)
		(layer "B.Cu")
		(net "UPI_CPU0_CPU1_P1P1_DN<1>")
	)
	(segment
		(start 266.426188 -47.664116)
		(end 265.980672 -47.575216)
		(width 0.1143)
		(layer "B.Cu")
		(net "UPI_CPU0_CPU1_P1P1_DN<1>")
	)
	(segment
		(start 273.479514 -49.073308)
		(end 273.47926 -49.073054)
		(width 0.1143)
		(layer "B.Cu")
		(net "UPI_CPU0_CPU1_P1P1_DN<1>")
	)
	(segment
		(start 267.677138 -47.967138)
		(end 267.437616 -48.127158)
		(width 0.1143)
		(layer "B.Cu")
		(net "UPI_CPU0_CPU1_P1P1_DN<1>")
	)
	(segment
		(start 287.273238 -50.489612)
		(end 286.420814 -49.9872)
		(width 0.1143)
		(layer "B.Cu")
		(net "UPI_CPU0_CPU1_P1P1_DN<1>")
	)
	(segment
		(start 273.54784 -50.618644)
		(end 273.458178 -50.484278)
		(width 0.1143)
		(layer "B.Cu")
		(net "UPI_CPU0_CPU1_P1P1_DN<1>")
	)
	(segment
		(start 146.109182 -52.95646)
		(end 146.07032 -52.949094)
		(width 0.1143)
		(layer "B.Cu")
		(net "UPI_CPU0_CPU1_P1P1_DN<1>")
	)
	(segment
		(start 281.83713 -51.66868)
		(end 281.30627 -51.562508)
		(width 0.1143)
		(layer "B.Cu")
		(net "UPI_CPU0_CPU1_P1P1_DN<1>")
	)
	(segment
		(start 141.11986 -56.304434)
		(end 141.087094 -56.304434)
		(width 0.0889)
		(layer "B.Cu")
		(net "UPI_CPU0_CPU1_P1P1_DN<1>")
	)
	(segment
		(start 273.47926 -49.073054)
		(end 271.926304 -48.763682)
		(width 0.1143)
		(layer "B.Cu")
		(net "UPI_CPU0_CPU1_P1P1_DN<1>")
	)
	(segment
		(start 268.435328 -49.813464)
		(end 268.61643 -48.90643)
		(width 0.1143)
		(layer "B.Cu")
		(net "UPI_CPU0_CPU1_P1P1_DN<1>")
	)
	(segment
		(start 288.551366 -51.76774)
		(end 287.273238 -50.489612)
		(width 0.1143)
		(layer "B.Cu")
		(net "UPI_CPU0_CPU1_P1P1_DN<1>")
	)
	(segment
		(start 283.525214 -51.331622)
		(end 281.83713 -51.66868)
		(width 0.1143)
		(layer "B.Cu")
		(net "UPI_CPU0_CPU1_P1P1_DN<1>")
	)
	(segment
		(start 146.110198 -52.956714)
		(end 146.109182 -52.95646)
		(width 0.1143)
		(layer "B.Cu")
		(net "UPI_CPU0_CPU1_P1P1_DN<1>")
	)
	(segment
		(start 268.61643 -48.90643)
		(end 268.720824 -48.383444)
		(width 0.1143)
		(layer "B.Cu")
		(net "UPI_CPU0_CPU1_P1P1_DN<1>")
	)
	(segment
		(start 277.02383 -49.767998)
		(end 276.777196 -49.933098)
		(width 0.1143)
		(layer "B.Cu")
		(net "UPI_CPU0_CPU1_P1P1_DN<1>")
	)
	(segment
		(start 266.987782 -49.797716)
		(end 266.400788 -49.680114)
		(width 0.1143)
		(layer "B.Cu")
		(net "UPI_CPU0_CPU1_P1P1_DN<1>")
	)
	(segment
		(start 269.111984 -50.065178)
		(end 268.52499 -49.947576)
		(width 0.1143)
		(layer "B.Cu")
		(net "UPI_CPU0_CPU1_P1P1_DN<1>")
	)
	(segment
		(start 269.832328 -48.34509)
		(end 269.531592 -48.54575)
		(width 0.1143)
		(layer "B.Cu")
		(net "UPI_CPU0_CPU1_P1P1_DN<1>")
	)
	(segment
		(start 265.002772 -47.943516)
		(end 263.843008 -48.874426)
		(width 0.1143)
		(layer "B.Cu")
		(net "UPI_CPU0_CPU1_P1P1_DN<1>")
	)
	(segment
		(start 288.798 -52.0446)
		(end 288.551366 -51.797966)
		(width 0.0889)
		(layer "B.Cu")
		(net "UPI_CPU0_CPU1_P1P1_DN<1>")
	)
	(segment
		(start 256.815844 -49.482502)
		(end 255.941068 -49.824894)
		(width 0.1143)
		(layer "B.Cu")
		(net "UPI_CPU0_CPU1_P1P1_DN<1>")
	)
	(segment
		(start 263.61009 -49.95672)
		(end 263.298432 -49.922684)
		(width 0.1143)
		(layer "B.Cu")
		(net "UPI_CPU0_CPU1_P1P1_DN<1>")
	)
	(segment
		(start 148.691092 -50.928524)
		(end 148.33981 -51.461924)
		(width 0.1143)
		(layer "B.Cu")
		(net "UPI_CPU0_CPU1_P1P1_DN<1>")
	)
	(segment
		(start 144.353026 -54.142386)
		(end 144.353026 -54.1782)
		(width 0.0889)
		(layer "B.Cu")
		(net "UPI_CPU0_CPU1_P1P1_DN<1>")
	)
	(segment
		(start 271.412462 -50.03038)
		(end 271.278604 -50.119788)
		(width 0.1143)
		(layer "B.Cu")
		(net "UPI_CPU0_CPU1_P1P1_DN<1>")
	)
	(segment
		(start 273.67992 -49.37379)
		(end 273.479514 -49.073308)
		(width 0.1143)
		(layer "B.Cu")
		(net "UPI_CPU0_CPU1_P1P1_DN<1>")
	)
	(arc
		(start 140.224764 -56.799988)
		(mid 139.941547 -56.884269)
		(end 139.734544 -57.095136)
		(width 0.0889)
		(layer "B.Cu")
		(net "UPI_CPU0_CPU1_P1P1_DN<1>")
	)
	(arc
		(start 290.783518 -53.923184)
		(mid 290.98367 -54.123336)
		(end 290.783518 -54.323234)
		(width 0.0889)
		(layer "B.Cu")
		(net "UPI_CPU0_CPU1_P1P1_DN<1>")
	)
	(arc
		(start 139.734544 -57.095136)
		(mid 139.594465 -57.237872)
		(end 139.40282 -57.295034)
		(width 0.0889)
		(layer "B.Cu")
		(net "UPI_CPU0_CPU1_P1P1_DN<1>")
	)
	(arc
		(start 138.876024 -57.590436)
		(mid 138.734341 -57.73424)
		(end 138.54049 -57.790588)
		(width 0.0889)
		(layer "B.Cu")
		(net "UPI_CPU0_CPU1_P1P1_DN<1>")
	)
	(arc
		(start 138.017504 -58.085736)
		(mid 137.96636 -58.155536)
		(end 137.901426 -58.212736)
		(width 0.0889)
		(layer "B.Cu")
		(net "UPI_CPU0_CPU1_P1P1_DN<1>")
	)
	(arc
		(start 141.087094 -56.304434)
		(mid 140.80167 -56.387901)
		(end 140.593064 -56.599836)
		(width 0.0889)
		(layer "B.Cu")
		(net "UPI_CPU0_CPU1_P1P1_DN<1>")
	)
	(arc
		(start 139.370054 -57.295034)
		(mid 139.08463 -57.378501)
		(end 138.876024 -57.590436)
		(width 0.0889)
		(layer "B.Cu")
		(net "UPI_CPU0_CPU1_P1P1_DN<1>")
	)
	(arc
		(start 141.941804 -55.809388)
		(mid 141.658587 -55.893669)
		(end 141.451584 -56.104536)
		(width 0.0889)
		(layer "B.Cu")
		(net "UPI_CPU0_CPU1_P1P1_DN<1>")
	)
	(arc
		(start 137.901426 -58.212736)
		(mid 137.749716 -58.223037)
		(end 137.670794 -58.093102)
		(width 0.0889)
		(layer "B.Cu")
		(net "UPI_CPU0_CPU1_P1P1_DN<1>")
	)
	(arc
		(start 142.34668 -55.612538)
		(mid 142.256021 -55.7296)
		(end 142.131288 -55.809388)
		(width 0.0889)
		(layer "B.Cu")
		(net "UPI_CPU0_CPU1_P1P1_DN<1>")
	)
	(arc
		(start 140.593064 -56.599836)
		(mid 140.451381 -56.74364)
		(end 140.25753 -56.799988)
		(width 0.0889)
		(layer "B.Cu")
		(net "UPI_CPU0_CPU1_P1P1_DN<1>")
	)
	(arc
		(start 141.451584 -56.104536)
		(mid 141.311505 -56.247272)
		(end 141.11986 -56.304434)
		(width 0.0889)
		(layer "B.Cu")
		(net "UPI_CPU0_CPU1_P1P1_DN<1>")
	)
	(arc
		(start 138.507724 -57.790588)
		(mid 138.224507 -57.874869)
		(end 138.017504 -58.085736)
		(width 0.0889)
		(layer "B.Cu")
		(net "UPI_CPU0_CPU1_P1P1_DN<1>")
	)
	(segment
		(start 125.938788 -61.352938)
		(end 126.510288 -61.352938)
		(width 0.1143)
		(layer "F.Cu")
		(net "UPI_CPU0_CPU1_P1P1_DN<19>")
	)
	(segment
		(start 305.533806 -56.894984)
		(end 306.105306 -56.894984)
		(width 0.1143)
		(layer "F.Cu")
		(net "UPI_CPU0_CPU1_P1P1_DN<19>")
	)
	(via
		(at 126.510288 -61.352938)
		(size 0.508)
		(drill 0.254)
		(layers "F.Cu" "B.Cu")
		(net "UPI_CPU0_CPU1_P1P1_DN<19>")
	)
	(via
		(at 306.105306 -56.894984)
		(size 0.508)
		(drill 0.254)
		(layers "F.Cu" "B.Cu")
		(net "UPI_CPU0_CPU1_P1P1_DN<19>")
	)
	(segment
		(start 121.592848 -56.610504)
		(end 121.586498 -56.599836)
		(width 0.0889)
		(layer "B.Cu")
		(net "UPI_CPU0_CPU1_P1P1_DN<19>")
	)
	(segment
		(start 143.425164 -30.02788)
		(end 145.840958 -28.845764)
		(width 0.1143)
		(layer "B.Cu")
		(net "UPI_CPU0_CPU1_P1P1_DN<19>")
	)
	(segment
		(start 306.772564 -56.651398)
		(end 306.772564 -56.651652)
		(width 0.0889)
		(layer "B.Cu")
		(net "UPI_CPU0_CPU1_P1P1_DN<19>")
	)
	(segment
		(start 280.226516 -32.205676)
		(end 292.237668 -29.804106)
		(width 0.1143)
		(layer "B.Cu")
		(net "UPI_CPU0_CPU1_P1P1_DN<19>")
	)
	(segment
		(start 126.7841 -61.752988)
		(end 126.499112 -61.752988)
		(width 0.0889)
		(layer "B.Cu")
		(net "UPI_CPU0_CPU1_P1P1_DN<19>")
	)
	(segment
		(start 309.225696 -49.807368)
		(end 309.118254 -49.903126)
		(width 0.1143)
		(layer "B.Cu")
		(net "UPI_CPU0_CPU1_P1P1_DN<19>")
	)
	(segment
		(start 308.13629 -55.540402)
		(end 307.35778 -56.030368)
		(width 0.1143)
		(layer "B.Cu")
		(net "UPI_CPU0_CPU1_P1P1_DN<19>")
	)
	(segment
		(start 119.41175 -43.637962)
		(end 119.53113 -43.557698)
		(width 0.1143)
		(layer "B.Cu")
		(net "UPI_CPU0_CPU1_P1P1_DN<19>")
	)
	(segment
		(start 308.902608 -46.329346)
		(end 308.969918 -46.665896)
		(width 0.1143)
		(layer "B.Cu")
		(net "UPI_CPU0_CPU1_P1P1_DN<19>")
	)
	(segment
		(start 120.136158 -39.90975)
		(end 122.056652 -37.063426)
		(width 0.1143)
		(layer "B.Cu")
		(net "UPI_CPU0_CPU1_P1P1_DN<19>")
	)
	(segment
		(start 208.925922 -28.950412)
		(end 209.598514 -29.218128)
		(width 0.1143)
		(layer "B.Cu")
		(net "UPI_CPU0_CPU1_P1P1_DN<19>")
	)
	(segment
		(start 308.45887 -43.593766)
		(end 308.379368 -43.7134)
		(width 0.1143)
		(layer "B.Cu")
		(net "UPI_CPU0_CPU1_P1P1_DN<19>")
	)
	(segment
		(start 309.33136 -47.953676)
		(end 309.225696 -49.807368)
		(width 0.1143)
		(layer "B.Cu")
		(net "UPI_CPU0_CPU1_P1P1_DN<19>")
	)
	(segment
		(start 121.592848 -57.601104)
		(end 121.586498 -57.590436)
		(width 0.0889)
		(layer "B.Cu")
		(net "UPI_CPU0_CPU1_P1P1_DN<19>")
	)
	(segment
		(start 126.9746 -61.5442)
		(end 126.9746 -61.562488)
		(width 0.0889)
		(layer "B.Cu")
		(net "UPI_CPU0_CPU1_P1P1_DN<19>")
	)
	(segment
		(start 307.35778 -56.030368)
		(end 307.053234 -56.334914)
		(width 0.1143)
		(layer "B.Cu")
		(net "UPI_CPU0_CPU1_P1P1_DN<19>")
	)
	(segment
		(start 308.770528 -53.037486)
		(end 308.850284 -53.15712)
		(width 0.1143)
		(layer "B.Cu")
		(net "UPI_CPU0_CPU1_P1P1_DN<19>")
	)
	(segment
		(start 308.982364 -46.209712)
		(end 308.902608 -46.329346)
		(width 0.1143)
		(layer "B.Cu")
		(net "UPI_CPU0_CPU1_P1P1_DN<19>")
	)
	(segment
		(start 119.1768 -50.747422)
		(end 119.1768 -44.847256)
		(width 0.1143)
		(layer "B.Cu")
		(net "UPI_CPU0_CPU1_P1P1_DN<19>")
	)
	(segment
		(start 196.526404 -27.15641)
		(end 197.145148 -27.22499)
		(width 0.1143)
		(layer "B.Cu")
		(net "UPI_CPU0_CPU1_P1P1_DN<19>")
	)
	(segment
		(start 145.840958 -28.845764)
		(end 163.27501 -25.291034)
		(width 0.1143)
		(layer "B.Cu")
		(net "UPI_CPU0_CPU1_P1P1_DN<19>")
	)
	(segment
		(start 308.837838 -52.700936)
		(end 308.770528 -53.037486)
		(width 0.1143)
		(layer "B.Cu")
		(net "UPI_CPU0_CPU1_P1P1_DN<19>")
	)
	(segment
		(start 212.322918 -29.125418)
		(end 222.396812 -31.218124)
		(width 0.1143)
		(layer "B.Cu")
		(net "UPI_CPU0_CPU1_P1P1_DN<19>")
	)
	(segment
		(start 121.586498 -58.581036)
		(end 121.581672 -58.5724)
		(width 0.0889)
		(layer "B.Cu")
		(net "UPI_CPU0_CPU1_P1P1_DN<19>")
	)
	(segment
		(start 309.108094 -51.867562)
		(end 308.957472 -52.62118)
		(width 0.1143)
		(layer "B.Cu")
		(net "UPI_CPU0_CPU1_P1P1_DN<19>")
	)
	(segment
		(start 308.633368 -44.465748)
		(end 308.553612 -44.585382)
		(width 0.1143)
		(layer "B.Cu")
		(net "UPI_CPU0_CPU1_P1P1_DN<19>")
	)
	(segment
		(start 292.237668 -29.804106)
		(end 298.670472 -31.090108)
		(width 0.1143)
		(layer "B.Cu")
		(net "UPI_CPU0_CPU1_P1P1_DN<19>")
	)
	(segment
		(start 307.6956 -39.775384)
		(end 308.284372 -42.721784)
		(width 0.1143)
		(layer "B.Cu")
		(net "UPI_CPU0_CPU1_P1P1_DN<19>")
	)
	(segment
		(start 306.620164 -56.804052)
		(end 306.452016 -57.095136)
		(width 0.0889)
		(layer "B.Cu")
		(net "UPI_CPU0_CPU1_P1P1_DN<19>")
	)
	(segment
		(start 120.727978 -54.123336)
		(end 119.1514 -50.994564)
		(width 0.0889)
		(layer "B.Cu")
		(net "UPI_CPU0_CPU1_P1P1_DN<19>")
	)
	(segment
		(start 307.293518 -37.76345)
		(end 307.6956 -39.775384)
		(width 0.1143)
		(layer "B.Cu")
		(net "UPI_CPU0_CPU1_P1P1_DN<19>")
	)
	(segment
		(start 249.631708 -27.877262)
		(end 254.339344 -27.028394)
		(width 0.1143)
		(layer "B.Cu")
		(net "UPI_CPU0_CPU1_P1P1_DN<19>")
	)
	(segment
		(start 308.489096 -54.4449)
		(end 308.421786 -54.78145)
		(width 0.1143)
		(layer "B.Cu")
		(net "UPI_CPU0_CPU1_P1P1_DN<19>")
	)
	(segment
		(start 128.057148 -33.015174)
		(end 143.425164 -30.02788)
		(width 0.1143)
		(layer "B.Cu")
		(net "UPI_CPU0_CPU1_P1P1_DN<19>")
	)
	(segment
		(start 119.596408 -43.220894)
		(end 119.516144 -43.101768)
		(width 0.1143)
		(layer "B.Cu")
		(net "UPI_CPU0_CPU1_P1P1_DN<19>")
	)
	(segment
		(start 308.608984 -54.365144)
		(end 308.489096 -54.4449)
		(width 0.1143)
		(layer "B.Cu")
		(net "UPI_CPU0_CPU1_P1P1_DN<19>")
	)
	(segment
		(start 309.04815 -51.133502)
		(end 309.143654 -51.24069)
		(width 0.1143)
		(layer "B.Cu")
		(net "UPI_CPU0_CPU1_P1P1_DN<19>")
	)
	(segment
		(start 308.957472 -52.62118)
		(end 308.837838 -52.700936)
		(width 0.1143)
		(layer "B.Cu")
		(net "UPI_CPU0_CPU1_P1P1_DN<19>")
	)
	(segment
		(start 119.1514 -50.79492)
		(end 119.1768 -50.747422)
		(width 0.0889)
		(layer "B.Cu")
		(net "UPI_CPU0_CPU1_P1P1_DN<19>")
	)
	(segment
		(start 308.391814 -43.257724)
		(end 308.45887 -43.593766)
		(width 0.1143)
		(layer "B.Cu")
		(net "UPI_CPU0_CPU1_P1P1_DN<19>")
	)
	(segment
		(start 126.510288 -61.352938)
		(end 126.783338 -61.352938)
		(width 0.0889)
		(layer "B.Cu")
		(net "UPI_CPU0_CPU1_P1P1_DN<19>")
	)
	(segment
		(start 236.883956 -29.604462)
		(end 238.93907 -30.015688)
		(width 0.1143)
		(layer "B.Cu")
		(net "UPI_CPU0_CPU1_P1P1_DN<19>")
	)
	(segment
		(start 309.194454 -50.35296)
		(end 309.17515 -50.695098)
		(width 0.1143)
		(layer "B.Cu")
		(net "UPI_CPU0_CPU1_P1P1_DN<19>")
	)
	(segment
		(start 308.663594 -53.572918)
		(end 308.596284 -53.909468)
		(width 0.1143)
		(layer "B.Cu")
		(net "UPI_CPU0_CPU1_P1P1_DN<19>")
	)
	(segment
		(start 197.145148 -27.22499)
		(end 208.265776 -28.71089)
		(width 0.1143)
		(layer "B.Cu")
		(net "UPI_CPU0_CPU1_P1P1_DN<19>")
	)
	(segment
		(start 121.586498 -55.609236)
		(end 121.581672 -55.6006)
		(width 0.0889)
		(layer "B.Cu")
		(net "UPI_CPU0_CPU1_P1P1_DN<19>")
	)
	(segment
		(start 189.626494 -25.314656)
		(end 191.461136 -27.054302)
		(width 0.1143)
		(layer "B.Cu")
		(net "UPI_CPU0_CPU1_P1P1_DN<19>")
	)
	(segment
		(start 308.379368 -43.7134)
		(end 308.446424 -44.04995)
		(width 0.1143)
		(layer "B.Cu")
		(net "UPI_CPU0_CPU1_P1P1_DN<19>")
	)
	(segment
		(start 122.056906 -37.063426)
		(end 128.057148 -33.015174)
		(width 0.1143)
		(layer "B.Cu")
		(net "UPI_CPU0_CPU1_P1P1_DN<19>")
	)
	(segment
		(start 244.874034 -28.828746)
		(end 249.631708 -27.877262)
		(width 0.1143)
		(layer "B.Cu")
		(net "UPI_CPU0_CPU1_P1P1_DN<19>")
	)
	(segment
		(start 225.544126 -31.87192)
		(end 236.883956 -29.604462)
		(width 0.1143)
		(layer "B.Cu")
		(net "UPI_CPU0_CPU1_P1P1_DN<19>")
	)
	(segment
		(start 124.853954 -61.257434)
		(end 124.358908 -60.762388)
		(width 0.0889)
		(layer "B.Cu")
		(net "UPI_CPU0_CPU1_P1P1_DN<19>")
	)
	(segment
		(start 186.652154 -25.166574)
		(end 189.626494 -25.314656)
		(width 0.1143)
		(layer "B.Cu")
		(net "UPI_CPU0_CPU1_P1P1_DN<19>")
	)
	(segment
		(start 191.461136 -27.054302)
		(end 196.526404 -27.15641)
		(width 0.1143)
		(layer "B.Cu")
		(net "UPI_CPU0_CPU1_P1P1_DN<19>")
	)
	(segment
		(start 181.380892 -23.718774)
		(end 186.652154 -25.166574)
		(width 0.1143)
		(layer "B.Cu")
		(net "UPI_CPU0_CPU1_P1P1_DN<19>")
	)
	(segment
		(start 254.339344 -27.028394)
		(end 263.341358 -28.828746)
		(width 0.1143)
		(layer "B.Cu")
		(net "UPI_CPU0_CPU1_P1P1_DN<19>")
	)
	(segment
		(start 309.144416 -47.537878)
		(end 309.264304 -47.617634)
		(width 0.1143)
		(layer "B.Cu")
		(net "UPI_CPU0_CPU1_P1P1_DN<19>")
	)
	(segment
		(start 308.271926 -43.177968)
		(end 308.391814 -43.257724)
		(width 0.1143)
		(layer "B.Cu")
		(net "UPI_CPU0_CPU1_P1P1_DN<19>")
	)
	(segment
		(start 125.669548 -61.257434)
		(end 124.853954 -61.257434)
		(width 0.0889)
		(layer "B.Cu")
		(net "UPI_CPU0_CPU1_P1P1_DN<19>")
	)
	(segment
		(start 308.566312 -44.129706)
		(end 308.633368 -44.465748)
		(width 0.1143)
		(layer "B.Cu")
		(net "UPI_CPU0_CPU1_P1P1_DN<19>")
	)
	(segment
		(start 308.79542 -45.793914)
		(end 308.915308 -45.87367)
		(width 0.1143)
		(layer "B.Cu")
		(net "UPI_CPU0_CPU1_P1P1_DN<19>")
	)
	(segment
		(start 309.156862 -47.081694)
		(end 309.077106 -47.201328)
		(width 0.1143)
		(layer "B.Cu")
		(net "UPI_CPU0_CPU1_P1P1_DN<19>")
	)
	(segment
		(start 176.551844 -24.265636)
		(end 179.734718 -23.832312)
		(width 0.1143)
		(layer "B.Cu")
		(net "UPI_CPU0_CPU1_P1P1_DN<19>")
	)
	(segment
		(start 163.27501 -25.291034)
		(end 166.455598 -24.737314)
		(width 0.1143)
		(layer "B.Cu")
		(net "UPI_CPU0_CPU1_P1P1_DN<19>")
	)
	(segment
		(start 308.807866 -45.33773)
		(end 308.72811 -45.457364)
		(width 0.1143)
		(layer "B.Cu")
		(net "UPI_CPU0_CPU1_P1P1_DN<19>")
	)
	(segment
		(start 309.098696 -50.245518)
		(end 309.194454 -50.35296)
		(width 0.1143)
		(layer "B.Cu")
		(net "UPI_CPU0_CPU1_P1P1_DN<19>")
	)
	(segment
		(start 119.516144 -43.101768)
		(end 120.136158 -39.90975)
		(width 0.1143)
		(layer "B.Cu")
		(net "UPI_CPU0_CPU1_P1P1_DN<19>")
	)
	(segment
		(start 309.089806 -46.745652)
		(end 309.156862 -47.081694)
		(width 0.1143)
		(layer "B.Cu")
		(net "UPI_CPU0_CPU1_P1P1_DN<19>")
	)
	(segment
		(start 306.163218 -57.29097)
		(end 306.105306 -57.233058)
		(width 0.0889)
		(layer "B.Cu")
		(net "UPI_CPU0_CPU1_P1P1_DN<19>")
	)
	(segment
		(start 309.067708 -50.790856)
		(end 309.04815 -51.133502)
		(width 0.1143)
		(layer "B.Cu")
		(net "UPI_CPU0_CPU1_P1P1_DN<19>")
	)
	(segment
		(start 179.734718 -23.832312)
		(end 180.15204 -23.753318)
		(width 0.1143)
		(layer "B.Cu")
		(net "UPI_CPU0_CPU1_P1P1_DN<19>")
	)
	(segment
		(start 308.553612 -44.585382)
		(end 308.620922 -44.921932)
		(width 0.1143)
		(layer "B.Cu")
		(net "UPI_CPU0_CPU1_P1P1_DN<19>")
	)
	(segment
		(start 124.358908 -60.762388)
		(end 123.639072 -60.762388)
		(width 0.0889)
		(layer "B.Cu")
		(net "UPI_CPU0_CPU1_P1P1_DN<19>")
	)
	(segment
		(start 308.446424 -44.04995)
		(end 308.566312 -44.129706)
		(width 0.1143)
		(layer "B.Cu")
		(net "UPI_CPU0_CPU1_P1P1_DN<19>")
	)
	(segment
		(start 306.925726 -56.49849)
		(end 306.925472 -56.49849)
		(width 0.0889)
		(layer "B.Cu")
		(net "UPI_CPU0_CPU1_P1P1_DN<19>")
	)
	(segment
		(start 298.670472 -31.090108)
		(end 307.293518 -37.76345)
		(width 0.1143)
		(layer "B.Cu")
		(net "UPI_CPU0_CPU1_P1P1_DN<19>")
	)
	(segment
		(start 308.284372 -42.721784)
		(end 308.20487 -42.841418)
		(width 0.1143)
		(layer "B.Cu")
		(net "UPI_CPU0_CPU1_P1P1_DN<19>")
	)
	(segment
		(start 309.077106 -47.201328)
		(end 309.144416 -47.537878)
		(width 0.1143)
		(layer "B.Cu")
		(net "UPI_CPU0_CPU1_P1P1_DN<19>")
	)
	(segment
		(start 308.74081 -45.001688)
		(end 308.807866 -45.33773)
		(width 0.1143)
		(layer "B.Cu")
		(net "UPI_CPU0_CPU1_P1P1_DN<19>")
	)
	(segment
		(start 121.586498 -59.171586)
		(end 121.592848 -59.160918)
		(width 0.0889)
		(layer "B.Cu")
		(net "UPI_CPU0_CPU1_P1P1_DN<19>")
	)
	(segment
		(start 308.969918 -46.665896)
		(end 309.089806 -46.745652)
		(width 0.1143)
		(layer "B.Cu")
		(net "UPI_CPU0_CPU1_P1P1_DN<19>")
	)
	(segment
		(start 307.053234 -56.334914)
		(end 307.03774 -56.386476)
		(width 0.0889)
		(layer "B.Cu")
		(net "UPI_CPU0_CPU1_P1P1_DN<19>")
	)
	(segment
		(start 308.72811 -45.457364)
		(end 308.79542 -45.793914)
		(width 0.1143)
		(layer "B.Cu")
		(net "UPI_CPU0_CPU1_P1P1_DN<19>")
	)
	(segment
		(start 222.396812 -31.218124)
		(end 225.544126 -31.87192)
		(width 0.1143)
		(layer "B.Cu")
		(net "UPI_CPU0_CPU1_P1P1_DN<19>")
	)
	(segment
		(start 309.118254 -49.903126)
		(end 309.098696 -50.245518)
		(width 0.1143)
		(layer "B.Cu")
		(net "UPI_CPU0_CPU1_P1P1_DN<19>")
	)
	(segment
		(start 122.809508 -60.266834)
		(end 122.776742 -60.266834)
		(width 0.0889)
		(layer "B.Cu")
		(net "UPI_CPU0_CPU1_P1P1_DN<19>")
	)
	(segment
		(start 119.1768 -44.847256)
		(end 119.41175 -43.637962)
		(width 0.1143)
		(layer "B.Cu")
		(net "UPI_CPU0_CPU1_P1P1_DN<19>")
	)
	(segment
		(start 166.455598 -24.737314)
		(end 170.643042 -25.551638)
		(width 0.1143)
		(layer "B.Cu")
		(net "UPI_CPU0_CPU1_P1P1_DN<19>")
	)
	(segment
		(start 122.056652 -37.063426)
		(end 122.056906 -37.063426)
		(width 0.1143)
		(layer "B.Cu")
		(net "UPI_CPU0_CPU1_P1P1_DN<19>")
	)
	(segment
		(start 121.586498 -56.599836)
		(end 121.581672 -56.5912)
		(width 0.0889)
		(layer "B.Cu")
		(net "UPI_CPU0_CPU1_P1P1_DN<19>")
	)
	(segment
		(start 121.092468 -54.323234)
		(end 121.057162 -54.323234)
		(width 0.0889)
		(layer "B.Cu")
		(net "UPI_CPU0_CPU1_P1P1_DN<19>")
	)
	(segment
		(start 211.77123 -29.030422)
		(end 212.322918 -29.125418)
		(width 0.1143)
		(layer "B.Cu")
		(net "UPI_CPU0_CPU1_P1P1_DN<19>")
	)
	(segment
		(start 238.93907 -30.015688)
		(end 244.874034 -28.828746)
		(width 0.1143)
		(layer "B.Cu")
		(net "UPI_CPU0_CPU1_P1P1_DN<19>")
	)
	(segment
		(start 308.434486 -55.237126)
		(end 308.13629 -55.540402)
		(width 0.1143)
		(layer "B.Cu")
		(net "UPI_CPU0_CPU1_P1P1_DN<19>")
	)
	(segment
		(start 119.53113 -43.557698)
		(end 119.596408 -43.220894)
		(width 0.1143)
		(layer "B.Cu")
		(net "UPI_CPU0_CPU1_P1P1_DN<19>")
	)
	(segment
		(start 263.341358 -28.828746)
		(end 280.226516 -32.205676)
		(width 0.1143)
		(layer "B.Cu")
		(net "UPI_CPU0_CPU1_P1P1_DN<19>")
	)
	(segment
		(start 308.421786 -54.78145)
		(end 308.501542 -54.901084)
		(width 0.1143)
		(layer "B.Cu")
		(net "UPI_CPU0_CPU1_P1P1_DN<19>")
	)
	(segment
		(start 306.105306 -57.233058)
		(end 306.105306 -56.894984)
		(width 0.0889)
		(layer "B.Cu")
		(net "UPI_CPU0_CPU1_P1P1_DN<19>")
	)
	(segment
		(start 174.326042 -24.854408)
		(end 176.551844 -24.265636)
		(width 0.1143)
		(layer "B.Cu")
		(net "UPI_CPU0_CPU1_P1P1_DN<19>")
	)
	(segment
		(start 309.264304 -47.617634)
		(end 309.33136 -47.953676)
		(width 0.1143)
		(layer "B.Cu")
		(net "UPI_CPU0_CPU1_P1P1_DN<19>")
	)
	(segment
		(start 121.586498 -57.590436)
		(end 121.581672 -57.5818)
		(width 0.0889)
		(layer "B.Cu")
		(net "UPI_CPU0_CPU1_P1P1_DN<19>")
	)
	(segment
		(start 121.946162 -59.771534)
		(end 121.922032 -59.771534)
		(width 0.0889)
		(layer "B.Cu")
		(net "UPI_CPU0_CPU1_P1P1_DN<19>")
	)
	(segment
		(start 308.20487 -42.841418)
		(end 308.271926 -43.177968)
		(width 0.1143)
		(layer "B.Cu")
		(net "UPI_CPU0_CPU1_P1P1_DN<19>")
	)
	(segment
		(start 208.265776 -28.71089)
		(end 208.925922 -28.950412)
		(width 0.1143)
		(layer "B.Cu")
		(net "UPI_CPU0_CPU1_P1P1_DN<19>")
	)
	(segment
		(start 308.596284 -53.909468)
		(end 308.67604 -54.029102)
		(width 0.1143)
		(layer "B.Cu")
		(net "UPI_CPU0_CPU1_P1P1_DN<19>")
	)
	(segment
		(start 308.620922 -44.921932)
		(end 308.74081 -45.001688)
		(width 0.1143)
		(layer "B.Cu")
		(net "UPI_CPU0_CPU1_P1P1_DN<19>")
	)
	(segment
		(start 308.67604 -54.029102)
		(end 308.608984 -54.365144)
		(width 0.1143)
		(layer "B.Cu")
		(net "UPI_CPU0_CPU1_P1P1_DN<19>")
	)
	(segment
		(start 209.598514 -29.218128)
		(end 211.77123 -29.030422)
		(width 0.1143)
		(layer "B.Cu")
		(net "UPI_CPU0_CPU1_P1P1_DN<19>")
	)
	(segment
		(start 119.1514 -50.994564)
		(end 119.1514 -50.79492)
		(width 0.0889)
		(layer "B.Cu")
		(net "UPI_CPU0_CPU1_P1P1_DN<19>")
	)
	(segment
		(start 308.850284 -53.15712)
		(end 308.783228 -53.493162)
		(width 0.1143)
		(layer "B.Cu")
		(net "UPI_CPU0_CPU1_P1P1_DN<19>")
	)
	(segment
		(start 308.501542 -54.901084)
		(end 308.434486 -55.237126)
		(width 0.1143)
		(layer "B.Cu")
		(net "UPI_CPU0_CPU1_P1P1_DN<19>")
	)
	(segment
		(start 306.925472 -56.49849)
		(end 306.772564 -56.651398)
		(width 0.0889)
		(layer "B.Cu")
		(net "UPI_CPU0_CPU1_P1P1_DN<19>")
	)
	(segment
		(start 309.143654 -51.24069)
		(end 309.108094 -51.867562)
		(width 0.1143)
		(layer "B.Cu")
		(net "UPI_CPU0_CPU1_P1P1_DN<19>")
	)
	(segment
		(start 180.15204 -23.753318)
		(end 181.380892 -23.718774)
		(width 0.1143)
		(layer "B.Cu")
		(net "UPI_CPU0_CPU1_P1P1_DN<19>")
	)
	(segment
		(start 170.643042 -25.551638)
		(end 174.326042 -24.854408)
		(width 0.1143)
		(layer "B.Cu")
		(net "UPI_CPU0_CPU1_P1P1_DN<19>")
	)
	(segment
		(start 306.772564 -56.651652)
		(end 306.620164 -56.804052)
		(width 0.0889)
		(layer "B.Cu")
		(net "UPI_CPU0_CPU1_P1P1_DN<19>")
	)
	(segment
		(start 309.17515 -50.695098)
		(end 309.067708 -50.790856)
		(width 0.1143)
		(layer "B.Cu")
		(net "UPI_CPU0_CPU1_P1P1_DN<19>")
	)
	(segment
		(start 308.915308 -45.87367)
		(end 308.982364 -46.209712)
		(width 0.1143)
		(layer "B.Cu")
		(net "UPI_CPU0_CPU1_P1P1_DN<19>")
	)
	(segment
		(start 308.783228 -53.493162)
		(end 308.663594 -53.572918)
		(width 0.1143)
		(layer "B.Cu")
		(net "UPI_CPU0_CPU1_P1P1_DN<19>")
	)
	(segment
		(start 121.592848 -55.619904)
		(end 121.586498 -55.609236)
		(width 0.0889)
		(layer "B.Cu")
		(net "UPI_CPU0_CPU1_P1P1_DN<19>")
	)
	(segment
		(start 307.03774 -56.386476)
		(end 306.925726 -56.49849)
		(width 0.0889)
		(layer "B.Cu")
		(net "UPI_CPU0_CPU1_P1P1_DN<19>")
	)
	(arc
		(start 121.057162 -54.323234)
		(mid 120.86692 -54.265499)
		(end 120.727978 -54.123336)
		(width 0.0889)
		(layer "B.Cu")
		(net "UPI_CPU0_CPU1_P1P1_DN<19>")
	)
	(arc
		(start 121.592848 -59.160918)
		(mid 121.665646 -58.870155)
		(end 121.586498 -58.581036)
		(width 0.0889)
		(layer "B.Cu")
		(net "UPI_CPU0_CPU1_P1P1_DN<19>")
	)
	(arc
		(start 123.303538 -60.562236)
		(mid 123.09493 -60.350304)
		(end 122.809508 -60.266834)
		(width 0.0889)
		(layer "B.Cu")
		(net "UPI_CPU0_CPU1_P1P1_DN<19>")
	)
	(arc
		(start 126.9746 -61.562488)
		(mid 126.947828 -61.659871)
		(end 126.875032 -61.729874)
		(width 0.0889)
		(layer "B.Cu")
		(net "UPI_CPU0_CPU1_P1P1_DN<19>")
	)
	(arc
		(start 306.452016 -57.095136)
		(mid 306.39849 -57.167586)
		(end 306.330096 -57.2262)
		(width 0.0889)
		(layer "B.Cu")
		(net "UPI_CPU0_CPU1_P1P1_DN<19>")
	)
	(arc
		(start 126.783338 -61.352938)
		(mid 126.918581 -61.408957)
		(end 126.9746 -61.5442)
		(width 0.0889)
		(layer "B.Cu")
		(net "UPI_CPU0_CPU1_P1P1_DN<19>")
	)
	(arc
		(start 121.922032 -59.771534)
		(mid 121.583917 -59.566832)
		(end 121.586498 -59.171586)
		(width 0.0889)
		(layer "B.Cu")
		(net "UPI_CPU0_CPU1_P1P1_DN<19>")
	)
	(arc
		(start 121.581672 -57.5818)
		(mid 121.532917 -57.385448)
		(end 121.586498 -57.190386)
		(width 0.0889)
		(layer "B.Cu")
		(net "UPI_CPU0_CPU1_P1P1_DN<19>")
	)
	(arc
		(start 121.581672 -56.5912)
		(mid 121.532917 -56.394848)
		(end 121.586498 -56.199786)
		(width 0.0889)
		(layer "B.Cu")
		(net "UPI_CPU0_CPU1_P1P1_DN<19>")
	)
	(arc
		(start 121.586498 -55.209186)
		(mid 121.590827 -54.626014)
		(end 121.092468 -54.323234)
		(width 0.0889)
		(layer "B.Cu")
		(net "UPI_CPU0_CPU1_P1P1_DN<19>")
	)
	(arc
		(start 121.586498 -57.190386)
		(mid 121.66572 -56.901268)
		(end 121.592848 -56.610504)
		(width 0.0889)
		(layer "B.Cu")
		(net "UPI_CPU0_CPU1_P1P1_DN<19>")
	)
	(arc
		(start 126.499112 -61.752988)
		(mid 126.305262 -61.696638)
		(end 126.163578 -61.552836)
		(width 0.0889)
		(layer "B.Cu")
		(net "UPI_CPU0_CPU1_P1P1_DN<19>")
	)
	(arc
		(start 122.776742 -60.266834)
		(mid 122.5851 -60.209668)
		(end 122.445018 -60.066936)
		(width 0.0889)
		(layer "B.Cu")
		(net "UPI_CPU0_CPU1_P1P1_DN<19>")
	)
	(arc
		(start 121.586498 -56.199786)
		(mid 121.66572 -55.910668)
		(end 121.592848 -55.619904)
		(width 0.0889)
		(layer "B.Cu")
		(net "UPI_CPU0_CPU1_P1P1_DN<19>")
	)
	(arc
		(start 122.445018 -60.066936)
		(mid 122.234305 -59.853857)
		(end 121.946162 -59.771534)
		(width 0.0889)
		(layer "B.Cu")
		(net "UPI_CPU0_CPU1_P1P1_DN<19>")
	)
	(arc
		(start 121.581672 -55.6006)
		(mid 121.532917 -55.404248)
		(end 121.586498 -55.209186)
		(width 0.0889)
		(layer "B.Cu")
		(net "UPI_CPU0_CPU1_P1P1_DN<19>")
	)
	(arc
		(start 121.586498 -58.180986)
		(mid 121.66572 -57.891868)
		(end 121.592848 -57.601104)
		(width 0.0889)
		(layer "B.Cu")
		(net "UPI_CPU0_CPU1_P1P1_DN<19>")
	)
	(arc
		(start 121.581672 -58.5724)
		(mid 121.532917 -58.376048)
		(end 121.586498 -58.180986)
		(width 0.0889)
		(layer "B.Cu")
		(net "UPI_CPU0_CPU1_P1P1_DN<19>")
	)
	(arc
		(start 306.330096 -57.2262)
		(mid 306.250324 -57.268031)
		(end 306.163218 -57.29097)
		(width 0.0889)
		(layer "B.Cu")
		(net "UPI_CPU0_CPU1_P1P1_DN<19>")
	)
	(arc
		(start 126.163578 -61.552836)
		(mid 125.95497 -61.340904)
		(end 125.669548 -61.257434)
		(width 0.0889)
		(layer "B.Cu")
		(net "UPI_CPU0_CPU1_P1P1_DN<19>")
	)
	(arc
		(start 126.875032 -61.729874)
		(mid 126.831011 -61.747112)
		(end 126.7841 -61.752988)
		(width 0.0889)
		(layer "B.Cu")
		(net "UPI_CPU0_CPU1_P1P1_DN<19>")
	)
	(arc
		(start 123.639072 -60.762388)
		(mid 123.445222 -60.706038)
		(end 123.303538 -60.562236)
		(width 0.0889)
		(layer "B.Cu")
		(net "UPI_CPU0_CPU1_P1P1_DN<19>")
	)
	(segment
		(start 304.675286 -56.399938)
		(end 305.246786 -56.399938)
		(width 0.1143)
		(layer "F.Cu")
		(net "UPI_CPU0_CPU1_P1P1_DN<18>")
	)
	(segment
		(start 125.938788 -60.362338)
		(end 126.510288 -60.362338)
		(width 0.1143)
		(layer "F.Cu")
		(net "UPI_CPU0_CPU1_P1P1_DN<18>")
	)
	(via
		(at 127.860806 -34.57575)
		(size 0.508)
		(drill 0.254)
		(layers "F.Cu" "B.Cu")
		(net "UPI_CPU0_CPU1_P1P1_DN<18>")
	)
	(via
		(at 305.246786 -56.399938)
		(size 0.508)
		(drill 0.254)
		(layers "F.Cu" "B.Cu")
		(net "UPI_CPU0_CPU1_P1P1_DN<18>")
	)
	(via
		(at 126.510288 -60.362338)
		(size 0.508)
		(drill 0.254)
		(layers "F.Cu" "B.Cu")
		(net "UPI_CPU0_CPU1_P1P1_DN<18>")
	)
	(segment
		(start 120.43156 -47.709582)
		(end 120.43156 -48.052482)
		(width 0.1143)
		(layer "B.Cu")
		(net "UPI_CPU0_CPU1_P1P1_DN<18>")
	)
	(segment
		(start 307.435504 -45.323506)
		(end 307.497734 -45.660818)
		(width 0.1143)
		(layer "B.Cu")
		(net "UPI_CPU0_CPU1_P1P1_DN<18>")
	)
	(segment
		(start 122.445018 -54.713886)
		(end 122.440192 -54.722522)
		(width 0.0889)
		(layer "B.Cu")
		(net "UPI_CPU0_CPU1_P1P1_DN<18>")
	)
	(segment
		(start 120.43156 -48.052482)
		(end 120.32996 -48.154082)
		(width 0.1143)
		(layer "B.Cu")
		(net "UPI_CPU0_CPU1_P1P1_DN<18>")
	)
	(segment
		(start 120.43156 -48.598582)
		(end 120.43156 -48.941482)
		(width 0.1143)
		(layer "B.Cu")
		(net "UPI_CPU0_CPU1_P1P1_DN<18>")
	)
	(segment
		(start 307.33619 -44.78655)
		(end 307.454808 -44.868084)
		(width 0.1143)
		(layer "B.Cu")
		(net "UPI_CPU0_CPU1_P1P1_DN<18>")
	)
	(segment
		(start 307.678582 -46.07941)
		(end 307.597048 -46.197774)
		(width 0.1143)
		(layer "B.Cu")
		(net "UPI_CPU0_CPU1_P1P1_DN<18>")
	)
	(segment
		(start 208.487264 -29.75737)
		(end 209.296 -30.053788)
		(width 0.1143)
		(layer "B.Cu")
		(net "UPI_CPU0_CPU1_P1P1_DN<18>")
	)
	(segment
		(start 308.1528 -48.64481)
		(end 308.134512 -49.115472)
		(width 0.1143)
		(layer "B.Cu")
		(net "UPI_CPU0_CPU1_P1P1_DN<18>")
	)
	(segment
		(start 307.820822 -47.409354)
		(end 307.93944 -47.490888)
		(width 0.1143)
		(layer "B.Cu")
		(net "UPI_CPU0_CPU1_P1P1_DN<18>")
	)
	(segment
		(start 252.694694 -28.570174)
		(end 254.533146 -28.074874)
		(width 0.1143)
		(layer "B.Cu")
		(net "UPI_CPU0_CPU1_P1P1_DN<18>")
	)
	(segment
		(start 209.296 -30.053788)
		(end 209.593688 -30.162754)
		(width 0.1143)
		(layer "B.Cu")
		(net "UPI_CPU0_CPU1_P1P1_DN<18>")
	)
	(segment
		(start 152.328118 -29.177996)
		(end 154.983434 -29.422598)
		(width 0.1143)
		(layer "B.Cu")
		(net "UPI_CPU0_CPU1_P1P1_DN<18>")
	)
	(segment
		(start 120.32996 -46.718982)
		(end 120.43156 -46.820582)
		(width 0.1143)
		(layer "B.Cu")
		(net "UPI_CPU0_CPU1_P1P1_DN<18>")
	)
	(segment
		(start 126.217172 -60.531248)
		(end 126.510288 -60.362338)
		(width 0.0889)
		(layer "B.Cu")
		(net "UPI_CPU0_CPU1_P1P1_DN<18>")
	)
	(segment
		(start 211.881466 -30.071822)
		(end 222.396812 -32.281622)
		(width 0.1143)
		(layer "B.Cu")
		(net "UPI_CPU0_CPU1_P1P1_DN<18>")
	)
	(segment
		(start 291.96538 -30.7975)
		(end 298.315126 -32.209994)
		(width 0.1143)
		(layer "B.Cu")
		(net "UPI_CPU0_CPU1_P1P1_DN<18>")
	)
	(segment
		(start 305.844956 -55.17388)
		(end 305.5874 -55.61965)
		(width 0.0889)
		(layer "B.Cu")
		(net "UPI_CPU0_CPU1_P1P1_DN<18>")
	)
	(segment
		(start 307.93944 -47.490888)
		(end 308.00167 -47.827946)
		(width 0.1143)
		(layer "B.Cu")
		(net "UPI_CPU0_CPU1_P1P1_DN<18>")
	)
	(segment
		(start 123.639072 -59.771534)
		(end 124.273818 -59.771534)
		(width 0.0889)
		(layer "B.Cu")
		(net "UPI_CPU0_CPU1_P1P1_DN<18>")
	)
	(segment
		(start 122.451368 -55.693818)
		(end 122.445018 -55.704486)
		(width 0.0889)
		(layer "B.Cu")
		(net "UPI_CPU0_CPU1_P1P1_DN<18>")
	)
	(segment
		(start 236.876082 -30.62224)
		(end 238.901732 -31.02737)
		(width 0.1143)
		(layer "B.Cu")
		(net "UPI_CPU0_CPU1_P1P1_DN<18>")
	)
	(segment
		(start 122.773694 -59.276234)
		(end 122.813318 -59.276234)
		(width 0.0889)
		(layer "B.Cu")
		(net "UPI_CPU0_CPU1_P1P1_DN<18>")
	)
	(segment
		(start 289.087052 -31.44012)
		(end 291.96538 -30.7975)
		(width 0.1143)
		(layer "B.Cu")
		(net "UPI_CPU0_CPU1_P1P1_DN<18>")
	)
	(segment
		(start 127.860806 -34.57575)
		(end 128.602486 -34.075624)
		(width 0.1143)
		(layer "B.Cu")
		(net "UPI_CPU0_CPU1_P1P1_DN<18>")
	)
	(segment
		(start 307.517038 -45.205142)
		(end 307.435504 -45.323506)
		(width 0.1143)
		(layer "B.Cu")
		(net "UPI_CPU0_CPU1_P1P1_DN<18>")
	)
	(segment
		(start 305.845464 -55.17261)
		(end 305.844956 -55.17388)
		(width 0.0889)
		(layer "B.Cu")
		(net "UPI_CPU0_CPU1_P1P1_DN<18>")
	)
	(segment
		(start 238.901732 -31.02737)
		(end 250.78182 -28.651454)
		(width 0.1143)
		(layer "B.Cu")
		(net "UPI_CPU0_CPU1_P1P1_DN<18>")
	)
	(segment
		(start 307.920136 -47.94631)
		(end 307.982366 -48.283622)
		(width 0.1143)
		(layer "B.Cu")
		(net "UPI_CPU0_CPU1_P1P1_DN<18>")
	)
	(segment
		(start 120.30456 -50.32248)
		(end 120.30456 -50.758344)
		(width 0.0889)
		(layer "B.Cu")
		(net "UPI_CPU0_CPU1_P1P1_DN<18>")
	)
	(segment
		(start 307.659278 -46.535086)
		(end 307.6956 -46.559978)
		(width 0.1143)
		(layer "B.Cu")
		(net "UPI_CPU0_CPU1_P1P1_DN<18>")
	)
	(segment
		(start 127.860806 -34.57575)
		(end 127.557784 -34.779966)
		(width 0.1143)
		(layer "B.Cu")
		(net "UPI_CPU0_CPU1_P1P1_DN<18>")
	)
	(segment
		(start 166.888414 -26.02611)
		(end 170.963336 -26.840688)
		(width 0.1143)
		(layer "B.Cu")
		(net "UPI_CPU0_CPU1_P1P1_DN<18>")
	)
	(segment
		(start 306.953158 -52.948078)
		(end 306.84343 -53.199538)
		(width 0.0889)
		(layer "B.Cu")
		(net "UPI_CPU0_CPU1_P1P1_DN<18>")
	)
	(segment
		(start 307.597048 -46.197774)
		(end 307.659278 -46.535086)
		(width 0.1143)
		(layer "B.Cu")
		(net "UPI_CPU0_CPU1_P1P1_DN<18>")
	)
	(segment
		(start 120.43156 -49.830482)
		(end 120.32996 -49.932082)
		(width 0.1143)
		(layer "B.Cu")
		(net "UPI_CPU0_CPU1_P1P1_DN<18>")
	)
	(segment
		(start 127.557784 -34.779966)
		(end 122.795284 -37.992558)
		(width 0.1143)
		(layer "B.Cu")
		(net "UPI_CPU0_CPU1_P1P1_DN<18>")
	)
	(segment
		(start 120.43156 -47.163482)
		(end 120.32996 -47.265082)
		(width 0.1143)
		(layer "B.Cu")
		(net "UPI_CPU0_CPU1_P1P1_DN<18>")
	)
	(segment
		(start 121.54662 -39.84371)
		(end 120.330214 -46.102778)
		(width 0.1143)
		(layer "B.Cu")
		(net "UPI_CPU0_CPU1_P1P1_DN<18>")
	)
	(segment
		(start 307.27396 -44.449238)
		(end 307.33619 -44.78655)
		(width 0.1143)
		(layer "B.Cu")
		(net "UPI_CPU0_CPU1_P1P1_DN<18>")
	)
	(segment
		(start 124.273818 -59.771534)
		(end 124.769118 -60.266834)
		(width 0.0889)
		(layer "B.Cu")
		(net "UPI_CPU0_CPU1_P1P1_DN<18>")
	)
	(segment
		(start 120.32996 -47.265082)
		(end 120.32996 -47.607982)
		(width 0.1143)
		(layer "B.Cu")
		(net "UPI_CPU0_CPU1_P1P1_DN<18>")
	)
	(segment
		(start 305.847496 -55.169308)
		(end 305.845464 -55.17261)
		(width 0.0889)
		(layer "B.Cu")
		(net "UPI_CPU0_CPU1_P1P1_DN<18>")
	)
	(segment
		(start 122.445018 -55.704486)
		(end 122.440192 -55.713122)
		(width 0.0889)
		(layer "B.Cu")
		(net "UPI_CPU0_CPU1_P1P1_DN<18>")
	)
	(segment
		(start 120.32996 -50.29708)
		(end 120.30456 -50.32248)
		(width 0.0889)
		(layer "B.Cu")
		(net "UPI_CPU0_CPU1_P1P1_DN<18>")
	)
	(segment
		(start 122.451368 -54.703218)
		(end 122.445018 -54.713886)
		(width 0.0889)
		(layer "B.Cu")
		(net "UPI_CPU0_CPU1_P1P1_DN<18>")
	)
	(segment
		(start 209.593688 -30.162754)
		(end 211.881466 -30.071822)
		(width 0.1143)
		(layer "B.Cu")
		(net "UPI_CPU0_CPU1_P1P1_DN<18>")
	)
	(segment
		(start 307.41112 -51.83759)
		(end 306.94884 -52.894738)
		(width 0.1143)
		(layer "B.Cu")
		(net "UPI_CPU0_CPU1_P1P1_DN<18>")
	)
	(segment
		(start 307.473604 -51.601878)
		(end 307.41112 -51.83759)
		(width 0.1143)
		(layer "B.Cu")
		(net "UPI_CPU0_CPU1_P1P1_DN<18>")
	)
	(segment
		(start 120.32996 -48.496982)
		(end 120.43156 -48.598582)
		(width 0.1143)
		(layer "B.Cu")
		(net "UPI_CPU0_CPU1_P1P1_DN<18>")
	)
	(segment
		(start 306.93995 -52.915058)
		(end 306.953158 -52.948078)
		(width 0.0889)
		(layer "B.Cu")
		(net "UPI_CPU0_CPU1_P1P1_DN<18>")
	)
	(segment
		(start 150.308564 -29.855922)
		(end 152.328118 -29.177996)
		(width 0.1143)
		(layer "B.Cu")
		(net "UPI_CPU0_CPU1_P1P1_DN<18>")
	)
	(segment
		(start 305.556412 -56.12257)
		(end 305.539902 -56.230774)
		(width 0.0889)
		(layer "B.Cu")
		(net "UPI_CPU0_CPU1_P1P1_DN<18>")
	)
	(segment
		(start 307.982366 -48.283622)
		(end 308.100984 -48.365156)
		(width 0.1143)
		(layer "B.Cu")
		(net "UPI_CPU0_CPU1_P1P1_DN<18>")
	)
	(segment
		(start 225.196654 -32.869886)
		(end 225.38563 -32.920432)
		(width 0.1143)
		(layer "B.Cu")
		(net "UPI_CPU0_CPU1_P1P1_DN<18>")
	)
	(segment
		(start 120.43156 -46.820582)
		(end 120.43156 -47.163482)
		(width 0.1143)
		(layer "B.Cu")
		(net "UPI_CPU0_CPU1_P1P1_DN<18>")
	)
	(segment
		(start 307.840126 -46.953678)
		(end 307.758592 -47.072042)
		(width 0.1143)
		(layer "B.Cu")
		(net "UPI_CPU0_CPU1_P1P1_DN<18>")
	)
	(segment
		(start 170.963336 -26.840688)
		(end 176.65827 -25.295098)
		(width 0.1143)
		(layer "B.Cu")
		(net "UPI_CPU0_CPU1_P1P1_DN<18>")
	)
	(segment
		(start 307.758592 -47.072042)
		(end 307.820822 -47.409354)
		(width 0.1143)
		(layer "B.Cu")
		(net "UPI_CPU0_CPU1_P1P1_DN<18>")
	)
	(segment
		(start 307.59781 -51.135026)
		(end 307.442362 -51.225196)
		(width 0.1143)
		(layer "B.Cu")
		(net "UPI_CPU0_CPU1_P1P1_DN<18>")
	)
	(segment
		(start 307.355494 -44.330874)
		(end 307.27396 -44.449238)
		(width 0.1143)
		(layer "B.Cu")
		(net "UPI_CPU0_CPU1_P1P1_DN<18>")
	)
	(segment
		(start 120.330214 -46.102778)
		(end 120.32996 -46.103032)
		(width 0.1143)
		(layer "B.Cu")
		(net "UPI_CPU0_CPU1_P1P1_DN<18>")
	)
	(segment
		(start 225.38563 -32.920432)
		(end 236.876082 -30.62224)
		(width 0.1143)
		(layer "B.Cu")
		(net "UPI_CPU0_CPU1_P1P1_DN<18>")
	)
	(segment
		(start 305.539902 -56.230774)
		(end 305.246786 -56.399938)
		(width 0.0889)
		(layer "B.Cu")
		(net "UPI_CPU0_CPU1_P1P1_DN<18>")
	)
	(segment
		(start 258.301998 -28.828746)
		(end 280.221182 -33.213294)
		(width 0.1143)
		(layer "B.Cu")
		(net "UPI_CPU0_CPU1_P1P1_DN<18>")
	)
	(segment
		(start 186.503056 -26.180796)
		(end 191.120014 -27.974798)
		(width 0.1143)
		(layer "B.Cu")
		(net "UPI_CPU0_CPU1_P1P1_DN<18>")
	)
	(segment
		(start 308.134512 -49.115472)
		(end 307.78069 -50.447448)
		(width 0.1143)
		(layer "B.Cu")
		(net "UPI_CPU0_CPU1_P1P1_DN<18>")
	)
	(segment
		(start 280.221182 -33.213294)
		(end 289.087052 -31.44012)
		(width 0.1143)
		(layer "B.Cu")
		(net "UPI_CPU0_CPU1_P1P1_DN<18>")
	)
	(segment
		(start 307.78069 -50.447448)
		(end 307.624988 -50.537618)
		(width 0.1143)
		(layer "B.Cu")
		(net "UPI_CPU0_CPU1_P1P1_DN<18>")
	)
	(segment
		(start 308.00167 -47.827946)
		(end 307.920136 -47.94631)
		(width 0.1143)
		(layer "B.Cu")
		(net "UPI_CPU0_CPU1_P1P1_DN<18>")
	)
	(segment
		(start 122.451368 -56.684418)
		(end 122.445018 -56.695086)
		(width 0.0889)
		(layer "B.Cu")
		(net "UPI_CPU0_CPU1_P1P1_DN<18>")
	)
	(segment
		(start 308.100984 -48.365156)
		(end 308.1528 -48.64481)
		(width 0.1143)
		(layer "B.Cu")
		(net "UPI_CPU0_CPU1_P1P1_DN<18>")
	)
	(segment
		(start 120.43156 -48.941482)
		(end 120.32996 -49.043082)
		(width 0.1143)
		(layer "B.Cu")
		(net "UPI_CPU0_CPU1_P1P1_DN<18>")
	)
	(segment
		(start 254.533146 -28.074874)
		(end 258.301998 -28.828746)
		(width 0.1143)
		(layer "B.Cu")
		(net "UPI_CPU0_CPU1_P1P1_DN<18>")
	)
	(segment
		(start 181.408324 -24.746966)
		(end 186.503056 -26.180796)
		(width 0.1143)
		(layer "B.Cu")
		(net "UPI_CPU0_CPU1_P1P1_DN<18>")
	)
	(segment
		(start 120.32996 -47.607982)
		(end 120.43156 -47.709582)
		(width 0.1143)
		(layer "B.Cu")
		(net "UPI_CPU0_CPU1_P1P1_DN<18>")
	)
	(segment
		(start 121.932954 -53.827934)
		(end 121.933208 -53.827934)
		(width 0.0889)
		(layer "B.Cu")
		(net "UPI_CPU0_CPU1_P1P1_DN<18>")
	)
	(segment
		(start 154.983434 -29.422598)
		(end 157.712664 -27.919934)
		(width 0.1143)
		(layer "B.Cu")
		(net "UPI_CPU0_CPU1_P1P1_DN<18>")
	)
	(segment
		(start 195.860416 -27.91079)
		(end 197.09003 -28.062936)
		(width 0.1143)
		(layer "B.Cu")
		(net "UPI_CPU0_CPU1_P1P1_DN<18>")
	)
	(segment
		(start 120.32996 -49.932082)
		(end 120.32996 -50.274982)
		(width 0.1143)
		(layer "B.Cu")
		(net "UPI_CPU0_CPU1_P1P1_DN<18>")
	)
	(segment
		(start 307.616352 -45.742352)
		(end 307.678582 -46.07941)
		(width 0.1143)
		(layer "B.Cu")
		(net "UPI_CPU0_CPU1_P1P1_DN<18>")
	)
	(segment
		(start 120.30456 -50.758344)
		(end 120.359678 -50.92827)
		(width 0.0889)
		(layer "B.Cu")
		(net "UPI_CPU0_CPU1_P1P1_DN<18>")
	)
	(segment
		(start 307.383688 -51.44643)
		(end 307.473604 -51.601878)
		(width 0.1143)
		(layer "B.Cu")
		(net "UPI_CPU0_CPU1_P1P1_DN<18>")
	)
	(segment
		(start 250.78182 -28.651454)
		(end 252.694694 -28.570174)
		(width 0.1143)
		(layer "B.Cu")
		(net "UPI_CPU0_CPU1_P1P1_DN<18>")
	)
	(segment
		(start 307.624988 -50.537618)
		(end 307.566314 -50.758852)
		(width 0.1143)
		(layer "B.Cu")
		(net "UPI_CPU0_CPU1_P1P1_DN<18>")
	)
	(segment
		(start 122.445018 -57.685686)
		(end 122.440192 -57.694322)
		(width 0.0889)
		(layer "B.Cu")
		(net "UPI_CPU0_CPU1_P1P1_DN<18>")
	)
	(segment
		(start 307.6956 -46.559978)
		(end 307.777896 -46.61662)
		(width 0.1143)
		(layer "B.Cu")
		(net "UPI_CPU0_CPU1_P1P1_DN<18>")
	)
	(segment
		(start 191.120014 -27.974798)
		(end 195.860416 -27.91079)
		(width 0.1143)
		(layer "B.Cu")
		(net "UPI_CPU0_CPU1_P1P1_DN<18>")
	)
	(segment
		(start 128.602486 -34.075624)
		(end 150.308564 -29.855922)
		(width 0.1143)
		(layer "B.Cu")
		(net "UPI_CPU0_CPU1_P1P1_DN<18>")
	)
	(segment
		(start 306.94884 -52.894738)
		(end 306.93995 -52.915058)
		(width 0.0889)
		(layer "B.Cu")
		(net "UPI_CPU0_CPU1_P1P1_DN<18>")
	)
	(segment
		(start 120.32996 -50.274982)
		(end 120.32996 -50.29708)
		(width 0.0889)
		(layer "B.Cu")
		(net "UPI_CPU0_CPU1_P1P1_DN<18>")
	)
	(segment
		(start 307.566314 -50.758852)
		(end 307.656484 -50.9143)
		(width 0.1143)
		(layer "B.Cu")
		(net "UPI_CPU0_CPU1_P1P1_DN<18>")
	)
	(segment
		(start 222.396812 -32.281622)
		(end 225.196654 -32.869886)
		(width 0.1143)
		(layer "B.Cu")
		(net "UPI_CPU0_CPU1_P1P1_DN<18>")
	)
	(segment
		(start 120.32996 -46.103032)
		(end 120.32996 -46.718982)
		(width 0.1143)
		(layer "B.Cu")
		(net "UPI_CPU0_CPU1_P1P1_DN<18>")
	)
	(segment
		(start 307.442362 -51.225196)
		(end 307.383688 -51.44643)
		(width 0.1143)
		(layer "B.Cu")
		(net "UPI_CPU0_CPU1_P1P1_DN<18>")
	)
	(segment
		(start 126.127764 -60.507118)
		(end 126.217172 -60.531248)
		(width 0.0889)
		(layer "B.Cu")
		(net "UPI_CPU0_CPU1_P1P1_DN<18>")
	)
	(segment
		(start 157.712664 -27.919934)
		(end 166.888414 -26.02611)
		(width 0.1143)
		(layer "B.Cu")
		(net "UPI_CPU0_CPU1_P1P1_DN<18>")
	)
	(segment
		(start 122.795284 -37.992558)
		(end 121.54662 -39.84371)
		(width 0.1143)
		(layer "B.Cu")
		(net "UPI_CPU0_CPU1_P1P1_DN<18>")
	)
	(segment
		(start 122.445018 -56.695086)
		(end 122.440192 -56.703722)
		(width 0.0889)
		(layer "B.Cu")
		(net "UPI_CPU0_CPU1_P1P1_DN<18>")
	)
	(segment
		(start 120.32996 -49.043082)
		(end 120.32996 -49.385982)
		(width 0.1143)
		(layer "B.Cu")
		(net "UPI_CPU0_CPU1_P1P1_DN<18>")
	)
	(segment
		(start 121.469404 -53.425344)
		(end 121.586498 -53.627782)
		(width 0.0889)
		(layer "B.Cu")
		(net "UPI_CPU0_CPU1_P1P1_DN<18>")
	)
	(segment
		(start 120.32996 -49.385982)
		(end 120.43156 -49.487582)
		(width 0.1143)
		(layer "B.Cu")
		(net "UPI_CPU0_CPU1_P1P1_DN<18>")
	)
	(segment
		(start 298.315126 -32.209994)
		(end 306.299362 -38.61181)
		(width 0.1143)
		(layer "B.Cu")
		(net "UPI_CPU0_CPU1_P1P1_DN<18>")
	)
	(segment
		(start 120.32996 -48.154082)
		(end 120.32996 -48.496982)
		(width 0.1143)
		(layer "B.Cu")
		(net "UPI_CPU0_CPU1_P1P1_DN<18>")
	)
	(segment
		(start 307.656484 -50.9143)
		(end 307.59781 -51.135026)
		(width 0.1143)
		(layer "B.Cu")
		(net "UPI_CPU0_CPU1_P1P1_DN<18>")
	)
	(segment
		(start 307.454808 -44.868084)
		(end 307.517038 -45.205142)
		(width 0.1143)
		(layer "B.Cu")
		(net "UPI_CPU0_CPU1_P1P1_DN<18>")
	)
	(segment
		(start 306.299362 -38.61181)
		(end 307.355494 -44.330874)
		(width 0.1143)
		(layer "B.Cu")
		(net "UPI_CPU0_CPU1_P1P1_DN<18>")
	)
	(segment
		(start 307.497734 -45.660818)
		(end 307.616352 -45.742352)
		(width 0.1143)
		(layer "B.Cu")
		(net "UPI_CPU0_CPU1_P1P1_DN<18>")
	)
	(segment
		(start 124.769118 -60.266834)
		(end 125.665484 -60.266834)
		(width 0.0889)
		(layer "B.Cu")
		(net "UPI_CPU0_CPU1_P1P1_DN<18>")
	)
	(segment
		(start 120.43156 -49.487582)
		(end 120.43156 -49.830482)
		(width 0.1143)
		(layer "B.Cu")
		(net "UPI_CPU0_CPU1_P1P1_DN<18>")
	)
	(segment
		(start 307.777896 -46.61662)
		(end 307.840126 -46.953678)
		(width 0.1143)
		(layer "B.Cu")
		(net "UPI_CPU0_CPU1_P1P1_DN<18>")
	)
	(segment
		(start 176.65827 -25.295098)
		(end 181.408324 -24.746966)
		(width 0.1143)
		(layer "B.Cu")
		(net "UPI_CPU0_CPU1_P1P1_DN<18>")
	)
	(segment
		(start 197.09003 -28.062936)
		(end 208.487264 -29.75737)
		(width 0.1143)
		(layer "B.Cu")
		(net "UPI_CPU0_CPU1_P1P1_DN<18>")
	)
	(segment
		(start 306.84343 -53.199538)
		(end 305.847496 -55.169308)
		(width 0.0889)
		(layer "B.Cu")
		(net "UPI_CPU0_CPU1_P1P1_DN<18>")
	)
	(segment
		(start 122.451368 -57.675018)
		(end 122.445018 -57.685686)
		(width 0.0889)
		(layer "B.Cu")
		(net "UPI_CPU0_CPU1_P1P1_DN<18>")
	)
	(arc
		(start 122.445018 -55.113936)
		(mid 122.52424 -55.403054)
		(end 122.451368 -55.693818)
		(width 0.0889)
		(layer "B.Cu")
		(net "UPI_CPU0_CPU1_P1P1_DN<18>")
	)
	(arc
		(start 122.440192 -57.694322)
		(mid 122.391437 -57.890674)
		(end 122.445018 -58.085736)
		(width 0.0889)
		(layer "B.Cu")
		(net "UPI_CPU0_CPU1_P1P1_DN<18>")
	)
	(arc
		(start 122.813318 -59.276234)
		(mid 123.096535 -59.360515)
		(end 123.303538 -59.571382)
		(width 0.0889)
		(layer "B.Cu")
		(net "UPI_CPU0_CPU1_P1P1_DN<18>")
	)
	(arc
		(start 122.445018 -58.67654)
		(mid 122.440773 -59.068785)
		(end 122.773694 -59.276234)
		(width 0.0889)
		(layer "B.Cu")
		(net "UPI_CPU0_CPU1_P1P1_DN<18>")
	)
	(arc
		(start 122.440192 -56.703722)
		(mid 122.391437 -56.900074)
		(end 122.445018 -57.095136)
		(width 0.0889)
		(layer "B.Cu")
		(net "UPI_CPU0_CPU1_P1P1_DN<18>")
	)
	(arc
		(start 121.933208 -53.827934)
		(mid 122.441815 -54.11788)
		(end 122.451368 -54.703218)
		(width 0.0889)
		(layer "B.Cu")
		(net "UPI_CPU0_CPU1_P1P1_DN<18>")
	)
	(arc
		(start 305.5874 -55.61965)
		(mid 305.515678 -55.867634)
		(end 305.556412 -56.12257)
		(width 0.0889)
		(layer "B.Cu")
		(net "UPI_CPU0_CPU1_P1P1_DN<18>")
	)
	(arc
		(start 121.586498 -53.627782)
		(mid 121.73288 -53.774346)
		(end 121.932954 -53.827934)
		(width 0.0889)
		(layer "B.Cu")
		(net "UPI_CPU0_CPU1_P1P1_DN<18>")
	)
	(arc
		(start 122.440192 -54.722522)
		(mid 122.391437 -54.918874)
		(end 122.445018 -55.113936)
		(width 0.0889)
		(layer "B.Cu")
		(net "UPI_CPU0_CPU1_P1P1_DN<18>")
	)
	(arc
		(start 123.303538 -59.571382)
		(mid 123.445221 -59.715186)
		(end 123.639072 -59.771534)
		(width 0.0889)
		(layer "B.Cu")
		(net "UPI_CPU0_CPU1_P1P1_DN<18>")
	)
	(arc
		(start 122.445018 -57.095136)
		(mid 122.52424 -57.384254)
		(end 122.451368 -57.675018)
		(width 0.0889)
		(layer "B.Cu")
		(net "UPI_CPU0_CPU1_P1P1_DN<18>")
	)
	(arc
		(start 122.440192 -55.713122)
		(mid 122.391437 -55.909474)
		(end 122.445018 -56.104536)
		(width 0.0889)
		(layer "B.Cu")
		(net "UPI_CPU0_CPU1_P1P1_DN<18>")
	)
	(arc
		(start 122.445018 -56.104536)
		(mid 122.52424 -56.393654)
		(end 122.451368 -56.684418)
		(width 0.0889)
		(layer "B.Cu")
		(net "UPI_CPU0_CPU1_P1P1_DN<18>")
	)
	(arc
		(start 125.665484 -60.266834)
		(mid 125.924544 -60.333269)
		(end 126.127764 -60.507118)
		(width 0.0889)
		(layer "B.Cu")
		(net "UPI_CPU0_CPU1_P1P1_DN<18>")
	)
	(arc
		(start 122.445018 -58.085736)
		(mid 122.524149 -58.381138)
		(end 122.445018 -58.67654)
		(width 0.0889)
		(layer "B.Cu")
		(net "UPI_CPU0_CPU1_P1P1_DN<18>")
	)
	(arc
		(start 120.359678 -50.92827)
		(mid 120.848894 -52.205982)
		(end 121.469404 -53.425344)
		(width 0.0889)
		(layer "B.Cu")
		(net "UPI_CPU0_CPU1_P1P1_DN<18>")
	)
	(segment
		(start 303.816766 -55.904384)
		(end 304.388266 -55.904384)
		(width 0.1143)
		(layer "F.Cu")
		(net "UPI_CPU0_CPU1_P1P1_DN<17>")
	)
	(segment
		(start 126.797308 -59.866784)
		(end 127.368808 -59.866784)
		(width 0.1143)
		(layer "F.Cu")
		(net "UPI_CPU0_CPU1_P1P1_DN<17>")
	)
	(via
		(at 138.171936 -33.343342)
		(size 0.508)
		(drill 0.254)
		(layers "F.Cu" "B.Cu")
		(net "UPI_CPU0_CPU1_P1P1_DN<17>")
	)
	(via
		(at 127.368808 -59.866784)
		(size 0.508)
		(drill 0.254)
		(layers "F.Cu" "B.Cu")
		(net "UPI_CPU0_CPU1_P1P1_DN<17>")
	)
	(via
		(at 304.388266 -55.904384)
		(size 0.508)
		(drill 0.254)
		(layers "F.Cu" "B.Cu")
		(net "UPI_CPU0_CPU1_P1P1_DN<17>")
	)
	(segment
		(start 176.98466 -27.738578)
		(end 179.645056 -27.330654)
		(width 0.1143)
		(layer "B.Cu")
		(net "UPI_CPU0_CPU1_P1P1_DN<17>")
	)
	(segment
		(start 121.910094 -44.089066)
		(end 121.990612 -44.208192)
		(width 0.1143)
		(layer "B.Cu")
		(net "UPI_CPU0_CPU1_P1P1_DN<17>")
	)
	(segment
		(start 238.802418 -32.011112)
		(end 250.740418 -29.623512)
		(width 0.1143)
		(layer "B.Cu")
		(net "UPI_CPU0_CPU1_P1P1_DN<17>")
	)
	(segment
		(start 121.872502 -46.855634)
		(end 121.792238 -46.97476)
		(width 0.1143)
		(layer "B.Cu")
		(net "UPI_CPU0_CPU1_P1P1_DN<17>")
	)
	(segment
		(start 125.669802 -59.276488)
		(end 125.673358 -59.276234)
		(width 0.0889)
		(layer "B.Cu")
		(net "UPI_CPU0_CPU1_P1P1_DN<17>")
	)
	(segment
		(start 304.734722 -55.113936)
		(end 304.734976 -55.113936)
		(width 0.0889)
		(layer "B.Cu")
		(net "UPI_CPU0_CPU1_P1P1_DN<17>")
	)
	(segment
		(start 122.146568 -48.264318)
		(end 122.211846 -48.601122)
		(width 0.1143)
		(layer "B.Cu")
		(net "UPI_CPU0_CPU1_P1P1_DN<17>")
	)
	(segment
		(start 304.913792 -38.977316)
		(end 306.545742 -47.864268)
		(width 0.1143)
		(layer "B.Cu")
		(net "UPI_CPU0_CPU1_P1P1_DN<17>")
	)
	(segment
		(start 121.976896 -47.391574)
		(end 122.042174 -47.728378)
		(width 0.1143)
		(layer "B.Cu")
		(net "UPI_CPU0_CPU1_P1P1_DN<17>")
	)
	(segment
		(start 280.272744 -34.213546)
		(end 291.963094 -31.875476)
		(width 0.1143)
		(layer "B.Cu")
		(net "UPI_CPU0_CPU1_P1P1_DN<17>")
	)
	(segment
		(start 122.264424 -42.799508)
		(end 122.145044 -42.879772)
		(width 0.1143)
		(layer "B.Cu")
		(net "UPI_CPU0_CPU1_P1P1_DN<17>")
	)
	(segment
		(start 123.298712 -57.5818)
		(end 123.303538 -57.590436)
		(width 0.0889)
		(layer "B.Cu")
		(net "UPI_CPU0_CPU1_P1P1_DN<17>")
	)
	(segment
		(start 160.878012 -28.390596)
		(end 167.42283 -27.149552)
		(width 0.1143)
		(layer "B.Cu")
		(net "UPI_CPU0_CPU1_P1P1_DN<17>")
	)
	(segment
		(start 254.898652 -29.138372)
		(end 280.272744 -34.213546)
		(width 0.1143)
		(layer "B.Cu")
		(net "UPI_CPU0_CPU1_P1P1_DN<17>")
	)
	(segment
		(start 127.537972 -60.159646)
		(end 127.368808 -59.866784)
		(width 0.0889)
		(layer "B.Cu")
		(net "UPI_CPU0_CPU1_P1P1_DN<17>")
	)
	(segment
		(start 123.298712 -56.5912)
		(end 123.303538 -56.599836)
		(width 0.0889)
		(layer "B.Cu")
		(net "UPI_CPU0_CPU1_P1P1_DN<17>")
	)
	(segment
		(start 304.71618 -56.133746)
		(end 304.665126 -56.206644)
		(width 0.0889)
		(layer "B.Cu")
		(net "UPI_CPU0_CPU1_P1P1_DN<17>")
	)
	(segment
		(start 250.740418 -29.623512)
		(end 252.781816 -29.64307)
		(width 0.1143)
		(layer "B.Cu")
		(net "UPI_CPU0_CPU1_P1P1_DN<17>")
	)
	(segment
		(start 304.934366 -54.286912)
		(end 304.998628 -54.399688)
		(width 0.0889)
		(layer "B.Cu")
		(net "UPI_CPU0_CPU1_P1P1_DN<17>")
	)
	(segment
		(start 305.382676 -53.0098)
		(end 305.269646 -53.073808)
		(width 0.0889)
		(layer "B.Cu")
		(net "UPI_CPU0_CPU1_P1P1_DN<17>")
	)
	(segment
		(start 123.303538 -54.618636)
		(end 123.309888 -54.629304)
		(width 0.0889)
		(layer "B.Cu")
		(net "UPI_CPU0_CPU1_P1P1_DN<17>")
	)
	(segment
		(start 138.171936 -33.343342)
		(end 150.587964 -30.92958)
		(width 0.1143)
		(layer "B.Cu")
		(net "UPI_CPU0_CPU1_P1P1_DN<17>")
	)
	(segment
		(start 305.142392 -53.879496)
		(end 305.094894 -54.0512)
		(width 0.0889)
		(layer "B.Cu")
		(net "UPI_CPU0_CPU1_P1P1_DN<17>")
	)
	(segment
		(start 122.584718 -52.032662)
		(end 123.175522 -53.406548)
		(width 0.0889)
		(layer "B.Cu")
		(net "UPI_CPU0_CPU1_P1P1_DN<17>")
	)
	(segment
		(start 305.238658 -53.531008)
		(end 305.125628 -53.595016)
		(width 0.0889)
		(layer "B.Cu")
		(net "UPI_CPU0_CPU1_P1P1_DN<17>")
	)
	(segment
		(start 121.807224 -46.51883)
		(end 121.872502 -46.855634)
		(width 0.1143)
		(layer "B.Cu")
		(net "UPI_CPU0_CPU1_P1P1_DN<17>")
	)
	(segment
		(start 122.329702 -42.462704)
		(end 122.264424 -42.799508)
		(width 0.1143)
		(layer "B.Cu")
		(net "UPI_CPU0_CPU1_P1P1_DN<17>")
	)
	(segment
		(start 138.171936 -33.343342)
		(end 138.171936 -33.343596)
		(width 0.1143)
		(layer "B.Cu")
		(net "UPI_CPU0_CPU1_P1P1_DN<17>")
	)
	(segment
		(start 170.70451 -27.806142)
		(end 170.70959 -27.806396)
		(width 0.1143)
		(layer "B.Cu")
		(net "UPI_CPU0_CPU1_P1P1_DN<17>")
	)
	(segment
		(start 208.337912 -30.651196)
		(end 209.459576 -31.073852)
		(width 0.1143)
		(layer "B.Cu")
		(net "UPI_CPU0_CPU1_P1P1_DN<17>")
	)
	(segment
		(start 305.481482 -52.558188)
		(end 305.499262 -52.589176)
		(width 0.0889)
		(layer "B.Cu")
		(net "UPI_CPU0_CPU1_P1P1_DN<17>")
	)
	(segment
		(start 305.221894 -53.246528)
		(end 305.286156 -53.359304)
		(width 0.0889)
		(layer "B.Cu")
		(net "UPI_CPU0_CPU1_P1P1_DN<17>")
	)
	(segment
		(start 121.57075 -45.834554)
		(end 121.687844 -46.438566)
		(width 0.1143)
		(layer "B.Cu")
		(net "UPI_CPU0_CPU1_P1P1_DN<17>")
	)
	(segment
		(start 122.211846 -48.601122)
		(end 122.131582 -48.720248)
		(width 0.1143)
		(layer "B.Cu")
		(net "UPI_CPU0_CPU1_P1P1_DN<17>")
	)
	(segment
		(start 179.645056 -27.330654)
		(end 183.388762 -26.360374)
		(width 0.1143)
		(layer "B.Cu")
		(net "UPI_CPU0_CPU1_P1P1_DN<17>")
	)
	(segment
		(start 304.981864 -54.115208)
		(end 304.934366 -54.286912)
		(width 0.0889)
		(layer "B.Cu")
		(net "UPI_CPU0_CPU1_P1P1_DN<17>")
	)
	(segment
		(start 121.96191 -47.847504)
		(end 122.027188 -48.184054)
		(width 0.1143)
		(layer "B.Cu")
		(net "UPI_CPU0_CPU1_P1P1_DN<17>")
	)
	(segment
		(start 212.804756 -31.279592)
		(end 225.094038 -33.895792)
		(width 0.1143)
		(layer "B.Cu")
		(net "UPI_CPU0_CPU1_P1P1_DN<17>")
	)
	(segment
		(start 122.314716 -42.007028)
		(end 122.249438 -42.343578)
		(width 0.1143)
		(layer "B.Cu")
		(net "UPI_CPU0_CPU1_P1P1_DN<17>")
	)
	(segment
		(start 122.610118 -51.665124)
		(end 122.584718 -51.690524)
		(width 0.0889)
		(layer "B.Cu")
		(net "UPI_CPU0_CPU1_P1P1_DN<17>")
	)
	(segment
		(start 185.348626 -26.87447)
		(end 191.189102 -28.84424)
		(width 0.1143)
		(layer "B.Cu")
		(net "UPI_CPU0_CPU1_P1P1_DN<17>")
	)
	(segment
		(start 122.499374 -41.58996)
		(end 122.434096 -41.926764)
		(width 0.1143)
		(layer "B.Cu")
		(net "UPI_CPU0_CPU1_P1P1_DN<17>")
	)
	(segment
		(start 122.434096 -41.926764)
		(end 122.314716 -42.007028)
		(width 0.1143)
		(layer "B.Cu")
		(net "UPI_CPU0_CPU1_P1P1_DN<17>")
	)
	(segment
		(start 305.094894 -54.0512)
		(end 304.981864 -54.115208)
		(width 0.0889)
		(layer "B.Cu")
		(net "UPI_CPU0_CPU1_P1P1_DN<17>")
	)
	(segment
		(start 196.07403 -28.710128)
		(end 197.32117 -28.880308)
		(width 0.1143)
		(layer "B.Cu")
		(net "UPI_CPU0_CPU1_P1P1_DN<17>")
	)
	(segment
		(start 122.584718 -51.690524)
		(end 122.584718 -52.032662)
		(width 0.0889)
		(layer "B.Cu")
		(net "UPI_CPU0_CPU1_P1P1_DN<17>")
	)
	(segment
		(start 121.740422 -44.96181)
		(end 121.82094 -45.080936)
		(width 0.1143)
		(layer "B.Cu")
		(net "UPI_CPU0_CPU1_P1P1_DN<17>")
	)
	(segment
		(start 121.857516 -47.31131)
		(end 121.976896 -47.391574)
		(width 0.1143)
		(layer "B.Cu")
		(net "UPI_CPU0_CPU1_P1P1_DN<17>")
	)
	(segment
		(start 123.175522 -53.406548)
		(end 123.30938 -53.63845)
		(width 0.0889)
		(layer "B.Cu")
		(net "UPI_CPU0_CPU1_P1P1_DN<17>")
	)
	(segment
		(start 305.286156 -53.359304)
		(end 305.238658 -53.531008)
		(width 0.0889)
		(layer "B.Cu")
		(net "UPI_CPU0_CPU1_P1P1_DN<17>")
	)
	(segment
		(start 123.632214 -58.780934)
		(end 124.365004 -58.780934)
		(width 0.0889)
		(layer "B.Cu")
		(net "UPI_CPU0_CPU1_P1P1_DN<17>")
	)
	(segment
		(start 123.298712 -54.61)
		(end 123.303538 -54.618636)
		(width 0.0889)
		(layer "B.Cu")
		(net "UPI_CPU0_CPU1_P1P1_DN<17>")
	)
	(segment
		(start 305.07813 -53.76672)
		(end 305.142392 -53.879496)
		(width 0.0889)
		(layer "B.Cu")
		(net "UPI_CPU0_CPU1_P1P1_DN<17>")
	)
	(segment
		(start 122.131582 -48.720248)
		(end 122.610118 -51.185318)
		(width 0.1143)
		(layer "B.Cu")
		(net "UPI_CPU0_CPU1_P1P1_DN<17>")
	)
	(segment
		(start 121.8057 -44.62526)
		(end 121.740422 -44.96181)
		(width 0.1143)
		(layer "B.Cu")
		(net "UPI_CPU0_CPU1_P1P1_DN<17>")
	)
	(segment
		(start 127.516636 -60.23864)
		(end 127.537972 -60.159646)
		(width 0.0889)
		(layer "B.Cu")
		(net "UPI_CPU0_CPU1_P1P1_DN<17>")
	)
	(segment
		(start 122.042174 -47.728378)
		(end 121.96191 -47.847504)
		(width 0.1143)
		(layer "B.Cu")
		(net "UPI_CPU0_CPU1_P1P1_DN<17>")
	)
	(segment
		(start 122.610118 -51.185318)
		(end 122.610118 -51.665124)
		(width 0.1143)
		(layer "B.Cu")
		(net "UPI_CPU0_CPU1_P1P1_DN<17>")
	)
	(segment
		(start 305.269646 -53.073808)
		(end 305.221894 -53.246528)
		(width 0.0889)
		(layer "B.Cu")
		(net "UPI_CPU0_CPU1_P1P1_DN<17>")
	)
	(segment
		(start 122.637042 -40.3479)
		(end 122.41911 -41.470834)
		(width 0.1143)
		(layer "B.Cu")
		(net "UPI_CPU0_CPU1_P1P1_DN<17>")
	)
	(segment
		(start 155.975812 -30.922214)
		(end 156.74086 -30.76956)
		(width 0.1143)
		(layer "B.Cu")
		(net "UPI_CPU0_CPU1_P1P1_DN<17>")
	)
	(segment
		(start 123.303538 -56.599836)
		(end 123.309888 -56.610504)
		(width 0.0889)
		(layer "B.Cu")
		(net "UPI_CPU0_CPU1_P1P1_DN<17>")
	)
	(segment
		(start 170.710098 -27.806396)
		(end 172.129958 -27.850084)
		(width 0.1143)
		(layer "B.Cu")
		(net "UPI_CPU0_CPU1_P1P1_DN<17>")
	)
	(segment
		(start 150.587964 -30.92958)
		(end 153.651712 -31.090362)
		(width 0.1143)
		(layer "B.Cu")
		(net "UPI_CPU0_CPU1_P1P1_DN<17>")
	)
	(segment
		(start 123.737116 -38.716966)
		(end 122.637042 -40.3479)
		(width 0.1143)
		(layer "B.Cu")
		(net "UPI_CPU0_CPU1_P1P1_DN<17>")
	)
	(segment
		(start 121.755408 -45.41774)
		(end 121.636028 -45.498004)
		(width 0.1143)
		(layer "B.Cu")
		(net "UPI_CPU0_CPU1_P1P1_DN<17>")
	)
	(segment
		(start 236.913928 -31.63316)
		(end 238.802418 -32.011112)
		(width 0.1143)
		(layer "B.Cu")
		(net "UPI_CPU0_CPU1_P1P1_DN<17>")
	)
	(segment
		(start 304.862738 -54.892956)
		(end 304.734722 -55.113936)
		(width 0.0889)
		(layer "B.Cu")
		(net "UPI_CPU0_CPU1_P1P1_DN<17>")
	)
	(segment
		(start 304.388266 -56.119522)
		(end 304.388266 -55.904384)
		(width 0.0889)
		(layer "B.Cu")
		(net "UPI_CPU0_CPU1_P1P1_DN<17>")
	)
	(segment
		(start 123.303538 -55.609236)
		(end 123.309888 -55.619904)
		(width 0.0889)
		(layer "B.Cu")
		(net "UPI_CPU0_CPU1_P1P1_DN<17>")
	)
	(segment
		(start 123.303538 -57.590436)
		(end 123.309888 -57.601104)
		(width 0.0889)
		(layer "B.Cu")
		(net "UPI_CPU0_CPU1_P1P1_DN<17>")
	)
	(segment
		(start 123.298712 -55.6006)
		(end 123.303538 -55.609236)
		(width 0.0889)
		(layer "B.Cu")
		(net "UPI_CPU0_CPU1_P1P1_DN<17>")
	)
	(segment
		(start 305.499262 -52.589176)
		(end 305.382676 -53.0098)
		(width 0.0889)
		(layer "B.Cu")
		(net "UPI_CPU0_CPU1_P1P1_DN<17>")
	)
	(segment
		(start 297.890184 -33.282128)
		(end 304.913792 -38.977316)
		(width 0.1143)
		(layer "B.Cu")
		(net "UPI_CPU0_CPU1_P1P1_DN<17>")
	)
	(segment
		(start 121.687844 -46.438566)
		(end 121.807224 -46.51883)
		(width 0.1143)
		(layer "B.Cu")
		(net "UPI_CPU0_CPU1_P1P1_DN<17>")
	)
	(segment
		(start 138.171936 -33.343596)
		(end 129.083816 -35.110166)
		(width 0.1143)
		(layer "B.Cu")
		(net "UPI_CPU0_CPU1_P1P1_DN<17>")
	)
	(segment
		(start 291.963094 -31.875476)
		(end 297.890184 -33.282128)
		(width 0.1143)
		(layer "B.Cu")
		(net "UPI_CPU0_CPU1_P1P1_DN<17>")
	)
	(segment
		(start 156.74086 -30.76956)
		(end 160.878012 -28.390596)
		(width 0.1143)
		(layer "B.Cu")
		(net "UPI_CPU0_CPU1_P1P1_DN<17>")
	)
	(segment
		(start 122.094752 -43.672252)
		(end 121.975372 -43.752516)
		(width 0.1143)
		(layer "B.Cu")
		(net "UPI_CPU0_CPU1_P1P1_DN<17>")
	)
	(segment
		(start 121.792238 -46.97476)
		(end 121.857516 -47.31131)
		(width 0.1143)
		(layer "B.Cu")
		(net "UPI_CPU0_CPU1_P1P1_DN<17>")
	)
	(segment
		(start 122.41911 -41.470834)
		(end 122.499374 -41.58996)
		(width 0.1143)
		(layer "B.Cu")
		(net "UPI_CPU0_CPU1_P1P1_DN<17>")
	)
	(segment
		(start 124.860558 -59.276488)
		(end 125.669802 -59.276488)
		(width 0.0889)
		(layer "B.Cu")
		(net "UPI_CPU0_CPU1_P1P1_DN<17>")
	)
	(segment
		(start 122.249438 -42.343578)
		(end 122.329702 -42.462704)
		(width 0.1143)
		(layer "B.Cu")
		(net "UPI_CPU0_CPU1_P1P1_DN<17>")
	)
	(segment
		(start 197.32117 -28.880308)
		(end 208.337912 -30.651196)
		(width 0.1143)
		(layer "B.Cu")
		(net "UPI_CPU0_CPU1_P1P1_DN<17>")
	)
	(segment
		(start 305.601116 -52.126642)
		(end 305.481482 -52.558188)
		(width 0.1143)
		(layer "B.Cu")
		(net "UPI_CPU0_CPU1_P1P1_DN<17>")
	)
	(segment
		(start 121.82094 -45.080936)
		(end 121.755408 -45.41774)
		(width 0.1143)
		(layer "B.Cu")
		(net "UPI_CPU0_CPU1_P1P1_DN<17>")
	)
	(segment
		(start 121.92508 -44.544996)
		(end 121.8057 -44.62526)
		(width 0.1143)
		(layer "B.Cu")
		(net "UPI_CPU0_CPU1_P1P1_DN<17>")
	)
	(segment
		(start 124.365004 -58.780934)
		(end 124.860558 -59.276488)
		(width 0.0889)
		(layer "B.Cu")
		(net "UPI_CPU0_CPU1_P1P1_DN<17>")
	)
	(segment
		(start 126.499112 -59.771534)
		(end 126.523242 -59.771534)
		(width 0.0889)
		(layer "B.Cu")
		(net "UPI_CPU0_CPU1_P1P1_DN<17>")
	)
	(segment
		(start 191.189102 -28.84424)
		(end 196.07403 -28.710128)
		(width 0.1143)
		(layer "B.Cu")
		(net "UPI_CPU0_CPU1_P1P1_DN<17>")
	)
	(segment
		(start 306.398168 -50.033428)
		(end 305.79822 -51.859688)
		(width 0.1143)
		(layer "B.Cu")
		(net "UPI_CPU0_CPU1_P1P1_DN<17>")
	)
	(segment
		(start 170.70959 -27.806396)
		(end 170.710098 -27.806396)
		(width 0.1143)
		(layer "B.Cu")
		(net "UPI_CPU0_CPU1_P1P1_DN<17>")
	)
	(segment
		(start 121.975372 -43.752516)
		(end 121.910094 -44.089066)
		(width 0.1143)
		(layer "B.Cu")
		(net "UPI_CPU0_CPU1_P1P1_DN<17>")
	)
	(segment
		(start 167.42283 -27.149552)
		(end 170.70451 -27.806142)
		(width 0.1143)
		(layer "B.Cu")
		(net "UPI_CPU0_CPU1_P1P1_DN<17>")
	)
	(segment
		(start 122.145044 -42.879772)
		(end 122.079766 -43.216322)
		(width 0.1143)
		(layer "B.Cu")
		(net "UPI_CPU0_CPU1_P1P1_DN<17>")
	)
	(segment
		(start 121.636028 -45.498004)
		(end 121.57075 -45.834554)
		(width 0.1143)
		(layer "B.Cu")
		(net "UPI_CPU0_CPU1_P1P1_DN<17>")
	)
	(segment
		(start 304.998628 -54.399688)
		(end 304.862738 -54.892956)
		(width 0.0889)
		(layer "B.Cu")
		(net "UPI_CPU0_CPU1_P1P1_DN<17>")
	)
	(segment
		(start 122.079766 -43.216322)
		(end 122.16003 -43.335448)
		(width 0.1143)
		(layer "B.Cu")
		(net "UPI_CPU0_CPU1_P1P1_DN<17>")
	)
	(segment
		(start 225.094038 -33.895792)
		(end 225.3107 -33.953958)
		(width 0.1143)
		(layer "B.Cu")
		(net "UPI_CPU0_CPU1_P1P1_DN<17>")
	)
	(segment
		(start 304.734976 -55.704486)
		(end 304.739802 -55.713122)
		(width 0.0889)
		(layer "B.Cu")
		(net "UPI_CPU0_CPU1_P1P1_DN<17>")
	)
	(segment
		(start 153.651712 -31.090362)
		(end 155.975812 -30.922214)
		(width 0.1143)
		(layer "B.Cu")
		(net "UPI_CPU0_CPU1_P1P1_DN<17>")
	)
	(segment
		(start 305.79822 -51.859688)
		(end 305.601116 -52.126642)
		(width 0.1143)
		(layer "B.Cu")
		(net "UPI_CPU0_CPU1_P1P1_DN<17>")
	)
	(segment
		(start 252.781816 -29.64307)
		(end 254.898652 -29.138372)
		(width 0.1143)
		(layer "B.Cu")
		(net "UPI_CPU0_CPU1_P1P1_DN<17>")
	)
	(segment
		(start 172.129958 -27.850084)
		(end 176.98466 -27.738578)
		(width 0.1143)
		(layer "B.Cu")
		(net "UPI_CPU0_CPU1_P1P1_DN<17>")
	)
	(segment
		(start 304.728626 -55.693818)
		(end 304.734976 -55.704486)
		(width 0.0889)
		(layer "B.Cu")
		(net "UPI_CPU0_CPU1_P1P1_DN<17>")
	)
	(segment
		(start 185.137552 -26.802334)
		(end 185.348626 -26.87447)
		(width 0.1143)
		(layer "B.Cu")
		(net "UPI_CPU0_CPU1_P1P1_DN<17>")
	)
	(segment
		(start 121.990612 -44.208192)
		(end 121.92508 -44.544996)
		(width 0.1143)
		(layer "B.Cu")
		(net "UPI_CPU0_CPU1_P1P1_DN<17>")
	)
	(segment
		(start 129.083816 -35.110166)
		(end 123.737116 -38.716966)
		(width 0.1143)
		(layer "B.Cu")
		(net "UPI_CPU0_CPU1_P1P1_DN<17>")
	)
	(segment
		(start 305.125628 -53.595016)
		(end 305.07813 -53.76672)
		(width 0.0889)
		(layer "B.Cu")
		(net "UPI_CPU0_CPU1_P1P1_DN<17>")
	)
	(segment
		(start 209.459576 -31.073852)
		(end 211.485226 -31.095188)
		(width 0.1143)
		(layer "B.Cu")
		(net "UPI_CPU0_CPU1_P1P1_DN<17>")
	)
	(segment
		(start 306.545742 -47.864268)
		(end 306.398168 -50.033428)
		(width 0.1143)
		(layer "B.Cu")
		(net "UPI_CPU0_CPU1_P1P1_DN<17>")
	)
	(segment
		(start 183.388762 -26.360374)
		(end 185.137552 -26.802334)
		(width 0.1143)
		(layer "B.Cu")
		(net "UPI_CPU0_CPU1_P1P1_DN<17>")
	)
	(segment
		(start 211.485226 -31.095188)
		(end 212.804756 -31.279592)
		(width 0.1143)
		(layer "B.Cu")
		(net "UPI_CPU0_CPU1_P1P1_DN<17>")
	)
	(segment
		(start 225.3107 -33.953958)
		(end 236.913928 -31.63316)
		(width 0.1143)
		(layer "B.Cu")
		(net "UPI_CPU0_CPU1_P1P1_DN<17>")
	)
	(segment
		(start 122.16003 -43.335448)
		(end 122.094752 -43.672252)
		(width 0.1143)
		(layer "B.Cu")
		(net "UPI_CPU0_CPU1_P1P1_DN<17>")
	)
	(segment
		(start 122.027188 -48.184054)
		(end 122.146568 -48.264318)
		(width 0.1143)
		(layer "B.Cu")
		(net "UPI_CPU0_CPU1_P1P1_DN<17>")
	)
	(segment
		(start 127.310896 -60.26277)
		(end 127.403352 -60.276232)
		(width 0.0889)
		(layer "B.Cu")
		(net "UPI_CPU0_CPU1_P1P1_DN<17>")
	)
	(arc
		(start 304.734976 -55.113936)
		(mid 304.655754 -55.403054)
		(end 304.728626 -55.693818)
		(width 0.0889)
		(layer "B.Cu")
		(net "UPI_CPU0_CPU1_P1P1_DN<17>")
	)
	(arc
		(start 123.303538 -55.209186)
		(mid 123.250068 -55.404249)
		(end 123.298712 -55.6006)
		(width 0.0889)
		(layer "B.Cu")
		(net "UPI_CPU0_CPU1_P1P1_DN<17>")
	)
	(arc
		(start 123.309888 -56.610504)
		(mid 123.382686 -56.901267)
		(end 123.303538 -57.190386)
		(width 0.0889)
		(layer "B.Cu")
		(net "UPI_CPU0_CPU1_P1P1_DN<17>")
	)
	(arc
		(start 126.163578 -59.571382)
		(mid 126.305261 -59.715186)
		(end 126.499112 -59.771534)
		(width 0.0889)
		(layer "B.Cu")
		(net "UPI_CPU0_CPU1_P1P1_DN<17>")
	)
	(arc
		(start 304.665126 -56.206644)
		(mid 304.494745 -56.264637)
		(end 304.388266 -56.119522)
		(width 0.0889)
		(layer "B.Cu")
		(net "UPI_CPU0_CPU1_P1P1_DN<17>")
	)
	(arc
		(start 123.309888 -55.619904)
		(mid 123.382686 -55.910667)
		(end 123.303538 -56.199786)
		(width 0.0889)
		(layer "B.Cu")
		(net "UPI_CPU0_CPU1_P1P1_DN<17>")
	)
	(arc
		(start 123.303538 -54.218586)
		(mid 123.250068 -54.413649)
		(end 123.298712 -54.61)
		(width 0.0889)
		(layer "B.Cu")
		(net "UPI_CPU0_CPU1_P1P1_DN<17>")
	)
	(arc
		(start 123.309888 -57.601104)
		(mid 123.382686 -57.891867)
		(end 123.303538 -58.180986)
		(width 0.0889)
		(layer "B.Cu")
		(net "UPI_CPU0_CPU1_P1P1_DN<17>")
	)
	(arc
		(start 123.303538 -57.190386)
		(mid 123.250068 -57.385449)
		(end 123.298712 -57.5818)
		(width 0.0889)
		(layer "B.Cu")
		(net "UPI_CPU0_CPU1_P1P1_DN<17>")
	)
	(arc
		(start 304.739802 -55.713122)
		(mid 304.787836 -55.926799)
		(end 304.71618 -56.133746)
		(width 0.0889)
		(layer "B.Cu")
		(net "UPI_CPU0_CPU1_P1P1_DN<17>")
	)
	(arc
		(start 126.523242 -59.771534)
		(mid 126.811387 -59.853853)
		(end 127.022098 -60.066936)
		(width 0.0889)
		(layer "B.Cu")
		(net "UPI_CPU0_CPU1_P1P1_DN<17>")
	)
	(arc
		(start 123.30938 -53.63845)
		(mid 123.382615 -53.929298)
		(end 123.303538 -54.218586)
		(width 0.0889)
		(layer "B.Cu")
		(net "UPI_CPU0_CPU1_P1P1_DN<17>")
	)
	(arc
		(start 127.403352 -60.276232)
		(mid 127.46447 -60.270896)
		(end 127.516636 -60.23864)
		(width 0.0889)
		(layer "B.Cu")
		(net "UPI_CPU0_CPU1_P1P1_DN<17>")
	)
	(arc
		(start 125.673358 -59.276234)
		(mid 125.956575 -59.360515)
		(end 126.163578 -59.571382)
		(width 0.0889)
		(layer "B.Cu")
		(net "UPI_CPU0_CPU1_P1P1_DN<17>")
	)
	(arc
		(start 123.303538 -58.180986)
		(mid 123.299128 -58.573449)
		(end 123.632214 -58.780934)
		(width 0.0889)
		(layer "B.Cu")
		(net "UPI_CPU0_CPU1_P1P1_DN<17>")
	)
	(arc
		(start 127.022098 -60.066936)
		(mid 127.144052 -60.197967)
		(end 127.310896 -60.26277)
		(width 0.0889)
		(layer "B.Cu")
		(net "UPI_CPU0_CPU1_P1P1_DN<17>")
	)
	(arc
		(start 123.303538 -56.199786)
		(mid 123.250068 -56.394849)
		(end 123.298712 -56.5912)
		(width 0.0889)
		(layer "B.Cu")
		(net "UPI_CPU0_CPU1_P1P1_DN<17>")
	)
	(arc
		(start 123.309888 -54.629304)
		(mid 123.382686 -54.920067)
		(end 123.303538 -55.209186)
		(width 0.0889)
		(layer "B.Cu")
		(net "UPI_CPU0_CPU1_P1P1_DN<17>")
	)
	(segment
		(start 125.080268 -57.885584)
		(end 125.651768 -57.885584)
		(width 0.1143)
		(layer "F.Cu")
		(net "UPI_CPU0_CPU1_P1P1_DN<16>")
	)
	(segment
		(start 303.529746 -55.409338)
		(end 302.958246 -55.409338)
		(width 0.1143)
		(layer "F.Cu")
		(net "UPI_CPU0_CPU1_P1P1_DN<16>")
	)
	(via
		(at 303.529746 -55.409338)
		(size 0.508)
		(drill 0.254)
		(layers "F.Cu" "B.Cu")
		(net "UPI_CPU0_CPU1_P1P1_DN<16>")
	)
	(via
		(at 125.651768 -57.885584)
		(size 0.508)
		(drill 0.254)
		(layers "F.Cu" "B.Cu")
		(net "UPI_CPU0_CPU1_P1P1_DN<16>")
	)
	(segment
		(start 124.387864 -57.674256)
		(end 124.24664 -57.533032)
		(width 0.0889)
		(layer "B.Cu")
		(net "UPI_CPU0_CPU1_P1P1_DN<16>")
	)
	(segment
		(start 209.86242 -32.10687)
		(end 211.890102 -32.158178)
		(width 0.1143)
		(layer "B.Cu")
		(net "UPI_CPU0_CPU1_P1P1_DN<16>")
	)
	(segment
		(start 190.396368 -29.723588)
		(end 196.15023 -29.519118)
		(width 0.1143)
		(layer "B.Cu")
		(net "UPI_CPU0_CPU1_P1P1_DN<16>")
	)
	(segment
		(start 123.029218 -45.365924)
		(end 123.09475 -45.02912)
		(width 0.1143)
		(layer "B.Cu")
		(net "UPI_CPU0_CPU1_P1P1_DN<16>")
	)
	(segment
		(start 125.651768 -58.129424)
		(end 125.495304 -58.285888)
		(width 0.0889)
		(layer "B.Cu")
		(net "UPI_CPU0_CPU1_P1P1_DN<16>")
	)
	(segment
		(start 303.902872 -39.65702)
		(end 305.341274 -48.303434)
		(width 0.1143)
		(layer "B.Cu")
		(net "UPI_CPU0_CPU1_P1P1_DN<16>")
	)
	(segment
		(start 124.650246 -57.936638)
		(end 124.650246 -57.799986)
		(width 0.0889)
		(layer "B.Cu")
		(net "UPI_CPU0_CPU1_P1P1_DN<16>")
	)
	(segment
		(start 123.538234 -42.747692)
		(end 123.603766 -42.410888)
		(width 0.1143)
		(layer "B.Cu")
		(net "UPI_CPU0_CPU1_P1P1_DN<16>")
	)
	(segment
		(start 304.835052 -51.537362)
		(end 304.825908 -51.557428)
		(width 0.0889)
		(layer "B.Cu")
		(net "UPI_CPU0_CPU1_P1P1_DN<16>")
	)
	(segment
		(start 123.750324 -50.95494)
		(end 123.691396 -50.617374)
		(width 0.1143)
		(layer "B.Cu")
		(net "UPI_CPU0_CPU1_P1P1_DN<16>")
	)
	(segment
		(start 123.69292 -41.419018)
		(end 123.829064 -40.717724)
		(width 0.1143)
		(layer "B.Cu")
		(net "UPI_CPU0_CPU1_P1P1_DN<16>")
	)
	(segment
		(start 124.999496 -58.285888)
		(end 124.650246 -57.936638)
		(width 0.0889)
		(layer "B.Cu")
		(net "UPI_CPU0_CPU1_P1P1_DN<16>")
	)
	(segment
		(start 123.707906 -41.874948)
		(end 123.773184 -41.538144)
		(width 0.1143)
		(layer "B.Cu")
		(net "UPI_CPU0_CPU1_P1P1_DN<16>")
	)
	(segment
		(start 185.448194 -27.976576)
		(end 190.396368 -29.723588)
		(width 0.1143)
		(layer "B.Cu")
		(net "UPI_CPU0_CPU1_P1P1_DN<16>")
	)
	(segment
		(start 123.750324 -51.396646)
		(end 123.750324 -51.374548)
		(width 0.0889)
		(layer "B.Cu")
		(net "UPI_CPU0_CPU1_P1P1_DN<16>")
	)
	(segment
		(start 123.691396 -50.617374)
		(end 123.773946 -50.499772)
		(width 0.1143)
		(layer "B.Cu")
		(net "UPI_CPU0_CPU1_P1P1_DN<16>")
	)
	(segment
		(start 124.353828 -40.121586)
		(end 124.326396 -39.980616)
		(width 0.1143)
		(layer "B.Cu")
		(net "UPI_CPU0_CPU1_P1P1_DN<16>")
	)
	(segment
		(start 123.407424 -48.408082)
		(end 123.289568 -48.325532)
		(width 0.1143)
		(layer "B.Cu")
		(net "UPI_CPU0_CPU1_P1P1_DN<16>")
	)
	(segment
		(start 124.326396 -39.980616)
		(end 124.676662 -39.46144)
		(width 0.1143)
		(layer "B.Cu")
		(net "UPI_CPU0_CPU1_P1P1_DN<16>")
	)
	(segment
		(start 161.11601 -29.397198)
		(end 167.304466 -28.159202)
		(width 0.1143)
		(layer "B.Cu")
		(net "UPI_CPU0_CPU1_P1P1_DN<16>")
	)
	(segment
		(start 305.341274 -48.303434)
		(end 305.324764 -49.4411)
		(width 0.1143)
		(layer "B.Cu")
		(net "UPI_CPU0_CPU1_P1P1_DN<16>")
	)
	(segment
		(start 124.676662 -39.46144)
		(end 129.564892 -36.163758)
		(width 0.1143)
		(layer "B.Cu")
		(net "UPI_CPU0_CPU1_P1P1_DN<16>")
	)
	(segment
		(start 303.822862 -55.240174)
		(end 303.529746 -55.409338)
		(width 0.0889)
		(layer "B.Cu")
		(net "UPI_CPU0_CPU1_P1P1_DN<16>")
	)
	(segment
		(start 151.217376 -31.954724)
		(end 154.690826 -32.62376)
		(width 0.1143)
		(layer "B.Cu")
		(net "UPI_CPU0_CPU1_P1P1_DN<16>")
	)
	(segment
		(start 123.750324 -51.374548)
		(end 123.750324 -50.95494)
		(width 0.1143)
		(layer "B.Cu")
		(net "UPI_CPU0_CPU1_P1P1_DN<16>")
	)
	(segment
		(start 124.3457 -57.047638)
		(end 124.24664 -56.948578)
		(width 0.0889)
		(layer "B.Cu")
		(net "UPI_CPU0_CPU1_P1P1_DN<16>")
	)
	(segment
		(start 179.962302 -28.263342)
		(end 183.894222 -27.524202)
		(width 0.1143)
		(layer "B.Cu")
		(net "UPI_CPU0_CPU1_P1P1_DN<16>")
	)
	(segment
		(start 197.058534 -29.652976)
		(end 208.31048 -31.573724)
		(width 0.1143)
		(layer "B.Cu")
		(net "UPI_CPU0_CPU1_P1P1_DN<16>")
	)
	(segment
		(start 249.931428 -30.565598)
		(end 252.766322 -30.632146)
		(width 0.1143)
		(layer "B.Cu")
		(net "UPI_CPU0_CPU1_P1P1_DN<16>")
	)
	(segment
		(start 123.434094 -43.283632)
		(end 123.353576 -43.164506)
		(width 0.1143)
		(layer "B.Cu")
		(net "UPI_CPU0_CPU1_P1P1_DN<16>")
	)
	(segment
		(start 123.724924 -51.422046)
		(end 123.750324 -51.396646)
		(width 0.0889)
		(layer "B.Cu")
		(net "UPI_CPU0_CPU1_P1P1_DN<16>")
	)
	(segment
		(start 124.24664 -56.948578)
		(end 124.24664 -53.052726)
		(width 0.0889)
		(layer "B.Cu")
		(net "UPI_CPU0_CPU1_P1P1_DN<16>")
	)
	(segment
		(start 123.523248 -42.291762)
		(end 123.588526 -41.955212)
		(width 0.1143)
		(layer "B.Cu")
		(net "UPI_CPU0_CPU1_P1P1_DN<16>")
	)
	(segment
		(start 123.159774 -46.994572)
		(end 123.100592 -46.656498)
		(width 0.1143)
		(layer "B.Cu")
		(net "UPI_CPU0_CPU1_P1P1_DN<16>")
	)
	(segment
		(start 124.02058 -40.433498)
		(end 124.161804 -40.406066)
		(width 0.1143)
		(layer "B.Cu")
		(net "UPI_CPU0_CPU1_P1P1_DN<16>")
	)
	(segment
		(start 123.254008 -47.53229)
		(end 123.136152 -47.44974)
		(width 0.1143)
		(layer "B.Cu")
		(net "UPI_CPU0_CPU1_P1P1_DN<16>")
	)
	(segment
		(start 124.650246 -57.799986)
		(end 124.524516 -57.674256)
		(width 0.0889)
		(layer "B.Cu")
		(net "UPI_CPU0_CPU1_P1P1_DN<16>")
	)
	(segment
		(start 123.596908 -50.079148)
		(end 123.53798 -49.741582)
		(width 0.1143)
		(layer "B.Cu")
		(net "UPI_CPU0_CPU1_P1P1_DN<16>")
	)
	(segment
		(start 304.825908 -51.557428)
		(end 304.838608 -51.590448)
		(width 0.0889)
		(layer "B.Cu")
		(net "UPI_CPU0_CPU1_P1P1_DN<16>")
	)
	(segment
		(start 211.890102 -32.158178)
		(end 212.469476 -32.245554)
		(width 0.1143)
		(layer "B.Cu")
		(net "UPI_CPU0_CPU1_P1P1_DN<16>")
	)
	(segment
		(start 304.838608 -51.590448)
		(end 304.028856 -53.363876)
		(width 0.0889)
		(layer "B.Cu")
		(net "UPI_CPU0_CPU1_P1P1_DN<16>")
	)
	(segment
		(start 123.714764 -50.161698)
		(end 123.596908 -50.079148)
		(width 0.1143)
		(layer "B.Cu")
		(net "UPI_CPU0_CPU1_P1P1_DN<16>")
	)
	(segment
		(start 124.24664 -57.533032)
		(end 124.24664 -57.324498)
		(width 0.0889)
		(layer "B.Cu")
		(net "UPI_CPU0_CPU1_P1P1_DN<16>")
	)
	(segment
		(start 123.100592 -46.656498)
		(end 122.982736 -46.573948)
		(width 0.1143)
		(layer "B.Cu")
		(net "UPI_CPU0_CPU1_P1P1_DN<16>")
	)
	(segment
		(start 125.651768 -57.885584)
		(end 125.651768 -58.129424)
		(width 0.0889)
		(layer "B.Cu")
		(net "UPI_CPU0_CPU1_P1P1_DN<16>")
	)
	(segment
		(start 304.028856 -53.363876)
		(end 303.876456 -53.627782)
		(width 0.0889)
		(layer "B.Cu")
		(net "UPI_CPU0_CPU1_P1P1_DN<16>")
	)
	(segment
		(start 122.982736 -46.573948)
		(end 122.84456 -45.782738)
		(width 0.1143)
		(layer "B.Cu")
		(net "UPI_CPU0_CPU1_P1P1_DN<16>")
	)
	(segment
		(start 176.553368 -28.816554)
		(end 179.962302 -28.263342)
		(width 0.1143)
		(layer "B.Cu")
		(net "UPI_CPU0_CPU1_P1P1_DN<16>")
	)
	(segment
		(start 124.161804 -40.406066)
		(end 124.353828 -40.121586)
		(width 0.1143)
		(layer "B.Cu")
		(net "UPI_CPU0_CPU1_P1P1_DN<16>")
	)
	(segment
		(start 123.62053 -49.62398)
		(end 123.561348 -49.285906)
		(width 0.1143)
		(layer "B.Cu")
		(net "UPI_CPU0_CPU1_P1P1_DN<16>")
	)
	(segment
		(start 303.876456 -54.618636)
		(end 303.870106 -54.629304)
		(width 0.0889)
		(layer "B.Cu")
		(net "UPI_CPU0_CPU1_P1P1_DN<16>")
	)
	(segment
		(start 123.09475 -45.02912)
		(end 123.014232 -44.909994)
		(width 0.1143)
		(layer "B.Cu")
		(net "UPI_CPU0_CPU1_P1P1_DN<16>")
	)
	(segment
		(start 125.495304 -58.285888)
		(end 124.999496 -58.285888)
		(width 0.0889)
		(layer "B.Cu")
		(net "UPI_CPU0_CPU1_P1P1_DN<16>")
	)
	(segment
		(start 123.418854 -42.827956)
		(end 123.538234 -42.747692)
		(width 0.1143)
		(layer "B.Cu")
		(net "UPI_CPU0_CPU1_P1P1_DN<16>")
	)
	(segment
		(start 303.846738 -55.150766)
		(end 303.822862 -55.240174)
		(width 0.0889)
		(layer "B.Cu")
		(net "UPI_CPU0_CPU1_P1P1_DN<16>")
	)
	(segment
		(start 123.588526 -41.955212)
		(end 123.707906 -41.874948)
		(width 0.1143)
		(layer "B.Cu")
		(net "UPI_CPU0_CPU1_P1P1_DN<16>")
	)
	(segment
		(start 124.524516 -57.674256)
		(end 124.387864 -57.674256)
		(width 0.0889)
		(layer "B.Cu")
		(net "UPI_CPU0_CPU1_P1P1_DN<16>")
	)
	(segment
		(start 255.370838 -30.227524)
		(end 280.268934 -35.207194)
		(width 0.1143)
		(layer "B.Cu")
		(net "UPI_CPU0_CPU1_P1P1_DN<16>")
	)
	(segment
		(start 123.724924 -52.10556)
		(end 123.724924 -51.422046)
		(width 0.0889)
		(layer "B.Cu")
		(net "UPI_CPU0_CPU1_P1P1_DN<16>")
	)
	(segment
		(start 123.249182 -43.7007)
		(end 123.368562 -43.620436)
		(width 0.1143)
		(layer "B.Cu")
		(net "UPI_CPU0_CPU1_P1P1_DN<16>")
	)
	(segment
		(start 208.31048 -31.573724)
		(end 209.86242 -32.10687)
		(width 0.1143)
		(layer "B.Cu")
		(net "UPI_CPU0_CPU1_P1P1_DN<16>")
	)
	(segment
		(start 123.264422 -44.156376)
		(end 123.183904 -44.03725)
		(width 0.1143)
		(layer "B.Cu")
		(net "UPI_CPU0_CPU1_P1P1_DN<16>")
	)
	(segment
		(start 291.82314 -32.896556)
		(end 294.6273 -33.61309)
		(width 0.1143)
		(layer "B.Cu")
		(net "UPI_CPU0_CPU1_P1P1_DN<16>")
	)
	(segment
		(start 236.801152 -32.644842)
		(end 238.362998 -32.880808)
		(width 0.1143)
		(layer "B.Cu")
		(net "UPI_CPU0_CPU1_P1P1_DN<16>")
	)
	(segment
		(start 124.3457 -57.225438)
		(end 124.3457 -57.047638)
		(width 0.0889)
		(layer "B.Cu")
		(net "UPI_CPU0_CPU1_P1P1_DN<16>")
	)
	(segment
		(start 294.627554 -33.61309)
		(end 297.43146 -34.32937)
		(width 0.1143)
		(layer "B.Cu")
		(net "UPI_CPU0_CPU1_P1P1_DN<16>")
	)
	(segment
		(start 156.213302 -32.352488)
		(end 161.11601 -29.397198)
		(width 0.1143)
		(layer "B.Cu")
		(net "UPI_CPU0_CPU1_P1P1_DN<16>")
	)
	(segment
		(start 196.15023 -29.519118)
		(end 197.058534 -29.652976)
		(width 0.1143)
		(layer "B.Cu")
		(net "UPI_CPU0_CPU1_P1P1_DN<16>")
	)
	(segment
		(start 222.396812 -34.388044)
		(end 225.123248 -34.976308)
		(width 0.1143)
		(layer "B.Cu")
		(net "UPI_CPU0_CPU1_P1P1_DN<16>")
	)
	(segment
		(start 123.53798 -49.741582)
		(end 123.62053 -49.62398)
		(width 0.1143)
		(layer "B.Cu")
		(net "UPI_CPU0_CPU1_P1P1_DN<16>")
	)
	(segment
		(start 183.894222 -27.524202)
		(end 185.448194 -27.976576)
		(width 0.1143)
		(layer "B.Cu")
		(net "UPI_CPU0_CPU1_P1P1_DN<16>")
	)
	(segment
		(start 123.368562 -43.620436)
		(end 123.434094 -43.283632)
		(width 0.1143)
		(layer "B.Cu")
		(net "UPI_CPU0_CPU1_P1P1_DN<16>")
	)
	(segment
		(start 294.6273 -33.61309)
		(end 294.627554 -33.61309)
		(width 0.1143)
		(layer "B.Cu")
		(net "UPI_CPU0_CPU1_P1P1_DN<16>")
	)
	(segment
		(start 123.353576 -43.164506)
		(end 123.418854 -42.827956)
		(width 0.1143)
		(layer "B.Cu")
		(net "UPI_CPU0_CPU1_P1P1_DN<16>")
	)
	(segment
		(start 303.881282 -54.61)
		(end 303.876456 -54.618636)
		(width 0.0889)
		(layer "B.Cu")
		(net "UPI_CPU0_CPU1_P1P1_DN<16>")
	)
	(segment
		(start 123.183904 -44.03725)
		(end 123.249182 -43.7007)
		(width 0.1143)
		(layer "B.Cu")
		(net "UPI_CPU0_CPU1_P1P1_DN<16>")
	)
	(segment
		(start 123.443492 -49.203356)
		(end 123.384056 -48.863758)
		(width 0.1143)
		(layer "B.Cu")
		(net "UPI_CPU0_CPU1_P1P1_DN<16>")
	)
	(segment
		(start 123.31319 -47.870364)
		(end 123.254008 -47.53229)
		(width 0.1143)
		(layer "B.Cu")
		(net "UPI_CPU0_CPU1_P1P1_DN<16>")
	)
	(segment
		(start 225.123248 -34.976308)
		(end 225.367342 -35.04438)
		(width 0.1143)
		(layer "B.Cu")
		(net "UPI_CPU0_CPU1_P1P1_DN<16>")
	)
	(segment
		(start 252.766322 -30.632146)
		(end 255.370838 -30.227524)
		(width 0.1143)
		(layer "B.Cu")
		(net "UPI_CPU0_CPU1_P1P1_DN<16>")
	)
	(segment
		(start 123.19889 -44.49318)
		(end 123.264422 -44.156376)
		(width 0.1143)
		(layer "B.Cu")
		(net "UPI_CPU0_CPU1_P1P1_DN<16>")
	)
	(segment
		(start 123.077224 -47.112174)
		(end 123.159774 -46.994572)
		(width 0.1143)
		(layer "B.Cu")
		(net "UPI_CPU0_CPU1_P1P1_DN<16>")
	)
	(segment
		(start 238.362998 -32.880808)
		(end 249.931428 -30.565598)
		(width 0.1143)
		(layer "B.Cu")
		(net "UPI_CPU0_CPU1_P1P1_DN<16>")
	)
	(segment
		(start 167.304466 -28.159202)
		(end 170.607736 -28.82011)
		(width 0.1143)
		(layer "B.Cu")
		(net "UPI_CPU0_CPU1_P1P1_DN<16>")
	)
	(segment
		(start 123.466606 -48.746156)
		(end 123.407424 -48.408082)
		(width 0.1143)
		(layer "B.Cu")
		(net "UPI_CPU0_CPU1_P1P1_DN<16>")
	)
	(segment
		(start 212.469476 -32.245554)
		(end 222.396812 -34.388044)
		(width 0.1143)
		(layer "B.Cu")
		(net "UPI_CPU0_CPU1_P1P1_DN<16>")
	)
	(segment
		(start 123.289568 -48.325532)
		(end 123.23064 -47.987966)
		(width 0.1143)
		(layer "B.Cu")
		(net "UPI_CPU0_CPU1_P1P1_DN<16>")
	)
	(segment
		(start 124.24664 -53.052726)
		(end 123.724924 -52.10556)
		(width 0.0889)
		(layer "B.Cu")
		(net "UPI_CPU0_CPU1_P1P1_DN<16>")
	)
	(segment
		(start 123.384056 -48.863758)
		(end 123.466606 -48.746156)
		(width 0.1143)
		(layer "B.Cu")
		(net "UPI_CPU0_CPU1_P1P1_DN<16>")
	)
	(segment
		(start 122.909838 -45.446188)
		(end 123.029218 -45.365924)
		(width 0.1143)
		(layer "B.Cu")
		(net "UPI_CPU0_CPU1_P1P1_DN<16>")
	)
	(segment
		(start 123.23064 -47.987966)
		(end 123.31319 -47.870364)
		(width 0.1143)
		(layer "B.Cu")
		(net "UPI_CPU0_CPU1_P1P1_DN<16>")
	)
	(segment
		(start 123.603766 -42.410888)
		(end 123.523248 -42.291762)
		(width 0.1143)
		(layer "B.Cu")
		(net "UPI_CPU0_CPU1_P1P1_DN<16>")
	)
	(segment
		(start 123.561348 -49.285906)
		(end 123.443492 -49.203356)
		(width 0.1143)
		(layer "B.Cu")
		(net "UPI_CPU0_CPU1_P1P1_DN<16>")
	)
	(segment
		(start 123.014232 -44.909994)
		(end 123.07951 -44.573444)
		(width 0.1143)
		(layer "B.Cu")
		(net "UPI_CPU0_CPU1_P1P1_DN<16>")
	)
	(segment
		(start 280.268934 -35.207194)
		(end 291.82314 -32.896556)
		(width 0.1143)
		(layer "B.Cu")
		(net "UPI_CPU0_CPU1_P1P1_DN<16>")
	)
	(segment
		(start 123.773184 -41.538144)
		(end 123.69292 -41.419018)
		(width 0.1143)
		(layer "B.Cu")
		(net "UPI_CPU0_CPU1_P1P1_DN<16>")
	)
	(segment
		(start 123.829064 -40.717724)
		(end 124.02058 -40.433498)
		(width 0.1143)
		(layer "B.Cu")
		(net "UPI_CPU0_CPU1_P1P1_DN<16>")
	)
	(segment
		(start 124.24664 -57.324498)
		(end 124.3457 -57.225438)
		(width 0.0889)
		(layer "B.Cu")
		(net "UPI_CPU0_CPU1_P1P1_DN<16>")
	)
	(segment
		(start 305.324764 -49.4411)
		(end 304.970434 -51.239928)
		(width 0.1143)
		(layer "B.Cu")
		(net "UPI_CPU0_CPU1_P1P1_DN<16>")
	)
	(segment
		(start 123.773946 -50.499772)
		(end 123.714764 -50.161698)
		(width 0.1143)
		(layer "B.Cu")
		(net "UPI_CPU0_CPU1_P1P1_DN<16>")
	)
	(segment
		(start 297.43146 -34.32937)
		(end 303.902872 -39.65702)
		(width 0.1143)
		(layer "B.Cu")
		(net "UPI_CPU0_CPU1_P1P1_DN<16>")
	)
	(segment
		(start 170.607736 -28.82011)
		(end 176.553368 -28.816554)
		(width 0.1143)
		(layer "B.Cu")
		(net "UPI_CPU0_CPU1_P1P1_DN<16>")
	)
	(segment
		(start 123.07951 -44.573444)
		(end 123.19889 -44.49318)
		(width 0.1143)
		(layer "B.Cu")
		(net "UPI_CPU0_CPU1_P1P1_DN<16>")
	)
	(segment
		(start 154.690826 -32.62376)
		(end 156.213302 -32.352488)
		(width 0.1143)
		(layer "B.Cu")
		(net "UPI_CPU0_CPU1_P1P1_DN<16>")
	)
	(segment
		(start 225.367342 -35.04438)
		(end 236.801152 -32.644842)
		(width 0.1143)
		(layer "B.Cu")
		(net "UPI_CPU0_CPU1_P1P1_DN<16>")
	)
	(segment
		(start 123.136152 -47.44974)
		(end 123.077224 -47.112174)
		(width 0.1143)
		(layer "B.Cu")
		(net "UPI_CPU0_CPU1_P1P1_DN<16>")
	)
	(segment
		(start 122.84456 -45.782738)
		(end 122.909838 -45.446188)
		(width 0.1143)
		(layer "B.Cu")
		(net "UPI_CPU0_CPU1_P1P1_DN<16>")
	)
	(segment
		(start 304.970434 -51.239928)
		(end 304.835052 -51.537362)
		(width 0.1143)
		(layer "B.Cu")
		(net "UPI_CPU0_CPU1_P1P1_DN<16>")
	)
	(segment
		(start 129.564892 -36.163758)
		(end 151.217376 -31.954724)
		(width 0.1143)
		(layer "B.Cu")
		(net "UPI_CPU0_CPU1_P1P1_DN<16>")
	)
	(arc
		(start 303.876456 -54.218586)
		(mid 303.929926 -54.413649)
		(end 303.881282 -54.61)
		(width 0.0889)
		(layer "B.Cu")
		(net "UPI_CPU0_CPU1_P1P1_DN<16>")
	)
	(arc
		(start 303.870106 -54.629304)
		(mid 303.797711 -54.887316)
		(end 303.846738 -55.150766)
		(width 0.0889)
		(layer "B.Cu")
		(net "UPI_CPU0_CPU1_P1P1_DN<16>")
	)
	(arc
		(start 303.876456 -53.627782)
		(mid 303.797325 -53.923184)
		(end 303.876456 -54.218586)
		(width 0.0889)
		(layer "B.Cu")
		(net "UPI_CPU0_CPU1_P1P1_DN<16>")
	)
	(segment
		(start 303.529746 -54.418738)
		(end 302.958246 -54.418738)
		(width 0.1143)
		(layer "F.Cu")
		(net "UPI_CPU0_CPU1_P1P1_DN<15>")
	)
	(segment
		(start 127.655828 -59.371484)
		(end 128.227328 -59.371484)
		(width 0.1143)
		(layer "F.Cu")
		(net "UPI_CPU0_CPU1_P1P1_DN<15>")
	)
	(via
		(at 303.529746 -54.418738)
		(size 0.508)
		(drill 0.254)
		(layers "F.Cu" "B.Cu")
		(net "UPI_CPU0_CPU1_P1P1_DN<15>")
	)
	(via
		(at 158.094934 -32.15005)
		(size 0.508)
		(drill 0.254)
		(layers "F.Cu" "B.Cu")
		(net "UPI_CPU0_CPU1_P1P1_DN<15>")
	)
	(via
		(at 128.227328 -59.371484)
		(size 0.508)
		(drill 0.254)
		(layers "F.Cu" "B.Cu")
		(net "UPI_CPU0_CPU1_P1P1_DN<15>")
	)
	(segment
		(start 172.523912 -30.665928)
		(end 173.932088 -29.897324)
		(width 0.1143)
		(layer "B.Cu")
		(net "UPI_CPU0_CPU1_P1P1_DN<15>")
	)
	(segment
		(start 125.37313 -57.485534)
		(end 124.568966 -56.68137)
		(width 0.0889)
		(layer "B.Cu")
		(net "UPI_CPU0_CPU1_P1P1_DN<15>")
	)
	(segment
		(start 159.668718 -31.191454)
		(end 160.253172 -31.074614)
		(width 0.1143)
		(layer "B.Cu")
		(net "UPI_CPU0_CPU1_P1P1_DN<15>")
	)
	(segment
		(start 124.568966 -51.894486)
		(end 124.64923 -51.814222)
		(width 0.0889)
		(layer "B.Cu")
		(net "UPI_CPU0_CPU1_P1P1_DN<15>")
	)
	(segment
		(start 303.062894 -40.34155)
		(end 304.477928 -48.36668)
		(width 0.1143)
		(layer "B.Cu")
		(net "UPI_CPU0_CPU1_P1P1_DN<15>")
	)
	(segment
		(start 303.671224 -50.996342)
		(end 303.671224 -51.11369)
		(width 0.1143)
		(layer "B.Cu")
		(net "UPI_CPU0_CPU1_P1P1_DN<15>")
	)
	(segment
		(start 158.094934 -32.15005)
		(end 159.668718 -31.191454)
		(width 0.1143)
		(layer "B.Cu")
		(net "UPI_CPU0_CPU1_P1P1_DN<15>")
	)
	(segment
		(start 128.952244 -43.44416)
		(end 131.456176 -39.731696)
		(width 0.1143)
		(layer "B.Cu")
		(net "UPI_CPU0_CPU1_P1P1_DN<15>")
	)
	(segment
		(start 255.665986 -31.04134)
		(end 280.233374 -35.955224)
		(width 0.1143)
		(layer "B.Cu")
		(net "UPI_CPU0_CPU1_P1P1_DN<15>")
	)
	(segment
		(start 211.705952 -32.947102)
		(end 222.396812 -35.213036)
		(width 0.1143)
		(layer "B.Cu")
		(net "UPI_CPU0_CPU1_P1P1_DN<15>")
	)
	(segment
		(start 154.944826 -33.434528)
		(end 156.429202 -33.16478)
		(width 0.1143)
		(layer "B.Cu")
		(net "UPI_CPU0_CPU1_P1P1_DN<15>")
	)
	(segment
		(start 303.249584 -54.045612)
		(end 303.249584 -54.138576)
		(width 0.0889)
		(layer "B.Cu")
		(net "UPI_CPU0_CPU1_P1P1_DN<15>")
	)
	(segment
		(start 160.253172 -31.074614)
		(end 160.253172 -31.07436)
		(width 0.1143)
		(layer "B.Cu")
		(net "UPI_CPU0_CPU1_P1P1_DN<15>")
	)
	(segment
		(start 184.725818 -28.534106)
		(end 189.761622 -30.282642)
		(width 0.1143)
		(layer "B.Cu")
		(net "UPI_CPU0_CPU1_P1P1_DN<15>")
	)
	(segment
		(start 303.6443 -51.140614)
		(end 303.6443 -51.555396)
		(width 0.0889)
		(layer "B.Cu")
		(net "UPI_CPU0_CPU1_P1P1_DN<15>")
	)
	(segment
		(start 209.773012 -32.853122)
		(end 211.705952 -32.947102)
		(width 0.1143)
		(layer "B.Cu")
		(net "UPI_CPU0_CPU1_P1P1_DN<15>")
	)
	(segment
		(start 124.798074 -46.848776)
		(end 128.952244 -43.44416)
		(width 0.1143)
		(layer "B.Cu")
		(net "UPI_CPU0_CPU1_P1P1_DN<15>")
	)
	(segment
		(start 253.067312 -31.40583)
		(end 255.665986 -31.04134)
		(width 0.1143)
		(layer "B.Cu")
		(net "UPI_CPU0_CPU1_P1P1_DN<15>")
	)
	(segment
		(start 176.7459 -29.59227)
		(end 183.785002 -28.322524)
		(width 0.1143)
		(layer "B.Cu")
		(net "UPI_CPU0_CPU1_P1P1_DN<15>")
	)
	(segment
		(start 249.29338 -31.236412)
		(end 253.067312 -31.40583)
		(width 0.1143)
		(layer "B.Cu")
		(net "UPI_CPU0_CPU1_P1P1_DN<15>")
	)
	(segment
		(start 124.568966 -56.68137)
		(end 124.568966 -51.894486)
		(width 0.0889)
		(layer "B.Cu")
		(net "UPI_CPU0_CPU1_P1P1_DN<15>")
	)
	(segment
		(start 303.249584 -54.138576)
		(end 303.529746 -54.418738)
		(width 0.0889)
		(layer "B.Cu")
		(net "UPI_CPU0_CPU1_P1P1_DN<15>")
	)
	(segment
		(start 304.477928 -48.36668)
		(end 303.671224 -50.996342)
		(width 0.1143)
		(layer "B.Cu")
		(net "UPI_CPU0_CPU1_P1P1_DN<15>")
	)
	(segment
		(start 137.025126 -35.975544)
		(end 137.30097 -35.922458)
		(width 0.1143)
		(layer "B.Cu")
		(net "UPI_CPU0_CPU1_P1P1_DN<15>")
	)
	(segment
		(start 160.253172 -31.07436)
		(end 166.32936 -29.85897)
		(width 0.1143)
		(layer "B.Cu")
		(net "UPI_CPU0_CPU1_P1P1_DN<15>")
	)
	(segment
		(start 124.62383 -47.888652)
		(end 124.798074 -46.848776)
		(width 0.1143)
		(layer "B.Cu")
		(net "UPI_CPU0_CPU1_P1P1_DN<15>")
	)
	(segment
		(start 156.429202 -33.16478)
		(end 158.094934 -32.150304)
		(width 0.1143)
		(layer "B.Cu")
		(net "UPI_CPU0_CPU1_P1P1_DN<15>")
	)
	(segment
		(start 303.412652 -52.703984)
		(end 303.278286 -53.062886)
		(width 0.0889)
		(layer "B.Cu")
		(net "UPI_CPU0_CPU1_P1P1_DN<15>")
	)
	(segment
		(start 222.396812 -35.213036)
		(end 225.24847 -35.817302)
		(width 0.1143)
		(layer "B.Cu")
		(net "UPI_CPU0_CPU1_P1P1_DN<15>")
	)
	(segment
		(start 225.24847 -35.817302)
		(end 236.83722 -33.406588)
		(width 0.1143)
		(layer "B.Cu")
		(net "UPI_CPU0_CPU1_P1P1_DN<15>")
	)
	(segment
		(start 173.932088 -29.897324)
		(end 176.7459 -29.59227)
		(width 0.1143)
		(layer "B.Cu")
		(net "UPI_CPU0_CPU1_P1P1_DN<15>")
	)
	(segment
		(start 280.233374 -35.955224)
		(end 291.50691 -33.700212)
		(width 0.1143)
		(layer "B.Cu")
		(net "UPI_CPU0_CPU1_P1P1_DN<15>")
	)
	(segment
		(start 297.058334 -35.306)
		(end 303.062894 -40.34155)
		(width 0.1143)
		(layer "B.Cu")
		(net "UPI_CPU0_CPU1_P1P1_DN<15>")
	)
	(segment
		(start 131.456176 -39.731696)
		(end 137.025126 -35.975544)
		(width 0.1143)
		(layer "B.Cu")
		(net "UPI_CPU0_CPU1_P1P1_DN<15>")
	)
	(segment
		(start 151.56434 -32.793178)
		(end 154.944826 -33.434528)
		(width 0.1143)
		(layer "B.Cu")
		(net "UPI_CPU0_CPU1_P1P1_DN<15>")
	)
	(segment
		(start 236.83722 -33.406588)
		(end 237.866174 -33.522158)
		(width 0.1143)
		(layer "B.Cu")
		(net "UPI_CPU0_CPU1_P1P1_DN<15>")
	)
	(segment
		(start 237.866174 -33.522158)
		(end 249.29338 -31.236412)
		(width 0.1143)
		(layer "B.Cu")
		(net "UPI_CPU0_CPU1_P1P1_DN<15>")
	)
	(segment
		(start 127.996696 -59.466988)
		(end 127.351028 -59.466988)
		(width 0.0889)
		(layer "B.Cu")
		(net "UPI_CPU0_CPU1_P1P1_DN<15>")
	)
	(segment
		(start 166.32936 -29.85897)
		(end 171.29379 -30.851856)
		(width 0.1143)
		(layer "B.Cu")
		(net "UPI_CPU0_CPU1_P1P1_DN<15>")
	)
	(segment
		(start 291.50691 -33.700212)
		(end 296.881042 -35.15741)
		(width 0.1143)
		(layer "B.Cu")
		(net "UPI_CPU0_CPU1_P1P1_DN<15>")
	)
	(segment
		(start 158.094934 -32.150304)
		(end 158.094934 -32.15005)
		(width 0.1143)
		(layer "B.Cu")
		(net "UPI_CPU0_CPU1_P1P1_DN<15>")
	)
	(segment
		(start 124.64923 -51.814222)
		(end 124.64923 -51.5874)
		(width 0.0889)
		(layer "B.Cu")
		(net "UPI_CPU0_CPU1_P1P1_DN<15>")
	)
	(segment
		(start 196.396864 -30.181804)
		(end 197.534022 -30.362144)
		(width 0.1143)
		(layer "B.Cu")
		(net "UPI_CPU0_CPU1_P1P1_DN<15>")
	)
	(segment
		(start 171.29379 -30.851856)
		(end 172.523912 -30.665928)
		(width 0.1143)
		(layer "B.Cu")
		(net "UPI_CPU0_CPU1_P1P1_DN<15>")
	)
	(segment
		(start 124.62383 -51.562)
		(end 124.62383 -47.888652)
		(width 0.1143)
		(layer "B.Cu")
		(net "UPI_CPU0_CPU1_P1P1_DN<15>")
	)
	(segment
		(start 303.278286 -53.062886)
		(end 303.183036 -53.227986)
		(width 0.0889)
		(layer "B.Cu")
		(net "UPI_CPU0_CPU1_P1P1_DN<15>")
	)
	(segment
		(start 296.881042 -35.15741)
		(end 297.058334 -35.306)
		(width 0.1143)
		(layer "B.Cu")
		(net "UPI_CPU0_CPU1_P1P1_DN<15>")
	)
	(segment
		(start 183.785002 -28.322524)
		(end 184.725818 -28.534106)
		(width 0.1143)
		(layer "B.Cu")
		(net "UPI_CPU0_CPU1_P1P1_DN<15>")
	)
	(segment
		(start 126.528322 -58.971688)
		(end 126.488698 -58.971688)
		(width 0.0889)
		(layer "B.Cu")
		(net "UPI_CPU0_CPU1_P1P1_DN<15>")
	)
	(segment
		(start 207.982566 -32.208978)
		(end 209.773012 -32.853122)
		(width 0.1143)
		(layer "B.Cu")
		(net "UPI_CPU0_CPU1_P1P1_DN<15>")
	)
	(segment
		(start 303.43602 -52.58816)
		(end 303.412652 -52.703984)
		(width 0.0889)
		(layer "B.Cu")
		(net "UPI_CPU0_CPU1_P1P1_DN<15>")
	)
	(segment
		(start 303.671224 -51.11369)
		(end 303.6443 -51.140614)
		(width 0.0889)
		(layer "B.Cu")
		(net "UPI_CPU0_CPU1_P1P1_DN<15>")
	)
	(segment
		(start 124.64923 -51.5874)
		(end 124.62383 -51.562)
		(width 0.0889)
		(layer "B.Cu")
		(net "UPI_CPU0_CPU1_P1P1_DN<15>")
	)
	(segment
		(start 303.6443 -51.555396)
		(end 303.43602 -52.58816)
		(width 0.0889)
		(layer "B.Cu")
		(net "UPI_CPU0_CPU1_P1P1_DN<15>")
	)
	(segment
		(start 137.30097 -35.922458)
		(end 151.56434 -32.793178)
		(width 0.1143)
		(layer "B.Cu")
		(net "UPI_CPU0_CPU1_P1P1_DN<15>")
	)
	(segment
		(start 197.534022 -30.362144)
		(end 207.982566 -32.208978)
		(width 0.1143)
		(layer "B.Cu")
		(net "UPI_CPU0_CPU1_P1P1_DN<15>")
	)
	(segment
		(start 125.666246 -57.485534)
		(end 125.37313 -57.485534)
		(width 0.0889)
		(layer "B.Cu")
		(net "UPI_CPU0_CPU1_P1P1_DN<15>")
	)
	(segment
		(start 189.761622 -30.282642)
		(end 196.396864 -30.181804)
		(width 0.1143)
		(layer "B.Cu")
		(net "UPI_CPU0_CPU1_P1P1_DN<15>")
	)
	(arc
		(start 126.856998 -59.171586)
		(mid 126.718254 -59.029553)
		(end 126.528322 -58.971688)
		(width 0.0889)
		(layer "B.Cu")
		(net "UPI_CPU0_CPU1_P1P1_DN<15>")
	)
	(arc
		(start 303.183036 -53.627782)
		(mid 303.254979 -53.830536)
		(end 303.249584 -54.045612)
		(width 0.0889)
		(layer "B.Cu")
		(net "UPI_CPU0_CPU1_P1P1_DN<15>")
	)
	(arc
		(start 303.183036 -53.227986)
		(mid 303.129537 -53.427884)
		(end 303.183036 -53.627782)
		(width 0.0889)
		(layer "B.Cu")
		(net "UPI_CPU0_CPU1_P1P1_DN<15>")
	)
	(arc
		(start 125.998478 -58.085736)
		(mid 126.002028 -57.691711)
		(end 125.666246 -57.485534)
		(width 0.0889)
		(layer "B.Cu")
		(net "UPI_CPU0_CPU1_P1P1_DN<15>")
	)
	(arc
		(start 126.488698 -58.971688)
		(mid 125.993221 -58.667245)
		(end 125.998478 -58.085736)
		(width 0.0889)
		(layer "B.Cu")
		(net "UPI_CPU0_CPU1_P1P1_DN<15>")
	)
	(arc
		(start 128.227328 -59.371484)
		(mid 128.121513 -59.442187)
		(end 127.996696 -59.466988)
		(width 0.0889)
		(layer "B.Cu")
		(net "UPI_CPU0_CPU1_P1P1_DN<15>")
	)
	(arc
		(start 127.351028 -59.466988)
		(mid 127.065604 -59.383521)
		(end 126.856998 -59.171586)
		(width 0.0889)
		(layer "B.Cu")
		(net "UPI_CPU0_CPU1_P1P1_DN<15>")
	)
	(segment
		(start 302.099726 -54.913784)
		(end 302.671226 -54.913784)
		(width 0.1143)
		(layer "F.Cu")
		(net "UPI_CPU0_CPU1_P1P1_DN<14>")
	)
	(segment
		(start 125.938788 -58.381138)
		(end 126.510288 -58.381138)
		(width 0.1143)
		(layer "F.Cu")
		(net "UPI_CPU0_CPU1_P1P1_DN<14>")
	)
	(via
		(at 302.671226 -54.913784)
		(size 0.508)
		(drill 0.254)
		(layers "F.Cu" "B.Cu")
		(net "UPI_CPU0_CPU1_P1P1_DN<14>")
	)
	(via
		(at 126.510288 -58.381138)
		(size 0.508)
		(drill 0.254)
		(layers "F.Cu" "B.Cu")
		(net "UPI_CPU0_CPU1_P1P1_DN<14>")
	)
	(via
		(at 151.064214 -34.31159)
		(size 0.508)
		(drill 0.254)
		(layers "F.Cu" "B.Cu")
		(net "UPI_CPU0_CPU1_P1P1_DN<14>")
	)
	(segment
		(start 225.293936 -36.848542)
		(end 236.874558 -34.40176)
		(width 0.1143)
		(layer "B.Cu")
		(net "UPI_CPU0_CPU1_P1P1_DN<14>")
	)
	(segment
		(start 125.75667 -52.953158)
		(end 125.060202 -53.649626)
		(width 0.0889)
		(layer "B.Cu")
		(net "UPI_CPU0_CPU1_P1P1_DN<14>")
	)
	(segment
		(start 125.060202 -53.649626)
		(end 125.060202 -56.213502)
		(width 0.0889)
		(layer "B.Cu")
		(net "UPI_CPU0_CPU1_P1P1_DN<14>")
	)
	(segment
		(start 155.223464 -34.48304)
		(end 157.197044 -34.236914)
		(width 0.1143)
		(layer "B.Cu")
		(net "UPI_CPU0_CPU1_P1P1_DN<14>")
	)
	(segment
		(start 256.321052 -32.277558)
		(end 279.936956 -37.00145)
		(width 0.1143)
		(layer "B.Cu")
		(net "UPI_CPU0_CPU1_P1P1_DN<14>")
	)
	(segment
		(start 125.73127 -52.106068)
		(end 125.75667 -52.131468)
		(width 0.0889)
		(layer "B.Cu")
		(net "UPI_CPU0_CPU1_P1P1_DN<14>")
	)
	(segment
		(start 126.492508 -56.990488)
		(end 126.525274 -56.990488)
		(width 0.0889)
		(layer "B.Cu")
		(net "UPI_CPU0_CPU1_P1P1_DN<14>")
	)
	(segment
		(start 125.73127 -48.321214)
		(end 125.73127 -52.08397)
		(width 0.1143)
		(layer "B.Cu")
		(net "UPI_CPU0_CPU1_P1P1_DN<14>")
	)
	(segment
		(start 302.615346 -50.842926)
		(end 302.611536 -50.86477)
		(width 0.0889)
		(layer "B.Cu")
		(net "UPI_CPU0_CPU1_P1P1_DN<14>")
	)
	(segment
		(start 301.881032 -41.014904)
		(end 303.216818 -48.429926)
		(width 0.1143)
		(layer "B.Cu")
		(net "UPI_CPU0_CPU1_P1P1_DN<14>")
	)
	(segment
		(start 129.628138 -44.417742)
		(end 129.629662 -44.417742)
		(width 0.1143)
		(layer "B.Cu")
		(net "UPI_CPU0_CPU1_P1P1_DN<14>")
	)
	(segment
		(start 207.950816 -33.157922)
		(end 208.506314 -33.367726)
		(width 0.1143)
		(layer "B.Cu")
		(net "UPI_CPU0_CPU1_P1P1_DN<14>")
	)
	(segment
		(start 209.620612 -33.81756)
		(end 211.38515 -33.946084)
		(width 0.1143)
		(layer "B.Cu")
		(net "UPI_CPU0_CPU1_P1P1_DN<14>")
	)
	(segment
		(start 132.334 -40.513508)
		(end 132.201666 -40.602662)
		(width 0.1143)
		(layer "B.Cu")
		(net "UPI_CPU0_CPU1_P1P1_DN<14>")
	)
	(segment
		(start 126.791212 -57.7596)
		(end 126.510288 -58.381138)
		(width 0.0889)
		(layer "B.Cu")
		(net "UPI_CPU0_CPU1_P1P1_DN<14>")
	)
	(segment
		(start 303.216818 -48.429926)
		(end 302.665638 -50.563526)
		(width 0.1143)
		(layer "B.Cu")
		(net "UPI_CPU0_CPU1_P1P1_DN<14>")
	)
	(segment
		(start 302.582326 -50.884836)
		(end 302.44288 -51.66106)
		(width 0.0889)
		(layer "B.Cu")
		(net "UPI_CPU0_CPU1_P1P1_DN<14>")
	)
	(segment
		(start 302.665638 -50.563526)
		(end 302.615346 -50.842926)
		(width 0.1143)
		(layer "B.Cu")
		(net "UPI_CPU0_CPU1_P1P1_DN<14>")
	)
	(segment
		(start 132.201666 -40.602662)
		(end 129.628138 -44.417742)
		(width 0.1143)
		(layer "B.Cu")
		(net "UPI_CPU0_CPU1_P1P1_DN<14>")
	)
	(segment
		(start 237.43412 -34.464498)
		(end 238.519208 -34.180018)
		(width 0.1143)
		(layer "B.Cu")
		(net "UPI_CPU0_CPU1_P1P1_DN<14>")
	)
	(segment
		(start 302.330866 -54.703218)
		(end 302.324516 -54.713886)
		(width 0.0889)
		(layer "B.Cu")
		(net "UPI_CPU0_CPU1_P1P1_DN<14>")
	)
	(segment
		(start 302.280066 -52.06492)
		(end 302.324516 -52.142136)
		(width 0.0889)
		(layer "B.Cu")
		(net "UPI_CPU0_CPU1_P1P1_DN<14>")
	)
	(segment
		(start 196.250052 -30.949138)
		(end 197.258686 -31.11881)
		(width 0.1143)
		(layer "B.Cu")
		(net "UPI_CPU0_CPU1_P1P1_DN<14>")
	)
	(segment
		(start 126.856998 -57.590436)
		(end 126.850648 -57.601104)
		(width 0.0889)
		(layer "B.Cu")
		(net "UPI_CPU0_CPU1_P1P1_DN<14>")
	)
	(segment
		(start 129.629662 -44.417742)
		(end 129.631948 -44.420028)
		(width 0.1143)
		(layer "B.Cu")
		(net "UPI_CPU0_CPU1_P1P1_DN<14>")
	)
	(segment
		(start 302.324516 -53.723286)
		(end 302.31969 -53.731922)
		(width 0.0889)
		(layer "B.Cu")
		(net "UPI_CPU0_CPU1_P1P1_DN<14>")
	)
	(segment
		(start 291.209984 -34.811716)
		(end 296.48023 -36.28263)
		(width 0.1143)
		(layer "B.Cu")
		(net "UPI_CPU0_CPU1_P1P1_DN<14>")
	)
	(segment
		(start 152.654508 -33.994598)
		(end 155.223464 -34.48304)
		(width 0.1143)
		(layer "B.Cu")
		(net "UPI_CPU0_CPU1_P1P1_DN<14>")
	)
	(segment
		(start 163.345876 -32.485076)
		(end 165.668706 -32.949642)
		(width 0.1143)
		(layer "B.Cu")
		(net "UPI_CPU0_CPU1_P1P1_DN<14>")
	)
	(segment
		(start 157.197044 -34.236914)
		(end 159.533082 -33.147762)
		(width 0.1143)
		(layer "B.Cu")
		(net "UPI_CPU0_CPU1_P1P1_DN<14>")
	)
	(segment
		(start 151.064214 -34.31159)
		(end 152.654508 -33.994598)
		(width 0.1143)
		(layer "B.Cu")
		(net "UPI_CPU0_CPU1_P1P1_DN<14>")
	)
	(segment
		(start 125.341634 -56.494934)
		(end 125.662944 -56.494934)
		(width 0.0889)
		(layer "B.Cu")
		(net "UPI_CPU0_CPU1_P1P1_DN<14>")
	)
	(segment
		(start 125.75667 -52.131468)
		(end 125.75667 -52.953158)
		(width 0.0889)
		(layer "B.Cu")
		(net "UPI_CPU0_CPU1_P1P1_DN<14>")
	)
	(segment
		(start 302.611536 -50.86477)
		(end 302.582326 -50.884836)
		(width 0.0889)
		(layer "B.Cu")
		(net "UPI_CPU0_CPU1_P1P1_DN<14>")
	)
	(segment
		(start 197.258686 -31.11881)
		(end 207.950816 -33.157922)
		(width 0.1143)
		(layer "B.Cu")
		(net "UPI_CPU0_CPU1_P1P1_DN<14>")
	)
	(segment
		(start 160.887156 -33.067244)
		(end 163.345876 -32.485076)
		(width 0.1143)
		(layer "B.Cu")
		(net "UPI_CPU0_CPU1_P1P1_DN<14>")
	)
	(segment
		(start 129.631948 -44.420536)
		(end 125.73127 -48.321214)
		(width 0.1143)
		(layer "B.Cu")
		(net "UPI_CPU0_CPU1_P1P1_DN<14>")
	)
	(segment
		(start 302.44288 -51.66106)
		(end 302.27778 -51.94808)
		(width 0.0889)
		(layer "B.Cu")
		(net "UPI_CPU0_CPU1_P1P1_DN<14>")
	)
	(segment
		(start 302.27778 -51.94808)
		(end 302.280066 -52.06492)
		(width 0.0889)
		(layer "B.Cu")
		(net "UPI_CPU0_CPU1_P1P1_DN<14>")
	)
	(segment
		(start 211.38515 -33.946084)
		(end 222.396812 -36.238434)
		(width 0.1143)
		(layer "B.Cu")
		(net "UPI_CPU0_CPU1_P1P1_DN<14>")
	)
	(segment
		(start 159.533082 -33.147762)
		(end 160.887156 -33.067244)
		(width 0.1143)
		(layer "B.Cu")
		(net "UPI_CPU0_CPU1_P1P1_DN<14>")
	)
	(segment
		(start 167.463724 -32.730694)
		(end 183.66486 -29.360114)
		(width 0.1143)
		(layer "B.Cu")
		(net "UPI_CPU0_CPU1_P1P1_DN<14>")
	)
	(segment
		(start 183.66486 -29.360114)
		(end 184.10682 -29.459936)
		(width 0.1143)
		(layer "B.Cu")
		(net "UPI_CPU0_CPU1_P1P1_DN<14>")
	)
	(segment
		(start 302.613314 -55.30977)
		(end 302.659542 -55.316628)
		(width 0.0889)
		(layer "B.Cu")
		(net "UPI_CPU0_CPU1_P1P1_DN<14>")
	)
	(segment
		(start 248.335038 -32.224726)
		(end 252.46076 -32.535114)
		(width 0.1143)
		(layer "B.Cu")
		(net "UPI_CPU0_CPU1_P1P1_DN<14>")
	)
	(segment
		(start 296.612056 -36.3982)
		(end 301.881032 -41.014904)
		(width 0.1143)
		(layer "B.Cu")
		(net "UPI_CPU0_CPU1_P1P1_DN<14>")
	)
	(segment
		(start 126.861824 -57.5818)
		(end 126.856998 -57.590436)
		(width 0.0889)
		(layer "B.Cu")
		(net "UPI_CPU0_CPU1_P1P1_DN<14>")
	)
	(segment
		(start 125.060202 -56.213502)
		(end 125.341634 -56.494934)
		(width 0.0889)
		(layer "B.Cu")
		(net "UPI_CPU0_CPU1_P1P1_DN<14>")
	)
	(segment
		(start 302.324516 -53.132736)
		(end 302.330866 -53.143404)
		(width 0.0889)
		(layer "B.Cu")
		(net "UPI_CPU0_CPU1_P1P1_DN<14>")
	)
	(segment
		(start 289.74796 -35.038792)
		(end 291.209984 -34.811716)
		(width 0.1143)
		(layer "B.Cu")
		(net "UPI_CPU0_CPU1_P1P1_DN<14>")
	)
	(segment
		(start 151.064214 -34.31159)
		(end 137.52703 -37.010594)
		(width 0.1143)
		(layer "B.Cu")
		(net "UPI_CPU0_CPU1_P1P1_DN<14>")
	)
	(segment
		(start 302.797972 -55.04053)
		(end 302.671226 -54.913784)
		(width 0.0889)
		(layer "B.Cu")
		(net "UPI_CPU0_CPU1_P1P1_DN<14>")
	)
	(segment
		(start 129.631948 -44.420028)
		(end 129.631948 -44.420536)
		(width 0.1143)
		(layer "B.Cu")
		(net "UPI_CPU0_CPU1_P1P1_DN<14>")
	)
	(segment
		(start 279.936956 -37.00145)
		(end 289.74796 -35.038792)
		(width 0.1143)
		(layer "B.Cu")
		(net "UPI_CPU0_CPU1_P1P1_DN<14>")
	)
	(segment
		(start 165.668706 -32.949642)
		(end 167.463724 -32.730694)
		(width 0.1143)
		(layer "B.Cu")
		(net "UPI_CPU0_CPU1_P1P1_DN<14>")
	)
	(segment
		(start 208.506314 -33.367726)
		(end 209.620612 -33.81756)
		(width 0.1143)
		(layer "B.Cu")
		(net "UPI_CPU0_CPU1_P1P1_DN<14>")
	)
	(segment
		(start 222.396812 -36.238434)
		(end 225.06559 -36.793932)
		(width 0.1143)
		(layer "B.Cu")
		(net "UPI_CPU0_CPU1_P1P1_DN<14>")
	)
	(segment
		(start 238.519208 -34.180018)
		(end 248.335038 -32.224726)
		(width 0.1143)
		(layer "B.Cu")
		(net "UPI_CPU0_CPU1_P1P1_DN<14>")
	)
	(segment
		(start 125.73127 -52.08397)
		(end 125.73127 -52.106068)
		(width 0.0889)
		(layer "B.Cu")
		(net "UPI_CPU0_CPU1_P1P1_DN<14>")
	)
	(segment
		(start 302.324516 -54.713886)
		(end 302.31969 -54.722522)
		(width 0.0889)
		(layer "B.Cu")
		(net "UPI_CPU0_CPU1_P1P1_DN<14>")
	)
	(segment
		(start 137.52703 -37.010594)
		(end 132.334 -40.513508)
		(width 0.1143)
		(layer "B.Cu")
		(net "UPI_CPU0_CPU1_P1P1_DN<14>")
	)
	(segment
		(start 184.10682 -29.459936)
		(end 189.59068 -31.21406)
		(width 0.1143)
		(layer "B.Cu")
		(net "UPI_CPU0_CPU1_P1P1_DN<14>")
	)
	(segment
		(start 252.46076 -32.535114)
		(end 256.321052 -32.277558)
		(width 0.1143)
		(layer "B.Cu")
		(net "UPI_CPU0_CPU1_P1P1_DN<14>")
	)
	(segment
		(start 296.48023 -36.28263)
		(end 296.612056 -36.3982)
		(width 0.1143)
		(layer "B.Cu")
		(net "UPI_CPU0_CPU1_P1P1_DN<14>")
	)
	(segment
		(start 236.874558 -34.40176)
		(end 237.43412 -34.464498)
		(width 0.1143)
		(layer "B.Cu")
		(net "UPI_CPU0_CPU1_P1P1_DN<14>")
	)
	(segment
		(start 225.06559 -36.793932)
		(end 225.293936 -36.848542)
		(width 0.1143)
		(layer "B.Cu")
		(net "UPI_CPU0_CPU1_P1P1_DN<14>")
	)
	(segment
		(start 189.59068 -31.21406)
		(end 196.250052 -30.949138)
		(width 0.1143)
		(layer "B.Cu")
		(net "UPI_CPU0_CPU1_P1P1_DN<14>")
	)
	(arc
		(start 126.525274 -56.990488)
		(mid 126.858192 -57.192479)
		(end 126.861824 -57.5818)
		(width 0.0889)
		(layer "B.Cu")
		(net "UPI_CPU0_CPU1_P1P1_DN<14>")
	)
	(arc
		(start 302.36414 -55.170324)
		(mid 302.475875 -55.263001)
		(end 302.613314 -55.30977)
		(width 0.0889)
		(layer "B.Cu")
		(net "UPI_CPU0_CPU1_P1P1_DN<14>")
	)
	(arc
		(start 302.659542 -55.316628)
		(mid 302.828373 -55.228524)
		(end 302.797972 -55.04053)
		(width 0.0889)
		(layer "B.Cu")
		(net "UPI_CPU0_CPU1_P1P1_DN<14>")
	)
	(arc
		(start 302.31969 -53.731922)
		(mid 302.270935 -53.928274)
		(end 302.324516 -54.123336)
		(width 0.0889)
		(layer "B.Cu")
		(net "UPI_CPU0_CPU1_P1P1_DN<14>")
	)
	(arc
		(start 125.662944 -56.494934)
		(mid 125.856794 -56.551284)
		(end 125.998478 -56.695086)
		(width 0.0889)
		(layer "B.Cu")
		(net "UPI_CPU0_CPU1_P1P1_DN<14>")
	)
	(arc
		(start 302.330866 -53.143404)
		(mid 302.403664 -53.434167)
		(end 302.324516 -53.723286)
		(width 0.0889)
		(layer "B.Cu")
		(net "UPI_CPU0_CPU1_P1P1_DN<14>")
	)
	(arc
		(start 302.324516 -54.123336)
		(mid 302.403738 -54.412454)
		(end 302.330866 -54.703218)
		(width 0.0889)
		(layer "B.Cu")
		(net "UPI_CPU0_CPU1_P1P1_DN<14>")
	)
	(arc
		(start 302.31969 -54.722522)
		(mid 302.272981 -54.953274)
		(end 302.36414 -55.170324)
		(width 0.0889)
		(layer "B.Cu")
		(net "UPI_CPU0_CPU1_P1P1_DN<14>")
	)
	(arc
		(start 126.850648 -57.601104)
		(mid 126.81521 -57.678208)
		(end 126.791212 -57.7596)
		(width 0.0889)
		(layer "B.Cu")
		(net "UPI_CPU0_CPU1_P1P1_DN<14>")
	)
	(arc
		(start 125.998478 -56.695086)
		(mid 126.207086 -56.907018)
		(end 126.492508 -56.990488)
		(width 0.0889)
		(layer "B.Cu")
		(net "UPI_CPU0_CPU1_P1P1_DN<14>")
	)
	(arc
		(start 302.324516 -52.142136)
		(mid 302.403647 -52.437538)
		(end 302.324516 -52.73294)
		(width 0.0889)
		(layer "B.Cu")
		(net "UPI_CPU0_CPU1_P1P1_DN<14>")
	)
	(arc
		(start 302.324516 -52.73294)
		(mid 302.271017 -52.932838)
		(end 302.324516 -53.132736)
		(width 0.0889)
		(layer "B.Cu")
		(net "UPI_CPU0_CPU1_P1P1_DN<14>")
	)
	(segment
		(start 128.514348 -59.866784)
		(end 129.085848 -59.866784)
		(width 0.1143)
		(layer "F.Cu")
		(net "UPI_CPU0_CPU1_P1P1_DN<13>")
	)
	(segment
		(start 300.382686 -55.904384)
		(end 300.954186 -55.904384)
		(width 0.1143)
		(layer "F.Cu")
		(net "UPI_CPU0_CPU1_P1P1_DN<13>")
	)
	(via
		(at 129.085848 -59.866784)
		(size 0.508)
		(drill 0.254)
		(layers "F.Cu" "B.Cu")
		(net "UPI_CPU0_CPU1_P1P1_DN<13>")
	)
	(via
		(at 300.954186 -55.904384)
		(size 0.508)
		(drill 0.254)
		(layers "F.Cu" "B.Cu")
		(net "UPI_CPU0_CPU1_P1P1_DN<13>")
	)
	(segment
		(start 163.610544 -33.777428)
		(end 166.099744 -34.275268)
		(width 0.1143)
		(layer "B.Cu")
		(net "UPI_CPU0_CPU1_P1P1_DN<13>")
	)
	(segment
		(start 187.843922 -31.92018)
		(end 189.553342 -32.508952)
		(width 0.1143)
		(layer "B.Cu")
		(net "UPI_CPU0_CPU1_P1P1_DN<13>")
	)
	(segment
		(start 256.28981 -33.503108)
		(end 279.937464 -38.233096)
		(width 0.1143)
		(layer "B.Cu")
		(net "UPI_CPU0_CPU1_P1P1_DN<13>")
	)
	(segment
		(start 299.763942 -41.03497)
		(end 299.771562 -41.17848)
		(width 0.1143)
		(layer "B.Cu")
		(net "UPI_CPU0_CPU1_P1P1_DN<13>")
	)
	(segment
		(start 128.245108 -58.780934)
		(end 128.209294 -58.780934)
		(width 0.0889)
		(layer "B.Cu")
		(net "UPI_CPU0_CPU1_P1P1_DN<13>")
	)
	(segment
		(start 126.531878 -55.809388)
		(end 126.499112 -55.809388)
		(width 0.0889)
		(layer "B.Cu")
		(net "UPI_CPU0_CPU1_P1P1_DN<13>")
	)
	(segment
		(start 301.300896 -53.723286)
		(end 301.305722 -53.731922)
		(width 0.0889)
		(layer "B.Cu")
		(net "UPI_CPU0_CPU1_P1P1_DN<13>")
	)
	(segment
		(start 150.958042 -35.853116)
		(end 153.286714 -35.358578)
		(width 0.1143)
		(layer "B.Cu")
		(net "UPI_CPU0_CPU1_P1P1_DN<13>")
	)
	(segment
		(start 300.531022 -42.197782)
		(end 300.449742 -42.3164)
		(width 0.1143)
		(layer "B.Cu")
		(net "UPI_CPU0_CPU1_P1P1_DN<13>")
	)
	(segment
		(start 299.10278 -40.440356)
		(end 299.1104 -40.583866)
		(width 0.1143)
		(layer "B.Cu")
		(net "UPI_CPU0_CPU1_P1P1_DN<13>")
	)
	(segment
		(start 301.438564 -50.719736)
		(end 301.256954 -51.168046)
		(width 0.0889)
		(layer "B.Cu")
		(net "UPI_CPU0_CPU1_P1P1_DN<13>")
	)
	(segment
		(start 127.192024 -53.493924)
		(end 127.192024 -53.144166)
		(width 0.0889)
		(layer "B.Cu")
		(net "UPI_CPU0_CPU1_P1P1_DN<13>")
	)
	(segment
		(start 166.244016 -34.246566)
		(end 169.085006 -33.756092)
		(width 0.1143)
		(layer "B.Cu")
		(net "UPI_CPU0_CPU1_P1P1_DN<13>")
	)
	(segment
		(start 207.878934 -34.297112)
		(end 209.66303 -35.027108)
		(width 0.1143)
		(layer "B.Cu")
		(net "UPI_CPU0_CPU1_P1P1_DN<13>")
	)
	(segment
		(start 300.631606 -42.734738)
		(end 300.694344 -43.071796)
		(width 0.1143)
		(layer "B.Cu")
		(net "UPI_CPU0_CPU1_P1P1_DN<13>")
	)
	(segment
		(start 155.101798 -35.713416)
		(end 157.47238 -35.438842)
		(width 0.1143)
		(layer "B.Cu")
		(net "UPI_CPU0_CPU1_P1P1_DN<13>")
	)
	(segment
		(start 153.286714 -35.358578)
		(end 155.101798 -35.713416)
		(width 0.1143)
		(layer "B.Cu")
		(net "UPI_CPU0_CPU1_P1P1_DN<13>")
	)
	(segment
		(start 300.794928 -43.608752)
		(end 300.857666 -43.94581)
		(width 0.1143)
		(layer "B.Cu")
		(net "UPI_CPU0_CPU1_P1P1_DN<13>")
	)
	(segment
		(start 183.639714 -30.612842)
		(end 187.843922 -31.92018)
		(width 0.1143)
		(layer "B.Cu")
		(net "UPI_CPU0_CPU1_P1P1_DN<13>")
	)
	(segment
		(start 252.62967 -33.814766)
		(end 256.28981 -33.503108)
		(width 0.1143)
		(layer "B.Cu")
		(net "UPI_CPU0_CPU1_P1P1_DN<13>")
	)
	(segment
		(start 301.0027 -45.275754)
		(end 301.121572 -45.35678)
		(width 0.1143)
		(layer "B.Cu")
		(net "UPI_CPU0_CPU1_P1P1_DN<13>")
	)
	(segment
		(start 301.551594 -50.110898)
		(end 301.551848 -50.110898)
		(width 0.0889)
		(layer "B.Cu")
		(net "UPI_CPU0_CPU1_P1P1_DN<13>")
	)
	(segment
		(start 301.448216 -47.104808)
		(end 301.674276 -48.31588)
		(width 0.1143)
		(layer "B.Cu")
		(net "UPI_CPU0_CPU1_P1P1_DN<13>")
	)
	(segment
		(start 301.166022 -46.149768)
		(end 301.284894 -46.230794)
		(width 0.1143)
		(layer "B.Cu")
		(net "UPI_CPU0_CPU1_P1P1_DN<13>")
	)
	(segment
		(start 301.18431 -45.693838)
		(end 301.10303 -45.812456)
		(width 0.1143)
		(layer "B.Cu")
		(net "UPI_CPU0_CPU1_P1P1_DN<13>")
	)
	(segment
		(start 127.886968 -57.601104)
		(end 127.880618 -57.590436)
		(width 0.0889)
		(layer "B.Cu")
		(net "UPI_CPU0_CPU1_P1P1_DN<13>")
	)
	(segment
		(start 300.170342 -41.400476)
		(end 300.425104 -41.629584)
		(width 0.1143)
		(layer "B.Cu")
		(net "UPI_CPU0_CPU1_P1P1_DN<13>")
	)
	(segment
		(start 301.121572 -45.35678)
		(end 301.18431 -45.693838)
		(width 0.1143)
		(layer "B.Cu")
		(net "UPI_CPU0_CPU1_P1P1_DN<13>")
	)
	(segment
		(start 237.961932 -35.603688)
		(end 238.509048 -35.23869)
		(width 0.1143)
		(layer "B.Cu")
		(net "UPI_CPU0_CPU1_P1P1_DN<13>")
	)
	(segment
		(start 301.266352 -46.68647)
		(end 301.329344 -47.023782)
		(width 0.1143)
		(layer "B.Cu")
		(net "UPI_CPU0_CPU1_P1P1_DN<13>")
	)
	(segment
		(start 301.551848 -50.11039)
		(end 301.551594 -50.110898)
		(width 0.0889)
		(layer "B.Cu")
		(net "UPI_CPU0_CPU1_P1P1_DN<13>")
	)
	(segment
		(start 300.694344 -43.071796)
		(end 300.613064 -43.190414)
		(width 0.1143)
		(layer "B.Cu")
		(net "UPI_CPU0_CPU1_P1P1_DN<13>")
	)
	(segment
		(start 133.115558 -41.783)
		(end 138.386566 -38.227762)
		(width 0.1143)
		(layer "B.Cu")
		(net "UPI_CPU0_CPU1_P1P1_DN<13>")
	)
	(segment
		(start 300.026832 -41.408096)
		(end 300.170342 -41.400476)
		(width 0.1143)
		(layer "B.Cu")
		(net "UPI_CPU0_CPU1_P1P1_DN<13>")
	)
	(segment
		(start 129.085848 -59.866784)
		(end 128.792732 -60.035948)
		(width 0.0889)
		(layer "B.Cu")
		(net "UPI_CPU0_CPU1_P1P1_DN<13>")
	)
	(segment
		(start 127.156972 -52.173378)
		(end 127.156972 -48.819054)
		(width 0.1143)
		(layer "B.Cu")
		(net "UPI_CPU0_CPU1_P1P1_DN<13>")
	)
	(segment
		(start 300.512734 -42.653712)
		(end 300.631606 -42.734738)
		(width 0.1143)
		(layer "B.Cu")
		(net "UPI_CPU0_CPU1_P1P1_DN<13>")
	)
	(segment
		(start 166.099744 -34.275268)
		(end 166.244016 -34.246566)
		(width 0.1143)
		(layer "B.Cu")
		(net "UPI_CPU0_CPU1_P1P1_DN<13>")
	)
	(segment
		(start 160.068514 -34.485326)
		(end 163.610544 -33.777428)
		(width 0.1143)
		(layer "B.Cu")
		(net "UPI_CPU0_CPU1_P1P1_DN<13>")
	)
	(segment
		(start 127.156972 -48.819054)
		(end 130.882136 -45.09389)
		(width 0.1143)
		(layer "B.Cu")
		(net "UPI_CPU0_CPU1_P1P1_DN<13>")
	)
	(segment
		(start 127.131572 -52.594002)
		(end 127.131572 -52.220876)
		(width 0.0889)
		(layer "B.Cu")
		(net "UPI_CPU0_CPU1_P1P1_DN<13>")
	)
	(segment
		(start 159.497776 -34.52622)
		(end 160.068514 -34.485326)
		(width 0.1143)
		(layer "B.Cu")
		(net "UPI_CPU0_CPU1_P1P1_DN<13>")
	)
	(segment
		(start 170.937682 -33.489392)
		(end 172.867828 -33.42767)
		(width 0.1143)
		(layer "B.Cu")
		(net "UPI_CPU0_CPU1_P1P1_DN<13>")
	)
	(segment
		(start 301.530512 -50.061368)
		(end 301.528734 -50.083466)
		(width 0.0889)
		(layer "B.Cu")
		(net "UPI_CPU0_CPU1_P1P1_DN<13>")
	)
	(segment
		(start 211.199222 -35.293554)
		(end 225.356928 -38.124638)
		(width 0.1143)
		(layer "B.Cu")
		(net "UPI_CPU0_CPU1_P1P1_DN<13>")
	)
	(segment
		(start 301.10303 -45.812456)
		(end 301.166022 -46.149768)
		(width 0.1143)
		(layer "B.Cu")
		(net "UPI_CPU0_CPU1_P1P1_DN<13>")
	)
	(segment
		(start 300.776386 -44.064428)
		(end 300.839378 -44.40174)
		(width 0.1143)
		(layer "B.Cu")
		(net "UPI_CPU0_CPU1_P1P1_DN<13>")
	)
	(segment
		(start 301.284894 -46.230794)
		(end 301.347632 -46.567852)
		(width 0.1143)
		(layer "B.Cu")
		(net "UPI_CPU0_CPU1_P1P1_DN<13>")
	)
	(segment
		(start 127.192024 -53.144166)
		(end 127.131572 -52.594002)
		(width 0.0889)
		(layer "B.Cu")
		(net "UPI_CPU0_CPU1_P1P1_DN<13>")
	)
	(segment
		(start 225.356928 -38.124638)
		(end 237.961932 -35.603688)
		(width 0.1143)
		(layer "B.Cu")
		(net "UPI_CPU0_CPU1_P1P1_DN<13>")
	)
	(segment
		(start 299.1104 -40.583866)
		(end 299.36567 -40.813228)
		(width 0.1143)
		(layer "B.Cu")
		(net "UPI_CPU0_CPU1_P1P1_DN<13>")
	)
	(segment
		(start 301.551848 -50.110898)
		(end 301.532036 -50.351182)
		(width 0.0889)
		(layer "B.Cu")
		(net "UPI_CPU0_CPU1_P1P1_DN<13>")
	)
	(segment
		(start 301.528734 -50.083466)
		(end 301.551848 -50.11039)
		(width 0.0889)
		(layer "B.Cu")
		(net "UPI_CPU0_CPU1_P1P1_DN<13>")
	)
	(segment
		(start 301.300896 -54.713886)
		(end 301.305722 -54.722522)
		(width 0.0889)
		(layer "B.Cu")
		(net "UPI_CPU0_CPU1_P1P1_DN<13>")
	)
	(segment
		(start 127.050292 -53.677312)
		(end 127.192024 -53.493924)
		(width 0.0889)
		(layer "B.Cu")
		(net "UPI_CPU0_CPU1_P1P1_DN<13>")
	)
	(segment
		(start 300.839378 -44.40174)
		(end 300.95825 -44.482766)
		(width 0.1143)
		(layer "B.Cu")
		(net "UPI_CPU0_CPU1_P1P1_DN<13>")
	)
	(segment
		(start 128.734312 -59.675522)
		(end 128.739138 -59.666886)
		(width 0.0889)
		(layer "B.Cu")
		(net "UPI_CPU0_CPU1_P1P1_DN<13>")
	)
	(segment
		(start 172.867828 -33.42767)
		(end 183.639714 -30.612842)
		(width 0.1143)
		(layer "B.Cu")
		(net "UPI_CPU0_CPU1_P1P1_DN<13>")
	)
	(segment
		(start 127.131572 -52.220876)
		(end 127.156972 -52.195476)
		(width 0.0889)
		(layer "B.Cu")
		(net "UPI_CPU0_CPU1_P1P1_DN<13>")
	)
	(segment
		(start 300.939708 -44.938442)
		(end 301.0027 -45.275754)
		(width 0.1143)
		(layer "B.Cu")
		(net "UPI_CPU0_CPU1_P1P1_DN<13>")
	)
	(segment
		(start 301.300896 -53.132736)
		(end 301.294546 -53.143404)
		(width 0.0889)
		(layer "B.Cu")
		(net "UPI_CPU0_CPU1_P1P1_DN<13>")
	)
	(segment
		(start 299.50918 -40.805862)
		(end 299.763942 -41.03497)
		(width 0.1143)
		(layer "B.Cu")
		(net "UPI_CPU0_CPU1_P1P1_DN<13>")
	)
	(segment
		(start 300.613064 -43.190414)
		(end 300.676056 -43.527726)
		(width 0.1143)
		(layer "B.Cu")
		(net "UPI_CPU0_CPU1_P1P1_DN<13>")
	)
	(segment
		(start 300.425104 -41.629584)
		(end 300.531022 -42.197782)
		(width 0.1143)
		(layer "B.Cu")
		(net "UPI_CPU0_CPU1_P1P1_DN<13>")
	)
	(segment
		(start 300.857666 -43.94581)
		(end 300.776386 -44.064428)
		(width 0.1143)
		(layer "B.Cu")
		(net "UPI_CPU0_CPU1_P1P1_DN<13>")
	)
	(segment
		(start 300.676056 -43.527726)
		(end 300.794928 -43.608752)
		(width 0.1143)
		(layer "B.Cu")
		(net "UPI_CPU0_CPU1_P1P1_DN<13>")
	)
	(segment
		(start 301.329344 -47.023782)
		(end 301.448216 -47.104808)
		(width 0.1143)
		(layer "B.Cu")
		(net "UPI_CPU0_CPU1_P1P1_DN<13>")
	)
	(segment
		(start 238.509048 -35.23869)
		(end 248.287794 -33.28289)
		(width 0.1143)
		(layer "B.Cu")
		(net "UPI_CPU0_CPU1_P1P1_DN<13>")
	)
	(segment
		(start 128.792732 -60.035948)
		(end 128.713992 -60.014612)
		(width 0.0889)
		(layer "B.Cu")
		(net "UPI_CPU0_CPU1_P1P1_DN<13>")
	)
	(segment
		(start 127.156972 -52.195476)
		(end 127.156972 -52.173378)
		(width 0.0889)
		(layer "B.Cu")
		(net "UPI_CPU0_CPU1_P1P1_DN<13>")
	)
	(segment
		(start 299.771562 -41.17848)
		(end 300.026832 -41.408096)
		(width 0.1143)
		(layer "B.Cu")
		(net "UPI_CPU0_CPU1_P1P1_DN<13>")
	)
	(segment
		(start 127.022098 -54.123336)
		(end 127.002032 -54.088538)
		(width 0.0889)
		(layer "B.Cu")
		(net "UPI_CPU0_CPU1_P1P1_DN<13>")
	)
	(segment
		(start 291.26561 -35.966908)
		(end 295.524428 -37.22116)
		(width 0.1143)
		(layer "B.Cu")
		(net "UPI_CPU0_CPU1_P1P1_DN<13>")
	)
	(segment
		(start 301.30115 -52.141882)
		(end 301.300896 -52.142136)
		(width 0.0889)
		(layer "B.Cu")
		(net "UPI_CPU0_CPU1_P1P1_DN<13>")
	)
	(segment
		(start 300.449742 -42.3164)
		(end 300.512734 -42.653712)
		(width 0.1143)
		(layer "B.Cu")
		(net "UPI_CPU0_CPU1_P1P1_DN<13>")
	)
	(segment
		(start 301.347632 -46.567852)
		(end 301.266352 -46.68647)
		(width 0.1143)
		(layer "B.Cu")
		(net "UPI_CPU0_CPU1_P1P1_DN<13>")
	)
	(segment
		(start 127.386588 -56.304434)
		(end 127.353822 -56.304434)
		(width 0.0889)
		(layer "B.Cu")
		(net "UPI_CPU0_CPU1_P1P1_DN<13>")
	)
	(segment
		(start 126.495302 -55.009288)
		(end 126.528068 -55.009288)
		(width 0.0889)
		(layer "B.Cu")
		(net "UPI_CPU0_CPU1_P1P1_DN<13>")
	)
	(segment
		(start 295.524428 -37.22116)
		(end 299.10278 -40.440356)
		(width 0.1143)
		(layer "B.Cu")
		(net "UPI_CPU0_CPU1_P1P1_DN<13>")
	)
	(segment
		(start 301.532036 -50.351182)
		(end 301.438564 -50.719736)
		(width 0.0889)
		(layer "B.Cu")
		(net "UPI_CPU0_CPU1_P1P1_DN<13>")
	)
	(segment
		(start 301.071026 -55.787544)
		(end 300.954186 -55.904384)
		(width 0.0889)
		(layer "B.Cu")
		(net "UPI_CPU0_CPU1_P1P1_DN<13>")
	)
	(segment
		(start 300.95825 -44.482766)
		(end 301.020988 -44.819824)
		(width 0.1143)
		(layer "B.Cu")
		(net "UPI_CPU0_CPU1_P1P1_DN<13>")
	)
	(segment
		(start 301.674276 -48.31588)
		(end 301.530512 -50.061368)
		(width 0.1143)
		(layer "B.Cu")
		(net "UPI_CPU0_CPU1_P1P1_DN<13>")
	)
	(segment
		(start 127.880618 -57.590436)
		(end 127.875792 -57.5818)
		(width 0.0889)
		(layer "B.Cu")
		(net "UPI_CPU0_CPU1_P1P1_DN<13>")
	)
	(segment
		(start 301.020988 -44.819824)
		(end 300.939708 -44.938442)
		(width 0.1143)
		(layer "B.Cu")
		(net "UPI_CPU0_CPU1_P1P1_DN<13>")
	)
	(segment
		(start 279.937464 -38.233096)
		(end 291.26561 -35.966908)
		(width 0.1143)
		(layer "B.Cu")
		(net "UPI_CPU0_CPU1_P1P1_DN<13>")
	)
	(segment
		(start 301.336964 -52.079906)
		(end 301.30115 -52.141882)
		(width 0.0889)
		(layer "B.Cu")
		(net "UPI_CPU0_CPU1_P1P1_DN<13>")
	)
	(segment
		(start 196.60489 -32.042608)
		(end 207.878934 -34.297112)
		(width 0.1143)
		(layer "B.Cu")
		(net "UPI_CPU0_CPU1_P1P1_DN<13>")
	)
	(segment
		(start 138.386566 -38.227762)
		(end 150.958042 -35.853116)
		(width 0.1143)
		(layer "B.Cu")
		(net "UPI_CPU0_CPU1_P1P1_DN<13>")
	)
	(segment
		(start 301.294546 -54.703218)
		(end 301.300896 -54.713886)
		(width 0.0889)
		(layer "B.Cu")
		(net "UPI_CPU0_CPU1_P1P1_DN<13>")
	)
	(segment
		(start 299.36567 -40.813228)
		(end 299.50918 -40.805862)
		(width 0.1143)
		(layer "B.Cu")
		(net "UPI_CPU0_CPU1_P1P1_DN<13>")
	)
	(segment
		(start 130.882136 -45.09389)
		(end 133.115558 -41.783)
		(width 0.1143)
		(layer "B.Cu")
		(net "UPI_CPU0_CPU1_P1P1_DN<13>")
	)
	(segment
		(start 189.553342 -32.508952)
		(end 196.60489 -32.042608)
		(width 0.1143)
		(layer "B.Cu")
		(net "UPI_CPU0_CPU1_P1P1_DN<13>")
	)
	(segment
		(start 169.085006 -33.756092)
		(end 170.937682 -33.489392)
		(width 0.1143)
		(layer "B.Cu")
		(net "UPI_CPU0_CPU1_P1P1_DN<13>")
	)
	(segment
		(start 248.287794 -33.28289)
		(end 252.62967 -33.814766)
		(width 0.1143)
		(layer "B.Cu")
		(net "UPI_CPU0_CPU1_P1P1_DN<13>")
	)
	(segment
		(start 209.66303 -35.027108)
		(end 211.199222 -35.293554)
		(width 0.1143)
		(layer "B.Cu")
		(net "UPI_CPU0_CPU1_P1P1_DN<13>")
	)
	(segment
		(start 157.47238 -35.438842)
		(end 159.497776 -34.52622)
		(width 0.1143)
		(layer "B.Cu")
		(net "UPI_CPU0_CPU1_P1P1_DN<13>")
	)
	(arc
		(start 301.300896 -55.113936)
		(mid 301.240123 -55.263187)
		(end 301.221902 -55.423308)
		(width 0.0889)
		(layer "B.Cu")
		(net "UPI_CPU0_CPU1_P1P1_DN<13>")
	)
	(arc
		(start 127.002032 -54.088538)
		(mid 126.969228 -53.87625)
		(end 127.050292 -53.677312)
		(width 0.0889)
		(layer "B.Cu")
		(net "UPI_CPU0_CPU1_P1P1_DN<13>")
	)
	(arc
		(start 301.300896 -52.142136)
		(mid 301.221765 -52.437538)
		(end 301.300896 -52.73294)
		(width 0.0889)
		(layer "B.Cu")
		(net "UPI_CPU0_CPU1_P1P1_DN<13>")
	)
	(arc
		(start 301.301912 -51.731164)
		(mid 301.358922 -51.901566)
		(end 301.336964 -52.079906)
		(width 0.0889)
		(layer "B.Cu")
		(net "UPI_CPU0_CPU1_P1P1_DN<13>")
	)
	(arc
		(start 301.305722 -53.731922)
		(mid 301.354477 -53.928274)
		(end 301.300896 -54.123336)
		(width 0.0889)
		(layer "B.Cu")
		(net "UPI_CPU0_CPU1_P1P1_DN<13>")
	)
	(arc
		(start 127.353822 -56.304434)
		(mid 127.16218 -56.247268)
		(end 127.022098 -56.104536)
		(width 0.0889)
		(layer "B.Cu")
		(net "UPI_CPU0_CPU1_P1P1_DN<13>")
	)
	(arc
		(start 301.305722 -54.722522)
		(mid 301.354477 -54.918874)
		(end 301.300896 -55.113936)
		(width 0.0889)
		(layer "B.Cu")
		(net "UPI_CPU0_CPU1_P1P1_DN<13>")
	)
	(arc
		(start 126.499112 -55.809388)
		(mid 126.110086 -55.411242)
		(end 126.495302 -55.009288)
		(width 0.0889)
		(layer "B.Cu")
		(net "UPI_CPU0_CPU1_P1P1_DN<13>")
	)
	(arc
		(start 301.294546 -53.143404)
		(mid 301.221748 -53.434167)
		(end 301.300896 -53.723286)
		(width 0.0889)
		(layer "B.Cu")
		(net "UPI_CPU0_CPU1_P1P1_DN<13>")
	)
	(arc
		(start 301.300896 -54.123336)
		(mid 301.221674 -54.412454)
		(end 301.294546 -54.703218)
		(width 0.0889)
		(layer "B.Cu")
		(net "UPI_CPU0_CPU1_P1P1_DN<13>")
	)
	(arc
		(start 128.739138 -59.666886)
		(mid 128.743467 -59.083714)
		(end 128.245108 -58.780934)
		(width 0.0889)
		(layer "B.Cu")
		(net "UPI_CPU0_CPU1_P1P1_DN<13>")
	)
	(arc
		(start 128.704848 -59.744102)
		(mid 128.717988 -59.709128)
		(end 128.734312 -59.675522)
		(width 0.0889)
		(layer "B.Cu")
		(net "UPI_CPU0_CPU1_P1P1_DN<13>")
	)
	(arc
		(start 127.875792 -57.5818)
		(mid 127.827037 -57.385448)
		(end 127.880618 -57.190386)
		(width 0.0889)
		(layer "B.Cu")
		(net "UPI_CPU0_CPU1_P1P1_DN<13>")
	)
	(arc
		(start 128.209294 -58.780934)
		(mid 127.876325 -58.573386)
		(end 127.880618 -58.180986)
		(width 0.0889)
		(layer "B.Cu")
		(net "UPI_CPU0_CPU1_P1P1_DN<13>")
	)
	(arc
		(start 127.880618 -57.190386)
		(mid 127.884947 -56.607214)
		(end 127.386588 -56.304434)
		(width 0.0889)
		(layer "B.Cu")
		(net "UPI_CPU0_CPU1_P1P1_DN<13>")
	)
	(arc
		(start 126.528068 -55.009288)
		(mid 127.026319 -54.706448)
		(end 127.022098 -54.123336)
		(width 0.0889)
		(layer "B.Cu")
		(net "UPI_CPU0_CPU1_P1P1_DN<13>")
	)
	(arc
		(start 127.880618 -58.180986)
		(mid 127.95984 -57.891868)
		(end 127.886968 -57.601104)
		(width 0.0889)
		(layer "B.Cu")
		(net "UPI_CPU0_CPU1_P1P1_DN<13>")
	)
	(arc
		(start 128.713992 -60.014612)
		(mid 128.685841 -59.880148)
		(end 128.704848 -59.744102)
		(width 0.0889)
		(layer "B.Cu")
		(net "UPI_CPU0_CPU1_P1P1_DN<13>")
	)
	(arc
		(start 301.256954 -51.168046)
		(mid 301.212757 -51.454923)
		(end 301.301912 -51.731164)
		(width 0.0889)
		(layer "B.Cu")
		(net "UPI_CPU0_CPU1_P1P1_DN<13>")
	)
	(arc
		(start 301.300896 -52.73294)
		(mid 301.354395 -52.932838)
		(end 301.300896 -53.132736)
		(width 0.0889)
		(layer "B.Cu")
		(net "UPI_CPU0_CPU1_P1P1_DN<13>")
	)
	(arc
		(start 127.022098 -56.104536)
		(mid 126.815094 -55.893672)
		(end 126.531878 -55.809388)
		(width 0.0889)
		(layer "B.Cu")
		(net "UPI_CPU0_CPU1_P1P1_DN<13>")
	)
	(arc
		(start 301.221902 -55.423308)
		(mid 301.182691 -55.620433)
		(end 301.071026 -55.787544)
		(width 0.0889)
		(layer "B.Cu")
		(net "UPI_CPU0_CPU1_P1P1_DN<13>")
	)
	(segment
		(start 129.372868 -60.362338)
		(end 129.944368 -60.362338)
		(width 0.1143)
		(layer "F.Cu")
		(net "UPI_CPU0_CPU1_P1P1_DN<12>")
	)
	(segment
		(start 300.382686 -52.932838)
		(end 300.954186 -52.932838)
		(width 0.1143)
		(layer "F.Cu")
		(net "UPI_CPU0_CPU1_P1P1_DN<12>")
	)
	(via
		(at 300.954186 -52.932838)
		(size 0.508)
		(drill 0.254)
		(layers "F.Cu" "B.Cu")
		(net "UPI_CPU0_CPU1_P1P1_DN<12>")
	)
	(via
		(at 129.944368 -60.362338)
		(size 0.508)
		(drill 0.254)
		(layers "F.Cu" "B.Cu")
		(net "UPI_CPU0_CPU1_P1P1_DN<12>")
	)
	(segment
		(start 127.715518 -54.713886)
		(end 127.720344 -54.722522)
		(width 0.0889)
		(layer "B.Cu")
		(net "UPI_CPU0_CPU1_P1P1_DN<12>")
	)
	(segment
		(start 300.686216 -51.3334)
		(end 300.780196 -51.23942)
		(width 0.0889)
		(layer "B.Cu")
		(net "UPI_CPU0_CPU1_P1P1_DN<12>")
	)
	(segment
		(start 128.066546 -49.13757)
		(end 128.066546 -52.442872)
		(width 0.1143)
		(layer "B.Cu")
		(net "UPI_CPU0_CPU1_P1P1_DN<12>")
	)
	(segment
		(start 300.710092 -50.139854)
		(end 300.710092 -50.090832)
		(width 0.1143)
		(layer "B.Cu")
		(net "UPI_CPU0_CPU1_P1P1_DN<12>")
	)
	(segment
		(start 127.708914 -54.702202)
		(end 127.713994 -54.7116)
		(width 0.0889)
		(layer "B.Cu")
		(net "UPI_CPU0_CPU1_P1P1_DN<12>")
	)
	(segment
		(start 300.686216 -50.546)
		(end 300.686216 -50.340006)
		(width 0.0889)
		(layer "B.Cu")
		(net "UPI_CPU0_CPU1_P1P1_DN<12>")
	)
	(segment
		(start 127.713994 -54.7116)
		(end 127.715518 -54.713886)
		(width 0.0889)
		(layer "B.Cu")
		(net "UPI_CPU0_CPU1_P1P1_DN<12>")
	)
	(segment
		(start 294.947086 -37.701728)
		(end 291.505132 -36.665408)
		(width 0.1143)
		(layer "B.Cu")
		(net "UPI_CPU0_CPU1_P1P1_DN<12>")
	)
	(segment
		(start 155.90901 -36.62045)
		(end 153.640028 -36.180268)
		(width 0.1143)
		(layer "B.Cu")
		(net "UPI_CPU0_CPU1_P1P1_DN<12>")
	)
	(segment
		(start 225.664014 -38.928802)
		(end 222.396812 -38.27526)
		(width 0.1143)
		(layer "B.Cu")
		(net "UPI_CPU0_CPU1_P1P1_DN<12>")
	)
	(segment
		(start 153.640028 -36.180268)
		(end 138.676888 -39.14775)
		(width 0.1143)
		(layer "B.Cu")
		(net "UPI_CPU0_CPU1_P1P1_DN<12>")
	)
	(segment
		(start 209.756502 -35.899852)
		(end 206.92872 -34.658808)
		(width 0.1143)
		(layer "B.Cu")
		(net "UPI_CPU0_CPU1_P1P1_DN<12>")
	)
	(segment
		(start 286.890714 -37.588444)
		(end 286.88919 -37.588698)
		(width 0.1143)
		(layer "B.Cu")
		(net "UPI_CPU0_CPU1_P1P1_DN<12>")
	)
	(segment
		(start 253.143766 -34.609278)
		(end 248.216166 -33.836102)
		(width 0.1143)
		(layer "B.Cu")
		(net "UPI_CPU0_CPU1_P1P1_DN<12>")
	)
	(segment
		(start 128.578864 -56.5912)
		(end 128.574038 -56.599836)
		(width 0.0889)
		(layer "B.Cu")
		(net "UPI_CPU0_CPU1_P1P1_DN<12>")
	)
	(segment
		(start 133.69417 -42.508424)
		(end 131.617466 -45.586904)
		(width 0.1143)
		(layer "B.Cu")
		(net "UPI_CPU0_CPU1_P1P1_DN<12>")
	)
	(segment
		(start 206.92872 -34.658808)
		(end 196.779642 -32.629094)
		(width 0.1143)
		(layer "B.Cu")
		(net "UPI_CPU0_CPU1_P1P1_DN<12>")
	)
	(segment
		(start 279.953974 -38.975792)
		(end 256.394458 -34.26333)
		(width 0.1143)
		(layer "B.Cu")
		(net "UPI_CPU0_CPU1_P1P1_DN<12>")
	)
	(segment
		(start 286.88919 -37.588698)
		(end 279.953974 -38.975792)
		(width 0.1143)
		(layer "B.Cu")
		(net "UPI_CPU0_CPU1_P1P1_DN<12>")
	)
	(segment
		(start 300.775624 -50.786792)
		(end 300.775624 -50.635408)
		(width 0.0889)
		(layer "B.Cu")
		(net "UPI_CPU0_CPU1_P1P1_DN<12>")
	)
	(segment
		(start 131.617466 -45.586904)
		(end 128.066546 -49.13757)
		(width 0.1143)
		(layer "B.Cu")
		(net "UPI_CPU0_CPU1_P1P1_DN<12>")
	)
	(segment
		(start 211.016342 -35.998912)
		(end 210.98002 -35.993324)
		(width 0.1143)
		(layer "B.Cu")
		(net "UPI_CPU0_CPU1_P1P1_DN<12>")
	)
	(segment
		(start 210.98002 -35.993324)
		(end 209.756502 -35.899852)
		(width 0.1143)
		(layer "B.Cu")
		(net "UPI_CPU0_CPU1_P1P1_DN<12>")
	)
	(segment
		(start 127.802894 -53.020722)
		(end 127.802894 -53.972206)
		(width 0.0889)
		(layer "B.Cu")
		(net "UPI_CPU0_CPU1_P1P1_DN<12>")
	)
	(segment
		(start 300.686216 -50.340006)
		(end 300.684692 -50.187352)
		(width 0.0889)
		(layer "B.Cu")
		(net "UPI_CPU0_CPU1_P1P1_DN<12>")
	)
	(segment
		(start 128.574038 -56.599836)
		(end 128.567688 -56.610504)
		(width 0.0889)
		(layer "B.Cu")
		(net "UPI_CPU0_CPU1_P1P1_DN<12>")
	)
	(segment
		(start 256.394458 -34.26333)
		(end 253.143766 -34.609278)
		(width 0.1143)
		(layer "B.Cu")
		(net "UPI_CPU0_CPU1_P1P1_DN<12>")
	)
	(segment
		(start 128.066546 -52.442872)
		(end 128.066546 -52.46497)
		(width 0.0889)
		(layer "B.Cu")
		(net "UPI_CPU0_CPU1_P1P1_DN<12>")
	)
	(segment
		(start 238.988346 -35.681666)
		(end 237.740952 -36.513008)
		(width 0.1143)
		(layer "B.Cu")
		(net "UPI_CPU0_CPU1_P1P1_DN<12>")
	)
	(segment
		(start 300.954186 -52.932838)
		(end 300.954186 -53.270912)
		(width 0.0889)
		(layer "B.Cu")
		(net "UPI_CPU0_CPU1_P1P1_DN<12>")
	)
	(segment
		(start 156.667708 -36.54679)
		(end 155.90901 -36.62045)
		(width 0.1143)
		(layer "B.Cu")
		(net "UPI_CPU0_CPU1_P1P1_DN<12>")
	)
	(segment
		(start 300.684692 -50.187352)
		(end 300.710092 -50.161952)
		(width 0.0889)
		(layer "B.Cu")
		(net "UPI_CPU0_CPU1_P1P1_DN<12>")
	)
	(segment
		(start 300.775624 -50.635408)
		(end 300.686216 -50.546)
		(width 0.0889)
		(layer "B.Cu")
		(net "UPI_CPU0_CPU1_P1P1_DN<12>")
	)
	(segment
		(start 300.706028 -48.12411)
		(end 299.173646 -42.249598)
		(width 0.1143)
		(layer "B.Cu")
		(net "UPI_CPU0_CPU1_P1P1_DN<12>")
	)
	(segment
		(start 166.262812 -35.076384)
		(end 163.63188 -34.549842)
		(width 0.1143)
		(layer "B.Cu")
		(net "UPI_CPU0_CPU1_P1P1_DN<12>")
	)
	(segment
		(start 129.072894 -58.476388)
		(end 129.097024 -58.476388)
		(width 0.0889)
		(layer "B.Cu")
		(net "UPI_CPU0_CPU1_P1P1_DN<12>")
	)
	(segment
		(start 300.780196 -51.09718)
		(end 300.686216 -51.0032)
		(width 0.0889)
		(layer "B.Cu")
		(net "UPI_CPU0_CPU1_P1P1_DN<12>")
	)
	(segment
		(start 300.686216 -50.8762)
		(end 300.775624 -50.786792)
		(width 0.0889)
		(layer "B.Cu")
		(net "UPI_CPU0_CPU1_P1P1_DN<12>")
	)
	(segment
		(start 159.692594 -35.32124)
		(end 156.667708 -36.54679)
		(width 0.1143)
		(layer "B.Cu")
		(net "UPI_CPU0_CPU1_P1P1_DN<12>")
	)
	(segment
		(start 127.802894 -53.972206)
		(end 127.715518 -54.123336)
		(width 0.0889)
		(layer "B.Cu")
		(net "UPI_CPU0_CPU1_P1P1_DN<12>")
	)
	(segment
		(start 128.066546 -52.46497)
		(end 128.091946 -52.49037)
		(width 0.0889)
		(layer "B.Cu")
		(net "UPI_CPU0_CPU1_P1P1_DN<12>")
	)
	(segment
		(start 300.60265 -51.750722)
		(end 300.607476 -51.742086)
		(width 0.0889)
		(layer "B.Cu")
		(net "UPI_CPU0_CPU1_P1P1_DN<12>")
	)
	(segment
		(start 299.173646 -42.249598)
		(end 294.947086 -37.701728)
		(width 0.1143)
		(layer "B.Cu")
		(net "UPI_CPU0_CPU1_P1P1_DN<12>")
	)
	(segment
		(start 128.091946 -52.73167)
		(end 127.802894 -53.020722)
		(width 0.0889)
		(layer "B.Cu")
		(net "UPI_CPU0_CPU1_P1P1_DN<12>")
	)
	(segment
		(start 286.893 -37.587936)
		(end 286.890714 -37.588444)
		(width 0.1143)
		(layer "B.Cu")
		(net "UPI_CPU0_CPU1_P1P1_DN<12>")
	)
	(segment
		(start 237.740952 -36.513008)
		(end 225.664014 -38.928802)
		(width 0.1143)
		(layer "B.Cu")
		(net "UPI_CPU0_CPU1_P1P1_DN<12>")
	)
	(segment
		(start 163.63188 -34.549842)
		(end 159.692594 -35.32124)
		(width 0.1143)
		(layer "B.Cu")
		(net "UPI_CPU0_CPU1_P1P1_DN<12>")
	)
	(segment
		(start 173.718474 -34.142172)
		(end 168.015158 -34.724848)
		(width 0.1143)
		(layer "B.Cu")
		(net "UPI_CPU0_CPU1_P1P1_DN<12>")
	)
	(segment
		(start 248.216166 -33.836102)
		(end 238.988346 -35.681666)
		(width 0.1143)
		(layer "B.Cu")
		(net "UPI_CPU0_CPU1_P1P1_DN<12>")
	)
	(segment
		(start 300.710092 -50.161952)
		(end 300.710092 -50.139854)
		(width 0.0889)
		(layer "B.Cu")
		(net "UPI_CPU0_CPU1_P1P1_DN<12>")
	)
	(segment
		(start 300.710092 -50.090832)
		(end 300.706028 -48.12411)
		(width 0.1143)
		(layer "B.Cu")
		(net "UPI_CPU0_CPU1_P1P1_DN<12>")
	)
	(segment
		(start 300.780196 -51.23942)
		(end 300.780196 -51.09718)
		(width 0.0889)
		(layer "B.Cu")
		(net "UPI_CPU0_CPU1_P1P1_DN<12>")
	)
	(segment
		(start 291.505132 -36.665408)
		(end 286.894524 -37.587682)
		(width 0.1143)
		(layer "B.Cu")
		(net "UPI_CPU0_CPU1_P1P1_DN<12>")
	)
	(segment
		(start 300.686216 -51.0032)
		(end 300.686216 -50.8762)
		(width 0.0889)
		(layer "B.Cu")
		(net "UPI_CPU0_CPU1_P1P1_DN<12>")
	)
	(segment
		(start 129.432558 -59.076336)
		(end 129.426208 -59.087004)
		(width 0.0889)
		(layer "B.Cu")
		(net "UPI_CPU0_CPU1_P1P1_DN<12>")
	)
	(segment
		(start 128.574038 -57.590436)
		(end 128.567688 -57.601104)
		(width 0.0889)
		(layer "B.Cu")
		(net "UPI_CPU0_CPU1_P1P1_DN<12>")
	)
	(segment
		(start 189.035182 -33.105598)
		(end 183.66105 -31.421324)
		(width 0.1143)
		(layer "B.Cu")
		(net "UPI_CPU0_CPU1_P1P1_DN<12>")
	)
	(segment
		(start 128.209548 -55.999888)
		(end 128.242314 -55.999888)
		(width 0.0889)
		(layer "B.Cu")
		(net "UPI_CPU0_CPU1_P1P1_DN<12>")
	)
	(segment
		(start 300.954186 -53.270912)
		(end 300.896274 -53.328824)
		(width 0.0889)
		(layer "B.Cu")
		(net "UPI_CPU0_CPU1_P1P1_DN<12>")
	)
	(segment
		(start 138.676888 -39.14775)
		(end 133.69417 -42.508424)
		(width 0.1143)
		(layer "B.Cu")
		(net "UPI_CPU0_CPU1_P1P1_DN<12>")
	)
	(segment
		(start 129.70891 -59.91352)
		(end 129.944368 -60.362338)
		(width 0.0889)
		(layer "B.Cu")
		(net "UPI_CPU0_CPU1_P1P1_DN<12>")
	)
	(segment
		(start 128.091946 -52.49037)
		(end 128.091946 -52.73167)
		(width 0.0889)
		(layer "B.Cu")
		(net "UPI_CPU0_CPU1_P1P1_DN<12>")
	)
	(segment
		(start 168.015158 -34.724848)
		(end 166.262812 -35.076384)
		(width 0.1143)
		(layer "B.Cu")
		(net "UPI_CPU0_CPU1_P1P1_DN<12>")
	)
	(segment
		(start 128.578864 -57.5818)
		(end 128.574038 -57.590436)
		(width 0.0889)
		(layer "B.Cu")
		(net "UPI_CPU0_CPU1_P1P1_DN<12>")
	)
	(segment
		(start 183.66105 -31.421324)
		(end 173.718474 -34.142172)
		(width 0.1143)
		(layer "B.Cu")
		(net "UPI_CPU0_CPU1_P1P1_DN<12>")
	)
	(segment
		(start 222.396812 -38.27526)
		(end 211.016342 -35.998912)
		(width 0.1143)
		(layer "B.Cu")
		(net "UPI_CPU0_CPU1_P1P1_DN<12>")
	)
	(segment
		(start 300.686216 -51.4604)
		(end 300.686216 -51.3334)
		(width 0.0889)
		(layer "B.Cu")
		(net "UPI_CPU0_CPU1_P1P1_DN<12>")
	)
	(segment
		(start 196.779642 -32.629094)
		(end 189.035182 -33.105598)
		(width 0.1143)
		(layer "B.Cu")
		(net "UPI_CPU0_CPU1_P1P1_DN<12>")
	)
	(segment
		(start 286.894524 -37.587682)
		(end 286.893 -37.587936)
		(width 0.1143)
		(layer "B.Cu")
		(net "UPI_CPU0_CPU1_P1P1_DN<12>")
	)
	(arc
		(start 128.242314 -55.999888)
		(mid 128.575232 -56.201879)
		(end 128.578864 -56.5912)
		(width 0.0889)
		(layer "B.Cu")
		(net "UPI_CPU0_CPU1_P1P1_DN<12>")
	)
	(arc
		(start 129.097024 -58.476388)
		(mid 129.435139 -58.68109)
		(end 129.432558 -59.076336)
		(width 0.0889)
		(layer "B.Cu")
		(net "UPI_CPU0_CPU1_P1P1_DN<12>")
	)
	(arc
		(start 128.567688 -56.610504)
		(mid 128.49489 -56.901267)
		(end 128.574038 -57.190386)
		(width 0.0889)
		(layer "B.Cu")
		(net "UPI_CPU0_CPU1_P1P1_DN<12>")
	)
	(arc
		(start 300.607476 -52.142136)
		(mid 300.554006 -51.947073)
		(end 300.60265 -51.750722)
		(width 0.0889)
		(layer "B.Cu")
		(net "UPI_CPU0_CPU1_P1P1_DN<12>")
	)
	(arc
		(start 300.681136 -51.524916)
		(mid 300.684556 -51.492727)
		(end 300.686216 -51.4604)
		(width 0.0889)
		(layer "B.Cu")
		(net "UPI_CPU0_CPU1_P1P1_DN<12>")
	)
	(arc
		(start 128.574038 -57.190386)
		(mid 128.627508 -57.385449)
		(end 128.578864 -57.5818)
		(width 0.0889)
		(layer "B.Cu")
		(net "UPI_CPU0_CPU1_P1P1_DN<12>")
	)
	(arc
		(start 300.607476 -51.742086)
		(mid 300.654923 -51.637104)
		(end 300.681136 -51.524916)
		(width 0.0889)
		(layer "B.Cu")
		(net "UPI_CPU0_CPU1_P1P1_DN<12>")
	)
	(arc
		(start 300.607476 -52.73294)
		(mid 300.686607 -52.437538)
		(end 300.607476 -52.142136)
		(width 0.0889)
		(layer "B.Cu")
		(net "UPI_CPU0_CPU1_P1P1_DN<12>")
	)
	(arc
		(start 300.896274 -53.328824)
		(mid 300.756061 -53.280552)
		(end 300.643036 -53.184552)
		(width 0.0889)
		(layer "B.Cu")
		(net "UPI_CPU0_CPU1_P1P1_DN<12>")
	)
	(arc
		(start 128.567688 -57.601104)
		(mid 128.573865 -58.181036)
		(end 129.072894 -58.476388)
		(width 0.0889)
		(layer "B.Cu")
		(net "UPI_CPU0_CPU1_P1P1_DN<12>")
	)
	(arc
		(start 127.715518 -54.123336)
		(mid 127.636426 -54.411916)
		(end 127.708914 -54.702202)
		(width 0.0889)
		(layer "B.Cu")
		(net "UPI_CPU0_CPU1_P1P1_DN<12>")
	)
	(arc
		(start 127.715518 -55.113936)
		(mid 127.711189 -55.697108)
		(end 128.209548 -55.999888)
		(width 0.0889)
		(layer "B.Cu")
		(net "UPI_CPU0_CPU1_P1P1_DN<12>")
	)
	(arc
		(start 300.643036 -53.184552)
		(mid 300.555204 -52.964261)
		(end 300.607476 -52.73294)
		(width 0.0889)
		(layer "B.Cu")
		(net "UPI_CPU0_CPU1_P1P1_DN<12>")
	)
	(arc
		(start 127.720344 -54.722522)
		(mid 127.769099 -54.918874)
		(end 127.715518 -55.113936)
		(width 0.0889)
		(layer "B.Cu")
		(net "UPI_CPU0_CPU1_P1P1_DN<12>")
	)
	(arc
		(start 129.426208 -59.087004)
		(mid 129.385042 -59.562725)
		(end 129.70891 -59.91352)
		(width 0.0889)
		(layer "B.Cu")
		(net "UPI_CPU0_CPU1_P1P1_DN<12>")
	)
	(segment
		(start 298.665646 -53.923184)
		(end 299.237146 -53.923184)
		(width 0.1143)
		(layer "F.Cu")
		(net "UPI_CPU0_CPU1_P1P1_DN<11>")
	)
	(segment
		(start 129.372868 -57.390538)
		(end 129.944368 -57.390538)
		(width 0.1143)
		(layer "F.Cu")
		(net "UPI_CPU0_CPU1_P1P1_DN<11>")
	)
	(via
		(at 299.237146 -53.923184)
		(size 0.508)
		(drill 0.254)
		(layers "F.Cu" "B.Cu")
		(net "UPI_CPU0_CPU1_P1P1_DN<11>")
	)
	(via
		(at 129.944368 -57.390538)
		(size 0.508)
		(drill 0.254)
		(layers "F.Cu" "B.Cu")
		(net "UPI_CPU0_CPU1_P1P1_DN<11>")
	)
	(via
		(at 160.676336 -37.58311)
		(size 0.508)
		(drill 0.254)
		(layers "F.Cu" "B.Cu")
		(net "UPI_CPU0_CPU1_P1P1_DN<11>")
	)
	(segment
		(start 139.245848 -40.47744)
		(end 139.245594 -40.477694)
		(width 0.1143)
		(layer "B.Cu")
		(net "UPI_CPU0_CPU1_P1P1_DN<11>")
	)
	(segment
		(start 175.170084 -35.261042)
		(end 183.778398 -32.907732)
		(width 0.1143)
		(layer "B.Cu")
		(net "UPI_CPU0_CPU1_P1P1_DN<11>")
	)
	(segment
		(start 298.995592 -47.651162)
		(end 298.923964 -47.775622)
		(width 0.1143)
		(layer "B.Cu")
		(net "UPI_CPU0_CPU1_P1P1_DN<11>")
	)
	(segment
		(start 298.692316 -46.917102)
		(end 298.781724 -47.248572)
		(width 0.1143)
		(layer "B.Cu")
		(net "UPI_CPU0_CPU1_P1P1_DN<11>")
	)
	(segment
		(start 129.572512 -57.538112)
		(end 129.651252 -57.559448)
		(width 0.0889)
		(layer "B.Cu")
		(net "UPI_CPU0_CPU1_P1P1_DN<11>")
	)
	(segment
		(start 299.138086 -48.17872)
		(end 299.22724 -48.509682)
		(width 0.1143)
		(layer "B.Cu")
		(net "UPI_CPU0_CPU1_P1P1_DN<11>")
	)
	(segment
		(start 286.900112 -38.821868)
		(end 287.1216 -38.777672)
		(width 0.1143)
		(layer "B.Cu")
		(net "UPI_CPU0_CPU1_P1P1_DN<11>")
	)
	(segment
		(start 299.505116 -50.187098)
		(end 299.505116 -51.463448)
		(width 0.0889)
		(layer "B.Cu")
		(net "UPI_CPU0_CPU1_P1P1_DN<11>")
	)
	(segment
		(start 297.855894 -43.814492)
		(end 297.980608 -43.88612)
		(width 0.1143)
		(layer "B.Cu")
		(net "UPI_CPU0_CPU1_P1P1_DN<11>")
	)
	(segment
		(start 174.797212 -35.307778)
		(end 175.170084 -35.261042)
		(width 0.1143)
		(layer "B.Cu")
		(net "UPI_CPU0_CPU1_P1P1_DN<11>")
	)
	(segment
		(start 183.778398 -32.907732)
		(end 187.187332 -33.818322)
		(width 0.1143)
		(layer "B.Cu")
		(net "UPI_CPU0_CPU1_P1P1_DN<11>")
	)
	(segment
		(start 253.475744 -35.927284)
		(end 256.531364 -35.602926)
		(width 0.1143)
		(layer "B.Cu")
		(net "UPI_CPU0_CPU1_P1P1_DN<11>")
	)
	(segment
		(start 297.524678 -42.726864)
		(end 297.74007 -42.993564)
		(width 0.1143)
		(layer "B.Cu")
		(net "UPI_CPU0_CPU1_P1P1_DN<11>")
	)
	(segment
		(start 298.069762 -44.217082)
		(end 297.998134 -44.341542)
		(width 0.1143)
		(layer "B.Cu")
		(net "UPI_CPU0_CPU1_P1P1_DN<11>")
	)
	(segment
		(start 129.5527 -51.189128)
		(end 129.5527 -51.532028)
		(width 0.1143)
		(layer "B.Cu")
		(net "UPI_CPU0_CPU1_P1P1_DN<11>")
	)
	(segment
		(start 298.212002 -44.74464)
		(end 298.301156 -45.075602)
		(width 0.1143)
		(layer "B.Cu")
		(net "UPI_CPU0_CPU1_P1P1_DN<11>")
	)
	(segment
		(start 188.4934 -34.166048)
		(end 196.801232 -33.670494)
		(width 0.1143)
		(layer "B.Cu")
		(net "UPI_CPU0_CPU1_P1P1_DN<11>")
	)
	(segment
		(start 247.551702 -35.001454)
		(end 248.205498 -34.891726)
		(width 0.1143)
		(layer "B.Cu")
		(net "UPI_CPU0_CPU1_P1P1_DN<11>")
	)
	(segment
		(start 298.675044 -46.46168)
		(end 298.764198 -46.792642)
		(width 0.1143)
		(layer "B.Cu")
		(net "UPI_CPU0_CPU1_P1P1_DN<11>")
	)
	(segment
		(start 299.583856 -51.742086)
		(end 299.588682 -51.750722)
		(width 0.0889)
		(layer "B.Cu")
		(net "UPI_CPU0_CPU1_P1P1_DN<11>")
	)
	(segment
		(start 297.38193 -42.711624)
		(end 297.524678 -42.726864)
		(width 0.1143)
		(layer "B.Cu")
		(net "UPI_CPU0_CPU1_P1P1_DN<11>")
	)
	(segment
		(start 297.998134 -44.341542)
		(end 298.087288 -44.673012)
		(width 0.1143)
		(layer "B.Cu")
		(net "UPI_CPU0_CPU1_P1P1_DN<11>")
	)
	(segment
		(start 128.680972 -54.022498)
		(end 128.739138 -54.123336)
		(width 0.0889)
		(layer "B.Cu")
		(net "UPI_CPU0_CPU1_P1P1_DN<11>")
	)
	(segment
		(start 287.1216 -38.777672)
		(end 291.399468 -37.921692)
		(width 0.1143)
		(layer "B.Cu")
		(net "UPI_CPU0_CPU1_P1P1_DN<11>")
	)
	(segment
		(start 297.16603 -42.44467)
		(end 297.38193 -42.711624)
		(width 0.1143)
		(layer "B.Cu")
		(net "UPI_CPU0_CPU1_P1P1_DN<11>")
	)
	(segment
		(start 167.761412 -37.072824)
		(end 168.24706 -37.144452)
		(width 0.1143)
		(layer "B.Cu")
		(net "UPI_CPU0_CPU1_P1P1_DN<11>")
	)
	(segment
		(start 294.597074 -39.102284)
		(end 297.18127 -42.301922)
		(width 0.1143)
		(layer "B.Cu")
		(net "UPI_CPU0_CPU1_P1P1_DN<11>")
	)
	(segment
		(start 128.745488 -54.703218)
		(end 128.739138 -54.713886)
		(width 0.0889)
		(layer "B.Cu")
		(net "UPI_CPU0_CPU1_P1P1_DN<11>")
	)
	(segment
		(start 129.4511 -51.087528)
		(end 129.5527 -51.189128)
		(width 0.1143)
		(layer "B.Cu")
		(net "UPI_CPU0_CPU1_P1P1_DN<11>")
	)
	(segment
		(start 297.74007 -42.993564)
		(end 297.838368 -43.358562)
		(width 0.1143)
		(layer "B.Cu")
		(net "UPI_CPU0_CPU1_P1P1_DN<11>")
	)
	(segment
		(start 299.24502 -48.965612)
		(end 299.369734 -49.03724)
		(width 0.1143)
		(layer "B.Cu")
		(net "UPI_CPU0_CPU1_P1P1_DN<11>")
	)
	(segment
		(start 129.592832 -56.5912)
		(end 129.597658 -56.599836)
		(width 0.0889)
		(layer "B.Cu")
		(net "UPI_CPU0_CPU1_P1P1_DN<11>")
	)
	(segment
		(start 196.801232 -33.670494)
		(end 206.3242 -35.574732)
		(width 0.1143)
		(layer "B.Cu")
		(net "UPI_CPU0_CPU1_P1P1_DN<11>")
	)
	(segment
		(start 187.23356 -33.830514)
		(end 187.233814 -33.830768)
		(width 0.1143)
		(layer "B.Cu")
		(net "UPI_CPU0_CPU1_P1P1_DN<11>")
	)
	(segment
		(start 161.637472 -37.249862)
		(end 164.302694 -37.782754)
		(width 0.1143)
		(layer "B.Cu")
		(net "UPI_CPU0_CPU1_P1P1_DN<11>")
	)
	(segment
		(start 129.4257 -52.024026)
		(end 129.4257 -52.908962)
		(width 0.0889)
		(layer "B.Cu")
		(net "UPI_CPU0_CPU1_P1P1_DN<11>")
	)
	(segment
		(start 299.334682 -53.825648)
		(end 299.237146 -53.923184)
		(width 0.0889)
		(layer "B.Cu")
		(net "UPI_CPU0_CPU1_P1P1_DN<11>")
	)
	(segment
		(start 298.906438 -47.3202)
		(end 298.995592 -47.651162)
		(width 0.1143)
		(layer "B.Cu")
		(net "UPI_CPU0_CPU1_P1P1_DN<11>")
	)
	(segment
		(start 134.554976 -43.64101)
		(end 132.659882 -46.450504)
		(width 0.1143)
		(layer "B.Cu")
		(net "UPI_CPU0_CPU1_P1P1_DN<11>")
	)
	(segment
		(start 298.087288 -44.673012)
		(end 298.212002 -44.74464)
		(width 0.1143)
		(layer "B.Cu")
		(net "UPI_CPU0_CPU1_P1P1_DN<11>")
	)
	(segment
		(start 299.574966 -51.726846)
		(end 299.583856 -51.742086)
		(width 0.0889)
		(layer "B.Cu")
		(net "UPI_CPU0_CPU1_P1P1_DN<11>")
	)
	(segment
		(start 225.77171 -40.185594)
		(end 237.761526 -37.788088)
		(width 0.1143)
		(layer "B.Cu")
		(net "UPI_CPU0_CPU1_P1P1_DN<11>")
	)
	(segment
		(start 160.676336 -37.58311)
		(end 161.637472 -37.249862)
		(width 0.1143)
		(layer "B.Cu")
		(net "UPI_CPU0_CPU1_P1P1_DN<11>")
	)
	(segment
		(start 298.44365 -45.60316)
		(end 298.532804 -45.934122)
		(width 0.1143)
		(layer "B.Cu")
		(net "UPI_CPU0_CPU1_P1P1_DN<11>")
	)
	(segment
		(start 298.318936 -45.531532)
		(end 298.44365 -45.60316)
		(width 0.1143)
		(layer "B.Cu")
		(net "UPI_CPU0_CPU1_P1P1_DN<11>")
	)
	(segment
		(start 129.597658 -56.599836)
		(end 129.604008 -56.610504)
		(width 0.0889)
		(layer "B.Cu")
		(net "UPI_CPU0_CPU1_P1P1_DN<11>")
	)
	(segment
		(start 299.013372 -48.107092)
		(end 299.138086 -48.17872)
		(width 0.1143)
		(layer "B.Cu")
		(net "UPI_CPU0_CPU1_P1P1_DN<11>")
	)
	(segment
		(start 299.583856 -53.132736)
		(end 299.577506 -53.143404)
		(width 0.0889)
		(layer "B.Cu")
		(net "UPI_CPU0_CPU1_P1P1_DN<11>")
	)
	(segment
		(start 297.838368 -43.358562)
		(end 297.76674 -43.483022)
		(width 0.1143)
		(layer "B.Cu")
		(net "UPI_CPU0_CPU1_P1P1_DN<11>")
	)
	(segment
		(start 132.659882 -46.450504)
		(end 129.4511 -49.894236)
		(width 0.1143)
		(layer "B.Cu")
		(net "UPI_CPU0_CPU1_P1P1_DN<11>")
	)
	(segment
		(start 168.24706 -37.144452)
		(end 168.70045 -37.040312)
		(width 0.1143)
		(layer "B.Cu")
		(net "UPI_CPU0_CPU1_P1P1_DN<11>")
	)
	(segment
		(start 129.4511 -51.633628)
		(end 129.4511 -51.976528)
		(width 0.1143)
		(layer "B.Cu")
		(net "UPI_CPU0_CPU1_P1P1_DN<11>")
	)
	(segment
		(start 299.369734 -49.03724)
		(end 299.458888 -49.368202)
		(width 0.1143)
		(layer "B.Cu")
		(net "UPI_CPU0_CPU1_P1P1_DN<11>")
	)
	(segment
		(start 297.76674 -43.483022)
		(end 297.855894 -43.814492)
		(width 0.1143)
		(layer "B.Cu")
		(net "UPI_CPU0_CPU1_P1P1_DN<11>")
	)
	(segment
		(start 129.4511 -49.894236)
		(end 129.4511 -51.087528)
		(width 0.1143)
		(layer "B.Cu")
		(net "UPI_CPU0_CPU1_P1P1_DN<11>")
	)
	(segment
		(start 167.59301 -37.039296)
		(end 167.761412 -37.072824)
		(width 0.1143)
		(layer "B.Cu")
		(net "UPI_CPU0_CPU1_P1P1_DN<11>")
	)
	(segment
		(start 286.892492 -38.823646)
		(end 286.900112 -38.821868)
		(width 0.1143)
		(layer "B.Cu")
		(net "UPI_CPU0_CPU1_P1P1_DN<11>")
	)
	(segment
		(start 299.479716 -50.161698)
		(end 299.505116 -50.187098)
		(width 0.0889)
		(layer "B.Cu")
		(net "UPI_CPU0_CPU1_P1P1_DN<11>")
	)
	(segment
		(start 298.55033 -46.390052)
		(end 298.675044 -46.46168)
		(width 0.1143)
		(layer "B.Cu")
		(net "UPI_CPU0_CPU1_P1P1_DN<11>")
	)
	(segment
		(start 248.205498 -34.891726)
		(end 253.475744 -35.927284)
		(width 0.1143)
		(layer "B.Cu")
		(net "UPI_CPU0_CPU1_P1P1_DN<11>")
	)
	(segment
		(start 209.340196 -36.982146)
		(end 210.95716 -37.22243)
		(width 0.1143)
		(layer "B.Cu")
		(net "UPI_CPU0_CPU1_P1P1_DN<11>")
	)
	(segment
		(start 298.229528 -45.200062)
		(end 298.318936 -45.531532)
		(width 0.1143)
		(layer "B.Cu")
		(net "UPI_CPU0_CPU1_P1P1_DN<11>")
	)
	(segment
		(start 169.17416 -36.931346)
		(end 170.32224 -35.835844)
		(width 0.1143)
		(layer "B.Cu")
		(net "UPI_CPU0_CPU1_P1P1_DN<11>")
	)
	(segment
		(start 129.4257 -52.908962)
		(end 128.680972 -53.65369)
		(width 0.0889)
		(layer "B.Cu")
		(net "UPI_CPU0_CPU1_P1P1_DN<11>")
	)
	(segment
		(start 129.4511 -51.998626)
		(end 129.4257 -52.024026)
		(width 0.0889)
		(layer "B.Cu")
		(net "UPI_CPU0_CPU1_P1P1_DN<11>")
	)
	(segment
		(start 139.245594 -40.477694)
		(end 134.554976 -43.64101)
		(width 0.1143)
		(layer "B.Cu")
		(net "UPI_CPU0_CPU1_P1P1_DN<11>")
	)
	(segment
		(start 237.761526 -37.788088)
		(end 239.816894 -36.548568)
		(width 0.1143)
		(layer "B.Cu")
		(net "UPI_CPU0_CPU1_P1P1_DN<11>")
	)
	(segment
		(start 129.5527 -51.532028)
		(end 129.4511 -51.633628)
		(width 0.1143)
		(layer "B.Cu")
		(net "UPI_CPU0_CPU1_P1P1_DN<11>")
	)
	(segment
		(start 129.4511 -51.976528)
		(end 129.4511 -51.998626)
		(width 0.0889)
		(layer "B.Cu")
		(net "UPI_CPU0_CPU1_P1P1_DN<11>")
	)
	(segment
		(start 299.505116 -51.46675)
		(end 299.504862 -51.46675)
		(width 0.0889)
		(layer "B.Cu")
		(net "UPI_CPU0_CPU1_P1P1_DN<11>")
	)
	(segment
		(start 160.676336 -37.58311)
		(end 158.451042 -38.354508)
		(width 0.1143)
		(layer "B.Cu")
		(net "UPI_CPU0_CPU1_P1P1_DN<11>")
	)
	(segment
		(start 258.931918 -36.00323)
		(end 279.963626 -40.20947)
		(width 0.1143)
		(layer "B.Cu")
		(net "UPI_CPU0_CPU1_P1P1_DN<11>")
	)
	(segment
		(start 299.458888 -49.368202)
		(end 299.479716 -49.403508)
		(width 0.1143)
		(layer "B.Cu")
		(net "UPI_CPU0_CPU1_P1P1_DN<11>")
	)
	(segment
		(start 187.233814 -33.830768)
		(end 188.4934 -34.166048)
		(width 0.1143)
		(layer "B.Cu")
		(net "UPI_CPU0_CPU1_P1P1_DN<11>")
	)
	(segment
		(start 256.531364 -35.602926)
		(end 258.931918 -36.00323)
		(width 0.1143)
		(layer "B.Cu")
		(net "UPI_CPU0_CPU1_P1P1_DN<11>")
	)
	(segment
		(start 129.651252 -57.559448)
		(end 129.944368 -57.390538)
		(width 0.0889)
		(layer "B.Cu")
		(net "UPI_CPU0_CPU1_P1P1_DN<11>")
	)
	(segment
		(start 279.963626 -40.20947)
		(end 286.892492 -38.823646)
		(width 0.1143)
		(layer "B.Cu")
		(net "UPI_CPU0_CPU1_P1P1_DN<11>")
	)
	(segment
		(start 139.356338 -40.459152)
		(end 139.245848 -40.47744)
		(width 0.1143)
		(layer "B.Cu")
		(net "UPI_CPU0_CPU1_P1P1_DN<11>")
	)
	(segment
		(start 170.32224 -35.835844)
		(end 174.797212 -35.307778)
		(width 0.1143)
		(layer "B.Cu")
		(net "UPI_CPU0_CPU1_P1P1_DN<11>")
	)
	(segment
		(start 299.479716 -50.1396)
		(end 299.479716 -50.161698)
		(width 0.0889)
		(layer "B.Cu")
		(net "UPI_CPU0_CPU1_P1P1_DN<11>")
	)
	(segment
		(start 297.18127 -42.301922)
		(end 297.16603 -42.44467)
		(width 0.1143)
		(layer "B.Cu")
		(net "UPI_CPU0_CPU1_P1P1_DN<11>")
	)
	(segment
		(start 299.22724 -48.509682)
		(end 299.155612 -48.634396)
		(width 0.1143)
		(layer "B.Cu")
		(net "UPI_CPU0_CPU1_P1P1_DN<11>")
	)
	(segment
		(start 153.89225 -37.468302)
		(end 139.356338 -40.459152)
		(width 0.1143)
		(layer "B.Cu")
		(net "UPI_CPU0_CPU1_P1P1_DN<11>")
	)
	(segment
		(start 291.399468 -37.921692)
		(end 293.437056 -38.329362)
		(width 0.1143)
		(layer "B.Cu")
		(net "UPI_CPU0_CPU1_P1P1_DN<11>")
	)
	(segment
		(start 128.680972 -53.65369)
		(end 128.680972 -54.022498)
		(width 0.0889)
		(layer "B.Cu")
		(net "UPI_CPU0_CPU1_P1P1_DN<11>")
	)
	(segment
		(start 210.95716 -37.22243)
		(end 222.396812 -39.510462)
		(width 0.1143)
		(layer "B.Cu")
		(net "UPI_CPU0_CPU1_P1P1_DN<11>")
	)
	(segment
		(start 128.739138 -54.713886)
		(end 128.734312 -54.722522)
		(width 0.0889)
		(layer "B.Cu")
		(net "UPI_CPU0_CPU1_P1P1_DN<11>")
	)
	(segment
		(start 187.187332 -33.818322)
		(end 187.187332 -33.818068)
		(width 0.1143)
		(layer "B.Cu")
		(net "UPI_CPU0_CPU1_P1P1_DN<11>")
	)
	(segment
		(start 299.155612 -48.634396)
		(end 299.24502 -48.965612)
		(width 0.1143)
		(layer "B.Cu")
		(net "UPI_CPU0_CPU1_P1P1_DN<11>")
	)
	(segment
		(start 298.301156 -45.075602)
		(end 298.229528 -45.200062)
		(width 0.1143)
		(layer "B.Cu")
		(net "UPI_CPU0_CPU1_P1P1_DN<11>")
	)
	(segment
		(start 158.451042 -38.354508)
		(end 153.89225 -37.468302)
		(width 0.1143)
		(layer "B.Cu")
		(net "UPI_CPU0_CPU1_P1P1_DN<11>")
	)
	(segment
		(start 222.396812 -39.510462)
		(end 225.77171 -40.185594)
		(width 0.1143)
		(layer "B.Cu")
		(net "UPI_CPU0_CPU1_P1P1_DN<11>")
	)
	(segment
		(start 129.070862 -55.313834)
		(end 129.103628 -55.313834)
		(width 0.0889)
		(layer "B.Cu")
		(net "UPI_CPU0_CPU1_P1P1_DN<11>")
	)
	(segment
		(start 298.764198 -46.792642)
		(end 298.692316 -46.917102)
		(width 0.1143)
		(layer "B.Cu")
		(net "UPI_CPU0_CPU1_P1P1_DN<11>")
	)
	(segment
		(start 164.302694 -37.782754)
		(end 167.59301 -37.039296)
		(width 0.1143)
		(layer "B.Cu")
		(net "UPI_CPU0_CPU1_P1P1_DN<11>")
	)
	(segment
		(start 297.980608 -43.88612)
		(end 298.069762 -44.217082)
		(width 0.1143)
		(layer "B.Cu")
		(net "UPI_CPU0_CPU1_P1P1_DN<11>")
	)
	(segment
		(start 206.3242 -35.574732)
		(end 209.340196 -36.982146)
		(width 0.1143)
		(layer "B.Cu")
		(net "UPI_CPU0_CPU1_P1P1_DN<11>")
	)
	(segment
		(start 239.816894 -36.548568)
		(end 247.551702 -35.001454)
		(width 0.1143)
		(layer "B.Cu")
		(net "UPI_CPU0_CPU1_P1P1_DN<11>")
	)
	(segment
		(start 298.460922 -46.058582)
		(end 298.55033 -46.390052)
		(width 0.1143)
		(layer "B.Cu")
		(net "UPI_CPU0_CPU1_P1P1_DN<11>")
	)
	(segment
		(start 168.70045 -37.040058)
		(end 169.17416 -36.931346)
		(width 0.1143)
		(layer "B.Cu")
		(net "UPI_CPU0_CPU1_P1P1_DN<11>")
	)
	(segment
		(start 298.923964 -47.775622)
		(end 299.013372 -48.107092)
		(width 0.1143)
		(layer "B.Cu")
		(net "UPI_CPU0_CPU1_P1P1_DN<11>")
	)
	(segment
		(start 168.70045 -37.040312)
		(end 168.70045 -37.040058)
		(width 0.1143)
		(layer "B.Cu")
		(net "UPI_CPU0_CPU1_P1P1_DN<11>")
	)
	(segment
		(start 298.532804 -45.934122)
		(end 298.460922 -46.058582)
		(width 0.1143)
		(layer "B.Cu")
		(net "UPI_CPU0_CPU1_P1P1_DN<11>")
	)
	(segment
		(start 298.781724 -47.248572)
		(end 298.906438 -47.3202)
		(width 0.1143)
		(layer "B.Cu")
		(net "UPI_CPU0_CPU1_P1P1_DN<11>")
	)
	(segment
		(start 187.187332 -33.818068)
		(end 187.23356 -33.830514)
		(width 0.1143)
		(layer "B.Cu")
		(net "UPI_CPU0_CPU1_P1P1_DN<11>")
	)
	(segment
		(start 299.479716 -49.403508)
		(end 299.479716 -50.1396)
		(width 0.1143)
		(layer "B.Cu")
		(net "UPI_CPU0_CPU1_P1P1_DN<11>")
	)
	(segment
		(start 293.437056 -38.329362)
		(end 294.597074 -39.102284)
		(width 0.1143)
		(layer "B.Cu")
		(net "UPI_CPU0_CPU1_P1P1_DN<11>")
	)
	(arc
		(start 299.588682 -51.750722)
		(mid 299.637437 -51.947074)
		(end 299.583856 -52.142136)
		(width 0.0889)
		(layer "B.Cu")
		(net "UPI_CPU0_CPU1_P1P1_DN<11>")
	)
	(arc
		(start 299.504862 -51.46675)
		(mid 299.524915 -51.600839)
		(end 299.574966 -51.726846)
		(width 0.0889)
		(layer "B.Cu")
		(net "UPI_CPU0_CPU1_P1P1_DN<11>")
	)
	(arc
		(start 299.583856 -52.142136)
		(mid 299.504725 -52.437538)
		(end 299.583856 -52.73294)
		(width 0.0889)
		(layer "B.Cu")
		(net "UPI_CPU0_CPU1_P1P1_DN<11>")
	)
	(arc
		(start 299.583856 -52.73294)
		(mid 299.637355 -52.932838)
		(end 299.583856 -53.132736)
		(width 0.0889)
		(layer "B.Cu")
		(net "UPI_CPU0_CPU1_P1P1_DN<11>")
	)
	(arc
		(start 299.504608 -53.415438)
		(mid 299.460448 -53.637446)
		(end 299.334682 -53.825648)
		(width 0.0889)
		(layer "B.Cu")
		(net "UPI_CPU0_CPU1_P1P1_DN<11>")
	)
	(arc
		(start 129.103628 -55.313834)
		(mid 129.601879 -55.616674)
		(end 129.597658 -56.199786)
		(width 0.0889)
		(layer "B.Cu")
		(net "UPI_CPU0_CPU1_P1P1_DN<11>")
	)
	(arc
		(start 128.734312 -54.722522)
		(mid 128.738059 -55.111778)
		(end 129.070862 -55.313834)
		(width 0.0889)
		(layer "B.Cu")
		(net "UPI_CPU0_CPU1_P1P1_DN<11>")
	)
	(arc
		(start 129.604008 -56.610504)
		(mid 129.676806 -56.901267)
		(end 129.597658 -57.190386)
		(width 0.0889)
		(layer "B.Cu")
		(net "UPI_CPU0_CPU1_P1P1_DN<11>")
	)
	(arc
		(start 128.739138 -54.123336)
		(mid 128.81836 -54.412454)
		(end 128.745488 -54.703218)
		(width 0.0889)
		(layer "B.Cu")
		(net "UPI_CPU0_CPU1_P1P1_DN<11>")
	)
	(arc
		(start 299.577506 -53.143404)
		(mid 299.524634 -53.275018)
		(end 299.504608 -53.415438)
		(width 0.0889)
		(layer "B.Cu")
		(net "UPI_CPU0_CPU1_P1P1_DN<11>")
	)
	(arc
		(start 299.505116 -51.463448)
		(mid 299.505113 -51.465099)
		(end 299.505116 -51.46675)
		(width 0.0889)
		(layer "B.Cu")
		(net "UPI_CPU0_CPU1_P1P1_DN<11>")
	)
	(arc
		(start 129.544318 -57.40019)
		(mid 129.552298 -57.470402)
		(end 129.572512 -57.538112)
		(width 0.0889)
		(layer "B.Cu")
		(net "UPI_CPU0_CPU1_P1P1_DN<11>")
	)
	(arc
		(start 129.597658 -57.190386)
		(mid 129.556514 -57.291611)
		(end 129.544318 -57.40019)
		(width 0.0889)
		(layer "B.Cu")
		(net "UPI_CPU0_CPU1_P1P1_DN<11>")
	)
	(arc
		(start 129.597658 -56.199786)
		(mid 129.544188 -56.394849)
		(end 129.592832 -56.5912)
		(width 0.0889)
		(layer "B.Cu")
		(net "UPI_CPU0_CPU1_P1P1_DN<11>")
	)
	(segment
		(start 299.524166 -54.418738)
		(end 300.095666 -54.418738)
		(width 0.1143)
		(layer "F.Cu")
		(net "UPI_CPU0_CPU1_P1P1_DN<10>")
	)
	(segment
		(start 129.372868 -58.381138)
		(end 129.944368 -58.381138)
		(width 0.1143)
		(layer "F.Cu")
		(net "UPI_CPU0_CPU1_P1P1_DN<10>")
	)
	(via
		(at 129.944368 -58.381138)
		(size 0.508)
		(drill 0.254)
		(layers "F.Cu" "B.Cu")
		(net "UPI_CPU0_CPU1_P1P1_DN<10>")
	)
	(via
		(at 300.095666 -54.418738)
		(size 0.508)
		(drill 0.254)
		(layers "F.Cu" "B.Cu")
		(net "UPI_CPU0_CPU1_P1P1_DN<10>")
	)
	(segment
		(start 298.890436 -53.723286)
		(end 298.88561 -53.731922)
		(width 0.0889)
		(layer "B.Cu")
		(net "UPI_CPU0_CPU1_P1P1_DN<10>")
	)
	(segment
		(start 299.22216 -54.323234)
		(end 299.254926 -54.323234)
		(width 0.0889)
		(layer "B.Cu")
		(net "UPI_CPU0_CPU1_P1P1_DN<10>")
	)
	(segment
		(start 130.299206 -52.623212)
		(end 130.299714 -52.62245)
		(width 0.0889)
		(layer "B.Cu")
		(net "UPI_CPU0_CPU1_P1P1_DN<10>")
	)
	(segment
		(start 130.291078 -53.227986)
		(end 130.284728 -53.217318)
		(width 0.0889)
		(layer "B.Cu")
		(net "UPI_CPU0_CPU1_P1P1_DN<10>")
	)
	(segment
		(start 296.355262 -43.19778)
		(end 296.5196 -43.711622)
		(width 0.1143)
		(layer "B.Cu")
		(net "UPI_CPU0_CPU1_P1P1_DN<10>")
	)
	(segment
		(start 295.0337 -40.884602)
		(end 296.355262 -43.19778)
		(width 0.1143)
		(layer "B.Cu")
		(net "UPI_CPU0_CPU1_P1P1_DN<10>")
	)
	(segment
		(start 185.031888 -34.166048)
		(end 187.902088 -34.827972)
		(width 0.1143)
		(layer "B.Cu")
		(net "UPI_CPU0_CPU1_P1P1_DN<10>")
	)
	(segment
		(start 209.296 -37.68852)
		(end 211.01939 -37.97554)
		(width 0.1143)
		(layer "B.Cu")
		(net "UPI_CPU0_CPU1_P1P1_DN<10>")
	)
	(segment
		(start 133.239764 -47.306992)
		(end 135.296402 -44.25823)
		(width 0.1143)
		(layer "B.Cu")
		(net "UPI_CPU0_CPU1_P1P1_DN<10>")
	)
	(segment
		(start 130.3528 -51.4096)
		(end 130.3528 -50.19421)
		(width 0.1143)
		(layer "B.Cu")
		(net "UPI_CPU0_CPU1_P1P1_DN<10>")
	)
	(segment
		(start 164.358574 -38.552628)
		(end 166.915846 -37.953442)
		(width 0.1143)
		(layer "B.Cu")
		(net "UPI_CPU0_CPU1_P1P1_DN<10>")
	)
	(segment
		(start 171.22394 -38.803834)
		(end 185.031888 -34.166048)
		(width 0.1143)
		(layer "B.Cu")
		(net "UPI_CPU0_CPU1_P1P1_DN<10>")
	)
	(segment
		(start 187.902088 -34.827972)
		(end 190.576962 -34.567114)
		(width 0.1143)
		(layer "B.Cu")
		(net "UPI_CPU0_CPU1_P1P1_DN<10>")
	)
	(segment
		(start 296.5196 -43.711622)
		(end 298.17695 -48.89246)
		(width 0.1143)
		(layer "B.Cu")
		(net "UPI_CPU0_CPU1_P1P1_DN<10>")
	)
	(segment
		(start 280.029412 -40.998394)
		(end 292.054534 -38.593268)
		(width 0.1143)
		(layer "B.Cu")
		(net "UPI_CPU0_CPU1_P1P1_DN<10>")
	)
	(segment
		(start 130.3528 -50.19421)
		(end 133.239764 -47.306992)
		(width 0.1143)
		(layer "B.Cu")
		(net "UPI_CPU0_CPU1_P1P1_DN<10>")
	)
	(segment
		(start 298.8183 -50.590958)
		(end 298.968922 -51.25212)
		(width 0.0889)
		(layer "B.Cu")
		(net "UPI_CPU0_CPU1_P1P1_DN<10>")
	)
	(segment
		(start 130.284728 -55.619904)
		(end 130.291078 -55.609236)
		(width 0.0889)
		(layer "B.Cu")
		(net "UPI_CPU0_CPU1_P1P1_DN<10>")
	)
	(segment
		(start 298.890436 -53.132736)
		(end 298.896786 -53.143404)
		(width 0.0889)
		(layer "B.Cu")
		(net "UPI_CPU0_CPU1_P1P1_DN<10>")
	)
	(segment
		(start 247.998488 -35.468814)
		(end 251.57176 -36.182808)
		(width 0.1143)
		(layer "B.Cu")
		(net "UPI_CPU0_CPU1_P1P1_DN<10>")
	)
	(segment
		(start 251.57176 -36.182808)
		(end 253.272544 -36.715446)
		(width 0.1143)
		(layer "B.Cu")
		(net "UPI_CPU0_CPU1_P1P1_DN<10>")
	)
	(segment
		(start 293.22395 -38.826948)
		(end 294.032432 -39.365682)
		(width 0.1143)
		(layer "B.Cu")
		(net "UPI_CPU0_CPU1_P1P1_DN<10>")
	)
	(segment
		(start 154.466544 -38.32733)
		(end 158.79445 -39.168832)
		(width 0.1143)
		(layer "B.Cu")
		(net "UPI_CPU0_CPU1_P1P1_DN<10>")
	)
	(segment
		(start 298.968922 -51.25212)
		(end 298.968922 -51.471068)
		(width 0.0889)
		(layer "B.Cu")
		(net "UPI_CPU0_CPU1_P1P1_DN<10>")
	)
	(segment
		(start 130.284728 -57.601104)
		(end 130.291078 -57.590436)
		(width 0.0889)
		(layer "B.Cu")
		(net "UPI_CPU0_CPU1_P1P1_DN<10>")
	)
	(segment
		(start 298.68368 -50.1396)
		(end 298.680886 -50.20183)
		(width 0.0889)
		(layer "B.Cu")
		(net "UPI_CPU0_CPU1_P1P1_DN<10>")
	)
	(segment
		(start 130.284728 -56.610504)
		(end 130.291078 -56.599836)
		(width 0.0889)
		(layer "B.Cu")
		(net "UPI_CPU0_CPU1_P1P1_DN<10>")
	)
	(segment
		(start 211.01939 -37.97554)
		(end 222.396812 -40.251126)
		(width 0.1143)
		(layer "B.Cu")
		(net "UPI_CPU0_CPU1_P1P1_DN<10>")
	)
	(segment
		(start 129.944368 -58.381138)
		(end 130.237484 -58.550048)
		(width 0.0889)
		(layer "B.Cu")
		(net "UPI_CPU0_CPU1_P1P1_DN<10>")
	)
	(segment
		(start 166.915846 -37.953442)
		(end 171.22394 -38.803834)
		(width 0.1143)
		(layer "B.Cu")
		(net "UPI_CPU0_CPU1_P1P1_DN<10>")
	)
	(segment
		(start 130.3782 -52.303934)
		(end 130.3782 -51.435)
		(width 0.0889)
		(layer "B.Cu")
		(net "UPI_CPU0_CPU1_P1P1_DN<10>")
	)
	(segment
		(start 240.786158 -36.911026)
		(end 247.998488 -35.468814)
		(width 0.1143)
		(layer "B.Cu")
		(net "UPI_CPU0_CPU1_P1P1_DN<10>")
	)
	(segment
		(start 196.906896 -34.227516)
		(end 206.073502 -36.061142)
		(width 0.1143)
		(layer "B.Cu")
		(net "UPI_CPU0_CPU1_P1P1_DN<10>")
	)
	(segment
		(start 206.073502 -36.061142)
		(end 209.18551 -37.670232)
		(width 0.1143)
		(layer "B.Cu")
		(net "UPI_CPU0_CPU1_P1P1_DN<10>")
	)
	(segment
		(start 298.680886 -50.20183)
		(end 298.8183 -50.590958)
		(width 0.0889)
		(layer "B.Cu")
		(net "UPI_CPU0_CPU1_P1P1_DN<10>")
	)
	(segment
		(start 300.08449 -54.818788)
		(end 300.246288 -54.818788)
		(width 0.0889)
		(layer "B.Cu")
		(net "UPI_CPU0_CPU1_P1P1_DN<10>")
	)
	(segment
		(start 130.299714 -52.62245)
		(end 130.299714 -52.622704)
		(width 0.0889)
		(layer "B.Cu")
		(net "UPI_CPU0_CPU1_P1P1_DN<10>")
	)
	(segment
		(start 256.634234 -36.54933)
		(end 259.337302 -36.859464)
		(width 0.1143)
		(layer "B.Cu")
		(net "UPI_CPU0_CPU1_P1P1_DN<10>")
	)
	(segment
		(start 238.55299 -38.400228)
		(end 240.786158 -36.911026)
		(width 0.1143)
		(layer "B.Cu")
		(net "UPI_CPU0_CPU1_P1P1_DN<10>")
	)
	(segment
		(start 190.576962 -34.567114)
		(end 196.906896 -34.227516)
		(width 0.1143)
		(layer "B.Cu")
		(net "UPI_CPU0_CPU1_P1P1_DN<10>")
	)
	(segment
		(start 298.890436 -51.742086)
		(end 298.88561 -51.750722)
		(width 0.0889)
		(layer "B.Cu")
		(net "UPI_CPU0_CPU1_P1P1_DN<10>")
	)
	(segment
		(start 130.377946 -52.30368)
		(end 130.3782 -52.303934)
		(width 0.0889)
		(layer "B.Cu")
		(net "UPI_CPU0_CPU1_P1P1_DN<10>")
	)
	(segment
		(start 294.032432 -39.365682)
		(end 295.0337 -40.884602)
		(width 0.1143)
		(layer "B.Cu")
		(net "UPI_CPU0_CPU1_P1P1_DN<10>")
	)
	(segment
		(start 259.337302 -36.859464)
		(end 280.029412 -40.998394)
		(width 0.1143)
		(layer "B.Cu")
		(net "UPI_CPU0_CPU1_P1P1_DN<10>")
	)
	(segment
		(start 139.42187 -41.475406)
		(end 154.466544 -38.32733)
		(width 0.1143)
		(layer "B.Cu")
		(net "UPI_CPU0_CPU1_P1P1_DN<10>")
	)
	(segment
		(start 130.284728 -54.629304)
		(end 130.291078 -54.618636)
		(width 0.0889)
		(layer "B.Cu")
		(net "UPI_CPU0_CPU1_P1P1_DN<10>")
	)
	(segment
		(start 298.17695 -48.89246)
		(end 298.68368 -50.1396)
		(width 0.1143)
		(layer "B.Cu")
		(net "UPI_CPU0_CPU1_P1P1_DN<10>")
	)
	(segment
		(start 130.291078 -52.637436)
		(end 130.299206 -52.623212)
		(width 0.0889)
		(layer "B.Cu")
		(net "UPI_CPU0_CPU1_P1P1_DN<10>")
	)
	(segment
		(start 225.846386 -40.94099)
		(end 238.55299 -38.400228)
		(width 0.1143)
		(layer "B.Cu")
		(net "UPI_CPU0_CPU1_P1P1_DN<10>")
	)
	(segment
		(start 130.291078 -57.590436)
		(end 130.295904 -57.5818)
		(width 0.0889)
		(layer "B.Cu")
		(net "UPI_CPU0_CPU1_P1P1_DN<10>")
	)
	(segment
		(start 158.79445 -39.168832)
		(end 161.68878 -38.01872)
		(width 0.1143)
		(layer "B.Cu")
		(net "UPI_CPU0_CPU1_P1P1_DN<10>")
	)
	(segment
		(start 130.291078 -56.599836)
		(end 130.295904 -56.5912)
		(width 0.0889)
		(layer "B.Cu")
		(net "UPI_CPU0_CPU1_P1P1_DN<10>")
	)
	(segment
		(start 300.329346 -54.418992)
		(end 300.095666 -54.418738)
		(width 0.0889)
		(layer "B.Cu")
		(net "UPI_CPU0_CPU1_P1P1_DN<10>")
	)
	(segment
		(start 253.272544 -36.715446)
		(end 256.634234 -36.54933)
		(width 0.1143)
		(layer "B.Cu")
		(net "UPI_CPU0_CPU1_P1P1_DN<10>")
	)
	(segment
		(start 292.054534 -38.593268)
		(end 293.22395 -38.826948)
		(width 0.1143)
		(layer "B.Cu")
		(net "UPI_CPU0_CPU1_P1P1_DN<10>")
	)
	(segment
		(start 130.3782 -51.435)
		(end 130.3528 -51.4096)
		(width 0.0889)
		(layer "B.Cu")
		(net "UPI_CPU0_CPU1_P1P1_DN<10>")
	)
	(segment
		(start 222.396812 -40.251126)
		(end 225.846386 -40.94099)
		(width 0.1143)
		(layer "B.Cu")
		(net "UPI_CPU0_CPU1_P1P1_DN<10>")
	)
	(segment
		(start 130.299714 -52.622704)
		(end 130.301492 -52.61991)
		(width 0.0889)
		(layer "B.Cu")
		(net "UPI_CPU0_CPU1_P1P1_DN<10>")
	)
	(segment
		(start 209.18551 -37.670232)
		(end 209.296 -37.68852)
		(width 0.1143)
		(layer "B.Cu")
		(net "UPI_CPU0_CPU1_P1P1_DN<10>")
	)
	(segment
		(start 130.291078 -54.618636)
		(end 130.295904 -54.61)
		(width 0.0889)
		(layer "B.Cu")
		(net "UPI_CPU0_CPU1_P1P1_DN<10>")
	)
	(segment
		(start 130.291078 -55.609236)
		(end 130.295904 -55.6006)
		(width 0.0889)
		(layer "B.Cu")
		(net "UPI_CPU0_CPU1_P1P1_DN<10>")
	)
	(segment
		(start 130.237484 -58.550048)
		(end 130.316224 -58.528712)
		(width 0.0889)
		(layer "B.Cu")
		(net "UPI_CPU0_CPU1_P1P1_DN<10>")
	)
	(segment
		(start 161.68878 -38.01872)
		(end 164.358574 -38.552628)
		(width 0.1143)
		(layer "B.Cu")
		(net "UPI_CPU0_CPU1_P1P1_DN<10>")
	)
	(segment
		(start 135.296402 -44.25823)
		(end 139.42187 -41.475406)
		(width 0.1143)
		(layer "B.Cu")
		(net "UPI_CPU0_CPU1_P1P1_DN<10>")
	)
	(arc
		(start 300.246288 -54.818788)
		(mid 300.361069 -54.795939)
		(end 300.458378 -54.730904)
		(width 0.0889)
		(layer "B.Cu")
		(net "UPI_CPU0_CPU1_P1P1_DN<10>")
	)
	(arc
		(start 299.254926 -54.323234)
		(mid 299.54035 -54.406701)
		(end 299.748956 -54.618636)
		(width 0.0889)
		(layer "B.Cu")
		(net "UPI_CPU0_CPU1_P1P1_DN<10>")
	)
	(arc
		(start 130.295904 -54.61)
		(mid 130.344659 -54.413648)
		(end 130.291078 -54.218586)
		(width 0.0889)
		(layer "B.Cu")
		(net "UPI_CPU0_CPU1_P1P1_DN<10>")
	)
	(arc
		(start 298.890436 -52.142136)
		(mid 298.969567 -52.437538)
		(end 298.890436 -52.73294)
		(width 0.0889)
		(layer "B.Cu")
		(net "UPI_CPU0_CPU1_P1P1_DN<10>")
	)
	(arc
		(start 130.301492 -52.61991)
		(mid 130.358579 -52.466358)
		(end 130.377946 -52.30368)
		(width 0.0889)
		(layer "B.Cu")
		(net "UPI_CPU0_CPU1_P1P1_DN<10>")
	)
	(arc
		(start 300.458378 -54.730904)
		(mid 300.498061 -54.531766)
		(end 300.329346 -54.418992)
		(width 0.0889)
		(layer "B.Cu")
		(net "UPI_CPU0_CPU1_P1P1_DN<10>")
	)
	(arc
		(start 130.291078 -53.627782)
		(mid 130.344577 -53.427884)
		(end 130.291078 -53.227986)
		(width 0.0889)
		(layer "B.Cu")
		(net "UPI_CPU0_CPU1_P1P1_DN<10>")
	)
	(arc
		(start 130.316224 -58.528712)
		(mid 130.330729 -58.484823)
		(end 130.3401 -58.439558)
		(width 0.0889)
		(layer "B.Cu")
		(net "UPI_CPU0_CPU1_P1P1_DN<10>")
	)
	(arc
		(start 298.88561 -51.750722)
		(mid 298.836855 -51.947074)
		(end 298.890436 -52.142136)
		(width 0.0889)
		(layer "B.Cu")
		(net "UPI_CPU0_CPU1_P1P1_DN<10>")
	)
	(arc
		(start 130.295904 -56.5912)
		(mid 130.344659 -56.394848)
		(end 130.291078 -56.199786)
		(width 0.0889)
		(layer "B.Cu")
		(net "UPI_CPU0_CPU1_P1P1_DN<10>")
	)
	(arc
		(start 130.284728 -53.217318)
		(mid 130.21193 -52.926555)
		(end 130.291078 -52.637436)
		(width 0.0889)
		(layer "B.Cu")
		(net "UPI_CPU0_CPU1_P1P1_DN<10>")
	)
	(arc
		(start 130.291078 -58.180986)
		(mid 130.211856 -57.891868)
		(end 130.284728 -57.601104)
		(width 0.0889)
		(layer "B.Cu")
		(net "UPI_CPU0_CPU1_P1P1_DN<10>")
	)
	(arc
		(start 130.291078 -56.199786)
		(mid 130.211856 -55.910668)
		(end 130.284728 -55.619904)
		(width 0.0889)
		(layer "B.Cu")
		(net "UPI_CPU0_CPU1_P1P1_DN<10>")
	)
	(arc
		(start 130.291078 -57.190386)
		(mid 130.211856 -56.901268)
		(end 130.284728 -56.610504)
		(width 0.0889)
		(layer "B.Cu")
		(net "UPI_CPU0_CPU1_P1P1_DN<10>")
	)
	(arc
		(start 298.968922 -51.471068)
		(mid 298.946084 -51.611326)
		(end 298.890436 -51.742086)
		(width 0.0889)
		(layer "B.Cu")
		(net "UPI_CPU0_CPU1_P1P1_DN<10>")
	)
	(arc
		(start 299.748956 -54.618636)
		(mid 299.890639 -54.76244)
		(end 300.08449 -54.818788)
		(width 0.0889)
		(layer "B.Cu")
		(net "UPI_CPU0_CPU1_P1P1_DN<10>")
	)
	(arc
		(start 130.295904 -57.5818)
		(mid 130.344659 -57.385448)
		(end 130.291078 -57.190386)
		(width 0.0889)
		(layer "B.Cu")
		(net "UPI_CPU0_CPU1_P1P1_DN<10>")
	)
	(arc
		(start 298.896786 -53.143404)
		(mid 298.969584 -53.434167)
		(end 298.890436 -53.723286)
		(width 0.0889)
		(layer "B.Cu")
		(net "UPI_CPU0_CPU1_P1P1_DN<10>")
	)
	(arc
		(start 130.3401 -58.439558)
		(mid 130.337466 -58.306121)
		(end 130.291078 -58.180986)
		(width 0.0889)
		(layer "B.Cu")
		(net "UPI_CPU0_CPU1_P1P1_DN<10>")
	)
	(arc
		(start 130.291078 -55.209186)
		(mid 130.211856 -54.920068)
		(end 130.284728 -54.629304)
		(width 0.0889)
		(layer "B.Cu")
		(net "UPI_CPU0_CPU1_P1P1_DN<10>")
	)
	(arc
		(start 298.890436 -52.73294)
		(mid 298.836937 -52.932838)
		(end 298.890436 -53.132736)
		(width 0.0889)
		(layer "B.Cu")
		(net "UPI_CPU0_CPU1_P1P1_DN<10>")
	)
	(arc
		(start 130.291078 -54.218586)
		(mid 130.211947 -53.923184)
		(end 130.291078 -53.627782)
		(width 0.0889)
		(layer "B.Cu")
		(net "UPI_CPU0_CPU1_P1P1_DN<10>")
	)
	(arc
		(start 298.88561 -53.731922)
		(mid 298.889357 -54.121178)
		(end 299.22216 -54.323234)
		(width 0.0889)
		(layer "B.Cu")
		(net "UPI_CPU0_CPU1_P1P1_DN<10>")
	)
	(arc
		(start 130.295904 -55.6006)
		(mid 130.344659 -55.404248)
		(end 130.291078 -55.209186)
		(width 0.0889)
		(layer "B.Cu")
		(net "UPI_CPU0_CPU1_P1P1_DN<10>")
	)
	(segment
		(start 137.957814 -58.381138)
		(end 138.529314 -58.381138)
		(width 0.1143)
		(layer "F.Cu")
		(net "UPI_CPU0_CPU1_P1P1_DN<0>")
	)
	(segment
		(start 290.0807 -54.913784)
		(end 290.6522 -54.913784)
		(width 0.1143)
		(layer "F.Cu")
		(net "UPI_CPU0_CPU1_P1P1_DN<0>")
	)
	(via
		(at 138.529314 -58.381138)
		(size 0.508)
		(drill 0.254)
		(layers "F.Cu" "B.Cu")
		(net "UPI_CPU0_CPU1_P1P1_DN<0>")
	)
	(via
		(at 290.6522 -54.913784)
		(size 0.508)
		(drill 0.254)
		(layers "F.Cu" "B.Cu")
		(net "UPI_CPU0_CPU1_P1P1_DN<0>")
	)
	(via
		(at 161.103056 -50.05832)
		(size 0.508)
		(drill 0.254)
		(layers "F.Cu" "B.Cu")
		(net "UPI_CPU0_CPU1_P1P1_DN<0>")
	)
	(segment
		(start 267.438378 -51.171094)
		(end 266.87526 -50.795682)
		(width 0.1143)
		(layer "B.Cu")
		(net "UPI_CPU0_CPU1_P1P1_DN<0>")
	)
	(segment
		(start 167.473884 -51.319684)
		(end 161.103056 -50.05832)
		(width 0.1143)
		(layer "B.Cu")
		(net "UPI_CPU0_CPU1_P1P1_DN<0>")
	)
	(segment
		(start 148.522182 -54.874668)
		(end 148.363432 -54.849014)
		(width 0.1143)
		(layer "B.Cu")
		(net "UPI_CPU0_CPU1_P1P1_DN<0>")
	)
	(segment
		(start 290.6522 -55.171086)
		(end 290.529518 -55.293768)
		(width 0.0889)
		(layer "B.Cu")
		(net "UPI_CPU0_CPU1_P1P1_DN<0>")
	)
	(segment
		(start 245.74881 -51.92649)
		(end 245.739666 -51.918108)
		(width 0.1143)
		(layer "B.Cu")
		(net "UPI_CPU0_CPU1_P1P1_DN<0>")
	)
	(segment
		(start 285.62173 -52.10429)
		(end 285.33979 -51.877976)
		(width 0.1143)
		(layer "B.Cu")
		(net "UPI_CPU0_CPU1_P1P1_DN<0>")
	)
	(segment
		(start 278.95931 -52.265834)
		(end 279.108916 -53.012086)
		(width 0.1143)
		(layer "B.Cu")
		(net "UPI_CPU0_CPU1_P1P1_DN<0>")
	)
	(segment
		(start 262.665464 -51.684174)
		(end 262.214106 -51.774598)
		(width 0.1143)
		(layer "B.Cu")
		(net "UPI_CPU0_CPU1_P1P1_DN<0>")
	)
	(segment
		(start 256.034794 -50.816256)
		(end 256.034794 -50.81651)
		(width 0.1143)
		(layer "B.Cu")
		(net "UPI_CPU0_CPU1_P1P1_DN<0>")
	)
	(segment
		(start 192.036446 -46.61662)
		(end 184.873138 -46.509432)
		(width 0.1143)
		(layer "B.Cu")
		(net "UPI_CPU0_CPU1_P1P1_DN<0>")
	)
	(segment
		(start 238.462566 -49.034192)
		(end 236.42193 -49.442116)
		(width 0.1143)
		(layer "B.Cu")
		(net "UPI_CPU0_CPU1_P1P1_DN<0>")
	)
	(segment
		(start 150.42896 -52.74691)
		(end 150.403814 -52.90185)
		(width 0.1143)
		(layer "B.Cu")
		(net "UPI_CPU0_CPU1_P1P1_DN<0>")
	)
	(segment
		(start 276.386036 -51.501294)
		(end 276.196298 -52.449984)
		(width 0.1143)
		(layer "B.Cu")
		(net "UPI_CPU0_CPU1_P1P1_DN<0>")
	)
	(segment
		(start 285.33979 -51.877976)
		(end 284.54731 -51.966876)
		(width 0.1143)
		(layer "B.Cu")
		(net "UPI_CPU0_CPU1_P1P1_DN<0>")
	)
	(segment
		(start 243.437918 -49.41697)
		(end 243.404644 -49.390046)
		(width 0.1143)
		(layer "B.Cu")
		(net "UPI_CPU0_CPU1_P1P1_DN<0>")
	)
	(segment
		(start 274.01012 -52.998624)
		(end 273.925792 -53.135784)
		(width 0.1143)
		(layer "B.Cu")
		(net "UPI_CPU0_CPU1_P1P1_DN<0>")
	)
	(segment
		(start 250.219718 -51.152806)
		(end 248.86412 -52.047394)
		(width 0.1143)
		(layer "B.Cu")
		(net "UPI_CPU0_CPU1_P1P1_DN<0>")
	)
	(segment
		(start 275.282914 -52.695348)
		(end 275.071332 -51.80711)
		(width 0.1143)
		(layer "B.Cu")
		(net "UPI_CPU0_CPU1_P1P1_DN<0>")
	)
	(segment
		(start 257.2258 -50.578258)
		(end 256.034794 -50.816256)
		(width 0.1143)
		(layer "B.Cu")
		(net "UPI_CPU0_CPU1_P1P1_DN<0>")
	)
	(segment
		(start 148.317458 -52.914296)
		(end 148.257006 -53.2892)
		(width 0.1143)
		(layer "B.Cu")
		(net "UPI_CPU0_CPU1_P1P1_DN<0>")
	)
	(segment
		(start 196.282056 -43.382692)
		(end 192.036446 -46.61662)
		(width 0.1143)
		(layer "B.Cu")
		(net "UPI_CPU0_CPU1_P1P1_DN<0>")
	)
	(segment
		(start 145.540984 -55.36819)
		(end 145.291048 -55.022242)
		(width 0.1143)
		(layer "B.Cu")
		(net "UPI_CPU0_CPU1_P1P1_DN<0>")
	)
	(segment
		(start 149.285198 -52.57546)
		(end 148.878798 -52.509166)
		(width 0.1143)
		(layer "B.Cu")
		(net "UPI_CPU0_CPU1_P1P1_DN<0>")
	)
	(segment
		(start 279.019254 -53.146198)
		(end 278.244808 -53.301138)
		(width 0.1143)
		(layer "B.Cu")
		(net "UPI_CPU0_CPU1_P1P1_DN<0>")
	)
	(segment
		(start 286.6771 -52.8193)
		(end 286.287972 -52.8193)
		(width 0.1143)
		(layer "B.Cu")
		(net "UPI_CPU0_CPU1_P1P1_DN<0>")
	)
	(segment
		(start 272.150078 -52.232052)
		(end 271.373854 -51.33594)
		(width 0.1143)
		(layer "B.Cu")
		(net "UPI_CPU0_CPU1_P1P1_DN<0>")
	)
	(segment
		(start 264.928858 -50.709322)
		(end 263.78408 -50.93843)
		(width 0.1143)
		(layer "B.Cu")
		(net "UPI_CPU0_CPU1_P1P1_DN<0>")
	)
	(segment
		(start 227.937568 -51.351942)
		(end 207.24876 -47.211488)
		(width 0.1143)
		(layer "B.Cu")
		(net "UPI_CPU0_CPU1_P1P1_DN<0>")
	)
	(segment
		(start 248.86412 -52.047394)
		(end 247.206008 -52.454556)
		(width 0.1143)
		(layer "B.Cu")
		(net "UPI_CPU0_CPU1_P1P1_DN<0>")
	)
	(segment
		(start 287.30575 -52.837588)
		(end 286.695388 -52.837588)
		(width 0.0889)
		(layer "B.Cu")
		(net "UPI_CPU0_CPU1_P1P1_DN<0>")
	)
	(segment
		(start 284.294326 -53.04155)
		(end 282.439364 -53.247798)
		(width 0.1143)
		(layer "B.Cu")
		(net "UPI_CPU0_CPU1_P1P1_DN<0>")
	)
	(segment
		(start 149.80539 -51.447446)
		(end 149.747986 -51.804316)
		(width 0.1143)
		(layer "B.Cu")
		(net "UPI_CPU0_CPU1_P1P1_DN<0>")
	)
	(segment
		(start 207.24876 -47.211488)
		(end 200.74255 -42.888662)
		(width 0.1143)
		(layer "B.Cu")
		(net "UPI_CPU0_CPU1_P1P1_DN<0>")
	)
	(segment
		(start 290.529518 -55.293768)
		(end 290.311078 -55.293768)
		(width 0.0889)
		(layer "B.Cu")
		(net "UPI_CPU0_CPU1_P1P1_DN<0>")
	)
	(segment
		(start 247.205754 -52.454556)
		(end 246.453152 -52.439316)
		(width 0.1143)
		(layer "B.Cu")
		(net "UPI_CPU0_CPU1_P1P1_DN<0>")
	)
	(segment
		(start 138.82243 -58.550048)
		(end 138.529314 -58.381138)
		(width 0.0889)
		(layer "B.Cu")
		(net "UPI_CPU0_CPU1_P1P1_DN<0>")
	)
	(segment
		(start 144.51457 -55.306722)
		(end 144.499076 -55.322216)
		(width 0.0889)
		(layer "B.Cu")
		(net "UPI_CPU0_CPU1_P1P1_DN<0>")
	)
	(segment
		(start 247.206008 -52.454556)
		(end 247.205754 -52.454556)
		(width 0.1143)
		(layer "B.Cu")
		(net "UPI_CPU0_CPU1_P1P1_DN<0>")
	)
	(segment
		(start 147.527518 -53.692044)
		(end 147.12061 -53.626258)
		(width 0.1143)
		(layer "B.Cu")
		(net "UPI_CPU0_CPU1_P1P1_DN<0>")
	)
	(segment
		(start 279.907238 -51.815492)
		(end 279.159716 -51.965098)
		(width 0.1143)
		(layer "B.Cu")
		(net "UPI_CPU0_CPU1_P1P1_DN<0>")
	)
	(segment
		(start 243.459254 -49.434496)
		(end 243.44249 -49.42078)
		(width 0.1143)
		(layer "B.Cu")
		(net "UPI_CPU0_CPU1_P1P1_DN<0>")
	)
	(segment
		(start 277.465282 -52.776628)
		(end 277.668736 -51.759104)
		(width 0.1143)
		(layer "B.Cu")
		(net "UPI_CPU0_CPU1_P1P1_DN<0>")
	)
	(segment
		(start 265.630914 -50.830988)
		(end 265.0236 -50.709322)
		(width 0.1143)
		(layer "B.Cu")
		(net "UPI_CPU0_CPU1_P1P1_DN<0>")
	)
	(segment
		(start 149.758654 -53.231288)
		(end 149.285198 -52.57546)
		(width 0.1143)
		(layer "B.Cu")
		(net "UPI_CPU0_CPU1_P1P1_DN<0>")
	)
	(segment
		(start 285.821882 -52.87137)
		(end 285.696152 -52.77104)
		(width 0.1143)
		(layer "B.Cu")
		(net "UPI_CPU0_CPU1_P1P1_DN<0>")
	)
	(segment
		(start 273.988022 -51.802792)
		(end 273.798538 -52.110386)
		(width 0.1143)
		(layer "B.Cu")
		(net "UPI_CPU0_CPU1_P1P1_DN<0>")
	)
	(segment
		(start 200.74255 -42.888662)
		(end 198.454264 -42.430192)
		(width 0.1143)
		(layer "B.Cu")
		(net "UPI_CPU0_CPU1_P1P1_DN<0>")
	)
	(segment
		(start 149.917404 -53.256688)
		(end 149.758654 -53.231288)
		(width 0.1143)
		(layer "B.Cu")
		(net "UPI_CPU0_CPU1_P1P1_DN<0>")
	)
	(segment
		(start 240.940844 -48.435514)
		(end 238.464598 -49.033938)
		(width 0.1143)
		(layer "B.Cu")
		(net "UPI_CPU0_CPU1_P1P1_DN<0>")
	)
	(segment
		(start 286.287972 -52.8193)
		(end 285.821882 -52.87137)
		(width 0.1143)
		(layer "B.Cu")
		(net "UPI_CPU0_CPU1_P1P1_DN<0>")
	)
	(segment
		(start 236.42193 -49.442116)
		(end 228.03739 -51.350926)
		(width 0.1143)
		(layer "B.Cu")
		(net "UPI_CPU0_CPU1_P1P1_DN<0>")
	)
	(segment
		(start 250.858782 -50.4317)
		(end 250.539504 -50.83302)
		(width 0.1143)
		(layer "B.Cu")
		(net "UPI_CPU0_CPU1_P1P1_DN<0>")
	)
	(segment
		(start 184.591706 -46.565058)
		(end 173.587156 -48.738282)
		(width 0.1143)
		(layer "B.Cu")
		(net "UPI_CPU0_CPU1_P1P1_DN<0>")
	)
	(segment
		(start 273.798538 -52.110386)
		(end 274.01012 -52.998624)
		(width 0.1143)
		(layer "B.Cu")
		(net "UPI_CPU0_CPU1_P1P1_DN<0>")
	)
	(segment
		(start 150.403306 -52.905914)
		(end 149.917404 -53.256688)
		(width 0.1143)
		(layer "B.Cu")
		(net "UPI_CPU0_CPU1_P1P1_DN<0>")
	)
	(segment
		(start 254.84328 -51.055016)
		(end 252.347222 -50.4317)
		(width 0.1143)
		(layer "B.Cu")
		(net "UPI_CPU0_CPU1_P1P1_DN<0>")
	)
	(segment
		(start 141.451584 -57.685686)
		(end 141.45641 -57.694322)
		(width 0.0889)
		(layer "B.Cu")
		(net "UPI_CPU0_CPU1_P1P1_DN<0>")
	)
	(segment
		(start 241.047778 -48.434244)
		(end 240.940844 -48.435514)
		(width 0.1143)
		(layer "B.Cu")
		(net "UPI_CPU0_CPU1_P1P1_DN<0>")
	)
	(segment
		(start 277.668736 -51.759104)
		(end 277.468838 -51.45786)
		(width 0.1143)
		(layer "B.Cu")
		(net "UPI_CPU0_CPU1_P1P1_DN<0>")
	)
	(segment
		(start 142.1384 -56.799988)
		(end 141.941804 -56.799988)
		(width 0.0889)
		(layer "B.Cu")
		(net "UPI_CPU0_CPU1_P1P1_DN<0>")
	)
	(segment
		(start 284.395672 -52.91582)
		(end 284.294326 -53.04155)
		(width 0.1143)
		(layer "B.Cu")
		(net "UPI_CPU0_CPU1_P1P1_DN<0>")
	)
	(segment
		(start 262.214106 -51.774598)
		(end 261.376668 -51.606958)
		(width 0.1143)
		(layer "B.Cu")
		(net "UPI_CPU0_CPU1_P1P1_DN<0>")
	)
	(segment
		(start 279.108916 -53.012086)
		(end 279.019254 -53.146198)
		(width 0.1143)
		(layer "B.Cu")
		(net "UPI_CPU0_CPU1_P1P1_DN<0>")
	)
	(segment
		(start 290.311078 -55.293768)
		(end 289.3314 -54.31409)
		(width 0.0889)
		(layer "B.Cu")
		(net "UPI_CPU0_CPU1_P1P1_DN<0>")
	)
	(segment
		(start 265.0236 -50.709322)
		(end 264.928858 -50.709322)
		(width 0.1143)
		(layer "B.Cu")
		(net "UPI_CPU0_CPU1_P1P1_DN<0>")
	)
	(segment
		(start 266.87526 -50.795682)
		(end 266.341352 -50.689002)
		(width 0.1143)
		(layer "B.Cu")
		(net "UPI_CPU0_CPU1_P1P1_DN<0>")
	)
	(segment
		(start 149.002242 -54.321456)
		(end 148.964396 -54.55539)
		(width 0.1143)
		(layer "B.Cu")
		(net "UPI_CPU0_CPU1_P1P1_DN<0>")
	)
	(segment
		(start 148.964396 -54.55539)
		(end 148.522182 -54.874668)
		(width 0.1143)
		(layer "B.Cu")
		(net "UPI_CPU0_CPU1_P1P1_DN<0>")
	)
	(segment
		(start 145.291048 -55.022242)
		(end 144.934178 -54.964838)
		(width 0.1143)
		(layer "B.Cu")
		(net "UPI_CPU0_CPU1_P1P1_DN<0>")
	)
	(segment
		(start 184.592722 -46.564804)
		(end 184.591706 -46.565058)
		(width 0.1143)
		(layer "B.Cu")
		(net "UPI_CPU0_CPU1_P1P1_DN<0>")
	)
	(segment
		(start 250.539504 -50.83302)
		(end 250.219718 -51.152806)
		(width 0.1143)
		(layer "B.Cu")
		(net "UPI_CPU0_CPU1_P1P1_DN<0>")
	)
	(segment
		(start 263.78408 -50.93843)
		(end 262.665464 -51.684174)
		(width 0.1143)
		(layer "B.Cu")
		(net "UPI_CPU0_CPU1_P1P1_DN<0>")
	)
	(segment
		(start 286.695388 -52.837588)
		(end 286.6771 -52.8193)
		(width 0.0889)
		(layer "B.Cu")
		(net "UPI_CPU0_CPU1_P1P1_DN<0>")
	)
	(segment
		(start 144.499076 -55.358284)
		(end 143.552672 -56.304688)
		(width 0.0889)
		(layer "B.Cu")
		(net "UPI_CPU0_CPU1_P1P1_DN<0>")
	)
	(segment
		(start 274.763738 -51.617626)
		(end 273.988022 -51.802792)
		(width 0.1143)
		(layer "B.Cu")
		(net "UPI_CPU0_CPU1_P1P1_DN<0>")
	)
	(segment
		(start 273.035268 -53.34762)
		(end 272.716244 -53.142388)
		(width 0.1143)
		(layer "B.Cu")
		(net "UPI_CPU0_CPU1_P1P1_DN<0>")
	)
	(segment
		(start 150.403814 -52.90185)
		(end 150.403306 -52.905914)
		(width 0.1143)
		(layer "B.Cu")
		(net "UPI_CPU0_CPU1_P1P1_DN<0>")
	)
	(segment
		(start 149.001988 -54.321456)
		(end 149.002242 -54.321456)
		(width 0.1143)
		(layer "B.Cu")
		(net "UPI_CPU0_CPU1_P1P1_DN<0>")
	)
	(segment
		(start 268.21638 -51.326542)
		(end 267.438378 -51.171094)
		(width 0.1143)
		(layer "B.Cu")
		(net "UPI_CPU0_CPU1_P1P1_DN<0>")
	)
	(segment
		(start 228.03739 -51.350926)
		(end 227.937568 -51.351942)
		(width 0.1143)
		(layer "B.Cu")
		(net "UPI_CPU0_CPU1_P1P1_DN<0>")
	)
	(segment
		(start 252.347222 -50.4317)
		(end 250.858782 -50.4317)
		(width 0.1143)
		(layer "B.Cu")
		(net "UPI_CPU0_CPU1_P1P1_DN<0>")
	)
	(segment
		(start 140.267944 -57.790588)
		(end 140.224764 -57.790588)
		(width 0.0889)
		(layer "B.Cu")
		(net "UPI_CPU0_CPU1_P1P1_DN<0>")
	)
	(segment
		(start 144.934178 -54.964838)
		(end 144.669256 -55.1561)
		(width 0.1143)
		(layer "B.Cu")
		(net "UPI_CPU0_CPU1_P1P1_DN<0>")
	)
	(segment
		(start 238.464598 -49.033938)
		(end 238.462566 -49.034192)
		(width 0.1143)
		(layer "B.Cu")
		(net "UPI_CPU0_CPU1_P1P1_DN<0>")
	)
	(segment
		(start 276.196298 -52.449984)
		(end 275.859748 -52.674774)
		(width 0.1143)
		(layer "B.Cu")
		(net "UPI_CPU0_CPU1_P1P1_DN<0>")
	)
	(segment
		(start 246.453152 -52.439316)
		(end 245.7577 -51.93411)
		(width 0.1143)
		(layer "B.Cu")
		(net "UPI_CPU0_CPU1_P1P1_DN<0>")
	)
	(segment
		(start 144.66951 -55.1561)
		(end 144.6403 -55.180992)
		(width 0.1143)
		(layer "B.Cu")
		(net "UPI_CPU0_CPU1_P1P1_DN<0>")
	)
	(segment
		(start 270.984472 -51.10861)
		(end 270.145764 -50.94097)
		(width 0.1143)
		(layer "B.Cu")
		(net "UPI_CPU0_CPU1_P1P1_DN<0>")
	)
	(segment
		(start 276.687534 -51.301396)
		(end 276.386036 -51.501294)
		(width 0.1143)
		(layer "B.Cu")
		(net "UPI_CPU0_CPU1_P1P1_DN<0>")
	)
	(segment
		(start 289.3314 -53.24856)
		(end 288.90214 -52.8193)
		(width 0.0889)
		(layer "B.Cu")
		(net "UPI_CPU0_CPU1_P1P1_DN<0>")
	)
	(segment
		(start 245.754652 -51.93157)
		(end 245.74881 -51.92649)
		(width 0.1143)
		(layer "B.Cu")
		(net "UPI_CPU0_CPU1_P1P1_DN<0>")
	)
	(segment
		(start 289.3314 -54.31409)
		(end 289.3314 -53.24856)
		(width 0.0889)
		(layer "B.Cu")
		(net "UPI_CPU0_CPU1_P1P1_DN<0>")
	)
	(segment
		(start 141.11986 -58.285634)
		(end 141.089888 -58.285634)
		(width 0.0889)
		(layer "B.Cu")
		(net "UPI_CPU0_CPU1_P1P1_DN<0>")
	)
	(segment
		(start 273.925792 -53.135784)
		(end 273.035268 -53.34762)
		(width 0.1143)
		(layer "B.Cu")
		(net "UPI_CPU0_CPU1_P1P1_DN<0>")
	)
	(segment
		(start 290.6522 -54.913784)
		(end 290.6522 -55.171086)
		(width 0.0889)
		(layer "B.Cu")
		(net "UPI_CPU0_CPU1_P1P1_DN<0>")
	)
	(segment
		(start 277.749 -53.20157)
		(end 277.465282 -52.776628)
		(width 0.1143)
		(layer "B.Cu")
		(net "UPI_CPU0_CPU1_P1P1_DN<0>")
	)
	(segment
		(start 278.244808 -53.301138)
		(end 277.749 -53.20157)
		(width 0.1143)
		(layer "B.Cu")
		(net "UPI_CPU0_CPU1_P1P1_DN<0>")
	)
	(segment
		(start 260.950964 -51.323494)
		(end 257.2258 -50.578258)
		(width 0.1143)
		(layer "B.Cu")
		(net "UPI_CPU0_CPU1_P1P1_DN<0>")
	)
	(segment
		(start 243.44249 -49.42078)
		(end 243.441474 -49.420018)
		(width 0.1143)
		(layer "B.Cu")
		(net "UPI_CPU0_CPU1_P1P1_DN<0>")
	)
	(segment
		(start 139.40282 -58.285634)
		(end 139.37488 -58.285634)
		(width 0.0889)
		(layer "B.Cu")
		(net "UPI_CPU0_CPU1_P1P1_DN<0>")
	)
	(segment
		(start 146.074892 -54.696106)
		(end 146.21129 -54.884574)
		(width 0.1143)
		(layer "B.Cu")
		(net "UPI_CPU0_CPU1_P1P1_DN<0>")
	)
	(segment
		(start 142.63624 -56.304688)
		(end 142.36319 -56.577738)
		(width 0.0889)
		(layer "B.Cu")
		(net "UPI_CPU0_CPU1_P1P1_DN<0>")
	)
	(segment
		(start 138.911838 -58.525918)
		(end 138.82243 -58.550048)
		(width 0.0889)
		(layer "B.Cu")
		(net "UPI_CPU0_CPU1_P1P1_DN<0>")
	)
	(segment
		(start 288.90214 -52.8193)
		(end 288.57956 -52.8193)
		(width 0.0889)
		(layer "B.Cu")
		(net "UPI_CPU0_CPU1_P1P1_DN<0>")
	)
	(segment
		(start 280.249122 -52.04333)
		(end 279.907238 -51.815492)
		(width 0.1143)
		(layer "B.Cu")
		(net "UPI_CPU0_CPU1_P1P1_DN<0>")
	)
	(segment
		(start 243.404644 -49.390046)
		(end 242.212876 -48.682148)
		(width 0.1143)
		(layer "B.Cu")
		(net "UPI_CPU0_CPU1_P1P1_DN<0>")
	)
	(segment
		(start 184.593484 -46.564804)
		(end 184.592722 -46.564804)
		(width 0.1143)
		(layer "B.Cu")
		(net "UPI_CPU0_CPU1_P1P1_DN<0>")
	)
	(segment
		(start 266.341352 -50.689002)
		(end 265.630914 -50.830988)
		(width 0.1143)
		(layer "B.Cu")
		(net "UPI_CPU0_CPU1_P1P1_DN<0>")
	)
	(segment
		(start 280.56967 -52.87391)
		(end 280.39187 -52.755292)
		(width 0.1143)
		(layer "B.Cu")
		(net "UPI_CPU0_CPU1_P1P1_DN<0>")
	)
	(segment
		(start 245.7577 -51.93411)
		(end 245.754652 -51.93157)
		(width 0.1143)
		(layer "B.Cu")
		(net "UPI_CPU0_CPU1_P1P1_DN<0>")
	)
	(segment
		(start 270.145764 -50.94097)
		(end 268.21638 -51.326542)
		(width 0.1143)
		(layer "B.Cu")
		(net "UPI_CPU0_CPU1_P1P1_DN<0>")
	)
	(segment
		(start 161.103056 -50.05832)
		(end 156.09697 -49.066958)
		(width 0.1143)
		(layer "B.Cu")
		(net "UPI_CPU0_CPU1_P1P1_DN<0>")
	)
	(segment
		(start 146.21129 -54.884574)
		(end 146.185636 -55.043324)
		(width 0.1143)
		(layer "B.Cu")
		(net "UPI_CPU0_CPU1_P1P1_DN<0>")
	)
	(segment
		(start 144.499076 -55.322216)
		(end 144.499076 -55.358284)
		(width 0.0889)
		(layer "B.Cu")
		(net "UPI_CPU0_CPU1_P1P1_DN<0>")
	)
	(segment
		(start 145.699988 -55.394098)
		(end 145.540984 -55.36819)
		(width 0.1143)
		(layer "B.Cu")
		(net "UPI_CPU0_CPU1_P1P1_DN<0>")
	)
	(segment
		(start 282.439364 -53.247798)
		(end 280.56967 -52.87391)
		(width 0.1143)
		(layer "B.Cu")
		(net "UPI_CPU0_CPU1_P1P1_DN<0>")
	)
	(segment
		(start 198.454264 -42.430192)
		(end 196.282056 -43.382692)
		(width 0.1143)
		(layer "B.Cu")
		(net "UPI_CPU0_CPU1_P1P1_DN<0>")
	)
	(segment
		(start 148.257006 -53.2892)
		(end 149.001988 -54.321456)
		(width 0.1143)
		(layer "B.Cu")
		(net "UPI_CPU0_CPU1_P1P1_DN<0>")
	)
	(segment
		(start 285.696152 -52.77104)
		(end 285.62173 -52.10429)
		(width 0.1143)
		(layer "B.Cu")
		(net "UPI_CPU0_CPU1_P1P1_DN<0>")
	)
	(segment
		(start 243.441474 -49.420018)
		(end 243.437918 -49.41697)
		(width 0.1143)
		(layer "B.Cu")
		(net "UPI_CPU0_CPU1_P1P1_DN<0>")
	)
	(segment
		(start 261.376668 -51.606958)
		(end 260.950964 -51.323494)
		(width 0.1143)
		(layer "B.Cu")
		(net "UPI_CPU0_CPU1_P1P1_DN<0>")
	)
	(segment
		(start 147.12061 -53.626258)
		(end 146.13255 -54.339744)
		(width 0.1143)
		(layer "B.Cu")
		(net "UPI_CPU0_CPU1_P1P1_DN<0>")
	)
	(segment
		(start 272.716244 -53.142388)
		(end 272.150078 -52.232052)
		(width 0.1143)
		(layer "B.Cu")
		(net "UPI_CPU0_CPU1_P1P1_DN<0>")
	)
	(segment
		(start 288.57956 -52.8193)
		(end 287.30575 -52.837588)
		(width 0.0889)
		(layer "B.Cu")
		(net "UPI_CPU0_CPU1_P1P1_DN<0>")
	)
	(segment
		(start 184.873138 -46.509432)
		(end 184.593484 -46.564804)
		(width 0.1143)
		(layer "B.Cu")
		(net "UPI_CPU0_CPU1_P1P1_DN<0>")
	)
	(segment
		(start 284.32125 -52.248816)
		(end 284.395672 -52.91582)
		(width 0.1143)
		(layer "B.Cu")
		(net "UPI_CPU0_CPU1_P1P1_DN<0>")
	)
	(segment
		(start 256.034794 -50.81651)
		(end 254.84328 -51.055016)
		(width 0.1143)
		(layer "B.Cu")
		(net "UPI_CPU0_CPU1_P1P1_DN<0>")
	)
	(segment
		(start 148.363432 -54.849014)
		(end 147.527518 -53.692044)
		(width 0.1143)
		(layer "B.Cu")
		(net "UPI_CPU0_CPU1_P1P1_DN<0>")
	)
	(segment
		(start 151.956008 -49.894744)
		(end 149.80539 -51.447446)
		(width 0.1143)
		(layer "B.Cu")
		(net "UPI_CPU0_CPU1_P1P1_DN<0>")
	)
	(segment
		(start 275.071332 -51.80711)
		(end 274.763738 -51.617626)
		(width 0.1143)
		(layer "B.Cu")
		(net "UPI_CPU0_CPU1_P1P1_DN<0>")
	)
	(segment
		(start 284.54731 -51.966876)
		(end 284.32125 -52.248816)
		(width 0.1143)
		(layer "B.Cu")
		(net "UPI_CPU0_CPU1_P1P1_DN<0>")
	)
	(segment
		(start 146.185636 -55.043324)
		(end 145.699988 -55.394098)
		(width 0.1143)
		(layer "B.Cu")
		(net "UPI_CPU0_CPU1_P1P1_DN<0>")
	)
	(segment
		(start 149.747986 -51.804316)
		(end 150.42896 -52.74691)
		(width 0.1143)
		(layer "B.Cu")
		(net "UPI_CPU0_CPU1_P1P1_DN<0>")
	)
	(segment
		(start 144.669256 -55.1561)
		(end 144.66951 -55.1561)
		(width 0.1143)
		(layer "B.Cu")
		(net "UPI_CPU0_CPU1_P1P1_DN<0>")
	)
	(segment
		(start 148.878798 -52.509166)
		(end 148.317458 -52.914296)
		(width 0.1143)
		(layer "B.Cu")
		(net "UPI_CPU0_CPU1_P1P1_DN<0>")
	)
	(segment
		(start 275.859748 -52.674774)
		(end 275.420328 -52.779676)
		(width 0.1143)
		(layer "B.Cu")
		(net "UPI_CPU0_CPU1_P1P1_DN<0>")
	)
	(segment
		(start 144.6403 -55.180992)
		(end 144.51457 -55.306722)
		(width 0.1143)
		(layer "B.Cu")
		(net "UPI_CPU0_CPU1_P1P1_DN<0>")
	)
	(segment
		(start 142.36319 -56.577738)
		(end 142.349728 -56.603392)
		(width 0.0889)
		(layer "B.Cu")
		(net "UPI_CPU0_CPU1_P1P1_DN<0>")
	)
	(segment
		(start 271.373854 -51.33594)
		(end 270.984472 -51.10861)
		(width 0.1143)
		(layer "B.Cu")
		(net "UPI_CPU0_CPU1_P1P1_DN<0>")
	)
	(segment
		(start 173.587156 -48.738282)
		(end 167.473884 -51.319684)
		(width 0.1143)
		(layer "B.Cu")
		(net "UPI_CPU0_CPU1_P1P1_DN<0>")
	)
	(segment
		(start 141.445234 -57.675018)
		(end 141.451584 -57.685686)
		(width 0.0889)
		(layer "B.Cu")
		(net "UPI_CPU0_CPU1_P1P1_DN<0>")
	)
	(segment
		(start 275.420328 -52.779676)
		(end 275.282914 -52.695348)
		(width 0.1143)
		(layer "B.Cu")
		(net "UPI_CPU0_CPU1_P1P1_DN<0>")
	)
	(segment
		(start 156.09697 -49.066958)
		(end 151.956008 -49.894744)
		(width 0.1143)
		(layer "B.Cu")
		(net "UPI_CPU0_CPU1_P1P1_DN<0>")
	)
	(segment
		(start 279.159716 -51.965098)
		(end 278.95931 -52.265834)
		(width 0.1143)
		(layer "B.Cu")
		(net "UPI_CPU0_CPU1_P1P1_DN<0>")
	)
	(segment
		(start 143.552672 -56.304688)
		(end 142.63624 -56.304688)
		(width 0.0889)
		(layer "B.Cu")
		(net "UPI_CPU0_CPU1_P1P1_DN<0>")
	)
	(segment
		(start 245.739666 -51.918108)
		(end 243.459254 -49.434496)
		(width 0.1143)
		(layer "B.Cu")
		(net "UPI_CPU0_CPU1_P1P1_DN<0>")
	)
	(segment
		(start 242.212876 -48.682148)
		(end 241.047778 -48.434244)
		(width 0.1143)
		(layer "B.Cu")
		(net "UPI_CPU0_CPU1_P1P1_DN<0>")
	)
	(segment
		(start 277.468838 -51.45786)
		(end 276.687534 -51.301396)
		(width 0.1143)
		(layer "B.Cu")
		(net "UPI_CPU0_CPU1_P1P1_DN<0>")
	)
	(segment
		(start 280.39187 -52.755292)
		(end 280.249122 -52.04333)
		(width 0.1143)
		(layer "B.Cu")
		(net "UPI_CPU0_CPU1_P1P1_DN<0>")
	)
	(segment
		(start 146.13255 -54.339744)
		(end 146.074892 -54.696106)
		(width 0.1143)
		(layer "B.Cu")
		(net "UPI_CPU0_CPU1_P1P1_DN<0>")
	)
	(arc
		(start 141.089888 -58.285634)
		(mid 140.898246 -58.228468)
		(end 140.758164 -58.085736)
		(width 0.0889)
		(layer "B.Cu")
		(net "UPI_CPU0_CPU1_P1P1_DN<0>")
	)
	(arc
		(start 142.349728 -56.603392)
		(mid 142.260772 -56.719647)
		(end 142.1384 -56.799988)
		(width 0.0889)
		(layer "B.Cu")
		(net "UPI_CPU0_CPU1_P1P1_DN<0>")
	)
	(arc
		(start 141.45641 -57.694322)
		(mid 141.452663 -58.083578)
		(end 141.11986 -58.285634)
		(width 0.0889)
		(layer "B.Cu")
		(net "UPI_CPU0_CPU1_P1P1_DN<0>")
	)
	(arc
		(start 139.37488 -58.285634)
		(mid 139.115404 -58.351909)
		(end 138.911838 -58.525918)
		(width 0.0889)
		(layer "B.Cu")
		(net "UPI_CPU0_CPU1_P1P1_DN<0>")
	)
	(arc
		(start 140.758164 -58.085736)
		(mid 140.55116 -57.874872)
		(end 140.267944 -57.790588)
		(width 0.0889)
		(layer "B.Cu")
		(net "UPI_CPU0_CPU1_P1P1_DN<0>")
	)
	(arc
		(start 140.224764 -57.790588)
		(mid 139.941547 -57.874869)
		(end 139.734544 -58.085736)
		(width 0.0889)
		(layer "B.Cu")
		(net "UPI_CPU0_CPU1_P1P1_DN<0>")
	)
	(arc
		(start 141.941804 -56.799988)
		(mid 141.449414 -57.098921)
		(end 141.445234 -57.675018)
		(width 0.0889)
		(layer "B.Cu")
		(net "UPI_CPU0_CPU1_P1P1_DN<0>")
	)
	(arc
		(start 139.734544 -58.085736)
		(mid 139.594465 -58.228472)
		(end 139.40282 -58.285634)
		(width 0.0889)
		(layer "B.Cu")
		(net "UPI_CPU0_CPU1_P1P1_DN<0>")
	)
	(segment
		(start 305.533806 -65.810384)
		(end 306.105306 -65.810384)
		(width 0.1143)
		(layer "F.Cu")
		(net "UPI_CPU0_CPU1_P0P0_DP<9>")
	)
	(segment
		(start 135.382254 -66.800984)
		(end 135.953754 -66.800984)
		(width 0.1143)
		(layer "F.Cu")
		(net "UPI_CPU0_CPU1_P0P0_DP<9>")
	)
	(via
		(at 306.105306 -65.810384)
		(size 0.508)
		(drill 0.254)
		(layers "F.Cu" "B.Cu")
		(net "UPI_CPU0_CPU1_P0P0_DP<9>")
	)
	(via
		(at 135.953754 -66.800984)
		(size 0.508)
		(drill 0.254)
		(layers "F.Cu" "B.Cu")
		(net "UPI_CPU0_CPU1_P0P0_DP<9>")
	)
	(segment
		(start 135.953754 -66.800984)
		(end 136.726422 -66.890392)
		(width 0.0889)
		(layer "In9.Cu")
		(net "UPI_CPU0_CPU1_P0P0_DP<9>")
	)
	(segment
		(start 227.934012 -111.960152)
		(end 247.932956 -115.364768)
		(width 0.1143)
		(layer "In9.Cu")
		(net "UPI_CPU0_CPU1_P0P0_DP<9>")
	)
	(segment
		(start 311.739788 -67.441064)
		(end 311.478422 -67.222624)
		(width 0.1143)
		(layer "In9.Cu")
		(net "UPI_CPU0_CPU1_P0P0_DP<9>")
	)
	(segment
		(start 291.125402 -108.97616)
		(end 291.50691 -108.817918)
		(width 0.1143)
		(layer "In9.Cu")
		(net "UPI_CPU0_CPU1_P0P0_DP<9>")
	)
	(segment
		(start 312.381138 -68.4276)
		(end 311.739788 -67.441064)
		(width 0.1143)
		(layer "In9.Cu")
		(net "UPI_CPU0_CPU1_P0P0_DP<9>")
	)
	(segment
		(start 292.10381 -108.76407)
		(end 302.8188 -111.496348)
		(width 0.1143)
		(layer "In9.Cu")
		(net "UPI_CPU0_CPU1_P0P0_DP<9>")
	)
	(segment
		(start 136.794494 -66.896488)
		(end 136.82726 -66.896488)
		(width 0.0889)
		(layer "In9.Cu")
		(net "UPI_CPU0_CPU1_P0P0_DP<9>")
	)
	(segment
		(start 154.746452 -87.61476)
		(end 161.062924 -95.08998)
		(width 0.1143)
		(layer "In9.Cu")
		(net "UPI_CPU0_CPU1_P0P0_DP<9>")
	)
	(segment
		(start 139.366244 -68.382134)
		(end 139.409424 -68.382134)
		(width 0.0889)
		(layer "In9.Cu")
		(net "UPI_CPU0_CPU1_P0P0_DP<9>")
	)
	(segment
		(start 161.738564 -99.458526)
		(end 168.572942 -106.11358)
		(width 0.1143)
		(layer "In9.Cu")
		(net "UPI_CPU0_CPU1_P0P0_DP<9>")
	)
	(segment
		(start 247.932956 -115.364768)
		(end 258.412996 -112.896904)
		(width 0.1143)
		(layer "In9.Cu")
		(net "UPI_CPU0_CPU1_P0P0_DP<9>")
	)
	(segment
		(start 314.689744 -77.285342)
		(end 314.57519 -73.162922)
		(width 0.1143)
		(layer "In9.Cu")
		(net "UPI_CPU0_CPU1_P0P0_DP<9>")
	)
	(segment
		(start 196.63918 -115.72621)
		(end 227.934012 -111.960152)
		(width 0.1143)
		(layer "In9.Cu")
		(net "UPI_CPU0_CPU1_P0P0_DP<9>")
	)
	(segment
		(start 141.945868 -67.887088)
		(end 142.141194 -67.887088)
		(width 0.0889)
		(layer "In9.Cu")
		(net "UPI_CPU0_CPU1_P0P0_DP<9>")
	)
	(segment
		(start 317.113412 -86.407498)
		(end 314.771786 -80.247998)
		(width 0.1143)
		(layer "In9.Cu")
		(net "UPI_CPU0_CPU1_P0P0_DP<9>")
	)
	(segment
		(start 312.837322 -69.129148)
		(end 312.381138 -68.4276)
		(width 0.1143)
		(layer "In9.Cu")
		(net "UPI_CPU0_CPU1_P0P0_DP<9>")
	)
	(segment
		(start 307.6956 -110.38713)
		(end 307.90388 -110.339886)
		(width 0.1143)
		(layer "In9.Cu")
		(net "UPI_CPU0_CPU1_P0P0_DP<9>")
	)
	(segment
		(start 143.71447 -69.134228)
		(end 144.174464 -69.134228)
		(width 0.1143)
		(layer "In9.Cu")
		(net "UPI_CPU0_CPU1_P0P0_DP<9>")
	)
	(segment
		(start 278.066246 -112.281716)
		(end 282.04922 -112.743488)
		(width 0.1143)
		(layer "In9.Cu")
		(net "UPI_CPU0_CPU1_P0P0_DP<9>")
	)
	(segment
		(start 140.231368 -67.887088)
		(end 140.26134 -67.887088)
		(width 0.0889)
		(layer "In9.Cu")
		(net "UPI_CPU0_CPU1_P0P0_DP<9>")
	)
	(segment
		(start 306.275232 -66.091054)
		(end 306.275232 -65.98031)
		(width 0.0889)
		(layer "In9.Cu")
		(net "UPI_CPU0_CPU1_P0P0_DP<9>")
	)
	(segment
		(start 142.141194 -67.887088)
		(end 143.337534 -69.083428)
		(width 0.0889)
		(layer "In9.Cu")
		(net "UPI_CPU0_CPU1_P0P0_DP<9>")
	)
	(segment
		(start 311.478422 -67.222624)
		(end 311.072022 -67.222624)
		(width 0.1143)
		(layer "In9.Cu")
		(net "UPI_CPU0_CPU1_P0P0_DP<9>")
	)
	(segment
		(start 137.649204 -67.391534)
		(end 137.68197 -67.391534)
		(width 0.0889)
		(layer "In9.Cu")
		(net "UPI_CPU0_CPU1_P0P0_DP<9>")
	)
	(segment
		(start 143.641572 -69.083428)
		(end 143.692372 -69.134228)
		(width 0.0889)
		(layer "In9.Cu")
		(net "UPI_CPU0_CPU1_P0P0_DP<9>")
	)
	(segment
		(start 143.692372 -69.134228)
		(end 143.71447 -69.134228)
		(width 0.0889)
		(layer "In9.Cu")
		(net "UPI_CPU0_CPU1_P0P0_DP<9>")
	)
	(segment
		(start 309.375556 -66.066924)
		(end 306.569872 -66.066924)
		(width 0.0889)
		(layer "In9.Cu")
		(net "UPI_CPU0_CPU1_P0P0_DP<9>")
	)
	(segment
		(start 168.572942 -106.11358)
		(end 174.715678 -108.256578)
		(width 0.1143)
		(layer "In9.Cu")
		(net "UPI_CPU0_CPU1_P0P0_DP<9>")
	)
	(segment
		(start 306.469796 -66.167)
		(end 306.351178 -66.167)
		(width 0.0889)
		(layer "In9.Cu")
		(net "UPI_CPU0_CPU1_P0P0_DP<9>")
	)
	(segment
		(start 291.50691 -108.817918)
		(end 292.10381 -108.76407)
		(width 0.1143)
		(layer "In9.Cu")
		(net "UPI_CPU0_CPU1_P0P0_DP<9>")
	)
	(segment
		(start 314.57519 -73.162922)
		(end 312.837322 -69.129148)
		(width 0.1143)
		(layer "In9.Cu")
		(net "UPI_CPU0_CPU1_P0P0_DP<9>")
	)
	(segment
		(start 174.715678 -108.256578)
		(end 174.719742 -108.255562)
		(width 0.1143)
		(layer "In9.Cu")
		(net "UPI_CPU0_CPU1_P0P0_DP<9>")
	)
	(segment
		(start 144.174464 -69.134228)
		(end 149.024594 -72.450198)
		(width 0.1143)
		(layer "In9.Cu")
		(net "UPI_CPU0_CPU1_P0P0_DP<9>")
	)
	(segment
		(start 149.024594 -72.450198)
		(end 151.539702 -75.792076)
		(width 0.1143)
		(layer "In9.Cu")
		(net "UPI_CPU0_CPU1_P0P0_DP<9>")
	)
	(segment
		(start 174.719742 -108.255562)
		(end 175.08982 -108.469176)
		(width 0.1143)
		(layer "In9.Cu")
		(net "UPI_CPU0_CPU1_P0P0_DP<9>")
	)
	(segment
		(start 314.771786 -80.247998)
		(end 314.760356 -79.8322)
		(width 0.1143)
		(layer "In9.Cu")
		(net "UPI_CPU0_CPU1_P0P0_DP<9>")
	)
	(segment
		(start 161.062924 -95.08998)
		(end 161.738564 -99.458526)
		(width 0.1143)
		(layer "In9.Cu")
		(net "UPI_CPU0_CPU1_P0P0_DP<9>")
	)
	(segment
		(start 310.582056 -67.273424)
		(end 309.375556 -66.066924)
		(width 0.0889)
		(layer "In9.Cu")
		(net "UPI_CPU0_CPU1_P0P0_DP<9>")
	)
	(segment
		(start 314.760356 -79.8322)
		(end 314.689744 -77.285342)
		(width 0.1143)
		(layer "In9.Cu")
		(net "UPI_CPU0_CPU1_P0P0_DP<9>")
	)
	(segment
		(start 311.072022 -67.222624)
		(end 311.049924 -67.222624)
		(width 0.0889)
		(layer "In9.Cu")
		(net "UPI_CPU0_CPU1_P0P0_DP<9>")
	)
	(segment
		(start 302.8188 -111.496348)
		(end 307.6956 -110.38713)
		(width 0.1143)
		(layer "In9.Cu")
		(net "UPI_CPU0_CPU1_P0P0_DP<9>")
	)
	(segment
		(start 267.173202 -113.327688)
		(end 278.066246 -112.281716)
		(width 0.1143)
		(layer "In9.Cu")
		(net "UPI_CPU0_CPU1_P0P0_DP<9>")
	)
	(segment
		(start 310.999124 -67.273424)
		(end 310.582056 -67.273424)
		(width 0.0889)
		(layer "In9.Cu")
		(net "UPI_CPU0_CPU1_P0P0_DP<9>")
	)
	(segment
		(start 282.04922 -112.743488)
		(end 291.125402 -108.97616)
		(width 0.1143)
		(layer "In9.Cu")
		(net "UPI_CPU0_CPU1_P0P0_DP<9>")
	)
	(segment
		(start 312.963306 -105.665524)
		(end 317.113412 -86.407498)
		(width 0.1143)
		(layer "In9.Cu")
		(net "UPI_CPU0_CPU1_P0P0_DP<9>")
	)
	(segment
		(start 193.358262 -115.94719)
		(end 196.63918 -115.72621)
		(width 0.1143)
		(layer "In9.Cu")
		(net "UPI_CPU0_CPU1_P0P0_DP<9>")
	)
	(segment
		(start 138.511534 -67.887088)
		(end 138.5443 -67.887088)
		(width 0.0889)
		(layer "In9.Cu")
		(net "UPI_CPU0_CPU1_P0P0_DP<9>")
	)
	(segment
		(start 151.539702 -75.792076)
		(end 154.746452 -87.61476)
		(width 0.1143)
		(layer "In9.Cu")
		(net "UPI_CPU0_CPU1_P0P0_DP<9>")
	)
	(segment
		(start 311.049924 -67.222624)
		(end 310.999124 -67.273424)
		(width 0.0889)
		(layer "In9.Cu")
		(net "UPI_CPU0_CPU1_P0P0_DP<9>")
	)
	(segment
		(start 178.410616 -111.437928)
		(end 186.04357 -115.148106)
		(width 0.1143)
		(layer "In9.Cu")
		(net "UPI_CPU0_CPU1_P0P0_DP<9>")
	)
	(segment
		(start 306.351178 -66.167)
		(end 306.275232 -66.091054)
		(width 0.0889)
		(layer "In9.Cu")
		(net "UPI_CPU0_CPU1_P0P0_DP<9>")
	)
	(segment
		(start 186.04357 -115.148106)
		(end 193.358262 -115.94719)
		(width 0.1143)
		(layer "In9.Cu")
		(net "UPI_CPU0_CPU1_P0P0_DP<9>")
	)
	(segment
		(start 306.569872 -66.066924)
		(end 306.469796 -66.167)
		(width 0.0889)
		(layer "In9.Cu")
		(net "UPI_CPU0_CPU1_P0P0_DP<9>")
	)
	(segment
		(start 143.337534 -69.083428)
		(end 143.641572 -69.083428)
		(width 0.0889)
		(layer "In9.Cu")
		(net "UPI_CPU0_CPU1_P0P0_DP<9>")
	)
	(segment
		(start 141.083284 -68.382134)
		(end 141.126464 -68.382134)
		(width 0.0889)
		(layer "In9.Cu")
		(net "UPI_CPU0_CPU1_P0P0_DP<9>")
	)
	(segment
		(start 175.08982 -108.469176)
		(end 178.410616 -111.437928)
		(width 0.1143)
		(layer "In9.Cu")
		(net "UPI_CPU0_CPU1_P0P0_DP<9>")
	)
	(segment
		(start 258.412996 -112.896904)
		(end 267.173202 -113.327688)
		(width 0.1143)
		(layer "In9.Cu")
		(net "UPI_CPU0_CPU1_P0P0_DP<9>")
	)
	(segment
		(start 307.90388 -110.339886)
		(end 312.963306 -105.665524)
		(width 0.1143)
		(layer "In9.Cu")
		(net "UPI_CPU0_CPU1_P0P0_DP<9>")
	)
	(segment
		(start 306.275232 -65.98031)
		(end 306.105306 -65.810384)
		(width 0.0889)
		(layer "In9.Cu")
		(net "UPI_CPU0_CPU1_P0P0_DP<9>")
	)
	(arc
		(start 141.126464 -68.382134)
		(mid 141.409681 -68.297853)
		(end 141.616684 -68.086986)
		(width 0.0889)
		(layer "In9.Cu")
		(net "UPI_CPU0_CPU1_P0P0_DP<9>")
	)
	(arc
		(start 141.616684 -68.086986)
		(mid 141.755677 -67.944906)
		(end 141.945868 -67.887088)
		(width 0.0889)
		(layer "In9.Cu")
		(net "UPI_CPU0_CPU1_P0P0_DP<9>")
	)
	(arc
		(start 139.899644 -68.086986)
		(mid 140.039723 -67.94425)
		(end 140.231368 -67.887088)
		(width 0.0889)
		(layer "In9.Cu")
		(net "UPI_CPU0_CPU1_P0P0_DP<9>")
	)
	(arc
		(start 138.017504 -67.591686)
		(mid 138.226112 -67.803618)
		(end 138.511534 -67.887088)
		(width 0.0889)
		(layer "In9.Cu")
		(net "UPI_CPU0_CPU1_P0P0_DP<9>")
	)
	(arc
		(start 137.158984 -67.096386)
		(mid 137.365988 -67.30725)
		(end 137.649204 -67.391534)
		(width 0.0889)
		(layer "In9.Cu")
		(net "UPI_CPU0_CPU1_P0P0_DP<9>")
	)
	(arc
		(start 140.593064 -68.086986)
		(mid 140.800068 -68.29785)
		(end 141.083284 -68.382134)
		(width 0.0889)
		(layer "In9.Cu")
		(net "UPI_CPU0_CPU1_P0P0_DP<9>")
	)
	(arc
		(start 138.876024 -68.086986)
		(mid 139.083028 -68.29785)
		(end 139.366244 -68.382134)
		(width 0.0889)
		(layer "In9.Cu")
		(net "UPI_CPU0_CPU1_P0P0_DP<9>")
	)
	(arc
		(start 136.82726 -66.896488)
		(mid 137.018902 -66.953654)
		(end 137.158984 -67.096386)
		(width 0.0889)
		(layer "In9.Cu")
		(net "UPI_CPU0_CPU1_P0P0_DP<9>")
	)
	(arc
		(start 136.726422 -66.890392)
		(mid 136.76037 -66.894423)
		(end 136.794494 -66.896488)
		(width 0.0889)
		(layer "In9.Cu")
		(net "UPI_CPU0_CPU1_P0P0_DP<9>")
	)
	(arc
		(start 139.409424 -68.382134)
		(mid 139.692641 -68.297853)
		(end 139.899644 -68.086986)
		(width 0.0889)
		(layer "In9.Cu")
		(net "UPI_CPU0_CPU1_P0P0_DP<9>")
	)
	(arc
		(start 138.5443 -67.887088)
		(mid 138.735942 -67.944254)
		(end 138.876024 -68.086986)
		(width 0.0889)
		(layer "In9.Cu")
		(net "UPI_CPU0_CPU1_P0P0_DP<9>")
	)
	(arc
		(start 137.68197 -67.391534)
		(mid 137.87582 -67.447884)
		(end 138.017504 -67.591686)
		(width 0.0889)
		(layer "In9.Cu")
		(net "UPI_CPU0_CPU1_P0P0_DP<9>")
	)
	(arc
		(start 140.26134 -67.887088)
		(mid 140.452982 -67.944254)
		(end 140.593064 -68.086986)
		(width 0.0889)
		(layer "In9.Cu")
		(net "UPI_CPU0_CPU1_P0P0_DP<9>")
	)
	(segment
		(start 305.533806 -67.791584)
		(end 306.105306 -67.791584)
		(width 0.1143)
		(layer "F.Cu")
		(net "UPI_CPU0_CPU1_P0P0_DP<8>")
	)
	(segment
		(start 137.099294 -65.810384)
		(end 137.670794 -65.810384)
		(width 0.1143)
		(layer "F.Cu")
		(net "UPI_CPU0_CPU1_P0P0_DP<8>")
	)
	(via
		(at 306.105306 -67.791584)
		(size 0.508)
		(drill 0.254)
		(layers "F.Cu" "B.Cu")
		(net "UPI_CPU0_CPU1_P0P0_DP<8>")
	)
	(via
		(at 137.670794 -65.810384)
		(size 0.508)
		(drill 0.254)
		(layers "F.Cu" "B.Cu")
		(net "UPI_CPU0_CPU1_P0P0_DP<8>")
	)
	(segment
		(start 313.432952 -75.974448)
		(end 313.563508 -75.837542)
		(width 0.1143)
		(layer "In9.Cu")
		(net "UPI_CPU0_CPU1_P0P0_DP<8>")
	)
	(segment
		(start 137.670794 -65.810384)
		(end 137.670794 -66.148458)
		(width 0.0889)
		(layer "In9.Cu")
		(net "UPI_CPU0_CPU1_P0P0_DP<8>")
	)
	(segment
		(start 313.59729 -77.057758)
		(end 313.459876 -76.927964)
		(width 0.1143)
		(layer "In9.Cu")
		(net "UPI_CPU0_CPU1_P0P0_DP<8>")
	)
	(segment
		(start 258.327398 -111.961676)
		(end 267.151358 -112.395508)
		(width 0.1143)
		(layer "In9.Cu")
		(net "UPI_CPU0_CPU1_P0P0_DP<8>")
	)
	(segment
		(start 308.028594 -66.8528)
		(end 307.98262 -66.898774)
		(width 0.0889)
		(layer "In9.Cu")
		(net "UPI_CPU0_CPU1_P0P0_DP<8>")
	)
	(segment
		(start 315.045852 -91.589352)
		(end 316.117986 -86.615524)
		(width 0.1143)
		(layer "In9.Cu")
		(net "UPI_CPU0_CPU1_P0P0_DP<8>")
	)
	(segment
		(start 307.173376 -66.899028)
		(end 307.173376 -66.898774)
		(width 0.0889)
		(layer "In9.Cu")
		(net "UPI_CPU0_CPU1_P0P0_DP<8>")
	)
	(segment
		(start 313.664854 -79.459582)
		(end 313.65825 -79.230982)
		(width 0.1143)
		(layer "In9.Cu")
		(net "UPI_CPU0_CPU1_P0P0_DP<8>")
	)
	(segment
		(start 309.035704 -66.8528)
		(end 308.028594 -66.8528)
		(width 0.0889)
		(layer "In9.Cu")
		(net "UPI_CPU0_CPU1_P0P0_DP<8>")
	)
	(segment
		(start 307.443124 -66.898774)
		(end 307.443124 -66.899028)
		(width 0.0889)
		(layer "In9.Cu")
		(net "UPI_CPU0_CPU1_P0P0_DP<8>")
	)
	(segment
		(start 310.854598 -68.743576)
		(end 310.576214 -68.465446)
		(width 0.1143)
		(layer "In9.Cu")
		(net "UPI_CPU0_CPU1_P0P0_DP<8>")
	)
	(segment
		(start 313.480196 -77.652372)
		(end 313.473592 -77.423264)
		(width 0.1143)
		(layer "In9.Cu")
		(net "UPI_CPU0_CPU1_P0P0_DP<8>")
	)
	(segment
		(start 313.603894 -77.286358)
		(end 313.603894 -77.285342)
		(width 0.1143)
		(layer "In9.Cu")
		(net "UPI_CPU0_CPU1_P0P0_DP<8>")
	)
	(segment
		(start 291.281104 -107.904788)
		(end 292.233604 -107.818428)
		(width 0.1143)
		(layer "In9.Cu")
		(net "UPI_CPU0_CPU1_P0P0_DP<8>")
	)
	(segment
		(start 186.46394 -114.266726)
		(end 194.95135 -114.879374)
		(width 0.1143)
		(layer "In9.Cu")
		(net "UPI_CPU0_CPU1_P0P0_DP<8>")
	)
	(segment
		(start 306.834286 -66.8528)
		(end 306.653184 -67.033902)
		(width 0.0889)
		(layer "In9.Cu")
		(net "UPI_CPU0_CPU1_P0P0_DP<8>")
	)
	(segment
		(start 162.59683 -98.924872)
		(end 169.188638 -105.343706)
		(width 0.1143)
		(layer "In9.Cu")
		(net "UPI_CPU0_CPU1_P0P0_DP<8>")
	)
	(segment
		(start 313.493912 -78.147672)
		(end 313.624214 -78.010766)
		(width 0.1143)
		(layer "In9.Cu")
		(net "UPI_CPU0_CPU1_P0P0_DP<8>")
	)
	(segment
		(start 148.133816 -69.126862)
		(end 152.139904 -74.450194)
		(width 0.1143)
		(layer "In9.Cu")
		(net "UPI_CPU0_CPU1_P0P0_DP<8>")
	)
	(segment
		(start 307.666898 -66.8528)
		(end 307.489098 -66.8528)
		(width 0.0889)
		(layer "In9.Cu")
		(net "UPI_CPU0_CPU1_P0P0_DP<8>")
	)
	(segment
		(start 267.151358 -112.395508)
		(end 278.074882 -111.346488)
		(width 0.1143)
		(layer "In9.Cu")
		(net "UPI_CPU0_CPU1_P0P0_DP<8>")
	)
	(segment
		(start 313.624214 -78.010766)
		(end 313.61761 -77.782166)
		(width 0.1143)
		(layer "In9.Cu")
		(net "UPI_CPU0_CPU1_P0P0_DP<8>")
	)
	(segment
		(start 307.21935 -66.945002)
		(end 307.173376 -66.899028)
		(width 0.0889)
		(layer "In9.Cu")
		(net "UPI_CPU0_CPU1_P0P0_DP<8>")
	)
	(segment
		(start 310.56072 -68.449952)
		(end 310.56072 -68.377816)
		(width 0.0889)
		(layer "In9.Cu")
		(net "UPI_CPU0_CPU1_P0P0_DP<8>")
	)
	(segment
		(start 313.540394 -74.944478)
		(end 312.245502 -70.444868)
		(width 0.1143)
		(layer "In9.Cu")
		(net "UPI_CPU0_CPU1_P0P0_DP<8>")
	)
	(segment
		(start 312.116724 -105.180638)
		(end 314.381642 -94.671642)
		(width 0.1143)
		(layer "In9.Cu")
		(net "UPI_CPU0_CPU1_P0P0_DP<8>")
	)
	(segment
		(start 307.39715 -66.945002)
		(end 307.21935 -66.945002)
		(width 0.0889)
		(layer "In9.Cu")
		(net "UPI_CPU0_CPU1_P0P0_DP<8>")
	)
	(segment
		(start 141.754606 -66.6623)
		(end 144.132554 -66.6623)
		(width 0.0889)
		(layer "In9.Cu")
		(net "UPI_CPU0_CPU1_P0P0_DP<8>")
	)
	(segment
		(start 310.56072 -68.377816)
		(end 309.035704 -66.8528)
		(width 0.0889)
		(layer "In9.Cu")
		(net "UPI_CPU0_CPU1_P0P0_DP<8>")
	)
	(segment
		(start 313.57697 -76.33335)
		(end 313.439556 -76.203556)
		(width 0.1143)
		(layer "In9.Cu")
		(net "UPI_CPU0_CPU1_P0P0_DP<8>")
	)
	(segment
		(start 310.576214 -68.465446)
		(end 310.56072 -68.449952)
		(width 0.0889)
		(layer "In9.Cu")
		(net "UPI_CPU0_CPU1_P0P0_DP<8>")
	)
	(segment
		(start 312.18378 -70.341236)
		(end 310.854598 -68.743576)
		(width 0.1143)
		(layer "In9.Cu")
		(net "UPI_CPU0_CPU1_P0P0_DP<8>")
	)
	(segment
		(start 139.372848 -67.201034)
		(end 139.40282 -67.201034)
		(width 0.0889)
		(layer "In9.Cu")
		(net "UPI_CPU0_CPU1_P0P0_DP<8>")
	)
	(segment
		(start 313.500516 -78.37678)
		(end 313.493912 -78.147672)
		(width 0.1143)
		(layer "In9.Cu")
		(net "UPI_CPU0_CPU1_P0P0_DP<8>")
	)
	(segment
		(start 313.439556 -76.203556)
		(end 313.432952 -75.974448)
		(width 0.1143)
		(layer "In9.Cu")
		(net "UPI_CPU0_CPU1_P0P0_DP<8>")
	)
	(segment
		(start 141.451838 -67.000882)
		(end 141.451838 -67.000628)
		(width 0.0889)
		(layer "In9.Cu")
		(net "UPI_CPU0_CPU1_P0P0_DP<8>")
	)
	(segment
		(start 169.188638 -105.343706)
		(end 175.46955 -107.53471)
		(width 0.1143)
		(layer "In9.Cu")
		(net "UPI_CPU0_CPU1_P0P0_DP<8>")
	)
	(segment
		(start 307.712872 -66.899028)
		(end 307.712872 -66.898774)
		(width 0.0889)
		(layer "In9.Cu")
		(net "UPI_CPU0_CPU1_P0P0_DP<8>")
	)
	(segment
		(start 314.330842 -81.915)
		(end 313.68619 -80.219042)
		(width 0.1143)
		(layer "In9.Cu")
		(net "UPI_CPU0_CPU1_P0P0_DP<8>")
	)
	(segment
		(start 281.915616 -111.79175)
		(end 291.125402 -107.969304)
		(width 0.1143)
		(layer "In9.Cu")
		(net "UPI_CPU0_CPU1_P0P0_DP<8>")
	)
	(segment
		(start 307.98262 -66.899028)
		(end 307.936646 -66.945002)
		(width 0.0889)
		(layer "In9.Cu")
		(net "UPI_CPU0_CPU1_P0P0_DP<8>")
	)
	(segment
		(start 161.942272 -94.690184)
		(end 162.59683 -98.924872)
		(width 0.1143)
		(layer "In9.Cu")
		(net "UPI_CPU0_CPU1_P0P0_DP<8>")
	)
	(segment
		(start 141.451838 -67.000628)
		(end 141.452092 -67.000374)
		(width 0.0889)
		(layer "In9.Cu")
		(net "UPI_CPU0_CPU1_P0P0_DP<8>")
	)
	(segment
		(start 313.67857 -79.95539)
		(end 313.548268 -79.8322)
		(width 0.1143)
		(layer "In9.Cu")
		(net "UPI_CPU0_CPU1_P0P0_DP<8>")
	)
	(segment
		(start 155.590748 -87.173308)
		(end 161.942272 -94.690184)
		(width 0.1143)
		(layer "In9.Cu")
		(net "UPI_CPU0_CPU1_P0P0_DP<8>")
	)
	(segment
		(start 306.045616 -67.791584)
		(end 306.105306 -67.791584)
		(width 0.0889)
		(layer "In9.Cu")
		(net "UPI_CPU0_CPU1_P0P0_DP<8>")
	)
	(segment
		(start 227.956872 -111.02086)
		(end 247.903238 -114.416332)
		(width 0.1143)
		(layer "In9.Cu")
		(net "UPI_CPU0_CPU1_P0P0_DP<8>")
	)
	(segment
		(start 141.451584 -67.001136)
		(end 141.451838 -67.000882)
		(width 0.0889)
		(layer "In9.Cu")
		(net "UPI_CPU0_CPU1_P0P0_DP<8>")
	)
	(segment
		(start 313.63793 -78.506574)
		(end 313.500516 -78.37678)
		(width 0.1143)
		(layer "In9.Cu")
		(net "UPI_CPU0_CPU1_P0P0_DP<8>")
	)
	(segment
		(start 194.95135 -114.879374)
		(end 196.981826 -114.747548)
		(width 0.1143)
		(layer "In9.Cu")
		(net "UPI_CPU0_CPU1_P0P0_DP<8>")
	)
	(segment
		(start 313.603894 -77.285342)
		(end 313.59729 -77.057758)
		(width 0.1143)
		(layer "In9.Cu")
		(net "UPI_CPU0_CPU1_P0P0_DP<8>")
	)
	(segment
		(start 138.518138 -66.705988)
		(end 138.550904 -66.705988)
		(width 0.0889)
		(layer "In9.Cu")
		(net "UPI_CPU0_CPU1_P0P0_DP<8>")
	)
	(segment
		(start 313.563508 -75.837542)
		(end 313.540394 -74.944478)
		(width 0.1143)
		(layer "In9.Cu")
		(net "UPI_CPU0_CPU1_P0P0_DP<8>")
	)
	(segment
		(start 141.501876 -66.91503)
		(end 141.754606 -66.6623)
		(width 0.0889)
		(layer "In9.Cu")
		(net "UPI_CPU0_CPU1_P0P0_DP<8>")
	)
	(segment
		(start 145.40992 -67.939666)
		(end 145.62582 -67.939666)
		(width 0.0889)
		(layer "In9.Cu")
		(net "UPI_CPU0_CPU1_P0P0_DP<8>")
	)
	(segment
		(start 302.86198 -110.532672)
		(end 307.457856 -109.485938)
		(width 0.1143)
		(layer "In9.Cu")
		(net "UPI_CPU0_CPU1_P0P0_DP<8>")
	)
	(segment
		(start 313.459876 -76.927964)
		(end 313.453272 -76.698856)
		(width 0.1143)
		(layer "In9.Cu")
		(net "UPI_CPU0_CPU1_P0P0_DP<8>")
	)
	(segment
		(start 313.583574 -76.56195)
		(end 313.57697 -76.33335)
		(width 0.1143)
		(layer "In9.Cu")
		(net "UPI_CPU0_CPU1_P0P0_DP<8>")
	)
	(segment
		(start 316.117986 -86.615524)
		(end 314.330842 -81.915)
		(width 0.1143)
		(layer "In9.Cu")
		(net "UPI_CPU0_CPU1_P0P0_DP<8>")
	)
	(segment
		(start 312.187336 -70.342252)
		(end 312.18378 -70.341236)
		(width 0.1143)
		(layer "In9.Cu")
		(net "UPI_CPU0_CPU1_P0P0_DP<8>")
	)
	(segment
		(start 313.65825 -79.230982)
		(end 313.520836 -79.101188)
		(width 0.1143)
		(layer "In9.Cu")
		(net "UPI_CPU0_CPU1_P0P0_DP<8>")
	)
	(segment
		(start 145.67662 -67.888866)
		(end 145.698718 -67.888866)
		(width 0.0889)
		(layer "In9.Cu")
		(net "UPI_CPU0_CPU1_P0P0_DP<8>")
	)
	(segment
		(start 247.903238 -114.416332)
		(end 258.327398 -111.961676)
		(width 0.1143)
		(layer "In9.Cu")
		(net "UPI_CPU0_CPU1_P0P0_DP<8>")
	)
	(segment
		(start 312.245502 -70.444868)
		(end 312.18759 -70.342252)
		(width 0.1143)
		(layer "In9.Cu")
		(net "UPI_CPU0_CPU1_P0P0_DP<8>")
	)
	(segment
		(start 152.139904 -74.450194)
		(end 155.590748 -87.173308)
		(width 0.1143)
		(layer "In9.Cu")
		(net "UPI_CPU0_CPU1_P0P0_DP<8>")
	)
	(segment
		(start 307.936646 -66.945002)
		(end 307.758846 -66.945002)
		(width 0.0889)
		(layer "In9.Cu")
		(net "UPI_CPU0_CPU1_P0P0_DP<8>")
	)
	(segment
		(start 313.453272 -76.698856)
		(end 313.583574 -76.56195)
		(width 0.1143)
		(layer "In9.Cu")
		(net "UPI_CPU0_CPU1_P0P0_DP<8>")
	)
	(segment
		(start 175.46955 -107.53471)
		(end 178.769772 -110.381288)
		(width 0.1143)
		(layer "In9.Cu")
		(net "UPI_CPU0_CPU1_P0P0_DP<8>")
	)
	(segment
		(start 178.769772 -110.381288)
		(end 186.46394 -114.266726)
		(width 0.1143)
		(layer "In9.Cu")
		(net "UPI_CPU0_CPU1_P0P0_DP<8>")
	)
	(segment
		(start 313.644534 -78.735174)
		(end 313.63793 -78.506574)
		(width 0.1143)
		(layer "In9.Cu")
		(net "UPI_CPU0_CPU1_P0P0_DP<8>")
	)
	(segment
		(start 141.089888 -67.201034)
		(end 141.1224 -67.201034)
		(width 0.0889)
		(layer "In9.Cu")
		(net "UPI_CPU0_CPU1_P0P0_DP<8>")
	)
	(segment
		(start 313.61761 -77.782166)
		(end 313.480196 -77.652372)
		(width 0.1143)
		(layer "In9.Cu")
		(net "UPI_CPU0_CPU1_P0P0_DP<8>")
	)
	(segment
		(start 314.381642 -94.671642)
		(end 314.574428 -93.7768)
		(width 0.1143)
		(layer "In9.Cu")
		(net "UPI_CPU0_CPU1_P0P0_DP<8>")
	)
	(segment
		(start 278.074882 -111.346488)
		(end 281.915616 -111.79175)
		(width 0.1143)
		(layer "In9.Cu")
		(net "UPI_CPU0_CPU1_P0P0_DP<8>")
	)
	(segment
		(start 313.473592 -77.423264)
		(end 313.603894 -77.286358)
		(width 0.1143)
		(layer "In9.Cu")
		(net "UPI_CPU0_CPU1_P0P0_DP<8>")
	)
	(segment
		(start 313.548268 -79.8322)
		(end 313.541156 -79.825596)
		(width 0.1143)
		(layer "In9.Cu")
		(net "UPI_CPU0_CPU1_P0P0_DP<8>")
	)
	(segment
		(start 141.452092 -67.000374)
		(end 141.501876 -66.91503)
		(width 0.0889)
		(layer "In9.Cu")
		(net "UPI_CPU0_CPU1_P0P0_DP<8>")
	)
	(segment
		(start 145.62582 -67.939666)
		(end 145.67662 -67.888866)
		(width 0.0889)
		(layer "In9.Cu")
		(net "UPI_CPU0_CPU1_P0P0_DP<8>")
	)
	(segment
		(start 137.670794 -66.148458)
		(end 137.736072 -66.213736)
		(width 0.0889)
		(layer "In9.Cu")
		(net "UPI_CPU0_CPU1_P0P0_DP<8>")
	)
	(segment
		(start 146.015456 -67.888866)
		(end 148.133816 -69.126862)
		(width 0.1143)
		(layer "In9.Cu")
		(net "UPI_CPU0_CPU1_P0P0_DP<8>")
	)
	(segment
		(start 313.534552 -79.596488)
		(end 313.664854 -79.459582)
		(width 0.1143)
		(layer "In9.Cu")
		(net "UPI_CPU0_CPU1_P0P0_DP<8>")
	)
	(segment
		(start 307.173376 -66.898774)
		(end 307.127402 -66.8528)
		(width 0.0889)
		(layer "In9.Cu")
		(net "UPI_CPU0_CPU1_P0P0_DP<8>")
	)
	(segment
		(start 196.981826 -114.747548)
		(end 227.956872 -111.02086)
		(width 0.1143)
		(layer "In9.Cu")
		(net "UPI_CPU0_CPU1_P0P0_DP<8>")
	)
	(segment
		(start 313.520836 -79.101188)
		(end 313.514232 -78.87208)
		(width 0.1143)
		(layer "In9.Cu")
		(net "UPI_CPU0_CPU1_P0P0_DP<8>")
	)
	(segment
		(start 307.127402 -66.8528)
		(end 306.834286 -66.8528)
		(width 0.0889)
		(layer "In9.Cu")
		(net "UPI_CPU0_CPU1_P0P0_DP<8>")
	)
	(segment
		(start 292.233604 -107.818428)
		(end 302.86198 -110.532672)
		(width 0.1143)
		(layer "In9.Cu")
		(net "UPI_CPU0_CPU1_P0P0_DP<8>")
	)
	(segment
		(start 306.653184 -67.033902)
		(end 306.617116 -67.096386)
		(width 0.0889)
		(layer "In9.Cu")
		(net "UPI_CPU0_CPU1_P0P0_DP<8>")
	)
	(segment
		(start 314.574428 -93.7768)
		(end 315.045852 -91.589352)
		(width 0.1143)
		(layer "In9.Cu")
		(net "UPI_CPU0_CPU1_P0P0_DP<8>")
	)
	(segment
		(start 307.712872 -66.898774)
		(end 307.666898 -66.8528)
		(width 0.0889)
		(layer "In9.Cu")
		(net "UPI_CPU0_CPU1_P0P0_DP<8>")
	)
	(segment
		(start 307.443124 -66.899028)
		(end 307.39715 -66.945002)
		(width 0.0889)
		(layer "In9.Cu")
		(net "UPI_CPU0_CPU1_P0P0_DP<8>")
	)
	(segment
		(start 306.126896 -67.391534)
		(end 305.888898 -67.391534)
		(width 0.0889)
		(layer "In9.Cu")
		(net "UPI_CPU0_CPU1_P0P0_DP<8>")
	)
	(segment
		(start 307.758846 -66.945002)
		(end 307.712872 -66.899028)
		(width 0.0889)
		(layer "In9.Cu")
		(net "UPI_CPU0_CPU1_P0P0_DP<8>")
	)
	(segment
		(start 313.68619 -80.219042)
		(end 313.67857 -79.95539)
		(width 0.1143)
		(layer "In9.Cu")
		(net "UPI_CPU0_CPU1_P0P0_DP<8>")
	)
	(segment
		(start 307.489098 -66.8528)
		(end 307.443124 -66.898774)
		(width 0.0889)
		(layer "In9.Cu")
		(net "UPI_CPU0_CPU1_P0P0_DP<8>")
	)
	(segment
		(start 145.698718 -67.888866)
		(end 146.015456 -67.888866)
		(width 0.1143)
		(layer "In9.Cu")
		(net "UPI_CPU0_CPU1_P0P0_DP<8>")
	)
	(segment
		(start 144.132554 -66.6623)
		(end 145.40992 -67.939666)
		(width 0.0889)
		(layer "In9.Cu")
		(net "UPI_CPU0_CPU1_P0P0_DP<8>")
	)
	(segment
		(start 291.125402 -107.969304)
		(end 291.281104 -107.904788)
		(width 0.1143)
		(layer "In9.Cu")
		(net "UPI_CPU0_CPU1_P0P0_DP<8>")
	)
	(segment
		(start 307.457856 -109.485938)
		(end 312.116724 -105.180638)
		(width 0.1143)
		(layer "In9.Cu")
		(net "UPI_CPU0_CPU1_P0P0_DP<8>")
	)
	(segment
		(start 312.18759 -70.342252)
		(end 312.187336 -70.342252)
		(width 0.1143)
		(layer "In9.Cu")
		(net "UPI_CPU0_CPU1_P0P0_DP<8>")
	)
	(segment
		(start 313.514232 -78.87208)
		(end 313.644534 -78.735174)
		(width 0.1143)
		(layer "In9.Cu")
		(net "UPI_CPU0_CPU1_P0P0_DP<8>")
	)
	(segment
		(start 140.224764 -66.705988)
		(end 140.267944 -66.705988)
		(width 0.0889)
		(layer "In9.Cu")
		(net "UPI_CPU0_CPU1_P0P0_DP<8>")
	)
	(segment
		(start 313.541156 -79.825596)
		(end 313.534552 -79.596488)
		(width 0.1143)
		(layer "In9.Cu")
		(net "UPI_CPU0_CPU1_P0P0_DP<8>")
	)
	(segment
		(start 307.98262 -66.898774)
		(end 307.98262 -66.899028)
		(width 0.0889)
		(layer "In9.Cu")
		(net "UPI_CPU0_CPU1_P0P0_DP<8>")
	)
	(arc
		(start 140.758164 -67.001136)
		(mid 140.898243 -67.143872)
		(end 141.089888 -67.201034)
		(width 0.0889)
		(layer "In9.Cu")
		(net "UPI_CPU0_CPU1_P0P0_DP<8>")
	)
	(arc
		(start 305.767232 -67.5132)
		(mid 305.848769 -67.710047)
		(end 306.045616 -67.791584)
		(width 0.0889)
		(layer "In9.Cu")
		(net "UPI_CPU0_CPU1_P0P0_DP<8>")
	)
	(arc
		(start 139.734544 -67.001136)
		(mid 139.941548 -66.790272)
		(end 140.224764 -66.705988)
		(width 0.0889)
		(layer "In9.Cu")
		(net "UPI_CPU0_CPU1_P0P0_DP<8>")
	)
	(arc
		(start 137.736072 -66.213736)
		(mid 137.994209 -66.30649)
		(end 138.182604 -66.505836)
		(width 0.0889)
		(layer "In9.Cu")
		(net "UPI_CPU0_CPU1_P0P0_DP<8>")
	)
	(arc
		(start 138.182604 -66.505836)
		(mid 138.324287 -66.64964)
		(end 138.518138 -66.705988)
		(width 0.0889)
		(layer "In9.Cu")
		(net "UPI_CPU0_CPU1_P0P0_DP<8>")
	)
	(arc
		(start 138.550904 -66.705988)
		(mid 138.834121 -66.790269)
		(end 139.041124 -67.001136)
		(width 0.0889)
		(layer "In9.Cu")
		(net "UPI_CPU0_CPU1_P0P0_DP<8>")
	)
	(arc
		(start 139.40282 -67.201034)
		(mid 139.594462 -67.143868)
		(end 139.734544 -67.001136)
		(width 0.0889)
		(layer "In9.Cu")
		(net "UPI_CPU0_CPU1_P0P0_DP<8>")
	)
	(arc
		(start 141.1224 -67.201034)
		(mid 141.312642 -67.143299)
		(end 141.451584 -67.001136)
		(width 0.0889)
		(layer "In9.Cu")
		(net "UPI_CPU0_CPU1_P0P0_DP<8>")
	)
	(arc
		(start 140.267944 -66.705988)
		(mid 140.551161 -66.790269)
		(end 140.758164 -67.001136)
		(width 0.0889)
		(layer "In9.Cu")
		(net "UPI_CPU0_CPU1_P0P0_DP<8>")
	)
	(arc
		(start 305.888898 -67.391534)
		(mid 305.802867 -67.427169)
		(end 305.767232 -67.5132)
		(width 0.0889)
		(layer "In9.Cu")
		(net "UPI_CPU0_CPU1_P0P0_DP<8>")
	)
	(arc
		(start 139.041124 -67.001136)
		(mid 139.181203 -67.143872)
		(end 139.372848 -67.201034)
		(width 0.0889)
		(layer "In9.Cu")
		(net "UPI_CPU0_CPU1_P0P0_DP<8>")
	)
	(arc
		(start 306.617116 -67.096386)
		(mid 306.410112 -67.30725)
		(end 306.126896 -67.391534)
		(width 0.0889)
		(layer "In9.Cu")
		(net "UPI_CPU0_CPU1_P0P0_DP<8>")
	)
	(segment
		(start 307.250846 -67.791584)
		(end 307.250846 -68.00596)
		(width 0.0889)
		(layer "F.Cu")
		(net "UPI_CPU0_CPU1_P0P0_DP<7>")
	)
	(segment
		(start 308.061106 -67.6656)
		(end 308.708806 -67.6656)
		(width 0.0889)
		(layer "F.Cu")
		(net "UPI_CPU0_CPU1_P0P0_DP<7>")
	)
	(segment
		(start 307.250846 -68.00596)
		(end 307.43652 -68.191634)
		(width 0.0889)
		(layer "F.Cu")
		(net "UPI_CPU0_CPU1_P0P0_DP<7>")
	)
	(segment
		(start 307.535072 -68.191634)
		(end 308.061106 -67.6656)
		(width 0.0889)
		(layer "F.Cu")
		(net "UPI_CPU0_CPU1_P0P0_DP<7>")
	)
	(segment
		(start 308.708806 -67.6656)
		(end 308.923436 -67.45097)
		(width 0.0889)
		(layer "F.Cu")
		(net "UPI_CPU0_CPU1_P0P0_DP<7>")
	)
	(segment
		(start 137.957814 -66.305938)
		(end 138.529314 -66.305938)
		(width 0.1143)
		(layer "F.Cu")
		(net "UPI_CPU0_CPU1_P0P0_DP<7>")
	)
	(segment
		(start 307.43652 -68.191634)
		(end 307.535072 -68.191634)
		(width 0.0889)
		(layer "F.Cu")
		(net "UPI_CPU0_CPU1_P0P0_DP<7>")
	)
	(via
		(at 138.529314 -66.305938)
		(size 0.508)
		(drill 0.254)
		(layers "F.Cu" "B.Cu")
		(net "UPI_CPU0_CPU1_P0P0_DP<7>")
	)
	(via
		(at 308.923436 -67.45097)
		(size 0.508)
		(drill 0.254)
		(layers "F.Cu" "B.Cu")
		(net "UPI_CPU0_CPU1_P0P0_DP<7>")
	)
	(segment
		(start 313.17438 -80.05445)
		(end 313.168284 -79.8322)
		(width 0.1143)
		(layer "In9.Cu")
		(net "UPI_CPU0_CPU1_P0P0_DP<7>")
	)
	(segment
		(start 162.268154 -94.540578)
		(end 162.898836 -98.621088)
		(width 0.1143)
		(layer "In9.Cu")
		(net "UPI_CPU0_CPU1_P0P0_DP<7>")
	)
	(segment
		(start 309.162958 -67.690492)
		(end 308.923436 -67.45097)
		(width 0.0889)
		(layer "In9.Cu")
		(net "UPI_CPU0_CPU1_P0P0_DP<7>")
	)
	(segment
		(start 291.125402 -107.595924)
		(end 291.198046 -107.565698)
		(width 0.1143)
		(layer "In9.Cu")
		(net "UPI_CPU0_CPU1_P0P0_DP<7>")
	)
	(segment
		(start 146.180302 -67.5005)
		(end 148.274278 -68.382134)
		(width 0.1143)
		(layer "In9.Cu")
		(net "UPI_CPU0_CPU1_P0P0_DP<7>")
	)
	(segment
		(start 310.03494 -69.004942)
		(end 310.03494 -68.39204)
		(width 0.0889)
		(layer "In9.Cu")
		(net "UPI_CPU0_CPU1_P0P0_DP<7>")
	)
	(segment
		(start 141.093698 -65.410334)
		(end 141.11605 -65.410334)
		(width 0.0889)
		(layer "In9.Cu")
		(net "UPI_CPU0_CPU1_P0P0_DP<7>")
	)
	(segment
		(start 141.92885 -66.1162)
		(end 142.418816 -66.2559)
		(width 0.0889)
		(layer "In9.Cu")
		(net "UPI_CPU0_CPU1_P0P0_DP<7>")
	)
	(segment
		(start 155.904692 -87.009986)
		(end 162.268154 -94.540578)
		(width 0.1143)
		(layer "In9.Cu")
		(net "UPI_CPU0_CPU1_P0P0_DP<7>")
	)
	(segment
		(start 278.078438 -110.999016)
		(end 281.865324 -111.437928)
		(width 0.1143)
		(layer "In9.Cu")
		(net "UPI_CPU0_CPU1_P0P0_DP<7>")
	)
	(segment
		(start 142.418816 -66.2559)
		(end 144.2847 -66.2559)
		(width 0.0889)
		(layer "In9.Cu")
		(net "UPI_CPU0_CPU1_P0P0_DP<7>")
	)
	(segment
		(start 169.515028 -105.091738)
		(end 175.92548 -107.328208)
		(width 0.1143)
		(layer "In9.Cu")
		(net "UPI_CPU0_CPU1_P0P0_DP<7>")
	)
	(segment
		(start 291.198046 -107.565698)
		(end 292.261544 -107.469178)
		(width 0.1143)
		(layer "In9.Cu")
		(net "UPI_CPU0_CPU1_P0P0_DP<7>")
	)
	(segment
		(start 311.801764 -105.001568)
		(end 314.090812 -94.380812)
		(width 0.1143)
		(layer "In9.Cu")
		(net "UPI_CPU0_CPU1_P0P0_DP<7>")
	)
	(segment
		(start 311.640474 -70.53834)
		(end 310.27497 -69.173344)
		(width 0.1143)
		(layer "In9.Cu")
		(net "UPI_CPU0_CPU1_P0P0_DP<7>")
	)
	(segment
		(start 315.729874 -86.776052)
		(end 313.17438 -80.05445)
		(width 0.1143)
		(layer "In9.Cu")
		(net "UPI_CPU0_CPU1_P0P0_DP<7>")
	)
	(segment
		(start 248.008648 -108.797598)
		(end 262.725154 -111.832136)
		(width 0.1143)
		(layer "In9.Cu")
		(net "UPI_CPU0_CPU1_P0P0_DP<7>")
	)
	(segment
		(start 262.725154 -111.832136)
		(end 267.14323 -112.049052)
		(width 0.1143)
		(layer "In9.Cu")
		(net "UPI_CPU0_CPU1_P0P0_DP<7>")
	)
	(segment
		(start 314.090812 -94.380812)
		(end 314.221114 -93.7768)
		(width 0.1143)
		(layer "In9.Cu")
		(net "UPI_CPU0_CPU1_P0P0_DP<7>")
	)
	(segment
		(start 313.168284 -79.8322)
		(end 313.097926 -77.285342)
		(width 0.1143)
		(layer "In9.Cu")
		(net "UPI_CPU0_CPU1_P0P0_DP<7>")
	)
	(segment
		(start 190.784988 -113.888012)
		(end 196.084698 -114.506248)
		(width 0.1143)
		(layer "In9.Cu")
		(net "UPI_CPU0_CPU1_P0P0_DP<7>")
	)
	(segment
		(start 141.928596 -66.1162)
		(end 141.92885 -66.1162)
		(width 0.0889)
		(layer "In9.Cu")
		(net "UPI_CPU0_CPU1_P0P0_DP<7>")
	)
	(segment
		(start 148.274278 -68.382134)
		(end 152.305004 -73.737978)
		(width 0.1143)
		(layer "In9.Cu")
		(net "UPI_CPU0_CPU1_P0P0_DP<7>")
	)
	(segment
		(start 310.03494 -68.39204)
		(end 309.333392 -67.690492)
		(width 0.0889)
		(layer "In9.Cu")
		(net "UPI_CPU0_CPU1_P0P0_DP<7>")
	)
	(segment
		(start 145.898108 -67.5005)
		(end 145.920206 -67.5005)
		(width 0.0889)
		(layer "In9.Cu")
		(net "UPI_CPU0_CPU1_P0P0_DP<7>")
	)
	(segment
		(start 152.305004 -73.737978)
		(end 155.904692 -87.009986)
		(width 0.1143)
		(layer "In9.Cu")
		(net "UPI_CPU0_CPU1_P0P0_DP<7>")
	)
	(segment
		(start 162.898836 -98.621088)
		(end 169.515028 -105.091738)
		(width 0.1143)
		(layer "In9.Cu")
		(net "UPI_CPU0_CPU1_P0P0_DP<7>")
	)
	(segment
		(start 145.847308 -67.4497)
		(end 145.898108 -67.5005)
		(width 0.0889)
		(layer "In9.Cu")
		(net "UPI_CPU0_CPU1_P0P0_DP<7>")
	)
	(segment
		(start 313.031378 -74.883264)
		(end 311.640474 -70.53834)
		(width 0.1143)
		(layer "In9.Cu")
		(net "UPI_CPU0_CPU1_P0P0_DP<7>")
	)
	(segment
		(start 307.291486 -109.169962)
		(end 311.801764 -105.001568)
		(width 0.1143)
		(layer "In9.Cu")
		(net "UPI_CPU0_CPU1_P0P0_DP<7>")
	)
	(segment
		(start 178.213258 -109.301788)
		(end 190.131954 -113.64976)
		(width 0.1143)
		(layer "In9.Cu")
		(net "UPI_CPU0_CPU1_P0P0_DP<7>")
	)
	(segment
		(start 267.14323 -112.049052)
		(end 278.078438 -110.999016)
		(width 0.1143)
		(layer "In9.Cu")
		(net "UPI_CPU0_CPU1_P0P0_DP<7>")
	)
	(segment
		(start 309.333392 -67.690492)
		(end 309.162958 -67.690492)
		(width 0.0889)
		(layer "In9.Cu")
		(net "UPI_CPU0_CPU1_P0P0_DP<7>")
	)
	(segment
		(start 227.891086 -110.659164)
		(end 233.685334 -111.6457)
		(width 0.1143)
		(layer "In9.Cu")
		(net "UPI_CPU0_CPU1_P0P0_DP<7>")
	)
	(segment
		(start 139.366244 -66.400934)
		(end 139.409424 -66.400934)
		(width 0.0889)
		(layer "In9.Cu")
		(net "UPI_CPU0_CPU1_P0P0_DP<7>")
	)
	(segment
		(start 313.097926 -77.285342)
		(end 313.031378 -74.883264)
		(width 0.1143)
		(layer "In9.Cu")
		(net "UPI_CPU0_CPU1_P0P0_DP<7>")
	)
	(segment
		(start 302.866044 -110.177834)
		(end 307.291486 -109.169962)
		(width 0.1143)
		(layer "In9.Cu")
		(net "UPI_CPU0_CPU1_P0P0_DP<7>")
	)
	(segment
		(start 314.221114 -93.7768)
		(end 314.755276 -91.298776)
		(width 0.1143)
		(layer "In9.Cu")
		(net "UPI_CPU0_CPU1_P0P0_DP<7>")
	)
	(segment
		(start 141.545564 -65.733168)
		(end 141.928596 -66.1162)
		(width 0.0889)
		(layer "In9.Cu")
		(net "UPI_CPU0_CPU1_P0P0_DP<7>")
	)
	(segment
		(start 310.203342 -69.173344)
		(end 310.03494 -69.004942)
		(width 0.0889)
		(layer "In9.Cu")
		(net "UPI_CPU0_CPU1_P0P0_DP<7>")
	)
	(segment
		(start 292.261544 -107.469178)
		(end 302.866044 -110.177834)
		(width 0.1143)
		(layer "In9.Cu")
		(net "UPI_CPU0_CPU1_P0P0_DP<7>")
	)
	(segment
		(start 190.131954 -113.64976)
		(end 190.784988 -113.888012)
		(width 0.1143)
		(layer "In9.Cu")
		(net "UPI_CPU0_CPU1_P0P0_DP<7>")
	)
	(segment
		(start 233.685334 -111.6457)
		(end 248.008648 -108.797598)
		(width 0.1143)
		(layer "In9.Cu")
		(net "UPI_CPU0_CPU1_P0P0_DP<7>")
	)
	(segment
		(start 196.084698 -114.506248)
		(end 227.891086 -110.659164)
		(width 0.1143)
		(layer "In9.Cu")
		(net "UPI_CPU0_CPU1_P0P0_DP<7>")
	)
	(segment
		(start 175.92548 -107.328208)
		(end 178.213258 -109.301788)
		(width 0.1143)
		(layer "In9.Cu")
		(net "UPI_CPU0_CPU1_P0P0_DP<7>")
	)
	(segment
		(start 144.2847 -66.2559)
		(end 145.4785 -67.4497)
		(width 0.0889)
		(layer "In9.Cu")
		(net "UPI_CPU0_CPU1_P0P0_DP<7>")
	)
	(segment
		(start 145.920206 -67.5005)
		(end 146.180302 -67.5005)
		(width 0.1143)
		(layer "In9.Cu")
		(net "UPI_CPU0_CPU1_P0P0_DP<7>")
	)
	(segment
		(start 310.27497 -69.173344)
		(end 310.203342 -69.173344)
		(width 0.0889)
		(layer "In9.Cu")
		(net "UPI_CPU0_CPU1_P0P0_DP<7>")
	)
	(segment
		(start 314.755276 -91.298776)
		(end 315.729874 -86.776052)
		(width 0.1143)
		(layer "In9.Cu")
		(net "UPI_CPU0_CPU1_P0P0_DP<7>")
	)
	(segment
		(start 140.231368 -65.905888)
		(end 140.264134 -65.905888)
		(width 0.0889)
		(layer "In9.Cu")
		(net "UPI_CPU0_CPU1_P0P0_DP<7>")
	)
	(segment
		(start 281.865324 -111.437928)
		(end 291.125402 -107.595924)
		(width 0.1143)
		(layer "In9.Cu")
		(net "UPI_CPU0_CPU1_P0P0_DP<7>")
	)
	(segment
		(start 145.4785 -67.4497)
		(end 145.847308 -67.4497)
		(width 0.0889)
		(layer "In9.Cu")
		(net "UPI_CPU0_CPU1_P0P0_DP<7>")
	)
	(arc
		(start 139.218162 -66.37655)
		(mid 139.291427 -66.393448)
		(end 139.366244 -66.400934)
		(width 0.0889)
		(layer "In9.Cu")
		(net "UPI_CPU0_CPU1_P0P0_DP<7>")
	)
	(arc
		(start 140.758164 -65.610486)
		(mid 140.899847 -65.466682)
		(end 141.093698 -65.410334)
		(width 0.0889)
		(layer "In9.Cu")
		(net "UPI_CPU0_CPU1_P0P0_DP<7>")
	)
	(arc
		(start 141.451584 -65.610486)
		(mid 141.494543 -65.674915)
		(end 141.545564 -65.733168)
		(width 0.0889)
		(layer "In9.Cu")
		(net "UPI_CPU0_CPU1_P0P0_DP<7>")
	)
	(arc
		(start 140.264134 -65.905888)
		(mid 140.549558 -65.822421)
		(end 140.758164 -65.610486)
		(width 0.0889)
		(layer "In9.Cu")
		(net "UPI_CPU0_CPU1_P0P0_DP<7>")
	)
	(arc
		(start 139.899644 -66.105786)
		(mid 140.039723 -65.96305)
		(end 140.231368 -65.905888)
		(width 0.0889)
		(layer "In9.Cu")
		(net "UPI_CPU0_CPU1_P0P0_DP<7>")
	)
	(arc
		(start 141.11605 -65.410334)
		(mid 141.3099 -65.466684)
		(end 141.451584 -65.610486)
		(width 0.0889)
		(layer "In9.Cu")
		(net "UPI_CPU0_CPU1_P0P0_DP<7>")
	)
	(arc
		(start 139.409424 -66.400934)
		(mid 139.692641 -66.316653)
		(end 139.899644 -66.105786)
		(width 0.0889)
		(layer "In9.Cu")
		(net "UPI_CPU0_CPU1_P0P0_DP<7>")
	)
	(arc
		(start 138.529314 -66.305938)
		(mid 138.877069 -66.308745)
		(end 139.218162 -66.37655)
		(width 0.0889)
		(layer "In9.Cu")
		(net "UPI_CPU0_CPU1_P0P0_DP<7>")
	)
	(segment
		(start 137.957814 -65.315338)
		(end 138.529314 -65.315338)
		(width 0.1143)
		(layer "F.Cu")
		(net "UPI_CPU0_CPU1_P0P0_DP<6>")
	)
	(segment
		(start 306.392326 -68.287138)
		(end 306.963826 -68.287138)
		(width 0.1143)
		(layer "F.Cu")
		(net "UPI_CPU0_CPU1_P0P0_DP<6>")
	)
	(via
		(at 138.529314 -65.315338)
		(size 0.508)
		(drill 0.254)
		(layers "F.Cu" "B.Cu")
		(net "UPI_CPU0_CPU1_P0P0_DP<6>")
	)
	(via
		(at 306.963826 -68.287138)
		(size 0.508)
		(drill 0.254)
		(layers "F.Cu" "B.Cu")
		(net "UPI_CPU0_CPU1_P0P0_DP<6>")
	)
	(segment
		(start 171.5897 -104.83088)
		(end 176.67859 -106.605832)
		(width 0.1143)
		(layer "In9.Cu")
		(net "UPI_CPU0_CPU1_P0P0_DP<6>")
	)
	(segment
		(start 308.788816 -69.180456)
		(end 308.645052 -69.180456)
		(width 0.0889)
		(layer "In9.Cu")
		(net "UPI_CPU0_CPU1_P0P0_DP<6>")
	)
	(segment
		(start 308.555136 -68.946776)
		(end 308.465474 -68.857114)
		(width 0.0889)
		(layer "In9.Cu")
		(net "UPI_CPU0_CPU1_P0P0_DP<6>")
	)
	(segment
		(start 312.085736 -79.242666)
		(end 312.079132 -79.014066)
		(width 0.1143)
		(layer "In9.Cu")
		(net "UPI_CPU0_CPU1_P0P0_DP<6>")
	)
	(segment
		(start 138.529314 -65.315338)
		(end 138.236198 -65.146174)
		(width 0.0889)
		(layer "In9.Cu")
		(net "UPI_CPU0_CPU1_P0P0_DP<6>")
	)
	(segment
		(start 311.915556 -77.93228)
		(end 312.045096 -77.795882)
		(width 0.1143)
		(layer "In9.Cu")
		(net "UPI_CPU0_CPU1_P0P0_DP<6>")
	)
	(segment
		(start 163.49599 -96.394778)
		(end 171.589446 -104.830626)
		(width 0.1143)
		(layer "In9.Cu")
		(net "UPI_CPU0_CPU1_P0P0_DP<6>")
	)
	(segment
		(start 149.787102 -67.71259)
		(end 152.677114 -71.552816)
		(width 0.1143)
		(layer "In9.Cu")
		(net "UPI_CPU0_CPU1_P0P0_DP<6>")
	)
	(segment
		(start 307.81879 -68.21043)
		(end 307.675026 -68.21043)
		(width 0.0889)
		(layer "In9.Cu")
		(net "UPI_CPU0_CPU1_P0P0_DP<6>")
	)
	(segment
		(start 139.370054 -65.219834)
		(end 139.40282 -65.219834)
		(width 0.0889)
		(layer "In9.Cu")
		(net "UPI_CPU0_CPU1_P0P0_DP<6>")
	)
	(segment
		(start 308.555136 -69.090794)
		(end 308.555136 -68.946776)
		(width 0.0889)
		(layer "In9.Cu")
		(net "UPI_CPU0_CPU1_P0P0_DP<6>")
	)
	(segment
		(start 138.236198 -65.146174)
		(end 138.157458 -65.16751)
		(width 0.0889)
		(layer "In9.Cu")
		(net "UPI_CPU0_CPU1_P0P0_DP<6>")
	)
	(segment
		(start 308.465474 -68.857114)
		(end 308.32171 -68.857114)
		(width 0.0889)
		(layer "In9.Cu")
		(net "UPI_CPU0_CPU1_P0P0_DP<6>")
	)
	(segment
		(start 144.870932 -65.365884)
		(end 145.007076 -65.365884)
		(width 0.0889)
		(layer "In9.Cu")
		(net "UPI_CPU0_CPU1_P0P0_DP<6>")
	)
	(segment
		(start 309.699152 -70.218808)
		(end 309.573422 -70.093078)
		(width 0.0889)
		(layer "In9.Cu")
		(net "UPI_CPU0_CPU1_P0P0_DP<6>")
	)
	(segment
		(start 307.675026 -68.21043)
		(end 307.58511 -68.120768)
		(width 0.0889)
		(layer "In9.Cu")
		(net "UPI_CPU0_CPU1_P0P0_DP<6>")
	)
	(segment
		(start 306.841652 -108.318808)
		(end 310.95442 -104.51846)
		(width 0.1143)
		(layer "In9.Cu")
		(net "UPI_CPU0_CPU1_P0P0_DP<6>")
	)
	(segment
		(start 311.854596 -75.762104)
		(end 311.98439 -75.625706)
		(width 0.1143)
		(layer "In9.Cu")
		(net "UPI_CPU0_CPU1_P0P0_DP<6>")
	)
	(segment
		(start 311.895236 -77.208888)
		(end 312.024776 -77.07249)
		(width 0.1143)
		(layer "In9.Cu")
		(net "UPI_CPU0_CPU1_P0P0_DP<6>")
	)
	(segment
		(start 227.988622 -109.732572)
		(end 233.672888 -110.700058)
		(width 0.1143)
		(layer "In9.Cu")
		(net "UPI_CPU0_CPU1_P0P0_DP<6>")
	)
	(segment
		(start 312.045096 -77.795882)
		(end 312.038492 -77.567282)
		(width 0.1143)
		(layer "In9.Cu")
		(net "UPI_CPU0_CPU1_P0P0_DP<6>")
	)
	(segment
		(start 312.038492 -77.567282)
		(end 311.90184 -77.437996)
		(width 0.1143)
		(layer "In9.Cu")
		(net "UPI_CPU0_CPU1_P0P0_DP<6>")
	)
	(segment
		(start 307.58511 -67.97675)
		(end 307.495448 -67.887088)
		(width 0.0889)
		(layer "In9.Cu")
		(net "UPI_CPU0_CPU1_P0P0_DP<6>")
	)
	(segment
		(start 145.728436 -64.957706)
		(end 145.779236 -64.906906)
		(width 0.0889)
		(layer "In9.Cu")
		(net "UPI_CPU0_CPU1_P0P0_DP<6>")
	)
	(segment
		(start 290.970462 -106.652822)
		(end 292.336474 -106.52887)
		(width 0.1143)
		(layer "In9.Cu")
		(net "UPI_CPU0_CPU1_P0P0_DP<6>")
	)
	(segment
		(start 196.280024 -113.25225)
		(end 197.265798 -113.428272)
		(width 0.1143)
		(layer "In9.Cu")
		(net "UPI_CPU0_CPU1_P0P0_DP<6>")
	)
	(segment
		(start 197.265798 -113.428272)
		(end 227.988622 -109.732572)
		(width 0.1143)
		(layer "In9.Cu")
		(net "UPI_CPU0_CPU1_P0P0_DP<6>")
	)
	(segment
		(start 233.672888 -110.700058)
		(end 248.028968 -107.845352)
		(width 0.1143)
		(layer "In9.Cu")
		(net "UPI_CPU0_CPU1_P0P0_DP<6>")
	)
	(segment
		(start 308.645052 -69.180456)
		(end 308.555136 -69.090794)
		(width 0.0889)
		(layer "In9.Cu")
		(net "UPI_CPU0_CPU1_P0P0_DP<6>")
	)
	(segment
		(start 143.529812 -65.27546)
		(end 143.707612 -65.27546)
		(width 0.0889)
		(layer "In9.Cu")
		(net "UPI_CPU0_CPU1_P0P0_DP<6>")
	)
	(segment
		(start 312.004456 -76.349098)
		(end 311.997852 -76.120498)
		(width 0.1143)
		(layer "In9.Cu")
		(net "UPI_CPU0_CPU1_P0P0_DP<6>")
	)
	(segment
		(start 312.099452 -79.737458)
		(end 311.9628 -79.608172)
		(width 0.1143)
		(layer "In9.Cu")
		(net "UPI_CPU0_CPU1_P0P0_DP<6>")
	)
	(segment
		(start 145.007076 -65.365884)
		(end 145.415254 -64.957706)
		(width 0.0889)
		(layer "In9.Cu")
		(net "UPI_CPU0_CPU1_P0P0_DP<6>")
	)
	(segment
		(start 311.960514 -74.70267)
		(end 310.678576 -71.142352)
		(width 0.1143)
		(layer "In9.Cu")
		(net "UPI_CPU0_CPU1_P0P0_DP<6>")
	)
	(segment
		(start 152.677114 -71.552816)
		(end 156.749242 -86.569042)
		(width 0.1143)
		(layer "In9.Cu")
		(net "UPI_CPU0_CPU1_P0P0_DP<6>")
	)
	(segment
		(start 143.171164 -65.27546)
		(end 143.261588 -65.365884)
		(width 0.0889)
		(layer "In9.Cu")
		(net "UPI_CPU0_CPU1_P0P0_DP<6>")
	)
	(segment
		(start 179.347876 -108.50753)
		(end 184.656476 -109.661452)
		(width 0.1143)
		(layer "In9.Cu")
		(net "UPI_CPU0_CPU1_P0P0_DP<6>")
	)
	(segment
		(start 310.078628 -70.598284)
		(end 309.952898 -70.472554)
		(width 0.0889)
		(layer "In9.Cu")
		(net "UPI_CPU0_CPU1_P0P0_DP<6>")
	)
	(segment
		(start 311.997852 -76.120498)
		(end 311.8612 -75.991212)
		(width 0.1143)
		(layer "In9.Cu")
		(net "UPI_CPU0_CPU1_P0P0_DP<6>")
	)
	(segment
		(start 144.06626 -65.27546)
		(end 144.24406 -65.27546)
		(width 0.0889)
		(layer "In9.Cu")
		(net "UPI_CPU0_CPU1_P0P0_DP<6>")
	)
	(segment
		(start 310.359044 -70.750684)
		(end 310.206644 -70.598284)
		(width 0.0889)
		(layer "In9.Cu")
		(net "UPI_CPU0_CPU1_P0P0_DP<6>")
	)
	(segment
		(start 311.874916 -76.485496)
		(end 312.004456 -76.349098)
		(width 0.1143)
		(layer "In9.Cu")
		(net "UPI_CPU0_CPU1_P0P0_DP<6>")
	)
	(segment
		(start 143.975836 -65.365884)
		(end 144.06626 -65.27546)
		(width 0.0889)
		(layer "In9.Cu")
		(net "UPI_CPU0_CPU1_P0P0_DP<6>")
	)
	(segment
		(start 144.334484 -65.365884)
		(end 144.512284 -65.365884)
		(width 0.0889)
		(layer "In9.Cu")
		(net "UPI_CPU0_CPU1_P0P0_DP<6>")
	)
	(segment
		(start 145.415254 -64.957706)
		(end 145.728436 -64.957706)
		(width 0.0889)
		(layer "In9.Cu")
		(net "UPI_CPU0_CPU1_P0P0_DP<6>")
	)
	(segment
		(start 176.67859 -106.605832)
		(end 178.464464 -108.146596)
		(width 0.1143)
		(layer "In9.Cu")
		(net "UPI_CPU0_CPU1_P0P0_DP<6>")
	)
	(segment
		(start 267.121386 -111.116872)
		(end 278.08682 -110.063788)
		(width 0.1143)
		(layer "In9.Cu")
		(net "UPI_CPU0_CPU1_P0P0_DP<6>")
	)
	(segment
		(start 248.028968 -107.845352)
		(end 262.840724 -110.90656)
		(width 0.1143)
		(layer "In9.Cu")
		(net "UPI_CPU0_CPU1_P0P0_DP<6>")
	)
	(segment
		(start 281.735784 -110.486698)
		(end 290.970462 -106.652822)
		(width 0.1143)
		(layer "In9.Cu")
		(net "UPI_CPU0_CPU1_P0P0_DP<6>")
	)
	(segment
		(start 143.261588 -65.365884)
		(end 143.439388 -65.365884)
		(width 0.0889)
		(layer "In9.Cu")
		(net "UPI_CPU0_CPU1_P0P0_DP<6>")
	)
	(segment
		(start 307.908452 -68.300092)
		(end 307.81879 -68.21043)
		(width 0.0889)
		(layer "In9.Cu")
		(net "UPI_CPU0_CPU1_P0P0_DP<6>")
	)
	(segment
		(start 190.30315 -110.478824)
		(end 191.382396 -110.557818)
		(width 0.1143)
		(layer "In9.Cu")
		(net "UPI_CPU0_CPU1_P0P0_DP<6>")
	)
	(segment
		(start 307.495448 -67.887088)
		(end 306.94884 -67.887088)
		(width 0.0889)
		(layer "In9.Cu")
		(net "UPI_CPU0_CPU1_P0P0_DP<6>")
	)
	(segment
		(start 191.382396 -110.557818)
		(end 196.280024 -113.25225)
		(width 0.1143)
		(layer "In9.Cu")
		(net "UPI_CPU0_CPU1_P0P0_DP<6>")
	)
	(segment
		(start 163.147502 -94.140782)
		(end 163.49599 -96.394778)
		(width 0.1143)
		(layer "In9.Cu")
		(net "UPI_CPU0_CPU1_P0P0_DP<6>")
	)
	(segment
		(start 143.439388 -65.365884)
		(end 143.529812 -65.27546)
		(width 0.0889)
		(layer "In9.Cu")
		(net "UPI_CPU0_CPU1_P0P0_DP<6>")
	)
	(segment
		(start 142.90294 -65.365884)
		(end 142.993364 -65.27546)
		(width 0.0889)
		(layer "In9.Cu")
		(net "UPI_CPU0_CPU1_P0P0_DP<6>")
	)
	(segment
		(start 278.08682 -110.063788)
		(end 281.735784 -110.486698)
		(width 0.1143)
		(layer "In9.Cu")
		(net "UPI_CPU0_CPU1_P0P0_DP<6>")
	)
	(segment
		(start 171.589446 -104.830626)
		(end 171.5897 -104.83088)
		(width 0.1143)
		(layer "In9.Cu")
		(net "UPI_CPU0_CPU1_P0P0_DP<6>")
	)
	(segment
		(start 311.88152 -76.714604)
		(end 311.874916 -76.485496)
		(width 0.1143)
		(layer "In9.Cu")
		(net "UPI_CPU0_CPU1_P0P0_DP<6>")
	)
	(segment
		(start 189.182756 -110.739174)
		(end 190.30315 -110.478824)
		(width 0.1143)
		(layer "In9.Cu")
		(net "UPI_CPU0_CPU1_P0P0_DP<6>")
	)
	(segment
		(start 309.952898 -70.344538)
		(end 309.827168 -70.218808)
		(width 0.0889)
		(layer "In9.Cu")
		(net "UPI_CPU0_CPU1_P0P0_DP<6>")
	)
	(segment
		(start 314.73394 -86.98357)
		(end 312.109104 -80.07985)
		(width 0.1143)
		(layer "In9.Cu")
		(net "UPI_CPU0_CPU1_P0P0_DP<6>")
	)
	(segment
		(start 312.109104 -80.07985)
		(end 312.099452 -79.737458)
		(width 0.1143)
		(layer "In9.Cu")
		(net "UPI_CPU0_CPU1_P0P0_DP<6>")
	)
	(segment
		(start 306.59197 -68.434712)
		(end 306.67071 -68.456048)
		(width 0.0889)
		(layer "In9.Cu")
		(net "UPI_CPU0_CPU1_P0P0_DP<6>")
	)
	(segment
		(start 312.058812 -78.290674)
		(end 311.92216 -78.161388)
		(width 0.1143)
		(layer "In9.Cu")
		(net "UPI_CPU0_CPU1_P0P0_DP<6>")
	)
	(segment
		(start 311.92216 -78.161388)
		(end 311.915556 -77.93228)
		(width 0.1143)
		(layer "In9.Cu")
		(net "UPI_CPU0_CPU1_P0P0_DP<6>")
	)
	(segment
		(start 143.707612 -65.27546)
		(end 143.798036 -65.365884)
		(width 0.0889)
		(layer "In9.Cu")
		(net "UPI_CPU0_CPU1_P0P0_DP<6>")
	)
	(segment
		(start 308.32171 -68.857114)
		(end 308.231794 -68.767452)
		(width 0.0889)
		(layer "In9.Cu")
		(net "UPI_CPU0_CPU1_P0P0_DP<6>")
	)
	(segment
		(start 310.374538 -70.838314)
		(end 310.359044 -70.82282)
		(width 0.0889)
		(layer "In9.Cu")
		(net "UPI_CPU0_CPU1_P0P0_DP<6>")
	)
	(segment
		(start 143.798036 -65.365884)
		(end 143.975836 -65.365884)
		(width 0.0889)
		(layer "In9.Cu")
		(net "UPI_CPU0_CPU1_P0P0_DP<6>")
	)
	(segment
		(start 146.497548 -64.906906)
		(end 148.473414 -66.060066)
		(width 0.1143)
		(layer "In9.Cu")
		(net "UPI_CPU0_CPU1_P0P0_DP<6>")
	)
	(segment
		(start 310.95442 -104.51846)
		(end 314.73394 -86.98357)
		(width 0.1143)
		(layer "In9.Cu")
		(net "UPI_CPU0_CPU1_P0P0_DP<6>")
	)
	(segment
		(start 306.67071 -68.456048)
		(end 306.963826 -68.287138)
		(width 0.0889)
		(layer "In9.Cu")
		(net "UPI_CPU0_CPU1_P0P0_DP<6>")
	)
	(segment
		(start 309.573422 -69.965062)
		(end 308.788816 -69.180456)
		(width 0.0889)
		(layer "In9.Cu")
		(net "UPI_CPU0_CPU1_P0P0_DP<6>")
	)
	(segment
		(start 144.602708 -65.27546)
		(end 144.780508 -65.27546)
		(width 0.0889)
		(layer "In9.Cu")
		(net "UPI_CPU0_CPU1_P0P0_DP<6>")
	)
	(segment
		(start 307.908452 -68.44411)
		(end 307.908452 -68.300092)
		(width 0.0889)
		(layer "In9.Cu")
		(net "UPI_CPU0_CPU1_P0P0_DP<6>")
	)
	(segment
		(start 144.512284 -65.365884)
		(end 144.602708 -65.27546)
		(width 0.0889)
		(layer "In9.Cu")
		(net "UPI_CPU0_CPU1_P0P0_DP<6>")
	)
	(segment
		(start 311.90184 -77.437996)
		(end 311.895236 -77.208888)
		(width 0.1143)
		(layer "In9.Cu")
		(net "UPI_CPU0_CPU1_P0P0_DP<6>")
	)
	(segment
		(start 309.573422 -70.093078)
		(end 309.573422 -69.965062)
		(width 0.0889)
		(layer "In9.Cu")
		(net "UPI_CPU0_CPU1_P0P0_DP<6>")
	)
	(segment
		(start 308.142132 -68.533772)
		(end 307.998368 -68.533772)
		(width 0.0889)
		(layer "In9.Cu")
		(net "UPI_CPU0_CPU1_P0P0_DP<6>")
	)
	(segment
		(start 310.359044 -70.82282)
		(end 310.359044 -70.750684)
		(width 0.0889)
		(layer "In9.Cu")
		(net "UPI_CPU0_CPU1_P0P0_DP<6>")
	)
	(segment
		(start 156.749242 -86.569042)
		(end 163.147502 -94.140782)
		(width 0.1143)
		(layer "In9.Cu")
		(net "UPI_CPU0_CPU1_P0P0_DP<6>")
	)
	(segment
		(start 310.678576 -71.142352)
		(end 310.374538 -70.838314)
		(width 0.1143)
		(layer "In9.Cu")
		(net "UPI_CPU0_CPU1_P0P0_DP<6>")
	)
	(segment
		(start 312.024776 -77.07249)
		(end 312.018172 -76.84389)
		(width 0.1143)
		(layer "In9.Cu")
		(net "UPI_CPU0_CPU1_P0P0_DP<6>")
	)
	(segment
		(start 178.464464 -108.146596)
		(end 179.347876 -108.50753)
		(width 0.1143)
		(layer "In9.Cu")
		(net "UPI_CPU0_CPU1_P0P0_DP<6>")
	)
	(segment
		(start 144.780508 -65.27546)
		(end 144.870932 -65.365884)
		(width 0.0889)
		(layer "In9.Cu")
		(net "UPI_CPU0_CPU1_P0P0_DP<6>")
	)
	(segment
		(start 140.224764 -64.724788)
		(end 140.25753 -64.724788)
		(width 0.0889)
		(layer "In9.Cu")
		(net "UPI_CPU0_CPU1_P0P0_DP<6>")
	)
	(segment
		(start 141.952218 -64.724788)
		(end 142.166594 -64.724788)
		(width 0.0889)
		(layer "In9.Cu")
		(net "UPI_CPU0_CPU1_P0P0_DP<6>")
	)
	(segment
		(start 292.336474 -106.52887)
		(end 302.878998 -109.220762)
		(width 0.1143)
		(layer "In9.Cu")
		(net "UPI_CPU0_CPU1_P0P0_DP<6>")
	)
	(segment
		(start 309.952898 -70.472554)
		(end 309.952898 -70.344538)
		(width 0.0889)
		(layer "In9.Cu")
		(net "UPI_CPU0_CPU1_P0P0_DP<6>")
	)
	(segment
		(start 311.935876 -78.655672)
		(end 312.065416 -78.519274)
		(width 0.1143)
		(layer "In9.Cu")
		(net "UPI_CPU0_CPU1_P0P0_DP<6>")
	)
	(segment
		(start 145.801334 -64.906906)
		(end 146.497548 -64.906906)
		(width 0.1143)
		(layer "In9.Cu")
		(net "UPI_CPU0_CPU1_P0P0_DP<6>")
	)
	(segment
		(start 307.58511 -68.120768)
		(end 307.58511 -67.97675)
		(width 0.0889)
		(layer "In9.Cu")
		(net "UPI_CPU0_CPU1_P0P0_DP<6>")
	)
	(segment
		(start 184.656476 -109.661452)
		(end 189.182756 -110.739174)
		(width 0.1143)
		(layer "In9.Cu")
		(net "UPI_CPU0_CPU1_P0P0_DP<6>")
	)
	(segment
		(start 142.741904 -65.365884)
		(end 142.90294 -65.365884)
		(width 0.0889)
		(layer "In9.Cu")
		(net "UPI_CPU0_CPU1_P0P0_DP<6>")
	)
	(segment
		(start 302.878998 -109.220762)
		(end 306.841652 -108.318808)
		(width 0.1143)
		(layer "In9.Cu")
		(net "UPI_CPU0_CPU1_P0P0_DP<6>")
	)
	(segment
		(start 142.643606 -65.267586)
		(end 142.741904 -65.365884)
		(width 0.0889)
		(layer "In9.Cu")
		(net "UPI_CPU0_CPU1_P0P0_DP<6>")
	)
	(segment
		(start 145.779236 -64.906906)
		(end 145.801334 -64.906906)
		(width 0.0889)
		(layer "In9.Cu")
		(net "UPI_CPU0_CPU1_P0P0_DP<6>")
	)
	(segment
		(start 308.231794 -68.767452)
		(end 308.231794 -68.623434)
		(width 0.0889)
		(layer "In9.Cu")
		(net "UPI_CPU0_CPU1_P0P0_DP<6>")
	)
	(segment
		(start 311.956196 -79.379064)
		(end 312.085736 -79.242666)
		(width 0.1143)
		(layer "In9.Cu")
		(net "UPI_CPU0_CPU1_P0P0_DP<6>")
	)
	(segment
		(start 144.24406 -65.27546)
		(end 144.334484 -65.365884)
		(width 0.0889)
		(layer "In9.Cu")
		(net "UPI_CPU0_CPU1_P0P0_DP<6>")
	)
	(segment
		(start 142.993364 -65.27546)
		(end 143.171164 -65.27546)
		(width 0.0889)
		(layer "In9.Cu")
		(net "UPI_CPU0_CPU1_P0P0_DP<6>")
	)
	(segment
		(start 311.8612 -75.991212)
		(end 311.854596 -75.762104)
		(width 0.1143)
		(layer "In9.Cu")
		(net "UPI_CPU0_CPU1_P0P0_DP<6>")
	)
	(segment
		(start 312.018172 -76.84389)
		(end 311.88152 -76.714604)
		(width 0.1143)
		(layer "In9.Cu")
		(net "UPI_CPU0_CPU1_P0P0_DP<6>")
	)
	(segment
		(start 308.231794 -68.623434)
		(end 308.142132 -68.533772)
		(width 0.0889)
		(layer "In9.Cu")
		(net "UPI_CPU0_CPU1_P0P0_DP<6>")
	)
	(segment
		(start 312.079132 -79.014066)
		(end 311.94248 -78.88478)
		(width 0.1143)
		(layer "In9.Cu")
		(net "UPI_CPU0_CPU1_P0P0_DP<6>")
	)
	(segment
		(start 142.477998 -64.982852)
		(end 142.643606 -65.267586)
		(width 0.0889)
		(layer "In9.Cu")
		(net "UPI_CPU0_CPU1_P0P0_DP<6>")
	)
	(segment
		(start 310.206644 -70.598284)
		(end 310.078628 -70.598284)
		(width 0.0889)
		(layer "In9.Cu")
		(net "UPI_CPU0_CPU1_P0P0_DP<6>")
	)
	(segment
		(start 262.840724 -110.90656)
		(end 267.121386 -111.116872)
		(width 0.1143)
		(layer "In9.Cu")
		(net "UPI_CPU0_CPU1_P0P0_DP<6>")
	)
	(segment
		(start 141.087094 -64.229234)
		(end 141.122654 -64.229234)
		(width 0.0889)
		(layer "In9.Cu")
		(net "UPI_CPU0_CPU1_P0P0_DP<6>")
	)
	(segment
		(start 309.827168 -70.218808)
		(end 309.699152 -70.218808)
		(width 0.0889)
		(layer "In9.Cu")
		(net "UPI_CPU0_CPU1_P0P0_DP<6>")
	)
	(segment
		(start 312.065416 -78.519274)
		(end 312.058812 -78.290674)
		(width 0.1143)
		(layer "In9.Cu")
		(net "UPI_CPU0_CPU1_P0P0_DP<6>")
	)
	(segment
		(start 311.94248 -78.88478)
		(end 311.935876 -78.655672)
		(width 0.1143)
		(layer "In9.Cu")
		(net "UPI_CPU0_CPU1_P0P0_DP<6>")
	)
	(segment
		(start 311.98439 -75.625706)
		(end 311.960514 -74.70267)
		(width 0.1143)
		(layer "In9.Cu")
		(net "UPI_CPU0_CPU1_P0P0_DP<6>")
	)
	(segment
		(start 148.473414 -66.060066)
		(end 149.787102 -67.71259)
		(width 0.1143)
		(layer "In9.Cu")
		(net "UPI_CPU0_CPU1_P0P0_DP<6>")
	)
	(segment
		(start 307.998368 -68.533772)
		(end 307.908452 -68.44411)
		(width 0.0889)
		(layer "In9.Cu")
		(net "UPI_CPU0_CPU1_P0P0_DP<6>")
	)
	(segment
		(start 311.9628 -79.608172)
		(end 311.956196 -79.379064)
		(width 0.1143)
		(layer "In9.Cu")
		(net "UPI_CPU0_CPU1_P0P0_DP<6>")
	)
	(arc
		(start 138.876024 -65.515236)
		(mid 139.084632 -65.303304)
		(end 139.370054 -65.219834)
		(width 0.0889)
		(layer "In9.Cu")
		(net "UPI_CPU0_CPU1_P0P0_DP<6>")
	)
	(arc
		(start 140.25753 -64.724788)
		(mid 140.45138 -64.668438)
		(end 140.593064 -64.524636)
		(width 0.0889)
		(layer "In9.Cu")
		(net "UPI_CPU0_CPU1_P0P0_DP<6>")
	)
	(arc
		(start 141.616684 -64.524636)
		(mid 141.758367 -64.66844)
		(end 141.952218 -64.724788)
		(width 0.0889)
		(layer "In9.Cu")
		(net "UPI_CPU0_CPU1_P0P0_DP<6>")
	)
	(arc
		(start 138.541252 -65.715388)
		(mid 138.734678 -65.658861)
		(end 138.876024 -65.515236)
		(width 0.0889)
		(layer "In9.Cu")
		(net "UPI_CPU0_CPU1_P0P0_DP<6>")
	)
	(arc
		(start 138.182604 -65.515236)
		(mid 138.32396 -65.658845)
		(end 138.517376 -65.715388)
		(width 0.0889)
		(layer "In9.Cu")
		(net "UPI_CPU0_CPU1_P0P0_DP<6>")
	)
	(arc
		(start 138.157458 -65.16751)
		(mid 138.130197 -65.344248)
		(end 138.182604 -65.515236)
		(width 0.0889)
		(layer "In9.Cu")
		(net "UPI_CPU0_CPU1_P0P0_DP<6>")
	)
	(arc
		(start 138.517376 -65.715388)
		(mid 138.529314 -65.715566)
		(end 138.541252 -65.715388)
		(width 0.0889)
		(layer "In9.Cu")
		(net "UPI_CPU0_CPU1_P0P0_DP<6>")
	)
	(arc
		(start 306.563776 -68.284598)
		(mid 306.570644 -68.361013)
		(end 306.59197 -68.434712)
		(width 0.0889)
		(layer "In9.Cu")
		(net "UPI_CPU0_CPU1_P0P0_DP<6>")
	)
	(arc
		(start 306.94884 -67.887088)
		(mid 306.676541 -68.008582)
		(end 306.563776 -68.284598)
		(width 0.0889)
		(layer "In9.Cu")
		(net "UPI_CPU0_CPU1_P0P0_DP<6>")
	)
	(arc
		(start 140.593064 -64.524636)
		(mid 140.801672 -64.312704)
		(end 141.087094 -64.229234)
		(width 0.0889)
		(layer "In9.Cu")
		(net "UPI_CPU0_CPU1_P0P0_DP<6>")
	)
	(arc
		(start 139.40282 -65.219834)
		(mid 139.594462 -65.162668)
		(end 139.734544 -65.019936)
		(width 0.0889)
		(layer "In9.Cu")
		(net "UPI_CPU0_CPU1_P0P0_DP<6>")
	)
	(arc
		(start 141.122654 -64.229234)
		(mid 141.408078 -64.312701)
		(end 141.616684 -64.524636)
		(width 0.0889)
		(layer "In9.Cu")
		(net "UPI_CPU0_CPU1_P0P0_DP<6>")
	)
	(arc
		(start 139.734544 -65.019936)
		(mid 139.941548 -64.809072)
		(end 140.224764 -64.724788)
		(width 0.0889)
		(layer "In9.Cu")
		(net "UPI_CPU0_CPU1_P0P0_DP<6>")
	)
	(arc
		(start 142.166594 -64.724788)
		(mid 142.345792 -64.82547)
		(end 142.477998 -64.982852)
		(width 0.0889)
		(layer "In9.Cu")
		(net "UPI_CPU0_CPU1_P0P0_DP<6>")
	)
	(segment
		(start 304.675286 -68.287138)
		(end 305.246786 -68.287138)
		(width 0.1143)
		(layer "F.Cu")
		(net "UPI_CPU0_CPU1_P0P0_DP<5>")
	)
	(segment
		(start 136.240774 -64.324738)
		(end 136.812274 -64.324738)
		(width 0.1143)
		(layer "F.Cu")
		(net "UPI_CPU0_CPU1_P0P0_DP<5>")
	)
	(via
		(at 136.812274 -64.324738)
		(size 0.508)
		(drill 0.254)
		(layers "F.Cu" "B.Cu")
		(net "UPI_CPU0_CPU1_P0P0_DP<5>")
	)
	(via
		(at 305.246786 -68.287138)
		(size 0.508)
		(drill 0.254)
		(layers "F.Cu" "B.Cu")
		(net "UPI_CPU0_CPU1_P0P0_DP<5>")
	)
	(segment
		(start 313.017662 -93.307662)
		(end 313.682126 -90.225626)
		(width 0.1143)
		(layer "In9.Cu")
		(net "UPI_CPU0_CPU1_P0P0_DP<5>")
	)
	(segment
		(start 266.051284 -110.718346)
		(end 266.051284 -110.718092)
		(width 0.1143)
		(layer "In9.Cu")
		(net "UPI_CPU0_CPU1_P0P0_DP<5>")
	)
	(segment
		(start 311.48147 -75.189588)
		(end 311.4802 -75.188572)
		(width 0.1143)
		(layer "In9.Cu")
		(net "UPI_CPU0_CPU1_P0P0_DP<5>")
	)
	(segment
		(start 227.992686 -109.382814)
		(end 233.667554 -110.348776)
		(width 0.1143)
		(layer "In9.Cu")
		(net "UPI_CPU0_CPU1_P0P0_DP<5>")
	)
	(segment
		(start 292.364414 -106.17962)
		(end 302.884078 -108.865924)
		(width 0.1143)
		(layer "In9.Cu")
		(net "UPI_CPU0_CPU1_P0P0_DP<5>")
	)
	(segment
		(start 179.748434 -108.272326)
		(end 183.769 -108.9152)
		(width 0.1143)
		(layer "In9.Cu")
		(net "UPI_CPU0_CPU1_P0P0_DP<5>")
	)
	(segment
		(start 314.346082 -87.144606)
		(end 311.612788 -79.95539)
		(width 0.1143)
		(layer "In9.Cu")
		(net "UPI_CPU0_CPU1_P0P0_DP<5>")
	)
	(segment
		(start 178.92014 -107.940602)
		(end 179.748434 -108.272326)
		(width 0.1143)
		(layer "In9.Cu")
		(net "UPI_CPU0_CPU1_P0P0_DP<5>")
	)
	(segment
		(start 212.654134 -111.228124)
		(end 227.992686 -109.382814)
		(width 0.1143)
		(layer "In9.Cu")
		(net "UPI_CPU0_CPU1_P0P0_DP<5>")
	)
	(segment
		(start 141.809724 -62.917578)
		(end 142.623286 -62.917578)
		(width 0.0889)
		(layer "In9.Cu")
		(net "UPI_CPU0_CPU1_P0P0_DP<5>")
	)
	(segment
		(start 309.327804 -70.582028)
		(end 309.256176 -70.582282)
		(width 0.0889)
		(layer "In9.Cu")
		(net "UPI_CPU0_CPU1_P0P0_DP<5>")
	)
	(segment
		(start 137.649204 -64.419734)
		(end 137.68197 -64.419734)
		(width 0.0889)
		(layer "In9.Cu")
		(net "UPI_CPU0_CPU1_P0P0_DP<5>")
	)
	(segment
		(start 308.141116 -69.162676)
		(end 307.6956 -68.949316)
		(width 0.0889)
		(layer "In9.Cu")
		(net "UPI_CPU0_CPU1_P0P0_DP<5>")
	)
	(segment
		(start 189.510162 -108.577888)
		(end 191.185292 -108.864654)
		(width 0.1143)
		(layer "In9.Cu")
		(net "UPI_CPU0_CPU1_P0P0_DP<5>")
	)
	(segment
		(start 309.14213 -70.16369)
		(end 308.141116 -69.162676)
		(width 0.0889)
		(layer "In9.Cu")
		(net "UPI_CPU0_CPU1_P0P0_DP<5>")
	)
	(segment
		(start 177.134012 -106.399076)
		(end 178.92014 -107.940602)
		(width 0.1143)
		(layer "In9.Cu")
		(net "UPI_CPU0_CPU1_P0P0_DP<5>")
	)
	(segment
		(start 143.981678 -64.27597)
		(end 145.520156 -64.27597)
		(width 0.0889)
		(layer "In9.Cu")
		(net "UPI_CPU0_CPU1_P0P0_DP<5>")
	)
	(segment
		(start 191.185292 -108.864654)
		(end 195.639182 -112.505744)
		(width 0.1143)
		(layer "In9.Cu")
		(net "UPI_CPU0_CPU1_P0P0_DP<5>")
	)
	(segment
		(start 291.125402 -106.291888)
		(end 292.364414 -106.17962)
		(width 0.1143)
		(layer "In9.Cu")
		(net "UPI_CPU0_CPU1_P0P0_DP<5>")
	)
	(segment
		(start 145.593054 -64.32677)
		(end 147.113752 -64.32677)
		(width 0.1143)
		(layer "In9.Cu")
		(net "UPI_CPU0_CPU1_P0P0_DP<5>")
	)
	(segment
		(start 309.14213 -70.468236)
		(end 309.14213 -70.16369)
		(width 0.0889)
		(layer "In9.Cu")
		(net "UPI_CPU0_CPU1_P0P0_DP<5>")
	)
	(segment
		(start 313.682126 -90.225626)
		(end 314.346082 -87.144606)
		(width 0.1143)
		(layer "In9.Cu")
		(net "UPI_CPU0_CPU1_P0P0_DP<5>")
	)
	(segment
		(start 197.315582 -113.07318)
		(end 212.654134 -111.228124)
		(width 0.1143)
		(layer "In9.Cu")
		(net "UPI_CPU0_CPU1_P0P0_DP<5>")
	)
	(segment
		(start 311.4802 -75.188572)
		(end 311.46623 -74.635614)
		(width 0.1143)
		(layer "In9.Cu")
		(net "UPI_CPU0_CPU1_P0P0_DP<5>")
	)
	(segment
		(start 136.812274 -64.324738)
		(end 137.10539 -64.155574)
		(width 0.0889)
		(layer "In9.Cu")
		(net "UPI_CPU0_CPU1_P0P0_DP<5>")
	)
	(segment
		(start 307.147722 -68.687188)
		(end 306.94249 -68.687188)
		(width 0.0889)
		(layer "In9.Cu")
		(net "UPI_CPU0_CPU1_P0P0_DP<5>")
	)
	(segment
		(start 267.113258 -110.770416)
		(end 278.09063 -109.716316)
		(width 0.1143)
		(layer "In9.Cu")
		(net "UPI_CPU0_CPU1_P0P0_DP<5>")
	)
	(segment
		(start 163.873942 -96.260158)
		(end 171.82338 -104.546654)
		(width 0.1143)
		(layer "In9.Cu")
		(net "UPI_CPU0_CPU1_P0P0_DP<5>")
	)
	(segment
		(start 140.231368 -63.924688)
		(end 140.264134 -63.924688)
		(width 0.0889)
		(layer "In9.Cu")
		(net "UPI_CPU0_CPU1_P0P0_DP<5>")
	)
	(segment
		(start 311.46623 -74.635614)
		(end 310.234838 -71.489062)
		(width 0.1143)
		(layer "In9.Cu")
		(net "UPI_CPU0_CPU1_P0P0_DP<5>")
	)
	(segment
		(start 290.887404 -106.313478)
		(end 291.125402 -106.291888)
		(width 0.1143)
		(layer "In9.Cu")
		(net "UPI_CPU0_CPU1_P0P0_DP<5>")
	)
	(segment
		(start 145.570956 -64.32677)
		(end 145.593054 -64.32677)
		(width 0.0889)
		(layer "In9.Cu")
		(net "UPI_CPU0_CPU1_P0P0_DP<5>")
	)
	(segment
		(start 138.528806 -64.915288)
		(end 138.529822 -64.915288)
		(width 0.0889)
		(layer "In9.Cu")
		(net "UPI_CPU0_CPU1_P0P0_DP<5>")
	)
	(segment
		(start 311.539382 -77.285342)
		(end 311.48147 -75.189588)
		(width 0.1143)
		(layer "In9.Cu")
		(net "UPI_CPU0_CPU1_P0P0_DP<5>")
	)
	(segment
		(start 302.884078 -108.865924)
		(end 306.676298 -108.002324)
		(width 0.1143)
		(layer "In9.Cu")
		(net "UPI_CPU0_CPU1_P0P0_DP<5>")
	)
	(segment
		(start 141.616938 -63.133986)
		(end 141.648688 -63.078614)
		(width 0.0889)
		(layer "In9.Cu")
		(net "UPI_CPU0_CPU1_P0P0_DP<5>")
	)
	(segment
		(start 171.82338 -104.546654)
		(end 174.538132 -105.49382)
		(width 0.1143)
		(layer "In9.Cu")
		(net "UPI_CPU0_CPU1_P0P0_DP<5>")
	)
	(segment
		(start 305.31181 -68.690236)
		(end 305.246786 -68.625212)
		(width 0.0889)
		(layer "In9.Cu")
		(net "UPI_CPU0_CPU1_P0P0_DP<5>")
	)
	(segment
		(start 163.776914 -95.629222)
		(end 163.873942 -96.260158)
		(width 0.1143)
		(layer "In9.Cu")
		(net "UPI_CPU0_CPU1_P0P0_DP<5>")
	)
	(segment
		(start 309.343298 -70.597522)
		(end 309.327804 -70.582028)
		(width 0.0889)
		(layer "In9.Cu")
		(net "UPI_CPU0_CPU1_P0P0_DP<5>")
	)
	(segment
		(start 189.380622 -108.575856)
		(end 189.510162 -108.577888)
		(width 0.1143)
		(layer "In9.Cu")
		(net "UPI_CPU0_CPU1_P0P0_DP<5>")
	)
	(segment
		(start 306.120292 -69.182234)
		(end 306.09032 -69.182234)
		(width 0.0889)
		(layer "In9.Cu")
		(net "UPI_CPU0_CPU1_P0P0_DP<5>")
	)
	(segment
		(start 142.623286 -62.917578)
		(end 143.981678 -64.27597)
		(width 0.0889)
		(layer "In9.Cu")
		(net "UPI_CPU0_CPU1_P0P0_DP<5>")
	)
	(segment
		(start 311.612788 -79.95539)
		(end 311.609486 -79.8322)
		(width 0.1143)
		(layer "In9.Cu")
		(net "UPI_CPU0_CPU1_P0P0_DP<5>")
	)
	(segment
		(start 306.676298 -108.002324)
		(end 310.639968 -104.338882)
		(width 0.1143)
		(layer "In9.Cu")
		(net "UPI_CPU0_CPU1_P0P0_DP<5>")
	)
	(segment
		(start 141.648688 -63.078614)
		(end 141.809724 -62.917578)
		(width 0.0889)
		(layer "In9.Cu")
		(net "UPI_CPU0_CPU1_P0P0_DP<5>")
	)
	(segment
		(start 196.302884 -112.86998)
		(end 197.315582 -113.07318)
		(width 0.1143)
		(layer "In9.Cu")
		(net "UPI_CPU0_CPU1_P0P0_DP<5>")
	)
	(segment
		(start 311.609486 -79.8322)
		(end 311.539382 -77.285342)
		(width 0.1143)
		(layer "In9.Cu")
		(net "UPI_CPU0_CPU1_P0P0_DP<5>")
	)
	(segment
		(start 262.908034 -110.563914)
		(end 266.051284 -110.718346)
		(width 0.1143)
		(layer "In9.Cu")
		(net "UPI_CPU0_CPU1_P0P0_DP<5>")
	)
	(segment
		(start 141.093698 -63.429134)
		(end 141.12621 -63.429134)
		(width 0.0889)
		(layer "In9.Cu")
		(net "UPI_CPU0_CPU1_P0P0_DP<5>")
	)
	(segment
		(start 310.234838 -71.489062)
		(end 309.343298 -70.597522)
		(width 0.1143)
		(layer "In9.Cu")
		(net "UPI_CPU0_CPU1_P0P0_DP<5>")
	)
	(segment
		(start 163.534598 -94.063312)
		(end 163.776406 -95.628968)
		(width 0.1143)
		(layer "In9.Cu")
		(net "UPI_CPU0_CPU1_P0P0_DP<5>")
	)
	(segment
		(start 174.538132 -105.49382)
		(end 174.538132 -105.493566)
		(width 0.1143)
		(layer "In9.Cu")
		(net "UPI_CPU0_CPU1_P0P0_DP<5>")
	)
	(segment
		(start 310.639968 -104.338882)
		(end 313.017662 -93.307662)
		(width 0.1143)
		(layer "In9.Cu")
		(net "UPI_CPU0_CPU1_P0P0_DP<5>")
	)
	(segment
		(start 307.6956 -68.949316)
		(end 307.147722 -68.687188)
		(width 0.0889)
		(layer "In9.Cu")
		(net "UPI_CPU0_CPU1_P0P0_DP<5>")
	)
	(segment
		(start 278.09063 -109.716316)
		(end 281.686 -110.13313)
		(width 0.1143)
		(layer "In9.Cu")
		(net "UPI_CPU0_CPU1_P0P0_DP<5>")
	)
	(segment
		(start 183.769 -108.9152)
		(end 188.358526 -108.713524)
		(width 0.1143)
		(layer "In9.Cu")
		(net "UPI_CPU0_CPU1_P0P0_DP<5>")
	)
	(segment
		(start 157.062678 -86.404196)
		(end 163.534598 -94.063312)
		(width 0.1143)
		(layer "In9.Cu")
		(net "UPI_CPU0_CPU1_P0P0_DP<5>")
	)
	(segment
		(start 309.256176 -70.582282)
		(end 309.14213 -70.468236)
		(width 0.0889)
		(layer "In9.Cu")
		(net "UPI_CPU0_CPU1_P0P0_DP<5>")
	)
	(segment
		(start 152.593548 -69.925946)
		(end 157.062678 -86.404196)
		(width 0.1143)
		(layer "In9.Cu")
		(net "UPI_CPU0_CPU1_P0P0_DP<5>")
	)
	(segment
		(start 233.667554 -110.348776)
		(end 248.030492 -107.492546)
		(width 0.1143)
		(layer "In9.Cu")
		(net "UPI_CPU0_CPU1_P0P0_DP<5>")
	)
	(segment
		(start 147.113752 -64.32677)
		(end 147.787868 -64.621918)
		(width 0.1143)
		(layer "In9.Cu")
		(net "UPI_CPU0_CPU1_P0P0_DP<5>")
	)
	(segment
		(start 305.246786 -68.625212)
		(end 305.246786 -68.287138)
		(width 0.0889)
		(layer "In9.Cu")
		(net "UPI_CPU0_CPU1_P0P0_DP<5>")
	)
	(segment
		(start 163.776406 -95.628968)
		(end 163.776914 -95.629222)
		(width 0.1143)
		(layer "In9.Cu")
		(net "UPI_CPU0_CPU1_P0P0_DP<5>")
	)
	(segment
		(start 248.030492 -107.492546)
		(end 262.908034 -110.563914)
		(width 0.1143)
		(layer "In9.Cu")
		(net "UPI_CPU0_CPU1_P0P0_DP<5>")
	)
	(segment
		(start 139.376658 -64.419734)
		(end 139.409424 -64.419734)
		(width 0.0889)
		(layer "In9.Cu")
		(net "UPI_CPU0_CPU1_P0P0_DP<5>")
	)
	(segment
		(start 195.639182 -112.505744)
		(end 196.302884 -112.86998)
		(width 0.1143)
		(layer "In9.Cu")
		(net "UPI_CPU0_CPU1_P0P0_DP<5>")
	)
	(segment
		(start 145.520156 -64.27597)
		(end 145.570956 -64.32677)
		(width 0.0889)
		(layer "In9.Cu")
		(net "UPI_CPU0_CPU1_P0P0_DP<5>")
	)
	(segment
		(start 147.787868 -64.621918)
		(end 152.593548 -69.925946)
		(width 0.1143)
		(layer "In9.Cu")
		(net "UPI_CPU0_CPU1_P0P0_DP<5>")
	)
	(segment
		(start 137.10539 -64.155574)
		(end 137.194798 -64.179704)
		(width 0.0889)
		(layer "In9.Cu")
		(net "UPI_CPU0_CPU1_P0P0_DP<5>")
	)
	(segment
		(start 174.538132 -105.493566)
		(end 177.134012 -106.399076)
		(width 0.1143)
		(layer "In9.Cu")
		(net "UPI_CPU0_CPU1_P0P0_DP<5>")
	)
	(segment
		(start 188.358526 -108.713524)
		(end 189.380622 -108.575856)
		(width 0.1143)
		(layer "In9.Cu")
		(net "UPI_CPU0_CPU1_P0P0_DP<5>")
	)
	(segment
		(start 281.686 -110.13313)
		(end 290.887404 -106.313478)
		(width 0.1143)
		(layer "In9.Cu")
		(net "UPI_CPU0_CPU1_P0P0_DP<5>")
	)
	(segment
		(start 266.051284 -110.718092)
		(end 267.113258 -110.770416)
		(width 0.1143)
		(layer "In9.Cu")
		(net "UPI_CPU0_CPU1_P0P0_DP<5>")
	)
	(arc
		(start 138.017504 -64.619886)
		(mid 138.233567 -64.836095)
		(end 138.528806 -64.915288)
		(width 0.0889)
		(layer "In9.Cu")
		(net "UPI_CPU0_CPU1_P0P0_DP<5>")
	)
	(arc
		(start 140.758164 -63.629286)
		(mid 140.899847 -63.485482)
		(end 141.093698 -63.429134)
		(width 0.0889)
		(layer "In9.Cu")
		(net "UPI_CPU0_CPU1_P0P0_DP<5>")
	)
	(arc
		(start 141.12621 -63.429134)
		(mid 141.409708 -63.344968)
		(end 141.616938 -63.133986)
		(width 0.0889)
		(layer "In9.Cu")
		(net "UPI_CPU0_CPU1_P0P0_DP<5>")
	)
	(arc
		(start 137.68197 -64.419734)
		(mid 137.87582 -64.476084)
		(end 138.017504 -64.619886)
		(width 0.0889)
		(layer "In9.Cu")
		(net "UPI_CPU0_CPU1_P0P0_DP<5>")
	)
	(arc
		(start 137.194798 -64.179704)
		(mid 137.394543 -64.351698)
		(end 137.649204 -64.419734)
		(width 0.0889)
		(layer "In9.Cu")
		(net "UPI_CPU0_CPU1_P0P0_DP<5>")
	)
	(arc
		(start 305.758596 -68.982336)
		(mid 305.570068 -68.782963)
		(end 305.31181 -68.690236)
		(width 0.0889)
		(layer "In9.Cu")
		(net "UPI_CPU0_CPU1_P0P0_DP<5>")
	)
	(arc
		(start 306.452016 -68.982336)
		(mid 306.311937 -69.125072)
		(end 306.120292 -69.182234)
		(width 0.0889)
		(layer "In9.Cu")
		(net "UPI_CPU0_CPU1_P0P0_DP<5>")
	)
	(arc
		(start 139.899644 -64.124586)
		(mid 140.039723 -63.98185)
		(end 140.231368 -63.924688)
		(width 0.0889)
		(layer "In9.Cu")
		(net "UPI_CPU0_CPU1_P0P0_DP<5>")
	)
	(arc
		(start 140.264134 -63.924688)
		(mid 140.549558 -63.841221)
		(end 140.758164 -63.629286)
		(width 0.0889)
		(layer "In9.Cu")
		(net "UPI_CPU0_CPU1_P0P0_DP<5>")
	)
	(arc
		(start 306.94249 -68.687188)
		(mid 306.659132 -68.771412)
		(end 306.452016 -68.982336)
		(width 0.0889)
		(layer "In9.Cu")
		(net "UPI_CPU0_CPU1_P0P0_DP<5>")
	)
	(arc
		(start 138.529822 -64.915288)
		(mid 138.825085 -64.836137)
		(end 139.041124 -64.619886)
		(width 0.0889)
		(layer "In9.Cu")
		(net "UPI_CPU0_CPU1_P0P0_DP<5>")
	)
	(arc
		(start 139.041124 -64.619886)
		(mid 139.182807 -64.476082)
		(end 139.376658 -64.419734)
		(width 0.0889)
		(layer "In9.Cu")
		(net "UPI_CPU0_CPU1_P0P0_DP<5>")
	)
	(arc
		(start 139.409424 -64.419734)
		(mid 139.692641 -64.335453)
		(end 139.899644 -64.124586)
		(width 0.0889)
		(layer "In9.Cu")
		(net "UPI_CPU0_CPU1_P0P0_DP<5>")
	)
	(arc
		(start 306.09032 -69.182234)
		(mid 305.898678 -69.125068)
		(end 305.758596 -68.982336)
		(width 0.0889)
		(layer "In9.Cu")
		(net "UPI_CPU0_CPU1_P0P0_DP<5>")
	)
	(segment
		(start 304.675286 -70.268084)
		(end 305.246786 -70.268084)
		(width 0.1143)
		(layer "F.Cu")
		(net "UPI_CPU0_CPU1_P0P0_DP<4>")
	)
	(segment
		(start 137.957814 -63.334138)
		(end 138.529314 -63.334138)
		(width 0.1143)
		(layer "F.Cu")
		(net "UPI_CPU0_CPU1_P0P0_DP<4>")
	)
	(via
		(at 305.246786 -70.268084)
		(size 0.508)
		(drill 0.254)
		(layers "F.Cu" "B.Cu")
		(net "UPI_CPU0_CPU1_P0P0_DP<4>")
	)
	(via
		(at 138.529314 -63.334138)
		(size 0.508)
		(drill 0.254)
		(layers "F.Cu" "B.Cu")
		(net "UPI_CPU0_CPU1_P0P0_DP<4>")
	)
	(segment
		(start 311.961784 -93.7768)
		(end 312.232294 -92.522294)
		(width 0.1143)
		(layer "In9.Cu")
		(net "UPI_CPU0_CPU1_P0P0_DP<4>")
	)
	(segment
		(start 308.98592 -71.747888)
		(end 308.687724 -71.449692)
		(width 0.0889)
		(layer "In9.Cu")
		(net "UPI_CPU0_CPU1_P0P0_DP<4>")
	)
	(segment
		(start 313.34837 -87.348568)
		(end 310.531764 -79.939134)
		(width 0.1143)
		(layer "In9.Cu")
		(net "UPI_CPU0_CPU1_P0P0_DP<4>")
	)
	(segment
		(start 310.373776 -79.418688)
		(end 310.367172 -79.18958)
		(width 0.1143)
		(layer "In9.Cu")
		(net "UPI_CPU0_CPU1_P0P0_DP<4>")
	)
	(segment
		(start 310.402986 -75.3237)
		(end 310.393588 -74.939652)
		(width 0.1143)
		(layer "In9.Cu")
		(net "UPI_CPU0_CPU1_P0P0_DP<4>")
	)
	(segment
		(start 310.520842 -79.557372)
		(end 310.373776 -79.418688)
		(width 0.1143)
		(layer "In9.Cu")
		(net "UPI_CPU0_CPU1_P0P0_DP<4>")
	)
	(segment
		(start 306.641754 -70.19036)
		(end 306.626006 -70.201282)
		(width 0.0889)
		(layer "In9.Cu")
		(net "UPI_CPU0_CPU1_P0P0_DP<4>")
	)
	(segment
		(start 302.895508 -107.909106)
		(end 304.56124 -107.529884)
		(width 0.1143)
		(layer "In9.Cu")
		(net "UPI_CPU0_CPU1_P0P0_DP<4>")
	)
	(segment
		(start 191.701166 -108.060236)
		(end 196.472556 -111.91621)
		(width 0.1143)
		(layer "In9.Cu")
		(net "UPI_CPU0_CPU1_P0P0_DP<4>")
	)
	(segment
		(start 173.768258 -103.449882)
		(end 173.768258 -103.45039)
		(width 0.1143)
		(layer "In9.Cu")
		(net "UPI_CPU0_CPU1_P0P0_DP<4>")
	)
	(segment
		(start 144.671542 -63.09995)
		(end 144.69364 -63.09995)
		(width 0.0889)
		(layer "In9.Cu")
		(net "UPI_CPU0_CPU1_P0P0_DP<4>")
	)
	(segment
		(start 310.416956 -75.838812)
		(end 310.269636 -75.700128)
		(width 0.1143)
		(layer "In9.Cu")
		(net "UPI_CPU0_CPU1_P0P0_DP<4>")
	)
	(segment
		(start 143.963644 -63.15075)
		(end 144.620742 -63.15075)
		(width 0.0889)
		(layer "In9.Cu")
		(net "UPI_CPU0_CPU1_P0P0_DP<4>")
	)
	(segment
		(start 309.213504 -72.047354)
		(end 309.001668 -71.835518)
		(width 0.1143)
		(layer "In9.Cu")
		(net "UPI_CPU0_CPU1_P0P0_DP<4>")
	)
	(segment
		(start 310.367172 -79.18958)
		(end 310.506872 -79.042514)
		(width 0.1143)
		(layer "In9.Cu")
		(net "UPI_CPU0_CPU1_P0P0_DP<4>")
	)
	(segment
		(start 306.105306 -70.363334)
		(end 306.083716 -70.363334)
		(width 0.0889)
		(layer "In9.Cu")
		(net "UPI_CPU0_CPU1_P0P0_DP<4>")
	)
	(segment
		(start 310.500268 -78.81366)
		(end 310.352948 -78.674976)
		(width 0.1143)
		(layer "In9.Cu")
		(net "UPI_CPU0_CPU1_P0P0_DP<4>")
	)
	(segment
		(start 310.444388 -76.811378)
		(end 310.437784 -76.582524)
		(width 0.1143)
		(layer "In9.Cu")
		(net "UPI_CPU0_CPU1_P0P0_DP<4>")
	)
	(segment
		(start 310.531764 -79.939134)
		(end 310.528716 -79.8322)
		(width 0.1143)
		(layer "In9.Cu")
		(net "UPI_CPU0_CPU1_P0P0_DP<4>")
	)
	(segment
		(start 308.687724 -71.449692)
		(end 308.557676 -71.449692)
		(width 0.0889)
		(layer "In9.Cu")
		(net "UPI_CPU0_CPU1_P0P0_DP<4>")
	)
	(segment
		(start 309.786274 -103.861108)
		(end 311.961784 -93.7768)
		(width 0.1143)
		(layer "In9.Cu")
		(net "UPI_CPU0_CPU1_P0P0_DP<4>")
	)
	(segment
		(start 308.98592 -71.820024)
		(end 308.98592 -71.747888)
		(width 0.0889)
		(layer "In9.Cu")
		(net "UPI_CPU0_CPU1_P0P0_DP<4>")
	)
	(segment
		(start 309.786528 -103.861108)
		(end 309.786274 -103.861108)
		(width 0.1143)
		(layer "In9.Cu")
		(net "UPI_CPU0_CPU1_P0P0_DP<4>")
	)
	(segment
		(start 310.28386 -76.214732)
		(end 310.42356 -76.067666)
		(width 0.1143)
		(layer "In9.Cu")
		(net "UPI_CPU0_CPU1_P0P0_DP<4>")
	)
	(segment
		(start 305.26482 -69.868288)
		(end 305.07432 -69.868288)
		(width 0.0889)
		(layer "In9.Cu")
		(net "UPI_CPU0_CPU1_P0P0_DP<4>")
	)
	(segment
		(start 306.626006 -70.201282)
		(end 306.625244 -70.20179)
		(width 0.0889)
		(layer "In9.Cu")
		(net "UPI_CPU0_CPU1_P0P0_DP<4>")
	)
	(segment
		(start 147.39239 -63.09995)
		(end 148.75383 -63.862712)
		(width 0.1143)
		(layer "In9.Cu")
		(net "UPI_CPU0_CPU1_P0P0_DP<4>")
	)
	(segment
		(start 291.546788 -105.320084)
		(end 292.439344 -105.239058)
		(width 0.1143)
		(layer "In9.Cu")
		(net "UPI_CPU0_CPU1_P0P0_DP<4>")
	)
	(segment
		(start 164.75329 -95.738696)
		(end 171.770548 -103.053388)
		(width 0.1143)
		(layer "In9.Cu")
		(net "UPI_CPU0_CPU1_P0P0_DP<4>")
	)
	(segment
		(start 310.486044 -78.298802)
		(end 310.47944 -78.069948)
		(width 0.1143)
		(layer "In9.Cu")
		(net "UPI_CPU0_CPU1_P0P0_DP<4>")
	)
	(segment
		(start 140.224764 -62.743588)
		(end 140.25753 -62.743588)
		(width 0.0889)
		(layer "In9.Cu")
		(net "UPI_CPU0_CPU1_P0P0_DP<4>")
	)
	(segment
		(start 290.660074 -105.400348)
		(end 291.125402 -105.358184)
		(width 0.1143)
		(layer "In9.Cu")
		(net "UPI_CPU0_CPU1_P0P0_DP<4>")
	)
	(segment
		(start 173.768258 -103.45039)
		(end 175.766476 -103.847392)
		(width 0.1143)
		(layer "In9.Cu")
		(net "UPI_CPU0_CPU1_P0P0_DP<4>")
	)
	(segment
		(start 227.975668 -108.436664)
		(end 233.653838 -109.403134)
		(width 0.1143)
		(layer "In9.Cu")
		(net "UPI_CPU0_CPU1_P0P0_DP<4>")
	)
	(segment
		(start 310.465216 -77.55509)
		(end 310.458612 -77.326236)
		(width 0.1143)
		(layer "In9.Cu")
		(net "UPI_CPU0_CPU1_P0P0_DP<4>")
	)
	(segment
		(start 310.269636 -75.700128)
		(end 310.263032 -75.47102)
		(width 0.1143)
		(layer "In9.Cu")
		(net "UPI_CPU0_CPU1_P0P0_DP<4>")
	)
	(segment
		(start 312.232294 -92.522294)
		(end 312.897012 -89.440512)
		(width 0.1143)
		(layer "In9.Cu")
		(net "UPI_CPU0_CPU1_P0P0_DP<4>")
	)
	(segment
		(start 309.001668 -71.835518)
		(end 309.001414 -71.835518)
		(width 0.1143)
		(layer "In9.Cu")
		(net "UPI_CPU0_CPU1_P0P0_DP<4>")
	)
	(segment
		(start 310.506872 -79.042514)
		(end 310.500268 -78.81366)
		(width 0.1143)
		(layer "In9.Cu")
		(net "UPI_CPU0_CPU1_P0P0_DP<4>")
	)
	(segment
		(start 278.09952 -108.781088)
		(end 281.554174 -109.181646)
		(width 0.1143)
		(layer "In9.Cu")
		(net "UPI_CPU0_CPU1_P0P0_DP<4>")
	)
	(segment
		(start 309.001414 -71.835518)
		(end 308.98592 -71.820024)
		(width 0.0889)
		(layer "In9.Cu")
		(net "UPI_CPU0_CPU1_P0P0_DP<4>")
	)
	(segment
		(start 310.290464 -76.44384)
		(end 310.28386 -76.214732)
		(width 0.1143)
		(layer "In9.Cu")
		(net "UPI_CPU0_CPU1_P0P0_DP<4>")
	)
	(segment
		(start 164.436806 -93.690694)
		(end 164.75329 -95.738696)
		(width 0.1143)
		(layer "In9.Cu")
		(net "UPI_CPU0_CPU1_P0P0_DP<4>")
	)
	(segment
		(start 175.766476 -103.847392)
		(end 179.608988 -107.161584)
		(width 0.1143)
		(layer "In9.Cu")
		(net "UPI_CPU0_CPU1_P0P0_DP<4>")
	)
	(segment
		(start 281.554174 -109.181646)
		(end 290.660074 -105.400348)
		(width 0.1143)
		(layer "In9.Cu")
		(net "UPI_CPU0_CPU1_P0P0_DP<4>")
	)
	(segment
		(start 183.151018 -107.70108)
		(end 189.587378 -107.70108)
		(width 0.1143)
		(layer "In9.Cu")
		(net "UPI_CPU0_CPU1_P0P0_DP<4>")
	)
	(segment
		(start 292.439344 -105.239058)
		(end 302.895508 -107.909106)
		(width 0.1143)
		(layer "In9.Cu")
		(net "UPI_CPU0_CPU1_P0P0_DP<4>")
	)
	(segment
		(start 148.795232 -63.9064)
		(end 153.179272 -68.52793)
		(width 0.1143)
		(layer "In9.Cu")
		(net "UPI_CPU0_CPU1_P0P0_DP<4>")
	)
	(segment
		(start 139.370054 -63.238634)
		(end 139.40282 -63.238634)
		(width 0.0889)
		(layer "In9.Cu")
		(net "UPI_CPU0_CPU1_P0P0_DP<4>")
	)
	(segment
		(start 308.557676 -71.449692)
		(end 308.431946 -71.323962)
		(width 0.0889)
		(layer "In9.Cu")
		(net "UPI_CPU0_CPU1_P0P0_DP<4>")
	)
	(segment
		(start 143.060928 -62.248034)
		(end 143.963644 -63.15075)
		(width 0.0889)
		(layer "In9.Cu")
		(net "UPI_CPU0_CPU1_P0P0_DP<4>")
	)
	(segment
		(start 308.431946 -71.323962)
		(end 308.431946 -71.193914)
		(width 0.0889)
		(layer "In9.Cu")
		(net "UPI_CPU0_CPU1_P0P0_DP<4>")
	)
	(segment
		(start 196.472556 -111.91621)
		(end 197.411086 -112.127538)
		(width 0.1143)
		(layer "In9.Cu")
		(net "UPI_CPU0_CPU1_P0P0_DP<4>")
	)
	(segment
		(start 144.620742 -63.15075)
		(end 144.671542 -63.09995)
		(width 0.0889)
		(layer "In9.Cu")
		(net "UPI_CPU0_CPU1_P0P0_DP<4>")
	)
	(segment
		(start 305.125628 -70.268084)
		(end 305.246786 -70.268084)
		(width 0.0889)
		(layer "In9.Cu")
		(net "UPI_CPU0_CPU1_P0P0_DP<4>")
	)
	(segment
		(start 310.33212 -77.931264)
		(end 310.325516 -77.702156)
		(width 0.1143)
		(layer "In9.Cu")
		(net "UPI_CPU0_CPU1_P0P0_DP<4>")
	)
	(segment
		(start 267.091414 -109.838236)
		(end 278.09952 -108.781088)
		(width 0.1143)
		(layer "In9.Cu")
		(net "UPI_CPU0_CPU1_P0P0_DP<4>")
	)
	(segment
		(start 138.529314 -63.672212)
		(end 138.587226 -63.730124)
		(width 0.0889)
		(layer "In9.Cu")
		(net "UPI_CPU0_CPU1_P0P0_DP<4>")
	)
	(segment
		(start 310.263032 -75.47102)
		(end 310.402986 -75.3237)
		(width 0.1143)
		(layer "In9.Cu")
		(net "UPI_CPU0_CPU1_P0P0_DP<4>")
	)
	(segment
		(start 248.033794 -106.543602)
		(end 263.03605 -109.638846)
		(width 0.1143)
		(layer "In9.Cu")
		(net "UPI_CPU0_CPU1_P0P0_DP<4>")
	)
	(segment
		(start 233.653838 -109.403134)
		(end 248.033794 -106.543602)
		(width 0.1143)
		(layer "In9.Cu")
		(net "UPI_CPU0_CPU1_P0P0_DP<4>")
	)
	(segment
		(start 153.179272 -68.52793)
		(end 157.907228 -85.963506)
		(width 0.1143)
		(layer "In9.Cu")
		(net "UPI_CPU0_CPU1_P0P0_DP<4>")
	)
	(segment
		(start 306.227226 -107.150662)
		(end 306.786026 -106.634026)
		(width 0.1143)
		(layer "In9.Cu")
		(net "UPI_CPU0_CPU1_P0P0_DP<4>")
	)
	(segment
		(start 310.352948 -78.674976)
		(end 310.346344 -78.445868)
		(width 0.1143)
		(layer "In9.Cu")
		(net "UPI_CPU0_CPU1_P0P0_DP<4>")
	)
	(segment
		(start 304.56124 -107.529884)
		(end 304.56124 -107.530138)
		(width 0.1143)
		(layer "In9.Cu")
		(net "UPI_CPU0_CPU1_P0P0_DP<4>")
	)
	(segment
		(start 179.608988 -107.161584)
		(end 183.151018 -107.70108)
		(width 0.1143)
		(layer "In9.Cu")
		(net "UPI_CPU0_CPU1_P0P0_DP<4>")
	)
	(segment
		(start 307.428392 -70.19036)
		(end 306.641754 -70.19036)
		(width 0.0889)
		(layer "In9.Cu")
		(net "UPI_CPU0_CPU1_P0P0_DP<4>")
	)
	(segment
		(start 189.587378 -107.70108)
		(end 191.701166 -108.060236)
		(width 0.1143)
		(layer "In9.Cu")
		(net "UPI_CPU0_CPU1_P0P0_DP<4>")
	)
	(segment
		(start 141.087094 -62.248034)
		(end 143.060928 -62.248034)
		(width 0.0889)
		(layer "In9.Cu")
		(net "UPI_CPU0_CPU1_P0P0_DP<4>")
	)
	(segment
		(start 310.42356 -76.067666)
		(end 310.416956 -75.838812)
		(width 0.1143)
		(layer "In9.Cu")
		(net "UPI_CPU0_CPU1_P0P0_DP<4>")
	)
	(segment
		(start 312.897012 -89.440512)
		(end 313.34837 -87.348568)
		(width 0.1143)
		(layer "In9.Cu")
		(net "UPI_CPU0_CPU1_P0P0_DP<4>")
	)
	(segment
		(start 306.786026 -106.634026)
		(end 309.786528 -103.861108)
		(width 0.1143)
		(layer "In9.Cu")
		(net "UPI_CPU0_CPU1_P0P0_DP<4>")
	)
	(segment
		(start 197.411086 -112.127538)
		(end 227.975668 -108.436664)
		(width 0.1143)
		(layer "In9.Cu")
		(net "UPI_CPU0_CPU1_P0P0_DP<4>")
	)
	(segment
		(start 265.063478 -109.738414)
		(end 267.091414 -109.838236)
		(width 0.1143)
		(layer "In9.Cu")
		(net "UPI_CPU0_CPU1_P0P0_DP<4>")
	)
	(segment
		(start 265.063478 -109.73816)
		(end 265.063478 -109.738414)
		(width 0.1143)
		(layer "In9.Cu")
		(net "UPI_CPU0_CPU1_P0P0_DP<4>")
	)
	(segment
		(start 157.907228 -85.963506)
		(end 164.436806 -93.690694)
		(width 0.1143)
		(layer "In9.Cu")
		(net "UPI_CPU0_CPU1_P0P0_DP<4>")
	)
	(segment
		(start 310.458612 -77.326236)
		(end 310.311292 -77.187552)
		(width 0.1143)
		(layer "In9.Cu")
		(net "UPI_CPU0_CPU1_P0P0_DP<4>")
	)
	(segment
		(start 310.528716 -79.8322)
		(end 310.520842 -79.557372)
		(width 0.1143)
		(layer "In9.Cu")
		(net "UPI_CPU0_CPU1_P0P0_DP<4>")
	)
	(segment
		(start 310.325516 -77.702156)
		(end 310.465216 -77.55509)
		(width 0.1143)
		(layer "In9.Cu")
		(net "UPI_CPU0_CPU1_P0P0_DP<4>")
	)
	(segment
		(start 310.311292 -77.187552)
		(end 310.304688 -76.958444)
		(width 0.1143)
		(layer "In9.Cu")
		(net "UPI_CPU0_CPU1_P0P0_DP<4>")
	)
	(segment
		(start 171.770548 -103.053388)
		(end 173.768258 -103.449882)
		(width 0.1143)
		(layer "In9.Cu")
		(net "UPI_CPU0_CPU1_P0P0_DP<4>")
	)
	(segment
		(start 148.75383 -63.862712)
		(end 148.795232 -63.9064)
		(width 0.1143)
		(layer "In9.Cu")
		(net "UPI_CPU0_CPU1_P0P0_DP<4>")
	)
	(segment
		(start 310.346344 -78.445868)
		(end 310.486044 -78.298802)
		(width 0.1143)
		(layer "In9.Cu")
		(net "UPI_CPU0_CPU1_P0P0_DP<4>")
	)
	(segment
		(start 291.125402 -105.358184)
		(end 291.546788 -105.320084)
		(width 0.1143)
		(layer "In9.Cu")
		(net "UPI_CPU0_CPU1_P0P0_DP<4>")
	)
	(segment
		(start 310.304688 -76.958444)
		(end 310.444388 -76.811378)
		(width 0.1143)
		(layer "In9.Cu")
		(net "UPI_CPU0_CPU1_P0P0_DP<4>")
	)
	(segment
		(start 263.03605 -109.638846)
		(end 265.063478 -109.73816)
		(width 0.1143)
		(layer "In9.Cu")
		(net "UPI_CPU0_CPU1_P0P0_DP<4>")
	)
	(segment
		(start 308.431946 -71.193914)
		(end 307.428392 -70.19036)
		(width 0.0889)
		(layer "In9.Cu")
		(net "UPI_CPU0_CPU1_P0P0_DP<4>")
	)
	(segment
		(start 144.69364 -63.09995)
		(end 147.39239 -63.09995)
		(width 0.1143)
		(layer "In9.Cu")
		(net "UPI_CPU0_CPU1_P0P0_DP<4>")
	)
	(segment
		(start 304.56124 -107.530138)
		(end 306.227226 -107.150662)
		(width 0.1143)
		(layer "In9.Cu")
		(net "UPI_CPU0_CPU1_P0P0_DP<4>")
	)
	(segment
		(start 310.437784 -76.582524)
		(end 310.290464 -76.44384)
		(width 0.1143)
		(layer "In9.Cu")
		(net "UPI_CPU0_CPU1_P0P0_DP<4>")
	)
	(segment
		(start 138.529314 -63.334138)
		(end 138.529314 -63.672212)
		(width 0.0889)
		(layer "In9.Cu")
		(net "UPI_CPU0_CPU1_P0P0_DP<4>")
	)
	(segment
		(start 310.393588 -74.939652)
		(end 309.213504 -72.047354)
		(width 0.1143)
		(layer "In9.Cu")
		(net "UPI_CPU0_CPU1_P0P0_DP<4>")
	)
	(segment
		(start 310.47944 -78.069948)
		(end 310.33212 -77.931264)
		(width 0.1143)
		(layer "In9.Cu")
		(net "UPI_CPU0_CPU1_P0P0_DP<4>")
	)
	(arc
		(start 305.07432 -69.868288)
		(mid 304.951111 -69.919323)
		(end 304.900076 -70.042532)
		(width 0.0889)
		(layer "In9.Cu")
		(net "UPI_CPU0_CPU1_P0P0_DP<4>")
	)
	(arc
		(start 304.900076 -70.042532)
		(mid 304.966139 -70.202021)
		(end 305.125628 -70.268084)
		(width 0.0889)
		(layer "In9.Cu")
		(net "UPI_CPU0_CPU1_P0P0_DP<4>")
	)
	(arc
		(start 139.40282 -63.238634)
		(mid 139.594462 -63.181468)
		(end 139.734544 -63.038736)
		(width 0.0889)
		(layer "In9.Cu")
		(net "UPI_CPU0_CPU1_P0P0_DP<4>")
	)
	(arc
		(start 306.083716 -70.363334)
		(mid 305.800499 -70.279053)
		(end 305.593496 -70.068186)
		(width 0.0889)
		(layer "In9.Cu")
		(net "UPI_CPU0_CPU1_P0P0_DP<4>")
	)
	(arc
		(start 306.625244 -70.20179)
		(mid 306.377535 -70.322024)
		(end 306.105306 -70.363334)
		(width 0.0889)
		(layer "In9.Cu")
		(net "UPI_CPU0_CPU1_P0P0_DP<4>")
	)
	(arc
		(start 140.593064 -62.543436)
		(mid 140.801672 -62.331504)
		(end 141.087094 -62.248034)
		(width 0.0889)
		(layer "In9.Cu")
		(net "UPI_CPU0_CPU1_P0P0_DP<4>")
	)
	(arc
		(start 138.587226 -63.730124)
		(mid 138.754127 -63.665224)
		(end 138.876024 -63.534036)
		(width 0.0889)
		(layer "In9.Cu")
		(net "UPI_CPU0_CPU1_P0P0_DP<4>")
	)
	(arc
		(start 140.25753 -62.743588)
		(mid 140.45138 -62.687238)
		(end 140.593064 -62.543436)
		(width 0.0889)
		(layer "In9.Cu")
		(net "UPI_CPU0_CPU1_P0P0_DP<4>")
	)
	(arc
		(start 139.734544 -63.038736)
		(mid 139.941548 -62.827872)
		(end 140.224764 -62.743588)
		(width 0.0889)
		(layer "In9.Cu")
		(net "UPI_CPU0_CPU1_P0P0_DP<4>")
	)
	(arc
		(start 138.876024 -63.534036)
		(mid 139.084632 -63.322104)
		(end 139.370054 -63.238634)
		(width 0.0889)
		(layer "In9.Cu")
		(net "UPI_CPU0_CPU1_P0P0_DP<4>")
	)
	(arc
		(start 305.593496 -70.068186)
		(mid 305.454752 -69.926153)
		(end 305.26482 -69.868288)
		(width 0.0889)
		(layer "In9.Cu")
		(net "UPI_CPU0_CPU1_P0P0_DP<4>")
	)
	(segment
		(start 305.533806 -70.763384)
		(end 306.105306 -70.763384)
		(width 0.1143)
		(layer "F.Cu")
		(net "UPI_CPU0_CPU1_P0P0_DP<3>")
	)
	(segment
		(start 138.816334 -62.838584)
		(end 139.387834 -62.838584)
		(width 0.1143)
		(layer "F.Cu")
		(net "UPI_CPU0_CPU1_P0P0_DP<3>")
	)
	(via
		(at 306.105306 -70.763384)
		(size 0.508)
		(drill 0.254)
		(layers "F.Cu" "B.Cu")
		(net "UPI_CPU0_CPU1_P0P0_DP<3>")
	)
	(via
		(at 139.387834 -62.838584)
		(size 0.508)
		(drill 0.254)
		(layers "F.Cu" "B.Cu")
		(net "UPI_CPU0_CPU1_P0P0_DP<3>")
	)
	(segment
		(start 292.467284 -104.890062)
		(end 302.899318 -107.554268)
		(width 0.1143)
		(layer "In9.Cu")
		(net "UPI_CPU0_CPU1_P0P0_DP<3>")
	)
	(segment
		(start 145.40611 -61.765942)
		(end 145.40611 -61.833252)
		(width 0.0889)
		(layer "In9.Cu")
		(net "UPI_CPU0_CPU1_P0P0_DP<3>")
	)
	(segment
		(start 307.120036 -70.573646)
		(end 306.808378 -70.582028)
		(width 0.0889)
		(layer "In9.Cu")
		(net "UPI_CPU0_CPU1_P0P0_DP<3>")
	)
	(segment
		(start 263.083802 -109.295438)
		(end 267.083286 -109.49178)
		(width 0.1143)
		(layer "In9.Cu")
		(net "UPI_CPU0_CPU1_P0P0_DP<3>")
	)
	(segment
		(start 182.888128 -106.567478)
		(end 191.778128 -107.65028)
		(width 0.1143)
		(layer "In9.Cu")
		(net "UPI_CPU0_CPU1_P0P0_DP<3>")
	)
	(segment
		(start 305.791108 -71.011288)
		(end 305.81219 -70.932548)
		(width 0.0889)
		(layer "In9.Cu")
		(net "UPI_CPU0_CPU1_P0P0_DP<3>")
	)
	(segment
		(start 179.522628 -104.80421)
		(end 180.822092 -105.163112)
		(width 0.1143)
		(layer "In9.Cu")
		(net "UPI_CPU0_CPU1_P0P0_DP<3>")
	)
	(segment
		(start 146.95805 -62.534292)
		(end 147.13585 -62.534292)
		(width 0.0889)
		(layer "In9.Cu")
		(net "UPI_CPU0_CPU1_P0P0_DP<3>")
	)
	(segment
		(start 148.439886 -62.909704)
		(end 148.439632 -62.981332)
		(width 0.0889)
		(layer "In9.Cu")
		(net "UPI_CPU0_CPU1_P0P0_DP<3>")
	)
	(segment
		(start 140.758164 -61.648086)
		(end 140.878306 -61.44006)
		(width 0.0889)
		(layer "In9.Cu")
		(net "UPI_CPU0_CPU1_P0P0_DP<3>")
	)
	(segment
		(start 145.40611 -61.833252)
		(end 145.532094 -61.959236)
		(width 0.0889)
		(layer "In9.Cu")
		(net "UPI_CPU0_CPU1_P0P0_DP<3>")
	)
	(segment
		(start 146.583146 -62.534292)
		(end 146.681698 -62.43574)
		(width 0.0889)
		(layer "In9.Cu")
		(net "UPI_CPU0_CPU1_P0P0_DP<3>")
	)
	(segment
		(start 281.50566 -108.828078)
		(end 290.57854 -105.061258)
		(width 0.1143)
		(layer "In9.Cu")
		(net "UPI_CPU0_CPU1_P0P0_DP<3>")
	)
	(segment
		(start 309.848758 -74.938382)
		(end 309.073042 -73.291954)
		(width 0.1143)
		(layer "In9.Cu")
		(net "UPI_CPU0_CPU1_P0P0_DP<3>")
	)
	(segment
		(start 158.220664 -85.799422)
		(end 164.76345 -93.542358)
		(width 0.1143)
		(layer "In9.Cu")
		(net "UPI_CPU0_CPU1_P0P0_DP<3>")
	)
	(segment
		(start 145.056098 -61.41466)
		(end 145.40611 -61.765942)
		(width 0.0889)
		(layer "In9.Cu")
		(net "UPI_CPU0_CPU1_P0P0_DP<3>")
	)
	(segment
		(start 141.846046 -60.94857)
		(end 142.150338 -60.94857)
		(width 0.0889)
		(layer "In9.Cu")
		(net "UPI_CPU0_CPU1_P0P0_DP<3>")
	)
	(segment
		(start 191.778128 -107.65028)
		(end 196.44995 -111.427006)
		(width 0.1143)
		(layer "In9.Cu")
		(net "UPI_CPU0_CPU1_P0P0_DP<3>")
	)
	(segment
		(start 305.81219 -70.932548)
		(end 306.105306 -70.763384)
		(width 0.0889)
		(layer "In9.Cu")
		(net "UPI_CPU0_CPU1_P0P0_DP<3>")
	)
	(segment
		(start 146.405346 -62.534292)
		(end 146.583146 -62.534292)
		(width 0.0889)
		(layer "In9.Cu")
		(net "UPI_CPU0_CPU1_P0P0_DP<3>")
	)
	(segment
		(start 309.073042 -73.291954)
		(end 308.995826 -73.247504)
		(width 0.0889)
		(layer "In9.Cu")
		(net "UPI_CPU0_CPU1_P0P0_DP<3>")
	)
	(segment
		(start 197.71868 -111.727996)
		(end 227.984304 -108.087668)
		(width 0.1143)
		(layer "In9.Cu")
		(net "UPI_CPU0_CPU1_P0P0_DP<3>")
	)
	(segment
		(start 142.616428 -61.41466)
		(end 145.056098 -61.41466)
		(width 0.0889)
		(layer "In9.Cu")
		(net "UPI_CPU0_CPU1_P0P0_DP<3>")
	)
	(segment
		(start 165.065456 -95.496126)
		(end 172.017436 -102.75062)
		(width 0.1143)
		(layer "In9.Cu")
		(net "UPI_CPU0_CPU1_P0P0_DP<3>")
	)
	(segment
		(start 278.102568 -108.433616)
		(end 281.50566 -108.828078)
		(width 0.1143)
		(layer "In9.Cu")
		(net "UPI_CPU0_CPU1_P0P0_DP<3>")
	)
	(segment
		(start 145.785586 -62.212728)
		(end 145.91157 -62.338712)
		(width 0.0889)
		(layer "In9.Cu")
		(net "UPI_CPU0_CPU1_P0P0_DP<3>")
	)
	(segment
		(start 140.231368 -61.943488)
		(end 140.264134 -61.943488)
		(width 0.0889)
		(layer "In9.Cu")
		(net "UPI_CPU0_CPU1_P0P0_DP<3>")
	)
	(segment
		(start 177.528982 -104.700578)
		(end 179.522628 -104.80421)
		(width 0.1143)
		(layer "In9.Cu")
		(net "UPI_CPU0_CPU1_P0P0_DP<3>")
	)
	(segment
		(start 310.028336 -79.797402)
		(end 309.848758 -74.938382)
		(width 0.1143)
		(layer "In9.Cu")
		(net "UPI_CPU0_CPU1_P0P0_DP<3>")
	)
	(segment
		(start 140.878306 -61.44006)
		(end 141.032738 -61.285374)
		(width 0.0889)
		(layer "In9.Cu")
		(net "UPI_CPU0_CPU1_P0P0_DP<3>")
	)
	(segment
		(start 306.273454 -71.163434)
		(end 306.09032 -71.163434)
		(width 0.0889)
		(layer "In9.Cu")
		(net "UPI_CPU0_CPU1_P0P0_DP<3>")
	)
	(segment
		(start 145.532094 -61.959236)
		(end 145.659602 -61.959236)
		(width 0.0889)
		(layer "In9.Cu")
		(net "UPI_CPU0_CPU1_P0P0_DP<3>")
	)
	(segment
		(start 148.455126 -62.996826)
		(end 149.798532 -64.340232)
		(width 0.1143)
		(layer "In9.Cu")
		(net "UPI_CPU0_CPU1_P0P0_DP<3>")
	)
	(segment
		(start 164.76345 -93.542358)
		(end 165.065456 -95.496126)
		(width 0.1143)
		(layer "In9.Cu")
		(net "UPI_CPU0_CPU1_P0P0_DP<3>")
	)
	(segment
		(start 145.785586 -62.08522)
		(end 145.785586 -62.212728)
		(width 0.0889)
		(layer "In9.Cu")
		(net "UPI_CPU0_CPU1_P0P0_DP<3>")
	)
	(segment
		(start 180.822092 -105.163112)
		(end 182.888128 -106.567478)
		(width 0.1143)
		(layer "In9.Cu")
		(net "UPI_CPU0_CPU1_P0P0_DP<3>")
	)
	(segment
		(start 309.471822 -103.681784)
		(end 312.960512 -87.510112)
		(width 0.1143)
		(layer "In9.Cu")
		(net "UPI_CPU0_CPU1_P0P0_DP<3>")
	)
	(segment
		(start 312.960512 -87.510112)
		(end 310.028336 -79.797402)
		(width 0.1143)
		(layer "In9.Cu")
		(net "UPI_CPU0_CPU1_P0P0_DP<3>")
	)
	(segment
		(start 139.094718 -62.669674)
		(end 139.073636 -62.590934)
		(width 0.0889)
		(layer "In9.Cu")
		(net "UPI_CPU0_CPU1_P0P0_DP<3>")
	)
	(segment
		(start 290.57854 -105.061258)
		(end 292.467284 -104.890062)
		(width 0.1143)
		(layer "In9.Cu")
		(net "UPI_CPU0_CPU1_P0P0_DP<3>")
	)
	(segment
		(start 307.457348 -70.719696)
		(end 307.120036 -70.573646)
		(width 0.0889)
		(layer "In9.Cu")
		(net "UPI_CPU0_CPU1_P0P0_DP<3>")
	)
	(segment
		(start 196.44995 -111.427006)
		(end 197.71868 -111.727996)
		(width 0.1143)
		(layer "In9.Cu")
		(net "UPI_CPU0_CPU1_P0P0_DP<3>")
	)
	(segment
		(start 146.039078 -62.338712)
		(end 146.136106 -62.43574)
		(width 0.0889)
		(layer "In9.Cu")
		(net "UPI_CPU0_CPU1_P0P0_DP<3>")
	)
	(segment
		(start 147.412202 -62.43574)
		(end 147.510754 -62.534292)
		(width 0.0889)
		(layer "In9.Cu")
		(net "UPI_CPU0_CPU1_P0P0_DP<3>")
	)
	(segment
		(start 248.035318 -106.19105)
		(end 263.083802 -109.295438)
		(width 0.1143)
		(layer "In9.Cu")
		(net "UPI_CPU0_CPU1_P0P0_DP<3>")
	)
	(segment
		(start 142.150338 -60.94857)
		(end 142.616428 -61.41466)
		(width 0.0889)
		(layer "In9.Cu")
		(net "UPI_CPU0_CPU1_P0P0_DP<3>")
	)
	(segment
		(start 147.787106 -62.43574)
		(end 147.965922 -62.43574)
		(width 0.0889)
		(layer "In9.Cu")
		(net "UPI_CPU0_CPU1_P0P0_DP<3>")
	)
	(segment
		(start 302.899318 -107.554268)
		(end 306.05984 -106.83494)
		(width 0.1143)
		(layer "In9.Cu")
		(net "UPI_CPU0_CPU1_P0P0_DP<3>")
	)
	(segment
		(start 267.083286 -109.49178)
		(end 278.102568 -108.433616)
		(width 0.1143)
		(layer "In9.Cu")
		(net "UPI_CPU0_CPU1_P0P0_DP<3>")
	)
	(segment
		(start 147.688554 -62.534292)
		(end 147.787106 -62.43574)
		(width 0.0889)
		(layer "In9.Cu")
		(net "UPI_CPU0_CPU1_P0P0_DP<3>")
	)
	(segment
		(start 141.032738 -61.285374)
		(end 141.846046 -60.94857)
		(width 0.0889)
		(layer "In9.Cu")
		(net "UPI_CPU0_CPU1_P0P0_DP<3>")
	)
	(segment
		(start 148.439632 -62.981332)
		(end 148.455126 -62.996826)
		(width 0.0889)
		(layer "In9.Cu")
		(net "UPI_CPU0_CPU1_P0P0_DP<3>")
	)
	(segment
		(start 176.17694 -103.576628)
		(end 177.528982 -104.700578)
		(width 0.1143)
		(layer "In9.Cu")
		(net "UPI_CPU0_CPU1_P0P0_DP<3>")
	)
	(segment
		(start 306.597558 -70.761352)
		(end 306.488592 -70.966584)
		(width 0.0889)
		(layer "In9.Cu")
		(net "UPI_CPU0_CPU1_P0P0_DP<3>")
	)
	(segment
		(start 172.017436 -102.75062)
		(end 176.177194 -103.576628)
		(width 0.1143)
		(layer "In9.Cu")
		(net "UPI_CPU0_CPU1_P0P0_DP<3>")
	)
	(segment
		(start 227.984304 -108.087668)
		(end 233.650028 -109.051852)
		(width 0.1143)
		(layer "In9.Cu")
		(net "UPI_CPU0_CPU1_P0P0_DP<3>")
	)
	(segment
		(start 233.650028 -109.051852)
		(end 248.035318 -106.19105)
		(width 0.1143)
		(layer "In9.Cu")
		(net "UPI_CPU0_CPU1_P0P0_DP<3>")
	)
	(segment
		(start 153.464514 -68.25742)
		(end 158.220664 -85.799422)
		(width 0.1143)
		(layer "In9.Cu")
		(net "UPI_CPU0_CPU1_P0P0_DP<3>")
	)
	(segment
		(start 146.306794 -62.43574)
		(end 146.405346 -62.534292)
		(width 0.0889)
		(layer "In9.Cu")
		(net "UPI_CPU0_CPU1_P0P0_DP<3>")
	)
	(segment
		(start 306.808378 -70.582028)
		(end 306.597558 -70.761352)
		(width 0.0889)
		(layer "In9.Cu")
		(net "UPI_CPU0_CPU1_P0P0_DP<3>")
	)
	(segment
		(start 147.965922 -62.43574)
		(end 148.439886 -62.909704)
		(width 0.0889)
		(layer "In9.Cu")
		(net "UPI_CPU0_CPU1_P0P0_DP<3>")
	)
	(segment
		(start 147.234402 -62.43574)
		(end 147.412202 -62.43574)
		(width 0.0889)
		(layer "In9.Cu")
		(net "UPI_CPU0_CPU1_P0P0_DP<3>")
	)
	(segment
		(start 146.859498 -62.43574)
		(end 146.95805 -62.534292)
		(width 0.0889)
		(layer "In9.Cu")
		(net "UPI_CPU0_CPU1_P0P0_DP<3>")
	)
	(segment
		(start 308.42077 -72.021192)
		(end 307.457348 -70.719696)
		(width 0.0889)
		(layer "In9.Cu")
		(net "UPI_CPU0_CPU1_P0P0_DP<3>")
	)
	(segment
		(start 139.387834 -62.838584)
		(end 139.094718 -62.669674)
		(width 0.0889)
		(layer "In9.Cu")
		(net "UPI_CPU0_CPU1_P0P0_DP<3>")
	)
	(segment
		(start 308.995826 -73.247504)
		(end 308.42077 -72.021192)
		(width 0.0889)
		(layer "In9.Cu")
		(net "UPI_CPU0_CPU1_P0P0_DP<3>")
	)
	(segment
		(start 146.136106 -62.43574)
		(end 146.306794 -62.43574)
		(width 0.0889)
		(layer "In9.Cu")
		(net "UPI_CPU0_CPU1_P0P0_DP<3>")
	)
	(segment
		(start 146.681698 -62.43574)
		(end 146.859498 -62.43574)
		(width 0.0889)
		(layer "In9.Cu")
		(net "UPI_CPU0_CPU1_P0P0_DP<3>")
	)
	(segment
		(start 147.13585 -62.534292)
		(end 147.234402 -62.43574)
		(width 0.0889)
		(layer "In9.Cu")
		(net "UPI_CPU0_CPU1_P0P0_DP<3>")
	)
	(segment
		(start 147.510754 -62.534292)
		(end 147.688554 -62.534292)
		(width 0.0889)
		(layer "In9.Cu")
		(net "UPI_CPU0_CPU1_P0P0_DP<3>")
	)
	(segment
		(start 149.798532 -64.340232)
		(end 153.464514 -68.25742)
		(width 0.1143)
		(layer "In9.Cu")
		(net "UPI_CPU0_CPU1_P0P0_DP<3>")
	)
	(segment
		(start 145.659602 -61.959236)
		(end 145.785586 -62.08522)
		(width 0.0889)
		(layer "In9.Cu")
		(net "UPI_CPU0_CPU1_P0P0_DP<3>")
	)
	(segment
		(start 145.91157 -62.338712)
		(end 146.039078 -62.338712)
		(width 0.0889)
		(layer "In9.Cu")
		(net "UPI_CPU0_CPU1_P0P0_DP<3>")
	)
	(segment
		(start 306.488592 -70.966584)
		(end 306.488592 -70.966838)
		(width 0.0889)
		(layer "In9.Cu")
		(net "UPI_CPU0_CPU1_P0P0_DP<3>")
	)
	(segment
		(start 176.177194 -103.576628)
		(end 176.17694 -103.576628)
		(width 0.1143)
		(layer "In9.Cu")
		(net "UPI_CPU0_CPU1_P0P0_DP<3>")
	)
	(segment
		(start 139.376658 -62.438534)
		(end 139.409424 -62.438534)
		(width 0.0889)
		(layer "In9.Cu")
		(net "UPI_CPU0_CPU1_P0P0_DP<3>")
	)
	(segment
		(start 306.05984 -106.83494)
		(end 309.471822 -103.681784)
		(width 0.1143)
		(layer "In9.Cu")
		(net "UPI_CPU0_CPU1_P0P0_DP<3>")
	)
	(arc
		(start 306.09032 -71.163434)
		(mid 305.924026 -71.1202)
		(end 305.791108 -71.011288)
		(width 0.0889)
		(layer "In9.Cu")
		(net "UPI_CPU0_CPU1_P0P0_DP<3>")
	)
	(arc
		(start 139.409424 -62.438534)
		(mid 139.692641 -62.354253)
		(end 139.899644 -62.143386)
		(width 0.0889)
		(layer "In9.Cu")
		(net "UPI_CPU0_CPU1_P0P0_DP<3>")
	)
	(arc
		(start 306.488592 -70.966838)
		(mid 306.398017 -71.083731)
		(end 306.273454 -71.163434)
		(width 0.0889)
		(layer "In9.Cu")
		(net "UPI_CPU0_CPU1_P0P0_DP<3>")
	)
	(arc
		(start 139.073636 -62.590934)
		(mid 139.208198 -62.481022)
		(end 139.376658 -62.438534)
		(width 0.0889)
		(layer "In9.Cu")
		(net "UPI_CPU0_CPU1_P0P0_DP<3>")
	)
	(arc
		(start 140.264134 -61.943488)
		(mid 140.549558 -61.860021)
		(end 140.758164 -61.648086)
		(width 0.0889)
		(layer "In9.Cu")
		(net "UPI_CPU0_CPU1_P0P0_DP<3>")
	)
	(arc
		(start 139.899644 -62.143386)
		(mid 140.039723 -62.00065)
		(end 140.231368 -61.943488)
		(width 0.0889)
		(layer "In9.Cu")
		(net "UPI_CPU0_CPU1_P0P0_DP<3>")
	)
	(segment
		(start 137.957814 -61.352938)
		(end 138.529314 -61.352938)
		(width 0.1143)
		(layer "F.Cu")
		(net "UPI_CPU0_CPU1_P0P0_DP<2>")
	)
	(segment
		(start 306.392326 -72.249538)
		(end 307.040026 -72.249538)
		(width 0.1143)
		(layer "F.Cu")
		(net "UPI_CPU0_CPU1_P0P0_DP<2>")
	)
	(via
		(at 138.529314 -61.352938)
		(size 0.508)
		(drill 0.254)
		(layers "F.Cu" "B.Cu")
		(net "UPI_CPU0_CPU1_P0P0_DP<2>")
	)
	(via
		(at 307.040026 -72.249538)
		(size 0.508)
		(drill 0.254)
		(layers "F.Cu" "B.Cu")
		(net "UPI_CPU0_CPU1_P0P0_DP<2>")
	)
	(segment
		(start 233.635296 -108.10621)
		(end 248.03862 -105.242106)
		(width 0.1143)
		(layer "In9.Cu")
		(net "UPI_CPU0_CPU1_P0P0_DP<2>")
	)
	(segment
		(start 281.372564 -107.876594)
		(end 290.353242 -104.147874)
		(width 0.1143)
		(layer "In9.Cu")
		(net "UPI_CPU0_CPU1_P0P0_DP<2>")
	)
	(segment
		(start 308.00802 -73.1774)
		(end 307.939186 -73.013062)
		(width 0.0889)
		(layer "In9.Cu")
		(net "UPI_CPU0_CPU1_P0P0_DP<2>")
	)
	(segment
		(start 307.812948 -72.961246)
		(end 307.744114 -72.796908)
		(width 0.0889)
		(layer "In9.Cu")
		(net "UPI_CPU0_CPU1_P0P0_DP<2>")
	)
	(segment
		(start 308.532276 -77.075792)
		(end 308.384956 -76.964032)
		(width 0.1143)
		(layer "In9.Cu")
		(net "UPI_CPU0_CPU1_P0P0_DP<2>")
	)
	(segment
		(start 159.06496 -85.35797)
		(end 165.642036 -93.141546)
		(width 0.1143)
		(layer "In9.Cu")
		(net "UPI_CPU0_CPU1_P0P0_DP<2>")
	)
	(segment
		(start 307.28412 -71.849488)
		(end 306.879498 -71.849488)
		(width 0.0889)
		(layer "In9.Cu")
		(net "UPI_CPU0_CPU1_P0P0_DP<2>")
	)
	(segment
		(start 146.842734 -61.578744)
		(end 146.842734 -61.578998)
		(width 0.0889)
		(layer "In9.Cu")
		(net "UPI_CPU0_CPU1_P0P0_DP<2>")
	)
	(segment
		(start 308.167786 -73.80986)
		(end 308.219856 -73.683876)
		(width 0.0889)
		(layer "In9.Cu")
		(net "UPI_CPU0_CPU1_P0P0_DP<2>")
	)
	(segment
		(start 179.705254 -103.882698)
		(end 181.287166 -104.285034)
		(width 0.1143)
		(layer "In9.Cu")
		(net "UPI_CPU0_CPU1_P0P0_DP<2>")
	)
	(segment
		(start 228.008434 -107.14863)
		(end 233.635296 -108.10621)
		(width 0.1143)
		(layer "In9.Cu")
		(net "UPI_CPU0_CPU1_P0P0_DP<2>")
	)
	(segment
		(start 308.41823 -75.238102)
		(end 308.41823 -74.708766)
		(width 0.0889)
		(layer "In9.Cu")
		(net "UPI_CPU0_CPU1_P0P0_DP<2>")
	)
	(segment
		(start 308.362858 -74.026014)
		(end 308.23662 -73.974198)
		(width 0.0889)
		(layer "In9.Cu")
		(net "UPI_CPU0_CPU1_P0P0_DP<2>")
	)
	(segment
		(start 147.393914 -61.57595)
		(end 147.416012 -61.57595)
		(width 0.0889)
		(layer "In9.Cu")
		(net "UPI_CPU0_CPU1_P0P0_DP<2>")
	)
	(segment
		(start 292.542214 -103.9495)
		(end 302.912272 -106.597704)
		(width 0.1143)
		(layer "In9.Cu")
		(net "UPI_CPU0_CPU1_P0P0_DP<2>")
	)
	(segment
		(start 138.236198 -61.521848)
		(end 138.215116 -61.600588)
		(width 0.0889)
		(layer "In9.Cu")
		(net "UPI_CPU0_CPU1_P0P0_DP<2>")
	)
	(segment
		(start 145.282666 -60.550298)
		(end 146.359118 -61.62675)
		(width 0.0889)
		(layer "In9.Cu")
		(net "UPI_CPU0_CPU1_P0P0_DP<2>")
	)
	(segment
		(start 308.677564 -79.102204)
		(end 308.646322 -78.875382)
		(width 0.1143)
		(layer "In9.Cu")
		(net "UPI_CPU0_CPU1_P0P0_DP<2>")
	)
	(segment
		(start 308.876954 -79.594964)
		(end 308.82463 -79.213964)
		(width 0.1143)
		(layer "In9.Cu")
		(net "UPI_CPU0_CPU1_P0P0_DP<2>")
	)
	(segment
		(start 146.56943 -61.578744)
		(end 146.617182 -61.530992)
		(width 0.0889)
		(layer "In9.Cu")
		(net "UPI_CPU0_CPU1_P0P0_DP<2>")
	)
	(segment
		(start 147.416012 -61.57595)
		(end 148.519388 -61.57595)
		(width 0.1143)
		(layer "In9.Cu")
		(net "UPI_CPU0_CPU1_P0P0_DP<2>")
	)
	(segment
		(start 146.794982 -61.530992)
		(end 146.842734 -61.578744)
		(width 0.0889)
		(layer "In9.Cu")
		(net "UPI_CPU0_CPU1_P0P0_DP<2>")
	)
	(segment
		(start 307.939186 -73.013062)
		(end 307.812948 -72.961246)
		(width 0.0889)
		(layer "In9.Cu")
		(net "UPI_CPU0_CPU1_P0P0_DP<2>")
	)
	(segment
		(start 308.353714 -76.73721)
		(end 308.465982 -76.58989)
		(width 0.1143)
		(layer "In9.Cu")
		(net "UPI_CPU0_CPU1_P0P0_DP<2>")
	)
	(segment
		(start 308.31917 -74.431906)
		(end 308.41823 -74.332846)
		(width 0.0889)
		(layer "In9.Cu")
		(net "UPI_CPU0_CPU1_P0P0_DP<2>")
	)
	(segment
		(start 308.151022 -73.519538)
		(end 308.024784 -73.467722)
		(width 0.0889)
		(layer "In9.Cu")
		(net "UPI_CPU0_CPU1_P0P0_DP<2>")
	)
	(segment
		(start 154.205432 -67.435222)
		(end 159.06496 -85.35797)
		(width 0.1143)
		(layer "In9.Cu")
		(net "UPI_CPU0_CPU1_P0P0_DP<2>")
	)
	(segment
		(start 146.56943 -61.578998)
		(end 146.56943 -61.578744)
		(width 0.0889)
		(layer "In9.Cu")
		(net "UPI_CPU0_CPU1_P0P0_DP<2>")
	)
	(segment
		(start 307.575458 -72.140826)
		(end 307.28412 -71.849488)
		(width 0.0889)
		(layer "In9.Cu")
		(net "UPI_CPU0_CPU1_P0P0_DP<2>")
	)
	(segment
		(start 308.45125 -77.449934)
		(end 308.563518 -77.302614)
		(width 0.1143)
		(layer "In9.Cu")
		(net "UPI_CPU0_CPU1_P0P0_DP<2>")
	)
	(segment
		(start 308.31917 -74.609706)
		(end 308.31917 -74.431906)
		(width 0.0889)
		(layer "In9.Cu")
		(net "UPI_CPU0_CPU1_P0P0_DP<2>")
	)
	(segment
		(start 308.41823 -74.708766)
		(end 308.31917 -74.609706)
		(width 0.0889)
		(layer "In9.Cu")
		(net "UPI_CPU0_CPU1_P0P0_DP<2>")
	)
	(segment
		(start 308.624478 -103.198676)
		(end 311.965086 -87.717884)
		(width 0.1143)
		(layer "In9.Cu")
		(net "UPI_CPU0_CPU1_P0P0_DP<2>")
	)
	(segment
		(start 308.75859 -78.728062)
		(end 308.727348 -78.50124)
		(width 0.1143)
		(layer "In9.Cu")
		(net "UPI_CPU0_CPU1_P0P0_DP<2>")
	)
	(segment
		(start 165.92931 -94.999302)
		(end 172.550328 -101.908356)
		(width 0.1143)
		(layer "In9.Cu")
		(net "UPI_CPU0_CPU1_P0P0_DP<2>")
	)
	(segment
		(start 308.36743 -75.867768)
		(end 308.36743 -75.311)
		(width 0.1143)
		(layer "In9.Cu")
		(net "UPI_CPU0_CPU1_P0P0_DP<2>")
	)
	(segment
		(start 148.519388 -61.57595)
		(end 154.205432 -67.435222)
		(width 0.1143)
		(layer "In9.Cu")
		(net "UPI_CPU0_CPU1_P0P0_DP<2>")
	)
	(segment
		(start 138.518138 -61.752988)
		(end 138.54049 -61.752988)
		(width 0.0889)
		(layer "In9.Cu")
		(net "UPI_CPU0_CPU1_P0P0_DP<2>")
	)
	(segment
		(start 146.521678 -61.62675)
		(end 146.56943 -61.578998)
		(width 0.0889)
		(layer "In9.Cu")
		(net "UPI_CPU0_CPU1_P0P0_DP<2>")
	)
	(segment
		(start 177.885598 -103.78821)
		(end 179.705254 -103.882698)
		(width 0.1143)
		(layer "In9.Cu")
		(net "UPI_CPU0_CPU1_P0P0_DP<2>")
	)
	(segment
		(start 305.611784 -105.983024)
		(end 308.624478 -103.198676)
		(width 0.1143)
		(layer "In9.Cu")
		(net "UPI_CPU0_CPU1_P0P0_DP<2>")
	)
	(segment
		(start 142.41018 -60.280296)
		(end 142.858744 -60.72886)
		(width 0.0889)
		(layer "In9.Cu")
		(net "UPI_CPU0_CPU1_P0P0_DP<2>")
	)
	(segment
		(start 146.842734 -61.578998)
		(end 146.890486 -61.62675)
		(width 0.0889)
		(layer "In9.Cu")
		(net "UPI_CPU0_CPU1_P0P0_DP<2>")
	)
	(segment
		(start 308.024784 -73.467722)
		(end 307.95595 -73.303384)
		(width 0.0889)
		(layer "In9.Cu")
		(net "UPI_CPU0_CPU1_P0P0_DP<2>")
	)
	(segment
		(start 140.523976 -60.762388)
		(end 141.006068 -60.280296)
		(width 0.0889)
		(layer "In9.Cu")
		(net "UPI_CPU0_CPU1_P0P0_DP<2>")
	)
	(segment
		(start 176.590198 -102.710742)
		(end 177.885598 -103.78821)
		(width 0.1143)
		(layer "In9.Cu")
		(net "UPI_CPU0_CPU1_P0P0_DP<2>")
	)
	(segment
		(start 192.131442 -106.807254)
		(end 196.50837 -109.69244)
		(width 0.1143)
		(layer "In9.Cu")
		(net "UPI_CPU0_CPU1_P0P0_DP<2>")
	)
	(segment
		(start 147.343114 -61.62675)
		(end 147.393914 -61.57595)
		(width 0.0889)
		(layer "In9.Cu")
		(net "UPI_CPU0_CPU1_P0P0_DP<2>")
	)
	(segment
		(start 183.335168 -105.73766)
		(end 192.131442 -106.807254)
		(width 0.1143)
		(layer "In9.Cu")
		(net "UPI_CPU0_CPU1_P0P0_DP<2>")
	)
	(segment
		(start 308.36743 -75.311)
		(end 308.36743 -75.288902)
		(width 0.0889)
		(layer "In9.Cu")
		(net "UPI_CPU0_CPU1_P0P0_DP<2>")
	)
	(segment
		(start 307.95595 -73.303384)
		(end 308.00802 -73.1774)
		(width 0.0889)
		(layer "In9.Cu")
		(net "UPI_CPU0_CPU1_P0P0_DP<2>")
	)
	(segment
		(start 308.41823 -74.158348)
		(end 308.362858 -74.026014)
		(width 0.0889)
		(layer "In9.Cu")
		(net "UPI_CPU0_CPU1_P0P0_DP<2>")
	)
	(segment
		(start 172.550328 -101.908356)
		(end 176.590198 -102.710742)
		(width 0.1143)
		(layer "In9.Cu")
		(net "UPI_CPU0_CPU1_P0P0_DP<2>")
	)
	(segment
		(start 146.359118 -61.62675)
		(end 146.521678 -61.62675)
		(width 0.0889)
		(layer "In9.Cu")
		(net "UPI_CPU0_CPU1_P0P0_DP<2>")
	)
	(segment
		(start 308.727348 -78.50124)
		(end 308.580028 -78.38948)
		(width 0.1143)
		(layer "In9.Cu")
		(net "UPI_CPU0_CPU1_P0P0_DP<2>")
	)
	(segment
		(start 143.812006 -60.72886)
		(end 143.990568 -60.550298)
		(width 0.0889)
		(layer "In9.Cu")
		(net "UPI_CPU0_CPU1_P0P0_DP<2>")
	)
	(segment
		(start 248.03862 -105.242106)
		(end 263.2075 -108.37037)
		(width 0.1143)
		(layer "In9.Cu")
		(net "UPI_CPU0_CPU1_P0P0_DP<2>")
	)
	(segment
		(start 267.061442 -108.5596)
		(end 278.111204 -107.498388)
		(width 0.1143)
		(layer "In9.Cu")
		(net "UPI_CPU0_CPU1_P0P0_DP<2>")
	)
	(segment
		(start 290.353242 -104.147874)
		(end 292.542214 -103.9495)
		(width 0.1143)
		(layer "In9.Cu")
		(net "UPI_CPU0_CPU1_P0P0_DP<2>")
	)
	(segment
		(start 278.111204 -107.498388)
		(end 281.372564 -107.876594)
		(width 0.1143)
		(layer "In9.Cu")
		(net "UPI_CPU0_CPU1_P0P0_DP<2>")
	)
	(segment
		(start 143.990568 -60.550298)
		(end 145.282666 -60.550298)
		(width 0.0889)
		(layer "In9.Cu")
		(net "UPI_CPU0_CPU1_P0P0_DP<2>")
	)
	(segment
		(start 308.661054 -78.015338)
		(end 308.629812 -77.788516)
		(width 0.1143)
		(layer "In9.Cu")
		(net "UPI_CPU0_CPU1_P0P0_DP<2>")
	)
	(segment
		(start 308.646322 -78.875382)
		(end 308.75859 -78.728062)
		(width 0.1143)
		(layer "In9.Cu")
		(net "UPI_CPU0_CPU1_P0P0_DP<2>")
	)
	(segment
		(start 140.224764 -60.762388)
		(end 140.523976 -60.762388)
		(width 0.0889)
		(layer "In9.Cu")
		(net "UPI_CPU0_CPU1_P0P0_DP<2>")
	)
	(segment
		(start 199.983598 -110.518448)
		(end 228.008434 -107.14863)
		(width 0.1143)
		(layer "In9.Cu")
		(net "UPI_CPU0_CPU1_P0P0_DP<2>")
	)
	(segment
		(start 311.965086 -87.717884)
		(end 308.876954 -79.594964)
		(width 0.1143)
		(layer "In9.Cu")
		(net "UPI_CPU0_CPU1_P0P0_DP<2>")
	)
	(segment
		(start 308.36743 -75.288902)
		(end 308.41823 -75.238102)
		(width 0.0889)
		(layer "In9.Cu")
		(net "UPI_CPU0_CPU1_P0P0_DP<2>")
	)
	(segment
		(start 308.384956 -76.964032)
		(end 308.353714 -76.73721)
		(width 0.1143)
		(layer "In9.Cu")
		(net "UPI_CPU0_CPU1_P0P0_DP<2>")
	)
	(segment
		(start 308.465982 -76.58989)
		(end 308.36743 -75.867768)
		(width 0.1143)
		(layer "In9.Cu")
		(net "UPI_CPU0_CPU1_P0P0_DP<2>")
	)
	(segment
		(start 146.890486 -61.62675)
		(end 147.343114 -61.62675)
		(width 0.0889)
		(layer "In9.Cu")
		(net "UPI_CPU0_CPU1_P0P0_DP<2>")
	)
	(segment
		(start 302.912272 -106.597704)
		(end 305.611784 -105.983024)
		(width 0.1143)
		(layer "In9.Cu")
		(net "UPI_CPU0_CPU1_P0P0_DP<2>")
	)
	(segment
		(start 263.2075 -108.37037)
		(end 267.061442 -108.5596)
		(width 0.1143)
		(layer "In9.Cu")
		(net "UPI_CPU0_CPU1_P0P0_DP<2>")
	)
	(segment
		(start 181.287166 -104.285034)
		(end 183.335168 -105.73766)
		(width 0.1143)
		(layer "In9.Cu")
		(net "UPI_CPU0_CPU1_P0P0_DP<2>")
	)
	(segment
		(start 308.563518 -77.302614)
		(end 308.532276 -77.075792)
		(width 0.1143)
		(layer "In9.Cu")
		(net "UPI_CPU0_CPU1_P0P0_DP<2>")
	)
	(segment
		(start 308.629812 -77.788516)
		(end 308.482492 -77.676756)
		(width 0.1143)
		(layer "In9.Cu")
		(net "UPI_CPU0_CPU1_P0P0_DP<2>")
	)
	(segment
		(start 165.642036 -93.141546)
		(end 165.92931 -94.999302)
		(width 0.1143)
		(layer "In9.Cu")
		(net "UPI_CPU0_CPU1_P0P0_DP<2>")
	)
	(segment
		(start 308.548786 -78.162658)
		(end 308.661054 -78.015338)
		(width 0.1143)
		(layer "In9.Cu")
		(net "UPI_CPU0_CPU1_P0P0_DP<2>")
	)
	(segment
		(start 139.374118 -61.257434)
		(end 139.40282 -61.257434)
		(width 0.0889)
		(layer "In9.Cu")
		(net "UPI_CPU0_CPU1_P0P0_DP<2>")
	)
	(segment
		(start 141.006068 -60.280296)
		(end 142.41018 -60.280296)
		(width 0.0889)
		(layer "In9.Cu")
		(net "UPI_CPU0_CPU1_P0P0_DP<2>")
	)
	(segment
		(start 138.529314 -61.352938)
		(end 138.236198 -61.521848)
		(width 0.0889)
		(layer "In9.Cu")
		(net "UPI_CPU0_CPU1_P0P0_DP<2>")
	)
	(segment
		(start 308.23662 -73.974198)
		(end 308.167786 -73.80986)
		(width 0.0889)
		(layer "In9.Cu")
		(net "UPI_CPU0_CPU1_P0P0_DP<2>")
	)
	(segment
		(start 308.482492 -77.676756)
		(end 308.45125 -77.449934)
		(width 0.1143)
		(layer "In9.Cu")
		(net "UPI_CPU0_CPU1_P0P0_DP<2>")
	)
	(segment
		(start 308.580028 -78.38948)
		(end 308.548786 -78.162658)
		(width 0.1143)
		(layer "In9.Cu")
		(net "UPI_CPU0_CPU1_P0P0_DP<2>")
	)
	(segment
		(start 196.50837 -109.69244)
		(end 199.983598 -110.518448)
		(width 0.1143)
		(layer "In9.Cu")
		(net "UPI_CPU0_CPU1_P0P0_DP<2>")
	)
	(segment
		(start 307.796184 -72.670924)
		(end 307.575458 -72.140826)
		(width 0.0889)
		(layer "In9.Cu")
		(net "UPI_CPU0_CPU1_P0P0_DP<2>")
	)
	(segment
		(start 308.219856 -73.683876)
		(end 308.151022 -73.519538)
		(width 0.0889)
		(layer "In9.Cu")
		(net "UPI_CPU0_CPU1_P0P0_DP<2>")
	)
	(segment
		(start 308.82463 -79.213964)
		(end 308.677564 -79.102204)
		(width 0.1143)
		(layer "In9.Cu")
		(net "UPI_CPU0_CPU1_P0P0_DP<2>")
	)
	(segment
		(start 142.858744 -60.72886)
		(end 143.812006 -60.72886)
		(width 0.0889)
		(layer "In9.Cu")
		(net "UPI_CPU0_CPU1_P0P0_DP<2>")
	)
	(segment
		(start 308.41823 -74.332846)
		(end 308.41823 -74.158348)
		(width 0.0889)
		(layer "In9.Cu")
		(net "UPI_CPU0_CPU1_P0P0_DP<2>")
	)
	(segment
		(start 306.879498 -72.249538)
		(end 307.040026 -72.249538)
		(width 0.0889)
		(layer "In9.Cu")
		(net "UPI_CPU0_CPU1_P0P0_DP<2>")
	)
	(segment
		(start 307.744114 -72.796908)
		(end 307.796184 -72.670924)
		(width 0.0889)
		(layer "In9.Cu")
		(net "UPI_CPU0_CPU1_P0P0_DP<2>")
	)
	(segment
		(start 146.617182 -61.530992)
		(end 146.794982 -61.530992)
		(width 0.0889)
		(layer "In9.Cu")
		(net "UPI_CPU0_CPU1_P0P0_DP<2>")
	)
	(arc
		(start 306.788566 -71.871332)
		(mid 306.685114 -72.096149)
		(end 306.879498 -72.249538)
		(width 0.0889)
		(layer "In9.Cu")
		(net "UPI_CPU0_CPU1_P0P0_DP<2>")
	)
	(arc
		(start 138.876024 -61.552836)
		(mid 139.086377 -61.339864)
		(end 139.374118 -61.257434)
		(width 0.0889)
		(layer "In9.Cu")
		(net "UPI_CPU0_CPU1_P0P0_DP<2>")
	)
	(arc
		(start 138.215116 -61.600588)
		(mid 138.349678 -61.7105)
		(end 138.518138 -61.752988)
		(width 0.0889)
		(layer "In9.Cu")
		(net "UPI_CPU0_CPU1_P0P0_DP<2>")
	)
	(arc
		(start 306.879498 -71.849488)
		(mid 306.832739 -71.855026)
		(end 306.788566 -71.871332)
		(width 0.0889)
		(layer "In9.Cu")
		(net "UPI_CPU0_CPU1_P0P0_DP<2>")
	)
	(arc
		(start 139.40282 -61.257434)
		(mid 139.594462 -61.200268)
		(end 139.734544 -61.057536)
		(width 0.0889)
		(layer "In9.Cu")
		(net "UPI_CPU0_CPU1_P0P0_DP<2>")
	)
	(arc
		(start 138.54049 -61.752988)
		(mid 138.73434 -61.696638)
		(end 138.876024 -61.552836)
		(width 0.0889)
		(layer "In9.Cu")
		(net "UPI_CPU0_CPU1_P0P0_DP<2>")
	)
	(arc
		(start 139.734544 -61.057536)
		(mid 139.941548 -60.846672)
		(end 140.224764 -60.762388)
		(width 0.0889)
		(layer "In9.Cu")
		(net "UPI_CPU0_CPU1_P0P0_DP<2>")
	)
	(segment
		(start 306.130706 -72.744584)
		(end 306.181506 -72.795384)
		(width 0.1143)
		(layer "F.Cu")
		(net "UPI_CPU0_CPU1_P0P0_DP<1>")
	)
	(segment
		(start 305.533806 -72.744584)
		(end 306.130706 -72.744584)
		(width 0.1143)
		(layer "F.Cu")
		(net "UPI_CPU0_CPU1_P0P0_DP<1>")
	)
	(segment
		(start 136.240774 -62.343538)
		(end 136.812274 -62.343538)
		(width 0.1143)
		(layer "F.Cu")
		(net "UPI_CPU0_CPU1_P0P0_DP<1>")
	)
	(via
		(at 306.181506 -72.795384)
		(size 0.508)
		(drill 0.254)
		(layers "F.Cu" "B.Cu")
		(net "UPI_CPU0_CPU1_P0P0_DP<1>")
	)
	(via
		(at 136.812274 -62.343538)
		(size 0.508)
		(drill 0.254)
		(layers "F.Cu" "B.Cu")
		(net "UPI_CPU0_CPU1_P0P0_DP<1>")
	)
	(segment
		(start 165.968426 -92.992956)
		(end 166.233602 -94.70771)
		(width 0.1143)
		(layer "In9.Cu")
		(net "UPI_CPU0_CPU1_P0P0_DP<1>")
	)
	(segment
		(start 310.485028 -85.141816)
		(end 310.482742 -85.134958)
		(width 0.1143)
		(layer "In9.Cu")
		(net "UPI_CPU0_CPU1_P0P0_DP<1>")
	)
	(segment
		(start 137.659618 -61.447934)
		(end 137.692384 -61.447934)
		(width 0.0889)
		(layer "In9.Cu")
		(net "UPI_CPU0_CPU1_P0P0_DP<1>")
	)
	(segment
		(start 307.6956 -74.587354)
		(end 307.6829 -74.407522)
		(width 0.1143)
		(layer "In9.Cu")
		(net "UPI_CPU0_CPU1_P0P0_DP<1>")
	)
	(segment
		(start 310.564022 -85.349334)
		(end 310.485028 -85.141816)
		(width 0.1143)
		(layer "In9.Cu")
		(net "UPI_CPU0_CPU1_P0P0_DP<1>")
	)
	(segment
		(start 145.526252 -60.245498)
		(end 146.291554 -61.0108)
		(width 0.0889)
		(layer "In9.Cu")
		(net "UPI_CPU0_CPU1_P0P0_DP<1>")
	)
	(segment
		(start 311.534048 -88.077548)
		(end 311.558432 -87.964264)
		(width 0.1143)
		(layer "In9.Cu")
		(net "UPI_CPU0_CPU1_P0P0_DP<1>")
	)
	(segment
		(start 178.071526 -103.492554)
		(end 179.840128 -103.584502)
		(width 0.1143)
		(layer "In9.Cu")
		(net "UPI_CPU0_CPU1_P0P0_DP<1>")
	)
	(segment
		(start 310.482742 -85.134958)
		(end 309.826406 -83.408774)
		(width 0.1143)
		(layer "In9.Cu")
		(net "UPI_CPU0_CPU1_P0P0_DP<1>")
	)
	(segment
		(start 140.231368 -59.962288)
		(end 142.494762 -59.962288)
		(width 0.0889)
		(layer "In9.Cu")
		(net "UPI_CPU0_CPU1_P0P0_DP<1>")
	)
	(segment
		(start 166.233602 -94.70771)
		(end 172.857922 -101.61778)
		(width 0.1143)
		(layer "In9.Cu")
		(net "UPI_CPU0_CPU1_P0P0_DP<1>")
	)
	(segment
		(start 305.639216 -105.487216)
		(end 308.310026 -103.01859)
		(width 0.1143)
		(layer "In9.Cu")
		(net "UPI_CPU0_CPU1_P0P0_DP<1>")
	)
	(segment
		(start 308.310026 -103.01859)
		(end 311.534048 -88.077548)
		(width 0.1143)
		(layer "In9.Cu")
		(net "UPI_CPU0_CPU1_P0P0_DP<1>")
	)
	(segment
		(start 310.564276 -85.350096)
		(end 310.564022 -85.349334)
		(width 0.1143)
		(layer "In9.Cu")
		(net "UPI_CPU0_CPU1_P0P0_DP<1>")
	)
	(segment
		(start 143.805402 -60.245498)
		(end 145.526252 -60.245498)
		(width 0.0889)
		(layer "In9.Cu")
		(net "UPI_CPU0_CPU1_P0P0_DP<1>")
	)
	(segment
		(start 183.576468 -105.467912)
		(end 192.44564 -106.54665)
		(width 0.1143)
		(layer "In9.Cu")
		(net "UPI_CPU0_CPU1_P0P0_DP<1>")
	)
	(segment
		(start 136.812274 -62.343538)
		(end 136.812274 -62.005464)
		(width 0.0889)
		(layer "In9.Cu")
		(net "UPI_CPU0_CPU1_P0P0_DP<1>")
	)
	(segment
		(start 138.514328 -60.952888)
		(end 138.547094 -60.952888)
		(width 0.0889)
		(layer "In9.Cu")
		(net "UPI_CPU0_CPU1_P0P0_DP<1>")
	)
	(segment
		(start 181.525672 -104.013508)
		(end 183.576468 -105.467912)
		(width 0.1143)
		(layer "In9.Cu")
		(net "UPI_CPU0_CPU1_P0P0_DP<1>")
	)
	(segment
		(start 159.379158 -85.195156)
		(end 165.968426 -92.992956)
		(width 0.1143)
		(layer "In9.Cu")
		(net "UPI_CPU0_CPU1_P0P0_DP<1>")
	)
	(segment
		(start 302.915574 -106.242866)
		(end 305.444906 -105.667048)
		(width 0.1143)
		(layer "In9.Cu")
		(net "UPI_CPU0_CPU1_P0P0_DP<1>")
	)
	(segment
		(start 142.494762 -59.962288)
		(end 142.99438 -60.461906)
		(width 0.0889)
		(layer "In9.Cu")
		(net "UPI_CPU0_CPU1_P0P0_DP<1>")
	)
	(segment
		(start 307.6829 -74.407522)
		(end 307.514244 -73.86574)
		(width 0.1143)
		(layer "In9.Cu")
		(net "UPI_CPU0_CPU1_P0P0_DP<1>")
	)
	(segment
		(start 292.5699 -103.60025)
		(end 302.915574 -106.242866)
		(width 0.1143)
		(layer "In9.Cu")
		(net "UPI_CPU0_CPU1_P0P0_DP<1>")
	)
	(segment
		(start 309.498746 -82.546444)
		(end 309.258716 -81.915)
		(width 0.1143)
		(layer "In9.Cu")
		(net "UPI_CPU0_CPU1_P0P0_DP<1>")
	)
	(segment
		(start 176.743614 -102.38867)
		(end 178.071526 -103.492554)
		(width 0.1143)
		(layer "In9.Cu")
		(net "UPI_CPU0_CPU1_P0P0_DP<1>")
	)
	(segment
		(start 147.007072 -61.0108)
		(end 147.057872 -61.0616)
		(width 0.0889)
		(layer "In9.Cu")
		(net "UPI_CPU0_CPU1_P0P0_DP<1>")
	)
	(segment
		(start 290.269422 -103.808784)
		(end 291.125402 -103.731314)
		(width 0.1143)
		(layer "In9.Cu")
		(net "UPI_CPU0_CPU1_P0P0_DP<1>")
	)
	(segment
		(start 306.778406 -73.129648)
		(end 306.51577 -73.129648)
		(width 0.1143)
		(layer "In9.Cu")
		(net "UPI_CPU0_CPU1_P0P0_DP<1>")
	)
	(segment
		(start 179.840128 -103.584502)
		(end 181.525672 -104.013508)
		(width 0.1143)
		(layer "In9.Cu")
		(net "UPI_CPU0_CPU1_P0P0_DP<1>")
	)
	(segment
		(start 309.088282 -81.466436)
		(end 308.192678 -79.110586)
		(width 0.1143)
		(layer "In9.Cu")
		(net "UPI_CPU0_CPU1_P0P0_DP<1>")
	)
	(segment
		(start 147.057872 -61.0616)
		(end 147.07997 -61.0616)
		(width 0.0889)
		(layer "In9.Cu")
		(net "UPI_CPU0_CPU1_P0P0_DP<1>")
	)
	(segment
		(start 146.291554 -61.0108)
		(end 147.007072 -61.0108)
		(width 0.0889)
		(layer "In9.Cu")
		(net "UPI_CPU0_CPU1_P0P0_DP<1>")
	)
	(segment
		(start 311.558432 -87.964264)
		(end 310.564276 -85.350096)
		(width 0.1143)
		(layer "In9.Cu")
		(net "UPI_CPU0_CPU1_P0P0_DP<1>")
	)
	(segment
		(start 309.826152 -83.408012)
		(end 309.50027 -82.551016)
		(width 0.1143)
		(layer "In9.Cu")
		(net "UPI_CPU0_CPU1_P0P0_DP<1>")
	)
	(segment
		(start 307.37429 -73.725532)
		(end 306.778406 -73.129648)
		(width 0.1143)
		(layer "In9.Cu")
		(net "UPI_CPU0_CPU1_P0P0_DP<1>")
	)
	(segment
		(start 309.826406 -83.408774)
		(end 309.826152 -83.408012)
		(width 0.1143)
		(layer "In9.Cu")
		(net "UPI_CPU0_CPU1_P0P0_DP<1>")
	)
	(segment
		(start 147.07997 -61.0616)
		(end 148.7297 -61.0616)
		(width 0.1143)
		(layer "In9.Cu")
		(net "UPI_CPU0_CPU1_P0P0_DP<1>")
	)
	(segment
		(start 307.937154 -78.006956)
		(end 307.8861 -77.285342)
		(width 0.1143)
		(layer "In9.Cu")
		(net "UPI_CPU0_CPU1_P0P0_DP<1>")
	)
	(segment
		(start 308.192678 -79.110586)
		(end 307.937154 -78.006956)
		(width 0.1143)
		(layer "In9.Cu")
		(net "UPI_CPU0_CPU1_P0P0_DP<1>")
	)
	(segment
		(start 139.376658 -60.457334)
		(end 139.409424 -60.457334)
		(width 0.0889)
		(layer "In9.Cu")
		(net "UPI_CPU0_CPU1_P0P0_DP<1>")
	)
	(segment
		(start 151.400256 -63.9064)
		(end 154.503882 -67.212464)
		(width 0.1143)
		(layer "In9.Cu")
		(net "UPI_CPU0_CPU1_P0P0_DP<1>")
	)
	(segment
		(start 142.99438 -60.461906)
		(end 143.588994 -60.461906)
		(width 0.0889)
		(layer "In9.Cu")
		(net "UPI_CPU0_CPU1_P0P0_DP<1>")
	)
	(segment
		(start 309.088536 -81.467198)
		(end 309.088282 -81.466436)
		(width 0.1143)
		(layer "In9.Cu")
		(net "UPI_CPU0_CPU1_P0P0_DP<1>")
	)
	(segment
		(start 233.635042 -107.75569)
		(end 248.03481 -104.887776)
		(width 0.1143)
		(layer "In9.Cu")
		(net "UPI_CPU0_CPU1_P0P0_DP<1>")
	)
	(segment
		(start 305.444906 -105.667048)
		(end 305.639216 -105.487216)
		(width 0.1143)
		(layer "In9.Cu")
		(net "UPI_CPU0_CPU1_P0P0_DP<1>")
	)
	(segment
		(start 143.588994 -60.461906)
		(end 143.805402 -60.245498)
		(width 0.0889)
		(layer "In9.Cu")
		(net "UPI_CPU0_CPU1_P0P0_DP<1>")
	)
	(segment
		(start 309.252874 -81.899506)
		(end 309.088536 -81.467198)
		(width 0.1143)
		(layer "In9.Cu")
		(net "UPI_CPU0_CPU1_P0P0_DP<1>")
	)
	(segment
		(start 307.514244 -73.86574)
		(end 307.37429 -73.725786)
		(width 0.1143)
		(layer "In9.Cu")
		(net "UPI_CPU0_CPU1_P0P0_DP<1>")
	)
	(segment
		(start 154.503882 -67.212464)
		(end 159.379158 -85.195156)
		(width 0.1143)
		(layer "In9.Cu")
		(net "UPI_CPU0_CPU1_P0P0_DP<1>")
	)
	(segment
		(start 136.812274 -62.005464)
		(end 136.877552 -61.940186)
		(width 0.0889)
		(layer "In9.Cu")
		(net "UPI_CPU0_CPU1_P0P0_DP<1>")
	)
	(segment
		(start 192.44564 -106.54665)
		(end 196.860668 -109.456982)
		(width 0.1143)
		(layer "In9.Cu")
		(net "UPI_CPU0_CPU1_P0P0_DP<1>")
	)
	(segment
		(start 291.125402 -103.731314)
		(end 292.5699 -103.60025)
		(width 0.1143)
		(layer "In9.Cu")
		(net "UPI_CPU0_CPU1_P0P0_DP<1>")
	)
	(segment
		(start 199.903588 -110.180374)
		(end 228.01707 -106.799634)
		(width 0.1143)
		(layer "In9.Cu")
		(net "UPI_CPU0_CPU1_P0P0_DP<1>")
	)
	(segment
		(start 306.51577 -73.129648)
		(end 306.181506 -72.795384)
		(width 0.1143)
		(layer "In9.Cu")
		(net "UPI_CPU0_CPU1_P0P0_DP<1>")
	)
	(segment
		(start 151.114252 -63.6016)
		(end 151.400256 -63.9064)
		(width 0.1143)
		(layer "In9.Cu")
		(net "UPI_CPU0_CPU1_P0P0_DP<1>")
	)
	(segment
		(start 263.236202 -108.025946)
		(end 267.053314 -108.213144)
		(width 0.1143)
		(layer "In9.Cu")
		(net "UPI_CPU0_CPU1_P0P0_DP<1>")
	)
	(segment
		(start 309.258716 -81.915)
		(end 309.253128 -81.900268)
		(width 0.1143)
		(layer "In9.Cu")
		(net "UPI_CPU0_CPU1_P0P0_DP<1>")
	)
	(segment
		(start 172.857922 -101.61778)
		(end 176.743614 -102.38867)
		(width 0.1143)
		(layer "In9.Cu")
		(net "UPI_CPU0_CPU1_P0P0_DP<1>")
	)
	(segment
		(start 267.053314 -108.213144)
		(end 278.114506 -107.150916)
		(width 0.1143)
		(layer "In9.Cu")
		(net "UPI_CPU0_CPU1_P0P0_DP<1>")
	)
	(segment
		(start 281.323796 -107.522772)
		(end 290.269422 -103.808784)
		(width 0.1143)
		(layer "In9.Cu")
		(net "UPI_CPU0_CPU1_P0P0_DP<1>")
	)
	(segment
		(start 228.01707 -106.799634)
		(end 233.635042 -107.75569)
		(width 0.1143)
		(layer "In9.Cu")
		(net "UPI_CPU0_CPU1_P0P0_DP<1>")
	)
	(segment
		(start 307.8861 -77.285342)
		(end 307.6956 -74.587354)
		(width 0.1143)
		(layer "In9.Cu")
		(net "UPI_CPU0_CPU1_P0P0_DP<1>")
	)
	(segment
		(start 309.50027 -82.551016)
		(end 309.498746 -82.546444)
		(width 0.1143)
		(layer "In9.Cu")
		(net "UPI_CPU0_CPU1_P0P0_DP<1>")
	)
	(segment
		(start 307.37429 -73.725786)
		(end 307.37429 -73.725532)
		(width 0.1143)
		(layer "In9.Cu")
		(net "UPI_CPU0_CPU1_P0P0_DP<1>")
	)
	(segment
		(start 278.114506 -107.150916)
		(end 281.323796 -107.522772)
		(width 0.1143)
		(layer "In9.Cu")
		(net "UPI_CPU0_CPU1_P0P0_DP<1>")
	)
	(segment
		(start 309.253128 -81.900268)
		(end 309.252874 -81.899506)
		(width 0.1143)
		(layer "In9.Cu")
		(net "UPI_CPU0_CPU1_P0P0_DP<1>")
	)
	(segment
		(start 196.860668 -109.456982)
		(end 199.903588 -110.180374)
		(width 0.1143)
		(layer "In9.Cu")
		(net "UPI_CPU0_CPU1_P0P0_DP<1>")
	)
	(segment
		(start 148.7297 -61.0616)
		(end 151.114252 -63.6016)
		(width 0.1143)
		(layer "In9.Cu")
		(net "UPI_CPU0_CPU1_P0P0_DP<1>")
	)
	(segment
		(start 248.03481 -104.887776)
		(end 263.236202 -108.025946)
		(width 0.1143)
		(layer "In9.Cu")
		(net "UPI_CPU0_CPU1_P0P0_DP<1>")
	)
	(arc
		(start 136.877552 -61.940186)
		(mid 137.135689 -61.847432)
		(end 137.324084 -61.648086)
		(width 0.0889)
		(layer "In9.Cu")
		(net "UPI_CPU0_CPU1_P0P0_DP<1>")
	)
	(arc
		(start 139.899644 -60.162186)
		(mid 140.039723 -60.01945)
		(end 140.231368 -59.962288)
		(width 0.0889)
		(layer "In9.Cu")
		(net "UPI_CPU0_CPU1_P0P0_DP<1>")
	)
	(arc
		(start 139.409424 -60.457334)
		(mid 139.692641 -60.373053)
		(end 139.899644 -60.162186)
		(width 0.0889)
		(layer "In9.Cu")
		(net "UPI_CPU0_CPU1_P0P0_DP<1>")
	)
	(arc
		(start 138.182604 -61.152786)
		(mid 138.322683 -61.01005)
		(end 138.514328 -60.952888)
		(width 0.0889)
		(layer "In9.Cu")
		(net "UPI_CPU0_CPU1_P0P0_DP<1>")
	)
	(arc
		(start 138.547094 -60.952888)
		(mid 138.832518 -60.869421)
		(end 139.041124 -60.657486)
		(width 0.0889)
		(layer "In9.Cu")
		(net "UPI_CPU0_CPU1_P0P0_DP<1>")
	)
	(arc
		(start 137.692384 -61.447934)
		(mid 137.975601 -61.363653)
		(end 138.182604 -61.152786)
		(width 0.0889)
		(layer "In9.Cu")
		(net "UPI_CPU0_CPU1_P0P0_DP<1>")
	)
	(arc
		(start 139.041124 -60.657486)
		(mid 139.182807 -60.513682)
		(end 139.376658 -60.457334)
		(width 0.0889)
		(layer "In9.Cu")
		(net "UPI_CPU0_CPU1_P0P0_DP<1>")
	)
	(arc
		(start 137.324084 -61.648086)
		(mid 137.465767 -61.504282)
		(end 137.659618 -61.447934)
		(width 0.0889)
		(layer "In9.Cu")
		(net "UPI_CPU0_CPU1_P0P0_DP<1>")
	)
	(segment
		(start 307.250846 -56.894984)
		(end 307.898546 -56.894984)
		(width 0.1143)
		(layer "F.Cu")
		(net "UPI_CPU0_CPU1_P0P0_DP<19>")
	)
	(segment
		(start 134.236714 -71.753984)
		(end 133.665214 -71.753984)
		(width 0.1143)
		(layer "F.Cu")
		(net "UPI_CPU0_CPU1_P0P0_DP<19>")
	)
	(via
		(at 134.236714 -71.753984)
		(size 0.508)
		(drill 0.254)
		(layers "F.Cu" "B.Cu")
		(net "UPI_CPU0_CPU1_P0P0_DP<19>")
	)
	(via
		(at 307.898546 -56.894984)
		(size 0.508)
		(drill 0.254)
		(layers "F.Cu" "B.Cu")
		(net "UPI_CPU0_CPU1_P0P0_DP<19>")
	)
	(segment
		(start 142.876778 -79.840836)
		(end 143.801846 -79.840836)
		(width 0.1143)
		(layer "In9.Cu")
		(net "UPI_CPU0_CPU1_P0P0_DP<19>")
	)
	(segment
		(start 320.063876 -68.4276)
		(end 318.4144 -64.027558)
		(width 0.1143)
		(layer "In9.Cu")
		(net "UPI_CPU0_CPU1_P0P0_DP<19>")
	)
	(segment
		(start 311.56529 -57.872884)
		(end 309.54472 -57.872884)
		(width 0.1143)
		(layer "In9.Cu")
		(net "UPI_CPU0_CPU1_P0P0_DP<19>")
	)
	(segment
		(start 322.639182 -80.204818)
		(end 322.629022 -79.8322)
		(width 0.1143)
		(layer "In9.Cu")
		(net "UPI_CPU0_CPU1_P0P0_DP<19>")
	)
	(segment
		(start 285.228538 -119.532908)
		(end 291.125402 -120.216676)
		(width 0.1143)
		(layer "In9.Cu")
		(net "UPI_CPU0_CPU1_P0P0_DP<19>")
	)
	(segment
		(start 134.577074 -73.524618)
		(end 134.583424 -73.535286)
		(width 0.0889)
		(layer "In9.Cu")
		(net "UPI_CPU0_CPU1_P0P0_DP<19>")
	)
	(segment
		(start 150.048468 -99.654106)
		(end 150.555198 -100.571046)
		(width 0.1143)
		(layer "In9.Cu")
		(net "UPI_CPU0_CPU1_P0P0_DP<19>")
	)
	(segment
		(start 135.932164 -76.306934)
		(end 135.96493 -76.306934)
		(width 0.0889)
		(layer "In9.Cu")
		(net "UPI_CPU0_CPU1_P0P0_DP<19>")
	)
	(segment
		(start 134.577074 -72.534018)
		(end 134.583424 -72.544686)
		(width 0.0889)
		(layer "In9.Cu")
		(net "UPI_CPU0_CPU1_P0P0_DP<19>")
	)
	(segment
		(start 134.577074 -74.515218)
		(end 134.583424 -74.525886)
		(width 0.0889)
		(layer "In9.Cu")
		(net "UPI_CPU0_CPU1_P0P0_DP<19>")
	)
	(segment
		(start 151.768048 -101.69017)
		(end 154.93873 -102.167944)
		(width 0.1143)
		(layer "In9.Cu")
		(net "UPI_CPU0_CPU1_P0P0_DP<19>")
	)
	(segment
		(start 324.020434 -104.310434)
		(end 324.143116 -104.19715)
		(width 0.1143)
		(layer "In9.Cu")
		(net "UPI_CPU0_CPU1_P0P0_DP<19>")
	)
	(segment
		(start 140.224764 -78.783688)
		(end 140.25753 -78.783688)
		(width 0.0889)
		(layer "In9.Cu")
		(net "UPI_CPU0_CPU1_P0P0_DP<19>")
	)
	(segment
		(start 149.974554 -98.629216)
		(end 149.975316 -98.629724)
		(width 0.1143)
		(layer "In9.Cu")
		(net "UPI_CPU0_CPU1_P0P0_DP<19>")
	)
	(segment
		(start 292.533324 -120.379998)
		(end 311.240678 -116.117116)
		(width 0.1143)
		(layer "In9.Cu")
		(net "UPI_CPU0_CPU1_P0P0_DP<19>")
	)
	(segment
		(start 227.841302 -118.412768)
		(end 248.17197 -121.87555)
		(width 0.1143)
		(layer "In9.Cu")
		(net "UPI_CPU0_CPU1_P0P0_DP<19>")
	)
	(segment
		(start 322.629022 -79.8322)
		(end 322.566284 -77.555598)
		(width 0.1143)
		(layer "In9.Cu")
		(net "UPI_CPU0_CPU1_P0P0_DP<19>")
	)
	(segment
		(start 137.649204 -77.297534)
		(end 137.68197 -77.297534)
		(width 0.0889)
		(layer "In9.Cu")
		(net "UPI_CPU0_CPU1_P0P0_DP<19>")
	)
	(segment
		(start 325.95058 -100.911914)
		(end 326.172576 -97.991676)
		(width 0.1143)
		(layer "In9.Cu")
		(net "UPI_CPU0_CPU1_P0P0_DP<19>")
	)
	(segment
		(start 149.975316 -98.629724)
		(end 150.048468 -99.654106)
		(width 0.1143)
		(layer "In9.Cu")
		(net "UPI_CPU0_CPU1_P0P0_DP<19>")
	)
	(segment
		(start 259.04952 -119.312944)
		(end 267.323062 -119.720868)
		(width 0.1143)
		(layer "In9.Cu")
		(net "UPI_CPU0_CPU1_P0P0_DP<19>")
	)
	(segment
		(start 150.555198 -100.571046)
		(end 151.701754 -101.628956)
		(width 0.1143)
		(layer "In9.Cu")
		(net "UPI_CPU0_CPU1_P0P0_DP<19>")
	)
	(segment
		(start 136.794494 -76.802488)
		(end 136.82726 -76.802488)
		(width 0.0889)
		(layer "In9.Cu")
		(net "UPI_CPU0_CPU1_P0P0_DP<19>")
	)
	(segment
		(start 146.714464 -82.437732)
		(end 149.562058 -92.9386)
		(width 0.1143)
		(layer "In9.Cu")
		(net "UPI_CPU0_CPU1_P0P0_DP<19>")
	)
	(segment
		(start 141.556994 -79.278988)
		(end 141.70914 -79.431134)
		(width 0.0889)
		(layer "In9.Cu")
		(net "UPI_CPU0_CPU1_P0P0_DP<19>")
	)
	(segment
		(start 185.735214 -123.077986)
		(end 193.447924 -122.553222)
		(width 0.1143)
		(layer "In9.Cu")
		(net "UPI_CPU0_CPU1_P0P0_DP<19>")
	)
	(segment
		(start 308.531768 -57.295034)
		(end 307.743098 -57.295034)
		(width 0.0889)
		(layer "In9.Cu")
		(net "UPI_CPU0_CPU1_P0P0_DP<19>")
	)
	(segment
		(start 134.583424 -72.544686)
		(end 134.58825 -72.553322)
		(width 0.0889)
		(layer "In9.Cu")
		(net "UPI_CPU0_CPU1_P0P0_DP<19>")
	)
	(segment
		(start 143.801846 -79.840836)
		(end 146.714464 -82.437732)
		(width 0.1143)
		(layer "In9.Cu")
		(net "UPI_CPU0_CPU1_P0P0_DP<19>")
	)
	(segment
		(start 278.00427 -118.695216)
		(end 285.228538 -119.533162)
		(width 0.1143)
		(layer "In9.Cu")
		(net "UPI_CPU0_CPU1_P0P0_DP<19>")
	)
	(segment
		(start 267.323062 -119.720868)
		(end 278.00427 -118.695216)
		(width 0.1143)
		(layer "In9.Cu")
		(net "UPI_CPU0_CPU1_P0P0_DP<19>")
	)
	(segment
		(start 318.4144 -64.027558)
		(end 311.56529 -57.872884)
		(width 0.1143)
		(layer "In9.Cu")
		(net "UPI_CPU0_CPU1_P0P0_DP<19>")
	)
	(segment
		(start 134.583424 -74.525886)
		(end 134.58825 -74.534522)
		(width 0.0889)
		(layer "In9.Cu")
		(net "UPI_CPU0_CPU1_P0P0_DP<19>")
	)
	(segment
		(start 307.743098 -56.894984)
		(end 307.898546 -56.894984)
		(width 0.0889)
		(layer "In9.Cu")
		(net "UPI_CPU0_CPU1_P0P0_DP<19>")
	)
	(segment
		(start 134.583424 -73.535286)
		(end 134.58825 -73.543922)
		(width 0.0889)
		(layer "In9.Cu")
		(net "UPI_CPU0_CPU1_P0P0_DP<19>")
	)
	(segment
		(start 141.834616 -79.687166)
		(end 141.965172 -79.687166)
		(width 0.0889)
		(layer "In9.Cu")
		(net "UPI_CPU0_CPU1_P0P0_DP<19>")
	)
	(segment
		(start 151.7015 -101.628956)
		(end 151.768048 -101.69017)
		(width 0.1143)
		(layer "In9.Cu")
		(net "UPI_CPU0_CPU1_P0P0_DP<19>")
	)
	(segment
		(start 291.125402 -120.216676)
		(end 292.533324 -120.379998)
		(width 0.1143)
		(layer "In9.Cu")
		(net "UPI_CPU0_CPU1_P0P0_DP<19>")
	)
	(segment
		(start 248.17197 -121.87555)
		(end 259.04952 -119.312944)
		(width 0.1143)
		(layer "In9.Cu")
		(net "UPI_CPU0_CPU1_P0P0_DP<19>")
	)
	(segment
		(start 285.228538 -119.533162)
		(end 285.228538 -119.532908)
		(width 0.1143)
		(layer "In9.Cu")
		(net "UPI_CPU0_CPU1_P0P0_DP<19>")
	)
	(segment
		(start 142.85468 -79.840836)
		(end 142.876778 -79.840836)
		(width 0.0889)
		(layer "In9.Cu")
		(net "UPI_CPU0_CPU1_P0P0_DP<19>")
	)
	(segment
		(start 309.160418 -57.923684)
		(end 308.531768 -57.295034)
		(width 0.0889)
		(layer "In9.Cu")
		(net "UPI_CPU0_CPU1_P0P0_DP<19>")
	)
	(segment
		(start 309.522622 -57.872884)
		(end 309.471822 -57.923684)
		(width 0.0889)
		(layer "In9.Cu")
		(net "UPI_CPU0_CPU1_P0P0_DP<19>")
	)
	(segment
		(start 309.471822 -57.923684)
		(end 309.160418 -57.923684)
		(width 0.0889)
		(layer "In9.Cu")
		(net "UPI_CPU0_CPU1_P0P0_DP<19>")
	)
	(segment
		(start 135.077454 -75.811888)
		(end 135.11022 -75.811888)
		(width 0.0889)
		(layer "In9.Cu")
		(net "UPI_CPU0_CPU1_P0P0_DP<19>")
	)
	(segment
		(start 322.897246 -81.915)
		(end 322.79971 -81.435956)
		(width 0.1143)
		(layer "In9.Cu")
		(net "UPI_CPU0_CPU1_P0P0_DP<19>")
	)
	(segment
		(start 311.240678 -116.117116)
		(end 324.020434 -104.310434)
		(width 0.1143)
		(layer "In9.Cu")
		(net "UPI_CPU0_CPU1_P0P0_DP<19>")
	)
	(segment
		(start 193.447924 -122.553222)
		(end 210.644232 -120.483122)
		(width 0.1143)
		(layer "In9.Cu")
		(net "UPI_CPU0_CPU1_P0P0_DP<19>")
	)
	(segment
		(start 322.56603 -77.555598)
		(end 322.492624 -74.905616)
		(width 0.1143)
		(layer "In9.Cu")
		(net "UPI_CPU0_CPU1_P0P0_DP<19>")
	)
	(segment
		(start 322.79971 -81.435956)
		(end 322.653406 -80.717644)
		(width 0.1143)
		(layer "In9.Cu")
		(net "UPI_CPU0_CPU1_P0P0_DP<19>")
	)
	(segment
		(start 322.492624 -74.905616)
		(end 320.063876 -68.4276)
		(width 0.1143)
		(layer "In9.Cu")
		(net "UPI_CPU0_CPU1_P0P0_DP<19>")
	)
	(segment
		(start 325.313802 -93.7768)
		(end 322.897246 -81.915)
		(width 0.1143)
		(layer "In9.Cu")
		(net "UPI_CPU0_CPU1_P0P0_DP<19>")
	)
	(segment
		(start 309.54472 -57.872884)
		(end 309.522622 -57.872884)
		(width 0.0889)
		(layer "In9.Cu")
		(net "UPI_CPU0_CPU1_P0P0_DP<19>")
	)
	(segment
		(start 210.644486 -120.483122)
		(end 227.841302 -118.412768)
		(width 0.1143)
		(layer "In9.Cu")
		(net "UPI_CPU0_CPU1_P0P0_DP<19>")
	)
	(segment
		(start 322.566284 -77.555598)
		(end 322.56603 -77.555598)
		(width 0.1143)
		(layer "In9.Cu")
		(net "UPI_CPU0_CPU1_P0P0_DP<19>")
	)
	(segment
		(start 149.562058 -92.9386)
		(end 149.974554 -98.629216)
		(width 0.1143)
		(layer "In9.Cu")
		(net "UPI_CPU0_CPU1_P0P0_DP<19>")
	)
	(segment
		(start 210.644232 -120.483122)
		(end 210.644486 -120.483122)
		(width 0.1143)
		(layer "In9.Cu")
		(net "UPI_CPU0_CPU1_P0P0_DP<19>")
	)
	(segment
		(start 141.70914 -79.431134)
		(end 141.70914 -79.56169)
		(width 0.0889)
		(layer "In9.Cu")
		(net "UPI_CPU0_CPU1_P0P0_DP<19>")
	)
	(segment
		(start 326.172576 -97.991676)
		(end 325.313802 -93.7768)
		(width 0.1143)
		(layer "In9.Cu")
		(net "UPI_CPU0_CPU1_P0P0_DP<19>")
	)
	(segment
		(start 141.965172 -79.687166)
		(end 142.068042 -79.790036)
		(width 0.0889)
		(layer "In9.Cu")
		(net "UPI_CPU0_CPU1_P0P0_DP<19>")
	)
	(segment
		(start 141.083284 -79.278988)
		(end 141.556994 -79.278988)
		(width 0.0889)
		(layer "In9.Cu")
		(net "UPI_CPU0_CPU1_P0P0_DP<19>")
	)
	(segment
		(start 142.80388 -79.790036)
		(end 142.85468 -79.840836)
		(width 0.0889)
		(layer "In9.Cu")
		(net "UPI_CPU0_CPU1_P0P0_DP<19>")
	)
	(segment
		(start 139.37488 -78.288388)
		(end 139.39901 -78.288388)
		(width 0.0889)
		(layer "In9.Cu")
		(net "UPI_CPU0_CPU1_P0P0_DP<19>")
	)
	(segment
		(start 138.511534 -77.793088)
		(end 138.5443 -77.793088)
		(width 0.0889)
		(layer "In9.Cu")
		(net "UPI_CPU0_CPU1_P0P0_DP<19>")
	)
	(segment
		(start 142.068042 -79.790036)
		(end 142.80388 -79.790036)
		(width 0.0889)
		(layer "In9.Cu")
		(net "UPI_CPU0_CPU1_P0P0_DP<19>")
	)
	(segment
		(start 170.252136 -117.003068)
		(end 180.115464 -121.411746)
		(width 0.1143)
		(layer "In9.Cu")
		(net "UPI_CPU0_CPU1_P0P0_DP<19>")
	)
	(segment
		(start 324.143116 -104.19715)
		(end 325.95058 -100.911914)
		(width 0.1143)
		(layer "In9.Cu")
		(net "UPI_CPU0_CPU1_P0P0_DP<19>")
	)
	(segment
		(start 154.93873 -102.167944)
		(end 170.252136 -117.003068)
		(width 0.1143)
		(layer "In9.Cu")
		(net "UPI_CPU0_CPU1_P0P0_DP<19>")
	)
	(segment
		(start 151.701754 -101.628956)
		(end 151.7015 -101.628956)
		(width 0.1143)
		(layer "In9.Cu")
		(net "UPI_CPU0_CPU1_P0P0_DP<19>")
	)
	(segment
		(start 180.115464 -121.411746)
		(end 185.735214 -123.077986)
		(width 0.1143)
		(layer "In9.Cu")
		(net "UPI_CPU0_CPU1_P0P0_DP<19>")
	)
	(segment
		(start 141.70914 -79.56169)
		(end 141.834616 -79.687166)
		(width 0.0889)
		(layer "In9.Cu")
		(net "UPI_CPU0_CPU1_P0P0_DP<19>")
	)
	(segment
		(start 322.653406 -80.717644)
		(end 322.639182 -80.204818)
		(width 0.1143)
		(layer "In9.Cu")
		(net "UPI_CPU0_CPU1_P0P0_DP<19>")
	)
	(arc
		(start 136.82726 -76.802488)
		(mid 137.018902 -76.859654)
		(end 137.158984 -77.002386)
		(width 0.0889)
		(layer "In9.Cu")
		(net "UPI_CPU0_CPU1_P0P0_DP<19>")
	)
	(arc
		(start 134.58825 -72.553322)
		(mid 134.637005 -72.749674)
		(end 134.583424 -72.944736)
		(width 0.0889)
		(layer "In9.Cu")
		(net "UPI_CPU0_CPU1_P0P0_DP<19>")
	)
	(arc
		(start 138.5443 -77.793088)
		(mid 138.735942 -77.850254)
		(end 138.876024 -77.992986)
		(width 0.0889)
		(layer "In9.Cu")
		(net "UPI_CPU0_CPU1_P0P0_DP<19>")
	)
	(arc
		(start 135.11022 -75.811888)
		(mid 135.301862 -75.869054)
		(end 135.441944 -76.011786)
		(width 0.0889)
		(layer "In9.Cu")
		(net "UPI_CPU0_CPU1_P0P0_DP<19>")
	)
	(arc
		(start 134.536434 -72.05726)
		(mid 134.506288 -72.29994)
		(end 134.577074 -72.534018)
		(width 0.0889)
		(layer "In9.Cu")
		(net "UPI_CPU0_CPU1_P0P0_DP<19>")
	)
	(arc
		(start 134.583424 -74.925936)
		(mid 134.579095 -75.509108)
		(end 135.077454 -75.811888)
		(width 0.0889)
		(layer "In9.Cu")
		(net "UPI_CPU0_CPU1_P0P0_DP<19>")
	)
	(arc
		(start 140.25753 -78.783688)
		(mid 140.45138 -78.840038)
		(end 140.593064 -78.98384)
		(width 0.0889)
		(layer "In9.Cu")
		(net "UPI_CPU0_CPU1_P0P0_DP<19>")
	)
	(arc
		(start 137.68197 -77.297534)
		(mid 137.87582 -77.353884)
		(end 138.017504 -77.497686)
		(width 0.0889)
		(layer "In9.Cu")
		(net "UPI_CPU0_CPU1_P0P0_DP<19>")
	)
	(arc
		(start 135.441944 -76.011786)
		(mid 135.648948 -76.22265)
		(end 135.932164 -76.306934)
		(width 0.0889)
		(layer "In9.Cu")
		(net "UPI_CPU0_CPU1_P0P0_DP<19>")
	)
	(arc
		(start 134.583424 -72.944736)
		(mid 134.504202 -73.233854)
		(end 134.577074 -73.524618)
		(width 0.0889)
		(layer "In9.Cu")
		(net "UPI_CPU0_CPU1_P0P0_DP<19>")
	)
	(arc
		(start 134.58825 -74.534522)
		(mid 134.637005 -74.730874)
		(end 134.583424 -74.925936)
		(width 0.0889)
		(layer "In9.Cu")
		(net "UPI_CPU0_CPU1_P0P0_DP<19>")
	)
	(arc
		(start 135.96493 -76.306934)
		(mid 136.15878 -76.363284)
		(end 136.300464 -76.507086)
		(width 0.0889)
		(layer "In9.Cu")
		(net "UPI_CPU0_CPU1_P0P0_DP<19>")
	)
	(arc
		(start 134.236714 -71.753984)
		(mid 134.480838 -71.812529)
		(end 134.536434 -72.05726)
		(width 0.0889)
		(layer "In9.Cu")
		(net "UPI_CPU0_CPU1_P0P0_DP<19>")
	)
	(arc
		(start 140.593064 -78.98384)
		(mid 140.800068 -79.194704)
		(end 141.083284 -79.278988)
		(width 0.0889)
		(layer "In9.Cu")
		(net "UPI_CPU0_CPU1_P0P0_DP<19>")
	)
	(arc
		(start 139.734544 -78.48854)
		(mid 139.941548 -78.699404)
		(end 140.224764 -78.783688)
		(width 0.0889)
		(layer "In9.Cu")
		(net "UPI_CPU0_CPU1_P0P0_DP<19>")
	)
	(arc
		(start 138.017504 -77.497686)
		(mid 138.226112 -77.709618)
		(end 138.511534 -77.793088)
		(width 0.0889)
		(layer "In9.Cu")
		(net "UPI_CPU0_CPU1_P0P0_DP<19>")
	)
	(arc
		(start 139.39901 -78.288388)
		(mid 139.59286 -78.344738)
		(end 139.734544 -78.48854)
		(width 0.0889)
		(layer "In9.Cu")
		(net "UPI_CPU0_CPU1_P0P0_DP<19>")
	)
	(arc
		(start 137.158984 -77.002386)
		(mid 137.365988 -77.21325)
		(end 137.649204 -77.297534)
		(width 0.0889)
		(layer "In9.Cu")
		(net "UPI_CPU0_CPU1_P0P0_DP<19>")
	)
	(arc
		(start 138.876024 -77.992986)
		(mid 139.086737 -78.206065)
		(end 139.37488 -78.288388)
		(width 0.0889)
		(layer "In9.Cu")
		(net "UPI_CPU0_CPU1_P0P0_DP<19>")
	)
	(arc
		(start 307.743098 -57.295034)
		(mid 307.5432 -57.095136)
		(end 307.743098 -56.894984)
		(width 0.0889)
		(layer "In9.Cu")
		(net "UPI_CPU0_CPU1_P0P0_DP<19>")
	)
	(arc
		(start 134.58825 -73.543922)
		(mid 134.637005 -73.740274)
		(end 134.583424 -73.935336)
		(width 0.0889)
		(layer "In9.Cu")
		(net "UPI_CPU0_CPU1_P0P0_DP<19>")
	)
	(arc
		(start 134.583424 -73.935336)
		(mid 134.504202 -74.224454)
		(end 134.577074 -74.515218)
		(width 0.0889)
		(layer "In9.Cu")
		(net "UPI_CPU0_CPU1_P0P0_DP<19>")
	)
	(arc
		(start 136.300464 -76.507086)
		(mid 136.509072 -76.719018)
		(end 136.794494 -76.802488)
		(width 0.0889)
		(layer "In9.Cu")
		(net "UPI_CPU0_CPU1_P0P0_DP<19>")
	)
	(segment
		(start 135.953754 -72.744584)
		(end 135.382254 -72.744584)
		(width 0.1143)
		(layer "F.Cu")
		(net "UPI_CPU0_CPU1_P0P0_DP<18>")
	)
	(segment
		(start 307.250846 -58.876438)
		(end 307.898546 -58.876438)
		(width 0.1143)
		(layer "F.Cu")
		(net "UPI_CPU0_CPU1_P0P0_DP<18>")
	)
	(via
		(at 135.953754 -72.744584)
		(size 0.508)
		(drill 0.254)
		(layers "F.Cu" "B.Cu")
		(net "UPI_CPU0_CPU1_P0P0_DP<18>")
	)
	(via
		(at 307.898546 -58.876438)
		(size 0.508)
		(drill 0.254)
		(layers "F.Cu" "B.Cu")
		(net "UPI_CPU0_CPU1_P0P0_DP<18>")
	)
	(segment
		(start 142.819628 -78.791562)
		(end 142.948152 -78.791562)
		(width 0.0889)
		(layer "In9.Cu")
		(net "UPI_CPU0_CPU1_P0P0_DP<18>")
	)
	(segment
		(start 321.633088 -78.477364)
		(end 321.626484 -78.24851)
		(width 0.1143)
		(layer "In9.Cu")
		(net "UPI_CPU0_CPU1_P0P0_DP<18>")
	)
	(segment
		(start 180.746146 -120.636284)
		(end 185.684922 -122.100594)
		(width 0.1143)
		(layer "In9.Cu")
		(net "UPI_CPU0_CPU1_P0P0_DP<18>")
	)
	(segment
		(start 321.498468 -78.854554)
		(end 321.491864 -78.625446)
		(width 0.1143)
		(layer "In9.Cu")
		(net "UPI_CPU0_CPU1_P0P0_DP<18>")
	)
	(segment
		(start 142.548864 -78.698598)
		(end 142.726664 -78.698598)
		(width 0.0889)
		(layer "In9.Cu")
		(net "UPI_CPU0_CPU1_P0P0_DP<18>")
	)
	(segment
		(start 292.482016 -119.437658)
		(end 310.740806 -115.277646)
		(width 0.1143)
		(layer "In9.Cu")
		(net "UPI_CPU0_CPU1_P0P0_DP<18>")
	)
	(segment
		(start 321.653916 -79.224124)
		(end 321.647312 -78.99527)
		(width 0.1143)
		(layer "In9.Cu")
		(net "UPI_CPU0_CPU1_P0P0_DP<18>")
	)
	(segment
		(start 156.720286 -102.642924)
		(end 171.011596 -116.277136)
		(width 0.1143)
		(layer "In9.Cu")
		(net "UPI_CPU0_CPU1_P0P0_DP<18>")
	)
	(segment
		(start 138.518138 -76.611988)
		(end 138.550904 -76.611988)
		(width 0.0889)
		(layer "In9.Cu")
		(net "UPI_CPU0_CPU1_P0P0_DP<18>")
	)
	(segment
		(start 321.564 -76.00823)
		(end 321.415156 -75.867514)
		(width 0.1143)
		(layer "In9.Cu")
		(net "UPI_CPU0_CPU1_P0P0_DP<18>")
	)
	(segment
		(start 321.415156 -75.867514)
		(end 321.408552 -75.638406)
		(width 0.1143)
		(layer "In9.Cu")
		(net "UPI_CPU0_CPU1_P0P0_DP<18>")
	)
	(segment
		(start 141.85392 -78.351634)
		(end 141.979396 -78.47711)
		(width 0.0889)
		(layer "In9.Cu")
		(net "UPI_CPU0_CPU1_P0P0_DP<18>")
	)
	(segment
		(start 142.233396 -78.602586)
		(end 142.233396 -78.73111)
		(width 0.0889)
		(layer "In9.Cu")
		(net "UPI_CPU0_CPU1_P0P0_DP<18>")
	)
	(segment
		(start 317.623444 -64.566038)
		(end 311.22112 -58.8137)
		(width 0.1143)
		(layer "In9.Cu")
		(net "UPI_CPU0_CPU1_P0P0_DP<18>")
	)
	(segment
		(start 323.441314 -103.543608)
		(end 325.03872 -100.640388)
		(width 0.1143)
		(layer "In9.Cu")
		(net "UPI_CPU0_CPU1_P0P0_DP<18>")
	)
	(segment
		(start 267.301218 -118.788688)
		(end 278.01443 -117.759988)
		(width 0.1143)
		(layer "In9.Cu")
		(net "UPI_CPU0_CPU1_P0P0_DP<18>")
	)
	(segment
		(start 321.42938 -76.385166)
		(end 321.570604 -76.237084)
		(width 0.1143)
		(layer "In9.Cu")
		(net "UPI_CPU0_CPU1_P0P0_DP<18>")
	)
	(segment
		(start 321.53352 -80.118966)
		(end 321.674744 -79.970884)
		(width 0.1143)
		(layer "In9.Cu")
		(net "UPI_CPU0_CPU1_P0P0_DP<18>")
	)
	(segment
		(start 135.607044 -74.525886)
		(end 135.602218 -74.534522)
		(width 0.0889)
		(layer "In9.Cu")
		(net "UPI_CPU0_CPU1_P0P0_DP<18>")
	)
	(segment
		(start 258.914138 -118.375176)
		(end 267.301218 -118.788688)
		(width 0.1143)
		(layer "In9.Cu")
		(net "UPI_CPU0_CPU1_P0P0_DP<18>")
	)
	(segment
		(start 321.491864 -78.625446)
		(end 321.633088 -78.477364)
		(width 0.1143)
		(layer "In9.Cu")
		(net "UPI_CPU0_CPU1_P0P0_DP<18>")
	)
	(segment
		(start 142.998952 -78.740762)
		(end 143.02105 -78.740762)
		(width 0.0889)
		(layer "In9.Cu")
		(net "UPI_CPU0_CPU1_P0P0_DP<18>")
	)
	(segment
		(start 325.03872 -100.640388)
		(end 325.23557 -98.050604)
		(width 0.1143)
		(layer "In9.Cu")
		(net "UPI_CPU0_CPU1_P0P0_DP<18>")
	)
	(segment
		(start 193.91884 -121.541286)
		(end 227.798884 -117.4623)
		(width 0.1143)
		(layer "In9.Cu")
		(net "UPI_CPU0_CPU1_P0P0_DP<18>")
	)
	(segment
		(start 156.68752 -102.430834)
		(end 156.688028 -102.434644)
		(width 0.1143)
		(layer "In9.Cu")
		(net "UPI_CPU0_CPU1_P0P0_DP<18>")
	)
	(segment
		(start 144.013682 -78.740762)
		(end 147.54733 -81.89087)
		(width 0.1143)
		(layer "In9.Cu")
		(net "UPI_CPU0_CPU1_P0P0_DP<18>")
	)
	(segment
		(start 141.85392 -78.22311)
		(end 141.85392 -78.351634)
		(width 0.0889)
		(layer "In9.Cu")
		(net "UPI_CPU0_CPU1_P0P0_DP<18>")
	)
	(segment
		(start 156.688028 -102.434644)
		(end 156.720286 -102.642924)
		(width 0.1143)
		(layer "In9.Cu")
		(net "UPI_CPU0_CPU1_P0P0_DP<18>")
	)
	(segment
		(start 325.23557 -98.050604)
		(end 321.693794 -80.659478)
		(width 0.1143)
		(layer "In9.Cu")
		(net "UPI_CPU0_CPU1_P0P0_DP<18>")
	)
	(segment
		(start 149.788372 -90.187272)
		(end 155.915868 -97.438464)
		(width 0.1143)
		(layer "In9.Cu")
		(net "UPI_CPU0_CPU1_P0P0_DP<18>")
	)
	(segment
		(start 142.293848 -78.791562)
		(end 142.4559 -78.791562)
		(width 0.0889)
		(layer "In9.Cu")
		(net "UPI_CPU0_CPU1_P0P0_DP<18>")
	)
	(segment
		(start 278.01443 -117.759988)
		(end 292.482016 -119.437658)
		(width 0.1143)
		(layer "In9.Cu")
		(net "UPI_CPU0_CPU1_P0P0_DP<18>")
	)
	(segment
		(start 142.4559 -78.791562)
		(end 142.548864 -78.698598)
		(width 0.0889)
		(layer "In9.Cu")
		(net "UPI_CPU0_CPU1_P0P0_DP<18>")
	)
	(segment
		(start 135.613394 -74.515218)
		(end 135.607044 -74.525886)
		(width 0.0889)
		(layer "In9.Cu")
		(net "UPI_CPU0_CPU1_P0P0_DP<18>")
	)
	(segment
		(start 321.408552 -75.638406)
		(end 321.549776 -75.49007)
		(width 0.1143)
		(layer "In9.Cu")
		(net "UPI_CPU0_CPU1_P0P0_DP<18>")
	)
	(segment
		(start 321.549776 -75.49007)
		(end 321.537076 -75.0062)
		(width 0.1143)
		(layer "In9.Cu")
		(net "UPI_CPU0_CPU1_P0P0_DP<18>")
	)
	(segment
		(start 310.740806 -115.277646)
		(end 323.441314 -103.543608)
		(width 0.1143)
		(layer "In9.Cu")
		(net "UPI_CPU0_CPU1_P0P0_DP<18>")
	)
	(segment
		(start 137.655808 -76.116434)
		(end 137.688574 -76.116434)
		(width 0.0889)
		(layer "In9.Cu")
		(net "UPI_CPU0_CPU1_P0P0_DP<18>")
	)
	(segment
		(start 147.54733 -81.89087)
		(end 149.788372 -90.187272)
		(width 0.1143)
		(layer "In9.Cu")
		(net "UPI_CPU0_CPU1_P0P0_DP<18>")
	)
	(segment
		(start 140.235178 -77.602588)
		(end 140.449554 -77.602588)
		(width 0.0889)
		(layer "In9.Cu")
		(net "UPI_CPU0_CPU1_P0P0_DP<18>")
	)
	(segment
		(start 321.688968 -80.48879)
		(end 321.540124 -80.348074)
		(width 0.1143)
		(layer "In9.Cu")
		(net "UPI_CPU0_CPU1_P0P0_DP<18>")
	)
	(segment
		(start 136.801098 -75.621388)
		(end 136.833864 -75.621388)
		(width 0.0889)
		(layer "In9.Cu")
		(net "UPI_CPU0_CPU1_P0P0_DP<18>")
	)
	(segment
		(start 321.570604 -76.237084)
		(end 321.564 -76.00823)
		(width 0.1143)
		(layer "In9.Cu")
		(net "UPI_CPU0_CPU1_P0P0_DP<18>")
	)
	(segment
		(start 321.540124 -80.348074)
		(end 321.53352 -80.118966)
		(width 0.1143)
		(layer "In9.Cu")
		(net "UPI_CPU0_CPU1_P0P0_DP<18>")
	)
	(segment
		(start 321.605656 -77.50175)
		(end 321.456812 -77.361034)
		(width 0.1143)
		(layer "In9.Cu")
		(net "UPI_CPU0_CPU1_P0P0_DP<18>")
	)
	(segment
		(start 321.66814 -79.74203)
		(end 321.519296 -79.601314)
		(width 0.1143)
		(layer "In9.Cu")
		(net "UPI_CPU0_CPU1_P0P0_DP<18>")
	)
	(segment
		(start 321.647312 -78.99527)
		(end 321.498468 -78.854554)
		(width 0.1143)
		(layer "In9.Cu")
		(net "UPI_CPU0_CPU1_P0P0_DP<18>")
	)
	(segment
		(start 185.684922 -122.100594)
		(end 193.91884 -121.541286)
		(width 0.1143)
		(layer "In9.Cu")
		(net "UPI_CPU0_CPU1_P0P0_DP<18>")
	)
	(segment
		(start 142.10792 -78.47711)
		(end 142.233396 -78.602586)
		(width 0.0889)
		(layer "In9.Cu")
		(net "UPI_CPU0_CPU1_P0P0_DP<18>")
	)
	(segment
		(start 135.607044 -73.535286)
		(end 135.602218 -73.543922)
		(width 0.0889)
		(layer "In9.Cu")
		(net "UPI_CPU0_CPU1_P0P0_DP<18>")
	)
	(segment
		(start 248.106946 -120.921272)
		(end 258.914138 -118.375176)
		(width 0.1143)
		(layer "In9.Cu")
		(net "UPI_CPU0_CPU1_P0P0_DP<18>")
	)
	(segment
		(start 321.512692 -79.372206)
		(end 321.653916 -79.224124)
		(width 0.1143)
		(layer "In9.Cu")
		(net "UPI_CPU0_CPU1_P0P0_DP<18>")
	)
	(segment
		(start 156.68752 -102.429056)
		(end 156.68752 -102.430834)
		(width 0.1143)
		(layer "In9.Cu")
		(net "UPI_CPU0_CPU1_P0P0_DP<18>")
	)
	(segment
		(start 321.61226 -77.730604)
		(end 321.605656 -77.50175)
		(width 0.1143)
		(layer "In9.Cu")
		(net "UPI_CPU0_CPU1_P0P0_DP<18>")
	)
	(segment
		(start 155.915868 -97.438464)
		(end 156.68752 -102.429056)
		(width 0.1143)
		(layer "In9.Cu")
		(net "UPI_CPU0_CPU1_P0P0_DP<18>")
	)
	(segment
		(start 321.591432 -76.983844)
		(end 321.584828 -76.75499)
		(width 0.1143)
		(layer "In9.Cu")
		(net "UPI_CPU0_CPU1_P0P0_DP<18>")
	)
	(segment
		(start 321.584828 -76.75499)
		(end 321.435984 -76.614274)
		(width 0.1143)
		(layer "In9.Cu")
		(net "UPI_CPU0_CPU1_P0P0_DP<18>")
	)
	(segment
		(start 227.798884 -117.4623)
		(end 248.106946 -120.921272)
		(width 0.1143)
		(layer "In9.Cu")
		(net "UPI_CPU0_CPU1_P0P0_DP<18>")
	)
	(segment
		(start 142.948152 -78.791562)
		(end 142.998952 -78.740762)
		(width 0.0889)
		(layer "In9.Cu")
		(net "UPI_CPU0_CPU1_P0P0_DP<18>")
	)
	(segment
		(start 321.435984 -76.614274)
		(end 321.42938 -76.385166)
		(width 0.1143)
		(layer "In9.Cu")
		(net "UPI_CPU0_CPU1_P0P0_DP<18>")
	)
	(segment
		(start 142.233396 -78.73111)
		(end 142.293848 -78.791562)
		(width 0.0889)
		(layer "In9.Cu")
		(net "UPI_CPU0_CPU1_P0P0_DP<18>")
	)
	(segment
		(start 135.613394 -73.524618)
		(end 135.607044 -73.535286)
		(width 0.0889)
		(layer "In9.Cu")
		(net "UPI_CPU0_CPU1_P0P0_DP<18>")
	)
	(segment
		(start 308.24805 -58.526934)
		(end 307.898546 -58.876438)
		(width 0.1143)
		(layer "In9.Cu")
		(net "UPI_CPU0_CPU1_P0P0_DP<18>")
	)
	(segment
		(start 308.74335 -58.8137)
		(end 308.456584 -58.526934)
		(width 0.1143)
		(layer "In9.Cu")
		(net "UPI_CPU0_CPU1_P0P0_DP<18>")
	)
	(segment
		(start 142.726664 -78.698598)
		(end 142.819628 -78.791562)
		(width 0.0889)
		(layer "In9.Cu")
		(net "UPI_CPU0_CPU1_P0P0_DP<18>")
	)
	(segment
		(start 321.537076 -75.0062)
		(end 317.623444 -64.566038)
		(width 0.1143)
		(layer "In9.Cu")
		(net "UPI_CPU0_CPU1_P0P0_DP<18>")
	)
	(segment
		(start 140.987526 -78.085442)
		(end 141.143228 -78.097634)
		(width 0.0889)
		(layer "In9.Cu")
		(net "UPI_CPU0_CPU1_P0P0_DP<18>")
	)
	(segment
		(start 321.471036 -77.878686)
		(end 321.61226 -77.730604)
		(width 0.1143)
		(layer "In9.Cu")
		(net "UPI_CPU0_CPU1_P0P0_DP<18>")
	)
	(segment
		(start 321.47764 -78.107794)
		(end 321.471036 -77.878686)
		(width 0.1143)
		(layer "In9.Cu")
		(net "UPI_CPU0_CPU1_P0P0_DP<18>")
	)
	(segment
		(start 141.979396 -78.47711)
		(end 142.10792 -78.47711)
		(width 0.0889)
		(layer "In9.Cu")
		(net "UPI_CPU0_CPU1_P0P0_DP<18>")
	)
	(segment
		(start 321.674744 -79.970884)
		(end 321.66814 -79.74203)
		(width 0.1143)
		(layer "In9.Cu")
		(net "UPI_CPU0_CPU1_P0P0_DP<18>")
	)
	(segment
		(start 135.938768 -75.125834)
		(end 135.971534 -75.125834)
		(width 0.0889)
		(layer "In9.Cu")
		(net "UPI_CPU0_CPU1_P0P0_DP<18>")
	)
	(segment
		(start 141.728444 -78.097634)
		(end 141.85392 -78.22311)
		(width 0.0889)
		(layer "In9.Cu")
		(net "UPI_CPU0_CPU1_P0P0_DP<18>")
	)
	(segment
		(start 308.456584 -58.526934)
		(end 308.24805 -58.526934)
		(width 0.1143)
		(layer "In9.Cu")
		(net "UPI_CPU0_CPU1_P0P0_DP<18>")
	)
	(segment
		(start 321.456812 -77.361034)
		(end 321.450208 -77.131926)
		(width 0.1143)
		(layer "In9.Cu")
		(net "UPI_CPU0_CPU1_P0P0_DP<18>")
	)
	(segment
		(start 311.22112 -58.8137)
		(end 308.74335 -58.8137)
		(width 0.1143)
		(layer "In9.Cu")
		(net "UPI_CPU0_CPU1_P0P0_DP<18>")
	)
	(segment
		(start 321.519296 -79.601314)
		(end 321.512692 -79.372206)
		(width 0.1143)
		(layer "In9.Cu")
		(net "UPI_CPU0_CPU1_P0P0_DP<18>")
	)
	(segment
		(start 321.626484 -78.24851)
		(end 321.47764 -78.107794)
		(width 0.1143)
		(layer "In9.Cu")
		(net "UPI_CPU0_CPU1_P0P0_DP<18>")
	)
	(segment
		(start 143.02105 -78.740762)
		(end 144.013682 -78.740762)
		(width 0.1143)
		(layer "In9.Cu")
		(net "UPI_CPU0_CPU1_P0P0_DP<18>")
	)
	(segment
		(start 141.143228 -78.097634)
		(end 141.728444 -78.097634)
		(width 0.0889)
		(layer "In9.Cu")
		(net "UPI_CPU0_CPU1_P0P0_DP<18>")
	)
	(segment
		(start 171.011596 -116.277136)
		(end 180.746146 -120.636284)
		(width 0.1143)
		(layer "In9.Cu")
		(net "UPI_CPU0_CPU1_P0P0_DP<18>")
	)
	(segment
		(start 321.450208 -77.131926)
		(end 321.591432 -76.983844)
		(width 0.1143)
		(layer "In9.Cu")
		(net "UPI_CPU0_CPU1_P0P0_DP<18>")
	)
	(segment
		(start 139.372848 -77.107034)
		(end 139.405614 -77.107034)
		(width 0.0889)
		(layer "In9.Cu")
		(net "UPI_CPU0_CPU1_P0P0_DP<18>")
	)
	(segment
		(start 321.693794 -80.659478)
		(end 321.688968 -80.48879)
		(width 0.1143)
		(layer "In9.Cu")
		(net "UPI_CPU0_CPU1_P0P0_DP<18>")
	)
	(arc
		(start 135.602218 -73.543922)
		(mid 135.553463 -73.740274)
		(end 135.607044 -73.935336)
		(width 0.0889)
		(layer "In9.Cu")
		(net "UPI_CPU0_CPU1_P0P0_DP<18>")
	)
	(arc
		(start 135.607044 -73.935336)
		(mid 135.686266 -74.224454)
		(end 135.613394 -74.515218)
		(width 0.0889)
		(layer "In9.Cu")
		(net "UPI_CPU0_CPU1_P0P0_DP<18>")
	)
	(arc
		(start 136.465564 -75.421236)
		(mid 136.607247 -75.56504)
		(end 136.801098 -75.621388)
		(width 0.0889)
		(layer "In9.Cu")
		(net "UPI_CPU0_CPU1_P0P0_DP<18>")
	)
	(arc
		(start 135.971534 -75.125834)
		(mid 136.256958 -75.209301)
		(end 136.465564 -75.421236)
		(width 0.0889)
		(layer "In9.Cu")
		(net "UPI_CPU0_CPU1_P0P0_DP<18>")
	)
	(arc
		(start 140.798042 -77.90053)
		(mid 140.878319 -78.00781)
		(end 140.987526 -78.085442)
		(width 0.0889)
		(layer "In9.Cu")
		(net "UPI_CPU0_CPU1_P0P0_DP<18>")
	)
	(arc
		(start 140.449554 -77.602588)
		(mid 140.652148 -77.718406)
		(end 140.798042 -77.90053)
		(width 0.0889)
		(layer "In9.Cu")
		(net "UPI_CPU0_CPU1_P0P0_DP<18>")
	)
	(arc
		(start 139.041124 -76.907136)
		(mid 139.181203 -77.049872)
		(end 139.372848 -77.107034)
		(width 0.0889)
		(layer "In9.Cu")
		(net "UPI_CPU0_CPU1_P0P0_DP<18>")
	)
	(arc
		(start 136.833864 -75.621388)
		(mid 137.117081 -75.705669)
		(end 137.324084 -75.916536)
		(width 0.0889)
		(layer "In9.Cu")
		(net "UPI_CPU0_CPU1_P0P0_DP<18>")
	)
	(arc
		(start 139.899644 -77.402436)
		(mid 140.041327 -77.54624)
		(end 140.235178 -77.602588)
		(width 0.0889)
		(layer "In9.Cu")
		(net "UPI_CPU0_CPU1_P0P0_DP<18>")
	)
	(arc
		(start 135.602218 -74.534522)
		(mid 135.605965 -74.923778)
		(end 135.938768 -75.125834)
		(width 0.0889)
		(layer "In9.Cu")
		(net "UPI_CPU0_CPU1_P0P0_DP<18>")
	)
	(arc
		(start 138.550904 -76.611988)
		(mid 138.834121 -76.696269)
		(end 139.041124 -76.907136)
		(width 0.0889)
		(layer "In9.Cu")
		(net "UPI_CPU0_CPU1_P0P0_DP<18>")
	)
	(arc
		(start 135.953754 -72.744584)
		(mid 135.753348 -72.5457)
		(end 135.553704 -72.7456)
		(width 0.0889)
		(layer "In9.Cu")
		(net "UPI_CPU0_CPU1_P0P0_DP<18>")
	)
	(arc
		(start 137.324084 -75.916536)
		(mid 137.464163 -76.059272)
		(end 137.655808 -76.116434)
		(width 0.0889)
		(layer "In9.Cu")
		(net "UPI_CPU0_CPU1_P0P0_DP<18>")
	)
	(arc
		(start 137.688574 -76.116434)
		(mid 137.973998 -76.199901)
		(end 138.182604 -76.411836)
		(width 0.0889)
		(layer "In9.Cu")
		(net "UPI_CPU0_CPU1_P0P0_DP<18>")
	)
	(arc
		(start 135.607044 -72.944736)
		(mid 135.686266 -73.233854)
		(end 135.613394 -73.524618)
		(width 0.0889)
		(layer "In9.Cu")
		(net "UPI_CPU0_CPU1_P0P0_DP<18>")
	)
	(arc
		(start 135.553704 -72.7456)
		(mid 135.567334 -72.848661)
		(end 135.607044 -72.944736)
		(width 0.0889)
		(layer "In9.Cu")
		(net "UPI_CPU0_CPU1_P0P0_DP<18>")
	)
	(arc
		(start 138.182604 -76.411836)
		(mid 138.324287 -76.55564)
		(end 138.518138 -76.611988)
		(width 0.0889)
		(layer "In9.Cu")
		(net "UPI_CPU0_CPU1_P0P0_DP<18>")
	)
	(arc
		(start 139.405614 -77.107034)
		(mid 139.691038 -77.190501)
		(end 139.899644 -77.402436)
		(width 0.0889)
		(layer "In9.Cu")
		(net "UPI_CPU0_CPU1_P0P0_DP<18>")
	)
	(segment
		(start 305.533806 -60.857384)
		(end 306.105306 -60.857384)
		(width 0.1143)
		(layer "F.Cu")
		(net "UPI_CPU0_CPU1_P0P0_DP<17>")
	)
	(segment
		(start 135.953754 -71.753984)
		(end 135.382254 -71.753984)
		(width 0.1143)
		(layer "F.Cu")
		(net "UPI_CPU0_CPU1_P0P0_DP<17>")
	)
	(via
		(at 306.105306 -60.857384)
		(size 0.508)
		(drill 0.254)
		(layers "F.Cu" "B.Cu")
		(net "UPI_CPU0_CPU1_P0P0_DP<17>")
	)
	(via
		(at 135.953754 -71.753984)
		(size 0.508)
		(drill 0.254)
		(layers "F.Cu" "B.Cu")
		(net "UPI_CPU0_CPU1_P0P0_DP<17>")
	)
	(segment
		(start 145.367248 -77.988414)
		(end 147.801584 -80.389222)
		(width 0.1143)
		(layer "In9.Cu")
		(net "UPI_CPU0_CPU1_P0P0_DP<17>")
	)
	(segment
		(start 143.431768 -77.950314)
		(end 143.609568 -77.950314)
		(width 0.0889)
		(layer "In9.Cu")
		(net "UPI_CPU0_CPU1_P0P0_DP<17>")
	)
	(segment
		(start 227.859844 -116.825776)
		(end 248.085864 -120.270778)
		(width 0.1143)
		(layer "In9.Cu")
		(net "UPI_CPU0_CPU1_P0P0_DP<17>")
	)
	(segment
		(start 324.413118 -100.454206)
		(end 324.59295 -98.090736)
		(width 0.1143)
		(layer "In9.Cu")
		(net "UPI_CPU0_CPU1_P0P0_DP<17>")
	)
	(segment
		(start 320.770504 -75.781408)
		(end 320.7639 -75.5523)
		(width 0.1143)
		(layer "In9.Cu")
		(net "UPI_CPU0_CPU1_P0P0_DP<17>")
	)
	(segment
		(start 140.235178 -76.611988)
		(end 140.449554 -76.611988)
		(width 0.0889)
		(layer "In9.Cu")
		(net "UPI_CPU0_CPU1_P0P0_DP<17>")
	)
	(segment
		(start 320.82486 -77.752956)
		(end 320.683128 -77.61859)
		(width 0.1143)
		(layer "In9.Cu")
		(net "UPI_CPU0_CPU1_P0P0_DP<17>")
	)
	(segment
		(start 142.44066 -77.83576)
		(end 142.644114 -78.039214)
		(width 0.0889)
		(layer "In9.Cu")
		(net "UPI_CPU0_CPU1_P0P0_DP<17>")
	)
	(segment
		(start 324.59295 -98.090736)
		(end 323.714364 -93.7768)
		(width 0.1143)
		(layer "In9.Cu")
		(net "UPI_CPU0_CPU1_P0P0_DP<17>")
	)
	(segment
		(start 320.790824 -76.51496)
		(end 320.78422 -76.285852)
		(width 0.1143)
		(layer "In9.Cu")
		(net "UPI_CPU0_CPU1_P0P0_DP<17>")
	)
	(segment
		(start 317.081662 -64.937132)
		(end 311.394602 -59.826398)
		(width 0.1143)
		(layer "In9.Cu")
		(net "UPI_CPU0_CPU1_P0P0_DP<17>")
	)
	(segment
		(start 258.855464 -117.733826)
		(end 267.286232 -118.14937)
		(width 0.1143)
		(layer "In9.Cu")
		(net "UPI_CPU0_CPU1_P0P0_DP<17>")
	)
	(segment
		(start 323.714364 -93.7768)
		(end 323.625718 -93.341444)
		(width 0.1143)
		(layer "In9.Cu")
		(net "UPI_CPU0_CPU1_P0P0_DP<17>")
	)
	(segment
		(start 308.35092 -59.405774)
		(end 308.28996 -59.466734)
		(width 0.0889)
		(layer "In9.Cu")
		(net "UPI_CPU0_CPU1_P0P0_DP<17>")
	)
	(segment
		(start 143.965168 -77.950314)
		(end 144.142968 -77.950314)
		(width 0.0889)
		(layer "In9.Cu")
		(net "UPI_CPU0_CPU1_P0P0_DP<17>")
	)
	(segment
		(start 310.432958 -114.693954)
		(end 322.79971 -103.265732)
		(width 0.1143)
		(layer "In9.Cu")
		(net "UPI_CPU0_CPU1_P0P0_DP<17>")
	)
	(segment
		(start 306.17033 -60.454286)
		(end 306.105306 -60.51931)
		(width 0.0889)
		(layer "In9.Cu")
		(net "UPI_CPU0_CPU1_P0P0_DP<17>")
	)
	(segment
		(start 320.757804 -79.8322)
		(end 320.744088 -79.819246)
		(width 0.1143)
		(layer "In9.Cu")
		(net "UPI_CPU0_CPU1_P0P0_DP<17>")
	)
	(segment
		(start 309.759096 -59.405774)
		(end 308.35092 -59.405774)
		(width 0.0889)
		(layer "In9.Cu")
		(net "UPI_CPU0_CPU1_P0P0_DP<17>")
	)
	(segment
		(start 267.286232 -118.14937)
		(end 278.021034 -117.118638)
		(width 0.1143)
		(layer "In9.Cu")
		(net "UPI_CPU0_CPU1_P0P0_DP<17>")
	)
	(segment
		(start 306.105306 -60.51931)
		(end 306.105306 -60.857384)
		(width 0.0889)
		(layer "In9.Cu")
		(net "UPI_CPU0_CPU1_P0P0_DP<17>")
	)
	(segment
		(start 309.831994 -59.456574)
		(end 309.809896 -59.456574)
		(width 0.0889)
		(layer "In9.Cu")
		(net "UPI_CPU0_CPU1_P0P0_DP<17>")
	)
	(segment
		(start 322.89115 -103.18115)
		(end 322.935854 -103.139748)
		(width 0.1143)
		(layer "In9.Cu")
		(net "UPI_CPU0_CPU1_P0P0_DP<17>")
	)
	(segment
		(start 164.277548 -108.88599)
		(end 164.277548 -108.886244)
		(width 0.1143)
		(layer "In9.Cu")
		(net "UPI_CPU0_CPU1_P0P0_DP<17>")
	)
	(segment
		(start 143.698468 -78.039214)
		(end 143.876268 -78.039214)
		(width 0.0889)
		(layer "In9.Cu")
		(net "UPI_CPU0_CPU1_P0P0_DP<17>")
	)
	(segment
		(start 142.31493 -77.580998)
		(end 142.44066 -77.706728)
		(width 0.0889)
		(layer "In9.Cu")
		(net "UPI_CPU0_CPU1_P0P0_DP<17>")
	)
	(segment
		(start 320.744088 -79.819246)
		(end 320.737484 -79.590646)
		(width 0.1143)
		(layer "In9.Cu")
		(net "UPI_CPU0_CPU1_P0P0_DP<17>")
	)
	(segment
		(start 320.737484 -79.590646)
		(end 320.872104 -79.449168)
		(width 0.1143)
		(layer "In9.Cu")
		(net "UPI_CPU0_CPU1_P0P0_DP<17>")
	)
	(segment
		(start 143.076168 -77.950314)
		(end 143.165068 -78.039214)
		(width 0.0889)
		(layer "In9.Cu")
		(net "UPI_CPU0_CPU1_P0P0_DP<17>")
	)
	(segment
		(start 320.90614 -80.687164)
		(end 320.764408 -80.552798)
		(width 0.1143)
		(layer "In9.Cu")
		(net "UPI_CPU0_CPU1_P0P0_DP<17>")
	)
	(segment
		(start 320.7639 -75.5523)
		(end 320.622168 -75.417934)
		(width 0.1143)
		(layer "In9.Cu")
		(net "UPI_CPU0_CPU1_P0P0_DP<17>")
	)
	(segment
		(start 320.764408 -80.552798)
		(end 320.757804 -80.324198)
		(width 0.1143)
		(layer "In9.Cu")
		(net "UPI_CPU0_CPU1_P0P0_DP<17>")
	)
	(segment
		(start 320.615564 -75.189334)
		(end 320.750184 -75.047856)
		(width 0.1143)
		(layer "In9.Cu")
		(net "UPI_CPU0_CPU1_P0P0_DP<17>")
	)
	(segment
		(start 144.765268 -78.039214)
		(end 144.981168 -78.039214)
		(width 0.0889)
		(layer "In9.Cu")
		(net "UPI_CPU0_CPU1_P0P0_DP<17>")
	)
	(segment
		(start 138.518138 -75.621388)
		(end 138.550904 -75.621388)
		(width 0.0889)
		(layer "In9.Cu")
		(net "UPI_CPU0_CPU1_P0P0_DP<17>")
	)
	(segment
		(start 320.740278 -74.695558)
		(end 318.39027 -68.4276)
		(width 0.1143)
		(layer "In9.Cu")
		(net "UPI_CPU0_CPU1_P0P0_DP<17>")
	)
	(segment
		(start 320.745358 -74.871834)
		(end 320.745358 -74.872088)
		(width 0.1143)
		(layer "In9.Cu")
		(net "UPI_CPU0_CPU1_P0P0_DP<17>")
	)
	(segment
		(start 144.676368 -77.950314)
		(end 144.765268 -78.039214)
		(width 0.0889)
		(layer "In9.Cu")
		(net "UPI_CPU0_CPU1_P0P0_DP<17>")
	)
	(segment
		(start 320.662808 -76.885038)
		(end 320.656204 -76.656438)
		(width 0.1143)
		(layer "In9.Cu")
		(net "UPI_CPU0_CPU1_P0P0_DP<17>")
	)
	(segment
		(start 320.676524 -77.38999)
		(end 320.811144 -77.248512)
		(width 0.1143)
		(layer "In9.Cu")
		(net "UPI_CPU0_CPU1_P0P0_DP<17>")
	)
	(segment
		(start 320.872104 -79.449168)
		(end 320.8655 -79.22006)
		(width 0.1143)
		(layer "In9.Cu")
		(net "UPI_CPU0_CPU1_P0P0_DP<17>")
	)
	(segment
		(start 139.372848 -76.116434)
		(end 139.405614 -76.116434)
		(width 0.0889)
		(layer "In9.Cu")
		(net "UPI_CPU0_CPU1_P0P0_DP<17>")
	)
	(segment
		(start 142.060168 -77.455268)
		(end 142.185898 -77.580998)
		(width 0.0889)
		(layer "In9.Cu")
		(net "UPI_CPU0_CPU1_P0P0_DP<17>")
	)
	(segment
		(start 143.342868 -78.039214)
		(end 143.431768 -77.950314)
		(width 0.0889)
		(layer "In9.Cu")
		(net "UPI_CPU0_CPU1_P0P0_DP<17>")
	)
	(segment
		(start 141.934438 -77.200506)
		(end 142.060168 -77.326236)
		(width 0.0889)
		(layer "In9.Cu")
		(net "UPI_CPU0_CPU1_P0P0_DP<17>")
	)
	(segment
		(start 311.394602 -59.826398)
		(end 310.982868 -59.456574)
		(width 0.1143)
		(layer "In9.Cu")
		(net "UPI_CPU0_CPU1_P0P0_DP<17>")
	)
	(segment
		(start 142.809468 -78.039214)
		(end 142.898368 -77.950314)
		(width 0.0889)
		(layer "In9.Cu")
		(net "UPI_CPU0_CPU1_P0P0_DP<17>")
	)
	(segment
		(start 136.465564 -73.440036)
		(end 136.471914 -73.450704)
		(width 0.0889)
		(layer "In9.Cu")
		(net "UPI_CPU0_CPU1_P0P0_DP<17>")
	)
	(segment
		(start 142.44066 -77.706728)
		(end 142.44066 -77.83576)
		(width 0.0889)
		(layer "In9.Cu")
		(net "UPI_CPU0_CPU1_P0P0_DP<17>")
	)
	(segment
		(start 320.84518 -78.486508)
		(end 320.703448 -78.352142)
		(width 0.1143)
		(layer "In9.Cu")
		(net "UPI_CPU0_CPU1_P0P0_DP<17>")
	)
	(segment
		(start 143.609568 -77.950314)
		(end 143.698468 -78.039214)
		(width 0.0889)
		(layer "In9.Cu")
		(net "UPI_CPU0_CPU1_P0P0_DP<17>")
	)
	(segment
		(start 320.78422 -76.285852)
		(end 320.642488 -76.151486)
		(width 0.1143)
		(layer "In9.Cu")
		(net "UPI_CPU0_CPU1_P0P0_DP<17>")
	)
	(segment
		(start 145.054066 -77.988414)
		(end 145.367248 -77.988414)
		(width 0.1143)
		(layer "In9.Cu")
		(net "UPI_CPU0_CPU1_P0P0_DP<17>")
	)
	(segment
		(start 135.938768 -72.154034)
		(end 135.971534 -72.154034)
		(width 0.0889)
		(layer "In9.Cu")
		(net "UPI_CPU0_CPU1_P0P0_DP<17>")
	)
	(segment
		(start 181.13248 -120.088406)
		(end 183.700928 -120.849136)
		(width 0.1143)
		(layer "In9.Cu")
		(net "UPI_CPU0_CPU1_P0P0_DP<17>")
	)
	(segment
		(start 135.953754 -71.753984)
		(end 135.953754 -71.41591)
		(width 0.0889)
		(layer "In9.Cu")
		(net "UPI_CPU0_CPU1_P0P0_DP<17>")
	)
	(segment
		(start 147.801584 -80.389222)
		(end 150.382224 -89.902284)
		(width 0.1143)
		(layer "In9.Cu")
		(net "UPI_CPU0_CPU1_P0P0_DP<17>")
	)
	(segment
		(start 320.683128 -77.61859)
		(end 320.676524 -77.38999)
		(width 0.1143)
		(layer "In9.Cu")
		(net "UPI_CPU0_CPU1_P0P0_DP<17>")
	)
	(segment
		(start 320.656204 -76.656438)
		(end 320.790824 -76.51496)
		(width 0.1143)
		(layer "In9.Cu")
		(net "UPI_CPU0_CPU1_P0P0_DP<17>")
	)
	(segment
		(start 143.165068 -78.039214)
		(end 143.342868 -78.039214)
		(width 0.0889)
		(layer "In9.Cu")
		(net "UPI_CPU0_CPU1_P0P0_DP<17>")
	)
	(segment
		(start 321.42557 -82.537046)
		(end 321.189096 -81.915)
		(width 0.1143)
		(layer "In9.Cu")
		(net "UPI_CPU0_CPU1_P0P0_DP<17>")
	)
	(segment
		(start 292.44671 -118.791736)
		(end 310.432958 -114.693954)
		(width 0.1143)
		(layer "In9.Cu")
		(net "UPI_CPU0_CPU1_P0P0_DP<17>")
	)
	(segment
		(start 291.125402 -118.638574)
		(end 292.44671 -118.791736)
		(width 0.1143)
		(layer "In9.Cu")
		(net "UPI_CPU0_CPU1_P0P0_DP<17>")
	)
	(segment
		(start 320.750184 -75.047856)
		(end 320.745358 -74.871834)
		(width 0.1143)
		(layer "In9.Cu")
		(net "UPI_CPU0_CPU1_P0P0_DP<17>")
	)
	(segment
		(start 142.644114 -78.039214)
		(end 142.809468 -78.039214)
		(width 0.0889)
		(layer "In9.Cu")
		(net "UPI_CPU0_CPU1_P0P0_DP<17>")
	)
	(segment
		(start 320.851784 -78.715616)
		(end 320.84518 -78.486508)
		(width 0.1143)
		(layer "In9.Cu")
		(net "UPI_CPU0_CPU1_P0P0_DP<17>")
	)
	(segment
		(start 144.498568 -77.950314)
		(end 144.676368 -77.950314)
		(width 0.0889)
		(layer "In9.Cu")
		(net "UPI_CPU0_CPU1_P0P0_DP<17>")
	)
	(segment
		(start 310.982868 -59.456574)
		(end 309.831994 -59.456574)
		(width 0.1143)
		(layer "In9.Cu")
		(net "UPI_CPU0_CPU1_P0P0_DP<17>")
	)
	(segment
		(start 307.731668 -59.466734)
		(end 307.73116 -59.466988)
		(width 0.0889)
		(layer "In9.Cu")
		(net "UPI_CPU0_CPU1_P0P0_DP<17>")
	)
	(segment
		(start 145.031968 -77.988414)
		(end 145.054066 -77.988414)
		(width 0.0889)
		(layer "In9.Cu")
		(net "UPI_CPU0_CPU1_P0P0_DP<17>")
	)
	(segment
		(start 136.460738 -73.4314)
		(end 136.465564 -73.440036)
		(width 0.0889)
		(layer "In9.Cu")
		(net "UPI_CPU0_CPU1_P0P0_DP<17>")
	)
	(segment
		(start 320.622168 -75.417934)
		(end 320.615564 -75.189334)
		(width 0.1143)
		(layer "In9.Cu")
		(net "UPI_CPU0_CPU1_P0P0_DP<17>")
	)
	(segment
		(start 137.655808 -75.125834)
		(end 137.688574 -75.125834)
		(width 0.0889)
		(layer "In9.Cu")
		(net "UPI_CPU0_CPU1_P0P0_DP<17>")
	)
	(segment
		(start 164.277548 -108.886244)
		(end 171.518072 -115.793774)
		(width 0.1143)
		(layer "In9.Cu")
		(net "UPI_CPU0_CPU1_P0P0_DP<17>")
	)
	(segment
		(start 141.014196 -77.107034)
		(end 141.711934 -77.107034)
		(width 0.0889)
		(layer "In9.Cu")
		(net "UPI_CPU0_CPU1_P0P0_DP<17>")
	)
	(segment
		(start 194.4878 -120.843548)
		(end 227.859844 -116.825776)
		(width 0.1143)
		(layer "In9.Cu")
		(net "UPI_CPU0_CPU1_P0P0_DP<17>")
	)
	(segment
		(start 136.801098 -74.630788)
		(end 136.833864 -74.630788)
		(width 0.0889)
		(layer "In9.Cu")
		(net "UPI_CPU0_CPU1_P0P0_DP<17>")
	)
	(segment
		(start 320.8655 -79.22006)
		(end 320.723768 -79.085694)
		(width 0.1143)
		(layer "In9.Cu")
		(net "UPI_CPU0_CPU1_P0P0_DP<17>")
	)
	(segment
		(start 320.745358 -74.872088)
		(end 320.740278 -74.695558)
		(width 0.1143)
		(layer "In9.Cu")
		(net "UPI_CPU0_CPU1_P0P0_DP<17>")
	)
	(segment
		(start 318.39027 -68.4276)
		(end 317.081662 -64.937132)
		(width 0.1143)
		(layer "In9.Cu")
		(net "UPI_CPU0_CPU1_P0P0_DP<17>")
	)
	(segment
		(start 278.021034 -117.118638)
		(end 291.125402 -118.638574)
		(width 0.1143)
		(layer "In9.Cu")
		(net "UPI_CPU0_CPU1_P0P0_DP<17>")
	)
	(segment
		(start 185.694828 -121.43994)
		(end 194.4878 -120.843548)
		(width 0.1143)
		(layer "In9.Cu")
		(net "UPI_CPU0_CPU1_P0P0_DP<17>")
	)
	(segment
		(start 144.231868 -78.039214)
		(end 144.409668 -78.039214)
		(width 0.0889)
		(layer "In9.Cu")
		(net "UPI_CPU0_CPU1_P0P0_DP<17>")
	)
	(segment
		(start 320.831464 -77.982064)
		(end 320.82486 -77.752956)
		(width 0.1143)
		(layer "In9.Cu")
		(net "UPI_CPU0_CPU1_P0P0_DP<17>")
	)
	(segment
		(start 324.413372 -100.454206)
		(end 324.413118 -100.454206)
		(width 0.1143)
		(layer "In9.Cu")
		(net "UPI_CPU0_CPU1_P0P0_DP<17>")
	)
	(segment
		(start 171.518072 -115.793774)
		(end 175.475392 -117.56136)
		(width 0.1143)
		(layer "In9.Cu")
		(net "UPI_CPU0_CPU1_P0P0_DP<17>")
	)
	(segment
		(start 320.723768 -79.085694)
		(end 320.717164 -78.857094)
		(width 0.1143)
		(layer "In9.Cu")
		(net "UPI_CPU0_CPU1_P0P0_DP<17>")
	)
	(segment
		(start 144.142968 -77.950314)
		(end 144.231868 -78.039214)
		(width 0.0889)
		(layer "In9.Cu")
		(net "UPI_CPU0_CPU1_P0P0_DP<17>")
	)
	(segment
		(start 323.625718 -93.341444)
		(end 321.42557 -82.537046)
		(width 0.1143)
		(layer "In9.Cu")
		(net "UPI_CPU0_CPU1_P0P0_DP<17>")
	)
	(segment
		(start 141.711934 -77.107034)
		(end 141.805406 -77.200506)
		(width 0.0889)
		(layer "In9.Cu")
		(net "UPI_CPU0_CPU1_P0P0_DP<17>")
	)
	(segment
		(start 320.635884 -75.922886)
		(end 320.770504 -75.781408)
		(width 0.1143)
		(layer "In9.Cu")
		(net "UPI_CPU0_CPU1_P0P0_DP<17>")
	)
	(segment
		(start 144.409668 -78.039214)
		(end 144.498568 -77.950314)
		(width 0.0889)
		(layer "In9.Cu")
		(net "UPI_CPU0_CPU1_P0P0_DP<17>")
	)
	(segment
		(start 309.809896 -59.456574)
		(end 309.759096 -59.405774)
		(width 0.0889)
		(layer "In9.Cu")
		(net "UPI_CPU0_CPU1_P0P0_DP<17>")
	)
	(segment
		(start 320.88582 -79.953612)
		(end 320.757804 -79.8322)
		(width 0.1143)
		(layer "In9.Cu")
		(net "UPI_CPU0_CPU1_P0P0_DP<17>")
	)
	(segment
		(start 320.920364 -81.207864)
		(end 320.90614 -80.687164)
		(width 0.1143)
		(layer "In9.Cu")
		(net "UPI_CPU0_CPU1_P0P0_DP<17>")
	)
	(segment
		(start 322.935854 -103.139748)
		(end 324.413372 -100.454206)
		(width 0.1143)
		(layer "In9.Cu")
		(net "UPI_CPU0_CPU1_P0P0_DP<17>")
	)
	(segment
		(start 320.703448 -78.352142)
		(end 320.696844 -78.123542)
		(width 0.1143)
		(layer "In9.Cu")
		(net "UPI_CPU0_CPU1_P0P0_DP<17>")
	)
	(segment
		(start 175.475392 -117.56136)
		(end 181.13248 -120.088406)
		(width 0.1143)
		(layer "In9.Cu")
		(net "UPI_CPU0_CPU1_P0P0_DP<17>")
	)
	(segment
		(start 320.757804 -80.324198)
		(end 320.892424 -80.18272)
		(width 0.1143)
		(layer "In9.Cu")
		(net "UPI_CPU0_CPU1_P0P0_DP<17>")
	)
	(segment
		(start 144.981168 -78.039214)
		(end 145.031968 -77.988414)
		(width 0.0889)
		(layer "In9.Cu")
		(net "UPI_CPU0_CPU1_P0P0_DP<17>")
	)
	(segment
		(start 307.16601 -59.962288)
		(end 306.94884 -59.962288)
		(width 0.0889)
		(layer "In9.Cu")
		(net "UPI_CPU0_CPU1_P0P0_DP<17>")
	)
	(segment
		(start 135.953754 -71.41591)
		(end 135.895842 -71.357998)
		(width 0.0889)
		(layer "In9.Cu")
		(net "UPI_CPU0_CPU1_P0P0_DP<17>")
	)
	(segment
		(start 322.79971 -103.265732)
		(end 322.89115 -103.18115)
		(width 0.1143)
		(layer "In9.Cu")
		(net "UPI_CPU0_CPU1_P0P0_DP<17>")
	)
	(segment
		(start 157.301184 -102.230428)
		(end 164.277548 -108.88599)
		(width 0.1143)
		(layer "In9.Cu")
		(net "UPI_CPU0_CPU1_P0P0_DP<17>")
	)
	(segment
		(start 156.51861 -97.163636)
		(end 157.301184 -102.230428)
		(width 0.1143)
		(layer "In9.Cu")
		(net "UPI_CPU0_CPU1_P0P0_DP<17>")
	)
	(segment
		(start 143.876268 -78.039214)
		(end 143.965168 -77.950314)
		(width 0.0889)
		(layer "In9.Cu")
		(net "UPI_CPU0_CPU1_P0P0_DP<17>")
	)
	(segment
		(start 150.382224 -89.902284)
		(end 156.51861 -97.163636)
		(width 0.1143)
		(layer "In9.Cu")
		(net "UPI_CPU0_CPU1_P0P0_DP<17>")
	)
	(segment
		(start 142.185898 -77.580998)
		(end 142.31493 -77.580998)
		(width 0.0889)
		(layer "In9.Cu")
		(net "UPI_CPU0_CPU1_P0P0_DP<17>")
	)
	(segment
		(start 248.085864 -120.270778)
		(end 258.855464 -117.733826)
		(width 0.1143)
		(layer "In9.Cu")
		(net "UPI_CPU0_CPU1_P0P0_DP<17>")
	)
	(segment
		(start 142.060168 -77.326236)
		(end 142.060168 -77.455268)
		(width 0.0889)
		(layer "In9.Cu")
		(net "UPI_CPU0_CPU1_P0P0_DP<17>")
	)
	(segment
		(start 320.696844 -78.123542)
		(end 320.831464 -77.982064)
		(width 0.1143)
		(layer "In9.Cu")
		(net "UPI_CPU0_CPU1_P0P0_DP<17>")
	)
	(segment
		(start 308.28996 -59.466734)
		(end 307.731668 -59.466734)
		(width 0.0889)
		(layer "In9.Cu")
		(net "UPI_CPU0_CPU1_P0P0_DP<17>")
	)
	(segment
		(start 142.898368 -77.950314)
		(end 143.076168 -77.950314)
		(width 0.0889)
		(layer "In9.Cu")
		(net "UPI_CPU0_CPU1_P0P0_DP<17>")
	)
	(segment
		(start 320.80454 -77.019404)
		(end 320.662808 -76.885038)
		(width 0.1143)
		(layer "In9.Cu")
		(net "UPI_CPU0_CPU1_P0P0_DP<17>")
	)
	(segment
		(start 320.892424 -80.18272)
		(end 320.88582 -79.953612)
		(width 0.1143)
		(layer "In9.Cu")
		(net "UPI_CPU0_CPU1_P0P0_DP<17>")
	)
	(segment
		(start 183.700928 -120.849136)
		(end 185.694828 -121.43994)
		(width 0.1143)
		(layer "In9.Cu")
		(net "UPI_CPU0_CPU1_P0P0_DP<17>")
	)
	(segment
		(start 320.642488 -76.151486)
		(end 320.635884 -75.922886)
		(width 0.1143)
		(layer "In9.Cu")
		(net "UPI_CPU0_CPU1_P0P0_DP<17>")
	)
	(segment
		(start 320.811144 -77.248512)
		(end 320.80454 -77.019404)
		(width 0.1143)
		(layer "In9.Cu")
		(net "UPI_CPU0_CPU1_P0P0_DP<17>")
	)
	(segment
		(start 141.805406 -77.200506)
		(end 141.934438 -77.200506)
		(width 0.0889)
		(layer "In9.Cu")
		(net "UPI_CPU0_CPU1_P0P0_DP<17>")
	)
	(segment
		(start 321.189096 -81.915)
		(end 320.920364 -81.207864)
		(width 0.1143)
		(layer "In9.Cu")
		(net "UPI_CPU0_CPU1_P0P0_DP<17>")
	)
	(segment
		(start 320.717164 -78.857094)
		(end 320.851784 -78.715616)
		(width 0.1143)
		(layer "In9.Cu")
		(net "UPI_CPU0_CPU1_P0P0_DP<17>")
	)
	(arc
		(start 137.688574 -75.125834)
		(mid 137.973998 -75.209301)
		(end 138.182604 -75.421236)
		(width 0.0889)
		(layer "In9.Cu")
		(net "UPI_CPU0_CPU1_P0P0_DP<17>")
	)
	(arc
		(start 307.73116 -59.466988)
		(mid 307.606284 -59.546725)
		(end 307.515514 -59.663838)
		(width 0.0889)
		(layer "In9.Cu")
		(net "UPI_CPU0_CPU1_P0P0_DP<17>")
	)
	(arc
		(start 136.465564 -74.030586)
		(mid 136.462816 -74.426053)
		(end 136.801098 -74.630788)
		(width 0.0889)
		(layer "In9.Cu")
		(net "UPI_CPU0_CPU1_P0P0_DP<17>")
	)
	(arc
		(start 135.971534 -72.154034)
		(mid 136.469785 -72.456874)
		(end 136.465564 -73.039986)
		(width 0.0889)
		(layer "In9.Cu")
		(net "UPI_CPU0_CPU1_P0P0_DP<17>")
	)
	(arc
		(start 136.833864 -74.630788)
		(mid 137.117081 -74.715069)
		(end 137.324084 -74.925936)
		(width 0.0889)
		(layer "In9.Cu")
		(net "UPI_CPU0_CPU1_P0P0_DP<17>")
	)
	(arc
		(start 140.798042 -76.90993)
		(mid 140.888986 -77.027273)
		(end 141.014196 -77.107034)
		(width 0.0889)
		(layer "In9.Cu")
		(net "UPI_CPU0_CPU1_P0P0_DP<17>")
	)
	(arc
		(start 139.899644 -76.411836)
		(mid 140.041327 -76.55564)
		(end 140.235178 -76.611988)
		(width 0.0889)
		(layer "In9.Cu")
		(net "UPI_CPU0_CPU1_P0P0_DP<17>")
	)
	(arc
		(start 307.515514 -59.663838)
		(mid 307.3692 -59.846355)
		(end 307.16601 -59.962288)
		(width 0.0889)
		(layer "In9.Cu")
		(net "UPI_CPU0_CPU1_P0P0_DP<17>")
	)
	(arc
		(start 138.550904 -75.621388)
		(mid 138.834121 -75.705669)
		(end 139.041124 -75.916536)
		(width 0.0889)
		(layer "In9.Cu")
		(net "UPI_CPU0_CPU1_P0P0_DP<17>")
	)
	(arc
		(start 138.182604 -75.421236)
		(mid 138.324287 -75.56504)
		(end 138.518138 -75.621388)
		(width 0.0889)
		(layer "In9.Cu")
		(net "UPI_CPU0_CPU1_P0P0_DP<17>")
	)
	(arc
		(start 136.465564 -73.039986)
		(mid 136.412094 -73.235049)
		(end 136.460738 -73.4314)
		(width 0.0889)
		(layer "In9.Cu")
		(net "UPI_CPU0_CPU1_P0P0_DP<17>")
	)
	(arc
		(start 139.405614 -76.116434)
		(mid 139.691038 -76.199901)
		(end 139.899644 -76.411836)
		(width 0.0889)
		(layer "In9.Cu")
		(net "UPI_CPU0_CPU1_P0P0_DP<17>")
	)
	(arc
		(start 136.471914 -73.450704)
		(mid 136.544712 -73.741467)
		(end 136.465564 -74.030586)
		(width 0.0889)
		(layer "In9.Cu")
		(net "UPI_CPU0_CPU1_P0P0_DP<17>")
	)
	(arc
		(start 135.602726 -71.561198)
		(mid 135.605299 -71.951379)
		(end 135.938768 -72.154034)
		(width 0.0889)
		(layer "In9.Cu")
		(net "UPI_CPU0_CPU1_P0P0_DP<17>")
	)
	(arc
		(start 139.041124 -75.916536)
		(mid 139.181203 -76.059272)
		(end 139.372848 -76.116434)
		(width 0.0889)
		(layer "In9.Cu")
		(net "UPI_CPU0_CPU1_P0P0_DP<17>")
	)
	(arc
		(start 140.449554 -76.611988)
		(mid 140.652148 -76.727806)
		(end 140.798042 -76.90993)
		(width 0.0889)
		(layer "In9.Cu")
		(net "UPI_CPU0_CPU1_P0P0_DP<17>")
	)
	(arc
		(start 306.94884 -59.962288)
		(mid 306.757198 -60.019454)
		(end 306.617116 -60.162186)
		(width 0.0889)
		(layer "In9.Cu")
		(net "UPI_CPU0_CPU1_P0P0_DP<17>")
	)
	(arc
		(start 135.895842 -71.357998)
		(mid 135.725435 -71.425175)
		(end 135.602726 -71.561198)
		(width 0.0889)
		(layer "In9.Cu")
		(net "UPI_CPU0_CPU1_P0P0_DP<17>")
	)
	(arc
		(start 137.324084 -74.925936)
		(mid 137.464163 -75.068672)
		(end 137.655808 -75.125834)
		(width 0.0889)
		(layer "In9.Cu")
		(net "UPI_CPU0_CPU1_P0P0_DP<17>")
	)
	(arc
		(start 306.617116 -60.162186)
		(mid 306.428588 -60.361559)
		(end 306.17033 -60.454286)
		(width 0.0889)
		(layer "In9.Cu")
		(net "UPI_CPU0_CPU1_P0P0_DP<17>")
	)
	(segment
		(start 306.392326 -60.362338)
		(end 306.963826 -60.362338)
		(width 0.1143)
		(layer "F.Cu")
		(net "UPI_CPU0_CPU1_P0P0_DP<16>")
	)
	(segment
		(start 135.382254 -69.772784)
		(end 135.953754 -69.772784)
		(width 0.1143)
		(layer "F.Cu")
		(net "UPI_CPU0_CPU1_P0P0_DP<16>")
	)
	(via
		(at 306.963826 -60.362338)
		(size 0.508)
		(drill 0.254)
		(layers "F.Cu" "B.Cu")
		(net "UPI_CPU0_CPU1_P0P0_DP<16>")
	)
	(via
		(at 135.953754 -69.772784)
		(size 0.508)
		(drill 0.254)
		(layers "F.Cu" "B.Cu")
		(net "UPI_CPU0_CPU1_P0P0_DP<16>")
	)
	(segment
		(start 145.509996 -77.513434)
		(end 145.77695 -77.618844)
		(width 0.1143)
		(layer "In9.Cu")
		(net "UPI_CPU0_CPU1_P0P0_DP<16>")
	)
	(segment
		(start 324.244716 -98.112834)
		(end 321.184778 -83.08594)
		(width 0.1143)
		(layer "In9.Cu")
		(net "UPI_CPU0_CPU1_P0P0_DP<16>")
	)
	(segment
		(start 311.149746 -60.071254)
		(end 310.863996 -59.814714)
		(width 0.1143)
		(layer "In9.Cu")
		(net "UPI_CPU0_CPU1_P0P0_DP<16>")
	)
	(segment
		(start 316.6364 -65.000632)
		(end 311.149746 -60.071254)
		(width 0.1143)
		(layer "In9.Cu")
		(net "UPI_CPU0_CPU1_P0P0_DP<16>")
	)
	(segment
		(start 148.054568 -80.001364)
		(end 150.694898 -89.737438)
		(width 0.1143)
		(layer "In9.Cu")
		(net "UPI_CPU0_CPU1_P0P0_DP<16>")
	)
	(segment
		(start 171.53636 -115.334288)
		(end 175.456342 -117.131846)
		(width 0.1143)
		(layer "In9.Cu")
		(net "UPI_CPU0_CPU1_P0P0_DP<16>")
	)
	(segment
		(start 320.3956 -79.8322)
		(end 320.26225 -75.004422)
		(width 0.1143)
		(layer "In9.Cu")
		(net "UPI_CPU0_CPU1_P0P0_DP<16>")
	)
	(segment
		(start 309.645304 -59.814714)
		(end 309.594504 -59.865514)
		(width 0.0889)
		(layer "In9.Cu")
		(net "UPI_CPU0_CPU1_P0P0_DP<16>")
	)
	(segment
		(start 227.823268 -116.46916)
		(end 237.949232 -118.19382)
		(width 0.1143)
		(layer "In9.Cu")
		(net "UPI_CPU0_CPU1_P0P0_DP<16>")
	)
	(segment
		(start 185.860436 -121.117106)
		(end 194.28841 -120.507252)
		(width 0.1143)
		(layer "In9.Cu")
		(net "UPI_CPU0_CPU1_P0P0_DP<16>")
	)
	(segment
		(start 150.694898 -89.737438)
		(end 156.844746 -97.015046)
		(width 0.1143)
		(layer "In9.Cu")
		(net "UPI_CPU0_CPU1_P0P0_DP<16>")
	)
	(segment
		(start 194.28841 -120.507252)
		(end 194.290442 -120.506998)
		(width 0.1143)
		(layer "In9.Cu")
		(net "UPI_CPU0_CPU1_P0P0_DP<16>")
	)
	(segment
		(start 320.24447 -74.36104)
		(end 318.1985 -68.90131)
		(width 0.1143)
		(layer "In9.Cu")
		(net "UPI_CPU0_CPU1_P0P0_DP<16>")
	)
	(segment
		(start 248.075196 -119.918226)
		(end 258.823714 -117.386354)
		(width 0.1143)
		(layer "In9.Cu")
		(net "UPI_CPU0_CPU1_P0P0_DP<16>")
	)
	(segment
		(start 323.625718 -101.169216)
		(end 324.074536 -100.353368)
		(width 0.1143)
		(layer "In9.Cu")
		(net "UPI_CPU0_CPU1_P0P0_DP<16>")
	)
	(segment
		(start 237.949232 -118.19382)
		(end 248.075196 -119.918226)
		(width 0.1143)
		(layer "In9.Cu")
		(net "UPI_CPU0_CPU1_P0P0_DP<16>")
	)
	(segment
		(start 141.71422 -76.306934)
		(end 142.86992 -77.462634)
		(width 0.0889)
		(layer "In9.Cu")
		(net "UPI_CPU0_CPU1_P0P0_DP<16>")
	)
	(segment
		(start 181.154578 -119.744998)
		(end 182.849012 -120.239028)
		(width 0.1143)
		(layer "In9.Cu")
		(net "UPI_CPU0_CPU1_P0P0_DP<16>")
	)
	(segment
		(start 308.124606 -60.266834)
		(end 307.194458 -60.266834)
		(width 0.0889)
		(layer "In9.Cu")
		(net "UPI_CPU0_CPU1_P0P0_DP<16>")
	)
	(segment
		(start 156.844746 -97.015046)
		(end 157.625034 -102.061264)
		(width 0.1143)
		(layer "In9.Cu")
		(net "UPI_CPU0_CPU1_P0P0_DP<16>")
	)
	(segment
		(start 143.869156 -77.513434)
		(end 143.891254 -77.513434)
		(width 0.0889)
		(layer "In9.Cu")
		(net "UPI_CPU0_CPU1_P0P0_DP<16>")
	)
	(segment
		(start 321.184778 -83.08594)
		(end 320.430652 -81.101692)
		(width 0.1143)
		(layer "In9.Cu")
		(net "UPI_CPU0_CPU1_P0P0_DP<16>")
	)
	(segment
		(start 194.290442 -120.506998)
		(end 194.295522 -120.50649)
		(width 0.1143)
		(layer "In9.Cu")
		(net "UPI_CPU0_CPU1_P0P0_DP<16>")
	)
	(segment
		(start 318.020954 -68.4276)
		(end 316.787784 -65.136522)
		(width 0.1143)
		(layer "In9.Cu")
		(net "UPI_CPU0_CPU1_P0P0_DP<16>")
	)
	(segment
		(start 258.823714 -117.386354)
		(end 267.278104 -117.802914)
		(width 0.1143)
		(layer "In9.Cu")
		(net "UPI_CPU0_CPU1_P0P0_DP<16>")
	)
	(segment
		(start 140.228574 -75.811888)
		(end 140.413232 -75.811888)
		(width 0.0889)
		(layer "In9.Cu")
		(net "UPI_CPU0_CPU1_P0P0_DP<16>")
	)
	(segment
		(start 136.794494 -71.849488)
		(end 136.82726 -71.849488)
		(width 0.0889)
		(layer "In9.Cu")
		(net "UPI_CPU0_CPU1_P0P0_DP<16>")
	)
	(segment
		(start 310.863996 -59.814714)
		(end 309.667402 -59.814714)
		(width 0.1143)
		(layer "In9.Cu")
		(net "UPI_CPU0_CPU1_P0P0_DP<16>")
	)
	(segment
		(start 145.77695 -77.618844)
		(end 148.054568 -80.001364)
		(width 0.1143)
		(layer "In9.Cu")
		(net "UPI_CPU0_CPU1_P0P0_DP<16>")
	)
	(segment
		(start 137.16381 -72.4408)
		(end 137.158984 -72.449436)
		(width 0.0889)
		(layer "In9.Cu")
		(net "UPI_CPU0_CPU1_P0P0_DP<16>")
	)
	(segment
		(start 143.891254 -77.513434)
		(end 145.509996 -77.513434)
		(width 0.1143)
		(layer "In9.Cu")
		(net "UPI_CPU0_CPU1_P0P0_DP<16>")
	)
	(segment
		(start 139.366244 -75.316334)
		(end 139.39901 -75.316334)
		(width 0.0889)
		(layer "In9.Cu")
		(net "UPI_CPU0_CPU1_P0P0_DP<16>")
	)
	(segment
		(start 309.667402 -59.814714)
		(end 309.645304 -59.814714)
		(width 0.0889)
		(layer "In9.Cu")
		(net "UPI_CPU0_CPU1_P0P0_DP<16>")
	)
	(segment
		(start 194.295522 -120.50649)
		(end 227.823268 -116.46916)
		(width 0.1143)
		(layer "In9.Cu")
		(net "UPI_CPU0_CPU1_P0P0_DP<16>")
	)
	(segment
		(start 143.818356 -77.462634)
		(end 143.869156 -77.513434)
		(width 0.0889)
		(layer "In9.Cu")
		(net "UPI_CPU0_CPU1_P0P0_DP<16>")
	)
	(segment
		(start 291.125402 -118.29034)
		(end 292.428168 -118.44147)
		(width 0.1143)
		(layer "In9.Cu")
		(net "UPI_CPU0_CPU1_P0P0_DP<16>")
	)
	(segment
		(start 137.158984 -73.440036)
		(end 137.152634 -73.450704)
		(width 0.0889)
		(layer "In9.Cu")
		(net "UPI_CPU0_CPU1_P0P0_DP<16>")
	)
	(segment
		(start 164.638736 -108.753148)
		(end 171.53636 -115.334288)
		(width 0.1143)
		(layer "In9.Cu")
		(net "UPI_CPU0_CPU1_P0P0_DP<16>")
	)
	(segment
		(start 179.522628 -118.996714)
		(end 181.154578 -119.744998)
		(width 0.1143)
		(layer "In9.Cu")
		(net "UPI_CPU0_CPU1_P0P0_DP<16>")
	)
	(segment
		(start 324.074536 -100.353368)
		(end 324.244716 -98.112834)
		(width 0.1143)
		(layer "In9.Cu")
		(net "UPI_CPU0_CPU1_P0P0_DP<16>")
	)
	(segment
		(start 308.525926 -59.865514)
		(end 308.124606 -60.266834)
		(width 0.0889)
		(layer "In9.Cu")
		(net "UPI_CPU0_CPU1_P0P0_DP<16>")
	)
	(segment
		(start 136.036812 -70.091808)
		(end 136.30529 -70.572122)
		(width 0.0889)
		(layer "In9.Cu")
		(net "UPI_CPU0_CPU1_P0P0_DP<16>")
	)
	(segment
		(start 175.456342 -117.131846)
		(end 179.522628 -118.996714)
		(width 0.1143)
		(layer "In9.Cu")
		(net "UPI_CPU0_CPU1_P0P0_DP<16>")
	)
	(segment
		(start 137.16381 -73.4314)
		(end 137.158984 -73.440036)
		(width 0.0889)
		(layer "In9.Cu")
		(net "UPI_CPU0_CPU1_P0P0_DP<16>")
	)
	(segment
		(start 137.158984 -72.449436)
		(end 137.152634 -72.460104)
		(width 0.0889)
		(layer "In9.Cu")
		(net "UPI_CPU0_CPU1_P0P0_DP<16>")
	)
	(segment
		(start 142.86992 -77.462634)
		(end 143.818356 -77.462634)
		(width 0.0889)
		(layer "In9.Cu")
		(net "UPI_CPU0_CPU1_P0P0_DP<16>")
	)
	(segment
		(start 157.625034 -102.061264)
		(end 164.638736 -108.753148)
		(width 0.1143)
		(layer "In9.Cu")
		(net "UPI_CPU0_CPU1_P0P0_DP<16>")
	)
	(segment
		(start 278.024336 -116.771166)
		(end 291.125402 -118.29034)
		(width 0.1143)
		(layer "In9.Cu")
		(net "UPI_CPU0_CPU1_P0P0_DP<16>")
	)
	(segment
		(start 309.594504 -59.865514)
		(end 308.525926 -59.865514)
		(width 0.0889)
		(layer "In9.Cu")
		(net "UPI_CPU0_CPU1_P0P0_DP<16>")
	)
	(segment
		(start 138.511534 -74.821288)
		(end 138.5443 -74.821288)
		(width 0.0889)
		(layer "In9.Cu")
		(net "UPI_CPU0_CPU1_P0P0_DP<16>")
	)
	(segment
		(start 322.639436 -102.929436)
		(end 322.675758 -102.895654)
		(width 0.1143)
		(layer "In9.Cu")
		(net "UPI_CPU0_CPU1_P0P0_DP<16>")
	)
	(segment
		(start 318.1985 -68.90131)
		(end 318.020954 -68.4276)
		(width 0.1143)
		(layer "In9.Cu")
		(net "UPI_CPU0_CPU1_P0P0_DP<16>")
	)
	(segment
		(start 292.428168 -118.44147)
		(end 310.241188 -114.383312)
		(width 0.1143)
		(layer "In9.Cu")
		(net "UPI_CPU0_CPU1_P0P0_DP<16>")
	)
	(segment
		(start 140.977874 -76.306934)
		(end 141.71422 -76.306934)
		(width 0.0889)
		(layer "In9.Cu")
		(net "UPI_CPU0_CPU1_P0P0_DP<16>")
	)
	(segment
		(start 316.787784 -65.136522)
		(end 316.6364 -65.000632)
		(width 0.1143)
		(layer "In9.Cu")
		(net "UPI_CPU0_CPU1_P0P0_DP<16>")
	)
	(segment
		(start 182.849012 -120.239028)
		(end 185.860436 -121.117106)
		(width 0.1143)
		(layer "In9.Cu")
		(net "UPI_CPU0_CPU1_P0P0_DP<16>")
	)
	(segment
		(start 320.261996 -75.004422)
		(end 320.24447 -74.36104)
		(width 0.1143)
		(layer "In9.Cu")
		(net "UPI_CPU0_CPU1_P0P0_DP<16>")
	)
	(segment
		(start 320.26225 -75.004422)
		(end 320.261996 -75.004422)
		(width 0.1143)
		(layer "In9.Cu")
		(net "UPI_CPU0_CPU1_P0P0_DP<16>")
	)
	(segment
		(start 320.430652 -81.101692)
		(end 320.3956 -79.8322)
		(width 0.1143)
		(layer "In9.Cu")
		(net "UPI_CPU0_CPU1_P0P0_DP<16>")
	)
	(segment
		(start 310.241188 -114.383312)
		(end 322.639436 -102.929436)
		(width 0.1143)
		(layer "In9.Cu")
		(net "UPI_CPU0_CPU1_P0P0_DP<16>")
	)
	(segment
		(start 137.649204 -74.325734)
		(end 137.68197 -74.325734)
		(width 0.0889)
		(layer "In9.Cu")
		(net "UPI_CPU0_CPU1_P0P0_DP<16>")
	)
	(segment
		(start 267.278104 -117.802914)
		(end 278.024336 -116.771166)
		(width 0.1143)
		(layer "In9.Cu")
		(net "UPI_CPU0_CPU1_P0P0_DP<16>")
	)
	(segment
		(start 322.675758 -102.895654)
		(end 323.625718 -101.169216)
		(width 0.1143)
		(layer "In9.Cu")
		(net "UPI_CPU0_CPU1_P0P0_DP<16>")
	)
	(arc
		(start 138.017504 -74.525886)
		(mid 138.226112 -74.737818)
		(end 138.511534 -74.821288)
		(width 0.0889)
		(layer "In9.Cu")
		(net "UPI_CPU0_CPU1_P0P0_DP<16>")
	)
	(arc
		(start 138.5443 -74.821288)
		(mid 138.735942 -74.878454)
		(end 138.876024 -75.021186)
		(width 0.0889)
		(layer "In9.Cu")
		(net "UPI_CPU0_CPU1_P0P0_DP<16>")
	)
	(arc
		(start 137.158984 -73.039986)
		(mid 137.212454 -73.235049)
		(end 137.16381 -73.4314)
		(width 0.0889)
		(layer "In9.Cu")
		(net "UPI_CPU0_CPU1_P0P0_DP<16>")
	)
	(arc
		(start 140.413232 -75.811888)
		(mid 140.538433 -75.891659)
		(end 140.629386 -76.008992)
		(width 0.0889)
		(layer "In9.Cu")
		(net "UPI_CPU0_CPU1_P0P0_DP<16>")
	)
	(arc
		(start 136.30529 -70.572122)
		(mid 136.354045 -70.768474)
		(end 136.300464 -70.963536)
		(width 0.0889)
		(layer "In9.Cu")
		(net "UPI_CPU0_CPU1_P0P0_DP<16>")
	)
	(arc
		(start 137.152634 -73.450704)
		(mid 137.156665 -74.026886)
		(end 137.649204 -74.325734)
		(width 0.0889)
		(layer "In9.Cu")
		(net "UPI_CPU0_CPU1_P0P0_DP<16>")
	)
	(arc
		(start 136.82726 -71.849488)
		(mid 137.160178 -72.051479)
		(end 137.16381 -72.4408)
		(width 0.0889)
		(layer "In9.Cu")
		(net "UPI_CPU0_CPU1_P0P0_DP<16>")
	)
	(arc
		(start 138.876024 -75.021186)
		(mid 139.083028 -75.23205)
		(end 139.366244 -75.316334)
		(width 0.0889)
		(layer "In9.Cu")
		(net "UPI_CPU0_CPU1_P0P0_DP<16>")
	)
	(arc
		(start 139.734544 -75.516486)
		(mid 139.943152 -75.728418)
		(end 140.228574 -75.811888)
		(width 0.0889)
		(layer "In9.Cu")
		(net "UPI_CPU0_CPU1_P0P0_DP<16>")
	)
	(arc
		(start 139.39901 -75.316334)
		(mid 139.59286 -75.372684)
		(end 139.734544 -75.516486)
		(width 0.0889)
		(layer "In9.Cu")
		(net "UPI_CPU0_CPU1_P0P0_DP<16>")
	)
	(arc
		(start 137.68197 -74.325734)
		(mid 137.87582 -74.382084)
		(end 138.017504 -74.525886)
		(width 0.0889)
		(layer "In9.Cu")
		(net "UPI_CPU0_CPU1_P0P0_DP<16>")
	)
	(arc
		(start 307.194458 -60.266834)
		(mid 307.069651 -60.29166)
		(end 306.963826 -60.362338)
		(width 0.0889)
		(layer "In9.Cu")
		(net "UPI_CPU0_CPU1_P0P0_DP<16>")
	)
	(arc
		(start 136.300464 -70.963536)
		(mid 136.296135 -71.546708)
		(end 136.794494 -71.849488)
		(width 0.0889)
		(layer "In9.Cu")
		(net "UPI_CPU0_CPU1_P0P0_DP<16>")
	)
	(arc
		(start 135.953754 -69.772784)
		(mid 135.974871 -69.937607)
		(end 136.036812 -70.091808)
		(width 0.0889)
		(layer "In9.Cu")
		(net "UPI_CPU0_CPU1_P0P0_DP<16>")
	)
	(arc
		(start 137.152634 -72.460104)
		(mid 137.079836 -72.750867)
		(end 137.158984 -73.039986)
		(width 0.0889)
		(layer "In9.Cu")
		(net "UPI_CPU0_CPU1_P0P0_DP<16>")
	)
	(arc
		(start 140.629386 -76.008992)
		(mid 140.775311 -76.191079)
		(end 140.977874 -76.306934)
		(width 0.0889)
		(layer "In9.Cu")
		(net "UPI_CPU0_CPU1_P0P0_DP<16>")
	)
	(segment
		(start 137.099294 -73.735184)
		(end 137.670794 -73.735184)
		(width 0.1143)
		(layer "F.Cu")
		(net "UPI_CPU0_CPU1_P0P0_DP<15>")
	)
	(segment
		(start 306.392326 -61.352938)
		(end 306.963826 -61.352938)
		(width 0.1143)
		(layer "F.Cu")
		(net "UPI_CPU0_CPU1_P0P0_DP<15>")
	)
	(via
		(at 306.963826 -61.352938)
		(size 0.508)
		(drill 0.254)
		(layers "F.Cu" "B.Cu")
		(net "UPI_CPU0_CPU1_P0P0_DP<15>")
	)
	(via
		(at 137.670794 -73.735184)
		(size 0.508)
		(drill 0.254)
		(layers "F.Cu" "B.Cu")
		(net "UPI_CPU0_CPU1_P0P0_DP<15>")
	)
	(segment
		(start 307.341016 -61.512704)
		(end 307.322728 -61.530992)
		(width 0.0889)
		(layer "In9.Cu")
		(net "UPI_CPU0_CPU1_P0P0_DP<15>")
	)
	(segment
		(start 310.698642 -60.522358)
		(end 310.62803 -60.459112)
		(width 0.1143)
		(layer "In9.Cu")
		(net "UPI_CPU0_CPU1_P0P0_DP<15>")
	)
	(segment
		(start 185.755534 -120.44807)
		(end 188.121544 -120.322848)
		(width 0.1143)
		(layer "In9.Cu")
		(net "UPI_CPU0_CPU1_P0P0_DP<15>")
	)
	(segment
		(start 309.974996 -60.459112)
		(end 309.952898 -60.459112)
		(width 0.0889)
		(layer "In9.Cu")
		(net "UPI_CPU0_CPU1_P0P0_DP<15>")
	)
	(segment
		(start 194.606926 -119.81688)
		(end 227.839016 -115.825016)
		(width 0.1143)
		(layer "In9.Cu")
		(net "UPI_CPU0_CPU1_P0P0_DP<15>")
	)
	(segment
		(start 143.467328 -76.815188)
		(end 145.574258 -76.815188)
		(width 0.1143)
		(layer "In9.Cu")
		(net "UPI_CPU0_CPU1_P0P0_DP<15>")
	)
	(segment
		(start 137.670794 -73.735184)
		(end 137.670794 -73.39711)
		(width 0.0889)
		(layer "In9.Cu")
		(net "UPI_CPU0_CPU1_P0P0_DP<15>")
	)
	(segment
		(start 307.322982 -61.530992)
		(end 307.310536 -61.552836)
		(width 0.0889)
		(layer "In9.Cu")
		(net "UPI_CPU0_CPU1_P0P0_DP<15>")
	)
	(segment
		(start 188.1251 -120.322594)
		(end 194.606926 -119.81688)
		(width 0.1143)
		(layer "In9.Cu")
		(net "UPI_CPU0_CPU1_P0P0_DP<15>")
	)
	(segment
		(start 319.36563 -74.269346)
		(end 319.365122 -74.2696)
		(width 0.1143)
		(layer "In9.Cu")
		(net "UPI_CPU0_CPU1_P0P0_DP<15>")
	)
	(segment
		(start 319.519554 -79.8322)
		(end 319.36563 -74.269346)
		(width 0.1143)
		(layer "In9.Cu")
		(net "UPI_CPU0_CPU1_P0P0_DP<15>")
	)
	(segment
		(start 307.322728 -61.530992)
		(end 307.322982 -61.530992)
		(width 0.0889)
		(layer "In9.Cu")
		(net "UPI_CPU0_CPU1_P0P0_DP<15>")
	)
	(segment
		(start 285.171134 -116.95811)
		(end 291.125402 -117.648736)
		(width 0.1143)
		(layer "In9.Cu")
		(net "UPI_CPU0_CPU1_P0P0_DP<15>")
	)
	(segment
		(start 248.054876 -119.267732)
		(end 258.76504 -116.745004)
		(width 0.1143)
		(layer "In9.Cu")
		(net "UPI_CPU0_CPU1_P0P0_DP<15>")
	)
	(segment
		(start 142.30985 -75.77201)
		(end 142.42415 -75.77201)
		(width 0.1143)
		(layer "In9.Cu")
		(net "UPI_CPU0_CPU1_P0P0_DP<15>")
	)
	(segment
		(start 139.370054 -74.325734)
		(end 139.40282 -74.325734)
		(width 0.0889)
		(layer "In9.Cu")
		(net "UPI_CPU0_CPU1_P0P0_DP<15>")
	)
	(segment
		(start 148.600668 -79.577946)
		(end 151.273256 -89.433654)
		(width 0.1143)
		(layer "In9.Cu")
		(net "UPI_CPU0_CPU1_P0P0_DP<15>")
	)
	(segment
		(start 171.963588 -114.859816)
		(end 181.487572 -119.071136)
		(width 0.1143)
		(layer "In9.Cu")
		(net "UPI_CPU0_CPU1_P0P0_DP<15>")
	)
	(segment
		(start 181.50205 -119.075708)
		(end 185.755534 -120.44807)
		(width 0.1143)
		(layer "In9.Cu")
		(net "UPI_CPU0_CPU1_P0P0_DP<15>")
	)
	(segment
		(start 309.883048 -113.81105)
		(end 322.169282 -102.459282)
		(width 0.1143)
		(layer "In9.Cu")
		(net "UPI_CPU0_CPU1_P0P0_DP<15>")
	)
	(segment
		(start 322.207382 -102.42423)
		(end 322.4784 -101.931724)
		(width 0.1143)
		(layer "In9.Cu")
		(net "UPI_CPU0_CPU1_P0P0_DP<15>")
	)
	(segment
		(start 309.902098 -60.509912)
		(end 308.867048 -60.509912)
		(width 0.0889)
		(layer "In9.Cu")
		(net "UPI_CPU0_CPU1_P0P0_DP<15>")
	)
	(segment
		(start 316.246002 -65.5066)
		(end 310.76138 -60.579)
		(width 0.1143)
		(layer "In9.Cu")
		(net "UPI_CPU0_CPU1_P0P0_DP<15>")
	)
	(segment
		(start 306.959508 -61.753242)
		(end 306.958492 -61.753496)
		(width 0.0889)
		(layer "In9.Cu")
		(net "UPI_CPU0_CPU1_P0P0_DP<15>")
	)
	(segment
		(start 140.977874 -75.316334)
		(end 141.37767 -75.316334)
		(width 0.0889)
		(layer "In9.Cu")
		(net "UPI_CPU0_CPU1_P0P0_DP<15>")
	)
	(segment
		(start 319.97777 -81.915)
		(end 319.545716 -80.778604)
		(width 0.1143)
		(layer "In9.Cu")
		(net "UPI_CPU0_CPU1_P0P0_DP<15>")
	)
	(segment
		(start 322.71081 -93.7768)
		(end 320.661792 -83.71459)
		(width 0.1143)
		(layer "In9.Cu")
		(net "UPI_CPU0_CPU1_P0P0_DP<15>")
	)
	(segment
		(start 151.273256 -89.433654)
		(end 157.44698 -96.738948)
		(width 0.1143)
		(layer "In9.Cu")
		(net "UPI_CPU0_CPU1_P0P0_DP<15>")
	)
	(segment
		(start 309.952898 -60.459112)
		(end 309.902098 -60.509912)
		(width 0.0889)
		(layer "In9.Cu")
		(net "UPI_CPU0_CPU1_P0P0_DP<15>")
	)
	(segment
		(start 292.392608 -117.795802)
		(end 292.441376 -117.78488)
		(width 0.1143)
		(layer "In9.Cu")
		(net "UPI_CPU0_CPU1_P0P0_DP<15>")
	)
	(segment
		(start 142.287752 -75.77201)
		(end 142.30985 -75.77201)
		(width 0.0889)
		(layer "In9.Cu")
		(net "UPI_CPU0_CPU1_P0P0_DP<15>")
	)
	(segment
		(start 308.119272 -61.257688)
		(end 307.596286 -61.257688)
		(width 0.0889)
		(layer "In9.Cu")
		(net "UPI_CPU0_CPU1_P0P0_DP<15>")
	)
	(segment
		(start 307.596286 -61.257688)
		(end 307.341016 -61.512958)
		(width 0.0889)
		(layer "In9.Cu")
		(net "UPI_CPU0_CPU1_P0P0_DP<15>")
	)
	(segment
		(start 291.125402 -117.648736)
		(end 292.392608 -117.795802)
		(width 0.1143)
		(layer "In9.Cu")
		(net "UPI_CPU0_CPU1_P0P0_DP<15>")
	)
	(segment
		(start 323.449188 -100.167186)
		(end 323.602096 -98.15322)
		(width 0.1143)
		(layer "In9.Cu")
		(net "UPI_CPU0_CPU1_P0P0_DP<15>")
	)
	(segment
		(start 323.602096 -98.15322)
		(end 322.79971 -94.213426)
		(width 0.1143)
		(layer "In9.Cu")
		(net "UPI_CPU0_CPU1_P0P0_DP<15>")
	)
	(segment
		(start 141.782546 -75.72121)
		(end 142.236952 -75.72121)
		(width 0.0889)
		(layer "In9.Cu")
		(net "UPI_CPU0_CPU1_P0P0_DP<15>")
	)
	(segment
		(start 322.169282 -102.459282)
		(end 322.207382 -102.42423)
		(width 0.1143)
		(layer "In9.Cu")
		(net "UPI_CPU0_CPU1_P0P0_DP<15>")
	)
	(segment
		(start 319.365122 -74.2696)
		(end 319.35293 -73.810368)
		(width 0.1143)
		(layer "In9.Cu")
		(net "UPI_CPU0_CPU1_P0P0_DP<15>")
	)
	(segment
		(start 285.171134 -116.958364)
		(end 285.171134 -116.95811)
		(width 0.1143)
		(layer "In9.Cu")
		(net "UPI_CPU0_CPU1_P0P0_DP<15>")
	)
	(segment
		(start 308.867048 -60.509912)
		(end 308.119272 -61.257688)
		(width 0.0889)
		(layer "In9.Cu")
		(net "UPI_CPU0_CPU1_P0P0_DP<15>")
	)
	(segment
		(start 319.545716 -80.778604)
		(end 319.519554 -79.8322)
		(width 0.1143)
		(layer "In9.Cu")
		(net "UPI_CPU0_CPU1_P0P0_DP<15>")
	)
	(segment
		(start 278.030178 -116.129816)
		(end 285.171134 -116.958364)
		(width 0.1143)
		(layer "In9.Cu")
		(net "UPI_CPU0_CPU1_P0P0_DP<15>")
	)
	(segment
		(start 306.958492 -61.753496)
		(end 306.854098 -61.753496)
		(width 0.0889)
		(layer "In9.Cu")
		(net "UPI_CPU0_CPU1_P0P0_DP<15>")
	)
	(segment
		(start 181.487572 -119.071136)
		(end 181.50205 -119.075708)
		(width 0.1143)
		(layer "In9.Cu")
		(net "UPI_CPU0_CPU1_P0P0_DP<15>")
	)
	(segment
		(start 157.44698 -96.738948)
		(end 158.221934 -101.750622)
		(width 0.1143)
		(layer "In9.Cu")
		(net "UPI_CPU0_CPU1_P0P0_DP<15>")
	)
	(segment
		(start 188.121544 -120.322848)
		(end 188.1251 -120.322594)
		(width 0.1143)
		(layer "In9.Cu")
		(net "UPI_CPU0_CPU1_P0P0_DP<15>")
	)
	(segment
		(start 146.195034 -77.06106)
		(end 148.600668 -79.577946)
		(width 0.1143)
		(layer "In9.Cu")
		(net "UPI_CPU0_CPU1_P0P0_DP<15>")
	)
	(segment
		(start 145.574258 -76.815188)
		(end 146.195034 -77.06106)
		(width 0.1143)
		(layer "In9.Cu")
		(net "UPI_CPU0_CPU1_P0P0_DP<15>")
	)
	(segment
		(start 307.341016 -61.512958)
		(end 307.341016 -61.512704)
		(width 0.0889)
		(layer "In9.Cu")
		(net "UPI_CPU0_CPU1_P0P0_DP<15>")
	)
	(segment
		(start 137.670794 -73.39711)
		(end 137.728706 -73.339198)
		(width 0.0889)
		(layer "In9.Cu")
		(net "UPI_CPU0_CPU1_P0P0_DP<15>")
	)
	(segment
		(start 292.441376 -117.784626)
		(end 309.883048 -113.81105)
		(width 0.1143)
		(layer "In9.Cu")
		(net "UPI_CPU0_CPU1_P0P0_DP<15>")
	)
	(segment
		(start 322.79971 -94.213426)
		(end 322.71081 -93.7768)
		(width 0.1143)
		(layer "In9.Cu")
		(net "UPI_CPU0_CPU1_P0P0_DP<15>")
	)
	(segment
		(start 138.504422 -73.830434)
		(end 138.547348 -73.830434)
		(width 0.0889)
		(layer "In9.Cu")
		(net "UPI_CPU0_CPU1_P0P0_DP<15>")
	)
	(segment
		(start 142.236952 -75.72121)
		(end 142.287752 -75.77201)
		(width 0.0889)
		(layer "In9.Cu")
		(net "UPI_CPU0_CPU1_P0P0_DP<15>")
	)
	(segment
		(start 258.76504 -116.745004)
		(end 267.263118 -117.163596)
		(width 0.1143)
		(layer "In9.Cu")
		(net "UPI_CPU0_CPU1_P0P0_DP<15>")
	)
	(segment
		(start 310.62803 -60.459112)
		(end 309.974996 -60.459112)
		(width 0.1143)
		(layer "In9.Cu")
		(net "UPI_CPU0_CPU1_P0P0_DP<15>")
	)
	(segment
		(start 142.42415 -75.77201)
		(end 143.467328 -76.815188)
		(width 0.1143)
		(layer "In9.Cu")
		(net "UPI_CPU0_CPU1_P0P0_DP<15>")
	)
	(segment
		(start 292.441376 -117.78488)
		(end 292.441376 -117.784626)
		(width 0.1143)
		(layer "In9.Cu")
		(net "UPI_CPU0_CPU1_P0P0_DP<15>")
	)
	(segment
		(start 141.37767 -75.316334)
		(end 141.782546 -75.72121)
		(width 0.0889)
		(layer "In9.Cu")
		(net "UPI_CPU0_CPU1_P0P0_DP<15>")
	)
	(segment
		(start 319.35293 -73.810368)
		(end 317.338964 -68.4276)
		(width 0.1143)
		(layer "In9.Cu")
		(net "UPI_CPU0_CPU1_P0P0_DP<15>")
	)
	(segment
		(start 267.263118 -117.163596)
		(end 278.030178 -116.129816)
		(width 0.1143)
		(layer "In9.Cu")
		(net "UPI_CPU0_CPU1_P0P0_DP<15>")
	)
	(segment
		(start 317.338964 -68.4276)
		(end 316.246002 -65.5066)
		(width 0.1143)
		(layer "In9.Cu")
		(net "UPI_CPU0_CPU1_P0P0_DP<15>")
	)
	(segment
		(start 158.221934 -101.750622)
		(end 171.963588 -114.859816)
		(width 0.1143)
		(layer "In9.Cu")
		(net "UPI_CPU0_CPU1_P0P0_DP<15>")
	)
	(segment
		(start 140.2334 -74.821034)
		(end 140.41247 -74.821034)
		(width 0.0889)
		(layer "In9.Cu")
		(net "UPI_CPU0_CPU1_P0P0_DP<15>")
	)
	(segment
		(start 306.854098 -61.352938)
		(end 306.963826 -61.352938)
		(width 0.0889)
		(layer "In9.Cu")
		(net "UPI_CPU0_CPU1_P0P0_DP<15>")
	)
	(segment
		(start 310.76138 -60.579)
		(end 310.698642 -60.522358)
		(width 0.1143)
		(layer "In9.Cu")
		(net "UPI_CPU0_CPU1_P0P0_DP<15>")
	)
	(segment
		(start 320.661792 -83.71459)
		(end 319.97777 -81.915)
		(width 0.1143)
		(layer "In9.Cu")
		(net "UPI_CPU0_CPU1_P0P0_DP<15>")
	)
	(segment
		(start 322.4784 -101.931724)
		(end 323.449188 -100.167186)
		(width 0.1143)
		(layer "In9.Cu")
		(net "UPI_CPU0_CPU1_P0P0_DP<15>")
	)
	(segment
		(start 227.839016 -115.825016)
		(end 248.054876 -119.267732)
		(width 0.1143)
		(layer "In9.Cu")
		(net "UPI_CPU0_CPU1_P0P0_DP<15>")
	)
	(arc
		(start 140.629386 -75.018392)
		(mid 140.775311 -75.200479)
		(end 140.977874 -75.316334)
		(width 0.0889)
		(layer "In9.Cu")
		(net "UPI_CPU0_CPU1_P0P0_DP<15>")
	)
	(arc
		(start 307.310536 -61.552836)
		(mid 307.162193 -61.700634)
		(end 306.959508 -61.753242)
		(width 0.0889)
		(layer "In9.Cu")
		(net "UPI_CPU0_CPU1_P0P0_DP<15>")
	)
	(arc
		(start 139.40282 -74.325734)
		(mid 139.594462 -74.3829)
		(end 139.734544 -74.525632)
		(width 0.0889)
		(layer "In9.Cu")
		(net "UPI_CPU0_CPU1_P0P0_DP<15>")
	)
	(arc
		(start 137.728706 -73.339198)
		(mid 137.895607 -73.404098)
		(end 138.017504 -73.535286)
		(width 0.0889)
		(layer "In9.Cu")
		(net "UPI_CPU0_CPU1_P0P0_DP<15>")
	)
	(arc
		(start 139.734544 -74.525632)
		(mid 139.945257 -74.738711)
		(end 140.2334 -74.821034)
		(width 0.0889)
		(layer "In9.Cu")
		(net "UPI_CPU0_CPU1_P0P0_DP<15>")
	)
	(arc
		(start 306.854098 -61.753496)
		(mid 306.653946 -61.553344)
		(end 306.854098 -61.352938)
		(width 0.0889)
		(layer "In9.Cu")
		(net "UPI_CPU0_CPU1_P0P0_DP<15>")
	)
	(arc
		(start 138.876024 -74.030332)
		(mid 139.084632 -74.242264)
		(end 139.370054 -74.325734)
		(width 0.0889)
		(layer "In9.Cu")
		(net "UPI_CPU0_CPU1_P0P0_DP<15>")
	)
	(arc
		(start 138.547348 -73.830434)
		(mid 138.737277 -73.888304)
		(end 138.876024 -74.030332)
		(width 0.0889)
		(layer "In9.Cu")
		(net "UPI_CPU0_CPU1_P0P0_DP<15>")
	)
	(arc
		(start 140.41247 -74.821034)
		(mid 140.538097 -74.900833)
		(end 140.629386 -75.018392)
		(width 0.0889)
		(layer "In9.Cu")
		(net "UPI_CPU0_CPU1_P0P0_DP<15>")
	)
	(arc
		(start 138.017504 -73.535286)
		(mid 138.223063 -73.745383)
		(end 138.504422 -73.830434)
		(width 0.0889)
		(layer "In9.Cu")
		(net "UPI_CPU0_CPU1_P0P0_DP<15>")
	)
	(segment
		(start 306.963572 -62.672976)
		(end 306.940458 -62.586362)
		(width 0.0889)
		(layer "F.Cu")
		(net "UPI_CPU0_CPU1_P0P0_DP<14>")
	)
	(segment
		(start 307.250846 -62.838584)
		(end 306.963572 -62.672976)
		(width 0.0889)
		(layer "F.Cu")
		(net "UPI_CPU0_CPU1_P0P0_DP<14>")
	)
	(segment
		(start 309.003954 -62.285626)
		(end 309.003954 -62.079378)
		(width 0.0889)
		(layer "F.Cu")
		(net "UPI_CPU0_CPU1_P0P0_DP<14>")
	)
	(segment
		(start 137.957814 -72.249538)
		(end 138.529314 -72.249538)
		(width 0.1143)
		(layer "F.Cu")
		(net "UPI_CPU0_CPU1_P0P0_DP<14>")
	)
	(segment
		(start 309.003954 -62.079378)
		(end 309.238904 -61.844428)
		(width 0.0889)
		(layer "F.Cu")
		(net "UPI_CPU0_CPU1_P0P0_DP<14>")
	)
	(segment
		(start 308.851046 -62.438534)
		(end 309.003954 -62.285626)
		(width 0.0889)
		(layer "F.Cu")
		(net "UPI_CPU0_CPU1_P0P0_DP<14>")
	)
	(segment
		(start 307.23967 -62.438534)
		(end 308.851046 -62.438534)
		(width 0.0889)
		(layer "F.Cu")
		(net "UPI_CPU0_CPU1_P0P0_DP<14>")
	)
	(via
		(at 138.529314 -72.249538)
		(size 0.508)
		(drill 0.254)
		(layers "F.Cu" "B.Cu")
		(net "UPI_CPU0_CPU1_P0P0_DP<14>")
	)
	(via
		(at 309.238904 -61.844428)
		(size 0.508)
		(drill 0.254)
		(layers "F.Cu" "B.Cu")
		(net "UPI_CPU0_CPU1_P0P0_DP<14>")
	)
	(arc
		(start 306.940458 -62.586362)
		(mid 307.073927 -62.479803)
		(end 307.23967 -62.438534)
		(width 0.0889)
		(layer "F.Cu")
		(net "UPI_CPU0_CPU1_P0P0_DP<14>")
	)
	(segment
		(start 171.444158 -113.090198)
		(end 171.564808 -113.17986)
		(width 0.1143)
		(layer "In9.Cu")
		(net "UPI_CPU0_CPU1_P0P0_DP<14>")
	)
	(segment
		(start 318.33693 -79.8322)
		(end 318.40043 -79.765398)
		(width 0.1143)
		(layer "In9.Cu")
		(net "UPI_CPU0_CPU1_P0P0_DP<14>")
	)
	(segment
		(start 171.564808 -113.17986)
		(end 172.893228 -114.16919)
		(width 0.1143)
		(layer "In9.Cu")
		(net "UPI_CPU0_CPU1_P0P0_DP<14>")
	)
	(segment
		(start 152.117044 -88.991694)
		(end 158.326328 -96.339914)
		(width 0.1143)
		(layer "In9.Cu")
		(net "UPI_CPU0_CPU1_P0P0_DP<14>")
	)
	(segment
		(start 318.23787 -73.90511)
		(end 318.226186 -73.465436)
		(width 0.1143)
		(layer "In9.Cu")
		(net "UPI_CPU0_CPU1_P0P0_DP<14>")
	)
	(segment
		(start 144.582896 -75.867006)
		(end 144.677892 -75.77201)
		(width 0.0889)
		(layer "In9.Cu")
		(net "UPI_CPU0_CPU1_P0P0_DP<14>")
	)
	(segment
		(start 197.015608 -118.61165)
		(end 227.903532 -114.892836)
		(width 0.1143)
		(layer "In9.Cu")
		(net "UPI_CPU0_CPU1_P0P0_DP<14>")
	)
	(segment
		(start 322.537328 -99.89566)
		(end 322.537074 -99.89566)
		(width 0.1143)
		(layer "In9.Cu")
		(net "UPI_CPU0_CPU1_P0P0_DP<14>")
	)
	(segment
		(start 144.855692 -75.77201)
		(end 144.950688 -75.867006)
		(width 0.0889)
		(layer "In9.Cu")
		(net "UPI_CPU0_CPU1_P0P0_DP<14>")
	)
	(segment
		(start 140.22832 -73.639934)
		(end 140.96111 -73.639934)
		(width 0.0889)
		(layer "In9.Cu")
		(net "UPI_CPU0_CPU1_P0P0_DP<14>")
	)
	(segment
		(start 174.14494 -114.733324)
		(end 174.45736 -114.87404)
		(width 0.1143)
		(layer "In9.Cu")
		(net "UPI_CPU0_CPU1_P0P0_DP<14>")
	)
	(segment
		(start 318.124078 -74.778616)
		(end 318.25819 -74.637646)
		(width 0.1143)
		(layer "In9.Cu")
		(net "UPI_CPU0_CPU1_P0P0_DP<14>")
	)
	(segment
		(start 143.581374 -75.46848)
		(end 143.581374 -75.598528)
		(width 0.0889)
		(layer "In9.Cu")
		(net "UPI_CPU0_CPU1_P0P0_DP<14>")
	)
	(segment
		(start 159.094424 -101.308408)
		(end 171.444158 -113.090198)
		(width 0.1143)
		(layer "In9.Cu")
		(net "UPI_CPU0_CPU1_P0P0_DP<14>")
	)
	(segment
		(start 140.96111 -73.639934)
		(end 142.070074 -74.748898)
		(width 0.0889)
		(layer "In9.Cu")
		(net "UPI_CPU0_CPU1_P0P0_DP<14>")
	)
	(segment
		(start 318.110362 -74.275188)
		(end 318.103758 -74.04608)
		(width 0.1143)
		(layer "In9.Cu")
		(net "UPI_CPU0_CPU1_P0P0_DP<14>")
	)
	(segment
		(start 318.1985 -76.962)
		(end 318.31915 -76.835254)
		(width 0.1143)
		(layer "In9.Cu")
		(net "UPI_CPU0_CPU1_P0P0_DP<14>")
	)
	(segment
		(start 138.236198 -72.080374)
		(end 138.157458 -72.10171)
		(width 0.0889)
		(layer "In9.Cu")
		(net "UPI_CPU0_CPU1_P0P0_DP<14>")
	)
	(segment
		(start 318.902842 -81.915)
		(end 318.425068 -80.658208)
		(width 0.1143)
		(layer "In9.Cu")
		(net "UPI_CPU0_CPU1_P0P0_DP<14>")
	)
	(segment
		(start 318.225678 -78.441296)
		(end 318.35979 -78.300326)
		(width 0.1143)
		(layer "In9.Cu")
		(net "UPI_CPU0_CPU1_P0P0_DP<14>")
	)
	(segment
		(start 138.529314 -72.249538)
		(end 138.236198 -72.080374)
		(width 0.0889)
		(layer "In9.Cu")
		(net "UPI_CPU0_CPU1_P0P0_DP<14>")
	)
	(segment
		(start 185.81497 -119.47525)
		(end 193.928238 -118.923054)
		(width 0.1143)
		(layer "In9.Cu")
		(net "UPI_CPU0_CPU1_P0P0_DP<14>")
	)
	(segment
		(start 318.103758 -74.04608)
		(end 318.23787 -73.90511)
		(width 0.1143)
		(layer "In9.Cu")
		(net "UPI_CPU0_CPU1_P0P0_DP<14>")
	)
	(segment
		(start 143.581374 -75.598528)
		(end 143.849852 -75.867006)
		(width 0.0889)
		(layer "In9.Cu")
		(net "UPI_CPU0_CPU1_P0P0_DP<14>")
	)
	(segment
		(start 318.185038 -76.976224)
		(end 318.1985 -76.962)
		(width 0.1143)
		(layer "In9.Cu")
		(net "UPI_CPU0_CPU1_P0P0_DP<14>")
	)
	(segment
		(start 321.761866 -93.7768)
		(end 319.858898 -84.430362)
		(width 0.1143)
		(layer "In9.Cu")
		(net "UPI_CPU0_CPU1_P0P0_DP<14>")
	)
	(segment
		(start 318.251586 -74.409046)
		(end 318.1985 -74.358754)
		(width 0.1143)
		(layer "In9.Cu")
		(net "UPI_CPU0_CPU1_P0P0_DP<14>")
	)
	(segment
		(start 318.29883 -76.102718)
		(end 318.292226 -75.874118)
		(width 0.1143)
		(layer "In9.Cu")
		(net "UPI_CPU0_CPU1_P0P0_DP<14>")
	)
	(segment
		(start 144.950688 -75.867006)
		(end 145.166588 -75.867006)
		(width 0.0889)
		(layer "In9.Cu")
		(net "UPI_CPU0_CPU1_P0P0_DP<14>")
	)
	(segment
		(start 318.1985 -75.785218)
		(end 318.151002 -75.74026)
		(width 0.1143)
		(layer "In9.Cu")
		(net "UPI_CPU0_CPU1_P0P0_DP<14>")
	)
	(segment
		(start 143.455644 -75.34275)
		(end 143.581374 -75.46848)
		(width 0.0889)
		(layer "In9.Cu")
		(net "UPI_CPU0_CPU1_P0P0_DP<14>")
	)
	(segment
		(start 144.677892 -75.77201)
		(end 144.855692 -75.77201)
		(width 0.0889)
		(layer "In9.Cu")
		(net "UPI_CPU0_CPU1_P0P0_DP<14>")
	)
	(segment
		(start 173.774862 -114.44097)
		(end 174.08779 -114.58194)
		(width 0.1143)
		(layer "In9.Cu")
		(net "UPI_CPU0_CPU1_P0P0_DP<14>")
	)
	(segment
		(start 318.144398 -75.511152)
		(end 318.1985 -75.454256)
		(width 0.1143)
		(layer "In9.Cu")
		(net "UPI_CPU0_CPU1_P0P0_DP<14>")
	)
	(segment
		(start 144.405096 -75.867006)
		(end 144.582896 -75.867006)
		(width 0.0889)
		(layer "In9.Cu")
		(net "UPI_CPU0_CPU1_P0P0_DP<14>")
	)
	(segment
		(start 318.393826 -79.536798)
		(end 318.252602 -79.40294)
		(width 0.1143)
		(layer "In9.Cu")
		(net "UPI_CPU0_CPU1_P0P0_DP<14>")
	)
	(segment
		(start 145.239486 -75.816206)
		(end 145.888456 -75.816206)
		(width 0.1143)
		(layer "In9.Cu")
		(net "UPI_CPU0_CPU1_P0P0_DP<14>")
	)
	(segment
		(start 318.272922 -80.135476)
		(end 318.266318 -79.906368)
		(width 0.1143)
		(layer "In9.Cu")
		(net "UPI_CPU0_CPU1_P0P0_DP<14>")
	)
	(segment
		(start 142.944088 -74.961242)
		(end 143.074136 -74.961242)
		(width 0.0889)
		(layer "In9.Cu")
		(net "UPI_CPU0_CPU1_P0P0_DP<14>")
	)
	(segment
		(start 309.175404 -61.3918)
		(end 309.0418 -61.525404)
		(width 0.1143)
		(layer "In9.Cu")
		(net "UPI_CPU0_CPU1_P0P0_DP<14>")
	)
	(segment
		(start 321.49669 -101.78669)
		(end 322.4784 -100.002848)
		(width 0.1143)
		(layer "In9.Cu")
		(net "UPI_CPU0_CPU1_P0P0_DP<14>")
	)
	(segment
		(start 139.372848 -73.144634)
		(end 139.405614 -73.144634)
		(width 0.0889)
		(layer "In9.Cu")
		(net "UPI_CPU0_CPU1_P0P0_DP<14>")
	)
	(segment
		(start 144.037304 -75.867006)
		(end 144.1323 -75.77201)
		(width 0.0889)
		(layer "In9.Cu")
		(net "UPI_CPU0_CPU1_P0P0_DP<14>")
	)
	(segment
		(start 318.35979 -78.300326)
		(end 318.353186 -78.071726)
		(width 0.1143)
		(layer "In9.Cu")
		(net "UPI_CPU0_CPU1_P0P0_DP<14>")
	)
	(segment
		(start 267.241274 -116.231416)
		(end 278.038306 -115.194588)
		(width 0.1143)
		(layer "In9.Cu")
		(net "UPI_CPU0_CPU1_P0P0_DP<14>")
	)
	(segment
		(start 144.3101 -75.77201)
		(end 144.405096 -75.867006)
		(width 0.0889)
		(layer "In9.Cu")
		(net "UPI_CPU0_CPU1_P0P0_DP<14>")
	)
	(segment
		(start 318.226186 -73.465436)
		(end 318.1985 -73.391522)
		(width 0.1143)
		(layer "In9.Cu")
		(net "UPI_CPU0_CPU1_P0P0_DP<14>")
	)
	(segment
		(start 158.326328 -96.339914)
		(end 159.094424 -101.308408)
		(width 0.1143)
		(layer "In9.Cu")
		(net "UPI_CPU0_CPU1_P0P0_DP<14>")
	)
	(segment
		(start 146.90217 -76.228956)
		(end 149.351238 -78.791054)
		(width 0.1143)
		(layer "In9.Cu")
		(net "UPI_CPU0_CPU1_P0P0_DP<14>")
	)
	(segment
		(start 145.217388 -75.816206)
		(end 145.239486 -75.816206)
		(width 0.0889)
		(layer "In9.Cu")
		(net "UPI_CPU0_CPU1_P0P0_DP<14>")
	)
	(segment
		(start 318.130682 -75.007724)
		(end 318.124078 -74.778616)
		(width 0.1143)
		(layer "In9.Cu")
		(net "UPI_CPU0_CPU1_P0P0_DP<14>")
	)
	(segment
		(start 322.4784 -100.002848)
		(end 322.537328 -99.89566)
		(width 0.1143)
		(layer "In9.Cu")
		(net "UPI_CPU0_CPU1_P0P0_DP<14>")
	)
	(segment
		(start 322.537074 -99.89566)
		(end 322.66509 -98.212148)
		(width 0.1143)
		(layer "In9.Cu")
		(net "UPI_CPU0_CPU1_P0P0_DP<14>")
	)
	(segment
		(start 318.25819 -74.637646)
		(end 318.251586 -74.409046)
		(width 0.1143)
		(layer "In9.Cu")
		(net "UPI_CPU0_CPU1_P0P0_DP<14>")
	)
	(segment
		(start 316.338204 -68.4276)
		(end 315.441076 -66.03365)
		(width 0.1143)
		(layer "In9.Cu")
		(net "UPI_CPU0_CPU1_P0P0_DP<14>")
	)
	(segment
		(start 309.0418 -61.647324)
		(end 309.238904 -61.844428)
		(width 0.1143)
		(layer "In9.Cu")
		(net "UPI_CPU0_CPU1_P0P0_DP<14>")
	)
	(segment
		(start 321.468496 -101.838252)
		(end 321.49669 -101.78669)
		(width 0.1143)
		(layer "In9.Cu")
		(net "UPI_CPU0_CPU1_P0P0_DP<14>")
	)
	(segment
		(start 143.325596 -75.34275)
		(end 143.455644 -75.34275)
		(width 0.0889)
		(layer "In9.Cu")
		(net "UPI_CPU0_CPU1_P0P0_DP<14>")
	)
	(segment
		(start 318.373506 -78.804262)
		(end 318.232282 -78.670404)
		(width 0.1143)
		(layer "In9.Cu")
		(net "UPI_CPU0_CPU1_P0P0_DP<14>")
	)
	(segment
		(start 175.442626 -115.192302)
		(end 175.7553 -115.333272)
		(width 0.1143)
		(layer "In9.Cu")
		(net "UPI_CPU0_CPU1_P0P0_DP<14>")
	)
	(segment
		(start 318.191642 -77.205332)
		(end 318.185038 -76.976224)
		(width 0.1143)
		(layer "In9.Cu")
		(net "UPI_CPU0_CPU1_P0P0_DP<14>")
	)
	(segment
		(start 175.291242 -115.249706)
		(end 175.442626 -115.192302)
		(width 0.1143)
		(layer "In9.Cu")
		(net "UPI_CPU0_CPU1_P0P0_DP<14>")
	)
	(segment
		(start 318.271906 -75.141582)
		(end 318.1985 -75.071986)
		(width 0.1143)
		(layer "In9.Cu")
		(net "UPI_CPU0_CPU1_P0P0_DP<14>")
	)
	(segment
		(start 227.903532 -114.892836)
		(end 248.025158 -118.319296)
		(width 0.1143)
		(layer "In9.Cu")
		(net "UPI_CPU0_CPU1_P0P0_DP<14>")
	)
	(segment
		(start 143.199866 -75.21702)
		(end 143.325596 -75.34275)
		(width 0.0889)
		(layer "In9.Cu")
		(net "UPI_CPU0_CPU1_P0P0_DP<14>")
	)
	(segment
		(start 318.1985 -77.211936)
		(end 318.191642 -77.205332)
		(width 0.1143)
		(layer "In9.Cu")
		(net "UPI_CPU0_CPU1_P0P0_DP<14>")
	)
	(segment
		(start 309.433468 -112.959896)
		(end 321.468496 -101.838252)
		(width 0.1143)
		(layer "In9.Cu")
		(net "UPI_CPU0_CPU1_P0P0_DP<14>")
	)
	(segment
		(start 309.0418 -61.525404)
		(end 309.0418 -61.647324)
		(width 0.1143)
		(layer "In9.Cu")
		(net "UPI_CPU0_CPU1_P0P0_DP<14>")
	)
	(segment
		(start 174.921418 -114.957606)
		(end 174.978822 -115.10899)
		(width 0.1143)
		(layer "In9.Cu")
		(net "UPI_CPU0_CPU1_P0P0_DP<14>")
	)
	(segment
		(start 318.1985 -75.071986)
		(end 318.130682 -75.007724)
		(width 0.1143)
		(layer "In9.Cu")
		(net "UPI_CPU0_CPU1_P0P0_DP<14>")
	)
	(segment
		(start 193.928238 -118.923054)
		(end 197.015608 -118.61165)
		(width 0.1143)
		(layer "In9.Cu")
		(net "UPI_CPU0_CPU1_P0P0_DP<14>")
	)
	(segment
		(start 172.893228 -114.16919)
		(end 173.623732 -114.498374)
		(width 0.1143)
		(layer "In9.Cu")
		(net "UPI_CPU0_CPU1_P0P0_DP<14>")
	)
	(segment
		(start 318.414146 -80.269334)
		(end 318.272922 -80.135476)
		(width 0.1143)
		(layer "In9.Cu")
		(net "UPI_CPU0_CPU1_P0P0_DP<14>")
	)
	(segment
		(start 145.166588 -75.867006)
		(end 145.217388 -75.816206)
		(width 0.0889)
		(layer "In9.Cu")
		(net "UPI_CPU0_CPU1_P0P0_DP<14>")
	)
	(segment
		(start 319.858898 -84.430362)
		(end 318.902842 -81.915)
		(width 0.1143)
		(layer "In9.Cu")
		(net "UPI_CPU0_CPU1_P0P0_DP<14>")
	)
	(segment
		(start 318.151002 -75.74026)
		(end 318.144398 -75.511152)
		(width 0.1143)
		(layer "In9.Cu")
		(net "UPI_CPU0_CPU1_P0P0_DP<14>")
	)
	(segment
		(start 174.45736 -114.87404)
		(end 174.608744 -114.816636)
		(width 0.1143)
		(layer "In9.Cu")
		(net "UPI_CPU0_CPU1_P0P0_DP<14>")
	)
	(segment
		(start 318.38011 -79.032862)
		(end 318.373506 -78.804262)
		(width 0.1143)
		(layer "In9.Cu")
		(net "UPI_CPU0_CPU1_P0P0_DP<14>")
	)
	(segment
		(start 318.1985 -76.208128)
		(end 318.29883 -76.102718)
		(width 0.1143)
		(layer "In9.Cu")
		(net "UPI_CPU0_CPU1_P0P0_DP<14>")
	)
	(segment
		(start 318.205358 -77.70876)
		(end 318.33947 -77.56779)
		(width 0.1143)
		(layer "In9.Cu")
		(net "UPI_CPU0_CPU1_P0P0_DP<14>")
	)
	(segment
		(start 318.1985 -75.454256)
		(end 318.27851 -75.370182)
		(width 0.1143)
		(layer "In9.Cu")
		(net "UPI_CPU0_CPU1_P0P0_DP<14>")
	)
	(segment
		(start 318.1985 -76.49845)
		(end 318.171322 -76.472796)
		(width 0.1143)
		(layer "In9.Cu")
		(net "UPI_CPU0_CPU1_P0P0_DP<14>")
	)
	(segment
		(start 291.125402 -116.711984)
		(end 292.342062 -116.852954)
		(width 0.1143)
		(layer "In9.Cu")
		(net "UPI_CPU0_CPU1_P0P0_DP<14>")
	)
	(segment
		(start 174.978822 -115.10899)
		(end 175.291242 -115.249706)
		(width 0.1143)
		(layer "In9.Cu")
		(net "UPI_CPU0_CPU1_P0P0_DP<14>")
	)
	(segment
		(start 278.038306 -115.194588)
		(end 291.125402 -116.711984)
		(width 0.1143)
		(layer "In9.Cu")
		(net "UPI_CPU0_CPU1_P0P0_DP<14>")
	)
	(segment
		(start 143.074136 -74.961242)
		(end 143.199866 -75.086972)
		(width 0.0889)
		(layer "In9.Cu")
		(net "UPI_CPU0_CPU1_P0P0_DP<14>")
	)
	(segment
		(start 318.292226 -75.874118)
		(end 318.1985 -75.785218)
		(width 0.1143)
		(layer "In9.Cu")
		(net "UPI_CPU0_CPU1_P0P0_DP<14>")
	)
	(segment
		(start 181.788054 -118.176294)
		(end 185.81497 -119.47525)
		(width 0.1143)
		(layer "In9.Cu")
		(net "UPI_CPU0_CPU1_P0P0_DP<14>")
	)
	(segment
		(start 318.171322 -76.472796)
		(end 318.164718 -76.243688)
		(width 0.1143)
		(layer "In9.Cu")
		(net "UPI_CPU0_CPU1_P0P0_DP<14>")
	)
	(segment
		(start 142.731744 -74.748898)
		(end 142.944088 -74.961242)
		(width 0.0889)
		(layer "In9.Cu")
		(net "UPI_CPU0_CPU1_P0P0_DP<14>")
	)
	(segment
		(start 318.211962 -77.937868)
		(end 318.205358 -77.70876)
		(width 0.1143)
		(layer "In9.Cu")
		(net "UPI_CPU0_CPU1_P0P0_DP<14>")
	)
	(segment
		(start 318.33947 -77.56779)
		(end 318.332866 -77.33919)
		(width 0.1143)
		(layer "In9.Cu")
		(net "UPI_CPU0_CPU1_P0P0_DP<14>")
	)
	(segment
		(start 318.245998 -79.173832)
		(end 318.38011 -79.032862)
		(width 0.1143)
		(layer "In9.Cu")
		(net "UPI_CPU0_CPU1_P0P0_DP<14>")
	)
	(segment
		(start 318.1985 -73.391522)
		(end 316.338204 -68.4276)
		(width 0.1143)
		(layer "In9.Cu")
		(net "UPI_CPU0_CPU1_P0P0_DP<14>")
	)
	(segment
		(start 174.608744 -114.816636)
		(end 174.921418 -114.957606)
		(width 0.1143)
		(layer "In9.Cu")
		(net "UPI_CPU0_CPU1_P0P0_DP<14>")
	)
	(segment
		(start 318.27851 -75.370182)
		(end 318.271906 -75.141582)
		(width 0.1143)
		(layer "In9.Cu")
		(net "UPI_CPU0_CPU1_P0P0_DP<14>")
	)
	(segment
		(start 318.1985 -74.358754)
		(end 318.110362 -74.275188)
		(width 0.1143)
		(layer "In9.Cu")
		(net "UPI_CPU0_CPU1_P0P0_DP<14>")
	)
	(segment
		(start 258.679442 -115.809776)
		(end 267.241274 -116.231416)
		(width 0.1143)
		(layer "In9.Cu")
		(net "UPI_CPU0_CPU1_P0P0_DP<14>")
	)
	(segment
		(start 318.252602 -79.40294)
		(end 318.245998 -79.173832)
		(width 0.1143)
		(layer "In9.Cu")
		(net "UPI_CPU0_CPU1_P0P0_DP<14>")
	)
	(segment
		(start 175.81245 -115.484148)
		(end 181.788054 -118.176294)
		(width 0.1143)
		(layer "In9.Cu")
		(net "UPI_CPU0_CPU1_P0P0_DP<14>")
	)
	(segment
		(start 248.025158 -118.319296)
		(end 258.679442 -115.809776)
		(width 0.1143)
		(layer "In9.Cu")
		(net "UPI_CPU0_CPU1_P0P0_DP<14>")
	)
	(segment
		(start 310.27497 -61.3918)
		(end 309.175404 -61.3918)
		(width 0.1143)
		(layer "In9.Cu")
		(net "UPI_CPU0_CPU1_P0P0_DP<14>")
	)
	(segment
		(start 174.08779 -114.58194)
		(end 174.14494 -114.733324)
		(width 0.1143)
		(layer "In9.Cu")
		(net "UPI_CPU0_CPU1_P0P0_DP<14>")
	)
	(segment
		(start 175.7553 -115.333272)
		(end 175.81245 -115.484148)
		(width 0.1143)
		(layer "In9.Cu")
		(net "UPI_CPU0_CPU1_P0P0_DP<14>")
	)
	(segment
		(start 143.199866 -75.086972)
		(end 143.199866 -75.21702)
		(width 0.0889)
		(layer "In9.Cu")
		(net "UPI_CPU0_CPU1_P0P0_DP<14>")
	)
	(segment
		(start 292.342062 -116.852954)
		(end 309.433468 -112.959896)
		(width 0.1143)
		(layer "In9.Cu")
		(net "UPI_CPU0_CPU1_P0P0_DP<14>")
	)
	(segment
		(start 318.40043 -79.765398)
		(end 318.393826 -79.536798)
		(width 0.1143)
		(layer "In9.Cu")
		(net "UPI_CPU0_CPU1_P0P0_DP<14>")
	)
	(segment
		(start 318.164718 -76.243688)
		(end 318.1985 -76.208128)
		(width 0.1143)
		(layer "In9.Cu")
		(net "UPI_CPU0_CPU1_P0P0_DP<14>")
	)
	(segment
		(start 322.66509 -98.212148)
		(end 321.761866 -93.7768)
		(width 0.1143)
		(layer "In9.Cu")
		(net "UPI_CPU0_CPU1_P0P0_DP<14>")
	)
	(segment
		(start 144.1323 -75.77201)
		(end 144.3101 -75.77201)
		(width 0.0889)
		(layer "In9.Cu")
		(net "UPI_CPU0_CPU1_P0P0_DP<14>")
	)
	(segment
		(start 138.518138 -72.649588)
		(end 138.550904 -72.649588)
		(width 0.0889)
		(layer "In9.Cu")
		(net "UPI_CPU0_CPU1_P0P0_DP<14>")
	)
	(segment
		(start 145.888456 -75.816206)
		(end 146.90217 -76.228956)
		(width 0.1143)
		(layer "In9.Cu")
		(net "UPI_CPU0_CPU1_P0P0_DP<14>")
	)
	(segment
		(start 318.266318 -79.906368)
		(end 318.33693 -79.8322)
		(width 0.1143)
		(layer "In9.Cu")
		(net "UPI_CPU0_CPU1_P0P0_DP<14>")
	)
	(segment
		(start 143.849852 -75.867006)
		(end 144.037304 -75.867006)
		(width 0.0889)
		(layer "In9.Cu")
		(net "UPI_CPU0_CPU1_P0P0_DP<14>")
	)
	(segment
		(start 318.31915 -76.835254)
		(end 318.312546 -76.606654)
		(width 0.1143)
		(layer "In9.Cu")
		(net "UPI_CPU0_CPU1_P0P0_DP<14>")
	)
	(segment
		(start 318.353186 -78.071726)
		(end 318.211962 -77.937868)
		(width 0.1143)
		(layer "In9.Cu")
		(net "UPI_CPU0_CPU1_P0P0_DP<14>")
	)
	(segment
		(start 149.351238 -78.791054)
		(end 152.117044 -88.991694)
		(width 0.1143)
		(layer "In9.Cu")
		(net "UPI_CPU0_CPU1_P0P0_DP<14>")
	)
	(segment
		(start 318.425068 -80.658208)
		(end 318.414146 -80.269334)
		(width 0.1143)
		(layer "In9.Cu")
		(net "UPI_CPU0_CPU1_P0P0_DP<14>")
	)
	(segment
		(start 142.070074 -74.748898)
		(end 142.731744 -74.748898)
		(width 0.0889)
		(layer "In9.Cu")
		(net "UPI_CPU0_CPU1_P0P0_DP<14>")
	)
	(segment
		(start 318.312546 -76.606654)
		(end 318.1985 -76.49845)
		(width 0.1143)
		(layer "In9.Cu")
		(net "UPI_CPU0_CPU1_P0P0_DP<14>")
	)
	(segment
		(start 173.623732 -114.498374)
		(end 173.774862 -114.44097)
		(width 0.1143)
		(layer "In9.Cu")
		(net "UPI_CPU0_CPU1_P0P0_DP<14>")
	)
	(segment
		(start 318.332866 -77.33919)
		(end 318.1985 -77.211936)
		(width 0.1143)
		(layer "In9.Cu")
		(net "UPI_CPU0_CPU1_P0P0_DP<14>")
	)
	(segment
		(start 315.441076 -66.03365)
		(end 310.27497 -61.3918)
		(width 0.1143)
		(layer "In9.Cu")
		(net "UPI_CPU0_CPU1_P0P0_DP<14>")
	)
	(segment
		(start 318.232282 -78.670404)
		(end 318.225678 -78.441296)
		(width 0.1143)
		(layer "In9.Cu")
		(net "UPI_CPU0_CPU1_P0P0_DP<14>")
	)
	(arc
		(start 138.129264 -72.25919)
		(mid 138.245816 -72.531959)
		(end 138.518138 -72.649588)
		(width 0.0889)
		(layer "In9.Cu")
		(net "UPI_CPU0_CPU1_P0P0_DP<14>")
	)
	(arc
		(start 139.899644 -73.440036)
		(mid 140.038388 -73.582069)
		(end 140.22832 -73.639934)
		(width 0.0889)
		(layer "In9.Cu")
		(net "UPI_CPU0_CPU1_P0P0_DP<14>")
	)
	(arc
		(start 138.550904 -72.649588)
		(mid 138.834121 -72.733869)
		(end 139.041124 -72.944736)
		(width 0.0889)
		(layer "In9.Cu")
		(net "UPI_CPU0_CPU1_P0P0_DP<14>")
	)
	(arc
		(start 139.405614 -73.144634)
		(mid 139.691038 -73.228101)
		(end 139.899644 -73.440036)
		(width 0.0889)
		(layer "In9.Cu")
		(net "UPI_CPU0_CPU1_P0P0_DP<14>")
	)
	(arc
		(start 139.041124 -72.944736)
		(mid 139.181203 -73.087472)
		(end 139.372848 -73.144634)
		(width 0.0889)
		(layer "In9.Cu")
		(net "UPI_CPU0_CPU1_P0P0_DP<14>")
	)
	(arc
		(start 138.157458 -72.10171)
		(mid 138.135413 -72.179027)
		(end 138.129264 -72.25919)
		(width 0.0889)
		(layer "In9.Cu")
		(net "UPI_CPU0_CPU1_P0P0_DP<14>")
	)
	(segment
		(start 137.099294 -70.763384)
		(end 137.670794 -70.763384)
		(width 0.1143)
		(layer "F.Cu")
		(net "UPI_CPU0_CPU1_P0P0_DP<13>")
	)
	(segment
		(start 305.533806 -63.829184)
		(end 306.105306 -63.829184)
		(width 0.1143)
		(layer "F.Cu")
		(net "UPI_CPU0_CPU1_P0P0_DP<13>")
	)
	(via
		(at 306.105306 -63.829184)
		(size 0.508)
		(drill 0.254)
		(layers "F.Cu" "B.Cu")
		(net "UPI_CPU0_CPU1_P0P0_DP<13>")
	)
	(via
		(at 137.670794 -70.763384)
		(size 0.508)
		(drill 0.254)
		(layers "F.Cu" "B.Cu")
		(net "UPI_CPU0_CPU1_P0P0_DP<13>")
	)
	(segment
		(start 317.54699 -77.01407)
		(end 317.392812 -76.86802)
		(width 0.1143)
		(layer "In9.Cu")
		(net "UPI_CPU0_CPU1_P0P0_DP<13>")
	)
	(segment
		(start 139.372848 -72.154034)
		(end 139.405614 -72.154034)
		(width 0.0889)
		(layer "In9.Cu")
		(net "UPI_CPU0_CPU1_P0P0_DP<13>")
	)
	(segment
		(start 320.959988 -101.439472)
		(end 321.027298 -101.317298)
		(width 0.1143)
		(layer "In9.Cu")
		(net "UPI_CPU0_CPU1_P0P0_DP<13>")
	)
	(segment
		(start 143.04137 -74.13879)
		(end 143.063468 -74.13879)
		(width 0.0889)
		(layer "In9.Cu")
		(net "UPI_CPU0_CPU1_P0P0_DP<13>")
	)
	(segment
		(start 278.044402 -114.553238)
		(end 291.125402 -116.069872)
		(width 0.1143)
		(layer "In9.Cu")
		(net "UPI_CPU0_CPU1_P0P0_DP<13>")
	)
	(segment
		(start 317.476124 -79.8322)
		(end 317.471552 -79.670402)
		(width 0.1143)
		(layer "In9.Cu")
		(net "UPI_CPU0_CPU1_P0P0_DP<13>")
	)
	(segment
		(start 306.78247 -62.9158)
		(end 306.269136 -63.429134)
		(width 0.0889)
		(layer "In9.Cu")
		(net "UPI_CPU0_CPU1_P0P0_DP<13>")
	)
	(segment
		(start 315.63945 -68.4276)
		(end 314.908184 -66.426842)
		(width 0.1143)
		(layer "In9.Cu")
		(net "UPI_CPU0_CPU1_P0P0_DP<13>")
	)
	(segment
		(start 137.377678 -70.932548)
		(end 137.356596 -71.011288)
		(width 0.0889)
		(layer "In9.Cu")
		(net "UPI_CPU0_CPU1_P0P0_DP<13>")
	)
	(segment
		(start 190.55715 -118.514622)
		(end 194.729862 -118.232428)
		(width 0.1143)
		(layer "In9.Cu")
		(net "UPI_CPU0_CPU1_P0P0_DP<13>")
	)
	(segment
		(start 317.449454 -73.378822)
		(end 315.63945 -68.4276)
		(width 0.1143)
		(layer "In9.Cu")
		(net "UPI_CPU0_CPU1_P0P0_DP<13>")
	)
	(segment
		(start 317.328804 -74.594212)
		(end 317.3222 -74.36485)
		(width 0.1143)
		(layer "In9.Cu")
		(net "UPI_CPU0_CPU1_P0P0_DP<13>")
	)
	(segment
		(start 321.9704 -98.939096)
		(end 322.000372 -98.543872)
		(width 0.1143)
		(layer "In9.Cu")
		(net "UPI_CPU0_CPU1_P0P0_DP<13>")
	)
	(segment
		(start 321.91198 -99.709478)
		(end 321.9704 -98.939096)
		(width 0.1143)
		(layer "In9.Cu")
		(net "UPI_CPU0_CPU1_P0P0_DP<13>")
	)
	(segment
		(start 317.648336 -80.618838)
		(end 317.632334 -80.045814)
		(width 0.1143)
		(layer "In9.Cu")
		(net "UPI_CPU0_CPU1_P0P0_DP<13>")
	)
	(segment
		(start 318.141096 -81.915)
		(end 317.648336 -80.618838)
		(width 0.1143)
		(layer "In9.Cu")
		(net "UPI_CPU0_CPU1_P0P0_DP<13>")
	)
	(segment
		(start 308.72684 -63.447676)
		(end 308.653942 -63.396622)
		(width 0.0889)
		(layer "In9.Cu")
		(net "UPI_CPU0_CPU1_P0P0_DP<13>")
	)
	(segment
		(start 317.471552 -79.670402)
		(end 317.617602 -79.516732)
		(width 0.1143)
		(layer "In9.Cu")
		(net "UPI_CPU0_CPU1_P0P0_DP<13>")
	)
	(segment
		(start 142.99057 -74.18959)
		(end 143.04137 -74.13879)
		(width 0.0889)
		(layer "In9.Cu")
		(net "UPI_CPU0_CPU1_P0P0_DP<13>")
	)
	(segment
		(start 138.518138 -71.658988)
		(end 138.550904 -71.658988)
		(width 0.0889)
		(layer "In9.Cu")
		(net "UPI_CPU0_CPU1_P0P0_DP<13>")
	)
	(segment
		(start 317.489586 -74.969116)
		(end 317.482982 -74.740262)
		(width 0.1143)
		(layer "In9.Cu")
		(net "UPI_CPU0_CPU1_P0P0_DP<13>")
	)
	(segment
		(start 267.226288 -115.592098)
		(end 278.044402 -114.553238)
		(width 0.1143)
		(layer "In9.Cu")
		(net "UPI_CPU0_CPU1_P0P0_DP<13>")
	)
	(segment
		(start 321.111118 -93.7768)
		(end 319.33642 -85.060028)
		(width 0.1143)
		(layer "In9.Cu")
		(net "UPI_CPU0_CPU1_P0P0_DP<13>")
	)
	(segment
		(start 319.33642 -85.060028)
		(end 318.1985 -82.06613)
		(width 0.1143)
		(layer "In9.Cu")
		(net "UPI_CPU0_CPU1_P0P0_DP<13>")
	)
	(segment
		(start 321.027298 -101.317298)
		(end 321.91198 -99.709478)
		(width 0.1143)
		(layer "In9.Cu")
		(net "UPI_CPU0_CPU1_P0P0_DP<13>")
	)
	(segment
		(start 141.293342 -73.167494)
		(end 142.315438 -74.18959)
		(width 0.0889)
		(layer "In9.Cu")
		(net "UPI_CPU0_CPU1_P0P0_DP<13>")
	)
	(segment
		(start 317.364872 -75.880722)
		(end 317.510922 -75.727052)
		(width 0.1143)
		(layer "In9.Cu")
		(net "UPI_CPU0_CPU1_P0P0_DP<13>")
	)
	(segment
		(start 306.105306 -63.995046)
		(end 306.105306 -63.829184)
		(width 0.0889)
		(layer "In9.Cu")
		(net "UPI_CPU0_CPU1_P0P0_DP<13>")
	)
	(segment
		(start 317.482982 -74.740262)
		(end 317.328804 -74.594212)
		(width 0.1143)
		(layer "In9.Cu")
		(net "UPI_CPU0_CPU1_P0P0_DP<13>")
	)
	(segment
		(start 147.243038 -75.555602)
		(end 149.88413 -78.318614)
		(width 0.1143)
		(layer "In9.Cu")
		(net "UPI_CPU0_CPU1_P0P0_DP<13>")
	)
	(segment
		(start 159.689292 -100.983796)
		(end 172.01769 -112.746028)
		(width 0.1143)
		(layer "In9.Cu")
		(net "UPI_CPU0_CPU1_P0P0_DP<13>")
	)
	(segment
		(start 291.125402 -116.069872)
		(end 292.30701 -116.206778)
		(width 0.1143)
		(layer "In9.Cu")
		(net "UPI_CPU0_CPU1_P0P0_DP<13>")
	)
	(segment
		(start 317.504318 -75.498198)
		(end 317.35014 -75.352148)
		(width 0.1143)
		(layer "In9.Cu")
		(net "UPI_CPU0_CPU1_P0P0_DP<13>")
	)
	(segment
		(start 308.653942 -63.396622)
		(end 308.252368 -63.393828)
		(width 0.0889)
		(layer "In9.Cu")
		(net "UPI_CPU0_CPU1_P0P0_DP<13>")
	)
	(segment
		(start 137.670794 -70.763384)
		(end 137.377678 -70.932548)
		(width 0.0889)
		(layer "In9.Cu")
		(net "UPI_CPU0_CPU1_P0P0_DP<13>")
	)
	(segment
		(start 318.1985 -82.06613)
		(end 318.141096 -81.915)
		(width 0.1143)
		(layer "In9.Cu")
		(net "UPI_CPU0_CPU1_P0P0_DP<13>")
	)
	(segment
		(start 141.03858 -72.912732)
		(end 141.167612 -72.912732)
		(width 0.0889)
		(layer "In9.Cu")
		(net "UPI_CPU0_CPU1_P0P0_DP<13>")
	)
	(segment
		(start 141.293342 -73.038462)
		(end 141.293342 -73.167494)
		(width 0.0889)
		(layer "In9.Cu")
		(net "UPI_CPU0_CPU1_P0P0_DP<13>")
	)
	(segment
		(start 317.589662 -78.529942)
		(end 317.435484 -78.383892)
		(width 0.1143)
		(layer "In9.Cu")
		(net "UPI_CPU0_CPU1_P0P0_DP<13>")
	)
	(segment
		(start 307.323236 -62.9158)
		(end 306.78247 -62.9158)
		(width 0.0889)
		(layer "In9.Cu")
		(net "UPI_CPU0_CPU1_P0P0_DP<13>")
	)
	(segment
		(start 317.610998 -79.287878)
		(end 317.45682 -79.141828)
		(width 0.1143)
		(layer "In9.Cu")
		(net "UPI_CPU0_CPU1_P0P0_DP<13>")
	)
	(segment
		(start 308.841394 -63.448692)
		(end 308.72684 -63.447676)
		(width 0.1143)
		(layer "In9.Cu")
		(net "UPI_CPU0_CPU1_P0P0_DP<13>")
	)
	(segment
		(start 140.775436 -72.649588)
		(end 141.03858 -72.912732)
		(width 0.0889)
		(layer "In9.Cu")
		(net "UPI_CPU0_CPU1_P0P0_DP<13>")
	)
	(segment
		(start 308.252368 -63.393828)
		(end 307.323236 -62.9158)
		(width 0.0889)
		(layer "In9.Cu")
		(net "UPI_CPU0_CPU1_P0P0_DP<13>")
	)
	(segment
		(start 149.88413 -78.318614)
		(end 152.696418 -88.689434)
		(width 0.1143)
		(layer "In9.Cu")
		(net "UPI_CPU0_CPU1_P0P0_DP<13>")
	)
	(segment
		(start 317.42888 -78.15453)
		(end 317.57493 -78.00086)
		(width 0.1143)
		(layer "In9.Cu")
		(net "UPI_CPU0_CPU1_P0P0_DP<13>")
	)
	(segment
		(start 317.386208 -76.638658)
		(end 317.532258 -76.484988)
		(width 0.1143)
		(layer "In9.Cu")
		(net "UPI_CPU0_CPU1_P0P0_DP<13>")
	)
	(segment
		(start 152.696418 -88.689434)
		(end 158.929324 -96.065086)
		(width 0.1143)
		(layer "In9.Cu")
		(net "UPI_CPU0_CPU1_P0P0_DP<13>")
	)
	(segment
		(start 317.510922 -75.727052)
		(end 317.504318 -75.498198)
		(width 0.1143)
		(layer "In9.Cu")
		(net "UPI_CPU0_CPU1_P0P0_DP<13>")
	)
	(segment
		(start 311.593484 -63.448692)
		(end 308.841394 -63.448692)
		(width 0.1143)
		(layer "In9.Cu")
		(net "UPI_CPU0_CPU1_P0P0_DP<13>")
	)
	(segment
		(start 248.004838 -117.668802)
		(end 258.620768 -115.168426)
		(width 0.1143)
		(layer "In9.Cu")
		(net "UPI_CPU0_CPU1_P0P0_DP<13>")
	)
	(segment
		(start 184.56656 -118.348252)
		(end 186.119262 -118.81485)
		(width 0.1143)
		(layer "In9.Cu")
		(net "UPI_CPU0_CPU1_P0P0_DP<13>")
	)
	(segment
		(start 317.478156 -79.899764)
		(end 317.476124 -79.8322)
		(width 0.1143)
		(layer "In9.Cu")
		(net "UPI_CPU0_CPU1_P0P0_DP<13>")
	)
	(segment
		(start 317.525654 -76.256134)
		(end 317.371476 -76.110084)
		(width 0.1143)
		(layer "In9.Cu")
		(net "UPI_CPU0_CPU1_P0P0_DP<13>")
	)
	(segment
		(start 317.617602 -79.516732)
		(end 317.610998 -79.287878)
		(width 0.1143)
		(layer "In9.Cu")
		(net "UPI_CPU0_CPU1_P0P0_DP<13>")
	)
	(segment
		(start 317.57493 -78.00086)
		(end 317.568326 -77.772006)
		(width 0.1143)
		(layer "In9.Cu")
		(net "UPI_CPU0_CPU1_P0P0_DP<13>")
	)
	(segment
		(start 317.435484 -78.383892)
		(end 317.42888 -78.15453)
		(width 0.1143)
		(layer "In9.Cu")
		(net "UPI_CPU0_CPU1_P0P0_DP<13>")
	)
	(segment
		(start 322.000372 -98.543872)
		(end 322.02247 -98.252534)
		(width 0.1143)
		(layer "In9.Cu")
		(net "UPI_CPU0_CPU1_P0P0_DP<13>")
	)
	(segment
		(start 321.9704 -97.996756)
		(end 321.111118 -93.7768)
		(width 0.1143)
		(layer "In9.Cu")
		(net "UPI_CPU0_CPU1_P0P0_DP<13>")
	)
	(segment
		(start 141.167612 -72.912732)
		(end 141.293342 -73.038462)
		(width 0.0889)
		(layer "In9.Cu")
		(net "UPI_CPU0_CPU1_P0P0_DP<13>")
	)
	(segment
		(start 317.568326 -77.772006)
		(end 317.414148 -77.625956)
		(width 0.1143)
		(layer "In9.Cu")
		(net "UPI_CPU0_CPU1_P0P0_DP<13>")
	)
	(segment
		(start 158.929324 -96.065086)
		(end 159.689292 -100.983796)
		(width 0.1143)
		(layer "In9.Cu")
		(net "UPI_CPU0_CPU1_P0P0_DP<13>")
	)
	(segment
		(start 317.45682 -79.141828)
		(end 317.450216 -78.912466)
		(width 0.1143)
		(layer "In9.Cu")
		(net "UPI_CPU0_CPU1_P0P0_DP<13>")
	)
	(segment
		(start 172.01769 -112.746028)
		(end 184.56656 -118.348252)
		(width 0.1143)
		(layer "In9.Cu")
		(net "UPI_CPU0_CPU1_P0P0_DP<13>")
	)
	(segment
		(start 314.908184 -66.426842)
		(end 311.593484 -63.448692)
		(width 0.1143)
		(layer "In9.Cu")
		(net "UPI_CPU0_CPU1_P0P0_DP<13>")
	)
	(segment
		(start 305.73345 -63.977012)
		(end 305.766216 -64.059816)
		(width 0.0889)
		(layer "In9.Cu")
		(net "UPI_CPU0_CPU1_P0P0_DP<13>")
	)
	(segment
		(start 194.729862 -118.232428)
		(end 227.877878 -114.24158)
		(width 0.1143)
		(layer "In9.Cu")
		(net "UPI_CPU0_CPU1_P0P0_DP<13>")
	)
	(segment
		(start 186.119262 -118.81485)
		(end 186.325256 -118.80088)
		(width 0.1143)
		(layer "In9.Cu")
		(net "UPI_CPU0_CPU1_P0P0_DP<13>")
	)
	(segment
		(start 143.342868 -74.13879)
		(end 147.243038 -75.555602)
		(width 0.1143)
		(layer "In9.Cu")
		(net "UPI_CPU0_CPU1_P0P0_DP<13>")
	)
	(segment
		(start 317.468758 -74.21118)
		(end 317.449454 -73.378822)
		(width 0.1143)
		(layer "In9.Cu")
		(net "UPI_CPU0_CPU1_P0P0_DP<13>")
	)
	(segment
		(start 143.063468 -74.13879)
		(end 143.342868 -74.13879)
		(width 0.1143)
		(layer "In9.Cu")
		(net "UPI_CPU0_CPU1_P0P0_DP<13>")
	)
	(segment
		(start 322.02247 -98.252534)
		(end 321.9704 -97.996756)
		(width 0.1143)
		(layer "In9.Cu")
		(net "UPI_CPU0_CPU1_P0P0_DP<13>")
	)
	(segment
		(start 186.325256 -118.80088)
		(end 190.55715 -118.514622)
		(width 0.1143)
		(layer "In9.Cu")
		(net "UPI_CPU0_CPU1_P0P0_DP<13>")
	)
	(segment
		(start 317.392812 -76.86802)
		(end 317.386208 -76.638658)
		(width 0.1143)
		(layer "In9.Cu")
		(net "UPI_CPU0_CPU1_P0P0_DP<13>")
	)
	(segment
		(start 227.877878 -114.24158)
		(end 248.004838 -117.668802)
		(width 0.1143)
		(layer "In9.Cu")
		(net "UPI_CPU0_CPU1_P0P0_DP<13>")
	)
	(segment
		(start 142.315438 -74.18959)
		(end 142.99057 -74.18959)
		(width 0.0889)
		(layer "In9.Cu")
		(net "UPI_CPU0_CPU1_P0P0_DP<13>")
	)
	(segment
		(start 137.655808 -71.163434)
		(end 137.688574 -71.163434)
		(width 0.0889)
		(layer "In9.Cu")
		(net "UPI_CPU0_CPU1_P0P0_DP<13>")
	)
	(segment
		(start 317.414148 -77.625956)
		(end 317.407544 -77.396594)
		(width 0.1143)
		(layer "In9.Cu")
		(net "UPI_CPU0_CPU1_P0P0_DP<13>")
	)
	(segment
		(start 317.596266 -78.758796)
		(end 317.589662 -78.529942)
		(width 0.1143)
		(layer "In9.Cu")
		(net "UPI_CPU0_CPU1_P0P0_DP<13>")
	)
	(segment
		(start 317.513208 -77.285342)
		(end 317.553594 -77.242924)
		(width 0.1143)
		(layer "In9.Cu")
		(net "UPI_CPU0_CPU1_P0P0_DP<13>")
	)
	(segment
		(start 317.532258 -76.484988)
		(end 317.525654 -76.256134)
		(width 0.1143)
		(layer "In9.Cu")
		(net "UPI_CPU0_CPU1_P0P0_DP<13>")
	)
	(segment
		(start 317.35014 -75.352148)
		(end 317.343536 -75.122786)
		(width 0.1143)
		(layer "In9.Cu")
		(net "UPI_CPU0_CPU1_P0P0_DP<13>")
	)
	(segment
		(start 306.269136 -63.429134)
		(end 306.09413 -63.429134)
		(width 0.0889)
		(layer "In9.Cu")
		(net "UPI_CPU0_CPU1_P0P0_DP<13>")
	)
	(segment
		(start 317.3222 -74.36485)
		(end 317.468758 -74.21118)
		(width 0.1143)
		(layer "In9.Cu")
		(net "UPI_CPU0_CPU1_P0P0_DP<13>")
	)
	(segment
		(start 258.620768 -115.168426)
		(end 267.226288 -115.592098)
		(width 0.1143)
		(layer "In9.Cu")
		(net "UPI_CPU0_CPU1_P0P0_DP<13>")
	)
	(segment
		(start 292.30701 -116.206778)
		(end 309.126636 -112.37595)
		(width 0.1143)
		(layer "In9.Cu")
		(net "UPI_CPU0_CPU1_P0P0_DP<13>")
	)
	(segment
		(start 317.371476 -76.110084)
		(end 317.364872 -75.880722)
		(width 0.1143)
		(layer "In9.Cu")
		(net "UPI_CPU0_CPU1_P0P0_DP<13>")
	)
	(segment
		(start 317.343536 -75.122786)
		(end 317.489586 -74.969116)
		(width 0.1143)
		(layer "In9.Cu")
		(net "UPI_CPU0_CPU1_P0P0_DP<13>")
	)
	(segment
		(start 140.235178 -72.649588)
		(end 140.775436 -72.649588)
		(width 0.0889)
		(layer "In9.Cu")
		(net "UPI_CPU0_CPU1_P0P0_DP<13>")
	)
	(segment
		(start 317.632334 -80.045814)
		(end 317.478156 -79.899764)
		(width 0.1143)
		(layer "In9.Cu")
		(net "UPI_CPU0_CPU1_P0P0_DP<13>")
	)
	(segment
		(start 317.553594 -77.242924)
		(end 317.54699 -77.01407)
		(width 0.1143)
		(layer "In9.Cu")
		(net "UPI_CPU0_CPU1_P0P0_DP<13>")
	)
	(segment
		(start 317.450216 -78.912466)
		(end 317.596266 -78.758796)
		(width 0.1143)
		(layer "In9.Cu")
		(net "UPI_CPU0_CPU1_P0P0_DP<13>")
	)
	(segment
		(start 309.126636 -112.37595)
		(end 320.959988 -101.439472)
		(width 0.1143)
		(layer "In9.Cu")
		(net "UPI_CPU0_CPU1_P0P0_DP<13>")
	)
	(segment
		(start 317.407544 -77.396594)
		(end 317.513208 -77.285342)
		(width 0.1143)
		(layer "In9.Cu")
		(net "UPI_CPU0_CPU1_P0P0_DP<13>")
	)
	(arc
		(start 139.899644 -72.449436)
		(mid 140.041327 -72.59324)
		(end 140.235178 -72.649588)
		(width 0.0889)
		(layer "In9.Cu")
		(net "UPI_CPU0_CPU1_P0P0_DP<13>")
	)
	(arc
		(start 138.182604 -71.458836)
		(mid 138.324287 -71.60264)
		(end 138.518138 -71.658988)
		(width 0.0889)
		(layer "In9.Cu")
		(net "UPI_CPU0_CPU1_P0P0_DP<13>")
	)
	(arc
		(start 138.550904 -71.658988)
		(mid 138.834121 -71.743269)
		(end 139.041124 -71.954136)
		(width 0.0889)
		(layer "In9.Cu")
		(net "UPI_CPU0_CPU1_P0P0_DP<13>")
	)
	(arc
		(start 306.09413 -63.429134)
		(mid 305.7711 -63.609187)
		(end 305.73345 -63.977012)
		(width 0.0889)
		(layer "In9.Cu")
		(net "UPI_CPU0_CPU1_P0P0_DP<13>")
	)
	(arc
		(start 137.356596 -71.011288)
		(mid 137.489477 -71.120271)
		(end 137.655808 -71.163434)
		(width 0.0889)
		(layer "In9.Cu")
		(net "UPI_CPU0_CPU1_P0P0_DP<13>")
	)
	(arc
		(start 139.405614 -72.154034)
		(mid 139.691038 -72.237501)
		(end 139.899644 -72.449436)
		(width 0.0889)
		(layer "In9.Cu")
		(net "UPI_CPU0_CPU1_P0P0_DP<13>")
	)
	(arc
		(start 305.766216 -64.059816)
		(mid 305.962509 -64.167621)
		(end 306.105306 -63.995046)
		(width 0.0889)
		(layer "In9.Cu")
		(net "UPI_CPU0_CPU1_P0P0_DP<13>")
	)
	(arc
		(start 137.688574 -71.163434)
		(mid 137.973998 -71.246901)
		(end 138.182604 -71.458836)
		(width 0.0889)
		(layer "In9.Cu")
		(net "UPI_CPU0_CPU1_P0P0_DP<13>")
	)
	(arc
		(start 139.041124 -71.954136)
		(mid 139.181203 -72.096872)
		(end 139.372848 -72.154034)
		(width 0.0889)
		(layer "In9.Cu")
		(net "UPI_CPU0_CPU1_P0P0_DP<13>")
	)
	(segment
		(start 306.392326 -64.324738)
		(end 306.963826 -64.324738)
		(width 0.1143)
		(layer "F.Cu")
		(net "UPI_CPU0_CPU1_P0P0_DP<12>")
	)
	(segment
		(start 135.382254 -68.782184)
		(end 135.953754 -68.782184)
		(width 0.1143)
		(layer "F.Cu")
		(net "UPI_CPU0_CPU1_P0P0_DP<12>")
	)
	(via
		(at 306.963826 -64.324738)
		(size 0.508)
		(drill 0.254)
		(layers "F.Cu" "B.Cu")
		(net "UPI_CPU0_CPU1_P0P0_DP<12>")
	)
	(via
		(at 135.953754 -68.782184)
		(size 0.508)
		(drill 0.254)
		(layers "F.Cu" "B.Cu")
		(net "UPI_CPU0_CPU1_P0P0_DP<12>")
	)
	(segment
		(start 316.778132 -77.780896)
		(end 316.771528 -77.552042)
		(width 0.1143)
		(layer "In9.Cu")
		(net "UPI_CPU0_CPU1_P0P0_DP<12>")
	)
	(segment
		(start 316.539626 -75.05065)
		(end 316.533022 -74.821542)
		(width 0.1143)
		(layer "In9.Cu")
		(net "UPI_CPU0_CPU1_P0P0_DP<12>")
	)
	(segment
		(start 316.6364 -75.142344)
		(end 316.539626 -75.05065)
		(width 0.1143)
		(layer "In9.Cu")
		(net "UPI_CPU0_CPU1_P0P0_DP<12>")
	)
	(segment
		(start 140.235178 -71.658988)
		(end 140.25753 -71.658988)
		(width 0.0889)
		(layer "In9.Cu")
		(net "UPI_CPU0_CPU1_P0P0_DP<12>")
	)
	(segment
		(start 316.642242 -78.728062)
		(end 316.799976 -78.5622)
		(width 0.1143)
		(layer "In9.Cu")
		(net "UPI_CPU0_CPU1_P0P0_DP<12>")
	)
	(segment
		(start 314.722002 -68.4276)
		(end 313.926982 -66.401442)
		(width 0.1143)
		(layer "In9.Cu")
		(net "UPI_CPU0_CPU1_P0P0_DP<12>")
	)
	(segment
		(start 139.372848 -71.163434)
		(end 139.405614 -71.163434)
		(width 0.0889)
		(layer "In9.Cu")
		(net "UPI_CPU0_CPU1_P0P0_DP<12>")
	)
	(segment
		(start 307.130704 -63.924688)
		(end 307.025802 -63.924688)
		(width 0.0889)
		(layer "In9.Cu")
		(net "UPI_CPU0_CPU1_P0P0_DP<12>")
	)
	(segment
		(start 307.347112 -64.121538)
		(end 307.346858 -64.121792)
		(width 0.0889)
		(layer "In9.Cu")
		(net "UPI_CPU0_CPU1_P0P0_DP<12>")
	)
	(segment
		(start 316.799976 -78.5622)
		(end 316.793372 -78.333346)
		(width 0.1143)
		(layer "In9.Cu")
		(net "UPI_CPU0_CPU1_P0P0_DP<12>")
	)
	(segment
		(start 316.674754 -74.006964)
		(end 316.65672 -73.358248)
		(width 0.1143)
		(layer "In9.Cu")
		(net "UPI_CPU0_CPU1_P0P0_DP<12>")
	)
	(segment
		(start 316.6364 -74.712576)
		(end 316.690756 -74.655426)
		(width 0.1143)
		(layer "In9.Cu")
		(net "UPI_CPU0_CPU1_P0P0_DP<12>")
	)
	(segment
		(start 316.705996 -75.20813)
		(end 316.6364 -75.142344)
		(width 0.1143)
		(layer "In9.Cu")
		(net "UPI_CPU0_CPU1_P0P0_DP<12>")
	)
	(segment
		(start 316.6364 -75.90282)
		(end 316.56147 -75.831954)
		(width 0.1143)
		(layer "In9.Cu")
		(net "UPI_CPU0_CPU1_P0P0_DP<12>")
	)
	(segment
		(start 316.734444 -76.218288)
		(end 316.72784 -75.989434)
		(width 0.1143)
		(layer "In9.Cu")
		(net "UPI_CPU0_CPU1_P0P0_DP<12>")
	)
	(segment
		(start 316.605158 -77.394562)
		(end 316.60211 -77.285342)
		(width 0.1143)
		(layer "In9.Cu")
		(net "UPI_CPU0_CPU1_P0P0_DP<12>")
	)
	(segment
		(start 306.963826 -63.986664)
		(end 306.963826 -64.324738)
		(width 0.0889)
		(layer "In9.Cu")
		(net "UPI_CPU0_CPU1_P0P0_DP<12>")
	)
	(segment
		(start 316.7126 -75.436984)
		(end 316.705996 -75.20813)
		(width 0.1143)
		(layer "In9.Cu")
		(net "UPI_CPU0_CPU1_P0P0_DP<12>")
	)
	(segment
		(start 316.620398 -77.946758)
		(end 316.6364 -77.929994)
		(width 0.1143)
		(layer "In9.Cu")
		(net "UPI_CPU0_CPU1_P0P0_DP<12>")
	)
	(segment
		(start 316.771528 -77.552042)
		(end 316.6364 -77.424026)
		(width 0.1143)
		(layer "In9.Cu")
		(net "UPI_CPU0_CPU1_P0P0_DP<12>")
	)
	(segment
		(start 160.286446 -100.672392)
		(end 172.207682 -112.046258)
		(width 0.1143)
		(layer "In9.Cu")
		(net "UPI_CPU0_CPU1_P0P0_DP<12>")
	)
	(segment
		(start 307.025802 -63.924688)
		(end 306.963826 -63.986664)
		(width 0.0889)
		(layer "In9.Cu")
		(net "UPI_CPU0_CPU1_P0P0_DP<12>")
	)
	(segment
		(start 278.050752 -113.911888)
		(end 291.125402 -115.42776)
		(width 0.1143)
		(layer "In9.Cu")
		(net "UPI_CPU0_CPU1_P0P0_DP<12>")
	)
	(segment
		(start 316.82182 -79.343504)
		(end 316.815216 -79.11465)
		(width 0.1143)
		(layer "In9.Cu")
		(net "UPI_CPU0_CPU1_P0P0_DP<12>")
	)
	(segment
		(start 137.659618 -70.172834)
		(end 137.692384 -70.172834)
		(width 0.0889)
		(layer "In9.Cu")
		(net "UPI_CPU0_CPU1_P0P0_DP<12>")
	)
	(segment
		(start 150.391622 -77.752448)
		(end 153.276808 -88.390476)
		(width 0.1143)
		(layer "In9.Cu")
		(net "UPI_CPU0_CPU1_P0P0_DP<12>")
	)
	(segment
		(start 186.21756 -118.134384)
		(end 195.329302 -117.517418)
		(width 0.1143)
		(layer "In9.Cu")
		(net "UPI_CPU0_CPU1_P0P0_DP<12>")
	)
	(segment
		(start 316.56147 -75.831954)
		(end 316.554866 -75.602846)
		(width 0.1143)
		(layer "In9.Cu")
		(net "UPI_CPU0_CPU1_P0P0_DP<12>")
	)
	(segment
		(start 292.271958 -115.560602)
		(end 308.817772 -111.792258)
		(width 0.1143)
		(layer "In9.Cu")
		(net "UPI_CPU0_CPU1_P0P0_DP<12>")
	)
	(segment
		(start 316.6364 -76.321412)
		(end 316.734444 -76.218288)
		(width 0.1143)
		(layer "In9.Cu")
		(net "UPI_CPU0_CPU1_P0P0_DP<12>")
	)
	(segment
		(start 313.926982 -66.401442)
		(end 311.634886 -64.342518)
		(width 0.1143)
		(layer "In9.Cu")
		(net "UPI_CPU0_CPU1_P0P0_DP<12>")
	)
	(segment
		(start 316.65672 -73.358248)
		(end 314.722002 -68.4276)
		(width 0.1143)
		(layer "In9.Cu")
		(net "UPI_CPU0_CPU1_P0P0_DP<12>")
	)
	(segment
		(start 316.554866 -75.602846)
		(end 316.6364 -75.516994)
		(width 0.1143)
		(layer "In9.Cu")
		(net "UPI_CPU0_CPU1_P0P0_DP<12>")
	)
	(segment
		(start 316.749684 -76.770738)
		(end 316.6364 -76.66355)
		(width 0.1143)
		(layer "In9.Cu")
		(net "UPI_CPU0_CPU1_P0P0_DP<12>")
	)
	(segment
		(start 316.6364 -76.66355)
		(end 316.583314 -76.613258)
		(width 0.1143)
		(layer "In9.Cu")
		(net "UPI_CPU0_CPU1_P0P0_DP<12>")
	)
	(segment
		(start 316.673738 -74.007726)
		(end 316.674754 -74.006964)
		(width 0.1143)
		(layer "In9.Cu")
		(net "UPI_CPU0_CPU1_P0P0_DP<12>")
	)
	(segment
		(start 316.627002 -78.175866)
		(end 316.620398 -77.946758)
		(width 0.1143)
		(layer "In9.Cu")
		(net "UPI_CPU0_CPU1_P0P0_DP<12>")
	)
	(segment
		(start 316.67069 -79.738474)
		(end 316.664086 -79.509366)
		(width 0.1143)
		(layer "In9.Cu")
		(net "UPI_CPU0_CPU1_P0P0_DP<12>")
	)
	(segment
		(start 316.6364 -77.125576)
		(end 316.756288 -76.999592)
		(width 0.1143)
		(layer "In9.Cu")
		(net "UPI_CPU0_CPU1_P0P0_DP<12>")
	)
	(segment
		(start 267.211302 -114.95278)
		(end 278.050752 -113.911888)
		(width 0.1143)
		(layer "In9.Cu")
		(net "UPI_CPU0_CPU1_P0P0_DP<12>")
	)
	(segment
		(start 141.087094 -71.163434)
		(end 141.307566 -71.163434)
		(width 0.0889)
		(layer "In9.Cu")
		(net "UPI_CPU0_CPU1_P0P0_DP<12>")
	)
	(segment
		(start 316.793372 -78.333346)
		(end 316.627002 -78.175866)
		(width 0.1143)
		(layer "In9.Cu")
		(net "UPI_CPU0_CPU1_P0P0_DP<12>")
	)
	(segment
		(start 316.598554 -77.165454)
		(end 316.6364 -77.125576)
		(width 0.1143)
		(layer "In9.Cu")
		(net "UPI_CPU0_CPU1_P0P0_DP<12>")
	)
	(segment
		(start 258.562094 -114.527076)
		(end 267.211302 -114.95278)
		(width 0.1143)
		(layer "In9.Cu")
		(net "UPI_CPU0_CPU1_P0P0_DP<12>")
	)
	(segment
		(start 291.125402 -115.42776)
		(end 292.271958 -115.560602)
		(width 0.1143)
		(layer "In9.Cu")
		(net "UPI_CPU0_CPU1_P0P0_DP<12>")
	)
	(segment
		(start 318.813688 -85.68944)
		(end 317.378842 -81.915)
		(width 0.1143)
		(layer "In9.Cu")
		(net "UPI_CPU0_CPU1_P0P0_DP<12>")
	)
	(segment
		(start 316.60211 -77.285342)
		(end 316.598554 -77.165454)
		(width 0.1143)
		(layer "In9.Cu")
		(net "UPI_CPU0_CPU1_P0P0_DP<12>")
	)
	(segment
		(start 142.475458 -71.608188)
		(end 142.86103 -71.608188)
		(width 0.1143)
		(layer "In9.Cu")
		(net "UPI_CPU0_CPU1_P0P0_DP<12>")
	)
	(segment
		(start 316.72784 -75.989434)
		(end 316.6364 -75.90282)
		(width 0.1143)
		(layer "In9.Cu")
		(net "UPI_CPU0_CPU1_P0P0_DP<12>")
	)
	(segment
		(start 316.648846 -78.95717)
		(end 316.642242 -78.728062)
		(width 0.1143)
		(layer "In9.Cu")
		(net "UPI_CPU0_CPU1_P0P0_DP<12>")
	)
	(segment
		(start 144.88795 -73.48347)
		(end 147.398994 -74.621898)
		(width 0.1143)
		(layer "In9.Cu")
		(net "UPI_CPU0_CPU1_P0P0_DP<12>")
	)
	(segment
		(start 172.207682 -112.046258)
		(end 184.47131 -117.572028)
		(width 0.1143)
		(layer "In9.Cu")
		(net "UPI_CPU0_CPU1_P0P0_DP<12>")
	)
	(segment
		(start 320.557906 -100.847906)
		(end 321.286632 -99.523296)
		(width 0.1143)
		(layer "In9.Cu")
		(net "UPI_CPU0_CPU1_P0P0_DP<12>")
	)
	(segment
		(start 136.79424 -69.677534)
		(end 136.833864 -69.677534)
		(width 0.0889)
		(layer "In9.Cu")
		(net "UPI_CPU0_CPU1_P0P0_DP<12>")
	)
	(segment
		(start 135.660638 -68.951348)
		(end 135.639556 -69.030088)
		(width 0.0889)
		(layer "In9.Cu")
		(net "UPI_CPU0_CPU1_P0P0_DP<12>")
	)
	(segment
		(start 316.583314 -76.613258)
		(end 316.57671 -76.38415)
		(width 0.1143)
		(layer "In9.Cu")
		(net "UPI_CPU0_CPU1_P0P0_DP<12>")
	)
	(segment
		(start 143.767048 -72.509126)
		(end 144.88795 -73.48347)
		(width 0.1143)
		(layer "In9.Cu")
		(net "UPI_CPU0_CPU1_P0P0_DP<12>")
	)
	(segment
		(start 316.533022 -74.821542)
		(end 316.6364 -74.712576)
		(width 0.1143)
		(layer "In9.Cu")
		(net "UPI_CPU0_CPU1_P0P0_DP<12>")
	)
	(segment
		(start 316.6364 -77.929994)
		(end 316.778132 -77.780896)
		(width 0.1143)
		(layer "In9.Cu")
		(net "UPI_CPU0_CPU1_P0P0_DP<12>")
	)
	(segment
		(start 308.376574 -64.291718)
		(end 308.248558 -64.419734)
		(width 0.0889)
		(layer "In9.Cu")
		(net "UPI_CPU0_CPU1_P0P0_DP<12>")
	)
	(segment
		(start 320.449956 -101.043994)
		(end 320.557906 -100.847906)
		(width 0.1143)
		(layer "In9.Cu")
		(net "UPI_CPU0_CPU1_P0P0_DP<12>")
	)
	(segment
		(start 153.276808 -88.390476)
		(end 159.531812 -95.790258)
		(width 0.1143)
		(layer "In9.Cu")
		(net "UPI_CPU0_CPU1_P0P0_DP<12>")
	)
	(segment
		(start 316.815216 -79.11465)
		(end 316.648846 -78.95717)
		(width 0.1143)
		(layer "In9.Cu")
		(net "UPI_CPU0_CPU1_P0P0_DP<12>")
	)
	(segment
		(start 184.47131 -117.572028)
		(end 186.21756 -118.134384)
		(width 0.1143)
		(layer "In9.Cu")
		(net "UPI_CPU0_CPU1_P0P0_DP<12>")
	)
	(segment
		(start 142.45336 -71.608188)
		(end 142.475458 -71.608188)
		(width 0.0889)
		(layer "In9.Cu")
		(net "UPI_CPU0_CPU1_P0P0_DP<12>")
	)
	(segment
		(start 316.6364 -75.516994)
		(end 316.7126 -75.436984)
		(width 0.1143)
		(layer "In9.Cu")
		(net "UPI_CPU0_CPU1_P0P0_DP<12>")
	)
	(segment
		(start 141.873224 -71.658988)
		(end 142.40256 -71.658988)
		(width 0.0889)
		(layer "In9.Cu")
		(net "UPI_CPU0_CPU1_P0P0_DP<12>")
	)
	(segment
		(start 308.964076 -64.291718)
		(end 308.376574 -64.291718)
		(width 0.0889)
		(layer "In9.Cu")
		(net "UPI_CPU0_CPU1_P0P0_DP<12>")
	)
	(segment
		(start 247.984518 -117.018308)
		(end 258.562094 -114.527076)
		(width 0.1143)
		(layer "In9.Cu")
		(net "UPI_CPU0_CPU1_P0P0_DP<12>")
	)
	(segment
		(start 142.86103 -71.608188)
		(end 143.767048 -72.509126)
		(width 0.1143)
		(layer "In9.Cu")
		(net "UPI_CPU0_CPU1_P0P0_DP<12>")
	)
	(segment
		(start 147.398994 -74.621898)
		(end 150.391622 -77.752448)
		(width 0.1143)
		(layer "In9.Cu")
		(net "UPI_CPU0_CPU1_P0P0_DP<12>")
	)
	(segment
		(start 138.518138 -70.668134)
		(end 138.542268 -70.668134)
		(width 0.0889)
		(layer "In9.Cu")
		(net "UPI_CPU0_CPU1_P0P0_DP<12>")
	)
	(segment
		(start 316.854586 -80.535526)
		(end 316.836806 -79.895954)
		(width 0.1143)
		(layer "In9.Cu")
		(net "UPI_CPU0_CPU1_P0P0_DP<12>")
	)
	(segment
		(start 316.769496 -79.8322)
		(end 316.67069 -79.738474)
		(width 0.1143)
		(layer "In9.Cu")
		(net "UPI_CPU0_CPU1_P0P0_DP<12>")
	)
	(segment
		(start 135.938768 -69.182234)
		(end 135.971534 -69.182234)
		(width 0.0889)
		(layer "In9.Cu")
		(net "UPI_CPU0_CPU1_P0P0_DP<12>")
	)
	(segment
		(start 316.57671 -76.38415)
		(end 316.6364 -76.321412)
		(width 0.1143)
		(layer "In9.Cu")
		(net "UPI_CPU0_CPU1_P0P0_DP<12>")
	)
	(segment
		(start 316.6364 -77.424026)
		(end 316.605158 -77.394562)
		(width 0.1143)
		(layer "In9.Cu")
		(net "UPI_CPU0_CPU1_P0P0_DP<12>")
	)
	(segment
		(start 316.690756 -74.655426)
		(end 316.673738 -74.007726)
		(width 0.1143)
		(layer "In9.Cu")
		(net "UPI_CPU0_CPU1_P0P0_DP<12>")
	)
	(segment
		(start 321.286632 -99.523296)
		(end 321.37985 -98.29292)
		(width 0.1143)
		(layer "In9.Cu")
		(net "UPI_CPU0_CPU1_P0P0_DP<12>")
	)
	(segment
		(start 311.634886 -64.342518)
		(end 309.036974 -64.342518)
		(width 0.1143)
		(layer "In9.Cu")
		(net "UPI_CPU0_CPU1_P0P0_DP<12>")
	)
	(segment
		(start 195.329302 -117.517418)
		(end 227.893626 -113.597436)
		(width 0.1143)
		(layer "In9.Cu")
		(net "UPI_CPU0_CPU1_P0P0_DP<12>")
	)
	(segment
		(start 308.817772 -111.792258)
		(end 320.449956 -101.043994)
		(width 0.1143)
		(layer "In9.Cu")
		(net "UPI_CPU0_CPU1_P0P0_DP<12>")
	)
	(segment
		(start 316.836806 -79.895954)
		(end 316.769496 -79.8322)
		(width 0.1143)
		(layer "In9.Cu")
		(net "UPI_CPU0_CPU1_P0P0_DP<12>")
	)
	(segment
		(start 321.37985 -98.29292)
		(end 318.813688 -85.68944)
		(width 0.1143)
		(layer "In9.Cu")
		(net "UPI_CPU0_CPU1_P0P0_DP<12>")
	)
	(segment
		(start 308.248558 -64.419734)
		(end 307.69687 -64.419734)
		(width 0.0889)
		(layer "In9.Cu")
		(net "UPI_CPU0_CPU1_P0P0_DP<12>")
	)
	(segment
		(start 309.036974 -64.342518)
		(end 309.014876 -64.342518)
		(width 0.0889)
		(layer "In9.Cu")
		(net "UPI_CPU0_CPU1_P0P0_DP<12>")
	)
	(segment
		(start 316.664086 -79.509366)
		(end 316.82182 -79.343504)
		(width 0.1143)
		(layer "In9.Cu")
		(net "UPI_CPU0_CPU1_P0P0_DP<12>")
	)
	(segment
		(start 317.378842 -81.915)
		(end 316.854586 -80.535526)
		(width 0.1143)
		(layer "In9.Cu")
		(net "UPI_CPU0_CPU1_P0P0_DP<12>")
	)
	(segment
		(start 159.531812 -95.790258)
		(end 160.286446 -100.672392)
		(width 0.1143)
		(layer "In9.Cu")
		(net "UPI_CPU0_CPU1_P0P0_DP<12>")
	)
	(segment
		(start 142.40256 -71.658988)
		(end 142.45336 -71.608188)
		(width 0.0889)
		(layer "In9.Cu")
		(net "UPI_CPU0_CPU1_P0P0_DP<12>")
	)
	(segment
		(start 227.893626 -113.597436)
		(end 247.984518 -117.018308)
		(width 0.1143)
		(layer "In9.Cu")
		(net "UPI_CPU0_CPU1_P0P0_DP<12>")
	)
	(segment
		(start 135.953754 -68.782184)
		(end 135.660638 -68.951348)
		(width 0.0889)
		(layer "In9.Cu")
		(net "UPI_CPU0_CPU1_P0P0_DP<12>")
	)
	(segment
		(start 316.756288 -76.999592)
		(end 316.749684 -76.770738)
		(width 0.1143)
		(layer "In9.Cu")
		(net "UPI_CPU0_CPU1_P0P0_DP<12>")
	)
	(segment
		(start 309.014876 -64.342518)
		(end 308.964076 -64.291718)
		(width 0.0889)
		(layer "In9.Cu")
		(net "UPI_CPU0_CPU1_P0P0_DP<12>")
	)
	(arc
		(start 135.639556 -69.030088)
		(mid 135.772437 -69.139071)
		(end 135.938768 -69.182234)
		(width 0.0889)
		(layer "In9.Cu")
		(net "UPI_CPU0_CPU1_P0P0_DP<12>")
	)
	(arc
		(start 137.324084 -69.972682)
		(mid 137.465767 -70.116486)
		(end 137.659618 -70.172834)
		(width 0.0889)
		(layer "In9.Cu")
		(net "UPI_CPU0_CPU1_P0P0_DP<12>")
	)
	(arc
		(start 138.182604 -70.467982)
		(mid 138.324287 -70.611786)
		(end 138.518138 -70.668134)
		(width 0.0889)
		(layer "In9.Cu")
		(net "UPI_CPU0_CPU1_P0P0_DP<12>")
	)
	(arc
		(start 139.899644 -71.458836)
		(mid 140.041327 -71.60264)
		(end 140.235178 -71.658988)
		(width 0.0889)
		(layer "In9.Cu")
		(net "UPI_CPU0_CPU1_P0P0_DP<12>")
	)
	(arc
		(start 136.833864 -69.677534)
		(mid 137.117081 -69.761815)
		(end 137.324084 -69.972682)
		(width 0.0889)
		(layer "In9.Cu")
		(net "UPI_CPU0_CPU1_P0P0_DP<12>")
	)
	(arc
		(start 138.542268 -70.668134)
		(mid 138.830413 -70.750453)
		(end 139.041124 -70.963536)
		(width 0.0889)
		(layer "In9.Cu")
		(net "UPI_CPU0_CPU1_P0P0_DP<12>")
	)
	(arc
		(start 139.405614 -71.163434)
		(mid 139.691038 -71.246901)
		(end 139.899644 -71.458836)
		(width 0.0889)
		(layer "In9.Cu")
		(net "UPI_CPU0_CPU1_P0P0_DP<12>")
	)
	(arc
		(start 307.69687 -64.419734)
		(mid 307.493517 -64.304028)
		(end 307.347112 -64.121538)
		(width 0.0889)
		(layer "In9.Cu")
		(net "UPI_CPU0_CPU1_P0P0_DP<12>")
	)
	(arc
		(start 307.346858 -64.121792)
		(mid 307.255914 -64.004449)
		(end 307.130704 -63.924688)
		(width 0.0889)
		(layer "In9.Cu")
		(net "UPI_CPU0_CPU1_P0P0_DP<12>")
	)
	(arc
		(start 137.692384 -70.172834)
		(mid 137.975601 -70.257115)
		(end 138.182604 -70.467982)
		(width 0.0889)
		(layer "In9.Cu")
		(net "UPI_CPU0_CPU1_P0P0_DP<12>")
	)
	(arc
		(start 141.307566 -71.163434)
		(mid 141.510464 -71.279294)
		(end 141.656562 -71.46163)
		(width 0.0889)
		(layer "In9.Cu")
		(net "UPI_CPU0_CPU1_P0P0_DP<12>")
	)
	(arc
		(start 136.465564 -69.477636)
		(mid 136.604308 -69.619669)
		(end 136.79424 -69.677534)
		(width 0.0889)
		(layer "In9.Cu")
		(net "UPI_CPU0_CPU1_P0P0_DP<12>")
	)
	(arc
		(start 135.971534 -69.182234)
		(mid 136.256958 -69.265701)
		(end 136.465564 -69.477636)
		(width 0.0889)
		(layer "In9.Cu")
		(net "UPI_CPU0_CPU1_P0P0_DP<12>")
	)
	(arc
		(start 141.656562 -71.46163)
		(mid 141.747676 -71.579222)
		(end 141.873224 -71.658988)
		(width 0.0889)
		(layer "In9.Cu")
		(net "UPI_CPU0_CPU1_P0P0_DP<12>")
	)
	(arc
		(start 140.593064 -71.458836)
		(mid 140.801672 -71.246904)
		(end 141.087094 -71.163434)
		(width 0.0889)
		(layer "In9.Cu")
		(net "UPI_CPU0_CPU1_P0P0_DP<12>")
	)
	(arc
		(start 139.041124 -70.963536)
		(mid 139.181203 -71.106272)
		(end 139.372848 -71.163434)
		(width 0.0889)
		(layer "In9.Cu")
		(net "UPI_CPU0_CPU1_P0P0_DP<12>")
	)
	(arc
		(start 140.25753 -71.658988)
		(mid 140.45138 -71.602638)
		(end 140.593064 -71.458836)
		(width 0.0889)
		(layer "In9.Cu")
		(net "UPI_CPU0_CPU1_P0P0_DP<12>")
	)
	(segment
		(start 136.240774 -68.287138)
		(end 136.812274 -68.287138)
		(width 0.1143)
		(layer "F.Cu")
		(net "UPI_CPU0_CPU1_P0P0_DP<11>")
	)
	(segment
		(start 306.392326 -65.315338)
		(end 306.963826 -65.315338)
		(width 0.1143)
		(layer "F.Cu")
		(net "UPI_CPU0_CPU1_P0P0_DP<11>")
	)
	(via
		(at 136.812274 -68.287138)
		(size 0.508)
		(drill 0.254)
		(layers "F.Cu" "B.Cu")
		(net "UPI_CPU0_CPU1_P0P0_DP<11>")
	)
	(via
		(at 306.963826 -65.315338)
		(size 0.508)
		(drill 0.254)
		(layers "F.Cu" "B.Cu")
		(net "UPI_CPU0_CPU1_P0P0_DP<11>")
	)
	(segment
		(start 315.857636 -73.670414)
		(end 315.730636 -73.803764)
		(width 0.1143)
		(layer "In9.Cu")
		(net "UPI_CPU0_CPU1_P0P0_DP<11>")
	)
	(segment
		(start 315.750448 -74.522076)
		(end 315.756798 -74.75093)
		(width 0.1143)
		(layer "In9.Cu")
		(net "UPI_CPU0_CPU1_P0P0_DP<11>")
	)
	(segment
		(start 315.77026 -75.240388)
		(end 315.77661 -75.469242)
		(width 0.1143)
		(layer "In9.Cu")
		(net "UPI_CPU0_CPU1_P0P0_DP<11>")
	)
	(segment
		(start 309.2069 -65.08242)
		(end 309.50916 -65.08242)
		(width 0.0889)
		(layer "In9.Cu")
		(net "UPI_CPU0_CPU1_P0P0_DP<11>")
	)
	(segment
		(start 186.127898 -117.352572)
		(end 172.1485 -111.107982)
		(width 0.1143)
		(layer "In9.Cu")
		(net "UPI_CPU0_CPU1_P0P0_DP<11>")
	)
	(segment
		(start 309.582058 -65.13322)
		(end 311.560718 -65.13322)
		(width 0.1143)
		(layer "In9.Cu")
		(net "UPI_CPU0_CPU1_P0P0_DP<11>")
	)
	(segment
		(start 313.850782 -68.4276)
		(end 315.849254 -73.372726)
		(width 0.1143)
		(layer "In9.Cu")
		(net "UPI_CPU0_CPU1_P0P0_DP<11>")
	)
	(segment
		(start 143.1544 -70.782688)
		(end 142.493746 -70.122034)
		(width 0.1143)
		(layer "In9.Cu")
		(net "UPI_CPU0_CPU1_P0P0_DP<11>")
	)
	(segment
		(start 315.98997 -78.46949)
		(end 315.99632 -78.698598)
		(width 0.1143)
		(layer "In9.Cu")
		(net "UPI_CPU0_CPU1_P0P0_DP<11>")
	)
	(segment
		(start 267.196316 -114.313462)
		(end 258.50342 -113.885726)
		(width 0.1143)
		(layer "In9.Cu")
		(net "UPI_CPU0_CPU1_P0P0_DP<11>")
	)
	(segment
		(start 315.917072 -75.82535)
		(end 315.790072 -75.9587)
		(width 0.1143)
		(layer "In9.Cu")
		(net "UPI_CPU0_CPU1_P0P0_DP<11>")
	)
	(segment
		(start 306.963826 -65.315338)
		(end 306.846732 -65.315338)
		(width 0.0889)
		(layer "In9.Cu")
		(net "UPI_CPU0_CPU1_P0P0_DP<11>")
	)
	(segment
		(start 315.976508 -77.980286)
		(end 315.849508 -78.113636)
		(width 0.1143)
		(layer "In9.Cu")
		(net "UPI_CPU0_CPU1_P0P0_DP<11>")
	)
	(segment
		(start 141.760702 -70.122034)
		(end 141.709902 -70.172834)
		(width 0.0889)
		(layer "In9.Cu")
		(net "UPI_CPU0_CPU1_P0P0_DP<11>")
	)
	(segment
		(start 138.550904 -69.677534)
		(end 138.51128 -69.677534)
		(width 0.0889)
		(layer "In9.Cu")
		(net "UPI_CPU0_CPU1_P0P0_DP<11>")
	)
	(segment
		(start 307.83657 -65.419224)
		(end 308.870096 -65.419224)
		(width 0.0889)
		(layer "In9.Cu")
		(net "UPI_CPU0_CPU1_P0P0_DP<11>")
	)
	(segment
		(start 315.89726 -75.107038)
		(end 315.77026 -75.240388)
		(width 0.1143)
		(layer "In9.Cu")
		(net "UPI_CPU0_CPU1_P0P0_DP<11>")
	)
	(segment
		(start 291.125402 -114.785648)
		(end 278.056848 -113.270538)
		(width 0.1143)
		(layer "In9.Cu")
		(net "UPI_CPU0_CPU1_P0P0_DP<11>")
	)
	(segment
		(start 318.1985 -86.074504)
		(end 318.290956 -86.317582)
		(width 0.1143)
		(layer "In9.Cu")
		(net "UPI_CPU0_CPU1_P0P0_DP<11>")
	)
	(segment
		(start 278.056848 -113.270538)
		(end 267.196316 -114.313462)
		(width 0.1143)
		(layer "In9.Cu")
		(net "UPI_CPU0_CPU1_P0P0_DP<11>")
	)
	(segment
		(start 319.942464 -100.643436)
		(end 308.511448 -111.208312)
		(width 0.1143)
		(layer "In9.Cu")
		(net "UPI_CPU0_CPU1_P0P0_DP<11>")
	)
	(segment
		(start 315.86932 -78.831948)
		(end 315.87567 -79.060802)
		(width 0.1143)
		(layer "In9.Cu")
		(net "UPI_CPU0_CPU1_P0P0_DP<11>")
	)
	(segment
		(start 315.877448 -74.388726)
		(end 315.750448 -74.522076)
		(width 0.1143)
		(layer "In9.Cu")
		(net "UPI_CPU0_CPU1_P0P0_DP<11>")
	)
	(segment
		(start 136.812274 -68.625212)
		(end 136.812274 -68.287138)
		(width 0.0889)
		(layer "In9.Cu")
		(net "UPI_CPU0_CPU1_P0P0_DP<11>")
	)
	(segment
		(start 315.950346 -77.032866)
		(end 315.956696 -77.261974)
		(width 0.1143)
		(layer "In9.Cu")
		(net "UPI_CPU0_CPU1_P0P0_DP<11>")
	)
	(segment
		(start 316.029594 -79.906114)
		(end 316.04331 -80.405986)
		(width 0.1143)
		(layer "In9.Cu")
		(net "UPI_CPU0_CPU1_P0P0_DP<11>")
	)
	(segment
		(start 318.290956 -86.317582)
		(end 319.809622 -93.7768)
		(width 0.1143)
		(layer "In9.Cu")
		(net "UPI_CPU0_CPU1_P0P0_DP<11>")
	)
	(segment
		(start 315.934344 -77.285342)
		(end 315.829696 -77.395324)
		(width 0.1143)
		(layer "In9.Cu")
		(net "UPI_CPU0_CPU1_P0P0_DP<11>")
	)
	(segment
		(start 309.55996 -65.13322)
		(end 309.582058 -65.13322)
		(width 0.0889)
		(layer "In9.Cu")
		(net "UPI_CPU0_CPU1_P0P0_DP<11>")
	)
	(segment
		(start 315.970158 -77.751178)
		(end 315.976508 -77.980286)
		(width 0.1143)
		(layer "In9.Cu")
		(net "UPI_CPU0_CPU1_P0P0_DP<11>")
	)
	(segment
		(start 320.08826 -100.37826)
		(end 319.942464 -100.643436)
		(width 0.1143)
		(layer "In9.Cu")
		(net "UPI_CPU0_CPU1_P0P0_DP<11>")
	)
	(segment
		(start 315.836046 -77.624178)
		(end 315.970158 -77.751178)
		(width 0.1143)
		(layer "In9.Cu")
		(net "UPI_CPU0_CPU1_P0P0_DP<11>")
	)
	(segment
		(start 315.951616 -79.8322)
		(end 316.029594 -79.906114)
		(width 0.1143)
		(layer "In9.Cu")
		(net "UPI_CPU0_CPU1_P0P0_DP<11>")
	)
	(segment
		(start 292.23716 -114.914426)
		(end 291.125402 -114.785648)
		(width 0.1143)
		(layer "In9.Cu")
		(net "UPI_CPU0_CPU1_P0P0_DP<11>")
	)
	(segment
		(start 315.889132 -79.55026)
		(end 315.895482 -79.779114)
		(width 0.1143)
		(layer "In9.Cu")
		(net "UPI_CPU0_CPU1_P0P0_DP<11>")
	)
	(segment
		(start 306.846732 -64.915288)
		(end 306.978812 -64.915288)
		(width 0.0889)
		(layer "In9.Cu")
		(net "UPI_CPU0_CPU1_P0P0_DP<11>")
	)
	(segment
		(start 153.852118 -88.078564)
		(end 150.916894 -77.25156)
		(width 0.1143)
		(layer "In9.Cu")
		(net "UPI_CPU0_CPU1_P0P0_DP<11>")
	)
	(segment
		(start 309.50916 -65.08242)
		(end 309.55996 -65.13322)
		(width 0.0889)
		(layer "In9.Cu")
		(net "UPI_CPU0_CPU1_P0P0_DP<11>")
	)
	(segment
		(start 315.871098 -74.159618)
		(end 315.877448 -74.388726)
		(width 0.1143)
		(layer "In9.Cu")
		(net "UPI_CPU0_CPU1_P0P0_DP<11>")
	)
	(segment
		(start 315.855858 -78.34249)
		(end 315.98997 -78.46949)
		(width 0.1143)
		(layer "In9.Cu")
		(net "UPI_CPU0_CPU1_P0P0_DP<11>")
	)
	(segment
		(start 315.730636 -73.803764)
		(end 315.736986 -74.032618)
		(width 0.1143)
		(layer "In9.Cu")
		(net "UPI_CPU0_CPU1_P0P0_DP<11>")
	)
	(segment
		(start 313.066176 -66.48577)
		(end 313.850782 -68.4276)
		(width 0.1143)
		(layer "In9.Cu")
		(net "UPI_CPU0_CPU1_P0P0_DP<11>")
	)
	(segment
		(start 150.916894 -77.25156)
		(end 148.222462 -73.67143)
		(width 0.1143)
		(layer "In9.Cu")
		(net "UPI_CPU0_CPU1_P0P0_DP<11>")
	)
	(segment
		(start 247.964198 -116.367814)
		(end 227.967794 -112.963198)
		(width 0.1143)
		(layer "In9.Cu")
		(net "UPI_CPU0_CPU1_P0P0_DP<11>")
	)
	(segment
		(start 320.661284 -99.337114)
		(end 320.08826 -100.37826)
		(width 0.1143)
		(layer "In9.Cu")
		(net "UPI_CPU0_CPU1_P0P0_DP<11>")
	)
	(segment
		(start 315.910722 -75.596242)
		(end 315.917072 -75.82535)
		(width 0.1143)
		(layer "In9.Cu")
		(net "UPI_CPU0_CPU1_P0P0_DP<11>")
	)
	(segment
		(start 315.930534 -76.314554)
		(end 315.936884 -76.543662)
		(width 0.1143)
		(layer "In9.Cu")
		(net "UPI_CPU0_CPU1_P0P0_DP<11>")
	)
	(segment
		(start 195.179188 -116.895626)
		(end 186.127898 -117.352572)
		(width 0.1143)
		(layer "In9.Cu")
		(net "UPI_CPU0_CPU1_P0P0_DP<11>")
	)
	(segment
		(start 316.016132 -79.41691)
		(end 315.889132 -79.55026)
		(width 0.1143)
		(layer "In9.Cu")
		(net "UPI_CPU0_CPU1_P0P0_DP<11>")
	)
	(segment
		(start 311.560718 -65.13322)
		(end 313.066176 -66.48577)
		(width 0.1143)
		(layer "In9.Cu")
		(net "UPI_CPU0_CPU1_P0P0_DP<11>")
	)
	(segment
		(start 320.468244 -97.011744)
		(end 320.73723 -98.333306)
		(width 0.1143)
		(layer "In9.Cu")
		(net "UPI_CPU0_CPU1_P0P0_DP<11>")
	)
	(segment
		(start 137.688574 -69.182234)
		(end 137.655808 -69.182234)
		(width 0.0889)
		(layer "In9.Cu")
		(net "UPI_CPU0_CPU1_P0P0_DP<11>")
	)
	(segment
		(start 315.796422 -76.187554)
		(end 315.930534 -76.314554)
		(width 0.1143)
		(layer "In9.Cu")
		(net "UPI_CPU0_CPU1_P0P0_DP<11>")
	)
	(segment
		(start 315.849254 -73.372726)
		(end 315.857636 -73.670414)
		(width 0.1143)
		(layer "In9.Cu")
		(net "UPI_CPU0_CPU1_P0P0_DP<11>")
	)
	(segment
		(start 136.877298 -68.690236)
		(end 136.812274 -68.625212)
		(width 0.0889)
		(layer "In9.Cu")
		(net "UPI_CPU0_CPU1_P0P0_DP<11>")
	)
	(segment
		(start 315.936884 -76.543662)
		(end 315.809884 -76.677012)
		(width 0.1143)
		(layer "In9.Cu")
		(net "UPI_CPU0_CPU1_P0P0_DP<11>")
	)
	(segment
		(start 315.736986 -74.032618)
		(end 315.871098 -74.159618)
		(width 0.1143)
		(layer "In9.Cu")
		(net "UPI_CPU0_CPU1_P0P0_DP<11>")
	)
	(segment
		(start 160.883092 -100.360734)
		(end 160.133792 -95.512636)
		(width 0.1143)
		(layer "In9.Cu")
		(net "UPI_CPU0_CPU1_P0P0_DP<11>")
	)
	(segment
		(start 320.73723 -98.333306)
		(end 320.661284 -99.337114)
		(width 0.1143)
		(layer "In9.Cu")
		(net "UPI_CPU0_CPU1_P0P0_DP<11>")
	)
	(segment
		(start 308.870096 -65.419224)
		(end 309.2069 -65.08242)
		(width 0.0889)
		(layer "In9.Cu")
		(net "UPI_CPU0_CPU1_P0P0_DP<11>")
	)
	(segment
		(start 315.956696 -77.261974)
		(end 315.934344 -77.285342)
		(width 0.1143)
		(layer "In9.Cu")
		(net "UPI_CPU0_CPU1_P0P0_DP<11>")
	)
	(segment
		(start 315.829696 -77.395324)
		(end 315.836046 -77.624178)
		(width 0.1143)
		(layer "In9.Cu")
		(net "UPI_CPU0_CPU1_P0P0_DP<11>")
	)
	(segment
		(start 148.222462 -73.67143)
		(end 143.1544 -70.782688)
		(width 0.1143)
		(layer "In9.Cu")
		(net "UPI_CPU0_CPU1_P0P0_DP<11>")
	)
	(segment
		(start 319.809622 -93.7768)
		(end 320.468244 -97.011744)
		(width 0.1143)
		(layer "In9.Cu")
		(net "UPI_CPU0_CPU1_P0P0_DP<11>")
	)
	(segment
		(start 227.967794 -112.963198)
		(end 195.179188 -116.895626)
		(width 0.1143)
		(layer "In9.Cu")
		(net "UPI_CPU0_CPU1_P0P0_DP<11>")
	)
	(segment
		(start 308.511448 -111.208312)
		(end 292.23716 -114.914426)
		(width 0.1143)
		(layer "In9.Cu")
		(net "UPI_CPU0_CPU1_P0P0_DP<11>")
	)
	(segment
		(start 160.133792 -95.512636)
		(end 153.852118 -88.078564)
		(width 0.1143)
		(layer "In9.Cu")
		(net "UPI_CPU0_CPU1_P0P0_DP<11>")
	)
	(segment
		(start 139.409424 -70.172834)
		(end 139.376658 -70.172834)
		(width 0.0889)
		(layer "In9.Cu")
		(net "UPI_CPU0_CPU1_P0P0_DP<11>")
	)
	(segment
		(start 315.809884 -76.677012)
		(end 315.816234 -76.905866)
		(width 0.1143)
		(layer "In9.Cu")
		(net "UPI_CPU0_CPU1_P0P0_DP<11>")
	)
	(segment
		(start 315.816234 -76.905866)
		(end 315.950346 -77.032866)
		(width 0.1143)
		(layer "In9.Cu")
		(net "UPI_CPU0_CPU1_P0P0_DP<11>")
	)
	(segment
		(start 315.756798 -74.75093)
		(end 315.89091 -74.87793)
		(width 0.1143)
		(layer "In9.Cu")
		(net "UPI_CPU0_CPU1_P0P0_DP<11>")
	)
	(segment
		(start 315.849508 -78.113636)
		(end 315.855858 -78.34249)
		(width 0.1143)
		(layer "In9.Cu")
		(net "UPI_CPU0_CPU1_P0P0_DP<11>")
	)
	(segment
		(start 315.99632 -78.698598)
		(end 315.86932 -78.831948)
		(width 0.1143)
		(layer "In9.Cu")
		(net "UPI_CPU0_CPU1_P0P0_DP<11>")
	)
	(segment
		(start 315.790072 -75.9587)
		(end 315.796422 -76.187554)
		(width 0.1143)
		(layer "In9.Cu")
		(net "UPI_CPU0_CPU1_P0P0_DP<11>")
	)
	(segment
		(start 315.87567 -79.060802)
		(end 316.009782 -79.187802)
		(width 0.1143)
		(layer "In9.Cu")
		(net "UPI_CPU0_CPU1_P0P0_DP<11>")
	)
	(segment
		(start 316.009782 -79.187802)
		(end 316.016132 -79.41691)
		(width 0.1143)
		(layer "In9.Cu")
		(net "UPI_CPU0_CPU1_P0P0_DP<11>")
	)
	(segment
		(start 142.493746 -70.122034)
		(end 141.760702 -70.122034)
		(width 0.1143)
		(layer "In9.Cu")
		(net "UPI_CPU0_CPU1_P0P0_DP<11>")
	)
	(segment
		(start 258.50342 -113.885726)
		(end 247.964198 -116.367814)
		(width 0.1143)
		(layer "In9.Cu")
		(net "UPI_CPU0_CPU1_P0P0_DP<11>")
	)
	(segment
		(start 316.04331 -80.405986)
		(end 318.1985 -86.074504)
		(width 0.1143)
		(layer "In9.Cu")
		(net "UPI_CPU0_CPU1_P0P0_DP<11>")
	)
	(segment
		(start 315.895482 -79.779114)
		(end 315.951616 -79.8322)
		(width 0.1143)
		(layer "In9.Cu")
		(net "UPI_CPU0_CPU1_P0P0_DP<11>")
	)
	(segment
		(start 141.709902 -70.172834)
		(end 141.083284 -70.172834)
		(width 0.0889)
		(layer "In9.Cu")
		(net "UPI_CPU0_CPU1_P0P0_DP<11>")
	)
	(segment
		(start 315.77661 -75.469242)
		(end 315.910722 -75.596242)
		(width 0.1143)
		(layer "In9.Cu")
		(net "UPI_CPU0_CPU1_P0P0_DP<11>")
	)
	(segment
		(start 315.89091 -74.87793)
		(end 315.89726 -75.107038)
		(width 0.1143)
		(layer "In9.Cu")
		(net "UPI_CPU0_CPU1_P0P0_DP<11>")
	)
	(segment
		(start 172.1485 -111.107982)
		(end 160.883092 -100.360734)
		(width 0.1143)
		(layer "In9.Cu")
		(net "UPI_CPU0_CPU1_P0P0_DP<11>")
	)
	(arc
		(start 140.593064 -70.467982)
		(mid 140.246354 -70.668293)
		(end 139.899644 -70.467982)
		(width 0.0889)
		(layer "In9.Cu")
		(net "UPI_CPU0_CPU1_P0P0_DP<11>")
	)
	(arc
		(start 307.310536 -65.115186)
		(mid 307.532832 -65.337677)
		(end 307.83657 -65.419224)
		(width 0.0889)
		(layer "In9.Cu")
		(net "UPI_CPU0_CPU1_P0P0_DP<11>")
	)
	(arc
		(start 137.655808 -69.182234)
		(mid 137.464166 -69.125068)
		(end 137.324084 -68.982336)
		(width 0.0889)
		(layer "In9.Cu")
		(net "UPI_CPU0_CPU1_P0P0_DP<11>")
	)
	(arc
		(start 139.376658 -70.172834)
		(mid 139.182808 -70.116484)
		(end 139.041124 -69.972682)
		(width 0.0889)
		(layer "In9.Cu")
		(net "UPI_CPU0_CPU1_P0P0_DP<11>")
	)
	(arc
		(start 138.51128 -69.677534)
		(mid 138.321351 -69.619664)
		(end 138.182604 -69.477636)
		(width 0.0889)
		(layer "In9.Cu")
		(net "UPI_CPU0_CPU1_P0P0_DP<11>")
	)
	(arc
		(start 306.978812 -64.915288)
		(mid 307.170454 -64.972454)
		(end 307.310536 -65.115186)
		(width 0.0889)
		(layer "In9.Cu")
		(net "UPI_CPU0_CPU1_P0P0_DP<11>")
	)
	(arc
		(start 139.899644 -70.467982)
		(mid 139.69264 -70.257118)
		(end 139.409424 -70.172834)
		(width 0.0889)
		(layer "In9.Cu")
		(net "UPI_CPU0_CPU1_P0P0_DP<11>")
	)
	(arc
		(start 141.083284 -70.172834)
		(mid 140.800067 -70.257115)
		(end 140.593064 -70.467982)
		(width 0.0889)
		(layer "In9.Cu")
		(net "UPI_CPU0_CPU1_P0P0_DP<11>")
	)
	(arc
		(start 137.324084 -68.982336)
		(mid 137.135556 -68.782963)
		(end 136.877298 -68.690236)
		(width 0.0889)
		(layer "In9.Cu")
		(net "UPI_CPU0_CPU1_P0P0_DP<11>")
	)
	(arc
		(start 306.846732 -65.315338)
		(mid 306.646834 -65.11544)
		(end 306.846732 -64.915288)
		(width 0.0889)
		(layer "In9.Cu")
		(net "UPI_CPU0_CPU1_P0P0_DP<11>")
	)
	(arc
		(start 138.182604 -69.477636)
		(mid 137.973996 -69.265704)
		(end 137.688574 -69.182234)
		(width 0.0889)
		(layer "In9.Cu")
		(net "UPI_CPU0_CPU1_P0P0_DP<11>")
	)
	(arc
		(start 139.041124 -69.972682)
		(mid 138.83412 -69.761818)
		(end 138.550904 -69.677534)
		(width 0.0889)
		(layer "In9.Cu")
		(net "UPI_CPU0_CPU1_P0P0_DP<11>")
	)
	(segment
		(start 307.250846 -65.810384)
		(end 307.076348 -65.810384)
		(width 0.0889)
		(layer "F.Cu")
		(net "UPI_CPU0_CPU1_P0P0_DP<10>")
	)
	(segment
		(start 311.152032 -66.0908)
		(end 311.380632 -65.8622)
		(width 0.0889)
		(layer "F.Cu")
		(net "UPI_CPU0_CPU1_P0P0_DP<10>")
	)
	(segment
		(start 306.935632 -66.121534)
		(end 307.024532 -66.210434)
		(width 0.0889)
		(layer "F.Cu")
		(net "UPI_CPU0_CPU1_P0P0_DP<10>")
	)
	(segment
		(start 307.707792 -66.0908)
		(end 311.152032 -66.0908)
		(width 0.0889)
		(layer "F.Cu")
		(net "UPI_CPU0_CPU1_P0P0_DP<10>")
	)
	(segment
		(start 307.076348 -65.810384)
		(end 306.935632 -65.9511)
		(width 0.0889)
		(layer "F.Cu")
		(net "UPI_CPU0_CPU1_P0P0_DP<10>")
	)
	(segment
		(start 307.024532 -66.210434)
		(end 307.588158 -66.210434)
		(width 0.0889)
		(layer "F.Cu")
		(net "UPI_CPU0_CPU1_P0P0_DP<10>")
	)
	(segment
		(start 306.935632 -65.9511)
		(end 306.935632 -66.121534)
		(width 0.0889)
		(layer "F.Cu")
		(net "UPI_CPU0_CPU1_P0P0_DP<10>")
	)
	(segment
		(start 136.240774 -67.296538)
		(end 136.812274 -67.296538)
		(width 0.1143)
		(layer "F.Cu")
		(net "UPI_CPU0_CPU1_P0P0_DP<10>")
	)
	(segment
		(start 307.588158 -66.210434)
		(end 307.707792 -66.0908)
		(width 0.0889)
		(layer "F.Cu")
		(net "UPI_CPU0_CPU1_P0P0_DP<10>")
	)
	(via
		(at 136.812274 -67.296538)
		(size 0.508)
		(drill 0.254)
		(layers "F.Cu" "B.Cu")
		(net "UPI_CPU0_CPU1_P0P0_DP<10>")
	)
	(via
		(at 311.380632 -65.8622)
		(size 0.508)
		(drill 0.254)
		(layers "F.Cu" "B.Cu")
		(net "UPI_CPU0_CPU1_P0P0_DP<10>")
	)
	(segment
		(start 271.757394 -113.528348)
		(end 271.76222 -113.528094)
		(width 0.1143)
		(layer "In9.Cu")
		(net "UPI_CPU0_CPU1_P0P0_DP<10>")
	)
	(segment
		(start 175.044354 -111.936784)
		(end 177.437288 -112.223042)
		(width 0.1143)
		(layer "In9.Cu")
		(net "UPI_CPU0_CPU1_P0P0_DP<10>")
	)
	(segment
		(start 142.131034 -68.877688)
		(end 142.911068 -69.657722)
		(width 0.0889)
		(layer "In9.Cu")
		(net "UPI_CPU0_CPU1_P0P0_DP<10>")
	)
	(segment
		(start 271.77111 -113.527078)
		(end 278.059642 -112.923066)
		(width 0.1143)
		(layer "In9.Cu")
		(net "UPI_CPU0_CPU1_P0P0_DP<10>")
	)
	(segment
		(start 271.76222 -113.528094)
		(end 271.76349 -113.528094)
		(width 0.1143)
		(layer "In9.Cu")
		(net "UPI_CPU0_CPU1_P0P0_DP<10>")
	)
	(segment
		(start 137.649204 -68.382134)
		(end 137.68197 -68.382134)
		(width 0.0889)
		(layer "In9.Cu")
		(net "UPI_CPU0_CPU1_P0P0_DP<10>")
	)
	(segment
		(start 311.937908 -66.0527)
		(end 311.571132 -66.0527)
		(width 0.1143)
		(layer "In9.Cu")
		(net "UPI_CPU0_CPU1_P0P0_DP<10>")
	)
	(segment
		(start 278.059642 -112.923066)
		(end 292.2143 -114.563906)
		(width 0.1143)
		(layer "In9.Cu")
		(net "UPI_CPU0_CPU1_P0P0_DP<10>")
	)
	(segment
		(start 193.121534 -116.585746)
		(end 196.723508 -116.363496)
		(width 0.1143)
		(layer "In9.Cu")
		(net "UPI_CPU0_CPU1_P0P0_DP<10>")
	)
	(segment
		(start 311.571132 -66.0527)
		(end 311.380632 -65.8622)
		(width 0.1143)
		(layer "In9.Cu")
		(net "UPI_CPU0_CPU1_P0P0_DP<10>")
	)
	(segment
		(start 267.188188 -113.967006)
		(end 271.756886 -113.528348)
		(width 0.1143)
		(layer "In9.Cu")
		(net "UPI_CPU0_CPU1_P0P0_DP<10>")
	)
	(segment
		(start 154.213052 -87.971376)
		(end 160.459928 -95.363792)
		(width 0.1143)
		(layer "In9.Cu")
		(net "UPI_CPU0_CPU1_P0P0_DP<10>")
	)
	(segment
		(start 143.97609 -70.224396)
		(end 144.745964 -70.99427)
		(width 0.1143)
		(layer "In9.Cu")
		(net "UPI_CPU0_CPU1_P0P0_DP<10>")
	)
	(segment
		(start 154.16784 -87.917782)
		(end 154.212036 -87.970106)
		(width 0.1143)
		(layer "In9.Cu")
		(net "UPI_CPU0_CPU1_P0P0_DP<10>")
	)
	(segment
		(start 148.65985 -73.317862)
		(end 151.08047 -76.534264)
		(width 0.1143)
		(layer "In9.Cu")
		(net "UPI_CPU0_CPU1_P0P0_DP<10>")
	)
	(segment
		(start 189.261242 -116.249704)
		(end 193.121534 -116.585746)
		(width 0.1143)
		(layer "In9.Cu")
		(net "UPI_CPU0_CPU1_P0P0_DP<10>")
	)
	(segment
		(start 196.723508 -116.363496)
		(end 227.936044 -112.607344)
		(width 0.1143)
		(layer "In9.Cu")
		(net "UPI_CPU0_CPU1_P0P0_DP<10>")
	)
	(segment
		(start 271.768316 -113.527586)
		(end 271.769586 -113.527332)
		(width 0.1143)
		(layer "In9.Cu")
		(net "UPI_CPU0_CPU1_P0P0_DP<10>")
	)
	(segment
		(start 143.481298 -69.657722)
		(end 143.960596 -70.13702)
		(width 0.0889)
		(layer "In9.Cu")
		(net "UPI_CPU0_CPU1_P0P0_DP<10>")
	)
	(segment
		(start 185.371232 -115.911376)
		(end 189.261242 -116.249704)
		(width 0.1143)
		(layer "In9.Cu")
		(net "UPI_CPU0_CPU1_P0P0_DP<10>")
	)
	(segment
		(start 315.366654 -73.213722)
		(end 312.522616 -66.612008)
		(width 0.1143)
		(layer "In9.Cu")
		(net "UPI_CPU0_CPU1_P0P0_DP<10>")
	)
	(segment
		(start 313.534552 -106.04119)
		(end 317.805562 -86.22284)
		(width 0.1143)
		(layer "In9.Cu")
		(net "UPI_CPU0_CPU1_P0P0_DP<10>")
	)
	(segment
		(start 139.366244 -69.372734)
		(end 139.39901 -69.372734)
		(width 0.0889)
		(layer "In9.Cu")
		(net "UPI_CPU0_CPU1_P0P0_DP<10>")
	)
	(segment
		(start 247.953276 -116.015262)
		(end 258.47167 -113.538254)
		(width 0.1143)
		(layer "In9.Cu")
		(net "UPI_CPU0_CPU1_P0P0_DP<10>")
	)
	(segment
		(start 172.192188 -110.673134)
		(end 175.044354 -111.936784)
		(width 0.1143)
		(layer "In9.Cu")
		(net "UPI_CPU0_CPU1_P0P0_DP<10>")
	)
	(segment
		(start 271.767046 -113.527586)
		(end 271.768316 -113.527586)
		(width 0.1143)
		(layer "In9.Cu")
		(net "UPI_CPU0_CPU1_P0P0_DP<10>")
	)
	(segment
		(start 160.459928 -95.363792)
		(end 161.206434 -100.19157)
		(width 0.1143)
		(layer "In9.Cu")
		(net "UPI_CPU0_CPU1_P0P0_DP<10>")
	)
	(segment
		(start 136.812274 -67.296538)
		(end 137.121138 -68.009008)
		(width 0.0889)
		(layer "In9.Cu")
		(net "UPI_CPU0_CPU1_P0P0_DP<10>")
	)
	(segment
		(start 315.563758 -80.32623)
		(end 315.366654 -73.213722)
		(width 0.1143)
		(layer "In9.Cu")
		(net "UPI_CPU0_CPU1_P0P0_DP<10>")
	)
	(segment
		(start 271.76349 -113.528094)
		(end 271.765014 -113.52784)
		(width 0.1143)
		(layer "In9.Cu")
		(net "UPI_CPU0_CPU1_P0P0_DP<10>")
	)
	(segment
		(start 143.960596 -70.13702)
		(end 143.97609 -70.224396)
		(width 0.0889)
		(layer "In9.Cu")
		(net "UPI_CPU0_CPU1_P0P0_DP<10>")
	)
	(segment
		(start 271.756886 -113.528348)
		(end 271.757394 -113.528348)
		(width 0.1143)
		(layer "In9.Cu")
		(net "UPI_CPU0_CPU1_P0P0_DP<10>")
	)
	(segment
		(start 142.911068 -69.657722)
		(end 143.481298 -69.657722)
		(width 0.0889)
		(layer "In9.Cu")
		(net "UPI_CPU0_CPU1_P0P0_DP<10>")
	)
	(segment
		(start 258.47167 -113.538254)
		(end 267.188188 -113.967006)
		(width 0.1143)
		(layer "In9.Cu")
		(net "UPI_CPU0_CPU1_P0P0_DP<10>")
	)
	(segment
		(start 177.437288 -112.223042)
		(end 185.371232 -115.911376)
		(width 0.1143)
		(layer "In9.Cu")
		(net "UPI_CPU0_CPU1_P0P0_DP<10>")
	)
	(segment
		(start 271.769586 -113.527332)
		(end 271.77111 -113.527078)
		(width 0.1143)
		(layer "In9.Cu")
		(net "UPI_CPU0_CPU1_P0P0_DP<10>")
	)
	(segment
		(start 227.936044 -112.607344)
		(end 247.953276 -116.015262)
		(width 0.1143)
		(layer "In9.Cu")
		(net "UPI_CPU0_CPU1_P0P0_DP<10>")
	)
	(segment
		(start 308.261766 -110.912656)
		(end 313.534552 -106.04119)
		(width 0.1143)
		(layer "In9.Cu")
		(net "UPI_CPU0_CPU1_P0P0_DP<10>")
	)
	(segment
		(start 151.08047 -76.534264)
		(end 154.16784 -87.917782)
		(width 0.1143)
		(layer "In9.Cu")
		(net "UPI_CPU0_CPU1_P0P0_DP<10>")
	)
	(segment
		(start 141.945868 -68.877688)
		(end 142.131034 -68.877688)
		(width 0.0889)
		(layer "In9.Cu")
		(net "UPI_CPU0_CPU1_P0P0_DP<10>")
	)
	(segment
		(start 154.212036 -87.970106)
		(end 154.213052 -87.971376)
		(width 0.1143)
		(layer "In9.Cu")
		(net "UPI_CPU0_CPU1_P0P0_DP<10>")
	)
	(segment
		(start 312.522616 -66.612008)
		(end 311.937908 -66.0527)
		(width 0.1143)
		(layer "In9.Cu")
		(net "UPI_CPU0_CPU1_P0P0_DP<10>")
	)
	(segment
		(start 140.228574 -69.868288)
		(end 140.264134 -69.868288)
		(width 0.0889)
		(layer "In9.Cu")
		(net "UPI_CPU0_CPU1_P0P0_DP<10>")
	)
	(segment
		(start 317.805562 -86.22284)
		(end 315.563758 -80.32623)
		(width 0.1143)
		(layer "In9.Cu")
		(net "UPI_CPU0_CPU1_P0P0_DP<10>")
	)
	(segment
		(start 138.511534 -68.877688)
		(end 138.5443 -68.877688)
		(width 0.0889)
		(layer "In9.Cu")
		(net "UPI_CPU0_CPU1_P0P0_DP<10>")
	)
	(segment
		(start 292.2143 -114.563906)
		(end 308.261766 -110.912656)
		(width 0.1143)
		(layer "In9.Cu")
		(net "UPI_CPU0_CPU1_P0P0_DP<10>")
	)
	(segment
		(start 161.206434 -100.19157)
		(end 172.192188 -110.673134)
		(width 0.1143)
		(layer "In9.Cu")
		(net "UPI_CPU0_CPU1_P0P0_DP<10>")
	)
	(segment
		(start 271.765014 -113.52784)
		(end 271.767046 -113.527586)
		(width 0.1143)
		(layer "In9.Cu")
		(net "UPI_CPU0_CPU1_P0P0_DP<10>")
	)
	(segment
		(start 141.093698 -69.372734)
		(end 141.126464 -69.372734)
		(width 0.0889)
		(layer "In9.Cu")
		(net "UPI_CPU0_CPU1_P0P0_DP<10>")
	)
	(segment
		(start 144.745964 -70.99427)
		(end 148.65985 -73.317862)
		(width 0.1143)
		(layer "In9.Cu")
		(net "UPI_CPU0_CPU1_P0P0_DP<10>")
	)
	(arc
		(start 140.758164 -69.572886)
		(mid 140.899847 -69.429082)
		(end 141.093698 -69.372734)
		(width 0.0889)
		(layer "In9.Cu")
		(net "UPI_CPU0_CPU1_P0P0_DP<10>")
	)
	(arc
		(start 138.5443 -68.877688)
		(mid 138.735942 -68.934854)
		(end 138.876024 -69.077586)
		(width 0.0889)
		(layer "In9.Cu")
		(net "UPI_CPU0_CPU1_P0P0_DP<10>")
	)
	(arc
		(start 137.121138 -68.009008)
		(mid 137.329596 -68.274263)
		(end 137.649204 -68.382134)
		(width 0.0889)
		(layer "In9.Cu")
		(net "UPI_CPU0_CPU1_P0P0_DP<10>")
	)
	(arc
		(start 141.616684 -69.077586)
		(mid 141.755677 -68.935506)
		(end 141.945868 -68.877688)
		(width 0.0889)
		(layer "In9.Cu")
		(net "UPI_CPU0_CPU1_P0P0_DP<10>")
	)
	(arc
		(start 140.264134 -69.868288)
		(mid 140.549558 -69.784821)
		(end 140.758164 -69.572886)
		(width 0.0889)
		(layer "In9.Cu")
		(net "UPI_CPU0_CPU1_P0P0_DP<10>")
	)
	(arc
		(start 141.126464 -69.372734)
		(mid 141.409681 -69.288453)
		(end 141.616684 -69.077586)
		(width 0.0889)
		(layer "In9.Cu")
		(net "UPI_CPU0_CPU1_P0P0_DP<10>")
	)
	(arc
		(start 138.876024 -69.077586)
		(mid 139.083028 -69.28845)
		(end 139.366244 -69.372734)
		(width 0.0889)
		(layer "In9.Cu")
		(net "UPI_CPU0_CPU1_P0P0_DP<10>")
	)
	(arc
		(start 139.39901 -69.372734)
		(mid 139.59286 -69.429084)
		(end 139.734544 -69.572886)
		(width 0.0889)
		(layer "In9.Cu")
		(net "UPI_CPU0_CPU1_P0P0_DP<10>")
	)
	(arc
		(start 139.734544 -69.572886)
		(mid 139.943152 -69.784818)
		(end 140.228574 -69.868288)
		(width 0.0889)
		(layer "In9.Cu")
		(net "UPI_CPU0_CPU1_P0P0_DP<10>")
	)
	(arc
		(start 138.017504 -68.582286)
		(mid 138.226112 -68.794218)
		(end 138.511534 -68.877688)
		(width 0.0889)
		(layer "In9.Cu")
		(net "UPI_CPU0_CPU1_P0P0_DP<10>")
	)
	(arc
		(start 137.68197 -68.382134)
		(mid 137.87582 -68.438484)
		(end 138.017504 -68.582286)
		(width 0.0889)
		(layer "In9.Cu")
		(net "UPI_CPU0_CPU1_P0P0_DP<10>")
	)
	(segment
		(start 134.523734 -62.343538)
		(end 135.095234 -62.343538)
		(width 0.1143)
		(layer "F.Cu")
		(net "UPI_CPU0_CPU1_P0P0_DP<0>")
	)
	(segment
		(start 305.533806 -74.725784)
		(end 306.181506 -74.725784)
		(width 0.1143)
		(layer "F.Cu")
		(net "UPI_CPU0_CPU1_P0P0_DP<0>")
	)
	(via
		(at 306.181506 -74.725784)
		(size 0.508)
		(drill 0.254)
		(layers "F.Cu" "B.Cu")
		(net "UPI_CPU0_CPU1_P0P0_DP<0>")
	)
	(via
		(at 135.095234 -62.343538)
		(size 0.508)
		(drill 0.254)
		(layers "F.Cu" "B.Cu")
		(net "UPI_CPU0_CPU1_P0P0_DP<0>")
	)
	(segment
		(start 148.127212 -60.048648)
		(end 148.71827 -59.979814)
		(width 0.1143)
		(layer "In9.Cu")
		(net "UPI_CPU0_CPU1_P0P0_DP<0>")
	)
	(segment
		(start 308.6481 -83.389978)
		(end 308.567582 -83.179158)
		(width 0.1143)
		(layer "In9.Cu")
		(net "UPI_CPU0_CPU1_P0P0_DP<0>")
	)
	(segment
		(start 227.934266 -105.842308)
		(end 233.623612 -106.810556)
		(width 0.1143)
		(layer "In9.Cu")
		(net "UPI_CPU0_CPU1_P0P0_DP<0>")
	)
	(segment
		(start 306.58054 -74.325734)
		(end 306.04333 -74.325734)
		(width 0.0889)
		(layer "In9.Cu")
		(net "UPI_CPU0_CPU1_P0P0_DP<0>")
	)
	(segment
		(start 306.698142 -77.102716)
		(end 306.698142 -76.595478)
		(width 0.0889)
		(layer "In9.Cu")
		(net "UPI_CPU0_CPU1_P0P0_DP<0>")
	)
	(segment
		(start 307.898292 -81.417922)
		(end 307.6956 -80.884522)
		(width 0.1143)
		(layer "In9.Cu")
		(net "UPI_CPU0_CPU1_P0P0_DP<0>")
	)
	(segment
		(start 263.359138 -107.100878)
		(end 267.03147 -107.280964)
		(width 0.1143)
		(layer "In9.Cu")
		(net "UPI_CPU0_CPU1_P0P0_DP<0>")
	)
	(segment
		(start 310.527446 -88.334088)
		(end 309.066438 -84.490814)
		(width 0.1143)
		(layer "In9.Cu")
		(net "UPI_CPU0_CPU1_P0P0_DP<0>")
	)
	(segment
		(start 307.295804 -79.8322)
		(end 307.24729 -79.704438)
		(width 0.1143)
		(layer "In9.Cu")
		(net "UPI_CPU0_CPU1_P0P0_DP<0>")
	)
	(segment
		(start 307.826664 -81.576672)
		(end 307.898292 -81.417922)
		(width 0.1143)
		(layer "In9.Cu")
		(net "UPI_CPU0_CPU1_P0P0_DP<0>")
	)
	(segment
		(start 177.156618 -101.522276)
		(end 178.374802 -102.535736)
		(width 0.1143)
		(layer "In9.Cu")
		(net "UPI_CPU0_CPU1_P0P0_DP<0>")
	)
	(segment
		(start 233.623612 -106.810556)
		(end 248.018554 -103.935276)
		(width 0.1143)
		(layer "In9.Cu")
		(net "UPI_CPU0_CPU1_P0P0_DP<0>")
	)
	(segment
		(start 173.443138 -100.785676)
		(end 177.156618 -101.522276)
		(width 0.1143)
		(layer "In9.Cu")
		(net "UPI_CPU0_CPU1_P0P0_DP<0>")
	)
	(segment
		(start 135.935974 -61.257434)
		(end 135.96874 -61.257434)
		(width 0.0889)
		(layer "In9.Cu")
		(net "UPI_CPU0_CPU1_P0P0_DP<0>")
	)
	(segment
		(start 292.645338 -102.659434)
		(end 302.91659 -105.28173)
		(width 0.1143)
		(layer "In9.Cu")
		(net "UPI_CPU0_CPU1_P0P0_DP<0>")
	)
	(segment
		(start 309.066438 -84.490814)
		(end 308.907942 -84.419948)
		(width 0.1143)
		(layer "In9.Cu")
		(net "UPI_CPU0_CPU1_P0P0_DP<0>")
	)
	(segment
		(start 302.91659 -105.28173)
		(end 304.966878 -104.814878)
		(width 0.1143)
		(layer "In9.Cu")
		(net "UPI_CPU0_CPU1_P0P0_DP<0>")
	)
	(segment
		(start 306.759356 -77.817726)
		(end 306.759356 -77.817218)
		(width 0.1143)
		(layer "In9.Cu")
		(net "UPI_CPU0_CPU1_P0P0_DP<0>")
	)
	(segment
		(start 140.228828 -58.781188)
		(end 140.268452 -58.781188)
		(width 0.0889)
		(layer "In9.Cu")
		(net "UPI_CPU0_CPU1_P0P0_DP<0>")
	)
	(segment
		(start 307.6956 -101.456744)
		(end 310.086756 -90.376756)
		(width 0.1143)
		(layer "In9.Cu")
		(net "UPI_CPU0_CPU1_P0P0_DP<0>")
	)
	(segment
		(start 308.148228 -82.075274)
		(end 308.087014 -81.915)
		(width 0.1143)
		(layer "In9.Cu")
		(net "UPI_CPU0_CPU1_P0P0_DP<0>")
	)
	(segment
		(start 139.366244 -59.276234)
		(end 139.405868 -59.276234)
		(width 0.0889)
		(layer "In9.Cu")
		(net "UPI_CPU0_CPU1_P0P0_DP<0>")
	)
	(segment
		(start 306.698142 -76.050902)
		(end 306.603654 -75.956414)
		(width 0.0889)
		(layer "In9.Cu")
		(net "UPI_CPU0_CPU1_P0P0_DP<0>")
	)
	(segment
		(start 307.24729 -79.704438)
		(end 306.949094 -78.551024)
		(width 0.1143)
		(layer "In9.Cu")
		(net "UPI_CPU0_CPU1_P0P0_DP<0>")
	)
	(segment
		(start 308.40807 -83.105244)
		(end 308.326536 -82.891376)
		(width 0.1143)
		(layer "In9.Cu")
		(net "UPI_CPU0_CPU1_P0P0_DP<0>")
	)
	(segment
		(start 167.089074 -94.155514)
		(end 173.443138 -100.785676)
		(width 0.1143)
		(layer "In9.Cu")
		(net "UPI_CPU0_CPU1_P0P0_DP<0>")
	)
	(segment
		(start 308.567582 -83.179158)
		(end 308.566566 -83.17611)
		(width 0.1143)
		(layer "In9.Cu")
		(net "UPI_CPU0_CPU1_P0P0_DP<0>")
	)
	(segment
		(start 181.895496 -103.108252)
		(end 184.05348 -104.639618)
		(width 0.1143)
		(layer "In9.Cu")
		(net "UPI_CPU0_CPU1_P0P0_DP<0>")
	)
	(segment
		(start 147.024344 -60.048648)
		(end 148.127212 -60.048648)
		(width 0.1143)
		(layer "In9.Cu")
		(net "UPI_CPU0_CPU1_P0P0_DP<0>")
	)
	(segment
		(start 307.908198 -81.79054)
		(end 307.826664 -81.576672)
		(width 0.1143)
		(layer "In9.Cu")
		(net "UPI_CPU0_CPU1_P0P0_DP<0>")
	)
	(segment
		(start 306.647342 -77.175614)
		(end 306.647342 -77.153516)
		(width 0.0889)
		(layer "In9.Cu")
		(net "UPI_CPU0_CPU1_P0P0_DP<0>")
	)
	(segment
		(start 306.603654 -75.956414)
		(end 306.603654 -75.778614)
		(width 0.0889)
		(layer "In9.Cu")
		(net "UPI_CPU0_CPU1_P0P0_DP<0>")
	)
	(segment
		(start 166.847774 -92.592652)
		(end 167.089074 -94.155514)
		(width 0.1143)
		(layer "In9.Cu")
		(net "UPI_CPU0_CPU1_P0P0_DP<0>")
	)
	(segment
		(start 308.31663 -82.518758)
		(end 308.158134 -82.447892)
		(width 0.1143)
		(layer "In9.Cu")
		(net "UPI_CPU0_CPU1_P0P0_DP<0>")
	)
	(segment
		(start 306.603654 -76.32319)
		(end 306.698142 -76.228702)
		(width 0.0889)
		(layer "In9.Cu")
		(net "UPI_CPU0_CPU1_P0P0_DP<0>")
	)
	(segment
		(start 308.816502 -83.833462)
		(end 308.658006 -83.762596)
		(width 0.1143)
		(layer "In9.Cu")
		(net "UPI_CPU0_CPU1_P0P0_DP<0>")
	)
	(segment
		(start 308.326536 -82.891376)
		(end 308.398164 -82.732626)
		(width 0.1143)
		(layer "In9.Cu")
		(net "UPI_CPU0_CPU1_P0P0_DP<0>")
	)
	(segment
		(start 306.74056 -77.744574)
		(end 306.73929 -77.738224)
		(width 0.1143)
		(layer "In9.Cu")
		(net "UPI_CPU0_CPU1_P0P0_DP<0>")
	)
	(segment
		(start 144.036796 -59.555126)
		(end 146.059906 -59.555126)
		(width 0.0889)
		(layer "In9.Cu")
		(net "UPI_CPU0_CPU1_P0P0_DP<0>")
	)
	(segment
		(start 306.603654 -75.234038)
		(end 306.698142 -75.13955)
		(width 0.0889)
		(layer "In9.Cu")
		(net "UPI_CPU0_CPU1_P0P0_DP<0>")
	)
	(segment
		(start 290.08705 -102.89159)
		(end 290.087304 -102.891336)
		(width 0.1143)
		(layer "In9.Cu")
		(net "UPI_CPU0_CPU1_P0P0_DP<0>")
	)
	(segment
		(start 308.898036 -84.04733)
		(end 308.816502 -83.833462)
		(width 0.1143)
		(layer "In9.Cu")
		(net "UPI_CPU0_CPU1_P0P0_DP<0>")
	)
	(segment
		(start 306.603654 -75.411838)
		(end 306.603654 -75.234038)
		(width 0.0889)
		(layer "In9.Cu")
		(net "UPI_CPU0_CPU1_P0P0_DP<0>")
	)
	(segment
		(start 308.826408 -84.20608)
		(end 308.898036 -84.04733)
		(width 0.1143)
		(layer "In9.Cu")
		(net "UPI_CPU0_CPU1_P0P0_DP<0>")
	)
	(segment
		(start 308.087014 -81.915)
		(end 308.066948 -81.862168)
		(width 0.1143)
		(layer "In9.Cu")
		(net "UPI_CPU0_CPU1_P0P0_DP<0>")
	)
	(segment
		(start 178.374802 -102.535736)
		(end 179.972462 -102.618794)
		(width 0.1143)
		(layer "In9.Cu")
		(net "UPI_CPU0_CPU1_P0P0_DP<0>")
	)
	(segment
		(start 304.966878 -104.814878)
		(end 304.971958 -104.813862)
		(width 0.1143)
		(layer "In9.Cu")
		(net "UPI_CPU0_CPU1_P0P0_DP<0>")
	)
	(segment
		(start 184.05348 -104.639618)
		(end 192.85458 -105.70972)
		(width 0.1143)
		(layer "In9.Cu")
		(net "UPI_CPU0_CPU1_P0P0_DP<0>")
	)
	(segment
		(start 306.647342 -77.153516)
		(end 306.698142 -77.102716)
		(width 0.0889)
		(layer "In9.Cu")
		(net "UPI_CPU0_CPU1_P0P0_DP<0>")
	)
	(segment
		(start 197.149212 -108.524294)
		(end 199.99833 -109.201458)
		(width 0.1143)
		(layer "In9.Cu")
		(net "UPI_CPU0_CPU1_P0P0_DP<0>")
	)
	(segment
		(start 289.64001 -103.062786)
		(end 290.0426 -102.895654)
		(width 0.1143)
		(layer "In9.Cu")
		(net "UPI_CPU0_CPU1_P0P0_DP<0>")
	)
	(segment
		(start 160.2232 -84.753704)
		(end 166.847774 -92.592652)
		(width 0.1143)
		(layer "In9.Cu")
		(net "UPI_CPU0_CPU1_P0P0_DP<0>")
	)
	(segment
		(start 308.576472 -83.548728)
		(end 308.6481 -83.389978)
		(width 0.1143)
		(layer "In9.Cu")
		(net "UPI_CPU0_CPU1_P0P0_DP<0>")
	)
	(segment
		(start 308.317138 -82.520282)
		(end 308.31663 -82.518758)
		(width 0.1143)
		(layer "In9.Cu")
		(net "UPI_CPU0_CPU1_P0P0_DP<0>")
	)
	(segment
		(start 137.653014 -60.266834)
		(end 137.68578 -60.266834)
		(width 0.0889)
		(layer "In9.Cu")
		(net "UPI_CPU0_CPU1_P0P0_DP<0>")
	)
	(segment
		(start 290.087304 -102.891844)
		(end 292.645338 -102.659434)
		(width 0.1143)
		(layer "In9.Cu")
		(net "UPI_CPU0_CPU1_P0P0_DP<0>")
	)
	(segment
		(start 146.951446 -60.099448)
		(end 147.002246 -60.048648)
		(width 0.0889)
		(layer "In9.Cu")
		(net "UPI_CPU0_CPU1_P0P0_DP<0>")
	)
	(segment
		(start 306.647342 -77.322172)
		(end 306.647342 -77.175614)
		(width 0.1143)
		(layer "In9.Cu")
		(net "UPI_CPU0_CPU1_P0P0_DP<0>")
	)
	(segment
		(start 143.740886 -59.259216)
		(end 144.036796 -59.555126)
		(width 0.0889)
		(layer "In9.Cu")
		(net "UPI_CPU0_CPU1_P0P0_DP<0>")
	)
	(segment
		(start 306.698142 -75.684126)
		(end 306.698142 -75.506326)
		(width 0.0889)
		(layer "In9.Cu")
		(net "UPI_CPU0_CPU1_P0P0_DP<0>")
	)
	(segment
		(start 306.698142 -75.13955)
		(end 306.698142 -74.443336)
		(width 0.0889)
		(layer "In9.Cu")
		(net "UPI_CPU0_CPU1_P0P0_DP<0>")
	)
	(segment
		(start 140.228574 -58.780934)
		(end 140.228828 -58.781188)
		(width 0.0889)
		(layer "In9.Cu")
		(net "UPI_CPU0_CPU1_P0P0_DP<0>")
	)
	(segment
		(start 306.698142 -75.506326)
		(end 306.603654 -75.411838)
		(width 0.0889)
		(layer "In9.Cu")
		(net "UPI_CPU0_CPU1_P0P0_DP<0>")
	)
	(segment
		(start 308.066948 -81.862168)
		(end 308.066694 -81.861406)
		(width 0.1143)
		(layer "In9.Cu")
		(net "UPI_CPU0_CPU1_P0P0_DP<0>")
	)
	(segment
		(start 306.603654 -76.50099)
		(end 306.603654 -76.32319)
		(width 0.0889)
		(layer "In9.Cu")
		(net "UPI_CPU0_CPU1_P0P0_DP<0>")
	)
	(segment
		(start 138.51636 -59.771534)
		(end 138.54049 -59.771534)
		(width 0.0889)
		(layer "In9.Cu")
		(net "UPI_CPU0_CPU1_P0P0_DP<0>")
	)
	(segment
		(start 267.03147 -107.280964)
		(end 278.123396 -106.215942)
		(width 0.1143)
		(layer "In9.Cu")
		(net "UPI_CPU0_CPU1_P0P0_DP<0>")
	)
	(segment
		(start 306.04333 -74.725784)
		(end 306.181506 -74.725784)
		(width 0.0889)
		(layer "In9.Cu")
		(net "UPI_CPU0_CPU1_P0P0_DP<0>")
	)
	(segment
		(start 308.158134 -82.447892)
		(end 308.0766 -82.234024)
		(width 0.1143)
		(layer "In9.Cu")
		(net "UPI_CPU0_CPU1_P0P0_DP<0>")
	)
	(segment
		(start 135.18515 -62.204854)
		(end 135.401558 -61.637418)
		(width 0.0889)
		(layer "In9.Cu")
		(net "UPI_CPU0_CPU1_P0P0_DP<0>")
	)
	(segment
		(start 306.603654 -75.778614)
		(end 306.698142 -75.684126)
		(width 0.0889)
		(layer "In9.Cu")
		(net "UPI_CPU0_CPU1_P0P0_DP<0>")
	)
	(segment
		(start 199.99833 -109.201458)
		(end 227.934266 -105.842308)
		(width 0.1143)
		(layer "In9.Cu")
		(net "UPI_CPU0_CPU1_P0P0_DP<0>")
	)
	(segment
		(start 147.002246 -60.048648)
		(end 147.024344 -60.048648)
		(width 0.0889)
		(layer "In9.Cu")
		(net "UPI_CPU0_CPU1_P0P0_DP<0>")
	)
	(segment
		(start 290.0426 -102.895654)
		(end 290.08705 -102.89159)
		(width 0.1143)
		(layer "In9.Cu")
		(net "UPI_CPU0_CPU1_P0P0_DP<0>")
	)
	(segment
		(start 306.698142 -76.595478)
		(end 306.603654 -76.50099)
		(width 0.0889)
		(layer "In9.Cu")
		(net "UPI_CPU0_CPU1_P0P0_DP<0>")
	)
	(segment
		(start 307.6956 -80.884522)
		(end 307.295804 -79.8322)
		(width 0.1143)
		(layer "In9.Cu")
		(net "UPI_CPU0_CPU1_P0P0_DP<0>")
	)
	(segment
		(start 308.398164 -82.732626)
		(end 308.317138 -82.520282)
		(width 0.1143)
		(layer "In9.Cu")
		(net "UPI_CPU0_CPU1_P0P0_DP<0>")
	)
	(segment
		(start 308.566566 -83.17611)
		(end 308.40807 -83.105244)
		(width 0.1143)
		(layer "In9.Cu")
		(net "UPI_CPU0_CPU1_P0P0_DP<0>")
	)
	(segment
		(start 281.1907 -106.571542)
		(end 289.64001 -103.062786)
		(width 0.1143)
		(layer "In9.Cu")
		(net "UPI_CPU0_CPU1_P0P0_DP<0>")
	)
	(segment
		(start 278.123396 -106.215942)
		(end 281.1907 -106.571542)
		(width 0.1143)
		(layer "In9.Cu")
		(net "UPI_CPU0_CPU1_P0P0_DP<0>")
	)
	(segment
		(start 148.71827 -59.979814)
		(end 149.297136 -60.020962)
		(width 0.1143)
		(layer "In9.Cu")
		(net "UPI_CPU0_CPU1_P0P0_DP<0>")
	)
	(segment
		(start 192.85458 -105.70972)
		(end 197.149212 -108.524294)
		(width 0.1143)
		(layer "In9.Cu")
		(net "UPI_CPU0_CPU1_P0P0_DP<0>")
	)
	(segment
		(start 306.759356 -77.817218)
		(end 306.74056 -77.744574)
		(width 0.1143)
		(layer "In9.Cu")
		(net "UPI_CPU0_CPU1_P0P0_DP<0>")
	)
	(segment
		(start 146.059906 -59.555126)
		(end 146.604228 -60.099448)
		(width 0.0889)
		(layer "In9.Cu")
		(net "UPI_CPU0_CPU1_P0P0_DP<0>")
	)
	(segment
		(start 141.1859 -59.323478)
		(end 142.338298 -59.323478)
		(width 0.0889)
		(layer "In9.Cu")
		(net "UPI_CPU0_CPU1_P0P0_DP<0>")
	)
	(segment
		(start 304.971958 -104.813862)
		(end 304.974244 -104.81183)
		(width 0.1143)
		(layer "In9.Cu")
		(net "UPI_CPU0_CPU1_P0P0_DP<0>")
	)
	(segment
		(start 308.658006 -83.762596)
		(end 308.576472 -83.548728)
		(width 0.1143)
		(layer "In9.Cu")
		(net "UPI_CPU0_CPU1_P0P0_DP<0>")
	)
	(segment
		(start 306.698142 -74.443336)
		(end 306.58054 -74.325734)
		(width 0.0889)
		(layer "In9.Cu")
		(net "UPI_CPU0_CPU1_P0P0_DP<0>")
	)
	(segment
		(start 308.907942 -84.419948)
		(end 308.826408 -84.20608)
		(width 0.1143)
		(layer "In9.Cu")
		(net "UPI_CPU0_CPU1_P0P0_DP<0>")
	)
	(segment
		(start 310.086756 -90.376756)
		(end 310.527446 -88.334088)
		(width 0.1143)
		(layer "In9.Cu")
		(net "UPI_CPU0_CPU1_P0P0_DP<0>")
	)
	(segment
		(start 308.066694 -81.861406)
		(end 307.908198 -81.79054)
		(width 0.1143)
		(layer "In9.Cu")
		(net "UPI_CPU0_CPU1_P0P0_DP<0>")
	)
	(segment
		(start 155.296108 -66.581274)
		(end 160.2232 -84.753704)
		(width 0.1143)
		(layer "In9.Cu")
		(net "UPI_CPU0_CPU1_P0P0_DP<0>")
	)
	(segment
		(start 306.73929 -77.738224)
		(end 306.647342 -77.322172)
		(width 0.1143)
		(layer "In9.Cu")
		(net "UPI_CPU0_CPU1_P0P0_DP<0>")
	)
	(segment
		(start 308.0766 -82.234024)
		(end 308.148228 -82.075274)
		(width 0.1143)
		(layer "In9.Cu")
		(net "UPI_CPU0_CPU1_P0P0_DP<0>")
	)
	(segment
		(start 142.40256 -59.259216)
		(end 143.740886 -59.259216)
		(width 0.0889)
		(layer "In9.Cu")
		(net "UPI_CPU0_CPU1_P0P0_DP<0>")
	)
	(segment
		(start 307.469286 -102.50551)
		(end 307.6956 -101.456744)
		(width 0.1143)
		(layer "In9.Cu")
		(net "UPI_CPU0_CPU1_P0P0_DP<0>")
	)
	(segment
		(start 306.949094 -78.551024)
		(end 306.949094 -78.550516)
		(width 0.1143)
		(layer "In9.Cu")
		(net "UPI_CPU0_CPU1_P0P0_DP<0>")
	)
	(segment
		(start 304.974244 -104.81183)
		(end 307.469286 -102.50551)
		(width 0.1143)
		(layer "In9.Cu")
		(net "UPI_CPU0_CPU1_P0P0_DP<0>")
	)
	(segment
		(start 149.297136 -60.020962)
		(end 155.296108 -66.581274)
		(width 0.1143)
		(layer "In9.Cu")
		(net "UPI_CPU0_CPU1_P0P0_DP<0>")
	)
	(segment
		(start 146.604228 -60.099448)
		(end 146.951446 -60.099448)
		(width 0.0889)
		(layer "In9.Cu")
		(net "UPI_CPU0_CPU1_P0P0_DP<0>")
	)
	(segment
		(start 248.018554 -103.935276)
		(end 263.359138 -107.100878)
		(width 0.1143)
		(layer "In9.Cu")
		(net "UPI_CPU0_CPU1_P0P0_DP<0>")
	)
	(segment
		(start 306.949094 -78.550516)
		(end 306.759356 -77.817726)
		(width 0.1143)
		(layer "In9.Cu")
		(net "UPI_CPU0_CPU1_P0P0_DP<0>")
	)
	(segment
		(start 179.972462 -102.618794)
		(end 181.895496 -103.108252)
		(width 0.1143)
		(layer "In9.Cu")
		(net "UPI_CPU0_CPU1_P0P0_DP<0>")
	)
	(segment
		(start 306.698142 -76.228702)
		(end 306.698142 -76.050902)
		(width 0.0889)
		(layer "In9.Cu")
		(net "UPI_CPU0_CPU1_P0P0_DP<0>")
	)
	(segment
		(start 290.087304 -102.891336)
		(end 290.087304 -102.891844)
		(width 0.1143)
		(layer "In9.Cu")
		(net "UPI_CPU0_CPU1_P0P0_DP<0>")
	)
	(segment
		(start 136.790684 -60.762388)
		(end 136.82345 -60.762388)
		(width 0.0889)
		(layer "In9.Cu")
		(net "UPI_CPU0_CPU1_P0P0_DP<0>")
	)
	(segment
		(start 142.338298 -59.323478)
		(end 142.40256 -59.259216)
		(width 0.0889)
		(layer "In9.Cu")
		(net "UPI_CPU0_CPU1_P0P0_DP<0>")
	)
	(arc
		(start 135.96874 -61.257434)
		(mid 136.160382 -61.200268)
		(end 136.300464 -61.057536)
		(width 0.0889)
		(layer "In9.Cu")
		(net "UPI_CPU0_CPU1_P0P0_DP<0>")
	)
	(arc
		(start 305.98237 -74.335386)
		(mid 305.845707 -74.556735)
		(end 306.04333 -74.725784)
		(width 0.0889)
		(layer "In9.Cu")
		(net "UPI_CPU0_CPU1_P0P0_DP<0>")
	)
	(arc
		(start 138.876024 -59.571382)
		(mid 139.083028 -59.360518)
		(end 139.366244 -59.276234)
		(width 0.0889)
		(layer "In9.Cu")
		(net "UPI_CPU0_CPU1_P0P0_DP<0>")
	)
	(arc
		(start 135.401558 -61.637418)
		(mid 135.611218 -61.366506)
		(end 135.935974 -61.257434)
		(width 0.0889)
		(layer "In9.Cu")
		(net "UPI_CPU0_CPU1_P0P0_DP<0>")
	)
	(arc
		(start 139.405868 -59.276234)
		(mid 139.595797 -59.218364)
		(end 139.734544 -59.076336)
		(width 0.0889)
		(layer "In9.Cu")
		(net "UPI_CPU0_CPU1_P0P0_DP<0>")
	)
	(arc
		(start 138.54049 -59.771534)
		(mid 138.73434 -59.715184)
		(end 138.876024 -59.571382)
		(width 0.0889)
		(layer "In9.Cu")
		(net "UPI_CPU0_CPU1_P0P0_DP<0>")
	)
	(arc
		(start 137.158984 -60.562236)
		(mid 137.367592 -60.350304)
		(end 137.653014 -60.266834)
		(width 0.0889)
		(layer "In9.Cu")
		(net "UPI_CPU0_CPU1_P0P0_DP<0>")
	)
	(arc
		(start 138.017504 -60.066936)
		(mid 138.228217 -59.853857)
		(end 138.51636 -59.771534)
		(width 0.0889)
		(layer "In9.Cu")
		(net "UPI_CPU0_CPU1_P0P0_DP<0>")
	)
	(arc
		(start 140.268452 -58.781188)
		(mid 140.551356 -58.865607)
		(end 140.758164 -59.076336)
		(width 0.0889)
		(layer "In9.Cu")
		(net "UPI_CPU0_CPU1_P0P0_DP<0>")
	)
	(arc
		(start 140.758164 -59.076336)
		(mid 140.938875 -59.25732)
		(end 141.1859 -59.323478)
		(width 0.0889)
		(layer "In9.Cu")
		(net "UPI_CPU0_CPU1_P0P0_DP<0>")
	)
	(arc
		(start 136.82345 -60.762388)
		(mid 137.0173 -60.706038)
		(end 137.158984 -60.562236)
		(width 0.0889)
		(layer "In9.Cu")
		(net "UPI_CPU0_CPU1_P0P0_DP<0>")
	)
	(arc
		(start 139.734544 -59.076336)
		(mid 139.943152 -58.864404)
		(end 140.228574 -58.780934)
		(width 0.0889)
		(layer "In9.Cu")
		(net "UPI_CPU0_CPU1_P0P0_DP<0>")
	)
	(arc
		(start 306.04333 -74.325734)
		(mid 306.012479 -74.328208)
		(end 305.98237 -74.335386)
		(width 0.0889)
		(layer "In9.Cu")
		(net "UPI_CPU0_CPU1_P0P0_DP<0>")
	)
	(arc
		(start 136.300464 -61.057536)
		(mid 136.507468 -60.846672)
		(end 136.790684 -60.762388)
		(width 0.0889)
		(layer "In9.Cu")
		(net "UPI_CPU0_CPU1_P0P0_DP<0>")
	)
	(arc
		(start 135.095234 -62.343538)
		(mid 135.147493 -62.278933)
		(end 135.18515 -62.204854)
		(width 0.0889)
		(layer "In9.Cu")
		(net "UPI_CPU0_CPU1_P0P0_DP<0>")
	)
	(arc
		(start 137.68578 -60.266834)
		(mid 137.877422 -60.209668)
		(end 138.017504 -60.066936)
		(width 0.0889)
		(layer "In9.Cu")
		(net "UPI_CPU0_CPU1_P0P0_DP<0>")
	)
	(segment
		(start 305.533806 -66.800984)
		(end 306.105306 -66.800984)
		(width 0.1143)
		(layer "F.Cu")
		(net "UPI_CPU0_CPU1_P0P0_DN<9>")
	)
	(segment
		(start 136.240774 -66.305938)
		(end 136.812274 -66.305938)
		(width 0.1143)
		(layer "F.Cu")
		(net "UPI_CPU0_CPU1_P0P0_DN<9>")
	)
	(via
		(at 306.105306 -66.800984)
		(size 0.508)
		(drill 0.254)
		(layers "F.Cu" "B.Cu")
		(net "UPI_CPU0_CPU1_P0P0_DN<9>")
	)
	(via
		(at 136.812274 -66.305938)
		(size 0.508)
		(drill 0.254)
		(layers "F.Cu" "B.Cu")
		(net "UPI_CPU0_CPU1_P0P0_DN<9>")
	)
	(segment
		(start 302.82261 -111.195866)
		(end 307.6956 -110.08741)
		(width 0.1143)
		(layer "In9.Cu")
		(net "UPI_CPU0_CPU1_P0P0_DN<9>")
	)
	(segment
		(start 315.645292 -83.368134)
		(end 314.480956 -80.305656)
		(width 0.1143)
		(layer "In9.Cu")
		(net "UPI_CPU0_CPU1_P0P0_DN<9>")
	)
	(segment
		(start 314.41898 -78.090522)
		(end 314.280296 -77.959712)
		(width 0.1143)
		(layer "In9.Cu")
		(net "UPI_CPU0_CPU1_P0P0_DN<9>")
	)
	(segment
		(start 314.219336 -75.777344)
		(end 314.212732 -75.548236)
		(width 0.1143)
		(layer "In9.Cu")
		(net "UPI_CPU0_CPU1_P0P0_DN<9>")
	)
	(segment
		(start 316.6364 -85.975444)
		(end 315.645292 -83.368134)
		(width 0.1143)
		(layer "In9.Cu")
		(net "UPI_CPU0_CPU1_P0P0_DN<9>")
	)
	(segment
		(start 278.06904 -111.987838)
		(end 282.00731 -112.44453)
		(width 0.1143)
		(layer "In9.Cu")
		(net "UPI_CPU0_CPU1_P0P0_DN<9>")
	)
	(segment
		(start 312.697114 -105.513632)
		(end 314.91809 -95.20809)
		(width 0.1143)
		(layer "In9.Cu")
		(net "UPI_CPU0_CPU1_P0P0_DN<9>")
	)
	(segment
		(start 314.425584 -78.319376)
		(end 314.41898 -78.090522)
		(width 0.1143)
		(layer "In9.Cu")
		(net "UPI_CPU0_CPU1_P0P0_DN<9>")
	)
	(segment
		(start 314.253372 -77.003148)
		(end 314.384944 -76.864464)
		(width 0.1143)
		(layer "In9.Cu")
		(net "UPI_CPU0_CPU1_P0P0_DN<9>")
	)
	(segment
		(start 316.809374 -86.430612)
		(end 316.6364 -85.975444)
		(width 0.1143)
		(layer "In9.Cu")
		(net "UPI_CPU0_CPU1_P0P0_DN<9>")
	)
	(segment
		(start 143.71447 -68.842128)
		(end 144.264888 -68.842128)
		(width 0.1143)
		(layer "In9.Cu")
		(net "UPI_CPU0_CPU1_P0P0_DN<9>")
	)
	(segment
		(start 136.801098 -66.705988)
		(end 136.833864 -66.705988)
		(width 0.0889)
		(layer "In9.Cu")
		(net "UPI_CPU0_CPU1_P0P0_DN<9>")
	)
	(segment
		(start 247.923558 -115.066826)
		(end 258.386072 -112.603026)
		(width 0.1143)
		(layer "In9.Cu")
		(net "UPI_CPU0_CPU1_P0P0_DN<9>")
	)
	(segment
		(start 314.320936 -79.414624)
		(end 314.314332 -79.185516)
		(width 0.1143)
		(layer "In9.Cu")
		(net "UPI_CPU0_CPU1_P0P0_DN<9>")
	)
	(segment
		(start 310.503062 -67.463924)
		(end 309.296562 -66.257424)
		(width 0.0889)
		(layer "In9.Cu")
		(net "UPI_CPU0_CPU1_P0P0_DN<9>")
	)
	(segment
		(start 136.519158 -66.474848)
		(end 136.498076 -66.553588)
		(width 0.0889)
		(layer "In9.Cu")
		(net "UPI_CPU0_CPU1_P0P0_DN<9>")
	)
	(segment
		(start 142.608046 -67.95389)
		(end 142.608046 -68.084446)
		(width 0.0889)
		(layer "In9.Cu")
		(net "UPI_CPU0_CPU1_P0P0_DN<9>")
	)
	(segment
		(start 174.864522 -107.998768)
		(end 174.865792 -108.002578)
		(width 0.1143)
		(layer "In9.Cu")
		(net "UPI_CPU0_CPU1_P0P0_DN<9>")
	)
	(segment
		(start 258.386072 -112.603026)
		(end 267.166344 -113.034826)
		(width 0.1143)
		(layer "In9.Cu")
		(net "UPI_CPU0_CPU1_P0P0_DN<9>")
	)
	(segment
		(start 137.655808 -67.201034)
		(end 137.688574 -67.201034)
		(width 0.0889)
		(layer "In9.Cu")
		(net "UPI_CPU0_CPU1_P0P0_DN<9>")
	)
	(segment
		(start 311.049924 -67.514724)
		(end 310.999124 -67.463924)
		(width 0.0889)
		(layer "In9.Cu")
		(net "UPI_CPU0_CPU1_P0P0_DN<9>")
	)
	(segment
		(start 314.3377 -75.180698)
		(end 314.199016 -75.049888)
		(width 0.1143)
		(layer "In9.Cu")
		(net "UPI_CPU0_CPU1_P0P0_DN<9>")
	)
	(segment
		(start 314.37834 -76.63561)
		(end 314.239656 -76.5048)
		(width 0.1143)
		(layer "In9.Cu")
		(net "UPI_CPU0_CPU1_P0P0_DN<9>")
	)
	(segment
		(start 161.339276 -94.963996)
		(end 162.012376 -99.317302)
		(width 0.1143)
		(layer "In9.Cu")
		(net "UPI_CPU0_CPU1_P0P0_DN<9>")
	)
	(segment
		(start 307.6956 -110.08741)
		(end 307.76291 -110.07217)
		(width 0.1143)
		(layer "In9.Cu")
		(net "UPI_CPU0_CPU1_P0P0_DN<9>")
	)
	(segment
		(start 314.233052 -76.275692)
		(end 314.364624 -76.137008)
		(width 0.1143)
		(layer "In9.Cu")
		(net "UPI_CPU0_CPU1_P0P0_DN<9>")
	)
	(segment
		(start 311.518808 -67.637152)
		(end 311.37225 -67.514724)
		(width 0.1143)
		(layer "In9.Cu")
		(net "UPI_CPU0_CPU1_P0P0_DN<9>")
	)
	(segment
		(start 314.192412 -74.82078)
		(end 314.323984 -74.682096)
		(width 0.1143)
		(layer "In9.Cu")
		(net "UPI_CPU0_CPU1_P0P0_DN<9>")
	)
	(segment
		(start 193.364358 -115.65382)
		(end 196.611748 -115.435126)
		(width 0.1143)
		(layer "In9.Cu")
		(net "UPI_CPU0_CPU1_P0P0_DN<9>")
	)
	(segment
		(start 138.518138 -67.696588)
		(end 138.550904 -67.696588)
		(width 0.0889)
		(layer "In9.Cu")
		(net "UPI_CPU0_CPU1_P0P0_DN<9>")
	)
	(segment
		(start 139.372848 -68.191634)
		(end 139.40282 -68.191634)
		(width 0.0889)
		(layer "In9.Cu")
		(net "UPI_CPU0_CPU1_P0P0_DN<9>")
	)
	(segment
		(start 142.220188 -67.696588)
		(end 142.351506 -67.827906)
		(width 0.0889)
		(layer "In9.Cu")
		(net "UPI_CPU0_CPU1_P0P0_DN<9>")
	)
	(segment
		(start 141.942058 -67.696588)
		(end 142.220188 -67.696588)
		(width 0.0889)
		(layer "In9.Cu")
		(net "UPI_CPU0_CPU1_P0P0_DN<9>")
	)
	(segment
		(start 291.125402 -108.65993)
		(end 291.436298 -108.530898)
		(width 0.1143)
		(layer "In9.Cu")
		(net "UPI_CPU0_CPU1_P0P0_DN<9>")
	)
	(segment
		(start 314.323984 -74.682096)
		(end 314.31738 -74.453242)
		(width 0.1143)
		(layer "In9.Cu")
		(net "UPI_CPU0_CPU1_P0P0_DN<9>")
	)
	(segment
		(start 314.273692 -77.730604)
		(end 314.405264 -77.59192)
		(width 0.1143)
		(layer "In9.Cu")
		(net "UPI_CPU0_CPU1_P0P0_DN<9>")
	)
	(segment
		(start 314.172092 -74.093324)
		(end 314.303918 -73.95464)
		(width 0.1143)
		(layer "In9.Cu")
		(net "UPI_CPU0_CPU1_P0P0_DN<9>")
	)
	(segment
		(start 306.648866 -66.257424)
		(end 306.105306 -66.800984)
		(width 0.0889)
		(layer "In9.Cu")
		(net "UPI_CPU0_CPU1_P0P0_DN<9>")
	)
	(segment
		(start 314.384944 -76.864464)
		(end 314.37834 -76.63561)
		(width 0.1143)
		(layer "In9.Cu")
		(net "UPI_CPU0_CPU1_P0P0_DN<9>")
	)
	(segment
		(start 315.226446 -93.7768)
		(end 315.5823 -92.1258)
		(width 0.1143)
		(layer "In9.Cu")
		(net "UPI_CPU0_CPU1_P0P0_DN<9>")
	)
	(segment
		(start 143.692372 -68.842128)
		(end 143.71447 -68.842128)
		(width 0.0889)
		(layer "In9.Cu")
		(net "UPI_CPU0_CPU1_P0P0_DN<9>")
	)
	(segment
		(start 136.812274 -66.305938)
		(end 136.519158 -66.474848)
		(width 0.0889)
		(layer "In9.Cu")
		(net "UPI_CPU0_CPU1_P0P0_DN<9>")
	)
	(segment
		(start 162.012376 -99.317302)
		(end 168.730422 -105.859072)
		(width 0.1143)
		(layer "In9.Cu")
		(net "UPI_CPU0_CPU1_P0P0_DN<9>")
	)
	(segment
		(start 307.76291 -110.07217)
		(end 312.697114 -105.513632)
		(width 0.1143)
		(layer "In9.Cu")
		(net "UPI_CPU0_CPU1_P0P0_DN<9>")
	)
	(segment
		(start 292.127432 -108.468414)
		(end 302.82261 -111.195866)
		(width 0.1143)
		(layer "In9.Cu")
		(net "UPI_CPU0_CPU1_P0P0_DN<9>")
	)
	(segment
		(start 155.011628 -87.475568)
		(end 161.339276 -94.963996)
		(width 0.1143)
		(layer "In9.Cu")
		(net "UPI_CPU0_CPU1_P0P0_DN<9>")
	)
	(segment
		(start 314.31738 -74.453242)
		(end 314.178696 -74.322432)
		(width 0.1143)
		(layer "In9.Cu")
		(net "UPI_CPU0_CPU1_P0P0_DN<9>")
	)
	(segment
		(start 314.4393 -78.817978)
		(end 314.300616 -78.687168)
		(width 0.1143)
		(layer "In9.Cu")
		(net "UPI_CPU0_CPU1_P0P0_DN<9>")
	)
	(segment
		(start 144.264888 -68.842128)
		(end 149.229064 -72.236076)
		(width 0.1143)
		(layer "In9.Cu")
		(net "UPI_CPU0_CPU1_P0P0_DN<9>")
	)
	(segment
		(start 168.730422 -105.859072)
		(end 174.864522 -107.998768)
		(width 0.1143)
		(layer "In9.Cu")
		(net "UPI_CPU0_CPU1_P0P0_DN<9>")
	)
	(segment
		(start 314.445904 -79.046832)
		(end 314.4393 -78.817978)
		(width 0.1143)
		(layer "In9.Cu")
		(net "UPI_CPU0_CPU1_P0P0_DN<9>")
	)
	(segment
		(start 314.284614 -73.227184)
		(end 312.57875 -69.267578)
		(width 0.1143)
		(layer "In9.Cu")
		(net "UPI_CPU0_CPU1_P0P0_DN<9>")
	)
	(segment
		(start 314.259976 -77.232256)
		(end 314.253372 -77.003148)
		(width 0.1143)
		(layer "In9.Cu")
		(net "UPI_CPU0_CPU1_P0P0_DN<9>")
	)
	(segment
		(start 311.37225 -67.514724)
		(end 311.072022 -67.514724)
		(width 0.1143)
		(layer "In9.Cu")
		(net "UPI_CPU0_CPU1_P0P0_DN<9>")
	)
	(segment
		(start 314.212732 -75.548236)
		(end 314.344304 -75.409552)
		(width 0.1143)
		(layer "In9.Cu")
		(net "UPI_CPU0_CPU1_P0P0_DN<9>")
	)
	(segment
		(start 314.199016 -75.049888)
		(end 314.192412 -74.82078)
		(width 0.1143)
		(layer "In9.Cu")
		(net "UPI_CPU0_CPU1_P0P0_DN<9>")
	)
	(segment
		(start 314.316364 -77.285342)
		(end 314.259976 -77.232256)
		(width 0.1143)
		(layer "In9.Cu")
		(net "UPI_CPU0_CPU1_P0P0_DN<9>")
	)
	(segment
		(start 314.303918 -73.95464)
		(end 314.284614 -73.227184)
		(width 0.1143)
		(layer "In9.Cu")
		(net "UPI_CPU0_CPU1_P0P0_DN<9>")
	)
	(segment
		(start 141.089888 -68.191634)
		(end 141.11986 -68.191634)
		(width 0.0889)
		(layer "In9.Cu")
		(net "UPI_CPU0_CPU1_P0P0_DN<9>")
	)
	(segment
		(start 314.91809 -95.20809)
		(end 315.226446 -93.7768)
		(width 0.1143)
		(layer "In9.Cu")
		(net "UPI_CPU0_CPU1_P0P0_DN<9>")
	)
	(segment
		(start 186.125612 -114.863118)
		(end 193.364358 -115.65382)
		(width 0.1143)
		(layer "In9.Cu")
		(net "UPI_CPU0_CPU1_P0P0_DN<9>")
	)
	(segment
		(start 314.344304 -75.409552)
		(end 314.3377 -75.180698)
		(width 0.1143)
		(layer "In9.Cu")
		(net "UPI_CPU0_CPU1_P0P0_DN<9>")
	)
	(segment
		(start 174.865792 -108.002578)
		(end 175.262032 -108.231178)
		(width 0.1143)
		(layer "In9.Cu")
		(net "UPI_CPU0_CPU1_P0P0_DN<9>")
	)
	(segment
		(start 314.294012 -78.45806)
		(end 314.425584 -78.319376)
		(width 0.1143)
		(layer "In9.Cu")
		(net "UPI_CPU0_CPU1_P0P0_DN<9>")
	)
	(segment
		(start 314.39866 -77.363066)
		(end 314.316364 -77.285342)
		(width 0.1143)
		(layer "In9.Cu")
		(net "UPI_CPU0_CPU1_P0P0_DN<9>")
	)
	(segment
		(start 196.611748 -115.435126)
		(end 227.941124 -111.665004)
		(width 0.1143)
		(layer "In9.Cu")
		(net "UPI_CPU0_CPU1_P0P0_DN<9>")
	)
	(segment
		(start 314.239656 -76.5048)
		(end 314.233052 -76.275692)
		(width 0.1143)
		(layer "In9.Cu")
		(net "UPI_CPU0_CPU1_P0P0_DN<9>")
	)
	(segment
		(start 312.03265 -68.4276)
		(end 311.518808 -67.637152)
		(width 0.1143)
		(layer "In9.Cu")
		(net "UPI_CPU0_CPU1_P0P0_DN<9>")
	)
	(segment
		(start 175.262032 -108.231178)
		(end 178.574954 -111.192818)
		(width 0.1143)
		(layer "In9.Cu")
		(net "UPI_CPU0_CPU1_P0P0_DN<9>")
	)
	(segment
		(start 315.5823 -92.1258)
		(end 316.809374 -86.430612)
		(width 0.1143)
		(layer "In9.Cu")
		(net "UPI_CPU0_CPU1_P0P0_DN<9>")
	)
	(segment
		(start 149.229064 -72.236076)
		(end 151.80691 -75.661266)
		(width 0.1143)
		(layer "In9.Cu")
		(net "UPI_CPU0_CPU1_P0P0_DN<9>")
	)
	(segment
		(start 143.641572 -68.892928)
		(end 143.692372 -68.842128)
		(width 0.0889)
		(layer "In9.Cu")
		(net "UPI_CPU0_CPU1_P0P0_DN<9>")
	)
	(segment
		(start 227.941124 -111.665004)
		(end 247.923558 -115.066826)
		(width 0.1143)
		(layer "In9.Cu")
		(net "UPI_CPU0_CPU1_P0P0_DN<9>")
	)
	(segment
		(start 291.436298 -108.530898)
		(end 292.127432 -108.468414)
		(width 0.1143)
		(layer "In9.Cu")
		(net "UPI_CPU0_CPU1_P0P0_DN<9>")
	)
	(segment
		(start 314.314332 -79.185516)
		(end 314.445904 -79.046832)
		(width 0.1143)
		(layer "In9.Cu")
		(net "UPI_CPU0_CPU1_P0P0_DN<9>")
	)
	(segment
		(start 140.224764 -67.696588)
		(end 140.267944 -67.696588)
		(width 0.0889)
		(layer "In9.Cu")
		(net "UPI_CPU0_CPU1_P0P0_DN<9>")
	)
	(segment
		(start 142.608046 -68.084446)
		(end 143.416528 -68.892928)
		(width 0.0889)
		(layer "In9.Cu")
		(net "UPI_CPU0_CPU1_P0P0_DN<9>")
	)
	(segment
		(start 312.57875 -69.267578)
		(end 312.03265 -68.4276)
		(width 0.1143)
		(layer "In9.Cu")
		(net "UPI_CPU0_CPU1_P0P0_DN<9>")
	)
	(segment
		(start 142.482062 -67.827906)
		(end 142.608046 -67.95389)
		(width 0.0889)
		(layer "In9.Cu")
		(net "UPI_CPU0_CPU1_P0P0_DN<9>")
	)
	(segment
		(start 314.405264 -77.59192)
		(end 314.39866 -77.363066)
		(width 0.1143)
		(layer "In9.Cu")
		(net "UPI_CPU0_CPU1_P0P0_DN<9>")
	)
	(segment
		(start 314.300616 -78.687168)
		(end 314.294012 -78.45806)
		(width 0.1143)
		(layer "In9.Cu")
		(net "UPI_CPU0_CPU1_P0P0_DN<9>")
	)
	(segment
		(start 309.296562 -66.257424)
		(end 306.648866 -66.257424)
		(width 0.0889)
		(layer "In9.Cu")
		(net "UPI_CPU0_CPU1_P0P0_DN<9>")
	)
	(segment
		(start 310.999124 -67.463924)
		(end 310.503062 -67.463924)
		(width 0.0889)
		(layer "In9.Cu")
		(net "UPI_CPU0_CPU1_P0P0_DN<9>")
	)
	(segment
		(start 311.072022 -67.514724)
		(end 311.049924 -67.514724)
		(width 0.0889)
		(layer "In9.Cu")
		(net "UPI_CPU0_CPU1_P0P0_DN<9>")
	)
	(segment
		(start 282.00731 -112.44453)
		(end 291.125402 -108.65993)
		(width 0.1143)
		(layer "In9.Cu")
		(net "UPI_CPU0_CPU1_P0P0_DN<9>")
	)
	(segment
		(start 314.480956 -80.305656)
		(end 314.467748 -79.8322)
		(width 0.1143)
		(layer "In9.Cu")
		(net "UPI_CPU0_CPU1_P0P0_DN<9>")
	)
	(segment
		(start 267.166344 -113.034826)
		(end 278.06904 -111.987838)
		(width 0.1143)
		(layer "In9.Cu")
		(net "UPI_CPU0_CPU1_P0P0_DN<9>")
	)
	(segment
		(start 314.35802 -75.908154)
		(end 314.219336 -75.777344)
		(width 0.1143)
		(layer "In9.Cu")
		(net "UPI_CPU0_CPU1_P0P0_DN<9>")
	)
	(segment
		(start 151.80691 -75.661266)
		(end 155.011628 -87.475568)
		(width 0.1143)
		(layer "In9.Cu")
		(net "UPI_CPU0_CPU1_P0P0_DN<9>")
	)
	(segment
		(start 314.467748 -79.8322)
		(end 314.45962 -79.545434)
		(width 0.1143)
		(layer "In9.Cu")
		(net "UPI_CPU0_CPU1_P0P0_DN<9>")
	)
	(segment
		(start 314.178696 -74.322432)
		(end 314.172092 -74.093324)
		(width 0.1143)
		(layer "In9.Cu")
		(net "UPI_CPU0_CPU1_P0P0_DN<9>")
	)
	(segment
		(start 314.280296 -77.959712)
		(end 314.273692 -77.730604)
		(width 0.1143)
		(layer "In9.Cu")
		(net "UPI_CPU0_CPU1_P0P0_DN<9>")
	)
	(segment
		(start 142.351506 -67.827906)
		(end 142.482062 -67.827906)
		(width 0.0889)
		(layer "In9.Cu")
		(net "UPI_CPU0_CPU1_P0P0_DN<9>")
	)
	(segment
		(start 314.45962 -79.545434)
		(end 314.320936 -79.414624)
		(width 0.1143)
		(layer "In9.Cu")
		(net "UPI_CPU0_CPU1_P0P0_DN<9>")
	)
	(segment
		(start 178.574954 -111.192818)
		(end 186.125612 -114.863118)
		(width 0.1143)
		(layer "In9.Cu")
		(net "UPI_CPU0_CPU1_P0P0_DN<9>")
	)
	(segment
		(start 314.364624 -76.137008)
		(end 314.35802 -75.908154)
		(width 0.1143)
		(layer "In9.Cu")
		(net "UPI_CPU0_CPU1_P0P0_DN<9>")
	)
	(segment
		(start 143.416528 -68.892928)
		(end 143.641572 -68.892928)
		(width 0.0889)
		(layer "In9.Cu")
		(net "UPI_CPU0_CPU1_P0P0_DN<9>")
	)
	(arc
		(start 141.451584 -67.991736)
		(mid 141.658697 -67.780806)
		(end 141.942058 -67.696588)
		(width 0.0889)
		(layer "In9.Cu")
		(net "UPI_CPU0_CPU1_P0P0_DN<9>")
	)
	(arc
		(start 139.40282 -68.191634)
		(mid 139.594462 -68.134468)
		(end 139.734544 -67.991736)
		(width 0.0889)
		(layer "In9.Cu")
		(net "UPI_CPU0_CPU1_P0P0_DN<9>")
	)
	(arc
		(start 136.833864 -66.705988)
		(mid 137.117081 -66.790269)
		(end 137.324084 -67.001136)
		(width 0.0889)
		(layer "In9.Cu")
		(net "UPI_CPU0_CPU1_P0P0_DN<9>")
	)
	(arc
		(start 138.550904 -67.696588)
		(mid 138.834121 -67.780869)
		(end 139.041124 -67.991736)
		(width 0.0889)
		(layer "In9.Cu")
		(net "UPI_CPU0_CPU1_P0P0_DN<9>")
	)
	(arc
		(start 139.041124 -67.991736)
		(mid 139.181203 -68.134472)
		(end 139.372848 -68.191634)
		(width 0.0889)
		(layer "In9.Cu")
		(net "UPI_CPU0_CPU1_P0P0_DN<9>")
	)
	(arc
		(start 138.182604 -67.496436)
		(mid 138.324287 -67.64024)
		(end 138.518138 -67.696588)
		(width 0.0889)
		(layer "In9.Cu")
		(net "UPI_CPU0_CPU1_P0P0_DN<9>")
	)
	(arc
		(start 139.734544 -67.991736)
		(mid 139.941548 -67.780872)
		(end 140.224764 -67.696588)
		(width 0.0889)
		(layer "In9.Cu")
		(net "UPI_CPU0_CPU1_P0P0_DN<9>")
	)
	(arc
		(start 140.267944 -67.696588)
		(mid 140.551161 -67.780869)
		(end 140.758164 -67.991736)
		(width 0.0889)
		(layer "In9.Cu")
		(net "UPI_CPU0_CPU1_P0P0_DN<9>")
	)
	(arc
		(start 137.324084 -67.001136)
		(mid 137.464163 -67.143872)
		(end 137.655808 -67.201034)
		(width 0.0889)
		(layer "In9.Cu")
		(net "UPI_CPU0_CPU1_P0P0_DN<9>")
	)
	(arc
		(start 136.498076 -66.553588)
		(mid 136.632638 -66.6635)
		(end 136.801098 -66.705988)
		(width 0.0889)
		(layer "In9.Cu")
		(net "UPI_CPU0_CPU1_P0P0_DN<9>")
	)
	(arc
		(start 137.688574 -67.201034)
		(mid 137.973998 -67.284501)
		(end 138.182604 -67.496436)
		(width 0.0889)
		(layer "In9.Cu")
		(net "UPI_CPU0_CPU1_P0P0_DN<9>")
	)
	(arc
		(start 141.11986 -68.191634)
		(mid 141.311502 -68.134468)
		(end 141.451584 -67.991736)
		(width 0.0889)
		(layer "In9.Cu")
		(net "UPI_CPU0_CPU1_P0P0_DN<9>")
	)
	(arc
		(start 140.758164 -67.991736)
		(mid 140.898243 -68.134472)
		(end 141.089888 -68.191634)
		(width 0.0889)
		(layer "In9.Cu")
		(net "UPI_CPU0_CPU1_P0P0_DN<9>")
	)
	(segment
		(start 137.099294 -66.800984)
		(end 137.670794 -66.800984)
		(width 0.1143)
		(layer "F.Cu")
		(net "UPI_CPU0_CPU1_P0P0_DN<8>")
	)
	(segment
		(start 304.675286 -67.296538)
		(end 305.246786 -67.296538)
		(width 0.1143)
		(layer "F.Cu")
		(net "UPI_CPU0_CPU1_P0P0_DN<8>")
	)
	(via
		(at 305.246786 -67.296538)
		(size 0.508)
		(drill 0.254)
		(layers "F.Cu" "B.Cu")
		(net "UPI_CPU0_CPU1_P0P0_DN<8>")
	)
	(via
		(at 137.670794 -66.800984)
		(size 0.508)
		(drill 0.254)
		(layers "F.Cu" "B.Cu")
		(net "UPI_CPU0_CPU1_P0P0_DN<8>")
	)
	(segment
		(start 314.87364 -93.7768)
		(end 315.291978 -91.835478)
		(width 0.1143)
		(layer "In9.Cu")
		(net "UPI_CPU0_CPU1_P0P0_DN<8>")
	)
	(segment
		(start 312.442352 -70.194932)
		(end 312.441844 -70.19417)
		(width 0.1143)
		(layer "In9.Cu")
		(net "UPI_CPU0_CPU1_P0P0_DN<8>")
	)
	(segment
		(start 145.67662 -68.180966)
		(end 145.698718 -68.180966)
		(width 0.0889)
		(layer "In9.Cu")
		(net "UPI_CPU0_CPU1_P0P0_DN<8>")
	)
	(segment
		(start 312.51652 -70.329552)
		(end 312.441336 -70.197472)
		(width 0.1143)
		(layer "In9.Cu")
		(net "UPI_CPU0_CPU1_P0P0_DN<8>")
	)
	(segment
		(start 281.957526 -112.090708)
		(end 291.125402 -108.285788)
		(width 0.1143)
		(layer "In9.Cu")
		(net "UPI_CPU0_CPU1_P0P0_DN<8>")
	)
	(segment
		(start 186.384438 -114.554)
		(end 194.950334 -115.172236)
		(width 0.1143)
		(layer "In9.Cu")
		(net "UPI_CPU0_CPU1_P0P0_DN<8>")
	)
	(segment
		(start 137.670794 -66.46291)
		(end 137.728706 -66.404998)
		(width 0.0889)
		(layer "In9.Cu")
		(net "UPI_CPU0_CPU1_P0P0_DN<8>")
	)
	(segment
		(start 151.872696 -74.581004)
		(end 155.325572 -87.3125)
		(width 0.1143)
		(layer "In9.Cu")
		(net "UPI_CPU0_CPU1_P0P0_DN<8>")
	)
	(segment
		(start 310.695594 -68.243196)
		(end 309.114698 -66.6623)
		(width 0.0889)
		(layer "In9.Cu")
		(net "UPI_CPU0_CPU1_P0P0_DN<8>")
	)
	(segment
		(start 310.76773 -68.243196)
		(end 310.695594 -68.243196)
		(width 0.0889)
		(layer "In9.Cu")
		(net "UPI_CPU0_CPU1_P0P0_DN<8>")
	)
	(segment
		(start 141.8336 -66.8528)
		(end 144.05356 -66.8528)
		(width 0.0889)
		(layer "In9.Cu")
		(net "UPI_CPU0_CPU1_P0P0_DN<8>")
	)
	(segment
		(start 311.070752 -68.546218)
		(end 310.783224 -68.25869)
		(width 0.1143)
		(layer "In9.Cu")
		(net "UPI_CPU0_CPU1_P0P0_DN<8>")
	)
	(segment
		(start 144.05356 -66.8528)
		(end 145.330926 -68.130166)
		(width 0.0889)
		(layer "In9.Cu")
		(net "UPI_CPU0_CPU1_P0P0_DN<8>")
	)
	(segment
		(start 306.50053 -66.916808)
		(end 306.452016 -67.001136)
		(width 0.0889)
		(layer "In9.Cu")
		(net "UPI_CPU0_CPU1_P0P0_DN<8>")
	)
	(segment
		(start 141.083284 -67.391534)
		(end 141.126464 -67.391534)
		(width 0.0889)
		(layer "In9.Cu")
		(net "UPI_CPU0_CPU1_P0P0_DN<8>")
	)
	(segment
		(start 292.209982 -108.114084)
		(end 302.856138 -110.8329)
		(width 0.1143)
		(layer "In9.Cu")
		(net "UPI_CPU0_CPU1_P0P0_DN<8>")
	)
	(segment
		(start 145.936208 -68.180966)
		(end 147.935442 -69.34962)
		(width 0.1143)
		(layer "In9.Cu")
		(net "UPI_CPU0_CPU1_P0P0_DN<8>")
	)
	(segment
		(start 147.935442 -69.34962)
		(end 151.872696 -74.581004)
		(width 0.1143)
		(layer "In9.Cu")
		(net "UPI_CPU0_CPU1_P0P0_DN<8>")
	)
	(segment
		(start 313.831478 -74.899266)
		(end 312.51652 -70.329552)
		(width 0.1143)
		(layer "In9.Cu")
		(net "UPI_CPU0_CPU1_P0P0_DN<8>")
	)
	(segment
		(start 309.114698 -66.6623)
		(end 306.755292 -66.6623)
		(width 0.0889)
		(layer "In9.Cu")
		(net "UPI_CPU0_CPU1_P0P0_DN<8>")
	)
	(segment
		(start 258.354322 -112.255554)
		(end 267.158216 -112.68837)
		(width 0.1143)
		(layer "In9.Cu")
		(net "UPI_CPU0_CPU1_P0P0_DN<8>")
	)
	(segment
		(start 140.231368 -66.896488)
		(end 140.26134 -66.896488)
		(width 0.0889)
		(layer "In9.Cu")
		(net "UPI_CPU0_CPU1_P0P0_DN<8>")
	)
	(segment
		(start 313.97702 -80.161384)
		(end 313.967876 -79.8322)
		(width 0.1143)
		(layer "In9.Cu")
		(net "UPI_CPU0_CPU1_P0P0_DN<8>")
	)
	(segment
		(start 312.441336 -70.197472)
		(end 312.442352 -70.194932)
		(width 0.1143)
		(layer "In9.Cu")
		(net "UPI_CPU0_CPU1_P0P0_DN<8>")
	)
	(segment
		(start 162.323018 -99.066096)
		(end 169.031158 -105.598214)
		(width 0.1143)
		(layer "In9.Cu")
		(net "UPI_CPU0_CPU1_P0P0_DN<8>")
	)
	(segment
		(start 316.422024 -86.59241)
		(end 313.97702 -80.161384)
		(width 0.1143)
		(layer "In9.Cu")
		(net "UPI_CPU0_CPU1_P0P0_DN<8>")
	)
	(segment
		(start 138.511534 -66.896488)
		(end 138.5443 -66.896488)
		(width 0.0889)
		(layer "In9.Cu")
		(net "UPI_CPU0_CPU1_P0P0_DN<8>")
	)
	(segment
		(start 291.125402 -108.285788)
		(end 291.35197 -108.191808)
		(width 0.1143)
		(layer "In9.Cu")
		(net "UPI_CPU0_CPU1_P0P0_DN<8>")
	)
	(segment
		(start 313.967876 -79.8322)
		(end 313.897518 -77.285342)
		(width 0.1143)
		(layer "In9.Cu")
		(net "UPI_CPU0_CPU1_P0P0_DN<8>")
	)
	(segment
		(start 227.94976 -111.316008)
		(end 247.912636 -114.714274)
		(width 0.1143)
		(layer "In9.Cu")
		(net "UPI_CPU0_CPU1_P0P0_DN<8>")
	)
	(segment
		(start 310.783224 -68.25869)
		(end 310.76773 -68.243196)
		(width 0.0889)
		(layer "In9.Cu")
		(net "UPI_CPU0_CPU1_P0P0_DN<8>")
	)
	(segment
		(start 291.35197 -108.191808)
		(end 292.209982 -108.114084)
		(width 0.1143)
		(layer "In9.Cu")
		(net "UPI_CPU0_CPU1_P0P0_DN<8>")
	)
	(segment
		(start 247.912636 -114.714274)
		(end 258.354322 -112.255554)
		(width 0.1143)
		(layer "In9.Cu")
		(net "UPI_CPU0_CPU1_P0P0_DN<8>")
	)
	(segment
		(start 178.605942 -110.626144)
		(end 186.384438 -114.554)
		(width 0.1143)
		(layer "In9.Cu")
		(net "UPI_CPU0_CPU1_P0P0_DN<8>")
	)
	(segment
		(start 169.031158 -105.598214)
		(end 175.320706 -107.79252)
		(width 0.1143)
		(layer "In9.Cu")
		(net "UPI_CPU0_CPU1_P0P0_DN<8>")
	)
	(segment
		(start 141.654022 -67.032378)
		(end 141.8336 -66.8528)
		(width 0.0889)
		(layer "In9.Cu")
		(net "UPI_CPU0_CPU1_P0P0_DN<8>")
	)
	(segment
		(start 278.072088 -111.640366)
		(end 281.957526 -112.090708)
		(width 0.1143)
		(layer "In9.Cu")
		(net "UPI_CPU0_CPU1_P0P0_DN<8>")
	)
	(segment
		(start 314.627768 -94.917768)
		(end 314.87364 -93.7768)
		(width 0.1143)
		(layer "In9.Cu")
		(net "UPI_CPU0_CPU1_P0P0_DN<8>")
	)
	(segment
		(start 175.320706 -107.79252)
		(end 178.605942 -110.626144)
		(width 0.1143)
		(layer "In9.Cu")
		(net "UPI_CPU0_CPU1_P0P0_DN<8>")
	)
	(segment
		(start 155.325572 -87.3125)
		(end 161.66592 -94.816168)
		(width 0.1143)
		(layer "In9.Cu")
		(net "UPI_CPU0_CPU1_P0P0_DN<8>")
	)
	(segment
		(start 306.755292 -66.6623)
		(end 306.50053 -66.916808)
		(width 0.0889)
		(layer "In9.Cu")
		(net "UPI_CPU0_CPU1_P0P0_DN<8>")
	)
	(segment
		(start 302.856646 -110.833662)
		(end 307.598826 -109.753654)
		(width 0.1143)
		(layer "In9.Cu")
		(net "UPI_CPU0_CPU1_P0P0_DN<8>")
	)
	(segment
		(start 307.598826 -109.753654)
		(end 312.382916 -105.33253)
		(width 0.1143)
		(layer "In9.Cu")
		(net "UPI_CPU0_CPU1_P0P0_DN<8>")
	)
	(segment
		(start 197.00875 -115.038632)
		(end 227.94976 -111.316008)
		(width 0.1143)
		(layer "In9.Cu")
		(net "UPI_CPU0_CPU1_P0P0_DN<8>")
	)
	(segment
		(start 306.122832 -67.201034)
		(end 305.477418 -67.201034)
		(width 0.0889)
		(layer "In9.Cu")
		(net "UPI_CPU0_CPU1_P0P0_DN<8>")
	)
	(segment
		(start 161.66592 -94.816168)
		(end 162.323018 -99.066096)
		(width 0.1143)
		(layer "In9.Cu")
		(net "UPI_CPU0_CPU1_P0P0_DN<8>")
	)
	(segment
		(start 194.950334 -115.172236)
		(end 197.00875 -115.038632)
		(width 0.1143)
		(layer "In9.Cu")
		(net "UPI_CPU0_CPU1_P0P0_DN<8>")
	)
	(segment
		(start 267.158216 -112.68837)
		(end 278.072088 -111.640366)
		(width 0.1143)
		(layer "In9.Cu")
		(net "UPI_CPU0_CPU1_P0P0_DN<8>")
	)
	(segment
		(start 141.616684 -67.096386)
		(end 141.654022 -67.032378)
		(width 0.0889)
		(layer "In9.Cu")
		(net "UPI_CPU0_CPU1_P0P0_DN<8>")
	)
	(segment
		(start 313.897518 -77.285342)
		(end 313.831478 -74.899266)
		(width 0.1143)
		(layer "In9.Cu")
		(net "UPI_CPU0_CPU1_P0P0_DN<8>")
	)
	(segment
		(start 302.856138 -110.8329)
		(end 302.856646 -110.833662)
		(width 0.1143)
		(layer "In9.Cu")
		(net "UPI_CPU0_CPU1_P0P0_DN<8>")
	)
	(segment
		(start 315.291978 -91.835478)
		(end 316.422024 -86.59241)
		(width 0.1143)
		(layer "In9.Cu")
		(net "UPI_CPU0_CPU1_P0P0_DN<8>")
	)
	(segment
		(start 145.698718 -68.180966)
		(end 145.936208 -68.180966)
		(width 0.1143)
		(layer "In9.Cu")
		(net "UPI_CPU0_CPU1_P0P0_DN<8>")
	)
	(segment
		(start 145.62582 -68.130166)
		(end 145.67662 -68.180966)
		(width 0.0889)
		(layer "In9.Cu")
		(net "UPI_CPU0_CPU1_P0P0_DN<8>")
	)
	(segment
		(start 137.670794 -66.800984)
		(end 137.670794 -66.46291)
		(width 0.0889)
		(layer "In9.Cu")
		(net "UPI_CPU0_CPU1_P0P0_DN<8>")
	)
	(segment
		(start 312.441844 -70.19417)
		(end 311.070752 -68.546218)
		(width 0.1143)
		(layer "In9.Cu")
		(net "UPI_CPU0_CPU1_P0P0_DN<8>")
	)
	(segment
		(start 145.330926 -68.130166)
		(end 145.62582 -68.130166)
		(width 0.0889)
		(layer "In9.Cu")
		(net "UPI_CPU0_CPU1_P0P0_DN<8>")
	)
	(segment
		(start 139.366244 -67.391534)
		(end 139.409424 -67.391534)
		(width 0.0889)
		(layer "In9.Cu")
		(net "UPI_CPU0_CPU1_P0P0_DN<8>")
	)
	(segment
		(start 312.382916 -105.33253)
		(end 314.627768 -94.917768)
		(width 0.1143)
		(layer "In9.Cu")
		(net "UPI_CPU0_CPU1_P0P0_DN<8>")
	)
	(arc
		(start 140.593064 -67.096386)
		(mid 140.800068 -67.30725)
		(end 141.083284 -67.391534)
		(width 0.0889)
		(layer "In9.Cu")
		(net "UPI_CPU0_CPU1_P0P0_DN<8>")
	)
	(arc
		(start 137.728706 -66.404998)
		(mid 137.895607 -66.469898)
		(end 138.017504 -66.601086)
		(width 0.0889)
		(layer "In9.Cu")
		(net "UPI_CPU0_CPU1_P0P0_DN<8>")
	)
	(arc
		(start 305.477418 -67.201034)
		(mid 305.352611 -67.22586)
		(end 305.246786 -67.296538)
		(width 0.0889)
		(layer "In9.Cu")
		(net "UPI_CPU0_CPU1_P0P0_DN<8>")
	)
	(arc
		(start 139.409424 -67.391534)
		(mid 139.692641 -67.307253)
		(end 139.899644 -67.096386)
		(width 0.0889)
		(layer "In9.Cu")
		(net "UPI_CPU0_CPU1_P0P0_DN<8>")
	)
	(arc
		(start 138.017504 -66.601086)
		(mid 138.226112 -66.813018)
		(end 138.511534 -66.896488)
		(width 0.0889)
		(layer "In9.Cu")
		(net "UPI_CPU0_CPU1_P0P0_DN<8>")
	)
	(arc
		(start 140.26134 -66.896488)
		(mid 140.452982 -66.953654)
		(end 140.593064 -67.096386)
		(width 0.0889)
		(layer "In9.Cu")
		(net "UPI_CPU0_CPU1_P0P0_DN<8>")
	)
	(arc
		(start 138.876024 -67.096386)
		(mid 139.083028 -67.30725)
		(end 139.366244 -67.391534)
		(width 0.0889)
		(layer "In9.Cu")
		(net "UPI_CPU0_CPU1_P0P0_DN<8>")
	)
	(arc
		(start 141.126464 -67.391534)
		(mid 141.409681 -67.307253)
		(end 141.616684 -67.096386)
		(width 0.0889)
		(layer "In9.Cu")
		(net "UPI_CPU0_CPU1_P0P0_DN<8>")
	)
	(arc
		(start 138.5443 -66.896488)
		(mid 138.735942 -66.953654)
		(end 138.876024 -67.096386)
		(width 0.0889)
		(layer "In9.Cu")
		(net "UPI_CPU0_CPU1_P0P0_DN<8>")
	)
	(arc
		(start 306.452016 -67.001136)
		(mid 306.313023 -67.143216)
		(end 306.122832 -67.201034)
		(width 0.0889)
		(layer "In9.Cu")
		(net "UPI_CPU0_CPU1_P0P0_DN<8>")
	)
	(arc
		(start 139.899644 -67.096386)
		(mid 140.039723 -66.95365)
		(end 140.231368 -66.896488)
		(width 0.0889)
		(layer "In9.Cu")
		(net "UPI_CPU0_CPU1_P0P0_DN<8>")
	)
	(segment
		(start 307.614066 -68.382134)
		(end 308.1401 -67.8561)
		(width 0.0889)
		(layer "F.Cu")
		(net "UPI_CPU0_CPU1_P0P0_DN<7>")
	)
	(segment
		(start 308.693566 -67.8561)
		(end 308.923436 -68.08597)
		(width 0.0889)
		(layer "F.Cu")
		(net "UPI_CPU0_CPU1_P0P0_DN<7>")
	)
	(segment
		(start 307.438552 -68.382134)
		(end 307.614066 -68.382134)
		(width 0.0889)
		(layer "F.Cu")
		(net "UPI_CPU0_CPU1_P0P0_DN<7>")
	)
	(segment
		(start 138.816334 -65.810384)
		(end 139.387834 -65.810384)
		(width 0.1143)
		(layer "F.Cu")
		(net "UPI_CPU0_CPU1_P0P0_DN<7>")
	)
	(segment
		(start 308.1401 -67.8561)
		(end 308.693566 -67.8561)
		(width 0.0889)
		(layer "F.Cu")
		(net "UPI_CPU0_CPU1_P0P0_DN<7>")
	)
	(segment
		(start 307.250846 -68.56984)
		(end 307.438552 -68.382134)
		(width 0.0889)
		(layer "F.Cu")
		(net "UPI_CPU0_CPU1_P0P0_DN<7>")
	)
	(segment
		(start 307.250846 -68.782184)
		(end 307.250846 -68.56984)
		(width 0.0889)
		(layer "F.Cu")
		(net "UPI_CPU0_CPU1_P0P0_DN<7>")
	)
	(via
		(at 139.387834 -65.810384)
		(size 0.508)
		(drill 0.254)
		(layers "F.Cu" "B.Cu")
		(net "UPI_CPU0_CPU1_P0P0_DN<7>")
	)
	(via
		(at 308.923436 -68.08597)
		(size 0.508)
		(drill 0.254)
		(layers "F.Cu" "B.Cu")
		(net "UPI_CPU0_CPU1_P0P0_DN<7>")
	)
	(segment
		(start 310.05272 -69.364352)
		(end 310.05272 -69.292216)
		(width 0.0889)
		(layer "In9.Cu")
		(net "UPI_CPU0_CPU1_P0P0_DN<7>")
	)
	(segment
		(start 311.38368 -70.695058)
		(end 310.068214 -69.379846)
		(width 0.1143)
		(layer "In9.Cu")
		(net "UPI_CPU0_CPU1_P0P0_DN<7>")
	)
	(segment
		(start 315.425836 -86.799166)
		(end 313.569096 -81.915)
		(width 0.1143)
		(layer "In9.Cu")
		(net "UPI_CPU0_CPU1_P0P0_DN<7>")
	)
	(segment
		(start 309.254398 -67.880992)
		(end 309.128414 -67.880992)
		(width 0.0889)
		(layer "In9.Cu")
		(net "UPI_CPU0_CPU1_P0P0_DN<7>")
	)
	(segment
		(start 309.48249 -68.173346)
		(end 309.482998 -68.109592)
		(width 0.0889)
		(layer "In9.Cu")
		(net "UPI_CPU0_CPU1_P0P0_DN<7>")
	)
	(segment
		(start 142.028672 -65.946528)
		(end 142.445486 -66.0654)
		(width 0.0889)
		(layer "In9.Cu")
		(net "UPI_CPU0_CPU1_P0P0_DN<7>")
	)
	(segment
		(start 145.847308 -67.2592)
		(end 145.898108 -67.2084)
		(width 0.0889)
		(layer "In9.Cu")
		(net "UPI_CPU0_CPU1_P0P0_DN<7>")
	)
	(segment
		(start 309.798974 -68.657216)
		(end 309.84444 -68.61175)
		(width 0.0889)
		(layer "In9.Cu")
		(net "UPI_CPU0_CPU1_P0P0_DN<7>")
	)
	(segment
		(start 144.453356 -66.155062)
		(end 144.54632 -66.155062)
		(width 0.0889)
		(layer "In9.Cu")
		(net "UPI_CPU0_CPU1_P0P0_DN<7>")
	)
	(segment
		(start 141.087094 -65.219834)
		(end 141.122654 -65.219834)
		(width 0.0889)
		(layer "In9.Cu")
		(net "UPI_CPU0_CPU1_P0P0_DN<7>")
	)
	(segment
		(start 145.010378 -66.712084)
		(end 145.557494 -67.2592)
		(width 0.0889)
		(layer "In9.Cu")
		(net "UPI_CPU0_CPU1_P0P0_DN<7>")
	)
	(segment
		(start 309.84444 -68.971414)
		(end 309.798974 -68.925948)
		(width 0.0889)
		(layer "In9.Cu")
		(net "UPI_CPU0_CPU1_P0P0_DN<7>")
	)
	(segment
		(start 176.074324 -107.070398)
		(end 178.363626 -109.045502)
		(width 0.1143)
		(layer "In9.Cu")
		(net "UPI_CPU0_CPU1_P0P0_DN<7>")
	)
	(segment
		(start 144.869916 -66.478404)
		(end 145.010378 -66.618866)
		(width 0.0889)
		(layer "In9.Cu")
		(net "UPI_CPU0_CPU1_P0P0_DN<7>")
	)
	(segment
		(start 309.753254 -68.702682)
		(end 309.79872 -68.657216)
		(width 0.0889)
		(layer "In9.Cu")
		(net "UPI_CPU0_CPU1_P0P0_DN<7>")
	)
	(segment
		(start 146.239484 -67.2084)
		(end 148.46046 -68.143374)
		(width 0.1143)
		(layer "In9.Cu")
		(net "UPI_CPU0_CPU1_P0P0_DN<7>")
	)
	(segment
		(start 312.840878 -78.594458)
		(end 312.834274 -78.365858)
		(width 0.1143)
		(layer "In9.Cu")
		(net "UPI_CPU0_CPU1_P0P0_DN<7>")
	)
	(segment
		(start 313.569096 -81.915)
		(end 312.88355 -80.112108)
		(width 0.1143)
		(layer "In9.Cu")
		(net "UPI_CPU0_CPU1_P0P0_DN<7>")
	)
	(segment
		(start 148.46046 -68.143374)
		(end 152.572212 -73.607168)
		(width 0.1143)
		(layer "In9.Cu")
		(net "UPI_CPU0_CPU1_P0P0_DN<7>")
	)
	(segment
		(start 145.898108 -67.2084)
		(end 145.920206 -67.2084)
		(width 0.0889)
		(layer "In9.Cu")
		(net "UPI_CPU0_CPU1_P0P0_DN<7>")
	)
	(segment
		(start 312.71845 -78.959456)
		(end 312.711846 -78.730348)
		(width 0.1143)
		(layer "In9.Cu")
		(net "UPI_CPU0_CPU1_P0P0_DN<7>")
	)
	(segment
		(start 291.125402 -107.27944)
		(end 291.12718 -107.278678)
		(width 0.1143)
		(layer "In9.Cu")
		(net "UPI_CPU0_CPU1_P0P0_DN<7>")
	)
	(segment
		(start 302.869854 -109.877098)
		(end 307.150516 -108.902246)
		(width 0.1143)
		(layer "In9.Cu")
		(net "UPI_CPU0_CPU1_P0P0_DN<7>")
	)
	(segment
		(start 278.081232 -110.705138)
		(end 281.823414 -111.13897)
		(width 0.1143)
		(layer "In9.Cu")
		(net "UPI_CPU0_CPU1_P0P0_DN<7>")
	)
	(segment
		(start 312.854594 -79.088234)
		(end 312.71845 -78.959456)
		(width 0.1143)
		(layer "In9.Cu")
		(net "UPI_CPU0_CPU1_P0P0_DN<7>")
	)
	(segment
		(start 162.544506 -94.414594)
		(end 163.172902 -98.480118)
		(width 0.1143)
		(layer "In9.Cu")
		(net "UPI_CPU0_CPU1_P0P0_DN<7>")
	)
	(segment
		(start 312.759852 -75.704954)
		(end 312.740294 -74.932794)
		(width 0.1143)
		(layer "In9.Cu")
		(net "UPI_CPU0_CPU1_P0P0_DN<7>")
	)
	(segment
		(start 309.608474 -68.36283)
		(end 309.48249 -68.236846)
		(width 0.0889)
		(layer "In9.Cu")
		(net "UPI_CPU0_CPU1_P0P0_DN<7>")
	)
	(segment
		(start 227.898198 -110.364016)
		(end 233.68127 -111.34852)
		(width 0.1143)
		(layer "In9.Cu")
		(net "UPI_CPU0_CPU1_P0P0_DN<7>")
	)
	(segment
		(start 312.65749 -76.792328)
		(end 312.650886 -76.56322)
		(width 0.1143)
		(layer "In9.Cu")
		(net "UPI_CPU0_CPU1_P0P0_DN<7>")
	)
	(segment
		(start 312.820558 -77.872082)
		(end 312.813954 -77.643482)
		(width 0.1143)
		(layer "In9.Cu")
		(net "UPI_CPU0_CPU1_P0P0_DN<7>")
	)
	(segment
		(start 144.363694 -66.0654)
		(end 144.453356 -66.155062)
		(width 0.0889)
		(layer "In9.Cu")
		(net "UPI_CPU0_CPU1_P0P0_DN<7>")
	)
	(segment
		(start 309.798974 -68.925948)
		(end 309.79872 -68.925948)
		(width 0.0889)
		(layer "In9.Cu")
		(net "UPI_CPU0_CPU1_P0P0_DN<7>")
	)
	(segment
		(start 309.84444 -68.61175)
		(end 309.84444 -68.471034)
		(width 0.0889)
		(layer "In9.Cu")
		(net "UPI_CPU0_CPU1_P0P0_DN<7>")
	)
	(segment
		(start 312.773314 -76.19873)
		(end 312.63717 -76.069952)
		(width 0.1143)
		(layer "In9.Cu")
		(net "UPI_CPU0_CPU1_P0P0_DN<7>")
	)
	(segment
		(start 312.813954 -77.643482)
		(end 312.67781 -77.514704)
		(width 0.1143)
		(layer "In9.Cu")
		(net "UPI_CPU0_CPU1_P0P0_DN<7>")
	)
	(segment
		(start 312.711846 -78.730348)
		(end 312.840878 -78.594458)
		(width 0.1143)
		(layer "In9.Cu")
		(net "UPI_CPU0_CPU1_P0P0_DN<7>")
	)
	(segment
		(start 140.224764 -65.715388)
		(end 140.25753 -65.715388)
		(width 0.0889)
		(layer "In9.Cu")
		(net "UPI_CPU0_CPU1_P0P0_DN<7>")
	)
	(segment
		(start 312.740294 -74.932794)
		(end 311.38368 -70.695058)
		(width 0.1143)
		(layer "In9.Cu")
		(net "UPI_CPU0_CPU1_P0P0_DN<7>")
	)
	(segment
		(start 248.009664 -108.499402)
		(end 262.761984 -111.541306)
		(width 0.1143)
		(layer "In9.Cu")
		(net "UPI_CPU0_CPU1_P0P0_DN<7>")
	)
	(segment
		(start 312.88355 -80.112108)
		(end 312.875422 -79.8322)
		(width 0.1143)
		(layer "In9.Cu")
		(net "UPI_CPU0_CPU1_P0P0_DN<7>")
	)
	(segment
		(start 312.800238 -77.149706)
		(end 312.793634 -76.921106)
		(width 0.1143)
		(layer "In9.Cu")
		(net "UPI_CPU0_CPU1_P0P0_DN<7>")
	)
	(segment
		(start 310.05272 -69.292216)
		(end 309.84444 -69.083936)
		(width 0.0889)
		(layer "In9.Cu")
		(net "UPI_CPU0_CPU1_P0P0_DN<7>")
	)
	(segment
		(start 309.79872 -68.925948)
		(end 309.753254 -68.880482)
		(width 0.0889)
		(layer "In9.Cu")
		(net "UPI_CPU0_CPU1_P0P0_DN<7>")
	)
	(segment
		(start 309.736236 -68.36283)
		(end 309.608474 -68.36283)
		(width 0.0889)
		(layer "In9.Cu")
		(net "UPI_CPU0_CPU1_P0P0_DN<7>")
	)
	(segment
		(start 190.852806 -113.601754)
		(end 196.08419 -114.211862)
		(width 0.1143)
		(layer "In9.Cu")
		(net "UPI_CPU0_CPU1_P0P0_DN<7>")
	)
	(segment
		(start 141.680438 -65.598294)
		(end 142.028672 -65.946528)
		(width 0.0889)
		(layer "In9.Cu")
		(net "UPI_CPU0_CPU1_P0P0_DN<7>")
	)
	(segment
		(start 163.172902 -98.480118)
		(end 169.673016 -104.837484)
		(width 0.1143)
		(layer "In9.Cu")
		(net "UPI_CPU0_CPU1_P0P0_DN<7>")
	)
	(segment
		(start 139.372848 -66.210434)
		(end 139.40282 -66.210434)
		(width 0.0889)
		(layer "In9.Cu")
		(net "UPI_CPU0_CPU1_P0P0_DN<7>")
	)
	(segment
		(start 309.79872 -68.657216)
		(end 309.798974 -68.657216)
		(width 0.0889)
		(layer "In9.Cu")
		(net "UPI_CPU0_CPU1_P0P0_DN<7>")
	)
	(segment
		(start 309.482998 -68.109592)
		(end 309.254398 -67.880992)
		(width 0.0889)
		(layer "In9.Cu")
		(net "UPI_CPU0_CPU1_P0P0_DN<7>")
	)
	(segment
		(start 312.650886 -76.56322)
		(end 312.779918 -76.42733)
		(width 0.1143)
		(layer "In9.Cu")
		(net "UPI_CPU0_CPU1_P0P0_DN<7>")
	)
	(segment
		(start 292.285166 -107.173522)
		(end 302.869854 -109.877098)
		(width 0.1143)
		(layer "In9.Cu")
		(net "UPI_CPU0_CPU1_P0P0_DN<7>")
	)
	(segment
		(start 311.535572 -104.849676)
		(end 313.844686 -94.134686)
		(width 0.1143)
		(layer "In9.Cu")
		(net "UPI_CPU0_CPU1_P0P0_DN<7>")
	)
	(segment
		(start 309.753254 -68.880482)
		(end 309.753254 -68.702682)
		(width 0.0889)
		(layer "In9.Cu")
		(net "UPI_CPU0_CPU1_P0P0_DN<7>")
	)
	(segment
		(start 312.834274 -78.365858)
		(end 312.69813 -78.23708)
		(width 0.1143)
		(layer "In9.Cu")
		(net "UPI_CPU0_CPU1_P0P0_DN<7>")
	)
	(segment
		(start 144.776698 -66.478404)
		(end 144.869916 -66.478404)
		(width 0.0889)
		(layer "In9.Cu")
		(net "UPI_CPU0_CPU1_P0P0_DN<7>")
	)
	(segment
		(start 312.671206 -77.285596)
		(end 312.67146 -77.285342)
		(width 0.1143)
		(layer "In9.Cu")
		(net "UPI_CPU0_CPU1_P0P0_DN<7>")
	)
	(segment
		(start 313.921902 -93.7768)
		(end 314.50915 -91.05265)
		(width 0.1143)
		(layer "In9.Cu")
		(net "UPI_CPU0_CPU1_P0P0_DN<7>")
	)
	(segment
		(start 144.54632 -66.155062)
		(end 144.687036 -66.295778)
		(width 0.0889)
		(layer "In9.Cu")
		(net "UPI_CPU0_CPU1_P0P0_DN<7>")
	)
	(segment
		(start 156.169868 -86.870794)
		(end 162.544506 -94.414594)
		(width 0.1143)
		(layer "In9.Cu")
		(net "UPI_CPU0_CPU1_P0P0_DN<7>")
	)
	(segment
		(start 309.84444 -69.083936)
		(end 309.84444 -68.971414)
		(width 0.0889)
		(layer "In9.Cu")
		(net "UPI_CPU0_CPU1_P0P0_DN<7>")
	)
	(segment
		(start 145.920206 -67.2084)
		(end 146.239484 -67.2084)
		(width 0.1143)
		(layer "In9.Cu")
		(net "UPI_CPU0_CPU1_P0P0_DN<7>")
	)
	(segment
		(start 312.874914 -79.81061)
		(end 312.73877 -79.681832)
		(width 0.1143)
		(layer "In9.Cu")
		(net "UPI_CPU0_CPU1_P0P0_DN<7>")
	)
	(segment
		(start 312.67781 -77.514704)
		(end 312.671206 -77.285596)
		(width 0.1143)
		(layer "In9.Cu")
		(net "UPI_CPU0_CPU1_P0P0_DN<7>")
	)
	(segment
		(start 144.687036 -66.388742)
		(end 144.776698 -66.478404)
		(width 0.0889)
		(layer "In9.Cu")
		(net "UPI_CPU0_CPU1_P0P0_DN<7>")
	)
	(segment
		(start 309.48249 -68.236846)
		(end 309.48249 -68.173346)
		(width 0.0889)
		(layer "In9.Cu")
		(net "UPI_CPU0_CPU1_P0P0_DN<7>")
	)
	(segment
		(start 310.068214 -69.379846)
		(end 310.05272 -69.364352)
		(width 0.0889)
		(layer "In9.Cu")
		(net "UPI_CPU0_CPU1_P0P0_DN<7>")
	)
	(segment
		(start 312.793634 -76.921106)
		(end 312.65749 -76.792328)
		(width 0.1143)
		(layer "In9.Cu")
		(net "UPI_CPU0_CPU1_P0P0_DN<7>")
	)
	(segment
		(start 196.08419 -114.211862)
		(end 227.898198 -110.364016)
		(width 0.1143)
		(layer "In9.Cu")
		(net "UPI_CPU0_CPU1_P0P0_DN<7>")
	)
	(segment
		(start 314.50915 -91.05265)
		(end 315.425836 -86.799166)
		(width 0.1143)
		(layer "In9.Cu")
		(net "UPI_CPU0_CPU1_P0P0_DN<7>")
	)
	(segment
		(start 267.136372 -111.75619)
		(end 278.081232 -110.705138)
		(width 0.1143)
		(layer "In9.Cu")
		(net "UPI_CPU0_CPU1_P0P0_DN<7>")
	)
	(segment
		(start 313.844686 -94.134686)
		(end 313.921902 -93.7768)
		(width 0.1143)
		(layer "In9.Cu")
		(net "UPI_CPU0_CPU1_P0P0_DN<7>")
	)
	(segment
		(start 312.63717 -76.069952)
		(end 312.630566 -75.840844)
		(width 0.1143)
		(layer "In9.Cu")
		(net "UPI_CPU0_CPU1_P0P0_DN<7>")
	)
	(segment
		(start 312.67146 -77.285342)
		(end 312.800238 -77.149706)
		(width 0.1143)
		(layer "In9.Cu")
		(net "UPI_CPU0_CPU1_P0P0_DN<7>")
	)
	(segment
		(start 233.68127 -111.34852)
		(end 248.009664 -108.499402)
		(width 0.1143)
		(layer "In9.Cu")
		(net "UPI_CPU0_CPU1_P0P0_DN<7>")
	)
	(segment
		(start 145.010378 -66.618866)
		(end 145.010378 -66.712084)
		(width 0.0889)
		(layer "In9.Cu")
		(net "UPI_CPU0_CPU1_P0P0_DN<7>")
	)
	(segment
		(start 312.861198 -79.316834)
		(end 312.854594 -79.088234)
		(width 0.1143)
		(layer "In9.Cu")
		(net "UPI_CPU0_CPU1_P0P0_DN<7>")
	)
	(segment
		(start 312.630566 -75.840844)
		(end 312.759852 -75.704954)
		(width 0.1143)
		(layer "In9.Cu")
		(net "UPI_CPU0_CPU1_P0P0_DN<7>")
	)
	(segment
		(start 139.094718 -65.979548)
		(end 139.073636 -66.058288)
		(width 0.0889)
		(layer "In9.Cu")
		(net "UPI_CPU0_CPU1_P0P0_DN<7>")
	)
	(segment
		(start 262.761984 -111.541306)
		(end 267.136372 -111.75619)
		(width 0.1143)
		(layer "In9.Cu")
		(net "UPI_CPU0_CPU1_P0P0_DN<7>")
	)
	(segment
		(start 139.387834 -65.810384)
		(end 139.094718 -65.979548)
		(width 0.0889)
		(layer "In9.Cu")
		(net "UPI_CPU0_CPU1_P0P0_DN<7>")
	)
	(segment
		(start 152.572212 -73.607168)
		(end 156.169868 -86.870794)
		(width 0.1143)
		(layer "In9.Cu")
		(net "UPI_CPU0_CPU1_P0P0_DN<7>")
	)
	(segment
		(start 309.84444 -68.471034)
		(end 309.736236 -68.36283)
		(width 0.0889)
		(layer "In9.Cu")
		(net "UPI_CPU0_CPU1_P0P0_DN<7>")
	)
	(segment
		(start 312.732166 -79.452724)
		(end 312.861198 -79.316834)
		(width 0.1143)
		(layer "In9.Cu")
		(net "UPI_CPU0_CPU1_P0P0_DN<7>")
	)
	(segment
		(start 312.779918 -76.42733)
		(end 312.773314 -76.19873)
		(width 0.1143)
		(layer "In9.Cu")
		(net "UPI_CPU0_CPU1_P0P0_DN<7>")
	)
	(segment
		(start 291.12718 -107.278678)
		(end 292.285166 -107.173522)
		(width 0.1143)
		(layer "In9.Cu")
		(net "UPI_CPU0_CPU1_P0P0_DN<7>")
	)
	(segment
		(start 312.691526 -78.007972)
		(end 312.820558 -77.872082)
		(width 0.1143)
		(layer "In9.Cu")
		(net "UPI_CPU0_CPU1_P0P0_DN<7>")
	)
	(segment
		(start 312.73877 -79.681832)
		(end 312.732166 -79.452724)
		(width 0.1143)
		(layer "In9.Cu")
		(net "UPI_CPU0_CPU1_P0P0_DN<7>")
	)
	(segment
		(start 307.150516 -108.902246)
		(end 311.535572 -104.849676)
		(width 0.1143)
		(layer "In9.Cu")
		(net "UPI_CPU0_CPU1_P0P0_DN<7>")
	)
	(segment
		(start 178.363626 -109.045502)
		(end 190.232284 -113.37544)
		(width 0.1143)
		(layer "In9.Cu")
		(net "UPI_CPU0_CPU1_P0P0_DN<7>")
	)
	(segment
		(start 190.232284 -113.37544)
		(end 190.852806 -113.601754)
		(width 0.1143)
		(layer "In9.Cu")
		(net "UPI_CPU0_CPU1_P0P0_DN<7>")
	)
	(segment
		(start 281.823414 -111.13897)
		(end 291.125402 -107.27944)
		(width 0.1143)
		(layer "In9.Cu")
		(net "UPI_CPU0_CPU1_P0P0_DN<7>")
	)
	(segment
		(start 144.687036 -66.295778)
		(end 144.687036 -66.388742)
		(width 0.0889)
		(layer "In9.Cu")
		(net "UPI_CPU0_CPU1_P0P0_DN<7>")
	)
	(segment
		(start 309.128414 -67.880992)
		(end 308.923436 -68.08597)
		(width 0.0889)
		(layer "In9.Cu")
		(net "UPI_CPU0_CPU1_P0P0_DN<7>")
	)
	(segment
		(start 312.69813 -78.23708)
		(end 312.691526 -78.007972)
		(width 0.1143)
		(layer "In9.Cu")
		(net "UPI_CPU0_CPU1_P0P0_DN<7>")
	)
	(segment
		(start 312.875422 -79.8322)
		(end 312.874914 -79.81061)
		(width 0.1143)
		(layer "In9.Cu")
		(net "UPI_CPU0_CPU1_P0P0_DN<7>")
	)
	(segment
		(start 142.445486 -66.0654)
		(end 144.363694 -66.0654)
		(width 0.0889)
		(layer "In9.Cu")
		(net "UPI_CPU0_CPU1_P0P0_DN<7>")
	)
	(segment
		(start 169.673016 -104.837484)
		(end 176.074324 -107.070398)
		(width 0.1143)
		(layer "In9.Cu")
		(net "UPI_CPU0_CPU1_P0P0_DN<7>")
	)
	(segment
		(start 145.557494 -67.2592)
		(end 145.847308 -67.2592)
		(width 0.0889)
		(layer "In9.Cu")
		(net "UPI_CPU0_CPU1_P0P0_DN<7>")
	)
	(arc
		(start 141.616684 -65.515236)
		(mid 141.645835 -65.558857)
		(end 141.680438 -65.598294)
		(width 0.0889)
		(layer "In9.Cu")
		(net "UPI_CPU0_CPU1_P0P0_DN<7>")
	)
	(arc
		(start 141.122654 -65.219834)
		(mid 141.408078 -65.303301)
		(end 141.616684 -65.515236)
		(width 0.0889)
		(layer "In9.Cu")
		(net "UPI_CPU0_CPU1_P0P0_DN<7>")
	)
	(arc
		(start 140.593064 -65.515236)
		(mid 140.801672 -65.303304)
		(end 141.087094 -65.219834)
		(width 0.0889)
		(layer "In9.Cu")
		(net "UPI_CPU0_CPU1_P0P0_DN<7>")
	)
	(arc
		(start 139.40282 -66.210434)
		(mid 139.594462 -66.153268)
		(end 139.734544 -66.010536)
		(width 0.0889)
		(layer "In9.Cu")
		(net "UPI_CPU0_CPU1_P0P0_DN<7>")
	)
	(arc
		(start 139.073636 -66.058288)
		(mid 139.206517 -66.167271)
		(end 139.372848 -66.210434)
		(width 0.0889)
		(layer "In9.Cu")
		(net "UPI_CPU0_CPU1_P0P0_DN<7>")
	)
	(arc
		(start 140.25753 -65.715388)
		(mid 140.45138 -65.659038)
		(end 140.593064 -65.515236)
		(width 0.0889)
		(layer "In9.Cu")
		(net "UPI_CPU0_CPU1_P0P0_DN<7>")
	)
	(arc
		(start 139.734544 -66.010536)
		(mid 139.941548 -65.799672)
		(end 140.224764 -65.715388)
		(width 0.0889)
		(layer "In9.Cu")
		(net "UPI_CPU0_CPU1_P0P0_DN<7>")
	)
	(segment
		(start 305.533806 -68.782184)
		(end 306.105306 -68.782184)
		(width 0.1143)
		(layer "F.Cu")
		(net "UPI_CPU0_CPU1_P0P0_DN<6>")
	)
	(segment
		(start 137.099294 -64.819784)
		(end 137.670794 -64.819784)
		(width 0.1143)
		(layer "F.Cu")
		(net "UPI_CPU0_CPU1_P0P0_DN<6>")
	)
	(via
		(at 137.670794 -64.819784)
		(size 0.508)
		(drill 0.254)
		(layers "F.Cu" "B.Cu")
		(net "UPI_CPU0_CPU1_P0P0_DN<6>")
	)
	(via
		(at 306.105306 -68.782184)
		(size 0.508)
		(drill 0.254)
		(layers "F.Cu" "B.Cu")
		(net "UPI_CPU0_CPU1_P0P0_DN<6>")
	)
	(segment
		(start 292.312852 -106.824526)
		(end 302.874934 -109.521498)
		(width 0.1143)
		(layer "In9.Cu")
		(net "UPI_CPU0_CPU1_P0P0_DN<6>")
	)
	(segment
		(start 149.555962 -67.891406)
		(end 152.409906 -71.683626)
		(width 0.1143)
		(layer "In9.Cu")
		(net "UPI_CPU0_CPU1_P0P0_DN<6>")
	)
	(segment
		(start 152.409906 -71.683626)
		(end 156.484066 -86.708234)
		(width 0.1143)
		(layer "In9.Cu")
		(net "UPI_CPU0_CPU1_P0P0_DN<6>")
	)
	(segment
		(start 142.313152 -65.078864)
		(end 142.491206 -65.384934)
		(width 0.0889)
		(layer "In9.Cu")
		(net "UPI_CPU0_CPU1_P0P0_DN<6>")
	)
	(segment
		(start 142.66291 -65.556384)
		(end 145.08607 -65.556384)
		(width 0.0889)
		(layer "In9.Cu")
		(net "UPI_CPU0_CPU1_P0P0_DN<6>")
	)
	(segment
		(start 310.494172 -70.616064)
		(end 308.305454 -68.4276)
		(width 0.0889)
		(layer "In9.Cu")
		(net "UPI_CPU0_CPU1_P0P0_DN<6>")
	)
	(segment
		(start 178.309778 -108.399072)
		(end 179.261008 -108.787692)
		(width 0.1143)
		(layer "In9.Cu")
		(net "UPI_CPU0_CPU1_P0P0_DN<6>")
	)
	(segment
		(start 197.257416 -113.723674)
		(end 227.98151 -110.02772)
		(width 0.1143)
		(layer "In9.Cu")
		(net "UPI_CPU0_CPU1_P0P0_DN<6>")
	)
	(segment
		(start 162.87115 -94.266766)
		(end 163.221162 -96.530668)
		(width 0.1143)
		(layer "In9.Cu")
		(net "UPI_CPU0_CPU1_P0P0_DN<6>")
	)
	(segment
		(start 307.574442 -67.696588)
		(end 306.942236 -67.696588)
		(width 0.0889)
		(layer "In9.Cu")
		(net "UPI_CPU0_CPU1_P0P0_DN<6>")
	)
	(segment
		(start 145.494248 -65.148206)
		(end 145.728436 -65.148206)
		(width 0.0889)
		(layer "In9.Cu")
		(net "UPI_CPU0_CPU1_P0P0_DN<6>")
	)
	(segment
		(start 291.125402 -106.932222)
		(end 292.312852 -106.824526)
		(width 0.1143)
		(layer "In9.Cu")
		(net "UPI_CPU0_CPU1_P0P0_DN<6>")
	)
	(segment
		(start 145.801334 -65.199006)
		(end 146.4183 -65.199006)
		(width 0.1143)
		(layer "In9.Cu")
		(net "UPI_CPU0_CPU1_P0P0_DN<6>")
	)
	(segment
		(start 308.305454 -68.4276)
		(end 307.574442 -67.696588)
		(width 0.0889)
		(layer "In9.Cu")
		(net "UPI_CPU0_CPU1_P0P0_DN<6>")
	)
	(segment
		(start 306.209192 -68.678298)
		(end 306.105306 -68.782184)
		(width 0.0889)
		(layer "In9.Cu")
		(net "UPI_CPU0_CPU1_P0P0_DN<6>")
	)
	(segment
		(start 310.581294 -70.631558)
		(end 310.5658 -70.616064)
		(width 0.0889)
		(layer "In9.Cu")
		(net "UPI_CPU0_CPU1_P0P0_DN<6>")
	)
	(segment
		(start 262.80364 -111.19739)
		(end 267.128244 -111.409734)
		(width 0.1143)
		(layer "In9.Cu")
		(net "UPI_CPU0_CPU1_P0P0_DN<6>")
	)
	(segment
		(start 306.982622 -108.586524)
		(end 311.220612 -104.670352)
		(width 0.1143)
		(layer "In9.Cu")
		(net "UPI_CPU0_CPU1_P0P0_DN<6>")
	)
	(segment
		(start 267.128244 -111.409734)
		(end 278.084026 -110.357666)
		(width 0.1143)
		(layer "In9.Cu")
		(net "UPI_CPU0_CPU1_P0P0_DN<6>")
	)
	(segment
		(start 248.027952 -108.143548)
		(end 262.80364 -111.19739)
		(width 0.1143)
		(layer "In9.Cu")
		(net "UPI_CPU0_CPU1_P0P0_DN<6>")
	)
	(segment
		(start 179.261008 -108.787692)
		(end 184.591452 -109.94644)
		(width 0.1143)
		(layer "In9.Cu")
		(net "UPI_CPU0_CPU1_P0P0_DN<6>")
	)
	(segment
		(start 148.278596 -66.284856)
		(end 149.555962 -67.891406)
		(width 0.1143)
		(layer "In9.Cu")
		(net "UPI_CPU0_CPU1_P0P0_DN<6>")
	)
	(segment
		(start 146.4183 -65.199006)
		(end 148.278596 -66.284856)
		(width 0.1143)
		(layer "In9.Cu")
		(net "UPI_CPU0_CPU1_P0P0_DN<6>")
	)
	(segment
		(start 281.777694 -110.785656)
		(end 291.041328 -106.939842)
		(width 0.1143)
		(layer "In9.Cu")
		(net "UPI_CPU0_CPU1_P0P0_DN<6>")
	)
	(segment
		(start 310.931052 -70.981316)
		(end 310.581294 -70.631558)
		(width 0.1143)
		(layer "In9.Cu")
		(net "UPI_CPU0_CPU1_P0P0_DN<6>")
	)
	(segment
		(start 140.231368 -64.915288)
		(end 140.264134 -64.915288)
		(width 0.0889)
		(layer "In9.Cu")
		(net "UPI_CPU0_CPU1_P0P0_DN<6>")
	)
	(segment
		(start 145.08607 -65.556384)
		(end 145.494248 -65.148206)
		(width 0.0889)
		(layer "In9.Cu")
		(net "UPI_CPU0_CPU1_P0P0_DN<6>")
	)
	(segment
		(start 163.221162 -96.530668)
		(end 163.361624 -96.676972)
		(width 0.1143)
		(layer "In9.Cu")
		(net "UPI_CPU0_CPU1_P0P0_DN<6>")
	)
	(segment
		(start 312.399934 -80.022192)
		(end 312.3946 -79.8322)
		(width 0.1143)
		(layer "In9.Cu")
		(net "UPI_CPU0_CPU1_P0P0_DN<6>")
	)
	(segment
		(start 139.376658 -65.410334)
		(end 139.409424 -65.410334)
		(width 0.0889)
		(layer "In9.Cu")
		(net "UPI_CPU0_CPU1_P0P0_DN<6>")
	)
	(segment
		(start 145.779236 -65.199006)
		(end 145.801334 -65.199006)
		(width 0.0889)
		(layer "In9.Cu")
		(net "UPI_CPU0_CPU1_P0P0_DN<6>")
	)
	(segment
		(start 141.093698 -64.419734)
		(end 141.11605 -64.419734)
		(width 0.0889)
		(layer "In9.Cu")
		(net "UPI_CPU0_CPU1_P0P0_DN<6>")
	)
	(segment
		(start 142.31239 -65.07734)
		(end 142.312644 -65.078102)
		(width 0.0889)
		(layer "In9.Cu")
		(net "UPI_CPU0_CPU1_P0P0_DN<6>")
	)
	(segment
		(start 312.251344 -74.647806)
		(end 310.931052 -70.981316)
		(width 0.1143)
		(layer "In9.Cu")
		(net "UPI_CPU0_CPU1_P0P0_DN<6>")
	)
	(segment
		(start 156.634434 -86.886288)
		(end 162.87115 -94.266766)
		(width 0.1143)
		(layer "In9.Cu")
		(net "UPI_CPU0_CPU1_P0P0_DN<6>")
	)
	(segment
		(start 142.312644 -65.078102)
		(end 142.313152 -65.078864)
		(width 0.0889)
		(layer "In9.Cu")
		(net "UPI_CPU0_CPU1_P0P0_DN<6>")
	)
	(segment
		(start 302.874934 -109.521498)
		(end 306.982622 -108.586524)
		(width 0.1143)
		(layer "In9.Cu")
		(net "UPI_CPU0_CPU1_P0P0_DN<6>")
	)
	(segment
		(start 137.795 -65.236852)
		(end 138.017504 -65.610486)
		(width 0.0889)
		(layer "In9.Cu")
		(net "UPI_CPU0_CPU1_P0P0_DN<6>")
	)
	(segment
		(start 137.77722 -65.20688)
		(end 137.795 -65.236852)
		(width 0.0889)
		(layer "In9.Cu")
		(net "UPI_CPU0_CPU1_P0P0_DN<6>")
	)
	(segment
		(start 311.220612 -104.670352)
		(end 313.554364 -93.844364)
		(width 0.1143)
		(layer "In9.Cu")
		(net "UPI_CPU0_CPU1_P0P0_DN<6>")
	)
	(segment
		(start 156.484066 -86.708234)
		(end 156.634434 -86.886288)
		(width 0.1143)
		(layer "In9.Cu")
		(net "UPI_CPU0_CPU1_P0P0_DN<6>")
	)
	(segment
		(start 176.529746 -106.863642)
		(end 178.309778 -108.399072)
		(width 0.1143)
		(layer "In9.Cu")
		(net "UPI_CPU0_CPU1_P0P0_DN<6>")
	)
	(segment
		(start 227.98151 -110.02772)
		(end 233.676952 -110.997238)
		(width 0.1143)
		(layer "In9.Cu")
		(net "UPI_CPU0_CPU1_P0P0_DN<6>")
	)
	(segment
		(start 189.181994 -111.039402)
		(end 190.32601 -110.773464)
		(width 0.1143)
		(layer "In9.Cu")
		(net "UPI_CPU0_CPU1_P0P0_DN<6>")
	)
	(segment
		(start 315.037978 -86.960456)
		(end 313.119516 -81.915)
		(width 0.1143)
		(layer "In9.Cu")
		(net "UPI_CPU0_CPU1_P0P0_DN<6>")
	)
	(segment
		(start 291.041328 -106.939842)
		(end 291.125402 -106.932222)
		(width 0.1143)
		(layer "In9.Cu")
		(net "UPI_CPU0_CPU1_P0P0_DN<6>")
	)
	(segment
		(start 278.084026 -110.357666)
		(end 281.777694 -110.785656)
		(width 0.1143)
		(layer "In9.Cu")
		(net "UPI_CPU0_CPU1_P0P0_DN<6>")
	)
	(segment
		(start 184.591452 -109.94644)
		(end 189.181994 -111.039402)
		(width 0.1143)
		(layer "In9.Cu")
		(net "UPI_CPU0_CPU1_P0P0_DN<6>")
	)
	(segment
		(start 196.181218 -113.53165)
		(end 197.257416 -113.723674)
		(width 0.1143)
		(layer "In9.Cu")
		(net "UPI_CPU0_CPU1_P0P0_DN<6>")
	)
	(segment
		(start 190.32601 -110.773464)
		(end 191.29756 -110.844584)
		(width 0.1143)
		(layer "In9.Cu")
		(net "UPI_CPU0_CPU1_P0P0_DN<6>")
	)
	(segment
		(start 313.554364 -93.844364)
		(end 313.568842 -93.7768)
		(width 0.1143)
		(layer "In9.Cu")
		(net "UPI_CPU0_CPU1_P0P0_DN<6>")
	)
	(segment
		(start 313.568842 -93.7768)
		(end 314.218574 -90.762074)
		(width 0.1143)
		(layer "In9.Cu")
		(net "UPI_CPU0_CPU1_P0P0_DN<6>")
	)
	(segment
		(start 310.5658 -70.616064)
		(end 310.494172 -70.616064)
		(width 0.0889)
		(layer "In9.Cu")
		(net "UPI_CPU0_CPU1_P0P0_DN<6>")
	)
	(segment
		(start 312.3946 -79.8322)
		(end 312.324242 -77.285342)
		(width 0.1143)
		(layer "In9.Cu")
		(net "UPI_CPU0_CPU1_P0P0_DN<6>")
	)
	(segment
		(start 312.324242 -77.285342)
		(end 312.251344 -74.647806)
		(width 0.1143)
		(layer "In9.Cu")
		(net "UPI_CPU0_CPU1_P0P0_DN<6>")
	)
	(segment
		(start 314.218574 -90.762074)
		(end 315.037978 -86.960456)
		(width 0.1143)
		(layer "In9.Cu")
		(net "UPI_CPU0_CPU1_P0P0_DN<6>")
	)
	(segment
		(start 163.361624 -96.676972)
		(end 171.42714 -105.083864)
		(width 0.1143)
		(layer "In9.Cu")
		(net "UPI_CPU0_CPU1_P0P0_DN<6>")
	)
	(segment
		(start 191.29756 -110.844584)
		(end 196.181218 -113.53165)
		(width 0.1143)
		(layer "In9.Cu")
		(net "UPI_CPU0_CPU1_P0P0_DN<6>")
	)
	(segment
		(start 142.491206 -65.384934)
		(end 142.66291 -65.556384)
		(width 0.0889)
		(layer "In9.Cu")
		(net "UPI_CPU0_CPU1_P0P0_DN<6>")
	)
	(segment
		(start 145.728436 -65.148206)
		(end 145.779236 -65.199006)
		(width 0.0889)
		(layer "In9.Cu")
		(net "UPI_CPU0_CPU1_P0P0_DN<6>")
	)
	(segment
		(start 313.119516 -81.915)
		(end 312.399934 -80.022192)
		(width 0.1143)
		(layer "In9.Cu")
		(net "UPI_CPU0_CPU1_P0P0_DN<6>")
	)
	(segment
		(start 141.949678 -64.915288)
		(end 142.131288 -64.915288)
		(width 0.0889)
		(layer "In9.Cu")
		(net "UPI_CPU0_CPU1_P0P0_DN<6>")
	)
	(segment
		(start 171.42714 -105.083864)
		(end 176.529746 -106.863642)
		(width 0.1143)
		(layer "In9.Cu")
		(net "UPI_CPU0_CPU1_P0P0_DN<6>")
	)
	(segment
		(start 233.676952 -110.997238)
		(end 248.027952 -108.143548)
		(width 0.1143)
		(layer "In9.Cu")
		(net "UPI_CPU0_CPU1_P0P0_DN<6>")
	)
	(arc
		(start 139.409424 -65.410334)
		(mid 139.692641 -65.326053)
		(end 139.899644 -65.115186)
		(width 0.0889)
		(layer "In9.Cu")
		(net "UPI_CPU0_CPU1_P0P0_DN<6>")
	)
	(arc
		(start 142.131288 -64.915288)
		(mid 142.235048 -64.981557)
		(end 142.31239 -65.07734)
		(width 0.0889)
		(layer "In9.Cu")
		(net "UPI_CPU0_CPU1_P0P0_DN<6>")
	)
	(arc
		(start 139.899644 -65.115186)
		(mid 140.039723 -64.97245)
		(end 140.231368 -64.915288)
		(width 0.0889)
		(layer "In9.Cu")
		(net "UPI_CPU0_CPU1_P0P0_DN<6>")
	)
	(arc
		(start 138.511788 -65.905888)
		(mid 138.529314 -65.906148)
		(end 138.54684 -65.905888)
		(width 0.0889)
		(layer "In9.Cu")
		(net "UPI_CPU0_CPU1_P0P0_DN<6>")
	)
	(arc
		(start 139.041124 -65.610486)
		(mid 139.182807 -65.466682)
		(end 139.376658 -65.410334)
		(width 0.0889)
		(layer "In9.Cu")
		(net "UPI_CPU0_CPU1_P0P0_DN<6>")
	)
	(arc
		(start 137.670794 -64.819784)
		(mid 137.697894 -65.020509)
		(end 137.77722 -65.20688)
		(width 0.0889)
		(layer "In9.Cu")
		(net "UPI_CPU0_CPU1_P0P0_DN<6>")
	)
	(arc
		(start 306.942236 -67.696588)
		(mid 306.539725 -67.875612)
		(end 306.372768 -68.283328)
		(width 0.0889)
		(layer "In9.Cu")
		(net "UPI_CPU0_CPU1_P0P0_DN<6>")
	)
	(arc
		(start 141.451584 -64.619886)
		(mid 141.661937 -64.832858)
		(end 141.949678 -64.915288)
		(width 0.0889)
		(layer "In9.Cu")
		(net "UPI_CPU0_CPU1_P0P0_DN<6>")
	)
	(arc
		(start 138.017504 -65.610486)
		(mid 138.226221 -65.822483)
		(end 138.511788 -65.905888)
		(width 0.0889)
		(layer "In9.Cu")
		(net "UPI_CPU0_CPU1_P0P0_DN<6>")
	)
	(arc
		(start 140.758164 -64.619886)
		(mid 140.899847 -64.476082)
		(end 141.093698 -64.419734)
		(width 0.0889)
		(layer "In9.Cu")
		(net "UPI_CPU0_CPU1_P0P0_DN<6>")
	)
	(arc
		(start 138.54684 -65.905888)
		(mid 138.832405 -65.822479)
		(end 139.041124 -65.610486)
		(width 0.0889)
		(layer "In9.Cu")
		(net "UPI_CPU0_CPU1_P0P0_DN<6>")
	)
	(arc
		(start 141.11605 -64.419734)
		(mid 141.3099 -64.476084)
		(end 141.451584 -64.619886)
		(width 0.0889)
		(layer "In9.Cu")
		(net "UPI_CPU0_CPU1_P0P0_DN<6>")
	)
	(arc
		(start 140.264134 -64.915288)
		(mid 140.549558 -64.831821)
		(end 140.758164 -64.619886)
		(width 0.0889)
		(layer "In9.Cu")
		(net "UPI_CPU0_CPU1_P0P0_DN<6>")
	)
	(arc
		(start 306.372768 -68.283328)
		(mid 306.330251 -68.497074)
		(end 306.209192 -68.678298)
		(width 0.0889)
		(layer "In9.Cu")
		(net "UPI_CPU0_CPU1_P0P0_DN<6>")
	)
	(segment
		(start 137.099294 -63.829184)
		(end 137.670794 -63.829184)
		(width 0.1143)
		(layer "F.Cu")
		(net "UPI_CPU0_CPU1_P0P0_DN<5>")
	)
	(segment
		(start 304.675286 -69.277738)
		(end 305.246786 -69.277738)
		(width 0.1143)
		(layer "F.Cu")
		(net "UPI_CPU0_CPU1_P0P0_DN<5>")
	)
	(via
		(at 137.670794 -63.829184)
		(size 0.508)
		(drill 0.254)
		(layers "F.Cu" "B.Cu")
		(net "UPI_CPU0_CPU1_P0P0_DN<5>")
	)
	(via
		(at 305.246786 -69.277738)
		(size 0.508)
		(drill 0.254)
		(layers "F.Cu" "B.Cu")
		(net "UPI_CPU0_CPU1_P0P0_DN<5>")
	)
	(segment
		(start 309.136796 -70.804532)
		(end 309.136796 -70.732396)
		(width 0.0889)
		(layer "In9.Cu")
		(net "UPI_CPU0_CPU1_P0P0_DN<5>")
	)
	(segment
		(start 141.087094 -63.238634)
		(end 141.1224 -63.238634)
		(width 0.0889)
		(layer "In9.Cu")
		(net "UPI_CPU0_CPU1_P0P0_DN<5>")
	)
	(segment
		(start 144.656048 -63.987934)
		(end 144.753584 -64.08547)
		(width 0.0889)
		(layer "In9.Cu")
		(net "UPI_CPU0_CPU1_P0P0_DN<5>")
	)
	(segment
		(start 311.110122 -77.578712)
		(end 311.25033 -77.431646)
		(width 0.1143)
		(layer "In9.Cu")
		(net "UPI_CPU0_CPU1_P0P0_DN<5>")
	)
	(segment
		(start 168.067228 -100.209096)
		(end 171.98594 -104.29367)
		(width 0.1143)
		(layer "In9.Cu")
		(net "UPI_CPU0_CPU1_P0P0_DN<5>")
	)
	(segment
		(start 138.52906 -64.724788)
		(end 138.529568 -64.724788)
		(width 0.0889)
		(layer "In9.Cu")
		(net "UPI_CPU0_CPU1_P0P0_DN<5>")
	)
	(segment
		(start 311.20207 -75.713336)
		(end 311.054242 -75.573636)
		(width 0.1143)
		(layer "In9.Cu")
		(net "UPI_CPU0_CPU1_P0P0_DN<5>")
	)
	(segment
		(start 292.388036 -105.883964)
		(end 302.887888 -108.565188)
		(width 0.1143)
		(layer "In9.Cu")
		(net "UPI_CPU0_CPU1_P0P0_DN<5>")
	)
	(segment
		(start 163.81095 -93.937328)
		(end 164.14877 -96.124522)
		(width 0.1143)
		(layer "In9.Cu")
		(net "UPI_CPU0_CPU1_P0P0_DN<5>")
	)
	(segment
		(start 141.73073 -62.727078)
		(end 142.70228 -62.727078)
		(width 0.0889)
		(layer "In9.Cu")
		(net "UPI_CPU0_CPU1_P0P0_DN<5>")
	)
	(segment
		(start 179.82692 -107.988862)
		(end 179.827428 -107.989116)
		(width 0.1143)
		(layer "In9.Cu")
		(net "UPI_CPU0_CPU1_P0P0_DN<5>")
	)
	(segment
		(start 157.327854 -86.265004)
		(end 163.81095 -93.937328)
		(width 0.1143)
		(layer "In9.Cu")
		(net "UPI_CPU0_CPU1_P0P0_DN<5>")
	)
	(segment
		(start 147.174966 -64.03467)
		(end 147.962366 -64.379348)
		(width 0.1143)
		(layer "In9.Cu")
		(net "UPI_CPU0_CPU1_P0P0_DN<5>")
	)
	(segment
		(start 145.570956 -64.03467)
		(end 145.593054 -64.03467)
		(width 0.0889)
		(layer "In9.Cu")
		(net "UPI_CPU0_CPU1_P0P0_DN<5>")
	)
	(segment
		(start 144.753584 -64.08547)
		(end 144.931384 -64.08547)
		(width 0.0889)
		(layer "In9.Cu")
		(net "UPI_CPU0_CPU1_P0P0_DN<5>")
	)
	(segment
		(start 141.451584 -63.038736)
		(end 141.496034 -62.961774)
		(width 0.0889)
		(layer "In9.Cu")
		(net "UPI_CPU0_CPU1_P0P0_DN<5>")
	)
	(segment
		(start 306.535328 -107.734608)
		(end 310.373776 -104.18699)
		(width 0.1143)
		(layer "In9.Cu")
		(net "UPI_CPU0_CPU1_P0P0_DN<5>")
	)
	(segment
		(start 308.95163 -70.242684)
		(end 308.675786 -69.96684)
		(width 0.0889)
		(layer "In9.Cu")
		(net "UPI_CPU0_CPU1_P0P0_DN<5>")
	)
	(segment
		(start 307.646324 -69.23786)
		(end 307.485542 -69.160898)
		(width 0.0889)
		(layer "In9.Cu")
		(net "UPI_CPU0_CPU1_P0P0_DN<5>")
	)
	(segment
		(start 307.485542 -69.160898)
		(end 307.44287 -69.03974)
		(width 0.0889)
		(layer "In9.Cu")
		(net "UPI_CPU0_CPU1_P0P0_DN<5>")
	)
	(segment
		(start 140.224764 -63.734188)
		(end 140.25753 -63.734188)
		(width 0.0889)
		(layer "In9.Cu")
		(net "UPI_CPU0_CPU1_P0P0_DN<5>")
	)
	(segment
		(start 310.373776 -104.18699)
		(end 314.042044 -87.16772)
		(width 0.1143)
		(layer "In9.Cu")
		(net "UPI_CPU0_CPU1_P0P0_DN<5>")
	)
	(segment
		(start 177.282856 -106.14152)
		(end 179.074064 -107.687364)
		(width 0.1143)
		(layer "In9.Cu")
		(net "UPI_CPU0_CPU1_P0P0_DN<5>")
	)
	(segment
		(start 307.6956 -69.220334)
		(end 307.646324 -69.23786)
		(width 0.0889)
		(layer "In9.Cu")
		(net "UPI_CPU0_CPU1_P0P0_DN<5>")
	)
	(segment
		(start 144.060672 -64.08547)
		(end 144.380712 -64.08547)
		(width 0.0889)
		(layer "In9.Cu")
		(net "UPI_CPU0_CPU1_P0P0_DN<5>")
	)
	(segment
		(start 191.310514 -108.589572)
		(end 195.80352 -112.262412)
		(width 0.1143)
		(layer "In9.Cu")
		(net "UPI_CPU0_CPU1_P0P0_DN<5>")
	)
	(segment
		(start 188.332618 -108.422186)
		(end 189.36335 -108.283248)
		(width 0.1143)
		(layer "In9.Cu")
		(net "UPI_CPU0_CPU1_P0P0_DN<5>")
	)
	(segment
		(start 311.095898 -77.063092)
		(end 311.089294 -76.833984)
		(width 0.1143)
		(layer "In9.Cu")
		(net "UPI_CPU0_CPU1_P0P0_DN<5>")
	)
	(segment
		(start 302.887888 -108.565188)
		(end 306.535328 -107.734608)
		(width 0.1143)
		(layer "In9.Cu")
		(net "UPI_CPU0_CPU1_P0P0_DN<5>")
	)
	(segment
		(start 305.246786 -68.939664)
		(end 305.246786 -69.277738)
		(width 0.0889)
		(layer "In9.Cu")
		(net "UPI_CPU0_CPU1_P0P0_DN<5>")
	)
	(segment
		(start 139.374118 -64.229234)
		(end 139.40282 -64.229234)
		(width 0.0889)
		(layer "In9.Cu")
		(net "UPI_CPU0_CPU1_P0P0_DN<5>")
	)
	(segment
		(start 311.264554 -77.94752)
		(end 311.116726 -77.80782)
		(width 0.1143)
		(layer "In9.Cu")
		(net "UPI_CPU0_CPU1_P0P0_DN<5>")
	)
	(segment
		(start 145.304256 -64.08547)
		(end 145.520156 -64.08547)
		(width 0.0889)
		(layer "In9.Cu")
		(net "UPI_CPU0_CPU1_P0P0_DN<5>")
	)
	(segment
		(start 171.98594 -104.29367)
		(end 177.282856 -106.14152)
		(width 0.1143)
		(layer "In9.Cu")
		(net "UPI_CPU0_CPU1_P0P0_DN<5>")
	)
	(segment
		(start 152.8572 -69.781674)
		(end 157.327854 -86.265004)
		(width 0.1143)
		(layer "In9.Cu")
		(net "UPI_CPU0_CPU1_P0P0_DN<5>")
	)
	(segment
		(start 137.670794 -63.829184)
		(end 137.377678 -63.998348)
		(width 0.0889)
		(layer "In9.Cu")
		(net "UPI_CPU0_CPU1_P0P0_DN<5>")
	)
	(segment
		(start 311.116726 -77.80782)
		(end 311.110122 -77.578712)
		(width 0.1143)
		(layer "In9.Cu")
		(net "UPI_CPU0_CPU1_P0P0_DN<5>")
	)
	(segment
		(start 145.20672 -63.987934)
		(end 145.304256 -64.08547)
		(width 0.0889)
		(layer "In9.Cu")
		(net "UPI_CPU0_CPU1_P0P0_DN<5>")
	)
	(segment
		(start 168.067482 -100.209096)
		(end 168.067228 -100.209096)
		(width 0.1143)
		(layer "In9.Cu")
		(net "UPI_CPU0_CPU1_P0P0_DN<5>")
	)
	(segment
		(start 147.962366 -64.379348)
		(end 152.8572 -69.781674)
		(width 0.1143)
		(layer "In9.Cu")
		(net "UPI_CPU0_CPU1_P0P0_DN<5>")
	)
	(segment
		(start 189.36335 -108.283248)
		(end 189.53734 -108.286042)
		(width 0.1143)
		(layer "In9.Cu")
		(net "UPI_CPU0_CPU1_P0P0_DN<5>")
	)
	(segment
		(start 311.222898 -76.458064)
		(end 311.07507 -76.318364)
		(width 0.1143)
		(layer "In9.Cu")
		(net "UPI_CPU0_CPU1_P0P0_DN<5>")
	)
	(segment
		(start 308.39156 -69.682614)
		(end 308.029356 -69.32041)
		(width 0.0889)
		(layer "In9.Cu")
		(net "UPI_CPU0_CPU1_P0P0_DN<5>")
	)
	(segment
		(start 183.785764 -108.62183)
		(end 188.332618 -108.422186)
		(width 0.1143)
		(layer "In9.Cu")
		(net "UPI_CPU0_CPU1_P0P0_DN<5>")
	)
	(segment
		(start 311.137554 -78.552548)
		(end 311.13095 -78.32344)
		(width 0.1143)
		(layer "In9.Cu")
		(net "UPI_CPU0_CPU1_P0P0_DN<5>")
	)
	(segment
		(start 179.074064 -107.687364)
		(end 179.82692 -107.988862)
		(width 0.1143)
		(layer "In9.Cu")
		(net "UPI_CPU0_CPU1_P0P0_DN<5>")
	)
	(segment
		(start 311.208674 -75.94219)
		(end 311.20207 -75.713336)
		(width 0.1143)
		(layer "In9.Cu")
		(net "UPI_CPU0_CPU1_P0P0_DN<5>")
	)
	(segment
		(start 179.827428 -107.989116)
		(end 179.827682 -107.989116)
		(width 0.1143)
		(layer "In9.Cu")
		(net "UPI_CPU0_CPU1_P0P0_DN<5>")
	)
	(segment
		(start 179.827682 -107.988862)
		(end 183.785764 -108.62183)
		(width 0.1143)
		(layer "In9.Cu")
		(net "UPI_CPU0_CPU1_P0P0_DN<5>")
	)
	(segment
		(start 248.031508 -107.19435)
		(end 262.944864 -110.273084)
		(width 0.1143)
		(layer "In9.Cu")
		(net "UPI_CPU0_CPU1_P0P0_DN<5>")
	)
	(segment
		(start 197.327266 -112.777524)
		(end 227.999798 -109.087666)
		(width 0.1143)
		(layer "In9.Cu")
		(net "UPI_CPU0_CPU1_P0P0_DN<5>")
	)
	(segment
		(start 144.380712 -64.08547)
		(end 144.478248 -63.987934)
		(width 0.0889)
		(layer "In9.Cu")
		(net "UPI_CPU0_CPU1_P0P0_DN<5>")
	)
	(segment
		(start 305.304698 -68.881752)
		(end 305.246786 -68.939664)
		(width 0.0889)
		(layer "In9.Cu")
		(net "UPI_CPU0_CPU1_P0P0_DN<5>")
	)
	(segment
		(start 311.1754 -74.694288)
		(end 309.984902 -71.652638)
		(width 0.1143)
		(layer "In9.Cu")
		(net "UPI_CPU0_CPU1_P0P0_DN<5>")
	)
	(segment
		(start 227.999798 -109.087666)
		(end 233.66349 -110.051596)
		(width 0.1143)
		(layer "In9.Cu")
		(net "UPI_CPU0_CPU1_P0P0_DN<5>")
	)
	(segment
		(start 311.25033 -77.431646)
		(end 311.243726 -77.202792)
		(width 0.1143)
		(layer "In9.Cu")
		(net "UPI_CPU0_CPU1_P0P0_DN<5>")
	)
	(segment
		(start 145.02892 -63.987934)
		(end 145.20672 -63.987934)
		(width 0.0889)
		(layer "In9.Cu")
		(net "UPI_CPU0_CPU1_P0P0_DN<5>")
	)
	(segment
		(start 311.07507 -76.318364)
		(end 311.068466 -76.089256)
		(width 0.1143)
		(layer "In9.Cu")
		(net "UPI_CPU0_CPU1_P0P0_DN<5>")
	)
	(segment
		(start 307.104288 -68.877688)
		(end 306.9463 -68.877688)
		(width 0.0889)
		(layer "In9.Cu")
		(net "UPI_CPU0_CPU1_P0P0_DN<5>")
	)
	(segment
		(start 314.042044 -87.16772)
		(end 311.321958 -80.013048)
		(width 0.1143)
		(layer "In9.Cu")
		(net "UPI_CPU0_CPU1_P0P0_DN<5>")
	)
	(segment
		(start 308.39156 -69.822822)
		(end 308.39156 -69.682614)
		(width 0.0889)
		(layer "In9.Cu")
		(net "UPI_CPU0_CPU1_P0P0_DN<5>")
	)
	(segment
		(start 308.95163 -70.54723)
		(end 308.95163 -70.242684)
		(width 0.0889)
		(layer "In9.Cu")
		(net "UPI_CPU0_CPU1_P0P0_DN<5>")
	)
	(segment
		(start 309.984902 -71.652638)
		(end 309.136796 -70.804532)
		(width 0.1143)
		(layer "In9.Cu")
		(net "UPI_CPU0_CPU1_P0P0_DN<5>")
	)
	(segment
		(start 267.1064 -110.477554)
		(end 278.093424 -109.422438)
		(width 0.1143)
		(layer "In9.Cu")
		(net "UPI_CPU0_CPU1_P0P0_DN<5>")
	)
	(segment
		(start 144.931384 -64.08547)
		(end 145.02892 -63.987934)
		(width 0.0889)
		(layer "In9.Cu")
		(net "UPI_CPU0_CPU1_P0P0_DN<5>")
	)
	(segment
		(start 141.496034 -62.961774)
		(end 141.73073 -62.727078)
		(width 0.0889)
		(layer "In9.Cu")
		(net "UPI_CPU0_CPU1_P0P0_DN<5>")
	)
	(segment
		(start 145.593054 -64.03467)
		(end 147.174966 -64.03467)
		(width 0.1143)
		(layer "In9.Cu")
		(net "UPI_CPU0_CPU1_P0P0_DN<5>")
	)
	(segment
		(start 311.13095 -78.32344)
		(end 311.271158 -78.176374)
		(width 0.1143)
		(layer "In9.Cu")
		(net "UPI_CPU0_CPU1_P0P0_DN<5>")
	)
	(segment
		(start 179.827682 -107.989116)
		(end 179.827682 -107.988862)
		(width 0.1143)
		(layer "In9.Cu")
		(net "UPI_CPU0_CPU1_P0P0_DN<5>")
	)
	(segment
		(start 233.66349 -110.051596)
		(end 248.031508 -107.19435)
		(width 0.1143)
		(layer "In9.Cu")
		(net "UPI_CPU0_CPU1_P0P0_DN<5>")
	)
	(segment
		(start 311.151778 -79.068168)
		(end 311.291986 -78.921102)
		(width 0.1143)
		(layer "In9.Cu")
		(net "UPI_CPU0_CPU1_P0P0_DN<5>")
	)
	(segment
		(start 306.126896 -69.372734)
		(end 306.083716 -69.372734)
		(width 0.0889)
		(layer "In9.Cu")
		(net "UPI_CPU0_CPU1_P0P0_DN<5>")
	)
	(segment
		(start 311.243726 -77.202792)
		(end 311.095898 -77.063092)
		(width 0.1143)
		(layer "In9.Cu")
		(net "UPI_CPU0_CPU1_P0P0_DN<5>")
	)
	(segment
		(start 308.029356 -69.32041)
		(end 307.767228 -69.194934)
		(width 0.0889)
		(layer "In9.Cu")
		(net "UPI_CPU0_CPU1_P0P0_DN<5>")
	)
	(segment
		(start 311.321958 -80.013048)
		(end 311.305956 -79.436976)
		(width 0.1143)
		(layer "In9.Cu")
		(net "UPI_CPU0_CPU1_P0P0_DN<5>")
	)
	(segment
		(start 311.068466 -76.089256)
		(end 311.208674 -75.94219)
		(width 0.1143)
		(layer "In9.Cu")
		(net "UPI_CPU0_CPU1_P0P0_DN<5>")
	)
	(segment
		(start 311.291986 -78.921102)
		(end 311.285382 -78.692248)
		(width 0.1143)
		(layer "In9.Cu")
		(net "UPI_CPU0_CPU1_P0P0_DN<5>")
	)
	(segment
		(start 311.229502 -76.686918)
		(end 311.222898 -76.458064)
		(width 0.1143)
		(layer "In9.Cu")
		(net "UPI_CPU0_CPU1_P0P0_DN<5>")
	)
	(segment
		(start 189.53734 -108.286042)
		(end 191.310514 -108.589572)
		(width 0.1143)
		(layer "In9.Cu")
		(net "UPI_CPU0_CPU1_P0P0_DN<5>")
	)
	(segment
		(start 309.136796 -70.732396)
		(end 308.95163 -70.54723)
		(width 0.0889)
		(layer "In9.Cu")
		(net "UPI_CPU0_CPU1_P0P0_DN<5>")
	)
	(segment
		(start 311.305956 -79.436976)
		(end 311.158382 -79.297276)
		(width 0.1143)
		(layer "In9.Cu")
		(net "UPI_CPU0_CPU1_P0P0_DN<5>")
	)
	(segment
		(start 308.675786 -69.96684)
		(end 308.535578 -69.96684)
		(width 0.0889)
		(layer "In9.Cu")
		(net "UPI_CPU0_CPU1_P0P0_DN<5>")
	)
	(segment
		(start 281.64409 -109.834172)
		(end 290.816538 -106.026458)
		(width 0.1143)
		(layer "In9.Cu")
		(net "UPI_CPU0_CPU1_P0P0_DN<5>")
	)
	(segment
		(start 196.40423 -112.592358)
		(end 197.327266 -112.777524)
		(width 0.1143)
		(layer "In9.Cu")
		(net "UPI_CPU0_CPU1_P0P0_DN<5>")
	)
	(segment
		(start 145.520156 -64.08547)
		(end 145.570956 -64.03467)
		(width 0.0889)
		(layer "In9.Cu")
		(net "UPI_CPU0_CPU1_P0P0_DN<5>")
	)
	(segment
		(start 137.377678 -63.998348)
		(end 137.356596 -64.077088)
		(width 0.0889)
		(layer "In9.Cu")
		(net "UPI_CPU0_CPU1_P0P0_DN<5>")
	)
	(segment
		(start 311.054242 -75.573636)
		(end 311.047638 -75.344528)
		(width 0.1143)
		(layer "In9.Cu")
		(net "UPI_CPU0_CPU1_P0P0_DN<5>")
	)
	(segment
		(start 290.816538 -106.026458)
		(end 292.388036 -105.883964)
		(width 0.1143)
		(layer "In9.Cu")
		(net "UPI_CPU0_CPU1_P0P0_DN<5>")
	)
	(segment
		(start 307.44287 -69.03974)
		(end 307.104288 -68.877688)
		(width 0.0889)
		(layer "In9.Cu")
		(net "UPI_CPU0_CPU1_P0P0_DN<5>")
	)
	(segment
		(start 195.80352 -112.262412)
		(end 196.40423 -112.592358)
		(width 0.1143)
		(layer "In9.Cu")
		(net "UPI_CPU0_CPU1_P0P0_DN<5>")
	)
	(segment
		(start 278.093424 -109.422438)
		(end 281.64409 -109.834172)
		(width 0.1143)
		(layer "In9.Cu")
		(net "UPI_CPU0_CPU1_P0P0_DN<5>")
	)
	(segment
		(start 262.944864 -110.273084)
		(end 267.1064 -110.477554)
		(width 0.1143)
		(layer "In9.Cu")
		(net "UPI_CPU0_CPU1_P0P0_DN<5>")
	)
	(segment
		(start 311.271158 -78.176374)
		(end 311.264554 -77.94752)
		(width 0.1143)
		(layer "In9.Cu")
		(net "UPI_CPU0_CPU1_P0P0_DN<5>")
	)
	(segment
		(start 311.089294 -76.833984)
		(end 311.229502 -76.686918)
		(width 0.1143)
		(layer "In9.Cu")
		(net "UPI_CPU0_CPU1_P0P0_DN<5>")
	)
	(segment
		(start 142.70228 -62.727078)
		(end 144.060672 -64.08547)
		(width 0.0889)
		(layer "In9.Cu")
		(net "UPI_CPU0_CPU1_P0P0_DN<5>")
	)
	(segment
		(start 311.158382 -79.297276)
		(end 311.151778 -79.068168)
		(width 0.1143)
		(layer "In9.Cu")
		(net "UPI_CPU0_CPU1_P0P0_DN<5>")
	)
	(segment
		(start 137.655808 -64.229234)
		(end 137.68451 -64.229234)
		(width 0.0889)
		(layer "In9.Cu")
		(net "UPI_CPU0_CPU1_P0P0_DN<5>")
	)
	(segment
		(start 144.478248 -63.987934)
		(end 144.656048 -63.987934)
		(width 0.0889)
		(layer "In9.Cu")
		(net "UPI_CPU0_CPU1_P0P0_DN<5>")
	)
	(segment
		(start 311.187846 -75.197208)
		(end 311.1754 -74.694288)
		(width 0.1143)
		(layer "In9.Cu")
		(net "UPI_CPU0_CPU1_P0P0_DN<5>")
	)
	(segment
		(start 308.535578 -69.96684)
		(end 308.39156 -69.822822)
		(width 0.0889)
		(layer "In9.Cu")
		(net "UPI_CPU0_CPU1_P0P0_DN<5>")
	)
	(segment
		(start 307.767228 -69.194934)
		(end 307.6956 -69.220334)
		(width 0.0889)
		(layer "In9.Cu")
		(net "UPI_CPU0_CPU1_P0P0_DN<5>")
	)
	(segment
		(start 164.14877 -96.124522)
		(end 168.067482 -100.209096)
		(width 0.1143)
		(layer "In9.Cu")
		(net "UPI_CPU0_CPU1_P0P0_DN<5>")
	)
	(segment
		(start 311.047638 -75.344528)
		(end 311.187846 -75.197208)
		(width 0.1143)
		(layer "In9.Cu")
		(net "UPI_CPU0_CPU1_P0P0_DN<5>")
	)
	(segment
		(start 311.285382 -78.692248)
		(end 311.137554 -78.552548)
		(width 0.1143)
		(layer "In9.Cu")
		(net "UPI_CPU0_CPU1_P0P0_DN<5>")
	)
	(arc
		(start 138.876024 -64.524636)
		(mid 139.086377 -64.311664)
		(end 139.374118 -64.229234)
		(width 0.0889)
		(layer "In9.Cu")
		(net "UPI_CPU0_CPU1_P0P0_DN<5>")
	)
	(arc
		(start 305.593496 -69.077586)
		(mid 305.471551 -68.946554)
		(end 305.304698 -68.881752)
		(width 0.0889)
		(layer "In9.Cu")
		(net "UPI_CPU0_CPU1_P0P0_DN<5>")
	)
	(arc
		(start 139.734544 -64.029336)
		(mid 139.941548 -63.818472)
		(end 140.224764 -63.734188)
		(width 0.0889)
		(layer "In9.Cu")
		(net "UPI_CPU0_CPU1_P0P0_DN<5>")
	)
	(arc
		(start 140.25753 -63.734188)
		(mid 140.45138 -63.677838)
		(end 140.593064 -63.534036)
		(width 0.0889)
		(layer "In9.Cu")
		(net "UPI_CPU0_CPU1_P0P0_DN<5>")
	)
	(arc
		(start 141.1224 -63.238634)
		(mid 141.312642 -63.180899)
		(end 141.451584 -63.038736)
		(width 0.0889)
		(layer "In9.Cu")
		(net "UPI_CPU0_CPU1_P0P0_DN<5>")
	)
	(arc
		(start 137.68451 -64.229234)
		(mid 137.972197 -64.311755)
		(end 138.182604 -64.524636)
		(width 0.0889)
		(layer "In9.Cu")
		(net "UPI_CPU0_CPU1_P0P0_DN<5>")
	)
	(arc
		(start 137.356596 -64.077088)
		(mid 137.489477 -64.186071)
		(end 137.655808 -64.229234)
		(width 0.0889)
		(layer "In9.Cu")
		(net "UPI_CPU0_CPU1_P0P0_DN<5>")
	)
	(arc
		(start 139.40282 -64.229234)
		(mid 139.594462 -64.172068)
		(end 139.734544 -64.029336)
		(width 0.0889)
		(layer "In9.Cu")
		(net "UPI_CPU0_CPU1_P0P0_DN<5>")
	)
	(arc
		(start 306.9463 -68.877688)
		(mid 306.756058 -68.935423)
		(end 306.617116 -69.077586)
		(width 0.0889)
		(layer "In9.Cu")
		(net "UPI_CPU0_CPU1_P0P0_DN<5>")
	)
	(arc
		(start 306.083716 -69.372734)
		(mid 305.800499 -69.288453)
		(end 305.593496 -69.077586)
		(width 0.0889)
		(layer "In9.Cu")
		(net "UPI_CPU0_CPU1_P0P0_DN<5>")
	)
	(arc
		(start 138.182604 -64.524636)
		(mid 138.328986 -64.6712)
		(end 138.52906 -64.724788)
		(width 0.0889)
		(layer "In9.Cu")
		(net "UPI_CPU0_CPU1_P0P0_DN<5>")
	)
	(arc
		(start 138.529568 -64.724788)
		(mid 138.729609 -64.671143)
		(end 138.876024 -64.524636)
		(width 0.0889)
		(layer "In9.Cu")
		(net "UPI_CPU0_CPU1_P0P0_DN<5>")
	)
	(arc
		(start 140.593064 -63.534036)
		(mid 140.801672 -63.322104)
		(end 141.087094 -63.238634)
		(width 0.0889)
		(layer "In9.Cu")
		(net "UPI_CPU0_CPU1_P0P0_DN<5>")
	)
	(arc
		(start 306.617116 -69.077586)
		(mid 306.410112 -69.28845)
		(end 306.126896 -69.372734)
		(width 0.0889)
		(layer "In9.Cu")
		(net "UPI_CPU0_CPU1_P0P0_DN<5>")
	)
	(segment
		(start 137.957814 -64.324738)
		(end 138.529314 -64.324738)
		(width 0.1143)
		(layer "F.Cu")
		(net "UPI_CPU0_CPU1_P0P0_DN<4>")
	)
	(segment
		(start 303.816766 -69.772784)
		(end 304.388266 -69.772784)
		(width 0.1143)
		(layer "F.Cu")
		(net "UPI_CPU0_CPU1_P0P0_DN<4>")
	)
	(via
		(at 304.388266 -69.772784)
		(size 0.508)
		(drill 0.254)
		(layers "F.Cu" "B.Cu")
		(net "UPI_CPU0_CPU1_P0P0_DN<4>")
	)
	(via
		(at 138.529314 -64.324738)
		(size 0.508)
		(drill 0.254)
		(layers "F.Cu" "B.Cu")
		(net "UPI_CPU0_CPU1_P0P0_DN<4>")
	)
	(segment
		(start 175.633888 -104.118918)
		(end 179.481734 -107.437936)
		(width 0.1143)
		(layer "In9.Cu")
		(net "UPI_CPU0_CPU1_P0P0_DN<4>")
	)
	(segment
		(start 281.596084 -109.480604)
		(end 286.644842 -107.384088)
		(width 0.1143)
		(layer "In9.Cu")
		(net "UPI_CPU0_CPU1_P0P0_DN<4>")
	)
	(segment
		(start 309.19293 -71.613268)
		(end 309.120794 -71.613268)
		(width 0.0889)
		(layer "In9.Cu")
		(net "UPI_CPU0_CPU1_P0P0_DN<4>")
	)
	(segment
		(start 233.657902 -109.700314)
		(end 248.032778 -106.841798)
		(width 0.1143)
		(layer "In9.Cu")
		(net "UPI_CPU0_CPU1_P0P0_DN<4>")
	)
	(segment
		(start 189.562486 -107.99318)
		(end 191.57696 -108.335572)
		(width 0.1143)
		(layer "In9.Cu")
		(net "UPI_CPU0_CPU1_P0P0_DN<4>")
	)
	(segment
		(start 164.160454 -93.816678)
		(end 164.478462 -95.874586)
		(width 0.1143)
		(layer "In9.Cu")
		(net "UPI_CPU0_CPU1_P0P0_DN<4>")
	)
	(segment
		(start 143.88465 -63.34125)
		(end 144.620742 -63.34125)
		(width 0.0889)
		(layer "In9.Cu")
		(net "UPI_CPU0_CPU1_P0P0_DN<4>")
	)
	(segment
		(start 138.529314 -64.324738)
		(end 138.529314 -63.986664)
		(width 0.0889)
		(layer "In9.Cu")
		(net "UPI_CPU0_CPU1_P0P0_DN<4>")
	)
	(segment
		(start 311.595516 -81.915)
		(end 310.822594 -79.881476)
		(width 0.1143)
		(layer "In9.Cu")
		(net "UPI_CPU0_CPU1_P0P0_DN<4>")
	)
	(segment
		(start 307.507386 -69.99986)
		(end 306.580794 -69.99986)
		(width 0.0889)
		(layer "In9.Cu")
		(net "UPI_CPU0_CPU1_P0P0_DN<4>")
	)
	(segment
		(start 191.57696 -108.335572)
		(end 196.341746 -112.186466)
		(width 0.1143)
		(layer "In9.Cu")
		(net "UPI_CPU0_CPU1_P0P0_DN<4>")
	)
	(segment
		(start 140.231368 -62.934088)
		(end 140.264134 -62.934088)
		(width 0.0889)
		(layer "In9.Cu")
		(net "UPI_CPU0_CPU1_P0P0_DN<4>")
	)
	(segment
		(start 262.99922 -109.929676)
		(end 266.569952 -110.105444)
		(width 0.1143)
		(layer "In9.Cu")
		(net "UPI_CPU0_CPU1_P0P0_DN<4>")
	)
	(segment
		(start 266.569952 -110.10519)
		(end 267.098272 -110.131098)
		(width 0.1143)
		(layer "In9.Cu")
		(net "UPI_CPU0_CPU1_P0P0_DN<4>")
	)
	(segment
		(start 197.3961 -112.423702)
		(end 227.968556 -108.731812)
		(width 0.1143)
		(layer "In9.Cu")
		(net "UPI_CPU0_CPU1_P0P0_DN<4>")
	)
	(segment
		(start 164.478462 -95.874586)
		(end 171.623228 -103.32212)
		(width 0.1143)
		(layer "In9.Cu")
		(net "UPI_CPU0_CPU1_P0P0_DN<4>")
	)
	(segment
		(start 248.032778 -106.841798)
		(end 262.99922 -109.929676)
		(width 0.1143)
		(layer "In9.Cu")
		(net "UPI_CPU0_CPU1_P0P0_DN<4>")
	)
	(segment
		(start 286.644842 -107.384342)
		(end 290.73094 -105.687368)
		(width 0.1143)
		(layer "In9.Cu")
		(net "UPI_CPU0_CPU1_P0P0_DN<4>")
	)
	(segment
		(start 152.916636 -68.675504)
		(end 157.642052 -86.102698)
		(width 0.1143)
		(layer "In9.Cu")
		(net "UPI_CPU0_CPU1_P0P0_DN<4>")
	)
	(segment
		(start 290.73094 -105.687368)
		(end 291.125402 -105.651554)
		(width 0.1143)
		(layer "In9.Cu")
		(net "UPI_CPU0_CPU1_P0P0_DN<4>")
	)
	(segment
		(start 310.05272 -104.013)
		(end 312.260742 -93.7768)
		(width 0.1143)
		(layer "In9.Cu")
		(net "UPI_CPU0_CPU1_P0P0_DN<4>")
	)
	(segment
		(start 313.143138 -89.686638)
		(end 313.652408 -87.325708)
		(width 0.1143)
		(layer "In9.Cu")
		(net "UPI_CPU0_CPU1_P0P0_DN<4>")
	)
	(segment
		(start 310.684164 -74.878438)
		(end 309.461916 -71.882254)
		(width 0.1143)
		(layer "In9.Cu")
		(net "UPI_CPU0_CPU1_P0P0_DN<4>")
	)
	(segment
		(start 147.315936 -63.39205)
		(end 148.57222 -64.096138)
		(width 0.1143)
		(layer "In9.Cu")
		(net "UPI_CPU0_CPU1_P0P0_DN<4>")
	)
	(segment
		(start 266.569952 -110.105444)
		(end 266.569952 -110.10519)
		(width 0.1143)
		(layer "In9.Cu")
		(net "UPI_CPU0_CPU1_P0P0_DN<4>")
	)
	(segment
		(start 309.461916 -71.882254)
		(end 309.208424 -71.628762)
		(width 0.1143)
		(layer "In9.Cu")
		(net "UPI_CPU0_CPU1_P0P0_DN<4>")
	)
	(segment
		(start 292.415722 -105.534714)
		(end 302.891444 -108.209842)
		(width 0.1143)
		(layer "In9.Cu")
		(net "UPI_CPU0_CPU1_P0P0_DN<4>")
	)
	(segment
		(start 144.69364 -63.39205)
		(end 147.315936 -63.39205)
		(width 0.1143)
		(layer "In9.Cu")
		(net "UPI_CPU0_CPU1_P0P0_DN<4>")
	)
	(segment
		(start 312.47842 -92.76842)
		(end 313.143138 -89.686638)
		(width 0.1143)
		(layer "In9.Cu")
		(net "UPI_CPU0_CPU1_P0P0_DN<4>")
	)
	(segment
		(start 139.376658 -63.429134)
		(end 139.409424 -63.429134)
		(width 0.0889)
		(layer "In9.Cu")
		(net "UPI_CPU0_CPU1_P0P0_DN<4>")
	)
	(segment
		(start 310.822594 -79.881476)
		(end 310.821324 -79.8322)
		(width 0.1143)
		(layer "In9.Cu")
		(net "UPI_CPU0_CPU1_P0P0_DN<4>")
	)
	(segment
		(start 227.968556 -108.731812)
		(end 233.657902 -109.700314)
		(width 0.1143)
		(layer "In9.Cu")
		(net "UPI_CPU0_CPU1_P0P0_DN<4>")
	)
	(segment
		(start 144.671542 -63.39205)
		(end 144.69364 -63.39205)
		(width 0.0889)
		(layer "In9.Cu")
		(net "UPI_CPU0_CPU1_P0P0_DN<4>")
	)
	(segment
		(start 291.125402 -105.651554)
		(end 292.415722 -105.534714)
		(width 0.1143)
		(layer "In9.Cu")
		(net "UPI_CPU0_CPU1_P0P0_DN<4>")
	)
	(segment
		(start 148.57222 -64.096138)
		(end 152.916636 -68.675504)
		(width 0.1143)
		(layer "In9.Cu")
		(net "UPI_CPU0_CPU1_P0P0_DN<4>")
	)
	(segment
		(start 306.368196 -107.418378)
		(end 310.05272 -104.013)
		(width 0.1143)
		(layer "In9.Cu")
		(net "UPI_CPU0_CPU1_P0P0_DN<4>")
	)
	(segment
		(start 278.096726 -109.074966)
		(end 281.596084 -109.480604)
		(width 0.1143)
		(layer "In9.Cu")
		(net "UPI_CPU0_CPU1_P0P0_DN<4>")
	)
	(segment
		(start 138.529314 -63.986664)
		(end 138.594592 -63.921386)
		(width 0.0889)
		(layer "In9.Cu")
		(net "UPI_CPU0_CPU1_P0P0_DN<4>")
	)
	(segment
		(start 171.623228 -103.32212)
		(end 175.633888 -104.118918)
		(width 0.1143)
		(layer "In9.Cu")
		(net "UPI_CPU0_CPU1_P0P0_DN<4>")
	)
	(segment
		(start 310.821324 -79.8322)
		(end 310.750712 -77.285342)
		(width 0.1143)
		(layer "In9.Cu")
		(net "UPI_CPU0_CPU1_P0P0_DN<4>")
	)
	(segment
		(start 306.105306 -70.172834)
		(end 306.09413 -70.172834)
		(width 0.0889)
		(layer "In9.Cu")
		(net "UPI_CPU0_CPU1_P0P0_DN<4>")
	)
	(segment
		(start 310.750712 -77.285342)
		(end 310.684164 -74.878438)
		(width 0.1143)
		(layer "In9.Cu")
		(net "UPI_CPU0_CPU1_P0P0_DN<4>")
	)
	(segment
		(start 267.098272 -110.131098)
		(end 278.096726 -109.074966)
		(width 0.1143)
		(layer "In9.Cu")
		(net "UPI_CPU0_CPU1_P0P0_DN<4>")
	)
	(segment
		(start 313.652408 -87.325708)
		(end 311.595516 -81.915)
		(width 0.1143)
		(layer "In9.Cu")
		(net "UPI_CPU0_CPU1_P0P0_DN<4>")
	)
	(segment
		(start 309.208424 -71.628762)
		(end 309.19293 -71.613268)
		(width 0.0889)
		(layer "In9.Cu")
		(net "UPI_CPU0_CPU1_P0P0_DN<4>")
	)
	(segment
		(start 312.260742 -93.7768)
		(end 312.47842 -92.76842)
		(width 0.1143)
		(layer "In9.Cu")
		(net "UPI_CPU0_CPU1_P0P0_DN<4>")
	)
	(segment
		(start 305.268376 -69.677534)
		(end 304.618136 -69.677534)
		(width 0.0889)
		(layer "In9.Cu")
		(net "UPI_CPU0_CPU1_P0P0_DN<4>")
	)
	(segment
		(start 179.481734 -107.437936)
		(end 183.128666 -107.99318)
		(width 0.1143)
		(layer "In9.Cu")
		(net "UPI_CPU0_CPU1_P0P0_DN<4>")
	)
	(segment
		(start 141.093698 -62.438534)
		(end 142.981934 -62.438534)
		(width 0.0889)
		(layer "In9.Cu")
		(net "UPI_CPU0_CPU1_P0P0_DN<4>")
	)
	(segment
		(start 309.120794 -71.613268)
		(end 307.507386 -69.99986)
		(width 0.0889)
		(layer "In9.Cu")
		(net "UPI_CPU0_CPU1_P0P0_DN<4>")
	)
	(segment
		(start 183.128666 -107.99318)
		(end 189.562486 -107.99318)
		(width 0.1143)
		(layer "In9.Cu")
		(net "UPI_CPU0_CPU1_P0P0_DN<4>")
	)
	(segment
		(start 144.620742 -63.34125)
		(end 144.671542 -63.39205)
		(width 0.0889)
		(layer "In9.Cu")
		(net "UPI_CPU0_CPU1_P0P0_DN<4>")
	)
	(segment
		(start 142.981934 -62.438534)
		(end 143.88465 -63.34125)
		(width 0.0889)
		(layer "In9.Cu")
		(net "UPI_CPU0_CPU1_P0P0_DN<4>")
	)
	(segment
		(start 302.891444 -108.209842)
		(end 306.368196 -107.418378)
		(width 0.1143)
		(layer "In9.Cu")
		(net "UPI_CPU0_CPU1_P0P0_DN<4>")
	)
	(segment
		(start 306.580794 -69.99986)
		(end 306.517294 -70.044818)
		(width 0.0889)
		(layer "In9.Cu")
		(net "UPI_CPU0_CPU1_P0P0_DN<4>")
	)
	(segment
		(start 196.341746 -112.186466)
		(end 197.3961 -112.423702)
		(width 0.1143)
		(layer "In9.Cu")
		(net "UPI_CPU0_CPU1_P0P0_DN<4>")
	)
	(segment
		(start 286.644842 -107.384088)
		(end 286.644842 -107.384342)
		(width 0.1143)
		(layer "In9.Cu")
		(net "UPI_CPU0_CPU1_P0P0_DN<4>")
	)
	(segment
		(start 157.642052 -86.102698)
		(end 164.160454 -93.816678)
		(width 0.1143)
		(layer "In9.Cu")
		(net "UPI_CPU0_CPU1_P0P0_DN<4>")
	)
	(arc
		(start 140.264134 -62.934088)
		(mid 140.549558 -62.850621)
		(end 140.758164 -62.638686)
		(width 0.0889)
		(layer "In9.Cu")
		(net "UPI_CPU0_CPU1_P0P0_DN<4>")
	)
	(arc
		(start 306.517294 -70.044818)
		(mid 306.321015 -70.140093)
		(end 306.105306 -70.172834)
		(width 0.0889)
		(layer "In9.Cu")
		(net "UPI_CPU0_CPU1_P0P0_DN<4>")
	)
	(arc
		(start 139.899644 -63.133986)
		(mid 140.039723 -62.99125)
		(end 140.231368 -62.934088)
		(width 0.0889)
		(layer "In9.Cu")
		(net "UPI_CPU0_CPU1_P0P0_DN<4>")
	)
	(arc
		(start 140.758164 -62.638686)
		(mid 140.899847 -62.494882)
		(end 141.093698 -62.438534)
		(width 0.0889)
		(layer "In9.Cu")
		(net "UPI_CPU0_CPU1_P0P0_DN<4>")
	)
	(arc
		(start 139.041124 -63.629286)
		(mid 139.182807 -63.485482)
		(end 139.376658 -63.429134)
		(width 0.0889)
		(layer "In9.Cu")
		(net "UPI_CPU0_CPU1_P0P0_DN<4>")
	)
	(arc
		(start 305.758596 -69.972682)
		(mid 305.551592 -69.761818)
		(end 305.268376 -69.677534)
		(width 0.0889)
		(layer "In9.Cu")
		(net "UPI_CPU0_CPU1_P0P0_DN<4>")
	)
	(arc
		(start 138.594592 -63.921386)
		(mid 138.852729 -63.828632)
		(end 139.041124 -63.629286)
		(width 0.0889)
		(layer "In9.Cu")
		(net "UPI_CPU0_CPU1_P0P0_DN<4>")
	)
	(arc
		(start 304.618136 -69.677534)
		(mid 304.493718 -69.702282)
		(end 304.388266 -69.772784)
		(width 0.0889)
		(layer "In9.Cu")
		(net "UPI_CPU0_CPU1_P0P0_DN<4>")
	)
	(arc
		(start 139.409424 -63.429134)
		(mid 139.692641 -63.344853)
		(end 139.899644 -63.133986)
		(width 0.0889)
		(layer "In9.Cu")
		(net "UPI_CPU0_CPU1_P0P0_DN<4>")
	)
	(arc
		(start 306.09413 -70.172834)
		(mid 305.90028 -70.116484)
		(end 305.758596 -69.972682)
		(width 0.0889)
		(layer "In9.Cu")
		(net "UPI_CPU0_CPU1_P0P0_DN<4>")
	)
	(segment
		(start 304.675286 -71.258938)
		(end 305.246786 -71.258938)
		(width 0.1143)
		(layer "F.Cu")
		(net "UPI_CPU0_CPU1_P0P0_DN<3>")
	)
	(segment
		(start 137.957814 -62.343538)
		(end 138.529314 -62.343538)
		(width 0.1143)
		(layer "F.Cu")
		(net "UPI_CPU0_CPU1_P0P0_DN<3>")
	)
	(via
		(at 138.529314 -62.343538)
		(size 0.508)
		(drill 0.254)
		(layers "F.Cu" "B.Cu")
		(net "UPI_CPU0_CPU1_P0P0_DN<3>")
	)
	(via
		(at 305.246786 -71.258938)
		(size 0.508)
		(drill 0.254)
		(layers "F.Cu" "B.Cu")
		(net "UPI_CPU0_CPU1_P0P0_DN<3>")
	)
	(segment
		(start 309.587138 -75.831192)
		(end 309.430928 -75.686158)
		(width 0.1143)
		(layer "In9.Cu")
		(net "UPI_CPU0_CPU1_P0P0_DN<3>")
	)
	(segment
		(start 148.661628 -62.79007)
		(end 150.00859 -64.137032)
		(width 0.1143)
		(layer "In9.Cu")
		(net "UPI_CPU0_CPU1_P0P0_DN<3>")
	)
	(segment
		(start 148.044916 -62.24524)
		(end 148.574506 -62.77483)
		(width 0.0889)
		(layer "In9.Cu")
		(net "UPI_CPU0_CPU1_P0P0_DN<3>")
	)
	(segment
		(start 212.863684 -109.611668)
		(end 227.991416 -107.79252)
		(width 0.1143)
		(layer "In9.Cu")
		(net "UPI_CPU0_CPU1_P0P0_DN<3>")
	)
	(segment
		(start 306.880768 -70.77075)
		(end 306.748942 -70.883018)
		(width 0.0889)
		(layer "In9.Cu")
		(net "UPI_CPU0_CPU1_P0P0_DN<3>")
	)
	(segment
		(start 165.039802 -93.416374)
		(end 165.340284 -95.36049)
		(width 0.1143)
		(layer "In9.Cu")
		(net "UPI_CPU0_CPU1_P0P0_DN<3>")
	)
	(segment
		(start 309.564532 -79.24927)
		(end 309.709566 -79.093568)
		(width 0.1143)
		(layer "In9.Cu")
		(net "UPI_CPU0_CPU1_P0P0_DN<3>")
	)
	(segment
		(start 290.507674 -104.774238)
		(end 292.490906 -104.594406)
		(width 0.1143)
		(layer "In9.Cu")
		(net "UPI_CPU0_CPU1_P0P0_DN<3>")
	)
	(segment
		(start 309.573168 -79.478378)
		(end 309.564532 -79.24927)
		(width 0.1143)
		(layer "In9.Cu")
		(net "UPI_CPU0_CPU1_P0P0_DN<3>")
	)
	(segment
		(start 307.082952 -70.765416)
		(end 306.880768 -70.77075)
		(width 0.0889)
		(layer "In9.Cu")
		(net "UPI_CPU0_CPU1_P0P0_DN<3>")
	)
	(segment
		(start 179.569618 -104.514142)
		(end 180.946552 -104.894126)
		(width 0.1143)
		(layer "In9.Cu")
		(net "UPI_CPU0_CPU1_P0P0_DN<3>")
	)
	(segment
		(start 248.036334 -105.892854)
		(end 263.120632 -109.004608)
		(width 0.1143)
		(layer "In9.Cu")
		(net "UPI_CPU0_CPU1_P0P0_DN<3>")
	)
	(segment
		(start 140.224764 -61.752988)
		(end 140.260832 -61.752988)
		(width 0.0889)
		(layer "In9.Cu")
		(net "UPI_CPU0_CPU1_P0P0_DN<3>")
	)
	(segment
		(start 140.593064 -61.552836)
		(end 140.725652 -61.322966)
		(width 0.0889)
		(layer "In9.Cu")
		(net "UPI_CPU0_CPU1_P0P0_DN<3>")
	)
	(segment
		(start 142.229332 -60.75807)
		(end 142.695422 -61.22416)
		(width 0.0889)
		(layer "In9.Cu")
		(net "UPI_CPU0_CPU1_P0P0_DN<3>")
	)
	(segment
		(start 308.823614 -73.329038)
		(end 308.256178 -72.11949)
		(width 0.0889)
		(layer "In9.Cu")
		(net "UPI_CPU0_CPU1_P0P0_DN<3>")
	)
	(segment
		(start 309.738014 -79.85633)
		(end 309.729378 -79.623412)
		(width 0.1143)
		(layer "In9.Cu")
		(net "UPI_CPU0_CPU1_P0P0_DN<3>")
	)
	(segment
		(start 302.903382 -107.253532)
		(end 305.91887 -106.567224)
		(width 0.1143)
		(layer "In9.Cu")
		(net "UPI_CPU0_CPU1_P0P0_DN<3>")
	)
	(segment
		(start 309.253636 -74.361548)
		(end 308.808882 -73.416668)
		(width 0.1143)
		(layer "In9.Cu")
		(net "UPI_CPU0_CPU1_P0P0_DN<3>")
	)
	(segment
		(start 142.695422 -61.22416)
		(end 145.135346 -61.22416)
		(width 0.0889)
		(layer "In9.Cu")
		(net "UPI_CPU0_CPU1_P0P0_DN<3>")
	)
	(segment
		(start 308.256178 -72.11949)
		(end 307.334412 -70.874382)
		(width 0.0889)
		(layer "In9.Cu")
		(net "UPI_CPU0_CPU1_P0P0_DN<3>")
	)
	(segment
		(start 309.507636 -77.732382)
		(end 309.65267 -77.57668)
		(width 0.1143)
		(layer "In9.Cu")
		(net "UPI_CPU0_CPU1_P0P0_DN<3>")
	)
	(segment
		(start 139.370054 -62.248034)
		(end 139.40282 -62.248034)
		(width 0.0889)
		(layer "In9.Cu")
		(net "UPI_CPU0_CPU1_P0P0_DN<3>")
	)
	(segment
		(start 305.539902 -71.089774)
		(end 305.246786 -71.258938)
		(width 0.0889)
		(layer "In9.Cu")
		(net "UPI_CPU0_CPU1_P0P0_DN<3>")
	)
	(segment
		(start 309.516272 -77.96149)
		(end 309.507636 -77.732382)
		(width 0.1143)
		(layer "In9.Cu")
		(net "UPI_CPU0_CPU1_P0P0_DN<3>")
	)
	(segment
		(start 212.863684 -109.611922)
		(end 212.863684 -109.611668)
		(width 0.1143)
		(layer "In9.Cu")
		(net "UPI_CPU0_CPU1_P0P0_DN<3>")
	)
	(segment
		(start 309.567834 -75.301348)
		(end 309.558944 -75.00874)
		(width 0.1143)
		(layer "In9.Cu")
		(net "UPI_CPU0_CPU1_P0P0_DN<3>")
	)
	(segment
		(start 309.709566 -79.093568)
		(end 309.70093 -78.864968)
		(width 0.1143)
		(layer "In9.Cu")
		(net "UPI_CPU0_CPU1_P0P0_DN<3>")
	)
	(segment
		(start 292.490906 -104.594406)
		(end 302.903382 -107.253532)
		(width 0.1143)
		(layer "In9.Cu")
		(net "UPI_CPU0_CPU1_P0P0_DN<3>")
	)
	(segment
		(start 227.991416 -107.79252)
		(end 233.645964 -108.754672)
		(width 0.1143)
		(layer "In9.Cu")
		(net "UPI_CPU0_CPU1_P0P0_DN<3>")
	)
	(segment
		(start 197.735444 -111.431578)
		(end 212.863684 -109.611922)
		(width 0.1143)
		(layer "In9.Cu")
		(net "UPI_CPU0_CPU1_P0P0_DN<3>")
	)
	(segment
		(start 309.615586 -76.589636)
		(end 309.459376 -76.444602)
		(width 0.1143)
		(layer "In9.Cu")
		(net "UPI_CPU0_CPU1_P0P0_DN<3>")
	)
	(segment
		(start 196.58203 -111.15802)
		(end 197.735444 -111.431578)
		(width 0.1143)
		(layer "In9.Cu")
		(net "UPI_CPU0_CPU1_P0P0_DN<3>")
	)
	(segment
		(start 309.479188 -76.973938)
		(end 309.624222 -76.818236)
		(width 0.1143)
		(layer "In9.Cu")
		(net "UPI_CPU0_CPU1_P0P0_DN<3>")
	)
	(segment
		(start 309.430928 -75.686158)
		(end 309.422292 -75.45705)
		(width 0.1143)
		(layer "In9.Cu")
		(net "UPI_CPU0_CPU1_P0P0_DN<3>")
	)
	(segment
		(start 309.45074 -76.215494)
		(end 309.595774 -76.059792)
		(width 0.1143)
		(layer "In9.Cu")
		(net "UPI_CPU0_CPU1_P0P0_DN<3>")
	)
	(segment
		(start 140.924788 -61.12383)
		(end 141.807946 -60.75807)
		(width 0.0889)
		(layer "In9.Cu")
		(net "UPI_CPU0_CPU1_P0P0_DN<3>")
	)
	(segment
		(start 309.65267 -77.57668)
		(end 309.644034 -77.34808)
		(width 0.1143)
		(layer "In9.Cu")
		(net "UPI_CPU0_CPU1_P0P0_DN<3>")
	)
	(segment
		(start 145.511266 -61.60135)
		(end 145.57121 -61.60135)
		(width 0.0889)
		(layer "In9.Cu")
		(net "UPI_CPU0_CPU1_P0P0_DN<3>")
	)
	(segment
		(start 138.529314 -62.343538)
		(end 138.82243 -62.512448)
		(width 0.0889)
		(layer "In9.Cu")
		(net "UPI_CPU0_CPU1_P0P0_DN<3>")
	)
	(segment
		(start 309.46725 -74.814684)
		(end 309.286148 -74.749914)
		(width 0.1143)
		(layer "In9.Cu")
		(net "UPI_CPU0_CPU1_P0P0_DN<3>")
	)
	(segment
		(start 145.57121 -61.60135)
		(end 146.2151 -62.24524)
		(width 0.0889)
		(layer "In9.Cu")
		(net "UPI_CPU0_CPU1_P0P0_DN<3>")
	)
	(segment
		(start 150.00859 -64.137032)
		(end 153.727658 -68.110862)
		(width 0.1143)
		(layer "In9.Cu")
		(net "UPI_CPU0_CPU1_P0P0_DN<3>")
	)
	(segment
		(start 138.82243 -62.512448)
		(end 138.911838 -62.488318)
		(width 0.0889)
		(layer "In9.Cu")
		(net "UPI_CPU0_CPU1_P0P0_DN<3>")
	)
	(segment
		(start 165.340284 -95.36049)
		(end 172.164756 -102.481888)
		(width 0.1143)
		(layer "In9.Cu")
		(net "UPI_CPU0_CPU1_P0P0_DN<3>")
	)
	(segment
		(start 153.727658 -68.110862)
		(end 158.48584 -85.66023)
		(width 0.1143)
		(layer "In9.Cu")
		(net "UPI_CPU0_CPU1_P0P0_DN<3>")
	)
	(segment
		(start 267.076428 -109.198918)
		(end 278.105362 -108.139738)
		(width 0.1143)
		(layer "In9.Cu")
		(net "UPI_CPU0_CPU1_P0P0_DN<3>")
	)
	(segment
		(start 309.558944 -75.00874)
		(end 309.46725 -74.814684)
		(width 0.1143)
		(layer "In9.Cu")
		(net "UPI_CPU0_CPU1_P0P0_DN<3>")
	)
	(segment
		(start 233.645964 -108.754672)
		(end 248.036334 -105.892854)
		(width 0.1143)
		(layer "In9.Cu")
		(net "UPI_CPU0_CPU1_P0P0_DN<3>")
	)
	(segment
		(start 309.624222 -76.818236)
		(end 309.615586 -76.589636)
		(width 0.1143)
		(layer "In9.Cu")
		(net "UPI_CPU0_CPU1_P0P0_DN<3>")
	)
	(segment
		(start 309.536084 -78.490826)
		(end 309.681118 -78.335124)
		(width 0.1143)
		(layer "In9.Cu")
		(net "UPI_CPU0_CPU1_P0P0_DN<3>")
	)
	(segment
		(start 281.46375 -108.52912)
		(end 290.507674 -104.774238)
		(width 0.1143)
		(layer "In9.Cu")
		(net "UPI_CPU0_CPU1_P0P0_DN<3>")
	)
	(segment
		(start 278.105362 -108.139738)
		(end 281.46375 -108.52912)
		(width 0.1143)
		(layer "In9.Cu")
		(net "UPI_CPU0_CPU1_P0P0_DN<3>")
	)
	(segment
		(start 145.135346 -61.22416)
		(end 145.511266 -61.60135)
		(width 0.0889)
		(layer "In9.Cu")
		(net "UPI_CPU0_CPU1_P0P0_DN<3>")
	)
	(segment
		(start 309.644034 -77.34808)
		(end 309.487824 -77.203046)
		(width 0.1143)
		(layer "In9.Cu")
		(net "UPI_CPU0_CPU1_P0P0_DN<3>")
	)
	(segment
		(start 309.188358 -74.54265)
		(end 309.253636 -74.361548)
		(width 0.1143)
		(layer "In9.Cu")
		(net "UPI_CPU0_CPU1_P0P0_DN<3>")
	)
	(segment
		(start 309.54472 -78.719934)
		(end 309.536084 -78.490826)
		(width 0.1143)
		(layer "In9.Cu")
		(net "UPI_CPU0_CPU1_P0P0_DN<3>")
	)
	(segment
		(start 172.164756 -102.481888)
		(end 176.306988 -103.304594)
		(width 0.1143)
		(layer "In9.Cu")
		(net "UPI_CPU0_CPU1_P0P0_DN<3>")
	)
	(segment
		(start 180.946552 -104.894126)
		(end 182.993792 -106.286046)
		(width 0.1143)
		(layer "In9.Cu")
		(net "UPI_CPU0_CPU1_P0P0_DN<3>")
	)
	(segment
		(start 309.729378 -79.623412)
		(end 309.573168 -79.478378)
		(width 0.1143)
		(layer "In9.Cu")
		(net "UPI_CPU0_CPU1_P0P0_DN<3>")
	)
	(segment
		(start 312.656474 -87.532972)
		(end 309.738014 -79.85633)
		(width 0.1143)
		(layer "In9.Cu")
		(net "UPI_CPU0_CPU1_P0P0_DN<3>")
	)
	(segment
		(start 306.748942 -70.883018)
		(end 306.656994 -71.055992)
		(width 0.0889)
		(layer "In9.Cu")
		(net "UPI_CPU0_CPU1_P0P0_DN<3>")
	)
	(segment
		(start 158.48584 -85.66023)
		(end 165.039802 -93.416374)
		(width 0.1143)
		(layer "In9.Cu")
		(net "UPI_CPU0_CPU1_P0P0_DN<3>")
	)
	(segment
		(start 309.422292 -75.45705)
		(end 309.567834 -75.301348)
		(width 0.1143)
		(layer "In9.Cu")
		(net "UPI_CPU0_CPU1_P0P0_DN<3>")
	)
	(segment
		(start 309.681118 -78.335124)
		(end 309.672482 -78.106524)
		(width 0.1143)
		(layer "In9.Cu")
		(net "UPI_CPU0_CPU1_P0P0_DN<3>")
	)
	(segment
		(start 308.808628 -73.41616)
		(end 308.823614 -73.329038)
		(width 0.0889)
		(layer "In9.Cu")
		(net "UPI_CPU0_CPU1_P0P0_DN<3>")
	)
	(segment
		(start 148.661628 -62.789816)
		(end 148.661628 -62.79007)
		(width 0.0889)
		(layer "In9.Cu")
		(net "UPI_CPU0_CPU1_P0P0_DN<3>")
	)
	(segment
		(start 309.487824 -77.203046)
		(end 309.479188 -76.973938)
		(width 0.1143)
		(layer "In9.Cu")
		(net "UPI_CPU0_CPU1_P0P0_DN<3>")
	)
	(segment
		(start 148.574506 -62.77483)
		(end 148.646642 -62.77483)
		(width 0.0889)
		(layer "In9.Cu")
		(net "UPI_CPU0_CPU1_P0P0_DN<3>")
	)
	(segment
		(start 182.993792 -106.286046)
		(end 191.896746 -107.370372)
		(width 0.1143)
		(layer "In9.Cu")
		(net "UPI_CPU0_CPU1_P0P0_DN<3>")
	)
	(segment
		(start 141.807946 -60.75807)
		(end 142.229332 -60.75807)
		(width 0.0889)
		(layer "In9.Cu")
		(net "UPI_CPU0_CPU1_P0P0_DN<3>")
	)
	(segment
		(start 306.308506 -71.353934)
		(end 306.083716 -71.353934)
		(width 0.0889)
		(layer "In9.Cu")
		(net "UPI_CPU0_CPU1_P0P0_DN<3>")
	)
	(segment
		(start 309.672482 -78.106524)
		(end 309.516272 -77.96149)
		(width 0.1143)
		(layer "In9.Cu")
		(net "UPI_CPU0_CPU1_P0P0_DN<3>")
	)
	(segment
		(start 140.725652 -61.322966)
		(end 140.924788 -61.12383)
		(width 0.0889)
		(layer "In9.Cu")
		(net "UPI_CPU0_CPU1_P0P0_DN<3>")
	)
	(segment
		(start 309.70093 -78.864968)
		(end 309.54472 -78.719934)
		(width 0.1143)
		(layer "In9.Cu")
		(net "UPI_CPU0_CPU1_P0P0_DN<3>")
	)
	(segment
		(start 305.91887 -106.567224)
		(end 309.20563 -103.529892)
		(width 0.1143)
		(layer "In9.Cu")
		(net "UPI_CPU0_CPU1_P0P0_DN<3>")
	)
	(segment
		(start 309.20563 -103.529892)
		(end 312.656474 -87.532972)
		(width 0.1143)
		(layer "In9.Cu")
		(net "UPI_CPU0_CPU1_P0P0_DN<3>")
	)
	(segment
		(start 146.2151 -62.24524)
		(end 148.044916 -62.24524)
		(width 0.0889)
		(layer "In9.Cu")
		(net "UPI_CPU0_CPU1_P0P0_DN<3>")
	)
	(segment
		(start 309.459376 -76.444602)
		(end 309.45074 -76.215494)
		(width 0.1143)
		(layer "In9.Cu")
		(net "UPI_CPU0_CPU1_P0P0_DN<3>")
	)
	(segment
		(start 263.120632 -109.004608)
		(end 267.076428 -109.198918)
		(width 0.1143)
		(layer "In9.Cu")
		(net "UPI_CPU0_CPU1_P0P0_DN<3>")
	)
	(segment
		(start 177.640996 -104.413812)
		(end 179.569618 -104.514142)
		(width 0.1143)
		(layer "In9.Cu")
		(net "UPI_CPU0_CPU1_P0P0_DN<3>")
	)
	(segment
		(start 305.62931 -71.113904)
		(end 305.539902 -71.089774)
		(width 0.0889)
		(layer "In9.Cu")
		(net "UPI_CPU0_CPU1_P0P0_DN<3>")
	)
	(segment
		(start 191.896746 -107.370372)
		(end 196.58203 -111.15802)
		(width 0.1143)
		(layer "In9.Cu")
		(net "UPI_CPU0_CPU1_P0P0_DN<3>")
	)
	(segment
		(start 148.646642 -62.77483)
		(end 148.661628 -62.789816)
		(width 0.0889)
		(layer "In9.Cu")
		(net "UPI_CPU0_CPU1_P0P0_DN<3>")
	)
	(segment
		(start 308.808882 -73.416668)
		(end 308.808628 -73.41616)
		(width 0.1143)
		(layer "In9.Cu")
		(net "UPI_CPU0_CPU1_P0P0_DN<3>")
	)
	(segment
		(start 307.334412 -70.874382)
		(end 307.082952 -70.765416)
		(width 0.0889)
		(layer "In9.Cu")
		(net "UPI_CPU0_CPU1_P0P0_DN<3>")
	)
	(segment
		(start 176.306988 -103.304594)
		(end 177.640996 -104.413812)
		(width 0.1143)
		(layer "In9.Cu")
		(net "UPI_CPU0_CPU1_P0P0_DN<3>")
	)
	(segment
		(start 309.286148 -74.749914)
		(end 309.188358 -74.54265)
		(width 0.1143)
		(layer "In9.Cu")
		(net "UPI_CPU0_CPU1_P0P0_DN<3>")
	)
	(segment
		(start 309.595774 -76.059792)
		(end 309.587138 -75.831192)
		(width 0.1143)
		(layer "In9.Cu")
		(net "UPI_CPU0_CPU1_P0P0_DN<3>")
	)
	(arc
		(start 306.083716 -71.353934)
		(mid 305.829051 -71.285905)
		(end 305.62931 -71.113904)
		(width 0.0889)
		(layer "In9.Cu")
		(net "UPI_CPU0_CPU1_P0P0_DN<3>")
	)
	(arc
		(start 138.911838 -62.488318)
		(mid 139.113248 -62.315365)
		(end 139.370054 -62.248034)
		(width 0.0889)
		(layer "In9.Cu")
		(net "UPI_CPU0_CPU1_P0P0_DN<3>")
	)
	(arc
		(start 140.260832 -61.752988)
		(mid 140.452849 -61.69588)
		(end 140.593064 -61.552836)
		(width 0.0889)
		(layer "In9.Cu")
		(net "UPI_CPU0_CPU1_P0P0_DN<3>")
	)
	(arc
		(start 139.734544 -62.048136)
		(mid 139.941548 -61.837272)
		(end 140.224764 -61.752988)
		(width 0.0889)
		(layer "In9.Cu")
		(net "UPI_CPU0_CPU1_P0P0_DN<3>")
	)
	(arc
		(start 306.656994 -71.055992)
		(mid 306.511069 -71.238079)
		(end 306.308506 -71.353934)
		(width 0.0889)
		(layer "In9.Cu")
		(net "UPI_CPU0_CPU1_P0P0_DN<3>")
	)
	(arc
		(start 139.40282 -62.248034)
		(mid 139.594462 -62.190868)
		(end 139.734544 -62.048136)
		(width 0.0889)
		(layer "In9.Cu")
		(net "UPI_CPU0_CPU1_P0P0_DN<3>")
	)
	(segment
		(start 305.533806 -71.753984)
		(end 306.105306 -71.753984)
		(width 0.1143)
		(layer "F.Cu")
		(net "UPI_CPU0_CPU1_P0P0_DN<2>")
	)
	(segment
		(start 137.099294 -61.847984)
		(end 137.670794 -61.847984)
		(width 0.1143)
		(layer "F.Cu")
		(net "UPI_CPU0_CPU1_P0P0_DN<2>")
	)
	(via
		(at 306.105306 -71.753984)
		(size 0.508)
		(drill 0.254)
		(layers "F.Cu" "B.Cu")
		(net "UPI_CPU0_CPU1_P0P0_DN<2>")
	)
	(via
		(at 137.670794 -61.847984)
		(size 0.508)
		(drill 0.254)
		(layers "F.Cu" "B.Cu")
		(net "UPI_CPU0_CPU1_P0P0_DN<2>")
	)
	(segment
		(start 263.17067 -108.6612)
		(end 267.0683 -108.852462)
		(width 0.1143)
		(layer "In9.Cu")
		(net "UPI_CPU0_CPU1_P0P0_DN<2>")
	)
	(segment
		(start 308.65953 -75.311)
		(end 308.65953 -75.288902)
		(width 0.0889)
		(layer "In9.Cu")
		(net "UPI_CPU0_CPU1_P0P0_DN<2>")
	)
	(segment
		(start 308.65953 -75.847702)
		(end 308.65953 -75.311)
		(width 0.1143)
		(layer "In9.Cu")
		(net "UPI_CPU0_CPU1_P0P0_DN<2>")
	)
	(segment
		(start 309.161942 -79.52232)
		(end 308.65953 -75.847702)
		(width 0.1143)
		(layer "In9.Cu")
		(net "UPI_CPU0_CPU1_P0P0_DN<2>")
	)
	(segment
		(start 139.376658 -61.447934)
		(end 139.409424 -61.447934)
		(width 0.0889)
		(layer "In9.Cu")
		(net "UPI_CPU0_CPU1_P0P0_DN<2>")
	)
	(segment
		(start 179.661058 -104.17302)
		(end 181.163214 -104.555544)
		(width 0.1143)
		(layer "In9.Cu")
		(net "UPI_CPU0_CPU1_P0P0_DN<2>")
	)
	(segment
		(start 278.10841 -107.792266)
		(end 281.414474 -108.175552)
		(width 0.1143)
		(layer "In9.Cu")
		(net "UPI_CPU0_CPU1_P0P0_DN<2>")
	)
	(segment
		(start 144.069562 -60.740798)
		(end 145.203672 -60.740798)
		(width 0.0889)
		(layer "In9.Cu")
		(net "UPI_CPU0_CPU1_P0P0_DN<2>")
	)
	(segment
		(start 147.393914 -61.86805)
		(end 147.416012 -61.86805)
		(width 0.0889)
		(layer "In9.Cu")
		(net "UPI_CPU0_CPU1_P0P0_DN<2>")
	)
	(segment
		(start 140.60297 -60.952888)
		(end 141.085062 -60.470796)
		(width 0.0889)
		(layer "In9.Cu")
		(net "UPI_CPU0_CPU1_P0P0_DN<2>")
	)
	(segment
		(start 281.414474 -108.175552)
		(end 290.424108 -104.434894)
		(width 0.1143)
		(layer "In9.Cu")
		(net "UPI_CPU0_CPU1_P0P0_DN<2>")
	)
	(segment
		(start 307.363114 -71.658988)
		(end 306.879498 -71.658988)
		(width 0.0889)
		(layer "In9.Cu")
		(net "UPI_CPU0_CPU1_P0P0_DN<2>")
	)
	(segment
		(start 141.085062 -60.470796)
		(end 142.331186 -60.470796)
		(width 0.0889)
		(layer "In9.Cu")
		(net "UPI_CPU0_CPU1_P0P0_DN<2>")
	)
	(segment
		(start 228.001322 -107.443778)
		(end 230.773224 -107.915456)
		(width 0.1143)
		(layer "In9.Cu")
		(net "UPI_CPU0_CPU1_P0P0_DN<2>")
	)
	(segment
		(start 292.518592 -104.245156)
		(end 302.908462 -106.89844)
		(width 0.1143)
		(layer "In9.Cu")
		(net "UPI_CPU0_CPU1_P0P0_DN<2>")
	)
	(segment
		(start 230.773224 -107.915964)
		(end 233.63936 -108.40339)
		(width 0.1143)
		(layer "In9.Cu")
		(net "UPI_CPU0_CPU1_P0P0_DN<2>")
	)
	(segment
		(start 148.39569 -61.86805)
		(end 153.94305 -67.584574)
		(width 0.1143)
		(layer "In9.Cu")
		(net "UPI_CPU0_CPU1_P0P0_DN<2>")
	)
	(segment
		(start 267.0683 -108.852462)
		(end 278.10841 -107.792266)
		(width 0.1143)
		(layer "In9.Cu")
		(net "UPI_CPU0_CPU1_P0P0_DN<2>")
	)
	(segment
		(start 145.203672 -60.740798)
		(end 146.280124 -61.81725)
		(width 0.0889)
		(layer "In9.Cu")
		(net "UPI_CPU0_CPU1_P0P0_DN<2>")
	)
	(segment
		(start 308.89067 -103.350568)
		(end 312.269124 -87.695024)
		(width 0.1143)
		(layer "In9.Cu")
		(net "UPI_CPU0_CPU1_P0P0_DN<2>")
	)
	(segment
		(start 172.403008 -102.177088)
		(end 176.460404 -102.982776)
		(width 0.1143)
		(layer "In9.Cu")
		(net "UPI_CPU0_CPU1_P0P0_DN<2>")
	)
	(segment
		(start 307.736748 -72.032622)
		(end 307.363114 -71.658988)
		(width 0.0889)
		(layer "In9.Cu")
		(net "UPI_CPU0_CPU1_P0P0_DN<2>")
	)
	(segment
		(start 165.654482 -95.134938)
		(end 172.403008 -102.177088)
		(width 0.1143)
		(layer "In9.Cu")
		(net "UPI_CPU0_CPU1_P0P0_DN<2>")
	)
	(segment
		(start 142.77975 -60.91936)
		(end 143.891 -60.91936)
		(width 0.0889)
		(layer "In9.Cu")
		(net "UPI_CPU0_CPU1_P0P0_DN<2>")
	)
	(segment
		(start 140.231368 -60.952888)
		(end 140.60297 -60.952888)
		(width 0.0889)
		(layer "In9.Cu")
		(net "UPI_CPU0_CPU1_P0P0_DN<2>")
	)
	(segment
		(start 158.799784 -85.497162)
		(end 165.365684 -93.26753)
		(width 0.1143)
		(layer "In9.Cu")
		(net "UPI_CPU0_CPU1_P0P0_DN<2>")
	)
	(segment
		(start 146.280124 -61.81725)
		(end 147.343114 -61.81725)
		(width 0.0889)
		(layer "In9.Cu")
		(net "UPI_CPU0_CPU1_P0P0_DN<2>")
	)
	(segment
		(start 196.390514 -109.964982)
		(end 199.966834 -110.814866)
		(width 0.1143)
		(layer "In9.Cu")
		(net "UPI_CPU0_CPU1_P0P0_DN<2>")
	)
	(segment
		(start 138.511534 -61.943488)
		(end 138.547094 -61.943488)
		(width 0.0889)
		(layer "In9.Cu")
		(net "UPI_CPU0_CPU1_P0P0_DN<2>")
	)
	(segment
		(start 183.22671 -106.019092)
		(end 192.02781 -107.089194)
		(width 0.1143)
		(layer "In9.Cu")
		(net "UPI_CPU0_CPU1_P0P0_DN<2>")
	)
	(segment
		(start 308.65953 -75.288902)
		(end 308.60873 -75.238102)
		(width 0.0889)
		(layer "In9.Cu")
		(net "UPI_CPU0_CPU1_P0P0_DN<2>")
	)
	(segment
		(start 165.365684 -93.26753)
		(end 165.654482 -95.134938)
		(width 0.1143)
		(layer "In9.Cu")
		(net "UPI_CPU0_CPU1_P0P0_DN<2>")
	)
	(segment
		(start 290.424108 -104.434894)
		(end 292.518592 -104.245156)
		(width 0.1143)
		(layer "In9.Cu")
		(net "UPI_CPU0_CPU1_P0P0_DN<2>")
	)
	(segment
		(start 248.037604 -105.540302)
		(end 263.17067 -108.6612)
		(width 0.1143)
		(layer "In9.Cu")
		(net "UPI_CPU0_CPU1_P0P0_DN<2>")
	)
	(segment
		(start 305.752754 -106.25074)
		(end 308.89067 -103.350568)
		(width 0.1143)
		(layer "In9.Cu")
		(net "UPI_CPU0_CPU1_P0P0_DN<2>")
	)
	(segment
		(start 312.269124 -87.695024)
		(end 309.161942 -79.52232)
		(width 0.1143)
		(layer "In9.Cu")
		(net "UPI_CPU0_CPU1_P0P0_DN<2>")
	)
	(segment
		(start 176.460404 -102.982776)
		(end 176.46015 -102.982776)
		(width 0.1143)
		(layer "In9.Cu")
		(net "UPI_CPU0_CPU1_P0P0_DN<2>")
	)
	(segment
		(start 230.773224 -107.915456)
		(end 230.773224 -107.915964)
		(width 0.1143)
		(layer "In9.Cu")
		(net "UPI_CPU0_CPU1_P0P0_DN<2>")
	)
	(segment
		(start 308.60873 -74.119994)
		(end 307.736748 -72.032622)
		(width 0.0889)
		(layer "In9.Cu")
		(net "UPI_CPU0_CPU1_P0P0_DN<2>")
	)
	(segment
		(start 147.416012 -61.86805)
		(end 148.39569 -61.86805)
		(width 0.1143)
		(layer "In9.Cu")
		(net "UPI_CPU0_CPU1_P0P0_DN<2>")
	)
	(segment
		(start 176.46015 -102.982776)
		(end 177.77333 -104.07523)
		(width 0.1143)
		(layer "In9.Cu")
		(net "UPI_CPU0_CPU1_P0P0_DN<2>")
	)
	(segment
		(start 308.60873 -75.238102)
		(end 308.60873 -74.119994)
		(width 0.0889)
		(layer "In9.Cu")
		(net "UPI_CPU0_CPU1_P0P0_DN<2>")
	)
	(segment
		(start 199.966834 -110.814866)
		(end 228.001322 -107.443778)
		(width 0.1143)
		(layer "In9.Cu")
		(net "UPI_CPU0_CPU1_P0P0_DN<2>")
	)
	(segment
		(start 302.908462 -106.89844)
		(end 305.752754 -106.25074)
		(width 0.1143)
		(layer "In9.Cu")
		(net "UPI_CPU0_CPU1_P0P0_DN<2>")
	)
	(segment
		(start 192.02781 -107.089194)
		(end 196.390514 -109.964982)
		(width 0.1143)
		(layer "In9.Cu")
		(net "UPI_CPU0_CPU1_P0P0_DN<2>")
	)
	(segment
		(start 233.63936 -108.40339)
		(end 248.037604 -105.540302)
		(width 0.1143)
		(layer "In9.Cu")
		(net "UPI_CPU0_CPU1_P0P0_DN<2>")
	)
	(segment
		(start 306.484274 -71.753984)
		(end 306.105306 -71.753984)
		(width 0.0889)
		(layer "In9.Cu")
		(net "UPI_CPU0_CPU1_P0P0_DN<2>")
	)
	(segment
		(start 142.331186 -60.470796)
		(end 142.77975 -60.91936)
		(width 0.0889)
		(layer "In9.Cu")
		(net "UPI_CPU0_CPU1_P0P0_DN<2>")
	)
	(segment
		(start 153.94305 -67.584574)
		(end 158.799784 -85.497162)
		(width 0.1143)
		(layer "In9.Cu")
		(net "UPI_CPU0_CPU1_P0P0_DN<2>")
	)
	(segment
		(start 147.343114 -61.81725)
		(end 147.393914 -61.86805)
		(width 0.0889)
		(layer "In9.Cu")
		(net "UPI_CPU0_CPU1_P0P0_DN<2>")
	)
	(segment
		(start 181.163214 -104.555544)
		(end 183.22671 -106.019092)
		(width 0.1143)
		(layer "In9.Cu")
		(net "UPI_CPU0_CPU1_P0P0_DN<2>")
	)
	(segment
		(start 143.891 -60.91936)
		(end 144.069562 -60.740798)
		(width 0.0889)
		(layer "In9.Cu")
		(net "UPI_CPU0_CPU1_P0P0_DN<2>")
	)
	(segment
		(start 177.77333 -104.07523)
		(end 179.661058 -104.17302)
		(width 0.1143)
		(layer "In9.Cu")
		(net "UPI_CPU0_CPU1_P0P0_DN<2>")
	)
	(arc
		(start 138.547094 -61.943488)
		(mid 138.832518 -61.860021)
		(end 139.041124 -61.648086)
		(width 0.0889)
		(layer "In9.Cu")
		(net "UPI_CPU0_CPU1_P0P0_DN<2>")
	)
	(arc
		(start 306.879498 -71.658988)
		(mid 306.788198 -71.669807)
		(end 306.701952 -71.70166)
		(width 0.0889)
		(layer "In9.Cu")
		(net "UPI_CPU0_CPU1_P0P0_DN<2>")
	)
	(arc
		(start 137.670794 -61.847984)
		(mid 137.977154 -61.809475)
		(end 138.276076 -61.886846)
		(width 0.0889)
		(layer "In9.Cu")
		(net "UPI_CPU0_CPU1_P0P0_DN<2>")
	)
	(arc
		(start 139.899644 -61.152786)
		(mid 140.039723 -61.01005)
		(end 140.231368 -60.952888)
		(width 0.0889)
		(layer "In9.Cu")
		(net "UPI_CPU0_CPU1_P0P0_DN<2>")
	)
	(arc
		(start 139.041124 -61.648086)
		(mid 139.182807 -61.504282)
		(end 139.376658 -61.447934)
		(width 0.0889)
		(layer "In9.Cu")
		(net "UPI_CPU0_CPU1_P0P0_DN<2>")
	)
	(arc
		(start 306.701952 -71.70166)
		(mid 306.596212 -71.740712)
		(end 306.484274 -71.753984)
		(width 0.0889)
		(layer "In9.Cu")
		(net "UPI_CPU0_CPU1_P0P0_DN<2>")
	)
	(arc
		(start 139.409424 -61.447934)
		(mid 139.692641 -61.363653)
		(end 139.899644 -61.152786)
		(width 0.0889)
		(layer "In9.Cu")
		(net "UPI_CPU0_CPU1_P0P0_DN<2>")
	)
	(arc
		(start 138.276076 -61.886846)
		(mid 138.390872 -61.927362)
		(end 138.511534 -61.943488)
		(width 0.0889)
		(layer "In9.Cu")
		(net "UPI_CPU0_CPU1_P0P0_DN<2>")
	)
	(segment
		(start 305.533806 -73.735184)
		(end 306.181506 -73.735184)
		(width 0.1143)
		(layer "F.Cu")
		(net "UPI_CPU0_CPU1_P0P0_DN<1>")
	)
	(segment
		(start 136.240774 -61.352938)
		(end 136.812274 -61.352938)
		(width 0.1143)
		(layer "F.Cu")
		(net "UPI_CPU0_CPU1_P0P0_DN<1>")
	)
	(via
		(at 306.181506 -73.735184)
		(size 0.508)
		(drill 0.254)
		(layers "F.Cu" "B.Cu")
		(net "UPI_CPU0_CPU1_P0P0_DN<1>")
	)
	(via
		(at 136.812274 -61.352938)
		(size 0.508)
		(drill 0.254)
		(layers "F.Cu" "B.Cu")
		(net "UPI_CPU0_CPU1_P0P0_DN<1>")
	)
	(segment
		(start 309.226712 -82.65541)
		(end 309.225188 -82.650838)
		(width 0.1143)
		(layer "In9.Cu")
		(net "UPI_CPU0_CPU1_P0P0_DN<1>")
	)
	(segment
		(start 145.605246 -60.054998)
		(end 146.370548 -60.8203)
		(width 0.0889)
		(layer "In9.Cu")
		(net "UPI_CPU0_CPU1_P0P0_DN<1>")
	)
	(segment
		(start 147.057872 -60.7695)
		(end 147.07997 -60.7695)
		(width 0.0889)
		(layer "In9.Cu")
		(net "UPI_CPU0_CPU1_P0P0_DN<1>")
	)
	(segment
		(start 183.68518 -105.186734)
		(end 192.549272 -106.26471)
		(width 0.1143)
		(layer "In9.Cu")
		(net "UPI_CPU0_CPU1_P0P0_DN<1>")
	)
	(segment
		(start 310.45531 -85.888322)
		(end 310.454802 -85.886798)
		(width 0.1143)
		(layer "In9.Cu")
		(net "UPI_CPU0_CPU1_P0P0_DN<1>")
	)
	(segment
		(start 147.07997 -60.7695)
		(end 148.856192 -60.7695)
		(width 0.1143)
		(layer "In9.Cu")
		(net "UPI_CPU0_CPU1_P0P0_DN<1>")
	)
	(segment
		(start 308.979316 -82.003646)
		(end 308.828186 -81.936082)
		(width 0.1143)
		(layer "In9.Cu")
		(net "UPI_CPU0_CPU1_P0P0_DN<1>")
	)
	(segment
		(start 310.303418 -85.819234)
		(end 310.222138 -85.605112)
		(width 0.1143)
		(layer "In9.Cu")
		(net "UPI_CPU0_CPU1_P0P0_DN<1>")
	)
	(segment
		(start 310.210962 -85.246464)
		(end 310.208676 -85.239606)
		(width 0.1143)
		(layer "In9.Cu")
		(net "UPI_CPU0_CPU1_P0P0_DN<1>")
	)
	(segment
		(start 309.730394 -84.310728)
		(end 309.798466 -84.159598)
		(width 0.1143)
		(layer "In9.Cu")
		(net "UPI_CPU0_CPU1_P0P0_DN<1>")
	)
	(segment
		(start 308.746906 -81.72196)
		(end 308.814978 -81.57083)
		(width 0.1143)
		(layer "In9.Cu")
		(net "UPI_CPU0_CPU1_P0P0_DN<1>")
	)
	(segment
		(start 309.716932 -83.945222)
		(end 309.565802 -83.877658)
		(width 0.1143)
		(layer "In9.Cu")
		(net "UPI_CPU0_CPU1_P0P0_DN<1>")
	)
	(segment
		(start 306.657248 -73.421748)
		(end 306.494942 -73.421748)
		(width 0.1143)
		(layer "In9.Cu")
		(net "UPI_CPU0_CPU1_P0P0_DN<1>")
	)
	(segment
		(start 308.992778 -82.369152)
		(end 309.06085 -82.218022)
		(width 0.1143)
		(layer "In9.Cu")
		(net "UPI_CPU0_CPU1_P0P0_DN<1>")
	)
	(segment
		(start 305.43246 -105.28046)
		(end 308.043834 -102.866698)
		(width 0.1143)
		(layer "In9.Cu")
		(net "UPI_CPU0_CPU1_P0P0_DN<1>")
	)
	(segment
		(start 199.920352 -109.883956)
		(end 228.024182 -106.504486)
		(width 0.1143)
		(layer "In9.Cu")
		(net "UPI_CPU0_CPU1_P0P0_DN<1>")
	)
	(segment
		(start 310.454802 -85.886798)
		(end 310.303418 -85.819234)
		(width 0.1143)
		(layer "In9.Cu")
		(net "UPI_CPU0_CPU1_P0P0_DN<1>")
	)
	(segment
		(start 310.222138 -85.605112)
		(end 310.29021 -85.453982)
		(width 0.1143)
		(layer "In9.Cu")
		(net "UPI_CPU0_CPU1_P0P0_DN<1>")
	)
	(segment
		(start 309.306722 -82.865214)
		(end 309.226712 -82.65541)
		(width 0.1143)
		(layer "In9.Cu")
		(net "UPI_CPU0_CPU1_P0P0_DN<1>")
	)
	(segment
		(start 309.962804 -84.592414)
		(end 309.811674 -84.52485)
		(width 0.1143)
		(layer "In9.Cu")
		(net "UPI_CPU0_CPU1_P0P0_DN<1>")
	)
	(segment
		(start 147.007072 -60.8203)
		(end 147.057872 -60.7695)
		(width 0.0889)
		(layer "In9.Cu")
		(net "UPI_CPU0_CPU1_P0P0_DN<1>")
	)
	(segment
		(start 281.281886 -107.223814)
		(end 290.198556 -103.521764)
		(width 0.1143)
		(layer "In9.Cu")
		(net "UPI_CPU0_CPU1_P0P0_DN<1>")
	)
	(segment
		(start 140.228066 -59.771788)
		(end 142.573756 -59.771788)
		(width 0.0889)
		(layer "In9.Cu")
		(net "UPI_CPU0_CPU1_P0P0_DN<1>")
	)
	(segment
		(start 179.88407 -103.29418)
		(end 181.650386 -103.74376)
		(width 0.1143)
		(layer "In9.Cu")
		(net "UPI_CPU0_CPU1_P0P0_DN<1>")
	)
	(segment
		(start 308.569106 -80.923638)
		(end 308.487572 -80.709262)
		(width 0.1143)
		(layer "In9.Cu")
		(net "UPI_CPU0_CPU1_P0P0_DN<1>")
	)
	(segment
		(start 305.303936 -105.399332)
		(end 305.43246 -105.28046)
		(width 0.1143)
		(layer "In9.Cu")
		(net "UPI_CPU0_CPU1_P0P0_DN<1>")
	)
	(segment
		(start 181.650386 -103.74376)
		(end 183.68518 -105.186734)
		(width 0.1143)
		(layer "In9.Cu")
		(net "UPI_CPU0_CPU1_P0P0_DN<1>")
	)
	(segment
		(start 308.814978 -81.57083)
		(end 308.814724 -81.570068)
		(width 0.1143)
		(layer "In9.Cu")
		(net "UPI_CPU0_CPU1_P0P0_DN<1>")
	)
	(segment
		(start 309.225188 -82.650838)
		(end 309.074058 -82.583274)
		(width 0.1143)
		(layer "In9.Cu")
		(net "UPI_CPU0_CPU1_P0P0_DN<1>")
	)
	(segment
		(start 310.044084 -84.806028)
		(end 309.963058 -84.593176)
		(width 0.1143)
		(layer "In9.Cu")
		(net "UPI_CPU0_CPU1_P0P0_DN<1>")
	)
	(segment
		(start 196.978524 -109.184694)
		(end 199.920352 -109.883956)
		(width 0.1143)
		(layer "In9.Cu")
		(net "UPI_CPU0_CPU1_P0P0_DN<1>")
	)
	(segment
		(start 154.766772 -67.065652)
		(end 159.644334 -85.055964)
		(width 0.1143)
		(layer "In9.Cu")
		(net "UPI_CPU0_CPU1_P0P0_DN<1>")
	)
	(segment
		(start 166.50843 -94.57182)
		(end 173.005242 -101.349048)
		(width 0.1143)
		(layer "In9.Cu")
		(net "UPI_CPU0_CPU1_P0P0_DN<1>")
	)
	(segment
		(start 308.336442 -80.641698)
		(end 308.255162 -80.427576)
		(width 0.1143)
		(layer "In9.Cu")
		(net "UPI_CPU0_CPU1_P0P0_DN<1>")
	)
	(segment
		(start 290.198556 -103.521764)
		(end 291.125402 -103.43769)
		(width 0.1143)
		(layer "In9.Cu")
		(net "UPI_CPU0_CPU1_P0P0_DN<1>")
	)
	(segment
		(start 307.64734 -78.05039)
		(end 307.593238 -77.285342)
		(width 0.1143)
		(layer "In9.Cu")
		(net "UPI_CPU0_CPU1_P0P0_DN<1>")
	)
	(segment
		(start 159.644334 -85.055964)
		(end 166.244778 -92.866972)
		(width 0.1143)
		(layer "In9.Cu")
		(net "UPI_CPU0_CPU1_P0P0_DN<1>")
	)
	(segment
		(start 308.828186 -81.936082)
		(end 308.820058 -81.915)
		(width 0.1143)
		(layer "In9.Cu")
		(net "UPI_CPU0_CPU1_P0P0_DN<1>")
	)
	(segment
		(start 308.487572 -80.709262)
		(end 308.336442 -80.641698)
		(width 0.1143)
		(layer "In9.Cu")
		(net "UPI_CPU0_CPU1_P0P0_DN<1>")
	)
	(segment
		(start 309.811674 -84.52485)
		(end 309.730394 -84.310728)
		(width 0.1143)
		(layer "In9.Cu")
		(net "UPI_CPU0_CPU1_P0P0_DN<1>")
	)
	(segment
		(start 228.024182 -106.504486)
		(end 233.630978 -107.45851)
		(width 0.1143)
		(layer "In9.Cu")
		(net "UPI_CPU0_CPU1_P0P0_DN<1>")
	)
	(segment
		(start 310.044338 -84.80679)
		(end 310.044084 -84.806028)
		(width 0.1143)
		(layer "In9.Cu")
		(net "UPI_CPU0_CPU1_P0P0_DN<1>")
	)
	(segment
		(start 308.820058 -81.915)
		(end 308.746906 -81.72196)
		(width 0.1143)
		(layer "In9.Cu")
		(net "UPI_CPU0_CPU1_P0P0_DN<1>")
	)
	(segment
		(start 308.043834 -102.866698)
		(end 310.005222 -93.7768)
		(width 0.1143)
		(layer "In9.Cu")
		(net "UPI_CPU0_CPU1_P0P0_DN<1>")
	)
	(segment
		(start 307.393848 -74.461878)
		(end 307.256688 -74.021442)
		(width 0.1143)
		(layer "In9.Cu")
		(net "UPI_CPU0_CPU1_P0P0_DN<1>")
	)
	(segment
		(start 308.323234 -80.276446)
		(end 308.154324 -79.8322)
		(width 0.1143)
		(layer "In9.Cu")
		(net "UPI_CPU0_CPU1_P0P0_DN<1>")
	)
	(segment
		(start 310.623204 -90.913204)
		(end 311.254394 -87.987124)
		(width 0.1143)
		(layer "In9.Cu")
		(net "UPI_CPU0_CPU1_P0P0_DN<1>")
	)
	(segment
		(start 310.057546 -85.172042)
		(end 309.976266 -84.95792)
		(width 0.1143)
		(layer "In9.Cu")
		(net "UPI_CPU0_CPU1_P0P0_DN<1>")
	)
	(segment
		(start 143.726408 -60.054998)
		(end 145.605246 -60.054998)
		(width 0.0889)
		(layer "In9.Cu")
		(net "UPI_CPU0_CPU1_P0P0_DN<1>")
	)
	(segment
		(start 173.005242 -101.349048)
		(end 176.873408 -102.116382)
		(width 0.1143)
		(layer "In9.Cu")
		(net "UPI_CPU0_CPU1_P0P0_DN<1>")
	)
	(segment
		(start 267.046456 -107.920282)
		(end 278.1173 -106.857038)
		(width 0.1143)
		(layer "In9.Cu")
		(net "UPI_CPU0_CPU1_P0P0_DN<1>")
	)
	(segment
		(start 309.484522 -83.663536)
		(end 309.552594 -83.512406)
		(width 0.1143)
		(layer "In9.Cu")
		(net "UPI_CPU0_CPU1_P0P0_DN<1>")
	)
	(segment
		(start 136.812274 -61.352938)
		(end 136.812274 -61.691012)
		(width 0.0889)
		(layer "In9.Cu")
		(net "UPI_CPU0_CPU1_P0P0_DN<1>")
	)
	(segment
		(start 307.08219 -73.846944)
		(end 307.08219 -73.84669)
		(width 0.1143)
		(layer "In9.Cu")
		(net "UPI_CPU0_CPU1_P0P0_DN<1>")
	)
	(segment
		(start 142.573756 -59.771788)
		(end 143.073374 -60.271406)
		(width 0.0889)
		(layer "In9.Cu")
		(net "UPI_CPU0_CPU1_P0P0_DN<1>")
	)
	(segment
		(start 166.244778 -92.866972)
		(end 166.50843 -94.57182)
		(width 0.1143)
		(layer "In9.Cu")
		(net "UPI_CPU0_CPU1_P0P0_DN<1>")
	)
	(segment
		(start 151.801068 -63.9064)
		(end 154.766772 -67.065652)
		(width 0.1143)
		(layer "In9.Cu")
		(net "UPI_CPU0_CPU1_P0P0_DN<1>")
	)
	(segment
		(start 143.51 -60.271406)
		(end 143.726408 -60.054998)
		(width 0.0889)
		(layer "In9.Cu")
		(net "UPI_CPU0_CPU1_P0P0_DN<1>")
	)
	(segment
		(start 309.565802 -83.877658)
		(end 309.484522 -83.663536)
		(width 0.1143)
		(layer "In9.Cu")
		(net "UPI_CPU0_CPU1_P0P0_DN<1>")
	)
	(segment
		(start 233.630978 -107.45851)
		(end 248.035826 -104.58958)
		(width 0.1143)
		(layer "In9.Cu")
		(net "UPI_CPU0_CPU1_P0P0_DN<1>")
	)
	(segment
		(start 307.6956 -78.258924)
		(end 307.64734 -78.05039)
		(width 0.1143)
		(layer "In9.Cu")
		(net "UPI_CPU0_CPU1_P0P0_DN<1>")
	)
	(segment
		(start 138.507724 -60.762388)
		(end 138.54049 -60.762388)
		(width 0.0889)
		(layer "In9.Cu")
		(net "UPI_CPU0_CPU1_P0P0_DN<1>")
	)
	(segment
		(start 309.963058 -84.593176)
		(end 309.962804 -84.592414)
		(width 0.1143)
		(layer "In9.Cu")
		(net "UPI_CPU0_CPU1_P0P0_DN<1>")
	)
	(segment
		(start 137.653014 -61.257434)
		(end 137.68578 -61.257434)
		(width 0.0889)
		(layer "In9.Cu")
		(net "UPI_CPU0_CPU1_P0P0_DN<1>")
	)
	(segment
		(start 151.51481 -63.6016)
		(end 151.801068 -63.9064)
		(width 0.1143)
		(layer "In9.Cu")
		(net "UPI_CPU0_CPU1_P0P0_DN<1>")
	)
	(segment
		(start 307.593238 -77.285342)
		(end 307.393848 -74.461878)
		(width 0.1143)
		(layer "In9.Cu")
		(net "UPI_CPU0_CPU1_P0P0_DN<1>")
	)
	(segment
		(start 311.254394 -87.987124)
		(end 310.45531 -85.888322)
		(width 0.1143)
		(layer "In9.Cu")
		(net "UPI_CPU0_CPU1_P0P0_DN<1>")
	)
	(segment
		(start 307.256688 -74.021442)
		(end 307.08219 -73.846944)
		(width 0.1143)
		(layer "In9.Cu")
		(net "UPI_CPU0_CPU1_P0P0_DN<1>")
	)
	(segment
		(start 310.005222 -93.7768)
		(end 310.623204 -90.913204)
		(width 0.1143)
		(layer "In9.Cu")
		(net "UPI_CPU0_CPU1_P0P0_DN<1>")
	)
	(segment
		(start 309.06085 -82.218022)
		(end 308.97957 -82.004408)
		(width 0.1143)
		(layer "In9.Cu")
		(net "UPI_CPU0_CPU1_P0P0_DN<1>")
	)
	(segment
		(start 178.18354 -103.205788)
		(end 179.88407 -103.29418)
		(width 0.1143)
		(layer "In9.Cu")
		(net "UPI_CPU0_CPU1_P0P0_DN<1>")
	)
	(segment
		(start 309.23865 -83.016344)
		(end 309.306722 -82.865214)
		(width 0.1143)
		(layer "In9.Cu")
		(net "UPI_CPU0_CPU1_P0P0_DN<1>")
	)
	(segment
		(start 136.812274 -61.691012)
		(end 136.870186 -61.748924)
		(width 0.0889)
		(layer "In9.Cu")
		(net "UPI_CPU0_CPU1_P0P0_DN<1>")
	)
	(segment
		(start 310.208676 -85.239606)
		(end 310.057546 -85.172042)
		(width 0.1143)
		(layer "In9.Cu")
		(net "UPI_CPU0_CPU1_P0P0_DN<1>")
	)
	(segment
		(start 278.1173 -106.857038)
		(end 281.281886 -107.223814)
		(width 0.1143)
		(layer "In9.Cu")
		(net "UPI_CPU0_CPU1_P0P0_DN<1>")
	)
	(segment
		(start 308.154324 -79.8322)
		(end 307.912516 -79.19593)
		(width 0.1143)
		(layer "In9.Cu")
		(net "UPI_CPU0_CPU1_P0P0_DN<1>")
	)
	(segment
		(start 310.29021 -85.453982)
		(end 310.210962 -85.246464)
		(width 0.1143)
		(layer "In9.Cu")
		(net "UPI_CPU0_CPU1_P0P0_DN<1>")
	)
	(segment
		(start 307.08219 -73.84669)
		(end 306.657248 -73.421748)
		(width 0.1143)
		(layer "In9.Cu")
		(net "UPI_CPU0_CPU1_P0P0_DN<1>")
	)
	(segment
		(start 308.733444 -81.356454)
		(end 308.582314 -81.28889)
		(width 0.1143)
		(layer "In9.Cu")
		(net "UPI_CPU0_CPU1_P0P0_DN<1>")
	)
	(segment
		(start 176.873408 -102.116382)
		(end 178.18354 -103.205788)
		(width 0.1143)
		(layer "In9.Cu")
		(net "UPI_CPU0_CPU1_P0P0_DN<1>")
	)
	(segment
		(start 306.494942 -73.421748)
		(end 306.181506 -73.735184)
		(width 0.1143)
		(layer "In9.Cu")
		(net "UPI_CPU0_CPU1_P0P0_DN<1>")
	)
	(segment
		(start 308.814724 -81.570068)
		(end 308.733444 -81.356454)
		(width 0.1143)
		(layer "In9.Cu")
		(net "UPI_CPU0_CPU1_P0P0_DN<1>")
	)
	(segment
		(start 308.97957 -82.004408)
		(end 308.979316 -82.003646)
		(width 0.1143)
		(layer "In9.Cu")
		(net "UPI_CPU0_CPU1_P0P0_DN<1>")
	)
	(segment
		(start 309.976266 -84.95792)
		(end 310.044338 -84.80679)
		(width 0.1143)
		(layer "In9.Cu")
		(net "UPI_CPU0_CPU1_P0P0_DN<1>")
	)
	(segment
		(start 309.074058 -82.583274)
		(end 308.992778 -82.369152)
		(width 0.1143)
		(layer "In9.Cu")
		(net "UPI_CPU0_CPU1_P0P0_DN<1>")
	)
	(segment
		(start 302.919638 -105.94213)
		(end 305.303936 -105.399332)
		(width 0.1143)
		(layer "In9.Cu")
		(net "UPI_CPU0_CPU1_P0P0_DN<1>")
	)
	(segment
		(start 308.501034 -81.074768)
		(end 308.569106 -80.923638)
		(width 0.1143)
		(layer "In9.Cu")
		(net "UPI_CPU0_CPU1_P0P0_DN<1>")
	)
	(segment
		(start 192.549272 -106.26471)
		(end 196.978524 -109.184694)
		(width 0.1143)
		(layer "In9.Cu")
		(net "UPI_CPU0_CPU1_P0P0_DN<1>")
	)
	(segment
		(start 292.593522 -103.304594)
		(end 302.919638 -105.94213)
		(width 0.1143)
		(layer "In9.Cu")
		(net "UPI_CPU0_CPU1_P0P0_DN<1>")
	)
	(segment
		(start 146.370548 -60.8203)
		(end 147.007072 -60.8203)
		(width 0.0889)
		(layer "In9.Cu")
		(net "UPI_CPU0_CPU1_P0P0_DN<1>")
	)
	(segment
		(start 263.273032 -107.735116)
		(end 267.046456 -107.920282)
		(width 0.1143)
		(layer "In9.Cu")
		(net "UPI_CPU0_CPU1_P0P0_DN<1>")
	)
	(segment
		(start 308.255162 -80.427576)
		(end 308.323234 -80.276446)
		(width 0.1143)
		(layer "In9.Cu")
		(net "UPI_CPU0_CPU1_P0P0_DN<1>")
	)
	(segment
		(start 308.582314 -81.28889)
		(end 308.501034 -81.074768)
		(width 0.1143)
		(layer "In9.Cu")
		(net "UPI_CPU0_CPU1_P0P0_DN<1>")
	)
	(segment
		(start 143.073374 -60.271406)
		(end 143.51 -60.271406)
		(width 0.0889)
		(layer "In9.Cu")
		(net "UPI_CPU0_CPU1_P0P0_DN<1>")
	)
	(segment
		(start 291.125402 -103.43769)
		(end 292.593522 -103.304594)
		(width 0.1143)
		(layer "In9.Cu")
		(net "UPI_CPU0_CPU1_P0P0_DN<1>")
	)
	(segment
		(start 148.856192 -60.7695)
		(end 151.51481 -63.6016)
		(width 0.1143)
		(layer "In9.Cu")
		(net "UPI_CPU0_CPU1_P0P0_DN<1>")
	)
	(segment
		(start 307.912516 -79.19593)
		(end 307.6956 -78.258924)
		(width 0.1143)
		(layer "In9.Cu")
		(net "UPI_CPU0_CPU1_P0P0_DN<1>")
	)
	(segment
		(start 309.798466 -84.159598)
		(end 309.716932 -83.945222)
		(width 0.1143)
		(layer "In9.Cu")
		(net "UPI_CPU0_CPU1_P0P0_DN<1>")
	)
	(segment
		(start 139.370054 -60.266834)
		(end 139.40282 -60.266834)
		(width 0.0889)
		(layer "In9.Cu")
		(net "UPI_CPU0_CPU1_P0P0_DN<1>")
	)
	(segment
		(start 309.552594 -83.512406)
		(end 309.47106 -83.29803)
		(width 0.1143)
		(layer "In9.Cu")
		(net "UPI_CPU0_CPU1_P0P0_DN<1>")
	)
	(segment
		(start 309.47106 -83.29803)
		(end 309.31993 -83.230466)
		(width 0.1143)
		(layer "In9.Cu")
		(net "UPI_CPU0_CPU1_P0P0_DN<1>")
	)
	(segment
		(start 309.31993 -83.230466)
		(end 309.23865 -83.016344)
		(width 0.1143)
		(layer "In9.Cu")
		(net "UPI_CPU0_CPU1_P0P0_DN<1>")
	)
	(segment
		(start 248.035826 -104.58958)
		(end 263.273032 -107.735116)
		(width 0.1143)
		(layer "In9.Cu")
		(net "UPI_CPU0_CPU1_P0P0_DN<1>")
	)
	(arc
		(start 138.876024 -60.562236)
		(mid 139.084632 -60.350304)
		(end 139.370054 -60.266834)
		(width 0.0889)
		(layer "In9.Cu")
		(net "UPI_CPU0_CPU1_P0P0_DN<1>")
	)
	(arc
		(start 138.017504 -61.057536)
		(mid 138.224508 -60.846672)
		(end 138.507724 -60.762388)
		(width 0.0889)
		(layer "In9.Cu")
		(net "UPI_CPU0_CPU1_P0P0_DN<1>")
	)
	(arc
		(start 138.54049 -60.762388)
		(mid 138.73434 -60.706038)
		(end 138.876024 -60.562236)
		(width 0.0889)
		(layer "In9.Cu")
		(net "UPI_CPU0_CPU1_P0P0_DN<1>")
	)
	(arc
		(start 139.40282 -60.266834)
		(mid 139.594462 -60.209668)
		(end 139.734544 -60.066936)
		(width 0.0889)
		(layer "In9.Cu")
		(net "UPI_CPU0_CPU1_P0P0_DN<1>")
	)
	(arc
		(start 137.68578 -61.257434)
		(mid 137.877422 -61.200268)
		(end 138.017504 -61.057536)
		(width 0.0889)
		(layer "In9.Cu")
		(net "UPI_CPU0_CPU1_P0P0_DN<1>")
	)
	(arc
		(start 137.158984 -61.552836)
		(mid 137.367592 -61.340904)
		(end 137.653014 -61.257434)
		(width 0.0889)
		(layer "In9.Cu")
		(net "UPI_CPU0_CPU1_P0P0_DN<1>")
	)
	(arc
		(start 136.870186 -61.748924)
		(mid 137.037087 -61.684024)
		(end 137.158984 -61.552836)
		(width 0.0889)
		(layer "In9.Cu")
		(net "UPI_CPU0_CPU1_P0P0_DN<1>")
	)
	(arc
		(start 139.734544 -60.066936)
		(mid 139.942963 -59.855223)
		(end 140.228066 -59.771788)
		(width 0.0889)
		(layer "In9.Cu")
		(net "UPI_CPU0_CPU1_P0P0_DN<1>")
	)
	(segment
		(start 306.392326 -57.390538)
		(end 306.963826 -57.390538)
		(width 0.1143)
		(layer "F.Cu")
		(net "UPI_CPU0_CPU1_P0P0_DN<19>")
	)
	(segment
		(start 135.095234 -71.258938)
		(end 134.523734 -71.258938)
		(width 0.1143)
		(layer "F.Cu")
		(net "UPI_CPU0_CPU1_P0P0_DN<19>")
	)
	(via
		(at 306.963826 -57.390538)
		(size 0.508)
		(drill 0.254)
		(layers "F.Cu" "B.Cu")
		(net "UPI_CPU0_CPU1_P0P0_DN<19>")
	)
	(via
		(at 135.095234 -71.258938)
		(size 0.508)
		(drill 0.254)
		(layers "F.Cu" "B.Cu")
		(net "UPI_CPU0_CPU1_P0P0_DN<19>")
	)
	(segment
		(start 136.801098 -76.611988)
		(end 136.833864 -76.611988)
		(width 0.0889)
		(layer "In9.Cu")
		(net "UPI_CPU0_CPU1_P0P0_DN<19>")
	)
	(segment
		(start 322.354702 -80.489298)
		(end 322.336414 -79.8322)
		(width 0.1143)
		(layer "In9.Cu")
		(net "UPI_CPU0_CPU1_P0P0_DN<19>")
	)
	(segment
		(start 142.85468 -79.548736)
		(end 142.876778 -79.548736)
		(width 0.0889)
		(layer "In9.Cu")
		(net "UPI_CPU0_CPU1_P0P0_DN<19>")
	)
	(segment
		(start 170.418506 -116.757196)
		(end 180.217064 -121.137172)
		(width 0.1143)
		(layer "In9.Cu")
		(net "UPI_CPU0_CPU1_P0P0_DN<19>")
	)
	(segment
		(start 137.655808 -77.107034)
		(end 137.688574 -77.107034)
		(width 0.0889)
		(layer "In9.Cu")
		(net "UPI_CPU0_CPU1_P0P0_DN<19>")
	)
	(segment
		(start 311.453276 -58.164984)
		(end 309.54472 -58.164984)
		(width 0.1143)
		(layer "In9.Cu")
		(net "UPI_CPU0_CPU1_P0P0_DN<19>")
	)
	(segment
		(start 325.702676 -100.318824)
		(end 325.87819 -98.010218)
		(width 0.1143)
		(layer "In9.Cu")
		(net "UPI_CPU0_CPU1_P0P0_DN<19>")
	)
	(segment
		(start 150.142448 -96.88449)
		(end 150.159466 -97.112836)
		(width 0.1143)
		(layer "In9.Cu")
		(net "UPI_CPU0_CPU1_P0P0_DN<19>")
	)
	(segment
		(start 322.201794 -74.962512)
		(end 319.75171 -68.4276)
		(width 0.1143)
		(layer "In9.Cu")
		(net "UPI_CPU0_CPU1_P0P0_DN<19>")
	)
	(segment
		(start 138.518138 -77.602588)
		(end 138.550904 -77.602588)
		(width 0.0889)
		(layer "In9.Cu")
		(net "UPI_CPU0_CPU1_P0P0_DN<19>")
	)
	(segment
		(start 146.973798 -82.277458)
		(end 149.490176 -91.557348)
		(width 0.1143)
		(layer "In9.Cu")
		(net "UPI_CPU0_CPU1_P0P0_DN<19>")
	)
	(segment
		(start 150.788116 -100.38842)
		(end 151.899874 -101.414326)
		(width 0.1143)
		(layer "In9.Cu")
		(net "UPI_CPU0_CPU1_P0P0_DN<19>")
	)
	(segment
		(start 149.937978 -94.074996)
		(end 150.10003 -94.215458)
		(width 0.1143)
		(layer "In9.Cu")
		(net "UPI_CPU0_CPU1_P0P0_DN<19>")
	)
	(segment
		(start 134.748524 -74.430636)
		(end 134.754874 -74.441304)
		(width 0.0889)
		(layer "In9.Cu")
		(net "UPI_CPU0_CPU1_P0P0_DN<19>")
	)
	(segment
		(start 150.104094 -96.353376)
		(end 150.266146 -96.493838)
		(width 0.1143)
		(layer "In9.Cu")
		(net "UPI_CPU0_CPU1_P0P0_DN<19>")
	)
	(segment
		(start 259.022596 -119.019066)
		(end 267.316204 -119.428006)
		(width 0.1143)
		(layer "In9.Cu")
		(net "UPI_CPU0_CPU1_P0P0_DN<19>")
	)
	(segment
		(start 134.743698 -73.4314)
		(end 134.748524 -73.440036)
		(width 0.0889)
		(layer "In9.Cu")
		(net "UPI_CPU0_CPU1_P0P0_DN<19>")
	)
	(segment
		(start 150.061676 -93.684852)
		(end 149.92096 -93.84665)
		(width 0.1143)
		(layer "In9.Cu")
		(net "UPI_CPU0_CPU1_P0P0_DN<19>")
	)
	(segment
		(start 227.848414 -118.11762)
		(end 248.162572 -121.577608)
		(width 0.1143)
		(layer "In9.Cu")
		(net "UPI_CPU0_CPU1_P0P0_DN<19>")
	)
	(segment
		(start 318.1985 -64.284606)
		(end 318.165734 -64.19723)
		(width 0.1143)
		(layer "In9.Cu")
		(net "UPI_CPU0_CPU1_P0P0_DN<19>")
	)
	(segment
		(start 149.99335 -94.834456)
		(end 150.155402 -94.974918)
		(width 0.1143)
		(layer "In9.Cu")
		(net "UPI_CPU0_CPU1_P0P0_DN<19>")
	)
	(segment
		(start 325.87819 -98.010218)
		(end 325.702676 -97.148904)
		(width 0.1143)
		(layer "In9.Cu")
		(net "UPI_CPU0_CPU1_P0P0_DN<19>")
	)
	(segment
		(start 322.362068 -80.751172)
		(end 322.354702 -80.489298)
		(width 0.1143)
		(layer "In9.Cu")
		(net "UPI_CPU0_CPU1_P0P0_DN<19>")
	)
	(segment
		(start 149.490176 -91.557348)
		(end 149.63521 -91.64066)
		(width 0.1143)
		(layer "In9.Cu")
		(net "UPI_CPU0_CPU1_P0P0_DN<19>")
	)
	(segment
		(start 322.59905 -81.915)
		(end 322.362068 -80.751172)
		(width 0.1143)
		(layer "In9.Cu")
		(net "UPI_CPU0_CPU1_P0P0_DN<19>")
	)
	(segment
		(start 140.235178 -78.593188)
		(end 140.267944 -78.593188)
		(width 0.0889)
		(layer "In9.Cu")
		(net "UPI_CPU0_CPU1_P0P0_DN<19>")
	)
	(segment
		(start 318.165734 -64.19723)
		(end 311.453276 -58.164984)
		(width 0.1143)
		(layer "In9.Cu")
		(net "UPI_CPU0_CPU1_P0P0_DN<19>")
	)
	(segment
		(start 309.471822 -58.114184)
		(end 309.081424 -58.114184)
		(width 0.0889)
		(layer "In9.Cu")
		(net "UPI_CPU0_CPU1_P0P0_DN<19>")
	)
	(segment
		(start 149.851364 -92.889324)
		(end 149.882606 -93.315536)
		(width 0.1143)
		(layer "In9.Cu")
		(net "UPI_CPU0_CPU1_P0P0_DN<19>")
	)
	(segment
		(start 142.876778 -79.548736)
		(end 143.913352 -79.548736)
		(width 0.1143)
		(layer "In9.Cu")
		(net "UPI_CPU0_CPU1_P0P0_DN<19>")
	)
	(segment
		(start 180.217064 -121.137172)
		(end 185.76798 -122.782838)
		(width 0.1143)
		(layer "In9.Cu")
		(net "UPI_CPU0_CPU1_P0P0_DN<19>")
	)
	(segment
		(start 150.087076 -96.12503)
		(end 150.104094 -96.353376)
		(width 0.1143)
		(layer "In9.Cu")
		(net "UPI_CPU0_CPU1_P0P0_DN<19>")
	)
	(segment
		(start 134.743698 -72.4408)
		(end 134.748524 -72.449436)
		(width 0.0889)
		(layer "In9.Cu")
		(net "UPI_CPU0_CPU1_P0P0_DN<19>")
	)
	(segment
		(start 149.671532 -92.225368)
		(end 149.67204 -92.2274)
		(width 0.1143)
		(layer "In9.Cu")
		(net "UPI_CPU0_CPU1_P0P0_DN<19>")
	)
	(segment
		(start 142.147036 -79.599536)
		(end 142.80388 -79.599536)
		(width 0.0889)
		(layer "In9.Cu")
		(net "UPI_CPU0_CPU1_P0P0_DN<19>")
	)
	(segment
		(start 291.125402 -119.922544)
		(end 292.517322 -120.083834)
		(width 0.1143)
		(layer "In9.Cu")
		(net "UPI_CPU0_CPU1_P0P0_DN<19>")
	)
	(segment
		(start 149.877272 -92.531946)
		(end 149.793706 -92.676472)
		(width 0.1143)
		(layer "In9.Cu")
		(net "UPI_CPU0_CPU1_P0P0_DN<19>")
	)
	(segment
		(start 134.748524 -73.440036)
		(end 134.754874 -73.450704)
		(width 0.0889)
		(layer "In9.Cu")
		(net "UPI_CPU0_CPU1_P0P0_DN<19>")
	)
	(segment
		(start 150.283164 -96.722692)
		(end 150.142448 -96.88449)
		(width 0.1143)
		(layer "In9.Cu")
		(net "UPI_CPU0_CPU1_P0P0_DN<19>")
	)
	(segment
		(start 141.087348 -79.088488)
		(end 141.635988 -79.088488)
		(width 0.0889)
		(layer "In9.Cu")
		(net "UPI_CPU0_CPU1_P0P0_DN<19>")
	)
	(segment
		(start 267.316204 -119.428006)
		(end 278.007064 -118.401338)
		(width 0.1143)
		(layer "In9.Cu")
		(net "UPI_CPU0_CPU1_P0P0_DN<19>")
	)
	(segment
		(start 185.76798 -122.782838)
		(end 193.420492 -122.262138)
		(width 0.1143)
		(layer "In9.Cu")
		(net "UPI_CPU0_CPU1_P0P0_DN<19>")
	)
	(segment
		(start 142.80388 -79.599536)
		(end 142.85468 -79.548736)
		(width 0.0889)
		(layer "In9.Cu")
		(net "UPI_CPU0_CPU1_P0P0_DN<19>")
	)
	(segment
		(start 278.007064 -118.401338)
		(end 291.125402 -119.922544)
		(width 0.1143)
		(layer "In9.Cu")
		(net "UPI_CPU0_CPU1_P0P0_DN<19>")
	)
	(segment
		(start 134.743698 -74.422)
		(end 134.748524 -74.430636)
		(width 0.0889)
		(layer "In9.Cu")
		(net "UPI_CPU0_CPU1_P0P0_DN<19>")
	)
	(segment
		(start 149.63521 -91.64066)
		(end 149.695408 -91.861894)
		(width 0.1143)
		(layer "In9.Cu")
		(net "UPI_CPU0_CPU1_P0P0_DN<19>")
	)
	(segment
		(start 135.938768 -76.116434)
		(end 135.971534 -76.116434)
		(width 0.0889)
		(layer "In9.Cu")
		(net "UPI_CPU0_CPU1_P0P0_DN<19>")
	)
	(segment
		(start 325.702676 -97.148904)
		(end 325.015606 -93.7768)
		(width 0.1143)
		(layer "In9.Cu")
		(net "UPI_CPU0_CPU1_P0P0_DN<19>")
	)
	(segment
		(start 134.748524 -72.449436)
		(end 134.754874 -72.460104)
		(width 0.0889)
		(layer "In9.Cu")
		(net "UPI_CPU0_CPU1_P0P0_DN<19>")
	)
	(segment
		(start 322.336414 -79.8322)
		(end 322.201794 -74.962512)
		(width 0.1143)
		(layer "In9.Cu")
		(net "UPI_CPU0_CPU1_P0P0_DN<19>")
	)
	(segment
		(start 149.92096 -93.84665)
		(end 149.937978 -94.074996)
		(width 0.1143)
		(layer "In9.Cu")
		(net "UPI_CPU0_CPU1_P0P0_DN<19>")
	)
	(segment
		(start 150.338536 -97.482152)
		(end 150.19782 -97.64395)
		(width 0.1143)
		(layer "In9.Cu")
		(net "UPI_CPU0_CPU1_P0P0_DN<19>")
	)
	(segment
		(start 309.522622 -58.164984)
		(end 309.471822 -58.114184)
		(width 0.0889)
		(layer "In9.Cu")
		(net "UPI_CPU0_CPU1_P0P0_DN<19>")
	)
	(segment
		(start 325.015606 -93.7768)
		(end 322.59905 -81.915)
		(width 0.1143)
		(layer "In9.Cu")
		(net "UPI_CPU0_CPU1_P0P0_DN<19>")
	)
	(segment
		(start 292.517322 -120.083834)
		(end 311.099708 -115.8494)
		(width 0.1143)
		(layer "In9.Cu")
		(net "UPI_CPU0_CPU1_P0P0_DN<19>")
	)
	(segment
		(start 325.664068 -100.82657)
		(end 325.702676 -100.318824)
		(width 0.1143)
		(layer "In9.Cu")
		(net "UPI_CPU0_CPU1_P0P0_DN<19>")
	)
	(segment
		(start 309.54472 -58.164984)
		(end 309.522622 -58.164984)
		(width 0.0889)
		(layer "In9.Cu")
		(net "UPI_CPU0_CPU1_P0P0_DN<19>")
	)
	(segment
		(start 150.266146 -96.493838)
		(end 150.283164 -96.722692)
		(width 0.1143)
		(layer "In9.Cu")
		(net "UPI_CPU0_CPU1_P0P0_DN<19>")
	)
	(segment
		(start 150.117048 -94.444312)
		(end 149.976332 -94.60611)
		(width 0.1143)
		(layer "In9.Cu")
		(net "UPI_CPU0_CPU1_P0P0_DN<19>")
	)
	(segment
		(start 309.081424 -58.114184)
		(end 308.452774 -57.485534)
		(width 0.0889)
		(layer "In9.Cu")
		(net "UPI_CPU0_CPU1_P0P0_DN<19>")
	)
	(segment
		(start 150.159466 -97.112836)
		(end 150.321518 -97.253298)
		(width 0.1143)
		(layer "In9.Cu")
		(net "UPI_CPU0_CPU1_P0P0_DN<19>")
	)
	(segment
		(start 323.909944 -104.014778)
		(end 325.664068 -100.82657)
		(width 0.1143)
		(layer "In9.Cu")
		(net "UPI_CPU0_CPU1_P0P0_DN<19>")
	)
	(segment
		(start 149.976332 -94.60611)
		(end 149.99335 -94.834456)
		(width 0.1143)
		(layer "In9.Cu")
		(net "UPI_CPU0_CPU1_P0P0_DN<19>")
	)
	(segment
		(start 155.074874 -101.892862)
		(end 170.418506 -116.757196)
		(width 0.1143)
		(layer "In9.Cu")
		(net "UPI_CPU0_CPU1_P0P0_DN<19>")
	)
	(segment
		(start 193.420492 -122.262138)
		(end 227.848414 -118.11762)
		(width 0.1143)
		(layer "In9.Cu")
		(net "UPI_CPU0_CPU1_P0P0_DN<19>")
	)
	(segment
		(start 149.695408 -91.861894)
		(end 149.611842 -92.00642)
		(width 0.1143)
		(layer "In9.Cu")
		(net "UPI_CPU0_CPU1_P0P0_DN<19>")
	)
	(segment
		(start 150.227792 -95.963232)
		(end 150.087076 -96.12503)
		(width 0.1143)
		(layer "In9.Cu")
		(net "UPI_CPU0_CPU1_P0P0_DN<19>")
	)
	(segment
		(start 150.044658 -93.455998)
		(end 150.061676 -93.684852)
		(width 0.1143)
		(layer "In9.Cu")
		(net "UPI_CPU0_CPU1_P0P0_DN<19>")
	)
	(segment
		(start 311.099708 -115.8494)
		(end 323.909944 -104.014778)
		(width 0.1143)
		(layer "In9.Cu")
		(net "UPI_CPU0_CPU1_P0P0_DN<19>")
	)
	(segment
		(start 139.372848 -78.097634)
		(end 139.400788 -78.097634)
		(width 0.0889)
		(layer "In9.Cu")
		(net "UPI_CPU0_CPU1_P0P0_DN<19>")
	)
	(segment
		(start 149.793706 -92.676472)
		(end 149.851364 -92.889324)
		(width 0.1143)
		(layer "In9.Cu")
		(net "UPI_CPU0_CPU1_P0P0_DN<19>")
	)
	(segment
		(start 150.17242 -95.203772)
		(end 150.031704 -95.36557)
		(width 0.1143)
		(layer "In9.Cu")
		(net "UPI_CPU0_CPU1_P0P0_DN<19>")
	)
	(segment
		(start 150.048722 -95.593916)
		(end 150.210774 -95.734378)
		(width 0.1143)
		(layer "In9.Cu")
		(net "UPI_CPU0_CPU1_P0P0_DN<19>")
	)
	(segment
		(start 149.611842 -92.00642)
		(end 149.671532 -92.225368)
		(width 0.1143)
		(layer "In9.Cu")
		(net "UPI_CPU0_CPU1_P0P0_DN<19>")
	)
	(segment
		(start 150.10003 -94.215458)
		(end 150.117048 -94.444312)
		(width 0.1143)
		(layer "In9.Cu")
		(net "UPI_CPU0_CPU1_P0P0_DN<19>")
	)
	(segment
		(start 248.162572 -121.577608)
		(end 259.022596 -119.019066)
		(width 0.1143)
		(layer "In9.Cu")
		(net "UPI_CPU0_CPU1_P0P0_DN<19>")
	)
	(segment
		(start 141.635988 -79.088488)
		(end 142.147036 -79.599536)
		(width 0.0889)
		(layer "In9.Cu")
		(net "UPI_CPU0_CPU1_P0P0_DN<19>")
	)
	(segment
		(start 143.913352 -79.548736)
		(end 146.973798 -82.277458)
		(width 0.1143)
		(layer "In9.Cu")
		(net "UPI_CPU0_CPU1_P0P0_DN<19>")
	)
	(segment
		(start 149.882606 -93.315536)
		(end 150.044658 -93.455998)
		(width 0.1143)
		(layer "In9.Cu")
		(net "UPI_CPU0_CPU1_P0P0_DN<19>")
	)
	(segment
		(start 151.899874 -101.414326)
		(end 155.074874 -101.892862)
		(width 0.1143)
		(layer "In9.Cu")
		(net "UPI_CPU0_CPU1_P0P0_DN<19>")
	)
	(segment
		(start 150.031704 -95.36557)
		(end 150.048722 -95.593916)
		(width 0.1143)
		(layer "In9.Cu")
		(net "UPI_CPU0_CPU1_P0P0_DN<19>")
	)
	(segment
		(start 150.19782 -97.64395)
		(end 150.335488 -99.569016)
		(width 0.1143)
		(layer "In9.Cu")
		(net "UPI_CPU0_CPU1_P0P0_DN<19>")
	)
	(segment
		(start 149.817074 -92.310712)
		(end 149.877272 -92.531946)
		(width 0.1143)
		(layer "In9.Cu")
		(net "UPI_CPU0_CPU1_P0P0_DN<19>")
	)
	(segment
		(start 150.335488 -99.569016)
		(end 150.788116 -100.38842)
		(width 0.1143)
		(layer "In9.Cu")
		(net "UPI_CPU0_CPU1_P0P0_DN<19>")
	)
	(segment
		(start 149.67204 -92.2274)
		(end 149.817074 -92.310712)
		(width 0.1143)
		(layer "In9.Cu")
		(net "UPI_CPU0_CPU1_P0P0_DN<19>")
	)
	(segment
		(start 150.155402 -94.974918)
		(end 150.17242 -95.203772)
		(width 0.1143)
		(layer "In9.Cu")
		(net "UPI_CPU0_CPU1_P0P0_DN<19>")
	)
	(segment
		(start 135.000746 -71.611998)
		(end 134.748524 -72.049386)
		(width 0.0889)
		(layer "In9.Cu")
		(net "UPI_CPU0_CPU1_P0P0_DN<19>")
	)
	(segment
		(start 150.321518 -97.253298)
		(end 150.338536 -97.482152)
		(width 0.1143)
		(layer "In9.Cu")
		(net "UPI_CPU0_CPU1_P0P0_DN<19>")
	)
	(segment
		(start 308.452774 -57.485534)
		(end 307.193188 -57.485534)
		(width 0.0889)
		(layer "In9.Cu")
		(net "UPI_CPU0_CPU1_P0P0_DN<19>")
	)
	(segment
		(start 319.75171 -68.4276)
		(end 318.1985 -64.284606)
		(width 0.1143)
		(layer "In9.Cu")
		(net "UPI_CPU0_CPU1_P0P0_DN<19>")
	)
	(segment
		(start 150.210774 -95.734378)
		(end 150.227792 -95.963232)
		(width 0.1143)
		(layer "In9.Cu")
		(net "UPI_CPU0_CPU1_P0P0_DN<19>")
	)
	(segment
		(start 135.084058 -75.621388)
		(end 135.116824 -75.621388)
		(width 0.0889)
		(layer "In9.Cu")
		(net "UPI_CPU0_CPU1_P0P0_DN<19>")
	)
	(arc
		(start 134.748524 -74.030586)
		(mid 134.695054 -74.225649)
		(end 134.743698 -74.422)
		(width 0.0889)
		(layer "In9.Cu")
		(net "UPI_CPU0_CPU1_P0P0_DN<19>")
	)
	(arc
		(start 140.758164 -78.888336)
		(mid 140.896908 -79.030369)
		(end 141.08684 -79.088234)
		(width 0.0889)
		(layer "In9.Cu")
		(net "UPI_CPU0_CPU1_P0P0_DN<19>")
	)
	(arc
		(start 137.688574 -77.107034)
		(mid 137.973998 -77.190501)
		(end 138.182604 -77.402436)
		(width 0.0889)
		(layer "In9.Cu")
		(net "UPI_CPU0_CPU1_P0P0_DN<19>")
	)
	(arc
		(start 134.748524 -73.039986)
		(mid 134.695054 -73.235049)
		(end 134.743698 -73.4314)
		(width 0.0889)
		(layer "In9.Cu")
		(net "UPI_CPU0_CPU1_P0P0_DN<19>")
	)
	(arc
		(start 136.833864 -76.611988)
		(mid 137.117081 -76.696269)
		(end 137.324084 -76.907136)
		(width 0.0889)
		(layer "In9.Cu")
		(net "UPI_CPU0_CPU1_P0P0_DN<19>")
	)
	(arc
		(start 134.754874 -72.460104)
		(mid 134.827672 -72.750867)
		(end 134.748524 -73.039986)
		(width 0.0889)
		(layer "In9.Cu")
		(net "UPI_CPU0_CPU1_P0P0_DN<19>")
	)
	(arc
		(start 134.724648 -72.0979)
		(mid 134.695537 -72.271496)
		(end 134.743698 -72.4408)
		(width 0.0889)
		(layer "In9.Cu")
		(net "UPI_CPU0_CPU1_P0P0_DN<19>")
	)
	(arc
		(start 139.899644 -78.393036)
		(mid 140.041327 -78.53684)
		(end 140.235178 -78.593188)
		(width 0.0889)
		(layer "In9.Cu")
		(net "UPI_CPU0_CPU1_P0P0_DN<19>")
	)
	(arc
		(start 139.041124 -77.897736)
		(mid 139.181203 -78.040472)
		(end 139.372848 -78.097634)
		(width 0.0889)
		(layer "In9.Cu")
		(net "UPI_CPU0_CPU1_P0P0_DN<19>")
	)
	(arc
		(start 307.193188 -57.485534)
		(mid 307.069062 -57.460844)
		(end 306.963826 -57.390538)
		(width 0.0889)
		(layer "In9.Cu")
		(net "UPI_CPU0_CPU1_P0P0_DN<19>")
	)
	(arc
		(start 138.550904 -77.602588)
		(mid 138.834121 -77.686869)
		(end 139.041124 -77.897736)
		(width 0.0889)
		(layer "In9.Cu")
		(net "UPI_CPU0_CPU1_P0P0_DN<19>")
	)
	(arc
		(start 135.971534 -76.116434)
		(mid 136.256958 -76.199901)
		(end 136.465564 -76.411836)
		(width 0.0889)
		(layer "In9.Cu")
		(net "UPI_CPU0_CPU1_P0P0_DN<19>")
	)
	(arc
		(start 139.400788 -78.097634)
		(mid 139.688933 -78.179953)
		(end 139.899644 -78.393036)
		(width 0.0889)
		(layer "In9.Cu")
		(net "UPI_CPU0_CPU1_P0P0_DN<19>")
	)
	(arc
		(start 137.324084 -76.907136)
		(mid 137.464163 -77.049872)
		(end 137.655808 -77.107034)
		(width 0.0889)
		(layer "In9.Cu")
		(net "UPI_CPU0_CPU1_P0P0_DN<19>")
	)
	(arc
		(start 136.465564 -76.411836)
		(mid 136.607247 -76.55564)
		(end 136.801098 -76.611988)
		(width 0.0889)
		(layer "In9.Cu")
		(net "UPI_CPU0_CPU1_P0P0_DN<19>")
	)
	(arc
		(start 135.095234 -71.258938)
		(mid 135.071196 -71.441677)
		(end 135.000746 -71.611998)
		(width 0.0889)
		(layer "In9.Cu")
		(net "UPI_CPU0_CPU1_P0P0_DN<19>")
	)
	(arc
		(start 135.607044 -75.916536)
		(mid 135.747123 -76.059272)
		(end 135.938768 -76.116434)
		(width 0.0889)
		(layer "In9.Cu")
		(net "UPI_CPU0_CPU1_P0P0_DN<19>")
	)
	(arc
		(start 134.748524 -72.049386)
		(mid 134.735765 -72.073239)
		(end 134.724648 -72.0979)
		(width 0.0889)
		(layer "In9.Cu")
		(net "UPI_CPU0_CPU1_P0P0_DN<19>")
	)
	(arc
		(start 134.754874 -73.450704)
		(mid 134.827672 -73.741467)
		(end 134.748524 -74.030586)
		(width 0.0889)
		(layer "In9.Cu")
		(net "UPI_CPU0_CPU1_P0P0_DN<19>")
	)
	(arc
		(start 138.182604 -77.402436)
		(mid 138.324287 -77.54624)
		(end 138.518138 -77.602588)
		(width 0.0889)
		(layer "In9.Cu")
		(net "UPI_CPU0_CPU1_P0P0_DN<19>")
	)
	(arc
		(start 134.754874 -74.441304)
		(mid 134.827672 -74.732067)
		(end 134.748524 -75.021186)
		(width 0.0889)
		(layer "In9.Cu")
		(net "UPI_CPU0_CPU1_P0P0_DN<19>")
	)
	(arc
		(start 140.267944 -78.593188)
		(mid 140.551161 -78.677469)
		(end 140.758164 -78.888336)
		(width 0.0889)
		(layer "In9.Cu")
		(net "UPI_CPU0_CPU1_P0P0_DN<19>")
	)
	(arc
		(start 134.748524 -75.021186)
		(mid 134.745776 -75.416653)
		(end 135.084058 -75.621388)
		(width 0.0889)
		(layer "In9.Cu")
		(net "UPI_CPU0_CPU1_P0P0_DN<19>")
	)
	(arc
		(start 135.116824 -75.621388)
		(mid 135.400041 -75.705669)
		(end 135.607044 -75.916536)
		(width 0.0889)
		(layer "In9.Cu")
		(net "UPI_CPU0_CPU1_P0P0_DN<19>")
	)
	(arc
		(start 141.08684 -79.088234)
		(mid 141.087094 -79.088361)
		(end 141.087348 -79.088488)
		(width 0.0889)
		(layer "In9.Cu")
		(net "UPI_CPU0_CPU1_P0P0_DN<19>")
	)
	(segment
		(start 307.250846 -57.885584)
		(end 307.898546 -57.885584)
		(width 0.1143)
		(layer "F.Cu")
		(net "UPI_CPU0_CPU1_P0P0_DN<18>")
	)
	(segment
		(start 135.095234 -72.249538)
		(end 134.523734 -72.249538)
		(width 0.1143)
		(layer "F.Cu")
		(net "UPI_CPU0_CPU1_P0P0_DN<18>")
	)
	(via
		(at 135.095234 -72.249538)
		(size 0.508)
		(drill 0.254)
		(layers "F.Cu" "B.Cu")
		(net "UPI_CPU0_CPU1_P0P0_DN<18>")
	)
	(via
		(at 307.898546 -57.885584)
		(size 0.508)
		(drill 0.254)
		(layers "F.Cu" "B.Cu")
		(net "UPI_CPU0_CPU1_P0P0_DN<18>")
	)
	(segment
		(start 323.674486 -103.72598)
		(end 325.325232 -100.725732)
		(width 0.1143)
		(layer "In9.Cu")
		(net "UPI_CPU0_CPU1_P0P0_DN<18>")
	)
	(segment
		(start 156.39923 -102.479348)
		(end 156.446728 -102.785672)
		(width 0.1143)
		(layer "In9.Cu")
		(net "UPI_CPU0_CPU1_P0P0_DN<18>")
	)
	(segment
		(start 159.978852 -106.155236)
		(end 170.846242 -116.523262)
		(width 0.1143)
		(layer "In9.Cu")
		(net "UPI_CPU0_CPU1_P0P0_DN<18>")
	)
	(segment
		(start 142.214854 -78.982062)
		(end 142.948152 -78.982062)
		(width 0.0889)
		(layer "In9.Cu")
		(net "UPI_CPU0_CPU1_P0P0_DN<18>")
	)
	(segment
		(start 139.366244 -77.297534)
		(end 139.39901 -77.297534)
		(width 0.0889)
		(layer "In9.Cu")
		(net "UPI_CPU0_CPU1_P0P0_DN<18>")
	)
	(segment
		(start 142.998952 -79.032862)
		(end 143.02105 -79.032862)
		(width 0.0889)
		(layer "In9.Cu")
		(net "UPI_CPU0_CPU1_P0P0_DN<18>")
	)
	(segment
		(start 141.520926 -78.288134)
		(end 142.214854 -78.982062)
		(width 0.0889)
		(layer "In9.Cu")
		(net "UPI_CPU0_CPU1_P0P0_DN<18>")
	)
	(segment
		(start 308.247796 -58.234834)
		(end 307.898546 -57.885584)
		(width 0.1143)
		(layer "In9.Cu")
		(net "UPI_CPU0_CPU1_P0P0_DN<18>")
	)
	(segment
		(start 149.523196 -90.32621)
		(end 155.639516 -97.564448)
		(width 0.1143)
		(layer "In9.Cu")
		(net "UPI_CPU0_CPU1_P0P0_DN<18>")
	)
	(segment
		(start 142.948152 -78.982062)
		(end 142.998952 -79.032862)
		(width 0.0889)
		(layer "In9.Cu")
		(net "UPI_CPU0_CPU1_P0P0_DN<18>")
	)
	(segment
		(start 308.864508 -58.5216)
		(end 308.577742 -58.234834)
		(width 0.1143)
		(layer "In9.Cu")
		(net "UPI_CPU0_CPU1_P0P0_DN<18>")
	)
	(segment
		(start 156.39923 -102.478332)
		(end 156.39923 -102.479348)
		(width 0.1143)
		(layer "In9.Cu")
		(net "UPI_CPU0_CPU1_P0P0_DN<18>")
	)
	(segment
		(start 135.441944 -73.440036)
		(end 135.435594 -73.450704)
		(width 0.0889)
		(layer "In9.Cu")
		(net "UPI_CPU0_CPU1_P0P0_DN<18>")
	)
	(segment
		(start 227.791772 -117.757448)
		(end 248.116344 -121.219214)
		(width 0.1143)
		(layer "In9.Cu")
		(net "UPI_CPU0_CPU1_P0P0_DN<18>")
	)
	(segment
		(start 140.228574 -77.793088)
		(end 140.413232 -77.793088)
		(width 0.0889)
		(layer "In9.Cu")
		(net "UPI_CPU0_CPU1_P0P0_DN<18>")
	)
	(segment
		(start 135.44677 -73.4314)
		(end 135.441944 -73.440036)
		(width 0.0889)
		(layer "In9.Cu")
		(net "UPI_CPU0_CPU1_P0P0_DN<18>")
	)
	(segment
		(start 135.932164 -75.316334)
		(end 135.96493 -75.316334)
		(width 0.0889)
		(layer "In9.Cu")
		(net "UPI_CPU0_CPU1_P0P0_DN<18>")
	)
	(segment
		(start 185.652156 -122.395742)
		(end 193.946272 -121.83237)
		(width 0.1143)
		(layer "In9.Cu")
		(net "UPI_CPU0_CPU1_P0P0_DN<18>")
	)
	(segment
		(start 325.529956 -98.032062)
		(end 321.985132 -80.62595)
		(width 0.1143)
		(layer "In9.Cu")
		(net "UPI_CPU0_CPU1_P0P0_DN<18>")
	)
	(segment
		(start 308.577742 -58.234834)
		(end 308.247796 -58.234834)
		(width 0.1143)
		(layer "In9.Cu")
		(net "UPI_CPU0_CPU1_P0P0_DN<18>")
	)
	(segment
		(start 310.881776 -115.545362)
		(end 323.674486 -103.72598)
		(width 0.1143)
		(layer "In9.Cu")
		(net "UPI_CPU0_CPU1_P0P0_DN<18>")
	)
	(segment
		(start 321.985132 -80.62595)
		(end 321.827906 -74.949304)
		(width 0.1143)
		(layer "In9.Cu")
		(net "UPI_CPU0_CPU1_P0P0_DN<18>")
	)
	(segment
		(start 143.02105 -79.032862)
		(end 143.902176 -79.032862)
		(width 0.1143)
		(layer "In9.Cu")
		(net "UPI_CPU0_CPU1_P0P0_DN<18>")
	)
	(segment
		(start 156.39542 -102.45344)
		(end 156.39923 -102.478332)
		(width 0.1143)
		(layer "In9.Cu")
		(net "UPI_CPU0_CPU1_P0P0_DN<18>")
	)
	(segment
		(start 317.87211 -64.396366)
		(end 311.333134 -58.5216)
		(width 0.1143)
		(layer "In9.Cu")
		(net "UPI_CPU0_CPU1_P0P0_DN<18>")
	)
	(segment
		(start 147.287996 -82.051144)
		(end 149.523196 -90.32621)
		(width 0.1143)
		(layer "In9.Cu")
		(net "UPI_CPU0_CPU1_P0P0_DN<18>")
	)
	(segment
		(start 311.333134 -58.5216)
		(end 308.864508 -58.5216)
		(width 0.1143)
		(layer "In9.Cu")
		(net "UPI_CPU0_CPU1_P0P0_DN<18>")
	)
	(segment
		(start 258.941062 -118.669054)
		(end 267.308076 -119.08155)
		(width 0.1143)
		(layer "In9.Cu")
		(net "UPI_CPU0_CPU1_P0P0_DN<18>")
	)
	(segment
		(start 137.649204 -76.306934)
		(end 137.68197 -76.306934)
		(width 0.0889)
		(layer "In9.Cu")
		(net "UPI_CPU0_CPU1_P0P0_DN<18>")
	)
	(segment
		(start 278.011636 -118.053866)
		(end 292.498018 -119.733822)
		(width 0.1143)
		(layer "In9.Cu")
		(net "UPI_CPU0_CPU1_P0P0_DN<18>")
	)
	(segment
		(start 135.441944 -74.430636)
		(end 135.435594 -74.441304)
		(width 0.0889)
		(layer "In9.Cu")
		(net "UPI_CPU0_CPU1_P0P0_DN<18>")
	)
	(segment
		(start 292.498018 -119.733822)
		(end 310.881776 -115.545362)
		(width 0.1143)
		(layer "In9.Cu")
		(net "UPI_CPU0_CPU1_P0P0_DN<18>")
	)
	(segment
		(start 170.846242 -116.523262)
		(end 180.644546 -120.910858)
		(width 0.1143)
		(layer "In9.Cu")
		(net "UPI_CPU0_CPU1_P0P0_DN<18>")
	)
	(segment
		(start 136.794494 -75.811888)
		(end 136.82726 -75.811888)
		(width 0.0889)
		(layer "In9.Cu")
		(net "UPI_CPU0_CPU1_P0P0_DN<18>")
	)
	(segment
		(start 248.116344 -121.219214)
		(end 258.941062 -118.669054)
		(width 0.1143)
		(layer "In9.Cu")
		(net "UPI_CPU0_CPU1_P0P0_DN<18>")
	)
	(segment
		(start 193.946272 -121.83237)
		(end 227.791772 -117.757448)
		(width 0.1143)
		(layer "In9.Cu")
		(net "UPI_CPU0_CPU1_P0P0_DN<18>")
	)
	(segment
		(start 143.902176 -79.032862)
		(end 147.287996 -82.051144)
		(width 0.1143)
		(layer "In9.Cu")
		(net "UPI_CPU0_CPU1_P0P0_DN<18>")
	)
	(segment
		(start 135.44677 -74.422)
		(end 135.441944 -74.430636)
		(width 0.0889)
		(layer "In9.Cu")
		(net "UPI_CPU0_CPU1_P0P0_DN<18>")
	)
	(segment
		(start 321.827906 -74.949304)
		(end 317.87211 -64.396366)
		(width 0.1143)
		(layer "In9.Cu")
		(net "UPI_CPU0_CPU1_P0P0_DN<18>")
	)
	(segment
		(start 140.93825 -78.272894)
		(end 141.135608 -78.288134)
		(width 0.0889)
		(layer "In9.Cu")
		(net "UPI_CPU0_CPU1_P0P0_DN<18>")
	)
	(segment
		(start 159.978598 -106.155236)
		(end 159.978852 -106.155236)
		(width 0.1143)
		(layer "In9.Cu")
		(net "UPI_CPU0_CPU1_P0P0_DN<18>")
	)
	(segment
		(start 180.644546 -120.910858)
		(end 185.652156 -122.395742)
		(width 0.1143)
		(layer "In9.Cu")
		(net "UPI_CPU0_CPU1_P0P0_DN<18>")
	)
	(segment
		(start 141.135608 -78.288134)
		(end 141.520926 -78.288134)
		(width 0.0889)
		(layer "In9.Cu")
		(net "UPI_CPU0_CPU1_P0P0_DN<18>")
	)
	(segment
		(start 267.308076 -119.08155)
		(end 278.011636 -118.053866)
		(width 0.1143)
		(layer "In9.Cu")
		(net "UPI_CPU0_CPU1_P0P0_DN<18>")
	)
	(segment
		(start 325.325232 -100.725732)
		(end 325.529956 -98.032062)
		(width 0.1143)
		(layer "In9.Cu")
		(net "UPI_CPU0_CPU1_P0P0_DN<18>")
	)
	(segment
		(start 155.639516 -97.564448)
		(end 156.39542 -102.451916)
		(width 0.1143)
		(layer "In9.Cu")
		(net "UPI_CPU0_CPU1_P0P0_DN<18>")
	)
	(segment
		(start 138.511534 -76.802488)
		(end 138.5443 -76.802488)
		(width 0.0889)
		(layer "In9.Cu")
		(net "UPI_CPU0_CPU1_P0P0_DN<18>")
	)
	(segment
		(start 156.39542 -102.451916)
		(end 156.39542 -102.45344)
		(width 0.1143)
		(layer "In9.Cu")
		(net "UPI_CPU0_CPU1_P0P0_DN<18>")
	)
	(segment
		(start 156.446728 -102.785672)
		(end 159.978598 -106.155236)
		(width 0.1143)
		(layer "In9.Cu")
		(net "UPI_CPU0_CPU1_P0P0_DN<18>")
	)
	(arc
		(start 139.734544 -77.497686)
		(mid 139.943152 -77.709618)
		(end 140.228574 -77.793088)
		(width 0.0889)
		(layer "In9.Cu")
		(net "UPI_CPU0_CPU1_P0P0_DN<18>")
	)
	(arc
		(start 135.435594 -74.441304)
		(mid 135.439625 -75.017486)
		(end 135.932164 -75.316334)
		(width 0.0889)
		(layer "In9.Cu")
		(net "UPI_CPU0_CPU1_P0P0_DN<18>")
	)
	(arc
		(start 136.82726 -75.811888)
		(mid 137.018902 -75.869054)
		(end 137.158984 -76.011786)
		(width 0.0889)
		(layer "In9.Cu")
		(net "UPI_CPU0_CPU1_P0P0_DN<18>")
	)
	(arc
		(start 135.441944 -73.039986)
		(mid 135.495414 -73.235049)
		(end 135.44677 -73.4314)
		(width 0.0889)
		(layer "In9.Cu")
		(net "UPI_CPU0_CPU1_P0P0_DN<18>")
	)
	(arc
		(start 138.017504 -76.507086)
		(mid 138.226112 -76.719018)
		(end 138.511534 -76.802488)
		(width 0.0889)
		(layer "In9.Cu")
		(net "UPI_CPU0_CPU1_P0P0_DN<18>")
	)
	(arc
		(start 138.876024 -77.002386)
		(mid 139.083028 -77.21325)
		(end 139.366244 -77.297534)
		(width 0.0889)
		(layer "In9.Cu")
		(net "UPI_CPU0_CPU1_P0P0_DN<18>")
	)
	(arc
		(start 135.095234 -72.249538)
		(mid 135.246892 -72.654279)
		(end 135.441944 -73.039986)
		(width 0.0889)
		(layer "In9.Cu")
		(net "UPI_CPU0_CPU1_P0P0_DN<18>")
	)
	(arc
		(start 135.441944 -74.030586)
		(mid 135.495414 -74.225649)
		(end 135.44677 -74.422)
		(width 0.0889)
		(layer "In9.Cu")
		(net "UPI_CPU0_CPU1_P0P0_DN<18>")
	)
	(arc
		(start 135.96493 -75.316334)
		(mid 136.15878 -75.372684)
		(end 136.300464 -75.516486)
		(width 0.0889)
		(layer "In9.Cu")
		(net "UPI_CPU0_CPU1_P0P0_DN<18>")
	)
	(arc
		(start 136.300464 -75.516486)
		(mid 136.509072 -75.728418)
		(end 136.794494 -75.811888)
		(width 0.0889)
		(layer "In9.Cu")
		(net "UPI_CPU0_CPU1_P0P0_DN<18>")
	)
	(arc
		(start 139.39901 -77.297534)
		(mid 139.59286 -77.353884)
		(end 139.734544 -77.497686)
		(width 0.0889)
		(layer "In9.Cu")
		(net "UPI_CPU0_CPU1_P0P0_DN<18>")
	)
	(arc
		(start 140.413232 -77.793088)
		(mid 140.538433 -77.872859)
		(end 140.629386 -77.990192)
		(width 0.0889)
		(layer "In9.Cu")
		(net "UPI_CPU0_CPU1_P0P0_DN<18>")
	)
	(arc
		(start 138.5443 -76.802488)
		(mid 138.735942 -76.859654)
		(end 138.876024 -77.002386)
		(width 0.0889)
		(layer "In9.Cu")
		(net "UPI_CPU0_CPU1_P0P0_DN<18>")
	)
	(arc
		(start 137.68197 -76.306934)
		(mid 137.87582 -76.363284)
		(end 138.017504 -76.507086)
		(width 0.0889)
		(layer "In9.Cu")
		(net "UPI_CPU0_CPU1_P0P0_DN<18>")
	)
	(arc
		(start 135.435594 -73.450704)
		(mid 135.362796 -73.741467)
		(end 135.441944 -74.030586)
		(width 0.0889)
		(layer "In9.Cu")
		(net "UPI_CPU0_CPU1_P0P0_DN<18>")
	)
	(arc
		(start 137.158984 -76.011786)
		(mid 137.365988 -76.22265)
		(end 137.649204 -76.306934)
		(width 0.0889)
		(layer "In9.Cu")
		(net "UPI_CPU0_CPU1_P0P0_DN<18>")
	)
	(arc
		(start 140.629386 -77.990192)
		(mid 140.75941 -78.158213)
		(end 140.93825 -78.272894)
		(width 0.0889)
		(layer "In9.Cu")
		(net "UPI_CPU0_CPU1_P0P0_DN<18>")
	)
	(segment
		(start 135.382254 -70.763384)
		(end 135.953754 -70.763384)
		(width 0.1143)
		(layer "F.Cu")
		(net "UPI_CPU0_CPU1_P0P0_DN<17>")
	)
	(segment
		(start 305.533806 -59.866784)
		(end 306.105306 -59.866784)
		(width 0.1143)
		(layer "F.Cu")
		(net "UPI_CPU0_CPU1_P0P0_DN<17>")
	)
	(via
		(at 135.953754 -70.763384)
		(size 0.508)
		(drill 0.254)
		(layers "F.Cu" "B.Cu")
		(net "UPI_CPU0_CPU1_P0P0_DN<17>")
	)
	(via
		(at 306.105306 -59.866784)
		(size 0.508)
		(drill 0.254)
		(layers "F.Cu" "B.Cu")
		(net "UPI_CPU0_CPU1_P0P0_DN<17>")
	)
	(segment
		(start 306.163218 -60.26277)
		(end 306.105306 -60.204858)
		(width 0.0889)
		(layer "In9.Cu")
		(net "UPI_CPU0_CPU1_P0P0_DN<17>")
	)
	(segment
		(start 292.462712 -119.0879)
		(end 310.573928 -114.96167)
		(width 0.1143)
		(layer "In9.Cu")
		(net "UPI_CPU0_CPU1_P0P0_DN<17>")
	)
	(segment
		(start 157.027626 -102.373176)
		(end 171.352718 -116.040154)
		(width 0.1143)
		(layer "In9.Cu")
		(net "UPI_CPU0_CPU1_P0P0_DN<17>")
	)
	(segment
		(start 285.200344 -118.24589)
		(end 291.125402 -118.93296)
		(width 0.1143)
		(layer "In9.Cu")
		(net "UPI_CPU0_CPU1_P0P0_DN<17>")
	)
	(segment
		(start 324.887336 -98.072448)
		(end 324.01256 -93.7768)
		(width 0.1143)
		(layer "In9.Cu")
		(net "UPI_CPU0_CPU1_P0P0_DN<17>")
	)
	(segment
		(start 156.242258 -97.28962)
		(end 157.027626 -102.373176)
		(width 0.1143)
		(layer "In9.Cu")
		(net "UPI_CPU0_CPU1_P0P0_DN<17>")
	)
	(segment
		(start 324.699884 -100.53955)
		(end 324.887336 -98.072448)
		(width 0.1143)
		(layer "In9.Cu")
		(net "UPI_CPU0_CPU1_P0P0_DN<17>")
	)
	(segment
		(start 310.573928 -114.96167)
		(end 323.097906 -103.387906)
		(width 0.1143)
		(layer "In9.Cu")
		(net "UPI_CPU0_CPU1_P0P0_DN<17>")
	)
	(segment
		(start 291.125402 -118.93296)
		(end 292.462712 -119.0879)
		(width 0.1143)
		(layer "In9.Cu")
		(net "UPI_CPU0_CPU1_P0P0_DN<17>")
	)
	(segment
		(start 317.330328 -64.76746)
		(end 311.094882 -59.164474)
		(width 0.1143)
		(layer "In9.Cu")
		(net "UPI_CPU0_CPU1_P0P0_DN<17>")
	)
	(segment
		(start 311.094882 -59.164474)
		(end 309.831994 -59.164474)
		(width 0.1143)
		(layer "In9.Cu")
		(net "UPI_CPU0_CPU1_P0P0_DN<17>")
	)
	(segment
		(start 267.29309 -118.442232)
		(end 278.01824 -117.412516)
		(width 0.1143)
		(layer "In9.Cu")
		(net "UPI_CPU0_CPU1_P0P0_DN<17>")
	)
	(segment
		(start 308.210966 -59.276234)
		(end 307.695854 -59.276234)
		(width 0.0889)
		(layer "In9.Cu")
		(net "UPI_CPU0_CPU1_P0P0_DN<17>")
	)
	(segment
		(start 323.169026 -103.32212)
		(end 324.699884 -100.53955)
		(width 0.1143)
		(layer "In9.Cu")
		(net "UPI_CPU0_CPU1_P0P0_DN<17>")
	)
	(segment
		(start 306.105306 -60.204858)
		(end 306.105306 -59.866784)
		(width 0.0889)
		(layer "In9.Cu")
		(net "UPI_CPU0_CPU1_P0P0_DN<17>")
	)
	(segment
		(start 136.794494 -74.821288)
		(end 136.82726 -74.821288)
		(width 0.0889)
		(layer "In9.Cu")
		(net "UPI_CPU0_CPU1_P0P0_DN<17>")
	)
	(segment
		(start 150.117048 -90.041476)
		(end 156.242258 -97.28962)
		(width 0.1143)
		(layer "In9.Cu")
		(net "UPI_CPU0_CPU1_P0P0_DN<17>")
	)
	(segment
		(start 317.697358 -65.74663)
		(end 317.330328 -64.76746)
		(width 0.1143)
		(layer "In9.Cu")
		(net "UPI_CPU0_CPU1_P0P0_DN<17>")
	)
	(segment
		(start 135.932164 -72.344534)
		(end 135.96493 -72.344534)
		(width 0.0889)
		(layer "In9.Cu")
		(net "UPI_CPU0_CPU1_P0P0_DN<17>")
	)
	(segment
		(start 144.981168 -78.229714)
		(end 145.031968 -78.280514)
		(width 0.0889)
		(layer "In9.Cu")
		(net "UPI_CPU0_CPU1_P0P0_DN<17>")
	)
	(segment
		(start 318.702436 -68.4276)
		(end 317.697358 -65.74663)
		(width 0.1143)
		(layer "In9.Cu")
		(net "UPI_CPU0_CPU1_P0P0_DN<17>")
	)
	(segment
		(start 309.831994 -59.164474)
		(end 309.809896 -59.164474)
		(width 0.0889)
		(layer "In9.Cu")
		(net "UPI_CPU0_CPU1_P0P0_DN<17>")
	)
	(segment
		(start 138.511534 -75.811888)
		(end 138.5443 -75.811888)
		(width 0.0889)
		(layer "In9.Cu")
		(net "UPI_CPU0_CPU1_P0P0_DN<17>")
	)
	(segment
		(start 137.649204 -75.316334)
		(end 137.68197 -75.316334)
		(width 0.0889)
		(layer "In9.Cu")
		(net "UPI_CPU0_CPU1_P0P0_DN<17>")
	)
	(segment
		(start 258.882388 -118.027704)
		(end 267.29309 -118.442232)
		(width 0.1143)
		(layer "In9.Cu")
		(net "UPI_CPU0_CPU1_P0P0_DN<17>")
	)
	(segment
		(start 308.271926 -59.215274)
		(end 308.210966 -59.276234)
		(width 0.0889)
		(layer "In9.Cu")
		(net "UPI_CPU0_CPU1_P0P0_DN<17>")
	)
	(segment
		(start 145.24736 -78.280514)
		(end 147.540218 -80.541876)
		(width 0.1143)
		(layer "In9.Cu")
		(net "UPI_CPU0_CPU1_P0P0_DN<17>")
	)
	(segment
		(start 185.662062 -121.735088)
		(end 194.515232 -121.134632)
		(width 0.1143)
		(layer "In9.Cu")
		(net "UPI_CPU0_CPU1_P0P0_DN<17>")
	)
	(segment
		(start 321.50177 -81.915)
		(end 321.211194 -81.150206)
		(width 0.1143)
		(layer "In9.Cu")
		(net "UPI_CPU0_CPU1_P0P0_DN<17>")
	)
	(segment
		(start 194.515232 -121.134632)
		(end 227.852732 -117.120924)
		(width 0.1143)
		(layer "In9.Cu")
		(net "UPI_CPU0_CPU1_P0P0_DN<17>")
	)
	(segment
		(start 227.852732 -117.120924)
		(end 248.095262 -120.56872)
		(width 0.1143)
		(layer "In9.Cu")
		(net "UPI_CPU0_CPU1_P0P0_DN<17>")
	)
	(segment
		(start 141.63294 -77.297534)
		(end 142.56512 -78.229714)
		(width 0.0889)
		(layer "In9.Cu")
		(net "UPI_CPU0_CPU1_P0P0_DN<17>")
	)
	(segment
		(start 321.174618 -79.8322)
		(end 321.031108 -74.638662)
		(width 0.1143)
		(layer "In9.Cu")
		(net "UPI_CPU0_CPU1_P0P0_DN<17>")
	)
	(segment
		(start 136.300464 -73.535286)
		(end 136.30529 -73.543922)
		(width 0.0889)
		(layer "In9.Cu")
		(net "UPI_CPU0_CPU1_P0P0_DN<17>")
	)
	(segment
		(start 147.540218 -80.541876)
		(end 150.117048 -90.041476)
		(width 0.1143)
		(layer "In9.Cu")
		(net "UPI_CPU0_CPU1_P0P0_DN<17>")
	)
	(segment
		(start 145.031968 -78.280514)
		(end 145.054066 -78.280514)
		(width 0.0889)
		(layer "In9.Cu")
		(net "UPI_CPU0_CPU1_P0P0_DN<17>")
	)
	(segment
		(start 323.097906 -103.387906)
		(end 323.169026 -103.32212)
		(width 0.1143)
		(layer "In9.Cu")
		(net "UPI_CPU0_CPU1_P0P0_DN<17>")
	)
	(segment
		(start 321.707256 -82.455512)
		(end 321.50177 -81.915)
		(width 0.1143)
		(layer "In9.Cu")
		(net "UPI_CPU0_CPU1_P0P0_DN<17>")
	)
	(segment
		(start 285.200344 -118.245636)
		(end 285.200344 -118.24589)
		(width 0.1143)
		(layer "In9.Cu")
		(net "UPI_CPU0_CPU1_P0P0_DN<17>")
	)
	(segment
		(start 139.366244 -76.306934)
		(end 139.39901 -76.306934)
		(width 0.0889)
		(layer "In9.Cu")
		(net "UPI_CPU0_CPU1_P0P0_DN<17>")
	)
	(segment
		(start 183.61787 -121.129298)
		(end 185.662062 -121.735088)
		(width 0.1143)
		(layer "In9.Cu")
		(net "UPI_CPU0_CPU1_P0P0_DN<17>")
	)
	(segment
		(start 175.356012 -117.828314)
		(end 181.03088 -120.36298)
		(width 0.1143)
		(layer "In9.Cu")
		(net "UPI_CPU0_CPU1_P0P0_DN<17>")
	)
	(segment
		(start 307.130704 -59.771534)
		(end 306.950872 -59.771534)
		(width 0.0889)
		(layer "In9.Cu")
		(net "UPI_CPU0_CPU1_P0P0_DN<17>")
	)
	(segment
		(start 181.03088 -120.36298)
		(end 183.61787 -121.129298)
		(width 0.1143)
		(layer "In9.Cu")
		(net "UPI_CPU0_CPU1_P0P0_DN<17>")
	)
	(segment
		(start 140.977874 -77.297534)
		(end 141.63294 -77.297534)
		(width 0.0889)
		(layer "In9.Cu")
		(net "UPI_CPU0_CPU1_P0P0_DN<17>")
	)
	(segment
		(start 140.228574 -76.802488)
		(end 140.413232 -76.802488)
		(width 0.0889)
		(layer "In9.Cu")
		(net "UPI_CPU0_CPU1_P0P0_DN<17>")
	)
	(segment
		(start 309.759096 -59.215274)
		(end 308.271926 -59.215274)
		(width 0.0889)
		(layer "In9.Cu")
		(net "UPI_CPU0_CPU1_P0P0_DN<17>")
	)
	(segment
		(start 278.01824 -117.412516)
		(end 285.200344 -118.245636)
		(width 0.1143)
		(layer "In9.Cu")
		(net "UPI_CPU0_CPU1_P0P0_DN<17>")
	)
	(segment
		(start 321.211194 -81.150206)
		(end 321.174618 -79.8322)
		(width 0.1143)
		(layer "In9.Cu")
		(net "UPI_CPU0_CPU1_P0P0_DN<17>")
	)
	(segment
		(start 145.054066 -78.280514)
		(end 145.24736 -78.280514)
		(width 0.1143)
		(layer "In9.Cu")
		(net "UPI_CPU0_CPU1_P0P0_DN<17>")
	)
	(segment
		(start 324.01256 -93.7768)
		(end 321.707256 -82.455512)
		(width 0.1143)
		(layer "In9.Cu")
		(net "UPI_CPU0_CPU1_P0P0_DN<17>")
	)
	(segment
		(start 321.031108 -74.638662)
		(end 318.702436 -68.4276)
		(width 0.1143)
		(layer "In9.Cu")
		(net "UPI_CPU0_CPU1_P0P0_DN<17>")
	)
	(segment
		(start 136.294114 -73.524618)
		(end 136.300464 -73.535286)
		(width 0.0889)
		(layer "In9.Cu")
		(net "UPI_CPU0_CPU1_P0P0_DN<17>")
	)
	(segment
		(start 142.56512 -78.229714)
		(end 144.981168 -78.229714)
		(width 0.0889)
		(layer "In9.Cu")
		(net "UPI_CPU0_CPU1_P0P0_DN<17>")
	)
	(segment
		(start 309.809896 -59.164474)
		(end 309.759096 -59.215274)
		(width 0.0889)
		(layer "In9.Cu")
		(net "UPI_CPU0_CPU1_P0P0_DN<17>")
	)
	(segment
		(start 171.352718 -116.040154)
		(end 175.356012 -117.828314)
		(width 0.1143)
		(layer "In9.Cu")
		(net "UPI_CPU0_CPU1_P0P0_DN<17>")
	)
	(segment
		(start 248.095262 -120.56872)
		(end 258.882388 -118.027704)
		(width 0.1143)
		(layer "In9.Cu")
		(net "UPI_CPU0_CPU1_P0P0_DN<17>")
	)
	(arc
		(start 136.30529 -73.543922)
		(mid 136.354045 -73.740274)
		(end 136.300464 -73.935336)
		(width 0.0889)
		(layer "In9.Cu")
		(net "UPI_CPU0_CPU1_P0P0_DN<17>")
	)
	(arc
		(start 136.300464 -73.935336)
		(mid 136.296135 -74.518508)
		(end 136.794494 -74.821288)
		(width 0.0889)
		(layer "In9.Cu")
		(net "UPI_CPU0_CPU1_P0P0_DN<17>")
	)
	(arc
		(start 140.413232 -76.802488)
		(mid 140.538433 -76.882259)
		(end 140.629386 -76.999592)
		(width 0.0889)
		(layer "In9.Cu")
		(net "UPI_CPU0_CPU1_P0P0_DN<17>")
	)
	(arc
		(start 138.876024 -76.011786)
		(mid 139.083028 -76.22265)
		(end 139.366244 -76.306934)
		(width 0.0889)
		(layer "In9.Cu")
		(net "UPI_CPU0_CPU1_P0P0_DN<17>")
	)
	(arc
		(start 140.629386 -76.999592)
		(mid 140.775311 -77.181679)
		(end 140.977874 -77.297534)
		(width 0.0889)
		(layer "In9.Cu")
		(net "UPI_CPU0_CPU1_P0P0_DN<17>")
	)
	(arc
		(start 307.695854 -59.276234)
		(mid 307.676555 -59.283283)
		(end 307.6575 -59.290966)
		(width 0.0889)
		(layer "In9.Cu")
		(net "UPI_CPU0_CPU1_P0P0_DN<17>")
	)
	(arc
		(start 307.6575 -59.290966)
		(mid 307.477606 -59.405767)
		(end 307.346858 -59.57443)
		(width 0.0889)
		(layer "In9.Cu")
		(net "UPI_CPU0_CPU1_P0P0_DN<17>")
	)
	(arc
		(start 137.68197 -75.316334)
		(mid 137.87582 -75.372684)
		(end 138.017504 -75.516486)
		(width 0.0889)
		(layer "In9.Cu")
		(net "UPI_CPU0_CPU1_P0P0_DN<17>")
	)
	(arc
		(start 135.953754 -70.763384)
		(mid 135.854664 -70.956384)
		(end 135.7122 -71.12)
		(width 0.0889)
		(layer "In9.Cu")
		(net "UPI_CPU0_CPU1_P0P0_DN<17>")
	)
	(arc
		(start 135.435594 -71.469504)
		(mid 135.439625 -72.045686)
		(end 135.932164 -72.344534)
		(width 0.0889)
		(layer "In9.Cu")
		(net "UPI_CPU0_CPU1_P0P0_DN<17>")
	)
	(arc
		(start 135.96493 -72.344534)
		(mid 136.303099 -72.549332)
		(end 136.300464 -72.944736)
		(width 0.0889)
		(layer "In9.Cu")
		(net "UPI_CPU0_CPU1_P0P0_DN<17>")
	)
	(arc
		(start 136.300464 -72.944736)
		(mid 136.221242 -73.233854)
		(end 136.294114 -73.524618)
		(width 0.0889)
		(layer "In9.Cu")
		(net "UPI_CPU0_CPU1_P0P0_DN<17>")
	)
	(arc
		(start 307.346858 -59.57443)
		(mid 307.255914 -59.691773)
		(end 307.130704 -59.771534)
		(width 0.0889)
		(layer "In9.Cu")
		(net "UPI_CPU0_CPU1_P0P0_DN<17>")
	)
	(arc
		(start 135.7122 -71.12)
		(mid 135.559208 -71.283126)
		(end 135.435594 -71.469504)
		(width 0.0889)
		(layer "In9.Cu")
		(net "UPI_CPU0_CPU1_P0P0_DN<17>")
	)
	(arc
		(start 138.017504 -75.516486)
		(mid 138.226112 -75.728418)
		(end 138.511534 -75.811888)
		(width 0.0889)
		(layer "In9.Cu")
		(net "UPI_CPU0_CPU1_P0P0_DN<17>")
	)
	(arc
		(start 138.5443 -75.811888)
		(mid 138.735942 -75.869054)
		(end 138.876024 -76.011786)
		(width 0.0889)
		(layer "In9.Cu")
		(net "UPI_CPU0_CPU1_P0P0_DN<17>")
	)
	(arc
		(start 136.82726 -74.821288)
		(mid 137.018902 -74.878454)
		(end 137.158984 -75.021186)
		(width 0.0889)
		(layer "In9.Cu")
		(net "UPI_CPU0_CPU1_P0P0_DN<17>")
	)
	(arc
		(start 139.39901 -76.306934)
		(mid 139.59286 -76.363284)
		(end 139.734544 -76.507086)
		(width 0.0889)
		(layer "In9.Cu")
		(net "UPI_CPU0_CPU1_P0P0_DN<17>")
	)
	(arc
		(start 306.950872 -59.771534)
		(mid 306.662727 -59.853853)
		(end 306.452016 -60.066936)
		(width 0.0889)
		(layer "In9.Cu")
		(net "UPI_CPU0_CPU1_P0P0_DN<17>")
	)
	(arc
		(start 139.734544 -76.507086)
		(mid 139.943152 -76.719018)
		(end 140.228574 -76.802488)
		(width 0.0889)
		(layer "In9.Cu")
		(net "UPI_CPU0_CPU1_P0P0_DN<17>")
	)
	(arc
		(start 306.452016 -60.066936)
		(mid 306.330071 -60.197968)
		(end 306.163218 -60.26277)
		(width 0.0889)
		(layer "In9.Cu")
		(net "UPI_CPU0_CPU1_P0P0_DN<17>")
	)
	(arc
		(start 137.158984 -75.021186)
		(mid 137.365988 -75.23205)
		(end 137.649204 -75.316334)
		(width 0.0889)
		(layer "In9.Cu")
		(net "UPI_CPU0_CPU1_P0P0_DN<17>")
	)
	(segment
		(start 307.250846 -60.857384)
		(end 307.898546 -60.857384)
		(width 0.1143)
		(layer "F.Cu")
		(net "UPI_CPU0_CPU1_P0P0_DN<16>")
	)
	(segment
		(start 136.240774 -70.268084)
		(end 136.812274 -70.268084)
		(width 0.1143)
		(layer "F.Cu")
		(net "UPI_CPU0_CPU1_P0P0_DN<16>")
	)
	(via
		(at 307.898546 -60.857384)
		(size 0.508)
		(drill 0.254)
		(layers "F.Cu" "B.Cu")
		(net "UPI_CPU0_CPU1_P0P0_DN<16>")
	)
	(via
		(at 136.812274 -70.268084)
		(size 0.508)
		(drill 0.254)
		(layers "F.Cu" "B.Cu")
		(net "UPI_CPU0_CPU1_P0P0_DN<16>")
	)
	(segment
		(start 310.100218 -114.115596)
		(end 322.432426 -102.722426)
		(width 0.1143)
		(layer "In9.Cu")
		(net "UPI_CPU0_CPU1_P0P0_DN<16>")
	)
	(segment
		(start 136.812274 -70.268084)
		(end 136.519158 -70.099174)
		(width 0.0889)
		(layer "In9.Cu")
		(net "UPI_CPU0_CPU1_P0P0_DN<16>")
	)
	(segment
		(start 148.317204 -79.853028)
		(end 150.960074 -89.598246)
		(width 0.1143)
		(layer "In9.Cu")
		(net "UPI_CPU0_CPU1_P0P0_DN<16>")
	)
	(segment
		(start 140.235178 -75.621388)
		(end 140.449554 -75.621388)
		(width 0.0889)
		(layer "In9.Cu")
		(net "UPI_CPU0_CPU1_P0P0_DN<16>")
	)
	(segment
		(start 137.330434 -73.524618)
		(end 137.324084 -73.535286)
		(width 0.0889)
		(layer "In9.Cu")
		(net "UPI_CPU0_CPU1_P0P0_DN<16>")
	)
	(segment
		(start 143.818356 -77.272134)
		(end 143.869156 -77.221334)
		(width 0.0889)
		(layer "In9.Cu")
		(net "UPI_CPU0_CPU1_P0P0_DN<16>")
	)
	(segment
		(start 308.60492 -60.056014)
		(end 308.2036 -60.457334)
		(width 0.0889)
		(layer "In9.Cu")
		(net "UPI_CPU0_CPU1_P0P0_DN<16>")
	)
	(segment
		(start 142.506954 -76.830174)
		(end 142.632938 -76.956158)
		(width 0.0889)
		(layer "In9.Cu")
		(net "UPI_CPU0_CPU1_P0P0_DN<16>")
	)
	(segment
		(start 137.330434 -72.534018)
		(end 137.324084 -72.544686)
		(width 0.0889)
		(layer "In9.Cu")
		(net "UPI_CPU0_CPU1_P0P0_DN<16>")
	)
	(segment
		(start 323.95033 -98.131376)
		(end 323.063616 -93.7768)
		(width 0.1143)
		(layer "In9.Cu")
		(net "UPI_CPU0_CPU1_P0P0_DN<16>")
	)
	(segment
		(start 143.869156 -77.221334)
		(end 143.891254 -77.221334)
		(width 0.0889)
		(layer "In9.Cu")
		(net "UPI_CPU0_CPU1_P0P0_DN<16>")
	)
	(segment
		(start 319.897252 -78.367382)
		(end 319.890648 -78.138274)
		(width 0.1143)
		(layer "In9.Cu")
		(net "UPI_CPU0_CPU1_P0P0_DN<16>")
	)
	(segment
		(start 320.066924 -78.527402)
		(end 319.897252 -78.367382)
		(width 0.1143)
		(layer "In9.Cu")
		(net "UPI_CPU0_CPU1_P0P0_DN<16>")
	)
	(segment
		(start 323.063616 -93.7768)
		(end 320.903092 -83.167474)
		(width 0.1143)
		(layer "In9.Cu")
		(net "UPI_CPU0_CPU1_P0P0_DN<16>")
	)
	(segment
		(start 320.029586 -77.181456)
		(end 320.023236 -76.952602)
		(width 0.1143)
		(layer "In9.Cu")
		(net "UPI_CPU0_CPU1_P0P0_DN<16>")
	)
	(segment
		(start 157.898592 -101.918516)
		(end 164.840412 -108.541566)
		(width 0.1143)
		(layer "In9.Cu")
		(net "UPI_CPU0_CPU1_P0P0_DN<16>")
	)
	(segment
		(start 175.578008 -116.866162)
		(end 179.644294 -118.730776)
		(width 0.1143)
		(layer "In9.Cu")
		(net "UPI_CPU0_CPU1_P0P0_DN<16>")
	)
	(segment
		(start 320.073274 -78.756256)
		(end 320.066924 -78.527402)
		(width 0.1143)
		(layer "In9.Cu")
		(net "UPI_CPU0_CPU1_P0P0_DN<16>")
	)
	(segment
		(start 142.126462 -76.321158)
		(end 142.126462 -76.449682)
		(width 0.0889)
		(layer "In9.Cu")
		(net "UPI_CPU0_CPU1_P0P0_DN<16>")
	)
	(segment
		(start 323.788024 -100.268024)
		(end 323.95033 -98.131376)
		(width 0.1143)
		(layer "In9.Cu")
		(net "UPI_CPU0_CPU1_P0P0_DN<16>")
	)
	(segment
		(start 319.95618 -80.500474)
		(end 320.116962 -80.331056)
		(width 0.1143)
		(layer "In9.Cu")
		(net "UPI_CPU0_CPU1_P0P0_DN<16>")
	)
	(segment
		(start 143.424402 -77.17917)
		(end 143.517366 -77.272134)
		(width 0.0889)
		(layer "In9.Cu")
		(net "UPI_CPU0_CPU1_P0P0_DN<16>")
	)
	(segment
		(start 142.887446 -77.210666)
		(end 142.948914 -77.272134)
		(width 0.0889)
		(layer "In9.Cu")
		(net "UPI_CPU0_CPU1_P0P0_DN<16>")
	)
	(segment
		(start 319.986152 -75.606656)
		(end 319.95364 -74.417936)
		(width 0.1143)
		(layer "In9.Cu")
		(net "UPI_CPU0_CPU1_P0P0_DN<16>")
	)
	(segment
		(start 310.751982 -60.106814)
		(end 309.667402 -60.106814)
		(width 0.1143)
		(layer "In9.Cu")
		(net "UPI_CPU0_CPU1_P0P0_DN<16>")
	)
	(segment
		(start 319.875408 -77.579982)
		(end 319.868804 -77.350874)
		(width 0.1143)
		(layer "In9.Cu")
		(net "UPI_CPU0_CPU1_P0P0_DN<16>")
	)
	(segment
		(start 142.000478 -76.195174)
		(end 142.126462 -76.321158)
		(width 0.0889)
		(layer "In9.Cu")
		(net "UPI_CPU0_CPU1_P0P0_DN<16>")
	)
	(segment
		(start 320.05143 -77.968856)
		(end 320.04508 -77.740002)
		(width 0.1143)
		(layer "In9.Cu")
		(net "UPI_CPU0_CPU1_P0P0_DN<16>")
	)
	(segment
		(start 307.593238 -60.695586)
		(end 307.594 -60.696094)
		(width 0.0889)
		(layer "In9.Cu")
		(net "UPI_CPU0_CPU1_P0P0_DN<16>")
	)
	(segment
		(start 142.506954 -76.70165)
		(end 142.506954 -76.830174)
		(width 0.0889)
		(layer "In9.Cu")
		(net "UPI_CPU0_CPU1_P0P0_DN<16>")
	)
	(segment
		(start 309.645304 -60.106814)
		(end 309.594504 -60.056014)
		(width 0.0889)
		(layer "In9.Cu")
		(net "UPI_CPU0_CPU1_P0P0_DN<16>")
	)
	(segment
		(start 137.655808 -74.135234)
		(end 137.688574 -74.135234)
		(width 0.0889)
		(layer "In9.Cu")
		(net "UPI_CPU0_CPU1_P0P0_DN<16>")
	)
	(segment
		(start 142.761462 -76.956158)
		(end 142.887446 -77.082142)
		(width 0.0889)
		(layer "In9.Cu")
		(net "UPI_CPU0_CPU1_P0P0_DN<16>")
	)
	(segment
		(start 320.132202 -80.889602)
		(end 319.962784 -80.729582)
		(width 0.1143)
		(layer "In9.Cu")
		(net "UPI_CPU0_CPU1_P0P0_DN<16>")
	)
	(segment
		(start 319.934336 -79.713074)
		(end 320.095118 -79.543656)
		(width 0.1143)
		(layer "In9.Cu")
		(net "UPI_CPU0_CPU1_P0P0_DN<16>")
	)
	(segment
		(start 292.412166 -118.145306)
		(end 310.100218 -114.115596)
		(width 0.1143)
		(layer "In9.Cu")
		(net "UPI_CPU0_CPU1_P0P0_DN<16>")
	)
	(segment
		(start 142.126462 -76.449682)
		(end 142.252446 -76.575666)
		(width 0.0889)
		(layer "In9.Cu")
		(net "UPI_CPU0_CPU1_P0P0_DN<16>")
	)
	(segment
		(start 309.667402 -60.106814)
		(end 309.645304 -60.106814)
		(width 0.0889)
		(layer "In9.Cu")
		(net "UPI_CPU0_CPU1_P0P0_DN<16>")
	)
	(segment
		(start 322.4784 -102.648258)
		(end 323.625718 -100.562918)
		(width 0.1143)
		(layer "In9.Cu")
		(net "UPI_CPU0_CPU1_P0P0_DN<16>")
	)
	(segment
		(start 320.088768 -79.314802)
		(end 319.919096 -79.154782)
		(width 0.1143)
		(layer "In9.Cu")
		(net "UPI_CPU0_CPU1_P0P0_DN<16>")
	)
	(segment
		(start 320.110612 -80.102202)
		(end 319.94094 -79.942182)
		(width 0.1143)
		(layer "In9.Cu")
		(net "UPI_CPU0_CPU1_P0P0_DN<16>")
	)
	(segment
		(start 323.625718 -100.562918)
		(end 323.788024 -100.268024)
		(width 0.1143)
		(layer "In9.Cu")
		(net "UPI_CPU0_CPU1_P0P0_DN<16>")
	)
	(segment
		(start 138.518138 -74.630788)
		(end 138.550904 -74.630788)
		(width 0.0889)
		(layer "In9.Cu")
		(net "UPI_CPU0_CPU1_P0P0_DN<16>")
	)
	(segment
		(start 141.014196 -76.116434)
		(end 141.793214 -76.116434)
		(width 0.0889)
		(layer "In9.Cu")
		(net "UPI_CPU0_CPU1_P0P0_DN<16>")
	)
	(segment
		(start 319.937892 -79.8322)
		(end 319.934336 -79.713074)
		(width 0.1143)
		(layer "In9.Cu")
		(net "UPI_CPU0_CPU1_P0P0_DN<16>")
	)
	(segment
		(start 157.121098 -96.889062)
		(end 157.898592 -101.918516)
		(width 0.1143)
		(layer "In9.Cu")
		(net "UPI_CPU0_CPU1_P0P0_DN<16>")
	)
	(segment
		(start 319.962784 -80.729582)
		(end 319.95618 -80.500474)
		(width 0.1143)
		(layer "In9.Cu")
		(net "UPI_CPU0_CPU1_P0P0_DN<16>")
	)
	(segment
		(start 142.38097 -76.575666)
		(end 142.506954 -76.70165)
		(width 0.0889)
		(layer "In9.Cu")
		(net "UPI_CPU0_CPU1_P0P0_DN<16>")
	)
	(segment
		(start 320.001392 -76.165202)
		(end 319.83172 -76.005182)
		(width 0.1143)
		(layer "In9.Cu")
		(net "UPI_CPU0_CPU1_P0P0_DN<16>")
	)
	(segment
		(start 319.853564 -76.792582)
		(end 319.84696 -76.563474)
		(width 0.1143)
		(layer "In9.Cu")
		(net "UPI_CPU0_CPU1_P0P0_DN<16>")
	)
	(segment
		(start 322.442586 -102.713282)
		(end 322.4784 -102.648258)
		(width 0.1143)
		(layer "In9.Cu")
		(net "UPI_CPU0_CPU1_P0P0_DN<16>")
	)
	(segment
		(start 319.890648 -78.138274)
		(end 320.05143 -77.968856)
		(width 0.1143)
		(layer "In9.Cu")
		(net "UPI_CPU0_CPU1_P0P0_DN<16>")
	)
	(segment
		(start 320.095118 -79.543656)
		(end 320.088768 -79.314802)
		(width 0.1143)
		(layer "In9.Cu")
		(net "UPI_CPU0_CPU1_P0P0_DN<16>")
	)
	(segment
		(start 319.868804 -77.350874)
		(end 320.029586 -77.181456)
		(width 0.1143)
		(layer "In9.Cu")
		(net "UPI_CPU0_CPU1_P0P0_DN<16>")
	)
	(segment
		(start 141.793214 -76.116434)
		(end 141.871954 -76.195174)
		(width 0.0889)
		(layer "In9.Cu")
		(net "UPI_CPU0_CPU1_P0P0_DN<16>")
	)
	(segment
		(start 142.252446 -76.575666)
		(end 142.38097 -76.575666)
		(width 0.0889)
		(layer "In9.Cu")
		(net "UPI_CPU0_CPU1_P0P0_DN<16>")
	)
	(segment
		(start 319.84696 -76.563474)
		(end 320.007742 -76.394056)
		(width 0.1143)
		(layer "In9.Cu")
		(net "UPI_CPU0_CPU1_P0P0_DN<16>")
	)
	(segment
		(start 320.427096 -81.915)
		(end 320.139822 -81.15935)
		(width 0.1143)
		(layer "In9.Cu")
		(net "UPI_CPU0_CPU1_P0P0_DN<16>")
	)
	(segment
		(start 319.83172 -76.005182)
		(end 319.825116 -75.776074)
		(width 0.1143)
		(layer "In9.Cu")
		(net "UPI_CPU0_CPU1_P0P0_DN<16>")
	)
	(segment
		(start 319.94094 -79.942182)
		(end 319.937892 -79.8322)
		(width 0.1143)
		(layer "In9.Cu")
		(net "UPI_CPU0_CPU1_P0P0_DN<16>")
	)
	(segment
		(start 136.519158 -70.099174)
		(end 136.440418 -70.12051)
		(width 0.0889)
		(layer "In9.Cu")
		(net "UPI_CPU0_CPU1_P0P0_DN<16>")
	)
	(segment
		(start 136.801098 -71.658988)
		(end 136.833864 -71.658988)
		(width 0.0889)
		(layer "In9.Cu")
		(net "UPI_CPU0_CPU1_P0P0_DN<16>")
	)
	(segment
		(start 141.871954 -76.195174)
		(end 142.000478 -76.195174)
		(width 0.0889)
		(layer "In9.Cu")
		(net "UPI_CPU0_CPU1_P0P0_DN<16>")
	)
	(segment
		(start 308.2036 -60.457334)
		(end 307.65242 -60.457334)
		(width 0.0889)
		(layer "In9.Cu")
		(net "UPI_CPU0_CPU1_P0P0_DN<16>")
	)
	(segment
		(start 319.912492 -78.925674)
		(end 320.073274 -78.756256)
		(width 0.1143)
		(layer "In9.Cu")
		(net "UPI_CPU0_CPU1_P0P0_DN<16>")
	)
	(segment
		(start 320.023236 -76.952602)
		(end 319.853564 -76.792582)
		(width 0.1143)
		(layer "In9.Cu")
		(net "UPI_CPU0_CPU1_P0P0_DN<16>")
	)
	(segment
		(start 181.25694 -119.470424)
		(end 182.931054 -119.958612)
		(width 0.1143)
		(layer "In9.Cu")
		(net "UPI_CPU0_CPU1_P0P0_DN<16>")
	)
	(segment
		(start 137.324084 -73.535286)
		(end 137.319258 -73.543922)
		(width 0.0889)
		(layer "In9.Cu")
		(net "UPI_CPU0_CPU1_P0P0_DN<16>")
	)
	(segment
		(start 319.825116 -75.776074)
		(end 319.986152 -75.606656)
		(width 0.1143)
		(layer "In9.Cu")
		(net "UPI_CPU0_CPU1_P0P0_DN<16>")
	)
	(segment
		(start 142.948914 -77.272134)
		(end 143.153638 -77.272134)
		(width 0.0889)
		(layer "In9.Cu")
		(net "UPI_CPU0_CPU1_P0P0_DN<16>")
	)
	(segment
		(start 320.903092 -83.167474)
		(end 320.427096 -81.915)
		(width 0.1143)
		(layer "In9.Cu")
		(net "UPI_CPU0_CPU1_P0P0_DN<16>")
	)
	(segment
		(start 194.26047 -120.216168)
		(end 227.83038 -116.174012)
		(width 0.1143)
		(layer "In9.Cu")
		(net "UPI_CPU0_CPU1_P0P0_DN<16>")
	)
	(segment
		(start 258.79679 -117.092476)
		(end 267.271246 -117.510052)
		(width 0.1143)
		(layer "In9.Cu")
		(net "UPI_CPU0_CPU1_P0P0_DN<16>")
	)
	(segment
		(start 185.891678 -120.821704)
		(end 194.26047 -120.216168)
		(width 0.1143)
		(layer "In9.Cu")
		(net "UPI_CPU0_CPU1_P0P0_DN<16>")
	)
	(segment
		(start 142.887446 -77.082142)
		(end 142.887446 -77.210666)
		(width 0.0889)
		(layer "In9.Cu")
		(net "UPI_CPU0_CPU1_P0P0_DN<16>")
	)
	(segment
		(start 145.565622 -77.221334)
		(end 145.943828 -77.370686)
		(width 0.1143)
		(layer "In9.Cu")
		(net "UPI_CPU0_CPU1_P0P0_DN<16>")
	)
	(segment
		(start 145.943828 -77.370686)
		(end 148.317204 -79.853028)
		(width 0.1143)
		(layer "In9.Cu")
		(net "UPI_CPU0_CPU1_P0P0_DN<16>")
	)
	(segment
		(start 317.708788 -68.4276)
		(end 317.697358 -68.39712)
		(width 0.1143)
		(layer "In9.Cu")
		(net "UPI_CPU0_CPU1_P0P0_DN<16>")
	)
	(segment
		(start 143.891254 -77.221334)
		(end 145.565622 -77.221334)
		(width 0.1143)
		(layer "In9.Cu")
		(net "UPI_CPU0_CPU1_P0P0_DN<16>")
	)
	(segment
		(start 320.007742 -76.394056)
		(end 320.001392 -76.165202)
		(width 0.1143)
		(layer "In9.Cu")
		(net "UPI_CPU0_CPU1_P0P0_DN<16>")
	)
	(segment
		(start 319.95364 -74.417936)
		(end 317.708788 -68.4276)
		(width 0.1143)
		(layer "In9.Cu")
		(net "UPI_CPU0_CPU1_P0P0_DN<16>")
	)
	(segment
		(start 248.065798 -119.620284)
		(end 258.79679 -117.092476)
		(width 0.1143)
		(layer "In9.Cu")
		(net "UPI_CPU0_CPU1_P0P0_DN<16>")
	)
	(segment
		(start 307.594 -60.696094)
		(end 307.6956 -60.749942)
		(width 0.0889)
		(layer "In9.Cu")
		(net "UPI_CPU0_CPU1_P0P0_DN<16>")
	)
	(segment
		(start 320.116962 -80.331056)
		(end 320.110612 -80.102202)
		(width 0.1143)
		(layer "In9.Cu")
		(net "UPI_CPU0_CPU1_P0P0_DN<16>")
	)
	(segment
		(start 227.83038 -116.174012)
		(end 248.065798 -119.620284)
		(width 0.1143)
		(layer "In9.Cu")
		(net "UPI_CPU0_CPU1_P0P0_DN<16>")
	)
	(segment
		(start 291.125402 -117.996208)
		(end 292.412166 -118.145306)
		(width 0.1143)
		(layer "In9.Cu")
		(net "UPI_CPU0_CPU1_P0P0_DN<16>")
	)
	(segment
		(start 179.644294 -118.730776)
		(end 181.25694 -119.470424)
		(width 0.1143)
		(layer "In9.Cu")
		(net "UPI_CPU0_CPU1_P0P0_DN<16>")
	)
	(segment
		(start 310.942736 -60.278264)
		(end 310.751982 -60.106814)
		(width 0.1143)
		(layer "In9.Cu")
		(net "UPI_CPU0_CPU1_P0P0_DN<16>")
	)
	(segment
		(start 182.931054 -119.958612)
		(end 185.891678 -120.821704)
		(width 0.1143)
		(layer "In9.Cu")
		(net "UPI_CPU0_CPU1_P0P0_DN<16>")
	)
	(segment
		(start 137.324084 -72.544686)
		(end 137.319258 -72.553322)
		(width 0.0889)
		(layer "In9.Cu")
		(net "UPI_CPU0_CPU1_P0P0_DN<16>")
	)
	(segment
		(start 322.432426 -102.722426)
		(end 322.442586 -102.713282)
		(width 0.1143)
		(layer "In9.Cu")
		(net "UPI_CPU0_CPU1_P0P0_DN<16>")
	)
	(segment
		(start 143.246602 -77.17917)
		(end 143.424402 -77.17917)
		(width 0.0889)
		(layer "In9.Cu")
		(net "UPI_CPU0_CPU1_P0P0_DN<16>")
	)
	(segment
		(start 316.539118 -65.306194)
		(end 310.942736 -60.278264)
		(width 0.1143)
		(layer "In9.Cu")
		(net "UPI_CPU0_CPU1_P0P0_DN<16>")
	)
	(segment
		(start 267.271246 -117.510052)
		(end 278.02713 -116.477288)
		(width 0.1143)
		(layer "In9.Cu")
		(net "UPI_CPU0_CPU1_P0P0_DN<16>")
	)
	(segment
		(start 320.04508 -77.740002)
		(end 319.875408 -77.579982)
		(width 0.1143)
		(layer "In9.Cu")
		(net "UPI_CPU0_CPU1_P0P0_DN<16>")
	)
	(segment
		(start 278.02713 -116.477288)
		(end 291.125402 -117.996208)
		(width 0.1143)
		(layer "In9.Cu")
		(net "UPI_CPU0_CPU1_P0P0_DN<16>")
	)
	(segment
		(start 320.139822 -81.15935)
		(end 320.132202 -80.889602)
		(width 0.1143)
		(layer "In9.Cu")
		(net "UPI_CPU0_CPU1_P0P0_DN<16>")
	)
	(segment
		(start 309.594504 -60.056014)
		(end 308.60492 -60.056014)
		(width 0.0889)
		(layer "In9.Cu")
		(net "UPI_CPU0_CPU1_P0P0_DN<16>")
	)
	(segment
		(start 143.153638 -77.272134)
		(end 143.246602 -77.17917)
		(width 0.0889)
		(layer "In9.Cu")
		(net "UPI_CPU0_CPU1_P0P0_DN<16>")
	)
	(segment
		(start 317.697358 -68.39712)
		(end 316.539118 -65.306194)
		(width 0.1143)
		(layer "In9.Cu")
		(net "UPI_CPU0_CPU1_P0P0_DN<16>")
	)
	(segment
		(start 142.632938 -76.956158)
		(end 142.761462 -76.956158)
		(width 0.0889)
		(layer "In9.Cu")
		(net "UPI_CPU0_CPU1_P0P0_DN<16>")
	)
	(segment
		(start 164.840412 -108.541566)
		(end 171.70273 -115.088924)
		(width 0.1143)
		(layer "In9.Cu")
		(net "UPI_CPU0_CPU1_P0P0_DN<16>")
	)
	(segment
		(start 319.919096 -79.154782)
		(end 319.912492 -78.925674)
		(width 0.1143)
		(layer "In9.Cu")
		(net "UPI_CPU0_CPU1_P0P0_DN<16>")
	)
	(segment
		(start 143.517366 -77.272134)
		(end 143.818356 -77.272134)
		(width 0.0889)
		(layer "In9.Cu")
		(net "UPI_CPU0_CPU1_P0P0_DN<16>")
	)
	(segment
		(start 171.70273 -115.088924)
		(end 175.578008 -116.866162)
		(width 0.1143)
		(layer "In9.Cu")
		(net "UPI_CPU0_CPU1_P0P0_DN<16>")
	)
	(segment
		(start 139.372848 -75.125834)
		(end 139.405614 -75.125834)
		(width 0.0889)
		(layer "In9.Cu")
		(net "UPI_CPU0_CPU1_P0P0_DN<16>")
	)
	(segment
		(start 307.6956 -60.749942)
		(end 307.898546 -60.857384)
		(width 0.0889)
		(layer "In9.Cu")
		(net "UPI_CPU0_CPU1_P0P0_DN<16>")
	)
	(segment
		(start 150.960074 -89.598246)
		(end 157.121098 -96.889062)
		(width 0.1143)
		(layer "In9.Cu")
		(net "UPI_CPU0_CPU1_P0P0_DN<16>")
	)
	(arc
		(start 138.182604 -74.430636)
		(mid 138.324287 -74.57444)
		(end 138.518138 -74.630788)
		(width 0.0889)
		(layer "In9.Cu")
		(net "UPI_CPU0_CPU1_P0P0_DN<16>")
	)
	(arc
		(start 139.405614 -75.125834)
		(mid 139.691038 -75.209301)
		(end 139.899644 -75.421236)
		(width 0.0889)
		(layer "In9.Cu")
		(net "UPI_CPU0_CPU1_P0P0_DN<16>")
	)
	(arc
		(start 136.465564 -71.058786)
		(mid 136.462816 -71.454253)
		(end 136.801098 -71.658988)
		(width 0.0889)
		(layer "In9.Cu")
		(net "UPI_CPU0_CPU1_P0P0_DN<16>")
	)
	(arc
		(start 137.319258 -73.543922)
		(mid 137.323005 -73.933178)
		(end 137.655808 -74.135234)
		(width 0.0889)
		(layer "In9.Cu")
		(net "UPI_CPU0_CPU1_P0P0_DN<16>")
	)
	(arc
		(start 139.899644 -75.421236)
		(mid 140.041327 -75.56504)
		(end 140.235178 -75.621388)
		(width 0.0889)
		(layer "In9.Cu")
		(net "UPI_CPU0_CPU1_P0P0_DN<16>")
	)
	(arc
		(start 136.465564 -70.467982)
		(mid 136.544695 -70.763384)
		(end 136.465564 -71.058786)
		(width 0.0889)
		(layer "In9.Cu")
		(net "UPI_CPU0_CPU1_P0P0_DN<16>")
	)
	(arc
		(start 136.440418 -70.12051)
		(mid 136.413149 -70.297139)
		(end 136.465564 -70.467982)
		(width 0.0889)
		(layer "In9.Cu")
		(net "UPI_CPU0_CPU1_P0P0_DN<16>")
	)
	(arc
		(start 138.550904 -74.630788)
		(mid 138.834121 -74.715069)
		(end 139.041124 -74.925936)
		(width 0.0889)
		(layer "In9.Cu")
		(net "UPI_CPU0_CPU1_P0P0_DN<16>")
	)
	(arc
		(start 140.798042 -75.91933)
		(mid 140.888986 -76.036673)
		(end 141.014196 -76.116434)
		(width 0.0889)
		(layer "In9.Cu")
		(net "UPI_CPU0_CPU1_P0P0_DN<16>")
	)
	(arc
		(start 307.65242 -60.457334)
		(mid 307.52966 -60.553328)
		(end 307.593238 -60.695586)
		(width 0.0889)
		(layer "In9.Cu")
		(net "UPI_CPU0_CPU1_P0P0_DN<16>")
	)
	(arc
		(start 140.449554 -75.621388)
		(mid 140.652148 -75.737206)
		(end 140.798042 -75.91933)
		(width 0.0889)
		(layer "In9.Cu")
		(net "UPI_CPU0_CPU1_P0P0_DN<16>")
	)
	(arc
		(start 137.688574 -74.135234)
		(mid 137.973998 -74.218701)
		(end 138.182604 -74.430636)
		(width 0.0889)
		(layer "In9.Cu")
		(net "UPI_CPU0_CPU1_P0P0_DN<16>")
	)
	(arc
		(start 137.324084 -72.944736)
		(mid 137.403306 -73.233854)
		(end 137.330434 -73.524618)
		(width 0.0889)
		(layer "In9.Cu")
		(net "UPI_CPU0_CPU1_P0P0_DN<16>")
	)
	(arc
		(start 137.319258 -72.553322)
		(mid 137.270503 -72.749674)
		(end 137.324084 -72.944736)
		(width 0.0889)
		(layer "In9.Cu")
		(net "UPI_CPU0_CPU1_P0P0_DN<16>")
	)
	(arc
		(start 136.833864 -71.658988)
		(mid 137.326254 -71.957921)
		(end 137.330434 -72.534018)
		(width 0.0889)
		(layer "In9.Cu")
		(net "UPI_CPU0_CPU1_P0P0_DN<16>")
	)
	(arc
		(start 139.041124 -74.925936)
		(mid 139.181203 -75.068672)
		(end 139.372848 -75.125834)
		(width 0.0889)
		(layer "In9.Cu")
		(net "UPI_CPU0_CPU1_P0P0_DN<16>")
	)
	(segment
		(start 137.099294 -72.744584)
		(end 137.670794 -72.744584)
		(width 0.1143)
		(layer "F.Cu")
		(net "UPI_CPU0_CPU1_P0P0_DN<15>")
	)
	(segment
		(start 305.533806 -61.847984)
		(end 306.105306 -61.847984)
		(width 0.1143)
		(layer "F.Cu")
		(net "UPI_CPU0_CPU1_P0P0_DN<15>")
	)
	(via
		(at 137.670794 -72.744584)
		(size 0.508)
		(drill 0.254)
		(layers "F.Cu" "B.Cu")
		(net "UPI_CPU0_CPU1_P0P0_DN<15>")
	)
	(via
		(at 306.105306 -61.847984)
		(size 0.508)
		(drill 0.254)
		(layers "F.Cu" "B.Cu")
		(net "UPI_CPU0_CPU1_P0P0_DN<15>")
	)
	(segment
		(start 308.946042 -60.700412)
		(end 308.198266 -61.448188)
		(width 0.0889)
		(layer "In9.Cu")
		(net "UPI_CPU0_CPU1_P0P0_DN<15>")
	)
	(segment
		(start 319.06718 -79.322676)
		(end 319.208912 -79.174086)
		(width 0.1143)
		(layer "In9.Cu")
		(net "UPI_CPU0_CPU1_P0P0_DN<15>")
	)
	(segment
		(start 142.287752 -75.47991)
		(end 142.30985 -75.47991)
		(width 0.0889)
		(layer "In9.Cu")
		(net "UPI_CPU0_CPU1_P0P0_DN<15>")
	)
	(segment
		(start 319.046352 -78.5749)
		(end 319.188084 -78.42631)
		(width 0.1143)
		(layer "In9.Cu")
		(net "UPI_CPU0_CPU1_P0P0_DN<15>")
	)
	(segment
		(start 319.18148 -78.197456)
		(end 319.032128 -78.056232)
		(width 0.1143)
		(layer "In9.Cu")
		(net "UPI_CPU0_CPU1_P0P0_DN<15>")
	)
	(segment
		(start 158.495492 -101.607874)
		(end 172.128434 -114.613182)
		(width 0.1143)
		(layer "In9.Cu")
		(net "UPI_CPU0_CPU1_P0P0_DN<15>")
	)
	(segment
		(start 321.97421 -102.241858)
		(end 323.162676 -100.081842)
		(width 0.1143)
		(layer "In9.Cu")
		(net "UPI_CPU0_CPU1_P0P0_DN<15>")
	)
	(segment
		(start 137.670794 -73.082658)
		(end 137.736072 -73.147936)
		(width 0.0889)
		(layer "In9.Cu")
		(net "UPI_CPU0_CPU1_P0P0_DN<15>")
	)
	(segment
		(start 142.30985 -75.47991)
		(end 142.545308 -75.47991)
		(width 0.1143)
		(layer "In9.Cu")
		(net "UPI_CPU0_CPU1_P0P0_DN<15>")
	)
	(segment
		(start 319.24371 -80.440784)
		(end 319.094612 -80.29956)
		(width 0.1143)
		(layer "In9.Cu")
		(net "UPI_CPU0_CPU1_P0P0_DN<15>")
	)
	(segment
		(start 307.47589 -61.647578)
		(end 307.475636 -61.648086)
		(width 0.0889)
		(layer "In9.Cu")
		(net "UPI_CPU0_CPU1_P0P0_DN<15>")
	)
	(segment
		(start 185.793888 -120.15343)
		(end 188.10605 -120.031002)
		(width 0.1143)
		(layer "In9.Cu")
		(net "UPI_CPU0_CPU1_P0P0_DN<15>")
	)
	(segment
		(start 319.025524 -77.827124)
		(end 319.167256 -77.678534)
		(width 0.1143)
		(layer "In9.Cu")
		(net "UPI_CPU0_CPU1_P0P0_DN<15>")
	)
	(segment
		(start 323.162676 -100.081842)
		(end 323.30771 -98.171762)
		(width 0.1143)
		(layer "In9.Cu")
		(net "UPI_CPU0_CPU1_P0P0_DN<15>")
	)
	(segment
		(start 172.128434 -114.613182)
		(end 181.591966 -118.797578)
		(width 0.1143)
		(layer "In9.Cu")
		(net "UPI_CPU0_CPU1_P0P0_DN<15>")
	)
	(segment
		(start 315.997336 -65.676272)
		(end 310.516016 -60.751212)
		(width 0.1143)
		(layer "In9.Cu")
		(net "UPI_CPU0_CPU1_P0P0_DN<15>")
	)
	(segment
		(start 318.948816 -75.065128)
		(end 318.942212 -74.83602)
		(width 0.1143)
		(layer "In9.Cu")
		(net "UPI_CPU0_CPU1_P0P0_DN<15>")
	)
	(segment
		(start 319.052956 -78.804008)
		(end 319.046352 -78.5749)
		(width 0.1143)
		(layer "In9.Cu")
		(net "UPI_CPU0_CPU1_P0P0_DN<15>")
	)
	(segment
		(start 319.254886 -80.836262)
		(end 319.24371 -80.440784)
		(width 0.1143)
		(layer "In9.Cu")
		(net "UPI_CPU0_CPU1_P0P0_DN<15>")
	)
	(segment
		(start 140.241528 -74.630534)
		(end 140.448792 -74.630534)
		(width 0.0889)
		(layer "In9.Cu")
		(net "UPI_CPU0_CPU1_P0P0_DN<15>")
	)
	(segment
		(start 309.96382 -60.740036)
		(end 309.924196 -60.700412)
		(width 0.0889)
		(layer "In9.Cu")
		(net "UPI_CPU0_CPU1_P0P0_DN<15>")
	)
	(segment
		(start 319.073784 -79.551784)
		(end 319.06718 -79.322676)
		(width 0.1143)
		(layer "In9.Cu")
		(net "UPI_CPU0_CPU1_P0P0_DN<15>")
	)
	(segment
		(start 141.456664 -75.125834)
		(end 141.86154 -75.53071)
		(width 0.0889)
		(layer "In9.Cu")
		(net "UPI_CPU0_CPU1_P0P0_DN<15>")
	)
	(segment
		(start 309.924196 -60.700412)
		(end 308.946042 -60.700412)
		(width 0.0889)
		(layer "In9.Cu")
		(net "UPI_CPU0_CPU1_P0P0_DN<15>")
	)
	(segment
		(start 141.014196 -75.125834)
		(end 141.456664 -75.125834)
		(width 0.0889)
		(layer "In9.Cu")
		(net "UPI_CPU0_CPU1_P0P0_DN<15>")
	)
	(segment
		(start 319.004696 -77.079348)
		(end 319.146428 -76.930758)
		(width 0.1143)
		(layer "In9.Cu")
		(net "UPI_CPU0_CPU1_P0P0_DN<15>")
	)
	(segment
		(start 143.588486 -76.523088)
		(end 145.630138 -76.523088)
		(width 0.1143)
		(layer "In9.Cu")
		(net "UPI_CPU0_CPU1_P0P0_DN<15>")
	)
	(segment
		(start 321.962526 -102.252526)
		(end 321.9704 -102.245414)
		(width 0.1143)
		(layer "In9.Cu")
		(net "UPI_CPU0_CPU1_P0P0_DN<15>")
	)
	(segment
		(start 188.10605 -120.031002)
		(end 194.578224 -119.52605)
		(width 0.1143)
		(layer "In9.Cu")
		(net "UPI_CPU0_CPU1_P0P0_DN<15>")
	)
	(segment
		(start 319.094612 -80.29956)
		(end 319.088008 -80.070452)
		(width 0.1143)
		(layer "In9.Cu")
		(net "UPI_CPU0_CPU1_P0P0_DN<15>")
	)
	(segment
		(start 310.516016 -60.751212)
		(end 309.974996 -60.751212)
		(width 0.1143)
		(layer "In9.Cu")
		(net "UPI_CPU0_CPU1_P0P0_DN<15>")
	)
	(segment
		(start 319.202308 -78.945232)
		(end 319.052956 -78.804008)
		(width 0.1143)
		(layer "In9.Cu")
		(net "UPI_CPU0_CPU1_P0P0_DN<15>")
	)
	(segment
		(start 309.974996 -60.751212)
		(end 309.952644 -60.751212)
		(width 0.0889)
		(layer "In9.Cu")
		(net "UPI_CPU0_CPU1_P0P0_DN<15>")
	)
	(segment
		(start 318.990472 -76.56068)
		(end 318.983868 -76.331572)
		(width 0.1143)
		(layer "In9.Cu")
		(net "UPI_CPU0_CPU1_P0P0_DN<15>")
	)
	(segment
		(start 323.30771 -98.171762)
		(end 322.412614 -93.7768)
		(width 0.1143)
		(layer "In9.Cu")
		(net "UPI_CPU0_CPU1_P0P0_DN<15>")
	)
	(segment
		(start 137.670794 -72.744584)
		(end 137.670794 -73.082658)
		(width 0.0889)
		(layer "In9.Cu")
		(net "UPI_CPU0_CPU1_P0P0_DN<15>")
	)
	(segment
		(start 291.125402 -117.354604)
		(end 292.376606 -117.499638)
		(width 0.1143)
		(layer "In9.Cu")
		(net "UPI_CPU0_CPU1_P0P0_DN<15>")
	)
	(segment
		(start 267.25626 -116.870734)
		(end 278.032972 -115.835938)
		(width 0.1143)
		(layer "In9.Cu")
		(net "UPI_CPU0_CPU1_P0P0_DN<15>")
	)
	(segment
		(start 319.1256 -76.182982)
		(end 319.118996 -75.954128)
		(width 0.1143)
		(layer "In9.Cu")
		(net "UPI_CPU0_CPU1_P0P0_DN<15>")
	)
	(segment
		(start 138.51128 -73.639934)
		(end 138.554206 -73.639934)
		(width 0.0889)
		(layer "In9.Cu")
		(net "UPI_CPU0_CPU1_P0P0_DN<15>")
	)
	(segment
		(start 306.958492 -61.943996)
		(end 306.337208 -61.943996)
		(width 0.0889)
		(layer "In9.Cu")
		(net "UPI_CPU0_CPU1_P0P0_DN<15>")
	)
	(segment
		(start 319.223136 -79.693008)
		(end 319.073784 -79.551784)
		(width 0.1143)
		(layer "In9.Cu")
		(net "UPI_CPU0_CPU1_P0P0_DN<15>")
	)
	(segment
		(start 319.098168 -75.206352)
		(end 318.948816 -75.065128)
		(width 0.1143)
		(layer "In9.Cu")
		(net "UPI_CPU0_CPU1_P0P0_DN<15>")
	)
	(segment
		(start 308.198266 -61.448188)
		(end 307.67528 -61.448188)
		(width 0.0889)
		(layer "In9.Cu")
		(net "UPI_CPU0_CPU1_P0P0_DN<15>")
	)
	(segment
		(start 139.376658 -74.135234)
		(end 139.409424 -74.135234)
		(width 0.0889)
		(layer "In9.Cu")
		(net "UPI_CPU0_CPU1_P0P0_DN<15>")
	)
	(segment
		(start 320.380106 -83.796124)
		(end 319.665096 -81.915)
		(width 0.1143)
		(layer "In9.Cu")
		(net "UPI_CPU0_CPU1_P0P0_DN<15>")
	)
	(segment
		(start 307.67528 -61.448188)
		(end 307.47589 -61.647578)
		(width 0.0889)
		(layer "In9.Cu")
		(net "UPI_CPU0_CPU1_P0P0_DN<15>")
	)
	(segment
		(start 148.863304 -79.42961)
		(end 151.538432 -89.294462)
		(width 0.1143)
		(layer "In9.Cu")
		(net "UPI_CPU0_CPU1_P0P0_DN<15>")
	)
	(segment
		(start 319.083944 -74.687176)
		(end 319.0621 -73.86701)
		(width 0.1143)
		(layer "In9.Cu")
		(net "UPI_CPU0_CPU1_P0P0_DN<15>")
	)
	(segment
		(start 319.104772 -75.435206)
		(end 319.098168 -75.206352)
		(width 0.1143)
		(layer "In9.Cu")
		(net "UPI_CPU0_CPU1_P0P0_DN<15>")
	)
	(segment
		(start 318.969644 -75.812904)
		(end 318.96304 -75.583796)
		(width 0.1143)
		(layer "In9.Cu")
		(net "UPI_CPU0_CPU1_P0P0_DN<15>")
	)
	(segment
		(start 278.032972 -115.835938)
		(end 291.125402 -117.354604)
		(width 0.1143)
		(layer "In9.Cu")
		(net "UPI_CPU0_CPU1_P0P0_DN<15>")
	)
	(segment
		(start 319.208912 -79.174086)
		(end 319.202308 -78.945232)
		(width 0.1143)
		(layer "In9.Cu")
		(net "UPI_CPU0_CPU1_P0P0_DN<15>")
	)
	(segment
		(start 319.118996 -75.954128)
		(end 318.969644 -75.812904)
		(width 0.1143)
		(layer "In9.Cu")
		(net "UPI_CPU0_CPU1_P0P0_DN<15>")
	)
	(segment
		(start 309.952644 -60.751212)
		(end 309.96382 -60.740036)
		(width 0.0889)
		(layer "In9.Cu")
		(net "UPI_CPU0_CPU1_P0P0_DN<15>")
	)
	(segment
		(start 194.578224 -119.52605)
		(end 227.846382 -115.529868)
		(width 0.1143)
		(layer "In9.Cu")
		(net "UPI_CPU0_CPU1_P0P0_DN<15>")
	)
	(segment
		(start 258.738116 -116.451126)
		(end 267.25626 -116.870734)
		(width 0.1143)
		(layer "In9.Cu")
		(net "UPI_CPU0_CPU1_P0P0_DN<15>")
	)
	(segment
		(start 319.665096 -81.915)
		(end 319.254886 -80.836262)
		(width 0.1143)
		(layer "In9.Cu")
		(net "UPI_CPU0_CPU1_P0P0_DN<15>")
	)
	(segment
		(start 319.139824 -76.701904)
		(end 318.990472 -76.56068)
		(width 0.1143)
		(layer "In9.Cu")
		(net "UPI_CPU0_CPU1_P0P0_DN<15>")
	)
	(segment
		(start 151.538432 -89.294462)
		(end 157.723332 -96.612964)
		(width 0.1143)
		(layer "In9.Cu")
		(net "UPI_CPU0_CPU1_P0P0_DN<15>")
	)
	(segment
		(start 157.723332 -96.612964)
		(end 158.495492 -101.607874)
		(width 0.1143)
		(layer "In9.Cu")
		(net "UPI_CPU0_CPU1_P0P0_DN<15>")
	)
	(segment
		(start 319.032128 -78.056232)
		(end 319.025524 -77.827124)
		(width 0.1143)
		(layer "In9.Cu")
		(net "UPI_CPU0_CPU1_P0P0_DN<15>")
	)
	(segment
		(start 319.088008 -80.070452)
		(end 319.22974 -79.921862)
		(width 0.1143)
		(layer "In9.Cu")
		(net "UPI_CPU0_CPU1_P0P0_DN<15>")
	)
	(segment
		(start 319.0621 -73.86701)
		(end 317.026798 -68.4276)
		(width 0.1143)
		(layer "In9.Cu")
		(net "UPI_CPU0_CPU1_P0P0_DN<15>")
	)
	(segment
		(start 227.846382 -115.529868)
		(end 248.045478 -118.96979)
		(width 0.1143)
		(layer "In9.Cu")
		(net "UPI_CPU0_CPU1_P0P0_DN<15>")
	)
	(segment
		(start 319.0113 -77.308456)
		(end 319.004696 -77.079348)
		(width 0.1143)
		(layer "In9.Cu")
		(net "UPI_CPU0_CPU1_P0P0_DN<15>")
	)
	(segment
		(start 145.630138 -76.523088)
		(end 146.361912 -76.812902)
		(width 0.1143)
		(layer "In9.Cu")
		(net "UPI_CPU0_CPU1_P0P0_DN<15>")
	)
	(segment
		(start 318.96304 -75.583796)
		(end 319.104772 -75.435206)
		(width 0.1143)
		(layer "In9.Cu")
		(net "UPI_CPU0_CPU1_P0P0_DN<15>")
	)
	(segment
		(start 318.983868 -76.331572)
		(end 319.1256 -76.182982)
		(width 0.1143)
		(layer "In9.Cu")
		(net "UPI_CPU0_CPU1_P0P0_DN<15>")
	)
	(segment
		(start 141.86154 -75.53071)
		(end 142.236952 -75.53071)
		(width 0.0889)
		(layer "In9.Cu")
		(net "UPI_CPU0_CPU1_P0P0_DN<15>")
	)
	(segment
		(start 319.188084 -78.42631)
		(end 319.18148 -78.197456)
		(width 0.1143)
		(layer "In9.Cu")
		(net "UPI_CPU0_CPU1_P0P0_DN<15>")
	)
	(segment
		(start 317.026798 -68.4276)
		(end 315.997336 -65.676272)
		(width 0.1143)
		(layer "In9.Cu")
		(net "UPI_CPU0_CPU1_P0P0_DN<15>")
	)
	(segment
		(start 319.2272 -79.8322)
		(end 319.223136 -79.693008)
		(width 0.1143)
		(layer "In9.Cu")
		(net "UPI_CPU0_CPU1_P0P0_DN<15>")
	)
	(segment
		(start 319.22974 -79.921862)
		(end 319.2272 -79.8322)
		(width 0.1143)
		(layer "In9.Cu")
		(net "UPI_CPU0_CPU1_P0P0_DN<15>")
	)
	(segment
		(start 248.045478 -118.96979)
		(end 258.738116 -116.451126)
		(width 0.1143)
		(layer "In9.Cu")
		(net "UPI_CPU0_CPU1_P0P0_DN<15>")
	)
	(segment
		(start 292.376606 -117.499638)
		(end 309.742078 -113.543334)
		(width 0.1143)
		(layer "In9.Cu")
		(net "UPI_CPU0_CPU1_P0P0_DN<15>")
	)
	(segment
		(start 142.545308 -75.47991)
		(end 143.588486 -76.523088)
		(width 0.1143)
		(layer "In9.Cu")
		(net "UPI_CPU0_CPU1_P0P0_DN<15>")
	)
	(segment
		(start 322.412614 -93.7768)
		(end 320.380106 -83.796124)
		(width 0.1143)
		(layer "In9.Cu")
		(net "UPI_CPU0_CPU1_P0P0_DN<15>")
	)
	(segment
		(start 319.167256 -77.678534)
		(end 319.160652 -77.44968)
		(width 0.1143)
		(layer "In9.Cu")
		(net "UPI_CPU0_CPU1_P0P0_DN<15>")
	)
	(segment
		(start 319.160652 -77.44968)
		(end 319.0113 -77.308456)
		(width 0.1143)
		(layer "In9.Cu")
		(net "UPI_CPU0_CPU1_P0P0_DN<15>")
	)
	(segment
		(start 319.146428 -76.930758)
		(end 319.139824 -76.701904)
		(width 0.1143)
		(layer "In9.Cu")
		(net "UPI_CPU0_CPU1_P0P0_DN<15>")
	)
	(segment
		(start 181.591966 -118.797578)
		(end 185.793888 -120.15343)
		(width 0.1143)
		(layer "In9.Cu")
		(net "UPI_CPU0_CPU1_P0P0_DN<15>")
	)
	(segment
		(start 146.361912 -76.812902)
		(end 148.863304 -79.42961)
		(width 0.1143)
		(layer "In9.Cu")
		(net "UPI_CPU0_CPU1_P0P0_DN<15>")
	)
	(segment
		(start 318.942212 -74.83602)
		(end 319.083944 -74.687176)
		(width 0.1143)
		(layer "In9.Cu")
		(net "UPI_CPU0_CPU1_P0P0_DN<15>")
	)
	(segment
		(start 321.9704 -102.245414)
		(end 321.97421 -102.241858)
		(width 0.1143)
		(layer "In9.Cu")
		(net "UPI_CPU0_CPU1_P0P0_DN<15>")
	)
	(segment
		(start 309.742078 -113.543334)
		(end 321.962526 -102.252526)
		(width 0.1143)
		(layer "In9.Cu")
		(net "UPI_CPU0_CPU1_P0P0_DN<15>")
	)
	(segment
		(start 142.236952 -75.53071)
		(end 142.287752 -75.47991)
		(width 0.0889)
		(layer "In9.Cu")
		(net "UPI_CPU0_CPU1_P0P0_DN<15>")
	)
	(arc
		(start 139.041124 -73.935082)
		(mid 139.182807 -74.078886)
		(end 139.376658 -74.135234)
		(width 0.0889)
		(layer "In9.Cu")
		(net "UPI_CPU0_CPU1_P0P0_DN<15>")
	)
	(arc
		(start 138.554206 -73.639934)
		(mid 138.835568 -73.72498)
		(end 139.041124 -73.935082)
		(width 0.0889)
		(layer "In9.Cu")
		(net "UPI_CPU0_CPU1_P0P0_DN<15>")
	)
	(arc
		(start 139.899644 -74.430382)
		(mid 140.044092 -74.575713)
		(end 140.241528 -74.630534)
		(width 0.0889)
		(layer "In9.Cu")
		(net "UPI_CPU0_CPU1_P0P0_DN<15>")
	)
	(arc
		(start 139.409424 -74.135234)
		(mid 139.692641 -74.219515)
		(end 139.899644 -74.430382)
		(width 0.0889)
		(layer "In9.Cu")
		(net "UPI_CPU0_CPU1_P0P0_DN<15>")
	)
	(arc
		(start 306.337208 -61.943996)
		(mid 306.211721 -61.919035)
		(end 306.105306 -61.847984)
		(width 0.0889)
		(layer "In9.Cu")
		(net "UPI_CPU0_CPU1_P0P0_DN<15>")
	)
	(arc
		(start 138.182604 -73.440036)
		(mid 138.321348 -73.582069)
		(end 138.51128 -73.639934)
		(width 0.0889)
		(layer "In9.Cu")
		(net "UPI_CPU0_CPU1_P0P0_DN<15>")
	)
	(arc
		(start 307.475636 -61.648086)
		(mid 307.257104 -61.866038)
		(end 306.958492 -61.943996)
		(width 0.0889)
		(layer "In9.Cu")
		(net "UPI_CPU0_CPU1_P0P0_DN<15>")
	)
	(arc
		(start 140.448792 -74.630534)
		(mid 140.651838 -74.746351)
		(end 140.798042 -74.92873)
		(width 0.0889)
		(layer "In9.Cu")
		(net "UPI_CPU0_CPU1_P0P0_DN<15>")
	)
	(arc
		(start 140.798042 -74.92873)
		(mid 140.888986 -75.046073)
		(end 141.014196 -75.125834)
		(width 0.0889)
		(layer "In9.Cu")
		(net "UPI_CPU0_CPU1_P0P0_DN<15>")
	)
	(arc
		(start 137.736072 -73.147936)
		(mid 137.994209 -73.24069)
		(end 138.182604 -73.440036)
		(width 0.0889)
		(layer "In9.Cu")
		(net "UPI_CPU0_CPU1_P0P0_DN<15>")
	)
	(segment
		(start 137.099294 -71.753984)
		(end 137.670794 -71.753984)
		(width 0.1143)
		(layer "F.Cu")
		(net "UPI_CPU0_CPU1_P0P0_DN<14>")
	)
	(segment
		(start 308.813454 -62.11951)
		(end 308.541928 -61.847984)
		(width 0.0889)
		(layer "F.Cu")
		(net "UPI_CPU0_CPU1_P0P0_DN<14>")
	)
	(segment
		(start 308.129686 -62.1792)
		(end 308.256178 -62.1792)
		(width 0.0889)
		(layer "F.Cu")
		(net "UPI_CPU0_CPU1_P0P0_DN<14>")
	)
	(segment
		(start 308.813454 -62.206632)
		(end 308.813454 -62.11951)
		(width 0.0889)
		(layer "F.Cu")
		(net "UPI_CPU0_CPU1_P0P0_DN<14>")
	)
	(segment
		(start 307.233066 -62.248034)
		(end 308.060852 -62.248034)
		(width 0.0889)
		(layer "F.Cu")
		(net "UPI_CPU0_CPU1_P0P0_DN<14>")
	)
	(segment
		(start 308.772052 -62.248034)
		(end 308.813454 -62.206632)
		(width 0.0889)
		(layer "F.Cu")
		(net "UPI_CPU0_CPU1_P0P0_DN<14>")
	)
	(segment
		(start 308.256178 -62.1792)
		(end 308.325012 -62.248034)
		(width 0.0889)
		(layer "F.Cu")
		(net "UPI_CPU0_CPU1_P0P0_DN<14>")
	)
	(segment
		(start 308.060852 -62.248034)
		(end 308.129686 -62.1792)
		(width 0.0889)
		(layer "F.Cu")
		(net "UPI_CPU0_CPU1_P0P0_DN<14>")
	)
	(segment
		(start 308.325012 -62.248034)
		(end 308.772052 -62.248034)
		(width 0.0889)
		(layer "F.Cu")
		(net "UPI_CPU0_CPU1_P0P0_DN<14>")
	)
	(segment
		(start 306.392326 -62.343538)
		(end 306.547012 -62.498224)
		(width 0.0889)
		(layer "F.Cu")
		(net "UPI_CPU0_CPU1_P0P0_DN<14>")
	)
	(via
		(at 308.541928 -61.847984)
		(size 0.508)
		(drill 0.254)
		(layers "F.Cu" "B.Cu")
		(net "UPI_CPU0_CPU1_P0P0_DN<14>")
	)
	(via
		(at 137.670794 -71.753984)
		(size 0.508)
		(drill 0.254)
		(layers "F.Cu" "B.Cu")
		(net "UPI_CPU0_CPU1_P0P0_DN<14>")
	)
	(arc
		(start 306.547012 -62.498224)
		(mid 306.666852 -62.543099)
		(end 306.779422 -62.482222)
		(width 0.0889)
		(layer "F.Cu")
		(net "UPI_CPU0_CPU1_P0P0_DN<14>")
	)
	(arc
		(start 306.779422 -62.482222)
		(mid 306.979648 -62.313623)
		(end 307.233066 -62.248034)
		(width 0.0889)
		(layer "F.Cu")
		(net "UPI_CPU0_CPU1_P0P0_DN<14>")
	)
	(segment
		(start 197.047866 -118.902226)
		(end 227.89642 -115.187984)
		(width 0.1143)
		(layer "In9.Cu")
		(net "UPI_CPU0_CPU1_P0P0_DN<14>")
	)
	(segment
		(start 322.79971 -100.024946)
		(end 322.82384 -99.981004)
		(width 0.1143)
		(layer "In9.Cu")
		(net "UPI_CPU0_CPU1_P0P0_DN<14>")
	)
	(segment
		(start 267.248132 -116.524278)
		(end 278.035512 -115.488466)
		(width 0.1143)
		(layer "In9.Cu")
		(net "UPI_CPU0_CPU1_P0P0_DN<14>")
	)
	(segment
		(start 171.390056 -113.414302)
		(end 172.74413 -114.422682)
		(width 0.1143)
		(layer "In9.Cu")
		(net "UPI_CPU0_CPU1_P0P0_DN<14>")
	)
	(segment
		(start 145.830798 -76.108306)
		(end 146.734022 -76.476098)
		(width 0.1143)
		(layer "In9.Cu")
		(net "UPI_CPU0_CPU1_P0P0_DN<14>")
	)
	(segment
		(start 292.358064 -117.149118)
		(end 309.574438 -113.227612)
		(width 0.1143)
		(layer "In9.Cu")
		(net "UPI_CPU0_CPU1_P0P0_DN<14>")
	)
	(segment
		(start 291.125402 -117.006116)
		(end 292.358064 -117.149118)
		(width 0.1143)
		(layer "In9.Cu")
		(net "UPI_CPU0_CPU1_P0P0_DN<14>")
	)
	(segment
		(start 193.952876 -119.214392)
		(end 197.047866 -118.902226)
		(width 0.1143)
		(layer "In9.Cu")
		(net "UPI_CPU0_CPU1_P0P0_DN<14>")
	)
	(segment
		(start 310.386984 -61.0997)
		(end 309.054246 -61.0997)
		(width 0.1143)
		(layer "In9.Cu")
		(net "UPI_CPU0_CPU1_P0P0_DN<14>")
	)
	(segment
		(start 278.035512 -115.488466)
		(end 291.125402 -117.006116)
		(width 0.1143)
		(layer "In9.Cu")
		(net "UPI_CPU0_CPU1_P0P0_DN<14>")
	)
	(segment
		(start 172.74413 -114.422682)
		(end 181.682898 -118.449344)
		(width 0.1143)
		(layer "In9.Cu")
		(net "UPI_CPU0_CPU1_P0P0_DN<14>")
	)
	(segment
		(start 149.088602 -78.93939)
		(end 151.851868 -89.130886)
		(width 0.1143)
		(layer "In9.Cu")
		(net "UPI_CPU0_CPU1_P0P0_DN<14>")
	)
	(segment
		(start 138.511534 -72.840088)
		(end 138.5443 -72.840088)
		(width 0.0889)
		(layer "In9.Cu")
		(net "UPI_CPU0_CPU1_P0P0_DN<14>")
	)
	(segment
		(start 141.99108 -74.939398)
		(end 142.65275 -74.939398)
		(width 0.0889)
		(layer "In9.Cu")
		(net "UPI_CPU0_CPU1_P0P0_DN<14>")
	)
	(segment
		(start 320.140584 -84.348828)
		(end 318.715898 -80.60055)
		(width 0.1143)
		(layer "In9.Cu")
		(net "UPI_CPU0_CPU1_P0P0_DN<14>")
	)
	(segment
		(start 227.89642 -115.187984)
		(end 248.034556 -118.617238)
		(width 0.1143)
		(layer "In9.Cu")
		(net "UPI_CPU0_CPU1_P0P0_DN<14>")
	)
	(segment
		(start 140.882116 -73.830434)
		(end 141.99108 -74.939398)
		(width 0.0889)
		(layer "In9.Cu")
		(net "UPI_CPU0_CPU1_P0P0_DN<14>")
	)
	(segment
		(start 145.239486 -76.108306)
		(end 145.830798 -76.108306)
		(width 0.1143)
		(layer "In9.Cu")
		(net "UPI_CPU0_CPU1_P0P0_DN<14>")
	)
	(segment
		(start 146.734022 -76.476098)
		(end 149.088602 -78.93939)
		(width 0.1143)
		(layer "In9.Cu")
		(net "UPI_CPU0_CPU1_P0P0_DN<14>")
	)
	(segment
		(start 158.049976 -96.465898)
		(end 158.820866 -101.451156)
		(width 0.1143)
		(layer "In9.Cu")
		(net "UPI_CPU0_CPU1_P0P0_DN<14>")
	)
	(segment
		(start 309.054246 -61.0997)
		(end 308.7497 -61.404246)
		(width 0.1143)
		(layer "In9.Cu")
		(net "UPI_CPU0_CPU1_P0P0_DN<14>")
	)
	(segment
		(start 316.65037 -68.4276)
		(end 315.689742 -65.863978)
		(width 0.1143)
		(layer "In9.Cu")
		(net "UPI_CPU0_CPU1_P0P0_DN<14>")
	)
	(segment
		(start 322.060062 -93.7768)
		(end 320.140584 -84.348828)
		(width 0.1143)
		(layer "In9.Cu")
		(net "UPI_CPU0_CPU1_P0P0_DN<14>")
	)
	(segment
		(start 258.706366 -116.103654)
		(end 267.248132 -116.524278)
		(width 0.1143)
		(layer "In9.Cu")
		(net "UPI_CPU0_CPU1_P0P0_DN<14>")
	)
	(segment
		(start 321.711828 -102.001828)
		(end 322.79971 -100.024946)
		(width 0.1143)
		(layer "In9.Cu")
		(net "UPI_CPU0_CPU1_P0P0_DN<14>")
	)
	(segment
		(start 322.959476 -98.193606)
		(end 322.060062 -93.7768)
		(width 0.1143)
		(layer "In9.Cu")
		(net "UPI_CPU0_CPU1_P0P0_DN<14>")
	)
	(segment
		(start 181.682898 -118.449344)
		(end 185.778648 -119.770652)
		(width 0.1143)
		(layer "In9.Cu")
		(net "UPI_CPU0_CPU1_P0P0_DN<14>")
	)
	(segment
		(start 308.7497 -61.640212)
		(end 308.541928 -61.847984)
		(width 0.1143)
		(layer "In9.Cu")
		(net "UPI_CPU0_CPU1_P0P0_DN<14>")
	)
	(segment
		(start 158.820866 -101.451156)
		(end 171.255182 -113.313972)
		(width 0.1143)
		(layer "In9.Cu")
		(net "UPI_CPU0_CPU1_P0P0_DN<14>")
	)
	(segment
		(start 143.770858 -76.057506)
		(end 145.166588 -76.057506)
		(width 0.0889)
		(layer "In9.Cu")
		(net "UPI_CPU0_CPU1_P0P0_DN<14>")
	)
	(segment
		(start 145.166588 -76.057506)
		(end 145.217388 -76.108306)
		(width 0.0889)
		(layer "In9.Cu")
		(net "UPI_CPU0_CPU1_P0P0_DN<14>")
	)
	(segment
		(start 142.65275 -74.939398)
		(end 143.770858 -76.057506)
		(width 0.0889)
		(layer "In9.Cu")
		(net "UPI_CPU0_CPU1_P0P0_DN<14>")
	)
	(segment
		(start 309.574438 -113.227612)
		(end 321.701668 -102.020624)
		(width 0.1143)
		(layer "In9.Cu")
		(net "UPI_CPU0_CPU1_P0P0_DN<14>")
	)
	(segment
		(start 318.715898 -80.60055)
		(end 318.694562 -79.8322)
		(width 0.1143)
		(layer "In9.Cu")
		(net "UPI_CPU0_CPU1_P0P0_DN<14>")
	)
	(segment
		(start 318.517016 -73.40854)
		(end 316.65037 -68.4276)
		(width 0.1143)
		(layer "In9.Cu")
		(net "UPI_CPU0_CPU1_P0P0_DN<14>")
	)
	(segment
		(start 145.217388 -76.108306)
		(end 145.239486 -76.108306)
		(width 0.0889)
		(layer "In9.Cu")
		(net "UPI_CPU0_CPU1_P0P0_DN<14>")
	)
	(segment
		(start 137.670794 -71.753984)
		(end 137.767314 -71.850504)
		(width 0.0889)
		(layer "In9.Cu")
		(net "UPI_CPU0_CPU1_P0P0_DN<14>")
	)
	(segment
		(start 140.221462 -73.830434)
		(end 140.882116 -73.830434)
		(width 0.0889)
		(layer "In9.Cu")
		(net "UPI_CPU0_CPU1_P0P0_DN<14>")
	)
	(segment
		(start 171.255182 -113.313972)
		(end 171.390056 -113.414302)
		(width 0.1143)
		(layer "In9.Cu")
		(net "UPI_CPU0_CPU1_P0P0_DN<14>")
	)
	(segment
		(start 248.034556 -118.617238)
		(end 258.706366 -116.103654)
		(width 0.1143)
		(layer "In9.Cu")
		(net "UPI_CPU0_CPU1_P0P0_DN<14>")
	)
	(segment
		(start 321.701668 -102.020624)
		(end 321.711828 -102.001828)
		(width 0.1143)
		(layer "In9.Cu")
		(net "UPI_CPU0_CPU1_P0P0_DN<14>")
	)
	(segment
		(start 315.689742 -65.863978)
		(end 310.386984 -61.0997)
		(width 0.1143)
		(layer "In9.Cu")
		(net "UPI_CPU0_CPU1_P0P0_DN<14>")
	)
	(segment
		(start 322.82384 -99.981004)
		(end 322.959476 -98.193606)
		(width 0.1143)
		(layer "In9.Cu")
		(net "UPI_CPU0_CPU1_P0P0_DN<14>")
	)
	(segment
		(start 151.851868 -89.130886)
		(end 158.049976 -96.465898)
		(width 0.1143)
		(layer "In9.Cu")
		(net "UPI_CPU0_CPU1_P0P0_DN<14>")
	)
	(segment
		(start 139.366244 -73.335134)
		(end 139.39901 -73.335134)
		(width 0.0889)
		(layer "In9.Cu")
		(net "UPI_CPU0_CPU1_P0P0_DN<14>")
	)
	(segment
		(start 185.778648 -119.770652)
		(end 193.952876 -119.214392)
		(width 0.1143)
		(layer "In9.Cu")
		(net "UPI_CPU0_CPU1_P0P0_DN<14>")
	)
	(segment
		(start 308.7497 -61.404246)
		(end 308.7497 -61.640212)
		(width 0.1143)
		(layer "In9.Cu")
		(net "UPI_CPU0_CPU1_P0P0_DN<14>")
	)
	(segment
		(start 318.694562 -79.8322)
		(end 318.517016 -73.40854)
		(width 0.1143)
		(layer "In9.Cu")
		(net "UPI_CPU0_CPU1_P0P0_DN<14>")
	)
	(arc
		(start 138.5443 -72.840088)
		(mid 138.735942 -72.897254)
		(end 138.876024 -73.039986)
		(width 0.0889)
		(layer "In9.Cu")
		(net "UPI_CPU0_CPU1_P0P0_DN<14>")
	)
	(arc
		(start 138.876024 -73.039986)
		(mid 139.083028 -73.25085)
		(end 139.366244 -73.335134)
		(width 0.0889)
		(layer "In9.Cu")
		(net "UPI_CPU0_CPU1_P0P0_DN<14>")
	)
	(arc
		(start 137.93851 -72.263762)
		(mid 138.110174 -72.666159)
		(end 138.511534 -72.840088)
		(width 0.0889)
		(layer "In9.Cu")
		(net "UPI_CPU0_CPU1_P0P0_DN<14>")
	)
	(arc
		(start 137.767314 -71.850504)
		(mid 137.894004 -72.040108)
		(end 137.93851 -72.263762)
		(width 0.0889)
		(layer "In9.Cu")
		(net "UPI_CPU0_CPU1_P0P0_DN<14>")
	)
	(arc
		(start 139.39901 -73.335134)
		(mid 139.59286 -73.391484)
		(end 139.734544 -73.535286)
		(width 0.0889)
		(layer "In9.Cu")
		(net "UPI_CPU0_CPU1_P0P0_DN<14>")
	)
	(arc
		(start 139.734544 -73.535286)
		(mid 139.940103 -73.745383)
		(end 140.221462 -73.830434)
		(width 0.0889)
		(layer "In9.Cu")
		(net "UPI_CPU0_CPU1_P0P0_DN<14>")
	)
	(segment
		(start 304.675286 -64.324738)
		(end 305.246786 -64.324738)
		(width 0.1143)
		(layer "F.Cu")
		(net "UPI_CPU0_CPU1_P0P0_DN<13>")
	)
	(segment
		(start 136.240774 -71.258938)
		(end 136.812274 -71.258938)
		(width 0.1143)
		(layer "F.Cu")
		(net "UPI_CPU0_CPU1_P0P0_DN<13>")
	)
	(via
		(at 305.246786 -64.324738)
		(size 0.508)
		(drill 0.254)
		(layers "F.Cu" "B.Cu")
		(net "UPI_CPU0_CPU1_P0P0_DN<13>")
	)
	(via
		(at 136.812274 -71.258938)
		(size 0.508)
		(drill 0.254)
		(layers "F.Cu" "B.Cu")
		(net "UPI_CPU0_CPU1_P0P0_DN<13>")
	)
	(segment
		(start 322.198492 -99.794822)
		(end 322.27266 -98.81616)
		(width 0.1143)
		(layer "In9.Cu")
		(net "UPI_CPU0_CPU1_P0P0_DN<13>")
	)
	(segment
		(start 140.228574 -72.840088)
		(end 140.696442 -72.840088)
		(width 0.0889)
		(layer "In9.Cu")
		(net "UPI_CPU0_CPU1_P0P0_DN<13>")
	)
	(segment
		(start 306.703476 -62.7253)
		(end 306.190142 -63.238634)
		(width 0.0889)
		(layer "In9.Cu")
		(net "UPI_CPU0_CPU1_P0P0_DN<13>")
	)
	(segment
		(start 258.647692 -115.462304)
		(end 267.233146 -115.88496)
		(width 0.1143)
		(layer "In9.Cu")
		(net "UPI_CPU0_CPU1_P0P0_DN<13>")
	)
	(segment
		(start 158.652972 -96.19107)
		(end 159.415734 -101.126544)
		(width 0.1143)
		(layer "In9.Cu")
		(net "UPI_CPU0_CPU1_P0P0_DN<13>")
	)
	(segment
		(start 184.464452 -118.622826)
		(end 186.085988 -119.109998)
		(width 0.1143)
		(layer "In9.Cu")
		(net "UPI_CPU0_CPU1_P0P0_DN<13>")
	)
	(segment
		(start 190.576708 -118.806214)
		(end 194.757294 -118.523512)
		(width 0.1143)
		(layer "In9.Cu")
		(net "UPI_CPU0_CPU1_P0P0_DN<13>")
	)
	(segment
		(start 149.621494 -78.46695)
		(end 152.431242 -88.828626)
		(width 0.1143)
		(layer "In9.Cu")
		(net "UPI_CPU0_CPU1_P0P0_DN<13>")
	)
	(segment
		(start 248.014236 -117.966744)
		(end 258.647692 -115.462304)
		(width 0.1143)
		(layer "In9.Cu")
		(net "UPI_CPU0_CPU1_P0P0_DN<13>")
	)
	(segment
		(start 311.705498 -63.156592)
		(end 308.842918 -63.156592)
		(width 0.1143)
		(layer "In9.Cu")
		(net "UPI_CPU0_CPU1_P0P0_DN<13>")
	)
	(segment
		(start 307.369464 -62.7253)
		(end 306.703476 -62.7253)
		(width 0.0889)
		(layer "In9.Cu")
		(net "UPI_CPU0_CPU1_P0P0_DN<13>")
	)
	(segment
		(start 317.939166 -80.56118)
		(end 317.9191 -79.8322)
		(width 0.1143)
		(layer "In9.Cu")
		(net "UPI_CPU0_CPU1_P0P0_DN<13>")
	)
	(segment
		(start 308.72938 -63.155576)
		(end 308.655212 -63.206122)
		(width 0.0889)
		(layer "In9.Cu")
		(net "UPI_CPU0_CPU1_P0P0_DN<13>")
	)
	(segment
		(start 139.366244 -72.344534)
		(end 139.39901 -72.344534)
		(width 0.0889)
		(layer "In9.Cu")
		(net "UPI_CPU0_CPU1_P0P0_DN<13>")
	)
	(segment
		(start 322.316856 -98.233992)
		(end 321.409314 -93.7768)
		(width 0.1143)
		(layer "In9.Cu")
		(net "UPI_CPU0_CPU1_P0P0_DN<13>")
	)
	(segment
		(start 278.041608 -114.847116)
		(end 291.125402 -116.364004)
		(width 0.1143)
		(layer "In9.Cu")
		(net "UPI_CPU0_CPU1_P0P0_DN<13>")
	)
	(segment
		(start 308.299104 -63.203582)
		(end 307.369464 -62.7253)
		(width 0.0889)
		(layer "In9.Cu")
		(net "UPI_CPU0_CPU1_P0P0_DN<13>")
	)
	(segment
		(start 305.517296 -63.769748)
		(end 305.450748 -63.9064)
		(width 0.0889)
		(layer "In9.Cu")
		(net "UPI_CPU0_CPU1_P0P0_DN<13>")
	)
	(segment
		(start 147.078954 -75.807062)
		(end 149.621494 -78.46695)
		(width 0.1143)
		(layer "In9.Cu")
		(net "UPI_CPU0_CPU1_P0P0_DN<13>")
	)
	(segment
		(start 186.085988 -119.109998)
		(end 190.576708 -118.806214)
		(width 0.1143)
		(layer "In9.Cu")
		(net "UPI_CPU0_CPU1_P0P0_DN<13>")
	)
	(segment
		(start 321.19316 -101.621844)
		(end 321.242436 -101.532436)
		(width 0.1143)
		(layer "In9.Cu")
		(net "UPI_CPU0_CPU1_P0P0_DN<13>")
	)
	(segment
		(start 267.233146 -115.88496)
		(end 278.041608 -114.847116)
		(width 0.1143)
		(layer "In9.Cu")
		(net "UPI_CPU0_CPU1_P0P0_DN<13>")
	)
	(segment
		(start 317.760858 -74.204576)
		(end 317.740538 -73.323704)
		(width 0.1143)
		(layer "In9.Cu")
		(net "UPI_CPU0_CPU1_P0P0_DN<13>")
	)
	(segment
		(start 315.9506 -68.4276)
		(end 315.157612 -66.258186)
		(width 0.1143)
		(layer "In9.Cu")
		(net "UPI_CPU0_CPU1_P0P0_DN<13>")
	)
	(segment
		(start 317.9191 -79.8322)
		(end 317.763144 -74.20483)
		(width 0.1143)
		(layer "In9.Cu")
		(net "UPI_CPU0_CPU1_P0P0_DN<13>")
	)
	(segment
		(start 292.323012 -116.502942)
		(end 309.267606 -112.643666)
		(width 0.1143)
		(layer "In9.Cu")
		(net "UPI_CPU0_CPU1_P0P0_DN<13>")
	)
	(segment
		(start 140.696442 -72.840088)
		(end 142.236444 -74.38009)
		(width 0.0889)
		(layer "In9.Cu")
		(net "UPI_CPU0_CPU1_P0P0_DN<13>")
	)
	(segment
		(start 322.27266 -98.81616)
		(end 322.316856 -98.233992)
		(width 0.1143)
		(layer "In9.Cu")
		(net "UPI_CPU0_CPU1_P0P0_DN<13>")
	)
	(segment
		(start 142.99057 -74.38009)
		(end 143.04137 -74.43089)
		(width 0.0889)
		(layer "In9.Cu")
		(net "UPI_CPU0_CPU1_P0P0_DN<13>")
	)
	(segment
		(start 308.842918 -63.156592)
		(end 308.72938 -63.155576)
		(width 0.1143)
		(layer "In9.Cu")
		(net "UPI_CPU0_CPU1_P0P0_DN<13>")
	)
	(segment
		(start 143.291306 -74.43089)
		(end 147.078954 -75.807062)
		(width 0.1143)
		(layer "In9.Cu")
		(net "UPI_CPU0_CPU1_P0P0_DN<13>")
	)
	(segment
		(start 159.415734 -101.126544)
		(end 171.852336 -112.992408)
		(width 0.1143)
		(layer "In9.Cu")
		(net "UPI_CPU0_CPU1_P0P0_DN<13>")
	)
	(segment
		(start 317.763144 -74.20483)
		(end 317.760858 -74.204576)
		(width 0.1143)
		(layer "In9.Cu")
		(net "UPI_CPU0_CPU1_P0P0_DN<13>")
	)
	(segment
		(start 305.450748 -63.9064)
		(end 305.246786 -64.324738)
		(width 0.0889)
		(layer "In9.Cu")
		(net "UPI_CPU0_CPU1_P0P0_DN<13>")
	)
	(segment
		(start 138.511534 -71.849488)
		(end 138.5443 -71.849488)
		(width 0.0889)
		(layer "In9.Cu")
		(net "UPI_CPU0_CPU1_P0P0_DN<13>")
	)
	(segment
		(start 315.157612 -66.258186)
		(end 311.705498 -63.156592)
		(width 0.1143)
		(layer "In9.Cu")
		(net "UPI_CPU0_CPU1_P0P0_DN<13>")
	)
	(segment
		(start 317.740538 -73.323704)
		(end 315.9506 -68.4276)
		(width 0.1143)
		(layer "In9.Cu")
		(net "UPI_CPU0_CPU1_P0P0_DN<13>")
	)
	(segment
		(start 306.190142 -63.238634)
		(end 306.087526 -63.238634)
		(width 0.0889)
		(layer "In9.Cu")
		(net "UPI_CPU0_CPU1_P0P0_DN<13>")
	)
	(segment
		(start 143.063468 -74.43089)
		(end 143.291306 -74.43089)
		(width 0.1143)
		(layer "In9.Cu")
		(net "UPI_CPU0_CPU1_P0P0_DN<13>")
	)
	(segment
		(start 171.852336 -112.992408)
		(end 184.464452 -118.622826)
		(width 0.1143)
		(layer "In9.Cu")
		(net "UPI_CPU0_CPU1_P0P0_DN<13>")
	)
	(segment
		(start 137.041636 -71.353934)
		(end 137.68197 -71.353934)
		(width 0.0889)
		(layer "In9.Cu")
		(net "UPI_CPU0_CPU1_P0P0_DN<13>")
	)
	(segment
		(start 143.04137 -74.43089)
		(end 143.063468 -74.43089)
		(width 0.0889)
		(layer "In9.Cu")
		(net "UPI_CPU0_CPU1_P0P0_DN<13>")
	)
	(segment
		(start 291.125402 -116.364004)
		(end 292.323012 -116.502942)
		(width 0.1143)
		(layer "In9.Cu")
		(net "UPI_CPU0_CPU1_P0P0_DN<13>")
	)
	(segment
		(start 308.655212 -63.206122)
		(end 308.299104 -63.203582)
		(width 0.0889)
		(layer "In9.Cu")
		(net "UPI_CPU0_CPU1_P0P0_DN<13>")
	)
	(segment
		(start 319.618106 -84.978494)
		(end 317.939166 -80.56118)
		(width 0.1143)
		(layer "In9.Cu")
		(net "UPI_CPU0_CPU1_P0P0_DN<13>")
	)
	(segment
		(start 309.267606 -112.643666)
		(end 321.19316 -101.621844)
		(width 0.1143)
		(layer "In9.Cu")
		(net "UPI_CPU0_CPU1_P0P0_DN<13>")
	)
	(segment
		(start 194.757294 -118.523512)
		(end 227.870766 -114.536728)
		(width 0.1143)
		(layer "In9.Cu")
		(net "UPI_CPU0_CPU1_P0P0_DN<13>")
	)
	(segment
		(start 321.242436 -101.532436)
		(end 322.198492 -99.794822)
		(width 0.1143)
		(layer "In9.Cu")
		(net "UPI_CPU0_CPU1_P0P0_DN<13>")
	)
	(segment
		(start 152.431242 -88.828626)
		(end 158.652972 -96.19107)
		(width 0.1143)
		(layer "In9.Cu")
		(net "UPI_CPU0_CPU1_P0P0_DN<13>")
	)
	(segment
		(start 321.409314 -93.7768)
		(end 319.618106 -84.978494)
		(width 0.1143)
		(layer "In9.Cu")
		(net "UPI_CPU0_CPU1_P0P0_DN<13>")
	)
	(segment
		(start 142.236444 -74.38009)
		(end 142.99057 -74.38009)
		(width 0.0889)
		(layer "In9.Cu")
		(net "UPI_CPU0_CPU1_P0P0_DN<13>")
	)
	(segment
		(start 227.870766 -114.536728)
		(end 248.014236 -117.966744)
		(width 0.1143)
		(layer "In9.Cu")
		(net "UPI_CPU0_CPU1_P0P0_DN<13>")
	)
	(arc
		(start 139.734544 -72.544686)
		(mid 139.943152 -72.756618)
		(end 140.228574 -72.840088)
		(width 0.0889)
		(layer "In9.Cu")
		(net "UPI_CPU0_CPU1_P0P0_DN<13>")
	)
	(arc
		(start 138.876024 -72.049386)
		(mid 139.083028 -72.26025)
		(end 139.366244 -72.344534)
		(width 0.0889)
		(layer "In9.Cu")
		(net "UPI_CPU0_CPU1_P0P0_DN<13>")
	)
	(arc
		(start 138.017504 -71.554086)
		(mid 138.226112 -71.766018)
		(end 138.511534 -71.849488)
		(width 0.0889)
		(layer "In9.Cu")
		(net "UPI_CPU0_CPU1_P0P0_DN<13>")
	)
	(arc
		(start 136.812274 -71.258938)
		(mid 136.917506 -71.329252)
		(end 137.041636 -71.353934)
		(width 0.0889)
		(layer "In9.Cu")
		(net "UPI_CPU0_CPU1_P0P0_DN<13>")
	)
	(arc
		(start 137.68197 -71.353934)
		(mid 137.87582 -71.410284)
		(end 138.017504 -71.554086)
		(width 0.0889)
		(layer "In9.Cu")
		(net "UPI_CPU0_CPU1_P0P0_DN<13>")
	)
	(arc
		(start 139.39901 -72.344534)
		(mid 139.59286 -72.400884)
		(end 139.734544 -72.544686)
		(width 0.0889)
		(layer "In9.Cu")
		(net "UPI_CPU0_CPU1_P0P0_DN<13>")
	)
	(arc
		(start 306.087526 -63.238634)
		(mid 305.702401 -63.396831)
		(end 305.517296 -63.769748)
		(width 0.0889)
		(layer "In9.Cu")
		(net "UPI_CPU0_CPU1_P0P0_DN<13>")
	)
	(arc
		(start 138.5443 -71.849488)
		(mid 138.735942 -71.906654)
		(end 138.876024 -72.049386)
		(width 0.0889)
		(layer "In9.Cu")
		(net "UPI_CPU0_CPU1_P0P0_DN<13>")
	)
	(segment
		(start 134.523734 -69.277738)
		(end 135.095234 -69.277738)
		(width 0.1143)
		(layer "F.Cu")
		(net "UPI_CPU0_CPU1_P0P0_DN<12>")
	)
	(segment
		(start 306.392326 -63.334138)
		(end 306.963826 -63.334138)
		(width 0.1143)
		(layer "F.Cu")
		(net "UPI_CPU0_CPU1_P0P0_DN<12>")
	)
	(via
		(at 135.095234 -69.277738)
		(size 0.508)
		(drill 0.254)
		(layers "F.Cu" "B.Cu")
		(net "UPI_CPU0_CPU1_P0P0_DN<12>")
	)
	(via
		(at 306.963826 -63.334138)
		(size 0.508)
		(drill 0.254)
		(layers "F.Cu" "B.Cu")
		(net "UPI_CPU0_CPU1_P0P0_DN<12>")
	)
	(segment
		(start 307.731668 -64.229234)
		(end 308.169564 -64.229234)
		(width 0.0889)
		(layer "In9.Cu")
		(net "UPI_CPU0_CPU1_P0P0_DN<12>")
	)
	(segment
		(start 308.964076 -64.101218)
		(end 309.014876 -64.050418)
		(width 0.0889)
		(layer "In9.Cu")
		(net "UPI_CPU0_CPU1_P0P0_DN<12>")
	)
	(segment
		(start 320.683128 -101.226366)
		(end 308.958742 -112.059974)
		(width 0.1143)
		(layer "In9.Cu")
		(net "UPI_CPU0_CPU1_P0P0_DN<12>")
	)
	(segment
		(start 138.5443 -70.858888)
		(end 138.51636 -70.858888)
		(width 0.0889)
		(layer "In9.Cu")
		(net "UPI_CPU0_CPU1_P0P0_DN<12>")
	)
	(segment
		(start 139.39901 -71.353934)
		(end 139.366244 -71.353934)
		(width 0.0889)
		(layer "In9.Cu")
		(net "UPI_CPU0_CPU1_P0P0_DN<12>")
	)
	(segment
		(start 309.014876 -64.050418)
		(end 309.036974 -64.050418)
		(width 0.0889)
		(layer "In9.Cu")
		(net "UPI_CPU0_CPU1_P0P0_DN<12>")
	)
	(segment
		(start 195.356734 -117.808502)
		(end 186.181238 -118.429786)
		(width 0.1143)
		(layer "In9.Cu")
		(net "UPI_CPU0_CPU1_P0P0_DN<12>")
	)
	(segment
		(start 309.036974 -64.050418)
		(end 311.7469 -64.050418)
		(width 0.1143)
		(layer "In9.Cu")
		(net "UPI_CPU0_CPU1_P0P0_DN<12>")
	)
	(segment
		(start 153.011632 -88.529668)
		(end 150.128986 -77.900784)
		(width 0.1143)
		(layer "In9.Cu")
		(net "UPI_CPU0_CPU1_P0P0_DN<12>")
	)
	(segment
		(start 144.728438 -73.731882)
		(end 143.567912 -72.723248)
		(width 0.1143)
		(layer "In9.Cu")
		(net "UPI_CPU0_CPU1_P0P0_DN<12>")
	)
	(segment
		(start 291.125402 -115.721892)
		(end 278.047958 -114.205766)
		(width 0.1143)
		(layer "In9.Cu")
		(net "UPI_CPU0_CPU1_P0P0_DN<12>")
	)
	(segment
		(start 142.40256 -71.849488)
		(end 141.836902 -71.849488)
		(width 0.0889)
		(layer "In9.Cu")
		(net "UPI_CPU0_CPU1_P0P0_DN<12>")
	)
	(segment
		(start 135.96493 -69.372734)
		(end 135.932164 -69.372734)
		(width 0.0889)
		(layer "In9.Cu")
		(net "UPI_CPU0_CPU1_P0P0_DN<12>")
	)
	(segment
		(start 227.886514 -113.892584)
		(end 195.356734 -117.808502)
		(width 0.1143)
		(layer "In9.Cu")
		(net "UPI_CPU0_CPU1_P0P0_DN<12>")
	)
	(segment
		(start 307.025802 -63.734188)
		(end 307.167026 -63.734188)
		(width 0.0889)
		(layer "In9.Cu")
		(net "UPI_CPU0_CPU1_P0P0_DN<12>")
	)
	(segment
		(start 316.94755 -73.299066)
		(end 317.057532 -77.285342)
		(width 0.1143)
		(layer "In9.Cu")
		(net "UPI_CPU0_CPU1_P0P0_DN<12>")
	)
	(segment
		(start 159.25546 -95.916242)
		(end 153.011632 -88.529668)
		(width 0.1143)
		(layer "In9.Cu")
		(net "UPI_CPU0_CPU1_P0P0_DN<12>")
	)
	(segment
		(start 147.226782 -74.864722)
		(end 144.728438 -73.731882)
		(width 0.1143)
		(layer "In9.Cu")
		(net "UPI_CPU0_CPU1_P0P0_DN<12>")
	)
	(segment
		(start 321.674236 -98.274378)
		(end 321.573144 -99.60864)
		(width 0.1143)
		(layer "In9.Cu")
		(net "UPI_CPU0_CPU1_P0P0_DN<12>")
	)
	(segment
		(start 317.145416 -80.477868)
		(end 317.69177 -81.915)
		(width 0.1143)
		(layer "In9.Cu")
		(net "UPI_CPU0_CPU1_P0P0_DN<12>")
	)
	(segment
		(start 247.993916 -117.31625)
		(end 227.886514 -113.892584)
		(width 0.1143)
		(layer "In9.Cu")
		(net "UPI_CPU0_CPU1_P0P0_DN<12>")
	)
	(segment
		(start 278.047958 -114.205766)
		(end 267.21816 -115.245642)
		(width 0.1143)
		(layer "In9.Cu")
		(net "UPI_CPU0_CPU1_P0P0_DN<12>")
	)
	(segment
		(start 172.042074 -112.29213)
		(end 160.012888 -100.81514)
		(width 0.1143)
		(layer "In9.Cu")
		(net "UPI_CPU0_CPU1_P0P0_DN<12>")
	)
	(segment
		(start 140.264134 -71.849488)
		(end 140.228574 -71.849488)
		(width 0.0889)
		(layer "In9.Cu")
		(net "UPI_CPU0_CPU1_P0P0_DN<12>")
	)
	(segment
		(start 184.366154 -117.845078)
		(end 172.042074 -112.29213)
		(width 0.1143)
		(layer "In9.Cu")
		(net "UPI_CPU0_CPU1_P0P0_DN<12>")
	)
	(segment
		(start 320.773044 -101.063044)
		(end 320.683128 -101.226366)
		(width 0.1143)
		(layer "In9.Cu")
		(net "UPI_CPU0_CPU1_P0P0_DN<12>")
	)
	(segment
		(start 321.659758 -98.203258)
		(end 321.674236 -98.274378)
		(width 0.1143)
		(layer "In9.Cu")
		(net "UPI_CPU0_CPU1_P0P0_DN<12>")
	)
	(segment
		(start 160.012888 -100.81514)
		(end 159.25546 -95.916242)
		(width 0.1143)
		(layer "In9.Cu")
		(net "UPI_CPU0_CPU1_P0P0_DN<12>")
	)
	(segment
		(start 142.74038 -71.900288)
		(end 142.475458 -71.900288)
		(width 0.1143)
		(layer "In9.Cu")
		(net "UPI_CPU0_CPU1_P0P0_DN<12>")
	)
	(segment
		(start 137.68197 -70.363334)
		(end 137.649204 -70.363334)
		(width 0.0889)
		(layer "In9.Cu")
		(net "UPI_CPU0_CPU1_P0P0_DN<12>")
	)
	(segment
		(start 143.567912 -72.723248)
		(end 142.74038 -71.900288)
		(width 0.1143)
		(layer "In9.Cu")
		(net "UPI_CPU0_CPU1_P0P0_DN<12>")
	)
	(segment
		(start 317.057532 -77.285342)
		(end 317.145416 -80.477868)
		(width 0.1143)
		(layer "In9.Cu")
		(net "UPI_CPU0_CPU1_P0P0_DN<12>")
	)
	(segment
		(start 308.29758 -64.101218)
		(end 308.964076 -64.101218)
		(width 0.0889)
		(layer "In9.Cu")
		(net "UPI_CPU0_CPU1_P0P0_DN<12>")
	)
	(segment
		(start 306.963826 -63.672212)
		(end 307.025802 -63.734188)
		(width 0.0889)
		(layer "In9.Cu")
		(net "UPI_CPU0_CPU1_P0P0_DN<12>")
	)
	(segment
		(start 319.095374 -85.607906)
		(end 321.659758 -98.203258)
		(width 0.1143)
		(layer "In9.Cu")
		(net "UPI_CPU0_CPU1_P0P0_DN<12>")
	)
	(segment
		(start 308.169564 -64.229234)
		(end 308.29758 -64.101218)
		(width 0.0889)
		(layer "In9.Cu")
		(net "UPI_CPU0_CPU1_P0P0_DN<12>")
	)
	(segment
		(start 321.573144 -99.60864)
		(end 320.773044 -101.063044)
		(width 0.1143)
		(layer "In9.Cu")
		(net "UPI_CPU0_CPU1_P0P0_DN<12>")
	)
	(segment
		(start 186.181238 -118.429786)
		(end 184.366154 -117.845078)
		(width 0.1143)
		(layer "In9.Cu")
		(net "UPI_CPU0_CPU1_P0P0_DN<12>")
	)
	(segment
		(start 136.830308 -69.868288)
		(end 136.794494 -69.868288)
		(width 0.0889)
		(layer "In9.Cu")
		(net "UPI_CPU0_CPU1_P0P0_DN<12>")
	)
	(segment
		(start 142.45336 -71.900288)
		(end 142.40256 -71.849488)
		(width 0.0889)
		(layer "In9.Cu")
		(net "UPI_CPU0_CPU1_P0P0_DN<12>")
	)
	(segment
		(start 258.589018 -114.820954)
		(end 247.993916 -117.31625)
		(width 0.1143)
		(layer "In9.Cu")
		(net "UPI_CPU0_CPU1_P0P0_DN<12>")
	)
	(segment
		(start 142.475458 -71.900288)
		(end 142.45336 -71.900288)
		(width 0.0889)
		(layer "In9.Cu")
		(net "UPI_CPU0_CPU1_P0P0_DN<12>")
	)
	(segment
		(start 141.271244 -71.353934)
		(end 141.093698 -71.353934)
		(width 0.0889)
		(layer "In9.Cu")
		(net "UPI_CPU0_CPU1_P0P0_DN<12>")
	)
	(segment
		(start 317.69177 -81.915)
		(end 319.095374 -85.607906)
		(width 0.1143)
		(layer "In9.Cu")
		(net "UPI_CPU0_CPU1_P0P0_DN<12>")
	)
	(segment
		(start 314.173616 -66.230246)
		(end 315.035946 -68.4276)
		(width 0.1143)
		(layer "In9.Cu")
		(net "UPI_CPU0_CPU1_P0P0_DN<12>")
	)
	(segment
		(start 311.7469 -64.050418)
		(end 314.173616 -66.230246)
		(width 0.1143)
		(layer "In9.Cu")
		(net "UPI_CPU0_CPU1_P0P0_DN<12>")
	)
	(segment
		(start 150.128986 -77.900784)
		(end 147.226782 -74.864722)
		(width 0.1143)
		(layer "In9.Cu")
		(net "UPI_CPU0_CPU1_P0P0_DN<12>")
	)
	(segment
		(start 315.035946 -68.4276)
		(end 316.94755 -73.299066)
		(width 0.1143)
		(layer "In9.Cu")
		(net "UPI_CPU0_CPU1_P0P0_DN<12>")
	)
	(segment
		(start 267.21816 -115.245642)
		(end 258.589018 -114.820954)
		(width 0.1143)
		(layer "In9.Cu")
		(net "UPI_CPU0_CPU1_P0P0_DN<12>")
	)
	(segment
		(start 292.28796 -115.856766)
		(end 291.125402 -115.721892)
		(width 0.1143)
		(layer "In9.Cu")
		(net "UPI_CPU0_CPU1_P0P0_DN<12>")
	)
	(segment
		(start 308.958742 -112.059974)
		(end 292.28796 -115.856766)
		(width 0.1143)
		(layer "In9.Cu")
		(net "UPI_CPU0_CPU1_P0P0_DN<12>")
	)
	(segment
		(start 306.963826 -63.334138)
		(end 306.963826 -63.672212)
		(width 0.0889)
		(layer "In9.Cu")
		(net "UPI_CPU0_CPU1_P0P0_DN<12>")
	)
	(arc
		(start 139.734544 -71.554086)
		(mid 139.592861 -71.410282)
		(end 139.39901 -71.353934)
		(width 0.0889)
		(layer "In9.Cu")
		(net "UPI_CPU0_CPU1_P0P0_DN<12>")
	)
	(arc
		(start 140.228574 -71.849488)
		(mid 139.94315 -71.766021)
		(end 139.734544 -71.554086)
		(width 0.0889)
		(layer "In9.Cu")
		(net "UPI_CPU0_CPU1_P0P0_DN<12>")
	)
	(arc
		(start 139.366244 -71.353934)
		(mid 139.083027 -71.269653)
		(end 138.876024 -71.058786)
		(width 0.0889)
		(layer "In9.Cu")
		(net "UPI_CPU0_CPU1_P0P0_DN<12>")
	)
	(arc
		(start 135.932164 -69.372734)
		(mid 135.843527 -69.362719)
		(end 135.757412 -69.33946)
		(width 0.0889)
		(layer "In9.Cu")
		(net "UPI_CPU0_CPU1_P0P0_DN<12>")
	)
	(arc
		(start 138.876024 -71.058786)
		(mid 138.735945 -70.91605)
		(end 138.5443 -70.858888)
		(width 0.0889)
		(layer "In9.Cu")
		(net "UPI_CPU0_CPU1_P0P0_DN<12>")
	)
	(arc
		(start 135.757412 -69.33946)
		(mid 135.430142 -69.267627)
		(end 135.095234 -69.277738)
		(width 0.0889)
		(layer "In9.Cu")
		(net "UPI_CPU0_CPU1_P0P0_DN<12>")
	)
	(arc
		(start 307.515514 -64.03213)
		(mid 307.606458 -64.149473)
		(end 307.731668 -64.229234)
		(width 0.0889)
		(layer "In9.Cu")
		(net "UPI_CPU0_CPU1_P0P0_DN<12>")
	)
	(arc
		(start 140.758164 -71.554086)
		(mid 140.549556 -71.766018)
		(end 140.264134 -71.849488)
		(width 0.0889)
		(layer "In9.Cu")
		(net "UPI_CPU0_CPU1_P0P0_DN<12>")
	)
	(arc
		(start 137.158984 -70.068186)
		(mid 137.02024 -69.926153)
		(end 136.830308 -69.868288)
		(width 0.0889)
		(layer "In9.Cu")
		(net "UPI_CPU0_CPU1_P0P0_DN<12>")
	)
	(arc
		(start 136.794494 -69.868288)
		(mid 136.50907 -69.784821)
		(end 136.300464 -69.572886)
		(width 0.0889)
		(layer "In9.Cu")
		(net "UPI_CPU0_CPU1_P0P0_DN<12>")
	)
	(arc
		(start 138.017504 -70.563486)
		(mid 137.875821 -70.419682)
		(end 137.68197 -70.363334)
		(width 0.0889)
		(layer "In9.Cu")
		(net "UPI_CPU0_CPU1_P0P0_DN<12>")
	)
	(arc
		(start 136.300464 -69.572886)
		(mid 136.158781 -69.429082)
		(end 135.96493 -69.372734)
		(width 0.0889)
		(layer "In9.Cu")
		(net "UPI_CPU0_CPU1_P0P0_DN<12>")
	)
	(arc
		(start 137.649204 -70.363334)
		(mid 137.365987 -70.279053)
		(end 137.158984 -70.068186)
		(width 0.0889)
		(layer "In9.Cu")
		(net "UPI_CPU0_CPU1_P0P0_DN<12>")
	)
	(arc
		(start 141.487906 -71.551292)
		(mid 141.396792 -71.4337)
		(end 141.271244 -71.353934)
		(width 0.0889)
		(layer "In9.Cu")
		(net "UPI_CPU0_CPU1_P0P0_DN<12>")
	)
	(arc
		(start 307.167026 -63.734188)
		(mid 307.36962 -63.850006)
		(end 307.515514 -64.03213)
		(width 0.0889)
		(layer "In9.Cu")
		(net "UPI_CPU0_CPU1_P0P0_DN<12>")
	)
	(arc
		(start 141.093698 -71.353934)
		(mid 140.899848 -71.410284)
		(end 140.758164 -71.554086)
		(width 0.0889)
		(layer "In9.Cu")
		(net "UPI_CPU0_CPU1_P0P0_DN<12>")
	)
	(arc
		(start 141.836902 -71.849488)
		(mid 141.634004 -71.733628)
		(end 141.487906 -71.551292)
		(width 0.0889)
		(layer "In9.Cu")
		(net "UPI_CPU0_CPU1_P0P0_DN<12>")
	)
	(arc
		(start 138.51636 -70.858888)
		(mid 138.228215 -70.776569)
		(end 138.017504 -70.563486)
		(width 0.0889)
		(layer "In9.Cu")
		(net "UPI_CPU0_CPU1_P0P0_DN<12>")
	)
	(segment
		(start 305.533806 -64.819784)
		(end 306.105306 -64.819784)
		(width 0.1143)
		(layer "F.Cu")
		(net "UPI_CPU0_CPU1_P0P0_DN<11>")
	)
	(segment
		(start 136.240774 -69.277738)
		(end 136.812274 -69.277738)
		(width 0.1143)
		(layer "F.Cu")
		(net "UPI_CPU0_CPU1_P0P0_DN<11>")
	)
	(via
		(at 136.812274 -69.277738)
		(size 0.508)
		(drill 0.254)
		(layers "F.Cu" "B.Cu")
		(net "UPI_CPU0_CPU1_P0P0_DN<11>")
	)
	(via
		(at 306.105306 -64.819784)
		(size 0.508)
		(drill 0.254)
		(layers "F.Cu" "B.Cu")
		(net "UPI_CPU0_CPU1_P0P0_DN<11>")
	)
	(segment
		(start 309.50916 -64.89192)
		(end 309.127906 -64.89192)
		(width 0.0889)
		(layer "In9.Cu")
		(net "UPI_CPU0_CPU1_P0P0_DN<11>")
	)
	(segment
		(start 160.609534 -100.503482)
		(end 171.983146 -111.354362)
		(width 0.1143)
		(layer "In9.Cu")
		(net "UPI_CPU0_CPU1_P0P0_DN<11>")
	)
	(segment
		(start 247.973596 -116.665756)
		(end 258.530344 -114.179604)
		(width 0.1143)
		(layer "In9.Cu")
		(net "UPI_CPU0_CPU1_P0P0_DN<11>")
	)
	(segment
		(start 137.649204 -69.372734)
		(end 137.68197 -69.372734)
		(width 0.0889)
		(layer "In9.Cu")
		(net "UPI_CPU0_CPU1_P0P0_DN<11>")
	)
	(segment
		(start 144.001744 -71.733664)
		(end 144.157446 -71.690992)
		(width 0.1143)
		(layer "In9.Cu")
		(net "UPI_CPU0_CPU1_P0P0_DN<11>")
	)
	(segment
		(start 186.072526 -117.647974)
		(end 195.20408 -117.186964)
		(width 0.1143)
		(layer "In9.Cu")
		(net "UPI_CPU0_CPU1_P0P0_DN<11>")
	)
	(segment
		(start 150.649686 -77.38237)
		(end 153.586942 -88.217756)
		(width 0.1143)
		(layer "In9.Cu")
		(net "UPI_CPU0_CPU1_P0P0_DN<11>")
	)
	(segment
		(start 141.709902 -70.363334)
		(end 141.760702 -70.414134)
		(width 0.0889)
		(layer "In9.Cu")
		(net "UPI_CPU0_CPU1_P0P0_DN<11>")
	)
	(segment
		(start 267.203174 -114.606324)
		(end 278.054054 -113.564416)
		(width 0.1143)
		(layer "In9.Cu")
		(net "UPI_CPU0_CPU1_P0P0_DN<11>")
	)
	(segment
		(start 292.253162 -115.21059)
		(end 308.652418 -111.476028)
		(width 0.1143)
		(layer "In9.Cu")
		(net "UPI_CPU0_CPU1_P0P0_DN<11>")
	)
	(segment
		(start 148.025104 -73.895458)
		(end 150.649686 -77.38237)
		(width 0.1143)
		(layer "In9.Cu")
		(net "UPI_CPU0_CPU1_P0P0_DN<11>")
	)
	(segment
		(start 153.586942 -88.217756)
		(end 159.85744 -95.63862)
		(width 0.1143)
		(layer "In9.Cu")
		(net "UPI_CPU0_CPU1_P0P0_DN<11>")
	)
	(segment
		(start 321.031616 -98.314764)
		(end 318.572642 -86.236048)
		(width 0.1143)
		(layer "In9.Cu")
		(net "UPI_CPU0_CPU1_P0P0_DN<11>")
	)
	(segment
		(start 195.20408 -117.186964)
		(end 227.960428 -113.258346)
		(width 0.1143)
		(layer "In9.Cu")
		(net "UPI_CPU0_CPU1_P0P0_DN<11>")
	)
	(segment
		(start 136.812274 -69.277738)
		(end 136.812274 -68.939664)
		(width 0.0889)
		(layer "In9.Cu")
		(net "UPI_CPU0_CPU1_P0P0_DN<11>")
	)
	(segment
		(start 318.572642 -86.236048)
		(end 316.33414 -80.348328)
		(width 0.1143)
		(layer "In9.Cu")
		(net "UPI_CPU0_CPU1_P0P0_DN<11>")
	)
	(segment
		(start 316.33414 -80.348328)
		(end 316.13983 -73.311766)
		(width 0.1143)
		(layer "In9.Cu")
		(net "UPI_CPU0_CPU1_P0P0_DN<11>")
	)
	(segment
		(start 143.703548 -71.563738)
		(end 144.001744 -71.733664)
		(width 0.1143)
		(layer "In9.Cu")
		(net "UPI_CPU0_CPU1_P0P0_DN<11>")
	)
	(segment
		(start 306.982114 -64.724788)
		(end 306.334668 -64.724788)
		(width 0.0889)
		(layer "In9.Cu")
		(net "UPI_CPU0_CPU1_P0P0_DN<11>")
	)
	(segment
		(start 308.652418 -111.476028)
		(end 320.175636 -100.825808)
		(width 0.1143)
		(layer "In9.Cu")
		(net "UPI_CPU0_CPU1_P0P0_DN<11>")
	)
	(segment
		(start 144.157446 -71.690992)
		(end 148.025104 -73.895458)
		(width 0.1143)
		(layer "In9.Cu")
		(net "UPI_CPU0_CPU1_P0P0_DN<11>")
	)
	(segment
		(start 142.975584 -71.01713)
		(end 143.660876 -71.407528)
		(width 0.1143)
		(layer "In9.Cu")
		(net "UPI_CPU0_CPU1_P0P0_DN<11>")
	)
	(segment
		(start 316.13983 -73.311766)
		(end 313.311794 -66.313558)
		(width 0.1143)
		(layer "In9.Cu")
		(net "UPI_CPU0_CPU1_P0P0_DN<11>")
	)
	(segment
		(start 309.55996 -64.84112)
		(end 309.50916 -64.89192)
		(width 0.0889)
		(layer "In9.Cu")
		(net "UPI_CPU0_CPU1_P0P0_DN<11>")
	)
	(segment
		(start 320.947796 -99.422458)
		(end 321.031616 -98.314764)
		(width 0.1143)
		(layer "In9.Cu")
		(net "UPI_CPU0_CPU1_P0P0_DN<11>")
	)
	(segment
		(start 159.85744 -95.63862)
		(end 160.609534 -100.503482)
		(width 0.1143)
		(layer "In9.Cu")
		(net "UPI_CPU0_CPU1_P0P0_DN<11>")
	)
	(segment
		(start 171.983146 -111.354362)
		(end 186.072526 -117.647974)
		(width 0.1143)
		(layer "In9.Cu")
		(net "UPI_CPU0_CPU1_P0P0_DN<11>")
	)
	(segment
		(start 309.582058 -64.84112)
		(end 309.55996 -64.84112)
		(width 0.0889)
		(layer "In9.Cu")
		(net "UPI_CPU0_CPU1_P0P0_DN<11>")
	)
	(segment
		(start 139.366244 -70.363334)
		(end 139.39901 -70.363334)
		(width 0.0889)
		(layer "In9.Cu")
		(net "UPI_CPU0_CPU1_P0P0_DN<11>")
	)
	(segment
		(start 308.791102 -65.228724)
		(end 307.836824 -65.228724)
		(width 0.0889)
		(layer "In9.Cu")
		(net "UPI_CPU0_CPU1_P0P0_DN<11>")
	)
	(segment
		(start 311.672732 -64.84112)
		(end 309.582058 -64.84112)
		(width 0.1143)
		(layer "In9.Cu")
		(net "UPI_CPU0_CPU1_P0P0_DN<11>")
	)
	(segment
		(start 143.660876 -71.407528)
		(end 143.703548 -71.563738)
		(width 0.1143)
		(layer "In9.Cu")
		(net "UPI_CPU0_CPU1_P0P0_DN<11>")
	)
	(segment
		(start 142.372588 -70.414134)
		(end 142.975584 -71.01713)
		(width 0.1143)
		(layer "In9.Cu")
		(net "UPI_CPU0_CPU1_P0P0_DN<11>")
	)
	(segment
		(start 278.054054 -113.564416)
		(end 292.253162 -115.21059)
		(width 0.1143)
		(layer "In9.Cu")
		(net "UPI_CPU0_CPU1_P0P0_DN<11>")
	)
	(segment
		(start 313.311794 -66.313558)
		(end 311.672732 -64.84112)
		(width 0.1143)
		(layer "In9.Cu")
		(net "UPI_CPU0_CPU1_P0P0_DN<11>")
	)
	(segment
		(start 227.960428 -113.258346)
		(end 247.973596 -116.665756)
		(width 0.1143)
		(layer "In9.Cu")
		(net "UPI_CPU0_CPU1_P0P0_DN<11>")
	)
	(segment
		(start 141.093698 -70.363334)
		(end 141.709902 -70.363334)
		(width 0.0889)
		(layer "In9.Cu")
		(net "UPI_CPU0_CPU1_P0P0_DN<11>")
	)
	(segment
		(start 141.760702 -70.414134)
		(end 142.372588 -70.414134)
		(width 0.1143)
		(layer "In9.Cu")
		(net "UPI_CPU0_CPU1_P0P0_DN<11>")
	)
	(segment
		(start 320.175636 -100.825808)
		(end 320.947796 -99.422458)
		(width 0.1143)
		(layer "In9.Cu")
		(net "UPI_CPU0_CPU1_P0P0_DN<11>")
	)
	(segment
		(start 138.511534 -69.868288)
		(end 138.547348 -69.868288)
		(width 0.0889)
		(layer "In9.Cu")
		(net "UPI_CPU0_CPU1_P0P0_DN<11>")
	)
	(segment
		(start 136.812274 -68.939664)
		(end 136.870186 -68.881752)
		(width 0.0889)
		(layer "In9.Cu")
		(net "UPI_CPU0_CPU1_P0P0_DN<11>")
	)
	(segment
		(start 309.127906 -64.89192)
		(end 308.791102 -65.228724)
		(width 0.0889)
		(layer "In9.Cu")
		(net "UPI_CPU0_CPU1_P0P0_DN<11>")
	)
	(segment
		(start 258.530344 -114.179604)
		(end 267.203174 -114.606324)
		(width 0.1143)
		(layer "In9.Cu")
		(net "UPI_CPU0_CPU1_P0P0_DN<11>")
	)
	(arc
		(start 139.39901 -70.363334)
		(mid 139.59286 -70.419684)
		(end 139.734544 -70.563486)
		(width 0.0889)
		(layer "In9.Cu")
		(net "UPI_CPU0_CPU1_P0P0_DN<11>")
	)
	(arc
		(start 306.334668 -64.724788)
		(mid 306.210542 -64.749478)
		(end 306.105306 -64.819784)
		(width 0.0889)
		(layer "In9.Cu")
		(net "UPI_CPU0_CPU1_P0P0_DN<11>")
	)
	(arc
		(start 138.547348 -69.868288)
		(mid 138.737277 -69.926158)
		(end 138.876024 -70.068186)
		(width 0.0889)
		(layer "In9.Cu")
		(net "UPI_CPU0_CPU1_P0P0_DN<11>")
	)
	(arc
		(start 139.734544 -70.563486)
		(mid 140.246354 -70.859025)
		(end 140.758164 -70.563486)
		(width 0.0889)
		(layer "In9.Cu")
		(net "UPI_CPU0_CPU1_P0P0_DN<11>")
	)
	(arc
		(start 307.836824 -65.228724)
		(mid 307.628253 -65.172719)
		(end 307.475636 -65.019936)
		(width 0.0889)
		(layer "In9.Cu")
		(net "UPI_CPU0_CPU1_P0P0_DN<11>")
	)
	(arc
		(start 307.475636 -65.019936)
		(mid 307.267217 -64.808223)
		(end 306.982114 -64.724788)
		(width 0.0889)
		(layer "In9.Cu")
		(net "UPI_CPU0_CPU1_P0P0_DN<11>")
	)
	(arc
		(start 138.876024 -70.068186)
		(mid 139.083028 -70.27905)
		(end 139.366244 -70.363334)
		(width 0.0889)
		(layer "In9.Cu")
		(net "UPI_CPU0_CPU1_P0P0_DN<11>")
	)
	(arc
		(start 138.017504 -69.572886)
		(mid 138.226112 -69.784818)
		(end 138.511534 -69.868288)
		(width 0.0889)
		(layer "In9.Cu")
		(net "UPI_CPU0_CPU1_P0P0_DN<11>")
	)
	(arc
		(start 136.870186 -68.881752)
		(mid 137.037031 -68.946565)
		(end 137.158984 -69.077586)
		(width 0.0889)
		(layer "In9.Cu")
		(net "UPI_CPU0_CPU1_P0P0_DN<11>")
	)
	(arc
		(start 137.158984 -69.077586)
		(mid 137.365988 -69.28845)
		(end 137.649204 -69.372734)
		(width 0.0889)
		(layer "In9.Cu")
		(net "UPI_CPU0_CPU1_P0P0_DN<11>")
	)
	(arc
		(start 140.758164 -70.563486)
		(mid 140.899847 -70.419682)
		(end 141.093698 -70.363334)
		(width 0.0889)
		(layer "In9.Cu")
		(net "UPI_CPU0_CPU1_P0P0_DN<11>")
	)
	(arc
		(start 137.68197 -69.372734)
		(mid 137.87582 -69.429084)
		(end 138.017504 -69.572886)
		(width 0.0889)
		(layer "In9.Cu")
		(net "UPI_CPU0_CPU1_P0P0_DN<11>")
	)
	(segment
		(start 311.164732 -66.2813)
		(end 311.380632 -66.4972)
		(width 0.0889)
		(layer "F.Cu")
		(net "UPI_CPU0_CPU1_P0P0_DN<10>")
	)
	(segment
		(start 307.667152 -66.400934)
		(end 307.786786 -66.2813)
		(width 0.0889)
		(layer "F.Cu")
		(net "UPI_CPU0_CPU1_P0P0_DN<10>")
	)
	(segment
		(start 306.392326 -66.305938)
		(end 306.850542 -66.305938)
		(width 0.0889)
		(layer "F.Cu")
		(net "UPI_CPU0_CPU1_P0P0_DN<10>")
	)
	(segment
		(start 137.099294 -67.791584)
		(end 137.670794 -67.791584)
		(width 0.1143)
		(layer "F.Cu")
		(net "UPI_CPU0_CPU1_P0P0_DN<10>")
	)
	(segment
		(start 306.945538 -66.400934)
		(end 307.667152 -66.400934)
		(width 0.0889)
		(layer "F.Cu")
		(net "UPI_CPU0_CPU1_P0P0_DN<10>")
	)
	(segment
		(start 307.786786 -66.2813)
		(end 311.164732 -66.2813)
		(width 0.0889)
		(layer "F.Cu")
		(net "UPI_CPU0_CPU1_P0P0_DN<10>")
	)
	(segment
		(start 306.850542 -66.305938)
		(end 306.945538 -66.400934)
		(width 0.0889)
		(layer "F.Cu")
		(net "UPI_CPU0_CPU1_P0P0_DN<10>")
	)
	(via
		(at 137.670794 -67.791584)
		(size 0.508)
		(drill 0.254)
		(layers "F.Cu" "B.Cu")
		(net "UPI_CPU0_CPU1_P0P0_DN<10>")
	)
	(via
		(at 311.380632 -66.4972)
		(size 0.508)
		(drill 0.254)
		(layers "F.Cu" "B.Cu")
		(net "UPI_CPU0_CPU1_P0P0_DN<10>")
	)
	(segment
		(start 154.433016 -87.77859)
		(end 154.435048 -87.781384)
		(width 0.1143)
		(layer "In9.Cu")
		(net "UPI_CPU0_CPU1_P0P0_DN<10>")
	)
	(segment
		(start 137.655808 -68.191634)
		(end 137.688574 -68.191634)
		(width 0.0889)
		(layer "In9.Cu")
		(net "UPI_CPU0_CPU1_P0P0_DN<10>")
	)
	(segment
		(start 144.926812 -70.761606)
		(end 148.858732 -73.095866)
		(width 0.1143)
		(layer "In9.Cu")
		(net "UPI_CPU0_CPU1_P0P0_DN<10>")
	)
	(segment
		(start 227.943156 -112.312196)
		(end 247.943878 -115.71732)
		(width 0.1143)
		(layer "In9.Cu")
		(net "UPI_CPU0_CPU1_P0P0_DN<10>")
	)
	(segment
		(start 141.942058 -68.687188)
		(end 142.210028 -68.687188)
		(width 0.0889)
		(layer "In9.Cu")
		(net "UPI_CPU0_CPU1_P0P0_DN<10>")
	)
	(segment
		(start 142.210028 -68.687188)
		(end 142.287244 -68.764404)
		(width 0.0889)
		(layer "In9.Cu")
		(net "UPI_CPU0_CPU1_P0P0_DN<10>")
	)
	(segment
		(start 315.159898 -76.341986)
		(end 315.012832 -76.203302)
		(width 0.1143)
		(layer "In9.Cu")
		(net "UPI_CPU0_CPU1_P0P0_DN<10>")
	)
	(segment
		(start 314.943744 -73.743058)
		(end 315.083698 -73.595992)
		(width 0.1143)
		(layer "In9.Cu")
		(net "UPI_CPU0_CPU1_P0P0_DN<10>")
	)
	(segment
		(start 141.087094 -69.182234)
		(end 141.11986 -69.182234)
		(width 0.0889)
		(layer "In9.Cu")
		(net "UPI_CPU0_CPU1_P0P0_DN<10>")
	)
	(segment
		(start 142.414244 -68.764404)
		(end 142.540228 -68.890388)
		(width 0.0889)
		(layer "In9.Cu")
		(net "UPI_CPU0_CPU1_P0P0_DN<10>")
	)
	(segment
		(start 196.696838 -116.072412)
		(end 227.943156 -112.312196)
		(width 0.1143)
		(layer "In9.Cu")
		(net "UPI_CPU0_CPU1_P0P0_DN<10>")
	)
	(segment
		(start 315.047884 -77.461618)
		(end 315.18733 -77.314552)
		(width 0.1143)
		(layer "In9.Cu")
		(net "UPI_CPU0_CPU1_P0P0_DN<10>")
	)
	(segment
		(start 314.971176 -74.715878)
		(end 314.964572 -74.48677)
		(width 0.1143)
		(layer "In9.Cu")
		(net "UPI_CPU0_CPU1_P0P0_DN<10>")
	)
	(segment
		(start 143.560292 -69.467222)
		(end 144.095216 -70.002146)
		(width 0.0889)
		(layer "In9.Cu")
		(net "UPI_CPU0_CPU1_P0P0_DN<10>")
	)
	(segment
		(start 161.479992 -100.048822)
		(end 172.357288 -110.4265)
		(width 0.1143)
		(layer "In9.Cu")
		(net "UPI_CPU0_CPU1_P0P0_DN<10>")
	)
	(segment
		(start 315.201554 -77.82941)
		(end 315.054488 -77.690726)
		(width 0.1143)
		(layer "In9.Cu")
		(net "UPI_CPU0_CPU1_P0P0_DN<10>")
	)
	(segment
		(start 313.26836 -105.889298)
		(end 317.501524 -86.245954)
		(width 0.1143)
		(layer "In9.Cu")
		(net "UPI_CPU0_CPU1_P0P0_DN<10>")
	)
	(segment
		(start 315.110368 -79.692754)
		(end 315.249814 -79.545688)
		(width 0.1143)
		(layer "In9.Cu")
		(net "UPI_CPU0_CPU1_P0P0_DN<10>")
	)
	(segment
		(start 315.13907 -75.598274)
		(end 314.992004 -75.45959)
		(width 0.1143)
		(layer "In9.Cu")
		(net "UPI_CPU0_CPU1_P0P0_DN<10>")
	)
	(segment
		(start 284.941772 -113.426748)
		(end 292.198298 -114.267742)
		(width 0.1143)
		(layer "In9.Cu")
		(net "UPI_CPU0_CPU1_P0P0_DN<10>")
	)
	(segment
		(start 139.372848 -69.182234)
		(end 139.405614 -69.182234)
		(width 0.0889)
		(layer "In9.Cu")
		(net "UPI_CPU0_CPU1_P0P0_DN<10>")
	)
	(segment
		(start 315.145674 -75.827128)
		(end 315.13907 -75.598274)
		(width 0.1143)
		(layer "In9.Cu")
		(net "UPI_CPU0_CPU1_P0P0_DN<10>")
	)
	(segment
		(start 315.096144 -79.17815)
		(end 315.08954 -78.949042)
		(width 0.1143)
		(layer "In9.Cu")
		(net "UPI_CPU0_CPU1_P0P0_DN<10>")
	)
	(segment
		(start 142.990062 -69.467222)
		(end 143.560292 -69.467222)
		(width 0.0889)
		(layer "In9.Cu")
		(net "UPI_CPU0_CPU1_P0P0_DN<10>")
	)
	(segment
		(start 315.118242 -74.854562)
		(end 314.971176 -74.715878)
		(width 0.1143)
		(layer "In9.Cu")
		(net "UPI_CPU0_CPU1_P0P0_DN<10>")
	)
	(segment
		(start 142.540228 -68.890388)
		(end 142.540228 -69.017388)
		(width 0.0889)
		(layer "In9.Cu")
		(net "UPI_CPU0_CPU1_P0P0_DN<10>")
	)
	(segment
		(start 271.737074 -113.236756)
		(end 271.739106 -113.236502)
		(width 0.1143)
		(layer "In9.Cu")
		(net "UPI_CPU0_CPU1_P0P0_DN<10>")
	)
	(segment
		(start 142.793212 -69.143372)
		(end 142.919196 -69.269356)
		(width 0.0889)
		(layer "In9.Cu")
		(net "UPI_CPU0_CPU1_P0P0_DN<10>")
	)
	(segment
		(start 317.501524 -86.245954)
		(end 315.272928 -80.383888)
		(width 0.1143)
		(layer "In9.Cu")
		(net "UPI_CPU0_CPU1_P0P0_DN<10>")
	)
	(segment
		(start 271.74317 -113.236248)
		(end 278.062436 -112.629188)
		(width 0.1143)
		(layer "In9.Cu")
		(net "UPI_CPU0_CPU1_P0P0_DN<10>")
	)
	(segment
		(start 315.068712 -78.20533)
		(end 315.208158 -78.058264)
		(width 0.1143)
		(layer "In9.Cu")
		(net "UPI_CPU0_CPU1_P0P0_DN<10>")
	)
	(segment
		(start 315.03366 -76.947014)
		(end 315.027056 -76.717906)
		(width 0.1143)
		(layer "In9.Cu")
		(net "UPI_CPU0_CPU1_P0P0_DN<10>")
	)
	(segment
		(start 137.377678 -67.622674)
		(end 137.298938 -67.64401)
		(width 0.0889)
		(layer "In9.Cu")
		(net "UPI_CPU0_CPU1_P0P0_DN<10>")
	)
	(segment
		(start 267.18133 -113.674144)
		(end 271.73428 -113.23701)
		(width 0.1143)
		(layer "In9.Cu")
		(net "UPI_CPU0_CPU1_P0P0_DN<10>")
	)
	(segment
		(start 315.08954 -78.949042)
		(end 315.228986 -78.801976)
		(width 0.1143)
		(layer "In9.Cu")
		(net "UPI_CPU0_CPU1_P0P0_DN<10>")
	)
	(segment
		(start 314.992004 -75.45959)
		(end 314.9854 -75.230482)
		(width 0.1143)
		(layer "In9.Cu")
		(net "UPI_CPU0_CPU1_P0P0_DN<10>")
	)
	(segment
		(start 193.125344 -116.29263)
		(end 196.696838 -116.072412)
		(width 0.1143)
		(layer "In9.Cu")
		(net "UPI_CPU0_CPU1_P0P0_DN<10>")
	)
	(segment
		(start 144.182846 -70.01764)
		(end 144.926812 -70.761606)
		(width 0.1143)
		(layer "In9.Cu")
		(net "UPI_CPU0_CPU1_P0P0_DN<10>")
	)
	(segment
		(start 137.670794 -67.791584)
		(end 137.377678 -67.622674)
		(width 0.0889)
		(layer "In9.Cu")
		(net "UPI_CPU0_CPU1_P0P0_DN<10>")
	)
	(segment
		(start 315.006228 -75.974194)
		(end 315.145674 -75.827128)
		(width 0.1143)
		(layer "In9.Cu")
		(net "UPI_CPU0_CPU1_P0P0_DN<10>")
	)
	(segment
		(start 144.095216 -70.002146)
		(end 144.182846 -70.01764)
		(width 0.0889)
		(layer "In9.Cu")
		(net "UPI_CPU0_CPU1_P0P0_DN<10>")
	)
	(segment
		(start 142.919196 -69.269356)
		(end 142.919196 -69.396356)
		(width 0.0889)
		(layer "In9.Cu")
		(net "UPI_CPU0_CPU1_P0P0_DN<10>")
	)
	(segment
		(start 284.787848 -113.232184)
		(end 284.941772 -113.426748)
		(width 0.1143)
		(layer "In9.Cu")
		(net "UPI_CPU0_CPU1_P0P0_DN<10>")
	)
	(segment
		(start 271.739106 -113.236502)
		(end 271.740376 -113.236248)
		(width 0.1143)
		(layer "In9.Cu")
		(net "UPI_CPU0_CPU1_P0P0_DN<10>")
	)
	(segment
		(start 247.943878 -115.71732)
		(end 258.444746 -113.244376)
		(width 0.1143)
		(layer "In9.Cu")
		(net "UPI_CPU0_CPU1_P0P0_DN<10>")
	)
	(segment
		(start 311.533032 -66.3448)
		(end 311.380632 -66.4972)
		(width 0.1143)
		(layer "In9.Cu")
		(net "UPI_CPU0_CPU1_P0P0_DN<10>")
	)
	(segment
		(start 311.82056 -66.3448)
		(end 311.533032 -66.3448)
		(width 0.1143)
		(layer "In9.Cu")
		(net "UPI_CPU0_CPU1_P0P0_DN<10>")
	)
	(segment
		(start 315.228986 -78.801976)
		(end 315.222382 -78.573122)
		(width 0.1143)
		(layer "In9.Cu")
		(net "UPI_CPU0_CPU1_P0P0_DN<10>")
	)
	(segment
		(start 315.263784 -80.060546)
		(end 315.116972 -79.921862)
		(width 0.1143)
		(layer "In9.Cu")
		(net "UPI_CPU0_CPU1_P0P0_DN<10>")
	)
	(segment
		(start 315.222382 -78.573122)
		(end 315.075316 -78.434438)
		(width 0.1143)
		(layer "In9.Cu")
		(net "UPI_CPU0_CPU1_P0P0_DN<10>")
	)
	(segment
		(start 148.858732 -73.095866)
		(end 151.347678 -76.403454)
		(width 0.1143)
		(layer "In9.Cu")
		(net "UPI_CPU0_CPU1_P0P0_DN<10>")
	)
	(segment
		(start 314.9854 -75.230482)
		(end 315.124846 -75.083416)
		(width 0.1143)
		(layer "In9.Cu")
		(net "UPI_CPU0_CPU1_P0P0_DN<10>")
	)
	(segment
		(start 315.012832 -76.203302)
		(end 315.006228 -75.974194)
		(width 0.1143)
		(layer "In9.Cu")
		(net "UPI_CPU0_CPU1_P0P0_DN<10>")
	)
	(segment
		(start 284.560518 -113.205768)
		(end 284.787848 -113.232184)
		(width 0.1143)
		(layer "In9.Cu")
		(net "UPI_CPU0_CPU1_P0P0_DN<10>")
	)
	(segment
		(start 315.097414 -74.11085)
		(end 314.950348 -73.972166)
		(width 0.1143)
		(layer "In9.Cu")
		(net "UPI_CPU0_CPU1_P0P0_DN<10>")
	)
	(segment
		(start 315.249814 -79.545688)
		(end 315.24321 -79.316834)
		(width 0.1143)
		(layer "In9.Cu")
		(net "UPI_CPU0_CPU1_P0P0_DN<10>")
	)
	(segment
		(start 151.347678 -76.403454)
		(end 154.433016 -87.77859)
		(width 0.1143)
		(layer "In9.Cu")
		(net "UPI_CPU0_CPU1_P0P0_DN<10>")
	)
	(segment
		(start 314.950348 -73.972166)
		(end 314.943744 -73.743058)
		(width 0.1143)
		(layer "In9.Cu")
		(net "UPI_CPU0_CPU1_P0P0_DN<10>")
	)
	(segment
		(start 142.666212 -69.143372)
		(end 142.793212 -69.143372)
		(width 0.0889)
		(layer "In9.Cu")
		(net "UPI_CPU0_CPU1_P0P0_DN<10>")
	)
	(segment
		(start 315.180726 -77.085698)
		(end 315.03366 -76.947014)
		(width 0.1143)
		(layer "In9.Cu")
		(net "UPI_CPU0_CPU1_P0P0_DN<10>")
	)
	(segment
		(start 258.444746 -113.244376)
		(end 267.18133 -113.674144)
		(width 0.1143)
		(layer "In9.Cu")
		(net "UPI_CPU0_CPU1_P0P0_DN<10>")
	)
	(segment
		(start 177.518314 -111.938308)
		(end 185.44794 -115.62461)
		(width 0.1143)
		(layer "In9.Cu")
		(net "UPI_CPU0_CPU1_P0P0_DN<10>")
	)
	(segment
		(start 315.18733 -77.314552)
		(end 315.180726 -77.085698)
		(width 0.1143)
		(layer "In9.Cu")
		(net "UPI_CPU0_CPU1_P0P0_DN<10>")
	)
	(segment
		(start 271.740376 -113.236248)
		(end 271.74317 -113.236248)
		(width 0.1143)
		(layer "In9.Cu")
		(net "UPI_CPU0_CPU1_P0P0_DN<10>")
	)
	(segment
		(start 271.73428 -113.23701)
		(end 271.735804 -113.236756)
		(width 0.1143)
		(layer "In9.Cu")
		(net "UPI_CPU0_CPU1_P0P0_DN<10>")
	)
	(segment
		(start 278.062436 -112.629188)
		(end 284.366208 -113.359692)
		(width 0.1143)
		(layer "In9.Cu")
		(net "UPI_CPU0_CPU1_P0P0_DN<10>")
	)
	(segment
		(start 315.166502 -76.57084)
		(end 315.159898 -76.341986)
		(width 0.1143)
		(layer "In9.Cu")
		(net "UPI_CPU0_CPU1_P0P0_DN<10>")
	)
	(segment
		(start 315.054488 -77.690726)
		(end 315.047884 -77.461618)
		(width 0.1143)
		(layer "In9.Cu")
		(net "UPI_CPU0_CPU1_P0P0_DN<10>")
	)
	(segment
		(start 271.735804 -113.236756)
		(end 271.737074 -113.236756)
		(width 0.1143)
		(layer "In9.Cu")
		(net "UPI_CPU0_CPU1_P0P0_DN<10>")
	)
	(segment
		(start 315.24321 -79.316834)
		(end 315.096144 -79.17815)
		(width 0.1143)
		(layer "In9.Cu")
		(net "UPI_CPU0_CPU1_P0P0_DN<10>")
	)
	(segment
		(start 312.27776 -66.782188)
		(end 311.82056 -66.3448)
		(width 0.1143)
		(layer "In9.Cu")
		(net "UPI_CPU0_CPU1_P0P0_DN<10>")
	)
	(segment
		(start 315.104018 -74.339704)
		(end 315.097414 -74.11085)
		(width 0.1143)
		(layer "In9.Cu")
		(net "UPI_CPU0_CPU1_P0P0_DN<10>")
	)
	(segment
		(start 315.272928 -80.383888)
		(end 315.263784 -80.060546)
		(width 0.1143)
		(layer "In9.Cu")
		(net "UPI_CPU0_CPU1_P0P0_DN<10>")
	)
	(segment
		(start 315.084714 -73.594976)
		(end 315.076078 -73.277984)
		(width 0.1143)
		(layer "In9.Cu")
		(net "UPI_CPU0_CPU1_P0P0_DN<10>")
	)
	(segment
		(start 154.435048 -87.781384)
		(end 160.73628 -95.237808)
		(width 0.1143)
		(layer "In9.Cu")
		(net "UPI_CPU0_CPU1_P0P0_DN<10>")
	)
	(segment
		(start 142.540228 -69.017388)
		(end 142.666212 -69.143372)
		(width 0.0889)
		(layer "In9.Cu")
		(net "UPI_CPU0_CPU1_P0P0_DN<10>")
	)
	(segment
		(start 185.44794 -115.62461)
		(end 193.125344 -116.29263)
		(width 0.1143)
		(layer "In9.Cu")
		(net "UPI_CPU0_CPU1_P0P0_DN<10>")
	)
	(segment
		(start 160.73628 -95.237808)
		(end 161.479992 -100.048822)
		(width 0.1143)
		(layer "In9.Cu")
		(net "UPI_CPU0_CPU1_P0P0_DN<10>")
	)
	(segment
		(start 140.22832 -69.677534)
		(end 140.264388 -69.677534)
		(width 0.0889)
		(layer "In9.Cu")
		(net "UPI_CPU0_CPU1_P0P0_DN<10>")
	)
	(segment
		(start 142.919196 -69.396356)
		(end 142.990062 -69.467222)
		(width 0.0889)
		(layer "In9.Cu")
		(net "UPI_CPU0_CPU1_P0P0_DN<10>")
	)
	(segment
		(start 292.198298 -114.267742)
		(end 308.120796 -110.64494)
		(width 0.1143)
		(layer "In9.Cu")
		(net "UPI_CPU0_CPU1_P0P0_DN<10>")
	)
	(segment
		(start 315.076078 -73.277984)
		(end 312.27776 -66.782188)
		(width 0.1143)
		(layer "In9.Cu")
		(net "UPI_CPU0_CPU1_P0P0_DN<10>")
	)
	(segment
		(start 315.116972 -79.921862)
		(end 315.110368 -79.692754)
		(width 0.1143)
		(layer "In9.Cu")
		(net "UPI_CPU0_CPU1_P0P0_DN<10>")
	)
	(segment
		(start 284.366208 -113.359692)
		(end 284.560518 -113.205768)
		(width 0.1143)
		(layer "In9.Cu")
		(net "UPI_CPU0_CPU1_P0P0_DN<10>")
	)
	(segment
		(start 308.120796 -110.64494)
		(end 313.26836 -105.889298)
		(width 0.1143)
		(layer "In9.Cu")
		(net "UPI_CPU0_CPU1_P0P0_DN<10>")
	)
	(segment
		(start 172.357288 -110.4265)
		(end 175.122586 -111.651796)
		(width 0.1143)
		(layer "In9.Cu")
		(net "UPI_CPU0_CPU1_P0P0_DN<10>")
	)
	(segment
		(start 138.518138 -68.687188)
		(end 138.550904 -68.687188)
		(width 0.0889)
		(layer "In9.Cu")
		(net "UPI_CPU0_CPU1_P0P0_DN<10>")
	)
	(segment
		(start 315.124846 -75.083416)
		(end 315.118242 -74.854562)
		(width 0.1143)
		(layer "In9.Cu")
		(net "UPI_CPU0_CPU1_P0P0_DN<10>")
	)
	(segment
		(start 315.208158 -78.058264)
		(end 315.201554 -77.82941)
		(width 0.1143)
		(layer "In9.Cu")
		(net "UPI_CPU0_CPU1_P0P0_DN<10>")
	)
	(segment
		(start 315.083698 -73.595992)
		(end 315.084714 -73.594976)
		(width 0.1143)
		(layer "In9.Cu")
		(net "UPI_CPU0_CPU1_P0P0_DN<10>")
	)
	(segment
		(start 315.075316 -78.434438)
		(end 315.068712 -78.20533)
		(width 0.1143)
		(layer "In9.Cu")
		(net "UPI_CPU0_CPU1_P0P0_DN<10>")
	)
	(segment
		(start 314.964572 -74.48677)
		(end 315.104018 -74.339704)
		(width 0.1143)
		(layer "In9.Cu")
		(net "UPI_CPU0_CPU1_P0P0_DN<10>")
	)
	(segment
		(start 315.027056 -76.717906)
		(end 315.166502 -76.57084)
		(width 0.1143)
		(layer "In9.Cu")
		(net "UPI_CPU0_CPU1_P0P0_DN<10>")
	)
	(segment
		(start 142.287244 -68.764404)
		(end 142.414244 -68.764404)
		(width 0.0889)
		(layer "In9.Cu")
		(net "UPI_CPU0_CPU1_P0P0_DN<10>")
	)
	(segment
		(start 175.122586 -111.651796)
		(end 177.518314 -111.938308)
		(width 0.1143)
		(layer "In9.Cu")
		(net "UPI_CPU0_CPU1_P0P0_DN<10>")
	)
	(arc
		(start 139.041124 -68.982336)
		(mid 139.181203 -69.125072)
		(end 139.372848 -69.182234)
		(width 0.0889)
		(layer "In9.Cu")
		(net "UPI_CPU0_CPU1_P0P0_DN<10>")
	)
	(arc
		(start 141.451584 -68.982336)
		(mid 141.658697 -68.771406)
		(end 141.942058 -68.687188)
		(width 0.0889)
		(layer "In9.Cu")
		(net "UPI_CPU0_CPU1_P0P0_DN<10>")
	)
	(arc
		(start 139.405614 -69.182234)
		(mid 139.691038 -69.265701)
		(end 139.899644 -69.477636)
		(width 0.0889)
		(layer "In9.Cu")
		(net "UPI_CPU0_CPU1_P0P0_DN<10>")
	)
	(arc
		(start 138.550904 -68.687188)
		(mid 138.834121 -68.771469)
		(end 139.041124 -68.982336)
		(width 0.0889)
		(layer "In9.Cu")
		(net "UPI_CPU0_CPU1_P0P0_DN<10>")
	)
	(arc
		(start 140.264388 -69.677534)
		(mid 140.454317 -69.619664)
		(end 140.593064 -69.477636)
		(width 0.0889)
		(layer "In9.Cu")
		(net "UPI_CPU0_CPU1_P0P0_DN<10>")
	)
	(arc
		(start 137.298684 -67.938904)
		(mid 137.439635 -68.118426)
		(end 137.655808 -68.191634)
		(width 0.0889)
		(layer "In9.Cu")
		(net "UPI_CPU0_CPU1_P0P0_DN<10>")
	)
	(arc
		(start 140.593064 -69.477636)
		(mid 140.801672 -69.265704)
		(end 141.087094 -69.182234)
		(width 0.0889)
		(layer "In9.Cu")
		(net "UPI_CPU0_CPU1_P0P0_DN<10>")
	)
	(arc
		(start 139.899644 -69.477636)
		(mid 140.038388 -69.619669)
		(end 140.22832 -69.677534)
		(width 0.0889)
		(layer "In9.Cu")
		(net "UPI_CPU0_CPU1_P0P0_DN<10>")
	)
	(arc
		(start 137.688574 -68.191634)
		(mid 137.973998 -68.275101)
		(end 138.182604 -68.487036)
		(width 0.0889)
		(layer "In9.Cu")
		(net "UPI_CPU0_CPU1_P0P0_DN<10>")
	)
	(arc
		(start 141.11986 -69.182234)
		(mid 141.311502 -69.125068)
		(end 141.451584 -68.982336)
		(width 0.0889)
		(layer "In9.Cu")
		(net "UPI_CPU0_CPU1_P0P0_DN<10>")
	)
	(arc
		(start 138.182604 -68.487036)
		(mid 138.324287 -68.63084)
		(end 138.518138 -68.687188)
		(width 0.0889)
		(layer "In9.Cu")
		(net "UPI_CPU0_CPU1_P0P0_DN<10>")
	)
	(arc
		(start 137.298938 -67.64401)
		(mid 137.270632 -67.791437)
		(end 137.298684 -67.938904)
		(width 0.0889)
		(layer "In9.Cu")
		(net "UPI_CPU0_CPU1_P0P0_DN<10>")
	)
	(segment
		(start 135.382254 -61.847984)
		(end 135.953754 -61.847984)
		(width 0.1143)
		(layer "F.Cu")
		(net "UPI_CPU0_CPU1_P0P0_DN<0>")
	)
	(segment
		(start 304.675286 -74.230738)
		(end 305.246786 -74.230738)
		(width 0.1143)
		(layer "F.Cu")
		(net "UPI_CPU0_CPU1_P0P0_DN<0>")
	)
	(via
		(at 305.246786 -74.230738)
		(size 0.508)
		(drill 0.254)
		(layers "F.Cu" "B.Cu")
		(net "UPI_CPU0_CPU1_P0P0_DN<0>")
	)
	(via
		(at 135.953754 -61.847984)
		(size 0.508)
		(drill 0.254)
		(layers "F.Cu" "B.Cu")
		(net "UPI_CPU0_CPU1_P0P0_DN<0>")
	)
	(segment
		(start 305.112928 -105.081578)
		(end 305.175666 -105.023666)
		(width 0.1143)
		(layer "In9.Cu")
		(net "UPI_CPU0_CPU1_P0P0_DN<0>")
	)
	(segment
		(start 145.980912 -59.745626)
		(end 146.525234 -60.289948)
		(width 0.0889)
		(layer "In9.Cu")
		(net "UPI_CPU0_CPU1_P0P0_DN<0>")
	)
	(segment
		(start 135.953754 -61.847984)
		(end 135.9535 -62.0141)
		(width 0.0889)
		(layer "In9.Cu")
		(net "UPI_CPU0_CPU1_P0P0_DN<0>")
	)
	(segment
		(start 307.241194 -78.513178)
		(end 307.042312 -77.744574)
		(width 0.1143)
		(layer "In9.Cu")
		(net "UPI_CPU0_CPU1_P0P0_DN<0>")
	)
	(segment
		(start 306.888642 -77.102716)
		(end 306.888642 -74.364342)
		(width 0.0889)
		(layer "In9.Cu")
		(net "UPI_CPU0_CPU1_P0P0_DN<0>")
	)
	(segment
		(start 143.661892 -59.449716)
		(end 143.957802 -59.745626)
		(width 0.0889)
		(layer "In9.Cu")
		(net "UPI_CPU0_CPU1_P0P0_DN<0>")
	)
	(segment
		(start 248.017538 -104.233472)
		(end 263.322308 -107.391708)
		(width 0.1143)
		(layer "In9.Cu")
		(net "UPI_CPU0_CPU1_P0P0_DN<0>")
	)
	(segment
		(start 307.241194 -78.513686)
		(end 307.241194 -78.513178)
		(width 0.1143)
		(layer "In9.Cu")
		(net "UPI_CPU0_CPU1_P0P0_DN<0>")
	)
	(segment
		(start 155.032456 -66.726308)
		(end 159.958024 -84.892896)
		(width 0.1143)
		(layer "In9.Cu")
		(net "UPI_CPU0_CPU1_P0P0_DN<0>")
	)
	(segment
		(start 307.526182 -79.615792)
		(end 307.241194 -78.513686)
		(width 0.1143)
		(layer "In9.Cu")
		(net "UPI_CPU0_CPU1_P0P0_DN<0>")
	)
	(segment
		(start 136.797288 -60.952888)
		(end 136.830054 -60.952888)
		(width 0.0889)
		(layer "In9.Cu")
		(net "UPI_CPU0_CPU1_P0P0_DN<0>")
	)
	(segment
		(start 147.002246 -60.340748)
		(end 147.024344 -60.340748)
		(width 0.0889)
		(layer "In9.Cu")
		(net "UPI_CPU0_CPU1_P0P0_DN<0>")
	)
	(segment
		(start 135.614918 -62.07887)
		(end 135.581898 -61.995812)
		(width 0.0889)
		(layer "In9.Cu")
		(net "UPI_CPU0_CPU1_P0P0_DN<0>")
	)
	(segment
		(start 263.322308 -107.391708)
		(end 267.038328 -107.573826)
		(width 0.1143)
		(layer "In9.Cu")
		(net "UPI_CPU0_CPU1_P0P0_DN<0>")
	)
	(segment
		(start 143.957802 -59.745626)
		(end 145.980912 -59.745626)
		(width 0.0889)
		(layer "In9.Cu")
		(net "UPI_CPU0_CPU1_P0P0_DN<0>")
	)
	(segment
		(start 199.981566 -109.497876)
		(end 227.927154 -106.137456)
		(width 0.1143)
		(layer "In9.Cu")
		(net "UPI_CPU0_CPU1_P0P0_DN<0>")
	)
	(segment
		(start 306.888642 -74.364342)
		(end 306.659534 -74.135234)
		(width 0.0889)
		(layer "In9.Cu")
		(net "UPI_CPU0_CPU1_P0P0_DN<0>")
	)
	(segment
		(start 305.430428 -74.230738)
		(end 305.246786 -74.230738)
		(width 0.0889)
		(layer "In9.Cu")
		(net "UPI_CPU0_CPU1_P0P0_DN<0>")
	)
	(segment
		(start 307.026056 -77.672692)
		(end 306.939442 -77.290168)
		(width 0.1143)
		(layer "In9.Cu")
		(net "UPI_CPU0_CPU1_P0P0_DN<0>")
	)
	(segment
		(start 146.525234 -60.289948)
		(end 146.951446 -60.289948)
		(width 0.0889)
		(layer "In9.Cu")
		(net "UPI_CPU0_CPU1_P0P0_DN<0>")
	)
	(segment
		(start 138.514328 -59.962288)
		(end 138.542268 -59.962288)
		(width 0.0889)
		(layer "In9.Cu")
		(net "UPI_CPU0_CPU1_P0P0_DN<0>")
	)
	(segment
		(start 148.14423 -60.340748)
		(end 148.724874 -60.273184)
		(width 0.1143)
		(layer "In9.Cu")
		(net "UPI_CPU0_CPU1_P0P0_DN<0>")
	)
	(segment
		(start 290.113466 -103.183182)
		(end 290.11372 -103.183182)
		(width 0.1143)
		(layer "In9.Cu")
		(net "UPI_CPU0_CPU1_P0P0_DN<0>")
	)
	(segment
		(start 307.02631 -77.673708)
		(end 307.026056 -77.672692)
		(width 0.1143)
		(layer "In9.Cu")
		(net "UPI_CPU0_CPU1_P0P0_DN<0>")
	)
	(segment
		(start 290.113466 -103.182674)
		(end 290.113466 -103.183182)
		(width 0.1143)
		(layer "In9.Cu")
		(net "UPI_CPU0_CPU1_P0P0_DN<0>")
	)
	(segment
		(start 306.659534 -74.135234)
		(end 306.04333 -74.135234)
		(width 0.0889)
		(layer "In9.Cu")
		(net "UPI_CPU0_CPU1_P0P0_DN<0>")
	)
	(segment
		(start 159.958024 -84.892896)
		(end 166.571422 -92.718636)
		(width 0.1143)
		(layer "In9.Cu")
		(net "UPI_CPU0_CPU1_P0P0_DN<0>")
	)
	(segment
		(start 307.6956 -80.061308)
		(end 307.608478 -79.8322)
		(width 0.1143)
		(layer "In9.Cu")
		(net "UPI_CPU0_CPU1_P0P0_DN<0>")
	)
	(segment
		(start 148.724874 -60.273438)
		(end 149.16023 -60.304172)
		(width 0.1143)
		(layer "In9.Cu")
		(net "UPI_CPU0_CPU1_P0P0_DN<0>")
	)
	(segment
		(start 181.770782 -103.378)
		(end 183.944768 -104.920796)
		(width 0.1143)
		(layer "In9.Cu")
		(net "UPI_CPU0_CPU1_P0P0_DN<0>")
	)
	(segment
		(start 142.481554 -59.449716)
		(end 143.661892 -59.449716)
		(width 0.0889)
		(layer "In9.Cu")
		(net "UPI_CPU0_CPU1_P0P0_DN<0>")
	)
	(segment
		(start 149.16023 -60.304172)
		(end 149.411436 -60.579)
		(width 0.1143)
		(layer "In9.Cu")
		(net "UPI_CPU0_CPU1_P0P0_DN<0>")
	)
	(segment
		(start 307.608478 -79.8322)
		(end 307.526182 -79.615792)
		(width 0.1143)
		(layer "In9.Cu")
		(net "UPI_CPU0_CPU1_P0P0_DN<0>")
	)
	(segment
		(start 175.243236 -101.440742)
		(end 177.026824 -101.794564)
		(width 0.1143)
		(layer "In9.Cu")
		(net "UPI_CPU0_CPU1_P0P0_DN<0>")
	)
	(segment
		(start 192.751456 -105.99166)
		(end 197.031864 -108.796836)
		(width 0.1143)
		(layer "In9.Cu")
		(net "UPI_CPU0_CPU1_P0P0_DN<0>")
	)
	(segment
		(start 142.417292 -59.513978)
		(end 142.481554 -59.449716)
		(width 0.0889)
		(layer "In9.Cu")
		(net "UPI_CPU0_CPU1_P0P0_DN<0>")
	)
	(segment
		(start 137.659618 -60.457334)
		(end 137.692384 -60.457334)
		(width 0.0889)
		(layer "In9.Cu")
		(net "UPI_CPU0_CPU1_P0P0_DN<0>")
	)
	(segment
		(start 291.125402 -103.09098)
		(end 292.621716 -102.95509)
		(width 0.1143)
		(layer "In9.Cu")
		(net "UPI_CPU0_CPU1_P0P0_DN<0>")
	)
	(segment
		(start 197.031864 -108.796836)
		(end 199.981566 -109.497876)
		(width 0.1143)
		(layer "In9.Cu")
		(net "UPI_CPU0_CPU1_P0P0_DN<0>")
	)
	(segment
		(start 178.262534 -102.822502)
		(end 179.92852 -102.909116)
		(width 0.1143)
		(layer "In9.Cu")
		(net "UPI_CPU0_CPU1_P0P0_DN<0>")
	)
	(segment
		(start 281.23261 -106.8705)
		(end 290.113466 -103.182674)
		(width 0.1143)
		(layer "In9.Cu")
		(net "UPI_CPU0_CPU1_P0P0_DN<0>")
	)
	(segment
		(start 166.571422 -92.718636)
		(end 166.814246 -94.29115)
		(width 0.1143)
		(layer "In9.Cu")
		(net "UPI_CPU0_CPU1_P0P0_DN<0>")
	)
	(segment
		(start 166.814246 -94.29115)
		(end 173.295818 -101.054408)
		(width 0.1143)
		(layer "In9.Cu")
		(net "UPI_CPU0_CPU1_P0P0_DN<0>")
	)
	(segment
		(start 140.22832 -58.971688)
		(end 140.264388 -58.971688)
		(width 0.0889)
		(layer "In9.Cu")
		(net "UPI_CPU0_CPU1_P0P0_DN<0>")
	)
	(segment
		(start 278.120602 -106.50982)
		(end 281.23261 -106.8705)
		(width 0.1143)
		(layer "In9.Cu")
		(net "UPI_CPU0_CPU1_P0P0_DN<0>")
	)
	(segment
		(start 290.11372 -103.183182)
		(end 290.11372 -103.182928)
		(width 0.1143)
		(layer "In9.Cu")
		(net "UPI_CPU0_CPU1_P0P0_DN<0>")
	)
	(segment
		(start 135.942578 -61.447934)
		(end 135.975344 -61.447934)
		(width 0.0889)
		(layer "In9.Cu")
		(net "UPI_CPU0_CPU1_P0P0_DN<0>")
	)
	(segment
		(start 227.927154 -106.137456)
		(end 233.62793 -107.107736)
		(width 0.1143)
		(layer "In9.Cu")
		(net "UPI_CPU0_CPU1_P0P0_DN<0>")
	)
	(segment
		(start 290.11372 -103.182928)
		(end 291.125402 -103.09098)
		(width 0.1143)
		(layer "In9.Cu")
		(net "UPI_CPU0_CPU1_P0P0_DN<0>")
	)
	(segment
		(start 302.91278 -105.582466)
		(end 305.112928 -105.081578)
		(width 0.1143)
		(layer "In9.Cu")
		(net "UPI_CPU0_CPU1_P0P0_DN<0>")
	)
	(segment
		(start 267.038328 -107.573826)
		(end 278.120602 -106.50982)
		(width 0.1143)
		(layer "In9.Cu")
		(net "UPI_CPU0_CPU1_P0P0_DN<0>")
	)
	(segment
		(start 307.735478 -102.657402)
		(end 309.651908 -93.7768)
		(width 0.1143)
		(layer "In9.Cu")
		(net "UPI_CPU0_CPU1_P0P0_DN<0>")
	)
	(segment
		(start 139.3698 -59.466988)
		(end 139.405614 -59.466988)
		(width 0.0889)
		(layer "In9.Cu")
		(net "UPI_CPU0_CPU1_P0P0_DN<0>")
	)
	(segment
		(start 306.939442 -77.175614)
		(end 306.939442 -77.153516)
		(width 0.0889)
		(layer "In9.Cu")
		(net "UPI_CPU0_CPU1_P0P0_DN<0>")
	)
	(segment
		(start 173.295818 -101.054408)
		(end 175.243236 -101.440742)
		(width 0.1143)
		(layer "In9.Cu")
		(net "UPI_CPU0_CPU1_P0P0_DN<0>")
	)
	(segment
		(start 310.831484 -88.311228)
		(end 307.6956 -80.061308)
		(width 0.1143)
		(layer "In9.Cu")
		(net "UPI_CPU0_CPU1_P0P0_DN<0>")
	)
	(segment
		(start 306.939442 -77.290168)
		(end 306.939442 -77.175614)
		(width 0.1143)
		(layer "In9.Cu")
		(net "UPI_CPU0_CPU1_P0P0_DN<0>")
	)
	(segment
		(start 307.042312 -77.744574)
		(end 307.02631 -77.673708)
		(width 0.1143)
		(layer "In9.Cu")
		(net "UPI_CPU0_CPU1_P0P0_DN<0>")
	)
	(segment
		(start 177.026824 -101.794564)
		(end 178.262534 -102.822502)
		(width 0.1143)
		(layer "In9.Cu")
		(net "UPI_CPU0_CPU1_P0P0_DN<0>")
	)
	(segment
		(start 149.411436 -60.579)
		(end 155.032456 -66.726308)
		(width 0.1143)
		(layer "In9.Cu")
		(net "UPI_CPU0_CPU1_P0P0_DN<0>")
	)
	(segment
		(start 305.175666 -105.023666)
		(end 307.735478 -102.657402)
		(width 0.1143)
		(layer "In9.Cu")
		(net "UPI_CPU0_CPU1_P0P0_DN<0>")
	)
	(segment
		(start 146.951446 -60.289948)
		(end 147.002246 -60.340748)
		(width 0.0889)
		(layer "In9.Cu")
		(net "UPI_CPU0_CPU1_P0P0_DN<0>")
	)
	(segment
		(start 141.185646 -59.513978)
		(end 142.417292 -59.513978)
		(width 0.0889)
		(layer "In9.Cu")
		(net "UPI_CPU0_CPU1_P0P0_DN<0>")
	)
	(segment
		(start 292.621716 -102.95509)
		(end 302.91278 -105.582466)
		(width 0.1143)
		(layer "In9.Cu")
		(net "UPI_CPU0_CPU1_P0P0_DN<0>")
	)
	(segment
		(start 147.024344 -60.340748)
		(end 148.14423 -60.340748)
		(width 0.1143)
		(layer "In9.Cu")
		(net "UPI_CPU0_CPU1_P0P0_DN<0>")
	)
	(segment
		(start 179.92852 -102.909116)
		(end 181.770782 -103.378)
		(width 0.1143)
		(layer "In9.Cu")
		(net "UPI_CPU0_CPU1_P0P0_DN<0>")
	)
	(segment
		(start 233.62793 -107.107736)
		(end 248.017538 -104.233472)
		(width 0.1143)
		(layer "In9.Cu")
		(net "UPI_CPU0_CPU1_P0P0_DN<0>")
	)
	(segment
		(start 183.944768 -104.920796)
		(end 192.751456 -105.99166)
		(width 0.1143)
		(layer "In9.Cu")
		(net "UPI_CPU0_CPU1_P0P0_DN<0>")
	)
	(segment
		(start 148.724874 -60.273184)
		(end 148.724874 -60.273438)
		(width 0.1143)
		(layer "In9.Cu")
		(net "UPI_CPU0_CPU1_P0P0_DN<0>")
	)
	(segment
		(start 309.651908 -93.7768)
		(end 310.831484 -88.311228)
		(width 0.1143)
		(layer "In9.Cu")
		(net "UPI_CPU0_CPU1_P0P0_DN<0>")
	)
	(segment
		(start 306.939442 -77.153516)
		(end 306.888642 -77.102716)
		(width 0.0889)
		(layer "In9.Cu")
		(net "UPI_CPU0_CPU1_P0P0_DN<0>")
	)
	(arc
		(start 135.9535 -62.0141)
		(mid 135.810969 -62.186487)
		(end 135.614918 -62.07887)
		(width 0.0889)
		(layer "In9.Cu")
		(net "UPI_CPU0_CPU1_P0P0_DN<0>")
	)
	(arc
		(start 135.579866 -61.70549)
		(mid 135.722125 -61.521614)
		(end 135.942578 -61.447934)
		(width 0.0889)
		(layer "In9.Cu")
		(net "UPI_CPU0_CPU1_P0P0_DN<0>")
	)
	(arc
		(start 305.924204 -74.153776)
		(mid 305.680296 -74.21137)
		(end 305.430428 -74.230738)
		(width 0.0889)
		(layer "In9.Cu")
		(net "UPI_CPU0_CPU1_P0P0_DN<0>")
	)
	(arc
		(start 137.324084 -60.657486)
		(mid 137.465767 -60.513682)
		(end 137.659618 -60.457334)
		(width 0.0889)
		(layer "In9.Cu")
		(net "UPI_CPU0_CPU1_P0P0_DN<0>")
	)
	(arc
		(start 139.041124 -59.666886)
		(mid 139.179868 -59.524853)
		(end 139.3698 -59.466988)
		(width 0.0889)
		(layer "In9.Cu")
		(net "UPI_CPU0_CPU1_P0P0_DN<0>")
	)
	(arc
		(start 140.264388 -58.971688)
		(mid 140.454317 -59.029558)
		(end 140.593064 -59.171586)
		(width 0.0889)
		(layer "In9.Cu")
		(net "UPI_CPU0_CPU1_P0P0_DN<0>")
	)
	(arc
		(start 137.692384 -60.457334)
		(mid 137.975601 -60.373053)
		(end 138.182604 -60.162186)
		(width 0.0889)
		(layer "In9.Cu")
		(net "UPI_CPU0_CPU1_P0P0_DN<0>")
	)
	(arc
		(start 138.182604 -60.162186)
		(mid 138.322683 -60.01945)
		(end 138.514328 -59.962288)
		(width 0.0889)
		(layer "In9.Cu")
		(net "UPI_CPU0_CPU1_P0P0_DN<0>")
	)
	(arc
		(start 136.830054 -60.952888)
		(mid 137.115478 -60.869421)
		(end 137.324084 -60.657486)
		(width 0.0889)
		(layer "In9.Cu")
		(net "UPI_CPU0_CPU1_P0P0_DN<0>")
	)
	(arc
		(start 135.975344 -61.447934)
		(mid 136.258561 -61.363653)
		(end 136.465564 -61.152786)
		(width 0.0889)
		(layer "In9.Cu")
		(net "UPI_CPU0_CPU1_P0P0_DN<0>")
	)
	(arc
		(start 136.465564 -61.152786)
		(mid 136.605643 -61.01005)
		(end 136.797288 -60.952888)
		(width 0.0889)
		(layer "In9.Cu")
		(net "UPI_CPU0_CPU1_P0P0_DN<0>")
	)
	(arc
		(start 140.593064 -59.171586)
		(mid 140.843488 -59.422126)
		(end 141.185646 -59.513978)
		(width 0.0889)
		(layer "In9.Cu")
		(net "UPI_CPU0_CPU1_P0P0_DN<0>")
	)
	(arc
		(start 135.581898 -61.995812)
		(mid 135.55362 -61.850838)
		(end 135.579866 -61.70549)
		(width 0.0889)
		(layer "In9.Cu")
		(net "UPI_CPU0_CPU1_P0P0_DN<0>")
	)
	(arc
		(start 306.04333 -74.135234)
		(mid 305.983046 -74.139874)
		(end 305.924204 -74.153776)
		(width 0.0889)
		(layer "In9.Cu")
		(net "UPI_CPU0_CPU1_P0P0_DN<0>")
	)
	(arc
		(start 138.542268 -59.962288)
		(mid 138.830413 -59.879969)
		(end 139.041124 -59.666886)
		(width 0.0889)
		(layer "In9.Cu")
		(net "UPI_CPU0_CPU1_P0P0_DN<0>")
	)
	(arc
		(start 139.405614 -59.466988)
		(mid 139.691038 -59.383521)
		(end 139.899644 -59.171586)
		(width 0.0889)
		(layer "In9.Cu")
		(net "UPI_CPU0_CPU1_P0P0_DN<0>")
	)
	(arc
		(start 139.899644 -59.171586)
		(mid 140.038388 -59.029553)
		(end 140.22832 -58.971688)
		(width 0.0889)
		(layer "In9.Cu")
		(net "UPI_CPU0_CPU1_P0P0_DN<0>")
	)
	(segment
		(start 475.003368 -118.34368)
		(end 475.003368 -118.34622)
		(width 0.10795)
		(layer "F.Cu")
		(net "RST_PCIE_CPU_DEV0_R_N")
	)
	(segment
		(start 475.003368 -118.34622)
		(end 474.514418 -118.83517)
		(width 0.10795)
		(layer "F.Cu")
		(net "RST_PCIE_CPU_DEV0_R_N")
	)
	(segment
		(start 475.000828 -116.993162)
		(end 475.003368 -118.34368)
		(width 0.10795)
		(layer "F.Cu")
		(net "RST_PCIE_CPU_DEV0_R_N")
	)
	(via
		(at 474.514418 -118.83517)
		(size 0.508)
		(drill 0.254)
		(layers "F.Cu" "B.Cu")
		(net "RST_PCIE_CPU_DEV0_R_N")
	)
	(segment
		(start 474.514418 -118.83517)
		(end 474.345 -119.004588)
		(width 0.10795)
		(layer "B.Cu")
		(net "RST_PCIE_CPU_DEV0_R_N")
	)
	(segment
		(start 474.345 -119.004588)
		(end 474.345 -119.9388)
		(width 0.10795)
		(layer "B.Cu")
		(net "RST_PCIE_CPU_DEV0_R_N")
	)
	(segment
		(start 379.159262 -69.525896)
		(end 379.102366 -69.469)
		(width 0.10795)
		(layer "F.Cu")
		(net "FM_PCH_PLD_DATA")
	)
	(segment
		(start 416.089338 -110.1598)
		(end 416.248088 -110.00105)
		(width 0.10795)
		(layer "F.Cu")
		(net "FM_PCH_PLD_DATA")
	)
	(segment
		(start 414.8455 -110.617)
		(end 414.8455 -110.2995)
		(width 0.10795)
		(layer "F.Cu")
		(net "FM_PCH_PLD_DATA")
	)
	(segment
		(start 416.40125 -110.00105)
		(end 416.433 -110.0328)
		(width 0.10795)
		(layer "F.Cu")
		(net "FM_PCH_PLD_DATA")
	)
	(segment
		(start 379.102366 -69.469)
		(end 378.370846 -69.469)
		(width 0.10795)
		(layer "F.Cu")
		(net "FM_PCH_PLD_DATA")
	)
	(segment
		(start 414.9852 -110.1598)
		(end 416.089338 -110.1598)
		(width 0.10795)
		(layer "F.Cu")
		(net "FM_PCH_PLD_DATA")
	)
	(segment
		(start 416.248088 -110.00105)
		(end 416.40125 -110.00105)
		(width 0.10795)
		(layer "F.Cu")
		(net "FM_PCH_PLD_DATA")
	)
	(segment
		(start 414.8455 -110.2995)
		(end 414.9852 -110.1598)
		(width 0.10795)
		(layer "F.Cu")
		(net "FM_PCH_PLD_DATA")
	)
	(segment
		(start 378.370846 -69.469)
		(end 377.944888 -69.894958)
		(width 0.10795)
		(layer "F.Cu")
		(net "FM_PCH_PLD_DATA")
	)
	(segment
		(start 414.8455 -110.617)
		(end 413.3215 -110.617)
		(width 0.10795)
		(layer "F.Cu")
		(net "FM_PCH_PLD_DATA")
	)
	(via
		(at 416.433 -110.0328)
		(size 0.508)
		(drill 0.254)
		(layers "F.Cu" "B.Cu")
		(net "FM_PCH_PLD_DATA")
	)
	(via
		(at 379.159262 -69.525896)
		(size 0.508)
		(drill 0.254)
		(layers "F.Cu" "B.Cu")
		(net "FM_PCH_PLD_DATA")
	)
	(via
		(at 421.941244 -62.319408)
		(size 0.508)
		(drill 0.254)
		(layers "F.Cu" "B.Cu")
		(net "FM_PCH_PLD_DATA")
	)
	(via
		(at 420.751 -62.865)
		(size 0.6604)
		(drill 0.3302)
		(layers "F.Cu" "B.Cu")
		(net "FM_PCH_PLD_DATA")
	)
	(segment
		(start 421.941244 -62.319408)
		(end 421.395652 -62.865)
		(width 0.10795)
		(layer "B.Cu")
		(net "FM_PCH_PLD_DATA")
	)
	(segment
		(start 421.395652 -62.865)
		(end 420.751 -62.865)
		(width 0.10795)
		(layer "B.Cu")
		(net "FM_PCH_PLD_DATA")
	)
	(segment
		(start 419.198298 -75.169776)
		(end 419.198044 -75.169522)
		(width 0.089408)
		(layer "In2.Cu")
		(net "FM_PCH_PLD_DATA")
	)
	(segment
		(start 417.162996 -88.159336)
		(end 417.186618 -88.159336)
		(width 0.089408)
		(layer "In2.Cu")
		(net "FM_PCH_PLD_DATA")
	)
	(segment
		(start 416.89274 -93.870018)
		(end 416.88766 -93.870018)
		(width 0.089408)
		(layer "In2.Cu")
		(net "FM_PCH_PLD_DATA")
	)
	(segment
		(start 418.595302 -82.136234)
		(end 418.595048 -82.13598)
		(width 0.089408)
		(layer "In2.Cu")
		(net "FM_PCH_PLD_DATA")
	)
	(segment
		(start 418.595048 -86.750906)
		(end 418.595048 -83.297268)
		(width 0.089408)
		(layer "In2.Cu")
		(net "FM_PCH_PLD_DATA")
	)
	(segment
		(start 418.595048 -83.297268)
		(end 418.595302 -83.297014)
		(width 0.089408)
		(layer "In2.Cu")
		(net "FM_PCH_PLD_DATA")
	)
	(segment
		(start 417.122864 -109.739176)
		(end 417.122864 -106.987848)
		(width 0.089408)
		(layer "In2.Cu")
		(net "FM_PCH_PLD_DATA")
	)
	(segment
		(start 417.075112 -94.7801)
		(end 417.075112 -94.05239)
		(width 0.089408)
		(layer "In2.Cu")
		(net "FM_PCH_PLD_DATA")
	)
	(segment
		(start 417.122864 -106.987848)
		(end 417.472368 -106.638344)
		(width 0.089408)
		(layer "In2.Cu")
		(net "FM_PCH_PLD_DATA")
	)
	(segment
		(start 419.429692 -65.369186)
		(end 419.429946 -65.368932)
		(width 0.089408)
		(layer "In2.Cu")
		(net "FM_PCH_PLD_DATA")
	)
	(segment
		(start 416.82924 -110.0328)
		(end 417.122864 -109.739176)
		(width 0.089408)
		(layer "In2.Cu")
		(net "FM_PCH_PLD_DATA")
	)
	(segment
		(start 417.099496 -90.26652)
		(end 417.099496 -88.896444)
		(width 0.089408)
		(layer "In2.Cu")
		(net "FM_PCH_PLD_DATA")
	)
	(segment
		(start 419.19779 -76.172568)
		(end 419.198298 -76.17206)
		(width 0.089408)
		(layer "In2.Cu")
		(net "FM_PCH_PLD_DATA")
	)
	(segment
		(start 419.19779 -71.735696)
		(end 419.429692 -71.503794)
		(width 0.089408)
		(layer "In2.Cu")
		(net "FM_PCH_PLD_DATA")
	)
	(segment
		(start 416.16249 -93.144848)
		(end 416.16249 -91.203526)
		(width 0.089408)
		(layer "In2.Cu")
		(net "FM_PCH_PLD_DATA")
	)
	(segment
		(start 417.472368 -106.638344)
		(end 417.472368 -103.483156)
		(width 0.089408)
		(layer "In2.Cu")
		(net "FM_PCH_PLD_DATA")
	)
	(segment
		(start 416.928554 -88.725502)
		(end 416.928554 -88.393778)
		(width 0.089408)
		(layer "In2.Cu")
		(net "FM_PCH_PLD_DATA")
	)
	(segment
		(start 416.16249 -91.203526)
		(end 417.099496 -90.26652)
		(width 0.089408)
		(layer "In2.Cu")
		(net "FM_PCH_PLD_DATA")
	)
	(segment
		(start 418.595048 -76.911708)
		(end 419.19779 -76.308966)
		(width 0.089408)
		(layer "In2.Cu")
		(net "FM_PCH_PLD_DATA")
	)
	(segment
		(start 417.472368 -103.483156)
		(end 416.917124 -102.927912)
		(width 0.089408)
		(layer "In2.Cu")
		(net "FM_PCH_PLD_DATA")
	)
	(segment
		(start 419.198044 -75.011534)
		(end 419.19779 -75.01128)
		(width 0.089408)
		(layer "In2.Cu")
		(net "FM_PCH_PLD_DATA")
	)
	(segment
		(start 419.19779 -75.01128)
		(end 419.19779 -71.735696)
		(width 0.089408)
		(layer "In2.Cu")
		(net "FM_PCH_PLD_DATA")
	)
	(segment
		(start 416.433 -110.0328)
		(end 416.82924 -110.0328)
		(width 0.089408)
		(layer "In2.Cu")
		(net "FM_PCH_PLD_DATA")
	)
	(segment
		(start 416.928554 -88.393778)
		(end 417.162996 -88.159336)
		(width 0.089408)
		(layer "In2.Cu")
		(net "FM_PCH_PLD_DATA")
	)
	(segment
		(start 419.429946 -64.302894)
		(end 421.413432 -62.319408)
		(width 0.089408)
		(layer "In2.Cu")
		(net "FM_PCH_PLD_DATA")
	)
	(segment
		(start 418.595048 -82.13598)
		(end 418.595048 -76.911708)
		(width 0.089408)
		(layer "In2.Cu")
		(net "FM_PCH_PLD_DATA")
	)
	(segment
		(start 416.88766 -93.870018)
		(end 416.16249 -93.144848)
		(width 0.089408)
		(layer "In2.Cu")
		(net "FM_PCH_PLD_DATA")
	)
	(segment
		(start 419.429692 -71.503794)
		(end 419.429692 -65.369186)
		(width 0.089408)
		(layer "In2.Cu")
		(net "FM_PCH_PLD_DATA")
	)
	(segment
		(start 417.075112 -94.05239)
		(end 416.89274 -93.870018)
		(width 0.089408)
		(layer "In2.Cu")
		(net "FM_PCH_PLD_DATA")
	)
	(segment
		(start 417.099496 -88.896444)
		(end 416.928554 -88.725502)
		(width 0.089408)
		(layer "In2.Cu")
		(net "FM_PCH_PLD_DATA")
	)
	(segment
		(start 416.917124 -102.927912)
		(end 416.917124 -94.938088)
		(width 0.089408)
		(layer "In2.Cu")
		(net "FM_PCH_PLD_DATA")
	)
	(segment
		(start 417.186618 -88.159336)
		(end 418.595048 -86.750906)
		(width 0.089408)
		(layer "In2.Cu")
		(net "FM_PCH_PLD_DATA")
	)
	(segment
		(start 419.19779 -76.308966)
		(end 419.19779 -76.172568)
		(width 0.089408)
		(layer "In2.Cu")
		(net "FM_PCH_PLD_DATA")
	)
	(segment
		(start 419.429946 -65.368932)
		(end 419.429946 -64.302894)
		(width 0.089408)
		(layer "In2.Cu")
		(net "FM_PCH_PLD_DATA")
	)
	(segment
		(start 416.917124 -94.938088)
		(end 417.075112 -94.7801)
		(width 0.089408)
		(layer "In2.Cu")
		(net "FM_PCH_PLD_DATA")
	)
	(segment
		(start 419.198298 -76.17206)
		(end 419.198298 -75.169776)
		(width 0.089408)
		(layer "In2.Cu")
		(net "FM_PCH_PLD_DATA")
	)
	(segment
		(start 421.413432 -62.319408)
		(end 421.941244 -62.319408)
		(width 0.089408)
		(layer "In2.Cu")
		(net "FM_PCH_PLD_DATA")
	)
	(segment
		(start 419.198044 -75.169522)
		(end 419.198044 -75.011534)
		(width 0.089408)
		(layer "In2.Cu")
		(net "FM_PCH_PLD_DATA")
	)
	(segment
		(start 418.595302 -83.297014)
		(end 418.595302 -82.136234)
		(width 0.089408)
		(layer "In2.Cu")
		(net "FM_PCH_PLD_DATA")
	)
	(segment
		(start 407.59888 -69.907404)
		(end 382.96215 -69.907404)
		(width 0.089408)
		(layer "In4.Cu")
		(net "FM_PCH_PLD_DATA")
	)
	(segment
		(start 415.246312 -67.006724)
		(end 415.246312 -67.952112)
		(width 0.089408)
		(layer "In4.Cu")
		(net "FM_PCH_PLD_DATA")
	)
	(segment
		(start 408.720544 -68.78574)
		(end 407.59888 -69.907404)
		(width 0.089408)
		(layer "In4.Cu")
		(net "FM_PCH_PLD_DATA")
	)
	(segment
		(start 415.578544 -66.674492)
		(end 415.246312 -67.006724)
		(width 0.089408)
		(layer "In4.Cu")
		(net "FM_PCH_PLD_DATA")
	)
	(segment
		(start 415.246312 -67.952112)
		(end 414.412684 -68.78574)
		(width 0.089408)
		(layer "In4.Cu")
		(net "FM_PCH_PLD_DATA")
	)
	(segment
		(start 379.647958 -69.0372)
		(end 379.159262 -69.525896)
		(width 0.089408)
		(layer "In4.Cu")
		(net "FM_PCH_PLD_DATA")
	)
	(segment
		(start 382.96215 -69.907404)
		(end 382.091946 -69.0372)
		(width 0.089408)
		(layer "In4.Cu")
		(net "FM_PCH_PLD_DATA")
	)
	(segment
		(start 420.84117 -62.319408)
		(end 416.486086 -66.674492)
		(width 0.089408)
		(layer "In4.Cu")
		(net "FM_PCH_PLD_DATA")
	)
	(segment
		(start 416.486086 -66.674492)
		(end 415.578544 -66.674492)
		(width 0.089408)
		(layer "In4.Cu")
		(net "FM_PCH_PLD_DATA")
	)
	(segment
		(start 414.412684 -68.78574)
		(end 408.720544 -68.78574)
		(width 0.089408)
		(layer "In4.Cu")
		(net "FM_PCH_PLD_DATA")
	)
	(segment
		(start 382.091946 -69.0372)
		(end 379.647958 -69.0372)
		(width 0.089408)
		(layer "In4.Cu")
		(net "FM_PCH_PLD_DATA")
	)
	(segment
		(start 421.941244 -62.319408)
		(end 420.84117 -62.319408)
		(width 0.089408)
		(layer "In4.Cu")
		(net "FM_PCH_PLD_DATA")
	)
	(segment
		(start 393.68095 -100.41128)
		(end 394.17625 -100.181156)
		(width 0.10795)
		(layer "F.Cu")
		(net "FM_BOARD_SKU_ID4")
	)
	(segment
		(start 422.29024 -30.53461)
		(end 422.69029 -30.13456)
		(width 0.10795)
		(layer "F.Cu")
		(net "FM_BOARD_SKU_ID4")
	)
	(via
		(at 374.7008 -36.2204)
		(size 0.508)
		(drill 0.254)
		(layers "F.Cu" "B.Cu")
		(net "FM_BOARD_SKU_ID4")
	)
	(via
		(at 394.17625 -100.181156)
		(size 0.508)
		(drill 0.254)
		(layers "F.Cu" "B.Cu")
		(net "FM_BOARD_SKU_ID4")
	)
	(via
		(at 400.38147 -94.264988)
		(size 0.6604)
		(drill 0.3302)
		(layers "F.Cu" "B.Cu")
		(net "FM_BOARD_SKU_ID4")
	)
	(via
		(at 422.69029 -30.13456)
		(size 0.4572)
		(drill 0.2032)
		(layers "F.Cu" "B.Cu")
		(net "FM_BOARD_SKU_ID4")
	)
	(segment
		(start 403.5425 -92.96781)
		(end 403.568408 -92.993718)
		(width 0.10795)
		(layer "B.Cu")
		(net "FM_BOARD_SKU_ID4")
	)
	(segment
		(start 397.556228 -99.910138)
		(end 397.556228 -100.383594)
		(width 0.10795)
		(layer "B.Cu")
		(net "FM_BOARD_SKU_ID4")
	)
	(segment
		(start 397.822928 -97.2058)
		(end 397.813022 -97.195894)
		(width 0.10795)
		(layer "B.Cu")
		(net "FM_BOARD_SKU_ID4")
	)
	(segment
		(start 396.657322 -98.214434)
		(end 396.657322 -98.670872)
		(width 0.10795)
		(layer "B.Cu")
		(net "FM_BOARD_SKU_ID4")
	)
	(segment
		(start 397.218154 -101.05136)
		(end 396.82166 -101.447854)
		(width 0.10795)
		(layer "B.Cu")
		(net "FM_BOARD_SKU_ID4")
	)
	(segment
		(start 400.38147 -94.264988)
		(end 399.410936 -95.235522)
		(width 0.10795)
		(layer "B.Cu")
		(net "FM_BOARD_SKU_ID4")
	)
	(segment
		(start 397.233648 -97.435924)
		(end 397.233648 -97.43821)
		(width 0.10795)
		(layer "B.Cu")
		(net "FM_BOARD_SKU_ID4")
	)
	(segment
		(start 397.233648 -97.43821)
		(end 397.222472 -97.449386)
		(width 0.10795)
		(layer "B.Cu")
		(net "FM_BOARD_SKU_ID4")
	)
	(segment
		(start 397.473678 -97.195894)
		(end 397.233648 -97.435924)
		(width 0.10795)
		(layer "B.Cu")
		(net "FM_BOARD_SKU_ID4")
	)
	(segment
		(start 400.38147 -94.264988)
		(end 401.208494 -93.437964)
		(width 0.10795)
		(layer "B.Cu")
		(net "FM_BOARD_SKU_ID4")
	)
	(segment
		(start 399.410936 -96.051878)
		(end 398.257014 -97.2058)
		(width 0.10795)
		(layer "B.Cu")
		(net "FM_BOARD_SKU_ID4")
	)
	(segment
		(start 397.222472 -97.449386)
		(end 397.222472 -97.649284)
		(width 0.10795)
		(layer "B.Cu")
		(net "FM_BOARD_SKU_ID4")
	)
	(segment
		(start 396.82166 -101.447854)
		(end 395.49324 -101.447854)
		(width 0.10795)
		(layer "B.Cu")
		(net "FM_BOARD_SKU_ID4")
	)
	(segment
		(start 403.568408 -92.993718)
		(end 404.330408 -92.993718)
		(width 0.10795)
		(layer "B.Cu")
		(net "FM_BOARD_SKU_ID4")
	)
	(segment
		(start 395.226286 -101.1809)
		(end 395.226286 -101.017324)
		(width 0.10795)
		(layer "B.Cu")
		(net "FM_BOARD_SKU_ID4")
	)
	(segment
		(start 399.410936 -95.235522)
		(end 399.410936 -96.051878)
		(width 0.10795)
		(layer "B.Cu")
		(net "FM_BOARD_SKU_ID4")
	)
	(segment
		(start 403.29612 -92.571316)
		(end 403.5425 -92.817696)
		(width 0.10795)
		(layer "B.Cu")
		(net "FM_BOARD_SKU_ID4")
	)
	(segment
		(start 397.218154 -100.721668)
		(end 397.218154 -101.05136)
		(width 0.10795)
		(layer "B.Cu")
		(net "FM_BOARD_SKU_ID4")
	)
	(segment
		(start 402.355812 -92.571316)
		(end 403.29612 -92.571316)
		(width 0.10795)
		(layer "B.Cu")
		(net "FM_BOARD_SKU_ID4")
	)
	(segment
		(start 395.49324 -101.447854)
		(end 395.226286 -101.1809)
		(width 0.10795)
		(layer "B.Cu")
		(net "FM_BOARD_SKU_ID4")
	)
	(segment
		(start 397.813022 -97.195894)
		(end 397.473678 -97.195894)
		(width 0.10795)
		(layer "B.Cu")
		(net "FM_BOARD_SKU_ID4")
	)
	(segment
		(start 397.556228 -100.383594)
		(end 397.218154 -100.721668)
		(width 0.10795)
		(layer "B.Cu")
		(net "FM_BOARD_SKU_ID4")
	)
	(segment
		(start 401.208494 -93.437964)
		(end 401.91563 -93.437964)
		(width 0.10795)
		(layer "B.Cu")
		(net "FM_BOARD_SKU_ID4")
	)
	(segment
		(start 402.257006 -92.670122)
		(end 402.355812 -92.571316)
		(width 0.10795)
		(layer "B.Cu")
		(net "FM_BOARD_SKU_ID4")
	)
	(segment
		(start 402.257006 -93.096588)
		(end 402.257006 -92.670122)
		(width 0.10795)
		(layer "B.Cu")
		(net "FM_BOARD_SKU_ID4")
	)
	(segment
		(start 397.089376 -99.102926)
		(end 397.089376 -99.443286)
		(width 0.10795)
		(layer "B.Cu")
		(net "FM_BOARD_SKU_ID4")
	)
	(segment
		(start 403.5425 -92.817696)
		(end 403.5425 -92.96781)
		(width 0.10795)
		(layer "B.Cu")
		(net "FM_BOARD_SKU_ID4")
	)
	(segment
		(start 397.089376 -99.443286)
		(end 397.556228 -99.910138)
		(width 0.10795)
		(layer "B.Cu")
		(net "FM_BOARD_SKU_ID4")
	)
	(segment
		(start 394.692886 -100.483924)
		(end 394.479018 -100.483924)
		(width 0.10795)
		(layer "B.Cu")
		(net "FM_BOARD_SKU_ID4")
	)
	(segment
		(start 397.222472 -97.649284)
		(end 396.657322 -98.214434)
		(width 0.10795)
		(layer "B.Cu")
		(net "FM_BOARD_SKU_ID4")
	)
	(segment
		(start 396.657322 -98.670872)
		(end 397.089376 -99.102926)
		(width 0.10795)
		(layer "B.Cu")
		(net "FM_BOARD_SKU_ID4")
	)
	(segment
		(start 394.479018 -100.483924)
		(end 394.17625 -100.181156)
		(width 0.10795)
		(layer "B.Cu")
		(net "FM_BOARD_SKU_ID4")
	)
	(segment
		(start 398.257014 -97.2058)
		(end 397.822928 -97.2058)
		(width 0.10795)
		(layer "B.Cu")
		(net "FM_BOARD_SKU_ID4")
	)
	(segment
		(start 395.226286 -101.017324)
		(end 394.692886 -100.483924)
		(width 0.10795)
		(layer "B.Cu")
		(net "FM_BOARD_SKU_ID4")
	)
	(segment
		(start 401.91563 -93.437964)
		(end 402.257006 -93.096588)
		(width 0.10795)
		(layer "B.Cu")
		(net "FM_BOARD_SKU_ID4")
	)
	(segment
		(start 386.917184 -33.09874)
		(end 389.27151 -33.09874)
		(width 0.089408)
		(layer "In4.Cu")
		(net "FM_BOARD_SKU_ID4")
	)
	(segment
		(start 416.07232 -32.94888)
		(end 416.62096 -32.40024)
		(width 0.089408)
		(layer "In4.Cu")
		(net "FM_BOARD_SKU_ID4")
	)
	(segment
		(start 389.27151 -33.09874)
		(end 389.40359 -33.23082)
		(width 0.089408)
		(layer "In4.Cu")
		(net "FM_BOARD_SKU_ID4")
	)
	(segment
		(start 409.464764 -32.909256)
		(end 409.655518 -33.10001)
		(width 0.089408)
		(layer "In4.Cu")
		(net "FM_BOARD_SKU_ID4")
	)
	(segment
		(start 407.980388 -32.909256)
		(end 409.464764 -32.909256)
		(width 0.089408)
		(layer "In4.Cu")
		(net "FM_BOARD_SKU_ID4")
	)
	(segment
		(start 400.291554 -33.088326)
		(end 400.903948 -33.70072)
		(width 0.089408)
		(layer "In4.Cu")
		(net "FM_BOARD_SKU_ID4")
	)
	(segment
		(start 396.183104 -36.333684)
		(end 396.52575 -35.991038)
		(width 0.089408)
		(layer "In4.Cu")
		(net "FM_BOARD_SKU_ID4")
	)
	(segment
		(start 422.26484 -30.56001)
		(end 422.69029 -30.13456)
		(width 0.089408)
		(layer "In4.Cu")
		(net "FM_BOARD_SKU_ID4")
	)
	(segment
		(start 397.497554 -33.088326)
		(end 400.291554 -33.088326)
		(width 0.089408)
		(layer "In4.Cu")
		(net "FM_BOARD_SKU_ID4")
	)
	(segment
		(start 419.61054 -31.324804)
		(end 419.915594 -31.629858)
		(width 0.089408)
		(layer "In4.Cu")
		(net "FM_BOARD_SKU_ID4")
	)
	(segment
		(start 400.903948 -33.70072)
		(end 405.249888 -33.70072)
		(width 0.089408)
		(layer "In4.Cu")
		(net "FM_BOARD_SKU_ID4")
	)
	(segment
		(start 386.150104 -33.86582)
		(end 386.917184 -33.09874)
		(width 0.089408)
		(layer "In4.Cu")
		(net "FM_BOARD_SKU_ID4")
	)
	(segment
		(start 421.734742 -31.30931)
		(end 422.045638 -31.30931)
		(width 0.089408)
		(layer "In4.Cu")
		(net "FM_BOARD_SKU_ID4")
	)
	(segment
		(start 421.242998 -32.11195)
		(end 421.46474 -31.890208)
		(width 0.089408)
		(layer "In4.Cu")
		(net "FM_BOARD_SKU_ID4")
	)
	(segment
		(start 416.62096 -31.588964)
		(end 416.88512 -31.324804)
		(width 0.089408)
		(layer "In4.Cu")
		(net "FM_BOARD_SKU_ID4")
	)
	(segment
		(start 396.52575 -34.928048)
		(end 396.998698 -34.4551)
		(width 0.089408)
		(layer "In4.Cu")
		(net "FM_BOARD_SKU_ID4")
	)
	(segment
		(start 385.371594 -33.86582)
		(end 386.150104 -33.86582)
		(width 0.089408)
		(layer "In4.Cu")
		(net "FM_BOARD_SKU_ID4")
	)
	(segment
		(start 405.249888 -33.70072)
		(end 405.426418 -33.87725)
		(width 0.089408)
		(layer "In4.Cu")
		(net "FM_BOARD_SKU_ID4")
	)
	(segment
		(start 378.918978 -33.225994)
		(end 384.731768 -33.225994)
		(width 0.089408)
		(layer "In4.Cu")
		(net "FM_BOARD_SKU_ID4")
	)
	(segment
		(start 394.45311 -35.974274)
		(end 394.81252 -36.333684)
		(width 0.089408)
		(layer "In4.Cu")
		(net "FM_BOARD_SKU_ID4")
	)
	(segment
		(start 413.077406 -32.94888)
		(end 416.07232 -32.94888)
		(width 0.089408)
		(layer "In4.Cu")
		(net "FM_BOARD_SKU_ID4")
	)
	(segment
		(start 419.915594 -31.629858)
		(end 419.915594 -31.890208)
		(width 0.089408)
		(layer "In4.Cu")
		(net "FM_BOARD_SKU_ID4")
	)
	(segment
		(start 422.045638 -31.30931)
		(end 422.26484 -31.090108)
		(width 0.089408)
		(layer "In4.Cu")
		(net "FM_BOARD_SKU_ID4")
	)
	(segment
		(start 394.81252 -36.333684)
		(end 396.183104 -36.333684)
		(width 0.089408)
		(layer "In4.Cu")
		(net "FM_BOARD_SKU_ID4")
	)
	(segment
		(start 394.45311 -34.80943)
		(end 394.45311 -35.974274)
		(width 0.089408)
		(layer "In4.Cu")
		(net "FM_BOARD_SKU_ID4")
	)
	(segment
		(start 405.426418 -33.87725)
		(end 407.012394 -33.87725)
		(width 0.089408)
		(layer "In4.Cu")
		(net "FM_BOARD_SKU_ID4")
	)
	(segment
		(start 416.88512 -31.324804)
		(end 419.61054 -31.324804)
		(width 0.089408)
		(layer "In4.Cu")
		(net "FM_BOARD_SKU_ID4")
	)
	(segment
		(start 421.46474 -31.890208)
		(end 421.46474 -31.579312)
		(width 0.089408)
		(layer "In4.Cu")
		(net "FM_BOARD_SKU_ID4")
	)
	(segment
		(start 421.46474 -31.579312)
		(end 421.734742 -31.30931)
		(width 0.089408)
		(layer "In4.Cu")
		(net "FM_BOARD_SKU_ID4")
	)
	(segment
		(start 409.655518 -33.10001)
		(end 412.926276 -33.10001)
		(width 0.089408)
		(layer "In4.Cu")
		(net "FM_BOARD_SKU_ID4")
	)
	(segment
		(start 416.62096 -32.40024)
		(end 416.62096 -31.588964)
		(width 0.089408)
		(layer "In4.Cu")
		(net "FM_BOARD_SKU_ID4")
	)
	(segment
		(start 420.137336 -32.11195)
		(end 421.242998 -32.11195)
		(width 0.089408)
		(layer "In4.Cu")
		(net "FM_BOARD_SKU_ID4")
	)
	(segment
		(start 396.52575 -35.991038)
		(end 396.52575 -34.928048)
		(width 0.089408)
		(layer "In4.Cu")
		(net "FM_BOARD_SKU_ID4")
	)
	(segment
		(start 392.8745 -33.23082)
		(end 394.45311 -34.80943)
		(width 0.089408)
		(layer "In4.Cu")
		(net "FM_BOARD_SKU_ID4")
	)
	(segment
		(start 389.40359 -33.23082)
		(end 392.8745 -33.23082)
		(width 0.089408)
		(layer "In4.Cu")
		(net "FM_BOARD_SKU_ID4")
	)
	(segment
		(start 422.26484 -31.090108)
		(end 422.26484 -30.56001)
		(width 0.089408)
		(layer "In4.Cu")
		(net "FM_BOARD_SKU_ID4")
	)
	(segment
		(start 384.731768 -33.225994)
		(end 385.371594 -33.86582)
		(width 0.089408)
		(layer "In4.Cu")
		(net "FM_BOARD_SKU_ID4")
	)
	(segment
		(start 396.998698 -33.587182)
		(end 397.497554 -33.088326)
		(width 0.089408)
		(layer "In4.Cu")
		(net "FM_BOARD_SKU_ID4")
	)
	(segment
		(start 374.7008 -36.2204)
		(end 375.924572 -36.2204)
		(width 0.089408)
		(layer "In4.Cu")
		(net "FM_BOARD_SKU_ID4")
	)
	(segment
		(start 419.915594 -31.890208)
		(end 420.137336 -32.11195)
		(width 0.089408)
		(layer "In4.Cu")
		(net "FM_BOARD_SKU_ID4")
	)
	(segment
		(start 396.998698 -34.4551)
		(end 396.998698 -33.587182)
		(width 0.089408)
		(layer "In4.Cu")
		(net "FM_BOARD_SKU_ID4")
	)
	(segment
		(start 407.012394 -33.87725)
		(end 407.980388 -32.909256)
		(width 0.089408)
		(layer "In4.Cu")
		(net "FM_BOARD_SKU_ID4")
	)
	(segment
		(start 412.926276 -33.10001)
		(end 413.077406 -32.94888)
		(width 0.089408)
		(layer "In4.Cu")
		(net "FM_BOARD_SKU_ID4")
	)
	(segment
		(start 375.924572 -36.2204)
		(end 378.918978 -33.225994)
		(width 0.089408)
		(layer "In4.Cu")
		(net "FM_BOARD_SKU_ID4")
	)
	(segment
		(start 393.08913 -97.68713)
		(end 393.7254 -98.3234)
		(width 0.089408)
		(layer "In11.Cu")
		(net "FM_BOARD_SKU_ID4")
	)
	(segment
		(start 391.1854 -93.8784)
		(end 392.2776 -94.9706)
		(width 0.089408)
		(layer "In11.Cu")
		(net "FM_BOARD_SKU_ID4")
	)
	(segment
		(start 391.191242 -70.53199)
		(end 391.191242 -79.724758)
		(width 0.089408)
		(layer "In11.Cu")
		(net "FM_BOARD_SKU_ID4")
	)
	(segment
		(start 387.826758 -55.23484)
		(end 387.826758 -57.956958)
		(width 0.089408)
		(layer "In11.Cu")
		(net "FM_BOARD_SKU_ID4")
	)
	(segment
		(start 389.817864 -62.294516)
		(end 389.817864 -69.158612)
		(width 0.089408)
		(layer "In11.Cu")
		(net "FM_BOARD_SKU_ID4")
	)
	(segment
		(start 374.7008 -37.33419)
		(end 375.497598 -38.130988)
		(width 0.089408)
		(layer "In11.Cu")
		(net "FM_BOARD_SKU_ID4")
	)
	(segment
		(start 393.7254 -98.7044)
		(end 394.1572 -99.1362)
		(width 0.089408)
		(layer "In11.Cu")
		(net "FM_BOARD_SKU_ID4")
	)
	(segment
		(start 388.66191 -58.79211)
		(end 388.66191 -61.138562)
		(width 0.089408)
		(layer "In11.Cu")
		(net "FM_BOARD_SKU_ID4")
	)
	(segment
		(start 381.22352 -48.980852)
		(end 382.599692 -50.357024)
		(width 0.089408)
		(layer "In11.Cu")
		(net "FM_BOARD_SKU_ID4")
	)
	(segment
		(start 375.497598 -38.130988)
		(end 375.497598 -42.951908)
		(width 0.089408)
		(layer "In11.Cu")
		(net "FM_BOARD_SKU_ID4")
	)
	(segment
		(start 374.7008 -36.2204)
		(end 374.7008 -37.33419)
		(width 0.089408)
		(layer "In11.Cu")
		(net "FM_BOARD_SKU_ID4")
	)
	(segment
		(start 391.1854 -87.1728)
		(end 391.1854 -93.8784)
		(width 0.089408)
		(layer "In11.Cu")
		(net "FM_BOARD_SKU_ID4")
	)
	(segment
		(start 390.4234 -86.4108)
		(end 391.1854 -87.1728)
		(width 0.089408)
		(layer "In11.Cu")
		(net "FM_BOARD_SKU_ID4")
	)
	(segment
		(start 394.1572 -100.162106)
		(end 394.17625 -100.181156)
		(width 0.089408)
		(layer "In11.Cu")
		(net "FM_BOARD_SKU_ID4")
	)
	(segment
		(start 375.904252 -46.680628)
		(end 378.204476 -48.980852)
		(width 0.089408)
		(layer "In11.Cu")
		(net "FM_BOARD_SKU_ID4")
	)
	(segment
		(start 393.08913 -97.33153)
		(end 393.08913 -97.68713)
		(width 0.089408)
		(layer "In11.Cu")
		(net "FM_BOARD_SKU_ID4")
	)
	(segment
		(start 390.4234 -84.80044)
		(end 390.4234 -86.4108)
		(width 0.089408)
		(layer "In11.Cu")
		(net "FM_BOARD_SKU_ID4")
	)
	(segment
		(start 392.78687 -96.774762)
		(end 392.78687 -97.02927)
		(width 0.089408)
		(layer "In11.Cu")
		(net "FM_BOARD_SKU_ID4")
	)
	(segment
		(start 392.541252 -82.682588)
		(end 390.4234 -84.80044)
		(width 0.089408)
		(layer "In11.Cu")
		(net "FM_BOARD_SKU_ID4")
	)
	(segment
		(start 385.7752 -53.183282)
		(end 387.826758 -55.23484)
		(width 0.089408)
		(layer "In11.Cu")
		(net "FM_BOARD_SKU_ID4")
	)
	(segment
		(start 375.904252 -43.358562)
		(end 375.904252 -46.680628)
		(width 0.089408)
		(layer "In11.Cu")
		(net "FM_BOARD_SKU_ID4")
	)
	(segment
		(start 385.7752 -51.400964)
		(end 385.7752 -53.183282)
		(width 0.089408)
		(layer "In11.Cu")
		(net "FM_BOARD_SKU_ID4")
	)
	(segment
		(start 392.2776 -94.9706)
		(end 392.2776 -96.265492)
		(width 0.089408)
		(layer "In11.Cu")
		(net "FM_BOARD_SKU_ID4")
	)
	(segment
		(start 384.73126 -50.357024)
		(end 385.7752 -51.400964)
		(width 0.089408)
		(layer "In11.Cu")
		(net "FM_BOARD_SKU_ID4")
	)
	(segment
		(start 388.66191 -61.138562)
		(end 389.817864 -62.294516)
		(width 0.089408)
		(layer "In11.Cu")
		(net "FM_BOARD_SKU_ID4")
	)
	(segment
		(start 382.599692 -50.357024)
		(end 384.73126 -50.357024)
		(width 0.089408)
		(layer "In11.Cu")
		(net "FM_BOARD_SKU_ID4")
	)
	(segment
		(start 393.7254 -98.3234)
		(end 393.7254 -98.7044)
		(width 0.089408)
		(layer "In11.Cu")
		(net "FM_BOARD_SKU_ID4")
	)
	(segment
		(start 392.541252 -81.074768)
		(end 392.541252 -82.682588)
		(width 0.089408)
		(layer "In11.Cu")
		(net "FM_BOARD_SKU_ID4")
	)
	(segment
		(start 389.817864 -69.158612)
		(end 391.191242 -70.53199)
		(width 0.089408)
		(layer "In11.Cu")
		(net "FM_BOARD_SKU_ID4")
	)
	(segment
		(start 391.191242 -79.724758)
		(end 392.541252 -81.074768)
		(width 0.089408)
		(layer "In11.Cu")
		(net "FM_BOARD_SKU_ID4")
	)
	(segment
		(start 394.1572 -99.1362)
		(end 394.1572 -100.162106)
		(width 0.089408)
		(layer "In11.Cu")
		(net "FM_BOARD_SKU_ID4")
	)
	(segment
		(start 375.497598 -42.951908)
		(end 375.904252 -43.358562)
		(width 0.089408)
		(layer "In11.Cu")
		(net "FM_BOARD_SKU_ID4")
	)
	(segment
		(start 392.78687 -97.02927)
		(end 393.08913 -97.33153)
		(width 0.089408)
		(layer "In11.Cu")
		(net "FM_BOARD_SKU_ID4")
	)
	(segment
		(start 378.204476 -48.980852)
		(end 381.22352 -48.980852)
		(width 0.089408)
		(layer "In11.Cu")
		(net "FM_BOARD_SKU_ID4")
	)
	(segment
		(start 387.826758 -57.956958)
		(end 388.66191 -58.79211)
		(width 0.089408)
		(layer "In11.Cu")
		(net "FM_BOARD_SKU_ID4")
	)
	(segment
		(start 392.2776 -96.265492)
		(end 392.78687 -96.774762)
		(width 0.089408)
		(layer "In11.Cu")
		(net "FM_BOARD_SKU_ID4")
	)
	(segment
		(start 392.19505 -101.2698)
		(end 392.43 -101.16058)
		(width 0.10795)
		(layer "F.Cu")
		(net "FM_BOARD_SKU_ID1")
	)
	(segment
		(start 392.43 -101.16058)
		(end 392.69035 -101.039676)
		(width 0.10795)
		(layer "F.Cu")
		(net "FM_BOARD_SKU_ID1")
	)
	(segment
		(start 421.49014 -29.734764)
		(end 421.89019 -29.334714)
		(width 0.10795)
		(layer "F.Cu")
		(net "FM_BOARD_SKU_ID1")
	)
	(via
		(at 426.503338 -19.83359)
		(size 0.6604)
		(drill 0.3302)
		(layers "F.Cu" "B.Cu")
		(net "FM_BOARD_SKU_ID1")
	)
	(via
		(at 392.69035 -101.039676)
		(size 0.508)
		(drill 0.254)
		(layers "F.Cu" "B.Cu")
		(net "FM_BOARD_SKU_ID1")
	)
	(via
		(at 459.107286 -32.639)
		(size 0.508)
		(drill 0.254)
		(layers "F.Cu" "B.Cu")
		(net "FM_BOARD_SKU_ID1")
	)
	(via
		(at 421.89019 -29.334714)
		(size 0.4572)
		(drill 0.2032)
		(layers "F.Cu" "B.Cu")
		(net "FM_BOARD_SKU_ID1")
	)
	(via
		(at 426.212 -20.7264)
		(size 0.508)
		(drill 0.254)
		(layers "F.Cu" "B.Cu")
		(net "FM_BOARD_SKU_ID1")
	)
	(segment
		(start 426.212 -20.124928)
		(end 426.503338 -19.83359)
		(width 0.10795)
		(layer "B.Cu")
		(net "FM_BOARD_SKU_ID1")
	)
	(segment
		(start 426.893228 -19.4437)
		(end 428.225966 -19.4437)
		(width 0.10795)
		(layer "B.Cu")
		(net "FM_BOARD_SKU_ID1")
	)
	(segment
		(start 426.503338 -19.83359)
		(end 426.893228 -19.4437)
		(width 0.10795)
		(layer "B.Cu")
		(net "FM_BOARD_SKU_ID1")
	)
	(segment
		(start 428.8409 -18.828766)
		(end 428.8409 -18.034)
		(width 0.10795)
		(layer "B.Cu")
		(net "FM_BOARD_SKU_ID1")
	)
	(segment
		(start 428.8409 -18.034)
		(end 428.8409 -17.272)
		(width 0.10795)
		(layer "B.Cu")
		(net "FM_BOARD_SKU_ID1")
	)
	(segment
		(start 428.225966 -19.4437)
		(end 428.8409 -18.828766)
		(width 0.10795)
		(layer "B.Cu")
		(net "FM_BOARD_SKU_ID1")
	)
	(segment
		(start 426.212 -20.7264)
		(end 426.212 -20.124928)
		(width 0.10795)
		(layer "B.Cu")
		(net "FM_BOARD_SKU_ID1")
	)
	(segment
		(start 440.620912 -24.072088)
		(end 435.8767 -24.072088)
		(width 0.089408)
		(layer "In2.Cu")
		(net "FM_BOARD_SKU_ID1")
	)
	(segment
		(start 454.372218 -28.384754)
		(end 453.219058 -27.231594)
		(width 0.089408)
		(layer "In2.Cu")
		(net "FM_BOARD_SKU_ID1")
	)
	(segment
		(start 459.107286 -32.639)
		(end 458.80528 -32.639)
		(width 0.089408)
		(layer "In2.Cu")
		(net "FM_BOARD_SKU_ID1")
	)
	(segment
		(start 423.878502 -27.790902)
		(end 423.878502 -28.745942)
		(width 0.089408)
		(layer "In2.Cu")
		(net "FM_BOARD_SKU_ID1")
	)
	(segment
		(start 447.92646 -27.231594)
		(end 444.012066 -23.3172)
		(width 0.089408)
		(layer "In2.Cu")
		(net "FM_BOARD_SKU_ID1")
	)
	(segment
		(start 422.045638 -29.179266)
		(end 421.89019 -29.334714)
		(width 0.089408)
		(layer "In2.Cu")
		(net "FM_BOARD_SKU_ID1")
	)
	(segment
		(start 423.66438 -28.960064)
		(end 422.534842 -28.960064)
		(width 0.089408)
		(layer "In2.Cu")
		(net "FM_BOARD_SKU_ID1")
	)
	(segment
		(start 455.195178 -28.384754)
		(end 454.372218 -28.384754)
		(width 0.089408)
		(layer "In2.Cu")
		(net "FM_BOARD_SKU_ID1")
	)
	(segment
		(start 423.878502 -28.745942)
		(end 423.66438 -28.960064)
		(width 0.089408)
		(layer "In2.Cu")
		(net "FM_BOARD_SKU_ID1")
	)
	(segment
		(start 441.3758 -23.3172)
		(end 440.620912 -24.072088)
		(width 0.089408)
		(layer "In2.Cu")
		(net "FM_BOARD_SKU_ID1")
	)
	(segment
		(start 422.31564 -29.179266)
		(end 422.045638 -29.179266)
		(width 0.089408)
		(layer "In2.Cu")
		(net "FM_BOARD_SKU_ID1")
	)
	(segment
		(start 424.865546 -26.803858)
		(end 423.878502 -27.790902)
		(width 0.089408)
		(layer "In2.Cu")
		(net "FM_BOARD_SKU_ID1")
	)
	(segment
		(start 426.66793 -26.803858)
		(end 424.865546 -26.803858)
		(width 0.089408)
		(layer "In2.Cu")
		(net "FM_BOARD_SKU_ID1")
	)
	(segment
		(start 457.97978 -31.169356)
		(end 455.195178 -28.384754)
		(width 0.089408)
		(layer "In2.Cu")
		(net "FM_BOARD_SKU_ID1")
	)
	(segment
		(start 434.932582 -25.016206)
		(end 431.91811 -25.016206)
		(width 0.089408)
		(layer "In2.Cu")
		(net "FM_BOARD_SKU_ID1")
	)
	(segment
		(start 435.8767 -24.072088)
		(end 434.932582 -25.016206)
		(width 0.089408)
		(layer "In2.Cu")
		(net "FM_BOARD_SKU_ID1")
	)
	(segment
		(start 453.219058 -27.231594)
		(end 447.92646 -27.231594)
		(width 0.089408)
		(layer "In2.Cu")
		(net "FM_BOARD_SKU_ID1")
	)
	(segment
		(start 422.534842 -28.960064)
		(end 422.31564 -29.179266)
		(width 0.089408)
		(layer "In2.Cu")
		(net "FM_BOARD_SKU_ID1")
	)
	(segment
		(start 458.80528 -32.639)
		(end 457.97978 -31.8135)
		(width 0.089408)
		(layer "In2.Cu")
		(net "FM_BOARD_SKU_ID1")
	)
	(segment
		(start 444.012066 -23.3172)
		(end 441.3758 -23.3172)
		(width 0.089408)
		(layer "In2.Cu")
		(net "FM_BOARD_SKU_ID1")
	)
	(segment
		(start 431.91811 -25.016206)
		(end 431.368454 -25.565862)
		(width 0.089408)
		(layer "In2.Cu")
		(net "FM_BOARD_SKU_ID1")
	)
	(segment
		(start 431.368454 -25.565862)
		(end 427.905926 -25.565862)
		(width 0.089408)
		(layer "In2.Cu")
		(net "FM_BOARD_SKU_ID1")
	)
	(segment
		(start 457.97978 -31.8135)
		(end 457.97978 -31.169356)
		(width 0.089408)
		(layer "In2.Cu")
		(net "FM_BOARD_SKU_ID1")
	)
	(segment
		(start 427.905926 -25.565862)
		(end 426.66793 -26.803858)
		(width 0.089408)
		(layer "In2.Cu")
		(net "FM_BOARD_SKU_ID1")
	)
	(segment
		(start 410.165296 -56.228234)
		(end 410.165296 -60.650374)
		(width 0.089408)
		(layer "In9.Cu")
		(net "FM_BOARD_SKU_ID1")
	)
	(segment
		(start 455.64552 -39.653464)
		(end 454.298558 -41.000426)
		(width 0.089408)
		(layer "In9.Cu")
		(net "FM_BOARD_SKU_ID1")
	)
	(segment
		(start 422.896792 -48.592232)
		(end 421.488362 -48.592232)
		(width 0.089408)
		(layer "In9.Cu")
		(net "FM_BOARD_SKU_ID1")
	)
	(segment
		(start 421.488108 -48.591978)
		(end 421.33012 -48.591978)
		(width 0.089408)
		(layer "In9.Cu")
		(net "FM_BOARD_SKU_ID1")
	)
	(segment
		(start 401.699476 -80.172052)
		(end 401.194524 -80.677004)
		(width 0.089408)
		(layer "In9.Cu")
		(net "FM_BOARD_SKU_ID1")
	)
	(segment
		(start 395.735302 -90.83802)
		(end 395.46022 -90.83802)
		(width 0.089408)
		(layer "In9.Cu")
		(net "FM_BOARD_SKU_ID1")
	)
	(segment
		(start 455.64552 -35.850068)
		(end 455.64552 -39.653464)
		(width 0.089408)
		(layer "In9.Cu")
		(net "FM_BOARD_SKU_ID1")
	)
	(segment
		(start 401.204176 -81.176876)
		(end 401.204176 -82.853784)
		(width 0.089408)
		(layer "In9.Cu")
		(net "FM_BOARD_SKU_ID1")
	)
	(segment
		(start 407.65222 -70.40499)
		(end 403.710648 -74.346562)
		(width 0.089408)
		(layer "In9.Cu")
		(net "FM_BOARD_SKU_ID1")
	)
	(segment
		(start 452.386192 -42.055288)
		(end 452.386192 -42.133774)
		(width 0.089408)
		(layer "In9.Cu")
		(net "FM_BOARD_SKU_ID1")
	)
	(segment
		(start 422.31564 -27.168094)
		(end 422.31564 -28.909264)
		(width 0.089408)
		(layer "In9.Cu")
		(net "FM_BOARD_SKU_ID1")
	)
	(segment
		(start 424.87596 -23.251922)
		(end 423.468038 -24.659844)
		(width 0.089408)
		(layer "In9.Cu")
		(net "FM_BOARD_SKU_ID1")
	)
	(segment
		(start 457.427584 -34.672016)
		(end 456.823572 -34.672016)
		(width 0.089408)
		(layer "In9.Cu")
		(net "FM_BOARD_SKU_ID1")
	)
	(segment
		(start 403.710648 -74.346562)
		(end 403.710648 -78.718918)
		(width 0.089408)
		(layer "In9.Cu")
		(net "FM_BOARD_SKU_ID1")
	)
	(segment
		(start 453.282558 -41.000426)
		(end 452.385938 -41.897046)
		(width 0.089408)
		(layer "In9.Cu")
		(net "FM_BOARD_SKU_ID1")
	)
	(segment
		(start 452.386192 -42.133774)
		(end 451.755764 -42.764202)
		(width 0.089408)
		(layer "In9.Cu")
		(net "FM_BOARD_SKU_ID1")
	)
	(segment
		(start 401.194524 -81.167224)
		(end 401.204176 -81.176876)
		(width 0.089408)
		(layer "In9.Cu")
		(net "FM_BOARD_SKU_ID1")
	)
	(segment
		(start 421.33012 -48.591978)
		(end 418.262054 -51.660044)
		(width 0.089408)
		(layer "In9.Cu")
		(net "FM_BOARD_SKU_ID1")
	)
	(segment
		(start 456.823572 -34.672016)
		(end 455.64552 -35.850068)
		(width 0.089408)
		(layer "In9.Cu")
		(net "FM_BOARD_SKU_ID1")
	)
	(segment
		(start 392.29157 -98.94443)
		(end 392.29157 -99.55784)
		(width 0.089408)
		(layer "In9.Cu")
		(net "FM_BOARD_SKU_ID1")
	)
	(segment
		(start 392.29157 -99.55784)
		(end 392.59383 -99.8601)
		(width 0.089408)
		(layer "In9.Cu")
		(net "FM_BOARD_SKU_ID1")
	)
	(segment
		(start 407.65222 -70.137782)
		(end 407.65222 -70.40499)
		(width 0.089408)
		(layer "In9.Cu")
		(net "FM_BOARD_SKU_ID1")
	)
	(segment
		(start 421.488362 -48.592232)
		(end 421.488108 -48.591978)
		(width 0.089408)
		(layer "In9.Cu")
		(net "FM_BOARD_SKU_ID1")
	)
	(segment
		(start 432.143916 -45.192696)
		(end 428.349664 -45.192696)
		(width 0.089408)
		(layer "In9.Cu")
		(net "FM_BOARD_SKU_ID1")
	)
	(segment
		(start 391.34542 -96.04502)
		(end 391.79627 -96.49587)
		(width 0.089408)
		(layer "In9.Cu")
		(net "FM_BOARD_SKU_ID1")
	)
	(segment
		(start 422.31564 -28.909264)
		(end 421.89019 -29.334714)
		(width 0.089408)
		(layer "In9.Cu")
		(net "FM_BOARD_SKU_ID1")
	)
	(segment
		(start 435.765194 -43.800014)
		(end 433.536598 -43.800014)
		(width 0.089408)
		(layer "In9.Cu")
		(net "FM_BOARD_SKU_ID1")
	)
	(segment
		(start 391.79627 -97.13087)
		(end 392.59383 -97.92843)
		(width 0.089408)
		(layer "In9.Cu")
		(net "FM_BOARD_SKU_ID1")
	)
	(segment
		(start 401.194524 -80.677004)
		(end 401.194524 -81.167224)
		(width 0.089408)
		(layer "In9.Cu")
		(net "FM_BOARD_SKU_ID1")
	)
	(segment
		(start 426.212 -20.7264)
		(end 426.175424 -20.7264)
		(width 0.089408)
		(layer "In9.Cu")
		(net "FM_BOARD_SKU_ID1")
	)
	(segment
		(start 410.370274 -60.855352)
		(end 410.370274 -67.419728)
		(width 0.089408)
		(layer "In9.Cu")
		(net "FM_BOARD_SKU_ID1")
	)
	(segment
		(start 427.42358 -46.11878)
		(end 426.658532 -46.11878)
		(width 0.089408)
		(layer "In9.Cu")
		(net "FM_BOARD_SKU_ID1")
	)
	(segment
		(start 436.801006 -42.764202)
		(end 435.765194 -43.800014)
		(width 0.089408)
		(layer "In9.Cu")
		(net "FM_BOARD_SKU_ID1")
	)
	(segment
		(start 401.204176 -82.853784)
		(end 400.194018 -83.863942)
		(width 0.089408)
		(layer "In9.Cu")
		(net "FM_BOARD_SKU_ID1")
	)
	(segment
		(start 458.8764 -32.869886)
		(end 458.8764 -33.2232)
		(width 0.089408)
		(layer "In9.Cu")
		(net "FM_BOARD_SKU_ID1")
	)
	(segment
		(start 395.46022 -90.83802)
		(end 394.765022 -91.533218)
		(width 0.089408)
		(layer "In9.Cu")
		(net "FM_BOARD_SKU_ID1")
	)
	(segment
		(start 400.194018 -83.863942)
		(end 400.194018 -86.379304)
		(width 0.089408)
		(layer "In9.Cu")
		(net "FM_BOARD_SKU_ID1")
	)
	(segment
		(start 403.710648 -78.718918)
		(end 402.257514 -80.172052)
		(width 0.089408)
		(layer "In9.Cu")
		(net "FM_BOARD_SKU_ID1")
	)
	(segment
		(start 459.107286 -32.639)
		(end 458.8764 -32.869886)
		(width 0.089408)
		(layer "In9.Cu")
		(net "FM_BOARD_SKU_ID1")
	)
	(segment
		(start 425.759372 -47.01794)
		(end 424.471084 -47.01794)
		(width 0.089408)
		(layer "In9.Cu")
		(net "FM_BOARD_SKU_ID1")
	)
	(segment
		(start 433.536598 -43.800014)
		(end 432.143916 -45.192696)
		(width 0.089408)
		(layer "In9.Cu")
		(net "FM_BOARD_SKU_ID1")
	)
	(segment
		(start 424.87596 -22.025864)
		(end 424.87596 -23.251922)
		(width 0.089408)
		(layer "In9.Cu")
		(net "FM_BOARD_SKU_ID1")
	)
	(segment
		(start 410.370274 -67.419728)
		(end 407.65222 -70.137782)
		(width 0.089408)
		(layer "In9.Cu")
		(net "FM_BOARD_SKU_ID1")
	)
	(segment
		(start 394.765022 -91.533218)
		(end 394.765022 -92.999306)
		(width 0.089408)
		(layer "In9.Cu")
		(net "FM_BOARD_SKU_ID1")
	)
	(segment
		(start 392.59383 -98.64217)
		(end 392.29157 -98.94443)
		(width 0.089408)
		(layer "In9.Cu")
		(net "FM_BOARD_SKU_ID1")
	)
	(segment
		(start 452.385938 -42.055034)
		(end 452.386192 -42.055288)
		(width 0.089408)
		(layer "In9.Cu")
		(net "FM_BOARD_SKU_ID1")
	)
	(segment
		(start 458.8764 -33.2232)
		(end 457.427584 -34.672016)
		(width 0.089408)
		(layer "In9.Cu")
		(net "FM_BOARD_SKU_ID1")
	)
	(segment
		(start 392.59383 -99.8601)
		(end 392.59383 -100.943156)
		(width 0.089408)
		(layer "In9.Cu")
		(net "FM_BOARD_SKU_ID1")
	)
	(segment
		(start 423.468038 -26.015696)
		(end 422.31564 -27.168094)
		(width 0.089408)
		(layer "In9.Cu")
		(net "FM_BOARD_SKU_ID1")
	)
	(segment
		(start 452.385938 -41.897046)
		(end 452.385938 -42.055034)
		(width 0.089408)
		(layer "In9.Cu")
		(net "FM_BOARD_SKU_ID1")
	)
	(segment
		(start 418.262054 -51.660044)
		(end 414.733486 -51.660044)
		(width 0.089408)
		(layer "In9.Cu")
		(net "FM_BOARD_SKU_ID1")
	)
	(segment
		(start 402.257514 -80.172052)
		(end 401.699476 -80.172052)
		(width 0.089408)
		(layer "In9.Cu")
		(net "FM_BOARD_SKU_ID1")
	)
	(segment
		(start 394.094208 -93.67012)
		(end 392.875516 -93.67012)
		(width 0.089408)
		(layer "In9.Cu")
		(net "FM_BOARD_SKU_ID1")
	)
	(segment
		(start 454.298558 -41.000426)
		(end 453.282558 -41.000426)
		(width 0.089408)
		(layer "In9.Cu")
		(net "FM_BOARD_SKU_ID1")
	)
	(segment
		(start 424.471084 -47.01794)
		(end 422.896792 -48.592232)
		(width 0.089408)
		(layer "In9.Cu")
		(net "FM_BOARD_SKU_ID1")
	)
	(segment
		(start 426.175424 -20.7264)
		(end 424.87596 -22.025864)
		(width 0.089408)
		(layer "In9.Cu")
		(net "FM_BOARD_SKU_ID1")
	)
	(segment
		(start 451.755764 -42.764202)
		(end 436.801006 -42.764202)
		(width 0.089408)
		(layer "In9.Cu")
		(net "FM_BOARD_SKU_ID1")
	)
	(segment
		(start 400.194018 -86.379304)
		(end 395.735302 -90.83802)
		(width 0.089408)
		(layer "In9.Cu")
		(net "FM_BOARD_SKU_ID1")
	)
	(segment
		(start 392.59383 -97.92843)
		(end 392.59383 -98.64217)
		(width 0.089408)
		(layer "In9.Cu")
		(net "FM_BOARD_SKU_ID1")
	)
	(segment
		(start 392.875516 -93.67012)
		(end 391.34542 -95.200216)
		(width 0.089408)
		(layer "In9.Cu")
		(net "FM_BOARD_SKU_ID1")
	)
	(segment
		(start 391.79627 -96.49587)
		(end 391.79627 -97.13087)
		(width 0.089408)
		(layer "In9.Cu")
		(net "FM_BOARD_SKU_ID1")
	)
	(segment
		(start 394.765022 -92.999306)
		(end 394.094208 -93.67012)
		(width 0.089408)
		(layer "In9.Cu")
		(net "FM_BOARD_SKU_ID1")
	)
	(segment
		(start 426.658532 -46.11878)
		(end 425.759372 -47.01794)
		(width 0.089408)
		(layer "In9.Cu")
		(net "FM_BOARD_SKU_ID1")
	)
	(segment
		(start 414.733486 -51.660044)
		(end 410.165296 -56.228234)
		(width 0.089408)
		(layer "In9.Cu")
		(net "FM_BOARD_SKU_ID1")
	)
	(segment
		(start 428.349664 -45.192696)
		(end 427.42358 -46.11878)
		(width 0.089408)
		(layer "In9.Cu")
		(net "FM_BOARD_SKU_ID1")
	)
	(segment
		(start 423.468038 -24.659844)
		(end 423.468038 -26.015696)
		(width 0.089408)
		(layer "In9.Cu")
		(net "FM_BOARD_SKU_ID1")
	)
	(segment
		(start 410.165296 -60.650374)
		(end 410.370274 -60.855352)
		(width 0.089408)
		(layer "In9.Cu")
		(net "FM_BOARD_SKU_ID1")
	)
	(segment
		(start 392.59383 -100.943156)
		(end 392.69035 -101.039676)
		(width 0.089408)
		(layer "In9.Cu")
		(net "FM_BOARD_SKU_ID1")
	)
	(segment
		(start 391.34542 -95.200216)
		(end 391.34542 -96.04502)
		(width 0.089408)
		(layer "In9.Cu")
		(net "FM_BOARD_SKU_ID1")
	)
	(segment
		(start 391.20445 -96.11868)
		(end 391.7442 -95.686118)
		(width 0.10795)
		(layer "F.Cu")
		(net "FM_BOARD_SKU_ID2")
	)
	(segment
		(start 423.090086 -29.734764)
		(end 423.490136 -29.334714)
		(width 0.10795)
		(layer "F.Cu")
		(net "FM_BOARD_SKU_ID2")
	)
	(via
		(at 423.490136 -29.334714)
		(size 0.4572)
		(drill 0.2032)
		(layers "F.Cu" "B.Cu")
		(net "FM_BOARD_SKU_ID2")
	)
	(via
		(at 391.7442 -95.686118)
		(size 0.508)
		(drill 0.254)
		(layers "F.Cu" "B.Cu")
		(net "FM_BOARD_SKU_ID2")
	)
	(via
		(at 459.311502 -28.37307)
		(size 0.508)
		(drill 0.254)
		(layers "F.Cu" "B.Cu")
		(net "FM_BOARD_SKU_ID2")
	)
	(via
		(at 431.2412 -24.031448)
		(size 0.508)
		(drill 0.254)
		(layers "F.Cu" "B.Cu")
		(net "FM_BOARD_SKU_ID2")
	)
	(segment
		(start 431.2412 -23.4188)
		(end 432.0032 -23.4188)
		(width 0.10795)
		(layer "B.Cu")
		(net "FM_BOARD_SKU_ID2")
	)
	(segment
		(start 431.2412 -24.031448)
		(end 431.2412 -23.4188)
		(width 0.10795)
		(layer "B.Cu")
		(net "FM_BOARD_SKU_ID2")
	)
	(segment
		(start 448.450462 -24.847296)
		(end 449.254626 -24.847296)
		(width 0.089408)
		(layer "In4.Cu")
		(net "FM_BOARD_SKU_ID2")
	)
	(segment
		(start 449.254626 -24.847296)
		(end 452.93153 -28.5242)
		(width 0.089408)
		(layer "In4.Cu")
		(net "FM_BOARD_SKU_ID2")
	)
	(segment
		(start 447.36766 -23.764494)
		(end 448.450462 -24.847296)
		(width 0.089408)
		(layer "In4.Cu")
		(net "FM_BOARD_SKU_ID2")
	)
	(segment
		(start 459.160372 -28.5242)
		(end 459.311502 -28.37307)
		(width 0.089408)
		(layer "In4.Cu")
		(net "FM_BOARD_SKU_ID2")
	)
	(segment
		(start 431.2412 -24.015954)
		(end 433.182268 -22.074886)
		(width 0.089408)
		(layer "In4.Cu")
		(net "FM_BOARD_SKU_ID2")
	)
	(segment
		(start 434.88356 -21.29028)
		(end 444.83147 -21.29028)
		(width 0.089408)
		(layer "In4.Cu")
		(net "FM_BOARD_SKU_ID2")
	)
	(segment
		(start 445.678306 -22.137116)
		(end 447.099182 -22.137116)
		(width 0.089408)
		(layer "In4.Cu")
		(net "FM_BOARD_SKU_ID2")
	)
	(segment
		(start 452.93153 -28.5242)
		(end 459.160372 -28.5242)
		(width 0.089408)
		(layer "In4.Cu")
		(net "FM_BOARD_SKU_ID2")
	)
	(segment
		(start 444.83147 -21.29028)
		(end 445.678306 -22.137116)
		(width 0.089408)
		(layer "In4.Cu")
		(net "FM_BOARD_SKU_ID2")
	)
	(segment
		(start 447.099182 -22.137116)
		(end 447.36766 -22.405594)
		(width 0.089408)
		(layer "In4.Cu")
		(net "FM_BOARD_SKU_ID2")
	)
	(segment
		(start 431.2412 -24.031448)
		(end 431.2412 -24.015954)
		(width 0.089408)
		(layer "In4.Cu")
		(net "FM_BOARD_SKU_ID2")
	)
	(segment
		(start 447.36766 -22.405594)
		(end 447.36766 -23.764494)
		(width 0.089408)
		(layer "In4.Cu")
		(net "FM_BOARD_SKU_ID2")
	)
	(segment
		(start 433.182268 -22.074886)
		(end 434.098954 -22.074886)
		(width 0.089408)
		(layer "In4.Cu")
		(net "FM_BOARD_SKU_ID2")
	)
	(segment
		(start 434.098954 -22.074886)
		(end 434.88356 -21.29028)
		(width 0.089408)
		(layer "In4.Cu")
		(net "FM_BOARD_SKU_ID2")
	)
	(segment
		(start 451.835012 -42.95521)
		(end 452.5772 -42.213022)
		(width 0.089408)
		(layer "In9.Cu")
		(net "FM_BOARD_SKU_ID2")
	)
	(segment
		(start 402.24837 -80.52181)
		(end 402.545804 -80.819244)
		(width 0.089408)
		(layer "In9.Cu")
		(net "FM_BOARD_SKU_ID2")
	)
	(segment
		(start 401.395184 -81.097628)
		(end 401.385532 -81.087976)
		(width 0.089408)
		(layer "In9.Cu")
		(net "FM_BOARD_SKU_ID2")
	)
	(segment
		(start 458.873606 -31.795466)
		(end 458.873606 -31.792164)
		(width 0.089408)
		(layer "In9.Cu")
		(net "FM_BOARD_SKU_ID2")
	)
	(segment
		(start 391.7442 -95.686118)
		(end 392.348466 -95.686118)
		(width 0.089408)
		(layer "In9.Cu")
		(net "FM_BOARD_SKU_ID2")
	)
	(segment
		(start 401.385532 -80.756252)
		(end 401.619974 -80.52181)
		(width 0.089408)
		(layer "In9.Cu")
		(net "FM_BOARD_SKU_ID2")
	)
	(segment
		(start 458.373226 -31.291784)
		(end 458.373226 -29.7942)
		(width 0.089408)
		(layer "In9.Cu")
		(net "FM_BOARD_SKU_ID2")
	)
	(segment
		(start 395.776958 -91.06662)
		(end 400.38528 -86.458298)
		(width 0.089408)
		(layer "In9.Cu")
		(net "FM_BOARD_SKU_ID2")
	)
	(segment
		(start 435.844442 -43.991022)
		(end 436.880254 -42.95521)
		(width 0.089408)
		(layer "In9.Cu")
		(net "FM_BOARD_SKU_ID2")
	)
	(segment
		(start 436.880254 -42.95521)
		(end 451.835012 -42.95521)
		(width 0.089408)
		(layer "In9.Cu")
		(net "FM_BOARD_SKU_ID2")
	)
	(segment
		(start 433.615846 -43.991022)
		(end 435.844442 -43.991022)
		(width 0.089408)
		(layer "In9.Cu")
		(net "FM_BOARD_SKU_ID2")
	)
	(segment
		(start 410.356304 -56.307482)
		(end 414.812734 -51.851052)
		(width 0.089408)
		(layer "In9.Cu")
		(net "FM_BOARD_SKU_ID2")
	)
	(segment
		(start 455.836528 -39.732712)
		(end 455.836528 -35.929316)
		(width 0.089408)
		(layer "In9.Cu")
		(net "FM_BOARD_SKU_ID2")
	)
	(segment
		(start 410.561282 -67.498976)
		(end 410.561282 -60.776104)
		(width 0.089408)
		(layer "In9.Cu")
		(net "FM_BOARD_SKU_ID2")
	)
	(segment
		(start 458.851 -28.833572)
		(end 459.311502 -28.37307)
		(width 0.089408)
		(layer "In9.Cu")
		(net "FM_BOARD_SKU_ID2")
	)
	(segment
		(start 428.749968 -46.141132)
		(end 428.749968 -45.815504)
		(width 0.089408)
		(layer "In9.Cu")
		(net "FM_BOARD_SKU_ID2")
	)
	(segment
		(start 452.5772 -42.213022)
		(end 452.5772 -41.97604)
		(width 0.089408)
		(layer "In9.Cu")
		(net "FM_BOARD_SKU_ID2")
	)
	(segment
		(start 400.38528 -86.458298)
		(end 400.38528 -83.99018)
		(width 0.089408)
		(layer "In9.Cu")
		(net "FM_BOARD_SKU_ID2")
	)
	(segment
		(start 459.50759 -32.42945)
		(end 458.873606 -31.795466)
		(width 0.089408)
		(layer "In9.Cu")
		(net "FM_BOARD_SKU_ID2")
	)
	(segment
		(start 428.749968 -45.815504)
		(end 429.05934 -45.506132)
		(width 0.089408)
		(layer "In9.Cu")
		(net "FM_BOARD_SKU_ID2")
	)
	(segment
		(start 395.57452 -91.06662)
		(end 395.776958 -91.06662)
		(width 0.089408)
		(layer "In9.Cu")
		(net "FM_BOARD_SKU_ID2")
	)
	(segment
		(start 453.361806 -41.191434)
		(end 454.377806 -41.191434)
		(width 0.089408)
		(layer "In9.Cu")
		(net "FM_BOARD_SKU_ID2")
	)
	(segment
		(start 402.877528 -80.819244)
		(end 403.2123 -80.484472)
		(width 0.089408)
		(layer "In9.Cu")
		(net "FM_BOARD_SKU_ID2")
	)
	(segment
		(start 429.05934 -45.506132)
		(end 429.355504 -45.506132)
		(width 0.089408)
		(layer "In9.Cu")
		(net "FM_BOARD_SKU_ID2")
	)
	(segment
		(start 429.355504 -45.506132)
		(end 429.355758 -45.506386)
		(width 0.089408)
		(layer "In9.Cu")
		(net "FM_BOARD_SKU_ID2")
	)
	(segment
		(start 418.341302 -51.851052)
		(end 421.409114 -48.78324)
		(width 0.089408)
		(layer "In9.Cu")
		(net "FM_BOARD_SKU_ID2")
	)
	(segment
		(start 410.356304 -60.571126)
		(end 410.356304 -56.307482)
		(width 0.089408)
		(layer "In9.Cu")
		(net "FM_BOARD_SKU_ID2")
	)
	(segment
		(start 403.901656 -74.42581)
		(end 407.843228 -70.484238)
		(width 0.089408)
		(layer "In9.Cu")
		(net "FM_BOARD_SKU_ID2")
	)
	(segment
		(start 457.775564 -34.863024)
		(end 459.50759 -33.130998)
		(width 0.089408)
		(layer "In9.Cu")
		(net "FM_BOARD_SKU_ID2")
	)
	(segment
		(start 424.149012 -47.71898)
		(end 427.17212 -47.71898)
		(width 0.089408)
		(layer "In9.Cu")
		(net "FM_BOARD_SKU_ID2")
	)
	(segment
		(start 400.38528 -83.99018)
		(end 401.395184 -82.980276)
		(width 0.089408)
		(layer "In9.Cu")
		(net "FM_BOARD_SKU_ID2")
	)
	(segment
		(start 392.348466 -95.686118)
		(end 395.031722 -93.002862)
		(width 0.089408)
		(layer "In9.Cu")
		(net "FM_BOARD_SKU_ID2")
	)
	(segment
		(start 407.843228 -70.484238)
		(end 407.843228 -70.21703)
		(width 0.089408)
		(layer "In9.Cu")
		(net "FM_BOARD_SKU_ID2")
	)
	(segment
		(start 452.5772 -41.97604)
		(end 453.361806 -41.191434)
		(width 0.089408)
		(layer "In9.Cu")
		(net "FM_BOARD_SKU_ID2")
	)
	(segment
		(start 423.084752 -48.78324)
		(end 424.149012 -47.71898)
		(width 0.089408)
		(layer "In9.Cu")
		(net "FM_BOARD_SKU_ID2")
	)
	(segment
		(start 403.2123 -79.676498)
		(end 403.901656 -78.987142)
		(width 0.089408)
		(layer "In9.Cu")
		(net "FM_BOARD_SKU_ID2")
	)
	(segment
		(start 458.873606 -31.792164)
		(end 458.373226 -31.291784)
		(width 0.089408)
		(layer "In9.Cu")
		(net "FM_BOARD_SKU_ID2")
	)
	(segment
		(start 421.409114 -48.78324)
		(end 423.084752 -48.78324)
		(width 0.089408)
		(layer "In9.Cu")
		(net "FM_BOARD_SKU_ID2")
	)
	(segment
		(start 456.90282 -34.863024)
		(end 457.775564 -34.863024)
		(width 0.089408)
		(layer "In9.Cu")
		(net "FM_BOARD_SKU_ID2")
	)
	(segment
		(start 414.812734 -51.851052)
		(end 418.341302 -51.851052)
		(width 0.089408)
		(layer "In9.Cu")
		(net "FM_BOARD_SKU_ID2")
	)
	(segment
		(start 395.031722 -93.002862)
		(end 395.031722 -91.609418)
		(width 0.089408)
		(layer "In9.Cu")
		(net "FM_BOARD_SKU_ID2")
	)
	(segment
		(start 395.031722 -91.609418)
		(end 395.57452 -91.06662)
		(width 0.089408)
		(layer "In9.Cu")
		(net "FM_BOARD_SKU_ID2")
	)
	(segment
		(start 403.901656 -78.987142)
		(end 403.901656 -74.42581)
		(width 0.089408)
		(layer "In9.Cu")
		(net "FM_BOARD_SKU_ID2")
	)
	(segment
		(start 458.373226 -29.7942)
		(end 458.851 -29.316426)
		(width 0.089408)
		(layer "In9.Cu")
		(net "FM_BOARD_SKU_ID2")
	)
	(segment
		(start 403.2123 -80.484472)
		(end 403.2123 -79.676498)
		(width 0.089408)
		(layer "In9.Cu")
		(net "FM_BOARD_SKU_ID2")
	)
	(segment
		(start 401.385532 -81.087976)
		(end 401.385532 -80.756252)
		(width 0.089408)
		(layer "In9.Cu")
		(net "FM_BOARD_SKU_ID2")
	)
	(segment
		(start 429.355758 -45.506386)
		(end 432.100482 -45.506386)
		(width 0.089408)
		(layer "In9.Cu")
		(net "FM_BOARD_SKU_ID2")
	)
	(segment
		(start 402.545804 -80.819244)
		(end 402.877528 -80.819244)
		(width 0.089408)
		(layer "In9.Cu")
		(net "FM_BOARD_SKU_ID2")
	)
	(segment
		(start 427.17212 -47.71898)
		(end 428.749968 -46.141132)
		(width 0.089408)
		(layer "In9.Cu")
		(net "FM_BOARD_SKU_ID2")
	)
	(segment
		(start 407.843228 -70.21703)
		(end 410.561282 -67.498976)
		(width 0.089408)
		(layer "In9.Cu")
		(net "FM_BOARD_SKU_ID2")
	)
	(segment
		(start 401.395184 -82.980276)
		(end 401.395184 -81.097628)
		(width 0.089408)
		(layer "In9.Cu")
		(net "FM_BOARD_SKU_ID2")
	)
	(segment
		(start 454.377806 -41.191434)
		(end 455.836528 -39.732712)
		(width 0.089408)
		(layer "In9.Cu")
		(net "FM_BOARD_SKU_ID2")
	)
	(segment
		(start 458.851 -29.316426)
		(end 458.851 -28.833572)
		(width 0.089408)
		(layer "In9.Cu")
		(net "FM_BOARD_SKU_ID2")
	)
	(segment
		(start 459.50759 -33.130998)
		(end 459.50759 -32.42945)
		(width 0.089408)
		(layer "In9.Cu")
		(net "FM_BOARD_SKU_ID2")
	)
	(segment
		(start 410.561282 -60.776104)
		(end 410.356304 -60.571126)
		(width 0.089408)
		(layer "In9.Cu")
		(net "FM_BOARD_SKU_ID2")
	)
	(segment
		(start 455.836528 -35.929316)
		(end 456.90282 -34.863024)
		(width 0.089408)
		(layer "In9.Cu")
		(net "FM_BOARD_SKU_ID2")
	)
	(segment
		(start 432.100482 -45.506386)
		(end 433.615846 -43.991022)
		(width 0.089408)
		(layer "In9.Cu")
		(net "FM_BOARD_SKU_ID2")
	)
	(segment
		(start 401.619974 -80.52181)
		(end 402.24837 -80.52181)
		(width 0.089408)
		(layer "In9.Cu")
		(net "FM_BOARD_SKU_ID2")
	)
	(segment
		(start 424.51782 -28.09875)
		(end 427.370494 -28.09875)
		(width 0.089408)
		(layer "In11.Cu")
		(net "FM_BOARD_SKU_ID2")
	)
	(segment
		(start 423.490136 -29.334714)
		(end 423.490136 -29.126434)
		(width 0.089408)
		(layer "In11.Cu")
		(net "FM_BOARD_SKU_ID2")
	)
	(segment
		(start 427.370494 -28.09875)
		(end 431.2412 -24.228044)
		(width 0.089408)
		(layer "In11.Cu")
		(net "FM_BOARD_SKU_ID2")
	)
	(segment
		(start 431.2412 -24.228044)
		(end 431.2412 -24.031448)
		(width 0.089408)
		(layer "In11.Cu")
		(net "FM_BOARD_SKU_ID2")
	)
	(segment
		(start 423.490136 -29.126434)
		(end 424.51782 -28.09875)
		(width 0.089408)
		(layer "In11.Cu")
		(net "FM_BOARD_SKU_ID2")
	)
	(segment
		(start 385.30784 -89.55532)
		(end 385.30784 -88.994234)
		(width 0.10795)
		(layer "F.Cu")
		(net "FM_OCP_MEZZA_PRES")
	)
	(segment
		(start 385.318 -88.797638)
		(end 385.411218 -88.890856)
		(width 0.10795)
		(layer "F.Cu")
		(net "FM_OCP_MEZZA_PRES")
	)
	(segment
		(start 385.30784 -88.994234)
		(end 385.411218 -88.890856)
		(width 0.10795)
		(layer "F.Cu")
		(net "FM_OCP_MEZZA_PRES")
	)
	(segment
		(start 385.318 -88.2015)
		(end 385.318 -88.797638)
		(width 0.10795)
		(layer "F.Cu")
		(net "FM_OCP_MEZZA_PRES")
	)
	(segment
		(start 419.090094 -42.534586)
		(end 419.490144 -42.134536)
		(width 0.089408)
		(layer "F.Cu")
		(net "FM_OCP_MEZZA_PRES")
	)
	(via
		(at 477.0374 -114.3508)
		(size 0.508)
		(drill 0.254)
		(layers "F.Cu" "B.Cu")
		(net "FM_OCP_MEZZA_PRES")
	)
	(via
		(at 419.490144 -42.134536)
		(size 0.4572)
		(drill 0.2032)
		(layers "F.Cu" "B.Cu")
		(net "FM_OCP_MEZZA_PRES")
	)
	(via
		(at 385.411218 -88.890856)
		(size 0.508)
		(drill 0.254)
		(layers "F.Cu" "B.Cu")
		(net "FM_OCP_MEZZA_PRES")
	)
	(via
		(at 421.86606 -100.9142)
		(size 0.508)
		(drill 0.254)
		(layers "F.Cu" "B.Cu")
		(net "FM_OCP_MEZZA_PRES")
	)
	(segment
		(start 477.139 -115.5065)
		(end 477.139 -114.4524)
		(width 0.10795)
		(layer "B.Cu")
		(net "FM_OCP_MEZZA_PRES")
	)
	(segment
		(start 477.139 -114.4524)
		(end 477.0374 -114.3508)
		(width 0.10795)
		(layer "B.Cu")
		(net "FM_OCP_MEZZA_PRES")
	)
	(segment
		(start 418.22116 -42.50944)
		(end 419.11524 -42.50944)
		(width 0.089408)
		(layer "In2.Cu")
		(net "FM_OCP_MEZZA_PRES")
	)
	(segment
		(start 388.702296 -67.092576)
		(end 391.287254 -64.507618)
		(width 0.089408)
		(layer "In2.Cu")
		(net "FM_OCP_MEZZA_PRES")
	)
	(segment
		(start 388.95782 -79.056738)
		(end 388.958074 -79.056484)
		(width 0.089408)
		(layer "In2.Cu")
		(net "FM_OCP_MEZZA_PRES")
	)
	(segment
		(start 388.958074 -77.8002)
		(end 388.624064 -77.46619)
		(width 0.089408)
		(layer "In2.Cu")
		(net "FM_OCP_MEZZA_PRES")
	)
	(segment
		(start 411.371034 -43.480482)
		(end 411.371288 -43.480228)
		(width 0.089408)
		(layer "In2.Cu")
		(net "FM_OCP_MEZZA_PRES")
	)
	(segment
		(start 388.624064 -77.46619)
		(end 388.624064 -76.307442)
		(width 0.089408)
		(layer "In2.Cu")
		(net "FM_OCP_MEZZA_PRES")
	)
	(segment
		(start 388.9375 -83.154266)
		(end 387.907022 -82.123788)
		(width 0.089408)
		(layer "In2.Cu")
		(net "FM_OCP_MEZZA_PRES")
	)
	(segment
		(start 407.004012 -42.978578)
		(end 407.11628 -43.090846)
		(width 0.089408)
		(layer "In2.Cu")
		(net "FM_OCP_MEZZA_PRES")
	)
	(segment
		(start 392.45286 -52.27955)
		(end 391.441432 -51.268122)
		(width 0.089408)
		(layer "In2.Cu")
		(net "FM_OCP_MEZZA_PRES")
	)
	(segment
		(start 411.55747 -43.480228)
		(end 411.557978 -43.480736)
		(width 0.089408)
		(layer "In2.Cu")
		(net "FM_OCP_MEZZA_PRES")
	)
	(segment
		(start 388.9375 -84.596478)
		(end 388.9375 -83.154266)
		(width 0.089408)
		(layer "In2.Cu")
		(net "FM_OCP_MEZZA_PRES")
	)
	(segment
		(start 410.889958 -43.157648)
		(end 410.890212 -43.157648)
		(width 0.089408)
		(layer "In2.Cu")
		(net "FM_OCP_MEZZA_PRES")
	)
	(segment
		(start 386.737606 -86.239096)
		(end 387.29666 -85.680042)
		(width 0.089408)
		(layer "In2.Cu")
		(net "FM_OCP_MEZZA_PRES")
	)
	(segment
		(start 387.29666 -85.680042)
		(end 387.634988 -85.680042)
		(width 0.089408)
		(layer "In2.Cu")
		(net "FM_OCP_MEZZA_PRES")
	)
	(segment
		(start 388.958074 -79.056484)
		(end 388.958074 -78.898496)
		(width 0.089408)
		(layer "In2.Cu")
		(net "FM_OCP_MEZZA_PRES")
	)
	(segment
		(start 411.557978 -43.480736)
		(end 411.715966 -43.480736)
		(width 0.089408)
		(layer "In2.Cu")
		(net "FM_OCP_MEZZA_PRES")
	)
	(segment
		(start 393.309856 -60.748926)
		(end 393.309856 -57.964578)
		(width 0.089408)
		(layer "In2.Cu")
		(net "FM_OCP_MEZZA_PRES")
	)
	(segment
		(start 388.996936 -73.486264)
		(end 389.189214 -73.293986)
		(width 0.089408)
		(layer "In2.Cu")
		(net "FM_OCP_MEZZA_PRES")
	)
	(segment
		(start 385.411218 -88.890856)
		(end 385.411218 -88.163908)
		(width 0.089408)
		(layer "In2.Cu")
		(net "FM_OCP_MEZZA_PRES")
	)
	(segment
		(start 411.371288 -43.480228)
		(end 411.55747 -43.480228)
		(width 0.089408)
		(layer "In2.Cu")
		(net "FM_OCP_MEZZA_PRES")
	)
	(segment
		(start 392.55573 -61.503052)
		(end 393.309856 -60.748926)
		(width 0.089408)
		(layer "In2.Cu")
		(net "FM_OCP_MEZZA_PRES")
	)
	(segment
		(start 388.95782 -77.958442)
		(end 388.958074 -77.958188)
		(width 0.089408)
		(layer "In2.Cu")
		(net "FM_OCP_MEZZA_PRES")
	)
	(segment
		(start 388.958074 -77.958188)
		(end 388.958074 -77.8002)
		(width 0.089408)
		(layer "In2.Cu")
		(net "FM_OCP_MEZZA_PRES")
	)
	(segment
		(start 391.670794 -46.12005)
		(end 396.97025 -46.12005)
		(width 0.089408)
		(layer "In2.Cu")
		(net "FM_OCP_MEZZA_PRES")
	)
	(segment
		(start 387.634988 -85.680042)
		(end 387.635242 -85.680296)
		(width 0.089408)
		(layer "In2.Cu")
		(net "FM_OCP_MEZZA_PRES")
	)
	(segment
		(start 410.823156 -43.090846)
		(end 410.889958 -43.157648)
		(width 0.089408)
		(layer "In2.Cu")
		(net "FM_OCP_MEZZA_PRES")
	)
	(segment
		(start 402.293328 -45.191426)
		(end 404.506176 -42.978578)
		(width 0.089408)
		(layer "In2.Cu")
		(net "FM_OCP_MEZZA_PRES")
	)
	(segment
		(start 388.958074 -78.898496)
		(end 388.95782 -78.898242)
		(width 0.089408)
		(layer "In2.Cu")
		(net "FM_OCP_MEZZA_PRES")
	)
	(segment
		(start 388.95782 -78.898242)
		(end 388.95782 -77.958442)
		(width 0.089408)
		(layer "In2.Cu")
		(net "FM_OCP_MEZZA_PRES")
	)
	(segment
		(start 411.213046 -43.480482)
		(end 411.371034 -43.480482)
		(width 0.089408)
		(layer "In2.Cu")
		(net "FM_OCP_MEZZA_PRES")
	)
	(segment
		(start 388.99719 -75.90409)
		(end 388.99719 -75.746102)
		(width 0.089408)
		(layer "In2.Cu")
		(net "FM_OCP_MEZZA_PRES")
	)
	(segment
		(start 407.11628 -43.090846)
		(end 410.823156 -43.090846)
		(width 0.089408)
		(layer "In2.Cu")
		(net "FM_OCP_MEZZA_PRES")
	)
	(segment
		(start 396.97025 -46.12005)
		(end 397.898874 -45.191426)
		(width 0.089408)
		(layer "In2.Cu")
		(net "FM_OCP_MEZZA_PRES")
	)
	(segment
		(start 391.287254 -63.653162)
		(end 392.55573 -62.384686)
		(width 0.089408)
		(layer "In2.Cu")
		(net "FM_OCP_MEZZA_PRES")
	)
	(segment
		(start 419.11524 -42.50944)
		(end 419.490144 -42.134536)
		(width 0.089408)
		(layer "In2.Cu")
		(net "FM_OCP_MEZZA_PRES")
	)
	(segment
		(start 415.941764 -42.934636)
		(end 417.795964 -42.934636)
		(width 0.089408)
		(layer "In2.Cu")
		(net "FM_OCP_MEZZA_PRES")
	)
	(segment
		(start 388.996936 -75.904344)
		(end 388.99719 -75.90409)
		(width 0.089408)
		(layer "In2.Cu")
		(net "FM_OCP_MEZZA_PRES")
	)
	(segment
		(start 386.737606 -86.83752)
		(end 386.737606 -86.239096)
		(width 0.089408)
		(layer "In2.Cu")
		(net "FM_OCP_MEZZA_PRES")
	)
	(segment
		(start 417.795964 -42.934636)
		(end 418.22116 -42.50944)
		(width 0.089408)
		(layer "In2.Cu")
		(net "FM_OCP_MEZZA_PRES")
	)
	(segment
		(start 411.760416 -43.436286)
		(end 415.440114 -43.436286)
		(width 0.089408)
		(layer "In2.Cu")
		(net "FM_OCP_MEZZA_PRES")
	)
	(segment
		(start 388.99719 -75.746102)
		(end 388.996936 -75.745848)
		(width 0.089408)
		(layer "In2.Cu")
		(net "FM_OCP_MEZZA_PRES")
	)
	(segment
		(start 387.79323 -85.680296)
		(end 387.793484 -85.680042)
		(width 0.089408)
		(layer "In2.Cu")
		(net "FM_OCP_MEZZA_PRES")
	)
	(segment
		(start 391.222992 -46.567852)
		(end 391.670794 -46.12005)
		(width 0.089408)
		(layer "In2.Cu")
		(net "FM_OCP_MEZZA_PRES")
	)
	(segment
		(start 387.635242 -85.680296)
		(end 387.79323 -85.680296)
		(width 0.089408)
		(layer "In2.Cu")
		(net "FM_OCP_MEZZA_PRES")
	)
	(segment
		(start 388.996936 -75.93457)
		(end 388.996936 -75.904344)
		(width 0.089408)
		(layer "In2.Cu")
		(net "FM_OCP_MEZZA_PRES")
	)
	(segment
		(start 385.411218 -88.163908)
		(end 386.737606 -86.83752)
		(width 0.089408)
		(layer "In2.Cu")
		(net "FM_OCP_MEZZA_PRES")
	)
	(segment
		(start 391.222992 -46.92904)
		(end 391.222992 -46.567852)
		(width 0.089408)
		(layer "In2.Cu")
		(net "FM_OCP_MEZZA_PRES")
	)
	(segment
		(start 415.440114 -43.436286)
		(end 415.941764 -42.934636)
		(width 0.089408)
		(layer "In2.Cu")
		(net "FM_OCP_MEZZA_PRES")
	)
	(segment
		(start 404.506176 -42.978578)
		(end 407.004012 -42.978578)
		(width 0.089408)
		(layer "In2.Cu")
		(net "FM_OCP_MEZZA_PRES")
	)
	(segment
		(start 388.996936 -75.745848)
		(end 388.996936 -73.486264)
		(width 0.089408)
		(layer "In2.Cu")
		(net "FM_OCP_MEZZA_PRES")
	)
	(segment
		(start 391.287254 -64.507618)
		(end 391.287254 -63.653162)
		(width 0.089408)
		(layer "In2.Cu")
		(net "FM_OCP_MEZZA_PRES")
	)
	(segment
		(start 387.907022 -82.123788)
		(end 387.907022 -80.682084)
		(width 0.089408)
		(layer "In2.Cu")
		(net "FM_OCP_MEZZA_PRES")
	)
	(segment
		(start 387.907022 -80.682084)
		(end 388.95782 -79.631286)
		(width 0.089408)
		(layer "In2.Cu")
		(net "FM_OCP_MEZZA_PRES")
	)
	(segment
		(start 388.95782 -79.631286)
		(end 388.95782 -79.056738)
		(width 0.089408)
		(layer "In2.Cu")
		(net "FM_OCP_MEZZA_PRES")
	)
	(segment
		(start 392.45286 -57.107582)
		(end 392.45286 -52.27955)
		(width 0.089408)
		(layer "In2.Cu")
		(net "FM_OCP_MEZZA_PRES")
	)
	(segment
		(start 411.715966 -43.480736)
		(end 411.760416 -43.436286)
		(width 0.089408)
		(layer "In2.Cu")
		(net "FM_OCP_MEZZA_PRES")
	)
	(segment
		(start 397.898874 -45.191426)
		(end 402.293328 -45.191426)
		(width 0.089408)
		(layer "In2.Cu")
		(net "FM_OCP_MEZZA_PRES")
	)
	(segment
		(start 392.55573 -62.384686)
		(end 392.55573 -61.503052)
		(width 0.089408)
		(layer "In2.Cu")
		(net "FM_OCP_MEZZA_PRES")
	)
	(segment
		(start 388.624064 -76.307442)
		(end 388.996936 -75.93457)
		(width 0.089408)
		(layer "In2.Cu")
		(net "FM_OCP_MEZZA_PRES")
	)
	(segment
		(start 391.441432 -51.268122)
		(end 391.441432 -47.14748)
		(width 0.089408)
		(layer "In2.Cu")
		(net "FM_OCP_MEZZA_PRES")
	)
	(segment
		(start 387.853936 -85.680042)
		(end 388.9375 -84.596478)
		(width 0.089408)
		(layer "In2.Cu")
		(net "FM_OCP_MEZZA_PRES")
	)
	(segment
		(start 391.441432 -47.14748)
		(end 391.222992 -46.92904)
		(width 0.089408)
		(layer "In2.Cu")
		(net "FM_OCP_MEZZA_PRES")
	)
	(segment
		(start 388.702296 -69.861684)
		(end 388.702296 -67.092576)
		(width 0.089408)
		(layer "In2.Cu")
		(net "FM_OCP_MEZZA_PRES")
	)
	(segment
		(start 389.189214 -70.348602)
		(end 388.702296 -69.861684)
		(width 0.089408)
		(layer "In2.Cu")
		(net "FM_OCP_MEZZA_PRES")
	)
	(segment
		(start 389.189214 -73.293986)
		(end 389.189214 -70.348602)
		(width 0.089408)
		(layer "In2.Cu")
		(net "FM_OCP_MEZZA_PRES")
	)
	(segment
		(start 410.890212 -43.157648)
		(end 411.213046 -43.480482)
		(width 0.089408)
		(layer "In2.Cu")
		(net "FM_OCP_MEZZA_PRES")
	)
	(segment
		(start 393.309856 -57.964578)
		(end 392.45286 -57.107582)
		(width 0.089408)
		(layer "In2.Cu")
		(net "FM_OCP_MEZZA_PRES")
	)
	(segment
		(start 387.793484 -85.680042)
		(end 387.853936 -85.680042)
		(width 0.089408)
		(layer "In2.Cu")
		(net "FM_OCP_MEZZA_PRES")
	)
	(segment
		(start 415.94024 -94.42196)
		(end 415.94024 -91.092782)
		(width 0.089408)
		(layer "In4.Cu")
		(net "FM_OCP_MEZZA_PRES")
	)
	(segment
		(start 412.920942 -89.553288)
		(end 411.917896 -90.556334)
		(width 0.089408)
		(layer "In4.Cu")
		(net "FM_OCP_MEZZA_PRES")
	)
	(segment
		(start 399.584164 -88.350852)
		(end 399.161254 -87.927942)
		(width 0.089408)
		(layer "In4.Cu")
		(net "FM_OCP_MEZZA_PRES")
	)
	(segment
		(start 421.86606 -100.9142)
		(end 421.86606 -100.34778)
		(width 0.089408)
		(layer "In4.Cu")
		(net "FM_OCP_MEZZA_PRES")
	)
	(segment
		(start 394.9192 -87.376)
		(end 392.478768 -87.376)
		(width 0.089408)
		(layer "In4.Cu")
		(net "FM_OCP_MEZZA_PRES")
	)
	(segment
		(start 391.686542 -87.375746)
		(end 391.686288 -87.376)
		(width 0.089408)
		(layer "In4.Cu")
		(net "FM_OCP_MEZZA_PRES")
	)
	(segment
		(start 402.603208 -87.970614)
		(end 402.22297 -88.350852)
		(width 0.089408)
		(layer "In4.Cu")
		(net "FM_OCP_MEZZA_PRES")
	)
	(segment
		(start 414.400746 -89.553288)
		(end 412.920942 -89.553288)
		(width 0.089408)
		(layer "In4.Cu")
		(net "FM_OCP_MEZZA_PRES")
	)
	(segment
		(start 409.973272 -89.44864)
		(end 405.877522 -89.44864)
		(width 0.089408)
		(layer "In4.Cu")
		(net "FM_OCP_MEZZA_PRES")
	)
	(segment
		(start 395.471142 -87.927942)
		(end 394.9192 -87.376)
		(width 0.089408)
		(layer "In4.Cu")
		(net "FM_OCP_MEZZA_PRES")
	)
	(segment
		(start 392.478514 -87.375746)
		(end 391.686542 -87.375746)
		(width 0.089408)
		(layer "In4.Cu")
		(net "FM_OCP_MEZZA_PRES")
	)
	(segment
		(start 391.686288 -87.376)
		(end 389.552942 -87.376)
		(width 0.089408)
		(layer "In4.Cu")
		(net "FM_OCP_MEZZA_PRES")
	)
	(segment
		(start 402.22297 -88.350852)
		(end 399.584164 -88.350852)
		(width 0.089408)
		(layer "In4.Cu")
		(net "FM_OCP_MEZZA_PRES")
	)
	(segment
		(start 399.161254 -87.927942)
		(end 395.471142 -87.927942)
		(width 0.089408)
		(layer "In4.Cu")
		(net "FM_OCP_MEZZA_PRES")
	)
	(segment
		(start 411.917896 -90.556334)
		(end 411.081728 -90.556334)
		(width 0.089408)
		(layer "In4.Cu")
		(net "FM_OCP_MEZZA_PRES")
	)
	(segment
		(start 385.411218 -88.806782)
		(end 385.411218 -88.890856)
		(width 0.089408)
		(layer "In4.Cu")
		(net "FM_OCP_MEZZA_PRES")
	)
	(segment
		(start 389.552942 -87.376)
		(end 389.001 -87.927942)
		(width 0.089408)
		(layer "In4.Cu")
		(net "FM_OCP_MEZZA_PRES")
	)
	(segment
		(start 392.478768 -87.376)
		(end 392.478514 -87.375746)
		(width 0.089408)
		(layer "In4.Cu")
		(net "FM_OCP_MEZZA_PRES")
	)
	(segment
		(start 404.356316 -87.970868)
		(end 404.356062 -87.970614)
		(width 0.089408)
		(layer "In4.Cu")
		(net "FM_OCP_MEZZA_PRES")
	)
	(segment
		(start 411.081728 -90.556334)
		(end 409.973272 -89.44864)
		(width 0.089408)
		(layer "In4.Cu")
		(net "FM_OCP_MEZZA_PRES")
	)
	(segment
		(start 405.877522 -89.44864)
		(end 404.39975 -87.970868)
		(width 0.089408)
		(layer "In4.Cu")
		(net "FM_OCP_MEZZA_PRES")
	)
	(segment
		(start 389.001 -87.927942)
		(end 386.290058 -87.927942)
		(width 0.089408)
		(layer "In4.Cu")
		(net "FM_OCP_MEZZA_PRES")
	)
	(segment
		(start 404.39975 -87.970868)
		(end 404.356316 -87.970868)
		(width 0.089408)
		(layer "In4.Cu")
		(net "FM_OCP_MEZZA_PRES")
	)
	(segment
		(start 415.94024 -91.092782)
		(end 414.400746 -89.553288)
		(width 0.089408)
		(layer "In4.Cu")
		(net "FM_OCP_MEZZA_PRES")
	)
	(segment
		(start 386.290058 -87.927942)
		(end 385.411218 -88.806782)
		(width 0.089408)
		(layer "In4.Cu")
		(net "FM_OCP_MEZZA_PRES")
	)
	(segment
		(start 404.356062 -87.970614)
		(end 402.603208 -87.970614)
		(width 0.089408)
		(layer "In4.Cu")
		(net "FM_OCP_MEZZA_PRES")
	)
	(segment
		(start 421.86606 -100.34778)
		(end 415.94024 -94.42196)
		(width 0.089408)
		(layer "In4.Cu")
		(net "FM_OCP_MEZZA_PRES")
	)
	(segment
		(start 420.828724 -103.229156)
		(end 420.828724 -104.317546)
		(width 0.089408)
		(layer "In9.Cu")
		(net "FM_OCP_MEZZA_PRES")
	)
	(segment
		(start 419.911276 -100.60305)
		(end 419.911276 -102.311708)
		(width 0.089408)
		(layer "In9.Cu")
		(net "FM_OCP_MEZZA_PRES")
	)
	(segment
		(start 419.911276 -102.311708)
		(end 420.828724 -103.229156)
		(width 0.089408)
		(layer "In9.Cu")
		(net "FM_OCP_MEZZA_PRES")
	)
	(segment
		(start 474.03004 -111.34344)
		(end 477.0374 -114.3508)
		(width 0.089408)
		(layer "In9.Cu")
		(net "FM_OCP_MEZZA_PRES")
	)
	(segment
		(start 420.828724 -104.317546)
		(end 425.247816 -108.736638)
		(width 0.089408)
		(layer "In9.Cu")
		(net "FM_OCP_MEZZA_PRES")
	)
	(segment
		(start 421.86606 -100.9142)
		(end 421.477186 -100.9142)
		(width 0.089408)
		(layer "In9.Cu")
		(net "FM_OCP_MEZZA_PRES")
	)
	(segment
		(start 421.477186 -100.9142)
		(end 420.90848 -100.345494)
		(width 0.089408)
		(layer "In9.Cu")
		(net "FM_OCP_MEZZA_PRES")
	)
	(segment
		(start 420.90848 -100.345494)
		(end 420.168832 -100.345494)
		(width 0.089408)
		(layer "In9.Cu")
		(net "FM_OCP_MEZZA_PRES")
	)
	(segment
		(start 425.247816 -108.736638)
		(end 425.247816 -109.397292)
		(width 0.089408)
		(layer "In9.Cu")
		(net "FM_OCP_MEZZA_PRES")
	)
	(segment
		(start 425.247816 -109.397292)
		(end 427.193964 -111.34344)
		(width 0.089408)
		(layer "In9.Cu")
		(net "FM_OCP_MEZZA_PRES")
	)
	(segment
		(start 427.193964 -111.34344)
		(end 474.03004 -111.34344)
		(width 0.089408)
		(layer "In9.Cu")
		(net "FM_OCP_MEZZA_PRES")
	)
	(segment
		(start 420.168832 -100.345494)
		(end 419.911276 -100.60305)
		(width 0.089408)
		(layer "In9.Cu")
		(net "FM_OCP_MEZZA_PRES")
	)
	(segment
		(start 85.777832 -68.963286)
		(end 85.206332 -68.963286)
		(width 0.10795)
		(layer "F.Cu")
		(net "TP_CPU1_RSVD_182")
	)
	(via
		(at 85.206332 -68.963286)
		(size 0.508)
		(drill 0.254)
		(layers "F.Cu" "B.Cu")
		(net "TP_CPU1_RSVD_182")
	)
	(segment
		(start 92.645738 -64.010286)
		(end 92.074238 -64.010286)
		(width 0.10795)
		(layer "F.Cu")
		(net "TP_CPU1_RSVD_219")
	)
	(via
		(at 92.074238 -64.010286)
		(size 0.508)
		(drill 0.254)
		(layers "F.Cu" "B.Cu")
		(net "TP_CPU1_RSVD_219")
	)
	(segment
		(start 93.504258 -63.51524)
		(end 92.932758 -63.51524)
		(width 0.10795)
		(layer "F.Cu")
		(net "TP_CPU1_RSVD_226")
	)
	(via
		(at 92.932758 -63.51524)
		(size 0.508)
		(drill 0.254)
		(layers "F.Cu" "B.Cu")
		(net "TP_CPU1_RSVD_226")
	)
	(segment
		(start 94.362778 -63.019686)
		(end 93.791278 -63.019686)
		(width 0.10795)
		(layer "F.Cu")
		(net "TP_CPU1_RSVD_231")
	)
	(via
		(at 93.791278 -63.019686)
		(size 0.508)
		(drill 0.254)
		(layers "F.Cu" "B.Cu")
		(net "TP_CPU1_RSVD_231")
	)
	(segment
		(start 93.504258 -62.52464)
		(end 92.932758 -62.52464)
		(width 0.10795)
		(layer "F.Cu")
		(net "TP_CPU1_RSVD_235")
	)
	(via
		(at 92.932758 -62.52464)
		(size 0.508)
		(drill 0.254)
		(layers "F.Cu" "B.Cu")
		(net "TP_CPU1_RSVD_235")
	)
	(segment
		(start 95.221298 -62.52464)
		(end 94.649798 -62.52464)
		(width 0.10795)
		(layer "F.Cu")
		(net "TP_CPU1_RSVD_236")
	)
	(via
		(at 94.649798 -62.52464)
		(size 0.508)
		(drill 0.254)
		(layers "F.Cu" "B.Cu")
		(net "TP_CPU1_RSVD_236")
	)
	(segment
		(start 96.938338 -62.52464)
		(end 96.366838 -62.52464)
		(width 0.10795)
		(layer "F.Cu")
		(net "TP_CPU1_RSVD_237")
	)
	(via
		(at 96.366838 -62.52464)
		(size 0.508)
		(drill 0.254)
		(layers "F.Cu" "B.Cu")
		(net "TP_CPU1_RSVD_237")
	)
	(segment
		(start 98.655378 -62.52464)
		(end 98.083878 -62.52464)
		(width 0.10795)
		(layer "F.Cu")
		(net "TP_CPU1_RSVD_238")
	)
	(via
		(at 98.083878 -62.52464)
		(size 0.508)
		(drill 0.254)
		(layers "F.Cu" "B.Cu")
		(net "TP_CPU1_RSVD_238")
	)
	(segment
		(start 100.372164 -62.52464)
		(end 99.800664 -62.52464)
		(width 0.10795)
		(layer "F.Cu")
		(net "TP_CPU1_RSVD_239")
	)
	(via
		(at 99.800664 -62.52464)
		(size 0.508)
		(drill 0.254)
		(layers "F.Cu" "B.Cu")
		(net "TP_CPU1_RSVD_239")
	)
	(segment
		(start 96.079818 -62.029086)
		(end 95.508318 -62.029086)
		(width 0.10795)
		(layer "F.Cu")
		(net "TP_CPU1_RSVD_242")
	)
	(via
		(at 95.508318 -62.029086)
		(size 0.508)
		(drill 0.254)
		(layers "F.Cu" "B.Cu")
		(net "TP_CPU1_RSVD_242")
	)
	(segment
		(start 97.796858 -62.029086)
		(end 97.225358 -62.029086)
		(width 0.10795)
		(layer "F.Cu")
		(net "TP_CPU1_RSVD_243")
	)
	(via
		(at 97.225358 -62.029086)
		(size 0.508)
		(drill 0.254)
		(layers "F.Cu" "B.Cu")
		(net "TP_CPU1_RSVD_243")
	)
	(segment
		(start 99.513898 -62.029086)
		(end 98.942398 -62.029086)
		(width 0.10795)
		(layer "F.Cu")
		(net "TP_CPU1_RSVD_244")
	)
	(via
		(at 98.942398 -62.029086)
		(size 0.508)
		(drill 0.254)
		(layers "F.Cu" "B.Cu")
		(net "TP_CPU1_RSVD_244")
	)
	(segment
		(start 96.938338 -61.53404)
		(end 96.366838 -61.53404)
		(width 0.10795)
		(layer "F.Cu")
		(net "TP_CPU1_RSVD_248")
	)
	(via
		(at 96.366838 -61.53404)
		(size 0.508)
		(drill 0.254)
		(layers "F.Cu" "B.Cu")
		(net "TP_CPU1_RSVD_248")
	)
	(segment
		(start 98.655378 -61.53404)
		(end 98.083878 -61.53404)
		(width 0.10795)
		(layer "F.Cu")
		(net "TP_CPU1_RSVD_249")
	)
	(via
		(at 98.083878 -61.53404)
		(size 0.508)
		(drill 0.254)
		(layers "F.Cu" "B.Cu")
		(net "TP_CPU1_RSVD_249")
	)
	(segment
		(start 100.372164 -61.53404)
		(end 99.800664 -61.53404)
		(width 0.10795)
		(layer "F.Cu")
		(net "TP_CPU1_RSVD_250")
	)
	(via
		(at 99.800664 -61.53404)
		(size 0.508)
		(drill 0.254)
		(layers "F.Cu" "B.Cu")
		(net "TP_CPU1_RSVD_250")
	)
	(segment
		(start 97.796858 -61.038486)
		(end 97.225358 -61.038486)
		(width 0.10795)
		(layer "F.Cu")
		(net "TP_CPU1_RSVD_252")
	)
	(via
		(at 97.225358 -61.038486)
		(size 0.508)
		(drill 0.254)
		(layers "F.Cu" "B.Cu")
		(net "TP_CPU1_RSVD_252")
	)
	(segment
		(start 99.513898 -61.038486)
		(end 98.942398 -61.038486)
		(width 0.10795)
		(layer "F.Cu")
		(net "TP_CPU1_RSVD_253")
	)
	(via
		(at 98.942398 -61.038486)
		(size 0.508)
		(drill 0.254)
		(layers "F.Cu" "B.Cu")
		(net "TP_CPU1_RSVD_253")
	)
	(segment
		(start 257.64617 -64.010286)
		(end 257.07467 -64.010286)
		(width 0.10795)
		(layer "F.Cu")
		(net "TP_CPU0_RSVD_219")
	)
	(via
		(at 257.07467 -64.010286)
		(size 0.508)
		(drill 0.254)
		(layers "F.Cu" "B.Cu")
		(net "TP_CPU0_RSVD_219")
	)
	(segment
		(start 258.50469 -63.51524)
		(end 257.93319 -63.51524)
		(width 0.10795)
		(layer "F.Cu")
		(net "TP_CPU0_RSVD_226")
	)
	(via
		(at 257.93319 -63.51524)
		(size 0.508)
		(drill 0.254)
		(layers "F.Cu" "B.Cu")
		(net "TP_CPU0_RSVD_226")
	)
	(segment
		(start 259.36321 -63.019686)
		(end 258.79171 -63.019686)
		(width 0.10795)
		(layer "F.Cu")
		(net "TP_CPU0_RSVD_231")
	)
	(via
		(at 258.79171 -63.019686)
		(size 0.508)
		(drill 0.254)
		(layers "F.Cu" "B.Cu")
		(net "TP_CPU0_RSVD_231")
	)
	(segment
		(start 258.50469 -62.52464)
		(end 257.93319 -62.52464)
		(width 0.10795)
		(layer "F.Cu")
		(net "TP_CPU0_RSVD_235")
	)
	(via
		(at 257.93319 -62.52464)
		(size 0.508)
		(drill 0.254)
		(layers "F.Cu" "B.Cu")
		(net "TP_CPU0_RSVD_235")
	)
	(segment
		(start 260.22173 -62.52464)
		(end 259.65023 -62.52464)
		(width 0.10795)
		(layer "F.Cu")
		(net "TP_CPU0_RSVD_236")
	)
	(via
		(at 259.65023 -62.52464)
		(size 0.508)
		(drill 0.254)
		(layers "F.Cu" "B.Cu")
		(net "TP_CPU0_RSVD_236")
	)
	(segment
		(start 261.93877 -62.52464)
		(end 261.36727 -62.52464)
		(width 0.10795)
		(layer "F.Cu")
		(net "TP_CPU0_RSVD_237")
	)
	(via
		(at 261.36727 -62.52464)
		(size 0.508)
		(drill 0.254)
		(layers "F.Cu" "B.Cu")
		(net "TP_CPU0_RSVD_237")
	)
	(segment
		(start 263.65581 -62.52464)
		(end 263.08431 -62.52464)
		(width 0.10795)
		(layer "F.Cu")
		(net "TP_CPU0_RSVD_238")
	)
	(via
		(at 263.08431 -62.52464)
		(size 0.508)
		(drill 0.254)
		(layers "F.Cu" "B.Cu")
		(net "TP_CPU0_RSVD_238")
	)
	(segment
		(start 265.372596 -62.52464)
		(end 264.801096 -62.52464)
		(width 0.10795)
		(layer "F.Cu")
		(net "TP_CPU0_RSVD_239")
	)
	(via
		(at 264.801096 -62.52464)
		(size 0.508)
		(drill 0.254)
		(layers "F.Cu" "B.Cu")
		(net "TP_CPU0_RSVD_239")
	)
	(segment
		(start 260.50875 -62.029086)
		(end 261.08025 -62.029086)
		(width 0.10795)
		(layer "F.Cu")
		(net "TP_CPU0_RSVD_242")
	)
	(via
		(at 260.50875 -62.029086)
		(size 0.508)
		(drill 0.254)
		(layers "F.Cu" "B.Cu")
		(net "TP_CPU0_RSVD_242")
	)
	(segment
		(start 262.79729 -62.029086)
		(end 262.22579 -62.029086)
		(width 0.10795)
		(layer "F.Cu")
		(net "TP_CPU0_RSVD_243")
	)
	(via
		(at 262.22579 -62.029086)
		(size 0.508)
		(drill 0.254)
		(layers "F.Cu" "B.Cu")
		(net "TP_CPU0_RSVD_243")
	)
	(segment
		(start 264.51433 -62.029086)
		(end 263.94283 -62.029086)
		(width 0.10795)
		(layer "F.Cu")
		(net "TP_CPU0_RSVD_244")
	)
	(via
		(at 263.94283 -62.029086)
		(size 0.508)
		(drill 0.254)
		(layers "F.Cu" "B.Cu")
		(net "TP_CPU0_RSVD_244")
	)
	(segment
		(start 261.93877 -61.53404)
		(end 261.36727 -61.53404)
		(width 0.10795)
		(layer "F.Cu")
		(net "TP_CPU0_RSVD_248")
	)
	(via
		(at 261.36727 -61.53404)
		(size 0.508)
		(drill 0.254)
		(layers "F.Cu" "B.Cu")
		(net "TP_CPU0_RSVD_248")
	)
	(segment
		(start 263.65581 -61.53404)
		(end 263.08431 -61.53404)
		(width 0.10795)
		(layer "F.Cu")
		(net "TP_CPU0_RSVD_249")
	)
	(via
		(at 263.08431 -61.53404)
		(size 0.508)
		(drill 0.254)
		(layers "F.Cu" "B.Cu")
		(net "TP_CPU0_RSVD_249")
	)
	(segment
		(start 265.372596 -61.53404)
		(end 264.801096 -61.53404)
		(width 0.10795)
		(layer "F.Cu")
		(net "TP_CPU0_RSVD_250")
	)
	(via
		(at 264.801096 -61.53404)
		(size 0.508)
		(drill 0.254)
		(layers "F.Cu" "B.Cu")
		(net "TP_CPU0_RSVD_250")
	)
	(segment
		(start 262.79729 -61.038486)
		(end 262.22579 -61.038486)
		(width 0.10795)
		(layer "F.Cu")
		(net "TP_CPU0_RSVD_252")
	)
	(via
		(at 262.22579 -61.038486)
		(size 0.508)
		(drill 0.254)
		(layers "F.Cu" "B.Cu")
		(net "TP_CPU0_RSVD_252")
	)
	(segment
		(start 264.51433 -61.038486)
		(end 263.94283 -61.038486)
		(width 0.10795)
		(layer "F.Cu")
		(net "TP_CPU0_RSVD_253")
	)
	(via
		(at 263.94283 -61.038486)
		(size 0.508)
		(drill 0.254)
		(layers "F.Cu" "B.Cu")
		(net "TP_CPU0_RSVD_253")
	)
	(segment
		(start 377.83135 -95.888556)
		(end 377.33605 -96.11868)
		(width 0.10795)
		(layer "F.Cu")
		(net "TP_SPI_PCH_CS1_R1_N")
	)
	(via
		(at 377.83135 -95.888556)
		(size 0.508)
		(drill 0.254)
		(layers "F.Cu" "B.Cu")
		(net "TP_SPI_PCH_CS1_R1_N")
	)
	(segment
		(start 405.7396 -107.889294)
		(end 406.034494 -107.889294)
		(width 0.10795)
		(layer "F.Cu")
		(net "SMB_SMLINK0_STBY_LVC3_SDA_R1")
	)
	(segment
		(start 400.465036 -106.855006)
		(end 400.545808 -106.935778)
		(width 0.0889)
		(layer "F.Cu")
		(net "SMB_SMLINK0_STBY_LVC3_SDA_R1")
	)
	(segment
		(start 403.080474 -107.23753)
		(end 403.563836 -107.23753)
		(width 0.0889)
		(layer "F.Cu")
		(net "SMB_SMLINK0_STBY_LVC3_SDA_R1")
	)
	(segment
		(start 402.899118 -107.418886)
		(end 403.080474 -107.23753)
		(width 0.0889)
		(layer "F.Cu")
		(net "SMB_SMLINK0_STBY_LVC3_SDA_R1")
	)
	(segment
		(start 402.312378 -107.164124)
		(end 402.56714 -107.418886)
		(width 0.0889)
		(layer "F.Cu")
		(net "SMB_SMLINK0_STBY_LVC3_SDA_R1")
	)
	(segment
		(start 403.563836 -107.23753)
		(end 403.652736 -107.32643)
		(width 0.0889)
		(layer "F.Cu")
		(net "SMB_SMLINK0_STBY_LVC3_SDA_R1")
	)
	(segment
		(start 400.925284 -106.935778)
		(end 401.15363 -107.164124)
		(width 0.0889)
		(layer "F.Cu")
		(net "SMB_SMLINK0_STBY_LVC3_SDA_R1")
	)
	(segment
		(start 407.1112 -108.966)
		(end 407.8605 -108.966)
		(width 0.10795)
		(layer "F.Cu")
		(net "SMB_SMLINK0_STBY_LVC3_SDA_R1")
	)
	(segment
		(start 400.545808 -106.935778)
		(end 400.925284 -106.935778)
		(width 0.0889)
		(layer "F.Cu")
		(net "SMB_SMLINK0_STBY_LVC3_SDA_R1")
	)
	(segment
		(start 404.2156 -107.889294)
		(end 405.7396 -107.889294)
		(width 0.10795)
		(layer "F.Cu")
		(net "SMB_SMLINK0_STBY_LVC3_SDA_R1")
	)
	(segment
		(start 402.56714 -107.418886)
		(end 402.899118 -107.418886)
		(width 0.0889)
		(layer "F.Cu")
		(net "SMB_SMLINK0_STBY_LVC3_SDA_R1")
	)
	(segment
		(start 406.034494 -107.889294)
		(end 407.1112 -108.966)
		(width 0.10795)
		(layer "F.Cu")
		(net "SMB_SMLINK0_STBY_LVC3_SDA_R1")
	)
	(segment
		(start 403.652736 -107.32643)
		(end 404.2156 -107.889294)
		(width 0.10795)
		(layer "F.Cu")
		(net "SMB_SMLINK0_STBY_LVC3_SDA_R1")
	)
	(segment
		(start 401.15363 -107.164124)
		(end 402.312378 -107.164124)
		(width 0.0889)
		(layer "F.Cu")
		(net "SMB_SMLINK0_STBY_LVC3_SDA_R1")
	)
	(via
		(at 405.7396 -107.889294)
		(size 0.508)
		(drill 0.254)
		(layers "F.Cu" "B.Cu")
		(net "SMB_SMLINK0_STBY_LVC3_SDA_R1")
	)
	(segment
		(start 403.41677 -106.61777)
		(end 402.56714 -106.61777)
		(width 0.0889)
		(layer "F.Cu")
		(net "SMB_SMLINK0_STBY_LVC3_SCL_R1")
	)
	(segment
		(start 407.8605 -108.204)
		(end 407.543 -108.204)
		(width 0.10795)
		(layer "F.Cu")
		(net "SMB_SMLINK0_STBY_LVC3_SCL_R1")
	)
	(segment
		(start 407.543 -108.204)
		(end 407.4922 -108.1532)
		(width 0.10795)
		(layer "F.Cu")
		(net "SMB_SMLINK0_STBY_LVC3_SCL_R1")
	)
	(segment
		(start 406.654254 -108.1532)
		(end 406.120854 -107.6198)
		(width 0.10795)
		(layer "F.Cu")
		(net "SMB_SMLINK0_STBY_LVC3_SCL_R1")
	)
	(segment
		(start 402.510244 -106.674666)
		(end 401.584922 -106.674666)
		(width 0.0889)
		(layer "F.Cu")
		(net "SMB_SMLINK0_STBY_LVC3_SCL_R1")
	)
	(segment
		(start 401.124166 -106.569256)
		(end 401.027392 -106.66603)
		(width 0.0889)
		(layer "F.Cu")
		(net "SMB_SMLINK0_STBY_LVC3_SCL_R1")
	)
	(segment
		(start 407.4922 -108.1532)
		(end 407.04008 -108.1532)
		(width 0.10795)
		(layer "F.Cu")
		(net "SMB_SMLINK0_STBY_LVC3_SCL_R1")
	)
	(segment
		(start 402.56714 -106.61777)
		(end 402.510244 -106.674666)
		(width 0.0889)
		(layer "F.Cu")
		(net "SMB_SMLINK0_STBY_LVC3_SCL_R1")
	)
	(segment
		(start 404.4188 -107.6198)
		(end 404.037292 -107.238292)
		(width 0.10795)
		(layer "F.Cu")
		(net "SMB_SMLINK0_STBY_LVC3_SCL_R1")
	)
	(segment
		(start 407.04008 -108.1532)
		(end 406.654254 -108.1532)
		(width 0.10795)
		(layer "F.Cu")
		(net "SMB_SMLINK0_STBY_LVC3_SCL_R1")
	)
	(segment
		(start 400.42211 -106.35488)
		(end 400.05 -106.35488)
		(width 0.0889)
		(layer "F.Cu")
		(net "SMB_SMLINK0_STBY_LVC3_SCL_R1")
	)
	(segment
		(start 401.479512 -106.569256)
		(end 401.124166 -106.569256)
		(width 0.0889)
		(layer "F.Cu")
		(net "SMB_SMLINK0_STBY_LVC3_SCL_R1")
	)
	(segment
		(start 400.73326 -106.66603)
		(end 400.42211 -106.35488)
		(width 0.0889)
		(layer "F.Cu")
		(net "SMB_SMLINK0_STBY_LVC3_SCL_R1")
	)
	(segment
		(start 406.120854 -107.6198)
		(end 404.4188 -107.6198)
		(width 0.10795)
		(layer "F.Cu")
		(net "SMB_SMLINK0_STBY_LVC3_SCL_R1")
	)
	(segment
		(start 401.027392 -106.66603)
		(end 400.73326 -106.66603)
		(width 0.0889)
		(layer "F.Cu")
		(net "SMB_SMLINK0_STBY_LVC3_SCL_R1")
	)
	(segment
		(start 404.037292 -107.238292)
		(end 403.41677 -106.61777)
		(width 0.0889)
		(layer "F.Cu")
		(net "SMB_SMLINK0_STBY_LVC3_SCL_R1")
	)
	(segment
		(start 401.584922 -106.674666)
		(end 401.479512 -106.569256)
		(width 0.0889)
		(layer "F.Cu")
		(net "SMB_SMLINK0_STBY_LVC3_SCL_R1")
	)
	(via
		(at 407.04008 -108.1532)
		(size 0.508)
		(drill 0.254)
		(layers "F.Cu" "B.Cu")
		(net "SMB_SMLINK0_STBY_LVC3_SCL_R1")
	)
	(segment
		(start 400.433032 -105.354882)
		(end 400.744182 -105.666032)
		(width 0.0889)
		(layer "F.Cu")
		(net "SMB_HOST_STBY_LVC3_SDA_R1")
	)
	(segment
		(start 402.390356 -105.456482)
		(end 402.515324 -105.58145)
		(width 0.0889)
		(layer "F.Cu")
		(net "SMB_HOST_STBY_LVC3_SDA_R1")
	)
	(segment
		(start 401.969732 -105.456482)
		(end 402.390356 -105.456482)
		(width 0.0889)
		(layer "F.Cu")
		(net "SMB_HOST_STBY_LVC3_SDA_R1")
	)
	(segment
		(start 410.1846 -106.2228)
		(end 410.346398 -106.384598)
		(width 0.10795)
		(layer "F.Cu")
		(net "SMB_HOST_STBY_LVC3_SDA_R1")
	)
	(segment
		(start 401.127976 -105.54716)
		(end 401.879054 -105.54716)
		(width 0.0889)
		(layer "F.Cu")
		(net "SMB_HOST_STBY_LVC3_SDA_R1")
	)
	(segment
		(start 409.3972 -106.2228)
		(end 410.1846 -106.2228)
		(width 0.10795)
		(layer "F.Cu")
		(net "SMB_HOST_STBY_LVC3_SDA_R1")
	)
	(segment
		(start 404.669244 -106.5784)
		(end 409.0416 -106.5784)
		(width 0.10795)
		(layer "F.Cu")
		(net "SMB_HOST_STBY_LVC3_SDA_R1")
	)
	(segment
		(start 409.0416 -106.5784)
		(end 409.3972 -106.2228)
		(width 0.10795)
		(layer "F.Cu")
		(net "SMB_HOST_STBY_LVC3_SDA_R1")
	)
	(segment
		(start 410.806138 -106.308144)
		(end 411.152086 -105.962196)
		(width 0.10795)
		(layer "F.Cu")
		(net "SMB_HOST_STBY_LVC3_SDA_R1")
	)
	(segment
		(start 401.879054 -105.54716)
		(end 401.969732 -105.456482)
		(width 0.0889)
		(layer "F.Cu")
		(net "SMB_HOST_STBY_LVC3_SDA_R1")
	)
	(segment
		(start 410.346398 -106.384598)
		(end 410.806138 -106.384598)
		(width 0.10795)
		(layer "F.Cu")
		(net "SMB_HOST_STBY_LVC3_SDA_R1")
	)
	(segment
		(start 402.515324 -105.58145)
		(end 402.679916 -105.746042)
		(width 0.10795)
		(layer "F.Cu")
		(net "SMB_HOST_STBY_LVC3_SDA_R1")
	)
	(segment
		(start 410.806138 -106.384598)
		(end 410.806138 -106.308144)
		(width 0.10795)
		(layer "F.Cu")
		(net "SMB_HOST_STBY_LVC3_SDA_R1")
	)
	(segment
		(start 412.608776 -105.962196)
		(end 412.648908 -106.002328)
		(width 0.10795)
		(layer "F.Cu")
		(net "SMB_HOST_STBY_LVC3_SDA_R1")
	)
	(segment
		(start 411.152086 -105.962196)
		(end 412.608776 -105.962196)
		(width 0.10795)
		(layer "F.Cu")
		(net "SMB_HOST_STBY_LVC3_SDA_R1")
	)
	(segment
		(start 402.679916 -105.746042)
		(end 403.836886 -105.746042)
		(width 0.10795)
		(layer "F.Cu")
		(net "SMB_HOST_STBY_LVC3_SDA_R1")
	)
	(segment
		(start 401.009104 -105.666032)
		(end 401.127976 -105.54716)
		(width 0.0889)
		(layer "F.Cu")
		(net "SMB_HOST_STBY_LVC3_SDA_R1")
	)
	(segment
		(start 400.744182 -105.666032)
		(end 401.009104 -105.666032)
		(width 0.0889)
		(layer "F.Cu")
		(net "SMB_HOST_STBY_LVC3_SDA_R1")
	)
	(segment
		(start 403.836886 -105.746042)
		(end 404.669244 -106.5784)
		(width 0.10795)
		(layer "F.Cu")
		(net "SMB_HOST_STBY_LVC3_SDA_R1")
	)
	(segment
		(start 400.05 -105.354882)
		(end 400.433032 -105.354882)
		(width 0.0889)
		(layer "F.Cu")
		(net "SMB_HOST_STBY_LVC3_SDA_R1")
	)
	(via
		(at 412.648908 -106.002328)
		(size 0.762)
		(drill 0.381)
		(layers "F.Cu" "B.Cu")
		(net "SMB_HOST_STBY_LVC3_SDA_R1")
	)
	(segment
		(start 409.8036 -106.807)
		(end 410.46654 -106.807)
		(width 0.10795)
		(layer "F.Cu")
		(net "SMB_HOST_STBY_LVC3_SCL_R1")
	)
	(segment
		(start 409.7782 -106.807)
		(end 409.8036 -106.807)
		(width 0.10795)
		(layer "F.Cu")
		(net "SMB_HOST_STBY_LVC3_SCL_R1")
	)
	(segment
		(start 401.856956 -106.140758)
		(end 401.969732 -106.253534)
		(width 0.0889)
		(layer "F.Cu")
		(net "SMB_HOST_STBY_LVC3_SCL_R1")
	)
	(segment
		(start 400.465036 -105.855008)
		(end 400.663918 -105.855008)
		(width 0.0889)
		(layer "F.Cu")
		(net "SMB_HOST_STBY_LVC3_SCL_R1")
	)
	(segment
		(start 402.71192 -106.006392)
		(end 403.642068 -106.006392)
		(width 0.10795)
		(layer "F.Cu")
		(net "SMB_HOST_STBY_LVC3_SCL_R1")
	)
	(segment
		(start 401.969732 -106.253534)
		(end 402.299932 -106.253534)
		(width 0.0889)
		(layer "F.Cu")
		(net "SMB_HOST_STBY_LVC3_SCL_R1")
	)
	(segment
		(start 403.642068 -106.006392)
		(end 404.531068 -106.895392)
		(width 0.10795)
		(layer "F.Cu")
		(net "SMB_HOST_STBY_LVC3_SCL_R1")
	)
	(segment
		(start 400.839178 -105.856278)
		(end 401.123658 -106.140758)
		(width 0.0889)
		(layer "F.Cu")
		(net "SMB_HOST_STBY_LVC3_SCL_R1")
	)
	(segment
		(start 402.547074 -106.006392)
		(end 402.71192 -106.006392)
		(width 0.0889)
		(layer "F.Cu")
		(net "SMB_HOST_STBY_LVC3_SCL_R1")
	)
	(segment
		(start 410.46654 -106.807)
		(end 410.806138 -107.146598)
		(width 0.10795)
		(layer "F.Cu")
		(net "SMB_HOST_STBY_LVC3_SCL_R1")
	)
	(segment
		(start 400.665188 -105.856278)
		(end 400.839178 -105.856278)
		(width 0.0889)
		(layer "F.Cu")
		(net "SMB_HOST_STBY_LVC3_SCL_R1")
	)
	(segment
		(start 402.299932 -106.253534)
		(end 402.547074 -106.006392)
		(width 0.0889)
		(layer "F.Cu")
		(net "SMB_HOST_STBY_LVC3_SCL_R1")
	)
	(segment
		(start 400.663918 -105.855008)
		(end 400.665188 -105.856278)
		(width 0.0889)
		(layer "F.Cu")
		(net "SMB_HOST_STBY_LVC3_SCL_R1")
	)
	(segment
		(start 404.531068 -106.895392)
		(end 409.689808 -106.895392)
		(width 0.10795)
		(layer "F.Cu")
		(net "SMB_HOST_STBY_LVC3_SCL_R1")
	)
	(segment
		(start 401.123658 -106.140758)
		(end 401.856956 -106.140758)
		(width 0.0889)
		(layer "F.Cu")
		(net "SMB_HOST_STBY_LVC3_SCL_R1")
	)
	(segment
		(start 409.689808 -106.895392)
		(end 409.7782 -106.807)
		(width 0.10795)
		(layer "F.Cu")
		(net "SMB_HOST_STBY_LVC3_SCL_R1")
	)
	(via
		(at 409.8036 -106.807)
		(size 0.762)
		(drill 0.381)
		(layers "F.Cu" "B.Cu")
		(net "SMB_HOST_STBY_LVC3_SCL_R1")
	)
	(segment
		(start 388.23265 -97.83572)
		(end 388.72795 -97.605596)
		(width 0.10795)
		(layer "F.Cu")
		(net "LED_PCH_SSATA_HDD_N")
	)
	(via
		(at 470.1921 -121.32056)
		(size 0.6604)
		(drill 0.3302)
		(layers "F.Cu" "B.Cu")
		(net "LED_PCH_SSATA_HDD_N")
	)
	(via
		(at 411.918658 -100.424996)
		(size 0.508)
		(drill 0.254)
		(layers "F.Cu" "B.Cu")
		(net "LED_PCH_SSATA_HDD_N")
	)
	(via
		(at 422.921938 -118.683278)
		(size 0.508)
		(drill 0.254)
		(layers "F.Cu" "B.Cu")
		(net "LED_PCH_SSATA_HDD_N")
	)
	(via
		(at 388.72795 -97.605596)
		(size 0.508)
		(drill 0.254)
		(layers "F.Cu" "B.Cu")
		(net "LED_PCH_SSATA_HDD_N")
	)
	(segment
		(start 437.753252 -121.364756)
		(end 439.5597 -119.558308)
		(width 0.10795)
		(layer "B.Cu")
		(net "LED_PCH_SSATA_HDD_N")
	)
	(segment
		(start 482.530404 -122.180604)
		(end 476.2754 -122.180604)
		(width 0.10795)
		(layer "B.Cu")
		(net "LED_PCH_SSATA_HDD_N")
	)
	(segment
		(start 441.081922 -112.8776)
		(end 467.157054 -112.8776)
		(width 0.10795)
		(layer "B.Cu")
		(net "LED_PCH_SSATA_HDD_N")
	)
	(segment
		(start 493.5474 -124.05868)
		(end 493.45596 -124.15012)
		(width 0.10795)
		(layer "B.Cu")
		(net "LED_PCH_SSATA_HDD_N")
	)
	(segment
		(start 476.014796 -121.92)
		(end 473.9132 -121.92)
		(width 0.10795)
		(layer "B.Cu")
		(net "LED_PCH_SSATA_HDD_N")
	)
	(segment
		(start 473.4052 -122.428)
		(end 471.29954 -122.428)
		(width 0.10795)
		(layer "B.Cu")
		(net "LED_PCH_SSATA_HDD_N")
	)
	(segment
		(start 483.196646 -122.846846)
		(end 482.530404 -122.180604)
		(width 0.10795)
		(layer "B.Cu")
		(net "LED_PCH_SSATA_HDD_N")
	)
	(segment
		(start 439.5597 -114.399822)
		(end 441.081922 -112.8776)
		(width 0.10795)
		(layer "B.Cu")
		(net "LED_PCH_SSATA_HDD_N")
	)
	(segment
		(start 469.769698 -116.078508)
		(end 469.769698 -120.898158)
		(width 0.10795)
		(layer "B.Cu")
		(net "LED_PCH_SSATA_HDD_N")
	)
	(segment
		(start 469.769698 -120.898158)
		(end 470.1921 -121.32056)
		(width 0.10795)
		(layer "B.Cu")
		(net "LED_PCH_SSATA_HDD_N")
	)
	(segment
		(start 425.184316 -120.662446)
		(end 425.886626 -121.364756)
		(width 0.10795)
		(layer "B.Cu")
		(net "LED_PCH_SSATA_HDD_N")
	)
	(segment
		(start 469.569546 -114.4016)
		(end 470.071196 -114.90325)
		(width 0.10795)
		(layer "B.Cu")
		(net "LED_PCH_SSATA_HDD_N")
	)
	(segment
		(start 471.29954 -122.428)
		(end 470.1921 -121.32056)
		(width 0.10795)
		(layer "B.Cu")
		(net "LED_PCH_SSATA_HDD_N")
	)
	(segment
		(start 468.681054 -114.4016)
		(end 469.569546 -114.4016)
		(width 0.10795)
		(layer "B.Cu")
		(net "LED_PCH_SSATA_HDD_N")
	)
	(segment
		(start 476.2754 -122.180604)
		(end 476.014796 -121.92)
		(width 0.10795)
		(layer "B.Cu")
		(net "LED_PCH_SSATA_HDD_N")
	)
	(segment
		(start 439.5597 -119.558308)
		(end 439.5597 -114.399822)
		(width 0.10795)
		(layer "B.Cu")
		(net "LED_PCH_SSATA_HDD_N")
	)
	(segment
		(start 473.9132 -121.92)
		(end 473.4052 -122.428)
		(width 0.10795)
		(layer "B.Cu")
		(net "LED_PCH_SSATA_HDD_N")
	)
	(segment
		(start 425.184316 -120.125998)
		(end 425.184316 -120.662446)
		(width 0.10795)
		(layer "B.Cu")
		(net "LED_PCH_SSATA_HDD_N")
	)
	(segment
		(start 423.780458 -119.826278)
		(end 424.884596 -119.826278)
		(width 0.10795)
		(layer "B.Cu")
		(net "LED_PCH_SSATA_HDD_N")
	)
	(segment
		(start 422.921938 -118.967758)
		(end 423.780458 -119.826278)
		(width 0.10795)
		(layer "B.Cu")
		(net "LED_PCH_SSATA_HDD_N")
	)
	(segment
		(start 424.884596 -119.826278)
		(end 425.184316 -120.125998)
		(width 0.10795)
		(layer "B.Cu")
		(net "LED_PCH_SSATA_HDD_N")
	)
	(segment
		(start 425.886626 -121.364756)
		(end 437.753252 -121.364756)
		(width 0.10795)
		(layer "B.Cu")
		(net "LED_PCH_SSATA_HDD_N")
	)
	(segment
		(start 486.568242 -124.76226)
		(end 484.652828 -122.846846)
		(width 0.10795)
		(layer "B.Cu")
		(net "LED_PCH_SSATA_HDD_N")
	)
	(segment
		(start 493.45596 -124.15012)
		(end 492.04372 -124.15012)
		(width 0.10795)
		(layer "B.Cu")
		(net "LED_PCH_SSATA_HDD_N")
	)
	(segment
		(start 470.071196 -114.90325)
		(end 470.071196 -115.77701)
		(width 0.10795)
		(layer "B.Cu")
		(net "LED_PCH_SSATA_HDD_N")
	)
	(segment
		(start 467.157054 -112.8776)
		(end 468.681054 -114.4016)
		(width 0.10795)
		(layer "B.Cu")
		(net "LED_PCH_SSATA_HDD_N")
	)
	(segment
		(start 470.071196 -115.77701)
		(end 469.769698 -116.078508)
		(width 0.10795)
		(layer "B.Cu")
		(net "LED_PCH_SSATA_HDD_N")
	)
	(segment
		(start 492.04372 -124.15012)
		(end 491.43158 -124.76226)
		(width 0.10795)
		(layer "B.Cu")
		(net "LED_PCH_SSATA_HDD_N")
	)
	(segment
		(start 484.652828 -122.846846)
		(end 483.196646 -122.846846)
		(width 0.10795)
		(layer "B.Cu")
		(net "LED_PCH_SSATA_HDD_N")
	)
	(segment
		(start 491.43158 -124.76226)
		(end 486.568242 -124.76226)
		(width 0.10795)
		(layer "B.Cu")
		(net "LED_PCH_SSATA_HDD_N")
	)
	(segment
		(start 422.921938 -118.683278)
		(end 422.921938 -118.967758)
		(width 0.10795)
		(layer "B.Cu")
		(net "LED_PCH_SSATA_HDD_N")
	)
	(segment
		(start 415.463228 -117.82679)
		(end 414.982406 -117.82679)
		(width 0.089408)
		(layer "In2.Cu")
		(net "LED_PCH_SSATA_HDD_N")
	)
	(segment
		(start 413.1564 -116.000784)
		(end 413.1564 -109.176566)
		(width 0.089408)
		(layer "In2.Cu")
		(net "LED_PCH_SSATA_HDD_N")
	)
	(segment
		(start 412.439358 -100.945696)
		(end 411.918658 -100.424996)
		(width 0.089408)
		(layer "In2.Cu")
		(net "LED_PCH_SSATA_HDD_N")
	)
	(segment
		(start 413.1564 -109.176566)
		(end 412.439358 -108.459524)
		(width 0.089408)
		(layer "In2.Cu")
		(net "LED_PCH_SSATA_HDD_N")
	)
	(segment
		(start 412.439358 -108.459524)
		(end 412.439358 -100.945696)
		(width 0.089408)
		(layer "In2.Cu")
		(net "LED_PCH_SSATA_HDD_N")
	)
	(segment
		(start 422.877488 -118.727728)
		(end 416.364166 -118.727728)
		(width 0.089408)
		(layer "In2.Cu")
		(net "LED_PCH_SSATA_HDD_N")
	)
	(segment
		(start 422.921938 -118.683278)
		(end 422.877488 -118.727728)
		(width 0.089408)
		(layer "In2.Cu")
		(net "LED_PCH_SSATA_HDD_N")
	)
	(segment
		(start 416.364166 -118.727728)
		(end 415.463228 -117.82679)
		(width 0.089408)
		(layer "In2.Cu")
		(net "LED_PCH_SSATA_HDD_N")
	)
	(segment
		(start 414.982406 -117.82679)
		(end 413.1564 -116.000784)
		(width 0.089408)
		(layer "In2.Cu")
		(net "LED_PCH_SSATA_HDD_N")
	)
	(segment
		(start 396.818104 -98.004376)
		(end 397.05153 -97.77095)
		(width 0.089408)
		(layer "In4.Cu")
		(net "LED_PCH_SSATA_HDD_N")
	)
	(segment
		(start 398.92986 -96.68764)
		(end 400.619976 -96.68764)
		(width 0.089408)
		(layer "In4.Cu")
		(net "LED_PCH_SSATA_HDD_N")
	)
	(segment
		(start 390.31037 -97.57791)
		(end 390.31037 -97.440242)
		(width 0.089408)
		(layer "In4.Cu")
		(net "LED_PCH_SSATA_HDD_N")
	)
	(segment
		(start 388.72795 -97.605596)
		(end 389.12673 -98.004376)
		(width 0.089408)
		(layer "In4.Cu")
		(net "LED_PCH_SSATA_HDD_N")
	)
	(segment
		(start 394.07973 -97.440242)
		(end 394.07973 -97.57791)
		(width 0.089408)
		(layer "In4.Cu")
		(net "LED_PCH_SSATA_HDD_N")
	)
	(segment
		(start 394.07973 -97.57791)
		(end 394.506196 -98.004376)
		(width 0.089408)
		(layer "In4.Cu")
		(net "LED_PCH_SSATA_HDD_N")
	)
	(segment
		(start 398.4117 -97.2058)
		(end 398.92986 -96.68764)
		(width 0.089408)
		(layer "In4.Cu")
		(net "LED_PCH_SSATA_HDD_N")
	)
	(segment
		(start 393.846304 -97.206816)
		(end 394.07973 -97.440242)
		(width 0.089408)
		(layer "In4.Cu")
		(net "LED_PCH_SSATA_HDD_N")
	)
	(segment
		(start 397.05153 -97.77095)
		(end 397.05153 -97.633282)
		(width 0.089408)
		(layer "In4.Cu")
		(net "LED_PCH_SSATA_HDD_N")
	)
	(segment
		(start 406.29967 -102.367334)
		(end 408.359102 -102.367334)
		(width 0.089408)
		(layer "In4.Cu")
		(net "LED_PCH_SSATA_HDD_N")
	)
	(segment
		(start 389.12673 -98.004376)
		(end 389.883904 -98.004376)
		(width 0.089408)
		(layer "In4.Cu")
		(net "LED_PCH_SSATA_HDD_N")
	)
	(segment
		(start 389.883904 -98.004376)
		(end 390.31037 -97.57791)
		(width 0.089408)
		(layer "In4.Cu")
		(net "LED_PCH_SSATA_HDD_N")
	)
	(segment
		(start 397.05153 -97.633282)
		(end 397.479012 -97.2058)
		(width 0.089408)
		(layer "In4.Cu")
		(net "LED_PCH_SSATA_HDD_N")
	)
	(segment
		(start 390.543796 -97.206816)
		(end 393.846304 -97.206816)
		(width 0.089408)
		(layer "In4.Cu")
		(net "LED_PCH_SSATA_HDD_N")
	)
	(segment
		(start 400.619976 -96.68764)
		(end 406.29967 -102.367334)
		(width 0.089408)
		(layer "In4.Cu")
		(net "LED_PCH_SSATA_HDD_N")
	)
	(segment
		(start 397.479012 -97.2058)
		(end 398.4117 -97.2058)
		(width 0.089408)
		(layer "In4.Cu")
		(net "LED_PCH_SSATA_HDD_N")
	)
	(segment
		(start 410.30144 -100.424996)
		(end 411.918658 -100.424996)
		(width 0.089408)
		(layer "In4.Cu")
		(net "LED_PCH_SSATA_HDD_N")
	)
	(segment
		(start 390.31037 -97.440242)
		(end 390.543796 -97.206816)
		(width 0.089408)
		(layer "In4.Cu")
		(net "LED_PCH_SSATA_HDD_N")
	)
	(segment
		(start 408.359102 -102.367334)
		(end 410.30144 -100.424996)
		(width 0.089408)
		(layer "In4.Cu")
		(net "LED_PCH_SSATA_HDD_N")
	)
	(segment
		(start 394.506196 -98.004376)
		(end 396.818104 -98.004376)
		(width 0.089408)
		(layer "In4.Cu")
		(net "LED_PCH_SSATA_HDD_N")
	)
	(segment
		(start 386.280406 -93.724222)
		(end 386.162042 -93.842586)
		(width 0.0889)
		(layer "F.Cu")
		(net "RST_PCIE_PCH_PERST_N")
	)
	(segment
		(start 386.294376 -93.17101)
		(end 386.294376 -93.171772)
		(width 0.0889)
		(layer "F.Cu")
		(net "RST_PCIE_PCH_PERST_N")
	)
	(segment
		(start 386.162042 -93.842586)
		(end 386.162042 -94.104968)
		(width 0.0889)
		(layer "F.Cu")
		(net "RST_PCIE_PCH_PERST_N")
	)
	(segment
		(start 386.387848 -93.077538)
		(end 386.294376 -93.17101)
		(width 0.0889)
		(layer "F.Cu")
		(net "RST_PCIE_PCH_PERST_N")
	)
	(segment
		(start 386.120132 -90.695526)
		(end 386.051806 -90.763852)
		(width 0.10795)
		(layer "F.Cu")
		(net "RST_PCIE_PCH_PERST_N")
	)
	(segment
		(start 382.408938 -69.095112)
		(end 378.744988 -69.095112)
		(width 0.10795)
		(layer "F.Cu")
		(net "RST_PCIE_PCH_PERST_N")
	)
	(segment
		(start 382.465072 -69.151246)
		(end 382.408938 -69.095112)
		(width 0.10795)
		(layer "F.Cu")
		(net "RST_PCIE_PCH_PERST_N")
	)
	(segment
		(start 386.162042 -94.104968)
		(end 386.484876 -94.427802)
		(width 0.0889)
		(layer "F.Cu")
		(net "RST_PCIE_PCH_PERST_N")
	)
	(segment
		(start 386.280406 -93.185742)
		(end 386.280406 -93.724222)
		(width 0.0889)
		(layer "F.Cu")
		(net "RST_PCIE_PCH_PERST_N")
	)
	(segment
		(start 386.159502 -90.695526)
		(end 386.120132 -90.695526)
		(width 0.10795)
		(layer "F.Cu")
		(net "RST_PCIE_PCH_PERST_N")
	)
	(segment
		(start 386.233162 -92.539566)
		(end 386.387848 -92.694252)
		(width 0.0889)
		(layer "F.Cu")
		(net "RST_PCIE_PCH_PERST_N")
	)
	(segment
		(start 386.294376 -93.171772)
		(end 386.280406 -93.185742)
		(width 0.0889)
		(layer "F.Cu")
		(net "RST_PCIE_PCH_PERST_N")
	)
	(segment
		(start 386.051806 -92.36329)
		(end 386.228082 -92.539566)
		(width 0.0889)
		(layer "F.Cu")
		(net "RST_PCIE_PCH_PERST_N")
	)
	(segment
		(start 386.228082 -92.539566)
		(end 386.233162 -92.539566)
		(width 0.0889)
		(layer "F.Cu")
		(net "RST_PCIE_PCH_PERST_N")
	)
	(segment
		(start 382.778762 -69.151246)
		(end 382.465072 -69.151246)
		(width 0.10795)
		(layer "F.Cu")
		(net "RST_PCIE_PCH_PERST_N")
	)
	(segment
		(start 386.484876 -94.427802)
		(end 386.484876 -94.790006)
		(width 0.0889)
		(layer "F.Cu")
		(net "RST_PCIE_PCH_PERST_N")
	)
	(segment
		(start 386.051806 -90.763852)
		(end 386.051806 -92.36329)
		(width 0.10795)
		(layer "F.Cu")
		(net "RST_PCIE_PCH_PERST_N")
	)
	(segment
		(start 386.387848 -92.694252)
		(end 386.387848 -93.077538)
		(width 0.0889)
		(layer "F.Cu")
		(net "RST_PCIE_PCH_PERST_N")
	)
	(via
		(at 386.159502 -90.695526)
		(size 0.508)
		(drill 0.254)
		(layers "F.Cu" "B.Cu")
		(net "RST_PCIE_PCH_PERST_N")
	)
	(via
		(at 382.778762 -69.151246)
		(size 0.508)
		(drill 0.254)
		(layers "F.Cu" "B.Cu")
		(net "RST_PCIE_PCH_PERST_N")
	)
	(via
		(at 382.397 -68.453)
		(size 0.6604)
		(drill 0.3302)
		(layers "F.Cu" "B.Cu")
		(net "RST_PCIE_PCH_PERST_N")
	)
	(segment
		(start 382.61036 -68.982844)
		(end 382.61036 -68.66636)
		(width 0.10795)
		(layer "B.Cu")
		(net "RST_PCIE_PCH_PERST_N")
	)
	(segment
		(start 382.61036 -68.66636)
		(end 382.397 -68.453)
		(width 0.10795)
		(layer "B.Cu")
		(net "RST_PCIE_PCH_PERST_N")
	)
	(segment
		(start 382.778762 -69.151246)
		(end 382.61036 -68.982844)
		(width 0.10795)
		(layer "B.Cu")
		(net "RST_PCIE_PCH_PERST_N")
	)
	(segment
		(start 386.120132 -90.695526)
		(end 386.159502 -90.695526)
		(width 0.089408)
		(layer "In11.Cu")
		(net "RST_PCIE_PCH_PERST_N")
	)
	(segment
		(start 383.012188 -73.820274)
		(end 383.012188 -76.444856)
		(width 0.089408)
		(layer "In11.Cu")
		(net "RST_PCIE_PCH_PERST_N")
	)
	(segment
		(start 385.940808 -85.960712)
		(end 385.902962 -85.998558)
		(width 0.089408)
		(layer "In11.Cu")
		(net "RST_PCIE_PCH_PERST_N")
	)
	(segment
		(start 383.292096 -78.777846)
		(end 382.747266 -79.322676)
		(width 0.089408)
		(layer "In11.Cu")
		(net "RST_PCIE_PCH_PERST_N")
	)
	(segment
		(start 383.959608 -81.049114)
		(end 383.959608 -82.233008)
		(width 0.089408)
		(layer "In11.Cu")
		(net "RST_PCIE_PCH_PERST_N")
	)
	(segment
		(start 385.940808 -83.053428)
		(end 385.940808 -85.960712)
		(width 0.089408)
		(layer "In11.Cu")
		(net "RST_PCIE_PCH_PERST_N")
	)
	(segment
		(start 385.902962 -86.03869)
		(end 384.891534 -87.050118)
		(width 0.089408)
		(layer "In11.Cu")
		(net "RST_PCIE_PCH_PERST_N")
	)
	(segment
		(start 382.731518 -69.19849)
		(end 382.731518 -73.539604)
		(width 0.089408)
		(layer "In11.Cu")
		(net "RST_PCIE_PCH_PERST_N")
	)
	(segment
		(start 382.747266 -79.678276)
		(end 383.959862 -80.890872)
		(width 0.089408)
		(layer "In11.Cu")
		(net "RST_PCIE_PCH_PERST_N")
	)
	(segment
		(start 382.778762 -69.151246)
		(end 382.731518 -69.19849)
		(width 0.089408)
		(layer "In11.Cu")
		(net "RST_PCIE_PCH_PERST_N")
	)
	(segment
		(start 385.902962 -85.998558)
		(end 385.902962 -86.03869)
		(width 0.089408)
		(layer "In11.Cu")
		(net "RST_PCIE_PCH_PERST_N")
	)
	(segment
		(start 382.747266 -79.322676)
		(end 382.747266 -79.678276)
		(width 0.089408)
		(layer "In11.Cu")
		(net "RST_PCIE_PCH_PERST_N")
	)
	(segment
		(start 385.40944 -82.52206)
		(end 385.940808 -83.053428)
		(width 0.089408)
		(layer "In11.Cu")
		(net "RST_PCIE_PCH_PERST_N")
	)
	(segment
		(start 384.891534 -89.466928)
		(end 386.120132 -90.695526)
		(width 0.089408)
		(layer "In11.Cu")
		(net "RST_PCIE_PCH_PERST_N")
	)
	(segment
		(start 383.959862 -81.04886)
		(end 383.959608 -81.049114)
		(width 0.089408)
		(layer "In11.Cu")
		(net "RST_PCIE_PCH_PERST_N")
	)
	(segment
		(start 384.891534 -87.050118)
		(end 384.891534 -89.466928)
		(width 0.089408)
		(layer "In11.Cu")
		(net "RST_PCIE_PCH_PERST_N")
	)
	(segment
		(start 383.959608 -82.233008)
		(end 384.24866 -82.52206)
		(width 0.089408)
		(layer "In11.Cu")
		(net "RST_PCIE_PCH_PERST_N")
	)
	(segment
		(start 383.959862 -80.890872)
		(end 383.959862 -81.04886)
		(width 0.089408)
		(layer "In11.Cu")
		(net "RST_PCIE_PCH_PERST_N")
	)
	(segment
		(start 382.731518 -73.539604)
		(end 383.012188 -73.820274)
		(width 0.089408)
		(layer "In11.Cu")
		(net "RST_PCIE_PCH_PERST_N")
	)
	(segment
		(start 383.292096 -76.724764)
		(end 383.292096 -78.777846)
		(width 0.089408)
		(layer "In11.Cu")
		(net "RST_PCIE_PCH_PERST_N")
	)
	(segment
		(start 383.012188 -76.444856)
		(end 383.292096 -76.724764)
		(width 0.089408)
		(layer "In11.Cu")
		(net "RST_PCIE_PCH_PERST_N")
	)
	(segment
		(start 384.24866 -82.52206)
		(end 385.40944 -82.52206)
		(width 0.089408)
		(layer "In11.Cu")
		(net "RST_PCIE_PCH_PERST_N")
	)
	(segment
		(start 377.145042 -77.095096)
		(end 377.544838 -77.494892)
		(width 0.10795)
		(layer "F.Cu")
		(net "RST_PCIE_RISER1_PERST_N")
	)
	(via
		(at 478.62236 -55.337964)
		(size 0.508)
		(drill 0.254)
		(layers "F.Cu" "B.Cu")
		(net "RST_PCIE_RISER1_PERST_N")
	)
	(via
		(at 473.635324 -8.830564)
		(size 0.6604)
		(drill 0.3302)
		(layers "F.Cu" "B.Cu")
		(net "RST_PCIE_RISER1_PERST_N")
	)
	(via
		(at 468.236046 -62.08395)
		(size 0.508)
		(drill 0.254)
		(layers "F.Cu" "B.Cu")
		(net "RST_PCIE_RISER1_PERST_N")
	)
	(via
		(at 474.375226 -10.103866)
		(size 0.508)
		(drill 0.254)
		(layers "F.Cu" "B.Cu")
		(net "RST_PCIE_RISER1_PERST_N")
	)
	(via
		(at 377.544838 -77.494892)
		(size 0.4572)
		(drill 0.2032)
		(layers "F.Cu" "B.Cu")
		(net "RST_PCIE_RISER1_PERST_N")
	)
	(via
		(at 428.866554 -63.427864)
		(size 0.508)
		(drill 0.254)
		(layers "F.Cu" "B.Cu")
		(net "RST_PCIE_RISER1_PERST_N")
	)
	(segment
		(start 466.122512 -8.83666)
		(end 466.666072 -8.2931)
		(width 0.10795)
		(layer "B.Cu")
		(net "RST_PCIE_RISER1_PERST_N")
	)
	(segment
		(start 473.635324 -8.830564)
		(end 474.375226 -9.570466)
		(width 0.10795)
		(layer "B.Cu")
		(net "RST_PCIE_RISER1_PERST_N")
	)
	(segment
		(start 462.8896 -7.1628)
		(end 462.8896 -8.4582)
		(width 0.10795)
		(layer "B.Cu")
		(net "RST_PCIE_RISER1_PERST_N")
	)
	(segment
		(start 464.084162 -8.591042)
		(end 464.32978 -8.83666)
		(width 0.10795)
		(layer "B.Cu")
		(net "RST_PCIE_RISER1_PERST_N")
	)
	(segment
		(start 464.32978 -8.83666)
		(end 466.122512 -8.83666)
		(width 0.10795)
		(layer "B.Cu")
		(net "RST_PCIE_RISER1_PERST_N")
	)
	(segment
		(start 473.09786 -8.2931)
		(end 473.635324 -8.830564)
		(width 0.10795)
		(layer "B.Cu")
		(net "RST_PCIE_RISER1_PERST_N")
	)
	(segment
		(start 474.375226 -9.570466)
		(end 474.375226 -10.103866)
		(width 0.10795)
		(layer "B.Cu")
		(net "RST_PCIE_RISER1_PERST_N")
	)
	(segment
		(start 462.8896 -8.4582)
		(end 463.022442 -8.591042)
		(width 0.10795)
		(layer "B.Cu")
		(net "RST_PCIE_RISER1_PERST_N")
	)
	(segment
		(start 466.666072 -8.2931)
		(end 473.09786 -8.2931)
		(width 0.10795)
		(layer "B.Cu")
		(net "RST_PCIE_RISER1_PERST_N")
	)
	(segment
		(start 463.022442 -8.591042)
		(end 464.084162 -8.591042)
		(width 0.10795)
		(layer "B.Cu")
		(net "RST_PCIE_RISER1_PERST_N")
	)
	(segment
		(start 478.62236 -55.337964)
		(end 478.018602 -55.337964)
		(width 0.089408)
		(layer "In2.Cu")
		(net "RST_PCIE_RISER1_PERST_N")
	)
	(segment
		(start 477.473772 -55.882794)
		(end 472.564206 -55.882794)
		(width 0.089408)
		(layer "In2.Cu")
		(net "RST_PCIE_RISER1_PERST_N")
	)
	(segment
		(start 472.564206 -55.882794)
		(end 469.236298 -59.210702)
		(width 0.089408)
		(layer "In2.Cu")
		(net "RST_PCIE_RISER1_PERST_N")
	)
	(segment
		(start 469.236298 -61.083698)
		(end 468.236046 -62.08395)
		(width 0.089408)
		(layer "In2.Cu")
		(net "RST_PCIE_RISER1_PERST_N")
	)
	(segment
		(start 478.018602 -55.337964)
		(end 477.473772 -55.882794)
		(width 0.089408)
		(layer "In2.Cu")
		(net "RST_PCIE_RISER1_PERST_N")
	)
	(segment
		(start 469.236298 -59.210702)
		(end 469.236298 -61.083698)
		(width 0.089408)
		(layer "In2.Cu")
		(net "RST_PCIE_RISER1_PERST_N")
	)
	(segment
		(start 378.68098 -77.69098)
		(end 378.484892 -77.494892)
		(width 0.089408)
		(layer "In4.Cu")
		(net "RST_PCIE_RISER1_PERST_N")
	)
	(segment
		(start 414.049464 -70.206616)
		(end 413.970978 -70.206616)
		(width 0.089408)
		(layer "In4.Cu")
		(net "RST_PCIE_RISER1_PERST_N")
	)
	(segment
		(start 399.463514 -74.28484)
		(end 398.49298 -74.28484)
		(width 0.089408)
		(layer "In4.Cu")
		(net "RST_PCIE_RISER1_PERST_N")
	)
	(segment
		(start 417.237926 -68.183252)
		(end 416.021266 -69.399912)
		(width 0.089408)
		(layer "In4.Cu")
		(net "RST_PCIE_RISER1_PERST_N")
	)
	(segment
		(start 395.489176 -75.604624)
		(end 394.66774 -75.604624)
		(width 0.089408)
		(layer "In4.Cu")
		(net "RST_PCIE_RISER1_PERST_N")
	)
	(segment
		(start 380.212092 -76.617576)
		(end 379.992382 -76.837286)
		(width 0.089408)
		(layer "In4.Cu")
		(net "RST_PCIE_RISER1_PERST_N")
	)
	(segment
		(start 396.059914 -75.033886)
		(end 395.489176 -75.604624)
		(width 0.089408)
		(layer "In4.Cu")
		(net "RST_PCIE_RISER1_PERST_N")
	)
	(segment
		(start 428.866554 -63.787528)
		(end 428.595028 -64.059054)
		(width 0.089408)
		(layer "In4.Cu")
		(net "RST_PCIE_RISER1_PERST_N")
	)
	(segment
		(start 402.589746 -72.722994)
		(end 402.15058 -73.16216)
		(width 0.089408)
		(layer "In4.Cu")
		(net "RST_PCIE_RISER1_PERST_N")
	)
	(segment
		(start 417.237926 -67.273932)
		(end 417.237926 -68.183252)
		(width 0.089408)
		(layer "In4.Cu")
		(net "RST_PCIE_RISER1_PERST_N")
	)
	(segment
		(start 420.469314 -64.042544)
		(end 417.237926 -67.273932)
		(width 0.089408)
		(layer "In4.Cu")
		(net "RST_PCIE_RISER1_PERST_N")
	)
	(segment
		(start 413.970978 -70.206616)
		(end 412.168594 -72.009)
		(width 0.089408)
		(layer "In4.Cu")
		(net "RST_PCIE_RISER1_PERST_N")
	)
	(segment
		(start 428.595028 -64.059054)
		(end 426.226986 -64.059054)
		(width 0.089408)
		(layer "In4.Cu")
		(net "RST_PCIE_RISER1_PERST_N")
	)
	(segment
		(start 414.565338 -70.207124)
		(end 414.40735 -70.207124)
		(width 0.089408)
		(layer "In4.Cu")
		(net "RST_PCIE_RISER1_PERST_N")
	)
	(segment
		(start 380.532386 -76.627228)
		(end 380.522734 -76.617576)
		(width 0.089408)
		(layer "In4.Cu")
		(net "RST_PCIE_RISER1_PERST_N")
	)
	(segment
		(start 414.613598 -70.206362)
		(end 414.5661 -70.206362)
		(width 0.089408)
		(layer "In4.Cu")
		(net "RST_PCIE_RISER1_PERST_N")
	)
	(segment
		(start 391.731754 -76.164694)
		(end 381.562356 -76.164694)
		(width 0.089408)
		(layer "In4.Cu")
		(net "RST_PCIE_RISER1_PERST_N")
	)
	(segment
		(start 409.43022 -72.009)
		(end 409.2067 -72.23252)
		(width 0.089408)
		(layer "In4.Cu")
		(net "RST_PCIE_RISER1_PERST_N")
	)
	(segment
		(start 379.992382 -76.837286)
		(end 379.992382 -77.202284)
		(width 0.089408)
		(layer "In4.Cu")
		(net "RST_PCIE_RISER1_PERST_N")
	)
	(segment
		(start 416.021266 -69.399912)
		(end 415.420048 -69.399912)
		(width 0.089408)
		(layer "In4.Cu")
		(net "RST_PCIE_RISER1_PERST_N")
	)
	(segment
		(start 406.024588 -72.723248)
		(end 406.024334 -72.722994)
		(width 0.089408)
		(layer "In4.Cu")
		(net "RST_PCIE_RISER1_PERST_N")
	)
	(segment
		(start 393.061952 -74.834496)
		(end 391.731754 -76.164694)
		(width 0.089408)
		(layer "In4.Cu")
		(net "RST_PCIE_RISER1_PERST_N")
	)
	(segment
		(start 414.407096 -70.20687)
		(end 414.049718 -70.20687)
		(width 0.089408)
		(layer "In4.Cu")
		(net "RST_PCIE_RISER1_PERST_N")
	)
	(segment
		(start 400.586194 -73.16216)
		(end 399.463514 -74.28484)
		(width 0.089408)
		(layer "In4.Cu")
		(net "RST_PCIE_RISER1_PERST_N")
	)
	(segment
		(start 422.47185 -64.042544)
		(end 420.469314 -64.042544)
		(width 0.089408)
		(layer "In4.Cu")
		(net "RST_PCIE_RISER1_PERST_N")
	)
	(segment
		(start 379.503686 -77.69098)
		(end 378.68098 -77.69098)
		(width 0.089408)
		(layer "In4.Cu")
		(net "RST_PCIE_RISER1_PERST_N")
	)
	(segment
		(start 412.168594 -72.009)
		(end 409.43022 -72.009)
		(width 0.089408)
		(layer "In4.Cu")
		(net "RST_PCIE_RISER1_PERST_N")
	)
	(segment
		(start 394.3096 -75.075034)
		(end 394.069062 -74.834496)
		(width 0.089408)
		(layer "In4.Cu")
		(net "RST_PCIE_RISER1_PERST_N")
	)
	(segment
		(start 379.992382 -77.202284)
		(end 379.503686 -77.69098)
		(width 0.089408)
		(layer "In4.Cu")
		(net "RST_PCIE_RISER1_PERST_N")
	)
	(segment
		(start 406.024334 -72.722994)
		(end 402.589746 -72.722994)
		(width 0.089408)
		(layer "In4.Cu")
		(net "RST_PCIE_RISER1_PERST_N")
	)
	(segment
		(start 402.15058 -73.16216)
		(end 400.586194 -73.16216)
		(width 0.089408)
		(layer "In4.Cu")
		(net "RST_PCIE_RISER1_PERST_N")
	)
	(segment
		(start 414.5661 -70.206362)
		(end 414.565338 -70.207124)
		(width 0.089408)
		(layer "In4.Cu")
		(net "RST_PCIE_RISER1_PERST_N")
	)
	(segment
		(start 406.341072 -72.723248)
		(end 406.024588 -72.723248)
		(width 0.089408)
		(layer "In4.Cu")
		(net "RST_PCIE_RISER1_PERST_N")
	)
	(segment
		(start 398.49298 -74.28484)
		(end 397.743934 -75.033886)
		(width 0.089408)
		(layer "In4.Cu")
		(net "RST_PCIE_RISER1_PERST_N")
	)
	(segment
		(start 406.8318 -72.23252)
		(end 406.341072 -72.723248)
		(width 0.089408)
		(layer "In4.Cu")
		(net "RST_PCIE_RISER1_PERST_N")
	)
	(segment
		(start 381.562356 -76.164694)
		(end 381.099822 -76.627228)
		(width 0.089408)
		(layer "In4.Cu")
		(net "RST_PCIE_RISER1_PERST_N")
	)
	(segment
		(start 409.2067 -72.23252)
		(end 406.8318 -72.23252)
		(width 0.089408)
		(layer "In4.Cu")
		(net "RST_PCIE_RISER1_PERST_N")
	)
	(segment
		(start 378.484892 -77.494892)
		(end 377.544838 -77.494892)
		(width 0.089408)
		(layer "In4.Cu")
		(net "RST_PCIE_RISER1_PERST_N")
	)
	(segment
		(start 394.069062 -74.834496)
		(end 393.061952 -74.834496)
		(width 0.089408)
		(layer "In4.Cu")
		(net "RST_PCIE_RISER1_PERST_N")
	)
	(segment
		(start 414.40735 -70.207124)
		(end 414.407096 -70.20687)
		(width 0.089408)
		(layer "In4.Cu")
		(net "RST_PCIE_RISER1_PERST_N")
	)
	(segment
		(start 428.866554 -63.427864)
		(end 428.866554 -63.787528)
		(width 0.089408)
		(layer "In4.Cu")
		(net "RST_PCIE_RISER1_PERST_N")
	)
	(segment
		(start 394.3096 -75.246484)
		(end 394.3096 -75.075034)
		(width 0.089408)
		(layer "In4.Cu")
		(net "RST_PCIE_RISER1_PERST_N")
	)
	(segment
		(start 381.099822 -76.627228)
		(end 380.532386 -76.627228)
		(width 0.089408)
		(layer "In4.Cu")
		(net "RST_PCIE_RISER1_PERST_N")
	)
	(segment
		(start 380.522734 -76.617576)
		(end 380.212092 -76.617576)
		(width 0.089408)
		(layer "In4.Cu")
		(net "RST_PCIE_RISER1_PERST_N")
	)
	(segment
		(start 426.226986 -64.059054)
		(end 425.563538 -63.395606)
		(width 0.089408)
		(layer "In4.Cu")
		(net "RST_PCIE_RISER1_PERST_N")
	)
	(segment
		(start 415.420048 -69.399912)
		(end 414.613598 -70.206362)
		(width 0.089408)
		(layer "In4.Cu")
		(net "RST_PCIE_RISER1_PERST_N")
	)
	(segment
		(start 397.743934 -75.033886)
		(end 396.059914 -75.033886)
		(width 0.089408)
		(layer "In4.Cu")
		(net "RST_PCIE_RISER1_PERST_N")
	)
	(segment
		(start 414.049718 -70.20687)
		(end 414.049464 -70.206616)
		(width 0.089408)
		(layer "In4.Cu")
		(net "RST_PCIE_RISER1_PERST_N")
	)
	(segment
		(start 423.118788 -63.395606)
		(end 422.47185 -64.042544)
		(width 0.089408)
		(layer "In4.Cu")
		(net "RST_PCIE_RISER1_PERST_N")
	)
	(segment
		(start 394.66774 -75.604624)
		(end 394.3096 -75.246484)
		(width 0.089408)
		(layer "In4.Cu")
		(net "RST_PCIE_RISER1_PERST_N")
	)
	(segment
		(start 425.563538 -63.395606)
		(end 423.118788 -63.395606)
		(width 0.089408)
		(layer "In4.Cu")
		(net "RST_PCIE_RISER1_PERST_N")
	)
	(segment
		(start 430.736248 -64.290448)
		(end 462.679034 -64.290448)
		(width 0.089408)
		(layer "In9.Cu")
		(net "RST_PCIE_RISER1_PERST_N")
	)
	(segment
		(start 463.641948 -62.682374)
		(end 467.637622 -62.682374)
		(width 0.089408)
		(layer "In9.Cu")
		(net "RST_PCIE_RISER1_PERST_N")
	)
	(segment
		(start 429.812704 -63.366904)
		(end 430.736248 -64.290448)
		(width 0.089408)
		(layer "In9.Cu")
		(net "RST_PCIE_RISER1_PERST_N")
	)
	(segment
		(start 428.927514 -63.366904)
		(end 429.812704 -63.366904)
		(width 0.089408)
		(layer "In9.Cu")
		(net "RST_PCIE_RISER1_PERST_N")
	)
	(segment
		(start 467.637622 -62.682374)
		(end 468.236046 -62.08395)
		(width 0.089408)
		(layer "In9.Cu")
		(net "RST_PCIE_RISER1_PERST_N")
	)
	(segment
		(start 462.679034 -64.290448)
		(end 462.971896 -63.997586)
		(width 0.089408)
		(layer "In9.Cu")
		(net "RST_PCIE_RISER1_PERST_N")
	)
	(segment
		(start 428.866554 -63.427864)
		(end 428.927514 -63.366904)
		(width 0.089408)
		(layer "In9.Cu")
		(net "RST_PCIE_RISER1_PERST_N")
	)
	(segment
		(start 462.971896 -63.352426)
		(end 463.641948 -62.682374)
		(width 0.089408)
		(layer "In9.Cu")
		(net "RST_PCIE_RISER1_PERST_N")
	)
	(segment
		(start 462.971896 -63.997586)
		(end 462.971896 -63.352426)
		(width 0.089408)
		(layer "In9.Cu")
		(net "RST_PCIE_RISER1_PERST_N")
	)
	(segment
		(start 475.31274 -34.068004)
		(end 475.31274 -32.365188)
		(width 0.089408)
		(layer "In11.Cu")
		(net "RST_PCIE_RISER1_PERST_N")
	)
	(segment
		(start 465.964016 -19.99361)
		(end 464.765136 -18.79473)
		(width 0.089408)
		(layer "In11.Cu")
		(net "RST_PCIE_RISER1_PERST_N")
	)
	(segment
		(start 478.62236 -55.337964)
		(end 478.030286 -54.74589)
		(width 0.089408)
		(layer "In11.Cu")
		(net "RST_PCIE_RISER1_PERST_N")
	)
	(segment
		(start 478.030286 -54.74589)
		(end 478.030286 -52.227226)
		(width 0.089408)
		(layer "In11.Cu")
		(net "RST_PCIE_RISER1_PERST_N")
	)
	(segment
		(start 464.765136 -18.79473)
		(end 464.765136 -16.183864)
		(width 0.089408)
		(layer "In11.Cu")
		(net "RST_PCIE_RISER1_PERST_N")
	)
	(segment
		(start 475.766638 -39.937944)
		(end 475.766638 -37.964364)
		(width 0.089408)
		(layer "In11.Cu")
		(net "RST_PCIE_RISER1_PERST_N")
	)
	(segment
		(start 469.226138 -13.950696)
		(end 471.18778 -13.950696)
		(width 0.089408)
		(layer "In11.Cu")
		(net "RST_PCIE_RISER1_PERST_N")
	)
	(segment
		(start 475.31274 -32.365188)
		(end 475.312232 -32.36468)
		(width 0.089408)
		(layer "In11.Cu")
		(net "RST_PCIE_RISER1_PERST_N")
	)
	(segment
		(start 471.329258 -25.88641)
		(end 468.195406 -25.88641)
		(width 0.089408)
		(layer "In11.Cu")
		(net "RST_PCIE_RISER1_PERST_N")
	)
	(segment
		(start 475.107 -46.454822)
		(end 475.107 -44.2976)
		(width 0.089408)
		(layer "In11.Cu")
		(net "RST_PCIE_RISER1_PERST_N")
	)
	(segment
		(start 471.18778 -13.950696)
		(end 473.926916 -11.21156)
		(width 0.089408)
		(layer "In11.Cu")
		(net "RST_PCIE_RISER1_PERST_N")
	)
	(segment
		(start 474.375226 -10.391902)
		(end 474.375226 -10.103866)
		(width 0.089408)
		(layer "In11.Cu")
		(net "RST_PCIE_RISER1_PERST_N")
	)
	(segment
		(start 473.926916 -10.840212)
		(end 474.375226 -10.391902)
		(width 0.089408)
		(layer "In11.Cu")
		(net "RST_PCIE_RISER1_PERST_N")
	)
	(segment
		(start 475.107 -44.2976)
		(end 475.85249 -43.55211)
		(width 0.089408)
		(layer "In11.Cu")
		(net "RST_PCIE_RISER1_PERST_N")
	)
	(segment
		(start 478.030286 -52.227226)
		(end 476.972376 -51.169316)
		(width 0.089408)
		(layer "In11.Cu")
		(net "RST_PCIE_RISER1_PERST_N")
	)
	(segment
		(start 475.766638 -37.964364)
		(end 476.148654 -37.582348)
		(width 0.089408)
		(layer "In11.Cu")
		(net "RST_PCIE_RISER1_PERST_N")
	)
	(segment
		(start 475.85249 -43.55211)
		(end 475.85249 -40.023796)
		(width 0.089408)
		(layer "In11.Cu")
		(net "RST_PCIE_RISER1_PERST_N")
	)
	(segment
		(start 465.911184 -15.037816)
		(end 468.139018 -15.037816)
		(width 0.089408)
		(layer "In11.Cu")
		(net "RST_PCIE_RISER1_PERST_N")
	)
	(segment
		(start 475.85249 -40.023796)
		(end 475.766638 -39.937944)
		(width 0.089408)
		(layer "In11.Cu")
		(net "RST_PCIE_RISER1_PERST_N")
	)
	(segment
		(start 464.765136 -16.183864)
		(end 465.911184 -15.037816)
		(width 0.089408)
		(layer "In11.Cu")
		(net "RST_PCIE_RISER1_PERST_N")
	)
	(segment
		(start 468.139018 -15.037816)
		(end 469.226138 -13.950696)
		(width 0.089408)
		(layer "In11.Cu")
		(net "RST_PCIE_RISER1_PERST_N")
	)
	(segment
		(start 475.312232 -29.869384)
		(end 471.329258 -25.88641)
		(width 0.089408)
		(layer "In11.Cu")
		(net "RST_PCIE_RISER1_PERST_N")
	)
	(segment
		(start 476.972376 -48.320198)
		(end 475.107 -46.454822)
		(width 0.089408)
		(layer "In11.Cu")
		(net "RST_PCIE_RISER1_PERST_N")
	)
	(segment
		(start 473.926916 -11.21156)
		(end 473.926916 -10.840212)
		(width 0.089408)
		(layer "In11.Cu")
		(net "RST_PCIE_RISER1_PERST_N")
	)
	(segment
		(start 476.972376 -51.169316)
		(end 476.972376 -48.320198)
		(width 0.089408)
		(layer "In11.Cu")
		(net "RST_PCIE_RISER1_PERST_N")
	)
	(segment
		(start 476.148654 -34.903918)
		(end 475.31274 -34.068004)
		(width 0.089408)
		(layer "In11.Cu")
		(net "RST_PCIE_RISER1_PERST_N")
	)
	(segment
		(start 476.148654 -37.582348)
		(end 476.148654 -34.903918)
		(width 0.089408)
		(layer "In11.Cu")
		(net "RST_PCIE_RISER1_PERST_N")
	)
	(segment
		(start 475.312232 -32.36468)
		(end 475.312232 -29.869384)
		(width 0.089408)
		(layer "In11.Cu")
		(net "RST_PCIE_RISER1_PERST_N")
	)
	(segment
		(start 468.195406 -25.88641)
		(end 465.964016 -23.65502)
		(width 0.089408)
		(layer "In11.Cu")
		(net "RST_PCIE_RISER1_PERST_N")
	)
	(segment
		(start 465.964016 -23.65502)
		(end 465.964016 -19.99361)
		(width 0.089408)
		(layer "In11.Cu")
		(net "RST_PCIE_RISER1_PERST_N")
	)
	(segment
		(start 374.842532 -99.56927)
		(end 373.49303 -99.56927)
		(width 0.0889)
		(layer "F.Cu")
		(net "FM_PCH_PWRBTN_N")
	)
	(segment
		(start 375.322592 -99.672648)
		(end 374.94591 -99.672648)
		(width 0.0889)
		(layer "F.Cu")
		(net "FM_PCH_PWRBTN_N")
	)
	(segment
		(start 375.504964 -99.85502)
		(end 375.322592 -99.672648)
		(width 0.0889)
		(layer "F.Cu")
		(net "FM_PCH_PWRBTN_N")
	)
	(segment
		(start 374.94591 -99.672648)
		(end 374.842532 -99.56927)
		(width 0.0889)
		(layer "F.Cu")
		(net "FM_PCH_PWRBTN_N")
	)
	(segment
		(start 373.49303 -99.56927)
		(end 373.4054 -99.6569)
		(width 0.0889)
		(layer "F.Cu")
		(net "FM_PCH_PWRBTN_N")
	)
	(via
		(at 369.330224 -67.606926)
		(size 0.508)
		(drill 0.254)
		(layers "F.Cu" "B.Cu")
		(net "FM_PCH_PWRBTN_N")
	)
	(via
		(at 397.029432 -32.111442)
		(size 0.508)
		(drill 0.254)
		(layers "F.Cu" "B.Cu")
		(net "FM_PCH_PWRBTN_N")
	)
	(via
		(at 373.4054 -99.6569)
		(size 0.508)
		(drill 0.254)
		(layers "F.Cu" "B.Cu")
		(net "FM_PCH_PWRBTN_N")
	)
	(via
		(at 386.1181 -32.4104)
		(size 0.508)
		(drill 0.254)
		(layers "F.Cu" "B.Cu")
		(net "FM_PCH_PWRBTN_N")
	)
	(segment
		(start 369.777518 -67.159632)
		(end 369.330224 -67.606926)
		(width 0.10795)
		(layer "B.Cu")
		(net "FM_PCH_PWRBTN_N")
	)
	(segment
		(start 396.674086 -31.516574)
		(end 396.674086 -31.756096)
		(width 0.10795)
		(layer "B.Cu")
		(net "FM_PCH_PWRBTN_N")
	)
	(segment
		(start 396.674086 -31.756096)
		(end 397.029432 -32.111442)
		(width 0.10795)
		(layer "B.Cu")
		(net "FM_PCH_PWRBTN_N")
	)
	(segment
		(start 370.334794 -67.159632)
		(end 369.777518 -67.159632)
		(width 0.10795)
		(layer "B.Cu")
		(net "FM_PCH_PWRBTN_N")
	)
	(segment
		(start 384.071876 -36.872672)
		(end 383.630678 -36.872672)
		(width 0.089408)
		(layer "In2.Cu")
		(net "FM_PCH_PWRBTN_N")
	)
	(segment
		(start 380.763018 -40.427656)
		(end 381.302006 -40.966644)
		(width 0.089408)
		(layer "In2.Cu")
		(net "FM_PCH_PWRBTN_N")
	)
	(segment
		(start 381.156464 -45.197268)
		(end 379.62459 -46.729142)
		(width 0.089408)
		(layer "In2.Cu")
		(net "FM_PCH_PWRBTN_N")
	)
	(segment
		(start 379.181614 -60.525914)
		(end 378.491496 -61.216032)
		(width 0.089408)
		(layer "In2.Cu")
		(net "FM_PCH_PWRBTN_N")
	)
	(segment
		(start 370.9543 -65.717166)
		(end 369.330224 -67.341242)
		(width 0.089408)
		(layer "In2.Cu")
		(net "FM_PCH_PWRBTN_N")
	)
	(segment
		(start 381.302006 -40.966644)
		(end 381.302006 -41.56583)
		(width 0.089408)
		(layer "In2.Cu")
		(net "FM_PCH_PWRBTN_N")
	)
	(segment
		(start 372.93804 -65.717166)
		(end 370.9543 -65.717166)
		(width 0.089408)
		(layer "In2.Cu")
		(net "FM_PCH_PWRBTN_N")
	)
	(segment
		(start 380.89967 -38.318694)
		(end 380.763018 -38.455346)
		(width 0.089408)
		(layer "In2.Cu")
		(net "FM_PCH_PWRBTN_N")
	)
	(segment
		(start 381.156464 -41.711372)
		(end 381.156464 -45.197268)
		(width 0.089408)
		(layer "In2.Cu")
		(net "FM_PCH_PWRBTN_N")
	)
	(segment
		(start 379.52426 -56.275986)
		(end 379.52426 -56.502808)
		(width 0.089408)
		(layer "In2.Cu")
		(net "FM_PCH_PWRBTN_N")
	)
	(segment
		(start 378.491496 -63.200788)
		(end 377.063 -64.629284)
		(width 0.089408)
		(layer "In2.Cu")
		(net "FM_PCH_PWRBTN_N")
	)
	(segment
		(start 383.630678 -36.872672)
		(end 382.184656 -38.318694)
		(width 0.089408)
		(layer "In2.Cu")
		(net "FM_PCH_PWRBTN_N")
	)
	(segment
		(start 385.40182 -35.542728)
		(end 384.071876 -36.872672)
		(width 0.089408)
		(layer "In2.Cu")
		(net "FM_PCH_PWRBTN_N")
	)
	(segment
		(start 381.302006 -41.56583)
		(end 381.156464 -41.711372)
		(width 0.089408)
		(layer "In2.Cu")
		(net "FM_PCH_PWRBTN_N")
	)
	(segment
		(start 369.330224 -67.341242)
		(end 369.330224 -67.606926)
		(width 0.089408)
		(layer "In2.Cu")
		(net "FM_PCH_PWRBTN_N")
	)
	(segment
		(start 379.62459 -55.858664)
		(end 379.524006 -55.959248)
		(width 0.089408)
		(layer "In2.Cu")
		(net "FM_PCH_PWRBTN_N")
	)
	(segment
		(start 385.40182 -33.72612)
		(end 385.40182 -35.542728)
		(width 0.089408)
		(layer "In2.Cu")
		(net "FM_PCH_PWRBTN_N")
	)
	(segment
		(start 377.057412 -64.642746)
		(end 375.563638 -66.13652)
		(width 0.089408)
		(layer "In2.Cu")
		(net "FM_PCH_PWRBTN_N")
	)
	(segment
		(start 377.063 -64.629284)
		(end 377.057412 -64.642746)
		(width 0.089408)
		(layer "In2.Cu")
		(net "FM_PCH_PWRBTN_N")
	)
	(segment
		(start 375.563638 -66.13652)
		(end 373.357394 -66.13652)
		(width 0.089408)
		(layer "In2.Cu")
		(net "FM_PCH_PWRBTN_N")
	)
	(segment
		(start 378.491496 -61.216032)
		(end 378.491496 -63.200788)
		(width 0.089408)
		(layer "In2.Cu")
		(net "FM_PCH_PWRBTN_N")
	)
	(segment
		(start 386.1181 -32.4104)
		(end 385.7371 -32.4104)
		(width 0.089408)
		(layer "In2.Cu")
		(net "FM_PCH_PWRBTN_N")
	)
	(segment
		(start 382.184656 -38.318694)
		(end 380.89967 -38.318694)
		(width 0.089408)
		(layer "In2.Cu")
		(net "FM_PCH_PWRBTN_N")
	)
	(segment
		(start 373.357394 -66.13652)
		(end 372.93804 -65.717166)
		(width 0.089408)
		(layer "In2.Cu")
		(net "FM_PCH_PWRBTN_N")
	)
	(segment
		(start 385.7371 -32.4104)
		(end 385.2799 -32.8676)
		(width 0.089408)
		(layer "In2.Cu")
		(net "FM_PCH_PWRBTN_N")
	)
	(segment
		(start 379.181614 -56.845454)
		(end 379.181614 -60.525914)
		(width 0.089408)
		(layer "In2.Cu")
		(net "FM_PCH_PWRBTN_N")
	)
	(segment
		(start 379.62459 -46.729142)
		(end 379.62459 -55.858664)
		(width 0.089408)
		(layer "In2.Cu")
		(net "FM_PCH_PWRBTN_N")
	)
	(segment
		(start 379.52426 -56.502808)
		(end 379.181614 -56.845454)
		(width 0.089408)
		(layer "In2.Cu")
		(net "FM_PCH_PWRBTN_N")
	)
	(segment
		(start 385.2799 -33.6042)
		(end 385.40182 -33.72612)
		(width 0.089408)
		(layer "In2.Cu")
		(net "FM_PCH_PWRBTN_N")
	)
	(segment
		(start 385.2799 -32.8676)
		(end 385.2799 -33.6042)
		(width 0.089408)
		(layer "In2.Cu")
		(net "FM_PCH_PWRBTN_N")
	)
	(segment
		(start 379.524006 -56.275732)
		(end 379.52426 -56.275986)
		(width 0.089408)
		(layer "In2.Cu")
		(net "FM_PCH_PWRBTN_N")
	)
	(segment
		(start 379.524006 -55.959248)
		(end 379.524006 -56.275732)
		(width 0.089408)
		(layer "In2.Cu")
		(net "FM_PCH_PWRBTN_N")
	)
	(segment
		(start 380.763018 -38.455346)
		(end 380.763018 -40.427656)
		(width 0.089408)
		(layer "In2.Cu")
		(net "FM_PCH_PWRBTN_N")
	)
	(segment
		(start 397.029432 -32.111442)
		(end 396.208504 -32.93237)
		(width 0.089408)
		(layer "In4.Cu")
		(net "FM_PCH_PWRBTN_N")
	)
	(segment
		(start 395.944344 -33.198308)
		(end 394.759942 -33.198308)
		(width 0.089408)
		(layer "In4.Cu")
		(net "FM_PCH_PWRBTN_N")
	)
	(segment
		(start 396.208504 -32.93237)
		(end 396.208504 -32.934148)
		(width 0.089408)
		(layer "In4.Cu")
		(net "FM_PCH_PWRBTN_N")
	)
	(segment
		(start 394.21943 -32.657796)
		(end 389.641334 -32.657796)
		(width 0.089408)
		(layer "In4.Cu")
		(net "FM_PCH_PWRBTN_N")
	)
	(segment
		(start 394.759942 -33.198308)
		(end 394.21943 -32.657796)
		(width 0.089408)
		(layer "In4.Cu")
		(net "FM_PCH_PWRBTN_N")
	)
	(segment
		(start 389.509254 -32.525716)
		(end 386.233416 -32.525716)
		(width 0.089408)
		(layer "In4.Cu")
		(net "FM_PCH_PWRBTN_N")
	)
	(segment
		(start 386.233416 -32.525716)
		(end 386.1181 -32.4104)
		(width 0.089408)
		(layer "In4.Cu")
		(net "FM_PCH_PWRBTN_N")
	)
	(segment
		(start 396.208504 -32.934148)
		(end 395.944344 -33.198308)
		(width 0.089408)
		(layer "In4.Cu")
		(net "FM_PCH_PWRBTN_N")
	)
	(segment
		(start 389.641334 -32.657796)
		(end 389.509254 -32.525716)
		(width 0.089408)
		(layer "In4.Cu")
		(net "FM_PCH_PWRBTN_N")
	)
	(segment
		(start 372.35765 -98.60915)
		(end 371.98935 -98.60915)
		(width 0.089408)
		(layer "In11.Cu")
		(net "FM_PCH_PWRBTN_N")
	)
	(segment
		(start 365.042196 -83.326224)
		(end 365.042196 -79.82966)
		(width 0.089408)
		(layer "In11.Cu")
		(net "FM_PCH_PWRBTN_N")
	)
	(segment
		(start 365.380524 -68.331334)
		(end 366.190276 -67.521582)
		(width 0.089408)
		(layer "In11.Cu")
		(net "FM_PCH_PWRBTN_N")
	)
	(segment
		(start 365.531654 -72.818752)
		(end 365.380524 -72.667622)
		(width 0.089408)
		(layer "In11.Cu")
		(net "FM_PCH_PWRBTN_N")
	)
	(segment
		(start 371.323616 -97.73285)
		(end 370.180362 -96.589596)
		(width 0.089408)
		(layer "In11.Cu")
		(net "FM_PCH_PWRBTN_N")
	)
	(segment
		(start 368.9604 -93.354652)
		(end 365.887 -90.281252)
		(width 0.089408)
		(layer "In11.Cu")
		(net "FM_PCH_PWRBTN_N")
	)
	(segment
		(start 365.531654 -77.384656)
		(end 365.531654 -72.818752)
		(width 0.089408)
		(layer "In11.Cu")
		(net "FM_PCH_PWRBTN_N")
	)
	(segment
		(start 368.899694 -67.521582)
		(end 368.985038 -67.606926)
		(width 0.089408)
		(layer "In11.Cu")
		(net "FM_PCH_PWRBTN_N")
	)
	(segment
		(start 371.323616 -97.943416)
		(end 371.323616 -97.73285)
		(width 0.089408)
		(layer "In11.Cu")
		(net "FM_PCH_PWRBTN_N")
	)
	(segment
		(start 368.9604 -95.6818)
		(end 368.9604 -93.354652)
		(width 0.089408)
		(layer "In11.Cu")
		(net "FM_PCH_PWRBTN_N")
	)
	(segment
		(start 368.985038 -67.606926)
		(end 369.330224 -67.606926)
		(width 0.089408)
		(layer "In11.Cu")
		(net "FM_PCH_PWRBTN_N")
	)
	(segment
		(start 365.380524 -72.667622)
		(end 365.380524 -68.331334)
		(width 0.089408)
		(layer "In11.Cu")
		(net "FM_PCH_PWRBTN_N")
	)
	(segment
		(start 373.4054 -99.6569)
		(end 372.35765 -98.60915)
		(width 0.089408)
		(layer "In11.Cu")
		(net "FM_PCH_PWRBTN_N")
	)
	(segment
		(start 366.190276 -67.521582)
		(end 368.899694 -67.521582)
		(width 0.089408)
		(layer "In11.Cu")
		(net "FM_PCH_PWRBTN_N")
	)
	(segment
		(start 365.887 -84.171028)
		(end 365.042196 -83.326224)
		(width 0.089408)
		(layer "In11.Cu")
		(net "FM_PCH_PWRBTN_N")
	)
	(segment
		(start 365.887 -90.281252)
		(end 365.887 -84.171028)
		(width 0.089408)
		(layer "In11.Cu")
		(net "FM_PCH_PWRBTN_N")
	)
	(segment
		(start 365.042196 -79.82966)
		(end 365.531654 -77.384656)
		(width 0.089408)
		(layer "In11.Cu")
		(net "FM_PCH_PWRBTN_N")
	)
	(segment
		(start 370.180362 -96.589596)
		(end 369.868196 -96.589596)
		(width 0.089408)
		(layer "In11.Cu")
		(net "FM_PCH_PWRBTN_N")
	)
	(segment
		(start 371.98935 -98.60915)
		(end 371.323616 -97.943416)
		(width 0.089408)
		(layer "In11.Cu")
		(net "FM_PCH_PWRBTN_N")
	)
	(segment
		(start 369.868196 -96.589596)
		(end 368.9604 -95.6818)
		(width 0.089408)
		(layer "In11.Cu")
		(net "FM_PCH_PWRBTN_N")
	)
	(segment
		(start 173.331378 -96.310704)
		(end 173.331378 -97.3201)
		(width 0.10795)
		(layer "F.Cu")
		(net "PWRGD_CPU1_DRAMPWROK_KLM_G")
	)
	(segment
		(start 172.4152 -97.5614)
		(end 171.9326 -97.0788)
		(width 0.10795)
		(layer "F.Cu")
		(net "PWRGD_CPU1_DRAMPWROK_KLM_G")
	)
	(segment
		(start 173.331378 -97.3201)
		(end 173.090078 -97.5614)
		(width 0.10795)
		(layer "F.Cu")
		(net "PWRGD_CPU1_DRAMPWROK_KLM_G")
	)
	(segment
		(start 171.9326 -97.0788)
		(end 171.9326 -96.9772)
		(width 0.10795)
		(layer "F.Cu")
		(net "PWRGD_CPU1_DRAMPWROK_KLM_G")
	)
	(segment
		(start 173.090078 -97.5614)
		(end 172.4152 -97.5614)
		(width 0.10795)
		(layer "F.Cu")
		(net "PWRGD_CPU1_DRAMPWROK_KLM_G")
	)
	(segment
		(start 119.070882 -88.099138)
		(end 119.642382 -88.099138)
		(width 0.1016)
		(layer "F.Cu")
		(net "PWRGD_CPU1_DRAMPWROK_KLM_G")
	)
	(via
		(at 119.642382 -88.099138)
		(size 0.508)
		(drill 0.254)
		(layers "F.Cu" "B.Cu")
		(net "PWRGD_CPU1_DRAMPWROK_KLM_G")
	)
	(via
		(at 154.264106 -116.46916)
		(size 0.6604)
		(drill 0.3302)
		(layers "F.Cu" "B.Cu")
		(net "PWRGD_CPU1_DRAMPWROK_KLM_G")
	)
	(via
		(at 151.14778 -113.78438)
		(size 0.508)
		(drill 0.254)
		(layers "F.Cu" "B.Cu")
		(net "PWRGD_CPU1_DRAMPWROK_KLM_G")
	)
	(via
		(at 171.9326 -96.9772)
		(size 0.508)
		(drill 0.254)
		(layers "F.Cu" "B.Cu")
		(net "PWRGD_CPU1_DRAMPWROK_KLM_G")
	)
	(segment
		(start 155.525978 -119.384826)
		(end 155.525978 -117.731032)
		(width 0.10795)
		(layer "B.Cu")
		(net "PWRGD_CPU1_DRAMPWROK_KLM_G")
	)
	(segment
		(start 153.83256 -116.46916)
		(end 151.14778 -113.78438)
		(width 0.10795)
		(layer "B.Cu")
		(net "PWRGD_CPU1_DRAMPWROK_KLM_G")
	)
	(segment
		(start 154.264106 -116.46916)
		(end 153.83256 -116.46916)
		(width 0.10795)
		(layer "B.Cu")
		(net "PWRGD_CPU1_DRAMPWROK_KLM_G")
	)
	(segment
		(start 155.525978 -117.731032)
		(end 154.264106 -116.46916)
		(width 0.10795)
		(layer "B.Cu")
		(net "PWRGD_CPU1_DRAMPWROK_KLM_G")
	)
	(segment
		(start 132.747004 -91.167204)
		(end 132.174996 -91.167204)
		(width 0.089408)
		(layer "In4.Cu")
		(net "PWRGD_CPU1_DRAMPWROK_KLM_G")
	)
	(segment
		(start 149.133306 -114.368072)
		(end 143.529304 -108.76407)
		(width 0.089408)
		(layer "In4.Cu")
		(net "PWRGD_CPU1_DRAMPWROK_KLM_G")
	)
	(segment
		(start 131.872482 -91.469718)
		(end 131.322318 -91.469718)
		(width 0.089408)
		(layer "In4.Cu")
		(net "PWRGD_CPU1_DRAMPWROK_KLM_G")
	)
	(segment
		(start 127.044196 -91.167204)
		(end 126.741682 -91.469718)
		(width 0.089408)
		(layer "In4.Cu")
		(net "PWRGD_CPU1_DRAMPWROK_KLM_G")
	)
	(segment
		(start 122.411236 -90.974164)
		(end 121.962164 -90.974164)
		(width 0.089408)
		(layer "In4.Cu")
		(net "PWRGD_CPU1_DRAMPWROK_KLM_G")
	)
	(segment
		(start 131.322318 -91.469718)
		(end 131.019804 -91.167204)
		(width 0.089408)
		(layer "In4.Cu")
		(net "PWRGD_CPU1_DRAMPWROK_KLM_G")
	)
	(segment
		(start 134.474204 -91.167204)
		(end 133.902196 -91.167204)
		(width 0.089408)
		(layer "In4.Cu")
		(net "PWRGD_CPU1_DRAMPWROK_KLM_G")
	)
	(segment
		(start 149.923754 -112.843056)
		(end 150.47214 -112.29467)
		(width 0.089408)
		(layer "In4.Cu")
		(net "PWRGD_CPU1_DRAMPWROK_KLM_G")
	)
	(segment
		(start 140.6652 -101.849428)
		(end 140.6652 -91.91625)
		(width 0.089408)
		(layer "In4.Cu")
		(net "PWRGD_CPU1_DRAMPWROK_KLM_G")
	)
	(segment
		(start 133.049518 -91.469718)
		(end 132.747004 -91.167204)
		(width 0.089408)
		(layer "In4.Cu")
		(net "PWRGD_CPU1_DRAMPWROK_KLM_G")
	)
	(segment
		(start 123.336558 -90.672158)
		(end 122.713242 -90.672158)
		(width 0.089408)
		(layer "In4.Cu")
		(net "PWRGD_CPU1_DRAMPWROK_KLM_G")
	)
	(segment
		(start 135.301482 -91.469718)
		(end 134.776718 -91.469718)
		(width 0.089408)
		(layer "In4.Cu")
		(net "PWRGD_CPU1_DRAMPWROK_KLM_G")
	)
	(segment
		(start 130.498596 -91.167204)
		(end 130.196082 -91.469718)
		(width 0.089408)
		(layer "In4.Cu")
		(net "PWRGD_CPU1_DRAMPWROK_KLM_G")
	)
	(segment
		(start 129.267204 -91.167204)
		(end 128.771396 -91.167204)
		(width 0.089408)
		(layer "In4.Cu")
		(net "PWRGD_CPU1_DRAMPWROK_KLM_G")
	)
	(segment
		(start 135.603996 -91.167204)
		(end 135.301482 -91.469718)
		(width 0.089408)
		(layer "In4.Cu")
		(net "PWRGD_CPU1_DRAMPWROK_KLM_G")
	)
	(segment
		(start 120.420384 -90.0684)
		(end 120.0658 -89.713816)
		(width 0.089408)
		(layer "In4.Cu")
		(net "PWRGD_CPU1_DRAMPWROK_KLM_G")
	)
	(segment
		(start 140.6652 -91.91625)
		(end 140.31849 -91.56954)
		(width 0.089408)
		(layer "In4.Cu")
		(net "PWRGD_CPU1_DRAMPWROK_KLM_G")
	)
	(segment
		(start 156.61513 -112.29467)
		(end 171.9326 -96.9772)
		(width 0.089408)
		(layer "In4.Cu")
		(net "PWRGD_CPU1_DRAMPWROK_KLM_G")
	)
	(segment
		(start 121.5898 -90.6018)
		(end 121.158 -90.6018)
		(width 0.089408)
		(layer "In4.Cu")
		(net "PWRGD_CPU1_DRAMPWROK_KLM_G")
	)
	(segment
		(start 137.028682 -91.469718)
		(end 136.503918 -91.469718)
		(width 0.089408)
		(layer "In4.Cu")
		(net "PWRGD_CPU1_DRAMPWROK_KLM_G")
	)
	(segment
		(start 136.201404 -91.167204)
		(end 135.603996 -91.167204)
		(width 0.089408)
		(layer "In4.Cu")
		(net "PWRGD_CPU1_DRAMPWROK_KLM_G")
	)
	(segment
		(start 134.776718 -91.469718)
		(end 134.474204 -91.167204)
		(width 0.089408)
		(layer "In4.Cu")
		(net "PWRGD_CPU1_DRAMPWROK_KLM_G")
	)
	(segment
		(start 132.174996 -91.167204)
		(end 131.872482 -91.469718)
		(width 0.089408)
		(layer "In4.Cu")
		(net "PWRGD_CPU1_DRAMPWROK_KLM_G")
	)
	(segment
		(start 137.852404 -91.167204)
		(end 137.331196 -91.167204)
		(width 0.089408)
		(layer "In4.Cu")
		(net "PWRGD_CPU1_DRAMPWROK_KLM_G")
	)
	(segment
		(start 125.939804 -91.167204)
		(end 125.291596 -91.167204)
		(width 0.089408)
		(layer "In4.Cu")
		(net "PWRGD_CPU1_DRAMPWROK_KLM_G")
	)
	(segment
		(start 126.242318 -91.469718)
		(end 125.939804 -91.167204)
		(width 0.089408)
		(layer "In4.Cu")
		(net "PWRGD_CPU1_DRAMPWROK_KLM_G")
	)
	(segment
		(start 140.31849 -91.56954)
		(end 139.957302 -91.56954)
		(width 0.089408)
		(layer "In4.Cu")
		(net "PWRGD_CPU1_DRAMPWROK_KLM_G")
	)
	(segment
		(start 150.385272 -113.78438)
		(end 149.923754 -113.322862)
		(width 0.089408)
		(layer "In4.Cu")
		(net "PWRGD_CPU1_DRAMPWROK_KLM_G")
	)
	(segment
		(start 136.503918 -91.469718)
		(end 136.201404 -91.167204)
		(width 0.089408)
		(layer "In4.Cu")
		(net "PWRGD_CPU1_DRAMPWROK_KLM_G")
	)
	(segment
		(start 133.902196 -91.167204)
		(end 133.599682 -91.469718)
		(width 0.089408)
		(layer "In4.Cu")
		(net "PWRGD_CPU1_DRAMPWROK_KLM_G")
	)
	(segment
		(start 127.918718 -91.469718)
		(end 127.616204 -91.167204)
		(width 0.089408)
		(layer "In4.Cu")
		(net "PWRGD_CPU1_DRAMPWROK_KLM_G")
	)
	(segment
		(start 121.962164 -90.974164)
		(end 121.5898 -90.6018)
		(width 0.089408)
		(layer "In4.Cu")
		(net "PWRGD_CPU1_DRAMPWROK_KLM_G")
	)
	(segment
		(start 137.331196 -91.167204)
		(end 137.028682 -91.469718)
		(width 0.089408)
		(layer "In4.Cu")
		(net "PWRGD_CPU1_DRAMPWROK_KLM_G")
	)
	(segment
		(start 149.923754 -113.322862)
		(end 149.923754 -112.843056)
		(width 0.089408)
		(layer "In4.Cu")
		(net "PWRGD_CPU1_DRAMPWROK_KLM_G")
	)
	(segment
		(start 140.8176 -102.217474)
		(end 140.812012 -102.204012)
		(width 0.089408)
		(layer "In4.Cu")
		(net "PWRGD_CPU1_DRAMPWROK_KLM_G")
	)
	(segment
		(start 124.489718 -91.469718)
		(end 124.079 -91.059)
		(width 0.089408)
		(layer "In4.Cu")
		(net "PWRGD_CPU1_DRAMPWROK_KLM_G")
	)
	(segment
		(start 131.019804 -91.167204)
		(end 130.498596 -91.167204)
		(width 0.089408)
		(layer "In4.Cu")
		(net "PWRGD_CPU1_DRAMPWROK_KLM_G")
	)
	(segment
		(start 124.079 -91.059)
		(end 123.7234 -91.059)
		(width 0.089408)
		(layer "In4.Cu")
		(net "PWRGD_CPU1_DRAMPWROK_KLM_G")
	)
	(segment
		(start 150.564088 -114.368072)
		(end 149.133306 -114.368072)
		(width 0.089408)
		(layer "In4.Cu")
		(net "PWRGD_CPU1_DRAMPWROK_KLM_G")
	)
	(segment
		(start 143.529304 -108.76407)
		(end 140.8176 -102.217474)
		(width 0.089408)
		(layer "In4.Cu")
		(net "PWRGD_CPU1_DRAMPWROK_KLM_G")
	)
	(segment
		(start 138.730482 -91.469718)
		(end 138.154918 -91.469718)
		(width 0.089408)
		(layer "In4.Cu")
		(net "PWRGD_CPU1_DRAMPWROK_KLM_G")
	)
	(segment
		(start 139.032996 -91.167204)
		(end 138.730482 -91.469718)
		(width 0.089408)
		(layer "In4.Cu")
		(net "PWRGD_CPU1_DRAMPWROK_KLM_G")
	)
	(segment
		(start 129.569718 -91.469718)
		(end 129.267204 -91.167204)
		(width 0.089408)
		(layer "In4.Cu")
		(net "PWRGD_CPU1_DRAMPWROK_KLM_G")
	)
	(segment
		(start 138.154918 -91.469718)
		(end 137.852404 -91.167204)
		(width 0.089408)
		(layer "In4.Cu")
		(net "PWRGD_CPU1_DRAMPWROK_KLM_G")
	)
	(segment
		(start 130.196082 -91.469718)
		(end 129.569718 -91.469718)
		(width 0.089408)
		(layer "In4.Cu")
		(net "PWRGD_CPU1_DRAMPWROK_KLM_G")
	)
	(segment
		(start 133.599682 -91.469718)
		(end 133.049518 -91.469718)
		(width 0.089408)
		(layer "In4.Cu")
		(net "PWRGD_CPU1_DRAMPWROK_KLM_G")
	)
	(segment
		(start 121.158 -90.6018)
		(end 120.6246 -90.0684)
		(width 0.089408)
		(layer "In4.Cu")
		(net "PWRGD_CPU1_DRAMPWROK_KLM_G")
	)
	(segment
		(start 120.0658 -89.713816)
		(end 120.0658 -88.522556)
		(width 0.089408)
		(layer "In4.Cu")
		(net "PWRGD_CPU1_DRAMPWROK_KLM_G")
	)
	(segment
		(start 140.812012 -102.204012)
		(end 140.6652 -101.849428)
		(width 0.089408)
		(layer "In4.Cu")
		(net "PWRGD_CPU1_DRAMPWROK_KLM_G")
	)
	(segment
		(start 120.6246 -90.0684)
		(end 120.420384 -90.0684)
		(width 0.089408)
		(layer "In4.Cu")
		(net "PWRGD_CPU1_DRAMPWROK_KLM_G")
	)
	(segment
		(start 151.14778 -113.78438)
		(end 150.564088 -114.368072)
		(width 0.089408)
		(layer "In4.Cu")
		(net "PWRGD_CPU1_DRAMPWROK_KLM_G")
	)
	(segment
		(start 126.741682 -91.469718)
		(end 126.242318 -91.469718)
		(width 0.089408)
		(layer "In4.Cu")
		(net "PWRGD_CPU1_DRAMPWROK_KLM_G")
	)
	(segment
		(start 128.468882 -91.469718)
		(end 127.918718 -91.469718)
		(width 0.089408)
		(layer "In4.Cu")
		(net "PWRGD_CPU1_DRAMPWROK_KLM_G")
	)
	(segment
		(start 150.47214 -112.29467)
		(end 156.61513 -112.29467)
		(width 0.089408)
		(layer "In4.Cu")
		(net "PWRGD_CPU1_DRAMPWROK_KLM_G")
	)
	(segment
		(start 125.291596 -91.167204)
		(end 124.989082 -91.469718)
		(width 0.089408)
		(layer "In4.Cu")
		(net "PWRGD_CPU1_DRAMPWROK_KLM_G")
	)
	(segment
		(start 128.771396 -91.167204)
		(end 128.468882 -91.469718)
		(width 0.089408)
		(layer "In4.Cu")
		(net "PWRGD_CPU1_DRAMPWROK_KLM_G")
	)
	(segment
		(start 139.554966 -91.167204)
		(end 139.032996 -91.167204)
		(width 0.089408)
		(layer "In4.Cu")
		(net "PWRGD_CPU1_DRAMPWROK_KLM_G")
	)
	(segment
		(start 151.14778 -113.78438)
		(end 150.385272 -113.78438)
		(width 0.089408)
		(layer "In4.Cu")
		(net "PWRGD_CPU1_DRAMPWROK_KLM_G")
	)
	(segment
		(start 139.957302 -91.56954)
		(end 139.554966 -91.167204)
		(width 0.089408)
		(layer "In4.Cu")
		(net "PWRGD_CPU1_DRAMPWROK_KLM_G")
	)
	(segment
		(start 124.989082 -91.469718)
		(end 124.489718 -91.469718)
		(width 0.089408)
		(layer "In4.Cu")
		(net "PWRGD_CPU1_DRAMPWROK_KLM_G")
	)
	(segment
		(start 127.616204 -91.167204)
		(end 127.044196 -91.167204)
		(width 0.089408)
		(layer "In4.Cu")
		(net "PWRGD_CPU1_DRAMPWROK_KLM_G")
	)
	(segment
		(start 122.713242 -90.672158)
		(end 122.411236 -90.974164)
		(width 0.089408)
		(layer "In4.Cu")
		(net "PWRGD_CPU1_DRAMPWROK_KLM_G")
	)
	(segment
		(start 123.7234 -91.059)
		(end 123.336558 -90.672158)
		(width 0.089408)
		(layer "In4.Cu")
		(net "PWRGD_CPU1_DRAMPWROK_KLM_G")
	)
	(segment
		(start 120.0658 -88.522556)
		(end 119.642382 -88.099138)
		(width 0.089408)
		(layer "In4.Cu")
		(net "PWRGD_CPU1_DRAMPWROK_KLM_G")
	)
	(segment
		(start 174.481236 -97.771204)
		(end 174.606458 -97.771204)
		(width 0.10795)
		(layer "F.Cu")
		(net "PWRGD_CPU1_DRAMPWROK_GHJ_G")
	)
	(segment
		(start 173.981618 -96.310704)
		(end 173.981618 -97.271586)
		(width 0.10795)
		(layer "F.Cu")
		(net "PWRGD_CPU1_DRAMPWROK_GHJ_G")
	)
	(segment
		(start 173.981618 -97.271586)
		(end 174.481236 -97.771204)
		(width 0.10795)
		(layer "F.Cu")
		(net "PWRGD_CPU1_DRAMPWROK_GHJ_G")
	)
	(segment
		(start 162.703764 -71.13016)
		(end 162.98291 -71.409306)
		(width 0.10795)
		(layer "F.Cu")
		(net "PWRGD_CPU1_DRAMPWROK_GHJ_G")
	)
	(segment
		(start 117.353842 -67.296538)
		(end 116.782342 -67.296538)
		(width 0.1016)
		(layer "F.Cu")
		(net "PWRGD_CPU1_DRAMPWROK_GHJ_G")
	)
	(segment
		(start 162.703764 -70.694296)
		(end 162.703764 -71.13016)
		(width 0.10795)
		(layer "F.Cu")
		(net "PWRGD_CPU1_DRAMPWROK_GHJ_G")
	)
	(via
		(at 174.606458 -97.771204)
		(size 0.508)
		(drill 0.254)
		(layers "F.Cu" "B.Cu")
		(net "PWRGD_CPU1_DRAMPWROK_GHJ_G")
	)
	(via
		(at 174.606458 -96.52)
		(size 0.6604)
		(drill 0.3302)
		(layers "F.Cu" "B.Cu")
		(net "PWRGD_CPU1_DRAMPWROK_GHJ_G")
	)
	(via
		(at 116.782342 -67.296538)
		(size 0.508)
		(drill 0.254)
		(layers "F.Cu" "B.Cu")
		(net "PWRGD_CPU1_DRAMPWROK_GHJ_G")
	)
	(via
		(at 162.98291 -71.409306)
		(size 0.508)
		(drill 0.254)
		(layers "F.Cu" "B.Cu")
		(net "PWRGD_CPU1_DRAMPWROK_GHJ_G")
	)
	(segment
		(start 174.606458 -97.771204)
		(end 174.606458 -96.52)
		(width 0.10795)
		(layer "B.Cu")
		(net "PWRGD_CPU1_DRAMPWROK_GHJ_G")
	)
	(segment
		(start 132.715 -64.2874)
		(end 133.096 -63.9064)
		(width 0.089408)
		(layer "In4.Cu")
		(net "PWRGD_CPU1_DRAMPWROK_GHJ_G")
	)
	(segment
		(start 140.9446 -64.262)
		(end 141.351 -64.262)
		(width 0.089408)
		(layer "In4.Cu")
		(net "PWRGD_CPU1_DRAMPWROK_GHJ_G")
	)
	(segment
		(start 127.2286 -65.3034)
		(end 127.5842 -65.3034)
		(width 0.089408)
		(layer "In4.Cu")
		(net "PWRGD_CPU1_DRAMPWROK_GHJ_G")
	)
	(segment
		(start 120.4087 -66.72072)
		(end 120.76938 -66.36004)
		(width 0.089408)
		(layer "In4.Cu")
		(net "PWRGD_CPU1_DRAMPWROK_GHJ_G")
	)
	(segment
		(start 121.62536 -65.90284)
		(end 122.18924 -65.90284)
		(width 0.089408)
		(layer "In4.Cu")
		(net "PWRGD_CPU1_DRAMPWROK_GHJ_G")
	)
	(segment
		(start 137.8712 -64.2874)
		(end 138.2776 -63.881)
		(width 0.089408)
		(layer "In4.Cu")
		(net "PWRGD_CPU1_DRAMPWROK_GHJ_G")
	)
	(segment
		(start 146.332194 -64.925448)
		(end 146.57451 -64.925448)
		(width 0.089408)
		(layer "In4.Cu")
		(net "PWRGD_CPU1_DRAMPWROK_GHJ_G")
	)
	(segment
		(start 124.968 -66.802)
		(end 125.3744 -67.2084)
		(width 0.089408)
		(layer "In4.Cu")
		(net "PWRGD_CPU1_DRAMPWROK_GHJ_G")
	)
	(segment
		(start 119.96928 -66.72072)
		(end 120.4087 -66.72072)
		(width 0.089408)
		(layer "In4.Cu")
		(net "PWRGD_CPU1_DRAMPWROK_GHJ_G")
	)
	(segment
		(start 166.770812 -84.231988)
		(end 166.342568 -84.231988)
		(width 0.089408)
		(layer "In4.Cu")
		(net "PWRGD_CPU1_DRAMPWROK_GHJ_G")
	)
	(segment
		(start 133.5786 -63.9064)
		(end 133.9596 -64.2874)
		(width 0.089408)
		(layer "In4.Cu")
		(net "PWRGD_CPU1_DRAMPWROK_GHJ_G")
	)
	(segment
		(start 133.096 -63.9064)
		(end 133.5786 -63.9064)
		(width 0.089408)
		(layer "In4.Cu")
		(net "PWRGD_CPU1_DRAMPWROK_GHJ_G")
	)
	(segment
		(start 177.130964 -90.985848)
		(end 177.130964 -87.799164)
		(width 0.089408)
		(layer "In4.Cu")
		(net "PWRGD_CPU1_DRAMPWROK_GHJ_G")
	)
	(segment
		(start 143.56842 -64.925956)
		(end 146.331686 -64.925956)
		(width 0.089408)
		(layer "In4.Cu")
		(net "PWRGD_CPU1_DRAMPWROK_GHJ_G")
	)
	(segment
		(start 121.16816 -66.36004)
		(end 121.62536 -65.90284)
		(width 0.089408)
		(layer "In4.Cu")
		(net "PWRGD_CPU1_DRAMPWROK_GHJ_G")
	)
	(segment
		(start 123.3932 -66.802)
		(end 124.968 -66.802)
		(width 0.089408)
		(layer "In4.Cu")
		(net "PWRGD_CPU1_DRAMPWROK_GHJ_G")
	)
	(segment
		(start 138.2776 -63.881)
		(end 138.7094 -63.881)
		(width 0.089408)
		(layer "In4.Cu")
		(net "PWRGD_CPU1_DRAMPWROK_GHJ_G")
	)
	(segment
		(start 139.9667 -63.8683)
		(end 140.5509 -63.8683)
		(width 0.089408)
		(layer "In4.Cu")
		(net "PWRGD_CPU1_DRAMPWROK_GHJ_G")
	)
	(segment
		(start 142.3035 -63.8429)
		(end 142.881604 -64.421004)
		(width 0.089408)
		(layer "In4.Cu")
		(net "PWRGD_CPU1_DRAMPWROK_GHJ_G")
	)
	(segment
		(start 135.3312 -63.8556)
		(end 135.7122 -64.2366)
		(width 0.089408)
		(layer "In4.Cu")
		(net "PWRGD_CPU1_DRAMPWROK_GHJ_G")
	)
	(segment
		(start 119.61622 -66.36766)
		(end 119.96928 -66.72072)
		(width 0.089408)
		(layer "In4.Cu")
		(net "PWRGD_CPU1_DRAMPWROK_GHJ_G")
	)
	(segment
		(start 126.7206 -66.7512)
		(end 126.9492 -66.5226)
		(width 0.089408)
		(layer "In4.Cu")
		(net "PWRGD_CPU1_DRAMPWROK_GHJ_G")
	)
	(segment
		(start 133.9596 -64.2874)
		(end 134.3914 -64.2874)
		(width 0.089408)
		(layer "In4.Cu")
		(net "PWRGD_CPU1_DRAMPWROK_GHJ_G")
	)
	(segment
		(start 134.3914 -64.2874)
		(end 134.8232 -63.8556)
		(width 0.089408)
		(layer "In4.Cu")
		(net "PWRGD_CPU1_DRAMPWROK_GHJ_G")
	)
	(segment
		(start 139.0904 -64.262)
		(end 139.573 -64.262)
		(width 0.089408)
		(layer "In4.Cu")
		(net "PWRGD_CPU1_DRAMPWROK_GHJ_G")
	)
	(segment
		(start 119.1006 -66.36766)
		(end 119.61622 -66.36766)
		(width 0.089408)
		(layer "In4.Cu")
		(net "PWRGD_CPU1_DRAMPWROK_GHJ_G")
	)
	(segment
		(start 139.573 -64.262)
		(end 139.9667 -63.8683)
		(width 0.089408)
		(layer "In4.Cu")
		(net "PWRGD_CPU1_DRAMPWROK_GHJ_G")
	)
	(segment
		(start 126.9492 -65.5828)
		(end 127.2286 -65.3034)
		(width 0.089408)
		(layer "In4.Cu")
		(net "PWRGD_CPU1_DRAMPWROK_GHJ_G")
	)
	(segment
		(start 138.7094 -63.881)
		(end 139.0904 -64.262)
		(width 0.089408)
		(layer "In4.Cu")
		(net "PWRGD_CPU1_DRAMPWROK_GHJ_G")
	)
	(segment
		(start 140.5509 -63.8683)
		(end 140.9446 -64.262)
		(width 0.089408)
		(layer "In4.Cu")
		(net "PWRGD_CPU1_DRAMPWROK_GHJ_G")
	)
	(segment
		(start 134.8232 -63.8556)
		(end 135.3312 -63.8556)
		(width 0.089408)
		(layer "In4.Cu")
		(net "PWRGD_CPU1_DRAMPWROK_GHJ_G")
	)
	(segment
		(start 118.61546 -66.8528)
		(end 119.1006 -66.36766)
		(width 0.089408)
		(layer "In4.Cu")
		(net "PWRGD_CPU1_DRAMPWROK_GHJ_G")
	)
	(segment
		(start 169.981626 -87.442802)
		(end 166.770812 -84.231988)
		(width 0.089408)
		(layer "In4.Cu")
		(net "PWRGD_CPU1_DRAMPWROK_GHJ_G")
	)
	(segment
		(start 162.968178 -71.409306)
		(end 162.98291 -71.409306)
		(width 0.089408)
		(layer "In4.Cu")
		(net "PWRGD_CPU1_DRAMPWROK_GHJ_G")
	)
	(segment
		(start 146.57451 -64.925448)
		(end 149.263608 -67.614546)
		(width 0.089408)
		(layer "In4.Cu")
		(net "PWRGD_CPU1_DRAMPWROK_GHJ_G")
	)
	(segment
		(start 162.968178 -71.669656)
		(end 162.968178 -71.409306)
		(width 0.089408)
		(layer "In4.Cu")
		(net "PWRGD_CPU1_DRAMPWROK_GHJ_G")
	)
	(segment
		(start 136.2202 -64.2366)
		(end 136.5758 -63.881)
		(width 0.089408)
		(layer "In4.Cu")
		(net "PWRGD_CPU1_DRAMPWROK_GHJ_G")
	)
	(segment
		(start 126.9492 -66.5226)
		(end 126.9492 -65.5828)
		(width 0.089408)
		(layer "In4.Cu")
		(net "PWRGD_CPU1_DRAMPWROK_GHJ_G")
	)
	(segment
		(start 131.826 -64.8208)
		(end 132.3594 -64.2874)
		(width 0.089408)
		(layer "In4.Cu")
		(net "PWRGD_CPU1_DRAMPWROK_GHJ_G")
	)
	(segment
		(start 122.18924 -65.90284)
		(end 122.5042 -66.2178)
		(width 0.089408)
		(layer "In4.Cu")
		(net "PWRGD_CPU1_DRAMPWROK_GHJ_G")
	)
	(segment
		(start 136.5758 -63.881)
		(end 137.1092 -63.881)
		(width 0.089408)
		(layer "In4.Cu")
		(net "PWRGD_CPU1_DRAMPWROK_GHJ_G")
	)
	(segment
		(start 135.7122 -64.2366)
		(end 136.2202 -64.2366)
		(width 0.089408)
		(layer "In4.Cu")
		(net "PWRGD_CPU1_DRAMPWROK_GHJ_G")
	)
	(segment
		(start 176.774602 -87.442802)
		(end 169.981626 -87.442802)
		(width 0.089408)
		(layer "In4.Cu")
		(net "PWRGD_CPU1_DRAMPWROK_GHJ_G")
	)
	(segment
		(start 125.8824 -67.2084)
		(end 126.3396 -66.7512)
		(width 0.089408)
		(layer "In4.Cu")
		(net "PWRGD_CPU1_DRAMPWROK_GHJ_G")
	)
	(segment
		(start 122.809 -66.2178)
		(end 123.3932 -66.802)
		(width 0.089408)
		(layer "In4.Cu")
		(net "PWRGD_CPU1_DRAMPWROK_GHJ_G")
	)
	(segment
		(start 166.342568 -84.231988)
		(end 165.557708 -83.447128)
		(width 0.089408)
		(layer "In4.Cu")
		(net "PWRGD_CPU1_DRAMPWROK_GHJ_G")
	)
	(segment
		(start 141.7701 -63.8429)
		(end 142.3035 -63.8429)
		(width 0.089408)
		(layer "In4.Cu")
		(net "PWRGD_CPU1_DRAMPWROK_GHJ_G")
	)
	(segment
		(start 174.606458 -97.771204)
		(end 174.606458 -94.427802)
		(width 0.089408)
		(layer "In4.Cu")
		(net "PWRGD_CPU1_DRAMPWROK_GHJ_G")
	)
	(segment
		(start 122.5042 -66.2178)
		(end 122.809 -66.2178)
		(width 0.089408)
		(layer "In4.Cu")
		(net "PWRGD_CPU1_DRAMPWROK_GHJ_G")
	)
	(segment
		(start 128.0414 -64.8462)
		(end 130.0988 -64.8462)
		(width 0.089408)
		(layer "In4.Cu")
		(net "PWRGD_CPU1_DRAMPWROK_GHJ_G")
	)
	(segment
		(start 130.500374 -65.247774)
		(end 130.992626 -65.247774)
		(width 0.089408)
		(layer "In4.Cu")
		(net "PWRGD_CPU1_DRAMPWROK_GHJ_G")
	)
	(segment
		(start 142.881604 -64.421004)
		(end 143.063468 -64.421004)
		(width 0.089408)
		(layer "In4.Cu")
		(net "PWRGD_CPU1_DRAMPWROK_GHJ_G")
	)
	(segment
		(start 130.992626 -65.247774)
		(end 131.4196 -64.8208)
		(width 0.089408)
		(layer "In4.Cu")
		(net "PWRGD_CPU1_DRAMPWROK_GHJ_G")
	)
	(segment
		(start 155.59532 -67.614546)
		(end 158.786068 -70.805294)
		(width 0.089408)
		(layer "In4.Cu")
		(net "PWRGD_CPU1_DRAMPWROK_GHJ_G")
	)
	(segment
		(start 126.3396 -66.7512)
		(end 126.7206 -66.7512)
		(width 0.089408)
		(layer "In4.Cu")
		(net "PWRGD_CPU1_DRAMPWROK_GHJ_G")
	)
	(segment
		(start 149.263608 -67.614546)
		(end 155.59532 -67.614546)
		(width 0.089408)
		(layer "In4.Cu")
		(net "PWRGD_CPU1_DRAMPWROK_GHJ_G")
	)
	(segment
		(start 116.782342 -67.296538)
		(end 117.826282 -67.296538)
		(width 0.089408)
		(layer "In4.Cu")
		(net "PWRGD_CPU1_DRAMPWROK_GHJ_G")
	)
	(segment
		(start 127.5842 -65.3034)
		(end 128.0414 -64.8462)
		(width 0.089408)
		(layer "In4.Cu")
		(net "PWRGD_CPU1_DRAMPWROK_GHJ_G")
	)
	(segment
		(start 174.606458 -94.427802)
		(end 176.17313 -92.86113)
		(width 0.089408)
		(layer "In4.Cu")
		(net "PWRGD_CPU1_DRAMPWROK_GHJ_G")
	)
	(segment
		(start 118.27002 -66.8528)
		(end 118.61546 -66.8528)
		(width 0.089408)
		(layer "In4.Cu")
		(net "PWRGD_CPU1_DRAMPWROK_GHJ_G")
	)
	(segment
		(start 131.4196 -64.8208)
		(end 131.826 -64.8208)
		(width 0.089408)
		(layer "In4.Cu")
		(net "PWRGD_CPU1_DRAMPWROK_GHJ_G")
	)
	(segment
		(start 137.1092 -63.881)
		(end 137.5156 -64.2874)
		(width 0.089408)
		(layer "In4.Cu")
		(net "PWRGD_CPU1_DRAMPWROK_GHJ_G")
	)
	(segment
		(start 176.17313 -91.943682)
		(end 177.130964 -90.985848)
		(width 0.089408)
		(layer "In4.Cu")
		(net "PWRGD_CPU1_DRAMPWROK_GHJ_G")
	)
	(segment
		(start 137.5156 -64.2874)
		(end 137.8712 -64.2874)
		(width 0.089408)
		(layer "In4.Cu")
		(net "PWRGD_CPU1_DRAMPWROK_GHJ_G")
	)
	(segment
		(start 160.408366 -71.409306)
		(end 162.968178 -71.409306)
		(width 0.089408)
		(layer "In4.Cu")
		(net "PWRGD_CPU1_DRAMPWROK_GHJ_G")
	)
	(segment
		(start 177.130964 -87.799164)
		(end 176.774602 -87.442802)
		(width 0.089408)
		(layer "In4.Cu")
		(net "PWRGD_CPU1_DRAMPWROK_GHJ_G")
	)
	(segment
		(start 143.063468 -64.421004)
		(end 143.56842 -64.925956)
		(width 0.089408)
		(layer "In4.Cu")
		(net "PWRGD_CPU1_DRAMPWROK_GHJ_G")
	)
	(segment
		(start 159.804354 -70.805294)
		(end 160.408366 -71.409306)
		(width 0.089408)
		(layer "In4.Cu")
		(net "PWRGD_CPU1_DRAMPWROK_GHJ_G")
	)
	(segment
		(start 130.0988 -64.8462)
		(end 130.500374 -65.247774)
		(width 0.089408)
		(layer "In4.Cu")
		(net "PWRGD_CPU1_DRAMPWROK_GHJ_G")
	)
	(segment
		(start 165.557708 -83.447128)
		(end 165.557708 -74.259186)
		(width 0.089408)
		(layer "In4.Cu")
		(net "PWRGD_CPU1_DRAMPWROK_GHJ_G")
	)
	(segment
		(start 125.3744 -67.2084)
		(end 125.8824 -67.2084)
		(width 0.089408)
		(layer "In4.Cu")
		(net "PWRGD_CPU1_DRAMPWROK_GHJ_G")
	)
	(segment
		(start 132.3594 -64.2874)
		(end 132.715 -64.2874)
		(width 0.089408)
		(layer "In4.Cu")
		(net "PWRGD_CPU1_DRAMPWROK_GHJ_G")
	)
	(segment
		(start 176.17313 -92.86113)
		(end 176.17313 -91.943682)
		(width 0.089408)
		(layer "In4.Cu")
		(net "PWRGD_CPU1_DRAMPWROK_GHJ_G")
	)
	(segment
		(start 165.557708 -74.259186)
		(end 162.968178 -71.669656)
		(width 0.089408)
		(layer "In4.Cu")
		(net "PWRGD_CPU1_DRAMPWROK_GHJ_G")
	)
	(segment
		(start 158.786068 -70.805294)
		(end 159.804354 -70.805294)
		(width 0.089408)
		(layer "In4.Cu")
		(net "PWRGD_CPU1_DRAMPWROK_GHJ_G")
	)
	(segment
		(start 141.351 -64.262)
		(end 141.7701 -63.8429)
		(width 0.089408)
		(layer "In4.Cu")
		(net "PWRGD_CPU1_DRAMPWROK_GHJ_G")
	)
	(segment
		(start 117.826282 -67.296538)
		(end 118.27002 -66.8528)
		(width 0.089408)
		(layer "In4.Cu")
		(net "PWRGD_CPU1_DRAMPWROK_GHJ_G")
	)
	(segment
		(start 146.331686 -64.925956)
		(end 146.332194 -64.925448)
		(width 0.089408)
		(layer "In4.Cu")
		(net "PWRGD_CPU1_DRAMPWROK_GHJ_G")
	)
	(segment
		(start 120.76938 -66.36004)
		(end 121.16816 -66.36004)
		(width 0.089408)
		(layer "In4.Cu")
		(net "PWRGD_CPU1_DRAMPWROK_GHJ_G")
	)
	(segment
		(start 284.071314 -88.099138)
		(end 284.642814 -88.099138)
		(width 0.1016)
		(layer "F.Cu")
		(net "PWRGD_CPU0_DRAMPWROK_DEF_G")
	)
	(segment
		(start 273.10588 -85.55482)
		(end 273.10588 -86.96452)
		(width 0.10795)
		(layer "F.Cu")
		(net "PWRGD_CPU0_DRAMPWROK_DEF_G")
	)
	(segment
		(start 273.10588 -86.96452)
		(end 273.41449 -87.27313)
		(width 0.10795)
		(layer "F.Cu")
		(net "PWRGD_CPU0_DRAMPWROK_DEF_G")
	)
	(segment
		(start 273.37258 -85.28812)
		(end 273.10588 -85.55482)
		(width 0.10795)
		(layer "F.Cu")
		(net "PWRGD_CPU0_DRAMPWROK_DEF_G")
	)
	(via
		(at 284.642814 -88.099138)
		(size 0.508)
		(drill 0.254)
		(layers "F.Cu" "B.Cu")
		(net "PWRGD_CPU0_DRAMPWROK_DEF_G")
	)
	(via
		(at 273.41449 -87.27313)
		(size 0.508)
		(drill 0.254)
		(layers "F.Cu" "B.Cu")
		(net "PWRGD_CPU0_DRAMPWROK_DEF_G")
	)
	(via
		(at 356.131368 -72.141588)
		(size 0.508)
		(drill 0.254)
		(layers "F.Cu" "B.Cu")
		(net "PWRGD_CPU0_DRAMPWROK_DEF_G")
	)
	(via
		(at 356.341172 -70.632828)
		(size 0.6604)
		(drill 0.3302)
		(layers "F.Cu" "B.Cu")
		(net "PWRGD_CPU0_DRAMPWROK_DEF_G")
	)
	(segment
		(start 356.16388 -72.109076)
		(end 356.16388 -70.81012)
		(width 0.10795)
		(layer "B.Cu")
		(net "PWRGD_CPU0_DRAMPWROK_DEF_G")
	)
	(segment
		(start 361.337352 -58.609484)
		(end 360.952542 -58.994294)
		(width 0.10795)
		(layer "B.Cu")
		(net "PWRGD_CPU0_DRAMPWROK_DEF_G")
	)
	(segment
		(start 362.963206 -56.254396)
		(end 361.337352 -57.88025)
		(width 0.10795)
		(layer "B.Cu")
		(net "PWRGD_CPU0_DRAMPWROK_DEF_G")
	)
	(segment
		(start 360.952542 -64.991996)
		(end 357.9368 -68.007738)
		(width 0.10795)
		(layer "B.Cu")
		(net "PWRGD_CPU0_DRAMPWROK_DEF_G")
	)
	(segment
		(start 357.9368 -68.007738)
		(end 357.9368 -69.0372)
		(width 0.10795)
		(layer "B.Cu")
		(net "PWRGD_CPU0_DRAMPWROK_DEF_G")
	)
	(segment
		(start 369.8875 -54.51348)
		(end 368.142266 -54.51348)
		(width 0.10795)
		(layer "B.Cu")
		(net "PWRGD_CPU0_DRAMPWROK_DEF_G")
	)
	(segment
		(start 366.40135 -56.254396)
		(end 362.963206 -56.254396)
		(width 0.10795)
		(layer "B.Cu")
		(net "PWRGD_CPU0_DRAMPWROK_DEF_G")
	)
	(segment
		(start 368.142266 -54.51348)
		(end 366.40135 -56.254396)
		(width 0.10795)
		(layer "B.Cu")
		(net "PWRGD_CPU0_DRAMPWROK_DEF_G")
	)
	(segment
		(start 360.952542 -58.994294)
		(end 360.952542 -64.991996)
		(width 0.10795)
		(layer "B.Cu")
		(net "PWRGD_CPU0_DRAMPWROK_DEF_G")
	)
	(segment
		(start 356.131368 -72.141588)
		(end 356.16388 -72.109076)
		(width 0.10795)
		(layer "B.Cu")
		(net "PWRGD_CPU0_DRAMPWROK_DEF_G")
	)
	(segment
		(start 356.16388 -70.81012)
		(end 356.341172 -70.632828)
		(width 0.10795)
		(layer "B.Cu")
		(net "PWRGD_CPU0_DRAMPWROK_DEF_G")
	)
	(segment
		(start 361.337352 -57.88025)
		(end 361.337352 -58.609484)
		(width 0.10795)
		(layer "B.Cu")
		(net "PWRGD_CPU0_DRAMPWROK_DEF_G")
	)
	(segment
		(start 357.9368 -69.0372)
		(end 356.341172 -70.632828)
		(width 0.10795)
		(layer "B.Cu")
		(net "PWRGD_CPU0_DRAMPWROK_DEF_G")
	)
	(segment
		(start 346.3925 -71.6153)
		(end 338.855812 -71.6153)
		(width 0.089408)
		(layer "In11.Cu")
		(net "PWRGD_CPU0_DRAMPWROK_DEF_G")
	)
	(segment
		(start 294.106854 -81.06918)
		(end 294.074088 -81.06918)
		(width 0.089408)
		(layer "In11.Cu")
		(net "PWRGD_CPU0_DRAMPWROK_DEF_G")
	)
	(segment
		(start 286.75838 -80.452214)
		(end 286.75838 -85.292692)
		(width 0.089408)
		(layer "In11.Cu")
		(net "PWRGD_CPU0_DRAMPWROK_DEF_G")
	)
	(segment
		(start 286.161734 -85.526118)
		(end 285.473648 -86.214204)
		(width 0.089408)
		(layer "In11.Cu")
		(net "PWRGD_CPU0_DRAMPWROK_DEF_G")
	)
	(segment
		(start 298.3992 -81.56448)
		(end 298.362878 -81.56448)
		(width 0.089408)
		(layer "In11.Cu")
		(net "PWRGD_CPU0_DRAMPWROK_DEF_G")
	)
	(segment
		(start 332.85557 -79.120492)
		(end 331.660754 -79.440786)
		(width 0.089408)
		(layer "In11.Cu")
		(net "PWRGD_CPU0_DRAMPWROK_DEF_G")
	)
	(segment
		(start 351.952306 -72.924162)
		(end 351.630234 -72.60209)
		(width 0.089408)
		(layer "In11.Cu")
		(net "PWRGD_CPU0_DRAMPWROK_DEF_G")
	)
	(segment
		(start 287.043876 -80.166718)
		(end 286.75838 -80.452214)
		(width 0.089408)
		(layer "In11.Cu")
		(net "PWRGD_CPU0_DRAMPWROK_DEF_G")
	)
	(segment
		(start 284.593538 -88.099138)
		(end 284.642814 -88.099138)
		(width 0.089408)
		(layer "In11.Cu")
		(net "PWRGD_CPU0_DRAMPWROK_DEF_G")
	)
	(segment
		(start 299.249338 -82.05978)
		(end 299.224954 -82.05978)
		(width 0.089408)
		(layer "In11.Cu")
		(net "PWRGD_CPU0_DRAMPWROK_DEF_G")
	)
	(segment
		(start 290.093908 -79.714852)
		(end 289.62985 -79.714852)
		(width 0.089408)
		(layer "In11.Cu")
		(net "PWRGD_CPU0_DRAMPWROK_DEF_G")
	)
	(segment
		(start 335.7118 -76.767944)
		(end 335.7118 -76.99248)
		(width 0.089408)
		(layer "In11.Cu")
		(net "PWRGD_CPU0_DRAMPWROK_DEF_G")
	)
	(segment
		(start 282.2448 -82.519266)
		(end 282.2448 -85.7504)
		(width 0.089408)
		(layer "In11.Cu")
		(net "PWRGD_CPU0_DRAMPWROK_DEF_G")
	)
	(segment
		(start 356.131368 -72.141588)
		(end 356.131368 -72.217534)
		(width 0.089408)
		(layer "In11.Cu")
		(net "PWRGD_CPU0_DRAMPWROK_DEF_G")
	)
	(segment
		(start 293.25189 -80.574134)
		(end 293.220648 -80.574134)
		(width 0.089408)
		(layer "In11.Cu")
		(net "PWRGD_CPU0_DRAMPWROK_DEF_G")
	)
	(segment
		(start 287.399476 -80.166718)
		(end 287.043876 -80.166718)
		(width 0.089408)
		(layer "In11.Cu")
		(net "PWRGD_CPU0_DRAMPWROK_DEF_G")
	)
	(segment
		(start 356.131368 -72.217534)
		(end 355.42474 -72.924162)
		(width 0.089408)
		(layer "In11.Cu")
		(net "PWRGD_CPU0_DRAMPWROK_DEF_G")
	)
	(segment
		(start 301.828454 -81.56448)
		(end 301.792132 -81.56448)
		(width 0.089408)
		(layer "In11.Cu")
		(net "PWRGD_CPU0_DRAMPWROK_DEF_G")
	)
	(segment
		(start 282.2448 -85.7504)
		(end 284.593538 -88.099138)
		(width 0.089408)
		(layer "In11.Cu")
		(net "PWRGD_CPU0_DRAMPWROK_DEF_G")
	)
	(segment
		(start 351.630234 -72.60209)
		(end 347.37929 -72.60209)
		(width 0.089408)
		(layer "In11.Cu")
		(net "PWRGD_CPU0_DRAMPWROK_DEF_G")
	)
	(segment
		(start 281.902154 -82.17662)
		(end 282.2448 -82.519266)
		(width 0.089408)
		(layer "In11.Cu")
		(net "PWRGD_CPU0_DRAMPWROK_DEF_G")
	)
	(segment
		(start 347.37929 -72.60209)
		(end 346.3925 -71.6153)
		(width 0.089408)
		(layer "In11.Cu")
		(net "PWRGD_CPU0_DRAMPWROK_DEF_G")
	)
	(segment
		(start 333.722726 -78.609952)
		(end 332.85557 -79.120492)
		(width 0.089408)
		(layer "In11.Cu")
		(net "PWRGD_CPU0_DRAMPWROK_DEF_G")
	)
	(segment
		(start 276.094444 -87.27313)
		(end 281.190954 -82.17662)
		(width 0.089408)
		(layer "In11.Cu")
		(net "PWRGD_CPU0_DRAMPWROK_DEF_G")
	)
	(segment
		(start 289.62985 -79.714852)
		(end 289.24758 -80.097122)
		(width 0.089408)
		(layer "In11.Cu")
		(net "PWRGD_CPU0_DRAMPWROK_DEF_G")
	)
	(segment
		(start 331.660754 -79.440786)
		(end 311.01411 -79.440786)
		(width 0.089408)
		(layer "In11.Cu")
		(net "PWRGD_CPU0_DRAMPWROK_DEF_G")
	)
	(segment
		(start 337.21294 -73.258172)
		(end 337.21294 -74.048112)
		(width 0.089408)
		(layer "In11.Cu")
		(net "PWRGD_CPU0_DRAMPWROK_DEF_G")
	)
	(segment
		(start 273.41449 -87.27313)
		(end 276.094444 -87.27313)
		(width 0.089408)
		(layer "In11.Cu")
		(net "PWRGD_CPU0_DRAMPWROK_DEF_G")
	)
	(segment
		(start 285.058358 -87.683594)
		(end 284.642814 -88.099138)
		(width 0.089408)
		(layer "In11.Cu")
		(net "PWRGD_CPU0_DRAMPWROK_DEF_G")
	)
	(segment
		(start 335.717896 -76.761848)
		(end 335.7118 -76.767944)
		(width 0.089408)
		(layer "In11.Cu")
		(net "PWRGD_CPU0_DRAMPWROK_DEF_G")
	)
	(segment
		(start 303.694846 -80.574134)
		(end 303.505616 -80.574134)
		(width 0.089408)
		(layer "In11.Cu")
		(net "PWRGD_CPU0_DRAMPWROK_DEF_G")
	)
	(segment
		(start 311.01411 -79.440786)
		(end 309.985156 -80.46974)
		(width 0.089408)
		(layer "In11.Cu")
		(net "PWRGD_CPU0_DRAMPWROK_DEF_G")
	)
	(segment
		(start 290.457636 -80.07858)
		(end 290.093908 -79.714852)
		(width 0.089408)
		(layer "In11.Cu")
		(net "PWRGD_CPU0_DRAMPWROK_DEF_G")
	)
	(segment
		(start 302.683418 -81.06918)
		(end 302.650652 -81.06918)
		(width 0.089408)
		(layer "In11.Cu")
		(net "PWRGD_CPU0_DRAMPWROK_DEF_G")
	)
	(segment
		(start 288.350198 -79.77251)
		(end 287.793684 -79.77251)
		(width 0.089408)
		(layer "In11.Cu")
		(net "PWRGD_CPU0_DRAMPWROK_DEF_G")
	)
	(segment
		(start 303.79924 -80.46974)
		(end 303.694846 -80.574134)
		(width 0.089408)
		(layer "In11.Cu")
		(net "PWRGD_CPU0_DRAMPWROK_DEF_G")
	)
	(segment
		(start 287.793684 -79.77251)
		(end 287.399476 -80.166718)
		(width 0.089408)
		(layer "In11.Cu")
		(net "PWRGD_CPU0_DRAMPWROK_DEF_G")
	)
	(segment
		(start 335.717896 -75.543156)
		(end 335.717896 -76.761848)
		(width 0.089408)
		(layer "In11.Cu")
		(net "PWRGD_CPU0_DRAMPWROK_DEF_G")
	)
	(segment
		(start 309.985156 -80.46974)
		(end 303.79924 -80.46974)
		(width 0.089408)
		(layer "In11.Cu")
		(net "PWRGD_CPU0_DRAMPWROK_DEF_G")
	)
	(segment
		(start 288.67481 -80.097122)
		(end 288.350198 -79.77251)
		(width 0.089408)
		(layer "In11.Cu")
		(net "PWRGD_CPU0_DRAMPWROK_DEF_G")
	)
	(segment
		(start 355.42474 -72.924162)
		(end 351.952306 -72.924162)
		(width 0.089408)
		(layer "In11.Cu")
		(net "PWRGD_CPU0_DRAMPWROK_DEF_G")
	)
	(segment
		(start 300.966378 -82.05978)
		(end 300.941994 -82.05978)
		(width 0.089408)
		(layer "In11.Cu")
		(net "PWRGD_CPU0_DRAMPWROK_DEF_G")
	)
	(segment
		(start 286.524954 -85.526118)
		(end 286.161734 -85.526118)
		(width 0.089408)
		(layer "In11.Cu")
		(net "PWRGD_CPU0_DRAMPWROK_DEF_G")
	)
	(segment
		(start 337.21294 -74.048112)
		(end 335.717896 -75.543156)
		(width 0.089408)
		(layer "In11.Cu")
		(net "PWRGD_CPU0_DRAMPWROK_DEF_G")
	)
	(segment
		(start 334.626458 -78.077822)
		(end 333.722726 -78.609952)
		(width 0.089408)
		(layer "In11.Cu")
		(net "PWRGD_CPU0_DRAMPWROK_DEF_G")
	)
	(segment
		(start 300.11624 -81.56448)
		(end 300.075092 -81.56448)
		(width 0.089408)
		(layer "In11.Cu")
		(net "PWRGD_CPU0_DRAMPWROK_DEF_G")
	)
	(segment
		(start 281.190954 -82.17662)
		(end 281.902154 -82.17662)
		(width 0.089408)
		(layer "In11.Cu")
		(net "PWRGD_CPU0_DRAMPWROK_DEF_G")
	)
	(segment
		(start 286.75838 -85.292692)
		(end 286.524954 -85.526118)
		(width 0.089408)
		(layer "In11.Cu")
		(net "PWRGD_CPU0_DRAMPWROK_DEF_G")
	)
	(segment
		(start 285.473648 -86.214204)
		(end 285.33598 -86.214204)
		(width 0.089408)
		(layer "In11.Cu")
		(net "PWRGD_CPU0_DRAMPWROK_DEF_G")
	)
	(segment
		(start 294.960548 -81.56448)
		(end 294.929052 -81.56448)
		(width 0.089408)
		(layer "In11.Cu")
		(net "PWRGD_CPU0_DRAMPWROK_DEF_G")
	)
	(segment
		(start 285.33598 -86.214204)
		(end 285.058358 -86.491826)
		(width 0.089408)
		(layer "In11.Cu")
		(net "PWRGD_CPU0_DRAMPWROK_DEF_G")
	)
	(segment
		(start 290.672774 -80.07858)
		(end 290.457636 -80.07858)
		(width 0.089408)
		(layer "In11.Cu")
		(net "PWRGD_CPU0_DRAMPWROK_DEF_G")
	)
	(segment
		(start 289.24758 -80.097122)
		(end 288.67481 -80.097122)
		(width 0.089408)
		(layer "In11.Cu")
		(net "PWRGD_CPU0_DRAMPWROK_DEF_G")
	)
	(segment
		(start 338.855812 -71.6153)
		(end 337.21294 -73.258172)
		(width 0.089408)
		(layer "In11.Cu")
		(net "PWRGD_CPU0_DRAMPWROK_DEF_G")
	)
	(segment
		(start 335.7118 -76.99248)
		(end 334.626458 -78.077822)
		(width 0.089408)
		(layer "In11.Cu")
		(net "PWRGD_CPU0_DRAMPWROK_DEF_G")
	)
	(segment
		(start 285.058358 -86.491826)
		(end 285.058358 -87.683594)
		(width 0.089408)
		(layer "In11.Cu")
		(net "PWRGD_CPU0_DRAMPWROK_DEF_G")
	)
	(arc
		(start 295.291256 -81.364582)
		(mid 295.151654 -81.507138)
		(end 294.960548 -81.56448)
		(width 0.089408)
		(layer "In11.Cu")
		(net "PWRGD_CPU0_DRAMPWROK_DEF_G")
	)
	(arc
		(start 294.074088 -81.06918)
		(mid 293.880985 -81.012661)
		(end 293.739824 -80.869282)
		(width 0.089408)
		(layer "In11.Cu")
		(net "PWRGD_CPU0_DRAMPWROK_DEF_G")
	)
	(arc
		(start 299.224954 -82.05978)
		(mid 299.031851 -82.003261)
		(end 298.89069 -81.859882)
		(width 0.089408)
		(layer "In11.Cu")
		(net "PWRGD_CPU0_DRAMPWROK_DEF_G")
	)
	(arc
		(start 300.60773 -81.859882)
		(mid 300.400201 -81.648598)
		(end 300.11624 -81.56448)
		(width 0.089408)
		(layer "In11.Cu")
		(net "PWRGD_CPU0_DRAMPWROK_DEF_G")
	)
	(arc
		(start 294.598344 -81.364582)
		(mid 294.390815 -81.153298)
		(end 294.106854 -81.06918)
		(width 0.089408)
		(layer "In11.Cu")
		(net "PWRGD_CPU0_DRAMPWROK_DEF_G")
	)
	(arc
		(start 298.89069 -81.859882)
		(mid 298.683161 -81.648598)
		(end 298.3992 -81.56448)
		(width 0.089408)
		(layer "In11.Cu")
		(net "PWRGD_CPU0_DRAMPWROK_DEF_G")
	)
	(arc
		(start 301.792132 -81.56448)
		(mid 301.508171 -81.648598)
		(end 301.300642 -81.859882)
		(width 0.089408)
		(layer "In11.Cu")
		(net "PWRGD_CPU0_DRAMPWROK_DEF_G")
	)
	(arc
		(start 302.650652 -81.06918)
		(mid 302.366691 -81.153298)
		(end 302.159162 -81.364582)
		(width 0.089408)
		(layer "In11.Cu")
		(net "PWRGD_CPU0_DRAMPWROK_DEF_G")
	)
	(arc
		(start 294.929052 -81.56448)
		(mid 294.737951 -81.50713)
		(end 294.598344 -81.364582)
		(width 0.089408)
		(layer "In11.Cu")
		(net "PWRGD_CPU0_DRAMPWROK_DEF_G")
	)
	(arc
		(start 300.075092 -81.56448)
		(mid 299.791131 -81.648598)
		(end 299.583602 -81.859882)
		(width 0.089408)
		(layer "In11.Cu")
		(net "PWRGD_CPU0_DRAMPWROK_DEF_G")
	)
	(arc
		(start 291.164264 -80.373982)
		(mid 290.956735 -80.162698)
		(end 290.672774 -80.07858)
		(width 0.089408)
		(layer "In11.Cu")
		(net "PWRGD_CPU0_DRAMPWROK_DEF_G")
	)
	(arc
		(start 292.881304 -80.373982)
		(mid 292.36924 -80.078223)
		(end 291.857176 -80.373982)
		(width 0.089408)
		(layer "In11.Cu")
		(net "PWRGD_CPU0_DRAMPWROK_DEF_G")
	)
	(arc
		(start 293.739824 -80.869282)
		(mid 293.533787 -80.659004)
		(end 293.25189 -80.574134)
		(width 0.089408)
		(layer "In11.Cu")
		(net "PWRGD_CPU0_DRAMPWROK_DEF_G")
	)
	(arc
		(start 291.857176 -80.373982)
		(mid 291.51072 -80.5742)
		(end 291.164264 -80.373982)
		(width 0.089408)
		(layer "In11.Cu")
		(net "PWRGD_CPU0_DRAMPWROK_DEF_G")
	)
	(arc
		(start 297.008042 -81.364582)
		(mid 296.661777 -81.56458)
		(end 296.315384 -81.364582)
		(width 0.089408)
		(layer "In11.Cu")
		(net "PWRGD_CPU0_DRAMPWROK_DEF_G")
	)
	(arc
		(start 301.300642 -81.859882)
		(mid 301.159485 -82.003267)
		(end 300.966378 -82.05978)
		(width 0.089408)
		(layer "In11.Cu")
		(net "PWRGD_CPU0_DRAMPWROK_DEF_G")
	)
	(arc
		(start 296.315384 -81.364582)
		(mid 295.80332 -81.068823)
		(end 295.291256 -81.364582)
		(width 0.089408)
		(layer "In11.Cu")
		(net "PWRGD_CPU0_DRAMPWROK_DEF_G")
	)
	(arc
		(start 303.017682 -80.869282)
		(mid 302.876525 -81.012667)
		(end 302.683418 -81.06918)
		(width 0.089408)
		(layer "In11.Cu")
		(net "PWRGD_CPU0_DRAMPWROK_DEF_G")
	)
	(arc
		(start 299.583602 -81.859882)
		(mid 299.442445 -82.003267)
		(end 299.249338 -82.05978)
		(width 0.089408)
		(layer "In11.Cu")
		(net "PWRGD_CPU0_DRAMPWROK_DEF_G")
	)
	(arc
		(start 298.03217 -81.364582)
		(mid 297.520106 -81.068823)
		(end 297.008042 -81.364582)
		(width 0.089408)
		(layer "In11.Cu")
		(net "PWRGD_CPU0_DRAMPWROK_DEF_G")
	)
	(arc
		(start 298.362878 -81.56448)
		(mid 298.171777 -81.50713)
		(end 298.03217 -81.364582)
		(width 0.089408)
		(layer "In11.Cu")
		(net "PWRGD_CPU0_DRAMPWROK_DEF_G")
	)
	(arc
		(start 300.941994 -82.05978)
		(mid 300.748891 -82.003261)
		(end 300.60773 -81.859882)
		(width 0.089408)
		(layer "In11.Cu")
		(net "PWRGD_CPU0_DRAMPWROK_DEF_G")
	)
	(arc
		(start 302.159162 -81.364582)
		(mid 302.01956 -81.507138)
		(end 301.828454 -81.56448)
		(width 0.089408)
		(layer "In11.Cu")
		(net "PWRGD_CPU0_DRAMPWROK_DEF_G")
	)
	(arc
		(start 303.505616 -80.574134)
		(mid 303.223714 -80.658997)
		(end 303.017682 -80.869282)
		(width 0.089408)
		(layer "In11.Cu")
		(net "PWRGD_CPU0_DRAMPWROK_DEF_G")
	)
	(arc
		(start 293.220648 -80.574134)
		(mid 293.024616 -80.51875)
		(end 292.881304 -80.373982)
		(width 0.089408)
		(layer "In11.Cu")
		(net "PWRGD_CPU0_DRAMPWROK_DEF_G")
	)
	(segment
		(start 282.354274 -67.296538)
		(end 281.782774 -67.296538)
		(width 0.1016)
		(layer "F.Cu")
		(net "PWRGD_CPU0_DRAMPWROK_ABC_G")
	)
	(via
		(at 281.782774 -67.296538)
		(size 0.508)
		(drill 0.254)
		(layers "F.Cu" "B.Cu")
		(net "PWRGD_CPU0_DRAMPWROK_ABC_G")
	)
	(via
		(at 356.32898 -52.811172)
		(size 0.508)
		(drill 0.254)
		(layers "F.Cu" "B.Cu")
		(net "PWRGD_CPU0_DRAMPWROK_ABC_G")
	)
	(via
		(at 354.299774 -57.657238)
		(size 0.508)
		(drill 0.254)
		(layers "F.Cu" "B.Cu")
		(net "PWRGD_CPU0_DRAMPWROK_ABC_G")
	)
	(via
		(at 358.6353 -50.504852)
		(size 0.6604)
		(drill 0.3302)
		(layers "F.Cu" "B.Cu")
		(net "PWRGD_CPU0_DRAMPWROK_ABC_G")
	)
	(segment
		(start 372.869968 -52.23129)
		(end 373.018304 -52.23129)
		(width 0.10795)
		(layer "B.Cu")
		(net "PWRGD_CPU0_DRAMPWROK_ABC_G")
	)
	(segment
		(start 368.254534 -50.363374)
		(end 367.55578 -49.66462)
		(width 0.10795)
		(layer "B.Cu")
		(net "PWRGD_CPU0_DRAMPWROK_ABC_G")
	)
	(segment
		(start 359.257854 -49.882298)
		(end 358.6353 -50.504852)
		(width 0.10795)
		(layer "B.Cu")
		(net "PWRGD_CPU0_DRAMPWROK_ABC_G")
	)
	(segment
		(start 372.869968 -53.507132)
		(end 372.869968 -52.23129)
		(width 0.10795)
		(layer "B.Cu")
		(net "PWRGD_CPU0_DRAMPWROK_ABC_G")
	)
	(segment
		(start 366.588802 -50.199544)
		(end 366.380014 -50.408332)
		(width 0.10795)
		(layer "B.Cu")
		(net "PWRGD_CPU0_DRAMPWROK_ABC_G")
	)
	(segment
		(start 365.53521 -50.408332)
		(end 365.533432 -50.406554)
		(width 0.10795)
		(layer "B.Cu")
		(net "PWRGD_CPU0_DRAMPWROK_ABC_G")
	)
	(segment
		(start 369.8875 -53.86324)
		(end 372.51386 -53.86324)
		(width 0.10795)
		(layer "B.Cu")
		(net "PWRGD_CPU0_DRAMPWROK_ABC_G")
	)
	(segment
		(start 372.51386 -53.86324)
		(end 372.869968 -53.507132)
		(width 0.10795)
		(layer "B.Cu")
		(net "PWRGD_CPU0_DRAMPWROK_ABC_G")
	)
	(segment
		(start 366.380014 -50.408332)
		(end 365.53521 -50.408332)
		(width 0.10795)
		(layer "B.Cu")
		(net "PWRGD_CPU0_DRAMPWROK_ABC_G")
	)
	(segment
		(start 356.32898 -52.811172)
		(end 358.6353 -50.504852)
		(width 0.10795)
		(layer "B.Cu")
		(net "PWRGD_CPU0_DRAMPWROK_ABC_G")
	)
	(segment
		(start 366.594136 -50.199544)
		(end 366.588802 -50.199544)
		(width 0.10795)
		(layer "B.Cu")
		(net "PWRGD_CPU0_DRAMPWROK_ABC_G")
	)
	(segment
		(start 361.256326 -50.406554)
		(end 360.73207 -49.882298)
		(width 0.10795)
		(layer "B.Cu")
		(net "PWRGD_CPU0_DRAMPWROK_ABC_G")
	)
	(segment
		(start 373.018304 -52.23129)
		(end 373.31142 -51.938174)
		(width 0.10795)
		(layer "B.Cu")
		(net "PWRGD_CPU0_DRAMPWROK_ABC_G")
	)
	(segment
		(start 373.31142 -50.81524)
		(end 372.859554 -50.363374)
		(width 0.10795)
		(layer "B.Cu")
		(net "PWRGD_CPU0_DRAMPWROK_ABC_G")
	)
	(segment
		(start 365.533432 -50.406554)
		(end 361.256326 -50.406554)
		(width 0.10795)
		(layer "B.Cu")
		(net "PWRGD_CPU0_DRAMPWROK_ABC_G")
	)
	(segment
		(start 367.55578 -49.66462)
		(end 367.12906 -49.66462)
		(width 0.10795)
		(layer "B.Cu")
		(net "PWRGD_CPU0_DRAMPWROK_ABC_G")
	)
	(segment
		(start 360.73207 -49.882298)
		(end 359.257854 -49.882298)
		(width 0.10795)
		(layer "B.Cu")
		(net "PWRGD_CPU0_DRAMPWROK_ABC_G")
	)
	(segment
		(start 367.12906 -49.66462)
		(end 366.594136 -50.199544)
		(width 0.10795)
		(layer "B.Cu")
		(net "PWRGD_CPU0_DRAMPWROK_ABC_G")
	)
	(segment
		(start 372.859554 -50.363374)
		(end 368.254534 -50.363374)
		(width 0.10795)
		(layer "B.Cu")
		(net "PWRGD_CPU0_DRAMPWROK_ABC_G")
	)
	(segment
		(start 373.31142 -51.938174)
		(end 373.31142 -50.81524)
		(width 0.10795)
		(layer "B.Cu")
		(net "PWRGD_CPU0_DRAMPWROK_ABC_G")
	)
	(segment
		(start 356.047294 -55.254652)
		(end 356.32898 -54.972966)
		(width 0.089408)
		(layer "In9.Cu")
		(net "PWRGD_CPU0_DRAMPWROK_ABC_G")
	)
	(segment
		(start 354.299774 -57.657238)
		(end 354.299774 -56.831992)
		(width 0.089408)
		(layer "In9.Cu")
		(net "PWRGD_CPU0_DRAMPWROK_ABC_G")
	)
	(segment
		(start 355.877114 -55.254652)
		(end 356.047294 -55.254652)
		(width 0.089408)
		(layer "In9.Cu")
		(net "PWRGD_CPU0_DRAMPWROK_ABC_G")
	)
	(segment
		(start 356.32898 -54.972966)
		(end 356.32898 -52.811172)
		(width 0.089408)
		(layer "In9.Cu")
		(net "PWRGD_CPU0_DRAMPWROK_ABC_G")
	)
	(segment
		(start 354.299774 -56.831992)
		(end 355.877114 -55.254652)
		(width 0.089408)
		(layer "In9.Cu")
		(net "PWRGD_CPU0_DRAMPWROK_ABC_G")
	)
	(segment
		(start 296.31513 -62.543436)
		(end 296.32148 -62.554104)
		(width 0.0889)
		(layer "In11.Cu")
		(net "PWRGD_CPU0_DRAMPWROK_ABC_G")
	)
	(segment
		(start 296.31513 -60.562236)
		(end 296.32148 -60.572904)
		(width 0.0889)
		(layer "In11.Cu")
		(net "PWRGD_CPU0_DRAMPWROK_ABC_G")
	)
	(segment
		(start 296.310304 -61.5442)
		(end 296.31513 -61.552836)
		(width 0.0889)
		(layer "In11.Cu")
		(net "PWRGD_CPU0_DRAMPWROK_ABC_G")
	)
	(segment
		(start 308.26456 -59.3344)
		(end 307.6702 -59.3344)
		(width 0.0889)
		(layer "In11.Cu")
		(net "PWRGD_CPU0_DRAMPWROK_ABC_G")
	)
	(segment
		(start 306.5653 -58.546238)
		(end 306.5653 -57.225438)
		(width 0.0889)
		(layer "In11.Cu")
		(net "PWRGD_CPU0_DRAMPWROK_ABC_G")
	)
	(segment
		(start 329.742292 -58.128408)
		(end 328.295508 -58.128408)
		(width 0.089408)
		(layer "In11.Cu")
		(net "PWRGD_CPU0_DRAMPWROK_ABC_G")
	)
	(segment
		(start 284.1244 -66.3194)
		(end 283.739082 -66.704718)
		(width 0.0889)
		(layer "In11.Cu")
		(net "PWRGD_CPU0_DRAMPWROK_ABC_G")
	)
	(segment
		(start 297.537886 -59.466988)
		(end 297.507914 -59.466988)
		(width 0.0889)
		(layer "In11.Cu")
		(net "PWRGD_CPU0_DRAMPWROK_ABC_G")
	)
	(segment
		(start 295.176448 -64.8716)
		(end 294.37076 -64.8716)
		(width 0.0889)
		(layer "In11.Cu")
		(net "PWRGD_CPU0_DRAMPWROK_ABC_G")
	)
	(segment
		(start 285.4198 -65.8368)
		(end 285.121604 -65.8368)
		(width 0.0889)
		(layer "In11.Cu")
		(net "PWRGD_CPU0_DRAMPWROK_ABC_G")
	)
	(segment
		(start 298.400216 -58.971688)
		(end 298.360592 -58.971688)
		(width 0.0889)
		(layer "In11.Cu")
		(net "PWRGD_CPU0_DRAMPWROK_ABC_G")
	)
	(segment
		(start 291.719 -65.7352)
		(end 291.4904 -65.7352)
		(width 0.0889)
		(layer "In11.Cu")
		(net "PWRGD_CPU0_DRAMPWROK_ABC_G")
	)
	(segment
		(start 285.121604 -65.8368)
		(end 284.639004 -66.3194)
		(width 0.0889)
		(layer "In11.Cu")
		(net "PWRGD_CPU0_DRAMPWROK_ABC_G")
	)
	(segment
		(start 325.3232 -57.633108)
		(end 323.13245 -57.633108)
		(width 0.089408)
		(layer "In11.Cu")
		(net "PWRGD_CPU0_DRAMPWROK_ABC_G")
	)
	(segment
		(start 306.57038 -57.220358)
		(end 306.57038 -56.750204)
		(width 0.0889)
		(layer "In11.Cu")
		(net "PWRGD_CPU0_DRAMPWROK_ABC_G")
	)
	(segment
		(start 306.798726 -58.779664)
		(end 306.5653 -58.546238)
		(width 0.0889)
		(layer "In11.Cu")
		(net "PWRGD_CPU0_DRAMPWROK_ABC_G")
	)
	(segment
		(start 295.486328 -64.56172)
		(end 295.176448 -64.8716)
		(width 0.0889)
		(layer "In11.Cu")
		(net "PWRGD_CPU0_DRAMPWROK_ABC_G")
	)
	(segment
		(start 307.6702 -59.3344)
		(end 307.115464 -58.779664)
		(width 0.0889)
		(layer "In11.Cu")
		(net "PWRGD_CPU0_DRAMPWROK_ABC_G")
	)
	(segment
		(start 354.06711 -57.424574)
		(end 330.446126 -57.424574)
		(width 0.089408)
		(layer "In11.Cu")
		(net "PWRGD_CPU0_DRAMPWROK_ABC_G")
	)
	(segment
		(start 291.4904 -65.7352)
		(end 290.9316 -66.294)
		(width 0.0889)
		(layer "In11.Cu")
		(net "PWRGD_CPU0_DRAMPWROK_ABC_G")
	)
	(segment
		(start 325.589392 -57.8993)
		(end 325.3232 -57.633108)
		(width 0.089408)
		(layer "In11.Cu")
		(net "PWRGD_CPU0_DRAMPWROK_ABC_G")
	)
	(segment
		(start 296.31513 -61.552836)
		(end 296.32148 -61.563504)
		(width 0.0889)
		(layer "In11.Cu")
		(net "PWRGD_CPU0_DRAMPWROK_ABC_G")
	)
	(segment
		(start 300.975776 -57.485534)
		(end 300.94301 -57.485534)
		(width 0.0889)
		(layer "In11.Cu")
		(net "PWRGD_CPU0_DRAMPWROK_ABC_G")
	)
	(segment
		(start 293.45636 -65.786)
		(end 292.989 -65.786)
		(width 0.0889)
		(layer "In11.Cu")
		(net "PWRGD_CPU0_DRAMPWROK_ABC_G")
	)
	(segment
		(start 294.37076 -64.8716)
		(end 293.45636 -65.786)
		(width 0.0889)
		(layer "In11.Cu")
		(net "PWRGD_CPU0_DRAMPWROK_ABC_G")
	)
	(segment
		(start 330.446126 -57.424574)
		(end 329.742292 -58.128408)
		(width 0.089408)
		(layer "In11.Cu")
		(net "PWRGD_CPU0_DRAMPWROK_ABC_G")
	)
	(segment
		(start 308.60238 -58.99658)
		(end 308.26456 -59.3344)
		(width 0.089408)
		(layer "In11.Cu")
		(net "PWRGD_CPU0_DRAMPWROK_ABC_G")
	)
	(segment
		(start 319.262506 -61.503052)
		(end 314.710826 -61.503052)
		(width 0.089408)
		(layer "In11.Cu")
		(net "PWRGD_CPU0_DRAMPWROK_ABC_G")
	)
	(segment
		(start 306.57038 -56.750204)
		(end 306.315872 -56.495696)
		(width 0.0889)
		(layer "In11.Cu")
		(net "PWRGD_CPU0_DRAMPWROK_ABC_G")
	)
	(segment
		(start 305.264566 -56.990488)
		(end 305.2318 -56.990488)
		(width 0.0889)
		(layer "In11.Cu")
		(net "PWRGD_CPU0_DRAMPWROK_ABC_G")
	)
	(segment
		(start 354.299774 -57.657238)
		(end 354.06711 -57.424574)
		(width 0.089408)
		(layer "In11.Cu")
		(net "PWRGD_CPU0_DRAMPWROK_ABC_G")
	)
	(segment
		(start 312.204354 -58.99658)
		(end 308.60238 -58.99658)
		(width 0.089408)
		(layer "In11.Cu")
		(net "PWRGD_CPU0_DRAMPWROK_ABC_G")
	)
	(segment
		(start 299.2501 -58.476388)
		(end 299.22597 -58.476388)
		(width 0.0889)
		(layer "In11.Cu")
		(net "PWRGD_CPU0_DRAMPWROK_ABC_G")
	)
	(segment
		(start 292.192964 -66.209164)
		(end 291.719 -65.7352)
		(width 0.0889)
		(layer "In11.Cu")
		(net "PWRGD_CPU0_DRAMPWROK_ABC_G")
	)
	(segment
		(start 323.13245 -57.633108)
		(end 319.262506 -61.503052)
		(width 0.089408)
		(layer "In11.Cu")
		(net "PWRGD_CPU0_DRAMPWROK_ABC_G")
	)
	(segment
		(start 288.504884 -65.8876)
		(end 288.149284 -66.2432)
		(width 0.0889)
		(layer "In11.Cu")
		(net "PWRGD_CPU0_DRAMPWROK_ABC_G")
	)
	(segment
		(start 306.5653 -57.225438)
		(end 306.57038 -57.220358)
		(width 0.0889)
		(layer "In11.Cu")
		(net "PWRGD_CPU0_DRAMPWROK_ABC_G")
	)
	(segment
		(start 328.295508 -58.128408)
		(end 328.0664 -57.8993)
		(width 0.089408)
		(layer "In11.Cu")
		(net "PWRGD_CPU0_DRAMPWROK_ABC_G")
	)
	(segment
		(start 290.9316 -66.294)
		(end 289.7632 -66.294)
		(width 0.0889)
		(layer "In11.Cu")
		(net "PWRGD_CPU0_DRAMPWROK_ABC_G")
	)
	(segment
		(start 289.7632 -66.294)
		(end 289.3568 -65.8876)
		(width 0.0889)
		(layer "In11.Cu")
		(net "PWRGD_CPU0_DRAMPWROK_ABC_G")
	)
	(segment
		(start 289.3568 -65.8876)
		(end 288.504884 -65.8876)
		(width 0.0889)
		(layer "In11.Cu")
		(net "PWRGD_CPU0_DRAMPWROK_ABC_G")
	)
	(segment
		(start 296.310304 -60.5536)
		(end 296.31513 -60.562236)
		(width 0.0889)
		(layer "In11.Cu")
		(net "PWRGD_CPU0_DRAMPWROK_ABC_G")
	)
	(segment
		(start 296.674794 -59.962288)
		(end 296.646854 -59.962288)
		(width 0.0889)
		(layer "In11.Cu")
		(net "PWRGD_CPU0_DRAMPWROK_ABC_G")
	)
	(segment
		(start 286.385 -66.2178)
		(end 285.8008 -66.2178)
		(width 0.0889)
		(layer "In11.Cu")
		(net "PWRGD_CPU0_DRAMPWROK_ABC_G")
	)
	(segment
		(start 295.82491 -63.429134)
		(end 295.792144 -63.429134)
		(width 0.0889)
		(layer "In11.Cu")
		(net "PWRGD_CPU0_DRAMPWROK_ABC_G")
	)
	(segment
		(start 283.739082 -66.704718)
		(end 283.510482 -66.704718)
		(width 0.0889)
		(layer "In11.Cu")
		(net "PWRGD_CPU0_DRAMPWROK_ABC_G")
	)
	(segment
		(start 292.989 -65.786)
		(end 292.565836 -66.209164)
		(width 0.0889)
		(layer "In11.Cu")
		(net "PWRGD_CPU0_DRAMPWROK_ABC_G")
	)
	(segment
		(start 287.0962 -65.786)
		(end 286.8168 -65.786)
		(width 0.0889)
		(layer "In11.Cu")
		(net "PWRGD_CPU0_DRAMPWROK_ABC_G")
	)
	(segment
		(start 282.918662 -67.296538)
		(end 281.782774 -67.296538)
		(width 0.0889)
		(layer "In11.Cu")
		(net "PWRGD_CPU0_DRAMPWROK_ABC_G")
	)
	(segment
		(start 283.510482 -66.704718)
		(end 282.918662 -67.296538)
		(width 0.0889)
		(layer "In11.Cu")
		(net "PWRGD_CPU0_DRAMPWROK_ABC_G")
	)
	(segment
		(start 286.8168 -65.786)
		(end 286.385 -66.2178)
		(width 0.0889)
		(layer "In11.Cu")
		(net "PWRGD_CPU0_DRAMPWROK_ABC_G")
	)
	(segment
		(start 306.315872 -56.495696)
		(end 306.103782 -56.495696)
		(width 0.0889)
		(layer "In11.Cu")
		(net "PWRGD_CPU0_DRAMPWROK_ABC_G")
	)
	(segment
		(start 292.565836 -66.209164)
		(end 292.192964 -66.209164)
		(width 0.0889)
		(layer "In11.Cu")
		(net "PWRGD_CPU0_DRAMPWROK_ABC_G")
	)
	(segment
		(start 307.115464 -58.779664)
		(end 306.798726 -58.779664)
		(width 0.0889)
		(layer "In11.Cu")
		(net "PWRGD_CPU0_DRAMPWROK_ABC_G")
	)
	(segment
		(start 285.8008 -66.2178)
		(end 285.4198 -65.8368)
		(width 0.0889)
		(layer "In11.Cu")
		(net "PWRGD_CPU0_DRAMPWROK_ABC_G")
	)
	(segment
		(start 288.149284 -66.2432)
		(end 287.5534 -66.2432)
		(width 0.0889)
		(layer "In11.Cu")
		(net "PWRGD_CPU0_DRAMPWROK_ABC_G")
	)
	(segment
		(start 296.310304 -62.5348)
		(end 296.31513 -62.543436)
		(width 0.0889)
		(layer "In11.Cu")
		(net "PWRGD_CPU0_DRAMPWROK_ABC_G")
	)
	(segment
		(start 303.544732 -56.990488)
		(end 303.51476 -56.990488)
		(width 0.0889)
		(layer "In11.Cu")
		(net "PWRGD_CPU0_DRAMPWROK_ABC_G")
	)
	(segment
		(start 295.45661 -63.629286)
		(end 295.451784 -63.637922)
		(width 0.0889)
		(layer "In11.Cu")
		(net "PWRGD_CPU0_DRAMPWROK_ABC_G")
	)
	(segment
		(start 284.639004 -66.3194)
		(end 284.1244 -66.3194)
		(width 0.0889)
		(layer "In11.Cu")
		(net "PWRGD_CPU0_DRAMPWROK_ABC_G")
	)
	(segment
		(start 287.5534 -66.2432)
		(end 287.0962 -65.786)
		(width 0.0889)
		(layer "In11.Cu")
		(net "PWRGD_CPU0_DRAMPWROK_ABC_G")
	)
	(segment
		(start 314.710826 -61.503052)
		(end 312.204354 -58.99658)
		(width 0.089408)
		(layer "In11.Cu")
		(net "PWRGD_CPU0_DRAMPWROK_ABC_G")
	)
	(segment
		(start 328.0664 -57.8993)
		(end 325.589392 -57.8993)
		(width 0.089408)
		(layer "In11.Cu")
		(net "PWRGD_CPU0_DRAMPWROK_ABC_G")
	)
	(segment
		(start 300.113446 -57.981088)
		(end 300.08068 -57.981088)
		(width 0.0889)
		(layer "In11.Cu")
		(net "PWRGD_CPU0_DRAMPWROK_ABC_G")
	)
	(arc
		(start 296.31513 -62.143386)
		(mid 296.26166 -62.338449)
		(end 296.310304 -62.5348)
		(width 0.0889)
		(layer "In11.Cu")
		(net "PWRGD_CPU0_DRAMPWROK_ABC_G")
	)
	(arc
		(start 295.45661 -64.029336)
		(mid 295.534947 -64.291992)
		(end 295.486328 -64.56172)
		(width 0.0889)
		(layer "In11.Cu")
		(net "PWRGD_CPU0_DRAMPWROK_ABC_G")
	)
	(arc
		(start 296.31513 -60.162186)
		(mid 296.26166 -60.357249)
		(end 296.310304 -60.5536)
		(width 0.0889)
		(layer "In11.Cu")
		(net "PWRGD_CPU0_DRAMPWROK_ABC_G")
	)
	(arc
		(start 306.103782 -56.495696)
		(mid 305.904492 -56.549143)
		(end 305.758596 -56.695086)
		(width 0.0889)
		(layer "In11.Cu")
		(net "PWRGD_CPU0_DRAMPWROK_ABC_G")
	)
	(arc
		(start 298.360592 -58.971688)
		(mid 298.170663 -59.029558)
		(end 298.031916 -59.171586)
		(width 0.0889)
		(layer "In11.Cu")
		(net "PWRGD_CPU0_DRAMPWROK_ABC_G")
	)
	(arc
		(start 303.183036 -57.190386)
		(mid 302.671226 -57.485925)
		(end 302.159416 -57.190386)
		(width 0.0889)
		(layer "In11.Cu")
		(net "PWRGD_CPU0_DRAMPWROK_ABC_G")
	)
	(arc
		(start 299.22597 -58.476388)
		(mid 299.03212 -58.532738)
		(end 298.890436 -58.67654)
		(width 0.0889)
		(layer "In11.Cu")
		(net "PWRGD_CPU0_DRAMPWROK_ABC_G")
	)
	(arc
		(start 302.159416 -57.190386)
		(mid 301.812706 -56.990202)
		(end 301.465996 -57.190386)
		(width 0.0889)
		(layer "In11.Cu")
		(net "PWRGD_CPU0_DRAMPWROK_ABC_G")
	)
	(arc
		(start 298.890436 -58.67654)
		(mid 298.683432 -58.887404)
		(end 298.400216 -58.971688)
		(width 0.0889)
		(layer "In11.Cu")
		(net "PWRGD_CPU0_DRAMPWROK_ABC_G")
	)
	(arc
		(start 300.94301 -57.485534)
		(mid 300.74916 -57.541884)
		(end 300.607476 -57.685686)
		(width 0.0889)
		(layer "In11.Cu")
		(net "PWRGD_CPU0_DRAMPWROK_ABC_G")
	)
	(arc
		(start 295.451784 -63.637922)
		(mid 295.403029 -63.834274)
		(end 295.45661 -64.029336)
		(width 0.0889)
		(layer "In11.Cu")
		(net "PWRGD_CPU0_DRAMPWROK_ABC_G")
	)
	(arc
		(start 297.507914 -59.466988)
		(mid 297.314811 -59.523507)
		(end 297.17365 -59.666886)
		(width 0.0889)
		(layer "In11.Cu")
		(net "PWRGD_CPU0_DRAMPWROK_ABC_G")
	)
	(arc
		(start 298.031916 -59.171586)
		(mid 297.823308 -59.383518)
		(end 297.537886 -59.466988)
		(width 0.0889)
		(layer "In11.Cu")
		(net "PWRGD_CPU0_DRAMPWROK_ABC_G")
	)
	(arc
		(start 295.792144 -63.429134)
		(mid 295.598294 -63.485484)
		(end 295.45661 -63.629286)
		(width 0.0889)
		(layer "In11.Cu")
		(net "PWRGD_CPU0_DRAMPWROK_ABC_G")
	)
	(arc
		(start 296.31513 -61.152786)
		(mid 296.26166 -61.347849)
		(end 296.310304 -61.5442)
		(width 0.0889)
		(layer "In11.Cu")
		(net "PWRGD_CPU0_DRAMPWROK_ABC_G")
	)
	(arc
		(start 299.748956 -58.180986)
		(mid 299.538243 -58.394065)
		(end 299.2501 -58.476388)
		(width 0.0889)
		(layer "In11.Cu")
		(net "PWRGD_CPU0_DRAMPWROK_ABC_G")
	)
	(arc
		(start 296.32148 -62.554104)
		(mid 296.394278 -62.844867)
		(end 296.31513 -63.133986)
		(width 0.0889)
		(layer "In11.Cu")
		(net "PWRGD_CPU0_DRAMPWROK_ABC_G")
	)
	(arc
		(start 300.08068 -57.981088)
		(mid 299.889038 -58.038254)
		(end 299.748956 -58.180986)
		(width 0.0889)
		(layer "In11.Cu")
		(net "PWRGD_CPU0_DRAMPWROK_ABC_G")
	)
	(arc
		(start 300.607476 -57.685686)
		(mid 300.398868 -57.897618)
		(end 300.113446 -57.981088)
		(width 0.0889)
		(layer "In11.Cu")
		(net "PWRGD_CPU0_DRAMPWROK_ABC_G")
	)
	(arc
		(start 296.646854 -59.962288)
		(mid 296.455212 -60.019454)
		(end 296.31513 -60.162186)
		(width 0.0889)
		(layer "In11.Cu")
		(net "PWRGD_CPU0_DRAMPWROK_ABC_G")
	)
	(arc
		(start 296.32148 -60.572904)
		(mid 296.394278 -60.863667)
		(end 296.31513 -61.152786)
		(width 0.0889)
		(layer "In11.Cu")
		(net "PWRGD_CPU0_DRAMPWROK_ABC_G")
	)
	(arc
		(start 305.758596 -56.695086)
		(mid 305.549988 -56.907018)
		(end 305.264566 -56.990488)
		(width 0.0889)
		(layer "In11.Cu")
		(net "PWRGD_CPU0_DRAMPWROK_ABC_G")
	)
	(arc
		(start 303.876456 -57.190386)
		(mid 303.736377 -57.04765)
		(end 303.544732 -56.990488)
		(width 0.0889)
		(layer "In11.Cu")
		(net "PWRGD_CPU0_DRAMPWROK_ABC_G")
	)
	(arc
		(start 296.31513 -63.133986)
		(mid 296.108126 -63.34485)
		(end 295.82491 -63.429134)
		(width 0.0889)
		(layer "In11.Cu")
		(net "PWRGD_CPU0_DRAMPWROK_ABC_G")
	)
	(arc
		(start 303.51476 -56.990488)
		(mid 303.323118 -57.047654)
		(end 303.183036 -57.190386)
		(width 0.0889)
		(layer "In11.Cu")
		(net "PWRGD_CPU0_DRAMPWROK_ABC_G")
	)
	(arc
		(start 297.17365 -59.666886)
		(mid 296.962937 -59.879965)
		(end 296.674794 -59.962288)
		(width 0.0889)
		(layer "In11.Cu")
		(net "PWRGD_CPU0_DRAMPWROK_ABC_G")
	)
	(arc
		(start 301.465996 -57.190386)
		(mid 301.258992 -57.40125)
		(end 300.975776 -57.485534)
		(width 0.0889)
		(layer "In11.Cu")
		(net "PWRGD_CPU0_DRAMPWROK_ABC_G")
	)
	(arc
		(start 304.900076 -57.190386)
		(mid 304.388266 -57.485925)
		(end 303.876456 -57.190386)
		(width 0.0889)
		(layer "In11.Cu")
		(net "PWRGD_CPU0_DRAMPWROK_ABC_G")
	)
	(arc
		(start 296.32148 -61.563504)
		(mid 296.394278 -61.854267)
		(end 296.31513 -62.143386)
		(width 0.0889)
		(layer "In11.Cu")
		(net "PWRGD_CPU0_DRAMPWROK_ABC_G")
	)
	(arc
		(start 305.2318 -56.990488)
		(mid 305.040158 -57.047654)
		(end 304.900076 -57.190386)
		(width 0.0889)
		(layer "In11.Cu")
		(net "PWRGD_CPU0_DRAMPWROK_ABC_G")
	)
	(segment
		(start 408.721306 -106.136694)
		(end 408.8765 -105.9815)
		(width 0.10795)
		(layer "F.Cu")
		(net "PU_PCH_TLS_ENABLE_STRAP")
	)
	(segment
		(start 463.678778 -7.789672)
		(end 463.678778 -8.558022)
		(width 0.10795)
		(layer "F.Cu")
		(net "PU_PCH_TLS_ENABLE_STRAP")
	)
	(segment
		(start 402.690076 -105.393998)
		(end 402.787104 -105.491026)
		(width 0.10795)
		(layer "F.Cu")
		(net "PU_PCH_TLS_ENABLE_STRAP")
	)
	(segment
		(start 413.921702 -104.944926)
		(end 410.779976 -104.944926)
		(width 0.10795)
		(layer "F.Cu")
		(net "PU_PCH_TLS_ENABLE_STRAP")
	)
	(segment
		(start 409.601416 -105.664)
		(end 409.728416 -105.537)
		(width 0.10795)
		(layer "F.Cu")
		(net "PU_PCH_TLS_ENABLE_STRAP")
	)
	(segment
		(start 401.698206 -105.354882)
		(end 401.799552 -105.253536)
		(width 0.0889)
		(layer "F.Cu")
		(net "PU_PCH_TLS_ENABLE_STRAP")
	)
	(segment
		(start 414.118044 -105.141268)
		(end 413.921702 -104.944926)
		(width 0.10795)
		(layer "F.Cu")
		(net "PU_PCH_TLS_ENABLE_STRAP")
	)
	(segment
		(start 408.8765 -105.664)
		(end 409.601416 -105.664)
		(width 0.10795)
		(layer "F.Cu")
		(net "PU_PCH_TLS_ENABLE_STRAP")
	)
	(segment
		(start 401.799552 -105.253536)
		(end 402.549614 -105.253536)
		(width 0.0889)
		(layer "F.Cu")
		(net "PU_PCH_TLS_ENABLE_STRAP")
	)
	(segment
		(start 463.678778 -8.558022)
		(end 462.75625 -9.48055)
		(width 0.10795)
		(layer "F.Cu")
		(net "PU_PCH_TLS_ENABLE_STRAP")
	)
	(segment
		(start 462.22666 -9.48055)
		(end 461.565244 -10.141966)
		(width 0.10795)
		(layer "F.Cu")
		(net "PU_PCH_TLS_ENABLE_STRAP")
	)
	(segment
		(start 400.880072 -105.354882)
		(end 401.698206 -105.354882)
		(width 0.0889)
		(layer "F.Cu")
		(net "PU_PCH_TLS_ENABLE_STRAP")
	)
	(segment
		(start 404.713694 -106.136694)
		(end 408.721306 -106.136694)
		(width 0.10795)
		(layer "F.Cu")
		(net "PU_PCH_TLS_ENABLE_STRAP")
	)
	(segment
		(start 410.779976 -104.944926)
		(end 410.2735 -105.451402)
		(width 0.10795)
		(layer "F.Cu")
		(net "PU_PCH_TLS_ENABLE_STRAP")
	)
	(segment
		(start 409.728416 -105.537)
		(end 410.2735 -105.537)
		(width 0.10795)
		(layer "F.Cu")
		(net "PU_PCH_TLS_ENABLE_STRAP")
	)
	(segment
		(start 402.787104 -105.491026)
		(end 404.068026 -105.491026)
		(width 0.10795)
		(layer "F.Cu")
		(net "PU_PCH_TLS_ENABLE_STRAP")
	)
	(segment
		(start 462.75625 -9.48055)
		(end 462.22666 -9.48055)
		(width 0.10795)
		(layer "F.Cu")
		(net "PU_PCH_TLS_ENABLE_STRAP")
	)
	(segment
		(start 408.8765 -105.9815)
		(end 408.8765 -105.664)
		(width 0.10795)
		(layer "F.Cu")
		(net "PU_PCH_TLS_ENABLE_STRAP")
	)
	(segment
		(start 410.2735 -105.451402)
		(end 410.2735 -105.537)
		(width 0.10795)
		(layer "F.Cu")
		(net "PU_PCH_TLS_ENABLE_STRAP")
	)
	(segment
		(start 404.068026 -105.491026)
		(end 404.713694 -106.136694)
		(width 0.10795)
		(layer "F.Cu")
		(net "PU_PCH_TLS_ENABLE_STRAP")
	)
	(segment
		(start 402.549614 -105.253536)
		(end 402.690076 -105.393998)
		(width 0.0889)
		(layer "F.Cu")
		(net "PU_PCH_TLS_ENABLE_STRAP")
	)
	(via
		(at 413.726122 -104.527096)
		(size 0.6604)
		(drill 0.3302)
		(layers "F.Cu" "B.Cu")
		(net "PU_PCH_TLS_ENABLE_STRAP")
	)
	(via
		(at 387.24205 -100.181156)
		(size 0.508)
		(drill 0.254)
		(layers "F.Cu" "B.Cu")
		(net "PU_PCH_TLS_ENABLE_STRAP")
	)
	(via
		(at 414.118044 -105.141268)
		(size 0.508)
		(drill 0.254)
		(layers "F.Cu" "B.Cu")
		(net "PU_PCH_TLS_ENABLE_STRAP")
	)
	(via
		(at 461.565244 -10.141966)
		(size 0.508)
		(drill 0.254)
		(layers "F.Cu" "B.Cu")
		(net "PU_PCH_TLS_ENABLE_STRAP")
	)
	(segment
		(start 413.726122 -104.527096)
		(end 413.726122 -104.749346)
		(width 0.10795)
		(layer "B.Cu")
		(net "PU_PCH_TLS_ENABLE_STRAP")
	)
	(segment
		(start 413.726122 -104.749346)
		(end 414.118044 -105.141268)
		(width 0.10795)
		(layer "B.Cu")
		(net "PU_PCH_TLS_ENABLE_STRAP")
	)
	(segment
		(start 402.027136 -102.027482)
		(end 403.225254 -103.2256)
		(width 0.089408)
		(layer "In4.Cu")
		(net "PU_PCH_TLS_ENABLE_STRAP")
	)
	(segment
		(start 391.534396 -98.923856)
		(end 392.855704 -98.923856)
		(width 0.089408)
		(layer "In4.Cu")
		(net "PU_PCH_TLS_ENABLE_STRAP")
	)
	(segment
		(start 393.08913 -99.157282)
		(end 393.08913 -99.29495)
		(width 0.089408)
		(layer "In4.Cu")
		(net "PU_PCH_TLS_ENABLE_STRAP")
	)
	(segment
		(start 395.56563 -100.15347)
		(end 395.992096 -100.579936)
		(width 0.089408)
		(layer "In4.Cu")
		(net "PU_PCH_TLS_ENABLE_STRAP")
	)
	(segment
		(start 404.4442 -103.2256)
		(end 405.0284 -103.8098)
		(width 0.089408)
		(layer "In4.Cu")
		(net "PU_PCH_TLS_ENABLE_STRAP")
	)
	(segment
		(start 395.56563 -100.015802)
		(end 395.56563 -100.15347)
		(width 0.089408)
		(layer "In4.Cu")
		(net "PU_PCH_TLS_ENABLE_STRAP")
	)
	(segment
		(start 395.992096 -100.579936)
		(end 399.747232 -100.579936)
		(width 0.089408)
		(layer "In4.Cu")
		(net "PU_PCH_TLS_ENABLE_STRAP")
	)
	(segment
		(start 395.331696 -99.781868)
		(end 395.56563 -100.015802)
		(width 0.089408)
		(layer "In4.Cu")
		(net "PU_PCH_TLS_ENABLE_STRAP")
	)
	(segment
		(start 387.24205 -100.181156)
		(end 387.681978 -99.741228)
		(width 0.089408)
		(layer "In4.Cu")
		(net "PU_PCH_TLS_ENABLE_STRAP")
	)
	(segment
		(start 393.576048 -99.781868)
		(end 395.331696 -99.781868)
		(width 0.089408)
		(layer "In4.Cu")
		(net "PU_PCH_TLS_ENABLE_STRAP")
	)
	(segment
		(start 387.681978 -99.741228)
		(end 390.854692 -99.741228)
		(width 0.089408)
		(layer "In4.Cu")
		(net "PU_PCH_TLS_ENABLE_STRAP")
	)
	(segment
		(start 399.747232 -100.579936)
		(end 401.194778 -102.027482)
		(width 0.089408)
		(layer "In4.Cu")
		(net "PU_PCH_TLS_ENABLE_STRAP")
	)
	(segment
		(start 390.854692 -99.741228)
		(end 391.10793 -99.48799)
		(width 0.089408)
		(layer "In4.Cu")
		(net "PU_PCH_TLS_ENABLE_STRAP")
	)
	(segment
		(start 393.08913 -99.29495)
		(end 393.576048 -99.781868)
		(width 0.089408)
		(layer "In4.Cu")
		(net "PU_PCH_TLS_ENABLE_STRAP")
	)
	(segment
		(start 411.143196 -102.533196)
		(end 413.751268 -105.141268)
		(width 0.089408)
		(layer "In4.Cu")
		(net "PU_PCH_TLS_ENABLE_STRAP")
	)
	(segment
		(start 392.855704 -98.923856)
		(end 393.08913 -99.157282)
		(width 0.089408)
		(layer "In4.Cu")
		(net "PU_PCH_TLS_ENABLE_STRAP")
	)
	(segment
		(start 403.225254 -103.2256)
		(end 404.4442 -103.2256)
		(width 0.089408)
		(layer "In4.Cu")
		(net "PU_PCH_TLS_ENABLE_STRAP")
	)
	(segment
		(start 405.0284 -103.8098)
		(end 407.99766 -103.8098)
		(width 0.089408)
		(layer "In4.Cu")
		(net "PU_PCH_TLS_ENABLE_STRAP")
	)
	(segment
		(start 407.99766 -103.8098)
		(end 409.274264 -102.533196)
		(width 0.089408)
		(layer "In4.Cu")
		(net "PU_PCH_TLS_ENABLE_STRAP")
	)
	(segment
		(start 391.10793 -99.48799)
		(end 391.10793 -99.350322)
		(width 0.089408)
		(layer "In4.Cu")
		(net "PU_PCH_TLS_ENABLE_STRAP")
	)
	(segment
		(start 413.751268 -105.141268)
		(end 414.118044 -105.141268)
		(width 0.089408)
		(layer "In4.Cu")
		(net "PU_PCH_TLS_ENABLE_STRAP")
	)
	(segment
		(start 391.10793 -99.350322)
		(end 391.534396 -98.923856)
		(width 0.089408)
		(layer "In4.Cu")
		(net "PU_PCH_TLS_ENABLE_STRAP")
	)
	(segment
		(start 409.274264 -102.533196)
		(end 411.143196 -102.533196)
		(width 0.089408)
		(layer "In4.Cu")
		(net "PU_PCH_TLS_ENABLE_STRAP")
	)
	(segment
		(start 401.194778 -102.027482)
		(end 402.027136 -102.027482)
		(width 0.089408)
		(layer "In4.Cu")
		(net "PU_PCH_TLS_ENABLE_STRAP")
	)
	(segment
		(start 437.093614 -21.829268)
		(end 437.768746 -22.5044)
		(width 0.089408)
		(layer "In9.Cu")
		(net "PU_PCH_TLS_ENABLE_STRAP")
	)
	(segment
		(start 451.164706 -26.943304)
		(end 454.085706 -24.022304)
		(width 0.089408)
		(layer "In9.Cu")
		(net "PU_PCH_TLS_ENABLE_STRAP")
	)
	(segment
		(start 399.66138 -43.557444)
		(end 399.895822 -43.323002)
		(width 0.089408)
		(layer "In9.Cu")
		(net "PU_PCH_TLS_ENABLE_STRAP")
	)
	(segment
		(start 432.012344 -22.5171)
		(end 433.581556 -20.947888)
		(width 0.089408)
		(layer "In9.Cu")
		(net "PU_PCH_TLS_ENABLE_STRAP")
	)
	(segment
		(start 454.085706 -24.022304)
		(end 454.368662 -24.022304)
		(width 0.089408)
		(layer "In9.Cu")
		(net "PU_PCH_TLS_ENABLE_STRAP")
	)
	(segment
		(start 393.074906 -77.904086)
		(end 393.074906 -76.637642)
		(width 0.089408)
		(layer "In9.Cu")
		(net "PU_PCH_TLS_ENABLE_STRAP")
	)
	(segment
		(start 441.325 -23.369016)
		(end 441.37834 -23.422356)
		(width 0.089408)
		(layer "In9.Cu")
		(net "PU_PCH_TLS_ENABLE_STRAP")
	)
	(segment
		(start 441.133738 -23.178262)
		(end 441.133992 -23.178262)
		(width 0.089408)
		(layer "In9.Cu")
		(net "PU_PCH_TLS_ENABLE_STRAP")
	)
	(segment
		(start 388.13613 -98.968814)
		(end 387.83387 -98.666554)
		(width 0.089408)
		(layer "In9.Cu")
		(net "PU_PCH_TLS_ENABLE_STRAP")
	)
	(segment
		(start 396.041118 -69.381116)
		(end 396.041118 -65.056258)
		(width 0.089408)
		(layer "In9.Cu")
		(net "PU_PCH_TLS_ENABLE_STRAP")
	)
	(segment
		(start 389.036052 -88.344502)
		(end 391.623296 -85.757258)
		(width 0.089408)
		(layer "In9.Cu")
		(net "PU_PCH_TLS_ENABLE_STRAP")
	)
	(segment
		(start 436.208932 -21.829268)
		(end 437.093614 -21.829268)
		(width 0.089408)
		(layer "In9.Cu")
		(net "PU_PCH_TLS_ENABLE_STRAP")
	)
	(segment
		(start 399.895822 -43.323002)
		(end 399.895822 -41.882822)
		(width 0.089408)
		(layer "In9.Cu")
		(net "PU_PCH_TLS_ENABLE_STRAP")
	)
	(segment
		(start 394.406882 -73.194672)
		(end 394.406882 -72.106028)
		(width 0.089408)
		(layer "In9.Cu")
		(net "PU_PCH_TLS_ENABLE_STRAP")
	)
	(segment
		(start 412.304484 -23.616158)
		(end 413.882586 -22.038056)
		(width 0.089408)
		(layer "In9.Cu")
		(net "PU_PCH_TLS_ENABLE_STRAP")
	)
	(segment
		(start 396.041118 -65.056258)
		(end 396.687294 -64.410082)
		(width 0.089408)
		(layer "In9.Cu")
		(net "PU_PCH_TLS_ENABLE_STRAP")
	)
	(segment
		(start 399.375884 -37.029644)
		(end 399.375884 -31.086044)
		(width 0.089408)
		(layer "In9.Cu")
		(net "PU_PCH_TLS_ENABLE_STRAP")
	)
	(segment
		(start 398.869154 -28.520644)
		(end 398.746218 -28.397708)
		(width 0.089408)
		(layer "In9.Cu")
		(net "PU_PCH_TLS_ENABLE_STRAP")
	)
	(segment
		(start 401.325842 -24.159972)
		(end 401.48383 -24.159972)
		(width 0.089408)
		(layer "In9.Cu")
		(net "PU_PCH_TLS_ENABLE_STRAP")
	)
	(segment
		(start 399.375884 -31.086044)
		(end 398.869154 -30.579314)
		(width 0.089408)
		(layer "In9.Cu")
		(net "PU_PCH_TLS_ENABLE_STRAP")
	)
	(segment
		(start 391.623296 -85.757258)
		(end 391.623296 -84.36864)
		(width 0.089408)
		(layer "In9.Cu")
		(net "PU_PCH_TLS_ENABLE_STRAP")
	)
	(segment
		(start 462.272888 -10.84961)
		(end 461.565244 -10.141966)
		(width 0.089408)
		(layer "In9.Cu")
		(net "PU_PCH_TLS_ENABLE_STRAP")
	)
	(segment
		(start 391.728452 -84.04606)
		(end 392.54176 -83.232752)
		(width 0.089408)
		(layer "In9.Cu")
		(net "PU_PCH_TLS_ENABLE_STRAP")
	)
	(segment
		(start 462.272888 -15.6718)
		(end 462.272888 -10.84961)
		(width 0.089408)
		(layer "In9.Cu")
		(net "PU_PCH_TLS_ENABLE_STRAP")
	)
	(segment
		(start 401.48383 -24.159972)
		(end 401.484084 -24.160226)
		(width 0.089408)
		(layer "In9.Cu")
		(net "PU_PCH_TLS_ENABLE_STRAP")
	)
	(segment
		(start 398.746218 -27.865324)
		(end 398.869154 -27.742388)
		(width 0.089408)
		(layer "In9.Cu")
		(net "PU_PCH_TLS_ENABLE_STRAP")
	)
	(segment
		(start 413.882586 -22.038056)
		(end 413.882586 -22.037802)
		(width 0.089408)
		(layer "In9.Cu")
		(net "PU_PCH_TLS_ENABLE_STRAP")
	)
	(segment
		(start 391.623296 -84.36864)
		(end 391.728452 -84.263484)
		(width 0.089408)
		(layer "In9.Cu")
		(net "PU_PCH_TLS_ENABLE_STRAP")
	)
	(segment
		(start 397.371062 -48.673258)
		(end 396.765272 -48.067468)
		(width 0.089408)
		(layer "In9.Cu")
		(net "PU_PCH_TLS_ENABLE_STRAP")
	)
	(segment
		(start 397.685006 -61.529468)
		(end 397.685006 -60.895992)
		(width 0.089408)
		(layer "In9.Cu")
		(net "PU_PCH_TLS_ENABLE_STRAP")
	)
	(segment
		(start 394.036296 -71.385938)
		(end 396.041118 -69.381116)
		(width 0.089408)
		(layer "In9.Cu")
		(net "PU_PCH_TLS_ENABLE_STRAP")
	)
	(segment
		(start 397.684752 -58.936128)
		(end 397.371062 -58.622438)
		(width 0.089408)
		(layer "In9.Cu")
		(net "PU_PCH_TLS_ENABLE_STRAP")
	)
	(segment
		(start 412.035244 -24.206454)
		(end 412.035244 -24.048466)
		(width 0.089408)
		(layer "In9.Cu")
		(net "PU_PCH_TLS_ENABLE_STRAP")
	)
	(segment
		(start 454.368662 -24.022304)
		(end 454.603104 -23.787862)
		(width 0.089408)
		(layer "In9.Cu")
		(net "PU_PCH_TLS_ENABLE_STRAP")
	)
	(segment
		(start 387.705346 -97.009458)
		(end 387.705346 -96.421194)
		(width 0.089408)
		(layer "In9.Cu")
		(net "PU_PCH_TLS_ENABLE_STRAP")
	)
	(segment
		(start 399.204688 -41.191688)
		(end 399.204688 -37.20084)
		(width 0.089408)
		(layer "In9.Cu")
		(net "PU_PCH_TLS_ENABLE_STRAP")
	)
	(segment
		(start 397.685006 -60.895992)
		(end 397.684752 -60.895738)
		(width 0.089408)
		(layer "In9.Cu")
		(net "PU_PCH_TLS_ENABLE_STRAP")
	)
	(segment
		(start 400.226022 -24.051514)
		(end 400.460464 -23.817072)
		(width 0.089408)
		(layer "In9.Cu")
		(net "PU_PCH_TLS_ENABLE_STRAP")
	)
	(segment
		(start 398.285208 -43.557444)
		(end 399.66138 -43.557444)
		(width 0.089408)
		(layer "In9.Cu")
		(net "PU_PCH_TLS_ENABLE_STRAP")
	)
	(segment
		(start 426.39234 -20.28444)
		(end 428.625 -22.5171)
		(width 0.089408)
		(layer "In9.Cu")
		(net "PU_PCH_TLS_ENABLE_STRAP")
	)
	(segment
		(start 413.882586 -22.037802)
		(end 414.381188 -21.5392)
		(width 0.089408)
		(layer "In9.Cu")
		(net "PU_PCH_TLS_ENABLE_STRAP")
	)
	(segment
		(start 393.4968 -74.104754)
		(end 394.406882 -73.194672)
		(width 0.089408)
		(layer "In9.Cu")
		(net "PU_PCH_TLS_ENABLE_STRAP")
	)
	(segment
		(start 460.290926 -17.653762)
		(end 462.272888 -15.6718)
		(width 0.089408)
		(layer "In9.Cu")
		(net "PU_PCH_TLS_ENABLE_STRAP")
	)
	(segment
		(start 400.226022 -24.383238)
		(end 400.226022 -24.051514)
		(width 0.089408)
		(layer "In9.Cu")
		(net "PU_PCH_TLS_ENABLE_STRAP")
	)
	(segment
		(start 412.03499 -24.364696)
		(end 412.03499 -24.206708)
		(width 0.089408)
		(layer "In9.Cu")
		(net "PU_PCH_TLS_ENABLE_STRAP")
	)
	(segment
		(start 412.113476 -23.806912)
		(end 412.30423 -23.616158)
		(width 0.089408)
		(layer "In9.Cu")
		(net "PU_PCH_TLS_ENABLE_STRAP")
	)
	(segment
		(start 399.204688 -37.20084)
		(end 399.375884 -37.029644)
		(width 0.089408)
		(layer "In9.Cu")
		(net "PU_PCH_TLS_ENABLE_STRAP")
	)
	(segment
		(start 388.13613 -97.440242)
		(end 387.705346 -97.009458)
		(width 0.089408)
		(layer "In9.Cu")
		(net "PU_PCH_TLS_ENABLE_STRAP")
	)
	(segment
		(start 441.133992 -23.178262)
		(end 441.324746 -23.369016)
		(width 0.089408)
		(layer "In9.Cu")
		(net "PU_PCH_TLS_ENABLE_STRAP")
	)
	(segment
		(start 403.928072 -25.517348)
		(end 405.506428 -25.517348)
		(width 0.089408)
		(layer "In9.Cu")
		(net "PU_PCH_TLS_ENABLE_STRAP")
	)
	(segment
		(start 387.49224 -100.181156)
		(end 388.13613 -99.537266)
		(width 0.089408)
		(layer "In9.Cu")
		(net "PU_PCH_TLS_ENABLE_STRAP")
	)
	(segment
		(start 400.982942 -23.817072)
		(end 401.325842 -24.159972)
		(width 0.089408)
		(layer "In9.Cu")
		(net "PU_PCH_TLS_ENABLE_STRAP")
	)
	(segment
		(start 437.768746 -22.5044)
		(end 440.459876 -22.5044)
		(width 0.089408)
		(layer "In9.Cu")
		(net "PU_PCH_TLS_ENABLE_STRAP")
	)
	(segment
		(start 403.229064 -24.81834)
		(end 403.928072 -25.517348)
		(width 0.089408)
		(layer "In9.Cu")
		(net "PU_PCH_TLS_ENABLE_STRAP")
	)
	(segment
		(start 387.83387 -98.118422)
		(end 388.13613 -97.816162)
		(width 0.089408)
		(layer "In9.Cu")
		(net "PU_PCH_TLS_ENABLE_STRAP")
	)
	(segment
		(start 387.876796 -90.71737)
		(end 389.036052 -89.558114)
		(width 0.089408)
		(layer "In9.Cu")
		(net "PU_PCH_TLS_ENABLE_STRAP")
	)
	(segment
		(start 435.892194 -21.829522)
		(end 436.208678 -21.829522)
		(width 0.089408)
		(layer "In9.Cu")
		(net "PU_PCH_TLS_ENABLE_STRAP")
	)
	(segment
		(start 406.410668 -24.613108)
		(end 409.135834 -24.613108)
		(width 0.089408)
		(layer "In9.Cu")
		(net "PU_PCH_TLS_ENABLE_STRAP")
	)
	(segment
		(start 412.03499 -24.206708)
		(end 412.035244 -24.206454)
		(width 0.089408)
		(layer "In9.Cu")
		(net "PU_PCH_TLS_ENABLE_STRAP")
	)
	(segment
		(start 398.869154 -30.579314)
		(end 398.869154 -28.520644)
		(width 0.089408)
		(layer "In9.Cu")
		(net "PU_PCH_TLS_ENABLE_STRAP")
	)
	(segment
		(start 412.113222 -23.806912)
		(end 412.113476 -23.806912)
		(width 0.089408)
		(layer "In9.Cu")
		(net "PU_PCH_TLS_ENABLE_STRAP")
	)
	(segment
		(start 433.581556 -20.947888)
		(end 434.452014 -20.947888)
		(width 0.089408)
		(layer "In9.Cu")
		(net "PU_PCH_TLS_ENABLE_STRAP")
	)
	(segment
		(start 444.789052 -23.422356)
		(end 448.31 -26.943304)
		(width 0.089408)
		(layer "In9.Cu")
		(net "PU_PCH_TLS_ENABLE_STRAP")
	)
	(segment
		(start 387.876796 -91.797124)
		(end 387.876796 -90.71737)
		(width 0.089408)
		(layer "In9.Cu")
		(net "PU_PCH_TLS_ENABLE_STRAP")
	)
	(segment
		(start 387.24205 -100.181156)
		(end 387.49224 -100.181156)
		(width 0.089408)
		(layer "In9.Cu")
		(net "PU_PCH_TLS_ENABLE_STRAP")
	)
	(segment
		(start 393.4968 -76.215748)
		(end 393.4968 -74.104754)
		(width 0.089408)
		(layer "In9.Cu")
		(net "PU_PCH_TLS_ENABLE_STRAP")
	)
	(segment
		(start 392.54176 -83.232752)
		(end 392.54176 -79.00797)
		(width 0.089408)
		(layer "In9.Cu")
		(net "PU_PCH_TLS_ENABLE_STRAP")
	)
	(segment
		(start 397.371062 -58.622438)
		(end 397.371062 -48.673258)
		(width 0.089408)
		(layer "In9.Cu")
		(net "PU_PCH_TLS_ENABLE_STRAP")
	)
	(segment
		(start 409.135834 -24.613108)
		(end 409.4353 -24.912574)
		(width 0.089408)
		(layer "In9.Cu")
		(net "PU_PCH_TLS_ENABLE_STRAP")
	)
	(segment
		(start 412.035244 -24.048466)
		(end 412.034736 -24.047958)
		(width 0.089408)
		(layer "In9.Cu")
		(net "PU_PCH_TLS_ENABLE_STRAP")
	)
	(segment
		(start 436.208678 -21.829522)
		(end 436.208932 -21.829268)
		(width 0.089408)
		(layer "In9.Cu")
		(net "PU_PCH_TLS_ENABLE_STRAP")
	)
	(segment
		(start 387.33857 -96.054418)
		(end 387.33857 -92.33535)
		(width 0.089408)
		(layer "In9.Cu")
		(net "PU_PCH_TLS_ENABLE_STRAP")
	)
	(segment
		(start 398.746218 -28.397708)
		(end 398.746218 -27.865324)
		(width 0.089408)
		(layer "In9.Cu")
		(net "PU_PCH_TLS_ENABLE_STRAP")
	)
	(segment
		(start 388.13613 -99.537266)
		(end 388.13613 -98.968814)
		(width 0.089408)
		(layer "In9.Cu")
		(net "PU_PCH_TLS_ENABLE_STRAP")
	)
	(segment
		(start 448.31 -26.943304)
		(end 451.164706 -26.943304)
		(width 0.089408)
		(layer "In9.Cu")
		(net "PU_PCH_TLS_ENABLE_STRAP")
	)
	(segment
		(start 420.320978 -21.5392)
		(end 421.510968 -20.34921)
		(width 0.089408)
		(layer "In9.Cu")
		(net "PU_PCH_TLS_ENABLE_STRAP")
	)
	(segment
		(start 412.034736 -23.885398)
		(end 412.113222 -23.806912)
		(width 0.089408)
		(layer "In9.Cu")
		(net "PU_PCH_TLS_ENABLE_STRAP")
	)
	(segment
		(start 405.506428 -25.517348)
		(end 406.410668 -24.613108)
		(width 0.089408)
		(layer "In9.Cu")
		(net "PU_PCH_TLS_ENABLE_STRAP")
	)
	(segment
		(start 391.728452 -84.263484)
		(end 391.728452 -84.04606)
		(width 0.089408)
		(layer "In9.Cu")
		(net "PU_PCH_TLS_ENABLE_STRAP")
	)
	(segment
		(start 441.324746 -23.369016)
		(end 441.325 -23.369016)
		(width 0.089408)
		(layer "In9.Cu")
		(net "PU_PCH_TLS_ENABLE_STRAP")
	)
	(segment
		(start 396.687294 -64.410082)
		(end 396.687294 -62.52718)
		(width 0.089408)
		(layer "In9.Cu")
		(net "PU_PCH_TLS_ENABLE_STRAP")
	)
	(segment
		(start 460.290926 -17.97558)
		(end 460.290926 -17.653762)
		(width 0.089408)
		(layer "In9.Cu")
		(net "PU_PCH_TLS_ENABLE_STRAP")
	)
	(segment
		(start 387.33857 -92.33535)
		(end 387.876796 -91.797124)
		(width 0.089408)
		(layer "In9.Cu")
		(net "PU_PCH_TLS_ENABLE_STRAP")
	)
	(segment
		(start 400.226784 -25.09266)
		(end 400.226784 -24.384)
		(width 0.089408)
		(layer "In9.Cu")
		(net "PU_PCH_TLS_ENABLE_STRAP")
	)
	(segment
		(start 392.89228 -78.086712)
		(end 393.074906 -77.904086)
		(width 0.089408)
		(layer "In9.Cu")
		(net "PU_PCH_TLS_ENABLE_STRAP")
	)
	(segment
		(start 421.510968 -20.34921)
		(end 422.031668 -20.34921)
		(width 0.089408)
		(layer "In9.Cu")
		(net "PU_PCH_TLS_ENABLE_STRAP")
	)
	(segment
		(start 398.869154 -27.742388)
		(end 398.869154 -26.45029)
		(width 0.089408)
		(layer "In9.Cu")
		(net "PU_PCH_TLS_ENABLE_STRAP")
	)
	(segment
		(start 392.54176 -79.00797)
		(end 392.89228 -78.65745)
		(width 0.089408)
		(layer "In9.Cu")
		(net "PU_PCH_TLS_ENABLE_STRAP")
	)
	(segment
		(start 422.096438 -20.28444)
		(end 426.39234 -20.28444)
		(width 0.089408)
		(layer "In9.Cu")
		(net "PU_PCH_TLS_ENABLE_STRAP")
	)
	(segment
		(start 402.02358 -24.160226)
		(end 402.681694 -24.81834)
		(width 0.089408)
		(layer "In9.Cu")
		(net "PU_PCH_TLS_ENABLE_STRAP")
	)
	(segment
		(start 397.481552 -44.3611)
		(end 398.285208 -43.557444)
		(width 0.089408)
		(layer "In9.Cu")
		(net "PU_PCH_TLS_ENABLE_STRAP")
	)
	(segment
		(start 441.37834 -23.422356)
		(end 444.789052 -23.422356)
		(width 0.089408)
		(layer "In9.Cu")
		(net "PU_PCH_TLS_ENABLE_STRAP")
	)
	(segment
		(start 428.625 -22.5171)
		(end 432.012344 -22.5171)
		(width 0.089408)
		(layer "In9.Cu")
		(net "PU_PCH_TLS_ENABLE_STRAP")
	)
	(segment
		(start 435.89194 -21.829268)
		(end 435.892194 -21.829522)
		(width 0.089408)
		(layer "In9.Cu")
		(net "PU_PCH_TLS_ENABLE_STRAP")
	)
	(segment
		(start 409.4353 -24.912574)
		(end 411.487112 -24.912574)
		(width 0.089408)
		(layer "In9.Cu")
		(net "PU_PCH_TLS_ENABLE_STRAP")
	)
	(segment
		(start 397.481552 -44.832778)
		(end 397.481552 -44.3611)
		(width 0.089408)
		(layer "In9.Cu")
		(net "PU_PCH_TLS_ENABLE_STRAP")
	)
	(segment
		(start 394.406882 -72.106028)
		(end 394.036296 -71.735442)
		(width 0.089408)
		(layer "In9.Cu")
		(net "PU_PCH_TLS_ENABLE_STRAP")
	)
	(segment
		(start 387.705346 -96.421194)
		(end 387.33857 -96.054418)
		(width 0.089408)
		(layer "In9.Cu")
		(net "PU_PCH_TLS_ENABLE_STRAP")
	)
	(segment
		(start 411.487112 -24.912574)
		(end 412.03499 -24.364696)
		(width 0.089408)
		(layer "In9.Cu")
		(net "PU_PCH_TLS_ENABLE_STRAP")
	)
	(segment
		(start 454.603104 -23.663402)
		(end 460.290926 -17.97558)
		(width 0.089408)
		(layer "In9.Cu")
		(net "PU_PCH_TLS_ENABLE_STRAP")
	)
	(segment
		(start 388.13613 -97.816162)
		(end 388.13613 -97.440242)
		(width 0.089408)
		(layer "In9.Cu")
		(net "PU_PCH_TLS_ENABLE_STRAP")
	)
	(segment
		(start 396.765272 -48.067468)
		(end 396.765272 -45.549058)
		(width 0.089408)
		(layer "In9.Cu")
		(net "PU_PCH_TLS_ENABLE_STRAP")
	)
	(segment
		(start 393.074906 -76.637642)
		(end 393.4968 -76.215748)
		(width 0.089408)
		(layer "In9.Cu")
		(net "PU_PCH_TLS_ENABLE_STRAP")
	)
	(segment
		(start 400.226784 -24.384)
		(end 400.226022 -24.383238)
		(width 0.089408)
		(layer "In9.Cu")
		(net "PU_PCH_TLS_ENABLE_STRAP")
	)
	(segment
		(start 434.452014 -20.947888)
		(end 435.333394 -21.829268)
		(width 0.089408)
		(layer "In9.Cu")
		(net "PU_PCH_TLS_ENABLE_STRAP")
	)
	(segment
		(start 435.333394 -21.829268)
		(end 435.89194 -21.829268)
		(width 0.089408)
		(layer "In9.Cu")
		(net "PU_PCH_TLS_ENABLE_STRAP")
	)
	(segment
		(start 398.869154 -26.45029)
		(end 400.226784 -25.09266)
		(width 0.089408)
		(layer "In9.Cu")
		(net "PU_PCH_TLS_ENABLE_STRAP")
	)
	(segment
		(start 389.036052 -89.558114)
		(end 389.036052 -88.344502)
		(width 0.089408)
		(layer "In9.Cu")
		(net "PU_PCH_TLS_ENABLE_STRAP")
	)
	(segment
		(start 394.036296 -71.735442)
		(end 394.036296 -71.385938)
		(width 0.089408)
		(layer "In9.Cu")
		(net "PU_PCH_TLS_ENABLE_STRAP")
	)
	(segment
		(start 399.895822 -41.882822)
		(end 399.204688 -41.191688)
		(width 0.089408)
		(layer "In9.Cu")
		(net "PU_PCH_TLS_ENABLE_STRAP")
	)
	(segment
		(start 392.89228 -78.65745)
		(end 392.89228 -78.086712)
		(width 0.089408)
		(layer "In9.Cu")
		(net "PU_PCH_TLS_ENABLE_STRAP")
	)
	(segment
		(start 402.681694 -24.81834)
		(end 403.229064 -24.81834)
		(width 0.089408)
		(layer "In9.Cu")
		(net "PU_PCH_TLS_ENABLE_STRAP")
	)
	(segment
		(start 397.684752 -60.895738)
		(end 397.684752 -58.936128)
		(width 0.089408)
		(layer "In9.Cu")
		(net "PU_PCH_TLS_ENABLE_STRAP")
	)
	(segment
		(start 387.83387 -98.666554)
		(end 387.83387 -98.118422)
		(width 0.089408)
		(layer "In9.Cu")
		(net "PU_PCH_TLS_ENABLE_STRAP")
	)
	(segment
		(start 412.30423 -23.616158)
		(end 412.304484 -23.616158)
		(width 0.089408)
		(layer "In9.Cu")
		(net "PU_PCH_TLS_ENABLE_STRAP")
	)
	(segment
		(start 400.460464 -23.817072)
		(end 400.982942 -23.817072)
		(width 0.089408)
		(layer "In9.Cu")
		(net "PU_PCH_TLS_ENABLE_STRAP")
	)
	(segment
		(start 454.603104 -23.787862)
		(end 454.603104 -23.663402)
		(width 0.089408)
		(layer "In9.Cu")
		(net "PU_PCH_TLS_ENABLE_STRAP")
	)
	(segment
		(start 396.687294 -62.52718)
		(end 397.685006 -61.529468)
		(width 0.089408)
		(layer "In9.Cu")
		(net "PU_PCH_TLS_ENABLE_STRAP")
	)
	(segment
		(start 412.034736 -24.047958)
		(end 412.034736 -23.885398)
		(width 0.089408)
		(layer "In9.Cu")
		(net "PU_PCH_TLS_ENABLE_STRAP")
	)
	(segment
		(start 422.031668 -20.34921)
		(end 422.096438 -20.28444)
		(width 0.089408)
		(layer "In9.Cu")
		(net "PU_PCH_TLS_ENABLE_STRAP")
	)
	(segment
		(start 401.484084 -24.160226)
		(end 402.02358 -24.160226)
		(width 0.089408)
		(layer "In9.Cu")
		(net "PU_PCH_TLS_ENABLE_STRAP")
	)
	(segment
		(start 440.459876 -22.5044)
		(end 441.133738 -23.178262)
		(width 0.089408)
		(layer "In9.Cu")
		(net "PU_PCH_TLS_ENABLE_STRAP")
	)
	(segment
		(start 414.381188 -21.5392)
		(end 420.320978 -21.5392)
		(width 0.089408)
		(layer "In9.Cu")
		(net "PU_PCH_TLS_ENABLE_STRAP")
	)
	(segment
		(start 396.765272 -45.549058)
		(end 397.481552 -44.832778)
		(width 0.089408)
		(layer "In9.Cu")
		(net "PU_PCH_TLS_ENABLE_STRAP")
	)
	(segment
		(start 173.176184 -94.847664)
		(end 173.496224 -94.847664)
		(width 0.10795)
		(layer "F.Cu")
		(net "PU_GTL2014_2_DIR")
	)
	(segment
		(start 172.681138 -96.310704)
		(end 172.681138 -95.34271)
		(width 0.10795)
		(layer "F.Cu")
		(net "PU_GTL2014_2_DIR")
	)
	(segment
		(start 173.768004 -93.948504)
		(end 173.182788 -93.948504)
		(width 0.10795)
		(layer "F.Cu")
		(net "PU_GTL2014_2_DIR")
	)
	(segment
		(start 173.182788 -93.948504)
		(end 172.846492 -94.2848)
		(width 0.10795)
		(layer "F.Cu")
		(net "PU_GTL2014_2_DIR")
	)
	(segment
		(start 172.846492 -94.2848)
		(end 172.5676 -94.2848)
		(width 0.10795)
		(layer "F.Cu")
		(net "PU_GTL2014_2_DIR")
	)
	(segment
		(start 173.496224 -94.847664)
		(end 173.768004 -94.575884)
		(width 0.10795)
		(layer "F.Cu")
		(net "PU_GTL2014_2_DIR")
	)
	(segment
		(start 172.681138 -95.34271)
		(end 173.176184 -94.847664)
		(width 0.10795)
		(layer "F.Cu")
		(net "PU_GTL2014_2_DIR")
	)
	(segment
		(start 173.768004 -94.575884)
		(end 173.768004 -93.948504)
		(width 0.10795)
		(layer "F.Cu")
		(net "PU_GTL2014_2_DIR")
	)
	(via
		(at 173.768004 -93.948504)
		(size 0.762)
		(drill 0.381)
		(layers "F.Cu" "B.Cu")
		(net "PU_GTL2014_2_DIR")
	)
	(via
		(at 372.26494 -54.46776)
		(size 0.6604)
		(drill 0.3302)
		(layers "F.Cu" "B.Cu")
		(net "PU_GTL2014_1_DIR")
	)
	(segment
		(start 372.26494 -54.46776)
		(end 372.9228 -53.8099)
		(width 0.10795)
		(layer "B.Cu")
		(net "PU_GTL2014_1_DIR")
	)
	(segment
		(start 371.56898 -55.16372)
		(end 372.26494 -54.46776)
		(width 0.10795)
		(layer "B.Cu")
		(net "PU_GTL2014_1_DIR")
	)
	(segment
		(start 369.8875 -55.16372)
		(end 371.56898 -55.16372)
		(width 0.10795)
		(layer "B.Cu")
		(net "PU_GTL2014_1_DIR")
	)
	(segment
		(start 372.9228 -53.8099)
		(end 373.3038 -53.8099)
		(width 0.10795)
		(layer "B.Cu")
		(net "PU_GTL2014_1_DIR")
	)
	(segment
		(start 298.665646 -66.800984)
		(end 299.237146 -66.800984)
		(width 0.10795)
		(layer "F.Cu")
		(net "PU_CPU0_TSC_SYNC")
	)
	(via
		(at 299.237146 -66.800984)
		(size 0.508)
		(drill 0.254)
		(layers "F.Cu" "B.Cu")
		(net "PU_CPU0_TSC_SYNC")
	)
	(segment
		(start 299.233844 -66.804286)
		(end 299.237146 -66.800984)
		(width 0.10795)
		(layer "B.Cu")
		(net "PU_CPU0_TSC_SYNC")
	)
	(segment
		(start 296.042588 -66.330322)
		(end 296.512996 -66.80073)
		(width 0.10795)
		(layer "B.Cu")
		(net "PU_CPU0_TSC_SYNC")
	)
	(segment
		(start 296.80027 -66.80073)
		(end 297.2562 -66.3448)
		(width 0.10795)
		(layer "B.Cu")
		(net "PU_CPU0_TSC_SYNC")
	)
	(segment
		(start 298.172886 -66.804286)
		(end 299.233844 -66.804286)
		(width 0.10795)
		(layer "B.Cu")
		(net "PU_CPU0_TSC_SYNC")
	)
	(segment
		(start 296.512996 -66.80073)
		(end 296.80027 -66.80073)
		(width 0.10795)
		(layer "B.Cu")
		(net "PU_CPU0_TSC_SYNC")
	)
	(segment
		(start 297.2562 -66.3448)
		(end 297.7134 -66.3448)
		(width 0.10795)
		(layer "B.Cu")
		(net "PU_CPU0_TSC_SYNC")
	)
	(segment
		(start 297.7134 -66.3448)
		(end 298.172886 -66.804286)
		(width 0.10795)
		(layer "B.Cu")
		(net "PU_CPU0_TSC_SYNC")
	)
	(segment
		(start 306.249324 -80.5053)
		(end 305.872388 -80.882236)
		(width 0.0889)
		(layer "F.Cu")
		(net "P3E_CPU0_PE2_SS_TXP<9>")
	)
	(segment
		(start 307.340762 -80.5053)
		(end 306.249324 -80.5053)
		(width 0.0889)
		(layer "F.Cu")
		(net "P3E_CPU0_PE2_SS_TXP<9>")
	)
	(segment
		(start 372.816374 -14.13764)
		(end 372.658132 -14.105382)
		(width 0.1143)
		(layer "F.Cu")
		(net "P3E_CPU0_PE2_SS_TXP<9>")
	)
	(segment
		(start 373.897398 -13.28547)
		(end 373.86514 -13.443712)
		(width 0.1143)
		(layer "F.Cu")
		(net "P3E_CPU0_PE2_SS_TXP<9>")
	)
	(segment
		(start 307.696362 -80.4164)
		(end 307.429662 -80.4164)
		(width 0.0889)
		(layer "F.Cu")
		(net "P3E_CPU0_PE2_SS_TXP<9>")
	)
	(segment
		(start 305.872388 -80.882236)
		(end 305.746658 -80.882236)
		(width 0.0889)
		(layer "F.Cu")
		(net "P3E_CPU0_PE2_SS_TXP<9>")
	)
	(segment
		(start 318.097916 -70.161404)
		(end 312.191908 -78.44536)
		(width 0.1143)
		(layer "F.Cu")
		(net "P3E_CPU0_PE2_SS_TXP<9>")
	)
	(segment
		(start 371.14226 -16.52524)
		(end 371.009926 -16.841724)
		(width 0.1143)
		(layer "F.Cu")
		(net "P3E_CPU0_PE2_SS_TXP<9>")
	)
	(segment
		(start 354.95738 -50.75174)
		(end 349.876364 -51.76774)
		(width 0.1143)
		(layer "F.Cu")
		(net "P3E_CPU0_PE2_SS_TXP<9>")
	)
	(segment
		(start 308.496462 -80.5053)
		(end 308.407562 -80.4164)
		(width 0.0889)
		(layer "F.Cu")
		(net "P3E_CPU0_PE2_SS_TXP<9>")
	)
	(segment
		(start 339.2551 -52.049934)
		(end 337.644994 -51.727862)
		(width 0.1143)
		(layer "F.Cu")
		(net "P3E_CPU0_PE2_SS_TXP<9>")
	)
	(segment
		(start 308.051962 -80.5053)
		(end 307.785262 -80.5053)
		(width 0.0889)
		(layer "F.Cu")
		(net "P3E_CPU0_PE2_SS_TXP<9>")
	)
	(segment
		(start 309.15229 -80.5053)
		(end 308.496462 -80.5053)
		(width 0.0889)
		(layer "F.Cu")
		(net "P3E_CPU0_PE2_SS_TXP<9>")
	)
	(segment
		(start 308.407562 -80.4164)
		(end 308.140862 -80.4164)
		(width 0.0889)
		(layer "F.Cu")
		(net "P3E_CPU0_PE2_SS_TXP<9>")
	)
	(segment
		(start 364.197646 -32.93491)
		(end 362.722922 -37.926772)
		(width 0.1143)
		(layer "F.Cu")
		(net "P3E_CPU0_PE2_SS_TXP<9>")
	)
	(segment
		(start 373.579136 -13.632942)
		(end 373.42064 -13.600684)
		(width 0.1143)
		(layer "F.Cu")
		(net "P3E_CPU0_PE2_SS_TXP<9>")
	)
	(segment
		(start 373.42064 -13.600684)
		(end 373.134636 -13.789914)
		(width 0.1143)
		(layer "F.Cu")
		(net "P3E_CPU0_PE2_SS_TXP<9>")
	)
	(segment
		(start 370.7892 -17.368774)
		(end 370.656866 -17.685258)
		(width 0.1143)
		(layer "F.Cu")
		(net "P3E_CPU0_PE2_SS_TXP<9>")
	)
	(segment
		(start 305.746658 -80.882236)
		(end 305.533806 -80.669384)
		(width 0.0889)
		(layer "F.Cu")
		(net "P3E_CPU0_PE2_SS_TXP<9>")
	)
	(segment
		(start 307.785262 -80.5053)
		(end 307.696362 -80.4164)
		(width 0.0889)
		(layer "F.Cu")
		(net "P3E_CPU0_PE2_SS_TXP<9>")
	)
	(segment
		(start 377.002294 -11.26617)
		(end 376.963178 -11.393932)
		(width 0.1143)
		(layer "F.Cu")
		(net "P3E_CPU0_PE2_SS_TXP<9>")
	)
	(segment
		(start 309.199788 -80.4799)
		(end 309.17769 -80.4799)
		(width 0.0889)
		(layer "F.Cu")
		(net "P3E_CPU0_PE2_SS_TXP<9>")
	)
	(segment
		(start 347.58249 -51.309016)
		(end 343.5985 -52.105814)
		(width 0.1143)
		(layer "F.Cu")
		(net "P3E_CPU0_PE2_SS_TXP<9>")
	)
	(segment
		(start 308.140862 -80.4164)
		(end 308.051962 -80.5053)
		(width 0.0889)
		(layer "F.Cu")
		(net "P3E_CPU0_PE2_SS_TXP<9>")
	)
	(segment
		(start 309.17769 -80.4799)
		(end 309.15229 -80.5053)
		(width 0.0889)
		(layer "F.Cu")
		(net "P3E_CPU0_PE2_SS_TXP<9>")
	)
	(segment
		(start 370.720366 -22.173184)
		(end 371.066568 -23.902416)
		(width 0.1143)
		(layer "F.Cu")
		(net "P3E_CPU0_PE2_SS_TXP<9>")
	)
	(segment
		(start 309.345076 -80.4799)
		(end 309.199788 -80.4799)
		(width 0.1143)
		(layer "F.Cu")
		(net "P3E_CPU0_PE2_SS_TXP<9>")
	)
	(segment
		(start 374.341644 -13.128498)
		(end 374.183148 -13.09624)
		(width 0.1143)
		(layer "F.Cu")
		(net "P3E_CPU0_PE2_SS_TXP<9>")
	)
	(segment
		(start 362.722922 -37.926772)
		(end 363.364272 -40.582596)
		(width 0.1143)
		(layer "F.Cu")
		(net "P3E_CPU0_PE2_SS_TXP<9>")
	)
	(segment
		(start 323.814948 -65.885822)
		(end 318.53759 -69.544692)
		(width 0.1143)
		(layer "F.Cu")
		(net "P3E_CPU0_PE2_SS_TXP<9>")
	)
	(segment
		(start 371.07114 -16.99133)
		(end 370.938806 -17.30756)
		(width 0.1143)
		(layer "F.Cu")
		(net "P3E_CPU0_PE2_SS_TXP<9>")
	)
	(segment
		(start 370.938806 -17.30756)
		(end 370.7892 -17.368774)
		(width 0.1143)
		(layer "F.Cu")
		(net "P3E_CPU0_PE2_SS_TXP<9>")
	)
	(segment
		(start 335.062068 -52.572158)
		(end 331.97546 -54.98211)
		(width 0.1143)
		(layer "F.Cu")
		(net "P3E_CPU0_PE2_SS_TXP<9>")
	)
	(segment
		(start 376.678444 -10.916158)
		(end 377.002294 -11.240008)
		(width 0.1143)
		(layer "F.Cu")
		(net "P3E_CPU0_PE2_SS_TXP<9>")
	)
	(segment
		(start 312.191908 -78.44536)
		(end 309.345076 -80.4799)
		(width 0.1143)
		(layer "F.Cu")
		(net "P3E_CPU0_PE2_SS_TXP<9>")
	)
	(segment
		(start 372.658132 -14.105382)
		(end 372.372128 -14.294358)
		(width 0.1143)
		(layer "F.Cu")
		(net "P3E_CPU0_PE2_SS_TXP<9>")
	)
	(segment
		(start 371.066568 -23.902416)
		(end 370.101114 -28.727146)
		(width 0.1143)
		(layer "F.Cu")
		(net "P3E_CPU0_PE2_SS_TXP<9>")
	)
	(segment
		(start 370.101114 -28.727146)
		(end 364.197646 -32.93491)
		(width 0.1143)
		(layer "F.Cu")
		(net "P3E_CPU0_PE2_SS_TXP<9>")
	)
	(segment
		(start 307.429662 -80.4164)
		(end 307.340762 -80.5053)
		(width 0.0889)
		(layer "F.Cu")
		(net "P3E_CPU0_PE2_SS_TXP<9>")
	)
	(segment
		(start 363.364272 -40.582596)
		(end 362.305346 -45.790358)
		(width 0.1143)
		(layer "F.Cu")
		(net "P3E_CPU0_PE2_SS_TXP<9>")
	)
	(segment
		(start 337.644994 -51.727862)
		(end 335.062068 -52.572158)
		(width 0.1143)
		(layer "F.Cu")
		(net "P3E_CPU0_PE2_SS_TXP<9>")
	)
	(segment
		(start 372.372128 -14.294358)
		(end 372.33987 -14.452854)
		(width 0.1143)
		(layer "F.Cu")
		(net "P3E_CPU0_PE2_SS_TXP<9>")
	)
	(segment
		(start 371.009926 -16.841724)
		(end 371.07114 -16.99133)
		(width 0.1143)
		(layer "F.Cu")
		(net "P3E_CPU0_PE2_SS_TXP<9>")
	)
	(segment
		(start 370.718334 -17.834864)
		(end 370.586 -18.151094)
		(width 0.1143)
		(layer "F.Cu")
		(net "P3E_CPU0_PE2_SS_TXP<9>")
	)
	(segment
		(start 376.963178 -11.393932)
		(end 374.341644 -13.128498)
		(width 0.1143)
		(layer "F.Cu")
		(net "P3E_CPU0_PE2_SS_TXP<9>")
	)
	(segment
		(start 343.5985 -52.105814)
		(end 341.2871 -51.643534)
		(width 0.1143)
		(layer "F.Cu")
		(net "P3E_CPU0_PE2_SS_TXP<9>")
	)
	(segment
		(start 341.2871 -51.643534)
		(end 339.2551 -52.049934)
		(width 0.1143)
		(layer "F.Cu")
		(net "P3E_CPU0_PE2_SS_TXP<9>")
	)
	(segment
		(start 331.97546 -54.98211)
		(end 323.814948 -65.885822)
		(width 0.1143)
		(layer "F.Cu")
		(net "P3E_CPU0_PE2_SS_TXP<9>")
	)
	(segment
		(start 362.305346 -45.790358)
		(end 354.95738 -50.75174)
		(width 0.1143)
		(layer "F.Cu")
		(net "P3E_CPU0_PE2_SS_TXP<9>")
	)
	(segment
		(start 377.002294 -11.240008)
		(end 377.002294 -11.26617)
		(width 0.1143)
		(layer "F.Cu")
		(net "P3E_CPU0_PE2_SS_TXP<9>")
	)
	(segment
		(start 370.586 -18.151094)
		(end 371.05717 -20.518374)
		(width 0.1143)
		(layer "F.Cu")
		(net "P3E_CPU0_PE2_SS_TXP<9>")
	)
	(segment
		(start 349.876364 -51.76774)
		(end 347.58249 -51.309016)
		(width 0.1143)
		(layer "F.Cu")
		(net "P3E_CPU0_PE2_SS_TXP<9>")
	)
	(segment
		(start 372.053866 -14.642084)
		(end 371.291612 -16.464026)
		(width 0.1143)
		(layer "F.Cu")
		(net "P3E_CPU0_PE2_SS_TXP<9>")
	)
	(segment
		(start 373.86514 -13.443712)
		(end 373.579136 -13.632942)
		(width 0.1143)
		(layer "F.Cu")
		(net "P3E_CPU0_PE2_SS_TXP<9>")
	)
	(segment
		(start 371.05717 -20.518374)
		(end 370.720366 -22.173184)
		(width 0.1143)
		(layer "F.Cu")
		(net "P3E_CPU0_PE2_SS_TXP<9>")
	)
	(segment
		(start 372.33987 -14.452854)
		(end 372.053866 -14.642084)
		(width 0.1143)
		(layer "F.Cu")
		(net "P3E_CPU0_PE2_SS_TXP<9>")
	)
	(segment
		(start 371.291612 -16.464026)
		(end 371.14226 -16.52524)
		(width 0.1143)
		(layer "F.Cu")
		(net "P3E_CPU0_PE2_SS_TXP<9>")
	)
	(segment
		(start 370.656866 -17.685258)
		(end 370.718334 -17.834864)
		(width 0.1143)
		(layer "F.Cu")
		(net "P3E_CPU0_PE2_SS_TXP<9>")
	)
	(segment
		(start 373.134636 -13.789914)
		(end 373.102378 -13.94841)
		(width 0.1143)
		(layer "F.Cu")
		(net "P3E_CPU0_PE2_SS_TXP<9>")
	)
	(segment
		(start 373.102378 -13.94841)
		(end 372.816374 -14.13764)
		(width 0.1143)
		(layer "F.Cu")
		(net "P3E_CPU0_PE2_SS_TXP<9>")
	)
	(segment
		(start 374.183148 -13.09624)
		(end 373.897398 -13.28547)
		(width 0.1143)
		(layer "F.Cu")
		(net "P3E_CPU0_PE2_SS_TXP<9>")
	)
	(segment
		(start 318.53759 -69.544692)
		(end 318.097916 -70.161404)
		(width 0.1143)
		(layer "F.Cu")
		(net "P3E_CPU0_PE2_SS_TXP<9>")
	)
	(via
		(at 318.097916 -70.161404)
		(size 0.508)
		(drill 0.254)
		(layers "F.Cu" "B.Cu")
		(net "P3E_CPU0_PE2_SS_TXP<9>")
	)
	(segment
		(start 372.499128 -16.439642)
		(end 372.631462 -16.123158)
		(width 0.1143)
		(layer "F.Cu")
		(net "P3E_CPU0_PE2_SS_TXP<8>")
	)
	(segment
		(start 379.2474 -11.547348)
		(end 379.2474 -11.262614)
		(width 0.1143)
		(layer "F.Cu")
		(net "P3E_CPU0_PE2_SS_TXP<8>")
	)
	(segment
		(start 379.2474 -11.262614)
		(end 378.926344 -10.941558)
		(width 0.1143)
		(layer "F.Cu")
		(net "P3E_CPU0_PE2_SS_TXP<8>")
	)
	(segment
		(start 373.184674 -15.096236)
		(end 377.13666 -12.482068)
		(width 0.1143)
		(layer "F.Cu")
		(net "P3E_CPU0_PE2_SS_TXP<8>")
	)
	(segment
		(start 312.420762 -79.973678)
		(end 319.249552 -70.396608)
		(width 0.1143)
		(layer "F.Cu")
		(net "P3E_CPU0_PE2_SS_TXP<8>")
	)
	(segment
		(start 364.379256 -40.454326)
		(end 363.7788 -37.967666)
		(width 0.1143)
		(layer "F.Cu")
		(net "P3E_CPU0_PE2_SS_TXP<8>")
	)
	(segment
		(start 372.428262 -16.905478)
		(end 372.560596 -16.588994)
		(width 0.1143)
		(layer "F.Cu")
		(net "P3E_CPU0_PE2_SS_TXP<8>")
	)
	(segment
		(start 309.380128 -81.539334)
		(end 312.420762 -79.973678)
		(width 0.1143)
		(layer "F.Cu")
		(net "P3E_CPU0_PE2_SS_TXP<8>")
	)
	(segment
		(start 337.209892 -53.972714)
		(end 338.276946 -53.759354)
		(width 0.1143)
		(layer "F.Cu")
		(net "P3E_CPU0_PE2_SS_TXP<8>")
	)
	(segment
		(start 377.13666 -12.482068)
		(end 378.387356 -12.213844)
		(width 0.1143)
		(layer "F.Cu")
		(net "P3E_CPU0_PE2_SS_TXP<8>")
	)
	(segment
		(start 372.075456 -17.749012)
		(end 372.20779 -17.432782)
		(width 0.1143)
		(layer "F.Cu")
		(net "P3E_CPU0_PE2_SS_TXP<8>")
	)
	(segment
		(start 370.82476 -30.155642)
		(end 372.08714 -23.849076)
		(width 0.1143)
		(layer "F.Cu")
		(net "P3E_CPU0_PE2_SS_TXP<8>")
	)
	(segment
		(start 372.146322 -17.283176)
		(end 372.278656 -16.966692)
		(width 0.1143)
		(layer "F.Cu")
		(net "P3E_CPU0_PE2_SS_TXP<8>")
	)
	(segment
		(start 372.062756 -20.430744)
		(end 371.705124 -18.634456)
		(width 0.1143)
		(layer "F.Cu")
		(net "P3E_CPU0_PE2_SS_TXP<8>")
	)
	(segment
		(start 344.741754 -54.335934)
		(end 348.328742 -53.598572)
		(width 0.1143)
		(layer "F.Cu")
		(net "P3E_CPU0_PE2_SS_TXP<8>")
	)
	(segment
		(start 334.67675 -54.23535)
		(end 336.136742 -53.75783)
		(width 0.1143)
		(layer "F.Cu")
		(net "P3E_CPU0_PE2_SS_TXP<8>")
	)
	(segment
		(start 354.321872 -52.366672)
		(end 363.17555 -46.371002)
		(width 0.1143)
		(layer "F.Cu")
		(net "P3E_CPU0_PE2_SS_TXP<8>")
	)
	(segment
		(start 319.249552 -70.396608)
		(end 324.237858 -66.938144)
		(width 0.1143)
		(layer "F.Cu")
		(net "P3E_CPU0_PE2_SS_TXP<8>")
	)
	(segment
		(start 372.20779 -17.432782)
		(end 372.146322 -17.283176)
		(width 0.1143)
		(layer "F.Cu")
		(net "P3E_CPU0_PE2_SS_TXP<8>")
	)
	(segment
		(start 371.92585 -17.810226)
		(end 372.075456 -17.749012)
		(width 0.1143)
		(layer "F.Cu")
		(net "P3E_CPU0_PE2_SS_TXP<8>")
	)
	(segment
		(start 332.361794 -56.09463)
		(end 334.67675 -54.23535)
		(width 0.1143)
		(layer "F.Cu")
		(net "P3E_CPU0_PE2_SS_TXP<8>")
	)
	(segment
		(start 338.276946 -53.759354)
		(end 340.308946 -54.165754)
		(width 0.1143)
		(layer "F.Cu")
		(net "P3E_CPU0_PE2_SS_TXP<8>")
	)
	(segment
		(start 372.08714 -23.849076)
		(end 371.730016 -22.06498)
		(width 0.1143)
		(layer "F.Cu")
		(net "P3E_CPU0_PE2_SS_TXP<8>")
	)
	(segment
		(start 348.328742 -53.598572)
		(end 354.322126 -52.366672)
		(width 0.1143)
		(layer "F.Cu")
		(net "P3E_CPU0_PE2_SS_TXP<8>")
	)
	(segment
		(start 342.0999 -53.807614)
		(end 344.741754 -54.335934)
		(width 0.1143)
		(layer "F.Cu")
		(net "P3E_CPU0_PE2_SS_TXP<8>")
	)
	(segment
		(start 308.868826 -81.564734)
		(end 308.894226 -81.539334)
		(width 0.0889)
		(layer "F.Cu")
		(net "P3E_CPU0_PE2_SS_TXP<8>")
	)
	(segment
		(start 336.136742 -53.75783)
		(end 337.209892 -53.972714)
		(width 0.1143)
		(layer "F.Cu")
		(net "P3E_CPU0_PE2_SS_TXP<8>")
	)
	(segment
		(start 306.392326 -81.564734)
		(end 308.868826 -81.564734)
		(width 0.0889)
		(layer "F.Cu")
		(net "P3E_CPU0_PE2_SS_TXP<8>")
	)
	(segment
		(start 372.781068 -16.061944)
		(end 373.184674 -15.096236)
		(width 0.1143)
		(layer "F.Cu")
		(net "P3E_CPU0_PE2_SS_TXP<8>")
	)
	(segment
		(start 372.278656 -16.966692)
		(end 372.428262 -16.905478)
		(width 0.1143)
		(layer "F.Cu")
		(net "P3E_CPU0_PE2_SS_TXP<8>")
	)
	(segment
		(start 340.308946 -54.165754)
		(end 342.0999 -53.807614)
		(width 0.1143)
		(layer "F.Cu")
		(net "P3E_CPU0_PE2_SS_TXP<8>")
	)
	(segment
		(start 354.322126 -52.366672)
		(end 354.321872 -52.366672)
		(width 0.1143)
		(layer "F.Cu")
		(net "P3E_CPU0_PE2_SS_TXP<8>")
	)
	(segment
		(start 378.387356 -12.213844)
		(end 379.2474 -11.547348)
		(width 0.1143)
		(layer "F.Cu")
		(net "P3E_CPU0_PE2_SS_TXP<8>")
	)
	(segment
		(start 372.631462 -16.123158)
		(end 372.781068 -16.061944)
		(width 0.1143)
		(layer "F.Cu")
		(net "P3E_CPU0_PE2_SS_TXP<8>")
	)
	(segment
		(start 371.793516 -18.12671)
		(end 371.92585 -17.810226)
		(width 0.1143)
		(layer "F.Cu")
		(net "P3E_CPU0_PE2_SS_TXP<8>")
	)
	(segment
		(start 371.854984 -18.276316)
		(end 371.793516 -18.12671)
		(width 0.1143)
		(layer "F.Cu")
		(net "P3E_CPU0_PE2_SS_TXP<8>")
	)
	(segment
		(start 324.237858 -66.938144)
		(end 332.361794 -56.09463)
		(width 0.1143)
		(layer "F.Cu")
		(net "P3E_CPU0_PE2_SS_TXP<8>")
	)
	(segment
		(start 305.799744 -82.03946)
		(end 305.848512 -81.924398)
		(width 0.0889)
		(layer "F.Cu")
		(net "P3E_CPU0_PE2_SS_TXP<8>")
	)
	(segment
		(start 371.705124 -18.634456)
		(end 371.854984 -18.276316)
		(width 0.1143)
		(layer "F.Cu")
		(net "P3E_CPU0_PE2_SS_TXP<8>")
	)
	(segment
		(start 308.894226 -81.539334)
		(end 309.380128 -81.539334)
		(width 0.1143)
		(layer "F.Cu")
		(net "P3E_CPU0_PE2_SS_TXP<8>")
	)
	(segment
		(start 363.17555 -46.371002)
		(end 364.379256 -40.454326)
		(width 0.1143)
		(layer "F.Cu")
		(net "P3E_CPU0_PE2_SS_TXP<8>")
	)
	(segment
		(start 371.730016 -22.06498)
		(end 372.062756 -20.430744)
		(width 0.1143)
		(layer "F.Cu")
		(net "P3E_CPU0_PE2_SS_TXP<8>")
	)
	(segment
		(start 364.827566 -34.431732)
		(end 370.82476 -30.155642)
		(width 0.1143)
		(layer "F.Cu")
		(net "P3E_CPU0_PE2_SS_TXP<8>")
	)
	(segment
		(start 372.560596 -16.588994)
		(end 372.499128 -16.439642)
		(width 0.1143)
		(layer "F.Cu")
		(net "P3E_CPU0_PE2_SS_TXP<8>")
	)
	(segment
		(start 363.7788 -37.967666)
		(end 364.827566 -34.431732)
		(width 0.1143)
		(layer "F.Cu")
		(net "P3E_CPU0_PE2_SS_TXP<8>")
	)
	(via
		(at 348.328742 -53.598572)
		(size 0.508)
		(drill 0.254)
		(layers "F.Cu" "B.Cu")
		(net "P3E_CPU0_PE2_SS_TXP<8>")
	)
	(arc
		(start 305.848512 -81.924398)
		(mid 306.066264 -81.662702)
		(end 306.392326 -81.564734)
		(width 0.0889)
		(layer "F.Cu")
		(net "P3E_CPU0_PE2_SS_TXP<8>")
	)
	(arc
		(start 305.533806 -82.650584)
		(mid 305.666917 -82.347502)
		(end 305.797966 -82.043524)
		(width 0.0889)
		(layer "F.Cu")
		(net "P3E_CPU0_PE2_SS_TXP<8>")
	)
	(arc
		(start 305.797966 -82.043524)
		(mid 305.798848 -82.041489)
		(end 305.799744 -82.03946)
		(width 0.0889)
		(layer "F.Cu")
		(net "P3E_CPU0_PE2_SS_TXP<8>")
	)
	(segment
		(start 308.143656 -82.529934)
		(end 308.165754 -82.529934)
		(width 0.0889)
		(layer "F.Cu")
		(net "P3E_CPU0_PE2_SS_TXP<7>")
	)
	(segment
		(start 370.282978 -38.270688)
		(end 370.06657 -37.189156)
		(width 0.1143)
		(layer "F.Cu")
		(net "P3E_CPU0_PE2_SS_TXP<7>")
	)
	(segment
		(start 377.589034 -14.471396)
		(end 377.68022 -14.338046)
		(width 0.1143)
		(layer "F.Cu")
		(net "P3E_CPU0_PE2_SS_TXP<7>")
	)
	(segment
		(start 375.79173 -14.808708)
		(end 375.882916 -14.675358)
		(width 0.1143)
		(layer "F.Cu")
		(net "P3E_CPU0_PE2_SS_TXP<7>")
	)
	(segment
		(start 370.702078 -34.012632)
		(end 371.941852 -30.06979)
		(width 0.1143)
		(layer "F.Cu")
		(net "P3E_CPU0_PE2_SS_TXP<7>")
	)
	(segment
		(start 364.148624 -46.879002)
		(end 368.240564 -46.061376)
		(width 0.1143)
		(layer "F.Cu")
		(net "P3E_CPU0_PE2_SS_TXP<7>")
	)
	(segment
		(start 393.578842 -11.241786)
		(end 393.254992 -10.917936)
		(width 0.1143)
		(layer "F.Cu")
		(net "P3E_CPU0_PE2_SS_TXP<7>")
	)
	(segment
		(start 362.938822 -47.69866)
		(end 363.543088 -47.289466)
		(width 0.1143)
		(layer "F.Cu")
		(net "P3E_CPU0_PE2_SS_TXP<7>")
	)
	(segment
		(start 332.735682 -57.26684)
		(end 337.124548 -55.830724)
		(width 0.1143)
		(layer "F.Cu")
		(net "P3E_CPU0_PE2_SS_TXP<7>")
	)
	(segment
		(start 371.941852 -30.06979)
		(end 373.143526 -24.05634)
		(width 0.1143)
		(layer "F.Cu")
		(net "P3E_CPU0_PE2_SS_TXP<7>")
	)
	(segment
		(start 370.201952 -42.360596)
		(end 369.853972 -40.414448)
		(width 0.1143)
		(layer "F.Cu")
		(net "P3E_CPU0_PE2_SS_TXP<7>")
	)
	(segment
		(start 351.741486 -55.282846)
		(end 352.388678 -54.854856)
		(width 0.1143)
		(layer "F.Cu")
		(net "P3E_CPU0_PE2_SS_TXP<7>")
	)
	(segment
		(start 337.124548 -55.830724)
		(end 338.310982 -56.082184)
		(width 0.1143)
		(layer "F.Cu")
		(net "P3E_CPU0_PE2_SS_TXP<7>")
	)
	(segment
		(start 320.322702 -70.935088)
		(end 324.844156 -67.799966)
		(width 0.1143)
		(layer "F.Cu")
		(net "P3E_CPU0_PE2_SS_TXP<7>")
	)
	(segment
		(start 347.934788 -56.073548)
		(end 347.934788 -56.073294)
		(width 0.1143)
		(layer "F.Cu")
		(net "P3E_CPU0_PE2_SS_TXP<7>")
	)
	(segment
		(start 313.492642 -80.514698)
		(end 314.278264 -79.412592)
		(width 0.1143)
		(layer "F.Cu")
		(net "P3E_CPU0_PE2_SS_TXP<7>")
	)
	(segment
		(start 347.934788 -56.073294)
		(end 347.935296 -56.073548)
		(width 0.1143)
		(layer "F.Cu")
		(net "P3E_CPU0_PE2_SS_TXP<7>")
	)
	(segment
		(start 376.690382 -14.640052)
		(end 376.781568 -14.506702)
		(width 0.1143)
		(layer "F.Cu")
		(net "P3E_CPU0_PE2_SS_TXP<7>")
	)
	(segment
		(start 308.165754 -82.529934)
		(end 309.581296 -82.529934)
		(width 0.1143)
		(layer "F.Cu")
		(net "P3E_CPU0_PE2_SS_TXP<7>")
	)
	(segment
		(start 377.68022 -14.338046)
		(end 378.017278 -14.2748)
		(width 0.1143)
		(layer "F.Cu")
		(net "P3E_CPU0_PE2_SS_TXP<7>")
	)
	(segment
		(start 379.04928 -14.19733)
		(end 393.421108 -11.502136)
		(width 0.1143)
		(layer "F.Cu")
		(net "P3E_CPU0_PE2_SS_TXP<7>")
	)
	(segment
		(start 347.935296 -56.073548)
		(end 351.741232 -55.2831)
		(width 0.1143)
		(layer "F.Cu")
		(net "P3E_CPU0_PE2_SS_TXP<7>")
	)
	(segment
		(start 378.017278 -14.2748)
		(end 378.150628 -14.365986)
		(width 0.1143)
		(layer "F.Cu")
		(net "P3E_CPU0_PE2_SS_TXP<7>")
	)
	(segment
		(start 306.391818 -82.555334)
		(end 308.118256 -82.555334)
		(width 0.0889)
		(layer "F.Cu")
		(net "P3E_CPU0_PE2_SS_TXP<7>")
	)
	(segment
		(start 351.741232 -55.2831)
		(end 351.741486 -55.282846)
		(width 0.1143)
		(layer "F.Cu")
		(net "P3E_CPU0_PE2_SS_TXP<7>")
	)
	(segment
		(start 338.310982 -56.082184)
		(end 342.287098 -54.946296)
		(width 0.1143)
		(layer "F.Cu")
		(net "P3E_CPU0_PE2_SS_TXP<7>")
	)
	(segment
		(start 378.578872 -14.16939)
		(end 378.91593 -14.106144)
		(width 0.1143)
		(layer "F.Cu")
		(net "P3E_CPU0_PE2_SS_TXP<7>")
	)
	(segment
		(start 314.278264 -79.412592)
		(end 320.322702 -70.935088)
		(width 0.1143)
		(layer "F.Cu")
		(net "P3E_CPU0_PE2_SS_TXP<7>")
	)
	(segment
		(start 373.948706 -15.869666)
		(end 375.454672 -14.871954)
		(width 0.1143)
		(layer "F.Cu")
		(net "P3E_CPU0_PE2_SS_TXP<7>")
	)
	(segment
		(start 358.086406 -52.89296)
		(end 360.617262 -51.181)
		(width 0.1143)
		(layer "F.Cu")
		(net "P3E_CPU0_PE2_SS_TXP<7>")
	)
	(segment
		(start 393.578842 -11.312144)
		(end 393.578842 -11.241786)
		(width 0.1143)
		(layer "F.Cu")
		(net "P3E_CPU0_PE2_SS_TXP<7>")
	)
	(segment
		(start 372.749064 -18.73885)
		(end 373.948706 -15.869666)
		(width 0.1143)
		(layer "F.Cu")
		(net "P3E_CPU0_PE2_SS_TXP<7>")
	)
	(segment
		(start 372.741952 -22.049994)
		(end 373.07901 -20.396454)
		(width 0.1143)
		(layer "F.Cu")
		(net "P3E_CPU0_PE2_SS_TXP<7>")
	)
	(segment
		(start 373.07901 -20.396454)
		(end 372.749064 -18.73885)
		(width 0.1143)
		(layer "F.Cu")
		(net "P3E_CPU0_PE2_SS_TXP<7>")
	)
	(segment
		(start 360.617262 -51.181)
		(end 362.938822 -47.69866)
		(width 0.1143)
		(layer "F.Cu")
		(net "P3E_CPU0_PE2_SS_TXP<7>")
	)
	(segment
		(start 378.150628 -14.365986)
		(end 378.487686 -14.30274)
		(width 0.1143)
		(layer "F.Cu")
		(net "P3E_CPU0_PE2_SS_TXP<7>")
	)
	(segment
		(start 342.287098 -54.946296)
		(end 347.934788 -56.073548)
		(width 0.1143)
		(layer "F.Cu")
		(net "P3E_CPU0_PE2_SS_TXP<7>")
	)
	(segment
		(start 377.118626 -14.443456)
		(end 377.251976 -14.534642)
		(width 0.1143)
		(layer "F.Cu")
		(net "P3E_CPU0_PE2_SS_TXP<7>")
	)
	(segment
		(start 393.421108 -11.502136)
		(end 393.578842 -11.312144)
		(width 0.1143)
		(layer "F.Cu")
		(net "P3E_CPU0_PE2_SS_TXP<7>")
	)
	(segment
		(start 378.487686 -14.30274)
		(end 378.578872 -14.16939)
		(width 0.1143)
		(layer "F.Cu")
		(net "P3E_CPU0_PE2_SS_TXP<7>")
	)
	(segment
		(start 369.853972 -40.414448)
		(end 370.282978 -38.270688)
		(width 0.1143)
		(layer "F.Cu")
		(net "P3E_CPU0_PE2_SS_TXP<7>")
	)
	(segment
		(start 352.388678 -54.854856)
		(end 358.086406 -52.89296)
		(width 0.1143)
		(layer "F.Cu")
		(net "P3E_CPU0_PE2_SS_TXP<7>")
	)
	(segment
		(start 369.17249 -45.43044)
		(end 370.201952 -42.360596)
		(width 0.1143)
		(layer "F.Cu")
		(net "P3E_CPU0_PE2_SS_TXP<7>")
	)
	(segment
		(start 370.06657 -37.189156)
		(end 370.702078 -34.012632)
		(width 0.1143)
		(layer "F.Cu")
		(net "P3E_CPU0_PE2_SS_TXP<7>")
	)
	(segment
		(start 324.844156 -67.799966)
		(end 332.735682 -57.26684)
		(width 0.1143)
		(layer "F.Cu")
		(net "P3E_CPU0_PE2_SS_TXP<7>")
	)
	(segment
		(start 363.543088 -47.289466)
		(end 364.148624 -46.879002)
		(width 0.1143)
		(layer "F.Cu")
		(net "P3E_CPU0_PE2_SS_TXP<7>")
	)
	(segment
		(start 375.454672 -14.871954)
		(end 375.79173 -14.808708)
		(width 0.1143)
		(layer "F.Cu")
		(net "P3E_CPU0_PE2_SS_TXP<7>")
	)
	(segment
		(start 309.581296 -82.529934)
		(end 313.492642 -80.514698)
		(width 0.1143)
		(layer "F.Cu")
		(net "P3E_CPU0_PE2_SS_TXP<7>")
	)
	(segment
		(start 377.251976 -14.534642)
		(end 377.589034 -14.471396)
		(width 0.1143)
		(layer "F.Cu")
		(net "P3E_CPU0_PE2_SS_TXP<7>")
	)
	(segment
		(start 376.781568 -14.506702)
		(end 377.118626 -14.443456)
		(width 0.1143)
		(layer "F.Cu")
		(net "P3E_CPU0_PE2_SS_TXP<7>")
	)
	(segment
		(start 308.118256 -82.555334)
		(end 308.143656 -82.529934)
		(width 0.0889)
		(layer "F.Cu")
		(net "P3E_CPU0_PE2_SS_TXP<7>")
	)
	(segment
		(start 378.91593 -14.106144)
		(end 379.04928 -14.19733)
		(width 0.1143)
		(layer "F.Cu")
		(net "P3E_CPU0_PE2_SS_TXP<7>")
	)
	(segment
		(start 376.219974 -14.612112)
		(end 376.353324 -14.703298)
		(width 0.1143)
		(layer "F.Cu")
		(net "P3E_CPU0_PE2_SS_TXP<7>")
	)
	(segment
		(start 368.240564 -46.061376)
		(end 369.17249 -45.43044)
		(width 0.1143)
		(layer "F.Cu")
		(net "P3E_CPU0_PE2_SS_TXP<7>")
	)
	(segment
		(start 305.516026 -83.050634)
		(end 305.55184 -83.050634)
		(width 0.0889)
		(layer "F.Cu")
		(net "P3E_CPU0_PE2_SS_TXP<7>")
	)
	(segment
		(start 373.143526 -24.05634)
		(end 372.741952 -22.049994)
		(width 0.1143)
		(layer "F.Cu")
		(net "P3E_CPU0_PE2_SS_TXP<7>")
	)
	(segment
		(start 376.353324 -14.703298)
		(end 376.690382 -14.640052)
		(width 0.1143)
		(layer "F.Cu")
		(net "P3E_CPU0_PE2_SS_TXP<7>")
	)
	(segment
		(start 375.882916 -14.675358)
		(end 376.219974 -14.612112)
		(width 0.1143)
		(layer "F.Cu")
		(net "P3E_CPU0_PE2_SS_TXP<7>")
	)
	(via
		(at 314.278264 -79.412592)
		(size 0.508)
		(drill 0.254)
		(layers "F.Cu" "B.Cu")
		(net "P3E_CPU0_PE2_SS_TXP<7>")
	)
	(arc
		(start 304.675286 -83.146138)
		(mid 305.092952 -83.074585)
		(end 305.516026 -83.050634)
		(width 0.0889)
		(layer "F.Cu")
		(net "P3E_CPU0_PE2_SS_TXP<7>")
	)
	(arc
		(start 305.880516 -82.850736)
		(mid 306.09659 -82.634521)
		(end 306.391818 -82.555334)
		(width 0.0889)
		(layer "F.Cu")
		(net "P3E_CPU0_PE2_SS_TXP<7>")
	)
	(arc
		(start 305.55184 -83.050634)
		(mid 305.741802 -82.992787)
		(end 305.880516 -82.850736)
		(width 0.0889)
		(layer "F.Cu")
		(net "P3E_CPU0_PE2_SS_TXP<7>")
	)
	(segment
		(start 395.902942 -11.292586)
		(end 395.902942 -11.5316)
		(width 0.1143)
		(layer "F.Cu")
		(net "P3E_CPU0_PE2_SS_TXP<6>")
	)
	(segment
		(start 394.516356 -12.291822)
		(end 375.891044 -15.810992)
		(width 0.1143)
		(layer "F.Cu")
		(net "P3E_CPU0_PE2_SS_TXP<6>")
	)
	(segment
		(start 362.941108 -50.701448)
		(end 362.657136 -50.893726)
		(width 0.1143)
		(layer "F.Cu")
		(net "P3E_CPU0_PE2_SS_TXP<6>")
	)
	(segment
		(start 373.799862 -22.101302)
		(end 374.16232 -23.9141)
		(width 0.1143)
		(layer "F.Cu")
		(net "P3E_CPU0_PE2_SS_TXP<6>")
	)
	(segment
		(start 364.239302 -49.050702)
		(end 364.271052 -49.209198)
		(width 0.1143)
		(layer "F.Cu")
		(net "P3E_CPU0_PE2_SS_TXP<6>")
	)
	(segment
		(start 317.24473 -76.91882)
		(end 314.145168 -81.266284)
		(width 0.1143)
		(layer "F.Cu")
		(net "P3E_CPU0_PE2_SS_TXP<6>")
	)
	(segment
		(start 338.369402 -57.104026)
		(end 337.160108 -56.84774)
		(width 0.1143)
		(layer "F.Cu")
		(net "P3E_CPU0_PE2_SS_TXP<6>")
	)
	(segment
		(start 395.414754 -12.12215)
		(end 395.077696 -12.185904)
		(width 0.1143)
		(layer "F.Cu")
		(net "P3E_CPU0_PE2_SS_TXP<6>")
	)
	(segment
		(start 333.445866 -58.06313)
		(end 327.874122 -65.495932)
		(width 0.1143)
		(layer "F.Cu")
		(net "P3E_CPU0_PE2_SS_TXP<6>")
	)
	(segment
		(start 355.64572 -55.779924)
		(end 348.794578 -57.237122)
		(width 0.1143)
		(layer "F.Cu")
		(net "P3E_CPU0_PE2_SS_TXP<6>")
	)
	(segment
		(start 370.921026 -40.285416)
		(end 371.279166 -42.28719)
		(width 0.1143)
		(layer "F.Cu")
		(net "P3E_CPU0_PE2_SS_TXP<6>")
	)
	(segment
		(start 374.121172 -20.493228)
		(end 373.799862 -22.101302)
		(width 0.1143)
		(layer "F.Cu")
		(net "P3E_CPU0_PE2_SS_TXP<6>")
	)
	(segment
		(start 374.743218 -16.57096)
		(end 373.793004 -18.843498)
		(width 0.1143)
		(layer "F.Cu")
		(net "P3E_CPU0_PE2_SS_TXP<6>")
	)
	(segment
		(start 309.779416 -83.5152)
		(end 306.761388 -83.5152)
		(width 0.1143)
		(layer "F.Cu")
		(net "P3E_CPU0_PE2_SS_TXP<6>")
	)
	(segment
		(start 327.874122 -65.495932)
		(end 326.14616 -68.09867)
		(width 0.1143)
		(layer "F.Cu")
		(net "P3E_CPU0_PE2_SS_TXP<6>")
	)
	(segment
		(start 371.279166 -42.28719)
		(end 370.026946 -46.018958)
		(width 0.1143)
		(layer "F.Cu")
		(net "P3E_CPU0_PE2_SS_TXP<6>")
	)
	(segment
		(start 363.099858 -50.731928)
		(end 362.941108 -50.701448)
		(width 0.1143)
		(layer "F.Cu")
		(net "P3E_CPU0_PE2_SS_TXP<6>")
	)
	(segment
		(start 326.14616 -68.09867)
		(end 320.979292 -71.680578)
		(width 0.1143)
		(layer "F.Cu")
		(net "P3E_CPU0_PE2_SS_TXP<6>")
	)
	(segment
		(start 363.38383 -50.53965)
		(end 363.099858 -50.731928)
		(width 0.1143)
		(layer "F.Cu")
		(net "P3E_CPU0_PE2_SS_TXP<6>")
	)
	(segment
		(start 363.732064 -49.811432)
		(end 363.76356 -49.969928)
		(width 0.1143)
		(layer "F.Cu")
		(net "P3E_CPU0_PE2_SS_TXP<6>")
	)
	(segment
		(start 362.657136 -50.893726)
		(end 362.626656 -51.052476)
		(width 0.1143)
		(layer "F.Cu")
		(net "P3E_CPU0_PE2_SS_TXP<6>")
	)
	(segment
		(start 373.793004 -18.843498)
		(end 374.121172 -20.493228)
		(width 0.1143)
		(layer "F.Cu")
		(net "P3E_CPU0_PE2_SS_TXP<6>")
	)
	(segment
		(start 371.093492 -37.336222)
		(end 371.30228 -38.379654)
		(width 0.1143)
		(layer "F.Cu")
		(net "P3E_CPU0_PE2_SS_TXP<6>")
	)
	(segment
		(start 368.617754 -46.972982)
		(end 366.223804 -47.451772)
		(width 0.1143)
		(layer "F.Cu")
		(net "P3E_CPU0_PE2_SS_TXP<6>")
	)
	(segment
		(start 363.92231 -49.52619)
		(end 363.732064 -49.811432)
		(width 0.1143)
		(layer "F.Cu")
		(net "P3E_CPU0_PE2_SS_TXP<6>")
	)
	(segment
		(start 395.077696 -12.185904)
		(end 394.944346 -12.094718)
		(width 0.1143)
		(layer "F.Cu")
		(net "P3E_CPU0_PE2_SS_TXP<6>")
	)
	(segment
		(start 395.902942 -11.5316)
		(end 395.414754 -12.12215)
		(width 0.1143)
		(layer "F.Cu")
		(net "P3E_CPU0_PE2_SS_TXP<6>")
	)
	(segment
		(start 374.16232 -23.9141)
		(end 372.864126 -30.40634)
		(width 0.1143)
		(layer "F.Cu")
		(net "P3E_CPU0_PE2_SS_TXP<6>")
	)
	(segment
		(start 364.429548 -48.765206)
		(end 364.239302 -49.050702)
		(width 0.1143)
		(layer "F.Cu")
		(net "P3E_CPU0_PE2_SS_TXP<6>")
	)
	(segment
		(start 370.026946 -46.018958)
		(end 368.617754 -46.972982)
		(width 0.1143)
		(layer "F.Cu")
		(net "P3E_CPU0_PE2_SS_TXP<6>")
	)
	(segment
		(start 371.809772 -33.755584)
		(end 371.093492 -37.336222)
		(width 0.1143)
		(layer "F.Cu")
		(net "P3E_CPU0_PE2_SS_TXP<6>")
	)
	(segment
		(start 372.864126 -30.40634)
		(end 371.809772 -33.755584)
		(width 0.1143)
		(layer "F.Cu")
		(net "P3E_CPU0_PE2_SS_TXP<6>")
	)
	(segment
		(start 375.891044 -15.810992)
		(end 374.743218 -16.57096)
		(width 0.1143)
		(layer "F.Cu")
		(net "P3E_CPU0_PE2_SS_TXP<6>")
	)
	(segment
		(start 371.30228 -38.379654)
		(end 370.921026 -40.285416)
		(width 0.1143)
		(layer "F.Cu")
		(net "P3E_CPU0_PE2_SS_TXP<6>")
	)
	(segment
		(start 364.588044 -48.73371)
		(end 364.429548 -48.765206)
		(width 0.1143)
		(layer "F.Cu")
		(net "P3E_CPU0_PE2_SS_TXP<6>")
	)
	(segment
		(start 314.145168 -81.266284)
		(end 309.779416 -83.5152)
		(width 0.1143)
		(layer "F.Cu")
		(net "P3E_CPU0_PE2_SS_TXP<6>")
	)
	(segment
		(start 394.944346 -12.094718)
		(end 394.607288 -12.158472)
		(width 0.1143)
		(layer "F.Cu")
		(net "P3E_CPU0_PE2_SS_TXP<6>")
	)
	(segment
		(start 320.979292 -71.680578)
		(end 317.24473 -76.91882)
		(width 0.1143)
		(layer "F.Cu")
		(net "P3E_CPU0_PE2_SS_TXP<6>")
	)
	(segment
		(start 348.794578 -57.237122)
		(end 342.385142 -55.956708)
		(width 0.1143)
		(layer "F.Cu")
		(net "P3E_CPU0_PE2_SS_TXP<6>")
	)
	(segment
		(start 362.626656 -51.052476)
		(end 355.64572 -55.779924)
		(width 0.1143)
		(layer "F.Cu")
		(net "P3E_CPU0_PE2_SS_TXP<6>")
	)
	(segment
		(start 363.76356 -49.969928)
		(end 363.38383 -50.53965)
		(width 0.1143)
		(layer "F.Cu")
		(net "P3E_CPU0_PE2_SS_TXP<6>")
	)
	(segment
		(start 364.271052 -49.209198)
		(end 364.080806 -49.49444)
		(width 0.1143)
		(layer "F.Cu")
		(net "P3E_CPU0_PE2_SS_TXP<6>")
	)
	(segment
		(start 394.607288 -12.158472)
		(end 394.516356 -12.291822)
		(width 0.1143)
		(layer "F.Cu")
		(net "P3E_CPU0_PE2_SS_TXP<6>")
	)
	(segment
		(start 364.81766 -48.389032)
		(end 364.588044 -48.73371)
		(width 0.1143)
		(layer "F.Cu")
		(net "P3E_CPU0_PE2_SS_TXP<6>")
	)
	(segment
		(start 306.761388 -83.5152)
		(end 306.392326 -83.146138)
		(width 0.1143)
		(layer "F.Cu")
		(net "P3E_CPU0_PE2_SS_TXP<6>")
	)
	(segment
		(start 337.160108 -56.84774)
		(end 333.445866 -58.06313)
		(width 0.1143)
		(layer "F.Cu")
		(net "P3E_CPU0_PE2_SS_TXP<6>")
	)
	(segment
		(start 366.223804 -47.451772)
		(end 364.81766 -48.389032)
		(width 0.1143)
		(layer "F.Cu")
		(net "P3E_CPU0_PE2_SS_TXP<6>")
	)
	(segment
		(start 342.385142 -55.956708)
		(end 338.369402 -57.104026)
		(width 0.1143)
		(layer "F.Cu")
		(net "P3E_CPU0_PE2_SS_TXP<6>")
	)
	(segment
		(start 395.579092 -10.968736)
		(end 395.902942 -11.292586)
		(width 0.1143)
		(layer "F.Cu")
		(net "P3E_CPU0_PE2_SS_TXP<6>")
	)
	(segment
		(start 364.080806 -49.49444)
		(end 363.92231 -49.52619)
		(width 0.1143)
		(layer "F.Cu")
		(net "P3E_CPU0_PE2_SS_TXP<6>")
	)
	(via
		(at 317.24473 -76.91882)
		(size 0.508)
		(drill 0.254)
		(layers "F.Cu" "B.Cu")
		(net "P3E_CPU0_PE2_SS_TXP<6>")
	)
	(segment
		(start 358.18572 -57.680606)
		(end 358.325166 -57.598818)
		(width 0.1143)
		(layer "F.Cu")
		(net "P3E_CPU0_PE2_SS_TXP<5>")
	)
	(segment
		(start 358.416606 -56.79567)
		(end 358.555798 -56.713882)
		(width 0.1143)
		(layer "F.Cu")
		(net "P3E_CPU0_PE2_SS_TXP<5>")
	)
	(segment
		(start 320.255392 -74.459084)
		(end 321.747134 -72.328532)
		(width 0.1143)
		(layer "F.Cu")
		(net "P3E_CPU0_PE2_SS_TXP<5>")
	)
	(segment
		(start 308.400704 -85.006434)
		(end 308.41188 -85.006434)
		(width 0.0889)
		(layer "F.Cu")
		(net "P3E_CPU0_PE2_SS_TXP<5>")
	)
	(segment
		(start 358.41178 -57.267094)
		(end 358.329992 -57.127648)
		(width 0.1143)
		(layer "F.Cu")
		(net "P3E_CPU0_PE2_SS_TXP<5>")
	)
	(segment
		(start 376.240548 -16.75511)
		(end 396.759176 -13.006832)
		(width 0.1143)
		(layer "F.Cu")
		(net "P3E_CPU0_PE2_SS_TXP<5>")
	)
	(segment
		(start 370.929916 -46.574964)
		(end 372.323614 -42.420794)
		(width 0.1143)
		(layer "F.Cu")
		(net "P3E_CPU0_PE2_SS_TXP<5>")
	)
	(segment
		(start 375.17832 -24.041608)
		(end 374.814846 -22.22373)
		(width 0.1143)
		(layer "F.Cu")
		(net "P3E_CPU0_PE2_SS_TXP<5>")
	)
	(segment
		(start 372.676166 -34.953194)
		(end 373.080788 -34.345372)
		(width 0.1143)
		(layer "F.Cu")
		(net "P3E_CPU0_PE2_SS_TXP<5>")
	)
	(segment
		(start 357.06558 -60.191142)
		(end 357.984552 -58.905902)
		(width 0.1143)
		(layer "F.Cu")
		(net "P3E_CPU0_PE2_SS_TXP<5>")
	)
	(segment
		(start 349.600266 -61.489336)
		(end 351.322894 -61.123322)
		(width 0.1143)
		(layer "F.Cu")
		(net "P3E_CPU0_PE2_SS_TXP<5>")
	)
	(segment
		(start 308.41188 -85.006434)
		(end 308.995572 -85.006434)
		(width 0.1143)
		(layer "F.Cu")
		(net "P3E_CPU0_PE2_SS_TXP<5>")
	)
	(segment
		(start 374.888506 -32.84855)
		(end 374.5103 -31.378144)
		(width 0.1143)
		(layer "F.Cu")
		(net "P3E_CPU0_PE2_SS_TXP<5>")
	)
	(segment
		(start 365.521494 -49.090834)
		(end 366.62106 -48.35779)
		(width 0.1143)
		(layer "F.Cu")
		(net "P3E_CPU0_PE2_SS_TXP<5>")
	)
	(segment
		(start 358.09936 -58.012584)
		(end 358.18572 -57.680606)
		(width 0.1143)
		(layer "F.Cu")
		(net "P3E_CPU0_PE2_SS_TXP<5>")
	)
	(segment
		(start 374.223534 -34.13506)
		(end 374.641618 -33.806892)
		(width 0.1143)
		(layer "F.Cu")
		(net "P3E_CPU0_PE2_SS_TXP<5>")
	)
	(segment
		(start 368.9985 -47.882556)
		(end 370.929916 -46.574964)
		(width 0.1143)
		(layer "F.Cu")
		(net "P3E_CPU0_PE2_SS_TXP<5>")
	)
	(segment
		(start 359.103676 -54.612286)
		(end 364.09249 -51.234086)
		(width 0.1143)
		(layer "F.Cu")
		(net "P3E_CPU0_PE2_SS_TXP<5>")
	)
	(segment
		(start 321.747134 -72.328532)
		(end 327.081896 -68.627752)
		(width 0.1143)
		(layer "F.Cu")
		(net "P3E_CPU0_PE2_SS_TXP<5>")
	)
	(segment
		(start 358.873044 -55.497222)
		(end 358.791256 -55.357776)
		(width 0.1143)
		(layer "F.Cu")
		(net "P3E_CPU0_PE2_SS_TXP<5>")
	)
	(segment
		(start 357.984552 -58.905902)
		(end 358.181148 -58.15203)
		(width 0.1143)
		(layer "F.Cu")
		(net "P3E_CPU0_PE2_SS_TXP<5>")
	)
	(segment
		(start 371.98427 -40.520874)
		(end 372.42877 -38.297612)
		(width 0.1143)
		(layer "F.Cu")
		(net "P3E_CPU0_PE2_SS_TXP<5>")
	)
	(segment
		(start 358.325166 -57.598818)
		(end 358.41178 -57.267094)
		(width 0.1143)
		(layer "F.Cu")
		(net "P3E_CPU0_PE2_SS_TXP<5>")
	)
	(segment
		(start 308.995572 -85.006434)
		(end 315.057028 -81.884012)
		(width 0.1143)
		(layer "F.Cu")
		(net "P3E_CPU0_PE2_SS_TXP<5>")
	)
	(segment
		(start 398.354042 -11.4808)
		(end 398.354042 -11.241786)
		(width 0.1143)
		(layer "F.Cu")
		(net "P3E_CPU0_PE2_SS_TXP<5>")
	)
	(segment
		(start 373.080788 -34.345372)
		(end 374.223534 -34.13506)
		(width 0.1143)
		(layer "F.Cu")
		(net "P3E_CPU0_PE2_SS_TXP<5>")
	)
	(segment
		(start 397.630396 -12.35583)
		(end 398.354042 -11.4808)
		(width 0.1143)
		(layer "F.Cu")
		(net "P3E_CPU0_PE2_SS_TXP<5>")
	)
	(segment
		(start 398.354042 -11.241786)
		(end 398.030192 -10.917936)
		(width 0.1143)
		(layer "F.Cu")
		(net "P3E_CPU0_PE2_SS_TXP<5>")
	)
	(segment
		(start 375.154444 -20.545044)
		(end 374.83669 -18.947892)
		(width 0.1143)
		(layer "F.Cu")
		(net "P3E_CPU0_PE2_SS_TXP<5>")
	)
	(segment
		(start 328.699622 -66.053208)
		(end 332.83017 -63.595758)
		(width 0.1143)
		(layer "F.Cu")
		(net "P3E_CPU0_PE2_SS_TXP<5>")
	)
	(segment
		(start 355.59746 -61.163454)
		(end 357.06558 -60.191142)
		(width 0.1143)
		(layer "F.Cu")
		(net "P3E_CPU0_PE2_SS_TXP<5>")
	)
	(segment
		(start 374.83669 -18.947892)
		(end 375.567194 -17.20088)
		(width 0.1143)
		(layer "F.Cu")
		(net "P3E_CPU0_PE2_SS_TXP<5>")
	)
	(segment
		(start 358.87787 -55.025798)
		(end 359.017316 -54.94401)
		(width 0.1143)
		(layer "F.Cu")
		(net "P3E_CPU0_PE2_SS_TXP<5>")
	)
	(segment
		(start 358.791256 -55.357776)
		(end 358.87787 -55.025798)
		(width 0.1143)
		(layer "F.Cu")
		(net "P3E_CPU0_PE2_SS_TXP<5>")
	)
	(segment
		(start 364.09249 -51.234086)
		(end 365.521494 -49.090834)
		(width 0.1143)
		(layer "F.Cu")
		(net "P3E_CPU0_PE2_SS_TXP<5>")
	)
	(segment
		(start 358.647238 -55.910734)
		(end 358.786684 -55.828946)
		(width 0.1143)
		(layer "F.Cu")
		(net "P3E_CPU0_PE2_SS_TXP<5>")
	)
	(segment
		(start 315.057028 -81.884012)
		(end 320.255392 -74.459084)
		(width 0.1143)
		(layer "F.Cu")
		(net "P3E_CPU0_PE2_SS_TXP<5>")
	)
	(segment
		(start 351.322894 -61.123322)
		(end 353.246436 -61.624464)
		(width 0.1143)
		(layer "F.Cu")
		(net "P3E_CPU0_PE2_SS_TXP<5>")
	)
	(segment
		(start 358.786684 -55.828946)
		(end 358.873044 -55.497222)
		(width 0.1143)
		(layer "F.Cu")
		(net "P3E_CPU0_PE2_SS_TXP<5>")
	)
	(segment
		(start 375.155714 -28.159456)
		(end 374.755664 -26.157936)
		(width 0.1143)
		(layer "F.Cu")
		(net "P3E_CPU0_PE2_SS_TXP<5>")
	)
	(segment
		(start 375.567194 -17.20088)
		(end 376.240548 -16.75511)
		(width 0.1143)
		(layer "F.Cu")
		(net "P3E_CPU0_PE2_SS_TXP<5>")
	)
	(segment
		(start 358.642412 -56.382158)
		(end 358.560624 -56.242712)
		(width 0.1143)
		(layer "F.Cu")
		(net "P3E_CPU0_PE2_SS_TXP<5>")
	)
	(segment
		(start 308.375304 -85.031834)
		(end 308.400704 -85.006434)
		(width 0.0889)
		(layer "F.Cu")
		(net "P3E_CPU0_PE2_SS_TXP<5>")
	)
	(segment
		(start 353.246436 -61.624464)
		(end 355.59746 -61.163454)
		(width 0.1143)
		(layer "F.Cu")
		(net "P3E_CPU0_PE2_SS_TXP<5>")
	)
	(segment
		(start 307.250592 -85.031834)
		(end 308.375304 -85.031834)
		(width 0.0889)
		(layer "F.Cu")
		(net "P3E_CPU0_PE2_SS_TXP<5>")
	)
	(segment
		(start 366.62106 -48.35779)
		(end 368.9985 -47.882556)
		(width 0.1143)
		(layer "F.Cu")
		(net "P3E_CPU0_PE2_SS_TXP<5>")
	)
	(segment
		(start 374.755664 -26.157936)
		(end 375.17832 -24.041608)
		(width 0.1143)
		(layer "F.Cu")
		(net "P3E_CPU0_PE2_SS_TXP<5>")
	)
	(segment
		(start 397.558768 -12.409424)
		(end 397.630396 -12.35583)
		(width 0.1143)
		(layer "F.Cu")
		(net "P3E_CPU0_PE2_SS_TXP<5>")
	)
	(segment
		(start 358.555798 -56.713882)
		(end 358.642412 -56.382158)
		(width 0.1143)
		(layer "F.Cu")
		(net "P3E_CPU0_PE2_SS_TXP<5>")
	)
	(segment
		(start 347.173296 -61.507116)
		(end 348.427548 -61.240162)
		(width 0.1143)
		(layer "F.Cu")
		(net "P3E_CPU0_PE2_SS_TXP<5>")
	)
	(segment
		(start 372.42877 -38.297612)
		(end 372.21795 -37.24402)
		(width 0.1143)
		(layer "F.Cu")
		(net "P3E_CPU0_PE2_SS_TXP<5>")
	)
	(segment
		(start 327.081896 -68.627752)
		(end 328.699622 -66.053208)
		(width 0.1143)
		(layer "F.Cu")
		(net "P3E_CPU0_PE2_SS_TXP<5>")
	)
	(segment
		(start 358.560624 -56.242712)
		(end 358.647238 -55.910734)
		(width 0.1143)
		(layer "F.Cu")
		(net "P3E_CPU0_PE2_SS_TXP<5>")
	)
	(segment
		(start 374.888506 -33.229042)
		(end 374.888506 -32.84855)
		(width 0.1143)
		(layer "F.Cu")
		(net "P3E_CPU0_PE2_SS_TXP<5>")
	)
	(segment
		(start 306.370736 -85.527388)
		(end 306.403502 -85.527388)
		(width 0.0889)
		(layer "F.Cu")
		(net "P3E_CPU0_PE2_SS_TXP<5>")
	)
	(segment
		(start 359.017316 -54.94401)
		(end 359.103676 -54.612286)
		(width 0.1143)
		(layer "F.Cu")
		(net "P3E_CPU0_PE2_SS_TXP<5>")
	)
	(segment
		(start 343.976452 -61.350652)
		(end 344.767916 -61.518546)
		(width 0.1143)
		(layer "F.Cu")
		(net "P3E_CPU0_PE2_SS_TXP<5>")
	)
	(segment
		(start 396.759176 -13.006832)
		(end 397.558768 -12.409424)
		(width 0.1143)
		(layer "F.Cu")
		(net "P3E_CPU0_PE2_SS_TXP<5>")
	)
	(segment
		(start 374.814846 -22.22373)
		(end 375.154444 -20.545044)
		(width 0.1143)
		(layer "F.Cu")
		(net "P3E_CPU0_PE2_SS_TXP<5>")
	)
	(segment
		(start 345.99753 -61.25718)
		(end 347.173296 -61.507116)
		(width 0.1143)
		(layer "F.Cu")
		(net "P3E_CPU0_PE2_SS_TXP<5>")
	)
	(segment
		(start 344.767916 -61.518546)
		(end 345.99753 -61.25718)
		(width 0.1143)
		(layer "F.Cu")
		(net "P3E_CPU0_PE2_SS_TXP<5>")
	)
	(segment
		(start 348.427548 -61.240162)
		(end 349.600266 -61.489336)
		(width 0.1143)
		(layer "F.Cu")
		(net "P3E_CPU0_PE2_SS_TXP<5>")
	)
	(segment
		(start 358.181148 -58.15203)
		(end 358.09936 -58.012584)
		(width 0.1143)
		(layer "F.Cu")
		(net "P3E_CPU0_PE2_SS_TXP<5>")
	)
	(segment
		(start 358.329992 -57.127648)
		(end 358.416606 -56.79567)
		(width 0.1143)
		(layer "F.Cu")
		(net "P3E_CPU0_PE2_SS_TXP<5>")
	)
	(segment
		(start 374.5103 -31.378144)
		(end 375.155714 -28.159456)
		(width 0.1143)
		(layer "F.Cu")
		(net "P3E_CPU0_PE2_SS_TXP<5>")
	)
	(segment
		(start 374.641618 -33.806892)
		(end 374.888506 -33.229042)
		(width 0.1143)
		(layer "F.Cu")
		(net "P3E_CPU0_PE2_SS_TXP<5>")
	)
	(segment
		(start 372.323614 -42.420794)
		(end 371.98427 -40.520874)
		(width 0.1143)
		(layer "F.Cu")
		(net "P3E_CPU0_PE2_SS_TXP<5>")
	)
	(segment
		(start 372.21795 -37.24402)
		(end 372.676166 -34.953194)
		(width 0.1143)
		(layer "F.Cu")
		(net "P3E_CPU0_PE2_SS_TXP<5>")
	)
	(segment
		(start 332.83017 -63.595758)
		(end 343.976452 -61.350652)
		(width 0.1143)
		(layer "F.Cu")
		(net "P3E_CPU0_PE2_SS_TXP<5>")
	)
	(via
		(at 320.255392 -74.459084)
		(size 0.508)
		(drill 0.254)
		(layers "F.Cu" "B.Cu")
		(net "P3E_CPU0_PE2_SS_TXP<5>")
	)
	(arc
		(start 306.403502 -85.527388)
		(mid 306.597352 -85.471038)
		(end 306.739036 -85.327236)
		(width 0.0889)
		(layer "F.Cu")
		(net "P3E_CPU0_PE2_SS_TXP<5>")
	)
	(arc
		(start 306.739036 -85.327236)
		(mid 306.95522 -85.110957)
		(end 307.250592 -85.031834)
		(width 0.0889)
		(layer "F.Cu")
		(net "P3E_CPU0_PE2_SS_TXP<5>")
	)
	(arc
		(start 305.533806 -85.622384)
		(mid 305.949584 -85.551214)
		(end 306.370736 -85.527388)
		(width 0.0889)
		(layer "F.Cu")
		(net "P3E_CPU0_PE2_SS_TXP<5>")
	)
	(segment
		(start 316.285626 -81.929478)
		(end 315.838078 -82.572606)
		(width 0.1143)
		(layer "F.Cu")
		(net "P3E_CPU0_PE2_SS_TXP<4>")
	)
	(segment
		(start 393.127992 -15.547594)
		(end 392.79068 -15.60957)
		(width 0.1143)
		(layer "F.Cu")
		(net "P3E_CPU0_PE2_SS_TXP<4>")
	)
	(segment
		(start 348.427802 -62.265814)
		(end 347.186504 -62.529974)
		(width 0.1143)
		(layer "F.Cu")
		(net "P3E_CPU0_PE2_SS_TXP<4>")
	)
	(segment
		(start 379.664976 -21.613114)
		(end 380.21514 -23.523956)
		(width 0.1143)
		(layer "F.Cu")
		(net "P3E_CPU0_PE2_SS_TXP<4>")
	)
	(segment
		(start 353.24034 -62.659514)
		(end 351.22993 -62.135766)
		(width 0.1143)
		(layer "F.Cu")
		(net "P3E_CPU0_PE2_SS_TXP<4>")
	)
	(segment
		(start 371.105176 -48.864266)
		(end 371.104922 -48.864266)
		(width 0.1143)
		(layer "F.Cu")
		(net "P3E_CPU0_PE2_SS_TXP<4>")
	)
	(segment
		(start 357.607362 -61.239908)
		(end 356.413054 -62.03061)
		(width 0.1143)
		(layer "F.Cu")
		(net "P3E_CPU0_PE2_SS_TXP<4>")
	)
	(segment
		(start 378.893578 -27.877516)
		(end 377.728988 -27.625294)
		(width 0.1143)
		(layer "F.Cu")
		(net "P3E_CPU0_PE2_SS_TXP<4>")
	)
	(segment
		(start 395.488668 -15.114016)
		(end 395.355572 -15.022322)
		(width 0.1143)
		(layer "F.Cu")
		(net "P3E_CPU0_PE2_SS_TXP<4>")
	)
	(segment
		(start 380.1491 -19.819366)
		(end 379.664976 -21.613114)
		(width 0.1143)
		(layer "F.Cu")
		(net "P3E_CPU0_PE2_SS_TXP<4>")
	)
	(segment
		(start 392.228578 -15.712948)
		(end 387.653022 -16.553434)
		(width 0.1143)
		(layer "F.Cu")
		(net "P3E_CPU0_PE2_SS_TXP<4>")
	)
	(segment
		(start 346.010484 -62.280038)
		(end 344.76817 -62.544198)
		(width 0.1143)
		(layer "F.Cu")
		(net "P3E_CPU0_PE2_SS_TXP<4>")
	)
	(segment
		(start 358.936036 -59.2328)
		(end 357.607362 -61.239908)
		(width 0.1143)
		(layer "F.Cu")
		(net "P3E_CPU0_PE2_SS_TXP<4>")
	)
	(segment
		(start 380.99365 -18.644108)
		(end 380.1491 -19.819366)
		(width 0.1143)
		(layer "F.Cu")
		(net "P3E_CPU0_PE2_SS_TXP<4>")
	)
	(segment
		(start 347.186504 -62.529974)
		(end 346.010484 -62.280038)
		(width 0.1143)
		(layer "F.Cu")
		(net "P3E_CPU0_PE2_SS_TXP<4>")
	)
	(segment
		(start 387.653022 -16.553434)
		(end 380.99365 -18.644108)
		(width 0.1143)
		(layer "F.Cu")
		(net "P3E_CPU0_PE2_SS_TXP<4>")
	)
	(segment
		(start 370.514118 -49.367694)
		(end 369.692174 -49.537366)
		(width 0.1143)
		(layer "F.Cu")
		(net "P3E_CPU0_PE2_SS_TXP<4>")
	)
	(segment
		(start 375.46534 -34.504122)
		(end 373.783098 -35.717988)
		(width 0.1143)
		(layer "F.Cu")
		(net "P3E_CPU0_PE2_SS_TXP<4>")
	)
	(segment
		(start 369.692174 -49.537366)
		(end 367.999518 -49.100994)
		(width 0.1143)
		(layer "F.Cu")
		(net "P3E_CPU0_PE2_SS_TXP<4>")
	)
	(segment
		(start 373.361712 -39.62019)
		(end 373.71909 -41.40708)
		(width 0.1143)
		(layer "F.Cu")
		(net "P3E_CPU0_PE2_SS_TXP<4>")
	)
	(segment
		(start 395.018514 -15.084298)
		(end 394.926566 -15.21714)
		(width 0.1143)
		(layer "F.Cu")
		(net "P3E_CPU0_PE2_SS_TXP<4>")
	)
	(segment
		(start 373.79529 -37.448744)
		(end 373.361712 -39.62019)
		(width 0.1143)
		(layer "F.Cu")
		(net "P3E_CPU0_PE2_SS_TXP<4>")
	)
	(segment
		(start 379.464824 -25.96642)
		(end 379.793754 -26.96464)
		(width 0.1143)
		(layer "F.Cu")
		(net "P3E_CPU0_PE2_SS_TXP<4>")
	)
	(segment
		(start 377.3805 -27.71521)
		(end 377.005596 -27.81173)
		(width 0.1143)
		(layer "F.Cu")
		(net "P3E_CPU0_PE2_SS_TXP<4>")
	)
	(segment
		(start 349.522796 -62.498478)
		(end 348.427802 -62.265814)
		(width 0.1143)
		(layer "F.Cu")
		(net "P3E_CPU0_PE2_SS_TXP<4>")
	)
	(segment
		(start 375.854468 -33.575244)
		(end 375.46534 -34.504122)
		(width 0.1143)
		(layer "F.Cu")
		(net "P3E_CPU0_PE2_SS_TXP<4>")
	)
	(segment
		(start 359.98912 -55.193692)
		(end 358.935528 -59.2328)
		(width 0.1143)
		(layer "F.Cu")
		(net "P3E_CPU0_PE2_SS_TXP<4>")
	)
	(segment
		(start 371.021356 -49.067212)
		(end 370.514118 -49.367694)
		(width 0.1143)
		(layer "F.Cu")
		(net "P3E_CPU0_PE2_SS_TXP<4>")
	)
	(segment
		(start 377.005596 -27.81173)
		(end 375.929144 -29.229812)
		(width 0.1143)
		(layer "F.Cu")
		(net "P3E_CPU0_PE2_SS_TXP<4>")
	)
	(segment
		(start 329.576176 -67.19316)
		(end 328.372216 -69.04482)
		(width 0.1143)
		(layer "F.Cu")
		(net "P3E_CPU0_PE2_SS_TXP<4>")
	)
	(segment
		(start 373.71909 -41.40708)
		(end 371.697504 -47.432468)
		(width 0.1143)
		(layer "F.Cu")
		(net "P3E_CPU0_PE2_SS_TXP<4>")
	)
	(segment
		(start 393.556998 -15.352776)
		(end 393.219686 -15.414752)
		(width 0.1143)
		(layer "F.Cu")
		(net "P3E_CPU0_PE2_SS_TXP<4>")
	)
	(segment
		(start 373.570246 -36.360862)
		(end 373.79529 -37.448744)
		(width 0.1143)
		(layer "F.Cu")
		(net "P3E_CPU0_PE2_SS_TXP<4>")
	)
	(segment
		(start 394.1191 -15.249398)
		(end 394.027406 -15.382494)
		(width 0.1143)
		(layer "F.Cu")
		(net "P3E_CPU0_PE2_SS_TXP<4>")
	)
	(segment
		(start 373.783098 -35.717988)
		(end 373.570246 -36.360862)
		(width 0.1143)
		(layer "F.Cu")
		(net "P3E_CPU0_PE2_SS_TXP<4>")
	)
	(segment
		(start 377.3805 -27.714956)
		(end 377.3805 -27.71521)
		(width 0.1143)
		(layer "F.Cu")
		(net "P3E_CPU0_PE2_SS_TXP<4>")
	)
	(segment
		(start 377.728988 -27.625294)
		(end 377.3805 -27.714956)
		(width 0.1143)
		(layer "F.Cu")
		(net "P3E_CPU0_PE2_SS_TXP<4>")
	)
	(segment
		(start 393.690094 -15.44447)
		(end 393.556998 -15.352776)
		(width 0.1143)
		(layer "F.Cu")
		(net "P3E_CPU0_PE2_SS_TXP<4>")
	)
	(segment
		(start 344.76817 -62.544198)
		(end 343.96426 -62.37351)
		(width 0.1143)
		(layer "F.Cu")
		(net "P3E_CPU0_PE2_SS_TXP<4>")
	)
	(segment
		(start 393.219686 -15.414752)
		(end 393.127992 -15.547594)
		(width 0.1143)
		(layer "F.Cu")
		(net "P3E_CPU0_PE2_SS_TXP<4>")
	)
	(segment
		(start 366.97031 -49.306734)
		(end 366.246156 -49.789588)
		(width 0.1143)
		(layer "F.Cu")
		(net "P3E_CPU0_PE2_SS_TXP<4>")
	)
	(segment
		(start 328.372216 -69.04482)
		(end 322.461636 -73.055226)
		(width 0.1143)
		(layer "F.Cu")
		(net "P3E_CPU0_PE2_SS_TXP<4>")
	)
	(segment
		(start 351.22993 -62.135766)
		(end 349.522796 -62.498478)
		(width 0.1143)
		(layer "F.Cu")
		(net "P3E_CPU0_PE2_SS_TXP<4>")
	)
	(segment
		(start 400.189954 -12.163298)
		(end 395.82598 -15.05204)
		(width 0.1143)
		(layer "F.Cu")
		(net "P3E_CPU0_PE2_SS_TXP<4>")
	)
	(segment
		(start 371.104922 -48.864266)
		(end 371.021356 -49.067212)
		(width 0.1143)
		(layer "F.Cu")
		(net "P3E_CPU0_PE2_SS_TXP<4>")
	)
	(segment
		(start 375.929144 -29.229812)
		(end 375.545096 -31.144972)
		(width 0.1143)
		(layer "F.Cu")
		(net "P3E_CPU0_PE2_SS_TXP<4>")
	)
	(segment
		(start 379.692662 -27.443684)
		(end 378.893578 -27.877516)
		(width 0.1143)
		(layer "F.Cu")
		(net "P3E_CPU0_PE2_SS_TXP<4>")
	)
	(segment
		(start 395.82598 -15.05204)
		(end 395.488668 -15.114016)
		(width 0.1143)
		(layer "F.Cu")
		(net "P3E_CPU0_PE2_SS_TXP<4>")
	)
	(segment
		(start 392.320272 -15.579852)
		(end 392.228578 -15.712948)
		(width 0.1143)
		(layer "F.Cu")
		(net "P3E_CPU0_PE2_SS_TXP<4>")
	)
	(segment
		(start 394.456412 -15.187422)
		(end 394.1191 -15.249398)
		(width 0.1143)
		(layer "F.Cu")
		(net "P3E_CPU0_PE2_SS_TXP<4>")
	)
	(segment
		(start 309.192422 -85.997034)
		(end 307.625496 -85.997034)
		(width 0.1143)
		(layer "F.Cu")
		(net "P3E_CPU0_PE2_SS_TXP<4>")
	)
	(segment
		(start 394.926566 -15.21714)
		(end 394.589254 -15.279116)
		(width 0.1143)
		(layer "F.Cu")
		(net "P3E_CPU0_PE2_SS_TXP<4>")
	)
	(segment
		(start 400.430492 -10.917936)
		(end 400.754342 -11.241786)
		(width 0.1143)
		(layer "F.Cu")
		(net "P3E_CPU0_PE2_SS_TXP<4>")
	)
	(segment
		(start 356.413054 -62.03061)
		(end 353.24034 -62.659514)
		(width 0.1143)
		(layer "F.Cu")
		(net "P3E_CPU0_PE2_SS_TXP<4>")
	)
	(segment
		(start 307.625496 -85.997034)
		(end 307.250846 -85.622384)
		(width 0.1143)
		(layer "F.Cu")
		(net "P3E_CPU0_PE2_SS_TXP<4>")
	)
	(segment
		(start 364.81766 -51.931824)
		(end 359.98912 -55.193692)
		(width 0.1143)
		(layer "F.Cu")
		(net "P3E_CPU0_PE2_SS_TXP<4>")
	)
	(segment
		(start 375.854468 -32.573722)
		(end 375.854468 -33.575244)
		(width 0.1143)
		(layer "F.Cu")
		(net "P3E_CPU0_PE2_SS_TXP<4>")
	)
	(segment
		(start 338.895182 -63.394336)
		(end 334.3783 -65.533016)
		(width 0.1143)
		(layer "F.Cu")
		(net "P3E_CPU0_PE2_SS_TXP<4>")
	)
	(segment
		(start 375.545096 -31.144972)
		(end 375.854468 -32.573722)
		(width 0.1143)
		(layer "F.Cu")
		(net "P3E_CPU0_PE2_SS_TXP<4>")
	)
	(segment
		(start 358.935528 -59.2328)
		(end 358.936036 -59.2328)
		(width 0.1143)
		(layer "F.Cu")
		(net "P3E_CPU0_PE2_SS_TXP<4>")
	)
	(segment
		(start 315.838078 -82.572606)
		(end 309.192422 -85.997034)
		(width 0.1143)
		(layer "F.Cu")
		(net "P3E_CPU0_PE2_SS_TXP<4>")
	)
	(segment
		(start 394.589254 -15.279116)
		(end 394.456412 -15.187422)
		(width 0.1143)
		(layer "F.Cu")
		(net "P3E_CPU0_PE2_SS_TXP<4>")
	)
	(segment
		(start 394.027406 -15.382494)
		(end 393.690094 -15.44447)
		(width 0.1143)
		(layer "F.Cu")
		(net "P3E_CPU0_PE2_SS_TXP<4>")
	)
	(segment
		(start 366.246156 -49.789588)
		(end 364.81766 -51.931824)
		(width 0.1143)
		(layer "F.Cu")
		(net "P3E_CPU0_PE2_SS_TXP<4>")
	)
	(segment
		(start 371.697504 -47.432468)
		(end 371.105176 -48.864266)
		(width 0.1143)
		(layer "F.Cu")
		(net "P3E_CPU0_PE2_SS_TXP<4>")
	)
	(segment
		(start 392.657584 -15.517876)
		(end 392.320272 -15.579852)
		(width 0.1143)
		(layer "F.Cu")
		(net "P3E_CPU0_PE2_SS_TXP<4>")
	)
	(segment
		(start 395.355572 -15.022322)
		(end 395.018514 -15.084298)
		(width 0.1143)
		(layer "F.Cu")
		(net "P3E_CPU0_PE2_SS_TXP<4>")
	)
	(segment
		(start 400.754342 -11.241786)
		(end 400.754342 -11.4808)
		(width 0.1143)
		(layer "F.Cu")
		(net "P3E_CPU0_PE2_SS_TXP<4>")
	)
	(segment
		(start 334.3783 -65.533016)
		(end 329.576176 -67.19316)
		(width 0.1143)
		(layer "F.Cu")
		(net "P3E_CPU0_PE2_SS_TXP<4>")
	)
	(segment
		(start 322.461636 -73.055226)
		(end 316.285626 -81.929478)
		(width 0.1143)
		(layer "F.Cu")
		(net "P3E_CPU0_PE2_SS_TXP<4>")
	)
	(segment
		(start 343.96426 -62.37351)
		(end 338.895182 -63.394336)
		(width 0.1143)
		(layer "F.Cu")
		(net "P3E_CPU0_PE2_SS_TXP<4>")
	)
	(segment
		(start 400.754342 -11.4808)
		(end 400.189954 -12.163298)
		(width 0.1143)
		(layer "F.Cu")
		(net "P3E_CPU0_PE2_SS_TXP<4>")
	)
	(segment
		(start 380.21514 -23.523956)
		(end 379.464824 -25.96642)
		(width 0.1143)
		(layer "F.Cu")
		(net "P3E_CPU0_PE2_SS_TXP<4>")
	)
	(segment
		(start 379.793754 -26.96464)
		(end 379.692662 -27.443684)
		(width 0.1143)
		(layer "F.Cu")
		(net "P3E_CPU0_PE2_SS_TXP<4>")
	)
	(segment
		(start 367.999518 -49.100994)
		(end 366.97031 -49.306734)
		(width 0.1143)
		(layer "F.Cu")
		(net "P3E_CPU0_PE2_SS_TXP<4>")
	)
	(segment
		(start 392.79068 -15.60957)
		(end 392.657584 -15.517876)
		(width 0.1143)
		(layer "F.Cu")
		(net "P3E_CPU0_PE2_SS_TXP<4>")
	)
	(via
		(at 316.285626 -81.929478)
		(size 0.508)
		(drill 0.254)
		(layers "F.Cu" "B.Cu")
		(net "P3E_CPU0_PE2_SS_TXP<4>")
	)
	(segment
		(start 388.335774 -17.822672)
		(end 388.47395 -17.906238)
		(width 0.1143)
		(layer "F.Cu")
		(net "P3E_CPU0_PE2_SS_TXP<3>")
	)
	(segment
		(start 387.919214 -18.043144)
		(end 388.00278 -17.904714)
		(width 0.1143)
		(layer "F.Cu")
		(net "P3E_CPU0_PE2_SS_TXP<3>")
	)
	(segment
		(start 339.166962 -64.34201)
		(end 343.970864 -63.374524)
		(width 0.1143)
		(layer "F.Cu")
		(net "P3E_CPU0_PE2_SS_TXP<3>")
	)
	(segment
		(start 385.171188 -33.778952)
		(end 384.811524 -33.235392)
		(width 0.1143)
		(layer "F.Cu")
		(net "P3E_CPU0_PE2_SS_TXP<3>")
	)
	(segment
		(start 377.316746 -47.503842)
		(end 378.589794 -47.777146)
		(width 0.1143)
		(layer "F.Cu")
		(net "P3E_CPU0_PE2_SS_TXP<3>")
	)
	(segment
		(start 359.122218 -62.627256)
		(end 359.850182 -59.834272)
		(width 0.1143)
		(layer "F.Cu")
		(net "P3E_CPU0_PE2_SS_TXP<3>")
	)
	(segment
		(start 384.918458 -32.709358)
		(end 385.454144 -31.900114)
		(width 0.1143)
		(layer "F.Cu")
		(net "P3E_CPU0_PE2_SS_TXP<3>")
	)
	(segment
		(start 385.084574 -36.952682)
		(end 385.450588 -35.153092)
		(width 0.1143)
		(layer "F.Cu")
		(net "P3E_CPU0_PE2_SS_TXP<3>")
	)
	(segment
		(start 387.63067 -18.114518)
		(end 387.919214 -18.043144)
		(width 0.1143)
		(layer "F.Cu")
		(net "P3E_CPU0_PE2_SS_TXP<3>")
	)
	(segment
		(start 316.477142 -83.360006)
		(end 309.375302 -86.987634)
		(width 0.1143)
		(layer "F.Cu")
		(net "P3E_CPU0_PE2_SS_TXP<3>")
	)
	(segment
		(start 308.61 -87.013034)
		(end 307.233066 -87.013034)
		(width 0.0889)
		(layer "F.Cu")
		(net "P3E_CPU0_PE2_SS_TXP<3>")
	)
	(segment
		(start 359.875328 -59.798204)
		(end 362.961936 -55.408068)
		(width 0.1143)
		(layer "F.Cu")
		(net "P3E_CPU0_PE2_SS_TXP<3>")
	)
	(segment
		(start 402.742146 -12.031726)
		(end 403.154642 -11.4808)
		(width 0.1143)
		(layer "F.Cu")
		(net "P3E_CPU0_PE2_SS_TXP<3>")
	)
	(segment
		(start 390.66597 -17.247108)
		(end 390.998964 -17.165066)
		(width 0.1143)
		(layer "F.Cu")
		(net "P3E_CPU0_PE2_SS_TXP<3>")
	)
	(segment
		(start 385.454144 -31.900114)
		(end 386.255768 -27.957526)
		(width 0.1143)
		(layer "F.Cu")
		(net "P3E_CPU0_PE2_SS_TXP<3>")
	)
	(segment
		(start 386.255768 -27.957526)
		(end 386.087366 -27.116786)
		(width 0.1143)
		(layer "F.Cu")
		(net "P3E_CPU0_PE2_SS_TXP<3>")
	)
	(segment
		(start 370.023898 -50.618644)
		(end 370.699538 -50.483516)
		(width 0.1143)
		(layer "F.Cu")
		(net "P3E_CPU0_PE2_SS_TXP<3>")
	)
	(segment
		(start 373.73433 -48.435006)
		(end 373.866156 -48.346106)
		(width 0.1143)
		(layer "F.Cu")
		(net "P3E_CPU0_PE2_SS_TXP<3>")
	)
	(segment
		(start 385.867402 -24.783542)
		(end 387.039358 -19.007328)
		(width 0.1143)
		(layer "F.Cu")
		(net "P3E_CPU0_PE2_SS_TXP<3>")
	)
	(segment
		(start 388.806944 -17.823942)
		(end 388.89051 -17.685512)
		(width 0.1143)
		(layer "F.Cu")
		(net "P3E_CPU0_PE2_SS_TXP<3>")
	)
	(segment
		(start 385.284472 -41.56964)
		(end 385.439666 -40.90035)
		(width 0.1143)
		(layer "F.Cu")
		(net "P3E_CPU0_PE2_SS_TXP<3>")
	)
	(segment
		(start 355.666802 -63.200026)
		(end 356.9462 -63.626492)
		(width 0.1143)
		(layer "F.Cu")
		(net "P3E_CPU0_PE2_SS_TXP<3>")
	)
	(segment
		(start 381.394716 -44.657264)
		(end 385.284472 -41.56964)
		(width 0.1143)
		(layer "F.Cu")
		(net "P3E_CPU0_PE2_SS_TXP<3>")
	)
	(segment
		(start 386.087366 -27.116786)
		(end 386.348478 -26.151078)
		(width 0.1143)
		(layer "F.Cu")
		(net "P3E_CPU0_PE2_SS_TXP<3>")
	)
	(segment
		(start 373.866156 -48.346106)
		(end 377.316746 -47.503842)
		(width 0.1143)
		(layer "F.Cu")
		(net "P3E_CPU0_PE2_SS_TXP<3>")
	)
	(segment
		(start 356.9462 -63.626492)
		(end 357.9368 -63.3984)
		(width 0.1143)
		(layer "F.Cu")
		(net "P3E_CPU0_PE2_SS_TXP<3>")
	)
	(segment
		(start 385.439666 -40.90035)
		(end 385.151884 -39.652448)
		(width 0.1143)
		(layer "F.Cu")
		(net "P3E_CPU0_PE2_SS_TXP<3>")
	)
	(segment
		(start 388.47395 -17.906238)
		(end 388.806944 -17.823942)
		(width 0.1143)
		(layer "F.Cu")
		(net "P3E_CPU0_PE2_SS_TXP<3>")
	)
	(segment
		(start 391.470134 -17.166336)
		(end 395.771624 -16.291306)
		(width 0.1143)
		(layer "F.Cu")
		(net "P3E_CPU0_PE2_SS_TXP<3>")
	)
	(segment
		(start 305.666648 -87.981282)
		(end 305.533806 -87.603584)
		(width 0.0889)
		(layer "F.Cu")
		(net "P3E_CPU0_PE2_SS_TXP<3>")
	)
	(segment
		(start 385.407662 -38.542722)
		(end 385.084574 -36.952682)
		(width 0.1143)
		(layer "F.Cu")
		(net "P3E_CPU0_PE2_SS_TXP<3>")
	)
	(segment
		(start 378.589794 -47.777146)
		(end 379.257814 -47.501302)
		(width 0.1143)
		(layer "F.Cu")
		(net "P3E_CPU0_PE2_SS_TXP<3>")
	)
	(segment
		(start 403.154642 -11.4808)
		(end 403.154642 -11.241786)
		(width 0.1143)
		(layer "F.Cu")
		(net "P3E_CPU0_PE2_SS_TXP<3>")
	)
	(segment
		(start 318.95542 -79.79664)
		(end 316.477142 -83.360006)
		(width 0.1143)
		(layer "F.Cu")
		(net "P3E_CPU0_PE2_SS_TXP<3>")
	)
	(segment
		(start 389.77824 -17.46631)
		(end 390.111234 -17.384268)
		(width 0.1143)
		(layer "F.Cu")
		(net "P3E_CPU0_PE2_SS_TXP<3>")
	)
	(segment
		(start 389.223504 -17.60347)
		(end 389.36168 -17.687036)
		(width 0.1143)
		(layer "F.Cu")
		(net "P3E_CPU0_PE2_SS_TXP<3>")
	)
	(segment
		(start 385.151884 -39.652448)
		(end 385.407662 -38.542722)
		(width 0.1143)
		(layer "F.Cu")
		(net "P3E_CPU0_PE2_SS_TXP<3>")
	)
	(segment
		(start 390.111234 -17.384268)
		(end 390.24941 -17.467834)
		(width 0.1143)
		(layer "F.Cu")
		(net "P3E_CPU0_PE2_SS_TXP<3>")
	)
	(segment
		(start 346.005658 -63.278766)
		(end 347.181678 -63.528448)
		(width 0.1143)
		(layer "F.Cu")
		(net "P3E_CPU0_PE2_SS_TXP<3>")
	)
	(segment
		(start 390.582404 -17.385538)
		(end 390.66597 -17.247108)
		(width 0.1143)
		(layer "F.Cu")
		(net "P3E_CPU0_PE2_SS_TXP<3>")
	)
	(segment
		(start 385.450588 -35.153092)
		(end 385.171188 -33.778952)
		(width 0.1143)
		(layer "F.Cu")
		(net "P3E_CPU0_PE2_SS_TXP<3>")
	)
	(segment
		(start 379.257814 -47.501302)
		(end 381.394716 -44.657264)
		(width 0.1143)
		(layer "F.Cu")
		(net "P3E_CPU0_PE2_SS_TXP<3>")
	)
	(segment
		(start 359.850182 -59.834272)
		(end 359.850436 -59.834018)
		(width 0.1143)
		(layer "F.Cu")
		(net "P3E_CPU0_PE2_SS_TXP<3>")
	)
	(segment
		(start 343.970864 -63.374524)
		(end 344.76309 -63.542672)
		(width 0.1143)
		(layer "F.Cu")
		(net "P3E_CPU0_PE2_SS_TXP<3>")
	)
	(segment
		(start 367.87709 -50.5841)
		(end 368.86388 -50.386488)
		(width 0.1143)
		(layer "F.Cu")
		(net "P3E_CPU0_PE2_SS_TXP<3>")
	)
	(segment
		(start 367.415064 -50.89144)
		(end 367.87709 -50.5841)
		(width 0.1143)
		(layer "F.Cu")
		(net "P3E_CPU0_PE2_SS_TXP<3>")
	)
	(segment
		(start 353.19462 -63.684404)
		(end 355.666802 -63.200026)
		(width 0.1143)
		(layer "F.Cu")
		(net "P3E_CPU0_PE2_SS_TXP<3>")
	)
	(segment
		(start 390.24941 -17.467834)
		(end 390.582404 -17.385538)
		(width 0.1143)
		(layer "F.Cu")
		(net "P3E_CPU0_PE2_SS_TXP<3>")
	)
	(segment
		(start 308.6354 -86.987634)
		(end 308.61 -87.013034)
		(width 0.0889)
		(layer "F.Cu")
		(net "P3E_CPU0_PE2_SS_TXP<3>")
	)
	(segment
		(start 351.256346 -63.179706)
		(end 353.19462 -63.684404)
		(width 0.1143)
		(layer "F.Cu")
		(net "P3E_CPU0_PE2_SS_TXP<3>")
	)
	(segment
		(start 388.00278 -17.904714)
		(end 388.335774 -17.822672)
		(width 0.1143)
		(layer "F.Cu")
		(net "P3E_CPU0_PE2_SS_TXP<3>")
	)
	(segment
		(start 389.36168 -17.687036)
		(end 389.694674 -17.60474)
		(width 0.1143)
		(layer "F.Cu")
		(net "P3E_CPU0_PE2_SS_TXP<3>")
	)
	(segment
		(start 323.050662 -73.90892)
		(end 332.342744 -67.57289)
		(width 0.1143)
		(layer "F.Cu")
		(net "P3E_CPU0_PE2_SS_TXP<3>")
	)
	(segment
		(start 332.342744 -67.57289)
		(end 339.166962 -64.34201)
		(width 0.1143)
		(layer "F.Cu")
		(net "P3E_CPU0_PE2_SS_TXP<3>")
	)
	(segment
		(start 349.649288 -63.520828)
		(end 351.256346 -63.179706)
		(width 0.1143)
		(layer "F.Cu")
		(net "P3E_CPU0_PE2_SS_TXP<3>")
	)
	(segment
		(start 390.998964 -17.165066)
		(end 391.13714 -17.248632)
		(width 0.1143)
		(layer "F.Cu")
		(net "P3E_CPU0_PE2_SS_TXP<3>")
	)
	(segment
		(start 391.13714 -17.248632)
		(end 391.470134 -17.166336)
		(width 0.1143)
		(layer "F.Cu")
		(net "P3E_CPU0_PE2_SS_TXP<3>")
	)
	(segment
		(start 373.718074 -48.439324)
		(end 373.73433 -48.435006)
		(width 0.1143)
		(layer "F.Cu")
		(net "P3E_CPU0_PE2_SS_TXP<3>")
	)
	(segment
		(start 402.023072 -12.152884)
		(end 402.742146 -12.031726)
		(width 0.1143)
		(layer "F.Cu")
		(net "P3E_CPU0_PE2_SS_TXP<3>")
	)
	(segment
		(start 318.95542 -79.79664)
		(end 323.050662 -73.90892)
		(width 0.1143)
		(layer "F.Cu")
		(net "P3E_CPU0_PE2_SS_TXP<3>")
	)
	(segment
		(start 388.89051 -17.685512)
		(end 389.223504 -17.60347)
		(width 0.1143)
		(layer "F.Cu")
		(net "P3E_CPU0_PE2_SS_TXP<3>")
	)
	(segment
		(start 365.584232 -53.63845)
		(end 367.415064 -50.89144)
		(width 0.1143)
		(layer "F.Cu")
		(net "P3E_CPU0_PE2_SS_TXP<3>")
	)
	(segment
		(start 368.86388 -50.386488)
		(end 370.023898 -50.618644)
		(width 0.1143)
		(layer "F.Cu")
		(net "P3E_CPU0_PE2_SS_TXP<3>")
	)
	(segment
		(start 306.403502 -87.508588)
		(end 306.370736 -87.508588)
		(width 0.0889)
		(layer "F.Cu")
		(net "P3E_CPU0_PE2_SS_TXP<3>")
	)
	(segment
		(start 403.154642 -11.241786)
		(end 402.830792 -10.917936)
		(width 0.1143)
		(layer "F.Cu")
		(net "P3E_CPU0_PE2_SS_TXP<3>")
	)
	(segment
		(start 389.694674 -17.60474)
		(end 389.77824 -17.46631)
		(width 0.1143)
		(layer "F.Cu")
		(net "P3E_CPU0_PE2_SS_TXP<3>")
	)
	(segment
		(start 386.348478 -26.151078)
		(end 386.41274 -25.913842)
		(width 0.1143)
		(layer "F.Cu")
		(net "P3E_CPU0_PE2_SS_TXP<3>")
	)
	(segment
		(start 348.433136 -63.26251)
		(end 349.649288 -63.520828)
		(width 0.1143)
		(layer "F.Cu")
		(net "P3E_CPU0_PE2_SS_TXP<3>")
	)
	(segment
		(start 357.9368 -63.3984)
		(end 359.122218 -62.627256)
		(width 0.1143)
		(layer "F.Cu")
		(net "P3E_CPU0_PE2_SS_TXP<3>")
	)
	(segment
		(start 359.850436 -59.834018)
		(end 359.875328 -59.798204)
		(width 0.1143)
		(layer "F.Cu")
		(net "P3E_CPU0_PE2_SS_TXP<3>")
	)
	(segment
		(start 387.039358 -19.007328)
		(end 387.63067 -18.114518)
		(width 0.1143)
		(layer "F.Cu")
		(net "P3E_CPU0_PE2_SS_TXP<3>")
	)
	(segment
		(start 370.699538 -50.483516)
		(end 373.718074 -48.439324)
		(width 0.1143)
		(layer "F.Cu")
		(net "P3E_CPU0_PE2_SS_TXP<3>")
	)
	(segment
		(start 362.961936 -55.408068)
		(end 365.584232 -53.63845)
		(width 0.1143)
		(layer "F.Cu")
		(net "P3E_CPU0_PE2_SS_TXP<3>")
	)
	(segment
		(start 309.375302 -86.987634)
		(end 308.6354 -86.987634)
		(width 0.1143)
		(layer "F.Cu")
		(net "P3E_CPU0_PE2_SS_TXP<3>")
	)
	(segment
		(start 386.41274 -25.913842)
		(end 385.867402 -24.783542)
		(width 0.1143)
		(layer "F.Cu")
		(net "P3E_CPU0_PE2_SS_TXP<3>")
	)
	(segment
		(start 347.181678 -63.528448)
		(end 348.433136 -63.26251)
		(width 0.1143)
		(layer "F.Cu")
		(net "P3E_CPU0_PE2_SS_TXP<3>")
	)
	(segment
		(start 395.771624 -16.291306)
		(end 402.023072 -12.152884)
		(width 0.1143)
		(layer "F.Cu")
		(net "P3E_CPU0_PE2_SS_TXP<3>")
	)
	(segment
		(start 384.811524 -33.235392)
		(end 384.918458 -32.709358)
		(width 0.1143)
		(layer "F.Cu")
		(net "P3E_CPU0_PE2_SS_TXP<3>")
	)
	(segment
		(start 344.76309 -63.542672)
		(end 346.005658 -63.278766)
		(width 0.1143)
		(layer "F.Cu")
		(net "P3E_CPU0_PE2_SS_TXP<3>")
	)
	(via
		(at 318.95542 -79.79664)
		(size 0.508)
		(drill 0.254)
		(layers "F.Cu" "B.Cu")
		(net "P3E_CPU0_PE2_SS_TXP<3>")
	)
	(arc
		(start 306.739036 -87.308436)
		(mid 306.597353 -87.45224)
		(end 306.403502 -87.508588)
		(width 0.0889)
		(layer "F.Cu")
		(net "P3E_CPU0_PE2_SS_TXP<3>")
	)
	(arc
		(start 306.370736 -87.508588)
		(mid 306.087519 -87.592869)
		(end 305.880516 -87.803736)
		(width 0.0889)
		(layer "F.Cu")
		(net "P3E_CPU0_PE2_SS_TXP<3>")
	)
	(arc
		(start 305.880516 -87.803736)
		(mid 305.789474 -87.911646)
		(end 305.666648 -87.981282)
		(width 0.0889)
		(layer "F.Cu")
		(net "P3E_CPU0_PE2_SS_TXP<3>")
	)
	(arc
		(start 307.233066 -87.013034)
		(mid 306.947642 -87.096501)
		(end 306.739036 -87.308436)
		(width 0.0889)
		(layer "F.Cu")
		(net "P3E_CPU0_PE2_SS_TXP<3>")
	)
	(segment
		(start 386.144008 -37.304726)
		(end 386.691378 -39.994586)
		(width 0.1143)
		(layer "F.Cu")
		(net "P3E_CPU0_PE2_SS_TXP<2>")
	)
	(segment
		(start 388.35203 -22.7711)
		(end 388.689596 -24.236426)
		(width 0.1143)
		(layer "F.Cu")
		(net "P3E_CPU0_PE2_SS_TXP<2>")
	)
	(segment
		(start 404.232872 -12.740132)
		(end 404.098506 -12.65047)
		(width 0.1143)
		(layer "F.Cu")
		(net "P3E_CPU0_PE2_SS_TXP<2>")
	)
	(segment
		(start 391.839958 -20.742148)
		(end 391.480802 -20.815046)
		(width 0.1143)
		(layer "F.Cu")
		(net "P3E_CPU0_PE2_SS_TXP<2>")
	)
	(segment
		(start 394.161518 -18.347944)
		(end 394.002514 -18.375884)
		(width 0.1143)
		(layer "F.Cu")
		(net "P3E_CPU0_PE2_SS_TXP<2>")
	)
	(segment
		(start 349.639636 -64.522604)
		(end 348.443804 -64.26835)
		(width 0.1143)
		(layer "F.Cu")
		(net "P3E_CPU0_PE2_SS_TXP<2>")
	)
	(segment
		(start 363.27207 -56.680862)
		(end 360.734102 -60.290202)
		(width 0.1143)
		(layer "F.Cu")
		(net "P3E_CPU0_PE2_SS_TXP<2>")
	)
	(segment
		(start 403.76221 -12.717526)
		(end 403.672548 -12.852146)
		(width 0.1143)
		(layer "F.Cu")
		(net "P3E_CPU0_PE2_SS_TXP<2>")
	)
	(segment
		(start 309.630318 -87.982552)
		(end 309.20055 -87.982552)
		(width 0.1143)
		(layer "F.Cu")
		(net "P3E_CPU0_PE2_SS_TXP<2>")
	)
	(segment
		(start 386.691378 -39.994586)
		(end 386.54609 -40.774112)
		(width 0.1143)
		(layer "F.Cu")
		(net "P3E_CPU0_PE2_SS_TXP<2>")
	)
	(segment
		(start 360.734102 -60.290202)
		(end 359.821226 -63.791338)
		(width 0.1143)
		(layer "F.Cu")
		(net "P3E_CPU0_PE2_SS_TXP<2>")
	)
	(segment
		(start 355.602286 -65.46215)
		(end 351.056194 -64.221614)
		(width 0.1143)
		(layer "F.Cu")
		(net "P3E_CPU0_PE2_SS_TXP<2>")
	)
	(segment
		(start 386.711698 -33.14065)
		(end 386.711952 -33.14065)
		(width 0.1143)
		(layer "F.Cu")
		(net "P3E_CPU0_PE2_SS_TXP<2>")
	)
	(segment
		(start 404.098506 -12.65047)
		(end 403.76221 -12.717526)
		(width 0.1143)
		(layer "F.Cu")
		(net "P3E_CPU0_PE2_SS_TXP<2>")
	)
	(segment
		(start 393.833604 -18.815812)
		(end 393.636754 -19.096736)
		(width 0.1143)
		(layer "F.Cu")
		(net "P3E_CPU0_PE2_SS_TXP<2>")
	)
	(segment
		(start 386.625084 -34.939732)
		(end 386.144008 -37.304726)
		(width 0.1143)
		(layer "F.Cu")
		(net "P3E_CPU0_PE2_SS_TXP<2>")
	)
	(segment
		(start 386.62356 -33.306258)
		(end 386.457952 -34.118296)
		(width 0.1143)
		(layer "F.Cu")
		(net "P3E_CPU0_PE2_SS_TXP<2>")
	)
	(segment
		(start 386.711952 -33.14065)
		(end 386.632704 -33.260538)
		(width 0.1143)
		(layer "F.Cu")
		(net "P3E_CPU0_PE2_SS_TXP<2>")
	)
	(segment
		(start 377.193048 -48.533304)
		(end 374.12295 -49.332388)
		(width 0.1143)
		(layer "F.Cu")
		(net "P3E_CPU0_PE2_SS_TXP<2>")
	)
	(segment
		(start 386.457952 -34.118296)
		(end 386.625084 -34.939732)
		(width 0.1143)
		(layer "F.Cu")
		(net "P3E_CPU0_PE2_SS_TXP<2>")
	)
	(segment
		(start 402.330412 -13.12037)
		(end 396.163038 -17.202658)
		(width 0.1143)
		(layer "F.Cu")
		(net "P3E_CPU0_PE2_SS_TXP<2>")
	)
	(segment
		(start 309.20055 -87.982552)
		(end 309.178452 -87.982552)
		(width 0.0889)
		(layer "F.Cu")
		(net "P3E_CPU0_PE2_SS_TXP<2>")
	)
	(segment
		(start 388.376668 -25.591516)
		(end 388.669784 -26.860754)
		(width 0.1143)
		(layer "F.Cu")
		(net "P3E_CPU0_PE2_SS_TXP<2>")
	)
	(segment
		(start 386.54609 -40.774112)
		(end 386.093462 -42.73423)
		(width 0.1143)
		(layer "F.Cu")
		(net "P3E_CPU0_PE2_SS_TXP<2>")
	)
	(segment
		(start 393.2809 -19.4056)
		(end 393.30884 -19.564604)
		(width 0.1143)
		(layer "F.Cu")
		(net "P3E_CPU0_PE2_SS_TXP<2>")
	)
	(segment
		(start 378.53493 -48.87722)
		(end 377.193048 -48.533304)
		(width 0.1143)
		(layer "F.Cu")
		(net "P3E_CPU0_PE2_SS_TXP<2>")
	)
	(segment
		(start 388.737602 -29.581856)
		(end 388.153656 -32.109918)
		(width 0.1143)
		(layer "F.Cu")
		(net "P3E_CPU0_PE2_SS_TXP<2>")
	)
	(segment
		(start 333.102458 -68.283328)
		(end 323.828664 -74.561954)
		(width 0.1143)
		(layer "F.Cu")
		(net "P3E_CPU0_PE2_SS_TXP<2>")
	)
	(segment
		(start 393.805664 -18.656808)
		(end 393.833604 -18.815812)
		(width 0.1143)
		(layer "F.Cu")
		(net "P3E_CPU0_PE2_SS_TXP<2>")
	)
	(segment
		(start 388.689596 -24.236426)
		(end 388.376668 -25.591516)
		(width 0.1143)
		(layer "F.Cu")
		(net "P3E_CPU0_PE2_SS_TXP<2>")
	)
	(segment
		(start 388.566152 -21.843492)
		(end 388.35203 -22.7711)
		(width 0.1143)
		(layer "F.Cu")
		(net "P3E_CPU0_PE2_SS_TXP<2>")
	)
	(segment
		(start 388.389622 -28.075382)
		(end 388.737602 -29.581856)
		(width 0.1143)
		(layer "F.Cu")
		(net "P3E_CPU0_PE2_SS_TXP<2>")
	)
	(segment
		(start 317.878714 -83.115912)
		(end 317.200534 -84.091018)
		(width 0.1143)
		(layer "F.Cu")
		(net "P3E_CPU0_PE2_SS_TXP<2>")
	)
	(segment
		(start 388.131304 -32.13227)
		(end 386.79247 -33.018476)
		(width 0.1143)
		(layer "F.Cu")
		(net "P3E_CPU0_PE2_SS_TXP<2>")
	)
	(segment
		(start 317.200534 -84.091018)
		(end 309.630318 -87.982552)
		(width 0.1143)
		(layer "F.Cu")
		(net "P3E_CPU0_PE2_SS_TXP<2>")
	)
	(segment
		(start 393.041378 -19.946366)
		(end 391.839958 -20.742148)
		(width 0.1143)
		(layer "F.Cu")
		(net "P3E_CPU0_PE2_SS_TXP<2>")
	)
	(segment
		(start 386.79247 -33.018476)
		(end 386.711698 -33.14065)
		(width 0.1143)
		(layer "F.Cu")
		(net "P3E_CPU0_PE2_SS_TXP<2>")
	)
	(segment
		(start 309.178452 -87.982552)
		(end 309.153052 -88.007952)
		(width 0.0889)
		(layer "F.Cu")
		(net "P3E_CPU0_PE2_SS_TXP<2>")
	)
	(segment
		(start 388.153656 -32.109918)
		(end 388.131304 -32.13227)
		(width 0.1143)
		(layer "F.Cu")
		(net "P3E_CPU0_PE2_SS_TXP<2>")
	)
	(segment
		(start 391.480802 -20.815046)
		(end 390.1821 -20.550378)
		(width 0.1143)
		(layer "F.Cu")
		(net "P3E_CPU0_PE2_SS_TXP<2>")
	)
	(segment
		(start 394.765784 -17.485868)
		(end 394.161518 -18.347944)
		(width 0.1143)
		(layer "F.Cu")
		(net "P3E_CPU0_PE2_SS_TXP<2>")
	)
	(segment
		(start 405.231092 -10.917936)
		(end 405.554942 -11.241786)
		(width 0.1143)
		(layer "F.Cu")
		(net "P3E_CPU0_PE2_SS_TXP<2>")
	)
	(segment
		(start 404.569168 -12.672568)
		(end 404.232618 -12.739878)
		(width 0.1143)
		(layer "F.Cu")
		(net "P3E_CPU0_PE2_SS_TXP<2>")
	)
	(segment
		(start 396.163038 -17.202658)
		(end 394.765784 -17.485868)
		(width 0.1143)
		(layer "F.Cu")
		(net "P3E_CPU0_PE2_SS_TXP<2>")
	)
	(segment
		(start 358.310942 -64.929512)
		(end 355.602286 -65.46215)
		(width 0.1143)
		(layer "F.Cu")
		(net "P3E_CPU0_PE2_SS_TXP<2>")
	)
	(segment
		(start 404.569168 -12.672822)
		(end 404.569168 -12.672568)
		(width 0.1143)
		(layer "F.Cu")
		(net "P3E_CPU0_PE2_SS_TXP<2>")
	)
	(segment
		(start 394.002514 -18.375884)
		(end 393.805664 -18.656808)
		(width 0.1143)
		(layer "F.Cu")
		(net "P3E_CPU0_PE2_SS_TXP<2>")
	)
	(segment
		(start 388.669784 -26.860754)
		(end 388.389622 -28.075382)
		(width 0.1143)
		(layer "F.Cu")
		(net "P3E_CPU0_PE2_SS_TXP<2>")
	)
	(segment
		(start 390.1821 -20.550378)
		(end 389.030718 -21.099272)
		(width 0.1143)
		(layer "F.Cu")
		(net "P3E_CPU0_PE2_SS_TXP<2>")
	)
	(segment
		(start 347.201744 -64.532256)
		(end 346.005658 -64.278256)
		(width 0.1143)
		(layer "F.Cu")
		(net "P3E_CPU0_PE2_SS_TXP<2>")
	)
	(segment
		(start 386.623306 -33.306258)
		(end 386.62356 -33.306258)
		(width 0.1143)
		(layer "F.Cu")
		(net "P3E_CPU0_PE2_SS_TXP<2>")
	)
	(segment
		(start 393.477496 -19.124676)
		(end 393.2809 -19.4056)
		(width 0.1143)
		(layer "F.Cu")
		(net "P3E_CPU0_PE2_SS_TXP<2>")
	)
	(segment
		(start 359.821226 -63.791338)
		(end 358.310942 -64.929512)
		(width 0.1143)
		(layer "F.Cu")
		(net "P3E_CPU0_PE2_SS_TXP<2>")
	)
	(segment
		(start 404.232618 -12.739878)
		(end 404.232872 -12.740132)
		(width 0.1143)
		(layer "F.Cu")
		(net "P3E_CPU0_PE2_SS_TXP<2>")
	)
	(segment
		(start 380.409704 -48.333406)
		(end 378.53493 -48.87722)
		(width 0.1143)
		(layer "F.Cu")
		(net "P3E_CPU0_PE2_SS_TXP<2>")
	)
	(segment
		(start 348.443804 -64.26835)
		(end 347.201744 -64.532256)
		(width 0.1143)
		(layer "F.Cu")
		(net "P3E_CPU0_PE2_SS_TXP<2>")
	)
	(segment
		(start 306.779422 -88.237822)
		(end 306.6796 -88.264746)
		(width 0.0889)
		(layer "F.Cu")
		(net "P3E_CPU0_PE2_SS_TXP<2>")
	)
	(segment
		(start 351.056194 -64.221614)
		(end 349.639636 -64.522604)
		(width 0.1143)
		(layer "F.Cu")
		(net "P3E_CPU0_PE2_SS_TXP<2>")
	)
	(segment
		(start 393.636754 -19.096736)
		(end 393.477496 -19.124676)
		(width 0.1143)
		(layer "F.Cu")
		(net "P3E_CPU0_PE2_SS_TXP<2>")
	)
	(segment
		(start 306.6796 -88.264746)
		(end 306.392326 -88.099138)
		(width 0.0889)
		(layer "F.Cu")
		(net "P3E_CPU0_PE2_SS_TXP<2>")
	)
	(segment
		(start 383.390648 -44.423076)
		(end 380.409704 -48.333406)
		(width 0.1143)
		(layer "F.Cu")
		(net "P3E_CPU0_PE2_SS_TXP<2>")
	)
	(segment
		(start 339.432138 -65.286128)
		(end 333.102458 -68.283328)
		(width 0.1143)
		(layer "F.Cu")
		(net "P3E_CPU0_PE2_SS_TXP<2>")
	)
	(segment
		(start 343.965784 -64.372998)
		(end 339.432138 -65.286128)
		(width 0.1143)
		(layer "F.Cu")
		(net "P3E_CPU0_PE2_SS_TXP<2>")
	)
	(segment
		(start 323.828664 -74.561954)
		(end 322.311014 -76.74356)
		(width 0.1143)
		(layer "F.Cu")
		(net "P3E_CPU0_PE2_SS_TXP<2>")
	)
	(segment
		(start 322.311014 -76.74356)
		(end 317.878714 -83.115912)
		(width 0.1143)
		(layer "F.Cu")
		(net "P3E_CPU0_PE2_SS_TXP<2>")
	)
	(segment
		(start 346.005658 -64.278256)
		(end 344.76309 -64.542416)
		(width 0.1143)
		(layer "F.Cu")
		(net "P3E_CPU0_PE2_SS_TXP<2>")
	)
	(segment
		(start 393.30884 -19.564604)
		(end 393.041378 -19.946366)
		(width 0.1143)
		(layer "F.Cu")
		(net "P3E_CPU0_PE2_SS_TXP<2>")
	)
	(segment
		(start 389.030718 -21.099272)
		(end 388.566152 -21.843492)
		(width 0.1143)
		(layer "F.Cu")
		(net "P3E_CPU0_PE2_SS_TXP<2>")
	)
	(segment
		(start 405.554942 -11.4808)
		(end 404.569168 -12.672822)
		(width 0.1143)
		(layer "F.Cu")
		(net "P3E_CPU0_PE2_SS_TXP<2>")
	)
	(segment
		(start 405.554942 -11.241786)
		(end 405.554942 -11.4808)
		(width 0.1143)
		(layer "F.Cu")
		(net "P3E_CPU0_PE2_SS_TXP<2>")
	)
	(segment
		(start 309.153052 -88.007952)
		(end 307.241448 -88.007952)
		(width 0.0889)
		(layer "F.Cu")
		(net "P3E_CPU0_PE2_SS_TXP<2>")
	)
	(segment
		(start 386.093462 -42.73423)
		(end 383.390648 -44.423076)
		(width 0.1143)
		(layer "F.Cu")
		(net "P3E_CPU0_PE2_SS_TXP<2>")
	)
	(segment
		(start 403.672548 -12.852146)
		(end 402.330412 -13.12037)
		(width 0.1143)
		(layer "F.Cu")
		(net "P3E_CPU0_PE2_SS_TXP<2>")
	)
	(segment
		(start 344.76309 -64.542416)
		(end 343.965784 -64.372998)
		(width 0.1143)
		(layer "F.Cu")
		(net "P3E_CPU0_PE2_SS_TXP<2>")
	)
	(segment
		(start 374.12295 -49.332388)
		(end 363.27207 -56.680862)
		(width 0.1143)
		(layer "F.Cu")
		(net "P3E_CPU0_PE2_SS_TXP<2>")
	)
	(segment
		(start 386.632704 -33.260538)
		(end 386.623306 -33.306258)
		(width 0.1143)
		(layer "F.Cu")
		(net "P3E_CPU0_PE2_SS_TXP<2>")
	)
	(via
		(at 317.878714 -83.115912)
		(size 0.508)
		(drill 0.254)
		(layers "F.Cu" "B.Cu")
		(net "P3E_CPU0_PE2_SS_TXP<2>")
	)
	(arc
		(start 307.241448 -88.007952)
		(mid 306.983412 -88.068585)
		(end 306.779422 -88.237822)
		(width 0.0889)
		(layer "F.Cu")
		(net "P3E_CPU0_PE2_SS_TXP<2>")
	)
	(segment
		(start 378.59716 -50.144934)
		(end 381.324612 -49.510442)
		(width 0.1143)
		(layer "F.Cu")
		(net "P3E_CPU0_PE2_SS_TXP<1>")
	)
	(segment
		(start 406.425908 -12.911836)
		(end 406.425908 -12.911582)
		(width 0.1143)
		(layer "F.Cu")
		(net "P3E_CPU0_PE2_SS_TXP<1>")
	)
	(segment
		(start 402.711158 -14.319504)
		(end 405.000968 -13.861796)
		(width 0.1143)
		(layer "F.Cu")
		(net "P3E_CPU0_PE2_SS_TXP<1>")
	)
	(segment
		(start 308.059328 -89.184734)
		(end 308.148228 -89.273634)
		(width 0.0889)
		(layer "F.Cu")
		(net "P3E_CPU0_PE2_SS_TXP<1>")
	)
	(segment
		(start 309.570628 -89.273634)
		(end 309.837328 -89.273634)
		(width 0.0889)
		(layer "F.Cu")
		(net "P3E_CPU0_PE2_SS_TXP<1>")
	)
	(segment
		(start 348.436184 -65.508378)
		(end 349.652082 -65.766696)
		(width 0.1143)
		(layer "F.Cu")
		(net "P3E_CPU0_PE2_SS_TXP<1>")
	)
	(segment
		(start 406.425908 -12.911582)
		(end 407.725118 -12.045442)
		(width 0.1143)
		(layer "F.Cu")
		(net "P3E_CPU0_PE2_SS_TXP<1>")
	)
	(segment
		(start 394.170916 -21.814282)
		(end 396.338298 -18.53692)
		(width 0.1143)
		(layer "F.Cu")
		(net "P3E_CPU0_PE2_SS_TXP<1>")
	)
	(segment
		(start 324.721474 -75.443334)
		(end 333.698596 -69.344794)
		(width 0.1143)
		(layer "F.Cu")
		(net "P3E_CPU0_PE2_SS_TXP<1>")
	)
	(segment
		(start 344.762582 -65.789048)
		(end 346.00515 -65.525142)
		(width 0.1143)
		(layer "F.Cu")
		(net "P3E_CPU0_PE2_SS_TXP<1>")
	)
	(segment
		(start 309.215028 -89.184734)
		(end 309.481728 -89.184734)
		(width 0.0889)
		(layer "F.Cu")
		(net "P3E_CPU0_PE2_SS_TXP<1>")
	)
	(segment
		(start 389.145272 -43.32097)
		(end 390.96823 -42.091102)
		(width 0.1143)
		(layer "F.Cu")
		(net "P3E_CPU0_PE2_SS_TXP<1>")
	)
	(segment
		(start 347.181678 -65.774824)
		(end 348.423738 -65.510918)
		(width 0.1143)
		(layer "F.Cu")
		(net "P3E_CPU0_PE2_SS_TXP<1>")
	)
	(segment
		(start 392.164062 -36.838382)
		(end 392.163808 -36.838128)
		(width 0.1143)
		(layer "F.Cu")
		(net "P3E_CPU0_PE2_SS_TXP<1>")
	)
	(segment
		(start 339.798406 -66.456306)
		(end 343.95918 -65.61836)
		(width 0.1143)
		(layer "F.Cu")
		(net "P3E_CPU0_PE2_SS_TXP<1>")
	)
	(segment
		(start 310.314594 -89.09304)
		(end 310.334406 -89.083388)
		(width 0.0889)
		(layer "F.Cu")
		(net "P3E_CPU0_PE2_SS_TXP<1>")
	)
	(segment
		(start 392.163808 -36.838382)
		(end 392.164062 -36.838382)
		(width 0.1143)
		(layer "F.Cu")
		(net "P3E_CPU0_PE2_SS_TXP<1>")
	)
	(segment
		(start 346.00515 -65.525142)
		(end 347.181678 -65.774824)
		(width 0.1143)
		(layer "F.Cu")
		(net "P3E_CPU0_PE2_SS_TXP<1>")
	)
	(segment
		(start 310.334406 -89.083388)
		(end 317.836042 -85.353144)
		(width 0.1143)
		(layer "F.Cu")
		(net "P3E_CPU0_PE2_SS_TXP<1>")
	)
	(segment
		(start 364.374176 -57.410858)
		(end 374.61698 -50.475388)
		(width 0.1143)
		(layer "F.Cu")
		(net "P3E_CPU0_PE2_SS_TXP<1>")
	)
	(segment
		(start 392.163808 -36.838128)
		(end 393.094718 -32.193484)
		(width 0.1143)
		(layer "F.Cu")
		(net "P3E_CPU0_PE2_SS_TXP<1>")
	)
	(segment
		(start 374.61698 -50.475388)
		(end 377.20778 -49.793906)
		(width 0.1143)
		(layer "F.Cu")
		(net "P3E_CPU0_PE2_SS_TXP<1>")
	)
	(segment
		(start 390.96823 -42.091102)
		(end 392.303762 -40.073326)
		(width 0.1143)
		(layer "F.Cu")
		(net "P3E_CPU0_PE2_SS_TXP<1>")
	)
	(segment
		(start 405.000968 -13.861796)
		(end 406.425908 -12.911836)
		(width 0.1143)
		(layer "F.Cu")
		(net "P3E_CPU0_PE2_SS_TXP<1>")
	)
	(segment
		(start 392.657584 -30.045152)
		(end 393.13612 -27.694382)
		(width 0.1143)
		(layer "F.Cu")
		(net "P3E_CPU0_PE2_SS_TXP<1>")
	)
	(segment
		(start 317.836042 -85.353144)
		(end 322.42633 -78.746604)
		(width 0.1143)
		(layer "F.Cu")
		(net "P3E_CPU0_PE2_SS_TXP<1>")
	)
	(segment
		(start 306.392326 -89.089738)
		(end 306.145692 -89.231978)
		(width 0.0889)
		(layer "F.Cu")
		(net "P3E_CPU0_PE2_SS_TXP<1>")
	)
	(segment
		(start 333.698596 -69.344794)
		(end 339.798406 -66.456306)
		(width 0.1143)
		(layer "F.Cu")
		(net "P3E_CPU0_PE2_SS_TXP<1>")
	)
	(segment
		(start 310.073548 -89.184734)
		(end 310.281066 -89.08161)
		(width 0.0889)
		(layer "F.Cu")
		(net "P3E_CPU0_PE2_SS_TXP<1>")
	)
	(segment
		(start 309.837328 -89.273634)
		(end 309.926228 -89.184734)
		(width 0.0889)
		(layer "F.Cu")
		(net "P3E_CPU0_PE2_SS_TXP<1>")
	)
	(segment
		(start 308.414928 -89.273634)
		(end 308.503828 -89.184734)
		(width 0.0889)
		(layer "F.Cu")
		(net "P3E_CPU0_PE2_SS_TXP<1>")
	)
	(segment
		(start 310.281066 -89.08161)
		(end 310.314594 -89.09304)
		(width 0.0889)
		(layer "F.Cu")
		(net "P3E_CPU0_PE2_SS_TXP<1>")
	)
	(segment
		(start 308.770528 -89.184734)
		(end 308.859428 -89.273634)
		(width 0.0889)
		(layer "F.Cu")
		(net "P3E_CPU0_PE2_SS_TXP<1>")
	)
	(segment
		(start 383.582418 -46.47819)
		(end 386.917438 -43.769026)
		(width 0.1143)
		(layer "F.Cu")
		(net "P3E_CPU0_PE2_SS_TXP<1>")
	)
	(segment
		(start 393.13612 -27.694382)
		(end 392.787124 -26.405332)
		(width 0.1143)
		(layer "F.Cu")
		(net "P3E_CPU0_PE2_SS_TXP<1>")
	)
	(segment
		(start 355.556312 -66.740024)
		(end 358.831896 -66.09588)
		(width 0.1143)
		(layer "F.Cu")
		(net "P3E_CPU0_PE2_SS_TXP<1>")
	)
	(segment
		(start 392.787124 -26.405332)
		(end 394.170916 -21.814282)
		(width 0.1143)
		(layer "F.Cu")
		(net "P3E_CPU0_PE2_SS_TXP<1>")
	)
	(segment
		(start 309.126128 -89.273634)
		(end 309.215028 -89.184734)
		(width 0.0889)
		(layer "F.Cu")
		(net "P3E_CPU0_PE2_SS_TXP<1>")
	)
	(segment
		(start 348.423738 -65.511172)
		(end 348.426532 -65.510664)
		(width 0.1143)
		(layer "F.Cu")
		(net "P3E_CPU0_PE2_SS_TXP<1>")
	)
	(segment
		(start 307.229256 -89.184734)
		(end 308.059328 -89.184734)
		(width 0.0889)
		(layer "F.Cu")
		(net "P3E_CPU0_PE2_SS_TXP<1>")
	)
	(segment
		(start 392.562588 -38.800024)
		(end 392.163808 -36.838382)
		(width 0.1143)
		(layer "F.Cu")
		(net "P3E_CPU0_PE2_SS_TXP<1>")
	)
	(segment
		(start 393.094718 -32.193484)
		(end 392.657584 -30.045152)
		(width 0.1143)
		(layer "F.Cu")
		(net "P3E_CPU0_PE2_SS_TXP<1>")
	)
	(segment
		(start 309.481728 -89.184734)
		(end 309.570628 -89.273634)
		(width 0.0889)
		(layer "F.Cu")
		(net "P3E_CPU0_PE2_SS_TXP<1>")
	)
	(segment
		(start 348.423738 -65.510918)
		(end 348.423738 -65.511172)
		(width 0.1143)
		(layer "F.Cu")
		(net "P3E_CPU0_PE2_SS_TXP<1>")
	)
	(segment
		(start 349.652082 -65.766696)
		(end 350.96577 -65.48755)
		(width 0.1143)
		(layer "F.Cu")
		(net "P3E_CPU0_PE2_SS_TXP<1>")
	)
	(segment
		(start 360.886248 -64.547242)
		(end 361.787186 -61.091826)
		(width 0.1143)
		(layer "F.Cu")
		(net "P3E_CPU0_PE2_SS_TXP<1>")
	)
	(segment
		(start 361.787186 -61.091826)
		(end 364.374176 -57.410858)
		(width 0.1143)
		(layer "F.Cu")
		(net "P3E_CPU0_PE2_SS_TXP<1>")
	)
	(segment
		(start 381.324612 -49.510442)
		(end 383.582418 -46.47819)
		(width 0.1143)
		(layer "F.Cu")
		(net "P3E_CPU0_PE2_SS_TXP<1>")
	)
	(segment
		(start 407.725118 -12.045442)
		(end 408.197812 -11.473688)
		(width 0.1143)
		(layer "F.Cu")
		(net "P3E_CPU0_PE2_SS_TXP<1>")
	)
	(segment
		(start 308.859428 -89.273634)
		(end 309.126128 -89.273634)
		(width 0.0889)
		(layer "F.Cu")
		(net "P3E_CPU0_PE2_SS_TXP<1>")
	)
	(segment
		(start 343.95918 -65.61836)
		(end 344.762582 -65.789048)
		(width 0.1143)
		(layer "F.Cu")
		(net "P3E_CPU0_PE2_SS_TXP<1>")
	)
	(segment
		(start 309.926228 -89.184734)
		(end 310.073548 -89.184734)
		(width 0.0889)
		(layer "F.Cu")
		(net "P3E_CPU0_PE2_SS_TXP<1>")
	)
	(segment
		(start 386.917438 -43.769026)
		(end 389.145272 -43.32097)
		(width 0.1143)
		(layer "F.Cu")
		(net "P3E_CPU0_PE2_SS_TXP<1>")
	)
	(segment
		(start 358.831896 -66.09588)
		(end 360.886248 -64.547242)
		(width 0.1143)
		(layer "F.Cu")
		(net "P3E_CPU0_PE2_SS_TXP<1>")
	)
	(segment
		(start 306.145692 -89.231978)
		(end 306.018184 -89.231978)
		(width 0.0889)
		(layer "F.Cu")
		(net "P3E_CPU0_PE2_SS_TXP<1>")
	)
	(segment
		(start 377.20778 -49.793906)
		(end 378.59716 -50.144934)
		(width 0.1143)
		(layer "F.Cu")
		(net "P3E_CPU0_PE2_SS_TXP<1>")
	)
	(segment
		(start 408.187398 -11.24966)
		(end 408.520392 -10.916666)
		(width 0.1143)
		(layer "F.Cu")
		(net "P3E_CPU0_PE2_SS_TXP<1>")
	)
	(segment
		(start 308.503828 -89.184734)
		(end 308.770528 -89.184734)
		(width 0.0889)
		(layer "F.Cu")
		(net "P3E_CPU0_PE2_SS_TXP<1>")
	)
	(segment
		(start 350.96577 -65.48755)
		(end 355.556312 -66.740024)
		(width 0.1143)
		(layer "F.Cu")
		(net "P3E_CPU0_PE2_SS_TXP<1>")
	)
	(segment
		(start 408.197812 -11.473688)
		(end 408.187398 -11.24966)
		(width 0.1143)
		(layer "F.Cu")
		(net "P3E_CPU0_PE2_SS_TXP<1>")
	)
	(segment
		(start 396.338298 -18.53692)
		(end 402.711158 -14.319504)
		(width 0.1143)
		(layer "F.Cu")
		(net "P3E_CPU0_PE2_SS_TXP<1>")
	)
	(segment
		(start 348.426532 -65.510664)
		(end 348.436184 -65.508378)
		(width 0.1143)
		(layer "F.Cu")
		(net "P3E_CPU0_PE2_SS_TXP<1>")
	)
	(segment
		(start 322.42633 -78.746604)
		(end 324.721474 -75.443334)
		(width 0.1143)
		(layer "F.Cu")
		(net "P3E_CPU0_PE2_SS_TXP<1>")
	)
	(segment
		(start 392.303762 -40.073326)
		(end 392.562588 -38.800024)
		(width 0.1143)
		(layer "F.Cu")
		(net "P3E_CPU0_PE2_SS_TXP<1>")
	)
	(segment
		(start 308.148228 -89.273634)
		(end 308.414928 -89.273634)
		(width 0.0889)
		(layer "F.Cu")
		(net "P3E_CPU0_PE2_SS_TXP<1>")
	)
	(via
		(at 322.42633 -78.746604)
		(size 0.508)
		(drill 0.254)
		(layers "F.Cu" "B.Cu")
		(net "P3E_CPU0_PE2_SS_TXP<1>")
	)
	(arc
		(start 306.739036 -88.889586)
		(mid 306.94604 -89.10045)
		(end 307.229256 -89.184734)
		(width 0.0889)
		(layer "F.Cu")
		(net "P3E_CPU0_PE2_SS_TXP<1>")
	)
	(arc
		(start 306.018184 -89.231978)
		(mid 306.220596 -88.728181)
		(end 306.739036 -88.889586)
		(width 0.0889)
		(layer "F.Cu")
		(net "P3E_CPU0_PE2_SS_TXP<1>")
	)
	(segment
		(start 360.138472 -19.809968)
		(end 360.138726 -19.810222)
		(width 0.1143)
		(layer "F.Cu")
		(net "P3E_CPU0_PE2_SS_TXP<15>")
	)
	(segment
		(start 361.796584 -14.130528)
		(end 361.854496 -14.281658)
		(width 0.1143)
		(layer "F.Cu")
		(net "P3E_CPU0_PE2_SS_TXP<15>")
	)
	(segment
		(start 343.6239 -46.096174)
		(end 341.2998 -45.631354)
		(width 0.1143)
		(layer "F.Cu")
		(net "P3E_CPU0_PE2_SS_TXP<15>")
	)
	(segment
		(start 356.82936 -42.346118)
		(end 352.807778 -45.069252)
		(width 0.1143)
		(layer "F.Cu")
		(net "P3E_CPU0_PE2_SS_TXP<15>")
	)
	(segment
		(start 360.156506 -22.64283)
		(end 360.492548 -24.221186)
		(width 0.1143)
		(layer "F.Cu")
		(net "P3E_CPU0_PE2_SS_TXP<15>")
	)
	(segment
		(start 312.864246 -66.167)
		(end 307.688742 -73.420732)
		(width 0.1143)
		(layer "F.Cu")
		(net "P3E_CPU0_PE2_SS_TXP<15>")
	)
	(segment
		(start 360.138726 -19.810222)
		(end 360.448352 -21.267674)
		(width 0.1143)
		(layer "F.Cu")
		(net "P3E_CPU0_PE2_SS_TXP<15>")
	)
	(segment
		(start 347.7006 -45.280834)
		(end 343.6239 -46.096174)
		(width 0.1143)
		(layer "F.Cu")
		(net "P3E_CPU0_PE2_SS_TXP<15>")
	)
	(segment
		(start 341.2998 -45.631354)
		(end 339.089746 -46.073314)
		(width 0.1143)
		(layer "F.Cu")
		(net "P3E_CPU0_PE2_SS_TXP<15>")
	)
	(segment
		(start 356.530656 -37.58565)
		(end 357.227632 -40.472614)
		(width 0.1143)
		(layer "F.Cu")
		(net "P3E_CPU0_PE2_SS_TXP<15>")
	)
	(segment
		(start 306.418996 -75.125834)
		(end 306.016152 -75.125834)
		(width 0.0889)
		(layer "F.Cu")
		(net "P3E_CPU0_PE2_SS_TXP<15>")
	)
	(segment
		(start 362.16971 -13.29563)
		(end 362.227368 -13.44676)
		(width 0.1143)
		(layer "F.Cu")
		(net "P3E_CPU0_PE2_SS_TXP<15>")
	)
	(segment
		(start 360.820462 -16.595598)
		(end 360.138472 -19.80946)
		(width 0.1143)
		(layer "F.Cu")
		(net "P3E_CPU0_PE2_SS_TXP<15>")
	)
	(segment
		(start 307.024278 -74.39787)
		(end 306.883054 -74.421746)
		(width 0.0889)
		(layer "F.Cu")
		(net "P3E_CPU0_PE2_SS_TXP<15>")
	)
	(segment
		(start 306.77993 -74.56678)
		(end 306.803552 -74.70775)
		(width 0.0889)
		(layer "F.Cu")
		(net "P3E_CPU0_PE2_SS_TXP<15>")
	)
	(segment
		(start 307.688742 -73.420732)
		(end 307.682138 -73.473818)
		(width 0.0889)
		(layer "F.Cu")
		(net "P3E_CPU0_PE2_SS_TXP<15>")
	)
	(segment
		(start 305.954176 -75.063858)
		(end 305.776376 -75.063858)
		(width 0.0889)
		(layer "F.Cu")
		(net "P3E_CPU0_PE2_SS_TXP<15>")
	)
	(segment
		(start 339.089746 -46.073314)
		(end 339.089238 -46.07306)
		(width 0.1143)
		(layer "F.Cu")
		(net "P3E_CPU0_PE2_SS_TXP<15>")
	)
	(segment
		(start 306.700682 -74.85253)
		(end 306.418996 -75.125834)
		(width 0.0889)
		(layer "F.Cu")
		(net "P3E_CPU0_PE2_SS_TXP<15>")
	)
	(segment
		(start 360.138472 -19.80946)
		(end 360.138472 -19.809968)
		(width 0.1143)
		(layer "F.Cu")
		(net "P3E_CPU0_PE2_SS_TXP<15>")
	)
	(segment
		(start 358.56926 -30.7086)
		(end 356.530656 -37.58565)
		(width 0.1143)
		(layer "F.Cu")
		(net "P3E_CPU0_PE2_SS_TXP<15>")
	)
	(segment
		(start 360.448352 -21.267674)
		(end 360.156506 -22.64283)
		(width 0.1143)
		(layer "F.Cu")
		(net "P3E_CPU0_PE2_SS_TXP<15>")
	)
	(segment
		(start 323.221858 -53.81752)
		(end 321.161918 -56.812434)
		(width 0.1143)
		(layer "F.Cu")
		(net "P3E_CPU0_PE2_SS_TXP<15>")
	)
	(segment
		(start 362.600494 -12.611862)
		(end 362.46054 -12.925044)
		(width 0.1143)
		(layer "F.Cu")
		(net "P3E_CPU0_PE2_SS_TXP<15>")
	)
	(segment
		(start 362.46054 -12.925044)
		(end 362.309664 -12.982702)
		(width 0.1143)
		(layer "F.Cu")
		(net "P3E_CPU0_PE2_SS_TXP<15>")
	)
	(segment
		(start 307.103526 -74.11212)
		(end 307.127148 -74.25309)
		(width 0.0889)
		(layer "F.Cu")
		(net "P3E_CPU0_PE2_SS_TXP<15>")
	)
	(segment
		(start 361.854496 -14.281658)
		(end 360.820462 -16.595598)
		(width 0.1143)
		(layer "F.Cu")
		(net "P3E_CPU0_PE2_SS_TXP<15>")
	)
	(segment
		(start 360.492548 -24.221186)
		(end 358.56926 -30.7086)
		(width 0.1143)
		(layer "F.Cu")
		(net "P3E_CPU0_PE2_SS_TXP<15>")
	)
	(segment
		(start 303.967642 -76.087224)
		(end 303.816766 -75.716384)
		(width 0.0889)
		(layer "F.Cu")
		(net "P3E_CPU0_PE2_SS_TXP<15>")
	)
	(segment
		(start 352.807778 -45.069252)
		(end 349.725996 -45.685964)
		(width 0.1143)
		(layer "F.Cu")
		(net "P3E_CPU0_PE2_SS_TXP<15>")
	)
	(segment
		(start 305.776376 -75.063858)
		(end 305.7144 -75.125834)
		(width 0.0889)
		(layer "F.Cu")
		(net "P3E_CPU0_PE2_SS_TXP<15>")
	)
	(segment
		(start 316.427358 -63.696596)
		(end 312.864246 -66.167)
		(width 0.1143)
		(layer "F.Cu")
		(net "P3E_CPU0_PE2_SS_TXP<15>")
	)
	(segment
		(start 362.087668 -13.759688)
		(end 361.936538 -13.8176)
		(width 0.1143)
		(layer "F.Cu")
		(net "P3E_CPU0_PE2_SS_TXP<15>")
	)
	(segment
		(start 362.600494 -11.240008)
		(end 362.600494 -12.611862)
		(width 0.1143)
		(layer "F.Cu")
		(net "P3E_CPU0_PE2_SS_TXP<15>")
	)
	(segment
		(start 306.016152 -75.125834)
		(end 305.954176 -75.063858)
		(width 0.0889)
		(layer "F.Cu")
		(net "P3E_CPU0_PE2_SS_TXP<15>")
	)
	(segment
		(start 321.161918 -56.812434)
		(end 316.427358 -63.696596)
		(width 0.1143)
		(layer "F.Cu")
		(net "P3E_CPU0_PE2_SS_TXP<15>")
	)
	(segment
		(start 306.803552 -74.70775)
		(end 306.700682 -74.85253)
		(width 0.0889)
		(layer "F.Cu")
		(net "P3E_CPU0_PE2_SS_TXP<15>")
	)
	(segment
		(start 305.7144 -75.125834)
		(end 305.516026 -75.125834)
		(width 0.0889)
		(layer "F.Cu")
		(net "P3E_CPU0_PE2_SS_TXP<15>")
	)
	(segment
		(start 331.078078 -47.683928)
		(end 327.180194 -50.727102)
		(width 0.1143)
		(layer "F.Cu")
		(net "P3E_CPU0_PE2_SS_TXP<15>")
	)
	(segment
		(start 307.20665 -73.967086)
		(end 307.103526 -74.11212)
		(width 0.0889)
		(layer "F.Cu")
		(net "P3E_CPU0_PE2_SS_TXP<15>")
	)
	(segment
		(start 362.276644 -10.916158)
		(end 362.600494 -11.240008)
		(width 0.1143)
		(layer "F.Cu")
		(net "P3E_CPU0_PE2_SS_TXP<15>")
	)
	(segment
		(start 327.180194 -50.727102)
		(end 323.221858 -53.81752)
		(width 0.1143)
		(layer "F.Cu")
		(net "P3E_CPU0_PE2_SS_TXP<15>")
	)
	(segment
		(start 362.227368 -13.44676)
		(end 362.087668 -13.759688)
		(width 0.1143)
		(layer "F.Cu")
		(net "P3E_CPU0_PE2_SS_TXP<15>")
	)
	(segment
		(start 339.089238 -46.07306)
		(end 337.174332 -45.690028)
		(width 0.1143)
		(layer "F.Cu")
		(net "P3E_CPU0_PE2_SS_TXP<15>")
	)
	(segment
		(start 349.725996 -45.685964)
		(end 347.7006 -45.280834)
		(width 0.1143)
		(layer "F.Cu")
		(net "P3E_CPU0_PE2_SS_TXP<15>")
	)
	(segment
		(start 307.682138 -73.473818)
		(end 307.347874 -73.943464)
		(width 0.0889)
		(layer "F.Cu")
		(net "P3E_CPU0_PE2_SS_TXP<15>")
	)
	(segment
		(start 306.883054 -74.421746)
		(end 306.77993 -74.56678)
		(width 0.0889)
		(layer "F.Cu")
		(net "P3E_CPU0_PE2_SS_TXP<15>")
	)
	(segment
		(start 307.127148 -74.25309)
		(end 307.024278 -74.39787)
		(width 0.0889)
		(layer "F.Cu")
		(net "P3E_CPU0_PE2_SS_TXP<15>")
	)
	(segment
		(start 361.936538 -13.8176)
		(end 361.796584 -14.130528)
		(width 0.1143)
		(layer "F.Cu")
		(net "P3E_CPU0_PE2_SS_TXP<15>")
	)
	(segment
		(start 307.347874 -73.943464)
		(end 307.20665 -73.967086)
		(width 0.0889)
		(layer "F.Cu")
		(net "P3E_CPU0_PE2_SS_TXP<15>")
	)
	(segment
		(start 357.227632 -40.472614)
		(end 356.82936 -42.346118)
		(width 0.1143)
		(layer "F.Cu")
		(net "P3E_CPU0_PE2_SS_TXP<15>")
	)
	(segment
		(start 337.174332 -45.690028)
		(end 331.078078 -47.683928)
		(width 0.1143)
		(layer "F.Cu")
		(net "P3E_CPU0_PE2_SS_TXP<15>")
	)
	(segment
		(start 304.686462 -75.621388)
		(end 304.653696 -75.621388)
		(width 0.0889)
		(layer "F.Cu")
		(net "P3E_CPU0_PE2_SS_TXP<15>")
	)
	(segment
		(start 362.309664 -12.982702)
		(end 362.16971 -13.29563)
		(width 0.1143)
		(layer "F.Cu")
		(net "P3E_CPU0_PE2_SS_TXP<15>")
	)
	(via
		(at 327.180194 -50.727102)
		(size 0.508)
		(drill 0.254)
		(layers "F.Cu" "B.Cu")
		(net "P3E_CPU0_PE2_SS_TXP<15>")
	)
	(arc
		(start 304.163476 -75.916536)
		(mid 304.079783 -76.018197)
		(end 303.967642 -76.087224)
		(width 0.0889)
		(layer "F.Cu")
		(net "P3E_CPU0_PE2_SS_TXP<15>")
	)
	(arc
		(start 305.021996 -75.421236)
		(mid 304.880313 -75.56504)
		(end 304.686462 -75.621388)
		(width 0.0889)
		(layer "F.Cu")
		(net "P3E_CPU0_PE2_SS_TXP<15>")
	)
	(arc
		(start 305.516026 -75.125834)
		(mid 305.230602 -75.209301)
		(end 305.021996 -75.421236)
		(width 0.0889)
		(layer "F.Cu")
		(net "P3E_CPU0_PE2_SS_TXP<15>")
	)
	(arc
		(start 304.653696 -75.621388)
		(mid 304.370479 -75.705669)
		(end 304.163476 -75.916536)
		(width 0.0889)
		(layer "F.Cu")
		(net "P3E_CPU0_PE2_SS_TXP<15>")
	)
	(segment
		(start 307.644546 -75.576938)
		(end 307.59654 -75.600814)
		(width 0.0889)
		(layer "F.Cu")
		(net "P3E_CPU0_PE2_SS_TXP<14>")
	)
	(segment
		(start 364.983776 -12.674854)
		(end 363.35843 -14.3002)
		(width 0.1143)
		(layer "F.Cu")
		(net "P3E_CPU0_PE2_SS_TXP<14>")
	)
	(segment
		(start 339.1027 -47.31258)
		(end 337.264756 -46.945042)
		(width 0.1143)
		(layer "F.Cu")
		(net "P3E_CPU0_PE2_SS_TXP<14>")
	)
	(segment
		(start 343.6874 -47.3456)
		(end 341.3125 -46.87062)
		(width 0.1143)
		(layer "F.Cu")
		(net "P3E_CPU0_PE2_SS_TXP<14>")
	)
	(segment
		(start 341.3125 -46.87062)
		(end 339.1027 -47.31258)
		(width 0.1143)
		(layer "F.Cu")
		(net "P3E_CPU0_PE2_SS_TXP<14>")
	)
	(segment
		(start 361.411266 -19.809714)
		(end 361.721146 -21.268182)
		(width 0.1143)
		(layer "F.Cu")
		(net "P3E_CPU0_PE2_SS_TXP<14>")
	)
	(segment
		(start 307.444902 -75.813666)
		(end 306.83835 -76.306934)
		(width 0.0889)
		(layer "F.Cu")
		(net "P3E_CPU0_PE2_SS_TXP<14>")
	)
	(segment
		(start 361.721146 -21.268182)
		(end 361.4293 -22.642322)
		(width 0.1143)
		(layer "F.Cu")
		(net "P3E_CPU0_PE2_SS_TXP<14>")
	)
	(segment
		(start 361.775756 -24.271224)
		(end 357.815134 -37.633656)
		(width 0.1143)
		(layer "F.Cu")
		(net "P3E_CPU0_PE2_SS_TXP<14>")
	)
	(segment
		(start 353.08794 -46.343316)
		(end 349.90405 -46.980602)
		(width 0.1143)
		(layer "F.Cu")
		(net "P3E_CPU0_PE2_SS_TXP<14>")
	)
	(segment
		(start 365.489744 -10.916158)
		(end 365.165894 -11.240008)
		(width 0.1143)
		(layer "F.Cu")
		(net "P3E_CPU0_PE2_SS_TXP<14>")
	)
	(segment
		(start 313.72429 -67.054476)
		(end 307.644546 -75.576938)
		(width 0.1143)
		(layer "F.Cu")
		(net "P3E_CPU0_PE2_SS_TXP<14>")
	)
	(segment
		(start 365.165894 -12.23518)
		(end 364.983776 -12.674854)
		(width 0.1143)
		(layer "F.Cu")
		(net "P3E_CPU0_PE2_SS_TXP<14>")
	)
	(segment
		(start 306.83835 -76.306934)
		(end 305.52263 -76.306934)
		(width 0.0889)
		(layer "F.Cu")
		(net "P3E_CPU0_PE2_SS_TXP<14>")
	)
	(segment
		(start 332.030832 -48.657764)
		(end 326.8599 -52.695602)
		(width 0.1143)
		(layer "F.Cu")
		(net "P3E_CPU0_PE2_SS_TXP<14>")
	)
	(segment
		(start 347.707966 -46.541436)
		(end 343.6874 -47.3456)
		(width 0.1143)
		(layer "F.Cu")
		(net "P3E_CPU0_PE2_SS_TXP<14>")
	)
	(segment
		(start 349.90405 -46.980602)
		(end 347.707966 -46.541436)
		(width 0.1143)
		(layer "F.Cu")
		(net "P3E_CPU0_PE2_SS_TXP<14>")
	)
	(segment
		(start 307.59654 -75.600814)
		(end 307.444902 -75.813666)
		(width 0.0889)
		(layer "F.Cu")
		(net "P3E_CPU0_PE2_SS_TXP<14>")
	)
	(segment
		(start 365.165894 -11.240008)
		(end 365.165894 -12.23518)
		(width 0.1143)
		(layer "F.Cu")
		(net "P3E_CPU0_PE2_SS_TXP<14>")
	)
	(segment
		(start 337.264756 -46.945042)
		(end 332.030832 -48.657764)
		(width 0.1143)
		(layer "F.Cu")
		(net "P3E_CPU0_PE2_SS_TXP<14>")
	)
	(segment
		(start 363.35843 -14.3002)
		(end 362.03382 -16.872204)
		(width 0.1143)
		(layer "F.Cu")
		(net "P3E_CPU0_PE2_SS_TXP<14>")
	)
	(segment
		(start 305.246532 -76.541376)
		(end 305.533806 -76.706984)
		(width 0.0889)
		(layer "F.Cu")
		(net "P3E_CPU0_PE2_SS_TXP<14>")
	)
	(segment
		(start 357.815134 -37.633656)
		(end 358.484932 -40.412162)
		(width 0.1143)
		(layer "F.Cu")
		(net "P3E_CPU0_PE2_SS_TXP<14>")
	)
	(segment
		(start 305.223418 -76.454762)
		(end 305.246532 -76.541376)
		(width 0.0889)
		(layer "F.Cu")
		(net "P3E_CPU0_PE2_SS_TXP<14>")
	)
	(segment
		(start 323.382132 -55.741824)
		(end 317.313564 -64.565276)
		(width 0.1143)
		(layer "F.Cu")
		(net "P3E_CPU0_PE2_SS_TXP<14>")
	)
	(segment
		(start 323.873876 -55.027068)
		(end 323.382132 -55.741824)
		(width 0.1143)
		(layer "F.Cu")
		(net "P3E_CPU0_PE2_SS_TXP<14>")
	)
	(segment
		(start 326.8599 -52.695602)
		(end 323.873876 -55.027068)
		(width 0.1143)
		(layer "F.Cu")
		(net "P3E_CPU0_PE2_SS_TXP<14>")
	)
	(segment
		(start 358.484932 -40.412162)
		(end 357.945436 -43.05427)
		(width 0.1143)
		(layer "F.Cu")
		(net "P3E_CPU0_PE2_SS_TXP<14>")
	)
	(segment
		(start 357.945436 -43.05427)
		(end 353.08794 -46.343316)
		(width 0.1143)
		(layer "F.Cu")
		(net "P3E_CPU0_PE2_SS_TXP<14>")
	)
	(segment
		(start 362.03382 -16.872204)
		(end 361.411266 -19.809714)
		(width 0.1143)
		(layer "F.Cu")
		(net "P3E_CPU0_PE2_SS_TXP<14>")
	)
	(segment
		(start 317.313564 -64.565276)
		(end 313.72429 -67.054476)
		(width 0.1143)
		(layer "F.Cu")
		(net "P3E_CPU0_PE2_SS_TXP<14>")
	)
	(segment
		(start 361.4293 -22.642322)
		(end 361.775756 -24.271224)
		(width 0.1143)
		(layer "F.Cu")
		(net "P3E_CPU0_PE2_SS_TXP<14>")
	)
	(via
		(at 326.8599 -52.695602)
		(size 0.508)
		(drill 0.254)
		(layers "F.Cu" "B.Cu")
		(net "P3E_CPU0_PE2_SS_TXP<14>")
	)
	(arc
		(start 305.52263 -76.306934)
		(mid 305.356856 -76.34814)
		(end 305.223418 -76.454762)
		(width 0.0889)
		(layer "F.Cu")
		(net "P3E_CPU0_PE2_SS_TXP<14>")
	)
	(segment
		(start 362.742734 -17.202404)
		(end 362.189776 -19.80946)
		(width 0.1143)
		(layer "F.Cu")
		(net "P3E_CPU0_PE2_SS_TXP<13>")
	)
	(segment
		(start 306.88661 -77.107034)
		(end 307.092096 -77.107034)
		(width 0.0889)
		(layer "F.Cu")
		(net "P3E_CPU0_PE2_SS_TXP<13>")
	)
	(segment
		(start 304.388012 -77.368146)
		(end 304.364898 -77.45476)
		(width 0.0889)
		(layer "F.Cu")
		(net "P3E_CPU0_PE2_SS_TXP<13>")
	)
	(segment
		(start 362.208064 -22.641814)
		(end 362.561124 -24.302466)
		(width 0.1143)
		(layer "F.Cu")
		(net "P3E_CPU0_PE2_SS_TXP<13>")
	)
	(segment
		(start 305.863498 -77.03312)
		(end 306.130198 -77.03312)
		(width 0.0889)
		(layer "F.Cu")
		(net "P3E_CPU0_PE2_SS_TXP<13>")
	)
	(segment
		(start 307.808884 -76.641198)
		(end 307.790596 -76.53528)
		(width 0.0889)
		(layer "F.Cu")
		(net "P3E_CPU0_PE2_SS_TXP<13>")
	)
	(segment
		(start 307.6956 -76.79309)
		(end 307.703728 -76.788772)
		(width 0.0889)
		(layer "F.Cu")
		(net "P3E_CPU0_PE2_SS_TXP<13>")
	)
	(segment
		(start 314.222892 -67.604386)
		(end 318.43599 -64.683386)
		(width 0.1143)
		(layer "F.Cu")
		(net "P3E_CPU0_PE2_SS_TXP<13>")
	)
	(segment
		(start 307.21808 -76.93914)
		(end 307.455316 -76.815696)
		(width 0.0889)
		(layer "F.Cu")
		(net "P3E_CPU0_PE2_SS_TXP<13>")
	)
	(segment
		(start 305.789584 -77.107034)
		(end 305.863498 -77.03312)
		(width 0.0889)
		(layer "F.Cu")
		(net "P3E_CPU0_PE2_SS_TXP<13>")
	)
	(segment
		(start 307.703728 -76.788772)
		(end 307.808884 -76.641198)
		(width 0.0889)
		(layer "F.Cu")
		(net "P3E_CPU0_PE2_SS_TXP<13>")
	)
	(segment
		(start 367.145062 -12.577318)
		(end 366.264698 -13.159994)
		(width 0.1143)
		(layer "F.Cu")
		(net "P3E_CPU0_PE2_SS_TXP<13>")
	)
	(segment
		(start 364.609126 -14.25575)
		(end 364.609126 -14.256258)
		(width 0.1143)
		(layer "F.Cu")
		(net "P3E_CPU0_PE2_SS_TXP<13>")
	)
	(segment
		(start 367.077244 -10.916158)
		(end 367.401094 -11.240008)
		(width 0.1143)
		(layer "F.Cu")
		(net "P3E_CPU0_PE2_SS_TXP<13>")
	)
	(segment
		(start 307.455316 -76.815696)
		(end 307.57749 -76.854558)
		(width 0.0889)
		(layer "F.Cu")
		(net "P3E_CPU0_PE2_SS_TXP<13>")
	)
	(segment
		(start 365.820452 -13.31722)
		(end 365.788194 -13.475462)
		(width 0.1143)
		(layer "F.Cu")
		(net "P3E_CPU0_PE2_SS_TXP<13>")
	)
	(segment
		(start 318.43599 -64.683386)
		(end 325.036688 -55.085996)
		(width 0.1143)
		(layer "F.Cu")
		(net "P3E_CPU0_PE2_SS_TXP<13>")
	)
	(segment
		(start 341.286846 -47.640494)
		(end 339.153246 -48.067214)
		(width 0.1143)
		(layer "F.Cu")
		(net "P3E_CPU0_PE2_SS_TXP<13>")
	)
	(segment
		(start 306.819554 -77.039978)
		(end 306.88661 -77.107034)
		(width 0.0889)
		(layer "F.Cu")
		(net "P3E_CPU0_PE2_SS_TXP<13>")
	)
	(segment
		(start 308.051454 -76.30033)
		(end 308.169564 -76.134468)
		(width 0.0889)
		(layer "F.Cu")
		(net "P3E_CPU0_PE2_SS_TXP<13>")
	)
	(segment
		(start 307.179726 -77.061314)
		(end 307.21808 -76.93914)
		(width 0.0889)
		(layer "F.Cu")
		(net "P3E_CPU0_PE2_SS_TXP<13>")
	)
	(segment
		(start 306.552854 -77.039978)
		(end 306.819554 -77.039978)
		(width 0.0889)
		(layer "F.Cu")
		(net "P3E_CPU0_PE2_SS_TXP<13>")
	)
	(segment
		(start 366.264698 -13.159994)
		(end 366.106456 -13.127736)
		(width 0.1143)
		(layer "F.Cu")
		(net "P3E_CPU0_PE2_SS_TXP<13>")
	)
	(segment
		(start 365.057944 -13.821918)
		(end 365.025686 -13.98016)
		(width 0.1143)
		(layer "F.Cu")
		(net "P3E_CPU0_PE2_SS_TXP<13>")
	)
	(segment
		(start 358.583992 -37.718746)
		(end 359.255822 -40.501062)
		(width 0.1143)
		(layer "F.Cu")
		(net "P3E_CPU0_PE2_SS_TXP<13>")
	)
	(segment
		(start 362.189776 -19.80946)
		(end 362.49991 -21.268182)
		(width 0.1143)
		(layer "F.Cu")
		(net "P3E_CPU0_PE2_SS_TXP<13>")
	)
	(segment
		(start 325.036688 -55.085996)
		(end 325.624698 -54.626764)
		(width 0.1143)
		(layer "F.Cu")
		(net "P3E_CPU0_PE2_SS_TXP<13>")
	)
	(segment
		(start 339.153246 -48.06696)
		(end 337.32851 -47.702216)
		(width 0.1143)
		(layer "F.Cu")
		(net "P3E_CPU0_PE2_SS_TXP<13>")
	)
	(segment
		(start 364.609126 -14.256258)
		(end 364.079282 -14.606524)
		(width 0.1143)
		(layer "F.Cu")
		(net "P3E_CPU0_PE2_SS_TXP<13>")
	)
	(segment
		(start 365.788194 -13.475462)
		(end 365.50219 -13.664692)
		(width 0.1143)
		(layer "F.Cu")
		(net "P3E_CPU0_PE2_SS_TXP<13>")
	)
	(segment
		(start 343.5985 -48.102774)
		(end 341.286846 -47.640494)
		(width 0.1143)
		(layer "F.Cu")
		(net "P3E_CPU0_PE2_SS_TXP<13>")
	)
	(segment
		(start 359.255822 -40.501062)
		(end 358.63149 -43.549824)
		(width 0.1143)
		(layer "F.Cu")
		(net "P3E_CPU0_PE2_SS_TXP<13>")
	)
	(segment
		(start 362.561124 -24.302466)
		(end 358.583992 -37.718746)
		(width 0.1143)
		(layer "F.Cu")
		(net "P3E_CPU0_PE2_SS_TXP<13>")
	)
	(segment
		(start 349.967296 -47.766224)
		(end 347.6244 -47.297594)
		(width 0.1143)
		(layer "F.Cu")
		(net "P3E_CPU0_PE2_SS_TXP<13>")
	)
	(segment
		(start 332.447392 -49.29886)
		(end 325.624698 -54.626764)
		(width 0.1143)
		(layer "F.Cu")
		(net "P3E_CPU0_PE2_SS_TXP<13>")
	)
	(segment
		(start 306.130198 -77.03312)
		(end 306.204112 -77.107034)
		(width 0.0889)
		(layer "F.Cu")
		(net "P3E_CPU0_PE2_SS_TXP<13>")
	)
	(segment
		(start 307.790596 -76.53528)
		(end 307.945536 -76.317602)
		(width 0.0889)
		(layer "F.Cu")
		(net "P3E_CPU0_PE2_SS_TXP<13>")
	)
	(segment
		(start 308.169564 -76.134468)
		(end 308.169818 -76.13396)
		(width 0.0889)
		(layer "F.Cu")
		(net "P3E_CPU0_PE2_SS_TXP<13>")
	)
	(segment
		(start 307.57749 -76.854558)
		(end 307.6956 -76.79309)
		(width 0.0889)
		(layer "F.Cu")
		(net "P3E_CPU0_PE2_SS_TXP<13>")
	)
	(segment
		(start 306.204112 -77.107034)
		(end 306.485798 -77.107034)
		(width 0.0889)
		(layer "F.Cu")
		(net "P3E_CPU0_PE2_SS_TXP<13>")
	)
	(segment
		(start 339.153246 -48.067214)
		(end 339.153246 -48.06696)
		(width 0.1143)
		(layer "F.Cu")
		(net "P3E_CPU0_PE2_SS_TXP<13>")
	)
	(segment
		(start 308.177438 -76.07935)
		(end 314.222892 -67.604386)
		(width 0.1143)
		(layer "F.Cu")
		(net "P3E_CPU0_PE2_SS_TXP<13>")
	)
	(segment
		(start 306.485798 -77.107034)
		(end 306.552854 -77.039978)
		(width 0.0889)
		(layer "F.Cu")
		(net "P3E_CPU0_PE2_SS_TXP<13>")
	)
	(segment
		(start 347.6244 -47.297594)
		(end 343.5985 -48.102774)
		(width 0.1143)
		(layer "F.Cu")
		(net "P3E_CPU0_PE2_SS_TXP<13>")
	)
	(segment
		(start 365.50219 -13.664692)
		(end 365.343948 -13.632434)
		(width 0.1143)
		(layer "F.Cu")
		(net "P3E_CPU0_PE2_SS_TXP<13>")
	)
	(segment
		(start 362.49991 -21.268182)
		(end 362.208064 -22.641814)
		(width 0.1143)
		(layer "F.Cu")
		(net "P3E_CPU0_PE2_SS_TXP<13>")
	)
	(segment
		(start 367.401094 -11.996928)
		(end 367.145062 -12.577318)
		(width 0.1143)
		(layer "F.Cu")
		(net "P3E_CPU0_PE2_SS_TXP<13>")
	)
	(segment
		(start 308.17693 -76.124054)
		(end 308.177438 -76.07935)
		(width 0.0889)
		(layer "F.Cu")
		(net "P3E_CPU0_PE2_SS_TXP<13>")
	)
	(segment
		(start 353.311714 -47.096934)
		(end 349.967296 -47.766224)
		(width 0.1143)
		(layer "F.Cu")
		(net "P3E_CPU0_PE2_SS_TXP<13>")
	)
	(segment
		(start 332.447646 -49.298606)
		(end 332.447392 -49.29886)
		(width 0.1143)
		(layer "F.Cu")
		(net "P3E_CPU0_PE2_SS_TXP<13>")
	)
	(segment
		(start 364.079282 -14.606524)
		(end 362.742734 -17.202404)
		(width 0.1143)
		(layer "F.Cu")
		(net "P3E_CPU0_PE2_SS_TXP<13>")
	)
	(segment
		(start 367.401094 -11.240008)
		(end 367.401094 -11.996928)
		(width 0.1143)
		(layer "F.Cu")
		(net "P3E_CPU0_PE2_SS_TXP<13>")
	)
	(segment
		(start 366.106456 -13.127736)
		(end 365.820452 -13.31722)
		(width 0.1143)
		(layer "F.Cu")
		(net "P3E_CPU0_PE2_SS_TXP<13>")
	)
	(segment
		(start 307.945536 -76.317602)
		(end 308.051454 -76.30033)
		(width 0.0889)
		(layer "F.Cu")
		(net "P3E_CPU0_PE2_SS_TXP<13>")
	)
	(segment
		(start 308.170834 -76.13269)
		(end 308.17693 -76.124054)
		(width 0.0889)
		(layer "F.Cu")
		(net "P3E_CPU0_PE2_SS_TXP<13>")
	)
	(segment
		(start 365.343948 -13.632434)
		(end 365.057944 -13.821918)
		(width 0.1143)
		(layer "F.Cu")
		(net "P3E_CPU0_PE2_SS_TXP<13>")
	)
	(segment
		(start 308.169818 -76.13396)
		(end 308.170834 -76.13269)
		(width 0.0889)
		(layer "F.Cu")
		(net "P3E_CPU0_PE2_SS_TXP<13>")
	)
	(segment
		(start 365.025686 -13.98016)
		(end 364.609126 -14.25575)
		(width 0.1143)
		(layer "F.Cu")
		(net "P3E_CPU0_PE2_SS_TXP<13>")
	)
	(segment
		(start 305.52009 -77.107034)
		(end 305.789584 -77.107034)
		(width 0.0889)
		(layer "F.Cu")
		(net "P3E_CPU0_PE2_SS_TXP<13>")
	)
	(segment
		(start 304.675286 -77.202538)
		(end 304.531776 -77.285342)
		(width 0.0889)
		(layer "F.Cu")
		(net "P3E_CPU0_PE2_SS_TXP<13>")
	)
	(segment
		(start 358.63149 -43.549824)
		(end 353.311714 -47.096934)
		(width 0.1143)
		(layer "F.Cu")
		(net "P3E_CPU0_PE2_SS_TXP<13>")
	)
	(segment
		(start 304.531776 -77.285342)
		(end 304.388012 -77.368146)
		(width 0.0889)
		(layer "F.Cu")
		(net "P3E_CPU0_PE2_SS_TXP<13>")
	)
	(segment
		(start 337.32851 -47.702216)
		(end 332.447646 -49.298606)
		(width 0.1143)
		(layer "F.Cu")
		(net "P3E_CPU0_PE2_SS_TXP<13>")
	)
	(segment
		(start 307.092096 -77.107034)
		(end 307.179726 -77.061314)
		(width 0.0889)
		(layer "F.Cu")
		(net "P3E_CPU0_PE2_SS_TXP<13>")
	)
	(via
		(at 325.624698 -54.626764)
		(size 0.508)
		(drill 0.254)
		(layers "F.Cu" "B.Cu")
		(net "P3E_CPU0_PE2_SS_TXP<13>")
	)
	(arc
		(start 305.021996 -77.402436)
		(mid 305.232349 -77.189464)
		(end 305.52009 -77.107034)
		(width 0.0889)
		(layer "F.Cu")
		(net "P3E_CPU0_PE2_SS_TXP<13>")
	)
	(arc
		(start 304.687478 -77.602334)
		(mid 304.880755 -77.545896)
		(end 305.021996 -77.402436)
		(width 0.0889)
		(layer "F.Cu")
		(net "P3E_CPU0_PE2_SS_TXP<13>")
	)
	(arc
		(start 304.364898 -77.45476)
		(mid 304.498062 -77.560999)
		(end 304.663348 -77.602334)
		(width 0.0889)
		(layer "F.Cu")
		(net "P3E_CPU0_PE2_SS_TXP<13>")
	)
	(arc
		(start 304.663348 -77.602334)
		(mid 304.675413 -77.60252)
		(end 304.687478 -77.602334)
		(width 0.0889)
		(layer "F.Cu")
		(net "P3E_CPU0_PE2_SS_TXP<13>")
	)
	(segment
		(start 359.527856 -44.122594)
		(end 360.275632 -40.461438)
		(width 0.1143)
		(layer "F.Cu")
		(net "P3E_CPU0_PE2_SS_TXP<12>")
	)
	(segment
		(start 368.43335 -12.95273)
		(end 368.591592 -12.984988)
		(width 0.1143)
		(layer "F.Cu")
		(net "P3E_CPU0_PE2_SS_TXP<12>")
	)
	(segment
		(start 305.9557 -78.03261)
		(end 306.020978 -78.097888)
		(width 0.0889)
		(layer "F.Cu")
		(net "P3E_CPU0_PE2_SS_TXP<12>")
	)
	(segment
		(start 363.71657 -17.448784)
		(end 364.681516 -15.573248)
		(width 0.1143)
		(layer "F.Cu")
		(net "P3E_CPU0_PE2_SS_TXP<12>")
	)
	(segment
		(start 347.599 -48.293274)
		(end 349.973392 -48.768254)
		(width 0.1143)
		(layer "F.Cu")
		(net "P3E_CPU0_PE2_SS_TXP<12>")
	)
	(segment
		(start 339.192108 -49.07026)
		(end 341.2617 -48.656494)
		(width 0.1143)
		(layer "F.Cu")
		(net "P3E_CPU0_PE2_SS_TXP<12>")
	)
	(segment
		(start 339.1916 -49.070514)
		(end 339.192108 -49.07026)
		(width 0.1143)
		(layer "F.Cu")
		(net "P3E_CPU0_PE2_SS_TXP<12>")
	)
	(segment
		(start 307.295804 -78.097888)
		(end 307.473604 -78.097888)
		(width 0.0889)
		(layer "F.Cu")
		(net "P3E_CPU0_PE2_SS_TXP<12>")
	)
	(segment
		(start 368.147346 -13.142214)
		(end 368.43335 -12.95273)
		(width 0.1143)
		(layer "F.Cu")
		(net "P3E_CPU0_PE2_SS_TXP<12>")
	)
	(segment
		(start 341.2617 -48.656494)
		(end 343.5223 -49.108614)
		(width 0.1143)
		(layer "F.Cu")
		(net "P3E_CPU0_PE2_SS_TXP<12>")
	)
	(segment
		(start 369.801394 -11.240008)
		(end 369.477544 -10.916158)
		(width 0.1143)
		(layer "F.Cu")
		(net "P3E_CPU0_PE2_SS_TXP<12>")
	)
	(segment
		(start 369.24488 -12.55268)
		(end 369.801394 -11.540236)
		(width 0.1143)
		(layer "F.Cu")
		(net "P3E_CPU0_PE2_SS_TXP<12>")
	)
	(segment
		(start 319.114678 -65.402206)
		(end 325.683626 -55.852822)
		(width 0.1143)
		(layer "F.Cu")
		(net "P3E_CPU0_PE2_SS_TXP<12>")
	)
	(segment
		(start 343.5223 -49.108614)
		(end 347.599 -48.293274)
		(width 0.1143)
		(layer "F.Cu")
		(net "P3E_CPU0_PE2_SS_TXP<12>")
	)
	(segment
		(start 307.473604 -78.097888)
		(end 308.255162 -77.701394)
		(width 0.0889)
		(layer "F.Cu")
		(net "P3E_CPU0_PE2_SS_TXP<12>")
	)
	(segment
		(start 304.675286 -78.193138)
		(end 304.825908 -78.563724)
		(width 0.0889)
		(layer "F.Cu")
		(net "P3E_CPU0_PE2_SS_TXP<12>")
	)
	(segment
		(start 305.52009 -78.097888)
		(end 305.712622 -78.097888)
		(width 0.0889)
		(layer "F.Cu")
		(net "P3E_CPU0_PE2_SS_TXP<12>")
	)
	(segment
		(start 314.922154 -68.309744)
		(end 318.649604 -65.724786)
		(width 0.1143)
		(layer "F.Cu")
		(net "P3E_CPU0_PE2_SS_TXP<12>")
	)
	(segment
		(start 367.384838 -13.646912)
		(end 367.670842 -13.457428)
		(width 0.1143)
		(layer "F.Cu")
		(net "P3E_CPU0_PE2_SS_TXP<12>")
	)
	(segment
		(start 363.233716 -22.642068)
		(end 363.525562 -21.268182)
		(width 0.1143)
		(layer "F.Cu")
		(net "P3E_CPU0_PE2_SS_TXP<12>")
	)
	(segment
		(start 308.518052 -77.332586)
		(end 308.51856 -77.287374)
		(width 0.0889)
		(layer "F.Cu")
		(net "P3E_CPU0_PE2_SS_TXP<12>")
	)
	(segment
		(start 306.73802 -78.097888)
		(end 306.91582 -78.097888)
		(width 0.0889)
		(layer "F.Cu")
		(net "P3E_CPU0_PE2_SS_TXP<12>")
	)
	(segment
		(start 306.636928 -77.996796)
		(end 306.73802 -78.097888)
		(width 0.0889)
		(layer "F.Cu")
		(net "P3E_CPU0_PE2_SS_TXP<12>")
	)
	(segment
		(start 364.681516 -15.573248)
		(end 367.35258 -13.805154)
		(width 0.1143)
		(layer "F.Cu")
		(net "P3E_CPU0_PE2_SS_TXP<12>")
	)
	(segment
		(start 306.020978 -78.097888)
		(end 306.358036 -78.097888)
		(width 0.0889)
		(layer "F.Cu")
		(net "P3E_CPU0_PE2_SS_TXP<12>")
	)
	(segment
		(start 363.215428 -19.809206)
		(end 363.71657 -17.448784)
		(width 0.1143)
		(layer "F.Cu")
		(net "P3E_CPU0_PE2_SS_TXP<12>")
	)
	(segment
		(start 305.7779 -78.03261)
		(end 305.9557 -78.03261)
		(width 0.0889)
		(layer "F.Cu")
		(net "P3E_CPU0_PE2_SS_TXP<12>")
	)
	(segment
		(start 306.91582 -78.097888)
		(end 307.016912 -77.996796)
		(width 0.0889)
		(layer "F.Cu")
		(net "P3E_CPU0_PE2_SS_TXP<12>")
	)
	(segment
		(start 363.525562 -21.268182)
		(end 363.215428 -19.809206)
		(width 0.1143)
		(layer "F.Cu")
		(net "P3E_CPU0_PE2_SS_TXP<12>")
	)
	(segment
		(start 306.459128 -77.996796)
		(end 306.636928 -77.996796)
		(width 0.0889)
		(layer "F.Cu")
		(net "P3E_CPU0_PE2_SS_TXP<12>")
	)
	(segment
		(start 332.979776 -50.156364)
		(end 337.395566 -48.711358)
		(width 0.1143)
		(layer "F.Cu")
		(net "P3E_CPU0_PE2_SS_TXP<12>")
	)
	(segment
		(start 367.670842 -13.457428)
		(end 367.829084 -13.489686)
		(width 0.1143)
		(layer "F.Cu")
		(net "P3E_CPU0_PE2_SS_TXP<12>")
	)
	(segment
		(start 353.781614 -48.006762)
		(end 359.527856 -44.122594)
		(width 0.1143)
		(layer "F.Cu")
		(net "P3E_CPU0_PE2_SS_TXP<12>")
	)
	(segment
		(start 306.358036 -78.097888)
		(end 306.459128 -77.996796)
		(width 0.0889)
		(layer "F.Cu")
		(net "P3E_CPU0_PE2_SS_TXP<12>")
	)
	(segment
		(start 307.016912 -77.996796)
		(end 307.194712 -77.996796)
		(width 0.0889)
		(layer "F.Cu")
		(net "P3E_CPU0_PE2_SS_TXP<12>")
	)
	(segment
		(start 359.621582 -37.748972)
		(end 363.595412 -24.343868)
		(width 0.1143)
		(layer "F.Cu")
		(net "P3E_CPU0_PE2_SS_TXP<12>")
	)
	(segment
		(start 363.595412 -24.343868)
		(end 363.233716 -22.642068)
		(width 0.1143)
		(layer "F.Cu")
		(net "P3E_CPU0_PE2_SS_TXP<12>")
	)
	(segment
		(start 367.35258 -13.805154)
		(end 367.384838 -13.646912)
		(width 0.1143)
		(layer "F.Cu")
		(net "P3E_CPU0_PE2_SS_TXP<12>")
	)
	(segment
		(start 360.275632 -40.461438)
		(end 359.621582 -37.748972)
		(width 0.1143)
		(layer "F.Cu")
		(net "P3E_CPU0_PE2_SS_TXP<12>")
	)
	(segment
		(start 305.712622 -78.097888)
		(end 305.7779 -78.03261)
		(width 0.0889)
		(layer "F.Cu")
		(net "P3E_CPU0_PE2_SS_TXP<12>")
	)
	(segment
		(start 325.683626 -55.852822)
		(end 332.979776 -50.156364)
		(width 0.1143)
		(layer "F.Cu")
		(net "P3E_CPU0_PE2_SS_TXP<12>")
	)
	(segment
		(start 308.51856 -77.287374)
		(end 314.922154 -68.309744)
		(width 0.1143)
		(layer "F.Cu")
		(net "P3E_CPU0_PE2_SS_TXP<12>")
	)
	(segment
		(start 369.801394 -11.540236)
		(end 369.801394 -11.240008)
		(width 0.1143)
		(layer "F.Cu")
		(net "P3E_CPU0_PE2_SS_TXP<12>")
	)
	(segment
		(start 349.973392 -48.768254)
		(end 353.781614 -48.006762)
		(width 0.1143)
		(layer "F.Cu")
		(net "P3E_CPU0_PE2_SS_TXP<12>")
	)
	(segment
		(start 367.829084 -13.489686)
		(end 368.115088 -13.300456)
		(width 0.1143)
		(layer "F.Cu")
		(net "P3E_CPU0_PE2_SS_TXP<12>")
	)
	(segment
		(start 308.255162 -77.701394)
		(end 308.518052 -77.332586)
		(width 0.0889)
		(layer "F.Cu")
		(net "P3E_CPU0_PE2_SS_TXP<12>")
	)
	(segment
		(start 368.591592 -12.984988)
		(end 369.24488 -12.55268)
		(width 0.1143)
		(layer "F.Cu")
		(net "P3E_CPU0_PE2_SS_TXP<12>")
	)
	(segment
		(start 368.115088 -13.300456)
		(end 368.147346 -13.142214)
		(width 0.1143)
		(layer "F.Cu")
		(net "P3E_CPU0_PE2_SS_TXP<12>")
	)
	(segment
		(start 307.194712 -77.996796)
		(end 307.295804 -78.097888)
		(width 0.0889)
		(layer "F.Cu")
		(net "P3E_CPU0_PE2_SS_TXP<12>")
	)
	(segment
		(start 318.649604 -65.724786)
		(end 319.114678 -65.402206)
		(width 0.1143)
		(layer "F.Cu")
		(net "P3E_CPU0_PE2_SS_TXP<12>")
	)
	(segment
		(start 337.395566 -48.711358)
		(end 339.1916 -49.070514)
		(width 0.1143)
		(layer "F.Cu")
		(net "P3E_CPU0_PE2_SS_TXP<12>")
	)
	(via
		(at 318.649604 -65.724786)
		(size 0.508)
		(drill 0.254)
		(layers "F.Cu" "B.Cu")
		(net "P3E_CPU0_PE2_SS_TXP<12>")
	)
	(arc
		(start 304.825908 -78.563724)
		(mid 304.93822 -78.494765)
		(end 305.021996 -78.393036)
		(width 0.0889)
		(layer "F.Cu")
		(net "P3E_CPU0_PE2_SS_TXP<12>")
	)
	(arc
		(start 305.021996 -78.393036)
		(mid 305.232401 -78.180245)
		(end 305.52009 -78.097888)
		(width 0.0889)
		(layer "F.Cu")
		(net "P3E_CPU0_PE2_SS_TXP<12>")
	)
	(segment
		(start 307.366162 -79.36992)
		(end 307.632862 -79.36992)
		(width 0.0889)
		(layer "F.Cu")
		(net "P3E_CPU0_PE2_SS_TXP<11>")
	)
	(segment
		(start 305.515772 -79.278988)
		(end 305.844702 -79.278988)
		(width 0.0889)
		(layer "F.Cu")
		(net "P3E_CPU0_PE2_SS_TXP<11>")
	)
	(segment
		(start 307.904134 -79.278988)
		(end 308.954678 -78.725522)
		(width 0.0889)
		(layer "F.Cu")
		(net "P3E_CPU0_PE2_SS_TXP<11>")
	)
	(segment
		(start 321.351402 -65.335658)
		(end 322.02247 -64.360044)
		(width 0.1143)
		(layer "F.Cu")
		(net "P3E_CPU0_PE2_SS_TXP<11>")
	)
	(segment
		(start 307.723794 -79.278988)
		(end 307.904134 -79.278988)
		(width 0.0889)
		(layer "F.Cu")
		(net "P3E_CPU0_PE2_SS_TXP<11>")
	)
	(segment
		(start 333.20228 -51.785012)
		(end 327.732136 -56.058308)
		(width 0.1143)
		(layer "F.Cu")
		(net "P3E_CPU0_PE2_SS_TXP<11>")
	)
	(segment
		(start 347.5863 -49.53762)
		(end 343.535 -50.34788)
		(width 0.1143)
		(layer "F.Cu")
		(net "P3E_CPU0_PE2_SS_TXP<11>")
	)
	(segment
		(start 343.535 -50.34788)
		(end 341.249 -49.89068)
		(width 0.1143)
		(layer "F.Cu")
		(net "P3E_CPU0_PE2_SS_TXP<11>")
	)
	(segment
		(start 364.878366 -24.394668)
		(end 360.900472 -37.81552)
		(width 0.1143)
		(layer "F.Cu")
		(net "P3E_CPU0_PE2_SS_TXP<11>")
	)
	(segment
		(start 372.442994 -11.643106)
		(end 371.734588 -12.540742)
		(width 0.1143)
		(layer "F.Cu")
		(net "P3E_CPU0_PE2_SS_TXP<11>")
	)
	(segment
		(start 341.249 -49.89068)
		(end 339.166708 -50.306986)
		(width 0.1143)
		(layer "F.Cu")
		(net "P3E_CPU0_PE2_SS_TXP<11>")
	)
	(segment
		(start 364.925864 -17.744948)
		(end 364.487968 -19.809206)
		(width 0.1143)
		(layer "F.Cu")
		(net "P3E_CPU0_PE2_SS_TXP<11>")
	)
	(segment
		(start 364.507018 -22.645878)
		(end 364.878366 -24.394668)
		(width 0.1143)
		(layer "F.Cu")
		(net "P3E_CPU0_PE2_SS_TXP<11>")
	)
	(segment
		(start 309.202328 -78.420722)
		(end 315.779658 -69.198744)
		(width 0.1143)
		(layer "F.Cu")
		(net "P3E_CPU0_PE2_SS_TXP<11>")
	)
	(segment
		(start 306.650898 -79.36992)
		(end 306.917598 -79.36992)
		(width 0.0889)
		(layer "F.Cu")
		(net "P3E_CPU0_PE2_SS_TXP<11>")
	)
	(segment
		(start 371.734588 -12.540742)
		(end 365.471456 -16.685768)
		(width 0.1143)
		(layer "F.Cu")
		(net "P3E_CPU0_PE2_SS_TXP<11>")
	)
	(segment
		(start 306.293266 -79.278988)
		(end 306.559966 -79.278988)
		(width 0.0889)
		(layer "F.Cu")
		(net "P3E_CPU0_PE2_SS_TXP<11>")
	)
	(segment
		(start 308.954678 -78.725522)
		(end 309.154576 -78.444598)
		(width 0.0889)
		(layer "F.Cu")
		(net "P3E_CPU0_PE2_SS_TXP<11>")
	)
	(segment
		(start 307.00853 -79.278988)
		(end 307.27523 -79.278988)
		(width 0.0889)
		(layer "F.Cu")
		(net "P3E_CPU0_PE2_SS_TXP<11>")
	)
	(segment
		(start 309.154576 -78.444598)
		(end 309.202328 -78.420722)
		(width 0.0889)
		(layer "F.Cu")
		(net "P3E_CPU0_PE2_SS_TXP<11>")
	)
	(segment
		(start 365.471456 -16.685768)
		(end 364.925864 -17.744948)
		(width 0.1143)
		(layer "F.Cu")
		(net "P3E_CPU0_PE2_SS_TXP<11>")
	)
	(segment
		(start 337.49361 -49.972722)
		(end 334.101186 -51.082956)
		(width 0.1143)
		(layer "F.Cu")
		(net "P3E_CPU0_PE2_SS_TXP<11>")
	)
	(segment
		(start 306.202334 -79.36992)
		(end 306.293266 -79.278988)
		(width 0.0889)
		(layer "F.Cu")
		(net "P3E_CPU0_PE2_SS_TXP<11>")
	)
	(segment
		(start 364.798864 -21.272754)
		(end 364.507018 -22.645878)
		(width 0.1143)
		(layer "F.Cu")
		(net "P3E_CPU0_PE2_SS_TXP<11>")
	)
	(segment
		(start 349.966534 -50.013616)
		(end 347.5863 -49.53762)
		(width 0.1143)
		(layer "F.Cu")
		(net "P3E_CPU0_PE2_SS_TXP<11>")
	)
	(segment
		(start 305.246532 -79.844646)
		(end 305.159918 -79.821278)
		(width 0.0889)
		(layer "F.Cu")
		(net "P3E_CPU0_PE2_SS_TXP<11>")
	)
	(segment
		(start 361.540044 -40.466772)
		(end 360.647742 -44.829984)
		(width 0.1143)
		(layer "F.Cu")
		(net "P3E_CPU0_PE2_SS_TXP<11>")
	)
	(segment
		(start 305.844702 -79.278988)
		(end 305.935634 -79.36992)
		(width 0.0889)
		(layer "F.Cu")
		(net "P3E_CPU0_PE2_SS_TXP<11>")
	)
	(segment
		(start 307.27523 -79.278988)
		(end 307.366162 -79.36992)
		(width 0.0889)
		(layer "F.Cu")
		(net "P3E_CPU0_PE2_SS_TXP<11>")
	)
	(segment
		(start 315.779658 -69.198744)
		(end 321.351402 -65.335658)
		(width 0.1143)
		(layer "F.Cu")
		(net "P3E_CPU0_PE2_SS_TXP<11>")
	)
	(segment
		(start 305.935634 -79.36992)
		(end 306.202334 -79.36992)
		(width 0.0889)
		(layer "F.Cu")
		(net "P3E_CPU0_PE2_SS_TXP<11>")
	)
	(segment
		(start 307.632862 -79.36992)
		(end 307.723794 -79.278988)
		(width 0.0889)
		(layer "F.Cu")
		(net "P3E_CPU0_PE2_SS_TXP<11>")
	)
	(segment
		(start 305.533806 -79.678784)
		(end 305.246532 -79.844646)
		(width 0.0889)
		(layer "F.Cu")
		(net "P3E_CPU0_PE2_SS_TXP<11>")
	)
	(segment
		(start 306.917598 -79.36992)
		(end 307.00853 -79.278988)
		(width 0.0889)
		(layer "F.Cu")
		(net "P3E_CPU0_PE2_SS_TXP<11>")
	)
	(segment
		(start 334.101186 -51.082956)
		(end 333.20228 -51.785012)
		(width 0.1143)
		(layer "F.Cu")
		(net "P3E_CPU0_PE2_SS_TXP<11>")
	)
	(segment
		(start 360.647742 -44.829984)
		(end 354.245926 -49.15789)
		(width 0.1143)
		(layer "F.Cu")
		(net "P3E_CPU0_PE2_SS_TXP<11>")
	)
	(segment
		(start 306.559966 -79.278988)
		(end 306.650898 -79.36992)
		(width 0.0889)
		(layer "F.Cu")
		(net "P3E_CPU0_PE2_SS_TXP<11>")
	)
	(segment
		(start 372.442994 -11.240008)
		(end 372.442994 -11.643106)
		(width 0.1143)
		(layer "F.Cu")
		(net "P3E_CPU0_PE2_SS_TXP<11>")
	)
	(segment
		(start 372.766844 -10.916158)
		(end 372.442994 -11.240008)
		(width 0.1143)
		(layer "F.Cu")
		(net "P3E_CPU0_PE2_SS_TXP<11>")
	)
	(segment
		(start 360.900472 -37.81552)
		(end 361.540044 -40.466772)
		(width 0.1143)
		(layer "F.Cu")
		(net "P3E_CPU0_PE2_SS_TXP<11>")
	)
	(segment
		(start 364.487968 -19.809206)
		(end 364.798864 -21.272754)
		(width 0.1143)
		(layer "F.Cu")
		(net "P3E_CPU0_PE2_SS_TXP<11>")
	)
	(segment
		(start 327.732136 -56.058308)
		(end 322.02247 -64.360044)
		(width 0.1143)
		(layer "F.Cu")
		(net "P3E_CPU0_PE2_SS_TXP<11>")
	)
	(segment
		(start 339.166708 -50.306986)
		(end 337.49361 -49.972722)
		(width 0.1143)
		(layer "F.Cu")
		(net "P3E_CPU0_PE2_SS_TXP<11>")
	)
	(segment
		(start 354.245926 -49.15789)
		(end 349.966534 -50.013616)
		(width 0.1143)
		(layer "F.Cu")
		(net "P3E_CPU0_PE2_SS_TXP<11>")
	)
	(via
		(at 322.02247 -64.360044)
		(size 0.508)
		(drill 0.254)
		(layers "F.Cu" "B.Cu")
		(net "P3E_CPU0_PE2_SS_TXP<11>")
	)
	(arc
		(start 305.159918 -79.821278)
		(mid 305.199306 -79.459179)
		(end 305.515772 -79.278988)
		(width 0.0889)
		(layer "F.Cu")
		(net "P3E_CPU0_PE2_SS_TXP<11>")
	)
	(segment
		(start 308.356 -79.875634)
		(end 308.3814 -79.850234)
		(width 0.0889)
		(layer "F.Cu")
		(net "P3E_CPU0_PE2_SS_TXP<10>")
	)
	(segment
		(start 354.531676 -49.83988)
		(end 361.306618 -45.26026)
		(width 0.1143)
		(layer "F.Cu")
		(net "P3E_CPU0_PE2_SS_TXP<10>")
	)
	(segment
		(start 347.6244 -50.294794)
		(end 349.941642 -50.758344)
		(width 0.1143)
		(layer "F.Cu")
		(net "P3E_CPU0_PE2_SS_TXP<10>")
	)
	(segment
		(start 304.10404 -80.835246)
		(end 304.203862 -80.808322)
		(width 0.0889)
		(layer "F.Cu")
		(net "P3E_CPU0_PE2_SS_TXP<10>")
	)
	(segment
		(start 373.927116 -11.898884)
		(end 374.085612 -11.931142)
		(width 0.1143)
		(layer "F.Cu")
		(net "P3E_CPU0_PE2_SS_TXP<10>")
	)
	(segment
		(start 343.5731 -51.105054)
		(end 347.6244 -50.294794)
		(width 0.1143)
		(layer "F.Cu")
		(net "P3E_CPU0_PE2_SS_TXP<10>")
	)
	(segment
		(start 373.608854 -12.246356)
		(end 373.641112 -12.088114)
		(width 0.1143)
		(layer "F.Cu")
		(net "P3E_CPU0_PE2_SS_TXP<10>")
	)
	(segment
		(start 321.788282 -65.981834)
		(end 328.106024 -56.795924)
		(width 0.1143)
		(layer "F.Cu")
		(net "P3E_CPU0_PE2_SS_TXP<10>")
	)
	(segment
		(start 305.979576 -79.875634)
		(end 308.356 -79.875634)
		(width 0.0889)
		(layer "F.Cu")
		(net "P3E_CPU0_PE2_SS_TXP<10>")
	)
	(segment
		(start 365.99876 -17.28343)
		(end 372.846346 -12.751054)
		(width 0.1143)
		(layer "F.Cu")
		(net "P3E_CPU0_PE2_SS_TXP<10>")
	)
	(segment
		(start 372.846346 -12.751054)
		(end 372.878604 -12.592558)
		(width 0.1143)
		(layer "F.Cu")
		(net "P3E_CPU0_PE2_SS_TXP<10>")
	)
	(segment
		(start 305.776376 -80.078834)
		(end 305.979576 -79.875634)
		(width 0.0889)
		(layer "F.Cu")
		(net "P3E_CPU0_PE2_SS_TXP<10>")
	)
	(segment
		(start 374.085612 -11.931142)
		(end 374.400826 -11.722354)
		(width 0.1143)
		(layer "F.Cu")
		(net "P3E_CPU0_PE2_SS_TXP<10>")
	)
	(segment
		(start 372.878604 -12.592558)
		(end 373.164608 -12.403328)
		(width 0.1143)
		(layer "F.Cu")
		(net "P3E_CPU0_PE2_SS_TXP<10>")
	)
	(segment
		(start 304.653696 -80.574388)
		(end 304.686462 -80.574388)
		(width 0.0889)
		(layer "F.Cu")
		(net "P3E_CPU0_PE2_SS_TXP<10>")
	)
	(segment
		(start 334.571594 -51.692556)
		(end 337.577684 -50.728626)
		(width 0.1143)
		(layer "F.Cu")
		(net "P3E_CPU0_PE2_SS_TXP<10>")
	)
	(segment
		(start 308.403498 -79.850234)
		(end 308.73319 -79.850234)
		(width 0.1143)
		(layer "F.Cu")
		(net "P3E_CPU0_PE2_SS_TXP<10>")
	)
	(segment
		(start 308.73319 -79.850234)
		(end 311.773824 -76.8096)
		(width 0.1143)
		(layer "F.Cu")
		(net "P3E_CPU0_PE2_SS_TXP<10>")
	)
	(segment
		(start 337.577684 -50.728626)
		(end 339.204554 -51.054254)
		(width 0.1143)
		(layer "F.Cu")
		(net "P3E_CPU0_PE2_SS_TXP<10>")
	)
	(segment
		(start 374.601994 -11.240008)
		(end 374.278144 -10.916158)
		(width 0.1143)
		(layer "F.Cu")
		(net "P3E_CPU0_PE2_SS_TXP<10>")
	)
	(segment
		(start 365.266732 -19.808952)
		(end 365.66602 -17.92859)
		(width 0.1143)
		(layer "F.Cu")
		(net "P3E_CPU0_PE2_SS_TXP<10>")
	)
	(segment
		(start 362.301282 -40.398954)
		(end 361.685078 -37.847778)
		(width 0.1143)
		(layer "F.Cu")
		(net "P3E_CPU0_PE2_SS_TXP<10>")
	)
	(segment
		(start 311.773824 -76.8096)
		(end 316.710314 -70.050152)
		(width 0.1143)
		(layer "F.Cu")
		(net "P3E_CPU0_PE2_SS_TXP<10>")
	)
	(segment
		(start 365.576866 -21.267928)
		(end 365.266732 -19.808952)
		(width 0.1143)
		(layer "F.Cu")
		(net "P3E_CPU0_PE2_SS_TXP<10>")
	)
	(segment
		(start 305.516026 -80.078834)
		(end 305.776376 -80.078834)
		(width 0.0889)
		(layer "F.Cu")
		(net "P3E_CPU0_PE2_SS_TXP<10>")
	)
	(segment
		(start 341.2617 -50.642774)
		(end 343.5731 -51.105054)
		(width 0.1143)
		(layer "F.Cu")
		(net "P3E_CPU0_PE2_SS_TXP<10>")
	)
	(segment
		(start 365.663988 -24.426164)
		(end 365.28502 -22.642322)
		(width 0.1143)
		(layer "F.Cu")
		(net "P3E_CPU0_PE2_SS_TXP<10>")
	)
	(segment
		(start 373.641112 -12.088114)
		(end 373.927116 -11.898884)
		(width 0.1143)
		(layer "F.Cu")
		(net "P3E_CPU0_PE2_SS_TXP<10>")
	)
	(segment
		(start 328.106024 -56.795924)
		(end 328.63028 -56.382158)
		(width 0.1143)
		(layer "F.Cu")
		(net "P3E_CPU0_PE2_SS_TXP<10>")
	)
	(segment
		(start 373.164608 -12.403328)
		(end 373.32285 -12.435586)
		(width 0.1143)
		(layer "F.Cu")
		(net "P3E_CPU0_PE2_SS_TXP<10>")
	)
	(segment
		(start 303.816766 -80.669384)
		(end 304.10404 -80.835246)
		(width 0.0889)
		(layer "F.Cu")
		(net "P3E_CPU0_PE2_SS_TXP<10>")
	)
	(segment
		(start 339.204554 -51.054254)
		(end 341.2617 -50.642774)
		(width 0.1143)
		(layer "F.Cu")
		(net "P3E_CPU0_PE2_SS_TXP<10>")
	)
	(segment
		(start 349.941642 -50.758344)
		(end 354.531676 -49.83988)
		(width 0.1143)
		(layer "F.Cu")
		(net "P3E_CPU0_PE2_SS_TXP<10>")
	)
	(segment
		(start 317.36665 -69.1515)
		(end 321.788282 -65.981834)
		(width 0.1143)
		(layer "F.Cu")
		(net "P3E_CPU0_PE2_SS_TXP<10>")
	)
	(segment
		(start 308.3814 -79.850234)
		(end 308.403498 -79.850234)
		(width 0.0889)
		(layer "F.Cu")
		(net "P3E_CPU0_PE2_SS_TXP<10>")
	)
	(segment
		(start 328.63028 -56.382158)
		(end 334.571594 -51.692556)
		(width 0.1143)
		(layer "F.Cu")
		(net "P3E_CPU0_PE2_SS_TXP<10>")
	)
	(segment
		(start 317.047372 -69.588634)
		(end 317.36665 -69.1515)
		(width 0.1143)
		(layer "F.Cu")
		(net "P3E_CPU0_PE2_SS_TXP<10>")
	)
	(segment
		(start 373.32285 -12.435586)
		(end 373.608854 -12.246356)
		(width 0.1143)
		(layer "F.Cu")
		(net "P3E_CPU0_PE2_SS_TXP<10>")
	)
	(segment
		(start 361.306618 -45.26026)
		(end 362.301282 -40.398954)
		(width 0.1143)
		(layer "F.Cu")
		(net "P3E_CPU0_PE2_SS_TXP<10>")
	)
	(segment
		(start 361.685078 -37.847778)
		(end 365.663988 -24.426164)
		(width 0.1143)
		(layer "F.Cu")
		(net "P3E_CPU0_PE2_SS_TXP<10>")
	)
	(segment
		(start 316.887606 -69.613526)
		(end 317.047372 -69.588634)
		(width 0.1143)
		(layer "F.Cu")
		(net "P3E_CPU0_PE2_SS_TXP<10>")
	)
	(segment
		(start 374.400826 -11.722354)
		(end 374.601994 -11.537188)
		(width 0.1143)
		(layer "F.Cu")
		(net "P3E_CPU0_PE2_SS_TXP<10>")
	)
	(segment
		(start 365.66602 -17.92859)
		(end 365.99876 -17.28343)
		(width 0.1143)
		(layer "F.Cu")
		(net "P3E_CPU0_PE2_SS_TXP<10>")
	)
	(segment
		(start 374.601994 -11.537188)
		(end 374.601994 -11.240008)
		(width 0.1143)
		(layer "F.Cu")
		(net "P3E_CPU0_PE2_SS_TXP<10>")
	)
	(segment
		(start 316.710314 -70.050152)
		(end 316.685422 -69.890386)
		(width 0.1143)
		(layer "F.Cu")
		(net "P3E_CPU0_PE2_SS_TXP<10>")
	)
	(segment
		(start 365.28502 -22.642322)
		(end 365.576866 -21.267928)
		(width 0.1143)
		(layer "F.Cu")
		(net "P3E_CPU0_PE2_SS_TXP<10>")
	)
	(segment
		(start 316.685422 -69.890386)
		(end 316.887606 -69.613526)
		(width 0.1143)
		(layer "F.Cu")
		(net "P3E_CPU0_PE2_SS_TXP<10>")
	)
	(via
		(at 328.63028 -56.382158)
		(size 0.508)
		(drill 0.254)
		(layers "F.Cu" "B.Cu")
		(net "P3E_CPU0_PE2_SS_TXP<10>")
	)
	(arc
		(start 304.203862 -80.808322)
		(mid 304.402417 -80.64067)
		(end 304.653696 -80.574388)
		(width 0.0889)
		(layer "F.Cu")
		(net "P3E_CPU0_PE2_SS_TXP<10>")
	)
	(arc
		(start 304.686462 -80.574388)
		(mid 304.880312 -80.518038)
		(end 305.021996 -80.374236)
		(width 0.0889)
		(layer "F.Cu")
		(net "P3E_CPU0_PE2_SS_TXP<10>")
	)
	(arc
		(start 305.021996 -80.374236)
		(mid 305.230604 -80.162304)
		(end 305.516026 -80.078834)
		(width 0.0889)
		(layer "F.Cu")
		(net "P3E_CPU0_PE2_SS_TXP<10>")
	)
	(segment
		(start 355.528118 -67.521836)
		(end 359.150666 -66.809874)
		(width 0.1143)
		(layer "F.Cu")
		(net "P3E_CPU0_PE2_SS_TXP<0>")
	)
	(segment
		(start 334.2386 -69.905118)
		(end 339.88756 -67.229482)
		(width 0.1143)
		(layer "F.Cu")
		(net "P3E_CPU0_PE2_SS_TXP<0>")
	)
	(segment
		(start 359.150666 -66.809874)
		(end 361.516676 -65.026032)
		(width 0.1143)
		(layer "F.Cu")
		(net "P3E_CPU0_PE2_SS_TXP<0>")
	)
	(segment
		(start 383.098802 -48.37684)
		(end 383.918714 -48.053752)
		(width 0.1143)
		(layer "F.Cu")
		(net "P3E_CPU0_PE2_SS_TXP<0>")
	)
	(segment
		(start 402.894546 -15.10284)
		(end 405.179276 -14.646148)
		(width 0.1143)
		(layer "F.Cu")
		(net "P3E_CPU0_PE2_SS_TXP<0>")
	)
	(segment
		(start 362.449364 -61.450474)
		(end 364.750096 -58.176668)
		(width 0.1143)
		(layer "F.Cu")
		(net "P3E_CPU0_PE2_SS_TXP<0>")
	)
	(segment
		(start 343.903046 -66.377058)
		(end 344.763344 -66.541904)
		(width 0.1143)
		(layer "F.Cu")
		(net "P3E_CPU0_PE2_SS_TXP<0>")
	)
	(segment
		(start 410.273246 -11.781282)
		(end 409.928822 -11.436858)
		(width 0.1143)
		(layer "F.Cu")
		(net "P3E_CPU0_PE2_SS_TXP<0>")
	)
	(segment
		(start 305.062382 -90.219022)
		(end 304.96256 -90.245946)
		(width 0.0889)
		(layer "F.Cu")
		(net "P3E_CPU0_PE2_SS_TXP<0>")
	)
	(segment
		(start 383.918714 -48.053752)
		(end 385.383024 -46.143926)
		(width 0.1143)
		(layer "F.Cu")
		(net "P3E_CPU0_PE2_SS_TXP<0>")
	)
	(segment
		(start 393.692888 -31.412942)
		(end 393.761214 -31.0769)
		(width 0.1143)
		(layer "F.Cu")
		(net "P3E_CPU0_PE2_SS_TXP<0>")
	)
	(segment
		(start 408.97937 -12.120118)
		(end 410.138372 -12.120118)
		(width 0.1143)
		(layer "F.Cu")
		(net "P3E_CPU0_PE2_SS_TXP<0>")
	)
	(segment
		(start 394.159486 -28.543758)
		(end 394.294106 -28.45435)
		(width 0.1143)
		(layer "F.Cu")
		(net "P3E_CPU0_PE2_SS_TXP<0>")
	)
	(segment
		(start 381.456692 -50.929032)
		(end 383.098802 -48.37684)
		(width 0.1143)
		(layer "F.Cu")
		(net "P3E_CPU0_PE2_SS_TXP<0>")
	)
	(segment
		(start 410.138372 -12.120118)
		(end 410.273246 -11.985244)
		(width 0.1143)
		(layer "F.Cu")
		(net "P3E_CPU0_PE2_SS_TXP<0>")
	)
	(segment
		(start 305.548792 -89.984834)
		(end 305.516026 -89.984834)
		(width 0.0889)
		(layer "F.Cu")
		(net "P3E_CPU0_PE2_SS_TXP<0>")
	)
	(segment
		(start 304.96256 -90.245946)
		(end 304.675286 -90.080338)
		(width 0.0889)
		(layer "F.Cu")
		(net "P3E_CPU0_PE2_SS_TXP<0>")
	)
	(segment
		(start 388.153402 -44.310554)
		(end 389.507984 -44.034964)
		(width 0.1143)
		(layer "F.Cu")
		(net "P3E_CPU0_PE2_SS_TXP<0>")
	)
	(segment
		(start 349.642176 -66.5226)
		(end 350.891856 -66.25717)
		(width 0.1143)
		(layer "F.Cu")
		(net "P3E_CPU0_PE2_SS_TXP<0>")
	)
	(segment
		(start 394.180314 -29.01442)
		(end 394.09116 -28.879546)
		(width 0.1143)
		(layer "F.Cu")
		(net "P3E_CPU0_PE2_SS_TXP<0>")
	)
	(segment
		(start 348.423738 -66.263774)
		(end 349.642176 -66.5226)
		(width 0.1143)
		(layer "F.Cu")
		(net "P3E_CPU0_PE2_SS_TXP<0>")
	)
	(segment
		(start 309.742586 -89.959434)
		(end 309.720488 -89.959434)
		(width 0.0889)
		(layer "F.Cu")
		(net "P3E_CPU0_PE2_SS_TXP<0>")
	)
	(segment
		(start 339.88756 -67.229482)
		(end 343.903046 -66.377058)
		(width 0.1143)
		(layer "F.Cu")
		(net "P3E_CPU0_PE2_SS_TXP<0>")
	)
	(segment
		(start 393.67206 -30.942026)
		(end 393.740132 -30.605984)
		(width 0.1143)
		(layer "F.Cu")
		(net "P3E_CPU0_PE2_SS_TXP<0>")
	)
	(segment
		(start 389.507984 -44.034964)
		(end 392.4935 -42.059098)
		(width 0.1143)
		(layer "F.Cu")
		(net "P3E_CPU0_PE2_SS_TXP<0>")
	)
	(segment
		(start 309.695088 -89.984834)
		(end 307.250338 -89.984834)
		(width 0.0889)
		(layer "F.Cu")
		(net "P3E_CPU0_PE2_SS_TXP<0>")
	)
	(segment
		(start 306.410614 -89.489788)
		(end 306.370736 -89.489788)
		(width 0.0889)
		(layer "F.Cu")
		(net "P3E_CPU0_PE2_SS_TXP<0>")
	)
	(segment
		(start 393.025122 -41.254934)
		(end 393.43203 -39.254938)
		(width 0.1143)
		(layer "F.Cu")
		(net "P3E_CPU0_PE2_SS_TXP<0>")
	)
	(segment
		(start 347.181678 -66.52768)
		(end 348.423738 -66.263774)
		(width 0.1143)
		(layer "F.Cu")
		(net "P3E_CPU0_PE2_SS_TXP<0>")
	)
	(segment
		(start 379.99924 -51.359816)
		(end 381.456692 -50.929032)
		(width 0.1143)
		(layer "F.Cu")
		(net "P3E_CPU0_PE2_SS_TXP<0>")
	)
	(segment
		(start 364.750096 -58.176668)
		(end 374.997472 -51.128676)
		(width 0.1143)
		(layer "F.Cu")
		(net "P3E_CPU0_PE2_SS_TXP<0>")
	)
	(segment
		(start 395.9352 -20.472654)
		(end 397.97355 -19.297142)
		(width 0.1143)
		(layer "F.Cu")
		(net "P3E_CPU0_PE2_SS_TXP<0>")
	)
	(segment
		(start 310.284114 -89.959434)
		(end 309.742586 -89.959434)
		(width 0.1143)
		(layer "F.Cu")
		(net "P3E_CPU0_PE2_SS_TXP<0>")
	)
	(segment
		(start 346.005658 -66.277998)
		(end 347.181678 -66.52768)
		(width 0.1143)
		(layer "F.Cu")
		(net "P3E_CPU0_PE2_SS_TXP<0>")
	)
	(segment
		(start 397.97355 -19.297142)
		(end 398.279874 -18.157952)
		(width 0.1143)
		(layer "F.Cu")
		(net "P3E_CPU0_PE2_SS_TXP<0>")
	)
	(segment
		(start 394.204952 -26.823162)
		(end 393.845542 -25.509728)
		(width 0.1143)
		(layer "F.Cu")
		(net "P3E_CPU0_PE2_SS_TXP<0>")
	)
	(segment
		(start 398.279874 -18.157952)
		(end 402.894546 -15.10284)
		(width 0.1143)
		(layer "F.Cu")
		(net "P3E_CPU0_PE2_SS_TXP<0>")
	)
	(segment
		(start 394.124942 -26.963624)
		(end 394.204952 -26.823162)
		(width 0.1143)
		(layer "F.Cu")
		(net "P3E_CPU0_PE2_SS_TXP<0>")
	)
	(segment
		(start 392.921998 -36.746942)
		(end 393.8524 -32.176212)
		(width 0.1143)
		(layer "F.Cu")
		(net "P3E_CPU0_PE2_SS_TXP<0>")
	)
	(segment
		(start 410.273246 -11.985244)
		(end 410.273246 -11.781282)
		(width 0.1143)
		(layer "F.Cu")
		(net "P3E_CPU0_PE2_SS_TXP<0>")
	)
	(segment
		(start 344.763344 -66.541904)
		(end 346.005658 -66.277998)
		(width 0.1143)
		(layer "F.Cu")
		(net "P3E_CPU0_PE2_SS_TXP<0>")
	)
	(segment
		(start 325.289926 -75.954382)
		(end 334.2386 -69.905118)
		(width 0.1143)
		(layer "F.Cu")
		(net "P3E_CPU0_PE2_SS_TXP<0>")
	)
	(segment
		(start 393.875006 -30.51683)
		(end 394.180314 -29.01442)
		(width 0.1143)
		(layer "F.Cu")
		(net "P3E_CPU0_PE2_SS_TXP<0>")
	)
	(segment
		(start 394.446506 -27.70505)
		(end 394.356082 -27.374342)
		(width 0.1143)
		(layer "F.Cu")
		(net "P3E_CPU0_PE2_SS_TXP<0>")
	)
	(segment
		(start 377.286266 -50.586132)
		(end 379.99924 -51.359816)
		(width 0.1143)
		(layer "F.Cu")
		(net "P3E_CPU0_PE2_SS_TXP<0>")
	)
	(segment
		(start 394.294106 -28.45435)
		(end 394.446506 -27.70505)
		(width 0.1143)
		(layer "F.Cu")
		(net "P3E_CPU0_PE2_SS_TXP<0>")
	)
	(segment
		(start 361.516676 -65.026032)
		(end 362.449364 -61.450474)
		(width 0.1143)
		(layer "F.Cu")
		(net "P3E_CPU0_PE2_SS_TXP<0>")
	)
	(segment
		(start 320.099436 -83.542378)
		(end 325.289926 -75.954382)
		(width 0.1143)
		(layer "F.Cu")
		(net "P3E_CPU0_PE2_SS_TXP<0>")
	)
	(segment
		(start 320.099436 -83.542378)
		(end 318.50711 -85.870288)
		(width 0.1143)
		(layer "F.Cu")
		(net "P3E_CPU0_PE2_SS_TXP<0>")
	)
	(segment
		(start 393.740132 -30.605984)
		(end 393.875006 -30.51683)
		(width 0.1143)
		(layer "F.Cu")
		(net "P3E_CPU0_PE2_SS_TXP<0>")
	)
	(segment
		(start 350.891856 -66.25717)
		(end 355.528118 -67.521836)
		(width 0.1143)
		(layer "F.Cu")
		(net "P3E_CPU0_PE2_SS_TXP<0>")
	)
	(segment
		(start 309.720488 -89.959434)
		(end 309.695088 -89.984834)
		(width 0.0889)
		(layer "F.Cu")
		(net "P3E_CPU0_PE2_SS_TXP<0>")
	)
	(segment
		(start 393.43203 -39.254938)
		(end 392.921998 -36.746942)
		(width 0.1143)
		(layer "F.Cu")
		(net "P3E_CPU0_PE2_SS_TXP<0>")
	)
	(segment
		(start 394.356082 -27.374342)
		(end 394.21562 -27.294332)
		(width 0.1143)
		(layer "F.Cu")
		(net "P3E_CPU0_PE2_SS_TXP<0>")
	)
	(segment
		(start 405.179276 -14.646148)
		(end 408.97937 -12.120118)
		(width 0.1143)
		(layer "F.Cu")
		(net "P3E_CPU0_PE2_SS_TXP<0>")
	)
	(segment
		(start 385.383024 -46.143926)
		(end 388.153402 -44.310554)
		(width 0.1143)
		(layer "F.Cu")
		(net "P3E_CPU0_PE2_SS_TXP<0>")
	)
	(segment
		(start 318.50711 -85.870288)
		(end 310.284114 -89.959434)
		(width 0.1143)
		(layer "F.Cu")
		(net "P3E_CPU0_PE2_SS_TXP<0>")
	)
	(segment
		(start 394.876782 -22.146768)
		(end 395.9352 -20.472654)
		(width 0.1143)
		(layer "F.Cu")
		(net "P3E_CPU0_PE2_SS_TXP<0>")
	)
	(segment
		(start 394.21562 -27.294332)
		(end 394.124942 -26.963624)
		(width 0.1143)
		(layer "F.Cu")
		(net "P3E_CPU0_PE2_SS_TXP<0>")
	)
	(segment
		(start 393.761214 -31.0769)
		(end 393.67206 -30.942026)
		(width 0.1143)
		(layer "F.Cu")
		(net "P3E_CPU0_PE2_SS_TXP<0>")
	)
	(segment
		(start 394.09116 -28.879546)
		(end 394.159486 -28.543758)
		(width 0.1143)
		(layer "F.Cu")
		(net "P3E_CPU0_PE2_SS_TXP<0>")
	)
	(segment
		(start 393.8524 -32.176212)
		(end 393.692888 -31.412942)
		(width 0.1143)
		(layer "F.Cu")
		(net "P3E_CPU0_PE2_SS_TXP<0>")
	)
	(segment
		(start 392.4935 -42.059098)
		(end 393.025122 -41.254934)
		(width 0.1143)
		(layer "F.Cu")
		(net "P3E_CPU0_PE2_SS_TXP<0>")
	)
	(segment
		(start 374.997472 -51.128676)
		(end 377.286266 -50.586132)
		(width 0.1143)
		(layer "F.Cu")
		(net "P3E_CPU0_PE2_SS_TXP<0>")
	)
	(segment
		(start 393.845542 -25.509728)
		(end 394.876782 -22.146768)
		(width 0.1143)
		(layer "F.Cu")
		(net "P3E_CPU0_PE2_SS_TXP<0>")
	)
	(via
		(at 320.099436 -83.542378)
		(size 0.508)
		(drill 0.254)
		(layers "F.Cu" "B.Cu")
		(net "P3E_CPU0_PE2_SS_TXP<0>")
	)
	(arc
		(start 306.370736 -89.489788)
		(mid 306.087519 -89.574069)
		(end 305.880516 -89.784936)
		(width 0.0889)
		(layer "F.Cu")
		(net "P3E_CPU0_PE2_SS_TXP<0>")
	)
	(arc
		(start 305.880516 -89.784936)
		(mid 305.740437 -89.927672)
		(end 305.548792 -89.984834)
		(width 0.0889)
		(layer "F.Cu")
		(net "P3E_CPU0_PE2_SS_TXP<0>")
	)
	(arc
		(start 306.904136 -89.784936)
		(mid 306.695717 -89.573223)
		(end 306.410614 -89.489788)
		(width 0.0889)
		(layer "F.Cu")
		(net "P3E_CPU0_PE2_SS_TXP<0>")
	)
	(arc
		(start 305.516026 -89.984834)
		(mid 305.262584 -90.050376)
		(end 305.062382 -90.219022)
		(width 0.0889)
		(layer "F.Cu")
		(net "P3E_CPU0_PE2_SS_TXP<0>")
	)
	(arc
		(start 307.250338 -89.984834)
		(mid 307.050479 -89.931254)
		(end 306.904136 -89.784936)
		(width 0.0889)
		(layer "F.Cu")
		(net "P3E_CPU0_PE2_SS_TXP<0>")
	)
	(segment
		(start 349.876364 -52.013866)
		(end 355.052376 -50.97907)
		(width 0.1143)
		(layer "F.Cu")
		(net "P3E_CPU0_PE2_SS_TXN<9>")
	)
	(segment
		(start 347.58249 -51.555142)
		(end 349.876364 -52.013866)
		(width 0.1143)
		(layer "F.Cu")
		(net "P3E_CPU0_PE2_SS_TXN<9>")
	)
	(segment
		(start 343.5985 -52.35194)
		(end 347.58249 -51.555142)
		(width 0.1143)
		(layer "F.Cu")
		(net "P3E_CPU0_PE2_SS_TXN<9>")
	)
	(segment
		(start 377.169172 -11.547348)
		(end 377.243594 -11.301984)
		(width 0.1143)
		(layer "F.Cu")
		(net "P3E_CPU0_PE2_SS_TXN<9>")
	)
	(segment
		(start 337.659726 -51.977036)
		(end 339.2551 -52.29606)
		(width 0.1143)
		(layer "F.Cu")
		(net "P3E_CPU0_PE2_SS_TXN<9>")
	)
	(segment
		(start 309.199788 -80.7212)
		(end 309.422546 -80.7212)
		(width 0.1143)
		(layer "F.Cu")
		(net "P3E_CPU0_PE2_SS_TXN<9>")
	)
	(segment
		(start 362.972858 -37.933122)
		(end 364.405672 -33.083246)
		(width 0.1143)
		(layer "F.Cu")
		(net "P3E_CPU0_PE2_SS_TXN<9>")
	)
	(segment
		(start 364.405672 -33.083246)
		(end 370.3193 -28.868624)
		(width 0.1143)
		(layer "F.Cu")
		(net "P3E_CPU0_PE2_SS_TXN<9>")
	)
	(segment
		(start 313.9821 -76.350368)
		(end 318.709802 -69.71919)
		(width 0.1143)
		(layer "F.Cu")
		(net "P3E_CPU0_PE2_SS_TXN<9>")
	)
	(segment
		(start 305.821842 -81.202276)
		(end 306.328318 -80.6958)
		(width 0.0889)
		(layer "F.Cu")
		(net "P3E_CPU0_PE2_SS_TXN<9>")
	)
	(segment
		(start 323.98462 -66.061844)
		(end 332.14945 -55.152544)
		(width 0.1143)
		(layer "F.Cu")
		(net "P3E_CPU0_PE2_SS_TXN<9>")
	)
	(segment
		(start 370.966746 -22.173692)
		(end 371.30355 -20.518882)
		(width 0.1143)
		(layer "F.Cu")
		(net "P3E_CPU0_PE2_SS_TXN<9>")
	)
	(segment
		(start 370.3193 -28.868624)
		(end 371.312694 -23.902416)
		(width 0.1143)
		(layer "F.Cu")
		(net "P3E_CPU0_PE2_SS_TXN<9>")
	)
	(segment
		(start 309.422546 -80.7212)
		(end 312.365136 -78.618334)
		(width 0.1143)
		(layer "F.Cu")
		(net "P3E_CPU0_PE2_SS_TXN<9>")
	)
	(segment
		(start 372.248176 -14.802866)
		(end 377.169172 -11.547348)
		(width 0.1143)
		(layer "F.Cu")
		(net "P3E_CPU0_PE2_SS_TXN<9>")
	)
	(segment
		(start 363.611668 -40.578024)
		(end 362.972858 -37.933122)
		(width 0.1143)
		(layer "F.Cu")
		(net "P3E_CPU0_PE2_SS_TXN<9>")
	)
	(segment
		(start 362.522262 -45.935138)
		(end 363.611668 -40.578024)
		(width 0.1143)
		(layer "F.Cu")
		(net "P3E_CPU0_PE2_SS_TXN<9>")
	)
	(segment
		(start 318.709802 -69.71919)
		(end 323.98462 -66.061844)
		(width 0.1143)
		(layer "F.Cu")
		(net "P3E_CPU0_PE2_SS_TXN<9>")
	)
	(segment
		(start 355.052376 -50.97907)
		(end 362.522262 -45.935138)
		(width 0.1143)
		(layer "F.Cu")
		(net "P3E_CPU0_PE2_SS_TXN<9>")
	)
	(segment
		(start 341.2871 -51.88966)
		(end 343.5985 -52.35194)
		(width 0.1143)
		(layer "F.Cu")
		(net "P3E_CPU0_PE2_SS_TXN<9>")
	)
	(segment
		(start 309.174388 -80.6958)
		(end 309.199788 -80.7212)
		(width 0.0889)
		(layer "F.Cu")
		(net "P3E_CPU0_PE2_SS_TXN<9>")
	)
	(segment
		(start 377.243594 -11.301984)
		(end 377.243594 -11.240008)
		(width 0.1143)
		(layer "F.Cu")
		(net "P3E_CPU0_PE2_SS_TXN<9>")
	)
	(segment
		(start 371.30355 -20.518882)
		(end 370.837206 -18.17624)
		(width 0.1143)
		(layer "F.Cu")
		(net "P3E_CPU0_PE2_SS_TXN<9>")
	)
	(segment
		(start 370.837206 -18.17624)
		(end 372.248176 -14.802866)
		(width 0.1143)
		(layer "F.Cu")
		(net "P3E_CPU0_PE2_SS_TXN<9>")
	)
	(segment
		(start 332.14945 -55.152544)
		(end 335.177384 -52.788566)
		(width 0.1143)
		(layer "F.Cu")
		(net "P3E_CPU0_PE2_SS_TXN<9>")
	)
	(segment
		(start 312.365136 -78.618334)
		(end 313.9821 -76.350368)
		(width 0.1143)
		(layer "F.Cu")
		(net "P3E_CPU0_PE2_SS_TXN<9>")
	)
	(segment
		(start 306.328318 -80.6958)
		(end 309.174388 -80.6958)
		(width 0.0889)
		(layer "F.Cu")
		(net "P3E_CPU0_PE2_SS_TXN<9>")
	)
	(segment
		(start 377.243594 -11.240008)
		(end 377.567444 -10.916158)
		(width 0.1143)
		(layer "F.Cu")
		(net "P3E_CPU0_PE2_SS_TXN<9>")
	)
	(segment
		(start 335.177384 -52.788566)
		(end 337.659726 -51.977036)
		(width 0.1143)
		(layer "F.Cu")
		(net "P3E_CPU0_PE2_SS_TXN<9>")
	)
	(segment
		(start 305.533806 -81.659984)
		(end 305.821842 -81.202276)
		(width 0.0889)
		(layer "F.Cu")
		(net "P3E_CPU0_PE2_SS_TXN<9>")
	)
	(segment
		(start 371.312694 -23.902416)
		(end 370.966746 -22.173692)
		(width 0.1143)
		(layer "F.Cu")
		(net "P3E_CPU0_PE2_SS_TXN<9>")
	)
	(segment
		(start 339.2551 -52.29606)
		(end 341.2871 -51.88966)
		(width 0.1143)
		(layer "F.Cu")
		(net "P3E_CPU0_PE2_SS_TXN<9>")
	)
	(via
		(at 313.9821 -76.350368)
		(size 0.508)
		(drill 0.254)
		(layers "F.Cu" "B.Cu")
		(net "P3E_CPU0_PE2_SS_TXN<9>")
	)
	(segment
		(start 307.090826 -81.844134)
		(end 307.179726 -81.755234)
		(width 0.0889)
		(layer "F.Cu")
		(net "P3E_CPU0_PE2_SS_TXN<8>")
	)
	(segment
		(start 307.535326 -81.844134)
		(end 307.802026 -81.844134)
		(width 0.0889)
		(layer "F.Cu")
		(net "P3E_CPU0_PE2_SS_TXN<8>")
	)
	(segment
		(start 332.5368 -56.263794)
		(end 334.79359 -54.45125)
		(width 0.1143)
		(layer "F.Cu")
		(net "P3E_CPU0_PE2_SS_TXN<8>")
	)
	(segment
		(start 312.583322 -80.161638)
		(end 312.583322 -80.161384)
		(width 0.1143)
		(layer "F.Cu")
		(net "P3E_CPU0_PE2_SS_TXN<8>")
	)
	(segment
		(start 372.333266 -23.849076)
		(end 371.042692 -30.296612)
		(width 0.1143)
		(layer "F.Cu")
		(net "P3E_CPU0_PE2_SS_TXN<8>")
	)
	(segment
		(start 308.894226 -81.780634)
		(end 308.916324 -81.780634)
		(width 0.0889)
		(layer "F.Cu")
		(net "P3E_CPU0_PE2_SS_TXN<8>")
	)
	(segment
		(start 308.513226 -81.844134)
		(end 308.602126 -81.755234)
		(width 0.0889)
		(layer "F.Cu")
		(net "P3E_CPU0_PE2_SS_TXN<8>")
	)
	(segment
		(start 334.79359 -54.45125)
		(end 336.151474 -54.007004)
		(width 0.1143)
		(layer "F.Cu")
		(net "P3E_CPU0_PE2_SS_TXN<8>")
	)
	(segment
		(start 344.742516 -54.582314)
		(end 345.504262 -54.425596)
		(width 0.1143)
		(layer "F.Cu")
		(net "P3E_CPU0_PE2_SS_TXN<8>")
	)
	(segment
		(start 338.276946 -54.00548)
		(end 340.308946 -54.41188)
		(width 0.1143)
		(layer "F.Cu")
		(net "P3E_CPU0_PE2_SS_TXN<8>")
	)
	(segment
		(start 308.602126 -81.755234)
		(end 308.868826 -81.755234)
		(width 0.0889)
		(layer "F.Cu")
		(net "P3E_CPU0_PE2_SS_TXN<8>")
	)
	(segment
		(start 308.157626 -81.755234)
		(end 308.246526 -81.844134)
		(width 0.0889)
		(layer "F.Cu")
		(net "P3E_CPU0_PE2_SS_TXN<8>")
	)
	(segment
		(start 379.815344 -10.941558)
		(end 379.4887 -11.268202)
		(width 0.1143)
		(layer "F.Cu")
		(net "P3E_CPU0_PE2_SS_TXN<8>")
	)
	(segment
		(start 372.309136 -20.431252)
		(end 371.976396 -22.065488)
		(width 0.1143)
		(layer "F.Cu")
		(net "P3E_CPU0_PE2_SS_TXN<8>")
	)
	(segment
		(start 379.4887 -11.268202)
		(end 379.4887 -11.665712)
		(width 0.1143)
		(layer "F.Cu")
		(net "P3E_CPU0_PE2_SS_TXN<8>")
	)
	(segment
		(start 337.209892 -54.21884)
		(end 338.276946 -54.00548)
		(width 0.1143)
		(layer "F.Cu")
		(net "P3E_CPU0_PE2_SS_TXN<8>")
	)
	(segment
		(start 379.4887 -11.665712)
		(end 378.49175 -12.43838)
		(width 0.1143)
		(layer "F.Cu")
		(net "P3E_CPU0_PE2_SS_TXN<8>")
	)
	(segment
		(start 340.308946 -54.41188)
		(end 342.0999 -54.05374)
		(width 0.1143)
		(layer "F.Cu")
		(net "P3E_CPU0_PE2_SS_TXN<8>")
	)
	(segment
		(start 371.95633 -18.659602)
		(end 372.309136 -20.431252)
		(width 0.1143)
		(layer "F.Cu")
		(net "P3E_CPU0_PE2_SS_TXN<8>")
	)
	(segment
		(start 365.035338 -34.580068)
		(end 364.028736 -37.974016)
		(width 0.1143)
		(layer "F.Cu")
		(net "P3E_CPU0_PE2_SS_TXN<8>")
	)
	(segment
		(start 306.392072 -81.755234)
		(end 306.735226 -81.755234)
		(width 0.0889)
		(layer "F.Cu")
		(net "P3E_CPU0_PE2_SS_TXN<8>")
	)
	(segment
		(start 324.40753 -67.114166)
		(end 332.5368 -56.263794)
		(width 0.1143)
		(layer "F.Cu")
		(net "P3E_CPU0_PE2_SS_TXN<8>")
	)
	(segment
		(start 306.105052 -82.320892)
		(end 305.973988 -82.180938)
		(width 0.0889)
		(layer "F.Cu")
		(net "P3E_CPU0_PE2_SS_TXN<8>")
	)
	(segment
		(start 378.49175 -12.43838)
		(end 377.23191 -12.708636)
		(width 0.1143)
		(layer "F.Cu")
		(net "P3E_CPU0_PE2_SS_TXN<8>")
	)
	(segment
		(start 308.868826 -81.755234)
		(end 308.894226 -81.780634)
		(width 0.0889)
		(layer "F.Cu")
		(net "P3E_CPU0_PE2_SS_TXN<8>")
	)
	(segment
		(start 307.446426 -81.755234)
		(end 307.535326 -81.844134)
		(width 0.0889)
		(layer "F.Cu")
		(net "P3E_CPU0_PE2_SS_TXN<8>")
	)
	(segment
		(start 308.916324 -81.780634)
		(end 309.438802 -81.780634)
		(width 0.1143)
		(layer "F.Cu")
		(net "P3E_CPU0_PE2_SS_TXN<8>")
	)
	(segment
		(start 371.042692 -30.296612)
		(end 365.035338 -34.580068)
		(width 0.1143)
		(layer "F.Cu")
		(net "P3E_CPU0_PE2_SS_TXN<8>")
	)
	(segment
		(start 363.392466 -46.515782)
		(end 354.41763 -52.593494)
		(width 0.1143)
		(layer "F.Cu")
		(net "P3E_CPU0_PE2_SS_TXN<8>")
	)
	(segment
		(start 309.438802 -81.780634)
		(end 312.583322 -80.161638)
		(width 0.1143)
		(layer "F.Cu")
		(net "P3E_CPU0_PE2_SS_TXN<8>")
	)
	(segment
		(start 364.028736 -37.974016)
		(end 364.626652 -40.449754)
		(width 0.1143)
		(layer "F.Cu")
		(net "P3E_CPU0_PE2_SS_TXN<8>")
	)
	(segment
		(start 305.975258 -82.113882)
		(end 306.024026 -81.99882)
		(width 0.0889)
		(layer "F.Cu")
		(net "P3E_CPU0_PE2_SS_TXN<8>")
	)
	(segment
		(start 342.0999 -54.05374)
		(end 344.742516 -54.582314)
		(width 0.1143)
		(layer "F.Cu")
		(net "P3E_CPU0_PE2_SS_TXN<8>")
	)
	(segment
		(start 308.246526 -81.844134)
		(end 308.513226 -81.844134)
		(width 0.0889)
		(layer "F.Cu")
		(net "P3E_CPU0_PE2_SS_TXN<8>")
	)
	(segment
		(start 364.626652 -40.449754)
		(end 363.392466 -46.515782)
		(width 0.1143)
		(layer "F.Cu")
		(net "P3E_CPU0_PE2_SS_TXN<8>")
	)
	(segment
		(start 307.890926 -81.755234)
		(end 308.157626 -81.755234)
		(width 0.0889)
		(layer "F.Cu")
		(net "P3E_CPU0_PE2_SS_TXN<8>")
	)
	(segment
		(start 307.802026 -81.844134)
		(end 307.890926 -81.755234)
		(width 0.0889)
		(layer "F.Cu")
		(net "P3E_CPU0_PE2_SS_TXN<8>")
	)
	(segment
		(start 377.23191 -12.708636)
		(end 373.379238 -15.257272)
		(width 0.1143)
		(layer "F.Cu")
		(net "P3E_CPU0_PE2_SS_TXN<8>")
	)
	(segment
		(start 371.976396 -22.065488)
		(end 372.333266 -23.849076)
		(width 0.1143)
		(layer "F.Cu")
		(net "P3E_CPU0_PE2_SS_TXN<8>")
	)
	(segment
		(start 319.421764 -70.571106)
		(end 324.40753 -67.114166)
		(width 0.1143)
		(layer "F.Cu")
		(net "P3E_CPU0_PE2_SS_TXN<8>")
	)
	(segment
		(start 306.735226 -81.755234)
		(end 306.824126 -81.844134)
		(width 0.0889)
		(layer "F.Cu")
		(net "P3E_CPU0_PE2_SS_TXN<8>")
	)
	(segment
		(start 306.392326 -82.155284)
		(end 306.105052 -82.320892)
		(width 0.0889)
		(layer "F.Cu")
		(net "P3E_CPU0_PE2_SS_TXN<8>")
	)
	(segment
		(start 373.379238 -15.257272)
		(end 371.95633 -18.659602)
		(width 0.1143)
		(layer "F.Cu")
		(net "P3E_CPU0_PE2_SS_TXN<8>")
	)
	(segment
		(start 312.583322 -80.161384)
		(end 319.421764 -70.571106)
		(width 0.1143)
		(layer "F.Cu")
		(net "P3E_CPU0_PE2_SS_TXN<8>")
	)
	(segment
		(start 336.151474 -54.007004)
		(end 337.209892 -54.21884)
		(width 0.1143)
		(layer "F.Cu")
		(net "P3E_CPU0_PE2_SS_TXN<8>")
	)
	(segment
		(start 307.179726 -81.755234)
		(end 307.446426 -81.755234)
		(width 0.0889)
		(layer "F.Cu")
		(net "P3E_CPU0_PE2_SS_TXN<8>")
	)
	(segment
		(start 354.41763 -52.593494)
		(end 345.504262 -54.425596)
		(width 0.1143)
		(layer "F.Cu")
		(net "P3E_CPU0_PE2_SS_TXN<8>")
	)
	(segment
		(start 306.824126 -81.844134)
		(end 307.090826 -81.844134)
		(width 0.0889)
		(layer "F.Cu")
		(net "P3E_CPU0_PE2_SS_TXN<8>")
	)
	(via
		(at 345.504262 -54.425596)
		(size 0.508)
		(drill 0.254)
		(layers "F.Cu" "B.Cu")
		(net "P3E_CPU0_PE2_SS_TXN<8>")
	)
	(arc
		(start 306.024026 -81.99882)
		(mid 306.171388 -81.821626)
		(end 306.392072 -81.755234)
		(width 0.0889)
		(layer "F.Cu")
		(net "P3E_CPU0_PE2_SS_TXN<8>")
	)
	(arc
		(start 305.973988 -82.180938)
		(mid 305.968118 -82.147283)
		(end 305.975258 -82.113882)
		(width 0.0889)
		(layer "F.Cu")
		(net "P3E_CPU0_PE2_SS_TXN<8>")
	)
	(segment
		(start 325.013828 -67.975988)
		(end 320.494914 -71.109586)
		(width 0.1143)
		(layer "F.Cu")
		(net "P3E_CPU0_PE2_SS_TXN<7>")
	)
	(segment
		(start 337.13801 -56.080406)
		(end 332.883256 -57.47258)
		(width 0.1143)
		(layer "F.Cu")
		(net "P3E_CPU0_PE2_SS_TXN<7>")
	)
	(segment
		(start 338.319618 -56.33085)
		(end 337.13801 -56.080406)
		(width 0.1143)
		(layer "F.Cu")
		(net "P3E_CPU0_PE2_SS_TXN<7>")
	)
	(segment
		(start 372.17604 -30.129734)
		(end 370.936266 -34.072576)
		(width 0.1143)
		(layer "F.Cu")
		(net "P3E_CPU0_PE2_SS_TXN<7>")
	)
	(segment
		(start 305.555904 -83.241134)
		(end 305.52263 -83.241134)
		(width 0.0889)
		(layer "F.Cu")
		(net "P3E_CPU0_PE2_SS_TXN<7>")
	)
	(segment
		(start 370.529104 -38.270688)
		(end 370.09959 -40.416988)
		(width 0.1143)
		(layer "F.Cu")
		(net "P3E_CPU0_PE2_SS_TXN<7>")
	)
	(segment
		(start 313.655202 -80.702404)
		(end 309.63997 -82.771234)
		(width 0.1143)
		(layer "F.Cu")
		(net "P3E_CPU0_PE2_SS_TXN<7>")
	)
	(segment
		(start 351.83572 -55.510176)
		(end 347.936312 -56.319928)
		(width 0.1143)
		(layer "F.Cu")
		(net "P3E_CPU0_PE2_SS_TXN<7>")
	)
	(segment
		(start 318.641222 -73.70953)
		(end 313.655202 -80.702404)
		(width 0.1143)
		(layer "F.Cu")
		(net "P3E_CPU0_PE2_SS_TXN<7>")
	)
	(segment
		(start 305.223418 -83.388962)
		(end 305.246532 -83.475576)
		(width 0.0889)
		(layer "F.Cu")
		(net "P3E_CPU0_PE2_SS_TXN<7>")
	)
	(segment
		(start 347.936312 -56.319928)
		(end 342.297258 -55.194454)
		(width 0.1143)
		(layer "F.Cu")
		(net "P3E_CPU0_PE2_SS_TXN<7>")
	)
	(segment
		(start 370.09959 -40.416988)
		(end 370.450364 -42.378884)
		(width 0.1143)
		(layer "F.Cu")
		(net "P3E_CPU0_PE2_SS_TXN<7>")
	)
	(segment
		(start 309.63997 -82.771234)
		(end 308.143656 -82.771234)
		(width 0.1143)
		(layer "F.Cu")
		(net "P3E_CPU0_PE2_SS_TXN<7>")
	)
	(segment
		(start 307.103272 -82.745834)
		(end 307.014372 -82.834734)
		(width 0.0889)
		(layer "F.Cu")
		(net "P3E_CPU0_PE2_SS_TXN<7>")
	)
	(segment
		(start 370.312696 -37.189156)
		(end 370.31295 -37.189156)
		(width 0.1143)
		(layer "F.Cu")
		(net "P3E_CPU0_PE2_SS_TXN<7>")
	)
	(segment
		(start 307.458872 -82.834734)
		(end 307.369972 -82.745834)
		(width 0.0889)
		(layer "F.Cu")
		(net "P3E_CPU0_PE2_SS_TXN<7>")
	)
	(segment
		(start 370.936266 -34.072576)
		(end 370.312696 -37.189156)
		(width 0.1143)
		(layer "F.Cu")
		(net "P3E_CPU0_PE2_SS_TXN<7>")
	)
	(segment
		(start 307.014372 -82.834734)
		(end 306.747672 -82.834734)
		(width 0.0889)
		(layer "F.Cu")
		(net "P3E_CPU0_PE2_SS_TXN<7>")
	)
	(segment
		(start 308.143656 -82.771234)
		(end 308.118256 -82.745834)
		(width 0.0889)
		(layer "F.Cu")
		(net "P3E_CPU0_PE2_SS_TXN<7>")
	)
	(segment
		(start 370.31295 -37.189156)
		(end 370.529104 -38.270688)
		(width 0.1143)
		(layer "F.Cu")
		(net "P3E_CPU0_PE2_SS_TXN<7>")
	)
	(segment
		(start 368.33556 -46.288706)
		(end 364.243874 -47.106332)
		(width 0.1143)
		(layer "F.Cu")
		(net "P3E_CPU0_PE2_SS_TXN<7>")
	)
	(segment
		(start 393.551156 -11.72337)
		(end 375.547382 -15.1003)
		(width 0.1143)
		(layer "F.Cu")
		(net "P3E_CPU0_PE2_SS_TXN<7>")
	)
	(segment
		(start 307.369972 -82.745834)
		(end 307.103272 -82.745834)
		(width 0.0889)
		(layer "F.Cu")
		(net "P3E_CPU0_PE2_SS_TXN<7>")
	)
	(segment
		(start 352.496374 -55.073296)
		(end 351.83572 -55.510176)
		(width 0.1143)
		(layer "F.Cu")
		(net "P3E_CPU0_PE2_SS_TXN<7>")
	)
	(segment
		(start 375.547382 -15.1003)
		(end 374.14327 -16.030448)
		(width 0.1143)
		(layer "F.Cu")
		(net "P3E_CPU0_PE2_SS_TXN<7>")
	)
	(segment
		(start 393.820142 -11.399266)
		(end 393.551156 -11.72337)
		(width 0.1143)
		(layer "F.Cu")
		(net "P3E_CPU0_PE2_SS_TXN<7>")
	)
	(segment
		(start 308.118256 -82.745834)
		(end 307.814472 -82.745834)
		(width 0.0889)
		(layer "F.Cu")
		(net "P3E_CPU0_PE2_SS_TXN<7>")
	)
	(segment
		(start 373.32539 -20.396962)
		(end 372.988332 -22.050502)
		(width 0.1143)
		(layer "F.Cu")
		(net "P3E_CPU0_PE2_SS_TXN<7>")
	)
	(segment
		(start 372.988332 -22.050502)
		(end 373.389652 -24.05634)
		(width 0.1143)
		(layer "F.Cu")
		(net "P3E_CPU0_PE2_SS_TXN<7>")
	)
	(segment
		(start 342.297258 -55.194454)
		(end 338.319618 -56.33085)
		(width 0.1143)
		(layer "F.Cu")
		(net "P3E_CPU0_PE2_SS_TXN<7>")
	)
	(segment
		(start 306.658772 -82.745834)
		(end 306.392072 -82.745834)
		(width 0.0889)
		(layer "F.Cu")
		(net "P3E_CPU0_PE2_SS_TXN<7>")
	)
	(segment
		(start 363.113574 -47.872142)
		(end 360.792014 -51.354482)
		(width 0.1143)
		(layer "F.Cu")
		(net "P3E_CPU0_PE2_SS_TXN<7>")
	)
	(segment
		(start 393.820142 -11.241786)
		(end 393.820142 -11.399266)
		(width 0.1143)
		(layer "F.Cu")
		(net "P3E_CPU0_PE2_SS_TXN<7>")
	)
	(segment
		(start 307.814472 -82.745834)
		(end 307.725572 -82.834734)
		(width 0.0889)
		(layer "F.Cu")
		(net "P3E_CPU0_PE2_SS_TXN<7>")
	)
	(segment
		(start 360.792014 -51.354482)
		(end 358.195372 -53.110892)
		(width 0.1143)
		(layer "F.Cu")
		(net "P3E_CPU0_PE2_SS_TXN<7>")
	)
	(segment
		(start 306.747672 -82.834734)
		(end 306.658772 -82.745834)
		(width 0.0889)
		(layer "F.Cu")
		(net "P3E_CPU0_PE2_SS_TXN<7>")
	)
	(segment
		(start 305.246532 -83.475576)
		(end 305.533806 -83.641184)
		(width 0.0889)
		(layer "F.Cu")
		(net "P3E_CPU0_PE2_SS_TXN<7>")
	)
	(segment
		(start 364.243874 -47.106332)
		(end 363.113574 -47.872142)
		(width 0.1143)
		(layer "F.Cu")
		(net "P3E_CPU0_PE2_SS_TXN<7>")
	)
	(segment
		(start 320.494914 -71.109586)
		(end 318.641222 -73.70953)
		(width 0.1143)
		(layer "F.Cu")
		(net "P3E_CPU0_PE2_SS_TXN<7>")
	)
	(segment
		(start 394.143992 -10.917936)
		(end 393.820142 -11.241786)
		(width 0.1143)
		(layer "F.Cu")
		(net "P3E_CPU0_PE2_SS_TXN<7>")
	)
	(segment
		(start 358.195372 -53.110892)
		(end 352.496374 -55.073296)
		(width 0.1143)
		(layer "F.Cu")
		(net "P3E_CPU0_PE2_SS_TXN<7>")
	)
	(segment
		(start 332.883256 -57.47258)
		(end 325.013828 -67.975988)
		(width 0.1143)
		(layer "F.Cu")
		(net "P3E_CPU0_PE2_SS_TXN<7>")
	)
	(segment
		(start 373.389652 -24.05634)
		(end 372.17604 -30.129734)
		(width 0.1143)
		(layer "F.Cu")
		(net "P3E_CPU0_PE2_SS_TXN<7>")
	)
	(segment
		(start 373.00027 -18.763996)
		(end 373.32539 -20.396962)
		(width 0.1143)
		(layer "F.Cu")
		(net "P3E_CPU0_PE2_SS_TXN<7>")
	)
	(segment
		(start 370.450364 -42.378884)
		(end 369.375436 -45.584618)
		(width 0.1143)
		(layer "F.Cu")
		(net "P3E_CPU0_PE2_SS_TXN<7>")
	)
	(segment
		(start 374.14327 -16.030448)
		(end 373.00027 -18.763996)
		(width 0.1143)
		(layer "F.Cu")
		(net "P3E_CPU0_PE2_SS_TXN<7>")
	)
	(segment
		(start 307.725572 -82.834734)
		(end 307.458872 -82.834734)
		(width 0.0889)
		(layer "F.Cu")
		(net "P3E_CPU0_PE2_SS_TXN<7>")
	)
	(segment
		(start 369.375436 -45.584618)
		(end 368.33556 -46.288706)
		(width 0.1143)
		(layer "F.Cu")
		(net "P3E_CPU0_PE2_SS_TXN<7>")
	)
	(via
		(at 318.641222 -73.70953)
		(size 0.508)
		(drill 0.254)
		(layers "F.Cu" "B.Cu")
		(net "P3E_CPU0_PE2_SS_TXN<7>")
	)
	(arc
		(start 306.045616 -82.945986)
		(mid 305.838829 -83.156719)
		(end 305.555904 -83.241134)
		(width 0.0889)
		(layer "F.Cu")
		(net "P3E_CPU0_PE2_SS_TXN<7>")
	)
	(arc
		(start 305.52263 -83.241134)
		(mid 305.356856 -83.28234)
		(end 305.223418 -83.388962)
		(width 0.0889)
		(layer "F.Cu")
		(net "P3E_CPU0_PE2_SS_TXN<7>")
	)
	(arc
		(start 306.392072 -82.745834)
		(mid 306.191999 -82.799458)
		(end 306.045616 -82.945986)
		(width 0.0889)
		(layer "F.Cu")
		(net "P3E_CPU0_PE2_SS_TXN<7>")
	)
	(segment
		(start 348.796102 -57.483502)
		(end 342.395302 -56.204866)
		(width 0.1143)
		(layer "F.Cu")
		(net "P3E_CPU0_PE2_SS_TXN<6>")
	)
	(segment
		(start 396.144242 -11.292586)
		(end 396.144242 -11.618468)
		(width 0.1143)
		(layer "F.Cu")
		(net "P3E_CPU0_PE2_SS_TXN<6>")
	)
	(segment
		(start 342.395302 -56.204866)
		(end 338.378038 -57.352692)
		(width 0.1143)
		(layer "F.Cu")
		(net "P3E_CPU0_PE2_SS_TXN<6>")
	)
	(segment
		(start 363.558582 -50.713132)
		(end 355.741986 -56.006238)
		(width 0.1143)
		(layer "F.Cu")
		(net "P3E_CPU0_PE2_SS_TXN<6>")
	)
	(segment
		(start 374.367298 -20.493228)
		(end 374.045988 -22.101302)
		(width 0.1143)
		(layer "F.Cu")
		(net "P3E_CPU0_PE2_SS_TXN<6>")
	)
	(segment
		(start 371.548406 -38.379654)
		(end 371.166644 -40.287956)
		(width 0.1143)
		(layer "F.Cu")
		(net "P3E_CPU0_PE2_SS_TXN<6>")
	)
	(segment
		(start 371.527578 -42.305478)
		(end 370.229892 -46.173136)
		(width 0.1143)
		(layer "F.Cu")
		(net "P3E_CPU0_PE2_SS_TXN<6>")
	)
	(segment
		(start 374.045988 -22.101302)
		(end 374.408446 -23.9141)
		(width 0.1143)
		(layer "F.Cu")
		(net "P3E_CPU0_PE2_SS_TXN<6>")
	)
	(segment
		(start 374.937782 -16.731742)
		(end 374.04421 -18.868644)
		(width 0.1143)
		(layer "F.Cu")
		(net "P3E_CPU0_PE2_SS_TXN<6>")
	)
	(segment
		(start 338.378038 -57.352692)
		(end 337.17357 -57.097422)
		(width 0.1143)
		(layer "F.Cu")
		(net "P3E_CPU0_PE2_SS_TXN<6>")
	)
	(segment
		(start 371.339618 -37.336222)
		(end 371.548406 -38.379654)
		(width 0.1143)
		(layer "F.Cu")
		(net "P3E_CPU0_PE2_SS_TXN<6>")
	)
	(segment
		(start 333.59344 -58.26887)
		(end 328.07148 -65.635378)
		(width 0.1143)
		(layer "F.Cu")
		(net "P3E_CPU0_PE2_SS_TXN<6>")
	)
	(segment
		(start 318.506856 -75.564492)
		(end 314.307728 -81.45399)
		(width 0.1143)
		(layer "F.Cu")
		(net "P3E_CPU0_PE2_SS_TXN<6>")
	)
	(segment
		(start 321.151504 -71.855076)
		(end 318.506856 -75.564492)
		(width 0.1143)
		(layer "F.Cu")
		(net "P3E_CPU0_PE2_SS_TXN<6>")
	)
	(segment
		(start 396.144242 -11.618468)
		(end 395.54531 -12.34313)
		(width 0.1143)
		(layer "F.Cu")
		(net "P3E_CPU0_PE2_SS_TXN<6>")
	)
	(segment
		(start 337.17357 -57.097422)
		(end 333.59344 -58.26887)
		(width 0.1143)
		(layer "F.Cu")
		(net "P3E_CPU0_PE2_SS_TXN<6>")
	)
	(segment
		(start 371.166644 -40.287956)
		(end 371.527578 -42.305478)
		(width 0.1143)
		(layer "F.Cu")
		(net "P3E_CPU0_PE2_SS_TXN<6>")
	)
	(segment
		(start 364.991904 -48.563276)
		(end 363.558582 -50.713132)
		(width 0.1143)
		(layer "F.Cu")
		(net "P3E_CPU0_PE2_SS_TXN<6>")
	)
	(segment
		(start 375.983754 -16.039084)
		(end 374.937782 -16.731742)
		(width 0.1143)
		(layer "F.Cu")
		(net "P3E_CPU0_PE2_SS_TXN<6>")
	)
	(segment
		(start 326.321674 -68.270628)
		(end 321.151504 -71.855076)
		(width 0.1143)
		(layer "F.Cu")
		(net "P3E_CPU0_PE2_SS_TXN<6>")
	)
	(segment
		(start 355.741986 -56.006238)
		(end 348.796102 -57.483502)
		(width 0.1143)
		(layer "F.Cu")
		(net "P3E_CPU0_PE2_SS_TXN<6>")
	)
	(segment
		(start 370.229892 -46.173136)
		(end 368.71275 -47.200312)
		(width 0.1143)
		(layer "F.Cu")
		(net "P3E_CPU0_PE2_SS_TXN<6>")
	)
	(segment
		(start 314.307728 -81.45399)
		(end 309.83809 -83.7565)
		(width 0.1143)
		(layer "F.Cu")
		(net "P3E_CPU0_PE2_SS_TXN<6>")
	)
	(segment
		(start 328.07148 -65.635378)
		(end 326.321674 -68.270628)
		(width 0.1143)
		(layer "F.Cu")
		(net "P3E_CPU0_PE2_SS_TXN<6>")
	)
	(segment
		(start 396.468092 -10.968736)
		(end 396.144242 -11.292586)
		(width 0.1143)
		(layer "F.Cu")
		(net "P3E_CPU0_PE2_SS_TXN<6>")
	)
	(segment
		(start 374.408446 -23.9141)
		(end 373.098314 -30.466284)
		(width 0.1143)
		(layer "F.Cu")
		(net "P3E_CPU0_PE2_SS_TXN<6>")
	)
	(segment
		(start 366.318038 -47.679102)
		(end 364.991904 -48.563276)
		(width 0.1143)
		(layer "F.Cu")
		(net "P3E_CPU0_PE2_SS_TXN<6>")
	)
	(segment
		(start 368.71275 -47.200312)
		(end 366.318038 -47.679102)
		(width 0.1143)
		(layer "F.Cu")
		(net "P3E_CPU0_PE2_SS_TXN<6>")
	)
	(segment
		(start 372.04396 -33.815782)
		(end 371.339618 -37.336222)
		(width 0.1143)
		(layer "F.Cu")
		(net "P3E_CPU0_PE2_SS_TXN<6>")
	)
	(segment
		(start 306.772564 -83.7565)
		(end 306.392326 -84.136738)
		(width 0.1143)
		(layer "F.Cu")
		(net "P3E_CPU0_PE2_SS_TXN<6>")
	)
	(segment
		(start 373.098314 -30.466284)
		(end 372.04396 -33.815782)
		(width 0.1143)
		(layer "F.Cu")
		(net "P3E_CPU0_PE2_SS_TXN<6>")
	)
	(segment
		(start 374.04421 -18.868644)
		(end 374.367298 -20.493228)
		(width 0.1143)
		(layer "F.Cu")
		(net "P3E_CPU0_PE2_SS_TXN<6>")
	)
	(segment
		(start 309.83809 -83.7565)
		(end 306.772564 -83.7565)
		(width 0.1143)
		(layer "F.Cu")
		(net "P3E_CPU0_PE2_SS_TXN<6>")
	)
	(segment
		(start 395.54531 -12.34313)
		(end 375.983754 -16.039084)
		(width 0.1143)
		(layer "F.Cu")
		(net "P3E_CPU0_PE2_SS_TXN<6>")
	)
	(via
		(at 318.506856 -75.564492)
		(size 0.508)
		(drill 0.254)
		(layers "F.Cu" "B.Cu")
		(net "P3E_CPU0_PE2_SS_TXN<6>")
	)
	(segment
		(start 397.798036 -12.531852)
		(end 396.858236 -13.234162)
		(width 0.1143)
		(layer "F.Cu")
		(net "P3E_CPU0_PE2_SS_TXN<5>")
	)
	(segment
		(start 375.00179 -26.157936)
		(end 375.40184 -28.159456)
		(width 0.1143)
		(layer "F.Cu")
		(net "P3E_CPU0_PE2_SS_TXN<5>")
	)
	(segment
		(start 375.40057 -20.545552)
		(end 375.061226 -22.223984)
		(width 0.1143)
		(layer "F.Cu")
		(net "P3E_CPU0_PE2_SS_TXN<5>")
	)
	(segment
		(start 355.690932 -61.391038)
		(end 353.238816 -61.87186)
		(width 0.1143)
		(layer "F.Cu")
		(net "P3E_CPU0_PE2_SS_TXN<5>")
	)
	(segment
		(start 307.76418 -85.311234)
		(end 307.67528 -85.222334)
		(width 0.0889)
		(layer "F.Cu")
		(net "P3E_CPU0_PE2_SS_TXN<5>")
	)
	(segment
		(start 306.105052 -85.952076)
		(end 306.392326 -86.117938)
		(width 0.0889)
		(layer "F.Cu")
		(net "P3E_CPU0_PE2_SS_TXN<5>")
	)
	(segment
		(start 345.99753 -61.504068)
		(end 344.767916 -61.765434)
		(width 0.1143)
		(layer "F.Cu")
		(net "P3E_CPU0_PE2_SS_TXN<5>")
	)
	(segment
		(start 374.839484 -33.958784)
		(end 374.325642 -34.361628)
		(width 0.1143)
		(layer "F.Cu")
		(net "P3E_CPU0_PE2_SS_TXN<5>")
	)
	(segment
		(start 375.087896 -18.973038)
		(end 375.40057 -20.545552)
		(width 0.1143)
		(layer "F.Cu")
		(net "P3E_CPU0_PE2_SS_TXN<5>")
	)
	(segment
		(start 372.572026 -42.439082)
		(end 371.132862 -46.729142)
		(width 0.1143)
		(layer "F.Cu")
		(net "P3E_CPU0_PE2_SS_TXN<5>")
	)
	(segment
		(start 353.238816 -61.87186)
		(end 351.317052 -61.37148)
		(width 0.1143)
		(layer "F.Cu")
		(net "P3E_CPU0_PE2_SS_TXN<5>")
	)
	(segment
		(start 365.695738 -49.265078)
		(end 364.267242 -51.407568)
		(width 0.1143)
		(layer "F.Cu")
		(net "P3E_CPU0_PE2_SS_TXN<5>")
	)
	(segment
		(start 358.206802 -59.010042)
		(end 357.236014 -60.367926)
		(width 0.1143)
		(layer "F.Cu")
		(net "P3E_CPU0_PE2_SS_TXN<5>")
	)
	(segment
		(start 357.236014 -60.367926)
		(end 355.690932 -61.391038)
		(width 0.1143)
		(layer "F.Cu")
		(net "P3E_CPU0_PE2_SS_TXN<5>")
	)
	(segment
		(start 398.595342 -11.241786)
		(end 398.595342 -11.567668)
		(width 0.1143)
		(layer "F.Cu")
		(net "P3E_CPU0_PE2_SS_TXN<5>")
	)
	(segment
		(start 366.715294 -48.58512)
		(end 365.695738 -49.265078)
		(width 0.1143)
		(layer "F.Cu")
		(net "P3E_CPU0_PE2_SS_TXN<5>")
	)
	(segment
		(start 359.314496 -54.761384)
		(end 358.206802 -59.010042)
		(width 0.1143)
		(layer "F.Cu")
		(net "P3E_CPU0_PE2_SS_TXN<5>")
	)
	(segment
		(start 308.41188 -85.247734)
		(end 308.38648 -85.222334)
		(width 0.0889)
		(layer "F.Cu")
		(net "P3E_CPU0_PE2_SS_TXN<5>")
	)
	(segment
		(start 372.674896 -38.297612)
		(end 372.229888 -40.523414)
		(width 0.1143)
		(layer "F.Cu")
		(net "P3E_CPU0_PE2_SS_TXN<5>")
	)
	(segment
		(start 369.09375 -48.109886)
		(end 366.715294 -48.58512)
		(width 0.1143)
		(layer "F.Cu")
		(net "P3E_CPU0_PE2_SS_TXN<5>")
	)
	(segment
		(start 348.427548 -61.48705)
		(end 347.173296 -61.754004)
		(width 0.1143)
		(layer "F.Cu")
		(net "P3E_CPU0_PE2_SS_TXN<5>")
	)
	(segment
		(start 343.975182 -61.597286)
		(end 332.918308 -63.824358)
		(width 0.1143)
		(layer "F.Cu")
		(net "P3E_CPU0_PE2_SS_TXN<5>")
	)
	(segment
		(start 308.03088 -85.311234)
		(end 307.76418 -85.311234)
		(width 0.0889)
		(layer "F.Cu")
		(net "P3E_CPU0_PE2_SS_TXN<5>")
	)
	(segment
		(start 371.132862 -46.729142)
		(end 371.132608 -46.729142)
		(width 0.1143)
		(layer "F.Cu")
		(net "P3E_CPU0_PE2_SS_TXN<5>")
	)
	(segment
		(start 398.595342 -11.567668)
		(end 397.798036 -12.531852)
		(width 0.1143)
		(layer "F.Cu")
		(net "P3E_CPU0_PE2_SS_TXN<5>")
	)
	(segment
		(start 321.49288 -73.112376)
		(end 315.220604 -82.07121)
		(width 0.1143)
		(layer "F.Cu")
		(net "P3E_CPU0_PE2_SS_TXN<5>")
	)
	(segment
		(start 307.67528 -85.222334)
		(end 307.250338 -85.222334)
		(width 0.0889)
		(layer "F.Cu")
		(net "P3E_CPU0_PE2_SS_TXN<5>")
	)
	(segment
		(start 372.464076 -37.24402)
		(end 372.674896 -38.297612)
		(width 0.1143)
		(layer "F.Cu")
		(net "P3E_CPU0_PE2_SS_TXN<5>")
	)
	(segment
		(start 396.858236 -13.234162)
		(end 376.332496 -16.98371)
		(width 0.1143)
		(layer "F.Cu")
		(net "P3E_CPU0_PE2_SS_TXN<5>")
	)
	(segment
		(start 306.408582 -85.717888)
		(end 306.37734 -85.717888)
		(width 0.0889)
		(layer "F.Cu")
		(net "P3E_CPU0_PE2_SS_TXN<5>")
	)
	(segment
		(start 328.873104 -66.231008)
		(end 327.25995 -68.797932)
		(width 0.1143)
		(layer "F.Cu")
		(net "P3E_CPU0_PE2_SS_TXN<5>")
	)
	(segment
		(start 374.325642 -34.361628)
		(end 373.22506 -34.56432)
		(width 0.1143)
		(layer "F.Cu")
		(net "P3E_CPU0_PE2_SS_TXN<5>")
	)
	(segment
		(start 374.75795 -31.37154)
		(end 375.129806 -32.817816)
		(width 0.1143)
		(layer "F.Cu")
		(net "P3E_CPU0_PE2_SS_TXN<5>")
	)
	(segment
		(start 351.317052 -61.37148)
		(end 349.600266 -61.736224)
		(width 0.1143)
		(layer "F.Cu")
		(net "P3E_CPU0_PE2_SS_TXN<5>")
	)
	(segment
		(start 332.918308 -63.824358)
		(end 328.873104 -66.231008)
		(width 0.1143)
		(layer "F.Cu")
		(net "P3E_CPU0_PE2_SS_TXN<5>")
	)
	(segment
		(start 372.903496 -35.047174)
		(end 372.464076 -37.24402)
		(width 0.1143)
		(layer "F.Cu")
		(net "P3E_CPU0_PE2_SS_TXN<5>")
	)
	(segment
		(start 375.40184 -28.159456)
		(end 374.75795 -31.37154)
		(width 0.1143)
		(layer "F.Cu")
		(net "P3E_CPU0_PE2_SS_TXN<5>")
	)
	(segment
		(start 327.25995 -68.797932)
		(end 321.920108 -72.502268)
		(width 0.1143)
		(layer "F.Cu")
		(net "P3E_CPU0_PE2_SS_TXN<5>")
	)
	(segment
		(start 308.38648 -85.222334)
		(end 308.11978 -85.222334)
		(width 0.0889)
		(layer "F.Cu")
		(net "P3E_CPU0_PE2_SS_TXN<5>")
	)
	(segment
		(start 375.424446 -24.041608)
		(end 375.00179 -26.157936)
		(width 0.1143)
		(layer "F.Cu")
		(net "P3E_CPU0_PE2_SS_TXN<5>")
	)
	(segment
		(start 398.919192 -10.917936)
		(end 398.595342 -11.241786)
		(width 0.1143)
		(layer "F.Cu")
		(net "P3E_CPU0_PE2_SS_TXN<5>")
	)
	(segment
		(start 364.267242 -51.407568)
		(end 359.314496 -54.76113)
		(width 0.1143)
		(layer "F.Cu")
		(net "P3E_CPU0_PE2_SS_TXN<5>")
	)
	(segment
		(start 359.314496 -54.76113)
		(end 359.314496 -54.761384)
		(width 0.1143)
		(layer "F.Cu")
		(net "P3E_CPU0_PE2_SS_TXN<5>")
	)
	(segment
		(start 344.767916 -61.765434)
		(end 343.975182 -61.597286)
		(width 0.1143)
		(layer "F.Cu")
		(net "P3E_CPU0_PE2_SS_TXN<5>")
	)
	(segment
		(start 308.11978 -85.222334)
		(end 308.03088 -85.311234)
		(width 0.0889)
		(layer "F.Cu")
		(net "P3E_CPU0_PE2_SS_TXN<5>")
	)
	(segment
		(start 372.229888 -40.523414)
		(end 372.572026 -42.439082)
		(width 0.1143)
		(layer "F.Cu")
		(net "P3E_CPU0_PE2_SS_TXN<5>")
	)
	(segment
		(start 375.061226 -22.223984)
		(end 375.424446 -24.041608)
		(width 0.1143)
		(layer "F.Cu")
		(net "P3E_CPU0_PE2_SS_TXN<5>")
	)
	(segment
		(start 375.129806 -33.278572)
		(end 374.839484 -33.958784)
		(width 0.1143)
		(layer "F.Cu")
		(net "P3E_CPU0_PE2_SS_TXN<5>")
	)
	(segment
		(start 321.920108 -72.502268)
		(end 321.49288 -73.112376)
		(width 0.1143)
		(layer "F.Cu")
		(net "P3E_CPU0_PE2_SS_TXN<5>")
	)
	(segment
		(start 375.761758 -17.361662)
		(end 375.087896 -18.973038)
		(width 0.1143)
		(layer "F.Cu")
		(net "P3E_CPU0_PE2_SS_TXN<5>")
	)
	(segment
		(start 376.332496 -16.98371)
		(end 375.761758 -17.361662)
		(width 0.1143)
		(layer "F.Cu")
		(net "P3E_CPU0_PE2_SS_TXN<5>")
	)
	(segment
		(start 315.220604 -82.07121)
		(end 309.054246 -85.247734)
		(width 0.1143)
		(layer "F.Cu")
		(net "P3E_CPU0_PE2_SS_TXN<5>")
	)
	(segment
		(start 306.081938 -85.865462)
		(end 306.105052 -85.952076)
		(width 0.0889)
		(layer "F.Cu")
		(net "P3E_CPU0_PE2_SS_TXN<5>")
	)
	(segment
		(start 373.22506 -34.56432)
		(end 372.903496 -35.047174)
		(width 0.1143)
		(layer "F.Cu")
		(net "P3E_CPU0_PE2_SS_TXN<5>")
	)
	(segment
		(start 375.129806 -32.817816)
		(end 375.129806 -33.278572)
		(width 0.1143)
		(layer "F.Cu")
		(net "P3E_CPU0_PE2_SS_TXN<5>")
	)
	(segment
		(start 347.173296 -61.754004)
		(end 345.99753 -61.504068)
		(width 0.1143)
		(layer "F.Cu")
		(net "P3E_CPU0_PE2_SS_TXN<5>")
	)
	(segment
		(start 349.600266 -61.736224)
		(end 348.427548 -61.48705)
		(width 0.1143)
		(layer "F.Cu")
		(net "P3E_CPU0_PE2_SS_TXN<5>")
	)
	(segment
		(start 371.132608 -46.729142)
		(end 369.09375 -48.109886)
		(width 0.1143)
		(layer "F.Cu")
		(net "P3E_CPU0_PE2_SS_TXN<5>")
	)
	(segment
		(start 309.054246 -85.247734)
		(end 308.41188 -85.247734)
		(width 0.1143)
		(layer "F.Cu")
		(net "P3E_CPU0_PE2_SS_TXN<5>")
	)
	(via
		(at 321.49288 -73.112376)
		(size 0.508)
		(drill 0.254)
		(layers "F.Cu" "B.Cu")
		(net "P3E_CPU0_PE2_SS_TXN<5>")
	)
	(arc
		(start 307.250338 -85.222334)
		(mid 307.050441 -85.276043)
		(end 306.904136 -85.422486)
		(width 0.0889)
		(layer "F.Cu")
		(net "P3E_CPU0_PE2_SS_TXN<5>")
	)
	(arc
		(start 306.37734 -85.717888)
		(mid 306.213702 -85.759783)
		(end 306.081938 -85.865462)
		(width 0.0889)
		(layer "F.Cu")
		(net "P3E_CPU0_PE2_SS_TXN<5>")
	)
	(arc
		(start 306.904136 -85.422486)
		(mid 306.694874 -85.634809)
		(end 306.408582 -85.717888)
		(width 0.0889)
		(layer "F.Cu")
		(net "P3E_CPU0_PE2_SS_TXN<5>")
	)
	(segment
		(start 343.96299 -62.620144)
		(end 338.97189 -63.625222)
		(width 0.1143)
		(layer "F.Cu")
		(net "P3E_CPU0_PE2_SS_TXN<4>")
	)
	(segment
		(start 349.522796 -62.745366)
		(end 348.427802 -62.512702)
		(width 0.1143)
		(layer "F.Cu")
		(net "P3E_CPU0_PE2_SS_TXN<4>")
	)
	(segment
		(start 356.50678 -62.258194)
		(end 353.232974 -62.907164)
		(width 0.1143)
		(layer "F.Cu")
		(net "P3E_CPU0_PE2_SS_TXN<4>")
	)
	(segment
		(start 360.199686 -55.34279)
		(end 359.159048 -59.333384)
		(width 0.1143)
		(layer "F.Cu")
		(net "P3E_CPU0_PE2_SS_TXN<4>")
	)
	(segment
		(start 347.186504 -62.776862)
		(end 346.010484 -62.526926)
		(width 0.1143)
		(layer "F.Cu")
		(net "P3E_CPU0_PE2_SS_TXN<4>")
	)
	(segment
		(start 376.095768 -32.547814)
		(end 376.095768 -33.623758)
		(width 0.1143)
		(layer "F.Cu")
		(net "P3E_CPU0_PE2_SS_TXN<4>")
	)
	(segment
		(start 328.548492 -69.217032)
		(end 322.634356 -73.229978)
		(width 0.1143)
		(layer "F.Cu")
		(net "P3E_CPU0_PE2_SS_TXN<4>")
	)
	(segment
		(start 376.15495 -29.331666)
		(end 375.79173 -31.143194)
		(width 0.1143)
		(layer "F.Cu")
		(net "P3E_CPU0_PE2_SS_TXN<4>")
	)
	(segment
		(start 353.232974 -62.907164)
		(end 351.224088 -62.383924)
		(width 0.1143)
		(layer "F.Cu")
		(net "P3E_CPU0_PE2_SS_TXN<4>")
	)
	(segment
		(start 373.987822 -35.868102)
		(end 373.819674 -36.37534)
		(width 0.1143)
		(layer "F.Cu")
		(net "P3E_CPU0_PE2_SS_TXN<4>")
	)
	(segment
		(start 376.095768 -33.623758)
		(end 375.661682 -34.660078)
		(width 0.1143)
		(layer "F.Cu")
		(net "P3E_CPU0_PE2_SS_TXN<4>")
	)
	(segment
		(start 329.733402 -67.394328)
		(end 328.548492 -69.217032)
		(width 0.1143)
		(layer "F.Cu")
		(net "P3E_CPU0_PE2_SS_TXN<4>")
	)
	(segment
		(start 351.224088 -62.383924)
		(end 349.522796 -62.745366)
		(width 0.1143)
		(layer "F.Cu")
		(net "P3E_CPU0_PE2_SS_TXN<4>")
	)
	(segment
		(start 367.99266 -49.348644)
		(end 367.064544 -49.534064)
		(width 0.1143)
		(layer "F.Cu")
		(net "P3E_CPU0_PE2_SS_TXN<4>")
	)
	(segment
		(start 380.370842 -19.924776)
		(end 379.915674 -21.611082)
		(width 0.1143)
		(layer "F.Cu")
		(net "P3E_CPU0_PE2_SS_TXN<4>")
	)
	(segment
		(start 380.043436 -26.950924)
		(end 379.905768 -27.602688)
		(width 0.1143)
		(layer "F.Cu")
		(net "P3E_CPU0_PE2_SS_TXN<4>")
	)
	(segment
		(start 380.467108 -23.526242)
		(end 379.718062 -25.96388)
		(width 0.1143)
		(layer "F.Cu")
		(net "P3E_CPU0_PE2_SS_TXN<4>")
	)
	(segment
		(start 400.995642 -11.241786)
		(end 400.995642 -11.567668)
		(width 0.1143)
		(layer "F.Cu")
		(net "P3E_CPU0_PE2_SS_TXN<4>")
	)
	(segment
		(start 400.995642 -11.567668)
		(end 400.353784 -12.3444)
		(width 0.1143)
		(layer "F.Cu")
		(net "P3E_CPU0_PE2_SS_TXN<4>")
	)
	(segment
		(start 307.625496 -86.238334)
		(end 307.250846 -86.612984)
		(width 0.1143)
		(layer "F.Cu")
		(net "P3E_CPU0_PE2_SS_TXN<4>")
	)
	(segment
		(start 357.781606 -61.414152)
		(end 356.50678 -62.258194)
		(width 0.1143)
		(layer "F.Cu")
		(net "P3E_CPU0_PE2_SS_TXN<4>")
	)
	(segment
		(start 334.46974 -65.75679)
		(end 329.733402 -67.394328)
		(width 0.1143)
		(layer "F.Cu")
		(net "P3E_CPU0_PE2_SS_TXN<4>")
	)
	(segment
		(start 316.002162 -82.759804)
		(end 309.251096 -86.238334)
		(width 0.1143)
		(layer "F.Cu")
		(net "P3E_CPU0_PE2_SS_TXN<4>")
	)
	(segment
		(start 370.60251 -49.59604)
		(end 369.686078 -49.785016)
		(width 0.1143)
		(layer "F.Cu")
		(net "P3E_CPU0_PE2_SS_TXN<4>")
	)
	(segment
		(start 379.739144 -26.027888)
		(end 379.739398 -26.027888)
		(width 0.1143)
		(layer "F.Cu")
		(net "P3E_CPU0_PE2_SS_TXN<4>")
	)
	(segment
		(start 348.427802 -62.512702)
		(end 347.186504 -62.776862)
		(width 0.1143)
		(layer "F.Cu")
		(net "P3E_CPU0_PE2_SS_TXN<4>")
	)
	(segment
		(start 379.718062 -25.96388)
		(end 379.739144 -26.027888)
		(width 0.1143)
		(layer "F.Cu")
		(net "P3E_CPU0_PE2_SS_TXN<4>")
	)
	(segment
		(start 395.91742 -15.280894)
		(end 387.711188 -16.78813)
		(width 0.1143)
		(layer "F.Cu")
		(net "P3E_CPU0_PE2_SS_TXN<4>")
	)
	(segment
		(start 373.968518 -41.422828)
		(end 371.923818 -47.51705)
		(width 0.1143)
		(layer "F.Cu")
		(net "P3E_CPU0_PE2_SS_TXN<4>")
	)
	(segment
		(start 344.76817 -62.791086)
		(end 343.96299 -62.620144)
		(width 0.1143)
		(layer "F.Cu")
		(net "P3E_CPU0_PE2_SS_TXN<4>")
	)
	(segment
		(start 373.819674 -36.37534)
		(end 374.04167 -37.447982)
		(width 0.1143)
		(layer "F.Cu")
		(net "P3E_CPU0_PE2_SS_TXN<4>")
	)
	(segment
		(start 322.634356 -73.229978)
		(end 320.540888 -76.2381)
		(width 0.1143)
		(layer "F.Cu")
		(net "P3E_CPU0_PE2_SS_TXN<4>")
	)
	(segment
		(start 364.992158 -52.105306)
		(end 360.199686 -55.34279)
		(width 0.1143)
		(layer "F.Cu")
		(net "P3E_CPU0_PE2_SS_TXN<4>")
	)
	(segment
		(start 378.930154 -28.132532)
		(end 377.733814 -27.873452)
		(width 0.1143)
		(layer "F.Cu")
		(net "P3E_CPU0_PE2_SS_TXN<4>")
	)
	(segment
		(start 377.147328 -28.024582)
		(end 376.15495 -29.331666)
		(width 0.1143)
		(layer "F.Cu")
		(net "P3E_CPU0_PE2_SS_TXN<4>")
	)
	(segment
		(start 346.010484 -62.526926)
		(end 344.76817 -62.791086)
		(width 0.1143)
		(layer "F.Cu")
		(net "P3E_CPU0_PE2_SS_TXN<4>")
	)
	(segment
		(start 375.79173 -31.143194)
		(end 376.095768 -32.547814)
		(width 0.1143)
		(layer "F.Cu")
		(net "P3E_CPU0_PE2_SS_TXN<4>")
	)
	(segment
		(start 400.353784 -12.3444)
		(end 395.91742 -15.280894)
		(width 0.1143)
		(layer "F.Cu")
		(net "P3E_CPU0_PE2_SS_TXN<4>")
	)
	(segment
		(start 338.97189 -63.625222)
		(end 334.46974 -65.75679)
		(width 0.1143)
		(layer "F.Cu")
		(net "P3E_CPU0_PE2_SS_TXN<4>")
	)
	(segment
		(start 371.213634 -49.233836)
		(end 370.60251 -49.59604)
		(width 0.1143)
		(layer "F.Cu")
		(net "P3E_CPU0_PE2_SS_TXN<4>")
	)
	(segment
		(start 387.711188 -16.78813)
		(end 381.142748 -18.850356)
		(width 0.1143)
		(layer "F.Cu")
		(net "P3E_CPU0_PE2_SS_TXN<4>")
	)
	(segment
		(start 401.319492 -10.917936)
		(end 400.995642 -11.241786)
		(width 0.1143)
		(layer "F.Cu")
		(net "P3E_CPU0_PE2_SS_TXN<4>")
	)
	(segment
		(start 320.540888 -76.238354)
		(end 316.002162 -82.759804)
		(width 0.1143)
		(layer "F.Cu")
		(net "P3E_CPU0_PE2_SS_TXN<4>")
	)
	(segment
		(start 367.064544 -49.534064)
		(end 366.4204 -49.963832)
		(width 0.1143)
		(layer "F.Cu")
		(net "P3E_CPU0_PE2_SS_TXN<4>")
	)
	(segment
		(start 366.4204 -49.963832)
		(end 364.992158 -52.105306)
		(width 0.1143)
		(layer "F.Cu")
		(net "P3E_CPU0_PE2_SS_TXN<4>")
	)
	(segment
		(start 375.661682 -34.660078)
		(end 373.987822 -35.868102)
		(width 0.1143)
		(layer "F.Cu")
		(net "P3E_CPU0_PE2_SS_TXN<4>")
	)
	(segment
		(start 379.915674 -21.611082)
		(end 380.467108 -23.526242)
		(width 0.1143)
		(layer "F.Cu")
		(net "P3E_CPU0_PE2_SS_TXN<4>")
	)
	(segment
		(start 371.923818 -47.51705)
		(end 371.213634 -49.233836)
		(width 0.1143)
		(layer "F.Cu")
		(net "P3E_CPU0_PE2_SS_TXN<4>")
	)
	(segment
		(start 309.251096 -86.238334)
		(end 307.625496 -86.238334)
		(width 0.1143)
		(layer "F.Cu")
		(net "P3E_CPU0_PE2_SS_TXN<4>")
	)
	(segment
		(start 379.905768 -27.602688)
		(end 378.930154 -28.132532)
		(width 0.1143)
		(layer "F.Cu")
		(net "P3E_CPU0_PE2_SS_TXN<4>")
	)
	(segment
		(start 373.607838 -39.62019)
		(end 373.968518 -41.422828)
		(width 0.1143)
		(layer "F.Cu")
		(net "P3E_CPU0_PE2_SS_TXN<4>")
	)
	(segment
		(start 379.739398 -26.027888)
		(end 380.043436 -26.950924)
		(width 0.1143)
		(layer "F.Cu")
		(net "P3E_CPU0_PE2_SS_TXN<4>")
	)
	(segment
		(start 381.142748 -18.850356)
		(end 380.370842 -19.924776)
		(width 0.1143)
		(layer "F.Cu")
		(net "P3E_CPU0_PE2_SS_TXN<4>")
	)
	(segment
		(start 369.686078 -49.785016)
		(end 367.99266 -49.348644)
		(width 0.1143)
		(layer "F.Cu")
		(net "P3E_CPU0_PE2_SS_TXN<4>")
	)
	(segment
		(start 320.540888 -76.2381)
		(end 320.540888 -76.238354)
		(width 0.1143)
		(layer "F.Cu")
		(net "P3E_CPU0_PE2_SS_TXN<4>")
	)
	(segment
		(start 377.733814 -27.873452)
		(end 377.147328 -28.024582)
		(width 0.1143)
		(layer "F.Cu")
		(net "P3E_CPU0_PE2_SS_TXN<4>")
	)
	(segment
		(start 359.159048 -59.333384)
		(end 357.781606 -61.414152)
		(width 0.1143)
		(layer "F.Cu")
		(net "P3E_CPU0_PE2_SS_TXN<4>")
	)
	(segment
		(start 374.04167 -37.447982)
		(end 373.607838 -39.62019)
		(width 0.1143)
		(layer "F.Cu")
		(net "P3E_CPU0_PE2_SS_TXN<4>")
	)
	(via
		(at 320.540888 -76.2381)
		(size 0.508)
		(drill 0.254)
		(layers "F.Cu" "B.Cu")
		(net "P3E_CPU0_PE2_SS_TXN<4>")
	)
	(segment
		(start 386.502148 -27.95778)
		(end 386.33527 -27.124914)
		(width 0.1143)
		(layer "F.Cu")
		(net "P3E_CPU0_PE2_SS_TXN<3>")
	)
	(segment
		(start 367.97107 -50.81143)
		(end 368.86388 -50.632614)
		(width 0.1143)
		(layer "F.Cu")
		(net "P3E_CPU0_PE2_SS_TXN<3>")
	)
	(segment
		(start 356.934262 -63.876936)
		(end 358.032304 -63.624206)
		(width 0.1143)
		(layer "F.Cu")
		(net "P3E_CPU0_PE2_SS_TXN<3>")
	)
	(segment
		(start 373.83593 -48.658018)
		(end 373.96547 -48.570388)
		(width 0.1143)
		(layer "F.Cu")
		(net "P3E_CPU0_PE2_SS_TXN<3>")
	)
	(segment
		(start 385.681474 -31.994348)
		(end 386.502148 -27.95778)
		(width 0.1143)
		(layer "F.Cu")
		(net "P3E_CPU0_PE2_SS_TXN<3>")
	)
	(segment
		(start 377.320302 -47.751492)
		(end 378.612654 -48.029114)
		(width 0.1143)
		(layer "F.Cu")
		(net "P3E_CPU0_PE2_SS_TXN<3>")
	)
	(segment
		(start 402.877528 -12.253722)
		(end 403.395942 -11.561318)
		(width 0.1143)
		(layer "F.Cu")
		(net "P3E_CPU0_PE2_SS_TXN<3>")
	)
	(segment
		(start 368.86388 -50.632614)
		(end 370.023898 -50.86477)
		(width 0.1143)
		(layer "F.Cu")
		(net "P3E_CPU0_PE2_SS_TXN<3>")
	)
	(segment
		(start 308.657498 -87.228934)
		(end 308.6354 -87.228934)
		(width 0.0889)
		(layer "F.Cu")
		(net "P3E_CPU0_PE2_SS_TXN<3>")
	)
	(segment
		(start 370.023898 -50.86477)
		(end 370.794534 -50.710846)
		(width 0.1143)
		(layer "F.Cu")
		(net "P3E_CPU0_PE2_SS_TXN<3>")
	)
	(segment
		(start 309.433468 -87.228934)
		(end 308.657498 -87.228934)
		(width 0.1143)
		(layer "F.Cu")
		(net "P3E_CPU0_PE2_SS_TXN<3>")
	)
	(segment
		(start 332.46314 -67.782948)
		(end 339.24367 -64.572896)
		(width 0.1143)
		(layer "F.Cu")
		(net "P3E_CPU0_PE2_SS_TXN<3>")
	)
	(segment
		(start 308.6354 -87.228934)
		(end 308.61 -87.203534)
		(width 0.0889)
		(layer "F.Cu")
		(net "P3E_CPU0_PE2_SS_TXN<3>")
	)
	(segment
		(start 365.75873 -53.811932)
		(end 367.589308 -51.065684)
		(width 0.1143)
		(layer "F.Cu")
		(net "P3E_CPU0_PE2_SS_TXN<3>")
	)
	(segment
		(start 305.685444 -88.175084)
		(end 305.533806 -88.594184)
		(width 0.0889)
		(layer "F.Cu")
		(net "P3E_CPU0_PE2_SS_TXN<3>")
	)
	(segment
		(start 385.500626 -41.706292)
		(end 385.68757 -40.900604)
		(width 0.1143)
		(layer "F.Cu")
		(net "P3E_CPU0_PE2_SS_TXN<3>")
	)
	(segment
		(start 353.187 -63.9318)
		(end 355.6508 -63.4492)
		(width 0.1143)
		(layer "F.Cu")
		(net "P3E_CPU0_PE2_SS_TXN<3>")
	)
	(segment
		(start 387.780022 -18.326354)
		(end 391.52322 -17.401794)
		(width 0.1143)
		(layer "F.Cu")
		(net "P3E_CPU0_PE2_SS_TXN<3>")
	)
	(segment
		(start 373.819674 -48.662336)
		(end 373.83593 -48.658018)
		(width 0.1143)
		(layer "F.Cu")
		(net "P3E_CPU0_PE2_SS_TXN<3>")
	)
	(segment
		(start 391.52322 -17.401794)
		(end 395.865858 -16.518636)
		(width 0.1143)
		(layer "F.Cu")
		(net "P3E_CPU0_PE2_SS_TXN<3>")
	)
	(segment
		(start 385.068064 -33.185608)
		(end 385.145788 -32.803592)
		(width 0.1143)
		(layer "F.Cu")
		(net "P3E_CPU0_PE2_SS_TXN<3>")
	)
	(segment
		(start 385.145788 -32.803592)
		(end 385.681474 -31.994348)
		(width 0.1143)
		(layer "F.Cu")
		(net "P3E_CPU0_PE2_SS_TXN<3>")
	)
	(segment
		(start 320.44259 -78.081632)
		(end 323.223636 -74.083418)
		(width 0.1143)
		(layer "F.Cu")
		(net "P3E_CPU0_PE2_SS_TXN<3>")
	)
	(segment
		(start 320.44259 -78.081632)
		(end 316.640718 -83.547458)
		(width 0.1143)
		(layer "F.Cu")
		(net "P3E_CPU0_PE2_SS_TXN<3>")
	)
	(segment
		(start 381.569214 -44.82719)
		(end 385.500626 -41.706292)
		(width 0.1143)
		(layer "F.Cu")
		(net "P3E_CPU0_PE2_SS_TXN<3>")
	)
	(segment
		(start 360.07294 -59.937142)
		(end 363.133894 -55.583328)
		(width 0.1143)
		(layer "F.Cu")
		(net "P3E_CPU0_PE2_SS_TXN<3>")
	)
	(segment
		(start 373.96547 -48.570388)
		(end 377.320302 -47.751492)
		(width 0.1143)
		(layer "F.Cu")
		(net "P3E_CPU0_PE2_SS_TXN<3>")
	)
	(segment
		(start 385.330954 -36.952682)
		(end 385.696968 -35.153092)
		(width 0.1143)
		(layer "F.Cu")
		(net "P3E_CPU0_PE2_SS_TXN<3>")
	)
	(segment
		(start 344.76309 -63.78956)
		(end 346.005658 -63.525654)
		(width 0.1143)
		(layer "F.Cu")
		(net "P3E_CPU0_PE2_SS_TXN<3>")
	)
	(segment
		(start 385.654804 -38.546024)
		(end 385.330954 -36.952682)
		(width 0.1143)
		(layer "F.Cu")
		(net "P3E_CPU0_PE2_SS_TXN<3>")
	)
	(segment
		(start 402.11375 -12.3825)
		(end 402.877528 -12.253722)
		(width 0.1143)
		(layer "F.Cu")
		(net "P3E_CPU0_PE2_SS_TXN<3>")
	)
	(segment
		(start 367.589308 -51.065684)
		(end 367.97107 -50.81143)
		(width 0.1143)
		(layer "F.Cu")
		(net "P3E_CPU0_PE2_SS_TXN<3>")
	)
	(segment
		(start 385.398518 -33.684718)
		(end 385.068064 -33.185608)
		(width 0.1143)
		(layer "F.Cu")
		(net "P3E_CPU0_PE2_SS_TXN<3>")
	)
	(segment
		(start 378.612654 -48.029114)
		(end 379.410976 -47.699168)
		(width 0.1143)
		(layer "F.Cu")
		(net "P3E_CPU0_PE2_SS_TXN<3>")
	)
	(segment
		(start 306.410106 -87.699088)
		(end 306.37734 -87.699088)
		(width 0.0889)
		(layer "F.Cu")
		(net "P3E_CPU0_PE2_SS_TXN<3>")
	)
	(segment
		(start 359.332276 -62.77864)
		(end 360.07294 -59.937142)
		(width 0.1143)
		(layer "F.Cu")
		(net "P3E_CPU0_PE2_SS_TXN<3>")
	)
	(segment
		(start 385.399534 -39.652448)
		(end 385.654804 -38.546024)
		(width 0.1143)
		(layer "F.Cu")
		(net "P3E_CPU0_PE2_SS_TXN<3>")
	)
	(segment
		(start 348.433136 -63.509398)
		(end 349.649288 -63.767716)
		(width 0.1143)
		(layer "F.Cu")
		(net "P3E_CPU0_PE2_SS_TXN<3>")
	)
	(segment
		(start 386.66928 -25.889966)
		(end 386.120132 -24.751792)
		(width 0.1143)
		(layer "F.Cu")
		(net "P3E_CPU0_PE2_SS_TXN<3>")
	)
	(segment
		(start 403.395942 -11.561318)
		(end 403.395942 -11.241786)
		(width 0.1143)
		(layer "F.Cu")
		(net "P3E_CPU0_PE2_SS_TXN<3>")
	)
	(segment
		(start 387.266688 -19.101562)
		(end 387.780022 -18.326354)
		(width 0.1143)
		(layer "F.Cu")
		(net "P3E_CPU0_PE2_SS_TXN<3>")
	)
	(segment
		(start 385.696968 -35.153092)
		(end 385.398518 -33.684718)
		(width 0.1143)
		(layer "F.Cu")
		(net "P3E_CPU0_PE2_SS_TXN<3>")
	)
	(segment
		(start 386.33527 -27.124914)
		(end 386.66928 -25.889966)
		(width 0.1143)
		(layer "F.Cu")
		(net "P3E_CPU0_PE2_SS_TXN<3>")
	)
	(segment
		(start 358.032304 -63.624206)
		(end 359.332276 -62.77864)
		(width 0.1143)
		(layer "F.Cu")
		(net "P3E_CPU0_PE2_SS_TXN<3>")
	)
	(segment
		(start 308.61 -87.203534)
		(end 307.23967 -87.203534)
		(width 0.0889)
		(layer "F.Cu")
		(net "P3E_CPU0_PE2_SS_TXN<3>")
	)
	(segment
		(start 385.68757 -40.900604)
		(end 385.399534 -39.652448)
		(width 0.1143)
		(layer "F.Cu")
		(net "P3E_CPU0_PE2_SS_TXN<3>")
	)
	(segment
		(start 347.181678 -63.775336)
		(end 348.433136 -63.509398)
		(width 0.1143)
		(layer "F.Cu")
		(net "P3E_CPU0_PE2_SS_TXN<3>")
	)
	(segment
		(start 339.24367 -64.572896)
		(end 343.969594 -63.621158)
		(width 0.1143)
		(layer "F.Cu")
		(net "P3E_CPU0_PE2_SS_TXN<3>")
	)
	(segment
		(start 351.250758 -63.42761)
		(end 353.187 -63.9318)
		(width 0.1143)
		(layer "F.Cu")
		(net "P3E_CPU0_PE2_SS_TXN<3>")
	)
	(segment
		(start 349.649288 -63.767716)
		(end 351.250758 -63.42761)
		(width 0.1143)
		(layer "F.Cu")
		(net "P3E_CPU0_PE2_SS_TXN<3>")
	)
	(segment
		(start 355.6508 -63.4492)
		(end 356.934262 -63.876936)
		(width 0.1143)
		(layer "F.Cu")
		(net "P3E_CPU0_PE2_SS_TXN<3>")
	)
	(segment
		(start 403.395942 -11.241786)
		(end 403.719792 -10.917936)
		(width 0.1143)
		(layer "F.Cu")
		(net "P3E_CPU0_PE2_SS_TXN<3>")
	)
	(segment
		(start 346.005658 -63.525654)
		(end 347.181678 -63.775336)
		(width 0.1143)
		(layer "F.Cu")
		(net "P3E_CPU0_PE2_SS_TXN<3>")
	)
	(segment
		(start 386.120132 -24.751792)
		(end 387.266688 -19.101562)
		(width 0.1143)
		(layer "F.Cu")
		(net "P3E_CPU0_PE2_SS_TXN<3>")
	)
	(segment
		(start 316.640718 -83.547458)
		(end 309.433468 -87.228934)
		(width 0.1143)
		(layer "F.Cu")
		(net "P3E_CPU0_PE2_SS_TXN<3>")
	)
	(segment
		(start 379.410976 -47.699168)
		(end 381.569214 -44.82719)
		(width 0.1143)
		(layer "F.Cu")
		(net "P3E_CPU0_PE2_SS_TXN<3>")
	)
	(segment
		(start 370.794534 -50.710846)
		(end 373.819674 -48.662336)
		(width 0.1143)
		(layer "F.Cu")
		(net "P3E_CPU0_PE2_SS_TXN<3>")
	)
	(segment
		(start 343.969594 -63.621158)
		(end 344.76309 -63.78956)
		(width 0.1143)
		(layer "F.Cu")
		(net "P3E_CPU0_PE2_SS_TXN<3>")
	)
	(segment
		(start 363.133894 -55.583328)
		(end 365.75873 -53.811932)
		(width 0.1143)
		(layer "F.Cu")
		(net "P3E_CPU0_PE2_SS_TXN<3>")
	)
	(segment
		(start 395.865858 -16.518636)
		(end 402.11375 -12.3825)
		(width 0.1143)
		(layer "F.Cu")
		(net "P3E_CPU0_PE2_SS_TXN<3>")
	)
	(segment
		(start 323.223636 -74.083418)
		(end 332.46314 -67.782948)
		(width 0.1143)
		(layer "F.Cu")
		(net "P3E_CPU0_PE2_SS_TXN<3>")
	)
	(via
		(at 320.44259 -78.081632)
		(size 0.508)
		(drill 0.254)
		(layers "F.Cu" "B.Cu")
		(net "P3E_CPU0_PE2_SS_TXN<3>")
	)
	(arc
		(start 306.37734 -87.699088)
		(mid 306.185698 -87.756254)
		(end 306.045616 -87.898986)
		(width 0.0889)
		(layer "F.Cu")
		(net "P3E_CPU0_PE2_SS_TXN<3>")
	)
	(arc
		(start 305.730148 -88.161368)
		(mid 305.707932 -88.168668)
		(end 305.685444 -88.175084)
		(width 0.0889)
		(layer "F.Cu")
		(net "P3E_CPU0_PE2_SS_TXN<3>")
	)
	(arc
		(start 307.23967 -87.203534)
		(mid 307.04582 -87.259884)
		(end 306.904136 -87.403686)
		(width 0.0889)
		(layer "F.Cu")
		(net "P3E_CPU0_PE2_SS_TXN<3>")
	)
	(arc
		(start 306.904136 -87.403686)
		(mid 306.695528 -87.615618)
		(end 306.410106 -87.699088)
		(width 0.0889)
		(layer "F.Cu")
		(net "P3E_CPU0_PE2_SS_TXN<3>")
	)
	(arc
		(start 306.045616 -87.898986)
		(mid 305.91138 -88.058425)
		(end 305.730148 -88.161368)
		(width 0.0889)
		(layer "F.Cu")
		(net "P3E_CPU0_PE2_SS_TXN<3>")
	)
	(segment
		(start 405.796242 -11.241786)
		(end 405.796242 -11.567668)
		(width 0.1143)
		(layer "F.Cu")
		(net "P3E_CPU0_PE2_SS_TXN<2>")
	)
	(segment
		(start 319.215516 -81.617058)
		(end 317.364364 -84.278216)
		(width 0.1143)
		(layer "F.Cu")
		(net "P3E_CPU0_PE2_SS_TXN<2>")
	)
	(segment
		(start 389.198358 -21.286978)
		(end 388.792212 -21.937218)
		(width 0.1143)
		(layer "F.Cu")
		(net "P3E_CPU0_PE2_SS_TXN<2>")
	)
	(segment
		(start 388.792212 -21.937218)
		(end 388.59968 -22.7711)
		(width 0.1143)
		(layer "F.Cu")
		(net "P3E_CPU0_PE2_SS_TXN<2>")
	)
	(segment
		(start 308.086252 -88.287352)
		(end 307.819552 -88.287352)
		(width 0.0889)
		(layer "F.Cu")
		(net "P3E_CPU0_PE2_SS_TXN<2>")
	)
	(segment
		(start 405.796242 -11.567668)
		(end 404.700994 -12.892532)
		(width 0.1143)
		(layer "F.Cu")
		(net "P3E_CPU0_PE2_SS_TXN<2>")
	)
	(segment
		(start 386.966968 -33.19272)
		(end 386.860034 -33.354518)
		(width 0.1143)
		(layer "F.Cu")
		(net "P3E_CPU0_PE2_SS_TXN<2>")
	)
	(segment
		(start 386.871464 -34.939732)
		(end 386.390388 -37.304726)
		(width 0.1143)
		(layer "F.Cu")
		(net "P3E_CPU0_PE2_SS_TXN<2>")
	)
	(segment
		(start 307.730652 -88.198452)
		(end 307.241702 -88.198452)
		(width 0.0889)
		(layer "F.Cu")
		(net "P3E_CPU0_PE2_SS_TXN<2>")
	)
	(segment
		(start 406.120092 -10.917936)
		(end 405.796242 -11.241786)
		(width 0.1143)
		(layer "F.Cu")
		(net "P3E_CPU0_PE2_SS_TXN<2>")
	)
	(segment
		(start 360.956606 -60.393326)
		(end 360.03357 -63.933578)
		(width 0.1143)
		(layer "F.Cu")
		(net "P3E_CPU0_PE2_SS_TXN<2>")
	)
	(segment
		(start 317.364364 -84.278216)
		(end 309.688738 -88.223852)
		(width 0.1143)
		(layer "F.Cu")
		(net "P3E_CPU0_PE2_SS_TXN<2>")
	)
	(segment
		(start 388.624572 -25.591516)
		(end 388.917688 -26.860754)
		(width 0.1143)
		(layer "F.Cu")
		(net "P3E_CPU0_PE2_SS_TXN<2>")
	)
	(segment
		(start 388.386828 -32.173164)
		(end 388.386828 -32.218376)
		(width 0.1143)
		(layer "F.Cu")
		(net "P3E_CPU0_PE2_SS_TXN<2>")
	)
	(segment
		(start 388.386828 -32.218376)
		(end 388.284974 -32.32023)
		(width 0.1143)
		(layer "F.Cu")
		(net "P3E_CPU0_PE2_SS_TXN<2>")
	)
	(segment
		(start 386.860034 -33.354518)
		(end 386.704332 -34.118296)
		(width 0.1143)
		(layer "F.Cu")
		(net "P3E_CPU0_PE2_SS_TXN<2>")
	)
	(segment
		(start 404.700994 -12.892532)
		(end 402.424138 -13.347954)
		(width 0.1143)
		(layer "F.Cu")
		(net "P3E_CPU0_PE2_SS_TXN<2>")
	)
	(segment
		(start 339.508846 -65.517014)
		(end 333.2226 -68.49364)
		(width 0.1143)
		(layer "F.Cu")
		(net "P3E_CPU0_PE2_SS_TXN<2>")
	)
	(segment
		(start 386.306314 -42.886122)
		(end 383.556002 -44.604686)
		(width 0.1143)
		(layer "F.Cu")
		(net "P3E_CPU0_PE2_SS_TXN<2>")
	)
	(segment
		(start 308.886352 -88.198452)
		(end 308.797452 -88.287352)
		(width 0.0889)
		(layer "F.Cu")
		(net "P3E_CPU0_PE2_SS_TXN<2>")
	)
	(segment
		(start 388.59968 -22.7711)
		(end 388.9375 -24.236426)
		(width 0.1143)
		(layer "F.Cu")
		(net "P3E_CPU0_PE2_SS_TXN<2>")
	)
	(segment
		(start 388.917688 -26.860754)
		(end 388.637526 -28.075382)
		(width 0.1143)
		(layer "F.Cu")
		(net "P3E_CPU0_PE2_SS_TXN<2>")
	)
	(segment
		(start 306.940458 -88.341962)
		(end 306.963572 -88.428576)
		(width 0.0889)
		(layer "F.Cu")
		(net "P3E_CPU0_PE2_SS_TXN<2>")
	)
	(segment
		(start 386.93725 -39.992554)
		(end 386.782564 -40.823388)
		(width 0.1143)
		(layer "F.Cu")
		(net "P3E_CPU0_PE2_SS_TXN<2>")
	)
	(segment
		(start 347.201744 -64.779144)
		(end 346.005658 -64.525144)
		(width 0.1143)
		(layer "F.Cu")
		(net "P3E_CPU0_PE2_SS_TXN<2>")
	)
	(segment
		(start 308.797452 -88.287352)
		(end 308.530752 -88.287352)
		(width 0.0889)
		(layer "F.Cu")
		(net "P3E_CPU0_PE2_SS_TXN<2>")
	)
	(segment
		(start 394.908278 -17.703546)
		(end 393.212828 -20.122388)
		(width 0.1143)
		(layer "F.Cu")
		(net "P3E_CPU0_PE2_SS_TXN<2>")
	)
	(segment
		(start 377.193556 -48.782732)
		(end 374.224042 -49.555654)
		(width 0.1143)
		(layer "F.Cu")
		(net "P3E_CPU0_PE2_SS_TXN<2>")
	)
	(segment
		(start 393.212828 -20.122388)
		(end 391.934192 -20.969478)
		(width 0.1143)
		(layer "F.Cu")
		(net "P3E_CPU0_PE2_SS_TXN<2>")
	)
	(segment
		(start 380.553468 -48.542956)
		(end 378.53874 -49.12741)
		(width 0.1143)
		(layer "F.Cu")
		(net "P3E_CPU0_PE2_SS_TXN<2>")
	)
	(segment
		(start 306.963572 -88.428576)
		(end 307.250846 -88.594184)
		(width 0.0889)
		(layer "F.Cu")
		(net "P3E_CPU0_PE2_SS_TXN<2>")
	)
	(segment
		(start 383.556002 -44.604686)
		(end 380.553468 -48.542956)
		(width 0.1143)
		(layer "F.Cu")
		(net "P3E_CPU0_PE2_SS_TXN<2>")
	)
	(segment
		(start 386.782564 -40.823388)
		(end 386.306314 -42.886122)
		(width 0.1143)
		(layer "F.Cu")
		(net "P3E_CPU0_PE2_SS_TXN<2>")
	)
	(segment
		(start 348.443804 -64.515238)
		(end 347.201744 -64.779144)
		(width 0.1143)
		(layer "F.Cu")
		(net "P3E_CPU0_PE2_SS_TXN<2>")
	)
	(segment
		(start 346.005658 -64.525144)
		(end 344.76309 -64.789304)
		(width 0.1143)
		(layer "F.Cu")
		(net "P3E_CPU0_PE2_SS_TXN<2>")
	)
	(segment
		(start 388.985506 -29.581856)
		(end 388.386828 -32.173164)
		(width 0.1143)
		(layer "F.Cu")
		(net "P3E_CPU0_PE2_SS_TXN<2>")
	)
	(segment
		(start 308.441852 -88.198452)
		(end 308.175152 -88.198452)
		(width 0.0889)
		(layer "F.Cu")
		(net "P3E_CPU0_PE2_SS_TXN<2>")
	)
	(segment
		(start 374.224042 -49.555654)
		(end 363.445044 -56.855614)
		(width 0.1143)
		(layer "F.Cu")
		(net "P3E_CPU0_PE2_SS_TXN<2>")
	)
	(segment
		(start 390.213088 -20.803108)
		(end 389.198358 -21.286978)
		(width 0.1143)
		(layer "F.Cu")
		(net "P3E_CPU0_PE2_SS_TXN<2>")
	)
	(segment
		(start 378.53874 -49.12741)
		(end 377.193556 -48.782732)
		(width 0.1143)
		(layer "F.Cu")
		(net "P3E_CPU0_PE2_SS_TXN<2>")
	)
	(segment
		(start 308.530752 -88.287352)
		(end 308.441852 -88.198452)
		(width 0.0889)
		(layer "F.Cu")
		(net "P3E_CPU0_PE2_SS_TXN<2>")
	)
	(segment
		(start 343.964514 -64.619632)
		(end 339.508846 -65.517014)
		(width 0.1143)
		(layer "F.Cu")
		(net "P3E_CPU0_PE2_SS_TXN<2>")
	)
	(segment
		(start 355.593396 -65.710054)
		(end 351.049082 -64.470026)
		(width 0.1143)
		(layer "F.Cu")
		(net "P3E_CPU0_PE2_SS_TXN<2>")
	)
	(segment
		(start 309.688738 -88.223852)
		(end 309.20055 -88.223852)
		(width 0.1143)
		(layer "F.Cu")
		(net "P3E_CPU0_PE2_SS_TXN<2>")
	)
	(segment
		(start 388.284974 -32.32023)
		(end 386.966968 -33.19272)
		(width 0.1143)
		(layer "F.Cu")
		(net "P3E_CPU0_PE2_SS_TXN<2>")
	)
	(segment
		(start 309.153052 -88.198452)
		(end 308.886352 -88.198452)
		(width 0.0889)
		(layer "F.Cu")
		(net "P3E_CPU0_PE2_SS_TXN<2>")
	)
	(segment
		(start 402.424138 -13.347954)
		(end 396.257018 -17.429988)
		(width 0.1143)
		(layer "F.Cu")
		(net "P3E_CPU0_PE2_SS_TXN<2>")
	)
	(segment
		(start 344.76309 -64.789304)
		(end 343.964514 -64.619632)
		(width 0.1143)
		(layer "F.Cu")
		(net "P3E_CPU0_PE2_SS_TXN<2>")
	)
	(segment
		(start 386.390388 -37.304726)
		(end 386.93725 -39.992554)
		(width 0.1143)
		(layer "F.Cu")
		(net "P3E_CPU0_PE2_SS_TXN<2>")
	)
	(segment
		(start 363.445044 -56.855614)
		(end 360.956606 -60.393326)
		(width 0.1143)
		(layer "F.Cu")
		(net "P3E_CPU0_PE2_SS_TXN<2>")
	)
	(segment
		(start 309.178452 -88.223852)
		(end 309.153052 -88.198452)
		(width 0.0889)
		(layer "F.Cu")
		(net "P3E_CPU0_PE2_SS_TXN<2>")
	)
	(segment
		(start 349.639636 -64.769492)
		(end 348.443804 -64.515238)
		(width 0.1143)
		(layer "F.Cu")
		(net "P3E_CPU0_PE2_SS_TXN<2>")
	)
	(segment
		(start 358.412034 -65.155826)
		(end 355.593396 -65.710054)
		(width 0.1143)
		(layer "F.Cu")
		(net "P3E_CPU0_PE2_SS_TXN<2>")
	)
	(segment
		(start 309.20055 -88.223852)
		(end 309.178452 -88.223852)
		(width 0.0889)
		(layer "F.Cu")
		(net "P3E_CPU0_PE2_SS_TXN<2>")
	)
	(segment
		(start 333.2226 -68.49364)
		(end 324.00113 -74.736706)
		(width 0.1143)
		(layer "F.Cu")
		(net "P3E_CPU0_PE2_SS_TXN<2>")
	)
	(segment
		(start 388.637526 -28.075382)
		(end 388.985506 -29.581856)
		(width 0.1143)
		(layer "F.Cu")
		(net "P3E_CPU0_PE2_SS_TXN<2>")
	)
	(segment
		(start 308.175152 -88.198452)
		(end 308.086252 -88.287352)
		(width 0.0889)
		(layer "F.Cu")
		(net "P3E_CPU0_PE2_SS_TXN<2>")
	)
	(segment
		(start 351.049082 -64.470026)
		(end 349.639636 -64.769492)
		(width 0.1143)
		(layer "F.Cu")
		(net "P3E_CPU0_PE2_SS_TXN<2>")
	)
	(segment
		(start 396.257018 -17.429988)
		(end 394.908278 -17.703546)
		(width 0.1143)
		(layer "F.Cu")
		(net "P3E_CPU0_PE2_SS_TXN<2>")
	)
	(segment
		(start 391.934192 -20.969478)
		(end 391.480802 -21.061426)
		(width 0.1143)
		(layer "F.Cu")
		(net "P3E_CPU0_PE2_SS_TXN<2>")
	)
	(segment
		(start 360.03357 -63.933578)
		(end 358.412034 -65.155826)
		(width 0.1143)
		(layer "F.Cu")
		(net "P3E_CPU0_PE2_SS_TXN<2>")
	)
	(segment
		(start 388.9375 -24.236426)
		(end 388.624572 -25.591516)
		(width 0.1143)
		(layer "F.Cu")
		(net "P3E_CPU0_PE2_SS_TXN<2>")
	)
	(segment
		(start 391.480802 -21.061426)
		(end 390.213088 -20.803108)
		(width 0.1143)
		(layer "F.Cu")
		(net "P3E_CPU0_PE2_SS_TXN<2>")
	)
	(segment
		(start 307.819552 -88.287352)
		(end 307.730652 -88.198452)
		(width 0.0889)
		(layer "F.Cu")
		(net "P3E_CPU0_PE2_SS_TXN<2>")
	)
	(segment
		(start 324.00113 -74.736706)
		(end 319.215516 -81.617058)
		(width 0.1143)
		(layer "F.Cu")
		(net "P3E_CPU0_PE2_SS_TXN<2>")
	)
	(segment
		(start 386.704332 -34.118296)
		(end 386.871464 -34.939732)
		(width 0.1143)
		(layer "F.Cu")
		(net "P3E_CPU0_PE2_SS_TXN<2>")
	)
	(via
		(at 319.215516 -81.617058)
		(size 0.508)
		(drill 0.254)
		(layers "F.Cu" "B.Cu")
		(net "P3E_CPU0_PE2_SS_TXN<2>")
	)
	(arc
		(start 307.241702 -88.198452)
		(mid 307.074847 -88.23615)
		(end 306.940458 -88.341962)
		(width 0.0889)
		(layer "F.Cu")
		(net "P3E_CPU0_PE2_SS_TXN<2>")
	)
	(segment
		(start 393.949428 -21.711412)
		(end 396.164054 -18.362676)
		(width 0.1143)
		(layer "F.Cu")
		(net "P3E_CPU0_PE2_SS_TXN<1>")
	)
	(segment
		(start 391.917428 -36.838382)
		(end 392.848338 -32.193738)
		(width 0.1143)
		(layer "F.Cu")
		(net "P3E_CPU0_PE2_SS_TXN<1>")
	)
	(segment
		(start 406.240488 -12.607798)
		(end 406.52573 -12.417552)
		(width 0.1143)
		(layer "F.Cu")
		(net "P3E_CPU0_PE2_SS_TXN<1>")
	)
	(segment
		(start 406.969468 -12.258802)
		(end 407.001218 -12.100306)
		(width 0.1143)
		(layer "F.Cu")
		(net "P3E_CPU0_PE2_SS_TXN<1>")
	)
	(segment
		(start 310.02859 -88.994234)
		(end 307.23586 -88.994234)
		(width 0.0889)
		(layer "F.Cu")
		(net "P3E_CPU0_PE2_SS_TXN<1>")
	)
	(segment
		(start 361.564682 -60.988702)
		(end 364.202218 -57.235598)
		(width 0.1143)
		(layer "F.Cu")
		(net "P3E_CPU0_PE2_SS_TXN<1>")
	)
	(segment
		(start 406.208738 -12.766294)
		(end 406.240488 -12.607798)
		(width 0.1143)
		(layer "F.Cu")
		(net "P3E_CPU0_PE2_SS_TXN<1>")
	)
	(segment
		(start 347.181678 -65.527936)
		(end 348.436184 -65.26149)
		(width 0.1143)
		(layer "F.Cu")
		(net "P3E_CPU0_PE2_SS_TXN<1>")
	)
	(segment
		(start 386.811266 -43.543982)
		(end 389.050276 -43.093894)
		(width 0.1143)
		(layer "F.Cu")
		(net "P3E_CPU0_PE2_SS_TXN<1>")
	)
	(segment
		(start 377.20651 -49.544478)
		(end 378.599446 -49.896522)
		(width 0.1143)
		(layer "F.Cu")
		(net "P3E_CPU0_PE2_SS_TXN<1>")
	)
	(segment
		(start 321.102228 -80.228948)
		(end 317.672974 -85.164422)
		(width 0.1143)
		(layer "F.Cu")
		(net "P3E_CPU0_PE2_SS_TXN<1>")
	)
	(segment
		(start 360.673904 -64.405002)
		(end 361.564682 -60.988702)
		(width 0.1143)
		(layer "F.Cu")
		(net "P3E_CPU0_PE2_SS_TXN<1>")
	)
	(segment
		(start 392.535918 -26.401268)
		(end 392.536172 -26.401268)
		(width 0.1143)
		(layer "F.Cu")
		(net "P3E_CPU0_PE2_SS_TXN<1>")
	)
	(segment
		(start 364.202218 -57.235598)
		(end 374.515888 -50.252376)
		(width 0.1143)
		(layer "F.Cu")
		(net "P3E_CPU0_PE2_SS_TXN<1>")
	)
	(segment
		(start 310.195976 -88.910922)
		(end 310.02859 -88.994234)
		(width 0.0889)
		(layer "F.Cu")
		(net "P3E_CPU0_PE2_SS_TXN<1>")
	)
	(segment
		(start 404.906734 -13.634466)
		(end 406.208738 -12.766294)
		(width 0.1143)
		(layer "F.Cu")
		(net "P3E_CPU0_PE2_SS_TXN<1>")
	)
	(segment
		(start 339.721698 -66.22542)
		(end 343.96045 -65.371726)
		(width 0.1143)
		(layer "F.Cu")
		(net "P3E_CPU0_PE2_SS_TXN<1>")
	)
	(segment
		(start 333.5782 -69.134482)
		(end 339.721698 -66.22542)
		(width 0.1143)
		(layer "F.Cu")
		(net "P3E_CPU0_PE2_SS_TXN<1>")
	)
	(segment
		(start 348.436184 -65.26149)
		(end 349.652082 -65.519808)
		(width 0.1143)
		(layer "F.Cu")
		(net "P3E_CPU0_PE2_SS_TXN<1>")
	)
	(segment
		(start 390.793478 -41.917874)
		(end 392.076432 -39.979092)
		(width 0.1143)
		(layer "F.Cu")
		(net "P3E_CPU0_PE2_SS_TXN<1>")
	)
	(segment
		(start 406.684226 -12.449048)
		(end 406.969468 -12.258802)
		(width 0.1143)
		(layer "F.Cu")
		(net "P3E_CPU0_PE2_SS_TXN<1>")
	)
	(segment
		(start 355.565202 -66.49212)
		(end 358.730804 -65.86982)
		(width 0.1143)
		(layer "F.Cu")
		(net "P3E_CPU0_PE2_SS_TXN<1>")
	)
	(segment
		(start 350.972882 -65.239138)
		(end 355.565202 -66.49212)
		(width 0.1143)
		(layer "F.Cu")
		(net "P3E_CPU0_PE2_SS_TXN<1>")
	)
	(segment
		(start 407.944574 -11.229848)
		(end 407.631392 -10.916666)
		(width 0.1143)
		(layer "F.Cu")
		(net "P3E_CPU0_PE2_SS_TXN<1>")
	)
	(segment
		(start 392.848338 -32.193738)
		(end 392.411204 -30.045152)
		(width 0.1143)
		(layer "F.Cu")
		(net "P3E_CPU0_PE2_SS_TXN<1>")
	)
	(segment
		(start 392.076432 -39.979092)
		(end 392.316208 -38.800024)
		(width 0.1143)
		(layer "F.Cu")
		(net "P3E_CPU0_PE2_SS_TXN<1>")
	)
	(segment
		(start 407.444956 -11.94181)
		(end 407.561542 -11.864086)
		(width 0.1143)
		(layer "F.Cu")
		(net "P3E_CPU0_PE2_SS_TXN<1>")
	)
	(segment
		(start 374.515888 -50.252376)
		(end 377.20651 -49.544478)
		(width 0.1143)
		(layer "F.Cu")
		(net "P3E_CPU0_PE2_SS_TXN<1>")
	)
	(segment
		(start 358.730804 -65.86982)
		(end 360.673904 -64.405002)
		(width 0.1143)
		(layer "F.Cu")
		(net "P3E_CPU0_PE2_SS_TXN<1>")
	)
	(segment
		(start 392.536172 -26.401268)
		(end 393.949682 -21.711412)
		(width 0.1143)
		(layer "F.Cu")
		(net "P3E_CPU0_PE2_SS_TXN<1>")
	)
	(segment
		(start 407.561542 -11.864086)
		(end 407.952194 -11.391646)
		(width 0.1143)
		(layer "F.Cu")
		(net "P3E_CPU0_PE2_SS_TXN<1>")
	)
	(segment
		(start 349.652082 -65.519808)
		(end 350.972882 -65.239138)
		(width 0.1143)
		(layer "F.Cu")
		(net "P3E_CPU0_PE2_SS_TXN<1>")
	)
	(segment
		(start 310.207152 -88.876886)
		(end 310.195976 -88.910922)
		(width 0.0889)
		(layer "F.Cu")
		(net "P3E_CPU0_PE2_SS_TXN<1>")
	)
	(segment
		(start 406.52573 -12.417552)
		(end 406.684226 -12.449048)
		(width 0.1143)
		(layer "F.Cu")
		(net "P3E_CPU0_PE2_SS_TXN<1>")
	)
	(segment
		(start 396.164054 -18.362676)
		(end 402.617432 -14.09192)
		(width 0.1143)
		(layer "F.Cu")
		(net "P3E_CPU0_PE2_SS_TXN<1>")
	)
	(segment
		(start 402.617432 -14.09192)
		(end 404.906734 -13.634466)
		(width 0.1143)
		(layer "F.Cu")
		(net "P3E_CPU0_PE2_SS_TXN<1>")
	)
	(segment
		(start 344.762582 -65.54216)
		(end 346.00515 -65.278254)
		(width 0.1143)
		(layer "F.Cu")
		(net "P3E_CPU0_PE2_SS_TXN<1>")
	)
	(segment
		(start 378.599446 -49.896522)
		(end 381.183642 -49.295304)
		(width 0.1143)
		(layer "F.Cu")
		(net "P3E_CPU0_PE2_SS_TXN<1>")
	)
	(segment
		(start 346.00515 -65.278254)
		(end 347.181678 -65.527936)
		(width 0.1143)
		(layer "F.Cu")
		(net "P3E_CPU0_PE2_SS_TXN<1>")
	)
	(segment
		(start 317.672974 -85.164422)
		(end 317.672974 -85.164676)
		(width 0.1143)
		(layer "F.Cu")
		(net "P3E_CPU0_PE2_SS_TXN<1>")
	)
	(segment
		(start 305.84775 -89.319608)
		(end 305.82108 -89.419176)
		(width 0.0889)
		(layer "F.Cu")
		(net "P3E_CPU0_PE2_SS_TXN<1>")
	)
	(segment
		(start 392.887962 -27.702256)
		(end 392.888216 -27.702256)
		(width 0.1143)
		(layer "F.Cu")
		(net "P3E_CPU0_PE2_SS_TXN<1>")
	)
	(segment
		(start 392.316208 -38.800024)
		(end 391.917428 -36.838382)
		(width 0.1143)
		(layer "F.Cu")
		(net "P3E_CPU0_PE2_SS_TXN<1>")
	)
	(segment
		(start 389.050276 -43.093894)
		(end 390.793478 -41.917874)
		(width 0.1143)
		(layer "F.Cu")
		(net "P3E_CPU0_PE2_SS_TXN<1>")
	)
	(segment
		(start 392.411204 -30.045152)
		(end 392.887962 -27.702256)
		(width 0.1143)
		(layer "F.Cu")
		(net "P3E_CPU0_PE2_SS_TXN<1>")
	)
	(segment
		(start 321.102228 -80.228948)
		(end 324.548754 -75.268836)
		(width 0.1143)
		(layer "F.Cu")
		(net "P3E_CPU0_PE2_SS_TXN<1>")
	)
	(segment
		(start 305.82108 -89.419176)
		(end 305.533806 -89.584784)
		(width 0.0889)
		(layer "F.Cu")
		(net "P3E_CPU0_PE2_SS_TXN<1>")
	)
	(segment
		(start 392.888216 -27.702256)
		(end 392.535918 -26.401268)
		(width 0.1143)
		(layer "F.Cu")
		(net "P3E_CPU0_PE2_SS_TXN<1>")
	)
	(segment
		(start 343.96045 -65.371726)
		(end 344.762582 -65.54216)
		(width 0.1143)
		(layer "F.Cu")
		(net "P3E_CPU0_PE2_SS_TXN<1>")
	)
	(segment
		(start 383.406904 -46.309534)
		(end 386.811266 -43.543982)
		(width 0.1143)
		(layer "F.Cu")
		(net "P3E_CPU0_PE2_SS_TXN<1>")
	)
	(segment
		(start 381.183642 -49.295304)
		(end 383.406904 -46.309534)
		(width 0.1143)
		(layer "F.Cu")
		(net "P3E_CPU0_PE2_SS_TXN<1>")
	)
	(segment
		(start 317.672974 -85.164676)
		(end 310.226964 -88.867234)
		(width 0.1143)
		(layer "F.Cu")
		(net "P3E_CPU0_PE2_SS_TXN<1>")
	)
	(segment
		(start 310.226964 -88.867234)
		(end 310.207152 -88.876886)
		(width 0.0889)
		(layer "F.Cu")
		(net "P3E_CPU0_PE2_SS_TXN<1>")
	)
	(segment
		(start 407.001218 -12.100306)
		(end 407.28646 -11.91006)
		(width 0.1143)
		(layer "F.Cu")
		(net "P3E_CPU0_PE2_SS_TXN<1>")
	)
	(segment
		(start 393.949682 -21.711412)
		(end 393.949428 -21.711412)
		(width 0.1143)
		(layer "F.Cu")
		(net "P3E_CPU0_PE2_SS_TXN<1>")
	)
	(segment
		(start 407.952194 -11.391646)
		(end 407.944574 -11.229848)
		(width 0.1143)
		(layer "F.Cu")
		(net "P3E_CPU0_PE2_SS_TXN<1>")
	)
	(segment
		(start 324.548754 -75.268836)
		(end 333.5782 -69.134482)
		(width 0.1143)
		(layer "F.Cu")
		(net "P3E_CPU0_PE2_SS_TXN<1>")
	)
	(segment
		(start 407.28646 -11.91006)
		(end 407.444956 -11.94181)
		(width 0.1143)
		(layer "F.Cu")
		(net "P3E_CPU0_PE2_SS_TXN<1>")
	)
	(via
		(at 321.102228 -80.228948)
		(size 0.508)
		(drill 0.254)
		(layers "F.Cu" "B.Cu")
		(net "P3E_CPU0_PE2_SS_TXN<1>")
	)
	(arc
		(start 307.23586 -88.994234)
		(mid 307.044218 -88.937068)
		(end 306.904136 -88.794336)
		(width 0.0889)
		(layer "F.Cu")
		(net "P3E_CPU0_PE2_SS_TXN<1>")
	)
	(arc
		(start 306.904136 -88.794336)
		(mid 306.138801 -88.555943)
		(end 305.839876 -89.299796)
		(width 0.0889)
		(layer "F.Cu")
		(net "P3E_CPU0_PE2_SS_TXN<1>")
	)
	(arc
		(start 305.839876 -89.299796)
		(mid 305.843723 -89.309738)
		(end 305.84775 -89.319608)
		(width 0.0889)
		(layer "F.Cu")
		(net "P3E_CPU0_PE2_SS_TXN<1>")
	)
	(segment
		(start 356.780592 -37.592)
		(end 357.475282 -40.469312)
		(width 0.1143)
		(layer "F.Cu")
		(net "P3E_CPU0_PE2_SS_TXN<15>")
	)
	(segment
		(start 360.741468 -24.230838)
		(end 360.073956 -26.48331)
		(width 0.1143)
		(layer "F.Cu")
		(net "P3E_CPU0_PE2_SS_TXN<15>")
	)
	(segment
		(start 361.051348 -16.671036)
		(end 360.38536 -19.80946)
		(width 0.1143)
		(layer "F.Cu")
		(net "P3E_CPU0_PE2_SS_TXN<15>")
	)
	(segment
		(start 313.036712 -66.341244)
		(end 307.885338 -73.560686)
		(width 0.1143)
		(layer "F.Cu")
		(net "P3E_CPU0_PE2_SS_TXN<15>")
	)
	(segment
		(start 321.3608 -56.94934)
		(end 316.601094 -63.869824)
		(width 0.1143)
		(layer "F.Cu")
		(net "P3E_CPU0_PE2_SS_TXN<15>")
	)
	(segment
		(start 362.841794 -12.663424)
		(end 361.051348 -16.670782)
		(width 0.1143)
		(layer "F.Cu")
		(net "P3E_CPU0_PE2_SS_TXN<15>")
	)
	(segment
		(start 352.903028 -45.296582)
		(end 349.725996 -45.93209)
		(width 0.1143)
		(layer "F.Cu")
		(net "P3E_CPU0_PE2_SS_TXN<15>")
	)
	(segment
		(start 360.073702 -26.48331)
		(end 356.780592 -37.592)
		(width 0.1143)
		(layer "F.Cu")
		(net "P3E_CPU0_PE2_SS_TXN<15>")
	)
	(segment
		(start 323.39915 -53.985668)
		(end 321.3608 -56.94934)
		(width 0.1143)
		(layer "F.Cu")
		(net "P3E_CPU0_PE2_SS_TXN<15>")
	)
	(segment
		(start 357.04526 -42.491406)
		(end 352.903028 -45.296582)
		(width 0.1143)
		(layer "F.Cu")
		(net "P3E_CPU0_PE2_SS_TXN<15>")
	)
	(segment
		(start 306.496466 -75.316334)
		(end 305.519328 -75.316334)
		(width 0.0889)
		(layer "F.Cu")
		(net "P3E_CPU0_PE2_SS_TXN<15>")
	)
	(segment
		(start 347.7006 -45.52696)
		(end 343.6239 -46.3423)
		(width 0.1143)
		(layer "F.Cu")
		(net "P3E_CPU0_PE2_SS_TXN<15>")
	)
	(segment
		(start 307.837332 -73.584562)
		(end 306.84597 -74.977244)
		(width 0.0889)
		(layer "F.Cu")
		(net "P3E_CPU0_PE2_SS_TXN<15>")
	)
	(segment
		(start 339.089746 -46.31944)
		(end 337.189064 -45.939202)
		(width 0.1143)
		(layer "F.Cu")
		(net "P3E_CPU0_PE2_SS_TXN<15>")
	)
	(segment
		(start 325.101712 -52.656232)
		(end 323.39915 -53.985668)
		(width 0.1143)
		(layer "F.Cu")
		(net "P3E_CPU0_PE2_SS_TXN<15>")
	)
	(segment
		(start 349.725996 -45.93209)
		(end 347.7006 -45.52696)
		(width 0.1143)
		(layer "F.Cu")
		(net "P3E_CPU0_PE2_SS_TXN<15>")
	)
	(segment
		(start 363.165644 -10.916158)
		(end 362.841794 -11.240008)
		(width 0.1143)
		(layer "F.Cu")
		(net "P3E_CPU0_PE2_SS_TXN<15>")
	)
	(segment
		(start 307.885338 -73.560686)
		(end 307.837332 -73.584562)
		(width 0.0889)
		(layer "F.Cu")
		(net "P3E_CPU0_PE2_SS_TXN<15>")
	)
	(segment
		(start 362.841794 -11.240008)
		(end 362.841794 -12.663424)
		(width 0.1143)
		(layer "F.Cu")
		(net "P3E_CPU0_PE2_SS_TXN<15>")
	)
	(segment
		(start 316.601094 -63.869824)
		(end 313.036712 -66.341244)
		(width 0.1143)
		(layer "F.Cu")
		(net "P3E_CPU0_PE2_SS_TXN<15>")
	)
	(segment
		(start 331.193394 -47.900336)
		(end 325.101712 -52.656232)
		(width 0.1143)
		(layer "F.Cu")
		(net "P3E_CPU0_PE2_SS_TXN<15>")
	)
	(segment
		(start 337.189064 -45.939202)
		(end 331.193394 -47.900336)
		(width 0.1143)
		(layer "F.Cu")
		(net "P3E_CPU0_PE2_SS_TXN<15>")
	)
	(segment
		(start 343.6239 -46.3423)
		(end 341.2998 -45.87748)
		(width 0.1143)
		(layer "F.Cu")
		(net "P3E_CPU0_PE2_SS_TXN<15>")
	)
	(segment
		(start 361.051348 -16.670782)
		(end 361.051348 -16.671036)
		(width 0.1143)
		(layer "F.Cu")
		(net "P3E_CPU0_PE2_SS_TXN<15>")
	)
	(segment
		(start 341.2998 -45.87748)
		(end 339.089746 -46.31944)
		(width 0.1143)
		(layer "F.Cu")
		(net "P3E_CPU0_PE2_SS_TXN<15>")
	)
	(segment
		(start 360.69524 -21.268182)
		(end 360.403394 -22.642576)
		(width 0.1143)
		(layer "F.Cu")
		(net "P3E_CPU0_PE2_SS_TXN<15>")
	)
	(segment
		(start 357.475282 -40.469312)
		(end 357.04526 -42.491406)
		(width 0.1143)
		(layer "F.Cu")
		(net "P3E_CPU0_PE2_SS_TXN<15>")
	)
	(segment
		(start 360.073956 -26.48331)
		(end 360.073702 -26.48331)
		(width 0.1143)
		(layer "F.Cu")
		(net "P3E_CPU0_PE2_SS_TXN<15>")
	)
	(segment
		(start 303.988978 -76.282042)
		(end 303.816766 -76.706984)
		(width 0.0889)
		(layer "F.Cu")
		(net "P3E_CPU0_PE2_SS_TXN<15>")
	)
	(segment
		(start 360.403394 -22.642576)
		(end 360.569002 -23.420324)
		(width 0.1143)
		(layer "F.Cu")
		(net "P3E_CPU0_PE2_SS_TXN<15>")
	)
	(segment
		(start 360.569002 -23.420324)
		(end 360.741468 -24.230838)
		(width 0.1143)
		(layer "F.Cu")
		(net "P3E_CPU0_PE2_SS_TXN<15>")
	)
	(segment
		(start 306.84597 -74.977244)
		(end 306.496466 -75.316334)
		(width 0.0889)
		(layer "F.Cu")
		(net "P3E_CPU0_PE2_SS_TXN<15>")
	)
	(segment
		(start 360.38536 -19.80946)
		(end 360.69524 -21.268182)
		(width 0.1143)
		(layer "F.Cu")
		(net "P3E_CPU0_PE2_SS_TXN<15>")
	)
	(segment
		(start 304.693066 -75.811888)
		(end 304.6603 -75.811888)
		(width 0.0889)
		(layer "F.Cu")
		(net "P3E_CPU0_PE2_SS_TXN<15>")
	)
	(via
		(at 325.101712 -52.656232)
		(size 0.508)
		(drill 0.254)
		(layers "F.Cu" "B.Cu")
		(net "P3E_CPU0_PE2_SS_TXN<15>")
	)
	(arc
		(start 305.187096 -75.516486)
		(mid 304.978488 -75.728418)
		(end 304.693066 -75.811888)
		(width 0.0889)
		(layer "F.Cu")
		(net "P3E_CPU0_PE2_SS_TXN<15>")
	)
	(arc
		(start 304.039778 -76.264008)
		(mid 304.014585 -76.273608)
		(end 303.988978 -76.282042)
		(width 0.0889)
		(layer "F.Cu")
		(net "P3E_CPU0_PE2_SS_TXN<15>")
	)
	(arc
		(start 304.328576 -76.011786)
		(mid 304.205201 -76.161968)
		(end 304.039778 -76.264008)
		(width 0.0889)
		(layer "F.Cu")
		(net "P3E_CPU0_PE2_SS_TXN<15>")
	)
	(arc
		(start 304.6603 -75.811888)
		(mid 304.468658 -75.869054)
		(end 304.328576 -76.011786)
		(width 0.0889)
		(layer "F.Cu")
		(net "P3E_CPU0_PE2_SS_TXN<15>")
	)
	(arc
		(start 305.519328 -75.316334)
		(mid 305.327311 -75.373442)
		(end 305.187096 -75.516486)
		(width 0.0889)
		(layer "F.Cu")
		(net "P3E_CPU0_PE2_SS_TXN<15>")
	)
	(segment
		(start 358.237536 -40.41648)
		(end 357.565198 -37.627306)
		(width 0.1143)
		(layer "F.Cu")
		(net "P3E_CPU0_PE2_SS_TXN<14>")
	)
	(segment
		(start 361.526582 -24.26208)
		(end 361.526836 -24.261318)
		(width 0.1143)
		(layer "F.Cu")
		(net "P3E_CPU0_PE2_SS_TXN<14>")
	)
	(segment
		(start 306.770532 -76.116434)
		(end 307.304694 -75.682094)
		(width 0.0889)
		(layer "F.Cu")
		(net "P3E_CPU0_PE2_SS_TXN<14>")
	)
	(segment
		(start 364.924594 -12.187174)
		(end 364.924594 -11.240008)
		(width 0.1143)
		(layer "F.Cu")
		(net "P3E_CPU0_PE2_SS_TXN<14>")
	)
	(segment
		(start 313.552078 -66.879978)
		(end 317.139828 -64.392048)
		(width 0.1143)
		(layer "F.Cu")
		(net "P3E_CPU0_PE2_SS_TXN<14>")
	)
	(segment
		(start 361.164378 -19.809714)
		(end 361.804458 -16.790416)
		(width 0.1143)
		(layer "F.Cu")
		(net "P3E_CPU0_PE2_SS_TXN<14>")
	)
	(segment
		(start 352.99269 -46.115986)
		(end 357.72852 -42.90949)
		(width 0.1143)
		(layer "F.Cu")
		(net "P3E_CPU0_PE2_SS_TXN<14>")
	)
	(segment
		(start 339.102954 -47.066454)
		(end 339.102954 -47.0662)
		(width 0.1143)
		(layer "F.Cu")
		(net "P3E_CPU0_PE2_SS_TXN<14>")
	)
	(segment
		(start 307.44795 -75.436984)
		(end 313.551824 -66.879978)
		(width 0.1143)
		(layer "F.Cu")
		(net "P3E_CPU0_PE2_SS_TXN<14>")
	)
	(segment
		(start 304.675286 -76.211938)
		(end 304.96256 -76.377546)
		(width 0.0889)
		(layer "F.Cu")
		(net "P3E_CPU0_PE2_SS_TXN<14>")
	)
	(segment
		(start 361.182412 -22.642322)
		(end 361.474258 -21.268182)
		(width 0.1143)
		(layer "F.Cu")
		(net "P3E_CPU0_PE2_SS_TXN<14>")
	)
	(segment
		(start 304.96256 -76.377546)
		(end 305.062382 -76.350622)
		(width 0.0889)
		(layer "F.Cu")
		(net "P3E_CPU0_PE2_SS_TXN<14>")
	)
	(segment
		(start 313.551824 -66.879978)
		(end 313.552078 -66.879978)
		(width 0.1143)
		(layer "F.Cu")
		(net "P3E_CPU0_PE2_SS_TXN<14>")
	)
	(segment
		(start 347.707966 -46.29531)
		(end 349.90405 -46.734476)
		(width 0.1143)
		(layer "F.Cu")
		(net "P3E_CPU0_PE2_SS_TXN<14>")
	)
	(segment
		(start 349.90405 -46.734476)
		(end 352.99269 -46.115986)
		(width 0.1143)
		(layer "F.Cu")
		(net "P3E_CPU0_PE2_SS_TXN<14>")
	)
	(segment
		(start 361.474258 -21.268182)
		(end 361.164378 -19.809714)
		(width 0.1143)
		(layer "F.Cu")
		(net "P3E_CPU0_PE2_SS_TXN<14>")
	)
	(segment
		(start 305.516026 -76.116434)
		(end 306.770532 -76.116434)
		(width 0.0889)
		(layer "F.Cu")
		(net "P3E_CPU0_PE2_SS_TXN<14>")
	)
	(segment
		(start 337.250024 -46.695868)
		(end 339.102954 -47.066454)
		(width 0.1143)
		(layer "F.Cu")
		(net "P3E_CPU0_PE2_SS_TXN<14>")
	)
	(segment
		(start 307.441346 -75.49007)
		(end 307.44795 -75.436984)
		(width 0.0889)
		(layer "F.Cu")
		(net "P3E_CPU0_PE2_SS_TXN<14>")
	)
	(segment
		(start 357.565198 -37.627306)
		(end 361.526582 -24.26208)
		(width 0.1143)
		(layer "F.Cu")
		(net "P3E_CPU0_PE2_SS_TXN<14>")
	)
	(segment
		(start 343.6874 -47.099474)
		(end 347.707966 -46.29531)
		(width 0.1143)
		(layer "F.Cu")
		(net "P3E_CPU0_PE2_SS_TXN<14>")
	)
	(segment
		(start 363.877352 -13.278358)
		(end 364.038896 -13.278104)
		(width 0.1143)
		(layer "F.Cu")
		(net "P3E_CPU0_PE2_SS_TXN<14>")
	)
	(segment
		(start 341.3125 -46.624494)
		(end 343.6874 -47.099474)
		(width 0.1143)
		(layer "F.Cu")
		(net "P3E_CPU0_PE2_SS_TXN<14>")
	)
	(segment
		(start 357.72852 -42.90949)
		(end 358.237536 -40.41648)
		(width 0.1143)
		(layer "F.Cu")
		(net "P3E_CPU0_PE2_SS_TXN<14>")
	)
	(segment
		(start 329.332844 -50.457862)
		(end 331.915516 -48.441356)
		(width 0.1143)
		(layer "F.Cu")
		(net "P3E_CPU0_PE2_SS_TXN<14>")
	)
	(segment
		(start 364.924594 -11.240008)
		(end 364.600744 -10.916158)
		(width 0.1143)
		(layer "F.Cu")
		(net "P3E_CPU0_PE2_SS_TXN<14>")
	)
	(segment
		(start 339.102954 -47.0662)
		(end 341.3125 -46.624494)
		(width 0.1143)
		(layer "F.Cu")
		(net "P3E_CPU0_PE2_SS_TXN<14>")
	)
	(segment
		(start 361.526836 -24.261064)
		(end 361.182412 -22.642322)
		(width 0.1143)
		(layer "F.Cu")
		(net "P3E_CPU0_PE2_SS_TXN<14>")
	)
	(segment
		(start 363.634782 -13.520674)
		(end 363.877352 -13.278358)
		(width 0.1143)
		(layer "F.Cu")
		(net "P3E_CPU0_PE2_SS_TXN<14>")
	)
	(segment
		(start 331.915516 -48.441356)
		(end 337.250024 -46.695868)
		(width 0.1143)
		(layer "F.Cu")
		(net "P3E_CPU0_PE2_SS_TXN<14>")
	)
	(segment
		(start 307.304694 -75.682094)
		(end 307.441346 -75.49007)
		(width 0.0889)
		(layer "F.Cu")
		(net "P3E_CPU0_PE2_SS_TXN<14>")
	)
	(segment
		(start 361.526836 -24.261318)
		(end 361.526836 -24.261064)
		(width 0.1143)
		(layer "F.Cu")
		(net "P3E_CPU0_PE2_SS_TXN<14>")
	)
	(segment
		(start 363.634782 -13.682472)
		(end 363.634782 -13.520674)
		(width 0.1143)
		(layer "F.Cu")
		(net "P3E_CPU0_PE2_SS_TXN<14>")
	)
	(segment
		(start 363.161072 -14.156182)
		(end 363.634782 -13.682472)
		(width 0.1143)
		(layer "F.Cu")
		(net "P3E_CPU0_PE2_SS_TXN<14>")
	)
	(segment
		(start 364.779052 -12.537948)
		(end 364.924594 -12.187174)
		(width 0.1143)
		(layer "F.Cu")
		(net "P3E_CPU0_PE2_SS_TXN<14>")
	)
	(segment
		(start 317.139828 -64.392048)
		(end 323.69633 -54.859174)
		(width 0.1143)
		(layer "F.Cu")
		(net "P3E_CPU0_PE2_SS_TXN<14>")
	)
	(segment
		(start 364.038896 -13.278104)
		(end 364.779052 -12.537948)
		(width 0.1143)
		(layer "F.Cu")
		(net "P3E_CPU0_PE2_SS_TXN<14>")
	)
	(segment
		(start 323.696584 -54.859174)
		(end 329.332844 -50.457862)
		(width 0.1143)
		(layer "F.Cu")
		(net "P3E_CPU0_PE2_SS_TXN<14>")
	)
	(segment
		(start 323.69633 -54.859174)
		(end 323.696584 -54.859174)
		(width 0.1143)
		(layer "F.Cu")
		(net "P3E_CPU0_PE2_SS_TXN<14>")
	)
	(segment
		(start 361.804458 -16.790416)
		(end 363.161072 -14.156182)
		(width 0.1143)
		(layer "F.Cu")
		(net "P3E_CPU0_PE2_SS_TXN<14>")
	)
	(via
		(at 329.332844 -50.457862)
		(size 0.508)
		(drill 0.254)
		(layers "F.Cu" "B.Cu")
		(net "P3E_CPU0_PE2_SS_TXN<14>")
	)
	(arc
		(start 305.062382 -76.350622)
		(mid 305.262608 -76.182023)
		(end 305.516026 -76.116434)
		(width 0.0889)
		(layer "F.Cu")
		(net "P3E_CPU0_PE2_SS_TXN<14>")
	)
	(segment
		(start 325.214488 -55.253382)
		(end 318.609726 -64.856614)
		(width 0.1143)
		(layer "F.Cu")
		(net "P3E_CPU0_PE2_SS_TXN<13>")
	)
	(segment
		(start 358.833928 -37.725096)
		(end 359.503218 -40.496744)
		(width 0.1143)
		(layer "F.Cu")
		(net "P3E_CPU0_PE2_SS_TXN<13>")
	)
	(segment
		(start 314.395104 -67.778884)
		(end 308.374034 -76.219304)
		(width 0.1143)
		(layer "F.Cu")
		(net "P3E_CPU0_PE2_SS_TXN<13>")
	)
	(segment
		(start 337.343242 -47.95139)
		(end 332.562708 -49.515268)
		(width 0.1143)
		(layer "F.Cu")
		(net "P3E_CPU0_PE2_SS_TXN<13>")
	)
	(segment
		(start 332.562708 -49.515268)
		(end 331.126338 -50.636932)
		(width 0.1143)
		(layer "F.Cu")
		(net "P3E_CPU0_PE2_SS_TXN<13>")
	)
	(segment
		(start 362.454952 -22.642068)
		(end 362.810044 -24.312372)
		(width 0.1143)
		(layer "F.Cu")
		(net "P3E_CPU0_PE2_SS_TXN<13>")
	)
	(segment
		(start 343.5985 -48.3489)
		(end 341.286846 -47.88662)
		(width 0.1143)
		(layer "F.Cu")
		(net "P3E_CPU0_PE2_SS_TXN<13>")
	)
	(segment
		(start 339.153754 -48.31334)
		(end 337.343242 -47.95139)
		(width 0.1143)
		(layer "F.Cu")
		(net "P3E_CPU0_PE2_SS_TXN<13>")
	)
	(segment
		(start 364.850426 -14.386052)
		(end 364.264956 -14.773148)
		(width 0.1143)
		(layer "F.Cu")
		(net "P3E_CPU0_PE2_SS_TXN<13>")
	)
	(segment
		(start 364.850426 -14.385544)
		(end 364.850426 -14.386052)
		(width 0.1143)
		(layer "F.Cu")
		(net "P3E_CPU0_PE2_SS_TXN<13>")
	)
	(segment
		(start 307.1622 -77.285342)
		(end 307.138832 -77.297534)
		(width 0.0889)
		(layer "F.Cu")
		(net "P3E_CPU0_PE2_SS_TXN<13>")
	)
	(segment
		(start 307.6956 -77.007974)
		(end 307.1622 -77.285342)
		(width 0.0889)
		(layer "F.Cu")
		(net "P3E_CPU0_PE2_SS_TXN<13>")
	)
	(segment
		(start 353.405948 -47.324264)
		(end 349.967296 -48.01235)
		(width 0.1143)
		(layer "F.Cu")
		(net "P3E_CPU0_PE2_SS_TXN<13>")
	)
	(segment
		(start 364.264956 -14.773148)
		(end 362.972096 -17.284192)
		(width 0.1143)
		(layer "F.Cu")
		(net "P3E_CPU0_PE2_SS_TXN<13>")
	)
	(segment
		(start 318.609726 -64.856614)
		(end 314.395104 -67.778884)
		(width 0.1143)
		(layer "F.Cu")
		(net "P3E_CPU0_PE2_SS_TXN<13>")
	)
	(segment
		(start 331.126084 -50.636932)
		(end 331.126084 -50.63744)
		(width 0.1143)
		(layer "F.Cu")
		(net "P3E_CPU0_PE2_SS_TXN<13>")
	)
	(segment
		(start 304.693066 -77.793088)
		(end 304.657506 -77.793088)
		(width 0.0889)
		(layer "F.Cu")
		(net "P3E_CPU0_PE2_SS_TXN<13>")
	)
	(segment
		(start 359.503218 -40.496744)
		(end 358.848152 -43.69562)
		(width 0.1143)
		(layer "F.Cu")
		(net "P3E_CPU0_PE2_SS_TXN<13>")
	)
	(segment
		(start 347.6244 -47.54372)
		(end 343.5985 -48.3489)
		(width 0.1143)
		(layer "F.Cu")
		(net "P3E_CPU0_PE2_SS_TXN<13>")
	)
	(segment
		(start 331.126084 -50.63744)
		(end 325.214488 -55.253382)
		(width 0.1143)
		(layer "F.Cu")
		(net "P3E_CPU0_PE2_SS_TXN<13>")
	)
	(segment
		(start 349.967296 -48.01235)
		(end 347.6244 -47.54372)
		(width 0.1143)
		(layer "F.Cu")
		(net "P3E_CPU0_PE2_SS_TXN<13>")
	)
	(segment
		(start 331.126338 -50.636932)
		(end 331.126084 -50.636932)
		(width 0.1143)
		(layer "F.Cu")
		(net "P3E_CPU0_PE2_SS_TXN<13>")
	)
	(segment
		(start 308.374034 -76.219304)
		(end 308.326282 -76.24318)
		(width 0.0889)
		(layer "F.Cu")
		(net "P3E_CPU0_PE2_SS_TXN<13>")
	)
	(segment
		(start 308.103778 -76.5556)
		(end 307.832506 -76.936854)
		(width 0.0889)
		(layer "F.Cu")
		(net "P3E_CPU0_PE2_SS_TXN<13>")
	)
	(segment
		(start 308.104032 -76.5556)
		(end 308.103778 -76.5556)
		(width 0.0889)
		(layer "F.Cu")
		(net "P3E_CPU0_PE2_SS_TXN<13>")
	)
	(segment
		(start 308.326282 -76.24318)
		(end 308.104032 -76.5556)
		(width 0.0889)
		(layer "F.Cu")
		(net "P3E_CPU0_PE2_SS_TXN<13>")
	)
	(segment
		(start 362.746798 -21.268182)
		(end 362.454952 -22.642068)
		(width 0.1143)
		(layer "F.Cu")
		(net "P3E_CPU0_PE2_SS_TXN<13>")
	)
	(segment
		(start 362.436664 -19.80946)
		(end 362.746798 -21.268182)
		(width 0.1143)
		(layer "F.Cu")
		(net "P3E_CPU0_PE2_SS_TXN<13>")
	)
	(segment
		(start 362.972096 -17.284192)
		(end 362.436664 -19.80946)
		(width 0.1143)
		(layer "F.Cu")
		(net "P3E_CPU0_PE2_SS_TXN<13>")
	)
	(segment
		(start 307.832506 -76.936854)
		(end 307.6956 -77.007974)
		(width 0.0889)
		(layer "F.Cu")
		(net "P3E_CPU0_PE2_SS_TXN<13>")
	)
	(segment
		(start 362.810044 -24.312372)
		(end 358.833928 -37.725096)
		(width 0.1143)
		(layer "F.Cu")
		(net "P3E_CPU0_PE2_SS_TXN<13>")
	)
	(segment
		(start 367.966244 -10.916158)
		(end 367.642394 -11.240008)
		(width 0.1143)
		(layer "F.Cu")
		(net "P3E_CPU0_PE2_SS_TXN<13>")
	)
	(segment
		(start 307.138832 -77.297534)
		(end 305.52263 -77.297534)
		(width 0.0889)
		(layer "F.Cu")
		(net "P3E_CPU0_PE2_SS_TXN<13>")
	)
	(segment
		(start 358.848152 -43.69562)
		(end 353.405948 -47.324264)
		(width 0.1143)
		(layer "F.Cu")
		(net "P3E_CPU0_PE2_SS_TXN<13>")
	)
	(segment
		(start 367.337594 -12.739624)
		(end 364.850426 -14.385544)
		(width 0.1143)
		(layer "F.Cu")
		(net "P3E_CPU0_PE2_SS_TXN<13>")
	)
	(segment
		(start 367.642394 -12.047728)
		(end 367.337594 -12.739624)
		(width 0.1143)
		(layer "F.Cu")
		(net "P3E_CPU0_PE2_SS_TXN<13>")
	)
	(segment
		(start 341.286846 -47.88662)
		(end 339.153754 -48.31334)
		(width 0.1143)
		(layer "F.Cu")
		(net "P3E_CPU0_PE2_SS_TXN<13>")
	)
	(segment
		(start 367.642394 -11.240008)
		(end 367.642394 -12.047728)
		(width 0.1143)
		(layer "F.Cu")
		(net "P3E_CPU0_PE2_SS_TXN<13>")
	)
	(via
		(at 331.126084 -50.636932)
		(size 0.508)
		(drill 0.254)
		(layers "F.Cu" "B.Cu")
		(net "P3E_CPU0_PE2_SS_TXN<13>")
	)
	(arc
		(start 304.657506 -77.793088)
		(mid 304.234433 -77.769135)
		(end 303.816766 -77.697584)
		(width 0.0889)
		(layer "F.Cu")
		(net "P3E_CPU0_PE2_SS_TXN<13>")
	)
	(arc
		(start 305.187096 -77.497686)
		(mid 304.978488 -77.709618)
		(end 304.693066 -77.793088)
		(width 0.0889)
		(layer "F.Cu")
		(net "P3E_CPU0_PE2_SS_TXN<13>")
	)
	(arc
		(start 305.52263 -77.297534)
		(mid 305.32878 -77.353884)
		(end 305.187096 -77.497686)
		(width 0.0889)
		(layer "F.Cu")
		(net "P3E_CPU0_PE2_SS_TXN<13>")
	)
	(segment
		(start 359.871518 -37.755322)
		(end 363.844332 -24.35352)
		(width 0.1143)
		(layer "F.Cu")
		(net "P3E_CPU0_PE2_SS_TXN<12>")
	)
	(segment
		(start 308.715156 -77.427328)
		(end 315.094366 -68.484242)
		(width 0.1143)
		(layer "F.Cu")
		(net "P3E_CPU0_PE2_SS_TXN<12>")
	)
	(segment
		(start 341.2617 -48.90262)
		(end 343.5223 -49.35474)
		(width 0.1143)
		(layer "F.Cu")
		(net "P3E_CPU0_PE2_SS_TXN<12>")
	)
	(segment
		(start 308.667912 -77.45095)
		(end 308.715156 -77.427328)
		(width 0.0889)
		(layer "F.Cu")
		(net "P3E_CPU0_PE2_SS_TXN<12>")
	)
	(segment
		(start 363.480604 -22.642068)
		(end 363.77245 -21.268182)
		(width 0.1143)
		(layer "F.Cu")
		(net "P3E_CPU0_PE2_SS_TXN<12>")
	)
	(segment
		(start 363.945932 -17.530572)
		(end 364.867444 -15.739872)
		(width 0.1143)
		(layer "F.Cu")
		(net "P3E_CPU0_PE2_SS_TXN<12>")
	)
	(segment
		(start 359.744772 -44.267374)
		(end 360.523028 -40.45712)
		(width 0.1143)
		(layer "F.Cu")
		(net "P3E_CPU0_PE2_SS_TXN<12>")
	)
	(segment
		(start 353.87661 -48.234092)
		(end 359.744772 -44.267374)
		(width 0.1143)
		(layer "F.Cu")
		(net "P3E_CPU0_PE2_SS_TXN<12>")
	)
	(segment
		(start 325.861426 -56.020208)
		(end 333.095092 -50.372772)
		(width 0.1143)
		(layer "F.Cu")
		(net "P3E_CPU0_PE2_SS_TXN<12>")
	)
	(segment
		(start 305.187096 -78.48854)
		(end 305.186842 -78.48854)
		(width 0.0889)
		(layer "F.Cu")
		(net "P3E_CPU0_PE2_SS_TXN<12>")
	)
	(segment
		(start 347.599 -48.5394)
		(end 349.973392 -49.01438)
		(width 0.1143)
		(layer "F.Cu")
		(net "P3E_CPU0_PE2_SS_TXN<12>")
	)
	(segment
		(start 364.867444 -15.739872)
		(end 369.42776 -12.721082)
		(width 0.1143)
		(layer "F.Cu")
		(net "P3E_CPU0_PE2_SS_TXN<12>")
	)
	(segment
		(start 343.5223 -49.35474)
		(end 347.599 -48.5394)
		(width 0.1143)
		(layer "F.Cu")
		(net "P3E_CPU0_PE2_SS_TXN<12>")
	)
	(segment
		(start 363.844332 -24.35352)
		(end 363.480604 -22.642068)
		(width 0.1143)
		(layer "F.Cu")
		(net "P3E_CPU0_PE2_SS_TXN<12>")
	)
	(segment
		(start 319.288668 -65.575434)
		(end 325.861426 -56.020208)
		(width 0.1143)
		(layer "F.Cu")
		(net "P3E_CPU0_PE2_SS_TXN<12>")
	)
	(segment
		(start 369.42776 -12.721082)
		(end 370.042694 -11.602212)
		(width 0.1143)
		(layer "F.Cu")
		(net "P3E_CPU0_PE2_SS_TXN<12>")
	)
	(segment
		(start 304.675286 -79.183738)
		(end 304.845212 -78.759304)
		(width 0.0889)
		(layer "F.Cu")
		(net "P3E_CPU0_PE2_SS_TXN<12>")
	)
	(segment
		(start 370.042694 -11.602212)
		(end 370.042694 -11.240008)
		(width 0.1143)
		(layer "F.Cu")
		(net "P3E_CPU0_PE2_SS_TXN<12>")
	)
	(segment
		(start 339.1916 -49.31664)
		(end 341.2617 -48.90262)
		(width 0.1143)
		(layer "F.Cu")
		(net "P3E_CPU0_PE2_SS_TXN<12>")
	)
	(segment
		(start 315.094366 -68.484242)
		(end 316.470284 -67.529964)
		(width 0.1143)
		(layer "F.Cu")
		(net "P3E_CPU0_PE2_SS_TXN<12>")
	)
	(segment
		(start 349.973392 -49.01438)
		(end 353.87661 -48.234092)
		(width 0.1143)
		(layer "F.Cu")
		(net "P3E_CPU0_PE2_SS_TXN<12>")
	)
	(segment
		(start 363.77245 -21.268182)
		(end 363.462316 -19.809206)
		(width 0.1143)
		(layer "F.Cu")
		(net "P3E_CPU0_PE2_SS_TXN<12>")
	)
	(segment
		(start 305.52263 -78.288388)
		(end 307.519324 -78.288388)
		(width 0.0889)
		(layer "F.Cu")
		(net "P3E_CPU0_PE2_SS_TXN<12>")
	)
	(segment
		(start 307.519324 -78.288388)
		(end 308.383178 -77.850238)
		(width 0.0889)
		(layer "F.Cu")
		(net "P3E_CPU0_PE2_SS_TXN<12>")
	)
	(segment
		(start 308.383178 -77.850238)
		(end 308.667912 -77.45095)
		(width 0.0889)
		(layer "F.Cu")
		(net "P3E_CPU0_PE2_SS_TXN<12>")
	)
	(segment
		(start 316.470284 -67.529964)
		(end 319.288668 -65.575434)
		(width 0.1143)
		(layer "F.Cu")
		(net "P3E_CPU0_PE2_SS_TXN<12>")
	)
	(segment
		(start 360.523028 -40.45712)
		(end 359.871518 -37.755322)
		(width 0.1143)
		(layer "F.Cu")
		(net "P3E_CPU0_PE2_SS_TXN<12>")
	)
	(segment
		(start 363.462316 -19.809206)
		(end 363.945932 -17.530572)
		(width 0.1143)
		(layer "F.Cu")
		(net "P3E_CPU0_PE2_SS_TXN<12>")
	)
	(segment
		(start 333.095092 -50.372772)
		(end 337.410298 -48.960532)
		(width 0.1143)
		(layer "F.Cu")
		(net "P3E_CPU0_PE2_SS_TXN<12>")
	)
	(segment
		(start 370.042694 -11.240008)
		(end 370.366544 -10.916158)
		(width 0.1143)
		(layer "F.Cu")
		(net "P3E_CPU0_PE2_SS_TXN<12>")
	)
	(segment
		(start 337.410298 -48.960532)
		(end 339.1916 -49.31664)
		(width 0.1143)
		(layer "F.Cu")
		(net "P3E_CPU0_PE2_SS_TXN<12>")
	)
	(via
		(at 316.470284 -67.529964)
		(size 0.508)
		(drill 0.254)
		(layers "F.Cu" "B.Cu")
		(net "P3E_CPU0_PE2_SS_TXN<12>")
	)
	(arc
		(start 304.898044 -78.740762)
		(mid 305.063611 -78.638762)
		(end 305.187096 -78.48854)
		(width 0.0889)
		(layer "F.Cu")
		(net "P3E_CPU0_PE2_SS_TXN<12>")
	)
	(arc
		(start 304.845212 -78.759304)
		(mid 304.871846 -78.750654)
		(end 304.898044 -78.740762)
		(width 0.0889)
		(layer "F.Cu")
		(net "P3E_CPU0_PE2_SS_TXN<12>")
	)
	(arc
		(start 305.186842 -78.48854)
		(mid 305.328634 -78.344671)
		(end 305.52263 -78.288388)
		(width 0.0889)
		(layer "F.Cu")
		(net "P3E_CPU0_PE2_SS_TXN<12>")
	)
	(segment
		(start 326.20966 -57.845706)
		(end 327.554336 -55.890922)
		(width 0.1143)
		(layer "F.Cu")
		(net "P3E_CPU0_PE2_SS_TXN<11>")
	)
	(segment
		(start 327.554336 -55.890922)
		(end 333.98587 -50.866548)
		(width 0.1143)
		(layer "F.Cu")
		(net "P3E_CPU0_PE2_SS_TXN<11>")
	)
	(segment
		(start 370.442998 -13.105638)
		(end 370.443252 -13.105638)
		(width 0.1143)
		(layer "F.Cu")
		(net "P3E_CPU0_PE2_SS_TXN<11>")
	)
	(segment
		(start 370.47551 -12.947142)
		(end 370.761514 -12.757912)
		(width 0.1143)
		(layer "F.Cu")
		(net "P3E_CPU0_PE2_SS_TXN<11>")
	)
	(segment
		(start 304.96256 -80.008476)
		(end 304.98923 -79.908654)
		(width 0.0889)
		(layer "F.Cu")
		(net "P3E_CPU0_PE2_SS_TXN<11>")
	)
	(segment
		(start 371.56898 -12.360656)
		(end 372.201694 -11.559286)
		(width 0.1143)
		(layer "F.Cu")
		(net "P3E_CPU0_PE2_SS_TXN<11>")
	)
	(segment
		(start 304.675286 -80.174338)
		(end 304.96256 -80.008476)
		(width 0.0889)
		(layer "F.Cu")
		(net "P3E_CPU0_PE2_SS_TXN<11>")
	)
	(segment
		(start 305.51628 -79.088488)
		(end 307.85689 -79.088488)
		(width 0.0889)
		(layer "F.Cu")
		(net "P3E_CPU0_PE2_SS_TXN<11>")
	)
	(segment
		(start 370.919756 -12.79017)
		(end 371.56898 -12.360656)
		(width 0.1143)
		(layer "F.Cu")
		(net "P3E_CPU0_PE2_SS_TXN<11>")
	)
	(segment
		(start 364.629446 -24.384762)
		(end 364.26013 -22.645878)
		(width 0.1143)
		(layer "F.Cu")
		(net "P3E_CPU0_PE2_SS_TXN<11>")
	)
	(segment
		(start 360.650536 -37.80917)
		(end 364.629446 -24.384762)
		(width 0.1143)
		(layer "F.Cu")
		(net "P3E_CPU0_PE2_SS_TXN<11>")
	)
	(segment
		(start 343.535 -50.101754)
		(end 347.5863 -49.291494)
		(width 0.1143)
		(layer "F.Cu")
		(net "P3E_CPU0_PE2_SS_TXN<11>")
	)
	(segment
		(start 364.24108 -19.809206)
		(end 364.696502 -17.66316)
		(width 0.1143)
		(layer "F.Cu")
		(net "P3E_CPU0_PE2_SS_TXN<11>")
	)
	(segment
		(start 308.825646 -78.577948)
		(end 308.999128 -78.334362)
		(width 0.0889)
		(layer "F.Cu")
		(net "P3E_CPU0_PE2_SS_TXN<11>")
	)
	(segment
		(start 364.696502 -17.66316)
		(end 365.285528 -16.519144)
		(width 0.1143)
		(layer "F.Cu")
		(net "P3E_CPU0_PE2_SS_TXN<11>")
	)
	(segment
		(start 321.177666 -65.16243)
		(end 326.20966 -57.845706)
		(width 0.1143)
		(layer "F.Cu")
		(net "P3E_CPU0_PE2_SS_TXN<11>")
	)
	(segment
		(start 315.607446 -69.024246)
		(end 321.177666 -65.16243)
		(width 0.1143)
		(layer "F.Cu")
		(net "P3E_CPU0_PE2_SS_TXN<11>")
	)
	(segment
		(start 364.26013 -22.645878)
		(end 364.551976 -21.272754)
		(width 0.1143)
		(layer "F.Cu")
		(net "P3E_CPU0_PE2_SS_TXN<11>")
	)
	(segment
		(start 370.761514 -12.757912)
		(end 370.919756 -12.79017)
		(width 0.1143)
		(layer "F.Cu")
		(net "P3E_CPU0_PE2_SS_TXN<11>")
	)
	(segment
		(start 364.551976 -21.272754)
		(end 364.24108 -19.809206)
		(width 0.1143)
		(layer "F.Cu")
		(net "P3E_CPU0_PE2_SS_TXN<11>")
	)
	(segment
		(start 347.5863 -49.291494)
		(end 349.966534 -49.76749)
		(width 0.1143)
		(layer "F.Cu")
		(net "P3E_CPU0_PE2_SS_TXN<11>")
	)
	(segment
		(start 365.285528 -16.519144)
		(end 370.442998 -13.105638)
		(width 0.1143)
		(layer "F.Cu")
		(net "P3E_CPU0_PE2_SS_TXN<11>")
	)
	(segment
		(start 339.166708 -50.06086)
		(end 341.249 -49.644554)
		(width 0.1143)
		(layer "F.Cu")
		(net "P3E_CPU0_PE2_SS_TXN<11>")
	)
	(segment
		(start 307.85689 -79.088488)
		(end 308.825646 -78.577948)
		(width 0.0889)
		(layer "F.Cu")
		(net "P3E_CPU0_PE2_SS_TXN<11>")
	)
	(segment
		(start 305.516026 -79.088234)
		(end 305.51628 -79.088488)
		(width 0.0889)
		(layer "F.Cu")
		(net "P3E_CPU0_PE2_SS_TXN<11>")
	)
	(segment
		(start 360.430826 -44.68495)
		(end 361.292648 -40.47109)
		(width 0.1143)
		(layer "F.Cu")
		(net "P3E_CPU0_PE2_SS_TXN<11>")
	)
	(segment
		(start 308.999128 -78.334362)
		(end 309.005732 -78.280768)
		(width 0.0889)
		(layer "F.Cu")
		(net "P3E_CPU0_PE2_SS_TXN<11>")
	)
	(segment
		(start 372.201694 -11.240008)
		(end 371.877844 -10.916158)
		(width 0.1143)
		(layer "F.Cu")
		(net "P3E_CPU0_PE2_SS_TXN<11>")
	)
	(segment
		(start 333.98587 -50.866548)
		(end 337.478624 -49.723548)
		(width 0.1143)
		(layer "F.Cu")
		(net "P3E_CPU0_PE2_SS_TXN<11>")
	)
	(segment
		(start 337.478624 -49.723548)
		(end 339.166708 -50.06086)
		(width 0.1143)
		(layer "F.Cu")
		(net "P3E_CPU0_PE2_SS_TXN<11>")
	)
	(segment
		(start 372.201694 -11.559286)
		(end 372.201694 -11.240008)
		(width 0.1143)
		(layer "F.Cu")
		(net "P3E_CPU0_PE2_SS_TXN<11>")
	)
	(segment
		(start 341.249 -49.644554)
		(end 343.535 -50.101754)
		(width 0.1143)
		(layer "F.Cu")
		(net "P3E_CPU0_PE2_SS_TXN<11>")
	)
	(segment
		(start 361.292648 -40.47109)
		(end 360.650536 -37.80917)
		(width 0.1143)
		(layer "F.Cu")
		(net "P3E_CPU0_PE2_SS_TXN<11>")
	)
	(segment
		(start 370.443252 -13.105638)
		(end 370.47551 -12.947142)
		(width 0.1143)
		(layer "F.Cu")
		(net "P3E_CPU0_PE2_SS_TXN<11>")
	)
	(segment
		(start 349.966534 -49.76749)
		(end 354.15093 -48.93056)
		(width 0.1143)
		(layer "F.Cu")
		(net "P3E_CPU0_PE2_SS_TXN<11>")
	)
	(segment
		(start 354.15093 -48.93056)
		(end 360.430826 -44.68495)
		(width 0.1143)
		(layer "F.Cu")
		(net "P3E_CPU0_PE2_SS_TXN<11>")
	)
	(segment
		(start 309.005732 -78.280768)
		(end 315.607446 -69.024246)
		(width 0.1143)
		(layer "F.Cu")
		(net "P3E_CPU0_PE2_SS_TXN<11>")
	)
	(via
		(at 326.20966 -57.845706)
		(size 0.508)
		(drill 0.254)
		(layers "F.Cu" "B.Cu")
		(net "P3E_CPU0_PE2_SS_TXN<11>")
	)
	(arc
		(start 304.98923 -79.908654)
		(mid 304.985206 -79.899038)
		(end 304.981356 -79.88935)
		(width 0.0889)
		(layer "F.Cu")
		(net "P3E_CPU0_PE2_SS_TXN<11>")
	)
	(arc
		(start 304.981356 -79.88935)
		(mid 305.04196 -79.350766)
		(end 305.516026 -79.088234)
		(width 0.0889)
		(layer "F.Cu")
		(net "P3E_CPU0_PE2_SS_TXN<11>")
	)
	(segment
		(start 307.052218 -80.066134)
		(end 307.141118 -80.155034)
		(width 0.0889)
		(layer "F.Cu")
		(net "P3E_CPU0_PE2_SS_TXN<10>")
	)
	(segment
		(start 306.696618 -80.155034)
		(end 306.785518 -80.066134)
		(width 0.0889)
		(layer "F.Cu")
		(net "P3E_CPU0_PE2_SS_TXN<10>")
	)
	(segment
		(start 307.141118 -80.155034)
		(end 307.407818 -80.155034)
		(width 0.0889)
		(layer "F.Cu")
		(net "P3E_CPU0_PE2_SS_TXN<10>")
	)
	(segment
		(start 321.963288 -66.153284)
		(end 328.284332 -56.962802)
		(width 0.1143)
		(layer "F.Cu")
		(net "P3E_CPU0_PE2_SS_TXN<10>")
	)
	(segment
		(start 306.785518 -80.066134)
		(end 307.052218 -80.066134)
		(width 0.0889)
		(layer "F.Cu")
		(net "P3E_CPU0_PE2_SS_TXN<10>")
	)
	(segment
		(start 365.51362 -19.808952)
		(end 365.823754 -21.267928)
		(width 0.1143)
		(layer "F.Cu")
		(net "P3E_CPU0_PE2_SS_TXN<10>")
	)
	(segment
		(start 306.429918 -80.155034)
		(end 306.696618 -80.155034)
		(width 0.0889)
		(layer "F.Cu")
		(net "P3E_CPU0_PE2_SS_TXN<10>")
	)
	(segment
		(start 366.184434 -17.450054)
		(end 365.895382 -18.010378)
		(width 0.1143)
		(layer "F.Cu")
		(net "P3E_CPU0_PE2_SS_TXN<10>")
	)
	(segment
		(start 308.3814 -80.091534)
		(end 308.403498 -80.091534)
		(width 0.0889)
		(layer "F.Cu")
		(net "P3E_CPU0_PE2_SS_TXN<10>")
	)
	(segment
		(start 304.6603 -80.764888)
		(end 304.693066 -80.764888)
		(width 0.0889)
		(layer "F.Cu")
		(net "P3E_CPU0_PE2_SS_TXN<10>")
	)
	(segment
		(start 365.912908 -24.43607)
		(end 361.935014 -37.854128)
		(width 0.1143)
		(layer "F.Cu")
		(net "P3E_CPU0_PE2_SS_TXN<10>")
	)
	(segment
		(start 365.531908 -22.642322)
		(end 365.912908 -24.43607)
		(width 0.1143)
		(layer "F.Cu")
		(net "P3E_CPU0_PE2_SS_TXN<10>")
	)
	(segment
		(start 347.6244 -50.54092)
		(end 343.5731 -51.35118)
		(width 0.1143)
		(layer "F.Cu")
		(net "P3E_CPU0_PE2_SS_TXN<10>")
	)
	(segment
		(start 328.284332 -56.962802)
		(end 334.322674 -52.197254)
		(width 0.1143)
		(layer "F.Cu")
		(net "P3E_CPU0_PE2_SS_TXN<10>")
	)
	(segment
		(start 308.356 -80.066134)
		(end 308.3814 -80.091534)
		(width 0.0889)
		(layer "F.Cu")
		(net "P3E_CPU0_PE2_SS_TXN<10>")
	)
	(segment
		(start 374.843294 -11.643106)
		(end 374.550178 -11.913108)
		(width 0.1143)
		(layer "F.Cu")
		(net "P3E_CPU0_PE2_SS_TXN<10>")
	)
	(segment
		(start 308.833266 -80.091534)
		(end 311.95772 -76.96708)
		(width 0.1143)
		(layer "F.Cu")
		(net "P3E_CPU0_PE2_SS_TXN<10>")
	)
	(segment
		(start 311.95772 -76.96708)
		(end 317.538862 -69.325236)
		(width 0.1143)
		(layer "F.Cu")
		(net "P3E_CPU0_PE2_SS_TXN<10>")
	)
	(segment
		(start 349.941642 -51.00447)
		(end 347.6244 -50.54092)
		(width 0.1143)
		(layer "F.Cu")
		(net "P3E_CPU0_PE2_SS_TXN<10>")
	)
	(segment
		(start 307.496718 -80.066134)
		(end 308.356 -80.066134)
		(width 0.0889)
		(layer "F.Cu")
		(net "P3E_CPU0_PE2_SS_TXN<10>")
	)
	(segment
		(start 308.403498 -80.091534)
		(end 308.833266 -80.091534)
		(width 0.1143)
		(layer "F.Cu")
		(net "P3E_CPU0_PE2_SS_TXN<10>")
	)
	(segment
		(start 337.591654 -50.9778)
		(end 334.687164 -51.909472)
		(width 0.1143)
		(layer "F.Cu")
		(net "P3E_CPU0_PE2_SS_TXN<10>")
	)
	(segment
		(start 361.523534 -45.405294)
		(end 354.626926 -50.066956)
		(width 0.1143)
		(layer "F.Cu")
		(net "P3E_CPU0_PE2_SS_TXN<10>")
	)
	(segment
		(start 343.5731 -51.35118)
		(end 341.2617 -50.8889)
		(width 0.1143)
		(layer "F.Cu")
		(net "P3E_CPU0_PE2_SS_TXN<10>")
	)
	(segment
		(start 306.341018 -80.066134)
		(end 306.429918 -80.155034)
		(width 0.0889)
		(layer "F.Cu")
		(net "P3E_CPU0_PE2_SS_TXN<10>")
	)
	(segment
		(start 361.935014 -37.854128)
		(end 362.548678 -40.394636)
		(width 0.1143)
		(layer "F.Cu")
		(net "P3E_CPU0_PE2_SS_TXN<10>")
	)
	(segment
		(start 339.204554 -51.30038)
		(end 337.591654 -50.9778)
		(width 0.1143)
		(layer "F.Cu")
		(net "P3E_CPU0_PE2_SS_TXN<10>")
	)
	(segment
		(start 307.407818 -80.155034)
		(end 307.496718 -80.066134)
		(width 0.0889)
		(layer "F.Cu")
		(net "P3E_CPU0_PE2_SS_TXN<10>")
	)
	(segment
		(start 374.550178 -11.913108)
		(end 366.184434 -17.450054)
		(width 0.1143)
		(layer "F.Cu")
		(net "P3E_CPU0_PE2_SS_TXN<10>")
	)
	(segment
		(start 354.626926 -50.066956)
		(end 349.941642 -51.00447)
		(width 0.1143)
		(layer "F.Cu")
		(net "P3E_CPU0_PE2_SS_TXN<10>")
	)
	(segment
		(start 304.675286 -81.164938)
		(end 304.388012 -80.999076)
		(width 0.0889)
		(layer "F.Cu")
		(net "P3E_CPU0_PE2_SS_TXN<10>")
	)
	(segment
		(start 365.823754 -21.267928)
		(end 365.531908 -22.642322)
		(width 0.1143)
		(layer "F.Cu")
		(net "P3E_CPU0_PE2_SS_TXN<10>")
	)
	(segment
		(start 375.167144 -10.916158)
		(end 374.843294 -11.240008)
		(width 0.1143)
		(layer "F.Cu")
		(net "P3E_CPU0_PE2_SS_TXN<10>")
	)
	(segment
		(start 362.548678 -40.394636)
		(end 361.523534 -45.405294)
		(width 0.1143)
		(layer "F.Cu")
		(net "P3E_CPU0_PE2_SS_TXN<10>")
	)
	(segment
		(start 334.687164 -51.909472)
		(end 334.322674 -52.197254)
		(width 0.1143)
		(layer "F.Cu")
		(net "P3E_CPU0_PE2_SS_TXN<10>")
	)
	(segment
		(start 365.895382 -18.010378)
		(end 365.51362 -19.808952)
		(width 0.1143)
		(layer "F.Cu")
		(net "P3E_CPU0_PE2_SS_TXN<10>")
	)
	(segment
		(start 306.05857 -80.066134)
		(end 306.341018 -80.066134)
		(width 0.0889)
		(layer "F.Cu")
		(net "P3E_CPU0_PE2_SS_TXN<10>")
	)
	(segment
		(start 305.85537 -80.269334)
		(end 306.05857 -80.066134)
		(width 0.0889)
		(layer "F.Cu")
		(net "P3E_CPU0_PE2_SS_TXN<10>")
	)
	(segment
		(start 374.843294 -11.240008)
		(end 374.843294 -11.643106)
		(width 0.1143)
		(layer "F.Cu")
		(net "P3E_CPU0_PE2_SS_TXN<10>")
	)
	(segment
		(start 304.388012 -80.999076)
		(end 304.364898 -80.912462)
		(width 0.0889)
		(layer "F.Cu")
		(net "P3E_CPU0_PE2_SS_TXN<10>")
	)
	(segment
		(start 305.519328 -80.269334)
		(end 305.85537 -80.269334)
		(width 0.0889)
		(layer "F.Cu")
		(net "P3E_CPU0_PE2_SS_TXN<10>")
	)
	(segment
		(start 341.2617 -50.8889)
		(end 339.204554 -51.30038)
		(width 0.1143)
		(layer "F.Cu")
		(net "P3E_CPU0_PE2_SS_TXN<10>")
	)
	(segment
		(start 317.538862 -69.325236)
		(end 321.963288 -66.153284)
		(width 0.1143)
		(layer "F.Cu")
		(net "P3E_CPU0_PE2_SS_TXN<10>")
	)
	(via
		(at 334.322674 -52.197254)
		(size 0.508)
		(drill 0.254)
		(layers "F.Cu" "B.Cu")
		(net "P3E_CPU0_PE2_SS_TXN<10>")
	)
	(arc
		(start 304.364898 -80.912462)
		(mid 304.496679 -80.806816)
		(end 304.6603 -80.764888)
		(width 0.0889)
		(layer "F.Cu")
		(net "P3E_CPU0_PE2_SS_TXN<10>")
	)
	(arc
		(start 304.693066 -80.764888)
		(mid 304.97849 -80.681421)
		(end 305.187096 -80.469486)
		(width 0.0889)
		(layer "F.Cu")
		(net "P3E_CPU0_PE2_SS_TXN<10>")
	)
	(arc
		(start 305.187096 -80.469486)
		(mid 305.327364 -80.32653)
		(end 305.519328 -80.269334)
		(width 0.0889)
		(layer "F.Cu")
		(net "P3E_CPU0_PE2_SS_TXN<10>")
	)
	(segment
		(start 405.27351 -14.873732)
		(end 409.052268 -12.361418)
		(width 0.1143)
		(layer "F.Cu")
		(net "P3E_CPU0_PE2_SS_TXN<0>")
	)
	(segment
		(start 402.988272 -15.330424)
		(end 405.27351 -14.873732)
		(width 0.1143)
		(layer "F.Cu")
		(net "P3E_CPU0_PE2_SS_TXN<0>")
	)
	(segment
		(start 309.742586 -90.200734)
		(end 309.720488 -90.200734)
		(width 0.0889)
		(layer "F.Cu")
		(net "P3E_CPU0_PE2_SS_TXN<0>")
	)
	(segment
		(start 334.358488 -70.11543)
		(end 339.965284 -67.45986)
		(width 0.1143)
		(layer "F.Cu")
		(net "P3E_CPU0_PE2_SS_TXN<0>")
	)
	(segment
		(start 384.06959 -48.253904)
		(end 385.550156 -46.322996)
		(width 0.1143)
		(layer "F.Cu")
		(net "P3E_CPU0_PE2_SS_TXN<0>")
	)
	(segment
		(start 305.246532 -90.409776)
		(end 305.533806 -90.575384)
		(width 0.0889)
		(layer "F.Cu")
		(net "P3E_CPU0_PE2_SS_TXN<0>")
	)
	(segment
		(start 347.181678 -66.774568)
		(end 348.423738 -66.510662)
		(width 0.1143)
		(layer "F.Cu")
		(net "P3E_CPU0_PE2_SS_TXN<0>")
	)
	(segment
		(start 305.223418 -90.323162)
		(end 305.246532 -90.409776)
		(width 0.0889)
		(layer "F.Cu")
		(net "P3E_CPU0_PE2_SS_TXN<0>")
	)
	(segment
		(start 343.905586 -66.623438)
		(end 344.76309 -66.787776)
		(width 0.1143)
		(layer "F.Cu")
		(net "P3E_CPU0_PE2_SS_TXN<0>")
	)
	(segment
		(start 309.200296 -90.274394)
		(end 308.920896 -90.274394)
		(width 0.0889)
		(layer "F.Cu")
		(net "P3E_CPU0_PE2_SS_TXN<0>")
	)
	(segment
		(start 310.34101 -90.200734)
		(end 309.742586 -90.200734)
		(width 0.1143)
		(layer "F.Cu")
		(net "P3E_CPU0_PE2_SS_TXN<0>")
	)
	(segment
		(start 349.642176 -66.769488)
		(end 350.886014 -66.505836)
		(width 0.1143)
		(layer "F.Cu")
		(net "P3E_CPU0_PE2_SS_TXN<0>")
	)
	(segment
		(start 393.168378 -36.746942)
		(end 394.099034 -32.17545)
		(width 0.1143)
		(layer "F.Cu")
		(net "P3E_CPU0_PE2_SS_TXN<0>")
	)
	(segment
		(start 364.923578 -58.350404)
		(end 375.09704 -51.353212)
		(width 0.1143)
		(layer "F.Cu")
		(net "P3E_CPU0_PE2_SS_TXN<0>")
	)
	(segment
		(start 348.423738 -66.510662)
		(end 349.642176 -66.769488)
		(width 0.1143)
		(layer "F.Cu")
		(net "P3E_CPU0_PE2_SS_TXN<0>")
	)
	(segment
		(start 344.76309 -66.787776)
		(end 344.76309 -66.788792)
		(width 0.1143)
		(layer "F.Cu")
		(net "P3E_CPU0_PE2_SS_TXN<0>")
	)
	(segment
		(start 394.097002 -25.513538)
		(end 395.09827 -22.248622)
		(width 0.1143)
		(layer "F.Cu")
		(net "P3E_CPU0_PE2_SS_TXN<0>")
	)
	(segment
		(start 309.695088 -90.175334)
		(end 309.299356 -90.175334)
		(width 0.0889)
		(layer "F.Cu")
		(net "P3E_CPU0_PE2_SS_TXN<0>")
	)
	(segment
		(start 325.463154 -76.128626)
		(end 334.358488 -70.11543)
		(width 0.1143)
		(layer "F.Cu")
		(net "P3E_CPU0_PE2_SS_TXN<0>")
	)
	(segment
		(start 308.064916 -90.175334)
		(end 307.250084 -90.175334)
		(width 0.0889)
		(layer "F.Cu")
		(net "P3E_CPU0_PE2_SS_TXN<0>")
	)
	(segment
		(start 355.519228 -67.76974)
		(end 359.251758 -67.035934)
		(width 0.1143)
		(layer "F.Cu")
		(net "P3E_CPU0_PE2_SS_TXN<0>")
	)
	(segment
		(start 392.667744 -42.233342)
		(end 393.252452 -41.349168)
		(width 0.1143)
		(layer "F.Cu")
		(net "P3E_CPU0_PE2_SS_TXN<0>")
	)
	(segment
		(start 308.920896 -90.274394)
		(end 308.821836 -90.175334)
		(width 0.0889)
		(layer "F.Cu")
		(net "P3E_CPU0_PE2_SS_TXN<0>")
	)
	(segment
		(start 394.099034 -32.17545)
		(end 393.939522 -31.41218)
		(width 0.1143)
		(layer "F.Cu")
		(net "P3E_CPU0_PE2_SS_TXN<0>")
	)
	(segment
		(start 305.555396 -90.175334)
		(end 305.52263 -90.175334)
		(width 0.0889)
		(layer "F.Cu")
		(net "P3E_CPU0_PE2_SS_TXN<0>")
	)
	(segment
		(start 362.671868 -61.553598)
		(end 364.923578 -58.350404)
		(width 0.1143)
		(layer "F.Cu")
		(net "P3E_CPU0_PE2_SS_TXN<0>")
	)
	(segment
		(start 308.821836 -90.175334)
		(end 308.542436 -90.175334)
		(width 0.0889)
		(layer "F.Cu")
		(net "P3E_CPU0_PE2_SS_TXN<0>")
	)
	(segment
		(start 381.611124 -51.135026)
		(end 383.259584 -48.572928)
		(width 0.1143)
		(layer "F.Cu")
		(net "P3E_CPU0_PE2_SS_TXN<0>")
	)
	(segment
		(start 393.67841 -39.254938)
		(end 393.168378 -36.746942)
		(width 0.1143)
		(layer "F.Cu")
		(net "P3E_CPU0_PE2_SS_TXN<0>")
	)
	(segment
		(start 346.005658 -66.524886)
		(end 347.181678 -66.774568)
		(width 0.1143)
		(layer "F.Cu")
		(net "P3E_CPU0_PE2_SS_TXN<0>")
	)
	(segment
		(start 410.514546 -11.740134)
		(end 410.817822 -11.436858)
		(width 0.1143)
		(layer "F.Cu")
		(net "P3E_CPU0_PE2_SS_TXN<0>")
	)
	(segment
		(start 393.939522 -31.41218)
		(end 394.694664 -27.696668)
		(width 0.1143)
		(layer "F.Cu")
		(net "P3E_CPU0_PE2_SS_TXN<0>")
	)
	(segment
		(start 318.67094 -86.058502)
		(end 310.34101 -90.200734)
		(width 0.1143)
		(layer "F.Cu")
		(net "P3E_CPU0_PE2_SS_TXN<0>")
	)
	(segment
		(start 309.299356 -90.175334)
		(end 309.200296 -90.274394)
		(width 0.0889)
		(layer "F.Cu")
		(net "P3E_CPU0_PE2_SS_TXN<0>")
	)
	(segment
		(start 398.489424 -18.308828)
		(end 402.988272 -15.330424)
		(width 0.1143)
		(layer "F.Cu")
		(net "P3E_CPU0_PE2_SS_TXN<0>")
	)
	(segment
		(start 375.09704 -51.353212)
		(end 377.280678 -50.83556)
		(width 0.1143)
		(layer "F.Cu")
		(net "P3E_CPU0_PE2_SS_TXN<0>")
	)
	(segment
		(start 395.09827 -22.248622)
		(end 396.107412 -20.651978)
		(width 0.1143)
		(layer "F.Cu")
		(net "P3E_CPU0_PE2_SS_TXN<0>")
	)
	(segment
		(start 308.163976 -90.274394)
		(end 308.064916 -90.175334)
		(width 0.0889)
		(layer "F.Cu")
		(net "P3E_CPU0_PE2_SS_TXN<0>")
	)
	(segment
		(start 393.252452 -41.349168)
		(end 393.67841 -39.254938)
		(width 0.1143)
		(layer "F.Cu")
		(net "P3E_CPU0_PE2_SS_TXN<0>")
	)
	(segment
		(start 394.694664 -27.696668)
		(end 394.097002 -25.513538)
		(width 0.1143)
		(layer "F.Cu")
		(net "P3E_CPU0_PE2_SS_TXN<0>")
	)
	(segment
		(start 321.433952 -82.01914)
		(end 318.67094 -86.058502)
		(width 0.1143)
		(layer "F.Cu")
		(net "P3E_CPU0_PE2_SS_TXN<0>")
	)
	(segment
		(start 308.542436 -90.175334)
		(end 308.443376 -90.274394)
		(width 0.0889)
		(layer "F.Cu")
		(net "P3E_CPU0_PE2_SS_TXN<0>")
	)
	(segment
		(start 339.965284 -67.45986)
		(end 343.905586 -66.623438)
		(width 0.1143)
		(layer "F.Cu")
		(net "P3E_CPU0_PE2_SS_TXN<0>")
	)
	(segment
		(start 308.443376 -90.274394)
		(end 308.163976 -90.274394)
		(width 0.0889)
		(layer "F.Cu")
		(net "P3E_CPU0_PE2_SS_TXN<0>")
	)
	(segment
		(start 350.886014 -66.505836)
		(end 355.519228 -67.76974)
		(width 0.1143)
		(layer "F.Cu")
		(net "P3E_CPU0_PE2_SS_TXN<0>")
	)
	(segment
		(start 410.238448 -12.361418)
		(end 410.514546 -12.08532)
		(width 0.1143)
		(layer "F.Cu")
		(net "P3E_CPU0_PE2_SS_TXN<0>")
	)
	(segment
		(start 396.107412 -20.651978)
		(end 398.180814 -19.4564)
		(width 0.1143)
		(layer "F.Cu")
		(net "P3E_CPU0_PE2_SS_TXN<0>")
	)
	(segment
		(start 359.251758 -67.035934)
		(end 361.72902 -65.168272)
		(width 0.1143)
		(layer "F.Cu")
		(net "P3E_CPU0_PE2_SS_TXN<0>")
	)
	(segment
		(start 388.247636 -44.537884)
		(end 389.602218 -44.262294)
		(width 0.1143)
		(layer "F.Cu")
		(net "P3E_CPU0_PE2_SS_TXN<0>")
	)
	(segment
		(start 383.259584 -48.572928)
		(end 384.06959 -48.253904)
		(width 0.1143)
		(layer "F.Cu")
		(net "P3E_CPU0_PE2_SS_TXN<0>")
	)
	(segment
		(start 377.280678 -50.83556)
		(end 380.00051 -51.611276)
		(width 0.1143)
		(layer "F.Cu")
		(net "P3E_CPU0_PE2_SS_TXN<0>")
	)
	(segment
		(start 409.052268 -12.361418)
		(end 410.238448 -12.361418)
		(width 0.1143)
		(layer "F.Cu")
		(net "P3E_CPU0_PE2_SS_TXN<0>")
	)
	(segment
		(start 344.76309 -66.788792)
		(end 346.005658 -66.524886)
		(width 0.1143)
		(layer "F.Cu")
		(net "P3E_CPU0_PE2_SS_TXN<0>")
	)
	(segment
		(start 385.550156 -46.322996)
		(end 388.247636 -44.537884)
		(width 0.1143)
		(layer "F.Cu")
		(net "P3E_CPU0_PE2_SS_TXN<0>")
	)
	(segment
		(start 309.720488 -90.200734)
		(end 309.695088 -90.175334)
		(width 0.0889)
		(layer "F.Cu")
		(net "P3E_CPU0_PE2_SS_TXN<0>")
	)
	(segment
		(start 389.602218 -44.262294)
		(end 392.667744 -42.233342)
		(width 0.1143)
		(layer "F.Cu")
		(net "P3E_CPU0_PE2_SS_TXN<0>")
	)
	(segment
		(start 321.433952 -82.01914)
		(end 325.463154 -76.128626)
		(width 0.1143)
		(layer "F.Cu")
		(net "P3E_CPU0_PE2_SS_TXN<0>")
	)
	(segment
		(start 380.00051 -51.611276)
		(end 381.611124 -51.135026)
		(width 0.1143)
		(layer "F.Cu")
		(net "P3E_CPU0_PE2_SS_TXN<0>")
	)
	(segment
		(start 398.180814 -19.4564)
		(end 398.489424 -18.308828)
		(width 0.1143)
		(layer "F.Cu")
		(net "P3E_CPU0_PE2_SS_TXN<0>")
	)
	(segment
		(start 410.514546 -12.08532)
		(end 410.514546 -11.740134)
		(width 0.1143)
		(layer "F.Cu")
		(net "P3E_CPU0_PE2_SS_TXN<0>")
	)
	(segment
		(start 306.407312 -89.680288)
		(end 306.37734 -89.680288)
		(width 0.0889)
		(layer "F.Cu")
		(net "P3E_CPU0_PE2_SS_TXN<0>")
	)
	(segment
		(start 361.72902 -65.168272)
		(end 362.671868 -61.553598)
		(width 0.1143)
		(layer "F.Cu")
		(net "P3E_CPU0_PE2_SS_TXN<0>")
	)
	(via
		(at 321.433952 -82.01914)
		(size 0.508)
		(drill 0.254)
		(layers "F.Cu" "B.Cu")
		(net "P3E_CPU0_PE2_SS_TXN<0>")
	)
	(arc
		(start 306.37734 -89.680288)
		(mid 306.185698 -89.737454)
		(end 306.045616 -89.880186)
		(width 0.0889)
		(layer "F.Cu")
		(net "P3E_CPU0_PE2_SS_TXN<0>")
	)
	(arc
		(start 307.250084 -90.175334)
		(mid 306.955003 -90.096249)
		(end 306.739036 -89.880186)
		(width 0.0889)
		(layer "F.Cu")
		(net "P3E_CPU0_PE2_SS_TXN<0>")
	)
	(arc
		(start 306.739036 -89.880186)
		(mid 306.598957 -89.73745)
		(end 306.407312 -89.680288)
		(width 0.0889)
		(layer "F.Cu")
		(net "P3E_CPU0_PE2_SS_TXN<0>")
	)
	(arc
		(start 306.045616 -89.880186)
		(mid 305.838612 -90.09105)
		(end 305.555396 -90.175334)
		(width 0.0889)
		(layer "F.Cu")
		(net "P3E_CPU0_PE2_SS_TXN<0>")
	)
	(arc
		(start 305.52263 -90.175334)
		(mid 305.356856 -90.21654)
		(end 305.223418 -90.323162)
		(width 0.0889)
		(layer "F.Cu")
		(net "P3E_CPU0_PE2_SS_TXN<0>")
	)
	(segment
		(start 389.7376 -105.0544)
		(end 389.7376 -105.029)
		(width 0.10795)
		(layer "F.Cu")
		(net "TP_PCH_RSVD58")
	)
	(segment
		(start 389.33755 -105.45445)
		(end 389.7376 -105.0544)
		(width 0.10795)
		(layer "F.Cu")
		(net "TP_PCH_RSVD58")
	)
	(via
		(at 389.7376 -105.029)
		(size 0.508)
		(drill 0.254)
		(layers "F.Cu" "B.Cu")
		(net "TP_PCH_RSVD58")
	)
	(segment
		(start 89.211912 -54.104286)
		(end 88.640412 -54.104286)
		(width 0.10795)
		(layer "F.Cu")
		(net "TP_CPU1_RSVD_267")
	)
	(via
		(at 88.640412 -54.104286)
		(size 0.508)
		(drill 0.254)
		(layers "F.Cu" "B.Cu")
		(net "TP_CPU1_RSVD_267")
	)
	(segment
		(start 88.353392 -53.60924)
		(end 87.781892 -53.60924)
		(width 0.10795)
		(layer "F.Cu")
		(net "TP_CPU1_RSVD_268")
	)
	(via
		(at 87.781892 -53.60924)
		(size 0.508)
		(drill 0.254)
		(layers "F.Cu" "B.Cu")
		(net "TP_CPU1_RSVD_268")
	)
	(segment
		(start 102.089204 -53.60924)
		(end 101.517704 -53.60924)
		(width 0.10795)
		(layer "F.Cu")
		(net "TP_CPU1_RSVD_269")
	)
	(via
		(at 101.517704 -53.60924)
		(size 0.508)
		(drill 0.254)
		(layers "F.Cu" "B.Cu")
		(net "TP_CPU1_RSVD_269")
	)
	(segment
		(start 75.475846 -83.822286)
		(end 74.904346 -83.822286)
		(width 0.10795)
		(layer "F.Cu")
		(net "TP_CPU1_RSVD_82")
	)
	(via
		(at 74.904346 -83.822286)
		(size 0.508)
		(drill 0.254)
		(layers "F.Cu" "B.Cu")
		(net "TP_CPU1_RSVD_82")
	)
	(segment
		(start 74.9046 -82.83194)
		(end 74.904346 -82.831686)
		(width 0.10795)
		(layer "F.Cu")
		(net "TP_CPU1_RSVD_90")
	)
	(segment
		(start 75.475846 -82.83194)
		(end 74.9046 -82.83194)
		(width 0.10795)
		(layer "F.Cu")
		(net "TP_CPU1_RSVD_90")
	)
	(via
		(at 74.904346 -82.831686)
		(size 0.508)
		(drill 0.254)
		(layers "F.Cu" "B.Cu")
		(net "TP_CPU1_RSVD_90")
	)
	(segment
		(start 71.183246 -82.33664)
		(end 70.611746 -82.33664)
		(width 0.10795)
		(layer "F.Cu")
		(net "TP_CPU1_RSVD_94")
	)
	(via
		(at 70.611746 -82.33664)
		(size 0.508)
		(drill 0.254)
		(layers "F.Cu" "B.Cu")
		(net "TP_CPU1_RSVD_94")
	)
	(segment
		(start 74.617326 -82.33664)
		(end 74.045826 -82.33664)
		(width 0.10795)
		(layer "F.Cu")
		(net "TP_CPU1_RSVD_95")
	)
	(via
		(at 74.045826 -82.33664)
		(size 0.508)
		(drill 0.254)
		(layers "F.Cu" "B.Cu")
		(net "TP_CPU1_RSVD_95")
	)
	(segment
		(start 72.041766 -81.841086)
		(end 71.470266 -81.841086)
		(width 0.10795)
		(layer "F.Cu")
		(net "TP_CPU1_RSVD_100")
	)
	(via
		(at 71.470266 -81.841086)
		(size 0.508)
		(drill 0.254)
		(layers "F.Cu" "B.Cu")
		(net "TP_CPU1_RSVD_100")
	)
	(segment
		(start 70.324726 -53.113686)
		(end 69.753226 -53.113686)
		(width 0.10795)
		(layer "F.Cu")
		(net "TP_CPU1_RSVD_271")
	)
	(via
		(at 69.753226 -53.113686)
		(size 0.508)
		(drill 0.254)
		(layers "F.Cu" "B.Cu")
		(net "TP_CPU1_RSVD_271")
	)
	(segment
		(start 73.758806 -81.841086)
		(end 73.187306 -81.841086)
		(width 0.10795)
		(layer "F.Cu")
		(net "TP_CPU1_RSVD_101")
	)
	(via
		(at 73.187306 -81.841086)
		(size 0.508)
		(drill 0.254)
		(layers "F.Cu" "B.Cu")
		(net "TP_CPU1_RSVD_101")
	)
	(segment
		(start 72.900286 -81.34604)
		(end 72.328786 -81.34604)
		(width 0.10795)
		(layer "F.Cu")
		(net "TP_CPU1_RSVD_105")
	)
	(via
		(at 72.328786 -81.34604)
		(size 0.508)
		(drill 0.254)
		(layers "F.Cu" "B.Cu")
		(net "TP_CPU1_RSVD_105")
	)
	(segment
		(start 74.617326 -81.34604)
		(end 74.045826 -81.34604)
		(width 0.10795)
		(layer "F.Cu")
		(net "TP_CPU1_RSVD_106")
	)
	(via
		(at 74.045826 -81.34604)
		(size 0.508)
		(drill 0.254)
		(layers "F.Cu" "B.Cu")
		(net "TP_CPU1_RSVD_106")
	)
	(segment
		(start 82.343752 -70.94474)
		(end 81.772252 -70.94474)
		(width 0.10795)
		(layer "F.Cu")
		(net "TP_CPU1_RSVD_150")
	)
	(via
		(at 81.772252 -70.94474)
		(size 0.508)
		(drill 0.254)
		(layers "F.Cu" "B.Cu")
		(net "TP_CPU1_RSVD_150")
	)
	(segment
		(start 84.060792 -70.94474)
		(end 83.489292 -70.94474)
		(width 0.10795)
		(layer "F.Cu")
		(net "TP_CPU1_RSVD_151")
	)
	(via
		(at 83.489292 -70.94474)
		(size 0.508)
		(drill 0.254)
		(layers "F.Cu" "B.Cu")
		(net "TP_CPU1_RSVD_151")
	)
	(segment
		(start 85.777832 -70.94474)
		(end 85.206332 -70.94474)
		(width 0.10795)
		(layer "F.Cu")
		(net "TP_CPU1_RSVD_152")
	)
	(via
		(at 85.206332 -70.94474)
		(size 0.508)
		(drill 0.254)
		(layers "F.Cu" "B.Cu")
		(net "TP_CPU1_RSVD_152")
	)
	(segment
		(start 83.202272 -70.44944)
		(end 82.630772 -70.44944)
		(width 0.10795)
		(layer "F.Cu")
		(net "TP_CPU1_RSVD_156")
	)
	(via
		(at 82.630772 -70.44944)
		(size 0.508)
		(drill 0.254)
		(layers "F.Cu" "B.Cu")
		(net "TP_CPU1_RSVD_156")
	)
	(segment
		(start 84.919312 -70.44944)
		(end 84.347812 -70.44944)
		(width 0.10795)
		(layer "F.Cu")
		(net "TP_CPU1_RSVD_157")
	)
	(via
		(at 84.347812 -70.44944)
		(size 0.508)
		(drill 0.254)
		(layers "F.Cu" "B.Cu")
		(net "TP_CPU1_RSVD_157")
	)
	(segment
		(start 86.636352 -70.44944)
		(end 86.064852 -70.44944)
		(width 0.10795)
		(layer "F.Cu")
		(net "TP_CPU1_RSVD_158")
	)
	(via
		(at 86.064852 -70.44944)
		(size 0.508)
		(drill 0.254)
		(layers "F.Cu" "B.Cu")
		(net "TP_CPU1_RSVD_158")
	)
	(segment
		(start 86.434168 -52.416202)
		(end 86.434168 -51.996848)
		(width 0.10795)
		(layer "F.Cu")
		(net "TP_CPU1_RSVD_274")
	)
	(segment
		(start 86.434168 -51.996848)
		(end 86.064852 -51.627532)
		(width 0.10795)
		(layer "F.Cu")
		(net "TP_CPU1_RSVD_274")
	)
	(segment
		(start 86.636352 -52.618386)
		(end 86.434168 -52.416202)
		(width 0.10795)
		(layer "F.Cu")
		(net "TP_CPU1_RSVD_274")
	)
	(via
		(at 86.064852 -51.627532)
		(size 0.508)
		(drill 0.254)
		(layers "F.Cu" "B.Cu")
		(net "TP_CPU1_RSVD_274")
	)
	(segment
		(start 84.060792 -69.953886)
		(end 83.489292 -69.953886)
		(width 0.10795)
		(layer "F.Cu")
		(net "TP_CPU1_RSVD_163")
	)
	(via
		(at 83.489292 -69.953886)
		(size 0.508)
		(drill 0.254)
		(layers "F.Cu" "B.Cu")
		(net "TP_CPU1_RSVD_163")
	)
	(segment
		(start 85.777832 -69.953886)
		(end 85.206332 -69.953886)
		(width 0.10795)
		(layer "F.Cu")
		(net "TP_CPU1_RSVD_164")
	)
	(via
		(at 85.206332 -69.953886)
		(size 0.508)
		(drill 0.254)
		(layers "F.Cu" "B.Cu")
		(net "TP_CPU1_RSVD_164")
	)
	(segment
		(start 71.183246 -69.45884)
		(end 70.611746 -69.45884)
		(width 0.10795)
		(layer "F.Cu")
		(net "TP_CPU1_RSVD_170")
	)
	(via
		(at 70.611746 -69.45884)
		(size 0.508)
		(drill 0.254)
		(layers "F.Cu" "B.Cu")
		(net "TP_CPU1_RSVD_170")
	)
	(segment
		(start 74.617326 -69.45884)
		(end 74.045826 -69.45884)
		(width 0.10795)
		(layer "F.Cu")
		(net "TP_CPU1_RSVD_171")
	)
	(via
		(at 74.045826 -69.45884)
		(size 0.508)
		(drill 0.254)
		(layers "F.Cu" "B.Cu")
		(net "TP_CPU1_RSVD_171")
	)
	(segment
		(start 76.334366 -69.45884)
		(end 75.762866 -69.45884)
		(width 0.10795)
		(layer "F.Cu")
		(net "TP_CPU1_RSVD_172")
	)
	(via
		(at 75.762866 -69.45884)
		(size 0.508)
		(drill 0.254)
		(layers "F.Cu" "B.Cu")
		(net "TP_CPU1_RSVD_172")
	)
	(segment
		(start 84.919312 -69.45884)
		(end 84.347812 -69.45884)
		(width 0.10795)
		(layer "F.Cu")
		(net "TP_CPU1_RSVD_173")
	)
	(via
		(at 84.347812 -69.45884)
		(size 0.508)
		(drill 0.254)
		(layers "F.Cu" "B.Cu")
		(net "TP_CPU1_RSVD_173")
	)
	(segment
		(start 85.777832 -52.12334)
		(end 86.064852 -52.618132)
		(width 0.10795)
		(layer "F.Cu")
		(net "TP_CPU1_RSVD_277")
	)
	(via
		(at 86.064852 -52.618132)
		(size 0.508)
		(drill 0.254)
		(layers "F.Cu" "B.Cu")
		(net "TP_CPU1_RSVD_277")
	)
	(segment
		(start 86.636352 -68.46824)
		(end 86.064852 -68.46824)
		(width 0.10795)
		(layer "F.Cu")
		(net "TP_CPU1_RSVD_184")
	)
	(via
		(at 86.064852 -68.46824)
		(size 0.508)
		(drill 0.254)
		(layers "F.Cu" "B.Cu")
		(net "TP_CPU1_RSVD_184")
	)
	(segment
		(start 75.475846 -67.972686)
		(end 74.904346 -67.972686)
		(width 0.10795)
		(layer "F.Cu")
		(net "TP_CPU1_RSVD_186")
	)
	(via
		(at 74.904346 -67.972686)
		(size 0.508)
		(drill 0.254)
		(layers "F.Cu" "B.Cu")
		(net "TP_CPU1_RSVD_186")
	)
	(segment
		(start 88.353392 -66.48704)
		(end 87.781892 -66.48704)
		(width 0.10795)
		(layer "F.Cu")
		(net "TP_CPU1_RSVD_190")
	)
	(via
		(at 162.841178 -119.885206)
		(size 0.762)
		(drill 0.3048)
		(layers "F.Cu" "B.Cu")
		(net "TP_CPU1_RSVD_190")
	)
	(via
		(at 87.781892 -66.48704)
		(size 0.508)
		(drill 0.254)
		(layers "F.Cu" "B.Cu")
		(net "TP_CPU1_RSVD_190")
	)
	(segment
		(start 88.618822 -66.582036)
		(end 88.640412 -66.582036)
		(width 0.0889)
		(layer "In9.Cu")
		(net "TP_CPU1_RSVD_190")
	)
	(segment
		(start 157.141418 -124.07773)
		(end 159.417004 -124.07773)
		(width 0.089408)
		(layer "In9.Cu")
		(net "TP_CPU1_RSVD_190")
	)
	(segment
		(start 87.781892 -66.148966)
		(end 87.839804 -66.091054)
		(width 0.0889)
		(layer "In9.Cu")
		(net "TP_CPU1_RSVD_190")
	)
	(segment
		(start 120.479312 -87.203534)
		(end 120.500902 -87.203534)
		(width 0.0889)
		(layer "In9.Cu")
		(net "TP_CPU1_RSVD_190")
	)
	(segment
		(start 90.449908 -79.955136)
		(end 91.54287 -79.955136)
		(width 0.0889)
		(layer "In9.Cu")
		(net "TP_CPU1_RSVD_190")
	)
	(segment
		(start 162.692588 -119.885206)
		(end 162.841178 -119.885206)
		(width 0.089408)
		(layer "In9.Cu")
		(net "TP_CPU1_RSVD_190")
	)
	(segment
		(start 116.553742 -85.18271)
		(end 117.455188 -86.084156)
		(width 0.0889)
		(layer "In9.Cu")
		(net "TP_CPU1_RSVD_190")
	)
	(segment
		(start 129.926588 -87.699088)
		(end 129.962148 -87.699088)
		(width 0.0889)
		(layer "In9.Cu")
		(net "TP_CPU1_RSVD_190")
	)
	(segment
		(start 121.341388 -87.699088)
		(end 121.376948 -87.699088)
		(width 0.0889)
		(layer "In9.Cu")
		(net "TP_CPU1_RSVD_190")
	)
	(segment
		(start 141.451584 -87.403686)
		(end 141.552676 -87.578692)
		(width 0.0889)
		(layer "In9.Cu")
		(net "TP_CPU1_RSVD_190")
	)
	(segment
		(start 160.884362 -121.693432)
		(end 162.692588 -119.885206)
		(width 0.089408)
		(layer "In9.Cu")
		(net "TP_CPU1_RSVD_190")
	)
	(segment
		(start 145.385028 -92.797884)
		(end 145.385028 -113.131092)
		(width 0.089408)
		(layer "In9.Cu")
		(net "TP_CPU1_RSVD_190")
	)
	(segment
		(start 143.155162 -87.203534)
		(end 143.585692 -87.634064)
		(width 0.089408)
		(layer "In9.Cu")
		(net "TP_CPU1_RSVD_190")
	)
	(segment
		(start 88.977978 -67.757548)
		(end 88.986868 -67.771772)
		(width 0.0889)
		(layer "In9.Cu")
		(net "TP_CPU1_RSVD_190")
	)
	(segment
		(start 135.077454 -87.699088)
		(end 135.113014 -87.699088)
		(width 0.0889)
		(layer "In9.Cu")
		(net "TP_CPU1_RSVD_190")
	)
	(segment
		(start 136.794494 -87.699088)
		(end 136.830054 -87.699088)
		(width 0.0889)
		(layer "In9.Cu")
		(net "TP_CPU1_RSVD_190")
	)
	(segment
		(start 118.81866 -86.084156)
		(end 119.097806 -86.363302)
		(width 0.0889)
		(layer "In9.Cu")
		(net "TP_CPU1_RSVD_190")
	)
	(segment
		(start 128.209548 -87.699088)
		(end 128.245108 -87.699088)
		(width 0.0889)
		(layer "In9.Cu")
		(net "TP_CPU1_RSVD_190")
	)
	(segment
		(start 159.417004 -124.07773)
		(end 160.884362 -122.610372)
		(width 0.089408)
		(layer "In9.Cu")
		(net "TP_CPU1_RSVD_190")
	)
	(segment
		(start 119.097806 -86.363302)
		(end 119.141748 -86.432898)
		(width 0.0889)
		(layer "In9.Cu")
		(net "TP_CPU1_RSVD_190")
	)
	(segment
		(start 142.731744 -87.203534)
		(end 143.155162 -87.203534)
		(width 0.0889)
		(layer "In9.Cu")
		(net "TP_CPU1_RSVD_190")
	)
	(segment
		(start 145.385028 -113.131092)
		(end 152.219406 -119.96547)
		(width 0.089408)
		(layer "In9.Cu")
		(net "TP_CPU1_RSVD_190")
	)
	(segment
		(start 113.068354 -83.264502)
		(end 115.298728 -83.264502)
		(width 0.0889)
		(layer "In9.Cu")
		(net "TP_CPU1_RSVD_190")
	)
	(segment
		(start 110.7948 -80.990948)
		(end 113.068354 -83.264502)
		(width 0.0889)
		(layer "In9.Cu")
		(net "TP_CPU1_RSVD_190")
	)
	(segment
		(start 92.578682 -80.990948)
		(end 110.7948 -80.990948)
		(width 0.0889)
		(layer "In9.Cu")
		(net "TP_CPU1_RSVD_190")
	)
	(segment
		(start 116.553742 -84.519516)
		(end 116.553742 -85.18271)
		(width 0.0889)
		(layer "In9.Cu")
		(net "TP_CPU1_RSVD_190")
	)
	(segment
		(start 120.844056 -87.397844)
		(end 120.847358 -87.403686)
		(width 0.0889)
		(layer "In9.Cu")
		(net "TP_CPU1_RSVD_190")
	)
	(segment
		(start 152.219406 -119.96547)
		(end 152.219406 -123.41225)
		(width 0.089408)
		(layer "In9.Cu")
		(net "TP_CPU1_RSVD_190")
	)
	(segment
		(start 156.738828 -124.48032)
		(end 157.141418 -124.07773)
		(width 0.089408)
		(layer "In9.Cu")
		(net "TP_CPU1_RSVD_190")
	)
	(segment
		(start 143.585692 -87.634064)
		(end 143.585692 -90.998548)
		(width 0.089408)
		(layer "In9.Cu")
		(net "TP_CPU1_RSVD_190")
	)
	(segment
		(start 126.492508 -87.699088)
		(end 126.528068 -87.699088)
		(width 0.0889)
		(layer "In9.Cu")
		(net "TP_CPU1_RSVD_190")
	)
	(segment
		(start 160.884362 -122.610372)
		(end 160.884362 -121.693432)
		(width 0.089408)
		(layer "In9.Cu")
		(net "TP_CPU1_RSVD_190")
	)
	(segment
		(start 88.986868 -67.771772)
		(end 88.986868 -67.772788)
		(width 0.0889)
		(layer "In9.Cu")
		(net "TP_CPU1_RSVD_190")
	)
	(segment
		(start 115.298728 -83.264502)
		(end 116.553742 -84.519516)
		(width 0.0889)
		(layer "In9.Cu")
		(net "TP_CPU1_RSVD_190")
	)
	(segment
		(start 87.781892 -66.48704)
		(end 87.781892 -66.148966)
		(width 0.0889)
		(layer "In9.Cu")
		(net "TP_CPU1_RSVD_190")
	)
	(segment
		(start 124.775468 -87.699088)
		(end 124.811028 -87.699088)
		(width 0.0889)
		(layer "In9.Cu")
		(net "TP_CPU1_RSVD_190")
	)
	(segment
		(start 143.585692 -90.998548)
		(end 145.385028 -92.797884)
		(width 0.089408)
		(layer "In9.Cu")
		(net "TP_CPU1_RSVD_190")
	)
	(segment
		(start 152.219406 -123.41225)
		(end 153.287476 -124.48032)
		(width 0.089408)
		(layer "In9.Cu")
		(net "TP_CPU1_RSVD_190")
	)
	(segment
		(start 123.058428 -87.699088)
		(end 123.093988 -87.699088)
		(width 0.0889)
		(layer "In9.Cu")
		(net "TP_CPU1_RSVD_190")
	)
	(segment
		(start 117.455188 -86.084156)
		(end 118.81866 -86.084156)
		(width 0.0889)
		(layer "In9.Cu")
		(net "TP_CPU1_RSVD_190")
	)
	(segment
		(start 89.136474 -78.641702)
		(end 90.449908 -79.955136)
		(width 0.0889)
		(layer "In9.Cu")
		(net "TP_CPU1_RSVD_190")
	)
	(segment
		(start 153.287476 -124.48032)
		(end 156.738828 -124.48032)
		(width 0.089408)
		(layer "In9.Cu")
		(net "TP_CPU1_RSVD_190")
	)
	(segment
		(start 132.173218 -87.403686)
		(end 132.179822 -87.392256)
		(width 0.0889)
		(layer "In9.Cu")
		(net "TP_CPU1_RSVD_190")
	)
	(segment
		(start 91.54287 -79.955136)
		(end 92.578682 -80.990948)
		(width 0.0889)
		(layer "In9.Cu")
		(net "TP_CPU1_RSVD_190")
	)
	(segment
		(start 89.136474 -68.338954)
		(end 89.136474 -78.641702)
		(width 0.0889)
		(layer "In9.Cu")
		(net "TP_CPU1_RSVD_190")
	)
	(segment
		(start 138.511534 -87.699088)
		(end 138.547094 -87.699088)
		(width 0.0889)
		(layer "In9.Cu")
		(net "TP_CPU1_RSVD_190")
	)
	(arc
		(start 123.093988 -87.699088)
		(mid 123.379412 -87.615621)
		(end 123.588018 -87.403686)
		(width 0.0889)
		(layer "In9.Cu")
		(net "TP_CPU1_RSVD_190")
	)
	(arc
		(start 136.300464 -87.403686)
		(mid 136.509072 -87.615618)
		(end 136.794494 -87.699088)
		(width 0.0889)
		(layer "In9.Cu")
		(net "TP_CPU1_RSVD_190")
	)
	(arc
		(start 124.281438 -87.403686)
		(mid 124.490046 -87.615618)
		(end 124.775468 -87.699088)
		(width 0.0889)
		(layer "In9.Cu")
		(net "TP_CPU1_RSVD_190")
	)
	(arc
		(start 119.719344 -86.7156)
		(mid 119.875138 -86.782734)
		(end 119.989092 -86.908386)
		(width 0.0889)
		(layer "In9.Cu")
		(net "TP_CPU1_RSVD_190")
	)
	(arc
		(start 131.149598 -87.403686)
		(mid 131.661408 -87.699353)
		(end 132.173218 -87.403686)
		(width 0.0889)
		(layer "In9.Cu")
		(net "TP_CPU1_RSVD_190")
	)
	(arc
		(start 135.113014 -87.699088)
		(mid 135.398438 -87.615621)
		(end 135.607044 -87.403686)
		(width 0.0889)
		(layer "In9.Cu")
		(net "TP_CPU1_RSVD_190")
	)
	(arc
		(start 138.547094 -87.699088)
		(mid 138.832518 -87.615621)
		(end 139.041124 -87.403686)
		(width 0.0889)
		(layer "In9.Cu")
		(net "TP_CPU1_RSVD_190")
	)
	(arc
		(start 121.870978 -87.403686)
		(mid 122.217688 -87.203375)
		(end 122.564398 -87.403686)
		(width 0.0889)
		(layer "In9.Cu")
		(net "TP_CPU1_RSVD_190")
	)
	(arc
		(start 120.500902 -87.203534)
		(mid 120.698063 -87.255493)
		(end 120.844056 -87.397844)
		(width 0.0889)
		(layer "In9.Cu")
		(net "TP_CPU1_RSVD_190")
	)
	(arc
		(start 139.041124 -87.403686)
		(mid 139.387834 -87.203375)
		(end 139.734544 -87.403686)
		(width 0.0889)
		(layer "In9.Cu")
		(net "TP_CPU1_RSVD_190")
	)
	(arc
		(start 135.607044 -87.403686)
		(mid 135.953754 -87.203375)
		(end 136.300464 -87.403686)
		(width 0.0889)
		(layer "In9.Cu")
		(net "TP_CPU1_RSVD_190")
	)
	(arc
		(start 129.962148 -87.699088)
		(mid 130.247572 -87.615621)
		(end 130.456178 -87.403686)
		(width 0.0889)
		(layer "In9.Cu")
		(net "TP_CPU1_RSVD_190")
	)
	(arc
		(start 127.022098 -87.403686)
		(mid 127.368808 -87.203375)
		(end 127.715518 -87.403686)
		(width 0.0889)
		(layer "In9.Cu")
		(net "TP_CPU1_RSVD_190")
	)
	(arc
		(start 137.324084 -87.403686)
		(mid 137.670794 -87.203375)
		(end 138.017504 -87.403686)
		(width 0.0889)
		(layer "In9.Cu")
		(net "TP_CPU1_RSVD_190")
	)
	(arc
		(start 87.839804 -66.091054)
		(mid 88.006649 -66.155867)
		(end 88.128602 -66.286888)
		(width 0.0889)
		(layer "In9.Cu")
		(net "TP_CPU1_RSVD_190")
	)
	(arc
		(start 125.998478 -87.403686)
		(mid 126.207086 -87.615618)
		(end 126.492508 -87.699088)
		(width 0.0889)
		(layer "In9.Cu")
		(net "TP_CPU1_RSVD_190")
	)
	(arc
		(start 119.141748 -86.432898)
		(mid 119.347231 -86.629715)
		(end 119.620792 -86.70798)
		(width 0.0889)
		(layer "In9.Cu")
		(net "TP_CPU1_RSVD_190")
	)
	(arc
		(start 133.890004 -87.403686)
		(mid 134.236714 -87.203375)
		(end 134.583424 -87.403686)
		(width 0.0889)
		(layer "In9.Cu")
		(net "TP_CPU1_RSVD_190")
	)
	(arc
		(start 140.758164 -87.403686)
		(mid 141.104874 -87.203375)
		(end 141.451584 -87.403686)
		(width 0.0889)
		(layer "In9.Cu")
		(net "TP_CPU1_RSVD_190")
	)
	(arc
		(start 119.989092 -86.908386)
		(mid 120.196096 -87.11925)
		(end 120.479312 -87.203534)
		(width 0.0889)
		(layer "In9.Cu")
		(net "TP_CPU1_RSVD_190")
	)
	(arc
		(start 124.811028 -87.699088)
		(mid 125.096452 -87.615621)
		(end 125.305058 -87.403686)
		(width 0.0889)
		(layer "In9.Cu")
		(net "TP_CPU1_RSVD_190")
	)
	(arc
		(start 88.640412 -66.582036)
		(mid 88.986838 -66.782013)
		(end 88.986868 -67.181984)
		(width 0.0889)
		(layer "In9.Cu")
		(net "TP_CPU1_RSVD_190")
	)
	(arc
		(start 88.986868 -67.181984)
		(mid 88.907679 -67.468599)
		(end 88.977978 -67.757548)
		(width 0.0889)
		(layer "In9.Cu")
		(net "TP_CPU1_RSVD_190")
	)
	(arc
		(start 130.456178 -87.403686)
		(mid 130.802888 -87.203375)
		(end 131.149598 -87.403686)
		(width 0.0889)
		(layer "In9.Cu")
		(net "TP_CPU1_RSVD_190")
	)
	(arc
		(start 128.245108 -87.699088)
		(mid 128.530532 -87.615621)
		(end 128.739138 -87.403686)
		(width 0.0889)
		(layer "In9.Cu")
		(net "TP_CPU1_RSVD_190")
	)
	(arc
		(start 88.128602 -66.286888)
		(mid 88.335606 -66.497752)
		(end 88.618822 -66.582036)
		(width 0.0889)
		(layer "In9.Cu")
		(net "TP_CPU1_RSVD_190")
	)
	(arc
		(start 127.715518 -87.403686)
		(mid 127.924126 -87.615618)
		(end 128.209548 -87.699088)
		(width 0.0889)
		(layer "In9.Cu")
		(net "TP_CPU1_RSVD_190")
	)
	(arc
		(start 132.866384 -87.403686)
		(mid 133.378194 -87.699353)
		(end 133.890004 -87.403686)
		(width 0.0889)
		(layer "In9.Cu")
		(net "TP_CPU1_RSVD_190")
	)
	(arc
		(start 134.583424 -87.403686)
		(mid 134.792032 -87.615618)
		(end 135.077454 -87.699088)
		(width 0.0889)
		(layer "In9.Cu")
		(net "TP_CPU1_RSVD_190")
	)
	(arc
		(start 121.376948 -87.699088)
		(mid 121.662372 -87.615621)
		(end 121.870978 -87.403686)
		(width 0.0889)
		(layer "In9.Cu")
		(net "TP_CPU1_RSVD_190")
	)
	(arc
		(start 122.564398 -87.403686)
		(mid 122.773006 -87.615618)
		(end 123.058428 -87.699088)
		(width 0.0889)
		(layer "In9.Cu")
		(net "TP_CPU1_RSVD_190")
	)
	(arc
		(start 125.305058 -87.403686)
		(mid 125.651768 -87.203375)
		(end 125.998478 -87.403686)
		(width 0.0889)
		(layer "In9.Cu")
		(net "TP_CPU1_RSVD_190")
	)
	(arc
		(start 138.017504 -87.403686)
		(mid 138.226112 -87.615618)
		(end 138.511534 -87.699088)
		(width 0.0889)
		(layer "In9.Cu")
		(net "TP_CPU1_RSVD_190")
	)
	(arc
		(start 136.830054 -87.699088)
		(mid 137.115478 -87.615621)
		(end 137.324084 -87.403686)
		(width 0.0889)
		(layer "In9.Cu")
		(net "TP_CPU1_RSVD_190")
	)
	(arc
		(start 129.432558 -87.403686)
		(mid 129.641166 -87.615618)
		(end 129.926588 -87.699088)
		(width 0.0889)
		(layer "In9.Cu")
		(net "TP_CPU1_RSVD_190")
	)
	(arc
		(start 123.588018 -87.403686)
		(mid 123.934728 -87.203375)
		(end 124.281438 -87.403686)
		(width 0.0889)
		(layer "In9.Cu")
		(net "TP_CPU1_RSVD_190")
	)
	(arc
		(start 89.136474 -68.337176)
		(mid 89.136474 -68.338065)
		(end 89.136474 -68.338954)
		(width 0.0889)
		(layer "In9.Cu")
		(net "TP_CPU1_RSVD_190")
	)
	(arc
		(start 132.179822 -87.392256)
		(mid 132.526339 -87.203441)
		(end 132.866384 -87.403686)
		(width 0.0889)
		(layer "In9.Cu")
		(net "TP_CPU1_RSVD_190")
	)
	(arc
		(start 126.528068 -87.699088)
		(mid 126.813492 -87.615621)
		(end 127.022098 -87.403686)
		(width 0.0889)
		(layer "In9.Cu")
		(net "TP_CPU1_RSVD_190")
	)
	(arc
		(start 139.734544 -87.403686)
		(mid 140.246354 -87.699353)
		(end 140.758164 -87.403686)
		(width 0.0889)
		(layer "In9.Cu")
		(net "TP_CPU1_RSVD_190")
	)
	(arc
		(start 141.552676 -87.578692)
		(mid 142.076839 -87.722431)
		(end 142.515082 -87.400892)
		(width 0.0889)
		(layer "In9.Cu")
		(net "TP_CPU1_RSVD_190")
	)
	(arc
		(start 119.620792 -86.70798)
		(mid 119.670291 -86.70891)
		(end 119.719344 -86.7156)
		(width 0.0889)
		(layer "In9.Cu")
		(net "TP_CPU1_RSVD_190")
	)
	(arc
		(start 88.986868 -67.772788)
		(mid 89.099213 -68.045033)
		(end 89.136474 -68.337176)
		(width 0.0889)
		(layer "In9.Cu")
		(net "TP_CPU1_RSVD_190")
	)
	(arc
		(start 120.847358 -87.403686)
		(mid 121.055966 -87.615618)
		(end 121.341388 -87.699088)
		(width 0.0889)
		(layer "In9.Cu")
		(net "TP_CPU1_RSVD_190")
	)
	(arc
		(start 142.515082 -87.400892)
		(mid 142.606196 -87.2833)
		(end 142.731744 -87.203534)
		(width 0.0889)
		(layer "In9.Cu")
		(net "TP_CPU1_RSVD_190")
	)
	(arc
		(start 128.739138 -87.403686)
		(mid 129.085848 -87.203375)
		(end 129.432558 -87.403686)
		(width 0.0889)
		(layer "In9.Cu")
		(net "TP_CPU1_RSVD_190")
	)
	(segment
		(start 86.636352 -69.45884)
		(end 86.064852 -69.45884)
		(width 0.10795)
		(layer "F.Cu")
		(net "TP_CPU1_RSVD_174")
	)
	(via
		(at 86.064852 -69.45884)
		(size 0.508)
		(drill 0.254)
		(layers "F.Cu" "B.Cu")
		(net "TP_CPU1_RSVD_174")
	)
	(segment
		(start 131.089908 -71.258938)
		(end 131.661408 -71.258938)
		(width 0.10795)
		(layer "F.Cu")
		(net "TP_CPU1_RSVD_178")
	)
	(via
		(at 131.661408 -71.258938)
		(size 0.508)
		(drill 0.254)
		(layers "F.Cu" "B.Cu")
		(net "TP_CPU1_RSVD_178")
	)
	(segment
		(start 75.475846 -68.963286)
		(end 74.904346 -68.963286)
		(width 0.10795)
		(layer "F.Cu")
		(net "TP_CPU1_RSVD_179")
	)
	(via
		(at 74.904346 -68.963286)
		(size 0.508)
		(drill 0.254)
		(layers "F.Cu" "B.Cu")
		(net "TP_CPU1_RSVD_179")
	)
	(segment
		(start 89.211912 -65.000886)
		(end 88.640412 -65.000886)
		(width 0.10795)
		(layer "F.Cu")
		(net "TP_CPU1_RSVD_204")
	)
	(via
		(at 88.640412 -65.000886)
		(size 0.508)
		(drill 0.254)
		(layers "F.Cu" "B.Cu")
		(net "TP_CPU1_RSVD_204")
	)
	(via
		(at 161.044382 -118.780052)
		(size 0.762)
		(drill 0.3048)
		(layers "F.Cu" "B.Cu")
		(net "TP_CPU1_RSVD_204")
	)
	(segment
		(start 110.16615 -68.265548)
		(end 111.350552 -69.44995)
		(width 0.0889)
		(layer "In9.Cu")
		(net "TP_CPU1_RSVD_204")
	)
	(segment
		(start 120.105424 -69.44995)
		(end 120.829324 -68.72605)
		(width 0.0889)
		(layer "In9.Cu")
		(net "TP_CPU1_RSVD_204")
	)
	(segment
		(start 125.630178 -70.363334)
		(end 125.662944 -70.363334)
		(width 0.0889)
		(layer "In9.Cu")
		(net "TP_CPU1_RSVD_204")
	)
	(segment
		(start 126.492508 -70.858888)
		(end 126.525274 -70.858888)
		(width 0.0889)
		(layer "In9.Cu")
		(net "TP_CPU1_RSVD_204")
	)
	(segment
		(start 124.775468 -69.868288)
		(end 124.808234 -69.868288)
		(width 0.0889)
		(layer "In9.Cu")
		(net "TP_CPU1_RSVD_204")
	)
	(segment
		(start 92.052648 -66.582036)
		(end 92.08516 -66.582036)
		(width 0.0889)
		(layer "In9.Cu")
		(net "TP_CPU1_RSVD_204")
	)
	(segment
		(start 130.295904 -75.4126)
		(end 130.291078 -75.421236)
		(width 0.0889)
		(layer "In9.Cu")
		(net "TP_CPU1_RSVD_204")
	)
	(segment
		(start 130.789934 -78.288388)
		(end 130.814064 -78.288388)
		(width 0.0889)
		(layer "In9.Cu")
		(net "TP_CPU1_RSVD_204")
	)
	(segment
		(start 130.291078 -75.421236)
		(end 130.284728 -75.431904)
		(width 0.0889)
		(layer "In9.Cu")
		(net "TP_CPU1_RSVD_204")
	)
	(segment
		(start 123.058428 -68.877688)
		(end 123.091194 -68.877688)
		(width 0.0889)
		(layer "In9.Cu")
		(net "TP_CPU1_RSVD_204")
	)
	(segment
		(start 90.335608 -65.591436)
		(end 90.368374 -65.591436)
		(width 0.0889)
		(layer "In9.Cu")
		(net "TP_CPU1_RSVD_204")
	)
	(segment
		(start 153.222706 -119.549418)
		(end 153.222706 -121.0564)
		(width 0.089408)
		(layer "In9.Cu")
		(net "TP_CPU1_RSVD_204")
	)
	(segment
		(start 130.291078 -76.411836)
		(end 130.284728 -76.422504)
		(width 0.0889)
		(layer "In9.Cu")
		(net "TP_CPU1_RSVD_204")
	)
	(segment
		(start 123.913138 -69.372734)
		(end 123.945904 -69.372734)
		(width 0.0889)
		(layer "In9.Cu")
		(net "TP_CPU1_RSVD_204")
	)
	(segment
		(start 134.215124 -80.269334)
		(end 134.24789 -80.269334)
		(width 0.0889)
		(layer "In9.Cu")
		(net "TP_CPU1_RSVD_204")
	)
	(segment
		(start 137.649204 -82.250534)
		(end 137.68197 -82.250534)
		(width 0.0889)
		(layer "In9.Cu")
		(net "TP_CPU1_RSVD_204")
	)
	(segment
		(start 142.694914 -85.222334)
		(end 143.304006 -85.222334)
		(width 0.0889)
		(layer "In9.Cu")
		(net "TP_CPU1_RSVD_204")
	)
	(segment
		(start 131.639818 -78.783688)
		(end 131.661408 -78.783688)
		(width 0.0889)
		(layer "In9.Cu")
		(net "TP_CPU1_RSVD_204")
	)
	(segment
		(start 140.228574 -83.736688)
		(end 140.26134 -83.736688)
		(width 0.0889)
		(layer "In9.Cu")
		(net "TP_CPU1_RSVD_204")
	)
	(segment
		(start 92.085414 -66.581782)
		(end 92.088716 -66.581782)
		(width 0.0889)
		(layer "In9.Cu")
		(net "TP_CPU1_RSVD_204")
	)
	(segment
		(start 111.350552 -69.44995)
		(end 120.105424 -69.44995)
		(width 0.0889)
		(layer "In9.Cu")
		(net "TP_CPU1_RSVD_204")
	)
	(segment
		(start 127.347218 -71.353934)
		(end 127.379984 -71.353934)
		(width 0.0889)
		(layer "In9.Cu")
		(net "TP_CPU1_RSVD_204")
	)
	(segment
		(start 146.388328 -92.381832)
		(end 146.388328 -112.71504)
		(width 0.089408)
		(layer "In9.Cu")
		(net "TP_CPU1_RSVD_204")
	)
	(segment
		(start 141.083284 -84.231734)
		(end 141.293596 -84.231734)
		(width 0.0889)
		(layer "In9.Cu")
		(net "TP_CPU1_RSVD_204")
	)
	(segment
		(start 129.926588 -72.840088)
		(end 129.959354 -72.840088)
		(width 0.0889)
		(layer "In9.Cu")
		(net "TP_CPU1_RSVD_204")
	)
	(segment
		(start 130.291078 -74.030332)
		(end 130.295904 -74.038968)
		(width 0.0889)
		(layer "In9.Cu")
		(net "TP_CPU1_RSVD_204")
	)
	(segment
		(start 143.304006 -85.222334)
		(end 144.588992 -86.50732)
		(width 0.089408)
		(layer "In9.Cu")
		(net "TP_CPU1_RSVD_204")
	)
	(segment
		(start 93.181932 -67.872356)
		(end 93.575378 -68.265548)
		(width 0.0889)
		(layer "In9.Cu")
		(net "TP_CPU1_RSVD_204")
	)
	(segment
		(start 129.064258 -72.344534)
		(end 129.097024 -72.344534)
		(width 0.0889)
		(layer "In9.Cu")
		(net "TP_CPU1_RSVD_204")
	)
	(segment
		(start 159.526478 -118.780052)
		(end 161.044382 -118.780052)
		(width 0.089408)
		(layer "In9.Cu")
		(net "TP_CPU1_RSVD_204")
	)
	(segment
		(start 159.329882 -118.976648)
		(end 159.526478 -118.780052)
		(width 0.089408)
		(layer "In9.Cu")
		(net "TP_CPU1_RSVD_204")
	)
	(segment
		(start 146.388328 -112.71504)
		(end 153.222706 -119.549418)
		(width 0.089408)
		(layer "In9.Cu")
		(net "TP_CPU1_RSVD_204")
	)
	(segment
		(start 120.829324 -68.72605)
		(end 121.562876 -68.72605)
		(width 0.0889)
		(layer "In9.Cu")
		(net "TP_CPU1_RSVD_204")
	)
	(segment
		(start 156.386784 -123.766072)
		(end 156.648404 -123.504452)
		(width 0.089408)
		(layer "In9.Cu")
		(net "TP_CPU1_RSVD_204")
	)
	(segment
		(start 135.932164 -81.259934)
		(end 135.96493 -81.259934)
		(width 0.0889)
		(layer "In9.Cu")
		(net "TP_CPU1_RSVD_204")
	)
	(segment
		(start 144.588992 -86.50732)
		(end 144.588992 -90.582496)
		(width 0.089408)
		(layer "In9.Cu")
		(net "TP_CPU1_RSVD_204")
	)
	(segment
		(start 92.935806 -67.301364)
		(end 93.181932 -67.872356)
		(width 0.0889)
		(layer "In9.Cu")
		(net "TP_CPU1_RSVD_204")
	)
	(segment
		(start 154.69235 -123.766072)
		(end 156.386784 -123.766072)
		(width 0.089408)
		(layer "In9.Cu")
		(net "TP_CPU1_RSVD_204")
	)
	(segment
		(start 135.077454 -80.764888)
		(end 135.11022 -80.764888)
		(width 0.0889)
		(layer "In9.Cu")
		(net "TP_CPU1_RSVD_204")
	)
	(segment
		(start 141.826742 -84.6963)
		(end 142.102332 -84.71662)
		(width 0.0889)
		(layer "In9.Cu")
		(net "TP_CPU1_RSVD_204")
	)
	(segment
		(start 160.090104 -122.593862)
		(end 160.090104 -121.247662)
		(width 0.089408)
		(layer "In9.Cu")
		(net "TP_CPU1_RSVD_204")
	)
	(segment
		(start 92.421202 -66.781934)
		(end 92.539058 -66.986404)
		(width 0.0889)
		(layer "In9.Cu")
		(net "TP_CPU1_RSVD_204")
	)
	(segment
		(start 88.983566 -64.795146)
		(end 88.986868 -64.800988)
		(width 0.0889)
		(layer "In9.Cu")
		(net "TP_CPU1_RSVD_204")
	)
	(segment
		(start 93.575378 -68.265548)
		(end 110.16615 -68.265548)
		(width 0.0889)
		(layer "In9.Cu")
		(net "TP_CPU1_RSVD_204")
	)
	(segment
		(start 133.360414 -79.774288)
		(end 133.39318 -79.774288)
		(width 0.0889)
		(layer "In9.Cu")
		(net "TP_CPU1_RSVD_204")
	)
	(segment
		(start 121.562876 -68.72605)
		(end 121.970292 -68.318634)
		(width 0.0889)
		(layer "In9.Cu")
		(net "TP_CPU1_RSVD_204")
	)
	(segment
		(start 122.441462 -68.386706)
		(end 122.576336 -68.603114)
		(width 0.0889)
		(layer "In9.Cu")
		(net "TP_CPU1_RSVD_204")
	)
	(segment
		(start 88.640412 -65.000886)
		(end 88.640412 -64.662812)
		(width 0.0889)
		(layer "In9.Cu")
		(net "TP_CPU1_RSVD_204")
	)
	(segment
		(start 130.295904 -76.4032)
		(end 130.291078 -76.411836)
		(width 0.0889)
		(layer "In9.Cu")
		(net "TP_CPU1_RSVD_204")
	)
	(segment
		(start 92.08516 -66.582036)
		(end 92.085414 -66.581782)
		(width 0.0889)
		(layer "In9.Cu")
		(net "TP_CPU1_RSVD_204")
	)
	(segment
		(start 122.347482 -68.318634)
		(end 122.34799 -68.318126)
		(width 0.0889)
		(layer "In9.Cu")
		(net "TP_CPU1_RSVD_204")
	)
	(segment
		(start 132.498084 -79.278988)
		(end 132.537708 -79.278988)
		(width 0.0889)
		(layer "In9.Cu")
		(net "TP_CPU1_RSVD_204")
	)
	(segment
		(start 154.162252 -121.995946)
		(end 154.162252 -123.235974)
		(width 0.089408)
		(layer "In9.Cu")
		(net "TP_CPU1_RSVD_204")
	)
	(segment
		(start 130.295904 -73.4314)
		(end 130.291078 -73.440036)
		(width 0.0889)
		(layer "In9.Cu")
		(net "TP_CPU1_RSVD_204")
	)
	(segment
		(start 156.648404 -123.504452)
		(end 159.179514 -123.504452)
		(width 0.089408)
		(layer "In9.Cu")
		(net "TP_CPU1_RSVD_204")
	)
	(segment
		(start 136.794494 -81.755488)
		(end 136.830308 -81.755488)
		(width 0.0889)
		(layer "In9.Cu")
		(net "TP_CPU1_RSVD_204")
	)
	(segment
		(start 132.004562 -78.977998)
		(end 132.007864 -78.98384)
		(width 0.0889)
		(layer "In9.Cu")
		(net "TP_CPU1_RSVD_204")
	)
	(segment
		(start 138.51636 -82.746088)
		(end 138.5443 -82.746088)
		(width 0.0889)
		(layer "In9.Cu")
		(net "TP_CPU1_RSVD_204")
	)
	(segment
		(start 88.640412 -64.662812)
		(end 88.69807 -64.605154)
		(width 0.0889)
		(layer "In9.Cu")
		(net "TP_CPU1_RSVD_204")
	)
	(segment
		(start 160.090104 -121.247662)
		(end 159.329882 -120.48744)
		(width 0.089408)
		(layer "In9.Cu")
		(net "TP_CPU1_RSVD_204")
	)
	(segment
		(start 139.366244 -83.241134)
		(end 139.39901 -83.241134)
		(width 0.0889)
		(layer "In9.Cu")
		(net "TP_CPU1_RSVD_204")
	)
	(segment
		(start 159.329882 -120.48744)
		(end 159.329882 -118.976648)
		(width 0.089408)
		(layer "In9.Cu")
		(net "TP_CPU1_RSVD_204")
	)
	(segment
		(start 130.291078 -77.402436)
		(end 130.284728 -77.413104)
		(width 0.0889)
		(layer "In9.Cu")
		(net "TP_CPU1_RSVD_204")
	)
	(segment
		(start 144.588992 -90.582496)
		(end 146.388328 -92.381832)
		(width 0.089408)
		(layer "In9.Cu")
		(net "TP_CPU1_RSVD_204")
	)
	(segment
		(start 159.179514 -123.504452)
		(end 160.090104 -122.593862)
		(width 0.089408)
		(layer "In9.Cu")
		(net "TP_CPU1_RSVD_204")
	)
	(segment
		(start 89.480898 -65.09639)
		(end 89.513664 -65.09639)
		(width 0.0889)
		(layer "In9.Cu")
		(net "TP_CPU1_RSVD_204")
	)
	(segment
		(start 121.970292 -68.318634)
		(end 122.347482 -68.318634)
		(width 0.0889)
		(layer "In9.Cu")
		(net "TP_CPU1_RSVD_204")
	)
	(segment
		(start 130.295904 -77.3938)
		(end 130.291078 -77.402436)
		(width 0.0889)
		(layer "In9.Cu")
		(net "TP_CPU1_RSVD_204")
	)
	(segment
		(start 91.197938 -66.08699)
		(end 91.230704 -66.08699)
		(width 0.0889)
		(layer "In9.Cu")
		(net "TP_CPU1_RSVD_204")
	)
	(segment
		(start 153.222706 -121.0564)
		(end 154.162252 -121.995946)
		(width 0.089408)
		(layer "In9.Cu")
		(net "TP_CPU1_RSVD_204")
	)
	(segment
		(start 154.162252 -123.235974)
		(end 154.69235 -123.766072)
		(width 0.089408)
		(layer "In9.Cu")
		(net "TP_CPU1_RSVD_204")
	)
	(segment
		(start 128.209548 -71.849488)
		(end 128.242314 -71.849488)
		(width 0.0889)
		(layer "In9.Cu")
		(net "TP_CPU1_RSVD_204")
	)
	(arc
		(start 140.26134 -83.736688)
		(mid 140.452982 -83.793854)
		(end 140.593064 -83.936586)
		(width 0.0889)
		(layer "In9.Cu")
		(net "TP_CPU1_RSVD_204")
	)
	(arc
		(start 142.102332 -84.71662)
		(mid 142.24433 -84.797083)
		(end 142.346426 -84.924392)
		(width 0.0889)
		(layer "In9.Cu")
		(net "TP_CPU1_RSVD_204")
	)
	(arc
		(start 90.368374 -65.591436)
		(mid 90.562224 -65.647786)
		(end 90.703908 -65.791588)
		(width 0.0889)
		(layer "In9.Cu")
		(net "TP_CPU1_RSVD_204")
	)
	(arc
		(start 133.724904 -79.974186)
		(mid 133.931908 -80.18505)
		(end 134.215124 -80.269334)
		(width 0.0889)
		(layer "In9.Cu")
		(net "TP_CPU1_RSVD_204")
	)
	(arc
		(start 139.39901 -83.241134)
		(mid 139.59286 -83.297484)
		(end 139.734544 -83.441286)
		(width 0.0889)
		(layer "In9.Cu")
		(net "TP_CPU1_RSVD_204")
	)
	(arc
		(start 130.284728 -76.422504)
		(mid 130.21193 -76.713267)
		(end 130.291078 -77.002386)
		(width 0.0889)
		(layer "In9.Cu")
		(net "TP_CPU1_RSVD_204")
	)
	(arc
		(start 124.808234 -69.868288)
		(mid 124.999876 -69.925454)
		(end 125.139958 -70.068186)
		(width 0.0889)
		(layer "In9.Cu")
		(net "TP_CPU1_RSVD_204")
	)
	(arc
		(start 135.441944 -80.964786)
		(mid 135.648948 -81.17565)
		(end 135.932164 -81.259934)
		(width 0.0889)
		(layer "In9.Cu")
		(net "TP_CPU1_RSVD_204")
	)
	(arc
		(start 122.576336 -68.603114)
		(mid 122.783229 -68.800334)
		(end 123.058428 -68.877688)
		(width 0.0889)
		(layer "In9.Cu")
		(net "TP_CPU1_RSVD_204")
	)
	(arc
		(start 137.158984 -81.955386)
		(mid 137.365988 -82.16625)
		(end 137.649204 -82.250534)
		(width 0.0889)
		(layer "In9.Cu")
		(net "TP_CPU1_RSVD_204")
	)
	(arc
		(start 138.5443 -82.746088)
		(mid 138.735942 -82.803254)
		(end 138.876024 -82.945986)
		(width 0.0889)
		(layer "In9.Cu")
		(net "TP_CPU1_RSVD_204")
	)
	(arc
		(start 130.284728 -77.413104)
		(mid 130.290905 -77.993036)
		(end 130.789934 -78.288388)
		(width 0.0889)
		(layer "In9.Cu")
		(net "TP_CPU1_RSVD_204")
	)
	(arc
		(start 130.814064 -78.288388)
		(mid 131.007914 -78.344738)
		(end 131.149598 -78.48854)
		(width 0.0889)
		(layer "In9.Cu")
		(net "TP_CPU1_RSVD_204")
	)
	(arc
		(start 134.583424 -80.469486)
		(mid 134.792032 -80.681418)
		(end 135.077454 -80.764888)
		(width 0.0889)
		(layer "In9.Cu")
		(net "TP_CPU1_RSVD_204")
	)
	(arc
		(start 128.242314 -71.849488)
		(mid 128.433956 -71.906654)
		(end 128.574038 -72.049386)
		(width 0.0889)
		(layer "In9.Cu")
		(net "TP_CPU1_RSVD_204")
	)
	(arc
		(start 131.149598 -78.48854)
		(mid 131.356602 -78.699404)
		(end 131.639818 -78.783688)
		(width 0.0889)
		(layer "In9.Cu")
		(net "TP_CPU1_RSVD_204")
	)
	(arc
		(start 141.48943 -84.41309)
		(mid 141.632675 -84.584952)
		(end 141.826742 -84.6963)
		(width 0.0889)
		(layer "In9.Cu")
		(net "TP_CPU1_RSVD_204")
	)
	(arc
		(start 134.24789 -80.269334)
		(mid 134.44174 -80.325684)
		(end 134.583424 -80.469486)
		(width 0.0889)
		(layer "In9.Cu")
		(net "TP_CPU1_RSVD_204")
	)
	(arc
		(start 129.097024 -72.344534)
		(mid 129.290874 -72.400884)
		(end 129.432558 -72.544686)
		(width 0.0889)
		(layer "In9.Cu")
		(net "TP_CPU1_RSVD_204")
	)
	(arc
		(start 131.661408 -78.783688)
		(mid 131.858569 -78.835647)
		(end 132.004562 -78.977998)
		(width 0.0889)
		(layer "In9.Cu")
		(net "TP_CPU1_RSVD_204")
	)
	(arc
		(start 135.96493 -81.259934)
		(mid 136.15878 -81.316284)
		(end 136.300464 -81.460086)
		(width 0.0889)
		(layer "In9.Cu")
		(net "TP_CPU1_RSVD_204")
	)
	(arc
		(start 137.68197 -82.250534)
		(mid 137.87582 -82.306884)
		(end 138.017504 -82.450686)
		(width 0.0889)
		(layer "In9.Cu")
		(net "TP_CPU1_RSVD_204")
	)
	(arc
		(start 132.007864 -78.98384)
		(mid 132.214868 -79.194704)
		(end 132.498084 -79.278988)
		(width 0.0889)
		(layer "In9.Cu")
		(net "TP_CPU1_RSVD_204")
	)
	(arc
		(start 138.876024 -82.945986)
		(mid 139.083028 -83.15685)
		(end 139.366244 -83.241134)
		(width 0.0889)
		(layer "In9.Cu")
		(net "TP_CPU1_RSVD_204")
	)
	(arc
		(start 125.139958 -70.068186)
		(mid 125.346962 -70.27905)
		(end 125.630178 -70.363334)
		(width 0.0889)
		(layer "In9.Cu")
		(net "TP_CPU1_RSVD_204")
	)
	(arc
		(start 125.998478 -70.563486)
		(mid 126.207086 -70.775418)
		(end 126.492508 -70.858888)
		(width 0.0889)
		(layer "In9.Cu")
		(net "TP_CPU1_RSVD_204")
	)
	(arc
		(start 129.959354 -72.840088)
		(mid 130.292272 -73.042079)
		(end 130.295904 -73.4314)
		(width 0.0889)
		(layer "In9.Cu")
		(net "TP_CPU1_RSVD_204")
	)
	(arc
		(start 88.69807 -64.605154)
		(mid 88.862247 -64.667971)
		(end 88.983566 -64.795146)
		(width 0.0889)
		(layer "In9.Cu")
		(net "TP_CPU1_RSVD_204")
	)
	(arc
		(start 136.300464 -81.460086)
		(mid 136.509072 -81.672018)
		(end 136.794494 -81.755488)
		(width 0.0889)
		(layer "In9.Cu")
		(net "TP_CPU1_RSVD_204")
	)
	(arc
		(start 130.291078 -76.011786)
		(mid 130.344548 -76.206849)
		(end 130.295904 -76.4032)
		(width 0.0889)
		(layer "In9.Cu")
		(net "TP_CPU1_RSVD_204")
	)
	(arc
		(start 142.346426 -84.924392)
		(mid 142.492351 -85.106479)
		(end 142.694914 -85.222334)
		(width 0.0889)
		(layer "In9.Cu")
		(net "TP_CPU1_RSVD_204")
	)
	(arc
		(start 92.775024 -67.164966)
		(mid 92.871369 -67.214359)
		(end 92.935806 -67.301364)
		(width 0.0889)
		(layer "In9.Cu")
		(net "TP_CPU1_RSVD_204")
	)
	(arc
		(start 130.291078 -77.002386)
		(mid 130.344548 -77.197449)
		(end 130.295904 -77.3938)
		(width 0.0889)
		(layer "In9.Cu")
		(net "TP_CPU1_RSVD_204")
	)
	(arc
		(start 130.295904 -74.038968)
		(mid 130.344659 -74.23532)
		(end 130.291078 -74.430382)
		(width 0.0889)
		(layer "In9.Cu")
		(net "TP_CPU1_RSVD_204")
	)
	(arc
		(start 89.845388 -65.296288)
		(mid 90.052392 -65.507152)
		(end 90.335608 -65.591436)
		(width 0.0889)
		(layer "In9.Cu")
		(net "TP_CPU1_RSVD_204")
	)
	(arc
		(start 127.379984 -71.353934)
		(mid 127.573834 -71.410284)
		(end 127.715518 -71.554086)
		(width 0.0889)
		(layer "In9.Cu")
		(net "TP_CPU1_RSVD_204")
	)
	(arc
		(start 133.39318 -79.774288)
		(mid 133.584822 -79.831454)
		(end 133.724904 -79.974186)
		(width 0.0889)
		(layer "In9.Cu")
		(net "TP_CPU1_RSVD_204")
	)
	(arc
		(start 126.525274 -70.858888)
		(mid 126.716916 -70.916054)
		(end 126.856998 -71.058786)
		(width 0.0889)
		(layer "In9.Cu")
		(net "TP_CPU1_RSVD_204")
	)
	(arc
		(start 122.34799 -68.318126)
		(mid 122.401298 -68.343446)
		(end 122.441462 -68.386706)
		(width 0.0889)
		(layer "In9.Cu")
		(net "TP_CPU1_RSVD_204")
	)
	(arc
		(start 129.432558 -72.544686)
		(mid 129.641166 -72.756618)
		(end 129.926588 -72.840088)
		(width 0.0889)
		(layer "In9.Cu")
		(net "TP_CPU1_RSVD_204")
	)
	(arc
		(start 91.562428 -66.286888)
		(mid 91.769432 -66.497752)
		(end 92.052648 -66.582036)
		(width 0.0889)
		(layer "In9.Cu")
		(net "TP_CPU1_RSVD_204")
	)
	(arc
		(start 130.291078 -74.430382)
		(mid 130.211947 -74.725784)
		(end 130.291078 -75.021186)
		(width 0.0889)
		(layer "In9.Cu")
		(net "TP_CPU1_RSVD_204")
	)
	(arc
		(start 92.088716 -66.581782)
		(mid 92.280821 -66.6389)
		(end 92.421202 -66.781934)
		(width 0.0889)
		(layer "In9.Cu")
		(net "TP_CPU1_RSVD_204")
	)
	(arc
		(start 124.281438 -69.572886)
		(mid 124.490046 -69.784818)
		(end 124.775468 -69.868288)
		(width 0.0889)
		(layer "In9.Cu")
		(net "TP_CPU1_RSVD_204")
	)
	(arc
		(start 132.866384 -79.478886)
		(mid 133.074992 -79.690818)
		(end 133.360414 -79.774288)
		(width 0.0889)
		(layer "In9.Cu")
		(net "TP_CPU1_RSVD_204")
	)
	(arc
		(start 89.513664 -65.09639)
		(mid 89.705306 -65.153556)
		(end 89.845388 -65.296288)
		(width 0.0889)
		(layer "In9.Cu")
		(net "TP_CPU1_RSVD_204")
	)
	(arc
		(start 139.734544 -83.441286)
		(mid 139.943152 -83.653218)
		(end 140.228574 -83.736688)
		(width 0.0889)
		(layer "In9.Cu")
		(net "TP_CPU1_RSVD_204")
	)
	(arc
		(start 123.422918 -69.077586)
		(mid 123.629922 -69.28845)
		(end 123.913138 -69.372734)
		(width 0.0889)
		(layer "In9.Cu")
		(net "TP_CPU1_RSVD_204")
	)
	(arc
		(start 92.539058 -66.986404)
		(mid 92.638917 -67.099629)
		(end 92.775024 -67.164966)
		(width 0.0889)
		(layer "In9.Cu")
		(net "TP_CPU1_RSVD_204")
	)
	(arc
		(start 135.11022 -80.764888)
		(mid 135.301862 -80.822054)
		(end 135.441944 -80.964786)
		(width 0.0889)
		(layer "In9.Cu")
		(net "TP_CPU1_RSVD_204")
	)
	(arc
		(start 130.284728 -75.431904)
		(mid 130.21193 -75.722667)
		(end 130.291078 -76.011786)
		(width 0.0889)
		(layer "In9.Cu")
		(net "TP_CPU1_RSVD_204")
	)
	(arc
		(start 136.830308 -81.755488)
		(mid 137.020237 -81.813358)
		(end 137.158984 -81.955386)
		(width 0.0889)
		(layer "In9.Cu")
		(net "TP_CPU1_RSVD_204")
	)
	(arc
		(start 138.017504 -82.450686)
		(mid 138.228217 -82.663765)
		(end 138.51636 -82.746088)
		(width 0.0889)
		(layer "In9.Cu")
		(net "TP_CPU1_RSVD_204")
	)
	(arc
		(start 125.662944 -70.363334)
		(mid 125.856794 -70.419684)
		(end 125.998478 -70.563486)
		(width 0.0889)
		(layer "In9.Cu")
		(net "TP_CPU1_RSVD_204")
	)
	(arc
		(start 90.703908 -65.791588)
		(mid 90.912516 -66.00352)
		(end 91.197938 -66.08699)
		(width 0.0889)
		(layer "In9.Cu")
		(net "TP_CPU1_RSVD_204")
	)
	(arc
		(start 141.293596 -84.231734)
		(mid 141.405493 -84.307309)
		(end 141.48943 -84.41309)
		(width 0.0889)
		(layer "In9.Cu")
		(net "TP_CPU1_RSVD_204")
	)
	(arc
		(start 127.715518 -71.554086)
		(mid 127.924126 -71.766018)
		(end 128.209548 -71.849488)
		(width 0.0889)
		(layer "In9.Cu")
		(net "TP_CPU1_RSVD_204")
	)
	(arc
		(start 123.091194 -68.877688)
		(mid 123.282836 -68.934854)
		(end 123.422918 -69.077586)
		(width 0.0889)
		(layer "In9.Cu")
		(net "TP_CPU1_RSVD_204")
	)
	(arc
		(start 88.986868 -64.800988)
		(mid 89.195476 -65.01292)
		(end 89.480898 -65.09639)
		(width 0.0889)
		(layer "In9.Cu")
		(net "TP_CPU1_RSVD_204")
	)
	(arc
		(start 91.230704 -66.08699)
		(mid 91.422346 -66.144156)
		(end 91.562428 -66.286888)
		(width 0.0889)
		(layer "In9.Cu")
		(net "TP_CPU1_RSVD_204")
	)
	(arc
		(start 123.945904 -69.372734)
		(mid 124.139754 -69.429084)
		(end 124.281438 -69.572886)
		(width 0.0889)
		(layer "In9.Cu")
		(net "TP_CPU1_RSVD_204")
	)
	(arc
		(start 130.291078 -75.021186)
		(mid 130.344548 -75.216249)
		(end 130.295904 -75.4126)
		(width 0.0889)
		(layer "In9.Cu")
		(net "TP_CPU1_RSVD_204")
	)
	(arc
		(start 126.856998 -71.058786)
		(mid 127.064002 -71.26965)
		(end 127.347218 -71.353934)
		(width 0.0889)
		(layer "In9.Cu")
		(net "TP_CPU1_RSVD_204")
	)
	(arc
		(start 132.537708 -79.278988)
		(mid 132.727637 -79.336858)
		(end 132.866384 -79.478886)
		(width 0.0889)
		(layer "In9.Cu")
		(net "TP_CPU1_RSVD_204")
	)
	(arc
		(start 128.574038 -72.049386)
		(mid 128.781042 -72.26025)
		(end 129.064258 -72.344534)
		(width 0.0889)
		(layer "In9.Cu")
		(net "TP_CPU1_RSVD_204")
	)
	(arc
		(start 140.593064 -83.936586)
		(mid 140.800068 -84.14745)
		(end 141.083284 -84.231734)
		(width 0.0889)
		(layer "In9.Cu")
		(net "TP_CPU1_RSVD_204")
	)
	(arc
		(start 130.291078 -73.440036)
		(mid 130.212073 -73.735184)
		(end 130.291078 -74.030332)
		(width 0.0889)
		(layer "In9.Cu")
		(net "TP_CPU1_RSVD_204")
	)
	(segment
		(start 90.928698 -65.000886)
		(end 90.357198 -65.000886)
		(width 0.10795)
		(layer "F.Cu")
		(net "TP_CPU1_RSVD_205")
	)
	(via
		(at 90.357198 -65.000886)
		(size 0.508)
		(drill 0.254)
		(layers "F.Cu" "B.Cu")
		(net "TP_CPU1_RSVD_205")
	)
	(segment
		(start 88.353392 -64.50584)
		(end 87.781892 -64.50584)
		(width 0.10795)
		(layer "F.Cu")
		(net "TP_CPU1_RSVD_210")
	)
	(via
		(at 87.781892 -64.50584)
		(size 0.508)
		(drill 0.254)
		(layers "F.Cu" "B.Cu")
		(net "TP_CPU1_RSVD_210")
	)
	(segment
		(start 90.070178 -64.50584)
		(end 89.498678 -64.50584)
		(width 0.10795)
		(layer "F.Cu")
		(net "TP_CPU1_RSVD_211")
	)
	(via
		(at 89.498678 -64.50584)
		(size 0.508)
		(drill 0.254)
		(layers "F.Cu" "B.Cu")
		(net "TP_CPU1_RSVD_211")
	)
	(segment
		(start 91.787218 -64.50584)
		(end 91.215718 -64.50584)
		(width 0.10795)
		(layer "F.Cu")
		(net "TP_CPU1_RSVD_212")
	)
	(via
		(at 91.215718 -64.50584)
		(size 0.508)
		(drill 0.254)
		(layers "F.Cu" "B.Cu")
		(net "TP_CPU1_RSVD_212")
	)
	(segment
		(start 82.343752 -64.010286)
		(end 81.772252 -64.010286)
		(width 0.10795)
		(layer "F.Cu")
		(net "TP_CPU1_RSVD_216")
	)
	(via
		(at 81.772252 -64.010286)
		(size 0.508)
		(drill 0.254)
		(layers "F.Cu" "B.Cu")
		(net "TP_CPU1_RSVD_216")
	)
	(segment
		(start 89.211912 -64.010286)
		(end 88.640412 -64.010286)
		(width 0.10795)
		(layer "F.Cu")
		(net "TP_CPU1_RSVD_217")
	)
	(via
		(at 159.661606 -117.766846)
		(size 0.762)
		(drill 0.3048)
		(layers "F.Cu" "B.Cu")
		(net "TP_CPU1_RSVD_217")
	)
	(via
		(at 88.640412 -64.010286)
		(size 0.508)
		(drill 0.254)
		(layers "F.Cu" "B.Cu")
		(net "TP_CPU1_RSVD_217")
	)
	(segment
		(start 158.10103 -123.313444)
		(end 156.886148 -123.313444)
		(width 0.089408)
		(layer "In9.Cu")
		(net "TP_CPU1_RSVD_217")
	)
	(segment
		(start 156.470096 -123.317)
		(end 156.212032 -123.575064)
		(width 0.089408)
		(layer "In9.Cu")
		(net "TP_CPU1_RSVD_217")
	)
	(segment
		(start 158.364174 -123.0503)
		(end 158.10103 -123.313444)
		(width 0.089408)
		(layer "In9.Cu")
		(net "TP_CPU1_RSVD_217")
	)
	(segment
		(start 130.451352 -77.506322)
		(end 130.456178 -77.497686)
		(width 0.0889)
		(layer "In9.Cu")
		(net "TP_CPU1_RSVD_217")
	)
	(segment
		(start 92.092018 -66.391536)
		(end 92.059252 -66.391536)
		(width 0.0889)
		(layer "In9.Cu")
		(net "TP_CPU1_RSVD_217")
	)
	(segment
		(start 88.640412 -64.34836)
		(end 88.640412 -64.010286)
		(width 0.0889)
		(layer "In9.Cu")
		(net "TP_CPU1_RSVD_217")
	)
	(segment
		(start 126.531878 -70.668388)
		(end 126.499112 -70.668388)
		(width 0.0889)
		(layer "In9.Cu")
		(net "TP_CPU1_RSVD_217")
	)
	(segment
		(start 130.456178 -75.516486)
		(end 130.462528 -75.505818)
		(width 0.0889)
		(layer "In9.Cu")
		(net "TP_CPU1_RSVD_217")
	)
	(segment
		(start 142.14094 -84.52866)
		(end 141.869414 -84.508594)
		(width 0.0889)
		(layer "In9.Cu")
		(net "TP_CPU1_RSVD_217")
	)
	(segment
		(start 121.901966 -68.11772)
		(end 121.483882 -68.535804)
		(width 0.0889)
		(layer "In9.Cu")
		(net "TP_CPU1_RSVD_217")
	)
	(segment
		(start 136.833864 -81.564734)
		(end 136.79424 -81.564734)
		(width 0.0889)
		(layer "In9.Cu")
		(net "TP_CPU1_RSVD_217")
	)
	(segment
		(start 91.237308 -65.89649)
		(end 91.204542 -65.89649)
		(width 0.0889)
		(layer "In9.Cu")
		(net "TP_CPU1_RSVD_217")
	)
	(segment
		(start 130.456178 -76.507086)
		(end 130.462528 -76.496418)
		(width 0.0889)
		(layer "In9.Cu")
		(net "TP_CPU1_RSVD_217")
	)
	(segment
		(start 156.56941 -123.31319)
		(end 156.5656 -123.317)
		(width 0.089408)
		(layer "In9.Cu")
		(net "TP_CPU1_RSVD_217")
	)
	(segment
		(start 124.814838 -69.677788)
		(end 124.782072 -69.677788)
		(width 0.0889)
		(layer "In9.Cu")
		(net "TP_CPU1_RSVD_217")
	)
	(segment
		(start 139.405614 -83.050634)
		(end 139.372848 -83.050634)
		(width 0.0889)
		(layer "In9.Cu")
		(net "TP_CPU1_RSVD_217")
	)
	(segment
		(start 154.771598 -123.575064)
		(end 154.357832 -123.161298)
		(width 0.089408)
		(layer "In9.Cu")
		(net "TP_CPU1_RSVD_217")
	)
	(segment
		(start 89.520268 -64.90589)
		(end 89.498678 -64.90589)
		(width 0.0889)
		(layer "In9.Cu")
		(net "TP_CPU1_RSVD_217")
	)
	(segment
		(start 132.537454 -79.088234)
		(end 132.507482 -79.088234)
		(width 0.0889)
		(layer "In9.Cu")
		(net "TP_CPU1_RSVD_217")
	)
	(segment
		(start 111.178848 -69.009006)
		(end 110.245144 -68.075302)
		(width 0.0889)
		(layer "In9.Cu")
		(net "TP_CPU1_RSVD_217")
	)
	(segment
		(start 120.02643 -69.259704)
		(end 116.959634 -69.259704)
		(width 0.0889)
		(layer "In9.Cu")
		(net "TP_CPU1_RSVD_217")
	)
	(segment
		(start 130.451352 -76.515722)
		(end 130.456178 -76.507086)
		(width 0.0889)
		(layer "In9.Cu")
		(net "TP_CPU1_RSVD_217")
	)
	(segment
		(start 159.136334 -118.292118)
		(end 159.136334 -120.90527)
		(width 0.089408)
		(layer "In9.Cu")
		(net "TP_CPU1_RSVD_217")
	)
	(segment
		(start 92.703904 -66.891408)
		(end 92.586048 -66.686938)
		(width 0.0889)
		(layer "In9.Cu")
		(net "TP_CPU1_RSVD_217")
	)
	(segment
		(start 156.5656 -123.317)
		(end 156.470096 -123.317)
		(width 0.089408)
		(layer "In9.Cu")
		(net "TP_CPU1_RSVD_217")
	)
	(segment
		(start 128.248918 -71.658988)
		(end 128.216152 -71.658988)
		(width 0.0889)
		(layer "In9.Cu")
		(net "TP_CPU1_RSVD_217")
	)
	(segment
		(start 135.971534 -81.069434)
		(end 135.938768 -81.069434)
		(width 0.0889)
		(layer "In9.Cu")
		(net "TP_CPU1_RSVD_217")
	)
	(segment
		(start 137.692384 -82.060034)
		(end 137.659618 -82.060034)
		(width 0.0889)
		(layer "In9.Cu")
		(net "TP_CPU1_RSVD_217")
	)
	(segment
		(start 130.456178 -77.497686)
		(end 130.462528 -77.487018)
		(width 0.0889)
		(layer "In9.Cu")
		(net "TP_CPU1_RSVD_217")
	)
	(segment
		(start 141.332712 -84.041234)
		(end 141.089888 -84.041234)
		(width 0.0889)
		(layer "In9.Cu")
		(net "TP_CPU1_RSVD_217")
	)
	(segment
		(start 138.542268 -82.555334)
		(end 138.518138 -82.555334)
		(width 0.0889)
		(layer "In9.Cu")
		(net "TP_CPU1_RSVD_217")
	)
	(segment
		(start 159.136334 -120.90527)
		(end 158.364174 -121.67743)
		(width 0.089408)
		(layer "In9.Cu")
		(net "TP_CPU1_RSVD_217")
	)
	(segment
		(start 140.267944 -83.546188)
		(end 140.235178 -83.546188)
		(width 0.0889)
		(layer "In9.Cu")
		(net "TP_CPU1_RSVD_217")
	)
	(segment
		(start 156.727652 -123.312936)
		(end 156.727398 -123.31319)
		(width 0.089408)
		(layer "In9.Cu")
		(net "TP_CPU1_RSVD_217")
	)
	(segment
		(start 122.738896 -68.501768)
		(end 122.564652 -68.222368)
		(width 0.0889)
		(layer "In9.Cu")
		(net "TP_CPU1_RSVD_217")
	)
	(segment
		(start 89.155524 -64.71158)
		(end 89.152222 -64.705738)
		(width 0.0889)
		(layer "In9.Cu")
		(net "TP_CPU1_RSVD_217")
	)
	(segment
		(start 121.483882 -68.535804)
		(end 120.75033 -68.535804)
		(width 0.0889)
		(layer "In9.Cu")
		(net "TP_CPU1_RSVD_217")
	)
	(segment
		(start 116.708936 -69.009006)
		(end 111.178848 -69.009006)
		(width 0.0889)
		(layer "In9.Cu")
		(net "TP_CPU1_RSVD_217")
	)
	(segment
		(start 116.959634 -69.259704)
		(end 116.708936 -69.009006)
		(width 0.0889)
		(layer "In9.Cu")
		(net "TP_CPU1_RSVD_217")
	)
	(segment
		(start 120.75033 -68.535804)
		(end 120.02643 -69.259704)
		(width 0.0889)
		(layer "In9.Cu")
		(net "TP_CPU1_RSVD_217")
	)
	(segment
		(start 130.462528 -73.94575)
		(end 130.456178 -73.935082)
		(width 0.0889)
		(layer "In9.Cu")
		(net "TP_CPU1_RSVD_217")
	)
	(segment
		(start 130.451352 -75.525122)
		(end 130.456178 -75.516486)
		(width 0.0889)
		(layer "In9.Cu")
		(net "TP_CPU1_RSVD_217")
	)
	(segment
		(start 158.364174 -121.67743)
		(end 158.364174 -123.0503)
		(width 0.089408)
		(layer "In9.Cu")
		(net "TP_CPU1_RSVD_217")
	)
	(segment
		(start 156.727398 -123.31319)
		(end 156.56941 -123.31319)
		(width 0.089408)
		(layer "In9.Cu")
		(net "TP_CPU1_RSVD_217")
	)
	(segment
		(start 123.952508 -69.182234)
		(end 123.919742 -69.182234)
		(width 0.0889)
		(layer "In9.Cu")
		(net "TP_CPU1_RSVD_217")
	)
	(segment
		(start 129.103628 -72.154034)
		(end 129.070862 -72.154034)
		(width 0.0889)
		(layer "In9.Cu")
		(net "TP_CPU1_RSVD_217")
	)
	(segment
		(start 153.429208 -119.46382)
		(end 146.59483 -112.629442)
		(width 0.089408)
		(layer "In9.Cu")
		(net "TP_CPU1_RSVD_217")
	)
	(segment
		(start 135.116824 -80.574388)
		(end 135.084058 -80.574388)
		(width 0.0889)
		(layer "In9.Cu")
		(net "TP_CPU1_RSVD_217")
	)
	(segment
		(start 88.70569 -64.413638)
		(end 88.640412 -64.34836)
		(width 0.0889)
		(layer "In9.Cu")
		(net "TP_CPU1_RSVD_217")
	)
	(segment
		(start 154.357832 -121.92127)
		(end 153.429208 -120.992646)
		(width 0.089408)
		(layer "In9.Cu")
		(net "TP_CPU1_RSVD_217")
	)
	(segment
		(start 130.456178 -73.535286)
		(end 130.462528 -73.524618)
		(width 0.0889)
		(layer "In9.Cu")
		(net "TP_CPU1_RSVD_217")
	)
	(segment
		(start 93.34246 -67.76339)
		(end 93.110558 -67.225926)
		(width 0.0889)
		(layer "In9.Cu")
		(net "TP_CPU1_RSVD_217")
	)
	(segment
		(start 90.374978 -65.400936)
		(end 90.342212 -65.400936)
		(width 0.0889)
		(layer "In9.Cu")
		(net "TP_CPU1_RSVD_217")
	)
	(segment
		(start 122.376184 -68.11772)
		(end 121.901966 -68.11772)
		(width 0.0889)
		(layer "In9.Cu")
		(net "TP_CPU1_RSVD_217")
	)
	(segment
		(start 146.59483 -92.296234)
		(end 144.795494 -90.496898)
		(width 0.089408)
		(layer "In9.Cu")
		(net "TP_CPU1_RSVD_217")
	)
	(segment
		(start 153.429208 -120.992646)
		(end 153.429208 -119.46382)
		(width 0.089408)
		(layer "In9.Cu")
		(net "TP_CPU1_RSVD_217")
	)
	(segment
		(start 93.654372 -68.075302)
		(end 93.34246 -67.76339)
		(width 0.0889)
		(layer "In9.Cu")
		(net "TP_CPU1_RSVD_217")
	)
	(segment
		(start 146.59483 -112.629442)
		(end 146.59483 -92.296234)
		(width 0.089408)
		(layer "In9.Cu")
		(net "TP_CPU1_RSVD_217")
	)
	(segment
		(start 133.399784 -79.583788)
		(end 133.367018 -79.583788)
		(width 0.0889)
		(layer "In9.Cu")
		(net "TP_CPU1_RSVD_217")
	)
	(segment
		(start 110.245144 -68.075302)
		(end 93.654372 -68.075302)
		(width 0.0889)
		(layer "In9.Cu")
		(net "TP_CPU1_RSVD_217")
	)
	(segment
		(start 127.386588 -71.163434)
		(end 127.353822 -71.163434)
		(width 0.0889)
		(layer "In9.Cu")
		(net "TP_CPU1_RSVD_217")
	)
	(segment
		(start 156.886148 -123.313444)
		(end 156.88564 -123.312936)
		(width 0.089408)
		(layer "In9.Cu")
		(net "TP_CPU1_RSVD_217")
	)
	(segment
		(start 144.795494 -90.496898)
		(end 144.795494 -86.421722)
		(width 0.089408)
		(layer "In9.Cu")
		(net "TP_CPU1_RSVD_217")
	)
	(segment
		(start 143.405606 -85.031834)
		(end 142.731236 -85.031834)
		(width 0.0889)
		(layer "In9.Cu")
		(net "TP_CPU1_RSVD_217")
	)
	(segment
		(start 129.965958 -72.649588)
		(end 129.933192 -72.649588)
		(width 0.0889)
		(layer "In9.Cu")
		(net "TP_CPU1_RSVD_217")
	)
	(segment
		(start 134.254494 -80.078834)
		(end 134.221728 -80.078834)
		(width 0.0889)
		(layer "In9.Cu")
		(net "TP_CPU1_RSVD_217")
	)
	(segment
		(start 131.682998 -78.593188)
		(end 131.650232 -78.593188)
		(width 0.0889)
		(layer "In9.Cu")
		(net "TP_CPU1_RSVD_217")
	)
	(segment
		(start 123.097798 -68.687188)
		(end 123.065032 -68.687188)
		(width 0.0889)
		(layer "In9.Cu")
		(net "TP_CPU1_RSVD_217")
	)
	(segment
		(start 144.795494 -86.421722)
		(end 143.405606 -85.031834)
		(width 0.089408)
		(layer "In9.Cu")
		(net "TP_CPU1_RSVD_217")
	)
	(segment
		(start 156.212032 -123.575064)
		(end 154.771598 -123.575064)
		(width 0.089408)
		(layer "In9.Cu")
		(net "TP_CPU1_RSVD_217")
	)
	(segment
		(start 159.661606 -117.766846)
		(end 159.136334 -118.292118)
		(width 0.089408)
		(layer "In9.Cu")
		(net "TP_CPU1_RSVD_217")
	)
	(segment
		(start 156.88564 -123.312936)
		(end 156.727652 -123.312936)
		(width 0.089408)
		(layer "In9.Cu")
		(net "TP_CPU1_RSVD_217")
	)
	(segment
		(start 130.815842 -78.097634)
		(end 130.787902 -78.097634)
		(width 0.0889)
		(layer "In9.Cu")
		(net "TP_CPU1_RSVD_217")
	)
	(segment
		(start 154.357832 -123.161298)
		(end 154.357832 -121.92127)
		(width 0.089408)
		(layer "In9.Cu")
		(net "TP_CPU1_RSVD_217")
	)
	(segment
		(start 125.669548 -70.172834)
		(end 125.636782 -70.172834)
		(width 0.0889)
		(layer "In9.Cu")
		(net "TP_CPU1_RSVD_217")
	)
	(arc
		(start 130.456178 -76.907136)
		(mid 130.402708 -76.712073)
		(end 130.451352 -76.515722)
		(width 0.0889)
		(layer "In9.Cu")
		(net "TP_CPU1_RSVD_217")
	)
	(arc
		(start 133.367018 -79.583788)
		(mid 133.173168 -79.527438)
		(end 133.031484 -79.383636)
		(width 0.0889)
		(layer "In9.Cu")
		(net "TP_CPU1_RSVD_217")
	)
	(arc
		(start 126.163578 -70.468236)
		(mid 125.95497 -70.256304)
		(end 125.669548 -70.172834)
		(width 0.0889)
		(layer "In9.Cu")
		(net "TP_CPU1_RSVD_217")
	)
	(arc
		(start 129.597658 -72.449436)
		(mid 129.38905 -72.237504)
		(end 129.103628 -72.154034)
		(width 0.0889)
		(layer "In9.Cu")
		(net "TP_CPU1_RSVD_217")
	)
	(arc
		(start 130.456178 -73.935082)
		(mid 130.402679 -73.735184)
		(end 130.456178 -73.535286)
		(width 0.0889)
		(layer "In9.Cu")
		(net "TP_CPU1_RSVD_217")
	)
	(arc
		(start 132.173218 -78.888336)
		(mid 131.966214 -78.677472)
		(end 131.682998 -78.593188)
		(width 0.0889)
		(layer "In9.Cu")
		(net "TP_CPU1_RSVD_217")
	)
	(arc
		(start 128.216152 -71.658988)
		(mid 128.022302 -71.602638)
		(end 127.880618 -71.458836)
		(width 0.0889)
		(layer "In9.Cu")
		(net "TP_CPU1_RSVD_217")
	)
	(arc
		(start 137.324084 -81.859882)
		(mid 137.11708 -81.649018)
		(end 136.833864 -81.564734)
		(width 0.0889)
		(layer "In9.Cu")
		(net "TP_CPU1_RSVD_217")
	)
	(arc
		(start 92.586048 -66.686938)
		(mid 92.37744 -66.475006)
		(end 92.092018 -66.391536)
		(width 0.0889)
		(layer "In9.Cu")
		(net "TP_CPU1_RSVD_217")
	)
	(arc
		(start 135.084058 -80.574388)
		(mid 134.890208 -80.518038)
		(end 134.748524 -80.374236)
		(width 0.0889)
		(layer "In9.Cu")
		(net "TP_CPU1_RSVD_217")
	)
	(arc
		(start 122.564652 -68.222368)
		(mid 122.484004 -68.145539)
		(end 122.376184 -68.11772)
		(width 0.0889)
		(layer "In9.Cu")
		(net "TP_CPU1_RSVD_217")
	)
	(arc
		(start 125.636782 -70.172834)
		(mid 125.44514 -70.115668)
		(end 125.305058 -69.972936)
		(width 0.0889)
		(layer "In9.Cu")
		(net "TP_CPU1_RSVD_217")
	)
	(arc
		(start 141.089888 -84.041234)
		(mid 140.898246 -83.984068)
		(end 140.758164 -83.841336)
		(width 0.0889)
		(layer "In9.Cu")
		(net "TP_CPU1_RSVD_217")
	)
	(arc
		(start 136.465564 -81.364836)
		(mid 136.256956 -81.152904)
		(end 135.971534 -81.069434)
		(width 0.0889)
		(layer "In9.Cu")
		(net "TP_CPU1_RSVD_217")
	)
	(arc
		(start 142.731236 -85.031834)
		(mid 142.606035 -84.952063)
		(end 142.515082 -84.83473)
		(width 0.0889)
		(layer "In9.Cu")
		(net "TP_CPU1_RSVD_217")
	)
	(arc
		(start 142.515082 -84.83473)
		(mid 142.358835 -84.64401)
		(end 142.14094 -84.52866)
		(width 0.0889)
		(layer "In9.Cu")
		(net "TP_CPU1_RSVD_217")
	)
	(arc
		(start 139.899644 -83.346036)
		(mid 139.691036 -83.134104)
		(end 139.405614 -83.050634)
		(width 0.0889)
		(layer "In9.Cu")
		(net "TP_CPU1_RSVD_217")
	)
	(arc
		(start 140.235178 -83.546188)
		(mid 140.041328 -83.489838)
		(end 139.899644 -83.346036)
		(width 0.0889)
		(layer "In9.Cu")
		(net "TP_CPU1_RSVD_217")
	)
	(arc
		(start 139.372848 -83.050634)
		(mid 139.181206 -82.993468)
		(end 139.041124 -82.850736)
		(width 0.0889)
		(layer "In9.Cu")
		(net "TP_CPU1_RSVD_217")
	)
	(arc
		(start 123.919742 -69.182234)
		(mid 123.7281 -69.125068)
		(end 123.588018 -68.982336)
		(width 0.0889)
		(layer "In9.Cu")
		(net "TP_CPU1_RSVD_217")
	)
	(arc
		(start 126.499112 -70.668388)
		(mid 126.305262 -70.612038)
		(end 126.163578 -70.468236)
		(width 0.0889)
		(layer "In9.Cu")
		(net "TP_CPU1_RSVD_217")
	)
	(arc
		(start 130.456178 -74.925936)
		(mid 130.402552 -74.725784)
		(end 130.456178 -74.525632)
		(width 0.0889)
		(layer "In9.Cu")
		(net "TP_CPU1_RSVD_217")
	)
	(arc
		(start 130.456178 -75.916536)
		(mid 130.402708 -75.721473)
		(end 130.451352 -75.525122)
		(width 0.0889)
		(layer "In9.Cu")
		(net "TP_CPU1_RSVD_217")
	)
	(arc
		(start 128.739138 -71.954136)
		(mid 128.532134 -71.743272)
		(end 128.248918 -71.658988)
		(width 0.0889)
		(layer "In9.Cu")
		(net "TP_CPU1_RSVD_217")
	)
	(arc
		(start 141.869414 -84.508594)
		(mid 141.746425 -84.431568)
		(end 141.655038 -84.318856)
		(width 0.0889)
		(layer "In9.Cu")
		(net "TP_CPU1_RSVD_217")
	)
	(arc
		(start 123.065032 -68.687188)
		(mid 122.878875 -68.6351)
		(end 122.738896 -68.501768)
		(width 0.0889)
		(layer "In9.Cu")
		(net "TP_CPU1_RSVD_217")
	)
	(arc
		(start 133.890004 -79.878936)
		(mid 133.683 -79.668072)
		(end 133.399784 -79.583788)
		(width 0.0889)
		(layer "In9.Cu")
		(net "TP_CPU1_RSVD_217")
	)
	(arc
		(start 90.010488 -65.201038)
		(mid 89.803484 -64.990174)
		(end 89.520268 -64.90589)
		(width 0.0889)
		(layer "In9.Cu")
		(net "TP_CPU1_RSVD_217")
	)
	(arc
		(start 135.938768 -81.069434)
		(mid 135.747126 -81.012268)
		(end 135.607044 -80.869536)
		(width 0.0889)
		(layer "In9.Cu")
		(net "TP_CPU1_RSVD_217")
	)
	(arc
		(start 134.221728 -80.078834)
		(mid 134.030086 -80.021668)
		(end 133.890004 -79.878936)
		(width 0.0889)
		(layer "In9.Cu")
		(net "TP_CPU1_RSVD_217")
	)
	(arc
		(start 129.933192 -72.649588)
		(mid 129.739342 -72.593238)
		(end 129.597658 -72.449436)
		(width 0.0889)
		(layer "In9.Cu")
		(net "TP_CPU1_RSVD_217")
	)
	(arc
		(start 92.821506 -66.980308)
		(mid 92.753722 -66.947761)
		(end 92.703904 -66.891408)
		(width 0.0889)
		(layer "In9.Cu")
		(net "TP_CPU1_RSVD_217")
	)
	(arc
		(start 127.880618 -71.458836)
		(mid 127.67201 -71.246904)
		(end 127.386588 -71.163434)
		(width 0.0889)
		(layer "In9.Cu")
		(net "TP_CPU1_RSVD_217")
	)
	(arc
		(start 93.110558 -67.225926)
		(mid 92.994752 -67.069306)
		(end 92.821506 -66.980308)
		(width 0.0889)
		(layer "In9.Cu")
		(net "TP_CPU1_RSVD_217")
	)
	(arc
		(start 92.059252 -66.391536)
		(mid 91.86761 -66.33437)
		(end 91.727528 -66.191638)
		(width 0.0889)
		(layer "In9.Cu")
		(net "TP_CPU1_RSVD_217")
	)
	(arc
		(start 130.462528 -76.496418)
		(mid 130.535326 -76.205655)
		(end 130.456178 -75.916536)
		(width 0.0889)
		(layer "In9.Cu")
		(net "TP_CPU1_RSVD_217")
	)
	(arc
		(start 130.462528 -73.524618)
		(mid 130.458497 -72.948436)
		(end 129.965958 -72.649588)
		(width 0.0889)
		(layer "In9.Cu")
		(net "TP_CPU1_RSVD_217")
	)
	(arc
		(start 89.498678 -64.90589)
		(mid 89.301517 -64.853931)
		(end 89.155524 -64.71158)
		(width 0.0889)
		(layer "In9.Cu")
		(net "TP_CPU1_RSVD_217")
	)
	(arc
		(start 138.518138 -82.555334)
		(mid 138.324288 -82.498984)
		(end 138.182604 -82.355182)
		(width 0.0889)
		(layer "In9.Cu")
		(net "TP_CPU1_RSVD_217")
	)
	(arc
		(start 133.031484 -79.383636)
		(mid 132.822876 -79.171704)
		(end 132.537454 -79.088234)
		(width 0.0889)
		(layer "In9.Cu")
		(net "TP_CPU1_RSVD_217")
	)
	(arc
		(start 124.782072 -69.677788)
		(mid 124.588222 -69.621438)
		(end 124.446538 -69.477636)
		(width 0.0889)
		(layer "In9.Cu")
		(net "TP_CPU1_RSVD_217")
	)
	(arc
		(start 90.869008 -65.696338)
		(mid 90.6604 -65.484406)
		(end 90.374978 -65.400936)
		(width 0.0889)
		(layer "In9.Cu")
		(net "TP_CPU1_RSVD_217")
	)
	(arc
		(start 90.342212 -65.400936)
		(mid 90.15057 -65.34377)
		(end 90.010488 -65.201038)
		(width 0.0889)
		(layer "In9.Cu")
		(net "TP_CPU1_RSVD_217")
	)
	(arc
		(start 91.727528 -66.191638)
		(mid 91.520524 -65.980774)
		(end 91.237308 -65.89649)
		(width 0.0889)
		(layer "In9.Cu")
		(net "TP_CPU1_RSVD_217")
	)
	(arc
		(start 129.070862 -72.154034)
		(mid 128.87922 -72.096868)
		(end 128.739138 -71.954136)
		(width 0.0889)
		(layer "In9.Cu")
		(net "TP_CPU1_RSVD_217")
	)
	(arc
		(start 123.588018 -68.982336)
		(mid 123.381014 -68.771472)
		(end 123.097798 -68.687188)
		(width 0.0889)
		(layer "In9.Cu")
		(net "TP_CPU1_RSVD_217")
	)
	(arc
		(start 136.79424 -81.564734)
		(mid 136.604311 -81.506864)
		(end 136.465564 -81.364836)
		(width 0.0889)
		(layer "In9.Cu")
		(net "TP_CPU1_RSVD_217")
	)
	(arc
		(start 138.182604 -82.355182)
		(mid 137.9756 -82.144318)
		(end 137.692384 -82.060034)
		(width 0.0889)
		(layer "In9.Cu")
		(net "TP_CPU1_RSVD_217")
	)
	(arc
		(start 131.650232 -78.593188)
		(mid 131.456382 -78.536838)
		(end 131.314698 -78.393036)
		(width 0.0889)
		(layer "In9.Cu")
		(net "TP_CPU1_RSVD_217")
	)
	(arc
		(start 91.204542 -65.89649)
		(mid 91.010692 -65.84014)
		(end 90.869008 -65.696338)
		(width 0.0889)
		(layer "In9.Cu")
		(net "TP_CPU1_RSVD_217")
	)
	(arc
		(start 127.353822 -71.163434)
		(mid 127.16218 -71.106268)
		(end 127.022098 -70.963536)
		(width 0.0889)
		(layer "In9.Cu")
		(net "TP_CPU1_RSVD_217")
	)
	(arc
		(start 141.655038 -84.318856)
		(mid 141.517886 -84.152174)
		(end 141.332712 -84.041234)
		(width 0.0889)
		(layer "In9.Cu")
		(net "TP_CPU1_RSVD_217")
	)
	(arc
		(start 140.758164 -83.841336)
		(mid 140.55116 -83.630472)
		(end 140.267944 -83.546188)
		(width 0.0889)
		(layer "In9.Cu")
		(net "TP_CPU1_RSVD_217")
	)
	(arc
		(start 130.462528 -75.505818)
		(mid 130.535326 -75.215055)
		(end 130.456178 -74.925936)
		(width 0.0889)
		(layer "In9.Cu")
		(net "TP_CPU1_RSVD_217")
	)
	(arc
		(start 125.305058 -69.972936)
		(mid 125.098054 -69.762072)
		(end 124.814838 -69.677788)
		(width 0.0889)
		(layer "In9.Cu")
		(net "TP_CPU1_RSVD_217")
	)
	(arc
		(start 124.446538 -69.477636)
		(mid 124.23793 -69.265704)
		(end 123.952508 -69.182234)
		(width 0.0889)
		(layer "In9.Cu")
		(net "TP_CPU1_RSVD_217")
	)
	(arc
		(start 137.659618 -82.060034)
		(mid 137.465768 -82.003684)
		(end 137.324084 -81.859882)
		(width 0.0889)
		(layer "In9.Cu")
		(net "TP_CPU1_RSVD_217")
	)
	(arc
		(start 135.607044 -80.869536)
		(mid 135.40004 -80.658672)
		(end 135.116824 -80.574388)
		(width 0.0889)
		(layer "In9.Cu")
		(net "TP_CPU1_RSVD_217")
	)
	(arc
		(start 130.462528 -77.487018)
		(mid 130.535326 -77.196255)
		(end 130.456178 -76.907136)
		(width 0.0889)
		(layer "In9.Cu")
		(net "TP_CPU1_RSVD_217")
	)
	(arc
		(start 130.456178 -74.525632)
		(mid 130.5354 -74.236514)
		(end 130.462528 -73.94575)
		(width 0.0889)
		(layer "In9.Cu")
		(net "TP_CPU1_RSVD_217")
	)
	(arc
		(start 139.041124 -82.850736)
		(mid 138.830411 -82.637657)
		(end 138.542268 -82.555334)
		(width 0.0889)
		(layer "In9.Cu")
		(net "TP_CPU1_RSVD_217")
	)
	(arc
		(start 89.152222 -64.705738)
		(mid 88.963799 -64.506434)
		(end 88.70569 -64.413638)
		(width 0.0889)
		(layer "In9.Cu")
		(net "TP_CPU1_RSVD_217")
	)
	(arc
		(start 130.787902 -78.097634)
		(mid 130.454984 -77.895643)
		(end 130.451352 -77.506322)
		(width 0.0889)
		(layer "In9.Cu")
		(net "TP_CPU1_RSVD_217")
	)
	(arc
		(start 131.314698 -78.393036)
		(mid 131.103985 -78.179957)
		(end 130.815842 -78.097634)
		(width 0.0889)
		(layer "In9.Cu")
		(net "TP_CPU1_RSVD_217")
	)
	(arc
		(start 134.748524 -80.374236)
		(mid 134.539916 -80.162304)
		(end 134.254494 -80.078834)
		(width 0.0889)
		(layer "In9.Cu")
		(net "TP_CPU1_RSVD_217")
	)
	(arc
		(start 132.507482 -79.088234)
		(mid 132.314379 -79.031715)
		(end 132.173218 -78.888336)
		(width 0.0889)
		(layer "In9.Cu")
		(net "TP_CPU1_RSVD_217")
	)
	(arc
		(start 127.022098 -70.963536)
		(mid 126.815094 -70.752672)
		(end 126.531878 -70.668388)
		(width 0.0889)
		(layer "In9.Cu")
		(net "TP_CPU1_RSVD_217")
	)
	(segment
		(start 90.928698 -64.010286)
		(end 90.357198 -64.010286)
		(width 0.10795)
		(layer "F.Cu")
		(net "TP_CPU1_RSVD_218")
	)
	(via
		(at 90.357198 -64.010286)
		(size 0.508)
		(drill 0.254)
		(layers "F.Cu" "B.Cu")
		(net "TP_CPU1_RSVD_218")
	)
	(segment
		(start 81.485232 -63.51524)
		(end 80.913732 -63.51524)
		(width 0.10795)
		(layer "F.Cu")
		(net "TP_CPU1_RSVD_222")
	)
	(via
		(at 80.913732 -63.51524)
		(size 0.508)
		(drill 0.254)
		(layers "F.Cu" "B.Cu")
		(net "TP_CPU1_RSVD_222")
	)
	(segment
		(start 88.353392 -63.51524)
		(end 87.781892 -63.51524)
		(width 0.10795)
		(layer "F.Cu")
		(net "TP_CPU1_RSVD_223")
	)
	(via
		(at 87.781892 -63.51524)
		(size 0.508)
		(drill 0.254)
		(layers "F.Cu" "B.Cu")
		(net "TP_CPU1_RSVD_223")
	)
	(segment
		(start 90.070178 -63.51524)
		(end 89.498678 -63.51524)
		(width 0.10795)
		(layer "F.Cu")
		(net "TP_CPU1_RSVD_224")
	)
	(via
		(at 89.498678 -63.51524)
		(size 0.508)
		(drill 0.254)
		(layers "F.Cu" "B.Cu")
		(net "TP_CPU1_RSVD_224")
	)
	(segment
		(start 91.787218 -63.51524)
		(end 91.215718 -63.51524)
		(width 0.10795)
		(layer "F.Cu")
		(net "TP_CPU1_RSVD_225")
	)
	(via
		(at 91.215718 -63.51524)
		(size 0.508)
		(drill 0.254)
		(layers "F.Cu" "B.Cu")
		(net "TP_CPU1_RSVD_225")
	)
	(segment
		(start 78.909672 -63.019686)
		(end 78.338172 -63.019686)
		(width 0.10795)
		(layer "F.Cu")
		(net "TP_CPU1_RSVD_228")
	)
	(via
		(at 78.338172 -63.019686)
		(size 0.508)
		(drill 0.254)
		(layers "F.Cu" "B.Cu")
		(net "TP_CPU1_RSVD_228")
	)
	(segment
		(start 80.626712 -63.019686)
		(end 80.055212 -63.019686)
		(width 0.10795)
		(layer "F.Cu")
		(net "TP_CPU1_RSVD_229")
	)
	(via
		(at 80.055212 -63.019686)
		(size 0.508)
		(drill 0.254)
		(layers "F.Cu" "B.Cu")
		(net "TP_CPU1_RSVD_229")
	)
	(segment
		(start 92.645738 -63.019686)
		(end 92.074238 -63.019686)
		(width 0.10795)
		(layer "F.Cu")
		(net "TP_CPU1_RSVD_230")
	)
	(via
		(at 92.074238 -63.019686)
		(size 0.508)
		(drill 0.254)
		(layers "F.Cu" "B.Cu")
		(net "TP_CPU1_RSVD_230")
	)
	(segment
		(start 79.768192 -62.52464)
		(end 79.196692 -62.52464)
		(width 0.10795)
		(layer "F.Cu")
		(net "TP_CPU1_RSVD_234")
	)
	(via
		(at 79.196692 -62.52464)
		(size 0.508)
		(drill 0.254)
		(layers "F.Cu" "B.Cu")
		(net "TP_CPU1_RSVD_234")
	)
	(segment
		(start 80.626712 -62.029086)
		(end 80.055212 -62.029086)
		(width 0.10795)
		(layer "F.Cu")
		(net "TP_CPU1_RSVD_241")
	)
	(via
		(at 80.055212 -62.029086)
		(size 0.508)
		(drill 0.254)
		(layers "F.Cu" "B.Cu")
		(net "TP_CPU1_RSVD_241")
	)
	(segment
		(start 79.768192 -61.53404)
		(end 79.196692 -61.53404)
		(width 0.10795)
		(layer "F.Cu")
		(net "TP_CPU1_RSVD_247")
	)
	(via
		(at 79.196692 -61.53404)
		(size 0.508)
		(drill 0.254)
		(layers "F.Cu" "B.Cu")
		(net "TP_CPU1_RSVD_247")
	)
	(segment
		(start 102.089204 -61.53404)
		(end 101.517704 -61.53404)
		(width 0.10795)
		(layer "F.Cu")
		(net "TP_CPU1_RSVD_251")
	)
	(via
		(at 101.517704 -61.53404)
		(size 0.508)
		(drill 0.254)
		(layers "F.Cu" "B.Cu")
		(net "TP_CPU1_RSVD_251")
	)
	(segment
		(start 70.324726 -68.963286)
		(end 69.753226 -68.963286)
		(width 0.10795)
		(layer "F.Cu")
		(net "TP_CPU1_RSVD_255")
	)
	(via
		(at 69.753226 -68.963286)
		(size 0.508)
		(drill 0.254)
		(layers "F.Cu" "B.Cu")
		(net "TP_CPU1_RSVD_255")
	)
	(segment
		(start 85.777832 -59.057286)
		(end 85.206586 -59.057286)
		(width 0.10795)
		(layer "F.Cu")
		(net "TP_CPU1_RSVD_256")
	)
	(segment
		(start 85.206586 -59.057286)
		(end 85.206332 -59.05754)
		(width 0.10795)
		(layer "F.Cu")
		(net "TP_CPU1_RSVD_256")
	)
	(via
		(at 85.206332 -59.05754)
		(size 0.508)
		(drill 0.254)
		(layers "F.Cu" "B.Cu")
		(net "TP_CPU1_RSVD_256")
	)
	(segment
		(start 75.475846 -50.141886)
		(end 74.904346 -50.141886)
		(width 0.10795)
		(layer "F.Cu")
		(net "TP_CPU1_RSVD_293")
	)
	(via
		(at 74.904346 -50.141886)
		(size 0.508)
		(drill 0.254)
		(layers "F.Cu" "B.Cu")
		(net "TP_CPU1_RSVD_293")
	)
	(segment
		(start 84.919312 -58.561986)
		(end 84.348066 -58.561986)
		(width 0.10795)
		(layer "F.Cu")
		(net "TP_CPU1_RSVD_258")
	)
	(segment
		(start 84.348066 -58.561986)
		(end 84.347812 -58.56224)
		(width 0.10795)
		(layer "F.Cu")
		(net "TP_CPU1_RSVD_258")
	)
	(via
		(at 84.347812 -58.56224)
		(size 0.508)
		(drill 0.254)
		(layers "F.Cu" "B.Cu")
		(net "TP_CPU1_RSVD_258")
	)
	(segment
		(start 84.060792 -58.06694)
		(end 83.489292 -58.06694)
		(width 0.10795)
		(layer "F.Cu")
		(net "TP_CPU1_RSVD_259")
	)
	(via
		(at 83.489292 -58.06694)
		(size 0.508)
		(drill 0.254)
		(layers "F.Cu" "B.Cu")
		(net "TP_CPU1_RSVD_259")
	)
	(segment
		(start 85.777832 -58.06694)
		(end 85.206332 -58.06694)
		(width 0.10795)
		(layer "F.Cu")
		(net "TP_CPU1_RSVD_260")
	)
	(via
		(at 85.206332 -58.06694)
		(size 0.508)
		(drill 0.254)
		(layers "F.Cu" "B.Cu")
		(net "TP_CPU1_RSVD_260")
	)
	(segment
		(start 84.919312 -57.57164)
		(end 84.347812 -57.57164)
		(width 0.10795)
		(layer "F.Cu")
		(net "TP_CPU1_RSVD_261")
	)
	(via
		(at 84.347812 -57.57164)
		(size 0.508)
		(drill 0.254)
		(layers "F.Cu" "B.Cu")
		(net "TP_CPU1_RSVD_261")
	)
	(segment
		(start 84.060792 -57.076086)
		(end 83.489292 -57.076086)
		(width 0.10795)
		(layer "F.Cu")
		(net "TP_CPU1_RSVD_262")
	)
	(via
		(at 83.489292 -57.076086)
		(size 0.508)
		(drill 0.254)
		(layers "F.Cu" "B.Cu")
		(net "TP_CPU1_RSVD_262")
	)
	(segment
		(start 84.919312 -56.58104)
		(end 84.347812 -56.58104)
		(width 0.10795)
		(layer "F.Cu")
		(net "TP_CPU1_RSVD_263")
	)
	(via
		(at 84.347812 -56.58104)
		(size 0.508)
		(drill 0.254)
		(layers "F.Cu" "B.Cu")
		(net "TP_CPU1_RSVD_263")
	)
	(segment
		(start 88.353392 -56.58104)
		(end 87.781892 -56.58104)
		(width 0.10795)
		(layer "F.Cu")
		(net "TP_CPU1_RSVD_264")
	)
	(via
		(at 87.781892 -56.58104)
		(size 0.508)
		(drill 0.254)
		(layers "F.Cu" "B.Cu")
		(net "TP_CPU1_RSVD_264")
	)
	(segment
		(start 69.466206 -51.62804)
		(end 68.894706 -51.62804)
		(width 0.10795)
		(layer "F.Cu")
		(net "TP_CPU1_RSVD_280")
	)
	(via
		(at 68.894706 -51.62804)
		(size 0.508)
		(drill 0.254)
		(layers "F.Cu" "B.Cu")
		(net "TP_CPU1_RSVD_280")
	)
	(segment
		(start 70.324726 -51.132486)
		(end 69.753226 -51.132486)
		(width 0.10795)
		(layer "F.Cu")
		(net "TP_CPU1_RSVD_284")
	)
	(via
		(at 69.753226 -51.132486)
		(size 0.508)
		(drill 0.254)
		(layers "F.Cu" "B.Cu")
		(net "TP_CPU1_RSVD_284")
	)
	(segment
		(start 71.183246 -50.63744)
		(end 70.611746 -50.63744)
		(width 0.10795)
		(layer "F.Cu")
		(net "TP_CPU1_RSVD_288")
	)
	(via
		(at 70.611746 -50.63744)
		(size 0.508)
		(drill 0.254)
		(layers "F.Cu" "B.Cu")
		(net "TP_CPU1_RSVD_288")
	)
	(segment
		(start 85.777832 -56.085486)
		(end 85.206332 -56.085486)
		(width 0.10795)
		(layer "F.Cu")
		(net "TP_CPU1_RSVD_265")
	)
	(via
		(at 85.206332 -56.085486)
		(size 0.508)
		(drill 0.254)
		(layers "F.Cu" "B.Cu")
		(net "TP_CPU1_RSVD_265")
	)
	(segment
		(start 68.607686 -53.113686)
		(end 68.036186 -53.113686)
		(width 0.10795)
		(layer "F.Cu")
		(net "TP_CPU1_RSVD_270")
	)
	(via
		(at 68.036186 -53.113686)
		(size 0.508)
		(drill 0.254)
		(layers "F.Cu" "B.Cu")
		(net "TP_CPU1_RSVD_270")
	)
	(segment
		(start 125.938788 -65.315338)
		(end 126.510288 -65.315338)
		(width 0.1016)
		(layer "F.Cu")
		(net "TP_CPU1_RSVD_227")
	)
	(via
		(at 126.510288 -65.315338)
		(size 0.508)
		(drill 0.254)
		(layers "F.Cu" "B.Cu")
		(net "TP_CPU1_RSVD_227")
	)
	(segment
		(start 125.938788 -64.324738)
		(end 126.510288 -64.324738)
		(width 0.1016)
		(layer "F.Cu")
		(net "TP_CPU1_RSVD_240")
	)
	(via
		(at 126.510288 -64.324738)
		(size 0.508)
		(drill 0.254)
		(layers "F.Cu" "B.Cu")
		(net "TP_CPU1_RSVD_240")
	)
	(segment
		(start 127.655828 -69.277738)
		(end 128.227328 -69.277738)
		(width 0.10795)
		(layer "F.Cu")
		(net "TP_CPU1_TEST_7")
	)
	(via
		(at 128.227328 -69.277738)
		(size 0.508)
		(drill 0.254)
		(layers "F.Cu" "B.Cu")
		(net "TP_CPU1_TEST_7")
	)
	(segment
		(start 129.944114 -70.268084)
		(end 129.944368 -70.268338)
		(width 0.10795)
		(layer "F.Cu")
		(net "TP_CPU1_TEST_8")
	)
	(segment
		(start 129.372868 -70.268084)
		(end 129.944114 -70.268084)
		(width 0.10795)
		(layer "F.Cu")
		(net "TP_CPU1_TEST_8")
	)
	(via
		(at 129.944368 -70.268338)
		(size 0.508)
		(drill 0.254)
		(layers "F.Cu" "B.Cu")
		(net "TP_CPU1_TEST_8")
	)
	(segment
		(start 124.221748 -70.268084)
		(end 124.792994 -70.268084)
		(width 0.10795)
		(layer "F.Cu")
		(net "TP_CPU1_TEST_10")
	)
	(segment
		(start 124.792994 -70.268084)
		(end 124.793248 -70.268338)
		(width 0.10795)
		(layer "F.Cu")
		(net "TP_CPU1_TEST_10")
	)
	(via
		(at 124.793248 -70.268338)
		(size 0.508)
		(drill 0.254)
		(layers "F.Cu" "B.Cu")
		(net "TP_CPU1_TEST_10")
	)
	(segment
		(start 126.510034 -70.268084)
		(end 126.510288 -70.268338)
		(width 0.10795)
		(layer "F.Cu")
		(net "TP_CPU1_TEST_9")
	)
	(segment
		(start 125.938788 -70.268084)
		(end 126.510034 -70.268084)
		(width 0.10795)
		(layer "F.Cu")
		(net "TP_CPU1_TEST_9")
	)
	(via
		(at 126.510288 -70.268338)
		(size 0.508)
		(drill 0.254)
		(layers "F.Cu" "B.Cu")
		(net "TP_CPU1_TEST_9")
	)
	(segment
		(start 131.948174 -70.763384)
		(end 132.519674 -70.763384)
		(width 0.10795)
		(layer "F.Cu")
		(net "TP_CPU1_RSVD_TEST_11")
	)
	(via
		(at 132.519674 -70.763384)
		(size 0.508)
		(drill 0.254)
		(layers "F.Cu" "B.Cu")
		(net "TP_CPU1_RSVD_TEST_11")
	)
	(segment
		(start 87.494872 -55.094886)
		(end 86.923372 -55.094886)
		(width 0.10795)
		(layer "F.Cu")
		(net "TP_CPU1_RSVD_266")
	)
	(via
		(at 86.923372 -55.094886)
		(size 0.508)
		(drill 0.254)
		(layers "F.Cu" "B.Cu")
		(net "TP_CPU1_RSVD_266")
	)
	(segment
		(start 254.212344 -54.104286)
		(end 253.640844 -54.104286)
		(width 0.10795)
		(layer "F.Cu")
		(net "TP_CPU0_RSVD_267")
	)
	(via
		(at 253.640844 -54.104286)
		(size 0.508)
		(drill 0.254)
		(layers "F.Cu" "B.Cu")
		(net "TP_CPU0_RSVD_267")
	)
	(segment
		(start 253.353824 -53.60924)
		(end 252.782324 -53.60924)
		(width 0.10795)
		(layer "F.Cu")
		(net "TP_CPU0_RSVD_268")
	)
	(via
		(at 252.782324 -53.60924)
		(size 0.508)
		(drill 0.254)
		(layers "F.Cu" "B.Cu")
		(net "TP_CPU0_RSVD_268")
	)
	(segment
		(start 267.089636 -53.60924)
		(end 266.518136 -53.60924)
		(width 0.10795)
		(layer "F.Cu")
		(net "TP_CPU0_RSVD_269")
	)
	(via
		(at 266.518136 -53.60924)
		(size 0.508)
		(drill 0.254)
		(layers "F.Cu" "B.Cu")
		(net "TP_CPU0_RSVD_269")
	)
	(segment
		(start 240.476278 -83.822286)
		(end 239.904778 -83.822286)
		(width 0.10795)
		(layer "F.Cu")
		(net "TP_CPU0_RSVD_82")
	)
	(via
		(at 239.904778 -83.822286)
		(size 0.508)
		(drill 0.254)
		(layers "F.Cu" "B.Cu")
		(net "TP_CPU0_RSVD_82")
	)
	(segment
		(start 240.476278 -82.83194)
		(end 239.904778 -82.83194)
		(width 0.10795)
		(layer "F.Cu")
		(net "TP_CPU0_RSVD_90")
	)
	(via
		(at 239.904778 -82.83194)
		(size 0.508)
		(drill 0.254)
		(layers "F.Cu" "B.Cu")
		(net "TP_CPU0_RSVD_90")
	)
	(segment
		(start 236.183678 -82.33664)
		(end 235.612178 -82.33664)
		(width 0.10795)
		(layer "F.Cu")
		(net "TP_CPU0_RSVD_94")
	)
	(via
		(at 235.612178 -82.33664)
		(size 0.508)
		(drill 0.254)
		(layers "F.Cu" "B.Cu")
		(net "TP_CPU0_RSVD_94")
	)
	(segment
		(start 239.617758 -82.33664)
		(end 239.046258 -82.33664)
		(width 0.10795)
		(layer "F.Cu")
		(net "TP_CPU0_RSVD_95")
	)
	(via
		(at 239.046258 -82.33664)
		(size 0.4826)
		(drill 0.254)
		(layers "F.Cu" "B.Cu")
		(net "TP_CPU0_RSVD_95")
	)
	(segment
		(start 237.042198 -81.841086)
		(end 236.470698 -81.841086)
		(width 0.10795)
		(layer "F.Cu")
		(net "TP_CPU0_RSVD_100")
	)
	(via
		(at 236.470698 -81.841086)
		(size 0.4826)
		(drill 0.254)
		(layers "F.Cu" "B.Cu")
		(net "TP_CPU0_RSVD_100")
	)
	(segment
		(start 235.325158 -53.113686)
		(end 234.753658 -53.113686)
		(width 0.10795)
		(layer "F.Cu")
		(net "TP_CPU0_RSVD_271")
	)
	(via
		(at 234.753658 -53.113686)
		(size 0.508)
		(drill 0.254)
		(layers "F.Cu" "B.Cu")
		(net "TP_CPU0_RSVD_271")
	)
	(segment
		(start 238.759238 -81.841086)
		(end 238.187738 -81.841086)
		(width 0.10795)
		(layer "F.Cu")
		(net "TP_CPU0_RSVD_101")
	)
	(via
		(at 238.187738 -81.841086)
		(size 0.4826)
		(drill 0.254)
		(layers "F.Cu" "B.Cu")
		(net "TP_CPU0_RSVD_101")
	)
	(segment
		(start 237.900718 -81.34604)
		(end 237.329218 -81.34604)
		(width 0.10795)
		(layer "F.Cu")
		(net "TP_CPU0_RSVD_105")
	)
	(via
		(at 237.329218 -81.34604)
		(size 0.508)
		(drill 0.254)
		(layers "F.Cu" "B.Cu")
		(net "TP_CPU0_RSVD_105")
	)
	(segment
		(start 239.617758 -81.34604)
		(end 239.046258 -81.34604)
		(width 0.10795)
		(layer "F.Cu")
		(net "TP_CPU0_RSVD_106")
	)
	(via
		(at 239.046258 -81.34604)
		(size 0.508)
		(drill 0.254)
		(layers "F.Cu" "B.Cu")
		(net "TP_CPU0_RSVD_106")
	)
	(segment
		(start 247.344184 -70.94474)
		(end 246.772684 -70.94474)
		(width 0.10795)
		(layer "F.Cu")
		(net "TP_CPU0_RSVD_150")
	)
	(via
		(at 246.772684 -70.94474)
		(size 0.508)
		(drill 0.254)
		(layers "F.Cu" "B.Cu")
		(net "TP_CPU0_RSVD_150")
	)
	(segment
		(start 249.061224 -70.94474)
		(end 248.489724 -70.94474)
		(width 0.10795)
		(layer "F.Cu")
		(net "TP_CPU0_RSVD_151")
	)
	(via
		(at 248.489724 -70.94474)
		(size 0.508)
		(drill 0.254)
		(layers "F.Cu" "B.Cu")
		(net "TP_CPU0_RSVD_151")
	)
	(segment
		(start 250.778264 -70.94474)
		(end 250.206764 -70.94474)
		(width 0.10795)
		(layer "F.Cu")
		(net "TP_CPU0_RSVD_152")
	)
	(via
		(at 250.206764 -70.94474)
		(size 0.508)
		(drill 0.254)
		(layers "F.Cu" "B.Cu")
		(net "TP_CPU0_RSVD_152")
	)
	(segment
		(start 248.202704 -70.44944)
		(end 247.631204 -70.44944)
		(width 0.10795)
		(layer "F.Cu")
		(net "TP_CPU0_RSVD_156")
	)
	(via
		(at 247.631204 -70.44944)
		(size 0.508)
		(drill 0.254)
		(layers "F.Cu" "B.Cu")
		(net "TP_CPU0_RSVD_156")
	)
	(segment
		(start 249.919744 -70.44944)
		(end 249.348244 -70.44944)
		(width 0.10795)
		(layer "F.Cu")
		(net "TP_CPU0_RSVD_157")
	)
	(via
		(at 249.348244 -70.44944)
		(size 0.508)
		(drill 0.254)
		(layers "F.Cu" "B.Cu")
		(net "TP_CPU0_RSVD_157")
	)
	(segment
		(start 251.636784 -70.44944)
		(end 251.065284 -70.44944)
		(width 0.10795)
		(layer "F.Cu")
		(net "TP_CPU0_RSVD_158")
	)
	(via
		(at 251.065284 -70.44944)
		(size 0.508)
		(drill 0.254)
		(layers "F.Cu" "B.Cu")
		(net "TP_CPU0_RSVD_158")
	)
	(segment
		(start 251.4346 -51.996848)
		(end 251.065284 -51.627532)
		(width 0.10795)
		(layer "F.Cu")
		(net "TP_CPU0_RSVD_274")
	)
	(segment
		(start 251.636784 -52.618386)
		(end 251.4346 -52.416202)
		(width 0.10795)
		(layer "F.Cu")
		(net "TP_CPU0_RSVD_274")
	)
	(segment
		(start 251.4346 -52.416202)
		(end 251.4346 -51.996848)
		(width 0.10795)
		(layer "F.Cu")
		(net "TP_CPU0_RSVD_274")
	)
	(via
		(at 251.065284 -51.627532)
		(size 0.508)
		(drill 0.254)
		(layers "F.Cu" "B.Cu")
		(net "TP_CPU0_RSVD_274")
	)
	(segment
		(start 249.061224 -69.953886)
		(end 248.489724 -69.953886)
		(width 0.10795)
		(layer "F.Cu")
		(net "TP_CPU0_RSVD_163")
	)
	(via
		(at 248.489724 -69.953886)
		(size 0.508)
		(drill 0.254)
		(layers "F.Cu" "B.Cu")
		(net "TP_CPU0_RSVD_163")
	)
	(segment
		(start 250.778264 -69.953886)
		(end 250.206764 -69.953886)
		(width 0.10795)
		(layer "F.Cu")
		(net "TP_CPU0_RSVD_164")
	)
	(via
		(at 250.206764 -69.953886)
		(size 0.508)
		(drill 0.254)
		(layers "F.Cu" "B.Cu")
		(net "TP_CPU0_RSVD_164")
	)
	(segment
		(start 236.183678 -69.45884)
		(end 235.612178 -69.45884)
		(width 0.10795)
		(layer "F.Cu")
		(net "TP_CPU0_RSVD_170")
	)
	(via
		(at 235.612178 -69.45884)
		(size 0.508)
		(drill 0.254)
		(layers "F.Cu" "B.Cu")
		(net "TP_CPU0_RSVD_170")
	)
	(segment
		(start 239.617758 -69.45884)
		(end 239.046258 -69.45884)
		(width 0.10795)
		(layer "F.Cu")
		(net "TP_CPU0_RSVD_171")
	)
	(via
		(at 239.046258 -69.45884)
		(size 0.508)
		(drill 0.254)
		(layers "F.Cu" "B.Cu")
		(net "TP_CPU0_RSVD_171")
	)
	(segment
		(start 241.334798 -69.45884)
		(end 240.763298 -69.45884)
		(width 0.10795)
		(layer "F.Cu")
		(net "TP_CPU0_RSVD_172")
	)
	(via
		(at 240.763298 -69.45884)
		(size 0.508)
		(drill 0.254)
		(layers "F.Cu" "B.Cu")
		(net "TP_CPU0_RSVD_172")
	)
	(segment
		(start 249.919744 -69.45884)
		(end 249.348244 -69.45884)
		(width 0.10795)
		(layer "F.Cu")
		(net "TP_CPU0_RSVD_173")
	)
	(via
		(at 249.348244 -69.45884)
		(size 0.508)
		(drill 0.254)
		(layers "F.Cu" "B.Cu")
		(net "TP_CPU0_RSVD_173")
	)
	(segment
		(start 251.636784 -69.45884)
		(end 251.065284 -69.45884)
		(width 0.10795)
		(layer "F.Cu")
		(net "TP_CPU0_RSVD_174")
	)
	(via
		(at 251.065284 -69.45884)
		(size 0.508)
		(drill 0.254)
		(layers "F.Cu" "B.Cu")
		(net "TP_CPU0_RSVD_174")
	)
	(segment
		(start 242.193318 -68.963286)
		(end 241.621818 -68.963286)
		(width 0.10795)
		(layer "F.Cu")
		(net "TP_CPU0_RSVD_180")
	)
	(via
		(at 241.621818 -68.963286)
		(size 0.508)
		(drill 0.254)
		(layers "F.Cu" "B.Cu")
		(net "TP_CPU0_RSVD_180")
	)
	(segment
		(start 250.778264 -52.12334)
		(end 251.065284 -52.618132)
		(width 0.10795)
		(layer "F.Cu")
		(net "TP_CPU0_RSVD_277")
	)
	(via
		(at 251.065284 -52.618132)
		(size 0.508)
		(drill 0.254)
		(layers "F.Cu" "B.Cu")
		(net "TP_CPU0_RSVD_277")
	)
	(segment
		(start 249.061224 -68.963286)
		(end 248.489724 -68.963286)
		(width 0.10795)
		(layer "F.Cu")
		(net "TP_CPU0_RSVD_181")
	)
	(via
		(at 248.489724 -68.963286)
		(size 0.508)
		(drill 0.254)
		(layers "F.Cu" "B.Cu")
		(net "TP_CPU0_RSVD_181")
	)
	(segment
		(start 250.778264 -68.963286)
		(end 250.206764 -68.963286)
		(width 0.10795)
		(layer "F.Cu")
		(net "TP_CPU0_RSVD_182")
	)
	(via
		(at 250.206764 -68.963286)
		(size 0.508)
		(drill 0.254)
		(layers "F.Cu" "B.Cu")
		(net "TP_CPU0_RSVD_182")
	)
	(segment
		(start 241.334798 -68.46824)
		(end 240.763298 -68.46824)
		(width 0.10795)
		(layer "F.Cu")
		(net "TP_CPU0_RSVD_183")
	)
	(via
		(at 240.763298 -68.46824)
		(size 0.508)
		(drill 0.254)
		(layers "F.Cu" "B.Cu")
		(net "TP_CPU0_RSVD_183")
	)
	(segment
		(start 251.636784 -68.46824)
		(end 251.065284 -68.46824)
		(width 0.10795)
		(layer "F.Cu")
		(net "TP_CPU0_RSVD_184")
	)
	(via
		(at 251.065284 -68.46824)
		(size 0.508)
		(drill 0.254)
		(layers "F.Cu" "B.Cu")
		(net "TP_CPU0_RSVD_184")
	)
	(segment
		(start 240.476278 -67.972686)
		(end 239.904778 -67.972686)
		(width 0.10795)
		(layer "F.Cu")
		(net "TP_CPU0_RSVD_186")
	)
	(via
		(at 239.904778 -67.972686)
		(size 0.508)
		(drill 0.254)
		(layers "F.Cu" "B.Cu")
		(net "TP_CPU0_RSVD_186")
	)
	(segment
		(start 201.298556 -51.12766)
		(end 200.043288 -51.12766)
		(width 0.10795)
		(layer "F.Cu")
		(net "TP_CPU0_RSVD_190")
	)
	(segment
		(start 200.043288 -51.12766)
		(end 199.824086 -50.908458)
		(width 0.10795)
		(layer "F.Cu")
		(net "TP_CPU0_RSVD_190")
	)
	(segment
		(start 253.353824 -66.48704)
		(end 252.782324 -66.48704)
		(width 0.10795)
		(layer "F.Cu")
		(net "TP_CPU0_RSVD_190")
	)
	(via
		(at 201.298556 -51.12766)
		(size 0.762)
		(drill 0.3048)
		(layers "F.Cu" "B.Cu")
		(net "TP_CPU0_RSVD_190")
	)
	(via
		(at 252.782324 -66.48704)
		(size 0.508)
		(drill 0.254)
		(layers "F.Cu" "B.Cu")
		(net "TP_CPU0_RSVD_190")
	)
	(via
		(at 199.824086 -50.908458)
		(size 0.762)
		(drill 0.381)
		(layers "F.Cu" "B.Cu")
		(net "TP_CPU0_RSVD_190")
	)
	(segment
		(start 202.722226 -52.55133)
		(end 205.576678 -52.55133)
		(width 0.089408)
		(layer "In9.Cu")
		(net "TP_CPU0_RSVD_190")
	)
	(segment
		(start 252.7173 -66.084196)
		(end 252.782324 -66.14922)
		(width 0.089408)
		(layer "In9.Cu")
		(net "TP_CPU0_RSVD_190")
	)
	(segment
		(start 205.576678 -52.55133)
		(end 206.261462 -53.236114)
		(width 0.089408)
		(layer "In9.Cu")
		(net "TP_CPU0_RSVD_190")
	)
	(segment
		(start 250.182634 -64.60109)
		(end 250.213876 -64.60109)
		(width 0.089408)
		(layer "In9.Cu")
		(net "TP_CPU0_RSVD_190")
	)
	(segment
		(start 206.261462 -53.236114)
		(end 214.133684 -53.236114)
		(width 0.089408)
		(layer "In9.Cu")
		(net "TP_CPU0_RSVD_190")
	)
	(segment
		(start 242.459764 -60.143644)
		(end 242.480338 -60.143644)
		(width 0.089408)
		(layer "In9.Cu")
		(net "TP_CPU0_RSVD_190")
	)
	(segment
		(start 251.04471 -65.096644)
		(end 251.077476 -65.096644)
		(width 0.089408)
		(layer "In9.Cu")
		(net "TP_CPU0_RSVD_190")
	)
	(segment
		(start 236.446568 -56.67629)
		(end 236.47781 -56.67629)
		(width 0.089408)
		(layer "In9.Cu")
		(net "TP_CPU0_RSVD_190")
	)
	(segment
		(start 252.782324 -66.14922)
		(end 252.782324 -66.48704)
		(width 0.089408)
		(layer "In9.Cu")
		(net "TP_CPU0_RSVD_190")
	)
	(segment
		(start 214.756492 -53.858922)
		(end 231.947212 -53.858922)
		(width 0.089408)
		(layer "In9.Cu")
		(net "TP_CPU0_RSVD_190")
	)
	(segment
		(start 244.17655 -61.134244)
		(end 244.209316 -61.134244)
		(width 0.089408)
		(layer "In9.Cu")
		(net "TP_CPU0_RSVD_190")
	)
	(segment
		(start 241.597688 -59.64809)
		(end 241.62893 -59.64809)
		(width 0.089408)
		(layer "In9.Cu")
		(net "TP_CPU0_RSVD_190")
	)
	(segment
		(start 246.748554 -62.61989)
		(end 246.779796 -62.61989)
		(width 0.089408)
		(layer "In9.Cu")
		(net "TP_CPU0_RSVD_190")
	)
	(segment
		(start 239.884204 -58.657744)
		(end 239.923574 -58.657744)
		(width 0.089408)
		(layer "In9.Cu")
		(net "TP_CPU0_RSVD_190")
	)
	(segment
		(start 251.899674 -65.59169)
		(end 251.930916 -65.59169)
		(width 0.089408)
		(layer "In9.Cu")
		(net "TP_CPU0_RSVD_190")
	)
	(segment
		(start 201.298556 -51.12766)
		(end 202.722226 -52.55133)
		(width 0.089408)
		(layer "In9.Cu")
		(net "TP_CPU0_RSVD_190")
	)
	(segment
		(start 245.031514 -61.62929)
		(end 245.062756 -61.62929)
		(width 0.089408)
		(layer "In9.Cu")
		(net "TP_CPU0_RSVD_190")
	)
	(segment
		(start 214.133684 -53.236114)
		(end 214.756492 -53.858922)
		(width 0.089408)
		(layer "In9.Cu")
		(net "TP_CPU0_RSVD_190")
	)
	(segment
		(start 247.61063 -63.115444)
		(end 247.643396 -63.115444)
		(width 0.089408)
		(layer "In9.Cu")
		(net "TP_CPU0_RSVD_190")
	)
	(segment
		(start 233.77398 -55.68569)
		(end 234.76077 -55.68569)
		(width 0.089408)
		(layer "In9.Cu")
		(net "TP_CPU0_RSVD_190")
	)
	(segment
		(start 235.591604 -56.181244)
		(end 235.62437 -56.181244)
		(width 0.089408)
		(layer "In9.Cu")
		(net "TP_CPU0_RSVD_190")
	)
	(segment
		(start 240.752122 -59.153044)
		(end 240.77549 -59.153044)
		(width 0.089408)
		(layer "In9.Cu")
		(net "TP_CPU0_RSVD_190")
	)
	(segment
		(start 249.32767 -64.106044)
		(end 249.360436 -64.106044)
		(width 0.089408)
		(layer "In9.Cu")
		(net "TP_CPU0_RSVD_190")
	)
	(segment
		(start 242.824254 -60.339732)
		(end 242.82654 -60.343542)
		(width 0.089408)
		(layer "In9.Cu")
		(net "TP_CPU0_RSVD_190")
	)
	(segment
		(start 248.465594 -63.61049)
		(end 248.496836 -63.61049)
		(width 0.089408)
		(layer "In9.Cu")
		(net "TP_CPU0_RSVD_190")
	)
	(segment
		(start 231.947212 -53.858922)
		(end 233.77398 -55.68569)
		(width 0.089408)
		(layer "In9.Cu")
		(net "TP_CPU0_RSVD_190")
	)
	(segment
		(start 243.314474 -60.63869)
		(end 243.345716 -60.63869)
		(width 0.089408)
		(layer "In9.Cu")
		(net "TP_CPU0_RSVD_190")
	)
	(segment
		(start 245.89359 -62.124844)
		(end 245.926356 -62.124844)
		(width 0.089408)
		(layer "In9.Cu")
		(net "TP_CPU0_RSVD_190")
	)
	(segment
		(start 237.308644 -57.171844)
		(end 237.34141 -57.171844)
		(width 0.089408)
		(layer "In9.Cu")
		(net "TP_CPU0_RSVD_190")
	)
	(segment
		(start 238.171228 -57.667144)
		(end 238.19993 -57.667144)
		(width 0.089408)
		(layer "In9.Cu")
		(net "TP_CPU0_RSVD_190")
	)
	(segment
		(start 239.025684 -58.162444)
		(end 239.062006 -58.162444)
		(width 0.089408)
		(layer "In9.Cu")
		(net "TP_CPU0_RSVD_190")
	)
	(arc
		(start 236.47781 -56.67629)
		(mid 236.673842 -56.731674)
		(end 236.817154 -56.876442)
		(width 0.089408)
		(layer "In9.Cu")
		(net "TP_CPU0_RSVD_190")
	)
	(arc
		(start 249.6947 -64.305942)
		(mid 249.900737 -64.51622)
		(end 250.182634 -64.60109)
		(width 0.089408)
		(layer "In9.Cu")
		(net "TP_CPU0_RSVD_190")
	)
	(arc
		(start 245.926356 -62.124844)
		(mid 246.119459 -62.181363)
		(end 246.26062 -62.324742)
		(width 0.089408)
		(layer "In9.Cu")
		(net "TP_CPU0_RSVD_190")
	)
	(arc
		(start 252.27026 -65.791842)
		(mid 252.458881 -65.991372)
		(end 252.7173 -66.084196)
		(width 0.089408)
		(layer "In9.Cu")
		(net "TP_CPU0_RSVD_190")
	)
	(arc
		(start 239.392714 -58.362342)
		(mid 239.600243 -58.573626)
		(end 239.884204 -58.657744)
		(width 0.089408)
		(layer "In9.Cu")
		(net "TP_CPU0_RSVD_190")
	)
	(arc
		(start 238.534194 -57.867042)
		(mid 238.741723 -58.078326)
		(end 239.025684 -58.162444)
		(width 0.089408)
		(layer "In9.Cu")
		(net "TP_CPU0_RSVD_190")
	)
	(arc
		(start 235.100114 -55.885842)
		(mid 235.307643 -56.097126)
		(end 235.591604 -56.181244)
		(width 0.089408)
		(layer "In9.Cu")
		(net "TP_CPU0_RSVD_190")
	)
	(arc
		(start 246.779796 -62.61989)
		(mid 246.975828 -62.675274)
		(end 247.11914 -62.820042)
		(width 0.089408)
		(layer "In9.Cu")
		(net "TP_CPU0_RSVD_190")
	)
	(arc
		(start 241.109754 -59.352942)
		(mid 241.315791 -59.56322)
		(end 241.597688 -59.64809)
		(width 0.089408)
		(layer "In9.Cu")
		(net "TP_CPU0_RSVD_190")
	)
	(arc
		(start 245.4021 -61.829442)
		(mid 245.609629 -62.040726)
		(end 245.89359 -62.124844)
		(width 0.089408)
		(layer "In9.Cu")
		(net "TP_CPU0_RSVD_190")
	)
	(arc
		(start 246.26062 -62.324742)
		(mid 246.466657 -62.53502)
		(end 246.748554 -62.61989)
		(width 0.089408)
		(layer "In9.Cu")
		(net "TP_CPU0_RSVD_190")
	)
	(arc
		(start 236.817154 -56.876442)
		(mid 237.024683 -57.087726)
		(end 237.308644 -57.171844)
		(width 0.089408)
		(layer "In9.Cu")
		(net "TP_CPU0_RSVD_190")
	)
	(arc
		(start 237.675674 -57.371742)
		(mid 237.884979 -57.583982)
		(end 238.171228 -57.667144)
		(width 0.089408)
		(layer "In9.Cu")
		(net "TP_CPU0_RSVD_190")
	)
	(arc
		(start 241.968274 -59.848242)
		(mid 242.175803 -60.059526)
		(end 242.459764 -60.143644)
		(width 0.089408)
		(layer "In9.Cu")
		(net "TP_CPU0_RSVD_190")
	)
	(arc
		(start 247.11914 -62.820042)
		(mid 247.326669 -63.031326)
		(end 247.61063 -63.115444)
		(width 0.089408)
		(layer "In9.Cu")
		(net "TP_CPU0_RSVD_190")
	)
	(arc
		(start 251.41174 -65.296542)
		(mid 251.617777 -65.50682)
		(end 251.899674 -65.59169)
		(width 0.089408)
		(layer "In9.Cu")
		(net "TP_CPU0_RSVD_190")
	)
	(arc
		(start 243.345716 -60.63869)
		(mid 243.541748 -60.694074)
		(end 243.68506 -60.838842)
		(width 0.089408)
		(layer "In9.Cu")
		(net "TP_CPU0_RSVD_190")
	)
	(arc
		(start 237.34141 -57.171844)
		(mid 237.534513 -57.228363)
		(end 237.675674 -57.371742)
		(width 0.089408)
		(layer "In9.Cu")
		(net "TP_CPU0_RSVD_190")
	)
	(arc
		(start 247.97766 -63.315342)
		(mid 248.183697 -63.52562)
		(end 248.465594 -63.61049)
		(width 0.089408)
		(layer "In9.Cu")
		(net "TP_CPU0_RSVD_190")
	)
	(arc
		(start 238.19993 -57.667144)
		(mid 238.393033 -57.723663)
		(end 238.534194 -57.867042)
		(width 0.089408)
		(layer "In9.Cu")
		(net "TP_CPU0_RSVD_190")
	)
	(arc
		(start 234.76077 -55.68569)
		(mid 234.956802 -55.741074)
		(end 235.100114 -55.885842)
		(width 0.089408)
		(layer "In9.Cu")
		(net "TP_CPU0_RSVD_190")
	)
	(arc
		(start 245.062756 -61.62929)
		(mid 245.258788 -61.684674)
		(end 245.4021 -61.829442)
		(width 0.089408)
		(layer "In9.Cu")
		(net "TP_CPU0_RSVD_190")
	)
	(arc
		(start 240.77549 -59.153044)
		(mid 240.968593 -59.209563)
		(end 241.109754 -59.352942)
		(width 0.089408)
		(layer "In9.Cu")
		(net "TP_CPU0_RSVD_190")
	)
	(arc
		(start 248.83618 -63.810642)
		(mid 249.043709 -64.021926)
		(end 249.32767 -64.106044)
		(width 0.089408)
		(layer "In9.Cu")
		(net "TP_CPU0_RSVD_190")
	)
	(arc
		(start 250.55322 -64.801242)
		(mid 250.760749 -65.012526)
		(end 251.04471 -65.096644)
		(width 0.089408)
		(layer "In9.Cu")
		(net "TP_CPU0_RSVD_190")
	)
	(arc
		(start 244.54358 -61.334142)
		(mid 244.749617 -61.54442)
		(end 245.031514 -61.62929)
		(width 0.089408)
		(layer "In9.Cu")
		(net "TP_CPU0_RSVD_190")
	)
	(arc
		(start 239.062006 -58.162444)
		(mid 239.253107 -58.219794)
		(end 239.392714 -58.362342)
		(width 0.089408)
		(layer "In9.Cu")
		(net "TP_CPU0_RSVD_190")
	)
	(arc
		(start 242.82654 -60.343542)
		(mid 243.032577 -60.55382)
		(end 243.314474 -60.63869)
		(width 0.089408)
		(layer "In9.Cu")
		(net "TP_CPU0_RSVD_190")
	)
	(arc
		(start 249.360436 -64.106044)
		(mid 249.553539 -64.162563)
		(end 249.6947 -64.305942)
		(width 0.089408)
		(layer "In9.Cu")
		(net "TP_CPU0_RSVD_190")
	)
	(arc
		(start 247.643396 -63.115444)
		(mid 247.836499 -63.171963)
		(end 247.97766 -63.315342)
		(width 0.089408)
		(layer "In9.Cu")
		(net "TP_CPU0_RSVD_190")
	)
	(arc
		(start 251.077476 -65.096644)
		(mid 251.270579 -65.153163)
		(end 251.41174 -65.296542)
		(width 0.089408)
		(layer "In9.Cu")
		(net "TP_CPU0_RSVD_190")
	)
	(arc
		(start 235.958634 -56.381142)
		(mid 236.164671 -56.59142)
		(end 236.446568 -56.67629)
		(width 0.089408)
		(layer "In9.Cu")
		(net "TP_CPU0_RSVD_190")
	)
	(arc
		(start 239.923574 -58.657744)
		(mid 240.112903 -58.715715)
		(end 240.251234 -58.857388)
		(width 0.089408)
		(layer "In9.Cu")
		(net "TP_CPU0_RSVD_190")
	)
	(arc
		(start 241.62893 -59.64809)
		(mid 241.824962 -59.703474)
		(end 241.968274 -59.848242)
		(width 0.089408)
		(layer "In9.Cu")
		(net "TP_CPU0_RSVD_190")
	)
	(arc
		(start 243.68506 -60.838842)
		(mid 243.892589 -61.050126)
		(end 244.17655 -61.134244)
		(width 0.089408)
		(layer "In9.Cu")
		(net "TP_CPU0_RSVD_190")
	)
	(arc
		(start 242.480338 -60.143644)
		(mid 242.678271 -60.196118)
		(end 242.824254 -60.339732)
		(width 0.089408)
		(layer "In9.Cu")
		(net "TP_CPU0_RSVD_190")
	)
	(arc
		(start 240.251234 -58.857388)
		(mid 240.462802 -59.071077)
		(end 240.752122 -59.153044)
		(width 0.089408)
		(layer "In9.Cu")
		(net "TP_CPU0_RSVD_190")
	)
	(arc
		(start 244.209316 -61.134244)
		(mid 244.402419 -61.190763)
		(end 244.54358 -61.334142)
		(width 0.089408)
		(layer "In9.Cu")
		(net "TP_CPU0_RSVD_190")
	)
	(arc
		(start 235.62437 -56.181244)
		(mid 235.817473 -56.237763)
		(end 235.958634 -56.381142)
		(width 0.089408)
		(layer "In9.Cu")
		(net "TP_CPU0_RSVD_190")
	)
	(arc
		(start 251.930916 -65.59169)
		(mid 252.126948 -65.647074)
		(end 252.27026 -65.791842)
		(width 0.089408)
		(layer "In9.Cu")
		(net "TP_CPU0_RSVD_190")
	)
	(arc
		(start 250.213876 -64.60109)
		(mid 250.409908 -64.656474)
		(end 250.55322 -64.801242)
		(width 0.089408)
		(layer "In9.Cu")
		(net "TP_CPU0_RSVD_190")
	)
	(arc
		(start 248.496836 -63.61049)
		(mid 248.692868 -63.665874)
		(end 248.83618 -63.810642)
		(width 0.089408)
		(layer "In9.Cu")
		(net "TP_CPU0_RSVD_190")
	)
	(segment
		(start 254.212344 -65.991486)
		(end 253.640844 -65.991486)
		(width 0.10795)
		(layer "F.Cu")
		(net "TP_CPU0_RSVD_194")
	)
	(via
		(at 203.996036 -51.554126)
		(size 0.762)
		(drill 0.3048)
		(layers "F.Cu" "B.Cu")
		(net "TP_CPU0_RSVD_194")
	)
	(via
		(at 253.640844 -65.991486)
		(size 0.508)
		(drill 0.254)
		(layers "F.Cu" "B.Cu")
		(net "TP_CPU0_RSVD_194")
	)
	(segment
		(start 240.742724 -58.162444)
		(end 240.779046 -58.162444)
		(width 0.089408)
		(layer "In9.Cu")
		(net "TP_CPU0_RSVD_194")
	)
	(segment
		(start 235.591604 -55.190644)
		(end 235.62437 -55.190644)
		(width 0.089408)
		(layer "In9.Cu")
		(net "TP_CPU0_RSVD_194")
	)
	(segment
		(start 215.091772 -53.27015)
		(end 232.201212 -53.27015)
		(width 0.089408)
		(layer "In9.Cu")
		(net "TP_CPU0_RSVD_194")
	)
	(segment
		(start 253.616714 -65.59169)
		(end 253.640844 -65.59169)
		(width 0.089408)
		(layer "In9.Cu")
		(net "TP_CPU0_RSVD_194")
	)
	(segment
		(start 242.469162 -59.153044)
		(end 242.480338 -59.153044)
		(width 0.089408)
		(layer "In9.Cu")
		(net "TP_CPU0_RSVD_194")
	)
	(segment
		(start 242.824254 -59.349132)
		(end 242.82654 -59.352942)
		(width 0.089408)
		(layer "In9.Cu")
		(net "TP_CPU0_RSVD_194")
	)
	(segment
		(start 241.601244 -58.657744)
		(end 241.640614 -58.657744)
		(width 0.089408)
		(layer "In9.Cu")
		(net "TP_CPU0_RSVD_194")
	)
	(segment
		(start 203.996036 -51.554126)
		(end 204.611478 -52.169568)
		(width 0.089408)
		(layer "In9.Cu")
		(net "TP_CPU0_RSVD_194")
	)
	(segment
		(start 238.163608 -56.67629)
		(end 238.19485 -56.67629)
		(width 0.089408)
		(layer "In9.Cu")
		(net "TP_CPU0_RSVD_194")
	)
	(segment
		(start 245.89359 -61.134244)
		(end 245.926356 -61.134244)
		(width 0.089408)
		(layer "In9.Cu")
		(net "TP_CPU0_RSVD_194")
	)
	(segment
		(start 239.025684 -57.171844)
		(end 239.05845 -57.171844)
		(width 0.089408)
		(layer "In9.Cu")
		(net "TP_CPU0_RSVD_194")
	)
	(segment
		(start 253.954534 -65.743836)
		(end 253.933452 -65.82283)
		(width 0.089408)
		(layer "In9.Cu")
		(net "TP_CPU0_RSVD_194")
	)
	(segment
		(start 253.933452 -65.82283)
		(end 253.640844 -65.991486)
		(width 0.089408)
		(layer "In9.Cu")
		(net "TP_CPU0_RSVD_194")
	)
	(segment
		(start 249.32767 -63.115444)
		(end 249.360436 -63.115444)
		(width 0.089408)
		(layer "In9.Cu")
		(net "TP_CPU0_RSVD_194")
	)
	(segment
		(start 237.308644 -56.181244)
		(end 237.34141 -56.181244)
		(width 0.089408)
		(layer "In9.Cu")
		(net "TP_CPU0_RSVD_194")
	)
	(segment
		(start 248.465594 -62.61989)
		(end 248.496836 -62.61989)
		(width 0.089408)
		(layer "In9.Cu")
		(net "TP_CPU0_RSVD_194")
	)
	(segment
		(start 244.17655 -60.143644)
		(end 244.209316 -60.143644)
		(width 0.089408)
		(layer "In9.Cu")
		(net "TP_CPU0_RSVD_194")
	)
	(segment
		(start 236.446568 -55.68569)
		(end 236.47781 -55.68569)
		(width 0.089408)
		(layer "In9.Cu")
		(net "TP_CPU0_RSVD_194")
	)
	(segment
		(start 250.182634 -63.61049)
		(end 250.213876 -63.61049)
		(width 0.089408)
		(layer "In9.Cu")
		(net "TP_CPU0_RSVD_194")
	)
	(segment
		(start 239.888268 -57.667144)
		(end 239.91697 -57.667144)
		(width 0.089408)
		(layer "In9.Cu")
		(net "TP_CPU0_RSVD_194")
	)
	(segment
		(start 251.04471 -64.106044)
		(end 251.077476 -64.106044)
		(width 0.089408)
		(layer "In9.Cu")
		(net "TP_CPU0_RSVD_194")
	)
	(segment
		(start 247.61063 -62.124844)
		(end 247.643396 -62.124844)
		(width 0.089408)
		(layer "In9.Cu")
		(net "TP_CPU0_RSVD_194")
	)
	(segment
		(start 245.031514 -60.63869)
		(end 245.062756 -60.63869)
		(width 0.089408)
		(layer "In9.Cu")
		(net "TP_CPU0_RSVD_194")
	)
	(segment
		(start 252.76175 -65.096644)
		(end 252.794516 -65.096644)
		(width 0.089408)
		(layer "In9.Cu")
		(net "TP_CPU0_RSVD_194")
	)
	(segment
		(start 233.626152 -54.69509)
		(end 234.76077 -54.69509)
		(width 0.089408)
		(layer "In9.Cu")
		(net "TP_CPU0_RSVD_194")
	)
	(segment
		(start 214.628984 -52.807362)
		(end 215.091772 -53.27015)
		(width 0.089408)
		(layer "In9.Cu")
		(net "TP_CPU0_RSVD_194")
	)
	(segment
		(start 204.611478 -52.169568)
		(end 205.856078 -52.169568)
		(width 0.089408)
		(layer "In9.Cu")
		(net "TP_CPU0_RSVD_194")
	)
	(segment
		(start 205.856078 -52.169568)
		(end 206.493872 -52.807362)
		(width 0.089408)
		(layer "In9.Cu")
		(net "TP_CPU0_RSVD_194")
	)
	(segment
		(start 232.201212 -53.27015)
		(end 233.626152 -54.69509)
		(width 0.089408)
		(layer "In9.Cu")
		(net "TP_CPU0_RSVD_194")
	)
	(segment
		(start 206.493872 -52.807362)
		(end 214.628984 -52.807362)
		(width 0.089408)
		(layer "In9.Cu")
		(net "TP_CPU0_RSVD_194")
	)
	(segment
		(start 243.314474 -59.64809)
		(end 243.345716 -59.64809)
		(width 0.089408)
		(layer "In9.Cu")
		(net "TP_CPU0_RSVD_194")
	)
	(segment
		(start 251.899674 -64.60109)
		(end 251.930916 -64.60109)
		(width 0.089408)
		(layer "In9.Cu")
		(net "TP_CPU0_RSVD_194")
	)
	(segment
		(start 246.748554 -61.62929)
		(end 246.779796 -61.62929)
		(width 0.089408)
		(layer "In9.Cu")
		(net "TP_CPU0_RSVD_194")
	)
	(arc
		(start 237.34141 -56.181244)
		(mid 237.534513 -56.237763)
		(end 237.675674 -56.381142)
		(width 0.089408)
		(layer "In9.Cu")
		(net "TP_CPU0_RSVD_194")
	)
	(arc
		(start 247.11914 -61.829442)
		(mid 247.326669 -62.040726)
		(end 247.61063 -62.124844)
		(width 0.089408)
		(layer "In9.Cu")
		(net "TP_CPU0_RSVD_194")
	)
	(arc
		(start 241.640614 -58.657744)
		(mid 241.829943 -58.715715)
		(end 241.968274 -58.857388)
		(width 0.089408)
		(layer "In9.Cu")
		(net "TP_CPU0_RSVD_194")
	)
	(arc
		(start 251.41174 -64.305942)
		(mid 251.617777 -64.51622)
		(end 251.899674 -64.60109)
		(width 0.089408)
		(layer "In9.Cu")
		(net "TP_CPU0_RSVD_194")
	)
	(arc
		(start 236.817154 -55.885842)
		(mid 237.024683 -56.097126)
		(end 237.308644 -56.181244)
		(width 0.089408)
		(layer "In9.Cu")
		(net "TP_CPU0_RSVD_194")
	)
	(arc
		(start 244.54358 -60.343542)
		(mid 244.749617 -60.55382)
		(end 245.031514 -60.63869)
		(width 0.089408)
		(layer "In9.Cu")
		(net "TP_CPU0_RSVD_194")
	)
	(arc
		(start 248.496836 -62.61989)
		(mid 248.692868 -62.675274)
		(end 248.83618 -62.820042)
		(width 0.089408)
		(layer "In9.Cu")
		(net "TP_CPU0_RSVD_194")
	)
	(arc
		(start 249.6947 -63.315342)
		(mid 249.900737 -63.52562)
		(end 250.182634 -63.61049)
		(width 0.089408)
		(layer "In9.Cu")
		(net "TP_CPU0_RSVD_194")
	)
	(arc
		(start 245.062756 -60.63869)
		(mid 245.258788 -60.694074)
		(end 245.4021 -60.838842)
		(width 0.089408)
		(layer "In9.Cu")
		(net "TP_CPU0_RSVD_194")
	)
	(arc
		(start 251.077476 -64.106044)
		(mid 251.270579 -64.162563)
		(end 251.41174 -64.305942)
		(width 0.089408)
		(layer "In9.Cu")
		(net "TP_CPU0_RSVD_194")
	)
	(arc
		(start 243.68506 -59.848242)
		(mid 243.892589 -60.059526)
		(end 244.17655 -60.143644)
		(width 0.089408)
		(layer "In9.Cu")
		(net "TP_CPU0_RSVD_194")
	)
	(arc
		(start 237.675674 -56.381142)
		(mid 237.881711 -56.59142)
		(end 238.163608 -56.67629)
		(width 0.089408)
		(layer "In9.Cu")
		(net "TP_CPU0_RSVD_194")
	)
	(arc
		(start 234.76077 -54.69509)
		(mid 234.956802 -54.750474)
		(end 235.100114 -54.895242)
		(width 0.089408)
		(layer "In9.Cu")
		(net "TP_CPU0_RSVD_194")
	)
	(arc
		(start 238.534194 -56.876442)
		(mid 238.741723 -57.087726)
		(end 239.025684 -57.171844)
		(width 0.089408)
		(layer "In9.Cu")
		(net "TP_CPU0_RSVD_194")
	)
	(arc
		(start 244.209316 -60.143644)
		(mid 244.402419 -60.200163)
		(end 244.54358 -60.343542)
		(width 0.089408)
		(layer "In9.Cu")
		(net "TP_CPU0_RSVD_194")
	)
	(arc
		(start 249.360436 -63.115444)
		(mid 249.553539 -63.171963)
		(end 249.6947 -63.315342)
		(width 0.089408)
		(layer "In9.Cu")
		(net "TP_CPU0_RSVD_194")
	)
	(arc
		(start 236.47781 -55.68569)
		(mid 236.673842 -55.741074)
		(end 236.817154 -55.885842)
		(width 0.089408)
		(layer "In9.Cu")
		(net "TP_CPU0_RSVD_194")
	)
	(arc
		(start 235.62437 -55.190644)
		(mid 235.817473 -55.247163)
		(end 235.958634 -55.390542)
		(width 0.089408)
		(layer "In9.Cu")
		(net "TP_CPU0_RSVD_194")
	)
	(arc
		(start 238.19485 -56.67629)
		(mid 238.390882 -56.731674)
		(end 238.534194 -56.876442)
		(width 0.089408)
		(layer "In9.Cu")
		(net "TP_CPU0_RSVD_194")
	)
	(arc
		(start 250.213876 -63.61049)
		(mid 250.409908 -63.665874)
		(end 250.55322 -63.810642)
		(width 0.089408)
		(layer "In9.Cu")
		(net "TP_CPU0_RSVD_194")
	)
	(arc
		(start 245.926356 -61.134244)
		(mid 246.119459 -61.190763)
		(end 246.26062 -61.334142)
		(width 0.089408)
		(layer "In9.Cu")
		(net "TP_CPU0_RSVD_194")
	)
	(arc
		(start 239.05845 -57.171844)
		(mid 239.251553 -57.228363)
		(end 239.392714 -57.371742)
		(width 0.089408)
		(layer "In9.Cu")
		(net "TP_CPU0_RSVD_194")
	)
	(arc
		(start 253.12878 -65.296542)
		(mid 253.334817 -65.50682)
		(end 253.616714 -65.59169)
		(width 0.089408)
		(layer "In9.Cu")
		(net "TP_CPU0_RSVD_194")
	)
	(arc
		(start 247.643396 -62.124844)
		(mid 247.836499 -62.181363)
		(end 247.97766 -62.324742)
		(width 0.089408)
		(layer "In9.Cu")
		(net "TP_CPU0_RSVD_194")
	)
	(arc
		(start 243.345716 -59.64809)
		(mid 243.541748 -59.703474)
		(end 243.68506 -59.848242)
		(width 0.089408)
		(layer "In9.Cu")
		(net "TP_CPU0_RSVD_194")
	)
	(arc
		(start 252.794516 -65.096644)
		(mid 252.987619 -65.153163)
		(end 253.12878 -65.296542)
		(width 0.089408)
		(layer "In9.Cu")
		(net "TP_CPU0_RSVD_194")
	)
	(arc
		(start 239.91697 -57.667144)
		(mid 240.110073 -57.723663)
		(end 240.251234 -57.867042)
		(width 0.089408)
		(layer "In9.Cu")
		(net "TP_CPU0_RSVD_194")
	)
	(arc
		(start 241.109754 -58.362342)
		(mid 241.317283 -58.573626)
		(end 241.601244 -58.657744)
		(width 0.089408)
		(layer "In9.Cu")
		(net "TP_CPU0_RSVD_194")
	)
	(arc
		(start 246.26062 -61.334142)
		(mid 246.466657 -61.54442)
		(end 246.748554 -61.62929)
		(width 0.089408)
		(layer "In9.Cu")
		(net "TP_CPU0_RSVD_194")
	)
	(arc
		(start 235.100114 -54.895242)
		(mid 235.307643 -55.106526)
		(end 235.591604 -55.190644)
		(width 0.089408)
		(layer "In9.Cu")
		(net "TP_CPU0_RSVD_194")
	)
	(arc
		(start 245.4021 -60.838842)
		(mid 245.609629 -61.050126)
		(end 245.89359 -61.134244)
		(width 0.089408)
		(layer "In9.Cu")
		(net "TP_CPU0_RSVD_194")
	)
	(arc
		(start 251.930916 -64.60109)
		(mid 252.126948 -64.656474)
		(end 252.27026 -64.801242)
		(width 0.089408)
		(layer "In9.Cu")
		(net "TP_CPU0_RSVD_194")
	)
	(arc
		(start 252.27026 -64.801242)
		(mid 252.477789 -65.012526)
		(end 252.76175 -65.096644)
		(width 0.089408)
		(layer "In9.Cu")
		(net "TP_CPU0_RSVD_194")
	)
	(arc
		(start 248.83618 -62.820042)
		(mid 249.043709 -63.031326)
		(end 249.32767 -63.115444)
		(width 0.089408)
		(layer "In9.Cu")
		(net "TP_CPU0_RSVD_194")
	)
	(arc
		(start 240.251234 -57.867042)
		(mid 240.458763 -58.078326)
		(end 240.742724 -58.162444)
		(width 0.089408)
		(layer "In9.Cu")
		(net "TP_CPU0_RSVD_194")
	)
	(arc
		(start 235.958634 -55.390542)
		(mid 236.164671 -55.60082)
		(end 236.446568 -55.68569)
		(width 0.089408)
		(layer "In9.Cu")
		(net "TP_CPU0_RSVD_194")
	)
	(arc
		(start 239.392714 -57.371742)
		(mid 239.602019 -57.583982)
		(end 239.888268 -57.667144)
		(width 0.089408)
		(layer "In9.Cu")
		(net "TP_CPU0_RSVD_194")
	)
	(arc
		(start 250.55322 -63.810642)
		(mid 250.760749 -64.021926)
		(end 251.04471 -64.106044)
		(width 0.089408)
		(layer "In9.Cu")
		(net "TP_CPU0_RSVD_194")
	)
	(arc
		(start 246.779796 -61.62929)
		(mid 246.975828 -61.684674)
		(end 247.11914 -61.829442)
		(width 0.089408)
		(layer "In9.Cu")
		(net "TP_CPU0_RSVD_194")
	)
	(arc
		(start 242.82654 -59.352942)
		(mid 243.032577 -59.56322)
		(end 243.314474 -59.64809)
		(width 0.089408)
		(layer "In9.Cu")
		(net "TP_CPU0_RSVD_194")
	)
	(arc
		(start 240.779046 -58.162444)
		(mid 240.970147 -58.219794)
		(end 241.109754 -58.362342)
		(width 0.089408)
		(layer "In9.Cu")
		(net "TP_CPU0_RSVD_194")
	)
	(arc
		(start 242.480338 -59.153044)
		(mid 242.678271 -59.205518)
		(end 242.824254 -59.349132)
		(width 0.089408)
		(layer "In9.Cu")
		(net "TP_CPU0_RSVD_194")
	)
	(arc
		(start 253.640844 -65.59169)
		(mid 253.815124 -65.631799)
		(end 253.954534 -65.743836)
		(width 0.089408)
		(layer "In9.Cu")
		(net "TP_CPU0_RSVD_194")
	)
	(arc
		(start 247.97766 -62.324742)
		(mid 248.183697 -62.53502)
		(end 248.465594 -62.61989)
		(width 0.089408)
		(layer "In9.Cu")
		(net "TP_CPU0_RSVD_194")
	)
	(arc
		(start 241.968274 -58.857388)
		(mid 242.179842 -59.071077)
		(end 242.469162 -59.153044)
		(width 0.089408)
		(layer "In9.Cu")
		(net "TP_CPU0_RSVD_194")
	)
	(segment
		(start 202.469242 -51.133502)
		(end 202.469242 -49.38014)
		(width 0.10795)
		(layer "F.Cu")
		(net "TP_CPU0_RSVD_198")
	)
	(segment
		(start 202.469242 -49.38014)
		(end 203.002896 -48.846486)
		(width 0.10795)
		(layer "F.Cu")
		(net "TP_CPU0_RSVD_198")
	)
	(segment
		(start 253.353824 -65.49644)
		(end 252.782324 -65.49644)
		(width 0.10795)
		(layer "F.Cu")
		(net "TP_CPU0_RSVD_198")
	)
	(segment
		(start 202.620118 -51.284378)
		(end 202.469242 -51.133502)
		(width 0.10795)
		(layer "F.Cu")
		(net "TP_CPU0_RSVD_198")
	)
	(via
		(at 203.002896 -48.846486)
		(size 0.762)
		(drill 0.381)
		(layers "F.Cu" "B.Cu")
		(net "TP_CPU0_RSVD_198")
	)
	(via
		(at 202.620118 -51.284378)
		(size 0.762)
		(drill 0.3048)
		(layers "F.Cu" "B.Cu")
		(net "TP_CPU0_RSVD_198")
	)
	(via
		(at 252.782324 -65.49644)
		(size 0.508)
		(drill 0.254)
		(layers "F.Cu" "B.Cu")
		(net "TP_CPU0_RSVD_198")
	)
	(segment
		(start 245.907052 -61.933836)
		(end 245.938294 -61.933836)
		(width 0.089408)
		(layer "In9.Cu")
		(net "TP_CPU0_RSVD_198")
	)
	(segment
		(start 214.84971 -53.633878)
		(end 231.99217 -53.633878)
		(width 0.089408)
		(layer "In9.Cu")
		(net "TP_CPU0_RSVD_198")
	)
	(segment
		(start 206.378048 -53.01107)
		(end 214.226902 -53.01107)
		(width 0.089408)
		(layer "In9.Cu")
		(net "TP_CPU0_RSVD_198")
	)
	(segment
		(start 242.992402 -60.247784)
		(end 242.994688 -60.251594)
		(width 0.089408)
		(layer "In9.Cu")
		(net "TP_CPU0_RSVD_198")
	)
	(segment
		(start 251.911612 -65.400682)
		(end 251.944378 -65.400682)
		(width 0.089408)
		(layer "In9.Cu")
		(net "TP_CPU0_RSVD_198")
	)
	(segment
		(start 250.194572 -64.410082)
		(end 250.227338 -64.410082)
		(width 0.089408)
		(layer "In9.Cu")
		(net "TP_CPU0_RSVD_198")
	)
	(segment
		(start 251.058172 -64.905636)
		(end 251.089414 -64.905636)
		(width 0.089408)
		(layer "In9.Cu")
		(net "TP_CPU0_RSVD_198")
	)
	(segment
		(start 239.027462 -57.971182)
		(end 239.066832 -57.971182)
		(width 0.089408)
		(layer "In9.Cu")
		(net "TP_CPU0_RSVD_198")
	)
	(segment
		(start 241.609626 -59.457082)
		(end 241.642392 -59.457082)
		(width 0.089408)
		(layer "In9.Cu")
		(net "TP_CPU0_RSVD_198")
	)
	(segment
		(start 237.322106 -56.980836)
		(end 237.353348 -56.980836)
		(width 0.089408)
		(layer "In9.Cu")
		(net "TP_CPU0_RSVD_198")
	)
	(segment
		(start 245.043452 -61.438282)
		(end 245.076218 -61.438282)
		(width 0.089408)
		(layer "In9.Cu")
		(net "TP_CPU0_RSVD_198")
	)
	(segment
		(start 248.477532 -63.419482)
		(end 248.510298 -63.419482)
		(width 0.089408)
		(layer "In9.Cu")
		(net "TP_CPU0_RSVD_198")
	)
	(segment
		(start 252.724666 -65.891918)
		(end 252.782324 -65.83426)
		(width 0.089408)
		(layer "In9.Cu")
		(net "TP_CPU0_RSVD_198")
	)
	(segment
		(start 238.175546 -57.475882)
		(end 238.198914 -57.475882)
		(width 0.089408)
		(layer "In9.Cu")
		(net "TP_CPU0_RSVD_198")
	)
	(segment
		(start 236.458506 -56.485282)
		(end 236.491272 -56.485282)
		(width 0.089408)
		(layer "In9.Cu")
		(net "TP_CPU0_RSVD_198")
	)
	(segment
		(start 240.751106 -58.961782)
		(end 240.779808 -58.961782)
		(width 0.089408)
		(layer "In9.Cu")
		(net "TP_CPU0_RSVD_198")
	)
	(segment
		(start 214.226902 -53.01107)
		(end 214.84971 -53.633878)
		(width 0.089408)
		(layer "In9.Cu")
		(net "TP_CPU0_RSVD_198")
	)
	(segment
		(start 205.727554 -52.360576)
		(end 206.378048 -53.01107)
		(width 0.089408)
		(layer "In9.Cu")
		(net "TP_CPU0_RSVD_198")
	)
	(segment
		(start 202.620118 -51.284378)
		(end 203.696316 -52.360576)
		(width 0.089408)
		(layer "In9.Cu")
		(net "TP_CPU0_RSVD_198")
	)
	(segment
		(start 231.99217 -53.633878)
		(end 233.852974 -55.494682)
		(width 0.089408)
		(layer "In9.Cu")
		(net "TP_CPU0_RSVD_198")
	)
	(segment
		(start 247.624092 -62.924436)
		(end 247.655334 -62.924436)
		(width 0.089408)
		(layer "In9.Cu")
		(net "TP_CPU0_RSVD_198")
	)
	(segment
		(start 235.605066 -55.990236)
		(end 235.636308 -55.990236)
		(width 0.089408)
		(layer "In9.Cu")
		(net "TP_CPU0_RSVD_198")
	)
	(segment
		(start 239.88903 -58.466482)
		(end 239.925352 -58.466482)
		(width 0.089408)
		(layer "In9.Cu")
		(net "TP_CPU0_RSVD_198")
	)
	(segment
		(start 233.852974 -55.494682)
		(end 234.774232 -55.494682)
		(width 0.089408)
		(layer "In9.Cu")
		(net "TP_CPU0_RSVD_198")
	)
	(segment
		(start 244.190012 -60.943236)
		(end 244.221254 -60.943236)
		(width 0.089408)
		(layer "In9.Cu")
		(net "TP_CPU0_RSVD_198")
	)
	(segment
		(start 249.341132 -63.915036)
		(end 249.372374 -63.915036)
		(width 0.089408)
		(layer "In9.Cu")
		(net "TP_CPU0_RSVD_198")
	)
	(segment
		(start 242.473226 -59.952636)
		(end 242.504468 -59.952636)
		(width 0.089408)
		(layer "In9.Cu")
		(net "TP_CPU0_RSVD_198")
	)
	(segment
		(start 252.782324 -65.83426)
		(end 252.782324 -65.49644)
		(width 0.089408)
		(layer "In9.Cu")
		(net "TP_CPU0_RSVD_198")
	)
	(segment
		(start 243.338604 -60.447682)
		(end 243.359178 -60.447682)
		(width 0.089408)
		(layer "In9.Cu")
		(net "TP_CPU0_RSVD_198")
	)
	(segment
		(start 203.696316 -52.360576)
		(end 205.727554 -52.360576)
		(width 0.089408)
		(layer "In9.Cu")
		(net "TP_CPU0_RSVD_198")
	)
	(segment
		(start 246.760492 -62.428882)
		(end 246.793258 -62.428882)
		(width 0.089408)
		(layer "In9.Cu")
		(net "TP_CPU0_RSVD_198")
	)
	(arc
		(start 238.699802 -57.771538)
		(mid 238.83813 -57.913215)
		(end 239.027462 -57.971182)
		(width 0.089408)
		(layer "In9.Cu")
		(net "TP_CPU0_RSVD_198")
	)
	(arc
		(start 239.558322 -58.266584)
		(mid 239.697924 -58.40914)
		(end 239.88903 -58.466482)
		(width 0.089408)
		(layer "In9.Cu")
		(net "TP_CPU0_RSVD_198")
	)
	(arc
		(start 242.133882 -59.752484)
		(mid 242.277193 -59.897255)
		(end 242.473226 -59.952636)
		(width 0.089408)
		(layer "In9.Cu")
		(net "TP_CPU0_RSVD_198")
	)
	(arc
		(start 243.850668 -60.743084)
		(mid 243.993979 -60.887855)
		(end 244.190012 -60.943236)
		(width 0.089408)
		(layer "In9.Cu")
		(net "TP_CPU0_RSVD_198")
	)
	(arc
		(start 251.577348 -65.200784)
		(mid 251.718505 -65.344169)
		(end 251.911612 -65.400682)
		(width 0.089408)
		(layer "In9.Cu")
		(net "TP_CPU0_RSVD_198")
	)
	(arc
		(start 251.089414 -64.905636)
		(mid 251.371316 -64.990499)
		(end 251.577348 -65.200784)
		(width 0.089408)
		(layer "In9.Cu")
		(net "TP_CPU0_RSVD_198")
	)
	(arc
		(start 246.426228 -62.228984)
		(mid 246.567385 -62.372369)
		(end 246.760492 -62.428882)
		(width 0.089408)
		(layer "In9.Cu")
		(net "TP_CPU0_RSVD_198")
	)
	(arc
		(start 245.567708 -61.733684)
		(mid 245.711019 -61.878455)
		(end 245.907052 -61.933836)
		(width 0.089408)
		(layer "In9.Cu")
		(net "TP_CPU0_RSVD_198")
	)
	(arc
		(start 250.718828 -64.705484)
		(mid 250.862139 -64.850255)
		(end 251.058172 -64.905636)
		(width 0.089408)
		(layer "In9.Cu")
		(net "TP_CPU0_RSVD_198")
	)
	(arc
		(start 245.076218 -61.438282)
		(mid 245.360179 -61.5224)
		(end 245.567708 -61.733684)
		(width 0.089408)
		(layer "In9.Cu")
		(net "TP_CPU0_RSVD_198")
	)
	(arc
		(start 236.491272 -56.485282)
		(mid 236.775233 -56.5694)
		(end 236.982762 -56.780684)
		(width 0.089408)
		(layer "In9.Cu")
		(net "TP_CPU0_RSVD_198")
	)
	(arc
		(start 250.227338 -64.410082)
		(mid 250.511299 -64.4942)
		(end 250.718828 -64.705484)
		(width 0.089408)
		(layer "In9.Cu")
		(net "TP_CPU0_RSVD_198")
	)
	(arc
		(start 240.416842 -58.761884)
		(mid 240.557999 -58.905269)
		(end 240.751106 -58.961782)
		(width 0.089408)
		(layer "In9.Cu")
		(net "TP_CPU0_RSVD_198")
	)
	(arc
		(start 236.124242 -56.285384)
		(mid 236.265399 -56.428769)
		(end 236.458506 -56.485282)
		(width 0.089408)
		(layer "In9.Cu")
		(net "TP_CPU0_RSVD_198")
	)
	(arc
		(start 234.774232 -55.494682)
		(mid 235.058193 -55.5788)
		(end 235.265722 -55.790084)
		(width 0.089408)
		(layer "In9.Cu")
		(net "TP_CPU0_RSVD_198")
	)
	(arc
		(start 239.925352 -58.466482)
		(mid 240.209313 -58.5506)
		(end 240.416842 -58.761884)
		(width 0.089408)
		(layer "In9.Cu")
		(net "TP_CPU0_RSVD_198")
	)
	(arc
		(start 249.372374 -63.915036)
		(mid 249.654276 -63.999899)
		(end 249.860308 -64.210184)
		(width 0.089408)
		(layer "In9.Cu")
		(net "TP_CPU0_RSVD_198")
	)
	(arc
		(start 238.198914 -57.475882)
		(mid 238.488235 -57.557847)
		(end 238.699802 -57.771538)
		(width 0.089408)
		(layer "In9.Cu")
		(net "TP_CPU0_RSVD_198")
	)
	(arc
		(start 246.793258 -62.428882)
		(mid 247.077219 -62.513)
		(end 247.284748 -62.724284)
		(width 0.089408)
		(layer "In9.Cu")
		(net "TP_CPU0_RSVD_198")
	)
	(arc
		(start 244.709188 -61.238384)
		(mid 244.850345 -61.381769)
		(end 245.043452 -61.438282)
		(width 0.089408)
		(layer "In9.Cu")
		(net "TP_CPU0_RSVD_198")
	)
	(arc
		(start 247.284748 -62.724284)
		(mid 247.428059 -62.869055)
		(end 247.624092 -62.924436)
		(width 0.089408)
		(layer "In9.Cu")
		(net "TP_CPU0_RSVD_198")
	)
	(arc
		(start 248.510298 -63.419482)
		(mid 248.794259 -63.5036)
		(end 249.001788 -63.714884)
		(width 0.089408)
		(layer "In9.Cu")
		(net "TP_CPU0_RSVD_198")
	)
	(arc
		(start 249.001788 -63.714884)
		(mid 249.145099 -63.859655)
		(end 249.341132 -63.915036)
		(width 0.089408)
		(layer "In9.Cu")
		(net "TP_CPU0_RSVD_198")
	)
	(arc
		(start 242.504468 -59.952636)
		(mid 242.78637 -60.037499)
		(end 242.992402 -60.247784)
		(width 0.089408)
		(layer "In9.Cu")
		(net "TP_CPU0_RSVD_198")
	)
	(arc
		(start 251.944378 -65.400682)
		(mid 252.228339 -65.4848)
		(end 252.435868 -65.696084)
		(width 0.089408)
		(layer "In9.Cu")
		(net "TP_CPU0_RSVD_198")
	)
	(arc
		(start 237.353348 -56.980836)
		(mid 237.63525 -57.065699)
		(end 237.841282 -57.275984)
		(width 0.089408)
		(layer "In9.Cu")
		(net "TP_CPU0_RSVD_198")
	)
	(arc
		(start 243.359178 -60.447682)
		(mid 243.643139 -60.5318)
		(end 243.850668 -60.743084)
		(width 0.089408)
		(layer "In9.Cu")
		(net "TP_CPU0_RSVD_198")
	)
	(arc
		(start 239.066832 -57.971182)
		(mid 239.350793 -58.0553)
		(end 239.558322 -58.266584)
		(width 0.089408)
		(layer "In9.Cu")
		(net "TP_CPU0_RSVD_198")
	)
	(arc
		(start 237.841282 -57.275984)
		(mid 237.982439 -57.419369)
		(end 238.175546 -57.475882)
		(width 0.089408)
		(layer "In9.Cu")
		(net "TP_CPU0_RSVD_198")
	)
	(arc
		(start 241.642392 -59.457082)
		(mid 241.926353 -59.5412)
		(end 242.133882 -59.752484)
		(width 0.089408)
		(layer "In9.Cu")
		(net "TP_CPU0_RSVD_198")
	)
	(arc
		(start 244.221254 -60.943236)
		(mid 244.503156 -61.028099)
		(end 244.709188 -61.238384)
		(width 0.089408)
		(layer "In9.Cu")
		(net "TP_CPU0_RSVD_198")
	)
	(arc
		(start 248.143268 -63.219584)
		(mid 248.284425 -63.362969)
		(end 248.477532 -63.419482)
		(width 0.089408)
		(layer "In9.Cu")
		(net "TP_CPU0_RSVD_198")
	)
	(arc
		(start 242.994688 -60.251594)
		(mid 243.140647 -60.395249)
		(end 243.338604 -60.447682)
		(width 0.089408)
		(layer "In9.Cu")
		(net "TP_CPU0_RSVD_198")
	)
	(arc
		(start 235.265722 -55.790084)
		(mid 235.409033 -55.934855)
		(end 235.605066 -55.990236)
		(width 0.089408)
		(layer "In9.Cu")
		(net "TP_CPU0_RSVD_198")
	)
	(arc
		(start 245.938294 -61.933836)
		(mid 246.220196 -62.018699)
		(end 246.426228 -62.228984)
		(width 0.089408)
		(layer "In9.Cu")
		(net "TP_CPU0_RSVD_198")
	)
	(arc
		(start 241.275362 -59.257184)
		(mid 241.416519 -59.400569)
		(end 241.609626 -59.457082)
		(width 0.089408)
		(layer "In9.Cu")
		(net "TP_CPU0_RSVD_198")
	)
	(arc
		(start 249.860308 -64.210184)
		(mid 250.001465 -64.353569)
		(end 250.194572 -64.410082)
		(width 0.089408)
		(layer "In9.Cu")
		(net "TP_CPU0_RSVD_198")
	)
	(arc
		(start 240.779808 -58.961782)
		(mid 241.066057 -59.044943)
		(end 241.275362 -59.257184)
		(width 0.089408)
		(layer "In9.Cu")
		(net "TP_CPU0_RSVD_198")
	)
	(arc
		(start 252.435868 -65.696084)
		(mid 252.557796 -65.827118)
		(end 252.724666 -65.891918)
		(width 0.089408)
		(layer "In9.Cu")
		(net "TP_CPU0_RSVD_198")
	)
	(arc
		(start 236.982762 -56.780684)
		(mid 237.126073 -56.925455)
		(end 237.322106 -56.980836)
		(width 0.089408)
		(layer "In9.Cu")
		(net "TP_CPU0_RSVD_198")
	)
	(arc
		(start 235.636308 -55.990236)
		(mid 235.91821 -56.075099)
		(end 236.124242 -56.285384)
		(width 0.089408)
		(layer "In9.Cu")
		(net "TP_CPU0_RSVD_198")
	)
	(arc
		(start 247.655334 -62.924436)
		(mid 247.937236 -63.009299)
		(end 248.143268 -63.219584)
		(width 0.089408)
		(layer "In9.Cu")
		(net "TP_CPU0_RSVD_198")
	)
	(segment
		(start 207.305656 -49.48428)
		(end 207.305656 -50.77968)
		(width 0.10795)
		(layer "F.Cu")
		(net "TP_CPU0_RSVD_199")
	)
	(segment
		(start 206.564992 -48.345852)
		(end 206.564992 -48.743616)
		(width 0.10795)
		(layer "F.Cu")
		(net "TP_CPU0_RSVD_199")
	)
	(segment
		(start 207.305656 -50.77968)
		(end 206.38897 -51.696366)
		(width 0.10795)
		(layer "F.Cu")
		(net "TP_CPU0_RSVD_199")
	)
	(segment
		(start 255.07061 -65.49644)
		(end 254.49911 -65.49644)
		(width 0.10795)
		(layer "F.Cu")
		(net "TP_CPU0_RSVD_199")
	)
	(segment
		(start 206.38897 -51.696366)
		(end 205.27391 -51.696366)
		(width 0.10795)
		(layer "F.Cu")
		(net "TP_CPU0_RSVD_199")
	)
	(segment
		(start 206.564992 -48.743616)
		(end 207.305656 -49.48428)
		(width 0.10795)
		(layer "F.Cu")
		(net "TP_CPU0_RSVD_199")
	)
	(via
		(at 205.27391 -51.696366)
		(size 0.762)
		(drill 0.3048)
		(layers "F.Cu" "B.Cu")
		(net "TP_CPU0_RSVD_199")
	)
	(via
		(at 206.564992 -48.345852)
		(size 0.762)
		(drill 0.381)
		(layers "F.Cu" "B.Cu")
		(net "TP_CPU0_RSVD_199")
	)
	(via
		(at 254.49911 -65.49644)
		(size 0.508)
		(drill 0.254)
		(layers "F.Cu" "B.Cu")
		(net "TP_CPU0_RSVD_199")
	)
	(segment
		(start 206.584296 -52.578508)
		(end 214.72398 -52.578508)
		(width 0.089408)
		(layer "In9.Cu")
		(net "TP_CPU0_RSVD_199")
	)
	(segment
		(start 242.468146 -58.961782)
		(end 242.496848 -58.961782)
		(width 0.089408)
		(layer "In9.Cu")
		(net "TP_CPU0_RSVD_199")
	)
	(segment
		(start 233.705146 -54.504082)
		(end 234.774232 -54.504082)
		(width 0.089408)
		(layer "In9.Cu")
		(net "TP_CPU0_RSVD_199")
	)
	(segment
		(start 251.911612 -64.410082)
		(end 251.944378 -64.410082)
		(width 0.089408)
		(layer "In9.Cu")
		(net "TP_CPU0_RSVD_199")
	)
	(segment
		(start 244.190012 -59.952636)
		(end 244.221254 -59.952636)
		(width 0.089408)
		(layer "In9.Cu")
		(net "TP_CPU0_RSVD_199")
	)
	(segment
		(start 245.907052 -60.943236)
		(end 245.938294 -60.943236)
		(width 0.089408)
		(layer "In9.Cu")
		(net "TP_CPU0_RSVD_199")
	)
	(segment
		(start 235.605066 -54.999636)
		(end 235.636308 -54.999636)
		(width 0.089408)
		(layer "In9.Cu")
		(net "TP_CPU0_RSVD_199")
	)
	(segment
		(start 240.744502 -57.971182)
		(end 240.783872 -57.971182)
		(width 0.089408)
		(layer "In9.Cu")
		(net "TP_CPU0_RSVD_199")
	)
	(segment
		(start 248.477532 -62.428882)
		(end 248.510298 -62.428882)
		(width 0.089408)
		(layer "In9.Cu")
		(net "TP_CPU0_RSVD_199")
	)
	(segment
		(start 239.039146 -56.980836)
		(end 239.070388 -56.980836)
		(width 0.089408)
		(layer "In9.Cu")
		(net "TP_CPU0_RSVD_199")
	)
	(segment
		(start 205.702154 -51.696366)
		(end 206.584296 -52.578508)
		(width 0.089408)
		(layer "In9.Cu")
		(net "TP_CPU0_RSVD_199")
	)
	(segment
		(start 243.338604 -59.457082)
		(end 243.359178 -59.457082)
		(width 0.089408)
		(layer "In9.Cu")
		(net "TP_CPU0_RSVD_199")
	)
	(segment
		(start 249.341132 -62.924436)
		(end 249.372374 -62.924436)
		(width 0.089408)
		(layer "In9.Cu")
		(net "TP_CPU0_RSVD_199")
	)
	(segment
		(start 232.24236 -53.041296)
		(end 233.705146 -54.504082)
		(width 0.089408)
		(layer "In9.Cu")
		(net "TP_CPU0_RSVD_199")
	)
	(segment
		(start 215.186768 -53.041296)
		(end 232.24236 -53.041296)
		(width 0.089408)
		(layer "In9.Cu")
		(net "TP_CPU0_RSVD_199")
	)
	(segment
		(start 239.892586 -57.475882)
		(end 239.915954 -57.475882)
		(width 0.089408)
		(layer "In9.Cu")
		(net "TP_CPU0_RSVD_199")
	)
	(segment
		(start 246.760492 -61.438282)
		(end 246.793258 -61.438282)
		(width 0.089408)
		(layer "In9.Cu")
		(net "TP_CPU0_RSVD_199")
	)
	(segment
		(start 250.194572 -63.419482)
		(end 250.227338 -63.419482)
		(width 0.089408)
		(layer "In9.Cu")
		(net "TP_CPU0_RSVD_199")
	)
	(segment
		(start 254.206502 -65.665096)
		(end 254.49911 -65.49644)
		(width 0.089408)
		(layer "In9.Cu")
		(net "TP_CPU0_RSVD_199")
	)
	(segment
		(start 242.992402 -59.257184)
		(end 242.994688 -59.260994)
		(width 0.089408)
		(layer "In9.Cu")
		(net "TP_CPU0_RSVD_199")
	)
	(segment
		(start 236.458506 -55.494682)
		(end 236.491272 -55.494682)
		(width 0.089408)
		(layer "In9.Cu")
		(net "TP_CPU0_RSVD_199")
	)
	(segment
		(start 247.624092 -61.933836)
		(end 247.655334 -61.933836)
		(width 0.089408)
		(layer "In9.Cu")
		(net "TP_CPU0_RSVD_199")
	)
	(segment
		(start 245.043452 -60.447682)
		(end 245.076218 -60.447682)
		(width 0.089408)
		(layer "In9.Cu")
		(net "TP_CPU0_RSVD_199")
	)
	(segment
		(start 252.775212 -64.905636)
		(end 252.806454 -64.905636)
		(width 0.089408)
		(layer "In9.Cu")
		(net "TP_CPU0_RSVD_199")
	)
	(segment
		(start 251.058172 -63.915036)
		(end 251.089414 -63.915036)
		(width 0.089408)
		(layer "In9.Cu")
		(net "TP_CPU0_RSVD_199")
	)
	(segment
		(start 253.628652 -65.400682)
		(end 253.661418 -65.400682)
		(width 0.089408)
		(layer "In9.Cu")
		(net "TP_CPU0_RSVD_199")
	)
	(segment
		(start 254.117094 -65.640966)
		(end 254.206502 -65.665096)
		(width 0.089408)
		(layer "In9.Cu")
		(net "TP_CPU0_RSVD_199")
	)
	(segment
		(start 214.72398 -52.578508)
		(end 215.186768 -53.041296)
		(width 0.089408)
		(layer "In9.Cu")
		(net "TP_CPU0_RSVD_199")
	)
	(segment
		(start 238.175546 -56.485282)
		(end 238.208312 -56.485282)
		(width 0.089408)
		(layer "In9.Cu")
		(net "TP_CPU0_RSVD_199")
	)
	(segment
		(start 241.60607 -58.466482)
		(end 241.642392 -58.466482)
		(width 0.089408)
		(layer "In9.Cu")
		(net "TP_CPU0_RSVD_199")
	)
	(segment
		(start 205.27391 -51.696366)
		(end 205.702154 -51.696366)
		(width 0.089408)
		(layer "In9.Cu")
		(net "TP_CPU0_RSVD_199")
	)
	(segment
		(start 237.322106 -55.990236)
		(end 237.353348 -55.990236)
		(width 0.089408)
		(layer "In9.Cu")
		(net "TP_CPU0_RSVD_199")
	)
	(arc
		(start 242.496848 -58.961782)
		(mid 242.783097 -59.044943)
		(end 242.992402 -59.257184)
		(width 0.089408)
		(layer "In9.Cu")
		(net "TP_CPU0_RSVD_199")
	)
	(arc
		(start 244.221254 -59.952636)
		(mid 244.503156 -60.037499)
		(end 244.709188 -60.247784)
		(width 0.089408)
		(layer "In9.Cu")
		(net "TP_CPU0_RSVD_199")
	)
	(arc
		(start 253.661418 -65.400682)
		(mid 253.916814 -65.468568)
		(end 254.117094 -65.640966)
		(width 0.089408)
		(layer "In9.Cu")
		(net "TP_CPU0_RSVD_199")
	)
	(arc
		(start 246.793258 -61.438282)
		(mid 247.077219 -61.5224)
		(end 247.284748 -61.733684)
		(width 0.089408)
		(layer "In9.Cu")
		(net "TP_CPU0_RSVD_199")
	)
	(arc
		(start 252.435868 -64.705484)
		(mid 252.579179 -64.850255)
		(end 252.775212 -64.905636)
		(width 0.089408)
		(layer "In9.Cu")
		(net "TP_CPU0_RSVD_199")
	)
	(arc
		(start 248.510298 -62.428882)
		(mid 248.794259 -62.513)
		(end 249.001788 -62.724284)
		(width 0.089408)
		(layer "In9.Cu")
		(net "TP_CPU0_RSVD_199")
	)
	(arc
		(start 250.227338 -63.419482)
		(mid 250.511299 -63.5036)
		(end 250.718828 -63.714884)
		(width 0.089408)
		(layer "In9.Cu")
		(net "TP_CPU0_RSVD_199")
	)
	(arc
		(start 236.124242 -55.294784)
		(mid 236.265399 -55.438169)
		(end 236.458506 -55.494682)
		(width 0.089408)
		(layer "In9.Cu")
		(net "TP_CPU0_RSVD_199")
	)
	(arc
		(start 245.567708 -60.743084)
		(mid 245.711019 -60.887855)
		(end 245.907052 -60.943236)
		(width 0.089408)
		(layer "In9.Cu")
		(net "TP_CPU0_RSVD_199")
	)
	(arc
		(start 239.558322 -57.275984)
		(mid 239.699479 -57.419369)
		(end 239.892586 -57.475882)
		(width 0.089408)
		(layer "In9.Cu")
		(net "TP_CPU0_RSVD_199")
	)
	(arc
		(start 249.372374 -62.924436)
		(mid 249.654276 -63.009299)
		(end 249.860308 -63.219584)
		(width 0.089408)
		(layer "In9.Cu")
		(net "TP_CPU0_RSVD_199")
	)
	(arc
		(start 238.208312 -56.485282)
		(mid 238.492273 -56.5694)
		(end 238.699802 -56.780684)
		(width 0.089408)
		(layer "In9.Cu")
		(net "TP_CPU0_RSVD_199")
	)
	(arc
		(start 245.938294 -60.943236)
		(mid 246.220196 -61.028099)
		(end 246.426228 -61.238384)
		(width 0.089408)
		(layer "In9.Cu")
		(net "TP_CPU0_RSVD_199")
	)
	(arc
		(start 253.294388 -65.200784)
		(mid 253.435545 -65.344169)
		(end 253.628652 -65.400682)
		(width 0.089408)
		(layer "In9.Cu")
		(net "TP_CPU0_RSVD_199")
	)
	(arc
		(start 246.426228 -61.238384)
		(mid 246.567385 -61.381769)
		(end 246.760492 -61.438282)
		(width 0.089408)
		(layer "In9.Cu")
		(net "TP_CPU0_RSVD_199")
	)
	(arc
		(start 242.994688 -59.260994)
		(mid 243.140647 -59.404649)
		(end 243.338604 -59.457082)
		(width 0.089408)
		(layer "In9.Cu")
		(net "TP_CPU0_RSVD_199")
	)
	(arc
		(start 242.133882 -58.761884)
		(mid 242.275039 -58.905269)
		(end 242.468146 -58.961782)
		(width 0.089408)
		(layer "In9.Cu")
		(net "TP_CPU0_RSVD_199")
	)
	(arc
		(start 252.806454 -64.905636)
		(mid 253.088356 -64.990499)
		(end 253.294388 -65.200784)
		(width 0.089408)
		(layer "In9.Cu")
		(net "TP_CPU0_RSVD_199")
	)
	(arc
		(start 243.359178 -59.457082)
		(mid 243.643139 -59.5412)
		(end 243.850668 -59.752484)
		(width 0.089408)
		(layer "In9.Cu")
		(net "TP_CPU0_RSVD_199")
	)
	(arc
		(start 235.265722 -54.799484)
		(mid 235.409033 -54.944255)
		(end 235.605066 -54.999636)
		(width 0.089408)
		(layer "In9.Cu")
		(net "TP_CPU0_RSVD_199")
	)
	(arc
		(start 237.353348 -55.990236)
		(mid 237.63525 -56.075099)
		(end 237.841282 -56.285384)
		(width 0.089408)
		(layer "In9.Cu")
		(net "TP_CPU0_RSVD_199")
	)
	(arc
		(start 241.275362 -58.266584)
		(mid 241.414964 -58.40914)
		(end 241.60607 -58.466482)
		(width 0.089408)
		(layer "In9.Cu")
		(net "TP_CPU0_RSVD_199")
	)
	(arc
		(start 239.070388 -56.980836)
		(mid 239.35229 -57.065699)
		(end 239.558322 -57.275984)
		(width 0.089408)
		(layer "In9.Cu")
		(net "TP_CPU0_RSVD_199")
	)
	(arc
		(start 235.636308 -54.999636)
		(mid 235.91821 -55.084499)
		(end 236.124242 -55.294784)
		(width 0.089408)
		(layer "In9.Cu")
		(net "TP_CPU0_RSVD_199")
	)
	(arc
		(start 250.718828 -63.714884)
		(mid 250.862139 -63.859655)
		(end 251.058172 -63.915036)
		(width 0.089408)
		(layer "In9.Cu")
		(net "TP_CPU0_RSVD_199")
	)
	(arc
		(start 240.783872 -57.971182)
		(mid 241.067833 -58.0553)
		(end 241.275362 -58.266584)
		(width 0.089408)
		(layer "In9.Cu")
		(net "TP_CPU0_RSVD_199")
	)
	(arc
		(start 249.001788 -62.724284)
		(mid 249.145099 -62.869055)
		(end 249.341132 -62.924436)
		(width 0.089408)
		(layer "In9.Cu")
		(net "TP_CPU0_RSVD_199")
	)
	(arc
		(start 251.089414 -63.915036)
		(mid 251.371316 -63.999899)
		(end 251.577348 -64.210184)
		(width 0.089408)
		(layer "In9.Cu")
		(net "TP_CPU0_RSVD_199")
	)
	(arc
		(start 238.699802 -56.780684)
		(mid 238.843113 -56.925455)
		(end 239.039146 -56.980836)
		(width 0.089408)
		(layer "In9.Cu")
		(net "TP_CPU0_RSVD_199")
	)
	(arc
		(start 237.841282 -56.285384)
		(mid 237.982439 -56.428769)
		(end 238.175546 -56.485282)
		(width 0.089408)
		(layer "In9.Cu")
		(net "TP_CPU0_RSVD_199")
	)
	(arc
		(start 239.915954 -57.475882)
		(mid 240.205275 -57.557847)
		(end 240.416842 -57.771538)
		(width 0.089408)
		(layer "In9.Cu")
		(net "TP_CPU0_RSVD_199")
	)
	(arc
		(start 251.577348 -64.210184)
		(mid 251.718505 -64.353569)
		(end 251.911612 -64.410082)
		(width 0.089408)
		(layer "In9.Cu")
		(net "TP_CPU0_RSVD_199")
	)
	(arc
		(start 244.709188 -60.247784)
		(mid 244.850345 -60.391169)
		(end 245.043452 -60.447682)
		(width 0.089408)
		(layer "In9.Cu")
		(net "TP_CPU0_RSVD_199")
	)
	(arc
		(start 236.982762 -55.790084)
		(mid 237.126073 -55.934855)
		(end 237.322106 -55.990236)
		(width 0.089408)
		(layer "In9.Cu")
		(net "TP_CPU0_RSVD_199")
	)
	(arc
		(start 247.284748 -61.733684)
		(mid 247.428059 -61.878455)
		(end 247.624092 -61.933836)
		(width 0.089408)
		(layer "In9.Cu")
		(net "TP_CPU0_RSVD_199")
	)
	(arc
		(start 240.416842 -57.771538)
		(mid 240.55517 -57.913215)
		(end 240.744502 -57.971182)
		(width 0.089408)
		(layer "In9.Cu")
		(net "TP_CPU0_RSVD_199")
	)
	(arc
		(start 243.850668 -59.752484)
		(mid 243.993979 -59.897255)
		(end 244.190012 -59.952636)
		(width 0.089408)
		(layer "In9.Cu")
		(net "TP_CPU0_RSVD_199")
	)
	(arc
		(start 247.655334 -61.933836)
		(mid 247.937236 -62.018699)
		(end 248.143268 -62.228984)
		(width 0.089408)
		(layer "In9.Cu")
		(net "TP_CPU0_RSVD_199")
	)
	(arc
		(start 245.076218 -60.447682)
		(mid 245.360179 -60.5318)
		(end 245.567708 -60.743084)
		(width 0.089408)
		(layer "In9.Cu")
		(net "TP_CPU0_RSVD_199")
	)
	(arc
		(start 248.143268 -62.228984)
		(mid 248.284425 -62.372369)
		(end 248.477532 -62.428882)
		(width 0.089408)
		(layer "In9.Cu")
		(net "TP_CPU0_RSVD_199")
	)
	(arc
		(start 241.642392 -58.466482)
		(mid 241.926353 -58.5506)
		(end 242.133882 -58.761884)
		(width 0.089408)
		(layer "In9.Cu")
		(net "TP_CPU0_RSVD_199")
	)
	(arc
		(start 249.860308 -63.219584)
		(mid 250.001465 -63.362969)
		(end 250.194572 -63.419482)
		(width 0.089408)
		(layer "In9.Cu")
		(net "TP_CPU0_RSVD_199")
	)
	(arc
		(start 234.774232 -54.504082)
		(mid 235.058193 -54.5882)
		(end 235.265722 -54.799484)
		(width 0.089408)
		(layer "In9.Cu")
		(net "TP_CPU0_RSVD_199")
	)
	(arc
		(start 251.944378 -64.410082)
		(mid 252.228339 -64.4942)
		(end 252.435868 -64.705484)
		(width 0.089408)
		(layer "In9.Cu")
		(net "TP_CPU0_RSVD_199")
	)
	(arc
		(start 236.491272 -55.494682)
		(mid 236.775233 -55.5788)
		(end 236.982762 -55.790084)
		(width 0.089408)
		(layer "In9.Cu")
		(net "TP_CPU0_RSVD_199")
	)
	(segment
		(start 207.726534 -50.87874)
		(end 206.971646 -51.633628)
		(width 0.10795)
		(layer "F.Cu")
		(net "TP_CPU0_RSVD_204")
	)
	(segment
		(start 206.971646 -51.633628)
		(end 206.971646 -52.070254)
		(width 0.10795)
		(layer "F.Cu")
		(net "TP_CPU0_RSVD_204")
	)
	(segment
		(start 207.726534 -49.034446)
		(end 207.726534 -50.87874)
		(width 0.10795)
		(layer "F.Cu")
		(net "TP_CPU0_RSVD_204")
	)
	(segment
		(start 254.212344 -65.000886)
		(end 253.640844 -65.000886)
		(width 0.10795)
		(layer "F.Cu")
		(net "TP_CPU0_RSVD_204")
	)
	(via
		(at 253.640844 -65.000886)
		(size 0.508)
		(drill 0.254)
		(layers "F.Cu" "B.Cu")
		(net "TP_CPU0_RSVD_204")
	)
	(via
		(at 206.971646 -52.070254)
		(size 0.762)
		(drill 0.3048)
		(layers "F.Cu" "B.Cu")
		(net "TP_CPU0_RSVD_204")
	)
	(via
		(at 207.726534 -49.034446)
		(size 0.762)
		(drill 0.381)
		(layers "F.Cu" "B.Cu")
		(net "TP_CPU0_RSVD_204")
	)
	(segment
		(start 233.883962 -53.209444)
		(end 233.90733 -53.209444)
		(width 0.089408)
		(layer "In9.Cu")
		(net "TP_CPU0_RSVD_204")
	)
	(segment
		(start 234.729528 -53.70449)
		(end 234.76077 -53.70449)
		(width 0.089408)
		(layer "In9.Cu")
		(net "TP_CPU0_RSVD_204")
	)
	(segment
		(start 251.899674 -63.61049)
		(end 251.930916 -63.61049)
		(width 0.089408)
		(layer "In9.Cu")
		(net "TP_CPU0_RSVD_204")
	)
	(segment
		(start 245.89359 -60.143644)
		(end 245.926356 -60.143644)
		(width 0.089408)
		(layer "In9.Cu")
		(net "TP_CPU0_RSVD_204")
	)
	(segment
		(start 235.591604 -54.200044)
		(end 235.62437 -54.200044)
		(width 0.089408)
		(layer "In9.Cu")
		(net "TP_CPU0_RSVD_204")
	)
	(segment
		(start 241.605308 -57.667144)
		(end 241.63401 -57.667144)
		(width 0.089408)
		(layer "In9.Cu")
		(net "TP_CPU0_RSVD_204")
	)
	(segment
		(start 253.57582 -64.598042)
		(end 253.640844 -64.663066)
		(width 0.089408)
		(layer "In9.Cu")
		(net "TP_CPU0_RSVD_204")
	)
	(segment
		(start 246.748554 -60.63869)
		(end 246.779796 -60.63869)
		(width 0.089408)
		(layer "In9.Cu")
		(net "TP_CPU0_RSVD_204")
	)
	(segment
		(start 252.76175 -64.106044)
		(end 252.794516 -64.106044)
		(width 0.089408)
		(layer "In9.Cu")
		(net "TP_CPU0_RSVD_204")
	)
	(segment
		(start 236.446568 -54.69509)
		(end 236.47781 -54.69509)
		(width 0.089408)
		(layer "In9.Cu")
		(net "TP_CPU0_RSVD_204")
	)
	(segment
		(start 245.031514 -59.64809)
		(end 245.062756 -59.64809)
		(width 0.089408)
		(layer "In9.Cu")
		(net "TP_CPU0_RSVD_204")
	)
	(segment
		(start 243.31803 -58.657744)
		(end 243.3574 -58.657744)
		(width 0.089408)
		(layer "In9.Cu")
		(net "TP_CPU0_RSVD_204")
	)
	(segment
		(start 244.185948 -59.153044)
		(end 244.209316 -59.153044)
		(width 0.089408)
		(layer "In9.Cu")
		(net "TP_CPU0_RSVD_204")
	)
	(segment
		(start 251.04471 -63.115444)
		(end 251.077476 -63.115444)
		(width 0.089408)
		(layer "In9.Cu")
		(net "TP_CPU0_RSVD_204")
	)
	(segment
		(start 242.459764 -58.162444)
		(end 242.489228 -58.162444)
		(width 0.089408)
		(layer "In9.Cu")
		(net "TP_CPU0_RSVD_204")
	)
	(segment
		(start 239.880648 -56.67629)
		(end 239.91189 -56.67629)
		(width 0.089408)
		(layer "In9.Cu")
		(net "TP_CPU0_RSVD_204")
	)
	(segment
		(start 215.057736 -52.362862)
		(end 215.37549 -52.680616)
		(width 0.089408)
		(layer "In9.Cu")
		(net "TP_CPU0_RSVD_204")
	)
	(segment
		(start 239.025684 -56.181244)
		(end 239.05845 -56.181244)
		(width 0.089408)
		(layer "In9.Cu")
		(net "TP_CPU0_RSVD_204")
	)
	(segment
		(start 238.163608 -55.68569)
		(end 238.19485 -55.68569)
		(width 0.089408)
		(layer "In9.Cu")
		(net "TP_CPU0_RSVD_204")
	)
	(segment
		(start 250.182634 -62.61989)
		(end 250.213876 -62.61989)
		(width 0.089408)
		(layer "In9.Cu")
		(net "TP_CPU0_RSVD_204")
	)
	(segment
		(start 215.37549 -52.680616)
		(end 232.958132 -52.680616)
		(width 0.089408)
		(layer "In9.Cu")
		(net "TP_CPU0_RSVD_204")
	)
	(segment
		(start 206.971646 -52.070254)
		(end 207.264254 -52.362862)
		(width 0.089408)
		(layer "In9.Cu")
		(net "TP_CPU0_RSVD_204")
	)
	(segment
		(start 253.640844 -64.663066)
		(end 253.640844 -65.000886)
		(width 0.089408)
		(layer "In9.Cu")
		(net "TP_CPU0_RSVD_204")
	)
	(segment
		(start 240.742724 -57.171844)
		(end 240.77549 -57.171844)
		(width 0.089408)
		(layer "In9.Cu")
		(net "TP_CPU0_RSVD_204")
	)
	(segment
		(start 247.61063 -61.134244)
		(end 247.643396 -61.134244)
		(width 0.089408)
		(layer "In9.Cu")
		(net "TP_CPU0_RSVD_204")
	)
	(segment
		(start 237.308644 -55.190644)
		(end 237.34141 -55.190644)
		(width 0.089408)
		(layer "In9.Cu")
		(net "TP_CPU0_RSVD_204")
	)
	(segment
		(start 207.264254 -52.362862)
		(end 215.057736 -52.362862)
		(width 0.089408)
		(layer "In9.Cu")
		(net "TP_CPU0_RSVD_204")
	)
	(segment
		(start 248.465594 -61.62929)
		(end 248.496836 -61.62929)
		(width 0.089408)
		(layer "In9.Cu")
		(net "TP_CPU0_RSVD_204")
	)
	(segment
		(start 249.32767 -62.124844)
		(end 249.360436 -62.124844)
		(width 0.089408)
		(layer "In9.Cu")
		(net "TP_CPU0_RSVD_204")
	)
	(arc
		(start 253.12878 -64.305942)
		(mid 253.317458 -64.505304)
		(end 253.57582 -64.598042)
		(width 0.089408)
		(layer "In9.Cu")
		(net "TP_CPU0_RSVD_204")
	)
	(arc
		(start 246.26062 -60.343542)
		(mid 246.466657 -60.55382)
		(end 246.748554 -60.63869)
		(width 0.089408)
		(layer "In9.Cu")
		(net "TP_CPU0_RSVD_204")
	)
	(arc
		(start 252.794516 -64.106044)
		(mid 252.987619 -64.162563)
		(end 253.12878 -64.305942)
		(width 0.089408)
		(layer "In9.Cu")
		(net "TP_CPU0_RSVD_204")
	)
	(arc
		(start 237.675674 -55.390542)
		(mid 237.881711 -55.60082)
		(end 238.163608 -55.68569)
		(width 0.089408)
		(layer "In9.Cu")
		(net "TP_CPU0_RSVD_204")
	)
	(arc
		(start 239.392714 -56.381142)
		(mid 239.598751 -56.59142)
		(end 239.880648 -56.67629)
		(width 0.089408)
		(layer "In9.Cu")
		(net "TP_CPU0_RSVD_204")
	)
	(arc
		(start 244.54358 -59.352942)
		(mid 244.749617 -59.56322)
		(end 245.031514 -59.64809)
		(width 0.089408)
		(layer "In9.Cu")
		(net "TP_CPU0_RSVD_204")
	)
	(arc
		(start 234.76077 -53.70449)
		(mid 234.956802 -53.759874)
		(end 235.100114 -53.904642)
		(width 0.089408)
		(layer "In9.Cu")
		(net "TP_CPU0_RSVD_204")
	)
	(arc
		(start 249.360436 -62.124844)
		(mid 249.553539 -62.181363)
		(end 249.6947 -62.324742)
		(width 0.089408)
		(layer "In9.Cu")
		(net "TP_CPU0_RSVD_204")
	)
	(arc
		(start 249.6947 -62.324742)
		(mid 249.900737 -62.53502)
		(end 250.182634 -62.61989)
		(width 0.089408)
		(layer "In9.Cu")
		(net "TP_CPU0_RSVD_204")
	)
	(arc
		(start 250.213876 -62.61989)
		(mid 250.409908 -62.675274)
		(end 250.55322 -62.820042)
		(width 0.089408)
		(layer "In9.Cu")
		(net "TP_CPU0_RSVD_204")
	)
	(arc
		(start 238.534194 -55.885842)
		(mid 238.741723 -56.097126)
		(end 239.025684 -56.181244)
		(width 0.089408)
		(layer "In9.Cu")
		(net "TP_CPU0_RSVD_204")
	)
	(arc
		(start 239.91189 -56.67629)
		(mid 240.107922 -56.731674)
		(end 240.251234 -56.876442)
		(width 0.089408)
		(layer "In9.Cu")
		(net "TP_CPU0_RSVD_204")
	)
	(arc
		(start 234.241594 -53.409342)
		(mid 234.447631 -53.61962)
		(end 234.729528 -53.70449)
		(width 0.089408)
		(layer "In9.Cu")
		(net "TP_CPU0_RSVD_204")
	)
	(arc
		(start 251.077476 -63.115444)
		(mid 251.270579 -63.171963)
		(end 251.41174 -63.315342)
		(width 0.089408)
		(layer "In9.Cu")
		(net "TP_CPU0_RSVD_204")
	)
	(arc
		(start 235.958634 -54.399942)
		(mid 236.164671 -54.61022)
		(end 236.446568 -54.69509)
		(width 0.089408)
		(layer "In9.Cu")
		(net "TP_CPU0_RSVD_204")
	)
	(arc
		(start 250.55322 -62.820042)
		(mid 250.760749 -63.031326)
		(end 251.04471 -63.115444)
		(width 0.089408)
		(layer "In9.Cu")
		(net "TP_CPU0_RSVD_204")
	)
	(arc
		(start 235.62437 -54.200044)
		(mid 235.817473 -54.256563)
		(end 235.958634 -54.399942)
		(width 0.089408)
		(layer "In9.Cu")
		(net "TP_CPU0_RSVD_204")
	)
	(arc
		(start 236.47781 -54.69509)
		(mid 236.673842 -54.750474)
		(end 236.817154 -54.895242)
		(width 0.089408)
		(layer "In9.Cu")
		(net "TP_CPU0_RSVD_204")
	)
	(arc
		(start 236.817154 -54.895242)
		(mid 237.024683 -55.106526)
		(end 237.308644 -55.190644)
		(width 0.089408)
		(layer "In9.Cu")
		(net "TP_CPU0_RSVD_204")
	)
	(arc
		(start 241.109754 -57.371742)
		(mid 241.319059 -57.583982)
		(end 241.605308 -57.667144)
		(width 0.089408)
		(layer "In9.Cu")
		(net "TP_CPU0_RSVD_204")
	)
	(arc
		(start 242.489228 -58.162444)
		(mid 242.684084 -58.218183)
		(end 242.82654 -58.362342)
		(width 0.089408)
		(layer "In9.Cu")
		(net "TP_CPU0_RSVD_204")
	)
	(arc
		(start 247.643396 -61.134244)
		(mid 247.836499 -61.190763)
		(end 247.97766 -61.334142)
		(width 0.089408)
		(layer "In9.Cu")
		(net "TP_CPU0_RSVD_204")
	)
	(arc
		(start 240.251234 -56.876442)
		(mid 240.458763 -57.087726)
		(end 240.742724 -57.171844)
		(width 0.089408)
		(layer "In9.Cu")
		(net "TP_CPU0_RSVD_204")
	)
	(arc
		(start 248.83618 -61.829442)
		(mid 249.043709 -62.040726)
		(end 249.32767 -62.124844)
		(width 0.089408)
		(layer "In9.Cu")
		(net "TP_CPU0_RSVD_204")
	)
	(arc
		(start 233.383074 -52.913788)
		(mid 233.594642 -53.127477)
		(end 233.883962 -53.209444)
		(width 0.089408)
		(layer "In9.Cu")
		(net "TP_CPU0_RSVD_204")
	)
	(arc
		(start 237.34141 -55.190644)
		(mid 237.534513 -55.247163)
		(end 237.675674 -55.390542)
		(width 0.089408)
		(layer "In9.Cu")
		(net "TP_CPU0_RSVD_204")
	)
	(arc
		(start 233.90733 -53.209444)
		(mid 234.100433 -53.265963)
		(end 234.241594 -53.409342)
		(width 0.089408)
		(layer "In9.Cu")
		(net "TP_CPU0_RSVD_204")
	)
	(arc
		(start 238.19485 -55.68569)
		(mid 238.390882 -55.741074)
		(end 238.534194 -55.885842)
		(width 0.089408)
		(layer "In9.Cu")
		(net "TP_CPU0_RSVD_204")
	)
	(arc
		(start 242.82654 -58.362342)
		(mid 243.034069 -58.573626)
		(end 243.31803 -58.657744)
		(width 0.089408)
		(layer "In9.Cu")
		(net "TP_CPU0_RSVD_204")
	)
	(arc
		(start 245.062756 -59.64809)
		(mid 245.258788 -59.703474)
		(end 245.4021 -59.848242)
		(width 0.089408)
		(layer "In9.Cu")
		(net "TP_CPU0_RSVD_204")
	)
	(arc
		(start 232.958132 -52.680616)
		(mid 233.153749 -52.71979)
		(end 233.319574 -52.83073)
		(width 0.089408)
		(layer "In9.Cu")
		(net "TP_CPU0_RSVD_204")
	)
	(arc
		(start 247.97766 -61.334142)
		(mid 248.183697 -61.54442)
		(end 248.465594 -61.62929)
		(width 0.089408)
		(layer "In9.Cu")
		(net "TP_CPU0_RSVD_204")
	)
	(arc
		(start 240.77549 -57.171844)
		(mid 240.968593 -57.228363)
		(end 241.109754 -57.371742)
		(width 0.089408)
		(layer "In9.Cu")
		(net "TP_CPU0_RSVD_204")
	)
	(arc
		(start 248.496836 -61.62929)
		(mid 248.692868 -61.684674)
		(end 248.83618 -61.829442)
		(width 0.089408)
		(layer "In9.Cu")
		(net "TP_CPU0_RSVD_204")
	)
	(arc
		(start 233.319574 -52.83073)
		(mid 233.354042 -52.87018)
		(end 233.383074 -52.913788)
		(width 0.089408)
		(layer "In9.Cu")
		(net "TP_CPU0_RSVD_204")
	)
	(arc
		(start 243.3574 -58.657744)
		(mid 243.546729 -58.715715)
		(end 243.68506 -58.857388)
		(width 0.089408)
		(layer "In9.Cu")
		(net "TP_CPU0_RSVD_204")
	)
	(arc
		(start 243.68506 -58.857388)
		(mid 243.896628 -59.071077)
		(end 244.185948 -59.153044)
		(width 0.089408)
		(layer "In9.Cu")
		(net "TP_CPU0_RSVD_204")
	)
	(arc
		(start 239.05845 -56.181244)
		(mid 239.251553 -56.237763)
		(end 239.392714 -56.381142)
		(width 0.089408)
		(layer "In9.Cu")
		(net "TP_CPU0_RSVD_204")
	)
	(arc
		(start 241.968274 -57.867042)
		(mid 242.175803 -58.078326)
		(end 242.459764 -58.162444)
		(width 0.089408)
		(layer "In9.Cu")
		(net "TP_CPU0_RSVD_204")
	)
	(arc
		(start 245.926356 -60.143644)
		(mid 246.119459 -60.200163)
		(end 246.26062 -60.343542)
		(width 0.089408)
		(layer "In9.Cu")
		(net "TP_CPU0_RSVD_204")
	)
	(arc
		(start 241.63401 -57.667144)
		(mid 241.827113 -57.723663)
		(end 241.968274 -57.867042)
		(width 0.089408)
		(layer "In9.Cu")
		(net "TP_CPU0_RSVD_204")
	)
	(arc
		(start 246.779796 -60.63869)
		(mid 246.975828 -60.694074)
		(end 247.11914 -60.838842)
		(width 0.089408)
		(layer "In9.Cu")
		(net "TP_CPU0_RSVD_204")
	)
	(arc
		(start 235.100114 -53.904642)
		(mid 235.307643 -54.115926)
		(end 235.591604 -54.200044)
		(width 0.089408)
		(layer "In9.Cu")
		(net "TP_CPU0_RSVD_204")
	)
	(arc
		(start 251.930916 -63.61049)
		(mid 252.126948 -63.665874)
		(end 252.27026 -63.810642)
		(width 0.089408)
		(layer "In9.Cu")
		(net "TP_CPU0_RSVD_204")
	)
	(arc
		(start 244.209316 -59.153044)
		(mid 244.402419 -59.209563)
		(end 244.54358 -59.352942)
		(width 0.089408)
		(layer "In9.Cu")
		(net "TP_CPU0_RSVD_204")
	)
	(arc
		(start 247.11914 -60.838842)
		(mid 247.326669 -61.050126)
		(end 247.61063 -61.134244)
		(width 0.089408)
		(layer "In9.Cu")
		(net "TP_CPU0_RSVD_204")
	)
	(arc
		(start 245.4021 -59.848242)
		(mid 245.609629 -60.059526)
		(end 245.89359 -60.143644)
		(width 0.089408)
		(layer "In9.Cu")
		(net "TP_CPU0_RSVD_204")
	)
	(arc
		(start 252.27026 -63.810642)
		(mid 252.477789 -64.021926)
		(end 252.76175 -64.106044)
		(width 0.089408)
		(layer "In9.Cu")
		(net "TP_CPU0_RSVD_204")
	)
	(arc
		(start 251.41174 -63.315342)
		(mid 251.617777 -63.52562)
		(end 251.899674 -63.61049)
		(width 0.089408)
		(layer "In9.Cu")
		(net "TP_CPU0_RSVD_204")
	)
	(segment
		(start 255.92913 -65.000886)
		(end 255.35763 -65.000886)
		(width 0.10795)
		(layer "F.Cu")
		(net "TP_CPU0_RSVD_205")
	)
	(via
		(at 255.35763 -65.000886)
		(size 0.508)
		(drill 0.254)
		(layers "F.Cu" "B.Cu")
		(net "TP_CPU0_RSVD_205")
	)
	(segment
		(start 253.353824 -64.50584)
		(end 252.782324 -64.50584)
		(width 0.10795)
		(layer "F.Cu")
		(net "TP_CPU0_RSVD_210")
	)
	(via
		(at 252.782324 -64.50584)
		(size 0.508)
		(drill 0.254)
		(layers "F.Cu" "B.Cu")
		(net "TP_CPU0_RSVD_210")
	)
	(segment
		(start 255.07061 -64.50584)
		(end 254.49911 -64.50584)
		(width 0.10795)
		(layer "F.Cu")
		(net "TP_CPU0_RSVD_211")
	)
	(via
		(at 254.49911 -64.50584)
		(size 0.508)
		(drill 0.254)
		(layers "F.Cu" "B.Cu")
		(net "TP_CPU0_RSVD_211")
	)
	(segment
		(start 256.78765 -64.50584)
		(end 256.21615 -64.50584)
		(width 0.10795)
		(layer "F.Cu")
		(net "TP_CPU0_RSVD_212")
	)
	(via
		(at 256.21615 -64.50584)
		(size 0.508)
		(drill 0.254)
		(layers "F.Cu" "B.Cu")
		(net "TP_CPU0_RSVD_212")
	)
	(segment
		(start 247.344184 -64.010286)
		(end 246.772684 -64.010286)
		(width 0.10795)
		(layer "F.Cu")
		(net "TP_CPU0_RSVD_216")
	)
	(via
		(at 246.772684 -64.010286)
		(size 0.508)
		(drill 0.254)
		(layers "F.Cu" "B.Cu")
		(net "TP_CPU0_RSVD_216")
	)
	(segment
		(start 208.01584 -49.897792)
		(end 208.01584 -51.36642)
		(width 0.10795)
		(layer "F.Cu")
		(net "TP_CPU0_RSVD_217")
	)
	(segment
		(start 254.212344 -64.010286)
		(end 253.640844 -64.010286)
		(width 0.10795)
		(layer "F.Cu")
		(net "TP_CPU0_RSVD_217")
	)
	(segment
		(start 209.094324 -48.819308)
		(end 208.01584 -49.897792)
		(width 0.10795)
		(layer "F.Cu")
		(net "TP_CPU0_RSVD_217")
	)
	(via
		(at 208.01584 -51.36642)
		(size 0.762)
		(drill 0.3048)
		(layers "F.Cu" "B.Cu")
		(net "TP_CPU0_RSVD_217")
	)
	(via
		(at 253.640844 -64.010286)
		(size 0.508)
		(drill 0.254)
		(layers "F.Cu" "B.Cu")
		(net "TP_CPU0_RSVD_217")
	)
	(via
		(at 209.094324 -48.819308)
		(size 0.762)
		(drill 0.381)
		(layers "F.Cu" "B.Cu")
		(net "TP_CPU0_RSVD_217")
	)
	(segment
		(start 246.760492 -60.447682)
		(end 246.793258 -60.447682)
		(width 0.089408)
		(layer "In9.Cu")
		(net "TP_CPU0_RSVD_217")
	)
	(segment
		(start 238.175546 -55.494682)
		(end 238.208312 -55.494682)
		(width 0.089408)
		(layer "In9.Cu")
		(net "TP_CPU0_RSVD_217")
	)
	(segment
		(start 244.184932 -58.961782)
		(end 244.213634 -58.961782)
		(width 0.089408)
		(layer "In9.Cu")
		(net "TP_CPU0_RSVD_217")
	)
	(segment
		(start 214.09533 -51.065176)
		(end 215.473788 -52.443634)
		(width 0.089408)
		(layer "In9.Cu")
		(net "TP_CPU0_RSVD_217")
	)
	(segment
		(start 215.473788 -52.443634)
		(end 232.846372 -52.443634)
		(width 0.089408)
		(layer "In9.Cu")
		(net "TP_CPU0_RSVD_217")
	)
	(segment
		(start 236.458506 -54.504082)
		(end 236.491272 -54.504082)
		(width 0.089408)
		(layer "In9.Cu")
		(net "TP_CPU0_RSVD_217")
	)
	(segment
		(start 245.043452 -59.457082)
		(end 245.076218 -59.457082)
		(width 0.089408)
		(layer "In9.Cu")
		(net "TP_CPU0_RSVD_217")
	)
	(segment
		(start 240.756186 -56.980836)
		(end 240.787428 -56.980836)
		(width 0.089408)
		(layer "In9.Cu")
		(net "TP_CPU0_RSVD_217")
	)
	(segment
		(start 249.341132 -61.933836)
		(end 249.372374 -61.933836)
		(width 0.089408)
		(layer "In9.Cu")
		(net "TP_CPU0_RSVD_217")
	)
	(segment
		(start 235.605066 -54.009036)
		(end 235.636308 -54.009036)
		(width 0.089408)
		(layer "In9.Cu")
		(net "TP_CPU0_RSVD_217")
	)
	(segment
		(start 239.892586 -56.485282)
		(end 239.925352 -56.485282)
		(width 0.089408)
		(layer "In9.Cu")
		(net "TP_CPU0_RSVD_217")
	)
	(segment
		(start 233.882946 -53.018182)
		(end 233.911648 -53.018182)
		(width 0.089408)
		(layer "In9.Cu")
		(net "TP_CPU0_RSVD_217")
	)
	(segment
		(start 251.911612 -63.419482)
		(end 251.944378 -63.419482)
		(width 0.089408)
		(layer "In9.Cu")
		(net "TP_CPU0_RSVD_217")
	)
	(segment
		(start 252.775212 -63.915036)
		(end 252.806454 -63.915036)
		(width 0.089408)
		(layer "In9.Cu")
		(net "TP_CPU0_RSVD_217")
	)
	(segment
		(start 234.741466 -53.513482)
		(end 234.774232 -53.513482)
		(width 0.089408)
		(layer "In9.Cu")
		(net "TP_CPU0_RSVD_217")
	)
	(segment
		(start 243.329714 -58.466482)
		(end 243.359178 -58.466482)
		(width 0.089408)
		(layer "In9.Cu")
		(net "TP_CPU0_RSVD_217")
	)
	(segment
		(start 253.582932 -64.406018)
		(end 253.640844 -64.348106)
		(width 0.089408)
		(layer "In9.Cu")
		(net "TP_CPU0_RSVD_217")
	)
	(segment
		(start 208.317084 -51.065176)
		(end 214.09533 -51.065176)
		(width 0.089408)
		(layer "In9.Cu")
		(net "TP_CPU0_RSVD_217")
	)
	(segment
		(start 237.322106 -54.999636)
		(end 237.353348 -54.999636)
		(width 0.089408)
		(layer "In9.Cu")
		(net "TP_CPU0_RSVD_217")
	)
	(segment
		(start 242.461542 -57.971182)
		(end 242.500912 -57.971182)
		(width 0.089408)
		(layer "In9.Cu")
		(net "TP_CPU0_RSVD_217")
	)
	(segment
		(start 248.477532 -61.438282)
		(end 248.510298 -61.438282)
		(width 0.089408)
		(layer "In9.Cu")
		(net "TP_CPU0_RSVD_217")
	)
	(segment
		(start 245.907052 -59.952636)
		(end 245.938294 -59.952636)
		(width 0.089408)
		(layer "In9.Cu")
		(net "TP_CPU0_RSVD_217")
	)
	(segment
		(start 253.640844 -64.348106)
		(end 253.640844 -64.010286)
		(width 0.089408)
		(layer "In9.Cu")
		(net "TP_CPU0_RSVD_217")
	)
	(segment
		(start 250.194572 -62.428882)
		(end 250.227338 -62.428882)
		(width 0.089408)
		(layer "In9.Cu")
		(net "TP_CPU0_RSVD_217")
	)
	(segment
		(start 251.058172 -62.924436)
		(end 251.089414 -62.924436)
		(width 0.089408)
		(layer "In9.Cu")
		(net "TP_CPU0_RSVD_217")
	)
	(segment
		(start 239.039146 -55.990236)
		(end 239.070388 -55.990236)
		(width 0.089408)
		(layer "In9.Cu")
		(net "TP_CPU0_RSVD_217")
	)
	(segment
		(start 247.624092 -60.943236)
		(end 247.655334 -60.943236)
		(width 0.089408)
		(layer "In9.Cu")
		(net "TP_CPU0_RSVD_217")
	)
	(segment
		(start 208.01584 -51.36642)
		(end 208.317084 -51.065176)
		(width 0.089408)
		(layer "In9.Cu")
		(net "TP_CPU0_RSVD_217")
	)
	(segment
		(start 241.609626 -57.475882)
		(end 241.632994 -57.475882)
		(width 0.089408)
		(layer "In9.Cu")
		(net "TP_CPU0_RSVD_217")
	)
	(arc
		(start 239.558322 -56.285384)
		(mid 239.699479 -56.428769)
		(end 239.892586 -56.485282)
		(width 0.089408)
		(layer "In9.Cu")
		(net "TP_CPU0_RSVD_217")
	)
	(arc
		(start 235.265722 -53.808884)
		(mid 235.409033 -53.953655)
		(end 235.605066 -54.009036)
		(width 0.089408)
		(layer "In9.Cu")
		(net "TP_CPU0_RSVD_217")
	)
	(arc
		(start 245.938294 -59.952636)
		(mid 246.220196 -60.037499)
		(end 246.426228 -60.247784)
		(width 0.089408)
		(layer "In9.Cu")
		(net "TP_CPU0_RSVD_217")
	)
	(arc
		(start 238.208312 -55.494682)
		(mid 238.492273 -55.5788)
		(end 238.699802 -55.790084)
		(width 0.089408)
		(layer "In9.Cu")
		(net "TP_CPU0_RSVD_217")
	)
	(arc
		(start 240.787428 -56.980836)
		(mid 241.06933 -57.065699)
		(end 241.275362 -57.275984)
		(width 0.089408)
		(layer "In9.Cu")
		(net "TP_CPU0_RSVD_217")
	)
	(arc
		(start 234.774232 -53.513482)
		(mid 235.058193 -53.5976)
		(end 235.265722 -53.808884)
		(width 0.089408)
		(layer "In9.Cu")
		(net "TP_CPU0_RSVD_217")
	)
	(arc
		(start 250.227338 -62.428882)
		(mid 250.511299 -62.513)
		(end 250.718828 -62.724284)
		(width 0.089408)
		(layer "In9.Cu")
		(net "TP_CPU0_RSVD_217")
	)
	(arc
		(start 249.372374 -61.933836)
		(mid 249.654276 -62.018699)
		(end 249.860308 -62.228984)
		(width 0.089408)
		(layer "In9.Cu")
		(net "TP_CPU0_RSVD_217")
	)
	(arc
		(start 248.143268 -61.238384)
		(mid 248.284425 -61.381769)
		(end 248.477532 -61.438282)
		(width 0.089408)
		(layer "In9.Cu")
		(net "TP_CPU0_RSVD_217")
	)
	(arc
		(start 237.841282 -55.294784)
		(mid 237.982439 -55.438169)
		(end 238.175546 -55.494682)
		(width 0.089408)
		(layer "In9.Cu")
		(net "TP_CPU0_RSVD_217")
	)
	(arc
		(start 247.655334 -60.943236)
		(mid 247.937236 -61.028099)
		(end 248.143268 -61.238384)
		(width 0.089408)
		(layer "In9.Cu")
		(net "TP_CPU0_RSVD_217")
	)
	(arc
		(start 243.359178 -58.466482)
		(mid 243.643139 -58.5506)
		(end 243.850668 -58.761884)
		(width 0.089408)
		(layer "In9.Cu")
		(net "TP_CPU0_RSVD_217")
	)
	(arc
		(start 242.133882 -57.771538)
		(mid 242.27221 -57.913215)
		(end 242.461542 -57.971182)
		(width 0.089408)
		(layer "In9.Cu")
		(net "TP_CPU0_RSVD_217")
	)
	(arc
		(start 243.850668 -58.761884)
		(mid 243.991825 -58.905269)
		(end 244.184932 -58.961782)
		(width 0.089408)
		(layer "In9.Cu")
		(net "TP_CPU0_RSVD_217")
	)
	(arc
		(start 251.577348 -63.219584)
		(mid 251.718505 -63.362969)
		(end 251.911612 -63.419482)
		(width 0.089408)
		(layer "In9.Cu")
		(net "TP_CPU0_RSVD_217")
	)
	(arc
		(start 237.353348 -54.999636)
		(mid 237.63525 -55.084499)
		(end 237.841282 -55.294784)
		(width 0.089408)
		(layer "In9.Cu")
		(net "TP_CPU0_RSVD_217")
	)
	(arc
		(start 245.076218 -59.457082)
		(mid 245.360179 -59.5412)
		(end 245.567708 -59.752484)
		(width 0.089408)
		(layer "In9.Cu")
		(net "TP_CPU0_RSVD_217")
	)
	(arc
		(start 234.407202 -53.313584)
		(mid 234.548359 -53.456969)
		(end 234.741466 -53.513482)
		(width 0.089408)
		(layer "In9.Cu")
		(net "TP_CPU0_RSVD_217")
	)
	(arc
		(start 238.699802 -55.790084)
		(mid 238.843113 -55.934855)
		(end 239.039146 -55.990236)
		(width 0.089408)
		(layer "In9.Cu")
		(net "TP_CPU0_RSVD_217")
	)
	(arc
		(start 236.124242 -54.304184)
		(mid 236.265399 -54.447569)
		(end 236.458506 -54.504082)
		(width 0.089408)
		(layer "In9.Cu")
		(net "TP_CPU0_RSVD_217")
	)
	(arc
		(start 249.860308 -62.228984)
		(mid 250.001465 -62.372369)
		(end 250.194572 -62.428882)
		(width 0.089408)
		(layer "In9.Cu")
		(net "TP_CPU0_RSVD_217")
	)
	(arc
		(start 239.925352 -56.485282)
		(mid 240.209313 -56.5694)
		(end 240.416842 -56.780684)
		(width 0.089408)
		(layer "In9.Cu")
		(net "TP_CPU0_RSVD_217")
	)
	(arc
		(start 239.070388 -55.990236)
		(mid 239.35229 -56.075099)
		(end 239.558322 -56.285384)
		(width 0.089408)
		(layer "In9.Cu")
		(net "TP_CPU0_RSVD_217")
	)
	(arc
		(start 242.500912 -57.971182)
		(mid 242.784873 -58.0553)
		(end 242.992402 -58.266584)
		(width 0.089408)
		(layer "In9.Cu")
		(net "TP_CPU0_RSVD_217")
	)
	(arc
		(start 242.992402 -58.266584)
		(mid 243.134858 -58.410744)
		(end 243.329714 -58.466482)
		(width 0.089408)
		(layer "In9.Cu")
		(net "TP_CPU0_RSVD_217")
	)
	(arc
		(start 244.213634 -58.961782)
		(mid 244.499883 -59.044943)
		(end 244.709188 -59.257184)
		(width 0.089408)
		(layer "In9.Cu")
		(net "TP_CPU0_RSVD_217")
	)
	(arc
		(start 248.510298 -61.438282)
		(mid 248.794259 -61.5224)
		(end 249.001788 -61.733684)
		(width 0.089408)
		(layer "In9.Cu")
		(net "TP_CPU0_RSVD_217")
	)
	(arc
		(start 241.632994 -57.475882)
		(mid 241.922315 -57.557847)
		(end 242.133882 -57.771538)
		(width 0.089408)
		(layer "In9.Cu")
		(net "TP_CPU0_RSVD_217")
	)
	(arc
		(start 244.709188 -59.257184)
		(mid 244.850345 -59.400569)
		(end 245.043452 -59.457082)
		(width 0.089408)
		(layer "In9.Cu")
		(net "TP_CPU0_RSVD_217")
	)
	(arc
		(start 240.416842 -56.780684)
		(mid 240.560153 -56.925455)
		(end 240.756186 -56.980836)
		(width 0.089408)
		(layer "In9.Cu")
		(net "TP_CPU0_RSVD_217")
	)
	(arc
		(start 233.454702 -52.695602)
		(mid 233.50572 -52.753858)
		(end 233.548682 -52.818284)
		(width 0.089408)
		(layer "In9.Cu")
		(net "TP_CPU0_RSVD_217")
	)
	(arc
		(start 249.001788 -61.733684)
		(mid 249.145099 -61.878455)
		(end 249.341132 -61.933836)
		(width 0.089408)
		(layer "In9.Cu")
		(net "TP_CPU0_RSVD_217")
	)
	(arc
		(start 251.944378 -63.419482)
		(mid 252.228339 -63.5036)
		(end 252.435868 -63.714884)
		(width 0.089408)
		(layer "In9.Cu")
		(net "TP_CPU0_RSVD_217")
	)
	(arc
		(start 235.636308 -54.009036)
		(mid 235.91821 -54.093899)
		(end 236.124242 -54.304184)
		(width 0.089408)
		(layer "In9.Cu")
		(net "TP_CPU0_RSVD_217")
	)
	(arc
		(start 245.567708 -59.752484)
		(mid 245.711019 -59.897255)
		(end 245.907052 -59.952636)
		(width 0.089408)
		(layer "In9.Cu")
		(net "TP_CPU0_RSVD_217")
	)
	(arc
		(start 241.275362 -57.275984)
		(mid 241.416519 -57.419369)
		(end 241.609626 -57.475882)
		(width 0.089408)
		(layer "In9.Cu")
		(net "TP_CPU0_RSVD_217")
	)
	(arc
		(start 252.435868 -63.714884)
		(mid 252.579179 -63.859655)
		(end 252.775212 -63.915036)
		(width 0.089408)
		(layer "In9.Cu")
		(net "TP_CPU0_RSVD_217")
	)
	(arc
		(start 247.284748 -60.743084)
		(mid 247.428059 -60.887855)
		(end 247.624092 -60.943236)
		(width 0.089408)
		(layer "In9.Cu")
		(net "TP_CPU0_RSVD_217")
	)
	(arc
		(start 246.426228 -60.247784)
		(mid 246.567385 -60.391169)
		(end 246.760492 -60.447682)
		(width 0.089408)
		(layer "In9.Cu")
		(net "TP_CPU0_RSVD_217")
	)
	(arc
		(start 232.846372 -52.443634)
		(mid 233.175594 -52.50912)
		(end 233.454702 -52.695602)
		(width 0.089408)
		(layer "In9.Cu")
		(net "TP_CPU0_RSVD_217")
	)
	(arc
		(start 233.911648 -53.018182)
		(mid 234.197897 -53.101343)
		(end 234.407202 -53.313584)
		(width 0.089408)
		(layer "In9.Cu")
		(net "TP_CPU0_RSVD_217")
	)
	(arc
		(start 251.089414 -62.924436)
		(mid 251.371316 -63.009299)
		(end 251.577348 -63.219584)
		(width 0.089408)
		(layer "In9.Cu")
		(net "TP_CPU0_RSVD_217")
	)
	(arc
		(start 233.548682 -52.818284)
		(mid 233.689839 -52.961669)
		(end 233.882946 -53.018182)
		(width 0.089408)
		(layer "In9.Cu")
		(net "TP_CPU0_RSVD_217")
	)
	(arc
		(start 250.718828 -62.724284)
		(mid 250.862139 -62.869055)
		(end 251.058172 -62.924436)
		(width 0.089408)
		(layer "In9.Cu")
		(net "TP_CPU0_RSVD_217")
	)
	(arc
		(start 236.982762 -54.799484)
		(mid 237.126073 -54.944255)
		(end 237.322106 -54.999636)
		(width 0.089408)
		(layer "In9.Cu")
		(net "TP_CPU0_RSVD_217")
	)
	(arc
		(start 246.793258 -60.447682)
		(mid 247.077219 -60.5318)
		(end 247.284748 -60.743084)
		(width 0.089408)
		(layer "In9.Cu")
		(net "TP_CPU0_RSVD_217")
	)
	(arc
		(start 252.806454 -63.915036)
		(mid 253.088356 -63.999899)
		(end 253.294388 -64.210184)
		(width 0.089408)
		(layer "In9.Cu")
		(net "TP_CPU0_RSVD_217")
	)
	(arc
		(start 236.491272 -54.504082)
		(mid 236.775233 -54.5882)
		(end 236.982762 -54.799484)
		(width 0.089408)
		(layer "In9.Cu")
		(net "TP_CPU0_RSVD_217")
	)
	(arc
		(start 253.294388 -64.210184)
		(mid 253.416186 -64.341223)
		(end 253.582932 -64.406018)
		(width 0.089408)
		(layer "In9.Cu")
		(net "TP_CPU0_RSVD_217")
	)
	(segment
		(start 255.92913 -64.010286)
		(end 255.35763 -64.010286)
		(width 0.10795)
		(layer "F.Cu")
		(net "TP_CPU0_RSVD_218")
	)
	(via
		(at 255.35763 -64.010286)
		(size 0.508)
		(drill 0.254)
		(layers "F.Cu" "B.Cu")
		(net "TP_CPU0_RSVD_218")
	)
	(segment
		(start 246.485664 -63.51524)
		(end 245.914164 -63.51524)
		(width 0.10795)
		(layer "F.Cu")
		(net "TP_CPU0_RSVD_222")
	)
	(via
		(at 245.914164 -63.51524)
		(size 0.508)
		(drill 0.254)
		(layers "F.Cu" "B.Cu")
		(net "TP_CPU0_RSVD_222")
	)
	(segment
		(start 253.353824 -63.51524)
		(end 252.782324 -63.51524)
		(width 0.10795)
		(layer "F.Cu")
		(net "TP_CPU0_RSVD_223")
	)
	(via
		(at 252.782324 -63.51524)
		(size 0.508)
		(drill 0.254)
		(layers "F.Cu" "B.Cu")
		(net "TP_CPU0_RSVD_223")
	)
	(segment
		(start 255.07061 -63.51524)
		(end 254.49911 -63.51524)
		(width 0.10795)
		(layer "F.Cu")
		(net "TP_CPU0_RSVD_224")
	)
	(via
		(at 254.49911 -63.51524)
		(size 0.508)
		(drill 0.254)
		(layers "F.Cu" "B.Cu")
		(net "TP_CPU0_RSVD_224")
	)
	(segment
		(start 256.78765 -63.51524)
		(end 256.21615 -63.51524)
		(width 0.10795)
		(layer "F.Cu")
		(net "TP_CPU0_RSVD_225")
	)
	(via
		(at 256.21615 -63.51524)
		(size 0.508)
		(drill 0.254)
		(layers "F.Cu" "B.Cu")
		(net "TP_CPU0_RSVD_225")
	)
	(segment
		(start 243.910104 -63.019686)
		(end 243.338604 -63.019686)
		(width 0.10795)
		(layer "F.Cu")
		(net "TP_CPU0_RSVD_228")
	)
	(via
		(at 243.338604 -63.019686)
		(size 0.508)
		(drill 0.254)
		(layers "F.Cu" "B.Cu")
		(net "TP_CPU0_RSVD_228")
	)
	(segment
		(start 245.627144 -63.019686)
		(end 245.055644 -63.019686)
		(width 0.10795)
		(layer "F.Cu")
		(net "TP_CPU0_RSVD_229")
	)
	(via
		(at 245.055644 -63.019686)
		(size 0.508)
		(drill 0.254)
		(layers "F.Cu" "B.Cu")
		(net "TP_CPU0_RSVD_229")
	)
	(segment
		(start 257.64617 -63.019686)
		(end 257.07467 -63.019686)
		(width 0.10795)
		(layer "F.Cu")
		(net "TP_CPU0_RSVD_230")
	)
	(via
		(at 257.07467 -63.019686)
		(size 0.508)
		(drill 0.254)
		(layers "F.Cu" "B.Cu")
		(net "TP_CPU0_RSVD_230")
	)
	(segment
		(start 244.768624 -62.52464)
		(end 244.197124 -62.52464)
		(width 0.10795)
		(layer "F.Cu")
		(net "TP_CPU0_RSVD_234")
	)
	(via
		(at 244.197124 -62.52464)
		(size 0.508)
		(drill 0.254)
		(layers "F.Cu" "B.Cu")
		(net "TP_CPU0_RSVD_234")
	)
	(segment
		(start 245.627144 -62.029086)
		(end 245.055644 -62.029086)
		(width 0.10795)
		(layer "F.Cu")
		(net "TP_CPU0_RSVD_241")
	)
	(via
		(at 245.055644 -62.029086)
		(size 0.508)
		(drill 0.254)
		(layers "F.Cu" "B.Cu")
		(net "TP_CPU0_RSVD_241")
	)
	(segment
		(start 244.768624 -61.53404)
		(end 244.197124 -61.53404)
		(width 0.10795)
		(layer "F.Cu")
		(net "TP_CPU0_RSVD_247")
	)
	(via
		(at 244.197124 -61.53404)
		(size 0.508)
		(drill 0.254)
		(layers "F.Cu" "B.Cu")
		(net "TP_CPU0_RSVD_247")
	)
	(segment
		(start 267.089636 -61.53404)
		(end 266.518136 -61.53404)
		(width 0.10795)
		(layer "F.Cu")
		(net "TP_CPU0_RSVD_251")
	)
	(via
		(at 266.518136 -61.53404)
		(size 0.508)
		(drill 0.254)
		(layers "F.Cu" "B.Cu")
		(net "TP_CPU0_RSVD_251")
	)
	(segment
		(start 250.778264 -59.057286)
		(end 250.206764 -59.057286)
		(width 0.10795)
		(layer "F.Cu")
		(net "TP_CPU0_RSVD_256")
	)
	(via
		(at 250.206764 -59.057286)
		(size 0.508)
		(drill 0.254)
		(layers "F.Cu" "B.Cu")
		(net "TP_CPU0_RSVD_256")
	)
	(segment
		(start 240.476278 -50.141886)
		(end 239.904778 -50.141886)
		(width 0.10795)
		(layer "F.Cu")
		(net "TP_CPU0_RSVD_293")
	)
	(via
		(at 239.904778 -50.141886)
		(size 0.508)
		(drill 0.254)
		(layers "F.Cu" "B.Cu")
		(net "TP_CPU0_RSVD_293")
	)
	(segment
		(start 249.919744 -58.561986)
		(end 249.348244 -58.561986)
		(width 0.10795)
		(layer "F.Cu")
		(net "TP_CPU0_RSVD_258")
	)
	(via
		(at 249.348244 -58.561986)
		(size 0.508)
		(drill 0.254)
		(layers "F.Cu" "B.Cu")
		(net "TP_CPU0_RSVD_258")
	)
	(segment
		(start 249.061224 -58.06694)
		(end 248.489724 -58.06694)
		(width 0.10795)
		(layer "F.Cu")
		(net "TP_CPU0_RSVD_259")
	)
	(via
		(at 248.489724 -58.06694)
		(size 0.508)
		(drill 0.254)
		(layers "F.Cu" "B.Cu")
		(net "TP_CPU0_RSVD_259")
	)
	(segment
		(start 250.778264 -58.06694)
		(end 250.206764 -58.06694)
		(width 0.10795)
		(layer "F.Cu")
		(net "TP_CPU0_RSVD_260")
	)
	(via
		(at 250.206764 -58.06694)
		(size 0.508)
		(drill 0.254)
		(layers "F.Cu" "B.Cu")
		(net "TP_CPU0_RSVD_260")
	)
	(segment
		(start 249.919744 -57.57164)
		(end 249.348244 -57.57164)
		(width 0.10795)
		(layer "F.Cu")
		(net "TP_CPU0_RSVD_261")
	)
	(via
		(at 249.348244 -57.57164)
		(size 0.508)
		(drill 0.254)
		(layers "F.Cu" "B.Cu")
		(net "TP_CPU0_RSVD_261")
	)
	(segment
		(start 249.061224 -57.076086)
		(end 248.489724 -57.076086)
		(width 0.10795)
		(layer "F.Cu")
		(net "TP_CPU0_RSVD_262")
	)
	(via
		(at 248.489724 -57.076086)
		(size 0.508)
		(drill 0.254)
		(layers "F.Cu" "B.Cu")
		(net "TP_CPU0_RSVD_262")
	)
	(segment
		(start 249.919744 -56.58104)
		(end 249.348244 -56.58104)
		(width 0.10795)
		(layer "F.Cu")
		(net "TP_CPU0_RSVD_263")
	)
	(via
		(at 249.348244 -56.58104)
		(size 0.508)
		(drill 0.254)
		(layers "F.Cu" "B.Cu")
		(net "TP_CPU0_RSVD_263")
	)
	(segment
		(start 253.353824 -56.58104)
		(end 252.782324 -56.58104)
		(width 0.10795)
		(layer "F.Cu")
		(net "TP_CPU0_RSVD_264")
	)
	(via
		(at 252.782324 -56.58104)
		(size 0.508)
		(drill 0.254)
		(layers "F.Cu" "B.Cu")
		(net "TP_CPU0_RSVD_264")
	)
	(segment
		(start 235.325158 -51.132486)
		(end 234.753658 -51.132486)
		(width 0.10795)
		(layer "F.Cu")
		(net "TP_CPU0_RSVD_284")
	)
	(via
		(at 234.753658 -51.132486)
		(size 0.508)
		(drill 0.254)
		(layers "F.Cu" "B.Cu")
		(net "TP_CPU0_RSVD_284")
	)
	(segment
		(start 236.183678 -50.63744)
		(end 235.612178 -50.63744)
		(width 0.10795)
		(layer "F.Cu")
		(net "TP_CPU0_RSVD_288")
	)
	(via
		(at 235.612178 -50.63744)
		(size 0.508)
		(drill 0.254)
		(layers "F.Cu" "B.Cu")
		(net "TP_CPU0_RSVD_288")
	)
	(segment
		(start 250.778264 -56.085486)
		(end 250.206764 -56.085486)
		(width 0.10795)
		(layer "F.Cu")
		(net "TP_CPU0_RSVD_265")
	)
	(via
		(at 250.206764 -56.085486)
		(size 0.508)
		(drill 0.254)
		(layers "F.Cu" "B.Cu")
		(net "TP_CPU0_RSVD_265")
	)
	(segment
		(start 233.608118 -53.113686)
		(end 233.036618 -53.113686)
		(width 0.10795)
		(layer "F.Cu")
		(net "TP_CPU0_RSVD_270")
	)
	(via
		(at 231.3686 -53.797962)
		(size 0.6604)
		(drill 0.3302)
		(layers "F.Cu" "B.Cu")
		(net "TP_CPU0_RSVD_270")
	)
	(via
		(at 233.036618 -53.113686)
		(size 0.508)
		(drill 0.254)
		(layers "F.Cu" "B.Cu")
		(net "TP_CPU0_RSVD_270")
	)
	(segment
		(start 233.036618 -53.113686)
		(end 232.352342 -53.797962)
		(width 0.10795)
		(layer "B.Cu")
		(net "TP_CPU0_RSVD_270")
	)
	(segment
		(start 232.352342 -53.797962)
		(end 231.3686 -53.797962)
		(width 0.10795)
		(layer "B.Cu")
		(net "TP_CPU0_RSVD_270")
	)
	(segment
		(start 290.93922 -65.315338)
		(end 291.51072 -65.315338)
		(width 0.10795)
		(layer "F.Cu")
		(net "TP_CPU0_RSVD_227")
	)
	(via
		(at 291.51072 -65.315338)
		(size 0.508)
		(drill 0.254)
		(layers "F.Cu" "B.Cu")
		(net "TP_CPU0_RSVD_227")
	)
	(segment
		(start 290.93922 -64.324738)
		(end 291.51072 -64.324738)
		(width 0.10795)
		(layer "F.Cu")
		(net "TP_CPU0_RSVD_240")
	)
	(via
		(at 291.51072 -64.324738)
		(size 0.508)
		(drill 0.254)
		(layers "F.Cu" "B.Cu")
		(net "TP_CPU0_RSVD_240")
	)
	(segment
		(start 292.65626 -69.277738)
		(end 293.22776 -69.277738)
		(width 0.10795)
		(layer "F.Cu")
		(net "TP_CPU0_TEST_7")
	)
	(via
		(at 293.22776 -69.277738)
		(size 0.508)
		(drill 0.254)
		(layers "F.Cu" "B.Cu")
		(net "TP_CPU0_TEST_7")
	)
	(segment
		(start 294.3733 -70.268084)
		(end 294.9448 -70.268084)
		(width 0.10795)
		(layer "F.Cu")
		(net "TP_CPU0_TEST_8")
	)
	(via
		(at 294.9448 -70.268084)
		(size 0.508)
		(drill 0.254)
		(layers "F.Cu" "B.Cu")
		(net "TP_CPU0_TEST_8")
	)
	(segment
		(start 289.793426 -70.268084)
		(end 289.79368 -70.268338)
		(width 0.10795)
		(layer "F.Cu")
		(net "TP_CPU0_TEST_10")
	)
	(segment
		(start 289.22218 -70.268084)
		(end 289.793426 -70.268084)
		(width 0.10795)
		(layer "F.Cu")
		(net "TP_CPU0_TEST_10")
	)
	(via
		(at 289.79368 -70.268338)
		(size 0.508)
		(drill 0.254)
		(layers "F.Cu" "B.Cu")
		(net "TP_CPU0_TEST_10")
	)
	(segment
		(start 291.510466 -70.268084)
		(end 291.51072 -70.268338)
		(width 0.10795)
		(layer "F.Cu")
		(net "TP_CPU0_TEST_9")
	)
	(segment
		(start 290.93922 -70.268084)
		(end 291.510466 -70.268084)
		(width 0.10795)
		(layer "F.Cu")
		(net "TP_CPU0_TEST_9")
	)
	(via
		(at 291.51072 -70.268338)
		(size 0.508)
		(drill 0.254)
		(layers "F.Cu" "B.Cu")
		(net "TP_CPU0_TEST_9")
	)
	(segment
		(start 296.948606 -70.763384)
		(end 297.520106 -70.763384)
		(width 0.10795)
		(layer "F.Cu")
		(net "TP_CPU0_RSVD_TEST_11")
	)
	(via
		(at 297.520106 -70.763384)
		(size 0.508)
		(drill 0.254)
		(layers "F.Cu" "B.Cu")
		(net "TP_CPU0_RSVD_TEST_11")
	)
	(segment
		(start 252.495304 -55.094886)
		(end 251.923804 -55.094886)
		(width 0.10795)
		(layer "F.Cu")
		(net "TP_CPU0_RSVD_266")
	)
	(via
		(at 251.923804 -55.094886)
		(size 0.508)
		(drill 0.254)
		(layers "F.Cu" "B.Cu")
		(net "TP_CPU0_RSVD_266")
	)
	(segment
		(start 482.36251 4.50088)
		(end 481.887784 4.50088)
		(width 0.10033)
		(layer "F.Cu")
		(net "NIC_MDI_MNG_TX_DP")
	)
	(segment
		(start 481.887784 4.50088)
		(end 481.731574 4.65709)
		(width 0.10033)
		(layer "F.Cu")
		(net "NIC_MDI_MNG_TX_DP")
	)
	(segment
		(start 482.665024 4.803394)
		(end 482.36251 4.50088)
		(width 0.10033)
		(layer "F.Cu")
		(net "NIC_MDI_MNG_TX_DP")
	)
	(via
		(at 482.665024 4.803394)
		(size 0.508)
		(drill 0.254)
		(layers "F.Cu" "B.Cu")
		(net "NIC_MDI_MNG_TX_DP")
	)
	(segment
		(start 334.016858 -32.959548)
		(end 334.016858 -15.246858)
		(width 0.101346)
		(layer "In9.Cu")
		(net "NIC_MDI_MNG_TX_DP")
	)
	(segment
		(start 258.849368 -1.3462)
		(end 194.830954 -1.3462)
		(width 0.101346)
		(layer "In9.Cu")
		(net "NIC_MDI_MNG_TX_DP")
	)
	(segment
		(start -2.947416 -30.440122)
		(end -3.409696 -30.902402)
		(width 0.101346)
		(layer "In9.Cu")
		(net "NIC_MDI_MNG_TX_DP")
	)
	(segment
		(start 404.181056 1.27)
		(end 386.934202 1.27)
		(width 0.101346)
		(layer "In9.Cu")
		(net "NIC_MDI_MNG_TX_DP")
	)
	(segment
		(start 24.96439 -1.010158)
		(end 16.915638 -1.010158)
		(width 0.101346)
		(layer "In9.Cu")
		(net "NIC_MDI_MNG_TX_DP")
	)
	(segment
		(start -3.409696 -30.902402)
		(end -3.409696 -31.220156)
		(width 0.101346)
		(layer "In9.Cu")
		(net "NIC_MDI_MNG_TX_DP")
	)
	(segment
		(start 174.666148 -7.607046)
		(end 171.99356 -7.607046)
		(width 0.101346)
		(layer "In9.Cu")
		(net "NIC_MDI_MNG_TX_DP")
	)
	(segment
		(start 156.69641 -1.074166)
		(end 97.716086 -1.074166)
		(width 0.101346)
		(layer "In9.Cu")
		(net "NIC_MDI_MNG_TX_DP")
	)
	(segment
		(start 10.8204 -7.580884)
		(end 10.8204 -21.04771)
		(width 0.101346)
		(layer "In9.Cu")
		(net "NIC_MDI_MNG_TX_DP")
	)
	(segment
		(start 358.911652 -30.276292)
		(end 356.586028 -32.601916)
		(width 0.101346)
		(layer "In9.Cu")
		(net "NIC_MDI_MNG_TX_DP")
	)
	(segment
		(start 325.283576 -8.833358)
		(end 325.283576 -6.748018)
		(width 0.101346)
		(layer "In9.Cu")
		(net "NIC_MDI_MNG_TX_DP")
	)
	(segment
		(start 386.908802 1.2446)
		(end 386.571998 1.2446)
		(width 0.101346)
		(layer "In9.Cu")
		(net "NIC_MDI_MNG_TX_DP")
	)
	(segment
		(start 479.114866 0.327406)
		(end 476.526352 -2.261108)
		(width 0.101346)
		(layer "In9.Cu")
		(net "NIC_MDI_MNG_TX_DP")
	)
	(segment
		(start 362.53166 -18.860516)
		(end 361.513882 -19.878294)
		(width 0.101346)
		(layer "In9.Cu")
		(net "NIC_MDI_MNG_TX_DP")
	)
	(segment
		(start 365.285528 -8.043672)
		(end 365.285528 -10.671302)
		(width 0.101346)
		(layer "In9.Cu")
		(net "NIC_MDI_MNG_TX_DP")
	)
	(segment
		(start 411.260544 2.667)
		(end 410.99359 2.933954)
		(width 0.101346)
		(layer "In9.Cu")
		(net "NIC_MDI_MNG_TX_DP")
	)
	(segment
		(start 331.952854 -12.121642)
		(end 330.130912 -10.2997)
		(width 0.101346)
		(layer "In9.Cu")
		(net "NIC_MDI_MNG_TX_DP")
	)
	(segment
		(start 479.858578 4.485894)
		(end 479.114866 3.742182)
		(width 0.101346)
		(layer "In9.Cu")
		(net "NIC_MDI_MNG_TX_DP")
	)
	(segment
		(start 191.7954 -3.144012)
		(end 189.912498 -5.026914)
		(width 0.101346)
		(layer "In9.Cu")
		(net "NIC_MDI_MNG_TX_DP")
	)
	(segment
		(start 189.912498 -5.026914)
		(end 179.91074 -5.026914)
		(width 0.101346)
		(layer "In9.Cu")
		(net "NIC_MDI_MNG_TX_DP")
	)
	(segment
		(start 167.863012 -6.955028)
		(end 163.963604 -6.955028)
		(width 0.101346)
		(layer "In9.Cu")
		(net "NIC_MDI_MNG_TX_DP")
	)
	(segment
		(start 193.033142 -3.144012)
		(end 191.7954 -3.144012)
		(width 0.101346)
		(layer "In9.Cu")
		(net "NIC_MDI_MNG_TX_DP")
	)
	(segment
		(start 328.544682 -9.875266)
		(end 326.325484 -9.875266)
		(width 0.101346)
		(layer "In9.Cu")
		(net "NIC_MDI_MNG_TX_DP")
	)
	(segment
		(start 469.77046 -1.31826)
		(end 467.684358 0.767842)
		(width 0.101346)
		(layer "In9.Cu")
		(net "NIC_MDI_MNG_TX_DP")
	)
	(segment
		(start 9.031986 -30.440122)
		(end -2.947416 -30.440122)
		(width 0.101346)
		(layer "In9.Cu")
		(net "NIC_MDI_MNG_TX_DP")
	)
	(segment
		(start 423.201338 1.791208)
		(end 422.325546 2.667)
		(width 0.101346)
		(layer "In9.Cu")
		(net "NIC_MDI_MNG_TX_DP")
	)
	(segment
		(start 467.684358 2.770124)
		(end 464.962494 5.491988)
		(width 0.101346)
		(layer "In9.Cu")
		(net "NIC_MDI_MNG_TX_DP")
	)
	(segment
		(start 169.422826 -8.514842)
		(end 167.863012 -6.955028)
		(width 0.101346)
		(layer "In9.Cu")
		(net "NIC_MDI_MNG_TX_DP")
	)
	(segment
		(start 96.514666 -2.275586)
		(end 95.19793 -2.275586)
		(width 0.101346)
		(layer "In9.Cu")
		(net "NIC_MDI_MNG_TX_DP")
	)
	(segment
		(start 94.065344 -1.143)
		(end 30.47111 -1.143)
		(width 0.101346)
		(layer "In9.Cu")
		(net "NIC_MDI_MNG_TX_DP")
	)
	(segment
		(start 410.99359 2.933954)
		(end 405.84501 2.933954)
		(width 0.101346)
		(layer "In9.Cu")
		(net "NIC_MDI_MNG_TX_DP")
	)
	(segment
		(start 26.731214 -2.776982)
		(end 24.96439 -1.010158)
		(width 0.101346)
		(layer "In9.Cu")
		(net "NIC_MDI_MNG_TX_DP")
	)
	(segment
		(start 361.513882 -22.278594)
		(end 358.911652 -24.880824)
		(width 0.101346)
		(layer "In9.Cu")
		(net "NIC_MDI_MNG_TX_DP")
	)
	(segment
		(start 358.911652 -24.880824)
		(end 358.911652 -30.276292)
		(width 0.101346)
		(layer "In9.Cu")
		(net "NIC_MDI_MNG_TX_DP")
	)
	(segment
		(start 264.590276 -4.929632)
		(end 264.426192 -5.093716)
		(width 0.101346)
		(layer "In9.Cu")
		(net "NIC_MDI_MNG_TX_DP")
	)
	(segment
		(start 382.275588 1.27)
		(end 380.955042 -0.050546)
		(width 0.101346)
		(layer "In9.Cu")
		(net "NIC_MDI_MNG_TX_DP")
	)
	(segment
		(start 471.3986 -2.261108)
		(end 470.455752 -1.31826)
		(width 0.101346)
		(layer "In9.Cu")
		(net "NIC_MDI_MNG_TX_DP")
	)
	(segment
		(start 476.526352 -2.261108)
		(end 471.3986 -2.261108)
		(width 0.101346)
		(layer "In9.Cu")
		(net "NIC_MDI_MNG_TX_DP")
	)
	(segment
		(start 378.212858 -5.750052)
		(end 367.579148 -5.750052)
		(width 0.101346)
		(layer "In9.Cu")
		(net "NIC_MDI_MNG_TX_DP")
	)
	(segment
		(start 163.963604 -6.955028)
		(end 162.651186 -5.64261)
		(width 0.101346)
		(layer "In9.Cu")
		(net "NIC_MDI_MNG_TX_DP")
	)
	(segment
		(start 161.264854 -5.64261)
		(end 156.69641 -1.074166)
		(width 0.101346)
		(layer "In9.Cu")
		(net "NIC_MDI_MNG_TX_DP")
	)
	(segment
		(start 97.716086 -1.074166)
		(end 96.514666 -2.275586)
		(width 0.101346)
		(layer "In9.Cu")
		(net "NIC_MDI_MNG_TX_DP")
	)
	(segment
		(start 169.68089 -9.151366)
		(end 169.422826 -8.893302)
		(width 0.101346)
		(layer "In9.Cu")
		(net "NIC_MDI_MNG_TX_DP")
	)
	(segment
		(start 426.062648 1.791208)
		(end 423.201338 1.791208)
		(width 0.101346)
		(layer "In9.Cu")
		(net "NIC_MDI_MNG_TX_DP")
	)
	(segment
		(start -3.409696 -31.220156)
		(end -3.899662 -31.710122)
		(width 0.101346)
		(layer "In9.Cu")
		(net "NIC_MDI_MNG_TX_DP")
	)
	(segment
		(start 429.763428 5.491988)
		(end 426.062648 1.791208)
		(width 0.101346)
		(layer "In9.Cu")
		(net "NIC_MDI_MNG_TX_DP")
	)
	(segment
		(start 170.44924 -9.151366)
		(end 169.68089 -9.151366)
		(width 0.101346)
		(layer "In9.Cu")
		(net "NIC_MDI_MNG_TX_DP")
	)
	(segment
		(start 356.586028 -33.015682)
		(end 355.223064 -34.378646)
		(width 0.101346)
		(layer "In9.Cu")
		(net "NIC_MDI_MNG_TX_DP")
	)
	(segment
		(start 95.19793 -2.275586)
		(end 94.065344 -1.143)
		(width 0.101346)
		(layer "In9.Cu")
		(net "NIC_MDI_MNG_TX_DP")
	)
	(segment
		(start 464.962494 5.491988)
		(end 429.763428 5.491988)
		(width 0.101346)
		(layer "In9.Cu")
		(net "NIC_MDI_MNG_TX_DP")
	)
	(segment
		(start 467.684358 0.767842)
		(end 467.684358 2.770124)
		(width 0.101346)
		(layer "In9.Cu")
		(net "NIC_MDI_MNG_TX_DP")
	)
	(segment
		(start 361.513882 -19.878294)
		(end 361.513882 -22.278594)
		(width 0.101346)
		(layer "In9.Cu")
		(net "NIC_MDI_MNG_TX_DP")
	)
	(segment
		(start 14.715744 -3.68554)
		(end 10.8204 -7.580884)
		(width 0.101346)
		(layer "In9.Cu")
		(net "NIC_MDI_MNG_TX_DP")
	)
	(segment
		(start 367.579148 -5.750052)
		(end 365.285528 -8.043672)
		(width 0.101346)
		(layer "In9.Cu")
		(net "NIC_MDI_MNG_TX_DP")
	)
	(segment
		(start 323.46519 -4.929632)
		(end 264.590276 -4.929632)
		(width 0.101346)
		(layer "In9.Cu")
		(net "NIC_MDI_MNG_TX_DP")
	)
	(segment
		(start 356.586028 -32.601916)
		(end 356.586028 -33.015682)
		(width 0.101346)
		(layer "In9.Cu")
		(net "NIC_MDI_MNG_TX_DP")
	)
	(segment
		(start 14.715744 -3.210052)
		(end 14.715744 -3.68554)
		(width 0.101346)
		(layer "In9.Cu")
		(net "NIC_MDI_MNG_TX_DP")
	)
	(segment
		(start 405.84501 2.933954)
		(end 404.181056 1.27)
		(width 0.101346)
		(layer "In9.Cu")
		(net "NIC_MDI_MNG_TX_DP")
	)
	(segment
		(start 194.830954 -1.3462)
		(end 193.033142 -3.144012)
		(width 0.101346)
		(layer "In9.Cu")
		(net "NIC_MDI_MNG_TX_DP")
	)
	(segment
		(start 334.016858 -15.246858)
		(end 331.952854 -13.182854)
		(width 0.101346)
		(layer "In9.Cu")
		(net "NIC_MDI_MNG_TX_DP")
	)
	(segment
		(start 16.915638 -1.010158)
		(end 14.715744 -3.210052)
		(width 0.101346)
		(layer "In9.Cu")
		(net "NIC_MDI_MNG_TX_DP")
	)
	(segment
		(start 362.53166 -13.42517)
		(end 362.53166 -18.860516)
		(width 0.101346)
		(layer "In9.Cu")
		(net "NIC_MDI_MNG_TX_DP")
	)
	(segment
		(start 470.455752 -1.31826)
		(end 469.77046 -1.31826)
		(width 0.101346)
		(layer "In9.Cu")
		(net "NIC_MDI_MNG_TX_DP")
	)
	(segment
		(start 328.969116 -10.2997)
		(end 328.544682 -9.875266)
		(width 0.101346)
		(layer "In9.Cu")
		(net "NIC_MDI_MNG_TX_DP")
	)
	(segment
		(start 422.325546 2.667)
		(end 411.260544 2.667)
		(width 0.101346)
		(layer "In9.Cu")
		(net "NIC_MDI_MNG_TX_DP")
	)
	(segment
		(start 264.426192 -5.093716)
		(end 262.596884 -5.093716)
		(width 0.101346)
		(layer "In9.Cu")
		(net "NIC_MDI_MNG_TX_DP")
	)
	(segment
		(start 10.8204 -21.04771)
		(end 10.118598 -21.749512)
		(width 0.101346)
		(layer "In9.Cu")
		(net "NIC_MDI_MNG_TX_DP")
	)
	(segment
		(start 162.651186 -5.64261)
		(end 161.264854 -5.64261)
		(width 0.101346)
		(layer "In9.Cu")
		(net "NIC_MDI_MNG_TX_DP")
	)
	(segment
		(start 330.130912 -10.2997)
		(end 328.969116 -10.2997)
		(width 0.101346)
		(layer "In9.Cu")
		(net "NIC_MDI_MNG_TX_DP")
	)
	(segment
		(start 325.283576 -6.748018)
		(end 323.46519 -4.929632)
		(width 0.101346)
		(layer "In9.Cu")
		(net "NIC_MDI_MNG_TX_DP")
	)
	(segment
		(start -3.899662 -31.710122)
		(end -3.899916 -31.710122)
		(width 0.101346)
		(layer "In9.Cu")
		(net "NIC_MDI_MNG_TX_DP")
	)
	(segment
		(start 171.99356 -7.607046)
		(end 170.44924 -9.151366)
		(width 0.101346)
		(layer "In9.Cu")
		(net "NIC_MDI_MNG_TX_DP")
	)
	(segment
		(start 482.347524 4.485894)
		(end 479.858578 4.485894)
		(width 0.101346)
		(layer "In9.Cu")
		(net "NIC_MDI_MNG_TX_DP")
	)
	(segment
		(start 355.223064 -34.378646)
		(end 335.435956 -34.378646)
		(width 0.101346)
		(layer "In9.Cu")
		(net "NIC_MDI_MNG_TX_DP")
	)
	(segment
		(start 482.665024 4.803394)
		(end 482.347524 4.485894)
		(width 0.101346)
		(layer "In9.Cu")
		(net "NIC_MDI_MNG_TX_DP")
	)
	(segment
		(start 30.47111 -1.143)
		(end 28.837128 -2.776982)
		(width 0.101346)
		(layer "In9.Cu")
		(net "NIC_MDI_MNG_TX_DP")
	)
	(segment
		(start 169.422826 -8.893302)
		(end 169.422826 -8.514842)
		(width 0.101346)
		(layer "In9.Cu")
		(net "NIC_MDI_MNG_TX_DP")
	)
	(segment
		(start 28.837128 -2.776982)
		(end 26.731214 -2.776982)
		(width 0.101346)
		(layer "In9.Cu")
		(net "NIC_MDI_MNG_TX_DP")
	)
	(segment
		(start 262.596884 -5.093716)
		(end 258.849368 -1.3462)
		(width 0.101346)
		(layer "In9.Cu")
		(net "NIC_MDI_MNG_TX_DP")
	)
	(segment
		(start 326.325484 -9.875266)
		(end 325.283576 -8.833358)
		(width 0.101346)
		(layer "In9.Cu")
		(net "NIC_MDI_MNG_TX_DP")
	)
	(segment
		(start 380.955042 -0.050546)
		(end 380.955042 -3.007868)
		(width 0.101346)
		(layer "In9.Cu")
		(net "NIC_MDI_MNG_TX_DP")
	)
	(segment
		(start 9.260332 -30.211776)
		(end 9.031986 -30.440122)
		(width 0.101346)
		(layer "In9.Cu")
		(net "NIC_MDI_MNG_TX_DP")
	)
	(segment
		(start 9.260332 -24.089614)
		(end 9.260332 -30.211776)
		(width 0.101346)
		(layer "In9.Cu")
		(net "NIC_MDI_MNG_TX_DP")
	)
	(segment
		(start 179.134008 -5.803646)
		(end 176.469548 -5.803646)
		(width 0.101346)
		(layer "In9.Cu")
		(net "NIC_MDI_MNG_TX_DP")
	)
	(segment
		(start 10.118598 -23.231348)
		(end 9.260332 -24.089614)
		(width 0.101346)
		(layer "In9.Cu")
		(net "NIC_MDI_MNG_TX_DP")
	)
	(segment
		(start 176.469548 -5.803646)
		(end 174.666148 -7.607046)
		(width 0.101346)
		(layer "In9.Cu")
		(net "NIC_MDI_MNG_TX_DP")
	)
	(segment
		(start 179.91074 -5.026914)
		(end 179.134008 -5.803646)
		(width 0.101346)
		(layer "In9.Cu")
		(net "NIC_MDI_MNG_TX_DP")
	)
	(segment
		(start 10.118598 -21.749512)
		(end 10.118598 -23.231348)
		(width 0.101346)
		(layer "In9.Cu")
		(net "NIC_MDI_MNG_TX_DP")
	)
	(segment
		(start 386.571998 1.2446)
		(end 386.546598 1.27)
		(width 0.101346)
		(layer "In9.Cu")
		(net "NIC_MDI_MNG_TX_DP")
	)
	(segment
		(start 335.435956 -34.378646)
		(end 334.016858 -32.959548)
		(width 0.101346)
		(layer "In9.Cu")
		(net "NIC_MDI_MNG_TX_DP")
	)
	(segment
		(start 479.114866 3.742182)
		(end 479.114866 0.327406)
		(width 0.101346)
		(layer "In9.Cu")
		(net "NIC_MDI_MNG_TX_DP")
	)
	(segment
		(start 331.952854 -13.182854)
		(end 331.952854 -12.121642)
		(width 0.101346)
		(layer "In9.Cu")
		(net "NIC_MDI_MNG_TX_DP")
	)
	(segment
		(start 380.955042 -3.007868)
		(end 378.212858 -5.750052)
		(width 0.101346)
		(layer "In9.Cu")
		(net "NIC_MDI_MNG_TX_DP")
	)
	(segment
		(start 386.546598 1.27)
		(end 382.275588 1.27)
		(width 0.101346)
		(layer "In9.Cu")
		(net "NIC_MDI_MNG_TX_DP")
	)
	(segment
		(start 386.934202 1.27)
		(end 386.908802 1.2446)
		(width 0.101346)
		(layer "In9.Cu")
		(net "NIC_MDI_MNG_TX_DP")
	)
	(segment
		(start 365.285528 -10.671302)
		(end 362.53166 -13.42517)
		(width 0.101346)
		(layer "In9.Cu")
		(net "NIC_MDI_MNG_TX_DP")
	)
	(segment
		(start 481.734876 3.820668)
		(end 481.957888 4.04368)
		(width 0.10033)
		(layer "F.Cu")
		(net "NIC_MDI_MNG_TX_DN")
	)
	(segment
		(start 482.370384 4.04368)
		(end 482.665024 3.74904)
		(width 0.10033)
		(layer "F.Cu")
		(net "NIC_MDI_MNG_TX_DN")
	)
	(segment
		(start 481.957888 4.04368)
		(end 482.370384 4.04368)
		(width 0.10033)
		(layer "F.Cu")
		(net "NIC_MDI_MNG_TX_DN")
	)
	(via
		(at 482.665024 3.74904)
		(size 0.508)
		(drill 0.254)
		(layers "F.Cu" "B.Cu")
		(net "NIC_MDI_MNG_TX_DN")
	)
	(segment
		(start 264.764012 -5.348986)
		(end 264.599928 -5.51307)
		(width 0.101346)
		(layer "In9.Cu")
		(net "NIC_MDI_MNG_TX_DN")
	)
	(segment
		(start -2.990342 -31.219902)
		(end -2.500122 -31.710122)
		(width 0.101346)
		(layer "In9.Cu")
		(net "NIC_MDI_MNG_TX_DN")
	)
	(segment
		(start 378.386594 -6.169406)
		(end 367.752884 -6.169406)
		(width 0.101346)
		(layer "In9.Cu")
		(net "NIC_MDI_MNG_TX_DN")
	)
	(segment
		(start 355.3968 -34.798)
		(end 335.26222 -34.798)
		(width 0.101346)
		(layer "In9.Cu")
		(net "NIC_MDI_MNG_TX_DN")
	)
	(segment
		(start 9.679686 -30.385512)
		(end 9.205722 -30.859476)
		(width 0.101346)
		(layer "In9.Cu")
		(net "NIC_MDI_MNG_TX_DN")
	)
	(segment
		(start 324.864222 -9.007094)
		(end 324.864222 -6.921754)
		(width 0.101346)
		(layer "In9.Cu")
		(net "NIC_MDI_MNG_TX_DN")
	)
	(segment
		(start 26.557478 -3.196336)
		(end 24.790654 -1.429512)
		(width 0.101346)
		(layer "In9.Cu")
		(net "NIC_MDI_MNG_TX_DN")
	)
	(segment
		(start 365.704882 -10.845038)
		(end 362.951014 -13.598906)
		(width 0.101346)
		(layer "In9.Cu")
		(net "NIC_MDI_MNG_TX_DN")
	)
	(segment
		(start 479.53422 0.15367)
		(end 476.700088 -2.680462)
		(width 0.101346)
		(layer "In9.Cu")
		(net "NIC_MDI_MNG_TX_DN")
	)
	(segment
		(start 190.086234 -5.446268)
		(end 180.084476 -5.446268)
		(width 0.101346)
		(layer "In9.Cu")
		(net "NIC_MDI_MNG_TX_DN")
	)
	(segment
		(start 387.082538 0.825246)
		(end 386.398262 0.825246)
		(width 0.101346)
		(layer "In9.Cu")
		(net "NIC_MDI_MNG_TX_DN")
	)
	(segment
		(start 361.933236 -22.45233)
		(end 359.331006 -25.05456)
		(width 0.101346)
		(layer "In9.Cu")
		(net "NIC_MDI_MNG_TX_DN")
	)
	(segment
		(start 172.167296 -8.0264)
		(end 170.622976 -9.57072)
		(width 0.101346)
		(layer "In9.Cu")
		(net "NIC_MDI_MNG_TX_DN")
	)
	(segment
		(start 331.5335 -13.35659)
		(end 331.5335 -12.295378)
		(width 0.101346)
		(layer "In9.Cu")
		(net "NIC_MDI_MNG_TX_DN")
	)
	(segment
		(start 335.26222 -34.798)
		(end 333.597504 -33.133284)
		(width 0.101346)
		(layer "In9.Cu")
		(net "NIC_MDI_MNG_TX_DN")
	)
	(segment
		(start 333.597504 -15.420594)
		(end 331.5335 -13.35659)
		(width 0.101346)
		(layer "In9.Cu")
		(net "NIC_MDI_MNG_TX_DN")
	)
	(segment
		(start 426.236384 1.371854)
		(end 423.027602 1.371854)
		(width 0.101346)
		(layer "In9.Cu")
		(net "NIC_MDI_MNG_TX_DN")
	)
	(segment
		(start 471.224864 -2.680462)
		(end 470.282016 -1.737614)
		(width 0.101346)
		(layer "In9.Cu")
		(net "NIC_MDI_MNG_TX_DN")
	)
	(segment
		(start 464.788758 5.072634)
		(end 429.937164 5.072634)
		(width 0.101346)
		(layer "In9.Cu")
		(net "NIC_MDI_MNG_TX_DN")
	)
	(segment
		(start -2.77368 -30.859476)
		(end -2.990342 -31.076138)
		(width 0.101346)
		(layer "In9.Cu")
		(net "NIC_MDI_MNG_TX_DN")
	)
	(segment
		(start 176.643284 -6.223)
		(end 174.839884 -8.0264)
		(width 0.101346)
		(layer "In9.Cu")
		(net "NIC_MDI_MNG_TX_DN")
	)
	(segment
		(start 469.596724 -1.737614)
		(end 467.265004 0.594106)
		(width 0.101346)
		(layer "In9.Cu")
		(net "NIC_MDI_MNG_TX_DN")
	)
	(segment
		(start 386.398262 0.825246)
		(end 386.372862 0.850646)
		(width 0.101346)
		(layer "In9.Cu")
		(net "NIC_MDI_MNG_TX_DN")
	)
	(segment
		(start -2.990342 -31.076138)
		(end -2.990342 -31.219902)
		(width 0.101346)
		(layer "In9.Cu")
		(net "NIC_MDI_MNG_TX_DN")
	)
	(segment
		(start 169.003472 -8.688578)
		(end 167.689276 -7.374382)
		(width 0.101346)
		(layer "In9.Cu")
		(net "NIC_MDI_MNG_TX_DN")
	)
	(segment
		(start 9.679686 -24.26335)
		(end 9.679686 -30.385512)
		(width 0.101346)
		(layer "In9.Cu")
		(net "NIC_MDI_MNG_TX_DN")
	)
	(segment
		(start 328.79538 -10.719054)
		(end 328.370946 -10.29462)
		(width 0.101346)
		(layer "In9.Cu")
		(net "NIC_MDI_MNG_TX_DN")
	)
	(segment
		(start 404.354792 0.850646)
		(end 387.107938 0.850646)
		(width 0.101346)
		(layer "In9.Cu")
		(net "NIC_MDI_MNG_TX_DN")
	)
	(segment
		(start 10.537952 -21.923248)
		(end 10.537952 -23.405084)
		(width 0.101346)
		(layer "In9.Cu")
		(net "NIC_MDI_MNG_TX_DN")
	)
	(segment
		(start 387.107938 0.850646)
		(end 387.082538 0.825246)
		(width 0.101346)
		(layer "In9.Cu")
		(net "NIC_MDI_MNG_TX_DN")
	)
	(segment
		(start 333.597504 -33.133284)
		(end 333.597504 -15.420594)
		(width 0.101346)
		(layer "In9.Cu")
		(net "NIC_MDI_MNG_TX_DN")
	)
	(segment
		(start 328.370946 -10.29462)
		(end 326.151748 -10.29462)
		(width 0.101346)
		(layer "In9.Cu")
		(net "NIC_MDI_MNG_TX_DN")
	)
	(segment
		(start 331.5335 -12.295378)
		(end 329.957176 -10.719054)
		(width 0.101346)
		(layer "In9.Cu")
		(net "NIC_MDI_MNG_TX_DN")
	)
	(segment
		(start 17.089374 -1.429512)
		(end 15.135098 -3.383788)
		(width 0.101346)
		(layer "In9.Cu")
		(net "NIC_MDI_MNG_TX_DN")
	)
	(segment
		(start 467.265004 0.594106)
		(end 467.265004 2.596388)
		(width 0.101346)
		(layer "In9.Cu")
		(net "NIC_MDI_MNG_TX_DN")
	)
	(segment
		(start 9.205722 -30.859476)
		(end -2.77368 -30.859476)
		(width 0.101346)
		(layer "In9.Cu")
		(net "NIC_MDI_MNG_TX_DN")
	)
	(segment
		(start 357.005382 -32.775652)
		(end 357.005382 -33.189418)
		(width 0.101346)
		(layer "In9.Cu")
		(net "NIC_MDI_MNG_TX_DN")
	)
	(segment
		(start 96.688402 -2.69494)
		(end 95.024194 -2.69494)
		(width 0.101346)
		(layer "In9.Cu")
		(net "NIC_MDI_MNG_TX_DN")
	)
	(segment
		(start 15.135098 -3.383788)
		(end 15.135098 -3.859276)
		(width 0.101346)
		(layer "In9.Cu")
		(net "NIC_MDI_MNG_TX_DN")
	)
	(segment
		(start 422.15181 2.247646)
		(end 411.086808 2.247646)
		(width 0.101346)
		(layer "In9.Cu")
		(net "NIC_MDI_MNG_TX_DN")
	)
	(segment
		(start 324.864222 -6.921754)
		(end 323.291454 -5.348986)
		(width 0.101346)
		(layer "In9.Cu")
		(net "NIC_MDI_MNG_TX_DN")
	)
	(segment
		(start 362.951014 -13.598906)
		(end 362.951014 -19.034252)
		(width 0.101346)
		(layer "In9.Cu")
		(net "NIC_MDI_MNG_TX_DN")
	)
	(segment
		(start 264.599928 -5.51307)
		(end 262.423148 -5.51307)
		(width 0.101346)
		(layer "In9.Cu")
		(net "NIC_MDI_MNG_TX_DN")
	)
	(segment
		(start 11.239754 -7.75462)
		(end 11.239754 -21.221446)
		(width 0.101346)
		(layer "In9.Cu")
		(net "NIC_MDI_MNG_TX_DN")
	)
	(segment
		(start 323.291454 -5.348986)
		(end 264.764012 -5.348986)
		(width 0.101346)
		(layer "In9.Cu")
		(net "NIC_MDI_MNG_TX_DN")
	)
	(segment
		(start 367.752884 -6.169406)
		(end 365.704882 -8.217408)
		(width 0.101346)
		(layer "In9.Cu")
		(net "NIC_MDI_MNG_TX_DN")
	)
	(segment
		(start 361.933236 -20.05203)
		(end 361.933236 -22.45233)
		(width 0.101346)
		(layer "In9.Cu")
		(net "NIC_MDI_MNG_TX_DN")
	)
	(segment
		(start 476.700088 -2.680462)
		(end 471.224864 -2.680462)
		(width 0.101346)
		(layer "In9.Cu")
		(net "NIC_MDI_MNG_TX_DN")
	)
	(segment
		(start 24.790654 -1.429512)
		(end 17.089374 -1.429512)
		(width 0.101346)
		(layer "In9.Cu")
		(net "NIC_MDI_MNG_TX_DN")
	)
	(segment
		(start 479.53422 3.568446)
		(end 479.53422 0.15367)
		(width 0.101346)
		(layer "In9.Cu")
		(net "NIC_MDI_MNG_TX_DN")
	)
	(segment
		(start 179.307744 -6.223)
		(end 176.643284 -6.223)
		(width 0.101346)
		(layer "In9.Cu")
		(net "NIC_MDI_MNG_TX_DN")
	)
	(segment
		(start 156.522674 -1.49352)
		(end 97.889822 -1.49352)
		(width 0.101346)
		(layer "In9.Cu")
		(net "NIC_MDI_MNG_TX_DN")
	)
	(segment
		(start 411.086808 2.247646)
		(end 410.819854 2.5146)
		(width 0.101346)
		(layer "In9.Cu")
		(net "NIC_MDI_MNG_TX_DN")
	)
	(segment
		(start 359.331006 -25.05456)
		(end 359.331006 -30.450028)
		(width 0.101346)
		(layer "In9.Cu")
		(net "NIC_MDI_MNG_TX_DN")
	)
	(segment
		(start 162.47745 -6.061964)
		(end 161.091118 -6.061964)
		(width 0.101346)
		(layer "In9.Cu")
		(net "NIC_MDI_MNG_TX_DN")
	)
	(segment
		(start 423.027602 1.371854)
		(end 422.15181 2.247646)
		(width 0.101346)
		(layer "In9.Cu")
		(net "NIC_MDI_MNG_TX_DN")
	)
	(segment
		(start 161.091118 -6.061964)
		(end 156.522674 -1.49352)
		(width 0.101346)
		(layer "In9.Cu")
		(net "NIC_MDI_MNG_TX_DN")
	)
	(segment
		(start 170.622976 -9.57072)
		(end 169.507154 -9.57072)
		(width 0.101346)
		(layer "In9.Cu")
		(net "NIC_MDI_MNG_TX_DN")
	)
	(segment
		(start 167.689276 -7.374382)
		(end 163.789868 -7.374382)
		(width 0.101346)
		(layer "In9.Cu")
		(net "NIC_MDI_MNG_TX_DN")
	)
	(segment
		(start 195.00469 -1.765554)
		(end 193.206878 -3.563366)
		(width 0.101346)
		(layer "In9.Cu")
		(net "NIC_MDI_MNG_TX_DN")
	)
	(segment
		(start 381.374396 -0.224282)
		(end 381.374396 -3.181604)
		(width 0.101346)
		(layer "In9.Cu")
		(net "NIC_MDI_MNG_TX_DN")
	)
	(segment
		(start 480.032314 4.06654)
		(end 479.53422 3.568446)
		(width 0.101346)
		(layer "In9.Cu")
		(net "NIC_MDI_MNG_TX_DN")
	)
	(segment
		(start 362.951014 -19.034252)
		(end 361.933236 -20.05203)
		(width 0.101346)
		(layer "In9.Cu")
		(net "NIC_MDI_MNG_TX_DN")
	)
	(segment
		(start 30.644846 -1.562354)
		(end 29.010864 -3.196336)
		(width 0.101346)
		(layer "In9.Cu")
		(net "NIC_MDI_MNG_TX_DN")
	)
	(segment
		(start 163.789868 -7.374382)
		(end 162.47745 -6.061964)
		(width 0.101346)
		(layer "In9.Cu")
		(net "NIC_MDI_MNG_TX_DN")
	)
	(segment
		(start 169.507154 -9.57072)
		(end 169.003472 -9.067038)
		(width 0.101346)
		(layer "In9.Cu")
		(net "NIC_MDI_MNG_TX_DN")
	)
	(segment
		(start 97.889822 -1.49352)
		(end 96.688402 -2.69494)
		(width 0.101346)
		(layer "In9.Cu")
		(net "NIC_MDI_MNG_TX_DN")
	)
	(segment
		(start 11.239754 -21.221446)
		(end 10.537952 -21.923248)
		(width 0.101346)
		(layer "In9.Cu")
		(net "NIC_MDI_MNG_TX_DN")
	)
	(segment
		(start 359.331006 -30.450028)
		(end 357.005382 -32.775652)
		(width 0.101346)
		(layer "In9.Cu")
		(net "NIC_MDI_MNG_TX_DN")
	)
	(segment
		(start 410.819854 2.5146)
		(end 406.018746 2.5146)
		(width 0.101346)
		(layer "In9.Cu")
		(net "NIC_MDI_MNG_TX_DN")
	)
	(segment
		(start 357.005382 -33.189418)
		(end 355.3968 -34.798)
		(width 0.101346)
		(layer "In9.Cu")
		(net "NIC_MDI_MNG_TX_DN")
	)
	(segment
		(start 329.957176 -10.719054)
		(end 328.79538 -10.719054)
		(width 0.101346)
		(layer "In9.Cu")
		(net "NIC_MDI_MNG_TX_DN")
	)
	(segment
		(start 191.969136 -3.563366)
		(end 190.086234 -5.446268)
		(width 0.101346)
		(layer "In9.Cu")
		(net "NIC_MDI_MNG_TX_DN")
	)
	(segment
		(start 258.675632 -1.765554)
		(end 195.00469 -1.765554)
		(width 0.101346)
		(layer "In9.Cu")
		(net "NIC_MDI_MNG_TX_DN")
	)
	(segment
		(start 10.537952 -23.405084)
		(end 9.679686 -24.26335)
		(width 0.101346)
		(layer "In9.Cu")
		(net "NIC_MDI_MNG_TX_DN")
	)
	(segment
		(start 386.372862 0.850646)
		(end 382.449324 0.850646)
		(width 0.101346)
		(layer "In9.Cu")
		(net "NIC_MDI_MNG_TX_DN")
	)
	(segment
		(start 382.449324 0.850646)
		(end 381.374396 -0.224282)
		(width 0.101346)
		(layer "In9.Cu")
		(net "NIC_MDI_MNG_TX_DN")
	)
	(segment
		(start 15.135098 -3.859276)
		(end 11.239754 -7.75462)
		(width 0.101346)
		(layer "In9.Cu")
		(net "NIC_MDI_MNG_TX_DN")
	)
	(segment
		(start 381.374396 -3.181604)
		(end 378.386594 -6.169406)
		(width 0.101346)
		(layer "In9.Cu")
		(net "NIC_MDI_MNG_TX_DN")
	)
	(segment
		(start 482.347524 4.06654)
		(end 480.032314 4.06654)
		(width 0.101346)
		(layer "In9.Cu")
		(net "NIC_MDI_MNG_TX_DN")
	)
	(segment
		(start 482.665024 3.74904)
		(end 482.347524 4.06654)
		(width 0.101346)
		(layer "In9.Cu")
		(net "NIC_MDI_MNG_TX_DN")
	)
	(segment
		(start 169.003472 -9.067038)
		(end 169.003472 -8.688578)
		(width 0.101346)
		(layer "In9.Cu")
		(net "NIC_MDI_MNG_TX_DN")
	)
	(segment
		(start 262.423148 -5.51307)
		(end 258.675632 -1.765554)
		(width 0.101346)
		(layer "In9.Cu")
		(net "NIC_MDI_MNG_TX_DN")
	)
	(segment
		(start 429.937164 5.072634)
		(end 426.236384 1.371854)
		(width 0.101346)
		(layer "In9.Cu")
		(net "NIC_MDI_MNG_TX_DN")
	)
	(segment
		(start 193.206878 -3.563366)
		(end 191.969136 -3.563366)
		(width 0.101346)
		(layer "In9.Cu")
		(net "NIC_MDI_MNG_TX_DN")
	)
	(segment
		(start 95.024194 -2.69494)
		(end 93.891608 -1.562354)
		(width 0.101346)
		(layer "In9.Cu")
		(net "NIC_MDI_MNG_TX_DN")
	)
	(segment
		(start 470.282016 -1.737614)
		(end 469.596724 -1.737614)
		(width 0.101346)
		(layer "In9.Cu")
		(net "NIC_MDI_MNG_TX_DN")
	)
	(segment
		(start 174.839884 -8.0264)
		(end 172.167296 -8.0264)
		(width 0.101346)
		(layer "In9.Cu")
		(net "NIC_MDI_MNG_TX_DN")
	)
	(segment
		(start 365.704882 -8.217408)
		(end 365.704882 -10.845038)
		(width 0.101346)
		(layer "In9.Cu")
		(net "NIC_MDI_MNG_TX_DN")
	)
	(segment
		(start 29.010864 -3.196336)
		(end 26.557478 -3.196336)
		(width 0.101346)
		(layer "In9.Cu")
		(net "NIC_MDI_MNG_TX_DN")
	)
	(segment
		(start 93.891608 -1.562354)
		(end 30.644846 -1.562354)
		(width 0.101346)
		(layer "In9.Cu")
		(net "NIC_MDI_MNG_TX_DN")
	)
	(segment
		(start 467.265004 2.596388)
		(end 464.788758 5.072634)
		(width 0.101346)
		(layer "In9.Cu")
		(net "NIC_MDI_MNG_TX_DN")
	)
	(segment
		(start 326.151748 -10.29462)
		(end 324.864222 -9.007094)
		(width 0.101346)
		(layer "In9.Cu")
		(net "NIC_MDI_MNG_TX_DN")
	)
	(segment
		(start 406.018746 2.5146)
		(end 404.354792 0.850646)
		(width 0.101346)
		(layer "In9.Cu")
		(net "NIC_MDI_MNG_TX_DN")
	)
	(segment
		(start 180.084476 -5.446268)
		(end 179.307744 -6.223)
		(width 0.101346)
		(layer "In9.Cu")
		(net "NIC_MDI_MNG_TX_DN")
	)
	(via
		(at 475.275402 -3.349244)
		(size 0.508)
		(drill 0.254)
		(layers "F.Cu" "B.Cu")
		(net "NIC_MDI_MNG_RX_DP")
	)
	(segment
		(start 475.32544 -3.130804)
		(end 475.48419 -2.972054)
		(width 0.101346)
		(layer "B.Cu")
		(net "NIC_MDI_MNG_RX_DP")
	)
	(segment
		(start 476.350076 -2.972054)
		(end 476.756222 -3.3782)
		(width 0.101346)
		(layer "B.Cu")
		(net "NIC_MDI_MNG_RX_DP")
	)
	(segment
		(start 475.48419 -2.972054)
		(end 476.350076 -2.972054)
		(width 0.101346)
		(layer "B.Cu")
		(net "NIC_MDI_MNG_RX_DP")
	)
	(segment
		(start 475.275402 -3.349244)
		(end 475.275402 -3.180842)
		(width 0.10033)
		(layer "B.Cu")
		(net "NIC_MDI_MNG_RX_DP")
	)
	(segment
		(start 475.275402 -3.180842)
		(end 475.32544 -3.130804)
		(width 0.10033)
		(layer "B.Cu")
		(net "NIC_MDI_MNG_RX_DP")
	)
	(segment
		(start 469.279224 -2.791968)
		(end 466.88121 -0.393954)
		(width 0.101346)
		(layer "In9.Cu")
		(net "NIC_MDI_MNG_RX_DP")
	)
	(segment
		(start 96.153732 -5.799582)
		(end 95.47987 -6.473444)
		(width 0.101346)
		(layer "In9.Cu")
		(net "NIC_MDI_MNG_RX_DP")
	)
	(segment
		(start 0.790194 -32.200088)
		(end 0.300228 -31.710122)
		(width 0.101346)
		(layer "In9.Cu")
		(net "NIC_MDI_MNG_RX_DP")
	)
	(segment
		(start 382.346454 -0.720344)
		(end 382.3462 -0.720598)
		(width 0.101346)
		(layer "In9.Cu")
		(net "NIC_MDI_MNG_RX_DP")
	)
	(segment
		(start 379.02642 -7.138924)
		(end 368.18951 -7.138924)
		(width 0.101346)
		(layer "In9.Cu")
		(net "NIC_MDI_MNG_RX_DP")
	)
	(segment
		(start 462.730342 2.343658)
		(end 428.699168 2.343658)
		(width 0.101346)
		(layer "In9.Cu")
		(net "NIC_MDI_MNG_RX_DP")
	)
	(segment
		(start 367.463832 -8.984488)
		(end 366.687354 -9.760966)
		(width 0.101346)
		(layer "In9.Cu")
		(net "NIC_MDI_MNG_RX_DP")
	)
	(segment
		(start 406.298146 1.4224)
		(end 404.126192 -0.749554)
		(width 0.101346)
		(layer "In9.Cu")
		(net "NIC_MDI_MNG_RX_DP")
	)
	(segment
		(start 362.987336 -20.368006)
		(end 362.987336 -22.88921)
		(width 0.101346)
		(layer "In9.Cu")
		(net "NIC_MDI_MNG_RX_DP")
	)
	(segment
		(start 398.996408 -0.749554)
		(end 398.488408 -0.241554)
		(width 0.101346)
		(layer "In9.Cu")
		(net "NIC_MDI_MNG_RX_DP")
	)
	(segment
		(start 330.4794 -12.732258)
		(end 329.520296 -11.773154)
		(width 0.101346)
		(layer "In9.Cu")
		(net "NIC_MDI_MNG_RX_DP")
	)
	(segment
		(start 368.18951 -7.138924)
		(end 367.463832 -7.864602)
		(width 0.101346)
		(layer "In9.Cu")
		(net "NIC_MDI_MNG_RX_DP")
	)
	(segment
		(start 331.405484 -21.39823)
		(end 330.422504 -20.41525)
		(width 0.101346)
		(layer "In9.Cu")
		(net "NIC_MDI_MNG_RX_DP")
	)
	(segment
		(start 28.07208 -6.473444)
		(end 27.576526 -5.97789)
		(width 0.101346)
		(layer "In9.Cu")
		(net "NIC_MDI_MNG_RX_DP")
	)
	(segment
		(start 366.687354 -9.760966)
		(end 366.687354 -11.353546)
		(width 0.101346)
		(layer "In9.Cu")
		(net "NIC_MDI_MNG_RX_DP")
	)
	(segment
		(start 465.467954 -0.393954)
		(end 462.730342 2.343658)
		(width 0.101346)
		(layer "In9.Cu")
		(net "NIC_MDI_MNG_RX_DP")
	)
	(segment
		(start 99.536504 -6.000496)
		(end 97.50552 -6.000496)
		(width 0.101346)
		(layer "In9.Cu")
		(net "NIC_MDI_MNG_RX_DP")
	)
	(segment
		(start 367.463832 -7.864602)
		(end 367.463832 -8.984488)
		(width 0.101346)
		(layer "In9.Cu")
		(net "NIC_MDI_MNG_RX_DP")
	)
	(segment
		(start 422.717722 0.190754)
		(end 421.8432 1.065276)
		(width 0.101346)
		(layer "In9.Cu")
		(net "NIC_MDI_MNG_RX_DP")
	)
	(segment
		(start 475.275402 -3.349244)
		(end 474.963998 -3.660648)
		(width 0.101346)
		(layer "In9.Cu")
		(net "NIC_MDI_MNG_RX_DP")
	)
	(segment
		(start 330.4794 -13.8684)
		(end 330.4794 -12.732258)
		(width 0.101346)
		(layer "In9.Cu")
		(net "NIC_MDI_MNG_RX_DP")
	)
	(segment
		(start 259.117592 -5.34162)
		(end 193.961512 -5.34162)
		(width 0.101346)
		(layer "In9.Cu")
		(net "NIC_MDI_MNG_RX_DP")
	)
	(segment
		(start 14.432026 -5.97789)
		(end 12.204954 -8.204962)
		(width 0.101346)
		(layer "In9.Cu")
		(net "NIC_MDI_MNG_RX_DP")
	)
	(segment
		(start 364.005114 -19.350228)
		(end 362.987336 -20.368006)
		(width 0.101346)
		(layer "In9.Cu")
		(net "NIC_MDI_MNG_RX_DP")
	)
	(segment
		(start 362.987336 -22.88921)
		(end 360.385106 -25.49144)
		(width 0.101346)
		(layer "In9.Cu")
		(net "NIC_MDI_MNG_RX_DP")
	)
	(segment
		(start 469.732614 -2.791968)
		(end 469.279224 -2.791968)
		(width 0.101346)
		(layer "In9.Cu")
		(net "NIC_MDI_MNG_RX_DP")
	)
	(segment
		(start 165.668198 -11.000232)
		(end 160.898078 -11.000232)
		(width 0.101346)
		(layer "In9.Cu")
		(net "NIC_MDI_MNG_RX_DP")
	)
	(segment
		(start 262.173466 -7.518654)
		(end 261.294626 -7.518654)
		(width 0.101346)
		(layer "In9.Cu")
		(net "NIC_MDI_MNG_RX_DP")
	)
	(segment
		(start 1.137158 -32.864806)
		(end 0.790194 -32.517842)
		(width 0.101346)
		(layer "In9.Cu")
		(net "NIC_MDI_MNG_RX_DP")
	)
	(segment
		(start 325.51878 -11.205972)
		(end 323.810122 -9.497314)
		(width 0.101346)
		(layer "In9.Cu")
		(net "NIC_MDI_MNG_RX_DP")
	)
	(segment
		(start 428.699168 2.343658)
		(end 426.546264 0.190754)
		(width 0.101346)
		(layer "In9.Cu")
		(net "NIC_MDI_MNG_RX_DP")
	)
	(segment
		(start 360.385106 -30.955488)
		(end 358.0892 -33.251394)
		(width 0.101346)
		(layer "In9.Cu")
		(net "NIC_MDI_MNG_RX_DP")
	)
	(segment
		(start 176.445418 -9.0932)
		(end 173.134274 -9.0932)
		(width 0.101346)
		(layer "In9.Cu")
		(net "NIC_MDI_MNG_RX_DP")
	)
	(segment
		(start 0.300228 -31.710122)
		(end 0.299974 -31.710122)
		(width 0.101346)
		(layer "In9.Cu")
		(net "NIC_MDI_MNG_RX_DP")
	)
	(segment
		(start 398.488408 -0.241554)
		(end 382.718818 -0.241554)
		(width 0.101346)
		(layer "In9.Cu")
		(net "NIC_MDI_MNG_RX_DP")
	)
	(segment
		(start 474.963998 -3.89636)
		(end 474.292422 -4.567936)
		(width 0.101346)
		(layer "In9.Cu")
		(net "NIC_MDI_MNG_RX_DP")
	)
	(segment
		(start 97.50552 -6.000496)
		(end 97.304606 -5.799582)
		(width 0.101346)
		(layer "In9.Cu")
		(net "NIC_MDI_MNG_RX_DP")
	)
	(segment
		(start 334.736694 -35.814)
		(end 332.490318 -33.567624)
		(width 0.101346)
		(layer "In9.Cu")
		(net "NIC_MDI_MNG_RX_DP")
	)
	(segment
		(start 366.687354 -11.353546)
		(end 364.005114 -14.035786)
		(width 0.101346)
		(layer "In9.Cu")
		(net "NIC_MDI_MNG_RX_DP")
	)
	(segment
		(start 421.8432 1.065276)
		(end 410.837634 1.065276)
		(width 0.101346)
		(layer "In9.Cu")
		(net "NIC_MDI_MNG_RX_DP")
	)
	(segment
		(start 364.005114 -14.035786)
		(end 364.005114 -19.350228)
		(width 0.101346)
		(layer "In9.Cu")
		(net "NIC_MDI_MNG_RX_DP")
	)
	(segment
		(start 171.68368 -10.543794)
		(end 166.124636 -10.543794)
		(width 0.101346)
		(layer "In9.Cu")
		(net "NIC_MDI_MNG_RX_DP")
	)
	(segment
		(start 10.733786 -30.875224)
		(end 8.744204 -32.864806)
		(width 0.101346)
		(layer "In9.Cu")
		(net "NIC_MDI_MNG_RX_DP")
	)
	(segment
		(start 27.576526 -5.97789)
		(end 14.432026 -5.97789)
		(width 0.101346)
		(layer "In9.Cu")
		(net "NIC_MDI_MNG_RX_DP")
	)
	(segment
		(start 11.61669 -22.36851)
		(end 11.61669 -23.75027)
		(width 0.101346)
		(layer "In9.Cu")
		(net "NIC_MDI_MNG_RX_DP")
	)
	(segment
		(start 327.768712 -11.205972)
		(end 325.51878 -11.205972)
		(width 0.101346)
		(layer "In9.Cu")
		(net "NIC_MDI_MNG_RX_DP")
	)
	(segment
		(start 330.422504 -20.41525)
		(end 330.422504 -17.266666)
		(width 0.101346)
		(layer "In9.Cu")
		(net "NIC_MDI_MNG_RX_DP")
	)
	(segment
		(start 262.598154 -6.853936)
		(end 262.598154 -7.093966)
		(width 0.101346)
		(layer "In9.Cu")
		(net "NIC_MDI_MNG_RX_DP")
	)
	(segment
		(start 474.963998 -3.660648)
		(end 474.963998 -3.89636)
		(width 0.101346)
		(layer "In9.Cu")
		(net "NIC_MDI_MNG_RX_DP")
	)
	(segment
		(start 177.363882 -8.174736)
		(end 176.445418 -9.0932)
		(width 0.101346)
		(layer "In9.Cu")
		(net "NIC_MDI_MNG_RX_DP")
	)
	(segment
		(start 193.961512 -5.34162)
		(end 192.331848 -6.971284)
		(width 0.101346)
		(layer "In9.Cu")
		(net "NIC_MDI_MNG_RX_DP")
	)
	(segment
		(start 382.718818 -0.241554)
		(end 382.346454 -0.613918)
		(width 0.101346)
		(layer "In9.Cu")
		(net "NIC_MDI_MNG_RX_DP")
	)
	(segment
		(start 329.520296 -11.773154)
		(end 328.335894 -11.773154)
		(width 0.101346)
		(layer "In9.Cu")
		(net "NIC_MDI_MNG_RX_DP")
	)
	(segment
		(start 12.204954 -21.780246)
		(end 11.61669 -22.36851)
		(width 0.101346)
		(layer "In9.Cu")
		(net "NIC_MDI_MNG_RX_DP")
	)
	(segment
		(start 323.810122 -7.501382)
		(end 322.742052 -6.433312)
		(width 0.101346)
		(layer "In9.Cu")
		(net "NIC_MDI_MNG_RX_DP")
	)
	(segment
		(start 410.837634 1.065276)
		(end 410.48051 1.4224)
		(width 0.101346)
		(layer "In9.Cu")
		(net "NIC_MDI_MNG_RX_DP")
	)
	(segment
		(start 328.335894 -11.773154)
		(end 327.768712 -11.205972)
		(width 0.101346)
		(layer "In9.Cu")
		(net "NIC_MDI_MNG_RX_DP")
	)
	(segment
		(start 404.126192 -0.749554)
		(end 398.996408 -0.749554)
		(width 0.101346)
		(layer "In9.Cu")
		(net "NIC_MDI_MNG_RX_DP")
	)
	(segment
		(start 173.134274 -9.0932)
		(end 171.68368 -10.543794)
		(width 0.101346)
		(layer "In9.Cu")
		(net "NIC_MDI_MNG_RX_DP")
	)
	(segment
		(start 355.981 -35.814)
		(end 334.736694 -35.814)
		(width 0.101346)
		(layer "In9.Cu")
		(net "NIC_MDI_MNG_RX_DP")
	)
	(segment
		(start 360.385106 -25.49144)
		(end 360.385106 -30.955488)
		(width 0.101346)
		(layer "In9.Cu")
		(net "NIC_MDI_MNG_RX_DP")
	)
	(segment
		(start 323.810122 -9.497314)
		(end 323.810122 -7.501382)
		(width 0.101346)
		(layer "In9.Cu")
		(net "NIC_MDI_MNG_RX_DP")
	)
	(segment
		(start 382.346454 -0.613918)
		(end 382.346454 -0.720344)
		(width 0.101346)
		(layer "In9.Cu")
		(net "NIC_MDI_MNG_RX_DP")
	)
	(segment
		(start 322.742052 -6.433312)
		(end 263.018778 -6.433312)
		(width 0.101346)
		(layer "In9.Cu")
		(net "NIC_MDI_MNG_RX_DP")
	)
	(segment
		(start 166.124636 -10.543794)
		(end 165.668198 -11.000232)
		(width 0.101346)
		(layer "In9.Cu")
		(net "NIC_MDI_MNG_RX_DP")
	)
	(segment
		(start 466.88121 -0.393954)
		(end 465.467954 -0.393954)
		(width 0.101346)
		(layer "In9.Cu")
		(net "NIC_MDI_MNG_RX_DP")
	)
	(segment
		(start 192.331848 -6.971284)
		(end 190.906146 -6.971284)
		(width 0.101346)
		(layer "In9.Cu")
		(net "NIC_MDI_MNG_RX_DP")
	)
	(segment
		(start 155.927552 -5.802376)
		(end 99.734624 -5.802376)
		(width 0.101346)
		(layer "In9.Cu")
		(net "NIC_MDI_MNG_RX_DP")
	)
	(segment
		(start 10.733786 -24.633174)
		(end 10.733786 -30.875224)
		(width 0.101346)
		(layer "In9.Cu")
		(net "NIC_MDI_MNG_RX_DP")
	)
	(segment
		(start 190.349124 -6.414262)
		(end 186.173618 -6.414262)
		(width 0.101346)
		(layer "In9.Cu")
		(net "NIC_MDI_MNG_RX_DP")
	)
	(segment
		(start 331.804264 -15.193264)
		(end 330.4794 -13.8684)
		(width 0.101346)
		(layer "In9.Cu")
		(net "NIC_MDI_MNG_RX_DP")
	)
	(segment
		(start 11.61669 -23.75027)
		(end 10.733786 -24.633174)
		(width 0.101346)
		(layer "In9.Cu")
		(net "NIC_MDI_MNG_RX_DP")
	)
	(segment
		(start 330.422504 -17.266666)
		(end 331.804264 -15.884906)
		(width 0.101346)
		(layer "In9.Cu")
		(net "NIC_MDI_MNG_RX_DP")
	)
	(segment
		(start 184.413144 -8.174736)
		(end 177.363882 -8.174736)
		(width 0.101346)
		(layer "In9.Cu")
		(net "NIC_MDI_MNG_RX_DP")
	)
	(segment
		(start 262.598154 -7.093966)
		(end 262.173466 -7.518654)
		(width 0.101346)
		(layer "In9.Cu")
		(net "NIC_MDI_MNG_RX_DP")
	)
	(segment
		(start 358.0892 -33.7058)
		(end 355.981 -35.814)
		(width 0.101346)
		(layer "In9.Cu")
		(net "NIC_MDI_MNG_RX_DP")
	)
	(segment
		(start 186.173618 -6.414262)
		(end 184.413144 -8.174736)
		(width 0.101346)
		(layer "In9.Cu")
		(net "NIC_MDI_MNG_RX_DP")
	)
	(segment
		(start 95.47987 -6.473444)
		(end 28.07208 -6.473444)
		(width 0.101346)
		(layer "In9.Cu")
		(net "NIC_MDI_MNG_RX_DP")
	)
	(segment
		(start 159.15767 -9.259824)
		(end 159.15767 -9.032494)
		(width 0.101346)
		(layer "In9.Cu")
		(net "NIC_MDI_MNG_RX_DP")
	)
	(segment
		(start 159.15767 -9.032494)
		(end 155.927552 -5.802376)
		(width 0.101346)
		(layer "In9.Cu")
		(net "NIC_MDI_MNG_RX_DP")
	)
	(segment
		(start 358.0892 -33.251394)
		(end 358.0892 -33.7058)
		(width 0.101346)
		(layer "In9.Cu")
		(net "NIC_MDI_MNG_RX_DP")
	)
	(segment
		(start 382.346454 -1.057656)
		(end 382.346454 -3.81889)
		(width 0.101346)
		(layer "In9.Cu")
		(net "NIC_MDI_MNG_RX_DP")
	)
	(segment
		(start 382.3462 -0.720598)
		(end 382.3462 -1.057402)
		(width 0.101346)
		(layer "In9.Cu")
		(net "NIC_MDI_MNG_RX_DP")
	)
	(segment
		(start 471.508582 -4.567936)
		(end 469.732614 -2.791968)
		(width 0.101346)
		(layer "In9.Cu")
		(net "NIC_MDI_MNG_RX_DP")
	)
	(segment
		(start 332.490318 -33.567624)
		(end 332.490318 -25.845008)
		(width 0.101346)
		(layer "In9.Cu")
		(net "NIC_MDI_MNG_RX_DP")
	)
	(segment
		(start 263.018778 -6.433312)
		(end 262.598154 -6.853936)
		(width 0.101346)
		(layer "In9.Cu")
		(net "NIC_MDI_MNG_RX_DP")
	)
	(segment
		(start 8.744204 -32.864806)
		(end 1.137158 -32.864806)
		(width 0.101346)
		(layer "In9.Cu")
		(net "NIC_MDI_MNG_RX_DP")
	)
	(segment
		(start 474.292422 -4.567936)
		(end 471.508582 -4.567936)
		(width 0.101346)
		(layer "In9.Cu")
		(net "NIC_MDI_MNG_RX_DP")
	)
	(segment
		(start 99.734624 -5.802376)
		(end 99.536504 -6.000496)
		(width 0.101346)
		(layer "In9.Cu")
		(net "NIC_MDI_MNG_RX_DP")
	)
	(segment
		(start 97.304606 -5.799582)
		(end 96.153732 -5.799582)
		(width 0.101346)
		(layer "In9.Cu")
		(net "NIC_MDI_MNG_RX_DP")
	)
	(segment
		(start 410.48051 1.4224)
		(end 406.298146 1.4224)
		(width 0.101346)
		(layer "In9.Cu")
		(net "NIC_MDI_MNG_RX_DP")
	)
	(segment
		(start 261.294626 -7.518654)
		(end 259.117592 -5.34162)
		(width 0.101346)
		(layer "In9.Cu")
		(net "NIC_MDI_MNG_RX_DP")
	)
	(segment
		(start 426.546264 0.190754)
		(end 422.717722 0.190754)
		(width 0.101346)
		(layer "In9.Cu")
		(net "NIC_MDI_MNG_RX_DP")
	)
	(segment
		(start 160.898078 -11.000232)
		(end 159.15767 -9.259824)
		(width 0.101346)
		(layer "In9.Cu")
		(net "NIC_MDI_MNG_RX_DP")
	)
	(segment
		(start 331.804264 -15.884906)
		(end 331.804264 -15.193264)
		(width 0.101346)
		(layer "In9.Cu")
		(net "NIC_MDI_MNG_RX_DP")
	)
	(segment
		(start 331.405484 -24.760174)
		(end 331.405484 -21.39823)
		(width 0.101346)
		(layer "In9.Cu")
		(net "NIC_MDI_MNG_RX_DP")
	)
	(segment
		(start 190.906146 -6.971284)
		(end 190.349124 -6.414262)
		(width 0.101346)
		(layer "In9.Cu")
		(net "NIC_MDI_MNG_RX_DP")
	)
	(segment
		(start 382.346454 -3.81889)
		(end 379.02642 -7.138924)
		(width 0.101346)
		(layer "In9.Cu")
		(net "NIC_MDI_MNG_RX_DP")
	)
	(segment
		(start 12.204954 -8.204962)
		(end 12.204954 -21.780246)
		(width 0.101346)
		(layer "In9.Cu")
		(net "NIC_MDI_MNG_RX_DP")
	)
	(segment
		(start 332.490318 -25.845008)
		(end 331.405484 -24.760174)
		(width 0.101346)
		(layer "In9.Cu")
		(net "NIC_MDI_MNG_RX_DP")
	)
	(segment
		(start 0.790194 -32.517842)
		(end 0.790194 -32.200088)
		(width 0.101346)
		(layer "In9.Cu")
		(net "NIC_MDI_MNG_RX_DP")
	)
	(segment
		(start 382.3462 -1.057402)
		(end 382.346454 -1.057656)
		(width 0.101346)
		(layer "In9.Cu")
		(net "NIC_MDI_MNG_RX_DP")
	)
	(via
		(at 474.544644 -3.263392)
		(size 0.508)
		(drill 0.254)
		(layers "F.Cu" "B.Cu")
		(net "NIC_MDI_MNG_RX_DN")
	)
	(segment
		(start 474.544644 -3.263392)
		(end 475.294198 -2.513838)
		(width 0.101346)
		(layer "B.Cu")
		(net "NIC_MDI_MNG_RX_DN")
	)
	(segment
		(start 475.294198 -2.513838)
		(end 476.745554 -2.513838)
		(width 0.101346)
		(layer "B.Cu")
		(net "NIC_MDI_MNG_RX_DN")
	)
	(segment
		(start 334.91043 -35.394646)
		(end 332.909672 -33.393888)
		(width 0.101346)
		(layer "In9.Cu")
		(net "NIC_MDI_MNG_RX_DN")
	)
	(segment
		(start 1.209548 -32.200596)
		(end 1.700022 -31.710122)
		(width 0.101346)
		(layer "In9.Cu")
		(net "NIC_MDI_MNG_RX_DN")
	)
	(segment
		(start 366.513618 -9.341612)
		(end 366.513364 -9.341612)
		(width 0.101346)
		(layer "In9.Cu")
		(net "NIC_MDI_MNG_RX_DN")
	)
	(segment
		(start 261.99973 -7.0993)
		(end 261.468362 -7.0993)
		(width 0.101346)
		(layer "In9.Cu")
		(net "NIC_MDI_MNG_RX_DN")
	)
	(segment
		(start 156.101288 -5.383022)
		(end 99.560888 -5.383022)
		(width 0.101346)
		(layer "In9.Cu")
		(net "NIC_MDI_MNG_RX_DN")
	)
	(segment
		(start 322.915788 -6.013958)
		(end 262.845042 -6.013958)
		(width 0.101346)
		(layer "In9.Cu")
		(net "NIC_MDI_MNG_RX_DN")
	)
	(segment
		(start 363.58576 -13.86205)
		(end 363.58576 -19.176492)
		(width 0.101346)
		(layer "In9.Cu")
		(net "NIC_MDI_MNG_RX_DN")
	)
	(segment
		(start 330.898754 -13.694664)
		(end 330.898754 -12.558522)
		(width 0.101346)
		(layer "In9.Cu")
		(net "NIC_MDI_MNG_RX_DN")
	)
	(segment
		(start 185.999882 -5.994908)
		(end 184.239408 -7.755382)
		(width 0.101346)
		(layer "In9.Cu")
		(net "NIC_MDI_MNG_RX_DN")
	)
	(segment
		(start 465.64169 0.0254)
		(end 462.904078 2.763012)
		(width 0.101346)
		(layer "In9.Cu")
		(net "NIC_MDI_MNG_RX_DN")
	)
	(segment
		(start 399.170144 -0.3302)
		(end 398.662144 0.1778)
		(width 0.101346)
		(layer "In9.Cu")
		(net "NIC_MDI_MNG_RX_DN")
	)
	(segment
		(start 1.209548 -32.344106)
		(end 1.209548 -32.200596)
		(width 0.101346)
		(layer "In9.Cu")
		(net "NIC_MDI_MNG_RX_DN")
	)
	(segment
		(start 362.567982 -20.19427)
		(end 362.567982 -22.715474)
		(width 0.101346)
		(layer "In9.Cu")
		(net "NIC_MDI_MNG_RX_DN")
	)
	(segment
		(start 410.654246 1.841754)
		(end 406.12441 1.841754)
		(width 0.101346)
		(layer "In9.Cu")
		(net "NIC_MDI_MNG_RX_DN")
	)
	(segment
		(start 172.960538 -8.673846)
		(end 171.509944 -10.12444)
		(width 0.101346)
		(layer "In9.Cu")
		(net "NIC_MDI_MNG_RX_DN")
	)
	(segment
		(start 357.669846 -33.077658)
		(end 357.669846 -33.532064)
		(width 0.101346)
		(layer "In9.Cu")
		(net "NIC_MDI_MNG_RX_DN")
	)
	(segment
		(start 95.979996 -5.380228)
		(end 95.306134 -6.05409)
		(width 0.101346)
		(layer "In9.Cu")
		(net "NIC_MDI_MNG_RX_DN")
	)
	(segment
		(start 176.271682 -8.673846)
		(end 172.960538 -8.673846)
		(width 0.101346)
		(layer "In9.Cu")
		(net "NIC_MDI_MNG_RX_DN")
	)
	(segment
		(start 366.268 -11.17981)
		(end 363.58576 -13.86205)
		(width 0.101346)
		(layer "In9.Cu")
		(net "NIC_MDI_MNG_RX_DN")
	)
	(segment
		(start 159.577024 -8.858758)
		(end 156.101288 -5.383022)
		(width 0.101346)
		(layer "In9.Cu")
		(net "NIC_MDI_MNG_RX_DN")
	)
	(segment
		(start 259.291328 -4.922266)
		(end 193.787776 -4.922266)
		(width 0.101346)
		(layer "In9.Cu")
		(net "NIC_MDI_MNG_RX_DN")
	)
	(segment
		(start 191.079882 -6.55193)
		(end 190.52286 -5.994908)
		(width 0.101346)
		(layer "In9.Cu")
		(net "NIC_MDI_MNG_RX_DN")
	)
	(segment
		(start 27.750262 -5.558536)
		(end 14.25829 -5.558536)
		(width 0.101346)
		(layer "In9.Cu")
		(net "NIC_MDI_MNG_RX_DN")
	)
	(segment
		(start 332.223618 -15.019528)
		(end 330.898754 -13.694664)
		(width 0.101346)
		(layer "In9.Cu")
		(net "NIC_MDI_MNG_RX_DN")
	)
	(segment
		(start 381.926846 -1.231138)
		(end 381.9271 -1.231392)
		(width 0.101346)
		(layer "In9.Cu")
		(net "NIC_MDI_MNG_RX_DN")
	)
	(segment
		(start 97.679256 -5.581142)
		(end 97.478342 -5.380228)
		(width 0.101346)
		(layer "In9.Cu")
		(net "NIC_MDI_MNG_RX_DN")
	)
	(segment
		(start 368.015774 -6.71957)
		(end 367.044478 -7.690866)
		(width 0.101346)
		(layer "In9.Cu")
		(net "NIC_MDI_MNG_RX_DN")
	)
	(segment
		(start 177.190146 -7.755382)
		(end 176.271682 -8.673846)
		(width 0.101346)
		(layer "In9.Cu")
		(net "NIC_MDI_MNG_RX_DN")
	)
	(segment
		(start 329.694032 -11.3538)
		(end 328.50963 -11.3538)
		(width 0.101346)
		(layer "In9.Cu")
		(net "NIC_MDI_MNG_RX_DN")
	)
	(segment
		(start 262.845042 -6.013958)
		(end 262.1788 -6.6802)
		(width 0.101346)
		(layer "In9.Cu")
		(net "NIC_MDI_MNG_RX_DN")
	)
	(segment
		(start 332.223618 -16.058642)
		(end 332.223618 -15.019528)
		(width 0.101346)
		(layer "In9.Cu")
		(net "NIC_MDI_MNG_RX_DN")
	)
	(segment
		(start 11.197336 -23.576534)
		(end 10.314432 -24.459438)
		(width 0.101346)
		(layer "In9.Cu")
		(net "NIC_MDI_MNG_RX_DN")
	)
	(segment
		(start 403.952456 -0.3302)
		(end 399.170144 -0.3302)
		(width 0.101346)
		(layer "In9.Cu")
		(net "NIC_MDI_MNG_RX_DN")
	)
	(segment
		(start 381.9271 -0.440182)
		(end 381.9271 -0.546608)
		(width 0.101346)
		(layer "In9.Cu")
		(net "NIC_MDI_MNG_RX_DN")
	)
	(segment
		(start 190.52286 -5.994908)
		(end 185.999882 -5.994908)
		(width 0.101346)
		(layer "In9.Cu")
		(net "NIC_MDI_MNG_RX_DN")
	)
	(segment
		(start 411.01137 1.48463)
		(end 410.654246 1.841754)
		(width 0.101346)
		(layer "In9.Cu")
		(net "NIC_MDI_MNG_RX_DN")
	)
	(segment
		(start 332.909672 -33.393888)
		(end 332.909672 -25.671272)
		(width 0.101346)
		(layer "In9.Cu")
		(net "NIC_MDI_MNG_RX_DN")
	)
	(segment
		(start 474.118686 -4.148582)
		(end 471.682318 -4.148582)
		(width 0.101346)
		(layer "In9.Cu")
		(net "NIC_MDI_MNG_RX_DN")
	)
	(segment
		(start 11.7856 -8.031226)
		(end 11.7856 -21.60651)
		(width 0.101346)
		(layer "In9.Cu")
		(net "NIC_MDI_MNG_RX_DN")
	)
	(segment
		(start 467.054946 0.0254)
		(end 465.64169 0.0254)
		(width 0.101346)
		(layer "In9.Cu")
		(net "NIC_MDI_MNG_RX_DN")
	)
	(segment
		(start 10.314432 -30.701488)
		(end 8.570468 -32.445452)
		(width 0.101346)
		(layer "In9.Cu")
		(net "NIC_MDI_MNG_RX_DN")
	)
	(segment
		(start 161.071814 -10.580878)
		(end 159.577024 -9.086088)
		(width 0.101346)
		(layer "In9.Cu")
		(net "NIC_MDI_MNG_RX_DN")
	)
	(segment
		(start 184.239408 -7.755382)
		(end 177.190146 -7.755382)
		(width 0.101346)
		(layer "In9.Cu")
		(net "NIC_MDI_MNG_RX_DN")
	)
	(segment
		(start 331.824838 -24.586438)
		(end 331.824838 -21.224494)
		(width 0.101346)
		(layer "In9.Cu")
		(net "NIC_MDI_MNG_RX_DN")
	)
	(segment
		(start 165.9509 -10.12444)
		(end 165.494462 -10.580878)
		(width 0.101346)
		(layer "In9.Cu")
		(net "NIC_MDI_MNG_RX_DN")
	)
	(segment
		(start 10.314432 -24.459438)
		(end 10.314432 -30.701488)
		(width 0.101346)
		(layer "In9.Cu")
		(net "NIC_MDI_MNG_RX_DN")
	)
	(segment
		(start 471.682318 -4.148582)
		(end 469.90635 -2.372614)
		(width 0.101346)
		(layer "In9.Cu")
		(net "NIC_MDI_MNG_RX_DN")
	)
	(segment
		(start 381.9271 -3.645154)
		(end 378.852684 -6.71957)
		(width 0.101346)
		(layer "In9.Cu")
		(net "NIC_MDI_MNG_RX_DN")
	)
	(segment
		(start 362.567982 -22.715474)
		(end 359.965752 -25.317704)
		(width 0.101346)
		(layer "In9.Cu")
		(net "NIC_MDI_MNG_RX_DN")
	)
	(segment
		(start 422.016936 1.48463)
		(end 411.01137 1.48463)
		(width 0.101346)
		(layer "In9.Cu")
		(net "NIC_MDI_MNG_RX_DN")
	)
	(segment
		(start 398.662144 0.1778)
		(end 382.545082 0.1778)
		(width 0.101346)
		(layer "In9.Cu")
		(net "NIC_MDI_MNG_RX_DN")
	)
	(segment
		(start 95.306134 -6.05409)
		(end 28.245816 -6.05409)
		(width 0.101346)
		(layer "In9.Cu")
		(net "NIC_MDI_MNG_RX_DN")
	)
	(segment
		(start 99.560888 -5.383022)
		(end 99.362768 -5.581142)
		(width 0.101346)
		(layer "In9.Cu")
		(net "NIC_MDI_MNG_RX_DN")
	)
	(segment
		(start 359.965752 -25.317704)
		(end 359.965752 -30.781752)
		(width 0.101346)
		(layer "In9.Cu")
		(net "NIC_MDI_MNG_RX_DN")
	)
	(segment
		(start 428.525432 2.763012)
		(end 426.372528 0.610108)
		(width 0.101346)
		(layer "In9.Cu")
		(net "NIC_MDI_MNG_RX_DN")
	)
	(segment
		(start 382.545082 0.1778)
		(end 381.9271 -0.440182)
		(width 0.101346)
		(layer "In9.Cu")
		(net "NIC_MDI_MNG_RX_DN")
	)
	(segment
		(start 366.513364 -9.341866)
		(end 366.268 -9.58723)
		(width 0.101346)
		(layer "In9.Cu")
		(net "NIC_MDI_MNG_RX_DN")
	)
	(segment
		(start 422.891458 0.610108)
		(end 422.016936 1.48463)
		(width 0.101346)
		(layer "In9.Cu")
		(net "NIC_MDI_MNG_RX_DN")
	)
	(segment
		(start 331.824838 -21.224494)
		(end 330.841858 -20.241514)
		(width 0.101346)
		(layer "In9.Cu")
		(net "NIC_MDI_MNG_RX_DN")
	)
	(segment
		(start 355.807264 -35.394646)
		(end 334.91043 -35.394646)
		(width 0.101346)
		(layer "In9.Cu")
		(net "NIC_MDI_MNG_RX_DN")
	)
	(segment
		(start 381.926846 -0.546862)
		(end 381.926846 -1.231138)
		(width 0.101346)
		(layer "In9.Cu")
		(net "NIC_MDI_MNG_RX_DN")
	)
	(segment
		(start 366.268 -9.58723)
		(end 366.268 -11.17981)
		(width 0.101346)
		(layer "In9.Cu")
		(net "NIC_MDI_MNG_RX_DN")
	)
	(segment
		(start 462.904078 2.763012)
		(end 428.525432 2.763012)
		(width 0.101346)
		(layer "In9.Cu")
		(net "NIC_MDI_MNG_RX_DN")
	)
	(segment
		(start 261.468362 -7.0993)
		(end 259.291328 -4.922266)
		(width 0.101346)
		(layer "In9.Cu")
		(net "NIC_MDI_MNG_RX_DN")
	)
	(segment
		(start 193.787776 -4.922266)
		(end 192.158112 -6.55193)
		(width 0.101346)
		(layer "In9.Cu")
		(net "NIC_MDI_MNG_RX_DN")
	)
	(segment
		(start 1.310894 -32.445452)
		(end 1.209548 -32.344106)
		(width 0.101346)
		(layer "In9.Cu")
		(net "NIC_MDI_MNG_RX_DN")
	)
	(segment
		(start 8.570468 -32.445452)
		(end 1.310894 -32.445452)
		(width 0.101346)
		(layer "In9.Cu")
		(net "NIC_MDI_MNG_RX_DN")
	)
	(segment
		(start 359.965752 -30.781752)
		(end 357.669846 -33.077658)
		(width 0.101346)
		(layer "In9.Cu")
		(net "NIC_MDI_MNG_RX_DN")
	)
	(segment
		(start 378.852684 -6.71957)
		(end 368.015774 -6.71957)
		(width 0.101346)
		(layer "In9.Cu")
		(net "NIC_MDI_MNG_RX_DN")
	)
	(segment
		(start 366.513364 -9.341612)
		(end 366.513364 -9.341866)
		(width 0.101346)
		(layer "In9.Cu")
		(net "NIC_MDI_MNG_RX_DN")
	)
	(segment
		(start 330.898754 -12.558522)
		(end 329.694032 -11.3538)
		(width 0.101346)
		(layer "In9.Cu")
		(net "NIC_MDI_MNG_RX_DN")
	)
	(segment
		(start 330.841858 -20.241514)
		(end 330.841858 -17.440402)
		(width 0.101346)
		(layer "In9.Cu")
		(net "NIC_MDI_MNG_RX_DN")
	)
	(segment
		(start 367.044478 -7.690866)
		(end 367.044478 -8.810752)
		(width 0.101346)
		(layer "In9.Cu")
		(net "NIC_MDI_MNG_RX_DN")
	)
	(segment
		(start 328.50963 -11.3538)
		(end 327.942448 -10.786618)
		(width 0.101346)
		(layer "In9.Cu")
		(net "NIC_MDI_MNG_RX_DN")
	)
	(segment
		(start 363.58576 -19.176492)
		(end 362.567982 -20.19427)
		(width 0.101346)
		(layer "In9.Cu")
		(net "NIC_MDI_MNG_RX_DN")
	)
	(segment
		(start 14.25829 -5.558536)
		(end 11.7856 -8.031226)
		(width 0.101346)
		(layer "In9.Cu")
		(net "NIC_MDI_MNG_RX_DN")
	)
	(segment
		(start 469.90635 -2.372614)
		(end 469.45296 -2.372614)
		(width 0.101346)
		(layer "In9.Cu")
		(net "NIC_MDI_MNG_RX_DN")
	)
	(segment
		(start 159.577024 -9.086088)
		(end 159.577024 -8.858758)
		(width 0.101346)
		(layer "In9.Cu")
		(net "NIC_MDI_MNG_RX_DN")
	)
	(segment
		(start 327.942448 -10.786618)
		(end 325.692516 -10.786618)
		(width 0.101346)
		(layer "In9.Cu")
		(net "NIC_MDI_MNG_RX_DN")
	)
	(segment
		(start 474.544644 -3.722624)
		(end 474.118686 -4.148582)
		(width 0.101346)
		(layer "In9.Cu")
		(net "NIC_MDI_MNG_RX_DN")
	)
	(segment
		(start 171.509944 -10.12444)
		(end 165.9509 -10.12444)
		(width 0.101346)
		(layer "In9.Cu")
		(net "NIC_MDI_MNG_RX_DN")
	)
	(segment
		(start 330.841858 -17.440402)
		(end 332.223618 -16.058642)
		(width 0.101346)
		(layer "In9.Cu")
		(net "NIC_MDI_MNG_RX_DN")
	)
	(segment
		(start 324.229476 -7.327646)
		(end 322.915788 -6.013958)
		(width 0.101346)
		(layer "In9.Cu")
		(net "NIC_MDI_MNG_RX_DN")
	)
	(segment
		(start 469.45296 -2.372614)
		(end 467.054946 0.0254)
		(width 0.101346)
		(layer "In9.Cu")
		(net "NIC_MDI_MNG_RX_DN")
	)
	(segment
		(start 426.372528 0.610108)
		(end 422.891458 0.610108)
		(width 0.101346)
		(layer "In9.Cu")
		(net "NIC_MDI_MNG_RX_DN")
	)
	(segment
		(start 99.362768 -5.581142)
		(end 97.679256 -5.581142)
		(width 0.101346)
		(layer "In9.Cu")
		(net "NIC_MDI_MNG_RX_DN")
	)
	(segment
		(start 381.9271 -1.231392)
		(end 381.9271 -3.645154)
		(width 0.101346)
		(layer "In9.Cu")
		(net "NIC_MDI_MNG_RX_DN")
	)
	(segment
		(start 406.12441 1.841754)
		(end 403.952456 -0.3302)
		(width 0.101346)
		(layer "In9.Cu")
		(net "NIC_MDI_MNG_RX_DN")
	)
	(segment
		(start 165.494462 -10.580878)
		(end 161.071814 -10.580878)
		(width 0.101346)
		(layer "In9.Cu")
		(net "NIC_MDI_MNG_RX_DN")
	)
	(segment
		(start 262.1788 -6.6802)
		(end 262.1788 -6.92023)
		(width 0.101346)
		(layer "In9.Cu")
		(net "NIC_MDI_MNG_RX_DN")
	)
	(segment
		(start 11.7856 -21.60651)
		(end 11.197336 -22.194774)
		(width 0.101346)
		(layer "In9.Cu")
		(net "NIC_MDI_MNG_RX_DN")
	)
	(segment
		(start 381.9271 -0.546608)
		(end 381.926846 -0.546862)
		(width 0.101346)
		(layer "In9.Cu")
		(net "NIC_MDI_MNG_RX_DN")
	)
	(segment
		(start 28.245816 -6.05409)
		(end 27.750262 -5.558536)
		(width 0.101346)
		(layer "In9.Cu")
		(net "NIC_MDI_MNG_RX_DN")
	)
	(segment
		(start 332.909672 -25.671272)
		(end 331.824838 -24.586438)
		(width 0.101346)
		(layer "In9.Cu")
		(net "NIC_MDI_MNG_RX_DN")
	)
	(segment
		(start 325.692516 -10.786618)
		(end 324.229476 -9.323578)
		(width 0.101346)
		(layer "In9.Cu")
		(net "NIC_MDI_MNG_RX_DN")
	)
	(segment
		(start 11.197336 -22.194774)
		(end 11.197336 -23.576534)
		(width 0.101346)
		(layer "In9.Cu")
		(net "NIC_MDI_MNG_RX_DN")
	)
	(segment
		(start 192.158112 -6.55193)
		(end 191.079882 -6.55193)
		(width 0.101346)
		(layer "In9.Cu")
		(net "NIC_MDI_MNG_RX_DN")
	)
	(segment
		(start 324.229476 -9.323578)
		(end 324.229476 -7.327646)
		(width 0.101346)
		(layer "In9.Cu")
		(net "NIC_MDI_MNG_RX_DN")
	)
	(segment
		(start 357.669846 -33.532064)
		(end 355.807264 -35.394646)
		(width 0.101346)
		(layer "In9.Cu")
		(net "NIC_MDI_MNG_RX_DN")
	)
	(segment
		(start 97.478342 -5.380228)
		(end 95.979996 -5.380228)
		(width 0.101346)
		(layer "In9.Cu")
		(net "NIC_MDI_MNG_RX_DN")
	)
	(segment
		(start 474.544644 -3.263392)
		(end 474.544644 -3.722624)
		(width 0.101346)
		(layer "In9.Cu")
		(net "NIC_MDI_MNG_RX_DN")
	)
	(segment
		(start 262.1788 -6.92023)
		(end 261.99973 -7.0993)
		(width 0.101346)
		(layer "In9.Cu")
		(net "NIC_MDI_MNG_RX_DN")
	)
	(segment
		(start 367.044478 -8.810752)
		(end 366.513618 -9.341612)
		(width 0.101346)
		(layer "In9.Cu")
		(net "NIC_MDI_MNG_RX_DN")
	)
	(segment
		(start 379.81255 -95.888556)
		(end 379.31725 -96.11868)
		(width 0.10795)
		(layer "F.Cu")
		(net "TP_CPU_PCH_TRIGGER_IN")
	)
	(via
		(at 379.81255 -95.888556)
		(size 0.508)
		(drill 0.254)
		(layers "F.Cu" "B.Cu")
		(net "TP_CPU_PCH_TRIGGER_IN")
	)
	(segment
		(start 454.914 -35.45205)
		(end 454.914 -34.671)
		(width 0.10795)
		(layer "F.Cu")
		(net "FM_HEARTBEAT_LED_K")
	)
	(segment
		(start 454.914 -34.671)
		(end 454.66 -34.417)
		(width 0.10795)
		(layer "F.Cu")
		(net "FM_HEARTBEAT_LED_K")
	)
	(segment
		(start 456.70597 -35.418776)
		(end 456.564746 -35.56)
		(width 0.10795)
		(layer "F.Cu")
		(net "FM_HEARTBEAT_LED_K")
	)
	(segment
		(start 456.70597 -34.744406)
		(end 456.70597 -35.418776)
		(width 0.10795)
		(layer "F.Cu")
		(net "FM_HEARTBEAT_LED_K")
	)
	(segment
		(start 454.66 -34.417)
		(end 453.898 -34.417)
		(width 0.10795)
		(layer "F.Cu")
		(net "FM_HEARTBEAT_LED_K")
	)
	(segment
		(start 455.02195 -35.56)
		(end 454.914 -35.45205)
		(width 0.10795)
		(layer "F.Cu")
		(net "FM_HEARTBEAT_LED_K")
	)
	(segment
		(start 456.564746 -35.56)
		(end 455.02195 -35.56)
		(width 0.10795)
		(layer "F.Cu")
		(net "FM_HEARTBEAT_LED_K")
	)
	(segment
		(start 454.025 -37.846)
		(end 454.025 -37.4269)
		(width 0.10795)
		(layer "F.Cu")
		(net "FM_HEARTBEAT_LED_A")
	)
	(segment
		(start 453.898 -37.2999)
		(end 453.898 -36.449)
		(width 0.10795)
		(layer "F.Cu")
		(net "FM_HEARTBEAT_LED_A")
	)
	(segment
		(start 454.025 -37.4269)
		(end 453.898 -37.2999)
		(width 0.10795)
		(layer "F.Cu")
		(net "FM_HEARTBEAT_LED_A")
	)
	(segment
		(start 460.4258 -33.852358)
		(end 461.234282 -33.852358)
		(width 0.10795)
		(layer "F.Cu")
		(net "FM_BOARD_SKU_ID3")
	)
	(segment
		(start 423.890186 -29.734764)
		(end 424.290236 -29.334714)
		(width 0.10795)
		(layer "F.Cu")
		(net "FM_BOARD_SKU_ID3")
	)
	(segment
		(start 394.67155 -101.039676)
		(end 394.17625 -101.2698)
		(width 0.10795)
		(layer "F.Cu")
		(net "FM_BOARD_SKU_ID3")
	)
	(via
		(at 394.67155 -101.039676)
		(size 0.508)
		(drill 0.254)
		(layers "F.Cu" "B.Cu")
		(net "FM_BOARD_SKU_ID3")
	)
	(via
		(at 424.290236 -29.334714)
		(size 0.4572)
		(drill 0.2032)
		(layers "F.Cu" "B.Cu")
		(net "FM_BOARD_SKU_ID3")
	)
	(via
		(at 460.4258 -33.852358)
		(size 0.762)
		(drill 0.381)
		(layers "F.Cu" "B.Cu")
		(net "FM_BOARD_SKU_ID3")
	)
	(via
		(at 461.234282 -33.852358)
		(size 0.508)
		(drill 0.254)
		(layers "F.Cu" "B.Cu")
		(net "FM_BOARD_SKU_ID3")
	)
	(segment
		(start 460.0956 -34.2392)
		(end 460.0956 -34.9504)
		(width 0.10795)
		(layer "B.Cu")
		(net "FM_BOARD_SKU_ID3")
	)
	(segment
		(start 460.0956 -35.7124)
		(end 460.0956 -34.9504)
		(width 0.10795)
		(layer "B.Cu")
		(net "FM_BOARD_SKU_ID3")
	)
	(segment
		(start 461.234282 -33.852358)
		(end 460.482442 -33.852358)
		(width 0.10795)
		(layer "B.Cu")
		(net "FM_BOARD_SKU_ID3")
	)
	(segment
		(start 460.482442 -33.852358)
		(end 460.0956 -34.2392)
		(width 0.10795)
		(layer "B.Cu")
		(net "FM_BOARD_SKU_ID3")
	)
	(segment
		(start 412.329884 -63.358014)
		(end 412.329884 -63.200026)
		(width 0.089408)
		(layer "In9.Cu")
		(net "FM_BOARD_SKU_ID3")
	)
	(segment
		(start 393.2301 -99.572572)
		(end 393.2301 -99.209352)
		(width 0.089408)
		(layer "In9.Cu")
		(net "FM_BOARD_SKU_ID3")
	)
	(segment
		(start 394.27277 -96.05391)
		(end 394.27277 -95.723202)
		(width 0.089408)
		(layer "In9.Cu")
		(net "FM_BOARD_SKU_ID3")
	)
	(segment
		(start 412.329884 -63.200026)
		(end 412.330138 -63.199772)
		(width 0.089408)
		(layer "In9.Cu")
		(net "FM_BOARD_SKU_ID3")
	)
	(segment
		(start 450.608192 -44.583096)
		(end 450.6214 -44.569888)
		(width 0.089408)
		(layer "In9.Cu")
		(net "FM_BOARD_SKU_ID3")
	)
	(segment
		(start 412.32963 -63.358268)
		(end 412.329884 -63.358014)
		(width 0.089408)
		(layer "In9.Cu")
		(net "FM_BOARD_SKU_ID3")
	)
	(segment
		(start 450.6214 -44.569888)
		(end 450.6214 -44.5262)
		(width 0.089408)
		(layer "In9.Cu")
		(net "FM_BOARD_SKU_ID3")
	)
	(segment
		(start 412.438342 -56.974232)
		(end 412.816294 -56.59628)
		(width 0.089408)
		(layer "In9.Cu")
		(net "FM_BOARD_SKU_ID3")
	)
	(segment
		(start 398.06499 -91.858338)
		(end 403.076156 -86.847172)
		(width 0.089408)
		(layer "In9.Cu")
		(net "FM_BOARD_SKU_ID3")
	)
	(segment
		(start 418.994336 -52.948332)
		(end 420.13378 -51.808888)
		(width 0.089408)
		(layer "In9.Cu")
		(net "FM_BOARD_SKU_ID3")
	)
	(segment
		(start 416.140392 -54.30139)
		(end 417.49345 -52.948332)
		(width 0.089408)
		(layer "In9.Cu")
		(net "FM_BOARD_SKU_ID3")
	)
	(segment
		(start 411.83941 -68.06057)
		(end 411.83941 -68.043552)
		(width 0.089408)
		(layer "In9.Cu")
		(net "FM_BOARD_SKU_ID3")
	)
	(segment
		(start 420.13378 -51.808888)
		(end 421.92575 -51.808888)
		(width 0.089408)
		(layer "In9.Cu")
		(net "FM_BOARD_SKU_ID3")
	)
	(segment
		(start 394.27277 -95.723202)
		(end 394.506196 -95.489776)
		(width 0.089408)
		(layer "In9.Cu")
		(net "FM_BOARD_SKU_ID3")
	)
	(segment
		(start 451.085458 -44.062142)
		(end 452.517256 -44.062142)
		(width 0.089408)
		(layer "In9.Cu")
		(net "FM_BOARD_SKU_ID3")
	)
	(segment
		(start 394.67155 -101.039676)
		(end 394.228574 -100.5967)
		(width 0.089408)
		(layer "In9.Cu")
		(net "FM_BOARD_SKU_ID3")
	)
	(segment
		(start 456.866752 -42.196766)
		(end 456.866752 -36.356544)
		(width 0.089408)
		(layer "In9.Cu")
		(net "FM_BOARD_SKU_ID3")
	)
	(segment
		(start 397.5354 -92.206318)
		(end 397.88338 -91.858338)
		(width 0.089408)
		(layer "In9.Cu")
		(net "FM_BOARD_SKU_ID3")
	)
	(segment
		(start 394.228574 -100.5967)
		(end 393.03706 -100.5967)
		(width 0.089408)
		(layer "In9.Cu")
		(net "FM_BOARD_SKU_ID3")
	)
	(segment
		(start 412.330138 -63.199772)
		(end 412.330138 -63.041784)
		(width 0.089408)
		(layer "In9.Cu")
		(net "FM_BOARD_SKU_ID3")
	)
	(segment
		(start 403.076156 -86.5632)
		(end 405.43226 -84.207096)
		(width 0.089408)
		(layer "In9.Cu")
		(net "FM_BOARD_SKU_ID3")
	)
	(segment
		(start 433.004976 -49.772316)
		(end 434.898292 -47.879)
		(width 0.089408)
		(layer "In9.Cu")
		(net "FM_BOARD_SKU_ID3")
	)
	(segment
		(start 411.075378 -69.787262)
		(end 411.246828 -69.615812)
		(width 0.089408)
		(layer "In9.Cu")
		(net "FM_BOARD_SKU_ID3")
	)
	(segment
		(start 411.246828 -68.653152)
		(end 411.83941 -68.06057)
		(width 0.089408)
		(layer "In9.Cu")
		(net "FM_BOARD_SKU_ID3")
	)
	(segment
		(start 450.6214 -44.5262)
		(end 451.085458 -44.062142)
		(width 0.089408)
		(layer "In9.Cu")
		(net "FM_BOARD_SKU_ID3")
	)
	(segment
		(start 422.630346 -50.433478)
		(end 423.936922 -50.433478)
		(width 0.089408)
		(layer "In9.Cu")
		(net "FM_BOARD_SKU_ID3")
	)
	(segment
		(start 414.127442 -56.59628)
		(end 414.236154 -56.487568)
		(width 0.089408)
		(layer "In9.Cu")
		(net "FM_BOARD_SKU_ID3")
	)
	(segment
		(start 411.84957 -60.241688)
		(end 411.699456 -60.091574)
		(width 0.089408)
		(layer "In9.Cu")
		(net "FM_BOARD_SKU_ID3")
	)
	(segment
		(start 412.330138 -63.041784)
		(end 411.84957 -62.561216)
		(width 0.089408)
		(layer "In9.Cu")
		(net "FM_BOARD_SKU_ID3")
	)
	(segment
		(start 434.898292 -47.879)
		(end 437.592978 -47.879)
		(width 0.089408)
		(layer "In9.Cu")
		(net "FM_BOARD_SKU_ID3")
	)
	(segment
		(start 392.78687 -100.015802)
		(end 393.2301 -99.572572)
		(width 0.089408)
		(layer "In9.Cu")
		(net "FM_BOARD_SKU_ID3")
	)
	(segment
		(start 414.679892 -56.487568)
		(end 416.140392 -55.027068)
		(width 0.089408)
		(layer "In9.Cu")
		(net "FM_BOARD_SKU_ID3")
	)
	(segment
		(start 417.49345 -52.948332)
		(end 418.994336 -52.948332)
		(width 0.089408)
		(layer "In9.Cu")
		(net "FM_BOARD_SKU_ID3")
	)
	(segment
		(start 410.613606 -70.24878)
		(end 411.075124 -69.787262)
		(width 0.089408)
		(layer "In9.Cu")
		(net "FM_BOARD_SKU_ID3")
	)
	(segment
		(start 459.068678 -36.0426)
		(end 461.234282 -33.876996)
		(width 0.089408)
		(layer "In9.Cu")
		(net "FM_BOARD_SKU_ID3")
	)
	(segment
		(start 438.86501 -46.606968)
		(end 449.9864 -46.606968)
		(width 0.089408)
		(layer "In9.Cu")
		(net "FM_BOARD_SKU_ID3")
	)
	(segment
		(start 411.83941 -68.043552)
		(end 411.84957 -68.033392)
		(width 0.089408)
		(layer "In9.Cu")
		(net "FM_BOARD_SKU_ID3")
	)
	(segment
		(start 397.88338 -91.858338)
		(end 398.06499 -91.858338)
		(width 0.089408)
		(layer "In9.Cu")
		(net "FM_BOARD_SKU_ID3")
	)
	(segment
		(start 452.517256 -44.062142)
		(end 452.80072 -43.778678)
		(width 0.089408)
		(layer "In9.Cu")
		(net "FM_BOARD_SKU_ID3")
	)
	(segment
		(start 456.866752 -36.356544)
		(end 457.180696 -36.0426)
		(width 0.089408)
		(layer "In9.Cu")
		(net "FM_BOARD_SKU_ID3")
	)
	(segment
		(start 412.32963 -66.183002)
		(end 412.32963 -63.358268)
		(width 0.089408)
		(layer "In9.Cu")
		(net "FM_BOARD_SKU_ID3")
	)
	(segment
		(start 422.354756 -50.709068)
		(end 422.630346 -50.433478)
		(width 0.089408)
		(layer "In9.Cu")
		(net "FM_BOARD_SKU_ID3")
	)
	(segment
		(start 394.2969 -98.9076)
		(end 394.57503 -98.62947)
		(width 0.089408)
		(layer "In9.Cu")
		(net "FM_BOARD_SKU_ID3")
	)
	(segment
		(start 411.246828 -69.615812)
		(end 411.246828 -68.653152)
		(width 0.089408)
		(layer "In9.Cu")
		(net "FM_BOARD_SKU_ID3")
	)
	(segment
		(start 452.80072 -43.778678)
		(end 453.914002 -43.778678)
		(width 0.089408)
		(layer "In9.Cu")
		(net "FM_BOARD_SKU_ID3")
	)
	(segment
		(start 457.180696 -36.0426)
		(end 459.068678 -36.0426)
		(width 0.089408)
		(layer "In9.Cu")
		(net "FM_BOARD_SKU_ID3")
	)
	(segment
		(start 456.189334 -42.874184)
		(end 456.866752 -42.196766)
		(width 0.089408)
		(layer "In9.Cu")
		(net "FM_BOARD_SKU_ID3")
	)
	(segment
		(start 412.438342 -57.648094)
		(end 412.438342 -56.974232)
		(width 0.089408)
		(layer "In9.Cu")
		(net "FM_BOARD_SKU_ID3")
	)
	(segment
		(start 414.236154 -56.487568)
		(end 414.679892 -56.487568)
		(width 0.089408)
		(layer "In9.Cu")
		(net "FM_BOARD_SKU_ID3")
	)
	(segment
		(start 427.2788 -49.34966)
		(end 427.701456 -49.772316)
		(width 0.089408)
		(layer "In9.Cu")
		(net "FM_BOARD_SKU_ID3")
	)
	(segment
		(start 450.608192 -45.985176)
		(end 450.608192 -44.583096)
		(width 0.089408)
		(layer "In9.Cu")
		(net "FM_BOARD_SKU_ID3")
	)
	(segment
		(start 394.506196 -95.489776)
		(end 394.516864 -95.489776)
		(width 0.089408)
		(layer "In9.Cu")
		(net "FM_BOARD_SKU_ID3")
	)
	(segment
		(start 405.192484 -74.957686)
		(end 409.90139 -70.24878)
		(width 0.089408)
		(layer "In9.Cu")
		(net "FM_BOARD_SKU_ID3")
	)
	(segment
		(start 454.818496 -42.874184)
		(end 456.189334 -42.874184)
		(width 0.089408)
		(layer "In9.Cu")
		(net "FM_BOARD_SKU_ID3")
	)
	(segment
		(start 421.92575 -51.808888)
		(end 422.354756 -51.379882)
		(width 0.089408)
		(layer "In9.Cu")
		(net "FM_BOARD_SKU_ID3")
	)
	(segment
		(start 393.03706 -100.5967)
		(end 392.78687 -100.34651)
		(width 0.089408)
		(layer "In9.Cu")
		(net "FM_BOARD_SKU_ID3")
	)
	(segment
		(start 411.84957 -68.033392)
		(end 411.84957 -66.663062)
		(width 0.089408)
		(layer "In9.Cu")
		(net "FM_BOARD_SKU_ID3")
	)
	(segment
		(start 405.43226 -84.207096)
		(end 405.43226 -78.877668)
		(width 0.089408)
		(layer "In9.Cu")
		(net "FM_BOARD_SKU_ID3")
	)
	(segment
		(start 423.936922 -50.433478)
		(end 425.02074 -49.34966)
		(width 0.089408)
		(layer "In9.Cu")
		(net "FM_BOARD_SKU_ID3")
	)
	(segment
		(start 411.699456 -58.38698)
		(end 412.438342 -57.648094)
		(width 0.089408)
		(layer "In9.Cu")
		(net "FM_BOARD_SKU_ID3")
	)
	(segment
		(start 409.90139 -70.24878)
		(end 410.613606 -70.24878)
		(width 0.089408)
		(layer "In9.Cu")
		(net "FM_BOARD_SKU_ID3")
	)
	(segment
		(start 393.2301 -99.209352)
		(end 393.531852 -98.9076)
		(width 0.089408)
		(layer "In9.Cu")
		(net "FM_BOARD_SKU_ID3")
	)
	(segment
		(start 427.701456 -49.772316)
		(end 433.004976 -49.772316)
		(width 0.089408)
		(layer "In9.Cu")
		(net "FM_BOARD_SKU_ID3")
	)
	(segment
		(start 411.84957 -66.663062)
		(end 412.32963 -66.183002)
		(width 0.089408)
		(layer "In9.Cu")
		(net "FM_BOARD_SKU_ID3")
	)
	(segment
		(start 422.354756 -51.379882)
		(end 422.354756 -50.709068)
		(width 0.089408)
		(layer "In9.Cu")
		(net "FM_BOARD_SKU_ID3")
	)
	(segment
		(start 453.914002 -43.778678)
		(end 454.818496 -42.874184)
		(width 0.089408)
		(layer "In9.Cu")
		(net "FM_BOARD_SKU_ID3")
	)
	(segment
		(start 449.9864 -46.606968)
		(end 450.608192 -45.985176)
		(width 0.089408)
		(layer "In9.Cu")
		(net "FM_BOARD_SKU_ID3")
	)
	(segment
		(start 403.076156 -86.847172)
		(end 403.076156 -86.5632)
		(width 0.089408)
		(layer "In9.Cu")
		(net "FM_BOARD_SKU_ID3")
	)
	(segment
		(start 411.699456 -60.091574)
		(end 411.699456 -58.38698)
		(width 0.089408)
		(layer "In9.Cu")
		(net "FM_BOARD_SKU_ID3")
	)
	(segment
		(start 405.192484 -78.637892)
		(end 405.192484 -74.957686)
		(width 0.089408)
		(layer "In9.Cu")
		(net "FM_BOARD_SKU_ID3")
	)
	(segment
		(start 437.592978 -47.879)
		(end 438.86501 -46.606968)
		(width 0.089408)
		(layer "In9.Cu")
		(net "FM_BOARD_SKU_ID3")
	)
	(segment
		(start 411.84957 -62.561216)
		(end 411.84957 -60.241688)
		(width 0.089408)
		(layer "In9.Cu")
		(net "FM_BOARD_SKU_ID3")
	)
	(segment
		(start 411.075124 -69.787262)
		(end 411.075378 -69.787262)
		(width 0.089408)
		(layer "In9.Cu")
		(net "FM_BOARD_SKU_ID3")
	)
	(segment
		(start 394.516864 -95.489776)
		(end 397.5354 -92.47124)
		(width 0.089408)
		(layer "In9.Cu")
		(net "FM_BOARD_SKU_ID3")
	)
	(segment
		(start 461.234282 -33.876996)
		(end 461.234282 -33.852358)
		(width 0.089408)
		(layer "In9.Cu")
		(net "FM_BOARD_SKU_ID3")
	)
	(segment
		(start 393.531852 -98.9076)
		(end 394.2969 -98.9076)
		(width 0.089408)
		(layer "In9.Cu")
		(net "FM_BOARD_SKU_ID3")
	)
	(segment
		(start 416.140392 -55.027068)
		(end 416.140392 -54.30139)
		(width 0.089408)
		(layer "In9.Cu")
		(net "FM_BOARD_SKU_ID3")
	)
	(segment
		(start 397.5354 -92.47124)
		(end 397.5354 -92.206318)
		(width 0.089408)
		(layer "In9.Cu")
		(net "FM_BOARD_SKU_ID3")
	)
	(segment
		(start 394.57503 -96.35617)
		(end 394.27277 -96.05391)
		(width 0.089408)
		(layer "In9.Cu")
		(net "FM_BOARD_SKU_ID3")
	)
	(segment
		(start 394.57503 -98.62947)
		(end 394.57503 -96.35617)
		(width 0.089408)
		(layer "In9.Cu")
		(net "FM_BOARD_SKU_ID3")
	)
	(segment
		(start 405.43226 -78.877668)
		(end 405.192484 -78.637892)
		(width 0.089408)
		(layer "In9.Cu")
		(net "FM_BOARD_SKU_ID3")
	)
	(segment
		(start 425.02074 -49.34966)
		(end 427.2788 -49.34966)
		(width 0.089408)
		(layer "In9.Cu")
		(net "FM_BOARD_SKU_ID3")
	)
	(segment
		(start 412.816294 -56.59628)
		(end 414.127442 -56.59628)
		(width 0.089408)
		(layer "In9.Cu")
		(net "FM_BOARD_SKU_ID3")
	)
	(segment
		(start 392.78687 -100.34651)
		(end 392.78687 -100.015802)
		(width 0.089408)
		(layer "In9.Cu")
		(net "FM_BOARD_SKU_ID3")
	)
	(segment
		(start 424.510708 -29.114242)
		(end 424.290236 -29.334714)
		(width 0.089408)
		(layer "In11.Cu")
		(net "FM_BOARD_SKU_ID3")
	)
	(segment
		(start 461.234282 -33.852358)
		(end 461.012794 -33.63087)
		(width 0.089408)
		(layer "In11.Cu")
		(net "FM_BOARD_SKU_ID3")
	)
	(segment
		(start 426.908214 -28.869386)
		(end 425.678854 -28.869386)
		(width 0.089408)
		(layer "In11.Cu")
		(net "FM_BOARD_SKU_ID3")
	)
	(segment
		(start 449.00215 -34.205418)
		(end 446.089532 -37.118036)
		(width 0.089408)
		(layer "In11.Cu")
		(net "FM_BOARD_SKU_ID3")
	)
	(segment
		(start 435.255416 -38.267132)
		(end 434.23078 -37.242496)
		(width 0.089408)
		(layer "In11.Cu")
		(net "FM_BOARD_SKU_ID3")
	)
	(segment
		(start 445.862456 -37.118036)
		(end 445.04737 -37.933122)
		(width 0.089408)
		(layer "In11.Cu")
		(net "FM_BOARD_SKU_ID3")
	)
	(segment
		(start 434.23078 -35.59556)
		(end 430.84496 -32.20974)
		(width 0.089408)
		(layer "In11.Cu")
		(net "FM_BOARD_SKU_ID3")
	)
	(segment
		(start 461.012794 -33.63087)
		(end 458.290422 -33.63087)
		(width 0.089408)
		(layer "In11.Cu")
		(net "FM_BOARD_SKU_ID3")
	)
	(segment
		(start 434.23078 -37.242496)
		(end 434.23078 -35.59556)
		(width 0.089408)
		(layer "In11.Cu")
		(net "FM_BOARD_SKU_ID3")
	)
	(segment
		(start 442.144658 -38.267132)
		(end 435.255416 -38.267132)
		(width 0.089408)
		(layer "In11.Cu")
		(net "FM_BOARD_SKU_ID3")
	)
	(segment
		(start 442.478668 -37.933122)
		(end 442.144658 -38.267132)
		(width 0.089408)
		(layer "In11.Cu")
		(net "FM_BOARD_SKU_ID3")
	)
	(segment
		(start 430.84496 -32.20974)
		(end 430.248568 -32.20974)
		(width 0.089408)
		(layer "In11.Cu")
		(net "FM_BOARD_SKU_ID3")
	)
	(segment
		(start 458.290422 -33.63087)
		(end 457.715874 -34.205418)
		(width 0.089408)
		(layer "In11.Cu")
		(net "FM_BOARD_SKU_ID3")
	)
	(segment
		(start 445.04737 -37.933122)
		(end 442.478668 -37.933122)
		(width 0.089408)
		(layer "In11.Cu")
		(net "FM_BOARD_SKU_ID3")
	)
	(segment
		(start 430.248568 -32.20974)
		(end 426.908214 -28.869386)
		(width 0.089408)
		(layer "In11.Cu")
		(net "FM_BOARD_SKU_ID3")
	)
	(segment
		(start 425.678854 -28.869386)
		(end 425.433998 -29.114242)
		(width 0.089408)
		(layer "In11.Cu")
		(net "FM_BOARD_SKU_ID3")
	)
	(segment
		(start 425.433998 -29.114242)
		(end 424.510708 -29.114242)
		(width 0.089408)
		(layer "In11.Cu")
		(net "FM_BOARD_SKU_ID3")
	)
	(segment
		(start 446.089532 -37.118036)
		(end 445.862456 -37.118036)
		(width 0.089408)
		(layer "In11.Cu")
		(net "FM_BOARD_SKU_ID3")
	)
	(segment
		(start 457.715874 -34.205418)
		(end 449.00215 -34.205418)
		(width 0.089408)
		(layer "In11.Cu")
		(net "FM_BOARD_SKU_ID3")
	)
	(segment
		(start 371.996462 -129.253488)
		(end 371.96395 -129.286)
		(width 0.10795)
		(layer "F.Cu")
		(net "FM_PCH_PRSNT_N")
	)
	(segment
		(start 377.589796 -67.850258)
		(end 377.145042 -68.295012)
		(width 0.1016)
		(layer "F.Cu")
		(net "FM_PCH_PRSNT_N")
	)
	(segment
		(start 374.682512 -128.38176)
		(end 374.245632 -128.81864)
		(width 0.10795)
		(layer "F.Cu")
		(net "FM_PCH_PRSNT_N")
	)
	(segment
		(start 375.487692 -125.486668)
		(end 375.001282 -125.973078)
		(width 0.10795)
		(layer "F.Cu")
		(net "FM_PCH_PRSNT_N")
	)
	(segment
		(start 374.245632 -128.81864)
		(end 373.89816 -128.81864)
		(width 0.10795)
		(layer "F.Cu")
		(net "FM_PCH_PRSNT_N")
	)
	(segment
		(start 372.010178 -129.239772)
		(end 371.996462 -129.253488)
		(width 0.10795)
		(layer "F.Cu")
		(net "FM_PCH_PRSNT_N")
	)
	(segment
		(start 373.89816 -128.81864)
		(end 373.477028 -129.239772)
		(width 0.10795)
		(layer "F.Cu")
		(net "FM_PCH_PRSNT_N")
	)
	(segment
		(start 371.96395 -129.286)
		(end 370.7384 -129.286)
		(width 0.10795)
		(layer "F.Cu")
		(net "FM_PCH_PRSNT_N")
	)
	(segment
		(start 375.487692 -125.352302)
		(end 375.487692 -125.486668)
		(width 0.10795)
		(layer "F.Cu")
		(net "FM_PCH_PRSNT_N")
	)
	(segment
		(start 373.477028 -129.239772)
		(end 372.010178 -129.239772)
		(width 0.10795)
		(layer "F.Cu")
		(net "FM_PCH_PRSNT_N")
	)
	(segment
		(start 375.001282 -126.234698)
		(end 374.682512 -126.553468)
		(width 0.10795)
		(layer "F.Cu")
		(net "FM_PCH_PRSNT_N")
	)
	(segment
		(start 374.682512 -126.553468)
		(end 374.682512 -128.38176)
		(width 0.10795)
		(layer "F.Cu")
		(net "FM_PCH_PRSNT_N")
	)
	(segment
		(start 375.001282 -125.973078)
		(end 375.001282 -126.234698)
		(width 0.10795)
		(layer "F.Cu")
		(net "FM_PCH_PRSNT_N")
	)
	(via
		(at 377.589796 -67.850258)
		(size 0.4572)
		(drill 0.2032)
		(layers "F.Cu" "B.Cu")
		(net "FM_PCH_PRSNT_N")
	)
	(via
		(at 371.996462 -129.253488)
		(size 0.508)
		(drill 0.254)
		(layers "F.Cu" "B.Cu")
		(net "FM_PCH_PRSNT_N")
	)
	(segment
		(start 378.844556 -112.932464)
		(end 377.92787 -113.84915)
		(width 0.089408)
		(layer "In9.Cu")
		(net "FM_PCH_PRSNT_N")
	)
	(segment
		(start 374.386348 -98.5266)
		(end 375.984008 -100.12426)
		(width 0.0889)
		(layer "In9.Cu")
		(net "FM_PCH_PRSNT_N")
	)
	(segment
		(start 375.518172 -75.249532)
		(end 375.270522 -75.497182)
		(width 0.089408)
		(layer "In9.Cu")
		(net "FM_PCH_PRSNT_N")
	)
	(segment
		(start 377.663202 -68.321936)
		(end 377.699524 -68.321936)
		(width 0.089408)
		(layer "In9.Cu")
		(net "FM_PCH_PRSNT_N")
	)
	(segment
		(start 379.71603 -105.13441)
		(end 379.71603 -105.594912)
		(width 0.089408)
		(layer "In9.Cu")
		(net "FM_PCH_PRSNT_N")
	)
	(segment
		(start 379.298708 -108.18368)
		(end 379.71603 -108.601002)
		(width 0.089408)
		(layer "In9.Cu")
		(net "FM_PCH_PRSNT_N")
	)
	(segment
		(start 375.984008 -100.642674)
		(end 376.297698 -100.956364)
		(width 0.0889)
		(layer "In9.Cu")
		(net "FM_PCH_PRSNT_N")
	)
	(segment
		(start 374.651778 -121.950988)
		(end 372.823232 -123.779534)
		(width 0.089408)
		(layer "In9.Cu")
		(net "FM_PCH_PRSNT_N")
	)
	(segment
		(start 377.191016 -121.48312)
		(end 377.127008 -121.547128)
		(width 0.089408)
		(layer "In9.Cu")
		(net "FM_PCH_PRSNT_N")
	)
	(segment
		(start 377.118118 -76.849478)
		(end 376.899424 -77.068172)
		(width 0.089408)
		(layer "In9.Cu")
		(net "FM_PCH_PRSNT_N")
	)
	(segment
		(start 377.118118 -69.649848)
		(end 376.899424 -69.868542)
		(width 0.089408)
		(layer "In9.Cu")
		(net "FM_PCH_PRSNT_N")
	)
	(segment
		(start 379.22073 -106.35615)
		(end 378.91847 -106.65841)
		(width 0.089408)
		(layer "In9.Cu")
		(net "FM_PCH_PRSNT_N")
	)
	(segment
		(start 377.613926 -119.520208)
		(end 377.613926 -119.576342)
		(width 0.089408)
		(layer "In9.Cu")
		(net "FM_PCH_PRSNT_N")
	)
	(segment
		(start 372.823232 -125.275594)
		(end 371.988588 -126.110238)
		(width 0.089408)
		(layer "In9.Cu")
		(net "FM_PCH_PRSNT_N")
	)
	(segment
		(start 379.71603 -109.512862)
		(end 379.41377 -109.815122)
		(width 0.089408)
		(layer "In9.Cu")
		(net "FM_PCH_PRSNT_N")
	)
	(segment
		(start 378.23013 -115.401598)
		(end 377.199652 -116.432076)
		(width 0.089408)
		(layer "In9.Cu")
		(net "FM_PCH_PRSNT_N")
	)
	(segment
		(start 379.907038 -104.00411)
		(end 380.21133 -104.308402)
		(width 0.089408)
		(layer "In9.Cu")
		(net "FM_PCH_PRSNT_N")
	)
	(segment
		(start 377.184412 -100.956364)
		(end 377.66625 -101.438202)
		(width 0.0889)
		(layer "In9.Cu")
		(net "FM_PCH_PRSNT_N")
	)
	(segment
		(start 377.918218 -68.850002)
		(end 377.699524 -69.068696)
		(width 0.089408)
		(layer "In9.Cu")
		(net "FM_PCH_PRSNT_N")
	)
	(segment
		(start 376.899424 -69.868542)
		(end 376.643392 -69.868542)
		(width 0.089408)
		(layer "In9.Cu")
		(net "FM_PCH_PRSNT_N")
	)
	(segment
		(start 372.548658 -93.83903)
		(end 373.7483 -95.038672)
		(width 0.089408)
		(layer "In9.Cu")
		(net "FM_PCH_PRSNT_N")
	)
	(segment
		(start 379.233684 -111.591344)
		(end 379.233684 -112.09274)
		(width 0.089408)
		(layer "In9.Cu")
		(net "FM_PCH_PRSNT_N")
	)
	(segment
		(start 379.833886 -102.54996)
		(end 379.833886 -102.632002)
		(width 0.089408)
		(layer "In9.Cu")
		(net "FM_PCH_PRSNT_N")
	)
	(segment
		(start 376.371358 -80.011778)
		(end 376.154188 -80.228948)
		(width 0.089408)
		(layer "In9.Cu")
		(net "FM_PCH_PRSNT_N")
	)
	(segment
		(start 377.92787 -113.84915)
		(end 377.92787 -114.689128)
		(width 0.089408)
		(layer "In9.Cu")
		(net "FM_PCH_PRSNT_N")
	)
	(segment
		(start 377.61418 -119.519954)
		(end 377.613926 -119.520208)
		(width 0.089408)
		(layer "In9.Cu")
		(net "FM_PCH_PRSNT_N")
	)
	(segment
		(start 377.199652 -117.211602)
		(end 377.613926 -117.625876)
		(width 0.089408)
		(layer "In9.Cu")
		(net "FM_PCH_PRSNT_N")
	)
	(segment
		(start 375.270522 -75.497182)
		(end 375.014236 -75.497182)
		(width 0.089408)
		(layer "In9.Cu")
		(net "FM_PCH_PRSNT_N")
	)
	(segment
		(start 379.41377 -109.815122)
		(end 379.41377 -110.418626)
		(width 0.089408)
		(layer "In9.Cu")
		(net "FM_PCH_PRSNT_N")
	)
	(segment
		(start 376.371358 -70.140576)
		(end 376.371358 -70.396862)
		(width 0.089408)
		(layer "In9.Cu")
		(net "FM_PCH_PRSNT_N")
	)
	(segment
		(start 377.589796 -68.24853)
		(end 377.663202 -68.321936)
		(width 0.089408)
		(layer "In9.Cu")
		(net "FM_PCH_PRSNT_N")
	)
	(segment
		(start 379.71603 -111.108998)
		(end 379.233684 -111.591344)
		(width 0.089408)
		(layer "In9.Cu")
		(net "FM_PCH_PRSNT_N")
	)
	(segment
		(start 369.881912 -90.031824)
		(end 369.79098 -90.122756)
		(width 0.089408)
		(layer "In9.Cu")
		(net "FM_PCH_PRSNT_N")
	)
	(segment
		(start 377.918218 -68.54063)
		(end 377.918218 -68.850002)
		(width 0.089408)
		(layer "In9.Cu")
		(net "FM_PCH_PRSNT_N")
	)
	(segment
		(start 370.224304 -91.451938)
		(end 370.224304 -92.406216)
		(width 0.089408)
		(layer "In9.Cu")
		(net "FM_PCH_PRSNT_N")
	)
	(segment
		(start 377.118118 -69.393816)
		(end 377.118118 -69.649848)
		(width 0.089408)
		(layer "In9.Cu")
		(net "FM_PCH_PRSNT_N")
	)
	(segment
		(start 380.21133 -104.308402)
		(end 380.21133 -104.63911)
		(width 0.089408)
		(layer "In9.Cu")
		(net "FM_PCH_PRSNT_N")
	)
	(segment
		(start 379.233684 -112.09274)
		(end 378.844556 -112.481868)
		(width 0.089408)
		(layer "In9.Cu")
		(net "FM_PCH_PRSNT_N")
	)
	(segment
		(start 371.657118 -93.83903)
		(end 372.548658 -93.83903)
		(width 0.089408)
		(layer "In9.Cu")
		(net "FM_PCH_PRSNT_N")
	)
	(segment
		(start 376.371358 -70.396862)
		(end 375.299732 -71.468488)
		(width 0.089408)
		(layer "In9.Cu")
		(net "FM_PCH_PRSNT_N")
	)
	(segment
		(start 377.191016 -119.999252)
		(end 377.191016 -121.48312)
		(width 0.089408)
		(layer "In9.Cu")
		(net "FM_PCH_PRSNT_N")
	)
	(segment
		(start 377.589796 -67.850258)
		(end 377.589796 -68.24853)
		(width 0.089408)
		(layer "In9.Cu")
		(net "FM_PCH_PRSNT_N")
	)
	(segment
		(start 378.98705 -101.438202)
		(end 379.051566 -101.373686)
		(width 0.0889)
		(layer "In9.Cu")
		(net "FM_PCH_PRSNT_N")
	)
	(segment
		(start 374.771412 -73.64984)
		(end 375.518172 -74.3966)
		(width 0.089408)
		(layer "In9.Cu")
		(net "FM_PCH_PRSNT_N")
	)
	(segment
		(start 379.22073 -106.090212)
		(end 379.22073 -106.35615)
		(width 0.089408)
		(layer "In9.Cu")
		(net "FM_PCH_PRSNT_N")
	)
	(segment
		(start 377.66625 -101.438202)
		(end 378.98705 -101.438202)
		(width 0.0889)
		(layer "In9.Cu")
		(net "FM_PCH_PRSNT_N")
	)
	(segment
		(start 375.246392 -82.117184)
		(end 375.246392 -86.830662)
		(width 0.089408)
		(layer "In9.Cu")
		(net "FM_PCH_PRSNT_N")
	)
	(segment
		(start 374.990106 -76.268072)
		(end 376.846084 -76.268072)
		(width 0.089408)
		(layer "In9.Cu")
		(net "FM_PCH_PRSNT_N")
	)
	(segment
		(start 376.154188 -81.209388)
		(end 375.246392 -82.117184)
		(width 0.089408)
		(layer "In9.Cu")
		(net "FM_PCH_PRSNT_N")
	)
	(segment
		(start 372.823232 -123.779534)
		(end 372.823232 -125.275594)
		(width 0.089408)
		(layer "In9.Cu")
		(net "FM_PCH_PRSNT_N")
	)
	(segment
		(start 370.54409 -88.682576)
		(end 369.881912 -89.344754)
		(width 0.089408)
		(layer "In9.Cu")
		(net "FM_PCH_PRSNT_N")
	)
	(segment
		(start 380.21133 -104.63911)
		(end 379.71603 -105.13441)
		(width 0.089408)
		(layer "In9.Cu")
		(net "FM_PCH_PRSNT_N")
	)
	(segment
		(start 377.127008 -121.547128)
		(end 377.127008 -121.547382)
		(width 0.089408)
		(layer "In9.Cu")
		(net "FM_PCH_PRSNT_N")
	)
	(segment
		(start 375.246392 -86.830662)
		(end 373.394478 -88.682576)
		(width 0.089408)
		(layer "In9.Cu")
		(net "FM_PCH_PRSNT_N")
	)
	(segment
		(start 377.127008 -121.547382)
		(end 376.723402 -121.950988)
		(width 0.089408)
		(layer "In9.Cu")
		(net "FM_PCH_PRSNT_N")
	)
	(segment
		(start 374.771412 -75.740006)
		(end 374.771412 -76.049378)
		(width 0.089408)
		(layer "In9.Cu")
		(net "FM_PCH_PRSNT_N")
	)
	(segment
		(start 375.984008 -100.12426)
		(end 375.984008 -100.642674)
		(width 0.0889)
		(layer "In9.Cu")
		(net "FM_PCH_PRSNT_N")
	)
	(segment
		(start 373.7483 -95.038672)
		(end 373.7483 -95.871792)
		(width 0.089408)
		(layer "In9.Cu")
		(net "FM_PCH_PRSNT_N")
	)
	(segment
		(start 378.91847 -107.21467)
		(end 379.298708 -107.594908)
		(width 0.089408)
		(layer "In9.Cu")
		(net "FM_PCH_PRSNT_N")
	)
	(segment
		(start 369.79098 -91.018614)
		(end 370.224304 -91.451938)
		(width 0.089408)
		(layer "In9.Cu")
		(net "FM_PCH_PRSNT_N")
	)
	(segment
		(start 376.899424 -77.068172)
		(end 376.643392 -77.068172)
		(width 0.089408)
		(layer "In9.Cu")
		(net "FM_PCH_PRSNT_N")
	)
	(segment
		(start 373.7483 -95.871792)
		(end 373.651526 -95.968566)
		(width 0.089408)
		(layer "In9.Cu")
		(net "FM_PCH_PRSNT_N")
	)
	(segment
		(start 377.92787 -114.689128)
		(end 378.23013 -114.991388)
		(width 0.089408)
		(layer "In9.Cu")
		(net "FM_PCH_PRSNT_N")
	)
	(segment
		(start 379.71603 -110.720886)
		(end 379.71603 -111.108998)
		(width 0.089408)
		(layer "In9.Cu")
		(net "FM_PCH_PRSNT_N")
	)
	(segment
		(start 379.71603 -105.594912)
		(end 379.22073 -106.090212)
		(width 0.089408)
		(layer "In9.Cu")
		(net "FM_PCH_PRSNT_N")
	)
	(segment
		(start 377.613926 -119.188992)
		(end 377.61418 -119.189246)
		(width 0.089408)
		(layer "In9.Cu")
		(net "FM_PCH_PRSNT_N")
	)
	(segment
		(start 377.613926 -117.625876)
		(end 377.613926 -119.188992)
		(width 0.089408)
		(layer "In9.Cu")
		(net "FM_PCH_PRSNT_N")
	)
	(segment
		(start 377.61418 -119.189246)
		(end 377.61418 -119.519954)
		(width 0.089408)
		(layer "In9.Cu")
		(net "FM_PCH_PRSNT_N")
	)
	(segment
		(start 371.988588 -129.245614)
		(end 371.996462 -129.253488)
		(width 0.089408)
		(layer "In9.Cu")
		(net "FM_PCH_PRSNT_N")
	)
	(segment
		(start 379.71603 -108.601002)
		(end 379.71603 -109.512862)
		(width 0.089408)
		(layer "In9.Cu")
		(net "FM_PCH_PRSNT_N")
	)
	(segment
		(start 375.299732 -71.468488)
		(end 375.043446 -71.468488)
		(width 0.089408)
		(layer "In9.Cu")
		(net "FM_PCH_PRSNT_N")
	)
	(segment
		(start 378.844556 -112.481868)
		(end 378.844556 -112.932464)
		(width 0.089408)
		(layer "In9.Cu")
		(net "FM_PCH_PRSNT_N")
	)
	(segment
		(start 376.846084 -76.268072)
		(end 377.118118 -76.540106)
		(width 0.089408)
		(layer "In9.Cu")
		(net "FM_PCH_PRSNT_N")
	)
	(segment
		(start 379.41377 -110.418626)
		(end 379.71603 -110.720886)
		(width 0.089408)
		(layer "In9.Cu")
		(net "FM_PCH_PRSNT_N")
	)
	(segment
		(start 377.443238 -69.068696)
		(end 377.118118 -69.393816)
		(width 0.089408)
		(layer "In9.Cu")
		(net "FM_PCH_PRSNT_N")
	)
	(segment
		(start 373.107712 -96.512634)
		(end 373.107712 -98.08845)
		(width 0.089408)
		(layer "In9.Cu")
		(net "FM_PCH_PRSNT_N")
	)
	(segment
		(start 376.723402 -121.950988)
		(end 374.651778 -121.950988)
		(width 0.089408)
		(layer "In9.Cu")
		(net "FM_PCH_PRSNT_N")
	)
	(segment
		(start 374.771412 -71.740522)
		(end 374.771412 -73.64984)
		(width 0.089408)
		(layer "In9.Cu")
		(net "FM_PCH_PRSNT_N")
	)
	(segment
		(start 369.881912 -89.344754)
		(end 369.881912 -90.031824)
		(width 0.089408)
		(layer "In9.Cu")
		(net "FM_PCH_PRSNT_N")
	)
	(segment
		(start 377.699524 -68.321936)
		(end 377.918218 -68.54063)
		(width 0.089408)
		(layer "In9.Cu")
		(net "FM_PCH_PRSNT_N")
	)
	(segment
		(start 371.988588 -126.110238)
		(end 371.988588 -129.245614)
		(width 0.089408)
		(layer "In9.Cu")
		(net "FM_PCH_PRSNT_N")
	)
	(segment
		(start 379.051566 -101.373686)
		(end 379.32487 -101.373686)
		(width 0.0889)
		(layer "In9.Cu")
		(net "FM_PCH_PRSNT_N")
	)
	(segment
		(start 373.545862 -98.5266)
		(end 374.386348 -98.5266)
		(width 0.089408)
		(layer "In9.Cu")
		(net "FM_PCH_PRSNT_N")
	)
	(segment
		(start 376.643392 -69.868542)
		(end 376.371358 -70.140576)
		(width 0.089408)
		(layer "In9.Cu")
		(net "FM_PCH_PRSNT_N")
	)
	(segment
		(start 379.833886 -102.632002)
		(end 379.907038 -102.705154)
		(width 0.089408)
		(layer "In9.Cu")
		(net "FM_PCH_PRSNT_N")
	)
	(segment
		(start 373.394478 -88.682576)
		(end 370.54409 -88.682576)
		(width 0.089408)
		(layer "In9.Cu")
		(net "FM_PCH_PRSNT_N")
	)
	(segment
		(start 377.118118 -76.540106)
		(end 377.118118 -76.849478)
		(width 0.089408)
		(layer "In9.Cu")
		(net "FM_PCH_PRSNT_N")
	)
	(segment
		(start 376.297698 -100.956364)
		(end 377.184412 -100.956364)
		(width 0.0889)
		(layer "In9.Cu")
		(net "FM_PCH_PRSNT_N")
	)
	(segment
		(start 379.7173 -101.88702)
		(end 379.7173 -101.919786)
		(width 0.0889)
		(layer "In9.Cu")
		(net "FM_PCH_PRSNT_N")
	)
	(segment
		(start 375.043446 -71.468488)
		(end 374.771412 -71.740522)
		(width 0.089408)
		(layer "In9.Cu")
		(net "FM_PCH_PRSNT_N")
	)
	(segment
		(start 379.907038 -102.705154)
		(end 379.907038 -104.00411)
		(width 0.089408)
		(layer "In9.Cu")
		(net "FM_PCH_PRSNT_N")
	)
	(segment
		(start 379.298708 -107.594908)
		(end 379.298708 -108.18368)
		(width 0.089408)
		(layer "In9.Cu")
		(net "FM_PCH_PRSNT_N")
	)
	(segment
		(start 369.79098 -90.122756)
		(end 369.79098 -91.018614)
		(width 0.089408)
		(layer "In9.Cu")
		(net "FM_PCH_PRSNT_N")
	)
	(segment
		(start 373.651526 -95.96882)
		(end 373.107712 -96.512634)
		(width 0.089408)
		(layer "In9.Cu")
		(net "FM_PCH_PRSNT_N")
	)
	(segment
		(start 378.23013 -114.991388)
		(end 378.23013 -115.401598)
		(width 0.089408)
		(layer "In9.Cu")
		(net "FM_PCH_PRSNT_N")
	)
	(segment
		(start 378.91847 -106.65841)
		(end 378.91847 -107.21467)
		(width 0.089408)
		(layer "In9.Cu")
		(net "FM_PCH_PRSNT_N")
	)
	(segment
		(start 377.613926 -119.576342)
		(end 377.191016 -119.999252)
		(width 0.089408)
		(layer "In9.Cu")
		(net "FM_PCH_PRSNT_N")
	)
	(segment
		(start 374.771412 -76.049378)
		(end 374.990106 -76.268072)
		(width 0.089408)
		(layer "In9.Cu")
		(net "FM_PCH_PRSNT_N")
	)
	(segment
		(start 370.224304 -92.406216)
		(end 371.657118 -93.83903)
		(width 0.089408)
		(layer "In9.Cu")
		(net "FM_PCH_PRSNT_N")
	)
	(segment
		(start 376.154188 -80.228948)
		(end 376.154188 -81.209388)
		(width 0.089408)
		(layer "In9.Cu")
		(net "FM_PCH_PRSNT_N")
	)
	(segment
		(start 379.833886 -102.251002)
		(end 379.833886 -102.54996)
		(width 0.0889)
		(layer "In9.Cu")
		(net "FM_PCH_PRSNT_N")
	)
	(segment
		(start 377.199652 -116.432076)
		(end 377.199652 -117.211602)
		(width 0.089408)
		(layer "In9.Cu")
		(net "FM_PCH_PRSNT_N")
	)
	(segment
		(start 376.371358 -77.340206)
		(end 376.371358 -80.011778)
		(width 0.089408)
		(layer "In9.Cu")
		(net "FM_PCH_PRSNT_N")
	)
	(segment
		(start 377.699524 -69.068696)
		(end 377.443238 -69.068696)
		(width 0.089408)
		(layer "In9.Cu")
		(net "FM_PCH_PRSNT_N")
	)
	(segment
		(start 373.651526 -95.968566)
		(end 373.651526 -95.96882)
		(width 0.089408)
		(layer "In9.Cu")
		(net "FM_PCH_PRSNT_N")
	)
	(segment
		(start 373.107712 -98.08845)
		(end 373.545862 -98.5266)
		(width 0.089408)
		(layer "In9.Cu")
		(net "FM_PCH_PRSNT_N")
	)
	(segment
		(start 376.643392 -77.068172)
		(end 376.371358 -77.340206)
		(width 0.089408)
		(layer "In9.Cu")
		(net "FM_PCH_PRSNT_N")
	)
	(segment
		(start 375.014236 -75.497182)
		(end 374.771412 -75.740006)
		(width 0.089408)
		(layer "In9.Cu")
		(net "FM_PCH_PRSNT_N")
	)
	(segment
		(start 375.518172 -74.3966)
		(end 375.518172 -75.249532)
		(width 0.089408)
		(layer "In9.Cu")
		(net "FM_PCH_PRSNT_N")
	)
	(arc
		(start 379.32487 -101.373686)
		(mid 379.411039 -101.473368)
		(end 379.517148 -101.551486)
		(width 0.0889)
		(layer "In9.Cu")
		(net "FM_PCH_PRSNT_N")
	)
	(arc
		(start 379.517148 -101.551486)
		(mid 379.660952 -101.693169)
		(end 379.7173 -101.88702)
		(width 0.0889)
		(layer "In9.Cu")
		(net "FM_PCH_PRSNT_N")
	)
	(arc
		(start 379.7173 -101.919786)
		(mid 379.750451 -102.094239)
		(end 379.833886 -102.251002)
		(width 0.0889)
		(layer "In9.Cu")
		(net "FM_PCH_PRSNT_N")
	)
	(segment
		(start 436.404512 -48.165512)
		(end 436.404512 -47.795942)
		(width 0.10795)
		(layer "F.Cu")
		(net "FM_MEZZB_PRSNT1_N")
	)
	(segment
		(start 436.626 -48.387)
		(end 436.404512 -48.165512)
		(width 0.10795)
		(layer "F.Cu")
		(net "FM_MEZZB_PRSNT1_N")
	)
	(segment
		(start 436.718456 -47.481998)
		(end 437.34101 -47.481998)
		(width 0.10795)
		(layer "F.Cu")
		(net "FM_MEZZB_PRSNT1_N")
	)
	(segment
		(start 436.404512 -47.795942)
		(end 436.718456 -47.481998)
		(width 0.10795)
		(layer "F.Cu")
		(net "FM_MEZZB_PRSNT1_N")
	)
	(via
		(at 437.134 -49.201324)
		(size 0.6604)
		(drill 0.3302)
		(layers "F.Cu" "B.Cu")
		(net "FM_MEZZB_PRSNT1_N")
	)
	(via
		(at 436.626 -48.387)
		(size 0.508)
		(drill 0.254)
		(layers "F.Cu" "B.Cu")
		(net "FM_MEZZB_PRSNT1_N")
	)
	(segment
		(start 437.3499 -50.0507)
		(end 438.2135 -49.1871)
		(width 0.10795)
		(layer "B.Cu")
		(net "FM_MEZZB_PRSNT1_N")
	)
	(segment
		(start 437.3499 -50.4698)
		(end 437.3499 -50.0507)
		(width 0.10795)
		(layer "B.Cu")
		(net "FM_MEZZB_PRSNT1_N")
	)
	(segment
		(start 436.626 -48.387)
		(end 436.626 -48.693324)
		(width 0.10795)
		(layer "B.Cu")
		(net "FM_MEZZB_PRSNT1_N")
	)
	(segment
		(start 436.626 -48.693324)
		(end 437.134 -49.201324)
		(width 0.10795)
		(layer "B.Cu")
		(net "FM_MEZZB_PRSNT1_N")
	)
	(segment
		(start 437.694324 -48.641)
		(end 438.2135 -48.641)
		(width 0.10795)
		(layer "B.Cu")
		(net "FM_MEZZB_PRSNT1_N")
	)
	(segment
		(start 438.2135 -49.1871)
		(end 438.2135 -48.641)
		(width 0.10795)
		(layer "B.Cu")
		(net "FM_MEZZB_PRSNT1_N")
	)
	(segment
		(start 437.134 -49.201324)
		(end 437.694324 -48.641)
		(width 0.10795)
		(layer "B.Cu")
		(net "FM_MEZZB_PRSNT1_N")
	)
	(segment
		(start 384.556 -89.580212)
		(end 384.18008 -89.956132)
		(width 0.10795)
		(layer "F.Cu")
		(net "PU_LPC_PME_N")
	)
	(segment
		(start 384.221228 -91.636596)
		(end 384.221228 -92.90431)
		(width 0.0889)
		(layer "F.Cu")
		(net "PU_LPC_PME_N")
	)
	(segment
		(start 384.18008 -89.956132)
		(end 384.18008 -90.241882)
		(width 0.10795)
		(layer "F.Cu")
		(net "PU_LPC_PME_N")
	)
	(segment
		(start 384.221228 -92.90431)
		(end 384.461258 -93.14434)
		(width 0.0889)
		(layer "F.Cu")
		(net "PU_LPC_PME_N")
	)
	(segment
		(start 384.461258 -93.144594)
		(end 384.48488 -93.168216)
		(width 0.0889)
		(layer "F.Cu")
		(net "PU_LPC_PME_N")
	)
	(segment
		(start 384.461258 -93.14434)
		(end 384.461258 -93.144594)
		(width 0.0889)
		(layer "F.Cu")
		(net "PU_LPC_PME_N")
	)
	(segment
		(start 384.48488 -93.168216)
		(end 384.48488 -93.959934)
		(width 0.0889)
		(layer "F.Cu")
		(net "PU_LPC_PME_N")
	)
	(segment
		(start 384.18008 -90.241882)
		(end 384.18008 -91.595448)
		(width 0.0889)
		(layer "F.Cu")
		(net "PU_LPC_PME_N")
	)
	(segment
		(start 384.556 -88.2015)
		(end 384.556 -89.580212)
		(width 0.10795)
		(layer "F.Cu")
		(net "PU_LPC_PME_N")
	)
	(segment
		(start 384.18008 -91.595448)
		(end 384.221228 -91.636596)
		(width 0.0889)
		(layer "F.Cu")
		(net "PU_LPC_PME_N")
	)
	(segment
		(start 400.050254 -110.354872)
		(end 400.42211 -110.354872)
		(width 0.0889)
		(layer "F.Cu")
		(net "FM_BOARD_REV_ID1")
	)
	(segment
		(start 409.490164 -41.73474)
		(end 409.090114 -41.33469)
		(width 0.089408)
		(layer "F.Cu")
		(net "FM_BOARD_REV_ID1")
	)
	(segment
		(start 408.440382 -47.386748)
		(end 408.652726 -47.386748)
		(width 0.10795)
		(layer "F.Cu")
		(net "FM_BOARD_REV_ID1")
	)
	(segment
		(start 401.139406 -110.554008)
		(end 402.053552 -110.554008)
		(width 0.0889)
		(layer "F.Cu")
		(net "FM_BOARD_REV_ID1")
	)
	(segment
		(start 402.053552 -110.554008)
		(end 402.278342 -110.778798)
		(width 0.0889)
		(layer "F.Cu")
		(net "FM_BOARD_REV_ID1")
	)
	(segment
		(start 400.739102 -110.671864)
		(end 401.02155 -110.671864)
		(width 0.0889)
		(layer "F.Cu")
		(net "FM_BOARD_REV_ID1")
	)
	(segment
		(start 408.652726 -47.386748)
		(end 409.080716 -46.958758)
		(width 0.10795)
		(layer "F.Cu")
		(net "FM_BOARD_REV_ID1")
	)
	(segment
		(start 401.02155 -110.671864)
		(end 401.139406 -110.554008)
		(width 0.0889)
		(layer "F.Cu")
		(net "FM_BOARD_REV_ID1")
	)
	(segment
		(start 400.42211 -110.354872)
		(end 400.739102 -110.671864)
		(width 0.0889)
		(layer "F.Cu")
		(net "FM_BOARD_REV_ID1")
	)
	(segment
		(start 408.161236 -47.665894)
		(end 408.440382 -47.386748)
		(width 0.10795)
		(layer "F.Cu")
		(net "FM_BOARD_REV_ID1")
	)
	(segment
		(start 400.05 -110.355126)
		(end 400.050254 -110.354872)
		(width 0.0889)
		(layer "F.Cu")
		(net "FM_BOARD_REV_ID1")
	)
	(segment
		(start 408.161236 -47.825914)
		(end 408.161236 -47.665894)
		(width 0.10795)
		(layer "F.Cu")
		(net "FM_BOARD_REV_ID1")
	)
	(via
		(at 400.958558 -72.338946)
		(size 0.508)
		(drill 0.254)
		(layers "F.Cu" "B.Cu")
		(net "FM_BOARD_REV_ID1")
	)
	(via
		(at 402.278342 -110.778798)
		(size 0.508)
		(drill 0.254)
		(layers "F.Cu" "B.Cu")
		(net "FM_BOARD_REV_ID1")
	)
	(via
		(at 409.080716 -46.958758)
		(size 0.508)
		(drill 0.254)
		(layers "F.Cu" "B.Cu")
		(net "FM_BOARD_REV_ID1")
	)
	(via
		(at 405.56942 -48.01362)
		(size 0.6604)
		(drill 0.3302)
		(layers "F.Cu" "B.Cu")
		(net "FM_BOARD_REV_ID1")
	)
	(via
		(at 409.090114 -41.33469)
		(size 0.4572)
		(drill 0.2032)
		(layers "F.Cu" "B.Cu")
		(net "FM_BOARD_REV_ID1")
	)
	(segment
		(start 408.4574 -47.879)
		(end 406.7556 -49.5808)
		(width 0.10795)
		(layer "B.Cu")
		(net "FM_BOARD_REV_ID1")
	)
	(segment
		(start 409.067 -47.879)
		(end 409.067 -46.972474)
		(width 0.10795)
		(layer "B.Cu")
		(net "FM_BOARD_REV_ID1")
	)
	(segment
		(start 405.56942 -48.01362)
		(end 407.423874 -46.159166)
		(width 0.10795)
		(layer "B.Cu")
		(net "FM_BOARD_REV_ID1")
	)
	(segment
		(start 407.423874 -45.446442)
		(end 407.287222 -45.30979)
		(width 0.10795)
		(layer "B.Cu")
		(net "FM_BOARD_REV_ID1")
	)
	(segment
		(start 409.090114 -41.445942)
		(end 409.090114 -41.33469)
		(width 0.10795)
		(layer "B.Cu")
		(net "FM_BOARD_REV_ID1")
	)
	(segment
		(start 407.287222 -45.30979)
		(end 407.287222 -43.248834)
		(width 0.10795)
		(layer "B.Cu")
		(net "FM_BOARD_REV_ID1")
	)
	(segment
		(start 409.067 -46.972474)
		(end 409.080716 -46.958758)
		(width 0.10795)
		(layer "B.Cu")
		(net "FM_BOARD_REV_ID1")
	)
	(segment
		(start 407.423874 -46.159166)
		(end 407.423874 -45.446442)
		(width 0.10795)
		(layer "B.Cu")
		(net "FM_BOARD_REV_ID1")
	)
	(segment
		(start 406.7556 -49.5808)
		(end 405.843486 -49.5808)
		(width 0.10795)
		(layer "B.Cu")
		(net "FM_BOARD_REV_ID1")
	)
	(segment
		(start 405.3332 -49.070514)
		(end 405.3332 -48.24984)
		(width 0.10795)
		(layer "B.Cu")
		(net "FM_BOARD_REV_ID1")
	)
	(segment
		(start 405.3332 -48.24984)
		(end 405.56942 -48.01362)
		(width 0.10795)
		(layer "B.Cu")
		(net "FM_BOARD_REV_ID1")
	)
	(segment
		(start 405.843486 -49.5808)
		(end 405.3332 -49.070514)
		(width 0.10795)
		(layer "B.Cu")
		(net "FM_BOARD_REV_ID1")
	)
	(segment
		(start 407.287222 -43.248834)
		(end 409.090114 -41.445942)
		(width 0.10795)
		(layer "B.Cu")
		(net "FM_BOARD_REV_ID1")
	)
	(segment
		(start 409.067 -47.879)
		(end 408.4574 -47.879)
		(width 0.10795)
		(layer "B.Cu")
		(net "FM_BOARD_REV_ID1")
	)
	(segment
		(start 406.795224 -46.797976)
		(end 406.795224 -47.262288)
		(width 0.089408)
		(layer "In9.Cu")
		(net "FM_BOARD_REV_ID1")
	)
	(segment
		(start 407.496518 -47.963582)
		(end 407.496518 -49.772316)
		(width 0.089408)
		(layer "In9.Cu")
		(net "FM_BOARD_REV_ID1")
	)
	(segment
		(start 405.707088 -66.61531)
		(end 405.703278 -66.61912)
		(width 0.089408)
		(layer "In9.Cu")
		(net "FM_BOARD_REV_ID1")
	)
	(segment
		(start 405.25954 -67.063366)
		(end 405.25954 -67.221354)
		(width 0.089408)
		(layer "In9.Cu")
		(net "FM_BOARD_REV_ID1")
	)
	(segment
		(start 405.935434 -63.382144)
		(end 405.935434 -64.13119)
		(width 0.089408)
		(layer "In9.Cu")
		(net "FM_BOARD_REV_ID1")
	)
	(segment
		(start 406.15108 -60.603892)
		(end 404.943818 -61.811154)
		(width 0.089408)
		(layer "In9.Cu")
		(net "FM_BOARD_REV_ID1")
	)
	(segment
		(start 401.033996 -72.338946)
		(end 400.958558 -72.338946)
		(width 0.089408)
		(layer "In9.Cu")
		(net "FM_BOARD_REV_ID1")
	)
	(segment
		(start 405.25954 -67.221354)
		(end 405.259794 -67.221608)
		(width 0.089408)
		(layer "In9.Cu")
		(net "FM_BOARD_REV_ID1")
	)
	(segment
		(start 408.628342 -46.506384)
		(end 407.086816 -46.506384)
		(width 0.089408)
		(layer "In9.Cu")
		(net "FM_BOARD_REV_ID1")
	)
	(segment
		(start 404.943818 -61.811154)
		(end 404.943818 -62.821058)
		(width 0.089408)
		(layer "In9.Cu")
		(net "FM_BOARD_REV_ID1")
	)
	(segment
		(start 405.935434 -64.13119)
		(end 406.350216 -64.545972)
		(width 0.089408)
		(layer "In9.Cu")
		(net "FM_BOARD_REV_ID1")
	)
	(segment
		(start 409.080716 -46.958758)
		(end 408.628342 -46.506384)
		(width 0.089408)
		(layer "In9.Cu")
		(net "FM_BOARD_REV_ID1")
	)
	(segment
		(start 406.15108 -53.203856)
		(end 406.15108 -60.603892)
		(width 0.089408)
		(layer "In9.Cu")
		(net "FM_BOARD_REV_ID1")
	)
	(segment
		(start 407.086816 -46.506384)
		(end 406.795224 -46.797976)
		(width 0.089408)
		(layer "In9.Cu")
		(net "FM_BOARD_REV_ID1")
	)
	(segment
		(start 405.703278 -66.61912)
		(end 405.703278 -66.619628)
		(width 0.089408)
		(layer "In9.Cu")
		(net "FM_BOARD_REV_ID1")
	)
	(segment
		(start 405.703278 -66.619628)
		(end 405.25954 -67.063366)
		(width 0.089408)
		(layer "In9.Cu")
		(net "FM_BOARD_REV_ID1")
	)
	(segment
		(start 405.707088 -66.016124)
		(end 405.707088 -66.61531)
		(width 0.089408)
		(layer "In9.Cu")
		(net "FM_BOARD_REV_ID1")
	)
	(segment
		(start 401.821396 -71.945246)
		(end 401.427696 -71.945246)
		(width 0.089408)
		(layer "In9.Cu")
		(net "FM_BOARD_REV_ID1")
	)
	(segment
		(start 406.350216 -64.545972)
		(end 406.350216 -65.372996)
		(width 0.089408)
		(layer "In9.Cu")
		(net "FM_BOARD_REV_ID1")
	)
	(segment
		(start 404.943818 -62.821058)
		(end 405.299164 -63.176404)
		(width 0.089408)
		(layer "In9.Cu")
		(net "FM_BOARD_REV_ID1")
	)
	(segment
		(start 407.333196 -52.02174)
		(end 406.15108 -53.203856)
		(width 0.089408)
		(layer "In9.Cu")
		(net "FM_BOARD_REV_ID1")
	)
	(segment
		(start 401.427696 -71.945246)
		(end 401.033996 -72.338946)
		(width 0.089408)
		(layer "In9.Cu")
		(net "FM_BOARD_REV_ID1")
	)
	(segment
		(start 405.259794 -69.8246)
		(end 402.815552 -72.268842)
		(width 0.089408)
		(layer "In9.Cu")
		(net "FM_BOARD_REV_ID1")
	)
	(segment
		(start 405.729694 -63.176404)
		(end 405.935434 -63.382144)
		(width 0.089408)
		(layer "In9.Cu")
		(net "FM_BOARD_REV_ID1")
	)
	(segment
		(start 406.795224 -47.262288)
		(end 407.496518 -47.963582)
		(width 0.089408)
		(layer "In9.Cu")
		(net "FM_BOARD_REV_ID1")
	)
	(segment
		(start 402.144992 -72.268842)
		(end 401.821396 -71.945246)
		(width 0.089408)
		(layer "In9.Cu")
		(net "FM_BOARD_REV_ID1")
	)
	(segment
		(start 407.333196 -49.935638)
		(end 407.333196 -52.02174)
		(width 0.089408)
		(layer "In9.Cu")
		(net "FM_BOARD_REV_ID1")
	)
	(segment
		(start 406.350216 -65.372996)
		(end 405.707088 -66.016124)
		(width 0.089408)
		(layer "In9.Cu")
		(net "FM_BOARD_REV_ID1")
	)
	(segment
		(start 405.299164 -63.176404)
		(end 405.729694 -63.176404)
		(width 0.089408)
		(layer "In9.Cu")
		(net "FM_BOARD_REV_ID1")
	)
	(segment
		(start 407.496518 -49.772316)
		(end 407.333196 -49.935638)
		(width 0.089408)
		(layer "In9.Cu")
		(net "FM_BOARD_REV_ID1")
	)
	(segment
		(start 402.815552 -72.268842)
		(end 402.144992 -72.268842)
		(width 0.089408)
		(layer "In9.Cu")
		(net "FM_BOARD_REV_ID1")
	)
	(segment
		(start 405.259794 -67.221608)
		(end 405.259794 -69.8246)
		(width 0.089408)
		(layer "In9.Cu")
		(net "FM_BOARD_REV_ID1")
	)
	(segment
		(start 401.641564 -74.614786)
		(end 401.641564 -73.473564)
		(width 0.089408)
		(layer "In11.Cu")
		(net "FM_BOARD_REV_ID1")
	)
	(segment
		(start 404.113238 -99.948238)
		(end 403.552152 -99.387152)
		(width 0.089408)
		(layer "In11.Cu")
		(net "FM_BOARD_REV_ID1")
	)
	(segment
		(start 404.918418 -86.560152)
		(end 402.983192 -84.624926)
		(width 0.089408)
		(layer "In11.Cu")
		(net "FM_BOARD_REV_ID1")
	)
	(segment
		(start 404.61692 -104.80548)
		(end 404.876 -104.5464)
		(width 0.089408)
		(layer "In11.Cu")
		(net "FM_BOARD_REV_ID1")
	)
	(segment
		(start 401.630896 -79.572612)
		(end 401.630896 -79.107538)
		(width 0.089408)
		(layer "In11.Cu")
		(net "FM_BOARD_REV_ID1")
	)
	(segment
		(start 404.323296 -105.317036)
		(end 404.61692 -105.023412)
		(width 0.089408)
		(layer "In11.Cu")
		(net "FM_BOARD_REV_ID1")
	)
	(segment
		(start 404.113238 -102.198424)
		(end 404.113238 -99.948238)
		(width 0.089408)
		(layer "In11.Cu")
		(net "FM_BOARD_REV_ID1")
	)
	(segment
		(start 401.641564 -73.473564)
		(end 400.957288 -72.789288)
		(width 0.089408)
		(layer "In11.Cu")
		(net "FM_BOARD_REV_ID1")
	)
	(segment
		(start 402.983192 -81.256632)
		(end 402.311362 -80.584802)
		(width 0.089408)
		(layer "In11.Cu")
		(net "FM_BOARD_REV_ID1")
	)
	(segment
		(start 402.278342 -110.778798)
		(end 402.778214 -110.278926)
		(width 0.089408)
		(layer "In11.Cu")
		(net "FM_BOARD_REV_ID1")
	)
	(segment
		(start 404.323296 -109.971078)
		(end 404.323296 -105.317036)
		(width 0.089408)
		(layer "In11.Cu")
		(net "FM_BOARD_REV_ID1")
	)
	(segment
		(start 402.311362 -80.253078)
		(end 401.630896 -79.572612)
		(width 0.089408)
		(layer "In11.Cu")
		(net "FM_BOARD_REV_ID1")
	)
	(segment
		(start 402.983192 -84.624926)
		(end 402.983192 -81.256632)
		(width 0.089408)
		(layer "In11.Cu")
		(net "FM_BOARD_REV_ID1")
	)
	(segment
		(start 401.814792 -78.923642)
		(end 401.814792 -77.600048)
		(width 0.089408)
		(layer "In11.Cu")
		(net "FM_BOARD_REV_ID1")
	)
	(segment
		(start 401.322032 -74.934318)
		(end 401.641564 -74.614786)
		(width 0.089408)
		(layer "In11.Cu")
		(net "FM_BOARD_REV_ID1")
	)
	(segment
		(start 404.015448 -110.278926)
		(end 404.323296 -109.971078)
		(width 0.089408)
		(layer "In11.Cu")
		(net "FM_BOARD_REV_ID1")
	)
	(segment
		(start 403.552152 -99.387152)
		(end 403.552152 -93.333316)
		(width 0.089408)
		(layer "In11.Cu")
		(net "FM_BOARD_REV_ID1")
	)
	(segment
		(start 404.876 -104.5464)
		(end 404.876 -102.961186)
		(width 0.089408)
		(layer "In11.Cu")
		(net "FM_BOARD_REV_ID1")
	)
	(segment
		(start 404.61692 -105.023412)
		(end 404.61692 -104.80548)
		(width 0.089408)
		(layer "In11.Cu")
		(net "FM_BOARD_REV_ID1")
	)
	(segment
		(start 402.311362 -80.584802)
		(end 402.311362 -80.253078)
		(width 0.089408)
		(layer "In11.Cu")
		(net "FM_BOARD_REV_ID1")
	)
	(segment
		(start 401.630896 -79.107538)
		(end 401.814792 -78.923642)
		(width 0.089408)
		(layer "In11.Cu")
		(net "FM_BOARD_REV_ID1")
	)
	(segment
		(start 400.957288 -72.789288)
		(end 400.957288 -72.340216)
		(width 0.089408)
		(layer "In11.Cu")
		(net "FM_BOARD_REV_ID1")
	)
	(segment
		(start 403.552152 -93.333316)
		(end 404.918418 -91.96705)
		(width 0.089408)
		(layer "In11.Cu")
		(net "FM_BOARD_REV_ID1")
	)
	(segment
		(start 401.814792 -77.600048)
		(end 401.322032 -77.107288)
		(width 0.089408)
		(layer "In11.Cu")
		(net "FM_BOARD_REV_ID1")
	)
	(segment
		(start 401.322032 -77.107288)
		(end 401.322032 -74.934318)
		(width 0.089408)
		(layer "In11.Cu")
		(net "FM_BOARD_REV_ID1")
	)
	(segment
		(start 404.876 -102.961186)
		(end 404.113238 -102.198424)
		(width 0.089408)
		(layer "In11.Cu")
		(net "FM_BOARD_REV_ID1")
	)
	(segment
		(start 400.957288 -72.340216)
		(end 400.958558 -72.338946)
		(width 0.089408)
		(layer "In11.Cu")
		(net "FM_BOARD_REV_ID1")
	)
	(segment
		(start 402.778214 -110.278926)
		(end 404.015448 -110.278926)
		(width 0.089408)
		(layer "In11.Cu")
		(net "FM_BOARD_REV_ID1")
	)
	(segment
		(start 404.918418 -91.96705)
		(end 404.918418 -86.560152)
		(width 0.089408)
		(layer "In11.Cu")
		(net "FM_BOARD_REV_ID1")
	)
	(segment
		(start 409.321 -43.9166)
		(end 409.4226 -43.9166)
		(width 0.089408)
		(layer "F.Cu")
		(net "FM_BOARD_REV_ID0")
	)
	(segment
		(start 409.4226 -43.9166)
		(end 409.9052 -43.434)
		(width 0.089408)
		(layer "F.Cu")
		(net "FM_BOARD_REV_ID0")
	)
	(segment
		(start 402.669248 -106.953304)
		(end 402.73224 -107.016296)
		(width 0.10795)
		(layer "F.Cu")
		(net "FM_BOARD_REV_ID0")
	)
	(segment
		(start 409.715462 -46.977046)
		(end 408.923236 -47.769272)
		(width 0.10795)
		(layer "F.Cu")
		(net "FM_BOARD_REV_ID0")
	)
	(segment
		(start 408.923236 -47.769272)
		(end 408.923236 -47.825914)
		(width 0.10795)
		(layer "F.Cu")
		(net "FM_BOARD_REV_ID0")
	)
	(segment
		(start 401.295108 -106.855006)
		(end 401.393406 -106.953304)
		(width 0.10795)
		(layer "F.Cu")
		(net "FM_BOARD_REV_ID0")
	)
	(segment
		(start 409.9052 -42.91965)
		(end 410.290264 -42.534586)
		(width 0.089408)
		(layer "F.Cu")
		(net "FM_BOARD_REV_ID0")
	)
	(segment
		(start 409.9052 -43.434)
		(end 409.9052 -42.91965)
		(width 0.089408)
		(layer "F.Cu")
		(net "FM_BOARD_REV_ID0")
	)
	(segment
		(start 401.393406 -106.953304)
		(end 402.669248 -106.953304)
		(width 0.10795)
		(layer "F.Cu")
		(net "FM_BOARD_REV_ID0")
	)
	(via
		(at 402.73224 -107.016296)
		(size 0.508)
		(drill 0.254)
		(layers "F.Cu" "B.Cu")
		(net "FM_BOARD_REV_ID0")
	)
	(via
		(at 409.321 -43.9166)
		(size 0.4572)
		(drill 0.2032)
		(layers "F.Cu" "B.Cu")
		(net "FM_BOARD_REV_ID0")
	)
	(via
		(at 409.715462 -46.977046)
		(size 0.508)
		(drill 0.254)
		(layers "F.Cu" "B.Cu")
		(net "FM_BOARD_REV_ID0")
	)
	(via
		(at 469.1888 -51.3207)
		(size 0.508)
		(drill 0.254)
		(layers "F.Cu" "B.Cu")
		(net "FM_BOARD_REV_ID0")
	)
	(segment
		(start 409.194 -44.0436)
		(end 409.321 -43.9166)
		(width 0.10795)
		(layer "B.Cu")
		(net "FM_BOARD_REV_ID0")
	)
	(segment
		(start 409.829 -47.879)
		(end 409.829 -47.090584)
		(width 0.10795)
		(layer "B.Cu")
		(net "FM_BOARD_REV_ID0")
	)
	(segment
		(start 409.715462 -46.977046)
		(end 409.194 -46.455584)
		(width 0.10795)
		(layer "B.Cu")
		(net "FM_BOARD_REV_ID0")
	)
	(segment
		(start 409.194 -46.455584)
		(end 409.194 -44.0436)
		(width 0.10795)
		(layer "B.Cu")
		(net "FM_BOARD_REV_ID0")
	)
	(segment
		(start 409.829 -47.090584)
		(end 409.715462 -46.977046)
		(width 0.10795)
		(layer "B.Cu")
		(net "FM_BOARD_REV_ID0")
	)
	(segment
		(start 401.39366 -76.01204)
		(end 401.85594 -75.54976)
		(width 0.089408)
		(layer "In2.Cu")
		(net "FM_BOARD_REV_ID0")
	)
	(segment
		(start 401.701 -78.001622)
		(end 401.700746 -78.001368)
		(width 0.089408)
		(layer "In2.Cu")
		(net "FM_BOARD_REV_ID0")
	)
	(segment
		(start 406.474168 -61.57341)
		(end 406.474168 -60.252356)
		(width 0.089408)
		(layer "In2.Cu")
		(net "FM_BOARD_REV_ID0")
	)
	(segment
		(start 401.304252 -88.280748)
		(end 402.874988 -86.710012)
		(width 0.089408)
		(layer "In2.Cu")
		(net "FM_BOARD_REV_ID0")
	)
	(segment
		(start 419.676072 -52.085494)
		(end 419.950392 -51.811174)
		(width 0.089408)
		(layer "In2.Cu")
		(net "FM_BOARD_REV_ID0")
	)
	(segment
		(start 402.73224 -107.016296)
		(end 401.909534 -107.016296)
		(width 0.089408)
		(layer "In2.Cu")
		(net "FM_BOARD_REV_ID0")
	)
	(segment
		(start 401.85594 -75.54976)
		(end 402.00072 -75.54976)
		(width 0.089408)
		(layer "In2.Cu")
		(net "FM_BOARD_REV_ID0")
	)
	(segment
		(start 401.304252 -92.104718)
		(end 401.304252 -88.280748)
		(width 0.089408)
		(layer "In2.Cu")
		(net "FM_BOARD_REV_ID0")
	)
	(segment
		(start 407.94686 -66.505328)
		(end 407.463244 -66.021712)
		(width 0.089408)
		(layer "In2.Cu")
		(net "FM_BOARD_REV_ID0")
	)
	(segment
		(start 402.874988 -86.710012)
		(end 402.874988 -83.846416)
		(width 0.089408)
		(layer "In2.Cu")
		(net "FM_BOARD_REV_ID0")
	)
	(segment
		(start 402.964396 -73.844404)
		(end 402.964396 -73.522586)
		(width 0.089408)
		(layer "In2.Cu")
		(net "FM_BOARD_REV_ID0")
	)
	(segment
		(start 400.420078 -99.97059)
		(end 400.95678 -99.433888)
		(width 0.089408)
		(layer "In2.Cu")
		(net "FM_BOARD_REV_ID0")
	)
	(segment
		(start 407.1239 -59.602624)
		(end 407.1239 -55.77713)
		(width 0.089408)
		(layer "In2.Cu")
		(net "FM_BOARD_REV_ID0")
	)
	(segment
		(start 401.05838 -82.029808)
		(end 401.05838 -79.409798)
		(width 0.089408)
		(layer "In2.Cu")
		(net "FM_BOARD_REV_ID0")
	)
	(segment
		(start 401.05838 -79.409798)
		(end 401.701 -78.767178)
		(width 0.089408)
		(layer "In2.Cu")
		(net "FM_BOARD_REV_ID0")
	)
	(segment
		(start 437.553862 -52.223416)
		(end 468.286084 -52.223416)
		(width 0.089408)
		(layer "In2.Cu")
		(net "FM_BOARD_REV_ID0")
	)
	(segment
		(start 402.409406 -75.141074)
		(end 402.409406 -74.399394)
		(width 0.089408)
		(layer "In2.Cu")
		(net "FM_BOARD_REV_ID0")
	)
	(segment
		(start 401.700746 -77.526388)
		(end 401.701 -77.526134)
		(width 0.089408)
		(layer "In2.Cu")
		(net "FM_BOARD_REV_ID0")
	)
	(segment
		(start 407.94686 -68.540122)
		(end 407.94686 -66.505328)
		(width 0.089408)
		(layer "In2.Cu")
		(net "FM_BOARD_REV_ID0")
	)
	(segment
		(start 401.700746 -78.001368)
		(end 401.700746 -77.526388)
		(width 0.089408)
		(layer "In2.Cu")
		(net "FM_BOARD_REV_ID0")
	)
	(segment
		(start 407.1239 -55.77713)
		(end 407.968704 -54.932326)
		(width 0.089408)
		(layer "In2.Cu")
		(net "FM_BOARD_REV_ID0")
	)
	(segment
		(start 407.968704 -54.932326)
		(end 407.968704 -53.916326)
		(width 0.089408)
		(layer "In2.Cu")
		(net "FM_BOARD_REV_ID0")
	)
	(segment
		(start 402.00072 -75.54976)
		(end 402.409406 -75.141074)
		(width 0.089408)
		(layer "In2.Cu")
		(net "FM_BOARD_REV_ID0")
	)
	(segment
		(start 402.409406 -74.399394)
		(end 402.964396 -73.844404)
		(width 0.089408)
		(layer "In2.Cu")
		(net "FM_BOARD_REV_ID0")
	)
	(segment
		(start 436.92445 -52.852828)
		(end 437.553862 -52.223416)
		(width 0.089408)
		(layer "In2.Cu")
		(net "FM_BOARD_REV_ID0")
	)
	(segment
		(start 402.964396 -73.522586)
		(end 407.94686 -68.540122)
		(width 0.089408)
		(layer "In2.Cu")
		(net "FM_BOARD_REV_ID0")
	)
	(segment
		(start 419.950392 -51.811174)
		(end 424.709082 -51.811174)
		(width 0.089408)
		(layer "In2.Cu")
		(net "FM_BOARD_REV_ID0")
	)
	(segment
		(start 407.968704 -53.916326)
		(end 409.799536 -52.085494)
		(width 0.089408)
		(layer "In2.Cu")
		(net "FM_BOARD_REV_ID0")
	)
	(segment
		(start 401.909534 -107.016296)
		(end 400.420078 -105.52684)
		(width 0.089408)
		(layer "In2.Cu")
		(net "FM_BOARD_REV_ID0")
	)
	(segment
		(start 406.474168 -60.252356)
		(end 407.1239 -59.602624)
		(width 0.089408)
		(layer "In2.Cu")
		(net "FM_BOARD_REV_ID0")
	)
	(segment
		(start 407.463244 -66.021712)
		(end 407.463244 -62.562486)
		(width 0.089408)
		(layer "In2.Cu")
		(net "FM_BOARD_REV_ID0")
	)
	(segment
		(start 400.95678 -99.433888)
		(end 400.95678 -92.45219)
		(width 0.089408)
		(layer "In2.Cu")
		(net "FM_BOARD_REV_ID0")
	)
	(segment
		(start 409.799536 -52.085494)
		(end 419.676072 -52.085494)
		(width 0.089408)
		(layer "In2.Cu")
		(net "FM_BOARD_REV_ID0")
	)
	(segment
		(start 401.701 -78.767178)
		(end 401.701 -78.001622)
		(width 0.089408)
		(layer "In2.Cu")
		(net "FM_BOARD_REV_ID0")
	)
	(segment
		(start 425.750736 -52.852828)
		(end 436.92445 -52.852828)
		(width 0.089408)
		(layer "In2.Cu")
		(net "FM_BOARD_REV_ID0")
	)
	(segment
		(start 402.874988 -83.846416)
		(end 401.05838 -82.029808)
		(width 0.089408)
		(layer "In2.Cu")
		(net "FM_BOARD_REV_ID0")
	)
	(segment
		(start 424.709082 -51.811174)
		(end 425.750736 -52.852828)
		(width 0.089408)
		(layer "In2.Cu")
		(net "FM_BOARD_REV_ID0")
	)
	(segment
		(start 407.463244 -62.562486)
		(end 406.474168 -61.57341)
		(width 0.089408)
		(layer "In2.Cu")
		(net "FM_BOARD_REV_ID0")
	)
	(segment
		(start 468.286084 -52.223416)
		(end 469.1888 -51.3207)
		(width 0.089408)
		(layer "In2.Cu")
		(net "FM_BOARD_REV_ID0")
	)
	(segment
		(start 400.420078 -105.52684)
		(end 400.420078 -99.97059)
		(width 0.089408)
		(layer "In2.Cu")
		(net "FM_BOARD_REV_ID0")
	)
	(segment
		(start 401.39366 -77.022452)
		(end 401.39366 -76.01204)
		(width 0.089408)
		(layer "In2.Cu")
		(net "FM_BOARD_REV_ID0")
	)
	(segment
		(start 401.701 -77.329792)
		(end 401.39366 -77.022452)
		(width 0.089408)
		(layer "In2.Cu")
		(net "FM_BOARD_REV_ID0")
	)
	(segment
		(start 401.701 -77.526134)
		(end 401.701 -77.329792)
		(width 0.089408)
		(layer "In2.Cu")
		(net "FM_BOARD_REV_ID0")
	)
	(segment
		(start 400.95678 -92.45219)
		(end 401.304252 -92.104718)
		(width 0.089408)
		(layer "In2.Cu")
		(net "FM_BOARD_REV_ID0")
	)
	(segment
		(start 423.375328 -44.463208)
		(end 423.917872 -44.463208)
		(width 0.089408)
		(layer "In4.Cu")
		(net "FM_BOARD_REV_ID0")
	)
	(segment
		(start 410.516578 -46.566582)
		(end 412.170626 -46.566582)
		(width 0.089408)
		(layer "In4.Cu")
		(net "FM_BOARD_REV_ID0")
	)
	(segment
		(start 454.962768 -44.219368)
		(end 464.040728 -44.219368)
		(width 0.089408)
		(layer "In4.Cu")
		(net "FM_BOARD_REV_ID0")
	)
	(segment
		(start 413.44469 -45.292518)
		(end 418.854128 -45.292518)
		(width 0.089408)
		(layer "In4.Cu")
		(net "FM_BOARD_REV_ID0")
	)
	(segment
		(start 420.124382 -44.949618)
		(end 420.447978 -44.626022)
		(width 0.089408)
		(layer "In4.Cu")
		(net "FM_BOARD_REV_ID0")
	)
	(segment
		(start 434.9496 -42.322496)
		(end 435.200044 -42.072052)
		(width 0.089408)
		(layer "In4.Cu")
		(net "FM_BOARD_REV_ID0")
	)
	(segment
		(start 429.71847 -41.529)
		(end 430.511966 -42.322496)
		(width 0.089408)
		(layer "In4.Cu")
		(net "FM_BOARD_REV_ID0")
	)
	(segment
		(start 418.854128 -45.292518)
		(end 419.197028 -44.949618)
		(width 0.089408)
		(layer "In4.Cu")
		(net "FM_BOARD_REV_ID0")
	)
	(segment
		(start 423.917872 -44.463208)
		(end 424.31716 -44.06392)
		(width 0.089408)
		(layer "In4.Cu")
		(net "FM_BOARD_REV_ID0")
	)
	(segment
		(start 424.736006 -42.724578)
		(end 426.390562 -42.724578)
		(width 0.089408)
		(layer "In4.Cu")
		(net "FM_BOARD_REV_ID0")
	)
	(segment
		(start 423.212514 -44.626022)
		(end 423.375328 -44.463208)
		(width 0.089408)
		(layer "In4.Cu")
		(net "FM_BOARD_REV_ID0")
	)
	(segment
		(start 452.1708 -43.2562)
		(end 453.9996 -43.2562)
		(width 0.089408)
		(layer "In4.Cu")
		(net "FM_BOARD_REV_ID0")
	)
	(segment
		(start 427.58614 -41.529)
		(end 429.71847 -41.529)
		(width 0.089408)
		(layer "In4.Cu")
		(net "FM_BOARD_REV_ID0")
	)
	(segment
		(start 450.986652 -42.072052)
		(end 452.1708 -43.2562)
		(width 0.089408)
		(layer "In4.Cu")
		(net "FM_BOARD_REV_ID0")
	)
	(segment
		(start 410.184346 -46.566582)
		(end 410.1846 -46.566328)
		(width 0.089408)
		(layer "In4.Cu")
		(net "FM_BOARD_REV_ID0")
	)
	(segment
		(start 419.197028 -44.949618)
		(end 420.124382 -44.949618)
		(width 0.089408)
		(layer "In4.Cu")
		(net "FM_BOARD_REV_ID0")
	)
	(segment
		(start 424.316906 -43.905678)
		(end 424.316906 -43.143678)
		(width 0.089408)
		(layer "In4.Cu")
		(net "FM_BOARD_REV_ID0")
	)
	(segment
		(start 468.4014 -50.5333)
		(end 469.1888 -51.3207)
		(width 0.089408)
		(layer "In4.Cu")
		(net "FM_BOARD_REV_ID0")
	)
	(segment
		(start 410.516324 -46.566328)
		(end 410.516578 -46.566582)
		(width 0.089408)
		(layer "In4.Cu")
		(net "FM_BOARD_REV_ID0")
	)
	(segment
		(start 424.316906 -43.143678)
		(end 424.736006 -42.724578)
		(width 0.089408)
		(layer "In4.Cu")
		(net "FM_BOARD_REV_ID0")
	)
	(segment
		(start 424.31716 -43.905932)
		(end 424.316906 -43.905678)
		(width 0.089408)
		(layer "In4.Cu")
		(net "FM_BOARD_REV_ID0")
	)
	(segment
		(start 409.715462 -46.977046)
		(end 410.125926 -46.566582)
		(width 0.089408)
		(layer "In4.Cu")
		(net "FM_BOARD_REV_ID0")
	)
	(segment
		(start 410.125926 -46.566582)
		(end 410.184346 -46.566582)
		(width 0.089408)
		(layer "In4.Cu")
		(net "FM_BOARD_REV_ID0")
	)
	(segment
		(start 430.511966 -42.322496)
		(end 434.9496 -42.322496)
		(width 0.089408)
		(layer "In4.Cu")
		(net "FM_BOARD_REV_ID0")
	)
	(segment
		(start 424.31716 -44.06392)
		(end 424.31716 -43.905932)
		(width 0.089408)
		(layer "In4.Cu")
		(net "FM_BOARD_REV_ID0")
	)
	(segment
		(start 464.92287 -45.10151)
		(end 464.92287 -45.870114)
		(width 0.089408)
		(layer "In4.Cu")
		(net "FM_BOARD_REV_ID0")
	)
	(segment
		(start 426.390562 -42.724578)
		(end 427.58614 -41.529)
		(width 0.089408)
		(layer "In4.Cu")
		(net "FM_BOARD_REV_ID0")
	)
	(segment
		(start 410.1846 -46.566328)
		(end 410.516324 -46.566328)
		(width 0.089408)
		(layer "In4.Cu")
		(net "FM_BOARD_REV_ID0")
	)
	(segment
		(start 464.040728 -44.219368)
		(end 464.92287 -45.10151)
		(width 0.089408)
		(layer "In4.Cu")
		(net "FM_BOARD_REV_ID0")
	)
	(segment
		(start 420.447978 -44.626022)
		(end 423.212514 -44.626022)
		(width 0.089408)
		(layer "In4.Cu")
		(net "FM_BOARD_REV_ID0")
	)
	(segment
		(start 464.92287 -45.870114)
		(end 468.4014 -49.348644)
		(width 0.089408)
		(layer "In4.Cu")
		(net "FM_BOARD_REV_ID0")
	)
	(segment
		(start 453.9996 -43.2562)
		(end 454.962768 -44.219368)
		(width 0.089408)
		(layer "In4.Cu")
		(net "FM_BOARD_REV_ID0")
	)
	(segment
		(start 435.200044 -42.072052)
		(end 450.986652 -42.072052)
		(width 0.089408)
		(layer "In4.Cu")
		(net "FM_BOARD_REV_ID0")
	)
	(segment
		(start 412.170626 -46.566582)
		(end 413.44469 -45.292518)
		(width 0.089408)
		(layer "In4.Cu")
		(net "FM_BOARD_REV_ID0")
	)
	(segment
		(start 468.4014 -49.348644)
		(end 468.4014 -50.5333)
		(width 0.089408)
		(layer "In4.Cu")
		(net "FM_BOARD_REV_ID0")
	)
	(segment
		(start 366.745012 -69.095112)
		(end 366.345216 -68.695316)
		(width 0.1016)
		(layer "F.Cu")
		(net "FM_ADR_COMPLETE_DLY")
	)
	(segment
		(start 366.345216 -68.695316)
		(end 366.344962 -68.695316)
		(width 0.1016)
		(layer "F.Cu")
		(net "FM_ADR_COMPLETE_DLY")
	)
	(via
		(at 324.61962 -37.72154)
		(size 0.508)
		(drill 0.254)
		(layers "F.Cu" "B.Cu")
		(net "FM_ADR_COMPLETE_DLY")
	)
	(via
		(at 366.344962 -68.695316)
		(size 0.4572)
		(drill 0.2032)
		(layers "F.Cu" "B.Cu")
		(net "FM_ADR_COMPLETE_DLY")
	)
	(via
		(at 320.7766 -35.5727)
		(size 0.6604)
		(drill 0.3302)
		(layers "F.Cu" "B.Cu")
		(net "FM_ADR_COMPLETE_DLY")
	)
	(via
		(at 372.466616 -62.3189)
		(size 0.508)
		(drill 0.254)
		(layers "F.Cu" "B.Cu")
		(net "FM_ADR_COMPLETE_DLY")
	)
	(segment
		(start 322.87337 -35.54476)
		(end 322.602352 -35.815778)
		(width 0.10795)
		(layer "B.Cu")
		(net "FM_ADR_COMPLETE_DLY")
	)
	(segment
		(start 321.726052 -36.522152)
		(end 320.7766 -35.5727)
		(width 0.10795)
		(layer "B.Cu")
		(net "FM_ADR_COMPLETE_DLY")
	)
	(segment
		(start 323.98716 -35.680396)
		(end 323.851524 -35.54476)
		(width 0.10795)
		(layer "B.Cu")
		(net "FM_ADR_COMPLETE_DLY")
	)
	(segment
		(start 322.602352 -35.815778)
		(end 322.602352 -36.274756)
		(width 0.10795)
		(layer "B.Cu")
		(net "FM_ADR_COMPLETE_DLY")
	)
	(segment
		(start 319.08242 -34.2138)
		(end 318.9732 -34.2138)
		(width 0.10795)
		(layer "B.Cu")
		(net "FM_ADR_COMPLETE_DLY")
	)
	(segment
		(start 324.598284 -37.700204)
		(end 324.33006 -37.700204)
		(width 0.10795)
		(layer "B.Cu")
		(net "FM_ADR_COMPLETE_DLY")
	)
	(segment
		(start 322.354956 -36.522152)
		(end 321.726052 -36.522152)
		(width 0.10795)
		(layer "B.Cu")
		(net "FM_ADR_COMPLETE_DLY")
	)
	(segment
		(start 320.7766 -35.5727)
		(end 320.44132 -35.5727)
		(width 0.10795)
		(layer "B.Cu")
		(net "FM_ADR_COMPLETE_DLY")
	)
	(segment
		(start 324.33006 -37.700204)
		(end 323.98716 -37.357304)
		(width 0.10795)
		(layer "B.Cu")
		(net "FM_ADR_COMPLETE_DLY")
	)
	(segment
		(start 324.61962 -37.72154)
		(end 324.598284 -37.700204)
		(width 0.10795)
		(layer "B.Cu")
		(net "FM_ADR_COMPLETE_DLY")
	)
	(segment
		(start 320.44132 -35.5727)
		(end 319.08242 -34.2138)
		(width 0.10795)
		(layer "B.Cu")
		(net "FM_ADR_COMPLETE_DLY")
	)
	(segment
		(start 323.98716 -37.357304)
		(end 323.98716 -35.680396)
		(width 0.10795)
		(layer "B.Cu")
		(net "FM_ADR_COMPLETE_DLY")
	)
	(segment
		(start 322.602352 -36.274756)
		(end 322.354956 -36.522152)
		(width 0.10795)
		(layer "B.Cu")
		(net "FM_ADR_COMPLETE_DLY")
	)
	(segment
		(start 323.851524 -35.54476)
		(end 322.87337 -35.54476)
		(width 0.10795)
		(layer "B.Cu")
		(net "FM_ADR_COMPLETE_DLY")
	)
	(segment
		(start 370.08435 -63.773304)
		(end 368.93881 -63.773304)
		(width 0.089408)
		(layer "In9.Cu")
		(net "FM_ADR_COMPLETE_DLY")
	)
	(segment
		(start 366.912144 -65.482978)
		(end 366.912144 -66.79692)
		(width 0.089408)
		(layer "In9.Cu")
		(net "FM_ADR_COMPLETE_DLY")
	)
	(segment
		(start 372.031514 -62.992)
		(end 370.865654 -62.992)
		(width 0.089408)
		(layer "In9.Cu")
		(net "FM_ADR_COMPLETE_DLY")
	)
	(segment
		(start 366.912144 -66.79692)
		(end 365.971582 -67.737482)
		(width 0.089408)
		(layer "In9.Cu")
		(net "FM_ADR_COMPLETE_DLY")
	)
	(segment
		(start 368.93881 -63.773304)
		(end 368.938556 -63.77305)
		(width 0.089408)
		(layer "In9.Cu")
		(net "FM_ADR_COMPLETE_DLY")
	)
	(segment
		(start 372.466616 -62.3189)
		(end 372.466616 -62.556898)
		(width 0.089408)
		(layer "In9.Cu")
		(net "FM_ADR_COMPLETE_DLY")
	)
	(segment
		(start 368.938556 -63.77305)
		(end 368.622072 -63.77305)
		(width 0.089408)
		(layer "In9.Cu")
		(net "FM_ADR_COMPLETE_DLY")
	)
	(segment
		(start 365.971582 -68.321936)
		(end 366.344962 -68.695316)
		(width 0.089408)
		(layer "In9.Cu")
		(net "FM_ADR_COMPLETE_DLY")
	)
	(segment
		(start 365.971582 -67.737482)
		(end 365.971582 -68.321936)
		(width 0.089408)
		(layer "In9.Cu")
		(net "FM_ADR_COMPLETE_DLY")
	)
	(segment
		(start 368.622072 -63.77305)
		(end 366.912144 -65.482978)
		(width 0.089408)
		(layer "In9.Cu")
		(net "FM_ADR_COMPLETE_DLY")
	)
	(segment
		(start 372.466616 -62.556898)
		(end 372.031514 -62.992)
		(width 0.089408)
		(layer "In9.Cu")
		(net "FM_ADR_COMPLETE_DLY")
	)
	(segment
		(start 370.865654 -62.992)
		(end 370.08435 -63.773304)
		(width 0.089408)
		(layer "In9.Cu")
		(net "FM_ADR_COMPLETE_DLY")
	)
	(segment
		(start 323.30771 -44.16806)
		(end 320.437764 -44.16806)
		(width 0.089408)
		(layer "In11.Cu")
		(net "FM_ADR_COMPLETE_DLY")
	)
	(segment
		(start 372.466616 -62.3189)
		(end 372.466616 -61.828426)
		(width 0.089408)
		(layer "In11.Cu")
		(net "FM_ADR_COMPLETE_DLY")
	)
	(segment
		(start 366.34801 -55.710074)
		(end 364.631732 -55.710074)
		(width 0.089408)
		(layer "In11.Cu")
		(net "FM_ADR_COMPLETE_DLY")
	)
	(segment
		(start 320.437764 -44.16806)
		(end 319.24498 -42.975276)
		(width 0.089408)
		(layer "In11.Cu")
		(net "FM_ADR_COMPLETE_DLY")
	)
	(segment
		(start 323.726556 -35.105594)
		(end 325.012304 -36.391342)
		(width 0.089408)
		(layer "In11.Cu")
		(net "FM_ADR_COMPLETE_DLY")
	)
	(segment
		(start 320.556128 -35.105594)
		(end 323.726556 -35.105594)
		(width 0.089408)
		(layer "In11.Cu")
		(net "FM_ADR_COMPLETE_DLY")
	)
	(segment
		(start 360.759502 -51.837844)
		(end 359.376726 -51.837844)
		(width 0.089408)
		(layer "In11.Cu")
		(net "FM_ADR_COMPLETE_DLY")
	)
	(segment
		(start 319.24498 -42.975276)
		(end 319.24498 -36.416742)
		(width 0.089408)
		(layer "In11.Cu")
		(net "FM_ADR_COMPLETE_DLY")
	)
	(segment
		(start 372.466616 -61.828426)
		(end 366.34801 -55.710074)
		(width 0.089408)
		(layer "In11.Cu")
		(net "FM_ADR_COMPLETE_DLY")
	)
	(segment
		(start 357.116888 -49.578006)
		(end 328.717656 -49.578006)
		(width 0.089408)
		(layer "In11.Cu")
		(net "FM_ADR_COMPLETE_DLY")
	)
	(segment
		(start 359.376726 -51.837844)
		(end 357.116888 -49.578006)
		(width 0.089408)
		(layer "In11.Cu")
		(net "FM_ADR_COMPLETE_DLY")
	)
	(segment
		(start 325.012304 -36.391342)
		(end 325.012304 -37.328856)
		(width 0.089408)
		(layer "In11.Cu")
		(net "FM_ADR_COMPLETE_DLY")
	)
	(segment
		(start 325.012304 -37.328856)
		(end 324.61962 -37.72154)
		(width 0.089408)
		(layer "In11.Cu")
		(net "FM_ADR_COMPLETE_DLY")
	)
	(segment
		(start 364.631732 -55.710074)
		(end 360.759502 -51.837844)
		(width 0.089408)
		(layer "In11.Cu")
		(net "FM_ADR_COMPLETE_DLY")
	)
	(segment
		(start 328.717656 -49.578006)
		(end 323.30771 -44.16806)
		(width 0.089408)
		(layer "In11.Cu")
		(net "FM_ADR_COMPLETE_DLY")
	)
	(segment
		(start 319.24498 -36.416742)
		(end 320.556128 -35.105594)
		(width 0.089408)
		(layer "In11.Cu")
		(net "FM_ADR_COMPLETE_DLY")
	)
	(segment
		(start 373.544846 -69.495162)
		(end 373.14505 -69.894958)
		(width 0.1016)
		(layer "F.Cu")
		(net "FM_ADR_COMPLETE")
	)
	(via
		(at 401.41271 -86.688422)
		(size 0.508)
		(drill 0.254)
		(layers "F.Cu" "B.Cu")
		(net "FM_ADR_COMPLETE")
	)
	(via
		(at 397.041878 -65.573656)
		(size 0.508)
		(drill 0.254)
		(layers "F.Cu" "B.Cu")
		(net "FM_ADR_COMPLETE")
	)
	(via
		(at 321.520312 -35.704272)
		(size 0.508)
		(drill 0.254)
		(layers "F.Cu" "B.Cu")
		(net "FM_ADR_COMPLETE")
	)
	(via
		(at 375.539 -64.008)
		(size 0.508)
		(drill 0.254)
		(layers "F.Cu" "B.Cu")
		(net "FM_ADR_COMPLETE")
	)
	(via
		(at 373.544846 -69.495162)
		(size 0.4572)
		(drill 0.2032)
		(layers "F.Cu" "B.Cu")
		(net "FM_ADR_COMPLETE")
	)
	(via
		(at 322.173854 -34.8615)
		(size 0.6604)
		(drill 0.3302)
		(layers "F.Cu" "B.Cu")
		(net "FM_ADR_COMPLETE")
	)
	(segment
		(start 401.41271 -86.688422)
		(end 401.574 -86.849712)
		(width 0.10795)
		(layer "B.Cu")
		(net "FM_ADR_COMPLETE")
	)
	(segment
		(start 322.2117 -35.253168)
		(end 321.760596 -35.704272)
		(width 0.10795)
		(layer "B.Cu")
		(net "FM_ADR_COMPLETE")
	)
	(segment
		(start 318.9732 -33.1978)
		(end 318.9732 -33.4518)
		(width 0.10795)
		(layer "B.Cu")
		(net "FM_ADR_COMPLETE")
	)
	(segment
		(start 320.030856 -34.50971)
		(end 320.138806 -34.61766)
		(width 0.10795)
		(layer "B.Cu")
		(net "FM_ADR_COMPLETE")
	)
	(segment
		(start 320.138806 -34.61766)
		(end 321.930014 -34.61766)
		(width 0.10795)
		(layer "B.Cu")
		(net "FM_ADR_COMPLETE")
	)
	(segment
		(start 320.030856 -34.509456)
		(end 320.030856 -34.50971)
		(width 0.10795)
		(layer "B.Cu")
		(net "FM_ADR_COMPLETE")
	)
	(segment
		(start 322.173854 -34.8615)
		(end 322.2117 -34.899346)
		(width 0.10795)
		(layer "B.Cu")
		(net "FM_ADR_COMPLETE")
	)
	(segment
		(start 318.9732 -33.4518)
		(end 320.030856 -34.509456)
		(width 0.10795)
		(layer "B.Cu")
		(net "FM_ADR_COMPLETE")
	)
	(segment
		(start 322.2117 -34.899346)
		(end 322.2117 -35.253168)
		(width 0.10795)
		(layer "B.Cu")
		(net "FM_ADR_COMPLETE")
	)
	(segment
		(start 401.574 -86.849712)
		(end 401.574 -87.3125)
		(width 0.10795)
		(layer "B.Cu")
		(net "FM_ADR_COMPLETE")
	)
	(segment
		(start 321.930014 -34.61766)
		(end 322.173854 -34.8615)
		(width 0.10795)
		(layer "B.Cu")
		(net "FM_ADR_COMPLETE")
	)
	(segment
		(start 321.760596 -35.704272)
		(end 321.520312 -35.704272)
		(width 0.10795)
		(layer "B.Cu")
		(net "FM_ADR_COMPLETE")
	)
	(segment
		(start 391.485882 -65.573656)
		(end 391.485628 -65.573402)
		(width 0.089408)
		(layer "In4.Cu")
		(net "FM_ADR_COMPLETE")
	)
	(segment
		(start 390.852152 -65.573402)
		(end 388.66826 -67.757294)
		(width 0.089408)
		(layer "In4.Cu")
		(net "FM_ADR_COMPLETE")
	)
	(segment
		(start 375.3612 -66.995802)
		(end 373.949214 -68.407788)
		(width 0.089408)
		(layer "In4.Cu")
		(net "FM_ADR_COMPLETE")
	)
	(segment
		(start 391.485628 -65.573402)
		(end 390.852152 -65.573402)
		(width 0.089408)
		(layer "In4.Cu")
		(net "FM_ADR_COMPLETE")
	)
	(segment
		(start 378.085604 -66.873628)
		(end 376.428 -66.873628)
		(width 0.089408)
		(layer "In4.Cu")
		(net "FM_ADR_COMPLETE")
	)
	(segment
		(start 373.949214 -68.407788)
		(end 373.949214 -68.886324)
		(width 0.089408)
		(layer "In4.Cu")
		(net "FM_ADR_COMPLETE")
	)
	(segment
		(start 373.949214 -68.886324)
		(end 373.544846 -69.290692)
		(width 0.089408)
		(layer "In4.Cu")
		(net "FM_ADR_COMPLETE")
	)
	(segment
		(start 376.305826 -66.995802)
		(end 375.3612 -66.995802)
		(width 0.089408)
		(layer "In4.Cu")
		(net "FM_ADR_COMPLETE")
	)
	(segment
		(start 397.041878 -65.573656)
		(end 391.485882 -65.573656)
		(width 0.089408)
		(layer "In4.Cu")
		(net "FM_ADR_COMPLETE")
	)
	(segment
		(start 373.544846 -69.290692)
		(end 373.544846 -69.495162)
		(width 0.089408)
		(layer "In4.Cu")
		(net "FM_ADR_COMPLETE")
	)
	(segment
		(start 380.09576 -66.980816)
		(end 378.192792 -66.980816)
		(width 0.089408)
		(layer "In4.Cu")
		(net "FM_ADR_COMPLETE")
	)
	(segment
		(start 376.428 -66.873628)
		(end 376.305826 -66.995802)
		(width 0.089408)
		(layer "In4.Cu")
		(net "FM_ADR_COMPLETE")
	)
	(segment
		(start 378.192792 -66.980816)
		(end 378.085604 -66.873628)
		(width 0.089408)
		(layer "In4.Cu")
		(net "FM_ADR_COMPLETE")
	)
	(segment
		(start 380.872238 -67.757294)
		(end 380.09576 -66.980816)
		(width 0.089408)
		(layer "In4.Cu")
		(net "FM_ADR_COMPLETE")
	)
	(segment
		(start 388.66826 -67.757294)
		(end 380.872238 -67.757294)
		(width 0.089408)
		(layer "In4.Cu")
		(net "FM_ADR_COMPLETE")
	)
	(segment
		(start 375.539 -64.008)
		(end 375.539 -64.135)
		(width 0.089408)
		(layer "In9.Cu")
		(net "FM_ADR_COMPLETE")
	)
	(segment
		(start 373.971312 -69.068696)
		(end 373.544846 -69.495162)
		(width 0.089408)
		(layer "In9.Cu")
		(net "FM_ADR_COMPLETE")
	)
	(segment
		(start 374.820688 -64.853312)
		(end 374.820688 -66.738246)
		(width 0.089408)
		(layer "In9.Cu")
		(net "FM_ADR_COMPLETE")
	)
	(segment
		(start 374.820688 -66.738246)
		(end 373.971312 -67.587622)
		(width 0.089408)
		(layer "In9.Cu")
		(net "FM_ADR_COMPLETE")
	)
	(segment
		(start 373.971312 -67.587622)
		(end 373.971312 -69.068696)
		(width 0.089408)
		(layer "In9.Cu")
		(net "FM_ADR_COMPLETE")
	)
	(segment
		(start 375.539 -64.135)
		(end 374.820688 -64.853312)
		(width 0.089408)
		(layer "In9.Cu")
		(net "FM_ADR_COMPLETE")
	)
	(segment
		(start 373.380508 -60.720986)
		(end 372.055136 -59.395614)
		(width 0.089408)
		(layer "In11.Cu")
		(net "FM_ADR_COMPLETE")
	)
	(segment
		(start 322.299584 -42.938192)
		(end 319.626996 -40.265604)
		(width 0.089408)
		(layer "In11.Cu")
		(net "FM_ADR_COMPLETE")
	)
	(segment
		(start 402.212048 -87.042752)
		(end 401.76704 -87.042752)
		(width 0.089408)
		(layer "In11.Cu")
		(net "FM_ADR_COMPLETE")
	)
	(segment
		(start 328.831194 -48.61052)
		(end 323.158866 -42.938192)
		(width 0.089408)
		(layer "In11.Cu")
		(net "FM_ADR_COMPLETE")
	)
	(segment
		(start 402.68398 -86.57082)
		(end 402.212048 -87.042752)
		(width 0.089408)
		(layer "In11.Cu")
		(net "FM_ADR_COMPLETE")
	)
	(segment
		(start 364.830868 -54.791102)
		(end 358.650286 -48.61052)
		(width 0.089408)
		(layer "In11.Cu")
		(net "FM_ADR_COMPLETE")
	)
	(segment
		(start 397.041878 -65.573656)
		(end 396.875 -65.740534)
		(width 0.089408)
		(layer "In11.Cu")
		(net "FM_ADR_COMPLETE")
	)
	(segment
		(start 396.875 -65.740534)
		(end 396.875 -70.27799)
		(width 0.089408)
		(layer "In11.Cu")
		(net "FM_ADR_COMPLETE")
	)
	(segment
		(start 366.995456 -54.791102)
		(end 364.830868 -54.791102)
		(width 0.089408)
		(layer "In11.Cu")
		(net "FM_ADR_COMPLETE")
	)
	(segment
		(start 399.655792 -75.490832)
		(end 400.1643 -75.99934)
		(width 0.089408)
		(layer "In11.Cu")
		(net "FM_ADR_COMPLETE")
	)
	(segment
		(start 400.2786 -78.511146)
		(end 400.710654 -78.9432)
		(width 0.089408)
		(layer "In11.Cu")
		(net "FM_ADR_COMPLETE")
	)
	(segment
		(start 321.124834 -36.09975)
		(end 321.520312 -35.704272)
		(width 0.089408)
		(layer "In11.Cu")
		(net "FM_ADR_COMPLETE")
	)
	(segment
		(start 400.710654 -83.90763)
		(end 402.68398 -85.880956)
		(width 0.089408)
		(layer "In11.Cu")
		(net "FM_ADR_COMPLETE")
	)
	(segment
		(start 375.539 -63.881)
		(end 375.242328 -63.584328)
		(width 0.089408)
		(layer "In11.Cu")
		(net "FM_ADR_COMPLETE")
	)
	(segment
		(start 323.158866 -42.938192)
		(end 322.299584 -42.938192)
		(width 0.089408)
		(layer "In11.Cu")
		(net "FM_ADR_COMPLETE")
	)
	(segment
		(start 319.626996 -40.265604)
		(end 319.626996 -36.575238)
		(width 0.089408)
		(layer "In11.Cu")
		(net "FM_ADR_COMPLETE")
	)
	(segment
		(start 375.539 -64.008)
		(end 375.539 -63.881)
		(width 0.089408)
		(layer "In11.Cu")
		(net "FM_ADR_COMPLETE")
	)
	(segment
		(start 375.242328 -61.84265)
		(end 374.120664 -60.720986)
		(width 0.089408)
		(layer "In11.Cu")
		(net "FM_ADR_COMPLETE")
	)
	(segment
		(start 400.2786 -77.360526)
		(end 400.2786 -78.511146)
		(width 0.089408)
		(layer "In11.Cu")
		(net "FM_ADR_COMPLETE")
	)
	(segment
		(start 319.626996 -36.575238)
		(end 320.102484 -36.09975)
		(width 0.089408)
		(layer "In11.Cu")
		(net "FM_ADR_COMPLETE")
	)
	(segment
		(start 398.326102 -72.774048)
		(end 399.655792 -74.103738)
		(width 0.089408)
		(layer "In11.Cu")
		(net "FM_ADR_COMPLETE")
	)
	(segment
		(start 396.875 -70.27799)
		(end 398.326102 -71.729092)
		(width 0.089408)
		(layer "In11.Cu")
		(net "FM_ADR_COMPLETE")
	)
	(segment
		(start 401.76704 -87.042752)
		(end 401.41271 -86.688422)
		(width 0.089408)
		(layer "In11.Cu")
		(net "FM_ADR_COMPLETE")
	)
	(segment
		(start 358.650286 -48.61052)
		(end 328.831194 -48.61052)
		(width 0.089408)
		(layer "In11.Cu")
		(net "FM_ADR_COMPLETE")
	)
	(segment
		(start 374.120664 -60.720986)
		(end 373.380508 -60.720986)
		(width 0.089408)
		(layer "In11.Cu")
		(net "FM_ADR_COMPLETE")
	)
	(segment
		(start 372.055136 -59.395614)
		(end 371.599968 -59.395614)
		(width 0.089408)
		(layer "In11.Cu")
		(net "FM_ADR_COMPLETE")
	)
	(segment
		(start 399.655792 -74.103738)
		(end 399.655792 -75.490832)
		(width 0.089408)
		(layer "In11.Cu")
		(net "FM_ADR_COMPLETE")
	)
	(segment
		(start 400.1643 -75.99934)
		(end 400.1643 -77.246226)
		(width 0.089408)
		(layer "In11.Cu")
		(net "FM_ADR_COMPLETE")
	)
	(segment
		(start 398.326102 -71.729092)
		(end 398.326102 -72.774048)
		(width 0.089408)
		(layer "In11.Cu")
		(net "FM_ADR_COMPLETE")
	)
	(segment
		(start 320.102484 -36.09975)
		(end 321.124834 -36.09975)
		(width 0.089408)
		(layer "In11.Cu")
		(net "FM_ADR_COMPLETE")
	)
	(segment
		(start 400.710654 -78.9432)
		(end 400.710654 -83.90763)
		(width 0.089408)
		(layer "In11.Cu")
		(net "FM_ADR_COMPLETE")
	)
	(segment
		(start 371.599968 -59.395614)
		(end 366.995456 -54.791102)
		(width 0.089408)
		(layer "In11.Cu")
		(net "FM_ADR_COMPLETE")
	)
	(segment
		(start 402.68398 -85.880956)
		(end 402.68398 -86.57082)
		(width 0.089408)
		(layer "In11.Cu")
		(net "FM_ADR_COMPLETE")
	)
	(segment
		(start 375.242328 -63.584328)
		(end 375.242328 -61.84265)
		(width 0.089408)
		(layer "In11.Cu")
		(net "FM_ADR_COMPLETE")
	)
	(segment
		(start 400.1643 -77.246226)
		(end 400.2786 -77.360526)
		(width 0.089408)
		(layer "In11.Cu")
		(net "FM_ADR_COMPLETE")
	)
	(segment
		(start 398.13865 -99.55276)
		(end 398.63395 -99.322636)
		(width 0.10795)
		(layer "F.Cu")
		(net "PU_IRQ_VRALERT_N")
	)
	(via
		(at 402.665692 -97.285302)
		(size 0.6604)
		(drill 0.3302)
		(layers "F.Cu" "B.Cu")
		(net "PU_IRQ_VRALERT_N")
	)
	(via
		(at 398.63395 -99.322636)
		(size 0.508)
		(drill 0.254)
		(layers "F.Cu" "B.Cu")
		(net "PU_IRQ_VRALERT_N")
	)
	(segment
		(start 398.63395 -99.322636)
		(end 399.074386 -99.763072)
		(width 0.10795)
		(layer "B.Cu")
		(net "PU_IRQ_VRALERT_N")
	)
	(segment
		(start 402.795994 -97.155)
		(end 403.6695 -97.155)
		(width 0.10795)
		(layer "B.Cu")
		(net "PU_IRQ_VRALERT_N")
	)
	(segment
		(start 399.074386 -99.763072)
		(end 399.824194 -99.763072)
		(width 0.10795)
		(layer "B.Cu")
		(net "PU_IRQ_VRALERT_N")
	)
	(segment
		(start 399.824194 -99.763072)
		(end 402.301964 -97.285302)
		(width 0.10795)
		(layer "B.Cu")
		(net "PU_IRQ_VRALERT_N")
	)
	(segment
		(start 402.301964 -97.285302)
		(end 402.665692 -97.285302)
		(width 0.10795)
		(layer "B.Cu")
		(net "PU_IRQ_VRALERT_N")
	)
	(segment
		(start 402.665692 -97.285302)
		(end 402.795994 -97.155)
		(width 0.10795)
		(layer "B.Cu")
		(net "PU_IRQ_VRALERT_N")
	)
	(via
		(at 417.5125 -68.0466)
		(size 0.6604)
		(drill 0.3302)
		(layers "F.Cu" "B.Cu")
		(net "FM_FAST_PROCHOT_EN")
	)
	(segment
		(start 417.5125 -71.8947)
		(end 417.6522 -72.0344)
		(width 0.10795)
		(layer "B.Cu")
		(net "FM_FAST_PROCHOT_EN")
	)
	(segment
		(start 417.6522 -73.1647)
		(end 417.1823 -73.1647)
		(width 0.10795)
		(layer "B.Cu")
		(net "FM_FAST_PROCHOT_EN")
	)
	(segment
		(start 417.5125 -70.993)
		(end 417.5125 -71.8947)
		(width 0.10795)
		(layer "B.Cu")
		(net "FM_FAST_PROCHOT_EN")
	)
	(segment
		(start 417.1823 -73.1647)
		(end 416.889184 -73.457816)
		(width 0.10795)
		(layer "B.Cu")
		(net "FM_FAST_PROCHOT_EN")
	)
	(segment
		(start 417.5125 -68.0466)
		(end 417.5125 -70.993)
		(width 0.10795)
		(layer "B.Cu")
		(net "FM_FAST_PROCHOT_EN")
	)
	(segment
		(start 416.889184 -73.457816)
		(end 416.889184 -75.296014)
		(width 0.10795)
		(layer "B.Cu")
		(net "FM_FAST_PROCHOT_EN")
	)
	(segment
		(start 417.6522 -72.0344)
		(end 417.6522 -73.1647)
		(width 0.10795)
		(layer "B.Cu")
		(net "FM_FAST_PROCHOT_EN")
	)
	(segment
		(start 456.191874 -9.220962)
		(end 456.191874 -8.94588)
		(width 0.127)
		(layer "F.Cu")
		(net "CLK_100M_PCH_SLOTX24_S3_DP")
	)
	(segment
		(start 456.191874 -8.94588)
		(end 456.477878 -8.659876)
		(width 0.127)
		(layer "F.Cu")
		(net "CLK_100M_PCH_SLOTX24_S3_DP")
	)
	(segment
		(start 456.6158 -9.348216)
		(end 456.319128 -9.348216)
		(width 0.127)
		(layer "F.Cu")
		(net "CLK_100M_PCH_SLOTX24_S3_DP")
	)
	(segment
		(start 456.319128 -9.348216)
		(end 456.191874 -9.220962)
		(width 0.127)
		(layer "F.Cu")
		(net "CLK_100M_PCH_SLOTX24_S3_DP")
	)
	(segment
		(start 377.33605 -111.57204)
		(end 377.83135 -111.802164)
		(width 0.127)
		(layer "F.Cu")
		(net "CLK_100M_PCH_SLOTX24_S3_DP")
	)
	(segment
		(start 456.477878 -8.659876)
		(end 456.477878 -7.789672)
		(width 0.127)
		(layer "F.Cu")
		(net "CLK_100M_PCH_SLOTX24_S3_DP")
	)
	(via
		(at 377.83135 -111.802164)
		(size 0.508)
		(drill 0.254)
		(layers "F.Cu" "B.Cu")
		(net "CLK_100M_PCH_SLOTX24_S3_DP")
	)
	(via
		(at 456.6158 -9.348216)
		(size 0.508)
		(drill 0.254)
		(layers "F.Cu" "B.Cu")
		(net "CLK_100M_PCH_SLOTX24_S3_DP")
	)
	(segment
		(start 370.53266 -39.519606)
		(end 371.252242 -36.893246)
		(width 0.1143)
		(layer "In2.Cu")
		(net "CLK_100M_PCH_SLOTX24_S3_DP")
	)
	(segment
		(start 442.415168 -14.636242)
		(end 442.415168 -14.636496)
		(width 0.1143)
		(layer "In2.Cu")
		(net "CLK_100M_PCH_SLOTX24_S3_DP")
	)
	(segment
		(start 369.689888 -99.415346)
		(end 369.479322 -98.42119)
		(width 0.1143)
		(layer "In2.Cu")
		(net "CLK_100M_PCH_SLOTX24_S3_DP")
	)
	(segment
		(start 371.057424 -42.07637)
		(end 370.53266 -39.519606)
		(width 0.1143)
		(layer "In2.Cu")
		(net "CLK_100M_PCH_SLOTX24_S3_DP")
	)
	(segment
		(start 377.192286 -111.7346)
		(end 376.58675 -111.7346)
		(width 0.0889)
		(layer "In2.Cu")
		(net "CLK_100M_PCH_SLOTX24_S3_DP")
	)
	(segment
		(start 374.72874 -108.786422)
		(end 374.76684 -108.748322)
		(width 0.0889)
		(layer "In2.Cu")
		(net "CLK_100M_PCH_SLOTX24_S3_DP")
	)
	(segment
		(start 370.848636 -35.498024)
		(end 372.165118 -29.30652)
		(width 0.1143)
		(layer "In2.Cu")
		(net "CLK_100M_PCH_SLOTX24_S3_DP")
	)
	(segment
		(start 375.923048 -111.070898)
		(end 375.73458 -110.88243)
		(width 0.0889)
		(layer "In2.Cu")
		(net "CLK_100M_PCH_SLOTX24_S3_DP")
	)
	(segment
		(start 376.58675 -111.7346)
		(end 376.2375 -111.38535)
		(width 0.0889)
		(layer "In2.Cu")
		(net "CLK_100M_PCH_SLOTX24_S3_DP")
	)
	(segment
		(start 374.263158 -107.9627)
		(end 371.7544 -107.9627)
		(width 0.1143)
		(layer "In2.Cu")
		(net "CLK_100M_PCH_SLOTX24_S3_DP")
	)
	(segment
		(start 427.612556 -16.7767)
		(end 428.030132 -16.145764)
		(width 0.1143)
		(layer "In2.Cu")
		(net "CLK_100M_PCH_SLOTX24_S3_DP")
	)
	(segment
		(start 426.983652 -17.192752)
		(end 427.612556 -16.7767)
		(width 0.1143)
		(layer "In2.Cu")
		(net "CLK_100M_PCH_SLOTX24_S3_DP")
	)
	(segment
		(start 422.122346 -17.160494)
		(end 423.270172 -16.930878)
		(width 0.1143)
		(layer "In2.Cu")
		(net "CLK_100M_PCH_SLOTX24_S3_DP")
	)
	(segment
		(start 374.72874 -109.87659)
		(end 374.72874 -109.60989)
		(width 0.0889)
		(layer "In2.Cu")
		(net "CLK_100M_PCH_SLOTX24_S3_DP")
	)
	(segment
		(start 369.861592 -51.462178)
		(end 368.9731 -48.661574)
		(width 0.1143)
		(layer "In2.Cu")
		(net "CLK_100M_PCH_SLOTX24_S3_DP")
	)
	(segment
		(start 402.62556 -21.873718)
		(end 402.982938 -22.231096)
		(width 0.1143)
		(layer "In2.Cu")
		(net "CLK_100M_PCH_SLOTX24_S3_DP")
	)
	(segment
		(start 368.9731 -48.661574)
		(end 371.057424 -42.07637)
		(width 0.1143)
		(layer "In2.Cu")
		(net "CLK_100M_PCH_SLOTX24_S3_DP")
	)
	(segment
		(start 374.81764 -109.25429)
		(end 374.72874 -109.16539)
		(width 0.0889)
		(layer "In2.Cu")
		(net "CLK_100M_PCH_SLOTX24_S3_DP")
	)
	(segment
		(start 449.754498 -11.324336)
		(end 451.1421 -11.04646)
		(width 0.1143)
		(layer "In2.Cu")
		(net "CLK_100M_PCH_SLOTX24_S3_DP")
	)
	(segment
		(start 439.549032 -14.027658)
		(end 442.415168 -14.636242)
		(width 0.1143)
		(layer "In2.Cu")
		(net "CLK_100M_PCH_SLOTX24_S3_DP")
	)
	(segment
		(start 388.668514 -18.840704)
		(end 395.435328 -20.508722)
		(width 0.1143)
		(layer "In2.Cu")
		(net "CLK_100M_PCH_SLOTX24_S3_DP")
	)
	(segment
		(start 374.72874 -109.16539)
		(end 374.72874 -108.786422)
		(width 0.0889)
		(layer "In2.Cu")
		(net "CLK_100M_PCH_SLOTX24_S3_DP")
	)
	(segment
		(start 375.042938 -110.065058)
		(end 374.917208 -110.065058)
		(width 0.0889)
		(layer "In2.Cu")
		(net "CLK_100M_PCH_SLOTX24_S3_DP")
	)
	(segment
		(start 375.23166 -110.37951)
		(end 375.23166 -110.25378)
		(width 0.0889)
		(layer "In2.Cu")
		(net "CLK_100M_PCH_SLOTX24_S3_DP")
	)
	(segment
		(start 376.2375 -111.25962)
		(end 376.048778 -111.070898)
		(width 0.0889)
		(layer "In2.Cu")
		(net "CLK_100M_PCH_SLOTX24_S3_DP")
	)
	(segment
		(start 455.163682 -11.018012)
		(end 455.849228 -10.560812)
		(width 0.1143)
		(layer "In2.Cu")
		(net "CLK_100M_PCH_SLOTX24_S3_DP")
	)
	(segment
		(start 378.031248 -112.148874)
		(end 377.94692 -112.197388)
		(width 0.0889)
		(layer "In2.Cu")
		(net "CLK_100M_PCH_SLOTX24_S3_DP")
	)
	(segment
		(start 409.687268 -21.231352)
		(end 411.136846 -20.264882)
		(width 0.1143)
		(layer "In2.Cu")
		(net "CLK_100M_PCH_SLOTX24_S3_DP")
	)
	(segment
		(start 434.90261 -14.964664)
		(end 435.970172 -15.18031)
		(width 0.1143)
		(layer "In2.Cu")
		(net "CLK_100M_PCH_SLOTX24_S3_DP")
	)
	(segment
		(start 423.270172 -16.930878)
		(end 425.792392 -17.435576)
		(width 0.1143)
		(layer "In2.Cu")
		(net "CLK_100M_PCH_SLOTX24_S3_DP")
	)
	(segment
		(start 370.720874 -106.758486)
		(end 369.438936 -100.59797)
		(width 0.1143)
		(layer "In2.Cu")
		(net "CLK_100M_PCH_SLOTX24_S3_DP")
	)
	(segment
		(start 369.04549 -94.103444)
		(end 366.459008 -90.637106)
		(width 0.1143)
		(layer "In2.Cu")
		(net "CLK_100M_PCH_SLOTX24_S3_DP")
	)
	(segment
		(start 453.080882 -11.434064)
		(end 455.163682 -11.018012)
		(width 0.1143)
		(layer "In2.Cu")
		(net "CLK_100M_PCH_SLOTX24_S3_DP")
	)
	(segment
		(start 445.805052 -13.958062)
		(end 449.754498 -11.324336)
		(width 0.1143)
		(layer "In2.Cu")
		(net "CLK_100M_PCH_SLOTX24_S3_DP")
	)
	(segment
		(start 375.420128 -110.567978)
		(end 375.23166 -110.37951)
		(width 0.0889)
		(layer "In2.Cu")
		(net "CLK_100M_PCH_SLOTX24_S3_DP")
	)
	(segment
		(start 369.438936 -100.59797)
		(end 369.689888 -99.415346)
		(width 0.1143)
		(layer "In2.Cu")
		(net "CLK_100M_PCH_SLOTX24_S3_DP")
	)
	(segment
		(start 397.382746 -20.898358)
		(end 400.028664 -20.470114)
		(width 0.1143)
		(layer "In2.Cu")
		(net "CLK_100M_PCH_SLOTX24_S3_DP")
	)
	(segment
		(start 381.495554 -20.398486)
		(end 388.668514 -18.840704)
		(width 0.1143)
		(layer "In2.Cu")
		(net "CLK_100M_PCH_SLOTX24_S3_DP")
	)
	(segment
		(start 364.292896 -87.116158)
		(end 364.906814 -84.047076)
		(width 0.1143)
		(layer "In2.Cu")
		(net "CLK_100M_PCH_SLOTX24_S3_DP")
	)
	(segment
		(start 379.52934 -22.788372)
		(end 379.742192 -22.510496)
		(width 0.1143)
		(layer "In2.Cu")
		(net "CLK_100M_PCH_SLOTX24_S3_DP")
	)
	(segment
		(start 364.906814 -84.047076)
		(end 364.0836 -80.162146)
		(width 0.1143)
		(layer "In2.Cu")
		(net "CLK_100M_PCH_SLOTX24_S3_DP")
	)
	(segment
		(start 442.474096 -14.648942)
		(end 445.756284 -13.993114)
		(width 0.1143)
		(layer "In2.Cu")
		(net "CLK_100M_PCH_SLOTX24_S3_DP")
	)
	(segment
		(start 400.748246 -20.613878)
		(end 402.62556 -21.873718)
		(width 0.1143)
		(layer "In2.Cu")
		(net "CLK_100M_PCH_SLOTX24_S3_DP")
	)
	(segment
		(start 372.165118 -29.30652)
		(end 376.089418 -24.05761)
		(width 0.1143)
		(layer "In2.Cu")
		(net "CLK_100M_PCH_SLOTX24_S3_DP")
	)
	(segment
		(start 368.880136 -56.411622)
		(end 369.861592 -51.462178)
		(width 0.1143)
		(layer "In2.Cu")
		(net "CLK_100M_PCH_SLOTX24_S3_DP")
	)
	(segment
		(start 445.756284 -13.993114)
		(end 445.805052 -13.958062)
		(width 0.1143)
		(layer "In2.Cu")
		(net "CLK_100M_PCH_SLOTX24_S3_DP")
	)
	(segment
		(start 376.2375 -111.38535)
		(end 376.2375 -111.25962)
		(width 0.0889)
		(layer "In2.Cu")
		(net "CLK_100M_PCH_SLOTX24_S3_DP")
	)
	(segment
		(start 411.136846 -20.265136)
		(end 416.15487 -19.261074)
		(width 0.1143)
		(layer "In2.Cu")
		(net "CLK_100M_PCH_SLOTX24_S3_DP")
	)
	(segment
		(start 455.849228 -10.560812)
		(end 456.1586 -10.0965)
		(width 0.1143)
		(layer "In2.Cu")
		(net "CLK_100M_PCH_SLOTX24_S3_DP")
	)
	(segment
		(start 404.530052 -22.231096)
		(end 407.409396 -22.9235)
		(width 0.1143)
		(layer "In2.Cu")
		(net "CLK_100M_PCH_SLOTX24_S3_DP")
	)
	(segment
		(start 378.893832 -23.20798)
		(end 379.52934 -22.788372)
		(width 0.1143)
		(layer "In2.Cu")
		(net "CLK_100M_PCH_SLOTX24_S3_DP")
	)
	(segment
		(start 376.089418 -24.05761)
		(end 378.893832 -23.20798)
		(width 0.1143)
		(layer "In2.Cu")
		(net "CLK_100M_PCH_SLOTX24_S3_DP")
	)
	(segment
		(start 411.136846 -20.264882)
		(end 411.136846 -20.265136)
		(width 0.1143)
		(layer "In2.Cu")
		(net "CLK_100M_PCH_SLOTX24_S3_DP")
	)
	(segment
		(start 437.226202 -14.924532)
		(end 437.226202 -14.924786)
		(width 0.1143)
		(layer "In2.Cu")
		(net "CLK_100M_PCH_SLOTX24_S3_DP")
	)
	(segment
		(start 402.982938 -22.231096)
		(end 404.530052 -22.231096)
		(width 0.1143)
		(layer "In2.Cu")
		(net "CLK_100M_PCH_SLOTX24_S3_DP")
	)
	(segment
		(start 375.73458 -110.88243)
		(end 375.73458 -110.7567)
		(width 0.0889)
		(layer "In2.Cu")
		(net "CLK_100M_PCH_SLOTX24_S3_DP")
	)
	(segment
		(start 374.76684 -108.748322)
		(end 374.76684 -108.737146)
		(width 0.0889)
		(layer "In2.Cu")
		(net "CLK_100M_PCH_SLOTX24_S3_DP")
	)
	(segment
		(start 375.23166 -110.25378)
		(end 375.042938 -110.065058)
		(width 0.0889)
		(layer "In2.Cu")
		(net "CLK_100M_PCH_SLOTX24_S3_DP")
	)
	(segment
		(start 429.185324 -15.795244)
		(end 430.00295 -15.961614)
		(width 0.1143)
		(layer "In2.Cu")
		(net "CLK_100M_PCH_SLOTX24_S3_DP")
	)
	(segment
		(start 380.46152 -21.116798)
		(end 381.495554 -20.398486)
		(width 0.1143)
		(layer "In2.Cu")
		(net "CLK_100M_PCH_SLOTX24_S3_DP")
	)
	(segment
		(start 377.601988 -112.144302)
		(end 377.192286 -111.7346)
		(width 0.0889)
		(layer "In2.Cu")
		(net "CLK_100M_PCH_SLOTX24_S3_DP")
	)
	(segment
		(start 371.252242 -36.893246)
		(end 370.848636 -35.498024)
		(width 0.1143)
		(layer "In2.Cu")
		(net "CLK_100M_PCH_SLOTX24_S3_DP")
	)
	(segment
		(start 364.0836 -80.162146)
		(end 364.0836 -76.602844)
		(width 0.1143)
		(layer "In2.Cu")
		(net "CLK_100M_PCH_SLOTX24_S3_DP")
	)
	(segment
		(start 437.226202 -14.924786)
		(end 437.250586 -14.919706)
		(width 0.1143)
		(layer "In2.Cu")
		(net "CLK_100M_PCH_SLOTX24_S3_DP")
	)
	(segment
		(start 456.1586 -9.805416)
		(end 456.6158 -9.348216)
		(width 0.1143)
		(layer "In2.Cu")
		(net "CLK_100M_PCH_SLOTX24_S3_DP")
	)
	(segment
		(start 364.0836 -76.602844)
		(end 362.856018 -70.79361)
		(width 0.1143)
		(layer "In2.Cu")
		(net "CLK_100M_PCH_SLOTX24_S3_DP")
	)
	(segment
		(start 430.00295 -15.961614)
		(end 434.90261 -14.964664)
		(width 0.1143)
		(layer "In2.Cu")
		(net "CLK_100M_PCH_SLOTX24_S3_DP")
	)
	(segment
		(start 376.048778 -111.070898)
		(end 375.923048 -111.070898)
		(width 0.0889)
		(layer "In2.Cu")
		(net "CLK_100M_PCH_SLOTX24_S3_DP")
	)
	(segment
		(start 451.1421 -11.04646)
		(end 453.080882 -11.434064)
		(width 0.1143)
		(layer "In2.Cu")
		(net "CLK_100M_PCH_SLOTX24_S3_DP")
	)
	(segment
		(start 456.1586 -10.0965)
		(end 456.1586 -9.805416)
		(width 0.1143)
		(layer "In2.Cu")
		(net "CLK_100M_PCH_SLOTX24_S3_DP")
	)
	(segment
		(start 375.73458 -110.7567)
		(end 375.545858 -110.567978)
		(width 0.0889)
		(layer "In2.Cu")
		(net "CLK_100M_PCH_SLOTX24_S3_DP")
	)
	(segment
		(start 368.165888 -57.48274)
		(end 368.880136 -56.411622)
		(width 0.1143)
		(layer "In2.Cu")
		(net "CLK_100M_PCH_SLOTX24_S3_DP")
	)
	(segment
		(start 437.250586 -14.919706)
		(end 439.549032 -14.027658)
		(width 0.1143)
		(layer "In2.Cu")
		(net "CLK_100M_PCH_SLOTX24_S3_DP")
	)
	(segment
		(start 379.742192 -22.510496)
		(end 380.46152 -21.116798)
		(width 0.1143)
		(layer "In2.Cu")
		(net "CLK_100M_PCH_SLOTX24_S3_DP")
	)
	(segment
		(start 371.7544 -107.9627)
		(end 371.04447 -107.252516)
		(width 0.1143)
		(layer "In2.Cu")
		(net "CLK_100M_PCH_SLOTX24_S3_DP")
	)
	(segment
		(start 362.985812 -68.376292)
		(end 364.41888 -66.561462)
		(width 0.1143)
		(layer "In2.Cu")
		(net "CLK_100M_PCH_SLOTX24_S3_DP")
	)
	(segment
		(start 442.415168 -14.636496)
		(end 442.474096 -14.648942)
		(width 0.1143)
		(layer "In2.Cu")
		(net "CLK_100M_PCH_SLOTX24_S3_DP")
	)
	(segment
		(start 369.479322 -98.42119)
		(end 369.479322 -96.2152)
		(width 0.1143)
		(layer "In2.Cu")
		(net "CLK_100M_PCH_SLOTX24_S3_DP")
	)
	(segment
		(start 395.435328 -20.508722)
		(end 397.382746 -20.898358)
		(width 0.1143)
		(layer "In2.Cu")
		(net "CLK_100M_PCH_SLOTX24_S3_DP")
	)
	(segment
		(start 407.409396 -22.9235)
		(end 408.299158 -22.9235)
		(width 0.1143)
		(layer "In2.Cu")
		(net "CLK_100M_PCH_SLOTX24_S3_DP")
	)
	(segment
		(start 408.716734 -22.687534)
		(end 409.687268 -21.231352)
		(width 0.1143)
		(layer "In2.Cu")
		(net "CLK_100M_PCH_SLOTX24_S3_DP")
	)
	(segment
		(start 369.479322 -96.2152)
		(end 369.04549 -94.103444)
		(width 0.1143)
		(layer "In2.Cu")
		(net "CLK_100M_PCH_SLOTX24_S3_DP")
	)
	(segment
		(start 374.76684 -108.737146)
		(end 374.76684 -108.466382)
		(width 0.1143)
		(layer "In2.Cu")
		(net "CLK_100M_PCH_SLOTX24_S3_DP")
	)
	(segment
		(start 364.77194 -89.512648)
		(end 364.292896 -87.116158)
		(width 0.1143)
		(layer "In2.Cu")
		(net "CLK_100M_PCH_SLOTX24_S3_DP")
	)
	(segment
		(start 400.028664 -20.470114)
		(end 400.748246 -20.613878)
		(width 0.1143)
		(layer "In2.Cu")
		(net "CLK_100M_PCH_SLOTX24_S3_DP")
	)
	(segment
		(start 374.76684 -108.466382)
		(end 374.263158 -107.9627)
		(width 0.1143)
		(layer "In2.Cu")
		(net "CLK_100M_PCH_SLOTX24_S3_DP")
	)
	(segment
		(start 364.768638 -65.207642)
		(end 368.165888 -57.48274)
		(width 0.1143)
		(layer "In2.Cu")
		(net "CLK_100M_PCH_SLOTX24_S3_DP")
	)
	(segment
		(start 375.545858 -110.567978)
		(end 375.420128 -110.567978)
		(width 0.0889)
		(layer "In2.Cu")
		(net "CLK_100M_PCH_SLOTX24_S3_DP")
	)
	(segment
		(start 428.030132 -16.145764)
		(end 428.281846 -15.97914)
		(width 0.1143)
		(layer "In2.Cu")
		(net "CLK_100M_PCH_SLOTX24_S3_DP")
	)
	(segment
		(start 366.459008 -90.637106)
		(end 364.77194 -89.512648)
		(width 0.1143)
		(layer "In2.Cu")
		(net "CLK_100M_PCH_SLOTX24_S3_DP")
	)
	(segment
		(start 428.281846 -15.97914)
		(end 429.185324 -15.795244)
		(width 0.1143)
		(layer "In2.Cu")
		(net "CLK_100M_PCH_SLOTX24_S3_DP")
	)
	(segment
		(start 364.41888 -66.561462)
		(end 364.768638 -65.207642)
		(width 0.1143)
		(layer "In2.Cu")
		(net "CLK_100M_PCH_SLOTX24_S3_DP")
	)
	(segment
		(start 374.917208 -110.065058)
		(end 374.72874 -109.87659)
		(width 0.0889)
		(layer "In2.Cu")
		(net "CLK_100M_PCH_SLOTX24_S3_DP")
	)
	(segment
		(start 363.211364 -69.315838)
		(end 362.985812 -68.376292)
		(width 0.1143)
		(layer "In2.Cu")
		(net "CLK_100M_PCH_SLOTX24_S3_DP")
	)
	(segment
		(start 425.792392 -17.435576)
		(end 426.983652 -17.192752)
		(width 0.1143)
		(layer "In2.Cu")
		(net "CLK_100M_PCH_SLOTX24_S3_DP")
	)
	(segment
		(start 371.04447 -107.252516)
		(end 370.720874 -106.758486)
		(width 0.1143)
		(layer "In2.Cu")
		(net "CLK_100M_PCH_SLOTX24_S3_DP")
	)
	(segment
		(start 362.856018 -70.79361)
		(end 363.211364 -69.315838)
		(width 0.1143)
		(layer "In2.Cu")
		(net "CLK_100M_PCH_SLOTX24_S3_DP")
	)
	(segment
		(start 416.15487 -19.261074)
		(end 422.122346 -17.160494)
		(width 0.1143)
		(layer "In2.Cu")
		(net "CLK_100M_PCH_SLOTX24_S3_DP")
	)
	(segment
		(start 408.299158 -22.9235)
		(end 408.716734 -22.687534)
		(width 0.1143)
		(layer "In2.Cu")
		(net "CLK_100M_PCH_SLOTX24_S3_DP")
	)
	(segment
		(start 435.970172 -15.18031)
		(end 437.226202 -14.924532)
		(width 0.1143)
		(layer "In2.Cu")
		(net "CLK_100M_PCH_SLOTX24_S3_DP")
	)
	(segment
		(start 374.72874 -109.60989)
		(end 374.81764 -109.52099)
		(width 0.0889)
		(layer "In2.Cu")
		(net "CLK_100M_PCH_SLOTX24_S3_DP")
	)
	(segment
		(start 374.81764 -109.52099)
		(end 374.81764 -109.25429)
		(width 0.0889)
		(layer "In2.Cu")
		(net "CLK_100M_PCH_SLOTX24_S3_DP")
	)
	(arc
		(start 378.227336 -111.860076)
		(mid 378.209325 -111.933668)
		(end 378.177806 -112.00257)
		(width 0.0889)
		(layer "In2.Cu")
		(net "CLK_100M_PCH_SLOTX24_S3_DP")
	)
	(arc
		(start 378.177806 -112.00257)
		(mid 378.114164 -112.085379)
		(end 378.031248 -112.148874)
		(width 0.0889)
		(layer "In2.Cu")
		(net "CLK_100M_PCH_SLOTX24_S3_DP")
	)
	(arc
		(start 377.94692 -112.197388)
		(mid 377.768537 -112.209231)
		(end 377.601988 -112.144302)
		(width 0.0889)
		(layer "In2.Cu")
		(net "CLK_100M_PCH_SLOTX24_S3_DP")
	)
	(arc
		(start 377.83135 -111.802164)
		(mid 378.058444 -111.633003)
		(end 378.227336 -111.860076)
		(width 0.0889)
		(layer "In2.Cu")
		(net "CLK_100M_PCH_SLOTX24_S3_DP")
	)
	(segment
		(start 455.677778 -8.659876)
		(end 455.887074 -8.869172)
		(width 0.127)
		(layer "F.Cu")
		(net "CLK_100M_PCH_SLOTX24_S3_DN")
	)
	(segment
		(start 455.887074 -8.869172)
		(end 455.887074 -9.078468)
		(width 0.127)
		(layer "F.Cu")
		(net "CLK_100M_PCH_SLOTX24_S3_DN")
	)
	(segment
		(start 378.32665 -111.57204)
		(end 378.82195 -111.802164)
		(width 0.127)
		(layer "F.Cu")
		(net "CLK_100M_PCH_SLOTX24_S3_DN")
	)
	(segment
		(start 455.887074 -9.078468)
		(end 455.600308 -9.365234)
		(width 0.127)
		(layer "F.Cu")
		(net "CLK_100M_PCH_SLOTX24_S3_DN")
	)
	(segment
		(start 455.600308 -9.365234)
		(end 455.3458 -9.365234)
		(width 0.127)
		(layer "F.Cu")
		(net "CLK_100M_PCH_SLOTX24_S3_DN")
	)
	(segment
		(start 455.677778 -7.789672)
		(end 455.677778 -8.659876)
		(width 0.127)
		(layer "F.Cu")
		(net "CLK_100M_PCH_SLOTX24_S3_DN")
	)
	(via
		(at 455.3458 -9.365234)
		(size 0.508)
		(drill 0.254)
		(layers "F.Cu" "B.Cu")
		(net "CLK_100M_PCH_SLOTX24_S3_DN")
	)
	(via
		(at 378.82195 -111.802164)
		(size 0.508)
		(drill 0.254)
		(layers "F.Cu" "B.Cu")
		(net "CLK_100M_PCH_SLOTX24_S3_DN")
	)
	(segment
		(start 453.080882 -11.136122)
		(end 451.1421 -10.748518)
		(width 0.1143)
		(layer "In2.Cu")
		(net "CLK_100M_PCH_SLOTX24_S3_DN")
	)
	(segment
		(start 370.446046 -106.872532)
		(end 370.816378 -107.437936)
		(width 0.1143)
		(layer "In2.Cu")
		(net "CLK_100M_PCH_SLOTX24_S3_DN")
	)
	(segment
		(start 377.113292 -111.9251)
		(end 377.296172 -112.10798)
		(width 0.0889)
		(layer "In2.Cu")
		(net "CLK_100M_PCH_SLOTX24_S3_DN")
	)
	(segment
		(start 426.321982 -17.028922)
		(end 425.791884 -17.13738)
		(width 0.1143)
		(layer "In2.Cu")
		(net "CLK_100M_PCH_SLOTX24_S3_DN")
	)
	(segment
		(start 400.033998 -20.173188)
		(end 397.388334 -20.601432)
		(width 0.1143)
		(layer "In2.Cu")
		(net "CLK_100M_PCH_SLOTX24_S3_DN")
	)
	(segment
		(start 377.296172 -112.10798)
		(end 377.296172 -112.108234)
		(width 0.0889)
		(layer "In2.Cu")
		(net "CLK_100M_PCH_SLOTX24_S3_DN")
	)
	(segment
		(start 409.476448 -21.020532)
		(end 408.512264 -22.467316)
		(width 0.1143)
		(layer "In2.Cu")
		(net "CLK_100M_PCH_SLOTX24_S3_DN")
	)
	(segment
		(start 375.912888 -23.805642)
		(end 371.892576 -29.182822)
		(width 0.1143)
		(layer "In2.Cu")
		(net "CLK_100M_PCH_SLOTX24_S3_DN")
	)
	(segment
		(start 442.475874 -14.350492)
		(end 439.524394 -13.72362)
		(width 0.1143)
		(layer "In2.Cu")
		(net "CLK_100M_PCH_SLOTX24_S3_DN")
	)
	(segment
		(start 371.892576 -29.182822)
		(end 370.547646 -35.508946)
		(width 0.1143)
		(layer "In2.Cu")
		(net "CLK_100M_PCH_SLOTX24_S3_DN")
	)
	(segment
		(start 374.142 -108.2548)
		(end 374.47474 -108.58754)
		(width 0.1143)
		(layer "In2.Cu")
		(net "CLK_100M_PCH_SLOTX24_S3_DN")
	)
	(segment
		(start 374.47474 -108.759752)
		(end 374.53824 -108.823252)
		(width 0.0889)
		(layer "In2.Cu")
		(net "CLK_100M_PCH_SLOTX24_S3_DN")
	)
	(segment
		(start 455.8665 -9.885934)
		(end 455.8665 -10.007854)
		(width 0.1143)
		(layer "In2.Cu")
		(net "CLK_100M_PCH_SLOTX24_S3_DN")
	)
	(segment
		(start 402.81225 -21.646896)
		(end 400.862546 -20.338796)
		(width 0.1143)
		(layer "In2.Cu")
		(net "CLK_100M_PCH_SLOTX24_S3_DN")
	)
	(segment
		(start 366.255046 -90.852244)
		(end 368.772186 -94.226126)
		(width 0.1143)
		(layer "In2.Cu")
		(net "CLK_100M_PCH_SLOTX24_S3_DN")
	)
	(segment
		(start 370.816378 -107.437936)
		(end 371.633242 -108.2548)
		(width 0.1143)
		(layer "In2.Cu")
		(net "CLK_100M_PCH_SLOTX24_S3_DN")
	)
	(segment
		(start 378.023628 -112.373664)
		(end 378.126752 -112.313974)
		(width 0.0889)
		(layer "In2.Cu")
		(net "CLK_100M_PCH_SLOTX24_S3_DN")
	)
	(segment
		(start 370.948712 -36.895278)
		(end 370.232432 -39.509954)
		(width 0.1143)
		(layer "In2.Cu")
		(net "CLK_100M_PCH_SLOTX24_S3_DN")
	)
	(segment
		(start 427.401736 -16.56588)
		(end 426.869606 -16.91767)
		(width 0.1143)
		(layer "In2.Cu")
		(net "CLK_100M_PCH_SLOTX24_S3_DN")
	)
	(segment
		(start 408.512264 -22.467316)
		(end 408.222196 -22.6314)
		(width 0.1143)
		(layer "In2.Cu")
		(net "CLK_100M_PCH_SLOTX24_S3_DN")
	)
	(segment
		(start 455.049636 -10.742676)
		(end 453.080882 -11.136122)
		(width 0.1143)
		(layer "In2.Cu")
		(net "CLK_100M_PCH_SLOTX24_S3_DN")
	)
	(segment
		(start 374.47474 -108.58754)
		(end 374.47474 -108.737146)
		(width 0.1143)
		(layer "In2.Cu")
		(net "CLK_100M_PCH_SLOTX24_S3_DN")
	)
	(segment
		(start 369.140232 -100.597462)
		(end 370.446046 -106.872532)
		(width 0.1143)
		(layer "In2.Cu")
		(net "CLK_100M_PCH_SLOTX24_S3_DN")
	)
	(segment
		(start 429.185324 -15.497048)
		(end 428.1678 -15.704058)
		(width 0.1143)
		(layer "In2.Cu")
		(net "CLK_100M_PCH_SLOTX24_S3_DN")
	)
	(segment
		(start 370.547646 -35.508946)
		(end 370.948712 -36.895278)
		(width 0.1143)
		(layer "In2.Cu")
		(net "CLK_100M_PCH_SLOTX24_S3_DN")
	)
	(segment
		(start 404.56485 -21.938996)
		(end 403.104096 -21.938996)
		(width 0.1143)
		(layer "In2.Cu")
		(net "CLK_100M_PCH_SLOTX24_S3_DN")
	)
	(segment
		(start 449.640452 -11.049254)
		(end 445.63919 -13.717524)
		(width 0.1143)
		(layer "In2.Cu")
		(net "CLK_100M_PCH_SLOTX24_S3_DN")
	)
	(segment
		(start 437.168036 -14.638274)
		(end 435.969918 -14.882114)
		(width 0.1143)
		(layer "In2.Cu")
		(net "CLK_100M_PCH_SLOTX24_S3_DN")
	)
	(segment
		(start 374.53824 -108.823252)
		(end 374.53824 -109.955584)
		(width 0.0889)
		(layer "In2.Cu")
		(net "CLK_100M_PCH_SLOTX24_S3_DN")
	)
	(segment
		(start 364.491524 -65.11163)
		(end 364.151164 -66.42862)
		(width 0.1143)
		(layer "In2.Cu")
		(net "CLK_100M_PCH_SLOTX24_S3_DN")
	)
	(segment
		(start 455.3458 -9.365234)
		(end 455.8665 -9.885934)
		(width 0.1143)
		(layer "In2.Cu")
		(net "CLK_100M_PCH_SLOTX24_S3_DN")
	)
	(segment
		(start 426.322236 -17.029176)
		(end 426.321982 -17.028922)
		(width 0.1143)
		(layer "In2.Cu")
		(net "CLK_100M_PCH_SLOTX24_S3_DN")
	)
	(segment
		(start 435.969918 -14.882114)
		(end 434.902356 -14.666468)
		(width 0.1143)
		(layer "In2.Cu")
		(net "CLK_100M_PCH_SLOTX24_S3_DN")
	)
	(segment
		(start 416.0774 -18.978626)
		(end 411.0228 -19.9898)
		(width 0.1143)
		(layer "In2.Cu")
		(net "CLK_100M_PCH_SLOTX24_S3_DN")
	)
	(segment
		(start 430.00295 -15.663418)
		(end 429.185324 -15.497048)
		(width 0.1143)
		(layer "In2.Cu")
		(net "CLK_100M_PCH_SLOTX24_S3_DN")
	)
	(segment
		(start 364.608364 -84.048854)
		(end 363.994954 -87.116158)
		(width 0.1143)
		(layer "In2.Cu")
		(net "CLK_100M_PCH_SLOTX24_S3_DN")
	)
	(segment
		(start 369.391184 -99.415346)
		(end 369.140232 -100.597462)
		(width 0.1143)
		(layer "In2.Cu")
		(net "CLK_100M_PCH_SLOTX24_S3_DN")
	)
	(segment
		(start 374.53824 -109.955584)
		(end 376.507756 -111.9251)
		(width 0.0889)
		(layer "In2.Cu")
		(net "CLK_100M_PCH_SLOTX24_S3_DN")
	)
	(segment
		(start 445.63919 -13.717524)
		(end 445.637412 -13.718794)
		(width 0.1143)
		(layer "In2.Cu")
		(net "CLK_100M_PCH_SLOTX24_S3_DN")
	)
	(segment
		(start 364.151164 -66.42862)
		(end 362.668566 -68.306442)
		(width 0.1143)
		(layer "In2.Cu")
		(net "CLK_100M_PCH_SLOTX24_S3_DN")
	)
	(segment
		(start 411.0228 -19.9898)
		(end 409.476448 -21.020532)
		(width 0.1143)
		(layer "In2.Cu")
		(net "CLK_100M_PCH_SLOTX24_S3_DN")
	)
	(segment
		(start 400.862546 -20.338796)
		(end 400.033998 -20.173188)
		(width 0.1143)
		(layer "In2.Cu")
		(net "CLK_100M_PCH_SLOTX24_S3_DN")
	)
	(segment
		(start 428.1678 -15.704058)
		(end 427.819312 -15.934944)
		(width 0.1143)
		(layer "In2.Cu")
		(net "CLK_100M_PCH_SLOTX24_S3_DN")
	)
	(segment
		(start 396.443708 -20.41271)
		(end 396.443708 -20.412456)
		(width 0.1143)
		(layer "In2.Cu")
		(net "CLK_100M_PCH_SLOTX24_S3_DN")
	)
	(segment
		(start 374.47474 -108.737146)
		(end 374.47474 -108.759752)
		(width 0.0889)
		(layer "In2.Cu")
		(net "CLK_100M_PCH_SLOTX24_S3_DN")
	)
	(segment
		(start 455.638408 -10.349992)
		(end 455.049636 -10.742676)
		(width 0.1143)
		(layer "In2.Cu")
		(net "CLK_100M_PCH_SLOTX24_S3_DN")
	)
	(segment
		(start 426.869606 -16.91767)
		(end 426.32249 -17.029176)
		(width 0.1143)
		(layer "In2.Cu")
		(net "CLK_100M_PCH_SLOTX24_S3_DN")
	)
	(segment
		(start 445.637412 -13.718794)
		(end 442.475874 -14.350492)
		(width 0.1143)
		(layer "In2.Cu")
		(net "CLK_100M_PCH_SLOTX24_S3_DN")
	)
	(segment
		(start 396.443708 -20.412456)
		(end 395.499082 -20.22348)
		(width 0.1143)
		(layer "In2.Cu")
		(net "CLK_100M_PCH_SLOTX24_S3_DN")
	)
	(segment
		(start 388.672578 -18.54073)
		(end 381.376682 -20.125182)
		(width 0.1143)
		(layer "In2.Cu")
		(net "CLK_100M_PCH_SLOTX24_S3_DN")
	)
	(segment
		(start 369.187222 -98.451924)
		(end 369.391184 -99.415346)
		(width 0.1143)
		(layer "In2.Cu")
		(net "CLK_100M_PCH_SLOTX24_S3_DN")
	)
	(segment
		(start 376.507756 -111.9251)
		(end 377.113292 -111.9251)
		(width 0.0889)
		(layer "In2.Cu")
		(net "CLK_100M_PCH_SLOTX24_S3_DN")
	)
	(segment
		(start 395.499082 -20.22348)
		(end 388.672578 -18.54073)
		(width 0.1143)
		(layer "In2.Cu")
		(net "CLK_100M_PCH_SLOTX24_S3_DN")
	)
	(segment
		(start 368.772186 -94.226126)
		(end 369.187222 -96.244918)
		(width 0.1143)
		(layer "In2.Cu")
		(net "CLK_100M_PCH_SLOTX24_S3_DN")
	)
	(segment
		(start 363.7915 -76.633578)
		(end 363.7915 -80.19288)
		(width 0.1143)
		(layer "In2.Cu")
		(net "CLK_100M_PCH_SLOTX24_S3_DN")
	)
	(segment
		(start 370.755926 -42.060622)
		(end 368.666522 -48.661574)
		(width 0.1143)
		(layer "In2.Cu")
		(net "CLK_100M_PCH_SLOTX24_S3_DN")
	)
	(segment
		(start 403.104096 -21.938996)
		(end 402.81225 -21.646896)
		(width 0.1143)
		(layer "In2.Cu")
		(net "CLK_100M_PCH_SLOTX24_S3_DN")
	)
	(segment
		(start 434.902356 -14.666468)
		(end 430.00295 -15.663418)
		(width 0.1143)
		(layer "In2.Cu")
		(net "CLK_100M_PCH_SLOTX24_S3_DN")
	)
	(segment
		(start 379.327156 -22.571456)
		(end 378.768356 -22.940772)
		(width 0.1143)
		(layer "In2.Cu")
		(net "CLK_100M_PCH_SLOTX24_S3_DN")
	)
	(segment
		(start 362.910882 -69.315584)
		(end 362.556552 -70.789546)
		(width 0.1143)
		(layer "In2.Cu")
		(net "CLK_100M_PCH_SLOTX24_S3_DN")
	)
	(segment
		(start 379.494542 -22.35327)
		(end 379.327156 -22.571456)
		(width 0.1143)
		(layer "In2.Cu")
		(net "CLK_100M_PCH_SLOTX24_S3_DN")
	)
	(segment
		(start 425.791884 -17.13738)
		(end 423.270172 -16.632936)
		(width 0.1143)
		(layer "In2.Cu")
		(net "CLK_100M_PCH_SLOTX24_S3_DN")
	)
	(segment
		(start 423.270172 -16.632936)
		(end 422.044876 -16.878046)
		(width 0.1143)
		(layer "In2.Cu")
		(net "CLK_100M_PCH_SLOTX24_S3_DN")
	)
	(segment
		(start 407.444194 -22.6314)
		(end 404.56485 -21.938996)
		(width 0.1143)
		(layer "In2.Cu")
		(net "CLK_100M_PCH_SLOTX24_S3_DN")
	)
	(segment
		(start 416.077146 -18.978626)
		(end 416.0774 -18.978626)
		(width 0.1143)
		(layer "In2.Cu")
		(net "CLK_100M_PCH_SLOTX24_S3_DN")
	)
	(segment
		(start 362.556552 -70.789546)
		(end 363.7915 -76.633578)
		(width 0.1143)
		(layer "In2.Cu")
		(net "CLK_100M_PCH_SLOTX24_S3_DN")
	)
	(segment
		(start 422.044876 -16.878046)
		(end 416.077146 -18.978626)
		(width 0.1143)
		(layer "In2.Cu")
		(net "CLK_100M_PCH_SLOTX24_S3_DN")
	)
	(segment
		(start 397.388334 -20.601432)
		(end 396.443708 -20.41271)
		(width 0.1143)
		(layer "In2.Cu")
		(net "CLK_100M_PCH_SLOTX24_S3_DN")
	)
	(segment
		(start 427.819312 -15.934944)
		(end 427.401736 -16.56588)
		(width 0.1143)
		(layer "In2.Cu")
		(net "CLK_100M_PCH_SLOTX24_S3_DN")
	)
	(segment
		(start 378.768356 -22.940772)
		(end 375.912888 -23.805642)
		(width 0.1143)
		(layer "In2.Cu")
		(net "CLK_100M_PCH_SLOTX24_S3_DN")
	)
	(segment
		(start 362.668566 -68.306442)
		(end 362.910882 -69.315584)
		(width 0.1143)
		(layer "In2.Cu")
		(net "CLK_100M_PCH_SLOTX24_S3_DN")
	)
	(segment
		(start 370.232432 -39.509954)
		(end 370.755926 -42.060622)
		(width 0.1143)
		(layer "In2.Cu")
		(net "CLK_100M_PCH_SLOTX24_S3_DN")
	)
	(segment
		(start 367.908586 -57.34177)
		(end 364.491524 -65.11163)
		(width 0.1143)
		(layer "In2.Cu")
		(net "CLK_100M_PCH_SLOTX24_S3_DN")
	)
	(segment
		(start 369.187222 -96.244918)
		(end 369.187222 -98.451924)
		(width 0.1143)
		(layer "In2.Cu")
		(net "CLK_100M_PCH_SLOTX24_S3_DN")
	)
	(segment
		(start 368.666522 -48.661574)
		(end 369.560348 -51.478942)
		(width 0.1143)
		(layer "In2.Cu")
		(net "CLK_100M_PCH_SLOTX24_S3_DN")
	)
	(segment
		(start 368.6048 -56.29783)
		(end 367.908586 -57.34177)
		(width 0.1143)
		(layer "In2.Cu")
		(net "CLK_100M_PCH_SLOTX24_S3_DN")
	)
	(segment
		(start 439.524394 -13.72362)
		(end 437.168036 -14.638274)
		(width 0.1143)
		(layer "In2.Cu")
		(net "CLK_100M_PCH_SLOTX24_S3_DN")
	)
	(segment
		(start 363.7915 -80.19288)
		(end 364.608364 -84.048854)
		(width 0.1143)
		(layer "In2.Cu")
		(net "CLK_100M_PCH_SLOTX24_S3_DN")
	)
	(segment
		(start 381.376682 -20.125182)
		(end 380.234952 -20.91817)
		(width 0.1143)
		(layer "In2.Cu")
		(net "CLK_100M_PCH_SLOTX24_S3_DN")
	)
	(segment
		(start 380.234952 -20.91817)
		(end 379.494542 -22.35327)
		(width 0.1143)
		(layer "In2.Cu")
		(net "CLK_100M_PCH_SLOTX24_S3_DN")
	)
	(segment
		(start 377.296172 -112.108234)
		(end 377.479052 -112.291114)
		(width 0.0889)
		(layer "In2.Cu")
		(net "CLK_100M_PCH_SLOTX24_S3_DN")
	)
	(segment
		(start 426.32249 -17.029176)
		(end 426.322236 -17.029176)
		(width 0.1143)
		(layer "In2.Cu")
		(net "CLK_100M_PCH_SLOTX24_S3_DN")
	)
	(segment
		(start 363.994954 -87.116158)
		(end 364.50905 -89.68867)
		(width 0.1143)
		(layer "In2.Cu")
		(net "CLK_100M_PCH_SLOTX24_S3_DN")
	)
	(segment
		(start 369.560348 -51.478942)
		(end 368.6048 -56.29783)
		(width 0.1143)
		(layer "In2.Cu")
		(net "CLK_100M_PCH_SLOTX24_S3_DN")
	)
	(segment
		(start 455.8665 -10.007854)
		(end 455.638408 -10.349992)
		(width 0.1143)
		(layer "In2.Cu")
		(net "CLK_100M_PCH_SLOTX24_S3_DN")
	)
	(segment
		(start 451.1421 -10.748518)
		(end 449.640452 -11.049254)
		(width 0.1143)
		(layer "In2.Cu")
		(net "CLK_100M_PCH_SLOTX24_S3_DN")
	)
	(segment
		(start 371.633242 -108.2548)
		(end 374.142 -108.2548)
		(width 0.1143)
		(layer "In2.Cu")
		(net "CLK_100M_PCH_SLOTX24_S3_DN")
	)
	(segment
		(start 364.50905 -89.68867)
		(end 366.255046 -90.852244)
		(width 0.1143)
		(layer "In2.Cu")
		(net "CLK_100M_PCH_SLOTX24_S3_DN")
	)
	(segment
		(start 408.222196 -22.6314)
		(end 407.444194 -22.6314)
		(width 0.1143)
		(layer "In2.Cu")
		(net "CLK_100M_PCH_SLOTX24_S3_DN")
	)
	(arc
		(start 378.126752 -112.313974)
		(mid 378.249008 -112.220223)
		(end 378.342906 -112.098074)
		(width 0.0889)
		(layer "In2.Cu")
		(net "CLK_100M_PCH_SLOTX24_S3_DN")
	)
	(arc
		(start 377.495562 -112.302798)
		(mid 377.751345 -112.399757)
		(end 378.023628 -112.373664)
		(width 0.0889)
		(layer "In2.Cu")
		(net "CLK_100M_PCH_SLOTX24_S3_DN")
	)
	(arc
		(start 378.342906 -112.098074)
		(mid 378.545214 -111.889893)
		(end 378.82195 -111.802164)
		(width 0.0889)
		(layer "In2.Cu")
		(net "CLK_100M_PCH_SLOTX24_S3_DN")
	)
	(arc
		(start 377.479052 -112.291114)
		(mid 377.487257 -112.297026)
		(end 377.495562 -112.302798)
		(width 0.0889)
		(layer "In2.Cu")
		(net "CLK_100M_PCH_SLOTX24_S3_DN")
	)
	(segment
		(start 455.46772 -3.703066)
		(end 455.677778 -3.913124)
		(width 0.127)
		(layer "F.Cu")
		(net "CLK_100M_PCH_SLOTX24_S2_DP")
	)
	(segment
		(start 374.452388 -105.188004)
		(end 372.787926 -105.188004)
		(width 0.0889)
		(layer "F.Cu")
		(net "CLK_100M_PCH_SLOTX24_S2_DP")
	)
	(segment
		(start 375.504964 -105.855008)
		(end 374.895872 -105.631742)
		(width 0.0889)
		(layer "F.Cu")
		(net "CLK_100M_PCH_SLOTX24_S2_DP")
	)
	(segment
		(start 455.949812 -3.0226)
		(end 455.712322 -3.0226)
		(width 0.127)
		(layer "F.Cu")
		(net "CLK_100M_PCH_SLOTX24_S2_DP")
	)
	(segment
		(start 374.895872 -105.631742)
		(end 374.452388 -105.188004)
		(width 0.0889)
		(layer "F.Cu")
		(net "CLK_100M_PCH_SLOTX24_S2_DP")
	)
	(segment
		(start 455.46772 -3.267202)
		(end 455.46772 -3.703066)
		(width 0.127)
		(layer "F.Cu")
		(net "CLK_100M_PCH_SLOTX24_S2_DP")
	)
	(segment
		(start 371.638576 -103.243888)
		(end 366.47882 -103.243888)
		(width 0.0889)
		(layer "F.Cu")
		(net "CLK_100M_PCH_SLOTX24_S2_DP")
	)
	(segment
		(start 455.677778 -3.913124)
		(end 455.677778 -4.386072)
		(width 0.127)
		(layer "F.Cu")
		(net "CLK_100M_PCH_SLOTX24_S2_DP")
	)
	(segment
		(start 455.712322 -3.0226)
		(end 455.46772 -3.267202)
		(width 0.127)
		(layer "F.Cu")
		(net "CLK_100M_PCH_SLOTX24_S2_DP")
	)
	(segment
		(start 372.787926 -105.188004)
		(end 372.305326 -104.705404)
		(width 0.0889)
		(layer "F.Cu")
		(net "CLK_100M_PCH_SLOTX24_S2_DP")
	)
	(segment
		(start 372.305326 -104.705404)
		(end 372.305326 -103.910638)
		(width 0.0889)
		(layer "F.Cu")
		(net "CLK_100M_PCH_SLOTX24_S2_DP")
	)
	(segment
		(start 372.305326 -103.910638)
		(end 371.638576 -103.243888)
		(width 0.0889)
		(layer "F.Cu")
		(net "CLK_100M_PCH_SLOTX24_S2_DP")
	)
	(via
		(at 366.47882 -103.243888)
		(size 0.508)
		(drill 0.254)
		(layers "F.Cu" "B.Cu")
		(net "CLK_100M_PCH_SLOTX24_S2_DP")
	)
	(via
		(at 455.949812 -3.0226)
		(size 0.508)
		(drill 0.254)
		(layers "F.Cu" "B.Cu")
		(net "CLK_100M_PCH_SLOTX24_S2_DP")
	)
	(segment
		(start 452.105014 -6.401816)
		(end 452.402448 -6.231636)
		(width 0.1143)
		(layer "In2.Cu")
		(net "CLK_100M_PCH_SLOTX24_S2_DP")
	)
	(segment
		(start 435.43093 -10.854182)
		(end 435.767226 -10.786872)
		(width 0.1143)
		(layer "In2.Cu")
		(net "CLK_100M_PCH_SLOTX24_S2_DP")
	)
	(segment
		(start 363.257592 -60.459112)
		(end 366.579404 -55.474108)
		(width 0.1143)
		(layer "In2.Cu")
		(net "CLK_100M_PCH_SLOTX24_S2_DP")
	)
	(segment
		(start 446.07226 -10.79246)
		(end 446.997074 -10.188448)
		(width 0.1143)
		(layer "In2.Cu")
		(net "CLK_100M_PCH_SLOTX24_S2_DP")
	)
	(segment
		(start 429.899064 -12.556236)
		(end 431.139092 -12.808712)
		(width 0.1143)
		(layer "In2.Cu")
		(net "CLK_100M_PCH_SLOTX24_S2_DP")
	)
	(segment
		(start 455.450194 -3.161284)
		(end 455.588878 -3.0226)
		(width 0.1143)
		(layer "In2.Cu")
		(net "CLK_100M_PCH_SLOTX24_S2_DP")
	)
	(segment
		(start 428.754032 -13.059664)
		(end 429.34509 -12.668504)
		(width 0.1143)
		(layer "In2.Cu")
		(net "CLK_100M_PCH_SLOTX24_S2_DP")
	)
	(segment
		(start 366.579404 -55.474108)
		(end 366.660176 -55.072026)
		(width 0.1143)
		(layer "In2.Cu")
		(net "CLK_100M_PCH_SLOTX24_S2_DP")
	)
	(segment
		(start 365.84636 -45.937678)
		(end 365.991394 -45.482002)
		(width 0.1143)
		(layer "In2.Cu")
		(net "CLK_100M_PCH_SLOTX24_S2_DP")
	)
	(segment
		(start 451.879716 -6.340602)
		(end 452.105014 -6.401816)
		(width 0.1143)
		(layer "In2.Cu")
		(net "CLK_100M_PCH_SLOTX24_S2_DP")
	)
	(segment
		(start 438.61228 -11.56081)
		(end 438.80786 -11.433556)
		(width 0.1143)
		(layer "In2.Cu")
		(net "CLK_100M_PCH_SLOTX24_S2_DP")
	)
	(segment
		(start 455.588878 -3.0226)
		(end 455.949812 -3.0226)
		(width 0.1143)
		(layer "In2.Cu")
		(net "CLK_100M_PCH_SLOTX24_S2_DP")
	)
	(segment
		(start 375.073164 -22.170644)
		(end 380.028704 -18.704306)
		(width 0.1143)
		(layer "In2.Cu")
		(net "CLK_100M_PCH_SLOTX24_S2_DP")
	)
	(segment
		(start 440.615578 -11.360658)
		(end 440.742832 -11.165078)
		(width 0.1143)
		(layer "In2.Cu")
		(net "CLK_100M_PCH_SLOTX24_S2_DP")
	)
	(segment
		(start 437.15559 -11.082274)
		(end 437.282844 -11.278108)
		(width 0.1143)
		(layer "In2.Cu")
		(net "CLK_100M_PCH_SLOTX24_S2_DP")
	)
	(segment
		(start 431.636678 -12.707366)
		(end 434.003958 -11.140694)
		(width 0.1143)
		(layer "In2.Cu")
		(net "CLK_100M_PCH_SLOTX24_S2_DP")
	)
	(segment
		(start 388.634478 -16.830548)
		(end 392.209528 -17.59077)
		(width 0.1143)
		(layer "In2.Cu")
		(net "CLK_100M_PCH_SLOTX24_S2_DP")
	)
	(segment
		(start 450.997828 -6.8453)
		(end 451.223126 -6.906768)
		(width 0.1143)
		(layer "In2.Cu")
		(net "CLK_100M_PCH_SLOTX24_S2_DP")
	)
	(segment
		(start 438.276746 -11.489436)
		(end 438.61228 -11.56081)
		(width 0.1143)
		(layer "In2.Cu")
		(net "CLK_100M_PCH_SLOTX24_S2_DP")
	)
	(segment
		(start 401.60067 -17.06499)
		(end 403.476968 -16.666718)
		(width 0.1143)
		(layer "In2.Cu")
		(net "CLK_100M_PCH_SLOTX24_S2_DP")
	)
	(segment
		(start 367.915698 -36.793678)
		(end 368.749326 -32.874966)
		(width 0.1143)
		(layer "In2.Cu")
		(net "CLK_100M_PCH_SLOTX24_S2_DP")
	)
	(segment
		(start 452.402448 -6.231636)
		(end 452.463662 -6.006338)
		(width 0.1143)
		(layer "In2.Cu")
		(net "CLK_100M_PCH_SLOTX24_S2_DP")
	)
	(segment
		(start 455.450194 -3.598926)
		(end 455.450194 -3.161284)
		(width 0.1143)
		(layer "In2.Cu")
		(net "CLK_100M_PCH_SLOTX24_S2_DP")
	)
	(segment
		(start 440.742832 -11.165078)
		(end 443.35319 -10.610088)
		(width 0.1143)
		(layer "In2.Cu")
		(net "CLK_100M_PCH_SLOTX24_S2_DP")
	)
	(segment
		(start 450.341238 -7.411212)
		(end 450.638926 -7.241032)
		(width 0.1143)
		(layer "In2.Cu")
		(net "CLK_100M_PCH_SLOTX24_S2_DP")
	)
	(segment
		(start 428.754032 -13.059918)
		(end 428.754032 -13.059664)
		(width 0.1143)
		(layer "In2.Cu")
		(net "CLK_100M_PCH_SLOTX24_S2_DP")
	)
	(segment
		(start 426.531278 -13.313664)
		(end 427.072298 -13.4239)
		(width 0.1143)
		(layer "In2.Cu")
		(net "CLK_100M_PCH_SLOTX24_S2_DP")
	)
	(segment
		(start 452.76135 -5.835904)
		(end 453.349614 -4.910582)
		(width 0.1143)
		(layer "In2.Cu")
		(net "CLK_100M_PCH_SLOTX24_S2_DP")
	)
	(segment
		(start 400.674078 -16.933164)
		(end 401.60067 -17.06499)
		(width 0.1143)
		(layer "In2.Cu")
		(net "CLK_100M_PCH_SLOTX24_S2_DP")
	)
	(segment
		(start 451.52056 -6.736334)
		(end 451.582028 -6.511036)
		(width 0.1143)
		(layer "In2.Cu")
		(net "CLK_100M_PCH_SLOTX24_S2_DP")
	)
	(segment
		(start 434.965348 -11.115548)
		(end 435.30139 -11.048492)
		(width 0.1143)
		(layer "In2.Cu")
		(net "CLK_100M_PCH_SLOTX24_S2_DP")
	)
	(segment
		(start 427.072298 -13.4239)
		(end 428.706788 -13.09116)
		(width 0.1143)
		(layer "In2.Cu")
		(net "CLK_100M_PCH_SLOTX24_S2_DP")
	)
	(segment
		(start 368.749326 -32.874966)
		(end 369.542822 -32.296354)
		(width 0.1143)
		(layer "In2.Cu")
		(net "CLK_100M_PCH_SLOTX24_S2_DP")
	)
	(segment
		(start 452.463662 -6.006338)
		(end 452.76135 -5.835904)
		(width 0.1143)
		(layer "In2.Cu")
		(net "CLK_100M_PCH_SLOTX24_S2_DP")
	)
	(segment
		(start 365.653066 -97.489518)
		(end 365.432086 -96.428306)
		(width 0.1143)
		(layer "In2.Cu")
		(net "CLK_100M_PCH_SLOTX24_S2_DP")
	)
	(segment
		(start 451.582028 -6.511036)
		(end 451.879716 -6.340602)
		(width 0.1143)
		(layer "In2.Cu")
		(net "CLK_100M_PCH_SLOTX24_S2_DP")
	)
	(segment
		(start 437.618378 -11.349482)
		(end 437.813958 -11.222228)
		(width 0.1143)
		(layer "In2.Cu")
		(net "CLK_100M_PCH_SLOTX24_S2_DP")
	)
	(segment
		(start 450.638926 -7.241032)
		(end 450.70014 -7.015734)
		(width 0.1143)
		(layer "In2.Cu")
		(net "CLK_100M_PCH_SLOTX24_S2_DP")
	)
	(segment
		(start 434.771038 -10.986262)
		(end 434.965348 -11.115548)
		(width 0.1143)
		(layer "In2.Cu")
		(net "CLK_100M_PCH_SLOTX24_S2_DP")
	)
	(segment
		(start 366.660176 -55.072026)
		(end 365.727488 -50.401728)
		(width 0.1143)
		(layer "In2.Cu")
		(net "CLK_100M_PCH_SLOTX24_S2_DP")
	)
	(segment
		(start 453.349614 -4.910582)
		(end 455.096118 -4.162806)
		(width 0.1143)
		(layer "In2.Cu")
		(net "CLK_100M_PCH_SLOTX24_S2_DP")
	)
	(segment
		(start 362.222288 -65.340484)
		(end 363.257592 -60.459112)
		(width 0.1143)
		(layer "In2.Cu")
		(net "CLK_100M_PCH_SLOTX24_S2_DP")
	)
	(segment
		(start 437.282844 -11.278108)
		(end 437.618378 -11.349482)
		(width 0.1143)
		(layer "In2.Cu")
		(net "CLK_100M_PCH_SLOTX24_S2_DP")
	)
	(segment
		(start 431.139092 -12.808712)
		(end 431.636678 -12.707366)
		(width 0.1143)
		(layer "In2.Cu")
		(net "CLK_100M_PCH_SLOTX24_S2_DP")
	)
	(segment
		(start 445.11214 -10.983976)
		(end 446.07226 -10.79246)
		(width 0.1143)
		(layer "In2.Cu")
		(net "CLK_100M_PCH_SLOTX24_S2_DP")
	)
	(segment
		(start 365.991394 -45.482002)
		(end 366.911382 -44.889674)
		(width 0.1143)
		(layer "In2.Cu")
		(net "CLK_100M_PCH_SLOTX24_S2_DP")
	)
	(segment
		(start 411.029658 -16.347948)
		(end 412.41726 -16.664432)
		(width 0.1143)
		(layer "In2.Cu")
		(net "CLK_100M_PCH_SLOTX24_S2_DP")
	)
	(segment
		(start 429.34509 -12.668504)
		(end 429.899064 -12.556236)
		(width 0.1143)
		(layer "In2.Cu")
		(net "CLK_100M_PCH_SLOTX24_S2_DP")
	)
	(segment
		(start 440.084464 -11.305032)
		(end 440.280298 -11.432032)
		(width 0.1143)
		(layer "In2.Cu")
		(net "CLK_100M_PCH_SLOTX24_S2_DP")
	)
	(segment
		(start 362.59897 -83.065112)
		(end 362.0897 -80.613504)
		(width 0.1143)
		(layer "In2.Cu")
		(net "CLK_100M_PCH_SLOTX24_S2_DP")
	)
	(segment
		(start 412.41726 -16.664432)
		(end 424.952668 -14.084554)
		(width 0.1143)
		(layer "In2.Cu")
		(net "CLK_100M_PCH_SLOTX24_S2_DP")
	)
	(segment
		(start 455.096118 -4.162806)
		(end 455.450194 -3.598926)
		(width 0.1143)
		(layer "In2.Cu")
		(net "CLK_100M_PCH_SLOTX24_S2_DP")
	)
	(segment
		(start 443.35319 -10.610088)
		(end 445.11214 -10.983976)
		(width 0.1143)
		(layer "In2.Cu")
		(net "CLK_100M_PCH_SLOTX24_S2_DP")
	)
	(segment
		(start 395.91615 -16.803116)
		(end 398.600676 -17.3736)
		(width 0.1143)
		(layer "In2.Cu")
		(net "CLK_100M_PCH_SLOTX24_S2_DP")
	)
	(segment
		(start 365.710978 -95.114872)
		(end 364.626144 -91.75623)
		(width 0.1143)
		(layer "In2.Cu")
		(net "CLK_100M_PCH_SLOTX24_S2_DP")
	)
	(segment
		(start 398.600676 -17.3736)
		(end 400.674078 -16.933164)
		(width 0.1143)
		(layer "In2.Cu")
		(net "CLK_100M_PCH_SLOTX24_S2_DP")
	)
	(segment
		(start 407.47315 -17.51584)
		(end 411.029658 -16.347948)
		(width 0.1143)
		(layer "In2.Cu")
		(net "CLK_100M_PCH_SLOTX24_S2_DP")
	)
	(segment
		(start 360.367072 -68.621656)
		(end 360.928666 -66.283586)
		(width 0.1143)
		(layer "In2.Cu")
		(net "CLK_100M_PCH_SLOTX24_S2_DP")
	)
	(segment
		(start 434.003958 -11.140694)
		(end 434.771038 -10.986262)
		(width 0.1143)
		(layer "In2.Cu")
		(net "CLK_100M_PCH_SLOTX24_S2_DP")
	)
	(segment
		(start 369.542822 -32.296354)
		(end 370.352828 -28.485338)
		(width 0.1143)
		(layer "In2.Cu")
		(net "CLK_100M_PCH_SLOTX24_S2_DP")
	)
	(segment
		(start 362.0897 -80.613504)
		(end 362.0897 -76.760832)
		(width 0.1143)
		(layer "In2.Cu")
		(net "CLK_100M_PCH_SLOTX24_S2_DP")
	)
	(segment
		(start 448.125342 -8.495792)
		(end 450.12356 -7.35203)
		(width 0.1143)
		(layer "In2.Cu")
		(net "CLK_100M_PCH_SLOTX24_S2_DP")
	)
	(segment
		(start 425.932854 -13.435584)
		(end 426.531278 -13.313664)
		(width 0.1143)
		(layer "In2.Cu")
		(net "CLK_100M_PCH_SLOTX24_S2_DP")
	)
	(segment
		(start 366.395762 -47.54118)
		(end 365.84636 -45.937678)
		(width 0.1143)
		(layer "In2.Cu")
		(net "CLK_100M_PCH_SLOTX24_S2_DP")
	)
	(segment
		(start 403.476968 -16.666718)
		(end 407.47315 -17.51584)
		(width 0.1143)
		(layer "In2.Cu")
		(net "CLK_100M_PCH_SLOTX24_S2_DP")
	)
	(segment
		(start 446.997074 -10.188448)
		(end 448.125342 -8.495792)
		(width 0.1143)
		(layer "In2.Cu")
		(net "CLK_100M_PCH_SLOTX24_S2_DP")
	)
	(segment
		(start 366.61979 -103.102918)
		(end 366.61979 -102.135686)
		(width 0.1143)
		(layer "In2.Cu")
		(net "CLK_100M_PCH_SLOTX24_S2_DP")
	)
	(segment
		(start 392.209528 -17.59077)
		(end 395.91615 -16.803116)
		(width 0.1143)
		(layer "In2.Cu")
		(net "CLK_100M_PCH_SLOTX24_S2_DP")
	)
	(segment
		(start 380.028704 -18.704306)
		(end 388.634478 -16.830548)
		(width 0.1143)
		(layer "In2.Cu")
		(net "CLK_100M_PCH_SLOTX24_S2_DP")
	)
	(segment
		(start 366.911382 -44.889674)
		(end 368.19078 -37.847016)
		(width 0.1143)
		(layer "In2.Cu")
		(net "CLK_100M_PCH_SLOTX24_S2_DP")
	)
	(segment
		(start 362.0897 -76.760832)
		(end 360.367072 -68.621656)
		(width 0.1143)
		(layer "In2.Cu")
		(net "CLK_100M_PCH_SLOTX24_S2_DP")
	)
	(segment
		(start 438.80786 -11.433556)
		(end 439.143394 -11.50493)
		(width 0.1143)
		(layer "In2.Cu")
		(net "CLK_100M_PCH_SLOTX24_S2_DP")
	)
	(segment
		(start 361.746546 -87.3252)
		(end 362.59897 -83.065112)
		(width 0.1143)
		(layer "In2.Cu")
		(net "CLK_100M_PCH_SLOTX24_S2_DP")
	)
	(segment
		(start 428.706788 -13.09116)
		(end 428.754032 -13.059918)
		(width 0.1143)
		(layer "In2.Cu")
		(net "CLK_100M_PCH_SLOTX24_S2_DP")
	)
	(segment
		(start 365.727488 -50.401728)
		(end 366.395762 -47.54118)
		(width 0.1143)
		(layer "In2.Cu")
		(net "CLK_100M_PCH_SLOTX24_S2_DP")
	)
	(segment
		(start 366.61979 -102.135686)
		(end 365.786924 -101.302566)
		(width 0.1143)
		(layer "In2.Cu")
		(net "CLK_100M_PCH_SLOTX24_S2_DP")
	)
	(segment
		(start 438.149492 -11.293602)
		(end 438.276746 -11.489436)
		(width 0.1143)
		(layer "In2.Cu")
		(net "CLK_100M_PCH_SLOTX24_S2_DP")
	)
	(segment
		(start 439.143394 -11.50493)
		(end 440.084464 -11.305032)
		(width 0.1143)
		(layer "In2.Cu")
		(net "CLK_100M_PCH_SLOTX24_S2_DP")
	)
	(segment
		(start 451.223126 -6.906768)
		(end 451.52056 -6.736334)
		(width 0.1143)
		(layer "In2.Cu")
		(net "CLK_100M_PCH_SLOTX24_S2_DP")
	)
	(segment
		(start 450.70014 -7.015734)
		(end 450.997828 -6.8453)
		(width 0.1143)
		(layer "In2.Cu")
		(net "CLK_100M_PCH_SLOTX24_S2_DP")
	)
	(segment
		(start 437.813958 -11.222228)
		(end 438.149492 -11.293602)
		(width 0.1143)
		(layer "In2.Cu")
		(net "CLK_100M_PCH_SLOTX24_S2_DP")
	)
	(segment
		(start 450.12356 -7.35203)
		(end 450.341238 -7.411212)
		(width 0.1143)
		(layer "In2.Cu")
		(net "CLK_100M_PCH_SLOTX24_S2_DP")
	)
	(segment
		(start 365.314738 -99.083114)
		(end 365.653066 -97.489518)
		(width 0.1143)
		(layer "In2.Cu")
		(net "CLK_100M_PCH_SLOTX24_S2_DP")
	)
	(segment
		(start 364.626144 -91.75623)
		(end 362.326936 -90.223594)
		(width 0.1143)
		(layer "In2.Cu")
		(net "CLK_100M_PCH_SLOTX24_S2_DP")
	)
	(segment
		(start 360.928666 -66.283586)
		(end 362.222288 -65.340484)
		(width 0.1143)
		(layer "In2.Cu")
		(net "CLK_100M_PCH_SLOTX24_S2_DP")
	)
	(segment
		(start 435.767226 -10.786872)
		(end 437.15559 -11.082274)
		(width 0.1143)
		(layer "In2.Cu")
		(net "CLK_100M_PCH_SLOTX24_S2_DP")
	)
	(segment
		(start 362.326936 -90.223594)
		(end 361.746546 -87.3252)
		(width 0.1143)
		(layer "In2.Cu")
		(net "CLK_100M_PCH_SLOTX24_S2_DP")
	)
	(segment
		(start 435.30139 -11.048492)
		(end 435.43093 -10.854182)
		(width 0.1143)
		(layer "In2.Cu")
		(net "CLK_100M_PCH_SLOTX24_S2_DP")
	)
	(segment
		(start 366.47882 -103.243888)
		(end 366.61979 -103.102918)
		(width 0.1143)
		(layer "In2.Cu")
		(net "CLK_100M_PCH_SLOTX24_S2_DP")
	)
	(segment
		(start 365.432086 -96.428306)
		(end 365.710978 -95.114872)
		(width 0.1143)
		(layer "In2.Cu")
		(net "CLK_100M_PCH_SLOTX24_S2_DP")
	)
	(segment
		(start 370.352828 -28.485338)
		(end 375.073164 -22.170644)
		(width 0.1143)
		(layer "In2.Cu")
		(net "CLK_100M_PCH_SLOTX24_S2_DP")
	)
	(segment
		(start 440.280298 -11.432032)
		(end 440.615578 -11.360658)
		(width 0.1143)
		(layer "In2.Cu")
		(net "CLK_100M_PCH_SLOTX24_S2_DP")
	)
	(segment
		(start 365.786924 -101.302566)
		(end 365.314738 -99.083114)
		(width 0.1143)
		(layer "In2.Cu")
		(net "CLK_100M_PCH_SLOTX24_S2_DP")
	)
	(segment
		(start 424.952668 -14.084554)
		(end 425.932854 -13.435584)
		(width 0.1143)
		(layer "In2.Cu")
		(net "CLK_100M_PCH_SLOTX24_S2_DP")
	)
	(segment
		(start 368.19078 -37.847016)
		(end 367.915698 -36.793678)
		(width 0.1143)
		(layer "In2.Cu")
		(net "CLK_100M_PCH_SLOTX24_S2_DP")
	)
	(segment
		(start 367.044986 -103.434388)
		(end 366.586008 -103.893366)
		(width 0.0889)
		(layer "F.Cu")
		(net "CLK_100M_PCH_SLOTX24_S2_DN")
	)
	(segment
		(start 373.751094 -105.467404)
		(end 373.662194 -105.378504)
		(width 0.0889)
		(layer "F.Cu")
		(net "CLK_100M_PCH_SLOTX24_S2_DN")
	)
	(segment
		(start 370.911882 -103.523288)
		(end 370.822982 -103.434388)
		(width 0.0889)
		(layer "F.Cu")
		(net "CLK_100M_PCH_SLOTX24_S2_DN")
	)
	(segment
		(start 454.877678 -3.947668)
		(end 454.877678 -4.386072)
		(width 0.127)
		(layer "F.Cu")
		(net "CLK_100M_PCH_SLOTX24_S2_DN")
	)
	(segment
		(start 454.679812 -3.01244)
		(end 454.90638 -3.01244)
		(width 0.127)
		(layer "F.Cu")
		(net "CLK_100M_PCH_SLOTX24_S2_DN")
	)
	(segment
		(start 374.69953 -105.705148)
		(end 374.373394 -105.378504)
		(width 0.0889)
		(layer "F.Cu")
		(net "CLK_100M_PCH_SLOTX24_S2_DN")
	)
	(segment
		(start 371.68328 -103.558086)
		(end 371.559582 -103.434388)
		(width 0.0889)
		(layer "F.Cu")
		(net "CLK_100M_PCH_SLOTX24_S2_DN")
	)
	(segment
		(start 370.822982 -103.434388)
		(end 369.991386 -103.434388)
		(width 0.0889)
		(layer "F.Cu")
		(net "CLK_100M_PCH_SLOTX24_S2_DN")
	)
	(segment
		(start 369.623086 -103.523288)
		(end 369.534186 -103.434388)
		(width 0.0889)
		(layer "F.Cu")
		(net "CLK_100M_PCH_SLOTX24_S2_DN")
	)
	(segment
		(start 367.413286 -103.523288)
		(end 367.324386 -103.434388)
		(width 0.0889)
		(layer "F.Cu")
		(net "CLK_100M_PCH_SLOTX24_S2_DN")
	)
	(segment
		(start 368.060986 -103.434388)
		(end 367.781586 -103.434388)
		(width 0.0889)
		(layer "F.Cu")
		(net "CLK_100M_PCH_SLOTX24_S2_DN")
	)
	(segment
		(start 374.675146 -105.855008)
		(end 374.69953 -105.830624)
		(width 0.0889)
		(layer "F.Cu")
		(net "CLK_100M_PCH_SLOTX24_S2_DN")
	)
	(segment
		(start 369.534186 -103.434388)
		(end 369.254786 -103.434388)
		(width 0.0889)
		(layer "F.Cu")
		(net "CLK_100M_PCH_SLOTX24_S2_DN")
	)
	(segment
		(start 371.559582 -103.434388)
		(end 371.280182 -103.434388)
		(width 0.0889)
		(layer "F.Cu")
		(net "CLK_100M_PCH_SLOTX24_S2_DN")
	)
	(segment
		(start 374.69953 -105.830624)
		(end 374.69953 -105.705148)
		(width 0.0889)
		(layer "F.Cu")
		(net "CLK_100M_PCH_SLOTX24_S2_DN")
	)
	(segment
		(start 371.191282 -103.523288)
		(end 370.911882 -103.523288)
		(width 0.0889)
		(layer "F.Cu")
		(net "CLK_100M_PCH_SLOTX24_S2_DN")
	)
	(segment
		(start 368.518186 -103.434388)
		(end 368.429286 -103.523288)
		(width 0.0889)
		(layer "F.Cu")
		(net "CLK_100M_PCH_SLOTX24_S2_DN")
	)
	(segment
		(start 374.674892 -105.855008)
		(end 374.675146 -105.855008)
		(width 0.0889)
		(layer "F.Cu")
		(net "CLK_100M_PCH_SLOTX24_S2_DN")
	)
	(segment
		(start 371.871748 -103.872284)
		(end 371.68328 -103.683562)
		(width 0.0889)
		(layer "F.Cu")
		(net "CLK_100M_PCH_SLOTX24_S2_DN")
	)
	(segment
		(start 367.781586 -103.434388)
		(end 367.692686 -103.523288)
		(width 0.0889)
		(layer "F.Cu")
		(net "CLK_100M_PCH_SLOTX24_S2_DN")
	)
	(segment
		(start 368.797586 -103.434388)
		(end 368.518186 -103.434388)
		(width 0.0889)
		(layer "F.Cu")
		(net "CLK_100M_PCH_SLOTX24_S2_DN")
	)
	(segment
		(start 372.114826 -104.784398)
		(end 372.114826 -103.989632)
		(width 0.0889)
		(layer "F.Cu")
		(net "CLK_100M_PCH_SLOTX24_S2_DN")
	)
	(segment
		(start 372.114826 -103.989632)
		(end 371.997478 -103.872284)
		(width 0.0889)
		(layer "F.Cu")
		(net "CLK_100M_PCH_SLOTX24_S2_DN")
	)
	(segment
		(start 367.692686 -103.523288)
		(end 367.413286 -103.523288)
		(width 0.0889)
		(layer "F.Cu")
		(net "CLK_100M_PCH_SLOTX24_S2_DN")
	)
	(segment
		(start 372.950994 -105.378504)
		(end 372.708932 -105.378504)
		(width 0.0889)
		(layer "F.Cu")
		(net "CLK_100M_PCH_SLOTX24_S2_DN")
	)
	(segment
		(start 373.306594 -105.467404)
		(end 373.039894 -105.467404)
		(width 0.0889)
		(layer "F.Cu")
		(net "CLK_100M_PCH_SLOTX24_S2_DN")
	)
	(segment
		(start 371.68328 -103.683562)
		(end 371.68328 -103.558086)
		(width 0.0889)
		(layer "F.Cu")
		(net "CLK_100M_PCH_SLOTX24_S2_DN")
	)
	(segment
		(start 367.324386 -103.434388)
		(end 367.044986 -103.434388)
		(width 0.0889)
		(layer "F.Cu")
		(net "CLK_100M_PCH_SLOTX24_S2_DN")
	)
	(segment
		(start 368.886486 -103.523288)
		(end 368.797586 -103.434388)
		(width 0.0889)
		(layer "F.Cu")
		(net "CLK_100M_PCH_SLOTX24_S2_DN")
	)
	(segment
		(start 454.90638 -3.01244)
		(end 455.16292 -3.26898)
		(width 0.127)
		(layer "F.Cu")
		(net "CLK_100M_PCH_SLOTX24_S2_DN")
	)
	(segment
		(start 369.254786 -103.434388)
		(end 369.165886 -103.523288)
		(width 0.0889)
		(layer "F.Cu")
		(net "CLK_100M_PCH_SLOTX24_S2_DN")
	)
	(segment
		(start 369.165886 -103.523288)
		(end 368.886486 -103.523288)
		(width 0.0889)
		(layer "F.Cu")
		(net "CLK_100M_PCH_SLOTX24_S2_DN")
	)
	(segment
		(start 374.017794 -105.467404)
		(end 373.751094 -105.467404)
		(width 0.0889)
		(layer "F.Cu")
		(net "CLK_100M_PCH_SLOTX24_S2_DN")
	)
	(segment
		(start 368.429286 -103.523288)
		(end 368.149886 -103.523288)
		(width 0.0889)
		(layer "F.Cu")
		(net "CLK_100M_PCH_SLOTX24_S2_DN")
	)
	(segment
		(start 371.280182 -103.434388)
		(end 371.191282 -103.523288)
		(width 0.0889)
		(layer "F.Cu")
		(net "CLK_100M_PCH_SLOTX24_S2_DN")
	)
	(segment
		(start 369.902486 -103.523288)
		(end 369.623086 -103.523288)
		(width 0.0889)
		(layer "F.Cu")
		(net "CLK_100M_PCH_SLOTX24_S2_DN")
	)
	(segment
		(start 373.395494 -105.378504)
		(end 373.306594 -105.467404)
		(width 0.0889)
		(layer "F.Cu")
		(net "CLK_100M_PCH_SLOTX24_S2_DN")
	)
	(segment
		(start 374.106694 -105.378504)
		(end 374.017794 -105.467404)
		(width 0.0889)
		(layer "F.Cu")
		(net "CLK_100M_PCH_SLOTX24_S2_DN")
	)
	(segment
		(start 455.16292 -3.662426)
		(end 454.877678 -3.947668)
		(width 0.127)
		(layer "F.Cu")
		(net "CLK_100M_PCH_SLOTX24_S2_DN")
	)
	(segment
		(start 373.662194 -105.378504)
		(end 373.395494 -105.378504)
		(width 0.0889)
		(layer "F.Cu")
		(net "CLK_100M_PCH_SLOTX24_S2_DN")
	)
	(segment
		(start 374.373394 -105.378504)
		(end 374.106694 -105.378504)
		(width 0.0889)
		(layer "F.Cu")
		(net "CLK_100M_PCH_SLOTX24_S2_DN")
	)
	(segment
		(start 455.16292 -3.26898)
		(end 455.16292 -3.662426)
		(width 0.127)
		(layer "F.Cu")
		(net "CLK_100M_PCH_SLOTX24_S2_DN")
	)
	(segment
		(start 369.991386 -103.434388)
		(end 369.902486 -103.523288)
		(width 0.0889)
		(layer "F.Cu")
		(net "CLK_100M_PCH_SLOTX24_S2_DN")
	)
	(segment
		(start 368.149886 -103.523288)
		(end 368.060986 -103.434388)
		(width 0.0889)
		(layer "F.Cu")
		(net "CLK_100M_PCH_SLOTX24_S2_DN")
	)
	(segment
		(start 372.708932 -105.378504)
		(end 372.114826 -104.784398)
		(width 0.0889)
		(layer "F.Cu")
		(net "CLK_100M_PCH_SLOTX24_S2_DN")
	)
	(segment
		(start 371.997478 -103.872284)
		(end 371.871748 -103.872284)
		(width 0.0889)
		(layer "F.Cu")
		(net "CLK_100M_PCH_SLOTX24_S2_DN")
	)
	(segment
		(start 373.039894 -105.467404)
		(end 372.950994 -105.378504)
		(width 0.0889)
		(layer "F.Cu")
		(net "CLK_100M_PCH_SLOTX24_S2_DN")
	)
	(via
		(at 454.679812 -3.01244)
		(size 0.508)
		(drill 0.254)
		(layers "F.Cu" "B.Cu")
		(net "CLK_100M_PCH_SLOTX24_S2_DN")
	)
	(via
		(at 366.586008 -103.893366)
		(size 0.508)
		(drill 0.254)
		(layers "F.Cu" "B.Cu")
		(net "CLK_100M_PCH_SLOTX24_S2_DN")
	)
	(segment
		(start 366.32769 -102.811072)
		(end 366.06607 -103.072692)
		(width 0.1143)
		(layer "In2.Cu")
		(net "CLK_100M_PCH_SLOTX24_S2_DN")
	)
	(segment
		(start 388.633716 -16.53159)
		(end 379.909324 -18.431256)
		(width 0.1143)
		(layer "In2.Cu")
		(net "CLK_100M_PCH_SLOTX24_S2_DN")
	)
	(segment
		(start 361.7976 -80.644492)
		(end 362.300774 -83.066128)
		(width 0.1143)
		(layer "In2.Cu")
		(net "CLK_100M_PCH_SLOTX24_S2_DN")
	)
	(segment
		(start 455.158094 -3.185414)
		(end 455.158094 -3.514598)
		(width 0.1143)
		(layer "In2.Cu")
		(net "CLK_100M_PCH_SLOTX24_S2_DN")
	)
	(segment
		(start 362.983272 -60.343542)
		(end 361.959652 -65.170304)
		(width 0.1143)
		(layer "In2.Cu")
		(net "CLK_100M_PCH_SLOTX24_S2_DN")
	)
	(segment
		(start 379.909324 -18.431256)
		(end 374.866916 -21.958554)
		(width 0.1143)
		(layer "In2.Cu")
		(net "CLK_100M_PCH_SLOTX24_S2_DN")
	)
	(segment
		(start 455.158094 -3.514598)
		(end 454.897236 -3.930142)
		(width 0.1143)
		(layer "In2.Cu")
		(net "CLK_100M_PCH_SLOTX24_S2_DN")
	)
	(segment
		(start 365.74476 -45.293026)
		(end 365.538512 -45.94098)
		(width 0.1143)
		(layer "In2.Cu")
		(net "CLK_100M_PCH_SLOTX24_S2_DN")
	)
	(segment
		(start 365.133382 -96.427798)
		(end 365.354362 -97.48901)
		(width 0.1143)
		(layer "In2.Cu")
		(net "CLK_100M_PCH_SLOTX24_S2_DN")
	)
	(segment
		(start 401.59051 -16.768318)
		(end 400.663918 -16.636492)
		(width 0.1143)
		(layer "In2.Cu")
		(net "CLK_100M_PCH_SLOTX24_S2_DN")
	)
	(segment
		(start 424.838368 -13.809726)
		(end 418.6301 -15.087346)
		(width 0.1143)
		(layer "In2.Cu")
		(net "CLK_100M_PCH_SLOTX24_S2_DN")
	)
	(segment
		(start 433.889912 -10.865612)
		(end 431.522632 -12.432284)
		(width 0.1143)
		(layer "In2.Cu")
		(net "CLK_100M_PCH_SLOTX24_S2_DN")
	)
	(segment
		(start 362.300774 -83.066128)
		(end 361.448604 -87.3252)
		(width 0.1143)
		(layer "In2.Cu")
		(net "CLK_100M_PCH_SLOTX24_S2_DN")
	)
	(segment
		(start 365.538512 -45.94098)
		(end 366.091978 -47.55642)
		(width 0.1143)
		(layer "In2.Cu")
		(net "CLK_100M_PCH_SLOTX24_S2_DN")
	)
	(segment
		(start 360.669586 -66.110612)
		(end 360.067606 -68.617592)
		(width 0.1143)
		(layer "In2.Cu")
		(net "CLK_100M_PCH_SLOTX24_S2_DN")
	)
	(segment
		(start 366.32769 -102.256844)
		(end 366.32769 -102.811072)
		(width 0.1143)
		(layer "In2.Cu")
		(net "CLK_100M_PCH_SLOTX24_S2_DN")
	)
	(segment
		(start 367.615724 -36.800536)
		(end 367.891822 -37.858446)
		(width 0.1143)
		(layer "In2.Cu")
		(net "CLK_100M_PCH_SLOTX24_S2_DN")
	)
	(segment
		(start 454.679812 -3.01244)
		(end 454.98512 -3.01244)
		(width 0.1143)
		(layer "In2.Cu")
		(net "CLK_100M_PCH_SLOTX24_S2_DN")
	)
	(segment
		(start 412.42107 -16.36522)
		(end 412.420562 -16.36522)
		(width 0.1143)
		(layer "In2.Cu")
		(net "CLK_100M_PCH_SLOTX24_S2_DN")
	)
	(segment
		(start 429.899318 -12.25804)
		(end 429.231298 -12.393422)
		(width 0.1143)
		(layer "In2.Cu")
		(net "CLK_100M_PCH_SLOTX24_S2_DN")
	)
	(segment
		(start 403.476968 -16.368014)
		(end 401.59051 -16.768318)
		(width 0.1143)
		(layer "In2.Cu")
		(net "CLK_100M_PCH_SLOTX24_S2_DN")
	)
	(segment
		(start 431.522632 -12.432284)
		(end 431.139092 -12.510516)
		(width 0.1143)
		(layer "In2.Cu")
		(net "CLK_100M_PCH_SLOTX24_S2_DN")
	)
	(segment
		(start 435.767988 -10.488676)
		(end 433.889912 -10.865612)
		(width 0.1143)
		(layer "In2.Cu")
		(net "CLK_100M_PCH_SLOTX24_S2_DN")
	)
	(segment
		(start 366.51692 -103.893366)
		(end 366.586008 -103.893366)
		(width 0.1143)
		(layer "In2.Cu")
		(net "CLK_100M_PCH_SLOTX24_S2_DN")
	)
	(segment
		(start 426.531278 -13.015468)
		(end 425.818808 -13.160502)
		(width 0.1143)
		(layer "In2.Cu")
		(net "CLK_100M_PCH_SLOTX24_S2_DN")
	)
	(segment
		(start 447.927222 -8.265922)
		(end 446.787016 -9.976358)
		(width 0.1143)
		(layer "In2.Cu")
		(net "CLK_100M_PCH_SLOTX24_S2_DN")
	)
	(segment
		(start 411.015434 -16.044926)
		(end 407.456894 -17.21358)
		(width 0.1143)
		(layer "In2.Cu")
		(net "CLK_100M_PCH_SLOTX24_S2_DN")
	)
	(segment
		(start 446.787016 -9.976358)
		(end 445.959738 -10.51687)
		(width 0.1143)
		(layer "In2.Cu")
		(net "CLK_100M_PCH_SLOTX24_S2_DN")
	)
	(segment
		(start 418.629846 -15.087346)
		(end 412.42107 -16.36522)
		(width 0.1143)
		(layer "In2.Cu")
		(net "CLK_100M_PCH_SLOTX24_S2_DN")
	)
	(segment
		(start 439.143394 -11.206226)
		(end 435.767988 -10.488676)
		(width 0.1143)
		(layer "In2.Cu")
		(net "CLK_100M_PCH_SLOTX24_S2_DN")
	)
	(segment
		(start 361.448604 -87.3252)
		(end 362.064046 -90.399616)
		(width 0.1143)
		(layer "In2.Cu")
		(net "CLK_100M_PCH_SLOTX24_S2_DN")
	)
	(segment
		(start 365.016034 -99.083114)
		(end 365.518954 -101.448108)
		(width 0.1143)
		(layer "In2.Cu")
		(net "CLK_100M_PCH_SLOTX24_S2_DN")
	)
	(segment
		(start 360.067606 -68.617592)
		(end 361.7976 -76.791566)
		(width 0.1143)
		(layer "In2.Cu")
		(net "CLK_100M_PCH_SLOTX24_S2_DN")
	)
	(segment
		(start 361.7976 -76.791566)
		(end 361.7976 -80.644492)
		(width 0.1143)
		(layer "In2.Cu")
		(net "CLK_100M_PCH_SLOTX24_S2_DN")
	)
	(segment
		(start 367.891822 -37.858446)
		(end 366.646968 -44.712128)
		(width 0.1143)
		(layer "In2.Cu")
		(net "CLK_100M_PCH_SLOTX24_S2_DN")
	)
	(segment
		(start 454.897236 -3.930142)
		(end 453.151494 -4.677664)
		(width 0.1143)
		(layer "In2.Cu")
		(net "CLK_100M_PCH_SLOTX24_S2_DN")
	)
	(segment
		(start 370.080286 -28.36164)
		(end 369.280186 -32.126174)
		(width 0.1143)
		(layer "In2.Cu")
		(net "CLK_100M_PCH_SLOTX24_S2_DN")
	)
	(segment
		(start 365.518954 -101.448108)
		(end 366.32769 -102.256844)
		(width 0.1143)
		(layer "In2.Cu")
		(net "CLK_100M_PCH_SLOTX24_S2_DN")
	)
	(segment
		(start 374.866916 -21.958554)
		(end 370.080286 -28.36164)
		(width 0.1143)
		(layer "In2.Cu")
		(net "CLK_100M_PCH_SLOTX24_S2_DN")
	)
	(segment
		(start 407.456894 -17.21358)
		(end 403.476968 -16.368014)
		(width 0.1143)
		(layer "In2.Cu")
		(net "CLK_100M_PCH_SLOTX24_S2_DN")
	)
	(segment
		(start 452.553578 -5.618226)
		(end 447.927222 -8.265922)
		(width 0.1143)
		(layer "In2.Cu")
		(net "CLK_100M_PCH_SLOTX24_S2_DN")
	)
	(segment
		(start 361.959652 -65.170304)
		(end 360.669586 -66.110612)
		(width 0.1143)
		(layer "In2.Cu")
		(net "CLK_100M_PCH_SLOTX24_S2_DN")
	)
	(segment
		(start 431.139092 -12.510516)
		(end 429.899318 -12.25804)
		(width 0.1143)
		(layer "In2.Cu")
		(net "CLK_100M_PCH_SLOTX24_S2_DN")
	)
	(segment
		(start 366.362234 -55.071772)
		(end 366.304322 -55.360062)
		(width 0.1143)
		(layer "In2.Cu")
		(net "CLK_100M_PCH_SLOTX24_S2_DN")
	)
	(segment
		(start 428.592742 -12.816078)
		(end 427.072298 -13.125704)
		(width 0.1143)
		(layer "In2.Cu")
		(net "CLK_100M_PCH_SLOTX24_S2_DN")
	)
	(segment
		(start 425.818808 -13.160502)
		(end 424.838368 -13.809726)
		(width 0.1143)
		(layer "In2.Cu")
		(net "CLK_100M_PCH_SLOTX24_S2_DN")
	)
	(segment
		(start 453.151494 -4.677664)
		(end 452.553578 -5.618226)
		(width 0.1143)
		(layer "In2.Cu")
		(net "CLK_100M_PCH_SLOTX24_S2_DN")
	)
	(segment
		(start 398.600676 -17.074896)
		(end 395.91615 -16.504412)
		(width 0.1143)
		(layer "In2.Cu")
		(net "CLK_100M_PCH_SLOTX24_S2_DN")
	)
	(segment
		(start 445.959738 -10.51687)
		(end 445.113918 -10.685526)
		(width 0.1143)
		(layer "In2.Cu")
		(net "CLK_100M_PCH_SLOTX24_S2_DN")
	)
	(segment
		(start 366.06607 -103.442516)
		(end 366.51692 -103.893366)
		(width 0.1143)
		(layer "In2.Cu")
		(net "CLK_100M_PCH_SLOTX24_S2_DN")
	)
	(segment
		(start 429.231298 -12.393422)
		(end 428.592742 -12.816078)
		(width 0.1143)
		(layer "In2.Cu")
		(net "CLK_100M_PCH_SLOTX24_S2_DN")
	)
	(segment
		(start 445.113918 -10.685526)
		(end 443.35319 -10.311384)
		(width 0.1143)
		(layer "In2.Cu")
		(net "CLK_100M_PCH_SLOTX24_S2_DN")
	)
	(segment
		(start 392.209528 -17.292066)
		(end 388.633716 -16.53159)
		(width 0.1143)
		(layer "In2.Cu")
		(net "CLK_100M_PCH_SLOTX24_S2_DN")
	)
	(segment
		(start 366.304322 -55.360062)
		(end 362.983272 -60.343542)
		(width 0.1143)
		(layer "In2.Cu")
		(net "CLK_100M_PCH_SLOTX24_S2_DN")
	)
	(segment
		(start 412.420562 -16.36522)
		(end 411.015434 -16.044926)
		(width 0.1143)
		(layer "In2.Cu")
		(net "CLK_100M_PCH_SLOTX24_S2_DN")
	)
	(segment
		(start 427.072298 -13.125704)
		(end 426.531278 -13.015468)
		(width 0.1143)
		(layer "In2.Cu")
		(net "CLK_100M_PCH_SLOTX24_S2_DN")
	)
	(segment
		(start 369.280186 -32.126174)
		(end 368.48669 -32.704786)
		(width 0.1143)
		(layer "In2.Cu")
		(net "CLK_100M_PCH_SLOTX24_S2_DN")
	)
	(segment
		(start 362.064046 -90.399616)
		(end 364.379256 -91.94292)
		(width 0.1143)
		(layer "In2.Cu")
		(net "CLK_100M_PCH_SLOTX24_S2_DN")
	)
	(segment
		(start 400.663918 -16.636492)
		(end 398.600676 -17.074896)
		(width 0.1143)
		(layer "In2.Cu")
		(net "CLK_100M_PCH_SLOTX24_S2_DN")
	)
	(segment
		(start 443.35319 -10.311384)
		(end 439.143394 -11.206226)
		(width 0.1143)
		(layer "In2.Cu")
		(net "CLK_100M_PCH_SLOTX24_S2_DN")
	)
	(segment
		(start 366.646968 -44.712128)
		(end 365.74476 -45.293026)
		(width 0.1143)
		(layer "In2.Cu")
		(net "CLK_100M_PCH_SLOTX24_S2_DN")
	)
	(segment
		(start 454.98512 -3.01244)
		(end 455.158094 -3.185414)
		(width 0.1143)
		(layer "In2.Cu")
		(net "CLK_100M_PCH_SLOTX24_S2_DN")
	)
	(segment
		(start 395.91615 -16.504412)
		(end 392.209528 -17.292066)
		(width 0.1143)
		(layer "In2.Cu")
		(net "CLK_100M_PCH_SLOTX24_S2_DN")
	)
	(segment
		(start 365.408972 -95.130366)
		(end 365.133382 -96.427798)
		(width 0.1143)
		(layer "In2.Cu")
		(net "CLK_100M_PCH_SLOTX24_S2_DN")
	)
	(segment
		(start 365.354362 -97.48901)
		(end 365.016034 -99.083114)
		(width 0.1143)
		(layer "In2.Cu")
		(net "CLK_100M_PCH_SLOTX24_S2_DN")
	)
	(segment
		(start 366.06607 -103.072692)
		(end 366.06607 -103.442516)
		(width 0.1143)
		(layer "In2.Cu")
		(net "CLK_100M_PCH_SLOTX24_S2_DN")
	)
	(segment
		(start 364.379256 -91.94292)
		(end 365.408972 -95.130366)
		(width 0.1143)
		(layer "In2.Cu")
		(net "CLK_100M_PCH_SLOTX24_S2_DN")
	)
	(segment
		(start 368.48669 -32.704786)
		(end 367.615724 -36.800536)
		(width 0.1143)
		(layer "In2.Cu")
		(net "CLK_100M_PCH_SLOTX24_S2_DN")
	)
	(segment
		(start 366.091978 -47.55642)
		(end 365.42853 -50.396902)
		(width 0.1143)
		(layer "In2.Cu")
		(net "CLK_100M_PCH_SLOTX24_S2_DN")
	)
	(segment
		(start 418.6301 -15.087346)
		(end 418.629846 -15.087346)
		(width 0.1143)
		(layer "In2.Cu")
		(net "CLK_100M_PCH_SLOTX24_S2_DN")
	)
	(segment
		(start 365.42853 -50.396902)
		(end 366.362234 -55.071772)
		(width 0.1143)
		(layer "In2.Cu")
		(net "CLK_100M_PCH_SLOTX24_S2_DN")
	)
	(segment
		(start 457.994004 -2.24282)
		(end 457.834746 -2.402078)
		(width 0.127)
		(layer "F.Cu")
		(net "CLK_100M_PCH_SLOTX24_S1_DP")
	)
	(segment
		(start 377.83135 -112.43056)
		(end 378.32665 -112.660684)
		(width 0.127)
		(layer "F.Cu")
		(net "CLK_100M_PCH_SLOTX24_S1_DP")
	)
	(segment
		(start 457.834746 -3.512312)
		(end 458.078078 -3.755644)
		(width 0.127)
		(layer "F.Cu")
		(net "CLK_100M_PCH_SLOTX24_S1_DP")
	)
	(segment
		(start 457.834746 -2.402078)
		(end 457.834746 -3.512312)
		(width 0.127)
		(layer "F.Cu")
		(net "CLK_100M_PCH_SLOTX24_S1_DP")
	)
	(segment
		(start 458.078078 -3.755644)
		(end 458.078078 -4.386072)
		(width 0.127)
		(layer "F.Cu")
		(net "CLK_100M_PCH_SLOTX24_S1_DP")
	)
	(segment
		(start 458.333348 -2.24282)
		(end 457.994004 -2.24282)
		(width 0.127)
		(layer "F.Cu")
		(net "CLK_100M_PCH_SLOTX24_S1_DP")
	)
	(via
		(at 458.333348 -2.24282)
		(size 0.508)
		(drill 0.254)
		(layers "F.Cu" "B.Cu")
		(net "CLK_100M_PCH_SLOTX24_S1_DP")
	)
	(via
		(at 378.32665 -112.660684)
		(size 0.508)
		(drill 0.254)
		(layers "F.Cu" "B.Cu")
		(net "CLK_100M_PCH_SLOTX24_S1_DP")
	)
	(segment
		(start 377.099068 -113.035842)
		(end 376.923554 -112.878362)
		(width 0.0889)
		(layer "In2.Cu")
		(net "CLK_100M_PCH_SLOTX24_S1_DP")
	)
	(segment
		(start 375.732802 -112.282224)
		(end 375.607072 -112.282224)
		(width 0.0889)
		(layer "In2.Cu")
		(net "CLK_100M_PCH_SLOTX24_S1_DP")
	)
	(segment
		(start 396.965678 -17.711674)
		(end 397.98625 -18.38706)
		(width 0.1143)
		(layer "In2.Cu")
		(net "CLK_100M_PCH_SLOTX24_S1_DP")
	)
	(segment
		(start 433.489608 -12.912598)
		(end 434.824124 -12.640818)
		(width 0.1143)
		(layer "In2.Cu")
		(net "CLK_100M_PCH_SLOTX24_S1_DP")
	)
	(segment
		(start 374.310402 -110.91291)
		(end 374.090692 -110.6932)
		(width 0.1143)
		(layer "In2.Cu")
		(net "CLK_100M_PCH_SLOTX24_S1_DP")
	)
	(segment
		(start 373.569992 -110.5281)
		(end 373.214392 -110.5281)
		(width 0.1143)
		(layer "In2.Cu")
		(net "CLK_100M_PCH_SLOTX24_S1_DP")
	)
	(segment
		(start 397.98625 -18.38706)
		(end 400.115532 -18.82013)
		(width 0.1143)
		(layer "In2.Cu")
		(net "CLK_100M_PCH_SLOTX24_S1_DP")
	)
	(segment
		(start 366.452404 -50.639726)
		(end 367.34115 -46.848268)
		(width 0.1143)
		(layer "In2.Cu")
		(net "CLK_100M_PCH_SLOTX24_S1_DP")
	)
	(segment
		(start 366.453166 -94.925642)
		(end 365.334296 -91.461082)
		(width 0.1143)
		(layer "In2.Cu")
		(net "CLK_100M_PCH_SLOTX24_S1_DP")
	)
	(segment
		(start 374.915684 -111.464852)
		(end 374.727216 -111.276384)
		(width 0.0889)
		(layer "In2.Cu")
		(net "CLK_100M_PCH_SLOTX24_S1_DP")
	)
	(segment
		(start 441.221622 -12.121388)
		(end 441.221622 -12.121134)
		(width 0.1143)
		(layer "In2.Cu")
		(net "CLK_100M_PCH_SLOTX24_S1_DP")
	)
	(segment
		(start 369.714272 -109.53496)
		(end 369.714272 -108.978954)
		(width 0.1143)
		(layer "In2.Cu")
		(net "CLK_100M_PCH_SLOTX24_S1_DP")
	)
	(segment
		(start 370.957094 -28.758896)
		(end 375.441718 -22.760178)
		(width 0.1143)
		(layer "In2.Cu")
		(net "CLK_100M_PCH_SLOTX24_S1_DP")
	)
	(segment
		(start 367.353088 -55.14975)
		(end 366.452404 -50.639726)
		(width 0.1143)
		(layer "In2.Cu")
		(net "CLK_100M_PCH_SLOTX24_S1_DP")
	)
	(segment
		(start 361.504484 -66.66103)
		(end 362.815886 -65.704974)
		(width 0.1143)
		(layer "In2.Cu")
		(net "CLK_100M_PCH_SLOTX24_S1_DP")
	)
	(segment
		(start 428.568866 -13.791692)
		(end 429.569626 -13.9954)
		(width 0.1143)
		(layer "In2.Cu")
		(net "CLK_100M_PCH_SLOTX24_S1_DP")
	)
	(segment
		(start 375.418604 -112.093502)
		(end 375.418604 -111.967772)
		(width 0.0889)
		(layer "In2.Cu")
		(net "CLK_100M_PCH_SLOTX24_S1_DP")
	)
	(segment
		(start 447.514218 -10.629646)
		(end 448.417442 -9.292082)
		(width 0.1143)
		(layer "In2.Cu")
		(net "CLK_100M_PCH_SLOTX24_S1_DP")
	)
	(segment
		(start 375.441718 -22.760178)
		(end 380.423928 -19.278092)
		(width 0.1143)
		(layer "In2.Cu")
		(net "CLK_100M_PCH_SLOTX24_S1_DP")
	)
	(segment
		(start 396.019274 -17.52219)
		(end 396.965678 -17.711674)
		(width 0.1143)
		(layer "In2.Cu")
		(net "CLK_100M_PCH_SLOTX24_S1_DP")
	)
	(segment
		(start 369.797838 -109.90453)
		(end 369.714272 -109.53496)
		(width 0.1143)
		(layer "In2.Cu")
		(net "CLK_100M_PCH_SLOTX24_S1_DP")
	)
	(segment
		(start 429.569626 -13.9954)
		(end 432.867562 -13.324332)
		(width 0.1143)
		(layer "In2.Cu")
		(net "CLK_100M_PCH_SLOTX24_S1_DP")
	)
	(segment
		(start 378.32665 -112.660684)
		(end 378.426218 -112.560862)
		(width 0.0889)
		(layer "In2.Cu")
		(net "CLK_100M_PCH_SLOTX24_S1_DP")
	)
	(segment
		(start 361.028996 -68.639182)
		(end 361.504484 -66.66103)
		(width 0.1143)
		(layer "In2.Cu")
		(net "CLK_100M_PCH_SLOTX24_S1_DP")
	)
	(segment
		(start 444.895478 -11.678158)
		(end 446.390522 -11.379454)
		(width 0.1143)
		(layer "In2.Cu")
		(net "CLK_100M_PCH_SLOTX24_S1_DP")
	)
	(segment
		(start 372.528592 -110.5281)
		(end 372.172992 -110.5281)
		(width 0.1143)
		(layer "In2.Cu")
		(net "CLK_100M_PCH_SLOTX24_S1_DP")
	)
	(segment
		(start 438.837832 -12.364974)
		(end 440.060334 -12.624816)
		(width 0.1143)
		(layer "In2.Cu")
		(net "CLK_100M_PCH_SLOTX24_S1_DP")
	)
	(segment
		(start 440.471814 -12.624816)
		(end 441.221622 -12.121388)
		(width 0.1143)
		(layer "In2.Cu")
		(net "CLK_100M_PCH_SLOTX24_S1_DP")
	)
	(segment
		(start 369.92306 -110.069376)
		(end 369.797838 -109.90453)
		(width 0.1143)
		(layer "In2.Cu")
		(net "CLK_100M_PCH_SLOTX24_S1_DP")
	)
	(segment
		(start 452.92899 -7.570724)
		(end 453.193658 -7.416546)
		(width 0.1143)
		(layer "In2.Cu")
		(net "CLK_100M_PCH_SLOTX24_S1_DP")
	)
	(segment
		(start 362.7882 -80.347566)
		(end 362.7882 -76.94422)
		(width 0.1143)
		(layer "In2.Cu")
		(net "CLK_100M_PCH_SLOTX24_S1_DP")
	)
	(segment
		(start 363.022642 -89.920064)
		(end 362.55198 -87.567008)
		(width 0.1143)
		(layer "In2.Cu")
		(net "CLK_100M_PCH_SLOTX24_S1_DP")
	)
	(segment
		(start 440.060334 -12.624816)
		(end 440.471814 -12.624816)
		(width 0.1143)
		(layer "In2.Cu")
		(net "CLK_100M_PCH_SLOTX24_S1_DP")
	)
	(segment
		(start 376.602498 -112.785144)
		(end 376.109992 -112.785144)
		(width 0.0889)
		(layer "In2.Cu")
		(net "CLK_100M_PCH_SLOTX24_S1_DP")
	)
	(segment
		(start 363.398308 -83.334606)
		(end 362.7882 -80.347566)
		(width 0.1143)
		(layer "In2.Cu")
		(net "CLK_100M_PCH_SLOTX24_S1_DP")
	)
	(segment
		(start 400.115532 -18.82013)
		(end 400.611086 -18.719546)
		(width 0.1143)
		(layer "In2.Cu")
		(net "CLK_100M_PCH_SLOTX24_S1_DP")
	)
	(segment
		(start 367.34115 -46.848268)
		(end 367.259108 -46.59884)
		(width 0.1143)
		(layer "In2.Cu")
		(net "CLK_100M_PCH_SLOTX24_S1_DP")
	)
	(segment
		(start 378.717302 -112.78489)
		(end 378.672598 -112.861852)
		(width 0.0889)
		(layer "In2.Cu")
		(net "CLK_100M_PCH_SLOTX24_S1_DP")
	)
	(segment
		(start 362.815886 -65.704974)
		(end 363.861096 -60.769754)
		(width 0.1143)
		(layer "In2.Cu")
		(net "CLK_100M_PCH_SLOTX24_S1_DP")
	)
	(segment
		(start 412.732728 -17.354042)
		(end 424.100752 -14.940026)
		(width 0.1143)
		(layer "In2.Cu")
		(net "CLK_100M_PCH_SLOTX24_S1_DP")
	)
	(segment
		(start 446.390522 -11.379454)
		(end 447.514472 -10.629646)
		(width 0.1143)
		(layer "In2.Cu")
		(net "CLK_100M_PCH_SLOTX24_S1_DP")
	)
	(segment
		(start 427.332648 -14.043406)
		(end 428.568866 -13.791692)
		(width 0.1143)
		(layer "In2.Cu")
		(net "CLK_100M_PCH_SLOTX24_S1_DP")
	)
	(segment
		(start 435.990238 -12.878308)
		(end 438.836562 -12.364974)
		(width 0.1143)
		(layer "In2.Cu")
		(net "CLK_100M_PCH_SLOTX24_S1_DP")
	)
	(segment
		(start 374.727216 -111.276384)
		(end 374.601486 -111.27613)
		(width 0.0889)
		(layer "In2.Cu")
		(net "CLK_100M_PCH_SLOTX24_S1_DP")
	)
	(segment
		(start 372.172992 -110.5281)
		(end 372.007892 -110.6932)
		(width 0.1143)
		(layer "In2.Cu")
		(net "CLK_100M_PCH_SLOTX24_S1_DP")
	)
	(segment
		(start 362.7882 -76.94422)
		(end 361.028996 -68.639182)
		(width 0.1143)
		(layer "In2.Cu")
		(net "CLK_100M_PCH_SLOTX24_S1_DP")
	)
	(segment
		(start 441.851288 -11.698478)
		(end 443.41542 -11.365992)
		(width 0.1143)
		(layer "In2.Cu")
		(net "CLK_100M_PCH_SLOTX24_S1_DP")
	)
	(segment
		(start 412.674054 -17.390872)
		(end 412.732728 -17.354042)
		(width 0.1143)
		(layer "In2.Cu")
		(net "CLK_100M_PCH_SLOTX24_S1_DP")
	)
	(segment
		(start 371.083078 -110.6932)
		(end 369.92306 -110.069376)
		(width 0.1143)
		(layer "In2.Cu")
		(net "CLK_100M_PCH_SLOTX24_S1_DP")
	)
	(segment
		(start 457.92898 -3.563112)
		(end 457.92898 -2.647188)
		(width 0.1143)
		(layer "In2.Cu")
		(net "CLK_100M_PCH_SLOTX24_S1_DP")
	)
	(segment
		(start 367.6904 -102.304342)
		(end 366.427258 -101.040946)
		(width 0.1143)
		(layer "In2.Cu")
		(net "CLK_100M_PCH_SLOTX24_S1_DP")
	)
	(segment
		(start 432.867562 -13.324332)
		(end 433.489608 -12.912598)
		(width 0.1143)
		(layer "In2.Cu")
		(net "CLK_100M_PCH_SLOTX24_S1_DP")
	)
	(segment
		(start 374.325896 -110.928404)
		(end 374.310402 -110.91291)
		(width 0.0889)
		(layer "In2.Cu")
		(net "CLK_100M_PCH_SLOTX24_S1_DP")
	)
	(segment
		(start 400.611086 -18.719546)
		(end 402.291296 -17.607026)
		(width 0.1143)
		(layer "In2.Cu")
		(net "CLK_100M_PCH_SLOTX24_S1_DP")
	)
	(segment
		(start 369.51412 -35.546284)
		(end 370.957094 -28.758896)
		(width 0.1143)
		(layer "In2.Cu")
		(net "CLK_100M_PCH_SLOTX24_S1_DP")
	)
	(segment
		(start 368.493548 -39.80561)
		(end 369.352068 -38.924992)
		(width 0.1143)
		(layer "In2.Cu")
		(net "CLK_100M_PCH_SLOTX24_S1_DP")
	)
	(segment
		(start 378.126498 -113.00714)
		(end 377.976384 -112.920526)
		(width 0.0889)
		(layer "In2.Cu")
		(net "CLK_100M_PCH_SLOTX24_S1_DP")
	)
	(segment
		(start 424.643296 -15.048484)
		(end 426.757084 -14.61897)
		(width 0.1143)
		(layer "In2.Cu")
		(net "CLK_100M_PCH_SLOTX24_S1_DP")
	)
	(segment
		(start 366.00892 -99.068636)
		(end 366.3696 -97.359216)
		(width 0.1143)
		(layer "In2.Cu")
		(net "CLK_100M_PCH_SLOTX24_S1_DP")
	)
	(segment
		(start 457.330556 -4.161536)
		(end 457.92898 -3.563112)
		(width 0.1143)
		(layer "In2.Cu")
		(net "CLK_100M_PCH_SLOTX24_S1_DP")
	)
	(segment
		(start 365.334296 -91.461082)
		(end 363.022642 -89.920064)
		(width 0.1143)
		(layer "In2.Cu")
		(net "CLK_100M_PCH_SLOTX24_S1_DP")
	)
	(segment
		(start 376.109992 -112.785144)
		(end 375.921524 -112.596422)
		(width 0.0889)
		(layer "In2.Cu")
		(net "CLK_100M_PCH_SLOTX24_S1_DP")
	)
	(segment
		(start 375.921524 -112.470692)
		(end 375.732802 -112.282224)
		(width 0.0889)
		(layer "In2.Cu")
		(net "CLK_100M_PCH_SLOTX24_S1_DP")
	)
	(segment
		(start 450.17309 -8.121904)
		(end 452.92899 -7.570724)
		(width 0.1143)
		(layer "In2.Cu")
		(net "CLK_100M_PCH_SLOTX24_S1_DP")
	)
	(segment
		(start 434.824124 -12.640818)
		(end 435.990238 -12.878308)
		(width 0.1143)
		(layer "In2.Cu")
		(net "CLK_100M_PCH_SLOTX24_S1_DP")
	)
	(segment
		(start 455.262996 -5.788406)
		(end 455.262996 -5.788152)
		(width 0.1143)
		(layer "In2.Cu")
		(net "CLK_100M_PCH_SLOTX24_S1_DP")
	)
	(segment
		(start 369.906296 -36.90239)
		(end 369.51412 -35.546284)
		(width 0.1143)
		(layer "In2.Cu")
		(net "CLK_100M_PCH_SLOTX24_S1_DP")
	)
	(segment
		(start 441.221622 -12.121134)
		(end 441.851288 -11.698478)
		(width 0.1143)
		(layer "In2.Cu")
		(net "CLK_100M_PCH_SLOTX24_S1_DP")
	)
	(segment
		(start 373.735092 -110.6932)
		(end 373.569992 -110.5281)
		(width 0.1143)
		(layer "In2.Cu")
		(net "CLK_100M_PCH_SLOTX24_S1_DP")
	)
	(segment
		(start 369.714272 -108.978954)
		(end 368.883184 -104.667558)
		(width 0.1143)
		(layer "In2.Cu")
		(net "CLK_100M_PCH_SLOTX24_S1_DP")
	)
	(segment
		(start 380.423928 -19.278092)
		(end 388.653528 -17.48536)
		(width 0.1143)
		(layer "In2.Cu")
		(net "CLK_100M_PCH_SLOTX24_S1_DP")
	)
	(segment
		(start 411.088332 -17.031462)
		(end 412.674054 -17.390872)
		(width 0.1143)
		(layer "In2.Cu")
		(net "CLK_100M_PCH_SLOTX24_S1_DP")
	)
	(segment
		(start 453.193658 -7.416546)
		(end 455.262996 -5.788406)
		(width 0.1143)
		(layer "In2.Cu")
		(net "CLK_100M_PCH_SLOTX24_S1_DP")
	)
	(segment
		(start 375.607072 -112.282224)
		(end 375.418604 -112.093502)
		(width 0.0889)
		(layer "In2.Cu")
		(net "CLK_100M_PCH_SLOTX24_S1_DP")
	)
	(segment
		(start 367.243614 -55.696866)
		(end 367.353088 -55.14975)
		(width 0.1143)
		(layer "In2.Cu")
		(net "CLK_100M_PCH_SLOTX24_S1_DP")
	)
	(segment
		(start 426.757084 -14.61897)
		(end 427.332648 -14.043406)
		(width 0.1143)
		(layer "In2.Cu")
		(net "CLK_100M_PCH_SLOTX24_S1_DP")
	)
	(segment
		(start 372.007892 -110.6932)
		(end 371.083078 -110.6932)
		(width 0.1143)
		(layer "In2.Cu")
		(net "CLK_100M_PCH_SLOTX24_S1_DP")
	)
	(segment
		(start 375.418604 -111.967772)
		(end 375.230136 -111.779304)
		(width 0.0889)
		(layer "In2.Cu")
		(net "CLK_100M_PCH_SLOTX24_S1_DP")
	)
	(segment
		(start 374.601486 -111.27613)
		(end 374.325896 -111.00054)
		(width 0.0889)
		(layer "In2.Cu")
		(net "CLK_100M_PCH_SLOTX24_S1_DP")
	)
	(segment
		(start 368.883184 -104.667558)
		(end 367.6904 -103.170228)
		(width 0.1143)
		(layer "In2.Cu")
		(net "CLK_100M_PCH_SLOTX24_S1_DP")
	)
	(segment
		(start 375.921524 -112.596422)
		(end 375.921524 -112.470692)
		(width 0.0889)
		(layer "In2.Cu")
		(net "CLK_100M_PCH_SLOTX24_S1_DP")
	)
	(segment
		(start 388.653528 -17.48536)
		(end 392.30681 -18.26514)
		(width 0.1143)
		(layer "In2.Cu")
		(net "CLK_100M_PCH_SLOTX24_S1_DP")
	)
	(segment
		(start 374.090692 -110.6932)
		(end 373.735092 -110.6932)
		(width 0.1143)
		(layer "In2.Cu")
		(net "CLK_100M_PCH_SLOTX24_S1_DP")
	)
	(segment
		(start 424.100752 -14.940026)
		(end 424.643296 -15.048484)
		(width 0.1143)
		(layer "In2.Cu")
		(net "CLK_100M_PCH_SLOTX24_S1_DP")
	)
	(segment
		(start 372.693692 -110.6932)
		(end 372.528592 -110.5281)
		(width 0.1143)
		(layer "In2.Cu")
		(net "CLK_100M_PCH_SLOTX24_S1_DP")
	)
	(segment
		(start 402.291296 -17.607026)
		(end 403.560788 -17.337278)
		(width 0.1143)
		(layer "In2.Cu")
		(net "CLK_100M_PCH_SLOTX24_S1_DP")
	)
	(segment
		(start 374.915684 -111.590582)
		(end 374.915684 -111.464852)
		(width 0.0889)
		(layer "In2.Cu")
		(net "CLK_100M_PCH_SLOTX24_S1_DP")
	)
	(segment
		(start 366.152938 -96.33966)
		(end 366.453166 -94.925642)
		(width 0.1143)
		(layer "In2.Cu")
		(net "CLK_100M_PCH_SLOTX24_S1_DP")
	)
	(segment
		(start 373.214392 -110.5281)
		(end 373.049292 -110.6932)
		(width 0.1143)
		(layer "In2.Cu")
		(net "CLK_100M_PCH_SLOTX24_S1_DP")
	)
	(segment
		(start 362.55198 -87.567008)
		(end 363.398308 -83.334606)
		(width 0.1143)
		(layer "In2.Cu")
		(net "CLK_100M_PCH_SLOTX24_S1_DP")
	)
	(segment
		(start 374.325896 -111.00054)
		(end 374.325896 -110.928404)
		(width 0.0889)
		(layer "In2.Cu")
		(net "CLK_100M_PCH_SLOTX24_S1_DP")
	)
	(segment
		(start 392.30681 -18.26514)
		(end 396.019274 -17.522444)
		(width 0.1143)
		(layer "In2.Cu")
		(net "CLK_100M_PCH_SLOTX24_S1_DP")
	)
	(segment
		(start 375.104406 -111.779304)
		(end 374.915684 -111.590582)
		(width 0.0889)
		(layer "In2.Cu")
		(net "CLK_100M_PCH_SLOTX24_S1_DP")
	)
	(segment
		(start 396.019274 -17.522444)
		(end 396.019274 -17.52219)
		(width 0.1143)
		(layer "In2.Cu")
		(net "CLK_100M_PCH_SLOTX24_S1_DP")
	)
	(segment
		(start 373.049292 -110.6932)
		(end 372.693692 -110.6932)
		(width 0.1143)
		(layer "In2.Cu")
		(net "CLK_100M_PCH_SLOTX24_S1_DP")
	)
	(segment
		(start 366.427258 -101.040946)
		(end 366.00892 -99.068636)
		(width 0.1143)
		(layer "In2.Cu")
		(net "CLK_100M_PCH_SLOTX24_S1_DP")
	)
	(segment
		(start 443.41542 -11.365992)
		(end 444.895478 -11.678158)
		(width 0.1143)
		(layer "In2.Cu")
		(net "CLK_100M_PCH_SLOTX24_S1_DP")
	)
	(segment
		(start 438.836562 -12.364974)
		(end 438.837832 -12.364974)
		(width 0.1143)
		(layer "In2.Cu")
		(net "CLK_100M_PCH_SLOTX24_S1_DP")
	)
	(segment
		(start 369.352068 -38.924992)
		(end 369.906296 -36.90239)
		(width 0.1143)
		(layer "In2.Cu")
		(net "CLK_100M_PCH_SLOTX24_S1_DP")
	)
	(segment
		(start 375.230136 -111.779304)
		(end 375.104406 -111.779304)
		(width 0.0889)
		(layer "In2.Cu")
		(net "CLK_100M_PCH_SLOTX24_S1_DP")
	)
	(segment
		(start 367.259108 -46.59884)
		(end 368.493548 -39.80561)
		(width 0.1143)
		(layer "In2.Cu")
		(net "CLK_100M_PCH_SLOTX24_S1_DP")
	)
	(segment
		(start 366.3696 -97.359216)
		(end 366.152938 -96.33966)
		(width 0.1143)
		(layer "In2.Cu")
		(net "CLK_100M_PCH_SLOTX24_S1_DP")
	)
	(segment
		(start 367.6904 -103.170228)
		(end 367.6904 -102.304342)
		(width 0.1143)
		(layer "In2.Cu")
		(net "CLK_100M_PCH_SLOTX24_S1_DP")
	)
	(segment
		(start 363.861096 -60.769754)
		(end 367.243614 -55.696866)
		(width 0.1143)
		(layer "In2.Cu")
		(net "CLK_100M_PCH_SLOTX24_S1_DP")
	)
	(segment
		(start 378.126752 -113.007394)
		(end 378.126498 -113.00714)
		(width 0.0889)
		(layer "In2.Cu")
		(net "CLK_100M_PCH_SLOTX24_S1_DP")
	)
	(segment
		(start 455.262996 -5.788152)
		(end 457.330556 -4.161536)
		(width 0.1143)
		(layer "In2.Cu")
		(net "CLK_100M_PCH_SLOTX24_S1_DP")
	)
	(segment
		(start 403.560788 -17.337278)
		(end 407.506932 -18.210276)
		(width 0.1143)
		(layer "In2.Cu")
		(net "CLK_100M_PCH_SLOTX24_S1_DP")
	)
	(segment
		(start 457.92898 -2.647188)
		(end 458.333348 -2.24282)
		(width 0.1143)
		(layer "In2.Cu")
		(net "CLK_100M_PCH_SLOTX24_S1_DP")
	)
	(segment
		(start 447.514472 -10.629646)
		(end 447.514218 -10.629646)
		(width 0.1143)
		(layer "In2.Cu")
		(net "CLK_100M_PCH_SLOTX24_S1_DP")
	)
	(segment
		(start 448.417442 -9.292082)
		(end 450.17309 -8.121904)
		(width 0.1143)
		(layer "In2.Cu")
		(net "CLK_100M_PCH_SLOTX24_S1_DP")
	)
	(segment
		(start 407.506932 -18.210276)
		(end 411.088332 -17.031462)
		(width 0.1143)
		(layer "In2.Cu")
		(net "CLK_100M_PCH_SLOTX24_S1_DP")
	)
	(arc
		(start 377.976384 -112.920526)
		(mid 377.728202 -112.911906)
		(end 377.496832 -113.00206)
		(width 0.0889)
		(layer "In2.Cu")
		(net "CLK_100M_PCH_SLOTX24_S1_DP")
	)
	(arc
		(start 378.426218 -112.560862)
		(mid 378.670222 -112.544929)
		(end 378.717302 -112.78489)
		(width 0.0889)
		(layer "In2.Cu")
		(net "CLK_100M_PCH_SLOTX24_S1_DP")
	)
	(arc
		(start 378.672598 -112.861852)
		(mid 378.429741 -113.047363)
		(end 378.126752 -113.007394)
		(width 0.0889)
		(layer "In2.Cu")
		(net "CLK_100M_PCH_SLOTX24_S1_DP")
	)
	(arc
		(start 376.923554 -112.878362)
		(mid 376.769662 -112.808885)
		(end 376.602498 -112.785144)
		(width 0.0889)
		(layer "In2.Cu")
		(net "CLK_100M_PCH_SLOTX24_S1_DP")
	)
	(arc
		(start 377.496832 -113.00206)
		(mid 377.302163 -113.068534)
		(end 377.099068 -113.035842)
		(width 0.0889)
		(layer "In2.Cu")
		(net "CLK_100M_PCH_SLOTX24_S1_DP")
	)
	(segment
		(start 457.277978 -4.386072)
		(end 457.277978 -3.755644)
		(width 0.127)
		(layer "F.Cu")
		(net "CLK_100M_PCH_SLOTX24_S1_DN")
	)
	(segment
		(start 457.402946 -2.24282)
		(end 457.063348 -2.24282)
		(width 0.127)
		(layer "F.Cu")
		(net "CLK_100M_PCH_SLOTX24_S1_DN")
	)
	(segment
		(start 457.529946 -3.503676)
		(end 457.529946 -2.36982)
		(width 0.127)
		(layer "F.Cu")
		(net "CLK_100M_PCH_SLOTX24_S1_DN")
	)
	(segment
		(start 457.529946 -2.36982)
		(end 457.402946 -2.24282)
		(width 0.127)
		(layer "F.Cu")
		(net "CLK_100M_PCH_SLOTX24_S1_DN")
	)
	(segment
		(start 378.82195 -112.43056)
		(end 379.31725 -112.660684)
		(width 0.127)
		(layer "F.Cu")
		(net "CLK_100M_PCH_SLOTX24_S1_DN")
	)
	(segment
		(start 457.277978 -3.755644)
		(end 457.529946 -3.503676)
		(width 0.127)
		(layer "F.Cu")
		(net "CLK_100M_PCH_SLOTX24_S1_DN")
	)
	(via
		(at 457.063348 -2.24282)
		(size 0.508)
		(drill 0.254)
		(layers "F.Cu" "B.Cu")
		(net "CLK_100M_PCH_SLOTX24_S1_DN")
	)
	(via
		(at 379.31725 -112.660684)
		(size 0.508)
		(drill 0.254)
		(layers "F.Cu" "B.Cu")
		(net "CLK_100M_PCH_SLOTX24_S1_DN")
	)
	(segment
		(start 361.245404 -66.488056)
		(end 360.72953 -68.635118)
		(width 0.1143)
		(layer "In2.Cu")
		(net "CLK_100M_PCH_SLOTX24_S1_DN")
	)
	(segment
		(start 438.868566 -12.072874)
		(end 438.8104 -12.072874)
		(width 0.1143)
		(layer "In2.Cu")
		(net "CLK_100M_PCH_SLOTX24_S1_DN")
	)
	(segment
		(start 447.303652 -10.418826)
		(end 446.276476 -11.104118)
		(width 0.1143)
		(layer "In2.Cu")
		(net "CLK_100M_PCH_SLOTX24_S1_DN")
	)
	(segment
		(start 374.11914 -111.13516)
		(end 374.190768 -111.13516)
		(width 0.0889)
		(layer "In2.Cu")
		(net "CLK_100M_PCH_SLOTX24_S1_DN")
	)
	(segment
		(start 377.907042 -113.10112)
		(end 378.031248 -113.172494)
		(width 0.0889)
		(layer "In2.Cu")
		(net "CLK_100M_PCH_SLOTX24_S1_DN")
	)
	(segment
		(start 366.15116 -94.941136)
		(end 365.854234 -96.33966)
		(width 0.1143)
		(layer "In2.Cu")
		(net "CLK_100M_PCH_SLOTX24_S1_DN")
	)
	(segment
		(start 374.103646 -111.119666)
		(end 374.11914 -111.13516)
		(width 0.0889)
		(layer "In2.Cu")
		(net "CLK_100M_PCH_SLOTX24_S1_DN")
	)
	(segment
		(start 368.60988 -104.793288)
		(end 369.422172 -109.008164)
		(width 0.1143)
		(layer "In2.Cu")
		(net "CLK_100M_PCH_SLOTX24_S1_DN")
	)
	(segment
		(start 367.037874 -46.861476)
		(end 366.153446 -50.6349)
		(width 0.1143)
		(layer "In2.Cu")
		(net "CLK_100M_PCH_SLOTX24_S1_DN")
	)
	(segment
		(start 440.38266 -12.332716)
		(end 440.091068 -12.332716)
		(width 0.1143)
		(layer "In2.Cu")
		(net "CLK_100M_PCH_SLOTX24_S1_DN")
	)
	(segment
		(start 403.562058 -17.03832)
		(end 402.176234 -17.332706)
		(width 0.1143)
		(layer "In2.Cu")
		(net "CLK_100M_PCH_SLOTX24_S1_DN")
	)
	(segment
		(start 366.153446 -50.6349)
		(end 367.055146 -55.14975)
		(width 0.1143)
		(layer "In2.Cu")
		(net "CLK_100M_PCH_SLOTX24_S1_DN")
	)
	(segment
		(start 362.254038 -87.567008)
		(end 362.759752 -90.096086)
		(width 0.1143)
		(layer "In2.Cu")
		(net "CLK_100M_PCH_SLOTX24_S1_DN")
	)
	(segment
		(start 424.098974 -14.641576)
		(end 412.621222 -17.07896)
		(width 0.1143)
		(layer "In2.Cu")
		(net "CLK_100M_PCH_SLOTX24_S1_DN")
	)
	(segment
		(start 369.090194 -38.775132)
		(end 368.221768 -39.665402)
		(width 0.1143)
		(layer "In2.Cu")
		(net "CLK_100M_PCH_SLOTX24_S1_DN")
	)
	(segment
		(start 457.136246 -3.942588)
		(end 453.028812 -7.17423)
		(width 0.1143)
		(layer "In2.Cu")
		(net "CLK_100M_PCH_SLOTX24_S1_DN")
	)
	(segment
		(start 392.308842 -17.96669)
		(end 388.65302 -17.186402)
		(width 0.1143)
		(layer "In2.Cu")
		(net "CLK_100M_PCH_SLOTX24_S1_DN")
	)
	(segment
		(start 402.176234 -17.332706)
		(end 400.49704 -18.444464)
		(width 0.1143)
		(layer "In2.Cu")
		(net "CLK_100M_PCH_SLOTX24_S1_DN")
	)
	(segment
		(start 369.52682 -110.030768)
		(end 369.72875 -110.296706)
		(width 0.1143)
		(layer "In2.Cu")
		(net "CLK_100M_PCH_SLOTX24_S1_DN")
	)
	(segment
		(start 412.620968 -17.079214)
		(end 411.073854 -16.72844)
		(width 0.1143)
		(layer "In2.Cu")
		(net "CLK_100M_PCH_SLOTX24_S1_DN")
	)
	(segment
		(start 362.552996 -65.534794)
		(end 361.245404 -66.488056)
		(width 0.1143)
		(layer "In2.Cu")
		(net "CLK_100M_PCH_SLOTX24_S1_DN")
	)
	(segment
		(start 388.65302 -17.186402)
		(end 380.304548 -19.005042)
		(width 0.1143)
		(layer "In2.Cu")
		(net "CLK_100M_PCH_SLOTX24_S1_DN")
	)
	(segment
		(start 365.854234 -96.33966)
		(end 366.070896 -97.35947)
		(width 0.1143)
		(layer "In2.Cu")
		(net "CLK_100M_PCH_SLOTX24_S1_DN")
	)
	(segment
		(start 366.159288 -101.186488)
		(end 367.3983 -102.4255)
		(width 0.1143)
		(layer "In2.Cu")
		(net "CLK_100M_PCH_SLOTX24_S1_DN")
	)
	(segment
		(start 426.612558 -14.349984)
		(end 424.643804 -14.750034)
		(width 0.1143)
		(layer "In2.Cu")
		(net "CLK_100M_PCH_SLOTX24_S1_DN")
	)
	(segment
		(start 457.63688 -2.816352)
		(end 457.63688 -3.441954)
		(width 0.1143)
		(layer "In2.Cu")
		(net "CLK_100M_PCH_SLOTX24_S1_DN")
	)
	(segment
		(start 411.073854 -16.72844)
		(end 407.491692 -17.907508)
		(width 0.1143)
		(layer "In2.Cu")
		(net "CLK_100M_PCH_SLOTX24_S1_DN")
	)
	(segment
		(start 365.710216 -99.06889)
		(end 366.159288 -101.186488)
		(width 0.1143)
		(layer "In2.Cu")
		(net "CLK_100M_PCH_SLOTX24_S1_DN")
	)
	(segment
		(start 365.087408 -91.647772)
		(end 366.150906 -94.941136)
		(width 0.1143)
		(layer "In2.Cu")
		(net "CLK_100M_PCH_SLOTX24_S1_DN")
	)
	(segment
		(start 369.422172 -109.008164)
		(end 369.422172 -109.567726)
		(width 0.1143)
		(layer "In2.Cu")
		(net "CLK_100M_PCH_SLOTX24_S1_DN")
	)
	(segment
		(start 366.150906 -94.941136)
		(end 366.15116 -94.941136)
		(width 0.1143)
		(layer "In2.Cu")
		(net "CLK_100M_PCH_SLOTX24_S1_DN")
	)
	(segment
		(start 407.491692 -17.907508)
		(end 403.562058 -17.03832)
		(width 0.1143)
		(layer "In2.Cu")
		(net "CLK_100M_PCH_SLOTX24_S1_DN")
	)
	(segment
		(start 397.022828 -17.424908)
		(end 396.019274 -17.224248)
		(width 0.1143)
		(layer "In2.Cu")
		(net "CLK_100M_PCH_SLOTX24_S1_DN")
	)
	(segment
		(start 367.055146 -55.14975)
		(end 366.968532 -55.58282)
		(width 0.1143)
		(layer "In2.Cu")
		(net "CLK_100M_PCH_SLOTX24_S1_DN")
	)
	(segment
		(start 369.72875 -110.296706)
		(end 371.009418 -110.9853)
		(width 0.1143)
		(layer "In2.Cu")
		(net "CLK_100M_PCH_SLOTX24_S1_DN")
	)
	(segment
		(start 452.823834 -7.29361)
		(end 450.059044 -7.846822)
		(width 0.1143)
		(layer "In2.Cu")
		(net "CLK_100M_PCH_SLOTX24_S1_DN")
	)
	(segment
		(start 366.958372 -46.619668)
		(end 367.037874 -46.861476)
		(width 0.1143)
		(layer "In2.Cu")
		(net "CLK_100M_PCH_SLOTX24_S1_DN")
	)
	(segment
		(start 371.009418 -110.9853)
		(end 373.96928 -110.9853)
		(width 0.1143)
		(layer "In2.Cu")
		(net "CLK_100M_PCH_SLOTX24_S1_DN")
	)
	(segment
		(start 433.375562 -12.637516)
		(end 432.753516 -13.04925)
		(width 0.1143)
		(layer "In2.Cu")
		(net "CLK_100M_PCH_SLOTX24_S1_DN")
	)
	(segment
		(start 363.100112 -83.335114)
		(end 362.254038 -87.567008)
		(width 0.1143)
		(layer "In2.Cu")
		(net "CLK_100M_PCH_SLOTX24_S1_DN")
	)
	(segment
		(start 373.96928 -110.9853)
		(end 374.103646 -111.119666)
		(width 0.1143)
		(layer "In2.Cu")
		(net "CLK_100M_PCH_SLOTX24_S1_DN")
	)
	(segment
		(start 376.809254 -113.031778)
		(end 376.992896 -113.196878)
		(width 0.0889)
		(layer "In2.Cu")
		(net "CLK_100M_PCH_SLOTX24_S1_DN")
	)
	(segment
		(start 376.030998 -112.975644)
		(end 376.602498 -112.975644)
		(width 0.0889)
		(layer "In2.Cu")
		(net "CLK_100M_PCH_SLOTX24_S1_DN")
	)
	(segment
		(start 367.3983 -103.27259)
		(end 368.60988 -104.793288)
		(width 0.1143)
		(layer "In2.Cu")
		(net "CLK_100M_PCH_SLOTX24_S1_DN")
	)
	(segment
		(start 369.602766 -36.904422)
		(end 369.090194 -38.775132)
		(width 0.1143)
		(layer "In2.Cu")
		(net "CLK_100M_PCH_SLOTX24_S1_DN")
	)
	(segment
		(start 375.235724 -22.54758)
		(end 370.684552 -28.635198)
		(width 0.1143)
		(layer "In2.Cu")
		(net "CLK_100M_PCH_SLOTX24_S1_DN")
	)
	(segment
		(start 380.304548 -19.005042)
		(end 375.235724 -22.54758)
		(width 0.1143)
		(layer "In2.Cu")
		(net "CLK_100M_PCH_SLOTX24_S1_DN")
	)
	(segment
		(start 448.207384 -9.080754)
		(end 447.303652 -10.418826)
		(width 0.1143)
		(layer "In2.Cu")
		(net "CLK_100M_PCH_SLOTX24_S1_DN")
	)
	(segment
		(start 453.028812 -7.17423)
		(end 452.823834 -7.29361)
		(width 0.1143)
		(layer "In2.Cu")
		(net "CLK_100M_PCH_SLOTX24_S1_DN")
	)
	(segment
		(start 366.070896 -97.35947)
		(end 365.710216 -99.06889)
		(width 0.1143)
		(layer "In2.Cu")
		(net "CLK_100M_PCH_SLOTX24_S1_DN")
	)
	(segment
		(start 400.49704 -18.444464)
		(end 400.115532 -18.521934)
		(width 0.1143)
		(layer "In2.Cu")
		(net "CLK_100M_PCH_SLOTX24_S1_DN")
	)
	(segment
		(start 412.621222 -17.07896)
		(end 412.620968 -17.079214)
		(width 0.1143)
		(layer "In2.Cu")
		(net "CLK_100M_PCH_SLOTX24_S1_DN")
	)
	(segment
		(start 370.684552 -28.635198)
		(end 369.21313 -35.557206)
		(width 0.1143)
		(layer "In2.Cu")
		(net "CLK_100M_PCH_SLOTX24_S1_DN")
	)
	(segment
		(start 366.968532 -55.58282)
		(end 363.586776 -60.654184)
		(width 0.1143)
		(layer "In2.Cu")
		(net "CLK_100M_PCH_SLOTX24_S1_DN")
	)
	(segment
		(start 398.100296 -18.111978)
		(end 397.558768 -17.753838)
		(width 0.1143)
		(layer "In2.Cu")
		(net "CLK_100M_PCH_SLOTX24_S1_DN")
	)
	(segment
		(start 363.586776 -60.654184)
		(end 362.552996 -65.534794)
		(width 0.1143)
		(layer "In2.Cu")
		(net "CLK_100M_PCH_SLOTX24_S1_DN")
	)
	(segment
		(start 457.063348 -2.24282)
		(end 457.63688 -2.816352)
		(width 0.1143)
		(layer "In2.Cu")
		(net "CLK_100M_PCH_SLOTX24_S1_DN")
	)
	(segment
		(start 397.083788 -17.424908)
		(end 397.022828 -17.424908)
		(width 0.1143)
		(layer "In2.Cu")
		(net "CLK_100M_PCH_SLOTX24_S1_DN")
	)
	(segment
		(start 443.415166 -11.067288)
		(end 441.73521 -11.424412)
		(width 0.1143)
		(layer "In2.Cu")
		(net "CLK_100M_PCH_SLOTX24_S1_DN")
	)
	(segment
		(start 396.019274 -17.224248)
		(end 392.308842 -17.96669)
		(width 0.1143)
		(layer "In2.Cu")
		(net "CLK_100M_PCH_SLOTX24_S1_DN")
	)
	(segment
		(start 427.205394 -13.757148)
		(end 426.612558 -14.349984)
		(width 0.1143)
		(layer "In2.Cu")
		(net "CLK_100M_PCH_SLOTX24_S1_DN")
	)
	(segment
		(start 369.21313 -35.557206)
		(end 369.602766 -36.904422)
		(width 0.1143)
		(layer "In2.Cu")
		(net "CLK_100M_PCH_SLOTX24_S1_DN")
	)
	(segment
		(start 441.73521 -11.424412)
		(end 440.38266 -12.332716)
		(width 0.1143)
		(layer "In2.Cu")
		(net "CLK_100M_PCH_SLOTX24_S1_DN")
	)
	(segment
		(start 429.569626 -13.697204)
		(end 428.568866 -13.493496)
		(width 0.1143)
		(layer "In2.Cu")
		(net "CLK_100M_PCH_SLOTX24_S1_DN")
	)
	(segment
		(start 446.276476 -11.104118)
		(end 444.897002 -11.379708)
		(width 0.1143)
		(layer "In2.Cu")
		(net "CLK_100M_PCH_SLOTX24_S1_DN")
	)
	(segment
		(start 450.059044 -7.846822)
		(end 448.207384 -9.080754)
		(width 0.1143)
		(layer "In2.Cu")
		(net "CLK_100M_PCH_SLOTX24_S1_DN")
	)
	(segment
		(start 362.759752 -90.096086)
		(end 365.087408 -91.647772)
		(width 0.1143)
		(layer "In2.Cu")
		(net "CLK_100M_PCH_SLOTX24_S1_DN")
	)
	(segment
		(start 444.897002 -11.379708)
		(end 443.415166 -11.067288)
		(width 0.1143)
		(layer "In2.Cu")
		(net "CLK_100M_PCH_SLOTX24_S1_DN")
	)
	(segment
		(start 428.568866 -13.493496)
		(end 427.274482 -13.757148)
		(width 0.1143)
		(layer "In2.Cu")
		(net "CLK_100M_PCH_SLOTX24_S1_DN")
	)
	(segment
		(start 368.221768 -39.665402)
		(end 366.958372 -46.619668)
		(width 0.1143)
		(layer "In2.Cu")
		(net "CLK_100M_PCH_SLOTX24_S1_DN")
	)
	(segment
		(start 427.274482 -13.757148)
		(end 427.205394 -13.757148)
		(width 0.1143)
		(layer "In2.Cu")
		(net "CLK_100M_PCH_SLOTX24_S1_DN")
	)
	(segment
		(start 362.4961 -80.377284)
		(end 363.100112 -83.335114)
		(width 0.1143)
		(layer "In2.Cu")
		(net "CLK_100M_PCH_SLOTX24_S1_DN")
	)
	(segment
		(start 362.4961 -76.974954)
		(end 362.4961 -80.377284)
		(width 0.1143)
		(layer "In2.Cu")
		(net "CLK_100M_PCH_SLOTX24_S1_DN")
	)
	(segment
		(start 374.190768 -111.13516)
		(end 376.030998 -112.975644)
		(width 0.0889)
		(layer "In2.Cu")
		(net "CLK_100M_PCH_SLOTX24_S1_DN")
	)
	(segment
		(start 397.558768 -17.753838)
		(end 397.126968 -17.468088)
		(width 0.1143)
		(layer "In2.Cu")
		(net "CLK_100M_PCH_SLOTX24_S1_DN")
	)
	(segment
		(start 369.422172 -109.567726)
		(end 369.52682 -110.030768)
		(width 0.1143)
		(layer "In2.Cu")
		(net "CLK_100M_PCH_SLOTX24_S1_DN")
	)
	(segment
		(start 400.115532 -18.521934)
		(end 398.100296 -18.111978)
		(width 0.1143)
		(layer "In2.Cu")
		(net "CLK_100M_PCH_SLOTX24_S1_DN")
	)
	(segment
		(start 434.824124 -12.342622)
		(end 433.375562 -12.637516)
		(width 0.1143)
		(layer "In2.Cu")
		(net "CLK_100M_PCH_SLOTX24_S1_DN")
	)
	(segment
		(start 397.126968 -17.468088)
		(end 397.083788 -17.424908)
		(width 0.1143)
		(layer "In2.Cu")
		(net "CLK_100M_PCH_SLOTX24_S1_DN")
	)
	(segment
		(start 424.643804 -14.750034)
		(end 424.098974 -14.641576)
		(width 0.1143)
		(layer "In2.Cu")
		(net "CLK_100M_PCH_SLOTX24_S1_DN")
	)
	(segment
		(start 438.8104 -12.072874)
		(end 435.99354 -12.580874)
		(width 0.1143)
		(layer "In2.Cu")
		(net "CLK_100M_PCH_SLOTX24_S1_DN")
	)
	(segment
		(start 367.3983 -102.4255)
		(end 367.3983 -103.27259)
		(width 0.1143)
		(layer "In2.Cu")
		(net "CLK_100M_PCH_SLOTX24_S1_DN")
	)
	(segment
		(start 440.091068 -12.332716)
		(end 438.868566 -12.072874)
		(width 0.1143)
		(layer "In2.Cu")
		(net "CLK_100M_PCH_SLOTX24_S1_DN")
	)
	(segment
		(start 432.753516 -13.04925)
		(end 429.569626 -13.697204)
		(width 0.1143)
		(layer "In2.Cu")
		(net "CLK_100M_PCH_SLOTX24_S1_DN")
	)
	(segment
		(start 457.63688 -3.441954)
		(end 457.136246 -3.942588)
		(width 0.1143)
		(layer "In2.Cu")
		(net "CLK_100M_PCH_SLOTX24_S1_DN")
	)
	(segment
		(start 435.99354 -12.580874)
		(end 434.824124 -12.342622)
		(width 0.1143)
		(layer "In2.Cu")
		(net "CLK_100M_PCH_SLOTX24_S1_DN")
	)
	(segment
		(start 360.72953 -68.635118)
		(end 362.4961 -76.974954)
		(width 0.1143)
		(layer "In2.Cu")
		(net "CLK_100M_PCH_SLOTX24_S1_DN")
	)
	(arc
		(start 378.837698 -112.957864)
		(mid 379.040409 -112.74948)
		(end 379.31725 -112.660684)
		(width 0.0889)
		(layer "In2.Cu")
		(net "CLK_100M_PCH_SLOTX24_S1_DN")
	)
	(arc
		(start 376.992896 -113.196878)
		(mid 377.301407 -113.259831)
		(end 377.600718 -113.16208)
		(width 0.0889)
		(layer "In2.Cu")
		(net "CLK_100M_PCH_SLOTX24_S1_DN")
	)
	(arc
		(start 376.602498 -112.975644)
		(mid 376.709616 -112.989932)
		(end 376.809254 -113.031778)
		(width 0.0889)
		(layer "In2.Cu")
		(net "CLK_100M_PCH_SLOTX24_S1_DN")
	)
	(arc
		(start 377.600718 -113.16208)
		(mid 377.748076 -113.102408)
		(end 377.907042 -113.10112)
		(width 0.0889)
		(layer "In2.Cu")
		(net "CLK_100M_PCH_SLOTX24_S1_DN")
	)
	(arc
		(start 378.031248 -113.172494)
		(mid 378.478865 -113.231884)
		(end 378.837698 -112.957864)
		(width 0.0889)
		(layer "In2.Cu")
		(net "CLK_100M_PCH_SLOTX24_S1_DN")
	)
	(segment
		(start 467.58225 -118.56212)
		(end 467.58225 -118.908322)
		(width 0.127)
		(layer "F.Cu")
		(net "CLK_100M_MEZZ2_DP")
	)
	(segment
		(start 467.800944 -116.993162)
		(end 467.800944 -118.343426)
		(width 0.127)
		(layer "F.Cu")
		(net "CLK_100M_MEZZ2_DP")
	)
	(segment
		(start 467.58225 -118.908322)
		(end 467.705948 -119.03202)
		(width 0.127)
		(layer "F.Cu")
		(net "CLK_100M_MEZZ2_DP")
	)
	(segment
		(start 377.33605 -104.70388)
		(end 377.83135 -104.473756)
		(width 0.127)
		(layer "F.Cu")
		(net "CLK_100M_MEZZ2_DP")
	)
	(segment
		(start 467.705948 -119.03202)
		(end 468.085678 -119.03202)
		(width 0.127)
		(layer "F.Cu")
		(net "CLK_100M_MEZZ2_DP")
	)
	(segment
		(start 467.800944 -118.343426)
		(end 467.58225 -118.56212)
		(width 0.127)
		(layer "F.Cu")
		(net "CLK_100M_MEZZ2_DP")
	)
	(via
		(at 468.085678 -119.03202)
		(size 0.508)
		(drill 0.254)
		(layers "F.Cu" "B.Cu")
		(net "CLK_100M_MEZZ2_DP")
	)
	(via
		(at 377.83135 -104.473756)
		(size 0.508)
		(drill 0.254)
		(layers "F.Cu" "B.Cu")
		(net "CLK_100M_MEZZ2_DP")
	)
	(segment
		(start 463.203544 -118.09349)
		(end 462.943702 -117.833648)
		(width 0.1143)
		(layer "In11.Cu")
		(net "CLK_100M_MEZZ2_DP")
	)
	(segment
		(start 445.267588 -116.103146)
		(end 444.601346 -116.103146)
		(width 0.1143)
		(layer "In11.Cu")
		(net "CLK_100M_MEZZ2_DP")
	)
	(segment
		(start 400.416776 -132.249672)
		(end 397.423132 -132.249672)
		(width 0.1143)
		(layer "In11.Cu")
		(net "CLK_100M_MEZZ2_DP")
	)
	(segment
		(start 470.06002 -120.883426)
		(end 470.06002 -122.69851)
		(width 0.1143)
		(layer "In11.Cu")
		(net "CLK_100M_MEZZ2_DP")
	)
	(segment
		(start 468.766652 -119.590058)
		(end 470.06002 -120.883426)
		(width 0.1143)
		(layer "In11.Cu")
		(net "CLK_100M_MEZZ2_DP")
	)
	(segment
		(start 386.519928 -126.344426)
		(end 384.765042 -124.58954)
		(width 0.1143)
		(layer "In11.Cu")
		(net "CLK_100M_MEZZ2_DP")
	)
	(segment
		(start 456.40752 -116.103654)
		(end 455.740262 -116.103654)
		(width 0.1143)
		(layer "In11.Cu")
		(net "CLK_100M_MEZZ2_DP")
	)
	(segment
		(start 464.696302 -118.279164)
		(end 465.095844 -117.879622)
		(width 0.1143)
		(layer "In11.Cu")
		(net "CLK_100M_MEZZ2_DP")
	)
	(segment
		(start 376.945398 -105.761536)
		(end 377.688094 -105.01884)
		(width 0.0889)
		(layer "In11.Cu")
		(net "CLK_100M_MEZZ2_DP")
	)
	(segment
		(start 465.769452 -117.119654)
		(end 464.562952 -117.119654)
		(width 0.1143)
		(layer "In11.Cu")
		(net "CLK_100M_MEZZ2_DP")
	)
	(segment
		(start 457.01204 -116.708174)
		(end 456.40752 -116.103654)
		(width 0.1143)
		(layer "In11.Cu")
		(net "CLK_100M_MEZZ2_DP")
	)
	(segment
		(start 442.482732 -116.103146)
		(end 441.776866 -116.103146)
		(width 0.1143)
		(layer "In11.Cu")
		(net "CLK_100M_MEZZ2_DP")
	)
	(segment
		(start 423.6212 -121.0056)
		(end 422.3131 -122.3137)
		(width 0.1143)
		(layer "In11.Cu")
		(net "CLK_100M_MEZZ2_DP")
	)
	(segment
		(start 391.115804 -133.035802)
		(end 386.752846 -128.672844)
		(width 0.1143)
		(layer "In11.Cu")
		(net "CLK_100M_MEZZ2_DP")
	)
	(segment
		(start 448.052952 -116.103654)
		(end 447.385694 -116.103654)
		(width 0.1143)
		(layer "In11.Cu")
		(net "CLK_100M_MEZZ2_DP")
	)
	(segment
		(start 466.98662 -116.52377)
		(end 466.71992 -116.25707)
		(width 0.1143)
		(layer "In11.Cu")
		(net "CLK_100M_MEZZ2_DP")
	)
	(segment
		(start 375.772172 -105.710736)
		(end 376.145298 -105.710736)
		(width 0.1143)
		(layer "In11.Cu")
		(net "CLK_100M_MEZZ2_DP")
	)
	(segment
		(start 464.562952 -117.119654)
		(end 464.150202 -117.532404)
		(width 0.1143)
		(layer "In11.Cu")
		(net "CLK_100M_MEZZ2_DP")
	)
	(segment
		(start 441.310268 -117.752368)
		(end 440.946032 -118.116604)
		(width 0.1143)
		(layer "In11.Cu")
		(net "CLK_100M_MEZZ2_DP")
	)
	(segment
		(start 416.098482 -126.98095)
		(end 415.439606 -127.639826)
		(width 0.1143)
		(layer "In11.Cu")
		(net "CLK_100M_MEZZ2_DP")
	)
	(segment
		(start 397.423132 -132.249672)
		(end 396.637002 -133.035802)
		(width 0.1143)
		(layer "In11.Cu")
		(net "CLK_100M_MEZZ2_DP")
	)
	(segment
		(start 422.3131 -125.109478)
		(end 420.441628 -126.98095)
		(width 0.1143)
		(layer "In11.Cu")
		(net "CLK_100M_MEZZ2_DP")
	)
	(segment
		(start 467.711028 -119.03202)
		(end 467.596728 -119.14632)
		(width 0.1143)
		(layer "In11.Cu")
		(net "CLK_100M_MEZZ2_DP")
	)
	(segment
		(start 451.442328 -116.708174)
		(end 450.837808 -116.103654)
		(width 0.1143)
		(layer "In11.Cu")
		(net "CLK_100M_MEZZ2_DP")
	)
	(segment
		(start 426.017182 -121.0056)
		(end 423.6212 -121.0056)
		(width 0.1143)
		(layer "In11.Cu")
		(net "CLK_100M_MEZZ2_DP")
	)
	(segment
		(start 376.218196 -105.761536)
		(end 376.945398 -105.761536)
		(width 0.0889)
		(layer "In11.Cu")
		(net "CLK_100M_MEZZ2_DP")
	)
	(segment
		(start 452.350886 -116.708174)
		(end 451.442328 -116.708174)
		(width 0.1143)
		(layer "In11.Cu")
		(net "CLK_100M_MEZZ2_DP")
	)
	(segment
		(start 464.696302 -119.118888)
		(end 464.696302 -118.279164)
		(width 0.1143)
		(layer "In11.Cu")
		(net "CLK_100M_MEZZ2_DP")
	)
	(segment
		(start 413.6771 -127.639826)
		(end 412.932626 -128.3843)
		(width 0.1143)
		(layer "In11.Cu")
		(net "CLK_100M_MEZZ2_DP")
	)
	(segment
		(start 441.776866 -116.103146)
		(end 441.310268 -116.569744)
		(width 0.1143)
		(layer "In11.Cu")
		(net "CLK_100M_MEZZ2_DP")
	)
	(segment
		(start 412.932626 -128.3843)
		(end 404.282148 -128.3843)
		(width 0.1143)
		(layer "In11.Cu")
		(net "CLK_100M_MEZZ2_DP")
	)
	(segment
		(start 396.637002 -133.035802)
		(end 391.115804 -133.035802)
		(width 0.1143)
		(layer "In11.Cu")
		(net "CLK_100M_MEZZ2_DP")
	)
	(segment
		(start 435.027324 -120.827292)
		(end 427.790356 -120.827292)
		(width 0.1143)
		(layer "In11.Cu")
		(net "CLK_100M_MEZZ2_DP")
	)
	(segment
		(start 466.321394 -116.25707)
		(end 466.054694 -116.52377)
		(width 0.1143)
		(layer "In11.Cu")
		(net "CLK_100M_MEZZ2_DP")
	)
	(segment
		(start 463.89036 -118.09349)
		(end 463.203544 -118.09349)
		(width 0.1143)
		(layer "In11.Cu")
		(net "CLK_100M_MEZZ2_DP")
	)
	(segment
		(start 464.150202 -117.532404)
		(end 464.150202 -117.833648)
		(width 0.1143)
		(layer "In11.Cu")
		(net "CLK_100M_MEZZ2_DP")
	)
	(segment
		(start 379.755908 -125.114812)
		(end 377.188222 -125.114812)
		(width 0.1143)
		(layer "In11.Cu")
		(net "CLK_100M_MEZZ2_DP")
	)
	(segment
		(start 427.315376 -121.302272)
		(end 426.313854 -121.302272)
		(width 0.1143)
		(layer "In11.Cu")
		(net "CLK_100M_MEZZ2_DP")
	)
	(segment
		(start 420.441628 -126.98095)
		(end 416.098482 -126.98095)
		(width 0.1143)
		(layer "In11.Cu")
		(net "CLK_100M_MEZZ2_DP")
	)
	(segment
		(start 450.17055 -116.103654)
		(end 449.56603 -116.708174)
		(width 0.1143)
		(layer "In11.Cu")
		(net "CLK_100M_MEZZ2_DP")
	)
	(segment
		(start 380.28118 -124.58954)
		(end 379.755908 -125.114812)
		(width 0.1143)
		(layer "In11.Cu")
		(net "CLK_100M_MEZZ2_DP")
	)
	(segment
		(start 461.590644 -116.103654)
		(end 458.525118 -116.103654)
		(width 0.1143)
		(layer "In11.Cu")
		(net "CLK_100M_MEZZ2_DP")
	)
	(segment
		(start 443.08776 -116.708174)
		(end 442.482732 -116.103146)
		(width 0.1143)
		(layer "In11.Cu")
		(net "CLK_100M_MEZZ2_DP")
	)
	(segment
		(start 375.685304 -123.611894)
		(end 375.685304 -108.614972)
		(width 0.1143)
		(layer "In11.Cu")
		(net "CLK_100M_MEZZ2_DP")
	)
	(segment
		(start 386.752846 -128.0668)
		(end 386.519928 -127.833882)
		(width 0.1143)
		(layer "In11.Cu")
		(net "CLK_100M_MEZZ2_DP")
	)
	(segment
		(start 468.085678 -119.03202)
		(end 467.711028 -119.03202)
		(width 0.1143)
		(layer "In11.Cu")
		(net "CLK_100M_MEZZ2_DP")
	)
	(segment
		(start 376.167396 -105.710736)
		(end 376.218196 -105.761536)
		(width 0.0889)
		(layer "In11.Cu")
		(net "CLK_100M_MEZZ2_DP")
	)
	(segment
		(start 458.525118 -116.103654)
		(end 457.920598 -116.708174)
		(width 0.1143)
		(layer "In11.Cu")
		(net "CLK_100M_MEZZ2_DP")
	)
	(segment
		(start 457.920598 -116.708174)
		(end 457.01204 -116.708174)
		(width 0.1143)
		(layer "In11.Cu")
		(net "CLK_100M_MEZZ2_DP")
	)
	(segment
		(start 386.519928 -127.833882)
		(end 386.519928 -126.344426)
		(width 0.1143)
		(layer "In11.Cu")
		(net "CLK_100M_MEZZ2_DP")
	)
	(segment
		(start 467.596728 -119.14632)
		(end 467.596728 -119.308118)
		(width 0.1143)
		(layer "In11.Cu")
		(net "CLK_100M_MEZZ2_DP")
	)
	(segment
		(start 377.688094 -105.01884)
		(end 378.031248 -104.820466)
		(width 0.0889)
		(layer "In11.Cu")
		(net "CLK_100M_MEZZ2_DP")
	)
	(segment
		(start 466.054694 -116.834412)
		(end 465.769452 -117.119654)
		(width 0.1143)
		(layer "In11.Cu")
		(net "CLK_100M_MEZZ2_DP")
	)
	(segment
		(start 468.535766 -122.958352)
		(end 464.696302 -119.118888)
		(width 0.1143)
		(layer "In11.Cu")
		(net "CLK_100M_MEZZ2_DP")
	)
	(segment
		(start 452.955406 -116.103654)
		(end 452.350886 -116.708174)
		(width 0.1143)
		(layer "In11.Cu")
		(net "CLK_100M_MEZZ2_DP")
	)
	(segment
		(start 443.996318 -116.708174)
		(end 443.08776 -116.708174)
		(width 0.1143)
		(layer "In11.Cu")
		(net "CLK_100M_MEZZ2_DP")
	)
	(segment
		(start 466.71992 -116.25707)
		(end 466.321394 -116.25707)
		(width 0.1143)
		(layer "In11.Cu")
		(net "CLK_100M_MEZZ2_DP")
	)
	(segment
		(start 445.872616 -116.708174)
		(end 445.267588 -116.103146)
		(width 0.1143)
		(layer "In11.Cu")
		(net "CLK_100M_MEZZ2_DP")
	)
	(segment
		(start 426.313854 -121.302272)
		(end 426.017182 -121.0056)
		(width 0.1143)
		(layer "In11.Cu")
		(net "CLK_100M_MEZZ2_DP")
	)
	(segment
		(start 386.752846 -128.672844)
		(end 386.752846 -128.0668)
		(width 0.1143)
		(layer "In11.Cu")
		(net "CLK_100M_MEZZ2_DP")
	)
	(segment
		(start 464.150202 -117.833648)
		(end 463.89036 -118.09349)
		(width 0.1143)
		(layer "In11.Cu")
		(net "CLK_100M_MEZZ2_DP")
	)
	(segment
		(start 437.738012 -118.116604)
		(end 435.027324 -120.827292)
		(width 0.1143)
		(layer "In11.Cu")
		(net "CLK_100M_MEZZ2_DP")
	)
	(segment
		(start 404.282148 -128.3843)
		(end 400.416776 -132.249672)
		(width 0.1143)
		(layer "In11.Cu")
		(net "CLK_100M_MEZZ2_DP")
	)
	(segment
		(start 446.781174 -116.708174)
		(end 445.872616 -116.708174)
		(width 0.1143)
		(layer "In11.Cu")
		(net "CLK_100M_MEZZ2_DP")
	)
	(segment
		(start 462.943702 -117.833648)
		(end 462.943702 -117.456712)
		(width 0.1143)
		(layer "In11.Cu")
		(net "CLK_100M_MEZZ2_DP")
	)
	(segment
		(start 470.06002 -122.69851)
		(end 469.800178 -122.958352)
		(width 0.1143)
		(layer "In11.Cu")
		(net "CLK_100M_MEZZ2_DP")
	)
	(segment
		(start 447.385694 -116.103654)
		(end 446.781174 -116.708174)
		(width 0.1143)
		(layer "In11.Cu")
		(net "CLK_100M_MEZZ2_DP")
	)
	(segment
		(start 453.622664 -116.103654)
		(end 452.955406 -116.103654)
		(width 0.1143)
		(layer "In11.Cu")
		(net "CLK_100M_MEZZ2_DP")
	)
	(segment
		(start 469.800178 -122.958352)
		(end 468.535766 -122.958352)
		(width 0.1143)
		(layer "In11.Cu")
		(net "CLK_100M_MEZZ2_DP")
	)
	(segment
		(start 375.470166 -108.399834)
		(end 375.470166 -106.012742)
		(width 0.1143)
		(layer "In11.Cu")
		(net "CLK_100M_MEZZ2_DP")
	)
	(segment
		(start 467.596728 -119.308118)
		(end 467.878668 -119.590058)
		(width 0.1143)
		(layer "In11.Cu")
		(net "CLK_100M_MEZZ2_DP")
	)
	(segment
		(start 454.227184 -116.708174)
		(end 453.622664 -116.103654)
		(width 0.1143)
		(layer "In11.Cu")
		(net "CLK_100M_MEZZ2_DP")
	)
	(segment
		(start 448.657472 -116.708174)
		(end 448.052952 -116.103654)
		(width 0.1143)
		(layer "In11.Cu")
		(net "CLK_100M_MEZZ2_DP")
	)
	(segment
		(start 377.188222 -125.114812)
		(end 375.685304 -123.611894)
		(width 0.1143)
		(layer "In11.Cu")
		(net "CLK_100M_MEZZ2_DP")
	)
	(segment
		(start 427.790356 -120.827292)
		(end 427.315376 -121.302272)
		(width 0.1143)
		(layer "In11.Cu")
		(net "CLK_100M_MEZZ2_DP")
	)
	(segment
		(start 462.943702 -117.456712)
		(end 461.590644 -116.103654)
		(width 0.1143)
		(layer "In11.Cu")
		(net "CLK_100M_MEZZ2_DP")
	)
	(segment
		(start 444.601346 -116.103146)
		(end 443.996318 -116.708174)
		(width 0.1143)
		(layer "In11.Cu")
		(net "CLK_100M_MEZZ2_DP")
	)
	(segment
		(start 455.135742 -116.708174)
		(end 454.227184 -116.708174)
		(width 0.1143)
		(layer "In11.Cu")
		(net "CLK_100M_MEZZ2_DP")
	)
	(segment
		(start 455.740262 -116.103654)
		(end 455.135742 -116.708174)
		(width 0.1143)
		(layer "In11.Cu")
		(net "CLK_100M_MEZZ2_DP")
	)
	(segment
		(start 415.439606 -127.639826)
		(end 413.6771 -127.639826)
		(width 0.1143)
		(layer "In11.Cu")
		(net "CLK_100M_MEZZ2_DP")
	)
	(segment
		(start 375.470166 -106.012742)
		(end 375.772172 -105.710736)
		(width 0.1143)
		(layer "In11.Cu")
		(net "CLK_100M_MEZZ2_DP")
	)
	(segment
		(start 466.98662 -117.291866)
		(end 466.98662 -116.52377)
		(width 0.1143)
		(layer "In11.Cu")
		(net "CLK_100M_MEZZ2_DP")
	)
	(segment
		(start 441.310268 -116.569744)
		(end 441.310268 -117.752368)
		(width 0.1143)
		(layer "In11.Cu")
		(net "CLK_100M_MEZZ2_DP")
	)
	(segment
		(start 440.946032 -118.116604)
		(end 437.738012 -118.116604)
		(width 0.1143)
		(layer "In11.Cu")
		(net "CLK_100M_MEZZ2_DP")
	)
	(segment
		(start 384.765042 -124.58954)
		(end 380.28118 -124.58954)
		(width 0.1143)
		(layer "In11.Cu")
		(net "CLK_100M_MEZZ2_DP")
	)
	(segment
		(start 466.054694 -116.52377)
		(end 466.054694 -116.834412)
		(width 0.1143)
		(layer "In11.Cu")
		(net "CLK_100M_MEZZ2_DP")
	)
	(segment
		(start 467.878668 -119.590058)
		(end 468.766652 -119.590058)
		(width 0.1143)
		(layer "In11.Cu")
		(net "CLK_100M_MEZZ2_DP")
	)
	(segment
		(start 449.56603 -116.708174)
		(end 448.657472 -116.708174)
		(width 0.1143)
		(layer "In11.Cu")
		(net "CLK_100M_MEZZ2_DP")
	)
	(segment
		(start 450.837808 -116.103654)
		(end 450.17055 -116.103654)
		(width 0.1143)
		(layer "In11.Cu")
		(net "CLK_100M_MEZZ2_DP")
	)
	(segment
		(start 422.3131 -122.3137)
		(end 422.3131 -125.109478)
		(width 0.1143)
		(layer "In11.Cu")
		(net "CLK_100M_MEZZ2_DP")
	)
	(segment
		(start 375.685304 -108.614972)
		(end 375.470166 -108.399834)
		(width 0.1143)
		(layer "In11.Cu")
		(net "CLK_100M_MEZZ2_DP")
	)
	(segment
		(start 376.145298 -105.710736)
		(end 376.167396 -105.710736)
		(width 0.0889)
		(layer "In11.Cu")
		(net "CLK_100M_MEZZ2_DP")
	)
	(segment
		(start 465.095844 -117.879622)
		(end 466.398864 -117.879622)
		(width 0.1143)
		(layer "In11.Cu")
		(net "CLK_100M_MEZZ2_DP")
	)
	(segment
		(start 466.398864 -117.879622)
		(end 466.98662 -117.291866)
		(width 0.1143)
		(layer "In11.Cu")
		(net "CLK_100M_MEZZ2_DP")
	)
	(arc
		(start 378.227336 -104.531668)
		(mid 378.058408 -104.304843)
		(end 377.83135 -104.473756)
		(width 0.0889)
		(layer "In11.Cu")
		(net "CLK_100M_MEZZ2_DP")
	)
	(arc
		(start 378.031248 -104.820466)
		(mid 378.162444 -104.698575)
		(end 378.227336 -104.531668)
		(width 0.0889)
		(layer "In11.Cu")
		(net "CLK_100M_MEZZ2_DP")
	)
	(segment
		(start 467.27745 -118.578884)
		(end 467.27745 -118.928642)
		(width 0.127)
		(layer "F.Cu")
		(net "CLK_100M_MEZZ2_DN")
	)
	(segment
		(start 467.174072 -119.03202)
		(end 466.815678 -119.03202)
		(width 0.127)
		(layer "F.Cu")
		(net "CLK_100M_MEZZ2_DN")
	)
	(segment
		(start 466.999828 -116.994178)
		(end 466.999828 -118.301262)
		(width 0.127)
		(layer "F.Cu")
		(net "CLK_100M_MEZZ2_DN")
	)
	(segment
		(start 466.999828 -118.301262)
		(end 467.27745 -118.578884)
		(width 0.127)
		(layer "F.Cu")
		(net "CLK_100M_MEZZ2_DN")
	)
	(segment
		(start 467.27745 -118.928642)
		(end 467.174072 -119.03202)
		(width 0.127)
		(layer "F.Cu")
		(net "CLK_100M_MEZZ2_DN")
	)
	(segment
		(start 467.000844 -116.993162)
		(end 466.999828 -116.994178)
		(width 0.127)
		(layer "F.Cu")
		(net "CLK_100M_MEZZ2_DN")
	)
	(segment
		(start 378.32665 -104.70388)
		(end 378.82195 -104.473756)
		(width 0.127)
		(layer "F.Cu")
		(net "CLK_100M_MEZZ2_DN")
	)
	(via
		(at 466.815678 -119.03202)
		(size 0.508)
		(drill 0.254)
		(layers "F.Cu" "B.Cu")
		(net "CLK_100M_MEZZ2_DN")
	)
	(via
		(at 378.82195 -104.473756)
		(size 0.508)
		(drill 0.254)
		(layers "F.Cu" "B.Cu")
		(net "CLK_100M_MEZZ2_DN")
	)
	(segment
		(start 377.30938 -124.822712)
		(end 375.977404 -123.490736)
		(width 0.1143)
		(layer "In11.Cu")
		(net "CLK_100M_MEZZ2_DN")
	)
	(segment
		(start 422.021 -123.97232)
		(end 421.8559 -124.13742)
		(width 0.1143)
		(layer "In11.Cu")
		(net "CLK_100M_MEZZ2_DN")
	)
	(segment
		(start 466.815678 -119.03202)
		(end 467.190328 -119.03202)
		(width 0.1143)
		(layer "In11.Cu")
		(net "CLK_100M_MEZZ2_DN")
	)
	(segment
		(start 417.241228 -126.52375)
		(end 416.898328 -126.52375)
		(width 0.1143)
		(layer "In11.Cu")
		(net "CLK_100M_MEZZ2_DN")
	)
	(segment
		(start 468.888064 -120.358154)
		(end 469.13038 -120.60047)
		(width 0.1143)
		(layer "In11.Cu")
		(net "CLK_100M_MEZZ2_DN")
	)
	(segment
		(start 421.038782 -125.970538)
		(end 420.805356 -125.970538)
		(width 0.1143)
		(layer "In11.Cu")
		(net "CLK_100M_MEZZ2_DN")
	)
	(segment
		(start 387.044946 -128.551686)
		(end 387.044946 -127.945642)
		(width 0.1143)
		(layer "In11.Cu")
		(net "CLK_100M_MEZZ2_DN")
	)
	(segment
		(start 418.422328 -126.68885)
		(end 418.257228 -126.52375)
		(width 0.1143)
		(layer "In11.Cu")
		(net "CLK_100M_MEZZ2_DN")
	)
	(segment
		(start 375.977404 -123.490736)
		(end 375.977404 -108.493814)
		(width 0.1143)
		(layer "In11.Cu")
		(net "CLK_100M_MEZZ2_DN")
	)
	(segment
		(start 375.89333 -106.002836)
		(end 376.145298 -106.002836)
		(width 0.1143)
		(layer "In11.Cu")
		(net "CLK_100M_MEZZ2_DN")
	)
	(segment
		(start 450.049392 -115.811554)
		(end 449.444872 -116.416074)
		(width 0.1143)
		(layer "In11.Cu")
		(net "CLK_100M_MEZZ2_DN")
	)
	(segment
		(start 426.435012 -121.010172)
		(end 426.13834 -120.7135)
		(width 0.1143)
		(layer "In11.Cu")
		(net "CLK_100M_MEZZ2_DN")
	)
	(segment
		(start 419.438328 -126.68885)
		(end 419.273228 -126.52375)
		(width 0.1143)
		(layer "In11.Cu")
		(net "CLK_100M_MEZZ2_DN")
	)
	(segment
		(start 377.805188 -105.17124)
		(end 378.126752 -104.985566)
		(width 0.0889)
		(layer "In11.Cu")
		(net "CLK_100M_MEZZ2_DN")
	)
	(segment
		(start 466.841078 -115.96497)
		(end 466.200236 -115.96497)
		(width 0.1143)
		(layer "In11.Cu")
		(net "CLK_100M_MEZZ2_DN")
	)
	(segment
		(start 455.619104 -115.811554)
		(end 455.014584 -116.416074)
		(width 0.1143)
		(layer "In11.Cu")
		(net "CLK_100M_MEZZ2_DN")
	)
	(segment
		(start 447.264536 -115.811554)
		(end 446.660016 -116.416074)
		(width 0.1143)
		(layer "In11.Cu")
		(net "CLK_100M_MEZZ2_DN")
	)
	(segment
		(start 469.67902 -122.666252)
		(end 468.656924 -122.666252)
		(width 0.1143)
		(layer "In11.Cu")
		(net "CLK_100M_MEZZ2_DN")
	)
	(segment
		(start 420.805356 -125.970538)
		(end 420.56304 -126.212854)
		(width 0.1143)
		(layer "In11.Cu")
		(net "CLK_100M_MEZZ2_DN")
	)
	(segment
		(start 420.56304 -126.44628)
		(end 420.32047 -126.68885)
		(width 0.1143)
		(layer "In11.Cu")
		(net "CLK_100M_MEZZ2_DN")
	)
	(segment
		(start 469.76792 -122.020584)
		(end 469.76792 -122.577352)
		(width 0.1143)
		(layer "In11.Cu")
		(net "CLK_100M_MEZZ2_DN")
	)
	(segment
		(start 375.762266 -106.1339)
		(end 375.89333 -106.002836)
		(width 0.1143)
		(layer "In11.Cu")
		(net "CLK_100M_MEZZ2_DN")
	)
	(segment
		(start 467.27872 -116.402612)
		(end 466.841078 -115.96497)
		(width 0.1143)
		(layer "In11.Cu")
		(net "CLK_100M_MEZZ2_DN")
	)
	(segment
		(start 441.655708 -115.811046)
		(end 441.018168 -116.448586)
		(width 0.1143)
		(layer "In11.Cu")
		(net "CLK_100M_MEZZ2_DN")
	)
	(segment
		(start 391.236962 -132.743702)
		(end 387.044946 -128.551686)
		(width 0.1143)
		(layer "In11.Cu")
		(net "CLK_100M_MEZZ2_DN")
	)
	(segment
		(start 445.993774 -116.416074)
		(end 445.388746 -115.811046)
		(width 0.1143)
		(layer "In11.Cu")
		(net "CLK_100M_MEZZ2_DN")
	)
	(segment
		(start 444.480188 -115.811046)
		(end 443.87516 -116.416074)
		(width 0.1143)
		(layer "In11.Cu")
		(net "CLK_100M_MEZZ2_DN")
	)
	(segment
		(start 465.762594 -116.713254)
		(end 465.648294 -116.827554)
		(width 0.1143)
		(layer "In11.Cu")
		(net "CLK_100M_MEZZ2_DN")
	)
	(segment
		(start 422.021 -123.62942)
		(end 422.021 -123.97232)
		(width 0.1143)
		(layer "In11.Cu")
		(net "CLK_100M_MEZZ2_DN")
	)
	(segment
		(start 421.8559 -124.13742)
		(end 421.8559 -124.48032)
		(width 0.1143)
		(layer "In11.Cu")
		(net "CLK_100M_MEZZ2_DN")
	)
	(segment
		(start 384.8862 -124.29744)
		(end 380.160022 -124.29744)
		(width 0.1143)
		(layer "In11.Cu")
		(net "CLK_100M_MEZZ2_DN")
	)
	(segment
		(start 458.40396 -115.811554)
		(end 457.79944 -116.416074)
		(width 0.1143)
		(layer "In11.Cu")
		(net "CLK_100M_MEZZ2_DN")
	)
	(segment
		(start 452.229728 -116.416074)
		(end 451.563486 -116.416074)
		(width 0.1143)
		(layer "In11.Cu")
		(net "CLK_100M_MEZZ2_DN")
	)
	(segment
		(start 387.044946 -127.945642)
		(end 386.812028 -127.712724)
		(width 0.1143)
		(layer "In11.Cu")
		(net "CLK_100M_MEZZ2_DN")
	)
	(segment
		(start 463.769202 -117.80139)
		(end 463.324702 -117.80139)
		(width 0.1143)
		(layer "In11.Cu")
		(net "CLK_100M_MEZZ2_DN")
	)
	(segment
		(start 457.133198 -116.416074)
		(end 456.528678 -115.811554)
		(width 0.1143)
		(layer "In11.Cu")
		(net "CLK_100M_MEZZ2_DN")
	)
	(segment
		(start 464.441794 -116.827554)
		(end 463.858102 -117.411246)
		(width 0.1143)
		(layer "In11.Cu")
		(net "CLK_100M_MEZZ2_DN")
	)
	(segment
		(start 415.977324 -126.68885)
		(end 415.318448 -127.347726)
		(width 0.1143)
		(layer "In11.Cu")
		(net "CLK_100M_MEZZ2_DN")
	)
	(segment
		(start 469.76792 -121.004584)
		(end 469.76792 -121.347484)
		(width 0.1143)
		(layer "In11.Cu")
		(net "CLK_100M_MEZZ2_DN")
	)
	(segment
		(start 375.762266 -108.278676)
		(end 375.762266 -106.1339)
		(width 0.1143)
		(layer "In11.Cu")
		(net "CLK_100M_MEZZ2_DN")
	)
	(segment
		(start 469.76792 -122.577352)
		(end 469.67902 -122.666252)
		(width 0.1143)
		(layer "In11.Cu")
		(net "CLK_100M_MEZZ2_DN")
	)
	(segment
		(start 466.200236 -115.96497)
		(end 465.762594 -116.402612)
		(width 0.1143)
		(layer "In11.Cu")
		(net "CLK_100M_MEZZ2_DN")
	)
	(segment
		(start 456.528678 -115.811554)
		(end 455.619104 -115.811554)
		(width 0.1143)
		(layer "In11.Cu")
		(net "CLK_100M_MEZZ2_DN")
	)
	(segment
		(start 422.021 -122.192542)
		(end 422.021 -122.95632)
		(width 0.1143)
		(layer "In11.Cu")
		(net "CLK_100M_MEZZ2_DN")
	)
	(segment
		(start 397.301974 -131.957572)
		(end 396.515844 -132.743702)
		(width 0.1143)
		(layer "In11.Cu")
		(net "CLK_100M_MEZZ2_DN")
	)
	(segment
		(start 441.018168 -117.63121)
		(end 440.824874 -117.824504)
		(width 0.1143)
		(layer "In11.Cu")
		(net "CLK_100M_MEZZ2_DN")
	)
	(segment
		(start 467.304628 -119.429276)
		(end 467.75751 -119.882158)
		(width 0.1143)
		(layer "In11.Cu")
		(net "CLK_100M_MEZZ2_DN")
	)
	(segment
		(start 465.217002 -118.171722)
		(end 466.520022 -118.171722)
		(width 0.1143)
		(layer "In11.Cu")
		(net "CLK_100M_MEZZ2_DN")
	)
	(segment
		(start 376.218196 -105.952036)
		(end 377.024392 -105.952036)
		(width 0.0889)
		(layer "In11.Cu")
		(net "CLK_100M_MEZZ2_DN")
	)
	(segment
		(start 434.906166 -120.535192)
		(end 427.669198 -120.535192)
		(width 0.1143)
		(layer "In11.Cu")
		(net "CLK_100M_MEZZ2_DN")
	)
	(segment
		(start 421.523668 -125.252226)
		(end 421.281352 -125.494542)
		(width 0.1143)
		(layer "In11.Cu")
		(net "CLK_100M_MEZZ2_DN")
	)
	(segment
		(start 455.014584 -116.416074)
		(end 454.348342 -116.416074)
		(width 0.1143)
		(layer "In11.Cu")
		(net "CLK_100M_MEZZ2_DN")
	)
	(segment
		(start 421.281352 -125.727968)
		(end 421.038782 -125.970538)
		(width 0.1143)
		(layer "In11.Cu")
		(net "CLK_100M_MEZZ2_DN")
	)
	(segment
		(start 422.021 -124.64542)
		(end 422.021 -124.98832)
		(width 0.1143)
		(layer "In11.Cu")
		(net "CLK_100M_MEZZ2_DN")
	)
	(segment
		(start 380.160022 -124.29744)
		(end 379.63475 -124.822712)
		(width 0.1143)
		(layer "In11.Cu")
		(net "CLK_100M_MEZZ2_DN")
	)
	(segment
		(start 469.60282 -121.855484)
		(end 469.76792 -122.020584)
		(width 0.1143)
		(layer "In11.Cu")
		(net "CLK_100M_MEZZ2_DN")
	)
	(segment
		(start 377.024392 -105.952036)
		(end 377.805188 -105.17124)
		(width 0.0889)
		(layer "In11.Cu")
		(net "CLK_100M_MEZZ2_DN")
	)
	(segment
		(start 427.194218 -121.010172)
		(end 426.435012 -121.010172)
		(width 0.1143)
		(layer "In11.Cu")
		(net "CLK_100M_MEZZ2_DN")
	)
	(segment
		(start 418.765228 -126.68885)
		(end 418.422328 -126.68885)
		(width 0.1143)
		(layer "In11.Cu")
		(net "CLK_100M_MEZZ2_DN")
	)
	(segment
		(start 396.515844 -132.743702)
		(end 391.236962 -132.743702)
		(width 0.1143)
		(layer "In11.Cu")
		(net "CLK_100M_MEZZ2_DN")
	)
	(segment
		(start 413.555942 -127.347726)
		(end 412.811468 -128.0922)
		(width 0.1143)
		(layer "In11.Cu")
		(net "CLK_100M_MEZZ2_DN")
	)
	(segment
		(start 451.563486 -116.416074)
		(end 450.958966 -115.811554)
		(width 0.1143)
		(layer "In11.Cu")
		(net "CLK_100M_MEZZ2_DN")
	)
	(segment
		(start 437.616854 -117.824504)
		(end 434.906166 -120.535192)
		(width 0.1143)
		(layer "In11.Cu")
		(net "CLK_100M_MEZZ2_DN")
	)
	(segment
		(start 468.645494 -119.882158)
		(end 468.888064 -120.124728)
		(width 0.1143)
		(layer "In11.Cu")
		(net "CLK_100M_MEZZ2_DN")
	)
	(segment
		(start 463.235802 -117.71249)
		(end 463.235802 -117.335554)
		(width 0.1143)
		(layer "In11.Cu")
		(net "CLK_100M_MEZZ2_DN")
	)
	(segment
		(start 375.977404 -108.493814)
		(end 375.762266 -108.278676)
		(width 0.1143)
		(layer "In11.Cu")
		(net "CLK_100M_MEZZ2_DN")
	)
	(segment
		(start 464.988402 -118.400322)
		(end 465.217002 -118.171722)
		(width 0.1143)
		(layer "In11.Cu")
		(net "CLK_100M_MEZZ2_DN")
	)
	(segment
		(start 386.812028 -126.223268)
		(end 384.8862 -124.29744)
		(width 0.1143)
		(layer "In11.Cu")
		(net "CLK_100M_MEZZ2_DN")
	)
	(segment
		(start 457.79944 -116.416074)
		(end 457.133198 -116.416074)
		(width 0.1143)
		(layer "In11.Cu")
		(net "CLK_100M_MEZZ2_DN")
	)
	(segment
		(start 417.749228 -126.68885)
		(end 417.406328 -126.68885)
		(width 0.1143)
		(layer "In11.Cu")
		(net "CLK_100M_MEZZ2_DN")
	)
	(segment
		(start 446.660016 -116.416074)
		(end 445.993774 -116.416074)
		(width 0.1143)
		(layer "In11.Cu")
		(net "CLK_100M_MEZZ2_DN")
	)
	(segment
		(start 421.281352 -125.494542)
		(end 421.281352 -125.727968)
		(width 0.1143)
		(layer "In11.Cu")
		(net "CLK_100M_MEZZ2_DN")
	)
	(segment
		(start 468.888064 -120.124728)
		(end 468.888064 -120.358154)
		(width 0.1143)
		(layer "In11.Cu")
		(net "CLK_100M_MEZZ2_DN")
	)
	(segment
		(start 376.145298 -106.002836)
		(end 376.167396 -106.002836)
		(width 0.0889)
		(layer "In11.Cu")
		(net "CLK_100M_MEZZ2_DN")
	)
	(segment
		(start 463.235802 -117.335554)
		(end 461.711802 -115.811554)
		(width 0.1143)
		(layer "In11.Cu")
		(net "CLK_100M_MEZZ2_DN")
	)
	(segment
		(start 416.733228 -126.68885)
		(end 415.977324 -126.68885)
		(width 0.1143)
		(layer "In11.Cu")
		(net "CLK_100M_MEZZ2_DN")
	)
	(segment
		(start 421.8559 -123.46432)
		(end 422.021 -123.62942)
		(width 0.1143)
		(layer "In11.Cu")
		(net "CLK_100M_MEZZ2_DN")
	)
	(segment
		(start 427.669198 -120.535192)
		(end 427.194218 -121.010172)
		(width 0.1143)
		(layer "In11.Cu")
		(net "CLK_100M_MEZZ2_DN")
	)
	(segment
		(start 418.930328 -126.52375)
		(end 418.765228 -126.68885)
		(width 0.1143)
		(layer "In11.Cu")
		(net "CLK_100M_MEZZ2_DN")
	)
	(segment
		(start 386.812028 -127.712724)
		(end 386.812028 -126.223268)
		(width 0.1143)
		(layer "In11.Cu")
		(net "CLK_100M_MEZZ2_DN")
	)
	(segment
		(start 421.8559 -123.12142)
		(end 421.8559 -123.46432)
		(width 0.1143)
		(layer "In11.Cu")
		(net "CLK_100M_MEZZ2_DN")
	)
	(segment
		(start 469.363806 -120.60047)
		(end 469.76792 -121.004584)
		(width 0.1143)
		(layer "In11.Cu")
		(net "CLK_100M_MEZZ2_DN")
	)
	(segment
		(start 464.988402 -118.99773)
		(end 464.988402 -118.400322)
		(width 0.1143)
		(layer "In11.Cu")
		(net "CLK_100M_MEZZ2_DN")
	)
	(segment
		(start 463.324702 -117.80139)
		(end 463.235802 -117.71249)
		(width 0.1143)
		(layer "In11.Cu")
		(net "CLK_100M_MEZZ2_DN")
	)
	(segment
		(start 417.406328 -126.68885)
		(end 417.241228 -126.52375)
		(width 0.1143)
		(layer "In11.Cu")
		(net "CLK_100M_MEZZ2_DN")
	)
	(segment
		(start 467.304628 -119.14632)
		(end 467.304628 -119.429276)
		(width 0.1143)
		(layer "In11.Cu")
		(net "CLK_100M_MEZZ2_DN")
	)
	(segment
		(start 400.295618 -131.957572)
		(end 397.301974 -131.957572)
		(width 0.1143)
		(layer "In11.Cu")
		(net "CLK_100M_MEZZ2_DN")
	)
	(segment
		(start 465.762594 -116.402612)
		(end 465.762594 -116.713254)
		(width 0.1143)
		(layer "In11.Cu")
		(net "CLK_100M_MEZZ2_DN")
	)
	(segment
		(start 421.8559 -124.48032)
		(end 422.021 -124.64542)
		(width 0.1143)
		(layer "In11.Cu")
		(net "CLK_100M_MEZZ2_DN")
	)
	(segment
		(start 467.75751 -119.882158)
		(end 468.645494 -119.882158)
		(width 0.1143)
		(layer "In11.Cu")
		(net "CLK_100M_MEZZ2_DN")
	)
	(segment
		(start 421.757094 -125.252226)
		(end 421.523668 -125.252226)
		(width 0.1143)
		(layer "In11.Cu")
		(net "CLK_100M_MEZZ2_DN")
	)
	(segment
		(start 412.811468 -128.0922)
		(end 404.16099 -128.0922)
		(width 0.1143)
		(layer "In11.Cu")
		(net "CLK_100M_MEZZ2_DN")
	)
	(segment
		(start 463.858102 -117.71249)
		(end 463.769202 -117.80139)
		(width 0.1143)
		(layer "In11.Cu")
		(net "CLK_100M_MEZZ2_DN")
	)
	(segment
		(start 415.318448 -127.347726)
		(end 413.555942 -127.347726)
		(width 0.1143)
		(layer "In11.Cu")
		(net "CLK_100M_MEZZ2_DN")
	)
	(segment
		(start 422.021 -122.95632)
		(end 421.8559 -123.12142)
		(width 0.1143)
		(layer "In11.Cu")
		(net "CLK_100M_MEZZ2_DN")
	)
	(segment
		(start 454.348342 -116.416074)
		(end 453.743822 -115.811554)
		(width 0.1143)
		(layer "In11.Cu")
		(net "CLK_100M_MEZZ2_DN")
	)
	(segment
		(start 443.208918 -116.416074)
		(end 442.60389 -115.811046)
		(width 0.1143)
		(layer "In11.Cu")
		(net "CLK_100M_MEZZ2_DN")
	)
	(segment
		(start 453.743822 -115.811554)
		(end 452.834248 -115.811554)
		(width 0.1143)
		(layer "In11.Cu")
		(net "CLK_100M_MEZZ2_DN")
	)
	(segment
		(start 445.388746 -115.811046)
		(end 444.480188 -115.811046)
		(width 0.1143)
		(layer "In11.Cu")
		(net "CLK_100M_MEZZ2_DN")
	)
	(segment
		(start 469.76792 -121.347484)
		(end 469.60282 -121.512584)
		(width 0.1143)
		(layer "In11.Cu")
		(net "CLK_100M_MEZZ2_DN")
	)
	(segment
		(start 420.56304 -126.212854)
		(end 420.56304 -126.44628)
		(width 0.1143)
		(layer "In11.Cu")
		(net "CLK_100M_MEZZ2_DN")
	)
	(segment
		(start 440.824874 -117.824504)
		(end 437.616854 -117.824504)
		(width 0.1143)
		(layer "In11.Cu")
		(net "CLK_100M_MEZZ2_DN")
	)
	(segment
		(start 448.77863 -116.416074)
		(end 448.17411 -115.811554)
		(width 0.1143)
		(layer "In11.Cu")
		(net "CLK_100M_MEZZ2_DN")
	)
	(segment
		(start 448.17411 -115.811554)
		(end 447.264536 -115.811554)
		(width 0.1143)
		(layer "In11.Cu")
		(net "CLK_100M_MEZZ2_DN")
	)
	(segment
		(start 422.021 -124.98832)
		(end 421.757094 -125.252226)
		(width 0.1143)
		(layer "In11.Cu")
		(net "CLK_100M_MEZZ2_DN")
	)
	(segment
		(start 419.273228 -126.52375)
		(end 418.930328 -126.52375)
		(width 0.1143)
		(layer "In11.Cu")
		(net "CLK_100M_MEZZ2_DN")
	)
	(segment
		(start 449.444872 -116.416074)
		(end 448.77863 -116.416074)
		(width 0.1143)
		(layer "In11.Cu")
		(net "CLK_100M_MEZZ2_DN")
	)
	(segment
		(start 466.520022 -118.171722)
		(end 467.27872 -117.413024)
		(width 0.1143)
		(layer "In11.Cu")
		(net "CLK_100M_MEZZ2_DN")
	)
	(segment
		(start 417.914328 -126.52375)
		(end 417.749228 -126.68885)
		(width 0.1143)
		(layer "In11.Cu")
		(net "CLK_100M_MEZZ2_DN")
	)
	(segment
		(start 376.167396 -106.002836)
		(end 376.218196 -105.952036)
		(width 0.0889)
		(layer "In11.Cu")
		(net "CLK_100M_MEZZ2_DN")
	)
	(segment
		(start 420.32047 -126.68885)
		(end 419.438328 -126.68885)
		(width 0.1143)
		(layer "In11.Cu")
		(net "CLK_100M_MEZZ2_DN")
	)
	(segment
		(start 442.60389 -115.811046)
		(end 441.655708 -115.811046)
		(width 0.1143)
		(layer "In11.Cu")
		(net "CLK_100M_MEZZ2_DN")
	)
	(segment
		(start 463.858102 -117.411246)
		(end 463.858102 -117.71249)
		(width 0.1143)
		(layer "In11.Cu")
		(net "CLK_100M_MEZZ2_DN")
	)
	(segment
		(start 443.87516 -116.416074)
		(end 443.208918 -116.416074)
		(width 0.1143)
		(layer "In11.Cu")
		(net "CLK_100M_MEZZ2_DN")
	)
	(segment
		(start 469.13038 -120.60047)
		(end 469.363806 -120.60047)
		(width 0.1143)
		(layer "In11.Cu")
		(net "CLK_100M_MEZZ2_DN")
	)
	(segment
		(start 450.958966 -115.811554)
		(end 450.049392 -115.811554)
		(width 0.1143)
		(layer "In11.Cu")
		(net "CLK_100M_MEZZ2_DN")
	)
	(segment
		(start 461.711802 -115.811554)
		(end 458.40396 -115.811554)
		(width 0.1143)
		(layer "In11.Cu")
		(net "CLK_100M_MEZZ2_DN")
	)
	(segment
		(start 426.13834 -120.7135)
		(end 423.500042 -120.7135)
		(width 0.1143)
		(layer "In11.Cu")
		(net "CLK_100M_MEZZ2_DN")
	)
	(segment
		(start 468.656924 -122.666252)
		(end 464.988402 -118.99773)
		(width 0.1143)
		(layer "In11.Cu")
		(net "CLK_100M_MEZZ2_DN")
	)
	(segment
		(start 416.898328 -126.52375)
		(end 416.733228 -126.68885)
		(width 0.1143)
		(layer "In11.Cu")
		(net "CLK_100M_MEZZ2_DN")
	)
	(segment
		(start 379.63475 -124.822712)
		(end 377.30938 -124.822712)
		(width 0.1143)
		(layer "In11.Cu")
		(net "CLK_100M_MEZZ2_DN")
	)
	(segment
		(start 441.018168 -116.448586)
		(end 441.018168 -117.63121)
		(width 0.1143)
		(layer "In11.Cu")
		(net "CLK_100M_MEZZ2_DN")
	)
	(segment
		(start 418.257228 -126.52375)
		(end 417.914328 -126.52375)
		(width 0.1143)
		(layer "In11.Cu")
		(net "CLK_100M_MEZZ2_DN")
	)
	(segment
		(start 467.27872 -117.413024)
		(end 467.27872 -116.402612)
		(width 0.1143)
		(layer "In11.Cu")
		(net "CLK_100M_MEZZ2_DN")
	)
	(segment
		(start 423.500042 -120.7135)
		(end 422.021 -122.192542)
		(width 0.1143)
		(layer "In11.Cu")
		(net "CLK_100M_MEZZ2_DN")
	)
	(segment
		(start 465.648294 -116.827554)
		(end 464.441794 -116.827554)
		(width 0.1143)
		(layer "In11.Cu")
		(net "CLK_100M_MEZZ2_DN")
	)
	(segment
		(start 404.16099 -128.0922)
		(end 400.295618 -131.957572)
		(width 0.1143)
		(layer "In11.Cu")
		(net "CLK_100M_MEZZ2_DN")
	)
	(segment
		(start 469.60282 -121.512584)
		(end 469.60282 -121.855484)
		(width 0.1143)
		(layer "In11.Cu")
		(net "CLK_100M_MEZZ2_DN")
	)
	(segment
		(start 467.190328 -119.03202)
		(end 467.304628 -119.14632)
		(width 0.1143)
		(layer "In11.Cu")
		(net "CLK_100M_MEZZ2_DN")
	)
	(segment
		(start 452.834248 -115.811554)
		(end 452.229728 -116.416074)
		(width 0.1143)
		(layer "In11.Cu")
		(net "CLK_100M_MEZZ2_DN")
	)
	(arc
		(start 378.126752 -104.985566)
		(mid 378.488568 -104.748972)
		(end 378.82195 -104.473756)
		(width 0.0889)
		(layer "In11.Cu")
		(net "CLK_100M_MEZZ2_DN")
	)
	(segment
		(start 373.929402 -107.444286)
		(end 373.760746 -107.444286)
		(width 0.0889)
		(layer "F.Cu")
		(net "CLK_100M_MEZZ1_DP")
	)
	(segment
		(start 375.089928 -107.354878)
		(end 375.066306 -107.331256)
		(width 0.0889)
		(layer "F.Cu")
		(net "CLK_100M_MEZZ1_DP")
	)
	(segment
		(start 374.343168 -107.444286)
		(end 374.208802 -107.444286)
		(width 0.0889)
		(layer "F.Cu")
		(net "CLK_100M_MEZZ1_DP")
	)
	(segment
		(start 373.08917 -107.265216)
		(end 372.684548 -106.860594)
		(width 0.0889)
		(layer "F.Cu")
		(net "CLK_100M_MEZZ1_DP")
	)
	(segment
		(start 468.313262 -115.174776)
		(end 468.53602 -115.397534)
		(width 0.127)
		(layer "F.Cu")
		(net "CLK_100M_MEZZ1_DP")
	)
	(segment
		(start 469.40089 -113.440464)
		(end 469.1634 -113.677954)
		(width 0.127)
		(layer "F.Cu")
		(net "CLK_100M_MEZZ1_DP")
	)
	(segment
		(start 374.664478 -107.382056)
		(end 374.613678 -107.331256)
		(width 0.0889)
		(layer "F.Cu")
		(net "CLK_100M_MEZZ1_DP")
	)
	(segment
		(start 468.313262 -114.870992)
		(end 468.313262 -115.174776)
		(width 0.127)
		(layer "F.Cu")
		(net "CLK_100M_MEZZ1_DP")
	)
	(segment
		(start 469.1634 -113.677954)
		(end 469.1634 -114.020854)
		(width 0.127)
		(layer "F.Cu")
		(net "CLK_100M_MEZZ1_DP")
	)
	(segment
		(start 374.613678 -107.331256)
		(end 374.456198 -107.331256)
		(width 0.0889)
		(layer "F.Cu")
		(net "CLK_100M_MEZZ1_DP")
	)
	(segment
		(start 374.158002 -107.495086)
		(end 373.980202 -107.495086)
		(width 0.0889)
		(layer "F.Cu")
		(net "CLK_100M_MEZZ1_DP")
	)
	(segment
		(start 469.40089 -112.205516)
		(end 469.40089 -113.440464)
		(width 0.127)
		(layer "F.Cu")
		(net "CLK_100M_MEZZ1_DP")
	)
	(segment
		(start 374.842278 -107.382056)
		(end 374.664478 -107.382056)
		(width 0.0889)
		(layer "F.Cu")
		(net "CLK_100M_MEZZ1_DP")
	)
	(segment
		(start 469.1634 -114.020854)
		(end 468.313262 -114.870992)
		(width 0.127)
		(layer "F.Cu")
		(net "CLK_100M_MEZZ1_DP")
	)
	(segment
		(start 374.893078 -107.331256)
		(end 374.842278 -107.382056)
		(width 0.0889)
		(layer "F.Cu")
		(net "CLK_100M_MEZZ1_DP")
	)
	(segment
		(start 375.066306 -107.331256)
		(end 374.893078 -107.331256)
		(width 0.0889)
		(layer "F.Cu")
		(net "CLK_100M_MEZZ1_DP")
	)
	(segment
		(start 374.456198 -107.331256)
		(end 374.343168 -107.444286)
		(width 0.0889)
		(layer "F.Cu")
		(net "CLK_100M_MEZZ1_DP")
	)
	(segment
		(start 373.760746 -107.444286)
		(end 373.581676 -107.265216)
		(width 0.0889)
		(layer "F.Cu")
		(net "CLK_100M_MEZZ1_DP")
	)
	(segment
		(start 374.208802 -107.444286)
		(end 374.158002 -107.495086)
		(width 0.0889)
		(layer "F.Cu")
		(net "CLK_100M_MEZZ1_DP")
	)
	(segment
		(start 373.980202 -107.495086)
		(end 373.929402 -107.444286)
		(width 0.0889)
		(layer "F.Cu")
		(net "CLK_100M_MEZZ1_DP")
	)
	(segment
		(start 373.581676 -107.265216)
		(end 373.08917 -107.265216)
		(width 0.0889)
		(layer "F.Cu")
		(net "CLK_100M_MEZZ1_DP")
	)
	(via
		(at 468.53602 -115.397534)
		(size 0.508)
		(drill 0.254)
		(layers "F.Cu" "B.Cu")
		(net "CLK_100M_MEZZ1_DP")
	)
	(via
		(at 372.684548 -106.860594)
		(size 0.508)
		(drill 0.254)
		(layers "F.Cu" "B.Cu")
		(net "CLK_100M_MEZZ1_DP")
	)
	(segment
		(start 444.662814 -119.232426)
		(end 444.377572 -118.947184)
		(width 0.1143)
		(layer "In11.Cu")
		(net "CLK_100M_MEZZ1_DP")
	)
	(segment
		(start 397.643096 -132.92836)
		(end 396.900654 -133.670802)
		(width 0.1143)
		(layer "In11.Cu")
		(net "CLK_100M_MEZZ1_DP")
	)
	(segment
		(start 428.03826 -121.509536)
		(end 427.59503 -121.952766)
		(width 0.1143)
		(layer "In11.Cu")
		(net "CLK_100M_MEZZ1_DP")
	)
	(segment
		(start 450.910198 -118.369842)
		(end 450.910198 -117.939312)
		(width 0.1143)
		(layer "In11.Cu")
		(net "CLK_100M_MEZZ1_DP")
	)
	(segment
		(start 424.2435 -121.6533)
		(end 422.9481 -122.9487)
		(width 0.1143)
		(layer "In11.Cu")
		(net "CLK_100M_MEZZ1_DP")
	)
	(segment
		(start 450.567298 -117.596412)
		(end 449.13423 -117.596412)
		(width 0.1143)
		(layer "In11.Cu")
		(net "CLK_100M_MEZZ1_DP")
	)
	(segment
		(start 470.897204 -122.462544)
		(end 473.64015 -125.20549)
		(width 0.1143)
		(layer "In11.Cu")
		(net "CLK_100M_MEZZ1_DP")
	)
	(segment
		(start 400.654266 -132.92836)
		(end 397.643096 -132.92836)
		(width 0.1143)
		(layer "In11.Cu")
		(net "CLK_100M_MEZZ1_DP")
	)
	(segment
		(start 444.034672 -117.70995)
		(end 442.888116 -117.70995)
		(width 0.1143)
		(layer "In11.Cu")
		(net "CLK_100M_MEZZ1_DP")
	)
	(segment
		(start 459.81239 -119.657114)
		(end 459.81239 -119.253762)
		(width 0.1143)
		(layer "In11.Cu")
		(net "CLK_100M_MEZZ1_DP")
	)
	(segment
		(start 455.110088 -117.923564)
		(end 455.110088 -119.366792)
		(width 0.1143)
		(layer "In11.Cu")
		(net "CLK_100M_MEZZ1_DP")
	)
	(segment
		(start 376.882914 -125.6919)
		(end 375.07545 -123.884436)
		(width 0.1143)
		(layer "In11.Cu")
		(net "CLK_100M_MEZZ1_DP")
	)
	(segment
		(start 453.903588 -117.939058)
		(end 453.560688 -117.596158)
		(width 0.1143)
		(layer "In11.Cu")
		(net "CLK_100M_MEZZ1_DP")
	)
	(segment
		(start 460.217266 -118.848886)
		(end 460.217266 -118.448074)
		(width 0.1143)
		(layer "In11.Cu")
		(net "CLK_100M_MEZZ1_DP")
	)
	(segment
		(start 372.925086 -107.308142)
		(end 372.925086 -107.101132)
		(width 0.1143)
		(layer "In11.Cu")
		(net "CLK_100M_MEZZ1_DP")
	)
	(segment
		(start 442.545216 -118.05285)
		(end 442.545216 -118.896384)
		(width 0.1143)
		(layer "In11.Cu")
		(net "CLK_100M_MEZZ1_DP")
	)
	(segment
		(start 451.729856 -118.655084)
		(end 451.19544 -118.655084)
		(width 0.1143)
		(layer "In11.Cu")
		(net "CLK_100M_MEZZ1_DP")
	)
	(segment
		(start 380.23292 -125.6919)
		(end 376.882914 -125.6919)
		(width 0.1143)
		(layer "In11.Cu")
		(net "CLK_100M_MEZZ1_DP")
	)
	(segment
		(start 425.766484 -121.6533)
		(end 424.2435 -121.6533)
		(width 0.1143)
		(layer "In11.Cu")
		(net "CLK_100M_MEZZ1_DP")
	)
	(segment
		(start 473.64015 -127.826516)
		(end 471.440256 -130.02641)
		(width 0.1143)
		(layer "In11.Cu")
		(net "CLK_100M_MEZZ1_DP")
	)
	(segment
		(start 445.482472 -118.947184)
		(end 445.19723 -119.232426)
		(width 0.1143)
		(layer "In11.Cu")
		(net "CLK_100M_MEZZ1_DP")
	)
	(segment
		(start 461.186784 -120.035828)
		(end 460.191104 -120.035828)
		(width 0.1143)
		(layer "In11.Cu")
		(net "CLK_100M_MEZZ1_DP")
	)
	(segment
		(start 445.825372 -117.580664)
		(end 445.482472 -117.923564)
		(width 0.1143)
		(layer "In11.Cu")
		(net "CLK_100M_MEZZ1_DP")
	)
	(segment
		(start 452.357998 -117.596158)
		(end 452.015098 -117.939058)
		(width 0.1143)
		(layer "In11.Cu")
		(net "CLK_100M_MEZZ1_DP")
	)
	(segment
		(start 455.110088 -119.366792)
		(end 454.824846 -119.652034)
		(width 0.1143)
		(layer "In11.Cu")
		(net "CLK_100M_MEZZ1_DP")
	)
	(segment
		(start 464.672172 -120.461024)
		(end 463.823812 -119.612664)
		(width 0.1143)
		(layer "In11.Cu")
		(net "CLK_100M_MEZZ1_DP")
	)
	(segment
		(start 385.867402 -128.120394)
		(end 385.867402 -126.751842)
		(width 0.1143)
		(layer "In11.Cu")
		(net "CLK_100M_MEZZ1_DP")
	)
	(segment
		(start 451.19544 -118.655084)
		(end 450.910198 -118.369842)
		(width 0.1143)
		(layer "In11.Cu")
		(net "CLK_100M_MEZZ1_DP")
	)
	(segment
		(start 463.077052 -120.719596)
		(end 462.79181 -121.004838)
		(width 0.1143)
		(layer "In11.Cu")
		(net "CLK_100M_MEZZ1_DP")
	)
	(segment
		(start 374.876822 -107.98683)
		(end 374.61952 -107.729528)
		(width 0.1143)
		(layer "In11.Cu")
		(net "CLK_100M_MEZZ1_DP")
	)
	(segment
		(start 458.339698 -118.840758)
		(end 458.054456 -119.126)
		(width 0.1143)
		(layer "In11.Cu")
		(net "CLK_100M_MEZZ1_DP")
	)
	(segment
		(start 413.21228 -129.0193)
		(end 404.563326 -129.0193)
		(width 0.1143)
		(layer "In11.Cu")
		(net "CLK_100M_MEZZ1_DP")
	)
	(segment
		(start 463.823812 -119.612664)
		(end 463.419952 -119.612664)
		(width 0.1143)
		(layer "In11.Cu")
		(net "CLK_100M_MEZZ1_DP")
	)
	(segment
		(start 416.807904 -127.639826)
		(end 416.146996 -128.300734)
		(width 0.1143)
		(layer "In11.Cu")
		(net "CLK_100M_MEZZ1_DP")
	)
	(segment
		(start 447.971672 -118.841012)
		(end 446.711324 -117.580664)
		(width 0.1143)
		(layer "In11.Cu")
		(net "CLK_100M_MEZZ1_DP")
	)
	(segment
		(start 456.14971 -117.580664)
		(end 455.452988 -117.580664)
		(width 0.1143)
		(layer "In11.Cu")
		(net "CLK_100M_MEZZ1_DP")
	)
	(segment
		(start 384.33756 -125.222)
		(end 380.70282 -125.222)
		(width 0.1143)
		(layer "In11.Cu")
		(net "CLK_100M_MEZZ1_DP")
	)
	(segment
		(start 458.054456 -119.126)
		(end 457.41844 -119.126)
		(width 0.1143)
		(layer "In11.Cu")
		(net "CLK_100M_MEZZ1_DP")
	)
	(segment
		(start 386.112766 -128.952498)
		(end 386.112766 -128.365758)
		(width 0.1143)
		(layer "In11.Cu")
		(net "CLK_100M_MEZZ1_DP")
	)
	(segment
		(start 404.563326 -129.0193)
		(end 400.654266 -132.92836)
		(width 0.1143)
		(layer "In11.Cu")
		(net "CLK_100M_MEZZ1_DP")
	)
	(segment
		(start 457.133198 -118.840758)
		(end 457.133198 -118.564152)
		(width 0.1143)
		(layer "In11.Cu")
		(net "CLK_100M_MEZZ1_DP")
	)
	(segment
		(start 437.068976 -121.509536)
		(end 428.03826 -121.509536)
		(width 0.1143)
		(layer "In11.Cu")
		(net "CLK_100M_MEZZ1_DP")
	)
	(segment
		(start 453.903588 -119.366792)
		(end 453.903588 -117.939058)
		(width 0.1143)
		(layer "In11.Cu")
		(net "CLK_100M_MEZZ1_DP")
	)
	(segment
		(start 380.70282 -125.222)
		(end 380.23292 -125.6919)
		(width 0.1143)
		(layer "In11.Cu")
		(net "CLK_100M_MEZZ1_DP")
	)
	(segment
		(start 469.619584 -119.360188)
		(end 470.897204 -120.637808)
		(width 0.1143)
		(layer "In11.Cu")
		(net "CLK_100M_MEZZ1_DP")
	)
	(segment
		(start 463.419952 -119.612664)
		(end 463.077052 -119.955564)
		(width 0.1143)
		(layer "In11.Cu")
		(net "CLK_100M_MEZZ1_DP")
	)
	(segment
		(start 453.560688 -117.596158)
		(end 452.357998 -117.596158)
		(width 0.1143)
		(layer "In11.Cu")
		(net "CLK_100M_MEZZ1_DP")
	)
	(segment
		(start 452.015098 -117.939058)
		(end 452.015098 -118.369842)
		(width 0.1143)
		(layer "In11.Cu")
		(net "CLK_100M_MEZZ1_DP")
	)
	(segment
		(start 426.06595 -121.952766)
		(end 425.766484 -121.6533)
		(width 0.1143)
		(layer "In11.Cu")
		(net "CLK_100M_MEZZ1_DP")
	)
	(segment
		(start 468.53602 -115.397534)
		(end 468.3125 -115.621054)
		(width 0.1143)
		(layer "In11.Cu")
		(net "CLK_100M_MEZZ1_DP")
	)
	(segment
		(start 460.217266 -118.448074)
		(end 459.787498 -118.018306)
		(width 0.1143)
		(layer "In11.Cu")
		(net "CLK_100M_MEZZ1_DP")
	)
	(segment
		(start 467.664292 -127.634746)
		(end 465.52231 -125.492764)
		(width 0.1143)
		(layer "In11.Cu")
		(net "CLK_100M_MEZZ1_DP")
	)
	(segment
		(start 444.377572 -118.947184)
		(end 444.377572 -118.05285)
		(width 0.1143)
		(layer "In11.Cu")
		(net "CLK_100M_MEZZ1_DP")
	)
	(segment
		(start 372.925086 -107.101132)
		(end 372.684548 -106.860594)
		(width 0.1143)
		(layer "In11.Cu")
		(net "CLK_100M_MEZZ1_DP")
	)
	(segment
		(start 458.339698 -118.361206)
		(end 458.339698 -118.840758)
		(width 0.1143)
		(layer "In11.Cu")
		(net "CLK_100M_MEZZ1_DP")
	)
	(segment
		(start 446.711324 -117.580664)
		(end 445.825372 -117.580664)
		(width 0.1143)
		(layer "In11.Cu")
		(net "CLK_100M_MEZZ1_DP")
	)
	(segment
		(start 448.79133 -117.939312)
		(end 448.79133 -118.55577)
		(width 0.1143)
		(layer "In11.Cu")
		(net "CLK_100M_MEZZ1_DP")
	)
	(segment
		(start 422.9481 -122.9487)
		(end 422.9481 -125.372876)
		(width 0.1143)
		(layer "In11.Cu")
		(net "CLK_100M_MEZZ1_DP")
	)
	(segment
		(start 375.07545 -109.042454)
		(end 374.876822 -108.843826)
		(width 0.1143)
		(layer "In11.Cu")
		(net "CLK_100M_MEZZ1_DP")
	)
	(segment
		(start 462.155794 -121.004838)
		(end 461.186784 -120.035828)
		(width 0.1143)
		(layer "In11.Cu")
		(net "CLK_100M_MEZZ1_DP")
	)
	(segment
		(start 427.59503 -121.952766)
		(end 426.06595 -121.952766)
		(width 0.1143)
		(layer "In11.Cu")
		(net "CLK_100M_MEZZ1_DP")
	)
	(segment
		(start 438.423812 -120.1547)
		(end 437.068976 -121.509536)
		(width 0.1143)
		(layer "In11.Cu")
		(net "CLK_100M_MEZZ1_DP")
	)
	(segment
		(start 457.41844 -119.126)
		(end 457.133198 -118.840758)
		(width 0.1143)
		(layer "In11.Cu")
		(net "CLK_100M_MEZZ1_DP")
	)
	(segment
		(start 442.545216 -118.896384)
		(end 442.166502 -119.275098)
		(width 0.1143)
		(layer "In11.Cu")
		(net "CLK_100M_MEZZ1_DP")
	)
	(segment
		(start 450.910198 -117.939312)
		(end 450.567298 -117.596412)
		(width 0.1143)
		(layer "In11.Cu")
		(net "CLK_100M_MEZZ1_DP")
	)
	(segment
		(start 465.52231 -120.924828)
		(end 465.058506 -120.461024)
		(width 0.1143)
		(layer "In11.Cu")
		(net "CLK_100M_MEZZ1_DP")
	)
	(segment
		(start 465.52231 -125.492764)
		(end 465.52231 -120.924828)
		(width 0.1143)
		(layer "In11.Cu")
		(net "CLK_100M_MEZZ1_DP")
	)
	(segment
		(start 444.377572 -118.05285)
		(end 444.034672 -117.70995)
		(width 0.1143)
		(layer "In11.Cu")
		(net "CLK_100M_MEZZ1_DP")
	)
	(segment
		(start 454.824846 -119.652034)
		(end 454.18883 -119.652034)
		(width 0.1143)
		(layer "In11.Cu")
		(net "CLK_100M_MEZZ1_DP")
	)
	(segment
		(start 374.876822 -108.843826)
		(end 374.876822 -107.98683)
		(width 0.1143)
		(layer "In11.Cu")
		(net "CLK_100M_MEZZ1_DP")
	)
	(segment
		(start 468.3125 -115.774724)
		(end 469.619584 -117.081808)
		(width 0.1143)
		(layer "In11.Cu")
		(net "CLK_100M_MEZZ1_DP")
	)
	(segment
		(start 455.452988 -117.580664)
		(end 455.110088 -117.923564)
		(width 0.1143)
		(layer "In11.Cu")
		(net "CLK_100M_MEZZ1_DP")
	)
	(segment
		(start 386.112766 -128.365758)
		(end 385.867402 -128.120394)
		(width 0.1143)
		(layer "In11.Cu")
		(net "CLK_100M_MEZZ1_DP")
	)
	(segment
		(start 420.68115 -127.639826)
		(end 416.807904 -127.639826)
		(width 0.1143)
		(layer "In11.Cu")
		(net "CLK_100M_MEZZ1_DP")
	)
	(segment
		(start 422.9481 -125.372876)
		(end 420.68115 -127.639826)
		(width 0.1143)
		(layer "In11.Cu")
		(net "CLK_100M_MEZZ1_DP")
	)
	(segment
		(start 390.83107 -133.670802)
		(end 386.112766 -128.952498)
		(width 0.1143)
		(layer "In11.Cu")
		(net "CLK_100M_MEZZ1_DP")
	)
	(segment
		(start 373.346472 -107.729528)
		(end 372.925086 -107.308142)
		(width 0.1143)
		(layer "In11.Cu")
		(net "CLK_100M_MEZZ1_DP")
	)
	(segment
		(start 448.506088 -118.841012)
		(end 447.971672 -118.841012)
		(width 0.1143)
		(layer "In11.Cu")
		(net "CLK_100M_MEZZ1_DP")
	)
	(segment
		(start 396.900654 -133.670802)
		(end 390.83107 -133.670802)
		(width 0.1143)
		(layer "In11.Cu")
		(net "CLK_100M_MEZZ1_DP")
	)
	(segment
		(start 445.482472 -117.923564)
		(end 445.482472 -118.947184)
		(width 0.1143)
		(layer "In11.Cu")
		(net "CLK_100M_MEZZ1_DP")
	)
	(segment
		(start 457.133198 -118.564152)
		(end 456.14971 -117.580664)
		(width 0.1143)
		(layer "In11.Cu")
		(net "CLK_100M_MEZZ1_DP")
	)
	(segment
		(start 448.79133 -118.55577)
		(end 448.506088 -118.841012)
		(width 0.1143)
		(layer "In11.Cu")
		(net "CLK_100M_MEZZ1_DP")
	)
	(segment
		(start 442.166502 -119.275098)
		(end 441.797186 -119.275098)
		(width 0.1143)
		(layer "In11.Cu")
		(net "CLK_100M_MEZZ1_DP")
	)
	(segment
		(start 463.077052 -119.955564)
		(end 463.077052 -120.719596)
		(width 0.1143)
		(layer "In11.Cu")
		(net "CLK_100M_MEZZ1_DP")
	)
	(segment
		(start 374.61952 -107.729528)
		(end 373.346472 -107.729528)
		(width 0.1143)
		(layer "In11.Cu")
		(net "CLK_100M_MEZZ1_DP")
	)
	(segment
		(start 413.930846 -128.300734)
		(end 413.21228 -129.0193)
		(width 0.1143)
		(layer "In11.Cu")
		(net "CLK_100M_MEZZ1_DP")
	)
	(segment
		(start 470.897204 -120.637808)
		(end 470.897204 -122.462544)
		(width 0.1143)
		(layer "In11.Cu")
		(net "CLK_100M_MEZZ1_DP")
	)
	(segment
		(start 445.19723 -119.232426)
		(end 444.662814 -119.232426)
		(width 0.1143)
		(layer "In11.Cu")
		(net "CLK_100M_MEZZ1_DP")
	)
	(segment
		(start 442.888116 -117.70995)
		(end 442.545216 -118.05285)
		(width 0.1143)
		(layer "In11.Cu")
		(net "CLK_100M_MEZZ1_DP")
	)
	(segment
		(start 441.797186 -119.275098)
		(end 440.917584 -120.1547)
		(width 0.1143)
		(layer "In11.Cu")
		(net "CLK_100M_MEZZ1_DP")
	)
	(segment
		(start 462.79181 -121.004838)
		(end 462.155794 -121.004838)
		(width 0.1143)
		(layer "In11.Cu")
		(net "CLK_100M_MEZZ1_DP")
	)
	(segment
		(start 469.138 -127.634746)
		(end 467.664292 -127.634746)
		(width 0.1143)
		(layer "In11.Cu")
		(net "CLK_100M_MEZZ1_DP")
	)
	(segment
		(start 385.867402 -126.751842)
		(end 384.33756 -125.222)
		(width 0.1143)
		(layer "In11.Cu")
		(net "CLK_100M_MEZZ1_DP")
	)
	(segment
		(start 469.5317 -128.028446)
		(end 469.138 -127.634746)
		(width 0.1143)
		(layer "In11.Cu")
		(net "CLK_100M_MEZZ1_DP")
	)
	(segment
		(start 459.787498 -118.018306)
		(end 458.682598 -118.018306)
		(width 0.1143)
		(layer "In11.Cu")
		(net "CLK_100M_MEZZ1_DP")
	)
	(segment
		(start 449.13423 -117.596412)
		(end 448.79133 -117.939312)
		(width 0.1143)
		(layer "In11.Cu")
		(net "CLK_100M_MEZZ1_DP")
	)
	(segment
		(start 471.440256 -130.02641)
		(end 469.965024 -130.02641)
		(width 0.1143)
		(layer "In11.Cu")
		(net "CLK_100M_MEZZ1_DP")
	)
	(segment
		(start 440.917584 -120.1547)
		(end 438.423812 -120.1547)
		(width 0.1143)
		(layer "In11.Cu")
		(net "CLK_100M_MEZZ1_DP")
	)
	(segment
		(start 459.81239 -119.253762)
		(end 460.217266 -118.848886)
		(width 0.1143)
		(layer "In11.Cu")
		(net "CLK_100M_MEZZ1_DP")
	)
	(segment
		(start 458.682598 -118.018306)
		(end 458.339698 -118.361206)
		(width 0.1143)
		(layer "In11.Cu")
		(net "CLK_100M_MEZZ1_DP")
	)
	(segment
		(start 469.619584 -117.081808)
		(end 469.619584 -119.360188)
		(width 0.1143)
		(layer "In11.Cu")
		(net "CLK_100M_MEZZ1_DP")
	)
	(segment
		(start 465.058506 -120.461024)
		(end 464.672172 -120.461024)
		(width 0.1143)
		(layer "In11.Cu")
		(net "CLK_100M_MEZZ1_DP")
	)
	(segment
		(start 469.965024 -130.02641)
		(end 469.5317 -129.593086)
		(width 0.1143)
		(layer "In11.Cu")
		(net "CLK_100M_MEZZ1_DP")
	)
	(segment
		(start 468.3125 -115.621054)
		(end 468.3125 -115.774724)
		(width 0.1143)
		(layer "In11.Cu")
		(net "CLK_100M_MEZZ1_DP")
	)
	(segment
		(start 454.18883 -119.652034)
		(end 453.903588 -119.366792)
		(width 0.1143)
		(layer "In11.Cu")
		(net "CLK_100M_MEZZ1_DP")
	)
	(segment
		(start 375.07545 -123.884436)
		(end 375.07545 -109.042454)
		(width 0.1143)
		(layer "In11.Cu")
		(net "CLK_100M_MEZZ1_DP")
	)
	(segment
		(start 473.64015 -125.20549)
		(end 473.64015 -127.826516)
		(width 0.1143)
		(layer "In11.Cu")
		(net "CLK_100M_MEZZ1_DP")
	)
	(segment
		(start 460.191104 -120.035828)
		(end 459.81239 -119.657114)
		(width 0.1143)
		(layer "In11.Cu")
		(net "CLK_100M_MEZZ1_DP")
	)
	(segment
		(start 452.015098 -118.369842)
		(end 451.729856 -118.655084)
		(width 0.1143)
		(layer "In11.Cu")
		(net "CLK_100M_MEZZ1_DP")
	)
	(segment
		(start 469.5317 -129.593086)
		(end 469.5317 -128.028446)
		(width 0.1143)
		(layer "In11.Cu")
		(net "CLK_100M_MEZZ1_DP")
	)
	(segment
		(start 416.146996 -128.300734)
		(end 413.930846 -128.300734)
		(width 0.1143)
		(layer "In11.Cu")
		(net "CLK_100M_MEZZ1_DP")
	)
	(segment
		(start 467.77402 -115.397534)
		(end 468.008462 -115.163092)
		(width 0.127)
		(layer "F.Cu")
		(net "CLK_100M_MEZZ1_DN")
	)
	(segment
		(start 374.264174 -107.253786)
		(end 373.83974 -107.253786)
		(width 0.0889)
		(layer "F.Cu")
		(net "CLK_100M_MEZZ1_DN")
	)
	(segment
		(start 374.773952 -107.140756)
		(end 374.377204 -107.140756)
		(width 0.0889)
		(layer "F.Cu")
		(net "CLK_100M_MEZZ1_DN")
	)
	(segment
		(start 468.8586 -113.677954)
		(end 468.60079 -113.420144)
		(width 0.127)
		(layer "F.Cu")
		(net "CLK_100M_MEZZ1_DN")
	)
	(segment
		(start 375.014744 -107.041188)
		(end 374.773952 -107.140756)
		(width 0.0889)
		(layer "F.Cu")
		(net "CLK_100M_MEZZ1_DN")
	)
	(segment
		(start 468.008462 -114.7445)
		(end 468.8586 -113.894362)
		(width 0.127)
		(layer "F.Cu")
		(net "CLK_100M_MEZZ1_DN")
	)
	(segment
		(start 375.223278 -107.041188)
		(end 375.014744 -107.041188)
		(width 0.0889)
		(layer "F.Cu")
		(net "CLK_100M_MEZZ1_DN")
	)
	(segment
		(start 373.83974 -107.253786)
		(end 373.446548 -106.860594)
		(width 0.0889)
		(layer "F.Cu")
		(net "CLK_100M_MEZZ1_DN")
	)
	(segment
		(start 375.294906 -107.112816)
		(end 375.223278 -107.041188)
		(width 0.0889)
		(layer "F.Cu")
		(net "CLK_100M_MEZZ1_DN")
	)
	(segment
		(start 374.377204 -107.140756)
		(end 374.264174 -107.253786)
		(width 0.0889)
		(layer "F.Cu")
		(net "CLK_100M_MEZZ1_DN")
	)
	(segment
		(start 468.8586 -113.894362)
		(end 468.8586 -113.677954)
		(width 0.127)
		(layer "F.Cu")
		(net "CLK_100M_MEZZ1_DN")
	)
	(segment
		(start 468.008462 -115.163092)
		(end 468.008462 -114.7445)
		(width 0.127)
		(layer "F.Cu")
		(net "CLK_100M_MEZZ1_DN")
	)
	(segment
		(start 375.92 -107.354878)
		(end 375.294906 -107.112816)
		(width 0.0889)
		(layer "F.Cu")
		(net "CLK_100M_MEZZ1_DN")
	)
	(segment
		(start 468.60079 -113.420144)
		(end 468.60079 -112.205516)
		(width 0.127)
		(layer "F.Cu")
		(net "CLK_100M_MEZZ1_DN")
	)
	(via
		(at 467.77402 -115.397534)
		(size 0.508)
		(drill 0.254)
		(layers "F.Cu" "B.Cu")
		(net "CLK_100M_MEZZ1_DN")
	)
	(via
		(at 373.446548 -106.860594)
		(size 0.508)
		(drill 0.254)
		(layers "F.Cu" "B.Cu")
		(net "CLK_100M_MEZZ1_DN")
	)
	(segment
		(start 444.15583 -117.41785)
		(end 444.669672 -117.931692)
		(width 0.1143)
		(layer "In11.Cu")
		(net "CLK_100M_MEZZ1_DN")
	)
	(segment
		(start 471.123518 -123.335542)
		(end 470.881202 -123.093226)
		(width 0.1143)
		(layer "In11.Cu")
		(net "CLK_100M_MEZZ1_DN")
	)
	(segment
		(start 454.703688 -119.359934)
		(end 454.817988 -119.245634)
		(width 0.1143)
		(layer "In11.Cu")
		(net "CLK_100M_MEZZ1_DN")
	)
	(segment
		(start 472.560396 -124.77242)
		(end 472.31808 -124.530104)
		(width 0.1143)
		(layer "In11.Cu")
		(net "CLK_100M_MEZZ1_DN")
	)
	(segment
		(start 404.442168 -128.7272)
		(end 413.091122 -128.7272)
		(width 0.1143)
		(layer "In11.Cu")
		(net "CLK_100M_MEZZ1_DN")
	)
	(segment
		(start 464.79333 -120.168924)
		(end 465.179664 -120.168924)
		(width 0.1143)
		(layer "In11.Cu")
		(net "CLK_100M_MEZZ1_DN")
	)
	(segment
		(start 373.217186 -107.089956)
		(end 373.217186 -107.186984)
		(width 0.1143)
		(layer "In11.Cu")
		(net "CLK_100M_MEZZ1_DN")
	)
	(segment
		(start 416.025838 -128.008634)
		(end 416.686746 -127.347726)
		(width 0.1143)
		(layer "In11.Cu")
		(net "CLK_100M_MEZZ1_DN")
	)
	(segment
		(start 375.168922 -108.722668)
		(end 375.36755 -108.921296)
		(width 0.1143)
		(layer "In11.Cu")
		(net "CLK_100M_MEZZ1_DN")
	)
	(segment
		(start 469.8238 -127.907288)
		(end 469.8238 -129.471928)
		(width 0.1143)
		(layer "In11.Cu")
		(net "CLK_100M_MEZZ1_DN")
	)
	(segment
		(start 422.656 -125.251718)
		(end 422.656 -122.827542)
		(width 0.1143)
		(layer "In11.Cu")
		(net "CLK_100M_MEZZ1_DN")
	)
	(segment
		(start 469.259158 -127.342646)
		(end 469.8238 -127.907288)
		(width 0.1143)
		(layer "In11.Cu")
		(net "CLK_100M_MEZZ1_DN")
	)
	(segment
		(start 374.740678 -107.437428)
		(end 375.168922 -107.865672)
		(width 0.1143)
		(layer "In11.Cu")
		(net "CLK_100M_MEZZ1_DN")
	)
	(segment
		(start 461.307942 -119.743728)
		(end 462.276952 -120.712738)
		(width 0.1143)
		(layer "In11.Cu")
		(net "CLK_100M_MEZZ1_DN")
	)
	(segment
		(start 451.202298 -118.248684)
		(end 451.316598 -118.362984)
		(width 0.1143)
		(layer "In11.Cu")
		(net "CLK_100M_MEZZ1_DN")
	)
	(segment
		(start 457.539598 -118.8339)
		(end 457.933298 -118.8339)
		(width 0.1143)
		(layer "In11.Cu")
		(net "CLK_100M_MEZZ1_DN")
	)
	(segment
		(start 449.013072 -117.304312)
		(end 450.688456 -117.304312)
		(width 0.1143)
		(layer "In11.Cu")
		(net "CLK_100M_MEZZ1_DN")
	)
	(segment
		(start 468.0204 -115.643914)
		(end 467.77402 -115.397534)
		(width 0.1143)
		(layer "In11.Cu")
		(net "CLK_100M_MEZZ1_DN")
	)
	(segment
		(start 465.179664 -120.168924)
		(end 465.81441 -120.80367)
		(width 0.1143)
		(layer "In11.Cu")
		(net "CLK_100M_MEZZ1_DN")
	)
	(segment
		(start 426.187108 -121.660666)
		(end 427.473872 -121.660666)
		(width 0.1143)
		(layer "In11.Cu")
		(net "CLK_100M_MEZZ1_DN")
	)
	(segment
		(start 471.319098 -129.73431)
		(end 473.34805 -127.705358)
		(width 0.1143)
		(layer "In11.Cu")
		(net "CLK_100M_MEZZ1_DN")
	)
	(segment
		(start 400.533108 -132.63626)
		(end 404.442168 -128.7272)
		(width 0.1143)
		(layer "In11.Cu")
		(net "CLK_100M_MEZZ1_DN")
	)
	(segment
		(start 470.881202 -122.8598)
		(end 470.605104 -122.583702)
		(width 0.1143)
		(layer "In11.Cu")
		(net "CLK_100M_MEZZ1_DN")
	)
	(segment
		(start 465.97951 -122.831606)
		(end 465.81441 -122.996706)
		(width 0.1143)
		(layer "In11.Cu")
		(net "CLK_100M_MEZZ1_DN")
	)
	(segment
		(start 467.008718 -126.332488)
		(end 467.251288 -126.575058)
		(width 0.1143)
		(layer "In11.Cu")
		(net "CLK_100M_MEZZ1_DN")
	)
	(segment
		(start 462.670652 -120.712738)
		(end 462.784952 -120.598438)
		(width 0.1143)
		(layer "In11.Cu")
		(net "CLK_100M_MEZZ1_DN")
	)
	(segment
		(start 460.509366 -118.970044)
		(end 460.10449 -119.37492)
		(width 0.1143)
		(layer "In11.Cu")
		(net "CLK_100M_MEZZ1_DN")
	)
	(segment
		(start 386.159502 -127.999236)
		(end 386.404866 -128.2446)
		(width 0.1143)
		(layer "In11.Cu")
		(net "CLK_100M_MEZZ1_DN")
	)
	(segment
		(start 465.81441 -120.80367)
		(end 465.81441 -122.323606)
		(width 0.1143)
		(layer "In11.Cu")
		(net "CLK_100M_MEZZ1_DN")
	)
	(segment
		(start 465.81441 -122.996706)
		(end 465.81441 -123.339606)
		(width 0.1143)
		(layer "In11.Cu")
		(net "CLK_100M_MEZZ1_DN")
	)
	(segment
		(start 453.681846 -117.304058)
		(end 454.195688 -117.8179)
		(width 0.1143)
		(layer "In11.Cu")
		(net "CLK_100M_MEZZ1_DN")
	)
	(segment
		(start 471.599514 -123.578112)
		(end 471.356944 -123.335542)
		(width 0.1143)
		(layer "In11.Cu")
		(net "CLK_100M_MEZZ1_DN")
	)
	(segment
		(start 471.842084 -124.054108)
		(end 471.599514 -123.811538)
		(width 0.1143)
		(layer "In11.Cu")
		(net "CLK_100M_MEZZ1_DN")
	)
	(segment
		(start 445.190372 -118.826026)
		(end 445.190372 -117.802406)
		(width 0.1143)
		(layer "In11.Cu")
		(net "CLK_100M_MEZZ1_DN")
	)
	(segment
		(start 457.425298 -118.7196)
		(end 457.539598 -118.8339)
		(width 0.1143)
		(layer "In11.Cu")
		(net "CLK_100M_MEZZ1_DN")
	)
	(segment
		(start 460.509366 -118.326916)
		(end 460.509366 -118.970044)
		(width 0.1143)
		(layer "In11.Cu")
		(net "CLK_100M_MEZZ1_DN")
	)
	(segment
		(start 451.608698 -118.362984)
		(end 451.722998 -118.248684)
		(width 0.1143)
		(layer "In11.Cu")
		(net "CLK_100M_MEZZ1_DN")
	)
	(segment
		(start 451.722998 -118.248684)
		(end 451.722998 -117.8179)
		(width 0.1143)
		(layer "In11.Cu")
		(net "CLK_100M_MEZZ1_DN")
	)
	(segment
		(start 472.31808 -124.296678)
		(end 472.07551 -124.054108)
		(width 0.1143)
		(layer "In11.Cu")
		(net "CLK_100M_MEZZ1_DN")
	)
	(segment
		(start 444.669672 -118.826026)
		(end 444.783972 -118.940326)
		(width 0.1143)
		(layer "In11.Cu")
		(net "CLK_100M_MEZZ1_DN")
	)
	(segment
		(start 465.81441 -124.355606)
		(end 465.97951 -124.520706)
		(width 0.1143)
		(layer "In11.Cu")
		(net "CLK_100M_MEZZ1_DN")
	)
	(segment
		(start 470.605104 -120.758966)
		(end 469.327484 -119.481346)
		(width 0.1143)
		(layer "In11.Cu")
		(net "CLK_100M_MEZZ1_DN")
	)
	(segment
		(start 451.722998 -117.8179)
		(end 452.23684 -117.304058)
		(width 0.1143)
		(layer "In11.Cu")
		(net "CLK_100M_MEZZ1_DN")
	)
	(segment
		(start 386.159502 -126.630684)
		(end 386.159502 -127.999236)
		(width 0.1143)
		(layer "In11.Cu")
		(net "CLK_100M_MEZZ1_DN")
	)
	(segment
		(start 469.8238 -129.471928)
		(end 470.086182 -129.73431)
		(width 0.1143)
		(layer "In11.Cu")
		(net "CLK_100M_MEZZ1_DN")
	)
	(segment
		(start 465.81441 -124.012706)
		(end 465.81441 -124.355606)
		(width 0.1143)
		(layer "In11.Cu")
		(net "CLK_100M_MEZZ1_DN")
	)
	(segment
		(start 465.97951 -122.488706)
		(end 465.97951 -122.831606)
		(width 0.1143)
		(layer "In11.Cu")
		(net "CLK_100M_MEZZ1_DN")
	)
	(segment
		(start 397.521938 -132.63626)
		(end 400.533108 -132.63626)
		(width 0.1143)
		(layer "In11.Cu")
		(net "CLK_100M_MEZZ1_DN")
	)
	(segment
		(start 465.81441 -123.339606)
		(end 465.97951 -123.504706)
		(width 0.1143)
		(layer "In11.Cu")
		(net "CLK_100M_MEZZ1_DN")
	)
	(segment
		(start 472.07551 -124.054108)
		(end 471.842084 -124.054108)
		(width 0.1143)
		(layer "In11.Cu")
		(net "CLK_100M_MEZZ1_DN")
	)
	(segment
		(start 444.783972 -118.940326)
		(end 445.076072 -118.940326)
		(width 0.1143)
		(layer "In11.Cu")
		(net "CLK_100M_MEZZ1_DN")
	)
	(segment
		(start 375.168922 -107.865672)
		(end 375.168922 -108.722668)
		(width 0.1143)
		(layer "In11.Cu")
		(net "CLK_100M_MEZZ1_DN")
	)
	(segment
		(start 465.81441 -125.028706)
		(end 465.81441 -125.371606)
		(width 0.1143)
		(layer "In11.Cu")
		(net "CLK_100M_MEZZ1_DN")
	)
	(segment
		(start 420.559992 -127.347726)
		(end 422.656 -125.251718)
		(width 0.1143)
		(layer "In11.Cu")
		(net "CLK_100M_MEZZ1_DN")
	)
	(segment
		(start 386.404866 -128.2446)
		(end 386.404866 -128.83134)
		(width 0.1143)
		(layer "In11.Cu")
		(net "CLK_100M_MEZZ1_DN")
	)
	(segment
		(start 427.917102 -121.217436)
		(end 436.947818 -121.217436)
		(width 0.1143)
		(layer "In11.Cu")
		(net "CLK_100M_MEZZ1_DN")
	)
	(segment
		(start 442.766958 -117.41785)
		(end 444.15583 -117.41785)
		(width 0.1143)
		(layer "In11.Cu")
		(net "CLK_100M_MEZZ1_DN")
	)
	(segment
		(start 448.38493 -118.548912)
		(end 448.49923 -118.434612)
		(width 0.1143)
		(layer "In11.Cu")
		(net "CLK_100M_MEZZ1_DN")
	)
	(segment
		(start 466.775292 -126.332488)
		(end 467.008718 -126.332488)
		(width 0.1143)
		(layer "In11.Cu")
		(net "CLK_100M_MEZZ1_DN")
	)
	(segment
		(start 460.10449 -119.37492)
		(end 460.10449 -119.535956)
		(width 0.1143)
		(layer "In11.Cu")
		(net "CLK_100M_MEZZ1_DN")
	)
	(segment
		(start 460.312262 -119.743728)
		(end 461.307942 -119.743728)
		(width 0.1143)
		(layer "In11.Cu")
		(net "CLK_100M_MEZZ1_DN")
	)
	(segment
		(start 462.784952 -120.598438)
		(end 462.784952 -119.834406)
		(width 0.1143)
		(layer "In11.Cu")
		(net "CLK_100M_MEZZ1_DN")
	)
	(segment
		(start 424.122342 -121.3612)
		(end 425.887642 -121.3612)
		(width 0.1143)
		(layer "In11.Cu")
		(net "CLK_100M_MEZZ1_DN")
	)
	(segment
		(start 413.091122 -128.7272)
		(end 413.809688 -128.008634)
		(width 0.1143)
		(layer "In11.Cu")
		(net "CLK_100M_MEZZ1_DN")
	)
	(segment
		(start 452.23684 -117.304058)
		(end 453.681846 -117.304058)
		(width 0.1143)
		(layer "In11.Cu")
		(net "CLK_100M_MEZZ1_DN")
	)
	(segment
		(start 380.581662 -124.9299)
		(end 384.458718 -124.9299)
		(width 0.1143)
		(layer "In11.Cu")
		(net "CLK_100M_MEZZ1_DN")
	)
	(segment
		(start 373.217186 -107.186984)
		(end 373.46763 -107.437428)
		(width 0.1143)
		(layer "In11.Cu")
		(net "CLK_100M_MEZZ1_DN")
	)
	(segment
		(start 442.253116 -118.775226)
		(end 442.253116 -117.931692)
		(width 0.1143)
		(layer "In11.Cu")
		(net "CLK_100M_MEZZ1_DN")
	)
	(segment
		(start 396.779496 -133.378702)
		(end 397.521938 -132.63626)
		(width 0.1143)
		(layer "In11.Cu")
		(net "CLK_100M_MEZZ1_DN")
	)
	(segment
		(start 458.047598 -118.240048)
		(end 458.56144 -117.726206)
		(width 0.1143)
		(layer "In11.Cu")
		(net "CLK_100M_MEZZ1_DN")
	)
	(segment
		(start 451.202298 -117.818154)
		(end 451.202298 -118.248684)
		(width 0.1143)
		(layer "In11.Cu")
		(net "CLK_100M_MEZZ1_DN")
	)
	(segment
		(start 473.34805 -127.705358)
		(end 473.34805 -125.326648)
		(width 0.1143)
		(layer "In11.Cu")
		(net "CLK_100M_MEZZ1_DN")
	)
	(segment
		(start 455.33183 -117.288564)
		(end 456.270868 -117.288564)
		(width 0.1143)
		(layer "In11.Cu")
		(net "CLK_100M_MEZZ1_DN")
	)
	(segment
		(start 457.933298 -118.8339)
		(end 458.047598 -118.7196)
		(width 0.1143)
		(layer "In11.Cu")
		(net "CLK_100M_MEZZ1_DN")
	)
	(segment
		(start 470.086182 -129.73431)
		(end 471.319098 -129.73431)
		(width 0.1143)
		(layer "In11.Cu")
		(net "CLK_100M_MEZZ1_DN")
	)
	(segment
		(start 448.49923 -118.434612)
		(end 448.49923 -117.818154)
		(width 0.1143)
		(layer "In11.Cu")
		(net "CLK_100M_MEZZ1_DN")
	)
	(segment
		(start 445.704214 -117.288564)
		(end 446.832482 -117.288564)
		(width 0.1143)
		(layer "In11.Cu")
		(net "CLK_100M_MEZZ1_DN")
	)
	(segment
		(start 386.404866 -128.83134)
		(end 390.952228 -133.378702)
		(width 0.1143)
		(layer "In11.Cu")
		(net "CLK_100M_MEZZ1_DN")
	)
	(segment
		(start 458.56144 -117.726206)
		(end 459.908656 -117.726206)
		(width 0.1143)
		(layer "In11.Cu")
		(net "CLK_100M_MEZZ1_DN")
	)
	(segment
		(start 454.195688 -117.8179)
		(end 454.195688 -119.245634)
		(width 0.1143)
		(layer "In11.Cu")
		(net "CLK_100M_MEZZ1_DN")
	)
	(segment
		(start 416.686746 -127.347726)
		(end 420.559992 -127.347726)
		(width 0.1143)
		(layer "In11.Cu")
		(net "CLK_100M_MEZZ1_DN")
	)
	(segment
		(start 463.298794 -119.320564)
		(end 463.94497 -119.320564)
		(width 0.1143)
		(layer "In11.Cu")
		(net "CLK_100M_MEZZ1_DN")
	)
	(segment
		(start 448.09283 -118.548912)
		(end 448.38493 -118.548912)
		(width 0.1143)
		(layer "In11.Cu")
		(net "CLK_100M_MEZZ1_DN")
	)
	(segment
		(start 427.473872 -121.660666)
		(end 427.917102 -121.217436)
		(width 0.1143)
		(layer "In11.Cu")
		(net "CLK_100M_MEZZ1_DN")
	)
	(segment
		(start 459.908656 -117.726206)
		(end 460.509366 -118.326916)
		(width 0.1143)
		(layer "In11.Cu")
		(net "CLK_100M_MEZZ1_DN")
	)
	(segment
		(start 456.270868 -117.288564)
		(end 457.425298 -118.442994)
		(width 0.1143)
		(layer "In11.Cu")
		(net "CLK_100M_MEZZ1_DN")
	)
	(segment
		(start 442.253116 -117.931692)
		(end 442.766958 -117.41785)
		(width 0.1143)
		(layer "In11.Cu")
		(net "CLK_100M_MEZZ1_DN")
	)
	(segment
		(start 422.656 -122.827542)
		(end 424.122342 -121.3612)
		(width 0.1143)
		(layer "In11.Cu")
		(net "CLK_100M_MEZZ1_DN")
	)
	(segment
		(start 373.46763 -107.437428)
		(end 374.740678 -107.437428)
		(width 0.1143)
		(layer "In11.Cu")
		(net "CLK_100M_MEZZ1_DN")
	)
	(segment
		(start 390.952228 -133.378702)
		(end 396.779496 -133.378702)
		(width 0.1143)
		(layer "In11.Cu")
		(net "CLK_100M_MEZZ1_DN")
	)
	(segment
		(start 445.076072 -118.940326)
		(end 445.190372 -118.826026)
		(width 0.1143)
		(layer "In11.Cu")
		(net "CLK_100M_MEZZ1_DN")
	)
	(segment
		(start 458.047598 -118.7196)
		(end 458.047598 -118.240048)
		(width 0.1143)
		(layer "In11.Cu")
		(net "CLK_100M_MEZZ1_DN")
	)
	(segment
		(start 463.94497 -119.320564)
		(end 464.79333 -120.168924)
		(width 0.1143)
		(layer "In11.Cu")
		(net "CLK_100M_MEZZ1_DN")
	)
	(segment
		(start 375.36755 -108.921296)
		(end 375.36755 -123.763278)
		(width 0.1143)
		(layer "In11.Cu")
		(net "CLK_100M_MEZZ1_DN")
	)
	(segment
		(start 454.309988 -119.359934)
		(end 454.703688 -119.359934)
		(width 0.1143)
		(layer "In11.Cu")
		(net "CLK_100M_MEZZ1_DN")
	)
	(segment
		(start 473.34805 -125.326648)
		(end 472.793822 -124.77242)
		(width 0.1143)
		(layer "In11.Cu")
		(net "CLK_100M_MEZZ1_DN")
	)
	(segment
		(start 467.251288 -126.808484)
		(end 467.78545 -127.342646)
		(width 0.1143)
		(layer "In11.Cu")
		(net "CLK_100M_MEZZ1_DN")
	)
	(segment
		(start 472.793822 -124.77242)
		(end 472.560396 -124.77242)
		(width 0.1143)
		(layer "In11.Cu")
		(net "CLK_100M_MEZZ1_DN")
	)
	(segment
		(start 465.97951 -123.847606)
		(end 465.81441 -124.012706)
		(width 0.1143)
		(layer "In11.Cu")
		(net "CLK_100M_MEZZ1_DN")
	)
	(segment
		(start 413.809688 -128.008634)
		(end 416.025838 -128.008634)
		(width 0.1143)
		(layer "In11.Cu")
		(net "CLK_100M_MEZZ1_DN")
	)
	(segment
		(start 442.045344 -118.982998)
		(end 442.253116 -118.775226)
		(width 0.1143)
		(layer "In11.Cu")
		(net "CLK_100M_MEZZ1_DN")
	)
	(segment
		(start 465.81441 -125.371606)
		(end 466.775292 -126.332488)
		(width 0.1143)
		(layer "In11.Cu")
		(net "CLK_100M_MEZZ1_DN")
	)
	(segment
		(start 384.458718 -124.9299)
		(end 386.159502 -126.630684)
		(width 0.1143)
		(layer "In11.Cu")
		(net "CLK_100M_MEZZ1_DN")
	)
	(segment
		(start 460.10449 -119.535956)
		(end 460.312262 -119.743728)
		(width 0.1143)
		(layer "In11.Cu")
		(net "CLK_100M_MEZZ1_DN")
	)
	(segment
		(start 462.784952 -119.834406)
		(end 463.298794 -119.320564)
		(width 0.1143)
		(layer "In11.Cu")
		(net "CLK_100M_MEZZ1_DN")
	)
	(segment
		(start 425.887642 -121.3612)
		(end 426.187108 -121.660666)
		(width 0.1143)
		(layer "In11.Cu")
		(net "CLK_100M_MEZZ1_DN")
	)
	(segment
		(start 380.111762 -125.3998)
		(end 380.581662 -124.9299)
		(width 0.1143)
		(layer "In11.Cu")
		(net "CLK_100M_MEZZ1_DN")
	)
	(segment
		(start 441.676028 -118.982998)
		(end 442.045344 -118.982998)
		(width 0.1143)
		(layer "In11.Cu")
		(net "CLK_100M_MEZZ1_DN")
	)
	(segment
		(start 468.0204 -115.895882)
		(end 468.0204 -115.643914)
		(width 0.1143)
		(layer "In11.Cu")
		(net "CLK_100M_MEZZ1_DN")
	)
	(segment
		(start 436.947818 -121.217436)
		(end 438.302654 -119.8626)
		(width 0.1143)
		(layer "In11.Cu")
		(net "CLK_100M_MEZZ1_DN")
	)
	(segment
		(start 454.817988 -119.245634)
		(end 454.817988 -117.802406)
		(width 0.1143)
		(layer "In11.Cu")
		(net "CLK_100M_MEZZ1_DN")
	)
	(segment
		(start 454.195688 -119.245634)
		(end 454.309988 -119.359934)
		(width 0.1143)
		(layer "In11.Cu")
		(net "CLK_100M_MEZZ1_DN")
	)
	(segment
		(start 471.356944 -123.335542)
		(end 471.123518 -123.335542)
		(width 0.1143)
		(layer "In11.Cu")
		(net "CLK_100M_MEZZ1_DN")
	)
	(segment
		(start 471.599514 -123.811538)
		(end 471.599514 -123.578112)
		(width 0.1143)
		(layer "In11.Cu")
		(net "CLK_100M_MEZZ1_DN")
	)
	(segment
		(start 469.327484 -117.202966)
		(end 468.0204 -115.895882)
		(width 0.1143)
		(layer "In11.Cu")
		(net "CLK_100M_MEZZ1_DN")
	)
	(segment
		(start 444.669672 -117.931692)
		(end 444.669672 -118.826026)
		(width 0.1143)
		(layer "In11.Cu")
		(net "CLK_100M_MEZZ1_DN")
	)
	(segment
		(start 451.316598 -118.362984)
		(end 451.608698 -118.362984)
		(width 0.1143)
		(layer "In11.Cu")
		(net "CLK_100M_MEZZ1_DN")
	)
	(segment
		(start 375.36755 -123.763278)
		(end 377.004072 -125.3998)
		(width 0.1143)
		(layer "In11.Cu")
		(net "CLK_100M_MEZZ1_DN")
	)
	(segment
		(start 472.31808 -124.530104)
		(end 472.31808 -124.296678)
		(width 0.1143)
		(layer "In11.Cu")
		(net "CLK_100M_MEZZ1_DN")
	)
	(segment
		(start 446.832482 -117.288564)
		(end 448.09283 -118.548912)
		(width 0.1143)
		(layer "In11.Cu")
		(net "CLK_100M_MEZZ1_DN")
	)
	(segment
		(start 438.302654 -119.8626)
		(end 440.796426 -119.8626)
		(width 0.1143)
		(layer "In11.Cu")
		(net "CLK_100M_MEZZ1_DN")
	)
	(segment
		(start 470.605104 -122.583702)
		(end 470.605104 -120.758966)
		(width 0.1143)
		(layer "In11.Cu")
		(net "CLK_100M_MEZZ1_DN")
	)
	(segment
		(start 445.190372 -117.802406)
		(end 445.704214 -117.288564)
		(width 0.1143)
		(layer "In11.Cu")
		(net "CLK_100M_MEZZ1_DN")
	)
	(segment
		(start 450.688456 -117.304312)
		(end 451.202298 -117.818154)
		(width 0.1143)
		(layer "In11.Cu")
		(net "CLK_100M_MEZZ1_DN")
	)
	(segment
		(start 462.276952 -120.712738)
		(end 462.670652 -120.712738)
		(width 0.1143)
		(layer "In11.Cu")
		(net "CLK_100M_MEZZ1_DN")
	)
	(segment
		(start 465.97951 -124.863606)
		(end 465.81441 -125.028706)
		(width 0.1143)
		(layer "In11.Cu")
		(net "CLK_100M_MEZZ1_DN")
	)
	(segment
		(start 465.81441 -122.323606)
		(end 465.97951 -122.488706)
		(width 0.1143)
		(layer "In11.Cu")
		(net "CLK_100M_MEZZ1_DN")
	)
	(segment
		(start 377.004072 -125.3998)
		(end 380.111762 -125.3998)
		(width 0.1143)
		(layer "In11.Cu")
		(net "CLK_100M_MEZZ1_DN")
	)
	(segment
		(start 373.446548 -106.860594)
		(end 373.217186 -107.089956)
		(width 0.1143)
		(layer "In11.Cu")
		(net "CLK_100M_MEZZ1_DN")
	)
	(segment
		(start 467.78545 -127.342646)
		(end 469.259158 -127.342646)
		(width 0.1143)
		(layer "In11.Cu")
		(net "CLK_100M_MEZZ1_DN")
	)
	(segment
		(start 467.251288 -126.575058)
		(end 467.251288 -126.808484)
		(width 0.1143)
		(layer "In11.Cu")
		(net "CLK_100M_MEZZ1_DN")
	)
	(segment
		(start 465.97951 -124.520706)
		(end 465.97951 -124.863606)
		(width 0.1143)
		(layer "In11.Cu")
		(net "CLK_100M_MEZZ1_DN")
	)
	(segment
		(start 465.97951 -123.504706)
		(end 465.97951 -123.847606)
		(width 0.1143)
		(layer "In11.Cu")
		(net "CLK_100M_MEZZ1_DN")
	)
	(segment
		(start 454.817988 -117.802406)
		(end 455.33183 -117.288564)
		(width 0.1143)
		(layer "In11.Cu")
		(net "CLK_100M_MEZZ1_DN")
	)
	(segment
		(start 470.881202 -123.093226)
		(end 470.881202 -122.8598)
		(width 0.1143)
		(layer "In11.Cu")
		(net "CLK_100M_MEZZ1_DN")
	)
	(segment
		(start 469.327484 -119.481346)
		(end 469.327484 -117.202966)
		(width 0.1143)
		(layer "In11.Cu")
		(net "CLK_100M_MEZZ1_DN")
	)
	(segment
		(start 448.49923 -117.818154)
		(end 449.013072 -117.304312)
		(width 0.1143)
		(layer "In11.Cu")
		(net "CLK_100M_MEZZ1_DN")
	)
	(segment
		(start 440.796426 -119.8626)
		(end 441.676028 -118.982998)
		(width 0.1143)
		(layer "In11.Cu")
		(net "CLK_100M_MEZZ1_DN")
	)
	(segment
		(start 457.425298 -118.442994)
		(end 457.425298 -118.7196)
		(width 0.1143)
		(layer "In11.Cu")
		(net "CLK_100M_MEZZ1_DN")
	)
	(segment
		(start 383.532888 -34.771076)
		(end 383.642362 -34.661602)
		(width 0.127)
		(layer "F.Cu")
		(net "CLK_100M_M2_DP")
	)
	(segment
		(start 383.642362 -34.661602)
		(end 384.278632 -34.661602)
		(width 0.127)
		(layer "F.Cu")
		(net "CLK_100M_M2_DP")
	)
	(segment
		(start 377.83135 -105.5624)
		(end 378.32665 -105.332276)
		(width 0.127)
		(layer "F.Cu")
		(net "CLK_100M_M2_DP")
	)
	(segment
		(start 383.532634 -34.770822)
		(end 383.532888 -34.771076)
		(width 0.127)
		(layer "F.Cu")
		(net "CLK_100M_M2_DP")
	)
	(segment
		(start 382.797304 -34.770822)
		(end 383.532634 -34.770822)
		(width 0.127)
		(layer "F.Cu")
		(net "CLK_100M_M2_DP")
	)
	(segment
		(start 384.278632 -34.661602)
		(end 384.66395 -35.04692)
		(width 0.127)
		(layer "F.Cu")
		(net "CLK_100M_M2_DP")
	)
	(via
		(at 384.66395 -35.04692)
		(size 0.508)
		(drill 0.254)
		(layers "F.Cu" "B.Cu")
		(net "CLK_100M_M2_DP")
	)
	(via
		(at 378.32665 -105.332276)
		(size 0.508)
		(drill 0.254)
		(layers "F.Cu" "B.Cu")
		(net "CLK_100M_M2_DP")
	)
	(segment
		(start 373.467376 -49.126394)
		(end 373.191024 -50.442114)
		(width 0.1143)
		(layer "In2.Cu")
		(net "CLK_100M_M2_DP")
	)
	(segment
		(start 383.147062 -34.90849)
		(end 382.804162 -34.90849)
		(width 0.1143)
		(layer "In2.Cu")
		(net "CLK_100M_M2_DP")
	)
	(segment
		(start 365.265462 -72.709278)
		(end 365.9378 -75.88758)
		(width 0.1143)
		(layer "In2.Cu")
		(net "CLK_100M_M2_DP")
	)
	(segment
		(start 380.200154 -37.00907)
		(end 379.966728 -37.00907)
		(width 0.1143)
		(layer "In2.Cu")
		(net "CLK_100M_M2_DP")
	)
	(segment
		(start 367.393982 -65.4304)
		(end 367.290858 -65.887092)
		(width 0.1143)
		(layer "In2.Cu")
		(net "CLK_100M_M2_DP")
	)
	(segment
		(start 382.639062 -34.74339)
		(end 382.232408 -34.74339)
		(width 0.1143)
		(layer "In2.Cu")
		(net "CLK_100M_M2_DP")
	)
	(segment
		(start 372.465854 -46.605444)
		(end 372.612666 -47.306992)
		(width 0.1143)
		(layer "In2.Cu")
		(net "CLK_100M_M2_DP")
	)
	(segment
		(start 372.764558 -94.018862)
		(end 373.592344 -94.585282)
		(width 0.1143)
		(layer "In2.Cu")
		(net "CLK_100M_M2_DP")
	)
	(segment
		(start 376.0724 -104.758236)
		(end 376.759216 -104.758236)
		(width 0.0889)
		(layer "In2.Cu")
		(net "CLK_100M_M2_DP")
	)
	(segment
		(start 373.353076 -55.422546)
		(end 373.306594 -55.654956)
		(width 0.1143)
		(layer "In2.Cu")
		(net "CLK_100M_M2_DP")
	)
	(segment
		(start 369.600734 -62.563248)
		(end 368.259614 -64.588898)
		(width 0.1143)
		(layer "In2.Cu")
		(net "CLK_100M_M2_DP")
	)
	(segment
		(start 372.66499 -45.609256)
		(end 372.79453 -45.803566)
		(width 0.1143)
		(layer "In2.Cu")
		(net "CLK_100M_M2_DP")
	)
	(segment
		(start 381.879602 -35.096196)
		(end 381.879602 -35.09645)
		(width 0.1143)
		(layer "In2.Cu")
		(net "CLK_100M_M2_DP")
	)
	(segment
		(start 372.612666 -47.306992)
		(end 373.467376 -49.126394)
		(width 0.1143)
		(layer "In2.Cu")
		(net "CLK_100M_M2_DP")
	)
	(segment
		(start 371.98046 -87.258398)
		(end 370.078 -89.160858)
		(width 0.1143)
		(layer "In2.Cu")
		(net "CLK_100M_M2_DP")
	)
	(segment
		(start 376.759216 -104.758236)
		(end 377.600718 -105.599738)
		(width 0.0889)
		(layer "In2.Cu")
		(net "CLK_100M_M2_DP")
	)
	(segment
		(start 384.36042 -34.74339)
		(end 383.312162 -34.74339)
		(width 0.1143)
		(layer "In2.Cu")
		(net "CLK_100M_M2_DP")
	)
	(segment
		(start 367.101374 -67.11315)
		(end 366.089184 -67.560952)
		(width 0.1143)
		(layer "In2.Cu")
		(net "CLK_100M_M2_DP")
	)
	(segment
		(start 373.592344 -94.585282)
		(end 373.833644 -95.354902)
		(width 0.1143)
		(layer "In2.Cu")
		(net "CLK_100M_M2_DP")
	)
	(segment
		(start 372.86438 -44.612814)
		(end 372.99392 -44.807124)
		(width 0.1143)
		(layer "In2.Cu")
		(net "CLK_100M_M2_DP")
	)
	(segment
		(start 374.867932 -99.378516)
		(end 375.148856 -100.824284)
		(width 0.1143)
		(layer "In2.Cu")
		(net "CLK_100M_M2_DP")
	)
	(segment
		(start 372.727474 -46.139608)
		(end 372.533164 -46.269148)
		(width 0.1143)
		(layer "In2.Cu")
		(net "CLK_100M_M2_DP")
	)
	(segment
		(start 374.670066 -43.22191)
		(end 374.279922 -42.636948)
		(width 0.1143)
		(layer "In2.Cu")
		(net "CLK_100M_M2_DP")
	)
	(segment
		(start 373.058182 -53.948838)
		(end 373.353076 -55.422546)
		(width 0.1143)
		(layer "In2.Cu")
		(net "CLK_100M_M2_DP")
	)
	(segment
		(start 373.676164 -50.544222)
		(end 374.156478 -48.26)
		(width 0.1143)
		(layer "In2.Cu")
		(net "CLK_100M_M2_DP")
	)
	(segment
		(start 367.591594 -65.152524)
		(end 367.393982 -65.4304)
		(width 0.1143)
		(layer "In2.Cu")
		(net "CLK_100M_M2_DP")
	)
	(segment
		(start 375.213626 -48.482504)
		(end 374.570752 -51.538124)
		(width 0.1143)
		(layer "In2.Cu")
		(net "CLK_100M_M2_DP")
	)
	(segment
		(start 382.232408 -34.74339)
		(end 381.879602 -35.096196)
		(width 0.1143)
		(layer "In2.Cu")
		(net "CLK_100M_M2_DP")
	)
	(segment
		(start 375.999502 -104.707436)
		(end 376.0216 -104.707436)
		(width 0.0889)
		(layer "In2.Cu")
		(net "CLK_100M_M2_DP")
	)
	(segment
		(start 380.44247 -36.766754)
		(end 380.200154 -37.00907)
		(width 0.1143)
		(layer "In2.Cu")
		(net "CLK_100M_M2_DP")
	)
	(segment
		(start 373.515128 -98.192844)
		(end 374.392444 -98.774758)
		(width 0.1143)
		(layer "In2.Cu")
		(net "CLK_100M_M2_DP")
	)
	(segment
		(start 381.403606 -35.572446)
		(end 381.161036 -35.815016)
		(width 0.1143)
		(layer "In2.Cu")
		(net "CLK_100M_M2_DP")
	)
	(segment
		(start 368.259614 -64.588898)
		(end 367.591594 -65.152524)
		(width 0.1143)
		(layer "In2.Cu")
		(net "CLK_100M_M2_DP")
	)
	(segment
		(start 381.637032 -35.572446)
		(end 381.403606 -35.572446)
		(width 0.1143)
		(layer "In2.Cu")
		(net "CLK_100M_M2_DP")
	)
	(segment
		(start 373.936514 -42.568368)
		(end 373.374158 -42.943272)
		(width 0.1143)
		(layer "In2.Cu")
		(net "CLK_100M_M2_DP")
	)
	(segment
		(start 372.59133 -93.20149)
		(end 372.764558 -94.018862)
		(width 0.1143)
		(layer "In2.Cu")
		(net "CLK_100M_M2_DP")
	)
	(segment
		(start 372.747794 -56.947816)
		(end 373.015764 -57.124854)
		(width 0.1143)
		(layer "In2.Cu")
		(net "CLK_100M_M2_DP")
	)
	(segment
		(start 365.9378 -79.416402)
		(end 366.0521 -79.530702)
		(width 0.1143)
		(layer "In2.Cu")
		(net "CLK_100M_M2_DP")
	)
	(segment
		(start 372.92661 -45.14342)
		(end 372.7323 -45.27296)
		(width 0.1143)
		(layer "In2.Cu")
		(net "CLK_100M_M2_DP")
	)
	(segment
		(start 375.115836 -100.90531)
		(end 375.115582 -100.90531)
		(width 0.1143)
		(layer "In2.Cu")
		(net "CLK_100M_M2_DP")
	)
	(segment
		(start 376.0216 -104.707436)
		(end 376.0724 -104.758236)
		(width 0.0889)
		(layer "In2.Cu")
		(net "CLK_100M_M2_DP")
	)
	(segment
		(start 374.392444 -98.774758)
		(end 374.867932 -99.378516)
		(width 0.1143)
		(layer "In2.Cu")
		(net "CLK_100M_M2_DP")
	)
	(segment
		(start 372.533164 -46.269148)
		(end 372.465854 -46.605444)
		(width 0.1143)
		(layer "In2.Cu")
		(net "CLK_100M_M2_DP")
	)
	(segment
		(start 372.7323 -45.27296)
		(end 372.66499 -45.609256)
		(width 0.1143)
		(layer "In2.Cu")
		(net "CLK_100M_M2_DP")
	)
	(segment
		(start 365.9378 -70.739)
		(end 365.265462 -72.709278)
		(width 0.1143)
		(layer "In2.Cu")
		(net "CLK_100M_M2_DP")
	)
	(segment
		(start 373.374158 -42.943272)
		(end 373.122444 -43.32224)
		(width 0.1143)
		(layer "In2.Cu")
		(net "CLK_100M_M2_DP")
	)
	(segment
		(start 377.249182 -40.359076)
		(end 377.203462 -40.58793)
		(width 0.1143)
		(layer "In2.Cu")
		(net "CLK_100M_M2_DP")
	)
	(segment
		(start 368.735102 -81.57464)
		(end 371.98046 -84.821014)
		(width 0.1143)
		(layer "In2.Cu")
		(net "CLK_100M_M2_DP")
	)
	(segment
		(start 371.98046 -84.821014)
		(end 371.98046 -87.258398)
		(width 0.1143)
		(layer "In2.Cu")
		(net "CLK_100M_M2_DP")
	)
	(segment
		(start 377.600718 -105.599738)
		(end 377.83135 -105.599738)
		(width 0.0889)
		(layer "In2.Cu")
		(net "CLK_100M_M2_DP")
	)
	(segment
		(start 375.148856 -100.824284)
		(end 375.115836 -100.90531)
		(width 0.1143)
		(layer "In2.Cu")
		(net "CLK_100M_M2_DP")
	)
	(segment
		(start 370.078 -89.160858)
		(end 370.078 -90.713814)
		(width 0.1143)
		(layer "In2.Cu")
		(net "CLK_100M_M2_DP")
	)
	(segment
		(start 377.203462 -40.58793)
		(end 376.91822 -40.778176)
		(width 0.1143)
		(layer "In2.Cu")
		(net "CLK_100M_M2_DP")
	)
	(segment
		(start 367.290858 -65.887092)
		(end 367.101374 -67.11315)
		(width 0.1143)
		(layer "In2.Cu")
		(net "CLK_100M_M2_DP")
	)
	(segment
		(start 381.161036 -35.815016)
		(end 381.161036 -36.048442)
		(width 0.1143)
		(layer "In2.Cu")
		(net "CLK_100M_M2_DP")
	)
	(segment
		(start 369.985544 -60.671456)
		(end 369.600734 -62.563248)
		(width 0.1143)
		(layer "In2.Cu")
		(net "CLK_100M_M2_DP")
	)
	(segment
		(start 375.115582 -100.90531)
		(end 374.770142 -101.752908)
		(width 0.1143)
		(layer "In2.Cu")
		(net "CLK_100M_M2_DP")
	)
	(segment
		(start 380.91872 -36.290758)
		(end 380.68504 -36.290758)
		(width 0.1143)
		(layer "In2.Cu")
		(net "CLK_100M_M2_DP")
	)
	(segment
		(start 366.252506 -79.530702)
		(end 366.7125 -79.990696)
		(width 0.1143)
		(layer "In2.Cu")
		(net "CLK_100M_M2_DP")
	)
	(segment
		(start 367.37544 -81.57464)
		(end 368.735102 -81.57464)
		(width 0.1143)
		(layer "In2.Cu")
		(net "CLK_100M_M2_DP")
	)
	(segment
		(start 375.340626 -104.707436)
		(end 375.999502 -104.707436)
		(width 0.1143)
		(layer "In2.Cu")
		(net "CLK_100M_M2_DP")
	)
	(segment
		(start 373.3546 -52.7304)
		(end 373.058182 -53.948838)
		(width 0.1143)
		(layer "In2.Cu")
		(net "CLK_100M_M2_DP")
	)
	(segment
		(start 366.0521 -79.530702)
		(end 366.252506 -79.530702)
		(width 0.1143)
		(layer "In2.Cu")
		(net "CLK_100M_M2_DP")
	)
	(segment
		(start 377.910852 -39.741348)
		(end 377.381516 -40.270684)
		(width 0.1143)
		(layer "In2.Cu")
		(net "CLK_100M_M2_DP")
	)
	(segment
		(start 374.675908 -102.2223)
		(end 375.131584 -104.498394)
		(width 0.1143)
		(layer "In2.Cu")
		(net "CLK_100M_M2_DP")
	)
	(segment
		(start 374.770142 -101.752908)
		(end 374.675908 -102.2223)
		(width 0.1143)
		(layer "In2.Cu")
		(net "CLK_100M_M2_DP")
	)
	(segment
		(start 378.722382 -39.03853)
		(end 378.558552 -39.309294)
		(width 0.1143)
		(layer "In2.Cu")
		(net "CLK_100M_M2_DP")
	)
	(segment
		(start 373.147844 -57.902094)
		(end 373.14759 -57.902348)
		(width 0.1143)
		(layer "In2.Cu")
		(net "CLK_100M_M2_DP")
	)
	(segment
		(start 372.419626 -58.025792)
		(end 372.151656 -57.848246)
		(width 0.1143)
		(layer "In2.Cu")
		(net "CLK_100M_M2_DP")
	)
	(segment
		(start 376.91822 -40.778176)
		(end 376.689366 -40.732456)
		(width 0.1143)
		(layer "In2.Cu")
		(net "CLK_100M_M2_DP")
	)
	(segment
		(start 381.879348 -35.33013)
		(end 381.637032 -35.572446)
		(width 0.1143)
		(layer "In2.Cu")
		(net "CLK_100M_M2_DP")
	)
	(segment
		(start 375.419366 -43.371008)
		(end 375.418604 -43.371516)
		(width 0.1143)
		(layer "In2.Cu")
		(net "CLK_100M_M2_DP")
	)
	(segment
		(start 378.558552 -39.309294)
		(end 377.910852 -39.741348)
		(width 0.1143)
		(layer "In2.Cu")
		(net "CLK_100M_M2_DP")
	)
	(segment
		(start 381.161036 -36.048442)
		(end 380.91872 -36.290758)
		(width 0.1143)
		(layer "In2.Cu")
		(net "CLK_100M_M2_DP")
	)
	(segment
		(start 379.060202 -37.915596)
		(end 378.722382 -39.03853)
		(width 0.1143)
		(layer "In2.Cu")
		(net "CLK_100M_M2_DP")
	)
	(segment
		(start 370.078 -90.713814)
		(end 371.160548 -92.288614)
		(width 0.1143)
		(layer "In2.Cu")
		(net "CLK_100M_M2_DP")
	)
	(segment
		(start 373.323612 -97.555812)
		(end 373.398034 -97.96653)
		(width 0.1143)
		(layer "In2.Cu")
		(net "CLK_100M_M2_DP")
	)
	(segment
		(start 382.804162 -34.90849)
		(end 382.639062 -34.74339)
		(width 0.1143)
		(layer "In2.Cu")
		(net "CLK_100M_M2_DP")
	)
	(segment
		(start 372.010432 -92.620846)
		(end 372.59133 -93.20149)
		(width 0.1143)
		(layer "In2.Cu")
		(net "CLK_100M_M2_DP")
	)
	(segment
		(start 383.312162 -34.74339)
		(end 383.147062 -34.90849)
		(width 0.1143)
		(layer "In2.Cu")
		(net "CLK_100M_M2_DP")
	)
	(segment
		(start 374.795542 -47.842932)
		(end 374.796558 -47.843186)
		(width 0.1143)
		(layer "In2.Cu")
		(net "CLK_100M_M2_DP")
	)
	(segment
		(start 373.833644 -95.354902)
		(end 373.323612 -97.555812)
		(width 0.1143)
		(layer "In2.Cu")
		(net "CLK_100M_M2_DP")
	)
	(segment
		(start 376.689366 -40.732456)
		(end 375.247408 -41.6941)
		(width 0.1143)
		(layer "In2.Cu")
		(net "CLK_100M_M2_DP")
	)
	(segment
		(start 374.013984 -52.194714)
		(end 373.3546 -52.7304)
		(width 0.1143)
		(layer "In2.Cu")
		(net "CLK_100M_M2_DP")
	)
	(segment
		(start 372.99392 -44.807124)
		(end 372.92661 -45.14342)
		(width 0.1143)
		(layer "In2.Cu")
		(net "CLK_100M_M2_DP")
	)
	(segment
		(start 372.79453 -45.803566)
		(end 372.727474 -46.139608)
		(width 0.1143)
		(layer "In2.Cu")
		(net "CLK_100M_M2_DP")
	)
	(segment
		(start 373.122444 -43.32224)
		(end 372.86438 -44.612814)
		(width 0.1143)
		(layer "In2.Cu")
		(net "CLK_100M_M2_DP")
	)
	(segment
		(start 379.966728 -37.00907)
		(end 379.060202 -37.915596)
		(width 0.1143)
		(layer "In2.Cu")
		(net "CLK_100M_M2_DP")
	)
	(segment
		(start 365.346234 -68.502276)
		(end 365.9378 -70.739)
		(width 0.1143)
		(layer "In2.Cu")
		(net "CLK_100M_M2_DP")
	)
	(segment
		(start 380.44247 -36.533328)
		(end 380.44247 -36.766754)
		(width 0.1143)
		(layer "In2.Cu")
		(net "CLK_100M_M2_DP")
	)
	(segment
		(start 384.66395 -35.04692)
		(end 384.36042 -34.74339)
		(width 0.1143)
		(layer "In2.Cu")
		(net "CLK_100M_M2_DP")
	)
	(segment
		(start 371.808502 -57.918096)
		(end 369.985544 -60.671456)
		(width 0.1143)
		(layer "In2.Cu")
		(net "CLK_100M_M2_DP")
	)
	(segment
		(start 371.160548 -92.288614)
		(end 372.010432 -92.620846)
		(width 0.1143)
		(layer "In2.Cu")
		(net "CLK_100M_M2_DP")
	)
	(segment
		(start 366.7125 -80.9117)
		(end 367.37544 -81.57464)
		(width 0.1143)
		(layer "In2.Cu")
		(net "CLK_100M_M2_DP")
	)
	(segment
		(start 375.178828 -42.037508)
		(end 375.568972 -42.62247)
		(width 0.1143)
		(layer "In2.Cu")
		(net "CLK_100M_M2_DP")
	)
	(segment
		(start 375.131584 -104.498394)
		(end 375.340626 -104.707436)
		(width 0.1143)
		(layer "In2.Cu")
		(net "CLK_100M_M2_DP")
	)
	(segment
		(start 380.68504 -36.290758)
		(end 380.44247 -36.533328)
		(width 0.1143)
		(layer "In2.Cu")
		(net "CLK_100M_M2_DP")
	)
	(segment
		(start 366.7125 -79.990696)
		(end 366.7125 -80.9117)
		(width 0.1143)
		(layer "In2.Cu")
		(net "CLK_100M_M2_DP")
	)
	(segment
		(start 365.9378 -75.88758)
		(end 365.9378 -79.416402)
		(width 0.1143)
		(layer "In2.Cu")
		(net "CLK_100M_M2_DP")
	)
	(segment
		(start 366.089184 -67.560952)
		(end 365.346234 -68.502276)
		(width 0.1143)
		(layer "In2.Cu")
		(net "CLK_100M_M2_DP")
	)
	(segment
		(start 381.879602 -35.09645)
		(end 381.879348 -35.33013)
		(width 0.1143)
		(layer "In2.Cu")
		(net "CLK_100M_M2_DP")
	)
	(segment
		(start 373.306594 -55.654956)
		(end 372.677944 -56.604662)
		(width 0.1143)
		(layer "In2.Cu")
		(net "CLK_100M_M2_DP")
	)
	(segment
		(start 377.381516 -40.270684)
		(end 377.249182 -40.359076)
		(width 0.1143)
		(layer "In2.Cu")
		(net "CLK_100M_M2_DP")
	)
	(segment
		(start 373.398034 -97.96653)
		(end 373.515128 -98.192844)
		(width 0.1143)
		(layer "In2.Cu")
		(net "CLK_100M_M2_DP")
	)
	(arc
		(start 373.191024 -50.442114)
		(mid 373.186428 -50.473827)
		(end 373.185944 -50.505868)
		(width 0.1143)
		(layer "In2.Cu")
		(net "CLK_100M_M2_DP")
	)
	(arc
		(start 374.156478 -48.26)
		(mid 374.389686 -47.919268)
		(end 374.795542 -47.842932)
		(width 0.1143)
		(layer "In2.Cu")
		(net "CLK_100M_M2_DP")
	)
	(arc
		(start 374.570752 -51.538124)
		(mid 374.491429 -51.76284)
		(end 374.356122 -51.959002)
		(width 0.1143)
		(layer "In2.Cu")
		(net "CLK_100M_M2_DP")
	)
	(arc
		(start 375.418604 -43.371516)
		(mid 375.013351 -43.45174)
		(end 374.670066 -43.22191)
		(width 0.1143)
		(layer "In2.Cu")
		(net "CLK_100M_M2_DP")
	)
	(arc
		(start 373.015764 -57.124854)
		(mid 373.246995 -57.467709)
		(end 373.16791 -57.873646)
		(width 0.1143)
		(layer "In2.Cu")
		(net "CLK_100M_M2_DP")
	)
	(arc
		(start 373.14759 -57.902348)
		(mid 372.808022 -58.107927)
		(end 372.419626 -58.025792)
		(width 0.1143)
		(layer "In2.Cu")
		(net "CLK_100M_M2_DP")
	)
	(arc
		(start 375.568972 -42.62247)
		(mid 375.649196 -43.027723)
		(end 375.419366 -43.371008)
		(width 0.1143)
		(layer "In2.Cu")
		(net "CLK_100M_M2_DP")
	)
	(arc
		(start 372.677944 -56.604662)
		(mid 372.641799 -56.790705)
		(end 372.747794 -56.947816)
		(width 0.1143)
		(layer "In2.Cu")
		(net "CLK_100M_M2_DP")
	)
	(arc
		(start 374.279922 -42.636948)
		(mid 374.122421 -42.531536)
		(end 373.936514 -42.568368)
		(width 0.1143)
		(layer "In2.Cu")
		(net "CLK_100M_M2_DP")
	)
	(arc
		(start 378.526548 -105.678986)
		(mid 378.657744 -105.557095)
		(end 378.722636 -105.390188)
		(width 0.0889)
		(layer "In2.Cu")
		(net "CLK_100M_M2_DP")
	)
	(arc
		(start 375.247408 -41.6941)
		(mid 375.141996 -41.851601)
		(end 375.178828 -42.037508)
		(width 0.1143)
		(layer "In2.Cu")
		(net "CLK_100M_M2_DP")
	)
	(arc
		(start 377.83135 -105.599738)
		(mid 377.984295 -105.619822)
		(end 378.126752 -105.678986)
		(width 0.0889)
		(layer "In2.Cu")
		(net "CLK_100M_M2_DP")
	)
	(arc
		(start 373.185944 -50.505868)
		(mid 373.414246 -50.740387)
		(end 373.676164 -50.544222)
		(width 0.1143)
		(layer "In2.Cu")
		(net "CLK_100M_M2_DP")
	)
	(arc
		(start 374.796558 -47.843186)
		(mid 375.137484 -48.07649)
		(end 375.213626 -48.482504)
		(width 0.1143)
		(layer "In2.Cu")
		(net "CLK_100M_M2_DP")
	)
	(arc
		(start 374.356122 -51.959002)
		(mid 374.198775 -52.096775)
		(end 374.013984 -52.194714)
		(width 0.1143)
		(layer "In2.Cu")
		(net "CLK_100M_M2_DP")
	)
	(arc
		(start 373.16791 -57.873646)
		(mid 373.158105 -57.888031)
		(end 373.147844 -57.902094)
		(width 0.1143)
		(layer "In2.Cu")
		(net "CLK_100M_M2_DP")
	)
	(arc
		(start 378.126752 -105.678986)
		(mid 378.32665 -105.732485)
		(end 378.526548 -105.678986)
		(width 0.0889)
		(layer "In2.Cu")
		(net "CLK_100M_M2_DP")
	)
	(arc
		(start 378.722636 -105.390188)
		(mid 378.55349 -105.163115)
		(end 378.32665 -105.332276)
		(width 0.0889)
		(layer "In2.Cu")
		(net "CLK_100M_M2_DP")
	)
	(arc
		(start 372.151656 -57.848246)
		(mid 371.965613 -57.812101)
		(end 371.808502 -57.918096)
		(width 0.1143)
		(layer "In2.Cu")
		(net "CLK_100M_M2_DP")
	)
	(segment
		(start 378.82195 -105.5624)
		(end 379.31725 -105.332276)
		(width 0.127)
		(layer "F.Cu")
		(net "CLK_100M_M2_DN")
	)
	(segment
		(start 384.388868 -34.356802)
		(end 384.66395 -34.08172)
		(width 0.127)
		(layer "F.Cu")
		(net "CLK_100M_M2_DN")
	)
	(segment
		(start 383.533142 -34.27095)
		(end 383.618994 -34.356802)
		(width 0.127)
		(layer "F.Cu")
		(net "CLK_100M_M2_DN")
	)
	(segment
		(start 383.618994 -34.356802)
		(end 384.388868 -34.356802)
		(width 0.127)
		(layer "F.Cu")
		(net "CLK_100M_M2_DN")
	)
	(segment
		(start 382.797304 -34.27095)
		(end 383.533142 -34.27095)
		(width 0.127)
		(layer "F.Cu")
		(net "CLK_100M_M2_DN")
	)
	(via
		(at 379.31725 -105.332276)
		(size 0.508)
		(drill 0.254)
		(layers "F.Cu" "B.Cu")
		(net "CLK_100M_M2_DN")
	)
	(via
		(at 384.66395 -34.08172)
		(size 0.508)
		(drill 0.254)
		(layers "F.Cu" "B.Cu")
		(net "CLK_100M_M2_DN")
	)
	(segment
		(start 373.05488 -55.422546)
		(end 373.031258 -55.541418)
		(width 0.1143)
		(layer "In2.Cu")
		(net "CLK_100M_M2_DN")
	)
	(segment
		(start 382.11125 -34.45129)
		(end 378.801376 -37.76091)
		(width 0.1143)
		(layer "In2.Cu")
		(net "CLK_100M_M2_DN")
	)
	(segment
		(start 369.710462 -60.55741)
		(end 369.325652 -62.449202)
		(width 0.1143)
		(layer "In2.Cu")
		(net "CLK_100M_M2_DN")
	)
	(segment
		(start 368.064288 -64.353948)
		(end 368.064542 -64.354202)
		(width 0.1143)
		(layer "In2.Cu")
		(net "CLK_100M_M2_DN")
	)
	(segment
		(start 373.301768 -98.40214)
		(end 374.1928 -98.993198)
		(width 0.1143)
		(layer "In2.Cu")
		(net "CLK_100M_M2_DN")
	)
	(segment
		(start 371.84711 -92.870782)
		(end 372.32336 -93.347032)
		(width 0.1143)
		(layer "In2.Cu")
		(net "CLK_100M_M2_DN")
	)
	(segment
		(start 377.72467 -39.514272)
		(end 377.19508 -40.043608)
		(width 0.1143)
		(layer "In2.Cu")
		(net "CLK_100M_M2_DN")
	)
	(segment
		(start 376.680222 -104.948736)
		(end 377.521724 -105.790238)
		(width 0.0889)
		(layer "In2.Cu")
		(net "CLK_100M_M2_DN")
	)
	(segment
		(start 374.731534 -48.128174)
		(end 374.73636 -48.12919)
		(width 0.1143)
		(layer "In2.Cu")
		(net "CLK_100M_M2_DN")
	)
	(segment
		(start 371.68836 -87.13724)
		(end 369.7859 -89.0397)
		(width 0.1143)
		(layer "In2.Cu")
		(net "CLK_100M_M2_DN")
	)
	(segment
		(start 373.025416 -97.5487)
		(end 373.110506 -98.0186)
		(width 0.1143)
		(layer "In2.Cu")
		(net "CLK_100M_M2_DN")
	)
	(segment
		(start 373.031258 -55.541418)
		(end 372.434358 -56.443372)
		(width 0.1143)
		(layer "In2.Cu")
		(net "CLK_100M_M2_DN")
	)
	(segment
		(start 373.86514 -51.938936)
		(end 373.093742 -52.565554)
		(width 0.1143)
		(layer "In2.Cu")
		(net "CLK_100M_M2_DN")
	)
	(segment
		(start 373.055134 -55.422546)
		(end 373.05488 -55.422546)
		(width 0.1143)
		(layer "In2.Cu")
		(net "CLK_100M_M2_DN")
	)
	(segment
		(start 372.33352 -47.400464)
		(end 373.161306 -49.161954)
		(width 0.1143)
		(layer "In2.Cu")
		(net "CLK_100M_M2_DN")
	)
	(segment
		(start 365.6457 -75.918314)
		(end 365.6457 -79.53756)
		(width 0.1143)
		(layer "In2.Cu")
		(net "CLK_100M_M2_DN")
	)
	(segment
		(start 372.502938 -94.193868)
		(end 373.343678 -94.769432)
		(width 0.1143)
		(layer "In2.Cu")
		(net "CLK_100M_M2_DN")
	)
	(segment
		(start 366.4204 -80.111854)
		(end 366.4204 -81.032858)
		(width 0.1143)
		(layer "In2.Cu")
		(net "CLK_100M_M2_DN")
	)
	(segment
		(start 369.325652 -62.449202)
		(end 368.064288 -64.353948)
		(width 0.1143)
		(layer "In2.Cu")
		(net "CLK_100M_M2_DN")
	)
	(segment
		(start 374.37822 -102.221538)
		(end 374.862344 -104.642412)
		(width 0.1143)
		(layer "In2.Cu")
		(net "CLK_100M_M2_DN")
	)
	(segment
		(start 378.342398 -39.102284)
		(end 377.72467 -39.514272)
		(width 0.1143)
		(layer "In2.Cu")
		(net "CLK_100M_M2_DN")
	)
	(segment
		(start 378.453142 -38.918896)
		(end 378.342398 -39.102284)
		(width 0.1143)
		(layer "In2.Cu")
		(net "CLK_100M_M2_DN")
	)
	(segment
		(start 368.068606 -64.354202)
		(end 368.075972 -64.361568)
		(width 0.1143)
		(layer "In2.Cu")
		(net "CLK_100M_M2_DN")
	)
	(segment
		(start 367.254282 -81.86674)
		(end 368.613944 -81.86674)
		(width 0.1143)
		(layer "In2.Cu")
		(net "CLK_100M_M2_DN")
	)
	(segment
		(start 373.161306 -49.161954)
		(end 372.90502 -50.381916)
		(width 0.1143)
		(layer "In2.Cu")
		(net "CLK_100M_M2_DN")
	)
	(segment
		(start 372.586504 -57.191402)
		(end 372.854474 -57.368694)
		(width 0.1143)
		(layer "In2.Cu")
		(net "CLK_100M_M2_DN")
	)
	(segment
		(start 370.970556 -92.528136)
		(end 371.84711 -92.870782)
		(width 0.1143)
		(layer "In2.Cu")
		(net "CLK_100M_M2_DN")
	)
	(segment
		(start 371.68836 -84.942172)
		(end 371.68836 -87.13724)
		(width 0.1143)
		(layer "In2.Cu")
		(net "CLK_100M_M2_DN")
	)
	(segment
		(start 368.613944 -81.86674)
		(end 371.68836 -84.942172)
		(width 0.1143)
		(layer "In2.Cu")
		(net "CLK_100M_M2_DN")
	)
	(segment
		(start 364.962948 -72.69099)
		(end 365.6457 -75.918314)
		(width 0.1143)
		(layer "In2.Cu")
		(net "CLK_100M_M2_DN")
	)
	(segment
		(start 368.071146 -64.365378)
		(end 367.374932 -64.953134)
		(width 0.1143)
		(layer "In2.Cu")
		(net "CLK_100M_M2_DN")
	)
	(segment
		(start 374.488964 -101.668326)
		(end 374.37822 -102.221538)
		(width 0.1143)
		(layer "In2.Cu")
		(net "CLK_100M_M2_DN")
	)
	(segment
		(start 372.924324 -57.712102)
		(end 372.92407 -57.712356)
		(width 0.1143)
		(layer "In2.Cu")
		(net "CLK_100M_M2_DN")
	)
	(segment
		(start 366.83696 -66.910458)
		(end 365.904526 -67.322954)
		(width 0.1143)
		(layer "In2.Cu")
		(net "CLK_100M_M2_DN")
	)
	(segment
		(start 374.594628 -99.503738)
		(end 374.845326 -100.794312)
		(width 0.1143)
		(layer "In2.Cu")
		(net "CLK_100M_M2_DN")
	)
	(segment
		(start 373.110506 -98.0186)
		(end 373.138446 -98.100642)
		(width 0.1143)
		(layer "In2.Cu")
		(net "CLK_100M_M2_DN")
	)
	(segment
		(start 373.343678 -94.769432)
		(end 373.530876 -95.366332)
		(width 0.1143)
		(layer "In2.Cu")
		(net "CLK_100M_M2_DN")
	)
	(segment
		(start 373.908066 -51.922426)
		(end 373.86514 -51.938936)
		(width 0.1143)
		(layer "In2.Cu")
		(net "CLK_100M_M2_DN")
	)
	(segment
		(start 374.1928 -98.993198)
		(end 374.594628 -99.503738)
		(width 0.1143)
		(layer "In2.Cu")
		(net "CLK_100M_M2_DN")
	)
	(segment
		(start 384.66395 -34.08172)
		(end 384.29438 -34.45129)
		(width 0.1143)
		(layer "In2.Cu")
		(net "CLK_100M_M2_DN")
	)
	(segment
		(start 376.0724 -104.948736)
		(end 376.680222 -104.948736)
		(width 0.0889)
		(layer "In2.Cu")
		(net "CLK_100M_M2_DN")
	)
	(segment
		(start 377.19508 -40.043608)
		(end 375.085356 -41.451022)
		(width 0.1143)
		(layer "In2.Cu")
		(net "CLK_100M_M2_DN")
	)
	(segment
		(start 367.005616 -65.822576)
		(end 367.00206 -65.842642)
		(width 0.1143)
		(layer "In2.Cu")
		(net "CLK_100M_M2_DN")
	)
	(segment
		(start 372.75897 -53.942742)
		(end 373.055134 -55.422546)
		(width 0.1143)
		(layer "In2.Cu")
		(net "CLK_100M_M2_DN")
	)
	(segment
		(start 365.632492 -70.728332)
		(end 364.962948 -72.69099)
		(width 0.1143)
		(layer "In2.Cu")
		(net "CLK_100M_M2_DN")
	)
	(segment
		(start 373.138446 -98.100642)
		(end 373.138192 -98.100642)
		(width 0.1143)
		(layer "In2.Cu")
		(net "CLK_100M_M2_DN")
	)
	(segment
		(start 374.845326 -100.794312)
		(end 374.488964 -101.668326)
		(width 0.1143)
		(layer "In2.Cu")
		(net "CLK_100M_M2_DN")
	)
	(segment
		(start 376.0216 -104.999536)
		(end 376.0724 -104.948736)
		(width 0.0889)
		(layer "In2.Cu")
		(net "CLK_100M_M2_DN")
	)
	(segment
		(start 373.301768 -98.402394)
		(end 373.301768 -98.40214)
		(width 0.1143)
		(layer "In2.Cu")
		(net "CLK_100M_M2_DN")
	)
	(segment
		(start 366.4204 -81.032858)
		(end 367.254282 -81.86674)
		(width 0.1143)
		(layer "In2.Cu")
		(net "CLK_100M_M2_DN")
	)
	(segment
		(start 373.093742 -52.565554)
		(end 372.75897 -53.942742)
		(width 0.1143)
		(layer "In2.Cu")
		(net "CLK_100M_M2_DN")
	)
	(segment
		(start 367.121694 -65.308734)
		(end 367.005616 -65.822576)
		(width 0.1143)
		(layer "In2.Cu")
		(net "CLK_100M_M2_DN")
	)
	(segment
		(start 371.564916 -57.756806)
		(end 369.710462 -60.55741)
		(width 0.1143)
		(layer "In2.Cu")
		(net "CLK_100M_M2_DN")
	)
	(segment
		(start 372.847108 -43.208448)
		(end 372.167658 -46.606968)
		(width 0.1143)
		(layer "In2.Cu")
		(net "CLK_100M_M2_DN")
	)
	(segment
		(start 375.219468 -104.999536)
		(end 375.999502 -104.999536)
		(width 0.1143)
		(layer "In2.Cu")
		(net "CLK_100M_M2_DN")
	)
	(segment
		(start 367.374932 -64.953134)
		(end 367.121694 -65.308734)
		(width 0.1143)
		(layer "In2.Cu")
		(net "CLK_100M_M2_DN")
	)
	(segment
		(start 365.632746 -70.728332)
		(end 365.632492 -70.728332)
		(width 0.1143)
		(layer "In2.Cu")
		(net "CLK_100M_M2_DN")
	)
	(segment
		(start 384.29438 -34.45129)
		(end 382.11125 -34.45129)
		(width 0.1143)
		(layer "In2.Cu")
		(net "CLK_100M_M2_DN")
	)
	(segment
		(start 374.862344 -104.642412)
		(end 375.219468 -104.999536)
		(width 0.1143)
		(layer "In2.Cu")
		(net "CLK_100M_M2_DN")
	)
	(segment
		(start 374.913144 -43.059604)
		(end 374.523 -42.474896)
		(width 0.1143)
		(layer "In2.Cu")
		(net "CLK_100M_M2_DN")
	)
	(segment
		(start 373.138192 -98.100642)
		(end 373.255286 -98.326956)
		(width 0.1143)
		(layer "In2.Cu")
		(net "CLK_100M_M2_DN")
	)
	(segment
		(start 375.999502 -104.999536)
		(end 376.0216 -104.999536)
		(width 0.0889)
		(layer "In2.Cu")
		(net "CLK_100M_M2_DN")
	)
	(segment
		(start 373.530876 -95.366332)
		(end 373.025416 -97.5487)
		(width 0.1143)
		(layer "In2.Cu")
		(net "CLK_100M_M2_DN")
	)
	(segment
		(start 377.521724 -105.790238)
		(end 377.83135 -105.790238)
		(width 0.0889)
		(layer "In2.Cu")
		(net "CLK_100M_M2_DN")
	)
	(segment
		(start 375.257314 -43.12793)
		(end 375.256552 -43.128438)
		(width 0.1143)
		(layer "In2.Cu")
		(net "CLK_100M_M2_DN")
	)
	(segment
		(start 365.904526 -67.322954)
		(end 365.026194 -68.435728)
		(width 0.1143)
		(layer "In2.Cu")
		(net "CLK_100M_M2_DN")
	)
	(segment
		(start 366.131348 -79.822802)
		(end 366.4204 -80.111854)
		(width 0.1143)
		(layer "In2.Cu")
		(net "CLK_100M_M2_DN")
	)
	(segment
		(start 373.163338 -42.732706)
		(end 372.847108 -43.208448)
		(width 0.1143)
		(layer "In2.Cu")
		(net "CLK_100M_M2_DN")
	)
	(segment
		(start 369.7859 -90.804746)
		(end 370.970556 -92.528136)
		(width 0.1143)
		(layer "In2.Cu")
		(net "CLK_100M_M2_DN")
	)
	(segment
		(start 365.6457 -79.53756)
		(end 365.930942 -79.822802)
		(width 0.1143)
		(layer "In2.Cu")
		(net "CLK_100M_M2_DN")
	)
	(segment
		(start 373.25554 -98.326956)
		(end 373.301768 -98.402394)
		(width 0.1143)
		(layer "In2.Cu")
		(net "CLK_100M_M2_DN")
	)
	(segment
		(start 373.774462 -42.32529)
		(end 373.163338 -42.732706)
		(width 0.1143)
		(layer "In2.Cu")
		(net "CLK_100M_M2_DN")
	)
	(segment
		(start 373.255286 -98.326956)
		(end 373.25554 -98.326956)
		(width 0.1143)
		(layer "In2.Cu")
		(net "CLK_100M_M2_DN")
	)
	(segment
		(start 367.00206 -65.842642)
		(end 366.83696 -66.910458)
		(width 0.1143)
		(layer "In2.Cu")
		(net "CLK_100M_M2_DN")
	)
	(segment
		(start 374.93575 -42.19956)
		(end 375.325894 -42.784522)
		(width 0.1143)
		(layer "In2.Cu")
		(net "CLK_100M_M2_DN")
	)
	(segment
		(start 373.962168 -50.60442)
		(end 374.442482 -48.320198)
		(width 0.1143)
		(layer "In2.Cu")
		(net "CLK_100M_M2_DN")
	)
	(segment
		(start 368.075972 -64.361568)
		(end 368.071146 -64.365378)
		(width 0.1143)
		(layer "In2.Cu")
		(net "CLK_100M_M2_DN")
	)
	(segment
		(start 365.026194 -68.435728)
		(end 365.632746 -70.728332)
		(width 0.1143)
		(layer "In2.Cu")
		(net "CLK_100M_M2_DN")
	)
	(segment
		(start 378.801376 -37.76091)
		(end 378.453142 -38.918896)
		(width 0.1143)
		(layer "In2.Cu")
		(net "CLK_100M_M2_DN")
	)
	(segment
		(start 369.7859 -89.0397)
		(end 369.7859 -90.804746)
		(width 0.1143)
		(layer "In2.Cu")
		(net "CLK_100M_M2_DN")
	)
	(segment
		(start 365.930942 -79.822802)
		(end 366.131348 -79.822802)
		(width 0.1143)
		(layer "In2.Cu")
		(net "CLK_100M_M2_DN")
	)
	(segment
		(start 372.580916 -57.782206)
		(end 372.312946 -57.60466)
		(width 0.1143)
		(layer "In2.Cu")
		(net "CLK_100M_M2_DN")
	)
	(segment
		(start 372.167658 -46.606968)
		(end 372.33352 -47.400464)
		(width 0.1143)
		(layer "In2.Cu")
		(net "CLK_100M_M2_DN")
	)
	(segment
		(start 368.064542 -64.354202)
		(end 368.068606 -64.354202)
		(width 0.1143)
		(layer "In2.Cu")
		(net "CLK_100M_M2_DN")
	)
	(segment
		(start 374.13946 -51.762914)
		(end 374.134126 -51.768756)
		(width 0.1143)
		(layer "In2.Cu")
		(net "CLK_100M_M2_DN")
	)
	(segment
		(start 374.927622 -48.42256)
		(end 374.284748 -51.477926)
		(width 0.1143)
		(layer "In2.Cu")
		(net "CLK_100M_M2_DN")
	)
	(segment
		(start 372.32336 -93.347032)
		(end 372.502938 -94.193868)
		(width 0.1143)
		(layer "In2.Cu")
		(net "CLK_100M_M2_DN")
	)
	(arc
		(start 378.031248 -105.844086)
		(mid 378.32665 -105.923217)
		(end 378.622052 -105.844086)
		(width 0.0889)
		(layer "In2.Cu")
		(net "CLK_100M_M2_DN")
	)
	(arc
		(start 372.894098 -50.520854)
		(mid 373.391454 -51.031728)
		(end 373.962168 -50.60442)
		(width 0.1143)
		(layer "In2.Cu")
		(net "CLK_100M_M2_DN")
	)
	(arc
		(start 374.442482 -48.320198)
		(mid 374.547724 -48.165013)
		(end 374.731534 -48.128174)
		(width 0.1143)
		(layer "In2.Cu")
		(net "CLK_100M_M2_DN")
	)
	(arc
		(start 374.134126 -51.768756)
		(mid 374.029793 -51.858387)
		(end 373.908066 -51.922426)
		(width 0.1143)
		(layer "In2.Cu")
		(net "CLK_100M_M2_DN")
	)
	(arc
		(start 372.312946 -57.60466)
		(mid 371.907421 -57.525811)
		(end 371.564916 -57.756806)
		(width 0.1143)
		(layer "In2.Cu")
		(net "CLK_100M_M2_DN")
	)
	(arc
		(start 377.83135 -105.790238)
		(mid 377.934863 -105.803934)
		(end 378.031248 -105.844086)
		(width 0.0889)
		(layer "In2.Cu")
		(net "CLK_100M_M2_DN")
	)
	(arc
		(start 372.92407 -57.712356)
		(mid 372.919477 -57.719035)
		(end 372.914672 -57.725564)
		(width 0.1143)
		(layer "In2.Cu")
		(net "CLK_100M_M2_DN")
	)
	(arc
		(start 378.622052 -105.844086)
		(mid 378.983895 -105.607528)
		(end 379.31725 -105.332276)
		(width 0.0889)
		(layer "In2.Cu")
		(net "CLK_100M_M2_DN")
	)
	(arc
		(start 372.90502 -50.381916)
		(mid 372.895052 -50.451031)
		(end 372.894098 -50.520854)
		(width 0.1143)
		(layer "In2.Cu")
		(net "CLK_100M_M2_DN")
	)
	(arc
		(start 375.085356 -41.451022)
		(mid 374.855526 -41.794307)
		(end 374.93575 -42.19956)
		(width 0.1143)
		(layer "In2.Cu")
		(net "CLK_100M_M2_DN")
	)
	(arc
		(start 372.854474 -57.368694)
		(mid 372.96049 -57.525908)
		(end 372.924324 -57.712102)
		(width 0.1143)
		(layer "In2.Cu")
		(net "CLK_100M_M2_DN")
	)
	(arc
		(start 372.434358 -56.443372)
		(mid 372.355509 -56.848897)
		(end 372.586504 -57.191402)
		(width 0.1143)
		(layer "In2.Cu")
		(net "CLK_100M_M2_DN")
	)
	(arc
		(start 374.284748 -51.477926)
		(mid 374.231052 -51.630078)
		(end 374.13946 -51.762914)
		(width 0.1143)
		(layer "In2.Cu")
		(net "CLK_100M_M2_DN")
	)
	(arc
		(start 374.73636 -48.12919)
		(mid 374.89275 -48.236263)
		(end 374.927622 -48.42256)
		(width 0.1143)
		(layer "In2.Cu")
		(net "CLK_100M_M2_DN")
	)
	(arc
		(start 372.914672 -57.725564)
		(mid 372.758987 -57.81982)
		(end 372.580916 -57.782206)
		(width 0.1143)
		(layer "In2.Cu")
		(net "CLK_100M_M2_DN")
	)
	(arc
		(start 375.256552 -43.128438)
		(mid 375.070541 -43.165249)
		(end 374.913144 -43.059604)
		(width 0.1143)
		(layer "In2.Cu")
		(net "CLK_100M_M2_DN")
	)
	(arc
		(start 374.523 -42.474896)
		(mid 374.179715 -42.245066)
		(end 373.774462 -42.32529)
		(width 0.1143)
		(layer "In2.Cu")
		(net "CLK_100M_M2_DN")
	)
	(arc
		(start 375.325894 -42.784522)
		(mid 375.362726 -42.970429)
		(end 375.257314 -43.12793)
		(width 0.1143)
		(layer "In2.Cu")
		(net "CLK_100M_M2_DN")
	)
	(segment
		(start 412.148782 -133.900672)
		(end 411.80893 -134.240524)
		(width 0.10795)
		(layer "F.Cu")
		(net "XDP_TRST_N")
	)
	(segment
		(start 455.945494 -148.719794)
		(end 457.252324 -148.719794)
		(width 0.10795)
		(layer "F.Cu")
		(net "XDP_TRST_N")
	)
	(segment
		(start 413.149034 -132.900928)
		(end 412.928816 -133.121146)
		(width 0.10795)
		(layer "F.Cu")
		(net "XDP_TRST_N")
	)
	(segment
		(start 412.928816 -133.580378)
		(end 412.608522 -133.900672)
		(width 0.10795)
		(layer "F.Cu")
		(net "XDP_TRST_N")
	)
	(segment
		(start 455.21118 -148.3106)
		(end 455.5363 -148.3106)
		(width 0.10795)
		(layer "F.Cu")
		(net "XDP_TRST_N")
	)
	(segment
		(start 412.928816 -133.121146)
		(end 412.928816 -133.580378)
		(width 0.10795)
		(layer "F.Cu")
		(net "XDP_TRST_N")
	)
	(segment
		(start 413.39389 -132.900928)
		(end 413.149034 -132.900928)
		(width 0.10795)
		(layer "F.Cu")
		(net "XDP_TRST_N")
	)
	(segment
		(start 390.21385 -118.4402)
		(end 390.705848 -118.6688)
		(width 0.10668)
		(layer "F.Cu")
		(net "XDP_TRST_N")
	)
	(segment
		(start 414.060386 -132.234432)
		(end 413.39389 -132.900928)
		(width 0.10795)
		(layer "F.Cu")
		(net "XDP_TRST_N")
	)
	(segment
		(start 455.5363 -148.3106)
		(end 455.945494 -148.719794)
		(width 0.10795)
		(layer "F.Cu")
		(net "XDP_TRST_N")
	)
	(segment
		(start 412.608522 -133.900672)
		(end 412.148782 -133.900672)
		(width 0.10795)
		(layer "F.Cu")
		(net "XDP_TRST_N")
	)
	(segment
		(start 390.705848 -118.6688)
		(end 390.70915 -118.670324)
		(width 0.10668)
		(layer "F.Cu")
		(net "XDP_TRST_N")
	)
	(segment
		(start 411.80893 -134.240524)
		(end 411.80893 -134.699248)
		(width 0.10795)
		(layer "F.Cu")
		(net "XDP_TRST_N")
	)
	(via
		(at 414.060386 -132.234432)
		(size 0.508)
		(drill 0.254)
		(layers "F.Cu" "B.Cu")
		(net "XDP_TRST_N")
	)
	(via
		(at 453.7583 -149.87016)
		(size 0.6604)
		(drill 0.3302)
		(layers "F.Cu" "B.Cu")
		(net "XDP_TRST_N")
	)
	(via
		(at 436.1053 -153.2763)
		(size 0.508)
		(drill 0.254)
		(layers "F.Cu" "B.Cu")
		(net "XDP_TRST_N")
	)
	(via
		(at 455.21118 -148.3106)
		(size 0.508)
		(drill 0.254)
		(layers "F.Cu" "B.Cu")
		(net "XDP_TRST_N")
	)
	(via
		(at 390.70915 -118.670324)
		(size 0.508)
		(drill 0.254)
		(layers "F.Cu" "B.Cu")
		(net "XDP_TRST_N")
	)
	(segment
		(start 455.0664 -152.471882)
		(end 457.515468 -154.92095)
		(width 0.10795)
		(layer "B.Cu")
		(net "XDP_TRST_N")
	)
	(segment
		(start 462.0895 -152.535636)
		(end 461.430116 -151.876252)
		(width 0.10795)
		(layer "B.Cu")
		(net "XDP_TRST_N")
	)
	(segment
		(start 455.168 -148.3106)
		(end 453.7583 -149.7203)
		(width 0.10795)
		(layer "B.Cu")
		(net "XDP_TRST_N")
	)
	(segment
		(start 453.7583 -149.87016)
		(end 454.174352 -150.286212)
		(width 0.10795)
		(layer "B.Cu")
		(net "XDP_TRST_N")
	)
	(segment
		(start 455.45121 -150.675848)
		(end 455.45121 -151.02586)
		(width 0.10795)
		(layer "B.Cu")
		(net "XDP_TRST_N")
	)
	(segment
		(start 455.0664 -151.41067)
		(end 455.0664 -152.471882)
		(width 0.10795)
		(layer "B.Cu")
		(net "XDP_TRST_N")
	)
	(segment
		(start 461.232504 -154.92095)
		(end 462.0895 -154.063954)
		(width 0.10795)
		(layer "B.Cu")
		(net "XDP_TRST_N")
	)
	(segment
		(start 453.7583 -149.7203)
		(end 453.7583 -149.87016)
		(width 0.10795)
		(layer "B.Cu")
		(net "XDP_TRST_N")
	)
	(segment
		(start 455.061574 -150.286212)
		(end 455.45121 -150.675848)
		(width 0.10795)
		(layer "B.Cu")
		(net "XDP_TRST_N")
	)
	(segment
		(start 455.45121 -151.02586)
		(end 455.0664 -151.41067)
		(width 0.10795)
		(layer "B.Cu")
		(net "XDP_TRST_N")
	)
	(segment
		(start 457.515468 -154.92095)
		(end 461.232504 -154.92095)
		(width 0.10795)
		(layer "B.Cu")
		(net "XDP_TRST_N")
	)
	(segment
		(start 436.832502 -153.2763)
		(end 436.1053 -153.2763)
		(width 0.10795)
		(layer "B.Cu")
		(net "XDP_TRST_N")
	)
	(segment
		(start 455.21118 -148.3106)
		(end 455.168 -148.3106)
		(width 0.10795)
		(layer "B.Cu")
		(net "XDP_TRST_N")
	)
	(segment
		(start 454.174352 -150.286212)
		(end 455.061574 -150.286212)
		(width 0.10795)
		(layer "B.Cu")
		(net "XDP_TRST_N")
	)
	(segment
		(start 462.0895 -154.063954)
		(end 462.0895 -152.535636)
		(width 0.10795)
		(layer "B.Cu")
		(net "XDP_TRST_N")
	)
	(segment
		(start 437.339232 -152.76957)
		(end 436.832502 -153.2763)
		(width 0.10795)
		(layer "B.Cu")
		(net "XDP_TRST_N")
	)
	(segment
		(start 392.2903 -122.082814)
		(end 392.2903 -122.125994)
		(width 0.0889)
		(layer "In2.Cu")
		(net "XDP_TRST_N")
	)
	(segment
		(start 395.210284 -126.166118)
		(end 395.510512 -126.466346)
		(width 0.089408)
		(layer "In2.Cu")
		(net "XDP_TRST_N")
	)
	(segment
		(start 454.831704 -141.285976)
		(end 454.422764 -141.694916)
		(width 0.089408)
		(layer "In2.Cu")
		(net "XDP_TRST_N")
	)
	(segment
		(start 447.52006 -133.67766)
		(end 449.29552 -133.67766)
		(width 0.089408)
		(layer "In2.Cu")
		(net "XDP_TRST_N")
	)
	(segment
		(start 446.6336 -132.7912)
		(end 447.52006 -133.67766)
		(width 0.089408)
		(layer "In2.Cu")
		(net "XDP_TRST_N")
	)
	(segment
		(start 408.66949 -129.311908)
		(end 410.025342 -130.66776)
		(width 0.089408)
		(layer "In2.Cu")
		(net "XDP_TRST_N")
	)
	(segment
		(start 433.23256 -131.28752)
		(end 441.54852 -131.28752)
		(width 0.089408)
		(layer "In2.Cu")
		(net "XDP_TRST_N")
	)
	(segment
		(start 417.090098 -130.332734)
		(end 420.482776 -130.332734)
		(width 0.089408)
		(layer "In2.Cu")
		(net "XDP_TRST_N")
	)
	(segment
		(start 395.510512 -126.466346)
		(end 395.510512 -129.542286)
		(width 0.089408)
		(layer "In2.Cu")
		(net "XDP_TRST_N")
	)
	(segment
		(start 391.2997 -120.365774)
		(end 391.2997 -120.39854)
		(width 0.0889)
		(layer "In2.Cu")
		(net "XDP_TRST_N")
	)
	(segment
		(start 454.422764 -146.07413)
		(end 454.997566 -146.648932)
		(width 0.089408)
		(layer "In2.Cu")
		(net "XDP_TRST_N")
	)
	(segment
		(start 413.195516 -132.561076)
		(end 413.733742 -132.561076)
		(width 0.089408)
		(layer "In2.Cu")
		(net "XDP_TRST_N")
	)
	(segment
		(start 392.2903 -124.04979)
		(end 392.536172 -124.295662)
		(width 0.0889)
		(layer "In2.Cu")
		(net "XDP_TRST_N")
	)
	(segment
		(start 411.3022 -130.66776)
		(end 413.195516 -132.561076)
		(width 0.089408)
		(layer "In2.Cu")
		(net "XDP_TRST_N")
	)
	(segment
		(start 454.422764 -141.694916)
		(end 454.422764 -146.07413)
		(width 0.089408)
		(layer "In2.Cu")
		(net "XDP_TRST_N")
	)
	(segment
		(start 420.482776 -130.332734)
		(end 420.949882 -130.79984)
		(width 0.089408)
		(layer "In2.Cu")
		(net "XDP_TRST_N")
	)
	(segment
		(start 452.311008 -134.445248)
		(end 452.311008 -135.656828)
		(width 0.089408)
		(layer "In2.Cu")
		(net "XDP_TRST_N")
	)
	(segment
		(start 433.05476 -131.10972)
		(end 433.23256 -131.28752)
		(width 0.089408)
		(layer "In2.Cu")
		(net "XDP_TRST_N")
	)
	(segment
		(start 410.025342 -130.66776)
		(end 411.3022 -130.66776)
		(width 0.089408)
		(layer "In2.Cu")
		(net "XDP_TRST_N")
	)
	(segment
		(start 441.54852 -131.28752)
		(end 443.0522 -132.7912)
		(width 0.089408)
		(layer "In2.Cu")
		(net "XDP_TRST_N")
	)
	(segment
		(start 390.8044 -119.507254)
		(end 390.8044 -119.54002)
		(width 0.0889)
		(layer "In2.Cu")
		(net "XDP_TRST_N")
	)
	(segment
		(start 454.997566 -146.648932)
		(end 454.997566 -148.096986)
		(width 0.089408)
		(layer "In2.Cu")
		(net "XDP_TRST_N")
	)
	(segment
		(start 395.510512 -129.542286)
		(end 396.336266 -130.36804)
		(width 0.089408)
		(layer "In2.Cu")
		(net "XDP_TRST_N")
	)
	(segment
		(start 450.00418 -132.969)
		(end 450.83476 -132.969)
		(width 0.089408)
		(layer "In2.Cu")
		(net "XDP_TRST_N")
	)
	(segment
		(start 391.795 -122.951748)
		(end 391.795 -122.9741)
		(width 0.0889)
		(layer "In2.Cu")
		(net "XDP_TRST_N")
	)
	(segment
		(start 392.2903 -123.799854)
		(end 392.2903 -124.04979)
		(width 0.0889)
		(layer "In2.Cu")
		(net "XDP_TRST_N")
	)
	(segment
		(start 431.273966 -131.10972)
		(end 433.05476 -131.10972)
		(width 0.089408)
		(layer "In2.Cu")
		(net "XDP_TRST_N")
	)
	(segment
		(start 454.831704 -138.177524)
		(end 454.831704 -141.285976)
		(width 0.089408)
		(layer "In2.Cu")
		(net "XDP_TRST_N")
	)
	(segment
		(start 396.336266 -130.36804)
		(end 400.847306 -130.36804)
		(width 0.089408)
		(layer "In2.Cu")
		(net "XDP_TRST_N")
	)
	(segment
		(start 400.847306 -130.36804)
		(end 401.903438 -129.311908)
		(width 0.089408)
		(layer "In2.Cu")
		(net "XDP_TRST_N")
	)
	(segment
		(start 420.949882 -130.79984)
		(end 430.964086 -130.79984)
		(width 0.089408)
		(layer "In2.Cu")
		(net "XDP_TRST_N")
	)
	(segment
		(start 443.0522 -132.7912)
		(end 446.6336 -132.7912)
		(width 0.089408)
		(layer "In2.Cu")
		(net "XDP_TRST_N")
	)
	(segment
		(start 392.536172 -124.504958)
		(end 394.197332 -126.166118)
		(width 0.089408)
		(layer "In2.Cu")
		(net "XDP_TRST_N")
	)
	(segment
		(start 450.83476 -132.969)
		(end 452.311008 -134.445248)
		(width 0.089408)
		(layer "In2.Cu")
		(net "XDP_TRST_N")
	)
	(segment
		(start 392.536172 -124.295662)
		(end 392.536172 -124.504958)
		(width 0.089408)
		(layer "In2.Cu")
		(net "XDP_TRST_N")
	)
	(segment
		(start 452.311008 -135.656828)
		(end 454.831704 -138.177524)
		(width 0.089408)
		(layer "In2.Cu")
		(net "XDP_TRST_N")
	)
	(segment
		(start 413.733742 -132.561076)
		(end 414.060386 -132.234432)
		(width 0.089408)
		(layer "In2.Cu")
		(net "XDP_TRST_N")
	)
	(segment
		(start 454.997566 -148.096986)
		(end 455.21118 -148.3106)
		(width 0.089408)
		(layer "In2.Cu")
		(net "XDP_TRST_N")
	)
	(segment
		(start 401.903438 -129.311908)
		(end 408.66949 -129.311908)
		(width 0.089408)
		(layer "In2.Cu")
		(net "XDP_TRST_N")
	)
	(segment
		(start 416.200336 -131.222496)
		(end 417.090098 -130.332734)
		(width 0.089408)
		(layer "In2.Cu")
		(net "XDP_TRST_N")
	)
	(segment
		(start 430.964086 -130.79984)
		(end 431.273966 -131.10972)
		(width 0.089408)
		(layer "In2.Cu")
		(net "XDP_TRST_N")
	)
	(segment
		(start 449.29552 -133.67766)
		(end 450.00418 -132.969)
		(width 0.089408)
		(layer "In2.Cu")
		(net "XDP_TRST_N")
	)
	(segment
		(start 415.072322 -131.222496)
		(end 416.200336 -131.222496)
		(width 0.089408)
		(layer "In2.Cu")
		(net "XDP_TRST_N")
	)
	(segment
		(start 391.795 -121.224294)
		(end 391.795 -121.25706)
		(width 0.0889)
		(layer "In2.Cu")
		(net "XDP_TRST_N")
	)
	(segment
		(start 414.060386 -132.234432)
		(end 415.072322 -131.222496)
		(width 0.089408)
		(layer "In2.Cu")
		(net "XDP_TRST_N")
	)
	(segment
		(start 394.197332 -126.166118)
		(end 395.210284 -126.166118)
		(width 0.089408)
		(layer "In2.Cu")
		(net "XDP_TRST_N")
	)
	(arc
		(start 391.2997 -120.39854)
		(mid 391.35605 -120.59239)
		(end 391.499852 -120.734074)
		(width 0.0889)
		(layer "In2.Cu")
		(net "XDP_TRST_N")
	)
	(arc
		(start 391.283698 -120.249188)
		(mid 391.294601 -120.307082)
		(end 391.2997 -120.365774)
		(width 0.0889)
		(layer "In2.Cu")
		(net "XDP_TRST_N")
	)
	(arc
		(start 392.2903 -122.125994)
		(mid 392.206019 -122.409211)
		(end 391.995152 -122.616214)
		(width 0.0889)
		(layer "In2.Cu")
		(net "XDP_TRST_N")
	)
	(arc
		(start 391.995152 -122.616214)
		(mid 391.851348 -122.757897)
		(end 391.795 -122.951748)
		(width 0.0889)
		(layer "In2.Cu")
		(net "XDP_TRST_N")
	)
	(arc
		(start 391.795 -122.9741)
		(mid 391.85135 -123.16795)
		(end 391.995152 -123.309634)
		(width 0.0889)
		(layer "In2.Cu")
		(net "XDP_TRST_N")
	)
	(arc
		(start 391.499852 -120.734074)
		(mid 391.710716 -120.941078)
		(end 391.795 -121.224294)
		(width 0.0889)
		(layer "In2.Cu")
		(net "XDP_TRST_N")
	)
	(arc
		(start 391.995152 -123.309634)
		(mid 392.206016 -123.516638)
		(end 392.2903 -123.799854)
		(width 0.0889)
		(layer "In2.Cu")
		(net "XDP_TRST_N")
	)
	(arc
		(start 391.795 -121.25706)
		(mid 391.85135 -121.45091)
		(end 391.995152 -121.592594)
		(width 0.0889)
		(layer "In2.Cu")
		(net "XDP_TRST_N")
	)
	(arc
		(start 390.70915 -118.670324)
		(mid 390.657106 -118.964036)
		(end 390.73582 -119.25173)
		(width 0.0889)
		(layer "In2.Cu")
		(net "XDP_TRST_N")
	)
	(arc
		(start 391.004552 -119.875554)
		(mid 391.182551 -120.033664)
		(end 391.283698 -120.249188)
		(width 0.0889)
		(layer "In2.Cu")
		(net "XDP_TRST_N")
	)
	(arc
		(start 390.73582 -119.25173)
		(mid 390.784606 -119.375603)
		(end 390.8044 -119.507254)
		(width 0.0889)
		(layer "In2.Cu")
		(net "XDP_TRST_N")
	)
	(arc
		(start 391.995152 -121.592594)
		(mid 392.206016 -121.799598)
		(end 392.2903 -122.082814)
		(width 0.0889)
		(layer "In2.Cu")
		(net "XDP_TRST_N")
	)
	(arc
		(start 390.8044 -119.54002)
		(mid 390.86075 -119.73387)
		(end 391.004552 -119.875554)
		(width 0.0889)
		(layer "In2.Cu")
		(net "XDP_TRST_N")
	)
	(segment
		(start 443.483746 -152.781)
		(end 436.6006 -152.781)
		(width 0.089408)
		(layer "In11.Cu")
		(net "XDP_TRST_N")
	)
	(segment
		(start 455.21118 -148.3106)
		(end 453.17156 -150.35022)
		(width 0.089408)
		(layer "In11.Cu")
		(net "XDP_TRST_N")
	)
	(segment
		(start 436.6006 -152.781)
		(end 436.1053 -153.2763)
		(width 0.089408)
		(layer "In11.Cu")
		(net "XDP_TRST_N")
	)
	(segment
		(start 453.17156 -150.35022)
		(end 452.504048 -150.35022)
		(width 0.089408)
		(layer "In11.Cu")
		(net "XDP_TRST_N")
	)
	(segment
		(start 452.504048 -150.35022)
		(end 451.866762 -150.987506)
		(width 0.089408)
		(layer "In11.Cu")
		(net "XDP_TRST_N")
	)
	(segment
		(start 445.27724 -150.987506)
		(end 443.483746 -152.781)
		(width 0.089408)
		(layer "In11.Cu")
		(net "XDP_TRST_N")
	)
	(segment
		(start 451.866762 -150.987506)
		(end 445.27724 -150.987506)
		(width 0.089408)
		(layer "In11.Cu")
		(net "XDP_TRST_N")
	)
	(segment
		(start 455.998326 -149.719792)
		(end 457.252324 -149.719792)
		(width 0.10795)
		(layer "F.Cu")
		(net "XDP_TMS")
	)
	(segment
		(start 414.410652 -134.146798)
		(end 414.410652 -134.747)
		(width 0.10795)
		(layer "F.Cu")
		(net "XDP_TMS")
	)
	(segment
		(start 454.996042 -150.88362)
		(end 454.996042 -150.722076)
		(width 0.10795)
		(layer "F.Cu")
		(net "XDP_TMS")
	)
	(segment
		(start 414.52165 -134.0358)
		(end 414.410652 -134.146798)
		(width 0.10795)
		(layer "F.Cu")
		(net "XDP_TMS")
	)
	(segment
		(start 454.996042 -150.722076)
		(end 455.998326 -149.719792)
		(width 0.10795)
		(layer "F.Cu")
		(net "XDP_TMS")
	)
	(segment
		(start 386.74675 -117.58168)
		(end 387.24205 -117.811804)
		(width 0.1016)
		(layer "F.Cu")
		(net "XDP_TMS")
	)
	(via
		(at 454.996042 -150.88362)
		(size 0.508)
		(drill 0.254)
		(layers "F.Cu" "B.Cu")
		(net "XDP_TMS")
	)
	(via
		(at 414.52165 -134.0358)
		(size 0.508)
		(drill 0.254)
		(layers "F.Cu" "B.Cu")
		(net "XDP_TMS")
	)
	(via
		(at 448.1322 -145.0086)
		(size 0.508)
		(drill 0.254)
		(layers "F.Cu" "B.Cu")
		(net "XDP_TMS")
	)
	(via
		(at 387.24205 -117.811804)
		(size 0.508)
		(drill 0.254)
		(layers "F.Cu" "B.Cu")
		(net "XDP_TMS")
	)
	(via
		(at 464.111594 -151.747474)
		(size 0.6604)
		(drill 0.3302)
		(layers "F.Cu" "B.Cu")
		(net "XDP_TMS")
	)
	(segment
		(start 454.702418 -152.619964)
		(end 457.403454 -155.321)
		(width 0.10795)
		(layer "B.Cu")
		(net "XDP_TMS")
	)
	(segment
		(start 450.4182 -145.21053)
		(end 449.96862 -144.76095)
		(width 0.10795)
		(layer "B.Cu")
		(net "XDP_TMS")
	)
	(segment
		(start 464.111594 -152.776428)
		(end 464.111594 -151.747474)
		(width 0.10795)
		(layer "B.Cu")
		(net "XDP_TMS")
	)
	(segment
		(start 448.3735 -145.0086)
		(end 448.1322 -145.0086)
		(width 0.10795)
		(layer "B.Cu")
		(net "XDP_TMS")
	)
	(segment
		(start 464.111594 -150.55596)
		(end 464.111594 -151.747474)
		(width 0.10795)
		(layer "B.Cu")
		(net "XDP_TMS")
	)
	(segment
		(start 463.931762 -150.376128)
		(end 464.111594 -150.55596)
		(width 0.10795)
		(layer "B.Cu")
		(net "XDP_TMS")
	)
	(segment
		(start 461.567022 -155.321)
		(end 464.111594 -152.776428)
		(width 0.10795)
		(layer "B.Cu")
		(net "XDP_TMS")
	)
	(segment
		(start 449.96862 -144.76095)
		(end 448.62115 -144.76095)
		(width 0.10795)
		(layer "B.Cu")
		(net "XDP_TMS")
	)
	(segment
		(start 454.996042 -150.88362)
		(end 454.702418 -151.177244)
		(width 0.10795)
		(layer "B.Cu")
		(net "XDP_TMS")
	)
	(segment
		(start 457.403454 -155.321)
		(end 461.567022 -155.321)
		(width 0.10795)
		(layer "B.Cu")
		(net "XDP_TMS")
	)
	(segment
		(start 461.430116 -150.376128)
		(end 463.931762 -150.376128)
		(width 0.10795)
		(layer "B.Cu")
		(net "XDP_TMS")
	)
	(segment
		(start 454.702418 -151.177244)
		(end 454.702418 -152.619964)
		(width 0.10795)
		(layer "B.Cu")
		(net "XDP_TMS")
	)
	(segment
		(start 448.62115 -144.76095)
		(end 448.3735 -145.0086)
		(width 0.10795)
		(layer "B.Cu")
		(net "XDP_TMS")
	)
	(segment
		(start 387.24205 -117.811804)
		(end 386.90423 -117.811804)
		(width 0.089408)
		(layer "In2.Cu")
		(net "XDP_TMS")
	)
	(segment
		(start 415.800286 -132.55371)
		(end 414.52165 -133.832346)
		(width 0.089408)
		(layer "In2.Cu")
		(net "XDP_TMS")
	)
	(segment
		(start 448.1322 -145.0086)
		(end 447.929 -145.2118)
		(width 0.089408)
		(layer "In2.Cu")
		(net "XDP_TMS")
	)
	(segment
		(start 436.251096 -133.195822)
		(end 430.633886 -133.195822)
		(width 0.089408)
		(layer "In2.Cu")
		(net "XDP_TMS")
	)
	(segment
		(start 447.166238 -134.8486)
		(end 437.903874 -134.8486)
		(width 0.089408)
		(layer "In2.Cu")
		(net "XDP_TMS")
	)
	(segment
		(start 447.3956 -145.2118)
		(end 447.1416 -145.4658)
		(width 0.089408)
		(layer "In2.Cu")
		(net "XDP_TMS")
	)
	(segment
		(start 447.783712 -144.660112)
		(end 447.783712 -137.25144)
		(width 0.089408)
		(layer "In2.Cu")
		(net "XDP_TMS")
	)
	(segment
		(start 389.3185 -123.799854)
		(end 389.3185 -123.83262)
		(width 0.0889)
		(layer "In2.Cu")
		(net "XDP_TMS")
	)
	(segment
		(start 387.3373 -118.648734)
		(end 387.3373 -118.6815)
		(width 0.0889)
		(layer "In2.Cu")
		(net "XDP_TMS")
	)
	(segment
		(start 448.250818 -136.784334)
		(end 448.250818 -135.93318)
		(width 0.089408)
		(layer "In2.Cu")
		(net "XDP_TMS")
	)
	(segment
		(start 447.929 -145.2118)
		(end 447.3956 -145.2118)
		(width 0.089408)
		(layer "In2.Cu")
		(net "XDP_TMS")
	)
	(segment
		(start 387.8326 -119.507254)
		(end 387.8326 -119.54002)
		(width 0.0889)
		(layer "In2.Cu")
		(net "XDP_TMS")
	)
	(segment
		(start 411.08503 -134.71017)
		(end 413.84728 -134.71017)
		(width 0.089408)
		(layer "In2.Cu")
		(net "XDP_TMS")
	)
	(segment
		(start 402.387054 -130.556)
		(end 407.990802 -130.556)
		(width 0.089408)
		(layer "In2.Cu")
		(net "XDP_TMS")
	)
	(segment
		(start 390.7536 -125.421898)
		(end 390.7536 -130.3274)
		(width 0.089408)
		(layer "In2.Cu")
		(net "XDP_TMS")
	)
	(segment
		(start 437.903874 -134.8486)
		(end 436.251096 -133.195822)
		(width 0.089408)
		(layer "In2.Cu")
		(net "XDP_TMS")
	)
	(segment
		(start 447.1416 -147.2946)
		(end 451.104 -151.257)
		(width 0.089408)
		(layer "In2.Cu")
		(net "XDP_TMS")
	)
	(segment
		(start 430.633886 -133.195822)
		(end 429.408336 -131.970272)
		(width 0.089408)
		(layer "In2.Cu")
		(net "XDP_TMS")
	)
	(segment
		(start 447.783712 -137.25144)
		(end 448.250818 -136.784334)
		(width 0.089408)
		(layer "In2.Cu")
		(net "XDP_TMS")
	)
	(segment
		(start 454.622662 -151.257)
		(end 454.996042 -150.88362)
		(width 0.089408)
		(layer "In2.Cu")
		(net "XDP_TMS")
	)
	(segment
		(start 451.104 -151.257)
		(end 454.622662 -151.257)
		(width 0.089408)
		(layer "In2.Cu")
		(net "XDP_TMS")
	)
	(segment
		(start 448.1322 -145.0086)
		(end 447.783712 -144.660112)
		(width 0.089408)
		(layer "In2.Cu")
		(net "XDP_TMS")
	)
	(segment
		(start 401.353782 -131.589272)
		(end 402.387054 -130.556)
		(width 0.089408)
		(layer "In2.Cu")
		(net "XDP_TMS")
	)
	(segment
		(start 407.990802 -130.556)
		(end 409.776168 -132.341366)
		(width 0.089408)
		(layer "In2.Cu")
		(net "XDP_TMS")
	)
	(segment
		(start 448.250818 -135.93318)
		(end 447.166238 -134.8486)
		(width 0.089408)
		(layer "In2.Cu")
		(net "XDP_TMS")
	)
	(segment
		(start 409.776168 -132.341366)
		(end 409.776168 -133.401308)
		(width 0.089408)
		(layer "In2.Cu")
		(net "XDP_TMS")
	)
	(segment
		(start 414.52165 -133.832346)
		(end 414.52165 -134.0358)
		(width 0.089408)
		(layer "In2.Cu")
		(net "XDP_TMS")
	)
	(segment
		(start 447.1416 -145.4658)
		(end 447.1416 -147.2946)
		(width 0.089408)
		(layer "In2.Cu")
		(net "XDP_TMS")
	)
	(segment
		(start 390.7536 -130.3274)
		(end 392.015472 -131.589272)
		(width 0.089408)
		(layer "In2.Cu")
		(net "XDP_TMS")
	)
	(segment
		(start 392.015472 -131.589272)
		(end 401.353782 -131.589272)
		(width 0.089408)
		(layer "In2.Cu")
		(net "XDP_TMS")
	)
	(segment
		(start 419.421818 -132.55371)
		(end 415.800286 -132.55371)
		(width 0.089408)
		(layer "In2.Cu")
		(net "XDP_TMS")
	)
	(segment
		(start 413.84728 -134.71017)
		(end 414.52165 -134.0358)
		(width 0.089408)
		(layer "In2.Cu")
		(net "XDP_TMS")
	)
	(segment
		(start 386.90423 -117.811804)
		(end 386.846318 -117.869716)
		(width 0.089408)
		(layer "In2.Cu")
		(net "XDP_TMS")
	)
	(segment
		(start 420.005256 -131.970272)
		(end 419.421818 -132.55371)
		(width 0.089408)
		(layer "In2.Cu")
		(net "XDP_TMS")
	)
	(segment
		(start 389.422386 -124.090684)
		(end 390.7536 -125.421898)
		(width 0.089408)
		(layer "In2.Cu")
		(net "XDP_TMS")
	)
	(segment
		(start 429.408336 -131.970272)
		(end 420.005256 -131.970272)
		(width 0.089408)
		(layer "In2.Cu")
		(net "XDP_TMS")
	)
	(segment
		(start 388.3279 -120.365774)
		(end 388.3279 -120.39854)
		(width 0.0889)
		(layer "In2.Cu")
		(net "XDP_TMS")
	)
	(segment
		(start 409.776168 -133.401308)
		(end 411.08503 -134.71017)
		(width 0.089408)
		(layer "In2.Cu")
		(net "XDP_TMS")
	)
	(segment
		(start 388.8232 -121.224294)
		(end 388.8232 -121.25706)
		(width 0.0889)
		(layer "In2.Cu")
		(net "XDP_TMS")
	)
	(arc
		(start 388.528052 -120.734074)
		(mid 388.738916 -120.941078)
		(end 388.8232 -121.224294)
		(width 0.0889)
		(layer "In2.Cu")
		(net "XDP_TMS")
	)
	(arc
		(start 387.3373 -118.6815)
		(mid 387.39365 -118.87535)
		(end 387.537452 -119.017034)
		(width 0.0889)
		(layer "In2.Cu")
		(net "XDP_TMS")
	)
	(arc
		(start 389.3185 -122.082814)
		(mid 389.31348 -122.183927)
		(end 389.291322 -122.282712)
		(width 0.0889)
		(layer "In2.Cu")
		(net "XDP_TMS")
	)
	(arc
		(start 387.042152 -118.15826)
		(mid 387.257867 -118.362503)
		(end 387.3373 -118.648734)
		(width 0.0889)
		(layer "In2.Cu")
		(net "XDP_TMS")
	)
	(arc
		(start 389.3185 -123.83262)
		(mid 389.345452 -123.971709)
		(end 389.422386 -124.090684)
		(width 0.0889)
		(layer "In2.Cu")
		(net "XDP_TMS")
	)
	(arc
		(start 389.291322 -122.282712)
		(mid 389.188569 -122.474555)
		(end 389.023352 -122.616214)
		(width 0.0889)
		(layer "In2.Cu")
		(net "XDP_TMS")
	)
	(arc
		(start 388.032752 -119.875554)
		(mid 388.243616 -120.082558)
		(end 388.3279 -120.365774)
		(width 0.0889)
		(layer "In2.Cu")
		(net "XDP_TMS")
	)
	(arc
		(start 388.8232 -121.25706)
		(mid 388.87955 -121.45091)
		(end 389.023352 -121.592594)
		(width 0.0889)
		(layer "In2.Cu")
		(net "XDP_TMS")
	)
	(arc
		(start 387.8326 -119.54002)
		(mid 387.88895 -119.73387)
		(end 388.032752 -119.875554)
		(width 0.0889)
		(layer "In2.Cu")
		(net "XDP_TMS")
	)
	(arc
		(start 387.537452 -119.017034)
		(mid 387.748316 -119.224038)
		(end 387.8326 -119.507254)
		(width 0.0889)
		(layer "In2.Cu")
		(net "XDP_TMS")
	)
	(arc
		(start 386.846318 -117.869716)
		(mid 386.911147 -118.036439)
		(end 387.042152 -118.15826)
		(width 0.089408)
		(layer "In2.Cu")
		(net "XDP_TMS")
	)
	(arc
		(start 389.023352 -123.309634)
		(mid 389.234216 -123.516638)
		(end 389.3185 -123.799854)
		(width 0.0889)
		(layer "In2.Cu")
		(net "XDP_TMS")
	)
	(arc
		(start 388.3279 -120.39854)
		(mid 388.38425 -120.59239)
		(end 388.528052 -120.734074)
		(width 0.0889)
		(layer "In2.Cu")
		(net "XDP_TMS")
	)
	(arc
		(start 389.023352 -121.592594)
		(mid 389.234216 -121.799598)
		(end 389.3185 -122.082814)
		(width 0.0889)
		(layer "In2.Cu")
		(net "XDP_TMS")
	)
	(arc
		(start 389.023352 -122.616214)
		(mid 388.823041 -122.962924)
		(end 389.023352 -123.309634)
		(width 0.0889)
		(layer "In2.Cu")
		(net "XDP_TMS")
	)
	(segment
		(start 452.2089 -151.0157)
		(end 454.2282 -148.9964)
		(width 0.10795)
		(layer "F.Cu")
		(net "XDP_TDO")
	)
	(segment
		(start 454.2282 -148.285454)
		(end 454.2282 -148.6154)
		(width 0.10795)
		(layer "F.Cu")
		(net "XDP_TDO")
	)
	(segment
		(start 457.252324 -148.219922)
		(end 455.957686 -148.219922)
		(width 0.10795)
		(layer "F.Cu")
		(net "XDP_TDO")
	)
	(segment
		(start 455.686414 -147.94865)
		(end 455.669396 -147.94865)
		(width 0.10795)
		(layer "F.Cu")
		(net "XDP_TDO")
	)
	(segment
		(start 454.6854 -147.828254)
		(end 454.2282 -148.285454)
		(width 0.10795)
		(layer "F.Cu")
		(net "XDP_TDO")
	)
	(segment
		(start 455.549 -147.828254)
		(end 454.6854 -147.828254)
		(width 0.10795)
		(layer "F.Cu")
		(net "XDP_TDO")
	)
	(segment
		(start 389.22325 -118.4402)
		(end 389.715248 -118.6688)
		(width 0.1016)
		(layer "F.Cu")
		(net "XDP_TDO")
	)
	(segment
		(start 455.957686 -148.219922)
		(end 455.686414 -147.94865)
		(width 0.10795)
		(layer "F.Cu")
		(net "XDP_TDO")
	)
	(segment
		(start 454.2282 -148.9964)
		(end 454.2282 -148.6154)
		(width 0.10795)
		(layer "F.Cu")
		(net "XDP_TDO")
	)
	(segment
		(start 389.715248 -118.6688)
		(end 389.71855 -118.670324)
		(width 0.1016)
		(layer "F.Cu")
		(net "XDP_TDO")
	)
	(segment
		(start 450.1642 -151.0157)
		(end 452.2089 -151.0157)
		(width 0.10795)
		(layer "F.Cu")
		(net "XDP_TDO")
	)
	(segment
		(start 455.669396 -147.94865)
		(end 455.549 -147.828254)
		(width 0.10795)
		(layer "F.Cu")
		(net "XDP_TDO")
	)
	(via
		(at 454.2282 -148.6154)
		(size 0.508)
		(drill 0.254)
		(layers "F.Cu" "B.Cu")
		(net "XDP_TDO")
	)
	(via
		(at 389.71855 -118.670324)
		(size 0.508)
		(drill 0.254)
		(layers "F.Cu" "B.Cu")
		(net "XDP_TDO")
	)
	(segment
		(start 455.536554 -147.5486)
		(end 457.86421 -149.876256)
		(width 0.10795)
		(layer "B.Cu")
		(net "XDP_TDO")
	)
	(segment
		(start 454.5838 -148.2598)
		(end 454.5838 -147.5486)
		(width 0.10795)
		(layer "B.Cu")
		(net "XDP_TDO")
	)
	(segment
		(start 454.2282 -148.6154)
		(end 454.5838 -148.2598)
		(width 0.10795)
		(layer "B.Cu")
		(net "XDP_TDO")
	)
	(segment
		(start 457.86421 -149.876256)
		(end 458.3303 -149.876256)
		(width 0.10795)
		(layer "B.Cu")
		(net "XDP_TDO")
	)
	(segment
		(start 454.5838 -147.5486)
		(end 455.536554 -147.5486)
		(width 0.10795)
		(layer "B.Cu")
		(net "XDP_TDO")
	)
	(segment
		(start 412.735268 -133.906514)
		(end 412.92272 -133.719062)
		(width 0.089408)
		(layer "In2.Cu")
		(net "XDP_TDO")
	)
	(segment
		(start 391.2997 -122.082814)
		(end 391.2997 -122.125994)
		(width 0.0889)
		(layer "In2.Cu")
		(net "XDP_TDO")
	)
	(segment
		(start 391.2997 -124.311918)
		(end 391.46861 -124.480828)
		(width 0.0889)
		(layer "In2.Cu")
		(net "XDP_TDO")
	)
	(segment
		(start 438.146698 -134.263384)
		(end 447.771266 -134.263384)
		(width 0.089408)
		(layer "In2.Cu")
		(net "XDP_TDO")
	)
	(segment
		(start 408.24404 -129.945384)
		(end 410.412184 -132.113528)
		(width 0.089408)
		(layer "In2.Cu")
		(net "XDP_TDO")
	)
	(segment
		(start 389.71855 -118.670324)
		(end 389.71855 -119.599456)
		(width 0.089408)
		(layer "In2.Cu")
		(net "XDP_TDO")
	)
	(segment
		(start 393.586208 -130.953256)
		(end 401.09013 -130.953256)
		(width 0.089408)
		(layer "In2.Cu")
		(net "XDP_TDO")
	)
	(segment
		(start 430.721262 -131.385056)
		(end 431.031142 -131.694936)
		(width 0.089408)
		(layer "In2.Cu")
		(net "XDP_TDO")
	)
	(segment
		(start 413.58185 -133.732016)
		(end 415.477452 -131.836414)
		(width 0.089408)
		(layer "In2.Cu")
		(net "XDP_TDO")
	)
	(segment
		(start 402.098002 -129.945384)
		(end 408.24404 -129.945384)
		(width 0.089408)
		(layer "In2.Cu")
		(net "XDP_TDO")
	)
	(segment
		(start 436.429912 -132.546598)
		(end 438.146698 -134.263384)
		(width 0.089408)
		(layer "In2.Cu")
		(net "XDP_TDO")
	)
	(segment
		(start 432.811936 -131.694936)
		(end 433.663598 -132.546598)
		(width 0.089408)
		(layer "In2.Cu")
		(net "XDP_TDO")
	)
	(segment
		(start 419.212014 -131.836414)
		(end 419.663372 -131.385056)
		(width 0.089408)
		(layer "In2.Cu")
		(net "XDP_TDO")
	)
	(segment
		(start 413.237172 -133.719062)
		(end 413.250126 -133.732016)
		(width 0.089408)
		(layer "In2.Cu")
		(net "XDP_TDO")
	)
	(segment
		(start 447.771266 -134.263384)
		(end 448.836034 -135.328152)
		(width 0.089408)
		(layer "In2.Cu")
		(net "XDP_TDO")
	)
	(segment
		(start 419.663372 -131.385056)
		(end 430.721262 -131.385056)
		(width 0.089408)
		(layer "In2.Cu")
		(net "XDP_TDO")
	)
	(segment
		(start 389.71855 -119.599456)
		(end 389.935466 -119.816372)
		(width 0.089408)
		(layer "In2.Cu")
		(net "XDP_TDO")
	)
	(segment
		(start 449.775834 -144.399)
		(end 451.34657 -145.969736)
		(width 0.089408)
		(layer "In2.Cu")
		(net "XDP_TDO")
	)
	(segment
		(start 392.61034 -125.622558)
		(end 392.61034 -129.977388)
		(width 0.089408)
		(layer "In2.Cu")
		(net "XDP_TDO")
	)
	(segment
		(start 392.61034 -129.977388)
		(end 393.586208 -130.953256)
		(width 0.089408)
		(layer "In2.Cu")
		(net "XDP_TDO")
	)
	(segment
		(start 433.663598 -132.546598)
		(end 436.429912 -132.546598)
		(width 0.089408)
		(layer "In2.Cu")
		(net "XDP_TDO")
	)
	(segment
		(start 413.250126 -133.732016)
		(end 413.58185 -133.732016)
		(width 0.089408)
		(layer "In2.Cu")
		(net "XDP_TDO")
	)
	(segment
		(start 410.412184 -132.113528)
		(end 410.412184 -132.929376)
		(width 0.089408)
		(layer "In2.Cu")
		(net "XDP_TDO")
	)
	(segment
		(start 448.836034 -135.328152)
		(end 448.836034 -137.027158)
		(width 0.089408)
		(layer "In2.Cu")
		(net "XDP_TDO")
	)
	(segment
		(start 454.2282 -146.9644)
		(end 454.2282 -148.6154)
		(width 0.089408)
		(layer "In2.Cu")
		(net "XDP_TDO")
	)
	(segment
		(start 391.46861 -124.480828)
		(end 392.61034 -125.622558)
		(width 0.089408)
		(layer "In2.Cu")
		(net "XDP_TDO")
	)
	(segment
		(start 448.836034 -137.027158)
		(end 448.368928 -137.494264)
		(width 0.089408)
		(layer "In2.Cu")
		(net "XDP_TDO")
	)
	(segment
		(start 411.389322 -133.906514)
		(end 412.735268 -133.906514)
		(width 0.089408)
		(layer "In2.Cu")
		(net "XDP_TDO")
	)
	(segment
		(start 448.368928 -144.220692)
		(end 448.547236 -144.399)
		(width 0.089408)
		(layer "In2.Cu")
		(net "XDP_TDO")
	)
	(segment
		(start 391.2997 -123.799854)
		(end 391.2997 -124.311918)
		(width 0.0889)
		(layer "In2.Cu")
		(net "XDP_TDO")
	)
	(segment
		(start 390.8044 -121.224294)
		(end 390.8044 -121.25706)
		(width 0.0889)
		(layer "In2.Cu")
		(net "XDP_TDO")
	)
	(segment
		(start 448.368928 -137.494264)
		(end 448.368928 -144.220692)
		(width 0.089408)
		(layer "In2.Cu")
		(net "XDP_TDO")
	)
	(segment
		(start 448.547236 -144.399)
		(end 449.775834 -144.399)
		(width 0.089408)
		(layer "In2.Cu")
		(net "XDP_TDO")
	)
	(segment
		(start 451.34657 -145.969736)
		(end 453.233536 -145.969736)
		(width 0.089408)
		(layer "In2.Cu")
		(net "XDP_TDO")
	)
	(segment
		(start 453.233536 -145.969736)
		(end 454.2282 -146.9644)
		(width 0.089408)
		(layer "In2.Cu")
		(net "XDP_TDO")
	)
	(segment
		(start 390.3091 -120.365774)
		(end 390.3091 -120.39854)
		(width 0.0889)
		(layer "In2.Cu")
		(net "XDP_TDO")
	)
	(segment
		(start 431.031142 -131.694936)
		(end 432.811936 -131.694936)
		(width 0.089408)
		(layer "In2.Cu")
		(net "XDP_TDO")
	)
	(segment
		(start 415.477452 -131.836414)
		(end 419.212014 -131.836414)
		(width 0.089408)
		(layer "In2.Cu")
		(net "XDP_TDO")
	)
	(segment
		(start 401.09013 -130.953256)
		(end 402.098002 -129.945384)
		(width 0.089408)
		(layer "In2.Cu")
		(net "XDP_TDO")
	)
	(segment
		(start 410.412184 -132.929376)
		(end 411.389322 -133.906514)
		(width 0.089408)
		(layer "In2.Cu")
		(net "XDP_TDO")
	)
	(segment
		(start 412.92272 -133.719062)
		(end 413.237172 -133.719062)
		(width 0.089408)
		(layer "In2.Cu")
		(net "XDP_TDO")
	)
	(arc
		(start 390.3091 -120.39854)
		(mid 390.36545 -120.59239)
		(end 390.509252 -120.734074)
		(width 0.0889)
		(layer "In2.Cu")
		(net "XDP_TDO")
	)
	(arc
		(start 391.004552 -122.616214)
		(mid 390.804241 -122.962924)
		(end 391.004552 -123.309634)
		(width 0.0889)
		(layer "In2.Cu")
		(net "XDP_TDO")
	)
	(arc
		(start 390.8044 -121.25706)
		(mid 390.86075 -121.45091)
		(end 391.004552 -121.592594)
		(width 0.0889)
		(layer "In2.Cu")
		(net "XDP_TDO")
	)
	(arc
		(start 391.004552 -121.592594)
		(mid 391.215416 -121.799598)
		(end 391.2997 -122.082814)
		(width 0.0889)
		(layer "In2.Cu")
		(net "XDP_TDO")
	)
	(arc
		(start 390.509252 -120.734074)
		(mid 390.720116 -120.941078)
		(end 390.8044 -121.224294)
		(width 0.0889)
		(layer "In2.Cu")
		(net "XDP_TDO")
	)
	(arc
		(start 391.2997 -122.125994)
		(mid 391.215419 -122.409211)
		(end 391.004552 -122.616214)
		(width 0.0889)
		(layer "In2.Cu")
		(net "XDP_TDO")
	)
	(arc
		(start 390.013952 -119.875554)
		(mid 390.224816 -120.082558)
		(end 390.3091 -120.365774)
		(width 0.0889)
		(layer "In2.Cu")
		(net "XDP_TDO")
	)
	(arc
		(start 389.935466 -119.816372)
		(mid 389.972884 -119.848383)
		(end 390.013952 -119.875554)
		(width 0.0889)
		(layer "In2.Cu")
		(net "XDP_TDO")
	)
	(arc
		(start 391.004552 -123.309634)
		(mid 391.215416 -123.516638)
		(end 391.2997 -123.799854)
		(width 0.0889)
		(layer "In2.Cu")
		(net "XDP_TDO")
	)
	(segment
		(start 413.415988 -133.724142)
		(end 413.568134 -133.876288)
		(width 0.10795)
		(layer "F.Cu")
		(net "XDP_TDI")
	)
	(segment
		(start 455.569066 -149.636988)
		(end 455.986134 -149.21992)
		(width 0.10795)
		(layer "F.Cu")
		(net "XDP_TDI")
	)
	(segment
		(start 413.521652 -134.356348)
		(end 413.521652 -134.747)
		(width 0.10795)
		(layer "F.Cu")
		(net "XDP_TDI")
	)
	(segment
		(start 388.72795 -117.58168)
		(end 388.728204 -117.58168)
		(width 0.1016)
		(layer "F.Cu")
		(net "XDP_TDI")
	)
	(segment
		(start 413.568134 -133.876288)
		(end 413.568134 -134.309866)
		(width 0.10795)
		(layer "F.Cu")
		(net "XDP_TDI")
	)
	(segment
		(start 455.986134 -149.21992)
		(end 457.252324 -149.21992)
		(width 0.10795)
		(layer "F.Cu")
		(net "XDP_TDI")
	)
	(segment
		(start 455.002646 -149.636988)
		(end 455.569066 -149.636988)
		(width 0.10795)
		(layer "F.Cu")
		(net "XDP_TDI")
	)
	(segment
		(start 413.568134 -134.309866)
		(end 413.521652 -134.356348)
		(width 0.10795)
		(layer "F.Cu")
		(net "XDP_TDI")
	)
	(segment
		(start 388.728204 -117.58168)
		(end 389.22325 -117.811804)
		(width 0.1016)
		(layer "F.Cu")
		(net "XDP_TDI")
	)
	(segment
		(start 413.415988 -133.331712)
		(end 413.415988 -133.724142)
		(width 0.10795)
		(layer "F.Cu")
		(net "XDP_TDI")
	)
	(via
		(at 389.22325 -117.811804)
		(size 0.508)
		(drill 0.254)
		(layers "F.Cu" "B.Cu")
		(net "XDP_TDI")
	)
	(via
		(at 455.002646 -149.636988)
		(size 0.508)
		(drill 0.254)
		(layers "F.Cu" "B.Cu")
		(net "XDP_TDI")
	)
	(via
		(at 448.952366 -143.8148)
		(size 0.508)
		(drill 0.254)
		(layers "F.Cu" "B.Cu")
		(net "XDP_TDI")
	)
	(via
		(at 413.415988 -133.331712)
		(size 0.508)
		(drill 0.254)
		(layers "F.Cu" "B.Cu")
		(net "XDP_TDI")
	)
	(segment
		(start 449.320666 -144.1831)
		(end 448.952366 -143.8148)
		(width 0.10795)
		(layer "B.Cu")
		(net "XDP_TDI")
	)
	(segment
		(start 456.6412 -151.841454)
		(end 457.543154 -151.841454)
		(width 0.10795)
		(layer "B.Cu")
		(net "XDP_TDI")
	)
	(segment
		(start 450.4182 -144.1831)
		(end 449.320666 -144.1831)
		(width 0.10795)
		(layer "B.Cu")
		(net "XDP_TDI")
	)
	(segment
		(start 458.008228 -151.37638)
		(end 458.3303 -151.37638)
		(width 0.10795)
		(layer "B.Cu")
		(net "XDP_TDI")
	)
	(segment
		(start 455.93 -151.130254)
		(end 456.6412 -151.841454)
		(width 0.10795)
		(layer "B.Cu")
		(net "XDP_TDI")
	)
	(segment
		(start 455.93 -150.564342)
		(end 455.93 -151.130254)
		(width 0.10795)
		(layer "B.Cu")
		(net "XDP_TDI")
	)
	(segment
		(start 457.543154 -151.841454)
		(end 458.008228 -151.37638)
		(width 0.10795)
		(layer "B.Cu")
		(net "XDP_TDI")
	)
	(segment
		(start 455.002646 -149.636988)
		(end 455.93 -150.564342)
		(width 0.10795)
		(layer "B.Cu")
		(net "XDP_TDI")
	)
	(segment
		(start 394.01242 -129.689606)
		(end 394.012166 -129.68986)
		(width 0.089408)
		(layer "In2.Cu")
		(net "XDP_TDI")
	)
	(segment
		(start 419.090602 -131.543806)
		(end 415.318194 -131.543806)
		(width 0.089408)
		(layer "In2.Cu")
		(net "XDP_TDI")
	)
	(segment
		(start 415.318194 -131.543806)
		(end 413.530288 -133.331712)
		(width 0.089408)
		(layer "In2.Cu")
		(net "XDP_TDI")
	)
	(segment
		(start 413.530288 -133.331712)
		(end 413.415988 -133.331712)
		(width 0.089408)
		(layer "In2.Cu")
		(net "XDP_TDI")
	)
	(segment
		(start 431.152554 -131.402328)
		(end 430.842674 -131.092448)
		(width 0.089408)
		(layer "In2.Cu")
		(net "XDP_TDI")
	)
	(segment
		(start 391.1092 -120.376188)
		(end 391.1092 -120.408954)
		(width 0.0889)
		(layer "In2.Cu")
		(net "XDP_TDI")
	)
	(segment
		(start 389.39216 -118.10492)
		(end 389.481568 -118.128796)
		(width 0.0889)
		(layer "In2.Cu")
		(net "XDP_TDI")
	)
	(segment
		(start 392.0998 -124.7902)
		(end 394.01242 -126.70282)
		(width 0.089408)
		(layer "In2.Cu")
		(net "XDP_TDI")
	)
	(segment
		(start 433.487322 -131.580382)
		(end 433.487068 -131.580128)
		(width 0.089408)
		(layer "In2.Cu")
		(net "XDP_TDI")
	)
	(segment
		(start 411.044644 -130.960368)
		(end 413.415988 -133.331712)
		(width 0.089408)
		(layer "In2.Cu")
		(net "XDP_TDI")
	)
	(segment
		(start 394.012166 -129.932176)
		(end 394.740638 -130.660648)
		(width 0.089408)
		(layer "In2.Cu")
		(net "XDP_TDI")
	)
	(segment
		(start 448.952366 -143.8148)
		(end 449.4022 -143.364966)
		(width 0.089408)
		(layer "In2.Cu")
		(net "XDP_TDI")
	)
	(segment
		(start 394.012166 -129.68986)
		(end 394.012166 -129.932176)
		(width 0.089408)
		(layer "In2.Cu")
		(net "XDP_TDI")
	)
	(segment
		(start 394.740638 -130.660648)
		(end 400.968718 -130.660648)
		(width 0.089408)
		(layer "In2.Cu")
		(net "XDP_TDI")
	)
	(segment
		(start 435.877716 -131.580382)
		(end 433.487322 -131.580382)
		(width 0.089408)
		(layer "In2.Cu")
		(net "XDP_TDI")
	)
	(segment
		(start 390.3091 -118.648734)
		(end 390.3091 -118.691914)
		(width 0.0889)
		(layer "In2.Cu")
		(net "XDP_TDI")
	)
	(segment
		(start 394.01242 -126.70282)
		(end 394.01242 -129.689606)
		(width 0.089408)
		(layer "In2.Cu")
		(net "XDP_TDI")
	)
	(segment
		(start 448.661536 -137.615676)
		(end 449.128642 -137.14857)
		(width 0.089408)
		(layer "In2.Cu")
		(net "XDP_TDI")
	)
	(segment
		(start 392.0998 -122.093228)
		(end 392.0998 -122.11558)
		(width 0.0889)
		(layer "In2.Cu")
		(net "XDP_TDI")
	)
	(segment
		(start 408.548078 -129.604516)
		(end 409.90393 -130.960368)
		(width 0.089408)
		(layer "In2.Cu")
		(net "XDP_TDI")
	)
	(segment
		(start 447.892678 -133.970776)
		(end 438.26811 -133.970776)
		(width 0.089408)
		(layer "In2.Cu")
		(net "XDP_TDI")
	)
	(segment
		(start 391.6045 -121.234708)
		(end 391.6045 -121.267474)
		(width 0.0889)
		(layer "In2.Cu")
		(net "XDP_TDI")
	)
	(segment
		(start 392.0998 -124.14758)
		(end 392.0998 -124.7902)
		(width 0.089408)
		(layer "In2.Cu")
		(net "XDP_TDI")
	)
	(segment
		(start 449.128642 -137.14857)
		(end 449.128642 -135.20674)
		(width 0.089408)
		(layer "In2.Cu")
		(net "XDP_TDI")
	)
	(segment
		(start 449.128642 -135.20674)
		(end 447.892678 -133.970776)
		(width 0.089408)
		(layer "In2.Cu")
		(net "XDP_TDI")
	)
	(segment
		(start 454.69175 -147.01393)
		(end 454.69175 -149.326092)
		(width 0.089408)
		(layer "In2.Cu")
		(net "XDP_TDI")
	)
	(segment
		(start 392.0998 -123.810268)
		(end 392.0998 -124.14758)
		(width 0.0889)
		(layer "In2.Cu")
		(net "XDP_TDI")
	)
	(segment
		(start 409.90393 -130.960368)
		(end 411.044644 -130.960368)
		(width 0.089408)
		(layer "In2.Cu")
		(net "XDP_TDI")
	)
	(segment
		(start 430.842674 -131.092448)
		(end 419.54196 -131.092448)
		(width 0.089408)
		(layer "In2.Cu")
		(net "XDP_TDI")
	)
	(segment
		(start 419.54196 -131.092448)
		(end 419.090602 -131.543806)
		(width 0.089408)
		(layer "In2.Cu")
		(net "XDP_TDI")
	)
	(segment
		(start 448.952366 -143.8148)
		(end 449.685156 -143.8148)
		(width 0.089408)
		(layer "In2.Cu")
		(net "XDP_TDI")
	)
	(segment
		(start 433.487068 -131.580128)
		(end 433.111148 -131.580128)
		(width 0.089408)
		(layer "In2.Cu")
		(net "XDP_TDI")
	)
	(segment
		(start 402.02485 -129.604516)
		(end 408.548078 -129.604516)
		(width 0.089408)
		(layer "In2.Cu")
		(net "XDP_TDI")
	)
	(segment
		(start 449.685156 -143.8148)
		(end 451.547484 -145.677128)
		(width 0.089408)
		(layer "In2.Cu")
		(net "XDP_TDI")
	)
	(segment
		(start 438.26811 -133.970776)
		(end 435.877716 -131.580382)
		(width 0.089408)
		(layer "In2.Cu")
		(net "XDP_TDI")
	)
	(segment
		(start 454.69175 -149.326092)
		(end 455.002646 -149.636988)
		(width 0.089408)
		(layer "In2.Cu")
		(net "XDP_TDI")
	)
	(segment
		(start 400.968718 -130.660648)
		(end 402.02485 -129.604516)
		(width 0.089408)
		(layer "In2.Cu")
		(net "XDP_TDI")
	)
	(segment
		(start 432.933348 -131.402328)
		(end 431.152554 -131.402328)
		(width 0.089408)
		(layer "In2.Cu")
		(net "XDP_TDI")
	)
	(segment
		(start 391.6045 -122.941334)
		(end 391.6045 -122.984514)
		(width 0.0889)
		(layer "In2.Cu")
		(net "XDP_TDI")
	)
	(segment
		(start 448.661536 -140.217906)
		(end 448.661536 -137.615676)
		(width 0.089408)
		(layer "In2.Cu")
		(net "XDP_TDI")
	)
	(segment
		(start 451.547484 -145.677128)
		(end 453.354948 -145.677128)
		(width 0.089408)
		(layer "In2.Cu")
		(net "XDP_TDI")
	)
	(segment
		(start 390.6139 -119.517668)
		(end 390.6139 -119.550434)
		(width 0.0889)
		(layer "In2.Cu")
		(net "XDP_TDI")
	)
	(segment
		(start 433.111148 -131.580128)
		(end 432.933348 -131.402328)
		(width 0.089408)
		(layer "In2.Cu")
		(net "XDP_TDI")
	)
	(segment
		(start 453.354948 -145.677128)
		(end 454.69175 -147.01393)
		(width 0.089408)
		(layer "In2.Cu")
		(net "XDP_TDI")
	)
	(segment
		(start 449.4022 -143.364966)
		(end 449.4022 -140.95857)
		(width 0.089408)
		(layer "In2.Cu")
		(net "XDP_TDI")
	)
	(segment
		(start 449.4022 -140.95857)
		(end 448.661536 -140.217906)
		(width 0.089408)
		(layer "In2.Cu")
		(net "XDP_TDI")
	)
	(segment
		(start 389.22325 -117.811804)
		(end 389.39216 -118.10492)
		(width 0.0889)
		(layer "In2.Cu")
		(net "XDP_TDI")
	)
	(arc
		(start 390.909048 -120.040654)
		(mid 391.052852 -120.182337)
		(end 391.1092 -120.376188)
		(width 0.0889)
		(layer "In2.Cu")
		(net "XDP_TDI")
	)
	(arc
		(start 391.6045 -121.267474)
		(mid 391.688781 -121.550691)
		(end 391.899648 -121.757694)
		(width 0.0889)
		(layer "In2.Cu")
		(net "XDP_TDI")
	)
	(arc
		(start 390.3091 -118.691914)
		(mid 390.364392 -119.002583)
		(end 390.523476 -119.275098)
		(width 0.0889)
		(layer "In2.Cu")
		(net "XDP_TDI")
	)
	(arc
		(start 391.404348 -120.899174)
		(mid 391.548152 -121.040857)
		(end 391.6045 -121.234708)
		(width 0.0889)
		(layer "In2.Cu")
		(net "XDP_TDI")
	)
	(arc
		(start 389.481568 -118.128796)
		(mid 390.032977 -118.169776)
		(end 390.3091 -118.648734)
		(width 0.0889)
		(layer "In2.Cu")
		(net "XDP_TDI")
	)
	(arc
		(start 391.1092 -120.408954)
		(mid 391.193481 -120.692171)
		(end 391.404348 -120.899174)
		(width 0.0889)
		(layer "In2.Cu")
		(net "XDP_TDI")
	)
	(arc
		(start 391.899648 -121.757694)
		(mid 392.043452 -121.899377)
		(end 392.0998 -122.093228)
		(width 0.0889)
		(layer "In2.Cu")
		(net "XDP_TDI")
	)
	(arc
		(start 390.523476 -119.275098)
		(mid 390.588824 -119.388873)
		(end 390.6139 -119.517668)
		(width 0.0889)
		(layer "In2.Cu")
		(net "XDP_TDI")
	)
	(arc
		(start 392.0998 -122.11558)
		(mid 392.04345 -122.30943)
		(end 391.899648 -122.451114)
		(width 0.0889)
		(layer "In2.Cu")
		(net "XDP_TDI")
	)
	(arc
		(start 390.6139 -119.550434)
		(mid 390.698181 -119.833651)
		(end 390.909048 -120.040654)
		(width 0.0889)
		(layer "In2.Cu")
		(net "XDP_TDI")
	)
	(arc
		(start 391.899648 -122.451114)
		(mid 391.688784 -122.658118)
		(end 391.6045 -122.941334)
		(width 0.0889)
		(layer "In2.Cu")
		(net "XDP_TDI")
	)
	(arc
		(start 391.6045 -122.984514)
		(mid 391.688781 -123.267731)
		(end 391.899648 -123.474734)
		(width 0.0889)
		(layer "In2.Cu")
		(net "XDP_TDI")
	)
	(arc
		(start 391.899648 -123.474734)
		(mid 392.043452 -123.616417)
		(end 392.0998 -123.810268)
		(width 0.0889)
		(layer "In2.Cu")
		(net "XDP_TDI")
	)
	(segment
		(start 464.303872 -145.219928)
		(end 464.4644 -145.0594)
		(width 0.10795)
		(layer "F.Cu")
		(net "XDP_RSMRST_N")
	)
	(segment
		(start 464.731862 -145.0594)
		(end 465.042504 -144.748758)
		(width 0.10795)
		(layer "F.Cu")
		(net "XDP_RSMRST_N")
	)
	(segment
		(start 465.042504 -144.547336)
		(end 465.3788 -144.21104)
		(width 0.10795)
		(layer "F.Cu")
		(net "XDP_RSMRST_N")
	)
	(segment
		(start 464.4644 -145.0594)
		(end 464.731862 -145.0594)
		(width 0.10795)
		(layer "F.Cu")
		(net "XDP_RSMRST_N")
	)
	(segment
		(start 465.65312 -144.48536)
		(end 465.65312 -144.907)
		(width 0.10795)
		(layer "F.Cu")
		(net "XDP_RSMRST_N")
	)
	(segment
		(start 465.042504 -144.748758)
		(end 465.042504 -144.547336)
		(width 0.10795)
		(layer "F.Cu")
		(net "XDP_RSMRST_N")
	)
	(segment
		(start 462.980278 -145.219928)
		(end 464.303872 -145.219928)
		(width 0.10795)
		(layer "F.Cu")
		(net "XDP_RSMRST_N")
	)
	(segment
		(start 465.3788 -144.21104)
		(end 465.65312 -144.48536)
		(width 0.10795)
		(layer "F.Cu")
		(net "XDP_RSMRST_N")
	)
	(via
		(at 465.3788 -144.21104)
		(size 0.508)
		(drill 0.254)
		(layers "F.Cu" "B.Cu")
		(net "XDP_RSMRST_N")
	)
	(segment
		(start 447.3448 -140.97)
		(end 447.3448 -139.5222)
		(width 0.10795)
		(layer "F.Cu")
		(net "XDP_PREQ_N")
	)
	(segment
		(start 381.79375 -117.58168)
		(end 382.1684 -117.75567)
		(width 0.1016)
		(layer "F.Cu")
		(net "XDP_PREQ_N")
	)
	(segment
		(start 447.9798 -141.605)
		(end 447.3448 -140.97)
		(width 0.10795)
		(layer "F.Cu")
		(net "XDP_PREQ_N")
	)
	(segment
		(start 464.561936 -136.219946)
		(end 462.980532 -136.219946)
		(width 0.10795)
		(layer "F.Cu")
		(net "XDP_PREQ_N")
	)
	(segment
		(start 382.1684 -117.75567)
		(end 382.28905 -117.811804)
		(width 0.1016)
		(layer "F.Cu")
		(net "XDP_PREQ_N")
	)
	(segment
		(start 450.461634 -141.95933)
		(end 449.37553 -141.95933)
		(width 0.10795)
		(layer "F.Cu")
		(net "XDP_PREQ_N")
	)
	(segment
		(start 447.063368 -139.240768)
		(end 446.399412 -139.240768)
		(width 0.10795)
		(layer "F.Cu")
		(net "XDP_PREQ_N")
	)
	(segment
		(start 449.37553 -141.95933)
		(end 449.0212 -141.605)
		(width 0.10795)
		(layer "F.Cu")
		(net "XDP_PREQ_N")
	)
	(segment
		(start 447.3448 -139.5222)
		(end 447.063368 -139.240768)
		(width 0.10795)
		(layer "F.Cu")
		(net "XDP_PREQ_N")
	)
	(segment
		(start 449.0212 -141.605)
		(end 447.9798 -141.605)
		(width 0.10795)
		(layer "F.Cu")
		(net "XDP_PREQ_N")
	)
	(segment
		(start 464.566 -136.22401)
		(end 464.561936 -136.219946)
		(width 0.10795)
		(layer "F.Cu")
		(net "XDP_PREQ_N")
	)
	(via
		(at 464.566 -136.22401)
		(size 0.508)
		(drill 0.254)
		(layers "F.Cu" "B.Cu")
		(net "XDP_PREQ_N")
	)
	(via
		(at 382.28905 -117.811804)
		(size 0.508)
		(drill 0.254)
		(layers "F.Cu" "B.Cu")
		(net "XDP_PREQ_N")
	)
	(via
		(at 386.269738 -129.0828)
		(size 0.6604)
		(drill 0.3302)
		(layers "F.Cu" "B.Cu")
		(net "XDP_PREQ_N")
	)
	(via
		(at 458.343 -133.6548)
		(size 0.508)
		(drill 0.254)
		(layers "F.Cu" "B.Cu")
		(net "XDP_PREQ_N")
	)
	(via
		(at 446.399412 -139.240768)
		(size 0.508)
		(drill 0.254)
		(layers "F.Cu" "B.Cu")
		(net "XDP_PREQ_N")
	)
	(via
		(at 389.64108 -130.03022)
		(size 0.508)
		(drill 0.254)
		(layers "F.Cu" "B.Cu")
		(net "XDP_PREQ_N")
	)
	(segment
		(start 385.6609 -124.668788)
		(end 385.6609 -124.873512)
		(width 0.0889)
		(layer "B.Cu")
		(net "XDP_PREQ_N")
	)
	(segment
		(start 463.956146 -136.525254)
		(end 463.690208 -136.525254)
		(width 0.10795)
		(layer "B.Cu")
		(net "XDP_PREQ_N")
	)
	(segment
		(start 458.343 -133.6548)
		(end 458.7494 -133.6548)
		(width 0.10795)
		(layer "B.Cu")
		(net "XDP_PREQ_N")
	)
	(segment
		(start 385.6609 -124.873512)
		(end 385.6609 -125.869954)
		(width 0.10795)
		(layer "B.Cu")
		(net "XDP_PREQ_N")
	)
	(segment
		(start 382.28905 -117.811804)
		(end 382.627124 -117.811804)
		(width 0.0889)
		(layer "B.Cu")
		(net "XDP_PREQ_N")
	)
	(segment
		(start 382.627124 -117.811804)
		(end 382.692148 -117.74678)
		(width 0.0889)
		(layer "B.Cu")
		(net "XDP_PREQ_N")
	)
	(segment
		(start 386.269738 -126.478792)
		(end 386.269738 -129.0828)
		(width 0.10795)
		(layer "B.Cu")
		(net "XDP_PREQ_N")
	)
	(segment
		(start 464.25739 -136.22401)
		(end 463.956146 -136.525254)
		(width 0.10795)
		(layer "B.Cu")
		(net "XDP_PREQ_N")
	)
	(segment
		(start 386.269738 -129.0828)
		(end 386.269738 -130.440938)
		(width 0.10795)
		(layer "B.Cu")
		(net "XDP_PREQ_N")
	)
	(segment
		(start 385.1656 -120.376188)
		(end 385.1656 -120.408954)
		(width 0.0889)
		(layer "B.Cu")
		(net "XDP_PREQ_N")
	)
	(segment
		(start 458.7494 -133.6548)
		(end 459.253082 -134.158482)
		(width 0.10795)
		(layer "B.Cu")
		(net "XDP_PREQ_N")
	)
	(segment
		(start 386.269738 -130.440938)
		(end 387.1722 -131.3434)
		(width 0.10795)
		(layer "B.Cu")
		(net "XDP_PREQ_N")
	)
	(segment
		(start 385.1656 -122.082814)
		(end 385.1656 -122.125994)
		(width 0.0889)
		(layer "B.Cu")
		(net "XDP_PREQ_N")
	)
	(segment
		(start 387.1722 -131.3434)
		(end 388.941056 -131.3434)
		(width 0.10795)
		(layer "B.Cu")
		(net "XDP_PREQ_N")
	)
	(segment
		(start 384.3655 -118.648734)
		(end 384.3655 -118.6815)
		(width 0.0889)
		(layer "B.Cu")
		(net "XDP_PREQ_N")
	)
	(segment
		(start 388.941056 -131.3434)
		(end 389.64108 -130.643376)
		(width 0.10795)
		(layer "B.Cu")
		(net "XDP_PREQ_N")
	)
	(segment
		(start 383.8702 -117.790214)
		(end 383.8702 -117.82298)
		(width 0.0889)
		(layer "B.Cu")
		(net "XDP_PREQ_N")
	)
	(segment
		(start 384.8608 -119.507254)
		(end 384.8608 -119.54002)
		(width 0.0889)
		(layer "B.Cu")
		(net "XDP_PREQ_N")
	)
	(segment
		(start 389.64108 -130.643376)
		(end 389.64108 -130.03022)
		(width 0.10795)
		(layer "B.Cu")
		(net "XDP_PREQ_N")
	)
	(segment
		(start 464.566 -136.22401)
		(end 464.25739 -136.22401)
		(width 0.10795)
		(layer "B.Cu")
		(net "XDP_PREQ_N")
	)
	(segment
		(start 385.1656 -123.799854)
		(end 385.1656 -123.843034)
		(width 0.0889)
		(layer "B.Cu")
		(net "XDP_PREQ_N")
	)
	(segment
		(start 459.253082 -134.158482)
		(end 459.253082 -134.594346)
		(width 0.10795)
		(layer "B.Cu")
		(net "XDP_PREQ_N")
	)
	(segment
		(start 385.6609 -125.869954)
		(end 386.269738 -126.478792)
		(width 0.10795)
		(layer "B.Cu")
		(net "XDP_PREQ_N")
	)
	(arc
		(start 382.692148 -117.74678)
		(mid 383.301423 -117.221116)
		(end 383.8702 -117.790214)
		(width 0.0889)
		(layer "B.Cu")
		(net "XDP_PREQ_N")
	)
	(arc
		(start 385.460748 -124.333254)
		(mid 385.604552 -124.474937)
		(end 385.6609 -124.668788)
		(width 0.0889)
		(layer "B.Cu")
		(net "XDP_PREQ_N")
	)
	(arc
		(start 385.1656 -123.843034)
		(mid 385.249881 -124.126251)
		(end 385.460748 -124.333254)
		(width 0.0889)
		(layer "B.Cu")
		(net "XDP_PREQ_N")
	)
	(arc
		(start 383.8702 -117.82298)
		(mid 383.92655 -118.01683)
		(end 384.070352 -118.158514)
		(width 0.0889)
		(layer "B.Cu")
		(net "XDP_PREQ_N")
	)
	(arc
		(start 385.460748 -123.309634)
		(mid 385.249884 -123.516638)
		(end 385.1656 -123.799854)
		(width 0.0889)
		(layer "B.Cu")
		(net "XDP_PREQ_N")
	)
	(arc
		(start 384.565652 -119.017034)
		(mid 384.776516 -119.224038)
		(end 384.8608 -119.507254)
		(width 0.0889)
		(layer "B.Cu")
		(net "XDP_PREQ_N")
	)
	(arc
		(start 384.8608 -119.54002)
		(mid 384.914952 -119.852627)
		(end 385.071112 -120.128792)
		(width 0.0889)
		(layer "B.Cu")
		(net "XDP_PREQ_N")
	)
	(arc
		(start 385.071112 -120.128792)
		(mid 385.141179 -120.243774)
		(end 385.1656 -120.376188)
		(width 0.0889)
		(layer "B.Cu")
		(net "XDP_PREQ_N")
	)
	(arc
		(start 385.1656 -120.408954)
		(mid 385.249881 -120.692171)
		(end 385.460748 -120.899174)
		(width 0.0889)
		(layer "B.Cu")
		(net "XDP_PREQ_N")
	)
	(arc
		(start 385.460748 -120.899174)
		(mid 385.661059 -121.245884)
		(end 385.460748 -121.592594)
		(width 0.0889)
		(layer "B.Cu")
		(net "XDP_PREQ_N")
	)
	(arc
		(start 384.3655 -118.6815)
		(mid 384.42185 -118.87535)
		(end 384.565652 -119.017034)
		(width 0.0889)
		(layer "B.Cu")
		(net "XDP_PREQ_N")
	)
	(arc
		(start 385.460748 -121.592594)
		(mid 385.249884 -121.799598)
		(end 385.1656 -122.082814)
		(width 0.0889)
		(layer "B.Cu")
		(net "XDP_PREQ_N")
	)
	(arc
		(start 385.1656 -122.125994)
		(mid 385.249881 -122.409211)
		(end 385.460748 -122.616214)
		(width 0.0889)
		(layer "B.Cu")
		(net "XDP_PREQ_N")
	)
	(arc
		(start 384.070352 -118.158514)
		(mid 384.281216 -118.365518)
		(end 384.3655 -118.648734)
		(width 0.0889)
		(layer "B.Cu")
		(net "XDP_PREQ_N")
	)
	(arc
		(start 385.460748 -122.616214)
		(mid 385.661059 -122.962924)
		(end 385.460748 -123.309634)
		(width 0.0889)
		(layer "B.Cu")
		(net "XDP_PREQ_N")
	)
	(segment
		(start 426.449236 -135.467598)
		(end 425.92371 -135.993124)
		(width 0.089408)
		(layer "In2.Cu")
		(net "XDP_PREQ_N")
	)
	(segment
		(start 439.982102 -139.96797)
		(end 436.775098 -139.96797)
		(width 0.089408)
		(layer "In2.Cu")
		(net "XDP_PREQ_N")
	)
	(segment
		(start 423.445686 -134.8613)
		(end 417.538408 -134.8613)
		(width 0.089408)
		(layer "In2.Cu")
		(net "XDP_PREQ_N")
	)
	(segment
		(start 443.602364 -138.184636)
		(end 441.765436 -138.184636)
		(width 0.089408)
		(layer "In2.Cu")
		(net "XDP_PREQ_N")
	)
	(segment
		(start 427.254924 -136.73074)
		(end 427.254924 -135.71982)
		(width 0.089408)
		(layer "In2.Cu")
		(net "XDP_PREQ_N")
	)
	(segment
		(start 389.70585 -130.633724)
		(end 389.64108 -130.568954)
		(width 0.089408)
		(layer "In2.Cu")
		(net "XDP_PREQ_N")
	)
	(segment
		(start 427.002702 -135.467598)
		(end 426.449236 -135.467598)
		(width 0.089408)
		(layer "In2.Cu")
		(net "XDP_PREQ_N")
	)
	(segment
		(start 424.57751 -135.993124)
		(end 423.445686 -134.8613)
		(width 0.089408)
		(layer "In2.Cu")
		(net "XDP_PREQ_N")
	)
	(segment
		(start 425.92371 -135.993124)
		(end 424.57751 -135.993124)
		(width 0.089408)
		(layer "In2.Cu")
		(net "XDP_PREQ_N")
	)
	(segment
		(start 414.940496 -135.176768)
		(end 414.405064 -135.7122)
		(width 0.089408)
		(layer "In2.Cu")
		(net "XDP_PREQ_N")
	)
	(segment
		(start 427.254924 -135.71982)
		(end 427.002702 -135.467598)
		(width 0.089408)
		(layer "In2.Cu")
		(net "XDP_PREQ_N")
	)
	(segment
		(start 389.706104 -130.633724)
		(end 389.70585 -130.633724)
		(width 0.089408)
		(layer "In2.Cu")
		(net "XDP_PREQ_N")
	)
	(segment
		(start 410.586936 -135.7122)
		(end 408.898344 -134.023608)
		(width 0.089408)
		(layer "In2.Cu")
		(net "XDP_PREQ_N")
	)
	(segment
		(start 445.204088 -139.541758)
		(end 444.959486 -139.541758)
		(width 0.089408)
		(layer "In2.Cu")
		(net "XDP_PREQ_N")
	)
	(segment
		(start 434.991764 -138.184636)
		(end 428.70882 -138.184636)
		(width 0.089408)
		(layer "In2.Cu")
		(net "XDP_PREQ_N")
	)
	(segment
		(start 401.718018 -132.467096)
		(end 391.539476 -132.467096)
		(width 0.089408)
		(layer "In2.Cu")
		(net "XDP_PREQ_N")
	)
	(segment
		(start 445.729868 -139.541758)
		(end 445.63284 -139.638786)
		(width 0.089408)
		(layer "In2.Cu")
		(net "XDP_PREQ_N")
	)
	(segment
		(start 446.399412 -139.240768)
		(end 446.098422 -139.541758)
		(width 0.089408)
		(layer "In2.Cu")
		(net "XDP_PREQ_N")
	)
	(segment
		(start 428.70882 -138.184636)
		(end 427.254924 -136.73074)
		(width 0.089408)
		(layer "In2.Cu")
		(net "XDP_PREQ_N")
	)
	(segment
		(start 408.898344 -132.802122)
		(end 407.530046 -131.433824)
		(width 0.089408)
		(layer "In2.Cu")
		(net "XDP_PREQ_N")
	)
	(segment
		(start 389.64108 -130.568954)
		(end 389.64108 -130.03022)
		(width 0.089408)
		(layer "In2.Cu")
		(net "XDP_PREQ_N")
	)
	(segment
		(start 407.530046 -131.433824)
		(end 402.75129 -131.433824)
		(width 0.089408)
		(layer "In2.Cu")
		(net "XDP_PREQ_N")
	)
	(segment
		(start 444.959486 -139.541758)
		(end 443.602364 -138.184636)
		(width 0.089408)
		(layer "In2.Cu")
		(net "XDP_PREQ_N")
	)
	(segment
		(start 445.301116 -139.638786)
		(end 445.204088 -139.541758)
		(width 0.089408)
		(layer "In2.Cu")
		(net "XDP_PREQ_N")
	)
	(segment
		(start 414.405064 -135.7122)
		(end 410.586936 -135.7122)
		(width 0.089408)
		(layer "In2.Cu")
		(net "XDP_PREQ_N")
	)
	(segment
		(start 408.898344 -134.023608)
		(end 408.898344 -132.802122)
		(width 0.089408)
		(layer "In2.Cu")
		(net "XDP_PREQ_N")
	)
	(segment
		(start 446.098422 -139.541758)
		(end 445.729868 -139.541758)
		(width 0.089408)
		(layer "In2.Cu")
		(net "XDP_PREQ_N")
	)
	(segment
		(start 436.775098 -139.96797)
		(end 434.991764 -138.184636)
		(width 0.089408)
		(layer "In2.Cu")
		(net "XDP_PREQ_N")
	)
	(segment
		(start 391.539476 -132.467096)
		(end 389.706104 -130.633724)
		(width 0.089408)
		(layer "In2.Cu")
		(net "XDP_PREQ_N")
	)
	(segment
		(start 445.63284 -139.638786)
		(end 445.301116 -139.638786)
		(width 0.089408)
		(layer "In2.Cu")
		(net "XDP_PREQ_N")
	)
	(segment
		(start 417.22294 -135.176768)
		(end 414.940496 -135.176768)
		(width 0.089408)
		(layer "In2.Cu")
		(net "XDP_PREQ_N")
	)
	(segment
		(start 402.75129 -131.433824)
		(end 401.718018 -132.467096)
		(width 0.089408)
		(layer "In2.Cu")
		(net "XDP_PREQ_N")
	)
	(segment
		(start 417.538408 -134.8613)
		(end 417.22294 -135.176768)
		(width 0.089408)
		(layer "In2.Cu")
		(net "XDP_PREQ_N")
	)
	(segment
		(start 441.765436 -138.184636)
		(end 439.982102 -139.96797)
		(width 0.089408)
		(layer "In2.Cu")
		(net "XDP_PREQ_N")
	)
	(segment
		(start 448.753738 -136.387332)
		(end 449.37807 -135.763)
		(width 0.089408)
		(layer "In11.Cu")
		(net "XDP_PREQ_N")
	)
	(segment
		(start 448.753992 -136.886188)
		(end 448.753992 -136.387586)
		(width 0.089408)
		(layer "In11.Cu")
		(net "XDP_PREQ_N")
	)
	(segment
		(start 458.7494 -133.6548)
		(end 459.76032 -134.66572)
		(width 0.089408)
		(layer "In11.Cu")
		(net "XDP_PREQ_N")
	)
	(segment
		(start 449.37807 -135.763)
		(end 451.9168 -135.763)
		(width 0.089408)
		(layer "In11.Cu")
		(net "XDP_PREQ_N")
	)
	(segment
		(start 456.0316 -134.112)
		(end 456.3364 -133.8072)
		(width 0.089408)
		(layer "In11.Cu")
		(net "XDP_PREQ_N")
	)
	(segment
		(start 458.343 -133.6548)
		(end 458.7494 -133.6548)
		(width 0.089408)
		(layer "In11.Cu")
		(net "XDP_PREQ_N")
	)
	(segment
		(start 459.76032 -134.66572)
		(end 460.14132 -134.66572)
		(width 0.089408)
		(layer "In11.Cu")
		(net "XDP_PREQ_N")
	)
	(segment
		(start 456.3364 -133.8072)
		(end 458.1906 -133.8072)
		(width 0.089408)
		(layer "In11.Cu")
		(net "XDP_PREQ_N")
	)
	(segment
		(start 461.5688 -136.0932)
		(end 464.43519 -136.0932)
		(width 0.089408)
		(layer "In11.Cu")
		(net "XDP_PREQ_N")
	)
	(segment
		(start 451.9168 -135.763)
		(end 453.5678 -134.112)
		(width 0.089408)
		(layer "In11.Cu")
		(net "XDP_PREQ_N")
	)
	(segment
		(start 464.43519 -136.0932)
		(end 464.566 -136.22401)
		(width 0.089408)
		(layer "In11.Cu")
		(net "XDP_PREQ_N")
	)
	(segment
		(start 453.5678 -134.112)
		(end 456.0316 -134.112)
		(width 0.089408)
		(layer "In11.Cu")
		(net "XDP_PREQ_N")
	)
	(segment
		(start 448.753992 -136.387586)
		(end 448.753738 -136.387332)
		(width 0.089408)
		(layer "In11.Cu")
		(net "XDP_PREQ_N")
	)
	(segment
		(start 446.399412 -139.240768)
		(end 448.753992 -136.886188)
		(width 0.089408)
		(layer "In11.Cu")
		(net "XDP_PREQ_N")
	)
	(segment
		(start 460.14132 -134.66572)
		(end 461.5688 -136.0932)
		(width 0.089408)
		(layer "In11.Cu")
		(net "XDP_PREQ_N")
	)
	(segment
		(start 458.1906 -133.8072)
		(end 458.343 -133.6548)
		(width 0.089408)
		(layer "In11.Cu")
		(net "XDP_PREQ_N")
	)
	(segment
		(start 465.328 -137.033)
		(end 465.2518 -136.9568)
		(width 0.10795)
		(layer "F.Cu")
		(net "XDP_PRDY_N")
	)
	(segment
		(start 461.901286 -135.246872)
		(end 461.543654 -135.604504)
		(width 0.10795)
		(layer "F.Cu")
		(net "XDP_PRDY_N")
	)
	(segment
		(start 450.1642 -149.06498)
		(end 451.51802 -149.06498)
		(width 0.10795)
		(layer "F.Cu")
		(net "XDP_PRDY_N")
	)
	(segment
		(start 465.2518 -136.9568)
		(end 464.9978 -136.9568)
		(width 0.10795)
		(layer "F.Cu")
		(net "XDP_PRDY_N")
	)
	(segment
		(start 464.760818 -136.719818)
		(end 462.980532 -136.719818)
		(width 0.10795)
		(layer "F.Cu")
		(net "XDP_PRDY_N")
	)
	(segment
		(start 461.7339 -136.719818)
		(end 462.980532 -136.719818)
		(width 0.10795)
		(layer "F.Cu")
		(net "XDP_PRDY_N")
	)
	(segment
		(start 384.76555 -117.58168)
		(end 385.26085 -117.811804)
		(width 0.1016)
		(layer "F.Cu")
		(net "XDP_PRDY_N")
	)
	(segment
		(start 461.729836 -136.723882)
		(end 461.7339 -136.719818)
		(width 0.10795)
		(layer "F.Cu")
		(net "XDP_PRDY_N")
	)
	(segment
		(start 461.543654 -136.5377)
		(end 461.729836 -136.723882)
		(width 0.10795)
		(layer "F.Cu")
		(net "XDP_PRDY_N")
	)
	(segment
		(start 464.9978 -136.9568)
		(end 464.760818 -136.719818)
		(width 0.10795)
		(layer "F.Cu")
		(net "XDP_PRDY_N")
	)
	(segment
		(start 465.455 -137.033)
		(end 465.328 -137.033)
		(width 0.10795)
		(layer "F.Cu")
		(net "XDP_PRDY_N")
	)
	(segment
		(start 451.51802 -149.06498)
		(end 451.866 -148.717)
		(width 0.10795)
		(layer "F.Cu")
		(net "XDP_PRDY_N")
	)
	(segment
		(start 461.901286 -134.084822)
		(end 461.901286 -135.246872)
		(width 0.10795)
		(layer "F.Cu")
		(net "XDP_PRDY_N")
	)
	(segment
		(start 461.543654 -135.604504)
		(end 461.543654 -136.5377)
		(width 0.10795)
		(layer "F.Cu")
		(net "XDP_PRDY_N")
	)
	(via
		(at 465.455 -137.033)
		(size 0.508)
		(drill 0.254)
		(layers "F.Cu" "B.Cu")
		(net "XDP_PRDY_N")
	)
	(via
		(at 385.26085 -117.811804)
		(size 0.508)
		(drill 0.254)
		(layers "F.Cu" "B.Cu")
		(net "XDP_PRDY_N")
	)
	(via
		(at 445.466978 -139.238482)
		(size 0.508)
		(drill 0.254)
		(layers "F.Cu" "B.Cu")
		(net "XDP_PRDY_N")
	)
	(via
		(at 461.901286 -134.084822)
		(size 0.508)
		(drill 0.254)
		(layers "F.Cu" "B.Cu")
		(net "XDP_PRDY_N")
	)
	(via
		(at 451.866 -148.717)
		(size 0.508)
		(drill 0.254)
		(layers "F.Cu" "B.Cu")
		(net "XDP_PRDY_N")
	)
	(segment
		(start 460.88681 -134.594346)
		(end 460.753206 -134.594346)
		(width 0.10795)
		(layer "B.Cu")
		(net "XDP_PRDY_N")
	)
	(segment
		(start 464.9978 -136.9568)
		(end 464.842352 -136.801352)
		(width 0.10795)
		(layer "B.Cu")
		(net "XDP_PRDY_N")
	)
	(segment
		(start 464.842352 -136.801352)
		(end 464.30311 -136.801352)
		(width 0.10795)
		(layer "B.Cu")
		(net "XDP_PRDY_N")
	)
	(segment
		(start 461.396334 -134.084822)
		(end 460.88681 -134.594346)
		(width 0.10795)
		(layer "B.Cu")
		(net "XDP_PRDY_N")
	)
	(segment
		(start 464.30311 -136.801352)
		(end 463.690208 -137.414254)
		(width 0.10795)
		(layer "B.Cu")
		(net "XDP_PRDY_N")
	)
	(segment
		(start 465.2518 -136.9568)
		(end 464.9978 -136.9568)
		(width 0.10795)
		(layer "B.Cu")
		(net "XDP_PRDY_N")
	)
	(segment
		(start 465.455 -137.033)
		(end 465.328 -137.033)
		(width 0.10795)
		(layer "B.Cu")
		(net "XDP_PRDY_N")
	)
	(segment
		(start 461.901286 -134.084822)
		(end 461.396334 -134.084822)
		(width 0.10795)
		(layer "B.Cu")
		(net "XDP_PRDY_N")
	)
	(segment
		(start 465.328 -137.033)
		(end 465.2518 -136.9568)
		(width 0.10795)
		(layer "B.Cu")
		(net "XDP_PRDY_N")
	)
	(segment
		(start 387.73735 -121.262394)
		(end 387.73735 -121.229374)
		(width 0.0889)
		(layer "In2.Cu")
		(net "XDP_PRDY_N")
	)
	(segment
		(start 410.606748 -135.302752)
		(end 409.190952 -133.886956)
		(width 0.089408)
		(layer "In2.Cu")
		(net "XDP_PRDY_N")
	)
	(segment
		(start 388.23265 -123.837954)
		(end 388.23265 -123.804934)
		(width 0.0889)
		(layer "In2.Cu")
		(net "XDP_PRDY_N")
	)
	(segment
		(start 441.664852 -137.8712)
		(end 439.86069 -139.675362)
		(width 0.089408)
		(layer "In2.Cu")
		(net "XDP_PRDY_N")
	)
	(segment
		(start 390.0932 -130.6068)
		(end 390.0932 -125.887226)
		(width 0.089408)
		(layer "In2.Cu")
		(net "XDP_PRDY_N")
	)
	(segment
		(start 387.73735 -122.979434)
		(end 387.73735 -122.946414)
		(width 0.0889)
		(layer "In2.Cu")
		(net "XDP_PRDY_N")
	)
	(segment
		(start 390.0932 -125.887226)
		(end 388.364476 -124.158502)
		(width 0.089408)
		(layer "In2.Cu")
		(net "XDP_PRDY_N")
	)
	(segment
		(start 386.74675 -119.545354)
		(end 386.74675 -119.512334)
		(width 0.089408)
		(layer "In2.Cu")
		(net "XDP_PRDY_N")
	)
	(segment
		(start 388.23265 -122.120914)
		(end 388.23265 -122.087894)
		(width 0.0889)
		(layer "In2.Cu")
		(net "XDP_PRDY_N")
	)
	(segment
		(start 414.400492 -135.302752)
		(end 410.606748 -135.302752)
		(width 0.089408)
		(layer "In2.Cu")
		(net "XDP_PRDY_N")
	)
	(segment
		(start 417.101528 -134.88416)
		(end 414.819084 -134.88416)
		(width 0.089408)
		(layer "In2.Cu")
		(net "XDP_PRDY_N")
	)
	(segment
		(start 391.660888 -132.174488)
		(end 390.0932 -130.6068)
		(width 0.089408)
		(layer "In2.Cu")
		(net "XDP_PRDY_N")
	)
	(segment
		(start 409.190952 -133.886956)
		(end 409.190952 -132.68071)
		(width 0.089408)
		(layer "In2.Cu")
		(net "XDP_PRDY_N")
	)
	(segment
		(start 427.124114 -135.17499)
		(end 426.327824 -135.17499)
		(width 0.089408)
		(layer "In2.Cu")
		(net "XDP_PRDY_N")
	)
	(segment
		(start 427.547532 -135.598408)
		(end 427.124114 -135.17499)
		(width 0.089408)
		(layer "In2.Cu")
		(net "XDP_PRDY_N")
	)
	(segment
		(start 428.809404 -137.8712)
		(end 427.547532 -136.609328)
		(width 0.089408)
		(layer "In2.Cu")
		(net "XDP_PRDY_N")
	)
	(segment
		(start 386.25145 -118.686834)
		(end 386.25145 -118.653814)
		(width 0.089408)
		(layer "In2.Cu")
		(net "XDP_PRDY_N")
	)
	(segment
		(start 402.629878 -131.141216)
		(end 401.596606 -132.174488)
		(width 0.089408)
		(layer "In2.Cu")
		(net "XDP_PRDY_N")
	)
	(segment
		(start 445.466978 -139.238482)
		(end 444.099696 -137.8712)
		(width 0.089408)
		(layer "In2.Cu")
		(net "XDP_PRDY_N")
	)
	(segment
		(start 439.86069 -139.675362)
		(end 436.89651 -139.675362)
		(width 0.089408)
		(layer "In2.Cu")
		(net "XDP_PRDY_N")
	)
	(segment
		(start 409.190952 -132.68071)
		(end 407.651458 -131.141216)
		(width 0.089408)
		(layer "In2.Cu")
		(net "XDP_PRDY_N")
	)
	(segment
		(start 407.651458 -131.141216)
		(end 402.629878 -131.141216)
		(width 0.089408)
		(layer "In2.Cu")
		(net "XDP_PRDY_N")
	)
	(segment
		(start 426.327824 -135.17499)
		(end 425.802298 -135.700516)
		(width 0.089408)
		(layer "In2.Cu")
		(net "XDP_PRDY_N")
	)
	(segment
		(start 386.0038 -118.241064)
		(end 385.26085 -117.811804)
		(width 0.089408)
		(layer "In2.Cu")
		(net "XDP_PRDY_N")
	)
	(segment
		(start 414.819084 -134.88416)
		(end 414.400492 -135.302752)
		(width 0.089408)
		(layer "In2.Cu")
		(net "XDP_PRDY_N")
	)
	(segment
		(start 427.547532 -136.609328)
		(end 427.547532 -135.598408)
		(width 0.089408)
		(layer "In2.Cu")
		(net "XDP_PRDY_N")
	)
	(segment
		(start 423.567098 -134.568692)
		(end 417.416996 -134.568692)
		(width 0.089408)
		(layer "In2.Cu")
		(net "XDP_PRDY_N")
	)
	(segment
		(start 435.092348 -137.8712)
		(end 428.809404 -137.8712)
		(width 0.089408)
		(layer "In2.Cu")
		(net "XDP_PRDY_N")
	)
	(segment
		(start 417.416996 -134.568692)
		(end 417.101528 -134.88416)
		(width 0.089408)
		(layer "In2.Cu")
		(net "XDP_PRDY_N")
	)
	(segment
		(start 425.802298 -135.700516)
		(end 424.698922 -135.700516)
		(width 0.089408)
		(layer "In2.Cu")
		(net "XDP_PRDY_N")
	)
	(segment
		(start 401.596606 -132.174488)
		(end 391.660888 -132.174488)
		(width 0.089408)
		(layer "In2.Cu")
		(net "XDP_PRDY_N")
	)
	(segment
		(start 444.099696 -137.8712)
		(end 441.664852 -137.8712)
		(width 0.089408)
		(layer "In2.Cu")
		(net "XDP_PRDY_N")
	)
	(segment
		(start 424.698922 -135.700516)
		(end 423.567098 -134.568692)
		(width 0.089408)
		(layer "In2.Cu")
		(net "XDP_PRDY_N")
	)
	(segment
		(start 387.24205 -120.403874)
		(end 387.24205 -120.370854)
		(width 0.0889)
		(layer "In2.Cu")
		(net "XDP_PRDY_N")
	)
	(segment
		(start 436.89651 -139.675362)
		(end 435.092348 -137.8712)
		(width 0.089408)
		(layer "In2.Cu")
		(net "XDP_PRDY_N")
	)
	(arc
		(start 387.73735 -121.229374)
		(mid 387.667002 -120.990913)
		(end 387.4897 -120.816624)
		(width 0.0889)
		(layer "In2.Cu")
		(net "XDP_PRDY_N")
	)
	(arc
		(start 386.4991 -119.099584)
		(mid 386.321798 -118.925295)
		(end 386.25145 -118.686834)
		(width 0.089408)
		(layer "In2.Cu")
		(net "XDP_PRDY_N")
	)
	(arc
		(start 388.364476 -124.158502)
		(mid 388.269643 -124.010125)
		(end 388.23265 -123.837954)
		(width 0.0889)
		(layer "In2.Cu")
		(net "XDP_PRDY_N")
	)
	(arc
		(start 386.74675 -119.512334)
		(mid 386.676402 -119.273873)
		(end 386.4991 -119.099584)
		(width 0.089408)
		(layer "In2.Cu")
		(net "XDP_PRDY_N")
	)
	(arc
		(start 387.985 -122.533664)
		(mid 388.162302 -122.359375)
		(end 388.23265 -122.120914)
		(width 0.0889)
		(layer "In2.Cu")
		(net "XDP_PRDY_N")
	)
	(arc
		(start 386.9944 -119.958104)
		(mid 386.817098 -119.783815)
		(end 386.74675 -119.545354)
		(width 0.0889)
		(layer "In2.Cu")
		(net "XDP_PRDY_N")
	)
	(arc
		(start 388.23265 -123.804934)
		(mid 388.162302 -123.566473)
		(end 387.985 -123.392184)
		(width 0.0889)
		(layer "In2.Cu")
		(net "XDP_PRDY_N")
	)
	(arc
		(start 388.23265 -122.087894)
		(mid 388.162302 -121.849433)
		(end 387.985 -121.675144)
		(width 0.0889)
		(layer "In2.Cu")
		(net "XDP_PRDY_N")
	)
	(arc
		(start 387.985 -121.675144)
		(mid 387.807698 -121.500855)
		(end 387.73735 -121.262394)
		(width 0.0889)
		(layer "In2.Cu")
		(net "XDP_PRDY_N")
	)
	(arc
		(start 387.24205 -120.370854)
		(mid 387.171702 -120.132393)
		(end 386.9944 -119.958104)
		(width 0.0889)
		(layer "In2.Cu")
		(net "XDP_PRDY_N")
	)
	(arc
		(start 386.25145 -118.653814)
		(mid 386.181102 -118.415353)
		(end 386.0038 -118.241064)
		(width 0.089408)
		(layer "In2.Cu")
		(net "XDP_PRDY_N")
	)
	(arc
		(start 387.985 -123.392184)
		(mid 387.807698 -123.217895)
		(end 387.73735 -122.979434)
		(width 0.0889)
		(layer "In2.Cu")
		(net "XDP_PRDY_N")
	)
	(arc
		(start 387.73735 -122.946414)
		(mid 387.807698 -122.707953)
		(end 387.985 -122.533664)
		(width 0.0889)
		(layer "In2.Cu")
		(net "XDP_PRDY_N")
	)
	(arc
		(start 387.4897 -120.816624)
		(mid 387.312398 -120.642335)
		(end 387.24205 -120.403874)
		(width 0.0889)
		(layer "In2.Cu")
		(net "XDP_PRDY_N")
	)
	(segment
		(start 461.02397 -147.680934)
		(end 462.922112 -145.782792)
		(width 0.089408)
		(layer "In4.Cu")
		(net "XDP_PRDY_N")
	)
	(segment
		(start 452.579486 -148.556472)
		(end 452.579486 -148.501354)
		(width 0.089408)
		(layer "In4.Cu")
		(net "XDP_PRDY_N")
	)
	(segment
		(start 462.922112 -137.997692)
		(end 462.256886 -137.332466)
		(width 0.089408)
		(layer "In4.Cu")
		(net "XDP_PRDY_N")
	)
	(segment
		(start 452.579486 -148.501354)
		(end 452.579232 -148.5011)
		(width 0.089408)
		(layer "In4.Cu")
		(net "XDP_PRDY_N")
	)
	(segment
		(start 451.866 -148.717)
		(end 452.418958 -148.717)
		(width 0.089408)
		(layer "In4.Cu")
		(net "XDP_PRDY_N")
	)
	(segment
		(start 460.164434 -147.680934)
		(end 461.02397 -147.680934)
		(width 0.089408)
		(layer "In4.Cu")
		(net "XDP_PRDY_N")
	)
	(segment
		(start 453.25538 -147.561808)
		(end 460.045308 -147.561808)
		(width 0.089408)
		(layer "In4.Cu")
		(net "XDP_PRDY_N")
	)
	(segment
		(start 452.579232 -148.237956)
		(end 453.25538 -147.561808)
		(width 0.089408)
		(layer "In4.Cu")
		(net "XDP_PRDY_N")
	)
	(segment
		(start 462.256886 -134.440422)
		(end 461.901286 -134.084822)
		(width 0.089408)
		(layer "In4.Cu")
		(net "XDP_PRDY_N")
	)
	(segment
		(start 462.256886 -137.332466)
		(end 462.256886 -134.440422)
		(width 0.089408)
		(layer "In4.Cu")
		(net "XDP_PRDY_N")
	)
	(segment
		(start 452.418958 -148.717)
		(end 452.579486 -148.556472)
		(width 0.089408)
		(layer "In4.Cu")
		(net "XDP_PRDY_N")
	)
	(segment
		(start 452.579232 -148.5011)
		(end 452.579232 -148.237956)
		(width 0.089408)
		(layer "In4.Cu")
		(net "XDP_PRDY_N")
	)
	(segment
		(start 462.922112 -145.782792)
		(end 462.922112 -137.997692)
		(width 0.089408)
		(layer "In4.Cu")
		(net "XDP_PRDY_N")
	)
	(segment
		(start 460.045308 -147.561808)
		(end 460.164434 -147.680934)
		(width 0.089408)
		(layer "In4.Cu")
		(net "XDP_PRDY_N")
	)
	(segment
		(start 461.5688 -136.779)
		(end 464.82 -136.779)
		(width 0.089408)
		(layer "In11.Cu")
		(net "XDP_PRDY_N")
	)
	(segment
		(start 449.0466 -136.50849)
		(end 449.499482 -136.055608)
		(width 0.089408)
		(layer "In11.Cu")
		(net "XDP_PRDY_N")
	)
	(segment
		(start 465.0994 -136.0932)
		(end 464.2612 -135.255)
		(width 0.089408)
		(layer "In11.Cu")
		(net "XDP_PRDY_N")
	)
	(segment
		(start 465.0994 -136.4996)
		(end 465.0994 -136.0932)
		(width 0.089408)
		(layer "In11.Cu")
		(net "XDP_PRDY_N")
	)
	(segment
		(start 463.071464 -135.255)
		(end 461.901286 -134.084822)
		(width 0.089408)
		(layer "In11.Cu")
		(net "XDP_PRDY_N")
	)
	(segment
		(start 447.13017 -139.641072)
		(end 449.0466 -137.724642)
		(width 0.089408)
		(layer "In11.Cu")
		(net "XDP_PRDY_N")
	)
	(segment
		(start 452.038212 -136.055608)
		(end 452.25462 -135.8392)
		(width 0.089408)
		(layer "In11.Cu")
		(net "XDP_PRDY_N")
	)
	(segment
		(start 460.8576 -136.0678)
		(end 461.5688 -136.779)
		(width 0.089408)
		(layer "In11.Cu")
		(net "XDP_PRDY_N")
	)
	(segment
		(start 452.25462 -135.8392)
		(end 452.628 -135.8392)
		(width 0.089408)
		(layer "In11.Cu")
		(net "XDP_PRDY_N")
	)
	(segment
		(start 449.0466 -137.724642)
		(end 449.0466 -136.50849)
		(width 0.089408)
		(layer "In11.Cu")
		(net "XDP_PRDY_N")
	)
	(segment
		(start 464.2612 -135.255)
		(end 463.071464 -135.255)
		(width 0.089408)
		(layer "In11.Cu")
		(net "XDP_PRDY_N")
	)
	(segment
		(start 452.8566 -136.0678)
		(end 460.8576 -136.0678)
		(width 0.089408)
		(layer "In11.Cu")
		(net "XDP_PRDY_N")
	)
	(segment
		(start 445.869568 -139.641072)
		(end 447.13017 -139.641072)
		(width 0.089408)
		(layer "In11.Cu")
		(net "XDP_PRDY_N")
	)
	(segment
		(start 445.466978 -139.238482)
		(end 445.869568 -139.641072)
		(width 0.089408)
		(layer "In11.Cu")
		(net "XDP_PRDY_N")
	)
	(segment
		(start 464.82 -136.779)
		(end 465.0994 -136.4996)
		(width 0.089408)
		(layer "In11.Cu")
		(net "XDP_PRDY_N")
	)
	(segment
		(start 449.499482 -136.055608)
		(end 452.038212 -136.055608)
		(width 0.089408)
		(layer "In11.Cu")
		(net "XDP_PRDY_N")
	)
	(segment
		(start 452.628 -135.8392)
		(end 452.8566 -136.0678)
		(width 0.089408)
		(layer "In11.Cu")
		(net "XDP_PRDY_N")
	)
	(segment
		(start 455.676 -140.4112)
		(end 455.676 -140.9446)
		(width 0.10795)
		(layer "F.Cu")
		(net "XDP_OBSFN_B1_MBP7_N")
	)
	(segment
		(start 455.951336 -141.219936)
		(end 457.252578 -141.219936)
		(width 0.10795)
		(layer "F.Cu")
		(net "XDP_OBSFN_B1_MBP7_N")
	)
	(segment
		(start 455.676 -140.9446)
		(end 455.951336 -141.219936)
		(width 0.10795)
		(layer "F.Cu")
		(net "XDP_OBSFN_B1_MBP7_N")
	)
	(via
		(at 455.676 -140.4112)
		(size 0.508)
		(drill 0.254)
		(layers "F.Cu" "B.Cu")
		(net "XDP_OBSFN_B1_MBP7_N")
	)
	(via
		(at 459.55966 -139.615672)
		(size 0.6604)
		(drill 0.3302)
		(layers "F.Cu" "B.Cu")
		(net "XDP_OBSFN_B1_MBP7_N")
	)
	(segment
		(start 459.6638 -140.3604)
		(end 459.3082 -140.716)
		(width 0.10795)
		(layer "B.Cu")
		(net "XDP_OBSFN_B1_MBP7_N")
	)
	(segment
		(start 459.55966 -139.615672)
		(end 459.6638 -139.719812)
		(width 0.10795)
		(layer "B.Cu")
		(net "XDP_OBSFN_B1_MBP7_N")
	)
	(segment
		(start 459.6638 -139.719812)
		(end 459.6638 -140.3604)
		(width 0.10795)
		(layer "B.Cu")
		(net "XDP_OBSFN_B1_MBP7_N")
	)
	(segment
		(start 459.3082 -140.716)
		(end 455.9808 -140.716)
		(width 0.10795)
		(layer "B.Cu")
		(net "XDP_OBSFN_B1_MBP7_N")
	)
	(segment
		(start 458.75321 -138.809222)
		(end 458.75321 -137.694162)
		(width 0.10795)
		(layer "B.Cu")
		(net "XDP_OBSFN_B1_MBP7_N")
	)
	(segment
		(start 455.9808 -140.716)
		(end 455.676 -140.4112)
		(width 0.10795)
		(layer "B.Cu")
		(net "XDP_OBSFN_B1_MBP7_N")
	)
	(segment
		(start 459.55966 -139.615672)
		(end 458.75321 -138.809222)
		(width 0.10795)
		(layer "B.Cu")
		(net "XDP_OBSFN_B1_MBP7_N")
	)
	(segment
		(start 457.252578 -140.71981)
		(end 459.557882 -140.71981)
		(width 0.10795)
		(layer "F.Cu")
		(net "XDP_OBSFN_B0_MBP6_N")
	)
	(segment
		(start 459.557882 -140.71981)
		(end 460.489808 -139.787884)
		(width 0.10795)
		(layer "F.Cu")
		(net "XDP_OBSFN_B0_MBP6_N")
	)
	(segment
		(start 460.489808 -139.787884)
		(end 460.489808 -138.557254)
		(width 0.10795)
		(layer "F.Cu")
		(net "XDP_OBSFN_B0_MBP6_N")
	)
	(via
		(at 460.791052 -139.304776)
		(size 0.6604)
		(drill 0.3302)
		(layers "F.Cu" "B.Cu")
		(net "XDP_OBSFN_B0_MBP6_N")
	)
	(via
		(at 460.489808 -138.557254)
		(size 0.508)
		(drill 0.254)
		(layers "F.Cu" "B.Cu")
		(net "XDP_OBSFN_B0_MBP6_N")
	)
	(segment
		(start 460.791052 -139.304776)
		(end 460.489808 -139.003532)
		(width 0.10795)
		(layer "B.Cu")
		(net "XDP_OBSFN_B0_MBP6_N")
	)
	(segment
		(start 460.253334 -137.694162)
		(end 460.253334 -138.32078)
		(width 0.10795)
		(layer "B.Cu")
		(net "XDP_OBSFN_B0_MBP6_N")
	)
	(segment
		(start 460.253334 -138.32078)
		(end 460.489808 -138.557254)
		(width 0.10795)
		(layer "B.Cu")
		(net "XDP_OBSFN_B0_MBP6_N")
	)
	(segment
		(start 460.489808 -139.003532)
		(end 460.489808 -138.557254)
		(width 0.10795)
		(layer "B.Cu")
		(net "XDP_OBSFN_B0_MBP6_N")
	)
	(segment
		(start 455.37247 -145.96745)
		(end 455.378058 -145.96745)
		(width 0.10795)
		(layer "F.Cu")
		(net "XDP_ITP_PMODE")
	)
	(segment
		(start 389.71855 -117.58168)
		(end 390.21385 -117.811804)
		(width 0.1016)
		(layer "F.Cu")
		(net "XDP_ITP_PMODE")
	)
	(segment
		(start 456.130406 -146.719798)
		(end 457.252324 -146.719798)
		(width 0.10795)
		(layer "F.Cu")
		(net "XDP_ITP_PMODE")
	)
	(segment
		(start 455.378058 -145.96745)
		(end 456.130406 -146.719798)
		(width 0.10795)
		(layer "F.Cu")
		(net "XDP_ITP_PMODE")
	)
	(via
		(at 455.37247 -145.96745)
		(size 0.508)
		(drill 0.254)
		(layers "F.Cu" "B.Cu")
		(net "XDP_ITP_PMODE")
	)
	(via
		(at 390.21385 -117.811804)
		(size 0.508)
		(drill 0.254)
		(layers "F.Cu" "B.Cu")
		(net "XDP_ITP_PMODE")
	)
	(segment
		(start 455.37247 -145.96745)
		(end 455.377804 -145.962116)
		(width 0.10795)
		(layer "B.Cu")
		(net "XDP_ITP_PMODE")
	)
	(segment
		(start 455.377804 -145.962116)
		(end 455.377804 -145.828004)
		(width 0.10795)
		(layer "B.Cu")
		(net "XDP_ITP_PMODE")
	)
	(segment
		(start 454.453752 -144.903952)
		(end 454.453752 -144.455896)
		(width 0.10795)
		(layer "B.Cu")
		(net "XDP_ITP_PMODE")
	)
	(segment
		(start 455.377804 -145.828004)
		(end 454.453752 -144.903952)
		(width 0.10795)
		(layer "B.Cu")
		(net "XDP_ITP_PMODE")
	)
	(segment
		(start 412.96717 -131.628134)
		(end 410.339032 -128.999996)
		(width 0.089408)
		(layer "In2.Cu")
		(net "XDP_ITP_PMODE")
	)
	(segment
		(start 420.262304 -129.248916)
		(end 417.597336 -129.248916)
		(width 0.089408)
		(layer "In2.Cu")
		(net "XDP_ITP_PMODE")
	)
	(segment
		(start 441.738512 -130.994912)
		(end 433.353972 -130.994912)
		(width 0.089408)
		(layer "In2.Cu")
		(net "XDP_ITP_PMODE")
	)
	(segment
		(start 455.124312 -141.407388)
		(end 455.124312 -137.94867)
		(width 0.089408)
		(layer "In2.Cu")
		(net "XDP_ITP_PMODE")
	)
	(segment
		(start 449.2244 -133.3246)
		(end 447.6496 -133.3246)
		(width 0.089408)
		(layer "In2.Cu")
		(net "XDP_ITP_PMODE")
	)
	(segment
		(start 433.176172 -130.817112)
		(end 431.395378 -130.817112)
		(width 0.089408)
		(layer "In2.Cu")
		(net "XDP_ITP_PMODE")
	)
	(segment
		(start 416.0647 -129.782062)
		(end 414.218628 -131.628134)
		(width 0.089408)
		(layer "In2.Cu")
		(net "XDP_ITP_PMODE")
	)
	(segment
		(start 431.085498 -130.507232)
		(end 421.52062 -130.507232)
		(width 0.089408)
		(layer "In2.Cu")
		(net "XDP_ITP_PMODE")
	)
	(segment
		(start 414.218628 -131.628134)
		(end 412.96717 -131.628134)
		(width 0.089408)
		(layer "In2.Cu")
		(net "XDP_ITP_PMODE")
	)
	(segment
		(start 392.5951 -122.984514)
		(end 392.5951 -122.941334)
		(width 0.0889)
		(layer "In2.Cu")
		(net "XDP_ITP_PMODE")
	)
	(segment
		(start 401.74037 -128.999996)
		(end 400.664934 -130.075432)
		(width 0.089408)
		(layer "In2.Cu")
		(net "XDP_ITP_PMODE")
	)
	(segment
		(start 395.80312 -129.420874)
		(end 395.80312 -126.343156)
		(width 0.089408)
		(layer "In2.Cu")
		(net "XDP_ITP_PMODE")
	)
	(segment
		(start 410.339032 -128.999996)
		(end 401.74037 -128.999996)
		(width 0.089408)
		(layer "In2.Cu")
		(net "XDP_ITP_PMODE")
	)
	(segment
		(start 417.220654 -129.625598)
		(end 417.21151 -129.625598)
		(width 0.089408)
		(layer "In2.Cu")
		(net "XDP_ITP_PMODE")
	)
	(segment
		(start 417.21151 -129.625598)
		(end 417.055046 -129.782062)
		(width 0.089408)
		(layer "In2.Cu")
		(net "XDP_ITP_PMODE")
	)
	(segment
		(start 433.353972 -130.994912)
		(end 433.176172 -130.817112)
		(width 0.089408)
		(layer "In2.Cu")
		(net "XDP_ITP_PMODE")
	)
	(segment
		(start 443.1284 -132.3848)
		(end 441.738512 -130.994912)
		(width 0.089408)
		(layer "In2.Cu")
		(net "XDP_ITP_PMODE")
	)
	(segment
		(start 421.52062 -130.507232)
		(end 420.262304 -129.248916)
		(width 0.089408)
		(layer "In2.Cu")
		(net "XDP_ITP_PMODE")
	)
	(segment
		(start 417.055046 -129.782062)
		(end 416.0647 -129.782062)
		(width 0.089408)
		(layer "In2.Cu")
		(net "XDP_ITP_PMODE")
	)
	(segment
		(start 455.377804 -145.962116)
		(end 455.377804 -145.828004)
		(width 0.089408)
		(layer "In2.Cu")
		(net "XDP_ITP_PMODE")
	)
	(segment
		(start 447.6496 -133.3246)
		(end 446.7098 -132.3848)
		(width 0.089408)
		(layer "In2.Cu")
		(net "XDP_ITP_PMODE")
	)
	(segment
		(start 455.37247 -145.96745)
		(end 455.377804 -145.962116)
		(width 0.089408)
		(layer "In2.Cu")
		(net "XDP_ITP_PMODE")
	)
	(segment
		(start 392.5951 -121.267474)
		(end 392.5951 -121.234708)
		(width 0.0889)
		(layer "In2.Cu")
		(net "XDP_ITP_PMODE")
	)
	(segment
		(start 455.124312 -137.94867)
		(end 452.603616 -135.427974)
		(width 0.089408)
		(layer "In2.Cu")
		(net "XDP_ITP_PMODE")
	)
	(segment
		(start 391.6045 -119.550434)
		(end 391.6045 -119.517668)
		(width 0.0889)
		(layer "In2.Cu")
		(net "XDP_ITP_PMODE")
	)
	(segment
		(start 395.187932 -125.727968)
		(end 394.548614 -125.727968)
		(width 0.089408)
		(layer "In2.Cu")
		(net "XDP_ITP_PMODE")
	)
	(segment
		(start 392.0998 -120.408954)
		(end 392.0998 -120.376188)
		(width 0.0889)
		(layer "In2.Cu")
		(net "XDP_ITP_PMODE")
	)
	(segment
		(start 396.457678 -130.075432)
		(end 395.80312 -129.420874)
		(width 0.089408)
		(layer "In2.Cu")
		(net "XDP_ITP_PMODE")
	)
	(segment
		(start 394.51915 -125.698504)
		(end 394.518896 -125.698504)
		(width 0.089408)
		(layer "In2.Cu")
		(net "XDP_ITP_PMODE")
	)
	(segment
		(start 452.603616 -134.323836)
		(end 450.907658 -132.627878)
		(width 0.089408)
		(layer "In2.Cu")
		(net "XDP_ITP_PMODE")
	)
	(segment
		(start 417.597336 -129.248916)
		(end 417.220654 -129.625598)
		(width 0.089408)
		(layer "In2.Cu")
		(net "XDP_ITP_PMODE")
	)
	(segment
		(start 394.548614 -125.727968)
		(end 394.51915 -125.698504)
		(width 0.089408)
		(layer "In2.Cu")
		(net "XDP_ITP_PMODE")
	)
	(segment
		(start 393.0904 -124.269754)
		(end 393.0904 -123.810268)
		(width 0.0889)
		(layer "In2.Cu")
		(net "XDP_ITP_PMODE")
	)
	(segment
		(start 431.395378 -130.817112)
		(end 431.085498 -130.507232)
		(width 0.089408)
		(layer "In2.Cu")
		(net "XDP_ITP_PMODE")
	)
	(segment
		(start 449.921122 -132.627878)
		(end 449.2244 -133.3246)
		(width 0.089408)
		(layer "In2.Cu")
		(net "XDP_ITP_PMODE")
	)
	(segment
		(start 446.7098 -132.3848)
		(end 443.1284 -132.3848)
		(width 0.089408)
		(layer "In2.Cu")
		(net "XDP_ITP_PMODE")
	)
	(segment
		(start 393.34821 -124.527564)
		(end 393.0904 -124.269754)
		(width 0.089408)
		(layer "In2.Cu")
		(net "XDP_ITP_PMODE")
	)
	(segment
		(start 454.715372 -145.165572)
		(end 454.715372 -141.816328)
		(width 0.089408)
		(layer "In2.Cu")
		(net "XDP_ITP_PMODE")
	)
	(segment
		(start 450.907658 -132.627878)
		(end 449.921122 -132.627878)
		(width 0.089408)
		(layer "In2.Cu")
		(net "XDP_ITP_PMODE")
	)
	(segment
		(start 452.603616 -135.427974)
		(end 452.603616 -134.323836)
		(width 0.089408)
		(layer "In2.Cu")
		(net "XDP_ITP_PMODE")
	)
	(segment
		(start 395.80312 -126.343156)
		(end 395.187932 -125.727968)
		(width 0.089408)
		(layer "In2.Cu")
		(net "XDP_ITP_PMODE")
	)
	(segment
		(start 455.377804 -145.828004)
		(end 454.715372 -145.165572)
		(width 0.089408)
		(layer "In2.Cu")
		(net "XDP_ITP_PMODE")
	)
	(segment
		(start 393.34821 -124.527818)
		(end 393.34821 -124.527564)
		(width 0.089408)
		(layer "In2.Cu")
		(net "XDP_ITP_PMODE")
	)
	(segment
		(start 394.518896 -125.698504)
		(end 393.34821 -124.527818)
		(width 0.089408)
		(layer "In2.Cu")
		(net "XDP_ITP_PMODE")
	)
	(segment
		(start 400.664934 -130.075432)
		(end 396.457678 -130.075432)
		(width 0.089408)
		(layer "In2.Cu")
		(net "XDP_ITP_PMODE")
	)
	(segment
		(start 454.715372 -141.816328)
		(end 455.124312 -141.407388)
		(width 0.089408)
		(layer "In2.Cu")
		(net "XDP_ITP_PMODE")
	)
	(arc
		(start 391.6045 -119.517668)
		(mid 391.54815 -119.323818)
		(end 391.404348 -119.182134)
		(width 0.0889)
		(layer "In2.Cu")
		(net "XDP_ITP_PMODE")
	)
	(arc
		(start 391.112248 -118.735348)
		(mid 391.109817 -118.612769)
		(end 391.12952 -118.491762)
		(width 0.0889)
		(layer "In2.Cu")
		(net "XDP_ITP_PMODE")
	)
	(arc
		(start 391.036302 -118.275608)
		(mid 390.624098 -118.045439)
		(end 390.21385 -117.811804)
		(width 0.0889)
		(layer "In2.Cu")
		(net "XDP_ITP_PMODE")
	)
	(arc
		(start 392.5951 -121.234708)
		(mid 392.53875 -121.040858)
		(end 392.394948 -120.899174)
		(width 0.0889)
		(layer "In2.Cu")
		(net "XDP_ITP_PMODE")
	)
	(arc
		(start 392.5951 -122.941334)
		(mid 392.679381 -122.658117)
		(end 392.890248 -122.451114)
		(width 0.0889)
		(layer "In2.Cu")
		(net "XDP_ITP_PMODE")
	)
	(arc
		(start 392.0998 -120.376188)
		(mid 392.04345 -120.182338)
		(end 391.899648 -120.040654)
		(width 0.0889)
		(layer "In2.Cu")
		(net "XDP_ITP_PMODE")
	)
	(arc
		(start 391.12952 -118.491762)
		(mid 391.119926 -118.367697)
		(end 391.036302 -118.275608)
		(width 0.0889)
		(layer "In2.Cu")
		(net "XDP_ITP_PMODE")
	)
	(arc
		(start 392.394948 -120.899174)
		(mid 392.184084 -120.69217)
		(end 392.0998 -120.408954)
		(width 0.0889)
		(layer "In2.Cu")
		(net "XDP_ITP_PMODE")
	)
	(arc
		(start 391.404348 -119.182134)
		(mid 391.204975 -118.993606)
		(end 391.112248 -118.735348)
		(width 0.0889)
		(layer "In2.Cu")
		(net "XDP_ITP_PMODE")
	)
	(arc
		(start 392.890248 -121.757694)
		(mid 392.679384 -121.55069)
		(end 392.5951 -121.267474)
		(width 0.0889)
		(layer "In2.Cu")
		(net "XDP_ITP_PMODE")
	)
	(arc
		(start 393.0904 -123.810268)
		(mid 393.03405 -123.616418)
		(end 392.890248 -123.474734)
		(width 0.0889)
		(layer "In2.Cu")
		(net "XDP_ITP_PMODE")
	)
	(arc
		(start 391.899648 -120.040654)
		(mid 391.688784 -119.83365)
		(end 391.6045 -119.550434)
		(width 0.0889)
		(layer "In2.Cu")
		(net "XDP_ITP_PMODE")
	)
	(arc
		(start 392.890248 -122.451114)
		(mid 393.090559 -122.104404)
		(end 392.890248 -121.757694)
		(width 0.0889)
		(layer "In2.Cu")
		(net "XDP_ITP_PMODE")
	)
	(arc
		(start 392.890248 -123.474734)
		(mid 392.679384 -123.26773)
		(end 392.5951 -122.984514)
		(width 0.0889)
		(layer "In2.Cu")
		(net "XDP_ITP_PMODE")
	)
	(segment
		(start 462.980532 -135.71982)
		(end 464.25358 -135.71982)
		(width 0.10795)
		(layer "F.Cu")
		(net "XDP_DEBUG_CONSENT_N")
	)
	(segment
		(start 391.057638 -82.925666)
		(end 391.534904 -82.4484)
		(width 0.10795)
		(layer "F.Cu")
		(net "XDP_DEBUG_CONSENT_N")
	)
	(segment
		(start 378.81306 -84.22386)
		(end 381.100838 -84.22386)
		(width 0.10795)
		(layer "F.Cu")
		(net "XDP_DEBUG_CONSENT_N")
	)
	(segment
		(start 381.100838 -84.22386)
		(end 381.798068 -84.92109)
		(width 0.10795)
		(layer "F.Cu")
		(net "XDP_DEBUG_CONSENT_N")
	)
	(segment
		(start 375.40565 -83.31835)
		(end 377.90755 -83.31835)
		(width 0.10795)
		(layer "F.Cu")
		(net "XDP_DEBUG_CONSENT_N")
	)
	(segment
		(start 381.798068 -84.92109)
		(end 382.76784 -84.92109)
		(width 0.10795)
		(layer "F.Cu")
		(net "XDP_DEBUG_CONSENT_N")
	)
	(segment
		(start 373.592598 -89.826846)
		(end 373.592598 -86.45779)
		(width 0.10795)
		(layer "F.Cu")
		(net "XDP_DEBUG_CONSENT_N")
	)
	(segment
		(start 385.457954 -85.221572)
		(end 385.590542 -85.088984)
		(width 0.10795)
		(layer "F.Cu")
		(net "XDP_DEBUG_CONSENT_N")
	)
	(segment
		(start 388.005574 -85.089238)
		(end 388.373366 -85.089238)
		(width 0.10795)
		(layer "F.Cu")
		(net "XDP_DEBUG_CONSENT_N")
	)
	(segment
		(start 373.592598 -86.45779)
		(end 373.902986 -86.147402)
		(width 0.10795)
		(layer "F.Cu")
		(net "XDP_DEBUG_CONSENT_N")
	)
	(segment
		(start 385.590542 -85.088984)
		(end 388.00532 -85.088984)
		(width 0.10795)
		(layer "F.Cu")
		(net "XDP_DEBUG_CONSENT_N")
	)
	(segment
		(start 377.90755 -83.31835)
		(end 378.81306 -84.22386)
		(width 0.10795)
		(layer "F.Cu")
		(net "XDP_DEBUG_CONSENT_N")
	)
	(segment
		(start 382.76784 -84.92109)
		(end 383.068322 -85.221572)
		(width 0.10795)
		(layer "F.Cu")
		(net "XDP_DEBUG_CONSENT_N")
	)
	(segment
		(start 373.745252 -89.9795)
		(end 373.592598 -89.826846)
		(width 0.10795)
		(layer "F.Cu")
		(net "XDP_DEBUG_CONSENT_N")
	)
	(segment
		(start 374.015 -89.9795)
		(end 373.745252 -89.9795)
		(width 0.10795)
		(layer "F.Cu")
		(net "XDP_DEBUG_CONSENT_N")
	)
	(segment
		(start 464.4136 -135.5598)
		(end 464.4136 -134.2136)
		(width 0.10795)
		(layer "F.Cu")
		(net "XDP_DEBUG_CONSENT_N")
	)
	(segment
		(start 374.4722 -85.852508)
		(end 374.4722 -84.2518)
		(width 0.10795)
		(layer "F.Cu")
		(net "XDP_DEBUG_CONSENT_N")
	)
	(segment
		(start 464.25358 -135.71982)
		(end 464.4136 -135.5598)
		(width 0.10795)
		(layer "F.Cu")
		(net "XDP_DEBUG_CONSENT_N")
	)
	(segment
		(start 374.177306 -86.147402)
		(end 374.4722 -85.852508)
		(width 0.10795)
		(layer "F.Cu")
		(net "XDP_DEBUG_CONSENT_N")
	)
	(segment
		(start 374.4722 -84.2518)
		(end 375.40565 -83.31835)
		(width 0.10795)
		(layer "F.Cu")
		(net "XDP_DEBUG_CONSENT_N")
	)
	(segment
		(start 463.7786 -133.5786)
		(end 463.7786 -132.969)
		(width 0.10795)
		(layer "F.Cu")
		(net "XDP_DEBUG_CONSENT_N")
	)
	(segment
		(start 390.536938 -82.925666)
		(end 391.057638 -82.925666)
		(width 0.10795)
		(layer "F.Cu")
		(net "XDP_DEBUG_CONSENT_N")
	)
	(segment
		(start 383.068322 -85.221572)
		(end 385.457954 -85.221572)
		(width 0.10795)
		(layer "F.Cu")
		(net "XDP_DEBUG_CONSENT_N")
	)
	(segment
		(start 373.902986 -86.147402)
		(end 374.177306 -86.147402)
		(width 0.10795)
		(layer "F.Cu")
		(net "XDP_DEBUG_CONSENT_N")
	)
	(segment
		(start 388.00532 -85.088984)
		(end 388.005574 -85.089238)
		(width 0.10795)
		(layer "F.Cu")
		(net "XDP_DEBUG_CONSENT_N")
	)
	(segment
		(start 391.534904 -82.4484)
		(end 391.7188 -82.4484)
		(width 0.10795)
		(layer "F.Cu")
		(net "XDP_DEBUG_CONSENT_N")
	)
	(segment
		(start 388.373366 -85.089238)
		(end 390.536938 -82.925666)
		(width 0.10795)
		(layer "F.Cu")
		(net "XDP_DEBUG_CONSENT_N")
	)
	(segment
		(start 464.4136 -134.2136)
		(end 463.7786 -133.5786)
		(width 0.10795)
		(layer "F.Cu")
		(net "XDP_DEBUG_CONSENT_N")
	)
	(via
		(at 391.7188 -82.4484)
		(size 0.508)
		(drill 0.254)
		(layers "F.Cu" "B.Cu")
		(net "XDP_DEBUG_CONSENT_N")
	)
	(via
		(at 439.0898 -119.4308)
		(size 0.508)
		(drill 0.254)
		(layers "F.Cu" "B.Cu")
		(net "XDP_DEBUG_CONSENT_N")
	)
	(via
		(at 463.7786 -132.969)
		(size 0.508)
		(drill 0.254)
		(layers "F.Cu" "B.Cu")
		(net "XDP_DEBUG_CONSENT_N")
	)
	(via
		(at 389.3439 -77.2033)
		(size 0.508)
		(drill 0.254)
		(layers "F.Cu" "B.Cu")
		(net "XDP_DEBUG_CONSENT_N")
	)
	(segment
		(start 420.985696 -100.459032)
		(end 420.985696 -115.755928)
		(width 0.10795)
		(layer "B.Cu")
		(net "XDP_DEBUG_CONSENT_N")
	)
	(segment
		(start 425.419266 -120.56491)
		(end 425.984162 -121.129806)
		(width 0.10795)
		(layer "B.Cu")
		(net "XDP_DEBUG_CONSENT_N")
	)
	(segment
		(start 414.879028 -80.744568)
		(end 414.879028 -81.121504)
		(width 0.10795)
		(layer "B.Cu")
		(net "XDP_DEBUG_CONSENT_N")
	)
	(segment
		(start 437.390794 -121.129806)
		(end 439.0898 -119.4308)
		(width 0.10795)
		(layer "B.Cu")
		(net "XDP_DEBUG_CONSENT_N")
	)
	(segment
		(start 396.529814 -74.472292)
		(end 397.510508 -74.472292)
		(width 0.10795)
		(layer "B.Cu")
		(net "XDP_DEBUG_CONSENT_N")
	)
	(segment
		(start 390.335008 -76.90612)
		(end 390.341358 -76.90612)
		(width 0.10795)
		(layer "B.Cu")
		(net "XDP_DEBUG_CONSENT_N")
	)
	(segment
		(start 399.198338 -71.905368)
		(end 400.120104 -70.983602)
		(width 0.10795)
		(layer "B.Cu")
		(net "XDP_DEBUG_CONSENT_N")
	)
	(segment
		(start 390.341358 -76.90612)
		(end 390.69391 -76.553568)
		(width 0.10795)
		(layer "B.Cu")
		(net "XDP_DEBUG_CONSENT_N")
	)
	(segment
		(start 424.208702 -117.069108)
		(end 425.419266 -118.279672)
		(width 0.10795)
		(layer "B.Cu")
		(net "XDP_DEBUG_CONSENT_N")
	)
	(segment
		(start 397.510508 -74.472292)
		(end 398.018 -73.9648)
		(width 0.10795)
		(layer "B.Cu")
		(net "XDP_DEBUG_CONSENT_N")
	)
	(segment
		(start 416.493706 -82.736182)
		(end 416.493706 -83.512914)
		(width 0.10795)
		(layer "B.Cu")
		(net "XDP_DEBUG_CONSENT_N")
	)
	(segment
		(start 395.958822 -75.043284)
		(end 396.529814 -74.472292)
		(width 0.10795)
		(layer "B.Cu")
		(net "XDP_DEBUG_CONSENT_N")
	)
	(segment
		(start 420.831264 -87.850472)
		(end 420.831264 -93.939106)
		(width 0.10795)
		(layer "B.Cu")
		(net "XDP_DEBUG_CONSENT_N")
	)
	(segment
		(start 390.69391 -76.553568)
		(end 394.482066 -76.553568)
		(width 0.10795)
		(layer "B.Cu")
		(net "XDP_DEBUG_CONSENT_N")
	)
	(segment
		(start 398.018 -73.9648)
		(end 398.018 -73.47458)
		(width 0.10795)
		(layer "B.Cu")
		(net "XDP_DEBUG_CONSENT_N")
	)
	(segment
		(start 425.984162 -121.129806)
		(end 437.390794 -121.129806)
		(width 0.10795)
		(layer "B.Cu")
		(net "XDP_DEBUG_CONSENT_N")
	)
	(segment
		(start 398.508728 -71.905368)
		(end 399.198338 -71.905368)
		(width 0.10795)
		(layer "B.Cu")
		(net "XDP_DEBUG_CONSENT_N")
	)
	(segment
		(start 400.120104 -70.983602)
		(end 410.35097 -70.983602)
		(width 0.10795)
		(layer "B.Cu")
		(net "XDP_DEBUG_CONSENT_N")
	)
	(segment
		(start 414.23717 -80.10271)
		(end 414.879028 -80.744568)
		(width 0.10795)
		(layer "B.Cu")
		(net "XDP_DEBUG_CONSENT_N")
	)
	(segment
		(start 420.831264 -93.939106)
		(end 420.466774 -94.303596)
		(width 0.10795)
		(layer "B.Cu")
		(net "XDP_DEBUG_CONSENT_N")
	)
	(segment
		(start 422.298876 -117.069108)
		(end 424.208702 -117.069108)
		(width 0.10795)
		(layer "B.Cu")
		(net "XDP_DEBUG_CONSENT_N")
	)
	(segment
		(start 395.958822 -75.076812)
		(end 395.958822 -75.043284)
		(width 0.10795)
		(layer "B.Cu")
		(net "XDP_DEBUG_CONSENT_N")
	)
	(segment
		(start 410.35097 -70.983602)
		(end 414.23717 -74.869802)
		(width 0.10795)
		(layer "B.Cu")
		(net "XDP_DEBUG_CONSENT_N")
	)
	(segment
		(start 398.018 -73.47458)
		(end 397.65097 -73.10755)
		(width 0.10795)
		(layer "B.Cu")
		(net "XDP_DEBUG_CONSENT_N")
	)
	(segment
		(start 420.466774 -99.94011)
		(end 420.985696 -100.459032)
		(width 0.10795)
		(layer "B.Cu")
		(net "XDP_DEBUG_CONSENT_N")
	)
	(segment
		(start 414.879028 -81.121504)
		(end 416.493706 -82.736182)
		(width 0.10795)
		(layer "B.Cu")
		(net "XDP_DEBUG_CONSENT_N")
	)
	(segment
		(start 389.3439 -77.2033)
		(end 389.742934 -77.2033)
		(width 0.10795)
		(layer "B.Cu")
		(net "XDP_DEBUG_CONSENT_N")
	)
	(segment
		(start 389.897112 -77.049122)
		(end 390.192006 -77.049122)
		(width 0.10795)
		(layer "B.Cu")
		(net "XDP_DEBUG_CONSENT_N")
	)
	(segment
		(start 397.65097 -72.763126)
		(end 398.508728 -71.905368)
		(width 0.10795)
		(layer "B.Cu")
		(net "XDP_DEBUG_CONSENT_N")
	)
	(segment
		(start 420.466774 -94.303596)
		(end 420.466774 -99.94011)
		(width 0.10795)
		(layer "B.Cu")
		(net "XDP_DEBUG_CONSENT_N")
	)
	(segment
		(start 389.742934 -77.2033)
		(end 389.897112 -77.049122)
		(width 0.10795)
		(layer "B.Cu")
		(net "XDP_DEBUG_CONSENT_N")
	)
	(segment
		(start 425.419266 -118.279672)
		(end 425.419266 -120.56491)
		(width 0.10795)
		(layer "B.Cu")
		(net "XDP_DEBUG_CONSENT_N")
	)
	(segment
		(start 416.493706 -83.512914)
		(end 420.831264 -87.850472)
		(width 0.10795)
		(layer "B.Cu")
		(net "XDP_DEBUG_CONSENT_N")
	)
	(segment
		(start 390.192006 -77.049122)
		(end 390.335008 -76.90612)
		(width 0.10795)
		(layer "B.Cu")
		(net "XDP_DEBUG_CONSENT_N")
	)
	(segment
		(start 414.23717 -74.869802)
		(end 414.23717 -80.10271)
		(width 0.10795)
		(layer "B.Cu")
		(net "XDP_DEBUG_CONSENT_N")
	)
	(segment
		(start 397.65097 -73.10755)
		(end 397.65097 -72.763126)
		(width 0.10795)
		(layer "B.Cu")
		(net "XDP_DEBUG_CONSENT_N")
	)
	(segment
		(start 394.482066 -76.553568)
		(end 395.958822 -75.076812)
		(width 0.10795)
		(layer "B.Cu")
		(net "XDP_DEBUG_CONSENT_N")
	)
	(segment
		(start 420.985696 -115.755928)
		(end 422.298876 -117.069108)
		(width 0.10795)
		(layer "B.Cu")
		(net "XDP_DEBUG_CONSENT_N")
	)
	(segment
		(start 452.066152 -123.339098)
		(end 450.172328 -121.445274)
		(width 0.089408)
		(layer "In9.Cu")
		(net "XDP_DEBUG_CONSENT_N")
	)
	(segment
		(start 439.3438 -119.4308)
		(end 439.0898 -119.4308)
		(width 0.089408)
		(layer "In9.Cu")
		(net "XDP_DEBUG_CONSENT_N")
	)
	(segment
		(start 460.125826 -129.3114)
		(end 453.853296 -129.3114)
		(width 0.089408)
		(layer "In9.Cu")
		(net "XDP_DEBUG_CONSENT_N")
	)
	(segment
		(start 452.37908 -126.018798)
		(end 452.066152 -125.70587)
		(width 0.089408)
		(layer "In9.Cu")
		(net "XDP_DEBUG_CONSENT_N")
	)
	(segment
		(start 452.37908 -127.837184)
		(end 452.37908 -126.018798)
		(width 0.089408)
		(layer "In9.Cu")
		(net "XDP_DEBUG_CONSENT_N")
	)
	(segment
		(start 447.211196 -121.445274)
		(end 447.024506 -121.258584)
		(width 0.089408)
		(layer "In9.Cu")
		(net "XDP_DEBUG_CONSENT_N")
	)
	(segment
		(start 452.066152 -125.70587)
		(end 452.066152 -123.339098)
		(width 0.089408)
		(layer "In9.Cu")
		(net "XDP_DEBUG_CONSENT_N")
	)
	(segment
		(start 450.172328 -121.445274)
		(end 447.211196 -121.445274)
		(width 0.089408)
		(layer "In9.Cu")
		(net "XDP_DEBUG_CONSENT_N")
	)
	(segment
		(start 463.569304 -132.759704)
		(end 463.569304 -132.754878)
		(width 0.089408)
		(layer "In9.Cu")
		(net "XDP_DEBUG_CONSENT_N")
	)
	(segment
		(start 463.569304 -132.754878)
		(end 460.125826 -129.3114)
		(width 0.089408)
		(layer "In9.Cu")
		(net "XDP_DEBUG_CONSENT_N")
	)
	(segment
		(start 453.853296 -129.3114)
		(end 452.37908 -127.837184)
		(width 0.089408)
		(layer "In9.Cu")
		(net "XDP_DEBUG_CONSENT_N")
	)
	(segment
		(start 447.024506 -121.258584)
		(end 441.171584 -121.258584)
		(width 0.089408)
		(layer "In9.Cu")
		(net "XDP_DEBUG_CONSENT_N")
	)
	(segment
		(start 463.7786 -132.969)
		(end 463.569304 -132.759704)
		(width 0.089408)
		(layer "In9.Cu")
		(net "XDP_DEBUG_CONSENT_N")
	)
	(segment
		(start 441.171584 -121.258584)
		(end 439.3438 -119.4308)
		(width 0.089408)
		(layer "In9.Cu")
		(net "XDP_DEBUG_CONSENT_N")
	)
	(segment
		(start 391.7188 -82.4484)
		(end 391.43432 -82.4484)
		(width 0.089408)
		(layer "In11.Cu")
		(net "XDP_DEBUG_CONSENT_N")
	)
	(segment
		(start 389.3439 -77.547978)
		(end 389.3439 -77.2033)
		(width 0.089408)
		(layer "In11.Cu")
		(net "XDP_DEBUG_CONSENT_N")
	)
	(segment
		(start 391.43432 -82.4484)
		(end 390.33704 -81.35112)
		(width 0.089408)
		(layer "In11.Cu")
		(net "XDP_DEBUG_CONSENT_N")
	)
	(segment
		(start 390.33704 -81.35112)
		(end 390.33704 -78.542642)
		(width 0.089408)
		(layer "In11.Cu")
		(net "XDP_DEBUG_CONSENT_N")
	)
	(segment
		(start 390.33704 -78.542642)
		(end 389.3439 -77.547978)
		(width 0.089408)
		(layer "In11.Cu")
		(net "XDP_DEBUG_CONSENT_N")
	)
	(segment
		(start 367.4872 -94.7928)
		(end 367.0554 -95.2246)
		(width 0.10795)
		(layer "F.Cu")
		(net "XDP_CPU_PWR_DEBUG_N")
	)
	(segment
		(start 450.461634 -142.60957)
		(end 452.105522 -142.60957)
		(width 0.10795)
		(layer "F.Cu")
		(net "XDP_CPU_PWR_DEBUG_N")
	)
	(segment
		(start 128.514348 -67.791584)
		(end 129.085848 -67.791584)
		(width 0.1016)
		(layer "F.Cu")
		(net "XDP_CPU_PWR_DEBUG_N")
	)
	(segment
		(start 466.715348 -147.1295)
		(end 466.09 -147.1295)
		(width 0.10795)
		(layer "F.Cu")
		(net "XDP_CPU_PWR_DEBUG_N")
	)
	(segment
		(start 452.105522 -142.60957)
		(end 452.220076 -142.495016)
		(width 0.10795)
		(layer "F.Cu")
		(net "XDP_CPU_PWR_DEBUG_N")
	)
	(segment
		(start 293.51478 -67.791584)
		(end 294.08628 -67.791584)
		(width 0.1016)
		(layer "F.Cu")
		(net "XDP_CPU_PWR_DEBUG_N")
	)
	(segment
		(start 367.4872 -93.476572)
		(end 367.4872 -94.7928)
		(width 0.10795)
		(layer "F.Cu")
		(net "XDP_CPU_PWR_DEBUG_N")
	)
	(segment
		(start 464.982052 -146.719798)
		(end 462.980278 -146.719798)
		(width 0.10795)
		(layer "F.Cu")
		(net "XDP_CPU_PWR_DEBUG_N")
	)
	(segment
		(start 466.733636 -147.147788)
		(end 466.715348 -147.1295)
		(width 0.10795)
		(layer "F.Cu")
		(net "XDP_CPU_PWR_DEBUG_N")
	)
	(segment
		(start 466.09 -147.1295)
		(end 465.391754 -147.1295)
		(width 0.10795)
		(layer "F.Cu")
		(net "XDP_CPU_PWR_DEBUG_N")
	)
	(segment
		(start 465.391754 -147.1295)
		(end 464.982052 -146.719798)
		(width 0.10795)
		(layer "F.Cu")
		(net "XDP_CPU_PWR_DEBUG_N")
	)
	(segment
		(start 452.220076 -142.495016)
		(end 452.220076 -142.513304)
		(width 0.10795)
		(layer "F.Cu")
		(net "XDP_CPU_PWR_DEBUG_N")
	)
	(via
		(at 367.0554 -95.2246)
		(size 0.508)
		(drill 0.254)
		(layers "F.Cu" "B.Cu")
		(net "XDP_CPU_PWR_DEBUG_N")
	)
	(via
		(at 309.372 -55.3974)
		(size 0.508)
		(drill 0.254)
		(layers "F.Cu" "B.Cu")
		(net "XDP_CPU_PWR_DEBUG_N")
	)
	(via
		(at 466.733636 -147.147788)
		(size 0.508)
		(drill 0.254)
		(layers "F.Cu" "B.Cu")
		(net "XDP_CPU_PWR_DEBUG_N")
	)
	(via
		(at 294.08628 -67.791584)
		(size 0.508)
		(drill 0.254)
		(layers "F.Cu" "B.Cu")
		(net "XDP_CPU_PWR_DEBUG_N")
	)
	(via
		(at 452.220076 -142.513304)
		(size 0.508)
		(drill 0.254)
		(layers "F.Cu" "B.Cu")
		(net "XDP_CPU_PWR_DEBUG_N")
	)
	(via
		(at 129.085848 -67.791584)
		(size 0.508)
		(drill 0.254)
		(layers "F.Cu" "B.Cu")
		(net "XDP_CPU_PWR_DEBUG_N")
	)
	(via
		(at 320.762122 -126.378462)
		(size 0.508)
		(drill 0.254)
		(layers "F.Cu" "B.Cu")
		(net "XDP_CPU_PWR_DEBUG_N")
	)
	(via
		(at 364.3122 -63.9064)
		(size 0.508)
		(drill 0.254)
		(layers "F.Cu" "B.Cu")
		(net "XDP_CPU_PWR_DEBUG_N")
	)
	(via
		(at 176.784 -126.1872)
		(size 0.508)
		(drill 0.254)
		(layers "F.Cu" "B.Cu")
		(net "XDP_CPU_PWR_DEBUG_N")
	)
	(segment
		(start 466.733636 -147.147788)
		(end 466.652102 -147.066254)
		(width 0.10795)
		(layer "B.Cu")
		(net "XDP_CPU_PWR_DEBUG_N")
	)
	(segment
		(start 466.652102 -147.066254)
		(end 465.595208 -147.066254)
		(width 0.10795)
		(layer "B.Cu")
		(net "XDP_CPU_PWR_DEBUG_N")
	)
	(segment
		(start 466.014562 -147.866862)
		(end 466.733636 -147.147788)
		(width 0.089408)
		(layer "In2.Cu")
		(net "XDP_CPU_PWR_DEBUG_N")
	)
	(segment
		(start 369.984782 -137.330942)
		(end 369.98529 -137.330942)
		(width 0.089408)
		(layer "In2.Cu")
		(net "XDP_CPU_PWR_DEBUG_N")
	)
	(segment
		(start 340.0298 -126.5174)
		(end 340.0298 -126.7968)
		(width 0.089408)
		(layer "In2.Cu")
		(net "XDP_CPU_PWR_DEBUG_N")
	)
	(segment
		(start 437.919622 -146.655282)
		(end 440.406536 -146.655282)
		(width 0.089408)
		(layer "In2.Cu")
		(net "XDP_CPU_PWR_DEBUG_N")
	)
	(segment
		(start 431.405792 -155.834588)
		(end 431.405792 -149.872192)
		(width 0.089408)
		(layer "In2.Cu")
		(net "XDP_CPU_PWR_DEBUG_N")
	)
	(segment
		(start 431.5079 -146.2532)
		(end 437.51754 -146.2532)
		(width 0.089408)
		(layer "In2.Cu")
		(net "XDP_CPU_PWR_DEBUG_N")
	)
	(segment
		(start 451.67296 -153.2763)
		(end 453.9107 -153.2763)
		(width 0.089408)
		(layer "In2.Cu")
		(net "XDP_CPU_PWR_DEBUG_N")
	)
	(segment
		(start 431.405792 -149.872192)
		(end 430.8602 -149.3266)
		(width 0.089408)
		(layer "In2.Cu")
		(net "XDP_CPU_PWR_DEBUG_N")
	)
	(segment
		(start 354.5332 -128.016)
		(end 354.749608 -127.799592)
		(width 0.089408)
		(layer "In2.Cu")
		(net "XDP_CPU_PWR_DEBUG_N")
	)
	(segment
		(start 340.0298 -126.7968)
		(end 340.508082 -127.275082)
		(width 0.089408)
		(layer "In2.Cu")
		(net "XDP_CPU_PWR_DEBUG_N")
	)
	(segment
		(start 437.51754 -146.2532)
		(end 437.919622 -146.655282)
		(width 0.089408)
		(layer "In2.Cu")
		(net "XDP_CPU_PWR_DEBUG_N")
	)
	(segment
		(start 348.5642 -127.63246)
		(end 348.94774 -128.016)
		(width 0.089408)
		(layer "In2.Cu")
		(net "XDP_CPU_PWR_DEBUG_N")
	)
	(segment
		(start 345.232228 -127.275082)
		(end 345.589606 -127.63246)
		(width 0.089408)
		(layer "In2.Cu")
		(net "XDP_CPU_PWR_DEBUG_N")
	)
	(segment
		(start 447.307716 -152.81402)
		(end 448.75958 -152.81402)
		(width 0.089408)
		(layer "In2.Cu")
		(net "XDP_CPU_PWR_DEBUG_N")
	)
	(segment
		(start 453.9107 -153.2763)
		(end 457.327 -149.86)
		(width 0.089408)
		(layer "In2.Cu")
		(net "XDP_CPU_PWR_DEBUG_N")
	)
	(segment
		(start 411.5181 -151.6507)
		(end 411.5181 -155.98648)
		(width 0.089408)
		(layer "In2.Cu")
		(net "XDP_CPU_PWR_DEBUG_N")
	)
	(segment
		(start 370.214652 -137.560304)
		(end 376.515122 -137.560304)
		(width 0.089408)
		(layer "In2.Cu")
		(net "XDP_CPU_PWR_DEBUG_N")
	)
	(segment
		(start 397.409416 -141.758416)
		(end 398.4752 -142.8242)
		(width 0.089408)
		(layer "In2.Cu")
		(net "XDP_CPU_PWR_DEBUG_N")
	)
	(segment
		(start 345.589606 -127.63246)
		(end 348.5642 -127.63246)
		(width 0.089408)
		(layer "In2.Cu")
		(net "XDP_CPU_PWR_DEBUG_N")
	)
	(segment
		(start 441.960254 -148.209)
		(end 442.702696 -148.209)
		(width 0.089408)
		(layer "In2.Cu")
		(net "XDP_CPU_PWR_DEBUG_N")
	)
	(segment
		(start 367.06556 -137.317226)
		(end 369.971066 -137.317226)
		(width 0.089408)
		(layer "In2.Cu")
		(net "XDP_CPU_PWR_DEBUG_N")
	)
	(segment
		(start 339.6742 -126.1618)
		(end 340.0298 -126.5174)
		(width 0.089408)
		(layer "In2.Cu")
		(net "XDP_CPU_PWR_DEBUG_N")
	)
	(segment
		(start 430.8602 -149.3266)
		(end 430.8602 -146.9009)
		(width 0.089408)
		(layer "In2.Cu")
		(net "XDP_CPU_PWR_DEBUG_N")
	)
	(segment
		(start 335.161382 -128.141984)
		(end 337.141566 -126.1618)
		(width 0.089408)
		(layer "In2.Cu")
		(net "XDP_CPU_PWR_DEBUG_N")
	)
	(segment
		(start 412.877 -149.6314)
		(end 412.877 -150.2918)
		(width 0.089408)
		(layer "In2.Cu")
		(net "XDP_CPU_PWR_DEBUG_N")
	)
	(segment
		(start 391.580624 -141.758416)
		(end 397.409416 -141.758416)
		(width 0.089408)
		(layer "In2.Cu")
		(net "XDP_CPU_PWR_DEBUG_N")
	)
	(segment
		(start 379.602238 -140.64742)
		(end 390.469628 -140.64742)
		(width 0.089408)
		(layer "In2.Cu")
		(net "XDP_CPU_PWR_DEBUG_N")
	)
	(segment
		(start 360.641392 -127.799592)
		(end 364.363 -131.5212)
		(width 0.089408)
		(layer "In2.Cu")
		(net "XDP_CPU_PWR_DEBUG_N")
	)
	(segment
		(start 364.363 -133.480556)
		(end 366.27054 -135.388096)
		(width 0.089408)
		(layer "In2.Cu")
		(net "XDP_CPU_PWR_DEBUG_N")
	)
	(segment
		(start 442.702696 -148.209)
		(end 447.307716 -152.81402)
		(width 0.089408)
		(layer "In2.Cu")
		(net "XDP_CPU_PWR_DEBUG_N")
	)
	(segment
		(start 429.824388 -157.415992)
		(end 431.405792 -155.834588)
		(width 0.089408)
		(layer "In2.Cu")
		(net "XDP_CPU_PWR_DEBUG_N")
	)
	(segment
		(start 464.796886 -149.320504)
		(end 466.014562 -148.102828)
		(width 0.089408)
		(layer "In2.Cu")
		(net "XDP_CPU_PWR_DEBUG_N")
	)
	(segment
		(start 328.772774 -126.953518)
		(end 329.162664 -127.343408)
		(width 0.089408)
		(layer "In2.Cu")
		(net "XDP_CPU_PWR_DEBUG_N")
	)
	(segment
		(start 320.762122 -126.378462)
		(end 320.762122 -126.184914)
		(width 0.089408)
		(layer "In2.Cu")
		(net "XDP_CPU_PWR_DEBUG_N")
	)
	(segment
		(start 323.086222 -125.40742)
		(end 324.63232 -126.953518)
		(width 0.089408)
		(layer "In2.Cu")
		(net "XDP_CPU_PWR_DEBUG_N")
	)
	(segment
		(start 366.27054 -136.522206)
		(end 367.06556 -137.317226)
		(width 0.089408)
		(layer "In2.Cu")
		(net "XDP_CPU_PWR_DEBUG_N")
	)
	(segment
		(start 412.877 -150.2918)
		(end 411.5181 -151.6507)
		(width 0.089408)
		(layer "In2.Cu")
		(net "XDP_CPU_PWR_DEBUG_N")
	)
	(segment
		(start 354.749608 -127.799592)
		(end 360.641392 -127.799592)
		(width 0.089408)
		(layer "In2.Cu")
		(net "XDP_CPU_PWR_DEBUG_N")
	)
	(segment
		(start 440.406536 -146.655282)
		(end 441.960254 -148.209)
		(width 0.089408)
		(layer "In2.Cu")
		(net "XDP_CPU_PWR_DEBUG_N")
	)
	(segment
		(start 464.29549 -149.86)
		(end 464.796886 -149.358604)
		(width 0.089408)
		(layer "In2.Cu")
		(net "XDP_CPU_PWR_DEBUG_N")
	)
	(segment
		(start 410.8196 -147.574)
		(end 412.877 -149.6314)
		(width 0.089408)
		(layer "In2.Cu")
		(net "XDP_CPU_PWR_DEBUG_N")
	)
	(segment
		(start 348.94774 -128.016)
		(end 354.5332 -128.016)
		(width 0.089408)
		(layer "In2.Cu")
		(net "XDP_CPU_PWR_DEBUG_N")
	)
	(segment
		(start 321.539616 -125.40742)
		(end 323.086222 -125.40742)
		(width 0.089408)
		(layer "In2.Cu")
		(net "XDP_CPU_PWR_DEBUG_N")
	)
	(segment
		(start 409.2956 -147.574)
		(end 410.8196 -147.574)
		(width 0.089408)
		(layer "In2.Cu")
		(net "XDP_CPU_PWR_DEBUG_N")
	)
	(segment
		(start 331.773784 -128.141984)
		(end 335.161382 -128.141984)
		(width 0.089408)
		(layer "In2.Cu")
		(net "XDP_CPU_PWR_DEBUG_N")
	)
	(segment
		(start 464.796886 -149.358604)
		(end 464.796886 -149.320504)
		(width 0.089408)
		(layer "In2.Cu")
		(net "XDP_CPU_PWR_DEBUG_N")
	)
	(segment
		(start 457.327 -149.86)
		(end 464.29549 -149.86)
		(width 0.089408)
		(layer "In2.Cu")
		(net "XDP_CPU_PWR_DEBUG_N")
	)
	(segment
		(start 399.850102 -147.907502)
		(end 405.062182 -147.907502)
		(width 0.089408)
		(layer "In2.Cu")
		(net "XDP_CPU_PWR_DEBUG_N")
	)
	(segment
		(start 320.762122 -126.184914)
		(end 321.539616 -125.40742)
		(width 0.089408)
		(layer "In2.Cu")
		(net "XDP_CPU_PWR_DEBUG_N")
	)
	(segment
		(start 398.4752 -146.5326)
		(end 399.850102 -147.907502)
		(width 0.089408)
		(layer "In2.Cu")
		(net "XDP_CPU_PWR_DEBUG_N")
	)
	(segment
		(start 466.014562 -148.102828)
		(end 466.014562 -147.866862)
		(width 0.089408)
		(layer "In2.Cu")
		(net "XDP_CPU_PWR_DEBUG_N")
	)
	(segment
		(start 430.8602 -146.9009)
		(end 431.5079 -146.2532)
		(width 0.089408)
		(layer "In2.Cu")
		(net "XDP_CPU_PWR_DEBUG_N")
	)
	(segment
		(start 408.2542 -148.6154)
		(end 409.2956 -147.574)
		(width 0.089408)
		(layer "In2.Cu")
		(net "XDP_CPU_PWR_DEBUG_N")
	)
	(segment
		(start 369.98529 -137.330942)
		(end 370.214652 -137.560304)
		(width 0.089408)
		(layer "In2.Cu")
		(net "XDP_CPU_PWR_DEBUG_N")
	)
	(segment
		(start 390.469628 -140.64742)
		(end 391.580624 -141.758416)
		(width 0.089408)
		(layer "In2.Cu")
		(net "XDP_CPU_PWR_DEBUG_N")
	)
	(segment
		(start 405.062182 -147.907502)
		(end 405.77008 -148.6154)
		(width 0.089408)
		(layer "In2.Cu")
		(net "XDP_CPU_PWR_DEBUG_N")
	)
	(segment
		(start 376.515122 -137.560304)
		(end 379.602238 -140.64742)
		(width 0.089408)
		(layer "In2.Cu")
		(net "XDP_CPU_PWR_DEBUG_N")
	)
	(segment
		(start 340.508082 -127.275082)
		(end 345.232228 -127.275082)
		(width 0.089408)
		(layer "In2.Cu")
		(net "XDP_CPU_PWR_DEBUG_N")
	)
	(segment
		(start 411.5181 -155.98648)
		(end 412.947612 -157.415992)
		(width 0.089408)
		(layer "In2.Cu")
		(net "XDP_CPU_PWR_DEBUG_N")
	)
	(segment
		(start 330.975208 -127.343408)
		(end 331.773784 -128.141984)
		(width 0.089408)
		(layer "In2.Cu")
		(net "XDP_CPU_PWR_DEBUG_N")
	)
	(segment
		(start 369.971066 -137.317226)
		(end 369.984782 -137.330942)
		(width 0.089408)
		(layer "In2.Cu")
		(net "XDP_CPU_PWR_DEBUG_N")
	)
	(segment
		(start 337.141566 -126.1618)
		(end 339.6742 -126.1618)
		(width 0.089408)
		(layer "In2.Cu")
		(net "XDP_CPU_PWR_DEBUG_N")
	)
	(segment
		(start 405.77008 -148.6154)
		(end 408.2542 -148.6154)
		(width 0.089408)
		(layer "In2.Cu")
		(net "XDP_CPU_PWR_DEBUG_N")
	)
	(segment
		(start 448.75958 -152.81402)
		(end 449.45046 -152.12314)
		(width 0.089408)
		(layer "In2.Cu")
		(net "XDP_CPU_PWR_DEBUG_N")
	)
	(segment
		(start 364.363 -131.5212)
		(end 364.363 -133.480556)
		(width 0.089408)
		(layer "In2.Cu")
		(net "XDP_CPU_PWR_DEBUG_N")
	)
	(segment
		(start 449.45046 -152.12314)
		(end 450.5198 -152.12314)
		(width 0.089408)
		(layer "In2.Cu")
		(net "XDP_CPU_PWR_DEBUG_N")
	)
	(segment
		(start 450.5198 -152.12314)
		(end 451.67296 -153.2763)
		(width 0.089408)
		(layer "In2.Cu")
		(net "XDP_CPU_PWR_DEBUG_N")
	)
	(segment
		(start 398.4752 -142.8242)
		(end 398.4752 -146.5326)
		(width 0.089408)
		(layer "In2.Cu")
		(net "XDP_CPU_PWR_DEBUG_N")
	)
	(segment
		(start 366.27054 -135.388096)
		(end 366.27054 -136.522206)
		(width 0.089408)
		(layer "In2.Cu")
		(net "XDP_CPU_PWR_DEBUG_N")
	)
	(segment
		(start 329.162664 -127.343408)
		(end 330.975208 -127.343408)
		(width 0.089408)
		(layer "In2.Cu")
		(net "XDP_CPU_PWR_DEBUG_N")
	)
	(segment
		(start 412.947612 -157.415992)
		(end 429.824388 -157.415992)
		(width 0.089408)
		(layer "In2.Cu")
		(net "XDP_CPU_PWR_DEBUG_N")
	)
	(segment
		(start 324.63232 -126.953518)
		(end 328.772774 -126.953518)
		(width 0.089408)
		(layer "In2.Cu")
		(net "XDP_CPU_PWR_DEBUG_N")
	)
	(segment
		(start 319.3796 -101.5746)
		(end 317.2206 -101.5746)
		(width 0.089408)
		(layer "In4.Cu")
		(net "XDP_CPU_PWR_DEBUG_N")
	)
	(segment
		(start 330.203048 -80.511904)
		(end 328.67219 -82.042762)
		(width 0.089408)
		(layer "In4.Cu")
		(net "XDP_CPU_PWR_DEBUG_N")
	)
	(segment
		(start 335.242408 -71.193914)
		(end 334.178402 -71.193914)
		(width 0.089408)
		(layer "In4.Cu")
		(net "XDP_CPU_PWR_DEBUG_N")
	)
	(segment
		(start 335.859628 -70.576694)
		(end 335.242408 -71.193914)
		(width 0.089408)
		(layer "In4.Cu")
		(net "XDP_CPU_PWR_DEBUG_N")
	)
	(segment
		(start 352.52279 -68.447158)
		(end 352.522536 -68.446904)
		(width 0.089408)
		(layer "In4.Cu")
		(net "XDP_CPU_PWR_DEBUG_N")
	)
	(segment
		(start 315.242702 -100.6094)
		(end 314.883292 -100.96881)
		(width 0.089408)
		(layer "In4.Cu")
		(net "XDP_CPU_PWR_DEBUG_N")
	)
	(segment
		(start 316.2554 -100.6094)
		(end 315.242702 -100.6094)
		(width 0.089408)
		(layer "In4.Cu")
		(net "XDP_CPU_PWR_DEBUG_N")
	)
	(segment
		(start 352.522536 -68.446904)
		(end 344.924126 -68.446904)
		(width 0.089408)
		(layer "In4.Cu")
		(net "XDP_CPU_PWR_DEBUG_N")
	)
	(segment
		(start 328.67219 -82.042762)
		(end 328.67219 -84.278978)
		(width 0.089408)
		(layer "In4.Cu")
		(net "XDP_CPU_PWR_DEBUG_N")
	)
	(segment
		(start 321.899026 -91.259406)
		(end 321.899026 -91.732354)
		(width 0.089408)
		(layer "In4.Cu")
		(net "XDP_CPU_PWR_DEBUG_N")
	)
	(segment
		(start 316.478158 -120.999504)
		(end 319.073276 -120.999504)
		(width 0.089408)
		(layer "In4.Cu")
		(net "XDP_CPU_PWR_DEBUG_N")
	)
	(segment
		(start 332.4606 -76.347828)
		(end 330.203048 -78.60538)
		(width 0.089408)
		(layer "In4.Cu")
		(net "XDP_CPU_PWR_DEBUG_N")
	)
	(segment
		(start 359.966514 -67.413886)
		(end 358.351328 -67.413886)
		(width 0.089408)
		(layer "In4.Cu")
		(net "XDP_CPU_PWR_DEBUG_N")
	)
	(segment
		(start 321.899026 -91.732354)
		(end 321.89928 -91.732608)
		(width 0.089408)
		(layer "In4.Cu")
		(net "XDP_CPU_PWR_DEBUG_N")
	)
	(segment
		(start 358.351328 -67.413886)
		(end 357.318056 -68.447158)
		(width 0.089408)
		(layer "In4.Cu")
		(net "XDP_CPU_PWR_DEBUG_N")
	)
	(segment
		(start 321.89928 -99.05492)
		(end 319.3796 -101.5746)
		(width 0.089408)
		(layer "In4.Cu")
		(net "XDP_CPU_PWR_DEBUG_N")
	)
	(segment
		(start 317.2206 -101.5746)
		(end 316.2554 -100.6094)
		(width 0.089408)
		(layer "In4.Cu")
		(net "XDP_CPU_PWR_DEBUG_N")
	)
	(segment
		(start 364.3122 -63.9064)
		(end 363.474 -63.9064)
		(width 0.089408)
		(layer "In4.Cu")
		(net "XDP_CPU_PWR_DEBUG_N")
	)
	(segment
		(start 338.94649 -70.576694)
		(end 335.859628 -70.576694)
		(width 0.089408)
		(layer "In4.Cu")
		(net "XDP_CPU_PWR_DEBUG_N")
	)
	(segment
		(start 334.178402 -71.193914)
		(end 333.1464 -72.225916)
		(width 0.089408)
		(layer "In4.Cu")
		(net "XDP_CPU_PWR_DEBUG_N")
	)
	(segment
		(start 321.89928 -91.051888)
		(end 321.89928 -91.258898)
		(width 0.089408)
		(layer "In4.Cu")
		(net "XDP_CPU_PWR_DEBUG_N")
	)
	(segment
		(start 328.67219 -84.278978)
		(end 321.89928 -91.051888)
		(width 0.089408)
		(layer "In4.Cu")
		(net "XDP_CPU_PWR_DEBUG_N")
	)
	(segment
		(start 339.89391 -69.629274)
		(end 338.94649 -70.576694)
		(width 0.089408)
		(layer "In4.Cu")
		(net "XDP_CPU_PWR_DEBUG_N")
	)
	(segment
		(start 320.899028 -126.241556)
		(end 320.762122 -126.378462)
		(width 0.089408)
		(layer "In4.Cu")
		(net "XDP_CPU_PWR_DEBUG_N")
	)
	(segment
		(start 321.89928 -91.258898)
		(end 321.899026 -91.259406)
		(width 0.089408)
		(layer "In4.Cu")
		(net "XDP_CPU_PWR_DEBUG_N")
	)
	(segment
		(start 344.924126 -68.446904)
		(end 343.741756 -69.629274)
		(width 0.089408)
		(layer "In4.Cu")
		(net "XDP_CPU_PWR_DEBUG_N")
	)
	(segment
		(start 333.1464 -72.225916)
		(end 333.1464 -72.898)
		(width 0.089408)
		(layer "In4.Cu")
		(net "XDP_CPU_PWR_DEBUG_N")
	)
	(segment
		(start 332.4606 -73.5838)
		(end 332.4606 -76.347828)
		(width 0.089408)
		(layer "In4.Cu")
		(net "XDP_CPU_PWR_DEBUG_N")
	)
	(segment
		(start 319.463166 -120.99925)
		(end 320.899028 -122.435112)
		(width 0.089408)
		(layer "In4.Cu")
		(net "XDP_CPU_PWR_DEBUG_N")
	)
	(segment
		(start 319.073276 -120.999504)
		(end 319.07353 -120.99925)
		(width 0.089408)
		(layer "In4.Cu")
		(net "XDP_CPU_PWR_DEBUG_N")
	)
	(segment
		(start 363.474 -63.9064)
		(end 359.966514 -67.413886)
		(width 0.089408)
		(layer "In4.Cu")
		(net "XDP_CPU_PWR_DEBUG_N")
	)
	(segment
		(start 314.883292 -100.96881)
		(end 314.883292 -119.404638)
		(width 0.089408)
		(layer "In4.Cu")
		(net "XDP_CPU_PWR_DEBUG_N")
	)
	(segment
		(start 321.89928 -91.732608)
		(end 321.89928 -99.05492)
		(width 0.089408)
		(layer "In4.Cu")
		(net "XDP_CPU_PWR_DEBUG_N")
	)
	(segment
		(start 314.883292 -119.404638)
		(end 316.478158 -120.999504)
		(width 0.089408)
		(layer "In4.Cu")
		(net "XDP_CPU_PWR_DEBUG_N")
	)
	(segment
		(start 330.203048 -78.60538)
		(end 330.203048 -80.511904)
		(width 0.089408)
		(layer "In4.Cu")
		(net "XDP_CPU_PWR_DEBUG_N")
	)
	(segment
		(start 320.899028 -122.435112)
		(end 320.899028 -126.241556)
		(width 0.089408)
		(layer "In4.Cu")
		(net "XDP_CPU_PWR_DEBUG_N")
	)
	(segment
		(start 333.1464 -72.898)
		(end 332.4606 -73.5838)
		(width 0.089408)
		(layer "In4.Cu")
		(net "XDP_CPU_PWR_DEBUG_N")
	)
	(segment
		(start 319.07353 -120.99925)
		(end 319.463166 -120.99925)
		(width 0.089408)
		(layer "In4.Cu")
		(net "XDP_CPU_PWR_DEBUG_N")
	)
	(segment
		(start 357.318056 -68.447158)
		(end 352.52279 -68.447158)
		(width 0.089408)
		(layer "In4.Cu")
		(net "XDP_CPU_PWR_DEBUG_N")
	)
	(segment
		(start 343.741756 -69.629274)
		(end 339.89391 -69.629274)
		(width 0.089408)
		(layer "In4.Cu")
		(net "XDP_CPU_PWR_DEBUG_N")
	)
	(segment
		(start 294.08628 -67.791584)
		(end 295.5798 -67.791584)
		(width 0.089408)
		(layer "In9.Cu")
		(net "XDP_CPU_PWR_DEBUG_N")
	)
	(segment
		(start 305.0286 -58.9026)
		(end 305.271932 -58.9026)
		(width 0.089408)
		(layer "In9.Cu")
		(net "XDP_CPU_PWR_DEBUG_N")
	)
	(segment
		(start 298.2214 -60.8076)
		(end 298.6532 -60.8076)
		(width 0.089408)
		(layer "In9.Cu")
		(net "XDP_CPU_PWR_DEBUG_N")
	)
	(segment
		(start 299.4152 -60.4012)
		(end 299.8597 -60.8457)
		(width 0.089408)
		(layer "In9.Cu")
		(net "XDP_CPU_PWR_DEBUG_N")
	)
	(segment
		(start 299.0596 -60.4012)
		(end 299.4152 -60.4012)
		(width 0.089408)
		(layer "In9.Cu")
		(net "XDP_CPU_PWR_DEBUG_N")
	)
	(segment
		(start 306.456842 -57.694322)
		(end 306.452016 -57.685686)
		(width 0.0889)
		(layer "In9.Cu")
		(net "XDP_CPU_PWR_DEBUG_N")
	)
	(segment
		(start 180.797708 -125.819408)
		(end 191.120268 -125.819408)
		(width 0.089408)
		(layer "In9.Cu")
		(net "XDP_CPU_PWR_DEBUG_N")
	)
	(segment
		(start 306.766214 -56.650636)
		(end 307.405786 -56.011064)
		(width 0.089408)
		(layer "In9.Cu")
		(net "XDP_CPU_PWR_DEBUG_N")
	)
	(segment
		(start 222.342456 -125.281944)
		(end 224.275396 -123.349004)
		(width 0.089408)
		(layer "In9.Cu")
		(net "XDP_CPU_PWR_DEBUG_N")
	)
	(segment
		(start 309.996078 -126.79934)
		(end 320.1416 -126.79934)
		(width 0.089408)
		(layer "In9.Cu")
		(net "XDP_CPU_PWR_DEBUG_N")
	)
	(segment
		(start 320.1416 -126.79934)
		(end 320.562478 -126.378462)
		(width 0.089408)
		(layer "In9.Cu")
		(net "XDP_CPU_PWR_DEBUG_N")
	)
	(segment
		(start 306.452016 -57.685686)
		(end 306.445666 -57.675018)
		(width 0.0889)
		(layer "In9.Cu")
		(net "XDP_CPU_PWR_DEBUG_N")
	)
	(segment
		(start 296.2402 -62.0522)
		(end 296.4688 -61.8236)
		(width 0.089408)
		(layer "In9.Cu")
		(net "XDP_CPU_PWR_DEBUG_N")
	)
	(segment
		(start 305.271932 -58.9026)
		(end 305.514756 -58.694574)
		(width 0.0889)
		(layer "In9.Cu")
		(net "XDP_CPU_PWR_DEBUG_N")
	)
	(segment
		(start 305.514756 -58.694574)
		(end 305.593496 -58.581036)
		(width 0.0889)
		(layer "In9.Cu")
		(net "XDP_CPU_PWR_DEBUG_N")
	)
	(segment
		(start 296.2402 -67.131184)
		(end 296.2402 -62.0522)
		(width 0.089408)
		(layer "In9.Cu")
		(net "XDP_CPU_PWR_DEBUG_N")
	)
	(segment
		(start 306.352194 -123.155456)
		(end 309.996078 -126.79934)
		(width 0.089408)
		(layer "In9.Cu")
		(net "XDP_CPU_PWR_DEBUG_N")
	)
	(segment
		(start 299.8597 -60.8457)
		(end 300.2661 -60.8457)
		(width 0.089408)
		(layer "In9.Cu")
		(net "XDP_CPU_PWR_DEBUG_N")
	)
	(segment
		(start 264.836148 -123.155456)
		(end 306.352194 -123.155456)
		(width 0.089408)
		(layer "In9.Cu")
		(net "XDP_CPU_PWR_DEBUG_N")
	)
	(segment
		(start 300.7614 -60.3504)
		(end 301.0662 -60.3504)
		(width 0.089408)
		(layer "In9.Cu")
		(net "XDP_CPU_PWR_DEBUG_N")
	)
	(segment
		(start 300.2661 -60.8457)
		(end 300.7614 -60.3504)
		(width 0.089408)
		(layer "In9.Cu")
		(net "XDP_CPU_PWR_DEBUG_N")
	)
	(segment
		(start 296.4688 -61.8236)
		(end 296.8752 -61.8236)
		(width 0.089408)
		(layer "In9.Cu")
		(net "XDP_CPU_PWR_DEBUG_N")
	)
	(segment
		(start 244.498368 -124.079)
		(end 263.912604 -124.079)
		(width 0.089408)
		(layer "In9.Cu")
		(net "XDP_CPU_PWR_DEBUG_N")
	)
	(segment
		(start 307.744368 -56.011064)
		(end 308.358032 -55.3974)
		(width 0.089408)
		(layer "In9.Cu")
		(net "XDP_CPU_PWR_DEBUG_N")
	)
	(segment
		(start 224.275396 -123.349004)
		(end 243.768372 -123.349004)
		(width 0.089408)
		(layer "In9.Cu")
		(net "XDP_CPU_PWR_DEBUG_N")
	)
	(segment
		(start 176.784 -126.1872)
		(end 176.784 -126.1745)
		(width 0.089408)
		(layer "In9.Cu")
		(net "XDP_CPU_PWR_DEBUG_N")
	)
	(segment
		(start 179.6923 -124.714)
		(end 180.797708 -125.819408)
		(width 0.089408)
		(layer "In9.Cu")
		(net "XDP_CPU_PWR_DEBUG_N")
	)
	(segment
		(start 302.0568 -60.8076)
		(end 302.4886 -60.3758)
		(width 0.089408)
		(layer "In9.Cu")
		(net "XDP_CPU_PWR_DEBUG_N")
	)
	(segment
		(start 298.6532 -60.8076)
		(end 299.0596 -60.4012)
		(width 0.089408)
		(layer "In9.Cu")
		(net "XDP_CPU_PWR_DEBUG_N")
	)
	(segment
		(start 297.7388 -61.2902)
		(end 298.2214 -60.8076)
		(width 0.089408)
		(layer "In9.Cu")
		(net "XDP_CPU_PWR_DEBUG_N")
	)
	(segment
		(start 306.092352 -58.285634)
		(end 306.120292 -58.285634)
		(width 0.0889)
		(layer "In9.Cu")
		(net "XDP_CPU_PWR_DEBUG_N")
	)
	(segment
		(start 320.562478 -126.378462)
		(end 320.762122 -126.378462)
		(width 0.089408)
		(layer "In9.Cu")
		(net "XDP_CPU_PWR_DEBUG_N")
	)
	(segment
		(start 243.768372 -123.349004)
		(end 244.498368 -124.079)
		(width 0.089408)
		(layer "In9.Cu")
		(net "XDP_CPU_PWR_DEBUG_N")
	)
	(segment
		(start 263.912604 -124.079)
		(end 264.836148 -123.155456)
		(width 0.089408)
		(layer "In9.Cu")
		(net "XDP_CPU_PWR_DEBUG_N")
	)
	(segment
		(start 178.2445 -124.714)
		(end 179.6923 -124.714)
		(width 0.089408)
		(layer "In9.Cu")
		(net "XDP_CPU_PWR_DEBUG_N")
	)
	(segment
		(start 301.0662 -60.3504)
		(end 301.5234 -60.8076)
		(width 0.089408)
		(layer "In9.Cu")
		(net "XDP_CPU_PWR_DEBUG_N")
	)
	(segment
		(start 191.120268 -125.819408)
		(end 191.657732 -125.281944)
		(width 0.089408)
		(layer "In9.Cu")
		(net "XDP_CPU_PWR_DEBUG_N")
	)
	(segment
		(start 297.4086 -61.2902)
		(end 297.7388 -61.2902)
		(width 0.089408)
		(layer "In9.Cu")
		(net "XDP_CPU_PWR_DEBUG_N")
	)
	(segment
		(start 301.5234 -60.8076)
		(end 302.0568 -60.8076)
		(width 0.089408)
		(layer "In9.Cu")
		(net "XDP_CPU_PWR_DEBUG_N")
	)
	(segment
		(start 306.452016 -57.095136)
		(end 306.590954 -56.854344)
		(width 0.0889)
		(layer "In9.Cu")
		(net "XDP_CPU_PWR_DEBUG_N")
	)
	(segment
		(start 191.657732 -125.281944)
		(end 222.342456 -125.281944)
		(width 0.089408)
		(layer "In9.Cu")
		(net "XDP_CPU_PWR_DEBUG_N")
	)
	(segment
		(start 303.4284 -59.817)
		(end 303.657 -59.817)
		(width 0.089408)
		(layer "In9.Cu")
		(net "XDP_CPU_PWR_DEBUG_N")
	)
	(segment
		(start 306.590954 -56.854344)
		(end 306.766214 -56.650636)
		(width 0.0889)
		(layer "In9.Cu")
		(net "XDP_CPU_PWR_DEBUG_N")
	)
	(segment
		(start 307.405786 -56.011064)
		(end 307.744368 -56.011064)
		(width 0.089408)
		(layer "In9.Cu")
		(net "XDP_CPU_PWR_DEBUG_N")
	)
	(segment
		(start 302.4886 -60.3758)
		(end 302.8696 -60.3758)
		(width 0.089408)
		(layer "In9.Cu")
		(net "XDP_CPU_PWR_DEBUG_N")
	)
	(segment
		(start 304.165 -59.309)
		(end 304.6222 -59.309)
		(width 0.089408)
		(layer "In9.Cu")
		(net "XDP_CPU_PWR_DEBUG_N")
	)
	(segment
		(start 304.6222 -59.309)
		(end 305.0286 -58.9026)
		(width 0.089408)
		(layer "In9.Cu")
		(net "XDP_CPU_PWR_DEBUG_N")
	)
	(segment
		(start 296.8752 -61.8236)
		(end 297.4086 -61.2902)
		(width 0.089408)
		(layer "In9.Cu")
		(net "XDP_CPU_PWR_DEBUG_N")
	)
	(segment
		(start 295.5798 -67.791584)
		(end 296.2402 -67.131184)
		(width 0.089408)
		(layer "In9.Cu")
		(net "XDP_CPU_PWR_DEBUG_N")
	)
	(segment
		(start 302.8696 -60.3758)
		(end 303.4284 -59.817)
		(width 0.089408)
		(layer "In9.Cu")
		(net "XDP_CPU_PWR_DEBUG_N")
	)
	(segment
		(start 303.657 -59.817)
		(end 304.165 -59.309)
		(width 0.089408)
		(layer "In9.Cu")
		(net "XDP_CPU_PWR_DEBUG_N")
	)
	(segment
		(start 308.358032 -55.3974)
		(end 309.372 -55.3974)
		(width 0.089408)
		(layer "In9.Cu")
		(net "XDP_CPU_PWR_DEBUG_N")
	)
	(segment
		(start 176.784 -126.1745)
		(end 178.2445 -124.714)
		(width 0.089408)
		(layer "In9.Cu")
		(net "XDP_CPU_PWR_DEBUG_N")
	)
	(arc
		(start 306.445666 -57.675018)
		(mid 306.372868 -57.384255)
		(end 306.452016 -57.095136)
		(width 0.0889)
		(layer "In9.Cu")
		(net "XDP_CPU_PWR_DEBUG_N")
	)
	(arc
		(start 305.593496 -58.581036)
		(mid 305.804209 -58.367957)
		(end 306.092352 -58.285634)
		(width 0.0889)
		(layer "In9.Cu")
		(net "XDP_CPU_PWR_DEBUG_N")
	)
	(arc
		(start 306.120292 -58.285634)
		(mid 306.45321 -58.083643)
		(end 306.456842 -57.694322)
		(width 0.0889)
		(layer "In9.Cu")
		(net "XDP_CPU_PWR_DEBUG_N")
	)
	(segment
		(start 318.306958 -60.759086)
		(end 318.307212 -60.75934)
		(width 0.089408)
		(layer "In11.Cu")
		(net "XDP_CPU_PWR_DEBUG_N")
	)
	(segment
		(start 365.501682 -61.624972)
		(end 365.501682 -62.729618)
		(width 0.089408)
		(layer "In11.Cu")
		(net "XDP_CPU_PWR_DEBUG_N")
	)
	(segment
		(start 367.7285 -94.5515)
		(end 367.7285 -93.546422)
		(width 0.089408)
		(layer "In11.Cu")
		(net "XDP_CPU_PWR_DEBUG_N")
	)
	(segment
		(start 364.401608 -64.2366)
		(end 364.3122 -64.147192)
		(width 0.089408)
		(layer "In11.Cu")
		(net "XDP_CPU_PWR_DEBUG_N")
	)
	(segment
		(start 329.47864 -57.492392)
		(end 330.199238 -56.771794)
		(width 0.089408)
		(layer "In11.Cu")
		(net "XDP_CPU_PWR_DEBUG_N")
	)
	(segment
		(start 176.784 -126.1872)
		(end 176.784 -124.27585)
		(width 0.089408)
		(layer "In11.Cu")
		(net "XDP_CPU_PWR_DEBUG_N")
	)
	(segment
		(start 319.080642 -60.713874)
		(end 319.081404 -60.713874)
		(width 0.089408)
		(layer "In11.Cu")
		(net "XDP_CPU_PWR_DEBUG_N")
	)
	(segment
		(start 328.330052 -57.263284)
		(end 328.55916 -57.492392)
		(width 0.089408)
		(layer "In11.Cu")
		(net "XDP_CPU_PWR_DEBUG_N")
	)
	(segment
		(start 459.503018 -147.528534)
		(end 466.35289 -147.528534)
		(width 0.089408)
		(layer "In11.Cu")
		(net "XDP_CPU_PWR_DEBUG_N")
	)
	(segment
		(start 135.116824 -68.687188)
		(end 135.084058 -68.687188)
		(width 0.0889)
		(layer "In11.Cu")
		(net "XDP_CPU_PWR_DEBUG_N")
	)
	(segment
		(start 453.299322 -143.490696)
		(end 455.46518 -143.490696)
		(width 0.089408)
		(layer "In11.Cu")
		(net "XDP_CPU_PWR_DEBUG_N")
	)
	(segment
		(start 142.877286 -72.10806)
		(end 142.135098 -71.80072)
		(width 0.089408)
		(layer "In11.Cu")
		(net "XDP_CPU_PWR_DEBUG_N")
	)
	(segment
		(start 325.853044 -57.263284)
		(end 328.330052 -57.263284)
		(width 0.089408)
		(layer "In11.Cu")
		(net "XDP_CPU_PWR_DEBUG_N")
	)
	(segment
		(start 134.254494 -68.191634)
		(end 134.221728 -68.191634)
		(width 0.0889)
		(layer "In11.Cu")
		(net "XDP_CPU_PWR_DEBUG_N")
	)
	(segment
		(start 355.2698 -57.2008)
		(end 357.3526 -57.2008)
		(width 0.089408)
		(layer "In11.Cu")
		(net "XDP_CPU_PWR_DEBUG_N")
	)
	(segment
		(start 131.877816 -67.791584)
		(end 129.085848 -67.791584)
		(width 0.089408)
		(layer "In11.Cu")
		(net "XDP_CPU_PWR_DEBUG_N")
	)
	(segment
		(start 365.501682 -62.729618)
		(end 364.3249 -63.9064)
		(width 0.089408)
		(layer "In11.Cu")
		(net "XDP_CPU_PWR_DEBUG_N")
	)
	(segment
		(start 364.87735 -90.695272)
		(end 364.87735 -84.51977)
		(width 0.089408)
		(layer "In11.Cu")
		(net "XDP_CPU_PWR_DEBUG_N")
	)
	(segment
		(start 365.252 -61.37529)
		(end 365.501682 -61.624972)
		(width 0.089408)
		(layer "In11.Cu")
		(net "XDP_CPU_PWR_DEBUG_N")
	)
	(segment
		(start 364.3122 -64.147192)
		(end 364.3122 -63.9064)
		(width 0.089408)
		(layer "In11.Cu")
		(net "XDP_CPU_PWR_DEBUG_N")
	)
	(segment
		(start 310.019192 -55.552086)
		(end 310.135778 -55.552086)
		(width 0.089408)
		(layer "In11.Cu")
		(net "XDP_CPU_PWR_DEBUG_N")
	)
	(segment
		(start 362.997242 -69.199252)
		(end 364.121192 -68.075302)
		(width 0.089408)
		(layer "In11.Cu")
		(net "XDP_CPU_PWR_DEBUG_N")
	)
	(segment
		(start 364.121192 -67.361562)
		(end 366.084104 -65.39865)
		(width 0.089408)
		(layer "In11.Cu")
		(net "XDP_CPU_PWR_DEBUG_N")
	)
	(segment
		(start 140.267944 -71.658988)
		(end 140.235178 -71.658988)
		(width 0.0889)
		(layer "In11.Cu")
		(net "XDP_CPU_PWR_DEBUG_N")
	)
	(segment
		(start 452.220076 -142.513304)
		(end 452.220076 -142.495016)
		(width 0.089408)
		(layer "In11.Cu")
		(net "XDP_CPU_PWR_DEBUG_N")
	)
	(segment
		(start 362.997242 -72.403208)
		(end 362.997242 -69.199252)
		(width 0.089408)
		(layer "In11.Cu")
		(net "XDP_CPU_PWR_DEBUG_N")
	)
	(segment
		(start 364.8456 -64.2366)
		(end 364.401608 -64.2366)
		(width 0.089408)
		(layer "In11.Cu")
		(net "XDP_CPU_PWR_DEBUG_N")
	)
	(segment
		(start 364.20298 -83.8454)
		(end 364.20298 -79.745078)
		(width 0.089408)
		(layer "In11.Cu")
		(net "XDP_CPU_PWR_DEBUG_N")
	)
	(segment
		(start 135.971534 -69.182234)
		(end 135.938768 -69.182234)
		(width 0.0889)
		(layer "In11.Cu")
		(net "XDP_CPU_PWR_DEBUG_N")
	)
	(segment
		(start 367.7285 -93.546422)
		(end 364.87735 -90.695272)
		(width 0.089408)
		(layer "In11.Cu")
		(net "XDP_CPU_PWR_DEBUG_N")
	)
	(segment
		(start 132.2832 -67.3862)
		(end 131.877816 -67.791584)
		(width 0.089408)
		(layer "In11.Cu")
		(net "XDP_CPU_PWR_DEBUG_N")
	)
	(segment
		(start 364.3249 -63.9064)
		(end 364.3122 -63.9064)
		(width 0.089408)
		(layer "In11.Cu")
		(net "XDP_CPU_PWR_DEBUG_N")
	)
	(segment
		(start 366.084104 -65.39865)
		(end 366.084104 -63.918338)
		(width 0.089408)
		(layer "In11.Cu")
		(net "XDP_CPU_PWR_DEBUG_N")
	)
	(segment
		(start 466.35289 -147.528534)
		(end 466.733636 -147.147788)
		(width 0.089408)
		(layer "In11.Cu")
		(net "XDP_CPU_PWR_DEBUG_N")
	)
	(segment
		(start 133.356604 -67.696588)
		(end 133.147308 -67.691508)
		(width 0.0889)
		(layer "In11.Cu")
		(net "XDP_CPU_PWR_DEBUG_N")
	)
	(segment
		(start 142.135098 -71.80072)
		(end 141.714728 -71.80072)
		(width 0.089408)
		(layer "In11.Cu")
		(net "XDP_CPU_PWR_DEBUG_N")
	)
	(segment
		(start 455.46518 -143.490696)
		(end 459.503018 -147.528534)
		(width 0.089408)
		(layer "In11.Cu")
		(net "XDP_CPU_PWR_DEBUG_N")
	)
	(segment
		(start 315.342778 -60.759086)
		(end 318.306958 -60.759086)
		(width 0.089408)
		(layer "In11.Cu")
		(net "XDP_CPU_PWR_DEBUG_N")
	)
	(segment
		(start 141.355572 -72.159876)
		(end 140.960602 -72.159876)
		(width 0.089408)
		(layer "In11.Cu")
		(net "XDP_CPU_PWR_DEBUG_N")
	)
	(segment
		(start 319.035176 -60.75934)
		(end 319.080642 -60.713874)
		(width 0.089408)
		(layer "In11.Cu")
		(net "XDP_CPU_PWR_DEBUG_N")
	)
	(segment
		(start 168.547796 -104.025192)
		(end 168.547796 -97.77857)
		(width 0.089408)
		(layer "In11.Cu")
		(net "XDP_CPU_PWR_DEBUG_N")
	)
	(segment
		(start 137.692384 -70.172834)
		(end 137.659618 -70.172834)
		(width 0.0889)
		(layer "In11.Cu")
		(net "XDP_CPU_PWR_DEBUG_N")
	)
	(segment
		(start 310.135778 -55.552086)
		(end 315.342778 -60.759086)
		(width 0.089408)
		(layer "In11.Cu")
		(net "XDP_CPU_PWR_DEBUG_N")
	)
	(segment
		(start 366.084104 -63.918338)
		(end 365.932466 -63.7667)
		(width 0.089408)
		(layer "In11.Cu")
		(net "XDP_CPU_PWR_DEBUG_N")
	)
	(segment
		(start 367.0554 -95.2246)
		(end 367.7285 -94.5515)
		(width 0.089408)
		(layer "In11.Cu")
		(net "XDP_CPU_PWR_DEBUG_N")
	)
	(segment
		(start 364.692692 -77.293978)
		(end 364.692692 -74.098658)
		(width 0.089408)
		(layer "In11.Cu")
		(net "XDP_CPU_PWR_DEBUG_N")
	)
	(segment
		(start 140.83538 -72.087486)
		(end 140.758164 -71.954136)
		(width 0.0889)
		(layer "In11.Cu")
		(net "XDP_CPU_PWR_DEBUG_N")
	)
	(segment
		(start 357.3526 -57.2008)
		(end 361.52709 -61.37529)
		(width 0.089408)
		(layer "In11.Cu")
		(net "XDP_CPU_PWR_DEBUG_N")
	)
	(segment
		(start 172.606716 -105.614216)
		(end 170.13682 -105.614216)
		(width 0.089408)
		(layer "In11.Cu")
		(net "XDP_CPU_PWR_DEBUG_N")
	)
	(segment
		(start 309.372 -55.3974)
		(end 309.864506 -55.3974)
		(width 0.089408)
		(layer "In11.Cu")
		(net "XDP_CPU_PWR_DEBUG_N")
	)
	(segment
		(start 141.714728 -71.80072)
		(end 141.355572 -72.159876)
		(width 0.089408)
		(layer "In11.Cu")
		(net "XDP_CPU_PWR_DEBUG_N")
	)
	(segment
		(start 133.147308 -67.691508)
		(end 132.842 -67.3862)
		(width 0.089408)
		(layer "In11.Cu")
		(net "XDP_CPU_PWR_DEBUG_N")
	)
	(segment
		(start 361.52709 -61.37529)
		(end 365.252 -61.37529)
		(width 0.089408)
		(layer "In11.Cu")
		(net "XDP_CPU_PWR_DEBUG_N")
	)
	(segment
		(start 364.121192 -68.075302)
		(end 364.121192 -67.361562)
		(width 0.089408)
		(layer "In11.Cu")
		(net "XDP_CPU_PWR_DEBUG_N")
	)
	(segment
		(start 354.840794 -56.771794)
		(end 355.2698 -57.2008)
		(width 0.089408)
		(layer "In11.Cu")
		(net "XDP_CPU_PWR_DEBUG_N")
	)
	(segment
		(start 330.199238 -56.771794)
		(end 354.840794 -56.771794)
		(width 0.089408)
		(layer "In11.Cu")
		(net "XDP_CPU_PWR_DEBUG_N")
	)
	(segment
		(start 309.864506 -55.3974)
		(end 310.019192 -55.552086)
		(width 0.089408)
		(layer "In11.Cu")
		(net "XDP_CPU_PWR_DEBUG_N")
	)
	(segment
		(start 136.833864 -69.677534)
		(end 136.79424 -69.677534)
		(width 0.0889)
		(layer "In11.Cu")
		(net "XDP_CPU_PWR_DEBUG_N")
	)
	(segment
		(start 176.784 -124.27585)
		(end 176.528984 -124.020834)
		(width 0.089408)
		(layer "In11.Cu")
		(net "XDP_CPU_PWR_DEBUG_N")
	)
	(segment
		(start 328.55916 -57.492392)
		(end 329.47864 -57.492392)
		(width 0.089408)
		(layer "In11.Cu")
		(net "XDP_CPU_PWR_DEBUG_N")
	)
	(segment
		(start 132.842 -67.3862)
		(end 132.2832 -67.3862)
		(width 0.089408)
		(layer "In11.Cu")
		(net "XDP_CPU_PWR_DEBUG_N")
	)
	(segment
		(start 168.547796 -97.77857)
		(end 142.877286 -72.10806)
		(width 0.089408)
		(layer "In11.Cu")
		(net "XDP_CPU_PWR_DEBUG_N")
	)
	(segment
		(start 176.528984 -109.536484)
		(end 172.606716 -105.614216)
		(width 0.089408)
		(layer "In11.Cu")
		(net "XDP_CPU_PWR_DEBUG_N")
	)
	(segment
		(start 364.87735 -84.51977)
		(end 364.20298 -83.8454)
		(width 0.089408)
		(layer "In11.Cu")
		(net "XDP_CPU_PWR_DEBUG_N")
	)
	(segment
		(start 452.33463 -142.60957)
		(end 452.418196 -142.60957)
		(width 0.089408)
		(layer "In11.Cu")
		(net "XDP_CPU_PWR_DEBUG_N")
	)
	(segment
		(start 318.307212 -60.75934)
		(end 319.035176 -60.75934)
		(width 0.089408)
		(layer "In11.Cu")
		(net "XDP_CPU_PWR_DEBUG_N")
	)
	(segment
		(start 322.927218 -56.86806)
		(end 325.45782 -56.86806)
		(width 0.089408)
		(layer "In11.Cu")
		(net "XDP_CPU_PWR_DEBUG_N")
	)
	(segment
		(start 176.528984 -124.020834)
		(end 176.528984 -109.536484)
		(width 0.089408)
		(layer "In11.Cu")
		(net "XDP_CPU_PWR_DEBUG_N")
	)
	(segment
		(start 325.45782 -56.86806)
		(end 325.853044 -57.263284)
		(width 0.089408)
		(layer "In11.Cu")
		(net "XDP_CPU_PWR_DEBUG_N")
	)
	(segment
		(start 319.081404 -60.713874)
		(end 322.927218 -56.86806)
		(width 0.089408)
		(layer "In11.Cu")
		(net "XDP_CPU_PWR_DEBUG_N")
	)
	(segment
		(start 170.13682 -105.614216)
		(end 168.547796 -104.025192)
		(width 0.089408)
		(layer "In11.Cu")
		(net "XDP_CPU_PWR_DEBUG_N")
	)
	(segment
		(start 138.542268 -70.668134)
		(end 138.518138 -70.668134)
		(width 0.0889)
		(layer "In11.Cu")
		(net "XDP_CPU_PWR_DEBUG_N")
	)
	(segment
		(start 364.20298 -79.745078)
		(end 364.692692 -77.293978)
		(width 0.089408)
		(layer "In11.Cu")
		(net "XDP_CPU_PWR_DEBUG_N")
	)
	(segment
		(start 452.418196 -142.60957)
		(end 453.299322 -143.490696)
		(width 0.089408)
		(layer "In11.Cu")
		(net "XDP_CPU_PWR_DEBUG_N")
	)
	(segment
		(start 452.220076 -142.495016)
		(end 452.33463 -142.60957)
		(width 0.089408)
		(layer "In11.Cu")
		(net "XDP_CPU_PWR_DEBUG_N")
	)
	(segment
		(start 364.692692 -74.098658)
		(end 362.997242 -72.403208)
		(width 0.089408)
		(layer "In11.Cu")
		(net "XDP_CPU_PWR_DEBUG_N")
	)
	(segment
		(start 365.3155 -63.7667)
		(end 364.8456 -64.2366)
		(width 0.089408)
		(layer "In11.Cu")
		(net "XDP_CPU_PWR_DEBUG_N")
	)
	(segment
		(start 139.405614 -71.163434)
		(end 139.372848 -71.163434)
		(width 0.0889)
		(layer "In11.Cu")
		(net "XDP_CPU_PWR_DEBUG_N")
	)
	(segment
		(start 140.960602 -72.159876)
		(end 140.83538 -72.087486)
		(width 0.0889)
		(layer "In11.Cu")
		(net "XDP_CPU_PWR_DEBUG_N")
	)
	(segment
		(start 133.399784 -67.696588)
		(end 133.356604 -67.696588)
		(width 0.0889)
		(layer "In11.Cu")
		(net "XDP_CPU_PWR_DEBUG_N")
	)
	(segment
		(start 365.932466 -63.7667)
		(end 365.3155 -63.7667)
		(width 0.089408)
		(layer "In11.Cu")
		(net "XDP_CPU_PWR_DEBUG_N")
	)
	(arc
		(start 137.659618 -70.172834)
		(mid 137.465768 -70.116484)
		(end 137.324084 -69.972682)
		(width 0.0889)
		(layer "In11.Cu")
		(net "XDP_CPU_PWR_DEBUG_N")
	)
	(arc
		(start 134.221728 -68.191634)
		(mid 134.030086 -68.134468)
		(end 133.890004 -67.991736)
		(width 0.0889)
		(layer "In11.Cu")
		(net "XDP_CPU_PWR_DEBUG_N")
	)
	(arc
		(start 139.041124 -70.963536)
		(mid 138.830411 -70.750457)
		(end 138.542268 -70.668134)
		(width 0.0889)
		(layer "In11.Cu")
		(net "XDP_CPU_PWR_DEBUG_N")
	)
	(arc
		(start 134.748524 -68.487036)
		(mid 134.539916 -68.275104)
		(end 134.254494 -68.191634)
		(width 0.0889)
		(layer "In11.Cu")
		(net "XDP_CPU_PWR_DEBUG_N")
	)
	(arc
		(start 138.518138 -70.668134)
		(mid 138.324288 -70.611784)
		(end 138.182604 -70.467982)
		(width 0.0889)
		(layer "In11.Cu")
		(net "XDP_CPU_PWR_DEBUG_N")
	)
	(arc
		(start 140.758164 -71.954136)
		(mid 140.55116 -71.743272)
		(end 140.267944 -71.658988)
		(width 0.0889)
		(layer "In11.Cu")
		(net "XDP_CPU_PWR_DEBUG_N")
	)
	(arc
		(start 135.084058 -68.687188)
		(mid 134.890208 -68.630838)
		(end 134.748524 -68.487036)
		(width 0.0889)
		(layer "In11.Cu")
		(net "XDP_CPU_PWR_DEBUG_N")
	)
	(arc
		(start 139.899644 -71.458836)
		(mid 139.691036 -71.246904)
		(end 139.405614 -71.163434)
		(width 0.0889)
		(layer "In11.Cu")
		(net "XDP_CPU_PWR_DEBUG_N")
	)
	(arc
		(start 138.182604 -70.467982)
		(mid 137.9756 -70.257118)
		(end 137.692384 -70.172834)
		(width 0.0889)
		(layer "In11.Cu")
		(net "XDP_CPU_PWR_DEBUG_N")
	)
	(arc
		(start 133.890004 -67.991736)
		(mid 133.683 -67.780872)
		(end 133.399784 -67.696588)
		(width 0.0889)
		(layer "In11.Cu")
		(net "XDP_CPU_PWR_DEBUG_N")
	)
	(arc
		(start 135.607044 -68.982336)
		(mid 135.40004 -68.771472)
		(end 135.116824 -68.687188)
		(width 0.0889)
		(layer "In11.Cu")
		(net "XDP_CPU_PWR_DEBUG_N")
	)
	(arc
		(start 136.79424 -69.677534)
		(mid 136.604311 -69.619664)
		(end 136.465564 -69.477636)
		(width 0.0889)
		(layer "In11.Cu")
		(net "XDP_CPU_PWR_DEBUG_N")
	)
	(arc
		(start 140.235178 -71.658988)
		(mid 140.041328 -71.602638)
		(end 139.899644 -71.458836)
		(width 0.0889)
		(layer "In11.Cu")
		(net "XDP_CPU_PWR_DEBUG_N")
	)
	(arc
		(start 139.372848 -71.163434)
		(mid 139.181206 -71.106268)
		(end 139.041124 -70.963536)
		(width 0.0889)
		(layer "In11.Cu")
		(net "XDP_CPU_PWR_DEBUG_N")
	)
	(arc
		(start 135.938768 -69.182234)
		(mid 135.747126 -69.125068)
		(end 135.607044 -68.982336)
		(width 0.0889)
		(layer "In11.Cu")
		(net "XDP_CPU_PWR_DEBUG_N")
	)
	(arc
		(start 136.465564 -69.477636)
		(mid 136.256956 -69.265704)
		(end 135.971534 -69.182234)
		(width 0.0889)
		(layer "In11.Cu")
		(net "XDP_CPU_PWR_DEBUG_N")
	)
	(arc
		(start 137.324084 -69.972682)
		(mid 137.11708 -69.761818)
		(end 136.833864 -69.677534)
		(width 0.0889)
		(layer "In11.Cu")
		(net "XDP_CPU_PWR_DEBUG_N")
	)
	(segment
		(start 132.806694 -62.343538)
		(end 133.378194 -62.343538)
		(width 0.1016)
		(layer "F.Cu")
		(net "XDP_CPU_OBSFN_B1_MBP7_N")
	)
	(segment
		(start 297.807126 -62.343538)
		(end 298.378626 -62.343538)
		(width 0.1016)
		(layer "F.Cu")
		(net "XDP_CPU_OBSFN_B1_MBP7_N")
	)
	(via
		(at 323.281294 -61.01588)
		(size 0.508)
		(drill 0.254)
		(layers "F.Cu" "B.Cu")
		(net "XDP_CPU_OBSFN_B1_MBP7_N")
	)
	(via
		(at 357.447596 -62.395608)
		(size 0.508)
		(drill 0.254)
		(layers "F.Cu" "B.Cu")
		(net "XDP_CPU_OBSFN_B1_MBP7_N")
	)
	(via
		(at 357.6955 -84.582)
		(size 0.508)
		(drill 0.254)
		(layers "F.Cu" "B.Cu")
		(net "XDP_CPU_OBSFN_B1_MBP7_N")
	)
	(via
		(at 179.661566 -22.59457)
		(size 0.508)
		(drill 0.254)
		(layers "F.Cu" "B.Cu")
		(net "XDP_CPU_OBSFN_B1_MBP7_N")
	)
	(via
		(at 133.378194 -62.343538)
		(size 0.508)
		(drill 0.254)
		(layers "F.Cu" "B.Cu")
		(net "XDP_CPU_OBSFN_B1_MBP7_N")
	)
	(via
		(at 461.33512 -140.589)
		(size 0.508)
		(drill 0.254)
		(layers "F.Cu" "B.Cu")
		(net "XDP_CPU_OBSFN_B1_MBP7_N")
	)
	(via
		(at 298.378626 -62.343538)
		(size 0.508)
		(drill 0.254)
		(layers "F.Cu" "B.Cu")
		(net "XDP_CPU_OBSFN_B1_MBP7_N")
	)
	(segment
		(start 179.661566 -22.51837)
		(end 179.804822 -22.375114)
		(width 0.10795)
		(layer "B.Cu")
		(net "XDP_CPU_OBSFN_B1_MBP7_N")
	)
	(segment
		(start 459.253082 -137.694162)
		(end 459.253082 -138.553444)
		(width 0.10795)
		(layer "B.Cu")
		(net "XDP_CPU_OBSFN_B1_MBP7_N")
	)
	(segment
		(start 179.661566 -22.59457)
		(end 179.661566 -22.51837)
		(width 0.10795)
		(layer "B.Cu")
		(net "XDP_CPU_OBSFN_B1_MBP7_N")
	)
	(segment
		(start 179.804822 -22.375114)
		(end 179.804822 -20.903692)
		(width 0.10795)
		(layer "B.Cu")
		(net "XDP_CPU_OBSFN_B1_MBP7_N")
	)
	(segment
		(start 459.253082 -138.553444)
		(end 461.288638 -140.589)
		(width 0.10795)
		(layer "B.Cu")
		(net "XDP_CPU_OBSFN_B1_MBP7_N")
	)
	(segment
		(start 461.288638 -140.589)
		(end 461.33512 -140.589)
		(width 0.10795)
		(layer "B.Cu")
		(net "XDP_CPU_OBSFN_B1_MBP7_N")
	)
	(segment
		(start 441.41263 -141.181074)
		(end 441.412376 -141.18082)
		(width 0.089408)
		(layer "In4.Cu")
		(net "XDP_CPU_OBSFN_B1_MBP7_N")
	)
	(segment
		(start 352.673158 -138.667998)
		(end 350.71939 -138.667998)
		(width 0.089408)
		(layer "In4.Cu")
		(net "XDP_CPU_OBSFN_B1_MBP7_N")
	)
	(segment
		(start 399.353278 -144.011904)
		(end 399.353278 -143.948658)
		(width 0.089408)
		(layer "In4.Cu")
		(net "XDP_CPU_OBSFN_B1_MBP7_N")
	)
	(segment
		(start 461.33512 -140.589)
		(end 461.708754 -140.962634)
		(width 0.089408)
		(layer "In4.Cu")
		(net "XDP_CPU_OBSFN_B1_MBP7_N")
	)
	(segment
		(start 452.305166 -141.986)
		(end 449.58 -141.986)
		(width 0.089408)
		(layer "In4.Cu")
		(net "XDP_CPU_OBSFN_B1_MBP7_N")
	)
	(segment
		(start 350.5073 -89.016332)
		(end 350.5073 -86.00186)
		(width 0.089408)
		(layer "In4.Cu")
		(net "XDP_CPU_OBSFN_B1_MBP7_N")
	)
	(segment
		(start 461.099154 -145.700242)
		(end 459.850744 -146.948652)
		(width 0.089408)
		(layer "In4.Cu")
		(net "XDP_CPU_OBSFN_B1_MBP7_N")
	)
	(segment
		(start 340.501986 -104.898952)
		(end 335.14411 -104.898952)
		(width 0.089408)
		(layer "In4.Cu")
		(net "XDP_CPU_OBSFN_B1_MBP7_N")
	)
	(segment
		(start 348.82328 -135.62584)
		(end 348.21622 -135.01878)
		(width 0.089408)
		(layer "In4.Cu")
		(net "XDP_CPU_OBSFN_B1_MBP7_N")
	)
	(segment
		(start 397.060674 -141.656054)
		(end 392.977624 -141.656054)
		(width 0.089408)
		(layer "In4.Cu")
		(net "XDP_CPU_OBSFN_B1_MBP7_N")
	)
	(segment
		(start 370.799868 -141.532356)
		(end 365.455454 -141.532356)
		(width 0.089408)
		(layer "In4.Cu")
		(net "XDP_CPU_OBSFN_B1_MBP7_N")
	)
	(segment
		(start 411.76702 -145.60296)
		(end 410.402786 -146.967194)
		(width 0.089408)
		(layer "In4.Cu")
		(net "XDP_CPU_OBSFN_B1_MBP7_N")
	)
	(segment
		(start 439.783728 -140.6525)
		(end 438.404 -142.032228)
		(width 0.089408)
		(layer "In4.Cu")
		(net "XDP_CPU_OBSFN_B1_MBP7_N")
	)
	(segment
		(start 349.757238 -138.139424)
		(end 348.82328 -137.205466)
		(width 0.089408)
		(layer "In4.Cu")
		(net "XDP_CPU_OBSFN_B1_MBP7_N")
	)
	(segment
		(start 365.455454 -141.532356)
		(end 364.779052 -140.855954)
		(width 0.089408)
		(layer "In4.Cu")
		(net "XDP_CPU_OBSFN_B1_MBP7_N")
	)
	(segment
		(start 338.010754 -91.0082)
		(end 340.106 -91.0082)
		(width 0.089408)
		(layer "In4.Cu")
		(net "XDP_CPU_OBSFN_B1_MBP7_N")
	)
	(segment
		(start 343.523062 -120.375934)
		(end 343.956894 -119.942102)
		(width 0.089408)
		(layer "In4.Cu")
		(net "XDP_CPU_OBSFN_B1_MBP7_N")
	)
	(segment
		(start 420.077646 -142.032228)
		(end 418.980112 -143.129762)
		(width 0.089408)
		(layer "In4.Cu")
		(net "XDP_CPU_OBSFN_B1_MBP7_N")
	)
	(segment
		(start 441.15482 -141.18082)
		(end 440.6265 -140.6525)
		(width 0.089408)
		(layer "In4.Cu")
		(net "XDP_CPU_OBSFN_B1_MBP7_N")
	)
	(segment
		(start 449.3768 -141.7828)
		(end 443.0268 -141.7828)
		(width 0.089408)
		(layer "In4.Cu")
		(net "XDP_CPU_OBSFN_B1_MBP7_N")
	)
	(segment
		(start 438.404 -142.032228)
		(end 420.077646 -142.032228)
		(width 0.089408)
		(layer "In4.Cu")
		(net "XDP_CPU_OBSFN_B1_MBP7_N")
	)
	(segment
		(start 443.0268 -141.7828)
		(end 442.42482 -141.18082)
		(width 0.089408)
		(layer "In4.Cu")
		(net "XDP_CPU_OBSFN_B1_MBP7_N")
	)
	(segment
		(start 461.708754 -140.962634)
		(end 461.708754 -145.274284)
		(width 0.089408)
		(layer "In4.Cu")
		(net "XDP_CPU_OBSFN_B1_MBP7_N")
	)
	(segment
		(start 355.31806 -84.498688)
		(end 356.68331 -84.498688)
		(width 0.089408)
		(layer "In4.Cu")
		(net "XDP_CPU_OBSFN_B1_MBP7_N")
	)
	(segment
		(start 352.822764 -138.518392)
		(end 352.673158 -138.667998)
		(width 0.089408)
		(layer "In4.Cu")
		(net "XDP_CPU_OBSFN_B1_MBP7_N")
	)
	(segment
		(start 454.4822 -143.891)
		(end 454.210166 -143.891)
		(width 0.089408)
		(layer "In4.Cu")
		(net "XDP_CPU_OBSFN_B1_MBP7_N")
	)
	(segment
		(start 350.71939 -138.667998)
		(end 350.190816 -138.139424)
		(width 0.089408)
		(layer "In4.Cu")
		(net "XDP_CPU_OBSFN_B1_MBP7_N")
	)
	(segment
		(start 361.12323 -140.806678)
		(end 358.834944 -138.518392)
		(width 0.089408)
		(layer "In4.Cu")
		(net "XDP_CPU_OBSFN_B1_MBP7_N")
	)
	(segment
		(start 459.850744 -146.948652)
		(end 457.539852 -146.948652)
		(width 0.089408)
		(layer "In4.Cu")
		(net "XDP_CPU_OBSFN_B1_MBP7_N")
	)
	(segment
		(start 343.136474 -115.689888)
		(end 342.700102 -115.689888)
		(width 0.089408)
		(layer "In4.Cu")
		(net "XDP_CPU_OBSFN_B1_MBP7_N")
	)
	(segment
		(start 343.638886 -116.797074)
		(end 343.638886 -116.1923)
		(width 0.089408)
		(layer "In4.Cu")
		(net "XDP_CPU_OBSFN_B1_MBP7_N")
	)
	(segment
		(start 441.744608 -141.18082)
		(end 441.744354 -141.181074)
		(width 0.089408)
		(layer "In4.Cu")
		(net "XDP_CPU_OBSFN_B1_MBP7_N")
	)
	(segment
		(start 333.146908 -95.872046)
		(end 338.010754 -91.0082)
		(width 0.089408)
		(layer "In4.Cu")
		(net "XDP_CPU_OBSFN_B1_MBP7_N")
	)
	(segment
		(start 354.267008 -85.54974)
		(end 355.31806 -84.498688)
		(width 0.089408)
		(layer "In4.Cu")
		(net "XDP_CPU_OBSFN_B1_MBP7_N")
	)
	(segment
		(start 343.956894 -119.942102)
		(end 343.956894 -117.115082)
		(width 0.089408)
		(layer "In4.Cu")
		(net "XDP_CPU_OBSFN_B1_MBP7_N")
	)
	(segment
		(start 344.40876 -132.99186)
		(end 344.40876 -130.403346)
		(width 0.089408)
		(layer "In4.Cu")
		(net "XDP_CPU_OBSFN_B1_MBP7_N")
	)
	(segment
		(start 461.282796 -145.700242)
		(end 461.099154 -145.700242)
		(width 0.089408)
		(layer "In4.Cu")
		(net "XDP_CPU_OBSFN_B1_MBP7_N")
	)
	(segment
		(start 403.952202 -145.558764)
		(end 400.900138 -145.558764)
		(width 0.089408)
		(layer "In4.Cu")
		(net "XDP_CPU_OBSFN_B1_MBP7_N")
	)
	(segment
		(start 441.744354 -141.181074)
		(end 441.41263 -141.181074)
		(width 0.089408)
		(layer "In4.Cu")
		(net "XDP_CPU_OBSFN_B1_MBP7_N")
	)
	(segment
		(start 417.6268 -145.60296)
		(end 411.76702 -145.60296)
		(width 0.089408)
		(layer "In4.Cu")
		(net "XDP_CPU_OBSFN_B1_MBP7_N")
	)
	(segment
		(start 457.539852 -146.948652)
		(end 454.4822 -143.891)
		(width 0.089408)
		(layer "In4.Cu")
		(net "XDP_CPU_OBSFN_B1_MBP7_N")
	)
	(segment
		(start 441.412376 -141.18082)
		(end 441.15482 -141.18082)
		(width 0.089408)
		(layer "In4.Cu")
		(net "XDP_CPU_OBSFN_B1_MBP7_N")
	)
	(segment
		(start 333.146908 -96.357186)
		(end 333.146908 -95.872046)
		(width 0.089408)
		(layer "In4.Cu")
		(net "XDP_CPU_OBSFN_B1_MBP7_N")
	)
	(segment
		(start 362.456984 -140.855954)
		(end 362.407708 -140.806678)
		(width 0.089408)
		(layer "In4.Cu")
		(net "XDP_CPU_OBSFN_B1_MBP7_N")
	)
	(segment
		(start 440.6265 -140.6525)
		(end 439.783728 -140.6525)
		(width 0.089408)
		(layer "In4.Cu")
		(net "XDP_CPU_OBSFN_B1_MBP7_N")
	)
	(segment
		(start 350.95942 -85.54974)
		(end 354.267008 -85.54974)
		(width 0.089408)
		(layer "In4.Cu")
		(net "XDP_CPU_OBSFN_B1_MBP7_N")
	)
	(segment
		(start 333.147162 -102.902004)
		(end 333.147162 -96.35744)
		(width 0.089408)
		(layer "In4.Cu")
		(net "XDP_CPU_OBSFN_B1_MBP7_N")
	)
	(segment
		(start 364.779052 -140.855954)
		(end 362.456984 -140.855954)
		(width 0.089408)
		(layer "In4.Cu")
		(net "XDP_CPU_OBSFN_B1_MBP7_N")
	)
	(segment
		(start 392.476482 -141.154912)
		(end 371.177312 -141.154912)
		(width 0.089408)
		(layer "In4.Cu")
		(net "XDP_CPU_OBSFN_B1_MBP7_N")
	)
	(segment
		(start 333.147162 -96.35744)
		(end 333.146908 -96.357186)
		(width 0.089408)
		(layer "In4.Cu")
		(net "XDP_CPU_OBSFN_B1_MBP7_N")
	)
	(segment
		(start 358.834944 -138.518392)
		(end 352.822764 -138.518392)
		(width 0.089408)
		(layer "In4.Cu")
		(net "XDP_CPU_OBSFN_B1_MBP7_N")
	)
	(segment
		(start 343.956894 -117.115082)
		(end 343.638886 -116.797074)
		(width 0.089408)
		(layer "In4.Cu")
		(net "XDP_CPU_OBSFN_B1_MBP7_N")
	)
	(segment
		(start 350.5073 -86.00186)
		(end 350.95942 -85.54974)
		(width 0.089408)
		(layer "In4.Cu")
		(net "XDP_CPU_OBSFN_B1_MBP7_N")
	)
	(segment
		(start 335.14411 -104.898952)
		(end 333.147162 -102.902004)
		(width 0.089408)
		(layer "In4.Cu")
		(net "XDP_CPU_OBSFN_B1_MBP7_N")
	)
	(segment
		(start 343.638886 -116.1923)
		(end 343.136474 -115.689888)
		(width 0.089408)
		(layer "In4.Cu")
		(net "XDP_CPU_OBSFN_B1_MBP7_N")
	)
	(segment
		(start 400.900138 -145.558764)
		(end 399.353278 -144.011904)
		(width 0.089408)
		(layer "In4.Cu")
		(net "XDP_CPU_OBSFN_B1_MBP7_N")
	)
	(segment
		(start 349.213424 -90.310208)
		(end 350.5073 -89.016332)
		(width 0.089408)
		(layer "In4.Cu")
		(net "XDP_CPU_OBSFN_B1_MBP7_N")
	)
	(segment
		(start 442.42482 -141.18082)
		(end 441.744608 -141.18082)
		(width 0.089408)
		(layer "In4.Cu")
		(net "XDP_CPU_OBSFN_B1_MBP7_N")
	)
	(segment
		(start 348.82328 -137.205466)
		(end 348.82328 -135.62584)
		(width 0.089408)
		(layer "In4.Cu")
		(net "XDP_CPU_OBSFN_B1_MBP7_N")
	)
	(segment
		(start 392.977624 -141.656054)
		(end 392.476482 -141.154912)
		(width 0.089408)
		(layer "In4.Cu")
		(net "XDP_CPU_OBSFN_B1_MBP7_N")
	)
	(segment
		(start 408.136598 -148.461984)
		(end 406.855422 -148.461984)
		(width 0.089408)
		(layer "In4.Cu")
		(net "XDP_CPU_OBSFN_B1_MBP7_N")
	)
	(segment
		(start 356.68331 -84.498688)
		(end 356.766622 -84.582)
		(width 0.089408)
		(layer "In4.Cu")
		(net "XDP_CPU_OBSFN_B1_MBP7_N")
	)
	(segment
		(start 342.055704 -115.04549)
		(end 342.055704 -106.45267)
		(width 0.089408)
		(layer "In4.Cu")
		(net "XDP_CPU_OBSFN_B1_MBP7_N")
	)
	(segment
		(start 418.980112 -144.249648)
		(end 417.6268 -145.60296)
		(width 0.089408)
		(layer "In4.Cu")
		(net "XDP_CPU_OBSFN_B1_MBP7_N")
	)
	(segment
		(start 371.177312 -141.154912)
		(end 370.799868 -141.532356)
		(width 0.089408)
		(layer "In4.Cu")
		(net "XDP_CPU_OBSFN_B1_MBP7_N")
	)
	(segment
		(start 342.055704 -106.45267)
		(end 340.501986 -104.898952)
		(width 0.089408)
		(layer "In4.Cu")
		(net "XDP_CPU_OBSFN_B1_MBP7_N")
	)
	(segment
		(start 350.190816 -138.139424)
		(end 349.757238 -138.139424)
		(width 0.089408)
		(layer "In4.Cu")
		(net "XDP_CPU_OBSFN_B1_MBP7_N")
	)
	(segment
		(start 454.210166 -143.891)
		(end 452.305166 -141.986)
		(width 0.089408)
		(layer "In4.Cu")
		(net "XDP_CPU_OBSFN_B1_MBP7_N")
	)
	(segment
		(start 449.58 -141.986)
		(end 449.3768 -141.7828)
		(width 0.089408)
		(layer "In4.Cu")
		(net "XDP_CPU_OBSFN_B1_MBP7_N")
	)
	(segment
		(start 348.21622 -135.01878)
		(end 346.43568 -135.01878)
		(width 0.089408)
		(layer "In4.Cu")
		(net "XDP_CPU_OBSFN_B1_MBP7_N")
	)
	(segment
		(start 342.700102 -115.689888)
		(end 342.055704 -115.04549)
		(width 0.089408)
		(layer "In4.Cu")
		(net "XDP_CPU_OBSFN_B1_MBP7_N")
	)
	(segment
		(start 346.43568 -135.01878)
		(end 344.40876 -132.99186)
		(width 0.089408)
		(layer "In4.Cu")
		(net "XDP_CPU_OBSFN_B1_MBP7_N")
	)
	(segment
		(start 340.106 -91.0082)
		(end 340.803992 -90.310208)
		(width 0.089408)
		(layer "In4.Cu")
		(net "XDP_CPU_OBSFN_B1_MBP7_N")
	)
	(segment
		(start 399.353278 -143.948658)
		(end 397.060674 -141.656054)
		(width 0.089408)
		(layer "In4.Cu")
		(net "XDP_CPU_OBSFN_B1_MBP7_N")
	)
	(segment
		(start 418.980112 -143.129762)
		(end 418.980112 -144.249648)
		(width 0.089408)
		(layer "In4.Cu")
		(net "XDP_CPU_OBSFN_B1_MBP7_N")
	)
	(segment
		(start 406.855422 -148.461984)
		(end 403.952202 -145.558764)
		(width 0.089408)
		(layer "In4.Cu")
		(net "XDP_CPU_OBSFN_B1_MBP7_N")
	)
	(segment
		(start 409.631388 -146.967194)
		(end 408.136598 -148.461984)
		(width 0.089408)
		(layer "In4.Cu")
		(net "XDP_CPU_OBSFN_B1_MBP7_N")
	)
	(segment
		(start 340.803992 -90.310208)
		(end 349.213424 -90.310208)
		(width 0.089408)
		(layer "In4.Cu")
		(net "XDP_CPU_OBSFN_B1_MBP7_N")
	)
	(segment
		(start 356.766622 -84.582)
		(end 357.6955 -84.582)
		(width 0.089408)
		(layer "In4.Cu")
		(net "XDP_CPU_OBSFN_B1_MBP7_N")
	)
	(segment
		(start 344.40876 -130.403346)
		(end 343.523062 -129.517648)
		(width 0.089408)
		(layer "In4.Cu")
		(net "XDP_CPU_OBSFN_B1_MBP7_N")
	)
	(segment
		(start 461.708754 -145.274284)
		(end 461.282796 -145.700242)
		(width 0.089408)
		(layer "In4.Cu")
		(net "XDP_CPU_OBSFN_B1_MBP7_N")
	)
	(segment
		(start 343.523062 -129.517648)
		(end 343.523062 -120.375934)
		(width 0.089408)
		(layer "In4.Cu")
		(net "XDP_CPU_OBSFN_B1_MBP7_N")
	)
	(segment
		(start 410.402786 -146.967194)
		(end 409.631388 -146.967194)
		(width 0.089408)
		(layer "In4.Cu")
		(net "XDP_CPU_OBSFN_B1_MBP7_N")
	)
	(segment
		(start 362.407708 -140.806678)
		(end 361.12323 -140.806678)
		(width 0.089408)
		(layer "In4.Cu")
		(net "XDP_CPU_OBSFN_B1_MBP7_N")
	)
	(segment
		(start 181.0004 -21.4376)
		(end 181.51094 -21.4376)
		(width 0.089408)
		(layer "In9.Cu")
		(net "XDP_CPU_OBSFN_B1_MBP7_N")
	)
	(segment
		(start 191.3128 -19.2024)
		(end 191.870076 -18.645124)
		(width 0.089408)
		(layer "In9.Cu")
		(net "XDP_CPU_OBSFN_B1_MBP7_N")
	)
	(segment
		(start 356.95636 -62.886844)
		(end 357.447596 -62.395608)
		(width 0.089408)
		(layer "In9.Cu")
		(net "XDP_CPU_OBSFN_B1_MBP7_N")
	)
	(segment
		(start 189.747906 -19.406616)
		(end 189.952376 -19.202146)
		(width 0.089408)
		(layer "In9.Cu")
		(net "XDP_CPU_OBSFN_B1_MBP7_N")
	)
	(segment
		(start 181.690772 -21.257768)
		(end 181.690772 -21.182076)
		(width 0.089408)
		(layer "In9.Cu")
		(net "XDP_CPU_OBSFN_B1_MBP7_N")
	)
	(segment
		(start 190.194946 -19.2024)
		(end 191.3128 -19.2024)
		(width 0.089408)
		(layer "In9.Cu")
		(net "XDP_CPU_OBSFN_B1_MBP7_N")
	)
	(segment
		(start 259.787136 -16.11757)
		(end 263.305798 -19.636232)
		(width 0.089408)
		(layer "In9.Cu")
		(net "XDP_CPU_OBSFN_B1_MBP7_N")
	)
	(segment
		(start 354.4062 -73.8886)
		(end 354.4062 -71.501)
		(width 0.089408)
		(layer "In9.Cu")
		(net "XDP_CPU_OBSFN_B1_MBP7_N")
	)
	(segment
		(start 190.194692 -19.202146)
		(end 190.194946 -19.2024)
		(width 0.089408)
		(layer "In9.Cu")
		(net "XDP_CPU_OBSFN_B1_MBP7_N")
	)
	(segment
		(start 325.841868 -35.707828)
		(end 326.34809 -36.21405)
		(width 0.089408)
		(layer "In9.Cu")
		(net "XDP_CPU_OBSFN_B1_MBP7_N")
	)
	(segment
		(start 259.787136 -16.09979)
		(end 259.787136 -16.11757)
		(width 0.089408)
		(layer "In9.Cu")
		(net "XDP_CPU_OBSFN_B1_MBP7_N")
	)
	(segment
		(start 186.35599 -20.007072)
		(end 186.356244 -20.006818)
		(width 0.089408)
		(layer "In9.Cu")
		(net "XDP_CPU_OBSFN_B1_MBP7_N")
	)
	(segment
		(start 321.798696 -27.962352)
		(end 325.841868 -32.005524)
		(width 0.089408)
		(layer "In9.Cu")
		(net "XDP_CPU_OBSFN_B1_MBP7_N")
	)
	(segment
		(start 191.870076 -18.083022)
		(end 195.589398 -14.3637)
		(width 0.089408)
		(layer "In9.Cu")
		(net "XDP_CPU_OBSFN_B1_MBP7_N")
	)
	(segment
		(start 356.286816 -82.949034)
		(end 354.707444 -81.369662)
		(width 0.089408)
		(layer "In9.Cu")
		(net "XDP_CPU_OBSFN_B1_MBP7_N")
	)
	(segment
		(start 186.599068 -20.006818)
		(end 187.19927 -19.406616)
		(width 0.089408)
		(layer "In9.Cu")
		(net "XDP_CPU_OBSFN_B1_MBP7_N")
	)
	(segment
		(start 356.3112 -84.045552)
		(end 356.3112 -82.973672)
		(width 0.089408)
		(layer "In9.Cu")
		(net "XDP_CPU_OBSFN_B1_MBP7_N")
	)
	(segment
		(start 325.897748 -42.908728)
		(end 325.897748 -45.129196)
		(width 0.089408)
		(layer "In9.Cu")
		(net "XDP_CPU_OBSFN_B1_MBP7_N")
	)
	(segment
		(start 266.09421 -15.729458)
		(end 266.261342 -15.562326)
		(width 0.089408)
		(layer "In9.Cu")
		(net "XDP_CPU_OBSFN_B1_MBP7_N")
	)
	(segment
		(start 181.690772 -21.182076)
		(end 182.045864 -20.826984)
		(width 0.089408)
		(layer "In9.Cu")
		(net "XDP_CPU_OBSFN_B1_MBP7_N")
	)
	(segment
		(start 355.447092 -70.460108)
		(end 355.447092 -66.40322)
		(width 0.089408)
		(layer "In9.Cu")
		(net "XDP_CPU_OBSFN_B1_MBP7_N")
	)
	(segment
		(start 189.952376 -19.202146)
		(end 190.194692 -19.202146)
		(width 0.089408)
		(layer "In9.Cu")
		(net "XDP_CPU_OBSFN_B1_MBP7_N")
	)
	(segment
		(start 322.929504 -24.004016)
		(end 321.798696 -25.134824)
		(width 0.089408)
		(layer "In9.Cu")
		(net "XDP_CPU_OBSFN_B1_MBP7_N")
	)
	(segment
		(start 266.261342 -15.562326)
		(end 321.204844 -15.562326)
		(width 0.089408)
		(layer "In9.Cu")
		(net "XDP_CPU_OBSFN_B1_MBP7_N")
	)
	(segment
		(start 355.6 -75.0824)
		(end 354.4062 -73.8886)
		(width 0.089408)
		(layer "In9.Cu")
		(net "XDP_CPU_OBSFN_B1_MBP7_N")
	)
	(segment
		(start 321.798696 -25.134824)
		(end 321.798696 -27.962352)
		(width 0.089408)
		(layer "In9.Cu")
		(net "XDP_CPU_OBSFN_B1_MBP7_N")
	)
	(segment
		(start 324.880732 -50.571654)
		(end 324.880732 -53.012848)
		(width 0.089408)
		(layer "In9.Cu")
		(net "XDP_CPU_OBSFN_B1_MBP7_N")
	)
	(segment
		(start 323.47027 -49.161192)
		(end 324.880732 -50.571654)
		(width 0.089408)
		(layer "In9.Cu")
		(net "XDP_CPU_OBSFN_B1_MBP7_N")
	)
	(segment
		(start 186.356244 -20.006818)
		(end 186.599068 -20.006818)
		(width 0.089408)
		(layer "In9.Cu")
		(net "XDP_CPU_OBSFN_B1_MBP7_N")
	)
	(segment
		(start 264.709656 -18.737072)
		(end 264.709656 -16.406622)
		(width 0.089408)
		(layer "In9.Cu")
		(net "XDP_CPU_OBSFN_B1_MBP7_N")
	)
	(segment
		(start 187.19927 -19.406616)
		(end 189.747906 -19.406616)
		(width 0.089408)
		(layer "In9.Cu")
		(net "XDP_CPU_OBSFN_B1_MBP7_N")
	)
	(segment
		(start 323.16547 -60.945522)
		(end 323.254878 -61.03493)
		(width 0.089408)
		(layer "In9.Cu")
		(net "XDP_CPU_OBSFN_B1_MBP7_N")
	)
	(segment
		(start 325.897748 -45.129196)
		(end 323.47027 -47.556674)
		(width 0.089408)
		(layer "In9.Cu")
		(net "XDP_CPU_OBSFN_B1_MBP7_N")
	)
	(segment
		(start 326.34809 -42.458386)
		(end 325.897748 -42.908728)
		(width 0.089408)
		(layer "In9.Cu")
		(net "XDP_CPU_OBSFN_B1_MBP7_N")
	)
	(segment
		(start 265.38682 -15.729458)
		(end 266.09421 -15.729458)
		(width 0.089408)
		(layer "In9.Cu")
		(net "XDP_CPU_OBSFN_B1_MBP7_N")
	)
	(segment
		(start 356.286816 -82.949288)
		(end 356.286816 -82.949034)
		(width 0.089408)
		(layer "In9.Cu")
		(net "XDP_CPU_OBSFN_B1_MBP7_N")
	)
	(segment
		(start 323.262244 -61.03493)
		(end 323.281294 -61.01588)
		(width 0.089408)
		(layer "In9.Cu")
		(net "XDP_CPU_OBSFN_B1_MBP7_N")
	)
	(segment
		(start 323.16547 -54.72811)
		(end 323.16547 -60.945522)
		(width 0.089408)
		(layer "In9.Cu")
		(net "XDP_CPU_OBSFN_B1_MBP7_N")
	)
	(segment
		(start 355.447092 -66.40322)
		(end 355.446838 -66.402966)
		(width 0.089408)
		(layer "In9.Cu")
		(net "XDP_CPU_OBSFN_B1_MBP7_N")
	)
	(segment
		(start 184.945528 -20.826984)
		(end 185.76544 -20.007072)
		(width 0.089408)
		(layer "In9.Cu")
		(net "XDP_CPU_OBSFN_B1_MBP7_N")
	)
	(segment
		(start 185.76544 -20.007072)
		(end 186.35599 -20.007072)
		(width 0.089408)
		(layer "In9.Cu")
		(net "XDP_CPU_OBSFN_B1_MBP7_N")
	)
	(segment
		(start 356.95636 -64.649604)
		(end 356.95636 -62.886844)
		(width 0.089408)
		(layer "In9.Cu")
		(net "XDP_CPU_OBSFN_B1_MBP7_N")
	)
	(segment
		(start 324.880732 -53.012848)
		(end 323.16547 -54.72811)
		(width 0.089408)
		(layer "In9.Cu")
		(net "XDP_CPU_OBSFN_B1_MBP7_N")
	)
	(segment
		(start 258.85013 -15.180564)
		(end 258.86791 -15.180564)
		(width 0.089408)
		(layer "In9.Cu")
		(net "XDP_CPU_OBSFN_B1_MBP7_N")
	)
	(segment
		(start 354.707444 -81.369662)
		(end 354.707444 -79.971392)
		(width 0.089408)
		(layer "In9.Cu")
		(net "XDP_CPU_OBSFN_B1_MBP7_N")
	)
	(segment
		(start 322.929504 -17.286986)
		(end 322.929504 -24.004016)
		(width 0.089408)
		(layer "In9.Cu")
		(net "XDP_CPU_OBSFN_B1_MBP7_N")
	)
	(segment
		(start 263.810496 -19.636232)
		(end 264.709656 -18.737072)
		(width 0.089408)
		(layer "In9.Cu")
		(net "XDP_CPU_OBSFN_B1_MBP7_N")
	)
	(segment
		(start 355.446838 -66.402966)
		(end 355.446838 -66.160396)
		(width 0.089408)
		(layer "In9.Cu")
		(net "XDP_CPU_OBSFN_B1_MBP7_N")
	)
	(segment
		(start 323.254878 -61.03493)
		(end 323.262244 -61.03493)
		(width 0.089408)
		(layer "In9.Cu")
		(net "XDP_CPU_OBSFN_B1_MBP7_N")
	)
	(segment
		(start 355.6 -79.078836)
		(end 355.6 -75.0824)
		(width 0.089408)
		(layer "In9.Cu")
		(net "XDP_CPU_OBSFN_B1_MBP7_N")
	)
	(segment
		(start 258.033266 -14.3637)
		(end 258.85013 -15.180564)
		(width 0.089408)
		(layer "In9.Cu")
		(net "XDP_CPU_OBSFN_B1_MBP7_N")
	)
	(segment
		(start 179.84343 -22.59457)
		(end 181.0004 -21.4376)
		(width 0.089408)
		(layer "In9.Cu")
		(net "XDP_CPU_OBSFN_B1_MBP7_N")
	)
	(segment
		(start 325.841868 -32.005524)
		(end 325.841868 -35.707828)
		(width 0.089408)
		(layer "In9.Cu")
		(net "XDP_CPU_OBSFN_B1_MBP7_N")
	)
	(segment
		(start 264.709656 -16.406622)
		(end 265.38682 -15.729458)
		(width 0.089408)
		(layer "In9.Cu")
		(net "XDP_CPU_OBSFN_B1_MBP7_N")
	)
	(segment
		(start 357.6955 -84.582)
		(end 356.847648 -84.582)
		(width 0.089408)
		(layer "In9.Cu")
		(net "XDP_CPU_OBSFN_B1_MBP7_N")
	)
	(segment
		(start 182.045864 -20.826984)
		(end 184.945528 -20.826984)
		(width 0.089408)
		(layer "In9.Cu")
		(net "XDP_CPU_OBSFN_B1_MBP7_N")
	)
	(segment
		(start 191.870076 -18.645124)
		(end 191.870076 -18.083022)
		(width 0.089408)
		(layer "In9.Cu")
		(net "XDP_CPU_OBSFN_B1_MBP7_N")
	)
	(segment
		(start 356.3112 -82.973672)
		(end 356.286816 -82.949288)
		(width 0.089408)
		(layer "In9.Cu")
		(net "XDP_CPU_OBSFN_B1_MBP7_N")
	)
	(segment
		(start 323.47027 -47.556674)
		(end 323.47027 -49.161192)
		(width 0.089408)
		(layer "In9.Cu")
		(net "XDP_CPU_OBSFN_B1_MBP7_N")
	)
	(segment
		(start 195.589398 -14.3637)
		(end 258.033266 -14.3637)
		(width 0.089408)
		(layer "In9.Cu")
		(net "XDP_CPU_OBSFN_B1_MBP7_N")
	)
	(segment
		(start 356.847648 -84.582)
		(end 356.3112 -84.045552)
		(width 0.089408)
		(layer "In9.Cu")
		(net "XDP_CPU_OBSFN_B1_MBP7_N")
	)
	(segment
		(start 181.51094 -21.4376)
		(end 181.690772 -21.257768)
		(width 0.089408)
		(layer "In9.Cu")
		(net "XDP_CPU_OBSFN_B1_MBP7_N")
	)
	(segment
		(start 321.204844 -15.562326)
		(end 322.929504 -17.286986)
		(width 0.089408)
		(layer "In9.Cu")
		(net "XDP_CPU_OBSFN_B1_MBP7_N")
	)
	(segment
		(start 263.305798 -19.636232)
		(end 263.810496 -19.636232)
		(width 0.089408)
		(layer "In9.Cu")
		(net "XDP_CPU_OBSFN_B1_MBP7_N")
	)
	(segment
		(start 355.446838 -66.160396)
		(end 356.95636 -64.649604)
		(width 0.089408)
		(layer "In9.Cu")
		(net "XDP_CPU_OBSFN_B1_MBP7_N")
	)
	(segment
		(start 354.707444 -79.971392)
		(end 355.6 -79.078836)
		(width 0.089408)
		(layer "In9.Cu")
		(net "XDP_CPU_OBSFN_B1_MBP7_N")
	)
	(segment
		(start 258.86791 -15.180564)
		(end 259.787136 -16.09979)
		(width 0.089408)
		(layer "In9.Cu")
		(net "XDP_CPU_OBSFN_B1_MBP7_N")
	)
	(segment
		(start 354.4062 -71.501)
		(end 355.447092 -70.460108)
		(width 0.089408)
		(layer "In9.Cu")
		(net "XDP_CPU_OBSFN_B1_MBP7_N")
	)
	(segment
		(start 179.661566 -22.59457)
		(end 179.84343 -22.59457)
		(width 0.089408)
		(layer "In9.Cu")
		(net "XDP_CPU_OBSFN_B1_MBP7_N")
	)
	(segment
		(start 326.34809 -36.21405)
		(end 326.34809 -42.458386)
		(width 0.089408)
		(layer "In9.Cu")
		(net "XDP_CPU_OBSFN_B1_MBP7_N")
	)
	(segment
		(start 136.125966 -62.248034)
		(end 135.938768 -62.248034)
		(width 0.0889)
		(layer "In11.Cu")
		(net "XDP_CPU_OBSFN_B1_MBP7_N")
	)
	(segment
		(start 307.70957 -61.448188)
		(end 308.411626 -61.448188)
		(width 0.0889)
		(layer "In11.Cu")
		(net "XDP_CPU_OBSFN_B1_MBP7_N")
	)
	(segment
		(start 306.757832 -61.982858)
		(end 307.174646 -61.982858)
		(width 0.0889)
		(layer "In11.Cu")
		(net "XDP_CPU_OBSFN_B1_MBP7_N")
	)
	(segment
		(start 173.736 -30.06852)
		(end 173.33722 -31.03118)
		(width 0.089408)
		(layer "In11.Cu")
		(net "XDP_CPU_OBSFN_B1_MBP7_N")
	)
	(segment
		(start 298.378626 -62.343538)
		(end 298.378626 -62.005464)
		(width 0.0889)
		(layer "In11.Cu")
		(net "XDP_CPU_OBSFN_B1_MBP7_N")
	)
	(segment
		(start 175.41748 -25.54732)
		(end 175.19396 -25.77084)
		(width 0.089408)
		(layer "In11.Cu")
		(net "XDP_CPU_OBSFN_B1_MBP7_N")
	)
	(segment
		(start 306.545742 -61.770768)
		(end 306.757832 -61.982858)
		(width 0.0889)
		(layer "In11.Cu")
		(net "XDP_CPU_OBSFN_B1_MBP7_N")
	)
	(segment
		(start 307.190648 -61.96711)
		(end 307.70957 -61.448188)
		(width 0.0889)
		(layer "In11.Cu")
		(net "XDP_CPU_OBSFN_B1_MBP7_N")
	)
	(segment
		(start 332.64475 -60.483496)
		(end 333.013304 -60.85205)
		(width 0.089408)
		(layer "In11.Cu")
		(net "XDP_CPU_OBSFN_B1_MBP7_N")
	)
	(segment
		(start 142.9766 -59.436)
		(end 140.8684 -59.436)
		(width 0.089408)
		(layer "In11.Cu")
		(net "XDP_CPU_OBSFN_B1_MBP7_N")
	)
	(segment
		(start 334.010508 -61.933328)
		(end 357.12654 -61.933328)
		(width 0.089408)
		(layer "In11.Cu")
		(net "XDP_CPU_OBSFN_B1_MBP7_N")
	)
	(segment
		(start 134.2517 -62.248034)
		(end 134.218934 -62.248034)
		(width 0.0889)
		(layer "In11.Cu")
		(net "XDP_CPU_OBSFN_B1_MBP7_N")
	)
	(segment
		(start 135.116824 -61.752988)
		(end 135.073644 -61.752988)
		(width 0.0889)
		(layer "In11.Cu")
		(net "XDP_CPU_OBSFN_B1_MBP7_N")
	)
	(segment
		(start 357.12654 -61.933328)
		(end 357.447596 -62.254384)
		(width 0.089408)
		(layer "In11.Cu")
		(net "XDP_CPU_OBSFN_B1_MBP7_N")
	)
	(segment
		(start 173.736 -29.291026)
		(end 173.736 -30.06852)
		(width 0.089408)
		(layer "In11.Cu")
		(net "XDP_CPU_OBSFN_B1_MBP7_N")
	)
	(segment
		(start 308.41188 -61.447934)
		(end 308.558438 -61.447934)
		(width 0.0889)
		(layer "In11.Cu")
		(net "XDP_CPU_OBSFN_B1_MBP7_N")
	)
	(segment
		(start 357.447596 -62.254384)
		(end 357.447596 -62.395608)
		(width 0.089408)
		(layer "In11.Cu")
		(net "XDP_CPU_OBSFN_B1_MBP7_N")
	)
	(segment
		(start 323.281294 -61.01588)
		(end 323.565774 -61.30036)
		(width 0.089408)
		(layer "In11.Cu")
		(net "XDP_CPU_OBSFN_B1_MBP7_N")
	)
	(segment
		(start 302.66005 -61.447934)
		(end 302.682402 -61.447934)
		(width 0.0889)
		(layer "In11.Cu")
		(net "XDP_CPU_OBSFN_B1_MBP7_N")
	)
	(segment
		(start 333.013304 -60.936124)
		(end 334.010508 -61.933328)
		(width 0.089408)
		(layer "In11.Cu")
		(net "XDP_CPU_OBSFN_B1_MBP7_N")
	)
	(segment
		(start 177.735484 -24.5872)
		(end 175.41748 -25.54732)
		(width 0.089408)
		(layer "In11.Cu")
		(net "XDP_CPU_OBSFN_B1_MBP7_N")
	)
	(segment
		(start 138.2776 -60.833)
		(end 137.7696 -61.341)
		(width 0.089408)
		(layer "In11.Cu")
		(net "XDP_CPU_OBSFN_B1_MBP7_N")
	)
	(segment
		(start 137.7696 -61.341)
		(end 137.414 -61.341)
		(width 0.089408)
		(layer "In11.Cu")
		(net "XDP_CPU_OBSFN_B1_MBP7_N")
	)
	(segment
		(start 145.669 -52.048156)
		(end 145.669 -53.715412)
		(width 0.089408)
		(layer "In11.Cu")
		(net "XDP_CPU_OBSFN_B1_MBP7_N")
	)
	(segment
		(start 308.762908 -61.243464)
		(end 310.97093 -61.243464)
		(width 0.0889)
		(layer "In11.Cu")
		(net "XDP_CPU_OBSFN_B1_MBP7_N")
	)
	(segment
		(start 308.411626 -61.448188)
		(end 308.41188 -61.447934)
		(width 0.0889)
		(layer "In11.Cu")
		(net "XDP_CPU_OBSFN_B1_MBP7_N")
	)
	(segment
		(start 179.661566 -22.59457)
		(end 179.661566 -23.457154)
		(width 0.089408)
		(layer "In11.Cu")
		(net "XDP_CPU_OBSFN_B1_MBP7_N")
	)
	(segment
		(start 136.5504 -61.8236)
		(end 136.125966 -62.248034)
		(width 0.0889)
		(layer "In11.Cu")
		(net "XDP_CPU_OBSFN_B1_MBP7_N")
	)
	(segment
		(start 308.558438 -61.447934)
		(end 308.762908 -61.243464)
		(width 0.0889)
		(layer "In11.Cu")
		(net "XDP_CPU_OBSFN_B1_MBP7_N")
	)
	(segment
		(start 179.661566 -23.457154)
		(end 178.53152 -24.5872)
		(width 0.089408)
		(layer "In11.Cu")
		(net "XDP_CPU_OBSFN_B1_MBP7_N")
	)
	(segment
		(start 310.97093 -61.243464)
		(end 313.423046 -63.69558)
		(width 0.0889)
		(layer "In11.Cu")
		(net "XDP_CPU_OBSFN_B1_MBP7_N")
	)
	(segment
		(start 307.174646 -61.982858)
		(end 307.190394 -61.96711)
		(width 0.0889)
		(layer "In11.Cu")
		(net "XDP_CPU_OBSFN_B1_MBP7_N")
	)
	(segment
		(start 307.190394 -61.96711)
		(end 307.190648 -61.96711)
		(width 0.0889)
		(layer "In11.Cu")
		(net "XDP_CPU_OBSFN_B1_MBP7_N")
	)
	(segment
		(start 168.546018 -33.8074)
		(end 161.617406 -36.6776)
		(width 0.089408)
		(layer "In11.Cu")
		(net "XDP_CPU_OBSFN_B1_MBP7_N")
	)
	(segment
		(start 136.9314 -61.8236)
		(end 136.5504 -61.8236)
		(width 0.089408)
		(layer "In11.Cu")
		(net "XDP_CPU_OBSFN_B1_MBP7_N")
	)
	(segment
		(start 326.1995 -60.483496)
		(end 332.64475 -60.483496)
		(width 0.089408)
		(layer "In11.Cu")
		(net "XDP_CPU_OBSFN_B1_MBP7_N")
	)
	(segment
		(start 139.192 -60.2742)
		(end 138.6332 -60.833)
		(width 0.089408)
		(layer "In11.Cu")
		(net "XDP_CPU_OBSFN_B1_MBP7_N")
	)
	(segment
		(start 299.22597 -61.447934)
		(end 299.248322 -61.447934)
		(width 0.0889)
		(layer "In11.Cu")
		(net "XDP_CPU_OBSFN_B1_MBP7_N")
	)
	(segment
		(start 140.8684 -59.436)
		(end 140.4112 -59.8932)
		(width 0.089408)
		(layer "In11.Cu")
		(net "XDP_CPU_OBSFN_B1_MBP7_N")
	)
	(segment
		(start 159.0294 -36.6776)
		(end 147.090384 -48.616616)
		(width 0.089408)
		(layer "In11.Cu")
		(net "XDP_CPU_OBSFN_B1_MBP7_N")
	)
	(segment
		(start 140.4112 -59.8932)
		(end 139.9794 -59.8932)
		(width 0.089408)
		(layer "In11.Cu")
		(net "XDP_CPU_OBSFN_B1_MBP7_N")
	)
	(segment
		(start 304.37709 -61.447934)
		(end 304.399442 -61.447934)
		(width 0.0889)
		(layer "In11.Cu")
		(net "XDP_CPU_OBSFN_B1_MBP7_N")
	)
	(segment
		(start 298.378626 -62.005464)
		(end 298.443904 -61.940186)
		(width 0.0889)
		(layer "In11.Cu")
		(net "XDP_CPU_OBSFN_B1_MBP7_N")
	)
	(segment
		(start 306.09413 -61.447934)
		(end 306.116482 -61.447934)
		(width 0.0889)
		(layer "In11.Cu")
		(net "XDP_CPU_OBSFN_B1_MBP7_N")
	)
	(segment
		(start 161.617406 -36.6776)
		(end 159.0294 -36.6776)
		(width 0.089408)
		(layer "In11.Cu")
		(net "XDP_CPU_OBSFN_B1_MBP7_N")
	)
	(segment
		(start 171.785788 -32.582612)
		(end 168.829228 -33.8074)
		(width 0.089408)
		(layer "In11.Cu")
		(net "XDP_CPU_OBSFN_B1_MBP7_N")
	)
	(segment
		(start 322.462652 -61.01588)
		(end 323.281294 -61.01588)
		(width 0.089408)
		(layer "In11.Cu")
		(net "XDP_CPU_OBSFN_B1_MBP7_N")
	)
	(segment
		(start 137.414 -61.341)
		(end 136.9314 -61.8236)
		(width 0.089408)
		(layer "In11.Cu")
		(net "XDP_CPU_OBSFN_B1_MBP7_N")
	)
	(segment
		(start 145.669 -53.715412)
		(end 143.527272 -58.885328)
		(width 0.089408)
		(layer "In11.Cu")
		(net "XDP_CPU_OBSFN_B1_MBP7_N")
	)
	(segment
		(start 173.33722 -31.03118)
		(end 171.785788 -32.582612)
		(width 0.089408)
		(layer "In11.Cu")
		(net "XDP_CPU_OBSFN_B1_MBP7_N")
	)
	(segment
		(start 333.013304 -60.85205)
		(end 333.013304 -60.936124)
		(width 0.089408)
		(layer "In11.Cu")
		(net "XDP_CPU_OBSFN_B1_MBP7_N")
	)
	(segment
		(start 300.077886 -61.943488)
		(end 300.113446 -61.943488)
		(width 0.0889)
		(layer "In11.Cu")
		(net "XDP_CPU_OBSFN_B1_MBP7_N")
	)
	(segment
		(start 175.19396 -25.77084)
		(end 173.736 -29.291026)
		(width 0.089408)
		(layer "In11.Cu")
		(net "XDP_CPU_OBSFN_B1_MBP7_N")
	)
	(segment
		(start 313.423046 -63.69558)
		(end 319.782952 -63.69558)
		(width 0.089408)
		(layer "In11.Cu")
		(net "XDP_CPU_OBSFN_B1_MBP7_N")
	)
	(segment
		(start 139.5984 -60.2742)
		(end 139.192 -60.2742)
		(width 0.089408)
		(layer "In11.Cu")
		(net "XDP_CPU_OBSFN_B1_MBP7_N")
	)
	(segment
		(start 178.53152 -24.5872)
		(end 177.735484 -24.5872)
		(width 0.089408)
		(layer "In11.Cu")
		(net "XDP_CPU_OBSFN_B1_MBP7_N")
	)
	(segment
		(start 138.6332 -60.833)
		(end 138.2776 -60.833)
		(width 0.089408)
		(layer "In11.Cu")
		(net "XDP_CPU_OBSFN_B1_MBP7_N")
	)
	(segment
		(start 139.9794 -59.8932)
		(end 139.5984 -60.2742)
		(width 0.089408)
		(layer "In11.Cu")
		(net "XDP_CPU_OBSFN_B1_MBP7_N")
	)
	(segment
		(start 143.527272 -58.885328)
		(end 142.9766 -59.436)
		(width 0.089408)
		(layer "In11.Cu")
		(net "XDP_CPU_OBSFN_B1_MBP7_N")
	)
	(segment
		(start 147.090384 -48.616616)
		(end 145.669 -52.048156)
		(width 0.089408)
		(layer "In11.Cu")
		(net "XDP_CPU_OBSFN_B1_MBP7_N")
	)
	(segment
		(start 168.829228 -33.8074)
		(end 168.546018 -33.8074)
		(width 0.089408)
		(layer "In11.Cu")
		(net "XDP_CPU_OBSFN_B1_MBP7_N")
	)
	(segment
		(start 323.565774 -61.30036)
		(end 325.382636 -61.30036)
		(width 0.089408)
		(layer "In11.Cu")
		(net "XDP_CPU_OBSFN_B1_MBP7_N")
	)
	(segment
		(start 300.94301 -61.447934)
		(end 300.965362 -61.447934)
		(width 0.0889)
		(layer "In11.Cu")
		(net "XDP_CPU_OBSFN_B1_MBP7_N")
	)
	(segment
		(start 325.382636 -61.30036)
		(end 326.1995 -60.483496)
		(width 0.089408)
		(layer "In11.Cu")
		(net "XDP_CPU_OBSFN_B1_MBP7_N")
	)
	(segment
		(start 319.782952 -63.69558)
		(end 322.462652 -61.01588)
		(width 0.089408)
		(layer "In11.Cu")
		(net "XDP_CPU_OBSFN_B1_MBP7_N")
	)
	(arc
		(start 300.607476 -61.648086)
		(mid 300.749159 -61.504282)
		(end 300.94301 -61.447934)
		(width 0.0889)
		(layer "In11.Cu")
		(net "XDP_CPU_OBSFN_B1_MBP7_N")
	)
	(arc
		(start 302.324516 -61.648086)
		(mid 302.466199 -61.504282)
		(end 302.66005 -61.447934)
		(width 0.0889)
		(layer "In11.Cu")
		(net "XDP_CPU_OBSFN_B1_MBP7_N")
	)
	(arc
		(start 299.583856 -61.648086)
		(mid 299.792464 -61.860018)
		(end 300.077886 -61.943488)
		(width 0.0889)
		(layer "In11.Cu")
		(net "XDP_CPU_OBSFN_B1_MBP7_N")
	)
	(arc
		(start 302.682402 -61.447934)
		(mid 302.876252 -61.504284)
		(end 303.017936 -61.648086)
		(width 0.0889)
		(layer "In11.Cu")
		(net "XDP_CPU_OBSFN_B1_MBP7_N")
	)
	(arc
		(start 134.218934 -62.248034)
		(mid 133.795861 -62.271987)
		(end 133.378194 -62.343538)
		(width 0.0889)
		(layer "In11.Cu")
		(net "XDP_CPU_OBSFN_B1_MBP7_N")
	)
	(arc
		(start 306.478432 -61.689996)
		(mid 306.510287 -61.731882)
		(end 306.545742 -61.770768)
		(width 0.0889)
		(layer "In11.Cu")
		(net "XDP_CPU_OBSFN_B1_MBP7_N")
	)
	(arc
		(start 304.399442 -61.447934)
		(mid 304.593292 -61.504284)
		(end 304.734976 -61.648086)
		(width 0.0889)
		(layer "In11.Cu")
		(net "XDP_CPU_OBSFN_B1_MBP7_N")
	)
	(arc
		(start 135.607044 -62.048136)
		(mid 135.40004 -61.837272)
		(end 135.116824 -61.752988)
		(width 0.0889)
		(layer "In11.Cu")
		(net "XDP_CPU_OBSFN_B1_MBP7_N")
	)
	(arc
		(start 304.041556 -61.648086)
		(mid 304.183239 -61.504282)
		(end 304.37709 -61.447934)
		(width 0.0889)
		(layer "In11.Cu")
		(net "XDP_CPU_OBSFN_B1_MBP7_N")
	)
	(arc
		(start 135.741918 -62.187582)
		(mid 135.665908 -62.126151)
		(end 135.607044 -62.048136)
		(width 0.0889)
		(layer "In11.Cu")
		(net "XDP_CPU_OBSFN_B1_MBP7_N")
	)
	(arc
		(start 298.890436 -61.648086)
		(mid 299.032119 -61.504282)
		(end 299.22597 -61.447934)
		(width 0.0889)
		(layer "In11.Cu")
		(net "XDP_CPU_OBSFN_B1_MBP7_N")
	)
	(arc
		(start 134.583424 -62.048136)
		(mid 134.443345 -62.190872)
		(end 134.2517 -62.248034)
		(width 0.0889)
		(layer "In11.Cu")
		(net "XDP_CPU_OBSFN_B1_MBP7_N")
	)
	(arc
		(start 299.248322 -61.447934)
		(mid 299.442172 -61.504284)
		(end 299.583856 -61.648086)
		(width 0.0889)
		(layer "In11.Cu")
		(net "XDP_CPU_OBSFN_B1_MBP7_N")
	)
	(arc
		(start 303.017936 -61.648086)
		(mid 303.529746 -61.943753)
		(end 304.041556 -61.648086)
		(width 0.0889)
		(layer "In11.Cu")
		(net "XDP_CPU_OBSFN_B1_MBP7_N")
	)
	(arc
		(start 306.452016 -61.648086)
		(mid 306.464787 -61.669316)
		(end 306.478432 -61.689996)
		(width 0.0889)
		(layer "In11.Cu")
		(net "XDP_CPU_OBSFN_B1_MBP7_N")
	)
	(arc
		(start 300.965362 -61.447934)
		(mid 301.159212 -61.504284)
		(end 301.300896 -61.648086)
		(width 0.0889)
		(layer "In11.Cu")
		(net "XDP_CPU_OBSFN_B1_MBP7_N")
	)
	(arc
		(start 304.734976 -61.648086)
		(mid 305.246786 -61.943753)
		(end 305.758596 -61.648086)
		(width 0.0889)
		(layer "In11.Cu")
		(net "XDP_CPU_OBSFN_B1_MBP7_N")
	)
	(arc
		(start 135.938768 -62.248034)
		(mid 135.8364 -62.230659)
		(end 135.741918 -62.187582)
		(width 0.0889)
		(layer "In11.Cu")
		(net "XDP_CPU_OBSFN_B1_MBP7_N")
	)
	(arc
		(start 305.758596 -61.648086)
		(mid 305.900279 -61.504282)
		(end 306.09413 -61.447934)
		(width 0.0889)
		(layer "In11.Cu")
		(net "XDP_CPU_OBSFN_B1_MBP7_N")
	)
	(arc
		(start 135.073644 -61.752988)
		(mid 134.790427 -61.837269)
		(end 134.583424 -62.048136)
		(width 0.0889)
		(layer "In11.Cu")
		(net "XDP_CPU_OBSFN_B1_MBP7_N")
	)
	(arc
		(start 301.300896 -61.648086)
		(mid 301.812706 -61.943753)
		(end 302.324516 -61.648086)
		(width 0.0889)
		(layer "In11.Cu")
		(net "XDP_CPU_OBSFN_B1_MBP7_N")
	)
	(arc
		(start 306.116482 -61.447934)
		(mid 306.310332 -61.504284)
		(end 306.452016 -61.648086)
		(width 0.0889)
		(layer "In11.Cu")
		(net "XDP_CPU_OBSFN_B1_MBP7_N")
	)
	(arc
		(start 300.113446 -61.943488)
		(mid 300.39887 -61.860021)
		(end 300.607476 -61.648086)
		(width 0.0889)
		(layer "In11.Cu")
		(net "XDP_CPU_OBSFN_B1_MBP7_N")
	)
	(arc
		(start 298.443904 -61.940186)
		(mid 298.702041 -61.847432)
		(end 298.890436 -61.648086)
		(width 0.0889)
		(layer "In11.Cu")
		(net "XDP_CPU_OBSFN_B1_MBP7_N")
	)
	(segment
		(start 132.806694 -63.334138)
		(end 133.378194 -63.334138)
		(width 0.1016)
		(layer "F.Cu")
		(net "XDP_CPU_OBSFN_B0_MBP6_N")
	)
	(segment
		(start 297.807126 -63.334138)
		(end 298.378626 -63.334138)
		(width 0.1016)
		(layer "F.Cu")
		(net "XDP_CPU_OBSFN_B0_MBP6_N")
	)
	(via
		(at 181.1782 -21.844)
		(size 0.508)
		(drill 0.254)
		(layers "F.Cu" "B.Cu")
		(net "XDP_CPU_OBSFN_B0_MBP6_N")
	)
	(via
		(at 133.378194 -63.334138)
		(size 0.508)
		(drill 0.254)
		(layers "F.Cu" "B.Cu")
		(net "XDP_CPU_OBSFN_B0_MBP6_N")
	)
	(via
		(at 310.058308 -55.043832)
		(size 0.508)
		(drill 0.254)
		(layers "F.Cu" "B.Cu")
		(net "XDP_CPU_OBSFN_B0_MBP6_N")
	)
	(via
		(at 461.33512 -139.8016)
		(size 0.508)
		(drill 0.254)
		(layers "F.Cu" "B.Cu")
		(net "XDP_CPU_OBSFN_B0_MBP6_N")
	)
	(via
		(at 355.4984 -56.7944)
		(size 0.508)
		(drill 0.254)
		(layers "F.Cu" "B.Cu")
		(net "XDP_CPU_OBSFN_B0_MBP6_N")
	)
	(via
		(at 355.7016 -85.1916)
		(size 0.508)
		(drill 0.254)
		(layers "F.Cu" "B.Cu")
		(net "XDP_CPU_OBSFN_B0_MBP6_N")
	)
	(via
		(at 298.378626 -63.334138)
		(size 0.508)
		(drill 0.254)
		(layers "F.Cu" "B.Cu")
		(net "XDP_CPU_OBSFN_B0_MBP6_N")
	)
	(segment
		(start 460.921608 -138.252454)
		(end 460.753206 -138.084052)
		(width 0.10795)
		(layer "B.Cu")
		(net "XDP_CPU_OBSFN_B0_MBP6_N")
	)
	(segment
		(start 461.33512 -139.118848)
		(end 460.921608 -138.705336)
		(width 0.10795)
		(layer "B.Cu")
		(net "XDP_CPU_OBSFN_B0_MBP6_N")
	)
	(segment
		(start 181.1782 -21.844)
		(end 180.8226 -21.4884)
		(width 0.10795)
		(layer "B.Cu")
		(net "XDP_CPU_OBSFN_B0_MBP6_N")
	)
	(segment
		(start 460.753206 -138.084052)
		(end 460.753206 -137.694162)
		(width 0.10795)
		(layer "B.Cu")
		(net "XDP_CPU_OBSFN_B0_MBP6_N")
	)
	(segment
		(start 180.8226 -21.4884)
		(end 180.8226 -21.07311)
		(width 0.10795)
		(layer "B.Cu")
		(net "XDP_CPU_OBSFN_B0_MBP6_N")
	)
	(segment
		(start 461.33512 -139.8016)
		(end 461.33512 -139.118848)
		(width 0.10795)
		(layer "B.Cu")
		(net "XDP_CPU_OBSFN_B0_MBP6_N")
	)
	(segment
		(start 460.921608 -138.705336)
		(end 460.921608 -138.252454)
		(width 0.10795)
		(layer "B.Cu")
		(net "XDP_CPU_OBSFN_B0_MBP6_N")
	)
	(segment
		(start 180.8226 -21.07311)
		(end 180.653182 -20.903692)
		(width 0.10795)
		(layer "B.Cu")
		(net "XDP_CPU_OBSFN_B0_MBP6_N")
	)
	(segment
		(start 344.108278 -121.730516)
		(end 344.72626 -121.112534)
		(width 0.089408)
		(layer "In4.Cu")
		(net "XDP_CPU_OBSFN_B0_MBP6_N")
	)
	(segment
		(start 448.31762 -140.589)
		(end 447.55562 -141.351)
		(width 0.089408)
		(layer "In4.Cu")
		(net "XDP_CPU_OBSFN_B0_MBP6_N")
	)
	(segment
		(start 399.64614 -143.890746)
		(end 399.64614 -143.8275)
		(width 0.089408)
		(layer "In4.Cu")
		(net "XDP_CPU_OBSFN_B0_MBP6_N")
	)
	(segment
		(start 442.900562 -140.042138)
		(end 442.88202 -140.023596)
		(width 0.089408)
		(layer "In4.Cu")
		(net "XDP_CPU_OBSFN_B0_MBP6_N")
	)
	(segment
		(start 349.461074 -134.37108)
		(end 346.61602 -134.37108)
		(width 0.089408)
		(layer "In4.Cu")
		(net "XDP_CPU_OBSFN_B0_MBP6_N")
	)
	(segment
		(start 337.984084 -92.105226)
		(end 337.984338 -92.10548)
		(width 0.089408)
		(layer "In4.Cu")
		(net "XDP_CPU_OBSFN_B0_MBP6_N")
	)
	(segment
		(start 461.33512 -139.8016)
		(end 460.868776 -140.267944)
		(width 0.089408)
		(layer "In4.Cu")
		(net "XDP_CPU_OBSFN_B0_MBP6_N")
	)
	(segment
		(start 345.331288 -133.086348)
		(end 345.331288 -128.30302)
		(width 0.089408)
		(layer "In4.Cu")
		(net "XDP_CPU_OBSFN_B0_MBP6_N")
	)
	(segment
		(start 365.576866 -141.239748)
		(end 364.888272 -140.551154)
		(width 0.089408)
		(layer "In4.Cu")
		(net "XDP_CPU_OBSFN_B0_MBP6_N")
	)
	(segment
		(start 337.984338 -92.10548)
		(end 348.111064 -92.10548)
		(width 0.089408)
		(layer "In4.Cu")
		(net "XDP_CPU_OBSFN_B0_MBP6_N")
	)
	(segment
		(start 450.088 -141.605)
		(end 449.072 -140.589)
		(width 0.089408)
		(layer "In4.Cu")
		(net "XDP_CPU_OBSFN_B0_MBP6_N")
	)
	(segment
		(start 440.563508 -140.301472)
		(end 439.662062 -140.301472)
		(width 0.089408)
		(layer "In4.Cu")
		(net "XDP_CPU_OBSFN_B0_MBP6_N")
	)
	(segment
		(start 346.61602 -134.37108)
		(end 345.331288 -133.086348)
		(width 0.089408)
		(layer "In4.Cu")
		(net "XDP_CPU_OBSFN_B0_MBP6_N")
	)
	(segment
		(start 411.710632 -144.698974)
		(end 409.99283 -146.416776)
		(width 0.089408)
		(layer "In4.Cu")
		(net "XDP_CPU_OBSFN_B0_MBP6_N")
	)
	(segment
		(start 355.7016 -88.833452)
		(end 355.7016 -85.1916)
		(width 0.089408)
		(layer "In4.Cu")
		(net "XDP_CPU_OBSFN_B0_MBP6_N")
	)
	(segment
		(start 442.970158 -140.042138)
		(end 442.900562 -140.042138)
		(width 0.089408)
		(layer "In4.Cu")
		(net "XDP_CPU_OBSFN_B0_MBP6_N")
	)
	(segment
		(start 412.104586 -143.6116)
		(end 411.710632 -144.005554)
		(width 0.089408)
		(layer "In4.Cu")
		(net "XDP_CPU_OBSFN_B0_MBP6_N")
	)
	(segment
		(start 416.744912 -142.560294)
		(end 413.775906 -142.560294)
		(width 0.089408)
		(layer "In4.Cu")
		(net "XDP_CPU_OBSFN_B0_MBP6_N")
	)
	(segment
		(start 342.646 -110.27918)
		(end 342.646 -106.214926)
		(width 0.089408)
		(layer "In4.Cu")
		(net "XDP_CPU_OBSFN_B0_MBP6_N")
	)
	(segment
		(start 441.971176 -140.359892)
		(end 440.621928 -140.359892)
		(width 0.089408)
		(layer "In4.Cu")
		(net "XDP_CPU_OBSFN_B0_MBP6_N")
	)
	(segment
		(start 348.111064 -92.10548)
		(end 349.32112 -90.895424)
		(width 0.089408)
		(layer "In4.Cu")
		(net "XDP_CPU_OBSFN_B0_MBP6_N")
	)
	(segment
		(start 364.888272 -140.551154)
		(end 362.689394 -140.551154)
		(width 0.089408)
		(layer "In4.Cu")
		(net "XDP_CPU_OBSFN_B0_MBP6_N")
	)
	(segment
		(start 344.22461 -116.554758)
		(end 344.22461 -115.949984)
		(width 0.089408)
		(layer "In4.Cu")
		(net "XDP_CPU_OBSFN_B0_MBP6_N")
	)
	(segment
		(start 351.818194 -90.203274)
		(end 354.331778 -90.203274)
		(width 0.089408)
		(layer "In4.Cu")
		(net "XDP_CPU_OBSFN_B0_MBP6_N")
	)
	(segment
		(start 459.737968 -146.639026)
		(end 458.44968 -146.639026)
		(width 0.089408)
		(layer "In4.Cu")
		(net "XDP_CPU_OBSFN_B0_MBP6_N")
	)
	(segment
		(start 371.0559 -140.862304)
		(end 370.678456 -141.239748)
		(width 0.089408)
		(layer "In4.Cu")
		(net "XDP_CPU_OBSFN_B0_MBP6_N")
	)
	(segment
		(start 393.099036 -141.363446)
		(end 392.597894 -140.862304)
		(width 0.089408)
		(layer "In4.Cu")
		(net "XDP_CPU_OBSFN_B0_MBP6_N")
	)
	(segment
		(start 438.223914 -141.73962)
		(end 417.565586 -141.73962)
		(width 0.089408)
		(layer "In4.Cu")
		(net "XDP_CPU_OBSFN_B0_MBP6_N")
	)
	(segment
		(start 333.732378 -102.65918)
		(end 333.732378 -96.114616)
		(width 0.089408)
		(layer "In4.Cu")
		(net "XDP_CPU_OBSFN_B0_MBP6_N")
	)
	(segment
		(start 333.732378 -96.114616)
		(end 337.741768 -92.105226)
		(width 0.089408)
		(layer "In4.Cu")
		(net "XDP_CPU_OBSFN_B0_MBP6_N")
	)
	(segment
		(start 342.646 -106.214926)
		(end 340.74481 -104.313736)
		(width 0.089408)
		(layer "In4.Cu")
		(net "XDP_CPU_OBSFN_B0_MBP6_N")
	)
	(segment
		(start 343.325704 -110.958884)
		(end 342.646 -110.27918)
		(width 0.089408)
		(layer "In4.Cu")
		(net "XDP_CPU_OBSFN_B0_MBP6_N")
	)
	(segment
		(start 460.868776 -140.267944)
		(end 460.868776 -145.508218)
		(width 0.089408)
		(layer "In4.Cu")
		(net "XDP_CPU_OBSFN_B0_MBP6_N")
	)
	(segment
		(start 399.64614 -143.8275)
		(end 397.182086 -141.363446)
		(width 0.089408)
		(layer "In4.Cu")
		(net "XDP_CPU_OBSFN_B0_MBP6_N")
	)
	(segment
		(start 453.415654 -141.605)
		(end 450.088 -141.605)
		(width 0.089408)
		(layer "In4.Cu")
		(net "XDP_CPU_OBSFN_B0_MBP6_N")
	)
	(segment
		(start 439.662062 -140.301472)
		(end 438.223914 -141.73962)
		(width 0.089408)
		(layer "In4.Cu")
		(net "XDP_CPU_OBSFN_B0_MBP6_N")
	)
	(segment
		(start 335.386934 -104.313736)
		(end 333.732378 -102.65918)
		(width 0.089408)
		(layer "In4.Cu")
		(net "XDP_CPU_OBSFN_B0_MBP6_N")
	)
	(segment
		(start 340.74481 -104.313736)
		(end 335.386934 -104.313736)
		(width 0.089408)
		(layer "In4.Cu")
		(net "XDP_CPU_OBSFN_B0_MBP6_N")
	)
	(segment
		(start 392.597894 -140.862304)
		(end 371.0559 -140.862304)
		(width 0.089408)
		(layer "In4.Cu")
		(net "XDP_CPU_OBSFN_B0_MBP6_N")
	)
	(segment
		(start 337.741768 -92.105226)
		(end 337.984084 -92.105226)
		(width 0.089408)
		(layer "In4.Cu")
		(net "XDP_CPU_OBSFN_B0_MBP6_N")
	)
	(segment
		(start 397.182086 -141.363446)
		(end 393.099036 -141.363446)
		(width 0.089408)
		(layer "In4.Cu")
		(net "XDP_CPU_OBSFN_B0_MBP6_N")
	)
	(segment
		(start 413.775906 -142.560294)
		(end 412.7246 -143.6116)
		(width 0.089408)
		(layer "In4.Cu")
		(net "XDP_CPU_OBSFN_B0_MBP6_N")
	)
	(segment
		(start 404.172674 -145.266156)
		(end 401.02155 -145.266156)
		(width 0.089408)
		(layer "In4.Cu")
		(net "XDP_CPU_OBSFN_B0_MBP6_N")
	)
	(segment
		(start 344.22461 -115.949984)
		(end 343.325704 -115.051078)
		(width 0.089408)
		(layer "In4.Cu")
		(net "XDP_CPU_OBSFN_B0_MBP6_N")
	)
	(segment
		(start 349.32112 -90.895424)
		(end 351.126044 -90.895424)
		(width 0.089408)
		(layer "In4.Cu")
		(net "XDP_CPU_OBSFN_B0_MBP6_N")
	)
	(segment
		(start 405.378158 -146.47164)
		(end 404.172674 -145.266156)
		(width 0.089408)
		(layer "In4.Cu")
		(net "XDP_CPU_OBSFN_B0_MBP6_N")
	)
	(segment
		(start 401.02155 -145.266156)
		(end 399.64614 -143.890746)
		(width 0.089408)
		(layer "In4.Cu")
		(net "XDP_CPU_OBSFN_B0_MBP6_N")
	)
	(segment
		(start 449.072 -140.589)
		(end 448.31762 -140.589)
		(width 0.089408)
		(layer "In4.Cu")
		(net "XDP_CPU_OBSFN_B0_MBP6_N")
	)
	(segment
		(start 442.307472 -140.023596)
		(end 441.971176 -140.359892)
		(width 0.089408)
		(layer "In4.Cu")
		(net "XDP_CPU_OBSFN_B0_MBP6_N")
	)
	(segment
		(start 460.868776 -145.508218)
		(end 459.737968 -146.639026)
		(width 0.089408)
		(layer "In4.Cu")
		(net "XDP_CPU_OBSFN_B0_MBP6_N")
	)
	(segment
		(start 444.31204 -141.351)
		(end 443.262512 -140.301472)
		(width 0.089408)
		(layer "In4.Cu")
		(net "XDP_CPU_OBSFN_B0_MBP6_N")
	)
	(segment
		(start 344.72626 -121.112534)
		(end 344.72626 -117.056408)
		(width 0.089408)
		(layer "In4.Cu")
		(net "XDP_CPU_OBSFN_B0_MBP6_N")
	)
	(segment
		(start 458.44968 -146.639026)
		(end 453.415654 -141.605)
		(width 0.089408)
		(layer "In4.Cu")
		(net "XDP_CPU_OBSFN_B0_MBP6_N")
	)
	(segment
		(start 443.229492 -140.301472)
		(end 442.970158 -140.042138)
		(width 0.089408)
		(layer "In4.Cu")
		(net "XDP_CPU_OBSFN_B0_MBP6_N")
	)
	(segment
		(start 412.7246 -143.6116)
		(end 412.104586 -143.6116)
		(width 0.089408)
		(layer "In4.Cu")
		(net "XDP_CPU_OBSFN_B0_MBP6_N")
	)
	(segment
		(start 417.565586 -141.73962)
		(end 416.744912 -142.560294)
		(width 0.089408)
		(layer "In4.Cu")
		(net "XDP_CPU_OBSFN_B0_MBP6_N")
	)
	(segment
		(start 356.951026 -134.812786)
		(end 349.90278 -134.812786)
		(width 0.089408)
		(layer "In4.Cu")
		(net "XDP_CPU_OBSFN_B0_MBP6_N")
	)
	(segment
		(start 351.126044 -90.895424)
		(end 351.818194 -90.203274)
		(width 0.089408)
		(layer "In4.Cu")
		(net "XDP_CPU_OBSFN_B0_MBP6_N")
	)
	(segment
		(start 411.710632 -144.005554)
		(end 411.710632 -144.698974)
		(width 0.089408)
		(layer "In4.Cu")
		(net "XDP_CPU_OBSFN_B0_MBP6_N")
	)
	(segment
		(start 344.108278 -127.08001)
		(end 344.108278 -121.730516)
		(width 0.089408)
		(layer "In4.Cu")
		(net "XDP_CPU_OBSFN_B0_MBP6_N")
	)
	(segment
		(start 407.026618 -146.416776)
		(end 406.971754 -146.47164)
		(width 0.089408)
		(layer "In4.Cu")
		(net "XDP_CPU_OBSFN_B0_MBP6_N")
	)
	(segment
		(start 344.72626 -117.056408)
		(end 344.22461 -116.554758)
		(width 0.089408)
		(layer "In4.Cu")
		(net "XDP_CPU_OBSFN_B0_MBP6_N")
	)
	(segment
		(start 442.88202 -140.023596)
		(end 442.307472 -140.023596)
		(width 0.089408)
		(layer "In4.Cu")
		(net "XDP_CPU_OBSFN_B0_MBP6_N")
	)
	(segment
		(start 354.331778 -90.203274)
		(end 355.7016 -88.833452)
		(width 0.089408)
		(layer "In4.Cu")
		(net "XDP_CPU_OBSFN_B0_MBP6_N")
	)
	(segment
		(start 409.99283 -146.416776)
		(end 407.026618 -146.416776)
		(width 0.089408)
		(layer "In4.Cu")
		(net "XDP_CPU_OBSFN_B0_MBP6_N")
	)
	(segment
		(start 406.971754 -146.47164)
		(end 405.378158 -146.47164)
		(width 0.089408)
		(layer "In4.Cu")
		(net "XDP_CPU_OBSFN_B0_MBP6_N")
	)
	(segment
		(start 440.621928 -140.359892)
		(end 440.563508 -140.301472)
		(width 0.089408)
		(layer "In4.Cu")
		(net "XDP_CPU_OBSFN_B0_MBP6_N")
	)
	(segment
		(start 447.55562 -141.351)
		(end 444.31204 -141.351)
		(width 0.089408)
		(layer "In4.Cu")
		(net "XDP_CPU_OBSFN_B0_MBP6_N")
	)
	(segment
		(start 443.262512 -140.301472)
		(end 443.229492 -140.301472)
		(width 0.089408)
		(layer "In4.Cu")
		(net "XDP_CPU_OBSFN_B0_MBP6_N")
	)
	(segment
		(start 343.325704 -115.051078)
		(end 343.325704 -110.958884)
		(width 0.089408)
		(layer "In4.Cu")
		(net "XDP_CPU_OBSFN_B0_MBP6_N")
	)
	(segment
		(start 345.331288 -128.30302)
		(end 344.108278 -127.08001)
		(width 0.089408)
		(layer "In4.Cu")
		(net "XDP_CPU_OBSFN_B0_MBP6_N")
	)
	(segment
		(start 362.689394 -140.551154)
		(end 356.951026 -134.812786)
		(width 0.089408)
		(layer "In4.Cu")
		(net "XDP_CPU_OBSFN_B0_MBP6_N")
	)
	(segment
		(start 349.90278 -134.812786)
		(end 349.461074 -134.37108)
		(width 0.089408)
		(layer "In4.Cu")
		(net "XDP_CPU_OBSFN_B0_MBP6_N")
	)
	(segment
		(start 370.678456 -141.239748)
		(end 365.576866 -141.239748)
		(width 0.089408)
		(layer "In4.Cu")
		(net "XDP_CPU_OBSFN_B0_MBP6_N")
	)
	(segment
		(start 164.447474 -25.019)
		(end 158.627826 -30.838648)
		(width 0.089408)
		(layer "In9.Cu")
		(net "XDP_CPU_OBSFN_B0_MBP6_N")
	)
	(segment
		(start 129.721864 -59.770264)
		(end 129.779014 -59.770264)
		(width 0.0889)
		(layer "In9.Cu")
		(net "XDP_CPU_OBSFN_B0_MBP6_N")
	)
	(segment
		(start 133.776974 -62.935358)
		(end 133.378194 -63.334138)
		(width 0.089408)
		(layer "In9.Cu")
		(net "XDP_CPU_OBSFN_B0_MBP6_N")
	)
	(segment
		(start 305.652932 -60.625482)
		(end 305.354482 -60.923932)
		(width 0.089408)
		(layer "In9.Cu")
		(net "XDP_CPU_OBSFN_B0_MBP6_N")
	)
	(segment
		(start 303.336198 -61.8998)
		(end 302.49368 -62.742318)
		(width 0.089408)
		(layer "In9.Cu")
		(net "XDP_CPU_OBSFN_B0_MBP6_N")
	)
	(segment
		(start 131.826762 -59.770264)
		(end 132.129022 -59.468004)
		(width 0.089408)
		(layer "In9.Cu")
		(net "XDP_CPU_OBSFN_B0_MBP6_N")
	)
	(segment
		(start 189.747906 -24.207216)
		(end 188.352938 -24.207216)
		(width 0.089408)
		(layer "In9.Cu")
		(net "XDP_CPU_OBSFN_B0_MBP6_N")
	)
	(segment
		(start 262.75919 -26.129996)
		(end 261.452614 -24.82342)
		(width 0.089408)
		(layer "In9.Cu")
		(net "XDP_CPU_OBSFN_B0_MBP6_N")
	)
	(segment
		(start 188.352938 -24.207216)
		(end 187.367418 -23.221696)
		(width 0.089408)
		(layer "In9.Cu")
		(net "XDP_CPU_OBSFN_B0_MBP6_N")
	)
	(segment
		(start 192.428876 -21.526246)
		(end 189.747906 -24.207216)
		(width 0.089408)
		(layer "In9.Cu")
		(net "XDP_CPU_OBSFN_B0_MBP6_N")
	)
	(segment
		(start 304.928016 -60.923932)
		(end 304.406808 -61.44514)
		(width 0.089408)
		(layer "In9.Cu")
		(net "XDP_CPU_OBSFN_B0_MBP6_N")
	)
	(segment
		(start 124.282962 -40.321738)
		(end 124.282962 -58.237628)
		(width 0.089408)
		(layer "In9.Cu")
		(net "XDP_CPU_OBSFN_B0_MBP6_N")
	)
	(segment
		(start 302.49368 -62.742318)
		(end 301.639224 -62.742318)
		(width 0.089408)
		(layer "In9.Cu")
		(net "XDP_CPU_OBSFN_B0_MBP6_N")
	)
	(segment
		(start 301.639224 -62.742318)
		(end 301.33671 -62.439804)
		(width 0.089408)
		(layer "In9.Cu")
		(net "XDP_CPU_OBSFN_B0_MBP6_N")
	)
	(segment
		(start 127.667004 -59.468004)
		(end 127.96901 -59.77001)
		(width 0.089408)
		(layer "In9.Cu")
		(net "XDP_CPU_OBSFN_B0_MBP6_N")
	)
	(segment
		(start 306.786026 -58.79211)
		(end 306.120038 -59.458098)
		(width 0.0889)
		(layer "In9.Cu")
		(net "XDP_CPU_OBSFN_B0_MBP6_N")
	)
	(segment
		(start 354.122228 -79.999078)
		(end 354.122228 -81.683098)
		(width 0.089408)
		(layer "In9.Cu")
		(net "XDP_CPU_OBSFN_B0_MBP6_N")
	)
	(segment
		(start 259.809488 -20.31873)
		(end 259.228844 -19.738086)
		(width 0.089408)
		(layer "In9.Cu")
		(net "XDP_CPU_OBSFN_B0_MBP6_N")
	)
	(segment
		(start 259.228844 -19.738086)
		(end 259.228844 -18.722848)
		(width 0.089408)
		(layer "In9.Cu")
		(net "XDP_CPU_OBSFN_B0_MBP6_N")
	)
	(segment
		(start 261.452614 -20.94103)
		(end 260.830314 -20.31873)
		(width 0.089408)
		(layer "In9.Cu")
		(net "XDP_CPU_OBSFN_B0_MBP6_N")
	)
	(segment
		(start 310.014874 -56.39562)
		(end 307.291486 -56.39562)
		(width 0.089408)
		(layer "In9.Cu")
		(net "XDP_CPU_OBSFN_B0_MBP6_N")
	)
	(segment
		(start 260.830314 -20.31873)
		(end 259.809488 -20.31873)
		(width 0.089408)
		(layer "In9.Cu")
		(net "XDP_CPU_OBSFN_B0_MBP6_N")
	)
	(segment
		(start 303.620678 -61.8998)
		(end 303.336198 -61.8998)
		(width 0.089408)
		(layer "In9.Cu")
		(net "XDP_CPU_OBSFN_B0_MBP6_N")
	)
	(segment
		(start 356.351332 -64.288924)
		(end 354.861622 -65.778634)
		(width 0.089408)
		(layer "In9.Cu")
		(net "XDP_CPU_OBSFN_B0_MBP6_N")
	)
	(segment
		(start 126.949708 -59.536838)
		(end 127.018542 -59.468004)
		(width 0.089408)
		(layer "In9.Cu")
		(net "XDP_CPU_OBSFN_B0_MBP6_N")
	)
	(segment
		(start 182.624984 -22.812756)
		(end 180.41874 -25.019)
		(width 0.089408)
		(layer "In9.Cu")
		(net "XDP_CPU_OBSFN_B0_MBP6_N")
	)
	(segment
		(start 195.950078 -16.929862)
		(end 195.715636 -17.164304)
		(width 0.089408)
		(layer "In9.Cu")
		(net "XDP_CPU_OBSFN_B0_MBP6_N")
	)
	(segment
		(start 354.861876 -70.217284)
		(end 352.848164 -72.230996)
		(width 0.089408)
		(layer "In9.Cu")
		(net "XDP_CPU_OBSFN_B0_MBP6_N")
	)
	(segment
		(start 256.332736 -15.82674)
		(end 196.461888 -15.82674)
		(width 0.089408)
		(layer "In9.Cu")
		(net "XDP_CPU_OBSFN_B0_MBP6_N")
	)
	(segment
		(start 354.861622 -65.778634)
		(end 354.861622 -66.64579)
		(width 0.089408)
		(layer "In9.Cu")
		(net "XDP_CPU_OBSFN_B0_MBP6_N")
	)
	(segment
		(start 127.018542 -59.468004)
		(end 127.667004 -59.468004)
		(width 0.089408)
		(layer "In9.Cu")
		(net "XDP_CPU_OBSFN_B0_MBP6_N")
	)
	(segment
		(start 195.715636 -17.164304)
		(end 194.919092 -17.164304)
		(width 0.089408)
		(layer "In9.Cu")
		(net "XDP_CPU_OBSFN_B0_MBP6_N")
	)
	(segment
		(start 315.39053 -32.714692)
		(end 307.484272 -24.808434)
		(width 0.089408)
		(layer "In9.Cu")
		(net "XDP_CPU_OBSFN_B0_MBP6_N")
	)
	(segment
		(start 187.367418 -22.485604)
		(end 186.87923 -21.997416)
		(width 0.089408)
		(layer "In9.Cu")
		(net "XDP_CPU_OBSFN_B0_MBP6_N")
	)
	(segment
		(start 130.272282 -59.770264)
		(end 130.574542 -59.468004)
		(width 0.089408)
		(layer "In9.Cu")
		(net "XDP_CPU_OBSFN_B0_MBP6_N")
	)
	(segment
		(start 306.775104 -57.855866)
		(end 307.00218 -57.855866)
		(width 0.0889)
		(layer "In9.Cu")
		(net "XDP_CPU_OBSFN_B0_MBP6_N")
	)
	(segment
		(start 355.7016 -83.26247)
		(end 355.7016 -85.1916)
		(width 0.089408)
		(layer "In9.Cu")
		(net "XDP_CPU_OBSFN_B0_MBP6_N")
	)
	(segment
		(start 275.10486 -28.608528)
		(end 266.468606 -28.608528)
		(width 0.089408)
		(layer "In9.Cu")
		(net "XDP_CPU_OBSFN_B0_MBP6_N")
	)
	(segment
		(start 182.991506 -21.997416)
		(end 182.624984 -22.363938)
		(width 0.089408)
		(layer "In9.Cu")
		(net "XDP_CPU_OBSFN_B0_MBP6_N")
	)
	(segment
		(start 301.33671 -62.439804)
		(end 300.69282 -62.439804)
		(width 0.089408)
		(layer "In9.Cu")
		(net "XDP_CPU_OBSFN_B0_MBP6_N")
	)
	(segment
		(start 306.775612 -56.939688)
		(end 306.617116 -57.190386)
		(width 0.0889)
		(layer "In9.Cu")
		(net "XDP_CPU_OBSFN_B0_MBP6_N")
	)
	(segment
		(start 299.602906 -62.439804)
		(end 299.071792 -62.439804)
		(width 0.089408)
		(layer "In9.Cu")
		(net "XDP_CPU_OBSFN_B0_MBP6_N")
	)
	(segment
		(start 306.61229 -57.5818)
		(end 306.617116 -57.590436)
		(width 0.0889)
		(layer "In9.Cu")
		(net "XDP_CPU_OBSFN_B0_MBP6_N")
	)
	(segment
		(start 305.354482 -60.923932)
		(end 304.928016 -60.923932)
		(width 0.089408)
		(layer "In9.Cu")
		(net "XDP_CPU_OBSFN_B0_MBP6_N")
	)
	(segment
		(start 125.76302 -59.31662)
		(end 126.111 -59.6646)
		(width 0.089408)
		(layer "In9.Cu")
		(net "XDP_CPU_OBSFN_B0_MBP6_N")
	)
	(segment
		(start 129.419604 -59.468004)
		(end 129.721864 -59.770264)
		(width 0.089408)
		(layer "In9.Cu")
		(net "XDP_CPU_OBSFN_B0_MBP6_N")
	)
	(segment
		(start 307.00218 -57.855866)
		(end 307.362352 -58.216038)
		(width 0.0889)
		(layer "In9.Cu")
		(net "XDP_CPU_OBSFN_B0_MBP6_N")
	)
	(segment
		(start 300.69282 -62.439804)
		(end 300.390306 -62.742318)
		(width 0.089408)
		(layer "In9.Cu")
		(net "XDP_CPU_OBSFN_B0_MBP6_N")
	)
	(segment
		(start 307.197506 -56.4896)
		(end 306.775612 -56.939688)
		(width 0.0889)
		(layer "In9.Cu")
		(net "XDP_CPU_OBSFN_B0_MBP6_N")
	)
	(segment
		(start 310.013096 -54.99862)
		(end 309.450232 -54.99862)
		(width 0.089408)
		(layer "In9.Cu")
		(net "XDP_CPU_OBSFN_B0_MBP6_N")
	)
	(segment
		(start 309.193692 -54.74208)
		(end 309.193692 -52.520342)
		(width 0.089408)
		(layer "In9.Cu")
		(net "XDP_CPU_OBSFN_B0_MBP6_N")
	)
	(segment
		(start 127.96901 -59.77001)
		(end 128.52019 -59.77001)
		(width 0.0889)
		(layer "In9.Cu")
		(net "XDP_CPU_OBSFN_B0_MBP6_N")
	)
	(segment
		(start 307.291486 -56.39562)
		(end 307.197506 -56.4896)
		(width 0.089408)
		(layer "In9.Cu")
		(net "XDP_CPU_OBSFN_B0_MBP6_N")
	)
	(segment
		(start 186.87923 -21.997416)
		(end 182.991506 -21.997416)
		(width 0.089408)
		(layer "In9.Cu")
		(net "XDP_CPU_OBSFN_B0_MBP6_N")
	)
	(segment
		(start 354.861876 -66.646044)
		(end 354.861876 -70.217284)
		(width 0.089408)
		(layer "In9.Cu")
		(net "XDP_CPU_OBSFN_B0_MBP6_N")
	)
	(segment
		(start 305.652932 -59.800998)
		(end 305.652932 -60.625482)
		(width 0.0889)
		(layer "In9.Cu")
		(net "XDP_CPU_OBSFN_B0_MBP6_N")
	)
	(segment
		(start 263.50468 -26.129742)
		(end 263.504426 -26.129996)
		(width 0.089408)
		(layer "In9.Cu")
		(net "XDP_CPU_OBSFN_B0_MBP6_N")
	)
	(segment
		(start 133.39699 -59.817)
		(end 133.776974 -60.196984)
		(width 0.089408)
		(layer "In9.Cu")
		(net "XDP_CPU_OBSFN_B0_MBP6_N")
	)
	(segment
		(start 131.347718 -59.770264)
		(end 131.826762 -59.770264)
		(width 0.089408)
		(layer "In9.Cu")
		(net "XDP_CPU_OBSFN_B0_MBP6_N")
	)
	(segment
		(start 356.744016 -62.052708)
		(end 356.351332 -62.445392)
		(width 0.089408)
		(layer "In9.Cu")
		(net "XDP_CPU_OBSFN_B0_MBP6_N")
	)
	(segment
		(start 354.122228 -81.683098)
		(end 355.7016 -83.26247)
		(width 0.089408)
		(layer "In9.Cu")
		(net "XDP_CPU_OBSFN_B0_MBP6_N")
	)
	(segment
		(start 192.428876 -20.343876)
		(end 192.428876 -21.526246)
		(width 0.089408)
		(layer "In9.Cu")
		(net "XDP_CPU_OBSFN_B0_MBP6_N")
	)
	(segment
		(start 130.574542 -59.468004)
		(end 131.045458 -59.468004)
		(width 0.089408)
		(layer "In9.Cu")
		(net "XDP_CPU_OBSFN_B0_MBP6_N")
	)
	(segment
		(start 194.919092 -17.164304)
		(end 193.333116 -18.75028)
		(width 0.089408)
		(layer "In9.Cu")
		(net "XDP_CPU_OBSFN_B0_MBP6_N")
	)
	(segment
		(start 195.950078 -16.33855)
		(end 195.950078 -16.929862)
		(width 0.089408)
		(layer "In9.Cu")
		(net "XDP_CPU_OBSFN_B0_MBP6_N")
	)
	(segment
		(start 193.333116 -19.439636)
		(end 192.428876 -20.343876)
		(width 0.089408)
		(layer "In9.Cu")
		(net "XDP_CPU_OBSFN_B0_MBP6_N")
	)
	(segment
		(start 323.335904 -39.20617)
		(end 319.303146 -35.173412)
		(width 0.089408)
		(layer "In9.Cu")
		(net "XDP_CPU_OBSFN_B0_MBP6_N")
	)
	(segment
		(start 315.39053 -33.651698)
		(end 315.39053 -32.714692)
		(width 0.089408)
		(layer "In9.Cu")
		(net "XDP_CPU_OBSFN_B0_MBP6_N")
	)
	(segment
		(start 128.52019 -59.77001)
		(end 128.822196 -59.468004)
		(width 0.089408)
		(layer "In9.Cu")
		(net "XDP_CPU_OBSFN_B0_MBP6_N")
	)
	(segment
		(start 355.4984 -57.1754)
		(end 356.744016 -58.421016)
		(width 0.089408)
		(layer "In9.Cu")
		(net "XDP_CPU_OBSFN_B0_MBP6_N")
	)
	(segment
		(start 352.848164 -79.196184)
		(end 353.370642 -79.718662)
		(width 0.089408)
		(layer "In9.Cu")
		(net "XDP_CPU_OBSFN_B0_MBP6_N")
	)
	(segment
		(start 300.390306 -62.742318)
		(end 299.90542 -62.742318)
		(width 0.089408)
		(layer "In9.Cu")
		(net "XDP_CPU_OBSFN_B0_MBP6_N")
	)
	(segment
		(start 353.370642 -79.718662)
		(end 353.841812 -79.718662)
		(width 0.089408)
		(layer "In9.Cu")
		(net "XDP_CPU_OBSFN_B0_MBP6_N")
	)
	(segment
		(start 305.666902 -59.787028)
		(end 305.652932 -59.800998)
		(width 0.0889)
		(layer "In9.Cu")
		(net "XDP_CPU_OBSFN_B0_MBP6_N")
	)
	(segment
		(start 352.848164 -72.230996)
		(end 352.848164 -79.196184)
		(width 0.089408)
		(layer "In9.Cu")
		(net "XDP_CPU_OBSFN_B0_MBP6_N")
	)
	(segment
		(start 354.861622 -66.64579)
		(end 354.861876 -66.646044)
		(width 0.089408)
		(layer "In9.Cu")
		(net "XDP_CPU_OBSFN_B0_MBP6_N")
	)
	(segment
		(start 323.335904 -42.190162)
		(end 323.335904 -39.20617)
		(width 0.089408)
		(layer "In9.Cu")
		(net "XDP_CPU_OBSFN_B0_MBP6_N")
	)
	(segment
		(start 129.779014 -59.770264)
		(end 130.272282 -59.770264)
		(width 0.089408)
		(layer "In9.Cu")
		(net "XDP_CPU_OBSFN_B0_MBP6_N")
	)
	(segment
		(start 310.058308 -55.043832)
		(end 310.283098 -55.268622)
		(width 0.089408)
		(layer "In9.Cu")
		(net "XDP_CPU_OBSFN_B0_MBP6_N")
	)
	(segment
		(start 126.716536 -59.77001)
		(end 126.949708 -59.536838)
		(width 0.0889)
		(layer "In9.Cu")
		(net "XDP_CPU_OBSFN_B0_MBP6_N")
	)
	(segment
		(start 158.627826 -30.838648)
		(end 152.955752 -30.838648)
		(width 0.089408)
		(layer "In9.Cu")
		(net "XDP_CPU_OBSFN_B0_MBP6_N")
	)
	(segment
		(start 124.282962 -58.237628)
		(end 125.361954 -59.31662)
		(width 0.089408)
		(layer "In9.Cu")
		(net "XDP_CPU_OBSFN_B0_MBP6_N")
	)
	(segment
		(start 307.484272 -24.808434)
		(end 278.904954 -24.808434)
		(width 0.089408)
		(layer "In9.Cu")
		(net "XDP_CPU_OBSFN_B0_MBP6_N")
	)
	(segment
		(start 261.452614 -24.82342)
		(end 261.452614 -20.94103)
		(width 0.089408)
		(layer "In9.Cu")
		(net "XDP_CPU_OBSFN_B0_MBP6_N")
	)
	(segment
		(start 304.406808 -61.44514)
		(end 304.075338 -61.44514)
		(width 0.089408)
		(layer "In9.Cu")
		(net "XDP_CPU_OBSFN_B0_MBP6_N")
	)
	(segment
		(start 133.096 -59.817)
		(end 133.39699 -59.817)
		(width 0.089408)
		(layer "In9.Cu")
		(net "XDP_CPU_OBSFN_B0_MBP6_N")
	)
	(segment
		(start 132.747004 -59.468004)
		(end 133.096 -59.817)
		(width 0.089408)
		(layer "In9.Cu")
		(net "XDP_CPU_OBSFN_B0_MBP6_N")
	)
	(segment
		(start 180.41874 -25.019)
		(end 164.447474 -25.019)
		(width 0.089408)
		(layer "In9.Cu")
		(net "XDP_CPU_OBSFN_B0_MBP6_N")
	)
	(segment
		(start 132.129022 -59.468004)
		(end 132.747004 -59.468004)
		(width 0.089408)
		(layer "In9.Cu")
		(net "XDP_CPU_OBSFN_B0_MBP6_N")
	)
	(segment
		(start 152.955752 -30.838648)
		(end 148.612606 -35.181794)
		(width 0.089408)
		(layer "In9.Cu")
		(net "XDP_CPU_OBSFN_B0_MBP6_N")
	)
	(segment
		(start 263.504426 -26.129996)
		(end 262.75919 -26.129996)
		(width 0.089408)
		(layer "In9.Cu")
		(net "XDP_CPU_OBSFN_B0_MBP6_N")
	)
	(segment
		(start 187.367418 -23.221696)
		(end 187.367418 -22.485604)
		(width 0.089408)
		(layer "In9.Cu")
		(net "XDP_CPU_OBSFN_B0_MBP6_N")
	)
	(segment
		(start 126.21641 -59.77001)
		(end 126.716536 -59.77001)
		(width 0.0889)
		(layer "In9.Cu")
		(net "XDP_CPU_OBSFN_B0_MBP6_N")
	)
	(segment
		(start 353.841812 -79.718662)
		(end 354.122228 -79.999078)
		(width 0.089408)
		(layer "In9.Cu")
		(net "XDP_CPU_OBSFN_B0_MBP6_N")
	)
	(segment
		(start 310.283098 -56.127396)
		(end 310.014874 -56.39562)
		(width 0.089408)
		(layer "In9.Cu")
		(net "XDP_CPU_OBSFN_B0_MBP6_N")
	)
	(segment
		(start 319.99047 -45.535596)
		(end 323.335904 -42.190162)
		(width 0.089408)
		(layer "In9.Cu")
		(net "XDP_CPU_OBSFN_B0_MBP6_N")
	)
	(segment
		(start 196.461888 -15.82674)
		(end 195.950078 -16.33855)
		(width 0.089408)
		(layer "In9.Cu")
		(net "XDP_CPU_OBSFN_B0_MBP6_N")
	)
	(segment
		(start 126.111 -59.6646)
		(end 126.21641 -59.77001)
		(width 0.0889)
		(layer "In9.Cu")
		(net "XDP_CPU_OBSFN_B0_MBP6_N")
	)
	(segment
		(start 319.303146 -35.173412)
		(end 316.912244 -35.173412)
		(width 0.089408)
		(layer "In9.Cu")
		(net "XDP_CPU_OBSFN_B0_MBP6_N")
	)
	(segment
		(start 278.904954 -24.808434)
		(end 275.10486 -28.608528)
		(width 0.089408)
		(layer "In9.Cu")
		(net "XDP_CPU_OBSFN_B0_MBP6_N")
	)
	(segment
		(start 266.468606 -28.608528)
		(end 263.98982 -26.129742)
		(width 0.089408)
		(layer "In9.Cu")
		(net "XDP_CPU_OBSFN_B0_MBP6_N")
	)
	(segment
		(start 125.361954 -59.31662)
		(end 125.76302 -59.31662)
		(width 0.089408)
		(layer "In9.Cu")
		(net "XDP_CPU_OBSFN_B0_MBP6_N")
	)
	(segment
		(start 356.744016 -58.421016)
		(end 356.744016 -62.052708)
		(width 0.089408)
		(layer "In9.Cu")
		(net "XDP_CPU_OBSFN_B0_MBP6_N")
	)
	(segment
		(start 307.362352 -58.216038)
		(end 307.362352 -58.546238)
		(width 0.0889)
		(layer "In9.Cu")
		(net "XDP_CPU_OBSFN_B0_MBP6_N")
	)
	(segment
		(start 131.045458 -59.468004)
		(end 131.347718 -59.770264)
		(width 0.089408)
		(layer "In9.Cu")
		(net "XDP_CPU_OBSFN_B0_MBP6_N")
	)
	(segment
		(start 316.912244 -35.173412)
		(end 315.39053 -33.651698)
		(width 0.089408)
		(layer "In9.Cu")
		(net "XDP_CPU_OBSFN_B0_MBP6_N")
	)
	(segment
		(start 299.90542 -62.742318)
		(end 299.602906 -62.439804)
		(width 0.089408)
		(layer "In9.Cu")
		(net "XDP_CPU_OBSFN_B0_MBP6_N")
	)
	(segment
		(start 304.075338 -61.44514)
		(end 303.620678 -61.8998)
		(width 0.089408)
		(layer "In9.Cu")
		(net "XDP_CPU_OBSFN_B0_MBP6_N")
	)
	(segment
		(start 128.822196 -59.468004)
		(end 129.419604 -59.468004)
		(width 0.089408)
		(layer "In9.Cu")
		(net "XDP_CPU_OBSFN_B0_MBP6_N")
	)
	(segment
		(start 259.228844 -18.722848)
		(end 256.332736 -15.82674)
		(width 0.089408)
		(layer "In9.Cu")
		(net "XDP_CPU_OBSFN_B0_MBP6_N")
	)
	(segment
		(start 307.11648 -58.79211)
		(end 306.786026 -58.79211)
		(width 0.0889)
		(layer "In9.Cu")
		(net "XDP_CPU_OBSFN_B0_MBP6_N")
	)
	(segment
		(start 356.351332 -62.445392)
		(end 356.351332 -64.288924)
		(width 0.089408)
		(layer "In9.Cu")
		(net "XDP_CPU_OBSFN_B0_MBP6_N")
	)
	(segment
		(start 306.617116 -57.590436)
		(end 306.775104 -57.855866)
		(width 0.0889)
		(layer "In9.Cu")
		(net "XDP_CPU_OBSFN_B0_MBP6_N")
	)
	(segment
		(start 263.98982 -26.129742)
		(end 263.50468 -26.129742)
		(width 0.089408)
		(layer "In9.Cu")
		(net "XDP_CPU_OBSFN_B0_MBP6_N")
	)
	(segment
		(start 310.058308 -55.043832)
		(end 310.013096 -54.99862)
		(width 0.089408)
		(layer "In9.Cu")
		(net "XDP_CPU_OBSFN_B0_MBP6_N")
	)
	(segment
		(start 316.178438 -45.535596)
		(end 319.99047 -45.535596)
		(width 0.089408)
		(layer "In9.Cu")
		(net "XDP_CPU_OBSFN_B0_MBP6_N")
	)
	(segment
		(start 307.362352 -58.546238)
		(end 307.11648 -58.79211)
		(width 0.0889)
		(layer "In9.Cu")
		(net "XDP_CPU_OBSFN_B0_MBP6_N")
	)
	(segment
		(start 309.193692 -52.520342)
		(end 316.178438 -45.535596)
		(width 0.089408)
		(layer "In9.Cu")
		(net "XDP_CPU_OBSFN_B0_MBP6_N")
	)
	(segment
		(start 355.4984 -56.7944)
		(end 355.4984 -57.1754)
		(width 0.089408)
		(layer "In9.Cu")
		(net "XDP_CPU_OBSFN_B0_MBP6_N")
	)
	(segment
		(start 299.071792 -62.439804)
		(end 298.378626 -63.13297)
		(width 0.089408)
		(layer "In9.Cu")
		(net "XDP_CPU_OBSFN_B0_MBP6_N")
	)
	(segment
		(start 133.776974 -60.196984)
		(end 133.776974 -62.935358)
		(width 0.089408)
		(layer "In9.Cu")
		(net "XDP_CPU_OBSFN_B0_MBP6_N")
	)
	(segment
		(start 310.283098 -55.268622)
		(end 310.283098 -56.127396)
		(width 0.089408)
		(layer "In9.Cu")
		(net "XDP_CPU_OBSFN_B0_MBP6_N")
	)
	(segment
		(start 309.450232 -54.99862)
		(end 309.193692 -54.74208)
		(width 0.089408)
		(layer "In9.Cu")
		(net "XDP_CPU_OBSFN_B0_MBP6_N")
	)
	(segment
		(start 148.612606 -35.181794)
		(end 129.422906 -35.181794)
		(width 0.089408)
		(layer "In9.Cu")
		(net "XDP_CPU_OBSFN_B0_MBP6_N")
	)
	(segment
		(start 298.378626 -63.13297)
		(end 298.378626 -63.334138)
		(width 0.089408)
		(layer "In9.Cu")
		(net "XDP_CPU_OBSFN_B0_MBP6_N")
	)
	(segment
		(start 193.333116 -18.75028)
		(end 193.333116 -19.439636)
		(width 0.089408)
		(layer "In9.Cu")
		(net "XDP_CPU_OBSFN_B0_MBP6_N")
	)
	(segment
		(start 182.624984 -22.363938)
		(end 182.624984 -22.812756)
		(width 0.089408)
		(layer "In9.Cu")
		(net "XDP_CPU_OBSFN_B0_MBP6_N")
	)
	(segment
		(start 129.422906 -35.181794)
		(end 124.282962 -40.321738)
		(width 0.089408)
		(layer "In9.Cu")
		(net "XDP_CPU_OBSFN_B0_MBP6_N")
	)
	(arc
		(start 306.120038 -59.458098)
		(mid 305.911355 -59.514061)
		(end 305.758596 -59.666886)
		(width 0.0889)
		(layer "In9.Cu")
		(net "XDP_CPU_OBSFN_B0_MBP6_N")
	)
	(arc
		(start 306.617116 -57.190386)
		(mid 306.563646 -57.385449)
		(end 306.61229 -57.5818)
		(width 0.0889)
		(layer "In9.Cu")
		(net "XDP_CPU_OBSFN_B0_MBP6_N")
	)
	(arc
		(start 305.758596 -59.666886)
		(mid 305.716618 -59.729911)
		(end 305.666902 -59.787028)
		(width 0.0889)
		(layer "In9.Cu")
		(net "XDP_CPU_OBSFN_B0_MBP6_N")
	)
	(segment
		(start 318.913764 -60.466732)
		(end 318.428624 -60.466732)
		(width 0.089408)
		(layer "In11.Cu")
		(net "XDP_CPU_OBSFN_B0_MBP6_N")
	)
	(segment
		(start 141.7574 -64.7954)
		(end 142.113 -64.7954)
		(width 0.0889)
		(layer "In11.Cu")
		(net "XDP_CPU_OBSFN_B0_MBP6_N")
	)
	(segment
		(start 318.95923 -60.421266)
		(end 318.913764 -60.466732)
		(width 0.089408)
		(layer "In11.Cu")
		(net "XDP_CPU_OBSFN_B0_MBP6_N")
	)
	(segment
		(start 140.683234 -65.233804)
		(end 141.318996 -65.233804)
		(width 0.0889)
		(layer "In11.Cu")
		(net "XDP_CPU_OBSFN_B0_MBP6_N")
	)
	(segment
		(start 149.035008 -58.482992)
		(end 149.035008 -55.783988)
		(width 0.089408)
		(layer "In11.Cu")
		(net "XDP_CPU_OBSFN_B0_MBP6_N")
	)
	(segment
		(start 145.5166 -63.0174)
		(end 148.660104 -59.873896)
		(width 0.089408)
		(layer "In11.Cu")
		(net "XDP_CPU_OBSFN_B0_MBP6_N")
	)
	(segment
		(start 355.4984 -56.7944)
		(end 355.183186 -56.479186)
		(width 0.089408)
		(layer "In11.Cu")
		(net "XDP_CPU_OBSFN_B0_MBP6_N")
	)
	(segment
		(start 135.080248 -61.943488)
		(end 135.11022 -61.943488)
		(width 0.0889)
		(layer "In11.Cu")
		(net "XDP_CPU_OBSFN_B0_MBP6_N")
	)
	(segment
		(start 180.336444 -30.191456)
		(end 180.336444 -22.71522)
		(width 0.089408)
		(layer "In11.Cu")
		(net "XDP_CPU_OBSFN_B0_MBP6_N")
	)
	(segment
		(start 143.0782 -64.2874)
		(end 144.3482 -63.0174)
		(width 0.0889)
		(layer "In11.Cu")
		(net "XDP_CPU_OBSFN_B0_MBP6_N")
	)
	(segment
		(start 134.225538 -62.438534)
		(end 134.258304 -62.438534)
		(width 0.0889)
		(layer "In11.Cu")
		(net "XDP_CPU_OBSFN_B0_MBP6_N")
	)
	(segment
		(start 141.318996 -65.233804)
		(end 141.7574 -64.7954)
		(width 0.0889)
		(layer "In11.Cu")
		(net "XDP_CPU_OBSFN_B0_MBP6_N")
	)
	(segment
		(start 180.336444 -22.71522)
		(end 181.1782 -21.873464)
		(width 0.089408)
		(layer "In11.Cu")
		(net "XDP_CPU_OBSFN_B0_MBP6_N")
	)
	(segment
		(start 326.230742 -56.462676)
		(end 325.899018 -56.462676)
		(width 0.089408)
		(layer "In11.Cu")
		(net "XDP_CPU_OBSFN_B0_MBP6_N")
	)
	(segment
		(start 148.558504 -55.307484)
		(end 148.558504 -51.923696)
		(width 0.089408)
		(layer "In11.Cu")
		(net "XDP_CPU_OBSFN_B0_MBP6_N")
	)
	(segment
		(start 322.902072 -56.479186)
		(end 318.959992 -60.421266)
		(width 0.089408)
		(layer "In11.Cu")
		(net "XDP_CPU_OBSFN_B0_MBP6_N")
	)
	(segment
		(start 170.0657 -40.4622)
		(end 180.336444 -30.191456)
		(width 0.089408)
		(layer "In11.Cu")
		(net "XDP_CPU_OBSFN_B0_MBP6_N")
	)
	(segment
		(start 144.3482 -63.0174)
		(end 145.5166 -63.0174)
		(width 0.089408)
		(layer "In11.Cu")
		(net "XDP_CPU_OBSFN_B0_MBP6_N")
	)
	(segment
		(start 315.480954 -60.466478)
		(end 310.058308 -55.043832)
		(width 0.089408)
		(layer "In11.Cu")
		(net "XDP_CPU_OBSFN_B0_MBP6_N")
	)
	(segment
		(start 149.035008 -55.783988)
		(end 148.558504 -55.307484)
		(width 0.089408)
		(layer "In11.Cu")
		(net "XDP_CPU_OBSFN_B0_MBP6_N")
	)
	(segment
		(start 148.660104 -58.857896)
		(end 149.035008 -58.482992)
		(width 0.089408)
		(layer "In11.Cu")
		(net "XDP_CPU_OBSFN_B0_MBP6_N")
	)
	(segment
		(start 148.558504 -51.923696)
		(end 160.02 -40.4622)
		(width 0.089408)
		(layer "In11.Cu")
		(net "XDP_CPU_OBSFN_B0_MBP6_N")
	)
	(segment
		(start 181.1782 -21.873464)
		(end 181.1782 -21.844)
		(width 0.089408)
		(layer "In11.Cu")
		(net "XDP_CPU_OBSFN_B0_MBP6_N")
	)
	(segment
		(start 318.42837 -60.466478)
		(end 315.480954 -60.466478)
		(width 0.089408)
		(layer "In11.Cu")
		(net "XDP_CPU_OBSFN_B0_MBP6_N")
	)
	(segment
		(start 140.228574 -64.915288)
		(end 140.26134 -64.915288)
		(width 0.0889)
		(layer "In11.Cu")
		(net "XDP_CPU_OBSFN_B0_MBP6_N")
	)
	(segment
		(start 160.02 -40.4622)
		(end 170.0657 -40.4622)
		(width 0.089408)
		(layer "In11.Cu")
		(net "XDP_CPU_OBSFN_B0_MBP6_N")
	)
	(segment
		(start 137.649204 -63.429134)
		(end 137.68197 -63.429134)
		(width 0.0889)
		(layer "In11.Cu")
		(net "XDP_CPU_OBSFN_B0_MBP6_N")
	)
	(segment
		(start 139.366244 -64.419734)
		(end 139.39901 -64.419734)
		(width 0.0889)
		(layer "In11.Cu")
		(net "XDP_CPU_OBSFN_B0_MBP6_N")
	)
	(segment
		(start 138.511534 -63.924688)
		(end 138.5443 -63.924688)
		(width 0.0889)
		(layer "In11.Cu")
		(net "XDP_CPU_OBSFN_B0_MBP6_N")
	)
	(segment
		(start 318.959992 -60.421266)
		(end 318.95923 -60.421266)
		(width 0.089408)
		(layer "In11.Cu")
		(net "XDP_CPU_OBSFN_B0_MBP6_N")
	)
	(segment
		(start 142.113 -64.7954)
		(end 142.621 -64.2874)
		(width 0.0889)
		(layer "In11.Cu")
		(net "XDP_CPU_OBSFN_B0_MBP6_N")
	)
	(segment
		(start 355.183186 -56.479186)
		(end 326.247252 -56.479186)
		(width 0.089408)
		(layer "In11.Cu")
		(net "XDP_CPU_OBSFN_B0_MBP6_N")
	)
	(segment
		(start 325.882508 -56.479186)
		(end 322.902072 -56.479186)
		(width 0.089408)
		(layer "In11.Cu")
		(net "XDP_CPU_OBSFN_B0_MBP6_N")
	)
	(segment
		(start 326.247252 -56.479186)
		(end 326.230742 -56.462676)
		(width 0.089408)
		(layer "In11.Cu")
		(net "XDP_CPU_OBSFN_B0_MBP6_N")
	)
	(segment
		(start 325.899018 -56.462676)
		(end 325.882508 -56.479186)
		(width 0.089408)
		(layer "In11.Cu")
		(net "XDP_CPU_OBSFN_B0_MBP6_N")
	)
	(segment
		(start 142.621 -64.2874)
		(end 143.0782 -64.2874)
		(width 0.0889)
		(layer "In11.Cu")
		(net "XDP_CPU_OBSFN_B0_MBP6_N")
	)
	(segment
		(start 136.794494 -62.934088)
		(end 136.82726 -62.934088)
		(width 0.0889)
		(layer "In11.Cu")
		(net "XDP_CPU_OBSFN_B0_MBP6_N")
	)
	(segment
		(start 148.660104 -59.873896)
		(end 148.660104 -58.857896)
		(width 0.089408)
		(layer "In11.Cu")
		(net "XDP_CPU_OBSFN_B0_MBP6_N")
	)
	(segment
		(start 135.932164 -62.438534)
		(end 135.96493 -62.438534)
		(width 0.0889)
		(layer "In11.Cu")
		(net "XDP_CPU_OBSFN_B0_MBP6_N")
	)
	(segment
		(start 318.428624 -60.466732)
		(end 318.42837 -60.466478)
		(width 0.089408)
		(layer "In11.Cu")
		(net "XDP_CPU_OBSFN_B0_MBP6_N")
	)
	(arc
		(start 139.39901 -64.419734)
		(mid 139.59286 -64.476084)
		(end 139.734544 -64.619886)
		(width 0.0889)
		(layer "In11.Cu")
		(net "XDP_CPU_OBSFN_B0_MBP6_N")
	)
	(arc
		(start 138.017504 -63.629286)
		(mid 138.226112 -63.841218)
		(end 138.511534 -63.924688)
		(width 0.0889)
		(layer "In11.Cu")
		(net "XDP_CPU_OBSFN_B0_MBP6_N")
	)
	(arc
		(start 137.68197 -63.429134)
		(mid 137.87582 -63.485484)
		(end 138.017504 -63.629286)
		(width 0.0889)
		(layer "In11.Cu")
		(net "XDP_CPU_OBSFN_B0_MBP6_N")
	)
	(arc
		(start 134.258304 -62.438534)
		(mid 134.541521 -62.354253)
		(end 134.748524 -62.143386)
		(width 0.0889)
		(layer "In11.Cu")
		(net "XDP_CPU_OBSFN_B0_MBP6_N")
	)
	(arc
		(start 138.876024 -64.124586)
		(mid 139.083028 -64.33545)
		(end 139.366244 -64.419734)
		(width 0.0889)
		(layer "In11.Cu")
		(net "XDP_CPU_OBSFN_B0_MBP6_N")
	)
	(arc
		(start 135.96493 -62.438534)
		(mid 136.15878 -62.494884)
		(end 136.300464 -62.638686)
		(width 0.0889)
		(layer "In11.Cu")
		(net "XDP_CPU_OBSFN_B0_MBP6_N")
	)
	(arc
		(start 140.593064 -65.115186)
		(mid 140.634389 -65.177354)
		(end 140.683234 -65.233804)
		(width 0.0889)
		(layer "In11.Cu")
		(net "XDP_CPU_OBSFN_B0_MBP6_N")
	)
	(arc
		(start 136.82726 -62.934088)
		(mid 137.018902 -62.991254)
		(end 137.158984 -63.133986)
		(width 0.0889)
		(layer "In11.Cu")
		(net "XDP_CPU_OBSFN_B0_MBP6_N")
	)
	(arc
		(start 140.26134 -64.915288)
		(mid 140.452982 -64.972454)
		(end 140.593064 -65.115186)
		(width 0.0889)
		(layer "In11.Cu")
		(net "XDP_CPU_OBSFN_B0_MBP6_N")
	)
	(arc
		(start 139.734544 -64.619886)
		(mid 139.943152 -64.831818)
		(end 140.228574 -64.915288)
		(width 0.0889)
		(layer "In11.Cu")
		(net "XDP_CPU_OBSFN_B0_MBP6_N")
	)
	(arc
		(start 135.441944 -62.143386)
		(mid 135.648948 -62.35425)
		(end 135.932164 -62.438534)
		(width 0.0889)
		(layer "In11.Cu")
		(net "XDP_CPU_OBSFN_B0_MBP6_N")
	)
	(arc
		(start 136.300464 -62.638686)
		(mid 136.509072 -62.850618)
		(end 136.794494 -62.934088)
		(width 0.0889)
		(layer "In11.Cu")
		(net "XDP_CPU_OBSFN_B0_MBP6_N")
	)
	(arc
		(start 134.748524 -62.143386)
		(mid 134.888603 -62.00065)
		(end 135.080248 -61.943488)
		(width 0.0889)
		(layer "In11.Cu")
		(net "XDP_CPU_OBSFN_B0_MBP6_N")
	)
	(arc
		(start 133.378194 -63.334138)
		(mid 133.653478 -63.000675)
		(end 133.890004 -62.638686)
		(width 0.0889)
		(layer "In11.Cu")
		(net "XDP_CPU_OBSFN_B0_MBP6_N")
	)
	(arc
		(start 137.158984 -63.133986)
		(mid 137.365988 -63.34485)
		(end 137.649204 -63.429134)
		(width 0.0889)
		(layer "In11.Cu")
		(net "XDP_CPU_OBSFN_B0_MBP6_N")
	)
	(arc
		(start 133.890004 -62.638686)
		(mid 134.031687 -62.494882)
		(end 134.225538 -62.438534)
		(width 0.0889)
		(layer "In11.Cu")
		(net "XDP_CPU_OBSFN_B0_MBP6_N")
	)
	(arc
		(start 138.5443 -63.924688)
		(mid 138.735942 -63.981854)
		(end 138.876024 -64.124586)
		(width 0.0889)
		(layer "In11.Cu")
		(net "XDP_CPU_OBSFN_B0_MBP6_N")
	)
	(arc
		(start 135.11022 -61.943488)
		(mid 135.301862 -62.000654)
		(end 135.441944 -62.143386)
		(width 0.0889)
		(layer "In11.Cu")
		(net "XDP_CPU_OBSFN_B0_MBP6_N")
	)
	(segment
		(start 464.686396 -142.068804)
		(end 464.535266 -142.219934)
		(width 0.10795)
		(layer "F.Cu")
		(net "TP_XDP_OBSDATA_B0")
	)
	(segment
		(start 464.696302 -142.068804)
		(end 464.686396 -142.068804)
		(width 0.10795)
		(layer "F.Cu")
		(net "TP_XDP_OBSDATA_B0")
	)
	(segment
		(start 467.53526 -141.52626)
		(end 467.311486 -141.750034)
		(width 0.10795)
		(layer "F.Cu")
		(net "TP_XDP_OBSDATA_B0")
	)
	(segment
		(start 467.311486 -141.750034)
		(end 465.015072 -141.750034)
		(width 0.10795)
		(layer "F.Cu")
		(net "TP_XDP_OBSDATA_B0")
	)
	(segment
		(start 465.015072 -141.750034)
		(end 464.696302 -142.068804)
		(width 0.10795)
		(layer "F.Cu")
		(net "TP_XDP_OBSDATA_B0")
	)
	(segment
		(start 464.535266 -142.219934)
		(end 462.980532 -142.219934)
		(width 0.10795)
		(layer "F.Cu")
		(net "TP_XDP_OBSDATA_B0")
	)
	(via
		(at 466.0138 -141.351)
		(size 0.6604)
		(drill 0.3302)
		(layers "F.Cu" "B.Cu")
		(net "TP_XDP_OBSDATA_B0")
	)
	(via
		(at 467.53526 -141.52626)
		(size 0.508)
		(drill 0.254)
		(layers "F.Cu" "B.Cu")
		(net "TP_XDP_OBSDATA_B0")
	)
	(segment
		(start 467.53526 -141.52626)
		(end 466.18906 -141.52626)
		(width 0.10795)
		(layer "B.Cu")
		(net "TP_XDP_OBSDATA_B0")
	)
	(segment
		(start 466.18906 -141.52626)
		(end 466.0138 -141.351)
		(width 0.10795)
		(layer "B.Cu")
		(net "TP_XDP_OBSDATA_B0")
	)
	(segment
		(start 298.665646 -60.857384)
		(end 299.237146 -60.857384)
		(width 0.10795)
		(layer "F.Cu")
		(net "TP_XDP_CPU0_OBSDATA_A3_MBP5_N")
	)
	(via
		(at 299.237146 -60.857384)
		(size 0.508)
		(drill 0.254)
		(layers "F.Cu" "B.Cu")
		(net "TP_XDP_CPU0_OBSDATA_A3_MBP5_N")
	)
	(segment
		(start 297.807126 -61.352938)
		(end 298.378626 -61.352938)
		(width 0.10795)
		(layer "F.Cu")
		(net "TP_XDP_CPU0_OBSDATA_A2_MBP4_N")
	)
	(via
		(at 298.378626 -61.352938)
		(size 0.508)
		(drill 0.254)
		(layers "F.Cu" "B.Cu")
		(net "TP_XDP_CPU0_OBSDATA_A2_MBP4_N")
	)
	(segment
		(start 459.178406 -142.719806)
		(end 457.252578 -142.719806)
		(width 0.10795)
		(layer "F.Cu")
		(net "TP_XDP_CPU_OBSDATA_D1")
	)
	(segment
		(start 460.49819 -146.94154)
		(end 460.49819 -144.03959)
		(width 0.10795)
		(layer "F.Cu")
		(net "TP_XDP_CPU_OBSDATA_D1")
	)
	(segment
		(start 460.451708 -146.988022)
		(end 460.49819 -146.94154)
		(width 0.10795)
		(layer "F.Cu")
		(net "TP_XDP_CPU_OBSDATA_D1")
	)
	(segment
		(start 460.49819 -144.03959)
		(end 459.178406 -142.719806)
		(width 0.10795)
		(layer "F.Cu")
		(net "TP_XDP_CPU_OBSDATA_D1")
	)
	(via
		(at 460.451708 -146.988022)
		(size 0.508)
		(drill 0.254)
		(layers "F.Cu" "B.Cu")
		(net "TP_XDP_CPU_OBSDATA_D1")
	)
	(segment
		(start 460.86014 -143.965168)
		(end 459.114906 -142.219934)
		(width 0.10795)
		(layer "F.Cu")
		(net "TP_XDP_CPU_OBSDATA_D0")
	)
	(segment
		(start 459.114906 -142.219934)
		(end 457.252578 -142.219934)
		(width 0.10795)
		(layer "F.Cu")
		(net "TP_XDP_CPU_OBSDATA_D0")
	)
	(segment
		(start 461.26908 -145.147792)
		(end 460.86014 -144.738852)
		(width 0.10795)
		(layer "F.Cu")
		(net "TP_XDP_CPU_OBSDATA_D0")
	)
	(segment
		(start 460.86014 -144.738852)
		(end 460.86014 -143.965168)
		(width 0.10795)
		(layer "F.Cu")
		(net "TP_XDP_CPU_OBSDATA_D0")
	)
	(via
		(at 461.26908 -145.147792)
		(size 0.508)
		(drill 0.254)
		(layers "F.Cu" "B.Cu")
		(net "TP_XDP_CPU_OBSDATA_D0")
	)
	(segment
		(start 380.80315 -98.69424)
		(end 381.29845 -98.464116)
		(width 0.10795)
		(layer "F.Cu")
		(net "TP_CPU_PCH_TRIGGER_OUT")
	)
	(via
		(at 381.29845 -98.464116)
		(size 0.508)
		(drill 0.254)
		(layers "F.Cu" "B.Cu")
		(net "TP_CPU_PCH_TRIGGER_OUT")
	)
	(segment
		(start 382.1684 -100.23729)
		(end 382.28905 -100.181156)
		(width 0.10795)
		(layer "F.Cu")
		(net "TP_PLTRST_CPU_N")
	)
	(segment
		(start 381.79375 -100.41128)
		(end 382.1684 -100.23729)
		(width 0.10795)
		(layer "F.Cu")
		(net "TP_PLTRST_CPU_N")
	)
	(via
		(at 382.28905 -100.181156)
		(size 0.508)
		(drill 0.254)
		(layers "F.Cu" "B.Cu")
		(net "TP_PLTRST_CPU_N")
	)
	(segment
		(start 380.30785 -108.13796)
		(end 380.319026 -108.132626)
		(width 0.10795)
		(layer "F.Cu")
		(net "TP_PCH_RSVD29")
	)
	(segment
		(start 380.319026 -108.132626)
		(end 380.438914 -108.077)
		(width 0.10795)
		(layer "F.Cu")
		(net "TP_PCH_RSVD29")
	)
	(segment
		(start 380.438914 -108.077)
		(end 380.80315 -107.907836)
		(width 0.10795)
		(layer "F.Cu")
		(net "TP_PCH_RSVD29")
	)
	(via
		(at 380.80315 -107.907836)
		(size 0.508)
		(drill 0.254)
		(layers "F.Cu" "B.Cu")
		(net "TP_PCH_RSVD29")
	)
	(segment
		(start 380.279148 -106.407712)
		(end 379.81255 -106.190796)
		(width 0.10795)
		(layer "F.Cu")
		(net "TP_PCH_RSVD31")
	)
	(segment
		(start 380.30785 -106.42092)
		(end 380.279148 -106.407712)
		(width 0.10795)
		(layer "F.Cu")
		(net "TP_PCH_RSVD31")
	)
	(via
		(at 379.81255 -106.190796)
		(size 0.508)
		(drill 0.254)
		(layers "F.Cu" "B.Cu")
		(net "TP_PCH_RSVD31")
	)
	(segment
		(start 381.062484 -108.876084)
		(end 381.141986 -108.839)
		(width 0.10795)
		(layer "F.Cu")
		(net "TP_PCH_RSVD28")
	)
	(segment
		(start 380.80315 -108.99648)
		(end 380.975616 -108.916216)
		(width 0.10795)
		(layer "F.Cu")
		(net "TP_PCH_RSVD28")
	)
	(segment
		(start 380.975616 -108.916216)
		(end 381.062484 -108.876084)
		(width 0.10795)
		(layer "F.Cu")
		(net "TP_PCH_RSVD28")
	)
	(segment
		(start 381.141986 -108.839)
		(end 381.29845 -108.766356)
		(width 0.10795)
		(layer "F.Cu")
		(net "TP_PCH_RSVD28")
	)
	(via
		(at 381.29845 -108.766356)
		(size 0.508)
		(drill 0.254)
		(layers "F.Cu" "B.Cu")
		(net "TP_PCH_RSVD28")
	)
	(segment
		(start 380.80315 -107.27944)
		(end 381.29845 -107.049316)
		(width 0.10795)
		(layer "F.Cu")
		(net "TP_PCH_RSVD30")
	)
	(via
		(at 381.29845 -107.049316)
		(size 0.508)
		(drill 0.254)
		(layers "F.Cu" "B.Cu")
		(net "TP_PCH_RSVD30")
	)
	(segment
		(start 382.9304 -117.649498)
		(end 383.27965 -117.811804)
		(width 0.10795)
		(layer "F.Cu")
		(net "TP_PCH_RSVD35")
	)
	(segment
		(start 382.78435 -117.58168)
		(end 382.9304 -117.649498)
		(width 0.10795)
		(layer "F.Cu")
		(net "TP_PCH_RSVD35")
	)
	(via
		(at 383.27965 -117.811804)
		(size 0.508)
		(drill 0.254)
		(layers "F.Cu" "B.Cu")
		(net "TP_PCH_RSVD35")
	)
	(segment
		(start 382.397 -118.490238)
		(end 382.781048 -118.6688)
		(width 0.10795)
		(layer "F.Cu")
		(net "TP_PCH_RSVD33")
	)
	(segment
		(start 382.28905 -118.4402)
		(end 382.3462 -118.466616)
		(width 0.10795)
		(layer "F.Cu")
		(net "TP_PCH_RSVD33")
	)
	(segment
		(start 382.781048 -118.6688)
		(end 382.78435 -118.670324)
		(width 0.10795)
		(layer "F.Cu")
		(net "TP_PCH_RSVD33")
	)
	(segment
		(start 382.3462 -118.466616)
		(end 382.397 -118.490238)
		(width 0.10795)
		(layer "F.Cu")
		(net "TP_PCH_RSVD33")
	)
	(via
		(at 382.78435 -118.670324)
		(size 0.508)
		(drill 0.254)
		(layers "F.Cu" "B.Cu")
		(net "TP_PCH_RSVD33")
	)
	(segment
		(start 383.771648 -118.6688)
		(end 383.77495 -118.670324)
		(width 0.10795)
		(layer "F.Cu")
		(net "TP_PCH_RSVD34")
	)
	(segment
		(start 383.27965 -118.4402)
		(end 383.771648 -118.6688)
		(width 0.10795)
		(layer "F.Cu")
		(net "TP_PCH_RSVD34")
	)
	(via
		(at 383.77495 -118.670324)
		(size 0.508)
		(drill 0.254)
		(layers "F.Cu" "B.Cu")
		(net "TP_PCH_RSVD34")
	)
	(segment
		(start 383.77495 -117.58168)
		(end 384.27025 -117.811804)
		(width 0.10795)
		(layer "F.Cu")
		(net "TP_PCH_RSVD32")
	)
	(via
		(at 384.27025 -117.811804)
		(size 0.508)
		(drill 0.254)
		(layers "F.Cu" "B.Cu")
		(net "TP_PCH_RSVD32")
	)
	(segment
		(start 22.2758 -0.6604)
		(end 21.9964 -0.381)
		(width 0.10795)
		(layer "F.Cu")
		(net "PWRGD_DSW_PWROK")
	)
	(segment
		(start 453.506078 -16.088614)
		(end 453.730614 -16.088614)
		(width 0.10795)
		(layer "F.Cu")
		(net "PWRGD_DSW_PWROK")
	)
	(segment
		(start 378.82195 -98.69424)
		(end 379.31725 -98.464116)
		(width 0.10795)
		(layer "F.Cu")
		(net "PWRGD_DSW_PWROK")
	)
	(segment
		(start 19.16176 -23.547324)
		(end 19.16176 -23.51024)
		(width 0.10795)
		(layer "F.Cu")
		(net "PWRGD_DSW_PWROK")
	)
	(segment
		(start 447.52768 -13.843)
		(end 448.9196 -13.843)
		(width 0.10795)
		(layer "F.Cu")
		(net "PWRGD_DSW_PWROK")
	)
	(segment
		(start 447.181986 -13.497306)
		(end 447.52768 -13.843)
		(width 0.10795)
		(layer "F.Cu")
		(net "PWRGD_DSW_PWROK")
	)
	(segment
		(start 22.2758 -20.3962)
		(end 22.2758 -0.6604)
		(width 0.10795)
		(layer "F.Cu")
		(net "PWRGD_DSW_PWROK")
	)
	(segment
		(start 21.9964 -0.381)
		(end 21.9964 4.0386)
		(width 0.10795)
		(layer "F.Cu")
		(net "PWRGD_DSW_PWROK")
	)
	(segment
		(start 447.181986 -12.954)
		(end 447.181986 -13.497306)
		(width 0.10795)
		(layer "F.Cu")
		(net "PWRGD_DSW_PWROK")
	)
	(segment
		(start 21.9964 4.0386)
		(end 22.121114 4.163314)
		(width 0.10795)
		(layer "F.Cu")
		(net "PWRGD_DSW_PWROK")
	)
	(segment
		(start 370.756688 -69.095112)
		(end 370.745004 -69.095112)
		(width 0.10795)
		(layer "F.Cu")
		(net "PWRGD_DSW_PWROK")
	)
	(segment
		(start 449.514468 -14.437868)
		(end 451.855332 -14.437868)
		(width 0.10795)
		(layer "F.Cu")
		(net "PWRGD_DSW_PWROK")
	)
	(segment
		(start 19.16176 -23.51024)
		(end 22.2758 -20.3962)
		(width 0.10795)
		(layer "F.Cu")
		(net "PWRGD_DSW_PWROK")
	)
	(segment
		(start 371.1702 -68.6816)
		(end 370.756688 -69.095112)
		(width 0.10795)
		(layer "F.Cu")
		(net "PWRGD_DSW_PWROK")
	)
	(segment
		(start 448.9196 -13.843)
		(end 449.514468 -14.437868)
		(width 0.10795)
		(layer "F.Cu")
		(net "PWRGD_DSW_PWROK")
	)
	(segment
		(start 18.02892 -24.680164)
		(end 19.16176 -23.547324)
		(width 0.10795)
		(layer "F.Cu")
		(net "PWRGD_DSW_PWROK")
	)
	(segment
		(start 451.855332 -14.437868)
		(end 453.506078 -16.088614)
		(width 0.10795)
		(layer "F.Cu")
		(net "PWRGD_DSW_PWROK")
	)
	(via
		(at 401.286218 -67.42303)
		(size 0.508)
		(drill 0.254)
		(layers "F.Cu" "B.Cu")
		(net "PWRGD_DSW_PWROK")
	)
	(via
		(at 419.8874 -2.921)
		(size 0.508)
		(drill 0.254)
		(layers "F.Cu" "B.Cu")
		(net "PWRGD_DSW_PWROK")
	)
	(via
		(at 471.705432 -140.387832)
		(size 0.508)
		(drill 0.254)
		(layers "F.Cu" "B.Cu")
		(net "PWRGD_DSW_PWROK")
	)
	(via
		(at 426.4914 -70.2056)
		(size 0.508)
		(drill 0.254)
		(layers "F.Cu" "B.Cu")
		(net "PWRGD_DSW_PWROK")
	)
	(via
		(at 381.178562 -40.191182)
		(size 0.508)
		(drill 0.254)
		(layers "F.Cu" "B.Cu")
		(net "PWRGD_DSW_PWROK")
	)
	(via
		(at 379.31725 -98.464116)
		(size 0.508)
		(drill 0.254)
		(layers "F.Cu" "B.Cu")
		(net "PWRGD_DSW_PWROK")
	)
	(via
		(at 22.121114 4.163314)
		(size 0.508)
		(drill 0.254)
		(layers "F.Cu" "B.Cu")
		(net "PWRGD_DSW_PWROK")
	)
	(via
		(at 453.730614 -16.088614)
		(size 0.508)
		(drill 0.254)
		(layers "F.Cu" "B.Cu")
		(net "PWRGD_DSW_PWROK")
	)
	(via
		(at 464.39836 -38.08984)
		(size 0.508)
		(drill 0.254)
		(layers "F.Cu" "B.Cu")
		(net "PWRGD_DSW_PWROK")
	)
	(via
		(at 457.057252 -11.259312)
		(size 0.508)
		(drill 0.254)
		(layers "F.Cu" "B.Cu")
		(net "PWRGD_DSW_PWROK")
	)
	(via
		(at 18.02892 -24.680164)
		(size 0.508)
		(drill 0.254)
		(layers "F.Cu" "B.Cu")
		(net "PWRGD_DSW_PWROK")
	)
	(via
		(at 355.9048 -31.5722)
		(size 0.508)
		(drill 0.254)
		(layers "F.Cu" "B.Cu")
		(net "PWRGD_DSW_PWROK")
	)
	(via
		(at 371.1702 -68.6816)
		(size 0.4572)
		(drill 0.2032)
		(layers "F.Cu" "B.Cu")
		(net "PWRGD_DSW_PWROK")
	)
	(via
		(at 28.05938 -78.27518)
		(size 0.6604)
		(drill 0.3302)
		(layers "F.Cu" "B.Cu")
		(net "PWRGD_DSW_PWROK")
	)
	(segment
		(start 27.69616 -73.61936)
		(end 26.5938 -72.517)
		(width 0.10795)
		(layer "B.Cu")
		(net "PWRGD_DSW_PWROK")
	)
	(segment
		(start 458.547724 -34.009076)
		(end 459.025498 -33.531302)
		(width 0.10795)
		(layer "B.Cu")
		(net "PWRGD_DSW_PWROK")
	)
	(segment
		(start 28.05938 -77.46746)
		(end 27.69616 -77.10424)
		(width 0.10795)
		(layer "B.Cu")
		(net "PWRGD_DSW_PWROK")
	)
	(segment
		(start 458.04709 -39.00551)
		(end 457.054204 -39.998396)
		(width 0.10795)
		(layer "B.Cu")
		(net "PWRGD_DSW_PWROK")
	)
	(segment
		(start 455.390758 -36.2204)
		(end 455.390758 -35.174174)
		(width 0.10795)
		(layer "B.Cu")
		(net "PWRGD_DSW_PWROK")
	)
	(segment
		(start 26.5938 -53.595524)
		(end 28.437332 -51.751992)
		(width 0.10795)
		(layer "B.Cu")
		(net "PWRGD_DSW_PWROK")
	)
	(segment
		(start 456.127612 -25.948132)
		(end 456.127612 -19.822414)
		(width 0.10795)
		(layer "B.Cu")
		(net "PWRGD_DSW_PWROK")
	)
	(segment
		(start 385.575048 -39.034212)
		(end 385.574794 -39.034466)
		(width 0.10795)
		(layer "B.Cu")
		(net "PWRGD_DSW_PWROK")
	)
	(segment
		(start 419.6842 -3.1242)
		(end 419.8874 -2.921)
		(width 0.10795)
		(layer "B.Cu")
		(net "PWRGD_DSW_PWROK")
	)
	(segment
		(start 27.69616 -77.10424)
		(end 27.69616 -73.61936)
		(width 0.10795)
		(layer "B.Cu")
		(net "PWRGD_DSW_PWROK")
	)
	(segment
		(start 426.497242 -66.759582)
		(end 426.497496 -66.759836)
		(width 0.10795)
		(layer "B.Cu")
		(net "PWRGD_DSW_PWROK")
	)
	(segment
		(start 385.575048 -38.839648)
		(end 385.575048 -39.034212)
		(width 0.10795)
		(layer "B.Cu")
		(net "PWRGD_DSW_PWROK")
	)
	(segment
		(start 401.286218 -67.42303)
		(end 401.286218 -66.209164)
		(width 0.10795)
		(layer "B.Cu")
		(net "PWRGD_DSW_PWROK")
	)
	(segment
		(start 457.057252 -11.259312)
		(end 456.633834 -11.259312)
		(width 0.10795)
		(layer "B.Cu")
		(net "PWRGD_DSW_PWROK")
	)
	(segment
		(start 377.68784 -31.709106)
		(end 379.335538 -33.356804)
		(width 0.10795)
		(layer "B.Cu")
		(net "PWRGD_DSW_PWROK")
	)
	(segment
		(start 355.9048 -31.5722)
		(end 355.9048 -31.459424)
		(width 0.10795)
		(layer "B.Cu")
		(net "PWRGD_DSW_PWROK")
	)
	(segment
		(start 24.3078 -38.0492)
		(end 24.3078 -36.15182)
		(width 0.10795)
		(layer "B.Cu")
		(net "PWRGD_DSW_PWROK")
	)
	(segment
		(start 405.437848 -64.1604)
		(end 407.708608 -64.1604)
		(width 0.10795)
		(layer "B.Cu")
		(net "PWRGD_DSW_PWROK")
	)
	(segment
		(start 365.233204 -29.759402)
		(end 371.279674 -29.759402)
		(width 0.10795)
		(layer "B.Cu")
		(net "PWRGD_DSW_PWROK")
	)
	(segment
		(start 420.751 -4.699)
		(end 420.624 -4.826)
		(width 0.10795)
		(layer "B.Cu")
		(net "PWRGD_DSW_PWROK")
	)
	(segment
		(start 453.602598 -38.00856)
		(end 455.390758 -36.2204)
		(width 0.10795)
		(layer "B.Cu")
		(net "PWRGD_DSW_PWROK")
	)
	(segment
		(start 454.618598 -18.3134)
		(end 454.618598 -17.128236)
		(width 0.10795)
		(layer "B.Cu")
		(net "PWRGD_DSW_PWROK")
	)
	(segment
		(start 17.92097 -27.346402)
		(end 17.71015 -27.135582)
		(width 0.10795)
		(layer "B.Cu")
		(net "PWRGD_DSW_PWROK")
	)
	(segment
		(start 453.602598 -39.588186)
		(end 453.602598 -38.00856)
		(width 0.10795)
		(layer "B.Cu")
		(net "PWRGD_DSW_PWROK")
	)
	(segment
		(start 455.776584 -26.29916)
		(end 456.127612 -25.948132)
		(width 0.10795)
		(layer "B.Cu")
		(net "PWRGD_DSW_PWROK")
	)
	(segment
		(start 426.497496 -67.128136)
		(end 426.497242 -67.12839)
		(width 0.10795)
		(layer "B.Cu")
		(net "PWRGD_DSW_PWROK")
	)
	(segment
		(start 425.701206 -68.49237)
		(end 425.701206 -69.415406)
		(width 0.10795)
		(layer "B.Cu")
		(net "PWRGD_DSW_PWROK")
	)
	(segment
		(start 455.339196 -40.3098)
		(end 454.324212 -40.3098)
		(width 0.10795)
		(layer "B.Cu")
		(net "PWRGD_DSW_PWROK")
	)
	(segment
		(start 404.381462 -63.104014)
		(end 405.437848 -64.1604)
		(width 0.10795)
		(layer "B.Cu")
		(net "PWRGD_DSW_PWROK")
	)
	(segment
		(start 401.580858 -65.138046)
		(end 401.889468 -64.829436)
		(width 0.10795)
		(layer "B.Cu")
		(net "PWRGD_DSW_PWROK")
	)
	(segment
		(start 458.360272 -29.378402)
		(end 457.888594 -29.378402)
		(width 0.10795)
		(layer "B.Cu")
		(net "PWRGD_DSW_PWROK")
	)
	(segment
		(start 381.308356 -40.320976)
		(end 381.178562 -40.191182)
		(width 0.10795)
		(layer "B.Cu")
		(net "PWRGD_DSW_PWROK")
	)
	(segment
		(start 420.624 -7.781036)
		(end 420.73195 -7.888986)
		(width 0.10795)
		(layer "B.Cu")
		(net "PWRGD_DSW_PWROK")
	)
	(segment
		(start 379.335538 -33.356804)
		(end 381.41656 -33.356804)
		(width 0.10795)
		(layer "B.Cu")
		(net "PWRGD_DSW_PWROK")
	)
	(segment
		(start 415.741104 -60.290202)
		(end 417.440364 -60.290202)
		(width 0.10795)
		(layer "B.Cu")
		(net "PWRGD_DSW_PWROK")
	)
	(segment
		(start 371.279674 -29.759402)
		(end 373.662702 -27.376374)
		(width 0.10795)
		(layer "B.Cu")
		(net "PWRGD_DSW_PWROK")
	)
	(segment
		(start 21.1836 -33.02762)
		(end 21.1836 -30.4292)
		(width 0.10795)
		(layer "B.Cu")
		(net "PWRGD_DSW_PWROK")
	)
	(segment
		(start 425.701206 -69.415406)
		(end 426.4914 -70.2056)
		(width 0.10795)
		(layer "B.Cu")
		(net "PWRGD_DSW_PWROK")
	)
	(segment
		(start 402.278088 -64.829436)
		(end 402.662898 -64.444626)
		(width 0.10795)
		(layer "B.Cu")
		(net "PWRGD_DSW_PWROK")
	)
	(segment
		(start 426.497242 -62.97041)
		(end 426.497242 -66.759582)
		(width 0.10795)
		(layer "B.Cu")
		(net "PWRGD_DSW_PWROK")
	)
	(segment
		(start 464.25612 -37.9476)
		(end 463.539586 -37.9476)
		(width 0.10795)
		(layer "B.Cu")
		(net "PWRGD_DSW_PWROK")
	)
	(segment
		(start 419.6842 -3.922776)
		(end 419.6842 -3.1242)
		(width 0.10795)
		(layer "B.Cu")
		(net "PWRGD_DSW_PWROK")
	)
	(segment
		(start 17.71015 -27.135582)
		(end 17.71015 -25.69337)
		(width 0.10795)
		(layer "B.Cu")
		(net "PWRGD_DSW_PWROK")
	)
	(segment
		(start 355.9048 -31.459424)
		(end 356.21595 -31.148274)
		(width 0.10795)
		(layer "B.Cu")
		(net "PWRGD_DSW_PWROK")
	)
	(segment
		(start 356.21595 -31.148274)
		(end 363.844332 -31.148274)
		(width 0.10795)
		(layer "B.Cu")
		(net "PWRGD_DSW_PWROK")
	)
	(segment
		(start 373.857266 -27.376374)
		(end 373.85752 -27.376628)
		(width 0.10795)
		(layer "B.Cu")
		(net "PWRGD_DSW_PWROK")
	)
	(segment
		(start 385.574794 -39.310818)
		(end 384.564636 -40.320976)
		(width 0.10795)
		(layer "B.Cu")
		(net "PWRGD_DSW_PWROK")
	)
	(segment
		(start 426.497496 -66.759836)
		(end 426.497496 -67.128136)
		(width 0.10795)
		(layer "B.Cu")
		(net "PWRGD_DSW_PWROK")
	)
	(segment
		(start 411.084776 -62.44844)
		(end 413.582866 -62.44844)
		(width 0.10795)
		(layer "B.Cu")
		(net "PWRGD_DSW_PWROK")
	)
	(segment
		(start 459.47711 -33.531302)
		(end 459.999588 -33.008824)
		(width 0.10795)
		(layer "B.Cu")
		(net "PWRGD_DSW_PWROK")
	)
	(segment
		(start 22.677882 -42.029634)
		(end 22.677882 -39.679118)
		(width 0.10795)
		(layer "B.Cu")
		(net "PWRGD_DSW_PWROK")
	)
	(segment
		(start 419.952424 -4.191)
		(end 419.6842 -3.922776)
		(width 0.10795)
		(layer "B.Cu")
		(net "PWRGD_DSW_PWROK")
	)
	(segment
		(start 460.128874 -31.932372)
		(end 460.128874 -31.147004)
		(width 0.10795)
		(layer "B.Cu")
		(net "PWRGD_DSW_PWROK")
	)
	(segment
		(start 363.844332 -31.148274)
		(end 365.233204 -29.759402)
		(width 0.10795)
		(layer "B.Cu")
		(net "PWRGD_DSW_PWROK")
	)
	(segment
		(start 385.574794 -38.839394)
		(end 385.575048 -38.839648)
		(width 0.10795)
		(layer "B.Cu")
		(net "PWRGD_DSW_PWROK")
	)
	(segment
		(start 401.286218 -66.209164)
		(end 401.580858 -65.914524)
		(width 0.10795)
		(layer "B.Cu")
		(net "PWRGD_DSW_PWROK")
	)
	(segment
		(start 453.730614 -16.240252)
		(end 453.730614 -16.088614)
		(width 0.10795)
		(layer "B.Cu")
		(net "PWRGD_DSW_PWROK")
	)
	(segment
		(start 420.751 -4.191)
		(end 419.952424 -4.191)
		(width 0.10795)
		(layer "B.Cu")
		(net "PWRGD_DSW_PWROK")
	)
	(segment
		(start 417.440364 -60.290202)
		(end 419.326568 -58.403998)
		(width 0.10795)
		(layer "B.Cu")
		(net "PWRGD_DSW_PWROK")
	)
	(segment
		(start 472.127834 -139.96543)
		(end 472.55557 -139.96543)
		(width 0.10795)
		(layer "B.Cu")
		(net "PWRGD_DSW_PWROK")
	)
	(segment
		(start 28.05938 -78.31582)
		(end 26.0096 -80.3656)
		(width 0.10795)
		(layer "B.Cu")
		(net "PWRGD_DSW_PWROK")
	)
	(segment
		(start 463.48269 -39.00551)
		(end 458.04709 -39.00551)
		(width 0.10795)
		(layer "B.Cu")
		(net "PWRGD_DSW_PWROK")
	)
	(segment
		(start 28.437332 -47.789084)
		(end 22.677882 -42.029634)
		(width 0.10795)
		(layer "B.Cu")
		(net "PWRGD_DSW_PWROK")
	)
	(segment
		(start 18.02892 -25.3746)
		(end 18.02892 -24.680164)
		(width 0.10795)
		(layer "B.Cu")
		(net "PWRGD_DSW_PWROK")
	)
	(segment
		(start 455.6506 -39.998396)
		(end 455.339196 -40.3098)
		(width 0.10795)
		(layer "B.Cu")
		(net "PWRGD_DSW_PWROK")
	)
	(segment
		(start 402.662898 -63.318644)
		(end 402.877528 -63.104014)
		(width 0.10795)
		(layer "B.Cu")
		(net "PWRGD_DSW_PWROK")
	)
	(segment
		(start 472.783408 -139.737592)
		(end 473.660216 -139.737592)
		(width 0.10795)
		(layer "B.Cu")
		(net "PWRGD_DSW_PWROK")
	)
	(segment
		(start 426.497242 -67.696334)
		(end 425.701206 -68.49237)
		(width 0.10795)
		(layer "B.Cu")
		(net "PWRGD_DSW_PWROK")
	)
	(segment
		(start 24.3078 -36.15182)
		(end 21.1836 -33.02762)
		(width 0.10795)
		(layer "B.Cu")
		(net "PWRGD_DSW_PWROK")
	)
	(segment
		(start 385.574794 -39.034466)
		(end 385.574794 -39.310818)
		(width 0.10795)
		(layer "B.Cu")
		(net "PWRGD_DSW_PWROK")
	)
	(segment
		(start 413.582866 -62.44844)
		(end 415.741104 -60.290202)
		(width 0.10795)
		(layer "B.Cu")
		(net "PWRGD_DSW_PWROK")
	)
	(segment
		(start 407.708608 -64.1604)
		(end 408.045158 -64.49695)
		(width 0.10795)
		(layer "B.Cu")
		(net "PWRGD_DSW_PWROK")
	)
	(segment
		(start 456.127612 -19.822414)
		(end 454.618598 -18.3134)
		(width 0.10795)
		(layer "B.Cu")
		(net "PWRGD_DSW_PWROK")
	)
	(segment
		(start 28.05938 -78.27518)
		(end 28.05938 -77.46746)
		(width 0.10795)
		(layer "B.Cu")
		(net "PWRGD_DSW_PWROK")
	)
	(segment
		(start 472.55557 -139.96543)
		(end 472.783408 -139.737592)
		(width 0.10795)
		(layer "B.Cu")
		(net "PWRGD_DSW_PWROK")
	)
	(segment
		(start 26.5938 -72.517)
		(end 26.5938 -53.595524)
		(width 0.10795)
		(layer "B.Cu")
		(net "PWRGD_DSW_PWROK")
	)
	(segment
		(start 459.526386 -35.813238)
		(end 458.547724 -34.834576)
		(width 0.10795)
		(layer "B.Cu")
		(net "PWRGD_DSW_PWROK")
	)
	(segment
		(start 420.624 -4.826)
		(end 420.624 -7.781036)
		(width 0.10795)
		(layer "B.Cu")
		(net "PWRGD_DSW_PWROK")
	)
	(segment
		(start 420.751 -4.191)
		(end 420.751 -4.699)
		(width 0.10795)
		(layer "B.Cu")
		(net "PWRGD_DSW_PWROK")
	)
	(segment
		(start 384.918458 -33.510982)
		(end 385.574794 -34.167318)
		(width 0.10795)
		(layer "B.Cu")
		(net "PWRGD_DSW_PWROK")
	)
	(segment
		(start 459.526386 -36.565586)
		(end 459.526386 -35.813238)
		(width 0.10795)
		(layer "B.Cu")
		(net "PWRGD_DSW_PWROK")
	)
	(segment
		(start 28.437332 -51.751992)
		(end 28.437332 -47.789084)
		(width 0.10795)
		(layer "B.Cu")
		(net "PWRGD_DSW_PWROK")
	)
	(segment
		(start 426.497242 -67.12839)
		(end 426.497242 -67.696334)
		(width 0.10795)
		(layer "B.Cu")
		(net "PWRGD_DSW_PWROK")
	)
	(segment
		(start 454.324212 -40.3098)
		(end 453.602598 -39.588186)
		(width 0.10795)
		(layer "B.Cu")
		(net "PWRGD_DSW_PWROK")
	)
	(segment
		(start 381.570738 -33.510982)
		(end 384.918458 -33.510982)
		(width 0.10795)
		(layer "B.Cu")
		(net "PWRGD_DSW_PWROK")
	)
	(segment
		(start 426.073062 -62.54623)
		(end 426.497242 -62.97041)
		(width 0.10795)
		(layer "B.Cu")
		(net "PWRGD_DSW_PWROK")
	)
	(segment
		(start 20.2184 -29.464)
		(end 20.2184 -28.575)
		(width 0.10795)
		(layer "B.Cu")
		(net "PWRGD_DSW_PWROK")
	)
	(segment
		(start 463.539586 -37.9476)
		(end 462.548986 -36.957)
		(width 0.10795)
		(layer "B.Cu")
		(net "PWRGD_DSW_PWROK")
	)
	(segment
		(start 457.054204 -39.998396)
		(end 455.6506 -39.998396)
		(width 0.10795)
		(layer "B.Cu")
		(net "PWRGD_DSW_PWROK")
	)
	(segment
		(start 21.1836 -30.4292)
		(end 20.2184 -29.464)
		(width 0.10795)
		(layer "B.Cu")
		(net "PWRGD_DSW_PWROK")
	)
	(segment
		(start 420.73195 -7.888986)
		(end 421.3225 -7.888986)
		(width 0.10795)
		(layer "B.Cu")
		(net "PWRGD_DSW_PWROK")
	)
	(segment
		(start 28.05938 -78.27518)
		(end 28.05938 -78.31582)
		(width 0.10795)
		(layer "B.Cu")
		(net "PWRGD_DSW_PWROK")
	)
	(segment
		(start 459.9178 -36.957)
		(end 459.526386 -36.565586)
		(width 0.10795)
		(layer "B.Cu")
		(net "PWRGD_DSW_PWROK")
	)
	(segment
		(start 18.989802 -27.346402)
		(end 17.92097 -27.346402)
		(width 0.10795)
		(layer "B.Cu")
		(net "PWRGD_DSW_PWROK")
	)
	(segment
		(start 401.580858 -65.914524)
		(end 401.580858 -65.138046)
		(width 0.10795)
		(layer "B.Cu")
		(net "PWRGD_DSW_PWROK")
	)
	(segment
		(start 409.036266 -64.49695)
		(end 411.084776 -62.44844)
		(width 0.10795)
		(layer "B.Cu")
		(net "PWRGD_DSW_PWROK")
	)
	(segment
		(start 462.548986 -36.957)
		(end 459.9178 -36.957)
		(width 0.10795)
		(layer "B.Cu")
		(net "PWRGD_DSW_PWROK")
	)
	(segment
		(start 459.025498 -33.531302)
		(end 459.47711 -33.531302)
		(width 0.10795)
		(layer "B.Cu")
		(net "PWRGD_DSW_PWROK")
	)
	(segment
		(start 471.705432 -140.387832)
		(end 472.127834 -139.96543)
		(width 0.10795)
		(layer "B.Cu")
		(net "PWRGD_DSW_PWROK")
	)
	(segment
		(start 456.633834 -11.259312)
		(end 453.393048 -14.500098)
		(width 0.10795)
		(layer "B.Cu")
		(net "PWRGD_DSW_PWROK")
	)
	(segment
		(start 454.618598 -17.128236)
		(end 453.730614 -16.240252)
		(width 0.10795)
		(layer "B.Cu")
		(net "PWRGD_DSW_PWROK")
	)
	(segment
		(start 426.073062 -59.955684)
		(end 426.073062 -62.54623)
		(width 0.10795)
		(layer "B.Cu")
		(net "PWRGD_DSW_PWROK")
	)
	(segment
		(start 459.999588 -32.061658)
		(end 460.128874 -31.932372)
		(width 0.10795)
		(layer "B.Cu")
		(net "PWRGD_DSW_PWROK")
	)
	(segment
		(start 377.68784 -29.29636)
		(end 377.68784 -31.709106)
		(width 0.10795)
		(layer "B.Cu")
		(net "PWRGD_DSW_PWROK")
	)
	(segment
		(start 402.662898 -64.444626)
		(end 402.662898 -63.318644)
		(width 0.10795)
		(layer "B.Cu")
		(net "PWRGD_DSW_PWROK")
	)
	(segment
		(start 457.888594 -29.378402)
		(end 455.776584 -27.266392)
		(width 0.10795)
		(layer "B.Cu")
		(net "PWRGD_DSW_PWROK")
	)
	(segment
		(start 381.41656 -33.356804)
		(end 381.570738 -33.510982)
		(width 0.10795)
		(layer "B.Cu")
		(net "PWRGD_DSW_PWROK")
	)
	(segment
		(start 408.045158 -64.49695)
		(end 409.036266 -64.49695)
		(width 0.10795)
		(layer "B.Cu")
		(net "PWRGD_DSW_PWROK")
	)
	(segment
		(start 421.9575 -4.191)
		(end 420.751 -4.191)
		(width 0.10795)
		(layer "B.Cu")
		(net "PWRGD_DSW_PWROK")
	)
	(segment
		(start 455.776584 -27.266392)
		(end 455.776584 -26.29916)
		(width 0.10795)
		(layer "B.Cu")
		(net "PWRGD_DSW_PWROK")
	)
	(segment
		(start 17.71015 -25.69337)
		(end 18.02892 -25.3746)
		(width 0.10795)
		(layer "B.Cu")
		(net "PWRGD_DSW_PWROK")
	)
	(segment
		(start 384.564636 -40.320976)
		(end 381.308356 -40.320976)
		(width 0.10795)
		(layer "B.Cu")
		(net "PWRGD_DSW_PWROK")
	)
	(segment
		(start 22.677882 -39.679118)
		(end 24.3078 -38.0492)
		(width 0.10795)
		(layer "B.Cu")
		(net "PWRGD_DSW_PWROK")
	)
	(segment
		(start 373.85752 -27.376628)
		(end 375.768108 -27.376628)
		(width 0.10795)
		(layer "B.Cu")
		(net "PWRGD_DSW_PWROK")
	)
	(segment
		(start 458.547724 -34.834576)
		(end 458.547724 -34.009076)
		(width 0.10795)
		(layer "B.Cu")
		(net "PWRGD_DSW_PWROK")
	)
	(segment
		(start 373.662702 -27.376374)
		(end 373.857266 -27.376374)
		(width 0.10795)
		(layer "B.Cu")
		(net "PWRGD_DSW_PWROK")
	)
	(segment
		(start 464.39836 -38.08984)
		(end 463.48269 -39.00551)
		(width 0.10795)
		(layer "B.Cu")
		(net "PWRGD_DSW_PWROK")
	)
	(segment
		(start 459.999588 -33.008824)
		(end 459.999588 -32.061658)
		(width 0.10795)
		(layer "B.Cu")
		(net "PWRGD_DSW_PWROK")
	)
	(segment
		(start 424.521376 -58.403998)
		(end 426.073062 -59.955684)
		(width 0.10795)
		(layer "B.Cu")
		(net "PWRGD_DSW_PWROK")
	)
	(segment
		(start 453.393048 -14.500098)
		(end 453.393048 -15.751048)
		(width 0.10795)
		(layer "B.Cu")
		(net "PWRGD_DSW_PWROK")
	)
	(segment
		(start 26.0096 -80.3656)
		(end 26.0096 -80.645)
		(width 0.10795)
		(layer "B.Cu")
		(net "PWRGD_DSW_PWROK")
	)
	(segment
		(start 20.2184 -28.575)
		(end 18.989802 -27.346402)
		(width 0.10795)
		(layer "B.Cu")
		(net "PWRGD_DSW_PWROK")
	)
	(segment
		(start 460.128874 -31.147004)
		(end 458.360272 -29.378402)
		(width 0.10795)
		(layer "B.Cu")
		(net "PWRGD_DSW_PWROK")
	)
	(segment
		(start 453.393048 -15.751048)
		(end 453.730614 -16.088614)
		(width 0.10795)
		(layer "B.Cu")
		(net "PWRGD_DSW_PWROK")
	)
	(segment
		(start 401.889468 -64.829436)
		(end 402.278088 -64.829436)
		(width 0.10795)
		(layer "B.Cu")
		(net "PWRGD_DSW_PWROK")
	)
	(segment
		(start 402.877528 -63.104014)
		(end 404.381462 -63.104014)
		(width 0.10795)
		(layer "B.Cu")
		(net "PWRGD_DSW_PWROK")
	)
	(segment
		(start 419.326568 -58.403998)
		(end 424.521376 -58.403998)
		(width 0.10795)
		(layer "B.Cu")
		(net "PWRGD_DSW_PWROK")
	)
	(segment
		(start 385.574794 -34.167318)
		(end 385.574794 -38.839394)
		(width 0.10795)
		(layer "B.Cu")
		(net "PWRGD_DSW_PWROK")
	)
	(segment
		(start 375.768108 -27.376628)
		(end 377.68784 -29.29636)
		(width 0.10795)
		(layer "B.Cu")
		(net "PWRGD_DSW_PWROK")
	)
	(segment
		(start 464.39836 -38.08984)
		(end 464.25612 -37.9476)
		(width 0.10795)
		(layer "B.Cu")
		(net "PWRGD_DSW_PWROK")
	)
	(segment
		(start 378.152914 -64.843406)
		(end 379.831092 -63.165228)
		(width 0.089408)
		(layer "In2.Cu")
		(net "PWRGD_DSW_PWROK")
	)
	(segment
		(start 382.288288 -44.605956)
		(end 382.288288 -42.350436)
		(width 0.089408)
		(layer "In2.Cu")
		(net "PWRGD_DSW_PWROK")
	)
	(segment
		(start 381.178562 -40.247062)
		(end 381.178562 -40.191182)
		(width 0.089408)
		(layer "In2.Cu")
		(net "PWRGD_DSW_PWROK")
	)
	(segment
		(start 380.097284 -56.196738)
		(end 380.701042 -55.59298)
		(width 0.089408)
		(layer "In2.Cu")
		(net "PWRGD_DSW_PWROK")
	)
	(segment
		(start 380.701042 -54.991)
		(end 380.149354 -54.439312)
		(width 0.089408)
		(layer "In2.Cu")
		(net "PWRGD_DSW_PWROK")
	)
	(segment
		(start 371.592856 -68.258944)
		(end 371.592856 -67.485006)
		(width 0.089408)
		(layer "In2.Cu")
		(net "PWRGD_DSW_PWROK")
	)
	(segment
		(start 382.595628 -42.043096)
		(end 382.595628 -41.664128)
		(width 0.089408)
		(layer "In2.Cu")
		(net "PWRGD_DSW_PWROK")
	)
	(segment
		(start 379.831092 -57.006744)
		(end 380.097284 -56.740552)
		(width 0.089408)
		(layer "In2.Cu")
		(net "PWRGD_DSW_PWROK")
	)
	(segment
		(start 371.1702 -68.6816)
		(end 371.592856 -68.258944)
		(width 0.089408)
		(layer "In2.Cu")
		(net "PWRGD_DSW_PWROK")
	)
	(segment
		(start 382.595628 -41.664128)
		(end 381.178562 -40.247062)
		(width 0.089408)
		(layer "In2.Cu")
		(net "PWRGD_DSW_PWROK")
	)
	(segment
		(start 378.152914 -65.401952)
		(end 378.152914 -64.843406)
		(width 0.089408)
		(layer "In2.Cu")
		(net "PWRGD_DSW_PWROK")
	)
	(segment
		(start 380.149354 -54.439312)
		(end 380.149354 -46.74489)
		(width 0.089408)
		(layer "In2.Cu")
		(net "PWRGD_DSW_PWROK")
	)
	(segment
		(start 376.59056 -66.964306)
		(end 378.152914 -65.401952)
		(width 0.089408)
		(layer "In2.Cu")
		(net "PWRGD_DSW_PWROK")
	)
	(segment
		(start 372.113556 -66.964306)
		(end 376.59056 -66.964306)
		(width 0.089408)
		(layer "In2.Cu")
		(net "PWRGD_DSW_PWROK")
	)
	(segment
		(start 371.592856 -67.485006)
		(end 372.113556 -66.964306)
		(width 0.089408)
		(layer "In2.Cu")
		(net "PWRGD_DSW_PWROK")
	)
	(segment
		(start 380.097284 -56.740552)
		(end 380.097284 -56.196738)
		(width 0.089408)
		(layer "In2.Cu")
		(net "PWRGD_DSW_PWROK")
	)
	(segment
		(start 382.288288 -42.350436)
		(end 382.595628 -42.043096)
		(width 0.089408)
		(layer "In2.Cu")
		(net "PWRGD_DSW_PWROK")
	)
	(segment
		(start 380.701042 -55.59298)
		(end 380.701042 -54.991)
		(width 0.089408)
		(layer "In2.Cu")
		(net "PWRGD_DSW_PWROK")
	)
	(segment
		(start 380.149354 -46.74489)
		(end 382.288288 -44.605956)
		(width 0.089408)
		(layer "In2.Cu")
		(net "PWRGD_DSW_PWROK")
	)
	(segment
		(start 379.831092 -63.165228)
		(end 379.831092 -57.006744)
		(width 0.089408)
		(layer "In2.Cu")
		(net "PWRGD_DSW_PWROK")
	)
	(segment
		(start 471.84818 -126.29642)
		(end 472.7448 -126.29642)
		(width 0.089408)
		(layer "In4.Cu")
		(net "PWRGD_DSW_PWROK")
	)
	(segment
		(start 448.145662 -7.219442)
		(end 448.145408 -7.219696)
		(width 0.089408)
		(layer "In4.Cu")
		(net "PWRGD_DSW_PWROK")
	)
	(segment
		(start 470.36736 -137.2997)
		(end 470.36736 -133.96722)
		(width 0.089408)
		(layer "In4.Cu")
		(net "PWRGD_DSW_PWROK")
	)
	(segment
		(start 470.36736 -133.96722)
		(end 471.12428 -133.2103)
		(width 0.089408)
		(layer "In4.Cu")
		(net "PWRGD_DSW_PWROK")
	)
	(segment
		(start 400.800824 -67.42303)
		(end 401.286218 -67.42303)
		(width 0.089408)
		(layer "In4.Cu")
		(net "PWRGD_DSW_PWROK")
	)
	(segment
		(start 471.12428 -133.2103)
		(end 471.12428 -127.02032)
		(width 0.089408)
		(layer "In4.Cu")
		(net "PWRGD_DSW_PWROK")
	)
	(segment
		(start 437.02859 -118.12143)
		(end 434.232558 -120.917462)
		(width 0.089408)
		(layer "In4.Cu")
		(net "PWRGD_DSW_PWROK")
	)
	(segment
		(start 420.9288 -116.603526)
		(end 420.9288 -109.284262)
		(width 0.089408)
		(layer "In4.Cu")
		(net "PWRGD_DSW_PWROK")
	)
	(segment
		(start 448.320414 -7.219442)
		(end 448.145662 -7.219442)
		(width 0.089408)
		(layer "In4.Cu")
		(net "PWRGD_DSW_PWROK")
	)
	(segment
		(start 469.262968 -124.575062)
		(end 468.72779 -124.039884)
		(width 0.089408)
		(layer "In4.Cu")
		(net "PWRGD_DSW_PWROK")
	)
	(segment
		(start 371.651784 -68.6816)
		(end 373.18823 -67.145154)
		(width 0.089408)
		(layer "In4.Cu")
		(net "PWRGD_DSW_PWROK")
	)
	(segment
		(start 470.916 -139.5984)
		(end 470.916 -137.84834)
		(width 0.089408)
		(layer "In4.Cu")
		(net "PWRGD_DSW_PWROK")
	)
	(segment
		(start 376.01271 -66.422778)
		(end 376.205496 -66.229992)
		(width 0.089408)
		(layer "In4.Cu")
		(net "PWRGD_DSW_PWROK")
	)
	(segment
		(start 388.436104 -67.156584)
		(end 390.598152 -64.994536)
		(width 0.089408)
		(layer "In4.Cu")
		(net "PWRGD_DSW_PWROK")
	)
	(segment
		(start 472.016582 -124.575062)
		(end 469.262968 -124.575062)
		(width 0.089408)
		(layer "In4.Cu")
		(net "PWRGD_DSW_PWROK")
	)
	(segment
		(start 397.784066 -65.13068)
		(end 398.508474 -65.13068)
		(width 0.089408)
		(layer "In4.Cu")
		(net "PWRGD_DSW_PWROK")
	)
	(segment
		(start 396.553944 -64.758824)
		(end 397.41221 -64.758824)
		(width 0.089408)
		(layer "In4.Cu")
		(net "PWRGD_DSW_PWROK")
	)
	(segment
		(start 451.870572 -10.7696)
		(end 448.320414 -7.219442)
		(width 0.089408)
		(layer "In4.Cu")
		(net "PWRGD_DSW_PWROK")
	)
	(segment
		(start 419.8874 -3.6068)
		(end 419.8874 -2.921)
		(width 0.089408)
		(layer "In4.Cu")
		(net "PWRGD_DSW_PWROK")
	)
	(segment
		(start 378.252736 -66.229992)
		(end 378.430536 -66.407792)
		(width 0.089408)
		(layer "In4.Cu")
		(net "PWRGD_DSW_PWROK")
	)
	(segment
		(start 462.77276 -117.31244)
		(end 443.17158 -117.31244)
		(width 0.089408)
		(layer "In4.Cu")
		(net "PWRGD_DSW_PWROK")
	)
	(segment
		(start 468.24011 -119.5578)
		(end 465.01812 -119.5578)
		(width 0.089408)
		(layer "In4.Cu")
		(net "PWRGD_DSW_PWROK")
	)
	(segment
		(start 423.923714 -117.182646)
		(end 421.50792 -117.182646)
		(width 0.089408)
		(layer "In4.Cu")
		(net "PWRGD_DSW_PWROK")
	)
	(segment
		(start 373.18823 -67.145154)
		(end 374.189498 -67.145154)
		(width 0.089408)
		(layer "In4.Cu")
		(net "PWRGD_DSW_PWROK")
	)
	(segment
		(start 424.637962 -117.896894)
		(end 423.923714 -117.182646)
		(width 0.089408)
		(layer "In4.Cu")
		(net "PWRGD_DSW_PWROK")
	)
	(segment
		(start 443.17158 -117.31244)
		(end 442.36259 -118.12143)
		(width 0.089408)
		(layer "In4.Cu")
		(net "PWRGD_DSW_PWROK")
	)
	(segment
		(start 393.34059 -64.995044)
		(end 394.449554 -64.995044)
		(width 0.089408)
		(layer "In4.Cu")
		(net "PWRGD_DSW_PWROK")
	)
	(segment
		(start 396.318232 -64.994536)
		(end 396.553944 -64.758824)
		(width 0.089408)
		(layer "In4.Cu")
		(net "PWRGD_DSW_PWROK")
	)
	(segment
		(start 422.953942 -6.673342)
		(end 419.8874 -3.6068)
		(width 0.089408)
		(layer "In4.Cu")
		(net "PWRGD_DSW_PWROK")
	)
	(segment
		(start 470.916 -137.84834)
		(end 470.36736 -137.2997)
		(width 0.089408)
		(layer "In4.Cu")
		(net "PWRGD_DSW_PWROK")
	)
	(segment
		(start 442.36259 -118.12143)
		(end 437.02859 -118.12143)
		(width 0.089408)
		(layer "In4.Cu")
		(net "PWRGD_DSW_PWROK")
	)
	(segment
		(start 393.340336 -64.99479)
		(end 393.34059 -64.995044)
		(width 0.089408)
		(layer "In4.Cu")
		(net "PWRGD_DSW_PWROK")
	)
	(segment
		(start 371.1702 -68.6816)
		(end 371.651784 -68.6816)
		(width 0.089408)
		(layer "In4.Cu")
		(net "PWRGD_DSW_PWROK")
	)
	(segment
		(start 471.705432 -140.387832)
		(end 470.916 -139.5984)
		(width 0.089408)
		(layer "In4.Cu")
		(net "PWRGD_DSW_PWROK")
	)
	(segment
		(start 455.797412 -10.7696)
		(end 451.870572 -10.7696)
		(width 0.089408)
		(layer "In4.Cu")
		(net "PWRGD_DSW_PWROK")
	)
	(segment
		(start 472.7448 -126.29642)
		(end 472.96324 -126.07798)
		(width 0.089408)
		(layer "In4.Cu")
		(net "PWRGD_DSW_PWROK")
	)
	(segment
		(start 393.182348 -64.99479)
		(end 393.340336 -64.99479)
		(width 0.089408)
		(layer "In4.Cu")
		(net "PWRGD_DSW_PWROK")
	)
	(segment
		(start 390.598152 -64.994536)
		(end 393.182094 -64.994536)
		(width 0.089408)
		(layer "In4.Cu")
		(net "PWRGD_DSW_PWROK")
	)
	(segment
		(start 472.96324 -125.52172)
		(end 472.016582 -124.575062)
		(width 0.089408)
		(layer "In4.Cu")
		(net "PWRGD_DSW_PWROK")
	)
	(segment
		(start 425.02582 -71.67118)
		(end 426.4914 -70.2056)
		(width 0.089408)
		(layer "In4.Cu")
		(net "PWRGD_DSW_PWROK")
	)
	(segment
		(start 374.911874 -66.422778)
		(end 376.01271 -66.422778)
		(width 0.089408)
		(layer "In4.Cu")
		(net "PWRGD_DSW_PWROK")
	)
	(segment
		(start 428.283624 -120.917716)
		(end 427.56582 -120.917716)
		(width 0.089408)
		(layer "In4.Cu")
		(net "PWRGD_DSW_PWROK")
	)
	(segment
		(start 471.12428 -127.02032)
		(end 471.84818 -126.29642)
		(width 0.089408)
		(layer "In4.Cu")
		(net "PWRGD_DSW_PWROK")
	)
	(segment
		(start 422.779698 -107.433364)
		(end 424.281346 -107.433364)
		(width 0.089408)
		(layer "In4.Cu")
		(net "PWRGD_DSW_PWROK")
	)
	(segment
		(start 424.163998 -120.612662)
		(end 424.163998 -119.777256)
		(width 0.089408)
		(layer "In4.Cu")
		(net "PWRGD_DSW_PWROK")
	)
	(segment
		(start 457.057252 -11.259312)
		(end 456.287124 -11.259312)
		(width 0.089408)
		(layer "In4.Cu")
		(net "PWRGD_DSW_PWROK")
	)
	(segment
		(start 398.508474 -65.13068)
		(end 400.800824 -67.42303)
		(width 0.089408)
		(layer "In4.Cu")
		(net "PWRGD_DSW_PWROK")
	)
	(segment
		(start 376.205496 -66.229992)
		(end 378.252736 -66.229992)
		(width 0.089408)
		(layer "In4.Cu")
		(net "PWRGD_DSW_PWROK")
	)
	(segment
		(start 448.145408 -7.219696)
		(end 447.849244 -7.219696)
		(width 0.089408)
		(layer "In4.Cu")
		(net "PWRGD_DSW_PWROK")
	)
	(segment
		(start 394.450062 -64.994536)
		(end 396.318232 -64.994536)
		(width 0.089408)
		(layer "In4.Cu")
		(net "PWRGD_DSW_PWROK")
	)
	(segment
		(start 381.122936 -67.156584)
		(end 388.436104 -67.156584)
		(width 0.089408)
		(layer "In4.Cu")
		(net "PWRGD_DSW_PWROK")
	)
	(segment
		(start 465.01812 -119.5578)
		(end 462.77276 -117.31244)
		(width 0.089408)
		(layer "In4.Cu")
		(net "PWRGD_DSW_PWROK")
	)
	(segment
		(start 468.72779 -120.04548)
		(end 468.24011 -119.5578)
		(width 0.089408)
		(layer "In4.Cu")
		(net "PWRGD_DSW_PWROK")
	)
	(segment
		(start 374.189498 -67.145154)
		(end 374.911874 -66.422778)
		(width 0.089408)
		(layer "In4.Cu")
		(net "PWRGD_DSW_PWROK")
	)
	(segment
		(start 424.163998 -119.777256)
		(end 424.637962 -119.303292)
		(width 0.089408)
		(layer "In4.Cu")
		(net "PWRGD_DSW_PWROK")
	)
	(segment
		(start 380.374144 -66.407792)
		(end 381.122936 -67.156584)
		(width 0.089408)
		(layer "In4.Cu")
		(net "PWRGD_DSW_PWROK")
	)
	(segment
		(start 447.30289 -6.673342)
		(end 422.953942 -6.673342)
		(width 0.089408)
		(layer "In4.Cu")
		(net "PWRGD_DSW_PWROK")
	)
	(segment
		(start 424.468798 -120.917462)
		(end 424.163998 -120.612662)
		(width 0.089408)
		(layer "In4.Cu")
		(net "PWRGD_DSW_PWROK")
	)
	(segment
		(start 472.96324 -126.07798)
		(end 472.96324 -125.52172)
		(width 0.089408)
		(layer "In4.Cu")
		(net "PWRGD_DSW_PWROK")
	)
	(segment
		(start 468.72779 -124.039884)
		(end 468.72779 -120.04548)
		(width 0.089408)
		(layer "In4.Cu")
		(net "PWRGD_DSW_PWROK")
	)
	(segment
		(start 378.430536 -66.407792)
		(end 380.374144 -66.407792)
		(width 0.089408)
		(layer "In4.Cu")
		(net "PWRGD_DSW_PWROK")
	)
	(segment
		(start 424.281346 -107.433364)
		(end 425.02582 -106.68889)
		(width 0.089408)
		(layer "In4.Cu")
		(net "PWRGD_DSW_PWROK")
	)
	(segment
		(start 434.232558 -120.917462)
		(end 428.283878 -120.917462)
		(width 0.089408)
		(layer "In4.Cu")
		(net "PWRGD_DSW_PWROK")
	)
	(segment
		(start 394.449554 -64.995044)
		(end 394.450062 -64.994536)
		(width 0.089408)
		(layer "In4.Cu")
		(net "PWRGD_DSW_PWROK")
	)
	(segment
		(start 420.9288 -109.284262)
		(end 422.779698 -107.433364)
		(width 0.089408)
		(layer "In4.Cu")
		(net "PWRGD_DSW_PWROK")
	)
	(segment
		(start 425.02582 -106.68889)
		(end 425.02582 -71.67118)
		(width 0.089408)
		(layer "In4.Cu")
		(net "PWRGD_DSW_PWROK")
	)
	(segment
		(start 427.565566 -120.917462)
		(end 424.468798 -120.917462)
		(width 0.089408)
		(layer "In4.Cu")
		(net "PWRGD_DSW_PWROK")
	)
	(segment
		(start 456.287124 -11.259312)
		(end 455.797412 -10.7696)
		(width 0.089408)
		(layer "In4.Cu")
		(net "PWRGD_DSW_PWROK")
	)
	(segment
		(start 427.56582 -120.917716)
		(end 427.565566 -120.917462)
		(width 0.089408)
		(layer "In4.Cu")
		(net "PWRGD_DSW_PWROK")
	)
	(segment
		(start 447.849244 -7.219696)
		(end 447.30289 -6.673342)
		(width 0.089408)
		(layer "In4.Cu")
		(net "PWRGD_DSW_PWROK")
	)
	(segment
		(start 424.637962 -119.303292)
		(end 424.637962 -117.896894)
		(width 0.089408)
		(layer "In4.Cu")
		(net "PWRGD_DSW_PWROK")
	)
	(segment
		(start 397.41221 -64.758824)
		(end 397.784066 -65.13068)
		(width 0.089408)
		(layer "In4.Cu")
		(net "PWRGD_DSW_PWROK")
	)
	(segment
		(start 421.50792 -117.182646)
		(end 420.9288 -116.603526)
		(width 0.089408)
		(layer "In4.Cu")
		(net "PWRGD_DSW_PWROK")
	)
	(segment
		(start 428.283878 -120.917462)
		(end 428.283624 -120.917716)
		(width 0.089408)
		(layer "In4.Cu")
		(net "PWRGD_DSW_PWROK")
	)
	(segment
		(start 393.182094 -64.994536)
		(end 393.182348 -64.99479)
		(width 0.089408)
		(layer "In4.Cu")
		(net "PWRGD_DSW_PWROK")
	)
	(segment
		(start 350.929448 -22.953472)
		(end 351.50933 -23.533354)
		(width 0.089408)
		(layer "In9.Cu")
		(net "PWRGD_DSW_PWROK")
	)
	(segment
		(start 165.644068 -1.082802)
		(end 168.218866 -3.6576)
		(width 0.089408)
		(layer "In9.Cu")
		(net "PWRGD_DSW_PWROK")
	)
	(segment
		(start 340.469474 -19.693128)
		(end 340.469474 -22.42566)
		(width 0.089408)
		(layer "In9.Cu")
		(net "PWRGD_DSW_PWROK")
	)
	(segment
		(start 22.121114 4.163314)
		(end 22.905212 3.379216)
		(width 0.089408)
		(layer "In9.Cu")
		(net "PWRGD_DSW_PWROK")
	)
	(segment
		(start 103.310182 3.712464)
		(end 164.535358 3.712464)
		(width 0.089408)
		(layer "In9.Cu")
		(net "PWRGD_DSW_PWROK")
	)
	(segment
		(start 184.313576 -1.011428)
		(end 185.468514 0.14351)
		(width 0.089408)
		(layer "In9.Cu")
		(net "PWRGD_DSW_PWROK")
	)
	(segment
		(start 357.652828 -26.314908)
		(end 357.652828 -29.138118)
		(width 0.089408)
		(layer "In9.Cu")
		(net "PWRGD_DSW_PWROK")
	)
	(segment
		(start 331.30109 -8.629904)
		(end 332.038198 -8.629904)
		(width 0.089408)
		(layer "In9.Cu")
		(net "PWRGD_DSW_PWROK")
	)
	(segment
		(start 165.644068 2.603754)
		(end 165.644068 -1.082802)
		(width 0.089408)
		(layer "In9.Cu")
		(net "PWRGD_DSW_PWROK")
	)
	(segment
		(start 170.568366 -3.6576)
		(end 170.860974 -3.950208)
		(width 0.089408)
		(layer "In9.Cu")
		(net "PWRGD_DSW_PWROK")
	)
	(segment
		(start 181.95417 -3.570478)
		(end 184.313576 -1.211072)
		(width 0.089408)
		(layer "In9.Cu")
		(net "PWRGD_DSW_PWROK")
	)
	(segment
		(start 340.469474 -22.42566)
		(end 340.997286 -22.953472)
		(width 0.089408)
		(layer "In9.Cu")
		(net "PWRGD_DSW_PWROK")
	)
	(segment
		(start 258.892294 3.192526)
		(end 262.62457 -0.53975)
		(width 0.089408)
		(layer "In9.Cu")
		(net "PWRGD_DSW_PWROK")
	)
	(segment
		(start 102.579678 4.442968)
		(end 103.310182 3.712464)
		(width 0.089408)
		(layer "In9.Cu")
		(net "PWRGD_DSW_PWROK")
	)
	(segment
		(start 170.860974 -3.950208)
		(end 173.563026 -3.950208)
		(width 0.089408)
		(layer "In9.Cu")
		(net "PWRGD_DSW_PWROK")
	)
	(segment
		(start 332.563216 -9.154922)
		(end 337.376008 -9.154922)
		(width 0.089408)
		(layer "In9.Cu")
		(net "PWRGD_DSW_PWROK")
	)
	(segment
		(start 168.218866 -3.6576)
		(end 170.568366 -3.6576)
		(width 0.089408)
		(layer "In9.Cu")
		(net "PWRGD_DSW_PWROK")
	)
	(segment
		(start 354.871274 -23.533354)
		(end 357.652828 -26.314908)
		(width 0.089408)
		(layer "In9.Cu")
		(net "PWRGD_DSW_PWROK")
	)
	(segment
		(start 355.9048 -31.452566)
		(end 355.9048 -31.5722)
		(width 0.089408)
		(layer "In9.Cu")
		(net "PWRGD_DSW_PWROK")
	)
	(segment
		(start 178.471576 -3.485896)
		(end 178.556158 -3.570478)
		(width 0.089408)
		(layer "In9.Cu")
		(net "PWRGD_DSW_PWROK")
	)
	(segment
		(start 164.535358 3.712464)
		(end 165.644068 2.603754)
		(width 0.089408)
		(layer "In9.Cu")
		(net "PWRGD_DSW_PWROK")
	)
	(segment
		(start 24.384 3.379216)
		(end 25.447752 4.442968)
		(width 0.089408)
		(layer "In9.Cu")
		(net "PWRGD_DSW_PWROK")
	)
	(segment
		(start 262.62457 -0.53975)
		(end 323.364098 -0.53975)
		(width 0.089408)
		(layer "In9.Cu")
		(net "PWRGD_DSW_PWROK")
	)
	(segment
		(start 351.50933 -23.533354)
		(end 354.871274 -23.533354)
		(width 0.089408)
		(layer "In9.Cu")
		(net "PWRGD_DSW_PWROK")
	)
	(segment
		(start 357.067104 -30.442662)
		(end 356.832662 -30.677104)
		(width 0.089408)
		(layer "In9.Cu")
		(net "PWRGD_DSW_PWROK")
	)
	(segment
		(start 25.447752 4.442968)
		(end 102.579678 4.442968)
		(width 0.089408)
		(layer "In9.Cu")
		(net "PWRGD_DSW_PWROK")
	)
	(segment
		(start 184.313576 -1.211072)
		(end 184.313576 -1.011428)
		(width 0.089408)
		(layer "In9.Cu")
		(net "PWRGD_DSW_PWROK")
	)
	(segment
		(start 340.997286 -22.953472)
		(end 350.929448 -22.953472)
		(width 0.089408)
		(layer "In9.Cu")
		(net "PWRGD_DSW_PWROK")
	)
	(segment
		(start 339.023452 -18.247106)
		(end 340.469474 -19.693128)
		(width 0.089408)
		(layer "In9.Cu")
		(net "PWRGD_DSW_PWROK")
	)
	(segment
		(start 328.071734 -5.400548)
		(end 331.30109 -8.629904)
		(width 0.089408)
		(layer "In9.Cu")
		(net "PWRGD_DSW_PWROK")
	)
	(segment
		(start 185.468514 0.14351)
		(end 185.468514 1.589532)
		(width 0.089408)
		(layer "In9.Cu")
		(net "PWRGD_DSW_PWROK")
	)
	(segment
		(start 173.563026 -3.950208)
		(end 174.027338 -3.485896)
		(width 0.089408)
		(layer "In9.Cu")
		(net "PWRGD_DSW_PWROK")
	)
	(segment
		(start 357.174546 -30.18282)
		(end 357.067104 -30.290262)
		(width 0.089408)
		(layer "In9.Cu")
		(net "PWRGD_DSW_PWROK")
	)
	(segment
		(start 337.376008 -9.154922)
		(end 339.023452 -10.802366)
		(width 0.089408)
		(layer "In9.Cu")
		(net "PWRGD_DSW_PWROK")
	)
	(segment
		(start 356.680262 -30.677104)
		(end 355.9048 -31.452566)
		(width 0.089408)
		(layer "In9.Cu")
		(net "PWRGD_DSW_PWROK")
	)
	(segment
		(start 324.776084 -1.951736)
		(end 324.776084 -3.934968)
		(width 0.089408)
		(layer "In9.Cu")
		(net "PWRGD_DSW_PWROK")
	)
	(segment
		(start 356.832662 -30.677104)
		(end 356.680262 -30.677104)
		(width 0.089408)
		(layer "In9.Cu")
		(net "PWRGD_DSW_PWROK")
	)
	(segment
		(start 323.364098 -0.53975)
		(end 324.776084 -1.951736)
		(width 0.089408)
		(layer "In9.Cu")
		(net "PWRGD_DSW_PWROK")
	)
	(segment
		(start 326.241664 -5.400548)
		(end 328.071734 -5.400548)
		(width 0.089408)
		(layer "In9.Cu")
		(net "PWRGD_DSW_PWROK")
	)
	(segment
		(start 339.023452 -10.802366)
		(end 339.023452 -18.247106)
		(width 0.089408)
		(layer "In9.Cu")
		(net "PWRGD_DSW_PWROK")
	)
	(segment
		(start 324.776084 -3.934968)
		(end 326.241664 -5.400548)
		(width 0.089408)
		(layer "In9.Cu")
		(net "PWRGD_DSW_PWROK")
	)
	(segment
		(start 357.652828 -29.138118)
		(end 357.174546 -29.6164)
		(width 0.089408)
		(layer "In9.Cu")
		(net "PWRGD_DSW_PWROK")
	)
	(segment
		(start 22.905212 3.379216)
		(end 24.384 3.379216)
		(width 0.089408)
		(layer "In9.Cu")
		(net "PWRGD_DSW_PWROK")
	)
	(segment
		(start 357.174546 -29.6164)
		(end 357.174546 -30.18282)
		(width 0.089408)
		(layer "In9.Cu")
		(net "PWRGD_DSW_PWROK")
	)
	(segment
		(start 187.071508 3.192526)
		(end 258.892294 3.192526)
		(width 0.089408)
		(layer "In9.Cu")
		(net "PWRGD_DSW_PWROK")
	)
	(segment
		(start 357.067104 -30.290262)
		(end 357.067104 -30.442662)
		(width 0.089408)
		(layer "In9.Cu")
		(net "PWRGD_DSW_PWROK")
	)
	(segment
		(start 185.468514 1.589532)
		(end 187.071508 3.192526)
		(width 0.089408)
		(layer "In9.Cu")
		(net "PWRGD_DSW_PWROK")
	)
	(segment
		(start 174.027338 -3.485896)
		(end 178.471576 -3.485896)
		(width 0.089408)
		(layer "In9.Cu")
		(net "PWRGD_DSW_PWROK")
	)
	(segment
		(start 178.556158 -3.570478)
		(end 181.95417 -3.570478)
		(width 0.089408)
		(layer "In9.Cu")
		(net "PWRGD_DSW_PWROK")
	)
	(segment
		(start 332.038198 -8.629904)
		(end 332.563216 -9.154922)
		(width 0.089408)
		(layer "In9.Cu")
		(net "PWRGD_DSW_PWROK")
	)
	(segment
		(start 379.22073 -95.723202)
		(end 379.22073 -96.086422)
		(width 0.089408)
		(layer "In11.Cu")
		(net "PWRGD_DSW_PWROK")
	)
	(segment
		(start 375.2977 -90.68054)
		(end 375.610374 -90.68054)
		(width 0.089408)
		(layer "In11.Cu")
		(net "PWRGD_DSW_PWROK")
	)
	(segment
		(start 379.60046 -98.180906)
		(end 379.31725 -98.464116)
		(width 0.089408)
		(layer "In11.Cu")
		(net "PWRGD_DSW_PWROK")
	)
	(segment
		(start 379.41377 -97.440242)
		(end 379.41377 -97.77095)
		(width 0.089408)
		(layer "In11.Cu")
		(net "PWRGD_DSW_PWROK")
	)
	(segment
		(start 379.71603 -97.137982)
		(end 379.41377 -97.440242)
		(width 0.089408)
		(layer "In11.Cu")
		(net "PWRGD_DSW_PWROK")
	)
	(segment
		(start 373.044974 -81.935828)
		(end 373.342154 -82.233008)
		(width 0.089408)
		(layer "In11.Cu")
		(net "PWRGD_DSW_PWROK")
	)
	(segment
		(start 355.8286 -30.447234)
		(end 355.8286 -29.336746)
		(width 0.089408)
		(layer "In11.Cu")
		(net "PWRGD_DSW_PWROK")
	)
	(segment
		(start 371.093746 -5.0038)
		(end 380.873 -5.0038)
		(width 0.089408)
		(layer "In11.Cu")
		(net "PWRGD_DSW_PWROK")
	)
	(segment
		(start 371.1702 -68.6816)
		(end 371.5512 -69.0626)
		(width 0.089408)
		(layer "In11.Cu")
		(net "PWRGD_DSW_PWROK")
	)
	(segment
		(start 377.270518 -93.77299)
		(end 379.22073 -95.723202)
		(width 0.089408)
		(layer "In11.Cu")
		(net "PWRGD_DSW_PWROK")
	)
	(segment
		(start 379.71603 -96.581722)
		(end 379.71603 -97.137982)
		(width 0.089408)
		(layer "In11.Cu")
		(net "PWRGD_DSW_PWROK")
	)
	(segment
		(start 379.41377 -97.77095)
		(end 379.60046 -97.95764)
		(width 0.089408)
		(layer "In11.Cu")
		(net "PWRGD_DSW_PWROK")
	)
	(segment
		(start 379.60046 -97.95764)
		(end 379.60046 -98.180906)
		(width 0.089408)
		(layer "In11.Cu")
		(net "PWRGD_DSW_PWROK")
	)
	(segment
		(start 374.728232 -83.070192)
		(end 374.728232 -90.111072)
		(width 0.089408)
		(layer "In11.Cu")
		(net "PWRGD_DSW_PWROK")
	)
	(segment
		(start 418.615876 -2.921)
		(end 419.8874 -2.921)
		(width 0.089408)
		(layer "In11.Cu")
		(net "PWRGD_DSW_PWROK")
	)
	(segment
		(start 371.724428 -71.521828)
		(end 372.09984 -71.521828)
		(width 0.089408)
		(layer "In11.Cu")
		(net "PWRGD_DSW_PWROK")
	)
	(segment
		(start 380.873 -5.0038)
		(end 382.1684 -3.7084)
		(width 0.089408)
		(layer "In11.Cu")
		(net "PWRGD_DSW_PWROK")
	)
	(segment
		(start 390.500616 -2.335784)
		(end 403.158452 -2.335784)
		(width 0.089408)
		(layer "In11.Cu")
		(net "PWRGD_DSW_PWROK")
	)
	(segment
		(start 375.990104 -93.17736)
		(end 376.585734 -93.77299)
		(width 0.089408)
		(layer "In11.Cu")
		(net "PWRGD_DSW_PWROK")
	)
	(segment
		(start 382.1684 -3.7084)
		(end 389.128 -3.7084)
		(width 0.089408)
		(layer "In11.Cu")
		(net "PWRGD_DSW_PWROK")
	)
	(segment
		(start 376.585734 -93.77299)
		(end 377.270518 -93.77299)
		(width 0.089408)
		(layer "In11.Cu")
		(net "PWRGD_DSW_PWROK")
	)
	(segment
		(start 373.891048 -82.233008)
		(end 374.728232 -83.070192)
		(width 0.089408)
		(layer "In11.Cu")
		(net "PWRGD_DSW_PWROK")
	)
	(segment
		(start 371.5512 -71.3486)
		(end 371.724428 -71.521828)
		(width 0.089408)
		(layer "In11.Cu")
		(net "PWRGD_DSW_PWROK")
	)
	(segment
		(start 375.990104 -91.06027)
		(end 375.990104 -93.17736)
		(width 0.089408)
		(layer "In11.Cu")
		(net "PWRGD_DSW_PWROK")
	)
	(segment
		(start 374.728232 -90.111072)
		(end 375.2977 -90.68054)
		(width 0.089408)
		(layer "In11.Cu")
		(net "PWRGD_DSW_PWROK")
	)
	(segment
		(start 379.22073 -96.086422)
		(end 379.71603 -96.581722)
		(width 0.089408)
		(layer "In11.Cu")
		(net "PWRGD_DSW_PWROK")
	)
	(segment
		(start 360.2482 -15.849346)
		(end 371.093746 -5.0038)
		(width 0.089408)
		(layer "In11.Cu")
		(net "PWRGD_DSW_PWROK")
	)
	(segment
		(start 355.8286 -29.336746)
		(end 360.2482 -24.917146)
		(width 0.089408)
		(layer "In11.Cu")
		(net "PWRGD_DSW_PWROK")
	)
	(segment
		(start 355.9048 -31.5722)
		(end 356.076504 -31.400496)
		(width 0.089408)
		(layer "In11.Cu")
		(net "PWRGD_DSW_PWROK")
	)
	(segment
		(start 372.3894 -80.321404)
		(end 373.044974 -80.976978)
		(width 0.089408)
		(layer "In11.Cu")
		(net "PWRGD_DSW_PWROK")
	)
	(segment
		(start 403.158452 -2.335784)
		(end 403.91842 -1.575816)
		(width 0.089408)
		(layer "In11.Cu")
		(net "PWRGD_DSW_PWROK")
	)
	(segment
		(start 371.5512 -69.0626)
		(end 371.5512 -71.3486)
		(width 0.089408)
		(layer "In11.Cu")
		(net "PWRGD_DSW_PWROK")
	)
	(segment
		(start 403.91842 -1.575816)
		(end 406.736804 -1.575816)
		(width 0.089408)
		(layer "In11.Cu")
		(net "PWRGD_DSW_PWROK")
	)
	(segment
		(start 407.55062 -0.762)
		(end 416.456876 -0.762)
		(width 0.089408)
		(layer "In11.Cu")
		(net "PWRGD_DSW_PWROK")
	)
	(segment
		(start 373.342154 -82.233008)
		(end 373.891048 -82.233008)
		(width 0.089408)
		(layer "In11.Cu")
		(net "PWRGD_DSW_PWROK")
	)
	(segment
		(start 389.128 -3.7084)
		(end 390.500616 -2.335784)
		(width 0.089408)
		(layer "In11.Cu")
		(net "PWRGD_DSW_PWROK")
	)
	(segment
		(start 416.456876 -0.762)
		(end 418.615876 -2.921)
		(width 0.089408)
		(layer "In11.Cu")
		(net "PWRGD_DSW_PWROK")
	)
	(segment
		(start 372.09984 -71.521828)
		(end 372.3894 -71.811388)
		(width 0.089408)
		(layer "In11.Cu")
		(net "PWRGD_DSW_PWROK")
	)
	(segment
		(start 372.3894 -71.811388)
		(end 372.3894 -80.321404)
		(width 0.089408)
		(layer "In11.Cu")
		(net "PWRGD_DSW_PWROK")
	)
	(segment
		(start 356.076504 -30.695138)
		(end 355.8286 -30.447234)
		(width 0.089408)
		(layer "In11.Cu")
		(net "PWRGD_DSW_PWROK")
	)
	(segment
		(start 360.2482 -24.917146)
		(end 360.2482 -15.849346)
		(width 0.089408)
		(layer "In11.Cu")
		(net "PWRGD_DSW_PWROK")
	)
	(segment
		(start 406.736804 -1.575816)
		(end 407.55062 -0.762)
		(width 0.089408)
		(layer "In11.Cu")
		(net "PWRGD_DSW_PWROK")
	)
	(segment
		(start 373.044974 -80.976978)
		(end 373.044974 -81.935828)
		(width 0.089408)
		(layer "In11.Cu")
		(net "PWRGD_DSW_PWROK")
	)
	(segment
		(start 356.076504 -31.400496)
		(end 356.076504 -30.695138)
		(width 0.089408)
		(layer "In11.Cu")
		(net "PWRGD_DSW_PWROK")
	)
	(segment
		(start 375.610374 -90.68054)
		(end 375.990104 -91.06027)
		(width 0.089408)
		(layer "In11.Cu")
		(net "PWRGD_DSW_PWROK")
	)
	(segment
		(start 125.938788 -63.334138)
		(end 126.510288 -63.334138)
		(width 0.10795)
		(layer "F.Cu")
		(net "PU_CPU1_LEGACY_SKT")
	)
	(via
		(at 126.510288 -63.334138)
		(size 0.508)
		(drill 0.254)
		(layers "F.Cu" "B.Cu")
		(net "PU_CPU1_LEGACY_SKT")
	)
	(via
		(at 112.967008 -67.103752)
		(size 0.508)
		(drill 0.254)
		(layers "F.Cu" "B.Cu")
		(net "PU_CPU1_LEGACY_SKT")
	)
	(segment
		(start 112.967008 -67.103752)
		(end 112.967008 -67.18808)
		(width 0.10795)
		(layer "B.Cu")
		(net "PU_CPU1_LEGACY_SKT")
	)
	(segment
		(start 111.910368 -68.099178)
		(end 111.489236 -68.52031)
		(width 0.10795)
		(layer "B.Cu")
		(net "PU_CPU1_LEGACY_SKT")
	)
	(segment
		(start 112.967008 -67.18808)
		(end 112.05591 -68.099178)
		(width 0.10795)
		(layer "B.Cu")
		(net "PU_CPU1_LEGACY_SKT")
	)
	(segment
		(start 111.489236 -68.52031)
		(end 111.489236 -68.603114)
		(width 0.10795)
		(layer "B.Cu")
		(net "PU_CPU1_LEGACY_SKT")
	)
	(segment
		(start 112.05591 -68.099178)
		(end 111.910368 -68.099178)
		(width 0.10795)
		(layer "B.Cu")
		(net "PU_CPU1_LEGACY_SKT")
	)
	(segment
		(start 125.29566 -64.23406)
		(end 124.049028 -65.480692)
		(width 0.089408)
		(layer "In2.Cu")
		(net "PU_CPU1_LEGACY_SKT")
	)
	(segment
		(start 113.769902 -67.325494)
		(end 113.18875 -67.325494)
		(width 0.089408)
		(layer "In2.Cu")
		(net "PU_CPU1_LEGACY_SKT")
	)
	(segment
		(start 119.873014 -67.502278)
		(end 119.869712 -67.496436)
		(width 0.0889)
		(layer "In2.Cu")
		(net "PU_CPU1_LEGACY_SKT")
	)
	(segment
		(start 118.510558 -67.696588)
		(end 118.103904 -67.696588)
		(width 0.0889)
		(layer "In2.Cu")
		(net "PU_CPU1_LEGACY_SKT")
	)
	(segment
		(start 115.3414 -67.31)
		(end 114.977164 -66.945764)
		(width 0.089408)
		(layer "In2.Cu")
		(net "PU_CPU1_LEGACY_SKT")
	)
	(segment
		(start 116.134388 -67.696588)
		(end 115.7478 -67.31)
		(width 0.089408)
		(layer "In2.Cu")
		(net "PU_CPU1_LEGACY_SKT")
	)
	(segment
		(start 125.819662 -64.23406)
		(end 125.29566 -64.23406)
		(width 0.089408)
		(layer "In2.Cu")
		(net "PU_CPU1_LEGACY_SKT")
	)
	(segment
		(start 114.409982 -67.117468)
		(end 114.03457 -67.272916)
		(width 0.089408)
		(layer "In2.Cu")
		(net "PU_CPU1_LEGACY_SKT")
	)
	(segment
		(start 114.581686 -66.945764)
		(end 114.409982 -67.117468)
		(width 0.089408)
		(layer "In2.Cu")
		(net "PU_CPU1_LEGACY_SKT")
	)
	(segment
		(start 122.806714 -66.210434)
		(end 122.773948 -66.210434)
		(width 0.0889)
		(layer "In2.Cu")
		(net "PU_CPU1_LEGACY_SKT")
	)
	(segment
		(start 126.510288 -63.543434)
		(end 125.819662 -64.23406)
		(width 0.089408)
		(layer "In2.Cu")
		(net "PU_CPU1_LEGACY_SKT")
	)
	(segment
		(start 118.103904 -67.696588)
		(end 116.134388 -67.696588)
		(width 0.089408)
		(layer "In2.Cu")
		(net "PU_CPU1_LEGACY_SKT")
	)
	(segment
		(start 114.03457 -67.272916)
		(end 113.769902 -67.325494)
		(width 0.089408)
		(layer "In2.Cu")
		(net "PU_CPU1_LEGACY_SKT")
	)
	(segment
		(start 113.18875 -67.325494)
		(end 112.967008 -67.103752)
		(width 0.089408)
		(layer "In2.Cu")
		(net "PU_CPU1_LEGACY_SKT")
	)
	(segment
		(start 121.089674 -67.201034)
		(end 121.056908 -67.201034)
		(width 0.0889)
		(layer "In2.Cu")
		(net "PU_CPU1_LEGACY_SKT")
	)
	(segment
		(start 124.049028 -65.480692)
		(end 123.815094 -65.714626)
		(width 0.0889)
		(layer "In2.Cu")
		(net "PU_CPU1_LEGACY_SKT")
	)
	(segment
		(start 115.7478 -67.31)
		(end 115.3414 -67.31)
		(width 0.089408)
		(layer "In2.Cu")
		(net "PU_CPU1_LEGACY_SKT")
	)
	(segment
		(start 121.944384 -66.705988)
		(end 121.911618 -66.705988)
		(width 0.0889)
		(layer "In2.Cu")
		(net "PU_CPU1_LEGACY_SKT")
	)
	(segment
		(start 126.510288 -63.334138)
		(end 126.510288 -63.543434)
		(width 0.089408)
		(layer "In2.Cu")
		(net "PU_CPU1_LEGACY_SKT")
	)
	(segment
		(start 114.977164 -66.945764)
		(end 114.581686 -66.945764)
		(width 0.089408)
		(layer "In2.Cu")
		(net "PU_CPU1_LEGACY_SKT")
	)
	(segment
		(start 123.815094 -65.714626)
		(end 123.650756 -65.714626)
		(width 0.0889)
		(layer "In2.Cu")
		(net "PU_CPU1_LEGACY_SKT")
	)
	(arc
		(start 118.846092 -67.496436)
		(mid 118.704409 -67.64024)
		(end 118.510558 -67.696588)
		(width 0.0889)
		(layer "In2.Cu")
		(net "PU_CPU1_LEGACY_SKT")
	)
	(arc
		(start 120.562878 -67.496436)
		(mid 120.219588 -67.696732)
		(end 119.873014 -67.502278)
		(width 0.0889)
		(layer "In2.Cu")
		(net "PU_CPU1_LEGACY_SKT")
	)
	(arc
		(start 122.773948 -66.210434)
		(mid 122.488524 -66.293901)
		(end 122.279918 -66.505836)
		(width 0.0889)
		(layer "In2.Cu")
		(net "PU_CPU1_LEGACY_SKT")
	)
	(arc
		(start 123.138438 -66.010536)
		(mid 122.998359 -66.153272)
		(end 122.806714 -66.210434)
		(width 0.0889)
		(layer "In2.Cu")
		(net "PU_CPU1_LEGACY_SKT")
	)
	(arc
		(start 121.056908 -67.201034)
		(mid 120.771484 -67.284501)
		(end 120.562878 -67.496436)
		(width 0.0889)
		(layer "In2.Cu")
		(net "PU_CPU1_LEGACY_SKT")
	)
	(arc
		(start 122.279918 -66.505836)
		(mid 122.138235 -66.64964)
		(end 121.944384 -66.705988)
		(width 0.0889)
		(layer "In2.Cu")
		(net "PU_CPU1_LEGACY_SKT")
	)
	(arc
		(start 121.421398 -67.001136)
		(mid 121.281319 -67.143872)
		(end 121.089674 -67.201034)
		(width 0.0889)
		(layer "In2.Cu")
		(net "PU_CPU1_LEGACY_SKT")
	)
	(arc
		(start 121.911618 -66.705988)
		(mid 121.628401 -66.790269)
		(end 121.421398 -67.001136)
		(width 0.0889)
		(layer "In2.Cu")
		(net "PU_CPU1_LEGACY_SKT")
	)
	(arc
		(start 119.869712 -67.496436)
		(mid 119.357902 -67.200769)
		(end 118.846092 -67.496436)
		(width 0.0889)
		(layer "In2.Cu")
		(net "PU_CPU1_LEGACY_SKT")
	)
	(arc
		(start 123.650756 -65.714626)
		(mid 123.354956 -65.79393)
		(end 123.138438 -66.010536)
		(width 0.0889)
		(layer "In2.Cu")
		(net "PU_CPU1_LEGACY_SKT")
	)
	(segment
		(start 290.93922 -63.334138)
		(end 291.51072 -63.334138)
		(width 0.10795)
		(layer "F.Cu")
		(net "PU_CPU0_LEGACY_SKT")
	)
	(via
		(at 291.51072 -63.334138)
		(size 0.508)
		(drill 0.254)
		(layers "F.Cu" "B.Cu")
		(net "PU_CPU0_LEGACY_SKT")
	)
	(via
		(at 281.3304 -69.0626)
		(size 0.508)
		(drill 0.254)
		(layers "F.Cu" "B.Cu")
		(net "PU_CPU0_LEGACY_SKT")
	)
	(segment
		(start 280.785824 -69.607176)
		(end 280.785824 -70.673214)
		(width 0.10795)
		(layer "B.Cu")
		(net "PU_CPU0_LEGACY_SKT")
	)
	(segment
		(start 281.3304 -69.0626)
		(end 280.785824 -69.607176)
		(width 0.10795)
		(layer "B.Cu")
		(net "PU_CPU0_LEGACY_SKT")
	)
	(segment
		(start 290.068 -64.831214)
		(end 290.637214 -64.262)
		(width 0.089408)
		(layer "In2.Cu")
		(net "PU_CPU0_LEGACY_SKT")
	)
	(segment
		(start 283.0068 -68.5038)
		(end 283.21 -68.707)
		(width 0.089408)
		(layer "In2.Cu")
		(net "PU_CPU0_LEGACY_SKT")
	)
	(segment
		(start 286.6644 -67.9196)
		(end 287.3756 -67.9196)
		(width 0.089408)
		(layer "In2.Cu")
		(net "PU_CPU0_LEGACY_SKT")
	)
	(segment
		(start 288.114994 -67.414394)
		(end 290.068 -65.461388)
		(width 0.089408)
		(layer "In2.Cu")
		(net "PU_CPU0_LEGACY_SKT")
	)
	(segment
		(start 287.3756 -67.9196)
		(end 287.880806 -67.414394)
		(width 0.089408)
		(layer "In2.Cu")
		(net "PU_CPU0_LEGACY_SKT")
	)
	(segment
		(start 284.0736 -68.3768)
		(end 284.5562 -68.3768)
		(width 0.089408)
		(layer "In2.Cu")
		(net "PU_CPU0_LEGACY_SKT")
	)
	(segment
		(start 281.3304 -69.0626)
		(end 281.8892 -68.5038)
		(width 0.089408)
		(layer "In2.Cu")
		(net "PU_CPU0_LEGACY_SKT")
	)
	(segment
		(start 284.5562 -68.3768)
		(end 284.8864 -68.707)
		(width 0.089408)
		(layer "In2.Cu")
		(net "PU_CPU0_LEGACY_SKT")
	)
	(segment
		(start 285.877 -68.707)
		(end 286.6644 -67.9196)
		(width 0.089408)
		(layer "In2.Cu")
		(net "PU_CPU0_LEGACY_SKT")
	)
	(segment
		(start 291.211 -63.633858)
		(end 291.51072 -63.334138)
		(width 0.089408)
		(layer "In2.Cu")
		(net "PU_CPU0_LEGACY_SKT")
	)
	(segment
		(start 283.21 -68.707)
		(end 283.7434 -68.707)
		(width 0.089408)
		(layer "In2.Cu")
		(net "PU_CPU0_LEGACY_SKT")
	)
	(segment
		(start 290.068 -65.461388)
		(end 290.068 -64.831214)
		(width 0.089408)
		(layer "In2.Cu")
		(net "PU_CPU0_LEGACY_SKT")
	)
	(segment
		(start 284.8864 -68.707)
		(end 285.877 -68.707)
		(width 0.089408)
		(layer "In2.Cu")
		(net "PU_CPU0_LEGACY_SKT")
	)
	(segment
		(start 287.880806 -67.414394)
		(end 288.114994 -67.414394)
		(width 0.089408)
		(layer "In2.Cu")
		(net "PU_CPU0_LEGACY_SKT")
	)
	(segment
		(start 290.792154 -64.262)
		(end 291.211 -63.843154)
		(width 0.089408)
		(layer "In2.Cu")
		(net "PU_CPU0_LEGACY_SKT")
	)
	(segment
		(start 290.637214 -64.262)
		(end 290.792154 -64.262)
		(width 0.089408)
		(layer "In2.Cu")
		(net "PU_CPU0_LEGACY_SKT")
	)
	(segment
		(start 291.211 -63.843154)
		(end 291.211 -63.633858)
		(width 0.089408)
		(layer "In2.Cu")
		(net "PU_CPU0_LEGACY_SKT")
	)
	(segment
		(start 283.7434 -68.707)
		(end 284.0736 -68.3768)
		(width 0.089408)
		(layer "In2.Cu")
		(net "PU_CPU0_LEGACY_SKT")
	)
	(segment
		(start 281.8892 -68.5038)
		(end 283.0068 -68.5038)
		(width 0.089408)
		(layer "In2.Cu")
		(net "PU_CPU0_LEGACY_SKT")
	)
	(segment
		(start 388.53745 -106.25455)
		(end 388.813548 -105.978452)
		(width 0.127)
		(layer "F.Cu")
		(net "P1V8_PCH_STBY")
	)
	(segment
		(start 392.1379 -105.8545)
		(end 391.73785 -106.25455)
		(width 0.12446)
		(layer "F.Cu")
		(net "P1V8_PCH_STBY")
	)
	(segment
		(start 385.572 -104.2416)
		(end 385.572 -104.4194)
		(width 0.127)
		(layer "F.Cu")
		(net "P1V8_PCH_STBY")
	)
	(segment
		(start 388.53745 -106.25455)
		(end 388.3152 -106.4768)
		(width 0.12446)
		(layer "F.Cu")
		(net "P1V8_PCH_STBY")
	)
	(segment
		(start 385.445 -104.1146)
		(end 385.572 -104.2416)
		(width 0.127)
		(layer "F.Cu")
		(net "P1V8_PCH_STBY")
	)
	(segment
		(start 389.7376 -105.8545)
		(end 390.13765 -106.25455)
		(width 0.127)
		(layer "F.Cu")
		(net "P1V8_PCH_STBY")
	)
	(segment
		(start 385.1021 -104.2543)
		(end 385.2418 -104.1146)
		(width 0.127)
		(layer "F.Cu")
		(net "P1V8_PCH_STBY")
	)
	(segment
		(start 392.1379 -105.0544)
		(end 392.53795 -105.45445)
		(width 0.12446)
		(layer "F.Cu")
		(net "P1V8_PCH_STBY")
	)
	(segment
		(start 391.73785 -105.45445)
		(end 392.1379 -105.0544)
		(width 0.12446)
		(layer "F.Cu")
		(net "P1V8_PCH_STBY")
	)
	(segment
		(start 390.13765 -106.25455)
		(end 390.5377 -105.8545)
		(width 0.12446)
		(layer "F.Cu")
		(net "P1V8_PCH_STBY")
	)
	(segment
		(start 389.33755 -106.25455)
		(end 389.7376 -105.8545)
		(width 0.12446)
		(layer "F.Cu")
		(net "P1V8_PCH_STBY")
	)
	(segment
		(start 392.308588 -106.483912)
		(end 391.967212 -106.483912)
		(width 0.127)
		(layer "F.Cu")
		(net "P1V8_PCH_STBY")
	)
	(segment
		(start 388.1374 -105.8545)
		(end 388.53745 -106.25455)
		(width 0.127)
		(layer "F.Cu")
		(net "P1V8_PCH_STBY")
	)
	(segment
		(start 391.3378 -105.8545)
		(end 391.73785 -105.45445)
		(width 0.127)
		(layer "F.Cu")
		(net "P1V8_PCH_STBY")
	)
	(segment
		(start 389.061452 -105.978452)
		(end 389.33755 -106.25455)
		(width 0.127)
		(layer "F.Cu")
		(net "P1V8_PCH_STBY")
	)
	(segment
		(start 393.68095 -114.1476)
		(end 394.17625 -114.377724)
		(width 0.254)
		(layer "F.Cu")
		(net "P1V8_PCH_STBY")
	)
	(segment
		(start 387.73735 -106.25455)
		(end 387.35 -105.8672)
		(width 0.12446)
		(layer "F.Cu")
		(net "P1V8_PCH_STBY")
	)
	(segment
		(start 391.967212 -106.483912)
		(end 391.73785 -106.25455)
		(width 0.127)
		(layer "F.Cu")
		(net "P1V8_PCH_STBY")
	)
	(segment
		(start 391.73785 -106.25455)
		(end 391.3378 -105.8545)
		(width 0.127)
		(layer "F.Cu")
		(net "P1V8_PCH_STBY")
	)
	(segment
		(start 398.4244 -127.889)
		(end 398.3736 -127.8382)
		(width 0.254)
		(layer "F.Cu")
		(net "P1V8_PCH_STBY")
	)
	(segment
		(start 390.5377 -105.8545)
		(end 390.93775 -106.25455)
		(width 0.127)
		(layer "F.Cu")
		(net "P1V8_PCH_STBY")
	)
	(segment
		(start 385.572 -104.4194)
		(end 385.33705 -104.65435)
		(width 0.127)
		(layer "F.Cu")
		(net "P1V8_PCH_STBY")
	)
	(segment
		(start 388.3152 -106.4768)
		(end 387.9596 -106.4768)
		(width 0.12446)
		(layer "F.Cu")
		(net "P1V8_PCH_STBY")
	)
	(segment
		(start 387.73735 -103.84536)
		(end 388.23265 -103.615236)
		(width 0.254)
		(layer "F.Cu")
		(net "P1V8_PCH_STBY")
	)
	(segment
		(start 392.53795 -106.25455)
		(end 392.308588 -106.483912)
		(width 0.127)
		(layer "F.Cu")
		(net "P1V8_PCH_STBY")
	)
	(segment
		(start 385.1021 -104.4194)
		(end 385.1021 -104.2543)
		(width 0.127)
		(layer "F.Cu")
		(net "P1V8_PCH_STBY")
	)
	(segment
		(start 385.33705 -104.65435)
		(end 385.7371 -105.0544)
		(width 0.12446)
		(layer "F.Cu")
		(net "P1V8_PCH_STBY")
	)
	(segment
		(start 391.3378 -105.8545)
		(end 390.93775 -106.25455)
		(width 0.12446)
		(layer "F.Cu")
		(net "P1V8_PCH_STBY")
	)
	(segment
		(start 385.2418 -104.1146)
		(end 385.445 -104.1146)
		(width 0.127)
		(layer "F.Cu")
		(net "P1V8_PCH_STBY")
	)
	(segment
		(start 398.4244 -128.91262)
		(end 398.4244 -127.889)
		(width 0.254)
		(layer "F.Cu")
		(net "P1V8_PCH_STBY")
	)
	(segment
		(start 392.53795 -105.45445)
		(end 392.1379 -105.8545)
		(width 0.127)
		(layer "F.Cu")
		(net "P1V8_PCH_STBY")
	)
	(segment
		(start 392.1379 -105.8545)
		(end 391.73785 -105.45445)
		(width 0.127)
		(layer "F.Cu")
		(net "P1V8_PCH_STBY")
	)
	(segment
		(start 387.35 -105.8672)
		(end 387.35 -105.8545)
		(width 0.12446)
		(layer "F.Cu")
		(net "P1V8_PCH_STBY")
	)
	(segment
		(start 392.53795 -106.25455)
		(end 392.1379 -105.8545)
		(width 0.12446)
		(layer "F.Cu")
		(net "P1V8_PCH_STBY")
	)
	(segment
		(start 387.35 -105.8545)
		(end 388.1374 -105.8545)
		(width 0.127)
		(layer "F.Cu")
		(net "P1V8_PCH_STBY")
	)
	(segment
		(start 388.813548 -105.978452)
		(end 389.061452 -105.978452)
		(width 0.127)
		(layer "F.Cu")
		(net "P1V8_PCH_STBY")
	)
	(segment
		(start 385.33705 -104.65435)
		(end 385.1021 -104.4194)
		(width 0.127)
		(layer "F.Cu")
		(net "P1V8_PCH_STBY")
	)
	(segment
		(start 387.9596 -106.4768)
		(end 387.73735 -106.25455)
		(width 0.12446)
		(layer "F.Cu")
		(net "P1V8_PCH_STBY")
	)
	(segment
		(start 385.7371 -105.0544)
		(end 386.13715 -105.45445)
		(width 0.12446)
		(layer "F.Cu")
		(net "P1V8_PCH_STBY")
	)
	(via
		(at 391.3378 -105.8545)
		(size 0.508)
		(drill 0.254)
		(layers "F.Cu" "B.Cu")
		(net "P1V8_PCH_STBY")
	)
	(via
		(at 389.7376 -105.8545)
		(size 0.508)
		(drill 0.254)
		(layers "F.Cu" "B.Cu")
		(net "P1V8_PCH_STBY")
	)
	(via
		(at 392.1379 -105.8545)
		(size 0.508)
		(drill 0.254)
		(layers "F.Cu" "B.Cu")
		(net "P1V8_PCH_STBY")
	)
	(via
		(at 410.21 -129.6162)
		(size 0.508)
		(drill 0.254)
		(layers "F.Cu" "B.Cu")
		(net "P1V8_PCH_STBY")
	)
	(via
		(at 409.575 -129.6162)
		(size 0.508)
		(drill 0.254)
		(layers "F.Cu" "B.Cu")
		(net "P1V8_PCH_STBY")
	)
	(via
		(at 405.52878 -142.815564)
		(size 0.508)
		(drill 0.254)
		(layers "F.Cu" "B.Cu")
		(net "P1V8_PCH_STBY")
	)
	(via
		(at 406.16378 -142.815564)
		(size 0.508)
		(drill 0.254)
		(layers "F.Cu" "B.Cu")
		(net "P1V8_PCH_STBY")
	)
	(via
		(at 405.4348 -146.3675)
		(size 0.6604)
		(drill 0.3302)
		(layers "F.Cu" "B.Cu")
		(net "P1V8_PCH_STBY")
	)
	(via
		(at 405.5364 -144.0815)
		(size 0.508)
		(drill 0.254)
		(layers "F.Cu" "B.Cu")
		(net "P1V8_PCH_STBY")
	)
	(via
		(at 405.895302 -141.578838)
		(size 0.6604)
		(drill 0.3302)
		(layers "F.Cu" "B.Cu")
		(net "P1V8_PCH_STBY")
	)
	(via
		(at 387.35 -105.8545)
		(size 0.508)
		(drill 0.254)
		(layers "F.Cu" "B.Cu")
		(net "P1V8_PCH_STBY")
	)
	(via
		(at 385.2418 -104.1146)
		(size 0.508)
		(drill 0.254)
		(layers "F.Cu" "B.Cu")
		(net "P1V8_PCH_STBY")
	)
	(via
		(at 394.17625 -114.377724)
		(size 0.508)
		(drill 0.254)
		(layers "F.Cu" "B.Cu")
		(net "P1V8_PCH_STBY")
	)
	(via
		(at 406.17648 -143.450056)
		(size 0.508)
		(drill 0.254)
		(layers "F.Cu" "B.Cu")
		(net "P1V8_PCH_STBY")
	)
	(via
		(at 385.7371 -105.0544)
		(size 0.508)
		(drill 0.254)
		(layers "F.Cu" "B.Cu")
		(net "P1V8_PCH_STBY")
	)
	(via
		(at 392.1379 -105.0544)
		(size 0.508)
		(drill 0.254)
		(layers "F.Cu" "B.Cu")
		(net "P1V8_PCH_STBY")
	)
	(via
		(at 390.5377 -105.8545)
		(size 0.508)
		(drill 0.254)
		(layers "F.Cu" "B.Cu")
		(net "P1V8_PCH_STBY")
	)
	(via
		(at 405.54148 -143.450056)
		(size 0.508)
		(drill 0.254)
		(layers "F.Cu" "B.Cu")
		(net "P1V8_PCH_STBY")
	)
	(via
		(at 388.23265 -103.615236)
		(size 0.508)
		(drill 0.254)
		(layers "F.Cu" "B.Cu")
		(net "P1V8_PCH_STBY")
	)
	(via
		(at 398.3736 -127.8382)
		(size 0.508)
		(drill 0.254)
		(layers "F.Cu" "B.Cu")
		(net "P1V8_PCH_STBY")
	)
	(segment
		(start 394.17625 -115.448334)
		(end 393.719304 -115.90528)
		(width 0.2032)
		(layer "In2.Cu")
		(net "P1V8_PCH_STBY")
	)
	(segment
		(start 394.17625 -118.882414)
		(end 393.719304 -119.33936)
		(width 0.2032)
		(layer "In2.Cu")
		(net "P1V8_PCH_STBY")
	)
	(segment
		(start 395.6304 -123.0884)
		(end 396.1384 -123.5964)
		(width 0.2032)
		(layer "In2.Cu")
		(net "P1V8_PCH_STBY")
	)
	(segment
		(start 393.719304 -119.718328)
		(end 394.17625 -120.175274)
		(width 0.2032)
		(layer "In2.Cu")
		(net "P1V8_PCH_STBY")
	)
	(segment
		(start 394.6906 -121.113804)
		(end 394.6906 -121.4628)
		(width 0.2032)
		(layer "In2.Cu")
		(net "P1V8_PCH_STBY")
	)
	(segment
		(start 393.719304 -115.90528)
		(end 393.719304 -116.284248)
		(width 0.2032)
		(layer "In2.Cu")
		(net "P1V8_PCH_STBY")
	)
	(segment
		(start 398.2212 -126.1364)
		(end 398.7546 -126.6698)
		(width 0.254)
		(layer "In2.Cu")
		(net "P1V8_PCH_STBY")
	)
	(segment
		(start 396.1384 -124.5616)
		(end 397.7132 -126.1364)
		(width 0.254)
		(layer "In2.Cu")
		(net "P1V8_PCH_STBY")
	)
	(segment
		(start 394.17625 -118.458234)
		(end 394.17625 -118.882414)
		(width 0.2032)
		(layer "In2.Cu")
		(net "P1V8_PCH_STBY")
	)
	(segment
		(start 393.719304 -118.001288)
		(end 394.17625 -118.458234)
		(width 0.2032)
		(layer "In2.Cu")
		(net "P1V8_PCH_STBY")
	)
	(segment
		(start 398.7546 -126.6698)
		(end 398.7546 -127.1778)
		(width 0.254)
		(layer "In2.Cu")
		(net "P1V8_PCH_STBY")
	)
	(segment
		(start 395.6304 -122.7582)
		(end 395.6304 -123.0884)
		(width 0.2032)
		(layer "In2.Cu")
		(net "P1V8_PCH_STBY")
	)
	(segment
		(start 395.1986 -121.9708)
		(end 395.1986 -122.3264)
		(width 0.2032)
		(layer "In2.Cu")
		(net "P1V8_PCH_STBY")
	)
	(segment
		(start 393.719304 -119.33936)
		(end 393.719304 -119.718328)
		(width 0.2032)
		(layer "In2.Cu")
		(net "P1V8_PCH_STBY")
	)
	(segment
		(start 396.1384 -123.5964)
		(end 396.1384 -124.5616)
		(width 0.2032)
		(layer "In2.Cu")
		(net "P1V8_PCH_STBY")
	)
	(segment
		(start 394.17625 -120.175274)
		(end 394.17625 -120.599454)
		(width 0.2032)
		(layer "In2.Cu")
		(net "P1V8_PCH_STBY")
	)
	(segment
		(start 394.17625 -116.741194)
		(end 394.17625 -117.165374)
		(width 0.2032)
		(layer "In2.Cu")
		(net "P1V8_PCH_STBY")
	)
	(segment
		(start 398.7546 -127.1778)
		(end 398.3736 -127.5588)
		(width 0.254)
		(layer "In2.Cu")
		(net "P1V8_PCH_STBY")
	)
	(segment
		(start 394.17625 -120.599454)
		(end 394.6906 -121.113804)
		(width 0.2032)
		(layer "In2.Cu")
		(net "P1V8_PCH_STBY")
	)
	(segment
		(start 393.719304 -116.284248)
		(end 394.17625 -116.741194)
		(width 0.2032)
		(layer "In2.Cu")
		(net "P1V8_PCH_STBY")
	)
	(segment
		(start 393.719304 -117.62232)
		(end 393.719304 -118.001288)
		(width 0.2032)
		(layer "In2.Cu")
		(net "P1V8_PCH_STBY")
	)
	(segment
		(start 394.17625 -117.165374)
		(end 393.719304 -117.62232)
		(width 0.2032)
		(layer "In2.Cu")
		(net "P1V8_PCH_STBY")
	)
	(segment
		(start 394.6906 -121.4628)
		(end 395.1986 -121.9708)
		(width 0.2032)
		(layer "In2.Cu")
		(net "P1V8_PCH_STBY")
	)
	(segment
		(start 397.7132 -126.1364)
		(end 398.2212 -126.1364)
		(width 0.254)
		(layer "In2.Cu")
		(net "P1V8_PCH_STBY")
	)
	(segment
		(start 394.17625 -114.377724)
		(end 394.17625 -115.448334)
		(width 0.2032)
		(layer "In2.Cu")
		(net "P1V8_PCH_STBY")
	)
	(segment
		(start 395.1986 -122.3264)
		(end 395.6304 -122.7582)
		(width 0.2032)
		(layer "In2.Cu")
		(net "P1V8_PCH_STBY")
	)
	(segment
		(start 398.3736 -127.5588)
		(end 398.3736 -127.8382)
		(width 0.254)
		(layer "In2.Cu")
		(net "P1V8_PCH_STBY")
	)
	(segment
		(start 379.31725 -99.55276)
		(end 379.81255 -99.322636)
		(width 0.10795)
		(layer "F.Cu")
		(net "TP_SLP_LAN_N")
	)
	(via
		(at 379.81255 -99.322636)
		(size 0.508)
		(drill 0.254)
		(layers "F.Cu" "B.Cu")
		(net "TP_SLP_LAN_N")
	)
	(segment
		(start 371.945154 -71.095108)
		(end 372.34495 -71.494904)
		(width 0.1016)
		(layer "F.Cu")
		(net "FM_SLP_SUS_N")
	)
	(segment
		(start 380.80315 -95.888556)
		(end 380.30785 -96.11868)
		(width 0.10795)
		(layer "F.Cu")
		(net "FM_SLP_SUS_N")
	)
	(via
		(at 371.945154 -71.095108)
		(size 0.4572)
		(drill 0.2032)
		(layers "F.Cu" "B.Cu")
		(net "FM_SLP_SUS_N")
	)
	(via
		(at 380.80315 -95.888556)
		(size 0.508)
		(drill 0.254)
		(layers "F.Cu" "B.Cu")
		(net "FM_SLP_SUS_N")
	)
	(segment
		(start 372.700042 -71.531988)
		(end 372.263162 -71.095108)
		(width 0.089408)
		(layer "In11.Cu")
		(net "FM_SLP_SUS_N")
	)
	(segment
		(start 376.3772 -89.814146)
		(end 375.2088 -88.645746)
		(width 0.089408)
		(layer "In11.Cu")
		(net "FM_SLP_SUS_N")
	)
	(segment
		(start 375.2088 -82.91576)
		(end 373.801894 -81.508854)
		(width 0.089408)
		(layer "In11.Cu")
		(net "FM_SLP_SUS_N")
	)
	(segment
		(start 372.700042 -80.11287)
		(end 372.700042 -71.531988)
		(width 0.089408)
		(layer "In11.Cu")
		(net "FM_SLP_SUS_N")
	)
	(segment
		(start 373.801894 -81.214722)
		(end 372.700042 -80.11287)
		(width 0.089408)
		(layer "In11.Cu")
		(net "FM_SLP_SUS_N")
	)
	(segment
		(start 376.979688 -93.230446)
		(end 376.974354 -93.23578)
		(width 0.089408)
		(layer "In11.Cu")
		(net "FM_SLP_SUS_N")
	)
	(segment
		(start 376.643646 -93.23578)
		(end 376.3772 -92.969334)
		(width 0.089408)
		(layer "In11.Cu")
		(net "FM_SLP_SUS_N")
	)
	(segment
		(start 380.80315 -95.888556)
		(end 378.14504 -93.230446)
		(width 0.089408)
		(layer "In11.Cu")
		(net "FM_SLP_SUS_N")
	)
	(segment
		(start 376.974354 -93.23578)
		(end 376.643646 -93.23578)
		(width 0.089408)
		(layer "In11.Cu")
		(net "FM_SLP_SUS_N")
	)
	(segment
		(start 373.801894 -81.508854)
		(end 373.801894 -81.214722)
		(width 0.089408)
		(layer "In11.Cu")
		(net "FM_SLP_SUS_N")
	)
	(segment
		(start 376.3772 -92.969334)
		(end 376.3772 -89.814146)
		(width 0.089408)
		(layer "In11.Cu")
		(net "FM_SLP_SUS_N")
	)
	(segment
		(start 372.263162 -71.095108)
		(end 371.945154 -71.095108)
		(width 0.089408)
		(layer "In11.Cu")
		(net "FM_SLP_SUS_N")
	)
	(segment
		(start 375.2088 -88.645746)
		(end 375.2088 -82.91576)
		(width 0.089408)
		(layer "In11.Cu")
		(net "FM_SLP_SUS_N")
	)
	(segment
		(start 378.14504 -93.230446)
		(end 376.979688 -93.230446)
		(width 0.089408)
		(layer "In11.Cu")
		(net "FM_SLP_SUS_N")
	)
	(segment
		(start 367.945162 -77.494892)
		(end 368.344958 -77.095096)
		(width 0.1016)
		(layer "F.Cu")
		(net "FM_CPU1_PROC_ID1")
	)
	(segment
		(start 80.626712 -89.765886)
		(end 80.055212 -89.765886)
		(width 0.10795)
		(layer "F.Cu")
		(net "FM_CPU1_PROC_ID1")
	)
	(via
		(at 367.945162 -77.494892)
		(size 0.4572)
		(drill 0.2032)
		(layers "F.Cu" "B.Cu")
		(net "FM_CPU1_PROC_ID1")
	)
	(via
		(at 67.9196 -92.5576)
		(size 0.6604)
		(drill 0.3302)
		(layers "F.Cu" "B.Cu")
		(net "FM_CPU1_PROC_ID1")
	)
	(via
		(at 326.4916 -142.494)
		(size 0.508)
		(drill 0.254)
		(layers "F.Cu" "B.Cu")
		(net "FM_CPU1_PROC_ID1")
	)
	(via
		(at 80.055212 -89.765886)
		(size 0.508)
		(drill 0.254)
		(layers "F.Cu" "B.Cu")
		(net "FM_CPU1_PROC_ID1")
	)
	(segment
		(start 76.256388 -92.328238)
		(end 76.986384 -92.328238)
		(width 0.10795)
		(layer "B.Cu")
		(net "FM_CPU1_PROC_ID1")
	)
	(segment
		(start 79.645764 -90.175334)
		(end 80.055212 -89.765886)
		(width 0.10795)
		(layer "B.Cu")
		(net "FM_CPU1_PROC_ID1")
	)
	(segment
		(start 77.649578 -92.652088)
		(end 77.973428 -92.328238)
		(width 0.10795)
		(layer "B.Cu")
		(net "FM_CPU1_PROC_ID1")
	)
	(segment
		(start 71.835264 -92.328238)
		(end 72.159114 -92.652088)
		(width 0.10795)
		(layer "B.Cu")
		(net "FM_CPU1_PROC_ID1")
	)
	(segment
		(start 74.734674 -92.328238)
		(end 75.269344 -92.328238)
		(width 0.10795)
		(layer "B.Cu")
		(net "FM_CPU1_PROC_ID1")
	)
	(segment
		(start 73.876154 -92.652088)
		(end 74.410824 -92.652088)
		(width 0.10795)
		(layer "B.Cu")
		(net "FM_CPU1_PROC_ID1")
	)
	(segment
		(start 67.9196 -92.5576)
		(end 68.4022 -92.5576)
		(width 0.10795)
		(layer "B.Cu")
		(net "FM_CPU1_PROC_ID1")
	)
	(segment
		(start 79.025496 -91.661488)
		(end 79.366364 -91.661488)
		(width 0.10795)
		(layer "B.Cu")
		(net "FM_CPU1_PROC_ID1")
	)
	(segment
		(start 71.300594 -92.328238)
		(end 71.835264 -92.328238)
		(width 0.10795)
		(layer "B.Cu")
		(net "FM_CPU1_PROC_ID1")
	)
	(segment
		(start 70.976744 -92.652088)
		(end 71.300594 -92.328238)
		(width 0.10795)
		(layer "B.Cu")
		(net "FM_CPU1_PROC_ID1")
	)
	(segment
		(start 78.358746 -92.328238)
		(end 79.025496 -91.661488)
		(width 0.10795)
		(layer "B.Cu")
		(net "FM_CPU1_PROC_ID1")
	)
	(segment
		(start 66.6496 -92.5576)
		(end 67.9196 -92.5576)
		(width 0.10795)
		(layer "B.Cu")
		(net "FM_CPU1_PROC_ID1")
	)
	(segment
		(start 75.593194 -92.652088)
		(end 75.932538 -92.652088)
		(width 0.10795)
		(layer "B.Cu")
		(net "FM_CPU1_PROC_ID1")
	)
	(segment
		(start 75.932538 -92.652088)
		(end 76.256388 -92.328238)
		(width 0.10795)
		(layer "B.Cu")
		(net "FM_CPU1_PROC_ID1")
	)
	(segment
		(start 72.159114 -92.652088)
		(end 72.693784 -92.652088)
		(width 0.10795)
		(layer "B.Cu")
		(net "FM_CPU1_PROC_ID1")
	)
	(segment
		(start 76.986384 -92.328238)
		(end 77.310234 -92.652088)
		(width 0.10795)
		(layer "B.Cu")
		(net "FM_CPU1_PROC_ID1")
	)
	(segment
		(start 73.552304 -92.328238)
		(end 73.876154 -92.652088)
		(width 0.10795)
		(layer "B.Cu")
		(net "FM_CPU1_PROC_ID1")
	)
	(segment
		(start 77.310234 -92.652088)
		(end 77.649578 -92.652088)
		(width 0.10795)
		(layer "B.Cu")
		(net "FM_CPU1_PROC_ID1")
	)
	(segment
		(start 73.017634 -92.328238)
		(end 73.552304 -92.328238)
		(width 0.10795)
		(layer "B.Cu")
		(net "FM_CPU1_PROC_ID1")
	)
	(segment
		(start 70.442074 -92.652088)
		(end 70.976744 -92.652088)
		(width 0.10795)
		(layer "B.Cu")
		(net "FM_CPU1_PROC_ID1")
	)
	(segment
		(start 68.4022 -92.5576)
		(end 68.631562 -92.328238)
		(width 0.10795)
		(layer "B.Cu")
		(net "FM_CPU1_PROC_ID1")
	)
	(segment
		(start 75.269344 -92.328238)
		(end 75.593194 -92.652088)
		(width 0.10795)
		(layer "B.Cu")
		(net "FM_CPU1_PROC_ID1")
	)
	(segment
		(start 79.366364 -91.661488)
		(end 79.645764 -91.382088)
		(width 0.10795)
		(layer "B.Cu")
		(net "FM_CPU1_PROC_ID1")
	)
	(segment
		(start 77.973428 -92.328238)
		(end 78.358746 -92.328238)
		(width 0.10795)
		(layer "B.Cu")
		(net "FM_CPU1_PROC_ID1")
	)
	(segment
		(start 74.410824 -92.652088)
		(end 74.734674 -92.328238)
		(width 0.10795)
		(layer "B.Cu")
		(net "FM_CPU1_PROC_ID1")
	)
	(segment
		(start 66.04 -93.1672)
		(end 66.6496 -92.5576)
		(width 0.10795)
		(layer "B.Cu")
		(net "FM_CPU1_PROC_ID1")
	)
	(segment
		(start 63.9318 -93.1672)
		(end 66.04 -93.1672)
		(width 0.10795)
		(layer "B.Cu")
		(net "FM_CPU1_PROC_ID1")
	)
	(segment
		(start 72.693784 -92.652088)
		(end 73.017634 -92.328238)
		(width 0.10795)
		(layer "B.Cu")
		(net "FM_CPU1_PROC_ID1")
	)
	(segment
		(start 70.118224 -92.328238)
		(end 70.442074 -92.652088)
		(width 0.10795)
		(layer "B.Cu")
		(net "FM_CPU1_PROC_ID1")
	)
	(segment
		(start 68.631562 -92.328238)
		(end 70.118224 -92.328238)
		(width 0.10795)
		(layer "B.Cu")
		(net "FM_CPU1_PROC_ID1")
	)
	(segment
		(start 79.645764 -91.382088)
		(end 79.645764 -90.175334)
		(width 0.10795)
		(layer "B.Cu")
		(net "FM_CPU1_PROC_ID1")
	)
	(segment
		(start 366.718342 -75.995784)
		(end 367.04397 -76.321412)
		(width 0.089408)
		(layer "In4.Cu")
		(net "FM_CPU1_PROC_ID1")
	)
	(segment
		(start 326.934322 -142.051278)
		(end 327.77684 -142.051278)
		(width 0.089408)
		(layer "In4.Cu")
		(net "FM_CPU1_PROC_ID1")
	)
	(segment
		(start 345.61653 -71.716392)
		(end 346.401898 -70.931024)
		(width 0.089408)
		(layer "In4.Cu")
		(net "FM_CPU1_PROC_ID1")
	)
	(segment
		(start 331.949552 -129.422652)
		(end 328.478388 -125.951488)
		(width 0.089408)
		(layer "In4.Cu")
		(net "FM_CPU1_PROC_ID1")
	)
	(segment
		(start 336.269076 -78.71968)
		(end 337.23453 -77.754226)
		(width 0.089408)
		(layer "In4.Cu")
		(net "FM_CPU1_PROC_ID1")
	)
	(segment
		(start 328.562208 -112.753902)
		(end 327.661778 -111.853472)
		(width 0.089408)
		(layer "In4.Cu")
		(net "FM_CPU1_PROC_ID1")
	)
	(segment
		(start 327.661778 -111.853472)
		(end 327.661778 -91.6178)
		(width 0.089408)
		(layer "In4.Cu")
		(net "FM_CPU1_PROC_ID1")
	)
	(segment
		(start 331.1906 -135.619744)
		(end 331.949552 -134.860792)
		(width 0.089408)
		(layer "In4.Cu")
		(net "FM_CPU1_PROC_ID1")
	)
	(segment
		(start 367.518696 -76.540106)
		(end 367.518696 -77.068426)
		(width 0.089408)
		(layer "In4.Cu")
		(net "FM_CPU1_PROC_ID1")
	)
	(segment
		(start 354.727002 -70.5485)
		(end 357.160068 -70.5485)
		(width 0.089408)
		(layer "In4.Cu")
		(net "FM_CPU1_PROC_ID1")
	)
	(segment
		(start 337.23453 -77.754226)
		(end 337.23453 -74.45756)
		(width 0.089408)
		(layer "In4.Cu")
		(net "FM_CPU1_PROC_ID1")
	)
	(segment
		(start 367.04397 -76.321412)
		(end 367.300002 -76.321412)
		(width 0.089408)
		(layer "In4.Cu")
		(net "FM_CPU1_PROC_ID1")
	)
	(segment
		(start 352.308922 -71.12635)
		(end 354.149152 -71.12635)
		(width 0.089408)
		(layer "In4.Cu")
		(net "FM_CPU1_PROC_ID1")
	)
	(segment
		(start 327.77684 -142.051278)
		(end 328.874374 -140.953744)
		(width 0.089408)
		(layer "In4.Cu")
		(net "FM_CPU1_PROC_ID1")
	)
	(segment
		(start 333.283814 -85.995764)
		(end 333.283814 -82.80146)
		(width 0.089408)
		(layer "In4.Cu")
		(net "FM_CPU1_PROC_ID1")
	)
	(segment
		(start 337.23453 -74.45756)
		(end 338.315554 -73.376536)
		(width 0.089408)
		(layer "In4.Cu")
		(net "FM_CPU1_PROC_ID1")
	)
	(segment
		(start 366.718342 -75.466702)
		(end 366.718342 -75.995784)
		(width 0.089408)
		(layer "In4.Cu")
		(net "FM_CPU1_PROC_ID1")
	)
	(segment
		(start 336.269076 -79.816198)
		(end 336.269076 -78.71968)
		(width 0.089408)
		(layer "In4.Cu")
		(net "FM_CPU1_PROC_ID1")
	)
	(segment
		(start 367.300002 -76.321412)
		(end 367.518696 -76.540106)
		(width 0.089408)
		(layer "In4.Cu")
		(net "FM_CPU1_PROC_ID1")
	)
	(segment
		(start 331.949552 -134.860792)
		(end 331.949552 -129.422652)
		(width 0.089408)
		(layer "In4.Cu")
		(net "FM_CPU1_PROC_ID1")
	)
	(segment
		(start 333.283814 -82.80146)
		(end 336.269076 -79.816198)
		(width 0.089408)
		(layer "In4.Cu")
		(net "FM_CPU1_PROC_ID1")
	)
	(segment
		(start 357.160068 -70.5485)
		(end 358.389428 -71.77786)
		(width 0.089408)
		(layer "In4.Cu")
		(net "FM_CPU1_PROC_ID1")
	)
	(segment
		(start 367.518696 -77.068426)
		(end 367.945162 -77.494892)
		(width 0.089408)
		(layer "In4.Cu")
		(net "FM_CPU1_PROC_ID1")
	)
	(segment
		(start 328.562208 -124.450348)
		(end 328.562208 -112.753902)
		(width 0.089408)
		(layer "In4.Cu")
		(net "FM_CPU1_PROC_ID1")
	)
	(segment
		(start 328.478388 -124.534168)
		(end 328.562208 -124.450348)
		(width 0.089408)
		(layer "In4.Cu")
		(net "FM_CPU1_PROC_ID1")
	)
	(segment
		(start 338.315554 -73.376536)
		(end 339.551264 -73.376536)
		(width 0.089408)
		(layer "In4.Cu")
		(net "FM_CPU1_PROC_ID1")
	)
	(segment
		(start 331.1906 -137.17905)
		(end 331.1906 -135.619744)
		(width 0.089408)
		(layer "In4.Cu")
		(net "FM_CPU1_PROC_ID1")
	)
	(segment
		(start 341.211408 -71.716392)
		(end 345.61653 -71.716392)
		(width 0.089408)
		(layer "In4.Cu")
		(net "FM_CPU1_PROC_ID1")
	)
	(segment
		(start 328.874374 -139.495276)
		(end 331.1906 -137.17905)
		(width 0.089408)
		(layer "In4.Cu")
		(net "FM_CPU1_PROC_ID1")
	)
	(segment
		(start 352.113596 -70.931024)
		(end 352.308922 -71.12635)
		(width 0.089408)
		(layer "In4.Cu")
		(net "FM_CPU1_PROC_ID1")
	)
	(segment
		(start 358.389428 -71.77786)
		(end 363.0295 -71.77786)
		(width 0.089408)
		(layer "In4.Cu")
		(net "FM_CPU1_PROC_ID1")
	)
	(segment
		(start 327.661778 -91.6178)
		(end 333.283814 -85.995764)
		(width 0.089408)
		(layer "In4.Cu")
		(net "FM_CPU1_PROC_ID1")
	)
	(segment
		(start 328.478388 -125.951488)
		(end 328.478388 -124.534168)
		(width 0.089408)
		(layer "In4.Cu")
		(net "FM_CPU1_PROC_ID1")
	)
	(segment
		(start 346.401898 -70.931024)
		(end 352.113596 -70.931024)
		(width 0.089408)
		(layer "In4.Cu")
		(net "FM_CPU1_PROC_ID1")
	)
	(segment
		(start 326.4916 -142.494)
		(end 326.934322 -142.051278)
		(width 0.089408)
		(layer "In4.Cu")
		(net "FM_CPU1_PROC_ID1")
	)
	(segment
		(start 363.0295 -71.77786)
		(end 366.718342 -75.466702)
		(width 0.089408)
		(layer "In4.Cu")
		(net "FM_CPU1_PROC_ID1")
	)
	(segment
		(start 354.149152 -71.12635)
		(end 354.727002 -70.5485)
		(width 0.089408)
		(layer "In4.Cu")
		(net "FM_CPU1_PROC_ID1")
	)
	(segment
		(start 339.551264 -73.376536)
		(end 341.211408 -71.716392)
		(width 0.089408)
		(layer "In4.Cu")
		(net "FM_CPU1_PROC_ID1")
	)
	(segment
		(start 328.874374 -140.953744)
		(end 328.874374 -139.495276)
		(width 0.089408)
		(layer "In4.Cu")
		(net "FM_CPU1_PROC_ID1")
	)
	(segment
		(start 184.877964 -148.340318)
		(end 172.465238 -148.340318)
		(width 0.089408)
		(layer "In11.Cu")
		(net "FM_CPU1_PROC_ID1")
	)
	(segment
		(start 79.655416 -86.234016)
		(end 79.655416 -89.36609)
		(width 0.089408)
		(layer "In11.Cu")
		(net "FM_CPU1_PROC_ID1")
	)
	(segment
		(start 36.30803 -104.703118)
		(end 37.86886 -103.142288)
		(width 0.089408)
		(layer "In11.Cu")
		(net "FM_CPU1_PROC_ID1")
	)
	(segment
		(start 165.29939 -147.782788)
		(end 164.953188 -148.12899)
		(width 0.089408)
		(layer "In11.Cu")
		(net "FM_CPU1_PROC_ID1")
	)
	(segment
		(start 67.530218 -83.91906)
		(end 67.833494 -84.222336)
		(width 0.089408)
		(layer "In11.Cu")
		(net "FM_CPU1_PROC_ID1")
	)
	(segment
		(start 165.038024 -150.7998)
		(end 163.78936 -152.048464)
		(width 0.089408)
		(layer "In11.Cu")
		(net "FM_CPU1_PROC_ID1")
	)
	(segment
		(start 37.86886 -102.259892)
		(end 40.9321 -99.196652)
		(width 0.089408)
		(layer "In11.Cu")
		(net "FM_CPU1_PROC_ID1")
	)
	(segment
		(start 326.4916 -142.494)
		(end 324.89013 -144.09547)
		(width 0.089408)
		(layer "In11.Cu")
		(net "FM_CPU1_PROC_ID1")
	)
	(segment
		(start 49.880012 -93.958156)
		(end 49.880012 -93.833442)
		(width 0.089408)
		(layer "In11.Cu")
		(net "FM_CPU1_PROC_ID1")
	)
	(segment
		(start 73.169526 -81.250536)
		(end 73.202292 -81.250536)
		(width 0.0889)
		(layer "In11.Cu")
		(net "FM_CPU1_PROC_ID1")
	)
	(segment
		(start 47.65802 -96.180148)
		(end 49.880012 -93.958156)
		(width 0.089408)
		(layer "In11.Cu")
		(net "FM_CPU1_PROC_ID1")
	)
	(segment
		(start 324.89013 -149.455124)
		(end 324.330568 -150.014686)
		(width 0.089408)
		(layer "In11.Cu")
		(net "FM_CPU1_PROC_ID1")
	)
	(segment
		(start 43.899836 -97.244662)
		(end 44.96435 -96.180148)
		(width 0.089408)
		(layer "In11.Cu")
		(net "FM_CPU1_PROC_ID1")
	)
	(segment
		(start 265.521186 -157.49016)
		(end 265.51509 -157.49016)
		(width 0.089408)
		(layer "In11.Cu")
		(net "FM_CPU1_PROC_ID1")
	)
	(segment
		(start 186.79287 -150.255224)
		(end 184.877964 -148.340318)
		(width 0.089408)
		(layer "In11.Cu")
		(net "FM_CPU1_PROC_ID1")
	)
	(segment
		(start 78.9432 -84.679282)
		(end 78.9432 -85.5218)
		(width 0.0889)
		(layer "In11.Cu")
		(net "FM_CPU1_PROC_ID1")
	)
	(segment
		(start 75.75169 -81.74609)
		(end 75.784456 -81.74609)
		(width 0.0889)
		(layer "In11.Cu")
		(net "FM_CPU1_PROC_ID1")
	)
	(segment
		(start 186.79287 -155.158186)
		(end 186.79287 -150.255224)
		(width 0.089408)
		(layer "In11.Cu")
		(net "FM_CPU1_PROC_ID1")
	)
	(segment
		(start 36.30803 -107.458764)
		(end 36.30803 -104.703118)
		(width 0.089408)
		(layer "In11.Cu")
		(net "FM_CPU1_PROC_ID1")
	)
	(segment
		(start 28.400756 -130.76682)
		(end 28.591764 -130.575812)
		(width 0.089408)
		(layer "In11.Cu")
		(net "FM_CPU1_PROC_ID1")
	)
	(segment
		(start 265.48588 -157.517084)
		(end 265.386312 -157.616652)
		(width 0.089408)
		(layer "In11.Cu")
		(net "FM_CPU1_PROC_ID1")
	)
	(segment
		(start 70.590156 -82.73669)
		(end 70.622922 -82.73669)
		(width 0.0889)
		(layer "In11.Cu")
		(net "FM_CPU1_PROC_ID1")
	)
	(segment
		(start 78.32598 -83.231736)
		(end 78.355952 -83.231736)
		(width 0.0889)
		(layer "In11.Cu")
		(net "FM_CPU1_PROC_ID1")
	)
	(segment
		(start 66.1924 -84.49056)
		(end 66.7639 -83.91906)
		(width 0.089408)
		(layer "In11.Cu")
		(net "FM_CPU1_PROC_ID1")
	)
	(segment
		(start 49.880012 -93.833442)
		(end 50.47107 -93.242384)
		(width 0.089408)
		(layer "In11.Cu")
		(net "FM_CPU1_PROC_ID1")
	)
	(segment
		(start 61.665104 -84.49056)
		(end 66.1924 -84.49056)
		(width 0.089408)
		(layer "In11.Cu")
		(net "FM_CPU1_PROC_ID1")
	)
	(segment
		(start 74.024236 -80.75549)
		(end 74.067416 -80.75549)
		(width 0.0889)
		(layer "In11.Cu")
		(net "FM_CPU1_PROC_ID1")
	)
	(segment
		(start 321.694302 -157.403038)
		(end 265.608308 -157.403038)
		(width 0.089408)
		(layer "In11.Cu")
		(net "FM_CPU1_PROC_ID1")
	)
	(segment
		(start 33.687258 -109.597952)
		(end 34.169096 -109.597952)
		(width 0.089408)
		(layer "In11.Cu")
		(net "FM_CPU1_PROC_ID1")
	)
	(segment
		(start 324.330568 -150.014686)
		(end 324.330568 -154.766772)
		(width 0.089408)
		(layer "In11.Cu")
		(net "FM_CPU1_PROC_ID1")
	)
	(segment
		(start 265.608308 -157.403038)
		(end 265.521186 -157.49016)
		(width 0.089408)
		(layer "In11.Cu")
		(net "FM_CPU1_PROC_ID1")
	)
	(segment
		(start 40.9321 -99.196652)
		(end 43.626786 -99.196652)
		(width 0.089408)
		(layer "In11.Cu")
		(net "FM_CPU1_PROC_ID1")
	)
	(segment
		(start 72.307196 -81.74609)
		(end 72.339962 -81.74609)
		(width 0.0889)
		(layer "In11.Cu")
		(net "FM_CPU1_PROC_ID1")
	)
	(segment
		(start 43.899836 -98.923602)
		(end 43.899836 -97.244662)
		(width 0.089408)
		(layer "In11.Cu")
		(net "FM_CPU1_PROC_ID1")
	)
	(segment
		(start 28.591764 -128.040384)
		(end 29.321252 -127.310896)
		(width 0.089408)
		(layer "In11.Cu")
		(net "FM_CPU1_PROC_ID1")
	)
	(segment
		(start 77.46873 -82.73669)
		(end 77.501496 -82.73669)
		(width 0.0889)
		(layer "In11.Cu")
		(net "FM_CPU1_PROC_ID1")
	)
	(segment
		(start 50.47107 -93.242384)
		(end 52.91328 -93.242384)
		(width 0.089408)
		(layer "In11.Cu")
		(net "FM_CPU1_PROC_ID1")
	)
	(segment
		(start 28.286456 -132.257038)
		(end 28.400756 -132.142738)
		(width 0.089408)
		(layer "In11.Cu")
		(net "FM_CPU1_PROC_ID1")
	)
	(segment
		(start 165.038024 -149.671024)
		(end 165.038024 -150.7998)
		(width 0.089408)
		(layer "In11.Cu")
		(net "FM_CPU1_PROC_ID1")
	)
	(segment
		(start 79.655416 -89.36609)
		(end 80.055212 -89.765886)
		(width 0.089408)
		(layer "In11.Cu")
		(net "FM_CPU1_PROC_ID1")
	)
	(segment
		(start 160.945068 -152.048464)
		(end 157.557724 -155.435808)
		(width 0.089408)
		(layer "In11.Cu")
		(net "FM_CPU1_PROC_ID1")
	)
	(segment
		(start 76.6064 -82.241136)
		(end 76.63434 -82.241136)
		(width 0.0889)
		(layer "In11.Cu")
		(net "FM_CPU1_PROC_ID1")
	)
	(segment
		(start 265.51509 -157.49016)
		(end 265.488166 -157.517084)
		(width 0.089408)
		(layer "In11.Cu")
		(net "FM_CPU1_PROC_ID1")
	)
	(segment
		(start 67.833494 -84.222336)
		(end 68.051172 -84.222336)
		(width 0.0889)
		(layer "In11.Cu")
		(net "FM_CPU1_PROC_ID1")
	)
	(segment
		(start 172.465238 -148.340318)
		(end 171.907708 -147.782788)
		(width 0.089408)
		(layer "In11.Cu")
		(net "FM_CPU1_PROC_ID1")
	)
	(segment
		(start 44.96435 -96.180148)
		(end 47.65802 -96.180148)
		(width 0.089408)
		(layer "In11.Cu")
		(net "FM_CPU1_PROC_ID1")
	)
	(segment
		(start 164.953188 -148.12899)
		(end 164.953188 -149.586188)
		(width 0.089408)
		(layer "In11.Cu")
		(net "FM_CPU1_PROC_ID1")
	)
	(segment
		(start 29.321252 -113.963958)
		(end 33.687258 -109.597952)
		(width 0.089408)
		(layer "In11.Cu")
		(net "FM_CPU1_PROC_ID1")
	)
	(segment
		(start 28.286456 -154.536648)
		(end 28.286456 -132.257038)
		(width 0.089408)
		(layer "In11.Cu")
		(net "FM_CPU1_PROC_ID1")
	)
	(segment
		(start 112.708182 -156.7434)
		(end 112.622584 -156.828998)
		(width 0.089408)
		(layer "In11.Cu")
		(net "FM_CPU1_PROC_ID1")
	)
	(segment
		(start 78.845156 -84.509102)
		(end 78.9432 -84.679282)
		(width 0.0889)
		(layer "In11.Cu")
		(net "FM_CPU1_PROC_ID1")
	)
	(segment
		(start 71.457312 -82.241136)
		(end 71.485252 -82.241136)
		(width 0.0889)
		(layer "In11.Cu")
		(net "FM_CPU1_PROC_ID1")
	)
	(segment
		(start 29.321252 -127.310896)
		(end 29.321252 -113.963958)
		(width 0.089408)
		(layer "In11.Cu")
		(net "FM_CPU1_PROC_ID1")
	)
	(segment
		(start 52.91328 -93.242384)
		(end 61.665104 -84.49056)
		(width 0.089408)
		(layer "In11.Cu")
		(net "FM_CPU1_PROC_ID1")
	)
	(segment
		(start 189.251336 -157.616652)
		(end 186.79287 -155.158186)
		(width 0.089408)
		(layer "In11.Cu")
		(net "FM_CPU1_PROC_ID1")
	)
	(segment
		(start 163.78936 -152.048464)
		(end 160.945068 -152.048464)
		(width 0.089408)
		(layer "In11.Cu")
		(net "FM_CPU1_PROC_ID1")
	)
	(segment
		(start 28.400756 -132.142738)
		(end 28.400756 -130.76682)
		(width 0.089408)
		(layer "In11.Cu")
		(net "FM_CPU1_PROC_ID1")
	)
	(segment
		(start 164.953188 -149.586188)
		(end 165.038024 -149.671024)
		(width 0.089408)
		(layer "In11.Cu")
		(net "FM_CPU1_PROC_ID1")
	)
	(segment
		(start 78.9432 -85.5218)
		(end 79.655416 -86.234016)
		(width 0.089408)
		(layer "In11.Cu")
		(net "FM_CPU1_PROC_ID1")
	)
	(segment
		(start 171.907708 -147.782788)
		(end 165.29939 -147.782788)
		(width 0.089408)
		(layer "In11.Cu")
		(net "FM_CPU1_PROC_ID1")
	)
	(segment
		(start 34.169096 -109.597952)
		(end 36.30803 -107.458764)
		(width 0.089408)
		(layer "In11.Cu")
		(net "FM_CPU1_PROC_ID1")
	)
	(segment
		(start 324.330568 -154.766772)
		(end 321.694302 -157.403038)
		(width 0.089408)
		(layer "In11.Cu")
		(net "FM_CPU1_PROC_ID1")
	)
	(segment
		(start 43.626786 -99.196652)
		(end 43.899836 -98.923602)
		(width 0.089408)
		(layer "In11.Cu")
		(net "FM_CPU1_PROC_ID1")
	)
	(segment
		(start 157.557724 -155.435808)
		(end 157.557724 -155.783534)
		(width 0.089408)
		(layer "In11.Cu")
		(net "FM_CPU1_PROC_ID1")
	)
	(segment
		(start 112.622584 -156.828998)
		(end 30.578806 -156.828998)
		(width 0.089408)
		(layer "In11.Cu")
		(net "FM_CPU1_PROC_ID1")
	)
	(segment
		(start 69.735446 -83.231736)
		(end 69.77126 -83.231736)
		(width 0.0889)
		(layer "In11.Cu")
		(net "FM_CPU1_PROC_ID1")
	)
	(segment
		(start 68.873116 -83.72729)
		(end 68.905882 -83.72729)
		(width 0.0889)
		(layer "In11.Cu")
		(net "FM_CPU1_PROC_ID1")
	)
	(segment
		(start 324.89013 -144.09547)
		(end 324.89013 -149.455124)
		(width 0.089408)
		(layer "In11.Cu")
		(net "FM_CPU1_PROC_ID1")
	)
	(segment
		(start 157.557724 -155.783534)
		(end 156.597858 -156.7434)
		(width 0.089408)
		(layer "In11.Cu")
		(net "FM_CPU1_PROC_ID1")
	)
	(segment
		(start 265.488166 -157.517084)
		(end 265.48588 -157.517084)
		(width 0.089408)
		(layer "In11.Cu")
		(net "FM_CPU1_PROC_ID1")
	)
	(segment
		(start 28.591764 -130.575812)
		(end 28.591764 -128.040384)
		(width 0.089408)
		(layer "In11.Cu")
		(net "FM_CPU1_PROC_ID1")
	)
	(segment
		(start 265.386312 -157.616652)
		(end 189.251336 -157.616652)
		(width 0.089408)
		(layer "In11.Cu")
		(net "FM_CPU1_PROC_ID1")
	)
	(segment
		(start 30.578806 -156.828998)
		(end 28.286456 -154.536648)
		(width 0.089408)
		(layer "In11.Cu")
		(net "FM_CPU1_PROC_ID1")
	)
	(segment
		(start 37.86886 -103.142288)
		(end 37.86886 -102.259892)
		(width 0.089408)
		(layer "In11.Cu")
		(net "FM_CPU1_PROC_ID1")
	)
	(segment
		(start 156.597858 -156.7434)
		(end 112.708182 -156.7434)
		(width 0.089408)
		(layer "In11.Cu")
		(net "FM_CPU1_PROC_ID1")
	)
	(segment
		(start 74.88936 -81.250536)
		(end 74.922126 -81.250536)
		(width 0.0889)
		(layer "In11.Cu")
		(net "FM_CPU1_PROC_ID1")
	)
	(segment
		(start 66.7639 -83.91906)
		(end 67.530218 -83.91906)
		(width 0.089408)
		(layer "In11.Cu")
		(net "FM_CPU1_PROC_ID1")
	)
	(arc
		(start 72.675496 -81.545938)
		(mid 72.884104 -81.334006)
		(end 73.169526 -81.250536)
		(width 0.0889)
		(layer "In11.Cu")
		(net "FM_CPU1_PROC_ID1")
	)
	(arc
		(start 75.416156 -81.545938)
		(mid 75.557839 -81.689742)
		(end 75.75169 -81.74609)
		(width 0.0889)
		(layer "In11.Cu")
		(net "FM_CPU1_PROC_ID1")
	)
	(arc
		(start 70.099936 -83.031838)
		(mid 70.30694 -82.820974)
		(end 70.590156 -82.73669)
		(width 0.0889)
		(layer "In11.Cu")
		(net "FM_CPU1_PROC_ID1")
	)
	(arc
		(start 73.202292 -81.250536)
		(mid 73.393934 -81.19337)
		(end 73.534016 -81.050638)
		(width 0.0889)
		(layer "In11.Cu")
		(net "FM_CPU1_PROC_ID1")
	)
	(arc
		(start 77.991716 -83.031838)
		(mid 78.132873 -83.175223)
		(end 78.32598 -83.231736)
		(width 0.0889)
		(layer "In11.Cu")
		(net "FM_CPU1_PROC_ID1")
	)
	(arc
		(start 74.557636 -81.050638)
		(mid 74.697715 -81.193374)
		(end 74.88936 -81.250536)
		(width 0.0889)
		(layer "In11.Cu")
		(net "FM_CPU1_PROC_ID1")
	)
	(arc
		(start 68.382896 -84.022438)
		(mid 68.5899 -83.811574)
		(end 68.873116 -83.72729)
		(width 0.0889)
		(layer "In11.Cu")
		(net "FM_CPU1_PROC_ID1")
	)
	(arc
		(start 68.051172 -84.222336)
		(mid 68.242814 -84.16517)
		(end 68.382896 -84.022438)
		(width 0.0889)
		(layer "In11.Cu")
		(net "FM_CPU1_PROC_ID1")
	)
	(arc
		(start 74.922126 -81.250536)
		(mid 75.20755 -81.334003)
		(end 75.416156 -81.545938)
		(width 0.0889)
		(layer "In11.Cu")
		(net "FM_CPU1_PROC_ID1")
	)
	(arc
		(start 78.849982 -84.117688)
		(mid 78.796512 -84.312751)
		(end 78.845156 -84.509102)
		(width 0.0889)
		(layer "In11.Cu")
		(net "FM_CPU1_PROC_ID1")
	)
	(arc
		(start 70.622922 -82.73669)
		(mid 70.816772 -82.68034)
		(end 70.958456 -82.536538)
		(width 0.0889)
		(layer "In11.Cu")
		(net "FM_CPU1_PROC_ID1")
	)
	(arc
		(start 77.133196 -82.536538)
		(mid 77.274879 -82.680342)
		(end 77.46873 -82.73669)
		(width 0.0889)
		(layer "In11.Cu")
		(net "FM_CPU1_PROC_ID1")
	)
	(arc
		(start 77.501496 -82.73669)
		(mid 77.784713 -82.820971)
		(end 77.991716 -83.031838)
		(width 0.0889)
		(layer "In11.Cu")
		(net "FM_CPU1_PROC_ID1")
	)
	(arc
		(start 69.241416 -83.527138)
		(mid 69.450024 -83.315206)
		(end 69.735446 -83.231736)
		(width 0.0889)
		(layer "In11.Cu")
		(net "FM_CPU1_PROC_ID1")
	)
	(arc
		(start 76.63434 -82.241136)
		(mid 76.922485 -82.323455)
		(end 77.133196 -82.536538)
		(width 0.0889)
		(layer "In11.Cu")
		(net "FM_CPU1_PROC_ID1")
	)
	(arc
		(start 78.355952 -83.231736)
		(mid 78.854203 -83.534576)
		(end 78.849982 -84.117688)
		(width 0.0889)
		(layer "In11.Cu")
		(net "FM_CPU1_PROC_ID1")
	)
	(arc
		(start 71.816976 -82.041238)
		(mid 72.02398 -81.830374)
		(end 72.307196 -81.74609)
		(width 0.0889)
		(layer "In11.Cu")
		(net "FM_CPU1_PROC_ID1")
	)
	(arc
		(start 75.784456 -81.74609)
		(mid 76.067673 -81.830371)
		(end 76.274676 -82.041238)
		(width 0.0889)
		(layer "In11.Cu")
		(net "FM_CPU1_PROC_ID1")
	)
	(arc
		(start 71.485252 -82.241136)
		(mid 71.676894 -82.18397)
		(end 71.816976 -82.041238)
		(width 0.0889)
		(layer "In11.Cu")
		(net "FM_CPU1_PROC_ID1")
	)
	(arc
		(start 70.958456 -82.536538)
		(mid 71.169169 -82.323459)
		(end 71.457312 -82.241136)
		(width 0.0889)
		(layer "In11.Cu")
		(net "FM_CPU1_PROC_ID1")
	)
	(arc
		(start 73.534016 -81.050638)
		(mid 73.74102 -80.839774)
		(end 74.024236 -80.75549)
		(width 0.0889)
		(layer "In11.Cu")
		(net "FM_CPU1_PROC_ID1")
	)
	(arc
		(start 74.067416 -80.75549)
		(mid 74.350633 -80.839771)
		(end 74.557636 -81.050638)
		(width 0.0889)
		(layer "In11.Cu")
		(net "FM_CPU1_PROC_ID1")
	)
	(arc
		(start 72.339962 -81.74609)
		(mid 72.533812 -81.68974)
		(end 72.675496 -81.545938)
		(width 0.0889)
		(layer "In11.Cu")
		(net "FM_CPU1_PROC_ID1")
	)
	(arc
		(start 68.905882 -83.72729)
		(mid 69.099732 -83.67094)
		(end 69.241416 -83.527138)
		(width 0.0889)
		(layer "In11.Cu")
		(net "FM_CPU1_PROC_ID1")
	)
	(arc
		(start 76.274676 -82.041238)
		(mid 76.414755 -82.183974)
		(end 76.6064 -82.241136)
		(width 0.0889)
		(layer "In11.Cu")
		(net "FM_CPU1_PROC_ID1")
	)
	(arc
		(start 69.77126 -83.231736)
		(mid 69.961189 -83.173866)
		(end 70.099936 -83.031838)
		(width 0.0889)
		(layer "In11.Cu")
		(net "FM_CPU1_PROC_ID1")
	)
	(segment
		(start 80.626712 -88.775286)
		(end 80.055212 -88.775286)
		(width 0.10795)
		(layer "F.Cu")
		(net "FM_CPU1_PROC_ID0")
	)
	(segment
		(start 367.145316 -77.494892)
		(end 367.545112 -77.095096)
		(width 0.1016)
		(layer "F.Cu")
		(net "FM_CPU1_PROC_ID0")
	)
	(via
		(at 367.145316 -77.494892)
		(size 0.4572)
		(drill 0.2032)
		(layers "F.Cu" "B.Cu")
		(net "FM_CPU1_PROC_ID0")
	)
	(via
		(at 66.2686 -89.693242)
		(size 0.6604)
		(drill 0.3302)
		(layers "F.Cu" "B.Cu")
		(net "FM_CPU1_PROC_ID0")
	)
	(via
		(at 327.1774 -142.748)
		(size 0.508)
		(drill 0.254)
		(layers "F.Cu" "B.Cu")
		(net "FM_CPU1_PROC_ID0")
	)
	(via
		(at 80.055212 -88.775286)
		(size 0.508)
		(drill 0.254)
		(layers "F.Cu" "B.Cu")
		(net "FM_CPU1_PROC_ID0")
	)
	(segment
		(start 73.545446 -89.356438)
		(end 72.822308 -89.356438)
		(width 0.10795)
		(layer "B.Cu")
		(net "FM_CPU1_PROC_ID0")
	)
	(segment
		(start 80.055212 -88.775286)
		(end 78.974188 -88.775286)
		(width 0.10795)
		(layer "B.Cu")
		(net "FM_CPU1_PROC_ID0")
	)
	(segment
		(start 70.976744 -89.680288)
		(end 70.442074 -89.680288)
		(width 0.10795)
		(layer "B.Cu")
		(net "FM_CPU1_PROC_ID0")
	)
	(segment
		(start 73.876154 -89.680288)
		(end 73.545446 -89.356438)
		(width 0.10795)
		(layer "B.Cu")
		(net "FM_CPU1_PROC_ID0")
	)
	(segment
		(start 75.393042 -89.4842)
		(end 75.26528 -89.356438)
		(width 0.10795)
		(layer "B.Cu")
		(net "FM_CPU1_PROC_ID0")
	)
	(segment
		(start 76.986384 -89.356438)
		(end 76.451714 -89.356438)
		(width 0.10795)
		(layer "B.Cu")
		(net "FM_CPU1_PROC_ID0")
	)
	(segment
		(start 78.27264 -89.24036)
		(end 77.832712 -89.680288)
		(width 0.10795)
		(layer "B.Cu")
		(net "FM_CPU1_PROC_ID0")
	)
	(segment
		(start 70.114668 -89.356438)
		(end 69.583554 -89.356438)
		(width 0.10795)
		(layer "B.Cu")
		(net "FM_CPU1_PROC_ID0")
	)
	(segment
		(start 67.276472 -89.693242)
		(end 66.2686 -89.693242)
		(width 0.10795)
		(layer "B.Cu")
		(net "FM_CPU1_PROC_ID0")
	)
	(segment
		(start 65.322958 -89.693242)
		(end 65.024 -89.9922)
		(width 0.10795)
		(layer "B.Cu")
		(net "FM_CPU1_PROC_ID0")
	)
	(segment
		(start 74.410824 -89.680288)
		(end 73.876154 -89.680288)
		(width 0.10795)
		(layer "B.Cu")
		(net "FM_CPU1_PROC_ID0")
	)
	(segment
		(start 71.300594 -89.356438)
		(end 70.976744 -89.680288)
		(width 0.10795)
		(layer "B.Cu")
		(net "FM_CPU1_PROC_ID0")
	)
	(segment
		(start 68.725034 -89.680288)
		(end 68.472812 -89.4334)
		(width 0.10795)
		(layer "B.Cu")
		(net "FM_CPU1_PROC_ID0")
	)
	(segment
		(start 69.583554 -89.356438)
		(end 69.259704 -89.680288)
		(width 0.10795)
		(layer "B.Cu")
		(net "FM_CPU1_PROC_ID0")
	)
	(segment
		(start 77.310234 -89.680288)
		(end 76.986384 -89.356438)
		(width 0.10795)
		(layer "B.Cu")
		(net "FM_CPU1_PROC_ID0")
	)
	(segment
		(start 70.442074 -89.680288)
		(end 70.26783 -89.5096)
		(width 0.10795)
		(layer "B.Cu")
		(net "FM_CPU1_PROC_ID0")
	)
	(segment
		(start 77.832712 -89.680288)
		(end 77.310234 -89.680288)
		(width 0.10795)
		(layer "B.Cu")
		(net "FM_CPU1_PROC_ID0")
	)
	(segment
		(start 76.127864 -89.680288)
		(end 75.593194 -89.680288)
		(width 0.10795)
		(layer "B.Cu")
		(net "FM_CPU1_PROC_ID0")
	)
	(segment
		(start 68.472812 -89.4334)
		(end 68.39585 -89.356438)
		(width 0.10795)
		(layer "B.Cu")
		(net "FM_CPU1_PROC_ID0")
	)
	(segment
		(start 78.974188 -88.775286)
		(end 78.509114 -89.24036)
		(width 0.10795)
		(layer "B.Cu")
		(net "FM_CPU1_PROC_ID0")
	)
	(segment
		(start 69.259704 -89.680288)
		(end 68.725034 -89.680288)
		(width 0.10795)
		(layer "B.Cu")
		(net "FM_CPU1_PROC_ID0")
	)
	(segment
		(start 66.2686 -89.693242)
		(end 65.322958 -89.693242)
		(width 0.10795)
		(layer "B.Cu")
		(net "FM_CPU1_PROC_ID0")
	)
	(segment
		(start 70.26783 -89.5096)
		(end 70.114668 -89.356438)
		(width 0.10795)
		(layer "B.Cu")
		(net "FM_CPU1_PROC_ID0")
	)
	(segment
		(start 75.593194 -89.680288)
		(end 75.393042 -89.4842)
		(width 0.10795)
		(layer "B.Cu")
		(net "FM_CPU1_PROC_ID0")
	)
	(segment
		(start 74.734674 -89.356438)
		(end 74.410824 -89.680288)
		(width 0.10795)
		(layer "B.Cu")
		(net "FM_CPU1_PROC_ID0")
	)
	(segment
		(start 72.010778 -89.535)
		(end 71.832216 -89.356438)
		(width 0.10795)
		(layer "B.Cu")
		(net "FM_CPU1_PROC_ID0")
	)
	(segment
		(start 71.832216 -89.356438)
		(end 71.300594 -89.356438)
		(width 0.10795)
		(layer "B.Cu")
		(net "FM_CPU1_PROC_ID0")
	)
	(segment
		(start 67.613276 -89.356438)
		(end 67.276472 -89.693242)
		(width 0.10795)
		(layer "B.Cu")
		(net "FM_CPU1_PROC_ID0")
	)
	(segment
		(start 72.159114 -89.680288)
		(end 72.010778 -89.535)
		(width 0.10795)
		(layer "B.Cu")
		(net "FM_CPU1_PROC_ID0")
	)
	(segment
		(start 78.509114 -89.24036)
		(end 78.27264 -89.24036)
		(width 0.10795)
		(layer "B.Cu")
		(net "FM_CPU1_PROC_ID0")
	)
	(segment
		(start 68.39585 -89.356438)
		(end 67.613276 -89.356438)
		(width 0.10795)
		(layer "B.Cu")
		(net "FM_CPU1_PROC_ID0")
	)
	(segment
		(start 76.451714 -89.356438)
		(end 76.127864 -89.680288)
		(width 0.10795)
		(layer "B.Cu")
		(net "FM_CPU1_PROC_ID0")
	)
	(segment
		(start 72.498458 -89.680288)
		(end 72.159114 -89.680288)
		(width 0.10795)
		(layer "B.Cu")
		(net "FM_CPU1_PROC_ID0")
	)
	(segment
		(start 75.26528 -89.356438)
		(end 74.734674 -89.356438)
		(width 0.10795)
		(layer "B.Cu")
		(net "FM_CPU1_PROC_ID0")
	)
	(segment
		(start 65.024 -89.9922)
		(end 64.1858 -89.9922)
		(width 0.10795)
		(layer "B.Cu")
		(net "FM_CPU1_PROC_ID0")
	)
	(segment
		(start 72.822308 -89.356438)
		(end 72.498458 -89.680288)
		(width 0.10795)
		(layer "B.Cu")
		(net "FM_CPU1_PROC_ID0")
	)
	(segment
		(start 365.93272 -76.01077)
		(end 366.243616 -76.321666)
		(width 0.089408)
		(layer "In4.Cu")
		(net "FM_CPU1_PROC_ID0")
	)
	(segment
		(start 332.23835 -138.80465)
		(end 333.0829 -137.9601)
		(width 0.089408)
		(layer "In4.Cu")
		(net "FM_CPU1_PROC_ID0")
	)
	(segment
		(start 362.950252 -71.968868)
		(end 365.93272 -74.951336)
		(width 0.089408)
		(layer "In4.Cu")
		(net "FM_CPU1_PROC_ID0")
	)
	(segment
		(start 333.615792 -132.16636)
		(end 334.1878 -131.594352)
		(width 0.089408)
		(layer "In4.Cu")
		(net "FM_CPU1_PROC_ID0")
	)
	(segment
		(start 337.425538 -77.833474)
		(end 337.425538 -74.536808)
		(width 0.089408)
		(layer "In4.Cu")
		(net "FM_CPU1_PROC_ID0")
	)
	(segment
		(start 354.80625 -70.739508)
		(end 357.08082 -70.739508)
		(width 0.089408)
		(layer "In4.Cu")
		(net "FM_CPU1_PROC_ID0")
	)
	(segment
		(start 352.229674 -71.317358)
		(end 354.2284 -71.317358)
		(width 0.089408)
		(layer "In4.Cu")
		(net "FM_CPU1_PROC_ID0")
	)
	(segment
		(start 327.683114 -142.242286)
		(end 327.856088 -142.242286)
		(width 0.089408)
		(layer "In4.Cu")
		(net "FM_CPU1_PROC_ID0")
	)
	(segment
		(start 339.630512 -73.567544)
		(end 341.290656 -71.9074)
		(width 0.089408)
		(layer "In4.Cu")
		(net "FM_CPU1_PROC_ID0")
	)
	(segment
		(start 365.93272 -74.951336)
		(end 365.93272 -76.01077)
		(width 0.089408)
		(layer "In4.Cu")
		(net "FM_CPU1_PROC_ID0")
	)
	(segment
		(start 329.12685 -140.971524)
		(end 329.12685 -139.65682)
		(width 0.089408)
		(layer "In4.Cu")
		(net "FM_CPU1_PROC_ID0")
	)
	(segment
		(start 336.460084 -79.895446)
		(end 336.460084 -78.798928)
		(width 0.089408)
		(layer "In4.Cu")
		(net "FM_CPU1_PROC_ID0")
	)
	(segment
		(start 329.12685 -139.65682)
		(end 329.97902 -138.80465)
		(width 0.089408)
		(layer "In4.Cu")
		(net "FM_CPU1_PROC_ID0")
	)
	(segment
		(start 334.1878 -129.413)
		(end 330.924154 -126.149354)
		(width 0.089408)
		(layer "In4.Cu")
		(net "FM_CPU1_PROC_ID0")
	)
	(segment
		(start 352.034348 -71.122032)
		(end 352.229674 -71.317358)
		(width 0.089408)
		(layer "In4.Cu")
		(net "FM_CPU1_PROC_ID0")
	)
	(segment
		(start 329.656948 -124.150882)
		(end 328.765916 -123.25985)
		(width 0.089408)
		(layer "In4.Cu")
		(net "FM_CPU1_PROC_ID0")
	)
	(segment
		(start 327.1774 -142.748)
		(end 327.683114 -142.242286)
		(width 0.089408)
		(layer "In4.Cu")
		(net "FM_CPU1_PROC_ID0")
	)
	(segment
		(start 354.2284 -71.317358)
		(end 354.80625 -70.739508)
		(width 0.089408)
		(layer "In4.Cu")
		(net "FM_CPU1_PROC_ID0")
	)
	(segment
		(start 333.474822 -82.880708)
		(end 336.460084 -79.895446)
		(width 0.089408)
		(layer "In4.Cu")
		(net "FM_CPU1_PROC_ID0")
	)
	(segment
		(start 334.1878 -131.594352)
		(end 334.1878 -129.413)
		(width 0.089408)
		(layer "In4.Cu")
		(net "FM_CPU1_PROC_ID0")
	)
	(segment
		(start 357.08082 -70.739508)
		(end 358.31018 -71.968868)
		(width 0.089408)
		(layer "In4.Cu")
		(net "FM_CPU1_PROC_ID0")
	)
	(segment
		(start 341.290656 -71.9074)
		(end 345.696032 -71.9074)
		(width 0.089408)
		(layer "In4.Cu")
		(net "FM_CPU1_PROC_ID0")
	)
	(segment
		(start 330.924154 -126.149354)
		(end 330.924154 -124.829062)
		(width 0.089408)
		(layer "In4.Cu")
		(net "FM_CPU1_PROC_ID0")
	)
	(segment
		(start 327.852786 -111.774224)
		(end 327.852786 -91.697048)
		(width 0.089408)
		(layer "In4.Cu")
		(net "FM_CPU1_PROC_ID0")
	)
	(segment
		(start 366.718342 -77.067918)
		(end 367.145316 -77.494892)
		(width 0.089408)
		(layer "In4.Cu")
		(net "FM_CPU1_PROC_ID0")
	)
	(segment
		(start 328.765916 -123.25985)
		(end 328.765916 -112.687354)
		(width 0.089408)
		(layer "In4.Cu")
		(net "FM_CPU1_PROC_ID0")
	)
	(segment
		(start 333.615792 -135.9916)
		(end 333.615792 -132.16636)
		(width 0.089408)
		(layer "In4.Cu")
		(net "FM_CPU1_PROC_ID0")
	)
	(segment
		(start 333.0829 -137.9601)
		(end 333.0829 -136.524492)
		(width 0.089408)
		(layer "In4.Cu")
		(net "FM_CPU1_PROC_ID0")
	)
	(segment
		(start 366.499648 -76.321666)
		(end 366.718342 -76.54036)
		(width 0.089408)
		(layer "In4.Cu")
		(net "FM_CPU1_PROC_ID0")
	)
	(segment
		(start 358.31018 -71.968868)
		(end 362.950252 -71.968868)
		(width 0.089408)
		(layer "In4.Cu")
		(net "FM_CPU1_PROC_ID0")
	)
	(segment
		(start 330.245974 -124.150882)
		(end 329.656948 -124.150882)
		(width 0.089408)
		(layer "In4.Cu")
		(net "FM_CPU1_PROC_ID0")
	)
	(segment
		(start 366.718342 -76.54036)
		(end 366.718342 -77.067918)
		(width 0.089408)
		(layer "In4.Cu")
		(net "FM_CPU1_PROC_ID0")
	)
	(segment
		(start 328.765916 -112.687354)
		(end 327.852786 -111.774224)
		(width 0.089408)
		(layer "In4.Cu")
		(net "FM_CPU1_PROC_ID0")
	)
	(segment
		(start 366.243616 -76.321666)
		(end 366.499648 -76.321666)
		(width 0.089408)
		(layer "In4.Cu")
		(net "FM_CPU1_PROC_ID0")
	)
	(segment
		(start 336.460084 -78.798928)
		(end 337.425538 -77.833474)
		(width 0.089408)
		(layer "In4.Cu")
		(net "FM_CPU1_PROC_ID0")
	)
	(segment
		(start 345.696032 -71.9074)
		(end 346.4814 -71.122032)
		(width 0.089408)
		(layer "In4.Cu")
		(net "FM_CPU1_PROC_ID0")
	)
	(segment
		(start 329.97902 -138.80465)
		(end 332.23835 -138.80465)
		(width 0.089408)
		(layer "In4.Cu")
		(net "FM_CPU1_PROC_ID0")
	)
	(segment
		(start 327.856088 -142.242286)
		(end 329.12685 -140.971524)
		(width 0.089408)
		(layer "In4.Cu")
		(net "FM_CPU1_PROC_ID0")
	)
	(segment
		(start 338.394802 -73.567544)
		(end 339.630512 -73.567544)
		(width 0.089408)
		(layer "In4.Cu")
		(net "FM_CPU1_PROC_ID0")
	)
	(segment
		(start 330.924154 -124.829062)
		(end 330.245974 -124.150882)
		(width 0.089408)
		(layer "In4.Cu")
		(net "FM_CPU1_PROC_ID0")
	)
	(segment
		(start 333.0829 -136.524492)
		(end 333.615792 -135.9916)
		(width 0.089408)
		(layer "In4.Cu")
		(net "FM_CPU1_PROC_ID0")
	)
	(segment
		(start 327.852786 -91.697048)
		(end 333.474822 -86.075012)
		(width 0.089408)
		(layer "In4.Cu")
		(net "FM_CPU1_PROC_ID0")
	)
	(segment
		(start 333.474822 -86.075012)
		(end 333.474822 -82.880708)
		(width 0.089408)
		(layer "In4.Cu")
		(net "FM_CPU1_PROC_ID0")
	)
	(segment
		(start 346.4814 -71.122032)
		(end 352.034348 -71.122032)
		(width 0.089408)
		(layer "In4.Cu")
		(net "FM_CPU1_PROC_ID0")
	)
	(segment
		(start 337.425538 -74.536808)
		(end 338.394802 -73.567544)
		(width 0.089408)
		(layer "In4.Cu")
		(net "FM_CPU1_PROC_ID0")
	)
	(segment
		(start 186.601608 -155.079192)
		(end 186.601862 -155.078938)
		(width 0.089408)
		(layer "In11.Cu")
		(net "FM_CPU1_PROC_ID0")
	)
	(segment
		(start 324.521576 -150.102824)
		(end 324.521576 -154.84602)
		(width 0.089408)
		(layer "In11.Cu")
		(net "FM_CPU1_PROC_ID0")
	)
	(segment
		(start 36.117022 -104.62387)
		(end 37.66312 -103.077772)
		(width 0.089408)
		(layer "In11.Cu")
		(net "FM_CPU1_PROC_ID0")
	)
	(segment
		(start 40.852852 -99.005644)
		(end 42.734992 -99.005644)
		(width 0.089408)
		(layer "In11.Cu")
		(net "FM_CPU1_PROC_ID0")
	)
	(segment
		(start 33.570418 -109.406944)
		(end 34.089848 -109.406944)
		(width 0.089408)
		(layer "In11.Cu")
		(net "FM_CPU1_PROC_ID0")
	)
	(segment
		(start 76.488036 -81.441036)
		(end 76.78547 -81.441036)
		(width 0.089408)
		(layer "In11.Cu")
		(net "FM_CPU1_PROC_ID0")
	)
	(segment
		(start 325.081138 -149.543262)
		(end 324.521576 -150.102824)
		(width 0.089408)
		(layer "In11.Cu")
		(net "FM_CPU1_PROC_ID0")
	)
	(segment
		(start 165.229032 -149.591776)
		(end 165.229032 -150.879048)
		(width 0.089408)
		(layer "In11.Cu")
		(net "FM_CPU1_PROC_ID0")
	)
	(segment
		(start 61.592968 -84.29244)
		(end 66.04762 -84.29244)
		(width 0.089408)
		(layer "In11.Cu")
		(net "FM_CPU1_PROC_ID0")
	)
	(segment
		(start 75.0824 -80.4418)
		(end 75.4634 -80.8228)
		(width 0.089408)
		(layer "In11.Cu")
		(net "FM_CPU1_PROC_ID0")
	)
	(segment
		(start 265.594338 -157.681168)
		(end 265.567414 -157.708092)
		(width 0.089408)
		(layer "In11.Cu")
		(net "FM_CPU1_PROC_ID0")
	)
	(segment
		(start 327.1774 -142.748)
		(end 326.843898 -142.748)
		(width 0.089408)
		(layer "In11.Cu")
		(net "FM_CPU1_PROC_ID0")
	)
	(segment
		(start 165.378638 -147.973796)
		(end 165.144196 -148.208238)
		(width 0.089408)
		(layer "In11.Cu")
		(net "FM_CPU1_PROC_ID0")
	)
	(segment
		(start 321.77355 -157.594046)
		(end 265.687556 -157.594046)
		(width 0.089408)
		(layer "In11.Cu")
		(net "FM_CPU1_PROC_ID0")
	)
	(segment
		(start 69.1134 -82.9056)
		(end 69.596 -82.423)
		(width 0.089408)
		(layer "In11.Cu")
		(net "FM_CPU1_PROC_ID0")
	)
	(segment
		(start 186.601862 -150.334472)
		(end 184.798716 -148.531326)
		(width 0.089408)
		(layer "In11.Cu")
		(net "FM_CPU1_PROC_ID0")
	)
	(segment
		(start 43.0276 -98.713036)
		(end 43.0276 -97.06737)
		(width 0.089408)
		(layer "In11.Cu")
		(net "FM_CPU1_PROC_ID0")
	)
	(segment
		(start 75.4634 -80.8228)
		(end 75.8698 -80.8228)
		(width 0.089408)
		(layer "In11.Cu")
		(net "FM_CPU1_PROC_ID0")
	)
	(segment
		(start 77.471778 -81.7626)
		(end 78.081378 -82.3722)
		(width 0.089408)
		(layer "In11.Cu")
		(net "FM_CPU1_PROC_ID0")
	)
	(segment
		(start 66.61404 -83.72602)
		(end 67.48018 -83.72602)
		(width 0.089408)
		(layer "In11.Cu")
		(net "FM_CPU1_PROC_ID0")
	)
	(segment
		(start 78.6384 -82.3722)
		(end 79.19339 -82.92719)
		(width 0.089408)
		(layer "In11.Cu")
		(net "FM_CPU1_PROC_ID0")
	)
	(segment
		(start 325.081138 -144.51076)
		(end 325.081138 -149.543262)
		(width 0.089408)
		(layer "In11.Cu")
		(net "FM_CPU1_PROC_ID0")
	)
	(segment
		(start 189.172088 -157.80766)
		(end 186.601608 -155.23718)
		(width 0.089408)
		(layer "In11.Cu")
		(net "FM_CPU1_PROC_ID0")
	)
	(segment
		(start 112.709198 -157.01264)
		(end 112.701832 -157.020006)
		(width 0.089408)
		(layer "In11.Cu")
		(net "FM_CPU1_PROC_ID0")
	)
	(segment
		(start 77.107034 -81.7626)
		(end 77.471778 -81.7626)
		(width 0.089408)
		(layer "In11.Cu")
		(net "FM_CPU1_PROC_ID0")
	)
	(segment
		(start 171.82846 -147.973796)
		(end 165.378638 -147.973796)
		(width 0.089408)
		(layer "In11.Cu")
		(net "FM_CPU1_PROC_ID0")
	)
	(segment
		(start 163.868608 -152.239472)
		(end 161.024316 -152.239472)
		(width 0.089408)
		(layer "In11.Cu")
		(net "FM_CPU1_PROC_ID0")
	)
	(segment
		(start 76.78547 -81.441036)
		(end 77.107034 -81.7626)
		(width 0.089408)
		(layer "In11.Cu")
		(net "FM_CPU1_PROC_ID0")
	)
	(segment
		(start 265.565128 -157.708092)
		(end 265.46556 -157.80766)
		(width 0.089408)
		(layer "In11.Cu")
		(net "FM_CPU1_PROC_ID0")
	)
	(segment
		(start 79.596742 -83.161886)
		(end 79.596742 -85.514942)
		(width 0.089408)
		(layer "In11.Cu")
		(net "FM_CPU1_PROC_ID0")
	)
	(segment
		(start 37.66312 -103.077772)
		(end 37.66312 -102.195376)
		(width 0.089408)
		(layer "In11.Cu")
		(net "FM_CPU1_PROC_ID0")
	)
	(segment
		(start 326.843898 -142.748)
		(end 325.081138 -144.51076)
		(width 0.089408)
		(layer "In11.Cu")
		(net "FM_CPU1_PROC_ID0")
	)
	(segment
		(start 79.362046 -82.92719)
		(end 79.596742 -83.161886)
		(width 0.089408)
		(layer "In11.Cu")
		(net "FM_CPU1_PROC_ID0")
	)
	(segment
		(start 69.85 -82.423)
		(end 70.4342 -81.8388)
		(width 0.089408)
		(layer "In11.Cu")
		(net "FM_CPU1_PROC_ID0")
	)
	(segment
		(start 161.024316 -152.239472)
		(end 157.778196 -155.485592)
		(width 0.089408)
		(layer "In11.Cu")
		(net "FM_CPU1_PROC_ID0")
	)
	(segment
		(start 50.391822 -93.051376)
		(end 52.834032 -93.051376)
		(width 0.089408)
		(layer "In11.Cu")
		(net "FM_CPU1_PROC_ID0")
	)
	(segment
		(start 70.4342 -81.8388)
		(end 70.6882 -81.8388)
		(width 0.089408)
		(layer "In11.Cu")
		(net "FM_CPU1_PROC_ID0")
	)
	(segment
		(start 66.04762 -84.29244)
		(end 66.61404 -83.72602)
		(width 0.089408)
		(layer "In11.Cu")
		(net "FM_CPU1_PROC_ID0")
	)
	(segment
		(start 52.834032 -93.051376)
		(end 61.592968 -84.29244)
		(width 0.089408)
		(layer "In11.Cu")
		(net "FM_CPU1_PROC_ID0")
	)
	(segment
		(start 73.81494 -79.95666)
		(end 74.39406 -79.95666)
		(width 0.089408)
		(layer "In11.Cu")
		(net "FM_CPU1_PROC_ID0")
	)
	(segment
		(start 186.601608 -155.23718)
		(end 186.601608 -155.079192)
		(width 0.089408)
		(layer "In11.Cu")
		(net "FM_CPU1_PROC_ID0")
	)
	(segment
		(start 44.51477 -95.5802)
		(end 47.987712 -95.5802)
		(width 0.089408)
		(layer "In11.Cu")
		(net "FM_CPU1_PROC_ID0")
	)
	(segment
		(start 28.400756 -130.474212)
		(end 28.400756 -127.87122)
		(width 0.089408)
		(layer "In11.Cu")
		(net "FM_CPU1_PROC_ID0")
	)
	(segment
		(start 43.0276 -97.06737)
		(end 44.51477 -95.5802)
		(width 0.089408)
		(layer "In11.Cu")
		(net "FM_CPU1_PROC_ID0")
	)
	(segment
		(start 80.055212 -85.973412)
		(end 80.055212 -88.775286)
		(width 0.089408)
		(layer "In11.Cu")
		(net "FM_CPU1_PROC_ID0")
	)
	(segment
		(start 29.128212 -127.143764)
		(end 29.128212 -113.84915)
		(width 0.089408)
		(layer "In11.Cu")
		(net "FM_CPU1_PROC_ID0")
	)
	(segment
		(start 265.46556 -157.80766)
		(end 189.172088 -157.80766)
		(width 0.089408)
		(layer "In11.Cu")
		(net "FM_CPU1_PROC_ID0")
	)
	(segment
		(start 71.7804 -81.28)
		(end 72.2122 -80.8482)
		(width 0.089408)
		(layer "In11.Cu")
		(net "FM_CPU1_PROC_ID0")
	)
	(segment
		(start 42.734992 -99.005644)
		(end 43.0276 -98.713036)
		(width 0.089408)
		(layer "In11.Cu")
		(net "FM_CPU1_PROC_ID0")
	)
	(segment
		(start 73.4314 -80.3402)
		(end 73.81494 -79.95666)
		(width 0.089408)
		(layer "In11.Cu")
		(net "FM_CPU1_PROC_ID0")
	)
	(segment
		(start 49.689004 -93.878908)
		(end 49.689004 -93.754194)
		(width 0.089408)
		(layer "In11.Cu")
		(net "FM_CPU1_PROC_ID0")
	)
	(segment
		(start 112.701832 -157.020006)
		(end 30.499558 -157.020006)
		(width 0.089408)
		(layer "In11.Cu")
		(net "FM_CPU1_PROC_ID0")
	)
	(segment
		(start 156.598874 -157.01264)
		(end 112.709198 -157.01264)
		(width 0.089408)
		(layer "In11.Cu")
		(net "FM_CPU1_PROC_ID0")
	)
	(segment
		(start 68.3006 -83.3374)
		(end 68.7324 -82.9056)
		(width 0.089408)
		(layer "In11.Cu")
		(net "FM_CPU1_PROC_ID0")
	)
	(segment
		(start 79.596742 -85.514942)
		(end 80.055212 -85.973412)
		(width 0.089408)
		(layer "In11.Cu")
		(net "FM_CPU1_PROC_ID0")
	)
	(segment
		(start 34.089848 -109.406944)
		(end 36.117022 -107.379516)
		(width 0.089408)
		(layer "In11.Cu")
		(net "FM_CPU1_PROC_ID0")
	)
	(segment
		(start 28.095448 -154.615896)
		(end 28.095448 -132.104638)
		(width 0.089408)
		(layer "In11.Cu")
		(net "FM_CPU1_PROC_ID0")
	)
	(segment
		(start 78.081378 -82.3722)
		(end 78.6384 -82.3722)
		(width 0.089408)
		(layer "In11.Cu")
		(net "FM_CPU1_PROC_ID0")
	)
	(segment
		(start 36.117022 -107.379516)
		(end 36.117022 -104.62387)
		(width 0.089408)
		(layer "In11.Cu")
		(net "FM_CPU1_PROC_ID0")
	)
	(segment
		(start 70.6882 -81.8388)
		(end 71.247 -81.28)
		(width 0.089408)
		(layer "In11.Cu")
		(net "FM_CPU1_PROC_ID0")
	)
	(segment
		(start 67.48018 -83.72602)
		(end 67.8688 -83.3374)
		(width 0.089408)
		(layer "In11.Cu")
		(net "FM_CPU1_PROC_ID0")
	)
	(segment
		(start 29.128212 -113.84915)
		(end 33.570418 -109.406944)
		(width 0.089408)
		(layer "In11.Cu")
		(net "FM_CPU1_PROC_ID0")
	)
	(segment
		(start 74.39406 -79.95666)
		(end 74.8792 -80.4418)
		(width 0.089408)
		(layer "In11.Cu")
		(net "FM_CPU1_PROC_ID0")
	)
	(segment
		(start 184.798716 -148.531326)
		(end 172.38599 -148.531326)
		(width 0.089408)
		(layer "In11.Cu")
		(net "FM_CPU1_PROC_ID0")
	)
	(segment
		(start 72.4662 -80.8482)
		(end 72.9742 -80.3402)
		(width 0.089408)
		(layer "In11.Cu")
		(net "FM_CPU1_PROC_ID0")
	)
	(segment
		(start 79.19339 -82.92719)
		(end 79.362046 -82.92719)
		(width 0.089408)
		(layer "In11.Cu")
		(net "FM_CPU1_PROC_ID0")
	)
	(segment
		(start 324.521576 -154.84602)
		(end 321.77355 -157.594046)
		(width 0.089408)
		(layer "In11.Cu")
		(net "FM_CPU1_PROC_ID0")
	)
	(segment
		(start 49.689004 -93.754194)
		(end 50.391822 -93.051376)
		(width 0.089408)
		(layer "In11.Cu")
		(net "FM_CPU1_PROC_ID0")
	)
	(segment
		(start 74.8792 -80.4418)
		(end 75.0824 -80.4418)
		(width 0.089408)
		(layer "In11.Cu")
		(net "FM_CPU1_PROC_ID0")
	)
	(segment
		(start 28.095448 -132.104638)
		(end 28.209748 -131.990338)
		(width 0.089408)
		(layer "In11.Cu")
		(net "FM_CPU1_PROC_ID0")
	)
	(segment
		(start 172.38599 -148.531326)
		(end 171.82846 -147.973796)
		(width 0.089408)
		(layer "In11.Cu")
		(net "FM_CPU1_PROC_ID0")
	)
	(segment
		(start 165.229032 -150.879048)
		(end 163.868608 -152.239472)
		(width 0.089408)
		(layer "In11.Cu")
		(net "FM_CPU1_PROC_ID0")
	)
	(segment
		(start 165.144196 -148.208238)
		(end 165.144196 -149.50694)
		(width 0.089408)
		(layer "In11.Cu")
		(net "FM_CPU1_PROC_ID0")
	)
	(segment
		(start 30.499558 -157.020006)
		(end 28.095448 -154.615896)
		(width 0.089408)
		(layer "In11.Cu")
		(net "FM_CPU1_PROC_ID0")
	)
	(segment
		(start 68.7324 -82.9056)
		(end 69.1134 -82.9056)
		(width 0.089408)
		(layer "In11.Cu")
		(net "FM_CPU1_PROC_ID0")
	)
	(segment
		(start 265.567414 -157.708092)
		(end 265.565128 -157.708092)
		(width 0.089408)
		(layer "In11.Cu")
		(net "FM_CPU1_PROC_ID0")
	)
	(segment
		(start 157.778196 -155.833318)
		(end 156.598874 -157.01264)
		(width 0.089408)
		(layer "In11.Cu")
		(net "FM_CPU1_PROC_ID0")
	)
	(segment
		(start 37.66312 -102.195376)
		(end 40.852852 -99.005644)
		(width 0.089408)
		(layer "In11.Cu")
		(net "FM_CPU1_PROC_ID0")
	)
	(segment
		(start 157.778196 -155.485592)
		(end 157.778196 -155.833318)
		(width 0.089408)
		(layer "In11.Cu")
		(net "FM_CPU1_PROC_ID0")
	)
	(segment
		(start 265.687556 -157.594046)
		(end 265.600434 -157.681168)
		(width 0.089408)
		(layer "In11.Cu")
		(net "FM_CPU1_PROC_ID0")
	)
	(segment
		(start 28.400756 -127.87122)
		(end 29.128212 -127.143764)
		(width 0.089408)
		(layer "In11.Cu")
		(net "FM_CPU1_PROC_ID0")
	)
	(segment
		(start 75.8698 -80.8228)
		(end 76.488036 -81.441036)
		(width 0.089408)
		(layer "In11.Cu")
		(net "FM_CPU1_PROC_ID0")
	)
	(segment
		(start 47.987712 -95.5802)
		(end 49.689004 -93.878908)
		(width 0.089408)
		(layer "In11.Cu")
		(net "FM_CPU1_PROC_ID0")
	)
	(segment
		(start 165.144196 -149.50694)
		(end 165.229032 -149.591776)
		(width 0.089408)
		(layer "In11.Cu")
		(net "FM_CPU1_PROC_ID0")
	)
	(segment
		(start 72.9742 -80.3402)
		(end 73.4314 -80.3402)
		(width 0.089408)
		(layer "In11.Cu")
		(net "FM_CPU1_PROC_ID0")
	)
	(segment
		(start 28.209748 -130.66522)
		(end 28.400756 -130.474212)
		(width 0.089408)
		(layer "In11.Cu")
		(net "FM_CPU1_PROC_ID0")
	)
	(segment
		(start 186.601862 -155.078938)
		(end 186.601862 -150.334472)
		(width 0.089408)
		(layer "In11.Cu")
		(net "FM_CPU1_PROC_ID0")
	)
	(segment
		(start 67.8688 -83.3374)
		(end 68.3006 -83.3374)
		(width 0.089408)
		(layer "In11.Cu")
		(net "FM_CPU1_PROC_ID0")
	)
	(segment
		(start 72.2122 -80.8482)
		(end 72.4662 -80.8482)
		(width 0.089408)
		(layer "In11.Cu")
		(net "FM_CPU1_PROC_ID0")
	)
	(segment
		(start 69.596 -82.423)
		(end 69.85 -82.423)
		(width 0.089408)
		(layer "In11.Cu")
		(net "FM_CPU1_PROC_ID0")
	)
	(segment
		(start 28.209748 -131.990338)
		(end 28.209748 -130.66522)
		(width 0.089408)
		(layer "In11.Cu")
		(net "FM_CPU1_PROC_ID0")
	)
	(segment
		(start 71.247 -81.28)
		(end 71.7804 -81.28)
		(width 0.089408)
		(layer "In11.Cu")
		(net "FM_CPU1_PROC_ID0")
	)
	(segment
		(start 265.600434 -157.681168)
		(end 265.594338 -157.681168)
		(width 0.089408)
		(layer "In11.Cu")
		(net "FM_CPU1_PROC_ID0")
	)
	(segment
		(start 377.544838 -71.895208)
		(end 377.145042 -72.295004)
		(width 0.1016)
		(layer "F.Cu")
		(net "FM_CPU0_PROC_ID1")
	)
	(segment
		(start 245.627144 -89.765886)
		(end 245.055644 -89.765886)
		(width 0.10795)
		(layer "F.Cu")
		(net "FM_CPU0_PROC_ID1")
	)
	(via
		(at 378.206 -34.53257)
		(size 0.6604)
		(drill 0.3302)
		(layers "F.Cu" "B.Cu")
		(net "FM_CPU0_PROC_ID1")
	)
	(via
		(at 245.055644 -89.765886)
		(size 0.508)
		(drill 0.254)
		(layers "F.Cu" "B.Cu")
		(net "FM_CPU0_PROC_ID1")
	)
	(via
		(at 377.544838 -71.895208)
		(size 0.4572)
		(drill 0.2032)
		(layers "F.Cu" "B.Cu")
		(net "FM_CPU0_PROC_ID1")
	)
	(via
		(at 339.908896 -53.098954)
		(size 0.508)
		(drill 0.254)
		(layers "F.Cu" "B.Cu")
		(net "FM_CPU0_PROC_ID1")
	)
	(via
		(at 381.880364 -36.191444)
		(size 0.508)
		(drill 0.254)
		(layers "F.Cu" "B.Cu")
		(net "FM_CPU0_PROC_ID1")
	)
	(segment
		(start 239.189768 -90.772996)
		(end 239.665002 -91.24823)
		(width 0.0889)
		(layer "B.Cu")
		(net "FM_CPU0_PROC_ID1")
	)
	(segment
		(start 374.174258 -32.08655)
		(end 374.670828 -32.58312)
		(width 0.10795)
		(layer "B.Cu")
		(net "FM_CPU0_PROC_ID1")
	)
	(segment
		(start 243.557552 -90.258138)
		(end 244.049804 -89.765886)
		(width 0.0889)
		(layer "B.Cu")
		(net "FM_CPU0_PROC_ID1")
	)
	(segment
		(start 240.589054 -90.79484)
		(end 241.028474 -90.79484)
		(width 0.0889)
		(layer "B.Cu")
		(net "FM_CPU0_PROC_ID1")
	)
	(segment
		(start 373.858282 -32.086804)
		(end 373.858536 -32.08655)
		(width 0.10795)
		(layer "B.Cu")
		(net "FM_CPU0_PROC_ID1")
	)
	(segment
		(start 374.670828 -32.58312)
		(end 374.670828 -32.786828)
		(width 0.10795)
		(layer "B.Cu")
		(net "FM_CPU0_PROC_ID1")
	)
	(segment
		(start 381.389382 -36.191444)
		(end 381.880364 -36.191444)
		(width 0.10795)
		(layer "B.Cu")
		(net "FM_CPU0_PROC_ID1")
	)
	(segment
		(start 234.88015 -91.236038)
		(end 235.406692 -90.709496)
		(width 0.0889)
		(layer "B.Cu")
		(net "FM_CPU0_PROC_ID1")
	)
	(segment
		(start 241.028474 -90.79484)
		(end 241.456718 -91.223084)
		(width 0.0889)
		(layer "B.Cu")
		(net "FM_CPU0_PROC_ID1")
	)
	(segment
		(start 236.665516 -91.260676)
		(end 237.153196 -90.772996)
		(width 0.0889)
		(layer "B.Cu")
		(net "FM_CPU0_PROC_ID1")
	)
	(segment
		(start 238.844328 -90.772996)
		(end 239.189768 -90.772996)
		(width 0.0889)
		(layer "B.Cu")
		(net "FM_CPU0_PROC_ID1")
	)
	(segment
		(start 376.555 -34.671)
		(end 378.06757 -34.671)
		(width 0.10795)
		(layer "B.Cu")
		(net "FM_CPU0_PROC_ID1")
	)
	(segment
		(start 242.711478 -90.716354)
		(end 243.169694 -90.258138)
		(width 0.0889)
		(layer "B.Cu")
		(net "FM_CPU0_PROC_ID1")
	)
	(segment
		(start 242.245134 -90.716354)
		(end 242.711478 -90.716354)
		(width 0.0889)
		(layer "B.Cu")
		(net "FM_CPU0_PROC_ID1")
	)
	(segment
		(start 358.090724 -44.983146)
		(end 358.090724 -39.765224)
		(width 0.10795)
		(layer "B.Cu")
		(net "FM_CPU0_PROC_ID1")
	)
	(segment
		(start 373.082566 -31.505652)
		(end 373.663718 -32.086804)
		(width 0.10795)
		(layer "B.Cu")
		(net "FM_CPU0_PROC_ID1")
	)
	(segment
		(start 352.14052 -50.93335)
		(end 358.090724 -44.983146)
		(width 0.10795)
		(layer "B.Cu")
		(net "FM_CPU0_PROC_ID1")
	)
	(segment
		(start 241.456718 -91.223084)
		(end 241.738404 -91.223084)
		(width 0.0889)
		(layer "B.Cu")
		(net "FM_CPU0_PROC_ID1")
	)
	(segment
		(start 230.920036 -92.583)
		(end 232.266998 -91.236038)
		(width 0.1016)
		(layer "B.Cu")
		(net "FM_CPU0_PROC_ID1")
	)
	(segment
		(start 379.730508 -34.53257)
		(end 381.389382 -36.191444)
		(width 0.10795)
		(layer "B.Cu")
		(net "FM_CPU0_PROC_ID1")
	)
	(segment
		(start 239.665002 -91.24823)
		(end 240.135664 -91.24823)
		(width 0.0889)
		(layer "B.Cu")
		(net "FM_CPU0_PROC_ID1")
	)
	(segment
		(start 373.858536 -32.08655)
		(end 374.174258 -32.08655)
		(width 0.10795)
		(layer "B.Cu")
		(net "FM_CPU0_PROC_ID1")
	)
	(segment
		(start 238.356648 -91.260676)
		(end 238.844328 -90.772996)
		(width 0.0889)
		(layer "B.Cu")
		(net "FM_CPU0_PROC_ID1")
	)
	(segment
		(start 358.090724 -39.765224)
		(end 366.350296 -31.505652)
		(width 0.10795)
		(layer "B.Cu")
		(net "FM_CPU0_PROC_ID1")
	)
	(segment
		(start 378.06757 -34.671)
		(end 378.206 -34.53257)
		(width 0.10795)
		(layer "B.Cu")
		(net "FM_CPU0_PROC_ID1")
	)
	(segment
		(start 232.864406 -91.236038)
		(end 234.88015 -91.236038)
		(width 0.0889)
		(layer "B.Cu")
		(net "FM_CPU0_PROC_ID1")
	)
	(segment
		(start 235.767118 -90.709496)
		(end 236.318298 -91.260676)
		(width 0.0889)
		(layer "B.Cu")
		(net "FM_CPU0_PROC_ID1")
	)
	(segment
		(start 235.406692 -90.709496)
		(end 235.767118 -90.709496)
		(width 0.0889)
		(layer "B.Cu")
		(net "FM_CPU0_PROC_ID1")
	)
	(segment
		(start 236.318298 -91.260676)
		(end 236.665516 -91.260676)
		(width 0.0889)
		(layer "B.Cu")
		(net "FM_CPU0_PROC_ID1")
	)
	(segment
		(start 237.489492 -90.772996)
		(end 237.977172 -91.260676)
		(width 0.0889)
		(layer "B.Cu")
		(net "FM_CPU0_PROC_ID1")
	)
	(segment
		(start 339.908896 -53.098954)
		(end 342.0745 -50.93335)
		(width 0.10795)
		(layer "B.Cu")
		(net "FM_CPU0_PROC_ID1")
	)
	(segment
		(start 243.169694 -90.258138)
		(end 243.557552 -90.258138)
		(width 0.0889)
		(layer "B.Cu")
		(net "FM_CPU0_PROC_ID1")
	)
	(segment
		(start 244.049804 -89.765886)
		(end 245.055644 -89.765886)
		(width 0.0889)
		(layer "B.Cu")
		(net "FM_CPU0_PROC_ID1")
	)
	(segment
		(start 378.206 -34.53257)
		(end 379.730508 -34.53257)
		(width 0.10795)
		(layer "B.Cu")
		(net "FM_CPU0_PROC_ID1")
	)
	(segment
		(start 237.153196 -90.772996)
		(end 237.489492 -90.772996)
		(width 0.0889)
		(layer "B.Cu")
		(net "FM_CPU0_PROC_ID1")
	)
	(segment
		(start 240.135664 -91.24823)
		(end 240.589054 -90.79484)
		(width 0.0889)
		(layer "B.Cu")
		(net "FM_CPU0_PROC_ID1")
	)
	(segment
		(start 373.663718 -32.086804)
		(end 373.858282 -32.086804)
		(width 0.10795)
		(layer "B.Cu")
		(net "FM_CPU0_PROC_ID1")
	)
	(segment
		(start 232.266998 -91.236038)
		(end 232.864406 -91.236038)
		(width 0.1016)
		(layer "B.Cu")
		(net "FM_CPU0_PROC_ID1")
	)
	(segment
		(start 374.670828 -32.786828)
		(end 376.555 -34.671)
		(width 0.10795)
		(layer "B.Cu")
		(net "FM_CPU0_PROC_ID1")
	)
	(segment
		(start 366.350296 -31.505652)
		(end 373.082566 -31.505652)
		(width 0.10795)
		(layer "B.Cu")
		(net "FM_CPU0_PROC_ID1")
	)
	(segment
		(start 342.0745 -50.93335)
		(end 352.14052 -50.93335)
		(width 0.10795)
		(layer "B.Cu")
		(net "FM_CPU0_PROC_ID1")
	)
	(segment
		(start 237.977172 -91.260676)
		(end 238.356648 -91.260676)
		(width 0.0889)
		(layer "B.Cu")
		(net "FM_CPU0_PROC_ID1")
	)
	(segment
		(start 228.473 -92.583)
		(end 230.920036 -92.583)
		(width 0.1016)
		(layer "B.Cu")
		(net "FM_CPU0_PROC_ID1")
	)
	(segment
		(start 241.738404 -91.223084)
		(end 242.245134 -90.716354)
		(width 0.0889)
		(layer "B.Cu")
		(net "FM_CPU0_PROC_ID1")
	)
	(segment
		(start 320.187574 -68.040758)
		(end 320.187574 -66.440304)
		(width 0.089408)
		(layer "In2.Cu")
		(net "FM_CPU0_PROC_ID1")
	)
	(segment
		(start 297.354752 -88.195404)
		(end 297.68546 -88.195404)
		(width 0.089408)
		(layer "In2.Cu")
		(net "FM_CPU0_PROC_ID1")
	)
	(segment
		(start 286.1945 -88.497664)
		(end 286.751014 -88.497664)
		(width 0.0889)
		(layer "In2.Cu")
		(net "FM_CPU0_PROC_ID1")
	)
	(segment
		(start 284.477714 -88.691212)
		(end 284.84068 -88.691212)
		(width 0.0889)
		(layer "In2.Cu")
		(net "FM_CPU0_PROC_ID1")
	)
	(segment
		(start 304.604928 -87.118952)
		(end 304.993294 -87.507318)
		(width 0.089408)
		(layer "In2.Cu")
		(net "FM_CPU0_PROC_ID1")
	)
	(segment
		(start 288.547048 -88.192356)
		(end 288.690812 -88.192356)
		(width 0.0889)
		(layer "In2.Cu")
		(net "FM_CPU0_PROC_ID1")
	)
	(segment
		(start 283.619194 -89.186258)
		(end 283.982668 -89.186258)
		(width 0.0889)
		(layer "In2.Cu")
		(net "FM_CPU0_PROC_ID1")
	)
	(segment
		(start 294.190674 -87.700358)
		(end 295.698926 -87.700358)
		(width 0.089408)
		(layer "In2.Cu")
		(net "FM_CPU0_PROC_ID1")
	)
	(segment
		(start 260.493764 -90.165936)
		(end 260.523736 -90.165936)
		(width 0.0889)
		(layer "In2.Cu")
		(net "FM_CPU0_PROC_ID1")
	)
	(segment
		(start 314.211208 -74.017124)
		(end 320.187574 -68.040758)
		(width 0.089408)
		(layer "In2.Cu")
		(net "FM_CPU0_PROC_ID1")
	)
	(segment
		(start 245.881144 -87.38616)
		(end 246.937784 -87.38616)
		(width 0.0889)
		(layer "In2.Cu")
		(net "FM_CPU0_PROC_ID1")
	)
	(segment
		(start 249.683524 -87.688166)
		(end 249.98553 -87.38616)
		(width 0.0889)
		(layer "In2.Cu")
		(net "FM_CPU0_PROC_ID1")
	)
	(segment
		(start 301.253144 -88.002364)
		(end 301.55769 -87.697818)
		(width 0.089408)
		(layer "In2.Cu")
		(net "FM_CPU0_PROC_ID1")
	)
	(segment
		(start 297.052238 -88.497918)
		(end 297.354752 -88.195404)
		(width 0.089408)
		(layer "In2.Cu")
		(net "FM_CPU0_PROC_ID1")
	)
	(segment
		(start 272.944336 -90.670634)
		(end 273.249136 -90.975434)
		(width 0.0889)
		(layer "In2.Cu")
		(net "FM_CPU0_PROC_ID1")
	)
	(segment
		(start 287.685226 -88.497664)
		(end 288.24174 -88.497664)
		(width 0.0889)
		(layer "In2.Cu")
		(net "FM_CPU0_PROC_ID1")
	)
	(segment
		(start 297.987974 -88.497918)
		(end 298.576746 -88.497918)
		(width 0.089408)
		(layer "In2.Cu")
		(net "FM_CPU0_PROC_ID1")
	)
	(segment
		(start 304.993294 -87.507318)
		(end 305.908456 -87.507318)
		(width 0.089408)
		(layer "In2.Cu")
		(net "FM_CPU0_PROC_ID1")
	)
	(segment
		(start 288.691066 -88.19261)
		(end 289.323526 -88.19261)
		(width 0.0889)
		(layer "In2.Cu")
		(net "FM_CPU0_PROC_ID1")
	)
	(segment
		(start 292.757098 -88.19261)
		(end 293.062406 -88.497918)
		(width 0.089408)
		(layer "In2.Cu")
		(net "FM_CPU0_PROC_ID1")
	)
	(segment
		(start 256.204974 -88.68029)
		(end 256.23774 -88.68029)
		(width 0.0889)
		(layer "In2.Cu")
		(net "FM_CPU0_PROC_ID1")
	)
	(segment
		(start 253.173738 -87.688166)
		(end 253.475744 -87.38616)
		(width 0.0889)
		(layer "In2.Cu")
		(net "FM_CPU0_PROC_ID1")
	)
	(segment
		(start 273.249136 -90.975434)
		(end 273.497294 -90.975434)
		(width 0.0889)
		(layer "In2.Cu")
		(net "FM_CPU0_PROC_ID1")
	)
	(segment
		(start 287.38322 -88.195658)
		(end 287.685226 -88.497664)
		(width 0.0889)
		(layer "In2.Cu")
		(net "FM_CPU0_PROC_ID1")
	)
	(segment
		(start 252.088904 -87.38616)
		(end 252.39091 -87.688166)
		(width 0.0889)
		(layer "In2.Cu")
		(net "FM_CPU0_PROC_ID1")
	)
	(segment
		(start 303.361344 -87.598758)
		(end 303.712118 -87.598758)
		(width 0.089408)
		(layer "In2.Cu")
		(net "FM_CPU0_PROC_ID1")
	)
	(segment
		(start 299.071792 -88.992964)
		(end 299.4025 -88.992964)
		(width 0.089408)
		(layer "In2.Cu")
		(net "FM_CPU0_PROC_ID1")
	)
	(segment
		(start 292.11651 -88.19261)
		(end 292.124638 -88.19261)
		(width 0.089408)
		(layer "In2.Cu")
		(net "FM_CPU0_PROC_ID1")
	)
	(segment
		(start 299.897546 -88.497918)
		(end 300.2915 -88.497918)
		(width 0.089408)
		(layer "In2.Cu")
		(net "FM_CPU0_PROC_ID1")
	)
	(segment
		(start 283.385768 -90.18397)
		(end 283.385768 -89.419684)
		(width 0.0889)
		(layer "In2.Cu")
		(net "FM_CPU0_PROC_ID1")
	)
	(segment
		(start 326.10425 -60.523628)
		(end 327.123552 -60.523628)
		(width 0.089408)
		(layer "In2.Cu")
		(net "FM_CPU0_PROC_ID1")
	)
	(segment
		(start 285.336234 -88.195658)
		(end 285.892494 -88.195658)
		(width 0.0889)
		(layer "In2.Cu")
		(net "FM_CPU0_PROC_ID1")
	)
	(segment
		(start 262.210804 -90.165936)
		(end 262.24357 -90.165936)
		(width 0.0889)
		(layer "In2.Cu")
		(net "FM_CPU0_PROC_ID1")
	)
	(segment
		(start 283.08935 -90.480388)
		(end 283.385768 -90.18397)
		(width 0.0889)
		(layer "In2.Cu")
		(net "FM_CPU0_PROC_ID1")
	)
	(segment
		(start 255.342644 -88.184736)
		(end 255.37541 -88.184736)
		(width 0.0889)
		(layer "In2.Cu")
		(net "FM_CPU0_PROC_ID1")
	)
	(segment
		(start 284.84068 -88.691212)
		(end 285.336234 -88.195658)
		(width 0.0889)
		(layer "In2.Cu")
		(net "FM_CPU0_PROC_ID1")
	)
	(segment
		(start 290.457382 -88.195404)
		(end 290.817554 -88.195404)
		(width 0.089408)
		(layer "In2.Cu")
		(net "FM_CPU0_PROC_ID1")
	)
	(segment
		(start 257.059684 -89.175336)
		(end 257.09245 -89.175336)
		(width 0.0889)
		(layer "In2.Cu")
		(net "FM_CPU0_PROC_ID1")
	)
	(segment
		(start 268.33703 -90.165936)
		(end 268.841728 -90.670634)
		(width 0.0889)
		(layer "In2.Cu")
		(net "FM_CPU0_PROC_ID1")
	)
	(segment
		(start 250.67387 -87.688166)
		(end 251.456698 -87.688166)
		(width 0.0889)
		(layer "In2.Cu")
		(net "FM_CPU0_PROC_ID1")
	)
	(segment
		(start 283.385768 -89.419684)
		(end 283.619194 -89.186258)
		(width 0.0889)
		(layer "In2.Cu")
		(net "FM_CPU0_PROC_ID1")
	)
	(segment
		(start 244.657118 -89.36736)
		(end 244.657118 -88.610186)
		(width 0.0889)
		(layer "In2.Cu")
		(net "FM_CPU0_PROC_ID1")
	)
	(segment
		(start 335.116424 -52.530756)
		(end 339.340698 -52.530756)
		(width 0.089408)
		(layer "In2.Cu")
		(net "FM_CPU0_PROC_ID1")
	)
	(segment
		(start 289.631628 -88.500712)
		(end 290.152074 -88.500712)
		(width 0.0889)
		(layer "In2.Cu")
		(net "FM_CPU0_PROC_ID1")
	)
	(segment
		(start 291.120068 -88.497918)
		(end 291.811202 -88.497918)
		(width 0.089408)
		(layer "In2.Cu")
		(net "FM_CPU0_PROC_ID1")
	)
	(segment
		(start 265.641836 -90.165936)
		(end 265.677396 -90.165936)
		(width 0.0889)
		(layer "In2.Cu")
		(net "FM_CPU0_PROC_ID1")
	)
	(segment
		(start 258.776724 -90.165936)
		(end 258.806696 -90.165936)
		(width 0.0889)
		(layer "In2.Cu")
		(net "FM_CPU0_PROC_ID1")
	)
	(segment
		(start 249.98553 -87.38616)
		(end 250.371864 -87.38616)
		(width 0.0889)
		(layer "In2.Cu")
		(net "FM_CPU0_PROC_ID1")
	)
	(segment
		(start 250.371864 -87.38616)
		(end 250.67387 -87.688166)
		(width 0.0889)
		(layer "In2.Cu")
		(net "FM_CPU0_PROC_ID1")
	)
	(segment
		(start 287.05302 -88.195658)
		(end 287.38322 -88.195658)
		(width 0.0889)
		(layer "In2.Cu")
		(net "FM_CPU0_PROC_ID1")
	)
	(segment
		(start 339.340698 -52.530756)
		(end 339.908896 -53.098954)
		(width 0.089408)
		(layer "In2.Cu")
		(net "FM_CPU0_PROC_ID1")
	)
	(segment
		(start 257.922014 -89.67089)
		(end 257.95478 -89.67089)
		(width 0.0889)
		(layer "In2.Cu")
		(net "FM_CPU0_PROC_ID1")
	)
	(segment
		(start 302.376078 -88.037162)
		(end 302.92294 -88.037162)
		(width 0.089408)
		(layer "In2.Cu")
		(net "FM_CPU0_PROC_ID1")
	)
	(segment
		(start 301.55769 -87.697818)
		(end 302.036734 -87.697818)
		(width 0.089408)
		(layer "In2.Cu")
		(net "FM_CPU0_PROC_ID1")
	)
	(segment
		(start 290.817554 -88.195404)
		(end 291.120068 -88.497918)
		(width 0.089408)
		(layer "In2.Cu")
		(net "FM_CPU0_PROC_ID1")
	)
	(segment
		(start 314.211208 -81.860136)
		(end 314.211208 -74.017124)
		(width 0.089408)
		(layer "In2.Cu")
		(net "FM_CPU0_PROC_ID1")
	)
	(segment
		(start 289.323526 -88.19261)
		(end 289.631628 -88.500712)
		(width 0.0889)
		(layer "In2.Cu")
		(net "FM_CPU0_PROC_ID1")
	)
	(segment
		(start 306.71262 -86.703154)
		(end 309.36819 -86.703154)
		(width 0.089408)
		(layer "In2.Cu")
		(net "FM_CPU0_PROC_ID1")
	)
	(segment
		(start 252.39091 -87.688166)
		(end 253.173738 -87.688166)
		(width 0.0889)
		(layer "In2.Cu")
		(net "FM_CPU0_PROC_ID1")
	)
	(segment
		(start 248.95683 -87.688166)
		(end 249.683524 -87.688166)
		(width 0.0889)
		(layer "In2.Cu")
		(net "FM_CPU0_PROC_ID1")
	)
	(segment
		(start 292.708838 -88.192864)
		(end 292.709092 -88.19261)
		(width 0.089408)
		(layer "In2.Cu")
		(net "FM_CPU0_PROC_ID1")
	)
	(segment
		(start 296.496486 -88.497918)
		(end 297.052238 -88.497918)
		(width 0.089408)
		(layer "In2.Cu")
		(net "FM_CPU0_PROC_ID1")
	)
	(segment
		(start 290.152074 -88.500712)
		(end 290.348924 -88.303862)
		(width 0.0889)
		(layer "In2.Cu")
		(net "FM_CPU0_PROC_ID1")
	)
	(segment
		(start 309.36819 -86.703154)
		(end 314.211208 -81.860136)
		(width 0.089408)
		(layer "In2.Cu")
		(net "FM_CPU0_PROC_ID1")
	)
	(segment
		(start 283.982668 -89.186258)
		(end 284.477714 -88.691212)
		(width 0.0889)
		(layer "In2.Cu")
		(net "FM_CPU0_PROC_ID1")
	)
	(segment
		(start 293.393114 -88.497918)
		(end 294.190674 -87.700358)
		(width 0.089408)
		(layer "In2.Cu")
		(net "FM_CPU0_PROC_ID1")
	)
	(segment
		(start 248.324624 -87.38616)
		(end 248.654824 -87.38616)
		(width 0.0889)
		(layer "In2.Cu")
		(net "FM_CPU0_PROC_ID1")
	)
	(segment
		(start 246.937784 -87.38616)
		(end 247.23979 -87.688166)
		(width 0.0889)
		(layer "In2.Cu")
		(net "FM_CPU0_PROC_ID1")
	)
	(segment
		(start 245.055644 -89.765886)
		(end 244.657118 -89.36736)
		(width 0.0889)
		(layer "In2.Cu")
		(net "FM_CPU0_PROC_ID1")
	)
	(segment
		(start 297.68546 -88.195404)
		(end 297.987974 -88.497918)
		(width 0.089408)
		(layer "In2.Cu")
		(net "FM_CPU0_PROC_ID1")
	)
	(segment
		(start 264.45464 -90.461338)
		(end 264.457942 -90.46718)
		(width 0.0889)
		(layer "In2.Cu")
		(net "FM_CPU0_PROC_ID1")
	)
	(segment
		(start 244.657118 -88.610186)
		(end 245.881144 -87.38616)
		(width 0.0889)
		(layer "In2.Cu")
		(net "FM_CPU0_PROC_ID1")
	)
	(segment
		(start 291.811202 -88.497918)
		(end 292.11651 -88.19261)
		(width 0.089408)
		(layer "In2.Cu")
		(net "FM_CPU0_PROC_ID1")
	)
	(segment
		(start 292.709092 -88.19261)
		(end 292.757098 -88.19261)
		(width 0.089408)
		(layer "In2.Cu")
		(net "FM_CPU0_PROC_ID1")
	)
	(segment
		(start 288.24174 -88.497664)
		(end 288.547048 -88.192356)
		(width 0.0889)
		(layer "In2.Cu")
		(net "FM_CPU0_PROC_ID1")
	)
	(segment
		(start 282.904184 -90.480388)
		(end 283.08935 -90.480388)
		(width 0.0889)
		(layer "In2.Cu")
		(net "FM_CPU0_PROC_ID1")
	)
	(segment
		(start 261.34568 -89.67089)
		(end 261.38886 -89.67089)
		(width 0.0889)
		(layer "In2.Cu")
		(net "FM_CPU0_PROC_ID1")
	)
	(segment
		(start 275.537676 -90.789506)
		(end 275.545804 -90.775282)
		(width 0.0889)
		(layer "In2.Cu")
		(net "FM_CPU0_PROC_ID1")
	)
	(segment
		(start 300.787054 -88.002364)
		(end 301.253144 -88.002364)
		(width 0.089408)
		(layer "In2.Cu")
		(net "FM_CPU0_PROC_ID1")
	)
	(segment
		(start 302.036734 -87.697818)
		(end 302.376078 -88.037162)
		(width 0.089408)
		(layer "In2.Cu")
		(net "FM_CPU0_PROC_ID1")
	)
	(segment
		(start 304.191924 -87.118952)
		(end 304.604928 -87.118952)
		(width 0.089408)
		(layer "In2.Cu")
		(net "FM_CPU0_PROC_ID1")
	)
	(segment
		(start 254.109474 -87.68969)
		(end 254.5207 -87.68969)
		(width 0.0889)
		(layer "In2.Cu")
		(net "FM_CPU0_PROC_ID1")
	)
	(segment
		(start 251.758704 -87.38616)
		(end 252.088904 -87.38616)
		(width 0.0889)
		(layer "In2.Cu")
		(net "FM_CPU0_PROC_ID1")
	)
	(segment
		(start 300.2915 -88.497918)
		(end 300.787054 -88.002364)
		(width 0.089408)
		(layer "In2.Cu")
		(net "FM_CPU0_PROC_ID1")
	)
	(segment
		(start 299.4025 -88.992964)
		(end 299.897546 -88.497918)
		(width 0.089408)
		(layer "In2.Cu")
		(net "FM_CPU0_PROC_ID1")
	)
	(segment
		(start 320.187574 -66.440304)
		(end 326.10425 -60.523628)
		(width 0.089408)
		(layer "In2.Cu")
		(net "FM_CPU0_PROC_ID1")
	)
	(segment
		(start 267.358876 -90.165936)
		(end 268.33703 -90.165936)
		(width 0.0889)
		(layer "In2.Cu")
		(net "FM_CPU0_PROC_ID1")
	)
	(segment
		(start 303.712118 -87.598758)
		(end 304.191924 -87.118952)
		(width 0.089408)
		(layer "In2.Cu")
		(net "FM_CPU0_PROC_ID1")
	)
	(segment
		(start 288.690812 -88.192356)
		(end 288.691066 -88.19261)
		(width 0.0889)
		(layer "In2.Cu")
		(net "FM_CPU0_PROC_ID1")
	)
	(segment
		(start 292.124892 -88.192864)
		(end 292.708838 -88.192864)
		(width 0.089408)
		(layer "In2.Cu")
		(net "FM_CPU0_PROC_ID1")
	)
	(segment
		(start 248.022618 -87.688166)
		(end 248.324624 -87.38616)
		(width 0.0889)
		(layer "In2.Cu")
		(net "FM_CPU0_PROC_ID1")
	)
	(segment
		(start 251.456698 -87.688166)
		(end 251.758704 -87.38616)
		(width 0.0889)
		(layer "In2.Cu")
		(net "FM_CPU0_PROC_ID1")
	)
	(segment
		(start 292.124638 -88.19261)
		(end 292.124892 -88.192864)
		(width 0.089408)
		(layer "In2.Cu")
		(net "FM_CPU0_PROC_ID1")
	)
	(segment
		(start 295.698926 -87.700358)
		(end 296.496486 -88.497918)
		(width 0.089408)
		(layer "In2.Cu")
		(net "FM_CPU0_PROC_ID1")
	)
	(segment
		(start 248.654824 -87.38616)
		(end 248.95683 -87.688166)
		(width 0.0889)
		(layer "In2.Cu")
		(net "FM_CPU0_PROC_ID1")
	)
	(segment
		(start 268.841728 -90.670634)
		(end 272.944336 -90.670634)
		(width 0.0889)
		(layer "In2.Cu")
		(net "FM_CPU0_PROC_ID1")
	)
	(segment
		(start 276.563074 -90.764868)
		(end 276.569424 -90.775536)
		(width 0.0889)
		(layer "In2.Cu")
		(net "FM_CPU0_PROC_ID1")
	)
	(segment
		(start 253.475744 -87.38616)
		(end 253.805944 -87.38616)
		(width 0.0889)
		(layer "In2.Cu")
		(net "FM_CPU0_PROC_ID1")
	)
	(segment
		(start 247.23979 -87.688166)
		(end 248.022618 -87.688166)
		(width 0.0889)
		(layer "In2.Cu")
		(net "FM_CPU0_PROC_ID1")
	)
	(segment
		(start 298.576746 -88.497918)
		(end 299.071792 -88.992964)
		(width 0.089408)
		(layer "In2.Cu")
		(net "FM_CPU0_PROC_ID1")
	)
	(segment
		(start 290.348924 -88.303862)
		(end 290.457382 -88.195404)
		(width 0.089408)
		(layer "In2.Cu")
		(net "FM_CPU0_PROC_ID1")
	)
	(segment
		(start 305.908456 -87.507318)
		(end 306.71262 -86.703154)
		(width 0.089408)
		(layer "In2.Cu")
		(net "FM_CPU0_PROC_ID1")
	)
	(segment
		(start 285.892494 -88.195658)
		(end 286.1945 -88.497664)
		(width 0.0889)
		(layer "In2.Cu")
		(net "FM_CPU0_PROC_ID1")
	)
	(segment
		(start 253.805944 -87.38616)
		(end 254.109474 -87.68969)
		(width 0.0889)
		(layer "In2.Cu")
		(net "FM_CPU0_PROC_ID1")
	)
	(segment
		(start 327.123552 -60.523628)
		(end 335.116424 -52.530756)
		(width 0.089408)
		(layer "In2.Cu")
		(net "FM_CPU0_PROC_ID1")
	)
	(segment
		(start 293.062406 -88.497918)
		(end 293.393114 -88.497918)
		(width 0.089408)
		(layer "In2.Cu")
		(net "FM_CPU0_PROC_ID1")
	)
	(segment
		(start 286.751014 -88.497664)
		(end 287.05302 -88.195658)
		(width 0.0889)
		(layer "In2.Cu")
		(net "FM_CPU0_PROC_ID1")
	)
	(segment
		(start 263.92505 -90.165936)
		(end 263.96061 -90.165936)
		(width 0.0889)
		(layer "In2.Cu")
		(net "FM_CPU0_PROC_ID1")
	)
	(segment
		(start 302.92294 -88.037162)
		(end 303.361344 -87.598758)
		(width 0.089408)
		(layer "In2.Cu")
		(net "FM_CPU0_PROC_ID1")
	)
	(arc
		(start 257.95478 -89.67089)
		(mid 258.237997 -89.755171)
		(end 258.445 -89.966038)
		(width 0.0889)
		(layer "In2.Cu")
		(net "FM_CPU0_PROC_ID1")
	)
	(arc
		(start 259.13842 -89.966038)
		(mid 259.65023 -89.670499)
		(end 260.16204 -89.966038)
		(width 0.0889)
		(layer "In2.Cu")
		(net "FM_CPU0_PROC_ID1")
	)
	(arc
		(start 265.677396 -90.165936)
		(mid 265.96282 -90.249403)
		(end 266.171426 -90.461338)
		(width 0.0889)
		(layer "In2.Cu")
		(net "FM_CPU0_PROC_ID1")
	)
	(arc
		(start 260.85546 -89.966038)
		(mid 261.062464 -89.755174)
		(end 261.34568 -89.67089)
		(width 0.0889)
		(layer "In2.Cu")
		(net "FM_CPU0_PROC_ID1")
	)
	(arc
		(start 255.37541 -88.184736)
		(mid 255.660834 -88.268203)
		(end 255.86944 -88.480138)
		(width 0.0889)
		(layer "In2.Cu")
		(net "FM_CPU0_PROC_ID1")
	)
	(arc
		(start 266.171426 -90.461338)
		(mid 266.518136 -90.661649)
		(end 266.864846 -90.461338)
		(width 0.0889)
		(layer "In2.Cu")
		(net "FM_CPU0_PROC_ID1")
	)
	(arc
		(start 273.829018 -90.775536)
		(mid 274.340828 -90.479997)
		(end 274.852638 -90.775536)
		(width 0.0889)
		(layer "In2.Cu")
		(net "FM_CPU0_PROC_ID1")
	)
	(arc
		(start 258.806696 -90.165936)
		(mid 258.998338 -90.10877)
		(end 259.13842 -89.966038)
		(width 0.0889)
		(layer "In2.Cu")
		(net "FM_CPU0_PROC_ID1")
	)
	(arc
		(start 280.696924 -90.775536)
		(mid 281.208734 -90.479997)
		(end 281.720544 -90.775536)
		(width 0.0889)
		(layer "In2.Cu")
		(net "FM_CPU0_PROC_ID1")
	)
	(arc
		(start 255.86944 -88.480138)
		(mid 256.011123 -88.623942)
		(end 256.204974 -88.68029)
		(width 0.0889)
		(layer "In2.Cu")
		(net "FM_CPU0_PROC_ID1")
	)
	(arc
		(start 276.569424 -90.775536)
		(mid 276.916134 -90.97572)
		(end 277.262844 -90.775536)
		(width 0.0889)
		(layer "In2.Cu")
		(net "FM_CPU0_PROC_ID1")
	)
	(arc
		(start 260.16204 -89.966038)
		(mid 260.302119 -90.108774)
		(end 260.493764 -90.165936)
		(width 0.0889)
		(layer "In2.Cu")
		(net "FM_CPU0_PROC_ID1")
	)
	(arc
		(start 257.58648 -89.470738)
		(mid 257.728163 -89.614542)
		(end 257.922014 -89.67089)
		(width 0.0889)
		(layer "In2.Cu")
		(net "FM_CPU0_PROC_ID1")
	)
	(arc
		(start 257.09245 -89.175336)
		(mid 257.377874 -89.258803)
		(end 257.58648 -89.470738)
		(width 0.0889)
		(layer "In2.Cu")
		(net "FM_CPU0_PROC_ID1")
	)
	(arc
		(start 258.445 -89.966038)
		(mid 258.585079 -90.108774)
		(end 258.776724 -90.165936)
		(width 0.0889)
		(layer "In2.Cu")
		(net "FM_CPU0_PROC_ID1")
	)
	(arc
		(start 266.864846 -90.461338)
		(mid 267.073454 -90.249406)
		(end 267.358876 -90.165936)
		(width 0.0889)
		(layer "In2.Cu")
		(net "FM_CPU0_PROC_ID1")
	)
	(arc
		(start 278.979884 -90.775536)
		(mid 279.491694 -90.479997)
		(end 280.003504 -90.775536)
		(width 0.0889)
		(layer "In2.Cu")
		(net "FM_CPU0_PROC_ID1")
	)
	(arc
		(start 255.01092 -87.984838)
		(mid 255.150999 -88.127574)
		(end 255.342644 -88.184736)
		(width 0.0889)
		(layer "In2.Cu")
		(net "FM_CPU0_PROC_ID1")
	)
	(arc
		(start 256.23774 -88.68029)
		(mid 256.520957 -88.764571)
		(end 256.72796 -88.975438)
		(width 0.0889)
		(layer "In2.Cu")
		(net "FM_CPU0_PROC_ID1")
	)
	(arc
		(start 278.286464 -90.775536)
		(mid 278.633174 -90.97572)
		(end 278.979884 -90.775536)
		(width 0.0889)
		(layer "In2.Cu")
		(net "FM_CPU0_PROC_ID1")
	)
	(arc
		(start 264.457942 -90.46718)
		(mid 264.804515 -90.66153)
		(end 265.147806 -90.461338)
		(width 0.0889)
		(layer "In2.Cu")
		(net "FM_CPU0_PROC_ID1")
	)
	(arc
		(start 265.147806 -90.461338)
		(mid 265.356414 -90.249406)
		(end 265.641836 -90.165936)
		(width 0.0889)
		(layer "In2.Cu")
		(net "FM_CPU0_PROC_ID1")
	)
	(arc
		(start 274.852638 -90.775536)
		(mid 275.191203 -90.975637)
		(end 275.537676 -90.789506)
		(width 0.0889)
		(layer "In2.Cu")
		(net "FM_CPU0_PROC_ID1")
	)
	(arc
		(start 280.003504 -90.775536)
		(mid 280.350214 -90.97572)
		(end 280.696924 -90.775536)
		(width 0.0889)
		(layer "In2.Cu")
		(net "FM_CPU0_PROC_ID1")
	)
	(arc
		(start 261.38886 -89.67089)
		(mid 261.672077 -89.755171)
		(end 261.87908 -89.966038)
		(width 0.0889)
		(layer "In2.Cu")
		(net "FM_CPU0_PROC_ID1")
	)
	(arc
		(start 256.72796 -88.975438)
		(mid 256.868039 -89.118174)
		(end 257.059684 -89.175336)
		(width 0.0889)
		(layer "In2.Cu")
		(net "FM_CPU0_PROC_ID1")
	)
	(arc
		(start 277.262844 -90.775536)
		(mid 277.774654 -90.479997)
		(end 278.286464 -90.775536)
		(width 0.0889)
		(layer "In2.Cu")
		(net "FM_CPU0_PROC_ID1")
	)
	(arc
		(start 263.96061 -90.165936)
		(mid 264.246034 -90.249403)
		(end 264.45464 -90.461338)
		(width 0.0889)
		(layer "In2.Cu")
		(net "FM_CPU0_PROC_ID1")
	)
	(arc
		(start 254.5207 -87.68969)
		(mid 254.803917 -87.773971)
		(end 255.01092 -87.984838)
		(width 0.0889)
		(layer "In2.Cu")
		(net "FM_CPU0_PROC_ID1")
	)
	(arc
		(start 262.24357 -90.165936)
		(mid 262.528994 -90.249403)
		(end 262.7376 -90.461338)
		(width 0.0889)
		(layer "In2.Cu")
		(net "FM_CPU0_PROC_ID1")
	)
	(arc
		(start 273.497294 -90.975434)
		(mid 273.688936 -90.918268)
		(end 273.829018 -90.775536)
		(width 0.0889)
		(layer "In2.Cu")
		(net "FM_CPU0_PROC_ID1")
	)
	(arc
		(start 275.545804 -90.775282)
		(mid 276.051515 -90.479901)
		(end 276.563074 -90.764868)
		(width 0.0889)
		(layer "In2.Cu")
		(net "FM_CPU0_PROC_ID1")
	)
	(arc
		(start 282.413964 -90.775536)
		(mid 282.620968 -90.564672)
		(end 282.904184 -90.480388)
		(width 0.0889)
		(layer "In2.Cu")
		(net "FM_CPU0_PROC_ID1")
	)
	(arc
		(start 263.43102 -90.461338)
		(mid 263.639628 -90.249406)
		(end 263.92505 -90.165936)
		(width 0.0889)
		(layer "In2.Cu")
		(net "FM_CPU0_PROC_ID1")
	)
	(arc
		(start 281.720544 -90.775536)
		(mid 282.067254 -90.97572)
		(end 282.413964 -90.775536)
		(width 0.0889)
		(layer "In2.Cu")
		(net "FM_CPU0_PROC_ID1")
	)
	(arc
		(start 260.523736 -90.165936)
		(mid 260.715378 -90.10877)
		(end 260.85546 -89.966038)
		(width 0.0889)
		(layer "In2.Cu")
		(net "FM_CPU0_PROC_ID1")
	)
	(arc
		(start 261.87908 -89.966038)
		(mid 262.019159 -90.108774)
		(end 262.210804 -90.165936)
		(width 0.0889)
		(layer "In2.Cu")
		(net "FM_CPU0_PROC_ID1")
	)
	(arc
		(start 262.7376 -90.461338)
		(mid 263.08431 -90.661649)
		(end 263.43102 -90.461338)
		(width 0.0889)
		(layer "In2.Cu")
		(net "FM_CPU0_PROC_ID1")
	)
	(segment
		(start 382.662938 -59.393582)
		(end 381.921258 -60.135262)
		(width 0.089408)
		(layer "In9.Cu")
		(net "FM_CPU0_PROC_ID1")
	)
	(segment
		(start 380.365 -67.832224)
		(end 380.365 -68.141596)
		(width 0.089408)
		(layer "In9.Cu")
		(net "FM_CPU0_PROC_ID1")
	)
	(segment
		(start 383.095754 -37.798502)
		(end 383.095754 -38.38067)
		(width 0.089408)
		(layer "In9.Cu")
		(net "FM_CPU0_PROC_ID1")
	)
	(segment
		(start 383.096262 -37.640006)
		(end 383.096262 -37.797994)
		(width 0.089408)
		(layer "In9.Cu")
		(net "FM_CPU0_PROC_ID1")
	)
	(segment
		(start 379.324616 -69.924676)
		(end 378.512324 -69.924676)
		(width 0.089408)
		(layer "In9.Cu")
		(net "FM_CPU0_PROC_ID1")
	)
	(segment
		(start 377.720606 -71.71944)
		(end 377.544838 -71.895208)
		(width 0.089408)
		(layer "In9.Cu")
		(net "FM_CPU0_PROC_ID1")
	)
	(segment
		(start 382.969008 -41.118028)
		(end 382.975358 -41.124378)
		(width 0.089408)
		(layer "In9.Cu")
		(net "FM_CPU0_PROC_ID1")
	)
	(segment
		(start 379.476 -69.030596)
		(end 379.476 -69.2785)
		(width 0.089408)
		(layer "In9.Cu")
		(net "FM_CPU0_PROC_ID1")
	)
	(segment
		(start 380.34214 -64.819276)
		(end 380.34214 -67.809364)
		(width 0.089408)
		(layer "In9.Cu")
		(net "FM_CPU0_PROC_ID1")
	)
	(segment
		(start 381.921258 -60.135262)
		(end 381.921258 -61.47816)
		(width 0.089408)
		(layer "In9.Cu")
		(net "FM_CPU0_PROC_ID1")
	)
	(segment
		(start 383.096262 -37.797994)
		(end 383.095754 -37.798502)
		(width 0.089408)
		(layer "In9.Cu")
		(net "FM_CPU0_PROC_ID1")
	)
	(segment
		(start 379.558042 -69.360542)
		(end 379.558042 -69.69125)
		(width 0.089408)
		(layer "In9.Cu")
		(net "FM_CPU0_PROC_ID1")
	)
	(segment
		(start 379.476 -69.2785)
		(end 379.558042 -69.360542)
		(width 0.089408)
		(layer "In9.Cu")
		(net "FM_CPU0_PROC_ID1")
	)
	(segment
		(start 381.921258 -61.47816)
		(end 380.223776 -63.175642)
		(width 0.089408)
		(layer "In9.Cu")
		(net "FM_CPU0_PROC_ID1")
	)
	(segment
		(start 379.348492 -69.9008)
		(end 379.324616 -69.924676)
		(width 0.089408)
		(layer "In9.Cu")
		(net "FM_CPU0_PROC_ID1")
	)
	(segment
		(start 379.354842 -69.9008)
		(end 379.348492 -69.9008)
		(width 0.089408)
		(layer "In9.Cu")
		(net "FM_CPU0_PROC_ID1")
	)
	(segment
		(start 382.303782 -36.191444)
		(end 383.096008 -36.98367)
		(width 0.089408)
		(layer "In9.Cu")
		(net "FM_CPU0_PROC_ID1")
	)
	(segment
		(start 382.510792 -46.783498)
		(end 382.510792 -56.066182)
		(width 0.089408)
		(layer "In9.Cu")
		(net "FM_CPU0_PROC_ID1")
	)
	(segment
		(start 380.223776 -63.175642)
		(end 380.223776 -64.700912)
		(width 0.089408)
		(layer "In9.Cu")
		(net "FM_CPU0_PROC_ID1")
	)
	(segment
		(start 380.223776 -64.700912)
		(end 380.34214 -64.819276)
		(width 0.089408)
		(layer "In9.Cu")
		(net "FM_CPU0_PROC_ID1")
	)
	(segment
		(start 380.365 -68.141596)
		(end 379.476 -69.030596)
		(width 0.089408)
		(layer "In9.Cu")
		(net "FM_CPU0_PROC_ID1")
	)
	(segment
		(start 379.476 -69.779642)
		(end 379.354842 -69.9008)
		(width 0.089408)
		(layer "In9.Cu")
		(net "FM_CPU0_PROC_ID1")
	)
	(segment
		(start 377.720606 -70.716394)
		(end 377.720606 -71.71944)
		(width 0.089408)
		(layer "In9.Cu")
		(net "FM_CPU0_PROC_ID1")
	)
	(segment
		(start 380.34214 -67.809364)
		(end 380.365 -67.832224)
		(width 0.089408)
		(layer "In9.Cu")
		(net "FM_CPU0_PROC_ID1")
	)
	(segment
		(start 379.476 -69.773292)
		(end 379.476 -69.779642)
		(width 0.089408)
		(layer "In9.Cu")
		(net "FM_CPU0_PROC_ID1")
	)
	(segment
		(start 383.096008 -36.98367)
		(end 383.096008 -37.639752)
		(width 0.089408)
		(layer "In9.Cu")
		(net "FM_CPU0_PROC_ID1")
	)
	(segment
		(start 381.880364 -36.191444)
		(end 382.303782 -36.191444)
		(width 0.089408)
		(layer "In9.Cu")
		(net "FM_CPU0_PROC_ID1")
	)
	(segment
		(start 382.975358 -46.318932)
		(end 382.510792 -46.783498)
		(width 0.089408)
		(layer "In9.Cu")
		(net "FM_CPU0_PROC_ID1")
	)
	(segment
		(start 382.510792 -56.066182)
		(end 382.662938 -56.218328)
		(width 0.089408)
		(layer "In9.Cu")
		(net "FM_CPU0_PROC_ID1")
	)
	(segment
		(start 383.096008 -37.639752)
		(end 383.096262 -37.640006)
		(width 0.089408)
		(layer "In9.Cu")
		(net "FM_CPU0_PROC_ID1")
	)
	(segment
		(start 378.512324 -69.924676)
		(end 377.720606 -70.716394)
		(width 0.089408)
		(layer "In9.Cu")
		(net "FM_CPU0_PROC_ID1")
	)
	(segment
		(start 383.095754 -38.38067)
		(end 382.969008 -38.507416)
		(width 0.089408)
		(layer "In9.Cu")
		(net "FM_CPU0_PROC_ID1")
	)
	(segment
		(start 379.558042 -69.69125)
		(end 379.476 -69.773292)
		(width 0.089408)
		(layer "In9.Cu")
		(net "FM_CPU0_PROC_ID1")
	)
	(segment
		(start 382.975358 -41.124378)
		(end 382.975358 -46.318932)
		(width 0.089408)
		(layer "In9.Cu")
		(net "FM_CPU0_PROC_ID1")
	)
	(segment
		(start 382.662938 -56.218328)
		(end 382.662938 -59.393582)
		(width 0.089408)
		(layer "In9.Cu")
		(net "FM_CPU0_PROC_ID1")
	)
	(segment
		(start 382.969008 -38.507416)
		(end 382.969008 -41.118028)
		(width 0.089408)
		(layer "In9.Cu")
		(net "FM_CPU0_PROC_ID1")
	)
	(segment
		(start 380.7079 -71.5899)
		(end 380.1618 -72.136)
		(width 0.10795)
		(layer "F.Cu")
		(net "FM_CPU0_PROC_ID0")
	)
	(segment
		(start 380.918974 -71.09714)
		(end 380.7079 -71.308214)
		(width 0.10795)
		(layer "F.Cu")
		(net "FM_CPU0_PROC_ID0")
	)
	(segment
		(start 380.7079 -71.308214)
		(end 380.7079 -71.5899)
		(width 0.10795)
		(layer "F.Cu")
		(net "FM_CPU0_PROC_ID0")
	)
	(segment
		(start 380.1618 -72.136)
		(end 378.903992 -72.136)
		(width 0.10795)
		(layer "F.Cu")
		(net "FM_CPU0_PROC_ID0")
	)
	(segment
		(start 378.903992 -72.136)
		(end 378.744988 -72.295004)
		(width 0.10795)
		(layer "F.Cu")
		(net "FM_CPU0_PROC_ID0")
	)
	(segment
		(start 245.627144 -88.775286)
		(end 245.055644 -88.775286)
		(width 0.10795)
		(layer "F.Cu")
		(net "FM_CPU0_PROC_ID0")
	)
	(via
		(at 380.918974 -71.09714)
		(size 0.508)
		(drill 0.254)
		(layers "F.Cu" "B.Cu")
		(net "FM_CPU0_PROC_ID0")
	)
	(via
		(at 245.055644 -88.775286)
		(size 0.508)
		(drill 0.254)
		(layers "F.Cu" "B.Cu")
		(net "FM_CPU0_PROC_ID0")
	)
	(via
		(at 373.03329 -30.23235)
		(size 0.6604)
		(drill 0.3302)
		(layers "F.Cu" "B.Cu")
		(net "FM_CPU0_PROC_ID0")
	)
	(via
		(at 383.586736 -36.223956)
		(size 0.508)
		(drill 0.254)
		(layers "F.Cu" "B.Cu")
		(net "FM_CPU0_PROC_ID0")
	)
	(via
		(at 339.019896 -53.098954)
		(size 0.508)
		(drill 0.254)
		(layers "F.Cu" "B.Cu")
		(net "FM_CPU0_PROC_ID0")
	)
	(segment
		(start 238.81715 -88.79459)
		(end 238.41583 -89.19591)
		(width 0.0889)
		(layer "B.Cu")
		(net "FM_CPU0_PROC_ID0")
	)
	(segment
		(start 235.340398 -88.759538)
		(end 234.7341 -89.365836)
		(width 0.0889)
		(layer "B.Cu")
		(net "FM_CPU0_PROC_ID0")
	)
	(segment
		(start 241.451384 -89.271602)
		(end 240.996216 -88.816434)
		(width 0.0889)
		(layer "B.Cu")
		(net "FM_CPU0_PROC_ID0")
	)
	(segment
		(start 365.796068 -31.035752)
		(end 372.229888 -31.035752)
		(width 0.10795)
		(layer "B.Cu")
		(net "FM_CPU0_PROC_ID0")
	)
	(segment
		(start 341.564214 -50.20945)
		(end 351.76587 -50.20945)
		(width 0.10795)
		(layer "B.Cu")
		(net "FM_CPU0_PROC_ID0")
	)
	(segment
		(start 243.609876 -88.279986)
		(end 243.120418 -88.279986)
		(width 0.0889)
		(layer "B.Cu")
		(net "FM_CPU0_PROC_ID0")
	)
	(segment
		(start 242.589558 -88.810846)
		(end 242.269518 -88.810846)
		(width 0.0889)
		(layer "B.Cu")
		(net "FM_CPU0_PROC_ID0")
	)
	(segment
		(start 379.21311 -34.277808)
		(end 376.913902 -31.9786)
		(width 0.10795)
		(layer "B.Cu")
		(net "FM_CPU0_PROC_ID0")
	)
	(segment
		(start 232.830878 -89.336626)
		(end 232.328466 -89.839038)
		(width 0.10795)
		(layer "B.Cu")
		(net "FM_CPU0_PROC_ID0")
	)
	(segment
		(start 339.019896 -53.098954)
		(end 339.019896 -52.753768)
		(width 0.10795)
		(layer "B.Cu")
		(net "FM_CPU0_PROC_ID0")
	)
	(segment
		(start 237.955074 -89.19591)
		(end 237.537498 -88.778334)
		(width 0.0889)
		(layer "B.Cu")
		(net "FM_CPU0_PROC_ID0")
	)
	(segment
		(start 383.162556 -36.223956)
		(end 382.37287 -35.43427)
		(width 0.10795)
		(layer "B.Cu")
		(net "FM_CPU0_PROC_ID0")
	)
	(segment
		(start 244.105176 -88.775286)
		(end 243.609876 -88.279986)
		(width 0.0889)
		(layer "B.Cu")
		(net "FM_CPU0_PROC_ID0")
	)
	(segment
		(start 339.019896 -52.753768)
		(end 341.564214 -50.20945)
		(width 0.10795)
		(layer "B.Cu")
		(net "FM_CPU0_PROC_ID0")
	)
	(segment
		(start 376.359166 -31.9786)
		(end 375.344436 -30.96387)
		(width 0.10795)
		(layer "B.Cu")
		(net "FM_CPU0_PROC_ID0")
	)
	(segment
		(start 240.996216 -88.816434)
		(end 240.513362 -88.816434)
		(width 0.0889)
		(layer "B.Cu")
		(net "FM_CPU0_PROC_ID0")
	)
	(segment
		(start 237.537498 -88.778334)
		(end 237.055406 -88.778334)
		(width 0.0889)
		(layer "B.Cu")
		(net "FM_CPU0_PROC_ID0")
	)
	(segment
		(start 374.42267 -29.59735)
		(end 373.66829 -29.59735)
		(width 0.10795)
		(layer "B.Cu")
		(net "FM_CPU0_PROC_ID0")
	)
	(segment
		(start 373.66829 -29.59735)
		(end 373.03329 -30.23235)
		(width 0.10795)
		(layer "B.Cu")
		(net "FM_CPU0_PROC_ID0")
	)
	(segment
		(start 351.76587 -50.20945)
		(end 357.366824 -44.608496)
		(width 0.10795)
		(layer "B.Cu")
		(net "FM_CPU0_PROC_ID0")
	)
	(segment
		(start 375.344436 -30.96387)
		(end 375.344436 -30.519116)
		(width 0.10795)
		(layer "B.Cu")
		(net "FM_CPU0_PROC_ID0")
	)
	(segment
		(start 376.913902 -31.9786)
		(end 376.359166 -31.9786)
		(width 0.10795)
		(layer "B.Cu")
		(net "FM_CPU0_PROC_ID0")
	)
	(segment
		(start 234.7341 -89.365836)
		(end 234.51693 -89.365836)
		(width 0.0889)
		(layer "B.Cu")
		(net "FM_CPU0_PROC_ID0")
	)
	(segment
		(start 357.366824 -39.464996)
		(end 365.796068 -31.035752)
		(width 0.10795)
		(layer "B.Cu")
		(net "FM_CPU0_PROC_ID0")
	)
	(segment
		(start 237.055406 -88.778334)
		(end 236.599984 -89.233756)
		(width 0.0889)
		(layer "B.Cu")
		(net "FM_CPU0_PROC_ID0")
	)
	(segment
		(start 230.6574 -91.059)
		(end 228.473 -91.059)
		(width 0.10795)
		(layer "B.Cu")
		(net "FM_CPU0_PROC_ID0")
	)
	(segment
		(start 236.324648 -89.233756)
		(end 235.85043 -88.759538)
		(width 0.0889)
		(layer "B.Cu")
		(net "FM_CPU0_PROC_ID0")
	)
	(segment
		(start 232.328466 -89.839038)
		(end 231.877362 -89.839038)
		(width 0.10795)
		(layer "B.Cu")
		(net "FM_CPU0_PROC_ID0")
	)
	(segment
		(start 234.098846 -89.78392)
		(end 233.684064 -89.78392)
		(width 0.0889)
		(layer "B.Cu")
		(net "FM_CPU0_PROC_ID0")
	)
	(segment
		(start 383.586736 -36.223956)
		(end 383.162556 -36.223956)
		(width 0.10795)
		(layer "B.Cu")
		(net "FM_CPU0_PROC_ID0")
	)
	(segment
		(start 381.021082 -35.43427)
		(end 379.86462 -34.277808)
		(width 0.10795)
		(layer "B.Cu")
		(net "FM_CPU0_PROC_ID0")
	)
	(segment
		(start 242.269518 -88.810846)
		(end 241.808762 -89.271602)
		(width 0.0889)
		(layer "B.Cu")
		(net "FM_CPU0_PROC_ID0")
	)
	(segment
		(start 240.513362 -88.816434)
		(end 240.058194 -89.271602)
		(width 0.0889)
		(layer "B.Cu")
		(net "FM_CPU0_PROC_ID0")
	)
	(segment
		(start 231.877362 -89.839038)
		(end 230.6574 -91.059)
		(width 0.10795)
		(layer "B.Cu")
		(net "FM_CPU0_PROC_ID0")
	)
	(segment
		(start 243.120418 -88.279986)
		(end 242.589558 -88.810846)
		(width 0.0889)
		(layer "B.Cu")
		(net "FM_CPU0_PROC_ID0")
	)
	(segment
		(start 375.344436 -30.519116)
		(end 374.42267 -29.59735)
		(width 0.10795)
		(layer "B.Cu")
		(net "FM_CPU0_PROC_ID0")
	)
	(segment
		(start 238.41583 -89.19591)
		(end 237.955074 -89.19591)
		(width 0.0889)
		(layer "B.Cu")
		(net "FM_CPU0_PROC_ID0")
	)
	(segment
		(start 236.599984 -89.233756)
		(end 236.324648 -89.233756)
		(width 0.0889)
		(layer "B.Cu")
		(net "FM_CPU0_PROC_ID0")
	)
	(segment
		(start 382.37287 -35.43427)
		(end 381.021082 -35.43427)
		(width 0.10795)
		(layer "B.Cu")
		(net "FM_CPU0_PROC_ID0")
	)
	(segment
		(start 245.055644 -88.775286)
		(end 244.105176 -88.775286)
		(width 0.0889)
		(layer "B.Cu")
		(net "FM_CPU0_PROC_ID0")
	)
	(segment
		(start 379.86462 -34.277808)
		(end 379.21311 -34.277808)
		(width 0.10795)
		(layer "B.Cu")
		(net "FM_CPU0_PROC_ID0")
	)
	(segment
		(start 233.23677 -89.336626)
		(end 232.830878 -89.336626)
		(width 0.10795)
		(layer "B.Cu")
		(net "FM_CPU0_PROC_ID0")
	)
	(segment
		(start 239.212628 -88.79459)
		(end 238.81715 -88.79459)
		(width 0.0889)
		(layer "B.Cu")
		(net "FM_CPU0_PROC_ID0")
	)
	(segment
		(start 240.058194 -89.271602)
		(end 239.68964 -89.271602)
		(width 0.0889)
		(layer "B.Cu")
		(net "FM_CPU0_PROC_ID0")
	)
	(segment
		(start 241.808762 -89.271602)
		(end 241.451384 -89.271602)
		(width 0.0889)
		(layer "B.Cu")
		(net "FM_CPU0_PROC_ID0")
	)
	(segment
		(start 234.51693 -89.365836)
		(end 234.098846 -89.78392)
		(width 0.0889)
		(layer "B.Cu")
		(net "FM_CPU0_PROC_ID0")
	)
	(segment
		(start 357.366824 -44.608496)
		(end 357.366824 -39.464996)
		(width 0.10795)
		(layer "B.Cu")
		(net "FM_CPU0_PROC_ID0")
	)
	(segment
		(start 372.229888 -31.035752)
		(end 373.03329 -30.23235)
		(width 0.10795)
		(layer "B.Cu")
		(net "FM_CPU0_PROC_ID0")
	)
	(segment
		(start 233.684064 -89.78392)
		(end 233.23677 -89.336626)
		(width 0.0889)
		(layer "B.Cu")
		(net "FM_CPU0_PROC_ID0")
	)
	(segment
		(start 235.85043 -88.759538)
		(end 235.340398 -88.759538)
		(width 0.0889)
		(layer "B.Cu")
		(net "FM_CPU0_PROC_ID0")
	)
	(segment
		(start 239.68964 -89.271602)
		(end 239.212628 -88.79459)
		(width 0.0889)
		(layer "B.Cu")
		(net "FM_CPU0_PROC_ID0")
	)
	(segment
		(start 301.422562 -88.691212)
		(end 302.20285 -88.691212)
		(width 0.0889)
		(layer "In2.Cu")
		(net "FM_CPU0_PROC_ID0")
	)
	(segment
		(start 247.466104 -87.881714)
		(end 247.827546 -87.881714)
		(width 0.0889)
		(layer "In2.Cu")
		(net "FM_CPU0_PROC_ID0")
	)
	(segment
		(start 252.947424 -87.881714)
		(end 253.248922 -88.183212)
		(width 0.0889)
		(layer "In2.Cu")
		(net "FM_CPU0_PROC_ID0")
	)
	(segment
		(start 274.687538 -90.870786)
		(end 274.693888 -90.881454)
		(width 0.0889)
		(layer "In2.Cu")
		(net "FM_CPU0_PROC_ID0")
	)
	(segment
		(start 252.315726 -88.183212)
		(end 252.617224 -87.881714)
		(width 0.0889)
		(layer "In2.Cu")
		(net "FM_CPU0_PROC_ID0")
	)
	(segment
		(start 251.230384 -87.881714)
		(end 251.531882 -88.183212)
		(width 0.0889)
		(layer "In2.Cu")
		(net "FM_CPU0_PROC_ID0")
	)
	(segment
		(start 285.474664 -89.186258)
		(end 285.96971 -88.691212)
		(width 0.0889)
		(layer "In2.Cu")
		(net "FM_CPU0_PROC_ID0")
	)
	(segment
		(start 288.466784 -88.691212)
		(end 288.768282 -88.99271)
		(width 0.0889)
		(layer "In2.Cu")
		(net "FM_CPU0_PROC_ID0")
	)
	(segment
		(start 266.500356 -90.85199)
		(end 266.535916 -90.85199)
		(width 0.0889)
		(layer "In2.Cu")
		(net "FM_CPU0_PROC_ID0")
	)
	(segment
		(start 307.000148 -86.911688)
		(end 309.429912 -86.911688)
		(width 0.089408)
		(layer "In2.Cu")
		(net "FM_CPU0_PROC_ID0")
	)
	(segment
		(start 304.927254 -88.497918)
		(end 305.413918 -88.497918)
		(width 0.089408)
		(layer "In2.Cu")
		(net "FM_CPU0_PROC_ID0")
	)
	(segment
		(start 258.77012 -90.356436)
		(end 258.8133 -90.356436)
		(width 0.0889)
		(layer "In2.Cu")
		(net "FM_CPU0_PROC_ID0")
	)
	(segment
		(start 264.285984 -90.550746)
		(end 264.289286 -90.556588)
		(width 0.0889)
		(layer "In2.Cu")
		(net "FM_CPU0_PROC_ID0")
	)
	(segment
		(start 289.102038 -88.99271)
		(end 289.403536 -88.691212)
		(width 0.0889)
		(layer "In2.Cu")
		(net "FM_CPU0_PROC_ID0")
	)
	(segment
		(start 297.353228 -88.99271)
		(end 297.686984 -88.99271)
		(width 0.0889)
		(layer "In2.Cu")
		(net "FM_CPU0_PROC_ID0")
	)
	(segment
		(start 287.051242 -88.99271)
		(end 287.384998 -88.99271)
		(width 0.0889)
		(layer "In2.Cu")
		(net "FM_CPU0_PROC_ID0")
	)
	(segment
		(start 262.2042 -90.356436)
		(end 262.236966 -90.356436)
		(width 0.0889)
		(layer "In2.Cu")
		(net "FM_CPU0_PROC_ID0")
	)
	(segment
		(start 268.762734 -90.861134)
		(end 271.203166 -90.861134)
		(width 0.0889)
		(layer "In2.Cu")
		(net "FM_CPU0_PROC_ID0")
	)
	(segment
		(start 284.244288 -89.915238)
		(end 284.477714 -89.681812)
		(width 0.0889)
		(layer "In2.Cu")
		(net "FM_CPU0_PROC_ID0")
	)
	(segment
		(start 314.402216 -81.939384)
		(end 314.402216 -74.096372)
		(width 0.089408)
		(layer "In2.Cu")
		(net "FM_CPU0_PROC_ID0")
	)
	(segment
		(start 249.183144 -87.881714)
		(end 249.544586 -87.881714)
		(width 0.0889)
		(layer "In2.Cu")
		(net "FM_CPU0_PROC_ID0")
	)
	(segment
		(start 297.05173 -88.691212)
		(end 297.353228 -88.99271)
		(width 0.0889)
		(layer "In2.Cu")
		(net "FM_CPU0_PROC_ID0")
	)
	(segment
		(start 255.33604 -88.375236)
		(end 255.368806 -88.375236)
		(width 0.0889)
		(layer "In2.Cu")
		(net "FM_CPU0_PROC_ID0")
	)
	(segment
		(start 285.96971 -88.691212)
		(end 286.749744 -88.691212)
		(width 0.0889)
		(layer "In2.Cu")
		(net "FM_CPU0_PROC_ID0")
	)
	(segment
		(start 285.336234 -89.186258)
		(end 285.474664 -89.186258)
		(width 0.0889)
		(layer "In2.Cu")
		(net "FM_CPU0_PROC_ID0")
	)
	(segment
		(start 246.971312 -88.376506)
		(end 247.466104 -87.881714)
		(width 0.0889)
		(layer "In2.Cu")
		(net "FM_CPU0_PROC_ID0")
	)
	(segment
		(start 263.06653 -90.85199)
		(end 263.10209 -90.85199)
		(width 0.0889)
		(layer "In2.Cu")
		(net "FM_CPU0_PROC_ID0")
	)
	(segment
		(start 303.684432 -88.65616)
		(end 304.217832 -88.12276)
		(width 0.089408)
		(layer "In2.Cu")
		(net "FM_CPU0_PROC_ID0")
	)
	(segment
		(start 299.930312 -89.488518)
		(end 300.2915 -89.488518)
		(width 0.0889)
		(layer "In2.Cu")
		(net "FM_CPU0_PROC_ID0")
	)
	(segment
		(start 334.063594 -53.853842)
		(end 338.341208 -53.853842)
		(width 0.089408)
		(layer "In2.Cu")
		(net "FM_CPU0_PROC_ID0")
	)
	(segment
		(start 292.536118 -88.99271)
		(end 292.837616 -88.691212)
		(width 0.0889)
		(layer "In2.Cu")
		(net "FM_CPU0_PROC_ID0")
	)
	(segment
		(start 287.686496 -88.691212)
		(end 288.466784 -88.691212)
		(width 0.0889)
		(layer "In2.Cu")
		(net "FM_CPU0_PROC_ID0")
	)
	(segment
		(start 261.352284 -89.86139)
		(end 261.382256 -89.86139)
		(width 0.0889)
		(layer "In2.Cu")
		(net "FM_CPU0_PROC_ID0")
	)
	(segment
		(start 284.477714 -89.681812)
		(end 284.84068 -89.681812)
		(width 0.0889)
		(layer "In2.Cu")
		(net "FM_CPU0_PROC_ID0")
	)
	(segment
		(start 297.686984 -88.99271)
		(end 298.182792 -89.488518)
		(width 0.0889)
		(layer "In2.Cu")
		(net "FM_CPU0_PROC_ID0")
	)
	(segment
		(start 304.217832 -88.12276)
		(end 304.552096 -88.12276)
		(width 0.089408)
		(layer "In2.Cu")
		(net "FM_CPU0_PROC_ID0")
	)
	(segment
		(start 302.20285 -88.691212)
		(end 302.504348 -88.99271)
		(width 0.0889)
		(layer "In2.Cu")
		(net "FM_CPU0_PROC_ID0")
	)
	(segment
		(start 291.120576 -88.691212)
		(end 291.900864 -88.691212)
		(width 0.0889)
		(layer "In2.Cu")
		(net "FM_CPU0_PROC_ID0")
	)
	(segment
		(start 299.072046 -89.186258)
		(end 299.402246 -89.186258)
		(width 0.0889)
		(layer "In2.Cu")
		(net "FM_CPU0_PROC_ID0")
	)
	(segment
		(start 314.402216 -74.096372)
		(end 320.378582 -68.120006)
		(width 0.089408)
		(layer "In2.Cu")
		(net "FM_CPU0_PROC_ID0")
	)
	(segment
		(start 283.949394 -90.97391)
		(end 284.244288 -90.679016)
		(width 0.0889)
		(layer "In2.Cu")
		(net "FM_CPU0_PROC_ID0")
	)
	(segment
		(start 287.384998 -88.99271)
		(end 287.686496 -88.691212)
		(width 0.0889)
		(layer "In2.Cu")
		(net "FM_CPU0_PROC_ID0")
	)
	(segment
		(start 304.552096 -88.12276)
		(end 304.927254 -88.497918)
		(width 0.089408)
		(layer "In2.Cu")
		(net "FM_CPU0_PROC_ID0")
	)
	(segment
		(start 282.910788 -90.670888)
		(end 283.316172 -90.670888)
		(width 0.0889)
		(layer "In2.Cu")
		(net "FM_CPU0_PROC_ID0")
	)
	(segment
		(start 248.881646 -88.183212)
		(end 249.183144 -87.881714)
		(width 0.0889)
		(layer "In2.Cu")
		(net "FM_CPU0_PROC_ID0")
	)
	(segment
		(start 290.485322 -88.99271)
		(end 290.819078 -88.99271)
		(width 0.0889)
		(layer "In2.Cu")
		(net "FM_CPU0_PROC_ID0")
	)
	(segment
		(start 249.846084 -88.183212)
		(end 250.598686 -88.183212)
		(width 0.0889)
		(layer "In2.Cu")
		(net "FM_CPU0_PROC_ID0")
	)
	(segment
		(start 300.2915 -89.488518)
		(end 300.787308 -88.99271)
		(width 0.0889)
		(layer "In2.Cu")
		(net "FM_CPU0_PROC_ID0")
	)
	(segment
		(start 290.819078 -88.99271)
		(end 291.120576 -88.691212)
		(width 0.0889)
		(layer "In2.Cu")
		(net "FM_CPU0_PROC_ID0")
	)
	(segment
		(start 299.402246 -89.186258)
		(end 299.493686 -89.277698)
		(width 0.0889)
		(layer "In2.Cu")
		(net "FM_CPU0_PROC_ID0")
	)
	(segment
		(start 300.787308 -88.99271)
		(end 301.121064 -88.99271)
		(width 0.0889)
		(layer "In2.Cu")
		(net "FM_CPU0_PROC_ID0")
	)
	(segment
		(start 327.2028 -60.714636)
		(end 334.063594 -53.853842)
		(width 0.089408)
		(layer "In2.Cu")
		(net "FM_CPU0_PROC_ID0")
	)
	(segment
		(start 268.258036 -90.356436)
		(end 268.762734 -90.861134)
		(width 0.0889)
		(layer "In2.Cu")
		(net "FM_CPU0_PROC_ID0")
	)
	(segment
		(start 301.121064 -88.99271)
		(end 301.422562 -88.691212)
		(width 0.0889)
		(layer "In2.Cu")
		(net "FM_CPU0_PROC_ID0")
	)
	(segment
		(start 320.378582 -66.519552)
		(end 326.183498 -60.714636)
		(width 0.089408)
		(layer "In2.Cu")
		(net "FM_CPU0_PROC_ID0")
	)
	(segment
		(start 284.244288 -90.679016)
		(end 284.244288 -89.915238)
		(width 0.0889)
		(layer "In2.Cu")
		(net "FM_CPU0_PROC_ID0")
	)
	(segment
		(start 253.955296 -88.183212)
		(end 254.258318 -87.88019)
		(width 0.0889)
		(layer "In2.Cu")
		(net "FM_CPU0_PROC_ID0")
	)
	(segment
		(start 309.429912 -86.911688)
		(end 314.402216 -81.939384)
		(width 0.089408)
		(layer "In2.Cu")
		(net "FM_CPU0_PROC_ID0")
	)
	(segment
		(start 245.454424 -88.376506)
		(end 246.971312 -88.376506)
		(width 0.0889)
		(layer "In2.Cu")
		(net "FM_CPU0_PROC_ID0")
	)
	(segment
		(start 303.174654 -88.65616)
		(end 303.684432 -88.65616)
		(width 0.0889)
		(layer "In2.Cu")
		(net "FM_CPU0_PROC_ID0")
	)
	(segment
		(start 289.403536 -88.691212)
		(end 290.183824 -88.691212)
		(width 0.0889)
		(layer "In2.Cu")
		(net "FM_CPU0_PROC_ID0")
	)
	(segment
		(start 271.811496 -91.469464)
		(end 272.954242 -91.469464)
		(width 0.0889)
		(layer "In2.Cu")
		(net "FM_CPU0_PROC_ID0")
	)
	(segment
		(start 284.84068 -89.681812)
		(end 285.336234 -89.186258)
		(width 0.0889)
		(layer "In2.Cu")
		(net "FM_CPU0_PROC_ID0")
	)
	(segment
		(start 254.258318 -87.88019)
		(end 254.514096 -87.88019)
		(width 0.0889)
		(layer "In2.Cu")
		(net "FM_CPU0_PROC_ID0")
	)
	(segment
		(start 252.617224 -87.881714)
		(end 252.947424 -87.881714)
		(width 0.0889)
		(layer "In2.Cu")
		(net "FM_CPU0_PROC_ID0")
	)
	(segment
		(start 257.91541 -89.86139)
		(end 257.948176 -89.86139)
		(width 0.0889)
		(layer "In2.Cu")
		(net "FM_CPU0_PROC_ID0")
	)
	(segment
		(start 250.900184 -87.881714)
		(end 251.230384 -87.881714)
		(width 0.0889)
		(layer "In2.Cu")
		(net "FM_CPU0_PROC_ID0")
	)
	(segment
		(start 272.954242 -91.469464)
		(end 273.096228 -91.327478)
		(width 0.0889)
		(layer "In2.Cu")
		(net "FM_CPU0_PROC_ID0")
	)
	(segment
		(start 257.05308 -89.365836)
		(end 257.085846 -89.365836)
		(width 0.0889)
		(layer "In2.Cu")
		(net "FM_CPU0_PROC_ID0")
	)
	(segment
		(start 305.413918 -88.497918)
		(end 307.000148 -86.911688)
		(width 0.089408)
		(layer "In2.Cu")
		(net "FM_CPU0_PROC_ID0")
	)
	(segment
		(start 298.182792 -89.488518)
		(end 298.769786 -89.488518)
		(width 0.0889)
		(layer "In2.Cu")
		(net "FM_CPU0_PROC_ID0")
	)
	(segment
		(start 288.768282 -88.99271)
		(end 289.102038 -88.99271)
		(width 0.0889)
		(layer "In2.Cu")
		(net "FM_CPU0_PROC_ID0")
	)
	(segment
		(start 286.749744 -88.691212)
		(end 287.051242 -88.99271)
		(width 0.0889)
		(layer "In2.Cu")
		(net "FM_CPU0_PROC_ID0")
	)
	(segment
		(start 339.019896 -53.175154)
		(end 339.019896 -53.098954)
		(width 0.089408)
		(layer "In2.Cu")
		(net "FM_CPU0_PROC_ID0")
	)
	(segment
		(start 292.837616 -88.691212)
		(end 297.05173 -88.691212)
		(width 0.0889)
		(layer "In2.Cu")
		(net "FM_CPU0_PROC_ID0")
	)
	(segment
		(start 292.202362 -88.99271)
		(end 292.536118 -88.99271)
		(width 0.0889)
		(layer "In2.Cu")
		(net "FM_CPU0_PROC_ID0")
	)
	(segment
		(start 299.493686 -89.277698)
		(end 299.719492 -89.277698)
		(width 0.0889)
		(layer "In2.Cu")
		(net "FM_CPU0_PROC_ID0")
	)
	(segment
		(start 264.783316 -90.85199)
		(end 264.818876 -90.85199)
		(width 0.0889)
		(layer "In2.Cu")
		(net "FM_CPU0_PROC_ID0")
	)
	(segment
		(start 275.711158 -90.87104)
		(end 275.719286 -90.856816)
		(width 0.0889)
		(layer "In2.Cu")
		(net "FM_CPU0_PROC_ID0")
	)
	(segment
		(start 247.827546 -87.881714)
		(end 248.129044 -88.183212)
		(width 0.0889)
		(layer "In2.Cu")
		(net "FM_CPU0_PROC_ID0")
	)
	(segment
		(start 326.183498 -60.714636)
		(end 327.2028 -60.714636)
		(width 0.089408)
		(layer "In2.Cu")
		(net "FM_CPU0_PROC_ID0")
	)
	(segment
		(start 338.341208 -53.853842)
		(end 339.019896 -53.175154)
		(width 0.089408)
		(layer "In2.Cu")
		(net "FM_CPU0_PROC_ID0")
	)
	(segment
		(start 298.769786 -89.488518)
		(end 299.072046 -89.186258)
		(width 0.0889)
		(layer "In2.Cu")
		(net "FM_CPU0_PROC_ID0")
	)
	(segment
		(start 302.504348 -88.99271)
		(end 302.838104 -88.99271)
		(width 0.0889)
		(layer "In2.Cu")
		(net "FM_CPU0_PROC_ID0")
	)
	(segment
		(start 290.183824 -88.691212)
		(end 290.485322 -88.99271)
		(width 0.0889)
		(layer "In2.Cu")
		(net "FM_CPU0_PROC_ID0")
	)
	(segment
		(start 291.900864 -88.691212)
		(end 292.202362 -88.99271)
		(width 0.0889)
		(layer "In2.Cu")
		(net "FM_CPU0_PROC_ID0")
	)
	(segment
		(start 267.36548 -90.356436)
		(end 268.258036 -90.356436)
		(width 0.0889)
		(layer "In2.Cu")
		(net "FM_CPU0_PROC_ID0")
	)
	(segment
		(start 256.19837 -88.87079)
		(end 256.231136 -88.87079)
		(width 0.0889)
		(layer "In2.Cu")
		(net "FM_CPU0_PROC_ID0")
	)
	(segment
		(start 283.619194 -90.97391)
		(end 283.949394 -90.97391)
		(width 0.0889)
		(layer "In2.Cu")
		(net "FM_CPU0_PROC_ID0")
	)
	(segment
		(start 302.838104 -88.99271)
		(end 303.174654 -88.65616)
		(width 0.0889)
		(layer "In2.Cu")
		(net "FM_CPU0_PROC_ID0")
	)
	(segment
		(start 250.598686 -88.183212)
		(end 250.900184 -87.881714)
		(width 0.0889)
		(layer "In2.Cu")
		(net "FM_CPU0_PROC_ID0")
	)
	(segment
		(start 283.316172 -90.670888)
		(end 283.619194 -90.97391)
		(width 0.0889)
		(layer "In2.Cu")
		(net "FM_CPU0_PROC_ID0")
	)
	(segment
		(start 260.48716 -90.356436)
		(end 260.53034 -90.356436)
		(width 0.0889)
		(layer "In2.Cu")
		(net "FM_CPU0_PROC_ID0")
	)
	(segment
		(start 249.544586 -87.881714)
		(end 249.846084 -88.183212)
		(width 0.0889)
		(layer "In2.Cu")
		(net "FM_CPU0_PROC_ID0")
	)
	(segment
		(start 299.719492 -89.277698)
		(end 299.930312 -89.488518)
		(width 0.0889)
		(layer "In2.Cu")
		(net "FM_CPU0_PROC_ID0")
	)
	(segment
		(start 248.129044 -88.183212)
		(end 248.881646 -88.183212)
		(width 0.0889)
		(layer "In2.Cu")
		(net "FM_CPU0_PROC_ID0")
	)
	(segment
		(start 273.471132 -91.165934)
		(end 273.503898 -91.165934)
		(width 0.0889)
		(layer "In2.Cu")
		(net "FM_CPU0_PROC_ID0")
	)
	(segment
		(start 320.378582 -68.120006)
		(end 320.378582 -66.519552)
		(width 0.089408)
		(layer "In2.Cu")
		(net "FM_CPU0_PROC_ID0")
	)
	(segment
		(start 245.055644 -88.775286)
		(end 245.454424 -88.376506)
		(width 0.0889)
		(layer "In2.Cu")
		(net "FM_CPU0_PROC_ID0")
	)
	(segment
		(start 251.531882 -88.183212)
		(end 252.315726 -88.183212)
		(width 0.0889)
		(layer "In2.Cu")
		(net "FM_CPU0_PROC_ID0")
	)
	(segment
		(start 253.248922 -88.183212)
		(end 253.955296 -88.183212)
		(width 0.0889)
		(layer "In2.Cu")
		(net "FM_CPU0_PROC_ID0")
	)
	(segment
		(start 271.203166 -90.861134)
		(end 271.811496 -91.469464)
		(width 0.0889)
		(layer "In2.Cu")
		(net "FM_CPU0_PROC_ID0")
	)
	(arc
		(start 275.719286 -90.856816)
		(mid 276.06576 -90.670628)
		(end 276.404324 -90.870786)
		(width 0.0889)
		(layer "In2.Cu")
		(net "FM_CPU0_PROC_ID0")
	)
	(arc
		(start 257.42138 -89.565988)
		(mid 257.629988 -89.77792)
		(end 257.91541 -89.86139)
		(width 0.0889)
		(layer "In2.Cu")
		(net "FM_CPU0_PROC_ID0")
	)
	(arc
		(start 254.514096 -87.88019)
		(mid 254.705738 -87.937356)
		(end 254.84582 -88.080088)
		(width 0.0889)
		(layer "In2.Cu")
		(net "FM_CPU0_PROC_ID0")
	)
	(arc
		(start 276.404324 -90.870786)
		(mid 276.916134 -91.166325)
		(end 277.427944 -90.870786)
		(width 0.0889)
		(layer "In2.Cu")
		(net "FM_CPU0_PROC_ID0")
	)
	(arc
		(start 266.535916 -90.85199)
		(mid 266.82134 -90.768523)
		(end 267.029946 -90.556588)
		(width 0.0889)
		(layer "In2.Cu")
		(net "FM_CPU0_PROC_ID0")
	)
	(arc
		(start 255.368806 -88.375236)
		(mid 255.562656 -88.431586)
		(end 255.70434 -88.575388)
		(width 0.0889)
		(layer "In2.Cu")
		(net "FM_CPU0_PROC_ID0")
	)
	(arc
		(start 259.30352 -90.061288)
		(mid 259.65023 -89.861104)
		(end 259.99694 -90.061288)
		(width 0.0889)
		(layer "In2.Cu")
		(net "FM_CPU0_PROC_ID0")
	)
	(arc
		(start 280.862024 -90.870786)
		(mid 281.208734 -90.670602)
		(end 281.555444 -90.870786)
		(width 0.0889)
		(layer "In2.Cu")
		(net "FM_CPU0_PROC_ID0")
	)
	(arc
		(start 256.231136 -88.87079)
		(mid 256.422778 -88.927956)
		(end 256.56286 -89.070688)
		(width 0.0889)
		(layer "In2.Cu")
		(net "FM_CPU0_PROC_ID0")
	)
	(arc
		(start 258.2799 -90.061288)
		(mid 258.486904 -90.272152)
		(end 258.77012 -90.356436)
		(width 0.0889)
		(layer "In2.Cu")
		(net "FM_CPU0_PROC_ID0")
	)
	(arc
		(start 261.02056 -90.061288)
		(mid 261.160639 -89.918552)
		(end 261.352284 -89.86139)
		(width 0.0889)
		(layer "In2.Cu")
		(net "FM_CPU0_PROC_ID0")
	)
	(arc
		(start 263.59612 -90.556588)
		(mid 263.93941 -90.356292)
		(end 264.285984 -90.550746)
		(width 0.0889)
		(layer "In2.Cu")
		(net "FM_CPU0_PROC_ID0")
	)
	(arc
		(start 258.8133 -90.356436)
		(mid 259.096517 -90.272155)
		(end 259.30352 -90.061288)
		(width 0.0889)
		(layer "In2.Cu")
		(net "FM_CPU0_PROC_ID0")
	)
	(arc
		(start 260.53034 -90.356436)
		(mid 260.813557 -90.272155)
		(end 261.02056 -90.061288)
		(width 0.0889)
		(layer "In2.Cu")
		(net "FM_CPU0_PROC_ID0")
	)
	(arc
		(start 267.029946 -90.556588)
		(mid 267.171629 -90.412784)
		(end 267.36548 -90.356436)
		(width 0.0889)
		(layer "In2.Cu")
		(net "FM_CPU0_PROC_ID0")
	)
	(arc
		(start 273.096228 -91.327478)
		(mid 273.268193 -91.210759)
		(end 273.471132 -91.165934)
		(width 0.0889)
		(layer "In2.Cu")
		(net "FM_CPU0_PROC_ID0")
	)
	(arc
		(start 273.994118 -90.870786)
		(mid 274.340828 -90.670602)
		(end 274.687538 -90.870786)
		(width 0.0889)
		(layer "In2.Cu")
		(net "FM_CPU0_PROC_ID0")
	)
	(arc
		(start 278.121364 -90.870786)
		(mid 278.633174 -91.166325)
		(end 279.144984 -90.870786)
		(width 0.0889)
		(layer "In2.Cu")
		(net "FM_CPU0_PROC_ID0")
	)
	(arc
		(start 257.948176 -89.86139)
		(mid 258.139818 -89.918556)
		(end 258.2799 -90.061288)
		(width 0.0889)
		(layer "In2.Cu")
		(net "FM_CPU0_PROC_ID0")
	)
	(arc
		(start 274.693888 -90.881454)
		(mid 275.205445 -91.166257)
		(end 275.711158 -90.87104)
		(width 0.0889)
		(layer "In2.Cu")
		(net "FM_CPU0_PROC_ID0")
	)
	(arc
		(start 279.838404 -90.870786)
		(mid 280.350214 -91.166325)
		(end 280.862024 -90.870786)
		(width 0.0889)
		(layer "In2.Cu")
		(net "FM_CPU0_PROC_ID0")
	)
	(arc
		(start 282.579064 -90.870786)
		(mid 282.719143 -90.72805)
		(end 282.910788 -90.670888)
		(width 0.0889)
		(layer "In2.Cu")
		(net "FM_CPU0_PROC_ID0")
	)
	(arc
		(start 273.503898 -91.165934)
		(mid 273.787115 -91.081653)
		(end 273.994118 -90.870786)
		(width 0.0889)
		(layer "In2.Cu")
		(net "FM_CPU0_PROC_ID0")
	)
	(arc
		(start 263.10209 -90.85199)
		(mid 263.387514 -90.768523)
		(end 263.59612 -90.556588)
		(width 0.0889)
		(layer "In2.Cu")
		(net "FM_CPU0_PROC_ID0")
	)
	(arc
		(start 281.555444 -90.870786)
		(mid 282.067254 -91.166325)
		(end 282.579064 -90.870786)
		(width 0.0889)
		(layer "In2.Cu")
		(net "FM_CPU0_PROC_ID0")
	)
	(arc
		(start 262.5725 -90.556588)
		(mid 262.781108 -90.76852)
		(end 263.06653 -90.85199)
		(width 0.0889)
		(layer "In2.Cu")
		(net "FM_CPU0_PROC_ID0")
	)
	(arc
		(start 257.085846 -89.365836)
		(mid 257.279696 -89.422186)
		(end 257.42138 -89.565988)
		(width 0.0889)
		(layer "In2.Cu")
		(net "FM_CPU0_PROC_ID0")
	)
	(arc
		(start 266.006326 -90.556588)
		(mid 266.214934 -90.76852)
		(end 266.500356 -90.85199)
		(width 0.0889)
		(layer "In2.Cu")
		(net "FM_CPU0_PROC_ID0")
	)
	(arc
		(start 277.427944 -90.870786)
		(mid 277.774654 -90.670602)
		(end 278.121364 -90.870786)
		(width 0.0889)
		(layer "In2.Cu")
		(net "FM_CPU0_PROC_ID0")
	)
	(arc
		(start 254.84582 -88.080088)
		(mid 255.052824 -88.290952)
		(end 255.33604 -88.375236)
		(width 0.0889)
		(layer "In2.Cu")
		(net "FM_CPU0_PROC_ID0")
	)
	(arc
		(start 265.312906 -90.556588)
		(mid 265.659616 -90.356277)
		(end 266.006326 -90.556588)
		(width 0.0889)
		(layer "In2.Cu")
		(net "FM_CPU0_PROC_ID0")
	)
	(arc
		(start 255.70434 -88.575388)
		(mid 255.912948 -88.78732)
		(end 256.19837 -88.87079)
		(width 0.0889)
		(layer "In2.Cu")
		(net "FM_CPU0_PROC_ID0")
	)
	(arc
		(start 256.56286 -89.070688)
		(mid 256.769864 -89.281552)
		(end 257.05308 -89.365836)
		(width 0.0889)
		(layer "In2.Cu")
		(net "FM_CPU0_PROC_ID0")
	)
	(arc
		(start 279.144984 -90.870786)
		(mid 279.491694 -90.670602)
		(end 279.838404 -90.870786)
		(width 0.0889)
		(layer "In2.Cu")
		(net "FM_CPU0_PROC_ID0")
	)
	(arc
		(start 261.71398 -90.061288)
		(mid 261.920984 -90.272152)
		(end 262.2042 -90.356436)
		(width 0.0889)
		(layer "In2.Cu")
		(net "FM_CPU0_PROC_ID0")
	)
	(arc
		(start 259.99694 -90.061288)
		(mid 260.203944 -90.272152)
		(end 260.48716 -90.356436)
		(width 0.0889)
		(layer "In2.Cu")
		(net "FM_CPU0_PROC_ID0")
	)
	(arc
		(start 264.818876 -90.85199)
		(mid 265.1043 -90.768523)
		(end 265.312906 -90.556588)
		(width 0.0889)
		(layer "In2.Cu")
		(net "FM_CPU0_PROC_ID0")
	)
	(arc
		(start 261.382256 -89.86139)
		(mid 261.573898 -89.918556)
		(end 261.71398 -90.061288)
		(width 0.0889)
		(layer "In2.Cu")
		(net "FM_CPU0_PROC_ID0")
	)
	(arc
		(start 264.289286 -90.556588)
		(mid 264.497894 -90.76852)
		(end 264.783316 -90.85199)
		(width 0.0889)
		(layer "In2.Cu")
		(net "FM_CPU0_PROC_ID0")
	)
	(arc
		(start 262.236966 -90.356436)
		(mid 262.430816 -90.412786)
		(end 262.5725 -90.556588)
		(width 0.0889)
		(layer "In2.Cu")
		(net "FM_CPU0_PROC_ID0")
	)
	(segment
		(start 381.874776 -65.124076)
		(end 381.039624 -65.959228)
		(width 0.089408)
		(layer "In9.Cu")
		(net "FM_CPU0_PROC_ID0")
	)
	(segment
		(start 383.29743 -46.951392)
		(end 383.29743 -54.25694)
		(width 0.089408)
		(layer "In9.Cu")
		(net "FM_CPU0_PROC_ID0")
	)
	(segment
		(start 383.82067 -54.78018)
		(end 383.82067 -55.138828)
		(width 0.089408)
		(layer "In9.Cu")
		(net "FM_CPU0_PROC_ID0")
	)
	(segment
		(start 383.82067 -55.138828)
		(end 383.820416 -55.139082)
		(width 0.089408)
		(layer "In9.Cu")
		(net "FM_CPU0_PROC_ID0")
	)
	(segment
		(start 383.643632 -40.83812)
		(end 384.305302 -41.49979)
		(width 0.089408)
		(layer "In9.Cu")
		(net "FM_CPU0_PROC_ID0")
	)
	(segment
		(start 383.586736 -36.223956)
		(end 383.77114 -36.40836)
		(width 0.089408)
		(layer "In9.Cu")
		(net "FM_CPU0_PROC_ID0")
	)
	(segment
		(start 384.305302 -41.49979)
		(end 384.305302 -45.94352)
		(width 0.089408)
		(layer "In9.Cu")
		(net "FM_CPU0_PROC_ID0")
	)
	(segment
		(start 383.362962 -56.409336)
		(end 383.362962 -59.72683)
		(width 0.089408)
		(layer "In9.Cu")
		(net "FM_CPU0_PROC_ID0")
	)
	(segment
		(start 381.039624 -65.959228)
		(end 381.039624 -68.421504)
		(width 0.089408)
		(layer "In9.Cu")
		(net "FM_CPU0_PROC_ID0")
	)
	(segment
		(start 382.595882 -60.49391)
		(end 382.595882 -63.671704)
		(width 0.089408)
		(layer "In9.Cu")
		(net "FM_CPU0_PROC_ID0")
	)
	(segment
		(start 381.039624 -68.421504)
		(end 380.784608 -68.67652)
		(width 0.089408)
		(layer "In9.Cu")
		(net "FM_CPU0_PROC_ID0")
	)
	(segment
		(start 380.659132 -69.953124)
		(end 380.659132 -70.837298)
		(width 0.089408)
		(layer "In9.Cu")
		(net "FM_CPU0_PROC_ID0")
	)
	(segment
		(start 383.77114 -38.659816)
		(end 383.643632 -38.787324)
		(width 0.089408)
		(layer "In9.Cu")
		(net "FM_CPU0_PROC_ID0")
	)
	(segment
		(start 382.595882 -63.671704)
		(end 381.874776 -64.39281)
		(width 0.089408)
		(layer "In9.Cu")
		(net "FM_CPU0_PROC_ID0")
	)
	(segment
		(start 380.659132 -70.837298)
		(end 380.918974 -71.09714)
		(width 0.089408)
		(layer "In9.Cu")
		(net "FM_CPU0_PROC_ID0")
	)
	(segment
		(start 383.362962 -59.72683)
		(end 382.595882 -60.49391)
		(width 0.089408)
		(layer "In9.Cu")
		(net "FM_CPU0_PROC_ID0")
	)
	(segment
		(start 384.305302 -45.94352)
		(end 383.29743 -46.951392)
		(width 0.089408)
		(layer "In9.Cu")
		(net "FM_CPU0_PROC_ID0")
	)
	(segment
		(start 383.820416 -55.951882)
		(end 383.362962 -56.409336)
		(width 0.089408)
		(layer "In9.Cu")
		(net "FM_CPU0_PROC_ID0")
	)
	(segment
		(start 381.874776 -64.39281)
		(end 381.874776 -65.124076)
		(width 0.089408)
		(layer "In9.Cu")
		(net "FM_CPU0_PROC_ID0")
	)
	(segment
		(start 383.29743 -54.25694)
		(end 383.82067 -54.78018)
		(width 0.089408)
		(layer "In9.Cu")
		(net "FM_CPU0_PROC_ID0")
	)
	(segment
		(start 380.784608 -68.67652)
		(end 380.784608 -69.827648)
		(width 0.089408)
		(layer "In9.Cu")
		(net "FM_CPU0_PROC_ID0")
	)
	(segment
		(start 383.643632 -38.787324)
		(end 383.643632 -40.83812)
		(width 0.089408)
		(layer "In9.Cu")
		(net "FM_CPU0_PROC_ID0")
	)
	(segment
		(start 383.820416 -55.139082)
		(end 383.820416 -55.951882)
		(width 0.089408)
		(layer "In9.Cu")
		(net "FM_CPU0_PROC_ID0")
	)
	(segment
		(start 383.77114 -36.40836)
		(end 383.77114 -38.659816)
		(width 0.089408)
		(layer "In9.Cu")
		(net "FM_CPU0_PROC_ID0")
	)
	(segment
		(start 380.784608 -69.827648)
		(end 380.659132 -69.953124)
		(width 0.089408)
		(layer "In9.Cu")
		(net "FM_CPU0_PROC_ID0")
	)
	(segment
		(start 398.004792 -127.348488)
		(end 398.64284 -127.348488)
		(width 0.10795)
		(layer "F.Cu")
		(net "A_USB2_COMP")
	)
	(segment
		(start 397.98498 -125.721364)
		(end 397.6878 -126.018544)
		(width 0.10795)
		(layer "F.Cu")
		(net "A_USB2_COMP")
	)
	(segment
		(start 397.98498 -125.33503)
		(end 397.98498 -125.721364)
		(width 0.10795)
		(layer "F.Cu")
		(net "A_USB2_COMP")
	)
	(segment
		(start 403.707346 -125.349)
		(end 403.8854 -125.170946)
		(width 0.10795)
		(layer "F.Cu")
		(net "A_USB2_COMP")
	)
	(segment
		(start 397.6878 -126.018544)
		(end 397.6878 -126.335028)
		(width 0.10795)
		(layer "F.Cu")
		(net "A_USB2_COMP")
	)
	(segment
		(start 398.64284 -127.348488)
		(end 399.016728 -126.9746)
		(width 0.10795)
		(layer "F.Cu")
		(net "A_USB2_COMP")
	)
	(segment
		(start 403.8854 -125.170946)
		(end 403.8854 -124.841)
		(width 0.10795)
		(layer "F.Cu")
		(net "A_USB2_COMP")
	)
	(segment
		(start 403.34438 -125.349)
		(end 403.707346 -125.349)
		(width 0.10795)
		(layer "F.Cu")
		(net "A_USB2_COMP")
	)
	(segment
		(start 397.816578 -127.160274)
		(end 398.004792 -127.348488)
		(width 0.10795)
		(layer "F.Cu")
		(net "A_USB2_COMP")
	)
	(segment
		(start 397.816578 -126.463806)
		(end 397.816578 -127.160274)
		(width 0.10795)
		(layer "F.Cu")
		(net "A_USB2_COMP")
	)
	(segment
		(start 397.6878 -126.335028)
		(end 397.816578 -126.463806)
		(width 0.10795)
		(layer "F.Cu")
		(net "A_USB2_COMP")
	)
	(segment
		(start 401.71878 -126.9746)
		(end 403.34438 -125.349)
		(width 0.10795)
		(layer "F.Cu")
		(net "A_USB2_COMP")
	)
	(segment
		(start 399.016728 -126.9746)
		(end 401.71878 -126.9746)
		(width 0.10795)
		(layer "F.Cu")
		(net "A_USB2_COMP")
	)
	(segment
		(start 380.484888 -94.790006)
		(end 380.485142 -94.789752)
		(width 0.0889)
		(layer "F.Cu")
		(net "LPC_LFRAME_N_CS0_N")
	)
	(segment
		(start 380.485142 -94.40799)
		(end 380.175262 -94.09811)
		(width 0.0889)
		(layer "F.Cu")
		(net "LPC_LFRAME_N_CS0_N")
	)
	(segment
		(start 380.173738 -94.088966)
		(end 380.173738 -93.830902)
		(width 0.0889)
		(layer "F.Cu")
		(net "LPC_LFRAME_N_CS0_N")
	)
	(segment
		(start 380.175262 -94.09049)
		(end 380.173738 -94.088966)
		(width 0.0889)
		(layer "F.Cu")
		(net "LPC_LFRAME_N_CS0_N")
	)
	(segment
		(start 379.7173 -90.850212)
		(end 379.7173 -90.551)
		(width 0.10795)
		(layer "F.Cu")
		(net "LPC_LFRAME_N_CS0_N")
	)
	(segment
		(start 379.870208 -91.00312)
		(end 379.7173 -90.850212)
		(width 0.10795)
		(layer "F.Cu")
		(net "LPC_LFRAME_N_CS0_N")
	)
	(segment
		(start 380.270766 -93.733874)
		(end 380.270766 -93.38818)
		(width 0.0889)
		(layer "F.Cu")
		(net "LPC_LFRAME_N_CS0_N")
	)
	(segment
		(start 380.103634 -93.221048)
		(end 380.099316 -93.221048)
		(width 0.0889)
		(layer "F.Cu")
		(net "LPC_LFRAME_N_CS0_N")
	)
	(segment
		(start 379.870208 -92.99194)
		(end 379.870208 -92.67571)
		(width 0.0889)
		(layer "F.Cu")
		(net "LPC_LFRAME_N_CS0_N")
	)
	(segment
		(start 380.485142 -94.789752)
		(end 380.485142 -94.40799)
		(width 0.0889)
		(layer "F.Cu")
		(net "LPC_LFRAME_N_CS0_N")
	)
	(segment
		(start 379.870208 -92.67571)
		(end 379.870208 -91.00312)
		(width 0.10795)
		(layer "F.Cu")
		(net "LPC_LFRAME_N_CS0_N")
	)
	(segment
		(start 380.270766 -93.38818)
		(end 380.103634 -93.221048)
		(width 0.0889)
		(layer "F.Cu")
		(net "LPC_LFRAME_N_CS0_N")
	)
	(segment
		(start 380.173738 -93.830902)
		(end 380.270766 -93.733874)
		(width 0.0889)
		(layer "F.Cu")
		(net "LPC_LFRAME_N_CS0_N")
	)
	(segment
		(start 380.175262 -94.09811)
		(end 380.175262 -94.09049)
		(width 0.0889)
		(layer "F.Cu")
		(net "LPC_LFRAME_N_CS0_N")
	)
	(segment
		(start 380.099316 -93.221048)
		(end 379.870208 -92.99194)
		(width 0.0889)
		(layer "F.Cu")
		(net "LPC_LFRAME_N_CS0_N")
	)
	(segment
		(start 479.323654 -41.402)
		(end 478.2947 -41.402)
		(width 0.10795)
		(layer "F.Cu")
		(net "XTAL_25MHZ_IN_R")
	)
	(segment
		(start 478.2947 -41.402)
		(end 478.1931 -41.3004)
		(width 0.10795)
		(layer "F.Cu")
		(net "XTAL_25MHZ_IN_R")
	)
	(segment
		(start 479.508312 -41.217342)
		(end 479.323654 -41.402)
		(width 0.10795)
		(layer "F.Cu")
		(net "XTAL_25MHZ_IN_R")
	)
	(segment
		(start 479.8822 -41.217342)
		(end 479.508312 -41.217342)
		(width 0.10795)
		(layer "F.Cu")
		(net "XTAL_25MHZ_IN_R")
	)
	(segment
		(start 476.9231 -41.2369)
		(end 476.9866 -41.3004)
		(width 0.10795)
		(layer "F.Cu")
		(net "XTAL_25MHZ_IN")
	)
	(segment
		(start 474.9927 -40.631364)
		(end 475.579948 -40.631364)
		(width 0.10795)
		(layer "F.Cu")
		(net "XTAL_25MHZ_IN")
	)
	(segment
		(start 476.9866 -41.3004)
		(end 477.3041 -41.3004)
		(width 0.10795)
		(layer "F.Cu")
		(net "XTAL_25MHZ_IN")
	)
	(segment
		(start 475.579948 -40.631364)
		(end 476.185484 -41.2369)
		(width 0.10795)
		(layer "F.Cu")
		(net "XTAL_25MHZ_IN")
	)
	(segment
		(start 476.4786 -41.2369)
		(end 476.9231 -41.2369)
		(width 0.10795)
		(layer "F.Cu")
		(net "XTAL_25MHZ_IN")
	)
	(segment
		(start 476.185484 -41.2369)
		(end 476.4786 -41.2369)
		(width 0.10795)
		(layer "F.Cu")
		(net "XTAL_25MHZ_IN")
	)
	(segment
		(start 478.665032 -41.717468)
		(end 478.1931 -42.1894)
		(width 0.10795)
		(layer "F.Cu")
		(net "XTAL_25MHZ_OUT")
	)
	(segment
		(start 479.8822 -41.717468)
		(end 478.665032 -41.717468)
		(width 0.10795)
		(layer "F.Cu")
		(net "XTAL_25MHZ_OUT")
	)
	(segment
		(start 90.928698 -87.784686)
		(end 90.357198 -87.784686)
		(width 0.10795)
		(layer "F.Cu")
		(net "FM_CPU1_SM_WP")
	)
	(segment
		(start 29.964888 -102.235)
		(end 29.6418 -102.235)
		(width 0.10795)
		(layer "F.Cu")
		(net "FM_CPU1_SM_WP")
	)
	(segment
		(start 30.983174 -102.776782)
		(end 30.800294 -102.593902)
		(width 0.10795)
		(layer "F.Cu")
		(net "FM_CPU1_SM_WP")
	)
	(segment
		(start 30.983174 -103.015542)
		(end 30.983174 -102.776782)
		(width 0.10795)
		(layer "F.Cu")
		(net "FM_CPU1_SM_WP")
	)
	(segment
		(start 29.6418 -102.997)
		(end 29.6418 -102.235)
		(width 0.10795)
		(layer "F.Cu")
		(net "FM_CPU1_SM_WP")
	)
	(segment
		(start 30.32379 -102.593902)
		(end 29.964888 -102.235)
		(width 0.10795)
		(layer "F.Cu")
		(net "FM_CPU1_SM_WP")
	)
	(segment
		(start 30.800294 -102.593902)
		(end 30.32379 -102.593902)
		(width 0.10795)
		(layer "F.Cu")
		(net "FM_CPU1_SM_WP")
	)
	(via
		(at 90.357198 -87.784686)
		(size 0.508)
		(drill 0.254)
		(layers "F.Cu" "B.Cu")
		(net "FM_CPU1_SM_WP")
	)
	(via
		(at 30.983174 -103.015542)
		(size 0.508)
		(drill 0.254)
		(layers "F.Cu" "B.Cu")
		(net "FM_CPU1_SM_WP")
	)
	(segment
		(start 73.169526 -78.278736)
		(end 73.202292 -78.278736)
		(width 0.0889)
		(layer "In11.Cu")
		(net "FM_CPU1_SM_WP")
	)
	(segment
		(start 82.619596 -81.74609)
		(end 82.652362 -81.74609)
		(width 0.0889)
		(layer "In11.Cu")
		(net "FM_CPU1_SM_WP")
	)
	(segment
		(start 88.625426 -85.212936)
		(end 88.658192 -85.212936)
		(width 0.0889)
		(layer "In11.Cu")
		(net "FM_CPU1_SM_WP")
	)
	(segment
		(start 90.739722 -87.639906)
		(end 90.650314 -87.615776)
		(width 0.0889)
		(layer "In11.Cu")
		(net "FM_CPU1_SM_WP")
	)
	(segment
		(start 72.307196 -78.77429)
		(end 72.339962 -78.77429)
		(width 0.0889)
		(layer "In11.Cu")
		(net "FM_CPU1_SM_WP")
	)
	(segment
		(start 81.757266 -81.250536)
		(end 81.790032 -81.250536)
		(width 0.0889)
		(layer "In11.Cu")
		(net "FM_CPU1_SM_WP")
	)
	(segment
		(start 32.831278 -103.378)
		(end 36.281868 -103.378)
		(width 0.089408)
		(layer "In11.Cu")
		(net "FM_CPU1_SM_WP")
	)
	(segment
		(start 90.342212 -86.203536)
		(end 90.374978 -86.203536)
		(width 0.0889)
		(layer "In11.Cu")
		(net "FM_CPU1_SM_WP")
	)
	(segment
		(start 86.053676 -83.72729)
		(end 86.086442 -83.72729)
		(width 0.0889)
		(layer "In11.Cu")
		(net "FM_CPU1_SM_WP")
	)
	(segment
		(start 30.983174 -103.015542)
		(end 32.46882 -103.015542)
		(width 0.089408)
		(layer "In11.Cu")
		(net "FM_CPU1_SM_WP")
	)
	(segment
		(start 36.281868 -103.378)
		(end 36.879276 -102.780592)
		(width 0.089408)
		(layer "In11.Cu")
		(net "FM_CPU1_SM_WP")
	)
	(segment
		(start 36.879276 -101.769164)
		(end 44.111926 -94.536514)
		(width 0.089408)
		(layer "In11.Cu")
		(net "FM_CPU1_SM_WP")
	)
	(segment
		(start 74.024236 -77.78369)
		(end 74.067416 -77.78369)
		(width 0.0889)
		(layer "In11.Cu")
		(net "FM_CPU1_SM_WP")
	)
	(segment
		(start 76.6064 -78.278736)
		(end 76.639166 -78.278736)
		(width 0.0889)
		(layer "In11.Cu")
		(net "FM_CPU1_SM_WP")
	)
	(segment
		(start 89.152222 -85.508338)
		(end 89.155524 -85.51418)
		(width 0.0889)
		(layer "In11.Cu")
		(net "FM_CPU1_SM_WP")
	)
	(segment
		(start 91.204542 -86.69909)
		(end 91.237308 -86.69909)
		(width 0.0889)
		(layer "In11.Cu")
		(net "FM_CPU1_SM_WP")
	)
	(segment
		(start 32.46882 -103.015542)
		(end 32.831278 -103.378)
		(width 0.089408)
		(layer "In11.Cu")
		(net "FM_CPU1_SM_WP")
	)
	(segment
		(start 71.452486 -79.269336)
		(end 71.485252 -79.269336)
		(width 0.0889)
		(layer "In11.Cu")
		(net "FM_CPU1_SM_WP")
	)
	(segment
		(start 83.474306 -82.241136)
		(end 83.502246 -82.241136)
		(width 0.0889)
		(layer "In11.Cu")
		(net "FM_CPU1_SM_WP")
	)
	(segment
		(start 68.829174 -80.731614)
		(end 68.97878 -80.720692)
		(width 0.0889)
		(layer "In11.Cu")
		(net "FM_CPU1_SM_WP")
	)
	(segment
		(start 89.498678 -85.70849)
		(end 89.520268 -85.70849)
		(width 0.0889)
		(layer "In11.Cu")
		(net "FM_CPU1_SM_WP")
	)
	(segment
		(start 70.590156 -79.76489)
		(end 70.622922 -79.76489)
		(width 0.0889)
		(layer "In11.Cu")
		(net "FM_CPU1_SM_WP")
	)
	(segment
		(start 48.497998 -93.453204)
		(end 49.96434 -91.986862)
		(width 0.089408)
		(layer "In11.Cu")
		(net "FM_CPU1_SM_WP")
	)
	(segment
		(start 80.040226 -80.259936)
		(end 80.072992 -80.259936)
		(width 0.0889)
		(layer "In11.Cu")
		(net "FM_CPU1_SM_WP")
	)
	(segment
		(start 48.497998 -93.912436)
		(end 48.497998 -93.453204)
		(width 0.089408)
		(layer "In11.Cu")
		(net "FM_CPU1_SM_WP")
	)
	(segment
		(start 69.515482 -80.259936)
		(end 69.768212 -80.259936)
		(width 0.0889)
		(layer "In11.Cu")
		(net "FM_CPU1_SM_WP")
	)
	(segment
		(start 47.87392 -94.536514)
		(end 48.497998 -93.912436)
		(width 0.089408)
		(layer "In11.Cu")
		(net "FM_CPU1_SM_WP")
	)
	(segment
		(start 79.185516 -79.76489)
		(end 79.218282 -79.76489)
		(width 0.0889)
		(layer "In11.Cu")
		(net "FM_CPU1_SM_WP")
	)
	(segment
		(start 84.336636 -82.73669)
		(end 84.369402 -82.73669)
		(width 0.0889)
		(layer "In11.Cu")
		(net "FM_CPU1_SM_WP")
	)
	(segment
		(start 77.46873 -78.77429)
		(end 77.504798 -78.77429)
		(width 0.0889)
		(layer "In11.Cu")
		(net "FM_CPU1_SM_WP")
	)
	(segment
		(start 68.1482 -80.2386)
		(end 68.641214 -80.731614)
		(width 0.0889)
		(layer "In11.Cu")
		(net "FM_CPU1_SM_WP")
	)
	(segment
		(start 52.676044 -91.986862)
		(end 61.198506 -83.4644)
		(width 0.089408)
		(layer "In11.Cu")
		(net "FM_CPU1_SM_WP")
	)
	(segment
		(start 68.641214 -80.731614)
		(end 68.829174 -80.731614)
		(width 0.0889)
		(layer "In11.Cu")
		(net "FM_CPU1_SM_WP")
	)
	(segment
		(start 86.908386 -84.222336)
		(end 86.941152 -84.222336)
		(width 0.0889)
		(layer "In11.Cu")
		(net "FM_CPU1_SM_WP")
	)
	(segment
		(start 85.188298 -83.231736)
		(end 85.224112 -83.231736)
		(width 0.0889)
		(layer "In11.Cu")
		(net "FM_CPU1_SM_WP")
	)
	(segment
		(start 87.770716 -84.71789)
		(end 87.803482 -84.71789)
		(width 0.0889)
		(layer "In11.Cu")
		(net "FM_CPU1_SM_WP")
	)
	(segment
		(start 75.741276 -77.78369)
		(end 75.784456 -77.78369)
		(width 0.0889)
		(layer "In11.Cu")
		(net "FM_CPU1_SM_WP")
	)
	(segment
		(start 74.88936 -78.278736)
		(end 74.919332 -78.278736)
		(width 0.0889)
		(layer "In11.Cu")
		(net "FM_CPU1_SM_WP")
	)
	(segment
		(start 90.650314 -87.615776)
		(end 90.357198 -87.784686)
		(width 0.0889)
		(layer "In11.Cu")
		(net "FM_CPU1_SM_WP")
	)
	(segment
		(start 36.879276 -102.780592)
		(end 36.879276 -101.769164)
		(width 0.089408)
		(layer "In11.Cu")
		(net "FM_CPU1_SM_WP")
	)
	(segment
		(start 67.2846 -80.5688)
		(end 67.6148 -80.2386)
		(width 0.0889)
		(layer "In11.Cu")
		(net "FM_CPU1_SM_WP")
	)
	(segment
		(start 61.198506 -83.4644)
		(end 64.389 -83.4644)
		(width 0.089408)
		(layer "In11.Cu")
		(net "FM_CPU1_SM_WP")
	)
	(segment
		(start 64.389 -83.4644)
		(end 67.2846 -80.5688)
		(width 0.089408)
		(layer "In11.Cu")
		(net "FM_CPU1_SM_WP")
	)
	(segment
		(start 78.338172 -79.269336)
		(end 78.355952 -79.269336)
		(width 0.0889)
		(layer "In11.Cu")
		(net "FM_CPU1_SM_WP")
	)
	(segment
		(start 77.991716 -79.069184)
		(end 77.995018 -79.075026)
		(width 0.0889)
		(layer "In11.Cu")
		(net "FM_CPU1_SM_WP")
	)
	(segment
		(start 91.233498 -87.88019)
		(end 91.197938 -87.88019)
		(width 0.0889)
		(layer "In11.Cu")
		(net "FM_CPU1_SM_WP")
	)
	(segment
		(start 49.96434 -91.986862)
		(end 52.676044 -91.986862)
		(width 0.089408)
		(layer "In11.Cu")
		(net "FM_CPU1_SM_WP")
	)
	(segment
		(start 44.111926 -94.536514)
		(end 47.87392 -94.536514)
		(width 0.089408)
		(layer "In11.Cu")
		(net "FM_CPU1_SM_WP")
	)
	(segment
		(start 80.902556 -80.75549)
		(end 80.935322 -80.75549)
		(width 0.0889)
		(layer "In11.Cu")
		(net "FM_CPU1_SM_WP")
	)
	(segment
		(start 67.6148 -80.2386)
		(end 68.1482 -80.2386)
		(width 0.0889)
		(layer "In11.Cu")
		(net "FM_CPU1_SM_WP")
	)
	(arc
		(start 84.859622 -83.031838)
		(mid 84.998366 -83.173871)
		(end 85.188298 -83.231736)
		(width 0.0889)
		(layer "In11.Cu")
		(net "FM_CPU1_SM_WP")
	)
	(arc
		(start 74.919332 -78.278736)
		(mid 75.110974 -78.22157)
		(end 75.251056 -78.078838)
		(width 0.0889)
		(layer "In11.Cu")
		(net "FM_CPU1_SM_WP")
	)
	(arc
		(start 77.133196 -78.574138)
		(mid 77.274879 -78.717942)
		(end 77.46873 -78.77429)
		(width 0.0889)
		(layer "In11.Cu")
		(net "FM_CPU1_SM_WP")
	)
	(arc
		(start 70.958456 -79.564738)
		(mid 71.167064 -79.352806)
		(end 71.452486 -79.269336)
		(width 0.0889)
		(layer "In11.Cu")
		(net "FM_CPU1_SM_WP")
	)
	(arc
		(start 75.784456 -77.78369)
		(mid 76.067673 -77.867971)
		(end 76.274676 -78.078838)
		(width 0.0889)
		(layer "In11.Cu")
		(net "FM_CPU1_SM_WP")
	)
	(arc
		(start 91.197938 -87.88019)
		(mid 90.941116 -87.812889)
		(end 90.739722 -87.639906)
		(width 0.0889)
		(layer "In11.Cu")
		(net "FM_CPU1_SM_WP")
	)
	(arc
		(start 82.652362 -81.74609)
		(mid 82.935579 -81.830371)
		(end 83.142582 -82.041238)
		(width 0.0889)
		(layer "In11.Cu")
		(net "FM_CPU1_SM_WP")
	)
	(arc
		(start 88.658192 -85.212936)
		(mid 88.943616 -85.296403)
		(end 89.152222 -85.508338)
		(width 0.0889)
		(layer "In11.Cu")
		(net "FM_CPU1_SM_WP")
	)
	(arc
		(start 73.534016 -78.078838)
		(mid 73.74102 -77.867974)
		(end 74.024236 -77.78369)
		(width 0.0889)
		(layer "In11.Cu")
		(net "FM_CPU1_SM_WP")
	)
	(arc
		(start 70.099936 -80.060038)
		(mid 70.30694 -79.849174)
		(end 70.590156 -79.76489)
		(width 0.0889)
		(layer "In11.Cu")
		(net "FM_CPU1_SM_WP")
	)
	(arc
		(start 89.520268 -85.70849)
		(mid 89.803485 -85.792771)
		(end 90.010488 -86.003638)
		(width 0.0889)
		(layer "In11.Cu")
		(net "FM_CPU1_SM_WP")
	)
	(arc
		(start 72.675496 -78.574138)
		(mid 72.884104 -78.362206)
		(end 73.169526 -78.278736)
		(width 0.0889)
		(layer "In11.Cu")
		(net "FM_CPU1_SM_WP")
	)
	(arc
		(start 84.369402 -82.73669)
		(mid 84.652619 -82.820971)
		(end 84.859622 -83.031838)
		(width 0.0889)
		(layer "In11.Cu")
		(net "FM_CPU1_SM_WP")
	)
	(arc
		(start 75.251056 -78.078838)
		(mid 75.45806 -77.867974)
		(end 75.741276 -77.78369)
		(width 0.0889)
		(layer "In11.Cu")
		(net "FM_CPU1_SM_WP")
	)
	(arc
		(start 88.293702 -85.013038)
		(mid 88.433781 -85.155774)
		(end 88.625426 -85.212936)
		(width 0.0889)
		(layer "In11.Cu")
		(net "FM_CPU1_SM_WP")
	)
	(arc
		(start 69.768212 -80.259936)
		(mid 69.959854 -80.20277)
		(end 70.099936 -80.060038)
		(width 0.0889)
		(layer "In11.Cu")
		(net "FM_CPU1_SM_WP")
	)
	(arc
		(start 73.202292 -78.278736)
		(mid 73.393934 -78.22157)
		(end 73.534016 -78.078838)
		(width 0.0889)
		(layer "In11.Cu")
		(net "FM_CPU1_SM_WP")
	)
	(arc
		(start 77.504798 -78.77429)
		(mid 77.786098 -78.859256)
		(end 77.991716 -79.069184)
		(width 0.0889)
		(layer "In11.Cu")
		(net "FM_CPU1_SM_WP")
	)
	(arc
		(start 71.816976 -79.069438)
		(mid 72.02398 -78.858574)
		(end 72.307196 -78.77429)
		(width 0.0889)
		(layer "In11.Cu")
		(net "FM_CPU1_SM_WP")
	)
	(arc
		(start 80.072992 -80.259936)
		(mid 80.358416 -80.343403)
		(end 80.567022 -80.555338)
		(width 0.0889)
		(layer "In11.Cu")
		(net "FM_CPU1_SM_WP")
	)
	(arc
		(start 72.339962 -78.77429)
		(mid 72.533812 -78.71794)
		(end 72.675496 -78.574138)
		(width 0.0889)
		(layer "In11.Cu")
		(net "FM_CPU1_SM_WP")
	)
	(arc
		(start 90.010488 -86.003638)
		(mid 90.150567 -86.146374)
		(end 90.342212 -86.203536)
		(width 0.0889)
		(layer "In11.Cu")
		(net "FM_CPU1_SM_WP")
	)
	(arc
		(start 70.622922 -79.76489)
		(mid 70.816772 -79.70854)
		(end 70.958456 -79.564738)
		(width 0.0889)
		(layer "In11.Cu")
		(net "FM_CPU1_SM_WP")
	)
	(arc
		(start 78.355952 -79.269336)
		(mid 78.641376 -79.352803)
		(end 78.849982 -79.564738)
		(width 0.0889)
		(layer "In11.Cu")
		(net "FM_CPU1_SM_WP")
	)
	(arc
		(start 74.067416 -77.78369)
		(mid 74.350633 -77.867971)
		(end 74.557636 -78.078838)
		(width 0.0889)
		(layer "In11.Cu")
		(net "FM_CPU1_SM_WP")
	)
	(arc
		(start 71.485252 -79.269336)
		(mid 71.676894 -79.21217)
		(end 71.816976 -79.069438)
		(width 0.0889)
		(layer "In11.Cu")
		(net "FM_CPU1_SM_WP")
	)
	(arc
		(start 86.941152 -84.222336)
		(mid 87.226576 -84.305803)
		(end 87.435182 -84.517738)
		(width 0.0889)
		(layer "In11.Cu")
		(net "FM_CPU1_SM_WP")
	)
	(arc
		(start 83.502246 -82.241136)
		(mid 83.790391 -82.323455)
		(end 84.001102 -82.536538)
		(width 0.0889)
		(layer "In11.Cu")
		(net "FM_CPU1_SM_WP")
	)
	(arc
		(start 86.086442 -83.72729)
		(mid 86.369659 -83.811571)
		(end 86.576662 -84.022438)
		(width 0.0889)
		(layer "In11.Cu")
		(net "FM_CPU1_SM_WP")
	)
	(arc
		(start 90.869008 -86.498938)
		(mid 91.010691 -86.642742)
		(end 91.204542 -86.69909)
		(width 0.0889)
		(layer "In11.Cu")
		(net "FM_CPU1_SM_WP")
	)
	(arc
		(start 83.142582 -82.041238)
		(mid 83.282661 -82.183974)
		(end 83.474306 -82.241136)
		(width 0.0889)
		(layer "In11.Cu")
		(net "FM_CPU1_SM_WP")
	)
	(arc
		(start 82.284062 -81.545938)
		(mid 82.425745 -81.689742)
		(end 82.619596 -81.74609)
		(width 0.0889)
		(layer "In11.Cu")
		(net "FM_CPU1_SM_WP")
	)
	(arc
		(start 81.425542 -81.050638)
		(mid 81.565621 -81.193374)
		(end 81.757266 -81.250536)
		(width 0.0889)
		(layer "In11.Cu")
		(net "FM_CPU1_SM_WP")
	)
	(arc
		(start 74.557636 -78.078838)
		(mid 74.697715 -78.221574)
		(end 74.88936 -78.278736)
		(width 0.0889)
		(layer "In11.Cu")
		(net "FM_CPU1_SM_WP")
	)
	(arc
		(start 90.374978 -86.203536)
		(mid 90.660402 -86.287003)
		(end 90.869008 -86.498938)
		(width 0.0889)
		(layer "In11.Cu")
		(net "FM_CPU1_SM_WP")
	)
	(arc
		(start 76.639166 -78.278736)
		(mid 76.92459 -78.362203)
		(end 77.133196 -78.574138)
		(width 0.0889)
		(layer "In11.Cu")
		(net "FM_CPU1_SM_WP")
	)
	(arc
		(start 85.718142 -83.527138)
		(mid 85.859825 -83.670942)
		(end 86.053676 -83.72729)
		(width 0.0889)
		(layer "In11.Cu")
		(net "FM_CPU1_SM_WP")
	)
	(arc
		(start 76.274676 -78.078838)
		(mid 76.414755 -78.221574)
		(end 76.6064 -78.278736)
		(width 0.0889)
		(layer "In11.Cu")
		(net "FM_CPU1_SM_WP")
	)
	(arc
		(start 77.995018 -79.075026)
		(mid 78.140984 -79.217425)
		(end 78.338172 -79.269336)
		(width 0.0889)
		(layer "In11.Cu")
		(net "FM_CPU1_SM_WP")
	)
	(arc
		(start 85.224112 -83.231736)
		(mid 85.509536 -83.315203)
		(end 85.718142 -83.527138)
		(width 0.0889)
		(layer "In11.Cu")
		(net "FM_CPU1_SM_WP")
	)
	(arc
		(start 80.567022 -80.555338)
		(mid 80.708705 -80.699142)
		(end 80.902556 -80.75549)
		(width 0.0889)
		(layer "In11.Cu")
		(net "FM_CPU1_SM_WP")
	)
	(arc
		(start 86.576662 -84.022438)
		(mid 86.716741 -84.165174)
		(end 86.908386 -84.222336)
		(width 0.0889)
		(layer "In11.Cu")
		(net "FM_CPU1_SM_WP")
	)
	(arc
		(start 79.708502 -80.060038)
		(mid 79.848581 -80.202774)
		(end 80.040226 -80.259936)
		(width 0.0889)
		(layer "In11.Cu")
		(net "FM_CPU1_SM_WP")
	)
	(arc
		(start 80.935322 -80.75549)
		(mid 81.218539 -80.839771)
		(end 81.425542 -81.050638)
		(width 0.0889)
		(layer "In11.Cu")
		(net "FM_CPU1_SM_WP")
	)
	(arc
		(start 87.435182 -84.517738)
		(mid 87.576865 -84.661542)
		(end 87.770716 -84.71789)
		(width 0.0889)
		(layer "In11.Cu")
		(net "FM_CPU1_SM_WP")
	)
	(arc
		(start 84.001102 -82.536538)
		(mid 84.142785 -82.680342)
		(end 84.336636 -82.73669)
		(width 0.0889)
		(layer "In11.Cu")
		(net "FM_CPU1_SM_WP")
	)
	(arc
		(start 78.849982 -79.564738)
		(mid 78.991665 -79.708542)
		(end 79.185516 -79.76489)
		(width 0.0889)
		(layer "In11.Cu")
		(net "FM_CPU1_SM_WP")
	)
	(arc
		(start 69.20357 -80.52943)
		(mid 69.337124 -80.368762)
		(end 69.515482 -80.259936)
		(width 0.0889)
		(layer "In11.Cu")
		(net "FM_CPU1_SM_WP")
	)
	(arc
		(start 79.218282 -79.76489)
		(mid 79.501499 -79.849171)
		(end 79.708502 -80.060038)
		(width 0.0889)
		(layer "In11.Cu")
		(net "FM_CPU1_SM_WP")
	)
	(arc
		(start 87.803482 -84.71789)
		(mid 88.086699 -84.802171)
		(end 88.293702 -85.013038)
		(width 0.0889)
		(layer "In11.Cu")
		(net "FM_CPU1_SM_WP")
	)
	(arc
		(start 68.97878 -80.720692)
		(mid 69.107452 -80.644194)
		(end 69.20357 -80.52943)
		(width 0.0889)
		(layer "In11.Cu")
		(net "FM_CPU1_SM_WP")
	)
	(arc
		(start 89.155524 -85.51418)
		(mid 89.30149 -85.656579)
		(end 89.498678 -85.70849)
		(width 0.0889)
		(layer "In11.Cu")
		(net "FM_CPU1_SM_WP")
	)
	(arc
		(start 81.790032 -81.250536)
		(mid 82.075456 -81.334003)
		(end 82.284062 -81.545938)
		(width 0.0889)
		(layer "In11.Cu")
		(net "FM_CPU1_SM_WP")
	)
	(arc
		(start 91.237308 -86.69909)
		(mid 91.806659 -87.291544)
		(end 91.233498 -87.88019)
		(width 0.0889)
		(layer "In11.Cu")
		(net "FM_CPU1_SM_WP")
	)
	(segment
		(start 133.665214 -67.791584)
		(end 134.236714 -67.791584)
		(width 0.10795)
		(layer "F.Cu")
		(net "TP_CPU1_NMI")
	)
	(via
		(at 134.236714 -67.791584)
		(size 0.508)
		(drill 0.254)
		(layers "F.Cu" "B.Cu")
		(net "TP_CPU1_NMI")
	)
	(segment
		(start 125.938788 -95.033084)
		(end 126.510288 -95.033084)
		(width 0.10795)
		(layer "F.Cu")
		(net "TP_CPU1_UPI2_RSVD_CF11")
	)
	(via
		(at 126.510288 -95.033084)
		(size 0.4826)
		(drill 0.254)
		(layers "F.Cu" "B.Cu")
		(net "TP_CPU1_UPI2_RSVD_CF11")
	)
	(segment
		(start 125.938788 -94.042738)
		(end 126.510288 -94.042738)
		(width 0.10795)
		(layer "F.Cu")
		(net "TP_CPU1_UPI2_RSVD_CH11")
	)
	(via
		(at 126.510288 -94.042738)
		(size 0.508)
		(drill 0.254)
		(layers "F.Cu" "B.Cu")
		(net "TP_CPU1_UPI2_RSVD_CH11")
	)
	(segment
		(start 291.51072 -95.033084)
		(end 290.93922 -95.033084)
		(width 0.10795)
		(layer "F.Cu")
		(net "TP_CPU0_UPI2_RSVD_CF11")
	)
	(via
		(at 291.51072 -95.033084)
		(size 0.508)
		(drill 0.254)
		(layers "F.Cu" "B.Cu")
		(net "TP_CPU0_UPI2_RSVD_CF11")
	)
	(segment
		(start 290.93922 -94.042738)
		(end 291.51072 -94.042738)
		(width 0.10795)
		(layer "F.Cu")
		(net "TP_CPU0_UPI2_RSVD_CH11")
	)
	(via
		(at 291.51072 -94.042738)
		(size 0.508)
		(drill 0.254)
		(layers "F.Cu" "B.Cu")
		(net "TP_CPU0_UPI2_RSVD_CH11")
	)
	(segment
		(start 406.908 -23.0505)
		(end 406.908 -23.40102)
		(width 0.10795)
		(layer "F.Cu")
		(net "RMII_BMC_SPRNGVLLE_TXEN_R")
	)
	(segment
		(start 406.671018 -23.638002)
		(end 406.671018 -24.03348)
		(width 0.10795)
		(layer "F.Cu")
		(net "RMII_BMC_SPRNGVLLE_TXEN_R")
	)
	(segment
		(start 407.890218 -25.810972)
		(end 407.890218 -26.534618)
		(width 0.10795)
		(layer "F.Cu")
		(net "RMII_BMC_SPRNGVLLE_TXEN_R")
	)
	(segment
		(start 406.671018 -24.03348)
		(end 406.671018 -24.591772)
		(width 0.10795)
		(layer "F.Cu")
		(net "RMII_BMC_SPRNGVLLE_TXEN_R")
	)
	(segment
		(start 406.671018 -24.591772)
		(end 407.890218 -25.810972)
		(width 0.10795)
		(layer "F.Cu")
		(net "RMII_BMC_SPRNGVLLE_TXEN_R")
	)
	(segment
		(start 406.908 -23.40102)
		(end 406.671018 -23.638002)
		(width 0.10795)
		(layer "F.Cu")
		(net "RMII_BMC_SPRNGVLLE_TXEN_R")
	)
	(via
		(at 406.671018 -24.03348)
		(size 0.762)
		(drill 0.381)
		(layers "F.Cu" "B.Cu")
		(net "RMII_BMC_SPRNGVLLE_TXEN_R")
	)
	(segment
		(start 406.089866 -27.70632)
		(end 407.22042 -27.70632)
		(width 0.10795)
		(layer "F.Cu")
		(net "RMII_BMC_PCH_SPRNGVLLE_TXD1_R")
	)
	(segment
		(start 404.23084 -26.44394)
		(end 404.23084 -26.67508)
		(width 0.10795)
		(layer "F.Cu")
		(net "RMII_BMC_PCH_SPRNGVLLE_TXD1_R")
	)
	(segment
		(start 404.5839 -26.09088)
		(end 404.23084 -26.44394)
		(width 0.10795)
		(layer "F.Cu")
		(net "RMII_BMC_PCH_SPRNGVLLE_TXD1_R")
	)
	(segment
		(start 404.23084 -26.67508)
		(end 404.38832 -26.83256)
		(width 0.10795)
		(layer "F.Cu")
		(net "RMII_BMC_PCH_SPRNGVLLE_TXD1_R")
	)
	(segment
		(start 401.955 -23.495)
		(end 401.955 -24.003)
		(width 0.10795)
		(layer "F.Cu")
		(net "RMII_BMC_PCH_SPRNGVLLE_TXD1_R")
	)
	(segment
		(start 407.22042 -27.70632)
		(end 407.648664 -28.134564)
		(width 0.10795)
		(layer "F.Cu")
		(net "RMII_BMC_PCH_SPRNGVLLE_TXD1_R")
	)
	(segment
		(start 407.648664 -28.134564)
		(end 407.890218 -28.134564)
		(width 0.10795)
		(layer "F.Cu")
		(net "RMII_BMC_PCH_SPRNGVLLE_TXD1_R")
	)
	(segment
		(start 402.971 -24.003)
		(end 403.357334 -24.389334)
		(width 0.10795)
		(layer "F.Cu")
		(net "RMII_BMC_PCH_SPRNGVLLE_TXD1_R")
	)
	(segment
		(start 405.216106 -26.83256)
		(end 406.089866 -27.70632)
		(width 0.10795)
		(layer "F.Cu")
		(net "RMII_BMC_PCH_SPRNGVLLE_TXD1_R")
	)
	(segment
		(start 404.235412 -24.389334)
		(end 404.5839 -24.737822)
		(width 0.10795)
		(layer "F.Cu")
		(net "RMII_BMC_PCH_SPRNGVLLE_TXD1_R")
	)
	(segment
		(start 403.357334 -24.389334)
		(end 404.235412 -24.389334)
		(width 0.10795)
		(layer "F.Cu")
		(net "RMII_BMC_PCH_SPRNGVLLE_TXD1_R")
	)
	(segment
		(start 402.971 -22.987)
		(end 402.463 -22.987)
		(width 0.10795)
		(layer "F.Cu")
		(net "RMII_BMC_PCH_SPRNGVLLE_TXD1_R")
	)
	(segment
		(start 402.463 -22.987)
		(end 401.955 -23.495)
		(width 0.10795)
		(layer "F.Cu")
		(net "RMII_BMC_PCH_SPRNGVLLE_TXD1_R")
	)
	(segment
		(start 404.5839 -24.737822)
		(end 404.5839 -26.09088)
		(width 0.10795)
		(layer "F.Cu")
		(net "RMII_BMC_PCH_SPRNGVLLE_TXD1_R")
	)
	(segment
		(start 402.717 -24.003)
		(end 402.971 -24.003)
		(width 0.10795)
		(layer "F.Cu")
		(net "RMII_BMC_PCH_SPRNGVLLE_TXD1_R")
	)
	(segment
		(start 404.38832 -26.83256)
		(end 405.216106 -26.83256)
		(width 0.10795)
		(layer "F.Cu")
		(net "RMII_BMC_PCH_SPRNGVLLE_TXD1_R")
	)
	(segment
		(start 402.717 -24.003)
		(end 401.955 -24.003)
		(width 0.10795)
		(layer "F.Cu")
		(net "RMII_BMC_PCH_SPRNGVLLE_TXD1_R")
	)
	(via
		(at 404.23084 -26.44394)
		(size 0.762)
		(drill 0.381)
		(layers "F.Cu" "B.Cu")
		(net "RMII_BMC_PCH_SPRNGVLLE_TXD1_R")
	)
	(segment
		(start 405.257 -23.77186)
		(end 405.257 -23.0505)
		(width 0.10795)
		(layer "F.Cu")
		(net "RMII_BMC_PCH_SPRNGVLLE_TXD0_R")
	)
	(segment
		(start 404.79345 -26.067004)
		(end 404.79345 -24.23541)
		(width 0.10795)
		(layer "F.Cu")
		(net "RMII_BMC_PCH_SPRNGVLLE_TXD0_R")
	)
	(segment
		(start 406.061164 -27.334718)
		(end 404.79345 -26.067004)
		(width 0.10795)
		(layer "F.Cu")
		(net "RMII_BMC_PCH_SPRNGVLLE_TXD0_R")
	)
	(segment
		(start 404.5585 -23.0505)
		(end 404.495 -22.987)
		(width 0.10795)
		(layer "F.Cu")
		(net "RMII_BMC_PCH_SPRNGVLLE_TXD0_R")
	)
	(segment
		(start 404.79345 -24.23541)
		(end 404.99792 -24.03094)
		(width 0.10795)
		(layer "F.Cu")
		(net "RMII_BMC_PCH_SPRNGVLLE_TXD0_R")
	)
	(segment
		(start 405.257 -23.0505)
		(end 404.5585 -23.0505)
		(width 0.10795)
		(layer "F.Cu")
		(net "RMII_BMC_PCH_SPRNGVLLE_TXD0_R")
	)
	(segment
		(start 407.090118 -27.334718)
		(end 406.061164 -27.334718)
		(width 0.10795)
		(layer "F.Cu")
		(net "RMII_BMC_PCH_SPRNGVLLE_TXD0_R")
	)
	(segment
		(start 404.99792 -24.03094)
		(end 405.257 -23.77186)
		(width 0.10795)
		(layer "F.Cu")
		(net "RMII_BMC_PCH_SPRNGVLLE_TXD0_R")
	)
	(segment
		(start 404.495 -22.987)
		(end 403.733 -22.987)
		(width 0.10795)
		(layer "F.Cu")
		(net "RMII_BMC_PCH_SPRNGVLLE_TXD0_R")
	)
	(via
		(at 404.99792 -24.03094)
		(size 0.762)
		(drill 0.381)
		(layers "F.Cu" "B.Cu")
		(net "RMII_BMC_PCH_SPRNGVLLE_TXD0_R")
	)
	(segment
		(start 423.309542 -28.134564)
		(end 423.090086 -28.134564)
		(width 0.10795)
		(layer "F.Cu")
		(net "FM_BIOS_SPI_BMC_CTRL")
	)
	(segment
		(start 426.418756 -27.441652)
		(end 424.396154 -27.441652)
		(width 0.10795)
		(layer "F.Cu")
		(net "FM_BIOS_SPI_BMC_CTRL")
	)
	(segment
		(start 423.681144 -27.762962)
		(end 423.309542 -28.134564)
		(width 0.10795)
		(layer "F.Cu")
		(net "FM_BIOS_SPI_BMC_CTRL")
	)
	(segment
		(start 424.396154 -27.441652)
		(end 424.074844 -27.762962)
		(width 0.10795)
		(layer "F.Cu")
		(net "FM_BIOS_SPI_BMC_CTRL")
	)
	(segment
		(start 428.147988 -26.179526)
		(end 428.340774 -26.179526)
		(width 0.10795)
		(layer "F.Cu")
		(net "FM_BIOS_SPI_BMC_CTRL")
	)
	(segment
		(start 424.074844 -27.762962)
		(end 423.681144 -27.762962)
		(width 0.10795)
		(layer "F.Cu")
		(net "FM_BIOS_SPI_BMC_CTRL")
	)
	(segment
		(start 428.340774 -26.179526)
		(end 429.094392 -25.425908)
		(width 0.10795)
		(layer "F.Cu")
		(net "FM_BIOS_SPI_BMC_CTRL")
	)
	(segment
		(start 427.680882 -26.179526)
		(end 426.418756 -27.441652)
		(width 0.10795)
		(layer "F.Cu")
		(net "FM_BIOS_SPI_BMC_CTRL")
	)
	(segment
		(start 429.094392 -25.425908)
		(end 429.094392 -25.0825)
		(width 0.10795)
		(layer "F.Cu")
		(net "FM_BIOS_SPI_BMC_CTRL")
	)
	(segment
		(start 429.094392 -25.0825)
		(end 429.099472 -25.0825)
		(width 0.10795)
		(layer "F.Cu")
		(net "FM_BIOS_SPI_BMC_CTRL")
	)
	(segment
		(start 428.147988 -26.179526)
		(end 427.680882 -26.179526)
		(width 0.10795)
		(layer "F.Cu")
		(net "FM_BIOS_SPI_BMC_CTRL")
	)
	(via
		(at 384.24866 -60.985146)
		(size 0.508)
		(drill 0.254)
		(layers "F.Cu" "B.Cu")
		(net "FM_BIOS_SPI_BMC_CTRL")
	)
	(via
		(at 428.147988 -26.179526)
		(size 0.762)
		(drill 0.381)
		(layers "F.Cu" "B.Cu")
		(net "FM_BIOS_SPI_BMC_CTRL")
	)
	(via
		(at 405.94026 -28.120594)
		(size 0.4572)
		(drill 0.2032)
		(layers "F.Cu" "B.Cu")
		(net "FM_BIOS_SPI_BMC_CTRL")
	)
	(via
		(at 429.099472 -25.0825)
		(size 0.508)
		(drill 0.254)
		(layers "F.Cu" "B.Cu")
		(net "FM_BIOS_SPI_BMC_CTRL")
	)
	(via
		(at 384.5306 -55.372)
		(size 0.508)
		(drill 0.254)
		(layers "F.Cu" "B.Cu")
		(net "FM_BIOS_SPI_BMC_CTRL")
	)
	(segment
		(start 385.2545 -54.61)
		(end 385.2545 -55.142892)
		(width 0.10795)
		(layer "B.Cu")
		(net "FM_BIOS_SPI_BMC_CTRL")
	)
	(segment
		(start 384.24866 -60.985146)
		(end 384.187954 -60.985146)
		(width 0.10795)
		(layer "B.Cu")
		(net "FM_BIOS_SPI_BMC_CTRL")
	)
	(segment
		(start 383.641854 -61.5315)
		(end 382.7653 -61.5315)
		(width 0.10795)
		(layer "B.Cu")
		(net "FM_BIOS_SPI_BMC_CTRL")
	)
	(segment
		(start 384.187954 -60.985146)
		(end 383.921 -61.2521)
		(width 0.10795)
		(layer "B.Cu")
		(net "FM_BIOS_SPI_BMC_CTRL")
	)
	(segment
		(start 384.049016 -55.372)
		(end 383.477516 -54.8005)
		(width 0.10795)
		(layer "B.Cu")
		(net "FM_BIOS_SPI_BMC_CTRL")
	)
	(segment
		(start 383.477516 -54.8005)
		(end 382.5875 -54.8005)
		(width 0.10795)
		(layer "B.Cu")
		(net "FM_BIOS_SPI_BMC_CTRL")
	)
	(segment
		(start 383.921 -61.252354)
		(end 383.641854 -61.5315)
		(width 0.10795)
		(layer "B.Cu")
		(net "FM_BIOS_SPI_BMC_CTRL")
	)
	(segment
		(start 385.2545 -55.142892)
		(end 385.025392 -55.372)
		(width 0.10795)
		(layer "B.Cu")
		(net "FM_BIOS_SPI_BMC_CTRL")
	)
	(segment
		(start 383.921 -61.2521)
		(end 383.921 -61.252354)
		(width 0.10795)
		(layer "B.Cu")
		(net "FM_BIOS_SPI_BMC_CTRL")
	)
	(segment
		(start 385.025392 -55.372)
		(end 384.5306 -55.372)
		(width 0.10795)
		(layer "B.Cu")
		(net "FM_BIOS_SPI_BMC_CTRL")
	)
	(segment
		(start 384.5306 -55.372)
		(end 384.049016 -55.372)
		(width 0.10795)
		(layer "B.Cu")
		(net "FM_BIOS_SPI_BMC_CTRL")
	)
	(segment
		(start 404.02637 -30.034484)
		(end 405.94026 -28.120594)
		(width 0.089408)
		(layer "In2.Cu")
		(net "FM_BIOS_SPI_BMC_CTRL")
	)
	(segment
		(start 384.045206 -56.070754)
		(end 383.763012 -56.070754)
		(width 0.089408)
		(layer "In2.Cu")
		(net "FM_BIOS_SPI_BMC_CTRL")
	)
	(segment
		(start 383.402586 -60.660026)
		(end 383.727706 -60.985146)
		(width 0.089408)
		(layer "In2.Cu")
		(net "FM_BIOS_SPI_BMC_CTRL")
	)
	(segment
		(start 392.092688 -32.722312)
		(end 393.680696 -31.134304)
		(width 0.089408)
		(layer "In2.Cu")
		(net "FM_BIOS_SPI_BMC_CTRL")
	)
	(segment
		(start 383.419096 -47.934626)
		(end 383.419096 -47.015654)
		(width 0.089408)
		(layer "In2.Cu")
		(net "FM_BIOS_SPI_BMC_CTRL")
	)
	(segment
		(start 400.330416 -30.034484)
		(end 404.02637 -30.034484)
		(width 0.089408)
		(layer "In2.Cu")
		(net "FM_BIOS_SPI_BMC_CTRL")
	)
	(segment
		(start 389.971026 -34.28492)
		(end 391.533634 -32.722312)
		(width 0.089408)
		(layer "In2.Cu")
		(net "FM_BIOS_SPI_BMC_CTRL")
	)
	(segment
		(start 394.989304 -30.899862)
		(end 394.989304 -30.714696)
		(width 0.089408)
		(layer "In2.Cu")
		(net "FM_BIOS_SPI_BMC_CTRL")
	)
	(segment
		(start 383.727706 -60.985146)
		(end 384.24866 -60.985146)
		(width 0.089408)
		(layer "In2.Cu")
		(net "FM_BIOS_SPI_BMC_CTRL")
	)
	(segment
		(start 385.557014 -44.877736)
		(end 385.557014 -44.845732)
		(width 0.089408)
		(layer "In2.Cu")
		(net "FM_BIOS_SPI_BMC_CTRL")
	)
	(segment
		(start 394.754862 -31.134304)
		(end 394.989304 -30.899862)
		(width 0.089408)
		(layer "In2.Cu")
		(net "FM_BIOS_SPI_BMC_CTRL")
	)
	(segment
		(start 396.081504 -29.622496)
		(end 399.918428 -29.622496)
		(width 0.089408)
		(layer "In2.Cu")
		(net "FM_BIOS_SPI_BMC_CTRL")
	)
	(segment
		(start 384.2004 -55.372)
		(end 383.986786 -55.158386)
		(width 0.089408)
		(layer "In2.Cu")
		(net "FM_BIOS_SPI_BMC_CTRL")
	)
	(segment
		(start 384.404362 -49.910492)
		(end 384.404362 -48.919892)
		(width 0.089408)
		(layer "In2.Cu")
		(net "FM_BIOS_SPI_BMC_CTRL")
	)
	(segment
		(start 384.5306 -55.58536)
		(end 384.045206 -56.070754)
		(width 0.089408)
		(layer "In2.Cu")
		(net "FM_BIOS_SPI_BMC_CTRL")
	)
	(segment
		(start 388.177278 -37.66693)
		(end 388.177278 -36.907724)
		(width 0.089408)
		(layer "In2.Cu")
		(net "FM_BIOS_SPI_BMC_CTRL")
	)
	(segment
		(start 388.177278 -36.907724)
		(end 389.971026 -35.113976)
		(width 0.089408)
		(layer "In2.Cu")
		(net "FM_BIOS_SPI_BMC_CTRL")
	)
	(segment
		(start 383.986786 -53.883814)
		(end 383.7432 -53.640228)
		(width 0.089408)
		(layer "In2.Cu")
		(net "FM_BIOS_SPI_BMC_CTRL")
	)
	(segment
		(start 393.680696 -31.134304)
		(end 394.754862 -31.134304)
		(width 0.089408)
		(layer "In2.Cu")
		(net "FM_BIOS_SPI_BMC_CTRL")
	)
	(segment
		(start 385.595622 -40.248586)
		(end 388.177278 -37.66693)
		(width 0.089408)
		(layer "In2.Cu")
		(net "FM_BIOS_SPI_BMC_CTRL")
	)
	(segment
		(start 383.402586 -56.43118)
		(end 383.402586 -60.660026)
		(width 0.089408)
		(layer "In2.Cu")
		(net "FM_BIOS_SPI_BMC_CTRL")
	)
	(segment
		(start 383.763012 -56.070754)
		(end 383.402586 -56.43118)
		(width 0.089408)
		(layer "In2.Cu")
		(net "FM_BIOS_SPI_BMC_CTRL")
	)
	(segment
		(start 383.419096 -47.015654)
		(end 385.557014 -44.877736)
		(width 0.089408)
		(layer "In2.Cu")
		(net "FM_BIOS_SPI_BMC_CTRL")
	)
	(segment
		(start 384.5306 -55.372)
		(end 384.5306 -55.58536)
		(width 0.089408)
		(layer "In2.Cu")
		(net "FM_BIOS_SPI_BMC_CTRL")
	)
	(segment
		(start 399.918428 -29.622496)
		(end 400.330416 -30.034484)
		(width 0.089408)
		(layer "In2.Cu")
		(net "FM_BIOS_SPI_BMC_CTRL")
	)
	(segment
		(start 383.7432 -53.640228)
		(end 383.7432 -50.571654)
		(width 0.089408)
		(layer "In2.Cu")
		(net "FM_BIOS_SPI_BMC_CTRL")
	)
	(segment
		(start 389.971026 -35.113976)
		(end 389.971026 -34.28492)
		(width 0.089408)
		(layer "In2.Cu")
		(net "FM_BIOS_SPI_BMC_CTRL")
	)
	(segment
		(start 383.7432 -50.571654)
		(end 384.404362 -49.910492)
		(width 0.089408)
		(layer "In2.Cu")
		(net "FM_BIOS_SPI_BMC_CTRL")
	)
	(segment
		(start 394.989304 -30.714696)
		(end 396.081504 -29.622496)
		(width 0.089408)
		(layer "In2.Cu")
		(net "FM_BIOS_SPI_BMC_CTRL")
	)
	(segment
		(start 385.557014 -44.845732)
		(end 385.595622 -44.807124)
		(width 0.089408)
		(layer "In2.Cu")
		(net "FM_BIOS_SPI_BMC_CTRL")
	)
	(segment
		(start 384.404362 -48.919892)
		(end 383.419096 -47.934626)
		(width 0.089408)
		(layer "In2.Cu")
		(net "FM_BIOS_SPI_BMC_CTRL")
	)
	(segment
		(start 383.986786 -55.158386)
		(end 383.986786 -53.883814)
		(width 0.089408)
		(layer "In2.Cu")
		(net "FM_BIOS_SPI_BMC_CTRL")
	)
	(segment
		(start 384.5306 -55.372)
		(end 384.2004 -55.372)
		(width 0.089408)
		(layer "In2.Cu")
		(net "FM_BIOS_SPI_BMC_CTRL")
	)
	(segment
		(start 391.533634 -32.722312)
		(end 392.092688 -32.722312)
		(width 0.089408)
		(layer "In2.Cu")
		(net "FM_BIOS_SPI_BMC_CTRL")
	)
	(segment
		(start 385.595622 -44.807124)
		(end 385.595622 -40.248586)
		(width 0.089408)
		(layer "In2.Cu")
		(net "FM_BIOS_SPI_BMC_CTRL")
	)
	(segment
		(start 427.066202 -25.498044)
		(end 427.059852 -25.498044)
		(width 0.089408)
		(layer "In4.Cu")
		(net "FM_BIOS_SPI_BMC_CTRL")
	)
	(segment
		(start 408.199844 -26.224738)
		(end 406.893522 -27.53106)
		(width 0.089408)
		(layer "In4.Cu")
		(net "FM_BIOS_SPI_BMC_CTRL")
	)
	(segment
		(start 423.470578 -25.239472)
		(end 423.087546 -25.622504)
		(width 0.089408)
		(layer "In4.Cu")
		(net "FM_BIOS_SPI_BMC_CTRL")
	)
	(segment
		(start 427.894496 -24.675592)
		(end 427.168564 -25.401524)
		(width 0.089408)
		(layer "In4.Cu")
		(net "FM_BIOS_SPI_BMC_CTRL")
	)
	(segment
		(start 414.77311 -25.483312)
		(end 414.28289 -25.483312)
		(width 0.089408)
		(layer "In4.Cu")
		(net "FM_BIOS_SPI_BMC_CTRL")
	)
	(segment
		(start 414.28289 -25.483312)
		(end 414.282382 -25.482804)
		(width 0.089408)
		(layer "In4.Cu")
		(net "FM_BIOS_SPI_BMC_CTRL")
	)
	(segment
		(start 406.529794 -27.53106)
		(end 405.94026 -28.120594)
		(width 0.089408)
		(layer "In4.Cu")
		(net "FM_BIOS_SPI_BMC_CTRL")
	)
	(segment
		(start 409.607258 -25.483058)
		(end 408.865578 -26.224738)
		(width 0.089408)
		(layer "In4.Cu")
		(net "FM_BIOS_SPI_BMC_CTRL")
	)
	(segment
		(start 429.094392 -24.972772)
		(end 428.797212 -24.675592)
		(width 0.089408)
		(layer "In4.Cu")
		(net "FM_BIOS_SPI_BMC_CTRL")
	)
	(segment
		(start 426.523912 -25.571196)
		(end 426.192188 -25.239472)
		(width 0.089408)
		(layer "In4.Cu")
		(net "FM_BIOS_SPI_BMC_CTRL")
	)
	(segment
		(start 427.162722 -25.401524)
		(end 427.066202 -25.498044)
		(width 0.089408)
		(layer "In4.Cu")
		(net "FM_BIOS_SPI_BMC_CTRL")
	)
	(segment
		(start 427.168564 -25.401524)
		(end 427.162722 -25.401524)
		(width 0.089408)
		(layer "In4.Cu")
		(net "FM_BIOS_SPI_BMC_CTRL")
	)
	(segment
		(start 429.094392 -25.0825)
		(end 429.094392 -24.972772)
		(width 0.089408)
		(layer "In4.Cu")
		(net "FM_BIOS_SPI_BMC_CTRL")
	)
	(segment
		(start 429.099472 -25.0825)
		(end 429.094392 -25.0825)
		(width 0.089408)
		(layer "In4.Cu")
		(net "FM_BIOS_SPI_BMC_CTRL")
	)
	(segment
		(start 427.059852 -25.498044)
		(end 426.94225 -25.615646)
		(width 0.089408)
		(layer "In4.Cu")
		(net "FM_BIOS_SPI_BMC_CTRL")
	)
	(segment
		(start 406.893522 -27.53106)
		(end 406.529794 -27.53106)
		(width 0.089408)
		(layer "In4.Cu")
		(net "FM_BIOS_SPI_BMC_CTRL")
	)
	(segment
		(start 428.797212 -24.675592)
		(end 427.894496 -24.675592)
		(width 0.089408)
		(layer "In4.Cu")
		(net "FM_BIOS_SPI_BMC_CTRL")
	)
	(segment
		(start 426.55871 -25.571196)
		(end 426.523912 -25.571196)
		(width 0.089408)
		(layer "In4.Cu")
		(net "FM_BIOS_SPI_BMC_CTRL")
	)
	(segment
		(start 426.192188 -25.239472)
		(end 423.470578 -25.239472)
		(width 0.089408)
		(layer "In4.Cu")
		(net "FM_BIOS_SPI_BMC_CTRL")
	)
	(segment
		(start 420.997634 -25.622504)
		(end 419.872922 -24.497792)
		(width 0.089408)
		(layer "In4.Cu")
		(net "FM_BIOS_SPI_BMC_CTRL")
	)
	(segment
		(start 416.819588 -25.482804)
		(end 414.773618 -25.482804)
		(width 0.089408)
		(layer "In4.Cu")
		(net "FM_BIOS_SPI_BMC_CTRL")
	)
	(segment
		(start 419.872922 -24.497792)
		(end 417.8046 -24.497792)
		(width 0.089408)
		(layer "In4.Cu")
		(net "FM_BIOS_SPI_BMC_CTRL")
	)
	(segment
		(start 408.865578 -26.224738)
		(end 408.199844 -26.224738)
		(width 0.089408)
		(layer "In4.Cu")
		(net "FM_BIOS_SPI_BMC_CTRL")
	)
	(segment
		(start 410.001466 -25.483058)
		(end 409.607258 -25.483058)
		(width 0.089408)
		(layer "In4.Cu")
		(net "FM_BIOS_SPI_BMC_CTRL")
	)
	(segment
		(start 410.00172 -25.482804)
		(end 410.001466 -25.483058)
		(width 0.089408)
		(layer "In4.Cu")
		(net "FM_BIOS_SPI_BMC_CTRL")
	)
	(segment
		(start 417.8046 -24.497792)
		(end 416.819588 -25.482804)
		(width 0.089408)
		(layer "In4.Cu")
		(net "FM_BIOS_SPI_BMC_CTRL")
	)
	(segment
		(start 414.773618 -25.482804)
		(end 414.77311 -25.483312)
		(width 0.089408)
		(layer "In4.Cu")
		(net "FM_BIOS_SPI_BMC_CTRL")
	)
	(segment
		(start 426.60316 -25.615646)
		(end 426.55871 -25.571196)
		(width 0.089408)
		(layer "In4.Cu")
		(net "FM_BIOS_SPI_BMC_CTRL")
	)
	(segment
		(start 423.087546 -25.622504)
		(end 420.997634 -25.622504)
		(width 0.089408)
		(layer "In4.Cu")
		(net "FM_BIOS_SPI_BMC_CTRL")
	)
	(segment
		(start 414.282382 -25.482804)
		(end 410.00172 -25.482804)
		(width 0.089408)
		(layer "In4.Cu")
		(net "FM_BIOS_SPI_BMC_CTRL")
	)
	(segment
		(start 426.94225 -25.615646)
		(end 426.60316 -25.615646)
		(width 0.089408)
		(layer "In4.Cu")
		(net "FM_BIOS_SPI_BMC_CTRL")
	)
	(segment
		(start 391.17397 -93.830902)
		(end 391.270744 -93.734128)
		(width 0.0889)
		(layer "F.Cu")
		(net "FM_BACKUP_BIOS_SEL_N")
	)
	(segment
		(start 391.48512 -94.790006)
		(end 391.48512 -94.434914)
		(width 0.0889)
		(layer "F.Cu")
		(net "FM_BACKUP_BIOS_SEL_N")
	)
	(segment
		(start 421.49014 -28.134564)
		(end 421.89019 -27.734514)
		(width 0.10795)
		(layer "F.Cu")
		(net "FM_BACKUP_BIOS_SEL_N")
	)
	(segment
		(start 391.270744 -93.201744)
		(end 390.7028 -92.6338)
		(width 0.0889)
		(layer "F.Cu")
		(net "FM_BACKUP_BIOS_SEL_N")
	)
	(segment
		(start 391.17397 -94.123764)
		(end 391.17397 -93.830902)
		(width 0.0889)
		(layer "F.Cu")
		(net "FM_BACKUP_BIOS_SEL_N")
	)
	(segment
		(start 391.48512 -94.434914)
		(end 391.17397 -94.123764)
		(width 0.0889)
		(layer "F.Cu")
		(net "FM_BACKUP_BIOS_SEL_N")
	)
	(segment
		(start 391.270744 -93.734128)
		(end 391.270744 -93.201744)
		(width 0.0889)
		(layer "F.Cu")
		(net "FM_BACKUP_BIOS_SEL_N")
	)
	(via
		(at 386.578348 -70.7771)
		(size 0.508)
		(drill 0.254)
		(layers "F.Cu" "B.Cu")
		(net "FM_BACKUP_BIOS_SEL_N")
	)
	(via
		(at 385.9276 -68.19392)
		(size 0.6604)
		(drill 0.3302)
		(layers "F.Cu" "B.Cu")
		(net "FM_BACKUP_BIOS_SEL_N")
	)
	(via
		(at 482.117908 -27.26055)
		(size 0.508)
		(drill 0.254)
		(layers "F.Cu" "B.Cu")
		(net "FM_BACKUP_BIOS_SEL_N")
	)
	(via
		(at 407.105104 -84.151216)
		(size 0.508)
		(drill 0.254)
		(layers "F.Cu" "B.Cu")
		(net "FM_BACKUP_BIOS_SEL_N")
	)
	(via
		(at 421.89019 -27.734514)
		(size 0.4572)
		(drill 0.2032)
		(layers "F.Cu" "B.Cu")
		(net "FM_BACKUP_BIOS_SEL_N")
	)
	(via
		(at 390.7028 -92.6338)
		(size 0.508)
		(drill 0.254)
		(layers "F.Cu" "B.Cu")
		(net "FM_BACKUP_BIOS_SEL_N")
	)
	(via
		(at 476.98152 -51.76012)
		(size 0.508)
		(drill 0.254)
		(layers "F.Cu" "B.Cu")
		(net "FM_BACKUP_BIOS_SEL_N")
	)
	(segment
		(start 392.01725 -64.381888)
		(end 391.3251 -64.381888)
		(width 0.10795)
		(layer "B.Cu")
		(net "FM_BACKUP_BIOS_SEL_N")
	)
	(segment
		(start 393.639802 -87.093806)
		(end 393.639802 -84.141818)
		(width 0.10795)
		(layer "B.Cu")
		(net "FM_BACKUP_BIOS_SEL_N")
	)
	(segment
		(start 398.481804 -82.346546)
		(end 400.293078 -84.15782)
		(width 0.10795)
		(layer "B.Cu")
		(net "FM_BACKUP_BIOS_SEL_N")
	)
	(segment
		(start 391.402062 -88.85555)
		(end 391.403078 -88.85555)
		(width 0.10795)
		(layer "B.Cu")
		(net "FM_BACKUP_BIOS_SEL_N")
	)
	(segment
		(start 400.293078 -84.15782)
		(end 402.939504 -84.15782)
		(width 0.10795)
		(layer "B.Cu")
		(net "FM_BACKUP_BIOS_SEL_N")
	)
	(segment
		(start 390.330436 -92.261436)
		(end 390.330436 -91.129358)
		(width 0.10795)
		(layer "B.Cu")
		(net "FM_BACKUP_BIOS_SEL_N")
	)
	(segment
		(start 392.1252 -67.142868)
		(end 392.1252 -64.489838)
		(width 0.10795)
		(layer "B.Cu")
		(net "FM_BACKUP_BIOS_SEL_N")
	)
	(segment
		(start 391.323576 -90.44432)
		(end 391.323576 -88.934036)
		(width 0.10795)
		(layer "B.Cu")
		(net "FM_BACKUP_BIOS_SEL_N")
	)
	(segment
		(start 392.1252 -64.489838)
		(end 392.01725 -64.381888)
		(width 0.10795)
		(layer "B.Cu")
		(net "FM_BACKUP_BIOS_SEL_N")
	)
	(segment
		(start 390.603994 -90.8558)
		(end 390.912096 -90.8558)
		(width 0.10795)
		(layer "B.Cu")
		(net "FM_BACKUP_BIOS_SEL_N")
	)
	(segment
		(start 390.144 -65.542414)
		(end 389.970772 -65.369186)
		(width 0.10795)
		(layer "B.Cu")
		(net "FM_BACKUP_BIOS_SEL_N")
	)
	(segment
		(start 391.323576 -88.934036)
		(end 391.402062 -88.85555)
		(width 0.10795)
		(layer "B.Cu")
		(net "FM_BACKUP_BIOS_SEL_N")
	)
	(segment
		(start 403.492462 -84.710778)
		(end 406.545542 -84.710778)
		(width 0.10795)
		(layer "B.Cu")
		(net "FM_BACKUP_BIOS_SEL_N")
	)
	(segment
		(start 390.330436 -91.129358)
		(end 390.603994 -90.8558)
		(width 0.10795)
		(layer "B.Cu")
		(net "FM_BACKUP_BIOS_SEL_N")
	)
	(segment
		(start 393.389866 -87.341202)
		(end 393.392406 -87.341202)
		(width 0.10795)
		(layer "B.Cu")
		(net "FM_BACKUP_BIOS_SEL_N")
	)
	(segment
		(start 406.545542 -84.710778)
		(end 407.105104 -84.151216)
		(width 0.10795)
		(layer "B.Cu")
		(net "FM_BACKUP_BIOS_SEL_N")
	)
	(segment
		(start 392.2395 -88.019128)
		(end 392.2395 -88.018112)
		(width 0.10795)
		(layer "B.Cu")
		(net "FM_BACKUP_BIOS_SEL_N")
	)
	(segment
		(start 385.9276 -70.126352)
		(end 385.9276 -68.19392)
		(width 0.10795)
		(layer "B.Cu")
		(net "FM_BACKUP_BIOS_SEL_N")
	)
	(segment
		(start 392.858752 -87.872316)
		(end 393.389866 -87.341202)
		(width 0.10795)
		(layer "B.Cu")
		(net "FM_BACKUP_BIOS_SEL_N")
	)
	(segment
		(start 392.385296 -87.872316)
		(end 392.858752 -87.872316)
		(width 0.10795)
		(layer "B.Cu")
		(net "FM_BACKUP_BIOS_SEL_N")
	)
	(segment
		(start 391.215118 -68.05295)
		(end 392.1252 -67.142868)
		(width 0.10795)
		(layer "B.Cu")
		(net "FM_BACKUP_BIOS_SEL_N")
	)
	(segment
		(start 390.144 -66.167)
		(end 390.144 -67.691)
		(width 0.10795)
		(layer "B.Cu")
		(net "FM_BACKUP_BIOS_SEL_N")
	)
	(segment
		(start 393.639802 -84.141818)
		(end 395.435074 -82.346546)
		(width 0.10795)
		(layer "B.Cu")
		(net "FM_BACKUP_BIOS_SEL_N")
	)
	(segment
		(start 385.9276 -68.19392)
		(end 385.9276 -65.3288)
		(width 0.10795)
		(layer "B.Cu")
		(net "FM_BACKUP_BIOS_SEL_N")
	)
	(segment
		(start 388.403338 -64.39662)
		(end 386.85978 -64.39662)
		(width 0.10795)
		(layer "B.Cu")
		(net "FM_BACKUP_BIOS_SEL_N")
	)
	(segment
		(start 402.939504 -84.15782)
		(end 403.492462 -84.710778)
		(width 0.10795)
		(layer "B.Cu")
		(net "FM_BACKUP_BIOS_SEL_N")
	)
	(segment
		(start 390.144 -67.691)
		(end 390.50595 -68.05295)
		(width 0.10795)
		(layer "B.Cu")
		(net "FM_BACKUP_BIOS_SEL_N")
	)
	(segment
		(start 390.912096 -90.8558)
		(end 391.323576 -90.44432)
		(width 0.10795)
		(layer "B.Cu")
		(net "FM_BACKUP_BIOS_SEL_N")
	)
	(segment
		(start 389.375904 -65.369186)
		(end 388.403338 -64.39662)
		(width 0.10795)
		(layer "B.Cu")
		(net "FM_BACKUP_BIOS_SEL_N")
	)
	(segment
		(start 393.392406 -87.341202)
		(end 393.639802 -87.093806)
		(width 0.10795)
		(layer "B.Cu")
		(net "FM_BACKUP_BIOS_SEL_N")
	)
	(segment
		(start 390.144 -66.167)
		(end 390.144 -65.542414)
		(width 0.10795)
		(layer "B.Cu")
		(net "FM_BACKUP_BIOS_SEL_N")
	)
	(segment
		(start 389.970772 -65.369186)
		(end 389.375904 -65.369186)
		(width 0.10795)
		(layer "B.Cu")
		(net "FM_BACKUP_BIOS_SEL_N")
	)
	(segment
		(start 386.85978 -64.39662)
		(end 385.9276 -65.3288)
		(width 0.10795)
		(layer "B.Cu")
		(net "FM_BACKUP_BIOS_SEL_N")
	)
	(segment
		(start 386.578348 -70.7771)
		(end 385.9276 -70.126352)
		(width 0.10795)
		(layer "B.Cu")
		(net "FM_BACKUP_BIOS_SEL_N")
	)
	(segment
		(start 390.50595 -68.05295)
		(end 391.215118 -68.05295)
		(width 0.10795)
		(layer "B.Cu")
		(net "FM_BACKUP_BIOS_SEL_N")
	)
	(segment
		(start 392.2395 -88.018112)
		(end 392.385296 -87.872316)
		(width 0.10795)
		(layer "B.Cu")
		(net "FM_BACKUP_BIOS_SEL_N")
	)
	(segment
		(start 390.7028 -92.6338)
		(end 390.330436 -92.261436)
		(width 0.10795)
		(layer "B.Cu")
		(net "FM_BACKUP_BIOS_SEL_N")
	)
	(segment
		(start 391.403078 -88.85555)
		(end 392.2395 -88.019128)
		(width 0.10795)
		(layer "B.Cu")
		(net "FM_BACKUP_BIOS_SEL_N")
	)
	(segment
		(start 395.435074 -82.346546)
		(end 398.481804 -82.346546)
		(width 0.10795)
		(layer "B.Cu")
		(net "FM_BACKUP_BIOS_SEL_N")
	)
	(segment
		(start 463.645504 -55.086504)
		(end 464.633818 -56.074818)
		(width 0.089408)
		(layer "In2.Cu")
		(net "FM_BACKUP_BIOS_SEL_N")
	)
	(segment
		(start 404.872952 -79.129128)
		(end 404.37054 -78.626716)
		(width 0.089408)
		(layer "In2.Cu")
		(net "FM_BACKUP_BIOS_SEL_N")
	)
	(segment
		(start 471.272616 -30.649672)
		(end 472.826588 -30.649672)
		(width 0.089408)
		(layer "In2.Cu")
		(net "FM_BACKUP_BIOS_SEL_N")
	)
	(segment
		(start 455.440034 -26.920698)
		(end 460.269336 -31.75)
		(width 0.089408)
		(layer "In2.Cu")
		(net "FM_BACKUP_BIOS_SEL_N")
	)
	(segment
		(start 407.105104 -84.151216)
		(end 407.035 -84.081112)
		(width 0.089408)
		(layer "In2.Cu")
		(net "FM_BACKUP_BIOS_SEL_N")
	)
	(segment
		(start 468.663782 -33.258506)
		(end 471.272616 -30.649672)
		(width 0.089408)
		(layer "In2.Cu")
		(net "FM_BACKUP_BIOS_SEL_N")
	)
	(segment
		(start 436.449724 -23.003256)
		(end 437.377586 -22.075394)
		(width 0.089408)
		(layer "In2.Cu")
		(net "FM_BACKUP_BIOS_SEL_N")
	)
	(segment
		(start 472.70289 -52.334668)
		(end 475.00413 -52.334668)
		(width 0.089408)
		(layer "In2.Cu")
		(net "FM_BACKUP_BIOS_SEL_N")
	)
	(segment
		(start 404.986236 -74.203306)
		(end 410.676852 -68.51269)
		(width 0.089408)
		(layer "In2.Cu")
		(net "FM_BACKUP_BIOS_SEL_N")
	)
	(segment
		(start 453.36079 -25.486106)
		(end 454.795382 -26.920698)
		(width 0.089408)
		(layer "In2.Cu")
		(net "FM_BACKUP_BIOS_SEL_N")
	)
	(segment
		(start 475.578678 -51.76012)
		(end 476.98152 -51.76012)
		(width 0.089408)
		(layer "In2.Cu")
		(net "FM_BACKUP_BIOS_SEL_N")
	)
	(segment
		(start 436.489602 -55.086504)
		(end 463.645504 -55.086504)
		(width 0.089408)
		(layer "In2.Cu")
		(net "FM_BACKUP_BIOS_SEL_N")
	)
	(segment
		(start 422.324784 -27.734514)
		(end 423.865802 -26.193496)
		(width 0.089408)
		(layer "In2.Cu")
		(net "FM_BACKUP_BIOS_SEL_N")
	)
	(segment
		(start 410.676852 -68.51269)
		(end 410.676852 -57.00395)
		(width 0.089408)
		(layer "In2.Cu")
		(net "FM_BACKUP_BIOS_SEL_N")
	)
	(segment
		(start 425.953428 -24.886412)
		(end 426.419264 -24.420576)
		(width 0.089408)
		(layer "In2.Cu")
		(net "FM_BACKUP_BIOS_SEL_N")
	)
	(segment
		(start 424.810682 -24.886412)
		(end 425.953428 -24.886412)
		(width 0.089408)
		(layer "In2.Cu")
		(net "FM_BACKUP_BIOS_SEL_N")
	)
	(segment
		(start 410.676852 -57.00395)
		(end 411.530546 -56.150256)
		(width 0.089408)
		(layer "In2.Cu")
		(net "FM_BACKUP_BIOS_SEL_N")
	)
	(segment
		(start 421.93337 -54.746398)
		(end 427.425866 -54.746398)
		(width 0.089408)
		(layer "In2.Cu")
		(net "FM_BACKUP_BIOS_SEL_N")
	)
	(segment
		(start 446.696084 -24.4348)
		(end 449.437506 -24.4348)
		(width 0.089408)
		(layer "In2.Cu")
		(net "FM_BACKUP_BIOS_SEL_N")
	)
	(segment
		(start 468.27313 -54.835552)
		(end 468.27313 -54.003702)
		(width 0.089408)
		(layer "In2.Cu")
		(net "FM_BACKUP_BIOS_SEL_N")
	)
	(segment
		(start 450.488812 -25.486106)
		(end 453.36079 -25.486106)
		(width 0.089408)
		(layer "In2.Cu")
		(net "FM_BACKUP_BIOS_SEL_N")
	)
	(segment
		(start 454.795382 -26.920698)
		(end 455.440034 -26.920698)
		(width 0.089408)
		(layer "In2.Cu")
		(net "FM_BACKUP_BIOS_SEL_N")
	)
	(segment
		(start 420.529512 -56.150256)
		(end 421.93337 -54.746398)
		(width 0.089408)
		(layer "In2.Cu")
		(net "FM_BACKUP_BIOS_SEL_N")
	)
	(segment
		(start 407.035 -84.081112)
		(end 407.035 -82.523584)
		(width 0.089408)
		(layer "In2.Cu")
		(net "FM_BACKUP_BIOS_SEL_N")
	)
	(segment
		(start 404.872952 -79.41056)
		(end 404.872952 -79.129128)
		(width 0.089408)
		(layer "In2.Cu")
		(net "FM_BACKUP_BIOS_SEL_N")
	)
	(segment
		(start 460.269336 -31.75)
		(end 462.153 -31.75)
		(width 0.089408)
		(layer "In2.Cu")
		(net "FM_BACKUP_BIOS_SEL_N")
	)
	(segment
		(start 475.00413 -52.334668)
		(end 475.578678 -51.76012)
		(width 0.089408)
		(layer "In2.Cu")
		(net "FM_BACKUP_BIOS_SEL_N")
	)
	(segment
		(start 428.216314 -23.338536)
		(end 432.48707 -23.338536)
		(width 0.089408)
		(layer "In2.Cu")
		(net "FM_BACKUP_BIOS_SEL_N")
	)
	(segment
		(start 404.37054 -75.14082)
		(end 404.986236 -74.525124)
		(width 0.089408)
		(layer "In2.Cu")
		(net "FM_BACKUP_BIOS_SEL_N")
	)
	(segment
		(start 463.661506 -33.258506)
		(end 468.663782 -33.258506)
		(width 0.089408)
		(layer "In2.Cu")
		(net "FM_BACKUP_BIOS_SEL_N")
	)
	(segment
		(start 471.987372 -53.050186)
		(end 472.70289 -52.334668)
		(width 0.089408)
		(layer "In2.Cu")
		(net "FM_BACKUP_BIOS_SEL_N")
	)
	(segment
		(start 434.921914 -23.349458)
		(end 434.922168 -23.349458)
		(width 0.089408)
		(layer "In2.Cu")
		(net "FM_BACKUP_BIOS_SEL_N")
	)
	(segment
		(start 423.865802 -26.193496)
		(end 423.865802 -25.831292)
		(width 0.089408)
		(layer "In2.Cu")
		(net "FM_BACKUP_BIOS_SEL_N")
	)
	(segment
		(start 468.27313 -54.003702)
		(end 469.226646 -53.050186)
		(width 0.089408)
		(layer "In2.Cu")
		(net "FM_BACKUP_BIOS_SEL_N")
	)
	(segment
		(start 479.531426 -24.674068)
		(end 482.117908 -27.26055)
		(width 0.089408)
		(layer "In2.Cu")
		(net "FM_BACKUP_BIOS_SEL_N")
	)
	(segment
		(start 435.26837 -23.003256)
		(end 436.449724 -23.003256)
		(width 0.089408)
		(layer "In2.Cu")
		(net "FM_BACKUP_BIOS_SEL_N")
	)
	(segment
		(start 404.986236 -74.525124)
		(end 404.986236 -74.203306)
		(width 0.089408)
		(layer "In2.Cu")
		(net "FM_BACKUP_BIOS_SEL_N")
	)
	(segment
		(start 474.723968 -28.752292)
		(end 474.723968 -26.354532)
		(width 0.089408)
		(layer "In2.Cu")
		(net "FM_BACKUP_BIOS_SEL_N")
	)
	(segment
		(start 404.872698 -80.361282)
		(end 404.872698 -79.410814)
		(width 0.089408)
		(layer "In2.Cu")
		(net "FM_BACKUP_BIOS_SEL_N")
	)
	(segment
		(start 428.364396 -53.807868)
		(end 435.210966 -53.807868)
		(width 0.089408)
		(layer "In2.Cu")
		(net "FM_BACKUP_BIOS_SEL_N")
	)
	(segment
		(start 411.530546 -56.150256)
		(end 420.529512 -56.150256)
		(width 0.089408)
		(layer "In2.Cu")
		(net "FM_BACKUP_BIOS_SEL_N")
	)
	(segment
		(start 462.153 -31.75)
		(end 463.661506 -33.258506)
		(width 0.089408)
		(layer "In2.Cu")
		(net "FM_BACKUP_BIOS_SEL_N")
	)
	(segment
		(start 427.425866 -54.746398)
		(end 428.364396 -53.807868)
		(width 0.089408)
		(layer "In2.Cu")
		(net "FM_BACKUP_BIOS_SEL_N")
	)
	(segment
		(start 404.37054 -78.626716)
		(end 404.37054 -75.14082)
		(width 0.089408)
		(layer "In2.Cu")
		(net "FM_BACKUP_BIOS_SEL_N")
	)
	(segment
		(start 476.404432 -24.674068)
		(end 479.531426 -24.674068)
		(width 0.089408)
		(layer "In2.Cu")
		(net "FM_BACKUP_BIOS_SEL_N")
	)
	(segment
		(start 404.872698 -79.410814)
		(end 404.872952 -79.41056)
		(width 0.089408)
		(layer "In2.Cu")
		(net "FM_BACKUP_BIOS_SEL_N")
	)
	(segment
		(start 407.035 -82.523584)
		(end 404.872698 -80.361282)
		(width 0.089408)
		(layer "In2.Cu")
		(net "FM_BACKUP_BIOS_SEL_N")
	)
	(segment
		(start 427.134274 -24.420576)
		(end 428.216314 -23.338536)
		(width 0.089408)
		(layer "In2.Cu")
		(net "FM_BACKUP_BIOS_SEL_N")
	)
	(segment
		(start 432.893724 -23.74519)
		(end 434.526182 -23.74519)
		(width 0.089408)
		(layer "In2.Cu")
		(net "FM_BACKUP_BIOS_SEL_N")
	)
	(segment
		(start 449.437506 -24.4348)
		(end 450.488812 -25.486106)
		(width 0.089408)
		(layer "In2.Cu")
		(net "FM_BACKUP_BIOS_SEL_N")
	)
	(segment
		(start 474.723968 -26.354532)
		(end 476.404432 -24.674068)
		(width 0.089408)
		(layer "In2.Cu")
		(net "FM_BACKUP_BIOS_SEL_N")
	)
	(segment
		(start 444.336678 -22.075394)
		(end 446.696084 -24.4348)
		(width 0.089408)
		(layer "In2.Cu")
		(net "FM_BACKUP_BIOS_SEL_N")
	)
	(segment
		(start 426.419264 -24.420576)
		(end 427.134274 -24.420576)
		(width 0.089408)
		(layer "In2.Cu")
		(net "FM_BACKUP_BIOS_SEL_N")
	)
	(segment
		(start 467.033864 -56.074818)
		(end 468.27313 -54.835552)
		(width 0.089408)
		(layer "In2.Cu")
		(net "FM_BACKUP_BIOS_SEL_N")
	)
	(segment
		(start 434.526182 -23.74519)
		(end 434.921914 -23.349458)
		(width 0.089408)
		(layer "In2.Cu")
		(net "FM_BACKUP_BIOS_SEL_N")
	)
	(segment
		(start 469.226646 -53.050186)
		(end 471.987372 -53.050186)
		(width 0.089408)
		(layer "In2.Cu")
		(net "FM_BACKUP_BIOS_SEL_N")
	)
	(segment
		(start 432.48707 -23.338536)
		(end 432.893724 -23.74519)
		(width 0.089408)
		(layer "In2.Cu")
		(net "FM_BACKUP_BIOS_SEL_N")
	)
	(segment
		(start 423.865802 -25.831292)
		(end 424.810682 -24.886412)
		(width 0.089408)
		(layer "In2.Cu")
		(net "FM_BACKUP_BIOS_SEL_N")
	)
	(segment
		(start 421.89019 -27.734514)
		(end 422.324784 -27.734514)
		(width 0.089408)
		(layer "In2.Cu")
		(net "FM_BACKUP_BIOS_SEL_N")
	)
	(segment
		(start 434.922168 -23.349458)
		(end 435.26837 -23.003256)
		(width 0.089408)
		(layer "In2.Cu")
		(net "FM_BACKUP_BIOS_SEL_N")
	)
	(segment
		(start 472.826588 -30.649672)
		(end 474.723968 -28.752292)
		(width 0.089408)
		(layer "In2.Cu")
		(net "FM_BACKUP_BIOS_SEL_N")
	)
	(segment
		(start 437.377586 -22.075394)
		(end 444.336678 -22.075394)
		(width 0.089408)
		(layer "In2.Cu")
		(net "FM_BACKUP_BIOS_SEL_N")
	)
	(segment
		(start 435.210966 -53.807868)
		(end 436.489602 -55.086504)
		(width 0.089408)
		(layer "In2.Cu")
		(net "FM_BACKUP_BIOS_SEL_N")
	)
	(segment
		(start 464.633818 -56.074818)
		(end 467.033864 -56.074818)
		(width 0.089408)
		(layer "In2.Cu")
		(net "FM_BACKUP_BIOS_SEL_N")
	)
	(segment
		(start 480.226116 -28.731972)
		(end 480.226116 -33.479486)
		(width 0.089408)
		(layer "In9.Cu")
		(net "FM_BACKUP_BIOS_SEL_N")
	)
	(segment
		(start 477.266 -44.430696)
		(end 477.266 -48.70196)
		(width 0.089408)
		(layer "In9.Cu")
		(net "FM_BACKUP_BIOS_SEL_N")
	)
	(segment
		(start 476.98152 -48.98644)
		(end 476.98152 -51.76012)
		(width 0.089408)
		(layer "In9.Cu")
		(net "FM_BACKUP_BIOS_SEL_N")
	)
	(segment
		(start 480.226116 -33.479486)
		(end 477.727264 -35.978338)
		(width 0.089408)
		(layer "In9.Cu")
		(net "FM_BACKUP_BIOS_SEL_N")
	)
	(segment
		(start 481.235512 -27.722576)
		(end 480.226116 -28.731972)
		(width 0.089408)
		(layer "In9.Cu")
		(net "FM_BACKUP_BIOS_SEL_N")
	)
	(segment
		(start 477.266 -48.70196)
		(end 476.98152 -48.98644)
		(width 0.089408)
		(layer "In9.Cu")
		(net "FM_BACKUP_BIOS_SEL_N")
	)
	(segment
		(start 478.447608 -39.860474)
		(end 477.712278 -40.595804)
		(width 0.089408)
		(layer "In9.Cu")
		(net "FM_BACKUP_BIOS_SEL_N")
	)
	(segment
		(start 478.447608 -38.429692)
		(end 478.447608 -39.860474)
		(width 0.089408)
		(layer "In9.Cu")
		(net "FM_BACKUP_BIOS_SEL_N")
	)
	(segment
		(start 477.727264 -35.978338)
		(end 477.727264 -37.709348)
		(width 0.089408)
		(layer "In9.Cu")
		(net "FM_BACKUP_BIOS_SEL_N")
	)
	(segment
		(start 482.117908 -27.47645)
		(end 481.871782 -27.722576)
		(width 0.089408)
		(layer "In9.Cu")
		(net "FM_BACKUP_BIOS_SEL_N")
	)
	(segment
		(start 477.712278 -40.595804)
		(end 477.712278 -43.984418)
		(width 0.089408)
		(layer "In9.Cu")
		(net "FM_BACKUP_BIOS_SEL_N")
	)
	(segment
		(start 482.117908 -27.26055)
		(end 482.117908 -27.47645)
		(width 0.089408)
		(layer "In9.Cu")
		(net "FM_BACKUP_BIOS_SEL_N")
	)
	(segment
		(start 477.727264 -37.709348)
		(end 478.447608 -38.429692)
		(width 0.089408)
		(layer "In9.Cu")
		(net "FM_BACKUP_BIOS_SEL_N")
	)
	(segment
		(start 481.871782 -27.722576)
		(end 481.235512 -27.722576)
		(width 0.089408)
		(layer "In9.Cu")
		(net "FM_BACKUP_BIOS_SEL_N")
	)
	(segment
		(start 477.712278 -43.984418)
		(end 477.266 -44.430696)
		(width 0.089408)
		(layer "In9.Cu")
		(net "FM_BACKUP_BIOS_SEL_N")
	)
	(segment
		(start 390.1186 -81.897728)
		(end 389.84936 -81.628488)
		(width 0.089408)
		(layer "In11.Cu")
		(net "FM_BACKUP_BIOS_SEL_N")
	)
	(segment
		(start 388.366 -73.787)
		(end 387.407404 -72.828404)
		(width 0.089408)
		(layer "In11.Cu")
		(net "FM_BACKUP_BIOS_SEL_N")
	)
	(segment
		(start 389.84936 -81.628488)
		(end 389.84936 -79.421482)
		(width 0.089408)
		(layer "In11.Cu")
		(net "FM_BACKUP_BIOS_SEL_N")
	)
	(segment
		(start 390.1186 -87.7316)
		(end 390.1186 -81.897728)
		(width 0.089408)
		(layer "In11.Cu")
		(net "FM_BACKUP_BIOS_SEL_N")
	)
	(segment
		(start 390.7028 -92.6338)
		(end 390.3218 -92.2528)
		(width 0.089408)
		(layer "In11.Cu")
		(net "FM_BACKUP_BIOS_SEL_N")
	)
	(segment
		(start 390.3218 -92.2528)
		(end 390.3218 -87.9348)
		(width 0.089408)
		(layer "In11.Cu")
		(net "FM_BACKUP_BIOS_SEL_N")
	)
	(segment
		(start 387.407404 -71.606156)
		(end 386.578348 -70.7771)
		(width 0.089408)
		(layer "In11.Cu")
		(net "FM_BACKUP_BIOS_SEL_N")
	)
	(segment
		(start 390.3218 -87.9348)
		(end 390.1186 -87.7316)
		(width 0.089408)
		(layer "In11.Cu")
		(net "FM_BACKUP_BIOS_SEL_N")
	)
	(segment
		(start 387.407404 -72.828404)
		(end 387.407404 -71.606156)
		(width 0.089408)
		(layer "In11.Cu")
		(net "FM_BACKUP_BIOS_SEL_N")
	)
	(segment
		(start 389.84936 -79.421482)
		(end 388.935722 -78.507844)
		(width 0.089408)
		(layer "In11.Cu")
		(net "FM_BACKUP_BIOS_SEL_N")
	)
	(segment
		(start 389.3058 -73.787)
		(end 388.366 -73.787)
		(width 0.089408)
		(layer "In11.Cu")
		(net "FM_BACKUP_BIOS_SEL_N")
	)
	(segment
		(start 390.271 -74.7522)
		(end 389.3058 -73.787)
		(width 0.089408)
		(layer "In11.Cu")
		(net "FM_BACKUP_BIOS_SEL_N")
	)
	(segment
		(start 390.271 -75.5396)
		(end 390.271 -74.7522)
		(width 0.089408)
		(layer "In11.Cu")
		(net "FM_BACKUP_BIOS_SEL_N")
	)
	(segment
		(start 388.935722 -76.874878)
		(end 390.271 -75.5396)
		(width 0.089408)
		(layer "In11.Cu")
		(net "FM_BACKUP_BIOS_SEL_N")
	)
	(segment
		(start 388.935722 -78.507844)
		(end 388.935722 -76.874878)
		(width 0.089408)
		(layer "In11.Cu")
		(net "FM_BACKUP_BIOS_SEL_N")
	)
	(segment
		(start 453.644 -41.529)
		(end 453.517 -41.656)
		(width 0.10795)
		(layer "F.Cu")
		(net "RST_BMC_DDR3_R_N")
	)
	(segment
		(start 453.644 -41.021)
		(end 453.644 -41.529)
		(width 0.10795)
		(layer "F.Cu")
		(net "RST_BMC_DDR3_R_N")
	)
	(segment
		(start 454.152 -32.1945)
		(end 454.2155 -32.131)
		(width 0.10795)
		(layer "F.Cu")
		(net "RST_BMC_DDR3_R_N")
	)
	(segment
		(start 454.152 -32.766)
		(end 454.152 -32.1945)
		(width 0.10795)
		(layer "F.Cu")
		(net "RST_BMC_DDR3_R_N")
	)
	(segment
		(start 454.420986 -33.034986)
		(end 454.152 -32.766)
		(width 0.10795)
		(layer "F.Cu")
		(net "RST_BMC_DDR3_R_N")
	)
	(segment
		(start 455.422 -33.034986)
		(end 454.420986 -33.034986)
		(width 0.10795)
		(layer "F.Cu")
		(net "RST_BMC_DDR3_R_N")
	)
	(via
		(at 454.152 -32.766)
		(size 0.508)
		(drill 0.254)
		(layers "F.Cu" "B.Cu")
		(net "RST_BMC_DDR3_R_N")
	)
	(via
		(at 453.517 -41.656)
		(size 0.508)
		(drill 0.254)
		(layers "F.Cu" "B.Cu")
		(net "RST_BMC_DDR3_R_N")
	)
	(via
		(at 452.869046 -39.5986)
		(size 0.6604)
		(drill 0.3302)
		(layers "F.Cu" "B.Cu")
		(net "RST_BMC_DDR3_R_N")
	)
	(segment
		(start 453.132698 -38.989)
		(end 453.132698 -35.188652)
		(width 0.10795)
		(layer "B.Cu")
		(net "RST_BMC_DDR3_R_N")
	)
	(segment
		(start 453.136 -35.18535)
		(end 453.136 -34.0106)
		(width 0.10795)
		(layer "B.Cu")
		(net "RST_BMC_DDR3_R_N")
	)
	(segment
		(start 454.152 -32.9946)
		(end 454.152 -32.766)
		(width 0.10795)
		(layer "B.Cu")
		(net "RST_BMC_DDR3_R_N")
	)
	(segment
		(start 452.869046 -39.5986)
		(end 452.869046 -41.008046)
		(width 0.10795)
		(layer "B.Cu")
		(net "RST_BMC_DDR3_R_N")
	)
	(segment
		(start 452.869046 -39.5986)
		(end 452.869046 -39.252652)
		(width 0.10795)
		(layer "B.Cu")
		(net "RST_BMC_DDR3_R_N")
	)
	(segment
		(start 452.869046 -39.252652)
		(end 453.132698 -38.989)
		(width 0.10795)
		(layer "B.Cu")
		(net "RST_BMC_DDR3_R_N")
	)
	(segment
		(start 452.869046 -41.008046)
		(end 453.141842 -41.280842)
		(width 0.10795)
		(layer "B.Cu")
		(net "RST_BMC_DDR3_R_N")
	)
	(segment
		(start 453.141842 -41.280842)
		(end 453.517 -41.656)
		(width 0.089408)
		(layer "B.Cu")
		(net "RST_BMC_DDR3_R_N")
	)
	(segment
		(start 453.132698 -35.188652)
		(end 453.136 -35.18535)
		(width 0.10795)
		(layer "B.Cu")
		(net "RST_BMC_DDR3_R_N")
	)
	(segment
		(start 453.136 -34.0106)
		(end 454.152 -32.9946)
		(width 0.10795)
		(layer "B.Cu")
		(net "RST_BMC_DDR3_R_N")
	)
	(segment
		(start 396.99184 -101.97084)
		(end 397.14805 -101.898196)
		(width 0.10795)
		(layer "F.Cu")
		(net "FM_BIOS_PREFRB2_GOOD")
	)
	(segment
		(start 396.65275 -102.12832)
		(end 396.99184 -101.97084)
		(width 0.10795)
		(layer "F.Cu")
		(net "FM_BIOS_PREFRB2_GOOD")
	)
	(segment
		(start 420.69004 -28.134564)
		(end 421.09009 -27.734514)
		(width 0.10795)
		(layer "F.Cu")
		(net "FM_BIOS_PREFRB2_GOOD")
	)
	(via
		(at 397.14805 -101.898196)
		(size 0.508)
		(drill 0.254)
		(layers "F.Cu" "B.Cu")
		(net "FM_BIOS_PREFRB2_GOOD")
	)
	(via
		(at 461.016604 -30.855412)
		(size 0.508)
		(drill 0.254)
		(layers "F.Cu" "B.Cu")
		(net "FM_BIOS_PREFRB2_GOOD")
	)
	(via
		(at 421.09009 -27.734514)
		(size 0.4572)
		(drill 0.2032)
		(layers "F.Cu" "B.Cu")
		(net "FM_BIOS_PREFRB2_GOOD")
	)
	(via
		(at 422.31945 -27.04465)
		(size 0.6604)
		(drill 0.3302)
		(layers "F.Cu" "B.Cu")
		(net "FM_BIOS_PREFRB2_GOOD")
	)
	(segment
		(start 427.4185 -24.13)
		(end 427.4185 -24.46401)
		(width 0.10795)
		(layer "B.Cu")
		(net "FM_BIOS_PREFRB2_GOOD")
	)
	(segment
		(start 421.09009 -27.734514)
		(end 421.539162 -27.285442)
		(width 0.10795)
		(layer "B.Cu")
		(net "FM_BIOS_PREFRB2_GOOD")
	)
	(segment
		(start 425.447968 -25.767792)
		(end 423.828972 -25.767792)
		(width 0.10795)
		(layer "B.Cu")
		(net "FM_BIOS_PREFRB2_GOOD")
	)
	(segment
		(start 422.078658 -27.285442)
		(end 422.31945 -27.04465)
		(width 0.10795)
		(layer "B.Cu")
		(net "FM_BIOS_PREFRB2_GOOD")
	)
	(segment
		(start 426.55363 -24.662384)
		(end 426.426884 -24.78913)
		(width 0.10795)
		(layer "B.Cu")
		(net "FM_BIOS_PREFRB2_GOOD")
	)
	(segment
		(start 427.4185 -24.46401)
		(end 427.220126 -24.662384)
		(width 0.10795)
		(layer "B.Cu")
		(net "FM_BIOS_PREFRB2_GOOD")
	)
	(segment
		(start 426.42663 -24.78913)
		(end 425.447968 -25.767792)
		(width 0.10795)
		(layer "B.Cu")
		(net "FM_BIOS_PREFRB2_GOOD")
	)
	(segment
		(start 421.539162 -27.285442)
		(end 422.078658 -27.285442)
		(width 0.10795)
		(layer "B.Cu")
		(net "FM_BIOS_PREFRB2_GOOD")
	)
	(segment
		(start 427.220126 -24.662384)
		(end 426.55363 -24.662384)
		(width 0.10795)
		(layer "B.Cu")
		(net "FM_BIOS_PREFRB2_GOOD")
	)
	(segment
		(start 423.366438 -26.230326)
		(end 423.133774 -26.230326)
		(width 0.10795)
		(layer "B.Cu")
		(net "FM_BIOS_PREFRB2_GOOD")
	)
	(segment
		(start 426.426884 -24.78913)
		(end 426.42663 -24.78913)
		(width 0.089408)
		(layer "B.Cu")
		(net "FM_BIOS_PREFRB2_GOOD")
	)
	(segment
		(start 423.133774 -26.230326)
		(end 422.31945 -27.04465)
		(width 0.10795)
		(layer "B.Cu")
		(net "FM_BIOS_PREFRB2_GOOD")
	)
	(segment
		(start 423.828972 -25.767792)
		(end 423.366438 -26.230326)
		(width 0.10795)
		(layer "B.Cu")
		(net "FM_BIOS_PREFRB2_GOOD")
	)
	(segment
		(start 425.872148 -24.687784)
		(end 424.717972 -24.687784)
		(width 0.089408)
		(layer "In2.Cu")
		(net "FM_BIOS_PREFRB2_GOOD")
	)
	(segment
		(start 434.86832 -22.811994)
		(end 434.36286 -23.317454)
		(width 0.089408)
		(layer "In2.Cu")
		(net "FM_BIOS_PREFRB2_GOOD")
	)
	(segment
		(start 455.152506 -24.699976)
		(end 450.191124 -24.699976)
		(width 0.089408)
		(layer "In2.Cu")
		(net "FM_BIOS_PREFRB2_GOOD")
	)
	(segment
		(start 461.016604 -30.855412)
		(end 460.021178 -30.855412)
		(width 0.089408)
		(layer "In2.Cu")
		(net "FM_BIOS_PREFRB2_GOOD")
	)
	(segment
		(start 427.996096 -23.147528)
		(end 426.96511 -24.178514)
		(width 0.089408)
		(layer "In2.Cu")
		(net "FM_BIOS_PREFRB2_GOOD")
	)
	(segment
		(start 450.191124 -24.699976)
		(end 448.951096 -23.459948)
		(width 0.089408)
		(layer "In2.Cu")
		(net "FM_BIOS_PREFRB2_GOOD")
	)
	(segment
		(start 446.143634 -23.459948)
		(end 444.568072 -21.884386)
		(width 0.089408)
		(layer "In2.Cu")
		(net "FM_BIOS_PREFRB2_GOOD")
	)
	(segment
		(start 432.736244 -23.317454)
		(end 432.566318 -23.147528)
		(width 0.089408)
		(layer "In2.Cu")
		(net "FM_BIOS_PREFRB2_GOOD")
	)
	(segment
		(start 421.654224 -27.17038)
		(end 421.09009 -27.734514)
		(width 0.089408)
		(layer "In2.Cu")
		(net "FM_BIOS_PREFRB2_GOOD")
	)
	(segment
		(start 422.235376 -27.17038)
		(end 421.654224 -27.17038)
		(width 0.089408)
		(layer "In2.Cu")
		(net "FM_BIOS_PREFRB2_GOOD")
	)
	(segment
		(start 424.717972 -24.687784)
		(end 422.235376 -27.17038)
		(width 0.089408)
		(layer "In2.Cu")
		(net "FM_BIOS_PREFRB2_GOOD")
	)
	(segment
		(start 448.951096 -23.459948)
		(end 446.143634 -23.459948)
		(width 0.089408)
		(layer "In2.Cu")
		(net "FM_BIOS_PREFRB2_GOOD")
	)
	(segment
		(start 426.96511 -24.178514)
		(end 426.381418 -24.178514)
		(width 0.089408)
		(layer "In2.Cu")
		(net "FM_BIOS_PREFRB2_GOOD")
	)
	(segment
		(start 444.568072 -21.884386)
		(end 437.298338 -21.884386)
		(width 0.089408)
		(layer "In2.Cu")
		(net "FM_BIOS_PREFRB2_GOOD")
	)
	(segment
		(start 458.5081 -28.05557)
		(end 455.152506 -24.699976)
		(width 0.089408)
		(layer "In2.Cu")
		(net "FM_BIOS_PREFRB2_GOOD")
	)
	(segment
		(start 426.381418 -24.178514)
		(end 425.872148 -24.687784)
		(width 0.089408)
		(layer "In2.Cu")
		(net "FM_BIOS_PREFRB2_GOOD")
	)
	(segment
		(start 434.36286 -23.317454)
		(end 432.736244 -23.317454)
		(width 0.089408)
		(layer "In2.Cu")
		(net "FM_BIOS_PREFRB2_GOOD")
	)
	(segment
		(start 432.566318 -23.147528)
		(end 427.996096 -23.147528)
		(width 0.089408)
		(layer "In2.Cu")
		(net "FM_BIOS_PREFRB2_GOOD")
	)
	(segment
		(start 436.37073 -22.811994)
		(end 434.86832 -22.811994)
		(width 0.089408)
		(layer "In2.Cu")
		(net "FM_BIOS_PREFRB2_GOOD")
	)
	(segment
		(start 460.021178 -30.855412)
		(end 458.5081 -29.342334)
		(width 0.089408)
		(layer "In2.Cu")
		(net "FM_BIOS_PREFRB2_GOOD")
	)
	(segment
		(start 437.298338 -21.884386)
		(end 436.37073 -22.811994)
		(width 0.089408)
		(layer "In2.Cu")
		(net "FM_BIOS_PREFRB2_GOOD")
	)
	(segment
		(start 458.5081 -29.342334)
		(end 458.5081 -28.05557)
		(width 0.089408)
		(layer "In2.Cu")
		(net "FM_BIOS_PREFRB2_GOOD")
	)
	(segment
		(start 405.855678 -87.530432)
		(end 407.353008 -86.033102)
		(width 0.089408)
		(layer "In9.Cu")
		(net "FM_BIOS_PREFRB2_GOOD")
	)
	(segment
		(start 407.353008 -86.033102)
		(end 407.353008 -84.517992)
		(width 0.089408)
		(layer "In9.Cu")
		(net "FM_BIOS_PREFRB2_GOOD")
	)
	(segment
		(start 435.46649 -51.195478)
		(end 436.290466 -50.371502)
		(width 0.089408)
		(layer "In9.Cu")
		(net "FM_BIOS_PREFRB2_GOOD")
	)
	(segment
		(start 413.512 -78.359)
		(end 413.512 -72.517)
		(width 0.089408)
		(layer "In9.Cu")
		(net "FM_BIOS_PREFRB2_GOOD")
	)
	(segment
		(start 395.75867 -100.015802)
		(end 396.06093 -99.713542)
		(width 0.089408)
		(layer "In9.Cu")
		(net "FM_BIOS_PREFRB2_GOOD")
	)
	(segment
		(start 456.75423 -44.903136)
		(end 457.092304 -44.565062)
		(width 0.089408)
		(layer "In9.Cu")
		(net "FM_BIOS_PREFRB2_GOOD")
	)
	(segment
		(start 396.122652 -100.710492)
		(end 395.75867 -100.34651)
		(width 0.089408)
		(layer "In9.Cu")
		(net "FM_BIOS_PREFRB2_GOOD")
	)
	(segment
		(start 425.48556 -52.140104)
		(end 426.430186 -51.195478)
		(width 0.089408)
		(layer "In9.Cu")
		(net "FM_BIOS_PREFRB2_GOOD")
	)
	(segment
		(start 426.430186 -51.195478)
		(end 435.46649 -51.195478)
		(width 0.089408)
		(layer "In9.Cu")
		(net "FM_BIOS_PREFRB2_GOOD")
	)
	(segment
		(start 396.657068 -98.730816)
		(end 396.657068 -98.390964)
		(width 0.089408)
		(layer "In9.Cu")
		(net "FM_BIOS_PREFRB2_GOOD")
	)
	(segment
		(start 414.51403 -63.819786)
		(end 414.719516 -63.6143)
		(width 0.089408)
		(layer "In9.Cu")
		(net "FM_BIOS_PREFRB2_GOOD")
	)
	(segment
		(start 458.61986 -37.273992)
		(end 461.070452 -34.8234)
		(width 0.089408)
		(layer "In9.Cu")
		(net "FM_BIOS_PREFRB2_GOOD")
	)
	(segment
		(start 413.258 -72.263)
		(end 413.258 -70.866)
		(width 0.089408)
		(layer "In9.Cu")
		(net "FM_BIOS_PREFRB2_GOOD")
	)
	(segment
		(start 414.12668 -67.812666)
		(end 414.12668 -67.81165)
		(width 0.089408)
		(layer "In9.Cu")
		(net "FM_BIOS_PREFRB2_GOOD")
	)
	(segment
		(start 401.731734 -94.6658)
		(end 402.688298 -93.709236)
		(width 0.089408)
		(layer "In9.Cu")
		(net "FM_BIOS_PREFRB2_GOOD")
	)
	(segment
		(start 396.06093 -99.326954)
		(end 396.657068 -98.730816)
		(width 0.089408)
		(layer "In9.Cu")
		(net "FM_BIOS_PREFRB2_GOOD")
	)
	(segment
		(start 462.543398 -32.046418)
		(end 461.352392 -30.855412)
		(width 0.089408)
		(layer "In9.Cu")
		(net "FM_BIOS_PREFRB2_GOOD")
	)
	(segment
		(start 414.719516 -61.701172)
		(end 414.864296 -61.556392)
		(width 0.089408)
		(layer "In9.Cu")
		(net "FM_BIOS_PREFRB2_GOOD")
	)
	(segment
		(start 457.510896 -42.755312)
		(end 457.510896 -40.818816)
		(width 0.089408)
		(layer "In9.Cu")
		(net "FM_BIOS_PREFRB2_GOOD")
	)
	(segment
		(start 423.284396 -53.040534)
		(end 424.184826 -52.140104)
		(width 0.089408)
		(layer "In9.Cu")
		(net "FM_BIOS_PREFRB2_GOOD")
	)
	(segment
		(start 397.14805 -101.898196)
		(end 396.947136 -101.898196)
		(width 0.089408)
		(layer "In9.Cu")
		(net "FM_BIOS_PREFRB2_GOOD")
	)
	(segment
		(start 414.864296 -60.4647)
		(end 414.719516 -60.31992)
		(width 0.089408)
		(layer "In9.Cu")
		(net "FM_BIOS_PREFRB2_GOOD")
	)
	(segment
		(start 413.258 -70.866)
		(end 413.947356 -70.176644)
		(width 0.089408)
		(layer "In9.Cu")
		(net "FM_BIOS_PREFRB2_GOOD")
	)
	(segment
		(start 396.657068 -98.390964)
		(end 397.043656 -98.004376)
		(width 0.089408)
		(layer "In9.Cu")
		(net "FM_BIOS_PREFRB2_GOOD")
	)
	(segment
		(start 396.06093 -99.713542)
		(end 396.06093 -99.326954)
		(width 0.089408)
		(layer "In9.Cu")
		(net "FM_BIOS_PREFRB2_GOOD")
	)
	(segment
		(start 405.855678 -90.131138)
		(end 405.855678 -87.530432)
		(width 0.089408)
		(layer "In9.Cu")
		(net "FM_BIOS_PREFRB2_GOOD")
	)
	(segment
		(start 461.352392 -30.855412)
		(end 461.016604 -30.855412)
		(width 0.089408)
		(layer "In9.Cu")
		(net "FM_BIOS_PREFRB2_GOOD")
	)
	(segment
		(start 436.290466 -50.293524)
		(end 439.211974 -47.372016)
		(width 0.089408)
		(layer "In9.Cu")
		(net "FM_BIOS_PREFRB2_GOOD")
	)
	(segment
		(start 414.51403 -67.4243)
		(end 414.51403 -63.819786)
		(width 0.089408)
		(layer "In9.Cu")
		(net "FM_BIOS_PREFRB2_GOOD")
	)
	(segment
		(start 436.290466 -50.371502)
		(end 436.290466 -50.293524)
		(width 0.089408)
		(layer "In9.Cu")
		(net "FM_BIOS_PREFRB2_GOOD")
	)
	(segment
		(start 457.092304 -44.565062)
		(end 457.092304 -43.173904)
		(width 0.089408)
		(layer "In9.Cu")
		(net "FM_BIOS_PREFRB2_GOOD")
	)
	(segment
		(start 397.043656 -98.004376)
		(end 397.808704 -98.004376)
		(width 0.089408)
		(layer "In9.Cu")
		(net "FM_BIOS_PREFRB2_GOOD")
	)
	(segment
		(start 456.75423 -45.650912)
		(end 456.75423 -44.903136)
		(width 0.089408)
		(layer "In9.Cu")
		(net "FM_BIOS_PREFRB2_GOOD")
	)
	(segment
		(start 457.092304 -43.173904)
		(end 457.510896 -42.755312)
		(width 0.089408)
		(layer "In9.Cu")
		(net "FM_BIOS_PREFRB2_GOOD")
	)
	(segment
		(start 455.033126 -47.372016)
		(end 456.75423 -45.650912)
		(width 0.089408)
		(layer "In9.Cu")
		(net "FM_BIOS_PREFRB2_GOOD")
	)
	(segment
		(start 414.719516 -58.613294)
		(end 418.13734 -55.19547)
		(width 0.089408)
		(layer "In9.Cu")
		(net "FM_BIOS_PREFRB2_GOOD")
	)
	(segment
		(start 396.122652 -101.073712)
		(end 396.122652 -100.710492)
		(width 0.089408)
		(layer "In9.Cu")
		(net "FM_BIOS_PREFRB2_GOOD")
	)
	(segment
		(start 413.512 -72.517)
		(end 413.258 -72.263)
		(width 0.089408)
		(layer "In9.Cu")
		(net "FM_BIOS_PREFRB2_GOOD")
	)
	(segment
		(start 461.825594 -34.8234)
		(end 462.543398 -34.105596)
		(width 0.089408)
		(layer "In9.Cu")
		(net "FM_BIOS_PREFRB2_GOOD")
	)
	(segment
		(start 402.688298 -93.298518)
		(end 405.855678 -90.131138)
		(width 0.089408)
		(layer "In9.Cu")
		(net "FM_BIOS_PREFRB2_GOOD")
	)
	(segment
		(start 414.864296 -61.556392)
		(end 414.864296 -60.4647)
		(width 0.089408)
		(layer "In9.Cu")
		(net "FM_BIOS_PREFRB2_GOOD")
	)
	(segment
		(start 439.211974 -47.372016)
		(end 455.033126 -47.372016)
		(width 0.089408)
		(layer "In9.Cu")
		(net "FM_BIOS_PREFRB2_GOOD")
	)
	(segment
		(start 414.719516 -60.31992)
		(end 414.719516 -58.613294)
		(width 0.089408)
		(layer "In9.Cu")
		(net "FM_BIOS_PREFRB2_GOOD")
	)
	(segment
		(start 457.510896 -40.818816)
		(end 458.61986 -39.709852)
		(width 0.089408)
		(layer "In9.Cu")
		(net "FM_BIOS_PREFRB2_GOOD")
	)
	(segment
		(start 407.353008 -84.517992)
		(end 413.512 -78.359)
		(width 0.089408)
		(layer "In9.Cu")
		(net "FM_BIOS_PREFRB2_GOOD")
	)
	(segment
		(start 418.13734 -55.19547)
		(end 419.189916 -55.19547)
		(width 0.089408)
		(layer "In9.Cu")
		(net "FM_BIOS_PREFRB2_GOOD")
	)
	(segment
		(start 461.070452 -34.8234)
		(end 461.825594 -34.8234)
		(width 0.089408)
		(layer "In9.Cu")
		(net "FM_BIOS_PREFRB2_GOOD")
	)
	(segment
		(start 413.947356 -67.99199)
		(end 414.12668 -67.812666)
		(width 0.089408)
		(layer "In9.Cu")
		(net "FM_BIOS_PREFRB2_GOOD")
	)
	(segment
		(start 458.61986 -39.709852)
		(end 458.61986 -37.273992)
		(width 0.089408)
		(layer "In9.Cu")
		(net "FM_BIOS_PREFRB2_GOOD")
	)
	(segment
		(start 420.26078 -54.463696)
		(end 421.683942 -53.040534)
		(width 0.089408)
		(layer "In9.Cu")
		(net "FM_BIOS_PREFRB2_GOOD")
	)
	(segment
		(start 424.184826 -52.140104)
		(end 425.48556 -52.140104)
		(width 0.089408)
		(layer "In9.Cu")
		(net "FM_BIOS_PREFRB2_GOOD")
	)
	(segment
		(start 398.145 -97.66808)
		(end 398.145 -97.559876)
		(width 0.089408)
		(layer "In9.Cu")
		(net "FM_BIOS_PREFRB2_GOOD")
	)
	(segment
		(start 414.12668 -67.81165)
		(end 414.51403 -67.4243)
		(width 0.089408)
		(layer "In9.Cu")
		(net "FM_BIOS_PREFRB2_GOOD")
	)
	(segment
		(start 421.683942 -53.040534)
		(end 423.284396 -53.040534)
		(width 0.089408)
		(layer "In9.Cu")
		(net "FM_BIOS_PREFRB2_GOOD")
	)
	(segment
		(start 398.145 -97.559876)
		(end 401.039076 -94.6658)
		(width 0.089408)
		(layer "In9.Cu")
		(net "FM_BIOS_PREFRB2_GOOD")
	)
	(segment
		(start 395.75867 -100.34651)
		(end 395.75867 -100.015802)
		(width 0.089408)
		(layer "In9.Cu")
		(net "FM_BIOS_PREFRB2_GOOD")
	)
	(segment
		(start 419.189916 -55.19547)
		(end 419.92169 -54.463696)
		(width 0.089408)
		(layer "In9.Cu")
		(net "FM_BIOS_PREFRB2_GOOD")
	)
	(segment
		(start 402.688298 -93.709236)
		(end 402.688298 -93.298518)
		(width 0.089408)
		(layer "In9.Cu")
		(net "FM_BIOS_PREFRB2_GOOD")
	)
	(segment
		(start 396.947136 -101.898196)
		(end 396.122652 -101.073712)
		(width 0.089408)
		(layer "In9.Cu")
		(net "FM_BIOS_PREFRB2_GOOD")
	)
	(segment
		(start 397.808704 -98.004376)
		(end 398.145 -97.66808)
		(width 0.089408)
		(layer "In9.Cu")
		(net "FM_BIOS_PREFRB2_GOOD")
	)
	(segment
		(start 401.039076 -94.6658)
		(end 401.731734 -94.6658)
		(width 0.089408)
		(layer "In9.Cu")
		(net "FM_BIOS_PREFRB2_GOOD")
	)
	(segment
		(start 419.92169 -54.463696)
		(end 420.26078 -54.463696)
		(width 0.089408)
		(layer "In9.Cu")
		(net "FM_BIOS_PREFRB2_GOOD")
	)
	(segment
		(start 413.947356 -70.176644)
		(end 413.947356 -67.99199)
		(width 0.089408)
		(layer "In9.Cu")
		(net "FM_BIOS_PREFRB2_GOOD")
	)
	(segment
		(start 414.719516 -63.6143)
		(end 414.719516 -61.701172)
		(width 0.089408)
		(layer "In9.Cu")
		(net "FM_BIOS_PREFRB2_GOOD")
	)
	(segment
		(start 462.543398 -34.105596)
		(end 462.543398 -32.046418)
		(width 0.089408)
		(layer "In9.Cu")
		(net "FM_BIOS_PREFRB2_GOOD")
	)
	(segment
		(start 172.408088 -92.150946)
		(end 172.408088 -91.22156)
		(width 0.10795)
		(layer "F.Cu")
		(net "PU_CPU1_TSC_SYNC")
	)
	(segment
		(start 133.665214 -66.800984)
		(end 134.236714 -66.800984)
		(width 0.10795)
		(layer "F.Cu")
		(net "PU_CPU1_TSC_SYNC")
	)
	(segment
		(start 172.39742 -92.161614)
		(end 172.408088 -92.150946)
		(width 0.10795)
		(layer "F.Cu")
		(net "PU_CPU1_TSC_SYNC")
	)
	(via
		(at 134.236714 -66.800984)
		(size 0.508)
		(drill 0.254)
		(layers "F.Cu" "B.Cu")
		(net "PU_CPU1_TSC_SYNC")
	)
	(via
		(at 172.39742 -92.161614)
		(size 0.508)
		(drill 0.254)
		(layers "F.Cu" "B.Cu")
		(net "PU_CPU1_TSC_SYNC")
	)
	(segment
		(start 136.801098 -68.687188)
		(end 136.833864 -68.687188)
		(width 0.089408)
		(layer "In11.Cu")
		(net "PU_CPU1_TSC_SYNC")
	)
	(segment
		(start 163.505896 -92.093034)
		(end 172.32884 -92.093034)
		(width 0.089408)
		(layer "In11.Cu")
		(net "PU_CPU1_TSC_SYNC")
	)
	(segment
		(start 142.362174 -70.949312)
		(end 163.505896 -92.093034)
		(width 0.089408)
		(layer "In11.Cu")
		(net "PU_CPU1_TSC_SYNC")
	)
	(segment
		(start 139.376658 -70.172834)
		(end 139.409424 -70.172834)
		(width 0.089408)
		(layer "In11.Cu")
		(net "PU_CPU1_TSC_SYNC")
	)
	(segment
		(start 135.084058 -67.696588)
		(end 135.116824 -67.696588)
		(width 0.089408)
		(layer "In11.Cu")
		(net "PU_CPU1_TSC_SYNC")
	)
	(segment
		(start 137.655808 -69.182234)
		(end 137.688574 -69.182234)
		(width 0.089408)
		(layer "In11.Cu")
		(net "PU_CPU1_TSC_SYNC")
	)
	(segment
		(start 138.51128 -69.677534)
		(end 138.550904 -69.677534)
		(width 0.089408)
		(layer "In11.Cu")
		(net "PU_CPU1_TSC_SYNC")
	)
	(segment
		(start 141.979142 -70.848982)
		(end 142.120366 -70.848982)
		(width 0.089408)
		(layer "In11.Cu")
		(net "PU_CPU1_TSC_SYNC")
	)
	(segment
		(start 135.938768 -68.191634)
		(end 135.971534 -68.191634)
		(width 0.089408)
		(layer "In11.Cu")
		(net "PU_CPU1_TSC_SYNC")
	)
	(segment
		(start 172.32884 -92.093034)
		(end 172.39742 -92.161614)
		(width 0.089408)
		(layer "In11.Cu")
		(net "PU_CPU1_TSC_SYNC")
	)
	(segment
		(start 141.089888 -71.163434)
		(end 141.219682 -71.163434)
		(width 0.089408)
		(layer "In11.Cu")
		(net "PU_CPU1_TSC_SYNC")
	)
	(segment
		(start 140.235178 -70.668134)
		(end 140.259308 -70.668134)
		(width 0.089408)
		(layer "In11.Cu")
		(net "PU_CPU1_TSC_SYNC")
	)
	(segment
		(start 141.219682 -71.163434)
		(end 141.979142 -70.848982)
		(width 0.089408)
		(layer "In11.Cu")
		(net "PU_CPU1_TSC_SYNC")
	)
	(segment
		(start 142.120366 -70.848982)
		(end 142.362174 -70.949312)
		(width 0.089408)
		(layer "In11.Cu")
		(net "PU_CPU1_TSC_SYNC")
	)
	(arc
		(start 137.324084 -68.982336)
		(mid 137.464163 -69.125072)
		(end 137.655808 -69.182234)
		(width 0.089408)
		(layer "In11.Cu")
		(net "PU_CPU1_TSC_SYNC")
	)
	(arc
		(start 135.116824 -67.696588)
		(mid 135.400041 -67.780869)
		(end 135.607044 -67.991736)
		(width 0.089408)
		(layer "In11.Cu")
		(net "PU_CPU1_TSC_SYNC")
	)
	(arc
		(start 139.409424 -70.172834)
		(mid 139.692641 -70.257115)
		(end 139.899644 -70.467982)
		(width 0.089408)
		(layer "In11.Cu")
		(net "PU_CPU1_TSC_SYNC")
	)
	(arc
		(start 134.748524 -67.496436)
		(mid 134.890207 -67.64024)
		(end 135.084058 -67.696588)
		(width 0.089408)
		(layer "In11.Cu")
		(net "PU_CPU1_TSC_SYNC")
	)
	(arc
		(start 139.899644 -70.467982)
		(mid 140.041327 -70.611786)
		(end 140.235178 -70.668134)
		(width 0.089408)
		(layer "In11.Cu")
		(net "PU_CPU1_TSC_SYNC")
	)
	(arc
		(start 135.607044 -67.991736)
		(mid 135.747123 -68.134472)
		(end 135.938768 -68.191634)
		(width 0.089408)
		(layer "In11.Cu")
		(net "PU_CPU1_TSC_SYNC")
	)
	(arc
		(start 138.182604 -69.477636)
		(mid 138.321348 -69.619669)
		(end 138.51128 -69.677534)
		(width 0.089408)
		(layer "In11.Cu")
		(net "PU_CPU1_TSC_SYNC")
	)
	(arc
		(start 138.550904 -69.677534)
		(mid 138.834121 -69.761815)
		(end 139.041124 -69.972682)
		(width 0.089408)
		(layer "In11.Cu")
		(net "PU_CPU1_TSC_SYNC")
	)
	(arc
		(start 140.259308 -70.668134)
		(mid 140.547453 -70.750453)
		(end 140.758164 -70.963536)
		(width 0.089408)
		(layer "In11.Cu")
		(net "PU_CPU1_TSC_SYNC")
	)
	(arc
		(start 134.236714 -66.800984)
		(mid 134.511998 -67.134447)
		(end 134.748524 -67.496436)
		(width 0.089408)
		(layer "In11.Cu")
		(net "PU_CPU1_TSC_SYNC")
	)
	(arc
		(start 135.971534 -68.191634)
		(mid 136.256958 -68.275101)
		(end 136.465564 -68.487036)
		(width 0.089408)
		(layer "In11.Cu")
		(net "PU_CPU1_TSC_SYNC")
	)
	(arc
		(start 136.833864 -68.687188)
		(mid 137.117081 -68.771469)
		(end 137.324084 -68.982336)
		(width 0.089408)
		(layer "In11.Cu")
		(net "PU_CPU1_TSC_SYNC")
	)
	(arc
		(start 136.465564 -68.487036)
		(mid 136.607247 -68.63084)
		(end 136.801098 -68.687188)
		(width 0.089408)
		(layer "In11.Cu")
		(net "PU_CPU1_TSC_SYNC")
	)
	(arc
		(start 137.688574 -69.182234)
		(mid 137.973998 -69.265701)
		(end 138.182604 -69.477636)
		(width 0.089408)
		(layer "In11.Cu")
		(net "PU_CPU1_TSC_SYNC")
	)
	(arc
		(start 140.758164 -70.963536)
		(mid 140.898243 -71.106272)
		(end 141.089888 -71.163434)
		(width 0.089408)
		(layer "In11.Cu")
		(net "PU_CPU1_TSC_SYNC")
	)
	(arc
		(start 139.041124 -69.972682)
		(mid 139.182807 -70.116486)
		(end 139.376658 -70.172834)
		(width 0.089408)
		(layer "In11.Cu")
		(net "PU_CPU1_TSC_SYNC")
	)
	(segment
		(start 413.384492 -23.876)
		(end 413.26816 -23.992332)
		(width 0.10795)
		(layer "F.Cu")
		(net "PD_ADCREXT")
	)
	(segment
		(start 412.877 -23.368508)
		(end 412.877 -22.9235)
		(width 0.10795)
		(layer "F.Cu")
		(net "PD_ADCREXT")
	)
	(segment
		(start 413.26816 -23.992332)
		(end 413.26816 -25.42032)
		(width 0.10795)
		(layer "F.Cu")
		(net "PD_ADCREXT")
	)
	(segment
		(start 413.384492 -23.876)
		(end 412.877 -23.368508)
		(width 0.10795)
		(layer "F.Cu")
		(net "PD_ADCREXT")
	)
	(segment
		(start 413.26816 -25.42032)
		(end 413.490156 -25.642316)
		(width 0.10795)
		(layer "F.Cu")
		(net "PD_ADCREXT")
	)
	(segment
		(start 413.490156 -25.642316)
		(end 413.490156 -26.534618)
		(width 0.10795)
		(layer "F.Cu")
		(net "PD_ADCREXT")
	)
	(via
		(at 413.384492 -23.876)
		(size 0.762)
		(drill 0.381)
		(layers "F.Cu" "B.Cu")
		(net "PD_ADCREXT")
	)
	(segment
		(start 409.490164 -28.934664)
		(end 409.090114 -28.534614)
		(width 0.10795)
		(layer "F.Cu")
		(net "TP_RGMII2TXD3_GPIOU3")
	)
	(via
		(at 409.090114 -28.534614)
		(size 0.4572)
		(drill 0.2032)
		(layers "F.Cu" "B.Cu")
		(net "TP_RGMII2TXD3_GPIOU3")
	)
	(segment
		(start 408.051 -27.94)
		(end 408.28722 -27.94)
		(width 0.10795)
		(layer "B.Cu")
		(net "TP_RGMII2TXD3_GPIOU3")
	)
	(segment
		(start 408.28722 -27.94)
		(end 408.881834 -28.534614)
		(width 0.10795)
		(layer "B.Cu")
		(net "TP_RGMII2TXD3_GPIOU3")
	)
	(segment
		(start 408.881834 -28.534614)
		(end 409.090114 -28.534614)
		(width 0.10795)
		(layer "B.Cu")
		(net "TP_RGMII2TXD3_GPIOU3")
	)
	(segment
		(start 426.519594 -19.345402)
		(end 426.272198 -19.098006)
		(width 0.10795)
		(layer "F.Cu")
		(net "FM_MB_SLOT_ID2")
	)
	(segment
		(start 384.62331 -90.307668)
		(end 384.379724 -90.551254)
		(width 0.0889)
		(layer "F.Cu")
		(net "FM_MB_SLOT_ID2")
	)
	(segment
		(start 427.656752 -19.345402)
		(end 426.519594 -19.345402)
		(width 0.10795)
		(layer "F.Cu")
		(net "FM_MB_SLOT_ID2")
	)
	(segment
		(start 384.411474 -92.755212)
		(end 384.699256 -93.042994)
		(width 0.0889)
		(layer "F.Cu")
		(net "FM_MB_SLOT_ID2")
	)
	(segment
		(start 384.485134 -94.789752)
		(end 384.48488 -94.790006)
		(width 0.0889)
		(layer "F.Cu")
		(net "FM_MB_SLOT_ID2")
	)
	(segment
		(start 384.699256 -93.733874)
		(end 384.807968 -93.842586)
		(width 0.0889)
		(layer "F.Cu")
		(net "FM_MB_SLOT_ID2")
	)
	(segment
		(start 384.379724 -91.525852)
		(end 384.411474 -91.557602)
		(width 0.0889)
		(layer "F.Cu")
		(net "FM_MB_SLOT_ID2")
	)
	(segment
		(start 384.379724 -90.551254)
		(end 384.379724 -91.525852)
		(width 0.0889)
		(layer "F.Cu")
		(net "FM_MB_SLOT_ID2")
	)
	(segment
		(start 384.807968 -93.842586)
		(end 384.807968 -94.104968)
		(width 0.0889)
		(layer "F.Cu")
		(net "FM_MB_SLOT_ID2")
	)
	(segment
		(start 384.485134 -94.427802)
		(end 384.485134 -94.789752)
		(width 0.0889)
		(layer "F.Cu")
		(net "FM_MB_SLOT_ID2")
	)
	(segment
		(start 384.699256 -93.042994)
		(end 384.699256 -93.733874)
		(width 0.0889)
		(layer "F.Cu")
		(net "FM_MB_SLOT_ID2")
	)
	(segment
		(start 426.272198 -18.822162)
		(end 425.987718 -18.537682)
		(width 0.10795)
		(layer "F.Cu")
		(net "FM_MB_SLOT_ID2")
	)
	(segment
		(start 425.1452 -19.030188)
		(end 425.1452 -19.1008)
		(width 0.10795)
		(layer "F.Cu")
		(net "FM_MB_SLOT_ID2")
	)
	(segment
		(start 425.637706 -18.537682)
		(end 425.1452 -19.030188)
		(width 0.10795)
		(layer "F.Cu")
		(net "FM_MB_SLOT_ID2")
	)
	(segment
		(start 384.411474 -91.557602)
		(end 384.411474 -92.755212)
		(width 0.0889)
		(layer "F.Cu")
		(net "FM_MB_SLOT_ID2")
	)
	(segment
		(start 428.56912 -18.433034)
		(end 427.656752 -19.345402)
		(width 0.10795)
		(layer "F.Cu")
		(net "FM_MB_SLOT_ID2")
	)
	(segment
		(start 428.56912 -17.4244)
		(end 428.56912 -18.433034)
		(width 0.10795)
		(layer "F.Cu")
		(net "FM_MB_SLOT_ID2")
	)
	(segment
		(start 384.807968 -94.104968)
		(end 384.485134 -94.427802)
		(width 0.0889)
		(layer "F.Cu")
		(net "FM_MB_SLOT_ID2")
	)
	(segment
		(start 426.272198 -19.098006)
		(end 426.272198 -18.822162)
		(width 0.10795)
		(layer "F.Cu")
		(net "FM_MB_SLOT_ID2")
	)
	(segment
		(start 425.987718 -18.537682)
		(end 425.637706 -18.537682)
		(width 0.10795)
		(layer "F.Cu")
		(net "FM_MB_SLOT_ID2")
	)
	(via
		(at 412.76905 -20.366228)
		(size 0.508)
		(drill 0.254)
		(layers "F.Cu" "B.Cu")
		(net "FM_MB_SLOT_ID2")
	)
	(via
		(at 16.551656 4.941824)
		(size 0.508)
		(drill 0.254)
		(layers "F.Cu" "B.Cu")
		(net "FM_MB_SLOT_ID2")
	)
	(via
		(at 470.240614 -27.014932)
		(size 0.508)
		(drill 0.254)
		(layers "F.Cu" "B.Cu")
		(net "FM_MB_SLOT_ID2")
	)
	(via
		(at 472.69781 -33.22701)
		(size 0.508)
		(drill 0.254)
		(layers "F.Cu" "B.Cu")
		(net "FM_MB_SLOT_ID2")
	)
	(via
		(at 384.62331 -90.307668)
		(size 0.508)
		(drill 0.254)
		(layers "F.Cu" "B.Cu")
		(net "FM_MB_SLOT_ID2")
	)
	(via
		(at 407.671016 4.405884)
		(size 0.508)
		(drill 0.254)
		(layers "F.Cu" "B.Cu")
		(net "FM_MB_SLOT_ID2")
	)
	(via
		(at 481.83038 -18.65884)
		(size 0.508)
		(drill 0.254)
		(layers "F.Cu" "B.Cu")
		(net "FM_MB_SLOT_ID2")
	)
	(via
		(at 425.1452 -19.1008)
		(size 0.508)
		(drill 0.254)
		(layers "F.Cu" "B.Cu")
		(net "FM_MB_SLOT_ID2")
	)
	(via
		(at 472.4654 -28.321)
		(size 0.6604)
		(drill 0.3302)
		(layers "F.Cu" "B.Cu")
		(net "FM_MB_SLOT_ID2")
	)
	(via
		(at 404.683214 -34.11093)
		(size 0.508)
		(drill 0.254)
		(layers "F.Cu" "B.Cu")
		(net "FM_MB_SLOT_ID2")
	)
	(segment
		(start 385.856226 -89.089738)
		(end 385.856226 -88.735154)
		(width 0.10795)
		(layer "B.Cu")
		(net "FM_MB_SLOT_ID2")
	)
	(segment
		(start 470.240614 -27.014932)
		(end 471.768932 -27.014932)
		(width 0.10795)
		(layer "B.Cu")
		(net "FM_MB_SLOT_ID2")
	)
	(segment
		(start 385.325112 -89.620852)
		(end 385.856226 -89.089738)
		(width 0.10795)
		(layer "B.Cu")
		(net "FM_MB_SLOT_ID2")
	)
	(segment
		(start 472.4654 -27.7114)
		(end 472.4654 -28.321)
		(width 0.10795)
		(layer "B.Cu")
		(net "FM_MB_SLOT_ID2")
	)
	(segment
		(start 385.325112 -90.199718)
		(end 385.325112 -89.620852)
		(width 0.10795)
		(layer "B.Cu")
		(net "FM_MB_SLOT_ID2")
	)
	(segment
		(start 472.4654 -32.9946)
		(end 472.4654 -28.321)
		(width 0.10795)
		(layer "B.Cu")
		(net "FM_MB_SLOT_ID2")
	)
	(segment
		(start 472.69781 -33.22701)
		(end 472.4654 -32.9946)
		(width 0.10795)
		(layer "B.Cu")
		(net "FM_MB_SLOT_ID2")
	)
	(segment
		(start 385.217162 -90.307668)
		(end 385.325112 -90.199718)
		(width 0.10795)
		(layer "B.Cu")
		(net "FM_MB_SLOT_ID2")
	)
	(segment
		(start 471.768932 -27.014932)
		(end 472.4654 -27.7114)
		(width 0.10795)
		(layer "B.Cu")
		(net "FM_MB_SLOT_ID2")
	)
	(segment
		(start 385.856226 -88.735154)
		(end 385.318 -88.196928)
		(width 0.10795)
		(layer "B.Cu")
		(net "FM_MB_SLOT_ID2")
	)
	(segment
		(start 384.62331 -90.307668)
		(end 385.217162 -90.307668)
		(width 0.10795)
		(layer "B.Cu")
		(net "FM_MB_SLOT_ID2")
	)
	(segment
		(start 385.318 -88.196928)
		(end 385.318 -88.0491)
		(width 0.10795)
		(layer "B.Cu")
		(net "FM_MB_SLOT_ID2")
	)
	(segment
		(start 390.222486 -42.167048)
		(end 391.037826 -41.351708)
		(width 0.089408)
		(layer "In2.Cu")
		(net "FM_MB_SLOT_ID2")
	)
	(segment
		(start 389.594598 -61.684662)
		(end 388.595616 -60.68568)
		(width 0.089408)
		(layer "In2.Cu")
		(net "FM_MB_SLOT_ID2")
	)
	(segment
		(start 488.105196 -33.362646)
		(end 488.876594 -34.134044)
		(width 0.089408)
		(layer "In2.Cu")
		(net "FM_MB_SLOT_ID2")
	)
	(segment
		(start 488.103926 -33.31972)
		(end 488.105196 -33.32099)
		(width 0.089408)
		(layer "In2.Cu")
		(net "FM_MB_SLOT_ID2")
	)
	(segment
		(start 483.006654 -34.626804)
		(end 484.192834 -34.626804)
		(width 0.089408)
		(layer "In2.Cu")
		(net "FM_MB_SLOT_ID2")
	)
	(segment
		(start 387.605016 -64.600328)
		(end 388.10819 -64.600328)
		(width 0.089408)
		(layer "In2.Cu")
		(net "FM_MB_SLOT_ID2")
	)
	(segment
		(start 482.851206 -18.65884)
		(end 481.83038 -18.65884)
		(width 0.089408)
		(layer "In2.Cu")
		(net "FM_MB_SLOT_ID2")
	)
	(segment
		(start 490.3978 -34.134044)
		(end 490.973872 -33.557972)
		(width 0.089408)
		(layer "In2.Cu")
		(net "FM_MB_SLOT_ID2")
	)
	(segment
		(start 484.788972 -35.222942)
		(end 485.926384 -35.222942)
		(width 0.089408)
		(layer "In2.Cu")
		(net "FM_MB_SLOT_ID2")
	)
	(segment
		(start 386.29082 -77.834998)
		(end 386.576316 -77.549502)
		(width 0.089408)
		(layer "In2.Cu")
		(net "FM_MB_SLOT_ID2")
	)
	(segment
		(start 489.867448 -25.864312)
		(end 489.867448 -22.956774)
		(width 0.089408)
		(layer "In2.Cu")
		(net "FM_MB_SLOT_ID2")
	)
	(segment
		(start 488.876594 -34.134044)
		(end 490.3978 -34.134044)
		(width 0.089408)
		(layer "In2.Cu")
		(net "FM_MB_SLOT_ID2")
	)
	(segment
		(start 491.640368 -27.637232)
		(end 489.867448 -25.864312)
		(width 0.089408)
		(layer "In2.Cu")
		(net "FM_MB_SLOT_ID2")
	)
	(segment
		(start 384.435604 -89.609168)
		(end 384.435604 -86.792308)
		(width 0.089408)
		(layer "In2.Cu")
		(net "FM_MB_SLOT_ID2")
	)
	(segment
		(start 483.078282 -18.431764)
		(end 482.851206 -18.65884)
		(width 0.089408)
		(layer "In2.Cu")
		(net "FM_MB_SLOT_ID2")
	)
	(segment
		(start 402.120862 -34.011616)
		(end 402.315426 -33.817052)
		(width 0.089408)
		(layer "In2.Cu")
		(net "FM_MB_SLOT_ID2")
	)
	(segment
		(start 387.119622 -54.059328)
		(end 387.119622 -42.730674)
		(width 0.089408)
		(layer "In2.Cu")
		(net "FM_MB_SLOT_ID2")
	)
	(segment
		(start 487.229404 -31.544768)
		(end 487.83875 -31.544768)
		(width 0.089408)
		(layer "In2.Cu")
		(net "FM_MB_SLOT_ID2")
	)
	(segment
		(start 388.595616 -60.68568)
		(end 388.595616 -59.53379)
		(width 0.089408)
		(layer "In2.Cu")
		(net "FM_MB_SLOT_ID2")
	)
	(segment
		(start 473.842588 -33.22701)
		(end 473.975938 -33.36036)
		(width 0.089408)
		(layer "In2.Cu")
		(net "FM_MB_SLOT_ID2")
	)
	(segment
		(start 387.683248 -42.167048)
		(end 390.222486 -42.167048)
		(width 0.089408)
		(layer "In2.Cu")
		(net "FM_MB_SLOT_ID2")
	)
	(segment
		(start 384.435604 -86.792308)
		(end 386.969 -84.258912)
		(width 0.089408)
		(layer "In2.Cu")
		(net "FM_MB_SLOT_ID2")
	)
	(segment
		(start 484.192834 -34.626804)
		(end 484.788972 -35.222942)
		(width 0.089408)
		(layer "In2.Cu")
		(net "FM_MB_SLOT_ID2")
	)
	(segment
		(start 386.576316 -71.644002)
		(end 387.064504 -71.155814)
		(width 0.089408)
		(layer "In2.Cu")
		(net "FM_MB_SLOT_ID2")
	)
	(segment
		(start 488.105196 -33.32099)
		(end 488.105196 -33.362646)
		(width 0.089408)
		(layer "In2.Cu")
		(net "FM_MB_SLOT_ID2")
	)
	(segment
		(start 485.342438 -18.431764)
		(end 483.078282 -18.431764)
		(width 0.089408)
		(layer "In2.Cu")
		(net "FM_MB_SLOT_ID2")
	)
	(segment
		(start 391.790936 -37.453316)
		(end 391.81278 -37.47516)
		(width 0.089408)
		(layer "In2.Cu")
		(net "FM_MB_SLOT_ID2")
	)
	(segment
		(start 386.969 -84.258912)
		(end 386.969 -83.86318)
		(width 0.089408)
		(layer "In2.Cu")
		(net "FM_MB_SLOT_ID2")
	)
	(segment
		(start 487.83875 -31.544768)
		(end 488.103926 -31.809944)
		(width 0.089408)
		(layer "In2.Cu")
		(net "FM_MB_SLOT_ID2")
	)
	(segment
		(start 397.994378 -33.461452)
		(end 398.644364 -33.461452)
		(width 0.089408)
		(layer "In2.Cu")
		(net "FM_MB_SLOT_ID2")
	)
	(segment
		(start 384.62331 -89.796874)
		(end 384.435604 -89.609168)
		(width 0.089408)
		(layer "In2.Cu")
		(net "FM_MB_SLOT_ID2")
	)
	(segment
		(start 485.926384 -35.222942)
		(end 486.378504 -34.770822)
		(width 0.089408)
		(layer "In2.Cu")
		(net "FM_MB_SLOT_ID2")
	)
	(segment
		(start 482.170232 -33.36036)
		(end 482.735636 -33.925764)
		(width 0.089408)
		(layer "In2.Cu")
		(net "FM_MB_SLOT_ID2")
	)
	(segment
		(start 391.437368 -37.47516)
		(end 391.459212 -37.453316)
		(width 0.089408)
		(layer "In2.Cu")
		(net "FM_MB_SLOT_ID2")
	)
	(segment
		(start 473.975938 -33.36036)
		(end 482.170232 -33.36036)
		(width 0.089408)
		(layer "In2.Cu")
		(net "FM_MB_SLOT_ID2")
	)
	(segment
		(start 397.749776 -33.706054)
		(end 397.994378 -33.461452)
		(width 0.089408)
		(layer "In2.Cu")
		(net "FM_MB_SLOT_ID2")
	)
	(segment
		(start 391.459212 -37.453316)
		(end 391.790936 -37.453316)
		(width 0.089408)
		(layer "In2.Cu")
		(net "FM_MB_SLOT_ID2")
	)
	(segment
		(start 389.594598 -63.11392)
		(end 389.594598 -61.684662)
		(width 0.089408)
		(layer "In2.Cu")
		(net "FM_MB_SLOT_ID2")
	)
	(segment
		(start 386.487162 -54.691788)
		(end 387.119622 -54.059328)
		(width 0.089408)
		(layer "In2.Cu")
		(net "FM_MB_SLOT_ID2")
	)
	(segment
		(start 491.640368 -30.618938)
		(end 491.640368 -27.637232)
		(width 0.089408)
		(layer "In2.Cu")
		(net "FM_MB_SLOT_ID2")
	)
	(segment
		(start 388.59587 -59.533536)
		(end 388.59587 -58.923174)
		(width 0.089408)
		(layer "In2.Cu")
		(net "FM_MB_SLOT_ID2")
	)
	(segment
		(start 387.119622 -42.730674)
		(end 387.683248 -42.167048)
		(width 0.089408)
		(layer "In2.Cu")
		(net "FM_MB_SLOT_ID2")
	)
	(segment
		(start 388.59587 -58.923174)
		(end 387.956044 -58.283348)
		(width 0.089408)
		(layer "In2.Cu")
		(net "FM_MB_SLOT_ID2")
	)
	(segment
		(start 397.749776 -34.037778)
		(end 397.749776 -33.706054)
		(width 0.089408)
		(layer "In2.Cu")
		(net "FM_MB_SLOT_ID2")
	)
	(segment
		(start 486.378504 -32.395668)
		(end 487.229404 -31.544768)
		(width 0.089408)
		(layer "In2.Cu")
		(net "FM_MB_SLOT_ID2")
	)
	(segment
		(start 386.487162 -56.130952)
		(end 386.487162 -54.691788)
		(width 0.089408)
		(layer "In2.Cu")
		(net "FM_MB_SLOT_ID2")
	)
	(segment
		(start 397.756888 -36.141152)
		(end 397.756888 -34.04489)
		(width 0.089408)
		(layer "In2.Cu")
		(net "FM_MB_SLOT_ID2")
	)
	(segment
		(start 387.00964 -70.563994)
		(end 387.00964 -65.195704)
		(width 0.089408)
		(layer "In2.Cu")
		(net "FM_MB_SLOT_ID2")
	)
	(segment
		(start 391.81278 -37.47516)
		(end 396.42288 -37.47516)
		(width 0.089408)
		(layer "In2.Cu")
		(net "FM_MB_SLOT_ID2")
	)
	(segment
		(start 391.037826 -41.351708)
		(end 391.037826 -37.785294)
		(width 0.089408)
		(layer "In2.Cu")
		(net "FM_MB_SLOT_ID2")
	)
	(segment
		(start 404.389336 -33.817052)
		(end 404.683214 -34.11093)
		(width 0.089408)
		(layer "In2.Cu")
		(net "FM_MB_SLOT_ID2")
	)
	(segment
		(start 387.956044 -57.599834)
		(end 386.487162 -56.130952)
		(width 0.089408)
		(layer "In2.Cu")
		(net "FM_MB_SLOT_ID2")
	)
	(segment
		(start 391.34796 -37.47516)
		(end 391.437368 -37.47516)
		(width 0.089408)
		(layer "In2.Cu")
		(net "FM_MB_SLOT_ID2")
	)
	(segment
		(start 490.973872 -31.285434)
		(end 491.640368 -30.618938)
		(width 0.089408)
		(layer "In2.Cu")
		(net "FM_MB_SLOT_ID2")
	)
	(segment
		(start 391.037826 -37.785294)
		(end 391.34796 -37.47516)
		(width 0.089408)
		(layer "In2.Cu")
		(net "FM_MB_SLOT_ID2")
	)
	(segment
		(start 402.315426 -33.817052)
		(end 404.389336 -33.817052)
		(width 0.089408)
		(layer "In2.Cu")
		(net "FM_MB_SLOT_ID2")
	)
	(segment
		(start 472.69781 -33.22701)
		(end 473.842588 -33.22701)
		(width 0.089408)
		(layer "In2.Cu")
		(net "FM_MB_SLOT_ID2")
	)
	(segment
		(start 386.969 -83.86318)
		(end 386.29082 -83.185)
		(width 0.089408)
		(layer "In2.Cu")
		(net "FM_MB_SLOT_ID2")
	)
	(segment
		(start 488.103926 -31.809944)
		(end 488.103926 -33.31972)
		(width 0.089408)
		(layer "In2.Cu")
		(net "FM_MB_SLOT_ID2")
	)
	(segment
		(start 397.756888 -34.04489)
		(end 397.749776 -34.037778)
		(width 0.089408)
		(layer "In2.Cu")
		(net "FM_MB_SLOT_ID2")
	)
	(segment
		(start 388.595616 -59.53379)
		(end 388.59587 -59.533536)
		(width 0.089408)
		(layer "In2.Cu")
		(net "FM_MB_SLOT_ID2")
	)
	(segment
		(start 482.735636 -33.925764)
		(end 482.735636 -34.355786)
		(width 0.089408)
		(layer "In2.Cu")
		(net "FM_MB_SLOT_ID2")
	)
	(segment
		(start 387.064504 -71.155814)
		(end 387.064504 -70.618858)
		(width 0.089408)
		(layer "In2.Cu")
		(net "FM_MB_SLOT_ID2")
	)
	(segment
		(start 399.194528 -34.011616)
		(end 402.120862 -34.011616)
		(width 0.089408)
		(layer "In2.Cu")
		(net "FM_MB_SLOT_ID2")
	)
	(segment
		(start 386.29082 -83.185)
		(end 386.29082 -77.834998)
		(width 0.089408)
		(layer "In2.Cu")
		(net "FM_MB_SLOT_ID2")
	)
	(segment
		(start 398.644364 -33.461452)
		(end 399.194528 -34.011616)
		(width 0.089408)
		(layer "In2.Cu")
		(net "FM_MB_SLOT_ID2")
	)
	(segment
		(start 387.00964 -65.195704)
		(end 387.605016 -64.600328)
		(width 0.089408)
		(layer "In2.Cu")
		(net "FM_MB_SLOT_ID2")
	)
	(segment
		(start 386.576316 -77.549502)
		(end 386.576316 -71.644002)
		(width 0.089408)
		(layer "In2.Cu")
		(net "FM_MB_SLOT_ID2")
	)
	(segment
		(start 384.62331 -90.307668)
		(end 384.62331 -89.796874)
		(width 0.089408)
		(layer "In2.Cu")
		(net "FM_MB_SLOT_ID2")
	)
	(segment
		(start 387.956044 -58.283348)
		(end 387.956044 -57.599834)
		(width 0.089408)
		(layer "In2.Cu")
		(net "FM_MB_SLOT_ID2")
	)
	(segment
		(start 489.867448 -22.956774)
		(end 485.342438 -18.431764)
		(width 0.089408)
		(layer "In2.Cu")
		(net "FM_MB_SLOT_ID2")
	)
	(segment
		(start 387.064504 -70.618858)
		(end 387.00964 -70.563994)
		(width 0.089408)
		(layer "In2.Cu")
		(net "FM_MB_SLOT_ID2")
	)
	(segment
		(start 486.378504 -34.770822)
		(end 486.378504 -32.395668)
		(width 0.089408)
		(layer "In2.Cu")
		(net "FM_MB_SLOT_ID2")
	)
	(segment
		(start 482.735636 -34.355786)
		(end 483.006654 -34.626804)
		(width 0.089408)
		(layer "In2.Cu")
		(net "FM_MB_SLOT_ID2")
	)
	(segment
		(start 396.42288 -37.47516)
		(end 397.756888 -36.141152)
		(width 0.089408)
		(layer "In2.Cu")
		(net "FM_MB_SLOT_ID2")
	)
	(segment
		(start 490.973872 -33.557972)
		(end 490.973872 -31.285434)
		(width 0.089408)
		(layer "In2.Cu")
		(net "FM_MB_SLOT_ID2")
	)
	(segment
		(start 388.10819 -64.600328)
		(end 389.594598 -63.11392)
		(width 0.089408)
		(layer "In2.Cu")
		(net "FM_MB_SLOT_ID2")
	)
	(segment
		(start 466.532214 -8.4582)
		(end 465.998814 -8.9916)
		(width 0.089408)
		(layer "In4.Cu")
		(net "FM_MB_SLOT_ID2")
	)
	(segment
		(start 427.614588 -16.826992)
		(end 426.751496 -17.690084)
		(width 0.089408)
		(layer "In4.Cu")
		(net "FM_MB_SLOT_ID2")
	)
	(segment
		(start 470.240614 -27.014932)
		(end 470.151714 -26.926032)
		(width 0.089408)
		(layer "In4.Cu")
		(net "FM_MB_SLOT_ID2")
	)
	(segment
		(start 448.68084 -16.039592)
		(end 445.360552 -16.039592)
		(width 0.089408)
		(layer "In4.Cu")
		(net "FM_MB_SLOT_ID2")
	)
	(segment
		(start 468.2236 -8.89)
		(end 467.7918 -8.4582)
		(width 0.089408)
		(layer "In4.Cu")
		(net "FM_MB_SLOT_ID2")
	)
	(segment
		(start 456.020678 -21.911056)
		(end 454.854056 -20.744434)
		(width 0.089408)
		(layer "In4.Cu")
		(net "FM_MB_SLOT_ID2")
	)
	(segment
		(start 463.216244 -23.424388)
		(end 460.886048 -21.094192)
		(width 0.089408)
		(layer "In4.Cu")
		(net "FM_MB_SLOT_ID2")
	)
	(segment
		(start 450.233288 -18.201894)
		(end 450.233288 -17.59204)
		(width 0.089408)
		(layer "In4.Cu")
		(net "FM_MB_SLOT_ID2")
	)
	(segment
		(start 450.233288 -17.59204)
		(end 448.68084 -16.039592)
		(width 0.089408)
		(layer "In4.Cu")
		(net "FM_MB_SLOT_ID2")
	)
	(segment
		(start 426.6946 2.8194)
		(end 423.0116 2.8194)
		(width 0.089408)
		(layer "In4.Cu")
		(net "FM_MB_SLOT_ID2")
	)
	(segment
		(start 418.325554 -19.449796)
		(end 418.67455 -19.1008)
		(width 0.089408)
		(layer "In4.Cu")
		(net "FM_MB_SLOT_ID2")
	)
	(segment
		(start 464.500976 1.227328)
		(end 462.902808 2.825496)
		(width 0.089408)
		(layer "In4.Cu")
		(net "FM_MB_SLOT_ID2")
	)
	(segment
		(start 444.573152 -16.826992)
		(end 427.614588 -16.826992)
		(width 0.089408)
		(layer "In4.Cu")
		(net "FM_MB_SLOT_ID2")
	)
	(segment
		(start 465.252308 -0.590804)
		(end 464.500976 0.160528)
		(width 0.089408)
		(layer "In4.Cu")
		(net "FM_MB_SLOT_ID2")
	)
	(segment
		(start 426.700696 2.825496)
		(end 426.6946 2.8194)
		(width 0.089408)
		(layer "In4.Cu")
		(net "FM_MB_SLOT_ID2")
	)
	(segment
		(start 464.500976 0.160528)
		(end 464.500976 1.227328)
		(width 0.089408)
		(layer "In4.Cu")
		(net "FM_MB_SLOT_ID2")
	)
	(segment
		(start 418.67455 -19.1008)
		(end 425.1452 -19.1008)
		(width 0.089408)
		(layer "In4.Cu")
		(net "FM_MB_SLOT_ID2")
	)
	(segment
		(start 481.83038 -19.504406)
		(end 481.692204 -19.642582)
		(width 0.089408)
		(layer "In4.Cu")
		(net "FM_MB_SLOT_ID2")
	)
	(segment
		(start 454.854056 -20.744434)
		(end 452.775828 -20.744434)
		(width 0.089408)
		(layer "In4.Cu")
		(net "FM_MB_SLOT_ID2")
	)
	(segment
		(start 465.998814 -8.9916)
		(end 464.4898 -8.9916)
		(width 0.089408)
		(layer "In4.Cu")
		(net "FM_MB_SLOT_ID2")
	)
	(segment
		(start 465.252308 -1.745742)
		(end 465.252308 -0.590804)
		(width 0.089408)
		(layer "In4.Cu")
		(net "FM_MB_SLOT_ID2")
	)
	(segment
		(start 477.031812 -17.384268)
		(end 471.815668 -12.168124)
		(width 0.089408)
		(layer "In4.Cu")
		(net "FM_MB_SLOT_ID2")
	)
	(segment
		(start 481.692204 -19.642582)
		(end 481.092764 -19.642582)
		(width 0.089408)
		(layer "In4.Cu")
		(net "FM_MB_SLOT_ID2")
	)
	(segment
		(start 467.7918 -8.4582)
		(end 466.532214 -8.4582)
		(width 0.089408)
		(layer "In4.Cu")
		(net "FM_MB_SLOT_ID2")
	)
	(segment
		(start 409.4226 3.9878)
		(end 408.0891 3.9878)
		(width 0.089408)
		(layer "In4.Cu")
		(net "FM_MB_SLOT_ID2")
	)
	(segment
		(start 464.2866 -5.7912)
		(end 464.2866 -5.250434)
		(width 0.089408)
		(layer "In4.Cu")
		(net "FM_MB_SLOT_ID2")
	)
	(segment
		(start 412.76905 -20.300188)
		(end 413.619442 -19.449796)
		(width 0.089408)
		(layer "In4.Cu")
		(net "FM_MB_SLOT_ID2")
	)
	(segment
		(start 458.543152 -21.094192)
		(end 457.726288 -21.911056)
		(width 0.089408)
		(layer "In4.Cu")
		(net "FM_MB_SLOT_ID2")
	)
	(segment
		(start 465.956904 -3.58013)
		(end 465.956904 -2.450338)
		(width 0.089408)
		(layer "In4.Cu")
		(net "FM_MB_SLOT_ID2")
	)
	(segment
		(start 463.2579 -7.7597)
		(end 463.2579 -6.8199)
		(width 0.089408)
		(layer "In4.Cu")
		(net "FM_MB_SLOT_ID2")
	)
	(segment
		(start 413.619442 -19.449796)
		(end 418.325554 -19.449796)
		(width 0.089408)
		(layer "In4.Cu")
		(net "FM_MB_SLOT_ID2")
	)
	(segment
		(start 465.956904 -2.450338)
		(end 465.252308 -1.745742)
		(width 0.089408)
		(layer "In4.Cu")
		(net "FM_MB_SLOT_ID2")
	)
	(segment
		(start 457.726288 -21.911056)
		(end 456.020678 -21.911056)
		(width 0.089408)
		(layer "In4.Cu")
		(net "FM_MB_SLOT_ID2")
	)
	(segment
		(start 460.886048 -21.094192)
		(end 458.543152 -21.094192)
		(width 0.089408)
		(layer "In4.Cu")
		(net "FM_MB_SLOT_ID2")
	)
	(segment
		(start 421.1574 4.6736)
		(end 410.1084 4.6736)
		(width 0.089408)
		(layer "In4.Cu")
		(net "FM_MB_SLOT_ID2")
	)
	(segment
		(start 471.815668 -12.168124)
		(end 470.724738 -12.168124)
		(width 0.089408)
		(layer "In4.Cu")
		(net "FM_MB_SLOT_ID2")
	)
	(segment
		(start 481.092764 -19.642582)
		(end 480.345496 -18.895314)
		(width 0.089408)
		(layer "In4.Cu")
		(net "FM_MB_SLOT_ID2")
	)
	(segment
		(start 462.902808 2.825496)
		(end 426.700696 2.825496)
		(width 0.089408)
		(layer "In4.Cu")
		(net "FM_MB_SLOT_ID2")
	)
	(segment
		(start 464.2866 -5.250434)
		(end 465.956904 -3.58013)
		(width 0.089408)
		(layer "In4.Cu")
		(net "FM_MB_SLOT_ID2")
	)
	(segment
		(start 408.0891 3.9878)
		(end 407.671016 4.405884)
		(width 0.089408)
		(layer "In4.Cu")
		(net "FM_MB_SLOT_ID2")
	)
	(segment
		(start 410.1084 4.6736)
		(end 409.4226 3.9878)
		(width 0.089408)
		(layer "In4.Cu")
		(net "FM_MB_SLOT_ID2")
	)
	(segment
		(start 452.775828 -20.744434)
		(end 450.233288 -18.201894)
		(width 0.089408)
		(layer "In4.Cu")
		(net "FM_MB_SLOT_ID2")
	)
	(segment
		(start 426.751496 -17.690084)
		(end 426.403516 -17.690084)
		(width 0.089408)
		(layer "In4.Cu")
		(net "FM_MB_SLOT_ID2")
	)
	(segment
		(start 480.345496 -18.895314)
		(end 479.407982 -18.895314)
		(width 0.089408)
		(layer "In4.Cu")
		(net "FM_MB_SLOT_ID2")
	)
	(segment
		(start 470.724738 -12.168124)
		(end 468.2236 -9.666986)
		(width 0.089408)
		(layer "In4.Cu")
		(net "FM_MB_SLOT_ID2")
	)
	(segment
		(start 481.83038 -18.65884)
		(end 481.83038 -19.504406)
		(width 0.089408)
		(layer "In4.Cu")
		(net "FM_MB_SLOT_ID2")
	)
	(segment
		(start 470.151714 -26.926032)
		(end 468.064088 -26.926032)
		(width 0.089408)
		(layer "In4.Cu")
		(net "FM_MB_SLOT_ID2")
	)
	(segment
		(start 425.1452 -18.9484)
		(end 425.1452 -19.1008)
		(width 0.089408)
		(layer "In4.Cu")
		(net "FM_MB_SLOT_ID2")
	)
	(segment
		(start 464.4898 -8.9916)
		(end 463.2579 -7.7597)
		(width 0.089408)
		(layer "In4.Cu")
		(net "FM_MB_SLOT_ID2")
	)
	(segment
		(start 479.407982 -18.895314)
		(end 477.896936 -17.384268)
		(width 0.089408)
		(layer "In4.Cu")
		(net "FM_MB_SLOT_ID2")
	)
	(segment
		(start 468.064088 -26.926032)
		(end 464.562444 -23.424388)
		(width 0.089408)
		(layer "In4.Cu")
		(net "FM_MB_SLOT_ID2")
	)
	(segment
		(start 477.896936 -17.384268)
		(end 477.031812 -17.384268)
		(width 0.089408)
		(layer "In4.Cu")
		(net "FM_MB_SLOT_ID2")
	)
	(segment
		(start 445.360552 -16.039592)
		(end 444.573152 -16.826992)
		(width 0.089408)
		(layer "In4.Cu")
		(net "FM_MB_SLOT_ID2")
	)
	(segment
		(start 468.2236 -9.666986)
		(end 468.2236 -8.89)
		(width 0.089408)
		(layer "In4.Cu")
		(net "FM_MB_SLOT_ID2")
	)
	(segment
		(start 463.2579 -6.8199)
		(end 464.2866 -5.7912)
		(width 0.089408)
		(layer "In4.Cu")
		(net "FM_MB_SLOT_ID2")
	)
	(segment
		(start 412.76905 -20.366228)
		(end 412.76905 -20.300188)
		(width 0.089408)
		(layer "In4.Cu")
		(net "FM_MB_SLOT_ID2")
	)
	(segment
		(start 464.562444 -23.424388)
		(end 463.216244 -23.424388)
		(width 0.089408)
		(layer "In4.Cu")
		(net "FM_MB_SLOT_ID2")
	)
	(segment
		(start 426.403516 -17.690084)
		(end 425.1452 -18.9484)
		(width 0.089408)
		(layer "In4.Cu")
		(net "FM_MB_SLOT_ID2")
	)
	(segment
		(start 423.0116 2.8194)
		(end 421.1574 4.6736)
		(width 0.089408)
		(layer "In4.Cu")
		(net "FM_MB_SLOT_ID2")
	)
	(segment
		(start 322.379086 2.378202)
		(end 322.379086 2.891536)
		(width 0.089408)
		(layer "In9.Cu")
		(net "FM_MB_SLOT_ID2")
	)
	(segment
		(start 403.2504 3.689096)
		(end 401.30222 3.689096)
		(width 0.089408)
		(layer "In9.Cu")
		(net "FM_MB_SLOT_ID2")
	)
	(segment
		(start 23.42388 3.96748)
		(end 22.375368 5.015992)
		(width 0.089408)
		(layer "In9.Cu")
		(net "FM_MB_SLOT_ID2")
	)
	(segment
		(start 20.19173 5.292852)
		(end 17.874996 5.292852)
		(width 0.089408)
		(layer "In9.Cu")
		(net "FM_MB_SLOT_ID2")
	)
	(segment
		(start 348.6658 -18.748248)
		(end 347.525848 -17.608296)
		(width 0.089408)
		(layer "In9.Cu")
		(net "FM_MB_SLOT_ID2")
	)
	(segment
		(start 348.6658 -20.36953)
		(end 348.6658 -18.748248)
		(width 0.089408)
		(layer "In9.Cu")
		(net "FM_MB_SLOT_ID2")
	)
	(segment
		(start 186.937142 3.868928)
		(end 184.734708 1.666494)
		(width 0.089408)
		(layer "In9.Cu")
		(net "FM_MB_SLOT_ID2")
	)
	(segment
		(start 386.926836 2.744724)
		(end 381.014732 2.744724)
		(width 0.089408)
		(layer "In9.Cu")
		(net "FM_MB_SLOT_ID2")
	)
	(segment
		(start 360.299 -13.2588)
		(end 360.671364 -13.631164)
		(width 0.089408)
		(layer "In9.Cu")
		(net "FM_MB_SLOT_ID2")
	)
	(segment
		(start 407.671016 4.405884)
		(end 407.252932 3.9878)
		(width 0.089408)
		(layer "In9.Cu")
		(net "FM_MB_SLOT_ID2")
	)
	(segment
		(start 335.120996 -6.55828)
		(end 330.966826 -6.55828)
		(width 0.089408)
		(layer "In9.Cu")
		(net "FM_MB_SLOT_ID2")
	)
	(segment
		(start 325.966074 -1.208786)
		(end 322.379086 2.378202)
		(width 0.089408)
		(layer "In9.Cu")
		(net "FM_MB_SLOT_ID2")
	)
	(segment
		(start 363.23397 -7.462774)
		(end 363.23397 -9.440926)
		(width 0.089408)
		(layer "In9.Cu")
		(net "FM_MB_SLOT_ID2")
	)
	(segment
		(start 377.695968 -0.774446)
		(end 377.695968 -1.779778)
		(width 0.089408)
		(layer "In9.Cu")
		(net "FM_MB_SLOT_ID2")
	)
	(segment
		(start 181.716426 -2.997454)
		(end 178.913028 -2.997454)
		(width 0.089408)
		(layer "In9.Cu")
		(net "FM_MB_SLOT_ID2")
	)
	(segment
		(start 183.638952 -0.73152)
		(end 183.638952 -1.074928)
		(width 0.089408)
		(layer "In9.Cu")
		(net "FM_MB_SLOT_ID2")
	)
	(segment
		(start 386.92709 2.74447)
		(end 386.926836 2.744724)
		(width 0.089408)
		(layer "In9.Cu")
		(net "FM_MB_SLOT_ID2")
	)
	(segment
		(start 166.41064 2.935478)
		(end 165.06063 4.285488)
		(width 0.089408)
		(layer "In9.Cu")
		(net "FM_MB_SLOT_ID2")
	)
	(segment
		(start 184.734962 0.36449)
		(end 183.638952 -0.73152)
		(width 0.089408)
		(layer "In9.Cu")
		(net "FM_MB_SLOT_ID2")
	)
	(segment
		(start 392.876532 2.744216)
		(end 387.16966 2.744216)
		(width 0.089408)
		(layer "In9.Cu")
		(net "FM_MB_SLOT_ID2")
	)
	(segment
		(start 102.961186 5.015992)
		(end 25.210008 5.015992)
		(width 0.089408)
		(layer "In9.Cu")
		(net "FM_MB_SLOT_ID2")
	)
	(segment
		(start 347.525848 -14.437614)
		(end 346.354654 -13.26642)
		(width 0.089408)
		(layer "In9.Cu")
		(net "FM_MB_SLOT_ID2")
	)
	(segment
		(start 361.0864 -10.414)
		(end 360.299 -11.2014)
		(width 0.089408)
		(layer "In9.Cu")
		(net "FM_MB_SLOT_ID2")
	)
	(segment
		(start 407.252932 3.9878)
		(end 403.549104 3.9878)
		(width 0.089408)
		(layer "In9.Cu")
		(net "FM_MB_SLOT_ID2")
	)
	(segment
		(start 184.734962 1.508252)
		(end 184.734962 0.36449)
		(width 0.089408)
		(layer "In9.Cu")
		(net "FM_MB_SLOT_ID2")
	)
	(segment
		(start 363.23397 -9.440926)
		(end 362.260896 -10.414)
		(width 0.089408)
		(layer "In9.Cu")
		(net "FM_MB_SLOT_ID2")
	)
	(segment
		(start 17.425924 4.84378)
		(end 16.6497 4.84378)
		(width 0.089408)
		(layer "In9.Cu")
		(net "FM_MB_SLOT_ID2")
	)
	(segment
		(start 373.222774 -4.52501)
		(end 366.171734 -4.52501)
		(width 0.089408)
		(layer "In9.Cu")
		(net "FM_MB_SLOT_ID2")
	)
	(segment
		(start 168.342564 -2.97053)
		(end 166.41064 -1.038606)
		(width 0.089408)
		(layer "In9.Cu")
		(net "FM_MB_SLOT_ID2")
	)
	(segment
		(start 329.108562 -4.700016)
		(end 329.108562 -2.455926)
		(width 0.089408)
		(layer "In9.Cu")
		(net "FM_MB_SLOT_ID2")
	)
	(segment
		(start 380.919228 2.64922)
		(end 380.919228 1.748028)
		(width 0.089408)
		(layer "In9.Cu")
		(net "FM_MB_SLOT_ID2")
	)
	(segment
		(start 352.12655 -22.554946)
		(end 351.263458 -21.691854)
		(width 0.089408)
		(layer "In9.Cu")
		(net "FM_MB_SLOT_ID2")
	)
	(segment
		(start 184.734708 1.666494)
		(end 184.734708 1.508506)
		(width 0.089408)
		(layer "In9.Cu")
		(net "FM_MB_SLOT_ID2")
	)
	(segment
		(start 330.966826 -6.55828)
		(end 329.108562 -4.700016)
		(width 0.089408)
		(layer "In9.Cu")
		(net "FM_MB_SLOT_ID2")
	)
	(segment
		(start 17.874996 5.292852)
		(end 17.425924 4.84378)
		(width 0.089408)
		(layer "In9.Cu")
		(net "FM_MB_SLOT_ID2")
	)
	(segment
		(start 380.919228 1.748028)
		(end 378.763022 -0.408178)
		(width 0.089408)
		(layer "In9.Cu")
		(net "FM_MB_SLOT_ID2")
	)
	(segment
		(start 343.110058 -13.26642)
		(end 337.99653 -8.152892)
		(width 0.089408)
		(layer "In9.Cu")
		(net "FM_MB_SLOT_ID2")
	)
	(segment
		(start 356.208584 -22.076156)
		(end 356.077012 -22.207728)
		(width 0.089408)
		(layer "In9.Cu")
		(net "FM_MB_SLOT_ID2")
	)
	(segment
		(start 171.771564 -2.654808)
		(end 171.455842 -2.97053)
		(width 0.089408)
		(layer "In9.Cu")
		(net "FM_MB_SLOT_ID2")
	)
	(segment
		(start 399.937732 2.324608)
		(end 393.29614 2.324608)
		(width 0.089408)
		(layer "In9.Cu")
		(net "FM_MB_SLOT_ID2")
	)
	(segment
		(start 355.413056 -22.207728)
		(end 355.065838 -22.554946)
		(width 0.089408)
		(layer "In9.Cu")
		(net "FM_MB_SLOT_ID2")
	)
	(segment
		(start 378.062236 -0.408178)
		(end 377.695968 -0.774446)
		(width 0.089408)
		(layer "In9.Cu")
		(net "FM_MB_SLOT_ID2")
	)
	(segment
		(start 378.763022 -0.408178)
		(end 378.062236 -0.408178)
		(width 0.089408)
		(layer "In9.Cu")
		(net "FM_MB_SLOT_ID2")
	)
	(segment
		(start 387.011164 2.744724)
		(end 387.01091 2.74447)
		(width 0.089408)
		(layer "In9.Cu")
		(net "FM_MB_SLOT_ID2")
	)
	(segment
		(start 359.882694 -19.350482)
		(end 359.882694 -20.904454)
		(width 0.089408)
		(layer "In9.Cu")
		(net "FM_MB_SLOT_ID2")
	)
	(segment
		(start 346.354654 -13.26642)
		(end 343.110058 -13.26642)
		(width 0.089408)
		(layer "In9.Cu")
		(net "FM_MB_SLOT_ID2")
	)
	(segment
		(start 336.715608 -8.152892)
		(end 335.120996 -6.55828)
		(width 0.089408)
		(layer "In9.Cu")
		(net "FM_MB_SLOT_ID2")
	)
	(segment
		(start 347.525848 -17.608296)
		(end 347.525848 -14.437614)
		(width 0.089408)
		(layer "In9.Cu")
		(net "FM_MB_SLOT_ID2")
	)
	(segment
		(start 329.108562 -2.455926)
		(end 327.861422 -1.208786)
		(width 0.089408)
		(layer "In9.Cu")
		(net "FM_MB_SLOT_ID2")
	)
	(segment
		(start 184.734708 1.508506)
		(end 184.734962 1.508252)
		(width 0.089408)
		(layer "In9.Cu")
		(net "FM_MB_SLOT_ID2")
	)
	(segment
		(start 377.695968 -1.779778)
		(end 377.001278 -2.474468)
		(width 0.089408)
		(layer "In9.Cu")
		(net "FM_MB_SLOT_ID2")
	)
	(segment
		(start 360.299 -11.2014)
		(end 360.299 -13.2588)
		(width 0.089408)
		(layer "In9.Cu")
		(net "FM_MB_SLOT_ID2")
	)
	(segment
		(start 375.273316 -2.474468)
		(end 373.222774 -4.52501)
		(width 0.089408)
		(layer "In9.Cu")
		(net "FM_MB_SLOT_ID2")
	)
	(segment
		(start 355.065838 -22.554946)
		(end 352.12655 -22.554946)
		(width 0.089408)
		(layer "In9.Cu")
		(net "FM_MB_SLOT_ID2")
	)
	(segment
		(start 165.06063 4.285488)
		(end 103.69169 4.285488)
		(width 0.089408)
		(layer "In9.Cu")
		(net "FM_MB_SLOT_ID2")
	)
	(segment
		(start 178.913028 -2.997454)
		(end 178.570382 -2.654808)
		(width 0.089408)
		(layer "In9.Cu")
		(net "FM_MB_SLOT_ID2")
	)
	(segment
		(start 401.30222 3.689096)
		(end 399.937732 2.324608)
		(width 0.089408)
		(layer "In9.Cu")
		(net "FM_MB_SLOT_ID2")
	)
	(segment
		(start 24.161496 3.96748)
		(end 23.42388 3.96748)
		(width 0.089408)
		(layer "In9.Cu")
		(net "FM_MB_SLOT_ID2")
	)
	(segment
		(start 337.99653 -8.152892)
		(end 336.715608 -8.152892)
		(width 0.089408)
		(layer "In9.Cu")
		(net "FM_MB_SLOT_ID2")
	)
	(segment
		(start 327.861422 -1.208786)
		(end 325.966074 -1.208786)
		(width 0.089408)
		(layer "In9.Cu")
		(net "FM_MB_SLOT_ID2")
	)
	(segment
		(start 166.41064 -1.038606)
		(end 166.41064 2.935478)
		(width 0.089408)
		(layer "In9.Cu")
		(net "FM_MB_SLOT_ID2")
	)
	(segment
		(start 20.46859 5.015992)
		(end 20.19173 5.292852)
		(width 0.089408)
		(layer "In9.Cu")
		(net "FM_MB_SLOT_ID2")
	)
	(segment
		(start 381.014732 2.744724)
		(end 380.919228 2.64922)
		(width 0.089408)
		(layer "In9.Cu")
		(net "FM_MB_SLOT_ID2")
	)
	(segment
		(start 103.69169 4.285488)
		(end 102.961186 5.015992)
		(width 0.089408)
		(layer "In9.Cu")
		(net "FM_MB_SLOT_ID2")
	)
	(segment
		(start 183.638952 -1.074928)
		(end 181.716426 -2.997454)
		(width 0.089408)
		(layer "In9.Cu")
		(net "FM_MB_SLOT_ID2")
	)
	(segment
		(start 387.16966 2.744216)
		(end 387.169152 2.744724)
		(width 0.089408)
		(layer "In9.Cu")
		(net "FM_MB_SLOT_ID2")
	)
	(segment
		(start 362.260896 -10.414)
		(end 361.0864 -10.414)
		(width 0.089408)
		(layer "In9.Cu")
		(net "FM_MB_SLOT_ID2")
	)
	(segment
		(start 16.6497 4.84378)
		(end 16.551656 4.941824)
		(width 0.089408)
		(layer "In9.Cu")
		(net "FM_MB_SLOT_ID2")
	)
	(segment
		(start 393.29614 2.324608)
		(end 392.876532 2.744216)
		(width 0.089408)
		(layer "In9.Cu")
		(net "FM_MB_SLOT_ID2")
	)
	(segment
		(start 359.882694 -20.904454)
		(end 358.710992 -22.076156)
		(width 0.089408)
		(layer "In9.Cu")
		(net "FM_MB_SLOT_ID2")
	)
	(segment
		(start 321.401694 3.868928)
		(end 186.937142 3.868928)
		(width 0.089408)
		(layer "In9.Cu")
		(net "FM_MB_SLOT_ID2")
	)
	(segment
		(start 387.169152 2.744724)
		(end 387.011164 2.744724)
		(width 0.089408)
		(layer "In9.Cu")
		(net "FM_MB_SLOT_ID2")
	)
	(segment
		(start 171.455842 -2.97053)
		(end 168.342564 -2.97053)
		(width 0.089408)
		(layer "In9.Cu")
		(net "FM_MB_SLOT_ID2")
	)
	(segment
		(start 377.001278 -2.474468)
		(end 375.273316 -2.474468)
		(width 0.089408)
		(layer "In9.Cu")
		(net "FM_MB_SLOT_ID2")
	)
	(segment
		(start 356.077012 -22.207728)
		(end 355.413056 -22.207728)
		(width 0.089408)
		(layer "In9.Cu")
		(net "FM_MB_SLOT_ID2")
	)
	(segment
		(start 322.379086 2.891536)
		(end 321.401694 3.868928)
		(width 0.089408)
		(layer "In9.Cu")
		(net "FM_MB_SLOT_ID2")
	)
	(segment
		(start 178.570382 -2.654808)
		(end 171.771564 -2.654808)
		(width 0.089408)
		(layer "In9.Cu")
		(net "FM_MB_SLOT_ID2")
	)
	(segment
		(start 387.01091 2.74447)
		(end 386.92709 2.74447)
		(width 0.089408)
		(layer "In9.Cu")
		(net "FM_MB_SLOT_ID2")
	)
	(segment
		(start 403.549104 3.9878)
		(end 403.2504 3.689096)
		(width 0.089408)
		(layer "In9.Cu")
		(net "FM_MB_SLOT_ID2")
	)
	(segment
		(start 349.988124 -21.691854)
		(end 348.6658 -20.36953)
		(width 0.089408)
		(layer "In9.Cu")
		(net "FM_MB_SLOT_ID2")
	)
	(segment
		(start 25.210008 5.015992)
		(end 24.161496 3.96748)
		(width 0.089408)
		(layer "In9.Cu")
		(net "FM_MB_SLOT_ID2")
	)
	(segment
		(start 360.671364 -13.631164)
		(end 360.671364 -18.561812)
		(width 0.089408)
		(layer "In9.Cu")
		(net "FM_MB_SLOT_ID2")
	)
	(segment
		(start 22.375368 5.015992)
		(end 20.46859 5.015992)
		(width 0.089408)
		(layer "In9.Cu")
		(net "FM_MB_SLOT_ID2")
	)
	(segment
		(start 360.671364 -18.561812)
		(end 359.882694 -19.350482)
		(width 0.089408)
		(layer "In9.Cu")
		(net "FM_MB_SLOT_ID2")
	)
	(segment
		(start 351.263458 -21.691854)
		(end 349.988124 -21.691854)
		(width 0.089408)
		(layer "In9.Cu")
		(net "FM_MB_SLOT_ID2")
	)
	(segment
		(start 358.710992 -22.076156)
		(end 356.208584 -22.076156)
		(width 0.089408)
		(layer "In9.Cu")
		(net "FM_MB_SLOT_ID2")
	)
	(segment
		(start 366.171734 -4.52501)
		(end 363.23397 -7.462774)
		(width 0.089408)
		(layer "In9.Cu")
		(net "FM_MB_SLOT_ID2")
	)
	(segment
		(start 1.715008 -3.945128)
		(end 8.589518 2.929382)
		(width 0.089408)
		(layer "In11.Cu")
		(net "FM_MB_SLOT_ID2")
	)
	(segment
		(start -4.609592 -15.583916)
		(end -4.609592 -4.638802)
		(width 0.089408)
		(layer "In11.Cu")
		(net "FM_MB_SLOT_ID2")
	)
	(segment
		(start 16.030702 4.461002)
		(end 16.511524 4.941824)
		(width 0.089408)
		(layer "In11.Cu")
		(net "FM_MB_SLOT_ID2")
	)
	(segment
		(start 404.247858 -33.322514)
		(end 404.247858 -30.655006)
		(width 0.089408)
		(layer "In11.Cu")
		(net "FM_MB_SLOT_ID2")
	)
	(segment
		(start 403.318472 -29.72562)
		(end 403.318472 -27.902408)
		(width 0.089408)
		(layer "In11.Cu")
		(net "FM_MB_SLOT_ID2")
	)
	(segment
		(start 404.58263 -23.404576)
		(end 404.234904 -23.05685)
		(width 0.089408)
		(layer "In11.Cu")
		(net "FM_MB_SLOT_ID2")
	)
	(segment
		(start 412.76905 -18.817082)
		(end 412.76905 -20.366228)
		(width 0.089408)
		(layer "In11.Cu")
		(net "FM_MB_SLOT_ID2")
	)
	(segment
		(start 404.369016 -17.587214)
		(end 404.662386 -17.587214)
		(width 0.089408)
		(layer "In11.Cu")
		(net "FM_MB_SLOT_ID2")
	)
	(segment
		(start 404.247858 -30.655006)
		(end 403.318472 -29.72562)
		(width 0.089408)
		(layer "In11.Cu")
		(net "FM_MB_SLOT_ID2")
	)
	(segment
		(start 403.417532 -20.366228)
		(end 403.417532 -20.127468)
		(width 0.089408)
		(layer "In11.Cu")
		(net "FM_MB_SLOT_ID2")
	)
	(segment
		(start 404.662386 -17.587214)
		(end 404.7998 -17.4498)
		(width 0.089408)
		(layer "In11.Cu")
		(net "FM_MB_SLOT_ID2")
	)
	(segment
		(start 15.654782 4.461002)
		(end 16.030702 4.461002)
		(width 0.089408)
		(layer "In11.Cu")
		(net "FM_MB_SLOT_ID2")
	)
	(segment
		(start 403.417532 -20.127468)
		(end 403.196044 -19.90598)
		(width 0.089408)
		(layer "In11.Cu")
		(net "FM_MB_SLOT_ID2")
	)
	(segment
		(start 8.589518 2.929382)
		(end 14.123162 2.929382)
		(width 0.089408)
		(layer "In11.Cu")
		(net "FM_MB_SLOT_ID2")
	)
	(segment
		(start 404.234904 -21.1836)
		(end 403.417532 -20.366228)
		(width 0.089408)
		(layer "In11.Cu")
		(net "FM_MB_SLOT_ID2")
	)
	(segment
		(start -4.609592 -4.638802)
		(end -3.915918 -3.945128)
		(width 0.089408)
		(layer "In11.Cu")
		(net "FM_MB_SLOT_ID2")
	)
	(segment
		(start 403.318472 -27.902408)
		(end 404.58263 -26.63825)
		(width 0.089408)
		(layer "In11.Cu")
		(net "FM_MB_SLOT_ID2")
	)
	(segment
		(start 404.7998 -17.4498)
		(end 410.43098 -17.4498)
		(width 0.089408)
		(layer "In11.Cu")
		(net "FM_MB_SLOT_ID2")
	)
	(segment
		(start 403.196044 -19.90598)
		(end 403.196044 -18.760186)
		(width 0.089408)
		(layer "In11.Cu")
		(net "FM_MB_SLOT_ID2")
	)
	(segment
		(start 5.899912 -31.710122)
		(end 4.995418 -32.614616)
		(width 0.089408)
		(layer "In11.Cu")
		(net "FM_MB_SLOT_ID2")
	)
	(segment
		(start -5.243576 -16.2179)
		(end -4.609592 -15.583916)
		(width 0.089408)
		(layer "In11.Cu")
		(net "FM_MB_SLOT_ID2")
	)
	(segment
		(start -4.9022 -32.384746)
		(end -4.9022 -30.597856)
		(width 0.089408)
		(layer "In11.Cu")
		(net "FM_MB_SLOT_ID2")
	)
	(segment
		(start 16.511524 4.941824)
		(end 16.551656 4.941824)
		(width 0.089408)
		(layer "In11.Cu")
		(net "FM_MB_SLOT_ID2")
	)
	(segment
		(start 404.683214 -33.75787)
		(end 404.247858 -33.322514)
		(width 0.089408)
		(layer "In11.Cu")
		(net "FM_MB_SLOT_ID2")
	)
	(segment
		(start -5.243576 -30.25648)
		(end -5.243576 -16.2179)
		(width 0.089408)
		(layer "In11.Cu")
		(net "FM_MB_SLOT_ID2")
	)
	(segment
		(start 4.995418 -32.614616)
		(end -4.67233 -32.614616)
		(width 0.089408)
		(layer "In11.Cu")
		(net "FM_MB_SLOT_ID2")
	)
	(segment
		(start -4.67233 -32.614616)
		(end -4.9022 -32.384746)
		(width 0.089408)
		(layer "In11.Cu")
		(net "FM_MB_SLOT_ID2")
	)
	(segment
		(start 410.43098 -17.4498)
		(end 411.297374 -18.316194)
		(width 0.089408)
		(layer "In11.Cu")
		(net "FM_MB_SLOT_ID2")
	)
	(segment
		(start 404.58263 -26.63825)
		(end 404.58263 -23.404576)
		(width 0.089408)
		(layer "In11.Cu")
		(net "FM_MB_SLOT_ID2")
	)
	(segment
		(start 412.268162 -18.316194)
		(end 412.76905 -18.817082)
		(width 0.089408)
		(layer "In11.Cu")
		(net "FM_MB_SLOT_ID2")
	)
	(segment
		(start 404.683214 -34.11093)
		(end 404.683214 -33.75787)
		(width 0.089408)
		(layer "In11.Cu")
		(net "FM_MB_SLOT_ID2")
	)
	(segment
		(start 14.123162 2.929382)
		(end 15.654782 4.461002)
		(width 0.089408)
		(layer "In11.Cu")
		(net "FM_MB_SLOT_ID2")
	)
	(segment
		(start 411.297374 -18.316194)
		(end 412.268162 -18.316194)
		(width 0.089408)
		(layer "In11.Cu")
		(net "FM_MB_SLOT_ID2")
	)
	(segment
		(start 404.234904 -23.05685)
		(end 404.234904 -21.1836)
		(width 0.089408)
		(layer "In11.Cu")
		(net "FM_MB_SLOT_ID2")
	)
	(segment
		(start -3.915918 -3.945128)
		(end 1.715008 -3.945128)
		(width 0.089408)
		(layer "In11.Cu")
		(net "FM_MB_SLOT_ID2")
	)
	(segment
		(start -4.9022 -30.597856)
		(end -5.243576 -30.25648)
		(width 0.089408)
		(layer "In11.Cu")
		(net "FM_MB_SLOT_ID2")
	)
	(segment
		(start 403.196044 -18.760186)
		(end 404.369016 -17.587214)
		(width 0.089408)
		(layer "In11.Cu")
		(net "FM_MB_SLOT_ID2")
	)
	(segment
		(start 489.66374 -31.380176)
		(end 488.7214 -32.322516)
		(width 0.10795)
		(layer "F.Cu")
		(net "SP2_BMC_CM_UART_RX")
	)
	(segment
		(start 488.7214 -32.4358)
		(end 487.529886 -31.244286)
		(width 0.10795)
		(layer "F.Cu")
		(net "SP2_BMC_CM_UART_RX")
	)
	(segment
		(start 487.529886 -27.009852)
		(end 487.762042 -26.777696)
		(width 0.10795)
		(layer "F.Cu")
		(net "SP2_BMC_CM_UART_RX")
	)
	(segment
		(start 487.969306 -26.550112)
		(end 487.969306 -26.777696)
		(width 0.10795)
		(layer "F.Cu")
		(net "SP2_BMC_CM_UART_RX")
	)
	(segment
		(start 488.7214 -32.322516)
		(end 488.7214 -32.4358)
		(width 0.10795)
		(layer "F.Cu")
		(net "SP2_BMC_CM_UART_RX")
	)
	(segment
		(start 486.687876 -26.338784)
		(end 487.757978 -26.338784)
		(width 0.10795)
		(layer "F.Cu")
		(net "SP2_BMC_CM_UART_RX")
	)
	(segment
		(start 487.762042 -26.777696)
		(end 487.969306 -26.777696)
		(width 0.10795)
		(layer "F.Cu")
		(net "SP2_BMC_CM_UART_RX")
	)
	(segment
		(start 487.529886 -31.244286)
		(end 487.529886 -27.009852)
		(width 0.10795)
		(layer "F.Cu")
		(net "SP2_BMC_CM_UART_RX")
	)
	(segment
		(start 419.090094 -29.734764)
		(end 419.490144 -29.334714)
		(width 0.10795)
		(layer "F.Cu")
		(net "SP2_BMC_CM_UART_RX")
	)
	(segment
		(start 487.757978 -26.338784)
		(end 487.969306 -26.550112)
		(width 0.10795)
		(layer "F.Cu")
		(net "SP2_BMC_CM_UART_RX")
	)
	(via
		(at 476.35795 -38.84295)
		(size 0.508)
		(drill 0.254)
		(layers "F.Cu" "B.Cu")
		(net "SP2_BMC_CM_UART_RX")
	)
	(via
		(at 489.66374 -31.380176)
		(size 0.508)
		(drill 0.254)
		(layers "F.Cu" "B.Cu")
		(net "SP2_BMC_CM_UART_RX")
	)
	(via
		(at 488.7214 -32.4358)
		(size 0.762)
		(drill 0.381)
		(layers "F.Cu" "B.Cu")
		(net "SP2_BMC_CM_UART_RX")
	)
	(via
		(at 480.307396 -26.8224)
		(size 0.508)
		(drill 0.254)
		(layers "F.Cu" "B.Cu")
		(net "SP2_BMC_CM_UART_RX")
	)
	(via
		(at 419.490144 -29.334714)
		(size 0.4572)
		(drill 0.2032)
		(layers "F.Cu" "B.Cu")
		(net "SP2_BMC_CM_UART_RX")
	)
	(segment
		(start 487.979466 -30.131258)
		(end 486.04424 -30.131258)
		(width 0.089408)
		(layer "In2.Cu")
		(net "SP2_BMC_CM_UART_RX")
	)
	(segment
		(start 484.731314 -28.818332)
		(end 484.078534 -28.818332)
		(width 0.089408)
		(layer "In2.Cu")
		(net "SP2_BMC_CM_UART_RX")
	)
	(segment
		(start 483.301802 -28.0416)
		(end 481.526596 -28.0416)
		(width 0.089408)
		(layer "In2.Cu")
		(net "SP2_BMC_CM_UART_RX")
	)
	(segment
		(start 489.228384 -31.380176)
		(end 487.979466 -30.131258)
		(width 0.089408)
		(layer "In2.Cu")
		(net "SP2_BMC_CM_UART_RX")
	)
	(segment
		(start 481.526596 -28.0416)
		(end 480.307396 -26.8224)
		(width 0.089408)
		(layer "In2.Cu")
		(net "SP2_BMC_CM_UART_RX")
	)
	(segment
		(start 484.078534 -28.818332)
		(end 483.301802 -28.0416)
		(width 0.089408)
		(layer "In2.Cu")
		(net "SP2_BMC_CM_UART_RX")
	)
	(segment
		(start 486.04424 -30.131258)
		(end 484.731314 -28.818332)
		(width 0.089408)
		(layer "In2.Cu")
		(net "SP2_BMC_CM_UART_RX")
	)
	(segment
		(start 489.66374 -31.380176)
		(end 489.228384 -31.380176)
		(width 0.089408)
		(layer "In2.Cu")
		(net "SP2_BMC_CM_UART_RX")
	)
	(segment
		(start 459.679294 -33.214056)
		(end 459.67904 -33.21431)
		(width 0.089408)
		(layer "In4.Cu")
		(net "SP2_BMC_CM_UART_RX")
	)
	(segment
		(start 445.5414 -25.855676)
		(end 445.5414 -24.853646)
		(width 0.089408)
		(layer "In4.Cu")
		(net "SP2_BMC_CM_UART_RX")
	)
	(segment
		(start 451.874636 -32.188912)
		(end 445.5414 -25.855676)
		(width 0.089408)
		(layer "In4.Cu")
		(net "SP2_BMC_CM_UART_RX")
	)
	(segment
		(start 475.200472 -38.612318)
		(end 475.192344 -38.620446)
		(width 0.089408)
		(layer "In4.Cu")
		(net "SP2_BMC_CM_UART_RX")
	)
	(segment
		(start 420.664386 -28.960064)
		(end 420.289736 -29.334714)
		(width 0.089408)
		(layer "In4.Cu")
		(net "SP2_BMC_CM_UART_RX")
	)
	(segment
		(start 461.780128 -34.332164)
		(end 461.779874 -34.33191)
		(width 0.089408)
		(layer "In4.Cu")
		(net "SP2_BMC_CM_UART_RX")
	)
	(segment
		(start 461.136492 -34.332164)
		(end 461.136238 -34.332418)
		(width 0.089408)
		(layer "In4.Cu")
		(net "SP2_BMC_CM_UART_RX")
	)
	(segment
		(start 463.353404 -34.786062)
		(end 462.899506 -34.332164)
		(width 0.089408)
		(layer "In4.Cu")
		(net "SP2_BMC_CM_UART_RX")
	)
	(segment
		(start 422.190926 -28.001214)
		(end 422.082976 -28.109164)
		(width 0.089408)
		(layer "In4.Cu")
		(net "SP2_BMC_CM_UART_RX")
	)
	(segment
		(start 421.46474 -28.689808)
		(end 421.194484 -28.960064)
		(width 0.089408)
		(layer "In4.Cu")
		(net "SP2_BMC_CM_UART_RX")
	)
	(segment
		(start 465.580984 -34.786062)
		(end 463.353404 -34.786062)
		(width 0.089408)
		(layer "In4.Cu")
		(net "SP2_BMC_CM_UART_RX")
	)
	(segment
		(start 459.67904 -33.21431)
		(end 458.10043 -33.21431)
		(width 0.089408)
		(layer "In4.Cu")
		(net "SP2_BMC_CM_UART_RX")
	)
	(segment
		(start 442.015118 -23.121112)
		(end 441.228988 -23.907242)
		(width 0.089408)
		(layer "In4.Cu")
		(net "SP2_BMC_CM_UART_RX")
	)
	(segment
		(start 461.039972 -34.332418)
		(end 459.92161 -33.214056)
		(width 0.089408)
		(layer "In4.Cu")
		(net "SP2_BMC_CM_UART_RX")
	)
	(segment
		(start 422.082976 -28.109164)
		(end 421.785796 -28.109164)
		(width 0.089408)
		(layer "In4.Cu")
		(net "SP2_BMC_CM_UART_RX")
	)
	(segment
		(start 443.808866 -23.121112)
		(end 442.015118 -23.121112)
		(width 0.089408)
		(layer "In4.Cu")
		(net "SP2_BMC_CM_UART_RX")
	)
	(segment
		(start 437.80456 -23.640796)
		(end 435.831488 -23.640796)
		(width 0.089408)
		(layer "In4.Cu")
		(net "SP2_BMC_CM_UART_RX")
	)
	(segment
		(start 438.071006 -23.907242)
		(end 437.80456 -23.640796)
		(width 0.089408)
		(layer "In4.Cu")
		(net "SP2_BMC_CM_UART_RX")
	)
	(segment
		(start 421.46474 -28.43022)
		(end 421.46474 -28.689808)
		(width 0.089408)
		(layer "In4.Cu")
		(net "SP2_BMC_CM_UART_RX")
	)
	(segment
		(start 467.571836 -36.411154)
		(end 467.206076 -36.411154)
		(width 0.089408)
		(layer "In4.Cu")
		(net "SP2_BMC_CM_UART_RX")
	)
	(segment
		(start 476.35795 -38.84295)
		(end 476.135446 -38.620446)
		(width 0.089408)
		(layer "In4.Cu")
		(net "SP2_BMC_CM_UART_RX")
	)
	(segment
		(start 421.194484 -28.960064)
		(end 420.664386 -28.960064)
		(width 0.089408)
		(layer "In4.Cu")
		(net "SP2_BMC_CM_UART_RX")
	)
	(segment
		(start 462.899506 -34.332164)
		(end 461.780128 -34.332164)
		(width 0.089408)
		(layer "In4.Cu")
		(net "SP2_BMC_CM_UART_RX")
	)
	(segment
		(start 475.192344 -38.620446)
		(end 471.70594 -38.620446)
		(width 0.089408)
		(layer "In4.Cu")
		(net "SP2_BMC_CM_UART_RX")
	)
	(segment
		(start 421.785796 -28.109164)
		(end 421.46474 -28.43022)
		(width 0.089408)
		(layer "In4.Cu")
		(net "SP2_BMC_CM_UART_RX")
	)
	(segment
		(start 431.460148 -26.538936)
		(end 429.99787 -28.001214)
		(width 0.089408)
		(layer "In4.Cu")
		(net "SP2_BMC_CM_UART_RX")
	)
	(segment
		(start 441.228988 -23.907242)
		(end 438.071006 -23.907242)
		(width 0.089408)
		(layer "In4.Cu")
		(net "SP2_BMC_CM_UART_RX")
	)
	(segment
		(start 471.70594 -38.620446)
		(end 470.973404 -37.88791)
		(width 0.089408)
		(layer "In4.Cu")
		(net "SP2_BMC_CM_UART_RX")
	)
	(segment
		(start 467.206076 -36.411154)
		(end 465.580984 -34.786062)
		(width 0.089408)
		(layer "In4.Cu")
		(net "SP2_BMC_CM_UART_RX")
	)
	(segment
		(start 457.075032 -32.188912)
		(end 451.874636 -32.188912)
		(width 0.089408)
		(layer "In4.Cu")
		(net "SP2_BMC_CM_UART_RX")
	)
	(segment
		(start 420.289736 -29.334714)
		(end 419.490144 -29.334714)
		(width 0.089408)
		(layer "In4.Cu")
		(net "SP2_BMC_CM_UART_RX")
	)
	(segment
		(start 475.532196 -38.612318)
		(end 475.200472 -38.612318)
		(width 0.089408)
		(layer "In4.Cu")
		(net "SP2_BMC_CM_UART_RX")
	)
	(segment
		(start 432.933348 -26.538936)
		(end 431.460148 -26.538936)
		(width 0.089408)
		(layer "In4.Cu")
		(net "SP2_BMC_CM_UART_RX")
	)
	(segment
		(start 423.989754 -27.96921)
		(end 422.455594 -27.96921)
		(width 0.089408)
		(layer "In4.Cu")
		(net "SP2_BMC_CM_UART_RX")
	)
	(segment
		(start 459.92161 -33.214056)
		(end 459.679294 -33.214056)
		(width 0.089408)
		(layer "In4.Cu")
		(net "SP2_BMC_CM_UART_RX")
	)
	(segment
		(start 461.136238 -34.332418)
		(end 461.039972 -34.332418)
		(width 0.089408)
		(layer "In4.Cu")
		(net "SP2_BMC_CM_UART_RX")
	)
	(segment
		(start 476.135446 -38.620446)
		(end 475.540324 -38.620446)
		(width 0.089408)
		(layer "In4.Cu")
		(net "SP2_BMC_CM_UART_RX")
	)
	(segment
		(start 469.048592 -37.88791)
		(end 467.571836 -36.411154)
		(width 0.089408)
		(layer "In4.Cu")
		(net "SP2_BMC_CM_UART_RX")
	)
	(segment
		(start 461.779874 -34.33191)
		(end 461.294734 -34.33191)
		(width 0.089408)
		(layer "In4.Cu")
		(net "SP2_BMC_CM_UART_RX")
	)
	(segment
		(start 461.29448 -34.332164)
		(end 461.136492 -34.332164)
		(width 0.089408)
		(layer "In4.Cu")
		(net "SP2_BMC_CM_UART_RX")
	)
	(segment
		(start 422.455594 -27.96921)
		(end 422.42359 -28.001214)
		(width 0.089408)
		(layer "In4.Cu")
		(net "SP2_BMC_CM_UART_RX")
	)
	(segment
		(start 422.42359 -28.001214)
		(end 422.190926 -28.001214)
		(width 0.089408)
		(layer "In4.Cu")
		(net "SP2_BMC_CM_UART_RX")
	)
	(segment
		(start 470.973404 -37.88791)
		(end 469.048592 -37.88791)
		(width 0.089408)
		(layer "In4.Cu")
		(net "SP2_BMC_CM_UART_RX")
	)
	(segment
		(start 458.10043 -33.21431)
		(end 457.075032 -32.188912)
		(width 0.089408)
		(layer "In4.Cu")
		(net "SP2_BMC_CM_UART_RX")
	)
	(segment
		(start 424.021758 -28.001214)
		(end 423.989754 -27.96921)
		(width 0.089408)
		(layer "In4.Cu")
		(net "SP2_BMC_CM_UART_RX")
	)
	(segment
		(start 435.831488 -23.640796)
		(end 432.933348 -26.538936)
		(width 0.089408)
		(layer "In4.Cu")
		(net "SP2_BMC_CM_UART_RX")
	)
	(segment
		(start 429.99787 -28.001214)
		(end 424.021758 -28.001214)
		(width 0.089408)
		(layer "In4.Cu")
		(net "SP2_BMC_CM_UART_RX")
	)
	(segment
		(start 445.5414 -24.853646)
		(end 443.808866 -23.121112)
		(width 0.089408)
		(layer "In4.Cu")
		(net "SP2_BMC_CM_UART_RX")
	)
	(segment
		(start 461.294734 -34.33191)
		(end 461.29448 -34.332164)
		(width 0.089408)
		(layer "In4.Cu")
		(net "SP2_BMC_CM_UART_RX")
	)
	(segment
		(start 475.540324 -38.620446)
		(end 475.532196 -38.612318)
		(width 0.089408)
		(layer "In4.Cu")
		(net "SP2_BMC_CM_UART_RX")
	)
	(segment
		(start 476.0722 -38.823392)
		(end 476.0722 -35.306)
		(width 0.089408)
		(layer "In9.Cu")
		(net "SP2_BMC_CM_UART_RX")
	)
	(segment
		(start 476.161608 -38.9128)
		(end 476.0722 -38.823392)
		(width 0.089408)
		(layer "In9.Cu")
		(net "SP2_BMC_CM_UART_RX")
	)
	(segment
		(start 479.775266 -28.392374)
		(end 480.2632 -27.90444)
		(width 0.089408)
		(layer "In9.Cu")
		(net "SP2_BMC_CM_UART_RX")
	)
	(segment
		(start 476.0722 -35.306)
		(end 477.4184 -33.9598)
		(width 0.089408)
		(layer "In9.Cu")
		(net "SP2_BMC_CM_UART_RX")
	)
	(segment
		(start 479.133408 -33.9598)
		(end 479.775266 -33.317942)
		(width 0.089408)
		(layer "In9.Cu")
		(net "SP2_BMC_CM_UART_RX")
	)
	(segment
		(start 476.35795 -38.84295)
		(end 476.2881 -38.9128)
		(width 0.089408)
		(layer "In9.Cu")
		(net "SP2_BMC_CM_UART_RX")
	)
	(segment
		(start 477.4184 -33.9598)
		(end 479.133408 -33.9598)
		(width 0.089408)
		(layer "In9.Cu")
		(net "SP2_BMC_CM_UART_RX")
	)
	(segment
		(start 476.2881 -38.9128)
		(end 476.161608 -38.9128)
		(width 0.089408)
		(layer "In9.Cu")
		(net "SP2_BMC_CM_UART_RX")
	)
	(segment
		(start 480.2632 -26.866596)
		(end 480.307396 -26.8224)
		(width 0.089408)
		(layer "In9.Cu")
		(net "SP2_BMC_CM_UART_RX")
	)
	(segment
		(start 480.2632 -27.90444)
		(end 480.2632 -26.866596)
		(width 0.089408)
		(layer "In9.Cu")
		(net "SP2_BMC_CM_UART_RX")
	)
	(segment
		(start 479.775266 -33.317942)
		(end 479.775266 -28.392374)
		(width 0.089408)
		(layer "In9.Cu")
		(net "SP2_BMC_CM_UART_RX")
	)
	(segment
		(start 418.290248 -29.734764)
		(end 418.690298 -29.334714)
		(width 0.10795)
		(layer "F.Cu")
		(net "SP2_BMC_CM_UART_TX")
	)
	(via
		(at 492.9378 -34.6202)
		(size 0.508)
		(drill 0.254)
		(layers "F.Cu" "B.Cu")
		(net "SP2_BMC_CM_UART_TX")
	)
	(via
		(at 477.856296 -38.9255)
		(size 0.508)
		(drill 0.254)
		(layers "F.Cu" "B.Cu")
		(net "SP2_BMC_CM_UART_TX")
	)
	(via
		(at 494.908332 -37.851334)
		(size 0.6604)
		(drill 0.3302)
		(layers "F.Cu" "B.Cu")
		(net "SP2_BMC_CM_UART_TX")
	)
	(via
		(at 418.690298 -29.334714)
		(size 0.4572)
		(drill 0.2032)
		(layers "F.Cu" "B.Cu")
		(net "SP2_BMC_CM_UART_TX")
	)
	(segment
		(start 496.016534 -38.029896)
		(end 495.086894 -38.029896)
		(width 0.10795)
		(layer "B.Cu")
		(net "SP2_BMC_CM_UART_TX")
	)
	(segment
		(start 495.033046 -36.666932)
		(end 495.033046 -35.486594)
		(width 0.10795)
		(layer "B.Cu")
		(net "SP2_BMC_CM_UART_TX")
	)
	(segment
		(start 492.9378 -34.617406)
		(end 493.087406 -34.4678)
		(width 0.10795)
		(layer "B.Cu")
		(net "SP2_BMC_CM_UART_TX")
	)
	(segment
		(start 497.495322 -34.4678)
		(end 497.743226 -34.715704)
		(width 0.10795)
		(layer "B.Cu")
		(net "SP2_BMC_CM_UART_TX")
	)
	(segment
		(start 494.908332 -37.851334)
		(end 494.908332 -36.791646)
		(width 0.10795)
		(layer "B.Cu")
		(net "SP2_BMC_CM_UART_TX")
	)
	(segment
		(start 493.087406 -34.4678)
		(end 497.495322 -34.4678)
		(width 0.10795)
		(layer "B.Cu")
		(net "SP2_BMC_CM_UART_TX")
	)
	(segment
		(start 494.908332 -36.791646)
		(end 495.033046 -36.666932)
		(width 0.10795)
		(layer "B.Cu")
		(net "SP2_BMC_CM_UART_TX")
	)
	(segment
		(start 495.033046 -35.486594)
		(end 495.58956 -34.93008)
		(width 0.10795)
		(layer "B.Cu")
		(net "SP2_BMC_CM_UART_TX")
	)
	(segment
		(start 495.086894 -38.029896)
		(end 494.908332 -37.851334)
		(width 0.10795)
		(layer "B.Cu")
		(net "SP2_BMC_CM_UART_TX")
	)
	(segment
		(start 495.58956 -34.93008)
		(end 497.52885 -34.93008)
		(width 0.10795)
		(layer "B.Cu")
		(net "SP2_BMC_CM_UART_TX")
	)
	(segment
		(start 492.9378 -34.6202)
		(end 492.9378 -34.617406)
		(width 0.10795)
		(layer "B.Cu")
		(net "SP2_BMC_CM_UART_TX")
	)
	(segment
		(start 497.52885 -34.93008)
		(end 497.743226 -34.715704)
		(width 0.10795)
		(layer "B.Cu")
		(net "SP2_BMC_CM_UART_TX")
	)
	(segment
		(start 492.713264 -39.093902)
		(end 491.040166 -40.767)
		(width 0.089408)
		(layer "In2.Cu")
		(net "SP2_BMC_CM_UART_TX")
	)
	(segment
		(start 479.189034 -40.275764)
		(end 478.679764 -40.275764)
		(width 0.089408)
		(layer "In2.Cu")
		(net "SP2_BMC_CM_UART_TX")
	)
	(segment
		(start 478.4852 -39.554404)
		(end 477.856296 -38.9255)
		(width 0.089408)
		(layer "In2.Cu")
		(net "SP2_BMC_CM_UART_TX")
	)
	(segment
		(start 478.4852 -40.0812)
		(end 478.4852 -39.554404)
		(width 0.089408)
		(layer "In2.Cu")
		(net "SP2_BMC_CM_UART_TX")
	)
	(segment
		(start 488.799124 -41.558464)
		(end 480.471734 -41.558464)
		(width 0.089408)
		(layer "In2.Cu")
		(net "SP2_BMC_CM_UART_TX")
	)
	(segment
		(start 492.9378 -34.6202)
		(end 492.9378 -36.671758)
		(width 0.089408)
		(layer "In2.Cu")
		(net "SP2_BMC_CM_UART_TX")
	)
	(segment
		(start 492.713264 -36.896294)
		(end 492.713264 -39.093902)
		(width 0.089408)
		(layer "In2.Cu")
		(net "SP2_BMC_CM_UART_TX")
	)
	(segment
		(start 480.471734 -41.558464)
		(end 479.189034 -40.275764)
		(width 0.089408)
		(layer "In2.Cu")
		(net "SP2_BMC_CM_UART_TX")
	)
	(segment
		(start 478.679764 -40.275764)
		(end 478.4852 -40.0812)
		(width 0.089408)
		(layer "In2.Cu")
		(net "SP2_BMC_CM_UART_TX")
	)
	(segment
		(start 489.590588 -40.767)
		(end 488.799124 -41.558464)
		(width 0.089408)
		(layer "In2.Cu")
		(net "SP2_BMC_CM_UART_TX")
	)
	(segment
		(start 492.9378 -36.671758)
		(end 492.713264 -36.896294)
		(width 0.089408)
		(layer "In2.Cu")
		(net "SP2_BMC_CM_UART_TX")
	)
	(segment
		(start 491.040166 -40.767)
		(end 489.590588 -40.767)
		(width 0.089408)
		(layer "In2.Cu")
		(net "SP2_BMC_CM_UART_TX")
	)
	(segment
		(start 477.302576 -38.18001)
		(end 477.856296 -38.73373)
		(width 0.089408)
		(layer "In4.Cu")
		(net "SP2_BMC_CM_UART_TX")
	)
	(segment
		(start 437.030622 -22.868128)
		(end 443.825884 -22.868128)
		(width 0.089408)
		(layer "In4.Cu")
		(net "SP2_BMC_CM_UART_TX")
	)
	(segment
		(start 436.576216 -23.322534)
		(end 437.030622 -22.868128)
		(width 0.089408)
		(layer "In4.Cu")
		(net "SP2_BMC_CM_UART_TX")
	)
	(segment
		(start 421.218868 -28.159964)
		(end 421.470328 -27.908504)
		(width 0.089408)
		(layer "In4.Cu")
		(net "SP2_BMC_CM_UART_TX")
	)
	(segment
		(start 465.681314 -34.544254)
		(end 467.295484 -36.158424)
		(width 0.089408)
		(layer "In4.Cu")
		(net "SP2_BMC_CM_UART_TX")
	)
	(segment
		(start 432.833018 -26.297128)
		(end 435.807612 -23.322534)
		(width 0.089408)
		(layer "In4.Cu")
		(net "SP2_BMC_CM_UART_TX")
	)
	(segment
		(start 471.088974 -37.646102)
		(end 471.82151 -38.378638)
		(width 0.089408)
		(layer "In4.Cu")
		(net "SP2_BMC_CM_UART_TX")
	)
	(segment
		(start 471.82151 -38.378638)
		(end 475.092014 -38.378638)
		(width 0.089408)
		(layer "In4.Cu")
		(net "SP2_BMC_CM_UART_TX")
	)
	(segment
		(start 418.690298 -29.334714)
		(end 419.101778 -28.923234)
		(width 0.089408)
		(layer "In4.Cu")
		(net "SP2_BMC_CM_UART_TX")
	)
	(segment
		(start 463.453734 -34.544254)
		(end 465.681314 -34.544254)
		(width 0.089408)
		(layer "In4.Cu")
		(net "SP2_BMC_CM_UART_TX")
	)
	(segment
		(start 420.664894 -28.249626)
		(end 420.754556 -28.159964)
		(width 0.089408)
		(layer "In4.Cu")
		(net "SP2_BMC_CM_UART_TX")
	)
	(segment
		(start 475.092014 -38.378638)
		(end 475.100142 -38.37051)
		(width 0.089408)
		(layer "In4.Cu")
		(net "SP2_BMC_CM_UART_TX")
	)
	(segment
		(start 467.663784 -36.160964)
		(end 469.148922 -37.646102)
		(width 0.089408)
		(layer "In4.Cu")
		(net "SP2_BMC_CM_UART_TX")
	)
	(segment
		(start 458.514958 -32.238696)
		(end 459.288388 -32.238696)
		(width 0.089408)
		(layer "In4.Cu")
		(net "SP2_BMC_CM_UART_TX")
	)
	(segment
		(start 467.295484 -36.158424)
		(end 467.589362 -36.158424)
		(width 0.089408)
		(layer "In4.Cu")
		(net "SP2_BMC_CM_UART_TX")
	)
	(segment
		(start 460.328264 -33.278572)
		(end 462.188052 -33.278572)
		(width 0.089408)
		(layer "In4.Cu")
		(net "SP2_BMC_CM_UART_TX")
	)
	(segment
		(start 420.664894 -28.689554)
		(end 420.664894 -28.249626)
		(width 0.089408)
		(layer "In4.Cu")
		(net "SP2_BMC_CM_UART_TX")
	)
	(segment
		(start 423.152062 -27.759406)
		(end 429.89754 -27.759406)
		(width 0.089408)
		(layer "In4.Cu")
		(net "SP2_BMC_CM_UART_TX")
	)
	(segment
		(start 476.063564 -38.18001)
		(end 477.302576 -38.18001)
		(width 0.089408)
		(layer "In4.Cu")
		(net "SP2_BMC_CM_UART_TX")
	)
	(segment
		(start 431.359818 -26.297128)
		(end 432.833018 -26.297128)
		(width 0.089408)
		(layer "In4.Cu")
		(net "SP2_BMC_CM_UART_TX")
	)
	(segment
		(start 475.640654 -38.378638)
		(end 475.864936 -38.378638)
		(width 0.089408)
		(layer "In4.Cu")
		(net "SP2_BMC_CM_UART_TX")
	)
	(segment
		(start 477.856296 -38.73373)
		(end 477.856296 -38.9255)
		(width 0.089408)
		(layer "In4.Cu")
		(net "SP2_BMC_CM_UART_TX")
	)
	(segment
		(start 422.697148 -27.304492)
		(end 423.152062 -27.759406)
		(width 0.089408)
		(layer "In4.Cu")
		(net "SP2_BMC_CM_UART_TX")
	)
	(segment
		(start 467.589362 -36.158424)
		(end 467.589362 -36.160964)
		(width 0.089408)
		(layer "In4.Cu")
		(net "SP2_BMC_CM_UART_TX")
	)
	(segment
		(start 475.100142 -38.37051)
		(end 475.632526 -38.37051)
		(width 0.089408)
		(layer "In4.Cu")
		(net "SP2_BMC_CM_UART_TX")
	)
	(segment
		(start 451.974966 -31.947104)
		(end 458.223366 -31.947104)
		(width 0.089408)
		(layer "In4.Cu")
		(net "SP2_BMC_CM_UART_TX")
	)
	(segment
		(start 445.783208 -25.755346)
		(end 451.974966 -31.947104)
		(width 0.089408)
		(layer "In4.Cu")
		(net "SP2_BMC_CM_UART_TX")
	)
	(segment
		(start 469.148922 -37.646102)
		(end 471.088974 -37.646102)
		(width 0.089408)
		(layer "In4.Cu")
		(net "SP2_BMC_CM_UART_TX")
	)
	(segment
		(start 467.589362 -36.160964)
		(end 467.663784 -36.160964)
		(width 0.089408)
		(layer "In4.Cu")
		(net "SP2_BMC_CM_UART_TX")
	)
	(segment
		(start 475.632526 -38.37051)
		(end 475.640654 -38.378638)
		(width 0.089408)
		(layer "In4.Cu")
		(net "SP2_BMC_CM_UART_TX")
	)
	(segment
		(start 458.223366 -31.947104)
		(end 458.514958 -32.238696)
		(width 0.089408)
		(layer "In4.Cu")
		(net "SP2_BMC_CM_UART_TX")
	)
	(segment
		(start 421.470328 -27.908504)
		(end 421.470328 -27.457908)
		(width 0.089408)
		(layer "In4.Cu")
		(net "SP2_BMC_CM_UART_TX")
	)
	(segment
		(start 435.807612 -23.322534)
		(end 436.576216 -23.322534)
		(width 0.089408)
		(layer "In4.Cu")
		(net "SP2_BMC_CM_UART_TX")
	)
	(segment
		(start 421.623744 -27.304492)
		(end 422.697148 -27.304492)
		(width 0.089408)
		(layer "In4.Cu")
		(net "SP2_BMC_CM_UART_TX")
	)
	(segment
		(start 419.101778 -28.923234)
		(end 420.431214 -28.923234)
		(width 0.089408)
		(layer "In4.Cu")
		(net "SP2_BMC_CM_UART_TX")
	)
	(segment
		(start 420.431214 -28.923234)
		(end 420.664894 -28.689554)
		(width 0.089408)
		(layer "In4.Cu")
		(net "SP2_BMC_CM_UART_TX")
	)
	(segment
		(start 420.754556 -28.159964)
		(end 421.218868 -28.159964)
		(width 0.089408)
		(layer "In4.Cu")
		(net "SP2_BMC_CM_UART_TX")
	)
	(segment
		(start 475.864936 -38.378638)
		(end 476.063564 -38.18001)
		(width 0.089408)
		(layer "In4.Cu")
		(net "SP2_BMC_CM_UART_TX")
	)
	(segment
		(start 421.470328 -27.457908)
		(end 421.623744 -27.304492)
		(width 0.089408)
		(layer "In4.Cu")
		(net "SP2_BMC_CM_UART_TX")
	)
	(segment
		(start 462.188052 -33.278572)
		(end 463.453734 -34.544254)
		(width 0.089408)
		(layer "In4.Cu")
		(net "SP2_BMC_CM_UART_TX")
	)
	(segment
		(start 459.288388 -32.238696)
		(end 460.328264 -33.278572)
		(width 0.089408)
		(layer "In4.Cu")
		(net "SP2_BMC_CM_UART_TX")
	)
	(segment
		(start 429.89754 -27.759406)
		(end 431.359818 -26.297128)
		(width 0.089408)
		(layer "In4.Cu")
		(net "SP2_BMC_CM_UART_TX")
	)
	(segment
		(start 443.825884 -22.868128)
		(end 445.783208 -24.825452)
		(width 0.089408)
		(layer "In4.Cu")
		(net "SP2_BMC_CM_UART_TX")
	)
	(segment
		(start 445.783208 -24.825452)
		(end 445.783208 -25.755346)
		(width 0.089408)
		(layer "In4.Cu")
		(net "SP2_BMC_CM_UART_TX")
	)
	(segment
		(start 25.781 -82.837782)
		(end 25.781 -82.296)
		(width 0.10795)
		(layer "F.Cu")
		(net "FM_OC_DETECT_EN")
	)
	(segment
		(start 24.977598 -81.705958)
		(end 24.977598 -79.860902)
		(width 0.10795)
		(layer "F.Cu")
		(net "FM_OC_DETECT_EN")
	)
	(segment
		(start 24.7015 -84.911692)
		(end 24.7015 -84.455)
		(width 0.10795)
		(layer "F.Cu")
		(net "FM_OC_DETECT_EN")
	)
	(segment
		(start 25.925018 -85.950298)
		(end 25.740106 -85.950298)
		(width 0.10795)
		(layer "F.Cu")
		(net "FM_OC_DETECT_EN")
	)
	(segment
		(start 25.781 -82.296)
		(end 25.4 -81.915)
		(width 0.10795)
		(layer "F.Cu")
		(net "FM_OC_DETECT_EN")
	)
	(segment
		(start 25.570942 -84.310982)
		(end 25.570942 -83.04784)
		(width 0.10795)
		(layer "F.Cu")
		(net "FM_OC_DETECT_EN")
	)
	(segment
		(start 25.4 -81.915)
		(end 25.18664 -81.915)
		(width 0.10795)
		(layer "F.Cu")
		(net "FM_OC_DETECT_EN")
	)
	(segment
		(start 25.18664 -81.915)
		(end 24.977598 -81.705958)
		(width 0.10795)
		(layer "F.Cu")
		(net "FM_OC_DETECT_EN")
	)
	(segment
		(start 25.740106 -85.950298)
		(end 24.7015 -84.911692)
		(width 0.10795)
		(layer "F.Cu")
		(net "FM_OC_DETECT_EN")
	)
	(segment
		(start 24.7015 -84.455)
		(end 25.426924 -84.455)
		(width 0.10795)
		(layer "F.Cu")
		(net "FM_OC_DETECT_EN")
	)
	(segment
		(start 25.426924 -84.455)
		(end 25.570942 -84.310982)
		(width 0.10795)
		(layer "F.Cu")
		(net "FM_OC_DETECT_EN")
	)
	(segment
		(start 25.570942 -83.04784)
		(end 25.781 -82.837782)
		(width 0.10795)
		(layer "F.Cu")
		(net "FM_OC_DETECT_EN")
	)
	(segment
		(start 25.4889 -79.3496)
		(end 26.0223 -79.3496)
		(width 0.10795)
		(layer "F.Cu")
		(net "FM_OC_DETECT_EN")
	)
	(segment
		(start 24.977598 -79.860902)
		(end 25.4889 -79.3496)
		(width 0.10795)
		(layer "F.Cu")
		(net "FM_OC_DETECT_EN")
	)
	(via
		(at 25.925018 -85.950298)
		(size 0.762)
		(drill 0.381)
		(layers "F.Cu" "B.Cu")
		(net "FM_OC_DETECT_EN")
	)
	(segment
		(start 414.87979 -104.61879)
		(end 415.1376 -104.8766)
		(width 0.10795)
		(layer "F.Cu")
		(net "IRQ_BOARD_BMC_ALERT_N")
	)
	(segment
		(start 410.239464 -105.1052)
		(end 410.725874 -104.61879)
		(width 0.10795)
		(layer "F.Cu")
		(net "IRQ_BOARD_BMC_ALERT_N")
	)
	(segment
		(start 424.650916 -25.538684)
		(end 423.92473 -25.538684)
		(width 0.10795)
		(layer "F.Cu")
		(net "IRQ_BOARD_BMC_ALERT_N")
	)
	(segment
		(start 405.497284 -105.127044)
		(end 407.131774 -105.127044)
		(width 0.10795)
		(layer "F.Cu")
		(net "IRQ_BOARD_BMC_ALERT_N")
	)
	(segment
		(start 408.676602 -104.847898)
		(end 408.8765 -104.648)
		(width 0.10795)
		(layer "F.Cu")
		(net "IRQ_BOARD_BMC_ALERT_N")
	)
	(segment
		(start 404.067518 -104.422956)
		(end 404.180548 -104.422956)
		(width 0.10795)
		(layer "F.Cu")
		(net "IRQ_BOARD_BMC_ALERT_N")
	)
	(segment
		(start 402.691346 -103.660956)
		(end 403.06752 -104.03713)
		(width 0.0889)
		(layer "F.Cu")
		(net "IRQ_BOARD_BMC_ALERT_N")
	)
	(segment
		(start 400.586702 -103.733346)
		(end 400.966178 -103.733346)
		(width 0.0889)
		(layer "F.Cu")
		(net "IRQ_BOARD_BMC_ALERT_N")
	)
	(segment
		(start 403.681692 -104.03713)
		(end 404.067518 -104.422956)
		(width 0.0889)
		(layer "F.Cu")
		(net "IRQ_BOARD_BMC_ALERT_N")
	)
	(segment
		(start 407.502106 -105.106724)
		(end 407.522426 -105.127044)
		(width 0.10795)
		(layer "F.Cu")
		(net "IRQ_BOARD_BMC_ALERT_N")
	)
	(segment
		(start 400.465036 -103.855012)
		(end 400.586702 -103.733346)
		(width 0.0889)
		(layer "F.Cu")
		(net "IRQ_BOARD_BMC_ALERT_N")
	)
	(segment
		(start 11.7094 -105.732834)
		(end 12.6492 -104.793034)
		(width 0.10795)
		(layer "F.Cu")
		(net "IRQ_BOARD_BMC_ALERT_N")
	)
	(segment
		(start 401.130262 -103.569262)
		(end 401.451826 -103.569262)
		(width 0.0889)
		(layer "F.Cu")
		(net "IRQ_BOARD_BMC_ALERT_N")
	)
	(segment
		(start 404.180548 -104.422956)
		(end 405.015954 -105.258362)
		(width 0.10795)
		(layer "F.Cu")
		(net "IRQ_BOARD_BMC_ALERT_N")
	)
	(segment
		(start 408.676602 -104.924352)
		(end 408.676602 -104.847898)
		(width 0.10795)
		(layer "F.Cu")
		(net "IRQ_BOARD_BMC_ALERT_N")
	)
	(segment
		(start 401.451826 -103.569262)
		(end 401.54352 -103.660956)
		(width 0.0889)
		(layer "F.Cu")
		(net "IRQ_BOARD_BMC_ALERT_N")
	)
	(segment
		(start 400.966178 -103.733346)
		(end 401.130262 -103.569262)
		(width 0.0889)
		(layer "F.Cu")
		(net "IRQ_BOARD_BMC_ALERT_N")
	)
	(segment
		(start 405.015954 -105.258362)
		(end 405.365966 -105.258362)
		(width 0.10795)
		(layer "F.Cu")
		(net "IRQ_BOARD_BMC_ALERT_N")
	)
	(segment
		(start 410.725874 -104.61879)
		(end 414.87979 -104.61879)
		(width 0.10795)
		(layer "F.Cu")
		(net "IRQ_BOARD_BMC_ALERT_N")
	)
	(segment
		(start 12.6492 -104.793034)
		(end 12.6492 -102.6668)
		(width 0.10795)
		(layer "F.Cu")
		(net "IRQ_BOARD_BMC_ALERT_N")
	)
	(segment
		(start 408.47391 -105.127044)
		(end 408.676602 -104.924352)
		(width 0.10795)
		(layer "F.Cu")
		(net "IRQ_BOARD_BMC_ALERT_N")
	)
	(segment
		(start 12.6492 -102.6668)
		(end 13.335 -101.981)
		(width 0.10795)
		(layer "F.Cu")
		(net "IRQ_BOARD_BMC_ALERT_N")
	)
	(segment
		(start 407.131774 -105.127044)
		(end 407.152094 -105.106724)
		(width 0.10795)
		(layer "F.Cu")
		(net "IRQ_BOARD_BMC_ALERT_N")
	)
	(segment
		(start 407.152094 -105.106724)
		(end 407.502106 -105.106724)
		(width 0.10795)
		(layer "F.Cu")
		(net "IRQ_BOARD_BMC_ALERT_N")
	)
	(segment
		(start 408.8765 -104.648)
		(end 409.0924 -104.8639)
		(width 0.10795)
		(layer "F.Cu")
		(net "IRQ_BOARD_BMC_ALERT_N")
	)
	(segment
		(start 426.122846 -24.066754)
		(end 424.650916 -25.538684)
		(width 0.10033)
		(layer "F.Cu")
		(net "IRQ_BOARD_BMC_ALERT_N")
	)
	(segment
		(start 409.1813 -105.1052)
		(end 410.239464 -105.1052)
		(width 0.10795)
		(layer "F.Cu")
		(net "IRQ_BOARD_BMC_ALERT_N")
	)
	(segment
		(start 407.522426 -105.127044)
		(end 408.47391 -105.127044)
		(width 0.10795)
		(layer "F.Cu")
		(net "IRQ_BOARD_BMC_ALERT_N")
	)
	(segment
		(start 423.090086 -26.373328)
		(end 423.090086 -26.534618)
		(width 0.10795)
		(layer "F.Cu")
		(net "IRQ_BOARD_BMC_ALERT_N")
	)
	(segment
		(start 405.365966 -105.258362)
		(end 405.497284 -105.127044)
		(width 0.10795)
		(layer "F.Cu")
		(net "IRQ_BOARD_BMC_ALERT_N")
	)
	(segment
		(start 426.122846 -22.936454)
		(end 426.122846 -24.066754)
		(width 0.10033)
		(layer "F.Cu")
		(net "IRQ_BOARD_BMC_ALERT_N")
	)
	(segment
		(start 403.06752 -104.03713)
		(end 403.681692 -104.03713)
		(width 0.0889)
		(layer "F.Cu")
		(net "IRQ_BOARD_BMC_ALERT_N")
	)
	(segment
		(start 423.92473 -25.538684)
		(end 423.090086 -26.373328)
		(width 0.10795)
		(layer "F.Cu")
		(net "IRQ_BOARD_BMC_ALERT_N")
	)
	(segment
		(start 409.0924 -105.0163)
		(end 409.1813 -105.1052)
		(width 0.10795)
		(layer "F.Cu")
		(net "IRQ_BOARD_BMC_ALERT_N")
	)
	(segment
		(start 409.0924 -104.8639)
		(end 409.0924 -105.0163)
		(width 0.10795)
		(layer "F.Cu")
		(net "IRQ_BOARD_BMC_ALERT_N")
	)
	(segment
		(start 401.54352 -103.660956)
		(end 402.691346 -103.660956)
		(width 0.0889)
		(layer "F.Cu")
		(net "IRQ_BOARD_BMC_ALERT_N")
	)
	(via
		(at 426.122846 -22.936454)
		(size 0.508)
		(drill 0.254)
		(layers "F.Cu" "B.Cu")
		(net "IRQ_BOARD_BMC_ALERT_N")
	)
	(via
		(at 471.70594 -28.8544)
		(size 0.508)
		(drill 0.254)
		(layers "F.Cu" "B.Cu")
		(net "IRQ_BOARD_BMC_ALERT_N")
	)
	(via
		(at 415.1376 -104.8766)
		(size 0.508)
		(drill 0.254)
		(layers "F.Cu" "B.Cu")
		(net "IRQ_BOARD_BMC_ALERT_N")
	)
	(via
		(at 11.7094 -105.732834)
		(size 0.508)
		(drill 0.254)
		(layers "F.Cu" "B.Cu")
		(net "IRQ_BOARD_BMC_ALERT_N")
	)
	(via
		(at 458.732128 -65.117472)
		(size 0.6604)
		(drill 0.3302)
		(layers "F.Cu" "B.Cu")
		(net "IRQ_BOARD_BMC_ALERT_N")
	)
	(via
		(at 436.58028 -63.254128)
		(size 0.508)
		(drill 0.254)
		(layers "F.Cu" "B.Cu")
		(net "IRQ_BOARD_BMC_ALERT_N")
	)
	(via
		(at 467.397846 -62.08395)
		(size 0.508)
		(drill 0.254)
		(layers "F.Cu" "B.Cu")
		(net "IRQ_BOARD_BMC_ALERT_N")
	)
	(via
		(at 370.34724 -125.73508)
		(size 0.508)
		(drill 0.254)
		(layers "F.Cu" "B.Cu")
		(net "IRQ_BOARD_BMC_ALERT_N")
	)
	(segment
		(start 467.241636 -62.691772)
		(end 467.241636 -62.24016)
		(width 0.10795)
		(layer "B.Cu")
		(net "IRQ_BOARD_BMC_ALERT_N")
	)
	(segment
		(start 466.556598 -63.37681)
		(end 467.241636 -62.691772)
		(width 0.10795)
		(layer "B.Cu")
		(net "IRQ_BOARD_BMC_ALERT_N")
	)
	(segment
		(start 459.487016 -64.362584)
		(end 461.829658 -64.362584)
		(width 0.10795)
		(layer "B.Cu")
		(net "IRQ_BOARD_BMC_ALERT_N")
	)
	(segment
		(start 457.20635 -66.64325)
		(end 458.732128 -65.117472)
		(width 0.10795)
		(layer "B.Cu")
		(net "IRQ_BOARD_BMC_ALERT_N")
	)
	(segment
		(start 465.921598 -64.754252)
		(end 466.556598 -64.119252)
		(width 0.10795)
		(layer "B.Cu")
		(net "IRQ_BOARD_BMC_ALERT_N")
	)
	(segment
		(start 437.345836 -66.64325)
		(end 457.20635 -66.64325)
		(width 0.10795)
		(layer "B.Cu")
		(net "IRQ_BOARD_BMC_ALERT_N")
	)
	(segment
		(start 467.241636 -62.24016)
		(end 467.397846 -62.08395)
		(width 0.10795)
		(layer "B.Cu")
		(net "IRQ_BOARD_BMC_ALERT_N")
	)
	(segment
		(start 436.58028 -65.877694)
		(end 437.345836 -66.64325)
		(width 0.10795)
		(layer "B.Cu")
		(net "IRQ_BOARD_BMC_ALERT_N")
	)
	(segment
		(start 462.10855 -64.083692)
		(end 462.838292 -64.083692)
		(width 0.10795)
		(layer "B.Cu")
		(net "IRQ_BOARD_BMC_ALERT_N")
	)
	(segment
		(start 461.829658 -64.362584)
		(end 462.10855 -64.083692)
		(width 0.10795)
		(layer "B.Cu")
		(net "IRQ_BOARD_BMC_ALERT_N")
	)
	(segment
		(start 436.58028 -63.254128)
		(end 436.58028 -65.877694)
		(width 0.10795)
		(layer "B.Cu")
		(net "IRQ_BOARD_BMC_ALERT_N")
	)
	(segment
		(start 463.508852 -64.754252)
		(end 465.921598 -64.754252)
		(width 0.10795)
		(layer "B.Cu")
		(net "IRQ_BOARD_BMC_ALERT_N")
	)
	(segment
		(start 462.838292 -64.083692)
		(end 463.508852 -64.754252)
		(width 0.10795)
		(layer "B.Cu")
		(net "IRQ_BOARD_BMC_ALERT_N")
	)
	(segment
		(start 458.732128 -65.117472)
		(end 459.487016 -64.362584)
		(width 0.10795)
		(layer "B.Cu")
		(net "IRQ_BOARD_BMC_ALERT_N")
	)
	(segment
		(start 466.556598 -64.119252)
		(end 466.556598 -63.37681)
		(width 0.10795)
		(layer "B.Cu")
		(net "IRQ_BOARD_BMC_ALERT_N")
	)
	(segment
		(start 448.411346 -20.766278)
		(end 452.672958 -20.766278)
		(width 0.089408)
		(layer "In2.Cu")
		(net "IRQ_BOARD_BMC_ALERT_N")
	)
	(segment
		(start 458.545184 -25.932384)
		(end 460.581502 -25.932384)
		(width 0.089408)
		(layer "In2.Cu")
		(net "IRQ_BOARD_BMC_ALERT_N")
	)
	(segment
		(start 432.729894 -21.287994)
		(end 433.457096 -20.560792)
		(width 0.089408)
		(layer "In2.Cu")
		(net "IRQ_BOARD_BMC_ALERT_N")
	)
	(segment
		(start 426.122846 -22.936454)
		(end 426.340016 -22.719284)
		(width 0.089408)
		(layer "In2.Cu")
		(net "IRQ_BOARD_BMC_ALERT_N")
	)
	(segment
		(start 427.850554 -21.287994)
		(end 432.729894 -21.287994)
		(width 0.089408)
		(layer "In2.Cu")
		(net "IRQ_BOARD_BMC_ALERT_N")
	)
	(segment
		(start 445.320674 -20.29587)
		(end 447.940938 -20.29587)
		(width 0.089408)
		(layer "In2.Cu")
		(net "IRQ_BOARD_BMC_ALERT_N")
	)
	(segment
		(start 452.672958 -20.766278)
		(end 453.950324 -22.043644)
		(width 0.089408)
		(layer "In2.Cu")
		(net "IRQ_BOARD_BMC_ALERT_N")
	)
	(segment
		(start 443.027816 -20.66036)
		(end 444.956184 -20.66036)
		(width 0.089408)
		(layer "In2.Cu")
		(net "IRQ_BOARD_BMC_ALERT_N")
	)
	(segment
		(start 442.928248 -20.560792)
		(end 443.027816 -20.66036)
		(width 0.089408)
		(layer "In2.Cu")
		(net "IRQ_BOARD_BMC_ALERT_N")
	)
	(segment
		(start 453.950324 -22.043644)
		(end 454.656444 -22.043644)
		(width 0.089408)
		(layer "In2.Cu")
		(net "IRQ_BOARD_BMC_ALERT_N")
	)
	(segment
		(start 447.940938 -20.29587)
		(end 448.411346 -20.766278)
		(width 0.089408)
		(layer "In2.Cu")
		(net "IRQ_BOARD_BMC_ALERT_N")
	)
	(segment
		(start 426.340016 -22.719284)
		(end 426.419264 -22.719284)
		(width 0.089408)
		(layer "In2.Cu")
		(net "IRQ_BOARD_BMC_ALERT_N")
	)
	(segment
		(start 468.57158 -27.2288)
		(end 470.19718 -28.8544)
		(width 0.089408)
		(layer "In2.Cu")
		(net "IRQ_BOARD_BMC_ALERT_N")
	)
	(segment
		(start 426.419264 -22.719284)
		(end 427.850554 -21.287994)
		(width 0.089408)
		(layer "In2.Cu")
		(net "IRQ_BOARD_BMC_ALERT_N")
	)
	(segment
		(start 470.19718 -28.8544)
		(end 471.70594 -28.8544)
		(width 0.089408)
		(layer "In2.Cu")
		(net "IRQ_BOARD_BMC_ALERT_N")
	)
	(segment
		(start 444.956184 -20.66036)
		(end 445.320674 -20.29587)
		(width 0.089408)
		(layer "In2.Cu")
		(net "IRQ_BOARD_BMC_ALERT_N")
	)
	(segment
		(start 461.877918 -27.2288)
		(end 468.57158 -27.2288)
		(width 0.089408)
		(layer "In2.Cu")
		(net "IRQ_BOARD_BMC_ALERT_N")
	)
	(segment
		(start 433.457096 -20.560792)
		(end 442.928248 -20.560792)
		(width 0.089408)
		(layer "In2.Cu")
		(net "IRQ_BOARD_BMC_ALERT_N")
	)
	(segment
		(start 454.656444 -22.043644)
		(end 458.545184 -25.932384)
		(width 0.089408)
		(layer "In2.Cu")
		(net "IRQ_BOARD_BMC_ALERT_N")
	)
	(segment
		(start 460.581502 -25.932384)
		(end 461.877918 -27.2288)
		(width 0.089408)
		(layer "In2.Cu")
		(net "IRQ_BOARD_BMC_ALERT_N")
	)
	(segment
		(start 415.169096 -120.897904)
		(end 415.872168 -120.194832)
		(width 0.089408)
		(layer "In4.Cu")
		(net "IRQ_BOARD_BMC_ALERT_N")
	)
	(segment
		(start 379.135894 -125.376432)
		(end 379.753876 -124.75845)
		(width 0.089408)
		(layer "In4.Cu")
		(net "IRQ_BOARD_BMC_ALERT_N")
	)
	(segment
		(start 400.965924 -124.75845)
		(end 400.971512 -124.752862)
		(width 0.089408)
		(layer "In4.Cu")
		(net "IRQ_BOARD_BMC_ALERT_N")
	)
	(segment
		(start 407.173176 -122.192288)
		(end 407.7208 -121.644664)
		(width 0.089408)
		(layer "In4.Cu")
		(net "IRQ_BOARD_BMC_ALERT_N")
	)
	(segment
		(start 411.743144 -120.142)
		(end 412.499048 -120.897904)
		(width 0.089408)
		(layer "In4.Cu")
		(net "IRQ_BOARD_BMC_ALERT_N")
	)
	(segment
		(start 400.97202 -124.752862)
		(end 401.620482 -124.1044)
		(width 0.089408)
		(layer "In4.Cu")
		(net "IRQ_BOARD_BMC_ALERT_N")
	)
	(segment
		(start 371.612922 -125.137926)
		(end 372.62562 -124.125228)
		(width 0.089408)
		(layer "In4.Cu")
		(net "IRQ_BOARD_BMC_ALERT_N")
	)
	(segment
		(start 401.620482 -124.1044)
		(end 404.019766 -124.1044)
		(width 0.089408)
		(layer "In4.Cu")
		(net "IRQ_BOARD_BMC_ALERT_N")
	)
	(segment
		(start 415.671 -107.2388)
		(end 415.671 -105.3846)
		(width 0.089408)
		(layer "In4.Cu")
		(net "IRQ_BOARD_BMC_ALERT_N")
	)
	(segment
		(start 404.019766 -124.1044)
		(end 405.931878 -122.192288)
		(width 0.089408)
		(layer "In4.Cu")
		(net "IRQ_BOARD_BMC_ALERT_N")
	)
	(segment
		(start 372.62562 -124.125228)
		(end 375.218452 -124.125228)
		(width 0.089408)
		(layer "In4.Cu")
		(net "IRQ_BOARD_BMC_ALERT_N")
	)
	(segment
		(start 405.931878 -122.192288)
		(end 407.173176 -122.192288)
		(width 0.089408)
		(layer "In4.Cu")
		(net "IRQ_BOARD_BMC_ALERT_N")
	)
	(segment
		(start 400.971512 -124.752862)
		(end 400.97202 -124.752862)
		(width 0.089408)
		(layer "In4.Cu")
		(net "IRQ_BOARD_BMC_ALERT_N")
	)
	(segment
		(start 379.753876 -124.75845)
		(end 400.965924 -124.75845)
		(width 0.089408)
		(layer "In4.Cu")
		(net "IRQ_BOARD_BMC_ALERT_N")
	)
	(segment
		(start 414.9852 -117.301264)
		(end 414.9852 -107.9246)
		(width 0.089408)
		(layer "In4.Cu")
		(net "IRQ_BOARD_BMC_ALERT_N")
	)
	(segment
		(start 375.218452 -124.125228)
		(end 376.230896 -125.137672)
		(width 0.089408)
		(layer "In4.Cu")
		(net "IRQ_BOARD_BMC_ALERT_N")
	)
	(segment
		(start 376.230896 -125.137672)
		(end 377.249944 -125.137672)
		(width 0.089408)
		(layer "In4.Cu")
		(net "IRQ_BOARD_BMC_ALERT_N")
	)
	(segment
		(start 370.944394 -125.137926)
		(end 371.612922 -125.137926)
		(width 0.089408)
		(layer "In4.Cu")
		(net "IRQ_BOARD_BMC_ALERT_N")
	)
	(segment
		(start 407.7208 -120.577864)
		(end 408.156664 -120.142)
		(width 0.089408)
		(layer "In4.Cu")
		(net "IRQ_BOARD_BMC_ALERT_N")
	)
	(segment
		(start 377.249944 -125.137672)
		(end 377.488704 -125.376432)
		(width 0.089408)
		(layer "In4.Cu")
		(net "IRQ_BOARD_BMC_ALERT_N")
	)
	(segment
		(start 415.163 -104.8766)
		(end 415.1376 -104.8766)
		(width 0.089408)
		(layer "In4.Cu")
		(net "IRQ_BOARD_BMC_ALERT_N")
	)
	(segment
		(start 414.9852 -107.9246)
		(end 415.671 -107.2388)
		(width 0.089408)
		(layer "In4.Cu")
		(net "IRQ_BOARD_BMC_ALERT_N")
	)
	(segment
		(start 415.872168 -120.194832)
		(end 415.872168 -118.188232)
		(width 0.089408)
		(layer "In4.Cu")
		(net "IRQ_BOARD_BMC_ALERT_N")
	)
	(segment
		(start 370.34724 -125.73508)
		(end 370.944394 -125.137926)
		(width 0.089408)
		(layer "In4.Cu")
		(net "IRQ_BOARD_BMC_ALERT_N")
	)
	(segment
		(start 377.488704 -125.376432)
		(end 379.135894 -125.376432)
		(width 0.089408)
		(layer "In4.Cu")
		(net "IRQ_BOARD_BMC_ALERT_N")
	)
	(segment
		(start 407.7208 -121.644664)
		(end 407.7208 -120.577864)
		(width 0.089408)
		(layer "In4.Cu")
		(net "IRQ_BOARD_BMC_ALERT_N")
	)
	(segment
		(start 415.671 -105.3846)
		(end 415.163 -104.8766)
		(width 0.089408)
		(layer "In4.Cu")
		(net "IRQ_BOARD_BMC_ALERT_N")
	)
	(segment
		(start 415.872168 -118.188232)
		(end 414.9852 -117.301264)
		(width 0.089408)
		(layer "In4.Cu")
		(net "IRQ_BOARD_BMC_ALERT_N")
	)
	(segment
		(start 408.156664 -120.142)
		(end 411.743144 -120.142)
		(width 0.089408)
		(layer "In4.Cu")
		(net "IRQ_BOARD_BMC_ALERT_N")
	)
	(segment
		(start 412.499048 -120.897904)
		(end 415.169096 -120.897904)
		(width 0.089408)
		(layer "In4.Cu")
		(net "IRQ_BOARD_BMC_ALERT_N")
	)
	(segment
		(start 23.635716 -133.515608)
		(end 22.454616 -133.515608)
		(width 0.089408)
		(layer "In9.Cu")
		(net "IRQ_BOARD_BMC_ALERT_N")
	)
	(segment
		(start 370.34724 -126.959614)
		(end 369.189 -128.117854)
		(width 0.089408)
		(layer "In9.Cu")
		(net "IRQ_BOARD_BMC_ALERT_N")
	)
	(segment
		(start 469.992964 -35.718496)
		(end 469.838024 -35.563556)
		(width 0.089408)
		(layer "In9.Cu")
		(net "IRQ_BOARD_BMC_ALERT_N")
	)
	(segment
		(start 176.12741 -145.117566)
		(end 172.85589 -145.117566)
		(width 0.089408)
		(layer "In9.Cu")
		(net "IRQ_BOARD_BMC_ALERT_N")
	)
	(segment
		(start 470.493598 -38.83025)
		(end 469.992964 -38.329616)
		(width 0.089408)
		(layer "In9.Cu")
		(net "IRQ_BOARD_BMC_ALERT_N")
	)
	(segment
		(start 329.3364 -143.382238)
		(end 329.3364 -146.982434)
		(width 0.089408)
		(layer "In9.Cu")
		(net "IRQ_BOARD_BMC_ALERT_N")
	)
	(segment
		(start 470.68613 -58.909966)
		(end 470.68613 -54.600856)
		(width 0.089408)
		(layer "In9.Cu")
		(net "IRQ_BOARD_BMC_ALERT_N")
	)
	(segment
		(start 332.156562 -135.227822)
		(end 332.156562 -135.949182)
		(width 0.089408)
		(layer "In9.Cu")
		(net "IRQ_BOARD_BMC_ALERT_N")
	)
	(segment
		(start 19.88058 -117.468142)
		(end 18.34896 -115.936522)
		(width 0.089408)
		(layer "In9.Cu")
		(net "IRQ_BOARD_BMC_ALERT_N")
	)
	(segment
		(start 426.66158 -59.824112)
		(end 427.932342 -59.824112)
		(width 0.089408)
		(layer "In9.Cu")
		(net "IRQ_BOARD_BMC_ALERT_N")
	)
	(segment
		(start 369.189 -128.117854)
		(end 368.381534 -128.117854)
		(width 0.089408)
		(layer "In9.Cu")
		(net "IRQ_BOARD_BMC_ALERT_N")
	)
	(segment
		(start 169.99966 -147.973796)
		(end 161.42335 -147.973796)
		(width 0.089408)
		(layer "In9.Cu")
		(net "IRQ_BOARD_BMC_ALERT_N")
	)
	(segment
		(start 18.34896 -115.06708)
		(end 11.591798 -108.309918)
		(width 0.089408)
		(layer "In9.Cu")
		(net "IRQ_BOARD_BMC_ALERT_N")
	)
	(segment
		(start 26.569924 -135.407654)
		(end 24.79167 -133.6294)
		(width 0.089408)
		(layer "In9.Cu")
		(net "IRQ_BOARD_BMC_ALERT_N")
	)
	(segment
		(start 157.592522 -151.804624)
		(end 29.742384 -151.804624)
		(width 0.089408)
		(layer "In9.Cu")
		(net "IRQ_BOARD_BMC_ALERT_N")
	)
	(segment
		(start 339.465158 -134.207758)
		(end 337.8835 -132.6261)
		(width 0.089408)
		(layer "In9.Cu")
		(net "IRQ_BOARD_BMC_ALERT_N")
	)
	(segment
		(start 469.992964 -38.329616)
		(end 469.992964 -35.718496)
		(width 0.089408)
		(layer "In9.Cu")
		(net "IRQ_BOARD_BMC_ALERT_N")
	)
	(segment
		(start 467.397846 -62.08395)
		(end 467.397846 -61.828426)
		(width 0.089408)
		(layer "In9.Cu")
		(net "IRQ_BOARD_BMC_ALERT_N")
	)
	(segment
		(start 328.871834 -142.917672)
		(end 329.3364 -143.382238)
		(width 0.089408)
		(layer "In9.Cu")
		(net "IRQ_BOARD_BMC_ALERT_N")
	)
	(segment
		(start 27.4574 -137.573512)
		(end 26.569924 -136.686036)
		(width 0.089408)
		(layer "In9.Cu")
		(net "IRQ_BOARD_BMC_ALERT_N")
	)
	(segment
		(start -0.787654 -97.7646)
		(end -0.42164 -98.130614)
		(width 0.089408)
		(layer "In9.Cu")
		(net "IRQ_BOARD_BMC_ALERT_N")
	)
	(segment
		(start 329.126088 -150.95474)
		(end 328.290428 -151.7904)
		(width 0.089408)
		(layer "In9.Cu")
		(net "IRQ_BOARD_BMC_ALERT_N")
	)
	(segment
		(start 469.962992 -48.87849)
		(end 470.343738 -48.497744)
		(width 0.089408)
		(layer "In9.Cu")
		(net "IRQ_BOARD_BMC_ALERT_N")
	)
	(segment
		(start 329.355704 -147.001738)
		(end 329.355704 -147.333462)
		(width 0.089408)
		(layer "In9.Cu")
		(net "IRQ_BOARD_BMC_ALERT_N")
	)
	(segment
		(start 19.88058 -122.884184)
		(end 19.88058 -117.468142)
		(width 0.089408)
		(layer "In9.Cu")
		(net "IRQ_BOARD_BMC_ALERT_N")
	)
	(segment
		(start 370.34724 -125.73508)
		(end 370.34724 -126.959614)
		(width 0.089408)
		(layer "In9.Cu")
		(net "IRQ_BOARD_BMC_ALERT_N")
	)
	(segment
		(start 468.470742 -61.125354)
		(end 470.68613 -58.909966)
		(width 0.089408)
		(layer "In9.Cu")
		(net "IRQ_BOARD_BMC_ALERT_N")
	)
	(segment
		(start 9.525 -100.4062)
		(end 9.525 -103.548434)
		(width 0.089408)
		(layer "In9.Cu")
		(net "IRQ_BOARD_BMC_ALERT_N")
	)
	(segment
		(start 9.525 -103.548434)
		(end 11.7094 -105.732834)
		(width 0.089408)
		(layer "In9.Cu")
		(net "IRQ_BOARD_BMC_ALERT_N")
	)
	(segment
		(start 358.386634 -131.15417)
		(end 356.730554 -131.15417)
		(width 0.089408)
		(layer "In9.Cu")
		(net "IRQ_BOARD_BMC_ALERT_N")
	)
	(segment
		(start 354.328476 -132.99186)
		(end 353.112578 -134.207758)
		(width 0.089408)
		(layer "In9.Cu")
		(net "IRQ_BOARD_BMC_ALERT_N")
	)
	(segment
		(start 420.582598 -65.150492)
		(end 421.182038 -64.551052)
		(width 0.089408)
		(layer "In9.Cu")
		(net "IRQ_BOARD_BMC_ALERT_N")
	)
	(segment
		(start 415.5948 -104.4194)
		(end 415.5948 -97.702878)
		(width 0.089408)
		(layer "In9.Cu")
		(net "IRQ_BOARD_BMC_ALERT_N")
	)
	(segment
		(start 337.8835 -132.6261)
		(end 334.758284 -132.6261)
		(width 0.089408)
		(layer "In9.Cu")
		(net "IRQ_BOARD_BMC_ALERT_N")
	)
	(segment
		(start 188.168026 -151.7904)
		(end 184.802018 -148.424392)
		(width 0.089408)
		(layer "In9.Cu")
		(net "IRQ_BOARD_BMC_ALERT_N")
	)
	(segment
		(start 19.926808 -130.559048)
		(end 17.838674 -128.470914)
		(width 0.089408)
		(layer "In9.Cu")
		(net "IRQ_BOARD_BMC_ALERT_N")
	)
	(segment
		(start 19.926808 -130.9878)
		(end 19.926808 -130.559048)
		(width 0.089408)
		(layer "In9.Cu")
		(net "IRQ_BOARD_BMC_ALERT_N")
	)
	(segment
		(start 11.591798 -108.309918)
		(end 11.591798 -105.850436)
		(width 0.089408)
		(layer "In9.Cu")
		(net "IRQ_BOARD_BMC_ALERT_N")
	)
	(segment
		(start 328.290428 -151.7904)
		(end 188.168026 -151.7904)
		(width 0.089408)
		(layer "In9.Cu")
		(net "IRQ_BOARD_BMC_ALERT_N")
	)
	(segment
		(start 421.182038 -63.68288)
		(end 421.181784 -63.682626)
		(width 0.089408)
		(layer "In9.Cu")
		(net "IRQ_BOARD_BMC_ALERT_N")
	)
	(segment
		(start 470.815416 -53.661818)
		(end 469.962992 -52.809394)
		(width 0.089408)
		(layer "In9.Cu")
		(net "IRQ_BOARD_BMC_ALERT_N")
	)
	(segment
		(start 29.742384 -151.804624)
		(end 27.4574 -149.51964)
		(width 0.089408)
		(layer "In9.Cu")
		(net "IRQ_BOARD_BMC_ALERT_N")
	)
	(segment
		(start 332.156562 -135.949182)
		(end 328.871834 -139.23391)
		(width 0.089408)
		(layer "In9.Cu")
		(net "IRQ_BOARD_BMC_ALERT_N")
	)
	(segment
		(start 27.4574 -149.51964)
		(end 27.4574 -137.573512)
		(width 0.089408)
		(layer "In9.Cu")
		(net "IRQ_BOARD_BMC_ALERT_N")
	)
	(segment
		(start 415.5948 -97.702878)
		(end 417.79571 -95.501968)
		(width 0.089408)
		(layer "In9.Cu")
		(net "IRQ_BOARD_BMC_ALERT_N")
	)
	(segment
		(start 471.70594 -29.779976)
		(end 471.70594 -28.8544)
		(width 0.089408)
		(layer "In9.Cu")
		(net "IRQ_BOARD_BMC_ALERT_N")
	)
	(segment
		(start 423.163238 -60.260484)
		(end 426.224954 -60.260484)
		(width 0.089408)
		(layer "In9.Cu")
		(net "IRQ_BOARD_BMC_ALERT_N")
	)
	(segment
		(start 24.79167 -133.6294)
		(end 23.749508 -133.6294)
		(width 0.089408)
		(layer "In9.Cu")
		(net "IRQ_BOARD_BMC_ALERT_N")
	)
	(segment
		(start 329.3364 -147.352766)
		(end 329.3364 -149.404578)
		(width 0.089408)
		(layer "In9.Cu")
		(net "IRQ_BOARD_BMC_ALERT_N")
	)
	(segment
		(start 415.1376 -104.8766)
		(end 415.5948 -104.4194)
		(width 0.089408)
		(layer "In9.Cu")
		(net "IRQ_BOARD_BMC_ALERT_N")
	)
	(segment
		(start -0.42164 -99.02952)
		(end 0.16764 -99.6188)
		(width 0.089408)
		(layer "In9.Cu")
		(net "IRQ_BOARD_BMC_ALERT_N")
	)
	(segment
		(start 161.42335 -147.973796)
		(end 157.592522 -151.804624)
		(width 0.089408)
		(layer "In9.Cu")
		(net "IRQ_BOARD_BMC_ALERT_N")
	)
	(segment
		(start 11.591798 -105.850436)
		(end 11.7094 -105.732834)
		(width 0.089408)
		(layer "In9.Cu")
		(net "IRQ_BOARD_BMC_ALERT_N")
	)
	(segment
		(start 469.962992 -52.809394)
		(end 469.962992 -48.87849)
		(width 0.089408)
		(layer "In9.Cu")
		(net "IRQ_BOARD_BMC_ALERT_N")
	)
	(segment
		(start 354.892864 -132.99186)
		(end 354.328476 -132.99186)
		(width 0.089408)
		(layer "In9.Cu")
		(net "IRQ_BOARD_BMC_ALERT_N")
	)
	(segment
		(start 417.812728 -95.501968)
		(end 420.582598 -92.732098)
		(width 0.089408)
		(layer "In9.Cu")
		(net "IRQ_BOARD_BMC_ALERT_N")
	)
	(segment
		(start 470.68613 -54.600856)
		(end 470.815416 -54.47157)
		(width 0.089408)
		(layer "In9.Cu")
		(net "IRQ_BOARD_BMC_ALERT_N")
	)
	(segment
		(start 356.730554 -131.15417)
		(end 354.892864 -132.99186)
		(width 0.089408)
		(layer "In9.Cu")
		(net "IRQ_BOARD_BMC_ALERT_N")
	)
	(segment
		(start 470.0524 -44.18838)
		(end 470.0524 -40.39108)
		(width 0.089408)
		(layer "In9.Cu")
		(net "IRQ_BOARD_BMC_ALERT_N")
	)
	(segment
		(start 17.838674 -124.92609)
		(end 19.88058 -122.884184)
		(width 0.089408)
		(layer "In9.Cu")
		(net "IRQ_BOARD_BMC_ALERT_N")
	)
	(segment
		(start 470.0524 -40.39108)
		(end 470.493598 -39.949882)
		(width 0.089408)
		(layer "In9.Cu")
		(net "IRQ_BOARD_BMC_ALERT_N")
	)
	(segment
		(start -0.42164 -98.130614)
		(end -0.42164 -99.02952)
		(width 0.089408)
		(layer "In9.Cu")
		(net "IRQ_BOARD_BMC_ALERT_N")
	)
	(segment
		(start 468.100918 -61.125354)
		(end 468.470742 -61.125354)
		(width 0.089408)
		(layer "In9.Cu")
		(net "IRQ_BOARD_BMC_ALERT_N")
	)
	(segment
		(start 329.3364 -146.982434)
		(end 329.355704 -147.001738)
		(width 0.089408)
		(layer "In9.Cu")
		(net "IRQ_BOARD_BMC_ALERT_N")
	)
	(segment
		(start 470.493598 -39.949882)
		(end 470.493598 -38.83025)
		(width 0.089408)
		(layer "In9.Cu")
		(net "IRQ_BOARD_BMC_ALERT_N")
	)
	(segment
		(start 23.749508 -133.6294)
		(end 23.635716 -133.515608)
		(width 0.089408)
		(layer "In9.Cu")
		(net "IRQ_BOARD_BMC_ALERT_N")
	)
	(segment
		(start 470.343738 -48.497744)
		(end 470.343738 -44.479718)
		(width 0.089408)
		(layer "In9.Cu")
		(net "IRQ_BOARD_BMC_ALERT_N")
	)
	(segment
		(start 469.838024 -31.647892)
		(end 471.70594 -29.779976)
		(width 0.089408)
		(layer "In9.Cu")
		(net "IRQ_BOARD_BMC_ALERT_N")
	)
	(segment
		(start -2.500122 -96.769936)
		(end -1.505458 -97.7646)
		(width 0.089408)
		(layer "In9.Cu")
		(net "IRQ_BOARD_BMC_ALERT_N")
	)
	(segment
		(start 18.34896 -115.936522)
		(end 18.34896 -115.06708)
		(width 0.089408)
		(layer "In9.Cu")
		(net "IRQ_BOARD_BMC_ALERT_N")
	)
	(segment
		(start 172.85589 -145.117566)
		(end 169.99966 -147.973796)
		(width 0.089408)
		(layer "In9.Cu")
		(net "IRQ_BOARD_BMC_ALERT_N")
	)
	(segment
		(start 26.569924 -136.686036)
		(end 26.569924 -135.407654)
		(width 0.089408)
		(layer "In9.Cu")
		(net "IRQ_BOARD_BMC_ALERT_N")
	)
	(segment
		(start 470.815416 -54.47157)
		(end 470.815416 -53.661818)
		(width 0.089408)
		(layer "In9.Cu")
		(net "IRQ_BOARD_BMC_ALERT_N")
	)
	(segment
		(start 8.7376 -99.6188)
		(end 9.525 -100.4062)
		(width 0.089408)
		(layer "In9.Cu")
		(net "IRQ_BOARD_BMC_ALERT_N")
	)
	(segment
		(start 469.838024 -35.563556)
		(end 469.838024 -31.647892)
		(width 0.089408)
		(layer "In9.Cu")
		(net "IRQ_BOARD_BMC_ALERT_N")
	)
	(segment
		(start 421.182038 -64.551052)
		(end 421.182038 -63.68288)
		(width 0.089408)
		(layer "In9.Cu")
		(net "IRQ_BOARD_BMC_ALERT_N")
	)
	(segment
		(start 420.582598 -92.732098)
		(end 420.582598 -65.150492)
		(width 0.089408)
		(layer "In9.Cu")
		(net "IRQ_BOARD_BMC_ALERT_N")
	)
	(segment
		(start 421.181784 -62.241938)
		(end 423.163238 -60.260484)
		(width 0.089408)
		(layer "In9.Cu")
		(net "IRQ_BOARD_BMC_ALERT_N")
	)
	(segment
		(start 329.3364 -149.404578)
		(end 329.126088 -149.61489)
		(width 0.089408)
		(layer "In9.Cu")
		(net "IRQ_BOARD_BMC_ALERT_N")
	)
	(segment
		(start 334.758284 -132.6261)
		(end 332.156562 -135.227822)
		(width 0.089408)
		(layer "In9.Cu")
		(net "IRQ_BOARD_BMC_ALERT_N")
	)
	(segment
		(start 436.283862 -62.95771)
		(end 436.58028 -63.254128)
		(width 0.089408)
		(layer "In9.Cu")
		(net "IRQ_BOARD_BMC_ALERT_N")
	)
	(segment
		(start 184.802018 -148.424392)
		(end 181.722268 -148.424392)
		(width 0.089408)
		(layer "In9.Cu")
		(net "IRQ_BOARD_BMC_ALERT_N")
	)
	(segment
		(start 431.06594 -62.95771)
		(end 436.283862 -62.95771)
		(width 0.089408)
		(layer "In9.Cu")
		(net "IRQ_BOARD_BMC_ALERT_N")
	)
	(segment
		(start 359.461816 -130.078988)
		(end 358.386634 -131.15417)
		(width 0.089408)
		(layer "In9.Cu")
		(net "IRQ_BOARD_BMC_ALERT_N")
	)
	(segment
		(start 329.126088 -149.61489)
		(end 329.126088 -150.95474)
		(width 0.089408)
		(layer "In9.Cu")
		(net "IRQ_BOARD_BMC_ALERT_N")
	)
	(segment
		(start 421.181784 -63.682626)
		(end 421.181784 -62.241938)
		(width 0.089408)
		(layer "In9.Cu")
		(net "IRQ_BOARD_BMC_ALERT_N")
	)
	(segment
		(start 467.397846 -61.828426)
		(end 468.100918 -61.125354)
		(width 0.089408)
		(layer "In9.Cu")
		(net "IRQ_BOARD_BMC_ALERT_N")
	)
	(segment
		(start 353.112578 -134.207758)
		(end 339.465158 -134.207758)
		(width 0.089408)
		(layer "In9.Cu")
		(net "IRQ_BOARD_BMC_ALERT_N")
	)
	(segment
		(start 328.871834 -139.23391)
		(end 328.871834 -142.917672)
		(width 0.089408)
		(layer "In9.Cu")
		(net "IRQ_BOARD_BMC_ALERT_N")
	)
	(segment
		(start 426.224954 -60.260484)
		(end 426.66158 -59.824112)
		(width 0.089408)
		(layer "In9.Cu")
		(net "IRQ_BOARD_BMC_ALERT_N")
	)
	(segment
		(start 22.454616 -133.515608)
		(end 19.926808 -130.9878)
		(width 0.089408)
		(layer "In9.Cu")
		(net "IRQ_BOARD_BMC_ALERT_N")
	)
	(segment
		(start 0.16764 -99.6188)
		(end 8.7376 -99.6188)
		(width 0.089408)
		(layer "In9.Cu")
		(net "IRQ_BOARD_BMC_ALERT_N")
	)
	(segment
		(start 366.4204 -130.078988)
		(end 359.461816 -130.078988)
		(width 0.089408)
		(layer "In9.Cu")
		(net "IRQ_BOARD_BMC_ALERT_N")
	)
	(segment
		(start 470.343738 -44.479718)
		(end 470.0524 -44.18838)
		(width 0.089408)
		(layer "In9.Cu")
		(net "IRQ_BOARD_BMC_ALERT_N")
	)
	(segment
		(start 427.932342 -59.824112)
		(end 431.06594 -62.95771)
		(width 0.089408)
		(layer "In9.Cu")
		(net "IRQ_BOARD_BMC_ALERT_N")
	)
	(segment
		(start 368.381534 -128.117854)
		(end 366.4204 -130.078988)
		(width 0.089408)
		(layer "In9.Cu")
		(net "IRQ_BOARD_BMC_ALERT_N")
	)
	(segment
		(start -1.505458 -97.7646)
		(end -0.787654 -97.7646)
		(width 0.089408)
		(layer "In9.Cu")
		(net "IRQ_BOARD_BMC_ALERT_N")
	)
	(segment
		(start 329.355704 -147.333462)
		(end 329.3364 -147.352766)
		(width 0.089408)
		(layer "In9.Cu")
		(net "IRQ_BOARD_BMC_ALERT_N")
	)
	(segment
		(start 181.722268 -148.424392)
		(end 180.405532 -147.107656)
		(width 0.089408)
		(layer "In9.Cu")
		(net "IRQ_BOARD_BMC_ALERT_N")
	)
	(segment
		(start 180.405532 -147.107656)
		(end 178.1175 -147.107656)
		(width 0.089408)
		(layer "In9.Cu")
		(net "IRQ_BOARD_BMC_ALERT_N")
	)
	(segment
		(start 417.79571 -95.501968)
		(end 417.812728 -95.501968)
		(width 0.089408)
		(layer "In9.Cu")
		(net "IRQ_BOARD_BMC_ALERT_N")
	)
	(segment
		(start 17.838674 -128.470914)
		(end 17.838674 -124.92609)
		(width 0.089408)
		(layer "In9.Cu")
		(net "IRQ_BOARD_BMC_ALERT_N")
	)
	(segment
		(start 178.1175 -147.107656)
		(end 176.12741 -145.117566)
		(width 0.089408)
		(layer "In9.Cu")
		(net "IRQ_BOARD_BMC_ALERT_N")
	)
	(segment
		(start 396.15745 -113.28908)
		(end 396.65275 -113.519204)
		(width 0.10795)
		(layer "F.Cu")
		(net "IRQ_HSC_FAULT_N")
	)
	(segment
		(start 416.4965 -112.788446)
		(end 415.950654 -112.2426)
		(width 0.10795)
		(layer "F.Cu")
		(net "IRQ_HSC_FAULT_N")
	)
	(segment
		(start 416.4965 -113.151158)
		(end 416.4965 -112.788446)
		(width 0.10795)
		(layer "F.Cu")
		(net "IRQ_HSC_FAULT_N")
	)
	(segment
		(start 23.114 -77.1398)
		(end 22.935438 -76.961238)
		(width 0.10795)
		(layer "F.Cu")
		(net "IRQ_HSC_FAULT_N")
	)
	(segment
		(start 415.950654 -112.2426)
		(end 415.4678 -112.2426)
		(width 0.10795)
		(layer "F.Cu")
		(net "IRQ_HSC_FAULT_N")
	)
	(segment
		(start 22.935438 -76.961238)
		(end 22.5044 -76.961238)
		(width 0.10795)
		(layer "F.Cu")
		(net "IRQ_HSC_FAULT_N")
	)
	(segment
		(start 23.114 -77.724)
		(end 23.114 -77.1398)
		(width 0.10795)
		(layer "F.Cu")
		(net "IRQ_HSC_FAULT_N")
	)
	(segment
		(start 416.690048 -40.93464)
		(end 417.093654 -41.338246)
		(width 0.10795)
		(layer "F.Cu")
		(net "IRQ_HSC_FAULT_N")
	)
	(via
		(at 478.4852 -53.48605)
		(size 0.508)
		(drill 0.254)
		(layers "F.Cu" "B.Cu")
		(net "IRQ_HSC_FAULT_N")
	)
	(via
		(at 417.093654 -41.338246)
		(size 0.4572)
		(drill 0.2032)
		(layers "F.Cu" "B.Cu")
		(net "IRQ_HSC_FAULT_N")
	)
	(via
		(at 22.5044 -76.961238)
		(size 0.508)
		(drill 0.254)
		(layers "F.Cu" "B.Cu")
		(net "IRQ_HSC_FAULT_N")
	)
	(via
		(at 332.6638 -21.1582)
		(size 0.508)
		(drill 0.254)
		(layers "F.Cu" "B.Cu")
		(net "IRQ_HSC_FAULT_N")
	)
	(via
		(at 436.64632 -59.982608)
		(size 0.508)
		(drill 0.254)
		(layers "F.Cu" "B.Cu")
		(net "IRQ_HSC_FAULT_N")
	)
	(via
		(at 22.549358 2.688844)
		(size 0.508)
		(drill 0.254)
		(layers "F.Cu" "B.Cu")
		(net "IRQ_HSC_FAULT_N")
	)
	(via
		(at 21.9964 -23.876)
		(size 0.508)
		(drill 0.254)
		(layers "F.Cu" "B.Cu")
		(net "IRQ_HSC_FAULT_N")
	)
	(via
		(at 396.65275 -113.519204)
		(size 0.508)
		(drill 0.254)
		(layers "F.Cu" "B.Cu")
		(net "IRQ_HSC_FAULT_N")
	)
	(via
		(at 416.4965 -113.151158)
		(size 0.508)
		(drill 0.254)
		(layers "F.Cu" "B.Cu")
		(net "IRQ_HSC_FAULT_N")
	)
	(segment
		(start 22.2758 -23.5966)
		(end 21.9964 -23.876)
		(width 0.10795)
		(layer "B.Cu")
		(net "IRQ_HSC_FAULT_N")
	)
	(segment
		(start 22.2758 2.415286)
		(end 22.2758 -23.5966)
		(width 0.10795)
		(layer "B.Cu")
		(net "IRQ_HSC_FAULT_N")
	)
	(segment
		(start 22.549358 2.688844)
		(end 22.2758 2.415286)
		(width 0.10795)
		(layer "B.Cu")
		(net "IRQ_HSC_FAULT_N")
	)
	(segment
		(start 415.399474 -93.76537)
		(end 415.399474 -88.863424)
		(width 0.089408)
		(layer "In2.Cu")
		(net "IRQ_HSC_FAULT_N")
	)
	(segment
		(start 26.846022 -43.559222)
		(end 26.846022 -33.59785)
		(width 0.089408)
		(layer "In2.Cu")
		(net "IRQ_HSC_FAULT_N")
	)
	(segment
		(start 330.327 -5.174488)
		(end 330.327 -11.5824)
		(width 0.089408)
		(layer "In2.Cu")
		(net "IRQ_HSC_FAULT_N")
	)
	(segment
		(start 418.602668 -71.160894)
		(end 418.602668 -65.026286)
		(width 0.089408)
		(layer "In2.Cu")
		(net "IRQ_HSC_FAULT_N")
	)
	(segment
		(start 417.768278 -82.954114)
		(end 417.768278 -82.479134)
		(width 0.089408)
		(layer "In2.Cu")
		(net "IRQ_HSC_FAULT_N")
	)
	(segment
		(start 418.370766 -71.392796)
		(end 418.602668 -71.160894)
		(width 0.089408)
		(layer "In2.Cu")
		(net "IRQ_HSC_FAULT_N")
	)
	(segment
		(start 418.370766 -75.829668)
		(end 418.371274 -75.82916)
		(width 0.089408)
		(layer "In2.Cu")
		(net "IRQ_HSC_FAULT_N")
	)
	(segment
		(start 464.906868 -58.843164)
		(end 465.95157 -57.798462)
		(width 0.089408)
		(layer "In2.Cu")
		(net "IRQ_HSC_FAULT_N")
	)
	(segment
		(start 436.64632 -60.263024)
		(end 437.62422 -61.240924)
		(width 0.089408)
		(layer "In2.Cu")
		(net "IRQ_HSC_FAULT_N")
	)
	(segment
		(start 427.256702 -59.863482)
		(end 430.49444 -63.10122)
		(width 0.089408)
		(layer "In2.Cu")
		(net "IRQ_HSC_FAULT_N")
	)
	(segment
		(start 23.9014 -48.06188)
		(end 23.9014 -46.503844)
		(width 0.089408)
		(layer "In2.Cu")
		(net "IRQ_HSC_FAULT_N")
	)
	(segment
		(start 179.68976 0.246634)
		(end 179.68976 3.61061)
		(width 0.089408)
		(layer "In2.Cu")
		(net "IRQ_HSC_FAULT_N")
	)
	(segment
		(start 179.396136 -1.490726)
		(end 179.396136 -0.04699)
		(width 0.089408)
		(layer "In2.Cu")
		(net "IRQ_HSC_FAULT_N")
	)
	(segment
		(start 171.939712 -2.457704)
		(end 178.390042 -2.457704)
		(width 0.089408)
		(layer "In2.Cu")
		(net "IRQ_HSC_FAULT_N")
	)
	(segment
		(start 167.381174 3.99542)
		(end 168.516554 3.99542)
		(width 0.089408)
		(layer "In2.Cu")
		(net "IRQ_HSC_FAULT_N")
	)
	(segment
		(start 417.768024 -82.47888)
		(end 417.768024 -76.568808)
		(width 0.089408)
		(layer "In2.Cu")
		(net "IRQ_HSC_FAULT_N")
	)
	(segment
		(start 330.261976 5.4864)
		(end 330.73848 5.009896)
		(width 0.089408)
		(layer "In2.Cu")
		(net "IRQ_HSC_FAULT_N")
	)
	(segment
		(start 26.60269 -31.964884)
		(end 26.60269 -31.089854)
		(width 0.089408)
		(layer "In2.Cu")
		(net "IRQ_HSC_FAULT_N")
	)
	(segment
		(start 330.327 -11.5824)
		(end 332.733904 -13.989304)
		(width 0.089408)
		(layer "In2.Cu")
		(net "IRQ_HSC_FAULT_N")
	)
	(segment
		(start 417.768024 -76.568808)
		(end 418.370766 -75.966066)
		(width 0.089408)
		(layer "In2.Cu")
		(net "IRQ_HSC_FAULT_N")
	)
	(segment
		(start 469.177116 -55.759604)
		(end 469.838532 -55.098188)
		(width 0.089408)
		(layer "In2.Cu")
		(net "IRQ_HSC_FAULT_N")
	)
	(segment
		(start 178.390042 -2.457704)
		(end 178.618134 -2.229612)
		(width 0.089408)
		(layer "In2.Cu")
		(net "IRQ_HSC_FAULT_N")
	)
	(segment
		(start 416.056318 -88.20658)
		(end 416.056318 -86.670134)
		(width 0.089408)
		(layer "In2.Cu")
		(net "IRQ_HSC_FAULT_N")
	)
	(segment
		(start 422.654222 -59.863482)
		(end 427.256702 -59.863482)
		(width 0.089408)
		(layer "In2.Cu")
		(net "IRQ_HSC_FAULT_N")
	)
	(segment
		(start 22.810216 -24.689816)
		(end 21.9964 -23.876)
		(width 0.089408)
		(layer "In2.Cu")
		(net "IRQ_HSC_FAULT_N")
	)
	(segment
		(start 20.635214 -54.015386)
		(end 22.479 -52.1716)
		(width 0.089408)
		(layer "In2.Cu")
		(net "IRQ_HSC_FAULT_N")
	)
	(segment
		(start 418.602922 -63.914782)
		(end 422.654222 -59.863482)
		(width 0.089408)
		(layer "In2.Cu")
		(net "IRQ_HSC_FAULT_N")
	)
	(segment
		(start 418.370766 -75.35418)
		(end 418.370766 -71.392796)
		(width 0.089408)
		(layer "In2.Cu")
		(net "IRQ_HSC_FAULT_N")
	)
	(segment
		(start 417.768024 -84.958428)
		(end 417.768024 -82.954368)
		(width 0.089408)
		(layer "In2.Cu")
		(net "IRQ_HSC_FAULT_N")
	)
	(segment
		(start 23.719028 3.858514)
		(end 114.991388 3.858514)
		(width 0.089408)
		(layer "In2.Cu")
		(net "IRQ_HSC_FAULT_N")
	)
	(segment
		(start 168.805352 0.676656)
		(end 171.939712 -2.457704)
		(width 0.089408)
		(layer "In2.Cu")
		(net "IRQ_HSC_FAULT_N")
	)
	(segment
		(start 472.572588 -55.098188)
		(end 472.757754 -55.283354)
		(width 0.089408)
		(layer "In2.Cu")
		(net "IRQ_HSC_FAULT_N")
	)
	(segment
		(start 464.906868 -59.772804)
		(end 464.906868 -58.843164)
		(width 0.089408)
		(layer "In2.Cu")
		(net "IRQ_HSC_FAULT_N")
	)
	(segment
		(start 415.399474 -88.863424)
		(end 416.056318 -88.20658)
		(width 0.089408)
		(layer "In2.Cu")
		(net "IRQ_HSC_FAULT_N")
	)
	(segment
		(start 418.370766 -75.966066)
		(end 418.370766 -75.829668)
		(width 0.089408)
		(layer "In2.Cu")
		(net "IRQ_HSC_FAULT_N")
	)
	(segment
		(start 418.371274 -75.512676)
		(end 418.37102 -75.512422)
		(width 0.089408)
		(layer "In2.Cu")
		(net "IRQ_HSC_FAULT_N")
	)
	(segment
		(start 418.602668 -65.026286)
		(end 418.602922 -65.026032)
		(width 0.089408)
		(layer "In2.Cu")
		(net "IRQ_HSC_FAULT_N")
	)
	(segment
		(start 415.714688 -109.62894)
		(end 415.9377 -109.405928)
		(width 0.089408)
		(layer "In2.Cu")
		(net "IRQ_HSC_FAULT_N")
	)
	(segment
		(start 168.516554 3.99542)
		(end 168.805352 3.706622)
		(width 0.089408)
		(layer "In2.Cu")
		(net "IRQ_HSC_FAULT_N")
	)
	(segment
		(start 330.079096 -4.926584)
		(end 330.327 -5.174488)
		(width 0.089408)
		(layer "In2.Cu")
		(net "IRQ_HSC_FAULT_N")
	)
	(segment
		(start 463.438748 -61.240924)
		(end 464.906868 -59.772804)
		(width 0.089408)
		(layer "In2.Cu")
		(net "IRQ_HSC_FAULT_N")
	)
	(segment
		(start 116.130578 4.997704)
		(end 166.37889 4.997704)
		(width 0.089408)
		(layer "In2.Cu")
		(net "IRQ_HSC_FAULT_N")
	)
	(segment
		(start 417.768024 -82.954368)
		(end 417.768278 -82.954114)
		(width 0.089408)
		(layer "In2.Cu")
		(net "IRQ_HSC_FAULT_N")
	)
	(segment
		(start 415.791142 -94.157038)
		(end 415.399474 -93.76537)
		(width 0.089408)
		(layer "In2.Cu")
		(net "IRQ_HSC_FAULT_N")
	)
	(segment
		(start 26.846022 -33.59785)
		(end 26.38044 -33.132268)
		(width 0.089408)
		(layer "In2.Cu")
		(net "IRQ_HSC_FAULT_N")
	)
	(segment
		(start 168.805352 3.706622)
		(end 168.805352 0.676656)
		(width 0.089408)
		(layer "In2.Cu")
		(net "IRQ_HSC_FAULT_N")
	)
	(segment
		(start 26.38044 -33.132268)
		(end 26.38044 -32.187134)
		(width 0.089408)
		(layer "In2.Cu")
		(net "IRQ_HSC_FAULT_N")
	)
	(segment
		(start 416.80638 -106.38917)
		(end 416.80638 -104.022906)
		(width 0.089408)
		(layer "In2.Cu")
		(net "IRQ_HSC_FAULT_N")
	)
	(segment
		(start 477.872298 -54.429152)
		(end 477.872298 -54.098952)
		(width 0.089408)
		(layer "In2.Cu")
		(net "IRQ_HSC_FAULT_N")
	)
	(segment
		(start 416.4965 -113.151158)
		(end 416.4965 -112.782604)
		(width 0.089408)
		(layer "In2.Cu")
		(net "IRQ_HSC_FAULT_N")
	)
	(segment
		(start 477.872298 -54.098952)
		(end 478.4852 -53.48605)
		(width 0.089408)
		(layer "In2.Cu")
		(net "IRQ_HSC_FAULT_N")
	)
	(segment
		(start 22.6568 -68.446396)
		(end 20.635214 -66.42481)
		(width 0.089408)
		(layer "In2.Cu")
		(net "IRQ_HSC_FAULT_N")
	)
	(segment
		(start 415.9377 -107.25785)
		(end 416.80638 -106.38917)
		(width 0.089408)
		(layer "In2.Cu")
		(net "IRQ_HSC_FAULT_N")
	)
	(segment
		(start 178.946556 -1.733296)
		(end 179.153566 -1.733296)
		(width 0.089408)
		(layer "In2.Cu")
		(net "IRQ_HSC_FAULT_N")
	)
	(segment
		(start 436.64632 -59.982608)
		(end 436.64632 -60.263024)
		(width 0.089408)
		(layer "In2.Cu")
		(net "IRQ_HSC_FAULT_N")
	)
	(segment
		(start 418.37102 -75.512422)
		(end 418.37102 -75.354434)
		(width 0.089408)
		(layer "In2.Cu")
		(net "IRQ_HSC_FAULT_N")
	)
	(segment
		(start 437.62422 -61.240924)
		(end 463.438748 -61.240924)
		(width 0.089408)
		(layer "In2.Cu")
		(net "IRQ_HSC_FAULT_N")
	)
	(segment
		(start 418.37102 -75.354434)
		(end 418.370766 -75.35418)
		(width 0.089408)
		(layer "In2.Cu")
		(net "IRQ_HSC_FAULT_N")
	)
	(segment
		(start 179.153566 -1.733296)
		(end 179.396136 -1.490726)
		(width 0.089408)
		(layer "In2.Cu")
		(net "IRQ_HSC_FAULT_N")
	)
	(segment
		(start 330.73848 5.009896)
		(end 330.73848 3.566922)
		(width 0.089408)
		(layer "In2.Cu")
		(net "IRQ_HSC_FAULT_N")
	)
	(segment
		(start 418.371274 -75.82916)
		(end 418.371274 -75.512676)
		(width 0.089408)
		(layer "In2.Cu")
		(net "IRQ_HSC_FAULT_N")
	)
	(segment
		(start 26.60269 -31.089854)
		(end 28.0416 -29.650944)
		(width 0.089408)
		(layer "In2.Cu")
		(net "IRQ_HSC_FAULT_N")
	)
	(segment
		(start 27.382216 -24.689816)
		(end 22.810216 -24.689816)
		(width 0.089408)
		(layer "In2.Cu")
		(net "IRQ_HSC_FAULT_N")
	)
	(segment
		(start 430.49444 -63.10122)
		(end 432.774344 -63.10122)
		(width 0.089408)
		(layer "In2.Cu")
		(net "IRQ_HSC_FAULT_N")
	)
	(segment
		(start 20.635214 -66.42481)
		(end 20.635214 -54.015386)
		(width 0.089408)
		(layer "In2.Cu")
		(net "IRQ_HSC_FAULT_N")
	)
	(segment
		(start 415.791142 -94.697042)
		(end 415.791142 -94.157038)
		(width 0.089408)
		(layer "In2.Cu")
		(net "IRQ_HSC_FAULT_N")
	)
	(segment
		(start 330.73848 3.566922)
		(end 330.079096 2.907538)
		(width 0.089408)
		(layer "In2.Cu")
		(net "IRQ_HSC_FAULT_N")
	)
	(segment
		(start 469.177116 -57.300114)
		(end 469.177116 -55.759604)
		(width 0.089408)
		(layer "In2.Cu")
		(net "IRQ_HSC_FAULT_N")
	)
	(segment
		(start 469.13927 -57.338214)
		(end 469.13927 -57.33796)
		(width 0.089408)
		(layer "In2.Cu")
		(net "IRQ_HSC_FAULT_N")
	)
	(segment
		(start 332.733904 -13.989304)
		(end 332.733904 -21.088096)
		(width 0.089408)
		(layer "In2.Cu")
		(net "IRQ_HSC_FAULT_N")
	)
	(segment
		(start 22.5044 -76.961238)
		(end 22.6568 -76.808838)
		(width 0.089408)
		(layer "In2.Cu")
		(net "IRQ_HSC_FAULT_N")
	)
	(segment
		(start 166.37889 4.997704)
		(end 167.381174 3.99542)
		(width 0.089408)
		(layer "In2.Cu")
		(net "IRQ_HSC_FAULT_N")
	)
	(segment
		(start 114.991388 3.858514)
		(end 116.130578 4.997704)
		(width 0.089408)
		(layer "In2.Cu")
		(net "IRQ_HSC_FAULT_N")
	)
	(segment
		(start 332.733904 -21.088096)
		(end 332.6638 -21.1582)
		(width 0.089408)
		(layer "In2.Cu")
		(net "IRQ_HSC_FAULT_N")
	)
	(segment
		(start 416.281108 -95.187008)
		(end 415.791142 -94.697042)
		(width 0.089408)
		(layer "In2.Cu")
		(net "IRQ_HSC_FAULT_N")
	)
	(segment
		(start 22.6568 -76.808838)
		(end 22.6568 -68.446396)
		(width 0.089408)
		(layer "In2.Cu")
		(net "IRQ_HSC_FAULT_N")
	)
	(segment
		(start 475.931992 -55.283354)
		(end 476.54464 -54.670706)
		(width 0.089408)
		(layer "In2.Cu")
		(net "IRQ_HSC_FAULT_N")
	)
	(segment
		(start 28.0416 -29.650944)
		(end 28.0416 -25.3492)
		(width 0.089408)
		(layer "In2.Cu")
		(net "IRQ_HSC_FAULT_N")
	)
	(segment
		(start 476.54464 -54.670706)
		(end 477.630744 -54.670706)
		(width 0.089408)
		(layer "In2.Cu")
		(net "IRQ_HSC_FAULT_N")
	)
	(segment
		(start 330.079096 2.907538)
		(end 330.079096 -4.926584)
		(width 0.089408)
		(layer "In2.Cu")
		(net "IRQ_HSC_FAULT_N")
	)
	(segment
		(start 469.13927 -57.33796)
		(end 469.177116 -57.300114)
		(width 0.089408)
		(layer "In2.Cu")
		(net "IRQ_HSC_FAULT_N")
	)
	(segment
		(start 469.838532 -55.098188)
		(end 472.572588 -55.098188)
		(width 0.089408)
		(layer "In2.Cu")
		(net "IRQ_HSC_FAULT_N")
	)
	(segment
		(start 416.4965 -112.782604)
		(end 415.714688 -112.000792)
		(width 0.089408)
		(layer "In2.Cu")
		(net "IRQ_HSC_FAULT_N")
	)
	(segment
		(start 22.549358 2.688844)
		(end 23.719028 3.858514)
		(width 0.089408)
		(layer "In2.Cu")
		(net "IRQ_HSC_FAULT_N")
	)
	(segment
		(start 178.618134 -2.229612)
		(end 178.618134 -2.061718)
		(width 0.089408)
		(layer "In2.Cu")
		(net "IRQ_HSC_FAULT_N")
	)
	(segment
		(start 416.281108 -103.497634)
		(end 416.281108 -95.187008)
		(width 0.089408)
		(layer "In2.Cu")
		(net "IRQ_HSC_FAULT_N")
	)
	(segment
		(start 28.0416 -25.3492)
		(end 27.382216 -24.689816)
		(width 0.089408)
		(layer "In2.Cu")
		(net "IRQ_HSC_FAULT_N")
	)
	(segment
		(start 416.056318 -86.670134)
		(end 417.768024 -84.958428)
		(width 0.089408)
		(layer "In2.Cu")
		(net "IRQ_HSC_FAULT_N")
	)
	(segment
		(start 477.630744 -54.670706)
		(end 477.872298 -54.429152)
		(width 0.089408)
		(layer "In2.Cu")
		(net "IRQ_HSC_FAULT_N")
	)
	(segment
		(start 417.768278 -82.479134)
		(end 417.768024 -82.47888)
		(width 0.089408)
		(layer "In2.Cu")
		(net "IRQ_HSC_FAULT_N")
	)
	(segment
		(start 22.479 -52.1716)
		(end 22.479 -49.48428)
		(width 0.089408)
		(layer "In2.Cu")
		(net "IRQ_HSC_FAULT_N")
	)
	(segment
		(start 415.714688 -112.000792)
		(end 415.714688 -109.62894)
		(width 0.089408)
		(layer "In2.Cu")
		(net "IRQ_HSC_FAULT_N")
	)
	(segment
		(start 468.679022 -57.798462)
		(end 469.13927 -57.338214)
		(width 0.089408)
		(layer "In2.Cu")
		(net "IRQ_HSC_FAULT_N")
	)
	(segment
		(start 179.68976 3.61061)
		(end 181.56555 5.4864)
		(width 0.089408)
		(layer "In2.Cu")
		(net "IRQ_HSC_FAULT_N")
	)
	(segment
		(start 432.774344 -63.10122)
		(end 435.892956 -59.982608)
		(width 0.089408)
		(layer "In2.Cu")
		(net "IRQ_HSC_FAULT_N")
	)
	(segment
		(start 435.892956 -59.982608)
		(end 436.64632 -59.982608)
		(width 0.089408)
		(layer "In2.Cu")
		(net "IRQ_HSC_FAULT_N")
	)
	(segment
		(start 22.479 -49.48428)
		(end 23.9014 -48.06188)
		(width 0.089408)
		(layer "In2.Cu")
		(net "IRQ_HSC_FAULT_N")
	)
	(segment
		(start 179.396136 -0.04699)
		(end 179.68976 0.246634)
		(width 0.089408)
		(layer "In2.Cu")
		(net "IRQ_HSC_FAULT_N")
	)
	(segment
		(start 181.56555 5.4864)
		(end 330.261976 5.4864)
		(width 0.089408)
		(layer "In2.Cu")
		(net "IRQ_HSC_FAULT_N")
	)
	(segment
		(start 23.9014 -46.503844)
		(end 26.846022 -43.559222)
		(width 0.089408)
		(layer "In2.Cu")
		(net "IRQ_HSC_FAULT_N")
	)
	(segment
		(start 415.9377 -109.405928)
		(end 415.9377 -107.25785)
		(width 0.089408)
		(layer "In2.Cu")
		(net "IRQ_HSC_FAULT_N")
	)
	(segment
		(start 418.602922 -65.026032)
		(end 418.602922 -63.914782)
		(width 0.089408)
		(layer "In2.Cu")
		(net "IRQ_HSC_FAULT_N")
	)
	(segment
		(start 26.38044 -32.187134)
		(end 26.60269 -31.964884)
		(width 0.089408)
		(layer "In2.Cu")
		(net "IRQ_HSC_FAULT_N")
	)
	(segment
		(start 472.757754 -55.283354)
		(end 475.931992 -55.283354)
		(width 0.089408)
		(layer "In2.Cu")
		(net "IRQ_HSC_FAULT_N")
	)
	(segment
		(start 178.618134 -2.061718)
		(end 178.946556 -1.733296)
		(width 0.089408)
		(layer "In2.Cu")
		(net "IRQ_HSC_FAULT_N")
	)
	(segment
		(start 416.80638 -104.022906)
		(end 416.281108 -103.497634)
		(width 0.089408)
		(layer "In2.Cu")
		(net "IRQ_HSC_FAULT_N")
	)
	(segment
		(start 465.95157 -57.798462)
		(end 468.679022 -57.798462)
		(width 0.089408)
		(layer "In2.Cu")
		(net "IRQ_HSC_FAULT_N")
	)
	(segment
		(start 402.35378 -113.875312)
		(end 409.541218 -113.875312)
		(width 0.0889)
		(layer "In9.Cu")
		(net "IRQ_HSC_FAULT_N")
	)
	(segment
		(start 397.065754 -113.1062)
		(end 398.576038 -113.1062)
		(width 0.089408)
		(layer "In9.Cu")
		(net "IRQ_HSC_FAULT_N")
	)
	(segment
		(start 400.97202 -113.3856)
		(end 401.461732 -113.875312)
		(width 0.089408)
		(layer "In9.Cu")
		(net "IRQ_HSC_FAULT_N")
	)
	(segment
		(start 409.89504 -112.658906)
		(end 411.258004 -111.295942)
		(width 0.0889)
		(layer "In9.Cu")
		(net "IRQ_HSC_FAULT_N")
	)
	(segment
		(start 409.541218 -113.875312)
		(end 409.89504 -113.52149)
		(width 0.0889)
		(layer "In9.Cu")
		(net "IRQ_HSC_FAULT_N")
	)
	(segment
		(start 411.258004 -111.295942)
		(end 414.133284 -111.295942)
		(width 0.0889)
		(layer "In9.Cu")
		(net "IRQ_HSC_FAULT_N")
	)
	(segment
		(start 398.95018 -113.26114)
		(end 399.07464 -113.3856)
		(width 0.089408)
		(layer "In9.Cu")
		(net "IRQ_HSC_FAULT_N")
	)
	(segment
		(start 399.07464 -113.3856)
		(end 400.97202 -113.3856)
		(width 0.089408)
		(layer "In9.Cu")
		(net "IRQ_HSC_FAULT_N")
	)
	(segment
		(start 415.9885 -113.151158)
		(end 416.4965 -113.151158)
		(width 0.0889)
		(layer "In9.Cu")
		(net "IRQ_HSC_FAULT_N")
	)
	(segment
		(start 396.65275 -113.519204)
		(end 397.065754 -113.1062)
		(width 0.089408)
		(layer "In9.Cu")
		(net "IRQ_HSC_FAULT_N")
	)
	(segment
		(start 401.461732 -113.875312)
		(end 402.35378 -113.875312)
		(width 0.089408)
		(layer "In9.Cu")
		(net "IRQ_HSC_FAULT_N")
	)
	(segment
		(start 409.89504 -113.52149)
		(end 409.89504 -112.658906)
		(width 0.0889)
		(layer "In9.Cu")
		(net "IRQ_HSC_FAULT_N")
	)
	(segment
		(start 414.133284 -111.295942)
		(end 415.9885 -113.151158)
		(width 0.0889)
		(layer "In9.Cu")
		(net "IRQ_HSC_FAULT_N")
	)
	(arc
		(start 398.576038 -113.1062)
		(mid 398.778509 -113.146474)
		(end 398.95018 -113.26114)
		(width 0.089408)
		(layer "In9.Cu")
		(net "IRQ_HSC_FAULT_N")
	)
	(segment
		(start 478.4852 -52.40528)
		(end 478.4852 -53.48605)
		(width 0.089408)
		(layer "In11.Cu")
		(net "IRQ_HSC_FAULT_N")
	)
	(segment
		(start 474.104208 -12.380468)
		(end 474.104208 -18.018252)
		(width 0.089408)
		(layer "In11.Cu")
		(net "IRQ_HSC_FAULT_N")
	)
	(segment
		(start 469.2142 -2.8194)
		(end 469.837008 -2.8194)
		(width 0.089408)
		(layer "In11.Cu")
		(net "IRQ_HSC_FAULT_N")
	)
	(segment
		(start 436.64632 -59.804554)
		(end 435.953408 -59.111642)
		(width 0.089408)
		(layer "In11.Cu")
		(net "IRQ_HSC_FAULT_N")
	)
	(segment
		(start 355.496876 -35.955224)
		(end 363.720634 -27.731466)
		(width 0.089408)
		(layer "In11.Cu")
		(net "IRQ_HSC_FAULT_N")
	)
	(segment
		(start 475.722188 -33.52673)
		(end 476.42272 -34.227262)
		(width 0.089408)
		(layer "In11.Cu")
		(net "IRQ_HSC_FAULT_N")
	)
	(segment
		(start 417.994592 -4.610608)
		(end 424.428412 -4.610608)
		(width 0.089408)
		(layer "In11.Cu")
		(net "IRQ_HSC_FAULT_N")
	)
	(segment
		(start 440.759088 -3.570986)
		(end 447.1924 -3.570986)
		(width 0.089408)
		(layer "In11.Cu")
		(net "IRQ_HSC_FAULT_N")
	)
	(segment
		(start 363.720634 -27.731466)
		(end 363.720634 -19.739102)
		(width 0.089408)
		(layer "In11.Cu")
		(net "IRQ_HSC_FAULT_N")
	)
	(segment
		(start 468.4014 -2.0066)
		(end 469.2142 -2.8194)
		(width 0.089408)
		(layer "In11.Cu")
		(net "IRQ_HSC_FAULT_N")
	)
	(segment
		(start 474.26118 -25.604724)
		(end 474.185996 -25.679908)
		(width 0.089408)
		(layer "In11.Cu")
		(net "IRQ_HSC_FAULT_N")
	)
	(segment
		(start 475.957646 -39.858696)
		(end 476.043498 -39.944548)
		(width 0.089408)
		(layer "In11.Cu")
		(net "IRQ_HSC_FAULT_N")
	)
	(segment
		(start 448.26428 -3.570732)
		(end 450.991732 -0.84328)
		(width 0.089408)
		(layer "In11.Cu")
		(net "IRQ_HSC_FAULT_N")
	)
	(segment
		(start 464.006692 0.663956)
		(end 465.0232 -0.352552)
		(width 0.089408)
		(layer "In11.Cu")
		(net "IRQ_HSC_FAULT_N")
	)
	(segment
		(start 404.97887 -6.378702)
		(end 404.97887 -5.66293)
		(width 0.089408)
		(layer "In11.Cu")
		(net "IRQ_HSC_FAULT_N")
	)
	(segment
		(start 471.732864 -3.033268)
		(end 473.787724 -5.088128)
		(width 0.089408)
		(layer "In11.Cu")
		(net "IRQ_HSC_FAULT_N")
	)
	(segment
		(start 426.39996 -46.395386)
		(end 426.400214 -46.395132)
		(width 0.089408)
		(layer "In11.Cu")
		(net "IRQ_HSC_FAULT_N")
	)
	(segment
		(start 426.865034 -48.090328)
		(end 426.400214 -47.625508)
		(width 0.089408)
		(layer "In11.Cu")
		(net "IRQ_HSC_FAULT_N")
	)
	(segment
		(start 473.992702 -6.021832)
		(end 473.992702 -8.278622)
		(width 0.089408)
		(layer "In11.Cu")
		(net "IRQ_HSC_FAULT_N")
	)
	(segment
		(start 475.335092 -11.149584)
		(end 474.104208 -12.380468)
		(width 0.089408)
		(layer "In11.Cu")
		(net "IRQ_HSC_FAULT_N")
	)
	(segment
		(start 461.020922 -1.274064)
		(end 461.426814 -0.868172)
		(width 0.089408)
		(layer "In11.Cu")
		(net "IRQ_HSC_FAULT_N")
	)
	(segment
		(start 474.250004 -5.76453)
		(end 473.992702 -6.021832)
		(width 0.089408)
		(layer "In11.Cu")
		(net "IRQ_HSC_FAULT_N")
	)
	(segment
		(start 373.113046 -7.823708)
		(end 376.031252 -7.823708)
		(width 0.089408)
		(layer "In11.Cu")
		(net "IRQ_HSC_FAULT_N")
	)
	(segment
		(start 477.163384 -48.24095)
		(end 477.163384 -51.083464)
		(width 0.089408)
		(layer "In11.Cu")
		(net "IRQ_HSC_FAULT_N")
	)
	(segment
		(start 469.837008 -2.8194)
		(end 470.050876 -3.033268)
		(width 0.089408)
		(layer "In11.Cu")
		(net "IRQ_HSC_FAULT_N")
	)
	(segment
		(start 476.42272 -34.227262)
		(end 476.42272 -37.673026)
		(width 0.089408)
		(layer "In11.Cu")
		(net "IRQ_HSC_FAULT_N")
	)
	(segment
		(start 477.163384 -51.083464)
		(end 478.4852 -52.40528)
		(width 0.089408)
		(layer "In11.Cu")
		(net "IRQ_HSC_FAULT_N")
	)
	(segment
		(start 404.97887 -5.66293)
		(end 405.497792 -5.144008)
		(width 0.089408)
		(layer "In11.Cu")
		(net "IRQ_HSC_FAULT_N")
	)
	(segment
		(start 428.935388 -50.40249)
		(end 428.935388 -48.601376)
		(width 0.089408)
		(layer "In11.Cu")
		(net "IRQ_HSC_FAULT_N")
	)
	(segment
		(start 465.7598 -2.0066)
		(end 468.4014 -2.0066)
		(width 0.089408)
		(layer "In11.Cu")
		(net "IRQ_HSC_FAULT_N")
	)
	(segment
		(start 474.185996 -27.433524)
		(end 475.722188 -28.969716)
		(width 0.089408)
		(layer "In11.Cu")
		(net "IRQ_HSC_FAULT_N")
	)
	(segment
		(start 461.98409 0.057912)
		(end 462.482946 0.057912)
		(width 0.089408)
		(layer "In11.Cu")
		(net "IRQ_HSC_FAULT_N")
	)
	(segment
		(start 450.991732 -0.84328)
		(end 459.73746 -0.84328)
		(width 0.089408)
		(layer "In11.Cu")
		(net "IRQ_HSC_FAULT_N")
	)
	(segment
		(start 422.06291 -40.937942)
		(end 417.556696 -40.937942)
		(width 0.089408)
		(layer "In11.Cu")
		(net "IRQ_HSC_FAULT_N")
	)
	(segment
		(start 460.16799 -1.27381)
		(end 460.778352 -1.27381)
		(width 0.089408)
		(layer "In11.Cu")
		(net "IRQ_HSC_FAULT_N")
	)
	(segment
		(start 428.42434 -48.090328)
		(end 426.865034 -48.090328)
		(width 0.089408)
		(layer "In11.Cu")
		(net "IRQ_HSC_FAULT_N")
	)
	(segment
		(start 414.8074 -5.892546)
		(end 416.712654 -5.892546)
		(width 0.089408)
		(layer "In11.Cu")
		(net "IRQ_HSC_FAULT_N")
	)
	(segment
		(start 435.953662 -57.66308)
		(end 435.953662 -57.420764)
		(width 0.089408)
		(layer "In11.Cu")
		(net "IRQ_HSC_FAULT_N")
	)
	(segment
		(start 331.887576 -21.934424)
		(end 331.887576 -31.079948)
		(width 0.089408)
		(layer "In11.Cu")
		(net "IRQ_HSC_FAULT_N")
	)
	(segment
		(start 425.493688 -44.270422)
		(end 425.095924 -44.270422)
		(width 0.089408)
		(layer "In11.Cu")
		(net "IRQ_HSC_FAULT_N")
	)
	(segment
		(start 336.50428 -35.696652)
		(end 337.583018 -35.696652)
		(width 0.089408)
		(layer "In11.Cu")
		(net "IRQ_HSC_FAULT_N")
	)
	(segment
		(start 474.104208 -18.018252)
		(end 474.758258 -18.672302)
		(width 0.089408)
		(layer "In11.Cu")
		(net "IRQ_HSC_FAULT_N")
	)
	(segment
		(start 460.778606 -1.274064)
		(end 461.020922 -1.274064)
		(width 0.089408)
		(layer "In11.Cu")
		(net "IRQ_HSC_FAULT_N")
	)
	(segment
		(start 417.556696 -40.937942)
		(end 417.156392 -41.338246)
		(width 0.089408)
		(layer "In11.Cu")
		(net "IRQ_HSC_FAULT_N")
	)
	(segment
		(start 424.885612 -4.153408)
		(end 440.176666 -4.153408)
		(width 0.089408)
		(layer "In11.Cu")
		(net "IRQ_HSC_FAULT_N")
	)
	(segment
		(start 474.185996 -25.679908)
		(end 474.185996 -27.433524)
		(width 0.089408)
		(layer "In11.Cu")
		(net "IRQ_HSC_FAULT_N")
	)
	(segment
		(start 426.400214 -47.625508)
		(end 426.400214 -47.385224)
		(width 0.089408)
		(layer "In11.Cu")
		(net "IRQ_HSC_FAULT_N")
	)
	(segment
		(start 459.73746 -0.84328)
		(end 460.16799 -1.27381)
		(width 0.089408)
		(layer "In11.Cu")
		(net "IRQ_HSC_FAULT_N")
	)
	(segment
		(start 440.176666 -4.153408)
		(end 440.759088 -3.570986)
		(width 0.089408)
		(layer "In11.Cu")
		(net "IRQ_HSC_FAULT_N")
	)
	(segment
		(start 331.887576 -31.079948)
		(end 336.50428 -35.696652)
		(width 0.089408)
		(layer "In11.Cu")
		(net "IRQ_HSC_FAULT_N")
	)
	(segment
		(start 428.935388 -48.601376)
		(end 428.42434 -48.090328)
		(width 0.089408)
		(layer "In11.Cu")
		(net "IRQ_HSC_FAULT_N")
	)
	(segment
		(start 476.043498 -39.944548)
		(end 476.043498 -43.665902)
		(width 0.089408)
		(layer "In11.Cu")
		(net "IRQ_HSC_FAULT_N")
	)
	(segment
		(start 376.031252 -7.823708)
		(end 378.690378 -10.482834)
		(width 0.089408)
		(layer "In11.Cu")
		(net "IRQ_HSC_FAULT_N")
	)
	(segment
		(start 474.250004 -5.41147)
		(end 474.250004 -5.76453)
		(width 0.089408)
		(layer "In11.Cu")
		(net "IRQ_HSC_FAULT_N")
	)
	(segment
		(start 465.0232 -1.27)
		(end 465.7598 -2.0066)
		(width 0.089408)
		(layer "In11.Cu")
		(net "IRQ_HSC_FAULT_N")
	)
	(segment
		(start 475.44482 -44.26458)
		(end 475.44482 -46.522386)
		(width 0.089408)
		(layer "In11.Cu")
		(net "IRQ_HSC_FAULT_N")
	)
	(segment
		(start 403.779736 -7.577836)
		(end 404.97887 -6.378702)
		(width 0.089408)
		(layer "In11.Cu")
		(net "IRQ_HSC_FAULT_N")
	)
	(segment
		(start 337.583018 -35.696652)
		(end 337.84159 -35.955224)
		(width 0.089408)
		(layer "In11.Cu")
		(net "IRQ_HSC_FAULT_N")
	)
	(segment
		(start 476.42272 -37.673026)
		(end 475.957646 -38.1381)
		(width 0.089408)
		(layer "In11.Cu")
		(net "IRQ_HSC_FAULT_N")
	)
	(segment
		(start 426.400214 -46.395132)
		(end 426.400214 -45.176948)
		(width 0.089408)
		(layer "In11.Cu")
		(net "IRQ_HSC_FAULT_N")
	)
	(segment
		(start 426.400214 -47.385224)
		(end 426.39996 -47.38497)
		(width 0.089408)
		(layer "In11.Cu")
		(net "IRQ_HSC_FAULT_N")
	)
	(segment
		(start 474.758258 -18.672302)
		(end 474.758258 -25.107392)
		(width 0.089408)
		(layer "In11.Cu")
		(net "IRQ_HSC_FAULT_N")
	)
	(segment
		(start 476.043498 -43.665902)
		(end 475.44482 -44.26458)
		(width 0.089408)
		(layer "In11.Cu")
		(net "IRQ_HSC_FAULT_N")
	)
	(segment
		(start 436.64632 -59.982608)
		(end 436.64632 -59.804554)
		(width 0.089408)
		(layer "In11.Cu")
		(net "IRQ_HSC_FAULT_N")
	)
	(segment
		(start 474.758258 -25.107392)
		(end 474.26118 -25.60447)
		(width 0.089408)
		(layer "In11.Cu")
		(net "IRQ_HSC_FAULT_N")
	)
	(segment
		(start 435.953662 -57.420764)
		(end 428.935388 -50.40249)
		(width 0.089408)
		(layer "In11.Cu")
		(net "IRQ_HSC_FAULT_N")
	)
	(segment
		(start 424.428412 -4.610608)
		(end 424.885612 -4.153408)
		(width 0.089408)
		(layer "In11.Cu")
		(net "IRQ_HSC_FAULT_N")
	)
	(segment
		(start 475.722188 -28.969716)
		(end 475.722188 -33.52673)
		(width 0.089408)
		(layer "In11.Cu")
		(net "IRQ_HSC_FAULT_N")
	)
	(segment
		(start 426.39996 -47.38497)
		(end 426.39996 -46.395386)
		(width 0.089408)
		(layer "In11.Cu")
		(net "IRQ_HSC_FAULT_N")
	)
	(segment
		(start 378.690378 -10.482834)
		(end 392.99515 -10.482834)
		(width 0.089408)
		(layer "In11.Cu")
		(net "IRQ_HSC_FAULT_N")
	)
	(segment
		(start 332.6638 -21.1582)
		(end 331.887576 -21.934424)
		(width 0.089408)
		(layer "In11.Cu")
		(net "IRQ_HSC_FAULT_N")
	)
	(segment
		(start 474.26118 -25.60447)
		(end 474.26118 -25.604724)
		(width 0.089408)
		(layer "In11.Cu")
		(net "IRQ_HSC_FAULT_N")
	)
	(segment
		(start 475.44482 -46.522386)
		(end 477.163384 -48.24095)
		(width 0.089408)
		(layer "In11.Cu")
		(net "IRQ_HSC_FAULT_N")
	)
	(segment
		(start 337.84159 -35.955224)
		(end 355.496876 -35.955224)
		(width 0.089408)
		(layer "In11.Cu")
		(net "IRQ_HSC_FAULT_N")
	)
	(segment
		(start 475.335092 -9.621012)
		(end 475.335092 -11.149584)
		(width 0.089408)
		(layer "In11.Cu")
		(net "IRQ_HSC_FAULT_N")
	)
	(segment
		(start 473.992702 -8.278622)
		(end 475.335092 -9.621012)
		(width 0.089408)
		(layer "In11.Cu")
		(net "IRQ_HSC_FAULT_N")
	)
	(segment
		(start 461.426814 -0.868172)
		(end 461.426814 -0.499364)
		(width 0.089408)
		(layer "In11.Cu")
		(net "IRQ_HSC_FAULT_N")
	)
	(segment
		(start 460.778352 -1.27381)
		(end 460.778606 -1.274064)
		(width 0.089408)
		(layer "In11.Cu")
		(net "IRQ_HSC_FAULT_N")
	)
	(segment
		(start 422.90492 -42.079418)
		(end 422.90492 -41.779952)
		(width 0.089408)
		(layer "In11.Cu")
		(net "IRQ_HSC_FAULT_N")
	)
	(segment
		(start 417.156392 -41.338246)
		(end 417.093654 -41.338246)
		(width 0.089408)
		(layer "In11.Cu")
		(net "IRQ_HSC_FAULT_N")
	)
	(segment
		(start 416.712654 -5.892546)
		(end 417.994592 -4.610608)
		(width 0.089408)
		(layer "In11.Cu")
		(net "IRQ_HSC_FAULT_N")
	)
	(segment
		(start 426.400214 -45.176948)
		(end 425.493688 -44.270422)
		(width 0.089408)
		(layer "In11.Cu")
		(net "IRQ_HSC_FAULT_N")
	)
	(segment
		(start 447.1924 -3.570986)
		(end 447.192654 -3.570732)
		(width 0.089408)
		(layer "In11.Cu")
		(net "IRQ_HSC_FAULT_N")
	)
	(segment
		(start 447.192654 -3.570732)
		(end 448.26428 -3.570732)
		(width 0.089408)
		(layer "In11.Cu")
		(net "IRQ_HSC_FAULT_N")
	)
	(segment
		(start 405.497792 -5.144008)
		(end 414.058862 -5.144008)
		(width 0.089408)
		(layer "In11.Cu")
		(net "IRQ_HSC_FAULT_N")
	)
	(segment
		(start 465.0232 -0.352552)
		(end 465.0232 -1.27)
		(width 0.089408)
		(layer "In11.Cu")
		(net "IRQ_HSC_FAULT_N")
	)
	(segment
		(start 372.358666 -11.10107)
		(end 372.358666 -8.578088)
		(width 0.089408)
		(layer "In11.Cu")
		(net "IRQ_HSC_FAULT_N")
	)
	(segment
		(start 470.050876 -3.033268)
		(end 471.732864 -3.033268)
		(width 0.089408)
		(layer "In11.Cu")
		(net "IRQ_HSC_FAULT_N")
	)
	(segment
		(start 372.358666 -8.578088)
		(end 373.113046 -7.823708)
		(width 0.089408)
		(layer "In11.Cu")
		(net "IRQ_HSC_FAULT_N")
	)
	(segment
		(start 414.058862 -5.144008)
		(end 414.8074 -5.892546)
		(width 0.089408)
		(layer "In11.Cu")
		(net "IRQ_HSC_FAULT_N")
	)
	(segment
		(start 473.787724 -5.088128)
		(end 473.926662 -5.088128)
		(width 0.089408)
		(layer "In11.Cu")
		(net "IRQ_HSC_FAULT_N")
	)
	(segment
		(start 462.482946 0.057912)
		(end 463.08899 0.663956)
		(width 0.089408)
		(layer "In11.Cu")
		(net "IRQ_HSC_FAULT_N")
	)
	(segment
		(start 473.926662 -5.088128)
		(end 474.250004 -5.41147)
		(width 0.089408)
		(layer "In11.Cu")
		(net "IRQ_HSC_FAULT_N")
	)
	(segment
		(start 395.900148 -7.577836)
		(end 403.779736 -7.577836)
		(width 0.089408)
		(layer "In11.Cu")
		(net "IRQ_HSC_FAULT_N")
	)
	(segment
		(start 422.90492 -41.779952)
		(end 422.06291 -40.937942)
		(width 0.089408)
		(layer "In11.Cu")
		(net "IRQ_HSC_FAULT_N")
	)
	(segment
		(start 392.99515 -10.482834)
		(end 395.900148 -7.577836)
		(width 0.089408)
		(layer "In11.Cu")
		(net "IRQ_HSC_FAULT_N")
	)
	(segment
		(start 463.08899 0.663956)
		(end 464.006692 0.663956)
		(width 0.089408)
		(layer "In11.Cu")
		(net "IRQ_HSC_FAULT_N")
	)
	(segment
		(start 461.426814 -0.499364)
		(end 461.98409 0.057912)
		(width 0.089408)
		(layer "In11.Cu")
		(net "IRQ_HSC_FAULT_N")
	)
	(segment
		(start 363.720634 -19.739102)
		(end 372.358666 -11.10107)
		(width 0.089408)
		(layer "In11.Cu")
		(net "IRQ_HSC_FAULT_N")
	)
	(segment
		(start 435.953408 -57.663334)
		(end 435.953662 -57.66308)
		(width 0.089408)
		(layer "In11.Cu")
		(net "IRQ_HSC_FAULT_N")
	)
	(segment
		(start 425.095924 -44.270422)
		(end 422.90492 -42.079418)
		(width 0.089408)
		(layer "In11.Cu")
		(net "IRQ_HSC_FAULT_N")
	)
	(segment
		(start 475.957646 -38.1381)
		(end 475.957646 -39.858696)
		(width 0.089408)
		(layer "In11.Cu")
		(net "IRQ_HSC_FAULT_N")
	)
	(segment
		(start 435.953408 -59.111642)
		(end 435.953408 -57.663334)
		(width 0.089408)
		(layer "In11.Cu")
		(net "IRQ_HSC_FAULT_N")
	)
	(segment
		(start 459.7908 -130.3782)
		(end 461.0227 -130.3782)
		(width 0.10795)
		(layer "F.Cu")
		(net "FM_CPU1_SKTOCC_LVT3_N")
	)
	(segment
		(start 424.340528 -46.866048)
		(end 423.863008 -46.388528)
		(width 0.10795)
		(layer "F.Cu")
		(net "FM_CPU1_SKTOCC_LVT3_N")
	)
	(segment
		(start 422.661842 -43.48861)
		(end 422.661842 -42.906188)
		(width 0.10795)
		(layer "F.Cu")
		(net "FM_CPU1_SKTOCC_LVT3_N")
	)
	(segment
		(start 423.863008 -46.388528)
		(end 423.863008 -45.324268)
		(width 0.10795)
		(layer "F.Cu")
		(net "FM_CPU1_SKTOCC_LVT3_N")
	)
	(segment
		(start 422.499536 -43.650916)
		(end 422.661842 -43.48861)
		(width 0.10795)
		(layer "F.Cu")
		(net "FM_CPU1_SKTOCC_LVT3_N")
	)
	(segment
		(start 465.396326 -123.548394)
		(end 465.396326 -122.105674)
		(width 0.10795)
		(layer "F.Cu")
		(net "FM_CPU1_SKTOCC_LVT3_N")
	)
	(segment
		(start 422.661842 -42.906188)
		(end 422.29024 -42.534586)
		(width 0.10795)
		(layer "F.Cu")
		(net "FM_CPU1_SKTOCC_LVT3_N")
	)
	(segment
		(start 377.83135 -98.69424)
		(end 378.32665 -98.464116)
		(width 0.10795)
		(layer "F.Cu")
		(net "FM_CPU1_SKTOCC_LVT3_N")
	)
	(segment
		(start 465.396326 -122.105674)
		(end 466.6742 -120.8278)
		(width 0.10795)
		(layer "F.Cu")
		(net "FM_CPU1_SKTOCC_LVT3_N")
	)
	(segment
		(start 131.948174 -61.847984)
		(end 132.519674 -61.847984)
		(width 0.1016)
		(layer "F.Cu")
		(net "FM_CPU1_SKTOCC_LVT3_N")
	)
	(segment
		(start 461.0227 -130.3782)
		(end 461.8355 -129.5654)
		(width 0.10795)
		(layer "F.Cu")
		(net "FM_CPU1_SKTOCC_LVT3_N")
	)
	(segment
		(start 461.8355 -129.5654)
		(end 461.8355 -127.10922)
		(width 0.10795)
		(layer "F.Cu")
		(net "FM_CPU1_SKTOCC_LVT3_N")
	)
	(segment
		(start 424.169078 -49.039018)
		(end 424.169078 -47.874174)
		(width 0.10795)
		(layer "F.Cu")
		(net "FM_CPU1_SKTOCC_LVT3_N")
	)
	(segment
		(start 370.4336 -80.783684)
		(end 370.4336 -80.899)
		(width 0.1016)
		(layer "F.Cu")
		(net "FM_CPU1_SKTOCC_LVT3_N")
	)
	(segment
		(start 461.8355 -127.10922)
		(end 465.396326 -123.548394)
		(width 0.10795)
		(layer "F.Cu")
		(net "FM_CPU1_SKTOCC_LVT3_N")
	)
	(segment
		(start 466.6742 -120.8278)
		(end 466.6742 -119.958104)
		(width 0.10795)
		(layer "F.Cu")
		(net "FM_CPU1_SKTOCC_LVT3_N")
	)
	(segment
		(start 369.944904 -80.294988)
		(end 370.4336 -80.783684)
		(width 0.1016)
		(layer "F.Cu")
		(net "FM_CPU1_SKTOCC_LVT3_N")
	)
	(segment
		(start 423.863008 -45.324268)
		(end 422.499536 -43.960796)
		(width 0.10795)
		(layer "F.Cu")
		(net "FM_CPU1_SKTOCC_LVT3_N")
	)
	(segment
		(start 424.169078 -47.874174)
		(end 424.340528 -47.702724)
		(width 0.10795)
		(layer "F.Cu")
		(net "FM_CPU1_SKTOCC_LVT3_N")
	)
	(segment
		(start 422.499536 -43.960796)
		(end 422.499536 -43.650916)
		(width 0.10795)
		(layer "F.Cu")
		(net "FM_CPU1_SKTOCC_LVT3_N")
	)
	(segment
		(start 424.141646 -49.039018)
		(end 424.169078 -49.039018)
		(width 0.10795)
		(layer "F.Cu")
		(net "FM_CPU1_SKTOCC_LVT3_N")
	)
	(segment
		(start 424.340528 -47.702724)
		(end 424.340528 -46.866048)
		(width 0.10795)
		(layer "F.Cu")
		(net "FM_CPU1_SKTOCC_LVT3_N")
	)
	(via
		(at 378.32665 -98.464116)
		(size 0.508)
		(drill 0.254)
		(layers "F.Cu" "B.Cu")
		(net "FM_CPU1_SKTOCC_LVT3_N")
	)
	(via
		(at 459.7908 -130.3782)
		(size 0.508)
		(drill 0.254)
		(layers "F.Cu" "B.Cu")
		(net "FM_CPU1_SKTOCC_LVT3_N")
	)
	(via
		(at 424.141646 -49.039018)
		(size 0.508)
		(drill 0.254)
		(layers "F.Cu" "B.Cu")
		(net "FM_CPU1_SKTOCC_LVT3_N")
	)
	(via
		(at 165.41369 -63.28791)
		(size 0.508)
		(drill 0.254)
		(layers "F.Cu" "B.Cu")
		(net "FM_CPU1_SKTOCC_LVT3_N")
	)
	(via
		(at 353.949 -54.1655)
		(size 0.6604)
		(drill 0.3302)
		(layers "F.Cu" "B.Cu")
		(net "FM_CPU1_SKTOCC_LVT3_N")
	)
	(via
		(at 466.6742 -119.958104)
		(size 0.508)
		(drill 0.254)
		(layers "F.Cu" "B.Cu")
		(net "FM_CPU1_SKTOCC_LVT3_N")
	)
	(via
		(at 347.418406 -53.140864)
		(size 0.508)
		(drill 0.254)
		(layers "F.Cu" "B.Cu")
		(net "FM_CPU1_SKTOCC_LVT3_N")
	)
	(via
		(at 180.22824 -21.500592)
		(size 0.508)
		(drill 0.254)
		(layers "F.Cu" "B.Cu")
		(net "FM_CPU1_SKTOCC_LVT3_N")
	)
	(via
		(at 322.6689 -24.9682)
		(size 0.508)
		(drill 0.254)
		(layers "F.Cu" "B.Cu")
		(net "FM_CPU1_SKTOCC_LVT3_N")
	)
	(via
		(at 400.681444 -78.135734)
		(size 0.508)
		(drill 0.254)
		(layers "F.Cu" "B.Cu")
		(net "FM_CPU1_SKTOCC_LVT3_N")
	)
	(via
		(at 370.4336 -80.899)
		(size 0.4572)
		(drill 0.2032)
		(layers "F.Cu" "B.Cu")
		(net "FM_CPU1_SKTOCC_LVT3_N")
	)
	(via
		(at 132.519674 -61.847984)
		(size 0.508)
		(drill 0.254)
		(layers "F.Cu" "B.Cu")
		(net "FM_CPU1_SKTOCC_LVT3_N")
	)
	(segment
		(start 359.483152 -57.839864)
		(end 359.078276 -58.24474)
		(width 0.10795)
		(layer "B.Cu")
		(net "FM_CPU1_SKTOCC_LVT3_N")
	)
	(segment
		(start 165.67404 -63.54826)
		(end 165.67404 -64.37376)
		(width 0.10795)
		(layer "B.Cu")
		(net "FM_CPU1_SKTOCC_LVT3_N")
	)
	(segment
		(start 363.953298 -81.32572)
		(end 365.592868 -81.32572)
		(width 0.10795)
		(layer "B.Cu")
		(net "FM_CPU1_SKTOCC_LVT3_N")
	)
	(segment
		(start 357.98379 -54.1655)
		(end 359.483152 -55.664862)
		(width 0.10795)
		(layer "B.Cu")
		(net "FM_CPU1_SKTOCC_LVT3_N")
	)
	(segment
		(start 348.104206 -53.140864)
		(end 350.182942 -55.2196)
		(width 0.10795)
		(layer "B.Cu")
		(net "FM_CPU1_SKTOCC_LVT3_N")
	)
	(segment
		(start 459.7908 -130.3782)
		(end 459.2574 -130.3782)
		(width 0.10795)
		(layer "B.Cu")
		(net "FM_CPU1_SKTOCC_LVT3_N")
	)
	(segment
		(start 165.41369 -63.28791)
		(end 165.67404 -63.54826)
		(width 0.10795)
		(layer "B.Cu")
		(net "FM_CPU1_SKTOCC_LVT3_N")
	)
	(segment
		(start 459.0034 -130.1242)
		(end 459.0034 -129.6924)
		(width 0.10795)
		(layer "B.Cu")
		(net "FM_CPU1_SKTOCC_LVT3_N")
	)
	(segment
		(start 354.248466 -74.170794)
		(end 361.252008 -74.170794)
		(width 0.10795)
		(layer "B.Cu")
		(net "FM_CPU1_SKTOCC_LVT3_N")
	)
	(segment
		(start 165.646862 -64.400938)
		(end 165.646862 -64.40805)
		(width 0.10795)
		(layer "B.Cu")
		(net "FM_CPU1_SKTOCC_LVT3_N")
	)
	(segment
		(start 365.593122 -81.325466)
		(end 370.007134 -81.325466)
		(width 0.10795)
		(layer "B.Cu")
		(net "FM_CPU1_SKTOCC_LVT3_N")
	)
	(segment
		(start 370.007134 -81.325466)
		(end 370.4336 -80.899)
		(width 0.10795)
		(layer "B.Cu")
		(net "FM_CPU1_SKTOCC_LVT3_N")
	)
	(segment
		(start 365.592868 -81.32572)
		(end 365.593122 -81.325466)
		(width 0.10795)
		(layer "B.Cu")
		(net "FM_CPU1_SKTOCC_LVT3_N")
	)
	(segment
		(start 353.2251 -54.1655)
		(end 353.949 -54.1655)
		(width 0.10795)
		(layer "B.Cu")
		(net "FM_CPU1_SKTOCC_LVT3_N")
	)
	(segment
		(start 459.2574 -130.3782)
		(end 459.0034 -130.1242)
		(width 0.10795)
		(layer "B.Cu")
		(net "FM_CPU1_SKTOCC_LVT3_N")
	)
	(segment
		(start 359.483152 -55.664862)
		(end 359.483152 -57.839864)
		(width 0.10795)
		(layer "B.Cu")
		(net "FM_CPU1_SKTOCC_LVT3_N")
	)
	(segment
		(start 359.078276 -64.01054)
		(end 354.593906 -68.49491)
		(width 0.10795)
		(layer "B.Cu")
		(net "FM_CPU1_SKTOCC_LVT3_N")
	)
	(segment
		(start 363.260386 -76.179172)
		(end 363.260386 -80.632808)
		(width 0.10795)
		(layer "B.Cu")
		(net "FM_CPU1_SKTOCC_LVT3_N")
	)
	(segment
		(start 460.4512 -129.6924)
		(end 459.0034 -129.6924)
		(width 0.10795)
		(layer "B.Cu")
		(net "FM_CPU1_SKTOCC_LVT3_N")
	)
	(segment
		(start 353.407218 -68.49491)
		(end 350.15805 -71.744078)
		(width 0.10795)
		(layer "B.Cu")
		(net "FM_CPU1_SKTOCC_LVT3_N")
	)
	(segment
		(start 351.282 -74.0537)
		(end 354.131372 -74.0537)
		(width 0.10795)
		(layer "B.Cu")
		(net "FM_CPU1_SKTOCC_LVT3_N")
	)
	(segment
		(start 363.260386 -80.632808)
		(end 363.953298 -81.32572)
		(width 0.10795)
		(layer "B.Cu")
		(net "FM_CPU1_SKTOCC_LVT3_N")
	)
	(segment
		(start 353.949 -54.1655)
		(end 357.98379 -54.1655)
		(width 0.10795)
		(layer "B.Cu")
		(net "FM_CPU1_SKTOCC_LVT3_N")
	)
	(segment
		(start 354.131372 -74.0537)
		(end 354.248466 -74.170794)
		(width 0.10795)
		(layer "B.Cu")
		(net "FM_CPU1_SKTOCC_LVT3_N")
	)
	(segment
		(start 354.593906 -68.49491)
		(end 353.407218 -68.49491)
		(width 0.10795)
		(layer "B.Cu")
		(net "FM_CPU1_SKTOCC_LVT3_N")
	)
	(segment
		(start 350.182942 -55.2196)
		(end 352.171 -55.2196)
		(width 0.10795)
		(layer "B.Cu")
		(net "FM_CPU1_SKTOCC_LVT3_N")
	)
	(segment
		(start 350.15805 -72.92975)
		(end 351.282 -74.0537)
		(width 0.10795)
		(layer "B.Cu")
		(net "FM_CPU1_SKTOCC_LVT3_N")
	)
	(segment
		(start 165.67404 -64.37376)
		(end 165.646862 -64.400938)
		(width 0.10795)
		(layer "B.Cu")
		(net "FM_CPU1_SKTOCC_LVT3_N")
	)
	(segment
		(start 347.418406 -53.140864)
		(end 348.104206 -53.140864)
		(width 0.10795)
		(layer "B.Cu")
		(net "FM_CPU1_SKTOCC_LVT3_N")
	)
	(segment
		(start 361.252008 -74.170794)
		(end 363.260386 -76.179172)
		(width 0.10795)
		(layer "B.Cu")
		(net "FM_CPU1_SKTOCC_LVT3_N")
	)
	(segment
		(start 352.171 -55.2196)
		(end 353.2251 -54.1655)
		(width 0.10795)
		(layer "B.Cu")
		(net "FM_CPU1_SKTOCC_LVT3_N")
	)
	(segment
		(start 165.646862 -64.40805)
		(end 164.084 -65.970912)
		(width 0.10795)
		(layer "B.Cu")
		(net "FM_CPU1_SKTOCC_LVT3_N")
	)
	(segment
		(start 350.15805 -71.744078)
		(end 350.15805 -72.92975)
		(width 0.10795)
		(layer "B.Cu")
		(net "FM_CPU1_SKTOCC_LVT3_N")
	)
	(segment
		(start 359.078276 -58.24474)
		(end 359.078276 -64.01054)
		(width 0.10795)
		(layer "B.Cu")
		(net "FM_CPU1_SKTOCC_LVT3_N")
	)
	(segment
		(start 164.084 -65.970912)
		(end 164.084 -66.421)
		(width 0.10795)
		(layer "B.Cu")
		(net "FM_CPU1_SKTOCC_LVT3_N")
	)
	(segment
		(start 423.653712 -121.481088)
		(end 428.01159 -121.481088)
		(width 0.089408)
		(layer "In2.Cu")
		(net "FM_CPU1_SKTOCC_LVT3_N")
	)
	(segment
		(start 402.03755 -114.03965)
		(end 404.41245 -114.03965)
		(width 0.089408)
		(layer "In2.Cu")
		(net "FM_CPU1_SKTOCC_LVT3_N")
	)
	(segment
		(start 405.040592 -63.918592)
		(end 405.040592 -58.471816)
		(width 0.089408)
		(layer "In2.Cu")
		(net "FM_CPU1_SKTOCC_LVT3_N")
	)
	(segment
		(start 409.93822 -122.866912)
		(end 411.377892 -122.866912)
		(width 0.089408)
		(layer "In2.Cu")
		(net "FM_CPU1_SKTOCC_LVT3_N")
	)
	(segment
		(start 411.948884 -122.29592)
		(end 417.14928 -122.29592)
		(width 0.089408)
		(layer "In2.Cu")
		(net "FM_CPU1_SKTOCC_LVT3_N")
	)
	(segment
		(start 406.4 -64.994028)
		(end 405.667972 -64.262)
		(width 0.089408)
		(layer "In2.Cu")
		(net "FM_CPU1_SKTOCC_LVT3_N")
	)
	(segment
		(start 428.280576 -121.212102)
		(end 434.415184 -121.212102)
		(width 0.089408)
		(layer "In2.Cu")
		(net "FM_CPU1_SKTOCC_LVT3_N")
	)
	(segment
		(start 405.018748 -116.722652)
		(end 408.137614 -119.841518)
		(width 0.089408)
		(layer "In2.Cu")
		(net "FM_CPU1_SKTOCC_LVT3_N")
	)
	(segment
		(start 417.14928 -122.29592)
		(end 418.084 -121.3612)
		(width 0.089408)
		(layer "In2.Cu")
		(net "FM_CPU1_SKTOCC_LVT3_N")
	)
	(segment
		(start 402.082 -73.025)
		(end 404.99792 -70.10908)
		(width 0.089408)
		(layer "In2.Cu")
		(net "FM_CPU1_SKTOCC_LVT3_N")
	)
	(segment
		(start 419.424866 -121.3612)
		(end 419.814248 -121.750582)
		(width 0.089408)
		(layer "In2.Cu")
		(net "FM_CPU1_SKTOCC_LVT3_N")
	)
	(segment
		(start 405.882094 -53.554884)
		(end 408.452066 -50.984912)
		(width 0.089408)
		(layer "In2.Cu")
		(net "FM_CPU1_SKTOCC_LVT3_N")
	)
	(segment
		(start 394.768324 -105.167176)
		(end 394.768324 -105.357676)
		(width 0.0889)
		(layer "In2.Cu")
		(net "FM_CPU1_SKTOCC_LVT3_N")
	)
	(segment
		(start 395.278864 -104.656636)
		(end 394.768324 -105.167176)
		(width 0.0889)
		(layer "In2.Cu")
		(net "FM_CPU1_SKTOCC_LVT3_N")
	)
	(segment
		(start 395.7574 -108.744766)
		(end 395.7574 -108.777532)
		(width 0.0889)
		(layer "In2.Cu")
		(net "FM_CPU1_SKTOCC_LVT3_N")
	)
	(segment
		(start 388.8232 -100.159566)
		(end 388.8232 -100.192332)
		(width 0.0889)
		(layer "In2.Cu")
		(net "FM_CPU1_SKTOCC_LVT3_N")
	)
	(segment
		(start 395.7574 -110.61446)
		(end 395.7574 -110.943898)
		(width 0.0889)
		(layer "In2.Cu")
		(net "FM_CPU1_SKTOCC_LVT3_N")
	)
	(segment
		(start 395.2621 -104.46512)
		(end 395.278864 -104.604312)
		(width 0.0889)
		(layer "In2.Cu")
		(net "FM_CPU1_SKTOCC_LVT3_N")
	)
	(segment
		(start 400.013932 -112.016032)
		(end 400.41195 -112.41405)
		(width 0.0889)
		(layer "In2.Cu")
		(net "FM_CPU1_SKTOCC_LVT3_N")
	)
	(segment
		(start 434.415184 -121.212102)
		(end 437.40832 -118.218966)
		(width 0.089408)
		(layer "In2.Cu")
		(net "FM_CPU1_SKTOCC_LVT3_N")
	)
	(segment
		(start 408.452066 -50.984912)
		(end 417.136326 -50.984912)
		(width 0.089408)
		(layer "In2.Cu")
		(net "FM_CPU1_SKTOCC_LVT3_N")
	)
	(segment
		(start 390.3091 -102.735126)
		(end 390.3091 -102.767892)
		(width 0.0889)
		(layer "In2.Cu")
		(net "FM_CPU1_SKTOCC_LVT3_N")
	)
	(segment
		(start 400.685 -73.025)
		(end 402.082 -73.025)
		(width 0.089408)
		(layer "In2.Cu")
		(net "FM_CPU1_SKTOCC_LVT3_N")
	)
	(segment
		(start 396.2527 -111.780574)
		(end 396.2527 -111.81334)
		(width 0.0889)
		(layer "In2.Cu")
		(net "FM_CPU1_SKTOCC_LVT3_N")
	)
	(segment
		(start 395.2621 -104.464612)
		(end 395.2621 -104.46512)
		(width 0.0889)
		(layer "In2.Cu")
		(net "FM_CPU1_SKTOCC_LVT3_N")
	)
	(segment
		(start 404.99792 -67.074288)
		(end 406.4 -65.672208)
		(width 0.089408)
		(layer "In2.Cu")
		(net "FM_CPU1_SKTOCC_LVT3_N")
	)
	(segment
		(start 394.65631 -106.849672)
		(end 394.65631 -107.45089)
		(width 0.0889)
		(layer "In2.Cu")
		(net "FM_CPU1_SKTOCC_LVT3_N")
	)
	(segment
		(start 400.431 -73.279)
		(end 400.685 -73.025)
		(width 0.089408)
		(layer "In2.Cu")
		(net "FM_CPU1_SKTOCC_LVT3_N")
	)
	(segment
		(start 411.377892 -122.866912)
		(end 411.948884 -122.29592)
		(width 0.089408)
		(layer "In2.Cu")
		(net "FM_CPU1_SKTOCC_LVT3_N")
	)
	(segment
		(start 419.08222 -49.039018)
		(end 424.141646 -49.039018)
		(width 0.089408)
		(layer "In2.Cu")
		(net "FM_CPU1_SKTOCC_LVT3_N")
	)
	(segment
		(start 405.384 -64.262)
		(end 405.040592 -63.918592)
		(width 0.089408)
		(layer "In2.Cu")
		(net "FM_CPU1_SKTOCC_LVT3_N")
	)
	(segment
		(start 408.137614 -119.841518)
		(end 408.137614 -121.066306)
		(width 0.089408)
		(layer "In2.Cu")
		(net "FM_CPU1_SKTOCC_LVT3_N")
	)
	(segment
		(start 394.768324 -105.357676)
		(end 394.138658 -105.987342)
		(width 0.0889)
		(layer "In2.Cu")
		(net "FM_CPU1_SKTOCC_LVT3_N")
	)
	(segment
		(start 389.8138 -101.876606)
		(end 389.8138 -101.909372)
		(width 0.0889)
		(layer "In2.Cu")
		(net "FM_CPU1_SKTOCC_LVT3_N")
	)
	(segment
		(start 394.7668 -103.593646)
		(end 394.7668 -103.626412)
		(width 0.0889)
		(layer "In2.Cu")
		(net "FM_CPU1_SKTOCC_LVT3_N")
	)
	(segment
		(start 464.110578 -118.218966)
		(end 465.849716 -119.958104)
		(width 0.089408)
		(layer "In2.Cu")
		(net "FM_CPU1_SKTOCC_LVT3_N")
	)
	(segment
		(start 394.138658 -105.987342)
		(end 394.138658 -106.33202)
		(width 0.0889)
		(layer "In2.Cu")
		(net "FM_CPU1_SKTOCC_LVT3_N")
	)
	(segment
		(start 395.278864 -104.604312)
		(end 395.278864 -104.656636)
		(width 0.0889)
		(layer "In2.Cu")
		(net "FM_CPU1_SKTOCC_LVT3_N")
	)
	(segment
		(start 400.681444 -77.592428)
		(end 400.155664 -77.066648)
		(width 0.089408)
		(layer "In2.Cu")
		(net "FM_CPU1_SKTOCC_LVT3_N")
	)
	(segment
		(start 404.41245 -114.03965)
		(end 405.018748 -114.645948)
		(width 0.089408)
		(layer "In2.Cu")
		(net "FM_CPU1_SKTOCC_LVT3_N")
	)
	(segment
		(start 405.882094 -57.630314)
		(end 405.882094 -53.554884)
		(width 0.089408)
		(layer "In2.Cu")
		(net "FM_CPU1_SKTOCC_LVT3_N")
	)
	(segment
		(start 419.814248 -121.750582)
		(end 423.384218 -121.750582)
		(width 0.089408)
		(layer "In2.Cu")
		(net "FM_CPU1_SKTOCC_LVT3_N")
	)
	(segment
		(start 389.3185 -101.018086)
		(end 389.3185 -101.050852)
		(width 0.0889)
		(layer "In2.Cu")
		(net "FM_CPU1_SKTOCC_LVT3_N")
	)
	(segment
		(start 388.3279 -99.301046)
		(end 388.3279 -99.333812)
		(width 0.0889)
		(layer "In2.Cu")
		(net "FM_CPU1_SKTOCC_LVT3_N")
	)
	(segment
		(start 394.138658 -106.33202)
		(end 394.65631 -106.849672)
		(width 0.0889)
		(layer "In2.Cu")
		(net "FM_CPU1_SKTOCC_LVT3_N")
	)
	(segment
		(start 400.155664 -73.60666)
		(end 400.431 -73.331324)
		(width 0.089408)
		(layer "In2.Cu")
		(net "FM_CPU1_SKTOCC_LVT3_N")
	)
	(segment
		(start 400.41195 -112.41405)
		(end 402.03755 -114.03965)
		(width 0.089408)
		(layer "In2.Cu")
		(net "FM_CPU1_SKTOCC_LVT3_N")
	)
	(segment
		(start 423.384218 -121.750582)
		(end 423.653712 -121.481088)
		(width 0.089408)
		(layer "In2.Cu")
		(net "FM_CPU1_SKTOCC_LVT3_N")
	)
	(segment
		(start 405.667972 -64.262)
		(end 405.384 -64.262)
		(width 0.089408)
		(layer "In2.Cu")
		(net "FM_CPU1_SKTOCC_LVT3_N")
	)
	(segment
		(start 417.136326 -50.984912)
		(end 419.08222 -49.039018)
		(width 0.089408)
		(layer "In2.Cu")
		(net "FM_CPU1_SKTOCC_LVT3_N")
	)
	(segment
		(start 400.155664 -77.066648)
		(end 400.155664 -73.60666)
		(width 0.089408)
		(layer "In2.Cu")
		(net "FM_CPU1_SKTOCC_LVT3_N")
	)
	(segment
		(start 400.431 -73.331324)
		(end 400.431 -73.279)
		(width 0.089408)
		(layer "In2.Cu")
		(net "FM_CPU1_SKTOCC_LVT3_N")
	)
	(segment
		(start 437.40832 -118.218966)
		(end 464.110578 -118.218966)
		(width 0.089408)
		(layer "In2.Cu")
		(net "FM_CPU1_SKTOCC_LVT3_N")
	)
	(segment
		(start 406.4 -65.672208)
		(end 406.4 -64.994028)
		(width 0.089408)
		(layer "In2.Cu")
		(net "FM_CPU1_SKTOCC_LVT3_N")
	)
	(segment
		(start 465.849716 -119.958104)
		(end 466.6742 -119.958104)
		(width 0.089408)
		(layer "In2.Cu")
		(net "FM_CPU1_SKTOCC_LVT3_N")
	)
	(segment
		(start 399.329402 -112.016032)
		(end 400.013932 -112.016032)
		(width 0.0889)
		(layer "In2.Cu")
		(net "FM_CPU1_SKTOCC_LVT3_N")
	)
	(segment
		(start 396.2527 -109.603286)
		(end 396.2527 -109.646466)
		(width 0.0889)
		(layer "In2.Cu")
		(net "FM_CPU1_SKTOCC_LVT3_N")
	)
	(segment
		(start 400.681444 -78.135734)
		(end 400.681444 -77.592428)
		(width 0.089408)
		(layer "In2.Cu")
		(net "FM_CPU1_SKTOCC_LVT3_N")
	)
	(segment
		(start 395.262354 -104.452674)
		(end 395.2621 -104.464612)
		(width 0.0889)
		(layer "In2.Cu")
		(net "FM_CPU1_SKTOCC_LVT3_N")
	)
	(segment
		(start 408.137614 -121.066306)
		(end 409.93822 -122.866912)
		(width 0.089408)
		(layer "In2.Cu")
		(net "FM_CPU1_SKTOCC_LVT3_N")
	)
	(segment
		(start 405.040592 -58.471816)
		(end 405.882094 -57.630314)
		(width 0.089408)
		(layer "In2.Cu")
		(net "FM_CPU1_SKTOCC_LVT3_N")
	)
	(segment
		(start 428.01159 -121.481088)
		(end 428.280576 -121.212102)
		(width 0.089408)
		(layer "In2.Cu")
		(net "FM_CPU1_SKTOCC_LVT3_N")
	)
	(segment
		(start 404.99792 -70.10908)
		(end 404.99792 -67.074288)
		(width 0.089408)
		(layer "In2.Cu")
		(net "FM_CPU1_SKTOCC_LVT3_N")
	)
	(segment
		(start 378.680218 -98.558604)
		(end 379.117352 -98.810826)
		(width 0.0889)
		(layer "In2.Cu")
		(net "FM_CPU1_SKTOCC_LVT3_N")
	)
	(segment
		(start 418.084 -121.3612)
		(end 419.424866 -121.3612)
		(width 0.089408)
		(layer "In2.Cu")
		(net "FM_CPU1_SKTOCC_LVT3_N")
	)
	(segment
		(start 405.018748 -114.645948)
		(end 405.018748 -116.722652)
		(width 0.089408)
		(layer "In2.Cu")
		(net "FM_CPU1_SKTOCC_LVT3_N")
	)
	(segment
		(start 394.65631 -107.45089)
		(end 395.318488 -108.113068)
		(width 0.0889)
		(layer "In2.Cu")
		(net "FM_CPU1_SKTOCC_LVT3_N")
	)
	(arc
		(start 392.890248 -103.103426)
		(mid 393.18565 -103.024295)
		(end 393.481052 -103.103426)
		(width 0.0889)
		(layer "In2.Cu")
		(net "FM_CPU1_SKTOCC_LVT3_N")
	)
	(arc
		(start 395.462252 -108.254546)
		(mid 395.673116 -108.46155)
		(end 395.7574 -108.744766)
		(width 0.0889)
		(layer "In2.Cu")
		(net "FM_CPU1_SKTOCC_LVT3_N")
	)
	(arc
		(start 395.7574 -110.943898)
		(mid 395.811045 -111.143939)
		(end 395.957552 -111.290354)
		(width 0.0889)
		(layer "In2.Cu")
		(net "FM_CPU1_SKTOCC_LVT3_N")
	)
	(arc
		(start 385.460748 -98.810826)
		(mid 385.75615 -98.731695)
		(end 386.051552 -98.810826)
		(width 0.0889)
		(layer "In2.Cu")
		(net "FM_CPU1_SKTOCC_LVT3_N")
	)
	(arc
		(start 393.880848 -103.103426)
		(mid 394.462356 -103.098172)
		(end 394.7668 -103.593646)
		(width 0.0889)
		(layer "In2.Cu")
		(net "FM_CPU1_SKTOCC_LVT3_N")
	)
	(arc
		(start 389.518652 -101.386386)
		(mid 389.729516 -101.59339)
		(end 389.8138 -101.876606)
		(width 0.0889)
		(layer "In2.Cu")
		(net "FM_CPU1_SKTOCC_LVT3_N")
	)
	(arc
		(start 396.852648 -112.148874)
		(mid 397.14805 -112.069743)
		(end 397.443452 -112.148874)
		(width 0.0889)
		(layer "In2.Cu")
		(net "FM_CPU1_SKTOCC_LVT3_N")
	)
	(arc
		(start 395.957552 -111.290354)
		(mid 396.168416 -111.497358)
		(end 396.2527 -111.780574)
		(width 0.0889)
		(layer "In2.Cu")
		(net "FM_CPU1_SKTOCC_LVT3_N")
	)
	(arc
		(start 390.3091 -102.767892)
		(mid 390.513802 -103.106007)
		(end 390.909048 -103.103426)
		(width 0.0889)
		(layer "In2.Cu")
		(net "FM_CPU1_SKTOCC_LVT3_N")
	)
	(arc
		(start 378.32665 -98.464116)
		(mid 378.509644 -98.488118)
		(end 378.680218 -98.558604)
		(width 0.0889)
		(layer "In2.Cu")
		(net "FM_CPU1_SKTOCC_LVT3_N")
	)
	(arc
		(start 397.443452 -112.148874)
		(mid 397.64335 -112.202373)
		(end 397.843248 -112.148874)
		(width 0.0889)
		(layer "In2.Cu")
		(net "FM_CPU1_SKTOCC_LVT3_N")
	)
	(arc
		(start 381.498348 -98.810826)
		(mid 381.79375 -98.731695)
		(end 382.089152 -98.810826)
		(width 0.0889)
		(layer "In2.Cu")
		(net "FM_CPU1_SKTOCC_LVT3_N")
	)
	(arc
		(start 386.051552 -98.810826)
		(mid 386.25145 -98.864325)
		(end 386.451348 -98.810826)
		(width 0.0889)
		(layer "In2.Cu")
		(net "FM_CPU1_SKTOCC_LVT3_N")
	)
	(arc
		(start 382.488948 -98.810826)
		(mid 382.78435 -98.731695)
		(end 383.079752 -98.810826)
		(width 0.0889)
		(layer "In2.Cu")
		(net "FM_CPU1_SKTOCC_LVT3_N")
	)
	(arc
		(start 388.8232 -100.192332)
		(mid 388.87955 -100.386182)
		(end 389.023352 -100.527866)
		(width 0.0889)
		(layer "In2.Cu")
		(net "FM_CPU1_SKTOCC_LVT3_N")
	)
	(arc
		(start 390.013952 -102.244906)
		(mid 390.224816 -102.45191)
		(end 390.3091 -102.735126)
		(width 0.0889)
		(layer "In2.Cu")
		(net "FM_CPU1_SKTOCC_LVT3_N")
	)
	(arc
		(start 385.060952 -98.810826)
		(mid 385.26085 -98.864325)
		(end 385.460748 -98.810826)
		(width 0.0889)
		(layer "In2.Cu")
		(net "FM_CPU1_SKTOCC_LVT3_N")
	)
	(arc
		(start 395.957552 -109.113066)
		(mid 396.168416 -109.32007)
		(end 396.2527 -109.603286)
		(width 0.0889)
		(layer "In2.Cu")
		(net "FM_CPU1_SKTOCC_LVT3_N")
	)
	(arc
		(start 394.7668 -103.626412)
		(mid 394.82315 -103.820262)
		(end 394.966952 -103.961946)
		(width 0.0889)
		(layer "In2.Cu")
		(net "FM_CPU1_SKTOCC_LVT3_N")
	)
	(arc
		(start 395.7574 -108.777532)
		(mid 395.81375 -108.971382)
		(end 395.957552 -109.113066)
		(width 0.0889)
		(layer "In2.Cu")
		(net "FM_CPU1_SKTOCC_LVT3_N")
	)
	(arc
		(start 397.843248 -112.148874)
		(mid 398.13865 -112.069743)
		(end 398.434052 -112.148874)
		(width 0.0889)
		(layer "In2.Cu")
		(net "FM_CPU1_SKTOCC_LVT3_N")
	)
	(arc
		(start 384.470148 -98.810826)
		(mid 384.76555 -98.731695)
		(end 385.060952 -98.810826)
		(width 0.0889)
		(layer "In2.Cu")
		(net "FM_CPU1_SKTOCC_LVT3_N")
	)
	(arc
		(start 381.098552 -98.810826)
		(mid 381.29845 -98.864325)
		(end 381.498348 -98.810826)
		(width 0.0889)
		(layer "In2.Cu")
		(net "FM_CPU1_SKTOCC_LVT3_N")
	)
	(arc
		(start 389.023352 -100.527866)
		(mid 389.234216 -100.73487)
		(end 389.3185 -101.018086)
		(width 0.0889)
		(layer "In2.Cu")
		(net "FM_CPU1_SKTOCC_LVT3_N")
	)
	(arc
		(start 392.490452 -103.103426)
		(mid 392.69035 -103.156925)
		(end 392.890248 -103.103426)
		(width 0.0889)
		(layer "In2.Cu")
		(net "FM_CPU1_SKTOCC_LVT3_N")
	)
	(arc
		(start 391.499852 -103.103426)
		(mid 391.69975 -103.156925)
		(end 391.899648 -103.103426)
		(width 0.0889)
		(layer "In2.Cu")
		(net "FM_CPU1_SKTOCC_LVT3_N")
	)
	(arc
		(start 387.441948 -98.810826)
		(mid 388.023456 -98.805572)
		(end 388.3279 -99.301046)
		(width 0.0889)
		(layer "In2.Cu")
		(net "FM_CPU1_SKTOCC_LVT3_N")
	)
	(arc
		(start 382.089152 -98.810826)
		(mid 382.28905 -98.864325)
		(end 382.488948 -98.810826)
		(width 0.0889)
		(layer "In2.Cu")
		(net "FM_CPU1_SKTOCC_LVT3_N")
	)
	(arc
		(start 388.3279 -99.333812)
		(mid 388.38425 -99.527662)
		(end 388.528052 -99.669346)
		(width 0.0889)
		(layer "In2.Cu")
		(net "FM_CPU1_SKTOCC_LVT3_N")
	)
	(arc
		(start 395.318488 -108.113068)
		(mid 395.38129 -108.19304)
		(end 395.462252 -108.254546)
		(width 0.0889)
		(layer "In2.Cu")
		(net "FM_CPU1_SKTOCC_LVT3_N")
	)
	(arc
		(start 390.909048 -103.103426)
		(mid 391.20445 -103.024295)
		(end 391.499852 -103.103426)
		(width 0.0889)
		(layer "In2.Cu")
		(net "FM_CPU1_SKTOCC_LVT3_N")
	)
	(arc
		(start 389.3185 -101.050852)
		(mid 389.37485 -101.244702)
		(end 389.518652 -101.386386)
		(width 0.0889)
		(layer "In2.Cu")
		(net "FM_CPU1_SKTOCC_LVT3_N")
	)
	(arc
		(start 379.517148 -98.810826)
		(mid 379.81255 -98.731695)
		(end 380.107952 -98.810826)
		(width 0.0889)
		(layer "In2.Cu")
		(net "FM_CPU1_SKTOCC_LVT3_N")
	)
	(arc
		(start 383.479548 -98.810826)
		(mid 383.77495 -98.731695)
		(end 384.070352 -98.810826)
		(width 0.0889)
		(layer "In2.Cu")
		(net "FM_CPU1_SKTOCC_LVT3_N")
	)
	(arc
		(start 383.079752 -98.810826)
		(mid 383.27965 -98.864325)
		(end 383.479548 -98.810826)
		(width 0.0889)
		(layer "In2.Cu")
		(net "FM_CPU1_SKTOCC_LVT3_N")
	)
	(arc
		(start 380.107952 -98.810826)
		(mid 380.30785 -98.864325)
		(end 380.507748 -98.810826)
		(width 0.0889)
		(layer "In2.Cu")
		(net "FM_CPU1_SKTOCC_LVT3_N")
	)
	(arc
		(start 396.2527 -109.646466)
		(mid 396.184703 -109.900836)
		(end 396.012924 -110.100364)
		(width 0.0889)
		(layer "In2.Cu")
		(net "FM_CPU1_SKTOCC_LVT3_N")
	)
	(arc
		(start 388.528052 -99.669346)
		(mid 388.738916 -99.87635)
		(end 388.8232 -100.159566)
		(width 0.0889)
		(layer "In2.Cu")
		(net "FM_CPU1_SKTOCC_LVT3_N")
	)
	(arc
		(start 386.451348 -98.810826)
		(mid 386.74675 -98.731695)
		(end 387.042152 -98.810826)
		(width 0.0889)
		(layer "In2.Cu")
		(net "FM_CPU1_SKTOCC_LVT3_N")
	)
	(arc
		(start 391.899648 -103.103426)
		(mid 392.19505 -103.024295)
		(end 392.490452 -103.103426)
		(width 0.0889)
		(layer "In2.Cu")
		(net "FM_CPU1_SKTOCC_LVT3_N")
	)
	(arc
		(start 389.8138 -101.909372)
		(mid 389.87015 -102.103222)
		(end 390.013952 -102.244906)
		(width 0.0889)
		(layer "In2.Cu")
		(net "FM_CPU1_SKTOCC_LVT3_N")
	)
	(arc
		(start 384.070352 -98.810826)
		(mid 384.27025 -98.864325)
		(end 384.470148 -98.810826)
		(width 0.0889)
		(layer "In2.Cu")
		(net "FM_CPU1_SKTOCC_LVT3_N")
	)
	(arc
		(start 393.481052 -103.103426)
		(mid 393.68095 -103.156925)
		(end 393.880848 -103.103426)
		(width 0.0889)
		(layer "In2.Cu")
		(net "FM_CPU1_SKTOCC_LVT3_N")
	)
	(arc
		(start 387.042152 -98.810826)
		(mid 387.24205 -98.864325)
		(end 387.441948 -98.810826)
		(width 0.0889)
		(layer "In2.Cu")
		(net "FM_CPU1_SKTOCC_LVT3_N")
	)
	(arc
		(start 379.117352 -98.810826)
		(mid 379.31725 -98.864325)
		(end 379.517148 -98.810826)
		(width 0.0889)
		(layer "In2.Cu")
		(net "FM_CPU1_SKTOCC_LVT3_N")
	)
	(arc
		(start 380.507748 -98.810826)
		(mid 380.80315 -98.731695)
		(end 381.098552 -98.810826)
		(width 0.0889)
		(layer "In2.Cu")
		(net "FM_CPU1_SKTOCC_LVT3_N")
	)
	(arc
		(start 396.012924 -110.100364)
		(mid 395.824798 -110.32741)
		(end 395.7574 -110.61446)
		(width 0.0889)
		(layer "In2.Cu")
		(net "FM_CPU1_SKTOCC_LVT3_N")
	)
	(arc
		(start 398.434052 -112.148874)
		(mid 398.63395 -112.202373)
		(end 398.833848 -112.148874)
		(width 0.0889)
		(layer "In2.Cu")
		(net "FM_CPU1_SKTOCC_LVT3_N")
	)
	(arc
		(start 396.2527 -111.81334)
		(mid 396.457402 -112.151455)
		(end 396.852648 -112.148874)
		(width 0.0889)
		(layer "In2.Cu")
		(net "FM_CPU1_SKTOCC_LVT3_N")
	)
	(arc
		(start 394.966952 -103.961946)
		(mid 395.178126 -104.169116)
		(end 395.262354 -104.452674)
		(width 0.0889)
		(layer "In2.Cu")
		(net "FM_CPU1_SKTOCC_LVT3_N")
	)
	(arc
		(start 398.833848 -112.148874)
		(mid 399.07287 -112.049781)
		(end 399.329402 -112.016032)
		(width 0.0889)
		(layer "In2.Cu")
		(net "FM_CPU1_SKTOCC_LVT3_N")
	)
	(segment
		(start 397.788638 -79.616554)
		(end 397.990314 -79.414878)
		(width 0.089408)
		(layer "In4.Cu")
		(net "FM_CPU1_SKTOCC_LVT3_N")
	)
	(segment
		(start 400.609816 -78.135734)
		(end 400.681444 -78.135734)
		(width 0.089408)
		(layer "In4.Cu")
		(net "FM_CPU1_SKTOCC_LVT3_N")
	)
	(segment
		(start 398.302226 -78.81493)
		(end 399.93062 -78.81493)
		(width 0.089408)
		(layer "In4.Cu")
		(net "FM_CPU1_SKTOCC_LVT3_N")
	)
	(segment
		(start 395.265148 -78.150466)
		(end 395.664436 -77.751178)
		(width 0.089408)
		(layer "In4.Cu")
		(net "FM_CPU1_SKTOCC_LVT3_N")
	)
	(segment
		(start 373.086884 -80.93964)
		(end 374.339612 -80.93964)
		(width 0.089408)
		(layer "In4.Cu")
		(net "FM_CPU1_SKTOCC_LVT3_N")
	)
	(segment
		(start 391.060432 -80.4926)
		(end 391.541 -80.012032)
		(width 0.089408)
		(layer "In4.Cu")
		(net "FM_CPU1_SKTOCC_LVT3_N")
	)
	(segment
		(start 391.541 -80.012032)
		(end 391.541 -78.831694)
		(width 0.089408)
		(layer "In4.Cu")
		(net "FM_CPU1_SKTOCC_LVT3_N")
	)
	(segment
		(start 396.507462 -77.751178)
		(end 396.741904 -77.98562)
		(width 0.089408)
		(layer "In4.Cu")
		(net "FM_CPU1_SKTOCC_LVT3_N")
	)
	(segment
		(start 395.664436 -77.751178)
		(end 396.507462 -77.751178)
		(width 0.089408)
		(layer "In4.Cu")
		(net "FM_CPU1_SKTOCC_LVT3_N")
	)
	(segment
		(start 391.541 -78.831694)
		(end 392.09472 -78.277974)
		(width 0.089408)
		(layer "In4.Cu")
		(net "FM_CPU1_SKTOCC_LVT3_N")
	)
	(segment
		(start 396.741904 -77.98562)
		(end 396.741904 -79.362808)
		(width 0.089408)
		(layer "In4.Cu")
		(net "FM_CPU1_SKTOCC_LVT3_N")
	)
	(segment
		(start 399.93062 -78.81493)
		(end 400.609816 -78.135734)
		(width 0.089408)
		(layer "In4.Cu")
		(net "FM_CPU1_SKTOCC_LVT3_N")
	)
	(segment
		(start 370.93906 -80.899)
		(end 371.38864 -80.44942)
		(width 0.089408)
		(layer "In4.Cu")
		(net "FM_CPU1_SKTOCC_LVT3_N")
	)
	(segment
		(start 374.339612 -80.93964)
		(end 374.344692 -80.94472)
		(width 0.089408)
		(layer "In4.Cu")
		(net "FM_CPU1_SKTOCC_LVT3_N")
	)
	(segment
		(start 388.2136 -80.4926)
		(end 391.060432 -80.4926)
		(width 0.089408)
		(layer "In4.Cu")
		(net "FM_CPU1_SKTOCC_LVT3_N")
	)
	(segment
		(start 387.79704 -80.07604)
		(end 388.2136 -80.4926)
		(width 0.089408)
		(layer "In4.Cu")
		(net "FM_CPU1_SKTOCC_LVT3_N")
	)
	(segment
		(start 384.8608 -80.76438)
		(end 385.54914 -80.07604)
		(width 0.089408)
		(layer "In4.Cu")
		(net "FM_CPU1_SKTOCC_LVT3_N")
	)
	(segment
		(start 397.990314 -79.414878)
		(end 397.990314 -79.126842)
		(width 0.089408)
		(layer "In4.Cu")
		(net "FM_CPU1_SKTOCC_LVT3_N")
	)
	(segment
		(start 374.366028 -80.94472)
		(end 375.3993 -81.977992)
		(width 0.089408)
		(layer "In4.Cu")
		(net "FM_CPU1_SKTOCC_LVT3_N")
	)
	(segment
		(start 396.99565 -79.616554)
		(end 397.788638 -79.616554)
		(width 0.089408)
		(layer "In4.Cu")
		(net "FM_CPU1_SKTOCC_LVT3_N")
	)
	(segment
		(start 393.527026 -78.277974)
		(end 393.654534 -78.150466)
		(width 0.089408)
		(layer "In4.Cu")
		(net "FM_CPU1_SKTOCC_LVT3_N")
	)
	(segment
		(start 397.990314 -79.126842)
		(end 398.302226 -78.81493)
		(width 0.089408)
		(layer "In4.Cu")
		(net "FM_CPU1_SKTOCC_LVT3_N")
	)
	(segment
		(start 372.596664 -80.44942)
		(end 373.086884 -80.93964)
		(width 0.089408)
		(layer "In4.Cu")
		(net "FM_CPU1_SKTOCC_LVT3_N")
	)
	(segment
		(start 392.09472 -78.277974)
		(end 393.527026 -78.277974)
		(width 0.089408)
		(layer "In4.Cu")
		(net "FM_CPU1_SKTOCC_LVT3_N")
	)
	(segment
		(start 371.38864 -80.44942)
		(end 372.596664 -80.44942)
		(width 0.089408)
		(layer "In4.Cu")
		(net "FM_CPU1_SKTOCC_LVT3_N")
	)
	(segment
		(start 385.54914 -80.07604)
		(end 387.79704 -80.07604)
		(width 0.089408)
		(layer "In4.Cu")
		(net "FM_CPU1_SKTOCC_LVT3_N")
	)
	(segment
		(start 370.4336 -80.899)
		(end 370.93906 -80.899)
		(width 0.089408)
		(layer "In4.Cu")
		(net "FM_CPU1_SKTOCC_LVT3_N")
	)
	(segment
		(start 383.844546 -80.76438)
		(end 384.8608 -80.76438)
		(width 0.089408)
		(layer "In4.Cu")
		(net "FM_CPU1_SKTOCC_LVT3_N")
	)
	(segment
		(start 375.3993 -81.977992)
		(end 382.630934 -81.977992)
		(width 0.089408)
		(layer "In4.Cu")
		(net "FM_CPU1_SKTOCC_LVT3_N")
	)
	(segment
		(start 374.344692 -80.94472)
		(end 374.366028 -80.94472)
		(width 0.089408)
		(layer "In4.Cu")
		(net "FM_CPU1_SKTOCC_LVT3_N")
	)
	(segment
		(start 393.654534 -78.150466)
		(end 395.265148 -78.150466)
		(width 0.089408)
		(layer "In4.Cu")
		(net "FM_CPU1_SKTOCC_LVT3_N")
	)
	(segment
		(start 396.741904 -79.362808)
		(end 396.99565 -79.616554)
		(width 0.089408)
		(layer "In4.Cu")
		(net "FM_CPU1_SKTOCC_LVT3_N")
	)
	(segment
		(start 382.630934 -81.977992)
		(end 383.844546 -80.76438)
		(width 0.089408)
		(layer "In4.Cu")
		(net "FM_CPU1_SKTOCC_LVT3_N")
	)
	(segment
		(start 186.534298 -19.657568)
		(end 184.836054 -19.657568)
		(width 0.089408)
		(layer "In9.Cu")
		(net "FM_CPU1_SKTOCC_LVT3_N")
	)
	(segment
		(start 191.405256 -16.04899)
		(end 189.756288 -16.04899)
		(width 0.089408)
		(layer "In9.Cu")
		(net "FM_CPU1_SKTOCC_LVT3_N")
	)
	(segment
		(start 193.404236 -14.05001)
		(end 191.405256 -16.04899)
		(width 0.089408)
		(layer "In9.Cu")
		(net "FM_CPU1_SKTOCC_LVT3_N")
	)
	(segment
		(start 138.300714 -57.955942)
		(end 138.053826 -58.20283)
		(width 0.089408)
		(layer "In9.Cu")
		(net "FM_CPU1_SKTOCC_LVT3_N")
	)
	(segment
		(start 134.577074 -62.628018)
		(end 134.583424 -62.638686)
		(width 0.0889)
		(layer "In9.Cu")
		(net "FM_CPU1_SKTOCC_LVT3_N")
	)
	(segment
		(start 138.715242 -57.955942)
		(end 138.300714 -57.955942)
		(width 0.089408)
		(layer "In9.Cu")
		(net "FM_CPU1_SKTOCC_LVT3_N")
	)
	(segment
		(start 151.327104 -60.325)
		(end 148.281898 -57.279794)
		(width 0.089408)
		(layer "In9.Cu")
		(net "FM_CPU1_SKTOCC_LVT3_N")
	)
	(segment
		(start 183.959246 -20.534376)
		(end 181.924452 -20.534376)
		(width 0.089408)
		(layer "In9.Cu")
		(net "FM_CPU1_SKTOCC_LVT3_N")
	)
	(segment
		(start 143.434562 -57.4548)
		(end 142.5194 -57.4548)
		(width 0.089408)
		(layer "In9.Cu")
		(net "FM_CPU1_SKTOCC_LVT3_N")
	)
	(segment
		(start 187.367418 -17.026128)
		(end 187.367418 -18.824448)
		(width 0.089408)
		(layer "In9.Cu")
		(net "FM_CPU1_SKTOCC_LVT3_N")
	)
	(segment
		(start 181.924452 -20.534376)
		(end 181.846728 -20.6121)
		(width 0.089408)
		(layer "In9.Cu")
		(net "FM_CPU1_SKTOCC_LVT3_N")
	)
	(segment
		(start 138.053826 -58.20283)
		(end 137.23239 -58.54319)
		(width 0.089408)
		(layer "In9.Cu")
		(net "FM_CPU1_SKTOCC_LVT3_N")
	)
	(segment
		(start 136.446006 -59.047634)
		(end 136.258554 -59.235086)
		(width 0.089408)
		(layer "In9.Cu")
		(net "FM_CPU1_SKTOCC_LVT3_N")
	)
	(segment
		(start 322.6689 -24.9682)
		(end 323.271134 -24.365966)
		(width 0.089408)
		(layer "In9.Cu")
		(net "FM_CPU1_SKTOCC_LVT3_N")
	)
	(segment
		(start 135.333486 -59.78271)
		(end 134.984236 -59.78271)
		(width 0.089408)
		(layer "In9.Cu")
		(net "FM_CPU1_SKTOCC_LVT3_N")
	)
	(segment
		(start 259.409692 -11.446764)
		(end 195.253102 -11.446764)
		(width 0.089408)
		(layer "In9.Cu")
		(net "FM_CPU1_SKTOCC_LVT3_N")
	)
	(segment
		(start 136.927336 -58.848244)
		(end 136.446006 -59.047634)
		(width 0.089408)
		(layer "In9.Cu")
		(net "FM_CPU1_SKTOCC_LVT3_N")
	)
	(segment
		(start 184.836054 -19.657568)
		(end 183.959246 -20.534376)
		(width 0.089408)
		(layer "In9.Cu")
		(net "FM_CPU1_SKTOCC_LVT3_N")
	)
	(segment
		(start 262.28929 -16.028924)
		(end 261.912862 -15.652496)
		(width 0.089408)
		(layer "In9.Cu")
		(net "FM_CPU1_SKTOCC_LVT3_N")
	)
	(segment
		(start 134.2517 -63.238634)
		(end 134.218934 -63.238634)
		(width 0.0889)
		(layer "In9.Cu")
		(net "FM_CPU1_SKTOCC_LVT3_N")
	)
	(segment
		(start 137.23239 -58.54319)
		(end 136.927336 -58.848244)
		(width 0.089408)
		(layer "In9.Cu")
		(net "FM_CPU1_SKTOCC_LVT3_N")
	)
	(segment
		(start 133.101588 -63.734188)
		(end 132.9436 -63.5762)
		(width 0.0889)
		(layer "In9.Cu")
		(net "FM_CPU1_SKTOCC_LVT3_N")
	)
	(segment
		(start 261.912862 -15.652496)
		(end 261.474966 -15.652496)
		(width 0.089408)
		(layer "In9.Cu")
		(net "FM_CPU1_SKTOCC_LVT3_N")
	)
	(segment
		(start 133.38937 -63.734188)
		(end 133.101588 -63.734188)
		(width 0.0889)
		(layer "In9.Cu")
		(net "FM_CPU1_SKTOCC_LVT3_N")
	)
	(segment
		(start 193.40449 -13.6779)
		(end 193.40449 -13.920216)
		(width 0.089408)
		(layer "In9.Cu")
		(net "FM_CPU1_SKTOCC_LVT3_N")
	)
	(segment
		(start 140.267944 -57.790588)
		(end 140.224764 -57.790588)
		(width 0.0889)
		(layer "In9.Cu")
		(net "FM_CPU1_SKTOCC_LVT3_N")
	)
	(segment
		(start 134.689088 -60.077858)
		(end 134.689088 -60.875164)
		(width 0.0889)
		(layer "In9.Cu")
		(net "FM_CPU1_SKTOCC_LVT3_N")
	)
	(segment
		(start 266.13739 -15.269718)
		(end 265.970258 -15.43685)
		(width 0.089408)
		(layer "In9.Cu")
		(net "FM_CPU1_SKTOCC_LVT3_N")
	)
	(segment
		(start 181.116732 -20.6121)
		(end 180.22824 -21.500592)
		(width 0.089408)
		(layer "In9.Cu")
		(net "FM_CPU1_SKTOCC_LVT3_N")
	)
	(segment
		(start 181.846728 -20.6121)
		(end 181.116732 -20.6121)
		(width 0.089408)
		(layer "In9.Cu")
		(net "FM_CPU1_SKTOCC_LVT3_N")
	)
	(segment
		(start 260.299454 -12.336526)
		(end 259.409692 -11.446764)
		(width 0.089408)
		(layer "In9.Cu")
		(net "FM_CPU1_SKTOCC_LVT3_N")
	)
	(segment
		(start 321.961764 -15.269718)
		(end 266.13739 -15.269718)
		(width 0.089408)
		(layer "In9.Cu")
		(net "FM_CPU1_SKTOCC_LVT3_N")
	)
	(segment
		(start 165.41369 -63.28791)
		(end 164.58438 -62.4586)
		(width 0.089408)
		(layer "In9.Cu")
		(net "FM_CPU1_SKTOCC_LVT3_N")
	)
	(segment
		(start 189.756288 -16.04899)
		(end 189.747906 -16.040608)
		(width 0.089408)
		(layer "In9.Cu")
		(net "FM_CPU1_SKTOCC_LVT3_N")
	)
	(segment
		(start 195.253102 -11.446764)
		(end 193.404236 -13.29563)
		(width 0.089408)
		(layer "In9.Cu")
		(net "FM_CPU1_SKTOCC_LVT3_N")
	)
	(segment
		(start 139.40282 -58.285634)
		(end 139.044934 -58.285634)
		(width 0.0889)
		(layer "In9.Cu")
		(net "FM_CPU1_SKTOCC_LVT3_N")
	)
	(segment
		(start 134.689088 -60.875164)
		(end 134.583424 -61.057536)
		(width 0.0889)
		(layer "In9.Cu")
		(net "FM_CPU1_SKTOCC_LVT3_N")
	)
	(segment
		(start 135.350758 -59.765438)
		(end 135.333486 -59.78271)
		(width 0.089408)
		(layer "In9.Cu")
		(net "FM_CPU1_SKTOCC_LVT3_N")
	)
	(segment
		(start 193.404236 -13.92047)
		(end 193.404236 -14.05001)
		(width 0.089408)
		(layer "In9.Cu")
		(net "FM_CPU1_SKTOCC_LVT3_N")
	)
	(segment
		(start 261.474966 -15.652496)
		(end 260.299454 -14.476984)
		(width 0.089408)
		(layer "In9.Cu")
		(net "FM_CPU1_SKTOCC_LVT3_N")
	)
	(segment
		(start 142.183612 -57.790588)
		(end 141.941804 -57.790588)
		(width 0.0889)
		(layer "In9.Cu")
		(net "FM_CPU1_SKTOCC_LVT3_N")
	)
	(segment
		(start 323.271134 -16.579088)
		(end 321.961764 -15.269718)
		(width 0.089408)
		(layer "In9.Cu")
		(net "FM_CPU1_SKTOCC_LVT3_N")
	)
	(segment
		(start 141.11986 -58.285634)
		(end 141.089888 -58.285634)
		(width 0.0889)
		(layer "In9.Cu")
		(net "FM_CPU1_SKTOCC_LVT3_N")
	)
	(segment
		(start 189.747906 -16.040608)
		(end 188.352938 -16.040608)
		(width 0.089408)
		(layer "In9.Cu")
		(net "FM_CPU1_SKTOCC_LVT3_N")
	)
	(segment
		(start 193.404236 -13.29563)
		(end 193.404236 -13.677646)
		(width 0.089408)
		(layer "In9.Cu")
		(net "FM_CPU1_SKTOCC_LVT3_N")
	)
	(segment
		(start 160.9344 -62.4586)
		(end 158.8008 -60.325)
		(width 0.089408)
		(layer "In9.Cu")
		(net "FM_CPU1_SKTOCC_LVT3_N")
	)
	(segment
		(start 134.583424 -61.648086)
		(end 134.58825 -61.656722)
		(width 0.0889)
		(layer "In9.Cu")
		(net "FM_CPU1_SKTOCC_LVT3_N")
	)
	(segment
		(start 143.857218 -57.279794)
		(end 143.434562 -57.4548)
		(width 0.089408)
		(layer "In9.Cu")
		(net "FM_CPU1_SKTOCC_LVT3_N")
	)
	(segment
		(start 142.5194 -57.4548)
		(end 142.183612 -57.790588)
		(width 0.0889)
		(layer "In9.Cu")
		(net "FM_CPU1_SKTOCC_LVT3_N")
	)
	(segment
		(start 134.577074 -61.637418)
		(end 134.583424 -61.648086)
		(width 0.0889)
		(layer "In9.Cu")
		(net "FM_CPU1_SKTOCC_LVT3_N")
	)
	(segment
		(start 158.8008 -60.325)
		(end 151.327104 -60.325)
		(width 0.089408)
		(layer "In9.Cu")
		(net "FM_CPU1_SKTOCC_LVT3_N")
	)
	(segment
		(start 193.40449 -13.920216)
		(end 193.404236 -13.92047)
		(width 0.089408)
		(layer "In9.Cu")
		(net "FM_CPU1_SKTOCC_LVT3_N")
	)
	(segment
		(start 323.271134 -24.365966)
		(end 323.271134 -16.579088)
		(width 0.089408)
		(layer "In9.Cu")
		(net "FM_CPU1_SKTOCC_LVT3_N")
	)
	(segment
		(start 260.299454 -14.476984)
		(end 260.299454 -12.336526)
		(width 0.089408)
		(layer "In9.Cu")
		(net "FM_CPU1_SKTOCC_LVT3_N")
	)
	(segment
		(start 265.265408 -15.43685)
		(end 264.673334 -16.028924)
		(width 0.089408)
		(layer "In9.Cu")
		(net "FM_CPU1_SKTOCC_LVT3_N")
	)
	(segment
		(start 265.970258 -15.43685)
		(end 265.265408 -15.43685)
		(width 0.089408)
		(layer "In9.Cu")
		(net "FM_CPU1_SKTOCC_LVT3_N")
	)
	(segment
		(start 136.258554 -59.235086)
		(end 135.7122 -59.4614)
		(width 0.089408)
		(layer "In9.Cu")
		(net "FM_CPU1_SKTOCC_LVT3_N")
	)
	(segment
		(start 135.448802 -59.724798)
		(end 135.350758 -59.765438)
		(width 0.089408)
		(layer "In9.Cu")
		(net "FM_CPU1_SKTOCC_LVT3_N")
	)
	(segment
		(start 188.352938 -16.040608)
		(end 187.367418 -17.026128)
		(width 0.089408)
		(layer "In9.Cu")
		(net "FM_CPU1_SKTOCC_LVT3_N")
	)
	(segment
		(start 134.583424 -62.638686)
		(end 134.58825 -62.647322)
		(width 0.0889)
		(layer "In9.Cu")
		(net "FM_CPU1_SKTOCC_LVT3_N")
	)
	(segment
		(start 148.281898 -57.279794)
		(end 143.857218 -57.279794)
		(width 0.089408)
		(layer "In9.Cu")
		(net "FM_CPU1_SKTOCC_LVT3_N")
	)
	(segment
		(start 187.367418 -18.824448)
		(end 186.534298 -19.657568)
		(width 0.089408)
		(layer "In9.Cu")
		(net "FM_CPU1_SKTOCC_LVT3_N")
	)
	(segment
		(start 135.7122 -59.4614)
		(end 135.448802 -59.724798)
		(width 0.089408)
		(layer "In9.Cu")
		(net "FM_CPU1_SKTOCC_LVT3_N")
	)
	(segment
		(start 132.9436 -63.5762)
		(end 132.9436 -62.27191)
		(width 0.089408)
		(layer "In9.Cu")
		(net "FM_CPU1_SKTOCC_LVT3_N")
	)
	(segment
		(start 193.404236 -13.677646)
		(end 193.40449 -13.6779)
		(width 0.089408)
		(layer "In9.Cu")
		(net "FM_CPU1_SKTOCC_LVT3_N")
	)
	(segment
		(start 264.673334 -16.028924)
		(end 262.28929 -16.028924)
		(width 0.089408)
		(layer "In9.Cu")
		(net "FM_CPU1_SKTOCC_LVT3_N")
	)
	(segment
		(start 139.044934 -58.285634)
		(end 138.715242 -57.955942)
		(width 0.089408)
		(layer "In9.Cu")
		(net "FM_CPU1_SKTOCC_LVT3_N")
	)
	(segment
		(start 132.9436 -62.27191)
		(end 132.519674 -61.847984)
		(width 0.089408)
		(layer "In9.Cu")
		(net "FM_CPU1_SKTOCC_LVT3_N")
	)
	(segment
		(start 164.58438 -62.4586)
		(end 160.9344 -62.4586)
		(width 0.089408)
		(layer "In9.Cu")
		(net "FM_CPU1_SKTOCC_LVT3_N")
	)
	(segment
		(start 134.984236 -59.78271)
		(end 134.689088 -60.077858)
		(width 0.0889)
		(layer "In9.Cu")
		(net "FM_CPU1_SKTOCC_LVT3_N")
	)
	(arc
		(start 140.224764 -57.790588)
		(mid 139.941547 -57.874869)
		(end 139.734544 -58.085736)
		(width 0.0889)
		(layer "In9.Cu")
		(net "FM_CPU1_SKTOCC_LVT3_N")
	)
	(arc
		(start 134.583424 -61.057536)
		(mid 134.504202 -61.346654)
		(end 134.577074 -61.637418)
		(width 0.0889)
		(layer "In9.Cu")
		(net "FM_CPU1_SKTOCC_LVT3_N")
	)
	(arc
		(start 133.724904 -63.534036)
		(mid 133.583221 -63.67784)
		(end 133.38937 -63.734188)
		(width 0.0889)
		(layer "In9.Cu")
		(net "FM_CPU1_SKTOCC_LVT3_N")
	)
	(arc
		(start 139.734544 -58.085736)
		(mid 139.594465 -58.228472)
		(end 139.40282 -58.285634)
		(width 0.0889)
		(layer "In9.Cu")
		(net "FM_CPU1_SKTOCC_LVT3_N")
	)
	(arc
		(start 134.583424 -62.048136)
		(mid 134.504202 -62.337254)
		(end 134.577074 -62.628018)
		(width 0.0889)
		(layer "In9.Cu")
		(net "FM_CPU1_SKTOCC_LVT3_N")
	)
	(arc
		(start 141.941804 -57.790588)
		(mid 141.658587 -57.874869)
		(end 141.451584 -58.085736)
		(width 0.0889)
		(layer "In9.Cu")
		(net "FM_CPU1_SKTOCC_LVT3_N")
	)
	(arc
		(start 141.089888 -58.285634)
		(mid 140.898246 -58.228468)
		(end 140.758164 -58.085736)
		(width 0.0889)
		(layer "In9.Cu")
		(net "FM_CPU1_SKTOCC_LVT3_N")
	)
	(arc
		(start 141.451584 -58.085736)
		(mid 141.311505 -58.228472)
		(end 141.11986 -58.285634)
		(width 0.0889)
		(layer "In9.Cu")
		(net "FM_CPU1_SKTOCC_LVT3_N")
	)
	(arc
		(start 134.58825 -61.656722)
		(mid 134.637005 -61.853074)
		(end 134.583424 -62.048136)
		(width 0.0889)
		(layer "In9.Cu")
		(net "FM_CPU1_SKTOCC_LVT3_N")
	)
	(arc
		(start 134.58825 -62.647322)
		(mid 134.584503 -63.036578)
		(end 134.2517 -63.238634)
		(width 0.0889)
		(layer "In9.Cu")
		(net "FM_CPU1_SKTOCC_LVT3_N")
	)
	(arc
		(start 134.218934 -63.238634)
		(mid 133.93351 -63.322101)
		(end 133.724904 -63.534036)
		(width 0.0889)
		(layer "In9.Cu")
		(net "FM_CPU1_SKTOCC_LVT3_N")
	)
	(arc
		(start 140.758164 -58.085736)
		(mid 140.55116 -57.874872)
		(end 140.267944 -57.790588)
		(width 0.0889)
		(layer "In9.Cu")
		(net "FM_CPU1_SKTOCC_LVT3_N")
	)
	(segment
		(start 174.377604 -25.291796)
		(end 174.931832 -24.737568)
		(width 0.089408)
		(layer "In11.Cu")
		(net "FM_CPU1_SKTOCC_LVT3_N")
	)
	(segment
		(start 140.8684 -56.4642)
		(end 141.2494 -56.4642)
		(width 0.089408)
		(layer "In11.Cu")
		(net "FM_CPU1_SKTOCC_LVT3_N")
	)
	(segment
		(start 341.894668 -52.13604)
		(end 346.71635 -52.13604)
		(width 0.089408)
		(layer "In11.Cu")
		(net "FM_CPU1_SKTOCC_LVT3_N")
	)
	(segment
		(start 372.821962 -84.887816)
		(end 370.4336 -82.499454)
		(width 0.089408)
		(layer "In11.Cu")
		(net "FM_CPU1_SKTOCC_LVT3_N")
	)
	(segment
		(start 142.2146 -55.9816)
		(end 142.5448 -56.3118)
		(width 0.089408)
		(layer "In11.Cu")
		(net "FM_CPU1_SKTOCC_LVT3_N")
	)
	(segment
		(start 373.526304 -87.680038)
		(end 372.821962 -86.975696)
		(width 0.089408)
		(layer "In11.Cu")
		(net "FM_CPU1_SKTOCC_LVT3_N")
	)
	(segment
		(start 165.024308 -32.8422)
		(end 168.760902 -32.8422)
		(width 0.089408)
		(layer "In11.Cu")
		(net "FM_CPU1_SKTOCC_LVT3_N")
	)
	(segment
		(start 172.8216 -29.80309)
		(end 172.8216 -29.048202)
		(width 0.089408)
		(layer "In11.Cu")
		(net "FM_CPU1_SKTOCC_LVT3_N")
	)
	(segment
		(start 323.614796 -31.773368)
		(end 322.822824 -32.56534)
		(width 0.089408)
		(layer "In11.Cu")
		(net "FM_CPU1_SKTOCC_LVT3_N")
	)
	(segment
		(start 172.542962 -30.475682)
		(end 172.8216 -29.80309)
		(width 0.089408)
		(layer "In11.Cu")
		(net "FM_CPU1_SKTOCC_LVT3_N")
	)
	(segment
		(start 139.5222 -57.3532)
		(end 140.0048 -56.8706)
		(width 0.089408)
		(layer "In11.Cu")
		(net "FM_CPU1_SKTOCC_LVT3_N")
	)
	(segment
		(start 318.859916 -34.70402)
		(end 318.859916 -35.447732)
		(width 0.089408)
		(layer "In11.Cu")
		(net "FM_CPU1_SKTOCC_LVT3_N")
	)
	(segment
		(start 138.2268 -57.9374)
		(end 138.6332 -57.9374)
		(width 0.089408)
		(layer "In11.Cu")
		(net "FM_CPU1_SKTOCC_LVT3_N")
	)
	(segment
		(start 144.7292 -51.984402)
		(end 146.500596 -47.707804)
		(width 0.089408)
		(layer "In11.Cu")
		(net "FM_CPU1_SKTOCC_LVT3_N")
	)
	(segment
		(start 178.3588 -22.3266)
		(end 179.184554 -21.500846)
		(width 0.089408)
		(layer "In11.Cu")
		(net "FM_CPU1_SKTOCC_LVT3_N")
	)
	(segment
		(start 322.1863 -24.9682)
		(end 321.798696 -25.355804)
		(width 0.089408)
		(layer "In11.Cu")
		(net "FM_CPU1_SKTOCC_LVT3_N")
	)
	(segment
		(start 171.177458 -31.841186)
		(end 172.542962 -30.475682)
		(width 0.089408)
		(layer "In11.Cu")
		(net "FM_CPU1_SKTOCC_LVT3_N")
	)
	(segment
		(start 337.616038 -50.911506)
		(end 337.616546 -50.910998)
		(width 0.089408)
		(layer "In11.Cu")
		(net "FM_CPU1_SKTOCC_LVT3_N")
	)
	(segment
		(start 143.891254 -55.549546)
		(end 144.7292 -53.526436)
		(width 0.089408)
		(layer "In11.Cu")
		(net "FM_CPU1_SKTOCC_LVT3_N")
	)
	(segment
		(start 180.227986 -21.500846)
		(end 180.22824 -21.500592)
		(width 0.089408)
		(layer "In11.Cu")
		(net "FM_CPU1_SKTOCC_LVT3_N")
	)
	(segment
		(start 346.71635 -52.13604)
		(end 347.418406 -52.838096)
		(width 0.089408)
		(layer "In11.Cu")
		(net "FM_CPU1_SKTOCC_LVT3_N")
	)
	(segment
		(start 338.091526 -50.910998)
		(end 338.09178 -50.911252)
		(width 0.089408)
		(layer "In11.Cu")
		(net "FM_CPU1_SKTOCC_LVT3_N")
	)
	(segment
		(start 317.5 -42.817034)
		(end 319.806066 -45.1231)
		(width 0.089408)
		(layer "In11.Cu")
		(net "FM_CPU1_SKTOCC_LVT3_N")
	)
	(segment
		(start 135.080248 -59.962288)
		(end 135.581136 -59.4614)
		(width 0.089408)
		(layer "In11.Cu")
		(net "FM_CPU1_SKTOCC_LVT3_N")
	)
	(segment
		(start 317.5 -36.807648)
		(end 317.5 -42.817034)
		(width 0.089408)
		(layer "In11.Cu")
		(net "FM_CPU1_SKTOCC_LVT3_N")
	)
	(segment
		(start 139.2174 -57.3532)
		(end 139.5222 -57.3532)
		(width 0.089408)
		(layer "In11.Cu")
		(net "FM_CPU1_SKTOCC_LVT3_N")
	)
	(segment
		(start 158.779464 -35.428936)
		(end 165.024308 -32.8422)
		(width 0.089408)
		(layer "In11.Cu")
		(net "FM_CPU1_SKTOCC_LVT3_N")
	)
	(segment
		(start 372.821962 -86.975696)
		(end 372.821962 -84.887816)
		(width 0.089408)
		(layer "In11.Cu")
		(net "FM_CPU1_SKTOCC_LVT3_N")
	)
	(segment
		(start 320.998596 -32.56534)
		(end 318.859916 -34.70402)
		(width 0.089408)
		(layer "In11.Cu")
		(net "FM_CPU1_SKTOCC_LVT3_N")
	)
	(segment
		(start 322.91147 -45.1231)
		(end 328.699876 -50.911506)
		(width 0.089408)
		(layer "In11.Cu")
		(net "FM_CPU1_SKTOCC_LVT3_N")
	)
	(segment
		(start 376.521472 -95.399606)
		(end 373.526304 -92.404438)
		(width 0.089408)
		(layer "In11.Cu")
		(net "FM_CPU1_SKTOCC_LVT3_N")
	)
	(segment
		(start 338.09178 -50.911252)
		(end 340.66988 -50.911252)
		(width 0.089408)
		(layer "In11.Cu")
		(net "FM_CPU1_SKTOCC_LVT3_N")
	)
	(segment
		(start 318.859916 -35.447732)
		(end 317.5 -36.807648)
		(width 0.089408)
		(layer "In11.Cu")
		(net "FM_CPU1_SKTOCC_LVT3_N")
	)
	(segment
		(start 143.129 -56.3118)
		(end 143.891254 -55.549546)
		(width 0.089408)
		(layer "In11.Cu")
		(net "FM_CPU1_SKTOCC_LVT3_N")
	)
	(segment
		(start 136.906 -58.9534)
		(end 137.4648 -58.3946)
		(width 0.089408)
		(layer "In11.Cu")
		(net "FM_CPU1_SKTOCC_LVT3_N")
	)
	(segment
		(start 141.732 -55.9816)
		(end 142.2146 -55.9816)
		(width 0.089408)
		(layer "In11.Cu")
		(net "FM_CPU1_SKTOCC_LVT3_N")
	)
	(segment
		(start 172.8216 -29.048202)
		(end 174.377604 -25.291796)
		(width 0.089408)
		(layer "In11.Cu")
		(net "FM_CPU1_SKTOCC_LVT3_N")
	)
	(segment
		(start 168.760902 -32.8422)
		(end 171.177458 -31.841186)
		(width 0.089408)
		(layer "In11.Cu")
		(net "FM_CPU1_SKTOCC_LVT3_N")
	)
	(segment
		(start 177.446686 -23.695914)
		(end 178.3588 -22.7838)
		(width 0.089408)
		(layer "In11.Cu")
		(net "FM_CPU1_SKTOCC_LVT3_N")
	)
	(segment
		(start 179.184554 -21.500846)
		(end 180.227986 -21.500846)
		(width 0.089408)
		(layer "In11.Cu")
		(net "FM_CPU1_SKTOCC_LVT3_N")
	)
	(segment
		(start 321.798696 -26.866596)
		(end 323.614796 -28.682696)
		(width 0.089408)
		(layer "In11.Cu")
		(net "FM_CPU1_SKTOCC_LVT3_N")
	)
	(segment
		(start 373.526304 -92.404438)
		(end 373.526304 -87.680038)
		(width 0.089408)
		(layer "In11.Cu")
		(net "FM_CPU1_SKTOCC_LVT3_N")
	)
	(segment
		(start 328.699876 -50.911506)
		(end 337.616038 -50.911506)
		(width 0.089408)
		(layer "In11.Cu")
		(net "FM_CPU1_SKTOCC_LVT3_N")
	)
	(segment
		(start 376.521472 -95.506032)
		(end 376.521472 -95.399606)
		(width 0.089408)
		(layer "In11.Cu")
		(net "FM_CPU1_SKTOCC_LVT3_N")
	)
	(segment
		(start 321.798696 -25.355804)
		(end 321.798696 -26.866596)
		(width 0.089408)
		(layer "In11.Cu")
		(net "FM_CPU1_SKTOCC_LVT3_N")
	)
	(segment
		(start 140.462 -56.8706)
		(end 140.8684 -56.4642)
		(width 0.089408)
		(layer "In11.Cu")
		(net "FM_CPU1_SKTOCC_LVT3_N")
	)
	(segment
		(start 322.6689 -24.9682)
		(end 322.1863 -24.9682)
		(width 0.089408)
		(layer "In11.Cu")
		(net "FM_CPU1_SKTOCC_LVT3_N")
	)
	(segment
		(start 378.32665 -98.464116)
		(end 378.32665 -97.31121)
		(width 0.089408)
		(layer "In11.Cu")
		(net "FM_CPU1_SKTOCC_LVT3_N")
	)
	(segment
		(start 135.581136 -59.4614)
		(end 136.144 -59.4614)
		(width 0.089408)
		(layer "In11.Cu")
		(net "FM_CPU1_SKTOCC_LVT3_N")
	)
	(segment
		(start 178.3588 -22.7838)
		(end 178.3588 -22.3266)
		(width 0.089408)
		(layer "In11.Cu")
		(net "FM_CPU1_SKTOCC_LVT3_N")
	)
	(segment
		(start 137.4648 -58.3946)
		(end 137.7696 -58.3946)
		(width 0.089408)
		(layer "In11.Cu")
		(net "FM_CPU1_SKTOCC_LVT3_N")
	)
	(segment
		(start 347.418406 -52.838096)
		(end 347.418406 -53.140864)
		(width 0.089408)
		(layer "In11.Cu")
		(net "FM_CPU1_SKTOCC_LVT3_N")
	)
	(segment
		(start 319.806066 -45.1231)
		(end 322.91147 -45.1231)
		(width 0.089408)
		(layer "In11.Cu")
		(net "FM_CPU1_SKTOCC_LVT3_N")
	)
	(segment
		(start 340.66988 -50.911252)
		(end 341.894668 -52.13604)
		(width 0.089408)
		(layer "In11.Cu")
		(net "FM_CPU1_SKTOCC_LVT3_N")
	)
	(segment
		(start 132.519674 -61.50991)
		(end 132.584698 -61.444886)
		(width 0.0889)
		(layer "In11.Cu")
		(net "FM_CPU1_SKTOCC_LVT3_N")
	)
	(segment
		(start 140.0048 -56.8706)
		(end 140.462 -56.8706)
		(width 0.089408)
		(layer "In11.Cu")
		(net "FM_CPU1_SKTOCC_LVT3_N")
	)
	(segment
		(start 137.7696 -58.3946)
		(end 138.2268 -57.9374)
		(width 0.089408)
		(layer "In11.Cu")
		(net "FM_CPU1_SKTOCC_LVT3_N")
	)
	(segment
		(start 146.500596 -47.707804)
		(end 158.779464 -35.428936)
		(width 0.089408)
		(layer "In11.Cu")
		(net "FM_CPU1_SKTOCC_LVT3_N")
	)
	(segment
		(start 133.363208 -60.952888)
		(end 133.395974 -60.952888)
		(width 0.0889)
		(layer "In11.Cu")
		(net "FM_CPU1_SKTOCC_LVT3_N")
	)
	(segment
		(start 136.652 -58.9534)
		(end 136.906 -58.9534)
		(width 0.089408)
		(layer "In11.Cu")
		(net "FM_CPU1_SKTOCC_LVT3_N")
	)
	(segment
		(start 323.614796 -28.682696)
		(end 323.614796 -31.773368)
		(width 0.089408)
		(layer "In11.Cu")
		(net "FM_CPU1_SKTOCC_LVT3_N")
	)
	(segment
		(start 142.5448 -56.3118)
		(end 143.129 -56.3118)
		(width 0.089408)
		(layer "In11.Cu")
		(net "FM_CPU1_SKTOCC_LVT3_N")
	)
	(segment
		(start 134.225538 -60.457334)
		(end 134.258304 -60.457334)
		(width 0.0889)
		(layer "In11.Cu")
		(net "FM_CPU1_SKTOCC_LVT3_N")
	)
	(segment
		(start 132.519674 -61.847984)
		(end 132.519674 -61.50991)
		(width 0.0889)
		(layer "In11.Cu")
		(net "FM_CPU1_SKTOCC_LVT3_N")
	)
	(segment
		(start 174.931832 -24.737568)
		(end 177.446686 -23.695914)
		(width 0.089408)
		(layer "In11.Cu")
		(net "FM_CPU1_SKTOCC_LVT3_N")
	)
	(segment
		(start 138.6332 -57.9374)
		(end 139.2174 -57.3532)
		(width 0.089408)
		(layer "In11.Cu")
		(net "FM_CPU1_SKTOCC_LVT3_N")
	)
	(segment
		(start 144.7292 -53.526436)
		(end 144.7292 -51.984402)
		(width 0.089408)
		(layer "In11.Cu")
		(net "FM_CPU1_SKTOCC_LVT3_N")
	)
	(segment
		(start 378.32665 -97.31121)
		(end 376.521472 -95.506032)
		(width 0.089408)
		(layer "In11.Cu")
		(net "FM_CPU1_SKTOCC_LVT3_N")
	)
	(segment
		(start 370.4336 -82.499454)
		(end 370.4336 -80.899)
		(width 0.089408)
		(layer "In11.Cu")
		(net "FM_CPU1_SKTOCC_LVT3_N")
	)
	(segment
		(start 136.144 -59.4614)
		(end 136.652 -58.9534)
		(width 0.089408)
		(layer "In11.Cu")
		(net "FM_CPU1_SKTOCC_LVT3_N")
	)
	(segment
		(start 337.616546 -50.910998)
		(end 338.091526 -50.910998)
		(width 0.089408)
		(layer "In11.Cu")
		(net "FM_CPU1_SKTOCC_LVT3_N")
	)
	(segment
		(start 322.822824 -32.56534)
		(end 320.998596 -32.56534)
		(width 0.089408)
		(layer "In11.Cu")
		(net "FM_CPU1_SKTOCC_LVT3_N")
	)
	(segment
		(start 141.2494 -56.4642)
		(end 141.732 -55.9816)
		(width 0.089408)
		(layer "In11.Cu")
		(net "FM_CPU1_SKTOCC_LVT3_N")
	)
	(arc
		(start 132.584698 -61.444886)
		(mid 132.842968 -61.352178)
		(end 133.031484 -61.152786)
		(width 0.0889)
		(layer "In11.Cu")
		(net "FM_CPU1_SKTOCC_LVT3_N")
	)
	(arc
		(start 134.748524 -60.162186)
		(mid 134.888603 -60.01945)
		(end 135.080248 -59.962288)
		(width 0.089408)
		(layer "In11.Cu")
		(net "FM_CPU1_SKTOCC_LVT3_N")
	)
	(arc
		(start 134.258304 -60.457334)
		(mid 134.541521 -60.373053)
		(end 134.748524 -60.162186)
		(width 0.089408)
		(layer "In11.Cu")
		(net "FM_CPU1_SKTOCC_LVT3_N")
	)
	(arc
		(start 133.031484 -61.152786)
		(mid 133.171563 -61.01005)
		(end 133.363208 -60.952888)
		(width 0.0889)
		(layer "In11.Cu")
		(net "FM_CPU1_SKTOCC_LVT3_N")
	)
	(arc
		(start 133.890004 -60.657486)
		(mid 134.031687 -60.513682)
		(end 134.225538 -60.457334)
		(width 0.0889)
		(layer "In11.Cu")
		(net "FM_CPU1_SKTOCC_LVT3_N")
	)
	(arc
		(start 133.395974 -60.952888)
		(mid 133.681398 -60.869421)
		(end 133.890004 -60.657486)
		(width 0.0889)
		(layer "In11.Cu")
		(net "FM_CPU1_SKTOCC_LVT3_N")
	)
	(segment
		(start 340.085426 -75.257152)
		(end 337.105498 -75.257152)
		(width 0.10795)
		(layer "F.Cu")
		(net "FM_CPU0_SKTOCC_LVT3_N")
	)
	(segment
		(start 355.164644 -71.052944)
		(end 353.224338 -72.99325)
		(width 0.10795)
		(layer "F.Cu")
		(net "FM_CPU0_SKTOCC_LVT3_N")
	)
	(segment
		(start 366.573816 -80.86852)
		(end 365.723678 -80.86852)
		(width 0.10795)
		(layer "F.Cu")
		(net "FM_CPU0_SKTOCC_LVT3_N")
	)
	(segment
		(start 364.047532 -79.192374)
		(end 364.047532 -75.401932)
		(width 0.10795)
		(layer "F.Cu")
		(net "FM_CPU0_SKTOCC_LVT3_N")
	)
	(segment
		(start 367.945162 -80.694784)
		(end 368.344958 -80.294988)
		(width 0.1016)
		(layer "F.Cu")
		(net "FM_CPU0_SKTOCC_LVT3_N")
	)
	(segment
		(start 360.361738 -71.716138)
		(end 357.73614 -71.716138)
		(width 0.10795)
		(layer "F.Cu")
		(net "FM_CPU0_SKTOCC_LVT3_N")
	)
	(segment
		(start 342.265 -73.077578)
		(end 340.085426 -75.257152)
		(width 0.10795)
		(layer "F.Cu")
		(net "FM_CPU0_SKTOCC_LVT3_N")
	)
	(segment
		(start 336.279744 -74.431398)
		(end 333.007462 -74.431398)
		(width 0.10795)
		(layer "F.Cu")
		(net "FM_CPU0_SKTOCC_LVT3_N")
	)
	(segment
		(start 353.224338 -72.99325)
		(end 349.895668 -72.99325)
		(width 0.10795)
		(layer "F.Cu")
		(net "FM_CPU0_SKTOCC_LVT3_N")
	)
	(segment
		(start 366.802162 -81.096866)
		(end 366.573816 -80.86852)
		(width 0.10795)
		(layer "F.Cu")
		(net "FM_CPU0_SKTOCC_LVT3_N")
	)
	(segment
		(start 342.265 -72.516746)
		(end 342.265 -73.077578)
		(width 0.10795)
		(layer "F.Cu")
		(net "FM_CPU0_SKTOCC_LVT3_N")
	)
	(segment
		(start 331.660754 -75.21194)
		(end 331.449426 -75.423268)
		(width 0.10795)
		(layer "F.Cu")
		(net "FM_CPU0_SKTOCC_LVT3_N")
	)
	(segment
		(start 377.33605 -97.83572)
		(end 377.83135 -97.605596)
		(width 0.10795)
		(layer "F.Cu")
		(net "FM_CPU0_SKTOCC_LVT3_N")
	)
	(segment
		(start 357.73614 -71.716138)
		(end 357.072946 -71.052944)
		(width 0.10795)
		(layer "F.Cu")
		(net "FM_CPU0_SKTOCC_LVT3_N")
	)
	(segment
		(start 365.723678 -80.86852)
		(end 364.047532 -79.192374)
		(width 0.10795)
		(layer "F.Cu")
		(net "FM_CPU0_SKTOCC_LVT3_N")
	)
	(segment
		(start 367.945162 -80.694784)
		(end 367.54308 -81.096866)
		(width 0.10795)
		(layer "F.Cu")
		(net "FM_CPU0_SKTOCC_LVT3_N")
	)
	(segment
		(start 332.22692 -75.21194)
		(end 331.660754 -75.21194)
		(width 0.10795)
		(layer "F.Cu")
		(net "FM_CPU0_SKTOCC_LVT3_N")
	)
	(segment
		(start 331.449426 -75.423268)
		(end 330.903072 -75.423268)
		(width 0.10795)
		(layer "F.Cu")
		(net "FM_CPU0_SKTOCC_LVT3_N")
	)
	(segment
		(start 343.347548 -71.434198)
		(end 342.265 -72.516746)
		(width 0.10795)
		(layer "F.Cu")
		(net "FM_CPU0_SKTOCC_LVT3_N")
	)
	(segment
		(start 349.895668 -72.99325)
		(end 348.336616 -71.434198)
		(width 0.10795)
		(layer "F.Cu")
		(net "FM_CPU0_SKTOCC_LVT3_N")
	)
	(segment
		(start 364.047532 -75.401932)
		(end 360.361738 -71.716138)
		(width 0.10795)
		(layer "F.Cu")
		(net "FM_CPU0_SKTOCC_LVT3_N")
	)
	(segment
		(start 333.007462 -74.431398)
		(end 332.22692 -75.21194)
		(width 0.10795)
		(layer "F.Cu")
		(net "FM_CPU0_SKTOCC_LVT3_N")
	)
	(segment
		(start 409.890214 -38.934644)
		(end 410.290264 -38.534594)
		(width 0.10795)
		(layer "F.Cu")
		(net "FM_CPU0_SKTOCC_LVT3_N")
	)
	(segment
		(start 296.948606 -61.847984)
		(end 297.520106 -61.847984)
		(width 0.1016)
		(layer "F.Cu")
		(net "FM_CPU0_SKTOCC_LVT3_N")
	)
	(segment
		(start 367.54308 -81.096866)
		(end 366.802162 -81.096866)
		(width 0.10795)
		(layer "F.Cu")
		(net "FM_CPU0_SKTOCC_LVT3_N")
	)
	(segment
		(start 337.105498 -75.257152)
		(end 336.279744 -74.431398)
		(width 0.10795)
		(layer "F.Cu")
		(net "FM_CPU0_SKTOCC_LVT3_N")
	)
	(segment
		(start 357.072946 -71.052944)
		(end 355.164644 -71.052944)
		(width 0.10795)
		(layer "F.Cu")
		(net "FM_CPU0_SKTOCC_LVT3_N")
	)
	(segment
		(start 348.336616 -71.434198)
		(end 343.347548 -71.434198)
		(width 0.10795)
		(layer "F.Cu")
		(net "FM_CPU0_SKTOCC_LVT3_N")
	)
	(via
		(at 322.453 -59.9186)
		(size 0.6604)
		(drill 0.3302)
		(layers "F.Cu" "B.Cu")
		(net "FM_CPU0_SKTOCC_LVT3_N")
	)
	(via
		(at 297.520106 -61.847984)
		(size 0.508)
		(drill 0.254)
		(layers "F.Cu" "B.Cu")
		(net "FM_CPU0_SKTOCC_LVT3_N")
	)
	(via
		(at 367.945162 -80.694784)
		(size 0.4572)
		(drill 0.2032)
		(layers "F.Cu" "B.Cu")
		(net "FM_CPU0_SKTOCC_LVT3_N")
	)
	(via
		(at 409.890214 -38.934644)
		(size 0.4572)
		(drill 0.2032)
		(layers "F.Cu" "B.Cu")
		(net "FM_CPU0_SKTOCC_LVT3_N")
	)
	(via
		(at 379.714506 -40.513)
		(size 0.508)
		(drill 0.254)
		(layers "F.Cu" "B.Cu")
		(net "FM_CPU0_SKTOCC_LVT3_N")
	)
	(via
		(at 336.924396 -54.991)
		(size 0.508)
		(drill 0.254)
		(layers "F.Cu" "B.Cu")
		(net "FM_CPU0_SKTOCC_LVT3_N")
	)
	(via
		(at 377.83135 -97.605596)
		(size 0.508)
		(drill 0.254)
		(layers "F.Cu" "B.Cu")
		(net "FM_CPU0_SKTOCC_LVT3_N")
	)
	(via
		(at 396.7861 -40.8178)
		(size 0.508)
		(drill 0.254)
		(layers "F.Cu" "B.Cu")
		(net "FM_CPU0_SKTOCC_LVT3_N")
	)
	(via
		(at 330.903072 -75.423268)
		(size 0.508)
		(drill 0.254)
		(layers "F.Cu" "B.Cu")
		(net "FM_CPU0_SKTOCC_LVT3_N")
	)
	(segment
		(start 303.7459 -57.9501)
		(end 304.2539 -57.4421)
		(width 0.10795)
		(layer "B.Cu")
		(net "FM_CPU0_SKTOCC_LVT3_N")
	)
	(segment
		(start 302.0949 -58.8264)
		(end 302.5775 -58.3438)
		(width 0.10795)
		(layer "B.Cu")
		(net "FM_CPU0_SKTOCC_LVT3_N")
	)
	(segment
		(start 306.09032 -58.285634)
		(end 306.120292 -58.285634)
		(width 0.0889)
		(layer "B.Cu")
		(net "FM_CPU0_SKTOCC_LVT3_N")
	)
	(segment
		(start 299.4914 -60.325)
		(end 299.974 -59.8424)
		(width 0.10795)
		(layer "B.Cu")
		(net "FM_CPU0_SKTOCC_LVT3_N")
	)
	(segment
		(start 316.192408 -58.399426)
		(end 316.584838 -58.657236)
		(width 0.10795)
		(layer "B.Cu")
		(net "FM_CPU0_SKTOCC_LVT3_N")
	)
	(segment
		(start 326.932798 -59.752992)
		(end 327.052686 -59.87288)
		(width 0.10795)
		(layer "B.Cu")
		(net "FM_CPU0_SKTOCC_LVT3_N")
	)
	(segment
		(start 303.3141 -57.9501)
		(end 303.7459 -57.9501)
		(width 0.10795)
		(layer "B.Cu")
		(net "FM_CPU0_SKTOCC_LVT3_N")
	)
	(segment
		(start 317.503556 -59.261502)
		(end 319.107058 -59.9186)
		(width 0.10795)
		(layer "B.Cu")
		(net "FM_CPU0_SKTOCC_LVT3_N")
	)
	(segment
		(start 316.584838 -58.657236)
		(end 316.586362 -58.657998)
		(width 0.10795)
		(layer "B.Cu")
		(net "FM_CPU0_SKTOCC_LVT3_N")
	)
	(segment
		(start 323.530976 -60.448952)
		(end 323.000624 -59.9186)
		(width 0.10795)
		(layer "B.Cu")
		(net "FM_CPU0_SKTOCC_LVT3_N")
	)
	(segment
		(start 298.1833 -60.8203)
		(end 298.54779 -60.8203)
		(width 0.10795)
		(layer "B.Cu")
		(net "FM_CPU0_SKTOCC_LVT3_N")
	)
	(segment
		(start 300.3169 -59.8424)
		(end 300.8503 -59.309)
		(width 0.10795)
		(layer "B.Cu")
		(net "FM_CPU0_SKTOCC_LVT3_N")
	)
	(segment
		(start 297.520106 -61.483494)
		(end 298.1833 -60.8203)
		(width 0.10795)
		(layer "B.Cu")
		(net "FM_CPU0_SKTOCC_LVT3_N")
	)
	(segment
		(start 299.04309 -60.325)
		(end 299.4914 -60.325)
		(width 0.10795)
		(layer "B.Cu")
		(net "FM_CPU0_SKTOCC_LVT3_N")
	)
	(segment
		(start 327.06818 -58.724546)
		(end 326.171306 -58.724546)
		(width 0.10795)
		(layer "B.Cu")
		(net "FM_CPU0_SKTOCC_LVT3_N")
	)
	(segment
		(start 336.175096 -57.013348)
		(end 336.924396 -56.264048)
		(width 0.10795)
		(layer "B.Cu")
		(net "FM_CPU0_SKTOCC_LVT3_N")
	)
	(segment
		(start 302.9204 -58.3438)
		(end 303.3141 -57.9501)
		(width 0.10795)
		(layer "B.Cu")
		(net "FM_CPU0_SKTOCC_LVT3_N")
	)
	(segment
		(start 306.942236 -57.790588)
		(end 307.130196 -57.790588)
		(width 0.0889)
		(layer "B.Cu")
		(net "FM_CPU0_SKTOCC_LVT3_N")
	)
	(segment
		(start 327.06818 -58.724546)
		(end 327.06818 -59.100212)
		(width 0.10795)
		(layer "B.Cu")
		(net "FM_CPU0_SKTOCC_LVT3_N")
	)
	(segment
		(start 323.000624 -59.9186)
		(end 322.453 -59.9186)
		(width 0.10795)
		(layer "B.Cu")
		(net "FM_CPU0_SKTOCC_LVT3_N")
	)
	(segment
		(start 319.107058 -59.9186)
		(end 322.453 -59.9186)
		(width 0.10795)
		(layer "B.Cu")
		(net "FM_CPU0_SKTOCC_LVT3_N")
	)
	(segment
		(start 301.2313 -59.309)
		(end 301.7139 -58.8264)
		(width 0.10795)
		(layer "B.Cu")
		(net "FM_CPU0_SKTOCC_LVT3_N")
	)
	(segment
		(start 326.932798 -59.235594)
		(end 326.932798 -59.752992)
		(width 0.10795)
		(layer "B.Cu")
		(net "FM_CPU0_SKTOCC_LVT3_N")
	)
	(segment
		(start 300.8503 -59.309)
		(end 301.2313 -59.309)
		(width 0.10795)
		(layer "B.Cu")
		(net "FM_CPU0_SKTOCC_LVT3_N")
	)
	(segment
		(start 304.919888 -57.790588)
		(end 305.268376 -57.790588)
		(width 0.0889)
		(layer "B.Cu")
		(net "FM_CPU0_SKTOCC_LVT3_N")
	)
	(segment
		(start 304.2539 -57.4421)
		(end 304.5714 -57.4421)
		(width 0.10795)
		(layer "B.Cu")
		(net "FM_CPU0_SKTOCC_LVT3_N")
	)
	(segment
		(start 330.66355 -58.596276)
		(end 332.246478 -57.013348)
		(width 0.10795)
		(layer "B.Cu")
		(net "FM_CPU0_SKTOCC_LVT3_N")
	)
	(segment
		(start 297.520106 -61.847984)
		(end 297.520106 -61.483494)
		(width 0.10795)
		(layer "B.Cu")
		(net "FM_CPU0_SKTOCC_LVT3_N")
	)
	(segment
		(start 307.787802 -57.3278)
		(end 308.96052 -57.3278)
		(width 0.10795)
		(layer "B.Cu")
		(net "FM_CPU0_SKTOCC_LVT3_N")
	)
	(segment
		(start 327.06818 -59.100212)
		(end 326.932798 -59.235594)
		(width 0.10795)
		(layer "B.Cu")
		(net "FM_CPU0_SKTOCC_LVT3_N")
	)
	(segment
		(start 332.246478 -57.013348)
		(end 336.175096 -57.013348)
		(width 0.10795)
		(layer "B.Cu")
		(net "FM_CPU0_SKTOCC_LVT3_N")
	)
	(segment
		(start 327.052686 -59.87288)
		(end 328.321924 -59.87288)
		(width 0.10795)
		(layer "B.Cu")
		(net "FM_CPU0_SKTOCC_LVT3_N")
	)
	(segment
		(start 328.321924 -59.87288)
		(end 329.598528 -58.596276)
		(width 0.10795)
		(layer "B.Cu")
		(net "FM_CPU0_SKTOCC_LVT3_N")
	)
	(segment
		(start 309.39232 -56.896)
		(end 312.564526 -56.896)
		(width 0.10795)
		(layer "B.Cu")
		(net "FM_CPU0_SKTOCC_LVT3_N")
	)
	(segment
		(start 299.974 -59.8424)
		(end 300.3169 -59.8424)
		(width 0.10795)
		(layer "B.Cu")
		(net "FM_CPU0_SKTOCC_LVT3_N")
	)
	(segment
		(start 302.5775 -58.3438)
		(end 302.9204 -58.3438)
		(width 0.10795)
		(layer "B.Cu")
		(net "FM_CPU0_SKTOCC_LVT3_N")
	)
	(segment
		(start 336.924396 -56.264048)
		(end 336.924396 -54.991)
		(width 0.10795)
		(layer "B.Cu")
		(net "FM_CPU0_SKTOCC_LVT3_N")
	)
	(segment
		(start 304.5714 -57.4421)
		(end 304.919888 -57.790588)
		(width 0.10795)
		(layer "B.Cu")
		(net "FM_CPU0_SKTOCC_LVT3_N")
	)
	(segment
		(start 326.171306 -58.724546)
		(end 324.4469 -60.448952)
		(width 0.10795)
		(layer "B.Cu")
		(net "FM_CPU0_SKTOCC_LVT3_N")
	)
	(segment
		(start 316.586362 -58.657998)
		(end 317.503556 -59.261502)
		(width 0.10795)
		(layer "B.Cu")
		(net "FM_CPU0_SKTOCC_LVT3_N")
	)
	(segment
		(start 312.564526 -56.896)
		(end 316.192408 -58.399426)
		(width 0.10795)
		(layer "B.Cu")
		(net "FM_CPU0_SKTOCC_LVT3_N")
	)
	(segment
		(start 301.7139 -58.8264)
		(end 302.0949 -58.8264)
		(width 0.10795)
		(layer "B.Cu")
		(net "FM_CPU0_SKTOCC_LVT3_N")
	)
	(segment
		(start 324.4469 -60.448952)
		(end 323.530976 -60.448952)
		(width 0.10795)
		(layer "B.Cu")
		(net "FM_CPU0_SKTOCC_LVT3_N")
	)
	(segment
		(start 298.54779 -60.8203)
		(end 299.04309 -60.325)
		(width 0.10795)
		(layer "B.Cu")
		(net "FM_CPU0_SKTOCC_LVT3_N")
	)
	(segment
		(start 329.598528 -58.596276)
		(end 330.66355 -58.596276)
		(width 0.10795)
		(layer "B.Cu")
		(net "FM_CPU0_SKTOCC_LVT3_N")
	)
	(segment
		(start 308.96052 -57.3278)
		(end 309.39232 -56.896)
		(width 0.10795)
		(layer "B.Cu")
		(net "FM_CPU0_SKTOCC_LVT3_N")
	)
	(arc
		(start 306.452016 -58.085736)
		(mid 306.65902 -57.874872)
		(end 306.942236 -57.790588)
		(width 0.0889)
		(layer "B.Cu")
		(net "FM_CPU0_SKTOCC_LVT3_N")
	)
	(arc
		(start 306.120292 -58.285634)
		(mid 306.311934 -58.228468)
		(end 306.452016 -58.085736)
		(width 0.0889)
		(layer "B.Cu")
		(net "FM_CPU0_SKTOCC_LVT3_N")
	)
	(arc
		(start 305.758596 -58.085736)
		(mid 305.898675 -58.228472)
		(end 306.09032 -58.285634)
		(width 0.0889)
		(layer "B.Cu")
		(net "FM_CPU0_SKTOCC_LVT3_N")
	)
	(arc
		(start 307.130196 -57.790588)
		(mid 307.255683 -57.710755)
		(end 307.346858 -57.59323)
		(width 0.0889)
		(layer "B.Cu")
		(net "FM_CPU0_SKTOCC_LVT3_N")
	)
	(arc
		(start 307.346858 -57.59323)
		(mid 307.530486 -57.399328)
		(end 307.787802 -57.3278)
		(width 0.10795)
		(layer "B.Cu")
		(net "FM_CPU0_SKTOCC_LVT3_N")
	)
	(arc
		(start 305.268376 -57.790588)
		(mid 305.551593 -57.874869)
		(end 305.758596 -58.085736)
		(width 0.0889)
		(layer "B.Cu")
		(net "FM_CPU0_SKTOCC_LVT3_N")
	)
	(segment
		(start 379.714506 -40.513)
		(end 379.37059 -40.513)
		(width 0.089408)
		(layer "In2.Cu")
		(net "FM_CPU0_SKTOCC_LVT3_N")
	)
	(segment
		(start 371.724174 -62.241176)
		(end 369.63985 -64.3255)
		(width 0.089408)
		(layer "In2.Cu")
		(net "FM_CPU0_SKTOCC_LVT3_N")
	)
	(segment
		(start 377.2154 -42.66819)
		(end 377.2154 -53.695346)
		(width 0.089408)
		(layer "In2.Cu")
		(net "FM_CPU0_SKTOCC_LVT3_N")
	)
	(segment
		(start 367.565178 -67.511168)
		(end 367.565178 -80.041242)
		(width 0.089408)
		(layer "In2.Cu")
		(net "FM_CPU0_SKTOCC_LVT3_N")
	)
	(segment
		(start 379.37059 -40.513)
		(end 377.2154 -42.66819)
		(width 0.089408)
		(layer "In2.Cu")
		(net "FM_CPU0_SKTOCC_LVT3_N")
	)
	(segment
		(start 401.2692 -40.8178)
		(end 402.682964 -39.404036)
		(width 0.089408)
		(layer "In2.Cu")
		(net "FM_CPU0_SKTOCC_LVT3_N")
	)
	(segment
		(start 375.441972 -55.468774)
		(end 375.441972 -58.25109)
		(width 0.089408)
		(layer "In2.Cu")
		(net "FM_CPU0_SKTOCC_LVT3_N")
	)
	(segment
		(start 402.682964 -39.404036)
		(end 406.645364 -39.404036)
		(width 0.089408)
		(layer "In2.Cu")
		(net "FM_CPU0_SKTOCC_LVT3_N")
	)
	(segment
		(start 369.63985 -64.3255)
		(end 369.556538 -64.3255)
		(width 0.089408)
		(layer "In2.Cu")
		(net "FM_CPU0_SKTOCC_LVT3_N")
	)
	(segment
		(start 369.322096 -64.559942)
		(end 369.322096 -64.941704)
		(width 0.089408)
		(layer "In2.Cu")
		(net "FM_CPU0_SKTOCC_LVT3_N")
	)
	(segment
		(start 407.4922 -38.5572)
		(end 409.51277 -38.5572)
		(width 0.089408)
		(layer "In2.Cu")
		(net "FM_CPU0_SKTOCC_LVT3_N")
	)
	(segment
		(start 375.441972 -58.25109)
		(end 371.724174 -61.968888)
		(width 0.089408)
		(layer "In2.Cu")
		(net "FM_CPU0_SKTOCC_LVT3_N")
	)
	(segment
		(start 367.945162 -80.42275)
		(end 367.945162 -80.694784)
		(width 0.089408)
		(layer "In2.Cu")
		(net "FM_CPU0_SKTOCC_LVT3_N")
	)
	(segment
		(start 377.2154 -53.695346)
		(end 375.441972 -55.468774)
		(width 0.089408)
		(layer "In2.Cu")
		(net "FM_CPU0_SKTOCC_LVT3_N")
	)
	(segment
		(start 371.724174 -61.968888)
		(end 371.724174 -62.241176)
		(width 0.089408)
		(layer "In2.Cu")
		(net "FM_CPU0_SKTOCC_LVT3_N")
	)
	(segment
		(start 367.8174 -66.2178)
		(end 367.8174 -67.258946)
		(width 0.089408)
		(layer "In2.Cu")
		(net "FM_CPU0_SKTOCC_LVT3_N")
	)
	(segment
		(start 396.7861 -40.8178)
		(end 401.2692 -40.8178)
		(width 0.089408)
		(layer "In2.Cu")
		(net "FM_CPU0_SKTOCC_LVT3_N")
	)
	(segment
		(start 369.1636 -65.1002)
		(end 368.935 -65.1002)
		(width 0.089408)
		(layer "In2.Cu")
		(net "FM_CPU0_SKTOCC_LVT3_N")
	)
	(segment
		(start 369.556538 -64.3255)
		(end 369.322096 -64.559942)
		(width 0.089408)
		(layer "In2.Cu")
		(net "FM_CPU0_SKTOCC_LVT3_N")
	)
	(segment
		(start 367.8174 -67.258946)
		(end 367.565178 -67.511168)
		(width 0.089408)
		(layer "In2.Cu")
		(net "FM_CPU0_SKTOCC_LVT3_N")
	)
	(segment
		(start 368.935 -65.1002)
		(end 367.8174 -66.2178)
		(width 0.089408)
		(layer "In2.Cu")
		(net "FM_CPU0_SKTOCC_LVT3_N")
	)
	(segment
		(start 367.565178 -80.041242)
		(end 367.571782 -80.047846)
		(width 0.089408)
		(layer "In2.Cu")
		(net "FM_CPU0_SKTOCC_LVT3_N")
	)
	(segment
		(start 409.51277 -38.5572)
		(end 409.890214 -38.934644)
		(width 0.089408)
		(layer "In2.Cu")
		(net "FM_CPU0_SKTOCC_LVT3_N")
	)
	(segment
		(start 367.571782 -80.04937)
		(end 367.945162 -80.42275)
		(width 0.089408)
		(layer "In2.Cu")
		(net "FM_CPU0_SKTOCC_LVT3_N")
	)
	(segment
		(start 369.322096 -64.941704)
		(end 369.1636 -65.1002)
		(width 0.089408)
		(layer "In2.Cu")
		(net "FM_CPU0_SKTOCC_LVT3_N")
	)
	(segment
		(start 406.645364 -39.404036)
		(end 407.4922 -38.5572)
		(width 0.089408)
		(layer "In2.Cu")
		(net "FM_CPU0_SKTOCC_LVT3_N")
	)
	(segment
		(start 367.571782 -80.047846)
		(end 367.571782 -80.04937)
		(width 0.089408)
		(layer "In2.Cu")
		(net "FM_CPU0_SKTOCC_LVT3_N")
	)
	(segment
		(start 380.762256 -38.928548)
		(end 380.762256 -39.64559)
		(width 0.089408)
		(layer "In4.Cu")
		(net "FM_CPU0_SKTOCC_LVT3_N")
	)
	(segment
		(start 384.237738 -37.794692)
		(end 383.523236 -37.794692)
		(width 0.089408)
		(layer "In4.Cu")
		(net "FM_CPU0_SKTOCC_LVT3_N")
	)
	(segment
		(start 380.851664 -38.83914)
		(end 380.762256 -38.928548)
		(width 0.089408)
		(layer "In4.Cu")
		(net "FM_CPU0_SKTOCC_LVT3_N")
	)
	(segment
		(start 388.715504 -38.32352)
		(end 387.904482 -37.512498)
		(width 0.089408)
		(layer "In4.Cu")
		(net "FM_CPU0_SKTOCC_LVT3_N")
	)
	(segment
		(start 379.894846 -40.513)
		(end 379.714506 -40.513)
		(width 0.089408)
		(layer "In4.Cu")
		(net "FM_CPU0_SKTOCC_LVT3_N")
	)
	(segment
		(start 387.904482 -37.512498)
		(end 384.519932 -37.512498)
		(width 0.089408)
		(layer "In4.Cu")
		(net "FM_CPU0_SKTOCC_LVT3_N")
	)
	(segment
		(start 382.478788 -38.83914)
		(end 380.851664 -38.83914)
		(width 0.089408)
		(layer "In4.Cu")
		(net "FM_CPU0_SKTOCC_LVT3_N")
	)
	(segment
		(start 396.7861 -40.8178)
		(end 396.650972 -40.952928)
		(width 0.089408)
		(layer "In4.Cu")
		(net "FM_CPU0_SKTOCC_LVT3_N")
	)
	(segment
		(start 390.7917 -39.497)
		(end 389.61822 -38.32352)
		(width 0.089408)
		(layer "In4.Cu")
		(net "FM_CPU0_SKTOCC_LVT3_N")
	)
	(segment
		(start 391.734548 -40.416226)
		(end 391.492232 -40.416226)
		(width 0.089408)
		(layer "In4.Cu")
		(net "FM_CPU0_SKTOCC_LVT3_N")
	)
	(segment
		(start 389.61822 -38.32352)
		(end 388.715504 -38.32352)
		(width 0.089408)
		(layer "In4.Cu")
		(net "FM_CPU0_SKTOCC_LVT3_N")
	)
	(segment
		(start 393.268454 -40.952928)
		(end 392.731498 -40.415972)
		(width 0.089408)
		(layer "In4.Cu")
		(net "FM_CPU0_SKTOCC_LVT3_N")
	)
	(segment
		(start 390.791446 -39.71544)
		(end 390.791446 -39.587678)
		(width 0.089408)
		(layer "In4.Cu")
		(net "FM_CPU0_SKTOCC_LVT3_N")
	)
	(segment
		(start 383.523236 -37.794692)
		(end 382.478788 -38.83914)
		(width 0.089408)
		(layer "In4.Cu")
		(net "FM_CPU0_SKTOCC_LVT3_N")
	)
	(segment
		(start 391.734802 -40.415972)
		(end 391.734548 -40.416226)
		(width 0.089408)
		(layer "In4.Cu")
		(net "FM_CPU0_SKTOCC_LVT3_N")
	)
	(segment
		(start 384.519932 -37.512498)
		(end 384.237738 -37.794692)
		(width 0.089408)
		(layer "In4.Cu")
		(net "FM_CPU0_SKTOCC_LVT3_N")
	)
	(segment
		(start 380.762256 -39.64559)
		(end 379.894846 -40.513)
		(width 0.089408)
		(layer "In4.Cu")
		(net "FM_CPU0_SKTOCC_LVT3_N")
	)
	(segment
		(start 390.7917 -39.587424)
		(end 390.7917 -39.497)
		(width 0.089408)
		(layer "In4.Cu")
		(net "FM_CPU0_SKTOCC_LVT3_N")
	)
	(segment
		(start 392.731498 -40.415972)
		(end 391.734802 -40.415972)
		(width 0.089408)
		(layer "In4.Cu")
		(net "FM_CPU0_SKTOCC_LVT3_N")
	)
	(segment
		(start 390.791446 -39.587678)
		(end 390.7917 -39.587424)
		(width 0.089408)
		(layer "In4.Cu")
		(net "FM_CPU0_SKTOCC_LVT3_N")
	)
	(segment
		(start 396.650972 -40.952928)
		(end 393.268454 -40.952928)
		(width 0.089408)
		(layer "In4.Cu")
		(net "FM_CPU0_SKTOCC_LVT3_N")
	)
	(segment
		(start 391.492232 -40.416226)
		(end 390.791446 -39.71544)
		(width 0.089408)
		(layer "In4.Cu")
		(net "FM_CPU0_SKTOCC_LVT3_N")
	)
	(segment
		(start 334.080358 -61.947806)
		(end 334.080358 -65.718182)
		(width 0.089408)
		(layer "In9.Cu")
		(net "FM_CPU0_SKTOCC_LVT3_N")
	)
	(segment
		(start 330.698348 -75.218544)
		(end 330.903072 -75.423268)
		(width 0.089408)
		(layer "In9.Cu")
		(net "FM_CPU0_SKTOCC_LVT3_N")
	)
	(segment
		(start 333.4258 -61.293248)
		(end 334.080358 -61.947806)
		(width 0.089408)
		(layer "In9.Cu")
		(net "FM_CPU0_SKTOCC_LVT3_N")
	)
	(segment
		(start 335.32699 -54.5592)
		(end 334.978756 -54.907434)
		(width 0.089408)
		(layer "In9.Cu")
		(net "FM_CPU0_SKTOCC_LVT3_N")
	)
	(segment
		(start 334.978756 -57.197244)
		(end 333.4258 -58.7502)
		(width 0.089408)
		(layer "In9.Cu")
		(net "FM_CPU0_SKTOCC_LVT3_N")
	)
	(segment
		(start 336.543396 -54.5592)
		(end 335.32699 -54.5592)
		(width 0.089408)
		(layer "In9.Cu")
		(net "FM_CPU0_SKTOCC_LVT3_N")
	)
	(segment
		(start 334.080358 -65.718182)
		(end 330.698348 -69.100192)
		(width 0.089408)
		(layer "In9.Cu")
		(net "FM_CPU0_SKTOCC_LVT3_N")
	)
	(segment
		(start 330.698348 -69.100192)
		(end 330.698348 -75.218544)
		(width 0.089408)
		(layer "In9.Cu")
		(net "FM_CPU0_SKTOCC_LVT3_N")
	)
	(segment
		(start 333.4258 -58.7502)
		(end 333.4258 -61.293248)
		(width 0.089408)
		(layer "In9.Cu")
		(net "FM_CPU0_SKTOCC_LVT3_N")
	)
	(segment
		(start 336.924396 -54.9402)
		(end 336.543396 -54.5592)
		(width 0.089408)
		(layer "In9.Cu")
		(net "FM_CPU0_SKTOCC_LVT3_N")
	)
	(segment
		(start 336.924396 -54.991)
		(end 336.924396 -54.9402)
		(width 0.089408)
		(layer "In9.Cu")
		(net "FM_CPU0_SKTOCC_LVT3_N")
	)
	(segment
		(start 334.978756 -54.907434)
		(end 334.978756 -57.197244)
		(width 0.089408)
		(layer "In9.Cu")
		(net "FM_CPU0_SKTOCC_LVT3_N")
	)
	(segment
		(start 372.369334 -91.625928)
		(end 372.453662 -91.5416)
		(width 0.089408)
		(layer "In11.Cu")
		(net "FM_CPU0_SKTOCC_LVT3_N")
	)
	(segment
		(start 372.453662 -91.5416)
		(end 372.453662 -88.794082)
		(width 0.089408)
		(layer "In11.Cu")
		(net "FM_CPU0_SKTOCC_LVT3_N")
	)
	(segment
		(start 373.146574 -93.382846)
		(end 373.044212 -93.280484)
		(width 0.089408)
		(layer "In11.Cu")
		(net "FM_CPU0_SKTOCC_LVT3_N")
	)
	(segment
		(start 375.658126 -95.591884)
		(end 375.658126 -94.845124)
		(width 0.089408)
		(layer "In11.Cu")
		(net "FM_CPU0_SKTOCC_LVT3_N")
	)
	(segment
		(start 372.453662 -88.794082)
		(end 371.91315 -88.25357)
		(width 0.089408)
		(layer "In11.Cu")
		(net "FM_CPU0_SKTOCC_LVT3_N")
	)
	(segment
		(start 373.044212 -93.280484)
		(end 373.043704 -93.280484)
		(width 0.089408)
		(layer "In11.Cu")
		(net "FM_CPU0_SKTOCC_LVT3_N")
	)
	(segment
		(start 377.83135 -97.605596)
		(end 377.671838 -97.605596)
		(width 0.089408)
		(layer "In11.Cu")
		(net "FM_CPU0_SKTOCC_LVT3_N")
	)
	(segment
		(start 373.043704 -93.280484)
		(end 372.369334 -92.606114)
		(width 0.089408)
		(layer "In11.Cu")
		(net "FM_CPU0_SKTOCC_LVT3_N")
	)
	(segment
		(start 374.195848 -93.382846)
		(end 373.146574 -93.382846)
		(width 0.089408)
		(layer "In11.Cu")
		(net "FM_CPU0_SKTOCC_LVT3_N")
	)
	(segment
		(start 372.369334 -92.606114)
		(end 372.369334 -91.625928)
		(width 0.089408)
		(layer "In11.Cu")
		(net "FM_CPU0_SKTOCC_LVT3_N")
	)
	(segment
		(start 377.671838 -97.605596)
		(end 375.658126 -95.591884)
		(width 0.089408)
		(layer "In11.Cu")
		(net "FM_CPU0_SKTOCC_LVT3_N")
	)
	(segment
		(start 371.91315 -88.25357)
		(end 371.91315 -85.021166)
		(width 0.089408)
		(layer "In11.Cu")
		(net "FM_CPU0_SKTOCC_LVT3_N")
	)
	(segment
		(start 367.945162 -81.053178)
		(end 367.945162 -80.694784)
		(width 0.089408)
		(layer "In11.Cu")
		(net "FM_CPU0_SKTOCC_LVT3_N")
	)
	(segment
		(start 371.91315 -85.021166)
		(end 367.945162 -81.053178)
		(width 0.089408)
		(layer "In11.Cu")
		(net "FM_CPU0_SKTOCC_LVT3_N")
	)
	(segment
		(start 375.658126 -94.845124)
		(end 374.195848 -93.382846)
		(width 0.089408)
		(layer "In11.Cu")
		(net "FM_CPU0_SKTOCC_LVT3_N")
	)
	(segment
		(start 400.880072 -108.354876)
		(end 401.812506 -108.354876)
		(width 0.10795)
		(layer "F.Cu")
		(net "FM_BIOS_POST_CMPLT_N")
	)
	(segment
		(start 396.15745 -102.98684)
		(end 396.15745 -103.615236)
		(width 0.10795)
		(layer "F.Cu")
		(net "FM_BIOS_POST_CMPLT_N")
	)
	(segment
		(start 417.490148 -40.93464)
		(end 417.868354 -41.312846)
		(width 0.10795)
		(layer "F.Cu")
		(net "FM_BIOS_POST_CMPLT_N")
	)
	(via
		(at 408.446224 -46.931834)
		(size 0.508)
		(drill 0.254)
		(layers "F.Cu" "B.Cu")
		(net "FM_BIOS_POST_CMPLT_N")
	)
	(via
		(at 401.812506 -108.354876)
		(size 0.508)
		(drill 0.254)
		(layers "F.Cu" "B.Cu")
		(net "FM_BIOS_POST_CMPLT_N")
	)
	(via
		(at 396.15745 -103.615236)
		(size 0.508)
		(drill 0.254)
		(layers "F.Cu" "B.Cu")
		(net "FM_BIOS_POST_CMPLT_N")
	)
	(via
		(at 417.868354 -41.312846)
		(size 0.4572)
		(drill 0.2032)
		(layers "F.Cu" "B.Cu")
		(net "FM_BIOS_POST_CMPLT_N")
	)
	(segment
		(start 401.47113 -108.0135)
		(end 401.812506 -108.354876)
		(width 0.10795)
		(layer "B.Cu")
		(net "FM_BIOS_POST_CMPLT_N")
	)
	(segment
		(start 401.193 -108.0135)
		(end 401.47113 -108.0135)
		(width 0.10795)
		(layer "B.Cu")
		(net "FM_BIOS_POST_CMPLT_N")
	)
	(segment
		(start 399.191988 -86.121748)
		(end 399.191988 -85.583268)
		(width 0.089408)
		(layer "In2.Cu")
		(net "FM_BIOS_POST_CMPLT_N")
	)
	(segment
		(start 400.281902 -95.71482)
		(end 399.275554 -94.708472)
		(width 0.089408)
		(layer "In2.Cu")
		(net "FM_BIOS_POST_CMPLT_N")
	)
	(segment
		(start 396.501874 -103.615236)
		(end 396.947644 -103.169466)
		(width 0.089408)
		(layer "In2.Cu")
		(net "FM_BIOS_POST_CMPLT_N")
	)
	(segment
		(start 399.542 -65.37452)
		(end 400.653504 -64.263016)
		(width 0.089408)
		(layer "In2.Cu")
		(net "FM_BIOS_POST_CMPLT_N")
	)
	(segment
		(start 399.191988 -85.583268)
		(end 399.382488 -85.392768)
		(width 0.089408)
		(layer "In2.Cu")
		(net "FM_BIOS_POST_CMPLT_N")
	)
	(segment
		(start 399.275554 -94.708472)
		(end 399.275554 -92.671646)
		(width 0.089408)
		(layer "In2.Cu")
		(net "FM_BIOS_POST_CMPLT_N")
	)
	(segment
		(start 398.165066 -76.000102)
		(end 398.165066 -73.530714)
		(width 0.089408)
		(layer "In2.Cu")
		(net "FM_BIOS_POST_CMPLT_N")
	)
	(segment
		(start 396.15745 -103.615236)
		(end 396.563596 -104.021382)
		(width 0.089408)
		(layer "In2.Cu")
		(net "FM_BIOS_POST_CMPLT_N")
	)
	(segment
		(start 396.15745 -103.615236)
		(end 396.501874 -103.615236)
		(width 0.089408)
		(layer "In2.Cu")
		(net "FM_BIOS_POST_CMPLT_N")
	)
	(segment
		(start 398.838928 -104.021382)
		(end 399.686272 -104.868726)
		(width 0.089408)
		(layer "In2.Cu")
		(net "FM_BIOS_POST_CMPLT_N")
	)
	(segment
		(start 399.52803 -102.42677)
		(end 399.52803 -99.932998)
		(width 0.089408)
		(layer "In2.Cu")
		(net "FM_BIOS_POST_CMPLT_N")
	)
	(segment
		(start 399.212308 -79.835248)
		(end 399.212308 -77.973936)
		(width 0.089408)
		(layer "In2.Cu")
		(net "FM_BIOS_POST_CMPLT_N")
	)
	(segment
		(start 398.798034 -65.37452)
		(end 399.542 -65.37452)
		(width 0.089408)
		(layer "In2.Cu")
		(net "FM_BIOS_POST_CMPLT_N")
	)
	(segment
		(start 399.686272 -104.868726)
		(end 399.686272 -106.228642)
		(width 0.089408)
		(layer "In2.Cu")
		(net "FM_BIOS_POST_CMPLT_N")
	)
	(segment
		(start 399.382488 -83.496912)
		(end 398.120108 -82.234532)
		(width 0.089408)
		(layer "In2.Cu")
		(net "FM_BIOS_POST_CMPLT_N")
	)
	(segment
		(start 398.867376 -76.702412)
		(end 398.165066 -76.000102)
		(width 0.089408)
		(layer "In2.Cu")
		(net "FM_BIOS_POST_CMPLT_N")
	)
	(segment
		(start 400.653504 -64.263016)
		(end 400.653504 -55.445406)
		(width 0.089408)
		(layer "In2.Cu")
		(net "FM_BIOS_POST_CMPLT_N")
	)
	(segment
		(start 400.281902 -99.179126)
		(end 400.281902 -95.71482)
		(width 0.089408)
		(layer "In2.Cu")
		(net "FM_BIOS_POST_CMPLT_N")
	)
	(segment
		(start 399.52803 -99.932998)
		(end 400.281902 -99.179126)
		(width 0.089408)
		(layer "In2.Cu")
		(net "FM_BIOS_POST_CMPLT_N")
	)
	(segment
		(start 395.387576 -70.753224)
		(end 395.387576 -66.429128)
		(width 0.089408)
		(layer "In2.Cu")
		(net "FM_BIOS_POST_CMPLT_N")
	)
	(segment
		(start 396.947644 -103.169466)
		(end 398.785334 -103.169466)
		(width 0.089408)
		(layer "In2.Cu")
		(net "FM_BIOS_POST_CMPLT_N")
	)
	(segment
		(start 399.275554 -92.671646)
		(end 399.548604 -92.398596)
		(width 0.089408)
		(layer "In2.Cu")
		(net "FM_BIOS_POST_CMPLT_N")
	)
	(segment
		(start 398.120108 -80.927448)
		(end 399.212308 -79.835248)
		(width 0.089408)
		(layer "In2.Cu")
		(net "FM_BIOS_POST_CMPLT_N")
	)
	(segment
		(start 399.548604 -86.478364)
		(end 399.191988 -86.121748)
		(width 0.089408)
		(layer "In2.Cu")
		(net "FM_BIOS_POST_CMPLT_N")
	)
	(segment
		(start 399.686272 -106.228642)
		(end 401.812506 -108.354876)
		(width 0.089408)
		(layer "In2.Cu")
		(net "FM_BIOS_POST_CMPLT_N")
	)
	(segment
		(start 398.120108 -82.234532)
		(end 398.120108 -80.927448)
		(width 0.089408)
		(layer "In2.Cu")
		(net "FM_BIOS_POST_CMPLT_N")
	)
	(segment
		(start 396.563596 -104.021382)
		(end 398.838928 -104.021382)
		(width 0.089408)
		(layer "In2.Cu")
		(net "FM_BIOS_POST_CMPLT_N")
	)
	(segment
		(start 395.387576 -66.429128)
		(end 396.9512 -64.865504)
		(width 0.089408)
		(layer "In2.Cu")
		(net "FM_BIOS_POST_CMPLT_N")
	)
	(segment
		(start 398.785334 -103.169466)
		(end 399.52803 -102.42677)
		(width 0.089408)
		(layer "In2.Cu")
		(net "FM_BIOS_POST_CMPLT_N")
	)
	(segment
		(start 399.212308 -77.973936)
		(end 398.867376 -77.629004)
		(width 0.089408)
		(layer "In2.Cu")
		(net "FM_BIOS_POST_CMPLT_N")
	)
	(segment
		(start 396.9512 -64.865504)
		(end 398.289018 -64.865504)
		(width 0.089408)
		(layer "In2.Cu")
		(net "FM_BIOS_POST_CMPLT_N")
	)
	(segment
		(start 408.446224 -47.652686)
		(end 408.446224 -46.931834)
		(width 0.089408)
		(layer "In2.Cu")
		(net "FM_BIOS_POST_CMPLT_N")
	)
	(segment
		(start 399.382488 -85.392768)
		(end 399.382488 -83.496912)
		(width 0.089408)
		(layer "In2.Cu")
		(net "FM_BIOS_POST_CMPLT_N")
	)
	(segment
		(start 400.653504 -55.445406)
		(end 408.446224 -47.652686)
		(width 0.089408)
		(layer "In2.Cu")
		(net "FM_BIOS_POST_CMPLT_N")
	)
	(segment
		(start 399.548604 -92.398596)
		(end 399.548604 -86.478364)
		(width 0.089408)
		(layer "In2.Cu")
		(net "FM_BIOS_POST_CMPLT_N")
	)
	(segment
		(start 398.289018 -64.865504)
		(end 398.798034 -65.37452)
		(width 0.089408)
		(layer "In2.Cu")
		(net "FM_BIOS_POST_CMPLT_N")
	)
	(segment
		(start 398.867376 -77.629004)
		(end 398.867376 -76.702412)
		(width 0.089408)
		(layer "In2.Cu")
		(net "FM_BIOS_POST_CMPLT_N")
	)
	(segment
		(start 398.165066 -73.530714)
		(end 395.387576 -70.753224)
		(width 0.089408)
		(layer "In2.Cu")
		(net "FM_BIOS_POST_CMPLT_N")
	)
	(segment
		(start 410.518864 -47.377096)
		(end 408.891486 -47.377096)
		(width 0.089408)
		(layer "In9.Cu")
		(net "FM_BIOS_POST_CMPLT_N")
	)
	(segment
		(start 412.532068 -45.74667)
		(end 410.933138 -45.74667)
		(width 0.089408)
		(layer "In9.Cu")
		(net "FM_BIOS_POST_CMPLT_N")
	)
	(segment
		(start 417.868354 -41.312846)
		(end 417.421568 -41.759632)
		(width 0.089408)
		(layer "In9.Cu")
		(net "FM_BIOS_POST_CMPLT_N")
	)
	(segment
		(start 415.915602 -41.978834)
		(end 415.915348 -41.979088)
		(width 0.089408)
		(layer "In9.Cu")
		(net "FM_BIOS_POST_CMPLT_N")
	)
	(segment
		(start 415.915602 -41.953688)
		(end 415.915602 -41.978834)
		(width 0.089408)
		(layer "In9.Cu")
		(net "FM_BIOS_POST_CMPLT_N")
	)
	(segment
		(start 410.933138 -45.74667)
		(end 410.69895 -45.980858)
		(width 0.089408)
		(layer "In9.Cu")
		(net "FM_BIOS_POST_CMPLT_N")
	)
	(segment
		(start 416.109404 -41.759886)
		(end 415.915602 -41.953688)
		(width 0.089408)
		(layer "In9.Cu")
		(net "FM_BIOS_POST_CMPLT_N")
	)
	(segment
		(start 415.915602 -42.568622)
		(end 412.737808 -45.746416)
		(width 0.089408)
		(layer "In9.Cu")
		(net "FM_BIOS_POST_CMPLT_N")
	)
	(segment
		(start 415.915348 -42.289984)
		(end 415.915602 -42.290238)
		(width 0.089408)
		(layer "In9.Cu")
		(net "FM_BIOS_POST_CMPLT_N")
	)
	(segment
		(start 416.13455 -41.759886)
		(end 416.109404 -41.759886)
		(width 0.089408)
		(layer "In9.Cu")
		(net "FM_BIOS_POST_CMPLT_N")
	)
	(segment
		(start 416.134804 -41.759632)
		(end 416.13455 -41.759886)
		(width 0.089408)
		(layer "In9.Cu")
		(net "FM_BIOS_POST_CMPLT_N")
	)
	(segment
		(start 415.915602 -42.290238)
		(end 415.915602 -42.568622)
		(width 0.089408)
		(layer "In9.Cu")
		(net "FM_BIOS_POST_CMPLT_N")
	)
	(segment
		(start 410.762196 -47.133764)
		(end 410.518864 -47.377096)
		(width 0.089408)
		(layer "In9.Cu")
		(net "FM_BIOS_POST_CMPLT_N")
	)
	(segment
		(start 410.762196 -46.812454)
		(end 410.762196 -47.133764)
		(width 0.089408)
		(layer "In9.Cu")
		(net "FM_BIOS_POST_CMPLT_N")
	)
	(segment
		(start 412.737808 -45.746416)
		(end 412.532322 -45.746416)
		(width 0.089408)
		(layer "In9.Cu")
		(net "FM_BIOS_POST_CMPLT_N")
	)
	(segment
		(start 415.915348 -41.979088)
		(end 415.915348 -42.289984)
		(width 0.089408)
		(layer "In9.Cu")
		(net "FM_BIOS_POST_CMPLT_N")
	)
	(segment
		(start 412.532322 -45.746416)
		(end 412.532068 -45.74667)
		(width 0.089408)
		(layer "In9.Cu")
		(net "FM_BIOS_POST_CMPLT_N")
	)
	(segment
		(start 417.421568 -41.759632)
		(end 416.134804 -41.759632)
		(width 0.089408)
		(layer "In9.Cu")
		(net "FM_BIOS_POST_CMPLT_N")
	)
	(segment
		(start 410.69895 -45.980858)
		(end 410.69895 -46.749208)
		(width 0.089408)
		(layer "In9.Cu")
		(net "FM_BIOS_POST_CMPLT_N")
	)
	(segment
		(start 408.891486 -47.377096)
		(end 408.446224 -46.931834)
		(width 0.089408)
		(layer "In9.Cu")
		(net "FM_BIOS_POST_CMPLT_N")
	)
	(segment
		(start 410.69895 -46.749208)
		(end 410.762196 -46.812454)
		(width 0.089408)
		(layer "In9.Cu")
		(net "FM_BIOS_POST_CMPLT_N")
	)
	(segment
		(start 428.114968 -45.872654)
		(end 428.22622 -45.983906)
		(width 0.10795)
		(layer "F.Cu")
		(net "SPI_BMC_BT_CS_R_N")
	)
	(segment
		(start 424.902122 -42.22115)
		(end 424.04411 -41.363138)
		(width 0.10795)
		(layer "F.Cu")
		(net "SPI_BMC_BT_CS_R_N")
	)
	(segment
		(start 424.902122 -44.031662)
		(end 424.902122 -42.22115)
		(width 0.10795)
		(layer "F.Cu")
		(net "SPI_BMC_BT_CS_R_N")
	)
	(segment
		(start 424.04411 -41.363138)
		(end 423.518584 -41.363138)
		(width 0.10795)
		(layer "F.Cu")
		(net "SPI_BMC_BT_CS_R_N")
	)
	(segment
		(start 427.56836 -45.872654)
		(end 428.114968 -45.872654)
		(width 0.10795)
		(layer "F.Cu")
		(net "SPI_BMC_BT_CS_R_N")
	)
	(segment
		(start 427.8757 -47.2567)
		(end 427.8757 -47.74438)
		(width 0.10795)
		(layer "F.Cu")
		(net "SPI_BMC_BT_CS_R_N")
	)
	(segment
		(start 425.915328 -44.266866)
		(end 425.137326 -44.266866)
		(width 0.10795)
		(layer "F.Cu")
		(net "SPI_BMC_BT_CS_R_N")
	)
	(segment
		(start 428.22622 -45.983906)
		(end 428.22622 -46.90618)
		(width 0.10795)
		(layer "F.Cu")
		(net "SPI_BMC_BT_CS_R_N")
	)
	(segment
		(start 426.917104 -45.54855)
		(end 426.917104 -45.268642)
		(width 0.10795)
		(layer "F.Cu")
		(net "SPI_BMC_BT_CS_R_N")
	)
	(segment
		(start 423.518584 -41.363138)
		(end 423.090086 -40.93464)
		(width 0.10795)
		(layer "F.Cu")
		(net "SPI_BMC_BT_CS_R_N")
	)
	(segment
		(start 427.241208 -45.872654)
		(end 426.917104 -45.54855)
		(width 0.10795)
		(layer "F.Cu")
		(net "SPI_BMC_BT_CS_R_N")
	)
	(segment
		(start 428.22622 -46.90618)
		(end 427.8757 -47.2567)
		(width 0.10795)
		(layer "F.Cu")
		(net "SPI_BMC_BT_CS_R_N")
	)
	(segment
		(start 425.137326 -44.266866)
		(end 424.902122 -44.031662)
		(width 0.10795)
		(layer "F.Cu")
		(net "SPI_BMC_BT_CS_R_N")
	)
	(segment
		(start 427.56836 -45.872654)
		(end 427.241208 -45.872654)
		(width 0.10795)
		(layer "F.Cu")
		(net "SPI_BMC_BT_CS_R_N")
	)
	(segment
		(start 426.917104 -45.268642)
		(end 425.915328 -44.266866)
		(width 0.10795)
		(layer "F.Cu")
		(net "SPI_BMC_BT_CS_R_N")
	)
	(via
		(at 427.8757 -47.74438)
		(size 0.762)
		(drill 0.381)
		(layers "F.Cu" "B.Cu")
		(net "SPI_BMC_BT_CS_R_N")
	)
	(segment
		(start 436.292244 -22.749256)
		(end 436.5371 -22.5044)
		(width 0.10795)
		(layer "F.Cu")
		(net "FAN_TACH3")
	)
	(segment
		(start 432.4731 -27.2288)
		(end 433.475384 -26.226516)
		(width 0.10795)
		(layer "F.Cu")
		(net "FAN_TACH3")
	)
	(segment
		(start 437.6293 -22.313646)
		(end 437.6293 -21.9964)
		(width 0.10795)
		(layer "F.Cu")
		(net "FAN_TACH3")
	)
	(segment
		(start 427.923706 -27.2288)
		(end 432.4731 -27.2288)
		(width 0.10795)
		(layer "F.Cu")
		(net "FAN_TACH3")
	)
	(segment
		(start 442.503814 -23.1902)
		(end 443.608714 -24.2951)
		(width 0.10795)
		(layer "F.Cu")
		(net "FAN_TACH3")
	)
	(segment
		(start 437.6293 -21.9964)
		(end 438.375298 -21.9964)
		(width 0.10795)
		(layer "F.Cu")
		(net "FAN_TACH3")
	)
	(segment
		(start 439.1152 -22.736302)
		(end 440.744102 -22.736302)
		(width 0.10795)
		(layer "F.Cu")
		(net "FAN_TACH3")
	)
	(segment
		(start 440.744102 -22.736302)
		(end 441.198 -23.1902)
		(width 0.10795)
		(layer "F.Cu")
		(net "FAN_TACH3")
	)
	(segment
		(start 433.475384 -24.296624)
		(end 435.022752 -22.749256)
		(width 0.10795)
		(layer "F.Cu")
		(net "FAN_TACH3")
	)
	(segment
		(start 437.438546 -22.5044)
		(end 437.6293 -22.313646)
		(width 0.10795)
		(layer "F.Cu")
		(net "FAN_TACH3")
	)
	(segment
		(start 435.022752 -22.749256)
		(end 436.292244 -22.749256)
		(width 0.10795)
		(layer "F.Cu")
		(net "FAN_TACH3")
	)
	(segment
		(start 441.198 -23.1902)
		(end 442.503814 -23.1902)
		(width 0.10795)
		(layer "F.Cu")
		(net "FAN_TACH3")
	)
	(segment
		(start 436.5371 -22.5044)
		(end 437.438546 -22.5044)
		(width 0.10795)
		(layer "F.Cu")
		(net "FAN_TACH3")
	)
	(segment
		(start 423.890186 -28.934664)
		(end 426.217842 -28.934664)
		(width 0.10795)
		(layer "F.Cu")
		(net "FAN_TACH3")
	)
	(segment
		(start 438.375298 -21.9964)
		(end 439.1152 -22.736302)
		(width 0.10795)
		(layer "F.Cu")
		(net "FAN_TACH3")
	)
	(segment
		(start 433.475384 -26.226516)
		(end 433.475384 -24.296624)
		(width 0.10795)
		(layer "F.Cu")
		(net "FAN_TACH3")
	)
	(segment
		(start 426.217842 -28.934664)
		(end 427.923706 -27.2288)
		(width 0.10795)
		(layer "F.Cu")
		(net "FAN_TACH3")
	)
	(via
		(at 476.4024 -39.7002)
		(size 0.508)
		(drill 0.254)
		(layers "F.Cu" "B.Cu")
		(net "FAN_TACH3")
	)
	(via
		(at 14.6558 -43.0022)
		(size 0.6604)
		(drill 0.3302)
		(layers "F.Cu" "B.Cu")
		(net "FAN_TACH3")
	)
	(via
		(at 355.4476 -32.1056)
		(size 0.508)
		(drill 0.254)
		(layers "F.Cu" "B.Cu")
		(net "FAN_TACH3")
	)
	(via
		(at 22.085808 -46.157134)
		(size 0.508)
		(drill 0.254)
		(layers "F.Cu" "B.Cu")
		(net "FAN_TACH3")
	)
	(via
		(at 443.608714 -24.2951)
		(size 0.508)
		(drill 0.254)
		(layers "F.Cu" "B.Cu")
		(net "FAN_TACH3")
	)
	(via
		(at 448.31381 -30.2514)
		(size 0.508)
		(drill 0.254)
		(layers "F.Cu" "B.Cu")
		(net "FAN_TACH3")
	)
	(via
		(at 334.56753 -22.122892)
		(size 0.508)
		(drill 0.254)
		(layers "F.Cu" "B.Cu")
		(net "FAN_TACH3")
	)
	(segment
		(start 11.0744 -43.0022)
		(end 14.6558 -43.0022)
		(width 0.10795)
		(layer "B.Cu")
		(net "FAN_TACH3")
	)
	(segment
		(start 22.085808 -44.818808)
		(end 20.2692 -43.0022)
		(width 0.10795)
		(layer "B.Cu")
		(net "FAN_TACH3")
	)
	(segment
		(start 22.085808 -46.157134)
		(end 22.085808 -44.818808)
		(width 0.10795)
		(layer "B.Cu")
		(net "FAN_TACH3")
	)
	(segment
		(start 9.7536 -41.6814)
		(end 11.0744 -43.0022)
		(width 0.10795)
		(layer "B.Cu")
		(net "FAN_TACH3")
	)
	(segment
		(start 20.2692 -43.0022)
		(end 14.6558 -43.0022)
		(width 0.10795)
		(layer "B.Cu")
		(net "FAN_TACH3")
	)
	(segment
		(start 443.608714 -24.2951)
		(end 444.575946 -24.2951)
		(width 0.089408)
		(layer "In2.Cu")
		(net "FAN_TACH3")
	)
	(segment
		(start 338.12226 -34.5186)
		(end 348.5896 -34.5186)
		(width 0.089408)
		(layer "In2.Cu")
		(net "FAN_TACH3")
	)
	(segment
		(start 333.93126 -24.09952)
		(end 331.443584 -26.587196)
		(width 0.089408)
		(layer "In2.Cu")
		(net "FAN_TACH3")
	)
	(segment
		(start 448.2084 -30.14599)
		(end 448.31381 -30.2514)
		(width 0.089408)
		(layer "In2.Cu")
		(net "FAN_TACH3")
	)
	(segment
		(start 354.736146 -33.8328)
		(end 355.4476 -33.121346)
		(width 0.089408)
		(layer "In2.Cu")
		(net "FAN_TACH3")
	)
	(segment
		(start 331.6224 -32.45612)
		(end 331.6224 -32.4739)
		(width 0.089408)
		(layer "In2.Cu")
		(net "FAN_TACH3")
	)
	(segment
		(start 331.443584 -32.277304)
		(end 331.6224 -32.45612)
		(width 0.089408)
		(layer "In2.Cu")
		(net "FAN_TACH3")
	)
	(segment
		(start 336.342736 -34.546032)
		(end 336.49793 -34.390838)
		(width 0.089408)
		(layer "In2.Cu")
		(net "FAN_TACH3")
	)
	(segment
		(start 336.49793 -34.390838)
		(end 337.994498 -34.390838)
		(width 0.089408)
		(layer "In2.Cu")
		(net "FAN_TACH3")
	)
	(segment
		(start 355.4476 -33.121346)
		(end 355.4476 -32.1056)
		(width 0.089408)
		(layer "In2.Cu")
		(net "FAN_TACH3")
	)
	(segment
		(start 333.694532 -34.546032)
		(end 336.342736 -34.546032)
		(width 0.089408)
		(layer "In2.Cu")
		(net "FAN_TACH3")
	)
	(segment
		(start 448.2084 -27.927554)
		(end 448.2084 -30.14599)
		(width 0.089408)
		(layer "In2.Cu")
		(net "FAN_TACH3")
	)
	(segment
		(start 334.56753 -22.122892)
		(end 333.93126 -22.759162)
		(width 0.089408)
		(layer "In2.Cu")
		(net "FAN_TACH3")
	)
	(segment
		(start 331.443584 -26.587196)
		(end 331.443584 -32.277304)
		(width 0.089408)
		(layer "In2.Cu")
		(net "FAN_TACH3")
	)
	(segment
		(start 331.6224 -32.4739)
		(end 333.694532 -34.546032)
		(width 0.089408)
		(layer "In2.Cu")
		(net "FAN_TACH3")
	)
	(segment
		(start 337.994498 -34.390838)
		(end 338.12226 -34.5186)
		(width 0.089408)
		(layer "In2.Cu")
		(net "FAN_TACH3")
	)
	(segment
		(start 333.93126 -22.759162)
		(end 333.93126 -24.09952)
		(width 0.089408)
		(layer "In2.Cu")
		(net "FAN_TACH3")
	)
	(segment
		(start 349.2754 -33.8328)
		(end 354.736146 -33.8328)
		(width 0.089408)
		(layer "In2.Cu")
		(net "FAN_TACH3")
	)
	(segment
		(start 444.575946 -24.2951)
		(end 448.2084 -27.927554)
		(width 0.089408)
		(layer "In2.Cu")
		(net "FAN_TACH3")
	)
	(segment
		(start 348.5896 -34.5186)
		(end 349.2754 -33.8328)
		(width 0.089408)
		(layer "In2.Cu")
		(net "FAN_TACH3")
	)
	(segment
		(start 29.183584 -28.997656)
		(end 26.336498 -31.844742)
		(width 0.089408)
		(layer "In4.Cu")
		(net "FAN_TACH3")
	)
	(segment
		(start 28.168854 2.890774)
		(end 28.168854 -0.213106)
		(width 0.089408)
		(layer "In4.Cu")
		(net "FAN_TACH3")
	)
	(segment
		(start 329.788774 -21.630386)
		(end 328.129392 -19.971004)
		(width 0.089408)
		(layer "In4.Cu")
		(net "FAN_TACH3")
	)
	(segment
		(start 27.724608 -0.657352)
		(end 27.724608 -15.803626)
		(width 0.089408)
		(layer "In4.Cu")
		(net "FAN_TACH3")
	)
	(segment
		(start 117.232176 3.908552)
		(end 116.563902 3.240278)
		(width 0.089408)
		(layer "In4.Cu")
		(net "FAN_TACH3")
	)
	(segment
		(start 102.257352 3.796792)
		(end 29.074872 3.796792)
		(width 0.089408)
		(layer "In4.Cu")
		(net "FAN_TACH3")
	)
	(segment
		(start 461.057244 -34.62528)
		(end 461.057498 -34.625026)
		(width 0.089408)
		(layer "In4.Cu")
		(net "FAN_TACH3")
	)
	(segment
		(start 460.918814 -34.62528)
		(end 461.057244 -34.62528)
		(width 0.089408)
		(layer "In4.Cu")
		(net "FAN_TACH3")
	)
	(segment
		(start 321.93611 3.79349)
		(end 187.225432 3.79349)
		(width 0.089408)
		(layer "In4.Cu")
		(net "FAN_TACH3")
	)
	(segment
		(start 176.770538 -3.990848)
		(end 176.182274 -4.579112)
		(width 0.089408)
		(layer "In4.Cu")
		(net "FAN_TACH3")
	)
	(segment
		(start 462.778602 -34.62528)
		(end 463.231992 -35.07867)
		(width 0.089408)
		(layer "In4.Cu")
		(net "FAN_TACH3")
	)
	(segment
		(start 334.56753 -22.122892)
		(end 332.460092 -22.122892)
		(width 0.089408)
		(layer "In4.Cu")
		(net "FAN_TACH3")
	)
	(segment
		(start 328.129392 -19.971004)
		(end 325.9201 -19.971004)
		(width 0.089408)
		(layer "In4.Cu")
		(net "FAN_TACH3")
	)
	(segment
		(start 325.9201 -19.971004)
		(end 324.674738 -18.725642)
		(width 0.089408)
		(layer "In4.Cu")
		(net "FAN_TACH3")
	)
	(segment
		(start 461.658462 -34.624518)
		(end 461.659224 -34.62528)
		(width 0.089408)
		(layer "In4.Cu")
		(net "FAN_TACH3")
	)
	(segment
		(start 182.520082 -3.990848)
		(end 176.770538 -3.990848)
		(width 0.089408)
		(layer "In4.Cu")
		(net "FAN_TACH3")
	)
	(segment
		(start 323.8754 1.8542)
		(end 321.93611 3.79349)
		(width 0.089408)
		(layer "In4.Cu")
		(net "FAN_TACH3")
	)
	(segment
		(start 172.467016 -5.22986)
		(end 171.055284 -3.818128)
		(width 0.089408)
		(layer "In4.Cu")
		(net "FAN_TACH3")
	)
	(segment
		(start 183.923686 -1.092454)
		(end 183.923686 -1.97485)
		(width 0.089408)
		(layer "In4.Cu")
		(net "FAN_TACH3")
	)
	(segment
		(start 28.168854 -0.213106)
		(end 27.724608 -0.657352)
		(width 0.089408)
		(layer "In4.Cu")
		(net "FAN_TACH3")
	)
	(segment
		(start 461.659224 -34.62528)
		(end 462.778602 -34.62528)
		(width 0.089408)
		(layer "In4.Cu")
		(net "FAN_TACH3")
	)
	(segment
		(start 187.225432 3.79349)
		(end 184.379616 0.947674)
		(width 0.089408)
		(layer "In4.Cu")
		(net "FAN_TACH3")
	)
	(segment
		(start 448.32651 -30.2641)
		(end 449.429632 -30.2641)
		(width 0.089408)
		(layer "In4.Cu")
		(net "FAN_TACH3")
	)
	(segment
		(start 29.183584 -22.015958)
		(end 29.183584 -28.997656)
		(width 0.089408)
		(layer "In4.Cu")
		(net "FAN_TACH3")
	)
	(segment
		(start 332.460092 -22.122892)
		(end 331.967586 -21.630386)
		(width 0.089408)
		(layer "In4.Cu")
		(net "FAN_TACH3")
	)
	(segment
		(start 324.674738 -0.400304)
		(end 323.8754 0.399034)
		(width 0.089408)
		(layer "In4.Cu")
		(net "FAN_TACH3")
	)
	(segment
		(start 24.804878 -31.844742)
		(end 21.05787 -35.59175)
		(width 0.089408)
		(layer "In4.Cu")
		(net "FAN_TACH3")
	)
	(segment
		(start 471.502994 -38.929818)
		(end 472.383612 -38.929818)
		(width 0.089408)
		(layer "In4.Cu")
		(net "FAN_TACH3")
	)
	(segment
		(start 452.452486 -33.286954)
		(end 457.365862 -33.286954)
		(width 0.089408)
		(layer "In4.Cu")
		(net "FAN_TACH3")
	)
	(segment
		(start 23.745952 -39.776146)
		(end 23.745952 -44.49699)
		(width 0.089408)
		(layer "In4.Cu")
		(net "FAN_TACH3")
	)
	(segment
		(start 164.882068 0.31877)
		(end 164.882068 3.095498)
		(width 0.089408)
		(layer "In4.Cu")
		(net "FAN_TACH3")
	)
	(segment
		(start 468.92718 -38.180518)
		(end 470.753694 -38.180518)
		(width 0.089408)
		(layer "In4.Cu")
		(net "FAN_TACH3")
	)
	(segment
		(start 21.05787 -38.964362)
		(end 21.579078 -39.48557)
		(width 0.089408)
		(layer "In4.Cu")
		(net "FAN_TACH3")
	)
	(segment
		(start 21.05787 -35.59175)
		(end 21.05787 -38.964362)
		(width 0.089408)
		(layer "In4.Cu")
		(net "FAN_TACH3")
	)
	(segment
		(start 174.09287 -4.579112)
		(end 173.442122 -5.22986)
		(width 0.089408)
		(layer "In4.Cu")
		(net "FAN_TACH3")
	)
	(segment
		(start 472.383612 -38.929818)
		(end 473.142818 -39.689024)
		(width 0.089408)
		(layer "In4.Cu")
		(net "FAN_TACH3")
	)
	(segment
		(start 167.948102 -3.818128)
		(end 166.657528 -2.527554)
		(width 0.089408)
		(layer "In4.Cu")
		(net "FAN_TACH3")
	)
	(segment
		(start 448.31381 -30.2514)
		(end 448.32651 -30.2641)
		(width 0.089408)
		(layer "In4.Cu")
		(net "FAN_TACH3")
	)
	(segment
		(start 457.585826 -33.506918)
		(end 459.800452 -33.506918)
		(width 0.089408)
		(layer "In4.Cu")
		(net "FAN_TACH3")
	)
	(segment
		(start 164.882068 3.095498)
		(end 164.069014 3.908552)
		(width 0.089408)
		(layer "In4.Cu")
		(net "FAN_TACH3")
	)
	(segment
		(start 183.2991 -3.626866)
		(end 182.893462 -4.032504)
		(width 0.089408)
		(layer "In4.Cu")
		(net "FAN_TACH3")
	)
	(segment
		(start 182.561738 -4.032504)
		(end 182.520082 -3.990848)
		(width 0.089408)
		(layer "In4.Cu")
		(net "FAN_TACH3")
	)
	(segment
		(start 461.25765 -34.625026)
		(end 461.257904 -34.624772)
		(width 0.089408)
		(layer "In4.Cu")
		(net "FAN_TACH3")
	)
	(segment
		(start 21.579078 -39.48557)
		(end 23.455376 -39.48557)
		(width 0.089408)
		(layer "In4.Cu")
		(net "FAN_TACH3")
	)
	(segment
		(start 461.415892 -34.624772)
		(end 461.416146 -34.624518)
		(width 0.089408)
		(layer "In4.Cu")
		(net "FAN_TACH3")
	)
	(segment
		(start 465.459572 -35.07867)
		(end 467.084664 -36.703762)
		(width 0.089408)
		(layer "In4.Cu")
		(net "FAN_TACH3")
	)
	(segment
		(start 476.391224 -39.689024)
		(end 476.4024 -39.7002)
		(width 0.089408)
		(layer "In4.Cu")
		(net "FAN_TACH3")
	)
	(segment
		(start 467.450424 -36.703762)
		(end 468.92718 -38.180518)
		(width 0.089408)
		(layer "In4.Cu")
		(net "FAN_TACH3")
	)
	(segment
		(start 27.724608 -15.803626)
		(end 27.170888 -16.357346)
		(width 0.089408)
		(layer "In4.Cu")
		(net "FAN_TACH3")
	)
	(segment
		(start 461.257904 -34.624772)
		(end 461.415892 -34.624772)
		(width 0.089408)
		(layer "In4.Cu")
		(net "FAN_TACH3")
	)
	(segment
		(start 457.365862 -33.286954)
		(end 457.585826 -33.506918)
		(width 0.089408)
		(layer "In4.Cu")
		(net "FAN_TACH3")
	)
	(segment
		(start 473.142818 -39.689024)
		(end 476.391224 -39.689024)
		(width 0.089408)
		(layer "In4.Cu")
		(net "FAN_TACH3")
	)
	(segment
		(start 164.069014 3.908552)
		(end 117.232176 3.908552)
		(width 0.089408)
		(layer "In4.Cu")
		(net "FAN_TACH3")
	)
	(segment
		(start 183.923686 -1.97485)
		(end 183.2991 -2.599436)
		(width 0.089408)
		(layer "In4.Cu")
		(net "FAN_TACH3")
	)
	(segment
		(start 166.657528 -2.527554)
		(end 166.657528 -1.45669)
		(width 0.089408)
		(layer "In4.Cu")
		(net "FAN_TACH3")
	)
	(segment
		(start 171.055284 -3.818128)
		(end 167.948102 -3.818128)
		(width 0.089408)
		(layer "In4.Cu")
		(net "FAN_TACH3")
	)
	(segment
		(start 27.170888 -20.003262)
		(end 29.183584 -22.015958)
		(width 0.089408)
		(layer "In4.Cu")
		(net "FAN_TACH3")
	)
	(segment
		(start 467.084664 -36.703762)
		(end 467.450424 -36.703762)
		(width 0.089408)
		(layer "In4.Cu")
		(net "FAN_TACH3")
	)
	(segment
		(start 176.182274 -4.579112)
		(end 174.09287 -4.579112)
		(width 0.089408)
		(layer "In4.Cu")
		(net "FAN_TACH3")
	)
	(segment
		(start 29.074872 3.796792)
		(end 28.168854 2.890774)
		(width 0.089408)
		(layer "In4.Cu")
		(net "FAN_TACH3")
	)
	(segment
		(start 463.231992 -35.07867)
		(end 465.459572 -35.07867)
		(width 0.089408)
		(layer "In4.Cu")
		(net "FAN_TACH3")
	)
	(segment
		(start 182.893462 -4.032504)
		(end 182.561738 -4.032504)
		(width 0.089408)
		(layer "In4.Cu")
		(net "FAN_TACH3")
	)
	(segment
		(start 323.8754 0.399034)
		(end 323.8754 1.8542)
		(width 0.089408)
		(layer "In4.Cu")
		(net "FAN_TACH3")
	)
	(segment
		(start 449.429632 -30.2641)
		(end 452.452486 -33.286954)
		(width 0.089408)
		(layer "In4.Cu")
		(net "FAN_TACH3")
	)
	(segment
		(start 331.967586 -21.630386)
		(end 329.788774 -21.630386)
		(width 0.089408)
		(layer "In4.Cu")
		(net "FAN_TACH3")
	)
	(segment
		(start 324.674738 -18.725642)
		(end 324.674738 -0.400304)
		(width 0.089408)
		(layer "In4.Cu")
		(net "FAN_TACH3")
	)
	(segment
		(start 116.563902 3.240278)
		(end 102.813866 3.240278)
		(width 0.089408)
		(layer "In4.Cu")
		(net "FAN_TACH3")
	)
	(segment
		(start 461.416146 -34.624518)
		(end 461.658462 -34.624518)
		(width 0.089408)
		(layer "In4.Cu")
		(net "FAN_TACH3")
	)
	(segment
		(start 184.379616 0.947674)
		(end 184.379616 -0.636524)
		(width 0.089408)
		(layer "In4.Cu")
		(net "FAN_TACH3")
	)
	(segment
		(start 461.057498 -34.625026)
		(end 461.25765 -34.625026)
		(width 0.089408)
		(layer "In4.Cu")
		(net "FAN_TACH3")
	)
	(segment
		(start 26.336498 -31.844742)
		(end 24.804878 -31.844742)
		(width 0.089408)
		(layer "In4.Cu")
		(net "FAN_TACH3")
	)
	(segment
		(start 184.379616 -0.636524)
		(end 183.923686 -1.092454)
		(width 0.089408)
		(layer "In4.Cu")
		(net "FAN_TACH3")
	)
	(segment
		(start 102.813866 3.240278)
		(end 102.257352 3.796792)
		(width 0.089408)
		(layer "In4.Cu")
		(net "FAN_TACH3")
	)
	(segment
		(start 470.753694 -38.180518)
		(end 471.502994 -38.929818)
		(width 0.089408)
		(layer "In4.Cu")
		(net "FAN_TACH3")
	)
	(segment
		(start 173.442122 -5.22986)
		(end 172.467016 -5.22986)
		(width 0.089408)
		(layer "In4.Cu")
		(net "FAN_TACH3")
	)
	(segment
		(start 23.745952 -44.49699)
		(end 22.085808 -46.157134)
		(width 0.089408)
		(layer "In4.Cu")
		(net "FAN_TACH3")
	)
	(segment
		(start 459.800452 -33.506918)
		(end 460.918814 -34.62528)
		(width 0.089408)
		(layer "In4.Cu")
		(net "FAN_TACH3")
	)
	(segment
		(start 183.2991 -2.599436)
		(end 183.2991 -3.626866)
		(width 0.089408)
		(layer "In4.Cu")
		(net "FAN_TACH3")
	)
	(segment
		(start 166.657528 -1.45669)
		(end 164.882068 0.31877)
		(width 0.089408)
		(layer "In4.Cu")
		(net "FAN_TACH3")
	)
	(segment
		(start 27.170888 -16.357346)
		(end 27.170888 -20.003262)
		(width 0.089408)
		(layer "In4.Cu")
		(net "FAN_TACH3")
	)
	(segment
		(start 23.455376 -39.48557)
		(end 23.745952 -39.776146)
		(width 0.089408)
		(layer "In4.Cu")
		(net "FAN_TACH3")
	)
	(segment
		(start 440.055254 -3.8608)
		(end 424.7642 -3.8608)
		(width 0.089408)
		(layer "In11.Cu")
		(net "FAN_TACH3")
	)
	(segment
		(start 469.5952 -2.5146)
		(end 469.3412 -2.5146)
		(width 0.089408)
		(layer "In11.Cu")
		(net "FAN_TACH3")
	)
	(segment
		(start 474.28531 -8.12927)
		(end 474.28531 -6.143244)
		(width 0.089408)
		(layer "In11.Cu")
		(net "FAN_TACH3")
	)
	(segment
		(start 476.014796 -33.292796)
		(end 476.014796 -28.848304)
		(width 0.089408)
		(layer "In11.Cu")
		(net "FAN_TACH3")
	)
	(segment
		(start 475.050866 -18.55089)
		(end 474.396816 -17.89684)
		(width 0.089408)
		(layer "In11.Cu")
		(net "FAN_TACH3")
	)
	(segment
		(start 476.78467 -37.598858)
		(end 476.78467 -34.06267)
		(width 0.089408)
		(layer "In11.Cu")
		(net "FAN_TACH3")
	)
	(segment
		(start 461.134206 -0.74676)
		(end 460.899764 -0.981202)
		(width 0.089408)
		(layer "In11.Cu")
		(net "FAN_TACH3")
	)
	(segment
		(start 477.156272 -39.2684)
		(end 477.436688 -38.987984)
		(width 0.089408)
		(layer "In11.Cu")
		(net "FAN_TACH3")
	)
	(segment
		(start 476.529654 -39.2684)
		(end 477.156272 -39.2684)
		(width 0.089408)
		(layer "In11.Cu")
		(net "FAN_TACH3")
	)
	(segment
		(start 474.542612 -5.290058)
		(end 474.048074 -4.79552)
		(width 0.089408)
		(layer "In11.Cu")
		(net "FAN_TACH3")
	)
	(segment
		(start 474.478604 -27.312112)
		(end 474.478604 -25.80132)
		(width 0.089408)
		(layer "In11.Cu")
		(net "FAN_TACH3")
	)
	(segment
		(start 474.396816 -12.50188)
		(end 475.6277 -11.270996)
		(width 0.089408)
		(layer "In11.Cu")
		(net "FAN_TACH3")
	)
	(segment
		(start 477.436688 -38.987984)
		(end 477.436688 -38.250876)
		(width 0.089408)
		(layer "In11.Cu")
		(net "FAN_TACH3")
	)
	(segment
		(start 475.6277 -11.270996)
		(end 475.6277 -9.47166)
		(width 0.089408)
		(layer "In11.Cu")
		(net "FAN_TACH3")
	)
	(segment
		(start 361.0356 -17.342358)
		(end 361.0356 -25.341834)
		(width 0.089408)
		(layer "In11.Cu")
		(net "FAN_TACH3")
	)
	(segment
		(start 476.4024 -39.7002)
		(end 476.4024 -39.395654)
		(width 0.089408)
		(layer "In11.Cu")
		(net "FAN_TACH3")
	)
	(segment
		(start 474.396816 -17.89684)
		(end 474.396816 -12.50188)
		(width 0.089408)
		(layer "In11.Cu")
		(net "FAN_TACH3")
	)
	(segment
		(start 461.134206 1.606804)
		(end 461.134206 -0.74676)
		(width 0.089408)
		(layer "In11.Cu")
		(net "FAN_TACH3")
	)
	(segment
		(start 384.12166 -4.318)
		(end 382.850644 -5.589016)
		(width 0.089408)
		(layer "In11.Cu")
		(net "FAN_TACH3")
	)
	(segment
		(start 361.0356 -25.341834)
		(end 356.266496 -30.110938)
		(width 0.089408)
		(layer "In11.Cu")
		(net "FAN_TACH3")
	)
	(segment
		(start 465.32292 -0.238252)
		(end 464.666076 0.418592)
		(width 0.089408)
		(layer "In11.Cu")
		(net "FAN_TACH3")
	)
	(segment
		(start 440.637676 -3.278378)
		(end 440.055254 -3.8608)
		(width 0.089408)
		(layer "In11.Cu")
		(net "FAN_TACH3")
	)
	(segment
		(start 474.048074 -4.79552)
		(end 473.909136 -4.79552)
		(width 0.089408)
		(layer "In11.Cu")
		(net "FAN_TACH3")
	)
	(segment
		(start 356.30358 -30.508194)
		(end 356.30358 -31.737554)
		(width 0.089408)
		(layer "In11.Cu")
		(net "FAN_TACH3")
	)
	(segment
		(start 449.798694 -0.550672)
		(end 447.070988 -3.278378)
		(width 0.089408)
		(layer "In11.Cu")
		(net "FAN_TACH3")
	)
	(segment
		(start 471.854276 -2.74066)
		(end 470.172288 -2.74066)
		(width 0.089408)
		(layer "In11.Cu")
		(net "FAN_TACH3")
	)
	(segment
		(start 459.858872 -0.550672)
		(end 449.798694 -0.550672)
		(width 0.089408)
		(layer "In11.Cu")
		(net "FAN_TACH3")
	)
	(segment
		(start 369.100354 -9.277604)
		(end 361.0356 -17.342358)
		(width 0.089408)
		(layer "In11.Cu")
		(net "FAN_TACH3")
	)
	(segment
		(start 424.307 -4.318)
		(end 384.12166 -4.318)
		(width 0.089408)
		(layer "In11.Cu")
		(net "FAN_TACH3")
	)
	(segment
		(start 475.050866 -25.229058)
		(end 475.050866 -18.55089)
		(width 0.089408)
		(layer "In11.Cu")
		(net "FAN_TACH3")
	)
	(segment
		(start 424.7642 -3.8608)
		(end 424.307 -4.318)
		(width 0.089408)
		(layer "In11.Cu")
		(net "FAN_TACH3")
	)
	(segment
		(start 476.4024 -39.395654)
		(end 476.529654 -39.2684)
		(width 0.089408)
		(layer "In11.Cu")
		(net "FAN_TACH3")
	)
	(segment
		(start 463.367882 2.229104)
		(end 461.756506 2.229104)
		(width 0.089408)
		(layer "In11.Cu")
		(net "FAN_TACH3")
	)
	(segment
		(start 469.3412 -2.5146)
		(end 468.5284 -1.7018)
		(width 0.089408)
		(layer "In11.Cu")
		(net "FAN_TACH3")
	)
	(segment
		(start 476.78467 -34.06267)
		(end 476.014796 -33.292796)
		(width 0.089408)
		(layer "In11.Cu")
		(net "FAN_TACH3")
	)
	(segment
		(start 465.32292 -1.13792)
		(end 465.32292 -0.238252)
		(width 0.089408)
		(layer "In11.Cu")
		(net "FAN_TACH3")
	)
	(segment
		(start 356.30358 -31.737554)
		(end 355.935534 -32.1056)
		(width 0.089408)
		(layer "In11.Cu")
		(net "FAN_TACH3")
	)
	(segment
		(start 460.899764 -0.981202)
		(end 460.289402 -0.981202)
		(width 0.089408)
		(layer "In11.Cu")
		(net "FAN_TACH3")
	)
	(segment
		(start 476.014796 -28.848304)
		(end 474.478604 -27.312112)
		(width 0.089408)
		(layer "In11.Cu")
		(net "FAN_TACH3")
	)
	(segment
		(start 475.6277 -9.47166)
		(end 474.28531 -8.12927)
		(width 0.089408)
		(layer "In11.Cu")
		(net "FAN_TACH3")
	)
	(segment
		(start 356.266496 -30.110938)
		(end 356.266496 -30.47111)
		(width 0.089408)
		(layer "In11.Cu")
		(net "FAN_TACH3")
	)
	(segment
		(start 468.5284 -1.7018)
		(end 465.8868 -1.7018)
		(width 0.089408)
		(layer "In11.Cu")
		(net "FAN_TACH3")
	)
	(segment
		(start 382.850644 -5.589016)
		(end 371.68328 -5.589016)
		(width 0.089408)
		(layer "In11.Cu")
		(net "FAN_TACH3")
	)
	(segment
		(start 474.542612 -5.885942)
		(end 474.542612 -5.290058)
		(width 0.089408)
		(layer "In11.Cu")
		(net "FAN_TACH3")
	)
	(segment
		(start 356.266496 -30.47111)
		(end 356.30358 -30.508194)
		(width 0.089408)
		(layer "In11.Cu")
		(net "FAN_TACH3")
	)
	(segment
		(start 460.289402 -0.981202)
		(end 459.858872 -0.550672)
		(width 0.089408)
		(layer "In11.Cu")
		(net "FAN_TACH3")
	)
	(segment
		(start 371.68328 -5.589016)
		(end 369.100354 -8.171942)
		(width 0.089408)
		(layer "In11.Cu")
		(net "FAN_TACH3")
	)
	(segment
		(start 469.598756 -2.511044)
		(end 469.5952 -2.5146)
		(width 0.089408)
		(layer "In11.Cu")
		(net "FAN_TACH3")
	)
	(segment
		(start 447.070988 -3.278378)
		(end 440.637676 -3.278378)
		(width 0.089408)
		(layer "In11.Cu")
		(net "FAN_TACH3")
	)
	(segment
		(start 464.666076 0.418592)
		(end 464.666076 0.93091)
		(width 0.089408)
		(layer "In11.Cu")
		(net "FAN_TACH3")
	)
	(segment
		(start 369.100354 -8.171942)
		(end 369.100354 -9.277604)
		(width 0.089408)
		(layer "In11.Cu")
		(net "FAN_TACH3")
	)
	(segment
		(start 473.909136 -4.79552)
		(end 471.854276 -2.74066)
		(width 0.089408)
		(layer "In11.Cu")
		(net "FAN_TACH3")
	)
	(segment
		(start 474.478604 -25.80132)
		(end 475.050866 -25.229058)
		(width 0.089408)
		(layer "In11.Cu")
		(net "FAN_TACH3")
	)
	(segment
		(start 474.28531 -6.143244)
		(end 474.542612 -5.885942)
		(width 0.089408)
		(layer "In11.Cu")
		(net "FAN_TACH3")
	)
	(segment
		(start 477.436688 -38.250876)
		(end 476.78467 -37.598858)
		(width 0.089408)
		(layer "In11.Cu")
		(net "FAN_TACH3")
	)
	(segment
		(start 469.942672 -2.511044)
		(end 469.598756 -2.511044)
		(width 0.089408)
		(layer "In11.Cu")
		(net "FAN_TACH3")
	)
	(segment
		(start 461.756506 2.229104)
		(end 461.134206 1.606804)
		(width 0.089408)
		(layer "In11.Cu")
		(net "FAN_TACH3")
	)
	(segment
		(start 465.8868 -1.7018)
		(end 465.32292 -1.13792)
		(width 0.089408)
		(layer "In11.Cu")
		(net "FAN_TACH3")
	)
	(segment
		(start 470.172288 -2.74066)
		(end 469.942672 -2.511044)
		(width 0.089408)
		(layer "In11.Cu")
		(net "FAN_TACH3")
	)
	(segment
		(start 355.935534 -32.1056)
		(end 355.4476 -32.1056)
		(width 0.089408)
		(layer "In11.Cu")
		(net "FAN_TACH3")
	)
	(segment
		(start 464.666076 0.93091)
		(end 463.367882 2.229104)
		(width 0.089408)
		(layer "In11.Cu")
		(net "FAN_TACH3")
	)
	(segment
		(start 17.585182 -120.960134)
		(end 17.693132 -120.852184)
		(width 0.10795)
		(layer "F.Cu")
		(net "FAN_TACH2")
	)
	(segment
		(start 18.431256 -118.145052)
		(end 18.525998 -118.239794)
		(width 0.10795)
		(layer "F.Cu")
		(net "FAN_TACH2")
	)
	(segment
		(start 18.847308 -119.900446)
		(end 18.847308 -119.354854)
		(width 0.10795)
		(layer "F.Cu")
		(net "FAN_TACH2")
	)
	(segment
		(start 18.863564 -119.338598)
		(end 18.863564 -118.32463)
		(width 0.10795)
		(layer "F.Cu")
		(net "FAN_TACH2")
	)
	(segment
		(start 460.531972 -31.500572)
		(end 460.531972 -32.505904)
		(width 0.10795)
		(layer "F.Cu")
		(net "FAN_TACH2")
	)
	(segment
		(start 460.2226 -30.734)
		(end 460.2226 -31.1912)
		(width 0.10795)
		(layer "F.Cu")
		(net "FAN_TACH2")
	)
	(segment
		(start 460.2226 -31.1912)
		(end 460.531972 -31.500572)
		(width 0.10795)
		(layer "F.Cu")
		(net "FAN_TACH2")
	)
	(segment
		(start 17.585182 -121.795032)
		(end 17.585182 -120.960134)
		(width 0.10795)
		(layer "F.Cu")
		(net "FAN_TACH2")
	)
	(segment
		(start 18.863564 -120.744234)
		(end 18.863564 -119.916702)
		(width 0.10795)
		(layer "F.Cu")
		(net "FAN_TACH2")
	)
	(segment
		(start 420.69004 -29.734764)
		(end 421.09009 -29.334714)
		(width 0.10795)
		(layer "F.Cu")
		(net "FAN_TACH2")
	)
	(segment
		(start 18.847308 -119.354854)
		(end 18.863564 -119.338598)
		(width 0.10795)
		(layer "F.Cu")
		(net "FAN_TACH2")
	)
	(segment
		(start 18.755614 -120.852184)
		(end 18.863564 -120.744234)
		(width 0.10795)
		(layer "F.Cu")
		(net "FAN_TACH2")
	)
	(segment
		(start 17.693132 -120.852184)
		(end 18.755614 -120.852184)
		(width 0.10795)
		(layer "F.Cu")
		(net "FAN_TACH2")
	)
	(segment
		(start 15.171674 -121.936764)
		(end 15.563596 -122.328686)
		(width 0.10795)
		(layer "F.Cu")
		(net "FAN_TACH2")
	)
	(segment
		(start 18.9484 -118.239794)
		(end 18.960592 -118.227602)
		(width 0.10795)
		(layer "F.Cu")
		(net "FAN_TACH2")
	)
	(segment
		(start 18.525998 -118.239794)
		(end 18.9484 -118.239794)
		(width 0.10795)
		(layer "F.Cu")
		(net "FAN_TACH2")
	)
	(segment
		(start 17.91335 -118.145052)
		(end 18.431256 -118.145052)
		(width 0.10795)
		(layer "F.Cu")
		(net "FAN_TACH2")
	)
	(segment
		(start 17.051528 -122.328686)
		(end 17.585182 -121.795032)
		(width 0.10795)
		(layer "F.Cu")
		(net "FAN_TACH2")
	)
	(segment
		(start 15.563596 -122.328686)
		(end 17.051528 -122.328686)
		(width 0.10795)
		(layer "F.Cu")
		(net "FAN_TACH2")
	)
	(segment
		(start 18.863564 -119.916702)
		(end 18.847308 -119.900446)
		(width 0.10795)
		(layer "F.Cu")
		(net "FAN_TACH2")
	)
	(segment
		(start 18.960592 -118.227602)
		(end 18.960592 -117.145054)
		(width 0.10795)
		(layer "F.Cu")
		(net "FAN_TACH2")
	)
	(segment
		(start 18.863564 -118.32463)
		(end 18.9484 -118.239794)
		(width 0.10795)
		(layer "F.Cu")
		(net "FAN_TACH2")
	)
	(via
		(at 19.3802 -42.291)
		(size 0.6604)
		(drill 0.3302)
		(layers "F.Cu" "B.Cu")
		(net "FAN_TACH2")
	)
	(via
		(at 457.738226 -14.371574)
		(size 0.508)
		(drill 0.254)
		(layers "F.Cu" "B.Cu")
		(net "FAN_TACH2")
	)
	(via
		(at 22.136354 -46.957488)
		(size 0.508)
		(drill 0.254)
		(layers "F.Cu" "B.Cu")
		(net "FAN_TACH2")
	)
	(via
		(at 415.920428 -5.492242)
		(size 0.508)
		(drill 0.254)
		(layers "F.Cu" "B.Cu")
		(net "FAN_TACH2")
	)
	(via
		(at 460.531972 -32.505904)
		(size 0.508)
		(drill 0.254)
		(layers "F.Cu" "B.Cu")
		(net "FAN_TACH2")
	)
	(via
		(at 333.135986 -23.223474)
		(size 0.508)
		(drill 0.254)
		(layers "F.Cu" "B.Cu")
		(net "FAN_TACH2")
	)
	(via
		(at 421.09009 -29.334714)
		(size 0.4572)
		(drill 0.2032)
		(layers "F.Cu" "B.Cu")
		(net "FAN_TACH2")
	)
	(via
		(at 15.171674 -121.936764)
		(size 0.508)
		(drill 0.254)
		(layers "F.Cu" "B.Cu")
		(net "FAN_TACH2")
	)
	(segment
		(start 22.77999 -46.313852)
		(end 22.136354 -46.957488)
		(width 0.10795)
		(layer "B.Cu")
		(net "FAN_TACH2")
	)
	(segment
		(start 20.39874 -42.291)
		(end 22.77999 -44.67225)
		(width 0.10795)
		(layer "B.Cu")
		(net "FAN_TACH2")
	)
	(segment
		(start 17.653 -42.291)
		(end 19.3802 -42.291)
		(width 0.10795)
		(layer "B.Cu")
		(net "FAN_TACH2")
	)
	(segment
		(start 19.3802 -42.291)
		(end 20.39874 -42.291)
		(width 0.10795)
		(layer "B.Cu")
		(net "FAN_TACH2")
	)
	(segment
		(start 22.77999 -44.67225)
		(end 22.77999 -46.313852)
		(width 0.10795)
		(layer "B.Cu")
		(net "FAN_TACH2")
	)
	(segment
		(start 430.51476 -24.632666)
		(end 429.733202 -24.632666)
		(width 0.089408)
		(layer "In2.Cu")
		(net "FAN_TACH2")
	)
	(segment
		(start 453.056244 -26.120852)
		(end 449.132452 -26.120852)
		(width 0.089408)
		(layer "In2.Cu")
		(net "FAN_TACH2")
	)
	(segment
		(start 422.275 -28.42006)
		(end 422.275 -28.679648)
		(width 0.089408)
		(layer "In2.Cu")
		(net "FAN_TACH2")
	)
	(segment
		(start 12.979908 -83.721448)
		(end 13.555472 -83.721448)
		(width 0.089408)
		(layer "In2.Cu")
		(net "FAN_TACH2")
	)
	(segment
		(start 458.670406 -31.63443)
		(end 458.670406 -31.082742)
		(width 0.089408)
		(layer "In2.Cu")
		(net "FAN_TACH2")
	)
	(segment
		(start 12.573 -77.132688)
		(end 13.1318 -76.573888)
		(width 0.089408)
		(layer "In2.Cu")
		(net "FAN_TACH2")
	)
	(segment
		(start 459.967838 -31.94177)
		(end 458.977746 -31.94177)
		(width 0.089408)
		(layer "In2.Cu")
		(net "FAN_TACH2")
	)
	(segment
		(start 12.050014 -89.695782)
		(end 12.050014 -84.651342)
		(width 0.089408)
		(layer "In2.Cu")
		(net "FAN_TACH2")
	)
	(segment
		(start 13.778992 -51.810412)
		(end 13.778738 -51.810158)
		(width 0.089408)
		(layer "In2.Cu")
		(net "FAN_TACH2")
	)
	(segment
		(start 13.778738 -51.810158)
		(end 13.778738 -51.567842)
		(width 0.089408)
		(layer "In2.Cu")
		(net "FAN_TACH2")
	)
	(segment
		(start 430.688496 -24.45893)
		(end 430.51476 -24.632666)
		(width 0.089408)
		(layer "In2.Cu")
		(net "FAN_TACH2")
	)
	(segment
		(start 427.20641 -25.351486)
		(end 426.94225 -25.615646)
		(width 0.089408)
		(layer "In2.Cu")
		(net "FAN_TACH2")
	)
	(segment
		(start 427.20641 -25.248616)
		(end 427.20641 -25.351486)
		(width 0.089408)
		(layer "In2.Cu")
		(net "FAN_TACH2")
	)
	(segment
		(start 11.638788 -102.66553)
		(end 11.638788 -90.107008)
		(width 0.089408)
		(layer "In2.Cu")
		(net "FAN_TACH2")
	)
	(segment
		(start 13.971778 -81.755488)
		(end 12.579604 -80.363314)
		(width 0.089408)
		(layer "In2.Cu")
		(net "FAN_TACH2")
	)
	(segment
		(start 458.977746 -31.94177)
		(end 458.670406 -31.63443)
		(width 0.089408)
		(layer "In2.Cu")
		(net "FAN_TACH2")
	)
	(segment
		(start 13.1318 -71.9328)
		(end 12.738354 -71.539354)
		(width 0.0889)
		(layer "In2.Cu")
		(net "FAN_TACH2")
	)
	(segment
		(start 14.9479 -121.71299)
		(end 14.9479 -121.0691)
		(width 0.089408)
		(layer "In2.Cu")
		(net "FAN_TACH2")
	)
	(segment
		(start 17.73682 -120.390666)
		(end 21.707348 -116.420138)
		(width 0.089408)
		(layer "In2.Cu")
		(net "FAN_TACH2")
	)
	(segment
		(start 426.838618 -25.616408)
		(end 425.32935 -25.616408)
		(width 0.089408)
		(layer "In2.Cu")
		(net "FAN_TACH2")
	)
	(segment
		(start 13.778992 -52.46751)
		(end 13.778992 -51.810412)
		(width 0.089408)
		(layer "In2.Cu")
		(net "FAN_TACH2")
	)
	(segment
		(start 422.019984 -28.934664)
		(end 421.49014 -28.934664)
		(width 0.089408)
		(layer "In2.Cu")
		(net "FAN_TACH2")
	)
	(segment
		(start 12.579604 -80.363314)
		(end 12.573 -80.363314)
		(width 0.089408)
		(layer "In2.Cu")
		(net "FAN_TACH2")
	)
	(segment
		(start 22.136354 -47.223426)
		(end 22.136354 -46.957488)
		(width 0.089408)
		(layer "In2.Cu")
		(net "FAN_TACH2")
	)
	(segment
		(start 11.638788 -90.107008)
		(end 12.050014 -89.695782)
		(width 0.089408)
		(layer "In2.Cu")
		(net "FAN_TACH2")
	)
	(segment
		(start 13.555472 -83.721448)
		(end 13.971778 -83.305142)
		(width 0.089408)
		(layer "In2.Cu")
		(net "FAN_TACH2")
	)
	(segment
		(start 12.738354 -68.014596)
		(end 11.700764 -66.977006)
		(width 0.089408)
		(layer "In2.Cu")
		(net "FAN_TACH2")
	)
	(segment
		(start 432.350672 -24.37511)
		(end 432.266852 -24.45893)
		(width 0.089408)
		(layer "In2.Cu")
		(net "FAN_TACH2")
	)
	(segment
		(start 437.627522 -22.66061)
		(end 436.699406 -23.588726)
		(width 0.089408)
		(layer "In2.Cu")
		(net "FAN_TACH2")
	)
	(segment
		(start 428.122334 -24.332692)
		(end 427.20641 -25.248616)
		(width 0.089408)
		(layer "In2.Cu")
		(net "FAN_TACH2")
	)
	(segment
		(start 426.83938 -25.615646)
		(end 426.838618 -25.616408)
		(width 0.089408)
		(layer "In2.Cu")
		(net "FAN_TACH2")
	)
	(segment
		(start 424.80865 -26.137108)
		(end 424.80865 -26.317448)
		(width 0.089408)
		(layer "In2.Cu")
		(net "FAN_TACH2")
	)
	(segment
		(start 21.707348 -112.73409)
		(end 11.638788 -102.66553)
		(width 0.089408)
		(layer "In2.Cu")
		(net "FAN_TACH2")
	)
	(segment
		(start 426.94225 -25.615646)
		(end 426.83938 -25.615646)
		(width 0.089408)
		(layer "In2.Cu")
		(net "FAN_TACH2")
	)
	(segment
		(start 436.699406 -23.588726)
		(end 435.574186 -23.588726)
		(width 0.089408)
		(layer "In2.Cu")
		(net "FAN_TACH2")
	)
	(segment
		(start 19.398488 -49.961292)
		(end 22.136354 -47.223426)
		(width 0.089408)
		(layer "In2.Cu")
		(net "FAN_TACH2")
	)
	(segment
		(start 422.275 -28.679648)
		(end 422.019984 -28.934664)
		(width 0.089408)
		(layer "In2.Cu")
		(net "FAN_TACH2")
	)
	(segment
		(start 15.626334 -120.390666)
		(end 17.73682 -120.390666)
		(width 0.089408)
		(layer "In2.Cu")
		(net "FAN_TACH2")
	)
	(segment
		(start 432.266852 -24.45893)
		(end 430.688496 -24.45893)
		(width 0.089408)
		(layer "In2.Cu")
		(net "FAN_TACH2")
	)
	(segment
		(start 21.707348 -116.420138)
		(end 21.707348 -112.73409)
		(width 0.089408)
		(layer "In2.Cu")
		(net "FAN_TACH2")
	)
	(segment
		(start 444.093854 -22.66061)
		(end 437.627522 -22.66061)
		(width 0.089408)
		(layer "In2.Cu")
		(net "FAN_TACH2")
	)
	(segment
		(start 12.573 -80.363314)
		(end 12.573 -77.132688)
		(width 0.089408)
		(layer "In2.Cu")
		(net "FAN_TACH2")
	)
	(segment
		(start 15.385288 -49.961292)
		(end 19.398488 -49.961292)
		(width 0.089408)
		(layer "In2.Cu")
		(net "FAN_TACH2")
	)
	(segment
		(start 13.1318 -76.573888)
		(end 13.1318 -71.9328)
		(width 0.089408)
		(layer "In2.Cu")
		(net "FAN_TACH2")
	)
	(segment
		(start 448.0814 -25.0698)
		(end 446.503044 -25.0698)
		(width 0.089408)
		(layer "In2.Cu")
		(net "FAN_TACH2")
	)
	(segment
		(start 11.700764 -66.977006)
		(end 11.700764 -54.545738)
		(width 0.089408)
		(layer "In2.Cu")
		(net "FAN_TACH2")
	)
	(segment
		(start 421.49014 -28.934664)
		(end 421.09009 -29.334714)
		(width 0.089408)
		(layer "In2.Cu")
		(net "FAN_TACH2")
	)
	(segment
		(start 424.80865 -26.317448)
		(end 423.045636 -28.080462)
		(width 0.089408)
		(layer "In2.Cu")
		(net "FAN_TACH2")
	)
	(segment
		(start 429.433228 -24.332692)
		(end 428.122334 -24.332692)
		(width 0.089408)
		(layer "In2.Cu")
		(net "FAN_TACH2")
	)
	(segment
		(start 434.787802 -24.37511)
		(end 432.350672 -24.37511)
		(width 0.089408)
		(layer "In2.Cu")
		(net "FAN_TACH2")
	)
	(segment
		(start 455.27722 -27.689556)
		(end 454.624948 -27.689556)
		(width 0.089408)
		(layer "In2.Cu")
		(net "FAN_TACH2")
	)
	(segment
		(start 12.050014 -84.651342)
		(end 12.979908 -83.721448)
		(width 0.089408)
		(layer "In2.Cu")
		(net "FAN_TACH2")
	)
	(segment
		(start 15.171674 -121.936764)
		(end 14.9479 -121.71299)
		(width 0.089408)
		(layer "In2.Cu")
		(net "FAN_TACH2")
	)
	(segment
		(start 454.624948 -27.689556)
		(end 453.056244 -26.120852)
		(width 0.089408)
		(layer "In2.Cu")
		(net "FAN_TACH2")
	)
	(segment
		(start 11.700764 -54.545738)
		(end 13.778992 -52.46751)
		(width 0.089408)
		(layer "In2.Cu")
		(net "FAN_TACH2")
	)
	(segment
		(start 429.733202 -24.632666)
		(end 429.433228 -24.332692)
		(width 0.089408)
		(layer "In2.Cu")
		(net "FAN_TACH2")
	)
	(segment
		(start 13.778738 -51.567842)
		(end 15.385288 -49.961292)
		(width 0.089408)
		(layer "In2.Cu")
		(net "FAN_TACH2")
	)
	(segment
		(start 12.738354 -71.539354)
		(end 12.738354 -68.014596)
		(width 0.089408)
		(layer "In2.Cu")
		(net "FAN_TACH2")
	)
	(segment
		(start 435.574186 -23.588726)
		(end 434.787802 -24.37511)
		(width 0.089408)
		(layer "In2.Cu")
		(net "FAN_TACH2")
	)
	(segment
		(start 460.531972 -32.505904)
		(end 459.967838 -31.94177)
		(width 0.089408)
		(layer "In2.Cu")
		(net "FAN_TACH2")
	)
	(segment
		(start 458.670406 -31.082742)
		(end 455.27722 -27.689556)
		(width 0.089408)
		(layer "In2.Cu")
		(net "FAN_TACH2")
	)
	(segment
		(start 449.132452 -26.120852)
		(end 448.0814 -25.0698)
		(width 0.089408)
		(layer "In2.Cu")
		(net "FAN_TACH2")
	)
	(segment
		(start 13.971778 -83.305142)
		(end 13.971778 -81.755488)
		(width 0.089408)
		(layer "In2.Cu")
		(net "FAN_TACH2")
	)
	(segment
		(start 422.614598 -28.080462)
		(end 422.275 -28.42006)
		(width 0.089408)
		(layer "In2.Cu")
		(net "FAN_TACH2")
	)
	(segment
		(start 425.32935 -25.616408)
		(end 424.80865 -26.137108)
		(width 0.089408)
		(layer "In2.Cu")
		(net "FAN_TACH2")
	)
	(segment
		(start 446.503044 -25.0698)
		(end 444.093854 -22.66061)
		(width 0.089408)
		(layer "In2.Cu")
		(net "FAN_TACH2")
	)
	(segment
		(start 423.045636 -28.080462)
		(end 422.614598 -28.080462)
		(width 0.089408)
		(layer "In2.Cu")
		(net "FAN_TACH2")
	)
	(segment
		(start 14.9479 -121.0691)
		(end 15.626334 -120.390666)
		(width 0.089408)
		(layer "In2.Cu")
		(net "FAN_TACH2")
	)
	(segment
		(start 21.3995 -38.81882)
		(end 21.713698 -39.133018)
		(width 0.089408)
		(layer "In4.Cu")
		(net "FAN_TACH2")
	)
	(segment
		(start 21.713698 -39.133018)
		(end 23.7617 -39.133018)
		(width 0.089408)
		(layer "In4.Cu")
		(net "FAN_TACH2")
	)
	(segment
		(start 324.38213 -18.847054)
		(end 324.38213 -0.521716)
		(width 0.089408)
		(layer "In4.Cu")
		(net "FAN_TACH2")
	)
	(segment
		(start 184.225184 -1.204976)
		(end 184.225184 -1.263396)
		(width 0.089408)
		(layer "In4.Cu")
		(net "FAN_TACH2")
	)
	(segment
		(start 447.21399 -6.998462)
		(end 418.841682 -6.998462)
		(width 0.089408)
		(layer "In4.Cu")
		(net "FAN_TACH2")
	)
	(segment
		(start 104.1146 2.9464)
		(end 104.11333 2.94767)
		(width 0.089408)
		(layer "In4.Cu")
		(net "FAN_TACH2")
	)
	(segment
		(start 104.11333 2.94767)
		(end 102.692454 2.94767)
		(width 0.089408)
		(layer "In4.Cu")
		(net "FAN_TACH2")
	)
	(segment
		(start 27.463496 -19.88185)
		(end 29.476192 -21.894546)
		(width 0.089408)
		(layer "In4.Cu")
		(net "FAN_TACH2")
	)
	(segment
		(start 321.814698 3.500882)
		(end 187.346844 3.500882)
		(width 0.089408)
		(layer "In4.Cu")
		(net "FAN_TACH2")
	)
	(segment
		(start 29.476192 -29.167836)
		(end 25.611328 -33.0327)
		(width 0.089408)
		(layer "In4.Cu")
		(net "FAN_TACH2")
	)
	(segment
		(start 102.692454 2.94767)
		(end 102.13594 3.504184)
		(width 0.089408)
		(layer "In4.Cu")
		(net "FAN_TACH2")
	)
	(segment
		(start 183.014874 -4.325112)
		(end 182.440326 -4.325112)
		(width 0.089408)
		(layer "In4.Cu")
		(net "FAN_TACH2")
	)
	(segment
		(start 173.78426 -5.53974)
		(end 172.309536 -5.53974)
		(width 0.089408)
		(layer "In4.Cu")
		(net "FAN_TACH2")
	)
	(segment
		(start 156.734256 3.615944)
		(end 117.453664 3.615944)
		(width 0.089408)
		(layer "In4.Cu")
		(net "FAN_TACH2")
	)
	(segment
		(start 187.346844 3.500882)
		(end 184.672224 0.826262)
		(width 0.089408)
		(layer "In4.Cu")
		(net "FAN_TACH2")
	)
	(segment
		(start 167.82669 -4.110736)
		(end 166.36492 -2.648966)
		(width 0.089408)
		(layer "In4.Cu")
		(net "FAN_TACH2")
	)
	(segment
		(start 24.03094 -33.0327)
		(end 21.3995 -35.66414)
		(width 0.089408)
		(layer "In4.Cu")
		(net "FAN_TACH2")
	)
	(segment
		(start 324.38213 -0.521716)
		(end 323.582792 0.277622)
		(width 0.089408)
		(layer "In4.Cu")
		(net "FAN_TACH2")
	)
	(segment
		(start 329.667362 -21.922994)
		(end 328.009504 -20.265136)
		(width 0.089408)
		(layer "In4.Cu")
		(net "FAN_TACH2")
	)
	(segment
		(start 418.841682 -6.998462)
		(end 417.335462 -5.492242)
		(width 0.089408)
		(layer "In4.Cu")
		(net "FAN_TACH2")
	)
	(segment
		(start 25.611328 -33.0327)
		(end 24.03094 -33.0327)
		(width 0.089408)
		(layer "In4.Cu")
		(net "FAN_TACH2")
	)
	(segment
		(start 174.45228 -4.87172)
		(end 173.78426 -5.53974)
		(width 0.089408)
		(layer "In4.Cu")
		(net "FAN_TACH2")
	)
	(segment
		(start 160.6804 -0.3302)
		(end 156.734256 3.615944)
		(width 0.089408)
		(layer "In4.Cu")
		(net "FAN_TACH2")
	)
	(segment
		(start 116.78412 2.9464)
		(end 104.1146 2.9464)
		(width 0.089408)
		(layer "In4.Cu")
		(net "FAN_TACH2")
	)
	(segment
		(start 183.591708 -3.505454)
		(end 183.591962 -3.505708)
		(width 0.089408)
		(layer "In4.Cu")
		(net "FAN_TACH2")
	)
	(segment
		(start 27.463496 -16.478758)
		(end 27.463496 -19.88185)
		(width 0.089408)
		(layer "In4.Cu")
		(net "FAN_TACH2")
	)
	(segment
		(start 102.13594 3.504184)
		(end 29.196284 3.504184)
		(width 0.089408)
		(layer "In4.Cu")
		(net "FAN_TACH2")
	)
	(segment
		(start 325.800212 -20.265136)
		(end 324.38213 -18.847054)
		(width 0.089408)
		(layer "In4.Cu")
		(net "FAN_TACH2")
	)
	(segment
		(start 170.880532 -4.110736)
		(end 167.82669 -4.110736)
		(width 0.089408)
		(layer "In4.Cu")
		(net "FAN_TACH2")
	)
	(segment
		(start 28.461462 -0.334518)
		(end 28.017216 -0.778764)
		(width 0.089408)
		(layer "In4.Cu")
		(net "FAN_TACH2")
	)
	(segment
		(start 23.7617 -39.133018)
		(end 24.03856 -39.409878)
		(width 0.089408)
		(layer "In4.Cu")
		(net "FAN_TACH2")
	)
	(segment
		(start 29.196284 3.504184)
		(end 28.461462 2.769362)
		(width 0.089408)
		(layer "In4.Cu")
		(net "FAN_TACH2")
	)
	(segment
		(start 24.03856 -39.409878)
		(end 24.03856 -45.055282)
		(width 0.089408)
		(layer "In4.Cu")
		(net "FAN_TACH2")
	)
	(segment
		(start 182.440326 -4.325112)
		(end 182.39867 -4.283456)
		(width 0.089408)
		(layer "In4.Cu")
		(net "FAN_TACH2")
	)
	(segment
		(start 184.216294 -2.096262)
		(end 183.591708 -2.720848)
		(width 0.089408)
		(layer "In4.Cu")
		(net "FAN_TACH2")
	)
	(segment
		(start 184.672224 -0.757936)
		(end 184.225184 -1.204976)
		(width 0.089408)
		(layer "In4.Cu")
		(net "FAN_TACH2")
	)
	(segment
		(start 166.36492 -1.578102)
		(end 165.117018 -0.3302)
		(width 0.089408)
		(layer "In4.Cu")
		(net "FAN_TACH2")
	)
	(segment
		(start 28.017216 -0.778764)
		(end 28.017216 -15.925038)
		(width 0.089408)
		(layer "In4.Cu")
		(net "FAN_TACH2")
	)
	(segment
		(start 29.476192 -21.894546)
		(end 29.476192 -29.167836)
		(width 0.089408)
		(layer "In4.Cu")
		(net "FAN_TACH2")
	)
	(segment
		(start 165.117018 -0.3302)
		(end 160.6804 -0.3302)
		(width 0.089408)
		(layer "In4.Cu")
		(net "FAN_TACH2")
	)
	(segment
		(start 455.516742 -11.12774)
		(end 451.786498 -11.12774)
		(width 0.089408)
		(layer "In4.Cu")
		(net "FAN_TACH2")
	)
	(segment
		(start 176.89195 -4.283456)
		(end 176.303686 -4.87172)
		(width 0.089408)
		(layer "In4.Cu")
		(net "FAN_TACH2")
	)
	(segment
		(start 166.36492 -2.648966)
		(end 166.36492 -1.578102)
		(width 0.089408)
		(layer "In4.Cu")
		(net "FAN_TACH2")
	)
	(segment
		(start 333.135986 -23.223474)
		(end 331.835506 -21.922994)
		(width 0.089408)
		(layer "In4.Cu")
		(net "FAN_TACH2")
	)
	(segment
		(start 117.453664 3.615944)
		(end 116.78412 2.9464)
		(width 0.089408)
		(layer "In4.Cu")
		(net "FAN_TACH2")
	)
	(segment
		(start 184.225184 -1.263396)
		(end 184.216294 -1.272286)
		(width 0.089408)
		(layer "In4.Cu")
		(net "FAN_TACH2")
	)
	(segment
		(start 323.582792 0.277622)
		(end 323.582792 1.732788)
		(width 0.089408)
		(layer "In4.Cu")
		(net "FAN_TACH2")
	)
	(segment
		(start 28.017216 -15.925038)
		(end 27.463496 -16.478758)
		(width 0.089408)
		(layer "In4.Cu")
		(net "FAN_TACH2")
	)
	(segment
		(start 184.216294 -1.272286)
		(end 184.216294 -2.096262)
		(width 0.089408)
		(layer "In4.Cu")
		(net "FAN_TACH2")
	)
	(segment
		(start 184.672224 0.826262)
		(end 184.672224 -0.757936)
		(width 0.089408)
		(layer "In4.Cu")
		(net "FAN_TACH2")
	)
	(segment
		(start 24.03856 -45.055282)
		(end 22.136354 -46.957488)
		(width 0.089408)
		(layer "In4.Cu")
		(net "FAN_TACH2")
	)
	(segment
		(start 21.3995 -35.66414)
		(end 21.3995 -38.81882)
		(width 0.089408)
		(layer "In4.Cu")
		(net "FAN_TACH2")
	)
	(segment
		(start 183.591962 -3.505708)
		(end 183.591962 -3.748024)
		(width 0.089408)
		(layer "In4.Cu")
		(net "FAN_TACH2")
	)
	(segment
		(start 328.009504 -20.265136)
		(end 325.800212 -20.265136)
		(width 0.089408)
		(layer "In4.Cu")
		(net "FAN_TACH2")
	)
	(segment
		(start 448.171062 -7.512304)
		(end 447.727832 -7.512304)
		(width 0.089408)
		(layer "In4.Cu")
		(net "FAN_TACH2")
	)
	(segment
		(start 183.591708 -2.720848)
		(end 183.591708 -3.505454)
		(width 0.089408)
		(layer "In4.Cu")
		(net "FAN_TACH2")
	)
	(segment
		(start 182.39867 -4.283456)
		(end 176.89195 -4.283456)
		(width 0.089408)
		(layer "In4.Cu")
		(net "FAN_TACH2")
	)
	(segment
		(start 172.309536 -5.53974)
		(end 170.880532 -4.110736)
		(width 0.089408)
		(layer "In4.Cu")
		(net "FAN_TACH2")
	)
	(segment
		(start 451.786498 -11.12774)
		(end 448.171062 -7.512304)
		(width 0.089408)
		(layer "In4.Cu")
		(net "FAN_TACH2")
	)
	(segment
		(start 323.582792 1.732788)
		(end 321.814698 3.500882)
		(width 0.089408)
		(layer "In4.Cu")
		(net "FAN_TACH2")
	)
	(segment
		(start 457.738226 -14.371574)
		(end 457.738226 -13.349224)
		(width 0.089408)
		(layer "In4.Cu")
		(net "FAN_TACH2")
	)
	(segment
		(start 331.835506 -21.922994)
		(end 329.667362 -21.922994)
		(width 0.089408)
		(layer "In4.Cu")
		(net "FAN_TACH2")
	)
	(segment
		(start 457.738226 -13.349224)
		(end 455.516742 -11.12774)
		(width 0.089408)
		(layer "In4.Cu")
		(net "FAN_TACH2")
	)
	(segment
		(start 447.727832 -7.512304)
		(end 447.21399 -6.998462)
		(width 0.089408)
		(layer "In4.Cu")
		(net "FAN_TACH2")
	)
	(segment
		(start 417.335462 -5.492242)
		(end 415.920428 -5.492242)
		(width 0.089408)
		(layer "In4.Cu")
		(net "FAN_TACH2")
	)
	(segment
		(start 176.303686 -4.87172)
		(end 174.45228 -4.87172)
		(width 0.089408)
		(layer "In4.Cu")
		(net "FAN_TACH2")
	)
	(segment
		(start 183.591962 -3.748024)
		(end 183.014874 -4.325112)
		(width 0.089408)
		(layer "In4.Cu")
		(net "FAN_TACH2")
	)
	(segment
		(start 28.461462 2.769362)
		(end 28.461462 -0.334518)
		(width 0.089408)
		(layer "In4.Cu")
		(net "FAN_TACH2")
	)
	(segment
		(start 392.109706 -6.539992)
		(end 392.7094 -6.539992)
		(width 0.089408)
		(layer "In11.Cu")
		(net "FAN_TACH2")
	)
	(segment
		(start 390.554718 -4.985004)
		(end 392.109706 -6.539992)
		(width 0.089408)
		(layer "In11.Cu")
		(net "FAN_TACH2")
	)
	(segment
		(start 393.0904 -5.3086)
		(end 393.5476 -4.8514)
		(width 0.089408)
		(layer "In11.Cu")
		(net "FAN_TACH2")
	)
	(segment
		(start 461.892396 -24.56815)
		(end 461.957166 -24.50338)
		(width 0.089408)
		(layer "In11.Cu")
		(net "FAN_TACH2")
	)
	(segment
		(start 415.279586 -4.8514)
		(end 415.920428 -5.492242)
		(width 0.089408)
		(layer "In11.Cu")
		(net "FAN_TACH2")
	)
	(segment
		(start 392.7094 -6.539992)
		(end 393.0904 -6.158992)
		(width 0.089408)
		(layer "In11.Cu")
		(net "FAN_TACH2")
	)
	(segment
		(start 333.135986 -23.223474)
		(end 333.629 -23.716488)
		(width 0.089408)
		(layer "In11.Cu")
		(net "FAN_TACH2")
	)
	(segment
		(start 462.4578 -25.437846)
		(end 461.892396 -24.872442)
		(width 0.089408)
		(layer "In11.Cu")
		(net "FAN_TACH2")
	)
	(segment
		(start 369.696492 -8.570976)
		(end 372.093236 -6.174232)
		(width 0.089408)
		(layer "In11.Cu")
		(net "FAN_TACH2")
	)
	(segment
		(start 354.833936 -34.39668)
		(end 361.701588 -27.529028)
		(width 0.089408)
		(layer "In11.Cu")
		(net "FAN_TACH2")
	)
	(segment
		(start 461.957166 -22.323044)
		(end 457.738226 -18.104104)
		(width 0.089408)
		(layer "In11.Cu")
		(net "FAN_TACH2")
	)
	(segment
		(start 372.093236 -6.174232)
		(end 383.093468 -6.174232)
		(width 0.089408)
		(layer "In11.Cu")
		(net "FAN_TACH2")
	)
	(segment
		(start 393.5476 -4.8514)
		(end 415.279586 -4.8514)
		(width 0.089408)
		(layer "In11.Cu")
		(net "FAN_TACH2")
	)
	(segment
		(start 384.282696 -4.985004)
		(end 390.554718 -4.985004)
		(width 0.089408)
		(layer "In11.Cu")
		(net "FAN_TACH2")
	)
	(segment
		(start 460.531972 -32.171894)
		(end 462.4578 -30.246066)
		(width 0.089408)
		(layer "In11.Cu")
		(net "FAN_TACH2")
	)
	(segment
		(start 361.701588 -27.529028)
		(end 361.701588 -17.82699)
		(width 0.089408)
		(layer "In11.Cu")
		(net "FAN_TACH2")
	)
	(segment
		(start 338.86648 -34.39668)
		(end 354.833936 -34.39668)
		(width 0.089408)
		(layer "In11.Cu")
		(net "FAN_TACH2")
	)
	(segment
		(start 333.629 -30.119066)
		(end 336.510884 -33.00095)
		(width 0.089408)
		(layer "In11.Cu")
		(net "FAN_TACH2")
	)
	(segment
		(start 461.892396 -24.872442)
		(end 461.892396 -24.56815)
		(width 0.089408)
		(layer "In11.Cu")
		(net "FAN_TACH2")
	)
	(segment
		(start 369.696492 -9.832086)
		(end 369.696492 -8.570976)
		(width 0.089408)
		(layer "In11.Cu")
		(net "FAN_TACH2")
	)
	(segment
		(start 383.093468 -6.174232)
		(end 384.282696 -4.985004)
		(width 0.089408)
		(layer "In11.Cu")
		(net "FAN_TACH2")
	)
	(segment
		(start 460.531972 -32.505904)
		(end 460.531972 -32.171894)
		(width 0.089408)
		(layer "In11.Cu")
		(net "FAN_TACH2")
	)
	(segment
		(start 393.0904 -6.158992)
		(end 393.0904 -5.3086)
		(width 0.089408)
		(layer "In11.Cu")
		(net "FAN_TACH2")
	)
	(segment
		(start 336.510884 -33.00095)
		(end 337.47075 -33.00095)
		(width 0.089408)
		(layer "In11.Cu")
		(net "FAN_TACH2")
	)
	(segment
		(start 457.738226 -18.104104)
		(end 457.738226 -14.371574)
		(width 0.089408)
		(layer "In11.Cu")
		(net "FAN_TACH2")
	)
	(segment
		(start 461.957166 -24.50338)
		(end 461.957166 -22.323044)
		(width 0.089408)
		(layer "In11.Cu")
		(net "FAN_TACH2")
	)
	(segment
		(start 337.47075 -33.00095)
		(end 338.86648 -34.39668)
		(width 0.089408)
		(layer "In11.Cu")
		(net "FAN_TACH2")
	)
	(segment
		(start 462.4578 -30.246066)
		(end 462.4578 -25.437846)
		(width 0.089408)
		(layer "In11.Cu")
		(net "FAN_TACH2")
	)
	(segment
		(start 361.701588 -17.82699)
		(end 369.696492 -9.832086)
		(width 0.089408)
		(layer "In11.Cu")
		(net "FAN_TACH2")
	)
	(segment
		(start 333.629 -23.716488)
		(end 333.629 -30.119066)
		(width 0.089408)
		(layer "In11.Cu")
		(net "FAN_TACH2")
	)
	(segment
		(start 419.890194 -28.934664)
		(end 419.890194 -28.93441)
		(width 0.10795)
		(layer "F.Cu")
		(net "FAN_TACH1")
	)
	(segment
		(start 419.890194 -28.93441)
		(end 420.28999 -28.534614)
		(width 0.10795)
		(layer "F.Cu")
		(net "FAN_TACH1")
	)
	(via
		(at 158.242 0.762)
		(size 0.508)
		(drill 0.254)
		(layers "F.Cu" "B.Cu")
		(net "FAN_TACH1")
	)
	(via
		(at 333.133954 -23.863808)
		(size 0.508)
		(drill 0.254)
		(layers "F.Cu" "B.Cu")
		(net "FAN_TACH1")
	)
	(via
		(at 385.97332 -20.653502)
		(size 0.508)
		(drill 0.254)
		(layers "F.Cu" "B.Cu")
		(net "FAN_TACH1")
	)
	(via
		(at 422.783 -25.146)
		(size 0.508)
		(drill 0.254)
		(layers "F.Cu" "B.Cu")
		(net "FAN_TACH1")
	)
	(via
		(at 387.788912 -31.538672)
		(size 0.508)
		(drill 0.254)
		(layers "F.Cu" "B.Cu")
		(net "FAN_TACH1")
	)
	(via
		(at 383.413 -8.1026)
		(size 0.508)
		(drill 0.254)
		(layers "F.Cu" "B.Cu")
		(net "FAN_TACH1")
	)
	(via
		(at 22.1488 -38.702996)
		(size 0.508)
		(drill 0.254)
		(layers "F.Cu" "B.Cu")
		(net "FAN_TACH1")
	)
	(via
		(at 19.532346 -40.10533)
		(size 0.6604)
		(drill 0.3302)
		(layers "F.Cu" "B.Cu")
		(net "FAN_TACH1")
	)
	(via
		(at 28.956 -0.889)
		(size 0.508)
		(drill 0.254)
		(layers "F.Cu" "B.Cu")
		(net "FAN_TACH1")
	)
	(via
		(at 420.28999 -28.534614)
		(size 0.4572)
		(drill 0.2032)
		(layers "F.Cu" "B.Cu")
		(net "FAN_TACH1")
	)
	(segment
		(start 19.532346 -40.10533)
		(end 16.168116 -40.10533)
		(width 0.10795)
		(layer "B.Cu")
		(net "FAN_TACH1")
	)
	(segment
		(start 20.619974 -40.10533)
		(end 22.022308 -38.702996)
		(width 0.10795)
		(layer "B.Cu")
		(net "FAN_TACH1")
	)
	(segment
		(start 423.199814 -26.02103)
		(end 423.200068 -26.020776)
		(width 0.10795)
		(layer "B.Cu")
		(net "FAN_TACH1")
	)
	(segment
		(start 385.97332 -20.653502)
		(end 384.90398 -20.653502)
		(width 0.10795)
		(layer "B.Cu")
		(net "FAN_TACH1")
	)
	(segment
		(start 423.279824 -26.020776)
		(end 423.734738 -25.565862)
		(width 0.10795)
		(layer "B.Cu")
		(net "FAN_TACH1")
	)
	(segment
		(start 384.368802 -20.118324)
		(end 384.368802 -10.480802)
		(width 0.10795)
		(layer "B.Cu")
		(net "FAN_TACH1")
	)
	(segment
		(start 425.222416 -25.558496)
		(end 426.455586 -24.325326)
		(width 0.10033)
		(layer "B.Cu")
		(net "FAN_TACH1")
	)
	(segment
		(start 423.734738 -25.565862)
		(end 423.742104 -25.558496)
		(width 0.10033)
		(layer "B.Cu")
		(net "FAN_TACH1")
	)
	(segment
		(start 422.59631 -26.020776)
		(end 423.026332 -26.020776)
		(width 0.10795)
		(layer "B.Cu")
		(net "FAN_TACH1")
	)
	(segment
		(start 423.026332 -26.020776)
		(end 423.026586 -26.02103)
		(width 0.10795)
		(layer "B.Cu")
		(net "FAN_TACH1")
	)
	(segment
		(start 423.200068 -26.020776)
		(end 423.279824 -26.020776)
		(width 0.10795)
		(layer "B.Cu")
		(net "FAN_TACH1")
	)
	(segment
		(start 384.368802 -10.480802)
		(end 383.413 -9.525)
		(width 0.10795)
		(layer "B.Cu")
		(net "FAN_TACH1")
	)
	(segment
		(start 421.304466 -26.977086)
		(end 421.64 -26.977086)
		(width 0.10795)
		(layer "B.Cu")
		(net "FAN_TACH1")
	)
	(segment
		(start 420.28999 -28.534614)
		(end 420.684198 -28.140406)
		(width 0.10795)
		(layer "B.Cu")
		(net "FAN_TACH1")
	)
	(segment
		(start 22.022308 -38.702996)
		(end 22.1488 -38.702996)
		(width 0.10795)
		(layer "B.Cu")
		(net "FAN_TACH1")
	)
	(segment
		(start 426.999908 -24.110188)
		(end 426.999908 -23.67534)
		(width 0.10033)
		(layer "B.Cu")
		(net "FAN_TACH1")
	)
	(segment
		(start 423.742104 -25.558496)
		(end 425.222416 -25.558496)
		(width 0.10033)
		(layer "B.Cu")
		(net "FAN_TACH1")
	)
	(segment
		(start 16.168116 -40.10533)
		(end 14.871446 -41.402)
		(width 0.10795)
		(layer "B.Cu")
		(net "FAN_TACH1")
	)
	(segment
		(start 421.64 -26.977086)
		(end 422.59631 -26.020776)
		(width 0.10795)
		(layer "B.Cu")
		(net "FAN_TACH1")
	)
	(segment
		(start 19.532346 -40.10533)
		(end 20.619974 -40.10533)
		(width 0.10795)
		(layer "B.Cu")
		(net "FAN_TACH1")
	)
	(segment
		(start 420.684198 -27.597354)
		(end 421.304466 -26.977086)
		(width 0.10795)
		(layer "B.Cu")
		(net "FAN_TACH1")
	)
	(segment
		(start 426.455586 -24.325326)
		(end 426.78477 -24.325326)
		(width 0.10033)
		(layer "B.Cu")
		(net "FAN_TACH1")
	)
	(segment
		(start 383.413 -9.525)
		(end 383.413 -8.1026)
		(width 0.10795)
		(layer "B.Cu")
		(net "FAN_TACH1")
	)
	(segment
		(start 426.999908 -23.67534)
		(end 427.307248 -23.368)
		(width 0.10033)
		(layer "B.Cu")
		(net "FAN_TACH1")
	)
	(segment
		(start 423.026586 -26.02103)
		(end 423.199814 -26.02103)
		(width 0.10795)
		(layer "B.Cu")
		(net "FAN_TACH1")
	)
	(segment
		(start 384.90398 -20.653502)
		(end 384.368802 -20.118324)
		(width 0.10795)
		(layer "B.Cu")
		(net "FAN_TACH1")
	)
	(segment
		(start 420.684198 -28.140406)
		(end 420.684198 -27.597354)
		(width 0.10795)
		(layer "B.Cu")
		(net "FAN_TACH1")
	)
	(segment
		(start 427.307248 -23.368)
		(end 427.4185 -23.368)
		(width 0.10033)
		(layer "B.Cu")
		(net "FAN_TACH1")
	)
	(segment
		(start 426.78477 -24.325326)
		(end 426.999908 -24.110188)
		(width 0.10033)
		(layer "B.Cu")
		(net "FAN_TACH1")
	)
	(segment
		(start 14.871446 -41.402)
		(end 13.97 -41.402)
		(width 0.10795)
		(layer "B.Cu")
		(net "FAN_TACH1")
	)
	(segment
		(start 400.822414 -27.534616)
		(end 401.635468 -28.34767)
		(width 0.089408)
		(layer "In2.Cu")
		(net "FAN_TACH1")
	)
	(segment
		(start 407.227024 -27.422856)
		(end 408.576526 -27.422856)
		(width 0.089408)
		(layer "In2.Cu")
		(net "FAN_TACH1")
	)
	(segment
		(start 403.766274 -27.817064)
		(end 404.78202 -26.801318)
		(width 0.089408)
		(layer "In2.Cu")
		(net "FAN_TACH1")
	)
	(segment
		(start 387.788912 -31.538672)
		(end 387.788912 -31.258764)
		(width 0.089408)
		(layer "In2.Cu")
		(net "FAN_TACH1")
	)
	(segment
		(start 390.64692 -28.194)
		(end 391.916158 -28.194)
		(width 0.089408)
		(layer "In2.Cu")
		(net "FAN_TACH1")
	)
	(segment
		(start 401.635468 -28.34767)
		(end 402.250656 -28.34767)
		(width 0.089408)
		(layer "In2.Cu")
		(net "FAN_TACH1")
	)
	(segment
		(start 402.250656 -28.34767)
		(end 402.781262 -27.817064)
		(width 0.089408)
		(layer "In2.Cu")
		(net "FAN_TACH1")
	)
	(segment
		(start 422.2242 -24.5872)
		(end 422.783 -25.146)
		(width 0.089408)
		(layer "In2.Cu")
		(net "FAN_TACH1")
	)
	(segment
		(start 402.781262 -27.817064)
		(end 403.766274 -27.817064)
		(width 0.089408)
		(layer "In2.Cu")
		(net "FAN_TACH1")
	)
	(segment
		(start 405.78913 -26.801318)
		(end 406.063958 -27.076146)
		(width 0.089408)
		(layer "In2.Cu")
		(net "FAN_TACH1")
	)
	(segment
		(start 387.788912 -31.258764)
		(end 388.185406 -30.86227)
		(width 0.089408)
		(layer "In2.Cu")
		(net "FAN_TACH1")
	)
	(segment
		(start 408.576526 -27.422856)
		(end 409.630626 -26.368756)
		(width 0.089408)
		(layer "In2.Cu")
		(net "FAN_TACH1")
	)
	(segment
		(start 418.588952 -24.87295)
		(end 420.531036 -24.87295)
		(width 0.089408)
		(layer "In2.Cu")
		(net "FAN_TACH1")
	)
	(segment
		(start 388.185406 -30.86227)
		(end 388.185406 -30.655514)
		(width 0.089408)
		(layer "In2.Cu")
		(net "FAN_TACH1")
	)
	(segment
		(start 404.78202 -26.801318)
		(end 405.78913 -26.801318)
		(width 0.089408)
		(layer "In2.Cu")
		(net "FAN_TACH1")
	)
	(segment
		(start 391.916158 -28.194)
		(end 392.16203 -27.948128)
		(width 0.089408)
		(layer "In2.Cu")
		(net "FAN_TACH1")
	)
	(segment
		(start 417.500054 -25.961848)
		(end 418.588952 -24.87295)
		(width 0.089408)
		(layer "In2.Cu")
		(net "FAN_TACH1")
	)
	(segment
		(start 406.880314 -27.076146)
		(end 407.227024 -27.422856)
		(width 0.089408)
		(layer "In2.Cu")
		(net "FAN_TACH1")
	)
	(segment
		(start 413.50819 -25.961848)
		(end 417.500054 -25.961848)
		(width 0.089408)
		(layer "In2.Cu")
		(net "FAN_TACH1")
	)
	(segment
		(start 392.16203 -27.948128)
		(end 396.782544 -27.948128)
		(width 0.089408)
		(layer "In2.Cu")
		(net "FAN_TACH1")
	)
	(segment
		(start 420.816786 -24.5872)
		(end 422.2242 -24.5872)
		(width 0.089408)
		(layer "In2.Cu")
		(net "FAN_TACH1")
	)
	(segment
		(start 396.782544 -27.948128)
		(end 397.196056 -27.534616)
		(width 0.089408)
		(layer "In2.Cu")
		(net "FAN_TACH1")
	)
	(segment
		(start 420.531036 -24.87295)
		(end 420.816786 -24.5872)
		(width 0.089408)
		(layer "In2.Cu")
		(net "FAN_TACH1")
	)
	(segment
		(start 406.063958 -27.076146)
		(end 406.880314 -27.076146)
		(width 0.089408)
		(layer "In2.Cu")
		(net "FAN_TACH1")
	)
	(segment
		(start 397.196056 -27.534616)
		(end 400.822414 -27.534616)
		(width 0.089408)
		(layer "In2.Cu")
		(net "FAN_TACH1")
	)
	(segment
		(start 409.630626 -26.368756)
		(end 413.101282 -26.368756)
		(width 0.089408)
		(layer "In2.Cu")
		(net "FAN_TACH1")
	)
	(segment
		(start 388.185406 -30.655514)
		(end 390.64692 -28.194)
		(width 0.089408)
		(layer "In2.Cu")
		(net "FAN_TACH1")
	)
	(segment
		(start 413.101282 -26.368756)
		(end 413.50819 -25.961848)
		(width 0.089408)
		(layer "In2.Cu")
		(net "FAN_TACH1")
	)
	(segment
		(start 327.888092 -20.557744)
		(end 325.6788 -20.557744)
		(width 0.089408)
		(layer "In4.Cu")
		(net "FAN_TACH1")
	)
	(segment
		(start 28.309824 -16.292576)
		(end 28.309824 -1.535176)
		(width 0.089408)
		(layer "In4.Cu")
		(net "FAN_TACH1")
	)
	(segment
		(start 254.960374 3.073146)
		(end 254.825246 3.208274)
		(width 0.089408)
		(layer "In4.Cu")
		(net "FAN_TACH1")
	)
	(segment
		(start 325.6788 -20.557744)
		(end 324.089522 -18.968466)
		(width 0.089408)
		(layer "In4.Cu")
		(net "FAN_TACH1")
	)
	(segment
		(start 324.089522 -0.645922)
		(end 323.2404 0.2032)
		(width 0.089408)
		(layer "In4.Cu")
		(net "FAN_TACH1")
	)
	(segment
		(start 333.133954 -23.863808)
		(end 331.485748 -22.215602)
		(width 0.089408)
		(layer "In4.Cu")
		(net "FAN_TACH1")
	)
	(segment
		(start 182.318914 -4.61772)
		(end 182.277258 -4.576064)
		(width 0.089408)
		(layer "In4.Cu")
		(net "FAN_TACH1")
	)
	(segment
		(start 176.269904 -5.449062)
		(end 175.854106 -5.86486)
		(width 0.089408)
		(layer "In4.Cu")
		(net "FAN_TACH1")
	)
	(segment
		(start 176.269904 -5.314442)
		(end 176.269904 -5.449062)
		(width 0.089408)
		(layer "In4.Cu")
		(net "FAN_TACH1")
	)
	(segment
		(start 323.2404 1.66116)
		(end 321.707256 3.194304)
		(width 0.089408)
		(layer "In4.Cu")
		(net "FAN_TACH1")
	)
	(segment
		(start 176.420018 -5.164328)
		(end 176.269904 -5.314442)
		(width 0.089408)
		(layer "In4.Cu")
		(net "FAN_TACH1")
	)
	(segment
		(start 176.425098 -5.164328)
		(end 176.420018 -5.164328)
		(width 0.089408)
		(layer "In4.Cu")
		(net "FAN_TACH1")
	)
	(segment
		(start 175.854106 -5.86486)
		(end 172.197776 -5.86486)
		(width 0.089408)
		(layer "In4.Cu")
		(net "FAN_TACH1")
	)
	(segment
		(start 185.81878 -0.0254)
		(end 184.517792 -1.326388)
		(width 0.089408)
		(layer "In4.Cu")
		(net "FAN_TACH1")
	)
	(segment
		(start 192.964308 3.208274)
		(end 190.733426 0.977392)
		(width 0.089408)
		(layer "In4.Cu")
		(net "FAN_TACH1")
	)
	(segment
		(start 262.017764 3.194304)
		(end 261.218426 2.394966)
		(width 0.089408)
		(layer "In4.Cu")
		(net "FAN_TACH1")
	)
	(segment
		(start 188.174122 -0.0254)
		(end 185.81878 -0.0254)
		(width 0.089408)
		(layer "In4.Cu")
		(net "FAN_TACH1")
	)
	(segment
		(start 182.277258 -4.576064)
		(end 177.013362 -4.576064)
		(width 0.089408)
		(layer "In4.Cu")
		(net "FAN_TACH1")
	)
	(segment
		(start 324.089522 -18.968466)
		(end 324.089522 -0.645922)
		(width 0.089408)
		(layer "In4.Cu")
		(net "FAN_TACH1")
	)
	(segment
		(start 21.752052 -38.306248)
		(end 21.752052 -35.855148)
		(width 0.089408)
		(layer "In4.Cu")
		(net "FAN_TACH1")
	)
	(segment
		(start 184.517792 -1.384808)
		(end 184.508902 -1.393698)
		(width 0.089408)
		(layer "In4.Cu")
		(net "FAN_TACH1")
	)
	(segment
		(start 184.508902 -1.393698)
		(end 184.508902 -3.76047)
		(width 0.089408)
		(layer "In4.Cu")
		(net "FAN_TACH1")
	)
	(segment
		(start 190.733426 0.977392)
		(end 190.733426 0.629412)
		(width 0.089408)
		(layer "In4.Cu")
		(net "FAN_TACH1")
	)
	(segment
		(start 259.371338 2.394966)
		(end 258.693158 3.073146)
		(width 0.089408)
		(layer "In4.Cu")
		(net "FAN_TACH1")
	)
	(segment
		(start 24.257 -33.3502)
		(end 25.840436 -33.3502)
		(width 0.089408)
		(layer "In4.Cu")
		(net "FAN_TACH1")
	)
	(segment
		(start 27.756104 -16.846296)
		(end 28.309824 -16.292576)
		(width 0.089408)
		(layer "In4.Cu")
		(net "FAN_TACH1")
	)
	(segment
		(start 184.517792 -1.326388)
		(end 184.517792 -1.384808)
		(width 0.089408)
		(layer "In4.Cu")
		(net "FAN_TACH1")
	)
	(segment
		(start 165.109398 -0.7366)
		(end 160.3756 -0.7366)
		(width 0.089408)
		(layer "In4.Cu")
		(net "FAN_TACH1")
	)
	(segment
		(start 188.352938 -0.204216)
		(end 188.174122 -0.0254)
		(width 0.089408)
		(layer "In4.Cu")
		(net "FAN_TACH1")
	)
	(segment
		(start 166.072312 -1.699514)
		(end 165.109398 -0.7366)
		(width 0.089408)
		(layer "In4.Cu")
		(net "FAN_TACH1")
	)
	(segment
		(start 189.899798 -0.204216)
		(end 188.352938 -0.204216)
		(width 0.089408)
		(layer "In4.Cu")
		(net "FAN_TACH1")
	)
	(segment
		(start 21.752052 -35.855148)
		(end 24.257 -33.3502)
		(width 0.089408)
		(layer "In4.Cu")
		(net "FAN_TACH1")
	)
	(segment
		(start 177.013362 -4.576064)
		(end 176.425098 -5.164328)
		(width 0.089408)
		(layer "In4.Cu")
		(net "FAN_TACH1")
	)
	(segment
		(start 160.3756 -0.7366)
		(end 158.877 0.762)
		(width 0.089408)
		(layer "In4.Cu")
		(net "FAN_TACH1")
	)
	(segment
		(start 261.218426 2.394966)
		(end 259.371338 2.394966)
		(width 0.089408)
		(layer "In4.Cu")
		(net "FAN_TACH1")
	)
	(segment
		(start 190.733426 0.629412)
		(end 189.899798 -0.204216)
		(width 0.089408)
		(layer "In4.Cu")
		(net "FAN_TACH1")
	)
	(segment
		(start 183.651652 -4.61772)
		(end 182.318914 -4.61772)
		(width 0.089408)
		(layer "In4.Cu")
		(net "FAN_TACH1")
	)
	(segment
		(start 323.2404 0.2032)
		(end 323.2404 1.66116)
		(width 0.089408)
		(layer "In4.Cu")
		(net "FAN_TACH1")
	)
	(segment
		(start 167.792908 -4.572)
		(end 166.072312 -2.851404)
		(width 0.089408)
		(layer "In4.Cu")
		(net "FAN_TACH1")
	)
	(segment
		(start 254.825246 3.208274)
		(end 192.964308 3.208274)
		(width 0.089408)
		(layer "In4.Cu")
		(net "FAN_TACH1")
	)
	(segment
		(start 25.840436 -33.3502)
		(end 29.7688 -29.421836)
		(width 0.089408)
		(layer "In4.Cu")
		(net "FAN_TACH1")
	)
	(segment
		(start 331.485748 -22.215602)
		(end 329.54595 -22.215602)
		(width 0.089408)
		(layer "In4.Cu")
		(net "FAN_TACH1")
	)
	(segment
		(start 27.756104 -19.760438)
		(end 27.756104 -16.846296)
		(width 0.089408)
		(layer "In4.Cu")
		(net "FAN_TACH1")
	)
	(segment
		(start 28.309824 -1.535176)
		(end 28.956 -0.889)
		(width 0.089408)
		(layer "In4.Cu")
		(net "FAN_TACH1")
	)
	(segment
		(start 166.072312 -2.851404)
		(end 166.072312 -1.699514)
		(width 0.089408)
		(layer "In4.Cu")
		(net "FAN_TACH1")
	)
	(segment
		(start 29.7688 -29.421836)
		(end 29.7688 -21.773134)
		(width 0.089408)
		(layer "In4.Cu")
		(net "FAN_TACH1")
	)
	(segment
		(start 258.693158 3.073146)
		(end 254.960374 3.073146)
		(width 0.089408)
		(layer "In4.Cu")
		(net "FAN_TACH1")
	)
	(segment
		(start 22.1488 -38.702996)
		(end 21.752052 -38.306248)
		(width 0.089408)
		(layer "In4.Cu")
		(net "FAN_TACH1")
	)
	(segment
		(start 321.707256 3.194304)
		(end 262.017764 3.194304)
		(width 0.089408)
		(layer "In4.Cu")
		(net "FAN_TACH1")
	)
	(segment
		(start 158.877 0.762)
		(end 158.242 0.762)
		(width 0.089408)
		(layer "In4.Cu")
		(net "FAN_TACH1")
	)
	(segment
		(start 29.7688 -21.773134)
		(end 27.756104 -19.760438)
		(width 0.089408)
		(layer "In4.Cu")
		(net "FAN_TACH1")
	)
	(segment
		(start 172.197776 -5.86486)
		(end 170.904916 -4.572)
		(width 0.089408)
		(layer "In4.Cu")
		(net "FAN_TACH1")
	)
	(segment
		(start 184.508902 -3.76047)
		(end 183.651652 -4.61772)
		(width 0.089408)
		(layer "In4.Cu")
		(net "FAN_TACH1")
	)
	(segment
		(start 170.904916 -4.572)
		(end 167.792908 -4.572)
		(width 0.089408)
		(layer "In4.Cu")
		(net "FAN_TACH1")
	)
	(segment
		(start 329.54595 -22.215602)
		(end 327.888092 -20.557744)
		(width 0.089408)
		(layer "In4.Cu")
		(net "FAN_TACH1")
	)
	(segment
		(start 389.584438 -22.761956)
		(end 389.584438 -28.626054)
		(width 0.089408)
		(layer "In9.Cu")
		(net "FAN_TACH1")
	)
	(segment
		(start 158.242 0.762)
		(end 157.275784 -0.204216)
		(width 0.089408)
		(layer "In9.Cu")
		(net "FAN_TACH1")
	)
	(segment
		(start 389.165338 -22.342856)
		(end 389.584438 -22.761956)
		(width 0.089408)
		(layer "In9.Cu")
		(net "FAN_TACH1")
	)
	(segment
		(start 388.19836 -30.012132)
		(end 388.19836 -30.90164)
		(width 0.089408)
		(layer "In9.Cu")
		(net "FAN_TACH1")
	)
	(segment
		(start 422.783 -25.146)
		(end 420.665148 -27.263852)
		(width 0.089408)
		(layer "In9.Cu")
		(net "FAN_TACH1")
	)
	(segment
		(start 387.788912 -31.311088)
		(end 387.788912 -31.538672)
		(width 0.089408)
		(layer "In9.Cu")
		(net "FAN_TACH1")
	)
	(segment
		(start 387.258052 -22.03704)
		(end 387.40334 -22.03704)
		(width 0.089408)
		(layer "In9.Cu")
		(net "FAN_TACH1")
	)
	(segment
		(start 387.709156 -22.342856)
		(end 389.165338 -22.342856)
		(width 0.089408)
		(layer "In9.Cu")
		(net "FAN_TACH1")
	)
	(segment
		(start 157.275784 -0.204216)
		(end 29.640784 -0.204216)
		(width 0.089408)
		(layer "In9.Cu")
		(net "FAN_TACH1")
	)
	(segment
		(start 385.97332 -20.752308)
		(end 387.258052 -22.03704)
		(width 0.089408)
		(layer "In9.Cu")
		(net "FAN_TACH1")
	)
	(segment
		(start 387.40334 -22.03704)
		(end 387.709156 -22.342856)
		(width 0.089408)
		(layer "In9.Cu")
		(net "FAN_TACH1")
	)
	(segment
		(start 420.665148 -27.263852)
		(end 420.665148 -28.013152)
		(width 0.089408)
		(layer "In9.Cu")
		(net "FAN_TACH1")
	)
	(segment
		(start 29.640784 -0.204216)
		(end 28.956 -0.889)
		(width 0.089408)
		(layer "In9.Cu")
		(net "FAN_TACH1")
	)
	(segment
		(start 420.665148 -28.013152)
		(end 420.28999 -28.38831)
		(width 0.089408)
		(layer "In9.Cu")
		(net "FAN_TACH1")
	)
	(segment
		(start 385.97332 -20.653502)
		(end 385.97332 -20.752308)
		(width 0.089408)
		(layer "In9.Cu")
		(net "FAN_TACH1")
	)
	(segment
		(start 420.28999 -28.38831)
		(end 420.28999 -28.534614)
		(width 0.089408)
		(layer "In9.Cu")
		(net "FAN_TACH1")
	)
	(segment
		(start 388.19836 -30.90164)
		(end 387.788912 -31.311088)
		(width 0.089408)
		(layer "In9.Cu")
		(net "FAN_TACH1")
	)
	(segment
		(start 389.584438 -28.626054)
		(end 388.19836 -30.012132)
		(width 0.089408)
		(layer "In9.Cu")
		(net "FAN_TACH1")
	)
	(segment
		(start 361.99445 -27.650186)
		(end 354.955348 -34.689288)
		(width 0.089408)
		(layer "In11.Cu")
		(net "FAN_TACH1")
	)
	(segment
		(start 337.349592 -33.293812)
		(end 336.389726 -33.293812)
		(width 0.089408)
		(layer "In11.Cu")
		(net "FAN_TACH1")
	)
	(segment
		(start 361.994196 -17.948402)
		(end 361.994196 -27.407616)
		(width 0.089408)
		(layer "In11.Cu")
		(net "FAN_TACH1")
	)
	(segment
		(start 338.745068 -34.689288)
		(end 337.349592 -33.293812)
		(width 0.089408)
		(layer "In11.Cu")
		(net "FAN_TACH1")
	)
	(segment
		(start 369.9891 -8.692388)
		(end 369.9891 -9.953498)
		(width 0.089408)
		(layer "In11.Cu")
		(net "FAN_TACH1")
	)
	(segment
		(start 383.413 -7.1882)
		(end 382.729232 -6.504432)
		(width 0.089408)
		(layer "In11.Cu")
		(net "FAN_TACH1")
	)
	(segment
		(start 361.99445 -27.40787)
		(end 361.99445 -27.650186)
		(width 0.089408)
		(layer "In11.Cu")
		(net "FAN_TACH1")
	)
	(segment
		(start 333.323438 -30.227524)
		(end 333.323438 -24.053292)
		(width 0.089408)
		(layer "In11.Cu")
		(net "FAN_TACH1")
	)
	(segment
		(start 382.729232 -6.504432)
		(end 372.177056 -6.504432)
		(width 0.089408)
		(layer "In11.Cu")
		(net "FAN_TACH1")
	)
	(segment
		(start 333.323438 -24.053292)
		(end 333.133954 -23.863808)
		(width 0.089408)
		(layer "In11.Cu")
		(net "FAN_TACH1")
	)
	(segment
		(start 383.413 -8.1026)
		(end 383.413 -7.1882)
		(width 0.089408)
		(layer "In11.Cu")
		(net "FAN_TACH1")
	)
	(segment
		(start 336.389726 -33.293812)
		(end 333.323438 -30.227524)
		(width 0.089408)
		(layer "In11.Cu")
		(net "FAN_TACH1")
	)
	(segment
		(start 354.955348 -34.689288)
		(end 338.745068 -34.689288)
		(width 0.089408)
		(layer "In11.Cu")
		(net "FAN_TACH1")
	)
	(segment
		(start 369.9891 -9.953498)
		(end 361.994196 -17.948402)
		(width 0.089408)
		(layer "In11.Cu")
		(net "FAN_TACH1")
	)
	(segment
		(start 372.177056 -6.504432)
		(end 369.9891 -8.692388)
		(width 0.089408)
		(layer "In11.Cu")
		(net "FAN_TACH1")
	)
	(segment
		(start 361.994196 -27.407616)
		(end 361.99445 -27.40787)
		(width 0.089408)
		(layer "In11.Cu")
		(net "FAN_TACH1")
	)
	(segment
		(start 25.770332 -31.738316)
		(end 25.594056 -31.56204)
		(width 0.10795)
		(layer "F.Cu")
		(net "FAN_TACH0")
	)
	(segment
		(start 25.594056 -31.56204)
		(end 23.988522 -31.56204)
		(width 0.10795)
		(layer "F.Cu")
		(net "FAN_TACH0")
	)
	(segment
		(start 26.543 -29.972)
		(end 26.4922 -29.9212)
		(width 0.10795)
		(layer "F.Cu")
		(net "FAN_TACH0")
	)
	(segment
		(start 26.489406 -31.3309)
		(end 26.489406 -31.738316)
		(width 0.10795)
		(layer "F.Cu")
		(net "FAN_TACH0")
	)
	(segment
		(start 21.344382 -39.691818)
		(end 20.574 -40.4622)
		(width 0.10795)
		(layer "F.Cu")
		(net "FAN_TACH0")
	)
	(segment
		(start 23.6474 -31.903162)
		(end 23.6474 -32.91078)
		(width 0.10795)
		(layer "F.Cu")
		(net "FAN_TACH0")
	)
	(segment
		(start 26.543 -30.861)
		(end 26.543 -31.277306)
		(width 0.10795)
		(layer "F.Cu")
		(net "FAN_TACH0")
	)
	(segment
		(start 26.543 -31.277306)
		(end 26.489406 -31.3309)
		(width 0.10795)
		(layer "F.Cu")
		(net "FAN_TACH0")
	)
	(segment
		(start 13.6144 -40.4622)
		(end 13.1572 -40.005)
		(width 0.10795)
		(layer "F.Cu")
		(net "FAN_TACH0")
	)
	(segment
		(start 459.3336 -31.393638)
		(end 459.3336 -30.6832)
		(width 0.10795)
		(layer "F.Cu")
		(net "FAN_TACH0")
	)
	(segment
		(start 459.185772 -31.541466)
		(end 459.3336 -31.393638)
		(width 0.10795)
		(layer "F.Cu")
		(net "FAN_TACH0")
	)
	(segment
		(start 23.988522 -31.56204)
		(end 23.6474 -31.903162)
		(width 0.10795)
		(layer "F.Cu")
		(net "FAN_TACH0")
	)
	(segment
		(start 23.6474 -32.91078)
		(end 21.344382 -35.213798)
		(width 0.10795)
		(layer "F.Cu")
		(net "FAN_TACH0")
	)
	(segment
		(start 419.890194 -29.734764)
		(end 420.286942 -30.131512)
		(width 0.10795)
		(layer "F.Cu")
		(net "FAN_TACH0")
	)
	(segment
		(start 26.543 -30.861)
		(end 26.543 -29.972)
		(width 0.10795)
		(layer "F.Cu")
		(net "FAN_TACH0")
	)
	(segment
		(start 26.4922 -29.9212)
		(end 26.4922 -28.183078)
		(width 0.10795)
		(layer "F.Cu")
		(net "FAN_TACH0")
	)
	(segment
		(start 26.489406 -31.738316)
		(end 25.770332 -31.738316)
		(width 0.10795)
		(layer "F.Cu")
		(net "FAN_TACH0")
	)
	(segment
		(start 21.344382 -35.213798)
		(end 21.344382 -39.691818)
		(width 0.10795)
		(layer "F.Cu")
		(net "FAN_TACH0")
	)
	(segment
		(start 26.4922 -28.183078)
		(end 26.523696 -28.151582)
		(width 0.10795)
		(layer "F.Cu")
		(net "FAN_TACH0")
	)
	(segment
		(start 20.574 -40.4622)
		(end 13.6144 -40.4622)
		(width 0.10795)
		(layer "F.Cu")
		(net "FAN_TACH0")
	)
	(via
		(at 420.286942 -30.131512)
		(size 0.4572)
		(drill 0.2032)
		(layers "F.Cu" "B.Cu")
		(net "FAN_TACH0")
	)
	(via
		(at 361.970574 -12.296648)
		(size 0.508)
		(drill 0.254)
		(layers "F.Cu" "B.Cu")
		(net "FAN_TACH0")
	)
	(via
		(at 335.28 -21.717)
		(size 0.508)
		(drill 0.254)
		(layers "F.Cu" "B.Cu")
		(net "FAN_TACH0")
	)
	(via
		(at 460.733902 -0.580898)
		(size 0.508)
		(drill 0.254)
		(layers "F.Cu" "B.Cu")
		(net "FAN_TACH0")
	)
	(via
		(at 26.523696 -28.151582)
		(size 0.508)
		(drill 0.254)
		(layers "F.Cu" "B.Cu")
		(net "FAN_TACH0")
	)
	(via
		(at 459.185772 -31.541466)
		(size 0.508)
		(drill 0.254)
		(layers "F.Cu" "B.Cu")
		(net "FAN_TACH0")
	)
	(segment
		(start 420.66464 -28.373578)
		(end 420.66464 -28.690062)
		(width 0.089408)
		(layer "In2.Cu")
		(net "FAN_TACH0")
	)
	(segment
		(start 446.735708 -24.727408)
		(end 446.574672 -24.727408)
		(width 0.089408)
		(layer "In2.Cu")
		(net "FAN_TACH0")
	)
	(segment
		(start 434.678328 -24.070564)
		(end 432.805078 -24.070564)
		(width 0.089408)
		(layer "In2.Cu")
		(net "FAN_TACH0")
	)
	(segment
		(start 427.255686 -24.713184)
		(end 426.540676 -24.713184)
		(width 0.089408)
		(layer "In2.Cu")
		(net "FAN_TACH0")
	)
	(segment
		(start 437.498998 -22.368002)
		(end 436.524654 -23.342346)
		(width 0.089408)
		(layer "In2.Cu")
		(net "FAN_TACH0")
	)
	(segment
		(start 427.316392 -24.69769)
		(end 427.27118 -24.69769)
		(width 0.089408)
		(layer "In2.Cu")
		(net "FAN_TACH0")
	)
	(segment
		(start 450.39534 -25.806654)
		(end 449.316348 -24.727662)
		(width 0.089408)
		(layer "In2.Cu")
		(net "FAN_TACH0")
	)
	(segment
		(start 424.056556 -26.272744)
		(end 422.200324 -28.128976)
		(width 0.089408)
		(layer "In2.Cu")
		(net "FAN_TACH0")
	)
	(segment
		(start 420.909242 -28.128976)
		(end 420.66464 -28.373578)
		(width 0.089408)
		(layer "In2.Cu")
		(net "FAN_TACH0")
	)
	(segment
		(start 449.316348 -24.727662)
		(end 446.735962 -24.727662)
		(width 0.089408)
		(layer "In2.Cu")
		(net "FAN_TACH0")
	)
	(segment
		(start 424.876722 -25.090374)
		(end 424.056556 -25.91054)
		(width 0.089408)
		(layer "In2.Cu")
		(net "FAN_TACH0")
	)
	(segment
		(start 420.664386 -28.690316)
		(end 420.664386 -29.754068)
		(width 0.089408)
		(layer "In2.Cu")
		(net "FAN_TACH0")
	)
	(segment
		(start 427.27118 -24.69769)
		(end 427.255686 -24.713184)
		(width 0.089408)
		(layer "In2.Cu")
		(net "FAN_TACH0")
	)
	(segment
		(start 426.163486 -25.090374)
		(end 424.876722 -25.090374)
		(width 0.089408)
		(layer "In2.Cu")
		(net "FAN_TACH0")
	)
	(segment
		(start 436.524654 -23.342346)
		(end 435.406546 -23.342346)
		(width 0.089408)
		(layer "In2.Cu")
		(net "FAN_TACH0")
	)
	(segment
		(start 455.323956 -27.29357)
		(end 454.717658 -27.29357)
		(width 0.089408)
		(layer "In2.Cu")
		(net "FAN_TACH0")
	)
	(segment
		(start 446.574672 -24.727408)
		(end 444.215266 -22.368002)
		(width 0.089408)
		(layer "In2.Cu")
		(net "FAN_TACH0")
	)
	(segment
		(start 432.805078 -24.070564)
		(end 432.365658 -23.631144)
		(width 0.089408)
		(layer "In2.Cu")
		(net "FAN_TACH0")
	)
	(segment
		(start 420.66464 -28.690062)
		(end 420.664386 -28.690316)
		(width 0.089408)
		(layer "In2.Cu")
		(net "FAN_TACH0")
	)
	(segment
		(start 424.056556 -25.91054)
		(end 424.056556 -26.272744)
		(width 0.089408)
		(layer "In2.Cu")
		(net "FAN_TACH0")
	)
	(segment
		(start 432.365658 -23.631144)
		(end 428.382938 -23.631144)
		(width 0.089408)
		(layer "In2.Cu")
		(net "FAN_TACH0")
	)
	(segment
		(start 459.185772 -31.155386)
		(end 455.323956 -27.29357)
		(width 0.089408)
		(layer "In2.Cu")
		(net "FAN_TACH0")
	)
	(segment
		(start 420.664386 -29.754068)
		(end 420.286942 -30.131512)
		(width 0.089408)
		(layer "In2.Cu")
		(net "FAN_TACH0")
	)
	(segment
		(start 454.717658 -27.29357)
		(end 453.230742 -25.806654)
		(width 0.089408)
		(layer "In2.Cu")
		(net "FAN_TACH0")
	)
	(segment
		(start 446.735962 -24.727662)
		(end 446.735708 -24.727408)
		(width 0.089408)
		(layer "In2.Cu")
		(net "FAN_TACH0")
	)
	(segment
		(start 459.185772 -31.541466)
		(end 459.185772 -31.155386)
		(width 0.089408)
		(layer "In2.Cu")
		(net "FAN_TACH0")
	)
	(segment
		(start 428.382938 -23.631144)
		(end 427.316392 -24.69769)
		(width 0.089408)
		(layer "In2.Cu")
		(net "FAN_TACH0")
	)
	(segment
		(start 453.230742 -25.806654)
		(end 450.39534 -25.806654)
		(width 0.089408)
		(layer "In2.Cu")
		(net "FAN_TACH0")
	)
	(segment
		(start 422.200324 -28.128976)
		(end 420.909242 -28.128976)
		(width 0.089408)
		(layer "In2.Cu")
		(net "FAN_TACH0")
	)
	(segment
		(start 444.215266 -22.368002)
		(end 437.498998 -22.368002)
		(width 0.089408)
		(layer "In2.Cu")
		(net "FAN_TACH0")
	)
	(segment
		(start 435.406546 -23.342346)
		(end 434.678328 -24.070564)
		(width 0.089408)
		(layer "In2.Cu")
		(net "FAN_TACH0")
	)
	(segment
		(start 426.540676 -24.713184)
		(end 426.163486 -25.090374)
		(width 0.089408)
		(layer "In2.Cu")
		(net "FAN_TACH0")
	)
	(segment
		(start 26.523696 -28.151582)
		(end 26.867358 -27.80792)
		(width 0.089408)
		(layer "In4.Cu")
		(net "FAN_TACH0")
	)
	(segment
		(start 328.764392 -2.145792)
		(end 328.764392 -3.974084)
		(width 0.089408)
		(layer "In4.Cu")
		(net "FAN_TACH0")
	)
	(segment
		(start 324.517258 3.320542)
		(end 324.904608 2.933192)
		(width 0.089408)
		(layer "In4.Cu")
		(net "FAN_TACH0")
	)
	(segment
		(start 25.908 -1.2446)
		(end 26.181558 -0.971042)
		(width 0.089408)
		(layer "In4.Cu")
		(net "FAN_TACH0")
	)
	(segment
		(start 164.43325 4.786376)
		(end 165.871906 3.34772)
		(width 0.089408)
		(layer "In4.Cu")
		(net "FAN_TACH0")
	)
	(segment
		(start 28.0416 -26.8732)
		(end 28.0416 -25.38222)
		(width 0.089408)
		(layer "In4.Cu")
		(net "FAN_TACH0")
	)
	(segment
		(start 326.192388 -0.622808)
		(end 327.241408 -0.622808)
		(width 0.089408)
		(layer "In4.Cu")
		(net "FAN_TACH0")
	)
	(segment
		(start 324.904608 1.928876)
		(end 324.9168 1.916684)
		(width 0.089408)
		(layer "In4.Cu")
		(net "FAN_TACH0")
	)
	(segment
		(start 25.4762 -19.332956)
		(end 25.4762 -18.636234)
		(width 0.089408)
		(layer "In4.Cu")
		(net "FAN_TACH0")
	)
	(segment
		(start 25.908 -18.204434)
		(end 25.908 -1.2446)
		(width 0.089408)
		(layer "In4.Cu")
		(net "FAN_TACH0")
	)
	(segment
		(start 27.10688 -27.80792)
		(end 28.0416 -26.8732)
		(width 0.089408)
		(layer "In4.Cu")
		(net "FAN_TACH0")
	)
	(segment
		(start 183.451754 3.55727)
		(end 183.451754 3.89763)
		(width 0.089408)
		(layer "In4.Cu")
		(net "FAN_TACH0")
	)
	(segment
		(start 323.707506 3.320542)
		(end 324.517258 3.320542)
		(width 0.089408)
		(layer "In4.Cu")
		(net "FAN_TACH0")
	)
	(segment
		(start 183.501792 1.391412)
		(end 183.766206 1.655826)
		(width 0.089408)
		(layer "In4.Cu")
		(net "FAN_TACH0")
	)
	(segment
		(start 324.9168 1.916684)
		(end 324.9168 0.65278)
		(width 0.089408)
		(layer "In4.Cu")
		(net "FAN_TACH0")
	)
	(segment
		(start 183.451754 3.89763)
		(end 184.2643 4.710176)
		(width 0.089408)
		(layer "In4.Cu")
		(net "FAN_TACH0")
	)
	(segment
		(start 181.518052 -3.113024)
		(end 183.045862 -1.585214)
		(width 0.089408)
		(layer "In4.Cu")
		(net "FAN_TACH0")
	)
	(segment
		(start 330.7334 -20.6502)
		(end 334.3656 -20.6502)
		(width 0.089408)
		(layer "In4.Cu")
		(net "FAN_TACH0")
	)
	(segment
		(start 165.871906 0.570992)
		(end 167.535352 -1.092454)
		(width 0.089408)
		(layer "In4.Cu")
		(net "FAN_TACH0")
	)
	(segment
		(start 324.9168 0.65278)
		(end 326.192388 -0.622808)
		(width 0.089408)
		(layer "In4.Cu")
		(net "FAN_TACH0")
	)
	(segment
		(start 327.241408 -0.622808)
		(end 328.764392 -2.145792)
		(width 0.089408)
		(layer "In4.Cu")
		(net "FAN_TACH0")
	)
	(segment
		(start 168.312338 -2.940304)
		(end 172.59173 -2.940304)
		(width 0.089408)
		(layer "In4.Cu")
		(net "FAN_TACH0")
	)
	(segment
		(start 184.2643 4.710176)
		(end 322.317872 4.710176)
		(width 0.089408)
		(layer "In4.Cu")
		(net "FAN_TACH0")
	)
	(segment
		(start 328.3966 -4.341876)
		(end 328.3966 -6.29158)
		(width 0.089408)
		(layer "In4.Cu")
		(net "FAN_TACH0")
	)
	(segment
		(start 116.199666 4.118102)
		(end 116.86794 4.786376)
		(width 0.089408)
		(layer "In4.Cu")
		(net "FAN_TACH0")
	)
	(segment
		(start 167.535352 -1.092454)
		(end 167.535352 -2.163318)
		(width 0.089408)
		(layer "In4.Cu")
		(net "FAN_TACH0")
	)
	(segment
		(start 334.3656 -20.6502)
		(end 334.99679 -21.28139)
		(width 0.089408)
		(layer "In4.Cu")
		(net "FAN_TACH0")
	)
	(segment
		(start 172.669454 -2.86258)
		(end 173.008544 -2.86258)
		(width 0.089408)
		(layer "In4.Cu")
		(net "FAN_TACH0")
	)
	(segment
		(start 328.3966 -6.29158)
		(end 328.7141 -6.60908)
		(width 0.089408)
		(layer "In4.Cu")
		(net "FAN_TACH0")
	)
	(segment
		(start 172.59173 -2.940304)
		(end 172.669454 -2.86258)
		(width 0.089408)
		(layer "In4.Cu")
		(net "FAN_TACH0")
	)
	(segment
		(start 328.7141 -15.9639)
		(end 329.0443 -16.2941)
		(width 0.089408)
		(layer "In4.Cu")
		(net "FAN_TACH0")
	)
	(segment
		(start 183.501792 -0.272288)
		(end 183.501792 1.391412)
		(width 0.089408)
		(layer "In4.Cu")
		(net "FAN_TACH0")
	)
	(segment
		(start 25.4762 -18.636234)
		(end 25.908 -18.204434)
		(width 0.089408)
		(layer "In4.Cu")
		(net "FAN_TACH0")
	)
	(segment
		(start 173.258988 -3.113024)
		(end 181.518052 -3.113024)
		(width 0.089408)
		(layer "In4.Cu")
		(net "FAN_TACH0")
	)
	(segment
		(start 183.045862 -1.585214)
		(end 183.045862 -0.728218)
		(width 0.089408)
		(layer "In4.Cu")
		(net "FAN_TACH0")
	)
	(segment
		(start 328.7141 -6.60908)
		(end 328.7141 -15.9639)
		(width 0.089408)
		(layer "In4.Cu")
		(net "FAN_TACH0")
	)
	(segment
		(start 26.075894 -23.416514)
		(end 26.075894 -19.93265)
		(width 0.089408)
		(layer "In4.Cu")
		(net "FAN_TACH0")
	)
	(segment
		(start 116.86794 4.786376)
		(end 164.43325 4.786376)
		(width 0.089408)
		(layer "In4.Cu")
		(net "FAN_TACH0")
	)
	(segment
		(start 27.29103 0.15113)
		(end 27.29103 3.25501)
		(width 0.089408)
		(layer "In4.Cu")
		(net "FAN_TACH0")
	)
	(segment
		(start 165.871906 3.34772)
		(end 165.871906 0.570992)
		(width 0.089408)
		(layer "In4.Cu")
		(net "FAN_TACH0")
	)
	(segment
		(start 27.29103 3.25501)
		(end 28.710636 4.674616)
		(width 0.089408)
		(layer "In4.Cu")
		(net "FAN_TACH0")
	)
	(segment
		(start 167.535352 -2.163318)
		(end 168.312338 -2.940304)
		(width 0.089408)
		(layer "In4.Cu")
		(net "FAN_TACH0")
	)
	(segment
		(start 334.99679 -21.28139)
		(end 334.99679 -21.43379)
		(width 0.089408)
		(layer "In4.Cu")
		(net "FAN_TACH0")
	)
	(segment
		(start 183.766206 1.655826)
		(end 183.766206 3.242818)
		(width 0.089408)
		(layer "In4.Cu")
		(net "FAN_TACH0")
	)
	(segment
		(start 103.178102 4.118102)
		(end 116.199666 4.118102)
		(width 0.089408)
		(layer "In4.Cu")
		(net "FAN_TACH0")
	)
	(segment
		(start 324.904608 2.933192)
		(end 324.904608 1.928876)
		(width 0.089408)
		(layer "In4.Cu")
		(net "FAN_TACH0")
	)
	(segment
		(start 173.008544 -2.86258)
		(end 173.258988 -3.113024)
		(width 0.089408)
		(layer "In4.Cu")
		(net "FAN_TACH0")
	)
	(segment
		(start 102.621588 4.674616)
		(end 103.178102 4.118102)
		(width 0.089408)
		(layer "In4.Cu")
		(net "FAN_TACH0")
	)
	(segment
		(start 26.075894 -19.93265)
		(end 25.4762 -19.332956)
		(width 0.089408)
		(layer "In4.Cu")
		(net "FAN_TACH0")
	)
	(segment
		(start 26.181558 -0.971042)
		(end 26.181558 -0.958342)
		(width 0.089408)
		(layer "In4.Cu")
		(net "FAN_TACH0")
	)
	(segment
		(start 329.0443 -18.9611)
		(end 330.7334 -20.6502)
		(width 0.089408)
		(layer "In4.Cu")
		(net "FAN_TACH0")
	)
	(segment
		(start 329.0443 -16.2941)
		(end 329.0443 -18.9611)
		(width 0.089408)
		(layer "In4.Cu")
		(net "FAN_TACH0")
	)
	(segment
		(start 28.0416 -25.38222)
		(end 26.075894 -23.416514)
		(width 0.089408)
		(layer "In4.Cu")
		(net "FAN_TACH0")
	)
	(segment
		(start 183.766206 3.242818)
		(end 183.451754 3.55727)
		(width 0.089408)
		(layer "In4.Cu")
		(net "FAN_TACH0")
	)
	(segment
		(start 334.99679 -21.43379)
		(end 335.28 -21.717)
		(width 0.089408)
		(layer "In4.Cu")
		(net "FAN_TACH0")
	)
	(segment
		(start 322.317872 4.710176)
		(end 323.707506 3.320542)
		(width 0.089408)
		(layer "In4.Cu")
		(net "FAN_TACH0")
	)
	(segment
		(start 26.867358 -27.80792)
		(end 27.10688 -27.80792)
		(width 0.089408)
		(layer "In4.Cu")
		(net "FAN_TACH0")
	)
	(segment
		(start 328.764392 -3.974084)
		(end 328.3966 -4.341876)
		(width 0.089408)
		(layer "In4.Cu")
		(net "FAN_TACH0")
	)
	(segment
		(start 28.710636 4.674616)
		(end 102.621588 4.674616)
		(width 0.089408)
		(layer "In4.Cu")
		(net "FAN_TACH0")
	)
	(segment
		(start 26.181558 -0.958342)
		(end 27.29103 0.15113)
		(width 0.089408)
		(layer "In4.Cu")
		(net "FAN_TACH0")
	)
	(segment
		(start 183.045862 -0.728218)
		(end 183.501792 -0.272288)
		(width 0.089408)
		(layer "In4.Cu")
		(net "FAN_TACH0")
	)
	(segment
		(start 461.378808 -21.036788)
		(end 461.378808 -17.827498)
		(width 0.089408)
		(layer "In9.Cu")
		(net "FAN_TACH0")
	)
	(segment
		(start 358.282748 -30.015688)
		(end 355.957124 -32.341312)
		(width 0.089408)
		(layer "In9.Cu")
		(net "FAN_TACH0")
	)
	(segment
		(start 460.795878 -4.651502)
		(end 460.795878 -4.621022)
		(width 0.089408)
		(layer "In9.Cu")
		(net "FAN_TACH0")
	)
	(segment
		(start 460.795878 -4.894326)
		(end 460.795624 -4.894072)
		(width 0.089408)
		(layer "In9.Cu")
		(net "FAN_TACH0")
	)
	(segment
		(start 460.795624 -4.894072)
		(end 460.795624 -4.651756)
		(width 0.089408)
		(layer "In9.Cu")
		(net "FAN_TACH0")
	)
	(segment
		(start 465.13242 -10.07618)
		(end 465.13242 -9.609074)
		(width 0.089408)
		(layer "In9.Cu")
		(net "FAN_TACH0")
	)
	(segment
		(start 337.185 -33.1216)
		(end 335.1149 -33.1216)
		(width 0.089408)
		(layer "In9.Cu")
		(net "FAN_TACH0")
	)
	(segment
		(start 465.062062 -15.394178)
		(end 465.062062 -10.146538)
		(width 0.089408)
		(layer "In9.Cu")
		(net "FAN_TACH0")
	)
	(segment
		(start 465.062062 -10.146538)
		(end 465.13242 -10.07618)
		(width 0.089408)
		(layer "In9.Cu")
		(net "FAN_TACH0")
	)
	(segment
		(start 461.459072 -21.117052)
		(end 461.378808 -21.036788)
		(width 0.089408)
		(layer "In9.Cu")
		(net "FAN_TACH0")
	)
	(segment
		(start 463.71764 -16.7386)
		(end 465.062062 -15.394178)
		(width 0.089408)
		(layer "In9.Cu")
		(net "FAN_TACH0")
	)
	(segment
		(start 460.795624 -4.651756)
		(end 460.795878 -4.651502)
		(width 0.089408)
		(layer "In9.Cu")
		(net "FAN_TACH0")
	)
	(segment
		(start 335.28 -24.301704)
		(end 335.28 -21.717)
		(width 0.089408)
		(layer "In9.Cu")
		(net "FAN_TACH0")
	)
	(segment
		(start 459.185772 -29.129228)
		(end 461.459072 -26.855928)
		(width 0.089408)
		(layer "In9.Cu")
		(net "FAN_TACH0")
	)
	(segment
		(start 360.976418 -19.655536)
		(end 360.976418 -22.055836)
		(width 0.089408)
		(layer "In9.Cu")
		(net "FAN_TACH0")
	)
	(segment
		(start 361.970574 -18.66138)
		(end 360.976418 -19.655536)
		(width 0.089408)
		(layer "In9.Cu")
		(net "FAN_TACH0")
	)
	(segment
		(start 459.185772 -31.541466)
		(end 459.185772 -29.129228)
		(width 0.089408)
		(layer "In9.Cu")
		(net "FAN_TACH0")
	)
	(segment
		(start 354.839524 -33.704276)
		(end 337.767676 -33.704276)
		(width 0.089408)
		(layer "In9.Cu")
		(net "FAN_TACH0")
	)
	(segment
		(start 360.976418 -22.055836)
		(end 358.282748 -24.749506)
		(width 0.089408)
		(layer "In9.Cu")
		(net "FAN_TACH0")
	)
	(segment
		(start 337.767676 -33.704276)
		(end 337.185 -33.1216)
		(width 0.089408)
		(layer "In9.Cu")
		(net "FAN_TACH0")
	)
	(segment
		(start 361.970574 -12.296648)
		(end 361.970574 -18.66138)
		(width 0.089408)
		(layer "In9.Cu")
		(net "FAN_TACH0")
	)
	(segment
		(start 461.916272 -3.500628)
		(end 461.916272 -1.7653)
		(width 0.089408)
		(layer "In9.Cu")
		(net "FAN_TACH0")
	)
	(segment
		(start 358.282748 -24.749506)
		(end 358.282748 -30.015688)
		(width 0.089408)
		(layer "In9.Cu")
		(net "FAN_TACH0")
	)
	(segment
		(start 355.957124 -32.341312)
		(end 355.957124 -32.47263)
		(width 0.089408)
		(layer "In9.Cu")
		(net "FAN_TACH0")
	)
	(segment
		(start 461.378808 -17.827498)
		(end 462.467706 -16.7386)
		(width 0.089408)
		(layer "In9.Cu")
		(net "FAN_TACH0")
	)
	(segment
		(start 334.772 -32.7787)
		(end 334.772 -24.809704)
		(width 0.089408)
		(layer "In9.Cu")
		(net "FAN_TACH0")
	)
	(segment
		(start 335.1149 -33.1216)
		(end 334.772 -32.7787)
		(width 0.089408)
		(layer "In9.Cu")
		(net "FAN_TACH0")
	)
	(segment
		(start 465.13242 -9.609074)
		(end 464.062064 -8.538718)
		(width 0.089408)
		(layer "In9.Cu")
		(net "FAN_TACH0")
	)
	(segment
		(start 462.467706 -16.7386)
		(end 463.71764 -16.7386)
		(width 0.089408)
		(layer "In9.Cu")
		(net "FAN_TACH0")
	)
	(segment
		(start 463.383884 -8.538718)
		(end 460.795878 -5.950712)
		(width 0.089408)
		(layer "In9.Cu")
		(net "FAN_TACH0")
	)
	(segment
		(start 464.062064 -8.538718)
		(end 463.383884 -8.538718)
		(width 0.089408)
		(layer "In9.Cu")
		(net "FAN_TACH0")
	)
	(segment
		(start 461.916272 -1.7653)
		(end 460.733902 -0.58293)
		(width 0.089408)
		(layer "In9.Cu")
		(net "FAN_TACH0")
	)
	(segment
		(start 460.795878 -4.621022)
		(end 461.916272 -3.500628)
		(width 0.089408)
		(layer "In9.Cu")
		(net "FAN_TACH0")
	)
	(segment
		(start 355.946456 -32.483298)
		(end 355.946456 -32.597344)
		(width 0.089408)
		(layer "In9.Cu")
		(net "FAN_TACH0")
	)
	(segment
		(start 355.957124 -32.47263)
		(end 355.946456 -32.483298)
		(width 0.089408)
		(layer "In9.Cu")
		(net "FAN_TACH0")
	)
	(segment
		(start 461.459072 -26.855928)
		(end 461.459072 -21.117052)
		(width 0.089408)
		(layer "In9.Cu")
		(net "FAN_TACH0")
	)
	(segment
		(start 334.772 -24.809704)
		(end 335.28 -24.301704)
		(width 0.089408)
		(layer "In9.Cu")
		(net "FAN_TACH0")
	)
	(segment
		(start 355.946456 -32.597344)
		(end 354.839524 -33.704276)
		(width 0.089408)
		(layer "In9.Cu")
		(net "FAN_TACH0")
	)
	(segment
		(start 460.733902 -0.58293)
		(end 460.733902 -0.580898)
		(width 0.089408)
		(layer "In9.Cu")
		(net "FAN_TACH0")
	)
	(segment
		(start 460.795878 -5.950712)
		(end 460.795878 -4.894326)
		(width 0.089408)
		(layer "In9.Cu")
		(net "FAN_TACH0")
	)
	(segment
		(start 417.722812 1.3716)
		(end 415.906204 -0.445008)
		(width 0.089408)
		(layer "In11.Cu")
		(net "FAN_TACH0")
	)
	(segment
		(start 426.616876 -1.820164)
		(end 425.746418 -1.820164)
		(width 0.089408)
		(layer "In11.Cu")
		(net "FAN_TACH0")
	)
	(segment
		(start 449.392802 0.122936)
		(end 447.449702 -1.820164)
		(width 0.089408)
		(layer "In11.Cu")
		(net "FAN_TACH0")
	)
	(segment
		(start 425.746418 -1.820164)
		(end 422.554654 1.3716)
		(width 0.089408)
		(layer "In11.Cu")
		(net "FAN_TACH0")
	)
	(segment
		(start 447.449702 -1.820164)
		(end 426.8597 -1.820164)
		(width 0.089408)
		(layer "In11.Cu")
		(net "FAN_TACH0")
	)
	(segment
		(start 426.61713 -1.820418)
		(end 426.616876 -1.820164)
		(width 0.089408)
		(layer "In11.Cu")
		(net "FAN_TACH0")
	)
	(segment
		(start 406.615392 -1.283208)
		(end 403.797008 -1.283208)
		(width 0.089408)
		(layer "In11.Cu")
		(net "FAN_TACH0")
	)
	(segment
		(start 422.554654 1.3716)
		(end 417.722812 1.3716)
		(width 0.089408)
		(layer "In11.Cu")
		(net "FAN_TACH0")
	)
	(segment
		(start 403.03704 -2.043176)
		(end 390.379204 -2.043176)
		(width 0.089408)
		(layer "In11.Cu")
		(net "FAN_TACH0")
	)
	(segment
		(start 460.733902 -0.580898)
		(end 460.267304 -0.1143)
		(width 0.089408)
		(layer "In11.Cu")
		(net "FAN_TACH0")
	)
	(segment
		(start 426.8597 -1.820164)
		(end 426.859446 -1.820418)
		(width 0.089408)
		(layer "In11.Cu")
		(net "FAN_TACH0")
	)
	(segment
		(start 458.704188 0.7874)
		(end 458.67828 0.7874)
		(width 0.089408)
		(layer "In11.Cu")
		(net "FAN_TACH0")
	)
	(segment
		(start 381.978408 -3.415792)
		(end 380.683008 -4.711192)
		(width 0.089408)
		(layer "In11.Cu")
		(net "FAN_TACH0")
	)
	(segment
		(start 361.970574 -12.00404)
		(end 361.970574 -12.296648)
		(width 0.089408)
		(layer "In11.Cu")
		(net "FAN_TACH0")
	)
	(segment
		(start 407.453592 -0.445008)
		(end 406.615392 -1.283208)
		(width 0.089408)
		(layer "In11.Cu")
		(net "FAN_TACH0")
	)
	(segment
		(start 460.267304 -0.1143)
		(end 459.605888 -0.1143)
		(width 0.089408)
		(layer "In11.Cu")
		(net "FAN_TACH0")
	)
	(segment
		(start 380.683008 -4.711192)
		(end 369.263422 -4.711192)
		(width 0.089408)
		(layer "In11.Cu")
		(net "FAN_TACH0")
	)
	(segment
		(start 458.224382 0.851662)
		(end 457.495656 0.122936)
		(width 0.089408)
		(layer "In11.Cu")
		(net "FAN_TACH0")
	)
	(segment
		(start 458.67828 0.7874)
		(end 458.614018 0.851662)
		(width 0.089408)
		(layer "In11.Cu")
		(net "FAN_TACH0")
	)
	(segment
		(start 390.379204 -2.043176)
		(end 389.006588 -3.415792)
		(width 0.089408)
		(layer "In11.Cu")
		(net "FAN_TACH0")
	)
	(segment
		(start 457.495656 0.122936)
		(end 449.392802 0.122936)
		(width 0.089408)
		(layer "In11.Cu")
		(net "FAN_TACH0")
	)
	(segment
		(start 369.263422 -4.711192)
		(end 361.970574 -12.00404)
		(width 0.089408)
		(layer "In11.Cu")
		(net "FAN_TACH0")
	)
	(segment
		(start 426.859446 -1.820418)
		(end 426.61713 -1.820418)
		(width 0.089408)
		(layer "In11.Cu")
		(net "FAN_TACH0")
	)
	(segment
		(start 459.605888 -0.1143)
		(end 458.704188 0.7874)
		(width 0.089408)
		(layer "In11.Cu")
		(net "FAN_TACH0")
	)
	(segment
		(start 389.006588 -3.415792)
		(end 381.978408 -3.415792)
		(width 0.089408)
		(layer "In11.Cu")
		(net "FAN_TACH0")
	)
	(segment
		(start 403.797008 -1.283208)
		(end 403.03704 -2.043176)
		(width 0.089408)
		(layer "In11.Cu")
		(net "FAN_TACH0")
	)
	(segment
		(start 415.906204 -0.445008)
		(end 407.453592 -0.445008)
		(width 0.089408)
		(layer "In11.Cu")
		(net "FAN_TACH0")
	)
	(segment
		(start 458.614018 0.851662)
		(end 458.224382 0.851662)
		(width 0.089408)
		(layer "In11.Cu")
		(net "FAN_TACH0")
	)
	(segment
		(start 123.363228 -53.923184)
		(end 122.791728 -53.923184)
		(width 0.10795)
		(layer "F.Cu")
		(net "TP_CPU1_RSVD_278")
	)
	(via
		(at 122.791728 -53.923184)
		(size 0.4826)
		(drill 0.254)
		(layers "F.Cu" "B.Cu")
		(net "TP_CPU1_RSVD_278")
	)
	(segment
		(start 122.504708 -53.427884)
		(end 121.933208 -53.427884)
		(width 0.10795)
		(layer "F.Cu")
		(net "TP_CPU1_RSVD_281")
	)
	(via
		(at 121.933208 -53.427884)
		(size 0.4826)
		(drill 0.254)
		(layers "F.Cu" "B.Cu")
		(net "TP_CPU1_RSVD_281")
	)
	(segment
		(start 287.79216 -53.923184)
		(end 288.36366 -53.923184)
		(width 0.10795)
		(layer "F.Cu")
		(net "TP_CPU0_RSVD_278")
	)
	(via
		(at 287.79216 -53.923184)
		(size 0.508)
		(drill 0.254)
		(layers "F.Cu" "B.Cu")
		(net "TP_CPU0_RSVD_278")
	)
	(segment
		(start 287.50514 -53.427884)
		(end 286.93364 -53.427884)
		(width 0.10795)
		(layer "F.Cu")
		(net "TP_CPU0_RSVD_281")
	)
	(via
		(at 286.93364 -53.427884)
		(size 0.508)
		(drill 0.254)
		(layers "F.Cu" "B.Cu")
		(net "TP_CPU0_RSVD_281")
	)
	(segment
		(start 422.29024 -40.13454)
		(end 421.89019 -40.53459)
		(width 0.089408)
		(layer "F.Cu")
		(net "FM_BMC_HEARTBEAT_N")
	)
	(segment
		(start 457.83119 -33.340294)
		(end 457.83119 -34.680906)
		(width 0.10795)
		(layer "F.Cu")
		(net "FM_BMC_HEARTBEAT_N")
	)
	(segment
		(start 458.091286 -33.080198)
		(end 457.83119 -33.340294)
		(width 0.10795)
		(layer "F.Cu")
		(net "FM_BMC_HEARTBEAT_N")
	)
	(segment
		(start 456.934062 -34.036)
		(end 457.578968 -34.680906)
		(width 0.10795)
		(layer "F.Cu")
		(net "FM_BMC_HEARTBEAT_N")
	)
	(segment
		(start 401.295108 -114.85499)
		(end 402.134832 -114.85499)
		(width 0.10795)
		(layer "F.Cu")
		(net "FM_BMC_HEARTBEAT_N")
	)
	(segment
		(start 456.05573 -34.744406)
		(end 456.05573 -34.164524)
		(width 0.10795)
		(layer "F.Cu")
		(net "FM_BMC_HEARTBEAT_N")
	)
	(segment
		(start 457.578968 -34.680906)
		(end 457.83119 -34.680906)
		(width 0.10795)
		(layer "F.Cu")
		(net "FM_BMC_HEARTBEAT_N")
	)
	(segment
		(start 458.091286 -32.639)
		(end 458.091286 -33.080198)
		(width 0.10795)
		(layer "F.Cu")
		(net "FM_BMC_HEARTBEAT_N")
	)
	(segment
		(start 456.05573 -34.164524)
		(end 456.184254 -34.036)
		(width 0.10795)
		(layer "F.Cu")
		(net "FM_BMC_HEARTBEAT_N")
	)
	(segment
		(start 456.184254 -34.036)
		(end 456.934062 -34.036)
		(width 0.10795)
		(layer "F.Cu")
		(net "FM_BMC_HEARTBEAT_N")
	)
	(via
		(at 464.92541 -49.928018)
		(size 0.508)
		(drill 0.254)
		(layers "F.Cu" "B.Cu")
		(net "FM_BMC_HEARTBEAT_N")
	)
	(via
		(at 402.134832 -114.85499)
		(size 0.508)
		(drill 0.254)
		(layers "F.Cu" "B.Cu")
		(net "FM_BMC_HEARTBEAT_N")
	)
	(via
		(at 421.89019 -40.53459)
		(size 0.4572)
		(drill 0.2032)
		(layers "F.Cu" "B.Cu")
		(net "FM_BMC_HEARTBEAT_N")
	)
	(via
		(at 412.8516 -83.227418)
		(size 0.508)
		(drill 0.254)
		(layers "F.Cu" "B.Cu")
		(net "FM_BMC_HEARTBEAT_N")
	)
	(via
		(at 458.091286 -32.639)
		(size 0.508)
		(drill 0.254)
		(layers "F.Cu" "B.Cu")
		(net "FM_BMC_HEARTBEAT_N")
	)
	(via
		(at 473.3671 -48.1965)
		(size 0.508)
		(drill 0.254)
		(layers "F.Cu" "B.Cu")
		(net "FM_BMC_HEARTBEAT_N")
	)
	(via
		(at 414.090104 -114.177318)
		(size 0.508)
		(drill 0.254)
		(layers "F.Cu" "B.Cu")
		(net "FM_BMC_HEARTBEAT_N")
	)
	(segment
		(start 413.5882 -109.067854)
		(end 412.821374 -108.301028)
		(width 0.089408)
		(layer "In2.Cu")
		(net "FM_BMC_HEARTBEAT_N")
	)
	(segment
		(start 469.185498 -49.57064)
		(end 467.82736 -49.57064)
		(width 0.089408)
		(layer "In2.Cu")
		(net "FM_BMC_HEARTBEAT_N")
	)
	(segment
		(start 411.174184 -84.770468)
		(end 412.00578 -84.770468)
		(width 0.089408)
		(layer "In2.Cu")
		(net "FM_BMC_HEARTBEAT_N")
	)
	(segment
		(start 467.82736 -49.57064)
		(end 467.469982 -49.928018)
		(width 0.089408)
		(layer "In2.Cu")
		(net "FM_BMC_HEARTBEAT_N")
	)
	(segment
		(start 412.821374 -100.477574)
		(end 411.230064 -98.886264)
		(width 0.089408)
		(layer "In2.Cu")
		(net "FM_BMC_HEARTBEAT_N")
	)
	(segment
		(start 410.86024 -86.847172)
		(end 410.860494 -86.846918)
		(width 0.089408)
		(layer "In2.Cu")
		(net "FM_BMC_HEARTBEAT_N")
	)
	(segment
		(start 411.230064 -97.625408)
		(end 411.1752 -97.570544)
		(width 0.089408)
		(layer "In2.Cu")
		(net "FM_BMC_HEARTBEAT_N")
	)
	(segment
		(start 412.821374 -108.301028)
		(end 412.821374 -100.477574)
		(width 0.089408)
		(layer "In2.Cu")
		(net "FM_BMC_HEARTBEAT_N")
	)
	(segment
		(start 411.877002 -88.021922)
		(end 410.86024 -87.00516)
		(width 0.089408)
		(layer "In2.Cu")
		(net "FM_BMC_HEARTBEAT_N")
	)
	(segment
		(start 410.86024 -87.00516)
		(end 410.86024 -86.847172)
		(width 0.089408)
		(layer "In2.Cu")
		(net "FM_BMC_HEARTBEAT_N")
	)
	(segment
		(start 412.00578 -84.770468)
		(end 412.8516 -83.924648)
		(width 0.089408)
		(layer "In2.Cu")
		(net "FM_BMC_HEARTBEAT_N")
	)
	(segment
		(start 414.090104 -114.177318)
		(end 413.5882 -113.675414)
		(width 0.089408)
		(layer "In2.Cu")
		(net "FM_BMC_HEARTBEAT_N")
	)
	(segment
		(start 473.3671 -48.923194)
		(end 471.565986 -50.724308)
		(width 0.089408)
		(layer "In2.Cu")
		(net "FM_BMC_HEARTBEAT_N")
	)
	(segment
		(start 471.565986 -50.724308)
		(end 470.339166 -50.724308)
		(width 0.089408)
		(layer "In2.Cu")
		(net "FM_BMC_HEARTBEAT_N")
	)
	(segment
		(start 473.3671 -48.1965)
		(end 473.3671 -48.923194)
		(width 0.089408)
		(layer "In2.Cu")
		(net "FM_BMC_HEARTBEAT_N")
	)
	(segment
		(start 411.230064 -98.886264)
		(end 411.230064 -97.625408)
		(width 0.089408)
		(layer "In2.Cu")
		(net "FM_BMC_HEARTBEAT_N")
	)
	(segment
		(start 412.8516 -83.924648)
		(end 412.8516 -83.227418)
		(width 0.089408)
		(layer "In2.Cu")
		(net "FM_BMC_HEARTBEAT_N")
	)
	(segment
		(start 411.1752 -90.643202)
		(end 411.877002 -89.9414)
		(width 0.089408)
		(layer "In2.Cu")
		(net "FM_BMC_HEARTBEAT_N")
	)
	(segment
		(start 410.860494 -86.846918)
		(end 410.860494 -85.084158)
		(width 0.089408)
		(layer "In2.Cu")
		(net "FM_BMC_HEARTBEAT_N")
	)
	(segment
		(start 410.860494 -85.084158)
		(end 411.174184 -84.770468)
		(width 0.089408)
		(layer "In2.Cu")
		(net "FM_BMC_HEARTBEAT_N")
	)
	(segment
		(start 470.339166 -50.724308)
		(end 469.185498 -49.57064)
		(width 0.089408)
		(layer "In2.Cu")
		(net "FM_BMC_HEARTBEAT_N")
	)
	(segment
		(start 467.469982 -49.928018)
		(end 464.92541 -49.928018)
		(width 0.089408)
		(layer "In2.Cu")
		(net "FM_BMC_HEARTBEAT_N")
	)
	(segment
		(start 411.877002 -89.9414)
		(end 411.877002 -88.021922)
		(width 0.089408)
		(layer "In2.Cu")
		(net "FM_BMC_HEARTBEAT_N")
	)
	(segment
		(start 411.1752 -97.570544)
		(end 411.1752 -90.643202)
		(width 0.089408)
		(layer "In2.Cu")
		(net "FM_BMC_HEARTBEAT_N")
	)
	(segment
		(start 413.5882 -113.675414)
		(end 413.5882 -109.067854)
		(width 0.089408)
		(layer "In2.Cu")
		(net "FM_BMC_HEARTBEAT_N")
	)
	(segment
		(start 418.402262 -55.768494)
		(end 415.29254 -58.878216)
		(width 0.089408)
		(layer "In9.Cu")
		(net "FM_BMC_HEARTBEAT_N")
	)
	(segment
		(start 412.8516 -79.973424)
		(end 412.8516 -83.227418)
		(width 0.089408)
		(layer "In9.Cu")
		(net "FM_BMC_HEARTBEAT_N")
	)
	(segment
		(start 464.92541 -49.928018)
		(end 464.92541 -49.337722)
		(width 0.089408)
		(layer "In9.Cu")
		(net "FM_BMC_HEARTBEAT_N")
	)
	(segment
		(start 414.750504 -68.180458)
		(end 414.750504 -71.638922)
		(width 0.089408)
		(layer "In9.Cu")
		(net "FM_BMC_HEARTBEAT_N")
	)
	(segment
		(start 415.43732 -60.226956)
		(end 415.43732 -61.794136)
		(width 0.089408)
		(layer "In9.Cu")
		(net "FM_BMC_HEARTBEAT_N")
	)
	(segment
		(start 413.984186 -114.0714)
		(end 411.378654 -114.0714)
		(width 0.089408)
		(layer "In9.Cu")
		(net "FM_BMC_HEARTBEAT_N")
	)
	(segment
		(start 428.651924 -41.895268)
		(end 429.632618 -41.895268)
		(width 0.089408)
		(layer "In9.Cu")
		(net "FM_BMC_HEARTBEAT_N")
	)
	(segment
		(start 414.750504 -71.638922)
		(end 414.144206 -72.24522)
		(width 0.089408)
		(layer "In9.Cu")
		(net "FM_BMC_HEARTBEAT_N")
	)
	(segment
		(start 425.034964 -45.10151)
		(end 425.366688 -45.10151)
		(width 0.089408)
		(layer "In9.Cu")
		(net "FM_BMC_HEARTBEAT_N")
	)
	(segment
		(start 426.744892 -43.8023)
		(end 428.651924 -41.895268)
		(width 0.089408)
		(layer "In9.Cu")
		(net "FM_BMC_HEARTBEAT_N")
	)
	(segment
		(start 414.144206 -72.24522)
		(end 414.144206 -78.679802)
		(width 0.089408)
		(layer "In9.Cu")
		(net "FM_BMC_HEARTBEAT_N")
	)
	(segment
		(start 425.381166 -45.087032)
		(end 425.46016 -45.087032)
		(width 0.089408)
		(layer "In9.Cu")
		(net "FM_BMC_HEARTBEAT_N")
	)
	(segment
		(start 415.29254 -63.852044)
		(end 415.087054 -64.05753)
		(width 0.089408)
		(layer "In9.Cu")
		(net "FM_BMC_HEARTBEAT_N")
	)
	(segment
		(start 424.1038 -44.573444)
		(end 424.617388 -45.087032)
		(width 0.089408)
		(layer "In9.Cu")
		(net "FM_BMC_HEARTBEAT_N")
	)
	(segment
		(start 425.46016 -45.087032)
		(end 426.171614 -44.375578)
		(width 0.089408)
		(layer "In9.Cu")
		(net "FM_BMC_HEARTBEAT_N")
	)
	(segment
		(start 422.162478 -40.77843)
		(end 422.707054 -41.323006)
		(width 0.089408)
		(layer "In9.Cu")
		(net "FM_BMC_HEARTBEAT_N")
	)
	(segment
		(start 422.13403 -40.77843)
		(end 422.162478 -40.77843)
		(width 0.089408)
		(layer "In9.Cu")
		(net "FM_BMC_HEARTBEAT_N")
	)
	(segment
		(start 406.9207 -115.9383)
		(end 406.5524 -116.3066)
		(width 0.089408)
		(layer "In9.Cu")
		(net "FM_BMC_HEARTBEAT_N")
	)
	(segment
		(start 415.29254 -58.878216)
		(end 415.29254 -60.082176)
		(width 0.089408)
		(layer "In9.Cu")
		(net "FM_BMC_HEARTBEAT_N")
	)
	(segment
		(start 409.511754 -115.9383)
		(end 406.9207 -115.9383)
		(width 0.089408)
		(layer "In9.Cu")
		(net "FM_BMC_HEARTBEAT_N")
	)
	(segment
		(start 435.953662 -52.096924)
		(end 435.916324 -52.096924)
		(width 0.089408)
		(layer "In9.Cu")
		(net "FM_BMC_HEARTBEAT_N")
	)
	(segment
		(start 415.087054 -64.05753)
		(end 415.087054 -67.843908)
		(width 0.089408)
		(layer "In9.Cu")
		(net "FM_BMC_HEARTBEAT_N")
	)
	(segment
		(start 439.20537 -48.845216)
		(end 435.953662 -52.096924)
		(width 0.089408)
		(layer "In9.Cu")
		(net "FM_BMC_HEARTBEAT_N")
	)
	(segment
		(start 426.171614 -44.375578)
		(end 426.171614 -44.34205)
		(width 0.089408)
		(layer "In9.Cu")
		(net "FM_BMC_HEARTBEAT_N")
	)
	(segment
		(start 426.711364 -43.8023)
		(end 426.744892 -43.8023)
		(width 0.089408)
		(layer "In9.Cu")
		(net "FM_BMC_HEARTBEAT_N")
	)
	(segment
		(start 423.705274 -55.000398)
		(end 420.864284 -55.000398)
		(width 0.089408)
		(layer "In9.Cu")
		(net "FM_BMC_HEARTBEAT_N")
	)
	(segment
		(start 434.925978 -40.944546)
		(end 449.071238 -40.944546)
		(width 0.089408)
		(layer "In9.Cu")
		(net "FM_BMC_HEARTBEAT_N")
	)
	(segment
		(start 449.071238 -40.944546)
		(end 450.034914 -39.98087)
		(width 0.089408)
		(layer "In9.Cu")
		(net "FM_BMC_HEARTBEAT_N")
	)
	(segment
		(start 422.707054 -41.323006)
		(end 422.707054 -41.351454)
		(width 0.089408)
		(layer "In9.Cu")
		(net "FM_BMC_HEARTBEAT_N")
	)
	(segment
		(start 424.724068 -53.981604)
		(end 423.705274 -55.000398)
		(width 0.089408)
		(layer "In9.Cu")
		(net "FM_BMC_HEARTBEAT_N")
	)
	(segment
		(start 464.92541 -49.337722)
		(end 464.432904 -48.845216)
		(width 0.089408)
		(layer "In9.Cu")
		(net "FM_BMC_HEARTBEAT_N")
	)
	(segment
		(start 426.51045 -44.031662)
		(end 426.51045 -44.003214)
		(width 0.089408)
		(layer "In9.Cu")
		(net "FM_BMC_HEARTBEAT_N")
	)
	(segment
		(start 425.366688 -45.10151)
		(end 425.381166 -45.087032)
		(width 0.089408)
		(layer "In9.Cu")
		(net "FM_BMC_HEARTBEAT_N")
	)
	(segment
		(start 464.432904 -48.845216)
		(end 439.20537 -48.845216)
		(width 0.089408)
		(layer "In9.Cu")
		(net "FM_BMC_HEARTBEAT_N")
	)
	(segment
		(start 415.43732 -61.794136)
		(end 415.29254 -61.938916)
		(width 0.089408)
		(layer "In9.Cu")
		(net "FM_BMC_HEARTBEAT_N")
	)
	(segment
		(start 450.034914 -38.682168)
		(end 456.078082 -32.639)
		(width 0.089408)
		(layer "In9.Cu")
		(net "FM_BMC_HEARTBEAT_N")
	)
	(segment
		(start 425.020486 -45.087032)
		(end 425.034964 -45.10151)
		(width 0.089408)
		(layer "In9.Cu")
		(net "FM_BMC_HEARTBEAT_N")
	)
	(segment
		(start 420.864284 -55.000398)
		(end 420.096188 -55.768494)
		(width 0.089408)
		(layer "In9.Cu")
		(net "FM_BMC_HEARTBEAT_N")
	)
	(segment
		(start 413.479996 -79.344012)
		(end 413.479996 -79.345028)
		(width 0.089408)
		(layer "In9.Cu")
		(net "FM_BMC_HEARTBEAT_N")
	)
	(segment
		(start 415.087054 -67.843908)
		(end 414.750504 -68.180458)
		(width 0.089408)
		(layer "In9.Cu")
		(net "FM_BMC_HEARTBEAT_N")
	)
	(segment
		(start 426.51045 -44.003214)
		(end 426.711364 -43.8023)
		(width 0.089408)
		(layer "In9.Cu")
		(net "FM_BMC_HEARTBEAT_N")
	)
	(segment
		(start 411.378654 -114.0714)
		(end 409.511754 -115.9383)
		(width 0.089408)
		(layer "In9.Cu")
		(net "FM_BMC_HEARTBEAT_N")
	)
	(segment
		(start 450.034914 -39.98087)
		(end 450.034914 -38.682168)
		(width 0.089408)
		(layer "In9.Cu")
		(net "FM_BMC_HEARTBEAT_N")
	)
	(segment
		(start 422.707054 -41.351454)
		(end 424.1038 -42.7482)
		(width 0.089408)
		(layer "In9.Cu")
		(net "FM_BMC_HEARTBEAT_N")
	)
	(segment
		(start 421.89019 -40.53459)
		(end 422.13403 -40.77843)
		(width 0.089408)
		(layer "In9.Cu")
		(net "FM_BMC_HEARTBEAT_N")
	)
	(segment
		(start 426.276262 -44.26585)
		(end 426.51045 -44.031662)
		(width 0.089408)
		(layer "In9.Cu")
		(net "FM_BMC_HEARTBEAT_N")
	)
	(segment
		(start 431.089308 -41.428162)
		(end 434.442362 -41.428162)
		(width 0.089408)
		(layer "In9.Cu")
		(net "FM_BMC_HEARTBEAT_N")
	)
	(segment
		(start 427.828202 -52.150518)
		(end 425.997116 -53.981604)
		(width 0.089408)
		(layer "In9.Cu")
		(net "FM_BMC_HEARTBEAT_N")
	)
	(segment
		(start 420.096188 -55.768494)
		(end 418.402262 -55.768494)
		(width 0.089408)
		(layer "In9.Cu")
		(net "FM_BMC_HEARTBEAT_N")
	)
	(segment
		(start 403.417532 -115.539266)
		(end 402.819108 -115.539266)
		(width 0.089408)
		(layer "In9.Cu")
		(net "FM_BMC_HEARTBEAT_N")
	)
	(segment
		(start 435.916324 -52.096924)
		(end 435.86273 -52.150518)
		(width 0.089408)
		(layer "In9.Cu")
		(net "FM_BMC_HEARTBEAT_N")
	)
	(segment
		(start 435.86273 -52.150518)
		(end 427.828202 -52.150518)
		(width 0.089408)
		(layer "In9.Cu")
		(net "FM_BMC_HEARTBEAT_N")
	)
	(segment
		(start 424.617388 -45.087032)
		(end 425.020486 -45.087032)
		(width 0.089408)
		(layer "In9.Cu")
		(net "FM_BMC_HEARTBEAT_N")
	)
	(segment
		(start 434.442362 -41.428162)
		(end 434.925978 -40.944546)
		(width 0.089408)
		(layer "In9.Cu")
		(net "FM_BMC_HEARTBEAT_N")
	)
	(segment
		(start 414.144206 -78.679802)
		(end 413.479996 -79.344012)
		(width 0.089408)
		(layer "In9.Cu")
		(net "FM_BMC_HEARTBEAT_N")
	)
	(segment
		(start 402.819108 -115.539266)
		(end 402.134832 -114.85499)
		(width 0.089408)
		(layer "In9.Cu")
		(net "FM_BMC_HEARTBEAT_N")
	)
	(segment
		(start 429.632618 -41.895268)
		(end 430.185322 -41.342564)
		(width 0.089408)
		(layer "In9.Cu")
		(net "FM_BMC_HEARTBEAT_N")
	)
	(segment
		(start 406.5524 -116.3066)
		(end 404.184866 -116.3066)
		(width 0.089408)
		(layer "In9.Cu")
		(net "FM_BMC_HEARTBEAT_N")
	)
	(segment
		(start 430.185322 -41.342564)
		(end 431.00371 -41.342564)
		(width 0.089408)
		(layer "In9.Cu")
		(net "FM_BMC_HEARTBEAT_N")
	)
	(segment
		(start 413.479996 -79.345028)
		(end 412.8516 -79.973424)
		(width 0.089408)
		(layer "In9.Cu")
		(net "FM_BMC_HEARTBEAT_N")
	)
	(segment
		(start 424.1038 -42.7482)
		(end 424.1038 -44.573444)
		(width 0.089408)
		(layer "In9.Cu")
		(net "FM_BMC_HEARTBEAT_N")
	)
	(segment
		(start 415.29254 -60.082176)
		(end 415.43732 -60.226956)
		(width 0.089408)
		(layer "In9.Cu")
		(net "FM_BMC_HEARTBEAT_N")
	)
	(segment
		(start 425.997116 -53.981604)
		(end 424.724068 -53.981604)
		(width 0.089408)
		(layer "In9.Cu")
		(net "FM_BMC_HEARTBEAT_N")
	)
	(segment
		(start 426.171614 -44.34205)
		(end 426.247814 -44.26585)
		(width 0.089408)
		(layer "In9.Cu")
		(net "FM_BMC_HEARTBEAT_N")
	)
	(segment
		(start 404.184866 -116.3066)
		(end 403.417532 -115.539266)
		(width 0.089408)
		(layer "In9.Cu")
		(net "FM_BMC_HEARTBEAT_N")
	)
	(segment
		(start 415.29254 -61.938916)
		(end 415.29254 -63.852044)
		(width 0.089408)
		(layer "In9.Cu")
		(net "FM_BMC_HEARTBEAT_N")
	)
	(segment
		(start 426.247814 -44.26585)
		(end 426.276262 -44.26585)
		(width 0.089408)
		(layer "In9.Cu")
		(net "FM_BMC_HEARTBEAT_N")
	)
	(segment
		(start 456.078082 -32.639)
		(end 458.091286 -32.639)
		(width 0.089408)
		(layer "In9.Cu")
		(net "FM_BMC_HEARTBEAT_N")
	)
	(segment
		(start 414.090104 -114.177318)
		(end 413.984186 -114.0714)
		(width 0.089408)
		(layer "In9.Cu")
		(net "FM_BMC_HEARTBEAT_N")
	)
	(segment
		(start 431.00371 -41.342564)
		(end 431.089308 -41.428162)
		(width 0.089408)
		(layer "In9.Cu")
		(net "FM_BMC_HEARTBEAT_N")
	)
	(segment
		(start 470.94521 -39.175944)
		(end 472.339162 -37.781992)
		(width 0.089408)
		(layer "In11.Cu")
		(net "FM_BMC_HEARTBEAT_N")
	)
	(segment
		(start 472.510104 -46.827948)
		(end 472.355418 -46.673262)
		(width 0.089408)
		(layer "In11.Cu")
		(net "FM_BMC_HEARTBEAT_N")
	)
	(segment
		(start 469.892634 -39.175944)
		(end 470.94521 -39.175944)
		(width 0.089408)
		(layer "In11.Cu")
		(net "FM_BMC_HEARTBEAT_N")
	)
	(segment
		(start 471.686382 -33.492694)
		(end 471.686382 -33.487106)
		(width 0.089408)
		(layer "In11.Cu")
		(net "FM_BMC_HEARTBEAT_N")
	)
	(segment
		(start 469.502744 -39.565834)
		(end 469.892634 -39.175944)
		(width 0.089408)
		(layer "In11.Cu")
		(net "FM_BMC_HEARTBEAT_N")
	)
	(segment
		(start 470.67089 -45.34789)
		(end 468.376 -43.053)
		(width 0.089408)
		(layer "In11.Cu")
		(net "FM_BMC_HEARTBEAT_N")
	)
	(segment
		(start 471.75166 -34.292794)
		(end 471.75166 -33.557972)
		(width 0.089408)
		(layer "In11.Cu")
		(net "FM_BMC_HEARTBEAT_N")
	)
	(segment
		(start 471.75166 -33.557972)
		(end 471.686382 -33.492694)
		(width 0.089408)
		(layer "In11.Cu")
		(net "FM_BMC_HEARTBEAT_N")
	)
	(segment
		(start 472.339162 -34.880296)
		(end 471.75166 -34.292794)
		(width 0.089408)
		(layer "In11.Cu")
		(net "FM_BMC_HEARTBEAT_N")
	)
	(segment
		(start 471.282776 -32.950404)
		(end 471.18778 -32.855408)
		(width 0.089408)
		(layer "In11.Cu")
		(net "FM_BMC_HEARTBEAT_N")
	)
	(segment
		(start 473.3671 -47.858426)
		(end 472.510104 -47.00143)
		(width 0.089408)
		(layer "In11.Cu")
		(net "FM_BMC_HEARTBEAT_N")
	)
	(segment
		(start 473.3671 -48.1965)
		(end 473.3671 -47.858426)
		(width 0.089408)
		(layer "In11.Cu")
		(net "FM_BMC_HEARTBEAT_N")
	)
	(segment
		(start 472.510104 -47.00143)
		(end 472.510104 -46.827948)
		(width 0.089408)
		(layer "In11.Cu")
		(net "FM_BMC_HEARTBEAT_N")
	)
	(segment
		(start 469.502744 -40.456612)
		(end 469.502744 -39.565834)
		(width 0.089408)
		(layer "In11.Cu")
		(net "FM_BMC_HEARTBEAT_N")
	)
	(segment
		(start 472.355418 -46.341538)
		(end 472.510104 -46.186852)
		(width 0.089408)
		(layer "In11.Cu")
		(net "FM_BMC_HEARTBEAT_N")
	)
	(segment
		(start 472.510104 -45.64507)
		(end 472.212924 -45.34789)
		(width 0.089408)
		(layer "In11.Cu")
		(net "FM_BMC_HEARTBEAT_N")
	)
	(segment
		(start 471.18778 -32.855408)
		(end 470.369392 -32.855408)
		(width 0.089408)
		(layer "In11.Cu")
		(net "FM_BMC_HEARTBEAT_N")
	)
	(segment
		(start 470.369392 -32.855408)
		(end 470.1794 -33.0454)
		(width 0.089408)
		(layer "In11.Cu")
		(net "FM_BMC_HEARTBEAT_N")
	)
	(segment
		(start 471.686382 -33.487106)
		(end 471.522806 -33.32353)
		(width 0.089408)
		(layer "In11.Cu")
		(net "FM_BMC_HEARTBEAT_N")
	)
	(segment
		(start 458.497686 -33.0454)
		(end 458.091286 -32.639)
		(width 0.089408)
		(layer "In11.Cu")
		(net "FM_BMC_HEARTBEAT_N")
	)
	(segment
		(start 472.212924 -45.34789)
		(end 470.67089 -45.34789)
		(width 0.089408)
		(layer "In11.Cu")
		(net "FM_BMC_HEARTBEAT_N")
	)
	(segment
		(start 468.376 -43.053)
		(end 468.376 -41.583356)
		(width 0.089408)
		(layer "In11.Cu")
		(net "FM_BMC_HEARTBEAT_N")
	)
	(segment
		(start 468.376 -41.583356)
		(end 469.502744 -40.456612)
		(width 0.089408)
		(layer "In11.Cu")
		(net "FM_BMC_HEARTBEAT_N")
	)
	(segment
		(start 471.522806 -33.32353)
		(end 471.517218 -33.32353)
		(width 0.089408)
		(layer "In11.Cu")
		(net "FM_BMC_HEARTBEAT_N")
	)
	(segment
		(start 470.1794 -33.0454)
		(end 458.497686 -33.0454)
		(width 0.089408)
		(layer "In11.Cu")
		(net "FM_BMC_HEARTBEAT_N")
	)
	(segment
		(start 472.355418 -46.673262)
		(end 472.355418 -46.341538)
		(width 0.089408)
		(layer "In11.Cu")
		(net "FM_BMC_HEARTBEAT_N")
	)
	(segment
		(start 472.510104 -46.186852)
		(end 472.510104 -45.64507)
		(width 0.089408)
		(layer "In11.Cu")
		(net "FM_BMC_HEARTBEAT_N")
	)
	(segment
		(start 471.517218 -33.32353)
		(end 471.282776 -33.089088)
		(width 0.089408)
		(layer "In11.Cu")
		(net "FM_BMC_HEARTBEAT_N")
	)
	(segment
		(start 472.339162 -37.781992)
		(end 472.339162 -34.880296)
		(width 0.089408)
		(layer "In11.Cu")
		(net "FM_BMC_HEARTBEAT_N")
	)
	(segment
		(start 471.282776 -33.089088)
		(end 471.282776 -32.950404)
		(width 0.089408)
		(layer "In11.Cu")
		(net "FM_BMC_HEARTBEAT_N")
	)
	(segment
		(start 283.212794 -87.812118)
		(end 282.925774 -88.099138)
		(width 0.254)
		(layer "F.Cu")
		(net "A_CPU0_PE3_RBIAS")
	)
	(segment
		(start 282.925774 -88.099138)
		(end 282.354274 -88.099138)
		(width 0.254)
		(layer "F.Cu")
		(net "A_CPU0_PE3_RBIAS")
	)
	(segment
		(start 283.212794 -87.603584)
		(end 283.212794 -87.812118)
		(width 0.254)
		(layer "F.Cu")
		(net "A_CPU0_PE3_RBIAS")
	)
	(via
		(at 282.4226 -84.886546)
		(size 0.6604)
		(drill 0.3302)
		(layers "F.Cu" "B.Cu")
		(net "A_CPU0_PE3_RBIAS")
	)
	(via
		(at 282.925774 -88.099138)
		(size 0.508)
		(drill 0.254)
		(layers "F.Cu" "B.Cu")
		(net "A_CPU0_PE3_RBIAS")
	)
	(segment
		(start 282.4226 -87.270844)
		(end 282.925774 -87.774018)
		(width 0.2032)
		(layer "B.Cu")
		(net "A_CPU0_PE3_RBIAS")
	)
	(segment
		(start 284.5054 -78.1558)
		(end 284.8991 -78.5495)
		(width 0.2032)
		(layer "B.Cu")
		(net "A_CPU0_PE3_RBIAS")
	)
	(segment
		(start 283.972 -78.1558)
		(end 284.5054 -78.1558)
		(width 0.2032)
		(layer "B.Cu")
		(net "A_CPU0_PE3_RBIAS")
	)
	(segment
		(start 284.8991 -78.5495)
		(end 284.8991 -81.953354)
		(width 0.2032)
		(layer "B.Cu")
		(net "A_CPU0_PE3_RBIAS")
	)
	(segment
		(start 283.2354 -78.8924)
		(end 283.972 -78.1558)
		(width 0.2032)
		(layer "B.Cu")
		(net "A_CPU0_PE3_RBIAS")
	)
	(segment
		(start 282.35021 -78.8924)
		(end 283.2354 -78.8924)
		(width 0.2032)
		(layer "B.Cu")
		(net "A_CPU0_PE3_RBIAS")
	)
	(segment
		(start 282.4226 -84.429854)
		(end 282.4226 -84.886546)
		(width 0.2032)
		(layer "B.Cu")
		(net "A_CPU0_PE3_RBIAS")
	)
	(segment
		(start 284.8991 -81.953354)
		(end 282.4226 -84.429854)
		(width 0.2032)
		(layer "B.Cu")
		(net "A_CPU0_PE3_RBIAS")
	)
	(segment
		(start 282.4226 -84.886546)
		(end 282.4226 -87.270844)
		(width 0.2032)
		(layer "B.Cu")
		(net "A_CPU0_PE3_RBIAS")
	)
	(segment
		(start 282.925774 -87.774018)
		(end 282.925774 -88.099138)
		(width 0.2032)
		(layer "B.Cu")
		(net "A_CPU0_PE3_RBIAS")
	)
	(segment
		(start 282.259024 -78.801214)
		(end 282.35021 -78.8924)
		(width 0.2032)
		(layer "B.Cu")
		(net "A_CPU0_PE3_RBIAS")
	)
	(segment
		(start 282.354274 -86.117938)
		(end 282.354274 -87.108538)
		(width 0.254)
		(layer "F.Cu")
		(net "A_CPU0_PE012_RBIAS")
	)
	(segment
		(start 282.354274 -87.108538)
		(end 282.925774 -87.108538)
		(width 0.254)
		(layer "F.Cu")
		(net "A_CPU0_PE012_RBIAS")
	)
	(via
		(at 282.925774 -87.108538)
		(size 0.508)
		(drill 0.254)
		(layers "F.Cu" "B.Cu")
		(net "A_CPU0_PE012_RBIAS")
	)
	(segment
		(start 285.226252 -82.092292)
		(end 283.041598 -84.276946)
		(width 0.2032)
		(layer "B.Cu")
		(net "A_CPU0_PE012_RBIAS")
	)
	(segment
		(start 284.1244 -77.2414)
		(end 284.8864 -77.2414)
		(width 0.2032)
		(layer "B.Cu")
		(net "A_CPU0_PE012_RBIAS")
	)
	(segment
		(start 282.625038 -77.6732)
		(end 283.6926 -77.6732)
		(width 0.2032)
		(layer "B.Cu")
		(net "A_CPU0_PE012_RBIAS")
	)
	(segment
		(start 282.259024 -78.039214)
		(end 282.625038 -77.6732)
		(width 0.2032)
		(layer "B.Cu")
		(net "A_CPU0_PE012_RBIAS")
	)
	(segment
		(start 283.041598 -86.992714)
		(end 282.925774 -87.108538)
		(width 0.2032)
		(layer "B.Cu")
		(net "A_CPU0_PE012_RBIAS")
	)
	(segment
		(start 284.8864 -77.2414)
		(end 285.226252 -77.581252)
		(width 0.2032)
		(layer "B.Cu")
		(net "A_CPU0_PE012_RBIAS")
	)
	(segment
		(start 283.6926 -77.6732)
		(end 284.1244 -77.2414)
		(width 0.2032)
		(layer "B.Cu")
		(net "A_CPU0_PE012_RBIAS")
	)
	(segment
		(start 285.226252 -77.581252)
		(end 285.226252 -82.092292)
		(width 0.2032)
		(layer "B.Cu")
		(net "A_CPU0_PE012_RBIAS")
	)
	(segment
		(start 283.041598 -84.276946)
		(end 283.041598 -86.992714)
		(width 0.2032)
		(layer "B.Cu")
		(net "A_CPU0_PE012_RBIAS")
	)
	(segment
		(start 281.495754 -88.802718)
		(end 281.495754 -88.594184)
		(width 0.254)
		(layer "F.Cu")
		(net "A_CPU0_MCP01_RBIAS")
	)
	(segment
		(start 281.208734 -89.089738)
		(end 281.495754 -88.802718)
		(width 0.254)
		(layer "F.Cu")
		(net "A_CPU0_MCP01_RBIAS")
	)
	(segment
		(start 280.637234 -89.089738)
		(end 281.208734 -89.089738)
		(width 0.254)
		(layer "F.Cu")
		(net "A_CPU0_MCP01_RBIAS")
	)
	(segment
		(start 280.8986 -84.836)
		(end 279.908 -83.8454)
		(width 0.2032)
		(layer "F.Cu")
		(net "A_CPU0_MCP01_RBIAS")
	)
	(segment
		(start 279.908 -83.8454)
		(end 278.13 -83.8454)
		(width 0.2032)
		(layer "F.Cu")
		(net "A_CPU0_MCP01_RBIAS")
	)
	(via
		(at 280.8986 -84.836)
		(size 0.508)
		(drill 0.254)
		(layers "F.Cu" "B.Cu")
		(net "A_CPU0_MCP01_RBIAS")
	)
	(via
		(at 281.208734 -89.089738)
		(size 0.508)
		(drill 0.254)
		(layers "F.Cu" "B.Cu")
		(net "A_CPU0_MCP01_RBIAS")
	)
	(segment
		(start 281.208734 -89.089738)
		(end 281.66441 -88.634062)
		(width 0.2032)
		(layer "B.Cu")
		(net "A_CPU0_MCP01_RBIAS")
	)
	(segment
		(start 281.9654 -86.334346)
		(end 281.9654 -85.598)
		(width 0.2032)
		(layer "B.Cu")
		(net "A_CPU0_MCP01_RBIAS")
	)
	(segment
		(start 281.5082 -86.791546)
		(end 281.9654 -86.334346)
		(width 0.2032)
		(layer "B.Cu")
		(net "A_CPU0_MCP01_RBIAS")
	)
	(segment
		(start 281.5082 -87.7316)
		(end 281.5082 -86.791546)
		(width 0.2032)
		(layer "B.Cu")
		(net "A_CPU0_MCP01_RBIAS")
	)
	(segment
		(start 281.66441 -87.88781)
		(end 281.5082 -87.7316)
		(width 0.2032)
		(layer "B.Cu")
		(net "A_CPU0_MCP01_RBIAS")
	)
	(segment
		(start 281.9654 -85.598)
		(end 281.2034 -84.836)
		(width 0.2032)
		(layer "B.Cu")
		(net "A_CPU0_MCP01_RBIAS")
	)
	(segment
		(start 281.2034 -84.836)
		(end 280.8986 -84.836)
		(width 0.2032)
		(layer "B.Cu")
		(net "A_CPU0_MCP01_RBIAS")
	)
	(segment
		(start 281.66441 -88.634062)
		(end 281.66441 -87.88781)
		(width 0.2032)
		(layer "B.Cu")
		(net "A_CPU0_MCP01_RBIAS")
	)
	(segment
		(start 284.071314 -86.117938)
		(end 284.642814 -86.117938)
		(width 0.254)
		(layer "F.Cu")
		(net "A_CPU0_UPI2_RBIAS")
	)
	(segment
		(start 283.212794 -85.622384)
		(end 283.57576 -85.622384)
		(width 0.1016)
		(layer "F.Cu")
		(net "A_CPU0_UPI2_RBIAS")
	)
	(segment
		(start 283.57576 -85.622384)
		(end 284.071314 -86.117938)
		(width 0.1016)
		(layer "F.Cu")
		(net "A_CPU0_UPI2_RBIAS")
	)
	(via
		(at 284.642814 -86.117938)
		(size 0.508)
		(drill 0.254)
		(layers "F.Cu" "B.Cu")
		(net "A_CPU0_UPI2_RBIAS")
	)
	(segment
		(start 284.642814 -83.783932)
		(end 284.642814 -86.117938)
		(width 0.2032)
		(layer "B.Cu")
		(net "A_CPU0_UPI2_RBIAS")
	)
	(segment
		(start 285.292546 -83.1342)
		(end 284.642814 -83.783932)
		(width 0.2032)
		(layer "B.Cu")
		(net "A_CPU0_UPI2_RBIAS")
	)
	(segment
		(start 286.815276 -80.235806)
		(end 286.674306 -80.576166)
		(width 0.1778)
		(layer "B.Cu")
		(net "A_CPU0_UPI2_RBIAS")
	)
	(segment
		(start 284.69463 -76.2254)
		(end 286.140144 -77.670914)
		(width 0.2032)
		(layer "B.Cu")
		(net "A_CPU0_UPI2_RBIAS")
	)
	(segment
		(start 285.94431 -82.916776)
		(end 285.726886 -83.1342)
		(width 0.2032)
		(layer "B.Cu")
		(net "A_CPU0_UPI2_RBIAS")
	)
	(segment
		(start 286.175958 -80.721962)
		(end 285.877 -81.02092)
		(width 0.1778)
		(layer "B.Cu")
		(net "A_CPU0_UPI2_RBIAS")
	)
	(segment
		(start 283.512768 -76.2254)
		(end 284.69463 -76.2254)
		(width 0.2032)
		(layer "B.Cu")
		(net "A_CPU0_UPI2_RBIAS")
	)
	(segment
		(start 282.2448 -77.2414)
		(end 282.496768 -77.2414)
		(width 0.2032)
		(layer "B.Cu")
		(net "A_CPU0_UPI2_RBIAS")
	)
	(segment
		(start 286.674306 -80.652874)
		(end 286.605218 -80.721962)
		(width 0.1778)
		(layer "B.Cu")
		(net "A_CPU0_UPI2_RBIAS")
	)
	(segment
		(start 286.762444 -78.438756)
		(end 286.762444 -78.888844)
		(width 0.2032)
		(layer "B.Cu")
		(net "A_CPU0_UPI2_RBIAS")
	)
	(segment
		(start 286.8676 -79.384652)
		(end 286.762444 -79.489808)
		(width 0.2032)
		(layer "B.Cu")
		(net "A_CPU0_UPI2_RBIAS")
	)
	(segment
		(start 286.762444 -79.879444)
		(end 286.815276 -79.932276)
		(width 0.2032)
		(layer "B.Cu")
		(net "A_CPU0_UPI2_RBIAS")
	)
	(segment
		(start 286.762444 -78.888844)
		(end 286.8676 -78.994)
		(width 0.2032)
		(layer "B.Cu")
		(net "A_CPU0_UPI2_RBIAS")
	)
	(segment
		(start 285.877 -82.399632)
		(end 285.94431 -82.466942)
		(width 0.1778)
		(layer "B.Cu")
		(net "A_CPU0_UPI2_RBIAS")
	)
	(segment
		(start 285.726886 -83.1342)
		(end 285.292546 -83.1342)
		(width 0.2032)
		(layer "B.Cu")
		(net "A_CPU0_UPI2_RBIAS")
	)
	(segment
		(start 286.8676 -78.994)
		(end 286.8676 -79.384652)
		(width 0.2032)
		(layer "B.Cu")
		(net "A_CPU0_UPI2_RBIAS")
	)
	(segment
		(start 286.140144 -77.670914)
		(end 286.482028 -77.670914)
		(width 0.2032)
		(layer "B.Cu")
		(net "A_CPU0_UPI2_RBIAS")
	)
	(segment
		(start 286.815276 -78.004162)
		(end 286.815276 -78.385924)
		(width 0.2032)
		(layer "B.Cu")
		(net "A_CPU0_UPI2_RBIAS")
	)
	(segment
		(start 286.605218 -80.721962)
		(end 286.175958 -80.721962)
		(width 0.1778)
		(layer "B.Cu")
		(net "A_CPU0_UPI2_RBIAS")
	)
	(segment
		(start 286.762444 -79.489808)
		(end 286.762444 -79.879444)
		(width 0.2032)
		(layer "B.Cu")
		(net "A_CPU0_UPI2_RBIAS")
	)
	(segment
		(start 286.815276 -78.385924)
		(end 286.762444 -78.438756)
		(width 0.2032)
		(layer "B.Cu")
		(net "A_CPU0_UPI2_RBIAS")
	)
	(segment
		(start 285.94431 -82.466942)
		(end 285.94431 -82.916776)
		(width 0.1778)
		(layer "B.Cu")
		(net "A_CPU0_UPI2_RBIAS")
	)
	(segment
		(start 286.674306 -80.576166)
		(end 286.674306 -80.652874)
		(width 0.1778)
		(layer "B.Cu")
		(net "A_CPU0_UPI2_RBIAS")
	)
	(segment
		(start 282.496768 -77.2414)
		(end 283.512768 -76.2254)
		(width 0.2032)
		(layer "B.Cu")
		(net "A_CPU0_UPI2_RBIAS")
	)
	(segment
		(start 286.482028 -77.670914)
		(end 286.815276 -78.004162)
		(width 0.2032)
		(layer "B.Cu")
		(net "A_CPU0_UPI2_RBIAS")
	)
	(segment
		(start 286.815276 -79.932276)
		(end 286.815276 -80.235806)
		(width 0.1778)
		(layer "B.Cu")
		(net "A_CPU0_UPI2_RBIAS")
	)
	(segment
		(start 285.877 -81.02092)
		(end 285.877 -82.399632)
		(width 0.1778)
		(layer "B.Cu")
		(net "A_CPU0_UPI2_RBIAS")
	)
	(segment
		(start 282.93568 -68.50507)
		(end 283.212794 -68.782184)
		(width 0.254)
		(layer "F.Cu")
		(net "A_CPU0_UPI01_RBIAS")
	)
	(segment
		(start 283.212794 -70.278244)
		(end 282.030424 -71.460614)
		(width 0.254)
		(layer "F.Cu")
		(net "A_CPU0_UPI01_RBIAS")
	)
	(segment
		(start 283.212794 -68.782184)
		(end 283.212794 -70.278244)
		(width 0.254)
		(layer "F.Cu")
		(net "A_CPU0_UPI01_RBIAS")
	)
	(segment
		(start 282.93568 -68.068698)
		(end 282.93568 -68.50507)
		(width 0.254)
		(layer "F.Cu")
		(net "A_CPU0_UPI01_RBIAS")
	)
	(segment
		(start 283.212794 -67.791584)
		(end 282.93568 -68.068698)
		(width 0.254)
		(layer "F.Cu")
		(net "A_CPU0_UPI01_RBIAS")
	)
	(segment
		(start 406.9969 -19.84502)
		(end 407.40838 -20.2565)
		(width 0.254)
		(layer "F.Cu")
		(net "A_P1V05_STBY_PCH_SENSOR")
	)
	(segment
		(start 410.290264 -26.534618)
		(end 410.290264 -25.658318)
		(width 0.254)
		(layer "F.Cu")
		(net "A_P1V05_STBY_PCH_SENSOR")
	)
	(segment
		(start 409.35402 -20.75434)
		(end 409.35402 -20.100036)
		(width 0.254)
		(layer "F.Cu")
		(net "A_P1V05_STBY_PCH_SENSOR")
	)
	(segment
		(start 409.35402 -20.100036)
		(end 408.729942 -20.100036)
		(width 0.254)
		(layer "F.Cu")
		(net "A_P1V05_STBY_PCH_SENSOR")
	)
	(segment
		(start 409.148534 -20.959826)
		(end 409.35402 -20.75434)
		(width 0.254)
		(layer "F.Cu")
		(net "A_P1V05_STBY_PCH_SENSOR")
	)
	(segment
		(start 409.148534 -24.516588)
		(end 409.148534 -20.959826)
		(width 0.254)
		(layer "F.Cu")
		(net "A_P1V05_STBY_PCH_SENSOR")
	)
	(segment
		(start 408.573478 -20.2565)
		(end 407.67 -20.2565)
		(width 0.254)
		(layer "F.Cu")
		(net "A_P1V05_STBY_PCH_SENSOR")
	)
	(segment
		(start 406.9969 -18.31086)
		(end 406.9969 -19.84502)
		(width 0.254)
		(layer "F.Cu")
		(net "A_P1V05_STBY_PCH_SENSOR")
	)
	(segment
		(start 407.40838 -20.2565)
		(end 407.67 -20.2565)
		(width 0.254)
		(layer "F.Cu")
		(net "A_P1V05_STBY_PCH_SENSOR")
	)
	(segment
		(start 408.729942 -20.100036)
		(end 408.573478 -20.2565)
		(width 0.254)
		(layer "F.Cu")
		(net "A_P1V05_STBY_PCH_SENSOR")
	)
	(segment
		(start 410.290264 -25.658318)
		(end 409.148534 -24.516588)
		(width 0.254)
		(layer "F.Cu")
		(net "A_P1V05_STBY_PCH_SENSOR")
	)
	(via
		(at 406.9969 -18.31086)
		(size 0.762)
		(drill 0.381)
		(layers "F.Cu" "B.Cu")
		(net "A_P1V05_STBY_PCH_SENSOR")
	)
	(segment
		(start 411.09011 -29.734764)
		(end 410.679392 -29.324046)
		(width 0.10795)
		(layer "F.Cu")
		(net "A_P5V_SCALED")
	)
	(via
		(at 410.892752 -20.295616)
		(size 0.6604)
		(drill 0.3302)
		(layers "F.Cu" "B.Cu")
		(net "A_P5V_SCALED")
	)
	(via
		(at 410.209238 -21.438362)
		(size 0.508)
		(drill 0.254)
		(layers "F.Cu" "B.Cu")
		(net "A_P5V_SCALED")
	)
	(via
		(at 410.679392 -29.324046)
		(size 0.4572)
		(drill 0.2032)
		(layers "F.Cu" "B.Cu")
		(net "A_P5V_SCALED")
	)
	(segment
		(start 409.78328 -21.853652)
		(end 409.600146 -21.853652)
		(width 0.254)
		(layer "B.Cu")
		(net "A_P5V_SCALED")
	)
	(segment
		(start 410.209238 -21.438362)
		(end 410.19857 -21.438362)
		(width 0.254)
		(layer "B.Cu")
		(net "A_P5V_SCALED")
	)
	(segment
		(start 410.892752 -20.295616)
		(end 410.409136 -19.812)
		(width 0.254)
		(layer "B.Cu")
		(net "A_P5V_SCALED")
	)
	(segment
		(start 409.600146 -20.993354)
		(end 409.7655 -20.828)
		(width 0.254)
		(layer "B.Cu")
		(net "A_P5V_SCALED")
	)
	(segment
		(start 410.0195 -20.574)
		(end 409.7655 -20.828)
		(width 0.254)
		(layer "B.Cu")
		(net "A_P5V_SCALED")
	)
	(segment
		(start 410.0195 -19.812)
		(end 410.0195 -20.574)
		(width 0.254)
		(layer "B.Cu")
		(net "A_P5V_SCALED")
	)
	(segment
		(start 409.600146 -21.853652)
		(end 409.600146 -20.993354)
		(width 0.254)
		(layer "B.Cu")
		(net "A_P5V_SCALED")
	)
	(segment
		(start 410.19857 -21.438362)
		(end 409.78328 -21.853652)
		(width 0.254)
		(layer "B.Cu")
		(net "A_P5V_SCALED")
	)
	(segment
		(start 410.409136 -19.812)
		(end 410.0195 -19.812)
		(width 0.254)
		(layer "B.Cu")
		(net "A_P5V_SCALED")
	)
	(segment
		(start 410.967682 -25.54478)
		(end 411.562296 -24.950166)
		(width 0.254)
		(layer "In11.Cu")
		(net "A_P5V_SCALED")
	)
	(segment
		(start 411.157674 -28.845764)
		(end 411.157674 -27.875738)
		(width 0.254)
		(layer "In11.Cu")
		(net "A_P5V_SCALED")
	)
	(segment
		(start 410.679392 -29.324046)
		(end 411.157674 -28.845764)
		(width 0.254)
		(layer "In11.Cu")
		(net "A_P5V_SCALED")
	)
	(segment
		(start 411.562296 -24.950166)
		(end 411.562296 -22.79142)
		(width 0.254)
		(layer "In11.Cu")
		(net "A_P5V_SCALED")
	)
	(segment
		(start 411.562296 -22.79142)
		(end 410.209238 -21.438362)
		(width 0.254)
		(layer "In11.Cu")
		(net "A_P5V_SCALED")
	)
	(segment
		(start 411.157674 -27.875738)
		(end 410.967682 -27.685746)
		(width 0.254)
		(layer "In11.Cu")
		(net "A_P5V_SCALED")
	)
	(segment
		(start 410.967682 -27.685746)
		(end 410.967682 -25.54478)
		(width 0.254)
		(layer "In11.Cu")
		(net "A_P5V_SCALED")
	)
	(segment
		(start 411.09011 -28.934664)
		(end 410.69006 -28.534614)
		(width 0.254)
		(layer "F.Cu")
		(net "A_P3V3_SCALED")
	)
	(via
		(at 400.626326 -24.217376)
		(size 0.508)
		(drill 0.254)
		(layers "F.Cu" "B.Cu")
		(net "A_P3V3_SCALED")
	)
	(via
		(at 410.69006 -28.534614)
		(size 0.4572)
		(drill 0.2032)
		(layers "F.Cu" "B.Cu")
		(net "A_P3V3_SCALED")
	)
	(segment
		(start 400.667474 -23.110698)
		(end 401.400772 -23.110698)
		(width 0.254)
		(layer "B.Cu")
		(net "A_P3V3_SCALED")
	)
	(segment
		(start 401.400772 -23.110698)
		(end 401.404074 -23.114)
		(width 0.254)
		(layer "B.Cu")
		(net "A_P3V3_SCALED")
	)
	(segment
		(start 400.667474 -23.110698)
		(end 400.667474 -24.176228)
		(width 0.254)
		(layer "B.Cu")
		(net "A_P3V3_SCALED")
	)
	(segment
		(start 401.404074 -23.114)
		(end 401.454874 -23.114)
		(width 0.254)
		(layer "B.Cu")
		(net "A_P3V3_SCALED")
	)
	(segment
		(start 400.667474 -24.176228)
		(end 400.626326 -24.217376)
		(width 0.254)
		(layer "B.Cu")
		(net "A_P3V3_SCALED")
	)
	(segment
		(start 402.2344 -23.114)
		(end 401.454874 -23.114)
		(width 0.254)
		(layer "B.Cu")
		(net "A_P3V3_SCALED")
	)
	(segment
		(start 402.604224 -26.223976)
		(end 405.84247 -26.223976)
		(width 0.254)
		(layer "In9.Cu")
		(net "A_P3V3_SCALED")
	)
	(segment
		(start 400.626326 -24.217376)
		(end 400.91487 -24.217376)
		(width 0.254)
		(layer "In9.Cu")
		(net "A_P3V3_SCALED")
	)
	(segment
		(start 402.2344 -25.536906)
		(end 402.2344 -25.854152)
		(width 0.254)
		(layer "In9.Cu")
		(net "A_P3V3_SCALED")
	)
	(segment
		(start 402.2344 -25.854152)
		(end 402.604224 -26.223976)
		(width 0.254)
		(layer "In9.Cu")
		(net "A_P3V3_SCALED")
	)
	(segment
		(start 410.265626 -26.076656)
		(end 410.742638 -26.553668)
		(width 0.254)
		(layer "In9.Cu")
		(net "A_P3V3_SCALED")
	)
	(segment
		(start 400.91487 -24.217376)
		(end 402.2344 -25.536906)
		(width 0.254)
		(layer "In9.Cu")
		(net "A_P3V3_SCALED")
	)
	(segment
		(start 408.073098 -26.076656)
		(end 410.265626 -26.076656)
		(width 0.254)
		(layer "In9.Cu")
		(net "A_P3V3_SCALED")
	)
	(segment
		(start 407.39949 -25.418288)
		(end 408.016202 -26.035)
		(width 0.254)
		(layer "In9.Cu")
		(net "A_P3V3_SCALED")
	)
	(segment
		(start 408.031442 -26.035)
		(end 408.073098 -26.076656)
		(width 0.254)
		(layer "In9.Cu")
		(net "A_P3V3_SCALED")
	)
	(segment
		(start 406.648158 -25.418288)
		(end 407.39949 -25.418288)
		(width 0.254)
		(layer "In9.Cu")
		(net "A_P3V3_SCALED")
	)
	(segment
		(start 410.742638 -28.482036)
		(end 410.69006 -28.534614)
		(width 0.254)
		(layer "In9.Cu")
		(net "A_P3V3_SCALED")
	)
	(segment
		(start 408.016202 -26.035)
		(end 408.031442 -26.035)
		(width 0.254)
		(layer "In9.Cu")
		(net "A_P3V3_SCALED")
	)
	(segment
		(start 405.84247 -26.223976)
		(end 406.648158 -25.418288)
		(width 0.254)
		(layer "In9.Cu")
		(net "A_P3V3_SCALED")
	)
	(segment
		(start 410.742638 -26.553668)
		(end 410.742638 -28.482036)
		(width 0.254)
		(layer "In9.Cu")
		(net "A_P3V3_SCALED")
	)
	(segment
		(start 405.06015 -35.43935)
		(end 403.49805 -35.43935)
		(width 0.10795)
		(layer "F.Cu")
		(net "SMB_OCP_LAN_STBY_LVC3_SDA_R")
	)
	(segment
		(start 403.266656 -35.207956)
		(end 402.932646 -34.873946)
		(width 0.10795)
		(layer "F.Cu")
		(net "SMB_OCP_LAN_STBY_LVC3_SDA_R")
	)
	(segment
		(start 403.49805 -35.43935)
		(end 403.266656 -35.207956)
		(width 0.10795)
		(layer "F.Cu")
		(net "SMB_OCP_LAN_STBY_LVC3_SDA_R")
	)
	(segment
		(start 399.768568 -35.031934)
		(end 399.758916 -35.041586)
		(width 0.10795)
		(layer "F.Cu")
		(net "SMB_OCP_LAN_STBY_LVC3_SDA_R")
	)
	(segment
		(start 407.090118 -33.734756)
		(end 406.82037 -34.004504)
		(width 0.10795)
		(layer "F.Cu")
		(net "SMB_OCP_LAN_STBY_LVC3_SDA_R")
	)
	(segment
		(start 400.312128 -35.041586)
		(end 399.758916 -35.041586)
		(width 0.10795)
		(layer "F.Cu")
		(net "SMB_OCP_LAN_STBY_LVC3_SDA_R")
	)
	(segment
		(start 406.494996 -34.004504)
		(end 405.06015 -35.43935)
		(width 0.10795)
		(layer "F.Cu")
		(net "SMB_OCP_LAN_STBY_LVC3_SDA_R")
	)
	(segment
		(start 399.768568 -34.279586)
		(end 399.768568 -35.031934)
		(width 0.10795)
		(layer "F.Cu")
		(net "SMB_OCP_LAN_STBY_LVC3_SDA_R")
	)
	(segment
		(start 406.82037 -34.004504)
		(end 406.494996 -34.004504)
		(width 0.10795)
		(layer "F.Cu")
		(net "SMB_OCP_LAN_STBY_LVC3_SDA_R")
	)
	(segment
		(start 400.479768 -34.873946)
		(end 400.312128 -35.041586)
		(width 0.10795)
		(layer "F.Cu")
		(net "SMB_OCP_LAN_STBY_LVC3_SDA_R")
	)
	(segment
		(start 402.932646 -34.873946)
		(end 400.479768 -34.873946)
		(width 0.10795)
		(layer "F.Cu")
		(net "SMB_OCP_LAN_STBY_LVC3_SDA_R")
	)
	(via
		(at 403.266656 -35.207956)
		(size 0.508)
		(drill 0.254)
		(layers "F.Cu" "B.Cu")
		(net "SMB_OCP_LAN_STBY_LVC3_SDA_R")
	)
	(segment
		(start 402.799296 -35.108896)
		(end 403.3901 -35.6997)
		(width 0.10795)
		(layer "F.Cu")
		(net "SMB_OCP_LAN_STBY_LVC3_SCL_R")
	)
	(segment
		(start 404.575264 -35.6997)
		(end 405.1681 -35.6997)
		(width 0.10795)
		(layer "F.Cu")
		(net "SMB_OCP_LAN_STBY_LVC3_SCL_R")
	)
	(segment
		(start 405.1681 -35.6997)
		(end 406.602946 -34.264854)
		(width 0.10795)
		(layer "F.Cu")
		(net "SMB_OCP_LAN_STBY_LVC3_SCL_R")
	)
	(segment
		(start 400.627342 -35.108896)
		(end 402.799296 -35.108896)
		(width 0.10795)
		(layer "F.Cu")
		(net "SMB_OCP_LAN_STBY_LVC3_SCL_R")
	)
	(segment
		(start 403.3901 -35.6997)
		(end 404.575264 -35.6997)
		(width 0.10795)
		(layer "F.Cu")
		(net "SMB_OCP_LAN_STBY_LVC3_SCL_R")
	)
	(segment
		(start 406.82037 -34.264854)
		(end 407.090118 -34.534602)
		(width 0.10795)
		(layer "F.Cu")
		(net "SMB_OCP_LAN_STBY_LVC3_SCL_R")
	)
	(segment
		(start 406.602946 -34.264854)
		(end 406.82037 -34.264854)
		(width 0.10795)
		(layer "F.Cu")
		(net "SMB_OCP_LAN_STBY_LVC3_SCL_R")
	)
	(segment
		(start 399.932652 -35.803586)
		(end 400.627342 -35.108896)
		(width 0.10795)
		(layer "F.Cu")
		(net "SMB_OCP_LAN_STBY_LVC3_SCL_R")
	)
	(segment
		(start 399.763996 -35.803586)
		(end 399.932652 -35.803586)
		(width 0.10795)
		(layer "F.Cu")
		(net "SMB_OCP_LAN_STBY_LVC3_SCL_R")
	)
	(segment
		(start 399.763996 -35.803586)
		(end 399.763996 -36.565586)
		(width 0.10795)
		(layer "F.Cu")
		(net "SMB_OCP_LAN_STBY_LVC3_SCL_R")
	)
	(via
		(at 404.575264 -35.6997)
		(size 0.508)
		(drill 0.254)
		(layers "F.Cu" "B.Cu")
		(net "SMB_OCP_LAN_STBY_LVC3_SCL_R")
	)
	(segment
		(start 416.380168 -23.151846)
		(end 415.53384 -23.998174)
		(width 0.10795)
		(layer "F.Cu")
		(net "SMB_VR_STBY_LVC3_SDA_R")
	)
	(segment
		(start 417.244276 -19.218656)
		(end 416.714178 -19.748754)
		(width 0.10795)
		(layer "F.Cu")
		(net "SMB_VR_STBY_LVC3_SDA_R")
	)
	(segment
		(start 416.714178 -19.748754)
		(end 416.706812 -19.748754)
		(width 0.10795)
		(layer "F.Cu")
		(net "SMB_VR_STBY_LVC3_SDA_R")
	)
	(segment
		(start 418.192204 -19.218656)
		(end 417.244276 -19.218656)
		(width 0.10795)
		(layer "F.Cu")
		(net "SMB_VR_STBY_LVC3_SDA_R")
	)
	(segment
		(start 415.53384 -25.149302)
		(end 416.343592 -25.959054)
		(width 0.10795)
		(layer "F.Cu")
		(net "SMB_VR_STBY_LVC3_SDA_R")
	)
	(segment
		(start 416.343592 -26.48458)
		(end 416.343846 -26.484834)
		(width 0.10795)
		(layer "F.Cu")
		(net "SMB_VR_STBY_LVC3_SDA_R")
	)
	(segment
		(start 418.465 -18.7452)
		(end 418.465 -18.94586)
		(width 0.10795)
		(layer "F.Cu")
		(net "SMB_VR_STBY_LVC3_SDA_R")
	)
	(segment
		(start 415.53384 -23.998174)
		(end 415.53384 -25.149302)
		(width 0.10795)
		(layer "F.Cu")
		(net "SMB_VR_STBY_LVC3_SDA_R")
	)
	(segment
		(start 416.380168 -20.075398)
		(end 416.380168 -23.151846)
		(width 0.10795)
		(layer "F.Cu")
		(net "SMB_VR_STBY_LVC3_SDA_R")
	)
	(segment
		(start 416.343592 -25.959054)
		(end 416.343592 -26.48458)
		(width 0.10795)
		(layer "F.Cu")
		(net "SMB_VR_STBY_LVC3_SDA_R")
	)
	(segment
		(start 416.343846 -26.721308)
		(end 416.690048 -27.06751)
		(width 0.10795)
		(layer "F.Cu")
		(net "SMB_VR_STBY_LVC3_SDA_R")
	)
	(segment
		(start 418.465 -18.94586)
		(end 418.192204 -19.218656)
		(width 0.10795)
		(layer "F.Cu")
		(net "SMB_VR_STBY_LVC3_SDA_R")
	)
	(segment
		(start 416.706812 -19.748754)
		(end 416.380168 -20.075398)
		(width 0.10795)
		(layer "F.Cu")
		(net "SMB_VR_STBY_LVC3_SDA_R")
	)
	(segment
		(start 416.343846 -26.484834)
		(end 416.343846 -26.721308)
		(width 0.10795)
		(layer "F.Cu")
		(net "SMB_VR_STBY_LVC3_SDA_R")
	)
	(segment
		(start 416.690048 -27.06751)
		(end 416.690048 -27.334718)
		(width 0.10795)
		(layer "F.Cu")
		(net "SMB_VR_STBY_LVC3_SDA_R")
	)
	(via
		(at 416.706812 -19.748754)
		(size 0.762)
		(drill 0.381)
		(layers "F.Cu" "B.Cu")
		(net "SMB_VR_STBY_LVC3_SDA_R")
	)
	(segment
		(start 415.003996 -26.093928)
		(end 415.090102 -26.180034)
		(width 0.10795)
		(layer "F.Cu")
		(net "SMB_VR_STBY_LVC3_SCL_R")
	)
	(segment
		(start 414.124394 -19.935952)
		(end 413.893 -20.167346)
		(width 0.10795)
		(layer "F.Cu")
		(net "SMB_VR_STBY_LVC3_SCL_R")
	)
	(segment
		(start 415.090102 -26.180034)
		(end 415.090102 -26.534618)
		(width 0.10795)
		(layer "F.Cu")
		(net "SMB_VR_STBY_LVC3_SCL_R")
	)
	(segment
		(start 415.200592 -18.246598)
		(end 414.953196 -18.493994)
		(width 0.10795)
		(layer "F.Cu")
		(net "SMB_VR_STBY_LVC3_SCL_R")
	)
	(segment
		(start 414.953196 -18.497804)
		(end 414.950402 -18.500598)
		(width 0.10795)
		(layer "F.Cu")
		(net "SMB_VR_STBY_LVC3_SCL_R")
	)
	(segment
		(start 415.49701 -18.193004)
		(end 415.257996 -18.193004)
		(width 0.10795)
		(layer "F.Cu")
		(net "SMB_VR_STBY_LVC3_SCL_R")
	)
	(segment
		(start 413.893 -20.167346)
		(end 413.893 -21.209)
		(width 0.10795)
		(layer "F.Cu")
		(net "SMB_VR_STBY_LVC3_SCL_R")
	)
	(segment
		(start 417.5506 -18.7452)
		(end 416.049206 -18.7452)
		(width 0.10795)
		(layer "F.Cu")
		(net "SMB_VR_STBY_LVC3_SCL_R")
	)
	(segment
		(start 414.953196 -18.493994)
		(end 414.953196 -18.497804)
		(width 0.10795)
		(layer "F.Cu")
		(net "SMB_VR_STBY_LVC3_SCL_R")
	)
	(segment
		(start 415.003996 -22.319996)
		(end 415.003996 -26.093928)
		(width 0.10795)
		(layer "F.Cu")
		(net "SMB_VR_STBY_LVC3_SCL_R")
	)
	(segment
		(start 416.049206 -18.7452)
		(end 415.49701 -18.193004)
		(width 0.10795)
		(layer "F.Cu")
		(net "SMB_VR_STBY_LVC3_SCL_R")
	)
	(segment
		(start 415.257996 -18.193004)
		(end 415.204402 -18.246598)
		(width 0.10795)
		(layer "F.Cu")
		(net "SMB_VR_STBY_LVC3_SCL_R")
	)
	(segment
		(start 414.950402 -19.109944)
		(end 414.124394 -19.935952)
		(width 0.10795)
		(layer "F.Cu")
		(net "SMB_VR_STBY_LVC3_SCL_R")
	)
	(segment
		(start 413.893 -21.209)
		(end 415.003996 -22.319996)
		(width 0.10795)
		(layer "F.Cu")
		(net "SMB_VR_STBY_LVC3_SCL_R")
	)
	(segment
		(start 414.950402 -18.500598)
		(end 414.950402 -19.109944)
		(width 0.10795)
		(layer "F.Cu")
		(net "SMB_VR_STBY_LVC3_SCL_R")
	)
	(segment
		(start 415.204402 -18.246598)
		(end 415.200592 -18.246598)
		(width 0.10795)
		(layer "F.Cu")
		(net "SMB_VR_STBY_LVC3_SCL_R")
	)
	(via
		(at 414.124394 -19.935952)
		(size 0.762)
		(drill 0.381)
		(layers "F.Cu" "B.Cu")
		(net "SMB_VR_STBY_LVC3_SCL_R")
	)
	(segment
		(start 415.090102 -28.934664)
		(end 414.690052 -29.334714)
		(width 0.10795)
		(layer "F.Cu")
		(net "SMB_SMLINK0_STBY_LVC3_SDA_R")
	)
	(via
		(at 423.340022 -24.2062)
		(size 0.6604)
		(drill 0.3302)
		(layers "F.Cu" "B.Cu")
		(net "SMB_SMLINK0_STBY_LVC3_SDA_R")
	)
	(via
		(at 414.690052 -29.334714)
		(size 0.4572)
		(drill 0.2032)
		(layers "F.Cu" "B.Cu")
		(net "SMB_SMLINK0_STBY_LVC3_SDA_R")
	)
	(segment
		(start 420.530274 -26.285698)
		(end 421.442896 -26.285698)
		(width 0.10795)
		(layer "B.Cu")
		(net "SMB_SMLINK0_STBY_LVC3_SDA_R")
	)
	(segment
		(start 417.288726 -27.3304)
		(end 418.846 -27.3304)
		(width 0.10795)
		(layer "B.Cu")
		(net "SMB_SMLINK0_STBY_LVC3_SDA_R")
	)
	(segment
		(start 425.242482 -21.459952)
		(end 426.658532 -21.459952)
		(width 0.10795)
		(layer "B.Cu")
		(net "SMB_SMLINK0_STBY_LVC3_SDA_R")
	)
	(segment
		(start 414.690052 -29.334714)
		(end 414.690052 -29.179012)
		(width 0.10795)
		(layer "B.Cu")
		(net "SMB_SMLINK0_STBY_LVC3_SDA_R")
	)
	(segment
		(start 423.0624 -24.2062)
		(end 423.340022 -24.2062)
		(width 0.10795)
		(layer "B.Cu")
		(net "SMB_SMLINK0_STBY_LVC3_SDA_R")
	)
	(segment
		(start 427.036484 -21.082)
		(end 427.4185 -21.082)
		(width 0.10795)
		(layer "B.Cu")
		(net "SMB_SMLINK0_STBY_LVC3_SDA_R")
	)
	(segment
		(start 419.50005 -26.67635)
		(end 420.139622 -26.67635)
		(width 0.10795)
		(layer "B.Cu")
		(net "SMB_SMLINK0_STBY_LVC3_SDA_R")
	)
	(segment
		(start 416.486594 -28.132532)
		(end 417.288726 -27.3304)
		(width 0.10795)
		(layer "B.Cu")
		(net "SMB_SMLINK0_STBY_LVC3_SDA_R")
	)
	(segment
		(start 414.690052 -29.179012)
		(end 415.736532 -28.132532)
		(width 0.10795)
		(layer "B.Cu")
		(net "SMB_SMLINK0_STBY_LVC3_SDA_R")
	)
	(segment
		(start 426.658532 -21.459952)
		(end 427.036484 -21.082)
		(width 0.10795)
		(layer "B.Cu")
		(net "SMB_SMLINK0_STBY_LVC3_SDA_R")
	)
	(segment
		(start 423.8117 -24.2062)
		(end 424.961812 -23.056088)
		(width 0.10795)
		(layer "B.Cu")
		(net "SMB_SMLINK0_STBY_LVC3_SDA_R")
	)
	(segment
		(start 420.139622 -26.67635)
		(end 420.530274 -26.285698)
		(width 0.10795)
		(layer "B.Cu")
		(net "SMB_SMLINK0_STBY_LVC3_SDA_R")
	)
	(segment
		(start 418.846 -27.3304)
		(end 419.50005 -26.67635)
		(width 0.10795)
		(layer "B.Cu")
		(net "SMB_SMLINK0_STBY_LVC3_SDA_R")
	)
	(segment
		(start 422.373552 -25.355042)
		(end 422.373552 -24.895048)
		(width 0.10795)
		(layer "B.Cu")
		(net "SMB_SMLINK0_STBY_LVC3_SDA_R")
	)
	(segment
		(start 424.961812 -21.740622)
		(end 425.242482 -21.459952)
		(width 0.10795)
		(layer "B.Cu")
		(net "SMB_SMLINK0_STBY_LVC3_SDA_R")
	)
	(segment
		(start 422.373552 -24.895048)
		(end 423.0624 -24.2062)
		(width 0.10795)
		(layer "B.Cu")
		(net "SMB_SMLINK0_STBY_LVC3_SDA_R")
	)
	(segment
		(start 424.961812 -23.056088)
		(end 424.961812 -21.740622)
		(width 0.10795)
		(layer "B.Cu")
		(net "SMB_SMLINK0_STBY_LVC3_SDA_R")
	)
	(segment
		(start 423.340022 -24.2062)
		(end 423.8117 -24.2062)
		(width 0.10795)
		(layer "B.Cu")
		(net "SMB_SMLINK0_STBY_LVC3_SDA_R")
	)
	(segment
		(start 421.442896 -26.285698)
		(end 422.373552 -25.355042)
		(width 0.10795)
		(layer "B.Cu")
		(net "SMB_SMLINK0_STBY_LVC3_SDA_R")
	)
	(segment
		(start 415.736532 -28.132532)
		(end 416.486594 -28.132532)
		(width 0.10795)
		(layer "B.Cu")
		(net "SMB_SMLINK0_STBY_LVC3_SDA_R")
	)
	(segment
		(start 415.090102 -28.134564)
		(end 414.690052 -28.534614)
		(width 0.10795)
		(layer "F.Cu")
		(net "SMB_SMLINK0_STBY_LVC3_SCL_R")
	)
	(via
		(at 416.745928 -26.981658)
		(size 0.6604)
		(drill 0.3302)
		(layers "F.Cu" "B.Cu")
		(net "SMB_SMLINK0_STBY_LVC3_SCL_R")
	)
	(via
		(at 414.690052 -28.534614)
		(size 0.4572)
		(drill 0.2032)
		(layers "F.Cu" "B.Cu")
		(net "SMB_SMLINK0_STBY_LVC3_SCL_R")
	)
	(segment
		(start 427.219872 -20.32)
		(end 426.31487 -21.225002)
		(width 0.10795)
		(layer "B.Cu")
		(net "SMB_SMLINK0_STBY_LVC3_SCL_R")
	)
	(segment
		(start 422.164256 -24.981916)
		(end 422.164256 -25.268174)
		(width 0.10795)
		(layer "B.Cu")
		(net "SMB_SMLINK0_STBY_LVC3_SCL_R")
	)
	(segment
		(start 420.068248 -26.416)
		(end 419.356286 -26.416)
		(width 0.10795)
		(layer "B.Cu")
		(net "SMB_SMLINK0_STBY_LVC3_SCL_R")
	)
	(segment
		(start 426.31487 -21.225002)
		(end 425.144946 -21.225002)
		(width 0.10795)
		(layer "B.Cu")
		(net "SMB_SMLINK0_STBY_LVC3_SCL_R")
	)
	(segment
		(start 422.57218 -24.400256)
		(end 422.164002 -24.808434)
		(width 0.10795)
		(layer "B.Cu")
		(net "SMB_SMLINK0_STBY_LVC3_SCL_R")
	)
	(segment
		(start 421.356028 -26.076402)
		(end 420.407846 -26.076402)
		(width 0.10795)
		(layer "B.Cu")
		(net "SMB_SMLINK0_STBY_LVC3_SCL_R")
	)
	(segment
		(start 425.144946 -21.225002)
		(end 424.716702 -21.653246)
		(width 0.10795)
		(layer "B.Cu")
		(net "SMB_SMLINK0_STBY_LVC3_SCL_R")
	)
	(segment
		(start 427.4185 -20.32)
		(end 427.219872 -20.32)
		(width 0.10795)
		(layer "B.Cu")
		(net "SMB_SMLINK0_STBY_LVC3_SCL_R")
	)
	(segment
		(start 422.164256 -25.268174)
		(end 421.356028 -26.076402)
		(width 0.10795)
		(layer "B.Cu")
		(net "SMB_SMLINK0_STBY_LVC3_SCL_R")
	)
	(segment
		(start 416.41776 -26.981658)
		(end 416.745928 -26.981658)
		(width 0.10795)
		(layer "B.Cu")
		(net "SMB_SMLINK0_STBY_LVC3_SCL_R")
	)
	(segment
		(start 424.716702 -21.653246)
		(end 424.716702 -22.65553)
		(width 0.10795)
		(layer "B.Cu")
		(net "SMB_SMLINK0_STBY_LVC3_SCL_R")
	)
	(segment
		(start 422.164002 -24.808434)
		(end 422.164002 -24.981662)
		(width 0.10795)
		(layer "B.Cu")
		(net "SMB_SMLINK0_STBY_LVC3_SCL_R")
	)
	(segment
		(start 424.59783 -22.774402)
		(end 423.440098 -22.774402)
		(width 0.10795)
		(layer "B.Cu")
		(net "SMB_SMLINK0_STBY_LVC3_SCL_R")
	)
	(segment
		(start 419.356286 -26.416)
		(end 418.790628 -26.981658)
		(width 0.10795)
		(layer "B.Cu")
		(net "SMB_SMLINK0_STBY_LVC3_SCL_R")
	)
	(segment
		(start 422.57218 -23.64232)
		(end 422.57218 -24.400256)
		(width 0.10795)
		(layer "B.Cu")
		(net "SMB_SMLINK0_STBY_LVC3_SCL_R")
	)
	(segment
		(start 418.790628 -26.981658)
		(end 416.745928 -26.981658)
		(width 0.10795)
		(layer "B.Cu")
		(net "SMB_SMLINK0_STBY_LVC3_SCL_R")
	)
	(segment
		(start 420.407846 -26.076402)
		(end 420.068248 -26.416)
		(width 0.10795)
		(layer "B.Cu")
		(net "SMB_SMLINK0_STBY_LVC3_SCL_R")
	)
	(segment
		(start 414.690052 -28.534614)
		(end 414.864804 -28.534614)
		(width 0.10795)
		(layer "B.Cu")
		(net "SMB_SMLINK0_STBY_LVC3_SCL_R")
	)
	(segment
		(start 422.164002 -24.981662)
		(end 422.164256 -24.981916)
		(width 0.10795)
		(layer "B.Cu")
		(net "SMB_SMLINK0_STBY_LVC3_SCL_R")
	)
	(segment
		(start 424.716702 -22.65553)
		(end 424.59783 -22.774402)
		(width 0.10795)
		(layer "B.Cu")
		(net "SMB_SMLINK0_STBY_LVC3_SCL_R")
	)
	(segment
		(start 414.864804 -28.534614)
		(end 416.41776 -26.981658)
		(width 0.10795)
		(layer "B.Cu")
		(net "SMB_SMLINK0_STBY_LVC3_SCL_R")
	)
	(segment
		(start 423.440098 -22.774402)
		(end 422.57218 -23.64232)
		(width 0.10795)
		(layer "B.Cu")
		(net "SMB_SMLINK0_STBY_LVC3_SCL_R")
	)
	(segment
		(start 394.280644 -91.84767)
		(end 394.280644 -93.724222)
		(width 0.0889)
		(layer "F.Cu")
		(net "FP_PWR_ID_LED_N")
	)
	(segment
		(start 393.827 -88.2015)
		(end 394.064236 -88.438736)
		(width 0.10795)
		(layer "F.Cu")
		(net "FP_PWR_ID_LED_N")
	)
	(segment
		(start 394.064236 -88.438736)
		(end 394.064236 -88.74887)
		(width 0.10795)
		(layer "F.Cu")
		(net "FP_PWR_ID_LED_N")
	)
	(segment
		(start 423.45356 -46.3042)
		(end 423.45356 -45.211238)
		(width 0.10795)
		(layer "F.Cu")
		(net "FP_PWR_ID_LED_N")
	)
	(segment
		(start 423.45356 -45.211238)
		(end 422.29024 -44.047918)
		(width 0.10795)
		(layer "F.Cu")
		(net "FP_PWR_ID_LED_N")
	)
	(segment
		(start 394.198856 -91.765882)
		(end 394.280644 -91.84767)
		(width 0.0889)
		(layer "F.Cu")
		(net "FP_PWR_ID_LED_N")
	)
	(segment
		(start 394.064236 -88.74887)
		(end 393.862306 -88.9508)
		(width 0.10795)
		(layer "F.Cu")
		(net "FP_PWR_ID_LED_N")
	)
	(segment
		(start 394.280644 -93.724222)
		(end 393.984988 -94.019878)
		(width 0.0889)
		(layer "F.Cu")
		(net "FP_PWR_ID_LED_N")
	)
	(segment
		(start 414.105598 -92.1004)
		(end 414.867598 -92.1004)
		(width 0.10795)
		(layer "F.Cu")
		(net "FP_PWR_ID_LED_N")
	)
	(segment
		(start 393.862306 -88.9508)
		(end 393.862306 -91.429332)
		(width 0.10795)
		(layer "F.Cu")
		(net "FP_PWR_ID_LED_N")
	)
	(segment
		(start 393.984988 -94.019878)
		(end 393.984988 -94.37497)
		(width 0.0889)
		(layer "F.Cu")
		(net "FP_PWR_ID_LED_N")
	)
	(segment
		(start 393.862306 -91.429332)
		(end 394.198856 -91.765882)
		(width 0.10795)
		(layer "F.Cu")
		(net "FP_PWR_ID_LED_N")
	)
	(segment
		(start 422.29024 -44.047918)
		(end 422.29024 -43.334686)
		(width 0.10795)
		(layer "F.Cu")
		(net "FP_PWR_ID_LED_N")
	)
	(via
		(at 491.3249 -154.7495)
		(size 0.508)
		(drill 0.254)
		(layers "F.Cu" "B.Cu")
		(net "FP_PWR_ID_LED_N")
	)
	(via
		(at 414.105598 -92.1004)
		(size 0.508)
		(drill 0.254)
		(layers "F.Cu" "B.Cu")
		(net "FP_PWR_ID_LED_N")
	)
	(via
		(at 414.867598 -92.1004)
		(size 0.762)
		(drill 0.381)
		(layers "F.Cu" "B.Cu")
		(net "FP_PWR_ID_LED_N")
	)
	(via
		(at 423.45356 -46.3042)
		(size 0.508)
		(drill 0.254)
		(layers "F.Cu" "B.Cu")
		(net "FP_PWR_ID_LED_N")
	)
	(via
		(at 495.7826 -135.8646)
		(size 0.508)
		(drill 0.254)
		(layers "F.Cu" "B.Cu")
		(net "FP_PWR_ID_LED_N")
	)
	(via
		(at 393.862306 -88.9508)
		(size 0.508)
		(drill 0.254)
		(layers "F.Cu" "B.Cu")
		(net "FP_PWR_ID_LED_N")
	)
	(segment
		(start 491.3249 -154.7495)
		(end 490.0295 -154.7495)
		(width 0.10795)
		(layer "B.Cu")
		(net "FP_PWR_ID_LED_N")
	)
	(segment
		(start 489.839 -154.559)
		(end 489.839 -153.924)
		(width 0.10795)
		(layer "B.Cu")
		(net "FP_PWR_ID_LED_N")
	)
	(segment
		(start 490.0295 -154.7495)
		(end 489.839 -154.559)
		(width 0.10795)
		(layer "B.Cu")
		(net "FP_PWR_ID_LED_N")
	)
	(segment
		(start 424.555158 -116.981986)
		(end 423.208958 -116.981986)
		(width 0.089408)
		(layer "In2.Cu")
		(net "FP_PWR_ID_LED_N")
	)
	(segment
		(start 416.162744 -106.222038)
		(end 416.162744 -104.392222)
		(width 0.089408)
		(layer "In2.Cu")
		(net "FP_PWR_ID_LED_N")
	)
	(segment
		(start 425.078652 -117.504464)
		(end 425.077636 -117.504464)
		(width 0.089408)
		(layer "In2.Cu")
		(net "FP_PWR_ID_LED_N")
	)
	(segment
		(start 494.1824 -129.369312)
		(end 491.5027 -126.689612)
		(width 0.089408)
		(layer "In2.Cu")
		(net "FP_PWR_ID_LED_N")
	)
	(segment
		(start 491.5027 -126.689612)
		(end 485.832912 -126.689612)
		(width 0.089408)
		(layer "In2.Cu")
		(net "FP_PWR_ID_LED_N")
	)
	(segment
		(start 415.364676 -109.168184)
		(end 415.364676 -107.020106)
		(width 0.089408)
		(layer "In2.Cu")
		(net "FP_PWR_ID_LED_N")
	)
	(segment
		(start 415.708084 -95.424752)
		(end 415.218118 -94.934786)
		(width 0.089408)
		(layer "In2.Cu")
		(net "FP_PWR_ID_LED_N")
	)
	(segment
		(start 422.49471 -117.696234)
		(end 416.951668 -117.696234)
		(width 0.089408)
		(layer "In2.Cu")
		(net "FP_PWR_ID_LED_N")
	)
	(segment
		(start 495.7826 -134.66064)
		(end 494.1824 -133.06044)
		(width 0.089408)
		(layer "In2.Cu")
		(net "FP_PWR_ID_LED_N")
	)
	(segment
		(start 425.314364 -117.740176)
		(end 425.078652 -117.504464)
		(width 0.089408)
		(layer "In2.Cu")
		(net "FP_PWR_ID_LED_N")
	)
	(segment
		(start 485.832912 -126.689612)
		(end 485.2035 -126.0602)
		(width 0.089408)
		(layer "In2.Cu")
		(net "FP_PWR_ID_LED_N")
	)
	(segment
		(start 494.1824 -133.06044)
		(end 494.1824 -129.369312)
		(width 0.089408)
		(layer "In2.Cu")
		(net "FP_PWR_ID_LED_N")
	)
	(segment
		(start 416.951668 -117.696234)
		(end 415.41446 -116.159026)
		(width 0.089408)
		(layer "In2.Cu")
		(net "FP_PWR_ID_LED_N")
	)
	(segment
		(start 485.2035 -124.978922)
		(end 480.119944 -119.895366)
		(width 0.089408)
		(layer "In2.Cu")
		(net "FP_PWR_ID_LED_N")
	)
	(segment
		(start 466.864446 -115.809776)
		(end 466.503766 -115.449096)
		(width 0.089408)
		(layer "In2.Cu")
		(net "FP_PWR_ID_LED_N")
	)
	(segment
		(start 415.14141 -112.238282)
		(end 415.14141 -112.080294)
		(width 0.089408)
		(layer "In2.Cu")
		(net "FP_PWR_ID_LED_N")
	)
	(segment
		(start 415.41446 -112.511332)
		(end 415.14141 -112.238282)
		(width 0.089408)
		(layer "In2.Cu")
		(net "FP_PWR_ID_LED_N")
	)
	(segment
		(start 423.208958 -116.981986)
		(end 422.49471 -117.696234)
		(width 0.089408)
		(layer "In2.Cu")
		(net "FP_PWR_ID_LED_N")
	)
	(segment
		(start 416.162744 -104.392222)
		(end 415.708084 -103.937562)
		(width 0.089408)
		(layer "In2.Cu")
		(net "FP_PWR_ID_LED_N")
	)
	(segment
		(start 415.141664 -112.08004)
		(end 415.141664 -109.391196)
		(width 0.089408)
		(layer "In2.Cu")
		(net "FP_PWR_ID_LED_N")
	)
	(segment
		(start 430.499266 -118.68404)
		(end 429.555402 -117.740176)
		(width 0.089408)
		(layer "In2.Cu")
		(net "FP_PWR_ID_LED_N")
	)
	(segment
		(start 495.7826 -135.8646)
		(end 495.7826 -134.66064)
		(width 0.089408)
		(layer "In2.Cu")
		(net "FP_PWR_ID_LED_N")
	)
	(segment
		(start 480.119944 -118.716298)
		(end 477.213422 -115.809776)
		(width 0.089408)
		(layer "In2.Cu")
		(net "FP_PWR_ID_LED_N")
	)
	(segment
		(start 415.218118 -94.934786)
		(end 415.218118 -94.394782)
		(width 0.089408)
		(layer "In2.Cu")
		(net "FP_PWR_ID_LED_N")
	)
	(segment
		(start 466.503766 -115.449096)
		(end 436.463694 -115.449096)
		(width 0.089408)
		(layer "In2.Cu")
		(net "FP_PWR_ID_LED_N")
	)
	(segment
		(start 415.708084 -103.937562)
		(end 415.708084 -95.424752)
		(width 0.089408)
		(layer "In2.Cu")
		(net "FP_PWR_ID_LED_N")
	)
	(segment
		(start 415.218118 -94.394782)
		(end 414.82645 -94.003114)
		(width 0.089408)
		(layer "In2.Cu")
		(net "FP_PWR_ID_LED_N")
	)
	(segment
		(start 480.119944 -119.895366)
		(end 480.119944 -118.716298)
		(width 0.089408)
		(layer "In2.Cu")
		(net "FP_PWR_ID_LED_N")
	)
	(segment
		(start 415.14141 -112.080294)
		(end 415.141664 -112.08004)
		(width 0.089408)
		(layer "In2.Cu")
		(net "FP_PWR_ID_LED_N")
	)
	(segment
		(start 414.82645 -94.003114)
		(end 414.82645 -92.821252)
		(width 0.089408)
		(layer "In2.Cu")
		(net "FP_PWR_ID_LED_N")
	)
	(segment
		(start 415.141664 -109.391196)
		(end 415.364676 -109.168184)
		(width 0.089408)
		(layer "In2.Cu")
		(net "FP_PWR_ID_LED_N")
	)
	(segment
		(start 485.2035 -126.0602)
		(end 485.2035 -124.978922)
		(width 0.089408)
		(layer "In2.Cu")
		(net "FP_PWR_ID_LED_N")
	)
	(segment
		(start 436.463694 -115.449096)
		(end 433.22875 -118.68404)
		(width 0.089408)
		(layer "In2.Cu")
		(net "FP_PWR_ID_LED_N")
	)
	(segment
		(start 433.22875 -118.68404)
		(end 430.499266 -118.68404)
		(width 0.089408)
		(layer "In2.Cu")
		(net "FP_PWR_ID_LED_N")
	)
	(segment
		(start 425.077636 -117.504464)
		(end 424.555158 -116.981986)
		(width 0.089408)
		(layer "In2.Cu")
		(net "FP_PWR_ID_LED_N")
	)
	(segment
		(start 414.82645 -92.821252)
		(end 414.105598 -92.1004)
		(width 0.089408)
		(layer "In2.Cu")
		(net "FP_PWR_ID_LED_N")
	)
	(segment
		(start 415.364676 -107.020106)
		(end 416.162744 -106.222038)
		(width 0.089408)
		(layer "In2.Cu")
		(net "FP_PWR_ID_LED_N")
	)
	(segment
		(start 429.555402 -117.740176)
		(end 425.314364 -117.740176)
		(width 0.089408)
		(layer "In2.Cu")
		(net "FP_PWR_ID_LED_N")
	)
	(segment
		(start 415.41446 -116.159026)
		(end 415.41446 -112.511332)
		(width 0.089408)
		(layer "In2.Cu")
		(net "FP_PWR_ID_LED_N")
	)
	(segment
		(start 477.213422 -115.809776)
		(end 466.864446 -115.809776)
		(width 0.089408)
		(layer "In2.Cu")
		(net "FP_PWR_ID_LED_N")
	)
	(segment
		(start 411.109922 -91.516962)
		(end 409.64612 -90.05316)
		(width 0.089408)
		(layer "In4.Cu")
		(net "FP_PWR_ID_LED_N")
	)
	(segment
		(start 413.000952 -91.516962)
		(end 411.109922 -91.516962)
		(width 0.089408)
		(layer "In4.Cu")
		(net "FP_PWR_ID_LED_N")
	)
	(segment
		(start 413.93364 -92.272358)
		(end 413.756348 -92.272358)
		(width 0.089408)
		(layer "In4.Cu")
		(net "FP_PWR_ID_LED_N")
	)
	(segment
		(start 409.64612 -90.05316)
		(end 405.62276 -90.05316)
		(width 0.089408)
		(layer "In4.Cu")
		(net "FP_PWR_ID_LED_N")
	)
	(segment
		(start 404.131272 -88.561672)
		(end 402.838158 -88.561672)
		(width 0.089408)
		(layer "In4.Cu")
		(net "FP_PWR_ID_LED_N")
	)
	(segment
		(start 395.829536 -88.928702)
		(end 393.884404 -88.928702)
		(width 0.089408)
		(layer "In4.Cu")
		(net "FP_PWR_ID_LED_N")
	)
	(segment
		(start 402.838158 -88.561672)
		(end 402.399754 -89.000076)
		(width 0.089408)
		(layer "In4.Cu")
		(net "FP_PWR_ID_LED_N")
	)
	(segment
		(start 396.201138 -89.300304)
		(end 395.829536 -88.928702)
		(width 0.089408)
		(layer "In4.Cu")
		(net "FP_PWR_ID_LED_N")
	)
	(segment
		(start 396.548356 -89.300304)
		(end 396.201138 -89.300304)
		(width 0.089408)
		(layer "In4.Cu")
		(net "FP_PWR_ID_LED_N")
	)
	(segment
		(start 393.884404 -88.928702)
		(end 393.862306 -88.9508)
		(width 0.089408)
		(layer "In4.Cu")
		(net "FP_PWR_ID_LED_N")
	)
	(segment
		(start 398.773142 -88.500966)
		(end 397.347694 -88.500966)
		(width 0.089408)
		(layer "In4.Cu")
		(net "FP_PWR_ID_LED_N")
	)
	(segment
		(start 397.347694 -88.500966)
		(end 396.548356 -89.300304)
		(width 0.089408)
		(layer "In4.Cu")
		(net "FP_PWR_ID_LED_N")
	)
	(segment
		(start 413.756348 -92.272358)
		(end 413.000952 -91.516962)
		(width 0.089408)
		(layer "In4.Cu")
		(net "FP_PWR_ID_LED_N")
	)
	(segment
		(start 405.62276 -90.05316)
		(end 404.131272 -88.561672)
		(width 0.089408)
		(layer "In4.Cu")
		(net "FP_PWR_ID_LED_N")
	)
	(segment
		(start 402.399754 -89.000076)
		(end 399.272252 -89.000076)
		(width 0.089408)
		(layer "In4.Cu")
		(net "FP_PWR_ID_LED_N")
	)
	(segment
		(start 399.272252 -89.000076)
		(end 398.773142 -88.500966)
		(width 0.089408)
		(layer "In4.Cu")
		(net "FP_PWR_ID_LED_N")
	)
	(segment
		(start 414.105598 -92.1004)
		(end 413.93364 -92.272358)
		(width 0.089408)
		(layer "In4.Cu")
		(net "FP_PWR_ID_LED_N")
	)
	(segment
		(start 406.888188 -70.087998)
		(end 406.888188 -69.628258)
		(width 0.089408)
		(layer "In9.Cu")
		(net "FP_PWR_ID_LED_N")
	)
	(segment
		(start 409.401264 -55.911242)
		(end 414.416494 -50.896012)
		(width 0.089408)
		(layer "In9.Cu")
		(net "FP_PWR_ID_LED_N")
	)
	(segment
		(start 400.6215 -81.607152)
		(end 400.6215 -80.43926)
		(width 0.089408)
		(layer "In9.Cu")
		(net "FP_PWR_ID_LED_N")
	)
	(segment
		(start 409.401264 -60.967366)
		(end 409.401264 -55.911242)
		(width 0.089408)
		(layer "In9.Cu")
		(net "FP_PWR_ID_LED_N")
	)
	(segment
		(start 414.416494 -50.896012)
		(end 416.143948 -50.896012)
		(width 0.089408)
		(layer "In9.Cu")
		(net "FP_PWR_ID_LED_N")
	)
	(segment
		(start 393.884404 -88.928702)
		(end 394.46454 -88.928702)
		(width 0.089408)
		(layer "In9.Cu")
		(net "FP_PWR_ID_LED_N")
	)
	(segment
		(start 396.601696 -86.791546)
		(end 396.601696 -86.448138)
		(width 0.089408)
		(layer "In9.Cu")
		(net "FP_PWR_ID_LED_N")
	)
	(segment
		(start 398.417288 -83.811364)
		(end 400.6215 -81.607152)
		(width 0.089408)
		(layer "In9.Cu")
		(net "FP_PWR_ID_LED_N")
	)
	(segment
		(start 490.1184 -147.234656)
		(end 490.1184 -154.305)
		(width 0.089408)
		(layer "In9.Cu")
		(net "FP_PWR_ID_LED_N")
	)
	(segment
		(start 408.233626 -67.5767)
		(end 409.606242 -66.204084)
		(width 0.089408)
		(layer "In9.Cu")
		(net "FP_PWR_ID_LED_N")
	)
	(segment
		(start 489.766864 -142.61084)
		(end 489.766864 -146.88312)
		(width 0.089408)
		(layer "In9.Cu")
		(net "FP_PWR_ID_LED_N")
	)
	(segment
		(start 422.58488 -47.292768)
		(end 423.45356 -46.424088)
		(width 0.089408)
		(layer "In9.Cu")
		(net "FP_PWR_ID_LED_N")
	)
	(segment
		(start 401.648676 -76.308204)
		(end 402.496782 -75.460098)
		(width 0.089408)
		(layer "In9.Cu")
		(net "FP_PWR_ID_LED_N")
	)
	(segment
		(start 408.233626 -68.28282)
		(end 408.233626 -67.5767)
		(width 0.089408)
		(layer "In9.Cu")
		(net "FP_PWR_ID_LED_N")
	)
	(segment
		(start 416.763708 -50.276252)
		(end 416.763708 -49.936654)
		(width 0.089408)
		(layer "In9.Cu")
		(net "FP_PWR_ID_LED_N")
	)
	(segment
		(start 416.143948 -50.896012)
		(end 416.763708 -50.276252)
		(width 0.089408)
		(layer "In9.Cu")
		(net "FP_PWR_ID_LED_N")
	)
	(segment
		(start 418.74821 -49.18075)
		(end 419.706044 -49.18075)
		(width 0.089408)
		(layer "In9.Cu")
		(net "FP_PWR_ID_LED_N")
	)
	(segment
		(start 398.413732 -83.811364)
		(end 398.417288 -83.811364)
		(width 0.089408)
		(layer "In9.Cu")
		(net "FP_PWR_ID_LED_N")
	)
	(segment
		(start 402.496782 -74.479404)
		(end 406.888188 -70.087998)
		(width 0.089408)
		(layer "In9.Cu")
		(net "FP_PWR_ID_LED_N")
	)
	(segment
		(start 409.606242 -66.204084)
		(end 409.606242 -61.172344)
		(width 0.089408)
		(layer "In9.Cu")
		(net "FP_PWR_ID_LED_N")
	)
	(segment
		(start 418.46627 -49.46269)
		(end 418.74821 -49.18075)
		(width 0.089408)
		(layer "In9.Cu")
		(net "FP_PWR_ID_LED_N")
	)
	(segment
		(start 416.763708 -49.936654)
		(end 417.237672 -49.46269)
		(width 0.089408)
		(layer "In9.Cu")
		(net "FP_PWR_ID_LED_N")
	)
	(segment
		(start 398.0053 -84.219796)
		(end 398.413732 -83.811364)
		(width 0.089408)
		(layer "In9.Cu")
		(net "FP_PWR_ID_LED_N")
	)
	(segment
		(start 417.237672 -49.46269)
		(end 418.46627 -49.46269)
		(width 0.089408)
		(layer "In9.Cu")
		(net "FP_PWR_ID_LED_N")
	)
	(segment
		(start 495.5286 -135.6106)
		(end 492.897922 -135.6106)
		(width 0.089408)
		(layer "In9.Cu")
		(net "FP_PWR_ID_LED_N")
	)
	(segment
		(start 398.0053 -85.044534)
		(end 398.0053 -84.219796)
		(width 0.089408)
		(layer "In9.Cu")
		(net "FP_PWR_ID_LED_N")
	)
	(segment
		(start 406.888188 -69.628258)
		(end 408.233626 -68.28282)
		(width 0.089408)
		(layer "In9.Cu")
		(net "FP_PWR_ID_LED_N")
	)
	(segment
		(start 401.131532 -79.929228)
		(end 401.131532 -78.547468)
		(width 0.089408)
		(layer "In9.Cu")
		(net "FP_PWR_ID_LED_N")
	)
	(segment
		(start 401.131532 -78.547468)
		(end 401.648676 -78.030324)
		(width 0.089408)
		(layer "In9.Cu")
		(net "FP_PWR_ID_LED_N")
	)
	(segment
		(start 419.706044 -49.18075)
		(end 421.594026 -47.292768)
		(width 0.089408)
		(layer "In9.Cu")
		(net "FP_PWR_ID_LED_N")
	)
	(segment
		(start 421.594026 -47.292768)
		(end 422.58488 -47.292768)
		(width 0.089408)
		(layer "In9.Cu")
		(net "FP_PWR_ID_LED_N")
	)
	(segment
		(start 490.5629 -154.7495)
		(end 491.3249 -154.7495)
		(width 0.089408)
		(layer "In9.Cu")
		(net "FP_PWR_ID_LED_N")
	)
	(segment
		(start 495.7826 -135.8646)
		(end 495.5286 -135.6106)
		(width 0.089408)
		(layer "In9.Cu")
		(net "FP_PWR_ID_LED_N")
	)
	(segment
		(start 492.897922 -135.6106)
		(end 490.1946 -138.313922)
		(width 0.089408)
		(layer "In9.Cu")
		(net "FP_PWR_ID_LED_N")
	)
	(segment
		(start 490.1184 -154.305)
		(end 490.5629 -154.7495)
		(width 0.089408)
		(layer "In9.Cu")
		(net "FP_PWR_ID_LED_N")
	)
	(segment
		(start 490.1946 -142.183104)
		(end 489.766864 -142.61084)
		(width 0.089408)
		(layer "In9.Cu")
		(net "FP_PWR_ID_LED_N")
	)
	(segment
		(start 490.1946 -138.313922)
		(end 490.1946 -142.183104)
		(width 0.089408)
		(layer "In9.Cu")
		(net "FP_PWR_ID_LED_N")
	)
	(segment
		(start 489.766864 -146.88312)
		(end 490.1184 -147.234656)
		(width 0.089408)
		(layer "In9.Cu")
		(net "FP_PWR_ID_LED_N")
	)
	(segment
		(start 423.45356 -46.424088)
		(end 423.45356 -46.3042)
		(width 0.089408)
		(layer "In9.Cu")
		(net "FP_PWR_ID_LED_N")
	)
	(segment
		(start 409.606242 -61.172344)
		(end 409.401264 -60.967366)
		(width 0.089408)
		(layer "In9.Cu")
		(net "FP_PWR_ID_LED_N")
	)
	(segment
		(start 402.496782 -75.460098)
		(end 402.496782 -74.479404)
		(width 0.089408)
		(layer "In9.Cu")
		(net "FP_PWR_ID_LED_N")
	)
	(segment
		(start 396.601696 -86.448138)
		(end 398.0053 -85.044534)
		(width 0.089408)
		(layer "In9.Cu")
		(net "FP_PWR_ID_LED_N")
	)
	(segment
		(start 393.862306 -88.9508)
		(end 393.884404 -88.928702)
		(width 0.089408)
		(layer "In9.Cu")
		(net "FP_PWR_ID_LED_N")
	)
	(segment
		(start 400.6215 -80.43926)
		(end 401.131532 -79.929228)
		(width 0.089408)
		(layer "In9.Cu")
		(net "FP_PWR_ID_LED_N")
	)
	(segment
		(start 401.648676 -78.030324)
		(end 401.648676 -76.308204)
		(width 0.089408)
		(layer "In9.Cu")
		(net "FP_PWR_ID_LED_N")
	)
	(segment
		(start 394.46454 -88.928702)
		(end 396.601696 -86.791546)
		(width 0.089408)
		(layer "In9.Cu")
		(net "FP_PWR_ID_LED_N")
	)
	(segment
		(start 429.98263 -43.369484)
		(end 427.835568 -43.369484)
		(width 0.10795)
		(layer "F.Cu")
		(net "PECI_BMC_R")
	)
	(segment
		(start 426.481748 -42.015664)
		(end 426.236638 -41.770554)
		(width 0.089408)
		(layer "F.Cu")
		(net "PECI_BMC_R")
	)
	(segment
		(start 433.48148 -43.844464)
		(end 430.45761 -43.844464)
		(width 0.089408)
		(layer "F.Cu")
		(net "PECI_BMC_R")
	)
	(segment
		(start 427.835568 -43.369484)
		(end 426.481748 -42.015664)
		(width 0.10795)
		(layer "F.Cu")
		(net "PECI_BMC_R")
	)
	(segment
		(start 430.45761 -43.844464)
		(end 429.98263 -43.369484)
		(width 0.089408)
		(layer "F.Cu")
		(net "PECI_BMC_R")
	)
	(segment
		(start 424.600624 -40.13454)
		(end 423.890186 -40.13454)
		(width 0.089408)
		(layer "F.Cu")
		(net "PECI_BMC_R")
	)
	(segment
		(start 426.236638 -41.770554)
		(end 424.600624 -40.13454)
		(width 0.089408)
		(layer "F.Cu")
		(net "PECI_BMC_R")
	)
	(via
		(at 426.236638 -41.770554)
		(size 0.508)
		(drill 0.254)
		(layers "F.Cu" "B.Cu")
		(net "PECI_BMC_R")
	)
	(segment
		(start 414.290256 -28.134564)
		(end 414.68421 -27.74061)
		(width 0.10795)
		(layer "F.Cu")
		(net "PD_SP_ENTEST")
	)
	(via
		(at 414.229804 -22.374098)
		(size 0.508)
		(drill 0.254)
		(layers "F.Cu" "B.Cu")
		(net "PD_SP_ENTEST")
	)
	(via
		(at 414.68421 -27.74061)
		(size 0.4572)
		(drill 0.2032)
		(layers "F.Cu" "B.Cu")
		(net "PD_SP_ENTEST")
	)
	(segment
		(start 413.893 -20.9296)
		(end 413.639 -20.6756)
		(width 0.10795)
		(layer "B.Cu")
		(net "PD_SP_ENTEST")
	)
	(segment
		(start 413.893 -22.037294)
		(end 413.893 -20.9296)
		(width 0.10795)
		(layer "B.Cu")
		(net "PD_SP_ENTEST")
	)
	(segment
		(start 413.639 -20.6756)
		(end 413.639 -20.3962)
		(width 0.10795)
		(layer "B.Cu")
		(net "PD_SP_ENTEST")
	)
	(segment
		(start 414.229804 -22.374098)
		(end 413.893 -22.037294)
		(width 0.10795)
		(layer "B.Cu")
		(net "PD_SP_ENTEST")
	)
	(segment
		(start 415.078418 -27.346402)
		(end 415.078418 -23.222712)
		(width 0.089408)
		(layer "In9.Cu")
		(net "PD_SP_ENTEST")
	)
	(segment
		(start 415.078418 -23.222712)
		(end 414.229804 -22.374098)
		(width 0.089408)
		(layer "In9.Cu")
		(net "PD_SP_ENTEST")
	)
	(segment
		(start 414.68421 -27.74061)
		(end 415.078418 -27.346402)
		(width 0.089408)
		(layer "In9.Cu")
		(net "PD_SP_ENTEST")
	)
	(segment
		(start 414.290256 -28.934664)
		(end 413.890206 -29.334714)
		(width 0.254)
		(layer "F.Cu")
		(net "A_DACRSET")
	)
	(via
		(at 413.890206 -29.334714)
		(size 0.4572)
		(drill 0.2032)
		(layers "F.Cu" "B.Cu")
		(net "A_DACRSET")
	)
	(via
		(at 423.037 -20.7264)
		(size 0.508)
		(drill 0.254)
		(layers "F.Cu" "B.Cu")
		(net "A_DACRSET")
	)
	(via
		(at 422.1734 -21.59)
		(size 0.6604)
		(drill 0.3302)
		(layers "F.Cu" "B.Cu")
		(net "A_DACRSET")
	)
	(segment
		(start 423.2275 -21.59)
		(end 423.037 -21.3995)
		(width 0.254)
		(layer "B.Cu")
		(net "A_DACRSET")
	)
	(segment
		(start 423.037 -21.3995)
		(end 423.037 -20.7264)
		(width 0.254)
		(layer "B.Cu")
		(net "A_DACRSET")
	)
	(segment
		(start 423.2275 -21.59)
		(end 422.1734 -21.59)
		(width 0.254)
		(layer "B.Cu")
		(net "A_DACRSET")
	)
	(segment
		(start 414.284922 -28.939998)
		(end 415.052002 -28.939998)
		(width 0.1016)
		(layer "In11.Cu")
		(net "A_DACRSET")
	)
	(segment
		(start 415.544 -26.797)
		(end 421.132 -21.209)
		(width 0.254)
		(layer "In11.Cu")
		(net "A_DACRSET")
	)
	(segment
		(start 413.890206 -29.334714)
		(end 414.284922 -28.939998)
		(width 0.1016)
		(layer "In11.Cu")
		(net "A_DACRSET")
	)
	(segment
		(start 415.544 -28.448)
		(end 415.544 -26.797)
		(width 0.254)
		(layer "In11.Cu")
		(net "A_DACRSET")
	)
	(segment
		(start 415.163 -28.829)
		(end 415.544 -28.448)
		(width 0.254)
		(layer "In11.Cu")
		(net "A_DACRSET")
	)
	(segment
		(start 415.052002 -28.939998)
		(end 415.163 -28.829)
		(width 0.1016)
		(layer "In11.Cu")
		(net "A_DACRSET")
	)
	(segment
		(start 421.132 -21.209)
		(end 422.783 -21.209)
		(width 0.254)
		(layer "In11.Cu")
		(net "A_DACRSET")
	)
	(segment
		(start 422.783 -21.209)
		(end 423.037 -20.955)
		(width 0.254)
		(layer "In11.Cu")
		(net "A_DACRSET")
	)
	(segment
		(start 423.037 -20.955)
		(end 423.037 -20.7264)
		(width 0.254)
		(layer "In11.Cu")
		(net "A_DACRSET")
	)
	(segment
		(start 409.490164 -31.33471)
		(end 409.090114 -30.93466)
		(width 0.10795)
		(layer "F.Cu")
		(net "TP_RGMII1TXD3_GPIOT5")
	)
	(via
		(at 409.090114 -30.93466)
		(size 0.4572)
		(drill 0.2032)
		(layers "F.Cu" "B.Cu")
		(net "TP_RGMII1TXD3_GPIOT5")
	)
	(segment
		(start 408.833066 -30.93466)
		(end 409.090114 -30.93466)
		(width 0.10795)
		(layer "B.Cu")
		(net "TP_RGMII1TXD3_GPIOT5")
	)
	(segment
		(start 407.901902 -31.0896)
		(end 408.13101 -31.318708)
		(width 0.10795)
		(layer "B.Cu")
		(net "TP_RGMII1TXD3_GPIOT5")
	)
	(segment
		(start 405.5618 -30.861)
		(end 405.7904 -31.0896)
		(width 0.10795)
		(layer "B.Cu")
		(net "TP_RGMII1TXD3_GPIOT5")
	)
	(segment
		(start 408.449018 -31.318708)
		(end 408.833066 -30.93466)
		(width 0.10795)
		(layer "B.Cu")
		(net "TP_RGMII1TXD3_GPIOT5")
	)
	(segment
		(start 405.7904 -31.0896)
		(end 407.901902 -31.0896)
		(width 0.10795)
		(layer "B.Cu")
		(net "TP_RGMII1TXD3_GPIOT5")
	)
	(segment
		(start 408.13101 -31.318708)
		(end 408.449018 -31.318708)
		(width 0.10795)
		(layer "B.Cu")
		(net "TP_RGMII1TXD3_GPIOT5")
	)
	(segment
		(start 405.2062 -30.861)
		(end 405.5618 -30.861)
		(width 0.10795)
		(layer "B.Cu")
		(net "TP_RGMII1TXD3_GPIOT5")
	)
	(segment
		(start 410.290264 -31.33471)
		(end 409.890214 -30.93466)
		(width 0.089408)
		(layer "F.Cu")
		(net "TP_RGMII1TXD2_GPIOT4")
	)
	(via
		(at 409.890214 -30.93466)
		(size 0.4572)
		(drill 0.2032)
		(layers "F.Cu" "B.Cu")
		(net "TP_RGMII1TXD2_GPIOT4")
	)
	(via
		(at 406.013158 -30.2006)
		(size 0.508)
		(drill 0.254)
		(layers "F.Cu" "B.Cu")
		(net "TP_RGMII1TXD2_GPIOT4")
	)
	(segment
		(start 409.890214 -30.93466)
		(end 409.506166 -30.550612)
		(width 0.10795)
		(layer "B.Cu")
		(net "TP_RGMII1TXD2_GPIOT4")
	)
	(segment
		(start 407.766012 -30.550612)
		(end 407.5176 -30.3022)
		(width 0.10795)
		(layer "B.Cu")
		(net "TP_RGMII1TXD2_GPIOT4")
	)
	(segment
		(start 405.638 -30.2006)
		(end 406.013158 -30.2006)
		(width 0.10795)
		(layer "B.Cu")
		(net "TP_RGMII1TXD2_GPIOT4")
	)
	(segment
		(start 405.5364 -30.099)
		(end 405.638 -30.2006)
		(width 0.10795)
		(layer "B.Cu")
		(net "TP_RGMII1TXD2_GPIOT4")
	)
	(segment
		(start 406.013158 -30.2006)
		(end 406.993598 -30.2006)
		(width 0.10795)
		(layer "B.Cu")
		(net "TP_RGMII1TXD2_GPIOT4")
	)
	(segment
		(start 409.506166 -30.550612)
		(end 407.766012 -30.550612)
		(width 0.10795)
		(layer "B.Cu")
		(net "TP_RGMII1TXD2_GPIOT4")
	)
	(segment
		(start 405.1935 -30.099)
		(end 405.5364 -30.099)
		(width 0.10795)
		(layer "B.Cu")
		(net "TP_RGMII1TXD2_GPIOT4")
	)
	(segment
		(start 406.993598 -30.2006)
		(end 407.095198 -30.3022)
		(width 0.10795)
		(layer "B.Cu")
		(net "TP_RGMII1TXD2_GPIOT4")
	)
	(segment
		(start 407.095198 -30.3022)
		(end 407.5176 -30.3022)
		(width 0.10795)
		(layer "B.Cu")
		(net "TP_RGMII1TXD2_GPIOT4")
	)
	(segment
		(start 423.461688 -42.906188)
		(end 423.090086 -42.534586)
		(width 0.10795)
		(layer "F.Cu")
		(net "IRQ_BMC_PCH_SCI_LPC_N")
	)
	(segment
		(start 424.71848 -48.26)
		(end 424.71848 -50.520346)
		(width 0.10795)
		(layer "F.Cu")
		(net "IRQ_BMC_PCH_SCI_LPC_N")
	)
	(segment
		(start 406.3492 -112.2426)
		(end 406.22728 -112.2426)
		(width 0.10795)
		(layer "F.Cu")
		(net "IRQ_BMC_PCH_SCI_LPC_N")
	)
	(segment
		(start 409.494482 -112.426242)
		(end 408.813 -111.74476)
		(width 0.10795)
		(layer "F.Cu")
		(net "IRQ_BMC_PCH_SCI_LPC_N")
	)
	(segment
		(start 409.494482 -112.426242)
		(end 409.525724 -112.395)
		(width 0.10795)
		(layer "F.Cu")
		(net "IRQ_BMC_PCH_SCI_LPC_N")
	)
	(segment
		(start 424.71848 -50.520346)
		(end 425.1452 -50.947066)
		(width 0.10795)
		(layer "F.Cu")
		(net "IRQ_BMC_PCH_SCI_LPC_N")
	)
	(segment
		(start 424.71848 -48.26)
		(end 424.71848 -47.89932)
		(width 0.10795)
		(layer "F.Cu")
		(net "IRQ_BMC_PCH_SCI_LPC_N")
	)
	(segment
		(start 402.988272 -110.888272)
		(end 402.455126 -110.355126)
		(width 0.0889)
		(layer "F.Cu")
		(net "IRQ_BMC_PCH_SCI_LPC_N")
	)
	(segment
		(start 423.461688 -43.563794)
		(end 423.461688 -42.906188)
		(width 0.10795)
		(layer "F.Cu")
		(net "IRQ_BMC_PCH_SCI_LPC_N")
	)
	(segment
		(start 408.813 -111.74476)
		(end 406.84704 -111.74476)
		(width 0.10795)
		(layer "F.Cu")
		(net "IRQ_BMC_PCH_SCI_LPC_N")
	)
	(segment
		(start 424.71848 -47.89932)
		(end 425.0182 -47.5996)
		(width 0.10795)
		(layer "F.Cu")
		(net "IRQ_BMC_PCH_SCI_LPC_N")
	)
	(segment
		(start 406.22728 -112.2426)
		(end 405.920448 -112.2426)
		(width 0.10795)
		(layer "F.Cu")
		(net "IRQ_BMC_PCH_SCI_LPC_N")
	)
	(segment
		(start 425.0182 -46.156118)
		(end 423.342054 -44.479972)
		(width 0.10795)
		(layer "F.Cu")
		(net "IRQ_BMC_PCH_SCI_LPC_N")
	)
	(segment
		(start 423.342054 -44.479972)
		(end 423.342054 -43.683428)
		(width 0.10795)
		(layer "F.Cu")
		(net "IRQ_BMC_PCH_SCI_LPC_N")
	)
	(segment
		(start 404.56612 -110.888272)
		(end 403.337268 -110.888272)
		(width 0.10795)
		(layer "F.Cu")
		(net "IRQ_BMC_PCH_SCI_LPC_N")
	)
	(segment
		(start 425.0182 -47.5996)
		(end 425.0182 -46.156118)
		(width 0.10795)
		(layer "F.Cu")
		(net "IRQ_BMC_PCH_SCI_LPC_N")
	)
	(segment
		(start 398.13865 -115.00612)
		(end 398.63395 -115.236244)
		(width 0.10795)
		(layer "F.Cu")
		(net "IRQ_BMC_PCH_SCI_LPC_N")
	)
	(segment
		(start 425.1452 -50.947066)
		(end 425.1452 -51.07178)
		(width 0.10795)
		(layer "F.Cu")
		(net "IRQ_BMC_PCH_SCI_LPC_N")
	)
	(segment
		(start 405.920448 -112.2426)
		(end 404.56612 -110.888272)
		(width 0.10795)
		(layer "F.Cu")
		(net "IRQ_BMC_PCH_SCI_LPC_N")
	)
	(segment
		(start 403.337268 -110.888272)
		(end 402.988272 -110.888272)
		(width 0.0889)
		(layer "F.Cu")
		(net "IRQ_BMC_PCH_SCI_LPC_N")
	)
	(segment
		(start 423.342054 -43.683428)
		(end 423.461688 -43.563794)
		(width 0.10795)
		(layer "F.Cu")
		(net "IRQ_BMC_PCH_SCI_LPC_N")
	)
	(segment
		(start 406.84704 -111.74476)
		(end 406.3492 -112.2426)
		(width 0.10795)
		(layer "F.Cu")
		(net "IRQ_BMC_PCH_SCI_LPC_N")
	)
	(segment
		(start 402.455126 -110.355126)
		(end 400.880072 -110.355126)
		(width 0.0889)
		(layer "F.Cu")
		(net "IRQ_BMC_PCH_SCI_LPC_N")
	)
	(segment
		(start 409.525724 -112.395)
		(end 410.1465 -112.395)
		(width 0.10795)
		(layer "F.Cu")
		(net "IRQ_BMC_PCH_SCI_LPC_N")
	)
	(via
		(at 413.264096 -64.360298)
		(size 0.508)
		(drill 0.254)
		(layers "F.Cu" "B.Cu")
		(net "IRQ_BMC_PCH_SCI_LPC_N")
	)
	(via
		(at 406.22728 -112.2426)
		(size 0.762)
		(drill 0.381)
		(layers "F.Cu" "B.Cu")
		(net "IRQ_BMC_PCH_SCI_LPC_N")
	)
	(via
		(at 409.494482 -112.426242)
		(size 0.508)
		(drill 0.254)
		(layers "F.Cu" "B.Cu")
		(net "IRQ_BMC_PCH_SCI_LPC_N")
	)
	(via
		(at 398.63395 -115.236244)
		(size 0.508)
		(drill 0.254)
		(layers "F.Cu" "B.Cu")
		(net "IRQ_BMC_PCH_SCI_LPC_N")
	)
	(via
		(at 424.71848 -48.26)
		(size 0.762)
		(drill 0.381)
		(layers "F.Cu" "B.Cu")
		(net "IRQ_BMC_PCH_SCI_LPC_N")
	)
	(via
		(at 425.1452 -51.07178)
		(size 0.508)
		(drill 0.254)
		(layers "F.Cu" "B.Cu")
		(net "IRQ_BMC_PCH_SCI_LPC_N")
	)
	(segment
		(start 411.4038 -104.445054)
		(end 410.630878 -105.217976)
		(width 0.089408)
		(layer "In2.Cu")
		(net "IRQ_BMC_PCH_SCI_LPC_N")
	)
	(segment
		(start 410.6418 -102.6668)
		(end 411.4038 -103.4288)
		(width 0.089408)
		(layer "In2.Cu")
		(net "IRQ_BMC_PCH_SCI_LPC_N")
	)
	(segment
		(start 412.84652 -65.659)
		(end 411.961838 -66.543682)
		(width 0.089408)
		(layer "In2.Cu")
		(net "IRQ_BMC_PCH_SCI_LPC_N")
	)
	(segment
		(start 409.512262 -87.439754)
		(end 410.5402 -88.467692)
		(width 0.089408)
		(layer "In2.Cu")
		(net "IRQ_BMC_PCH_SCI_LPC_N")
	)
	(segment
		(start 411.634432 -68.90639)
		(end 411.634432 -69.600064)
		(width 0.089408)
		(layer "In2.Cu")
		(net "IRQ_BMC_PCH_SCI_LPC_N")
	)
	(segment
		(start 411.962092 -68.57873)
		(end 411.634432 -68.90639)
		(width 0.089408)
		(layer "In2.Cu")
		(net "IRQ_BMC_PCH_SCI_LPC_N")
	)
	(segment
		(start 406.019 -78.65364)
		(end 406.019 -79.886048)
		(width 0.089408)
		(layer "In2.Cu")
		(net "IRQ_BMC_PCH_SCI_LPC_N")
	)
	(segment
		(start 410.630878 -110.934754)
		(end 410.40685 -111.158782)
		(width 0.089408)
		(layer "In2.Cu")
		(net "IRQ_BMC_PCH_SCI_LPC_N")
	)
	(segment
		(start 413.264096 -64.360298)
		(end 412.84652 -64.777874)
		(width 0.089408)
		(layer "In2.Cu")
		(net "IRQ_BMC_PCH_SCI_LPC_N")
	)
	(segment
		(start 407.250392 -81.11744)
		(end 409.03144 -81.11744)
		(width 0.089408)
		(layer "In2.Cu")
		(net "IRQ_BMC_PCH_SCI_LPC_N")
	)
	(segment
		(start 411.961838 -66.543682)
		(end 411.961838 -67.628008)
		(width 0.089408)
		(layer "In2.Cu")
		(net "IRQ_BMC_PCH_SCI_LPC_N")
	)
	(segment
		(start 412.84652 -64.777874)
		(end 412.84652 -65.659)
		(width 0.089408)
		(layer "In2.Cu")
		(net "IRQ_BMC_PCH_SCI_LPC_N")
	)
	(segment
		(start 410.332174 -70.800722)
		(end 405.58466 -75.548236)
		(width 0.089408)
		(layer "In2.Cu")
		(net "IRQ_BMC_PCH_SCI_LPC_N")
	)
	(segment
		(start 411.961838 -67.628008)
		(end 411.962092 -67.628262)
		(width 0.089408)
		(layer "In2.Cu")
		(net "IRQ_BMC_PCH_SCI_LPC_N")
	)
	(segment
		(start 409.512262 -81.598262)
		(end 409.512262 -81.647792)
		(width 0.089408)
		(layer "In2.Cu")
		(net "IRQ_BMC_PCH_SCI_LPC_N")
	)
	(segment
		(start 406.019 -79.886048)
		(end 407.250392 -81.11744)
		(width 0.089408)
		(layer "In2.Cu")
		(net "IRQ_BMC_PCH_SCI_LPC_N")
	)
	(segment
		(start 411.634432 -69.600064)
		(end 411.634686 -69.600318)
		(width 0.089408)
		(layer "In2.Cu")
		(net "IRQ_BMC_PCH_SCI_LPC_N")
	)
	(segment
		(start 405.58466 -78.2193)
		(end 406.019 -78.65364)
		(width 0.089408)
		(layer "In2.Cu")
		(net "IRQ_BMC_PCH_SCI_LPC_N")
	)
	(segment
		(start 411.634686 -69.600318)
		(end 411.634686 -69.916802)
		(width 0.089408)
		(layer "In2.Cu")
		(net "IRQ_BMC_PCH_SCI_LPC_N")
	)
	(segment
		(start 411.962092 -67.628262)
		(end 411.962092 -68.57873)
		(width 0.089408)
		(layer "In2.Cu")
		(net "IRQ_BMC_PCH_SCI_LPC_N")
	)
	(segment
		(start 411.4038 -103.4288)
		(end 411.4038 -104.445054)
		(width 0.089408)
		(layer "In2.Cu")
		(net "IRQ_BMC_PCH_SCI_LPC_N")
	)
	(segment
		(start 410.750766 -70.800722)
		(end 410.332174 -70.800722)
		(width 0.089408)
		(layer "In2.Cu")
		(net "IRQ_BMC_PCH_SCI_LPC_N")
	)
	(segment
		(start 409.03144 -81.11744)
		(end 409.512262 -81.598262)
		(width 0.089408)
		(layer "In2.Cu")
		(net "IRQ_BMC_PCH_SCI_LPC_N")
	)
	(segment
		(start 411.634686 -69.916802)
		(end 410.750766 -70.800722)
		(width 0.089408)
		(layer "In2.Cu")
		(net "IRQ_BMC_PCH_SCI_LPC_N")
	)
	(segment
		(start 410.5402 -88.467692)
		(end 410.5402 -97.811082)
		(width 0.089408)
		(layer "In2.Cu")
		(net "IRQ_BMC_PCH_SCI_LPC_N")
	)
	(segment
		(start 405.58466 -75.548236)
		(end 405.58466 -78.2193)
		(width 0.089408)
		(layer "In2.Cu")
		(net "IRQ_BMC_PCH_SCI_LPC_N")
	)
	(segment
		(start 410.5402 -97.811082)
		(end 410.6418 -97.912682)
		(width 0.089408)
		(layer "In2.Cu")
		(net "IRQ_BMC_PCH_SCI_LPC_N")
	)
	(segment
		(start 409.512262 -81.647792)
		(end 409.512516 -81.648046)
		(width 0.089408)
		(layer "In2.Cu")
		(net "IRQ_BMC_PCH_SCI_LPC_N")
	)
	(segment
		(start 409.512516 -81.648046)
		(end 409.512516 -81.806034)
		(width 0.089408)
		(layer "In2.Cu")
		(net "IRQ_BMC_PCH_SCI_LPC_N")
	)
	(segment
		(start 410.630878 -105.217976)
		(end 410.630878 -110.934754)
		(width 0.089408)
		(layer "In2.Cu")
		(net "IRQ_BMC_PCH_SCI_LPC_N")
	)
	(segment
		(start 410.40685 -111.513874)
		(end 409.494482 -112.426242)
		(width 0.089408)
		(layer "In2.Cu")
		(net "IRQ_BMC_PCH_SCI_LPC_N")
	)
	(segment
		(start 409.512516 -81.806034)
		(end 409.512262 -81.806288)
		(width 0.089408)
		(layer "In2.Cu")
		(net "IRQ_BMC_PCH_SCI_LPC_N")
	)
	(segment
		(start 409.512262 -81.806288)
		(end 409.512262 -87.439754)
		(width 0.089408)
		(layer "In2.Cu")
		(net "IRQ_BMC_PCH_SCI_LPC_N")
	)
	(segment
		(start 410.40685 -111.158782)
		(end 410.40685 -111.513874)
		(width 0.089408)
		(layer "In2.Cu")
		(net "IRQ_BMC_PCH_SCI_LPC_N")
	)
	(segment
		(start 410.6418 -97.912682)
		(end 410.6418 -102.6668)
		(width 0.089408)
		(layer "In2.Cu")
		(net "IRQ_BMC_PCH_SCI_LPC_N")
	)
	(segment
		(start 409.494482 -112.426242)
		(end 405.453088 -116.467636)
		(width 0.0889)
		(layer "In4.Cu")
		(net "IRQ_BMC_PCH_SCI_LPC_N")
	)
	(segment
		(start 399.093944 -115.696238)
		(end 398.63395 -115.236244)
		(width 0.0889)
		(layer "In4.Cu")
		(net "IRQ_BMC_PCH_SCI_LPC_N")
	)
	(segment
		(start 405.453088 -116.467636)
		(end 400.065748 -116.467636)
		(width 0.0889)
		(layer "In4.Cu")
		(net "IRQ_BMC_PCH_SCI_LPC_N")
	)
	(segment
		(start 399.29435 -115.696238)
		(end 399.093944 -115.696238)
		(width 0.0889)
		(layer "In4.Cu")
		(net "IRQ_BMC_PCH_SCI_LPC_N")
	)
	(segment
		(start 400.065748 -116.467636)
		(end 399.29435 -115.696238)
		(width 0.0889)
		(layer "In4.Cu")
		(net "IRQ_BMC_PCH_SCI_LPC_N")
	)
	(segment
		(start 419.227 -53.2638)
		(end 419.21938 -53.2638)
		(width 0.089408)
		(layer "In9.Cu")
		(net "IRQ_BMC_PCH_SCI_LPC_N")
	)
	(segment
		(start 414.291272 -60.702444)
		(end 414.291272 -61.318648)
		(width 0.089408)
		(layer "In9.Cu")
		(net "IRQ_BMC_PCH_SCI_LPC_N")
	)
	(segment
		(start 419.152832 -53.330348)
		(end 417.712652 -53.330348)
		(width 0.089408)
		(layer "In9.Cu")
		(net "IRQ_BMC_PCH_SCI_LPC_N")
	)
	(segment
		(start 414.1343 -60.545472)
		(end 414.291272 -60.702444)
		(width 0.089408)
		(layer "In9.Cu")
		(net "IRQ_BMC_PCH_SCI_LPC_N")
	)
	(segment
		(start 417.712652 -53.330348)
		(end 416.522408 -54.520592)
		(width 0.089408)
		(layer "In9.Cu")
		(net "IRQ_BMC_PCH_SCI_LPC_N")
	)
	(segment
		(start 422.8084 -52.2224)
		(end 420.2684 -52.2224)
		(width 0.089408)
		(layer "In9.Cu")
		(net "IRQ_BMC_PCH_SCI_LPC_N")
	)
	(segment
		(start 423.95902 -51.07178)
		(end 422.8084 -52.2224)
		(width 0.089408)
		(layer "In9.Cu")
		(net "IRQ_BMC_PCH_SCI_LPC_N")
	)
	(segment
		(start 416.522408 -54.520592)
		(end 416.522408 -55.185564)
		(width 0.089408)
		(layer "In9.Cu")
		(net "IRQ_BMC_PCH_SCI_LPC_N")
	)
	(segment
		(start 414.291272 -61.318648)
		(end 413.107632 -62.502288)
		(width 0.089408)
		(layer "In9.Cu")
		(net "IRQ_BMC_PCH_SCI_LPC_N")
	)
	(segment
		(start 413.107632 -64.203834)
		(end 413.264096 -64.360298)
		(width 0.089408)
		(layer "In9.Cu")
		(net "IRQ_BMC_PCH_SCI_LPC_N")
	)
	(segment
		(start 413.107632 -62.502288)
		(end 413.107632 -64.203834)
		(width 0.089408)
		(layer "In9.Cu")
		(net "IRQ_BMC_PCH_SCI_LPC_N")
	)
	(segment
		(start 414.838388 -56.869584)
		(end 414.39465 -56.869584)
		(width 0.089408)
		(layer "In9.Cu")
		(net "IRQ_BMC_PCH_SCI_LPC_N")
	)
	(segment
		(start 414.1343 -57.129934)
		(end 414.1343 -60.545472)
		(width 0.089408)
		(layer "In9.Cu")
		(net "IRQ_BMC_PCH_SCI_LPC_N")
	)
	(segment
		(start 414.39465 -56.869584)
		(end 414.1343 -57.129934)
		(width 0.089408)
		(layer "In9.Cu")
		(net "IRQ_BMC_PCH_SCI_LPC_N")
	)
	(segment
		(start 416.522408 -55.185564)
		(end 414.838388 -56.869584)
		(width 0.089408)
		(layer "In9.Cu")
		(net "IRQ_BMC_PCH_SCI_LPC_N")
	)
	(segment
		(start 419.21938 -53.2638)
		(end 419.152832 -53.330348)
		(width 0.089408)
		(layer "In9.Cu")
		(net "IRQ_BMC_PCH_SCI_LPC_N")
	)
	(segment
		(start 425.1452 -51.07178)
		(end 423.95902 -51.07178)
		(width 0.089408)
		(layer "In9.Cu")
		(net "IRQ_BMC_PCH_SCI_LPC_N")
	)
	(segment
		(start 420.2684 -52.2224)
		(end 419.227 -53.2638)
		(width 0.089408)
		(layer "In9.Cu")
		(net "IRQ_BMC_PCH_SCI_LPC_N")
	)
	(via
		(at 430.2506 -18.6182)
		(size 0.508)
		(drill 0.254)
		(layers "F.Cu" "B.Cu")
		(net "H_CPU1_MEMKLM_MEMHOT_LVT3_N")
	)
	(via
		(at 431.83302 -19.7358)
		(size 0.6604)
		(drill 0.3302)
		(layers "F.Cu" "B.Cu")
		(net "H_CPU1_MEMKLM_MEMHOT_LVT3_N")
	)
	(via
		(at 416.7886 -16.9926)
		(size 0.508)
		(drill 0.254)
		(layers "F.Cu" "B.Cu")
		(net "H_CPU1_MEMKLM_MEMHOT_LVT3_N")
	)
	(segment
		(start 416.465258 -17.798796)
		(end 416.7886 -17.475454)
		(width 0.10795)
		(layer "B.Cu")
		(net "H_CPU1_MEMKLM_MEMHOT_LVT3_N")
	)
	(segment
		(start 431.424334 -19.327114)
		(end 430.85766 -19.327114)
		(width 0.10795)
		(layer "B.Cu")
		(net "H_CPU1_MEMKLM_MEMHOT_LVT3_N")
	)
	(segment
		(start 430.2506 -18.720054)
		(end 430.2506 -18.6182)
		(width 0.10795)
		(layer "B.Cu")
		(net "H_CPU1_MEMKLM_MEMHOT_LVT3_N")
	)
	(segment
		(start 416.7886 -17.475454)
		(end 416.7886 -16.9926)
		(width 0.10795)
		(layer "B.Cu")
		(net "H_CPU1_MEMKLM_MEMHOT_LVT3_N")
	)
	(segment
		(start 413.5755 -17.526)
		(end 413.5755 -18.288)
		(width 0.10795)
		(layer "B.Cu")
		(net "H_CPU1_MEMKLM_MEMHOT_LVT3_N")
	)
	(segment
		(start 433.7685 -18.9357)
		(end 433.7685 -18.288)
		(width 0.10795)
		(layer "B.Cu")
		(net "H_CPU1_MEMKLM_MEMHOT_LVT3_N")
	)
	(segment
		(start 413.5755 -17.526)
		(end 414.043368 -17.526)
		(width 0.10795)
		(layer "B.Cu")
		(net "H_CPU1_MEMKLM_MEMHOT_LVT3_N")
	)
	(segment
		(start 414.316164 -17.798796)
		(end 416.465258 -17.798796)
		(width 0.10795)
		(layer "B.Cu")
		(net "H_CPU1_MEMKLM_MEMHOT_LVT3_N")
	)
	(segment
		(start 430.85766 -19.327114)
		(end 430.2506 -18.720054)
		(width 0.10795)
		(layer "B.Cu")
		(net "H_CPU1_MEMKLM_MEMHOT_LVT3_N")
	)
	(segment
		(start 431.83302 -19.7358)
		(end 431.424334 -19.327114)
		(width 0.10795)
		(layer "B.Cu")
		(net "H_CPU1_MEMKLM_MEMHOT_LVT3_N")
	)
	(segment
		(start 432.9684 -19.7358)
		(end 433.7685 -18.9357)
		(width 0.10795)
		(layer "B.Cu")
		(net "H_CPU1_MEMKLM_MEMHOT_LVT3_N")
	)
	(segment
		(start 431.83302 -19.7358)
		(end 432.9684 -19.7358)
		(width 0.10795)
		(layer "B.Cu")
		(net "H_CPU1_MEMKLM_MEMHOT_LVT3_N")
	)
	(segment
		(start 414.043368 -17.526)
		(end 414.316164 -17.798796)
		(width 0.10795)
		(layer "B.Cu")
		(net "H_CPU1_MEMKLM_MEMHOT_LVT3_N")
	)
	(segment
		(start 427.07052 -18.177764)
		(end 423.85615 -18.177764)
		(width 0.089408)
		(layer "In9.Cu")
		(net "H_CPU1_MEMKLM_MEMHOT_LVT3_N")
	)
	(segment
		(start 417.166044 -17.370044)
		(end 416.7886 -16.9926)
		(width 0.089408)
		(layer "In9.Cu")
		(net "H_CPU1_MEMKLM_MEMHOT_LVT3_N")
	)
	(segment
		(start 423.04843 -17.370044)
		(end 417.166044 -17.370044)
		(width 0.089408)
		(layer "In9.Cu")
		(net "H_CPU1_MEMKLM_MEMHOT_LVT3_N")
	)
	(segment
		(start 428.791116 -19.323304)
		(end 427.799246 -18.331434)
		(width 0.089408)
		(layer "In9.Cu")
		(net "H_CPU1_MEMKLM_MEMHOT_LVT3_N")
	)
	(segment
		(start 427.799246 -18.331434)
		(end 427.56328 -18.28165)
		(width 0.089408)
		(layer "In9.Cu")
		(net "H_CPU1_MEMKLM_MEMHOT_LVT3_N")
	)
	(segment
		(start 423.85615 -18.177764)
		(end 423.04843 -17.370044)
		(width 0.089408)
		(layer "In9.Cu")
		(net "H_CPU1_MEMKLM_MEMHOT_LVT3_N")
	)
	(segment
		(start 427.56328 -18.28165)
		(end 427.07052 -18.177764)
		(width 0.089408)
		(layer "In9.Cu")
		(net "H_CPU1_MEMKLM_MEMHOT_LVT3_N")
	)
	(segment
		(start 430.2506 -18.6182)
		(end 429.545496 -19.323304)
		(width 0.089408)
		(layer "In9.Cu")
		(net "H_CPU1_MEMKLM_MEMHOT_LVT3_N")
	)
	(segment
		(start 429.545496 -19.323304)
		(end 428.791116 -19.323304)
		(width 0.089408)
		(layer "In9.Cu")
		(net "H_CPU1_MEMKLM_MEMHOT_LVT3_N")
	)
	(via
		(at 390.704324 -77.150214)
		(size 0.508)
		(drill 0.254)
		(layers "F.Cu" "B.Cu")
		(net "H_CPU1_MEMGHJ_MEMHOT_LVT3_N")
	)
	(via
		(at 389.14832 -78.94828)
		(size 0.6604)
		(drill 0.3302)
		(layers "F.Cu" "B.Cu")
		(net "H_CPU1_MEMGHJ_MEMHOT_LVT3_N")
	)
	(via
		(at 422.037002 -18.295112)
		(size 0.508)
		(drill 0.254)
		(layers "F.Cu" "B.Cu")
		(net "H_CPU1_MEMGHJ_MEMHOT_LVT3_N")
	)
	(segment
		(start 425.8056 -16.764)
		(end 426.263054 -16.764)
		(width 0.10795)
		(layer "B.Cu")
		(net "H_CPU1_MEMGHJ_MEMHOT_LVT3_N")
	)
	(segment
		(start 422.942258 -16.9545)
		(end 425.069 -16.9545)
		(width 0.10795)
		(layer "B.Cu")
		(net "H_CPU1_MEMGHJ_MEMHOT_LVT3_N")
	)
	(segment
		(start 425.069 -16.9545)
		(end 425.2595 -16.764)
		(width 0.10795)
		(layer "B.Cu")
		(net "H_CPU1_MEMGHJ_MEMHOT_LVT3_N")
	)
	(segment
		(start 389.14832 -78.94828)
		(end 389.14832 -79.21752)
		(width 0.10795)
		(layer "B.Cu")
		(net "H_CPU1_MEMGHJ_MEMHOT_LVT3_N")
	)
	(segment
		(start 426.263054 -16.764)
		(end 426.98416 -16.042894)
		(width 0.10795)
		(layer "B.Cu")
		(net "H_CPU1_MEMGHJ_MEMHOT_LVT3_N")
	)
	(segment
		(start 389.14832 -78.66888)
		(end 389.14832 -78.94828)
		(width 0.10795)
		(layer "B.Cu")
		(net "H_CPU1_MEMGHJ_MEMHOT_LVT3_N")
	)
	(segment
		(start 426.98416 -16.042894)
		(end 428.157894 -16.042894)
		(width 0.10795)
		(layer "B.Cu")
		(net "H_CPU1_MEMGHJ_MEMHOT_LVT3_N")
	)
	(segment
		(start 389.8138 -78.0034)
		(end 389.14832 -78.66888)
		(width 0.10795)
		(layer "B.Cu")
		(net "H_CPU1_MEMGHJ_MEMHOT_LVT3_N")
	)
	(segment
		(start 422.061132 -17.835626)
		(end 422.942258 -16.9545)
		(width 0.10795)
		(layer "B.Cu")
		(net "H_CPU1_MEMGHJ_MEMHOT_LVT3_N")
	)
	(segment
		(start 389.14832 -79.21752)
		(end 388.66064 -79.7052)
		(width 0.10795)
		(layer "B.Cu")
		(net "H_CPU1_MEMGHJ_MEMHOT_LVT3_N")
	)
	(segment
		(start 422.037002 -18.295112)
		(end 422.061132 -18.295112)
		(width 0.10795)
		(layer "B.Cu")
		(net "H_CPU1_MEMGHJ_MEMHOT_LVT3_N")
	)
	(segment
		(start 390.3726 -78.0034)
		(end 389.8138 -78.0034)
		(width 0.10795)
		(layer "B.Cu")
		(net "H_CPU1_MEMGHJ_MEMHOT_LVT3_N")
	)
	(segment
		(start 390.704324 -77.150214)
		(end 390.704324 -77.671676)
		(width 0.10795)
		(layer "B.Cu")
		(net "H_CPU1_MEMGHJ_MEMHOT_LVT3_N")
	)
	(segment
		(start 390.704324 -77.671676)
		(end 390.3726 -78.0034)
		(width 0.10795)
		(layer "B.Cu")
		(net "H_CPU1_MEMGHJ_MEMHOT_LVT3_N")
	)
	(segment
		(start 425.2595 -16.764)
		(end 425.8056 -16.764)
		(width 0.10795)
		(layer "B.Cu")
		(net "H_CPU1_MEMGHJ_MEMHOT_LVT3_N")
	)
	(segment
		(start 422.061132 -18.295112)
		(end 422.061132 -17.835626)
		(width 0.10795)
		(layer "B.Cu")
		(net "H_CPU1_MEMGHJ_MEMHOT_LVT3_N")
	)
	(segment
		(start 388.66064 -79.7052)
		(end 388.66064 -80.2386)
		(width 0.10795)
		(layer "B.Cu")
		(net "H_CPU1_MEMGHJ_MEMHOT_LVT3_N")
	)
	(segment
		(start 411.383226 -19.698208)
		(end 408.461718 -22.619716)
		(width 0.089408)
		(layer "In9.Cu")
		(net "H_CPU1_MEMGHJ_MEMHOT_LVT3_N")
	)
	(segment
		(start 413.290004 -19.698208)
		(end 411.383226 -19.698208)
		(width 0.089408)
		(layer "In9.Cu")
		(net "H_CPU1_MEMGHJ_MEMHOT_LVT3_N")
	)
	(segment
		(start 395.945106 -35.533076)
		(end 395.404086 -35.533076)
		(width 0.089408)
		(layer "In9.Cu")
		(net "H_CPU1_MEMGHJ_MEMHOT_LVT3_N")
	)
	(segment
		(start 401.89912 -22.755098)
		(end 400.930872 -21.78685)
		(width 0.089408)
		(layer "In9.Cu")
		(net "H_CPU1_MEMGHJ_MEMHOT_LVT3_N")
	)
	(segment
		(start 396.108428 -38.744906)
		(end 396.108428 -41.040558)
		(width 0.089408)
		(layer "In9.Cu")
		(net "H_CPU1_MEMGHJ_MEMHOT_LVT3_N")
	)
	(segment
		(start 415.946844 -19.154648)
		(end 413.833564 -19.154648)
		(width 0.089408)
		(layer "In9.Cu")
		(net "H_CPU1_MEMGHJ_MEMHOT_LVT3_N")
	)
	(segment
		(start 396.108682 -42.569892)
		(end 394.972794 -43.70578)
		(width 0.089408)
		(layer "In9.Cu")
		(net "H_CPU1_MEMGHJ_MEMHOT_LVT3_N")
	)
	(segment
		(start 393.721844 -63.732664)
		(end 393.722098 -63.732918)
		(width 0.089408)
		(layer "In9.Cu")
		(net "H_CPU1_MEMGHJ_MEMHOT_LVT3_N")
	)
	(segment
		(start 391.58672 -75.264772)
		(end 390.704324 -76.147168)
		(width 0.089408)
		(layer "In9.Cu")
		(net "H_CPU1_MEMGHJ_MEMHOT_LVT3_N")
	)
	(segment
		(start 400.930872 -21.78685)
		(end 398.070832 -21.78685)
		(width 0.089408)
		(layer "In9.Cu")
		(net "H_CPU1_MEMGHJ_MEMHOT_LVT3_N")
	)
	(segment
		(start 393.823698 -52.689506)
		(end 394.58646 -53.452268)
		(width 0.089408)
		(layer "In9.Cu")
		(net "H_CPU1_MEMGHJ_MEMHOT_LVT3_N")
	)
	(segment
		(start 422.037002 -18.295112)
		(end 416.80638 -18.295112)
		(width 0.089408)
		(layer "In9.Cu")
		(net "H_CPU1_MEMGHJ_MEMHOT_LVT3_N")
	)
	(segment
		(start 394.58646 -53.452268)
		(end 394.58646 -54.402736)
		(width 0.089408)
		(layer "In9.Cu")
		(net "H_CPU1_MEMGHJ_MEMHOT_LVT3_N")
	)
	(segment
		(start 394.972794 -43.70578)
		(end 394.972794 -44.031154)
		(width 0.089408)
		(layer "In9.Cu")
		(net "H_CPU1_MEMGHJ_MEMHOT_LVT3_N")
	)
	(segment
		(start 396.903702 -22.940264)
		(end 396.903702 -31.2674)
		(width 0.089408)
		(layer "In9.Cu")
		(net "H_CPU1_MEMGHJ_MEMHOT_LVT3_N")
	)
	(segment
		(start 391.424922 -72.34809)
		(end 391.424922 -73.725278)
		(width 0.089408)
		(layer "In9.Cu")
		(net "H_CPU1_MEMGHJ_MEMHOT_LVT3_N")
	)
	(segment
		(start 394.586206 -54.560978)
		(end 394.585952 -54.561232)
		(width 0.089408)
		(layer "In9.Cu")
		(net "H_CPU1_MEMGHJ_MEMHOT_LVT3_N")
	)
	(segment
		(start 393.823698 -51.150012)
		(end 393.823698 -52.689506)
		(width 0.089408)
		(layer "In9.Cu")
		(net "H_CPU1_MEMGHJ_MEMHOT_LVT3_N")
	)
	(segment
		(start 397.941038 -21.902928)
		(end 396.903702 -22.940264)
		(width 0.089408)
		(layer "In9.Cu")
		(net "H_CPU1_MEMGHJ_MEMHOT_LVT3_N")
	)
	(segment
		(start 397.954754 -21.902928)
		(end 397.941038 -21.902928)
		(width 0.089408)
		(layer "In9.Cu")
		(net "H_CPU1_MEMGHJ_MEMHOT_LVT3_N")
	)
	(segment
		(start 394.694918 -50.278792)
		(end 393.823698 -51.150012)
		(width 0.089408)
		(layer "In9.Cu")
		(net "H_CPU1_MEMGHJ_MEMHOT_LVT3_N")
	)
	(segment
		(start 396.59052 -34.887662)
		(end 395.945106 -35.533076)
		(width 0.089408)
		(layer "In9.Cu")
		(net "H_CPU1_MEMGHJ_MEMHOT_LVT3_N")
	)
	(segment
		(start 396.903702 -31.2674)
		(end 396.59052 -31.580582)
		(width 0.089408)
		(layer "In9.Cu")
		(net "H_CPU1_MEMGHJ_MEMHOT_LVT3_N")
	)
	(segment
		(start 394.513562 -49.310798)
		(end 394.694918 -49.492154)
		(width 0.089408)
		(layer "In9.Cu")
		(net "H_CPU1_MEMGHJ_MEMHOT_LVT3_N")
	)
	(segment
		(start 391.58672 -73.887076)
		(end 391.58672 -75.264772)
		(width 0.089408)
		(layer "In9.Cu")
		(net "H_CPU1_MEMGHJ_MEMHOT_LVT3_N")
	)
	(segment
		(start 394.585952 -54.561232)
		(end 394.585952 -62.552072)
		(width 0.089408)
		(layer "In9.Cu")
		(net "H_CPU1_MEMGHJ_MEMHOT_LVT3_N")
	)
	(segment
		(start 395.404086 -35.533076)
		(end 395.079982 -35.85718)
		(width 0.089408)
		(layer "In9.Cu")
		(net "H_CPU1_MEMGHJ_MEMHOT_LVT3_N")
	)
	(segment
		(start 396.108682 -41.040812)
		(end 396.108682 -42.569892)
		(width 0.089408)
		(layer "In9.Cu")
		(net "H_CPU1_MEMGHJ_MEMHOT_LVT3_N")
	)
	(segment
		(start 402.706586 -22.619716)
		(end 402.571204 -22.755098)
		(width 0.089408)
		(layer "In9.Cu")
		(net "H_CPU1_MEMGHJ_MEMHOT_LVT3_N")
	)
	(segment
		(start 394.585952 -62.552072)
		(end 393.721844 -63.41618)
		(width 0.089408)
		(layer "In9.Cu")
		(net "H_CPU1_MEMGHJ_MEMHOT_LVT3_N")
	)
	(segment
		(start 416.80638 -18.295112)
		(end 415.946844 -19.154648)
		(width 0.089408)
		(layer "In9.Cu")
		(net "H_CPU1_MEMGHJ_MEMHOT_LVT3_N")
	)
	(segment
		(start 408.461718 -22.619716)
		(end 402.706586 -22.619716)
		(width 0.089408)
		(layer "In9.Cu")
		(net "H_CPU1_MEMGHJ_MEMHOT_LVT3_N")
	)
	(segment
		(start 394.972794 -44.031154)
		(end 394.513562 -44.490386)
		(width 0.089408)
		(layer "In9.Cu")
		(net "H_CPU1_MEMGHJ_MEMHOT_LVT3_N")
	)
	(segment
		(start 396.59052 -33.092644)
		(end 396.58798 -33.095184)
		(width 0.089408)
		(layer "In9.Cu")
		(net "H_CPU1_MEMGHJ_MEMHOT_LVT3_N")
	)
	(segment
		(start 395.079982 -35.85718)
		(end 395.079982 -37.71646)
		(width 0.089408)
		(layer "In9.Cu")
		(net "H_CPU1_MEMGHJ_MEMHOT_LVT3_N")
	)
	(segment
		(start 396.58798 -33.567624)
		(end 396.59052 -33.570164)
		(width 0.089408)
		(layer "In9.Cu")
		(net "H_CPU1_MEMGHJ_MEMHOT_LVT3_N")
	)
	(segment
		(start 394.694918 -49.492154)
		(end 394.694918 -50.278792)
		(width 0.089408)
		(layer "In9.Cu")
		(net "H_CPU1_MEMGHJ_MEMHOT_LVT3_N")
	)
	(segment
		(start 394.513562 -44.490386)
		(end 394.513562 -49.310798)
		(width 0.089408)
		(layer "In9.Cu")
		(net "H_CPU1_MEMGHJ_MEMHOT_LVT3_N")
	)
	(segment
		(start 396.59052 -33.570164)
		(end 396.59052 -34.887662)
		(width 0.089408)
		(layer "In9.Cu")
		(net "H_CPU1_MEMGHJ_MEMHOT_LVT3_N")
	)
	(segment
		(start 394.58646 -54.402736)
		(end 394.586206 -54.40299)
		(width 0.089408)
		(layer "In9.Cu")
		(net "H_CPU1_MEMGHJ_MEMHOT_LVT3_N")
	)
	(segment
		(start 391.424922 -73.725278)
		(end 391.58672 -73.887076)
		(width 0.089408)
		(layer "In9.Cu")
		(net "H_CPU1_MEMGHJ_MEMHOT_LVT3_N")
	)
	(segment
		(start 396.108428 -41.040558)
		(end 396.108682 -41.040812)
		(width 0.089408)
		(layer "In9.Cu")
		(net "H_CPU1_MEMGHJ_MEMHOT_LVT3_N")
	)
	(segment
		(start 395.079982 -37.71646)
		(end 396.108428 -38.744906)
		(width 0.089408)
		(layer "In9.Cu")
		(net "H_CPU1_MEMGHJ_MEMHOT_LVT3_N")
	)
	(segment
		(start 394.586206 -54.40299)
		(end 394.586206 -54.560978)
		(width 0.089408)
		(layer "In9.Cu")
		(net "H_CPU1_MEMGHJ_MEMHOT_LVT3_N")
	)
	(segment
		(start 396.58798 -33.095184)
		(end 396.58798 -33.567624)
		(width 0.089408)
		(layer "In9.Cu")
		(net "H_CPU1_MEMGHJ_MEMHOT_LVT3_N")
	)
	(segment
		(start 402.571204 -22.755098)
		(end 401.89912 -22.755098)
		(width 0.089408)
		(layer "In9.Cu")
		(net "H_CPU1_MEMGHJ_MEMHOT_LVT3_N")
	)
	(segment
		(start 391.819384 -70.843648)
		(end 391.819384 -71.953628)
		(width 0.089408)
		(layer "In9.Cu")
		(net "H_CPU1_MEMGHJ_MEMHOT_LVT3_N")
	)
	(segment
		(start 390.704324 -76.147168)
		(end 390.704324 -77.150214)
		(width 0.089408)
		(layer "In9.Cu")
		(net "H_CPU1_MEMGHJ_MEMHOT_LVT3_N")
	)
	(segment
		(start 391.819384 -71.953628)
		(end 391.424922 -72.34809)
		(width 0.089408)
		(layer "In9.Cu")
		(net "H_CPU1_MEMGHJ_MEMHOT_LVT3_N")
	)
	(segment
		(start 413.833564 -19.154648)
		(end 413.290004 -19.698208)
		(width 0.089408)
		(layer "In9.Cu")
		(net "H_CPU1_MEMGHJ_MEMHOT_LVT3_N")
	)
	(segment
		(start 393.721844 -63.41618)
		(end 393.721844 -63.732664)
		(width 0.089408)
		(layer "In9.Cu")
		(net "H_CPU1_MEMGHJ_MEMHOT_LVT3_N")
	)
	(segment
		(start 393.722098 -68.940934)
		(end 391.819384 -70.843648)
		(width 0.089408)
		(layer "In9.Cu")
		(net "H_CPU1_MEMGHJ_MEMHOT_LVT3_N")
	)
	(segment
		(start 398.070832 -21.78685)
		(end 397.954754 -21.902928)
		(width 0.089408)
		(layer "In9.Cu")
		(net "H_CPU1_MEMGHJ_MEMHOT_LVT3_N")
	)
	(segment
		(start 396.59052 -31.580582)
		(end 396.59052 -33.092644)
		(width 0.089408)
		(layer "In9.Cu")
		(net "H_CPU1_MEMGHJ_MEMHOT_LVT3_N")
	)
	(segment
		(start 393.722098 -63.732918)
		(end 393.722098 -68.940934)
		(width 0.089408)
		(layer "In9.Cu")
		(net "H_CPU1_MEMGHJ_MEMHOT_LVT3_N")
	)
	(segment
		(start 391.16 2.54)
		(end 389.89 3.81)
		(width 0.10795)
		(layer "F.Cu")
		(net "JTAG_TRST_N")
	)
	(segment
		(start 391.16 0.635)
		(end 391.16 2.54)
		(width 0.10795)
		(layer "F.Cu")
		(net "JTAG_TRST_N")
	)
	(segment
		(start 391.16 0.635)
		(end 392.049 0.635)
		(width 0.10795)
		(layer "F.Cu")
		(net "JTAG_TRST_N")
	)
	(via
		(at 388.713218 0.403098)
		(size 0.6604)
		(drill 0.3302)
		(layers "F.Cu" "B.Cu")
		(net "JTAG_TRST_N")
	)
	(segment
		(start 389.89 1.57988)
		(end 388.713218 0.403098)
		(width 0.10795)
		(layer "B.Cu")
		(net "JTAG_TRST_N")
	)
	(segment
		(start 389.89 3.81)
		(end 389.89 1.57988)
		(width 0.10795)
		(layer "B.Cu")
		(net "JTAG_TRST_N")
	)
	(segment
		(start 392.9126 0.6604)
		(end 393.2936 0.6604)
		(width 0.10795)
		(layer "F.Cu")
		(net "JTAG_TMS")
	)
	(segment
		(start 403.969474 1.702308)
		(end 404.502874 1.702308)
		(width 0.10795)
		(layer "F.Cu")
		(net "JTAG_TMS")
	)
	(segment
		(start 395.6812 1.309624)
		(end 395.489176 1.1176)
		(width 0.10795)
		(layer "F.Cu")
		(net "JTAG_TMS")
	)
	(segment
		(start 394.9192 0.6604)
		(end 394.1064 0.6604)
		(width 0.10795)
		(layer "F.Cu")
		(net "JTAG_TMS")
	)
	(segment
		(start 392.836146 0.583946)
		(end 392.9126 0.6604)
		(width 0.10795)
		(layer "F.Cu")
		(net "JTAG_TMS")
	)
	(segment
		(start 395.0716 1.1176)
		(end 394.9192 0.9652)
		(width 0.10795)
		(layer "F.Cu")
		(net "JTAG_TMS")
	)
	(segment
		(start 394.1064 0.6604)
		(end 393.2936 0.6604)
		(width 0.10795)
		(layer "F.Cu")
		(net "JTAG_TMS")
	)
	(segment
		(start 392.8872 -0.8636)
		(end 392.836146 -0.812546)
		(width 0.10795)
		(layer "F.Cu")
		(net "JTAG_TMS")
	)
	(segment
		(start 394.9192 0.9652)
		(end 394.9192 0.6604)
		(width 0.10795)
		(layer "F.Cu")
		(net "JTAG_TMS")
	)
	(segment
		(start 395.6812 1.5748)
		(end 395.6812 1.309624)
		(width 0.10795)
		(layer "F.Cu")
		(net "JTAG_TMS")
	)
	(segment
		(start 395.489176 1.1176)
		(end 395.0716 1.1176)
		(width 0.10795)
		(layer "F.Cu")
		(net "JTAG_TMS")
	)
	(segment
		(start 392.836146 -0.812546)
		(end 392.836146 0.583946)
		(width 0.10795)
		(layer "F.Cu")
		(net "JTAG_TMS")
	)
	(via
		(at 392.8872 -0.8636)
		(size 0.508)
		(drill 0.254)
		(layers "F.Cu" "B.Cu")
		(net "JTAG_TMS")
	)
	(via
		(at 403.969474 1.702308)
		(size 0.508)
		(drill 0.254)
		(layers "F.Cu" "B.Cu")
		(net "JTAG_TMS")
	)
	(via
		(at 393.119864 -1.535684)
		(size 0.6604)
		(drill 0.3302)
		(layers "F.Cu" "B.Cu")
		(net "JTAG_TMS")
	)
	(segment
		(start 392.8872 -1.30302)
		(end 393.119864 -1.535684)
		(width 0.10795)
		(layer "B.Cu")
		(net "JTAG_TMS")
	)
	(segment
		(start 392.8872 -0.8636)
		(end 392.8872 -1.30302)
		(width 0.10795)
		(layer "B.Cu")
		(net "JTAG_TMS")
	)
	(segment
		(start 395.499336 1.748536)
		(end 392.8872 -0.8636)
		(width 0.089408)
		(layer "In4.Cu")
		(net "JTAG_TMS")
	)
	(segment
		(start 403.969474 1.702308)
		(end 403.56917 2.102612)
		(width 0.089408)
		(layer "In4.Cu")
		(net "JTAG_TMS")
	)
	(segment
		(start 400.906234 2.102612)
		(end 400.552158 1.748536)
		(width 0.089408)
		(layer "In4.Cu")
		(net "JTAG_TMS")
	)
	(segment
		(start 403.56917 2.102612)
		(end 400.906234 2.102612)
		(width 0.089408)
		(layer "In4.Cu")
		(net "JTAG_TMS")
	)
	(segment
		(start 400.552158 1.748536)
		(end 395.499336 1.748536)
		(width 0.089408)
		(layer "In4.Cu")
		(net "JTAG_TMS")
	)
	(segment
		(start 399.463768 -0.5588)
		(end 401.105116 -0.5588)
		(width 0.10795)
		(layer "F.Cu")
		(net "JTAG_TDO")
	)
	(segment
		(start 386.1054 0.635)
		(end 385.2926 0.635)
		(width 0.10795)
		(layer "F.Cu")
		(net "JTAG_TDO")
	)
	(segment
		(start 386.7404 0.52705)
		(end 386.7404 -1.0795)
		(width 0.10795)
		(layer "F.Cu")
		(net "JTAG_TDO")
	)
	(segment
		(start 386.63245 0.635)
		(end 386.7404 0.52705)
		(width 0.10795)
		(layer "F.Cu")
		(net "JTAG_TDO")
	)
	(segment
		(start 383.722372 0.635)
		(end 383.286 1.071372)
		(width 0.10795)
		(layer "F.Cu")
		(net "JTAG_TDO")
	)
	(segment
		(start 384.4798 0.635)
		(end 383.722372 0.635)
		(width 0.10795)
		(layer "F.Cu")
		(net "JTAG_TDO")
	)
	(segment
		(start 386.1054 0.635)
		(end 386.63245 0.635)
		(width 0.10795)
		(layer "F.Cu")
		(net "JTAG_TDO")
	)
	(segment
		(start 386.7404 -1.0795)
		(end 386.972302 -1.311402)
		(width 0.10795)
		(layer "F.Cu")
		(net "JTAG_TDO")
	)
	(segment
		(start 398.711166 -1.311402)
		(end 399.463768 -0.5588)
		(width 0.10795)
		(layer "F.Cu")
		(net "JTAG_TDO")
	)
	(segment
		(start 401.31619 -0.347726)
		(end 402.183092 -0.347726)
		(width 0.10795)
		(layer "F.Cu")
		(net "JTAG_TDO")
	)
	(segment
		(start 386.972302 -1.311402)
		(end 398.711166 -1.311402)
		(width 0.10795)
		(layer "F.Cu")
		(net "JTAG_TDO")
	)
	(segment
		(start 383.286 1.071372)
		(end 383.286 1.651)
		(width 0.10795)
		(layer "F.Cu")
		(net "JTAG_TDO")
	)
	(segment
		(start 385.2926 0.635)
		(end 384.4798 0.635)
		(width 0.10795)
		(layer "F.Cu")
		(net "JTAG_TDO")
	)
	(segment
		(start 401.105116 -0.5588)
		(end 401.31619 -0.347726)
		(width 0.10795)
		(layer "F.Cu")
		(net "JTAG_TDO")
	)
	(segment
		(start 390.162796 0.635)
		(end 389.636 0.635)
		(width 0.10795)
		(layer "F.Cu")
		(net "JTAG_TDI")
	)
	(segment
		(start 387.6294 0.635)
		(end 388.0104 0.635)
		(width 0.10795)
		(layer "F.Cu")
		(net "JTAG_TDI")
	)
	(segment
		(start 387.2992 -0.889)
		(end 387.2992 0.3048)
		(width 0.10795)
		(layer "F.Cu")
		(net "JTAG_TDI")
	)
	(segment
		(start 388.8232 0.635)
		(end 388.0104 0.635)
		(width 0.10795)
		(layer "F.Cu")
		(net "JTAG_TDI")
	)
	(segment
		(start 389.636 0.635)
		(end 388.8232 0.635)
		(width 0.10795)
		(layer "F.Cu")
		(net "JTAG_TDI")
	)
	(segment
		(start 387.2992 0.3048)
		(end 387.6294 0.635)
		(width 0.10795)
		(layer "F.Cu")
		(net "JTAG_TDI")
	)
	(segment
		(start 406.044908 0.1524)
		(end 405.282908 0.1524)
		(width 0.10795)
		(layer "F.Cu")
		(net "JTAG_TDI")
	)
	(segment
		(start 390.271 0.743204)
		(end 390.162796 0.635)
		(width 0.10795)
		(layer "F.Cu")
		(net "JTAG_TDI")
	)
	(segment
		(start 390.271 1.651)
		(end 390.271 0.743204)
		(width 0.10795)
		(layer "F.Cu")
		(net "JTAG_TDI")
	)
	(via
		(at 387.2992 -0.889)
		(size 0.508)
		(drill 0.254)
		(layers "F.Cu" "B.Cu")
		(net "JTAG_TDI")
	)
	(via
		(at 406.044908 0.1524)
		(size 0.508)
		(drill 0.254)
		(layers "F.Cu" "B.Cu")
		(net "JTAG_TDI")
	)
	(segment
		(start 400.310096 -1.289304)
		(end 387.699504 -1.289304)
		(width 0.089408)
		(layer "In4.Cu")
		(net "JTAG_TDI")
	)
	(segment
		(start 402.88464 -0.9906)
		(end 402.65604 -0.762)
		(width 0.089408)
		(layer "In4.Cu")
		(net "JTAG_TDI")
	)
	(segment
		(start 400.8374 -0.762)
		(end 400.310096 -1.289304)
		(width 0.089408)
		(layer "In4.Cu")
		(net "JTAG_TDI")
	)
	(segment
		(start 402.65604 -0.762)
		(end 400.8374 -0.762)
		(width 0.089408)
		(layer "In4.Cu")
		(net "JTAG_TDI")
	)
	(segment
		(start 387.699504 -1.289304)
		(end 387.2992 -0.889)
		(width 0.089408)
		(layer "In4.Cu")
		(net "JTAG_TDI")
	)
	(segment
		(start 406.044908 0.1524)
		(end 404.901908 -0.9906)
		(width 0.089408)
		(layer "In4.Cu")
		(net "JTAG_TDI")
	)
	(segment
		(start 404.901908 -0.9906)
		(end 402.88464 -0.9906)
		(width 0.089408)
		(layer "In4.Cu")
		(net "JTAG_TDI")
	)
	(segment
		(start 395.732 0.9652)
		(end 395.732 0.6604)
		(width 0.10795)
		(layer "F.Cu")
		(net "JTAG_TCK")
	)
	(segment
		(start 402.183092 1.152398)
		(end 401.589748 1.152398)
		(width 0.10795)
		(layer "F.Cu")
		(net "JTAG_TCK")
	)
	(segment
		(start 401.589748 1.152398)
		(end 401.472146 1.27)
		(width 0.10795)
		(layer "F.Cu")
		(net "JTAG_TCK")
	)
	(segment
		(start 396.5448 0.6604)
		(end 397.3576 0.6604)
		(width 0.10795)
		(layer "F.Cu")
		(net "JTAG_TCK")
	)
	(segment
		(start 398.4244 1.27)
		(end 397.8148 0.6604)
		(width 0.10795)
		(layer "F.Cu")
		(net "JTAG_TCK")
	)
	(segment
		(start 397.51 1.7272)
		(end 396.935198 1.152398)
		(width 0.10795)
		(layer "F.Cu")
		(net "JTAG_TCK")
	)
	(segment
		(start 395.732 0.6604)
		(end 396.5448 0.6604)
		(width 0.10795)
		(layer "F.Cu")
		(net "JTAG_TCK")
	)
	(segment
		(start 395.919198 1.152398)
		(end 395.732 0.9652)
		(width 0.10795)
		(layer "F.Cu")
		(net "JTAG_TCK")
	)
	(segment
		(start 396.935198 1.152398)
		(end 395.919198 1.152398)
		(width 0.10795)
		(layer "F.Cu")
		(net "JTAG_TCK")
	)
	(segment
		(start 397.8148 0.6604)
		(end 397.3576 0.6604)
		(width 0.10795)
		(layer "F.Cu")
		(net "JTAG_TCK")
	)
	(segment
		(start 401.472146 1.27)
		(end 398.4244 1.27)
		(width 0.10795)
		(layer "F.Cu")
		(net "JTAG_TCK")
	)
	(segment
		(start 397.9672 1.7272)
		(end 397.51 1.7272)
		(width 0.10795)
		(layer "F.Cu")
		(net "JTAG_TCK")
	)
	(segment
		(start 411.486604 -38.9382)
		(end 411.09011 -39.334694)
		(width 0.10795)
		(layer "F.Cu")
		(net "FM_BMC_PWRBTN_OUT_N")
	)
	(segment
		(start 411.5054 -38.9382)
		(end 411.486604 -38.9382)
		(width 0.10795)
		(layer "F.Cu")
		(net "FM_BMC_PWRBTN_OUT_N")
	)
	(via
		(at 411.5054 -38.9382)
		(size 0.4572)
		(drill 0.2032)
		(layers "F.Cu" "B.Cu")
		(net "FM_BMC_PWRBTN_OUT_N")
	)
	(via
		(at 398.395952 -41.670732)
		(size 0.508)
		(drill 0.254)
		(layers "F.Cu" "B.Cu")
		(net "FM_BMC_PWRBTN_OUT_N")
	)
	(via
		(at 398.22628 -29.2608)
		(size 0.6604)
		(drill 0.3302)
		(layers "F.Cu" "B.Cu")
		(net "FM_BMC_PWRBTN_OUT_N")
	)
	(segment
		(start 398.464532 -33.547304)
		(end 398.464532 -32.131254)
		(width 0.10795)
		(layer "B.Cu")
		(net "FM_BMC_PWRBTN_OUT_N")
	)
	(segment
		(start 397.637 -27.686)
		(end 397.637 -28.067)
		(width 0.10795)
		(layer "B.Cu")
		(net "FM_BMC_PWRBTN_OUT_N")
	)
	(segment
		(start 397.891 -28.321)
		(end 398.272 -28.321)
		(width 0.10795)
		(layer "B.Cu")
		(net "FM_BMC_PWRBTN_OUT_N")
	)
	(segment
		(start 398.324578 -34.294826)
		(end 398.585182 -34.034222)
		(width 0.10795)
		(layer "B.Cu")
		(net "FM_BMC_PWRBTN_OUT_N")
	)
	(segment
		(start 398.177004 -35.967416)
		(end 397.84147 -35.631882)
		(width 0.10795)
		(layer "B.Cu")
		(net "FM_BMC_PWRBTN_OUT_N")
	)
	(segment
		(start 398.878552 -36.389818)
		(end 398.45615 -35.967416)
		(width 0.10795)
		(layer "B.Cu")
		(net "FM_BMC_PWRBTN_OUT_N")
	)
	(segment
		(start 398.45615 -35.967416)
		(end 398.177004 -35.967416)
		(width 0.10795)
		(layer "B.Cu")
		(net "FM_BMC_PWRBTN_OUT_N")
	)
	(segment
		(start 398.585182 -33.667954)
		(end 398.464532 -33.547304)
		(width 0.10795)
		(layer "B.Cu")
		(net "FM_BMC_PWRBTN_OUT_N")
	)
	(segment
		(start 397.863822 -31.530544)
		(end 397.863822 -29.623258)
		(width 0.10795)
		(layer "B.Cu")
		(net "FM_BMC_PWRBTN_OUT_N")
	)
	(segment
		(start 398.464532 -32.131254)
		(end 397.863822 -31.530544)
		(width 0.10795)
		(layer "B.Cu")
		(net "FM_BMC_PWRBTN_OUT_N")
	)
	(segment
		(start 398.272 -28.321)
		(end 398.272 -29.21508)
		(width 0.10795)
		(layer "B.Cu")
		(net "FM_BMC_PWRBTN_OUT_N")
	)
	(segment
		(start 397.637 -28.067)
		(end 397.891 -28.321)
		(width 0.10795)
		(layer "B.Cu")
		(net "FM_BMC_PWRBTN_OUT_N")
	)
	(segment
		(start 398.272 -29.21508)
		(end 398.22628 -29.2608)
		(width 0.10795)
		(layer "B.Cu")
		(net "FM_BMC_PWRBTN_OUT_N")
	)
	(segment
		(start 398.088866 -34.294826)
		(end 398.324578 -34.294826)
		(width 0.10795)
		(layer "B.Cu")
		(net "FM_BMC_PWRBTN_OUT_N")
	)
	(segment
		(start 397.22552 -27.27452)
		(end 397.637 -27.686)
		(width 0.10795)
		(layer "B.Cu")
		(net "FM_BMC_PWRBTN_OUT_N")
	)
	(segment
		(start 397.863822 -29.623258)
		(end 398.22628 -29.2608)
		(width 0.10795)
		(layer "B.Cu")
		(net "FM_BMC_PWRBTN_OUT_N")
	)
	(segment
		(start 398.395952 -41.670732)
		(end 398.878552 -41.188132)
		(width 0.10795)
		(layer "B.Cu")
		(net "FM_BMC_PWRBTN_OUT_N")
	)
	(segment
		(start 398.585182 -34.034222)
		(end 398.585182 -33.667954)
		(width 0.10795)
		(layer "B.Cu")
		(net "FM_BMC_PWRBTN_OUT_N")
	)
	(segment
		(start 397.84147 -34.542222)
		(end 398.088866 -34.294826)
		(width 0.10795)
		(layer "B.Cu")
		(net "FM_BMC_PWRBTN_OUT_N")
	)
	(segment
		(start 396.7226 -27.27452)
		(end 397.22552 -27.27452)
		(width 0.10795)
		(layer "B.Cu")
		(net "FM_BMC_PWRBTN_OUT_N")
	)
	(segment
		(start 398.878552 -41.188132)
		(end 398.878552 -36.389818)
		(width 0.10795)
		(layer "B.Cu")
		(net "FM_BMC_PWRBTN_OUT_N")
	)
	(segment
		(start 397.84147 -35.631882)
		(end 397.84147 -34.542222)
		(width 0.10795)
		(layer "B.Cu")
		(net "FM_BMC_PWRBTN_OUT_N")
	)
	(segment
		(start 407.303478 -39.352728)
		(end 411.090872 -39.352728)
		(width 0.089408)
		(layer "In2.Cu")
		(net "FM_BMC_PWRBTN_OUT_N")
	)
	(segment
		(start 411.090872 -39.352728)
		(end 411.5054 -38.9382)
		(width 0.089408)
		(layer "In2.Cu")
		(net "FM_BMC_PWRBTN_OUT_N")
	)
	(segment
		(start 407.026872 -39.629334)
		(end 407.303478 -39.352728)
		(width 0.089408)
		(layer "In2.Cu")
		(net "FM_BMC_PWRBTN_OUT_N")
	)
	(segment
		(start 402.813266 -39.629334)
		(end 407.026872 -39.629334)
		(width 0.089408)
		(layer "In2.Cu")
		(net "FM_BMC_PWRBTN_OUT_N")
	)
	(segment
		(start 400.771868 -41.670732)
		(end 402.813266 -39.629334)
		(width 0.089408)
		(layer "In2.Cu")
		(net "FM_BMC_PWRBTN_OUT_N")
	)
	(segment
		(start 398.395952 -41.670732)
		(end 400.771868 -41.670732)
		(width 0.089408)
		(layer "In2.Cu")
		(net "FM_BMC_PWRBTN_OUT_N")
	)
	(segment
		(start 414.12287 -24.409654)
		(end 414.12287 -25.460198)
		(width 0.10795)
		(layer "F.Cu")
		(net "UART_BMC_TXD5")
	)
	(segment
		(start 414.02 -23.749)
		(end 414.275524 -23.749)
		(width 0.10795)
		(layer "F.Cu")
		(net "UART_BMC_TXD5")
	)
	(segment
		(start 488.5182 -23.9522)
		(end 488.3912 -23.8252)
		(width 0.10795)
		(layer "F.Cu")
		(net "UART_BMC_TXD5")
	)
	(segment
		(start 375.144792 -75.894692)
		(end 374.744996 -75.494896)
		(width 0.10795)
		(layer "F.Cu")
		(net "UART_BMC_TXD5")
	)
	(segment
		(start 414.12287 -25.460198)
		(end 414.290256 -25.627584)
		(width 0.10795)
		(layer "F.Cu")
		(net "UART_BMC_TXD5")
	)
	(segment
		(start 413.639 -23.368)
		(end 414.02 -23.749)
		(width 0.10795)
		(layer "F.Cu")
		(net "UART_BMC_TXD5")
	)
	(segment
		(start 488.3912 -23.8252)
		(end 488.3912 -23.0886)
		(width 0.10795)
		(layer "F.Cu")
		(net "UART_BMC_TXD5")
	)
	(segment
		(start 414.529524 -24.003)
		(end 414.12287 -24.409654)
		(width 0.10795)
		(layer "F.Cu")
		(net "UART_BMC_TXD5")
	)
	(segment
		(start 414.275524 -23.749)
		(end 414.529524 -24.003)
		(width 0.10795)
		(layer "F.Cu")
		(net "UART_BMC_TXD5")
	)
	(segment
		(start 414.290256 -25.627584)
		(end 414.290256 -26.534618)
		(width 0.10795)
		(layer "F.Cu")
		(net "UART_BMC_TXD5")
	)
	(segment
		(start 413.639 -22.86)
		(end 413.639 -23.368)
		(width 0.10795)
		(layer "F.Cu")
		(net "UART_BMC_TXD5")
	)
	(via
		(at 414.529524 -24.003)
		(size 0.508)
		(drill 0.254)
		(layers "F.Cu" "B.Cu")
		(net "UART_BMC_TXD5")
	)
	(via
		(at 385.683252 -25.635204)
		(size 0.508)
		(drill 0.254)
		(layers "F.Cu" "B.Cu")
		(net "UART_BMC_TXD5")
	)
	(via
		(at 488.5182 -23.9522)
		(size 0.508)
		(drill 0.254)
		(layers "F.Cu" "B.Cu")
		(net "UART_BMC_TXD5")
	)
	(via
		(at 495.7318 -35.814)
		(size 0.508)
		(drill 0.254)
		(layers "F.Cu" "B.Cu")
		(net "UART_BMC_TXD5")
	)
	(via
		(at 375.144792 -75.894692)
		(size 0.4572)
		(drill 0.2032)
		(layers "F.Cu" "B.Cu")
		(net "UART_BMC_TXD5")
	)
	(segment
		(start 495.875818 -35.958018)
		(end 496.919504 -35.958018)
		(width 0.10795)
		(layer "B.Cu")
		(net "UART_BMC_TXD5")
	)
	(segment
		(start 495.7318 -35.814)
		(end 495.875818 -35.958018)
		(width 0.10795)
		(layer "B.Cu")
		(net "UART_BMC_TXD5")
	)
	(segment
		(start 427.405292 -20.553426)
		(end 431.464466 -20.553426)
		(width 0.089408)
		(layer "In2.Cu")
		(net "UART_BMC_TXD5")
	)
	(segment
		(start 487.9086 -21.971)
		(end 488.368086 -22.430486)
		(width 0.089408)
		(layer "In2.Cu")
		(net "UART_BMC_TXD5")
	)
	(segment
		(start 458.93609 -21.374862)
		(end 461.328262 -21.374862)
		(width 0.089408)
		(layer "In2.Cu")
		(net "UART_BMC_TXD5")
	)
	(segment
		(start 463.9818 -25.2984)
		(end 464.57108 -25.2984)
		(width 0.089408)
		(layer "In2.Cu")
		(net "UART_BMC_TXD5")
	)
	(segment
		(start 431.464466 -20.553426)
		(end 432.127406 -19.890486)
		(width 0.089408)
		(layer "In2.Cu")
		(net "UART_BMC_TXD5")
	)
	(segment
		(start 471.043 -27.9146)
		(end 471.754962 -27.202638)
		(width 0.089408)
		(layer "In2.Cu")
		(net "UART_BMC_TXD5")
	)
	(segment
		(start 488.368086 -23.802086)
		(end 488.5182 -23.9522)
		(width 0.089408)
		(layer "In2.Cu")
		(net "UART_BMC_TXD5")
	)
	(segment
		(start 445.964056 -19.08556)
		(end 446.3796 -19.501104)
		(width 0.089408)
		(layer "In2.Cu")
		(net "UART_BMC_TXD5")
	)
	(segment
		(start 414.529524 -24.003)
		(end 420.58082 -24.003)
		(width 0.089408)
		(layer "In2.Cu")
		(net "UART_BMC_TXD5")
	)
	(segment
		(start 461.328262 -21.374862)
		(end 462.580482 -22.627082)
		(width 0.089408)
		(layer "In2.Cu")
		(net "UART_BMC_TXD5")
	)
	(segment
		(start 454.256394 -20.0914)
		(end 456.98029 -22.815296)
		(width 0.089408)
		(layer "In2.Cu")
		(net "UART_BMC_TXD5")
	)
	(segment
		(start 421.487854 -23.095966)
		(end 421.694102 -23.095966)
		(width 0.089408)
		(layer "In2.Cu")
		(net "UART_BMC_TXD5")
	)
	(segment
		(start 464.73999 -25.12949)
		(end 466.3567 -25.12949)
		(width 0.089408)
		(layer "In2.Cu")
		(net "UART_BMC_TXD5")
	)
	(segment
		(start 485.771444 -22.68601)
		(end 486.486454 -21.971)
		(width 0.089408)
		(layer "In2.Cu")
		(net "UART_BMC_TXD5")
	)
	(segment
		(start 462.580482 -23.897082)
		(end 463.9818 -25.2984)
		(width 0.089408)
		(layer "In2.Cu")
		(net "UART_BMC_TXD5")
	)
	(segment
		(start 482.999034 -24.970232)
		(end 485.418892 -24.970232)
		(width 0.089408)
		(layer "In2.Cu")
		(net "UART_BMC_TXD5")
	)
	(segment
		(start 448.691 -20.0914)
		(end 454.256394 -20.0914)
		(width 0.089408)
		(layer "In2.Cu")
		(net "UART_BMC_TXD5")
	)
	(segment
		(start 485.418892 -24.970232)
		(end 485.771444 -24.61768)
		(width 0.089408)
		(layer "In2.Cu")
		(net "UART_BMC_TXD5")
	)
	(segment
		(start 462.580482 -22.627082)
		(end 462.580482 -23.897082)
		(width 0.089408)
		(layer "In2.Cu")
		(net "UART_BMC_TXD5")
	)
	(segment
		(start 467.814914 -26.587704)
		(end 468.82685 -26.587704)
		(width 0.089408)
		(layer "In2.Cu")
		(net "UART_BMC_TXD5")
	)
	(segment
		(start 480.7458 -22.716998)
		(end 482.999034 -24.970232)
		(width 0.089408)
		(layer "In2.Cu")
		(net "UART_BMC_TXD5")
	)
	(segment
		(start 468.82685 -26.587704)
		(end 470.153746 -27.9146)
		(width 0.089408)
		(layer "In2.Cu")
		(net "UART_BMC_TXD5")
	)
	(segment
		(start 471.754962 -27.09418)
		(end 476.132144 -22.716998)
		(width 0.089408)
		(layer "In2.Cu")
		(net "UART_BMC_TXD5")
	)
	(segment
		(start 466.3567 -25.12949)
		(end 467.814914 -26.587704)
		(width 0.089408)
		(layer "In2.Cu")
		(net "UART_BMC_TXD5")
	)
	(segment
		(start 433.338224 -19.08556)
		(end 445.964056 -19.08556)
		(width 0.089408)
		(layer "In2.Cu")
		(net "UART_BMC_TXD5")
	)
	(segment
		(start 421.694102 -23.095966)
		(end 423.362374 -21.427694)
		(width 0.089408)
		(layer "In2.Cu")
		(net "UART_BMC_TXD5")
	)
	(segment
		(start 432.533298 -19.890486)
		(end 433.338224 -19.08556)
		(width 0.089408)
		(layer "In2.Cu")
		(net "UART_BMC_TXD5")
	)
	(segment
		(start 476.132144 -22.716998)
		(end 480.7458 -22.716998)
		(width 0.089408)
		(layer "In2.Cu")
		(net "UART_BMC_TXD5")
	)
	(segment
		(start 446.3796 -19.501104)
		(end 448.100704 -19.501104)
		(width 0.089408)
		(layer "In2.Cu")
		(net "UART_BMC_TXD5")
	)
	(segment
		(start 464.57108 -25.2984)
		(end 464.73999 -25.12949)
		(width 0.089408)
		(layer "In2.Cu")
		(net "UART_BMC_TXD5")
	)
	(segment
		(start 471.754962 -27.202638)
		(end 471.754962 -27.09418)
		(width 0.089408)
		(layer "In2.Cu")
		(net "UART_BMC_TXD5")
	)
	(segment
		(start 488.368086 -22.430486)
		(end 488.368086 -23.802086)
		(width 0.089408)
		(layer "In2.Cu")
		(net "UART_BMC_TXD5")
	)
	(segment
		(start 470.153746 -27.9146)
		(end 471.043 -27.9146)
		(width 0.089408)
		(layer "In2.Cu")
		(net "UART_BMC_TXD5")
	)
	(segment
		(start 485.771444 -24.61768)
		(end 485.771444 -22.68601)
		(width 0.089408)
		(layer "In2.Cu")
		(net "UART_BMC_TXD5")
	)
	(segment
		(start 420.58082 -24.003)
		(end 421.487854 -23.095966)
		(width 0.089408)
		(layer "In2.Cu")
		(net "UART_BMC_TXD5")
	)
	(segment
		(start 426.531024 -21.427694)
		(end 427.405292 -20.553426)
		(width 0.089408)
		(layer "In2.Cu")
		(net "UART_BMC_TXD5")
	)
	(segment
		(start 448.100704 -19.501104)
		(end 448.691 -20.0914)
		(width 0.089408)
		(layer "In2.Cu")
		(net "UART_BMC_TXD5")
	)
	(segment
		(start 486.486454 -21.971)
		(end 487.9086 -21.971)
		(width 0.089408)
		(layer "In2.Cu")
		(net "UART_BMC_TXD5")
	)
	(segment
		(start 432.127406 -19.890486)
		(end 432.533298 -19.890486)
		(width 0.089408)
		(layer "In2.Cu")
		(net "UART_BMC_TXD5")
	)
	(segment
		(start 456.98029 -22.815296)
		(end 457.495656 -22.815296)
		(width 0.089408)
		(layer "In2.Cu")
		(net "UART_BMC_TXD5")
	)
	(segment
		(start 423.362374 -21.427694)
		(end 426.531024 -21.427694)
		(width 0.089408)
		(layer "In2.Cu")
		(net "UART_BMC_TXD5")
	)
	(segment
		(start 457.495656 -22.815296)
		(end 458.93609 -21.374862)
		(width 0.089408)
		(layer "In2.Cu")
		(net "UART_BMC_TXD5")
	)
	(segment
		(start 409.422092 -24.85771)
		(end 409.421838 -24.85771)
		(width 0.089408)
		(layer "In4.Cu")
		(net "UART_BMC_TXD5")
	)
	(segment
		(start 403.794976 -27.524456)
		(end 402.99005 -27.524456)
		(width 0.089408)
		(layer "In4.Cu")
		(net "UART_BMC_TXD5")
	)
	(segment
		(start 406.65654 -26.958036)
		(end 404.361396 -26.958036)
		(width 0.089408)
		(layer "In4.Cu")
		(net "UART_BMC_TXD5")
	)
	(segment
		(start 402.496274 -27.03068)
		(end 401.588478 -27.03068)
		(width 0.089408)
		(layer "In4.Cu")
		(net "UART_BMC_TXD5")
	)
	(segment
		(start 388.581646 -25.9334)
		(end 386.54863 -25.9334)
		(width 0.089408)
		(layer "In4.Cu")
		(net "UART_BMC_TXD5")
	)
	(segment
		(start 400.118834 -27.245056)
		(end 399.726658 -26.85288)
		(width 0.089408)
		(layer "In4.Cu")
		(net "UART_BMC_TXD5")
	)
	(segment
		(start 492.596424 -32.256984)
		(end 495.7318 -35.39236)
		(width 0.089408)
		(layer "In4.Cu")
		(net "UART_BMC_TXD5")
	)
	(segment
		(start 495.7318 -35.39236)
		(end 495.7318 -35.814)
		(width 0.089408)
		(layer "In4.Cu")
		(net "UART_BMC_TXD5")
	)
	(segment
		(start 492.596424 -29.932376)
		(end 492.596424 -32.256984)
		(width 0.089408)
		(layer "In4.Cu")
		(net "UART_BMC_TXD5")
	)
	(segment
		(start 488.5182 -23.9522)
		(end 488.5182 -24.6126)
		(width 0.089408)
		(layer "In4.Cu")
		(net "UART_BMC_TXD5")
	)
	(segment
		(start 392.632184 -27.291538)
		(end 392.05281 -26.712164)
		(width 0.089408)
		(layer "In4.Cu")
		(net "UART_BMC_TXD5")
	)
	(segment
		(start 400.697954 -27.245056)
		(end 400.118834 -27.245056)
		(width 0.089408)
		(layer "In4.Cu")
		(net "UART_BMC_TXD5")
	)
	(segment
		(start 410.900118 -24.812244)
		(end 409.467558 -24.812244)
		(width 0.089408)
		(layer "In4.Cu")
		(net "UART_BMC_TXD5")
	)
	(segment
		(start 408.637232 -25.642316)
		(end 407.97226 -25.642316)
		(width 0.089408)
		(layer "In4.Cu")
		(net "UART_BMC_TXD5")
	)
	(segment
		(start 488.5182 -24.6126)
		(end 488.10037 -25.03043)
		(width 0.089408)
		(layer "In4.Cu")
		(net "UART_BMC_TXD5")
	)
	(segment
		(start 394.941298 -26.5684)
		(end 394.21816 -27.291538)
		(width 0.089408)
		(layer "In4.Cu")
		(net "UART_BMC_TXD5")
	)
	(segment
		(start 488.10037 -25.436322)
		(end 492.596424 -29.932376)
		(width 0.089408)
		(layer "In4.Cu")
		(net "UART_BMC_TXD5")
	)
	(segment
		(start 399.31721 -26.85288)
		(end 399.03273 -26.5684)
		(width 0.089408)
		(layer "In4.Cu")
		(net "UART_BMC_TXD5")
	)
	(segment
		(start 407.97226 -25.642316)
		(end 406.65654 -26.958036)
		(width 0.089408)
		(layer "In4.Cu")
		(net "UART_BMC_TXD5")
	)
	(segment
		(start 400.698208 -27.244802)
		(end 400.697954 -27.245056)
		(width 0.089408)
		(layer "In4.Cu")
		(net "UART_BMC_TXD5")
	)
	(segment
		(start 414.339278 -24.193246)
		(end 411.519116 -24.193246)
		(width 0.089408)
		(layer "In4.Cu")
		(net "UART_BMC_TXD5")
	)
	(segment
		(start 386.54863 -25.9334)
		(end 386.250434 -25.635204)
		(width 0.089408)
		(layer "In4.Cu")
		(net "UART_BMC_TXD5")
	)
	(segment
		(start 411.519116 -24.193246)
		(end 410.900118 -24.812244)
		(width 0.089408)
		(layer "In4.Cu")
		(net "UART_BMC_TXD5")
	)
	(segment
		(start 404.361396 -26.958036)
		(end 403.794976 -27.524456)
		(width 0.089408)
		(layer "In4.Cu")
		(net "UART_BMC_TXD5")
	)
	(segment
		(start 386.250434 -25.635204)
		(end 385.683252 -25.635204)
		(width 0.089408)
		(layer "In4.Cu")
		(net "UART_BMC_TXD5")
	)
	(segment
		(start 389.36041 -26.712164)
		(end 388.581646 -25.9334)
		(width 0.089408)
		(layer "In4.Cu")
		(net "UART_BMC_TXD5")
	)
	(segment
		(start 394.21816 -27.291538)
		(end 392.632184 -27.291538)
		(width 0.089408)
		(layer "In4.Cu")
		(net "UART_BMC_TXD5")
	)
	(segment
		(start 399.03273 -26.5684)
		(end 394.941298 -26.5684)
		(width 0.089408)
		(layer "In4.Cu")
		(net "UART_BMC_TXD5")
	)
	(segment
		(start 488.10037 -25.03043)
		(end 488.10037 -25.436322)
		(width 0.089408)
		(layer "In4.Cu")
		(net "UART_BMC_TXD5")
	)
	(segment
		(start 401.374356 -27.244802)
		(end 400.698208 -27.244802)
		(width 0.089408)
		(layer "In4.Cu")
		(net "UART_BMC_TXD5")
	)
	(segment
		(start 414.529524 -24.003)
		(end 414.339278 -24.193246)
		(width 0.089408)
		(layer "In4.Cu")
		(net "UART_BMC_TXD5")
	)
	(segment
		(start 401.588478 -27.03068)
		(end 401.374356 -27.244802)
		(width 0.089408)
		(layer "In4.Cu")
		(net "UART_BMC_TXD5")
	)
	(segment
		(start 409.421838 -24.85771)
		(end 408.637232 -25.642316)
		(width 0.089408)
		(layer "In4.Cu")
		(net "UART_BMC_TXD5")
	)
	(segment
		(start 402.99005 -27.524456)
		(end 402.496274 -27.03068)
		(width 0.089408)
		(layer "In4.Cu")
		(net "UART_BMC_TXD5")
	)
	(segment
		(start 399.726658 -26.85288)
		(end 399.31721 -26.85288)
		(width 0.089408)
		(layer "In4.Cu")
		(net "UART_BMC_TXD5")
	)
	(segment
		(start 392.05281 -26.712164)
		(end 389.36041 -26.712164)
		(width 0.089408)
		(layer "In4.Cu")
		(net "UART_BMC_TXD5")
	)
	(segment
		(start 409.467558 -24.812244)
		(end 409.422092 -24.85771)
		(width 0.089408)
		(layer "In4.Cu")
		(net "UART_BMC_TXD5")
	)
	(segment
		(start 376.590052 -71.521828)
		(end 376.846084 -71.521828)
		(width 0.089408)
		(layer "In9.Cu")
		(net "UART_BMC_TXD5")
	)
	(segment
		(start 381.046228 -37.037772)
		(end 380.795784 -36.787328)
		(width 0.089408)
		(layer "In9.Cu")
		(net "UART_BMC_TXD5")
	)
	(segment
		(start 382.199134 -43.566842)
		(end 380.839218 -42.206926)
		(width 0.089408)
		(layer "In9.Cu")
		(net "UART_BMC_TXD5")
	)
	(segment
		(start 375.843546 -72.268588)
		(end 376.099578 -72.268588)
		(width 0.089408)
		(layer "In9.Cu")
		(net "UART_BMC_TXD5")
	)
	(segment
		(start 376.092212 -75.475592)
		(end 376.318272 -75.249532)
		(width 0.089408)
		(layer "In9.Cu")
		(net "UART_BMC_TXD5")
	)
	(segment
		(start 376.846084 -71.521828)
		(end 377.2408 -71.127112)
		(width 0.089408)
		(layer "In9.Cu")
		(net "UART_BMC_TXD5")
	)
	(segment
		(start 378.124466 -66.111882)
		(end 378.124466 -65.280286)
		(width 0.089408)
		(layer "In9.Cu")
		(net "UART_BMC_TXD5")
	)
	(segment
		(start 377.2408 -70.597522)
		(end 378.909072 -68.92925)
		(width 0.089408)
		(layer "In9.Cu")
		(net "UART_BMC_TXD5")
	)
	(segment
		(start 381.429006 -40.887904)
		(end 381.836676 -40.480234)
		(width 0.089408)
		(layer "In9.Cu")
		(net "UART_BMC_TXD5")
	)
	(segment
		(start 377.2408 -71.127112)
		(end 377.2408 -70.597522)
		(width 0.089408)
		(layer "In9.Cu")
		(net "UART_BMC_TXD5")
	)
	(segment
		(start 381.881126 -56.573674)
		(end 381.712978 -56.405526)
		(width 0.089408)
		(layer "In9.Cu")
		(net "UART_BMC_TXD5")
	)
	(segment
		(start 378.908818 -68.222876)
		(end 378.746258 -68.060316)
		(width 0.089408)
		(layer "In9.Cu")
		(net "UART_BMC_TXD5")
	)
	(segment
		(start 385.683252 -27.574748)
		(end 385.683252 -25.635204)
		(width 0.089408)
		(layer "In9.Cu")
		(net "UART_BMC_TXD5")
	)
	(segment
		(start 385.09448 -30.690058)
		(end 385.09448 -28.16352)
		(width 0.089408)
		(layer "In9.Cu")
		(net "UART_BMC_TXD5")
	)
	(segment
		(start 376.099578 -72.268588)
		(end 376.34164 -72.026526)
		(width 0.089408)
		(layer "In9.Cu")
		(net "UART_BMC_TXD5")
	)
	(segment
		(start 375.571512 -72.540622)
		(end 375.843546 -72.268588)
		(width 0.089408)
		(layer "In9.Cu")
		(net "UART_BMC_TXD5")
	)
	(segment
		(start 380.839218 -41.194228)
		(end 381.145542 -40.887904)
		(width 0.089408)
		(layer "In9.Cu")
		(net "UART_BMC_TXD5")
	)
	(segment
		(start 376.34164 -71.77024)
		(end 376.590052 -71.521828)
		(width 0.089408)
		(layer "In9.Cu")
		(net "UART_BMC_TXD5")
	)
	(segment
		(start 375.571512 -73.68667)
		(end 375.571512 -72.540622)
		(width 0.089408)
		(layer "In9.Cu")
		(net "UART_BMC_TXD5")
	)
	(segment
		(start 379.386338 -63.39078)
		(end 379.386338 -63.365634)
		(width 0.089408)
		(layer "In9.Cu")
		(net "UART_BMC_TXD5")
	)
	(segment
		(start 382.669542 -34.459418)
		(end 382.669542 -32.951166)
		(width 0.089408)
		(layer "In9.Cu")
		(net "UART_BMC_TXD5")
	)
	(segment
		(start 375.144792 -75.894692)
		(end 375.563892 -75.475592)
		(width 0.089408)
		(layer "In9.Cu")
		(net "UART_BMC_TXD5")
	)
	(segment
		(start 379.386338 -63.365634)
		(end 379.386084 -63.36538)
		(width 0.089408)
		(layer "In9.Cu")
		(net "UART_BMC_TXD5")
	)
	(segment
		(start 378.124212 -65.037716)
		(end 378.286772 -64.875156)
		(width 0.089408)
		(layer "In9.Cu")
		(net "UART_BMC_TXD5")
	)
	(segment
		(start 382.669542 -32.951166)
		(end 384.112008 -31.5087)
		(width 0.089408)
		(layer "In9.Cu")
		(net "UART_BMC_TXD5")
	)
	(segment
		(start 378.746258 -68.060316)
		(end 378.746258 -66.733674)
		(width 0.089408)
		(layer "In9.Cu")
		(net "UART_BMC_TXD5")
	)
	(segment
		(start 378.909072 -68.92925)
		(end 378.909072 -68.461382)
		(width 0.089408)
		(layer "In9.Cu")
		(net "UART_BMC_TXD5")
	)
	(segment
		(start 376.318272 -74.43343)
		(end 375.571512 -73.68667)
		(width 0.089408)
		(layer "In9.Cu")
		(net "UART_BMC_TXD5")
	)
	(segment
		(start 378.908818 -68.461128)
		(end 378.908818 -68.222876)
		(width 0.089408)
		(layer "In9.Cu")
		(net "UART_BMC_TXD5")
	)
	(segment
		(start 375.563892 -75.475592)
		(end 376.092212 -75.475592)
		(width 0.089408)
		(layer "In9.Cu")
		(net "UART_BMC_TXD5")
	)
	(segment
		(start 378.746258 -66.733674)
		(end 378.124466 -66.111882)
		(width 0.089408)
		(layer "In9.Cu")
		(net "UART_BMC_TXD5")
	)
	(segment
		(start 378.286772 -64.490346)
		(end 379.386338 -63.39078)
		(width 0.089408)
		(layer "In9.Cu")
		(net "UART_BMC_TXD5")
	)
	(segment
		(start 380.334774 -60.560966)
		(end 381.881126 -59.014614)
		(width 0.089408)
		(layer "In9.Cu")
		(net "UART_BMC_TXD5")
	)
	(segment
		(start 381.194564 -35.102038)
		(end 382.026922 -35.102038)
		(width 0.089408)
		(layer "In9.Cu")
		(net "UART_BMC_TXD5")
	)
	(segment
		(start 376.34164 -72.026526)
		(end 376.34164 -71.77024)
		(width 0.089408)
		(layer "In9.Cu")
		(net "UART_BMC_TXD5")
	)
	(segment
		(start 382.026922 -35.102038)
		(end 382.669542 -34.459418)
		(width 0.089408)
		(layer "In9.Cu")
		(net "UART_BMC_TXD5")
	)
	(segment
		(start 381.046228 -37.973)
		(end 381.046228 -37.037772)
		(width 0.089408)
		(layer "In9.Cu")
		(net "UART_BMC_TXD5")
	)
	(segment
		(start 380.839218 -42.206926)
		(end 380.839218 -41.194228)
		(width 0.089408)
		(layer "In9.Cu")
		(net "UART_BMC_TXD5")
	)
	(segment
		(start 381.712978 -46.378622)
		(end 382.199134 -45.892466)
		(width 0.089408)
		(layer "In9.Cu")
		(net "UART_BMC_TXD5")
	)
	(segment
		(start 379.386084 -62.88024)
		(end 380.334774 -61.93155)
		(width 0.089408)
		(layer "In9.Cu")
		(net "UART_BMC_TXD5")
	)
	(segment
		(start 381.145542 -40.887904)
		(end 381.429006 -40.887904)
		(width 0.089408)
		(layer "In9.Cu")
		(net "UART_BMC_TXD5")
	)
	(segment
		(start 382.199134 -45.892466)
		(end 382.199134 -43.566842)
		(width 0.089408)
		(layer "In9.Cu")
		(net "UART_BMC_TXD5")
	)
	(segment
		(start 385.09448 -28.16352)
		(end 385.683252 -27.574748)
		(width 0.089408)
		(layer "In9.Cu")
		(net "UART_BMC_TXD5")
	)
	(segment
		(start 381.712978 -56.405526)
		(end 381.712978 -46.378622)
		(width 0.089408)
		(layer "In9.Cu")
		(net "UART_BMC_TXD5")
	)
	(segment
		(start 378.286772 -64.875156)
		(end 378.286772 -64.490346)
		(width 0.089408)
		(layer "In9.Cu")
		(net "UART_BMC_TXD5")
	)
	(segment
		(start 380.795784 -35.500818)
		(end 381.194564 -35.102038)
		(width 0.089408)
		(layer "In9.Cu")
		(net "UART_BMC_TXD5")
	)
	(segment
		(start 381.881126 -59.014614)
		(end 381.881126 -56.573674)
		(width 0.089408)
		(layer "In9.Cu")
		(net "UART_BMC_TXD5")
	)
	(segment
		(start 380.795784 -36.787328)
		(end 380.795784 -35.500818)
		(width 0.089408)
		(layer "In9.Cu")
		(net "UART_BMC_TXD5")
	)
	(segment
		(start 380.334774 -61.93155)
		(end 380.334774 -60.560966)
		(width 0.089408)
		(layer "In9.Cu")
		(net "UART_BMC_TXD5")
	)
	(segment
		(start 379.386084 -63.36538)
		(end 379.386084 -62.88024)
		(width 0.089408)
		(layer "In9.Cu")
		(net "UART_BMC_TXD5")
	)
	(segment
		(start 378.124212 -65.280032)
		(end 378.124212 -65.037716)
		(width 0.089408)
		(layer "In9.Cu")
		(net "UART_BMC_TXD5")
	)
	(segment
		(start 378.124466 -65.280286)
		(end 378.124212 -65.280032)
		(width 0.089408)
		(layer "In9.Cu")
		(net "UART_BMC_TXD5")
	)
	(segment
		(start 376.318272 -75.249532)
		(end 376.318272 -74.43343)
		(width 0.089408)
		(layer "In9.Cu")
		(net "UART_BMC_TXD5")
	)
	(segment
		(start 384.275838 -31.5087)
		(end 385.09448 -30.690058)
		(width 0.089408)
		(layer "In9.Cu")
		(net "UART_BMC_TXD5")
	)
	(segment
		(start 378.909072 -68.461382)
		(end 378.908818 -68.461128)
		(width 0.089408)
		(layer "In9.Cu")
		(net "UART_BMC_TXD5")
	)
	(segment
		(start 384.112008 -31.5087)
		(end 384.275838 -31.5087)
		(width 0.089408)
		(layer "In9.Cu")
		(net "UART_BMC_TXD5")
	)
	(segment
		(start 381.836676 -40.480234)
		(end 381.836676 -38.763448)
		(width 0.089408)
		(layer "In9.Cu")
		(net "UART_BMC_TXD5")
	)
	(segment
		(start 381.836676 -38.763448)
		(end 381.046228 -37.973)
		(width 0.089408)
		(layer "In9.Cu")
		(net "UART_BMC_TXD5")
	)
	(segment
		(start 414.673796 -26.951178)
		(end 414.290256 -27.334718)
		(width 0.10795)
		(layer "F.Cu")
		(net "UART_BMC_RXD5")
	)
	(segment
		(start 375.545096 -74.69505)
		(end 375.944892 -75.094846)
		(width 0.10795)
		(layer "F.Cu")
		(net "UART_BMC_RXD5")
	)
	(via
		(at 375.944892 -75.094846)
		(size 0.4572)
		(drill 0.2032)
		(layers "F.Cu" "B.Cu")
		(net "UART_BMC_RXD5")
	)
	(via
		(at 491.791498 -36.579302)
		(size 0.508)
		(drill 0.254)
		(layers "F.Cu" "B.Cu")
		(net "UART_BMC_RXD5")
	)
	(via
		(at 414.673796 -26.951178)
		(size 0.4572)
		(drill 0.2032)
		(layers "F.Cu" "B.Cu")
		(net "UART_BMC_RXD5")
	)
	(via
		(at 487.172508 -25.121108)
		(size 0.508)
		(drill 0.254)
		(layers "F.Cu" "B.Cu")
		(net "UART_BMC_RXD5")
	)
	(segment
		(start 489.078778 -36.3474)
		(end 489.481114 -35.945064)
		(width 0.10795)
		(layer "B.Cu")
		(net "UART_BMC_RXD5")
	)
	(segment
		(start 489.481114 -35.945064)
		(end 490.203998 -35.945064)
		(width 0.10795)
		(layer "B.Cu")
		(net "UART_BMC_RXD5")
	)
	(segment
		(start 491.791498 -36.579302)
		(end 491.15726 -35.945064)
		(width 0.10795)
		(layer "B.Cu")
		(net "UART_BMC_RXD5")
	)
	(segment
		(start 488.5944 -36.3474)
		(end 489.078778 -36.3474)
		(width 0.10795)
		(layer "B.Cu")
		(net "UART_BMC_RXD5")
	)
	(segment
		(start 491.15726 -35.945064)
		(end 490.203998 -35.945064)
		(width 0.10795)
		(layer "B.Cu")
		(net "UART_BMC_RXD5")
	)
	(segment
		(start 388.003542 -35.229546)
		(end 388.003542 -33.489138)
		(width 0.089408)
		(layer "In2.Cu")
		(net "UART_BMC_RXD5")
	)
	(segment
		(start 381.387858 -72.90562)
		(end 380.83871 -72.356472)
		(width 0.089408)
		(layer "In2.Cu")
		(net "UART_BMC_RXD5")
	)
	(segment
		(start 380.394972 -70.20052)
		(end 380.753112 -70.20052)
		(width 0.089408)
		(layer "In2.Cu")
		(net "UART_BMC_RXD5")
	)
	(segment
		(start 459.711806 -28.12796)
		(end 459.711806 -28.538932)
		(width 0.089408)
		(layer "In2.Cu")
		(net "UART_BMC_RXD5")
	)
	(segment
		(start 411.329378 -28.934664)
		(end 412.104078 -28.159964)
		(width 0.089408)
		(layer "In2.Cu")
		(net "UART_BMC_RXD5")
	)
	(segment
		(start 459.316074 -29.25064)
		(end 460.161132 -30.095698)
		(width 0.089408)
		(layer "In2.Cu")
		(net "UART_BMC_RXD5")
	)
	(segment
		(start 380.83871 -72.356472)
		(end 379.697234 -72.356472)
		(width 0.089408)
		(layer "In2.Cu")
		(net "UART_BMC_RXD5")
	)
	(segment
		(start 380.078742 -70.207378)
		(end 380.388114 -70.207378)
		(width 0.089408)
		(layer "In2.Cu")
		(net "UART_BMC_RXD5")
	)
	(segment
		(start 382.778762 -56.040274)
		(end 382.509776 -55.771288)
		(width 0.089408)
		(layer "In2.Cu")
		(net "UART_BMC_RXD5")
	)
	(segment
		(start 381.794004 -74.173334)
		(end 381.387858 -73.767188)
		(width 0.089408)
		(layer "In2.Cu")
		(net "UART_BMC_RXD5")
	)
	(segment
		(start 392.1506 -31.6484)
		(end 394.418312 -29.380688)
		(width 0.089408)
		(layer "In2.Cu")
		(net "UART_BMC_RXD5")
	)
	(segment
		(start 382.778762 -61.434218)
		(end 382.778762 -56.040274)
		(width 0.089408)
		(layer "In2.Cu")
		(net "UART_BMC_RXD5")
	)
	(segment
		(start 380.753112 -70.20052)
		(end 381.343408 -69.610224)
		(width 0.089408)
		(layer "In2.Cu")
		(net "UART_BMC_RXD5")
	)
	(segment
		(start 476.494856 -24.148034)
		(end 480.271836 -24.148034)
		(width 0.089408)
		(layer "In2.Cu")
		(net "UART_BMC_RXD5")
	)
	(segment
		(start 382.509776 -51.815238)
		(end 382.699514 -51.6255)
		(width 0.089408)
		(layer "In2.Cu")
		(net "UART_BMC_RXD5")
	)
	(segment
		(start 460.161132 -30.095698)
		(end 461.679798 -30.095698)
		(width 0.089408)
		(layer "In2.Cu")
		(net "UART_BMC_RXD5")
	)
	(segment
		(start 414.673796 -26.951178)
		(end 414.955228 -26.669746)
		(width 0.089408)
		(layer "In2.Cu")
		(net "UART_BMC_RXD5")
	)
	(segment
		(start 412.924752 -28.14955)
		(end 414.148016 -28.14955)
		(width 0.089408)
		(layer "In2.Cu")
		(net "UART_BMC_RXD5")
	)
	(segment
		(start 381.343408 -68.561712)
		(end 383.474976 -66.430144)
		(width 0.089408)
		(layer "In2.Cu")
		(net "UART_BMC_RXD5")
	)
	(segment
		(start 412.104078 -28.159964)
		(end 412.914338 -28.159964)
		(width 0.089408)
		(layer "In2.Cu")
		(net "UART_BMC_RXD5")
	)
	(segment
		(start 450.76999 -24.023574)
		(end 455.60742 -24.023574)
		(width 0.089408)
		(layer "In2.Cu")
		(net "UART_BMC_RXD5")
	)
	(segment
		(start 384.88239 -40.002206)
		(end 385.864608 -39.019988)
		(width 0.089408)
		(layer "In2.Cu")
		(net "UART_BMC_RXD5")
	)
	(segment
		(start 485.245156 -27.8765)
		(end 487.172508 -25.949148)
		(width 0.089408)
		(layer "In2.Cu")
		(net "UART_BMC_RXD5")
	)
	(segment
		(start 387.516878 -35.715956)
		(end 387.517132 -35.715956)
		(width 0.089408)
		(layer "In2.Cu")
		(net "UART_BMC_RXD5")
	)
	(segment
		(start 381.343408 -69.610224)
		(end 381.343408 -68.561712)
		(width 0.089408)
		(layer "In2.Cu")
		(net "UART_BMC_RXD5")
	)
	(segment
		(start 382.699514 -51.6255)
		(end 382.699514 -50.940208)
		(width 0.089408)
		(layer "In2.Cu")
		(net "UART_BMC_RXD5")
	)
	(segment
		(start 381.512064 -75.060302)
		(end 381.794004 -74.778362)
		(width 0.089408)
		(layer "In2.Cu")
		(net "UART_BMC_RXD5")
	)
	(segment
		(start 414.269936 -28.02763)
		(end 414.269936 -27.355038)
		(width 0.089408)
		(layer "In2.Cu")
		(net "UART_BMC_RXD5")
	)
	(segment
		(start 387.282436 -35.950398)
		(end 387.516878 -35.715956)
		(width 0.089408)
		(layer "In2.Cu")
		(net "UART_BMC_RXD5")
	)
	(segment
		(start 444.803784 -21.22043)
		(end 445.622172 -22.038818)
		(width 0.089408)
		(layer "In2.Cu")
		(net "UART_BMC_RXD5")
	)
	(segment
		(start 387.282436 -36.576762)
		(end 387.282436 -35.950398)
		(width 0.089408)
		(layer "In2.Cu")
		(net "UART_BMC_RXD5")
	)
	(segment
		(start 404.590758 -28.123896)
		(end 405.283924 -27.43073)
		(width 0.089408)
		(layer "In2.Cu")
		(net "UART_BMC_RXD5")
	)
	(segment
		(start 378.844302 -75.060302)
		(end 381.512064 -75.060302)
		(width 0.089408)
		(layer "In2.Cu")
		(net "UART_BMC_RXD5")
	)
	(segment
		(start 484.000302 -27.8765)
		(end 485.245156 -27.8765)
		(width 0.089408)
		(layer "In2.Cu")
		(net "UART_BMC_RXD5")
	)
	(segment
		(start 384.88239 -44.597828)
		(end 384.88239 -40.002206)
		(width 0.089408)
		(layer "In2.Cu")
		(net "UART_BMC_RXD5")
	)
	(segment
		(start 378.505466 -74.721466)
		(end 378.844302 -75.060302)
		(width 0.089408)
		(layer "In2.Cu")
		(net "UART_BMC_RXD5")
	)
	(segment
		(start 425.704254 -24.27732)
		(end 427.470062 -22.511512)
		(width 0.089408)
		(layer "In2.Cu")
		(net "UART_BMC_RXD5")
	)
	(segment
		(start 459.711806 -28.538932)
		(end 459.316074 -28.934664)
		(width 0.089408)
		(layer "In2.Cu")
		(net "UART_BMC_RXD5")
	)
	(segment
		(start 403.961854 -29.63672)
		(end 404.59152 -29.007054)
		(width 0.089408)
		(layer "In2.Cu")
		(net "UART_BMC_RXD5")
	)
	(segment
		(start 391.357358 -31.6484)
		(end 392.1506 -31.6484)
		(width 0.089408)
		(layer "In2.Cu")
		(net "UART_BMC_RXD5")
	)
	(segment
		(start 382.699514 -50.940208)
		(end 382.699006 -50.9397)
		(width 0.089408)
		(layer "In2.Cu")
		(net "UART_BMC_RXD5")
	)
	(segment
		(start 388.003542 -33.489138)
		(end 389.38708 -32.1056)
		(width 0.089408)
		(layer "In2.Cu")
		(net "UART_BMC_RXD5")
	)
	(segment
		(start 382.509776 -55.771288)
		(end 382.509776 -51.815238)
		(width 0.089408)
		(layer "In2.Cu")
		(net "UART_BMC_RXD5")
	)
	(segment
		(start 404.590758 -28.45562)
		(end 404.590758 -28.123896)
		(width 0.089408)
		(layer "In2.Cu")
		(net "UART_BMC_RXD5")
	)
	(segment
		(start 445.622172 -22.038818)
		(end 448.785234 -22.038818)
		(width 0.089408)
		(layer "In2.Cu")
		(net "UART_BMC_RXD5")
	)
	(segment
		(start 448.785234 -22.038818)
		(end 450.76999 -24.023574)
		(width 0.089408)
		(layer "In2.Cu")
		(net "UART_BMC_RXD5")
	)
	(segment
		(start 480.271836 -24.148034)
		(end 484.000302 -27.8765)
		(width 0.089408)
		(layer "In2.Cu")
		(net "UART_BMC_RXD5")
	)
	(segment
		(start 385.864608 -37.99459)
		(end 387.282436 -36.576762)
		(width 0.089408)
		(layer "In2.Cu")
		(net "UART_BMC_RXD5")
	)
	(segment
		(start 381.387858 -73.100692)
		(end 381.387858 -72.90562)
		(width 0.089408)
		(layer "In2.Cu")
		(net "UART_BMC_RXD5")
	)
	(segment
		(start 381.794004 -74.778362)
		(end 381.794004 -74.173334)
		(width 0.089408)
		(layer "In2.Cu")
		(net "UART_BMC_RXD5")
	)
	(segment
		(start 381.397002 -73.44156)
		(end 381.397002 -73.109836)
		(width 0.089408)
		(layer "In2.Cu")
		(net "UART_BMC_RXD5")
	)
	(segment
		(start 431.73777 -22.154134)
		(end 432.73345 -22.154134)
		(width 0.089408)
		(layer "In2.Cu")
		(net "UART_BMC_RXD5")
	)
	(segment
		(start 400.27479 -29.63672)
		(end 403.961854 -29.63672)
		(width 0.089408)
		(layer "In2.Cu")
		(net "UART_BMC_RXD5")
	)
	(segment
		(start 432.73345 -22.154134)
		(end 433.667154 -21.22043)
		(width 0.089408)
		(layer "In2.Cu")
		(net "UART_BMC_RXD5")
	)
	(segment
		(start 405.283924 -27.43073)
		(end 405.595328 -27.43073)
		(width 0.089408)
		(layer "In2.Cu")
		(net "UART_BMC_RXD5")
	)
	(segment
		(start 383.474976 -63.95339)
		(end 382.61798 -63.096394)
		(width 0.089408)
		(layer "In2.Cu")
		(net "UART_BMC_RXD5")
	)
	(segment
		(start 382.61798 -63.096394)
		(end 382.61798 -61.595)
		(width 0.089408)
		(layer "In2.Cu")
		(net "UART_BMC_RXD5")
	)
	(segment
		(start 387.517132 -35.715956)
		(end 388.003542 -35.229546)
		(width 0.089408)
		(layer "In2.Cu")
		(net "UART_BMC_RXD5")
	)
	(segment
		(start 381.387858 -73.450704)
		(end 381.397002 -73.44156)
		(width 0.089408)
		(layer "In2.Cu")
		(net "UART_BMC_RXD5")
	)
	(segment
		(start 414.955228 -26.669746)
		(end 422.196006 -26.669746)
		(width 0.089408)
		(layer "In2.Cu")
		(net "UART_BMC_RXD5")
	)
	(segment
		(start 382.699006 -50.9397)
		(end 382.699006 -46.781212)
		(width 0.089408)
		(layer "In2.Cu")
		(net "UART_BMC_RXD5")
	)
	(segment
		(start 459.316074 -28.934664)
		(end 459.316074 -29.25064)
		(width 0.089408)
		(layer "In2.Cu")
		(net "UART_BMC_RXD5")
	)
	(segment
		(start 473.153994 -29.35097)
		(end 473.153994 -27.488896)
		(width 0.089408)
		(layer "In2.Cu")
		(net "UART_BMC_RXD5")
	)
	(segment
		(start 404.59152 -28.456382)
		(end 404.590758 -28.45562)
		(width 0.089408)
		(layer "In2.Cu")
		(net "UART_BMC_RXD5")
	)
	(segment
		(start 431.380392 -22.511512)
		(end 431.73777 -22.154134)
		(width 0.089408)
		(layer "In2.Cu")
		(net "UART_BMC_RXD5")
	)
	(segment
		(start 406.627076 -27.687016)
		(end 407.874724 -28.934664)
		(width 0.089408)
		(layer "In2.Cu")
		(net "UART_BMC_RXD5")
	)
	(segment
		(start 390.900158 -32.1056)
		(end 391.357358 -31.6484)
		(width 0.089408)
		(layer "In2.Cu")
		(net "UART_BMC_RXD5")
	)
	(segment
		(start 422.196006 -26.669746)
		(end 424.587162 -24.27732)
		(width 0.089408)
		(layer "In2.Cu")
		(net "UART_BMC_RXD5")
	)
	(segment
		(start 376.318272 -74.721466)
		(end 378.505466 -74.721466)
		(width 0.089408)
		(layer "In2.Cu")
		(net "UART_BMC_RXD5")
	)
	(segment
		(start 379.00102 -71.660258)
		(end 379.00102 -71.32955)
		(width 0.089408)
		(layer "In2.Cu")
		(net "UART_BMC_RXD5")
	)
	(segment
		(start 424.587162 -24.27732)
		(end 425.704254 -24.27732)
		(width 0.089408)
		(layer "In2.Cu")
		(net "UART_BMC_RXD5")
	)
	(segment
		(start 473.153994 -27.488896)
		(end 476.494856 -24.148034)
		(width 0.089408)
		(layer "In2.Cu")
		(net "UART_BMC_RXD5")
	)
	(segment
		(start 382.61798 -61.595)
		(end 382.778762 -61.434218)
		(width 0.089408)
		(layer "In2.Cu")
		(net "UART_BMC_RXD5")
	)
	(segment
		(start 379.558042 -70.772528)
		(end 379.558042 -70.728078)
		(width 0.089408)
		(layer "In2.Cu")
		(net "UART_BMC_RXD5")
	)
	(segment
		(start 400.018758 -29.380688)
		(end 400.27479 -29.63672)
		(width 0.089408)
		(layer "In2.Cu")
		(net "UART_BMC_RXD5")
	)
	(segment
		(start 464.20659 -32.62249)
		(end 468.40013 -32.62249)
		(width 0.089408)
		(layer "In2.Cu")
		(net "UART_BMC_RXD5")
	)
	(segment
		(start 380.388114 -70.207378)
		(end 380.394972 -70.20052)
		(width 0.089408)
		(layer "In2.Cu")
		(net "UART_BMC_RXD5")
	)
	(segment
		(start 379.558042 -70.728078)
		(end 380.078742 -70.207378)
		(width 0.089408)
		(layer "In2.Cu")
		(net "UART_BMC_RXD5")
	)
	(segment
		(start 405.851614 -27.687016)
		(end 406.627076 -27.687016)
		(width 0.089408)
		(layer "In2.Cu")
		(net "UART_BMC_RXD5")
	)
	(segment
		(start 414.148016 -28.14955)
		(end 414.269936 -28.02763)
		(width 0.089408)
		(layer "In2.Cu")
		(net "UART_BMC_RXD5")
	)
	(segment
		(start 461.679798 -30.095698)
		(end 464.20659 -32.62249)
		(width 0.089408)
		(layer "In2.Cu")
		(net "UART_BMC_RXD5")
	)
	(segment
		(start 389.38708 -32.1056)
		(end 390.900158 -32.1056)
		(width 0.089408)
		(layer "In2.Cu")
		(net "UART_BMC_RXD5")
	)
	(segment
		(start 414.269936 -27.355038)
		(end 414.673796 -26.951178)
		(width 0.089408)
		(layer "In2.Cu")
		(net "UART_BMC_RXD5")
	)
	(segment
		(start 468.40013 -32.62249)
		(end 471.018108 -30.004512)
		(width 0.089408)
		(layer "In2.Cu")
		(net "UART_BMC_RXD5")
	)
	(segment
		(start 472.500452 -30.004512)
		(end 473.153994 -29.35097)
		(width 0.089408)
		(layer "In2.Cu")
		(net "UART_BMC_RXD5")
	)
	(segment
		(start 427.470062 -22.511512)
		(end 431.380392 -22.511512)
		(width 0.089408)
		(layer "In2.Cu")
		(net "UART_BMC_RXD5")
	)
	(segment
		(start 394.418312 -29.380688)
		(end 400.018758 -29.380688)
		(width 0.089408)
		(layer "In2.Cu")
		(net "UART_BMC_RXD5")
	)
	(segment
		(start 407.874724 -28.934664)
		(end 411.329378 -28.934664)
		(width 0.089408)
		(layer "In2.Cu")
		(net "UART_BMC_RXD5")
	)
	(segment
		(start 471.018108 -30.004512)
		(end 472.500452 -30.004512)
		(width 0.089408)
		(layer "In2.Cu")
		(net "UART_BMC_RXD5")
	)
	(segment
		(start 381.387858 -73.767188)
		(end 381.387858 -73.450704)
		(width 0.089408)
		(layer "In2.Cu")
		(net "UART_BMC_RXD5")
	)
	(segment
		(start 383.474976 -66.430144)
		(end 383.474976 -63.95339)
		(width 0.089408)
		(layer "In2.Cu")
		(net "UART_BMC_RXD5")
	)
	(segment
		(start 381.397002 -73.109836)
		(end 381.387858 -73.100692)
		(width 0.089408)
		(layer "In2.Cu")
		(net "UART_BMC_RXD5")
	)
	(segment
		(start 375.944892 -75.094846)
		(end 376.318272 -74.721466)
		(width 0.089408)
		(layer "In2.Cu")
		(net "UART_BMC_RXD5")
	)
	(segment
		(start 404.59152 -29.007054)
		(end 404.59152 -28.456382)
		(width 0.089408)
		(layer "In2.Cu")
		(net "UART_BMC_RXD5")
	)
	(segment
		(start 433.667154 -21.22043)
		(end 444.803784 -21.22043)
		(width 0.089408)
		(layer "In2.Cu")
		(net "UART_BMC_RXD5")
	)
	(segment
		(start 385.864608 -39.019988)
		(end 385.864608 -37.99459)
		(width 0.089408)
		(layer "In2.Cu")
		(net "UART_BMC_RXD5")
	)
	(segment
		(start 405.595328 -27.43073)
		(end 405.851614 -27.687016)
		(width 0.089408)
		(layer "In2.Cu")
		(net "UART_BMC_RXD5")
	)
	(segment
		(start 382.699006 -46.781212)
		(end 384.88239 -44.597828)
		(width 0.089408)
		(layer "In2.Cu")
		(net "UART_BMC_RXD5")
	)
	(segment
		(start 487.172508 -25.949148)
		(end 487.172508 -25.121108)
		(width 0.089408)
		(layer "In2.Cu")
		(net "UART_BMC_RXD5")
	)
	(segment
		(start 379.697234 -72.356472)
		(end 379.00102 -71.660258)
		(width 0.089408)
		(layer "In2.Cu")
		(net "UART_BMC_RXD5")
	)
	(segment
		(start 412.914338 -28.159964)
		(end 412.924752 -28.14955)
		(width 0.089408)
		(layer "In2.Cu")
		(net "UART_BMC_RXD5")
	)
	(segment
		(start 379.00102 -71.32955)
		(end 379.558042 -70.772528)
		(width 0.089408)
		(layer "In2.Cu")
		(net "UART_BMC_RXD5")
	)
	(segment
		(start 455.60742 -24.023574)
		(end 459.711806 -28.12796)
		(width 0.089408)
		(layer "In2.Cu")
		(net "UART_BMC_RXD5")
	)
	(segment
		(start 491.791498 -30.228286)
		(end 491.791498 -36.579302)
		(width 0.089408)
		(layer "In4.Cu")
		(net "UART_BMC_RXD5")
	)
	(segment
		(start 487.172508 -25.121108)
		(end 487.172508 -25.609296)
		(width 0.089408)
		(layer "In4.Cu")
		(net "UART_BMC_RXD5")
	)
	(segment
		(start 487.172508 -25.609296)
		(end 491.791498 -30.228286)
		(width 0.089408)
		(layer "In4.Cu")
		(net "UART_BMC_RXD5")
	)
	(segment
		(start 491.702852 -118.459758)
		(end 487.908854 -118.459758)
		(width 0.10795)
		(layer "F.Cu")
		(net "FM_MEZZA_PRSNT1_N")
	)
	(segment
		(start 492.10722 -118.05539)
		(end 491.702852 -118.459758)
		(width 0.10795)
		(layer "F.Cu")
		(net "FM_MEZZA_PRSNT1_N")
	)
	(segment
		(start 487.908854 -118.459758)
		(end 487.800904 -118.351808)
		(width 0.10795)
		(layer "F.Cu")
		(net "FM_MEZZA_PRSNT1_N")
	)
	(segment
		(start 487.800904 -118.351808)
		(end 487.800904 -116.993162)
		(width 0.10795)
		(layer "F.Cu")
		(net "FM_MEZZA_PRSNT1_N")
	)
	(via
		(at 492.10722 -119.34444)
		(size 0.6604)
		(drill 0.3302)
		(layers "F.Cu" "B.Cu")
		(net "FM_MEZZA_PRSNT1_N")
	)
	(via
		(at 492.10722 -118.05539)
		(size 0.508)
		(drill 0.254)
		(layers "F.Cu" "B.Cu")
		(net "FM_MEZZA_PRSNT1_N")
	)
	(segment
		(start 491.4392 -116.2558)
		(end 491.7059 -116.5225)
		(width 0.10795)
		(layer "B.Cu")
		(net "FM_MEZZA_PRSNT1_N")
	)
	(segment
		(start 491.7059 -116.5225)
		(end 492.4044 -116.5225)
		(width 0.10795)
		(layer "B.Cu")
		(net "FM_MEZZA_PRSNT1_N")
	)
	(segment
		(start 492.4044 -116.526818)
		(end 492.4044 -117.75821)
		(width 0.10795)
		(layer "B.Cu")
		(net "FM_MEZZA_PRSNT1_N")
	)
	(segment
		(start 492.4044 -117.75821)
		(end 492.10722 -118.05539)
		(width 0.10795)
		(layer "B.Cu")
		(net "FM_MEZZA_PRSNT1_N")
	)
	(segment
		(start 492.10722 -118.05539)
		(end 492.10722 -119.34444)
		(width 0.10795)
		(layer "B.Cu")
		(net "FM_MEZZA_PRSNT1_N")
	)
	(segment
		(start 492.4044 -116.5225)
		(end 492.4044 -116.526818)
		(width 0.10795)
		(layer "B.Cu")
		(net "FM_MEZZA_PRSNT1_N")
	)
	(segment
		(start 369.895374 -97.756726)
		(end 369.730528 -97.756726)
		(width 0.10795)
		(layer "F.Cu")
		(net "XTAL_33K_RTC2")
	)
	(segment
		(start 377.83135 -100.41128)
		(end 378.32665 -100.181156)
		(width 0.10795)
		(layer "F.Cu")
		(net "XTAL_33K_RTC2")
	)
	(segment
		(start 369.062 -97.155)
		(end 369.062 -96.8375)
		(width 0.10795)
		(layer "F.Cu")
		(net "XTAL_33K_RTC2")
	)
	(segment
		(start 368.350546 -97.028)
		(end 367.411 -97.028)
		(width 0.10795)
		(layer "F.Cu")
		(net "XTAL_33K_RTC2")
	)
	(segment
		(start 368.541046 -96.8375)
		(end 368.350546 -97.028)
		(width 0.10795)
		(layer "F.Cu")
		(net "XTAL_33K_RTC2")
	)
	(segment
		(start 370.073174 -97.680526)
		(end 369.971574 -97.680526)
		(width 0.10795)
		(layer "F.Cu")
		(net "XTAL_33K_RTC2")
	)
	(segment
		(start 369.2906 -97.8154)
		(end 369.2906 -97.3836)
		(width 0.10795)
		(layer "F.Cu")
		(net "XTAL_33K_RTC2")
	)
	(segment
		(start 369.671854 -97.8154)
		(end 369.2906 -97.8154)
		(width 0.10795)
		(layer "F.Cu")
		(net "XTAL_33K_RTC2")
	)
	(segment
		(start 369.971574 -97.680526)
		(end 369.895374 -97.756726)
		(width 0.10795)
		(layer "F.Cu")
		(net "XTAL_33K_RTC2")
	)
	(segment
		(start 369.2906 -97.3836)
		(end 369.062 -97.155)
		(width 0.10795)
		(layer "F.Cu")
		(net "XTAL_33K_RTC2")
	)
	(segment
		(start 369.730528 -97.756726)
		(end 369.671854 -97.8154)
		(width 0.10795)
		(layer "F.Cu")
		(net "XTAL_33K_RTC2")
	)
	(segment
		(start 369.062 -96.8375)
		(end 368.541046 -96.8375)
		(width 0.10795)
		(layer "F.Cu")
		(net "XTAL_33K_RTC2")
	)
	(via
		(at 378.32665 -100.181156)
		(size 0.508)
		(drill 0.254)
		(layers "F.Cu" "B.Cu")
		(net "XTAL_33K_RTC2")
	)
	(via
		(at 370.879116 -97.266252)
		(size 0.6604)
		(drill 0.3302)
		(layers "F.Cu" "B.Cu")
		(net "XTAL_33K_RTC2")
	)
	(via
		(at 370.073174 -97.680526)
		(size 0.508)
		(drill 0.254)
		(layers "F.Cu" "B.Cu")
		(net "XTAL_33K_RTC2")
	)
	(segment
		(start 372.179342 -96.777302)
		(end 372.1227 -96.72066)
		(width 0.10795)
		(layer "B.Cu")
		(net "XTAL_33K_RTC2")
	)
	(segment
		(start 374.29694 -97.131886)
		(end 373.705882 -97.131886)
		(width 0.10795)
		(layer "B.Cu")
		(net "XTAL_33K_RTC2")
	)
	(segment
		(start 373.705882 -97.131886)
		(end 373.351298 -96.777302)
		(width 0.10795)
		(layer "B.Cu")
		(net "XTAL_33K_RTC2")
	)
	(segment
		(start 374.553226 -96.8756)
		(end 374.29694 -97.131886)
		(width 0.10795)
		(layer "B.Cu")
		(net "XTAL_33K_RTC2")
	)
	(segment
		(start 370.073174 -97.680526)
		(end 370.487448 -97.266252)
		(width 0.10795)
		(layer "B.Cu")
		(net "XTAL_33K_RTC2")
	)
	(segment
		(start 375.59742 -97.17278)
		(end 375.30024 -96.8756)
		(width 0.10795)
		(layer "B.Cu")
		(net "XTAL_33K_RTC2")
	)
	(segment
		(start 370.487448 -97.266252)
		(end 370.879116 -97.266252)
		(width 0.10795)
		(layer "B.Cu")
		(net "XTAL_33K_RTC2")
	)
	(segment
		(start 376.687588 -98.70948)
		(end 376.633994 -98.763074)
		(width 0.10795)
		(layer "B.Cu")
		(net "XTAL_33K_RTC2")
	)
	(segment
		(start 372.1227 -96.72066)
		(end 371.424708 -96.72066)
		(width 0.10795)
		(layer "B.Cu")
		(net "XTAL_33K_RTC2")
	)
	(segment
		(start 376.633994 -98.763074)
		(end 376.165618 -98.763074)
		(width 0.10795)
		(layer "B.Cu")
		(net "XTAL_33K_RTC2")
	)
	(segment
		(start 377.072144 -98.70948)
		(end 376.687588 -98.70948)
		(width 0.10795)
		(layer "B.Cu")
		(net "XTAL_33K_RTC2")
	)
	(segment
		(start 378.32665 -100.181156)
		(end 378.32665 -99.963986)
		(width 0.10795)
		(layer "B.Cu")
		(net "XTAL_33K_RTC2")
	)
	(segment
		(start 373.351298 -96.777302)
		(end 372.179342 -96.777302)
		(width 0.10795)
		(layer "B.Cu")
		(net "XTAL_33K_RTC2")
	)
	(segment
		(start 378.32665 -99.963986)
		(end 377.072144 -98.70948)
		(width 0.10795)
		(layer "B.Cu")
		(net "XTAL_33K_RTC2")
	)
	(segment
		(start 375.30024 -96.8756)
		(end 374.553226 -96.8756)
		(width 0.10795)
		(layer "B.Cu")
		(net "XTAL_33K_RTC2")
	)
	(segment
		(start 376.165618 -98.763074)
		(end 375.59742 -98.194876)
		(width 0.10795)
		(layer "B.Cu")
		(net "XTAL_33K_RTC2")
	)
	(segment
		(start 371.424708 -96.72066)
		(end 370.879116 -97.266252)
		(width 0.10795)
		(layer "B.Cu")
		(net "XTAL_33K_RTC2")
	)
	(segment
		(start 375.59742 -98.194876)
		(end 375.59742 -97.17278)
		(width 0.10795)
		(layer "B.Cu")
		(net "XTAL_33K_RTC2")
	)
	(segment
		(start 370.0526 -98.51136)
		(end 370.0526 -98.4504)
		(width 0.10795)
		(layer "F.Cu")
		(net "XTAL_33K_RTC1")
	)
	(segment
		(start 369.2906 -100.2284)
		(end 368.5794 -100.2284)
		(width 0.10795)
		(layer "F.Cu")
		(net "XTAL_33K_RTC1")
	)
	(segment
		(start 369.35156 -99.2124)
		(end 370.0526 -98.51136)
		(width 0.10795)
		(layer "F.Cu")
		(net "XTAL_33K_RTC1")
	)
	(segment
		(start 378.82195 -100.41128)
		(end 379.31725 -100.181156)
		(width 0.10795)
		(layer "F.Cu")
		(net "XTAL_33K_RTC1")
	)
	(segment
		(start 368.427 -100.076)
		(end 367.411 -100.076)
		(width 0.10795)
		(layer "F.Cu")
		(net "XTAL_33K_RTC1")
	)
	(segment
		(start 368.5794 -100.2284)
		(end 368.427 -100.076)
		(width 0.10795)
		(layer "F.Cu")
		(net "XTAL_33K_RTC1")
	)
	(segment
		(start 369.2906 -99.2124)
		(end 369.35156 -99.2124)
		(width 0.10795)
		(layer "F.Cu")
		(net "XTAL_33K_RTC1")
	)
	(segment
		(start 369.2906 -99.2124)
		(end 369.2906 -100.2284)
		(width 0.10795)
		(layer "F.Cu")
		(net "XTAL_33K_RTC1")
	)
	(via
		(at 370.0526 -98.4504)
		(size 0.508)
		(drill 0.254)
		(layers "F.Cu" "B.Cu")
		(net "XTAL_33K_RTC1")
	)
	(via
		(at 379.31725 -100.181156)
		(size 0.508)
		(drill 0.254)
		(layers "F.Cu" "B.Cu")
		(net "XTAL_33K_RTC1")
	)
	(segment
		(start 375.177812 -98.083624)
		(end 376.679968 -99.58578)
		(width 0.10795)
		(layer "B.Cu")
		(net "XTAL_33K_RTC1")
	)
	(segment
		(start 378.909072 -100.589334)
		(end 379.31725 -100.181156)
		(width 0.10795)
		(layer "B.Cu")
		(net "XTAL_33K_RTC1")
	)
	(segment
		(start 374.057164 -98.083624)
		(end 375.177812 -98.083624)
		(width 0.10795)
		(layer "B.Cu")
		(net "XTAL_33K_RTC1")
	)
	(segment
		(start 376.679968 -99.58578)
		(end 377.333764 -99.58578)
		(width 0.10795)
		(layer "B.Cu")
		(net "XTAL_33K_RTC1")
	)
	(segment
		(start 377.688094 -99.94011)
		(end 377.688094 -100.182426)
		(width 0.10795)
		(layer "B.Cu")
		(net "XTAL_33K_RTC1")
	)
	(segment
		(start 378.095002 -100.589334)
		(end 378.909072 -100.589334)
		(width 0.10795)
		(layer "B.Cu")
		(net "XTAL_33K_RTC1")
	)
	(segment
		(start 371.14988 -98.31832)
		(end 373.822468 -98.31832)
		(width 0.10795)
		(layer "B.Cu")
		(net "XTAL_33K_RTC1")
	)
	(segment
		(start 377.333764 -99.58578)
		(end 377.688094 -99.94011)
		(width 0.10795)
		(layer "B.Cu")
		(net "XTAL_33K_RTC1")
	)
	(segment
		(start 373.822468 -98.31832)
		(end 374.057164 -98.083624)
		(width 0.10795)
		(layer "B.Cu")
		(net "XTAL_33K_RTC1")
	)
	(segment
		(start 370.0526 -98.4504)
		(end 371.0178 -98.4504)
		(width 0.10795)
		(layer "B.Cu")
		(net "XTAL_33K_RTC1")
	)
	(segment
		(start 377.688094 -100.182426)
		(end 378.095002 -100.589334)
		(width 0.10795)
		(layer "B.Cu")
		(net "XTAL_33K_RTC1")
	)
	(segment
		(start 371.0178 -98.4504)
		(end 371.14988 -98.31832)
		(width 0.10795)
		(layer "B.Cu")
		(net "XTAL_33K_RTC1")
	)
	(segment
		(start 375.564654 -109.354874)
		(end 375.253504 -109.043724)
		(width 0.0889)
		(layer "F.Cu")
		(net "XTAL_PCH_48M_OUT")
	)
	(segment
		(start 375.92 -109.354874)
		(end 375.564654 -109.354874)
		(width 0.0889)
		(layer "F.Cu")
		(net "XTAL_PCH_48M_OUT")
	)
	(segment
		(start 374.937782 -109.043724)
		(end 374.833388 -109.148118)
		(width 0.0889)
		(layer "F.Cu")
		(net "XTAL_PCH_48M_OUT")
	)
	(segment
		(start 369.7224 -107.2134)
		(end 369.615466 -107.106466)
		(width 0.10795)
		(layer "F.Cu")
		(net "XTAL_PCH_48M_OUT")
	)
	(segment
		(start 371.874542 -109.148118)
		(end 371.168676 -108.442252)
		(width 0.0889)
		(layer "F.Cu")
		(net "XTAL_PCH_48M_OUT")
	)
	(segment
		(start 371.168676 -108.442252)
		(end 369.939824 -107.2134)
		(width 0.10795)
		(layer "F.Cu")
		(net "XTAL_PCH_48M_OUT")
	)
	(segment
		(start 367.759234 -106.5149)
		(end 367.1062 -106.5149)
		(width 0.10795)
		(layer "F.Cu")
		(net "XTAL_PCH_48M_OUT")
	)
	(segment
		(start 368.69624 -107.106466)
		(end 368.3508 -107.106466)
		(width 0.10795)
		(layer "F.Cu")
		(net "XTAL_PCH_48M_OUT")
	)
	(segment
		(start 369.939824 -107.2134)
		(end 369.7224 -107.2134)
		(width 0.10795)
		(layer "F.Cu")
		(net "XTAL_PCH_48M_OUT")
	)
	(segment
		(start 375.253504 -109.043724)
		(end 374.937782 -109.043724)
		(width 0.0889)
		(layer "F.Cu")
		(net "XTAL_PCH_48M_OUT")
	)
	(segment
		(start 368.3508 -107.106466)
		(end 367.759234 -106.5149)
		(width 0.10795)
		(layer "F.Cu")
		(net "XTAL_PCH_48M_OUT")
	)
	(segment
		(start 369.615466 -107.106466)
		(end 368.69624 -107.106466)
		(width 0.10795)
		(layer "F.Cu")
		(net "XTAL_PCH_48M_OUT")
	)
	(segment
		(start 374.833388 -109.148118)
		(end 371.874542 -109.148118)
		(width 0.0889)
		(layer "F.Cu")
		(net "XTAL_PCH_48M_OUT")
	)
	(segment
		(start 371.575584 -109.515148)
		(end 370.903754 -108.843318)
		(width 0.089408)
		(layer "F.Cu")
		(net "XTAL_PCH_48M_IN")
	)
	(segment
		(start 369.189 -108.204)
		(end 369.316 -108.204)
		(width 0.10795)
		(layer "F.Cu")
		(net "XTAL_PCH_48M_IN")
	)
	(segment
		(start 366.493806 -107.6198)
		(end 365.506 -108.614972)
		(width 0.10795)
		(layer "F.Cu")
		(net "XTAL_PCH_48M_IN")
	)
	(segment
		(start 369.316 -108.204)
		(end 369.7224 -108.6104)
		(width 0.10795)
		(layer "F.Cu")
		(net "XTAL_PCH_48M_IN")
	)
	(segment
		(start 368.69624 -107.893866)
		(end 368.08664 -107.893866)
		(width 0.10795)
		(layer "F.Cu")
		(net "XTAL_PCH_48M_IN")
	)
	(segment
		(start 368.69624 -107.893866)
		(end 368.878866 -107.893866)
		(width 0.10795)
		(layer "F.Cu")
		(net "XTAL_PCH_48M_IN")
	)
	(segment
		(start 368.08664 -107.893866)
		(end 367.812574 -107.6198)
		(width 0.10795)
		(layer "F.Cu")
		(net "XTAL_PCH_48M_IN")
	)
	(segment
		(start 374.929654 -109.515148)
		(end 371.575584 -109.515148)
		(width 0.0889)
		(layer "F.Cu")
		(net "XTAL_PCH_48M_IN")
	)
	(segment
		(start 375.089928 -109.354874)
		(end 374.929654 -109.515148)
		(width 0.0889)
		(layer "F.Cu")
		(net "XTAL_PCH_48M_IN")
	)
	(segment
		(start 370.670836 -108.6104)
		(end 369.7224 -108.6104)
		(width 0.10795)
		(layer "F.Cu")
		(net "XTAL_PCH_48M_IN")
	)
	(segment
		(start 367.812574 -107.6198)
		(end 366.493806 -107.6198)
		(width 0.10795)
		(layer "F.Cu")
		(net "XTAL_PCH_48M_IN")
	)
	(segment
		(start 370.903754 -108.843318)
		(end 370.670836 -108.6104)
		(width 0.10795)
		(layer "F.Cu")
		(net "XTAL_PCH_48M_IN")
	)
	(segment
		(start 368.878866 -107.893866)
		(end 369.189 -108.204)
		(width 0.10795)
		(layer "F.Cu")
		(net "XTAL_PCH_48M_IN")
	)
	(segment
		(start 455.804778 -147.219924)
		(end 457.252324 -147.219924)
		(width 0.10795)
		(layer "F.Cu")
		(net "XDP_RST_CO_N")
	)
	(segment
		(start 455.4474 -146.939)
		(end 455.523854 -146.939)
		(width 0.10795)
		(layer "F.Cu")
		(net "XDP_RST_CO_N")
	)
	(segment
		(start 455.523854 -146.939)
		(end 455.804778 -147.219924)
		(width 0.10795)
		(layer "F.Cu")
		(net "XDP_RST_CO_N")
	)
	(via
		(at 455.4474 -146.939)
		(size 0.508)
		(drill 0.254)
		(layers "F.Cu" "B.Cu")
		(net "XDP_RST_CO_N")
	)
	(segment
		(start 454.5838 -146.7612)
		(end 455.2696 -146.7612)
		(width 0.10795)
		(layer "B.Cu")
		(net "XDP_RST_CO_N")
	)
	(segment
		(start 455.2696 -146.7612)
		(end 455.4474 -146.939)
		(width 0.10795)
		(layer "B.Cu")
		(net "XDP_RST_CO_N")
	)
	(segment
		(start 462.0514 -143.2052)
		(end 461.5942 -143.6624)
		(width 0.10795)
		(layer "B.Cu")
		(net "XDP_RST_CO_N")
	)
	(segment
		(start 460.754476 -145.507456)
		(end 459.766416 -146.495516)
		(width 0.10795)
		(layer "B.Cu")
		(net "XDP_RST_CO_N")
	)
	(segment
		(start 454.5838 -145.9738)
		(end 454.5838 -146.7612)
		(width 0.10795)
		(layer "B.Cu")
		(net "XDP_RST_CO_N")
	)
	(segment
		(start 459.766416 -146.495516)
		(end 455.890884 -146.495516)
		(width 0.10795)
		(layer "B.Cu")
		(net "XDP_RST_CO_N")
	)
	(segment
		(start 461.1116 -142.377414)
		(end 461.934814 -142.377414)
		(width 0.10795)
		(layer "B.Cu")
		(net "XDP_RST_CO_N")
	)
	(segment
		(start 462.0514 -142.494)
		(end 462.0514 -143.2052)
		(width 0.10795)
		(layer "B.Cu")
		(net "XDP_RST_CO_N")
	)
	(segment
		(start 461.5942 -143.6624)
		(end 461.1116 -143.6624)
		(width 0.10795)
		(layer "B.Cu")
		(net "XDP_RST_CO_N")
	)
	(segment
		(start 455.890884 -146.495516)
		(end 455.4474 -146.939)
		(width 0.10795)
		(layer "B.Cu")
		(net "XDP_RST_CO_N")
	)
	(segment
		(start 461.934814 -142.377414)
		(end 462.0514 -142.494)
		(width 0.10795)
		(layer "B.Cu")
		(net "XDP_RST_CO_N")
	)
	(segment
		(start 460.754476 -144.019524)
		(end 460.754476 -145.507456)
		(width 0.10795)
		(layer "B.Cu")
		(net "XDP_RST_CO_N")
	)
	(segment
		(start 461.1116 -143.6624)
		(end 460.754476 -144.019524)
		(width 0.10795)
		(layer "B.Cu")
		(net "XDP_RST_CO_N")
	)
	(segment
		(start 370.345208 -77.494892)
		(end 370.745004 -77.095096)
		(width 0.10795)
		(layer "F.Cu")
		(net "XDP_PWRGD_RST_N")
	)
	(segment
		(start 464.566 -145.5166)
		(end 464.3628 -145.7198)
		(width 0.10795)
		(layer "F.Cu")
		(net "XDP_PWRGD_RST_N")
	)
	(segment
		(start 464.3628 -145.7198)
		(end 462.980278 -145.7198)
		(width 0.10795)
		(layer "F.Cu")
		(net "XDP_PWRGD_RST_N")
	)
	(segment
		(start 464.6422 -145.5166)
		(end 464.566 -145.5166)
		(width 0.10795)
		(layer "F.Cu")
		(net "XDP_PWRGD_RST_N")
	)
	(via
		(at 464.6422 -145.5166)
		(size 0.508)
		(drill 0.254)
		(layers "F.Cu" "B.Cu")
		(net "XDP_PWRGD_RST_N")
	)
	(via
		(at 420.353998 -85.997288)
		(size 0.6604)
		(drill 0.3302)
		(layers "F.Cu" "B.Cu")
		(net "XDP_PWRGD_RST_N")
	)
	(via
		(at 415.717736 -69.80301)
		(size 0.508)
		(drill 0.254)
		(layers "F.Cu" "B.Cu")
		(net "XDP_PWRGD_RST_N")
	)
	(via
		(at 426.212254 -120.19407)
		(size 0.508)
		(drill 0.254)
		(layers "F.Cu" "B.Cu")
		(net "XDP_PWRGD_RST_N")
	)
	(via
		(at 370.345208 -77.494892)
		(size 0.4572)
		(drill 0.2032)
		(layers "F.Cu" "B.Cu")
		(net "XDP_PWRGD_RST_N")
	)
	(segment
		(start 414.962848 -79.800958)
		(end 414.962848 -71.869808)
		(width 0.10795)
		(layer "B.Cu")
		(net "XDP_PWRGD_RST_N")
	)
	(segment
		(start 416.24885 -80.772254)
		(end 415.934144 -80.772254)
		(width 0.10795)
		(layer "B.Cu")
		(net "XDP_PWRGD_RST_N")
	)
	(segment
		(start 426.143166 -120.124982)
		(end 426.212254 -120.19407)
		(width 0.10795)
		(layer "B.Cu")
		(net "XDP_PWRGD_RST_N")
	)
	(segment
		(start 420.353998 -85.997288)
		(end 421.555164 -87.198454)
		(width 0.10795)
		(layer "B.Cu")
		(net "XDP_PWRGD_RST_N")
	)
	(segment
		(start 424.688 -116.5098)
		(end 426.143166 -117.964966)
		(width 0.10795)
		(layer "B.Cu")
		(net "XDP_PWRGD_RST_N")
	)
	(segment
		(start 422.325038 -100.774246)
		(end 422.325038 -103.049324)
		(width 0.10795)
		(layer "B.Cu")
		(net "XDP_PWRGD_RST_N")
	)
	(segment
		(start 415.134552 -71.698104)
		(end 415.134552 -70.095872)
		(width 0.10795)
		(layer "B.Cu")
		(net "XDP_PWRGD_RST_N")
	)
	(segment
		(start 415.934144 -80.772254)
		(end 414.962848 -79.800958)
		(width 0.10795)
		(layer "B.Cu")
		(net "XDP_PWRGD_RST_N")
	)
	(segment
		(start 421.709596 -103.664766)
		(end 421.709596 -113.149126)
		(width 0.10795)
		(layer "B.Cu")
		(net "XDP_PWRGD_RST_N")
	)
	(segment
		(start 421.555164 -94.239334)
		(end 421.190674 -94.603824)
		(width 0.10795)
		(layer "B.Cu")
		(net "XDP_PWRGD_RST_N")
	)
	(segment
		(start 415.427414 -69.80301)
		(end 415.717736 -69.80301)
		(width 0.10795)
		(layer "B.Cu")
		(net "XDP_PWRGD_RST_N")
	)
	(segment
		(start 421.190674 -94.603824)
		(end 421.190674 -99.639882)
		(width 0.10795)
		(layer "B.Cu")
		(net "XDP_PWRGD_RST_N")
	)
	(segment
		(start 464.464654 -145.415254)
		(end 463.690208 -145.415254)
		(width 0.10795)
		(layer "B.Cu")
		(net "XDP_PWRGD_RST_N")
	)
	(segment
		(start 417.376864 -82.147664)
		(end 416.496246 -81.267046)
		(width 0.10795)
		(layer "B.Cu")
		(net "XDP_PWRGD_RST_N")
	)
	(segment
		(start 464.566 -145.5166)
		(end 464.464654 -145.415254)
		(width 0.10795)
		(layer "B.Cu")
		(net "XDP_PWRGD_RST_N")
	)
	(segment
		(start 421.190674 -99.639882)
		(end 422.325038 -100.774246)
		(width 0.10795)
		(layer "B.Cu")
		(net "XDP_PWRGD_RST_N")
	)
	(segment
		(start 421.555164 -87.198454)
		(end 421.555164 -94.239334)
		(width 0.10795)
		(layer "B.Cu")
		(net "XDP_PWRGD_RST_N")
	)
	(segment
		(start 420.097458 -85.740748)
		(end 419.745668 -85.740748)
		(width 0.10795)
		(layer "B.Cu")
		(net "XDP_PWRGD_RST_N")
	)
	(segment
		(start 416.496246 -81.267046)
		(end 416.496246 -81.01965)
		(width 0.10795)
		(layer "B.Cu")
		(net "XDP_PWRGD_RST_N")
	)
	(segment
		(start 422.325038 -103.049324)
		(end 421.709596 -103.664766)
		(width 0.10795)
		(layer "B.Cu")
		(net "XDP_PWRGD_RST_N")
	)
	(segment
		(start 421.709596 -113.149126)
		(end 424.688 -116.12753)
		(width 0.10795)
		(layer "B.Cu")
		(net "XDP_PWRGD_RST_N")
	)
	(segment
		(start 419.745668 -85.740748)
		(end 417.376864 -83.371944)
		(width 0.10795)
		(layer "B.Cu")
		(net "XDP_PWRGD_RST_N")
	)
	(segment
		(start 426.143166 -117.964966)
		(end 426.143166 -120.124982)
		(width 0.10795)
		(layer "B.Cu")
		(net "XDP_PWRGD_RST_N")
	)
	(segment
		(start 420.353998 -85.997288)
		(end 420.097458 -85.740748)
		(width 0.10795)
		(layer "B.Cu")
		(net "XDP_PWRGD_RST_N")
	)
	(segment
		(start 415.134552 -70.095872)
		(end 415.427414 -69.80301)
		(width 0.10795)
		(layer "B.Cu")
		(net "XDP_PWRGD_RST_N")
	)
	(segment
		(start 417.376864 -83.371944)
		(end 417.376864 -82.147664)
		(width 0.10795)
		(layer "B.Cu")
		(net "XDP_PWRGD_RST_N")
	)
	(segment
		(start 463.690208 -145.415254)
		(end 462.801208 -145.415254)
		(width 0.10795)
		(layer "B.Cu")
		(net "XDP_PWRGD_RST_N")
	)
	(segment
		(start 464.6422 -145.5166)
		(end 464.566 -145.5166)
		(width 0.10795)
		(layer "B.Cu")
		(net "XDP_PWRGD_RST_N")
	)
	(segment
		(start 424.688 -116.12753)
		(end 424.688 -116.5098)
		(width 0.10795)
		(layer "B.Cu")
		(net "XDP_PWRGD_RST_N")
	)
	(segment
		(start 416.496246 -81.01965)
		(end 416.24885 -80.772254)
		(width 0.10795)
		(layer "B.Cu")
		(net "XDP_PWRGD_RST_N")
	)
	(segment
		(start 414.962848 -71.869808)
		(end 415.134552 -71.698104)
		(width 0.10795)
		(layer "B.Cu")
		(net "XDP_PWRGD_RST_N")
	)
	(segment
		(start 380.118112 -77.419708)
		(end 379.621034 -77.916786)
		(width 0.089408)
		(layer "In4.Cu")
		(net "XDP_PWRGD_RST_N")
	)
	(segment
		(start 415.717736 -69.80301)
		(end 415.43097 -69.80301)
		(width 0.089408)
		(layer "In4.Cu")
		(net "XDP_PWRGD_RST_N")
	)
	(segment
		(start 391.853166 -76.457302)
		(end 381.700532 -76.457302)
		(width 0.089408)
		(layer "In4.Cu")
		(net "XDP_PWRGD_RST_N")
	)
	(segment
		(start 395.610588 -75.897232)
		(end 392.413236 -75.897232)
		(width 0.089408)
		(layer "In4.Cu")
		(net "XDP_PWRGD_RST_N")
	)
	(segment
		(start 414.687512 -70.49897)
		(end 414.68675 -70.499732)
		(width 0.089408)
		(layer "In4.Cu")
		(net "XDP_PWRGD_RST_N")
	)
	(segment
		(start 373.971312 -77.393292)
		(end 373.699532 -77.121512)
		(width 0.089408)
		(layer "In4.Cu")
		(net "XDP_PWRGD_RST_N")
	)
	(segment
		(start 373.971312 -77.649578)
		(end 373.971312 -77.393292)
		(width 0.089408)
		(layer "In4.Cu")
		(net "XDP_PWRGD_RST_N")
	)
	(segment
		(start 396.181326 -75.326494)
		(end 395.610588 -75.897232)
		(width 0.089408)
		(layer "In4.Cu")
		(net "XDP_PWRGD_RST_N")
	)
	(segment
		(start 370.718588 -77.121512)
		(end 370.345208 -77.494892)
		(width 0.089408)
		(layer "In4.Cu")
		(net "XDP_PWRGD_RST_N")
	)
	(segment
		(start 414.68675 -70.499732)
		(end 414.285938 -70.499732)
		(width 0.089408)
		(layer "In4.Cu")
		(net "XDP_PWRGD_RST_N")
	)
	(segment
		(start 373.699532 -77.121512)
		(end 370.718588 -77.121512)
		(width 0.089408)
		(layer "In4.Cu")
		(net "XDP_PWRGD_RST_N")
	)
	(segment
		(start 414.285938 -70.499732)
		(end 414.285684 -70.499478)
		(width 0.089408)
		(layer "In4.Cu")
		(net "XDP_PWRGD_RST_N")
	)
	(segment
		(start 412.066486 -72.525128)
		(end 406.953212 -72.525128)
		(width 0.089408)
		(layer "In4.Cu")
		(net "XDP_PWRGD_RST_N")
	)
	(segment
		(start 406.953212 -72.525128)
		(end 406.462484 -73.015856)
		(width 0.089408)
		(layer "In4.Cu")
		(net "XDP_PWRGD_RST_N")
	)
	(segment
		(start 402.711158 -73.015602)
		(end 402.249386 -73.477374)
		(width 0.089408)
		(layer "In4.Cu")
		(net "XDP_PWRGD_RST_N")
	)
	(segment
		(start 406.462484 -73.015856)
		(end 405.903176 -73.015856)
		(width 0.089408)
		(layer "In4.Cu")
		(net "XDP_PWRGD_RST_N")
	)
	(segment
		(start 381.700532 -76.457302)
		(end 380.738126 -77.419708)
		(width 0.089408)
		(layer "In4.Cu")
		(net "XDP_PWRGD_RST_N")
	)
	(segment
		(start 399.706084 -74.590656)
		(end 398.601184 -74.590656)
		(width 0.089408)
		(layer "In4.Cu")
		(net "XDP_PWRGD_RST_N")
	)
	(segment
		(start 414.285684 -70.499478)
		(end 414.092136 -70.499478)
		(width 0.089408)
		(layer "In4.Cu")
		(net "XDP_PWRGD_RST_N")
	)
	(segment
		(start 415.43097 -69.80301)
		(end 414.73501 -70.49897)
		(width 0.089408)
		(layer "In4.Cu")
		(net "XDP_PWRGD_RST_N")
	)
	(segment
		(start 402.249386 -73.477374)
		(end 400.819366 -73.477374)
		(width 0.089408)
		(layer "In4.Cu")
		(net "XDP_PWRGD_RST_N")
	)
	(segment
		(start 414.092136 -70.499478)
		(end 412.066486 -72.525128)
		(width 0.089408)
		(layer "In4.Cu")
		(net "XDP_PWRGD_RST_N")
	)
	(segment
		(start 397.865346 -75.326494)
		(end 396.181326 -75.326494)
		(width 0.089408)
		(layer "In4.Cu")
		(net "XDP_PWRGD_RST_N")
	)
	(segment
		(start 400.819366 -73.477374)
		(end 399.706084 -74.590656)
		(width 0.089408)
		(layer "In4.Cu")
		(net "XDP_PWRGD_RST_N")
	)
	(segment
		(start 414.73501 -70.49897)
		(end 414.687512 -70.49897)
		(width 0.089408)
		(layer "In4.Cu")
		(net "XDP_PWRGD_RST_N")
	)
	(segment
		(start 398.601184 -74.590656)
		(end 397.865346 -75.326494)
		(width 0.089408)
		(layer "In4.Cu")
		(net "XDP_PWRGD_RST_N")
	)
	(segment
		(start 379.621034 -77.916786)
		(end 374.23852 -77.916786)
		(width 0.089408)
		(layer "In4.Cu")
		(net "XDP_PWRGD_RST_N")
	)
	(segment
		(start 374.23852 -77.916786)
		(end 373.971312 -77.649578)
		(width 0.089408)
		(layer "In4.Cu")
		(net "XDP_PWRGD_RST_N")
	)
	(segment
		(start 392.413236 -75.897232)
		(end 391.853166 -76.457302)
		(width 0.089408)
		(layer "In4.Cu")
		(net "XDP_PWRGD_RST_N")
	)
	(segment
		(start 380.738126 -77.419708)
		(end 380.118112 -77.419708)
		(width 0.089408)
		(layer "In4.Cu")
		(net "XDP_PWRGD_RST_N")
	)
	(segment
		(start 405.902922 -73.015602)
		(end 402.711158 -73.015602)
		(width 0.089408)
		(layer "In4.Cu")
		(net "XDP_PWRGD_RST_N")
	)
	(segment
		(start 405.903176 -73.015856)
		(end 405.902922 -73.015602)
		(width 0.089408)
		(layer "In4.Cu")
		(net "XDP_PWRGD_RST_N")
	)
	(segment
		(start 468.801704 -140.119862)
		(end 468.801704 -139.788138)
		(width 0.089408)
		(layer "In11.Cu")
		(net "XDP_PWRGD_RST_N")
	)
	(segment
		(start 427.524926 -120.18137)
		(end 427.029372 -120.676924)
		(width 0.089408)
		(layer "In11.Cu")
		(net "XDP_PWRGD_RST_N")
	)
	(segment
		(start 426.569124 -120.676924)
		(end 426.212254 -120.320054)
		(width 0.089408)
		(layer "In11.Cu")
		(net "XDP_PWRGD_RST_N")
	)
	(segment
		(start 465.779104 -144.74952)
		(end 467.89848 -144.74952)
		(width 0.089408)
		(layer "In11.Cu")
		(net "XDP_PWRGD_RST_N")
	)
	(segment
		(start 468.75065 -136.03478)
		(end 469.235282 -135.550148)
		(width 0.089408)
		(layer "In11.Cu")
		(net "XDP_PWRGD_RST_N")
	)
	(segment
		(start 469.377776 -114.603276)
		(end 467.58225 -114.603276)
		(width 0.089408)
		(layer "In11.Cu")
		(net "XDP_PWRGD_RST_N")
	)
	(segment
		(start 427.029372 -120.676924)
		(end 426.569124 -120.676924)
		(width 0.089408)
		(layer "In11.Cu")
		(net "XDP_PWRGD_RST_N")
	)
	(segment
		(start 467.23935 -114.946176)
		(end 466.88121 -114.946176)
		(width 0.089408)
		(layer "In11.Cu")
		(net "XDP_PWRGD_RST_N")
	)
	(segment
		(start 468.75065 -140.170916)
		(end 468.801704 -140.119862)
		(width 0.089408)
		(layer "In11.Cu")
		(net "XDP_PWRGD_RST_N")
	)
	(segment
		(start 465.012024 -145.5166)
		(end 465.779104 -144.74952)
		(width 0.089408)
		(layer "In11.Cu")
		(net "XDP_PWRGD_RST_N")
	)
	(segment
		(start 470.31148 -115.53698)
		(end 469.377776 -114.603276)
		(width 0.089408)
		(layer "In11.Cu")
		(net "XDP_PWRGD_RST_N")
	)
	(segment
		(start 466.346794 -115.480592)
		(end 441.363608 -115.480592)
		(width 0.089408)
		(layer "In11.Cu")
		(net "XDP_PWRGD_RST_N")
	)
	(segment
		(start 474.267784 -125.365764)
		(end 471.227658 -122.325638)
		(width 0.089408)
		(layer "In11.Cu")
		(net "XDP_PWRGD_RST_N")
	)
	(segment
		(start 468.367364 -140.893038)
		(end 468.75065 -140.509752)
		(width 0.089408)
		(layer "In11.Cu")
		(net "XDP_PWRGD_RST_N")
	)
	(segment
		(start 434.483002 -120.18137)
		(end 427.524926 -120.18137)
		(width 0.089408)
		(layer "In11.Cu")
		(net "XDP_PWRGD_RST_N")
	)
	(segment
		(start 467.89848 -144.74952)
		(end 468.367364 -144.280636)
		(width 0.089408)
		(layer "In11.Cu")
		(net "XDP_PWRGD_RST_N")
	)
	(segment
		(start 471.227658 -122.325638)
		(end 471.227658 -120.316498)
		(width 0.089408)
		(layer "In11.Cu")
		(net "XDP_PWRGD_RST_N")
	)
	(segment
		(start 437.321706 -117.342666)
		(end 434.483002 -120.18137)
		(width 0.089408)
		(layer "In11.Cu")
		(net "XDP_PWRGD_RST_N")
	)
	(segment
		(start 470.31148 -119.40032)
		(end 470.31148 -115.53698)
		(width 0.089408)
		(layer "In11.Cu")
		(net "XDP_PWRGD_RST_N")
	)
	(segment
		(start 468.75065 -140.509752)
		(end 468.75065 -140.170916)
		(width 0.089408)
		(layer "In11.Cu")
		(net "XDP_PWRGD_RST_N")
	)
	(segment
		(start 467.58225 -114.603276)
		(end 467.23935 -114.946176)
		(width 0.089408)
		(layer "In11.Cu")
		(net "XDP_PWRGD_RST_N")
	)
	(segment
		(start 471.227658 -120.316498)
		(end 470.31148 -119.40032)
		(width 0.089408)
		(layer "In11.Cu")
		(net "XDP_PWRGD_RST_N")
	)
	(segment
		(start 469.235282 -132.759958)
		(end 474.267784 -127.727456)
		(width 0.089408)
		(layer "In11.Cu")
		(net "XDP_PWRGD_RST_N")
	)
	(segment
		(start 441.363608 -115.480592)
		(end 439.501534 -117.342666)
		(width 0.089408)
		(layer "In11.Cu")
		(net "XDP_PWRGD_RST_N")
	)
	(segment
		(start 468.801704 -139.788138)
		(end 468.75065 -139.737084)
		(width 0.089408)
		(layer "In11.Cu")
		(net "XDP_PWRGD_RST_N")
	)
	(segment
		(start 468.367364 -144.280636)
		(end 468.367364 -140.893038)
		(width 0.089408)
		(layer "In11.Cu")
		(net "XDP_PWRGD_RST_N")
	)
	(segment
		(start 466.88121 -114.946176)
		(end 466.346794 -115.480592)
		(width 0.089408)
		(layer "In11.Cu")
		(net "XDP_PWRGD_RST_N")
	)
	(segment
		(start 474.267784 -127.727456)
		(end 474.267784 -125.365764)
		(width 0.089408)
		(layer "In11.Cu")
		(net "XDP_PWRGD_RST_N")
	)
	(segment
		(start 439.501534 -117.342666)
		(end 437.321706 -117.342666)
		(width 0.089408)
		(layer "In11.Cu")
		(net "XDP_PWRGD_RST_N")
	)
	(segment
		(start 426.212254 -120.320054)
		(end 426.212254 -120.19407)
		(width 0.089408)
		(layer "In11.Cu")
		(net "XDP_PWRGD_RST_N")
	)
	(segment
		(start 464.6422 -145.5166)
		(end 465.012024 -145.5166)
		(width 0.089408)
		(layer "In11.Cu")
		(net "XDP_PWRGD_RST_N")
	)
	(segment
		(start 468.75065 -139.737084)
		(end 468.75065 -136.03478)
		(width 0.089408)
		(layer "In11.Cu")
		(net "XDP_PWRGD_RST_N")
	)
	(segment
		(start 469.235282 -135.550148)
		(end 469.235282 -132.759958)
		(width 0.089408)
		(layer "In11.Cu")
		(net "XDP_PWRGD_RST_N")
	)
	(segment
		(start 456.119484 -150.219918)
		(end 455.93 -150.409402)
		(width 0.10795)
		(layer "F.Cu")
		(net "XDP_PRESENT_N")
	)
	(segment
		(start 455.93 -150.409402)
		(end 455.93 -152.2984)
		(width 0.10795)
		(layer "F.Cu")
		(net "XDP_PRESENT_N")
	)
	(segment
		(start 421.49014 -40.93464)
		(end 421.09009 -41.33469)
		(width 0.089408)
		(layer "F.Cu")
		(net "XDP_PRESENT_N")
	)
	(segment
		(start 457.252324 -150.219918)
		(end 456.119484 -150.219918)
		(width 0.10795)
		(layer "F.Cu")
		(net "XDP_PRESENT_N")
	)
	(via
		(at 455.93 -152.2984)
		(size 0.508)
		(drill 0.254)
		(layers "F.Cu" "B.Cu")
		(net "XDP_PRESENT_N")
	)
	(via
		(at 427.003464 -60.607956)
		(size 0.508)
		(drill 0.254)
		(layers "F.Cu" "B.Cu")
		(net "XDP_PRESENT_N")
	)
	(via
		(at 426.50283 -117.3353)
		(size 0.508)
		(drill 0.254)
		(layers "F.Cu" "B.Cu")
		(net "XDP_PRESENT_N")
	)
	(via
		(at 421.09009 -41.33469)
		(size 0.4572)
		(drill 0.2032)
		(layers "F.Cu" "B.Cu")
		(net "XDP_PRESENT_N")
	)
	(via
		(at 422.5036 -45.58665)
		(size 0.508)
		(drill 0.254)
		(layers "F.Cu" "B.Cu")
		(net "XDP_PRESENT_N")
	)
	(via
		(at 446.359026 -154.166062)
		(size 0.508)
		(drill 0.254)
		(layers "F.Cu" "B.Cu")
		(net "XDP_PRESENT_N")
	)
	(via
		(at 421.866314 -43.022774)
		(size 0.6604)
		(drill 0.3302)
		(layers "F.Cu" "B.Cu")
		(net "XDP_PRESENT_N")
	)
	(segment
		(start 421.866314 -43.022774)
		(end 422.246806 -43.403266)
		(width 0.089408)
		(layer "B.Cu")
		(net "XDP_PRESENT_N")
	)
	(segment
		(start 446.292478 -151.966168)
		(end 445.543432 -151.966168)
		(width 0.10795)
		(layer "B.Cu")
		(net "XDP_PRESENT_N")
	)
	(segment
		(start 420.71544 -42.289984)
		(end 420.934642 -42.509186)
		(width 0.089408)
		(layer "B.Cu")
		(net "XDP_PRESENT_N")
	)
	(segment
		(start 422.246806 -43.403266)
		(end 422.246806 -44.105068)
		(width 0.089408)
		(layer "B.Cu")
		(net "XDP_PRESENT_N")
	)
	(segment
		(start 446.359026 -155.087574)
		(end 445.5922 -155.8544)
		(width 0.10795)
		(layer "B.Cu")
		(net "XDP_PRESENT_N")
	)
	(segment
		(start 422.246806 -44.105068)
		(end 422.2496 -44.107862)
		(width 0.089408)
		(layer "B.Cu")
		(net "XDP_PRESENT_N")
	)
	(segment
		(start 422.5036 -44.5008)
		(end 422.5036 -45.58665)
		(width 0.089408)
		(layer "B.Cu")
		(net "XDP_PRESENT_N")
	)
	(segment
		(start 420.934642 -42.509186)
		(end 421.352726 -42.509186)
		(width 0.089408)
		(layer "B.Cu")
		(net "XDP_PRESENT_N")
	)
	(segment
		(start 446.153032 -151.422354)
		(end 446.153032 -150.810722)
		(width 0.10795)
		(layer "B.Cu")
		(net "XDP_PRESENT_N")
	)
	(segment
		(start 446.359026 -154.166062)
		(end 446.359026 -155.087574)
		(width 0.10795)
		(layer "B.Cu")
		(net "XDP_PRESENT_N")
	)
	(segment
		(start 421.352726 -42.509186)
		(end 421.866314 -43.022774)
		(width 0.089408)
		(layer "B.Cu")
		(net "XDP_PRESENT_N")
	)
	(segment
		(start 445.42075 -152.08885)
		(end 445.42075 -153.178256)
		(width 0.10795)
		(layer "B.Cu")
		(net "XDP_PRESENT_N")
	)
	(segment
		(start 422.2496 -44.107862)
		(end 422.2496 -44.2468)
		(width 0.089408)
		(layer "B.Cu")
		(net "XDP_PRESENT_N")
	)
	(segment
		(start 446.292478 -151.966168)
		(end 446.292478 -151.5618)
		(width 0.10795)
		(layer "B.Cu")
		(net "XDP_PRESENT_N")
	)
	(segment
		(start 422.2496 -44.2468)
		(end 422.5036 -44.5008)
		(width 0.089408)
		(layer "B.Cu")
		(net "XDP_PRESENT_N")
	)
	(segment
		(start 446.292478 -151.5618)
		(end 446.153032 -151.422354)
		(width 0.10795)
		(layer "B.Cu")
		(net "XDP_PRESENT_N")
	)
	(segment
		(start 421.09009 -41.33469)
		(end 420.71544 -41.70934)
		(width 0.089408)
		(layer "B.Cu")
		(net "XDP_PRESENT_N")
	)
	(segment
		(start 446.359026 -154.116532)
		(end 446.359026 -154.166062)
		(width 0.10795)
		(layer "B.Cu")
		(net "XDP_PRESENT_N")
	)
	(segment
		(start 445.42075 -153.178256)
		(end 446.359026 -154.116532)
		(width 0.10795)
		(layer "B.Cu")
		(net "XDP_PRESENT_N")
	)
	(segment
		(start 445.543432 -151.966168)
		(end 445.42075 -152.08885)
		(width 0.10795)
		(layer "B.Cu")
		(net "XDP_PRESENT_N")
	)
	(segment
		(start 420.71544 -41.70934)
		(end 420.71544 -42.289984)
		(width 0.089408)
		(layer "B.Cu")
		(net "XDP_PRESENT_N")
	)
	(segment
		(start 423.099992 -116.641118)
		(end 422.362884 -117.378226)
		(width 0.089408)
		(layer "In2.Cu")
		(net "XDP_PRESENT_N")
	)
	(segment
		(start 416.907218 -112.743488)
		(end 416.032696 -111.868966)
		(width 0.089408)
		(layer "In2.Cu")
		(net "XDP_PRESENT_N")
	)
	(segment
		(start 416.781488 -89.02827)
		(end 416.610546 -88.857328)
		(width 0.089408)
		(layer "In2.Cu")
		(net "XDP_PRESENT_N")
	)
	(segment
		(start 425.210478 -117.186456)
		(end 425.209462 -117.186456)
		(width 0.089408)
		(layer "In2.Cu")
		(net "XDP_PRESENT_N")
	)
	(segment
		(start 417.124388 -103.58501)
		(end 416.599116 -103.059738)
		(width 0.089408)
		(layer "In2.Cu")
		(net "XDP_PRESENT_N")
	)
	(segment
		(start 426.854874 -60.459366)
		(end 427.003464 -60.607956)
		(width 0.089408)
		(layer "In2.Cu")
		(net "XDP_PRESENT_N")
	)
	(segment
		(start 418.277294 -83.165188)
		(end 418.277294 -82.26806)
		(width 0.089408)
		(layer "In2.Cu")
		(net "XDP_PRESENT_N")
	)
	(segment
		(start 418.27704 -85.36178)
		(end 418.27704 -83.165442)
		(width 0.089408)
		(layer "In2.Cu")
		(net "XDP_PRESENT_N")
	)
	(segment
		(start 416.907218 -113.380774)
		(end 416.907218 -112.743488)
		(width 0.089408)
		(layer "In2.Cu")
		(net "XDP_PRESENT_N")
	)
	(segment
		(start 418.561012 -117.378226)
		(end 416.68065 -115.497864)
		(width 0.089408)
		(layer "In2.Cu")
		(net "XDP_PRESENT_N")
	)
	(segment
		(start 419.111938 -65.237106)
		(end 419.111938 -64.171068)
		(width 0.089408)
		(layer "In2.Cu")
		(net "XDP_PRESENT_N")
	)
	(segment
		(start 425.359322 -117.3353)
		(end 425.210478 -117.186456)
		(width 0.089408)
		(layer "In2.Cu")
		(net "XDP_PRESENT_N")
	)
	(segment
		(start 417.124642 -104.154478)
		(end 417.124642 -103.891334)
		(width 0.089408)
		(layer "In2.Cu")
		(net "XDP_PRESENT_N")
	)
	(segment
		(start 418.27704 -83.165442)
		(end 418.277294 -83.165188)
		(width 0.089408)
		(layer "In2.Cu")
		(net "XDP_PRESENT_N")
	)
	(segment
		(start 422.362884 -117.378226)
		(end 418.561012 -117.378226)
		(width 0.089408)
		(layer "In2.Cu")
		(net "XDP_PRESENT_N")
	)
	(segment
		(start 416.10915 -94.565216)
		(end 416.10915 -94.025212)
		(width 0.089408)
		(layer "In2.Cu")
		(net "XDP_PRESENT_N")
	)
	(segment
		(start 424.664124 -116.641118)
		(end 423.099992 -116.641118)
		(width 0.089408)
		(layer "In2.Cu")
		(net "XDP_PRESENT_N")
	)
	(segment
		(start 418.27704 -82.267806)
		(end 418.27704 -76.779882)
		(width 0.089408)
		(layer "In2.Cu")
		(net "XDP_PRESENT_N")
	)
	(segment
		(start 418.879782 -75.143106)
		(end 418.879782 -71.60387)
		(width 0.089408)
		(layer "In2.Cu")
		(net "XDP_PRESENT_N")
	)
	(segment
		(start 416.032696 -111.868966)
		(end 416.032696 -109.760766)
		(width 0.089408)
		(layer "In2.Cu")
		(net "XDP_PRESENT_N")
	)
	(segment
		(start 418.879782 -71.60387)
		(end 419.111684 -71.371968)
		(width 0.089408)
		(layer "In2.Cu")
		(net "XDP_PRESENT_N")
	)
	(segment
		(start 416.114484 -114.173508)
		(end 416.907218 -113.380774)
		(width 0.089408)
		(layer "In2.Cu")
		(net "XDP_PRESENT_N")
	)
	(segment
		(start 416.599116 -95.055182)
		(end 416.10915 -94.565216)
		(width 0.089408)
		(layer "In2.Cu")
		(net "XDP_PRESENT_N")
	)
	(segment
		(start 416.032696 -109.760766)
		(end 416.255708 -109.537754)
		(width 0.089408)
		(layer "In2.Cu")
		(net "XDP_PRESENT_N")
	)
	(segment
		(start 426.50283 -117.3353)
		(end 425.359322 -117.3353)
		(width 0.089408)
		(layer "In2.Cu")
		(net "XDP_PRESENT_N")
	)
	(segment
		(start 416.599116 -103.059738)
		(end 416.599116 -95.055182)
		(width 0.089408)
		(layer "In2.Cu")
		(net "XDP_PRESENT_N")
	)
	(segment
		(start 416.114484 -115.263422)
		(end 416.114484 -114.173508)
		(width 0.089408)
		(layer "In2.Cu")
		(net "XDP_PRESENT_N")
	)
	(segment
		(start 422.82364 -60.459366)
		(end 426.854874 -60.459366)
		(width 0.089408)
		(layer "In2.Cu")
		(net "XDP_PRESENT_N")
	)
	(segment
		(start 415.844482 -90.914982)
		(end 416.781488 -89.977976)
		(width 0.089408)
		(layer "In2.Cu")
		(net "XDP_PRESENT_N")
	)
	(segment
		(start 418.27704 -76.779882)
		(end 418.879782 -76.17714)
		(width 0.089408)
		(layer "In2.Cu")
		(net "XDP_PRESENT_N")
	)
	(segment
		(start 416.10915 -94.025212)
		(end 415.844482 -93.760544)
		(width 0.089408)
		(layer "In2.Cu")
		(net "XDP_PRESENT_N")
	)
	(segment
		(start 416.255708 -107.40517)
		(end 417.124388 -106.53649)
		(width 0.089408)
		(layer "In2.Cu")
		(net "XDP_PRESENT_N")
	)
	(segment
		(start 417.124388 -103.89108)
		(end 417.124388 -103.58501)
		(width 0.089408)
		(layer "In2.Cu")
		(net "XDP_PRESENT_N")
	)
	(segment
		(start 418.88029 -75.301602)
		(end 418.880036 -75.301348)
		(width 0.089408)
		(layer "In2.Cu")
		(net "XDP_PRESENT_N")
	)
	(segment
		(start 419.111684 -71.371968)
		(end 419.111684 -65.23736)
		(width 0.089408)
		(layer "In2.Cu")
		(net "XDP_PRESENT_N")
	)
	(segment
		(start 417.124388 -106.53649)
		(end 417.124388 -104.154732)
		(width 0.089408)
		(layer "In2.Cu")
		(net "XDP_PRESENT_N")
	)
	(segment
		(start 417.124388 -104.154732)
		(end 417.124642 -104.154478)
		(width 0.089408)
		(layer "In2.Cu")
		(net "XDP_PRESENT_N")
	)
	(segment
		(start 425.209462 -117.186456)
		(end 424.664124 -116.641118)
		(width 0.089408)
		(layer "In2.Cu")
		(net "XDP_PRESENT_N")
	)
	(segment
		(start 418.879782 -76.17714)
		(end 418.879782 -76.040742)
		(width 0.089408)
		(layer "In2.Cu")
		(net "XDP_PRESENT_N")
	)
	(segment
		(start 419.111684 -65.23736)
		(end 419.111938 -65.237106)
		(width 0.089408)
		(layer "In2.Cu")
		(net "XDP_PRESENT_N")
	)
	(segment
		(start 416.68065 -115.497864)
		(end 416.348926 -115.497864)
		(width 0.089408)
		(layer "In2.Cu")
		(net "XDP_PRESENT_N")
	)
	(segment
		(start 416.348926 -115.497864)
		(end 416.114484 -115.263422)
		(width 0.089408)
		(layer "In2.Cu")
		(net "XDP_PRESENT_N")
	)
	(segment
		(start 418.880036 -75.301348)
		(end 418.880036 -75.14336)
		(width 0.089408)
		(layer "In2.Cu")
		(net "XDP_PRESENT_N")
	)
	(segment
		(start 418.879782 -76.040742)
		(end 418.88029 -76.040234)
		(width 0.089408)
		(layer "In2.Cu")
		(net "XDP_PRESENT_N")
	)
	(segment
		(start 417.124642 -103.891334)
		(end 417.124388 -103.89108)
		(width 0.089408)
		(layer "In2.Cu")
		(net "XDP_PRESENT_N")
	)
	(segment
		(start 418.277294 -82.26806)
		(end 418.27704 -82.267806)
		(width 0.089408)
		(layer "In2.Cu")
		(net "XDP_PRESENT_N")
	)
	(segment
		(start 419.111938 -64.171068)
		(end 422.82364 -60.459366)
		(width 0.089408)
		(layer "In2.Cu")
		(net "XDP_PRESENT_N")
	)
	(segment
		(start 416.781488 -89.977976)
		(end 416.781488 -89.02827)
		(width 0.089408)
		(layer "In2.Cu")
		(net "XDP_PRESENT_N")
	)
	(segment
		(start 416.610546 -88.857328)
		(end 416.610546 -87.028274)
		(width 0.089408)
		(layer "In2.Cu")
		(net "XDP_PRESENT_N")
	)
	(segment
		(start 418.880036 -75.14336)
		(end 418.879782 -75.143106)
		(width 0.089408)
		(layer "In2.Cu")
		(net "XDP_PRESENT_N")
	)
	(segment
		(start 416.255708 -109.537754)
		(end 416.255708 -107.40517)
		(width 0.089408)
		(layer "In2.Cu")
		(net "XDP_PRESENT_N")
	)
	(segment
		(start 415.844482 -93.760544)
		(end 415.844482 -90.914982)
		(width 0.089408)
		(layer "In2.Cu")
		(net "XDP_PRESENT_N")
	)
	(segment
		(start 416.610546 -87.028274)
		(end 418.27704 -85.36178)
		(width 0.089408)
		(layer "In2.Cu")
		(net "XDP_PRESENT_N")
	)
	(segment
		(start 418.88029 -76.040234)
		(end 418.88029 -75.301602)
		(width 0.089408)
		(layer "In2.Cu")
		(net "XDP_PRESENT_N")
	)
	(segment
		(start 446.676526 -154.166062)
		(end 446.359026 -154.166062)
		(width 0.089408)
		(layer "In4.Cu")
		(net "XDP_PRESENT_N")
	)
	(segment
		(start 447.737992 -153.104596)
		(end 446.676526 -154.166062)
		(width 0.089408)
		(layer "In4.Cu")
		(net "XDP_PRESENT_N")
	)
	(segment
		(start 455.123804 -153.104596)
		(end 447.737992 -153.104596)
		(width 0.089408)
		(layer "In4.Cu")
		(net "XDP_PRESENT_N")
	)
	(segment
		(start 455.93 -152.2984)
		(end 455.123804 -153.104596)
		(width 0.089408)
		(layer "In4.Cu")
		(net "XDP_PRESENT_N")
	)
	(segment
		(start 425.40682 -124.281946)
		(end 425.40682 -121.075704)
		(width 0.089408)
		(layer "In9.Cu")
		(net "XDP_PRESENT_N")
	)
	(segment
		(start 426.803058 -126.133098)
		(end 425.581572 -127.354584)
		(width 0.089408)
		(layer "In9.Cu")
		(net "XDP_PRESENT_N")
	)
	(segment
		(start 445.684148 -153.523188)
		(end 445.684148 -152.993852)
		(width 0.089408)
		(layer "In9.Cu")
		(net "XDP_PRESENT_N")
	)
	(segment
		(start 446.151 -145.664428)
		(end 444.989966 -144.503394)
		(width 0.089408)
		(layer "In9.Cu")
		(net "XDP_PRESENT_N")
	)
	(segment
		(start 424.996102 -115.7732)
		(end 425.294806 -115.474496)
		(width 0.089408)
		(layer "In9.Cu")
		(net "XDP_PRESENT_N")
	)
	(segment
		(start 425.203874 -120.872758)
		(end 425.203874 -117.061996)
		(width 0.089408)
		(layer "In9.Cu")
		(net "XDP_PRESENT_N")
	)
	(segment
		(start 444.094616 -139.040616)
		(end 441.706 -136.652)
		(width 0.089408)
		(layer "In9.Cu")
		(net "XDP_PRESENT_N")
	)
	(segment
		(start 444.99022 -139.608052)
		(end 444.422784 -139.040616)
		(width 0.089408)
		(layer "In9.Cu")
		(net "XDP_PRESENT_N")
	)
	(segment
		(start 424.099482 -125.549406)
		(end 424.572684 -125.076204)
		(width 0.089408)
		(layer "In9.Cu")
		(net "XDP_PRESENT_N")
	)
	(segment
		(start 425.581572 -127.354584)
		(end 424.676062 -127.354584)
		(width 0.089408)
		(layer "In9.Cu")
		(net "XDP_PRESENT_N")
	)
	(segment
		(start 425.40682 -121.075704)
		(end 425.203874 -120.872758)
		(width 0.089408)
		(layer "In9.Cu")
		(net "XDP_PRESENT_N")
	)
	(segment
		(start 444.989966 -139.87145)
		(end 444.99022 -139.871196)
		(width 0.089408)
		(layer "In9.Cu")
		(net "XDP_PRESENT_N")
	)
	(segment
		(start 441.706 -132.957062)
		(end 438.38876 -129.639822)
		(width 0.089408)
		(layer "In9.Cu")
		(net "XDP_PRESENT_N")
	)
	(segment
		(start 444.989966 -144.503394)
		(end 444.989966 -139.87145)
		(width 0.089408)
		(layer "In9.Cu")
		(net "XDP_PRESENT_N")
	)
	(segment
		(start 446.151 -147.574)
		(end 446.151 -145.664428)
		(width 0.089408)
		(layer "In9.Cu")
		(net "XDP_PRESENT_N")
	)
	(segment
		(start 424.996102 -116.854224)
		(end 424.996102 -115.7732)
		(width 0.089408)
		(layer "In9.Cu")
		(net "XDP_PRESENT_N")
	)
	(segment
		(start 448.056 -149.479)
		(end 446.151 -147.574)
		(width 0.089408)
		(layer "In9.Cu")
		(net "XDP_PRESENT_N")
	)
	(segment
		(start 438.38876 -129.639822)
		(end 435.383178 -129.639822)
		(width 0.089408)
		(layer "In9.Cu")
		(net "XDP_PRESENT_N")
	)
	(segment
		(start 445.684148 -152.993852)
		(end 448.056 -150.622)
		(width 0.089408)
		(layer "In9.Cu")
		(net "XDP_PRESENT_N")
	)
	(segment
		(start 433.121816 -126.133098)
		(end 426.803058 -126.133098)
		(width 0.089408)
		(layer "In9.Cu")
		(net "XDP_PRESENT_N")
	)
	(segment
		(start 433.845208 -128.101852)
		(end 433.845208 -126.85649)
		(width 0.089408)
		(layer "In9.Cu")
		(net "XDP_PRESENT_N")
	)
	(segment
		(start 433.845208 -126.85649)
		(end 433.121816 -126.133098)
		(width 0.089408)
		(layer "In9.Cu")
		(net "XDP_PRESENT_N")
	)
	(segment
		(start 426.50283 -116.172488)
		(end 426.50283 -117.3353)
		(width 0.089408)
		(layer "In9.Cu")
		(net "XDP_PRESENT_N")
	)
	(segment
		(start 424.572684 -125.076204)
		(end 424.612562 -125.076204)
		(width 0.089408)
		(layer "In9.Cu")
		(net "XDP_PRESENT_N")
	)
	(segment
		(start 424.099482 -126.778004)
		(end 424.099482 -125.549406)
		(width 0.089408)
		(layer "In9.Cu")
		(net "XDP_PRESENT_N")
	)
	(segment
		(start 444.99022 -139.871196)
		(end 444.99022 -139.608052)
		(width 0.089408)
		(layer "In9.Cu")
		(net "XDP_PRESENT_N")
	)
	(segment
		(start 425.294806 -115.474496)
		(end 425.804838 -115.474496)
		(width 0.089408)
		(layer "In9.Cu")
		(net "XDP_PRESENT_N")
	)
	(segment
		(start 446.359026 -154.198066)
		(end 445.684148 -153.523188)
		(width 0.089408)
		(layer "In9.Cu")
		(net "XDP_PRESENT_N")
	)
	(segment
		(start 441.706 -136.652)
		(end 441.706 -132.957062)
		(width 0.089408)
		(layer "In9.Cu")
		(net "XDP_PRESENT_N")
	)
	(segment
		(start 446.359026 -154.166062)
		(end 446.359026 -154.198066)
		(width 0.089408)
		(layer "In9.Cu")
		(net "XDP_PRESENT_N")
	)
	(segment
		(start 448.056 -150.622)
		(end 448.056 -149.479)
		(width 0.089408)
		(layer "In9.Cu")
		(net "XDP_PRESENT_N")
	)
	(segment
		(start 424.612562 -125.076204)
		(end 425.40682 -124.281946)
		(width 0.089408)
		(layer "In9.Cu")
		(net "XDP_PRESENT_N")
	)
	(segment
		(start 425.804838 -115.474496)
		(end 426.50283 -116.172488)
		(width 0.089408)
		(layer "In9.Cu")
		(net "XDP_PRESENT_N")
	)
	(segment
		(start 425.203874 -117.061996)
		(end 424.996102 -116.854224)
		(width 0.089408)
		(layer "In9.Cu")
		(net "XDP_PRESENT_N")
	)
	(segment
		(start 444.422784 -139.040616)
		(end 444.094616 -139.040616)
		(width 0.089408)
		(layer "In9.Cu")
		(net "XDP_PRESENT_N")
	)
	(segment
		(start 435.383178 -129.639822)
		(end 433.845208 -128.101852)
		(width 0.089408)
		(layer "In9.Cu")
		(net "XDP_PRESENT_N")
	)
	(segment
		(start 424.676062 -127.354584)
		(end 424.099482 -126.778004)
		(width 0.089408)
		(layer "In9.Cu")
		(net "XDP_PRESENT_N")
	)
	(segment
		(start 426.649134 -59.991498)
		(end 427.003464 -60.345828)
		(width 0.089408)
		(layer "In11.Cu")
		(net "XDP_PRESENT_N")
	)
	(segment
		(start 426.91812 -53.779166)
		(end 426.918374 -53.77942)
		(width 0.089408)
		(layer "In11.Cu")
		(net "XDP_PRESENT_N")
	)
	(segment
		(start 424.494198 -50.250598)
		(end 424.915076 -50.671476)
		(width 0.089408)
		(layer "In11.Cu")
		(net "XDP_PRESENT_N")
	)
	(segment
		(start 424.494452 -49.655476)
		(end 424.494452 -49.9872)
		(width 0.089408)
		(layer "In11.Cu")
		(net "XDP_PRESENT_N")
	)
	(segment
		(start 424.54195 -49.607978)
		(end 424.494452 -49.655476)
		(width 0.089408)
		(layer "In11.Cu")
		(net "XDP_PRESENT_N")
	)
	(segment
		(start 423.312844 -47.416212)
		(end 423.312844 -47.596044)
		(width 0.089408)
		(layer "In11.Cu")
		(net "XDP_PRESENT_N")
	)
	(segment
		(start 424.54195 -48.82515)
		(end 424.54195 -49.607978)
		(width 0.089408)
		(layer "In11.Cu")
		(net "XDP_PRESENT_N")
	)
	(segment
		(start 423.312844 -47.596044)
		(end 424.54195 -48.82515)
		(width 0.089408)
		(layer "In11.Cu")
		(net "XDP_PRESENT_N")
	)
	(segment
		(start 427.003464 -60.345828)
		(end 427.003464 -60.607956)
		(width 0.089408)
		(layer "In11.Cu")
		(net "XDP_PRESENT_N")
	)
	(segment
		(start 426.918374 -54.042564)
		(end 426.649134 -54.311804)
		(width 0.089408)
		(layer "In11.Cu")
		(net "XDP_PRESENT_N")
	)
	(segment
		(start 422.5036 -46.606968)
		(end 423.312844 -47.416212)
		(width 0.089408)
		(layer "In11.Cu")
		(net "XDP_PRESENT_N")
	)
	(segment
		(start 426.649134 -54.311804)
		(end 426.649134 -59.991498)
		(width 0.089408)
		(layer "In11.Cu")
		(net "XDP_PRESENT_N")
	)
	(segment
		(start 425.624498 -50.671476)
		(end 426.91812 -51.965098)
		(width 0.089408)
		(layer "In11.Cu")
		(net "XDP_PRESENT_N")
	)
	(segment
		(start 424.494452 -49.9872)
		(end 424.494198 -49.987454)
		(width 0.089408)
		(layer "In11.Cu")
		(net "XDP_PRESENT_N")
	)
	(segment
		(start 426.918374 -53.77942)
		(end 426.918374 -54.042564)
		(width 0.089408)
		(layer "In11.Cu")
		(net "XDP_PRESENT_N")
	)
	(segment
		(start 424.494198 -49.987454)
		(end 424.494198 -50.250598)
		(width 0.089408)
		(layer "In11.Cu")
		(net "XDP_PRESENT_N")
	)
	(segment
		(start 426.91812 -51.965098)
		(end 426.91812 -53.779166)
		(width 0.089408)
		(layer "In11.Cu")
		(net "XDP_PRESENT_N")
	)
	(segment
		(start 424.915076 -50.671476)
		(end 425.624498 -50.671476)
		(width 0.089408)
		(layer "In11.Cu")
		(net "XDP_PRESENT_N")
	)
	(segment
		(start 422.5036 -45.58665)
		(end 422.5036 -46.606968)
		(width 0.089408)
		(layer "In11.Cu")
		(net "XDP_PRESENT_N")
	)
	(segment
		(start 413.135572 -134.119366)
		(end 413.129222 -134.125716)
		(width 0.10795)
		(layer "F.Cu")
		(net "XDP_PCH_TCK1")
	)
	(segment
		(start 388.23265 -118.4402)
		(end 388.724648 -118.6688)
		(width 0.1016)
		(layer "F.Cu")
		(net "XDP_PCH_TCK1")
	)
	(segment
		(start 441.798456 -153.572718)
		(end 441.887356 -153.661618)
		(width 0.10795)
		(layer "F.Cu")
		(net "XDP_PCH_TCK1")
	)
	(segment
		(start 413.129222 -134.125716)
		(end 412.939738 -134.125716)
		(width 0.10795)
		(layer "F.Cu")
		(net "XDP_PCH_TCK1")
	)
	(segment
		(start 462.980278 -149.21992)
		(end 461.380332 -149.21992)
		(width 0.10795)
		(layer "F.Cu")
		(net "XDP_PCH_TCK1")
	)
	(segment
		(start 388.724648 -118.6688)
		(end 388.72795 -118.670324)
		(width 0.1016)
		(layer "F.Cu")
		(net "XDP_PCH_TCK1")
	)
	(segment
		(start 412.939738 -134.125716)
		(end 412.632652 -134.432802)
		(width 0.10795)
		(layer "F.Cu")
		(net "XDP_PCH_TCK1")
	)
	(segment
		(start 412.632652 -134.432802)
		(end 412.632652 -134.747)
		(width 0.10795)
		(layer "F.Cu")
		(net "XDP_PCH_TCK1")
	)
	(segment
		(start 439.604912 -153.572718)
		(end 441.798456 -153.572718)
		(width 0.10795)
		(layer "F.Cu")
		(net "XDP_PCH_TCK1")
	)
	(via
		(at 441.887356 -153.661618)
		(size 0.508)
		(drill 0.254)
		(layers "F.Cu" "B.Cu")
		(net "XDP_PCH_TCK1")
	)
	(via
		(at 388.72795 -118.670324)
		(size 0.508)
		(drill 0.254)
		(layers "F.Cu" "B.Cu")
		(net "XDP_PCH_TCK1")
	)
	(via
		(at 461.380332 -149.21992)
		(size 0.508)
		(drill 0.254)
		(layers "F.Cu" "B.Cu")
		(net "XDP_PCH_TCK1")
	)
	(via
		(at 413.135572 -134.119366)
		(size 0.508)
		(drill 0.254)
		(layers "F.Cu" "B.Cu")
		(net "XDP_PCH_TCK1")
	)
	(segment
		(start 392.147298 -131.271264)
		(end 401.221956 -131.271264)
		(width 0.089408)
		(layer "In2.Cu")
		(net "XDP_PCH_TCK1")
	)
	(segment
		(start 454.398126 -150.037292)
		(end 455.642218 -150.037292)
		(width 0.089408)
		(layer "In2.Cu")
		(net "XDP_PCH_TCK1")
	)
	(segment
		(start 436.347108 -132.877814)
		(end 438.025286 -134.555992)
		(width 0.089408)
		(layer "In2.Cu")
		(net "XDP_PCH_TCK1")
	)
	(segment
		(start 448.07632 -144.342104)
		(end 448.495166 -144.76095)
		(width 0.089408)
		(layer "In2.Cu")
		(net "XDP_PCH_TCK1")
	)
	(segment
		(start 460.892906 -149.567392)
		(end 461.240378 -149.21992)
		(width 0.089408)
		(layer "In2.Cu")
		(net "XDP_PCH_TCK1")
	)
	(segment
		(start 438.025286 -134.555992)
		(end 447.471546 -134.555992)
		(width 0.089408)
		(layer "In2.Cu")
		(net "XDP_PCH_TCK1")
	)
	(segment
		(start 389.71855 -122.946414)
		(end 389.71855 -122.979434)
		(width 0.0889)
		(layer "In2.Cu")
		(net "XDP_PCH_TCK1")
	)
	(segment
		(start 390.21385 -123.804934)
		(end 390.21385 -123.837954)
		(width 0.0889)
		(layer "In2.Cu")
		(net "XDP_PCH_TCK1")
	)
	(segment
		(start 390.345676 -124.158502)
		(end 391.09142 -124.904246)
		(width 0.089408)
		(layer "In2.Cu")
		(net "XDP_PCH_TCK1")
	)
	(segment
		(start 402.255228 -130.237992)
		(end 408.122628 -130.237992)
		(width 0.089408)
		(layer "In2.Cu")
		(net "XDP_PCH_TCK1")
	)
	(segment
		(start 413.687514 -134.119366)
		(end 415.652458 -132.154422)
		(width 0.089408)
		(layer "In2.Cu")
		(net "XDP_PCH_TCK1")
	)
	(segment
		(start 455.642218 -150.037292)
		(end 456.112118 -149.567392)
		(width 0.089408)
		(layer "In2.Cu")
		(net "XDP_PCH_TCK1")
	)
	(segment
		(start 456.112118 -149.567392)
		(end 460.892906 -149.567392)
		(width 0.089408)
		(layer "In2.Cu")
		(net "XDP_PCH_TCK1")
	)
	(segment
		(start 448.495166 -144.76095)
		(end 449.637912 -144.76095)
		(width 0.089408)
		(layer "In2.Cu")
		(net "XDP_PCH_TCK1")
	)
	(segment
		(start 413.135572 -134.119366)
		(end 413.687514 -134.119366)
		(width 0.089408)
		(layer "In2.Cu")
		(net "XDP_PCH_TCK1")
	)
	(segment
		(start 452.6407 -146.88566)
		(end 452.6407 -148.279866)
		(width 0.089408)
		(layer "In2.Cu")
		(net "XDP_PCH_TCK1")
	)
	(segment
		(start 447.471546 -134.555992)
		(end 448.543426 -135.627872)
		(width 0.089408)
		(layer "In2.Cu")
		(net "XDP_PCH_TCK1")
	)
	(segment
		(start 408.122628 -130.237992)
		(end 410.094176 -132.20954)
		(width 0.089408)
		(layer "In2.Cu")
		(net "XDP_PCH_TCK1")
	)
	(segment
		(start 390.21385 -122.087894)
		(end 390.21385 -122.120914)
		(width 0.0889)
		(layer "In2.Cu")
		(net "XDP_PCH_TCK1")
	)
	(segment
		(start 410.094176 -133.269482)
		(end 411.216856 -134.392162)
		(width 0.089408)
		(layer "In2.Cu")
		(net "XDP_PCH_TCK1")
	)
	(segment
		(start 448.543426 -136.905746)
		(end 448.07632 -137.372852)
		(width 0.089408)
		(layer "In2.Cu")
		(net "XDP_PCH_TCK1")
	)
	(segment
		(start 401.221956 -131.271264)
		(end 402.255228 -130.237992)
		(width 0.089408)
		(layer "In2.Cu")
		(net "XDP_PCH_TCK1")
	)
	(segment
		(start 410.094176 -132.20954)
		(end 410.094176 -133.269482)
		(width 0.089408)
		(layer "In2.Cu")
		(net "XDP_PCH_TCK1")
	)
	(segment
		(start 411.216856 -134.392162)
		(end 412.862776 -134.392162)
		(width 0.089408)
		(layer "In2.Cu")
		(net "XDP_PCH_TCK1")
	)
	(segment
		(start 451.277482 -146.40052)
		(end 452.15556 -146.40052)
		(width 0.089408)
		(layer "In2.Cu")
		(net "XDP_PCH_TCK1")
	)
	(segment
		(start 391.09142 -124.904246)
		(end 391.09142 -130.215386)
		(width 0.089408)
		(layer "In2.Cu")
		(net "XDP_PCH_TCK1")
	)
	(segment
		(start 412.862776 -134.392162)
		(end 413.135572 -134.119366)
		(width 0.089408)
		(layer "In2.Cu")
		(net "XDP_PCH_TCK1")
	)
	(segment
		(start 430.765712 -132.877814)
		(end 436.347108 -132.877814)
		(width 0.089408)
		(layer "In2.Cu")
		(net "XDP_PCH_TCK1")
	)
	(segment
		(start 449.637912 -144.76095)
		(end 451.277482 -146.40052)
		(width 0.089408)
		(layer "In2.Cu")
		(net "XDP_PCH_TCK1")
	)
	(segment
		(start 452.15556 -146.40052)
		(end 452.6407 -146.88566)
		(width 0.089408)
		(layer "In2.Cu")
		(net "XDP_PCH_TCK1")
	)
	(segment
		(start 391.09142 -130.215386)
		(end 392.147298 -131.271264)
		(width 0.089408)
		(layer "In2.Cu")
		(net "XDP_PCH_TCK1")
	)
	(segment
		(start 388.72795 -118.670324)
		(end 388.72795 -119.733568)
		(width 0.089408)
		(layer "In2.Cu")
		(net "XDP_PCH_TCK1")
	)
	(segment
		(start 429.565562 -131.677664)
		(end 430.765712 -132.877814)
		(width 0.089408)
		(layer "In2.Cu")
		(net "XDP_PCH_TCK1")
	)
	(segment
		(start 448.543426 -135.627872)
		(end 448.543426 -136.905746)
		(width 0.089408)
		(layer "In2.Cu")
		(net "XDP_PCH_TCK1")
	)
	(segment
		(start 419.34384 -132.154422)
		(end 419.820598 -131.677664)
		(width 0.089408)
		(layer "In2.Cu")
		(net "XDP_PCH_TCK1")
	)
	(segment
		(start 419.820598 -131.677664)
		(end 429.565562 -131.677664)
		(width 0.089408)
		(layer "In2.Cu")
		(net "XDP_PCH_TCK1")
	)
	(segment
		(start 389.22325 -120.370854)
		(end 389.22325 -120.403874)
		(width 0.0889)
		(layer "In2.Cu")
		(net "XDP_PCH_TCK1")
	)
	(segment
		(start 388.72795 -119.733568)
		(end 388.890002 -119.89562)
		(width 0.089408)
		(layer "In2.Cu")
		(net "XDP_PCH_TCK1")
	)
	(segment
		(start 452.6407 -148.279866)
		(end 454.398126 -150.037292)
		(width 0.089408)
		(layer "In2.Cu")
		(net "XDP_PCH_TCK1")
	)
	(segment
		(start 461.240378 -149.21992)
		(end 461.380332 -149.21992)
		(width 0.089408)
		(layer "In2.Cu")
		(net "XDP_PCH_TCK1")
	)
	(segment
		(start 415.652458 -132.154422)
		(end 419.34384 -132.154422)
		(width 0.089408)
		(layer "In2.Cu")
		(net "XDP_PCH_TCK1")
	)
	(segment
		(start 448.07632 -137.372852)
		(end 448.07632 -144.342104)
		(width 0.089408)
		(layer "In2.Cu")
		(net "XDP_PCH_TCK1")
	)
	(segment
		(start 389.71855 -121.229374)
		(end 389.71855 -121.262394)
		(width 0.0889)
		(layer "In2.Cu")
		(net "XDP_PCH_TCK1")
	)
	(arc
		(start 389.9662 -123.392184)
		(mid 390.143502 -123.566473)
		(end 390.21385 -123.804934)
		(width 0.0889)
		(layer "In2.Cu")
		(net "XDP_PCH_TCK1")
	)
	(arc
		(start 390.21385 -123.837954)
		(mid 390.250809 -124.010139)
		(end 390.345676 -124.158502)
		(width 0.0889)
		(layer "In2.Cu")
		(net "XDP_PCH_TCK1")
	)
	(arc
		(start 389.71855 -122.979434)
		(mid 389.788898 -123.217895)
		(end 389.9662 -123.392184)
		(width 0.0889)
		(layer "In2.Cu")
		(net "XDP_PCH_TCK1")
	)
	(arc
		(start 389.9662 -121.675144)
		(mid 390.143502 -121.849433)
		(end 390.21385 -122.087894)
		(width 0.0889)
		(layer "In2.Cu")
		(net "XDP_PCH_TCK1")
	)
	(arc
		(start 388.890002 -119.89562)
		(mid 388.93113 -119.92915)
		(end 388.9756 -119.958104)
		(width 0.0889)
		(layer "In2.Cu")
		(net "XDP_PCH_TCK1")
	)
	(arc
		(start 388.9756 -119.958104)
		(mid 389.152902 -120.132393)
		(end 389.22325 -120.370854)
		(width 0.0889)
		(layer "In2.Cu")
		(net "XDP_PCH_TCK1")
	)
	(arc
		(start 390.21385 -122.120914)
		(mid 390.143502 -122.359375)
		(end 389.9662 -122.533664)
		(width 0.0889)
		(layer "In2.Cu")
		(net "XDP_PCH_TCK1")
	)
	(arc
		(start 389.71855 -121.262394)
		(mid 389.788898 -121.500855)
		(end 389.9662 -121.675144)
		(width 0.0889)
		(layer "In2.Cu")
		(net "XDP_PCH_TCK1")
	)
	(arc
		(start 389.4709 -120.816624)
		(mid 389.648202 -120.990913)
		(end 389.71855 -121.229374)
		(width 0.0889)
		(layer "In2.Cu")
		(net "XDP_PCH_TCK1")
	)
	(arc
		(start 389.9662 -122.533664)
		(mid 389.788898 -122.707953)
		(end 389.71855 -122.946414)
		(width 0.0889)
		(layer "In2.Cu")
		(net "XDP_PCH_TCK1")
	)
	(arc
		(start 389.22325 -120.403874)
		(mid 389.293598 -120.642335)
		(end 389.4709 -120.816624)
		(width 0.0889)
		(layer "In2.Cu")
		(net "XDP_PCH_TCK1")
	)
	(segment
		(start 445.368172 -151.345646)
		(end 453.867774 -151.345646)
		(width 0.089408)
		(layer "In11.Cu")
		(net "XDP_PCH_TCK1")
	)
	(segment
		(start 461.240378 -149.21992)
		(end 461.380332 -149.21992)
		(width 0.089408)
		(layer "In11.Cu")
		(net "XDP_PCH_TCK1")
	)
	(segment
		(start 455.546968 -149.666452)
		(end 460.793846 -149.666452)
		(width 0.089408)
		(layer "In11.Cu")
		(net "XDP_PCH_TCK1")
	)
	(segment
		(start 460.793846 -149.666452)
		(end 461.240378 -149.21992)
		(width 0.089408)
		(layer "In11.Cu")
		(net "XDP_PCH_TCK1")
	)
	(segment
		(start 453.867774 -151.345646)
		(end 455.546968 -149.666452)
		(width 0.089408)
		(layer "In11.Cu")
		(net "XDP_PCH_TCK1")
	)
	(segment
		(start 443.0522 -153.661618)
		(end 445.368172 -151.345646)
		(width 0.089408)
		(layer "In11.Cu")
		(net "XDP_PCH_TCK1")
	)
	(segment
		(start 441.887356 -153.661618)
		(end 443.0522 -153.661618)
		(width 0.089408)
		(layer "In11.Cu")
		(net "XDP_PCH_TCK1")
	)
	(segment
		(start 131.948174 -60.857384)
		(end 132.519674 -60.857384)
		(width 0.1016)
		(layer "F.Cu")
		(net "XDP_CPU_TRST_N")
	)
	(segment
		(start 296.948606 -60.857384)
		(end 297.520106 -60.857384)
		(width 0.1016)
		(layer "F.Cu")
		(net "XDP_CPU_TRST_N")
	)
	(via
		(at 177.3682 -21.6662)
		(size 0.508)
		(drill 0.254)
		(layers "F.Cu" "B.Cu")
		(net "XDP_CPU_TRST_N")
	)
	(via
		(at 338.483702 -87.989918)
		(size 0.508)
		(drill 0.254)
		(layers "F.Cu" "B.Cu")
		(net "XDP_CPU_TRST_N")
	)
	(via
		(at 297.520106 -60.857384)
		(size 0.508)
		(drill 0.254)
		(layers "F.Cu" "B.Cu")
		(net "XDP_CPU_TRST_N")
	)
	(via
		(at 355.594412 -59.37885)
		(size 0.508)
		(drill 0.254)
		(layers "F.Cu" "B.Cu")
		(net "XDP_CPU_TRST_N")
	)
	(via
		(at 132.519674 -60.857384)
		(size 0.508)
		(drill 0.254)
		(layers "F.Cu" "B.Cu")
		(net "XDP_CPU_TRST_N")
	)
	(via
		(at 324.263512 -59.50458)
		(size 0.508)
		(drill 0.254)
		(layers "F.Cu" "B.Cu")
		(net "XDP_CPU_TRST_N")
	)
	(via
		(at 462.857342 -151.141684)
		(size 0.508)
		(drill 0.254)
		(layers "F.Cu" "B.Cu")
		(net "XDP_CPU_TRST_N")
	)
	(segment
		(start 176.276 -20.193)
		(end 176.276 -20.447)
		(width 0.10795)
		(layer "B.Cu")
		(net "XDP_CPU_TRST_N")
	)
	(segment
		(start 462.622646 -151.37638)
		(end 461.430116 -151.37638)
		(width 0.10795)
		(layer "B.Cu")
		(net "XDP_CPU_TRST_N")
	)
	(segment
		(start 177.3682 -21.5392)
		(end 177.3682 -21.6662)
		(width 0.10795)
		(layer "B.Cu")
		(net "XDP_CPU_TRST_N")
	)
	(segment
		(start 176.276 -20.447)
		(end 177.3682 -21.5392)
		(width 0.10795)
		(layer "B.Cu")
		(net "XDP_CPU_TRST_N")
	)
	(segment
		(start 462.857342 -151.141684)
		(end 462.622646 -151.37638)
		(width 0.10795)
		(layer "B.Cu")
		(net "XDP_CPU_TRST_N")
	)
	(segment
		(start 442.822584 -147.574)
		(end 442.270896 -147.574)
		(width 0.089408)
		(layer "In4.Cu")
		(net "XDP_CPU_TRST_N")
	)
	(segment
		(start 452.755254 -150.037292)
		(end 451.967346 -150.8252)
		(width 0.089408)
		(layer "In4.Cu")
		(net "XDP_CPU_TRST_N")
	)
	(segment
		(start 331.518514 -97.032826)
		(end 331.51826 -97.032572)
		(width 0.089408)
		(layer "In4.Cu")
		(net "XDP_CPU_TRST_N")
	)
	(segment
		(start 440.817 -146.120104)
		(end 420.35222 -146.120104)
		(width 0.089408)
		(layer "In4.Cu")
		(net "XDP_CPU_TRST_N")
	)
	(segment
		(start 337.445096 -88.759538)
		(end 337.70189 -88.502744)
		(width 0.089408)
		(layer "In4.Cu")
		(net "XDP_CPU_TRST_N")
	)
	(segment
		(start 331.518514 -106.733594)
		(end 331.518514 -97.032826)
		(width 0.089408)
		(layer "In4.Cu")
		(net "XDP_CPU_TRST_N")
	)
	(segment
		(start 363.816392 -143.262604)
		(end 363.317536 -142.763748)
		(width 0.089408)
		(layer "In4.Cu")
		(net "XDP_CPU_TRST_N")
	)
	(segment
		(start 334.753712 -114.318288)
		(end 333.483712 -113.048288)
		(width 0.089408)
		(layer "In4.Cu")
		(net "XDP_CPU_TRST_N")
	)
	(segment
		(start 406.322276 -149.259036)
		(end 403.550628 -146.487388)
		(width 0.089408)
		(layer "In4.Cu")
		(net "XDP_CPU_TRST_N")
	)
	(segment
		(start 410.94152 -149.96033)
		(end 408.812746 -152.089104)
		(width 0.089408)
		(layer "In4.Cu")
		(net "XDP_CPU_TRST_N")
	)
	(segment
		(start 343.51722 -138.321542)
		(end 342.516714 -137.321036)
		(width 0.089408)
		(layer "In4.Cu")
		(net "XDP_CPU_TRST_N")
	)
	(segment
		(start 451.967346 -150.8252)
		(end 447.758566 -150.8252)
		(width 0.089408)
		(layer "In4.Cu")
		(net "XDP_CPU_TRST_N")
	)
	(segment
		(start 363.317536 -142.763748)
		(end 363.317536 -142.65402)
		(width 0.089408)
		(layer "In4.Cu")
		(net "XDP_CPU_TRST_N")
	)
	(segment
		(start 406.322276 -151.854662)
		(end 406.322276 -149.259036)
		(width 0.089408)
		(layer "In4.Cu")
		(net "XDP_CPU_TRST_N")
	)
	(segment
		(start 331.51826 -95.19666)
		(end 331.518514 -95.196406)
		(width 0.089408)
		(layer "In4.Cu")
		(net "XDP_CPU_TRST_N")
	)
	(segment
		(start 362.022644 -141.735302)
		(end 360.738166 -141.735302)
		(width 0.089408)
		(layer "In4.Cu")
		(net "XDP_CPU_TRST_N")
	)
	(segment
		(start 333.483712 -113.048288)
		(end 333.483712 -111.179102)
		(width 0.089408)
		(layer "In4.Cu")
		(net "XDP_CPU_TRST_N")
	)
	(segment
		(start 331.51826 -97.032572)
		(end 331.51826 -95.19666)
		(width 0.089408)
		(layer "In4.Cu")
		(net "XDP_CPU_TRST_N")
	)
	(segment
		(start 362.090462 -141.80312)
		(end 362.022644 -141.735302)
		(width 0.089408)
		(layer "In4.Cu")
		(net "XDP_CPU_TRST_N")
	)
	(segment
		(start 334.854296 -91.593924)
		(end 334.854296 -91.368372)
		(width 0.089408)
		(layer "In4.Cu")
		(net "XDP_CPU_TRST_N")
	)
	(segment
		(start 396.719044 -146.2151)
		(end 392.890502 -146.2151)
		(width 0.089408)
		(layer "In4.Cu")
		(net "XDP_CPU_TRST_N")
	)
	(segment
		(start 461.0608 -150.7236)
		(end 459.0542 -150.7236)
		(width 0.089408)
		(layer "In4.Cu")
		(net "XDP_CPU_TRST_N")
	)
	(segment
		(start 371.496336 -142.256764)
		(end 371.256052 -142.497048)
		(width 0.089408)
		(layer "In4.Cu")
		(net "XDP_CPU_TRST_N")
	)
	(segment
		(start 333.20101 -108.41609)
		(end 331.518514 -106.733594)
		(width 0.089408)
		(layer "In4.Cu")
		(net "XDP_CPU_TRST_N")
	)
	(segment
		(start 353.004882 -140.150342)
		(end 352.349308 -139.494768)
		(width 0.089408)
		(layer "In4.Cu")
		(net "XDP_CPU_TRST_N")
	)
	(segment
		(start 337.894676 -134.478014)
		(end 337.894676 -125.369574)
		(width 0.089408)
		(layer "In4.Cu")
		(net "XDP_CPU_TRST_N")
	)
	(segment
		(start 418.50056 -146.531584)
		(end 412.984696 -146.531584)
		(width 0.089408)
		(layer "In4.Cu")
		(net "XDP_CPU_TRST_N")
	)
	(segment
		(start 335.18602 -116.802916)
		(end 334.753712 -116.370608)
		(width 0.089408)
		(layer "In4.Cu")
		(net "XDP_CPU_TRST_N")
	)
	(segment
		(start 359.153206 -140.150342)
		(end 353.004882 -140.150342)
		(width 0.089408)
		(layer "In4.Cu")
		(net "XDP_CPU_TRST_N")
	)
	(segment
		(start 461.571848 -151.234648)
		(end 461.0608 -150.7236)
		(width 0.089408)
		(layer "In4.Cu")
		(net "XDP_CPU_TRST_N")
	)
	(segment
		(start 419.230048 -145.802096)
		(end 418.50056 -146.531584)
		(width 0.089408)
		(layer "In4.Cu")
		(net "XDP_CPU_TRST_N")
	)
	(segment
		(start 447.36893 -150.8252)
		(end 446.073784 -150.8252)
		(width 0.089408)
		(layer "In4.Cu")
		(net "XDP_CPU_TRST_N")
	)
	(segment
		(start 363.317536 -142.65402)
		(end 362.466636 -141.80312)
		(width 0.089408)
		(layer "In4.Cu")
		(net "XDP_CPU_TRST_N")
	)
	(segment
		(start 362.466636 -141.80312)
		(end 362.090462 -141.80312)
		(width 0.089408)
		(layer "In4.Cu")
		(net "XDP_CPU_TRST_N")
	)
	(segment
		(start 360.738166 -141.735302)
		(end 359.153206 -140.150342)
		(width 0.089408)
		(layer "In4.Cu")
		(net "XDP_CPU_TRST_N")
	)
	(segment
		(start 462.764378 -151.234648)
		(end 461.571848 -151.234648)
		(width 0.089408)
		(layer "In4.Cu")
		(net "XDP_CPU_TRST_N")
	)
	(segment
		(start 458.367892 -150.037292)
		(end 452.755254 -150.037292)
		(width 0.089408)
		(layer "In4.Cu")
		(net "XDP_CPU_TRST_N")
	)
	(segment
		(start 334.753712 -116.370608)
		(end 334.753712 -114.318288)
		(width 0.089408)
		(layer "In4.Cu")
		(net "XDP_CPU_TRST_N")
	)
	(segment
		(start 459.0542 -150.7236)
		(end 458.367892 -150.037292)
		(width 0.089408)
		(layer "In4.Cu")
		(net "XDP_CPU_TRST_N")
	)
	(segment
		(start 367.273586 -142.497048)
		(end 366.50803 -143.262604)
		(width 0.089408)
		(layer "In4.Cu")
		(net "XDP_CPU_TRST_N")
	)
	(segment
		(start 383.393696 -143.393414)
		(end 382.257046 -142.256764)
		(width 0.089408)
		(layer "In4.Cu")
		(net "XDP_CPU_TRST_N")
	)
	(segment
		(start 420.35222 -146.120104)
		(end 420.034212 -145.802096)
		(width 0.089408)
		(layer "In4.Cu")
		(net "XDP_CPU_TRST_N")
	)
	(segment
		(start 366.50803 -143.262604)
		(end 363.816392 -143.262604)
		(width 0.089408)
		(layer "In4.Cu")
		(net "XDP_CPU_TRST_N")
	)
	(segment
		(start 382.257046 -142.256764)
		(end 371.496336 -142.256764)
		(width 0.089408)
		(layer "In4.Cu")
		(net "XDP_CPU_TRST_N")
	)
	(segment
		(start 410.94152 -148.57476)
		(end 410.94152 -149.96033)
		(width 0.089408)
		(layer "In4.Cu")
		(net "XDP_CPU_TRST_N")
	)
	(segment
		(start 392.890502 -146.2151)
		(end 390.068816 -143.393414)
		(width 0.089408)
		(layer "In4.Cu")
		(net "XDP_CPU_TRST_N")
	)
	(segment
		(start 402.649182 -146.793458)
		(end 397.297402 -146.793458)
		(width 0.089408)
		(layer "In4.Cu")
		(net "XDP_CPU_TRST_N")
	)
	(segment
		(start 340.737698 -137.321036)
		(end 337.894676 -134.478014)
		(width 0.089408)
		(layer "In4.Cu")
		(net "XDP_CPU_TRST_N")
	)
	(segment
		(start 337.970876 -88.502744)
		(end 338.483702 -87.989918)
		(width 0.089408)
		(layer "In4.Cu")
		(net "XDP_CPU_TRST_N")
	)
	(segment
		(start 337.70189 -88.502744)
		(end 337.970876 -88.502744)
		(width 0.089408)
		(layer "In4.Cu")
		(net "XDP_CPU_TRST_N")
	)
	(segment
		(start 334.854296 -91.368372)
		(end 337.445096 -88.777572)
		(width 0.089408)
		(layer "In4.Cu")
		(net "XDP_CPU_TRST_N")
	)
	(segment
		(start 406.556718 -152.089104)
		(end 406.322276 -151.854662)
		(width 0.089408)
		(layer "In4.Cu")
		(net "XDP_CPU_TRST_N")
	)
	(segment
		(start 333.483712 -111.179102)
		(end 333.20101 -110.8964)
		(width 0.089408)
		(layer "In4.Cu")
		(net "XDP_CPU_TRST_N")
	)
	(segment
		(start 447.376804 -150.833074)
		(end 447.36893 -150.8252)
		(width 0.089408)
		(layer "In4.Cu")
		(net "XDP_CPU_TRST_N")
	)
	(segment
		(start 337.445096 -88.777572)
		(end 337.445096 -88.759538)
		(width 0.089408)
		(layer "In4.Cu")
		(net "XDP_CPU_TRST_N")
	)
	(segment
		(start 390.068816 -143.393414)
		(end 383.393696 -143.393414)
		(width 0.089408)
		(layer "In4.Cu")
		(net "XDP_CPU_TRST_N")
	)
	(segment
		(start 348.531434 -139.494768)
		(end 347.358208 -138.321542)
		(width 0.089408)
		(layer "In4.Cu")
		(net "XDP_CPU_TRST_N")
	)
	(segment
		(start 442.270896 -147.574)
		(end 440.817 -146.120104)
		(width 0.089408)
		(layer "In4.Cu")
		(net "XDP_CPU_TRST_N")
	)
	(segment
		(start 403.550628 -146.487388)
		(end 402.955252 -146.487388)
		(width 0.089408)
		(layer "In4.Cu")
		(net "XDP_CPU_TRST_N")
	)
	(segment
		(start 333.20101 -110.8964)
		(end 333.20101 -108.41609)
		(width 0.089408)
		(layer "In4.Cu")
		(net "XDP_CPU_TRST_N")
	)
	(segment
		(start 331.518514 -95.196406)
		(end 331.518514 -94.929706)
		(width 0.089408)
		(layer "In4.Cu")
		(net "XDP_CPU_TRST_N")
	)
	(segment
		(start 347.358208 -138.321542)
		(end 343.51722 -138.321542)
		(width 0.089408)
		(layer "In4.Cu")
		(net "XDP_CPU_TRST_N")
	)
	(segment
		(start 335.18602 -117.13464)
		(end 335.18602 -116.802916)
		(width 0.089408)
		(layer "In4.Cu")
		(net "XDP_CPU_TRST_N")
	)
	(segment
		(start 408.812746 -152.089104)
		(end 406.556718 -152.089104)
		(width 0.089408)
		(layer "In4.Cu")
		(net "XDP_CPU_TRST_N")
	)
	(segment
		(start 337.894676 -125.369574)
		(end 334.074262 -121.54916)
		(width 0.089408)
		(layer "In4.Cu")
		(net "XDP_CPU_TRST_N")
	)
	(segment
		(start 412.984696 -146.531584)
		(end 410.94152 -148.57476)
		(width 0.089408)
		(layer "In4.Cu")
		(net "XDP_CPU_TRST_N")
	)
	(segment
		(start 331.518514 -94.929706)
		(end 334.854296 -91.593924)
		(width 0.089408)
		(layer "In4.Cu")
		(net "XDP_CPU_TRST_N")
	)
	(segment
		(start 462.857342 -151.141684)
		(end 462.764378 -151.234648)
		(width 0.089408)
		(layer "In4.Cu")
		(net "XDP_CPU_TRST_N")
	)
	(segment
		(start 342.516714 -137.321036)
		(end 340.737698 -137.321036)
		(width 0.089408)
		(layer "In4.Cu")
		(net "XDP_CPU_TRST_N")
	)
	(segment
		(start 446.073784 -150.8252)
		(end 442.822584 -147.574)
		(width 0.089408)
		(layer "In4.Cu")
		(net "XDP_CPU_TRST_N")
	)
	(segment
		(start 334.074262 -118.246398)
		(end 335.18602 -117.13464)
		(width 0.089408)
		(layer "In4.Cu")
		(net "XDP_CPU_TRST_N")
	)
	(segment
		(start 447.758566 -150.8252)
		(end 447.750692 -150.833074)
		(width 0.089408)
		(layer "In4.Cu")
		(net "XDP_CPU_TRST_N")
	)
	(segment
		(start 447.750692 -150.833074)
		(end 447.376804 -150.833074)
		(width 0.089408)
		(layer "In4.Cu")
		(net "XDP_CPU_TRST_N")
	)
	(segment
		(start 334.074262 -121.54916)
		(end 334.074262 -118.246398)
		(width 0.089408)
		(layer "In4.Cu")
		(net "XDP_CPU_TRST_N")
	)
	(segment
		(start 402.955252 -146.487388)
		(end 402.649182 -146.793458)
		(width 0.089408)
		(layer "In4.Cu")
		(net "XDP_CPU_TRST_N")
	)
	(segment
		(start 352.349308 -139.494768)
		(end 348.531434 -139.494768)
		(width 0.089408)
		(layer "In4.Cu")
		(net "XDP_CPU_TRST_N")
	)
	(segment
		(start 397.297402 -146.793458)
		(end 396.719044 -146.2151)
		(width 0.089408)
		(layer "In4.Cu")
		(net "XDP_CPU_TRST_N")
	)
	(segment
		(start 371.256052 -142.497048)
		(end 367.273586 -142.497048)
		(width 0.089408)
		(layer "In4.Cu")
		(net "XDP_CPU_TRST_N")
	)
	(segment
		(start 420.034212 -145.802096)
		(end 419.230048 -145.802096)
		(width 0.089408)
		(layer "In4.Cu")
		(net "XDP_CPU_TRST_N")
	)
	(segment
		(start 324.136512 -48.743616)
		(end 324.136512 -47.770288)
		(width 0.089408)
		(layer "In9.Cu")
		(net "XDP_CPU_TRST_N")
	)
	(segment
		(start 183.903112 -18.898616)
		(end 180.986176 -18.898616)
		(width 0.089408)
		(layer "In9.Cu")
		(net "XDP_CPU_TRST_N")
	)
	(segment
		(start 339.154008 -75.473814)
		(end 341.8586 -75.473814)
		(width 0.089408)
		(layer "In9.Cu")
		(net "XDP_CPU_TRST_N")
	)
	(segment
		(start 337.627214 -77.000608)
		(end 339.154008 -75.473814)
		(width 0.089408)
		(layer "In9.Cu")
		(net "XDP_CPU_TRST_N")
	)
	(segment
		(start 355.126544 -58.506868)
		(end 355.390704 -58.771028)
		(width 0.089408)
		(layer "In9.Cu")
		(net "XDP_CPU_TRST_N")
	)
	(segment
		(start 323.304408 -12.897358)
		(end 323.304662 -12.897104)
		(width 0.089408)
		(layer "In9.Cu")
		(net "XDP_CPU_TRST_N")
	)
	(segment
		(start 328.484484 -44.248832)
		(end 328.484484 -41.70045)
		(width 0.089408)
		(layer "In9.Cu")
		(net "XDP_CPU_TRST_N")
	)
	(segment
		(start 355.390704 -59.289442)
		(end 355.480112 -59.37885)
		(width 0.089408)
		(layer "In9.Cu")
		(net "XDP_CPU_TRST_N")
	)
	(segment
		(start 352.698812 -63.591948)
		(end 353.0854 -63.20536)
		(width 0.089408)
		(layer "In9.Cu")
		(net "XDP_CPU_TRST_N")
	)
	(segment
		(start 323.942202 -15.594076)
		(end 323.304408 -14.956282)
		(width 0.089408)
		(layer "In9.Cu")
		(net "XDP_CPU_TRST_N")
	)
	(segment
		(start 264.747248 -11.62685)
		(end 264.747248 -13.89888)
		(width 0.089408)
		(layer "In9.Cu")
		(net "XDP_CPU_TRST_N")
	)
	(segment
		(start 324.004178 -55.098442)
		(end 325.557388 -53.545232)
		(width 0.089408)
		(layer "In9.Cu")
		(net "XDP_CPU_TRST_N")
	)
	(segment
		(start 323.942202 -23.394162)
		(end 323.942202 -15.594076)
		(width 0.089408)
		(layer "In9.Cu")
		(net "XDP_CPU_TRST_N")
	)
	(segment
		(start 263.996678 -14.64945)
		(end 263.168638 -14.64945)
		(width 0.089408)
		(layer "In9.Cu")
		(net "XDP_CPU_TRST_N")
	)
	(segment
		(start 355.480112 -59.37885)
		(end 355.594412 -59.37885)
		(width 0.089408)
		(layer "In9.Cu")
		(net "XDP_CPU_TRST_N")
	)
	(segment
		(start 327.382378 -32.7406)
		(end 327.382378 -26.834338)
		(width 0.089408)
		(layer "In9.Cu")
		(net "XDP_CPU_TRST_N")
	)
	(segment
		(start 327.382378 -39.348156)
		(end 327.382378 -36.66998)
		(width 0.089408)
		(layer "In9.Cu")
		(net "XDP_CPU_TRST_N")
	)
	(segment
		(start 186.103006 -14.844776)
		(end 184.981342 -15.96644)
		(width 0.089408)
		(layer "In9.Cu")
		(net "XDP_CPU_TRST_N")
	)
	(segment
		(start 264.747248 -13.89888)
		(end 263.996678 -14.64945)
		(width 0.089408)
		(layer "In9.Cu")
		(net "XDP_CPU_TRST_N")
	)
	(segment
		(start 322.342256 -11.135614)
		(end 265.238484 -11.135614)
		(width 0.089408)
		(layer "In9.Cu")
		(net "XDP_CPU_TRST_N")
	)
	(segment
		(start 353.0854 -63.20536)
		(end 353.0854 -58.777124)
		(width 0.089408)
		(layer "In9.Cu")
		(net "XDP_CPU_TRST_N")
	)
	(segment
		(start 327.250298 -45.483018)
		(end 328.484484 -44.248832)
		(width 0.089408)
		(layer "In9.Cu")
		(net "XDP_CPU_TRST_N")
	)
	(segment
		(start 190.006224 -14.844776)
		(end 186.103006 -14.844776)
		(width 0.089408)
		(layer "In9.Cu")
		(net "XDP_CPU_TRST_N")
	)
	(segment
		(start 194.574668 -10.276332)
		(end 190.006224 -14.844776)
		(width 0.089408)
		(layer "In9.Cu")
		(net "XDP_CPU_TRST_N")
	)
	(segment
		(start 180.986176 -18.898616)
		(end 178.568096 -21.316696)
		(width 0.089408)
		(layer "In9.Cu")
		(net "XDP_CPU_TRST_N")
	)
	(segment
		(start 184.981342 -17.820386)
		(end 183.903112 -18.898616)
		(width 0.089408)
		(layer "In9.Cu")
		(net "XDP_CPU_TRST_N")
	)
	(segment
		(start 325.557388 -50.164492)
		(end 324.136512 -48.743616)
		(width 0.089408)
		(layer "In9.Cu")
		(net "XDP_CPU_TRST_N")
	)
	(segment
		(start 355.027992 -58.506868)
		(end 355.126544 -58.506868)
		(width 0.089408)
		(layer "In9.Cu")
		(net "XDP_CPU_TRST_N")
	)
	(segment
		(start 353.366324 -58.4962)
		(end 355.017324 -58.4962)
		(width 0.089408)
		(layer "In9.Cu")
		(net "XDP_CPU_TRST_N")
	)
	(segment
		(start 327.382378 -26.834338)
		(end 323.942202 -23.394162)
		(width 0.089408)
		(layer "In9.Cu")
		(net "XDP_CPU_TRST_N")
	)
	(segment
		(start 262.041894 -12.195556)
		(end 260.078728 -10.23239)
		(width 0.089408)
		(layer "In9.Cu")
		(net "XDP_CPU_TRST_N")
	)
	(segment
		(start 338.158582 -85.985858)
		(end 337.627214 -85.45449)
		(width 0.089408)
		(layer "In9.Cu")
		(net "XDP_CPU_TRST_N")
	)
	(segment
		(start 353.0854 -58.777124)
		(end 353.366324 -58.4962)
		(width 0.089408)
		(layer "In9.Cu")
		(net "XDP_CPU_TRST_N")
	)
	(segment
		(start 355.017324 -58.4962)
		(end 355.027992 -58.506868)
		(width 0.089408)
		(layer "In9.Cu")
		(net "XDP_CPU_TRST_N")
	)
	(segment
		(start 328.484484 -41.70045)
		(end 327.887584 -41.10355)
		(width 0.089408)
		(layer "In9.Cu")
		(net "XDP_CPU_TRST_N")
	)
	(segment
		(start 323.304408 -14.956282)
		(end 323.304408 -12.897358)
		(width 0.089408)
		(layer "In9.Cu")
		(net "XDP_CPU_TRST_N")
	)
	(segment
		(start 352.698812 -68.526406)
		(end 352.698812 -63.591948)
		(width 0.089408)
		(layer "In9.Cu")
		(net "XDP_CPU_TRST_N")
	)
	(segment
		(start 194.624198 -10.276332)
		(end 194.574668 -10.276332)
		(width 0.089408)
		(layer "In9.Cu")
		(net "XDP_CPU_TRST_N")
	)
	(segment
		(start 355.390704 -58.771028)
		(end 355.390704 -59.289442)
		(width 0.089408)
		(layer "In9.Cu")
		(net "XDP_CPU_TRST_N")
	)
	(segment
		(start 323.304662 -12.09802)
		(end 322.342256 -11.135614)
		(width 0.089408)
		(layer "In9.Cu")
		(net "XDP_CPU_TRST_N")
	)
	(segment
		(start 260.078728 -10.23239)
		(end 194.66814 -10.23239)
		(width 0.089408)
		(layer "In9.Cu")
		(net "XDP_CPU_TRST_N")
	)
	(segment
		(start 341.8586 -75.473814)
		(end 342.719406 -74.613008)
		(width 0.089408)
		(layer "In9.Cu")
		(net "XDP_CPU_TRST_N")
	)
	(segment
		(start 324.263512 -59.50458)
		(end 324.004178 -59.245246)
		(width 0.089408)
		(layer "In9.Cu")
		(net "XDP_CPU_TRST_N")
	)
	(segment
		(start 325.557388 -53.545232)
		(end 325.557388 -50.164492)
		(width 0.089408)
		(layer "In9.Cu")
		(net "XDP_CPU_TRST_N")
	)
	(segment
		(start 194.66814 -10.23239)
		(end 194.624198 -10.276332)
		(width 0.089408)
		(layer "In9.Cu")
		(net "XDP_CPU_TRST_N")
	)
	(segment
		(start 338.158582 -87.664798)
		(end 338.158582 -85.985858)
		(width 0.089408)
		(layer "In9.Cu")
		(net "XDP_CPU_TRST_N")
	)
	(segment
		(start 326.423782 -45.483018)
		(end 327.250298 -45.483018)
		(width 0.089408)
		(layer "In9.Cu")
		(net "XDP_CPU_TRST_N")
	)
	(segment
		(start 327.382378 -36.66998)
		(end 327.811384 -36.240974)
		(width 0.089408)
		(layer "In9.Cu")
		(net "XDP_CPU_TRST_N")
	)
	(segment
		(start 327.887584 -39.853362)
		(end 327.382378 -39.348156)
		(width 0.089408)
		(layer "In9.Cu")
		(net "XDP_CPU_TRST_N")
	)
	(segment
		(start 262.041894 -13.522706)
		(end 262.041894 -12.195556)
		(width 0.089408)
		(layer "In9.Cu")
		(net "XDP_CPU_TRST_N")
	)
	(segment
		(start 327.811384 -33.169606)
		(end 327.382378 -32.7406)
		(width 0.089408)
		(layer "In9.Cu")
		(net "XDP_CPU_TRST_N")
	)
	(segment
		(start 338.483702 -87.989918)
		(end 338.158582 -87.664798)
		(width 0.089408)
		(layer "In9.Cu")
		(net "XDP_CPU_TRST_N")
	)
	(segment
		(start 346.61221 -74.613008)
		(end 352.698812 -68.526406)
		(width 0.089408)
		(layer "In9.Cu")
		(net "XDP_CPU_TRST_N")
	)
	(segment
		(start 265.238484 -11.135614)
		(end 264.747248 -11.62685)
		(width 0.089408)
		(layer "In9.Cu")
		(net "XDP_CPU_TRST_N")
	)
	(segment
		(start 327.811384 -36.240974)
		(end 327.811384 -33.169606)
		(width 0.089408)
		(layer "In9.Cu")
		(net "XDP_CPU_TRST_N")
	)
	(segment
		(start 324.004178 -59.245246)
		(end 324.004178 -55.098442)
		(width 0.089408)
		(layer "In9.Cu")
		(net "XDP_CPU_TRST_N")
	)
	(segment
		(start 327.887584 -41.10355)
		(end 327.887584 -39.853362)
		(width 0.089408)
		(layer "In9.Cu")
		(net "XDP_CPU_TRST_N")
	)
	(segment
		(start 324.136512 -47.770288)
		(end 326.423782 -45.483018)
		(width 0.089408)
		(layer "In9.Cu")
		(net "XDP_CPU_TRST_N")
	)
	(segment
		(start 177.717704 -21.316696)
		(end 177.3682 -21.6662)
		(width 0.089408)
		(layer "In9.Cu")
		(net "XDP_CPU_TRST_N")
	)
	(segment
		(start 263.168638 -14.64945)
		(end 262.041894 -13.522706)
		(width 0.089408)
		(layer "In9.Cu")
		(net "XDP_CPU_TRST_N")
	)
	(segment
		(start 342.719406 -74.613008)
		(end 346.61221 -74.613008)
		(width 0.089408)
		(layer "In9.Cu")
		(net "XDP_CPU_TRST_N")
	)
	(segment
		(start 337.627214 -85.45449)
		(end 337.627214 -77.000608)
		(width 0.089408)
		(layer "In9.Cu")
		(net "XDP_CPU_TRST_N")
	)
	(segment
		(start 323.304662 -12.897104)
		(end 323.304662 -12.09802)
		(width 0.089408)
		(layer "In9.Cu")
		(net "XDP_CPU_TRST_N")
	)
	(segment
		(start 178.568096 -21.316696)
		(end 177.717704 -21.316696)
		(width 0.089408)
		(layer "In9.Cu")
		(net "XDP_CPU_TRST_N")
	)
	(segment
		(start 184.981342 -15.96644)
		(end 184.981342 -17.820386)
		(width 0.089408)
		(layer "In9.Cu")
		(net "XDP_CPU_TRST_N")
	)
	(segment
		(start 137.4902 -55.3974)
		(end 137.033 -55.8546)
		(width 0.089408)
		(layer "In11.Cu")
		(net "XDP_CPU_TRST_N")
	)
	(segment
		(start 140.132816 -53.770784)
		(end 139.3952 -54.5084)
		(width 0.089408)
		(layer "In11.Cu")
		(net "XDP_CPU_TRST_N")
	)
	(segment
		(start 138.6332 -54.9402)
		(end 138.303 -54.9402)
		(width 0.089408)
		(layer "In11.Cu")
		(net "XDP_CPU_TRST_N")
	)
	(segment
		(start 158.507176 -30.873446)
		(end 155.988258 -36.953952)
		(width 0.089408)
		(layer "In11.Cu")
		(net "XDP_CPU_TRST_N")
	)
	(segment
		(start 137.8458 -55.3974)
		(end 137.4902 -55.3974)
		(width 0.089408)
		(layer "In11.Cu")
		(net "XDP_CPU_TRST_N")
	)
	(segment
		(start 176.70018 -22.33422)
		(end 172.17771 -22.33422)
		(width 0.089408)
		(layer "In11.Cu")
		(net "XDP_CPU_TRST_N")
	)
	(segment
		(start 301.82566 -59.962288)
		(end 301.799752 -59.962288)
		(width 0.0889)
		(layer "In11.Cu")
		(net "XDP_CPU_TRST_N")
	)
	(segment
		(start 304.4063 -59.466988)
		(end 304.370232 -59.466988)
		(width 0.0889)
		(layer "In11.Cu")
		(net "XDP_CPU_TRST_N")
	)
	(segment
		(start 322.160646 -59.50458)
		(end 319.445386 -62.21984)
		(width 0.089408)
		(layer "In11.Cu")
		(net "XDP_CPU_TRST_N")
	)
	(segment
		(start 302.68926 -59.466988)
		(end 302.653192 -59.466988)
		(width 0.0889)
		(layer "In11.Cu")
		(net "XDP_CPU_TRST_N")
	)
	(segment
		(start 170.201336 -23.90394)
		(end 167.910764 -26.194512)
		(width 0.089408)
		(layer "In11.Cu")
		(net "XDP_CPU_TRST_N")
	)
	(segment
		(start 159.845502 -29.53512)
		(end 158.507176 -30.873446)
		(width 0.089408)
		(layer "In11.Cu")
		(net "XDP_CPU_TRST_N")
	)
	(segment
		(start 325.97725 -58.626248)
		(end 325.098918 -59.50458)
		(width 0.089408)
		(layer "In11.Cu")
		(net "XDP_CPU_TRST_N")
	)
	(segment
		(start 355.6254 -59.347862)
		(end 355.6254 -59.005724)
		(width 0.089408)
		(layer "In11.Cu")
		(net "XDP_CPU_TRST_N")
	)
	(segment
		(start 297.541696 -60.457334)
		(end 297.520106 -60.457334)
		(width 0.0889)
		(layer "In11.Cu")
		(net "XDP_CPU_TRST_N")
	)
	(segment
		(start 328.031856 -58.764424)
		(end 327.89368 -58.626248)
		(width 0.089408)
		(layer "In11.Cu")
		(net "XDP_CPU_TRST_N")
	)
	(segment
		(start 135.7884 -56.4134)
		(end 135.2296 -56.9722)
		(width 0.089408)
		(layer "In11.Cu")
		(net "XDP_CPU_TRST_N")
	)
	(segment
		(start 134.7724 -56.9722)
		(end 134.2898 -57.4548)
		(width 0.089408)
		(layer "In11.Cu")
		(net "XDP_CPU_TRST_N")
	)
	(segment
		(start 133.5278 -57.8612)
		(end 133.1976 -57.8612)
		(width 0.089408)
		(layer "In11.Cu")
		(net "XDP_CPU_TRST_N")
	)
	(segment
		(start 136.652 -55.8546)
		(end 136.0932 -56.4134)
		(width 0.089408)
		(layer "In11.Cu")
		(net "XDP_CPU_TRST_N")
	)
	(segment
		(start 132.969 -58.0898)
		(end 132.969 -60.071)
		(width 0.089408)
		(layer "In11.Cu")
		(net "XDP_CPU_TRST_N")
	)
	(segment
		(start 327.89368 -58.626248)
		(end 325.97725 -58.626248)
		(width 0.089408)
		(layer "In11.Cu")
		(net "XDP_CPU_TRST_N")
	)
	(segment
		(start 172.17771 -22.33422)
		(end 170.895772 -23.616158)
		(width 0.089408)
		(layer "In11.Cu")
		(net "XDP_CPU_TRST_N")
	)
	(segment
		(start 308.467252 -59.962288)
		(end 306.950872 -59.962288)
		(width 0.0889)
		(layer "In11.Cu")
		(net "XDP_CPU_TRST_N")
	)
	(segment
		(start 132.969 -60.071)
		(end 132.519674 -60.520326)
		(width 0.089408)
		(layer "In11.Cu")
		(net "XDP_CPU_TRST_N")
	)
	(segment
		(start 170.895772 -23.616158)
		(end 170.201336 -23.90394)
		(width 0.089408)
		(layer "In11.Cu")
		(net "XDP_CPU_TRST_N")
	)
	(segment
		(start 137.033 -55.8546)
		(end 136.652 -55.8546)
		(width 0.089408)
		(layer "In11.Cu")
		(net "XDP_CPU_TRST_N")
	)
	(segment
		(start 140.813282 -52.128674)
		(end 140.132816 -53.770784)
		(width 0.089408)
		(layer "In11.Cu")
		(net "XDP_CPU_TRST_N")
	)
	(segment
		(start 355.11613 -58.496454)
		(end 353.862386 -58.496454)
		(width 0.089408)
		(layer "In11.Cu")
		(net "XDP_CPU_TRST_N")
	)
	(segment
		(start 139.3952 -54.5084)
		(end 139.065 -54.5084)
		(width 0.089408)
		(layer "In11.Cu")
		(net "XDP_CPU_TRST_N")
	)
	(segment
		(start 355.594412 -59.37885)
		(end 355.6254 -59.347862)
		(width 0.089408)
		(layer "In11.Cu")
		(net "XDP_CPU_TRST_N")
	)
	(segment
		(start 134.2898 -57.4548)
		(end 133.9342 -57.4548)
		(width 0.089408)
		(layer "In11.Cu")
		(net "XDP_CPU_TRST_N")
	)
	(segment
		(start 311.59704 -59.77382)
		(end 308.65572 -59.77382)
		(width 0.0889)
		(layer "In11.Cu")
		(net "XDP_CPU_TRST_N")
	)
	(segment
		(start 135.2296 -56.9722)
		(end 134.7724 -56.9722)
		(width 0.089408)
		(layer "In11.Cu")
		(net "XDP_CPU_TRST_N")
	)
	(segment
		(start 298.39158 -59.962288)
		(end 298.36364 -59.962288)
		(width 0.0889)
		(layer "In11.Cu")
		(net "XDP_CPU_TRST_N")
	)
	(segment
		(start 324.263512 -59.50458)
		(end 322.160646 -59.50458)
		(width 0.089408)
		(layer "In11.Cu")
		(net "XDP_CPU_TRST_N")
	)
	(segment
		(start 353.426522 -58.06059)
		(end 330.709778 -58.06059)
		(width 0.089408)
		(layer "In11.Cu")
		(net "XDP_CPU_TRST_N")
	)
	(segment
		(start 319.445386 -62.21984)
		(end 314.04306 -62.21984)
		(width 0.089408)
		(layer "In11.Cu")
		(net "XDP_CPU_TRST_N")
	)
	(segment
		(start 300.97222 -59.466988)
		(end 300.936152 -59.466988)
		(width 0.0889)
		(layer "In11.Cu")
		(net "XDP_CPU_TRST_N")
	)
	(segment
		(start 138.303 -54.9402)
		(end 137.8458 -55.3974)
		(width 0.089408)
		(layer "In11.Cu")
		(net "XDP_CPU_TRST_N")
	)
	(segment
		(start 177.3682 -21.6662)
		(end 176.70018 -22.33422)
		(width 0.089408)
		(layer "In11.Cu")
		(net "XDP_CPU_TRST_N")
	)
	(segment
		(start 299.25518 -59.466988)
		(end 299.219112 -59.466988)
		(width 0.0889)
		(layer "In11.Cu")
		(net "XDP_CPU_TRST_N")
	)
	(segment
		(start 308.65572 -59.77382)
		(end 308.467252 -59.962288)
		(width 0.0889)
		(layer "In11.Cu")
		(net "XDP_CPU_TRST_N")
	)
	(segment
		(start 353.862386 -58.496454)
		(end 353.426522 -58.06059)
		(width 0.089408)
		(layer "In11.Cu")
		(net "XDP_CPU_TRST_N")
	)
	(segment
		(start 297.206162 -60.609734)
		(end 297.227244 -60.688474)
		(width 0.0889)
		(layer "In11.Cu")
		(net "XDP_CPU_TRST_N")
	)
	(segment
		(start 297.227244 -60.688474)
		(end 297.520106 -60.857384)
		(width 0.0889)
		(layer "In11.Cu")
		(net "XDP_CPU_TRST_N")
	)
	(segment
		(start 306.12334 -59.466988)
		(end 306.087272 -59.466988)
		(width 0.0889)
		(layer "In11.Cu")
		(net "XDP_CPU_TRST_N")
	)
	(segment
		(start 167.910764 -26.194512)
		(end 161.434526 -28.877006)
		(width 0.089408)
		(layer "In11.Cu")
		(net "XDP_CPU_TRST_N")
	)
	(segment
		(start 325.098918 -59.50458)
		(end 324.263512 -59.50458)
		(width 0.089408)
		(layer "In11.Cu")
		(net "XDP_CPU_TRST_N")
	)
	(segment
		(start 139.065 -54.5084)
		(end 138.6332 -54.9402)
		(width 0.089408)
		(layer "In11.Cu")
		(net "XDP_CPU_TRST_N")
	)
	(segment
		(start 132.519674 -60.520326)
		(end 132.519674 -60.857384)
		(width 0.089408)
		(layer "In11.Cu")
		(net "XDP_CPU_TRST_N")
	)
	(segment
		(start 161.434526 -28.877006)
		(end 159.845502 -29.53512)
		(width 0.089408)
		(layer "In11.Cu")
		(net "XDP_CPU_TRST_N")
	)
	(segment
		(start 355.6254 -59.005724)
		(end 355.11613 -58.496454)
		(width 0.089408)
		(layer "In11.Cu")
		(net "XDP_CPU_TRST_N")
	)
	(segment
		(start 330.005944 -58.764424)
		(end 328.031856 -58.764424)
		(width 0.089408)
		(layer "In11.Cu")
		(net "XDP_CPU_TRST_N")
	)
	(segment
		(start 330.709778 -58.06059)
		(end 330.005944 -58.764424)
		(width 0.089408)
		(layer "In11.Cu")
		(net "XDP_CPU_TRST_N")
	)
	(segment
		(start 133.9342 -57.4548)
		(end 133.5278 -57.8612)
		(width 0.089408)
		(layer "In11.Cu")
		(net "XDP_CPU_TRST_N")
	)
	(segment
		(start 155.988258 -36.953952)
		(end 140.813282 -52.128674)
		(width 0.089408)
		(layer "In11.Cu")
		(net "XDP_CPU_TRST_N")
	)
	(segment
		(start 136.0932 -56.4134)
		(end 135.7884 -56.4134)
		(width 0.089408)
		(layer "In11.Cu")
		(net "XDP_CPU_TRST_N")
	)
	(segment
		(start 133.1976 -57.8612)
		(end 132.969 -58.0898)
		(width 0.089408)
		(layer "In11.Cu")
		(net "XDP_CPU_TRST_N")
	)
	(segment
		(start 314.04306 -62.21984)
		(end 311.59704 -59.77382)
		(width 0.0889)
		(layer "In11.Cu")
		(net "XDP_CPU_TRST_N")
	)
	(arc
		(start 305.758596 -59.666886)
		(mid 305.246786 -59.962425)
		(end 304.734976 -59.666886)
		(width 0.0889)
		(layer "In11.Cu")
		(net "XDP_CPU_TRST_N")
	)
	(arc
		(start 300.936152 -59.466988)
		(mid 300.746223 -59.524858)
		(end 300.607476 -59.666886)
		(width 0.0889)
		(layer "In11.Cu")
		(net "XDP_CPU_TRST_N")
	)
	(arc
		(start 301.300896 -59.666886)
		(mid 301.162152 -59.524853)
		(end 300.97222 -59.466988)
		(width 0.0889)
		(layer "In11.Cu")
		(net "XDP_CPU_TRST_N")
	)
	(arc
		(start 303.017936 -59.666886)
		(mid 302.879192 -59.524853)
		(end 302.68926 -59.466988)
		(width 0.0889)
		(layer "In11.Cu")
		(net "XDP_CPU_TRST_N")
	)
	(arc
		(start 301.799752 -59.962288)
		(mid 301.511607 -59.879969)
		(end 301.300896 -59.666886)
		(width 0.0889)
		(layer "In11.Cu")
		(net "XDP_CPU_TRST_N")
	)
	(arc
		(start 304.734976 -59.666886)
		(mid 304.596232 -59.524853)
		(end 304.4063 -59.466988)
		(width 0.0889)
		(layer "In11.Cu")
		(net "XDP_CPU_TRST_N")
	)
	(arc
		(start 300.607476 -59.666886)
		(mid 300.095666 -59.962425)
		(end 299.583856 -59.666886)
		(width 0.0889)
		(layer "In11.Cu")
		(net "XDP_CPU_TRST_N")
	)
	(arc
		(start 302.324516 -59.666886)
		(mid 302.113803 -59.879965)
		(end 301.82566 -59.962288)
		(width 0.0889)
		(layer "In11.Cu")
		(net "XDP_CPU_TRST_N")
	)
	(arc
		(start 304.370232 -59.466988)
		(mid 304.180303 -59.524858)
		(end 304.041556 -59.666886)
		(width 0.0889)
		(layer "In11.Cu")
		(net "XDP_CPU_TRST_N")
	)
	(arc
		(start 306.452016 -59.666886)
		(mid 306.313272 -59.524853)
		(end 306.12334 -59.466988)
		(width 0.0889)
		(layer "In11.Cu")
		(net "XDP_CPU_TRST_N")
	)
	(arc
		(start 297.520106 -60.457334)
		(mid 297.345645 -60.497503)
		(end 297.206162 -60.609734)
		(width 0.0889)
		(layer "In11.Cu")
		(net "XDP_CPU_TRST_N")
	)
	(arc
		(start 306.950872 -59.962288)
		(mid 306.662727 -59.879969)
		(end 306.452016 -59.666886)
		(width 0.0889)
		(layer "In11.Cu")
		(net "XDP_CPU_TRST_N")
	)
	(arc
		(start 302.653192 -59.466988)
		(mid 302.463263 -59.524858)
		(end 302.324516 -59.666886)
		(width 0.0889)
		(layer "In11.Cu")
		(net "XDP_CPU_TRST_N")
	)
	(arc
		(start 298.890436 -59.666886)
		(mid 298.679723 -59.879965)
		(end 298.39158 -59.962288)
		(width 0.0889)
		(layer "In11.Cu")
		(net "XDP_CPU_TRST_N")
	)
	(arc
		(start 306.087272 -59.466988)
		(mid 305.897343 -59.524858)
		(end 305.758596 -59.666886)
		(width 0.0889)
		(layer "In11.Cu")
		(net "XDP_CPU_TRST_N")
	)
	(arc
		(start 304.041556 -59.666886)
		(mid 303.529746 -59.962425)
		(end 303.017936 -59.666886)
		(width 0.0889)
		(layer "In11.Cu")
		(net "XDP_CPU_TRST_N")
	)
	(arc
		(start 299.219112 -59.466988)
		(mid 299.029183 -59.524858)
		(end 298.890436 -59.666886)
		(width 0.0889)
		(layer "In11.Cu")
		(net "XDP_CPU_TRST_N")
	)
	(arc
		(start 298.36364 -59.962288)
		(mid 298.171998 -60.019454)
		(end 298.031916 -60.162186)
		(width 0.0889)
		(layer "In11.Cu")
		(net "XDP_CPU_TRST_N")
	)
	(arc
		(start 299.583856 -59.666886)
		(mid 299.445112 -59.524853)
		(end 299.25518 -59.466988)
		(width 0.0889)
		(layer "In11.Cu")
		(net "XDP_CPU_TRST_N")
	)
	(arc
		(start 298.031916 -60.162186)
		(mid 297.824912 -60.37305)
		(end 297.541696 -60.457334)
		(width 0.0889)
		(layer "In11.Cu")
		(net "XDP_CPU_TRST_N")
	)
	(segment
		(start 296.66184 -60.362338)
		(end 296.09034 -60.362338)
		(width 0.1016)
		(layer "F.Cu")
		(net "XDP_CPU_TMS")
	)
	(segment
		(start 131.089908 -60.362338)
		(end 131.661408 -60.362338)
		(width 0.1016)
		(layer "F.Cu")
		(net "XDP_CPU_TMS")
	)
	(via
		(at 353.6696 -84.0232)
		(size 0.508)
		(drill 0.254)
		(layers "F.Cu" "B.Cu")
		(net "XDP_CPU_TMS")
	)
	(via
		(at 325.1073 -58.251852)
		(size 0.508)
		(drill 0.254)
		(layers "F.Cu" "B.Cu")
		(net "XDP_CPU_TMS")
	)
	(via
		(at 355.2444 -58.0898)
		(size 0.508)
		(drill 0.254)
		(layers "F.Cu" "B.Cu")
		(net "XDP_CPU_TMS")
	)
	(via
		(at 131.661408 -60.362338)
		(size 0.508)
		(drill 0.254)
		(layers "F.Cu" "B.Cu")
		(net "XDP_CPU_TMS")
	)
	(via
		(at 296.66184 -60.362338)
		(size 0.508)
		(drill 0.254)
		(layers "F.Cu" "B.Cu")
		(net "XDP_CPU_TMS")
	)
	(via
		(at 460.0194 -149.0472)
		(size 0.508)
		(drill 0.254)
		(layers "F.Cu" "B.Cu")
		(net "XDP_CPU_TMS")
	)
	(via
		(at 176.4284 -21.59)
		(size 0.508)
		(drill 0.254)
		(layers "F.Cu" "B.Cu")
		(net "XDP_CPU_TMS")
	)
	(via
		(at 462.76133 -149.4028)
		(size 0.6604)
		(drill 0.3302)
		(layers "F.Cu" "B.Cu")
		(net "XDP_CPU_TMS")
	)
	(segment
		(start 462.76133 -149.54377)
		(end 462.428844 -149.876256)
		(width 0.10795)
		(layer "B.Cu")
		(net "XDP_CPU_TMS")
	)
	(segment
		(start 462.166208 -147.379436)
		(end 462.166208 -147.650454)
		(width 0.10795)
		(layer "B.Cu")
		(net "XDP_CPU_TMS")
	)
	(segment
		(start 462.76133 -148.944584)
		(end 462.76133 -149.4028)
		(width 0.10795)
		(layer "B.Cu")
		(net "XDP_CPU_TMS")
	)
	(segment
		(start 461.966564 -147.179792)
		(end 462.166208 -147.379436)
		(width 0.10795)
		(layer "B.Cu")
		(net "XDP_CPU_TMS")
	)
	(segment
		(start 462.76133 -149.4028)
		(end 462.76133 -149.54377)
		(width 0.10795)
		(layer "B.Cu")
		(net "XDP_CPU_TMS")
	)
	(segment
		(start 460.983076 -147.179792)
		(end 461.966564 -147.179792)
		(width 0.10795)
		(layer "B.Cu")
		(net "XDP_CPU_TMS")
	)
	(segment
		(start 462.428844 -149.876256)
		(end 461.430116 -149.876256)
		(width 0.10795)
		(layer "B.Cu")
		(net "XDP_CPU_TMS")
	)
	(segment
		(start 460.1464 -148.9202)
		(end 460.1464 -148.016468)
		(width 0.10795)
		(layer "B.Cu")
		(net "XDP_CPU_TMS")
	)
	(segment
		(start 460.1464 -148.016468)
		(end 460.983076 -147.179792)
		(width 0.10795)
		(layer "B.Cu")
		(net "XDP_CPU_TMS")
	)
	(segment
		(start 462.166208 -147.650454)
		(end 462.166208 -148.349462)
		(width 0.10795)
		(layer "B.Cu")
		(net "XDP_CPU_TMS")
	)
	(segment
		(start 462.166208 -148.349462)
		(end 462.76133 -148.944584)
		(width 0.10795)
		(layer "B.Cu")
		(net "XDP_CPU_TMS")
	)
	(segment
		(start 460.0194 -149.0472)
		(end 460.1464 -148.9202)
		(width 0.10795)
		(layer "B.Cu")
		(net "XDP_CPU_TMS")
	)
	(segment
		(start 335.7626 -108.476034)
		(end 335.7626 -110.0582)
		(width 0.089408)
		(layer "In4.Cu")
		(net "XDP_CPU_TMS")
	)
	(segment
		(start 366.396778 -142.924022)
		(end 367.142014 -142.178786)
		(width 0.089408)
		(layer "In4.Cu")
		(net "XDP_CPU_TMS")
	)
	(segment
		(start 339.092286 -111.80572)
		(end 340.785704 -113.499138)
		(width 0.089408)
		(layer "In4.Cu")
		(net "XDP_CPU_TMS")
	)
	(segment
		(start 338.371688 -130.231388)
		(end 338.371688 -132.726176)
		(width 0.089408)
		(layer "In4.Cu")
		(net "XDP_CPU_TMS")
	)
	(segment
		(start 347.533468 -138.003534)
		(end 348.706694 -139.17676)
		(width 0.089408)
		(layer "In4.Cu")
		(net "XDP_CPU_TMS")
	)
	(segment
		(start 362.15447 -141.417294)
		(end 362.222288 -141.485112)
		(width 0.089408)
		(layer "In4.Cu")
		(net "XDP_CPU_TMS")
	)
	(segment
		(start 338.371688 -132.726176)
		(end 343.649046 -138.003534)
		(width 0.089408)
		(layer "In4.Cu")
		(net "XDP_CPU_TMS")
	)
	(segment
		(start 337.7819 -90.3732)
		(end 332.536292 -95.618808)
		(width 0.089408)
		(layer "In4.Cu")
		(net "XDP_CPU_TMS")
	)
	(segment
		(start 340.785704 -114.88547)
		(end 342.706706 -116.806472)
		(width 0.089408)
		(layer "In4.Cu")
		(net "XDP_CPU_TMS")
	)
	(segment
		(start 453.387206 -147.879816)
		(end 456.775312 -147.879816)
		(width 0.089408)
		(layer "In4.Cu")
		(net "XDP_CPU_TMS")
	)
	(segment
		(start 371.257322 -141.938756)
		(end 382.646682 -141.938756)
		(width 0.089408)
		(layer "In4.Cu")
		(net "XDP_CPU_TMS")
	)
	(segment
		(start 456.775312 -147.879816)
		(end 457.942696 -149.0472)
		(width 0.089408)
		(layer "In4.Cu")
		(net "XDP_CPU_TMS")
	)
	(segment
		(start 418.279072 -146.213576)
		(end 419.00856 -145.484088)
		(width 0.089408)
		(layer "In4.Cu")
		(net "XDP_CPU_TMS")
	)
	(segment
		(start 348.9452 -85.77834)
		(end 348.9452 -88.89746)
		(width 0.089408)
		(layer "In4.Cu")
		(net "XDP_CPU_TMS")
	)
	(segment
		(start 348.9452 -88.89746)
		(end 348.143068 -89.699592)
		(width 0.089408)
		(layer "In4.Cu")
		(net "XDP_CPU_TMS")
	)
	(segment
		(start 392.223244 -141.765528)
		(end 392.748516 -142.2908)
		(width 0.089408)
		(layer "In4.Cu")
		(net "XDP_CPU_TMS")
	)
	(segment
		(start 452.198232 -149.908768)
		(end 452.897494 -149.209506)
		(width 0.089408)
		(layer "In4.Cu")
		(net "XDP_CPU_TMS")
	)
	(segment
		(start 335.7626 -110.0582)
		(end 337.51012 -111.80572)
		(width 0.089408)
		(layer "In4.Cu")
		(net "XDP_CPU_TMS")
	)
	(segment
		(start 452.897494 -149.209506)
		(end 452.897494 -148.369528)
		(width 0.089408)
		(layer "In4.Cu")
		(net "XDP_CPU_TMS")
	)
	(segment
		(start 383.203704 -142.495778)
		(end 384.707384 -142.495778)
		(width 0.089408)
		(layer "In4.Cu")
		(net "XDP_CPU_TMS")
	)
	(segment
		(start 398.720818 -144.180052)
		(end 398.720818 -145.146014)
		(width 0.089408)
		(layer "In4.Cu")
		(net "XDP_CPU_TMS")
	)
	(segment
		(start 402.547328 -146.445478)
		(end 402.823426 -146.16938)
		(width 0.089408)
		(layer "In4.Cu")
		(net "XDP_CPU_TMS")
	)
	(segment
		(start 341.969598 -125.53823)
		(end 341.969598 -126.72949)
		(width 0.089408)
		(layer "In4.Cu")
		(net "XDP_CPU_TMS")
	)
	(segment
		(start 360.869992 -141.417294)
		(end 362.15447 -141.417294)
		(width 0.089408)
		(layer "In4.Cu")
		(net "XDP_CPU_TMS")
	)
	(segment
		(start 339.281262 -129.356104)
		(end 339.246972 -129.356104)
		(width 0.089408)
		(layer "In4.Cu")
		(net "XDP_CPU_TMS")
	)
	(segment
		(start 398.720818 -145.146014)
		(end 400.020282 -146.445478)
		(width 0.089408)
		(layer "In4.Cu")
		(net "XDP_CPU_TMS")
	)
	(segment
		(start 382.646682 -141.938756)
		(end 383.203704 -142.495778)
		(width 0.089408)
		(layer "In4.Cu")
		(net "XDP_CPU_TMS")
	)
	(segment
		(start 352.8568 -84.836)
		(end 349.88754 -84.836)
		(width 0.089408)
		(layer "In4.Cu")
		(net "XDP_CPU_TMS")
	)
	(segment
		(start 339.246972 -129.356104)
		(end 338.371688 -130.231388)
		(width 0.089408)
		(layer "In4.Cu")
		(net "XDP_CPU_TMS")
	)
	(segment
		(start 420.391082 -145.707862)
		(end 440.944 -145.707862)
		(width 0.089408)
		(layer "In4.Cu")
		(net "XDP_CPU_TMS")
	)
	(segment
		(start 339.510878 -129.126488)
		(end 339.281262 -129.356104)
		(width 0.089408)
		(layer "In4.Cu")
		(net "XDP_CPU_TMS")
	)
	(segment
		(start 342.706706 -116.806472)
		(end 342.710516 -116.806472)
		(width 0.089408)
		(layer "In4.Cu")
		(net "XDP_CPU_TMS")
	)
	(segment
		(start 348.143068 -89.699592)
		(end 340.424008 -89.699592)
		(width 0.089408)
		(layer "In4.Cu")
		(net "XDP_CPU_TMS")
	)
	(segment
		(start 396.831566 -142.2908)
		(end 398.720818 -144.180052)
		(width 0.089408)
		(layer "In4.Cu")
		(net "XDP_CPU_TMS")
	)
	(segment
		(start 364.506764 -141.485112)
		(end 365.945674 -142.924022)
		(width 0.089408)
		(layer "In4.Cu")
		(net "XDP_CPU_TMS")
	)
	(segment
		(start 410.656024 -147.57781)
		(end 412.020258 -146.213576)
		(width 0.089408)
		(layer "In4.Cu")
		(net "XDP_CPU_TMS")
	)
	(segment
		(start 348.706694 -139.17676)
		(end 352.884232 -139.17676)
		(width 0.089408)
		(layer "In4.Cu")
		(net "XDP_CPU_TMS")
	)
	(segment
		(start 440.944 -145.707862)
		(end 442.429138 -147.193)
		(width 0.089408)
		(layer "In4.Cu")
		(net "XDP_CPU_TMS")
	)
	(segment
		(start 402.823426 -146.16938)
		(end 403.682454 -146.16938)
		(width 0.089408)
		(layer "In4.Cu")
		(net "XDP_CPU_TMS")
	)
	(segment
		(start 449.396866 -149.908768)
		(end 452.198232 -149.908768)
		(width 0.089408)
		(layer "In4.Cu")
		(net "XDP_CPU_TMS")
	)
	(segment
		(start 343.346278 -117.442234)
		(end 343.346278 -118.402354)
		(width 0.089408)
		(layer "In4.Cu")
		(net "XDP_CPU_TMS")
	)
	(segment
		(start 409.884626 -147.57781)
		(end 410.656024 -147.57781)
		(width 0.089408)
		(layer "In4.Cu")
		(net "XDP_CPU_TMS")
	)
	(segment
		(start 385.437634 -141.765528)
		(end 392.223244 -141.765528)
		(width 0.089408)
		(layer "In4.Cu")
		(net "XDP_CPU_TMS")
	)
	(segment
		(start 352.931984 -139.129008)
		(end 358.581706 -139.129008)
		(width 0.089408)
		(layer "In4.Cu")
		(net "XDP_CPU_TMS")
	)
	(segment
		(start 343.346278 -118.402354)
		(end 341.558372 -120.19026)
		(width 0.089408)
		(layer "In4.Cu")
		(net "XDP_CPU_TMS")
	)
	(segment
		(start 340.424008 -89.699592)
		(end 339.7504 -90.3732)
		(width 0.089408)
		(layer "In4.Cu")
		(net "XDP_CPU_TMS")
	)
	(segment
		(start 341.558372 -125.127004)
		(end 341.969598 -125.53823)
		(width 0.089408)
		(layer "In4.Cu")
		(net "XDP_CPU_TMS")
	)
	(segment
		(start 339.5726 -129.126488)
		(end 339.510878 -129.126488)
		(width 0.089408)
		(layer "In4.Cu")
		(net "XDP_CPU_TMS")
	)
	(segment
		(start 443.23 -147.193)
		(end 444.119 -148.082)
		(width 0.089408)
		(layer "In4.Cu")
		(net "XDP_CPU_TMS")
	)
	(segment
		(start 362.222288 -141.485112)
		(end 364.506764 -141.485112)
		(width 0.089408)
		(layer "In4.Cu")
		(net "XDP_CPU_TMS")
	)
	(segment
		(start 452.897494 -148.369528)
		(end 453.387206 -147.879816)
		(width 0.089408)
		(layer "In4.Cu")
		(net "XDP_CPU_TMS")
	)
	(segment
		(start 447.570098 -148.082)
		(end 449.396866 -149.908768)
		(width 0.089408)
		(layer "In4.Cu")
		(net "XDP_CPU_TMS")
	)
	(segment
		(start 342.710516 -116.806472)
		(end 343.346278 -117.442234)
		(width 0.089408)
		(layer "In4.Cu")
		(net "XDP_CPU_TMS")
	)
	(segment
		(start 349.88754 -84.836)
		(end 348.9452 -85.77834)
		(width 0.089408)
		(layer "In4.Cu")
		(net "XDP_CPU_TMS")
	)
	(segment
		(start 332.536292 -96.610424)
		(end 332.536546 -96.610678)
		(width 0.089408)
		(layer "In4.Cu")
		(net "XDP_CPU_TMS")
	)
	(segment
		(start 384.707384 -142.495778)
		(end 385.437634 -141.765528)
		(width 0.089408)
		(layer "In4.Cu")
		(net "XDP_CPU_TMS")
	)
	(segment
		(start 442.429138 -147.193)
		(end 443.23 -147.193)
		(width 0.089408)
		(layer "In4.Cu")
		(net "XDP_CPU_TMS")
	)
	(segment
		(start 408.389836 -149.0726)
		(end 409.884626 -147.57781)
		(width 0.089408)
		(layer "In4.Cu")
		(net "XDP_CPU_TMS")
	)
	(segment
		(start 358.581706 -139.129008)
		(end 360.869992 -141.417294)
		(width 0.089408)
		(layer "In4.Cu")
		(net "XDP_CPU_TMS")
	)
	(segment
		(start 353.6696 -84.0232)
		(end 352.8568 -84.836)
		(width 0.089408)
		(layer "In4.Cu")
		(net "XDP_CPU_TMS")
	)
	(segment
		(start 400.020282 -146.445478)
		(end 402.547328 -146.445478)
		(width 0.089408)
		(layer "In4.Cu")
		(net "XDP_CPU_TMS")
	)
	(segment
		(start 352.884232 -139.17676)
		(end 352.931984 -139.129008)
		(width 0.089408)
		(layer "In4.Cu")
		(net "XDP_CPU_TMS")
	)
	(segment
		(start 444.119 -148.082)
		(end 447.570098 -148.082)
		(width 0.089408)
		(layer "In4.Cu")
		(net "XDP_CPU_TMS")
	)
	(segment
		(start 341.558372 -120.19026)
		(end 341.558372 -125.127004)
		(width 0.089408)
		(layer "In4.Cu")
		(net "XDP_CPU_TMS")
	)
	(segment
		(start 341.969598 -126.72949)
		(end 339.5726 -129.126488)
		(width 0.089408)
		(layer "In4.Cu")
		(net "XDP_CPU_TMS")
	)
	(segment
		(start 371.017292 -142.178786)
		(end 371.257322 -141.938756)
		(width 0.089408)
		(layer "In4.Cu")
		(net "XDP_CPU_TMS")
	)
	(segment
		(start 365.945674 -142.924022)
		(end 366.396778 -142.924022)
		(width 0.089408)
		(layer "In4.Cu")
		(net "XDP_CPU_TMS")
	)
	(segment
		(start 403.682454 -146.16938)
		(end 406.585674 -149.0726)
		(width 0.089408)
		(layer "In4.Cu")
		(net "XDP_CPU_TMS")
	)
	(segment
		(start 339.7504 -90.3732)
		(end 337.7819 -90.3732)
		(width 0.089408)
		(layer "In4.Cu")
		(net "XDP_CPU_TMS")
	)
	(segment
		(start 392.748516 -142.2908)
		(end 396.831566 -142.2908)
		(width 0.089408)
		(layer "In4.Cu")
		(net "XDP_CPU_TMS")
	)
	(segment
		(start 419.00856 -145.484088)
		(end 420.167308 -145.484088)
		(width 0.089408)
		(layer "In4.Cu")
		(net "XDP_CPU_TMS")
	)
	(segment
		(start 332.536546 -96.610678)
		(end 332.536546 -106.115866)
		(width 0.089408)
		(layer "In4.Cu")
		(net "XDP_CPU_TMS")
	)
	(segment
		(start 333.922116 -107.501436)
		(end 334.788002 -107.501436)
		(width 0.089408)
		(layer "In4.Cu")
		(net "XDP_CPU_TMS")
	)
	(segment
		(start 332.536546 -106.115866)
		(end 333.922116 -107.501436)
		(width 0.089408)
		(layer "In4.Cu")
		(net "XDP_CPU_TMS")
	)
	(segment
		(start 420.167308 -145.484088)
		(end 420.391082 -145.707862)
		(width 0.089408)
		(layer "In4.Cu")
		(net "XDP_CPU_TMS")
	)
	(segment
		(start 343.649046 -138.003534)
		(end 347.533468 -138.003534)
		(width 0.089408)
		(layer "In4.Cu")
		(net "XDP_CPU_TMS")
	)
	(segment
		(start 332.536292 -95.618808)
		(end 332.536292 -96.610424)
		(width 0.089408)
		(layer "In4.Cu")
		(net "XDP_CPU_TMS")
	)
	(segment
		(start 340.785704 -113.499138)
		(end 340.785704 -114.88547)
		(width 0.089408)
		(layer "In4.Cu")
		(net "XDP_CPU_TMS")
	)
	(segment
		(start 406.585674 -149.0726)
		(end 408.389836 -149.0726)
		(width 0.089408)
		(layer "In4.Cu")
		(net "XDP_CPU_TMS")
	)
	(segment
		(start 457.942696 -149.0472)
		(end 460.0194 -149.0472)
		(width 0.089408)
		(layer "In4.Cu")
		(net "XDP_CPU_TMS")
	)
	(segment
		(start 367.142014 -142.178786)
		(end 371.017292 -142.178786)
		(width 0.089408)
		(layer "In4.Cu")
		(net "XDP_CPU_TMS")
	)
	(segment
		(start 412.020258 -146.213576)
		(end 418.279072 -146.213576)
		(width 0.089408)
		(layer "In4.Cu")
		(net "XDP_CPU_TMS")
	)
	(segment
		(start 337.51012 -111.80572)
		(end 339.092286 -111.80572)
		(width 0.089408)
		(layer "In4.Cu")
		(net "XDP_CPU_TMS")
	)
	(segment
		(start 334.788002 -107.501436)
		(end 335.7626 -108.476034)
		(width 0.089408)
		(layer "In4.Cu")
		(net "XDP_CPU_TMS")
	)
	(segment
		(start 328.129392 -36.3728)
		(end 328.129392 -32.763206)
		(width 0.089408)
		(layer "In9.Cu")
		(net "XDP_CPU_TMS")
	)
	(segment
		(start 261.634478 -11.3157)
		(end 260.23316 -9.914382)
		(width 0.089408)
		(layer "In9.Cu")
		(net "XDP_CPU_TMS")
	)
	(segment
		(start 324.302374 -15.348966)
		(end 323.65442 -14.701012)
		(width 0.089408)
		(layer "In9.Cu")
		(net "XDP_CPU_TMS")
	)
	(segment
		(start 183.771286 -18.580608)
		(end 180.85435 -18.580608)
		(width 0.089408)
		(layer "In9.Cu")
		(net "XDP_CPU_TMS")
	)
	(segment
		(start 264.803636 -10.997692)
		(end 262.65886 -10.997692)
		(width 0.089408)
		(layer "In9.Cu")
		(net "XDP_CPU_TMS")
	)
	(segment
		(start 327.362566 -45.820584)
		(end 328.802492 -44.380658)
		(width 0.089408)
		(layer "In9.Cu")
		(net "XDP_CPU_TMS")
	)
	(segment
		(start 328.802492 -44.380658)
		(end 328.802492 -41.568624)
		(width 0.089408)
		(layer "In9.Cu")
		(net "XDP_CPU_TMS")
	)
	(segment
		(start 186.954668 -13.285978)
		(end 186.954922 -13.286232)
		(width 0.089408)
		(layer "In9.Cu")
		(net "XDP_CPU_TMS")
	)
	(segment
		(start 180.85435 -18.580608)
		(end 178.478942 -20.956016)
		(width 0.089408)
		(layer "In9.Cu")
		(net "XDP_CPU_TMS")
	)
	(segment
		(start 328.478896 -41.245028)
		(end 328.478896 -39.99484)
		(width 0.089408)
		(layer "In9.Cu")
		(net "XDP_CPU_TMS")
	)
	(segment
		(start 324.322186 -55.230268)
		(end 325.875396 -53.677058)
		(width 0.089408)
		(layer "In9.Cu")
		(net "XDP_CPU_TMS")
	)
	(segment
		(start 349.876364 -81.166716)
		(end 349.876364 -73.875392)
		(width 0.089408)
		(layer "In9.Cu")
		(net "XDP_CPU_TMS")
	)
	(segment
		(start 325.1073 -58.251852)
		(end 324.322186 -57.466738)
		(width 0.089408)
		(layer "In9.Cu")
		(net "XDP_CPU_TMS")
	)
	(segment
		(start 353.958652 -69.793104)
		(end 353.958652 -67.020694)
		(width 0.089408)
		(layer "In9.Cu")
		(net "XDP_CPU_TMS")
	)
	(segment
		(start 353.958398 -64.956436)
		(end 354.457508 -64.457326)
		(width 0.089408)
		(layer "In9.Cu")
		(net "XDP_CPU_TMS")
	)
	(segment
		(start 186.954922 -13.286232)
		(end 186.954922 -13.501878)
		(width 0.089408)
		(layer "In9.Cu")
		(net "XDP_CPU_TMS")
	)
	(segment
		(start 327.700386 -32.3342)
		(end 327.700386 -26.680414)
		(width 0.089408)
		(layer "In9.Cu")
		(net "XDP_CPU_TMS")
	)
	(segment
		(start 186.954922 -13.501878)
		(end 186.954668 -13.502132)
		(width 0.089408)
		(layer "In9.Cu")
		(net "XDP_CPU_TMS")
	)
	(segment
		(start 262.65886 -10.997692)
		(end 262.340852 -11.3157)
		(width 0.089408)
		(layer "In9.Cu")
		(net "XDP_CPU_TMS")
	)
	(segment
		(start 326.558656 -45.820584)
		(end 327.362566 -45.820584)
		(width 0.089408)
		(layer "In9.Cu")
		(net "XDP_CPU_TMS")
	)
	(segment
		(start 262.340852 -11.3157)
		(end 261.634478 -11.3157)
		(width 0.089408)
		(layer "In9.Cu")
		(net "XDP_CPU_TMS")
	)
	(segment
		(start 351.831148 -81.854548)
		(end 350.564196 -81.854548)
		(width 0.089408)
		(layer "In9.Cu")
		(net "XDP_CPU_TMS")
	)
	(segment
		(start 353.958652 -67.020694)
		(end 353.958398 -67.02044)
		(width 0.089408)
		(layer "In9.Cu")
		(net "XDP_CPU_TMS")
	)
	(segment
		(start 353.6696 -83.693)
		(end 351.831148 -81.854548)
		(width 0.089408)
		(layer "In9.Cu")
		(net "XDP_CPU_TMS")
	)
	(segment
		(start 353.6696 -84.0232)
		(end 353.6696 -83.693)
		(width 0.089408)
		(layer "In9.Cu")
		(net "XDP_CPU_TMS")
	)
	(segment
		(start 322.498212 -10.817606)
		(end 264.983722 -10.817606)
		(width 0.089408)
		(layer "In9.Cu")
		(net "XDP_CPU_TMS")
	)
	(segment
		(start 323.65442 -14.701012)
		(end 323.65442 -11.973814)
		(width 0.089408)
		(layer "In9.Cu")
		(net "XDP_CPU_TMS")
	)
	(segment
		(start 328.129392 -32.763206)
		(end 327.700386 -32.3342)
		(width 0.089408)
		(layer "In9.Cu")
		(net "XDP_CPU_TMS")
	)
	(segment
		(start 356.1334 -58.9788)
		(end 355.2444 -58.0898)
		(width 0.089408)
		(layer "In9.Cu")
		(net "XDP_CPU_TMS")
	)
	(segment
		(start 184.663334 -17.68856)
		(end 183.771286 -18.580608)
		(width 0.089408)
		(layer "In9.Cu")
		(net "XDP_CPU_TMS")
	)
	(segment
		(start 349.876364 -73.875392)
		(end 353.958652 -69.793104)
		(width 0.089408)
		(layer "In9.Cu")
		(net "XDP_CPU_TMS")
	)
	(segment
		(start 186.954668 -13.502132)
		(end 186.954668 -13.54328)
		(width 0.089408)
		(layer "In9.Cu")
		(net "XDP_CPU_TMS")
	)
	(segment
		(start 354.457508 -64.457326)
		(end 355.740716 -63.17361)
		(width 0.089408)
		(layer "In9.Cu")
		(net "XDP_CPU_TMS")
	)
	(segment
		(start 192.86728 -11.19632)
		(end 188.318394 -11.19632)
		(width 0.089408)
		(layer "In9.Cu")
		(net "XDP_CPU_TMS")
	)
	(segment
		(start 323.65442 -11.973814)
		(end 322.498212 -10.817606)
		(width 0.089408)
		(layer "In9.Cu")
		(net "XDP_CPU_TMS")
	)
	(segment
		(start 186.954668 -13.54328)
		(end 184.663334 -15.834614)
		(width 0.089408)
		(layer "In9.Cu")
		(net "XDP_CPU_TMS")
	)
	(segment
		(start 184.663334 -15.834614)
		(end 184.663334 -17.68856)
		(width 0.089408)
		(layer "In9.Cu")
		(net "XDP_CPU_TMS")
	)
	(segment
		(start 355.740716 -63.17361)
		(end 355.740716 -62.192154)
		(width 0.089408)
		(layer "In9.Cu")
		(net "XDP_CPU_TMS")
	)
	(segment
		(start 264.983722 -10.817606)
		(end 264.803636 -10.997692)
		(width 0.089408)
		(layer "In9.Cu")
		(net "XDP_CPU_TMS")
	)
	(segment
		(start 178.478942 -20.956016)
		(end 177.062384 -20.956016)
		(width 0.089408)
		(layer "In9.Cu")
		(net "XDP_CPU_TMS")
	)
	(segment
		(start 324.473316 -48.623982)
		(end 324.473316 -47.905924)
		(width 0.089408)
		(layer "In9.Cu")
		(net "XDP_CPU_TMS")
	)
	(segment
		(start 353.958398 -67.02044)
		(end 353.958398 -64.956436)
		(width 0.089408)
		(layer "In9.Cu")
		(net "XDP_CPU_TMS")
	)
	(segment
		(start 177.062384 -20.956016)
		(end 176.4284 -21.59)
		(width 0.089408)
		(layer "In9.Cu")
		(net "XDP_CPU_TMS")
	)
	(segment
		(start 355.740716 -62.192154)
		(end 356.1334 -61.79947)
		(width 0.089408)
		(layer "In9.Cu")
		(net "XDP_CPU_TMS")
	)
	(segment
		(start 324.302374 -23.282402)
		(end 324.302374 -15.348966)
		(width 0.089408)
		(layer "In9.Cu")
		(net "XDP_CPU_TMS")
	)
	(segment
		(start 325.875396 -50.032666)
		(end 325.758556 -49.915826)
		(width 0.089408)
		(layer "In9.Cu")
		(net "XDP_CPU_TMS")
	)
	(segment
		(start 325.758556 -49.909222)
		(end 324.473316 -48.623982)
		(width 0.089408)
		(layer "In9.Cu")
		(net "XDP_CPU_TMS")
	)
	(segment
		(start 327.700386 -36.801806)
		(end 328.129392 -36.3728)
		(width 0.089408)
		(layer "In9.Cu")
		(net "XDP_CPU_TMS")
	)
	(segment
		(start 194.149218 -9.914382)
		(end 192.86728 -11.19632)
		(width 0.089408)
		(layer "In9.Cu")
		(net "XDP_CPU_TMS")
	)
	(segment
		(start 328.478896 -39.99484)
		(end 327.700386 -39.21633)
		(width 0.089408)
		(layer "In9.Cu")
		(net "XDP_CPU_TMS")
	)
	(segment
		(start 356.1334 -61.79947)
		(end 356.1334 -58.9788)
		(width 0.089408)
		(layer "In9.Cu")
		(net "XDP_CPU_TMS")
	)
	(segment
		(start 186.954668 -12.560046)
		(end 186.954668 -13.285978)
		(width 0.089408)
		(layer "In9.Cu")
		(net "XDP_CPU_TMS")
	)
	(segment
		(start 324.473316 -47.905924)
		(end 326.558656 -45.820584)
		(width 0.089408)
		(layer "In9.Cu")
		(net "XDP_CPU_TMS")
	)
	(segment
		(start 324.322186 -57.466738)
		(end 324.322186 -55.230268)
		(width 0.089408)
		(layer "In9.Cu")
		(net "XDP_CPU_TMS")
	)
	(segment
		(start 350.564196 -81.854548)
		(end 349.876364 -81.166716)
		(width 0.089408)
		(layer "In9.Cu")
		(net "XDP_CPU_TMS")
	)
	(segment
		(start 325.758556 -49.915826)
		(end 325.758556 -49.909222)
		(width 0.089408)
		(layer "In9.Cu")
		(net "XDP_CPU_TMS")
	)
	(segment
		(start 260.23316 -9.914382)
		(end 194.149218 -9.914382)
		(width 0.089408)
		(layer "In9.Cu")
		(net "XDP_CPU_TMS")
	)
	(segment
		(start 188.318394 -11.19632)
		(end 186.954668 -12.560046)
		(width 0.089408)
		(layer "In9.Cu")
		(net "XDP_CPU_TMS")
	)
	(segment
		(start 327.700386 -39.21633)
		(end 327.700386 -36.801806)
		(width 0.089408)
		(layer "In9.Cu")
		(net "XDP_CPU_TMS")
	)
	(segment
		(start 325.875396 -53.677058)
		(end 325.875396 -50.032666)
		(width 0.089408)
		(layer "In9.Cu")
		(net "XDP_CPU_TMS")
	)
	(segment
		(start 328.802492 -41.568624)
		(end 328.478896 -41.245028)
		(width 0.089408)
		(layer "In9.Cu")
		(net "XDP_CPU_TMS")
	)
	(segment
		(start 327.700386 -26.680414)
		(end 324.302374 -23.282402)
		(width 0.089408)
		(layer "In9.Cu")
		(net "XDP_CPU_TMS")
	)
	(segment
		(start 139.813792 -52.642262)
		(end 139.444476 -53.011578)
		(width 0.089408)
		(layer "In11.Cu")
		(net "XDP_CPU_TMS")
	)
	(segment
		(start 328.163682 -58.446416)
		(end 327.969118 -58.251852)
		(width 0.089408)
		(layer "In11.Cu")
		(net "XDP_CPU_TMS")
	)
	(segment
		(start 322.96354 -58.251852)
		(end 319.394332 -61.82106)
		(width 0.089408)
		(layer "In11.Cu")
		(net "XDP_CPU_TMS")
	)
	(segment
		(start 302.692816 -59.276234)
		(end 302.649636 -59.276234)
		(width 0.0889)
		(layer "In11.Cu")
		(net "XDP_CPU_TMS")
	)
	(segment
		(start 299.258736 -59.276234)
		(end 299.215556 -59.276234)
		(width 0.0889)
		(layer "In11.Cu")
		(net "XDP_CPU_TMS")
	)
	(segment
		(start 137.82548 -54.3814)
		(end 137.4394 -54.3814)
		(width 0.089408)
		(layer "In11.Cu")
		(net "XDP_CPU_TMS")
	)
	(segment
		(start 167.730424 -25.924764)
		(end 159.665162 -29.265372)
		(width 0.089408)
		(layer "In11.Cu")
		(net "XDP_CPU_TMS")
	)
	(segment
		(start 170.020996 -23.634192)
		(end 167.730424 -25.924764)
		(width 0.089408)
		(layer "In11.Cu")
		(net "XDP_CPU_TMS")
	)
	(segment
		(start 132.1054 -57.7088)
		(end 132.1054 -59.563)
		(width 0.089408)
		(layer "In11.Cu")
		(net "XDP_CPU_TMS")
	)
	(segment
		(start 327.969118 -58.251852)
		(end 325.1073 -58.251852)
		(width 0.089408)
		(layer "In11.Cu")
		(net "XDP_CPU_TMS")
	)
	(segment
		(start 131.661408 -60.006992)
		(end 131.661408 -60.362338)
		(width 0.089408)
		(layer "In11.Cu")
		(net "XDP_CPU_TMS")
	)
	(segment
		(start 170.715432 -23.34641)
		(end 170.020996 -23.634192)
		(width 0.089408)
		(layer "In11.Cu")
		(net "XDP_CPU_TMS")
	)
	(segment
		(start 132.1054 -59.563)
		(end 131.661408 -60.006992)
		(width 0.089408)
		(layer "In11.Cu")
		(net "XDP_CPU_TMS")
	)
	(segment
		(start 159.665162 -29.265372)
		(end 158.237428 -30.693106)
		(width 0.089408)
		(layer "In11.Cu")
		(net "XDP_CPU_TMS")
	)
	(segment
		(start 355.155754 -58.178446)
		(end 354.022152 -58.178446)
		(width 0.089408)
		(layer "In11.Cu")
		(net "XDP_CPU_TMS")
	)
	(segment
		(start 136.0424 -55.4228)
		(end 135.7376 -55.4228)
		(width 0.089408)
		(layer "In11.Cu")
		(net "XDP_CPU_TMS")
	)
	(segment
		(start 297.535092 -60.266834)
		(end 297.502326 -60.266834)
		(width 0.0889)
		(layer "In11.Cu")
		(net "XDP_CPU_TMS")
	)
	(segment
		(start 329.874118 -58.446416)
		(end 328.163682 -58.446416)
		(width 0.089408)
		(layer "In11.Cu")
		(net "XDP_CPU_TMS")
	)
	(segment
		(start 298.389802 -59.771534)
		(end 298.365672 -59.771534)
		(width 0.0889)
		(layer "In11.Cu")
		(net "XDP_CPU_TMS")
	)
	(segment
		(start 354.022152 -58.178446)
		(end 353.586542 -57.742582)
		(width 0.089408)
		(layer "In11.Cu")
		(net "XDP_CPU_TMS")
	)
	(segment
		(start 355.2444 -58.0898)
		(end 355.155754 -58.178446)
		(width 0.089408)
		(layer "In11.Cu")
		(net "XDP_CPU_TMS")
	)
	(segment
		(start 136.6266 -54.8386)
		(end 136.0424 -55.4228)
		(width 0.089408)
		(layer "In11.Cu")
		(net "XDP_CPU_TMS")
	)
	(segment
		(start 306.126896 -59.276234)
		(end 306.083716 -59.276234)
		(width 0.0889)
		(layer "In11.Cu")
		(net "XDP_CPU_TMS")
	)
	(segment
		(start 135.7376 -55.4228)
		(end 135.2804 -55.88)
		(width 0.089408)
		(layer "In11.Cu")
		(net "XDP_CPU_TMS")
	)
	(segment
		(start 353.586542 -57.742582)
		(end 330.577952 -57.742582)
		(width 0.089408)
		(layer "In11.Cu")
		(net "XDP_CPU_TMS")
	)
	(segment
		(start 139.849606 -52.642262)
		(end 139.813792 -52.642262)
		(width 0.089408)
		(layer "In11.Cu")
		(net "XDP_CPU_TMS")
	)
	(segment
		(start 176.4284 -21.59)
		(end 176.002188 -22.016212)
		(width 0.089408)
		(layer "In11.Cu")
		(net "XDP_CPU_TMS")
	)
	(segment
		(start 296.954702 -60.531248)
		(end 296.66184 -60.362338)
		(width 0.0889)
		(layer "In11.Cu")
		(net "XDP_CPU_TMS")
	)
	(segment
		(start 133.6294 -56.8706)
		(end 133.2484 -56.8706)
		(width 0.089408)
		(layer "In11.Cu")
		(net "XDP_CPU_TMS")
	)
	(segment
		(start 138.23188 -53.975)
		(end 137.82548 -54.3814)
		(width 0.089408)
		(layer "In11.Cu")
		(net "XDP_CPU_TMS")
	)
	(segment
		(start 176.002188 -22.016212)
		(end 172.04563 -22.016212)
		(width 0.089408)
		(layer "In11.Cu")
		(net "XDP_CPU_TMS")
	)
	(segment
		(start 307.816504 -59.626754)
		(end 307.671724 -59.771534)
		(width 0.0889)
		(layer "In11.Cu")
		(net "XDP_CPU_TMS")
	)
	(segment
		(start 138.684 -53.975)
		(end 138.23188 -53.975)
		(width 0.089408)
		(layer "In11.Cu")
		(net "XDP_CPU_TMS")
	)
	(segment
		(start 330.577952 -57.742582)
		(end 329.874118 -58.446416)
		(width 0.089408)
		(layer "In11.Cu")
		(net "XDP_CPU_TMS")
	)
	(segment
		(start 132.3848 -57.4294)
		(end 132.1054 -57.7088)
		(width 0.089408)
		(layer "In11.Cu")
		(net "XDP_CPU_TMS")
	)
	(segment
		(start 300.975776 -59.276234)
		(end 300.932596 -59.276234)
		(width 0.0889)
		(layer "In11.Cu")
		(net "XDP_CPU_TMS")
	)
	(segment
		(start 140.167868 -52.324)
		(end 139.849606 -52.642262)
		(width 0.089408)
		(layer "In11.Cu")
		(net "XDP_CPU_TMS")
	)
	(segment
		(start 132.6896 -57.4294)
		(end 132.3848 -57.4294)
		(width 0.089408)
		(layer "In11.Cu")
		(net "XDP_CPU_TMS")
	)
	(segment
		(start 297.04411 -60.507118)
		(end 296.954702 -60.531248)
		(width 0.0889)
		(layer "In11.Cu")
		(net "XDP_CPU_TMS")
	)
	(segment
		(start 304.409856 -59.276234)
		(end 304.366676 -59.276234)
		(width 0.0889)
		(layer "In11.Cu")
		(net "XDP_CPU_TMS")
	)
	(segment
		(start 307.671724 -59.771534)
		(end 306.95265 -59.771534)
		(width 0.0889)
		(layer "In11.Cu")
		(net "XDP_CPU_TMS")
	)
	(segment
		(start 158.237428 -30.693106)
		(end 155.71851 -36.773612)
		(width 0.089408)
		(layer "In11.Cu")
		(net "XDP_CPU_TMS")
	)
	(segment
		(start 172.04563 -22.016212)
		(end 170.715432 -23.34641)
		(width 0.089408)
		(layer "In11.Cu")
		(net "XDP_CPU_TMS")
	)
	(segment
		(start 314.32246 -61.82106)
		(end 311.889394 -59.387994)
		(width 0.089408)
		(layer "In11.Cu")
		(net "XDP_CPU_TMS")
	)
	(segment
		(start 325.1073 -58.251852)
		(end 322.96354 -58.251852)
		(width 0.089408)
		(layer "In11.Cu")
		(net "XDP_CPU_TMS")
	)
	(segment
		(start 136.9822 -54.8386)
		(end 136.6266 -54.8386)
		(width 0.089408)
		(layer "In11.Cu")
		(net "XDP_CPU_TMS")
	)
	(segment
		(start 134.3406 -56.4388)
		(end 134.0612 -56.4388)
		(width 0.089408)
		(layer "In11.Cu")
		(net "XDP_CPU_TMS")
	)
	(segment
		(start 135.2804 -55.88)
		(end 134.8994 -55.88)
		(width 0.089408)
		(layer "In11.Cu")
		(net "XDP_CPU_TMS")
	)
	(segment
		(start 134.8994 -55.88)
		(end 134.3406 -56.4388)
		(width 0.089408)
		(layer "In11.Cu")
		(net "XDP_CPU_TMS")
	)
	(segment
		(start 137.4394 -54.3814)
		(end 136.9822 -54.8386)
		(width 0.089408)
		(layer "In11.Cu")
		(net "XDP_CPU_TMS")
	)
	(segment
		(start 301.823882 -59.771534)
		(end 301.80153 -59.771534)
		(width 0.0889)
		(layer "In11.Cu")
		(net "XDP_CPU_TMS")
	)
	(segment
		(start 319.394332 -61.82106)
		(end 314.32246 -61.82106)
		(width 0.089408)
		(layer "In11.Cu")
		(net "XDP_CPU_TMS")
	)
	(segment
		(start 139.444476 -53.011578)
		(end 139.300966 -53.358034)
		(width 0.089408)
		(layer "In11.Cu")
		(net "XDP_CPU_TMS")
	)
	(segment
		(start 308.411626 -59.626754)
		(end 307.816504 -59.626754)
		(width 0.0889)
		(layer "In11.Cu")
		(net "XDP_CPU_TMS")
	)
	(segment
		(start 133.2484 -56.8706)
		(end 132.6896 -57.4294)
		(width 0.089408)
		(layer "In11.Cu")
		(net "XDP_CPU_TMS")
	)
	(segment
		(start 311.889394 -59.387994)
		(end 308.650386 -59.387994)
		(width 0.0889)
		(layer "In11.Cu")
		(net "XDP_CPU_TMS")
	)
	(segment
		(start 308.650386 -59.387994)
		(end 308.411626 -59.626754)
		(width 0.0889)
		(layer "In11.Cu")
		(net "XDP_CPU_TMS")
	)
	(segment
		(start 139.300966 -53.358034)
		(end 138.684 -53.975)
		(width 0.089408)
		(layer "In11.Cu")
		(net "XDP_CPU_TMS")
	)
	(segment
		(start 155.71851 -36.773612)
		(end 140.167868 -52.324)
		(width 0.089408)
		(layer "In11.Cu")
		(net "XDP_CPU_TMS")
	)
	(segment
		(start 134.0612 -56.4388)
		(end 133.6294 -56.8706)
		(width 0.089408)
		(layer "In11.Cu")
		(net "XDP_CPU_TMS")
	)
	(arc
		(start 298.365672 -59.771534)
		(mid 298.077527 -59.853853)
		(end 297.866816 -60.066936)
		(width 0.0889)
		(layer "In11.Cu")
		(net "XDP_CPU_TMS")
	)
	(arc
		(start 304.366676 -59.276234)
		(mid 304.083459 -59.360515)
		(end 303.876456 -59.571382)
		(width 0.0889)
		(layer "In11.Cu")
		(net "XDP_CPU_TMS")
	)
	(arc
		(start 306.95265 -59.771534)
		(mid 306.7588 -59.715184)
		(end 306.617116 -59.571382)
		(width 0.0889)
		(layer "In11.Cu")
		(net "XDP_CPU_TMS")
	)
	(arc
		(start 298.725336 -59.571382)
		(mid 298.583653 -59.715186)
		(end 298.389802 -59.771534)
		(width 0.0889)
		(layer "In11.Cu")
		(net "XDP_CPU_TMS")
	)
	(arc
		(start 304.900076 -59.571382)
		(mid 304.693072 -59.360518)
		(end 304.409856 -59.276234)
		(width 0.0889)
		(layer "In11.Cu")
		(net "XDP_CPU_TMS")
	)
	(arc
		(start 306.617116 -59.571382)
		(mid 306.410112 -59.360518)
		(end 306.126896 -59.276234)
		(width 0.0889)
		(layer "In11.Cu")
		(net "XDP_CPU_TMS")
	)
	(arc
		(start 299.215556 -59.276234)
		(mid 298.932339 -59.360515)
		(end 298.725336 -59.571382)
		(width 0.0889)
		(layer "In11.Cu")
		(net "XDP_CPU_TMS")
	)
	(arc
		(start 299.748956 -59.571382)
		(mid 299.541952 -59.360518)
		(end 299.258736 -59.276234)
		(width 0.0889)
		(layer "In11.Cu")
		(net "XDP_CPU_TMS")
	)
	(arc
		(start 306.083716 -59.276234)
		(mid 305.800499 -59.360515)
		(end 305.593496 -59.571382)
		(width 0.0889)
		(layer "In11.Cu")
		(net "XDP_CPU_TMS")
	)
	(arc
		(start 305.593496 -59.571382)
		(mid 305.246786 -59.771693)
		(end 304.900076 -59.571382)
		(width 0.0889)
		(layer "In11.Cu")
		(net "XDP_CPU_TMS")
	)
	(arc
		(start 300.442376 -59.571382)
		(mid 300.095666 -59.771693)
		(end 299.748956 -59.571382)
		(width 0.0889)
		(layer "In11.Cu")
		(net "XDP_CPU_TMS")
	)
	(arc
		(start 303.876456 -59.571382)
		(mid 303.529746 -59.771693)
		(end 303.183036 -59.571382)
		(width 0.0889)
		(layer "In11.Cu")
		(net "XDP_CPU_TMS")
	)
	(arc
		(start 303.183036 -59.571382)
		(mid 302.976032 -59.360518)
		(end 302.692816 -59.276234)
		(width 0.0889)
		(layer "In11.Cu")
		(net "XDP_CPU_TMS")
	)
	(arc
		(start 302.159416 -59.571382)
		(mid 302.017733 -59.715186)
		(end 301.823882 -59.771534)
		(width 0.0889)
		(layer "In11.Cu")
		(net "XDP_CPU_TMS")
	)
	(arc
		(start 301.80153 -59.771534)
		(mid 301.60768 -59.715184)
		(end 301.465996 -59.571382)
		(width 0.0889)
		(layer "In11.Cu")
		(net "XDP_CPU_TMS")
	)
	(arc
		(start 297.866816 -60.066936)
		(mid 297.726737 -60.209672)
		(end 297.535092 -60.266834)
		(width 0.0889)
		(layer "In11.Cu")
		(net "XDP_CPU_TMS")
	)
	(arc
		(start 297.502326 -60.266834)
		(mid 297.245504 -60.334135)
		(end 297.04411 -60.507118)
		(width 0.0889)
		(layer "In11.Cu")
		(net "XDP_CPU_TMS")
	)
	(arc
		(start 302.649636 -59.276234)
		(mid 302.366419 -59.360515)
		(end 302.159416 -59.571382)
		(width 0.0889)
		(layer "In11.Cu")
		(net "XDP_CPU_TMS")
	)
	(arc
		(start 300.932596 -59.276234)
		(mid 300.649379 -59.360515)
		(end 300.442376 -59.571382)
		(width 0.0889)
		(layer "In11.Cu")
		(net "XDP_CPU_TMS")
	)
	(arc
		(start 301.465996 -59.571382)
		(mid 301.258992 -59.360518)
		(end 300.975776 -59.276234)
		(width 0.0889)
		(layer "In11.Cu")
		(net "XDP_CPU_TMS")
	)
	(via
		(at 455.58964 -142.38478)
		(size 0.508)
		(drill 0.254)
		(layers "F.Cu" "B.Cu")
		(net "XDP_CPU_TDO")
	)
	(via
		(at 456.916282 -130.971544)
		(size 0.508)
		(drill 0.254)
		(layers "F.Cu" "B.Cu")
		(net "XDP_CPU_TDO")
	)
	(via
		(at 455.6506 -139.7254)
		(size 0.508)
		(drill 0.254)
		(layers "F.Cu" "B.Cu")
		(net "XDP_CPU_TDO")
	)
	(via
		(at 459.6384 -148.0312)
		(size 0.508)
		(drill 0.254)
		(layers "F.Cu" "B.Cu")
		(net "XDP_CPU_TDO")
	)
	(segment
		(start 457.703428 -130.184398)
		(end 456.916282 -130.971544)
		(width 0.10795)
		(layer "B.Cu")
		(net "XDP_CPU_TDO")
	)
	(segment
		(start 459.110334 -148.559266)
		(end 459.110334 -149.326346)
		(width 0.10795)
		(layer "B.Cu")
		(net "XDP_CPU_TDO")
	)
	(segment
		(start 459.6384 -148.0312)
		(end 459.110334 -148.559266)
		(width 0.10795)
		(layer "B.Cu")
		(net "XDP_CPU_TDO")
	)
	(segment
		(start 457.703428 -129.6924)
		(end 457.703428 -130.184398)
		(width 0.10795)
		(layer "B.Cu")
		(net "XDP_CPU_TDO")
	)
	(segment
		(start 455.58964 -142.38478)
		(end 456.1586 -141.81582)
		(width 0.089408)
		(layer "In2.Cu")
		(net "XDP_CPU_TDO")
	)
	(segment
		(start 456.1586 -141.81582)
		(end 456.1586 -140.2334)
		(width 0.089408)
		(layer "In2.Cu")
		(net "XDP_CPU_TDO")
	)
	(segment
		(start 456.1586 -140.2334)
		(end 455.6506 -139.7254)
		(width 0.089408)
		(layer "In2.Cu")
		(net "XDP_CPU_TDO")
	)
	(segment
		(start 455.561954 -138.727942)
		(end 455.168 -138.333988)
		(width 0.089408)
		(layer "In4.Cu")
		(net "XDP_CPU_TDO")
	)
	(segment
		(start 455.645012 -131.5212)
		(end 455.645012 -130.2512)
		(width 0.089408)
		(layer "In4.Cu")
		(net "XDP_CPU_TDO")
	)
	(segment
		(start 455.168 -131.998212)
		(end 455.645012 -131.5212)
		(width 0.089408)
		(layer "In4.Cu")
		(net "XDP_CPU_TDO")
	)
	(segment
		(start 455.6506 -139.7254)
		(end 455.561954 -139.636754)
		(width 0.089408)
		(layer "In4.Cu")
		(net "XDP_CPU_TDO")
	)
	(segment
		(start 455.645012 -130.2512)
		(end 456.026012 -129.8702)
		(width 0.089408)
		(layer "In4.Cu")
		(net "XDP_CPU_TDO")
	)
	(segment
		(start 455.168 -138.333988)
		(end 455.168 -131.998212)
		(width 0.089408)
		(layer "In4.Cu")
		(net "XDP_CPU_TDO")
	)
	(segment
		(start 456.916282 -130.221482)
		(end 456.916282 -130.971544)
		(width 0.089408)
		(layer "In4.Cu")
		(net "XDP_CPU_TDO")
	)
	(segment
		(start 456.565 -129.8702)
		(end 456.916282 -130.221482)
		(width 0.089408)
		(layer "In4.Cu")
		(net "XDP_CPU_TDO")
	)
	(segment
		(start 456.026012 -129.8702)
		(end 456.565 -129.8702)
		(width 0.089408)
		(layer "In4.Cu")
		(net "XDP_CPU_TDO")
	)
	(segment
		(start 455.561954 -139.636754)
		(end 455.561954 -138.727942)
		(width 0.089408)
		(layer "In4.Cu")
		(net "XDP_CPU_TDO")
	)
	(segment
		(start 457.49718 -145.88998)
		(end 457.49718 -144.29232)
		(width 0.089408)
		(layer "In9.Cu")
		(net "XDP_CPU_TDO")
	)
	(segment
		(start 457.49718 -144.29232)
		(end 455.58964 -142.38478)
		(width 0.089408)
		(layer "In9.Cu")
		(net "XDP_CPU_TDO")
	)
	(segment
		(start 459.6384 -148.0312)
		(end 457.49718 -145.88998)
		(width 0.089408)
		(layer "In9.Cu")
		(net "XDP_CPU_TDO")
	)
	(segment
		(start 296.66184 -62.343538)
		(end 296.09034 -62.343538)
		(width 0.1016)
		(layer "F.Cu")
		(net "XDP_CPU_TDI")
	)
	(via
		(at 296.66184 -62.343538)
		(size 0.508)
		(drill 0.254)
		(layers "F.Cu" "B.Cu")
		(net "XDP_CPU_TDI")
	)
	(via
		(at 457.289408 -151.409654)
		(size 0.508)
		(drill 0.254)
		(layers "F.Cu" "B.Cu")
		(net "XDP_CPU_TDI")
	)
	(via
		(at 339.429344 -84.79155)
		(size 0.508)
		(drill 0.254)
		(layers "F.Cu" "B.Cu")
		(net "XDP_CPU_TDI")
	)
	(via
		(at 355.616764 -60.013596)
		(size 0.508)
		(drill 0.254)
		(layers "F.Cu" "B.Cu")
		(net "XDP_CPU_TDI")
	)
	(segment
		(start 296.66184 -62.557152)
		(end 295.97223 -63.246762)
		(width 0.10795)
		(layer "B.Cu")
		(net "XDP_CPU_TDI")
	)
	(segment
		(start 457.289408 -151.409654)
		(end 457.822808 -150.876254)
		(width 0.10795)
		(layer "B.Cu")
		(net "XDP_CPU_TDI")
	)
	(segment
		(start 294.716962 -63.886334)
		(end 294.075104 -64.528192)
		(width 0.10795)
		(layer "B.Cu")
		(net "XDP_CPU_TDI")
	)
	(segment
		(start 294.075104 -64.528192)
		(end 293.881302 -64.528192)
		(width 0.10795)
		(layer "B.Cu")
		(net "XDP_CPU_TDI")
	)
	(segment
		(start 295.169082 -63.886334)
		(end 294.716962 -63.886334)
		(width 0.10795)
		(layer "B.Cu")
		(net "XDP_CPU_TDI")
	)
	(segment
		(start 295.97223 -63.246762)
		(end 295.808654 -63.246762)
		(width 0.10795)
		(layer "B.Cu")
		(net "XDP_CPU_TDI")
	)
	(segment
		(start 296.66184 -62.343538)
		(end 296.66184 -62.557152)
		(width 0.10795)
		(layer "B.Cu")
		(net "XDP_CPU_TDI")
	)
	(segment
		(start 457.822808 -150.876254)
		(end 458.3303 -150.876254)
		(width 0.10795)
		(layer "B.Cu")
		(net "XDP_CPU_TDI")
	)
	(segment
		(start 295.808654 -63.246762)
		(end 295.169082 -63.886334)
		(width 0.10795)
		(layer "B.Cu")
		(net "XDP_CPU_TDI")
	)
	(segment
		(start 362.834936 -144.3101)
		(end 363.09808 -144.3101)
		(width 0.089408)
		(layer "In4.Cu")
		(net "XDP_CPU_TDI")
	)
	(segment
		(start 363.10824 -144.32026)
		(end 371.86108 -144.32026)
		(width 0.089408)
		(layer "In4.Cu")
		(net "XDP_CPU_TDI")
	)
	(segment
		(start 336.976212 -87.612474)
		(end 336.572098 -87.612474)
		(width 0.089408)
		(layer "In4.Cu")
		(net "XDP_CPU_TDI")
	)
	(segment
		(start 337.636358 -86.952328)
		(end 336.976212 -87.612474)
		(width 0.089408)
		(layer "In4.Cu")
		(net "XDP_CPU_TDI")
	)
	(segment
		(start 431.29708 -156.232606)
		(end 431.29708 -155.1686)
		(width 0.089408)
		(layer "In4.Cu")
		(net "XDP_CPU_TDI")
	)
	(segment
		(start 392.522202 -147.32762)
		(end 396.279116 -147.32762)
		(width 0.089408)
		(layer "In4.Cu")
		(net "XDP_CPU_TDI")
	)
	(segment
		(start 409.59532 -154.422348)
		(end 410.9974 -155.824428)
		(width 0.089408)
		(layer "In4.Cu")
		(net "XDP_CPU_TDI")
	)
	(segment
		(start 360.910378 -142.717266)
		(end 361.242102 -142.717266)
		(width 0.089408)
		(layer "In4.Cu")
		(net "XDP_CPU_TDI")
	)
	(segment
		(start 396.279116 -147.32762)
		(end 397.118586 -148.16709)
		(width 0.089408)
		(layer "In4.Cu")
		(net "XDP_CPU_TDI")
	)
	(segment
		(start 446.268094 -155.0797)
		(end 447.867786 -153.480008)
		(width 0.089408)
		(layer "In4.Cu")
		(net "XDP_CPU_TDI")
	)
	(segment
		(start 348.45752 -140.642848)
		(end 348.676976 -140.423392)
		(width 0.089408)
		(layer "In4.Cu")
		(net "XDP_CPU_TDI")
	)
	(segment
		(start 360.675936 -142.951708)
		(end 360.910378 -142.717266)
		(width 0.089408)
		(layer "In4.Cu")
		(net "XDP_CPU_TDI")
	)
	(segment
		(start 332.3463 -116.618766)
		(end 333.145384 -117.41785)
		(width 0.089408)
		(layer "In4.Cu")
		(net "XDP_CPU_TDI")
	)
	(segment
		(start 339.762592 -138.399012)
		(end 342.017096 -138.399012)
		(width 0.089408)
		(layer "In4.Cu")
		(net "XDP_CPU_TDI")
	)
	(segment
		(start 405.575008 -152.497282)
		(end 405.575008 -155.008326)
		(width 0.089408)
		(layer "In4.Cu")
		(net "XDP_CPU_TDI")
	)
	(segment
		(start 361.242102 -142.717266)
		(end 362.834936 -144.3101)
		(width 0.089408)
		(layer "In4.Cu")
		(net "XDP_CPU_TDI")
	)
	(segment
		(start 339.429344 -84.826856)
		(end 337.636358 -86.619842)
		(width 0.089408)
		(layer "In4.Cu")
		(net "XDP_CPU_TDI")
	)
	(segment
		(start 333.145384 -122.014742)
		(end 336.963512 -125.83287)
		(width 0.089408)
		(layer "In4.Cu")
		(net "XDP_CPU_TDI")
	)
	(segment
		(start 405.574754 -155.00858)
		(end 405.574754 -155.52928)
		(width 0.089408)
		(layer "In4.Cu")
		(net "XDP_CPU_TDI")
	)
	(segment
		(start 407.95702 -155.54198)
		(end 407.95702 -155.503626)
		(width 0.089408)
		(layer "In4.Cu")
		(net "XDP_CPU_TDI")
	)
	(segment
		(start 373.334534 -144.064736)
		(end 373.608092 -144.338294)
		(width 0.089408)
		(layer "In4.Cu")
		(net "XDP_CPU_TDI")
	)
	(segment
		(start 371.992652 -144.188688)
		(end 372.615206 -144.188688)
		(width 0.089408)
		(layer "In4.Cu")
		(net "XDP_CPU_TDI")
	)
	(segment
		(start 344.260932 -140.642848)
		(end 348.45752 -140.642848)
		(width 0.089408)
		(layer "In4.Cu")
		(net "XDP_CPU_TDI")
	)
	(segment
		(start 409.038298 -154.422348)
		(end 409.59532 -154.422348)
		(width 0.089408)
		(layer "In4.Cu")
		(net "XDP_CPU_TDI")
	)
	(segment
		(start 331.095096 -112.921796)
		(end 332.3463 -114.173)
		(width 0.089408)
		(layer "In4.Cu")
		(net "XDP_CPU_TDI")
	)
	(segment
		(start 407.95702 -155.503626)
		(end 409.038298 -154.422348)
		(width 0.089408)
		(layer "In4.Cu")
		(net "XDP_CPU_TDI")
	)
	(segment
		(start 455.625708 -153.480008)
		(end 457.289408 -151.816308)
		(width 0.089408)
		(layer "In4.Cu")
		(net "XDP_CPU_TDI")
	)
	(segment
		(start 407.300684 -156.198316)
		(end 407.95702 -155.54198)
		(width 0.089408)
		(layer "In4.Cu")
		(net "XDP_CPU_TDI")
	)
	(segment
		(start 363.09808 -144.3101)
		(end 363.10824 -144.32026)
		(width 0.089408)
		(layer "In4.Cu")
		(net "XDP_CPU_TDI")
	)
	(segment
		(start 405.574754 -155.52928)
		(end 406.24379 -156.198316)
		(width 0.089408)
		(layer "In4.Cu")
		(net "XDP_CPU_TDI")
	)
	(segment
		(start 336.963512 -135.599932)
		(end 339.762592 -138.399012)
		(width 0.089408)
		(layer "In4.Cu")
		(net "XDP_CPU_TDI")
	)
	(segment
		(start 339.429344 -84.79155)
		(end 339.429344 -84.826856)
		(width 0.089408)
		(layer "In4.Cu")
		(net "XDP_CPU_TDI")
	)
	(segment
		(start 333.145384 -117.41785)
		(end 333.145384 -122.014742)
		(width 0.089408)
		(layer "In4.Cu")
		(net "XDP_CPU_TDI")
	)
	(segment
		(start 441.39612 -154.48534)
		(end 441.99048 -155.0797)
		(width 0.089408)
		(layer "In4.Cu")
		(net "XDP_CPU_TDI")
	)
	(segment
		(start 342.017096 -138.399012)
		(end 344.260932 -140.642848)
		(width 0.089408)
		(layer "In4.Cu")
		(net "XDP_CPU_TDI")
	)
	(segment
		(start 337.636358 -86.619842)
		(end 337.636358 -86.952328)
		(width 0.089408)
		(layer "In4.Cu")
		(net "XDP_CPU_TDI")
	)
	(segment
		(start 431.29708 -155.1686)
		(end 431.98034 -154.48534)
		(width 0.089408)
		(layer "In4.Cu")
		(net "XDP_CPU_TDI")
	)
	(segment
		(start 360.675936 -143.283686)
		(end 360.675936 -142.951708)
		(width 0.089408)
		(layer "In4.Cu")
		(net "XDP_CPU_TDI")
	)
	(segment
		(start 330.466446 -107.51312)
		(end 331.095096 -108.14177)
		(width 0.089408)
		(layer "In4.Cu")
		(net "XDP_CPU_TDI")
	)
	(segment
		(start 411.814518 -157.771084)
		(end 429.758602 -157.771084)
		(width 0.089408)
		(layer "In4.Cu")
		(net "XDP_CPU_TDI")
	)
	(segment
		(start 405.359616 -152.28189)
		(end 405.575008 -152.497282)
		(width 0.089408)
		(layer "In4.Cu")
		(net "XDP_CPU_TDI")
	)
	(segment
		(start 373.608092 -144.338294)
		(end 389.532876 -144.338294)
		(width 0.089408)
		(layer "In4.Cu")
		(net "XDP_CPU_TDI")
	)
	(segment
		(start 441.99048 -155.0797)
		(end 446.268094 -155.0797)
		(width 0.089408)
		(layer "In4.Cu")
		(net "XDP_CPU_TDI")
	)
	(segment
		(start 457.289408 -151.816308)
		(end 457.289408 -151.409654)
		(width 0.089408)
		(layer "In4.Cu")
		(net "XDP_CPU_TDI")
	)
	(segment
		(start 360.502454 -143.457168)
		(end 360.675936 -143.283686)
		(width 0.089408)
		(layer "In4.Cu")
		(net "XDP_CPU_TDI")
	)
	(segment
		(start 371.86108 -144.32026)
		(end 371.992652 -144.188688)
		(width 0.089408)
		(layer "In4.Cu")
		(net "XDP_CPU_TDI")
	)
	(segment
		(start 447.867786 -153.480008)
		(end 455.625708 -153.480008)
		(width 0.089408)
		(layer "In4.Cu")
		(net "XDP_CPU_TDI")
	)
	(segment
		(start 389.532876 -144.338294)
		(end 392.522202 -147.32762)
		(width 0.089408)
		(layer "In4.Cu")
		(net "XDP_CPU_TDI")
	)
	(segment
		(start 406.24379 -156.198316)
		(end 407.300684 -156.198316)
		(width 0.089408)
		(layer "In4.Cu")
		(net "XDP_CPU_TDI")
	)
	(segment
		(start 332.3463 -114.173)
		(end 332.3463 -116.618766)
		(width 0.089408)
		(layer "In4.Cu")
		(net "XDP_CPU_TDI")
	)
	(segment
		(start 405.575008 -155.008326)
		(end 405.574754 -155.00858)
		(width 0.089408)
		(layer "In4.Cu")
		(net "XDP_CPU_TDI")
	)
	(segment
		(start 372.739158 -144.064736)
		(end 373.334534 -144.064736)
		(width 0.089408)
		(layer "In4.Cu")
		(net "XDP_CPU_TDI")
	)
	(segment
		(start 405.359616 -149.851618)
		(end 405.359616 -152.28189)
		(width 0.089408)
		(layer "In4.Cu")
		(net "XDP_CPU_TDI")
	)
	(segment
		(start 372.615206 -144.188688)
		(end 372.739158 -144.064736)
		(width 0.089408)
		(layer "In4.Cu")
		(net "XDP_CPU_TDI")
	)
	(segment
		(start 331.095096 -108.14177)
		(end 331.095096 -112.921796)
		(width 0.089408)
		(layer "In4.Cu")
		(net "XDP_CPU_TDI")
	)
	(segment
		(start 336.572098 -87.612474)
		(end 330.466446 -93.718126)
		(width 0.089408)
		(layer "In4.Cu")
		(net "XDP_CPU_TDI")
	)
	(segment
		(start 336.963512 -125.83287)
		(end 336.963512 -135.599932)
		(width 0.089408)
		(layer "In4.Cu")
		(net "XDP_CPU_TDI")
	)
	(segment
		(start 330.466446 -93.718126)
		(end 330.466446 -107.51312)
		(width 0.089408)
		(layer "In4.Cu")
		(net "XDP_CPU_TDI")
	)
	(segment
		(start 358.70642 -142.81404)
		(end 359.349548 -143.457168)
		(width 0.089408)
		(layer "In4.Cu")
		(net "XDP_CPU_TDI")
	)
	(segment
		(start 431.98034 -154.48534)
		(end 441.39612 -154.48534)
		(width 0.089408)
		(layer "In4.Cu")
		(net "XDP_CPU_TDI")
	)
	(segment
		(start 351.964244 -140.423392)
		(end 354.354892 -142.81404)
		(width 0.089408)
		(layer "In4.Cu")
		(net "XDP_CPU_TDI")
	)
	(segment
		(start 348.676976 -140.423392)
		(end 351.964244 -140.423392)
		(width 0.089408)
		(layer "In4.Cu")
		(net "XDP_CPU_TDI")
	)
	(segment
		(start 429.758602 -157.771084)
		(end 431.29708 -156.232606)
		(width 0.089408)
		(layer "In4.Cu")
		(net "XDP_CPU_TDI")
	)
	(segment
		(start 397.118586 -148.16709)
		(end 403.675088 -148.16709)
		(width 0.089408)
		(layer "In4.Cu")
		(net "XDP_CPU_TDI")
	)
	(segment
		(start 410.9974 -155.824428)
		(end 410.9974 -156.953966)
		(width 0.089408)
		(layer "In4.Cu")
		(net "XDP_CPU_TDI")
	)
	(segment
		(start 410.9974 -156.953966)
		(end 411.814518 -157.771084)
		(width 0.089408)
		(layer "In4.Cu")
		(net "XDP_CPU_TDI")
	)
	(segment
		(start 403.675088 -148.16709)
		(end 405.359616 -149.851618)
		(width 0.089408)
		(layer "In4.Cu")
		(net "XDP_CPU_TDI")
	)
	(segment
		(start 359.349548 -143.457168)
		(end 360.502454 -143.457168)
		(width 0.089408)
		(layer "In4.Cu")
		(net "XDP_CPU_TDI")
	)
	(segment
		(start 354.354892 -142.81404)
		(end 358.70642 -142.81404)
		(width 0.089408)
		(layer "In4.Cu")
		(net "XDP_CPU_TDI")
	)
	(segment
		(start 338.639404 -76.64323)
		(end 339.395816 -75.886818)
		(width 0.089408)
		(layer "In9.Cu")
		(net "XDP_CPU_TDI")
	)
	(segment
		(start 353.403408 -63.337186)
		(end 353.403408 -62.60084)
		(width 0.089408)
		(layer "In9.Cu")
		(net "XDP_CPU_TDI")
	)
	(segment
		(start 353.403408 -62.60084)
		(end 355.616764 -60.387484)
		(width 0.089408)
		(layer "In9.Cu")
		(net "XDP_CPU_TDI")
	)
	(segment
		(start 341.958422 -75.886818)
		(end 342.734646 -75.110594)
		(width 0.089408)
		(layer "In9.Cu")
		(net "XDP_CPU_TDI")
	)
	(segment
		(start 346.564458 -75.110594)
		(end 353.054158 -68.620894)
		(width 0.089408)
		(layer "In9.Cu")
		(net "XDP_CPU_TDI")
	)
	(segment
		(start 338.639404 -84.00161)
		(end 338.639404 -76.64323)
		(width 0.089408)
		(layer "In9.Cu")
		(net "XDP_CPU_TDI")
	)
	(segment
		(start 353.054158 -63.686436)
		(end 353.403408 -63.337186)
		(width 0.089408)
		(layer "In9.Cu")
		(net "XDP_CPU_TDI")
	)
	(segment
		(start 342.734646 -75.110594)
		(end 346.564458 -75.110594)
		(width 0.089408)
		(layer "In9.Cu")
		(net "XDP_CPU_TDI")
	)
	(segment
		(start 339.395816 -75.886818)
		(end 341.958422 -75.886818)
		(width 0.089408)
		(layer "In9.Cu")
		(net "XDP_CPU_TDI")
	)
	(segment
		(start 339.429344 -84.79155)
		(end 338.639404 -84.00161)
		(width 0.089408)
		(layer "In9.Cu")
		(net "XDP_CPU_TDI")
	)
	(segment
		(start 353.054158 -68.620894)
		(end 353.054158 -63.686436)
		(width 0.089408)
		(layer "In9.Cu")
		(net "XDP_CPU_TDI")
	)
	(segment
		(start 355.616764 -60.387484)
		(end 355.616764 -60.013596)
		(width 0.089408)
		(layer "In9.Cu")
		(net "XDP_CPU_TDI")
	)
	(segment
		(start 302.66005 -60.457334)
		(end 302.682402 -60.457334)
		(width 0.0889)
		(layer "In11.Cu")
		(net "XDP_CPU_TDI")
	)
	(segment
		(start 307.694076 -60.398406)
		(end 308.921404 -60.398406)
		(width 0.0889)
		(layer "In11.Cu")
		(net "XDP_CPU_TDI")
	)
	(segment
		(start 334.270858 -61.322712)
		(end 354.728018 -61.322712)
		(width 0.089408)
		(layer "In11.Cu")
		(net "XDP_CPU_TDI")
	)
	(segment
		(start 332.930246 -59.872626)
		(end 333.62392 -60.5663)
		(width 0.089408)
		(layer "In11.Cu")
		(net "XDP_CPU_TDI")
	)
	(segment
		(start 299.22597 -60.457334)
		(end 299.248322 -60.457334)
		(width 0.0889)
		(layer "In11.Cu")
		(net "XDP_CPU_TDI")
	)
	(segment
		(start 297.17365 -61.648086)
		(end 297.176952 -61.642244)
		(width 0.0889)
		(layer "In11.Cu")
		(net "XDP_CPU_TDI")
	)
	(segment
		(start 296.66184 -62.005464)
		(end 296.727118 -61.940186)
		(width 0.0889)
		(layer "In11.Cu")
		(net "XDP_CPU_TDI")
	)
	(segment
		(start 300.94301 -60.457334)
		(end 300.965362 -60.457334)
		(width 0.0889)
		(layer "In11.Cu")
		(net "XDP_CPU_TDI")
	)
	(segment
		(start 313.783472 -63.014352)
		(end 319.600326 -63.014352)
		(width 0.089408)
		(layer "In11.Cu")
		(net "XDP_CPU_TDI")
	)
	(segment
		(start 307.602636 -60.489846)
		(end 307.694076 -60.398406)
		(width 0.0889)
		(layer "In11.Cu")
		(net "XDP_CPU_TDI")
	)
	(segment
		(start 298.36364 -60.952888)
		(end 298.396406 -60.952888)
		(width 0.0889)
		(layer "In11.Cu")
		(net "XDP_CPU_TDI")
	)
	(segment
		(start 323.578982 -60.297568)
		(end 323.70903 -60.427616)
		(width 0.089408)
		(layer "In11.Cu")
		(net "XDP_CPU_TDI")
	)
	(segment
		(start 319.600326 -63.014352)
		(end 322.31711 -60.297568)
		(width 0.089408)
		(layer "In11.Cu")
		(net "XDP_CPU_TDI")
	)
	(segment
		(start 355.614478 -60.013596)
		(end 355.616764 -60.013596)
		(width 0.089408)
		(layer "In11.Cu")
		(net "XDP_CPU_TDI")
	)
	(segment
		(start 296.66184 -62.343538)
		(end 296.66184 -62.005464)
		(width 0.0889)
		(layer "In11.Cu")
		(net "XDP_CPU_TDI")
	)
	(segment
		(start 307.515514 -60.654692)
		(end 307.602636 -60.489846)
		(width 0.0889)
		(layer "In11.Cu")
		(net "XDP_CPU_TDI")
	)
	(segment
		(start 311.347358 -60.578238)
		(end 313.783472 -63.014352)
		(width 0.0889)
		(layer "In11.Cu")
		(net "XDP_CPU_TDI")
	)
	(segment
		(start 306.946046 -60.952888)
		(end 307.166518 -60.952888)
		(width 0.0889)
		(layer "In11.Cu")
		(net "XDP_CPU_TDI")
	)
	(segment
		(start 333.62392 -60.675774)
		(end 334.270858 -61.322712)
		(width 0.089408)
		(layer "In11.Cu")
		(net "XDP_CPU_TDI")
	)
	(segment
		(start 354.728018 -61.322712)
		(end 355.614478 -60.436252)
		(width 0.089408)
		(layer "In11.Cu")
		(net "XDP_CPU_TDI")
	)
	(segment
		(start 306.09413 -60.457334)
		(end 306.116482 -60.457334)
		(width 0.0889)
		(layer "In11.Cu")
		(net "XDP_CPU_TDI")
	)
	(segment
		(start 305.229006 -60.952888)
		(end 305.264566 -60.952888)
		(width 0.0889)
		(layer "In11.Cu")
		(net "XDP_CPU_TDI")
	)
	(segment
		(start 304.37709 -60.457334)
		(end 304.399442 -60.457334)
		(width 0.0889)
		(layer "In11.Cu")
		(net "XDP_CPU_TDI")
	)
	(segment
		(start 323.70903 -60.427616)
		(end 325.265796 -60.427616)
		(width 0.089408)
		(layer "In11.Cu")
		(net "XDP_CPU_TDI")
	)
	(segment
		(start 325.820786 -59.872626)
		(end 332.930246 -59.872626)
		(width 0.089408)
		(layer "In11.Cu")
		(net "XDP_CPU_TDI")
	)
	(segment
		(start 309.101236 -60.578238)
		(end 311.347358 -60.578238)
		(width 0.0889)
		(layer "In11.Cu")
		(net "XDP_CPU_TDI")
	)
	(segment
		(start 308.921404 -60.398406)
		(end 309.101236 -60.578238)
		(width 0.0889)
		(layer "In11.Cu")
		(net "XDP_CPU_TDI")
	)
	(segment
		(start 322.31711 -60.297568)
		(end 323.578982 -60.297568)
		(width 0.089408)
		(layer "In11.Cu")
		(net "XDP_CPU_TDI")
	)
	(segment
		(start 325.265796 -60.427616)
		(end 325.820786 -59.872626)
		(width 0.089408)
		(layer "In11.Cu")
		(net "XDP_CPU_TDI")
	)
	(segment
		(start 297.520106 -61.447934)
		(end 297.541696 -61.447934)
		(width 0.0889)
		(layer "In11.Cu")
		(net "XDP_CPU_TDI")
	)
	(segment
		(start 333.62392 -60.5663)
		(end 333.62392 -60.675774)
		(width 0.089408)
		(layer "In11.Cu")
		(net "XDP_CPU_TDI")
	)
	(segment
		(start 355.614478 -60.436252)
		(end 355.614478 -60.013596)
		(width 0.089408)
		(layer "In11.Cu")
		(net "XDP_CPU_TDI")
	)
	(arc
		(start 298.031916 -61.152786)
		(mid 298.171995 -61.01005)
		(end 298.36364 -60.952888)
		(width 0.0889)
		(layer "In11.Cu")
		(net "XDP_CPU_TDI")
	)
	(arc
		(start 299.248322 -60.457334)
		(mid 299.442172 -60.513684)
		(end 299.583856 -60.657486)
		(width 0.0889)
		(layer "In11.Cu")
		(net "XDP_CPU_TDI")
	)
	(arc
		(start 300.607476 -60.657486)
		(mid 300.749159 -60.513682)
		(end 300.94301 -60.457334)
		(width 0.0889)
		(layer "In11.Cu")
		(net "XDP_CPU_TDI")
	)
	(arc
		(start 297.541696 -61.447934)
		(mid 297.824913 -61.363653)
		(end 298.031916 -61.152786)
		(width 0.0889)
		(layer "In11.Cu")
		(net "XDP_CPU_TDI")
	)
	(arc
		(start 304.734976 -60.657486)
		(mid 304.943584 -60.869418)
		(end 305.229006 -60.952888)
		(width 0.0889)
		(layer "In11.Cu")
		(net "XDP_CPU_TDI")
	)
	(arc
		(start 305.758596 -60.657486)
		(mid 305.900279 -60.513682)
		(end 306.09413 -60.457334)
		(width 0.0889)
		(layer "In11.Cu")
		(net "XDP_CPU_TDI")
	)
	(arc
		(start 307.166518 -60.952888)
		(mid 307.369416 -60.837028)
		(end 307.515514 -60.654692)
		(width 0.0889)
		(layer "In11.Cu")
		(net "XDP_CPU_TDI")
	)
	(arc
		(start 300.965362 -60.457334)
		(mid 301.159212 -60.513684)
		(end 301.300896 -60.657486)
		(width 0.0889)
		(layer "In11.Cu")
		(net "XDP_CPU_TDI")
	)
	(arc
		(start 296.727118 -61.940186)
		(mid 296.985255 -61.847432)
		(end 297.17365 -61.648086)
		(width 0.0889)
		(layer "In11.Cu")
		(net "XDP_CPU_TDI")
	)
	(arc
		(start 302.682402 -60.457334)
		(mid 302.876252 -60.513684)
		(end 303.017936 -60.657486)
		(width 0.0889)
		(layer "In11.Cu")
		(net "XDP_CPU_TDI")
	)
	(arc
		(start 303.017936 -60.657486)
		(mid 303.529746 -60.953153)
		(end 304.041556 -60.657486)
		(width 0.0889)
		(layer "In11.Cu")
		(net "XDP_CPU_TDI")
	)
	(arc
		(start 297.176952 -61.642244)
		(mid 297.322918 -61.499845)
		(end 297.520106 -61.447934)
		(width 0.0889)
		(layer "In11.Cu")
		(net "XDP_CPU_TDI")
	)
	(arc
		(start 306.116482 -60.457334)
		(mid 306.310332 -60.513684)
		(end 306.452016 -60.657486)
		(width 0.0889)
		(layer "In11.Cu")
		(net "XDP_CPU_TDI")
	)
	(arc
		(start 306.452016 -60.657486)
		(mid 306.660624 -60.869418)
		(end 306.946046 -60.952888)
		(width 0.0889)
		(layer "In11.Cu")
		(net "XDP_CPU_TDI")
	)
	(arc
		(start 304.399442 -60.457334)
		(mid 304.593292 -60.513684)
		(end 304.734976 -60.657486)
		(width 0.0889)
		(layer "In11.Cu")
		(net "XDP_CPU_TDI")
	)
	(arc
		(start 298.890436 -60.657486)
		(mid 299.032119 -60.513682)
		(end 299.22597 -60.457334)
		(width 0.0889)
		(layer "In11.Cu")
		(net "XDP_CPU_TDI")
	)
	(arc
		(start 299.583856 -60.657486)
		(mid 300.095666 -60.953153)
		(end 300.607476 -60.657486)
		(width 0.0889)
		(layer "In11.Cu")
		(net "XDP_CPU_TDI")
	)
	(arc
		(start 304.041556 -60.657486)
		(mid 304.183239 -60.513682)
		(end 304.37709 -60.457334)
		(width 0.0889)
		(layer "In11.Cu")
		(net "XDP_CPU_TDI")
	)
	(arc
		(start 305.264566 -60.952888)
		(mid 305.54999 -60.869421)
		(end 305.758596 -60.657486)
		(width 0.0889)
		(layer "In11.Cu")
		(net "XDP_CPU_TDI")
	)
	(arc
		(start 302.324516 -60.657486)
		(mid 302.466199 -60.513682)
		(end 302.66005 -60.457334)
		(width 0.0889)
		(layer "In11.Cu")
		(net "XDP_CPU_TDI")
	)
	(arc
		(start 301.300896 -60.657486)
		(mid 301.812706 -60.953153)
		(end 302.324516 -60.657486)
		(width 0.0889)
		(layer "In11.Cu")
		(net "XDP_CPU_TDI")
	)
	(arc
		(start 298.396406 -60.952888)
		(mid 298.68183 -60.869421)
		(end 298.890436 -60.657486)
		(width 0.0889)
		(layer "In11.Cu")
		(net "XDP_CPU_TDI")
	)
	(segment
		(start 456.692 -155.9052)
		(end 456.2856 -155.9052)
		(width 0.10795)
		(layer "F.Cu")
		(net "XDP_CPU_TCK0")
	)
	(segment
		(start 456.2856 -155.9052)
		(end 456.057 -156.1338)
		(width 0.10795)
		(layer "F.Cu")
		(net "XDP_CPU_TCK0")
	)
	(segment
		(start 453.644 -158.242)
		(end 456.8444 -158.242)
		(width 0.10795)
		(layer "F.Cu")
		(net "XDP_CPU_TCK0")
	)
	(segment
		(start 456.24496 -156.494988)
		(end 456.057 -156.307028)
		(width 0.10795)
		(layer "F.Cu")
		(net "XDP_CPU_TCK0")
	)
	(segment
		(start 452.6534 -155.321)
		(end 452.6534 -157.2514)
		(width 0.10795)
		(layer "F.Cu")
		(net "XDP_CPU_TCK0")
	)
	(segment
		(start 462.668366 -154.9654)
		(end 457.6318 -154.9654)
		(width 0.10795)
		(layer "F.Cu")
		(net "XDP_CPU_TCK0")
	)
	(segment
		(start 457.002388 -156.494988)
		(end 456.24496 -156.494988)
		(width 0.10795)
		(layer "F.Cu")
		(net "XDP_CPU_TCK0")
	)
	(segment
		(start 464.578954 -150.189946)
		(end 464.578954 -153.054812)
		(width 0.10795)
		(layer "F.Cu")
		(net "XDP_CPU_TCK0")
	)
	(segment
		(start 443.734444 -153.225246)
		(end 444.589154 -153.225246)
		(width 0.10795)
		(layer "F.Cu")
		(net "XDP_CPU_TCK0")
	)
	(segment
		(start 464.1088 -149.719792)
		(end 462.980278 -149.719792)
		(width 0.10795)
		(layer "F.Cu")
		(net "XDP_CPU_TCK0")
	)
	(segment
		(start 457.2508 -157.8356)
		(end 457.2508 -156.7434)
		(width 0.10795)
		(layer "F.Cu")
		(net "XDP_CPU_TCK0")
	)
	(segment
		(start 452.8058 -155.1686)
		(end 452.6534 -155.321)
		(width 0.10795)
		(layer "F.Cu")
		(net "XDP_CPU_TCK0")
	)
	(segment
		(start 464.578954 -150.189946)
		(end 464.1088 -149.719792)
		(width 0.10795)
		(layer "F.Cu")
		(net "XDP_CPU_TCK0")
	)
	(segment
		(start 456.8444 -158.242)
		(end 457.2508 -157.8356)
		(width 0.10795)
		(layer "F.Cu")
		(net "XDP_CPU_TCK0")
	)
	(segment
		(start 296.66184 -61.352938)
		(end 296.09034 -61.352938)
		(width 0.1016)
		(layer "F.Cu")
		(net "XDP_CPU_TCK0")
	)
	(segment
		(start 457.2508 -156.7434)
		(end 457.002388 -156.494988)
		(width 0.10795)
		(layer "F.Cu")
		(net "XDP_CPU_TCK0")
	)
	(segment
		(start 452.6534 -157.2514)
		(end 453.644 -158.242)
		(width 0.10795)
		(layer "F.Cu")
		(net "XDP_CPU_TCK0")
	)
	(segment
		(start 456.057 -156.1338)
		(end 456.057 -156.307028)
		(width 0.10795)
		(layer "F.Cu")
		(net "XDP_CPU_TCK0")
	)
	(segment
		(start 131.089908 -61.352938)
		(end 131.661408 -61.352938)
		(width 0.1016)
		(layer "F.Cu")
		(net "XDP_CPU_TCK0")
	)
	(segment
		(start 457.6318 -154.9654)
		(end 456.692 -155.9052)
		(width 0.10795)
		(layer "F.Cu")
		(net "XDP_CPU_TCK0")
	)
	(segment
		(start 444.589154 -153.225246)
		(end 444.601346 -153.213054)
		(width 0.10795)
		(layer "F.Cu")
		(net "XDP_CPU_TCK0")
	)
	(segment
		(start 464.578954 -153.054812)
		(end 462.668366 -154.9654)
		(width 0.10795)
		(layer "F.Cu")
		(net "XDP_CPU_TCK0")
	)
	(via
		(at 296.66184 -61.352938)
		(size 0.508)
		(drill 0.254)
		(layers "F.Cu" "B.Cu")
		(net "XDP_CPU_TCK0")
	)
	(via
		(at 131.661408 -61.352938)
		(size 0.508)
		(drill 0.254)
		(layers "F.Cu" "B.Cu")
		(net "XDP_CPU_TCK0")
	)
	(via
		(at 452.8058 -155.1686)
		(size 0.508)
		(drill 0.254)
		(layers "F.Cu" "B.Cu")
		(net "XDP_CPU_TCK0")
	)
	(via
		(at 337.758278 -88.013794)
		(size 0.508)
		(drill 0.254)
		(layers "F.Cu" "B.Cu")
		(net "XDP_CPU_TCK0")
	)
	(via
		(at 323.889116 -60.019184)
		(size 0.508)
		(drill 0.254)
		(layers "F.Cu" "B.Cu")
		(net "XDP_CPU_TCK0")
	)
	(via
		(at 444.601346 -153.213054)
		(size 0.508)
		(drill 0.254)
		(layers "F.Cu" "B.Cu")
		(net "XDP_CPU_TCK0")
	)
	(via
		(at 464.578954 -150.189946)
		(size 0.508)
		(drill 0.254)
		(layers "F.Cu" "B.Cu")
		(net "XDP_CPU_TCK0")
	)
	(via
		(at 178.181 -21.717)
		(size 0.508)
		(drill 0.254)
		(layers "F.Cu" "B.Cu")
		(net "XDP_CPU_TCK0")
	)
	(via
		(at 352.683572 -58.620406)
		(size 0.508)
		(drill 0.254)
		(layers "F.Cu" "B.Cu")
		(net "XDP_CPU_TCK0")
	)
	(segment
		(start 129.558796 -62.622176)
		(end 129.558796 -62.985142)
		(width 0.10795)
		(layer "B.Cu")
		(net "XDP_CPU_TCK0")
	)
	(segment
		(start 129.786888 -64.774826)
		(end 129.786888 -64.934338)
		(width 0.10795)
		(layer "B.Cu")
		(net "XDP_CPU_TCK0")
	)
	(segment
		(start 129.528062 -64.516)
		(end 129.786888 -64.774826)
		(width 0.10795)
		(layer "B.Cu")
		(net "XDP_CPU_TCK0")
	)
	(segment
		(start 129.485644 -63.058294)
		(end 129.485644 -63.568072)
		(width 0.10795)
		(layer "B.Cu")
		(net "XDP_CPU_TCK0")
	)
	(segment
		(start 129.520188 -62.583568)
		(end 129.558796 -62.622176)
		(width 0.10795)
		(layer "B.Cu")
		(net "XDP_CPU_TCK0")
	)
	(segment
		(start 129.528062 -63.61049)
		(end 129.528062 -64.516)
		(width 0.10795)
		(layer "B.Cu")
		(net "XDP_CPU_TCK0")
	)
	(segment
		(start 129.520188 -62.120526)
		(end 129.520188 -62.583568)
		(width 0.10795)
		(layer "B.Cu")
		(net "XDP_CPU_TCK0")
	)
	(segment
		(start 129.485644 -63.568072)
		(end 129.528062 -63.61049)
		(width 0.10795)
		(layer "B.Cu")
		(net "XDP_CPU_TCK0")
	)
	(segment
		(start 452.8058 -154.5336)
		(end 452.8058 -155.1686)
		(width 0.10795)
		(layer "B.Cu")
		(net "XDP_CPU_TCK0")
	)
	(segment
		(start 131.61518 -61.30671)
		(end 130.61315 -61.30671)
		(width 0.10795)
		(layer "B.Cu")
		(net "XDP_CPU_TCK0")
	)
	(segment
		(start 130.61315 -61.30671)
		(end 130.104388 -61.815472)
		(width 0.10795)
		(layer "B.Cu")
		(net "XDP_CPU_TCK0")
	)
	(segment
		(start 129.825242 -61.815472)
		(end 129.520188 -62.120526)
		(width 0.10795)
		(layer "B.Cu")
		(net "XDP_CPU_TCK0")
	)
	(segment
		(start 129.558796 -62.985142)
		(end 129.485644 -63.058294)
		(width 0.10795)
		(layer "B.Cu")
		(net "XDP_CPU_TCK0")
	)
	(segment
		(start 131.661408 -61.352938)
		(end 131.61518 -61.30671)
		(width 0.10795)
		(layer "B.Cu")
		(net "XDP_CPU_TCK0")
	)
	(segment
		(start 130.104388 -61.815472)
		(end 129.825242 -61.815472)
		(width 0.10795)
		(layer "B.Cu")
		(net "XDP_CPU_TCK0")
	)
	(segment
		(start 411.637734 -155.987242)
		(end 411.637734 -155.600908)
		(width 0.089408)
		(layer "In4.Cu")
		(net "XDP_CPU_TCK0")
	)
	(segment
		(start 432.97602 -153.58237)
		(end 423.81551 -153.58237)
		(width 0.089408)
		(layer "In4.Cu")
		(net "XDP_CPU_TCK0")
	)
	(segment
		(start 343.641172 -138.63955)
		(end 343.385394 -138.63955)
		(width 0.089408)
		(layer "In4.Cu")
		(net "XDP_CPU_TCK0")
	)
	(segment
		(start 406.004268 -151.986488)
		(end 406.004268 -149.390862)
		(width 0.089408)
		(layer "In4.Cu")
		(net "XDP_CPU_TCK0")
	)
	(segment
		(start 397.165576 -147.111466)
		(end 396.587218 -146.533108)
		(width 0.089408)
		(layer "In4.Cu")
		(net "XDP_CPU_TCK0")
	)
	(segment
		(start 337.741006 -88.013794)
		(end 337.758278 -88.013794)
		(width 0.089408)
		(layer "In4.Cu")
		(net "XDP_CPU_TCK0")
	)
	(segment
		(start 332.33995 -108.004864)
		(end 331.200506 -106.86542)
		(width 0.089408)
		(layer "In4.Cu")
		(net "XDP_CPU_TCK0")
	)
	(segment
		(start 444.601346 -153.213054)
		(end 443.47511 -153.213054)
		(width 0.089408)
		(layer "In4.Cu")
		(net "XDP_CPU_TCK0")
	)
	(segment
		(start 371.86108 -143.453866)
		(end 371.658642 -143.656304)
		(width 0.089408)
		(layer "In4.Cu")
		(net "XDP_CPU_TCK0")
	)
	(segment
		(start 444.601346 -153.213054)
		(end 446.469008 -151.345392)
		(width 0.089408)
		(layer "In4.Cu")
		(net "XDP_CPU_TCK0")
	)
	(segment
		(start 406.218644 -154.96159)
		(end 406.218644 -152.200864)
		(width 0.089408)
		(layer "In4.Cu")
		(net "XDP_CPU_TCK0")
	)
	(segment
		(start 333.165704 -111.310928)
		(end 332.33995 -110.485174)
		(width 0.089408)
		(layer "In4.Cu")
		(net "XDP_CPU_TCK0")
	)
	(segment
		(start 407.346404 -155.250388)
		(end 407.346404 -155.288742)
		(width 0.089408)
		(layer "In4.Cu")
		(net "XDP_CPU_TCK0")
	)
	(segment
		(start 333.165704 -113.180114)
		(end 333.165704 -111.310928)
		(width 0.089408)
		(layer "In4.Cu")
		(net "XDP_CPU_TCK0")
	)
	(segment
		(start 333.756254 -121.761758)
		(end 333.756254 -117.050312)
		(width 0.089408)
		(layer "In4.Cu")
		(net "XDP_CPU_TCK0")
	)
	(segment
		(start 452.88708 -150.3553)
		(end 458.2033 -150.3553)
		(width 0.089408)
		(layer "In4.Cu")
		(net "XDP_CPU_TCK0")
	)
	(segment
		(start 362.33481 -142.121128)
		(end 361.958636 -142.121128)
		(width 0.089408)
		(layer "In4.Cu")
		(net "XDP_CPU_TCK0")
	)
	(segment
		(start 334.435704 -114.450114)
		(end 333.165704 -113.180114)
		(width 0.089408)
		(layer "In4.Cu")
		(net "XDP_CPU_TCK0")
	)
	(segment
		(start 458.9018 -151.0538)
		(end 460.791052 -151.0538)
		(width 0.089408)
		(layer "In4.Cu")
		(net "XDP_CPU_TCK0")
	)
	(segment
		(start 451.896988 -151.345392)
		(end 452.88708 -150.3553)
		(width 0.089408)
		(layer "In4.Cu")
		(net "XDP_CPU_TCK0")
	)
	(segment
		(start 389.93699 -143.711422)
		(end 373.845074 -143.711422)
		(width 0.089408)
		(layer "In4.Cu")
		(net "XDP_CPU_TCK0")
	)
	(segment
		(start 446.469008 -151.345392)
		(end 451.896988 -151.345392)
		(width 0.089408)
		(layer "In4.Cu")
		(net "XDP_CPU_TCK0")
	)
	(segment
		(start 334.74406 -91.01074)
		(end 337.741006 -88.013794)
		(width 0.089408)
		(layer "In4.Cu")
		(net "XDP_CPU_TCK0")
	)
	(segment
		(start 342.384888 -137.639044)
		(end 340.605872 -137.639044)
		(width 0.089408)
		(layer "In4.Cu")
		(net "XDP_CPU_TCK0")
	)
	(segment
		(start 464.578954 -150.355046)
		(end 464.578954 -150.189946)
		(width 0.089408)
		(layer "In4.Cu")
		(net "XDP_CPU_TCK0")
	)
	(segment
		(start 363.760258 -143.656304)
		(end 362.999528 -142.895574)
		(width 0.089408)
		(layer "In4.Cu")
		(net "XDP_CPU_TCK0")
	)
	(segment
		(start 409.848304 -153.811478)
		(end 408.785314 -153.811478)
		(width 0.089408)
		(layer "In4.Cu")
		(net "XDP_CPU_TCK0")
	)
	(segment
		(start 443.06236 -152.800304)
		(end 433.758086 -152.800304)
		(width 0.089408)
		(layer "In4.Cu")
		(net "XDP_CPU_TCK0")
	)
	(segment
		(start 458.2033 -150.3553)
		(end 458.9018 -151.0538)
		(width 0.089408)
		(layer "In4.Cu")
		(net "XDP_CPU_TCK0")
	)
	(segment
		(start 359.02138 -140.46835)
		(end 352.873056 -140.46835)
		(width 0.089408)
		(layer "In4.Cu")
		(net "XDP_CPU_TCK0")
	)
	(segment
		(start 331.200252 -95.064834)
		(end 331.200506 -95.06458)
		(width 0.089408)
		(layer "In4.Cu")
		(net "XDP_CPU_TCK0")
	)
	(segment
		(start 334.435704 -116.370862)
		(end 334.435704 -114.450114)
		(width 0.089408)
		(layer "In4.Cu")
		(net "XDP_CPU_TCK0")
	)
	(segment
		(start 403.418802 -146.805396)
		(end 403.087078 -146.805396)
		(width 0.089408)
		(layer "In4.Cu")
		(net "XDP_CPU_TCK0")
	)
	(segment
		(start 340.605872 -137.639044)
		(end 337.576668 -134.60984)
		(width 0.089408)
		(layer "In4.Cu")
		(net "XDP_CPU_TCK0")
	)
	(segment
		(start 333.756254 -117.050312)
		(end 334.435704 -116.370862)
		(width 0.089408)
		(layer "In4.Cu")
		(net "XDP_CPU_TCK0")
	)
	(segment
		(start 407.111962 -155.523184)
		(end 406.780238 -155.523184)
		(width 0.089408)
		(layer "In4.Cu")
		(net "XDP_CPU_TCK0")
	)
	(segment
		(start 331.200506 -95.06458)
		(end 331.200506 -94.111572)
		(width 0.089408)
		(layer "In4.Cu")
		(net "XDP_CPU_TCK0")
	)
	(segment
		(start 396.587218 -146.533108)
		(end 392.758676 -146.533108)
		(width 0.089408)
		(layer "In4.Cu")
		(net "XDP_CPU_TCK0")
	)
	(segment
		(start 406.218644 -152.200864)
		(end 406.004268 -151.986488)
		(width 0.089408)
		(layer "In4.Cu")
		(net "XDP_CPU_TCK0")
	)
	(segment
		(start 402.781008 -147.111466)
		(end 397.165576 -147.111466)
		(width 0.089408)
		(layer "In4.Cu")
		(net "XDP_CPU_TCK0")
	)
	(segment
		(start 331.200506 -97.164652)
		(end 331.200252 -97.164398)
		(width 0.089408)
		(layer "In4.Cu")
		(net "XDP_CPU_TCK0")
	)
	(segment
		(start 443.47511 -153.213054)
		(end 443.06236 -152.800304)
		(width 0.089408)
		(layer "In4.Cu")
		(net "XDP_CPU_TCK0")
	)
	(segment
		(start 352.217482 -139.812776)
		(end 348.372176 -139.812776)
		(width 0.089408)
		(layer "In4.Cu")
		(net "XDP_CPU_TCK0")
	)
	(segment
		(start 348.372176 -139.812776)
		(end 347.20911 -138.64971)
		(width 0.089408)
		(layer "In4.Cu")
		(net "XDP_CPU_TCK0")
	)
	(segment
		(start 433.758086 -152.800304)
		(end 432.97602 -153.58237)
		(width 0.089408)
		(layer "In4.Cu")
		(net "XDP_CPU_TCK0")
	)
	(segment
		(start 362.999528 -142.895574)
		(end 362.999528 -142.785846)
		(width 0.089408)
		(layer "In4.Cu")
		(net "XDP_CPU_TCK0")
	)
	(segment
		(start 347.20911 -138.64971)
		(end 343.651332 -138.64971)
		(width 0.089408)
		(layer "In4.Cu")
		(net "XDP_CPU_TCK0")
	)
	(segment
		(start 392.758676 -146.533108)
		(end 389.93699 -143.711422)
		(width 0.089408)
		(layer "In4.Cu")
		(net "XDP_CPU_TCK0")
	)
	(segment
		(start 423.81551 -153.58237)
		(end 420.237412 -157.160468)
		(width 0.089408)
		(layer "In4.Cu")
		(net "XDP_CPU_TCK0")
	)
	(segment
		(start 361.958636 -142.121128)
		(end 361.890818 -142.05331)
		(width 0.089408)
		(layer "In4.Cu")
		(net "XDP_CPU_TCK0")
	)
	(segment
		(start 461.299052 -151.5618)
		(end 463.3722 -151.5618)
		(width 0.089408)
		(layer "In4.Cu")
		(net "XDP_CPU_TCK0")
	)
	(segment
		(start 337.576668 -125.582172)
		(end 333.756254 -121.761758)
		(width 0.089408)
		(layer "In4.Cu")
		(net "XDP_CPU_TCK0")
	)
	(segment
		(start 331.200506 -94.111572)
		(end 334.301338 -91.01074)
		(width 0.089408)
		(layer "In4.Cu")
		(net "XDP_CPU_TCK0")
	)
	(segment
		(start 460.791052 -151.0538)
		(end 461.299052 -151.5618)
		(width 0.089408)
		(layer "In4.Cu")
		(net "XDP_CPU_TCK0")
	)
	(segment
		(start 411.637734 -155.600908)
		(end 409.848304 -153.811478)
		(width 0.089408)
		(layer "In4.Cu")
		(net "XDP_CPU_TCK0")
	)
	(segment
		(start 373.587518 -143.453866)
		(end 371.86108 -143.453866)
		(width 0.089408)
		(layer "In4.Cu")
		(net "XDP_CPU_TCK0")
	)
	(segment
		(start 373.845074 -143.711422)
		(end 373.587518 -143.453866)
		(width 0.089408)
		(layer "In4.Cu")
		(net "XDP_CPU_TCK0")
	)
	(segment
		(start 406.780238 -155.523184)
		(end 406.218644 -154.96159)
		(width 0.089408)
		(layer "In4.Cu")
		(net "XDP_CPU_TCK0")
	)
	(segment
		(start 361.890818 -142.05331)
		(end 360.60634 -142.05331)
		(width 0.089408)
		(layer "In4.Cu")
		(net "XDP_CPU_TCK0")
	)
	(segment
		(start 420.237412 -157.160468)
		(end 412.81096 -157.160468)
		(width 0.089408)
		(layer "In4.Cu")
		(net "XDP_CPU_TCK0")
	)
	(segment
		(start 406.004268 -149.390862)
		(end 403.418802 -146.805396)
		(width 0.089408)
		(layer "In4.Cu")
		(net "XDP_CPU_TCK0")
	)
	(segment
		(start 360.60634 -142.05331)
		(end 359.02138 -140.46835)
		(width 0.089408)
		(layer "In4.Cu")
		(net "XDP_CPU_TCK0")
	)
	(segment
		(start 403.087078 -146.805396)
		(end 402.781008 -147.111466)
		(width 0.089408)
		(layer "In4.Cu")
		(net "XDP_CPU_TCK0")
	)
	(segment
		(start 343.651332 -138.64971)
		(end 343.641172 -138.63955)
		(width 0.089408)
		(layer "In4.Cu")
		(net "XDP_CPU_TCK0")
	)
	(segment
		(start 332.33995 -110.485174)
		(end 332.33995 -108.004864)
		(width 0.089408)
		(layer "In4.Cu")
		(net "XDP_CPU_TCK0")
	)
	(segment
		(start 334.301338 -91.01074)
		(end 334.74406 -91.01074)
		(width 0.089408)
		(layer "In4.Cu")
		(net "XDP_CPU_TCK0")
	)
	(segment
		(start 463.3722 -151.5618)
		(end 464.578954 -150.355046)
		(width 0.089408)
		(layer "In4.Cu")
		(net "XDP_CPU_TCK0")
	)
	(segment
		(start 337.576668 -134.60984)
		(end 337.576668 -125.582172)
		(width 0.089408)
		(layer "In4.Cu")
		(net "XDP_CPU_TCK0")
	)
	(segment
		(start 412.81096 -157.160468)
		(end 411.637734 -155.987242)
		(width 0.089408)
		(layer "In4.Cu")
		(net "XDP_CPU_TCK0")
	)
	(segment
		(start 407.346404 -155.288742)
		(end 407.111962 -155.523184)
		(width 0.089408)
		(layer "In4.Cu")
		(net "XDP_CPU_TCK0")
	)
	(segment
		(start 352.873056 -140.46835)
		(end 352.217482 -139.812776)
		(width 0.089408)
		(layer "In4.Cu")
		(net "XDP_CPU_TCK0")
	)
	(segment
		(start 331.200506 -106.86542)
		(end 331.200506 -97.164652)
		(width 0.089408)
		(layer "In4.Cu")
		(net "XDP_CPU_TCK0")
	)
	(segment
		(start 371.658642 -143.656304)
		(end 363.760258 -143.656304)
		(width 0.089408)
		(layer "In4.Cu")
		(net "XDP_CPU_TCK0")
	)
	(segment
		(start 331.200252 -97.164398)
		(end 331.200252 -95.064834)
		(width 0.089408)
		(layer "In4.Cu")
		(net "XDP_CPU_TCK0")
	)
	(segment
		(start 343.385394 -138.63955)
		(end 342.384888 -137.639044)
		(width 0.089408)
		(layer "In4.Cu")
		(net "XDP_CPU_TCK0")
	)
	(segment
		(start 408.785314 -153.811478)
		(end 407.346404 -155.250388)
		(width 0.089408)
		(layer "In4.Cu")
		(net "XDP_CPU_TCK0")
	)
	(segment
		(start 362.999528 -142.785846)
		(end 362.33481 -142.121128)
		(width 0.089408)
		(layer "In4.Cu")
		(net "XDP_CPU_TCK0")
	)
	(segment
		(start 346.596716 -74.178668)
		(end 352.327972 -68.447412)
		(width 0.089408)
		(layer "In9.Cu")
		(net "XDP_CPU_TCK0")
	)
	(segment
		(start 352.7044 -58.6486)
		(end 352.679 -58.6232)
		(width 0.089408)
		(layer "In9.Cu")
		(net "XDP_CPU_TCK0")
	)
	(segment
		(start 194.756024 -10.59434)
		(end 194.706494 -10.59434)
		(width 0.089408)
		(layer "In9.Cu")
		(net "XDP_CPU_TCK0")
	)
	(segment
		(start 178.617626 -21.717)
		(end 178.181 -21.717)
		(width 0.089408)
		(layer "In9.Cu")
		(net "XDP_CPU_TCK0")
	)
	(segment
		(start 337.758278 -86.164166)
		(end 337.52028 -85.926168)
		(width 0.089408)
		(layer "In9.Cu")
		(net "XDP_CPU_TCK0")
	)
	(segment
		(start 352.679 -58.620406)
		(end 352.683572 -58.620406)
		(width 0.089408)
		(layer "In9.Cu")
		(net "XDP_CPU_TCK0")
	)
	(segment
		(start 261.436104 -13.406628)
		(end 261.436104 -12.091924)
		(width 0.089408)
		(layer "In9.Cu")
		(net "XDP_CPU_TCK0")
	)
	(segment
		(start 323.610478 -15.712186)
		(end 322.9864 -15.088108)
		(width 0.089408)
		(layer "In9.Cu")
		(net "XDP_CPU_TCK0")
	)
	(segment
		(start 323.889116 -60.019184)
		(end 323.596508 -59.726576)
		(width 0.089408)
		(layer "In9.Cu")
		(net "XDP_CPU_TCK0")
	)
	(segment
		(start 325.21398 -53.37302)
		(end 325.21398 -50.333148)
		(width 0.089408)
		(layer "In9.Cu")
		(net "XDP_CPU_TCK0")
	)
	(segment
		(start 322.9864 -12.2301)
		(end 322.234052 -11.477752)
		(width 0.089408)
		(layer "In9.Cu")
		(net "XDP_CPU_TCK0")
	)
	(segment
		(start 337.52028 -85.926168)
		(end 337.52028 -85.79739)
		(width 0.089408)
		(layer "In9.Cu")
		(net "XDP_CPU_TCK0")
	)
	(segment
		(start 264.630916 -14.468856)
		(end 264.105898 -14.993874)
		(width 0.089408)
		(layer "In9.Cu")
		(net "XDP_CPU_TCK0")
	)
	(segment
		(start 325.21398 -50.333148)
		(end 323.814948 -48.934116)
		(width 0.089408)
		(layer "In9.Cu")
		(net "XDP_CPU_TCK0")
	)
	(segment
		(start 352.327972 -68.447412)
		(end 352.327972 -63.381636)
		(width 0.089408)
		(layer "In9.Cu")
		(net "XDP_CPU_TCK0")
	)
	(segment
		(start 352.679 -58.6232)
		(end 352.679 -58.620406)
		(width 0.089408)
		(layer "In9.Cu")
		(net "XDP_CPU_TCK0")
	)
	(segment
		(start 185.29935 -17.952212)
		(end 184.034938 -19.216624)
		(width 0.089408)
		(layer "In9.Cu")
		(net "XDP_CPU_TCK0")
	)
	(segment
		(start 264.105898 -14.993874)
		(end 263.02335 -14.993874)
		(width 0.089408)
		(layer "In9.Cu")
		(net "XDP_CPU_TCK0")
	)
	(segment
		(start 326.6948 -36.059618)
		(end 326.2122 -35.577018)
		(width 0.089408)
		(layer "In9.Cu")
		(net "XDP_CPU_TCK0")
	)
	(segment
		(start 185.29935 -16.098266)
		(end 185.29935 -17.952212)
		(width 0.089408)
		(layer "In9.Cu")
		(net "XDP_CPU_TCK0")
	)
	(segment
		(start 352.327972 -63.381636)
		(end 352.7044 -63.005208)
		(width 0.089408)
		(layer "In9.Cu")
		(net "XDP_CPU_TCK0")
	)
	(segment
		(start 323.596508 -59.726576)
		(end 323.596508 -54.990492)
		(width 0.089408)
		(layer "In9.Cu")
		(net "XDP_CPU_TCK0")
	)
	(segment
		(start 265.668252 -11.630914)
		(end 265.668252 -14.079728)
		(width 0.089408)
		(layer "In9.Cu")
		(net "XDP_CPU_TCK0")
	)
	(segment
		(start 342.594438 -74.178668)
		(end 346.596716 -74.178668)
		(width 0.089408)
		(layer "In9.Cu")
		(net "XDP_CPU_TCK0")
	)
	(segment
		(start 341.702136 -75.07097)
		(end 342.594438 -74.178668)
		(width 0.089408)
		(layer "In9.Cu")
		(net "XDP_CPU_TCK0")
	)
	(segment
		(start 337.309206 -85.586316)
		(end 337.309206 -76.679044)
		(width 0.089408)
		(layer "In9.Cu")
		(net "XDP_CPU_TCK0")
	)
	(segment
		(start 328.166476 -44.087288)
		(end 328.166476 -41.832276)
		(width 0.089408)
		(layer "In9.Cu")
		(net "XDP_CPU_TCK0")
	)
	(segment
		(start 326.2122 -35.577018)
		(end 326.2122 -26.264616)
		(width 0.089408)
		(layer "In9.Cu")
		(net "XDP_CPU_TCK0")
	)
	(segment
		(start 265.668252 -14.079728)
		(end 265.279124 -14.468856)
		(width 0.089408)
		(layer "In9.Cu")
		(net "XDP_CPU_TCK0")
	)
	(segment
		(start 337.758278 -88.013794)
		(end 337.758278 -86.164166)
		(width 0.089408)
		(layer "In9.Cu")
		(net "XDP_CPU_TCK0")
	)
	(segment
		(start 265.821414 -11.477752)
		(end 265.668252 -11.630914)
		(width 0.089408)
		(layer "In9.Cu")
		(net "XDP_CPU_TCK0")
	)
	(segment
		(start 337.52028 -85.79739)
		(end 337.309206 -85.586316)
		(width 0.089408)
		(layer "In9.Cu")
		(net "XDP_CPU_TCK0")
	)
	(segment
		(start 322.9864 -15.088108)
		(end 322.9864 -12.2301)
		(width 0.089408)
		(layer "In9.Cu")
		(net "XDP_CPU_TCK0")
	)
	(segment
		(start 323.814948 -48.934116)
		(end 323.814948 -47.634652)
		(width 0.089408)
		(layer "In9.Cu")
		(net "XDP_CPU_TCK0")
	)
	(segment
		(start 326.6948 -40.3606)
		(end 326.6948 -36.059618)
		(width 0.089408)
		(layer "In9.Cu")
		(net "XDP_CPU_TCK0")
	)
	(segment
		(start 181.118002 -19.216624)
		(end 178.617626 -21.717)
		(width 0.089408)
		(layer "In9.Cu")
		(net "XDP_CPU_TCK0")
	)
	(segment
		(start 194.781424 -10.56894)
		(end 194.756024 -10.59434)
		(width 0.089408)
		(layer "In9.Cu")
		(net "XDP_CPU_TCK0")
	)
	(segment
		(start 322.234052 -11.477752)
		(end 265.821414 -11.477752)
		(width 0.089408)
		(layer "In9.Cu")
		(net "XDP_CPU_TCK0")
	)
	(segment
		(start 337.309206 -76.679044)
		(end 338.91728 -75.07097)
		(width 0.089408)
		(layer "In9.Cu")
		(net "XDP_CPU_TCK0")
	)
	(segment
		(start 328.166476 -41.832276)
		(end 326.6948 -40.3606)
		(width 0.089408)
		(layer "In9.Cu")
		(net "XDP_CPU_TCK0")
	)
	(segment
		(start 261.436104 -12.091924)
		(end 259.91312 -10.56894)
		(width 0.089408)
		(layer "In9.Cu")
		(net "XDP_CPU_TCK0")
	)
	(segment
		(start 265.279124 -14.468856)
		(end 264.630916 -14.468856)
		(width 0.089408)
		(layer "In9.Cu")
		(net "XDP_CPU_TCK0")
	)
	(segment
		(start 184.034938 -19.216624)
		(end 181.118002 -19.216624)
		(width 0.089408)
		(layer "In9.Cu")
		(net "XDP_CPU_TCK0")
	)
	(segment
		(start 194.706494 -10.59434)
		(end 190.13805 -15.162784)
		(width 0.089408)
		(layer "In9.Cu")
		(net "XDP_CPU_TCK0")
	)
	(segment
		(start 326.2122 -26.264616)
		(end 323.610478 -23.662894)
		(width 0.089408)
		(layer "In9.Cu")
		(net "XDP_CPU_TCK0")
	)
	(segment
		(start 259.91312 -10.56894)
		(end 194.781424 -10.56894)
		(width 0.089408)
		(layer "In9.Cu")
		(net "XDP_CPU_TCK0")
	)
	(segment
		(start 323.596508 -54.990492)
		(end 325.21398 -53.37302)
		(width 0.089408)
		(layer "In9.Cu")
		(net "XDP_CPU_TCK0")
	)
	(segment
		(start 327.119996 -45.133768)
		(end 328.166476 -44.087288)
		(width 0.089408)
		(layer "In9.Cu")
		(net "XDP_CPU_TCK0")
	)
	(segment
		(start 326.315832 -45.133768)
		(end 327.119996 -45.133768)
		(width 0.089408)
		(layer "In9.Cu")
		(net "XDP_CPU_TCK0")
	)
	(segment
		(start 263.02335 -14.993874)
		(end 261.436104 -13.406628)
		(width 0.089408)
		(layer "In9.Cu")
		(net "XDP_CPU_TCK0")
	)
	(segment
		(start 338.91728 -75.07097)
		(end 341.702136 -75.07097)
		(width 0.089408)
		(layer "In9.Cu")
		(net "XDP_CPU_TCK0")
	)
	(segment
		(start 190.13805 -15.162784)
		(end 186.234832 -15.162784)
		(width 0.089408)
		(layer "In9.Cu")
		(net "XDP_CPU_TCK0")
	)
	(segment
		(start 352.7044 -63.005208)
		(end 352.7044 -58.6486)
		(width 0.089408)
		(layer "In9.Cu")
		(net "XDP_CPU_TCK0")
	)
	(segment
		(start 323.814948 -47.634652)
		(end 326.315832 -45.133768)
		(width 0.089408)
		(layer "In9.Cu")
		(net "XDP_CPU_TCK0")
	)
	(segment
		(start 186.234832 -15.162784)
		(end 185.29935 -16.098266)
		(width 0.089408)
		(layer "In9.Cu")
		(net "XDP_CPU_TCK0")
	)
	(segment
		(start 323.610478 -23.662894)
		(end 323.610478 -15.712186)
		(width 0.089408)
		(layer "In9.Cu")
		(net "XDP_CPU_TCK0")
	)
	(segment
		(start 135.7884 -57.3024)
		(end 136.1948 -57.3024)
		(width 0.089408)
		(layer "In11.Cu")
		(net "XDP_CPU_TCK0")
	)
	(segment
		(start 135.2169 -57.8739)
		(end 135.7884 -57.3024)
		(width 0.089408)
		(layer "In11.Cu")
		(net "XDP_CPU_TCK0")
	)
	(segment
		(start 140.6906 -53.269896)
		(end 141.082522 -52.324)
		(width 0.089408)
		(layer "In11.Cu")
		(net "XDP_CPU_TCK0")
	)
	(segment
		(start 140.6906 -54.5846)
		(end 140.6906 -53.269896)
		(width 0.089408)
		(layer "In11.Cu")
		(net "XDP_CPU_TCK0")
	)
	(segment
		(start 137.3632 -56.4388)
		(end 137.7696 -56.4388)
		(width 0.089408)
		(layer "In11.Cu")
		(net "XDP_CPU_TCK0")
	)
	(segment
		(start 139.1158 -55.4482)
		(end 139.4968 -55.4482)
		(width 0.089408)
		(layer "In11.Cu")
		(net "XDP_CPU_TCK0")
	)
	(segment
		(start 168.091104 -26.46426)
		(end 170.381676 -24.173688)
		(width 0.089408)
		(layer "In11.Cu")
		(net "XDP_CPU_TCK0")
	)
	(segment
		(start 300.936406 -60.266834)
		(end 300.971966 -60.266834)
		(width 0.0889)
		(layer "In11.Cu")
		(net "XDP_CPU_TCK0")
	)
	(segment
		(start 177.411634 -22.098)
		(end 177.8 -22.098)
		(width 0.089408)
		(layer "In11.Cu")
		(net "XDP_CPU_TCK0")
	)
	(segment
		(start 172.27804 -22.683978)
		(end 176.825656 -22.683978)
		(width 0.089408)
		(layer "In11.Cu")
		(net "XDP_CPU_TCK0")
	)
	(segment
		(start 299.219366 -60.266834)
		(end 299.254926 -60.266834)
		(width 0.0889)
		(layer "In11.Cu")
		(net "XDP_CPU_TCK0")
	)
	(segment
		(start 134.2136 -58.293)
		(end 134.4676 -58.293)
		(width 0.089408)
		(layer "In11.Cu")
		(net "XDP_CPU_TCK0")
	)
	(segment
		(start 296.66184 -61.691012)
		(end 296.719498 -61.74867)
		(width 0.0889)
		(layer "In11.Cu")
		(net "XDP_CPU_TCK0")
	)
	(segment
		(start 136.1948 -57.3024)
		(end 136.652 -56.8452)
		(width 0.089408)
		(layer "In11.Cu")
		(net "XDP_CPU_TCK0")
	)
	(segment
		(start 307.640228 -60.18276)
		(end 311.4675 -60.18276)
		(width 0.0889)
		(layer "In11.Cu")
		(net "XDP_CPU_TCK0")
	)
	(segment
		(start 141.082522 -52.324)
		(end 141.092936 -52.299108)
		(width 0.089408)
		(layer "In11.Cu")
		(net "XDP_CPU_TCK0")
	)
	(segment
		(start 325.129144 -60.019184)
		(end 323.889116 -60.019184)
		(width 0.089408)
		(layer "In11.Cu")
		(net "XDP_CPU_TCK0")
	)
	(segment
		(start 138.3284 -55.88)
		(end 138.684 -55.88)
		(width 0.089408)
		(layer "In11.Cu")
		(net "XDP_CPU_TCK0")
	)
	(segment
		(start 322.19646 -59.968384)
		(end 323.838316 -59.968384)
		(width 0.089408)
		(layer "In11.Cu")
		(net "XDP_CPU_TCK0")
	)
	(segment
		(start 133.356604 -60.762388)
		(end 133.38937 -60.762388)
		(width 0.0889)
		(layer "In11.Cu")
		(net "XDP_CPU_TCK0")
	)
	(segment
		(start 330.1746 -59.1566)
		(end 327.801732 -59.1566)
		(width 0.089408)
		(layer "In11.Cu")
		(net "XDP_CPU_TCK0")
	)
	(segment
		(start 171.076112 -23.885906)
		(end 172.27804 -22.683978)
		(width 0.089408)
		(layer "In11.Cu")
		(net "XDP_CPU_TCK0")
	)
	(segment
		(start 306.087526 -60.266834)
		(end 306.123086 -60.266834)
		(width 0.0889)
		(layer "In11.Cu")
		(net "XDP_CPU_TCK0")
	)
	(segment
		(start 311.4675 -60.18276)
		(end 313.981084 -62.696344)
		(width 0.089408)
		(layer "In11.Cu")
		(net "XDP_CPU_TCK0")
	)
	(segment
		(start 167.899334 -26.543762)
		(end 168.091104 -26.46426)
		(width 0.089408)
		(layer "In11.Cu")
		(net "XDP_CPU_TCK0")
	)
	(segment
		(start 319.4685 -62.696344)
		(end 322.19646 -59.968384)
		(width 0.089408)
		(layer "In11.Cu")
		(net "XDP_CPU_TCK0")
	)
	(segment
		(start 352.683572 -58.620406)
		(end 352.454464 -58.391298)
		(width 0.089408)
		(layer "In11.Cu")
		(net "XDP_CPU_TCK0")
	)
	(segment
		(start 134.4676 -58.293)
		(end 134.8867 -57.8739)
		(width 0.089408)
		(layer "In11.Cu")
		(net "XDP_CPU_TCK0")
	)
	(segment
		(start 170.381676 -24.173688)
		(end 171.076112 -23.885906)
		(width 0.089408)
		(layer "In11.Cu")
		(net "XDP_CPU_TCK0")
	)
	(segment
		(start 313.981084 -62.696344)
		(end 319.4685 -62.696344)
		(width 0.089408)
		(layer "In11.Cu")
		(net "XDP_CPU_TCK0")
	)
	(segment
		(start 158.776924 -31.053786)
		(end 160.025334 -29.805376)
		(width 0.089408)
		(layer "In11.Cu")
		(net "XDP_CPU_TCK0")
	)
	(segment
		(start 134.8867 -57.8739)
		(end 135.2169 -57.8739)
		(width 0.089408)
		(layer "In11.Cu")
		(net "XDP_CPU_TCK0")
	)
	(segment
		(start 177.8 -22.098)
		(end 178.181 -21.717)
		(width 0.089408)
		(layer "In11.Cu")
		(net "XDP_CPU_TCK0")
	)
	(segment
		(start 136.652 -56.8452)
		(end 136.9568 -56.8452)
		(width 0.089408)
		(layer "In11.Cu")
		(net "XDP_CPU_TCK0")
	)
	(segment
		(start 307.346858 -60.56503)
		(end 307.447696 -60.375292)
		(width 0.0889)
		(layer "In11.Cu")
		(net "XDP_CPU_TCK0")
	)
	(segment
		(start 136.9568 -56.8452)
		(end 137.3632 -56.4388)
		(width 0.089408)
		(layer "In11.Cu")
		(net "XDP_CPU_TCK0")
	)
	(segment
		(start 326.16521 -58.983118)
		(end 325.129144 -60.019184)
		(width 0.089408)
		(layer "In11.Cu")
		(net "XDP_CPU_TCK0")
	)
	(segment
		(start 297.502326 -61.257434)
		(end 297.535092 -61.257434)
		(width 0.0889)
		(layer "In11.Cu")
		(net "XDP_CPU_TCK0")
	)
	(segment
		(start 305.23561 -60.762388)
		(end 305.257962 -60.762388)
		(width 0.0889)
		(layer "In11.Cu")
		(net "XDP_CPU_TCK0")
	)
	(segment
		(start 298.357036 -60.762388)
		(end 298.389802 -60.762388)
		(width 0.0889)
		(layer "In11.Cu")
		(net "XDP_CPU_TCK0")
	)
	(segment
		(start 307.447696 -60.375292)
		(end 307.640228 -60.18276)
		(width 0.0889)
		(layer "In11.Cu")
		(net "XDP_CPU_TCK0")
	)
	(segment
		(start 304.370486 -60.266834)
		(end 304.406046 -60.266834)
		(width 0.0889)
		(layer "In11.Cu")
		(net "XDP_CPU_TCK0")
	)
	(segment
		(start 327.62825 -58.983118)
		(end 326.16521 -58.983118)
		(width 0.089408)
		(layer "In11.Cu")
		(net "XDP_CPU_TCK0")
	)
	(segment
		(start 140.3604 -54.9148)
		(end 140.6906 -54.5846)
		(width 0.089408)
		(layer "In11.Cu")
		(net "XDP_CPU_TCK0")
	)
	(segment
		(start 133.809486 -60.401962)
		(end 133.809486 -58.697114)
		(width 0.089408)
		(layer "In11.Cu")
		(net "XDP_CPU_TCK0")
	)
	(segment
		(start 160.025334 -29.805376)
		(end 167.899334 -26.543762)
		(width 0.089408)
		(layer "In11.Cu")
		(net "XDP_CPU_TCK0")
	)
	(segment
		(start 323.838316 -59.968384)
		(end 323.889116 -60.019184)
		(width 0.089408)
		(layer "In11.Cu")
		(net "XDP_CPU_TCK0")
	)
	(segment
		(start 327.801732 -59.1566)
		(end 327.62825 -58.983118)
		(width 0.089408)
		(layer "In11.Cu")
		(net "XDP_CPU_TCK0")
	)
	(segment
		(start 137.7696 -56.4388)
		(end 138.3284 -55.88)
		(width 0.089408)
		(layer "In11.Cu")
		(net "XDP_CPU_TCK0")
	)
	(segment
		(start 156.258006 -37.134292)
		(end 158.776924 -31.053786)
		(width 0.089408)
		(layer "In11.Cu")
		(net "XDP_CPU_TCK0")
	)
	(segment
		(start 302.653446 -60.266834)
		(end 302.689006 -60.266834)
		(width 0.0889)
		(layer "In11.Cu")
		(net "XDP_CPU_TCK0")
	)
	(segment
		(start 176.825656 -22.683978)
		(end 177.411634 -22.098)
		(width 0.089408)
		(layer "In11.Cu")
		(net "XDP_CPU_TCK0")
	)
	(segment
		(start 352.454464 -58.391298)
		(end 330.939902 -58.391298)
		(width 0.089408)
		(layer "In11.Cu")
		(net "XDP_CPU_TCK0")
	)
	(segment
		(start 330.939902 -58.391298)
		(end 330.1746 -59.1566)
		(width 0.089408)
		(layer "In11.Cu")
		(net "XDP_CPU_TCK0")
	)
	(segment
		(start 297.004994 -61.558678)
		(end 297.008296 -61.552836)
		(width 0.0889)
		(layer "In11.Cu")
		(net "XDP_CPU_TCK0")
	)
	(segment
		(start 140.0302 -54.9148)
		(end 140.3604 -54.9148)
		(width 0.089408)
		(layer "In11.Cu")
		(net "XDP_CPU_TCK0")
	)
	(segment
		(start 296.66184 -61.352938)
		(end 296.66184 -61.691012)
		(width 0.0889)
		(layer "In11.Cu")
		(net "XDP_CPU_TCK0")
	)
	(segment
		(start 141.092936 -52.299108)
		(end 156.258006 -37.134292)
		(width 0.089408)
		(layer "In11.Cu")
		(net "XDP_CPU_TCK0")
	)
	(segment
		(start 133.809486 -58.697114)
		(end 134.2136 -58.293)
		(width 0.089408)
		(layer "In11.Cu")
		(net "XDP_CPU_TCK0")
	)
	(segment
		(start 139.4968 -55.4482)
		(end 140.0302 -54.9148)
		(width 0.089408)
		(layer "In11.Cu")
		(net "XDP_CPU_TCK0")
	)
	(segment
		(start 138.684 -55.88)
		(end 139.1158 -55.4482)
		(width 0.089408)
		(layer "In11.Cu")
		(net "XDP_CPU_TCK0")
	)
	(segment
		(start 306.95265 -60.762388)
		(end 307.130196 -60.762388)
		(width 0.0889)
		(layer "In11.Cu")
		(net "XDP_CPU_TCK0")
	)
	(arc
		(start 131.661408 -61.352938)
		(mid 132.120414 -61.311596)
		(end 132.577586 -61.25337)
		(width 0.0889)
		(layer "In11.Cu")
		(net "XDP_CPU_TCK0")
	)
	(arc
		(start 301.465996 -60.562236)
		(mid 301.812706 -60.762547)
		(end 302.159416 -60.562236)
		(width 0.0889)
		(layer "In11.Cu")
		(net "XDP_CPU_TCK0")
	)
	(arc
		(start 297.866816 -61.057536)
		(mid 298.07382 -60.846672)
		(end 298.357036 -60.762388)
		(width 0.0889)
		(layer "In11.Cu")
		(net "XDP_CPU_TCK0")
	)
	(arc
		(start 299.254926 -60.266834)
		(mid 299.54035 -60.350301)
		(end 299.748956 -60.562236)
		(width 0.0889)
		(layer "In11.Cu")
		(net "XDP_CPU_TCK0")
	)
	(arc
		(start 299.748956 -60.562236)
		(mid 300.095666 -60.762547)
		(end 300.442376 -60.562236)
		(width 0.0889)
		(layer "In11.Cu")
		(net "XDP_CPU_TCK0")
	)
	(arc
		(start 305.593496 -60.562236)
		(mid 305.802104 -60.350304)
		(end 306.087526 -60.266834)
		(width 0.0889)
		(layer "In11.Cu")
		(net "XDP_CPU_TCK0")
	)
	(arc
		(start 304.900076 -60.562236)
		(mid 305.041759 -60.70604)
		(end 305.23561 -60.762388)
		(width 0.0889)
		(layer "In11.Cu")
		(net "XDP_CPU_TCK0")
	)
	(arc
		(start 297.008296 -61.552836)
		(mid 297.216904 -61.340904)
		(end 297.502326 -61.257434)
		(width 0.0889)
		(layer "In11.Cu")
		(net "XDP_CPU_TCK0")
	)
	(arc
		(start 133.38937 -60.762388)
		(mid 133.58322 -60.706038)
		(end 133.724904 -60.562236)
		(width 0.0889)
		(layer "In11.Cu")
		(net "XDP_CPU_TCK0")
	)
	(arc
		(start 296.719498 -61.74867)
		(mid 296.883675 -61.685853)
		(end 297.004994 -61.558678)
		(width 0.0889)
		(layer "In11.Cu")
		(net "XDP_CPU_TCK0")
	)
	(arc
		(start 306.123086 -60.266834)
		(mid 306.40851 -60.350301)
		(end 306.617116 -60.562236)
		(width 0.0889)
		(layer "In11.Cu")
		(net "XDP_CPU_TCK0")
	)
	(arc
		(start 297.535092 -61.257434)
		(mid 297.726734 -61.200268)
		(end 297.866816 -61.057536)
		(width 0.0889)
		(layer "In11.Cu")
		(net "XDP_CPU_TCK0")
	)
	(arc
		(start 298.389802 -60.762388)
		(mid 298.583652 -60.706038)
		(end 298.725336 -60.562236)
		(width 0.0889)
		(layer "In11.Cu")
		(net "XDP_CPU_TCK0")
	)
	(arc
		(start 307.130196 -60.762388)
		(mid 307.255683 -60.682555)
		(end 307.346858 -60.56503)
		(width 0.0889)
		(layer "In11.Cu")
		(net "XDP_CPU_TCK0")
	)
	(arc
		(start 305.257962 -60.762388)
		(mid 305.451812 -60.706038)
		(end 305.593496 -60.562236)
		(width 0.0889)
		(layer "In11.Cu")
		(net "XDP_CPU_TCK0")
	)
	(arc
		(start 132.866384 -61.057536)
		(mid 133.073388 -60.846672)
		(end 133.356604 -60.762388)
		(width 0.0889)
		(layer "In11.Cu")
		(net "XDP_CPU_TCK0")
	)
	(arc
		(start 306.617116 -60.562236)
		(mid 306.758799 -60.70604)
		(end 306.95265 -60.762388)
		(width 0.0889)
		(layer "In11.Cu")
		(net "XDP_CPU_TCK0")
	)
	(arc
		(start 302.689006 -60.266834)
		(mid 302.97443 -60.350301)
		(end 303.183036 -60.562236)
		(width 0.0889)
		(layer "In11.Cu")
		(net "XDP_CPU_TCK0")
	)
	(arc
		(start 300.442376 -60.562236)
		(mid 300.650984 -60.350304)
		(end 300.936406 -60.266834)
		(width 0.0889)
		(layer "In11.Cu")
		(net "XDP_CPU_TCK0")
	)
	(arc
		(start 300.971966 -60.266834)
		(mid 301.25739 -60.350301)
		(end 301.465996 -60.562236)
		(width 0.0889)
		(layer "In11.Cu")
		(net "XDP_CPU_TCK0")
	)
	(arc
		(start 132.577586 -61.25337)
		(mid 132.744431 -61.188557)
		(end 132.866384 -61.057536)
		(width 0.0889)
		(layer "In11.Cu")
		(net "XDP_CPU_TCK0")
	)
	(arc
		(start 303.876456 -60.562236)
		(mid 304.085064 -60.350304)
		(end 304.370486 -60.266834)
		(width 0.0889)
		(layer "In11.Cu")
		(net "XDP_CPU_TCK0")
	)
	(arc
		(start 302.159416 -60.562236)
		(mid 302.368024 -60.350304)
		(end 302.653446 -60.266834)
		(width 0.0889)
		(layer "In11.Cu")
		(net "XDP_CPU_TCK0")
	)
	(arc
		(start 304.406046 -60.266834)
		(mid 304.69147 -60.350301)
		(end 304.900076 -60.562236)
		(width 0.0889)
		(layer "In11.Cu")
		(net "XDP_CPU_TCK0")
	)
	(arc
		(start 298.725336 -60.562236)
		(mid 298.933944 -60.350304)
		(end 299.219366 -60.266834)
		(width 0.0889)
		(layer "In11.Cu")
		(net "XDP_CPU_TCK0")
	)
	(arc
		(start 303.183036 -60.562236)
		(mid 303.529746 -60.762547)
		(end 303.876456 -60.562236)
		(width 0.0889)
		(layer "In11.Cu")
		(net "XDP_CPU_TCK0")
	)
	(arc
		(start 133.724904 -60.562236)
		(mid 133.768691 -60.482888)
		(end 133.809486 -60.401962)
		(width 0.0889)
		(layer "In11.Cu")
		(net "XDP_CPU_TCK0")
	)
	(segment
		(start 297.807126 -68.287138)
		(end 298.378626 -68.287138)
		(width 0.1016)
		(layer "F.Cu")
		(net "XDP_CPU_PREQ_N")
	)
	(segment
		(start 132.806694 -68.287138)
		(end 133.378194 -68.287138)
		(width 0.1016)
		(layer "F.Cu")
		(net "XDP_CPU_PREQ_N")
	)
	(via
		(at 358.264206 -85.848952)
		(size 0.508)
		(drill 0.254)
		(layers "F.Cu" "B.Cu")
		(net "XDP_CPU_PREQ_N")
	)
	(via
		(at 358.39146 -84.93506)
		(size 0.6604)
		(drill 0.3302)
		(layers "F.Cu" "B.Cu")
		(net "XDP_CPU_PREQ_N")
	)
	(via
		(at 193.940176 -132.647944)
		(size 0.508)
		(drill 0.254)
		(layers "F.Cu" "B.Cu")
		(net "XDP_CPU_PREQ_N")
	)
	(via
		(at 298.378626 -68.287138)
		(size 0.508)
		(drill 0.254)
		(layers "F.Cu" "B.Cu")
		(net "XDP_CPU_PREQ_N")
	)
	(via
		(at 458.743304 -132.97535)
		(size 0.508)
		(drill 0.254)
		(layers "F.Cu" "B.Cu")
		(net "XDP_CPU_PREQ_N")
	)
	(via
		(at 355.562408 -64.097662)
		(size 0.508)
		(drill 0.254)
		(layers "F.Cu" "B.Cu")
		(net "XDP_CPU_PREQ_N")
	)
	(via
		(at 133.378194 -68.287138)
		(size 0.508)
		(drill 0.254)
		(layers "F.Cu" "B.Cu")
		(net "XDP_CPU_PREQ_N")
	)
	(segment
		(start 459.753208 -134.125462)
		(end 458.743304 -133.115558)
		(width 0.10795)
		(layer "B.Cu")
		(net "XDP_CPU_PREQ_N")
	)
	(segment
		(start 458.743304 -132.97535)
		(end 458.8764 -132.842254)
		(width 0.10795)
		(layer "B.Cu")
		(net "XDP_CPU_PREQ_N")
	)
	(segment
		(start 458.8764 -132.842254)
		(end 459.499208 -132.842254)
		(width 0.10795)
		(layer "B.Cu")
		(net "XDP_CPU_PREQ_N")
	)
	(segment
		(start 458.743304 -133.115558)
		(end 458.743304 -132.97535)
		(width 0.10795)
		(layer "B.Cu")
		(net "XDP_CPU_PREQ_N")
	)
	(segment
		(start 358.39146 -84.93506)
		(end 358.264206 -85.062314)
		(width 0.10795)
		(layer "B.Cu")
		(net "XDP_CPU_PREQ_N")
	)
	(segment
		(start 358.264206 -85.062314)
		(end 358.264206 -85.848952)
		(width 0.10795)
		(layer "B.Cu")
		(net "XDP_CPU_PREQ_N")
	)
	(segment
		(start 459.753208 -134.594346)
		(end 459.753208 -134.125462)
		(width 0.10795)
		(layer "B.Cu")
		(net "XDP_CPU_PREQ_N")
	)
	(segment
		(start 406.72893 -145.886424)
		(end 406.783794 -145.83156)
		(width 0.089408)
		(layer "In4.Cu")
		(net "XDP_CPU_PREQ_N")
	)
	(segment
		(start 401.264374 -144.68094)
		(end 404.461726 -144.68094)
		(width 0.089408)
		(layer "In4.Cu")
		(net "XDP_CPU_PREQ_N")
	)
	(segment
		(start 440.165236 -139.683744)
		(end 440.813952 -139.035028)
		(width 0.089408)
		(layer "In4.Cu")
		(net "XDP_CPU_PREQ_N")
	)
	(segment
		(start 251.08027 -86.88959)
		(end 251.047504 -86.88959)
		(width 0.0889)
		(layer "In4.Cu")
		(net "XDP_CPU_PREQ_N")
	)
	(segment
		(start 249.35942 -82.92719)
		(end 249.326654 -82.92719)
		(width 0.0889)
		(layer "In4.Cu")
		(net "XDP_CPU_PREQ_N")
	)
	(segment
		(start 234.764834 -80.450436)
		(end 234.525058 -80.450436)
		(width 0.0889)
		(layer "In4.Cu")
		(net "XDP_CPU_PREQ_N")
	)
	(segment
		(start 344.693494 -126.786894)
		(end 345.916504 -128.009904)
		(width 0.089408)
		(layer "In4.Cu")
		(net "XDP_CPU_PREQ_N")
	)
	(segment
		(start 209.696304 -102.493064)
		(end 209.461862 -102.727506)
		(width 0.089408)
		(layer "In4.Cu")
		(net "XDP_CPU_PREQ_N")
	)
	(segment
		(start 194.780408 -130.87096)
		(end 194.003676 -131.647692)
		(width 0.089408)
		(layer "In4.Cu")
		(net "XDP_CPU_PREQ_N")
	)
	(segment
		(start 358.264206 -87.098886)
		(end 354.50018 -90.862912)
		(width 0.089408)
		(layer "In4.Cu")
		(net "XDP_CPU_PREQ_N")
	)
	(segment
		(start 441.352686 -138.496294)
		(end 443.14745 -138.496294)
		(width 0.089408)
		(layer "In4.Cu")
		(net "XDP_CPU_PREQ_N")
	)
	(segment
		(start 296.31513 -69.477636)
		(end 296.32148 -69.488304)
		(width 0.0889)
		(layer "In4.Cu")
		(net "XDP_CPU_PREQ_N")
	)
	(segment
		(start 344.809826 -116.311934)
		(end 345.311476 -116.813584)
		(width 0.089408)
		(layer "In4.Cu")
		(net "XDP_CPU_PREQ_N")
	)
	(segment
		(start 196.07022 -115.357656)
		(end 194.780408 -116.647468)
		(width 0.089408)
		(layer "In4.Cu")
		(net "XDP_CPU_PREQ_N")
	)
	(segment
		(start 268.358366 -90.862658)
		(end 267.873226 -91.347798)
		(width 0.0889)
		(layer "In4.Cu")
		(net "XDP_CPU_PREQ_N")
	)
	(segment
		(start 234.064048 -80.911446)
		(end 233.772456 -80.911446)
		(width 0.0889)
		(layer "In4.Cu")
		(net "XDP_CPU_PREQ_N")
	)
	(segment
		(start 289.81146 -83.736688)
		(end 289.778694 -83.736688)
		(width 0.0889)
		(layer "In4.Cu")
		(net "XDP_CPU_PREQ_N")
	)
	(segment
		(start 446.980056 -139.683744)
		(end 449.393818 -137.269982)
		(width 0.089408)
		(layer "In4.Cu")
		(net "XDP_CPU_PREQ_N")
	)
	(segment
		(start 420.34206 -140.525754)
		(end 420.97071 -141.154404)
		(width 0.089408)
		(layer "In4.Cu")
		(net "XDP_CPU_PREQ_N")
	)
	(segment
		(start 458.3684 -138.8364)
		(end 458.730096 -138.474704)
		(width 0.089408)
		(layer "In4.Cu")
		(net "XDP_CPU_PREQ_N")
	)
	(segment
		(start 440.813952 -138.965432)
		(end 441.21959 -138.559794)
		(width 0.089408)
		(layer "In4.Cu")
		(net "XDP_CPU_PREQ_N")
	)
	(segment
		(start 284.660594 -86.708488)
		(end 284.627828 -86.708488)
		(width 0.0889)
		(layer "In4.Cu")
		(net "XDP_CPU_PREQ_N")
	)
	(segment
		(start 411.125416 -141.232636)
		(end 411.832298 -140.525754)
		(width 0.089408)
		(layer "In4.Cu")
		(net "XDP_CPU_PREQ_N")
	)
	(segment
		(start 400.422618 -142.708884)
		(end 400.422618 -143.839184)
		(width 0.089408)
		(layer "In4.Cu")
		(net "XDP_CPU_PREQ_N")
	)
	(segment
		(start 283.80563 -87.203788)
		(end 283.78404 -87.203534)
		(width 0.0889)
		(layer "In4.Cu")
		(net "XDP_CPU_PREQ_N")
	)
	(segment
		(start 294.10787 -80.269334)
		(end 294.075104 -80.269334)
		(width 0.0889)
		(layer "In4.Cu")
		(net "XDP_CPU_PREQ_N")
	)
	(segment
		(start 360.787188 -137.820908)
		(end 362.986066 -137.820908)
		(width 0.089408)
		(layer "In4.Cu")
		(net "XDP_CPU_PREQ_N")
	)
	(segment
		(start 293.24554 -80.764888)
		(end 293.212774 -80.764888)
		(width 0.0889)
		(layer "In4.Cu")
		(net "XDP_CPU_PREQ_N")
	)
	(segment
		(start 349.643954 -133.72592)
		(end 350.141032 -134.222998)
		(width 0.089408)
		(layer "In4.Cu")
		(net "XDP_CPU_PREQ_N")
	)
	(segment
		(start 346.7989 -133.72592)
		(end 349.643954 -133.72592)
		(width 0.089408)
		(layer "In4.Cu")
		(net "XDP_CPU_PREQ_N")
	)
	(segment
		(start 194.003676 -132.584444)
		(end 193.940176 -132.647944)
		(width 0.089408)
		(layer "In4.Cu")
		(net "XDP_CPU_PREQ_N")
	)
	(segment
		(start 296.310304 -69.469)
		(end 296.31513 -69.477636)
		(width 0.0889)
		(layer "In4.Cu")
		(net "XDP_CPU_PREQ_N")
	)
	(segment
		(start 344.809826 -111.173006)
		(end 344.809826 -116.311934)
		(width 0.089408)
		(layer "In4.Cu")
		(net "XDP_CPU_PREQ_N")
	)
	(segment
		(start 251.93498 -87.384636)
		(end 251.902214 -87.384636)
		(width 0.0889)
		(layer "In4.Cu")
		(net "XDP_CPU_PREQ_N")
	)
	(segment
		(start 267.873226 -91.347798)
		(end 267.377164 -91.347798)
		(width 0.0889)
		(layer "In4.Cu")
		(net "XDP_CPU_PREQ_N")
	)
	(segment
		(start 248.5009 -82.43189)
		(end 248.47677 -82.43189)
		(width 0.0889)
		(layer "In4.Cu")
		(net "XDP_CPU_PREQ_N")
	)
	(segment
		(start 357.189278 -134.222998)
		(end 360.787188 -137.820908)
		(width 0.089408)
		(layer "In4.Cu")
		(net "XDP_CPU_PREQ_N")
	)
	(segment
		(start 460.238602 -145.310352)
		(end 460.238602 -143.353282)
		(width 0.089408)
		(layer "In4.Cu")
		(net "XDP_CPU_PREQ_N")
	)
	(segment
		(start 241.643408 -81.441036)
		(end 241.600228 -81.441036)
		(width 0.0889)
		(layer "In4.Cu")
		(net "XDP_CPU_PREQ_N")
	)
	(segment
		(start 265.681206 -91.347036)
		(end 265.638026 -91.347036)
		(width 0.0889)
		(layer "In4.Cu")
		(net "XDP_CPU_PREQ_N")
	)
	(segment
		(start 350.141032 -134.222998)
		(end 357.189278 -134.222998)
		(width 0.089408)
		(layer "In4.Cu")
		(net "XDP_CPU_PREQ_N")
	)
	(segment
		(start 352.942398 -90.862912)
		(end 352.006408 -91.798902)
		(width 0.089408)
		(layer "In4.Cu")
		(net "XDP_CPU_PREQ_N")
	)
	(segment
		(start 420.97071 -141.154404)
		(end 434.356256 -141.154404)
		(width 0.089408)
		(layer "In4.Cu")
		(net "XDP_CPU_PREQ_N")
	)
	(segment
		(start 444.3349 -139.683744)
		(end 446.980056 -139.683744)
		(width 0.089408)
		(layer "In4.Cu")
		(net "XDP_CPU_PREQ_N")
	)
	(segment
		(start 296.31513 -72.449436)
		(end 296.32148 -72.460104)
		(width 0.0889)
		(layer "In4.Cu")
		(net "XDP_CPU_PREQ_N")
	)
	(segment
		(start 261.382256 -90.85199)
		(end 261.34949 -90.85199)
		(width 0.0889)
		(layer "In4.Cu")
		(net "XDP_CPU_PREQ_N")
	)
	(segment
		(start 250.5583 -84.621624)
		(end 250.553474 -84.612988)
		(width 0.0889)
		(layer "In4.Cu")
		(net "XDP_CPU_PREQ_N")
	)
	(segment
		(start 343.6874 -110.05058)
		(end 344.809826 -111.173006)
		(width 0.089408)
		(layer "In4.Cu")
		(net "XDP_CPU_PREQ_N")
	)
	(segment
		(start 297.382184 -68.287138)
		(end 297.294808 -68.374514)
		(width 0.089408)
		(layer "In4.Cu")
		(net "XDP_CPU_PREQ_N")
	)
	(segment
		(start 279.509474 -89.680288)
		(end 279.476708 -89.680288)
		(width 0.0889)
		(layer "In4.Cu")
		(net "XDP_CPU_PREQ_N")
	)
	(segment
		(start 393.34186 -140.77823)
		(end 397.42491 -140.77823)
		(width 0.089408)
		(layer "In4.Cu")
		(net "XDP_CPU_PREQ_N")
	)
	(segment
		(start 275.199348 -90.175334)
		(end 275.188172 -90.175334)
		(width 0.0889)
		(layer "In4.Cu")
		(net "XDP_CPU_PREQ_N")
	)
	(segment
		(start 348.527624 -92.690696)
		(end 337.984338 -92.690696)
		(width 0.089408)
		(layer "In4.Cu")
		(net "XDP_CPU_PREQ_N")
	)
	(segment
		(start 337.984338 -92.690696)
		(end 334.317848 -96.357186)
		(width 0.089408)
		(layer "In4.Cu")
		(net "XDP_CPU_PREQ_N")
	)
	(segment
		(start 257.09626 -89.365836)
		(end 257.063494 -89.365836)
		(width 0.0889)
		(layer "In4.Cu")
		(net "XDP_CPU_PREQ_N")
	)
	(segment
		(start 280.371804 -89.184734)
		(end 280.339038 -89.184734)
		(width 0.0889)
		(layer "In4.Cu")
		(net "XDP_CPU_PREQ_N")
	)
	(segment
		(start 233.772456 -80.911446)
		(end 233.585512 -80.911446)
		(width 0.089408)
		(layer "In4.Cu")
		(net "XDP_CPU_PREQ_N")
	)
	(segment
		(start 458.730096 -138.474704)
		(end 458.730096 -134.461504)
		(width 0.089408)
		(layer "In4.Cu")
		(net "XDP_CPU_PREQ_N")
	)
	(segment
		(start 217.094054 -91.42476)
		(end 217.094054 -96.049846)
		(width 0.089408)
		(layer "In4.Cu")
		(net "XDP_CPU_PREQ_N")
	)
	(segment
		(start 404.461726 -144.68094)
		(end 405.66721 -145.886424)
		(width 0.089408)
		(layer "In4.Cu")
		(net "XDP_CPU_PREQ_N")
	)
	(segment
		(start 250.5583 -85.612224)
		(end 250.553474 -85.603588)
		(width 0.0889)
		(layer "In4.Cu")
		(net "XDP_CPU_PREQ_N")
	)
	(segment
		(start 264.816082 -90.85199)
		(end 264.801096 -90.85199)
		(width 0.0889)
		(layer "In4.Cu")
		(net "XDP_CPU_PREQ_N")
	)
	(segment
		(start 352.006408 -91.798902)
		(end 349.419418 -91.798902)
		(width 0.089408)
		(layer "In4.Cu")
		(net "XDP_CPU_PREQ_N")
	)
	(segment
		(start 252.79731 -87.88019)
		(end 252.764544 -87.88019)
		(width 0.0889)
		(layer "In4.Cu")
		(net "XDP_CPU_PREQ_N")
	)
	(segment
		(start 246.78386 -81.441036)
		(end 246.751094 -81.441036)
		(width 0.0889)
		(layer "In4.Cu")
		(net "XDP_CPU_PREQ_N")
	)
	(segment
		(start 242.826794 -81.146142)
		(end 242.823492 -81.1403)
		(width 0.0889)
		(layer "In4.Cu")
		(net "XDP_CPU_PREQ_N")
	)
	(segment
		(start 275.545804 -90.375486)
		(end 275.542502 -90.369644)
		(width 0.0889)
		(layer "In4.Cu")
		(net "XDP_CPU_PREQ_N")
	)
	(segment
		(start 250.224798 -83.42249)
		(end 250.185174 -83.42249)
		(width 0.0889)
		(layer "In4.Cu")
		(net "XDP_CPU_PREQ_N")
	)
	(segment
		(start 290.67379 -83.241134)
		(end 290.641024 -83.241134)
		(width 0.0889)
		(layer "In4.Cu")
		(net "XDP_CPU_PREQ_N")
	)
	(segment
		(start 269.908274 -90.862658)
		(end 268.358366 -90.862658)
		(width 0.0889)
		(layer "In4.Cu")
		(net "XDP_CPU_PREQ_N")
	)
	(segment
		(start 250.5583 -83.631024)
		(end 250.553474 -83.622388)
		(width 0.0889)
		(layer "In4.Cu")
		(net "XDP_CPU_PREQ_N")
	)
	(segment
		(start 458.743304 -134.448296)
		(end 458.743304 -132.97535)
		(width 0.089408)
		(layer "In4.Cu")
		(net "XDP_CPU_PREQ_N")
	)
	(segment
		(start 450.917056 -137.269982)
		(end 451.9168 -138.269726)
		(width 0.089408)
		(layer "In4.Cu")
		(net "XDP_CPU_PREQ_N")
	)
	(segment
		(start 213.41969 -97.886266)
		(end 209.696304 -101.609652)
		(width 0.089408)
		(layer "In4.Cu")
		(net "XDP_CPU_PREQ_N")
	)
	(segment
		(start 235.629958 -80.94599)
		(end 235.594398 -80.94599)
		(width 0.0889)
		(layer "In4.Cu")
		(net "XDP_CPU_PREQ_N")
	)
	(segment
		(start 440.813952 -139.035028)
		(end 440.813952 -138.965432)
		(width 0.089408)
		(layer "In4.Cu")
		(net "XDP_CPU_PREQ_N")
	)
	(segment
		(start 286.37738 -85.717888)
		(end 286.3596 -85.717888)
		(width 0.0889)
		(layer "In4.Cu")
		(net "XDP_CPU_PREQ_N")
	)
	(segment
		(start 392.431524 -139.867894)
		(end 393.34186 -140.77823)
		(width 0.089408)
		(layer "In4.Cu")
		(net "XDP_CPU_PREQ_N")
	)
	(segment
		(start 194.003676 -131.647692)
		(end 194.003676 -132.584444)
		(width 0.089408)
		(layer "In4.Cu")
		(net "XDP_CPU_PREQ_N")
	)
	(segment
		(start 296.31513 -71.458836)
		(end 296.32148 -71.469504)
		(width 0.0889)
		(layer "In4.Cu")
		(net "XDP_CPU_PREQ_N")
	)
	(segment
		(start 259.665216 -89.86139)
		(end 259.63245 -89.86139)
		(width 0.0889)
		(layer "In4.Cu")
		(net "XDP_CPU_PREQ_N")
	)
	(segment
		(start 349.419418 -91.798902)
		(end 348.527624 -92.690696)
		(width 0.089408)
		(layer "In4.Cu")
		(net "XDP_CPU_PREQ_N")
	)
	(segment
		(start 405.66721 -145.886424)
		(end 406.72893 -145.886424)
		(width 0.089408)
		(layer "In4.Cu")
		(net "XDP_CPU_PREQ_N")
	)
	(segment
		(start 278.654764 -90.175334)
		(end 278.621998 -90.175334)
		(width 0.0889)
		(layer "In4.Cu")
		(net "XDP_CPU_PREQ_N")
	)
	(segment
		(start 451.9168 -138.269726)
		(end 451.9168 -139.278106)
		(width 0.089408)
		(layer "In4.Cu")
		(net "XDP_CPU_PREQ_N")
	)
	(segment
		(start 434.356256 -141.154404)
		(end 435.826916 -139.683744)
		(width 0.089408)
		(layer "In4.Cu")
		(net "XDP_CPU_PREQ_N")
	)
	(segment
		(start 228.085142 -80.433672)
		(end 217.094054 -91.42476)
		(width 0.089408)
		(layer "In4.Cu")
		(net "XDP_CPU_PREQ_N")
	)
	(segment
		(start 296.310304 -72.4408)
		(end 296.31513 -72.449436)
		(width 0.0889)
		(layer "In4.Cu")
		(net "XDP_CPU_PREQ_N")
	)
	(segment
		(start 288.95675 -84.231734)
		(end 288.923984 -84.231734)
		(width 0.0889)
		(layer "In4.Cu")
		(net "XDP_CPU_PREQ_N")
	)
	(segment
		(start 398.476216 -141.829536)
		(end 399.54327 -141.829536)
		(width 0.089408)
		(layer "In4.Cu")
		(net "XDP_CPU_PREQ_N")
	)
	(segment
		(start 345.916504 -128.009904)
		(end 345.916504 -132.843524)
		(width 0.089408)
		(layer "In4.Cu")
		(net "XDP_CPU_PREQ_N")
	)
	(segment
		(start 217.094054 -96.049846)
		(end 216.917524 -96.491044)
		(width 0.089408)
		(layer "In4.Cu")
		(net "XDP_CPU_PREQ_N")
	)
	(segment
		(start 254.514096 -88.87079)
		(end 254.48133 -88.87079)
		(width 0.0889)
		(layer "In4.Cu")
		(net "XDP_CPU_PREQ_N")
	)
	(segment
		(start 292.39083 -82.250534)
		(end 292.358064 -82.250534)
		(width 0.0889)
		(layer "In4.Cu")
		(net "XDP_CPU_PREQ_N")
	)
	(segment
		(start 295.46296 -77.487018)
		(end 295.45661 -77.497686)
		(width 0.0889)
		(layer "In4.Cu")
		(net "XDP_CPU_PREQ_N")
	)
	(segment
		(start 358.264206 -85.848952)
		(end 358.264206 -87.098886)
		(width 0.089408)
		(layer "In4.Cu")
		(net "XDP_CPU_PREQ_N")
	)
	(segment
		(start 234.525058 -80.450436)
		(end 234.064048 -80.911446)
		(width 0.0889)
		(layer "In4.Cu")
		(net "XDP_CPU_PREQ_N")
	)
	(segment
		(start 257.948176 -88.87079)
		(end 257.918204 -88.87079)
		(width 0.0889)
		(layer "In4.Cu")
		(net "XDP_CPU_PREQ_N")
	)
	(segment
		(start 292.88105 -81.364836)
		(end 292.8874 -81.375504)
		(width 0.0889)
		(layer "In4.Cu")
		(net "XDP_CPU_PREQ_N")
	)
	(segment
		(start 237.346998 -80.94599)
		(end 237.311438 -80.94599)
		(width 0.0889)
		(layer "In4.Cu")
		(net "XDP_CPU_PREQ_N")
	)
	(segment
		(start 243.34978 -81.441036)
		(end 243.313712 -81.441036)
		(width 0.0889)
		(layer "In4.Cu")
		(net "XDP_CPU_PREQ_N")
	)
	(segment
		(start 250.553474 -86.594188)
		(end 250.547124 -86.58352)
		(width 0.0889)
		(layer "In4.Cu")
		(net "XDP_CPU_PREQ_N")
	)
	(segment
		(start 281.226514 -88.689688)
		(end 281.193748 -88.689688)
		(width 0.0889)
		(layer "In4.Cu")
		(net "XDP_CPU_PREQ_N")
	)
	(segment
		(start 296.31513 -73.440036)
		(end 296.32148 -73.450704)
		(width 0.0889)
		(layer "In4.Cu")
		(net "XDP_CPU_PREQ_N")
	)
	(segment
		(start 233.585512 -80.911446)
		(end 233.014266 -80.3402)
		(width 0.089408)
		(layer "In4.Cu")
		(net "XDP_CPU_PREQ_N")
	)
	(segment
		(start 281.723846 -88.388444)
		(end 281.720544 -88.394286)
		(width 0.0889)
		(layer "In4.Cu")
		(net "XDP_CPU_PREQ_N")
	)
	(segment
		(start 294.96258 -77.793088)
		(end 294.929814 -77.793088)
		(width 0.0889)
		(layer "In4.Cu")
		(net "XDP_CPU_PREQ_N")
	)
	(segment
		(start 459.488032 -142.602712)
		(end 459.488032 -141.727174)
		(width 0.089408)
		(layer "In4.Cu")
		(net "XDP_CPU_PREQ_N")
	)
	(segment
		(start 460.238602 -143.353282)
		(end 459.488032 -142.602712)
		(width 0.089408)
		(layer "In4.Cu")
		(net "XDP_CPU_PREQ_N")
	)
	(segment
		(start 343.6874 -106.428286)
		(end 343.6874 -110.05058)
		(width 0.089408)
		(layer "In4.Cu")
		(net "XDP_CPU_PREQ_N")
	)
	(segment
		(start 345.311476 -116.813584)
		(end 345.311476 -121.355358)
		(width 0.089408)
		(layer "In4.Cu")
		(net "XDP_CPU_PREQ_N")
	)
	(segment
		(start 365.81969 -140.654532)
		(end 370.435632 -140.654532)
		(width 0.089408)
		(layer "In4.Cu")
		(net "XDP_CPU_PREQ_N")
	)
	(segment
		(start 216.874598 -96.534224)
		(end 215.522556 -97.886266)
		(width 0.089408)
		(layer "In4.Cu")
		(net "XDP_CPU_PREQ_N")
	)
	(segment
		(start 370.843302 -140.246862)
		(end 384.693922 -140.246862)
		(width 0.089408)
		(layer "In4.Cu")
		(net "XDP_CPU_PREQ_N")
	)
	(segment
		(start 459.5749 -145.974054)
		(end 460.238602 -145.310352)
		(width 0.089408)
		(layer "In4.Cu")
		(net "XDP_CPU_PREQ_N")
	)
	(segment
		(start 443.14745 -138.496294)
		(end 444.3349 -139.683744)
		(width 0.089408)
		(layer "In4.Cu")
		(net "XDP_CPU_PREQ_N")
	)
	(segment
		(start 244.214904 -81.93659)
		(end 244.179344 -81.93659)
		(width 0.0889)
		(layer "In4.Cu")
		(net "XDP_CPU_PREQ_N")
	)
	(segment
		(start 362.986066 -137.820908)
		(end 365.81969 -140.654532)
		(width 0.089408)
		(layer "In4.Cu")
		(net "XDP_CPU_PREQ_N")
	)
	(segment
		(start 282.08859 -88.194388)
		(end 282.067 -88.194134)
		(width 0.0889)
		(layer "In4.Cu")
		(net "XDP_CPU_PREQ_N")
	)
	(segment
		(start 283.440886 -87.397844)
		(end 283.437584 -87.403686)
		(width 0.0889)
		(layer "In4.Cu")
		(net "XDP_CPU_PREQ_N")
	)
	(segment
		(start 345.916504 -132.843524)
		(end 346.7989 -133.72592)
		(width 0.089408)
		(layer "In4.Cu")
		(net "XDP_CPU_PREQ_N")
	)
	(segment
		(start 344.693494 -121.97334)
		(end 344.693494 -126.786894)
		(width 0.089408)
		(layer "In4.Cu")
		(net "XDP_CPU_PREQ_N")
	)
	(segment
		(start 296.310304 -74.422)
		(end 296.31513 -74.430636)
		(width 0.0889)
		(layer "In4.Cu")
		(net "XDP_CPU_PREQ_N")
	)
	(segment
		(start 449.393818 -137.269982)
		(end 450.917056 -137.269982)
		(width 0.089408)
		(layer "In4.Cu")
		(net "XDP_CPU_PREQ_N")
	)
	(segment
		(start 370.435632 -140.654532)
		(end 370.843302 -140.246862)
		(width 0.089408)
		(layer "In4.Cu")
		(net "XDP_CPU_PREQ_N")
	)
	(segment
		(start 194.780408 -116.647468)
		(end 194.780408 -130.87096)
		(width 0.089408)
		(layer "In4.Cu")
		(net "XDP_CPU_PREQ_N")
	)
	(segment
		(start 292.876224 -81.3562)
		(end 292.88105 -81.364836)
		(width 0.0889)
		(layer "In4.Cu")
		(net "XDP_CPU_PREQ_N")
	)
	(segment
		(start 270.100044 -90.670888)
		(end 269.908274 -90.862658)
		(width 0.0889)
		(layer "In4.Cu")
		(net "XDP_CPU_PREQ_N")
	)
	(segment
		(start 411.125416 -144.45615)
		(end 411.125416 -141.232636)
		(width 0.089408)
		(layer "In4.Cu")
		(net "XDP_CPU_PREQ_N")
	)
	(segment
		(start 263.967722 -91.347036)
		(end 263.92124 -91.347036)
		(width 0.0889)
		(layer "In4.Cu")
		(net "XDP_CPU_PREQ_N")
	)
	(segment
		(start 253.640844 -88.375236)
		(end 253.619254 -88.375236)
		(width 0.0889)
		(layer "In4.Cu")
		(net "XDP_CPU_PREQ_N")
	)
	(segment
		(start 245.077234 -81.441036)
		(end 245.044468 -81.441036)
		(width 0.0889)
		(layer "In4.Cu")
		(net "XDP_CPU_PREQ_N")
	)
	(segment
		(start 451.9168 -139.278106)
		(end 458.612748 -145.974054)
		(width 0.089408)
		(layer "In4.Cu")
		(net "XDP_CPU_PREQ_N")
	)
	(segment
		(start 291.523674 -82.746088)
		(end 291.495734 -82.746088)
		(width 0.0889)
		(layer "In4.Cu")
		(net "XDP_CPU_PREQ_N")
	)
	(segment
		(start 296.67962 -68.877688)
		(end 296.646854 -68.877688)
		(width 0.0889)
		(layer "In4.Cu")
		(net "XDP_CPU_PREQ_N")
	)
	(segment
		(start 334.317848 -96.357186)
		(end 334.317848 -102.41661)
		(width 0.089408)
		(layer "In4.Cu")
		(net "XDP_CPU_PREQ_N")
	)
	(segment
		(start 276.075394 -90.670888)
		(end 276.039834 -90.670888)
		(width 0.0889)
		(layer "In4.Cu")
		(net "XDP_CPU_PREQ_N")
	)
	(segment
		(start 399.54327 -141.829536)
		(end 400.422618 -142.708884)
		(width 0.089408)
		(layer "In4.Cu")
		(net "XDP_CPU_PREQ_N")
	)
	(segment
		(start 273.493484 -90.175334)
		(end 273.471132 -90.175334)
		(width 0.0889)
		(layer "In4.Cu")
		(net "XDP_CPU_PREQ_N")
	)
	(segment
		(start 441.289186 -138.559794)
		(end 441.352686 -138.496294)
		(width 0.089408)
		(layer "In4.Cu")
		(net "XDP_CPU_PREQ_N")
	)
	(segment
		(start 266.533122 -90.85199)
		(end 266.50315 -90.85199)
		(width 0.0889)
		(layer "In4.Cu")
		(net "XDP_CPU_PREQ_N")
	)
	(segment
		(start 384.693922 -140.246862)
		(end 385.07289 -139.867894)
		(width 0.089408)
		(layer "In4.Cu")
		(net "XDP_CPU_PREQ_N")
	)
	(segment
		(start 459.488032 -141.727174)
		(end 458.3684 -140.607542)
		(width 0.089408)
		(layer "In4.Cu")
		(net "XDP_CPU_PREQ_N")
	)
	(segment
		(start 335.629504 -103.728266)
		(end 340.98738 -103.728266)
		(width 0.089408)
		(layer "In4.Cu")
		(net "XDP_CPU_PREQ_N")
	)
	(segment
		(start 296.31513 -75.421236)
		(end 296.32148 -75.431904)
		(width 0.0889)
		(layer "In4.Cu")
		(net "XDP_CPU_PREQ_N")
	)
	(segment
		(start 239.061244 -80.94599)
		(end 239.028478 -80.94599)
		(width 0.0889)
		(layer "In4.Cu")
		(net "XDP_CPU_PREQ_N")
	)
	(segment
		(start 256.23393 -89.86139)
		(end 256.19837 -89.86139)
		(width 0.0889)
		(layer "In4.Cu")
		(net "XDP_CPU_PREQ_N")
	)
	(segment
		(start 458.730096 -134.461504)
		(end 458.743304 -134.448296)
		(width 0.089408)
		(layer "In4.Cu")
		(net "XDP_CPU_PREQ_N")
	)
	(segment
		(start 340.98738 -103.728266)
		(end 343.6874 -106.428286)
		(width 0.089408)
		(layer "In4.Cu")
		(net "XDP_CPU_PREQ_N")
	)
	(segment
		(start 264.457942 -91.0463)
		(end 264.45464 -91.052142)
		(width 0.0889)
		(layer "In4.Cu")
		(net "XDP_CPU_PREQ_N")
	)
	(segment
		(start 295.45661 -76.507086)
		(end 295.451784 -76.515722)
		(width 0.0889)
		(layer "In4.Cu")
		(net "XDP_CPU_PREQ_N")
	)
	(segment
		(start 208.63052 -102.727506)
		(end 196.07022 -115.287806)
		(width 0.089408)
		(layer "In4.Cu")
		(net "XDP_CPU_PREQ_N")
	)
	(segment
		(start 260.519926 -90.356436)
		(end 260.48716 -90.356436)
		(width 0.0889)
		(layer "In4.Cu")
		(net "XDP_CPU_PREQ_N")
	)
	(segment
		(start 296.310304 -71.4502)
		(end 296.31513 -71.458836)
		(width 0.0889)
		(layer "In4.Cu")
		(net "XDP_CPU_PREQ_N")
	)
	(segment
		(start 233.014266 -80.3402)
		(end 230.694484 -80.3402)
		(width 0.089408)
		(layer "In4.Cu")
		(net "XDP_CPU_PREQ_N")
	)
	(segment
		(start 287.23971 -85.222334)
		(end 287.206944 -85.222334)
		(width 0.0889)
		(layer "In4.Cu")
		(net "XDP_CPU_PREQ_N")
	)
	(segment
		(start 441.21959 -138.559794)
		(end 441.289186 -138.559794)
		(width 0.089408)
		(layer "In4.Cu")
		(net "XDP_CPU_PREQ_N")
	)
	(segment
		(start 406.783794 -145.83156)
		(end 409.750006 -145.83156)
		(width 0.089408)
		(layer "In4.Cu")
		(net "XDP_CPU_PREQ_N")
	)
	(segment
		(start 258.802886 -89.365836)
		(end 258.77012 -89.365836)
		(width 0.0889)
		(layer "In4.Cu")
		(net "XDP_CPU_PREQ_N")
	)
	(segment
		(start 274.358608 -90.670888)
		(end 274.323048 -90.670888)
		(width 0.0889)
		(layer "In4.Cu")
		(net "XDP_CPU_PREQ_N")
	)
	(segment
		(start 288.09442 -84.727288)
		(end 288.061654 -84.727288)
		(width 0.0889)
		(layer "In4.Cu")
		(net "XDP_CPU_PREQ_N")
	)
	(segment
		(start 296.310304 -75.4126)
		(end 296.31513 -75.421236)
		(width 0.0889)
		(layer "In4.Cu")
		(net "XDP_CPU_PREQ_N")
	)
	(segment
		(start 345.311476 -121.355358)
		(end 344.693494 -121.97334)
		(width 0.089408)
		(layer "In4.Cu")
		(net "XDP_CPU_PREQ_N")
	)
	(segment
		(start 296.310304 -73.4314)
		(end 296.31513 -73.440036)
		(width 0.0889)
		(layer "In4.Cu")
		(net "XDP_CPU_PREQ_N")
	)
	(segment
		(start 458.612748 -145.974054)
		(end 459.5749 -145.974054)
		(width 0.089408)
		(layer "In4.Cu")
		(net "XDP_CPU_PREQ_N")
	)
	(segment
		(start 285.526226 -86.212934)
		(end 285.490158 -86.212934)
		(width 0.0889)
		(layer "In4.Cu")
		(net "XDP_CPU_PREQ_N")
	)
	(segment
		(start 272.641568 -90.670888)
		(end 270.100044 -90.670888)
		(width 0.0889)
		(layer "In4.Cu")
		(net "XDP_CPU_PREQ_N")
	)
	(segment
		(start 230.694484 -80.3402)
		(end 230.601012 -80.433672)
		(width 0.089408)
		(layer "In4.Cu")
		(net "XDP_CPU_PREQ_N")
	)
	(segment
		(start 397.42491 -140.77823)
		(end 398.476216 -141.829536)
		(width 0.089408)
		(layer "In4.Cu")
		(net "XDP_CPU_PREQ_N")
	)
	(segment
		(start 458.3684 -140.607542)
		(end 458.3684 -138.8364)
		(width 0.089408)
		(layer "In4.Cu")
		(net "XDP_CPU_PREQ_N")
	)
	(segment
		(start 277.792434 -90.670888)
		(end 277.756874 -90.670888)
		(width 0.0889)
		(layer "In4.Cu")
		(net "XDP_CPU_PREQ_N")
	)
	(segment
		(start 435.826916 -139.683744)
		(end 440.165236 -139.683744)
		(width 0.089408)
		(layer "In4.Cu")
		(net "XDP_CPU_PREQ_N")
	)
	(segment
		(start 255.368806 -89.365836)
		(end 255.33604 -89.365836)
		(width 0.0889)
		(layer "In4.Cu")
		(net "XDP_CPU_PREQ_N")
	)
	(segment
		(start 294.59809 -79.383636)
		(end 294.60444 -79.394304)
		(width 0.0889)
		(layer "In4.Cu")
		(net "XDP_CPU_PREQ_N")
	)
	(segment
		(start 196.07022 -115.287806)
		(end 196.07022 -115.357656)
		(width 0.089408)
		(layer "In4.Cu")
		(net "XDP_CPU_PREQ_N")
	)
	(segment
		(start 354.50018 -90.862912)
		(end 352.942398 -90.862912)
		(width 0.089408)
		(layer "In4.Cu")
		(net "XDP_CPU_PREQ_N")
	)
	(segment
		(start 253.9873 -88.575388)
		(end 253.983998 -88.569546)
		(width 0.0889)
		(layer "In4.Cu")
		(net "XDP_CPU_PREQ_N")
	)
	(segment
		(start 215.522556 -97.886266)
		(end 213.41969 -97.886266)
		(width 0.089408)
		(layer "In4.Cu")
		(net "XDP_CPU_PREQ_N")
	)
	(segment
		(start 276.92731 -90.175334)
		(end 276.904958 -90.175334)
		(width 0.0889)
		(layer "In4.Cu")
		(net "XDP_CPU_PREQ_N")
	)
	(segment
		(start 209.461862 -102.727506)
		(end 208.63052 -102.727506)
		(width 0.089408)
		(layer "In4.Cu")
		(net "XDP_CPU_PREQ_N")
	)
	(segment
		(start 385.07289 -139.867894)
		(end 392.431524 -139.867894)
		(width 0.089408)
		(layer "In4.Cu")
		(net "XDP_CPU_PREQ_N")
	)
	(segment
		(start 286.016446 -85.912198)
		(end 286.013144 -85.91804)
		(width 0.0889)
		(layer "In4.Cu")
		(net "XDP_CPU_PREQ_N")
	)
	(segment
		(start 216.917524 -96.491044)
		(end 216.874598 -96.534224)
		(width 0.089408)
		(layer "In4.Cu")
		(net "XDP_CPU_PREQ_N")
	)
	(segment
		(start 411.832298 -140.525754)
		(end 420.34206 -140.525754)
		(width 0.089408)
		(layer "In4.Cu")
		(net "XDP_CPU_PREQ_N")
	)
	(segment
		(start 209.696304 -101.609652)
		(end 209.696304 -102.493064)
		(width 0.089408)
		(layer "In4.Cu")
		(net "XDP_CPU_PREQ_N")
	)
	(segment
		(start 250.553474 -85.603588)
		(end 250.547124 -85.59292)
		(width 0.0889)
		(layer "In4.Cu")
		(net "XDP_CPU_PREQ_N")
	)
	(segment
		(start 400.422618 -143.839184)
		(end 401.264374 -144.68094)
		(width 0.089408)
		(layer "In4.Cu")
		(net "XDP_CPU_PREQ_N")
	)
	(segment
		(start 295.82491 -76.306934)
		(end 295.792144 -76.306934)
		(width 0.0889)
		(layer "In4.Cu")
		(net "XDP_CPU_PREQ_N")
	)
	(segment
		(start 250.553474 -84.612988)
		(end 250.547124 -84.60232)
		(width 0.0889)
		(layer "In4.Cu")
		(net "XDP_CPU_PREQ_N")
	)
	(segment
		(start 262.24738 -91.347036)
		(end 262.2042 -91.347036)
		(width 0.0889)
		(layer "In4.Cu")
		(net "XDP_CPU_PREQ_N")
	)
	(segment
		(start 296.31513 -74.430636)
		(end 296.32148 -74.441304)
		(width 0.0889)
		(layer "In4.Cu")
		(net "XDP_CPU_PREQ_N")
	)
	(segment
		(start 334.317848 -102.41661)
		(end 335.629504 -103.728266)
		(width 0.089408)
		(layer "In4.Cu")
		(net "XDP_CPU_PREQ_N")
	)
	(segment
		(start 230.601012 -80.433672)
		(end 228.085142 -80.433672)
		(width 0.089408)
		(layer "In4.Cu")
		(net "XDP_CPU_PREQ_N")
	)
	(segment
		(start 297.294808 -68.374514)
		(end 297.17365 -68.582286)
		(width 0.0889)
		(layer "In4.Cu")
		(net "XDP_CPU_PREQ_N")
	)
	(segment
		(start 239.926368 -81.441036)
		(end 239.883188 -81.441036)
		(width 0.0889)
		(layer "In4.Cu")
		(net "XDP_CPU_PREQ_N")
	)
	(segment
		(start 240.778284 -80.94599)
		(end 240.748312 -80.94599)
		(width 0.0889)
		(layer "In4.Cu")
		(net "XDP_CPU_PREQ_N")
	)
	(segment
		(start 245.92915 -80.94599)
		(end 245.899178 -80.94599)
		(width 0.0889)
		(layer "In4.Cu")
		(net "XDP_CPU_PREQ_N")
	)
	(segment
		(start 298.378626 -68.287138)
		(end 297.382184 -68.287138)
		(width 0.089408)
		(layer "In4.Cu")
		(net "XDP_CPU_PREQ_N")
	)
	(segment
		(start 409.750006 -145.83156)
		(end 411.125416 -144.45615)
		(width 0.089408)
		(layer "In4.Cu")
		(net "XDP_CPU_PREQ_N")
	)
	(segment
		(start 247.64619 -81.93659)
		(end 247.613424 -81.93659)
		(width 0.0889)
		(layer "In4.Cu")
		(net "XDP_CPU_PREQ_N")
	)
	(segment
		(start 294.593264 -78.3844)
		(end 294.59809 -78.393036)
		(width 0.0889)
		(layer "In4.Cu")
		(net "XDP_CPU_PREQ_N")
	)
	(segment
		(start 282.943554 -87.699088)
		(end 282.910788 -87.699088)
		(width 0.0889)
		(layer "In4.Cu")
		(net "XDP_CPU_PREQ_N")
	)
	(arc
		(start 254.84582 -89.070688)
		(mid 254.705741 -88.927952)
		(end 254.514096 -88.87079)
		(width 0.0889)
		(layer "In4.Cu")
		(net "XDP_CPU_PREQ_N")
	)
	(arc
		(start 296.32148 -73.450704)
		(mid 296.394278 -73.741467)
		(end 296.31513 -74.030586)
		(width 0.0889)
		(layer "In4.Cu")
		(net "XDP_CPU_PREQ_N")
	)
	(arc
		(start 277.756874 -90.670888)
		(mid 277.47145 -90.587421)
		(end 277.262844 -90.375486)
		(width 0.0889)
		(layer "In4.Cu")
		(net "XDP_CPU_PREQ_N")
	)
	(arc
		(start 296.32148 -74.441304)
		(mid 296.394278 -74.732067)
		(end 296.31513 -75.021186)
		(width 0.0889)
		(layer "In4.Cu")
		(net "XDP_CPU_PREQ_N")
	)
	(arc
		(start 296.31513 -73.039986)
		(mid 296.26166 -73.235049)
		(end 296.310304 -73.4314)
		(width 0.0889)
		(layer "In4.Cu")
		(net "XDP_CPU_PREQ_N")
	)
	(arc
		(start 242.823492 -81.1403)
		(mid 242.476902 -80.94573)
		(end 242.133628 -81.145888)
		(width 0.0889)
		(layer "In4.Cu")
		(net "XDP_CPU_PREQ_N")
	)
	(arc
		(start 296.31513 -71.058786)
		(mid 296.26166 -71.253849)
		(end 296.310304 -71.4502)
		(width 0.0889)
		(layer "In4.Cu")
		(net "XDP_CPU_PREQ_N")
	)
	(arc
		(start 249.326654 -82.92719)
		(mid 249.043437 -82.842909)
		(end 248.836434 -82.632042)
		(width 0.0889)
		(layer "In4.Cu")
		(net "XDP_CPU_PREQ_N")
	)
	(arc
		(start 250.185174 -83.42249)
		(mid 249.901957 -83.338209)
		(end 249.694954 -83.127342)
		(width 0.0889)
		(layer "In4.Cu")
		(net "XDP_CPU_PREQ_N")
	)
	(arc
		(start 241.110008 -81.145888)
		(mid 240.969929 -81.003152)
		(end 240.778284 -80.94599)
		(width 0.0889)
		(layer "In4.Cu")
		(net "XDP_CPU_PREQ_N")
	)
	(arc
		(start 292.88105 -81.955386)
		(mid 292.674046 -82.16625)
		(end 292.39083 -82.250534)
		(width 0.0889)
		(layer "In4.Cu")
		(net "XDP_CPU_PREQ_N")
	)
	(arc
		(start 251.902214 -87.384636)
		(mid 251.618997 -87.300355)
		(end 251.411994 -87.089488)
		(width 0.0889)
		(layer "In4.Cu")
		(net "XDP_CPU_PREQ_N")
	)
	(arc
		(start 266.50315 -90.85199)
		(mid 266.311508 -90.909156)
		(end 266.171426 -91.051888)
		(width 0.0889)
		(layer "In4.Cu")
		(net "XDP_CPU_PREQ_N")
	)
	(arc
		(start 277.262844 -90.375486)
		(mid 277.121161 -90.231682)
		(end 276.92731 -90.175334)
		(width 0.0889)
		(layer "In4.Cu")
		(net "XDP_CPU_PREQ_N")
	)
	(arc
		(start 273.471132 -90.175334)
		(mid 273.277282 -90.231684)
		(end 273.135598 -90.375486)
		(width 0.0889)
		(layer "In4.Cu")
		(net "XDP_CPU_PREQ_N")
	)
	(arc
		(start 267.377164 -91.347798)
		(mid 267.081364 -91.268494)
		(end 266.864846 -91.051888)
		(width 0.0889)
		(layer "In4.Cu")
		(net "XDP_CPU_PREQ_N")
	)
	(arc
		(start 294.075104 -80.269334)
		(mid 293.881254 -80.325684)
		(end 293.73957 -80.469486)
		(width 0.0889)
		(layer "In4.Cu")
		(net "XDP_CPU_PREQ_N")
	)
	(arc
		(start 282.067 -88.194134)
		(mid 281.869839 -88.246093)
		(end 281.723846 -88.388444)
		(width 0.0889)
		(layer "In4.Cu")
		(net "XDP_CPU_PREQ_N")
	)
	(arc
		(start 288.923984 -84.231734)
		(mid 288.730134 -84.288084)
		(end 288.58845 -84.431886)
		(width 0.0889)
		(layer "In4.Cu")
		(net "XDP_CPU_PREQ_N")
	)
	(arc
		(start 294.59809 -77.992986)
		(mid 294.54462 -78.188049)
		(end 294.593264 -78.3844)
		(width 0.0889)
		(layer "In4.Cu")
		(net "XDP_CPU_PREQ_N")
	)
	(arc
		(start 236.817408 -80.650588)
		(mid 236.470698 -80.450277)
		(end 236.123988 -80.650588)
		(width 0.0889)
		(layer "In4.Cu")
		(net "XDP_CPU_PREQ_N")
	)
	(arc
		(start 253.619254 -88.375236)
		(mid 253.336037 -88.290955)
		(end 253.129034 -88.080088)
		(width 0.0889)
		(layer "In4.Cu")
		(net "XDP_CPU_PREQ_N")
	)
	(arc
		(start 247.977914 -82.136488)
		(mid 247.837835 -81.993752)
		(end 247.64619 -81.93659)
		(width 0.0889)
		(layer "In4.Cu")
		(net "XDP_CPU_PREQ_N")
	)
	(arc
		(start 240.748312 -80.94599)
		(mid 240.55667 -81.003156)
		(end 240.416588 -81.145888)
		(width 0.0889)
		(layer "In4.Cu")
		(net "XDP_CPU_PREQ_N")
	)
	(arc
		(start 254.48133 -88.87079)
		(mid 254.195906 -88.787323)
		(end 253.9873 -88.575388)
		(width 0.0889)
		(layer "In4.Cu")
		(net "XDP_CPU_PREQ_N")
	)
	(arc
		(start 291.495734 -82.746088)
		(mid 291.304092 -82.803254)
		(end 291.16401 -82.945986)
		(width 0.0889)
		(layer "In4.Cu")
		(net "XDP_CPU_PREQ_N")
	)
	(arc
		(start 285.154624 -86.413086)
		(mid 284.946016 -86.625018)
		(end 284.660594 -86.708488)
		(width 0.0889)
		(layer "In4.Cu")
		(net "XDP_CPU_PREQ_N")
	)
	(arc
		(start 247.613424 -81.93659)
		(mid 247.328 -81.853123)
		(end 247.119394 -81.641188)
		(width 0.0889)
		(layer "In4.Cu")
		(net "XDP_CPU_PREQ_N")
	)
	(arc
		(start 293.212774 -80.764888)
		(mid 293.021132 -80.822054)
		(end 292.88105 -80.964786)
		(width 0.0889)
		(layer "In4.Cu")
		(net "XDP_CPU_PREQ_N")
	)
	(arc
		(start 281.193748 -88.689688)
		(mid 281.002106 -88.746854)
		(end 280.862024 -88.889586)
		(width 0.0889)
		(layer "In4.Cu")
		(net "XDP_CPU_PREQ_N")
	)
	(arc
		(start 246.260874 -81.145888)
		(mid 246.120795 -81.003152)
		(end 245.92915 -80.94599)
		(width 0.0889)
		(layer "In4.Cu")
		(net "XDP_CPU_PREQ_N")
	)
	(arc
		(start 262.7376 -91.051888)
		(mid 262.530596 -91.262752)
		(end 262.24738 -91.347036)
		(width 0.0889)
		(layer "In4.Cu")
		(net "XDP_CPU_PREQ_N")
	)
	(arc
		(start 250.553474 -84.022438)
		(mid 250.606944 -83.827375)
		(end 250.5583 -83.631024)
		(width 0.0889)
		(layer "In4.Cu")
		(net "XDP_CPU_PREQ_N")
	)
	(arc
		(start 274.323048 -90.670888)
		(mid 274.037624 -90.587421)
		(end 273.829018 -90.375486)
		(width 0.0889)
		(layer "In4.Cu")
		(net "XDP_CPU_PREQ_N")
	)
	(arc
		(start 293.73957 -80.469486)
		(mid 293.530962 -80.681418)
		(end 293.24554 -80.764888)
		(width 0.0889)
		(layer "In4.Cu")
		(net "XDP_CPU_PREQ_N")
	)
	(arc
		(start 248.47677 -82.43189)
		(mid 248.188625 -82.349571)
		(end 247.977914 -82.136488)
		(width 0.0889)
		(layer "In4.Cu")
		(net "XDP_CPU_PREQ_N")
	)
	(arc
		(start 294.59809 -79.974186)
		(mid 294.391086 -80.18505)
		(end 294.10787 -80.269334)
		(width 0.0889)
		(layer "In4.Cu")
		(net "XDP_CPU_PREQ_N")
	)
	(arc
		(start 239.883188 -81.441036)
		(mid 239.599971 -81.356755)
		(end 239.392968 -81.145888)
		(width 0.0889)
		(layer "In4.Cu")
		(net "XDP_CPU_PREQ_N")
	)
	(arc
		(start 266.171426 -91.051888)
		(mid 265.964422 -91.262752)
		(end 265.681206 -91.347036)
		(width 0.0889)
		(layer "In4.Cu")
		(net "XDP_CPU_PREQ_N")
	)
	(arc
		(start 256.19837 -89.86139)
		(mid 255.912946 -89.777923)
		(end 255.70434 -89.565988)
		(width 0.0889)
		(layer "In4.Cu")
		(net "XDP_CPU_PREQ_N")
	)
	(arc
		(start 250.547124 -84.60232)
		(mid 250.474326 -84.311557)
		(end 250.553474 -84.022438)
		(width 0.0889)
		(layer "In4.Cu")
		(net "XDP_CPU_PREQ_N")
	)
	(arc
		(start 295.45661 -77.497686)
		(mid 295.248002 -77.709618)
		(end 294.96258 -77.793088)
		(width 0.0889)
		(layer "In4.Cu")
		(net "XDP_CPU_PREQ_N")
	)
	(arc
		(start 259.99694 -90.061288)
		(mid 259.856861 -89.918552)
		(end 259.665216 -89.86139)
		(width 0.0889)
		(layer "In4.Cu")
		(net "XDP_CPU_PREQ_N")
	)
	(arc
		(start 284.296104 -86.908386)
		(mid 284.089042 -87.119494)
		(end 283.80563 -87.203788)
		(width 0.0889)
		(layer "In4.Cu")
		(net "XDP_CPU_PREQ_N")
	)
	(arc
		(start 261.34949 -90.85199)
		(mid 261.064066 -90.768523)
		(end 260.85546 -90.556588)
		(width 0.0889)
		(layer "In4.Cu")
		(net "XDP_CPU_PREQ_N")
	)
	(arc
		(start 296.32148 -69.488304)
		(mid 296.394278 -69.779067)
		(end 296.31513 -70.068186)
		(width 0.0889)
		(layer "In4.Cu")
		(net "XDP_CPU_PREQ_N")
	)
	(arc
		(start 250.553474 -83.622388)
		(mid 250.41473 -83.480355)
		(end 250.224798 -83.42249)
		(width 0.0889)
		(layer "In4.Cu")
		(net "XDP_CPU_PREQ_N")
	)
	(arc
		(start 294.59809 -78.393036)
		(mid 294.677221 -78.688438)
		(end 294.59809 -78.98384)
		(width 0.0889)
		(layer "In4.Cu")
		(net "XDP_CPU_PREQ_N")
	)
	(arc
		(start 296.31513 -76.011786)
		(mid 296.108126 -76.22265)
		(end 295.82491 -76.306934)
		(width 0.0889)
		(layer "In4.Cu")
		(net "XDP_CPU_PREQ_N")
	)
	(arc
		(start 255.70434 -89.565988)
		(mid 255.562657 -89.422184)
		(end 255.368806 -89.365836)
		(width 0.0889)
		(layer "In4.Cu")
		(net "XDP_CPU_PREQ_N")
	)
	(arc
		(start 261.71398 -91.051888)
		(mid 261.573901 -90.909152)
		(end 261.382256 -90.85199)
		(width 0.0889)
		(layer "In4.Cu")
		(net "XDP_CPU_PREQ_N")
	)
	(arc
		(start 274.852638 -90.375486)
		(mid 274.64403 -90.587418)
		(end 274.358608 -90.670888)
		(width 0.0889)
		(layer "In4.Cu")
		(net "XDP_CPU_PREQ_N")
	)
	(arc
		(start 257.58648 -89.070688)
		(mid 257.379476 -89.281552)
		(end 257.09626 -89.365836)
		(width 0.0889)
		(layer "In4.Cu")
		(net "XDP_CPU_PREQ_N")
	)
	(arc
		(start 289.44697 -83.936586)
		(mid 289.239966 -84.14745)
		(end 288.95675 -84.231734)
		(width 0.0889)
		(layer "In4.Cu")
		(net "XDP_CPU_PREQ_N")
	)
	(arc
		(start 283.437584 -87.403686)
		(mid 283.228976 -87.615618)
		(end 282.943554 -87.699088)
		(width 0.0889)
		(layer "In4.Cu")
		(net "XDP_CPU_PREQ_N")
	)
	(arc
		(start 280.003504 -89.384886)
		(mid 279.794896 -89.596818)
		(end 279.509474 -89.680288)
		(width 0.0889)
		(layer "In4.Cu")
		(net "XDP_CPU_PREQ_N")
	)
	(arc
		(start 235.594398 -80.94599)
		(mid 235.308974 -80.862523)
		(end 235.100368 -80.650588)
		(width 0.0889)
		(layer "In4.Cu")
		(net "XDP_CPU_PREQ_N")
	)
	(arc
		(start 296.32148 -71.469504)
		(mid 296.394278 -71.760267)
		(end 296.31513 -72.049386)
		(width 0.0889)
		(layer "In4.Cu")
		(net "XDP_CPU_PREQ_N")
	)
	(arc
		(start 286.87141 -85.422486)
		(mid 286.662802 -85.634418)
		(end 286.37738 -85.717888)
		(width 0.0889)
		(layer "In4.Cu")
		(net "XDP_CPU_PREQ_N")
	)
	(arc
		(start 294.60444 -79.394304)
		(mid 294.677238 -79.685067)
		(end 294.59809 -79.974186)
		(width 0.0889)
		(layer "In4.Cu")
		(net "XDP_CPU_PREQ_N")
	)
	(arc
		(start 295.792144 -76.306934)
		(mid 295.598294 -76.363284)
		(end 295.45661 -76.507086)
		(width 0.0889)
		(layer "In4.Cu")
		(net "XDP_CPU_PREQ_N")
	)
	(arc
		(start 239.392968 -81.145888)
		(mid 239.252889 -81.003152)
		(end 239.061244 -80.94599)
		(width 0.0889)
		(layer "In4.Cu")
		(net "XDP_CPU_PREQ_N")
	)
	(arc
		(start 296.31513 -70.068186)
		(mid 296.261631 -70.268084)
		(end 296.31513 -70.467982)
		(width 0.0889)
		(layer "In4.Cu")
		(net "XDP_CPU_PREQ_N")
	)
	(arc
		(start 290.30549 -83.441286)
		(mid 290.096882 -83.653218)
		(end 289.81146 -83.736688)
		(width 0.0889)
		(layer "In4.Cu")
		(net "XDP_CPU_PREQ_N")
	)
	(arc
		(start 253.129034 -88.080088)
		(mid 252.988955 -87.937352)
		(end 252.79731 -87.88019)
		(width 0.0889)
		(layer "In4.Cu")
		(net "XDP_CPU_PREQ_N")
	)
	(arc
		(start 294.929814 -77.793088)
		(mid 294.738172 -77.850254)
		(end 294.59809 -77.992986)
		(width 0.0889)
		(layer "In4.Cu")
		(net "XDP_CPU_PREQ_N")
	)
	(arc
		(start 297.17365 -68.582286)
		(mid 296.965042 -68.794218)
		(end 296.67962 -68.877688)
		(width 0.0889)
		(layer "In4.Cu")
		(net "XDP_CPU_PREQ_N")
	)
	(arc
		(start 278.621998 -90.175334)
		(mid 278.428148 -90.231684)
		(end 278.286464 -90.375486)
		(width 0.0889)
		(layer "In4.Cu")
		(net "XDP_CPU_PREQ_N")
	)
	(arc
		(start 258.2799 -89.070688)
		(mid 258.139821 -88.927952)
		(end 257.948176 -88.87079)
		(width 0.0889)
		(layer "In4.Cu")
		(net "XDP_CPU_PREQ_N")
	)
	(arc
		(start 245.899178 -80.94599)
		(mid 245.707536 -81.003156)
		(end 245.567454 -81.145888)
		(width 0.0889)
		(layer "In4.Cu")
		(net "XDP_CPU_PREQ_N")
	)
	(arc
		(start 284.627828 -86.708488)
		(mid 284.436186 -86.765654)
		(end 284.296104 -86.908386)
		(width 0.0889)
		(layer "In4.Cu")
		(net "XDP_CPU_PREQ_N")
	)
	(arc
		(start 244.179344 -81.93659)
		(mid 243.89392 -81.853123)
		(end 243.685314 -81.641188)
		(width 0.0889)
		(layer "In4.Cu")
		(net "XDP_CPU_PREQ_N")
	)
	(arc
		(start 262.2042 -91.347036)
		(mid 261.920983 -91.262755)
		(end 261.71398 -91.051888)
		(width 0.0889)
		(layer "In4.Cu")
		(net "XDP_CPU_PREQ_N")
	)
	(arc
		(start 292.02253 -82.450686)
		(mid 291.811817 -82.663765)
		(end 291.523674 -82.746088)
		(width 0.0889)
		(layer "In4.Cu")
		(net "XDP_CPU_PREQ_N")
	)
	(arc
		(start 236.123988 -80.650588)
		(mid 235.91538 -80.86252)
		(end 235.629958 -80.94599)
		(width 0.0889)
		(layer "In4.Cu")
		(net "XDP_CPU_PREQ_N")
	)
	(arc
		(start 285.490158 -86.212934)
		(mid 285.296308 -86.269284)
		(end 285.154624 -86.413086)
		(width 0.0889)
		(layer "In4.Cu")
		(net "XDP_CPU_PREQ_N")
	)
	(arc
		(start 275.188172 -90.175334)
		(mid 274.994322 -90.231684)
		(end 274.852638 -90.375486)
		(width 0.0889)
		(layer "In4.Cu")
		(net "XDP_CPU_PREQ_N")
	)
	(arc
		(start 265.638026 -91.347036)
		(mid 265.354809 -91.262755)
		(end 265.147806 -91.051888)
		(width 0.0889)
		(layer "In4.Cu")
		(net "XDP_CPU_PREQ_N")
	)
	(arc
		(start 288.061654 -84.727288)
		(mid 287.870012 -84.784454)
		(end 287.72993 -84.927186)
		(width 0.0889)
		(layer "In4.Cu")
		(net "XDP_CPU_PREQ_N")
	)
	(arc
		(start 241.600228 -81.441036)
		(mid 241.317011 -81.356755)
		(end 241.110008 -81.145888)
		(width 0.0889)
		(layer "In4.Cu")
		(net "XDP_CPU_PREQ_N")
	)
	(arc
		(start 249.694954 -83.127342)
		(mid 249.553271 -82.983538)
		(end 249.35942 -82.92719)
		(width 0.0889)
		(layer "In4.Cu")
		(net "XDP_CPU_PREQ_N")
	)
	(arc
		(start 286.013144 -85.91804)
		(mid 285.807523 -86.127963)
		(end 285.526226 -86.212934)
		(width 0.0889)
		(layer "In4.Cu")
		(net "XDP_CPU_PREQ_N")
	)
	(arc
		(start 264.801096 -90.85199)
		(mid 264.603935 -90.903949)
		(end 264.457942 -91.0463)
		(width 0.0889)
		(layer "In4.Cu")
		(net "XDP_CPU_PREQ_N")
	)
	(arc
		(start 266.864846 -91.051888)
		(mid 266.724767 -90.909152)
		(end 266.533122 -90.85199)
		(width 0.0889)
		(layer "In4.Cu")
		(net "XDP_CPU_PREQ_N")
	)
	(arc
		(start 237.841028 -80.650588)
		(mid 237.63242 -80.86252)
		(end 237.346998 -80.94599)
		(width 0.0889)
		(layer "In4.Cu")
		(net "XDP_CPU_PREQ_N")
	)
	(arc
		(start 296.32148 -72.460104)
		(mid 296.394278 -72.750867)
		(end 296.31513 -73.039986)
		(width 0.0889)
		(layer "In4.Cu")
		(net "XDP_CPU_PREQ_N")
	)
	(arc
		(start 296.31513 -69.077586)
		(mid 296.26166 -69.272649)
		(end 296.310304 -69.469)
		(width 0.0889)
		(layer "In4.Cu")
		(net "XDP_CPU_PREQ_N")
	)
	(arc
		(start 288.58845 -84.431886)
		(mid 288.379842 -84.643818)
		(end 288.09442 -84.727288)
		(width 0.0889)
		(layer "In4.Cu")
		(net "XDP_CPU_PREQ_N")
	)
	(arc
		(start 296.646854 -68.877688)
		(mid 296.455212 -68.934854)
		(end 296.31513 -69.077586)
		(width 0.0889)
		(layer "In4.Cu")
		(net "XDP_CPU_PREQ_N")
	)
	(arc
		(start 251.047504 -86.88959)
		(mid 250.76208 -86.806123)
		(end 250.553474 -86.594188)
		(width 0.0889)
		(layer "In4.Cu")
		(net "XDP_CPU_PREQ_N")
	)
	(arc
		(start 296.31513 -75.021186)
		(mid 296.26166 -75.216249)
		(end 296.310304 -75.4126)
		(width 0.0889)
		(layer "In4.Cu")
		(net "XDP_CPU_PREQ_N")
	)
	(arc
		(start 296.31513 -72.049386)
		(mid 296.26166 -72.244449)
		(end 296.310304 -72.4408)
		(width 0.0889)
		(layer "In4.Cu")
		(net "XDP_CPU_PREQ_N")
	)
	(arc
		(start 248.836434 -82.632042)
		(mid 248.694751 -82.488238)
		(end 248.5009 -82.43189)
		(width 0.0889)
		(layer "In4.Cu")
		(net "XDP_CPU_PREQ_N")
	)
	(arc
		(start 273.829018 -90.375486)
		(mid 273.687335 -90.231682)
		(end 273.493484 -90.175334)
		(width 0.0889)
		(layer "In4.Cu")
		(net "XDP_CPU_PREQ_N")
	)
	(arc
		(start 242.133628 -81.145888)
		(mid 241.926624 -81.356752)
		(end 241.643408 -81.441036)
		(width 0.0889)
		(layer "In4.Cu")
		(net "XDP_CPU_PREQ_N")
	)
	(arc
		(start 240.416588 -81.145888)
		(mid 240.209584 -81.356752)
		(end 239.926368 -81.441036)
		(width 0.0889)
		(layer "In4.Cu")
		(net "XDP_CPU_PREQ_N")
	)
	(arc
		(start 283.78404 -87.203534)
		(mid 283.586879 -87.255493)
		(end 283.440886 -87.397844)
		(width 0.0889)
		(layer "In4.Cu")
		(net "XDP_CPU_PREQ_N")
	)
	(arc
		(start 279.144984 -89.880186)
		(mid 278.93798 -90.09105)
		(end 278.654764 -90.175334)
		(width 0.0889)
		(layer "In4.Cu")
		(net "XDP_CPU_PREQ_N")
	)
	(arc
		(start 295.451784 -76.515722)
		(mid 295.403029 -76.712074)
		(end 295.45661 -76.907136)
		(width 0.0889)
		(layer "In4.Cu")
		(net "XDP_CPU_PREQ_N")
	)
	(arc
		(start 276.039834 -90.670888)
		(mid 275.75441 -90.587421)
		(end 275.545804 -90.375486)
		(width 0.0889)
		(layer "In4.Cu")
		(net "XDP_CPU_PREQ_N")
	)
	(arc
		(start 243.685314 -81.641188)
		(mid 243.543631 -81.497384)
		(end 243.34978 -81.441036)
		(width 0.0889)
		(layer "In4.Cu")
		(net "XDP_CPU_PREQ_N")
	)
	(arc
		(start 250.547124 -86.58352)
		(mid 250.474326 -86.292757)
		(end 250.553474 -86.003638)
		(width 0.0889)
		(layer "In4.Cu")
		(net "XDP_CPU_PREQ_N")
	)
	(arc
		(start 259.63245 -89.86139)
		(mid 259.347026 -89.777923)
		(end 259.13842 -89.565988)
		(width 0.0889)
		(layer "In4.Cu")
		(net "XDP_CPU_PREQ_N")
	)
	(arc
		(start 244.708934 -81.641188)
		(mid 244.500326 -81.85312)
		(end 244.214904 -81.93659)
		(width 0.0889)
		(layer "In4.Cu")
		(net "XDP_CPU_PREQ_N")
	)
	(arc
		(start 276.569424 -90.375486)
		(mid 276.360816 -90.587418)
		(end 276.075394 -90.670888)
		(width 0.0889)
		(layer "In4.Cu")
		(net "XDP_CPU_PREQ_N")
	)
	(arc
		(start 257.918204 -88.87079)
		(mid 257.726562 -88.927956)
		(end 257.58648 -89.070688)
		(width 0.0889)
		(layer "In4.Cu")
		(net "XDP_CPU_PREQ_N")
	)
	(arc
		(start 292.358064 -82.250534)
		(mid 292.164214 -82.306884)
		(end 292.02253 -82.450686)
		(width 0.0889)
		(layer "In4.Cu")
		(net "XDP_CPU_PREQ_N")
	)
	(arc
		(start 281.720544 -88.394286)
		(mid 281.511936 -88.606218)
		(end 281.226514 -88.689688)
		(width 0.0889)
		(layer "In4.Cu")
		(net "XDP_CPU_PREQ_N")
	)
	(arc
		(start 296.31513 -74.030586)
		(mid 296.26166 -74.225649)
		(end 296.310304 -74.422)
		(width 0.0889)
		(layer "In4.Cu")
		(net "XDP_CPU_PREQ_N")
	)
	(arc
		(start 253.983998 -88.569546)
		(mid 253.838032 -88.427147)
		(end 253.640844 -88.375236)
		(width 0.0889)
		(layer "In4.Cu")
		(net "XDP_CPU_PREQ_N")
	)
	(arc
		(start 250.553474 -85.013038)
		(mid 250.606944 -84.817975)
		(end 250.5583 -84.621624)
		(width 0.0889)
		(layer "In4.Cu")
		(net "XDP_CPU_PREQ_N")
	)
	(arc
		(start 238.534448 -80.650588)
		(mid 238.187738 -80.450277)
		(end 237.841028 -80.650588)
		(width 0.0889)
		(layer "In4.Cu")
		(net "XDP_CPU_PREQ_N")
	)
	(arc
		(start 290.641024 -83.241134)
		(mid 290.447174 -83.297484)
		(end 290.30549 -83.441286)
		(width 0.0889)
		(layer "In4.Cu")
		(net "XDP_CPU_PREQ_N")
	)
	(arc
		(start 246.751094 -81.441036)
		(mid 246.467877 -81.356755)
		(end 246.260874 -81.145888)
		(width 0.0889)
		(layer "In4.Cu")
		(net "XDP_CPU_PREQ_N")
	)
	(arc
		(start 239.028478 -80.94599)
		(mid 238.743054 -80.862523)
		(end 238.534448 -80.650588)
		(width 0.0889)
		(layer "In4.Cu")
		(net "XDP_CPU_PREQ_N")
	)
	(arc
		(start 260.85546 -90.556588)
		(mid 260.713777 -90.412784)
		(end 260.519926 -90.356436)
		(width 0.0889)
		(layer "In4.Cu")
		(net "XDP_CPU_PREQ_N")
	)
	(arc
		(start 289.778694 -83.736688)
		(mid 289.587052 -83.793854)
		(end 289.44697 -83.936586)
		(width 0.0889)
		(layer "In4.Cu")
		(net "XDP_CPU_PREQ_N")
	)
	(arc
		(start 276.904958 -90.175334)
		(mid 276.711108 -90.231684)
		(end 276.569424 -90.375486)
		(width 0.0889)
		(layer "In4.Cu")
		(net "XDP_CPU_PREQ_N")
	)
	(arc
		(start 296.32148 -75.431904)
		(mid 296.394278 -75.722667)
		(end 296.31513 -76.011786)
		(width 0.0889)
		(layer "In4.Cu")
		(net "XDP_CPU_PREQ_N")
	)
	(arc
		(start 294.59809 -78.98384)
		(mid 294.544591 -79.183738)
		(end 294.59809 -79.383636)
		(width 0.0889)
		(layer "In4.Cu")
		(net "XDP_CPU_PREQ_N")
	)
	(arc
		(start 247.119394 -81.641188)
		(mid 246.977711 -81.497384)
		(end 246.78386 -81.441036)
		(width 0.0889)
		(layer "In4.Cu")
		(net "XDP_CPU_PREQ_N")
	)
	(arc
		(start 296.31513 -70.467982)
		(mid 296.394261 -70.763384)
		(end 296.31513 -71.058786)
		(width 0.0889)
		(layer "In4.Cu")
		(net "XDP_CPU_PREQ_N")
	)
	(arc
		(start 282.579064 -87.898986)
		(mid 282.372002 -88.110094)
		(end 282.08859 -88.194388)
		(width 0.0889)
		(layer "In4.Cu")
		(net "XDP_CPU_PREQ_N")
	)
	(arc
		(start 250.547124 -85.59292)
		(mid 250.474326 -85.302157)
		(end 250.553474 -85.013038)
		(width 0.0889)
		(layer "In4.Cu")
		(net "XDP_CPU_PREQ_N")
	)
	(arc
		(start 245.044468 -81.441036)
		(mid 244.850618 -81.497386)
		(end 244.708934 -81.641188)
		(width 0.0889)
		(layer "In4.Cu")
		(net "XDP_CPU_PREQ_N")
	)
	(arc
		(start 278.286464 -90.375486)
		(mid 278.077856 -90.587418)
		(end 277.792434 -90.670888)
		(width 0.0889)
		(layer "In4.Cu")
		(net "XDP_CPU_PREQ_N")
	)
	(arc
		(start 250.553474 -86.003638)
		(mid 250.606944 -85.808575)
		(end 250.5583 -85.612224)
		(width 0.0889)
		(layer "In4.Cu")
		(net "XDP_CPU_PREQ_N")
	)
	(arc
		(start 263.43102 -91.051888)
		(mid 263.08431 -90.851704)
		(end 262.7376 -91.051888)
		(width 0.0889)
		(layer "In4.Cu")
		(net "XDP_CPU_PREQ_N")
	)
	(arc
		(start 292.88105 -80.964786)
		(mid 292.82758 -81.159849)
		(end 292.876224 -81.3562)
		(width 0.0889)
		(layer "In4.Cu")
		(net "XDP_CPU_PREQ_N")
	)
	(arc
		(start 237.311438 -80.94599)
		(mid 237.026014 -80.862523)
		(end 236.817408 -80.650588)
		(width 0.0889)
		(layer "In4.Cu")
		(net "XDP_CPU_PREQ_N")
	)
	(arc
		(start 291.16401 -82.945986)
		(mid 290.957006 -83.15685)
		(end 290.67379 -83.241134)
		(width 0.0889)
		(layer "In4.Cu")
		(net "XDP_CPU_PREQ_N")
	)
	(arc
		(start 292.8874 -81.375504)
		(mid 292.960198 -81.666267)
		(end 292.88105 -81.955386)
		(width 0.0889)
		(layer "In4.Cu")
		(net "XDP_CPU_PREQ_N")
	)
	(arc
		(start 258.77012 -89.365836)
		(mid 258.486903 -89.281555)
		(end 258.2799 -89.070688)
		(width 0.0889)
		(layer "In4.Cu")
		(net "XDP_CPU_PREQ_N")
	)
	(arc
		(start 280.339038 -89.184734)
		(mid 280.145188 -89.241084)
		(end 280.003504 -89.384886)
		(width 0.0889)
		(layer "In4.Cu")
		(net "XDP_CPU_PREQ_N")
	)
	(arc
		(start 286.3596 -85.717888)
		(mid 286.162439 -85.769847)
		(end 286.016446 -85.912198)
		(width 0.0889)
		(layer "In4.Cu")
		(net "XDP_CPU_PREQ_N")
	)
	(arc
		(start 263.92124 -91.347036)
		(mid 263.638023 -91.262755)
		(end 263.43102 -91.051888)
		(width 0.0889)
		(layer "In4.Cu")
		(net "XDP_CPU_PREQ_N")
	)
	(arc
		(start 280.862024 -88.889586)
		(mid 280.65502 -89.10045)
		(end 280.371804 -89.184734)
		(width 0.0889)
		(layer "In4.Cu")
		(net "XDP_CPU_PREQ_N")
	)
	(arc
		(start 295.45661 -76.907136)
		(mid 295.535832 -77.196254)
		(end 295.46296 -77.487018)
		(width 0.0889)
		(layer "In4.Cu")
		(net "XDP_CPU_PREQ_N")
	)
	(arc
		(start 282.910788 -87.699088)
		(mid 282.719146 -87.756254)
		(end 282.579064 -87.898986)
		(width 0.0889)
		(layer "In4.Cu")
		(net "XDP_CPU_PREQ_N")
	)
	(arc
		(start 256.72796 -89.565988)
		(mid 256.519352 -89.77792)
		(end 256.23393 -89.86139)
		(width 0.0889)
		(layer "In4.Cu")
		(net "XDP_CPU_PREQ_N")
	)
	(arc
		(start 275.542502 -90.369644)
		(mid 275.396536 -90.227245)
		(end 275.199348 -90.175334)
		(width 0.0889)
		(layer "In4.Cu")
		(net "XDP_CPU_PREQ_N")
	)
	(arc
		(start 287.72993 -84.927186)
		(mid 287.522926 -85.13805)
		(end 287.23971 -85.222334)
		(width 0.0889)
		(layer "In4.Cu")
		(net "XDP_CPU_PREQ_N")
	)
	(arc
		(start 252.764544 -87.88019)
		(mid 252.47912 -87.796723)
		(end 252.270514 -87.584788)
		(width 0.0889)
		(layer "In4.Cu")
		(net "XDP_CPU_PREQ_N")
	)
	(arc
		(start 273.135598 -90.375486)
		(mid 272.92699 -90.587418)
		(end 272.641568 -90.670888)
		(width 0.0889)
		(layer "In4.Cu")
		(net "XDP_CPU_PREQ_N")
	)
	(arc
		(start 257.063494 -89.365836)
		(mid 256.869644 -89.422186)
		(end 256.72796 -89.565988)
		(width 0.0889)
		(layer "In4.Cu")
		(net "XDP_CPU_PREQ_N")
	)
	(arc
		(start 245.567454 -81.145888)
		(mid 245.36045 -81.356752)
		(end 245.077234 -81.441036)
		(width 0.0889)
		(layer "In4.Cu")
		(net "XDP_CPU_PREQ_N")
	)
	(arc
		(start 252.270514 -87.584788)
		(mid 252.128831 -87.440984)
		(end 251.93498 -87.384636)
		(width 0.0889)
		(layer "In4.Cu")
		(net "XDP_CPU_PREQ_N")
	)
	(arc
		(start 265.147806 -91.051888)
		(mid 265.007727 -90.909152)
		(end 264.816082 -90.85199)
		(width 0.0889)
		(layer "In4.Cu")
		(net "XDP_CPU_PREQ_N")
	)
	(arc
		(start 287.206944 -85.222334)
		(mid 287.013094 -85.278684)
		(end 286.87141 -85.422486)
		(width 0.0889)
		(layer "In4.Cu")
		(net "XDP_CPU_PREQ_N")
	)
	(arc
		(start 259.13842 -89.565988)
		(mid 258.996737 -89.422184)
		(end 258.802886 -89.365836)
		(width 0.0889)
		(layer "In4.Cu")
		(net "XDP_CPU_PREQ_N")
	)
	(arc
		(start 255.33604 -89.365836)
		(mid 255.052823 -89.281555)
		(end 254.84582 -89.070688)
		(width 0.0889)
		(layer "In4.Cu")
		(net "XDP_CPU_PREQ_N")
	)
	(arc
		(start 260.48716 -90.356436)
		(mid 260.203943 -90.272155)
		(end 259.99694 -90.061288)
		(width 0.0889)
		(layer "In4.Cu")
		(net "XDP_CPU_PREQ_N")
	)
	(arc
		(start 251.411994 -87.089488)
		(mid 251.271915 -86.946752)
		(end 251.08027 -86.88959)
		(width 0.0889)
		(layer "In4.Cu")
		(net "XDP_CPU_PREQ_N")
	)
	(arc
		(start 243.313712 -81.441036)
		(mid 243.032412 -81.35607)
		(end 242.826794 -81.146142)
		(width 0.0889)
		(layer "In4.Cu")
		(net "XDP_CPU_PREQ_N")
	)
	(arc
		(start 235.100368 -80.650588)
		(mid 234.958685 -80.506784)
		(end 234.764834 -80.450436)
		(width 0.0889)
		(layer "In4.Cu")
		(net "XDP_CPU_PREQ_N")
	)
	(arc
		(start 279.476708 -89.680288)
		(mid 279.285066 -89.737454)
		(end 279.144984 -89.880186)
		(width 0.0889)
		(layer "In4.Cu")
		(net "XDP_CPU_PREQ_N")
	)
	(arc
		(start 264.45464 -91.052142)
		(mid 264.249019 -91.262065)
		(end 263.967722 -91.347036)
		(width 0.0889)
		(layer "In4.Cu")
		(net "XDP_CPU_PREQ_N")
	)
	(segment
		(start 358.270048 -85.854794)
		(end 358.270048 -86.459568)
		(width 0.089408)
		(layer "In9.Cu")
		(net "XDP_CPU_PREQ_N")
	)
	(segment
		(start 358.264206 -85.848952)
		(end 358.270048 -85.854794)
		(width 0.089408)
		(layer "In9.Cu")
		(net "XDP_CPU_PREQ_N")
	)
	(segment
		(start 358.270048 -86.459568)
		(end 357.913432 -86.816184)
		(width 0.089408)
		(layer "In9.Cu")
		(net "XDP_CPU_PREQ_N")
	)
	(segment
		(start 354.276406 -65.383664)
		(end 355.562408 -64.097662)
		(width 0.089408)
		(layer "In9.Cu")
		(net "XDP_CPU_PREQ_N")
	)
	(segment
		(start 356.269544 -86.816184)
		(end 354.216716 -84.763356)
		(width 0.089408)
		(layer "In9.Cu")
		(net "XDP_CPU_PREQ_N")
	)
	(segment
		(start 350.208088 -78.910688)
		(end 350.208088 -73.993502)
		(width 0.089408)
		(layer "In9.Cu")
		(net "XDP_CPU_PREQ_N")
	)
	(segment
		(start 352.177096 -80.144874)
		(end 351.331022 -79.2988)
		(width 0.089408)
		(layer "In9.Cu")
		(net "XDP_CPU_PREQ_N")
	)
	(segment
		(start 350.5962 -79.2988)
		(end 350.208088 -78.910688)
		(width 0.089408)
		(layer "In9.Cu")
		(net "XDP_CPU_PREQ_N")
	)
	(segment
		(start 354.216716 -84.763356)
		(end 354.216716 -83.769708)
		(width 0.089408)
		(layer "In9.Cu")
		(net "XDP_CPU_PREQ_N")
	)
	(segment
		(start 354.27666 -66.888868)
		(end 354.276406 -66.888614)
		(width 0.089408)
		(layer "In9.Cu")
		(net "XDP_CPU_PREQ_N")
	)
	(segment
		(start 352.177096 -81.730088)
		(end 352.177096 -80.144874)
		(width 0.089408)
		(layer "In9.Cu")
		(net "XDP_CPU_PREQ_N")
	)
	(segment
		(start 354.216716 -83.769708)
		(end 352.177096 -81.730088)
		(width 0.089408)
		(layer "In9.Cu")
		(net "XDP_CPU_PREQ_N")
	)
	(segment
		(start 351.331022 -79.2988)
		(end 350.5962 -79.2988)
		(width 0.089408)
		(layer "In9.Cu")
		(net "XDP_CPU_PREQ_N")
	)
	(segment
		(start 354.27666 -69.92493)
		(end 354.27666 -66.888868)
		(width 0.089408)
		(layer "In9.Cu")
		(net "XDP_CPU_PREQ_N")
	)
	(segment
		(start 357.913432 -86.816184)
		(end 356.269544 -86.816184)
		(width 0.089408)
		(layer "In9.Cu")
		(net "XDP_CPU_PREQ_N")
	)
	(segment
		(start 354.276406 -66.888614)
		(end 354.276406 -65.383664)
		(width 0.089408)
		(layer "In9.Cu")
		(net "XDP_CPU_PREQ_N")
	)
	(segment
		(start 350.208088 -73.993502)
		(end 354.27666 -69.92493)
		(width 0.089408)
		(layer "In9.Cu")
		(net "XDP_CPU_PREQ_N")
	)
	(segment
		(start 169.888916 -105.944416)
		(end 168.001696 -104.057196)
		(width 0.089408)
		(layer "In11.Cu")
		(net "XDP_CPU_PREQ_N")
	)
	(segment
		(start 305.234594 -66.896742)
		(end 305.26736 -66.896742)
		(width 0.089408)
		(layer "In11.Cu")
		(net "XDP_CPU_PREQ_N")
	)
	(segment
		(start 300.60773 -67.592194)
		(end 300.611032 -67.586352)
		(width 0.089408)
		(layer "In11.Cu")
		(net "XDP_CPU_PREQ_N")
	)
	(segment
		(start 302.664114 -67.391788)
		(end 302.695356 -67.391788)
		(width 0.089408)
		(layer "In11.Cu")
		(net "XDP_CPU_PREQ_N")
	)
	(segment
		(start 306.37988 -66.401188)
		(end 306.568602 -66.58991)
		(width 0.089408)
		(layer "In11.Cu")
		(net "XDP_CPU_PREQ_N")
	)
	(segment
		(start 177.224944 -131.200398)
		(end 176.515776 -130.49123)
		(width 0.089408)
		(layer "In11.Cu")
		(net "XDP_CPU_PREQ_N")
	)
	(segment
		(start 174.960534 -108.43514)
		(end 172.46981 -105.944416)
		(width 0.089408)
		(layer "In11.Cu")
		(net "XDP_CPU_PREQ_N")
	)
	(segment
		(start 135.96493 -69.372734)
		(end 135.932164 -69.372734)
		(width 0.0889)
		(layer "In11.Cu")
		(net "XDP_CPU_PREQ_N")
	)
	(segment
		(start 306.568602 -66.58991)
		(end 308.64302 -66.58991)
		(width 0.089408)
		(layer "In11.Cu")
		(net "XDP_CPU_PREQ_N")
	)
	(segment
		(start 306.098194 -66.401188)
		(end 306.37988 -66.401188)
		(width 0.089408)
		(layer "In11.Cu")
		(net "XDP_CPU_PREQ_N")
	)
	(segment
		(start 140.87983 -72.54621)
		(end 140.593064 -72.049386)
		(width 0.0889)
		(layer "In11.Cu")
		(net "XDP_CPU_PREQ_N")
	)
	(segment
		(start 176.515776 -130.49123)
		(end 176.515776 -129.140458)
		(width 0.089408)
		(layer "In11.Cu")
		(net "XDP_CPU_PREQ_N")
	)
	(segment
		(start 174.960534 -124.042678)
		(end 174.960534 -108.43514)
		(width 0.089408)
		(layer "In11.Cu")
		(net "XDP_CPU_PREQ_N")
	)
	(segment
		(start 176.515776 -129.140458)
		(end 174.304706 -126.929388)
		(width 0.089408)
		(layer "In11.Cu")
		(net "XDP_CPU_PREQ_N")
	)
	(segment
		(start 141.97711 -73.876154)
		(end 141.97711 -73.64349)
		(width 0.089408)
		(layer "In11.Cu")
		(net "XDP_CPU_PREQ_N")
	)
	(segment
		(start 298.378626 -68.287138)
		(end 298.378626 -67.949318)
		(width 0.089408)
		(layer "In11.Cu")
		(net "XDP_CPU_PREQ_N")
	)
	(segment
		(start 335.81594 -64.426338)
		(end 355.233732 -64.426338)
		(width 0.089408)
		(layer "In11.Cu")
		(net "XDP_CPU_PREQ_N")
	)
	(segment
		(start 139.39901 -71.353934)
		(end 139.366244 -71.353934)
		(width 0.0889)
		(layer "In11.Cu")
		(net "XDP_CPU_PREQ_N")
	)
	(segment
		(start 185.515758 -128.55194)
		(end 182.8673 -131.200398)
		(width 0.089408)
		(layer "In11.Cu")
		(net "XDP_CPU_PREQ_N")
	)
	(segment
		(start 168.001696 -104.057196)
		(end 168.001696 -99.90074)
		(width 0.089408)
		(layer "In11.Cu")
		(net "XDP_CPU_PREQ_N")
	)
	(segment
		(start 355.233732 -64.426338)
		(end 355.562408 -64.097662)
		(width 0.089408)
		(layer "In11.Cu")
		(net "XDP_CPU_PREQ_N")
	)
	(segment
		(start 192.323212 -130.100578)
		(end 190.774574 -128.55194)
		(width 0.089408)
		(layer "In11.Cu")
		(net "XDP_CPU_PREQ_N")
	)
	(segment
		(start 137.68197 -70.363334)
		(end 137.649204 -70.363334)
		(width 0.0889)
		(layer "In11.Cu")
		(net "XDP_CPU_PREQ_N")
	)
	(segment
		(start 190.774574 -128.55194)
		(end 185.515758 -128.55194)
		(width 0.089408)
		(layer "In11.Cu")
		(net "XDP_CPU_PREQ_N")
	)
	(segment
		(start 303.970182 -67.219068)
		(end 304.143156 -67.392042)
		(width 0.089408)
		(layer "In11.Cu")
		(net "XDP_CPU_PREQ_N")
	)
	(segment
		(start 174.304706 -124.698506)
		(end 174.960534 -124.042678)
		(width 0.089408)
		(layer "In11.Cu")
		(net "XDP_CPU_PREQ_N")
	)
	(segment
		(start 134.24789 -68.382134)
		(end 134.215124 -68.382134)
		(width 0.0889)
		(layer "In11.Cu")
		(net "XDP_CPU_PREQ_N")
	)
	(segment
		(start 141.97711 -73.64349)
		(end 140.87983 -72.54621)
		(width 0.089408)
		(layer "In11.Cu")
		(net "XDP_CPU_PREQ_N")
	)
	(segment
		(start 331.586078 -68.6562)
		(end 335.81594 -64.426338)
		(width 0.089408)
		(layer "In11.Cu")
		(net "XDP_CPU_PREQ_N")
	)
	(segment
		(start 193.81089 -132.77723)
		(end 193.21653 -132.77723)
		(width 0.089408)
		(layer "In11.Cu")
		(net "XDP_CPU_PREQ_N")
	)
	(segment
		(start 310.70931 -68.6562)
		(end 331.586078 -68.6562)
		(width 0.089408)
		(layer "In11.Cu")
		(net "XDP_CPU_PREQ_N")
	)
	(segment
		(start 135.11022 -68.877688)
		(end 135.077454 -68.877688)
		(width 0.0889)
		(layer "In11.Cu")
		(net "XDP_CPU_PREQ_N")
	)
	(segment
		(start 140.26134 -71.849488)
		(end 140.228574 -71.849488)
		(width 0.0889)
		(layer "In11.Cu")
		(net "XDP_CPU_PREQ_N")
	)
	(segment
		(start 193.21653 -132.77723)
		(end 192.323212 -131.883912)
		(width 0.089408)
		(layer "In11.Cu")
		(net "XDP_CPU_PREQ_N")
	)
	(segment
		(start 304.143156 -67.392042)
		(end 304.404776 -67.392042)
		(width 0.089408)
		(layer "In11.Cu")
		(net "XDP_CPU_PREQ_N")
	)
	(segment
		(start 192.323212 -131.883912)
		(end 192.323212 -130.100578)
		(width 0.089408)
		(layer "In11.Cu")
		(net "XDP_CPU_PREQ_N")
	)
	(segment
		(start 182.8673 -131.200398)
		(end 177.224944 -131.200398)
		(width 0.089408)
		(layer "In11.Cu")
		(net "XDP_CPU_PREQ_N")
	)
	(segment
		(start 168.001696 -99.90074)
		(end 141.97711 -73.876154)
		(width 0.089408)
		(layer "In11.Cu")
		(net "XDP_CPU_PREQ_N")
	)
	(segment
		(start 193.940176 -132.647944)
		(end 193.81089 -132.77723)
		(width 0.089408)
		(layer "In11.Cu")
		(net "XDP_CPU_PREQ_N")
	)
	(segment
		(start 174.304706 -126.929388)
		(end 174.304706 -124.698506)
		(width 0.089408)
		(layer "In11.Cu")
		(net "XDP_CPU_PREQ_N")
	)
	(segment
		(start 308.64302 -66.58991)
		(end 310.70931 -68.6562)
		(width 0.089408)
		(layer "In11.Cu")
		(net "XDP_CPU_PREQ_N")
	)
	(segment
		(start 301.29734 -67.586352)
		(end 301.300642 -67.592194)
		(width 0.089408)
		(layer "In11.Cu")
		(net "XDP_CPU_PREQ_N")
	)
	(segment
		(start 303.517554 -66.896742)
		(end 303.541938 -66.896742)
		(width 0.089408)
		(layer "In11.Cu")
		(net "XDP_CPU_PREQ_N")
	)
	(segment
		(start 298.378626 -67.949318)
		(end 298.44365 -67.884294)
		(width 0.089408)
		(layer "In11.Cu")
		(net "XDP_CPU_PREQ_N")
	)
	(segment
		(start 138.5443 -70.858888)
		(end 138.51636 -70.858888)
		(width 0.0889)
		(layer "In11.Cu")
		(net "XDP_CPU_PREQ_N")
	)
	(segment
		(start 172.46981 -105.944416)
		(end 169.888916 -105.944416)
		(width 0.089408)
		(layer "In11.Cu")
		(net "XDP_CPU_PREQ_N")
	)
	(segment
		(start 136.830308 -69.868288)
		(end 136.794494 -69.868288)
		(width 0.0889)
		(layer "In11.Cu")
		(net "XDP_CPU_PREQ_N")
	)
	(arc
		(start 137.158984 -70.068186)
		(mid 137.02024 -69.926153)
		(end 136.830308 -69.868288)
		(width 0.0889)
		(layer "In11.Cu")
		(net "XDP_CPU_PREQ_N")
	)
	(arc
		(start 138.51636 -70.858888)
		(mid 138.228215 -70.776569)
		(end 138.017504 -70.563486)
		(width 0.0889)
		(layer "In11.Cu")
		(net "XDP_CPU_PREQ_N")
	)
	(arc
		(start 134.215124 -68.382134)
		(mid 133.793972 -68.358309)
		(end 133.378194 -68.287138)
		(width 0.0889)
		(layer "In11.Cu")
		(net "XDP_CPU_PREQ_N")
	)
	(arc
		(start 301.300642 -67.592194)
		(mid 301.812816 -67.887826)
		(end 302.32477 -67.59194)
		(width 0.089408)
		(layer "In11.Cu")
		(net "XDP_CPU_PREQ_N")
	)
	(arc
		(start 304.404776 -67.392042)
		(mid 304.691025 -67.308881)
		(end 304.90033 -67.09664)
		(width 0.089408)
		(layer "In11.Cu")
		(net "XDP_CPU_PREQ_N")
	)
	(arc
		(start 139.734544 -71.554086)
		(mid 139.592861 -71.410282)
		(end 139.39901 -71.353934)
		(width 0.0889)
		(layer "In11.Cu")
		(net "XDP_CPU_PREQ_N")
	)
	(arc
		(start 140.228574 -71.849488)
		(mid 139.94315 -71.766021)
		(end 139.734544 -71.554086)
		(width 0.0889)
		(layer "In11.Cu")
		(net "XDP_CPU_PREQ_N")
	)
	(arc
		(start 303.876202 -67.09664)
		(mid 303.919169 -67.160943)
		(end 303.970182 -67.219068)
		(width 0.089408)
		(layer "In11.Cu")
		(net "XDP_CPU_PREQ_N")
	)
	(arc
		(start 137.649204 -70.363334)
		(mid 137.365987 -70.279053)
		(end 137.158984 -70.068186)
		(width 0.0889)
		(layer "In11.Cu")
		(net "XDP_CPU_PREQ_N")
	)
	(arc
		(start 300.611032 -67.586352)
		(mid 300.954186 -67.391987)
		(end 301.29734 -67.586352)
		(width 0.089408)
		(layer "In11.Cu")
		(net "XDP_CPU_PREQ_N")
	)
	(arc
		(start 139.366244 -71.353934)
		(mid 139.083027 -71.269653)
		(end 138.876024 -71.058786)
		(width 0.0889)
		(layer "In11.Cu")
		(net "XDP_CPU_PREQ_N")
	)
	(arc
		(start 135.077454 -68.877688)
		(mid 134.79203 -68.794221)
		(end 134.583424 -68.582286)
		(width 0.0889)
		(layer "In11.Cu")
		(net "XDP_CPU_PREQ_N")
	)
	(arc
		(start 140.593064 -72.049386)
		(mid 140.452985 -71.90665)
		(end 140.26134 -71.849488)
		(width 0.0889)
		(layer "In11.Cu")
		(net "XDP_CPU_PREQ_N")
	)
	(arc
		(start 302.32477 -67.59194)
		(mid 302.468081 -67.447169)
		(end 302.664114 -67.391788)
		(width 0.089408)
		(layer "In11.Cu")
		(net "XDP_CPU_PREQ_N")
	)
	(arc
		(start 305.26736 -66.896742)
		(mid 305.551321 -66.812624)
		(end 305.75885 -66.60134)
		(width 0.089408)
		(layer "In11.Cu")
		(net "XDP_CPU_PREQ_N")
	)
	(arc
		(start 299.583602 -67.59194)
		(mid 300.095556 -67.887699)
		(end 300.60773 -67.592194)
		(width 0.089408)
		(layer "In11.Cu")
		(net "XDP_CPU_PREQ_N")
	)
	(arc
		(start 135.441944 -69.077586)
		(mid 135.301865 -68.93485)
		(end 135.11022 -68.877688)
		(width 0.0889)
		(layer "In11.Cu")
		(net "XDP_CPU_PREQ_N")
	)
	(arc
		(start 136.794494 -69.868288)
		(mid 136.50907 -69.784821)
		(end 136.300464 -69.572886)
		(width 0.0889)
		(layer "In11.Cu")
		(net "XDP_CPU_PREQ_N")
	)
	(arc
		(start 305.75885 -66.60134)
		(mid 305.902161 -66.456569)
		(end 306.098194 -66.401188)
		(width 0.089408)
		(layer "In11.Cu")
		(net "XDP_CPU_PREQ_N")
	)
	(arc
		(start 298.89069 -67.59194)
		(mid 299.237146 -67.391722)
		(end 299.583602 -67.59194)
		(width 0.089408)
		(layer "In11.Cu")
		(net "XDP_CPU_PREQ_N")
	)
	(arc
		(start 138.876024 -71.058786)
		(mid 138.735945 -70.91605)
		(end 138.5443 -70.858888)
		(width 0.0889)
		(layer "In11.Cu")
		(net "XDP_CPU_PREQ_N")
	)
	(arc
		(start 303.18329 -67.09664)
		(mid 303.324447 -66.953255)
		(end 303.517554 -66.896742)
		(width 0.089408)
		(layer "In11.Cu")
		(net "XDP_CPU_PREQ_N")
	)
	(arc
		(start 138.017504 -70.563486)
		(mid 137.875821 -70.419682)
		(end 137.68197 -70.363334)
		(width 0.0889)
		(layer "In11.Cu")
		(net "XDP_CPU_PREQ_N")
	)
	(arc
		(start 298.44365 -67.884294)
		(mid 298.702099 -67.791516)
		(end 298.89069 -67.59194)
		(width 0.089408)
		(layer "In11.Cu")
		(net "XDP_CPU_PREQ_N")
	)
	(arc
		(start 135.932164 -69.372734)
		(mid 135.648947 -69.288453)
		(end 135.441944 -69.077586)
		(width 0.0889)
		(layer "In11.Cu")
		(net "XDP_CPU_PREQ_N")
	)
	(arc
		(start 303.541938 -66.896742)
		(mid 303.735041 -66.953261)
		(end 303.876202 -67.09664)
		(width 0.089408)
		(layer "In11.Cu")
		(net "XDP_CPU_PREQ_N")
	)
	(arc
		(start 136.300464 -69.572886)
		(mid 136.158781 -69.429082)
		(end 135.96493 -69.372734)
		(width 0.0889)
		(layer "In11.Cu")
		(net "XDP_CPU_PREQ_N")
	)
	(arc
		(start 302.695356 -67.391788)
		(mid 302.977258 -67.306925)
		(end 303.18329 -67.09664)
		(width 0.089408)
		(layer "In11.Cu")
		(net "XDP_CPU_PREQ_N")
	)
	(arc
		(start 304.90033 -67.09664)
		(mid 305.041487 -66.953255)
		(end 305.234594 -66.896742)
		(width 0.089408)
		(layer "In11.Cu")
		(net "XDP_CPU_PREQ_N")
	)
	(arc
		(start 134.583424 -68.582286)
		(mid 134.441741 -68.438482)
		(end 134.24789 -68.382134)
		(width 0.0889)
		(layer "In11.Cu")
		(net "XDP_CPU_PREQ_N")
	)
	(segment
		(start 129.372868 -64.324738)
		(end 129.944368 -64.324738)
		(width 0.1016)
		(layer "F.Cu")
		(net "XDP_CPU_PRDY_N")
	)
	(segment
		(start 294.3733 -64.324738)
		(end 294.9448 -64.324738)
		(width 0.1016)
		(layer "F.Cu")
		(net "XDP_CPU_PRDY_N")
	)
	(via
		(at 462.646014 -134.35584)
		(size 0.6604)
		(drill 0.3302)
		(layers "F.Cu" "B.Cu")
		(net "XDP_CPU_PRDY_N")
	)
	(via
		(at 357.727504 -86.330028)
		(size 0.508)
		(drill 0.254)
		(layers "F.Cu" "B.Cu")
		(net "XDP_CPU_PRDY_N")
	)
	(via
		(at 129.944368 -64.324738)
		(size 0.508)
		(drill 0.254)
		(layers "F.Cu" "B.Cu")
		(net "XDP_CPU_PRDY_N")
	)
	(via
		(at 309.592472 -54.576726)
		(size 0.508)
		(drill 0.254)
		(layers "F.Cu" "B.Cu")
		(net "XDP_CPU_PRDY_N")
	)
	(via
		(at 181.13121 -22.511766)
		(size 0.508)
		(drill 0.254)
		(layers "F.Cu" "B.Cu")
		(net "XDP_CPU_PRDY_N")
	)
	(via
		(at 356.2096 -56.7944)
		(size 0.508)
		(drill 0.254)
		(layers "F.Cu" "B.Cu")
		(net "XDP_CPU_PRDY_N")
	)
	(via
		(at 461.412336 -134.757668)
		(size 0.508)
		(drill 0.254)
		(layers "F.Cu" "B.Cu")
		(net "XDP_CPU_PRDY_N")
	)
	(via
		(at 294.9448 -64.324738)
		(size 0.508)
		(drill 0.254)
		(layers "F.Cu" "B.Cu")
		(net "XDP_CPU_PRDY_N")
	)
	(segment
		(start 461.303116 -134.866888)
		(end 461.303116 -135.37438)
		(width 0.10795)
		(layer "B.Cu")
		(net "XDP_CPU_PRDY_N")
	)
	(segment
		(start 462.317846 -134.684008)
		(end 462.646014 -134.35584)
		(width 0.10795)
		(layer "B.Cu")
		(net "XDP_CPU_PRDY_N")
	)
	(segment
		(start 461.412336 -134.757668)
		(end 461.303116 -134.866888)
		(width 0.10795)
		(layer "B.Cu")
		(net "XDP_CPU_PRDY_N")
	)
	(segment
		(start 462.646014 -134.35584)
		(end 462.8896 -134.112254)
		(width 0.10795)
		(layer "B.Cu")
		(net "XDP_CPU_PRDY_N")
	)
	(segment
		(start 462.8896 -133.655054)
		(end 462.547208 -133.312662)
		(width 0.10795)
		(layer "B.Cu")
		(net "XDP_CPU_PRDY_N")
	)
	(segment
		(start 461.412336 -134.757668)
		(end 461.485996 -134.684008)
		(width 0.10795)
		(layer "B.Cu")
		(net "XDP_CPU_PRDY_N")
	)
	(segment
		(start 462.547208 -133.312662)
		(end 462.547208 -132.842254)
		(width 0.10795)
		(layer "B.Cu")
		(net "XDP_CPU_PRDY_N")
	)
	(segment
		(start 461.485996 -134.684008)
		(end 462.317846 -134.684008)
		(width 0.10795)
		(layer "B.Cu")
		(net "XDP_CPU_PRDY_N")
	)
	(segment
		(start 462.8896 -134.112254)
		(end 462.8896 -133.655054)
		(width 0.10795)
		(layer "B.Cu")
		(net "XDP_CPU_PRDY_N")
	)
	(segment
		(start 458.566774 -146.3421)
		(end 452.581264 -140.35659)
		(width 0.089408)
		(layer "In4.Cu")
		(net "XDP_CPU_PRDY_N")
	)
	(segment
		(start 412.173166 -143.129)
		(end 411.418024 -143.884142)
		(width 0.089408)
		(layer "In4.Cu")
		(net "XDP_CPU_PRDY_N")
	)
	(segment
		(start 345.018868 -116.934996)
		(end 344.517218 -116.433346)
		(width 0.089408)
		(layer "In4.Cu")
		(net "XDP_CPU_PRDY_N")
	)
	(segment
		(start 344.517218 -116.433346)
		(end 344.517218 -115.828572)
		(width 0.089408)
		(layer "In4.Cu")
		(net "XDP_CPU_PRDY_N")
	)
	(segment
		(start 461.412336 -134.757668)
		(end 460.947516 -135.222488)
		(width 0.089408)
		(layer "In4.Cu")
		(net "XDP_CPU_PRDY_N")
	)
	(segment
		(start 459.620874 -146.3421)
		(end 458.566774 -146.3421)
		(width 0.089408)
		(layer "In4.Cu")
		(net "XDP_CPU_PRDY_N")
	)
	(segment
		(start 441.341002 -138.852402)
		(end 441.10656 -139.086844)
		(width 0.089408)
		(layer "In4.Cu")
		(net "XDP_CPU_PRDY_N")
	)
	(segment
		(start 346.6846 -134.02564)
		(end 345.623896 -132.964936)
		(width 0.089408)
		(layer "In4.Cu")
		(net "XDP_CPU_PRDY_N")
	)
	(segment
		(start 406.850342 -146.179032)
		(end 405.528526 -146.179032)
		(width 0.089408)
		(layer "In4.Cu")
		(net "XDP_CPU_PRDY_N")
	)
	(segment
		(start 435.915816 -140.008864)
		(end 434.477668 -141.447012)
		(width 0.089408)
		(layer "In4.Cu")
		(net "XDP_CPU_PRDY_N")
	)
	(segment
		(start 441.10656 -139.15644)
		(end 440.254136 -140.008864)
		(width 0.089408)
		(layer "In4.Cu")
		(net "XDP_CPU_PRDY_N")
	)
	(segment
		(start 344.400886 -126.920498)
		(end 344.400886 -121.851928)
		(width 0.089408)
		(layer "In4.Cu")
		(net "XDP_CPU_PRDY_N")
	)
	(segment
		(start 441.410598 -138.852402)
		(end 441.341002 -138.852402)
		(width 0.089408)
		(layer "In4.Cu")
		(net "XDP_CPU_PRDY_N")
	)
	(segment
		(start 441.474098 -138.788902)
		(end 441.410598 -138.852402)
		(width 0.089408)
		(layer "In4.Cu")
		(net "XDP_CPU_PRDY_N")
	)
	(segment
		(start 365.698278 -140.94714)
		(end 364.019338 -139.2682)
		(width 0.089408)
		(layer "In4.Cu")
		(net "XDP_CPU_PRDY_N")
	)
	(segment
		(start 345.018868 -121.233946)
		(end 345.018868 -116.934996)
		(width 0.089408)
		(layer "In4.Cu")
		(net "XDP_CPU_PRDY_N")
	)
	(segment
		(start 393.220448 -141.070838)
		(end 392.310112 -140.160502)
		(width 0.089408)
		(layer "In4.Cu")
		(net "XDP_CPU_PRDY_N")
	)
	(segment
		(start 397.303498 -141.070838)
		(end 393.220448 -141.070838)
		(width 0.089408)
		(layer "In4.Cu")
		(net "XDP_CPU_PRDY_N")
	)
	(segment
		(start 344.517218 -115.828572)
		(end 343.618312 -114.929666)
		(width 0.089408)
		(layer "In4.Cu")
		(net "XDP_CPU_PRDY_N")
	)
	(segment
		(start 370.964714 -140.53947)
		(end 370.557044 -140.94714)
		(width 0.089408)
		(layer "In4.Cu")
		(net "XDP_CPU_PRDY_N")
	)
	(segment
		(start 343.618312 -114.929666)
		(end 343.618312 -110.834932)
		(width 0.089408)
		(layer "In4.Cu")
		(net "XDP_CPU_PRDY_N")
	)
	(segment
		(start 351.939606 -90.495882)
		(end 354.45319 -90.495882)
		(width 0.089408)
		(layer "In4.Cu")
		(net "XDP_CPU_PRDY_N")
	)
	(segment
		(start 385.194302 -140.160502)
		(end 384.815334 -140.53947)
		(width 0.089408)
		(layer "In4.Cu")
		(net "XDP_CPU_PRDY_N")
	)
	(segment
		(start 348.306644 -92.398088)
		(end 349.495618 -91.209114)
		(width 0.089408)
		(layer "In4.Cu")
		(net "XDP_CPU_PRDY_N")
	)
	(segment
		(start 364.019338 -139.2682)
		(end 361.82046 -139.2682)
		(width 0.089408)
		(layer "In4.Cu")
		(net "XDP_CPU_PRDY_N")
	)
	(segment
		(start 443.026038 -138.788902)
		(end 441.474098 -138.788902)
		(width 0.089408)
		(layer "In4.Cu")
		(net "XDP_CPU_PRDY_N")
	)
	(segment
		(start 342.94064 -106.095546)
		(end 340.866222 -104.021128)
		(width 0.089408)
		(layer "In4.Cu")
		(net "XDP_CPU_PRDY_N")
	)
	(segment
		(start 354.45319 -90.495882)
		(end 357.727504 -87.221568)
		(width 0.089408)
		(layer "In4.Cu")
		(net "XDP_CPU_PRDY_N")
	)
	(segment
		(start 411.418024 -144.577562)
		(end 409.871418 -146.124168)
		(width 0.089408)
		(layer "In4.Cu")
		(net "XDP_CPU_PRDY_N")
	)
	(segment
		(start 400.041618 -143.872204)
		(end 400.041618 -142.741904)
		(width 0.089408)
		(layer "In4.Cu")
		(net "XDP_CPU_PRDY_N")
	)
	(segment
		(start 460.947516 -135.222488)
		(end 460.947516 -138.8364)
		(width 0.089408)
		(layer "In4.Cu")
		(net "XDP_CPU_PRDY_N")
	)
	(segment
		(start 357.067866 -134.515606)
		(end 350.01962 -134.515606)
		(width 0.089408)
		(layer "In4.Cu")
		(net "XDP_CPU_PRDY_N")
	)
	(segment
		(start 411.418024 -143.884142)
		(end 411.418024 -144.577562)
		(width 0.089408)
		(layer "In4.Cu")
		(net "XDP_CPU_PRDY_N")
	)
	(segment
		(start 409.871418 -146.124168)
		(end 406.905206 -146.124168)
		(width 0.089408)
		(layer "In4.Cu")
		(net "XDP_CPU_PRDY_N")
	)
	(segment
		(start 334.02524 -102.538022)
		(end 334.02524 -96.235774)
		(width 0.089408)
		(layer "In4.Cu")
		(net "XDP_CPU_PRDY_N")
	)
	(segment
		(start 413.611314 -142.267686)
		(end 412.75 -143.129)
		(width 0.089408)
		(layer "In4.Cu")
		(net "XDP_CPU_PRDY_N")
	)
	(segment
		(start 392.310112 -140.160502)
		(end 385.194302 -140.160502)
		(width 0.089408)
		(layer "In4.Cu")
		(net "XDP_CPU_PRDY_N")
	)
	(segment
		(start 404.323042 -144.973548)
		(end 401.142962 -144.973548)
		(width 0.089408)
		(layer "In4.Cu")
		(net "XDP_CPU_PRDY_N")
	)
	(segment
		(start 344.400886 -121.851928)
		(end 345.018868 -121.233946)
		(width 0.089408)
		(layer "In4.Cu")
		(net "XDP_CPU_PRDY_N")
	)
	(segment
		(start 406.905206 -146.124168)
		(end 406.850342 -146.179032)
		(width 0.089408)
		(layer "In4.Cu")
		(net "XDP_CPU_PRDY_N")
	)
	(segment
		(start 460.947516 -138.8364)
		(end 460.576168 -139.207748)
		(width 0.089408)
		(layer "In4.Cu")
		(net "XDP_CPU_PRDY_N")
	)
	(segment
		(start 334.02524 -96.235774)
		(end 337.862926 -92.398088)
		(width 0.089408)
		(layer "In4.Cu")
		(net "XDP_CPU_PRDY_N")
	)
	(segment
		(start 441.10656 -139.086844)
		(end 441.10656 -139.15644)
		(width 0.089408)
		(layer "In4.Cu")
		(net "XDP_CPU_PRDY_N")
	)
	(segment
		(start 450.490844 -140.35659)
		(end 450.143118 -140.008864)
		(width 0.089408)
		(layer "In4.Cu")
		(net "XDP_CPU_PRDY_N")
	)
	(segment
		(start 357.727504 -87.221568)
		(end 357.727504 -86.330028)
		(width 0.089408)
		(layer "In4.Cu")
		(net "XDP_CPU_PRDY_N")
	)
	(segment
		(start 349.529654 -134.02564)
		(end 346.6846 -134.02564)
		(width 0.089408)
		(layer "In4.Cu")
		(net "XDP_CPU_PRDY_N")
	)
	(segment
		(start 452.581264 -140.35659)
		(end 450.490844 -140.35659)
		(width 0.089408)
		(layer "In4.Cu")
		(net "XDP_CPU_PRDY_N")
	)
	(segment
		(start 460.576168 -139.207748)
		(end 460.576168 -145.386806)
		(width 0.089408)
		(layer "In4.Cu")
		(net "XDP_CPU_PRDY_N")
	)
	(segment
		(start 400.041618 -142.741904)
		(end 399.421858 -142.122144)
		(width 0.089408)
		(layer "In4.Cu")
		(net "XDP_CPU_PRDY_N")
	)
	(segment
		(start 351.226374 -91.209114)
		(end 351.939606 -90.495882)
		(width 0.089408)
		(layer "In4.Cu")
		(net "XDP_CPU_PRDY_N")
	)
	(segment
		(start 416.6235 -142.267686)
		(end 413.611314 -142.267686)
		(width 0.089408)
		(layer "In4.Cu")
		(net "XDP_CPU_PRDY_N")
	)
	(segment
		(start 342.94064 -110.15726)
		(end 342.94064 -106.095546)
		(width 0.089408)
		(layer "In4.Cu")
		(net "XDP_CPU_PRDY_N")
	)
	(segment
		(start 434.477668 -141.447012)
		(end 417.444174 -141.447012)
		(width 0.089408)
		(layer "In4.Cu")
		(net "XDP_CPU_PRDY_N")
	)
	(segment
		(start 343.618312 -110.834932)
		(end 342.94064 -110.15726)
		(width 0.089408)
		(layer "In4.Cu")
		(net "XDP_CPU_PRDY_N")
	)
	(segment
		(start 340.866222 -104.021128)
		(end 335.508346 -104.021128)
		(width 0.089408)
		(layer "In4.Cu")
		(net "XDP_CPU_PRDY_N")
	)
	(segment
		(start 450.143118 -140.008864)
		(end 444.246 -140.008864)
		(width 0.089408)
		(layer "In4.Cu")
		(net "XDP_CPU_PRDY_N")
	)
	(segment
		(start 440.254136 -140.008864)
		(end 435.915816 -140.008864)
		(width 0.089408)
		(layer "In4.Cu")
		(net "XDP_CPU_PRDY_N")
	)
	(segment
		(start 417.444174 -141.447012)
		(end 416.6235 -142.267686)
		(width 0.089408)
		(layer "In4.Cu")
		(net "XDP_CPU_PRDY_N")
	)
	(segment
		(start 337.862926 -92.398088)
		(end 348.306644 -92.398088)
		(width 0.089408)
		(layer "In4.Cu")
		(net "XDP_CPU_PRDY_N")
	)
	(segment
		(start 401.142962 -144.973548)
		(end 400.041618 -143.872204)
		(width 0.089408)
		(layer "In4.Cu")
		(net "XDP_CPU_PRDY_N")
	)
	(segment
		(start 350.01962 -134.515606)
		(end 349.529654 -134.02564)
		(width 0.089408)
		(layer "In4.Cu")
		(net "XDP_CPU_PRDY_N")
	)
	(segment
		(start 399.421858 -142.122144)
		(end 398.354804 -142.122144)
		(width 0.089408)
		(layer "In4.Cu")
		(net "XDP_CPU_PRDY_N")
	)
	(segment
		(start 349.495618 -91.209114)
		(end 351.226374 -91.209114)
		(width 0.089408)
		(layer "In4.Cu")
		(net "XDP_CPU_PRDY_N")
	)
	(segment
		(start 405.528526 -146.179032)
		(end 404.323042 -144.973548)
		(width 0.089408)
		(layer "In4.Cu")
		(net "XDP_CPU_PRDY_N")
	)
	(segment
		(start 460.576168 -145.386806)
		(end 459.620874 -146.3421)
		(width 0.089408)
		(layer "In4.Cu")
		(net "XDP_CPU_PRDY_N")
	)
	(segment
		(start 398.354804 -142.122144)
		(end 397.303498 -141.070838)
		(width 0.089408)
		(layer "In4.Cu")
		(net "XDP_CPU_PRDY_N")
	)
	(segment
		(start 335.508346 -104.021128)
		(end 334.02524 -102.538022)
		(width 0.089408)
		(layer "In4.Cu")
		(net "XDP_CPU_PRDY_N")
	)
	(segment
		(start 384.815334 -140.53947)
		(end 370.964714 -140.53947)
		(width 0.089408)
		(layer "In4.Cu")
		(net "XDP_CPU_PRDY_N")
	)
	(segment
		(start 345.623896 -132.964936)
		(end 345.623896 -128.143508)
		(width 0.089408)
		(layer "In4.Cu")
		(net "XDP_CPU_PRDY_N")
	)
	(segment
		(start 412.75 -143.129)
		(end 412.173166 -143.129)
		(width 0.089408)
		(layer "In4.Cu")
		(net "XDP_CPU_PRDY_N")
	)
	(segment
		(start 370.557044 -140.94714)
		(end 365.698278 -140.94714)
		(width 0.089408)
		(layer "In4.Cu")
		(net "XDP_CPU_PRDY_N")
	)
	(segment
		(start 345.623896 -128.143508)
		(end 344.400886 -126.920498)
		(width 0.089408)
		(layer "In4.Cu")
		(net "XDP_CPU_PRDY_N")
	)
	(segment
		(start 444.246 -140.008864)
		(end 443.026038 -138.788902)
		(width 0.089408)
		(layer "In4.Cu")
		(net "XDP_CPU_PRDY_N")
	)
	(segment
		(start 361.82046 -139.2682)
		(end 357.067866 -134.515606)
		(width 0.089408)
		(layer "In4.Cu")
		(net "XDP_CPU_PRDY_N")
	)
	(segment
		(start 353.141026 -72.352154)
		(end 353.141026 -79.075026)
		(width 0.089408)
		(layer "In9.Cu")
		(net "XDP_CPU_PRDY_N")
	)
	(segment
		(start 193.040508 -18.56867)
		(end 193.040508 -19.151092)
		(width 0.089408)
		(layer "In9.Cu")
		(net "XDP_CPU_PRDY_N")
	)
	(segment
		(start 320.111882 -45.828204)
		(end 323.628512 -42.311574)
		(width 0.089408)
		(layer "In9.Cu")
		(net "XDP_CPU_PRDY_N")
	)
	(segment
		(start 258.616704 -16.603218)
		(end 258.616704 -16.585438)
		(width 0.089408)
		(layer "In9.Cu")
		(net "XDP_CPU_PRDY_N")
	)
	(segment
		(start 193.040508 -19.151092)
		(end 191.807592 -20.384008)
		(width 0.089408)
		(layer "In9.Cu")
		(net "XDP_CPU_PRDY_N")
	)
	(segment
		(start 355.154484 -70.338696)
		(end 353.141026 -72.352154)
		(width 0.089408)
		(layer "In9.Cu")
		(net "XDP_CPU_PRDY_N")
	)
	(segment
		(start 182.870094 -21.704808)
		(end 182.332376 -22.242526)
		(width 0.089408)
		(layer "In9.Cu")
		(net "XDP_CPU_PRDY_N")
	)
	(segment
		(start 182.097934 -22.925786)
		(end 181.54523 -22.925786)
		(width 0.089408)
		(layer "In9.Cu")
		(net "XDP_CPU_PRDY_N")
	)
	(segment
		(start 258.364482 -16.350996)
		(end 257.547618 -15.534132)
		(width 0.089408)
		(layer "In9.Cu")
		(net "XDP_CPU_PRDY_N")
	)
	(segment
		(start 187.301378 -21.704808)
		(end 182.870094 -21.704808)
		(width 0.089408)
		(layer "In9.Cu")
		(net "XDP_CPU_PRDY_N")
	)
	(segment
		(start 261.745222 -24.702008)
		(end 261.745222 -19.731736)
		(width 0.089408)
		(layer "In9.Cu")
		(net "XDP_CPU_PRDY_N")
	)
	(segment
		(start 317.740538 -45.828204)
		(end 320.111882 -45.828204)
		(width 0.089408)
		(layer "In9.Cu")
		(net "XDP_CPU_PRDY_N")
	)
	(segment
		(start 315.490098 -48.078644)
		(end 315.56071 -48.078644)
		(width 0.089408)
		(layer "In9.Cu")
		(net "XDP_CPU_PRDY_N")
	)
	(segment
		(start 310.953658 -52.615084)
		(end 315.490098 -48.078644)
		(width 0.089408)
		(layer "In9.Cu")
		(net "XDP_CPU_PRDY_N")
	)
	(segment
		(start 190.233554 -20.577048)
		(end 188.429138 -20.577048)
		(width 0.089408)
		(layer "In9.Cu")
		(net "XDP_CPU_PRDY_N")
	)
	(segment
		(start 264.111232 -25.837134)
		(end 263.383268 -25.837134)
		(width 0.089408)
		(layer "In9.Cu")
		(net "XDP_CPU_PRDY_N")
	)
	(segment
		(start 263.383268 -25.837134)
		(end 263.383014 -25.837388)
		(width 0.089408)
		(layer "In9.Cu")
		(net "XDP_CPU_PRDY_N")
	)
	(segment
		(start 356.64394 -62.566804)
		(end 356.64394 -64.41186)
		(width 0.089408)
		(layer "In9.Cu")
		(net "XDP_CPU_PRDY_N")
	)
	(segment
		(start 262.880602 -25.837388)
		(end 261.745222 -24.702008)
		(width 0.089408)
		(layer "In9.Cu")
		(net "XDP_CPU_PRDY_N")
	)
	(segment
		(start 191.807592 -20.384008)
		(end 190.426594 -20.384008)
		(width 0.089408)
		(layer "In9.Cu")
		(net "XDP_CPU_PRDY_N")
	)
	(segment
		(start 263.383014 -25.837388)
		(end 262.880602 -25.837388)
		(width 0.089408)
		(layer "In9.Cu")
		(net "XDP_CPU_PRDY_N")
	)
	(segment
		(start 353.96297 -79.4258)
		(end 354.414836 -79.877666)
		(width 0.089408)
		(layer "In9.Cu")
		(net "XDP_CPU_PRDY_N")
	)
	(segment
		(start 188.429138 -20.577048)
		(end 187.301378 -21.704808)
		(width 0.089408)
		(layer "In9.Cu")
		(net "XDP_CPU_PRDY_N")
	)
	(segment
		(start 258.382262 -16.350996)
		(end 258.364482 -16.350996)
		(width 0.089408)
		(layer "In9.Cu")
		(net "XDP_CPU_PRDY_N")
	)
	(segment
		(start 182.332376 -22.242526)
		(end 182.332376 -22.691344)
		(width 0.089408)
		(layer "In9.Cu")
		(net "XDP_CPU_PRDY_N")
	)
	(segment
		(start 357.036624 -62.17412)
		(end 356.64394 -62.566804)
		(width 0.089408)
		(layer "In9.Cu")
		(net "XDP_CPU_PRDY_N")
	)
	(segment
		(start 257.547618 -15.534132)
		(end 196.075046 -15.534132)
		(width 0.089408)
		(layer "In9.Cu")
		(net "XDP_CPU_PRDY_N")
	)
	(segment
		(start 355.15423 -66.524378)
		(end 355.154484 -66.524632)
		(width 0.089408)
		(layer "In9.Cu")
		(net "XDP_CPU_PRDY_N")
	)
	(segment
		(start 356.64394 -64.41186)
		(end 355.15423 -65.902078)
		(width 0.089408)
		(layer "In9.Cu")
		(net "XDP_CPU_PRDY_N")
	)
	(segment
		(start 355.154484 -66.524632)
		(end 355.154484 -70.338696)
		(width 0.089408)
		(layer "In9.Cu")
		(net "XDP_CPU_PRDY_N")
	)
	(segment
		(start 274.983448 -28.31592)
		(end 266.590018 -28.31592)
		(width 0.089408)
		(layer "In9.Cu")
		(net "XDP_CPU_PRDY_N")
	)
	(segment
		(start 278.783542 -24.515826)
		(end 274.983448 -28.31592)
		(width 0.089408)
		(layer "In9.Cu")
		(net "XDP_CPU_PRDY_N")
	)
	(segment
		(start 182.332376 -22.691344)
		(end 182.097934 -22.925786)
		(width 0.089408)
		(layer "In9.Cu")
		(net "XDP_CPU_PRDY_N")
	)
	(segment
		(start 315.683138 -32.59328)
		(end 307.605684 -24.515826)
		(width 0.089408)
		(layer "In9.Cu")
		(net "XDP_CPU_PRDY_N")
	)
	(segment
		(start 353.4918 -79.4258)
		(end 353.96297 -79.4258)
		(width 0.089408)
		(layer "In9.Cu")
		(net "XDP_CPU_PRDY_N")
	)
	(segment
		(start 315.795152 -47.844202)
		(end 315.795152 -47.77359)
		(width 0.089408)
		(layer "In9.Cu")
		(net "XDP_CPU_PRDY_N")
	)
	(segment
		(start 323.628512 -42.311574)
		(end 323.628512 -39.084758)
		(width 0.089408)
		(layer "In9.Cu")
		(net "XDP_CPU_PRDY_N")
	)
	(segment
		(start 354.414836 -79.877666)
		(end 354.414836 -81.491074)
		(width 0.089408)
		(layer "In9.Cu")
		(net "XDP_CPU_PRDY_N")
	)
	(segment
		(start 355.994208 -84.596732)
		(end 357.727504 -86.330028)
		(width 0.089408)
		(layer "In9.Cu")
		(net "XDP_CPU_PRDY_N")
	)
	(segment
		(start 353.141026 -79.075026)
		(end 353.4918 -79.4258)
		(width 0.089408)
		(layer "In9.Cu")
		(net "XDP_CPU_PRDY_N")
	)
	(segment
		(start 317.033656 -34.880804)
		(end 315.683138 -33.530286)
		(width 0.089408)
		(layer "In9.Cu")
		(net "XDP_CPU_PRDY_N")
	)
	(segment
		(start 315.795152 -47.77359)
		(end 317.740538 -45.828204)
		(width 0.089408)
		(layer "In9.Cu")
		(net "XDP_CPU_PRDY_N")
	)
	(segment
		(start 310.953658 -53.21554)
		(end 310.953658 -52.615084)
		(width 0.089408)
		(layer "In9.Cu")
		(net "XDP_CPU_PRDY_N")
	)
	(segment
		(start 356.2096 -56.7944)
		(end 356.2096 -57.47258)
		(width 0.089408)
		(layer "In9.Cu")
		(net "XDP_CPU_PRDY_N")
	)
	(segment
		(start 258.616704 -16.585438)
		(end 258.382262 -16.350996)
		(width 0.089408)
		(layer "In9.Cu")
		(net "XDP_CPU_PRDY_N")
	)
	(segment
		(start 196.075046 -15.534132)
		(end 193.040508 -18.56867)
		(width 0.089408)
		(layer "In9.Cu")
		(net "XDP_CPU_PRDY_N")
	)
	(segment
		(start 323.628512 -39.084758)
		(end 319.424558 -34.880804)
		(width 0.089408)
		(layer "In9.Cu")
		(net "XDP_CPU_PRDY_N")
	)
	(segment
		(start 307.605684 -24.515826)
		(end 278.783542 -24.515826)
		(width 0.089408)
		(layer "In9.Cu")
		(net "XDP_CPU_PRDY_N")
	)
	(segment
		(start 315.56071 -48.078644)
		(end 315.795152 -47.844202)
		(width 0.089408)
		(layer "In9.Cu")
		(net "XDP_CPU_PRDY_N")
	)
	(segment
		(start 356.2096 -57.47258)
		(end 357.036624 -58.299604)
		(width 0.089408)
		(layer "In9.Cu")
		(net "XDP_CPU_PRDY_N")
	)
	(segment
		(start 315.683138 -33.530286)
		(end 315.683138 -32.59328)
		(width 0.089408)
		(layer "In9.Cu")
		(net "XDP_CPU_PRDY_N")
	)
	(segment
		(start 266.590018 -28.31592)
		(end 264.111232 -25.837134)
		(width 0.089408)
		(layer "In9.Cu")
		(net "XDP_CPU_PRDY_N")
	)
	(segment
		(start 355.15423 -65.902078)
		(end 355.15423 -66.524378)
		(width 0.089408)
		(layer "In9.Cu")
		(net "XDP_CPU_PRDY_N")
	)
	(segment
		(start 319.424558 -34.880804)
		(end 317.033656 -34.880804)
		(width 0.089408)
		(layer "In9.Cu")
		(net "XDP_CPU_PRDY_N")
	)
	(segment
		(start 190.426594 -20.384008)
		(end 190.233554 -20.577048)
		(width 0.089408)
		(layer "In9.Cu")
		(net "XDP_CPU_PRDY_N")
	)
	(segment
		(start 355.994208 -83.070446)
		(end 355.994208 -84.596732)
		(width 0.089408)
		(layer "In9.Cu")
		(net "XDP_CPU_PRDY_N")
	)
	(segment
		(start 354.414836 -81.491074)
		(end 355.994208 -83.070446)
		(width 0.089408)
		(layer "In9.Cu")
		(net "XDP_CPU_PRDY_N")
	)
	(segment
		(start 309.592472 -54.576726)
		(end 310.953658 -53.21554)
		(width 0.089408)
		(layer "In9.Cu")
		(net "XDP_CPU_PRDY_N")
	)
	(segment
		(start 181.54523 -22.925786)
		(end 181.13121 -22.511766)
		(width 0.089408)
		(layer "In9.Cu")
		(net "XDP_CPU_PRDY_N")
	)
	(segment
		(start 261.745222 -19.731736)
		(end 258.616704 -16.603218)
		(width 0.089408)
		(layer "In9.Cu")
		(net "XDP_CPU_PRDY_N")
	)
	(segment
		(start 357.036624 -58.299604)
		(end 357.036624 -62.17412)
		(width 0.089408)
		(layer "In9.Cu")
		(net "XDP_CPU_PRDY_N")
	)
	(segment
		(start 325.761096 -56.186578)
		(end 322.78066 -56.186578)
		(width 0.089408)
		(layer "In11.Cu")
		(net "XDP_CPU_PRDY_N")
	)
	(segment
		(start 296.15003 -61.648086)
		(end 296.154856 -61.656722)
		(width 0.0889)
		(layer "In11.Cu")
		(net "XDP_CPU_PRDY_N")
	)
	(segment
		(start 132.501894 -63.238634)
		(end 132.537454 -63.238634)
		(width 0.0889)
		(layer "In11.Cu")
		(net "XDP_CPU_PRDY_N")
	)
	(segment
		(start 144.9578 -63.3476)
		(end 145.6182 -63.3476)
		(width 0.089408)
		(layer "In11.Cu")
		(net "XDP_CPU_PRDY_N")
	)
	(segment
		(start 326.368664 -56.186578)
		(end 326.352154 -56.170068)
		(width 0.089408)
		(layer "In11.Cu")
		(net "XDP_CPU_PRDY_N")
	)
	(segment
		(start 298.39666 -58.780934)
		(end 298.360846 -58.780934)
		(width 0.0889)
		(layer "In11.Cu")
		(net "XDP_CPU_PRDY_N")
	)
	(segment
		(start 355.601778 -56.186578)
		(end 326.368664 -56.186578)
		(width 0.089408)
		(layer "In11.Cu")
		(net "XDP_CPU_PRDY_N")
	)
	(segment
		(start 129.944368 -64.086232)
		(end 130.6322 -63.3984)
		(width 0.089408)
		(layer "In11.Cu")
		(net "XDP_CPU_PRDY_N")
	)
	(segment
		(start 308.502304 -54.576726)
		(end 306.774596 -56.304434)
		(width 0.089408)
		(layer "In11.Cu")
		(net "XDP_CPU_PRDY_N")
	)
	(segment
		(start 296.66184 -59.771534)
		(end 296.648886 -59.771534)
		(width 0.0889)
		(layer "In11.Cu")
		(net "XDP_CPU_PRDY_N")
	)
	(segment
		(start 180.666644 -30.275276)
		(end 180.666644 -23.447756)
		(width 0.089408)
		(layer "In11.Cu")
		(net "XDP_CPU_PRDY_N")
	)
	(segment
		(start 170.17492 -40.767)
		(end 180.666644 -30.275276)
		(width 0.089408)
		(layer "In11.Cu")
		(net "XDP_CPU_PRDY_N")
	)
	(segment
		(start 137.655808 -64.229234)
		(end 137.688574 -64.229234)
		(width 0.0889)
		(layer "In11.Cu")
		(net "XDP_CPU_PRDY_N")
	)
	(segment
		(start 303.551336 -56.799988)
		(end 303.508156 -56.799988)
		(width 0.0889)
		(layer "In11.Cu")
		(net "XDP_CPU_PRDY_N")
	)
	(segment
		(start 136.801098 -63.734188)
		(end 136.833864 -63.734188)
		(width 0.0889)
		(layer "In11.Cu")
		(net "XDP_CPU_PRDY_N")
	)
	(segment
		(start 322.78066 -56.186578)
		(end 318.83858 -60.128658)
		(width 0.089408)
		(layer "In11.Cu")
		(net "XDP_CPU_PRDY_N")
	)
	(segment
		(start 149.352 -59.6138)
		(end 149.352 -55.68696)
		(width 0.089408)
		(layer "In11.Cu")
		(net "XDP_CPU_PRDY_N")
	)
	(segment
		(start 306.105306 -56.304434)
		(end 306.087526 -56.304434)
		(width 0.0889)
		(layer "In11.Cu")
		(net "XDP_CPU_PRDY_N")
	)
	(segment
		(start 309.592472 -54.576726)
		(end 308.502304 -54.576726)
		(width 0.089408)
		(layer "In11.Cu")
		(net "XDP_CPU_PRDY_N")
	)
	(segment
		(start 300.106842 -57.790588)
		(end 300.074076 -57.790588)
		(width 0.0889)
		(layer "In11.Cu")
		(net "XDP_CPU_PRDY_N")
	)
	(segment
		(start 296.14368 -60.646818)
		(end 296.15003 -60.657486)
		(width 0.0889)
		(layer "In11.Cu")
		(net "XDP_CPU_PRDY_N")
	)
	(segment
		(start 145.6182 -63.3476)
		(end 149.352 -59.6138)
		(width 0.089408)
		(layer "In11.Cu")
		(net "XDP_CPU_PRDY_N")
	)
	(segment
		(start 130.6322 -63.3984)
		(end 131.179062 -63.3984)
		(width 0.089408)
		(layer "In11.Cu")
		(net "XDP_CPU_PRDY_N")
	)
	(segment
		(start 295.818306 -63.238634)
		(end 295.78554 -63.238634)
		(width 0.0889)
		(layer "In11.Cu")
		(net "XDP_CPU_PRDY_N")
	)
	(segment
		(start 299.252132 -58.285634)
		(end 299.224192 -58.285634)
		(width 0.0889)
		(layer "In11.Cu")
		(net "XDP_CPU_PRDY_N")
	)
	(segment
		(start 296.15003 -60.657486)
		(end 296.154856 -60.666122)
		(width 0.0889)
		(layer "In11.Cu")
		(net "XDP_CPU_PRDY_N")
	)
	(segment
		(start 297.53814 -59.276234)
		(end 297.498516 -59.276234)
		(width 0.0889)
		(layer "In11.Cu")
		(net "XDP_CPU_PRDY_N")
	)
	(segment
		(start 131.179062 -63.3984)
		(end 131.314698 -63.534036)
		(width 0.089408)
		(layer "In11.Cu")
		(net "XDP_CPU_PRDY_N")
	)
	(segment
		(start 160.1724 -40.767)
		(end 170.17492 -40.767)
		(width 0.089408)
		(layer "In11.Cu")
		(net "XDP_CPU_PRDY_N")
	)
	(segment
		(start 318.792352 -60.174124)
		(end 318.550036 -60.174124)
		(width 0.089408)
		(layer "In11.Cu")
		(net "XDP_CPU_PRDY_N")
	)
	(segment
		(start 142.094966 -66.210434)
		(end 144.9578 -63.3476)
		(width 0.0889)
		(layer "In11.Cu")
		(net "XDP_CPU_PRDY_N")
	)
	(segment
		(start 149.352 -55.68696)
		(end 148.876512 -55.211472)
		(width 0.089408)
		(layer "In11.Cu")
		(net "XDP_CPU_PRDY_N")
	)
	(segment
		(start 296.14368 -62.628018)
		(end 296.15003 -62.638686)
		(width 0.0889)
		(layer "In11.Cu")
		(net "XDP_CPU_PRDY_N")
	)
	(segment
		(start 138.518138 -64.724788)
		(end 138.550904 -64.724788)
		(width 0.0889)
		(layer "In11.Cu")
		(net "XDP_CPU_PRDY_N")
	)
	(segment
		(start 296.14368 -61.637418)
		(end 296.15003 -61.648086)
		(width 0.0889)
		(layer "In11.Cu")
		(net "XDP_CPU_PRDY_N")
	)
	(segment
		(start 305.257962 -56.799988)
		(end 305.225196 -56.799988)
		(width 0.0889)
		(layer "In11.Cu")
		(net "XDP_CPU_PRDY_N")
	)
	(segment
		(start 133.367018 -63.734188)
		(end 133.38937 -63.734188)
		(width 0.0889)
		(layer "In11.Cu")
		(net "XDP_CPU_PRDY_N")
	)
	(segment
		(start 148.876512 -55.211472)
		(end 148.876512 -52.062888)
		(width 0.089408)
		(layer "In11.Cu")
		(net "XDP_CPU_PRDY_N")
	)
	(segment
		(start 181.13121 -22.98319)
		(end 181.13121 -22.511766)
		(width 0.089408)
		(layer "In11.Cu")
		(net "XDP_CPU_PRDY_N")
	)
	(segment
		(start 132.004562 -63.539878)
		(end 132.007864 -63.534036)
		(width 0.0889)
		(layer "In11.Cu")
		(net "XDP_CPU_PRDY_N")
	)
	(segment
		(start 148.876512 -52.062888)
		(end 160.1724 -40.767)
		(width 0.089408)
		(layer "In11.Cu")
		(net "XDP_CPU_PRDY_N")
	)
	(segment
		(start 135.938768 -63.238634)
		(end 135.971534 -63.238634)
		(width 0.0889)
		(layer "In11.Cu")
		(net "XDP_CPU_PRDY_N")
	)
	(segment
		(start 140.235178 -65.715388)
		(end 140.267944 -65.715388)
		(width 0.0889)
		(layer "In11.Cu")
		(net "XDP_CPU_PRDY_N")
	)
	(segment
		(start 295.214548 -63.881762)
		(end 295.214548 -64.05499)
		(width 0.0889)
		(layer "In11.Cu")
		(net "XDP_CPU_PRDY_N")
	)
	(segment
		(start 129.944368 -64.324738)
		(end 129.944368 -64.086232)
		(width 0.089408)
		(layer "In11.Cu")
		(net "XDP_CPU_PRDY_N")
	)
	(segment
		(start 139.372848 -65.219834)
		(end 139.405614 -65.219834)
		(width 0.0889)
		(layer "In11.Cu")
		(net "XDP_CPU_PRDY_N")
	)
	(segment
		(start 141.089888 -66.210434)
		(end 142.094966 -66.210434)
		(width 0.0889)
		(layer "In11.Cu")
		(net "XDP_CPU_PRDY_N")
	)
	(segment
		(start 315.834014 -60.17387)
		(end 310.23687 -54.576726)
		(width 0.089408)
		(layer "In11.Cu")
		(net "XDP_CPU_PRDY_N")
	)
	(segment
		(start 326.352154 -56.170068)
		(end 325.777606 -56.170068)
		(width 0.089408)
		(layer "In11.Cu")
		(net "XDP_CPU_PRDY_N")
	)
	(segment
		(start 318.549782 -60.17387)
		(end 315.834014 -60.17387)
		(width 0.089408)
		(layer "In11.Cu")
		(net "XDP_CPU_PRDY_N")
	)
	(segment
		(start 318.837818 -60.128658)
		(end 318.792352 -60.174124)
		(width 0.089408)
		(layer "In11.Cu")
		(net "XDP_CPU_PRDY_N")
	)
	(segment
		(start 306.774596 -56.304434)
		(end 306.105306 -56.304434)
		(width 0.089408)
		(layer "In11.Cu")
		(net "XDP_CPU_PRDY_N")
	)
	(segment
		(start 318.83858 -60.128658)
		(end 318.837818 -60.128658)
		(width 0.089408)
		(layer "In11.Cu")
		(net "XDP_CPU_PRDY_N")
	)
	(segment
		(start 310.23687 -54.576726)
		(end 309.592472 -54.576726)
		(width 0.089408)
		(layer "In11.Cu")
		(net "XDP_CPU_PRDY_N")
	)
	(segment
		(start 300.969172 -57.295034)
		(end 300.936406 -57.295034)
		(width 0.0889)
		(layer "In11.Cu")
		(net "XDP_CPU_PRDY_N")
	)
	(segment
		(start 296.15003 -62.638686)
		(end 296.154856 -62.647322)
		(width 0.0889)
		(layer "In11.Cu")
		(net "XDP_CPU_PRDY_N")
	)
	(segment
		(start 135.073644 -62.743588)
		(end 135.116824 -62.743588)
		(width 0.0889)
		(layer "In11.Cu")
		(net "XDP_CPU_PRDY_N")
	)
	(segment
		(start 131.650232 -63.734188)
		(end 131.661408 -63.734188)
		(width 0.0889)
		(layer "In11.Cu")
		(net "XDP_CPU_PRDY_N")
	)
	(segment
		(start 295.214548 -64.05499)
		(end 294.9448 -64.324738)
		(width 0.0889)
		(layer "In11.Cu")
		(net "XDP_CPU_PRDY_N")
	)
	(segment
		(start 318.550036 -60.174124)
		(end 318.549782 -60.17387)
		(width 0.089408)
		(layer "In11.Cu")
		(net "XDP_CPU_PRDY_N")
	)
	(segment
		(start 134.218934 -63.238634)
		(end 134.2517 -63.238634)
		(width 0.0889)
		(layer "In11.Cu")
		(net "XDP_CPU_PRDY_N")
	)
	(segment
		(start 180.666644 -23.447756)
		(end 181.13121 -22.98319)
		(width 0.089408)
		(layer "In11.Cu")
		(net "XDP_CPU_PRDY_N")
	)
	(segment
		(start 356.2096 -56.7944)
		(end 355.601778 -56.186578)
		(width 0.089408)
		(layer "In11.Cu")
		(net "XDP_CPU_PRDY_N")
	)
	(segment
		(start 325.777606 -56.170068)
		(end 325.761096 -56.186578)
		(width 0.089408)
		(layer "In11.Cu")
		(net "XDP_CPU_PRDY_N")
	)
	(segment
		(start 297.008296 -59.571382)
		(end 297.004994 -59.577224)
		(width 0.0889)
		(layer "In11.Cu")
		(net "XDP_CPU_PRDY_N")
	)
	(arc
		(start 296.154856 -61.656722)
		(mid 296.203611 -61.853074)
		(end 296.15003 -62.048136)
		(width 0.0889)
		(layer "In11.Cu")
		(net "XDP_CPU_PRDY_N")
	)
	(arc
		(start 304.041556 -57.095136)
		(mid 303.834552 -56.884272)
		(end 303.551336 -56.799988)
		(width 0.0889)
		(layer "In11.Cu")
		(net "XDP_CPU_PRDY_N")
	)
	(arc
		(start 300.074076 -57.790588)
		(mid 299.790859 -57.874869)
		(end 299.583856 -58.085736)
		(width 0.0889)
		(layer "In11.Cu")
		(net "XDP_CPU_PRDY_N")
	)
	(arc
		(start 304.734976 -57.095136)
		(mid 304.388266 -57.29532)
		(end 304.041556 -57.095136)
		(width 0.0889)
		(layer "In11.Cu")
		(net "XDP_CPU_PRDY_N")
	)
	(arc
		(start 300.442376 -57.590436)
		(mid 300.300693 -57.73424)
		(end 300.106842 -57.790588)
		(width 0.0889)
		(layer "In11.Cu")
		(net "XDP_CPU_PRDY_N")
	)
	(arc
		(start 137.688574 -64.229234)
		(mid 137.973998 -64.312701)
		(end 138.182604 -64.524636)
		(width 0.0889)
		(layer "In11.Cu")
		(net "XDP_CPU_PRDY_N")
	)
	(arc
		(start 305.225196 -56.799988)
		(mid 304.941979 -56.884269)
		(end 304.734976 -57.095136)
		(width 0.0889)
		(layer "In11.Cu")
		(net "XDP_CPU_PRDY_N")
	)
	(arc
		(start 298.360846 -58.780934)
		(mid 298.075422 -58.864401)
		(end 297.866816 -59.076336)
		(width 0.0889)
		(layer "In11.Cu")
		(net "XDP_CPU_PRDY_N")
	)
	(arc
		(start 305.593496 -56.599836)
		(mid 305.451813 -56.74364)
		(end 305.257962 -56.799988)
		(width 0.0889)
		(layer "In11.Cu")
		(net "XDP_CPU_PRDY_N")
	)
	(arc
		(start 296.154856 -62.647322)
		(mid 296.203611 -62.843674)
		(end 296.15003 -63.038736)
		(width 0.0889)
		(layer "In11.Cu")
		(net "XDP_CPU_PRDY_N")
	)
	(arc
		(start 301.300896 -57.095136)
		(mid 301.160817 -57.237872)
		(end 300.969172 -57.295034)
		(width 0.0889)
		(layer "In11.Cu")
		(net "XDP_CPU_PRDY_N")
	)
	(arc
		(start 135.116824 -62.743588)
		(mid 135.400041 -62.827869)
		(end 135.607044 -63.038736)
		(width 0.0889)
		(layer "In11.Cu")
		(net "XDP_CPU_PRDY_N")
	)
	(arc
		(start 131.661408 -63.734188)
		(mid 131.858569 -63.682229)
		(end 132.004562 -63.539878)
		(width 0.0889)
		(layer "In11.Cu")
		(net "XDP_CPU_PRDY_N")
	)
	(arc
		(start 297.866816 -59.076336)
		(mid 297.728072 -59.218369)
		(end 297.53814 -59.276234)
		(width 0.0889)
		(layer "In11.Cu")
		(net "XDP_CPU_PRDY_N")
	)
	(arc
		(start 131.314698 -63.534036)
		(mid 131.456381 -63.67784)
		(end 131.650232 -63.734188)
		(width 0.0889)
		(layer "In11.Cu")
		(net "XDP_CPU_PRDY_N")
	)
	(arc
		(start 295.78554 -63.238634)
		(mid 295.494719 -63.325221)
		(end 295.28516 -63.544704)
		(width 0.0889)
		(layer "In11.Cu")
		(net "XDP_CPU_PRDY_N")
	)
	(arc
		(start 303.017936 -57.095136)
		(mid 302.671226 -57.29532)
		(end 302.324516 -57.095136)
		(width 0.0889)
		(layer "In11.Cu")
		(net "XDP_CPU_PRDY_N")
	)
	(arc
		(start 140.758164 -66.010536)
		(mid 140.898243 -66.153272)
		(end 141.089888 -66.210434)
		(width 0.0889)
		(layer "In11.Cu")
		(net "XDP_CPU_PRDY_N")
	)
	(arc
		(start 297.004994 -59.577224)
		(mid 296.859028 -59.719623)
		(end 296.66184 -59.771534)
		(width 0.0889)
		(layer "In11.Cu")
		(net "XDP_CPU_PRDY_N")
	)
	(arc
		(start 139.899644 -65.515236)
		(mid 140.041327 -65.65904)
		(end 140.235178 -65.715388)
		(width 0.0889)
		(layer "In11.Cu")
		(net "XDP_CPU_PRDY_N")
	)
	(arc
		(start 136.465564 -63.534036)
		(mid 136.607247 -63.67784)
		(end 136.801098 -63.734188)
		(width 0.0889)
		(layer "In11.Cu")
		(net "XDP_CPU_PRDY_N")
	)
	(arc
		(start 296.15003 -62.048136)
		(mid 296.070808 -62.337254)
		(end 296.14368 -62.628018)
		(width 0.0889)
		(layer "In11.Cu")
		(net "XDP_CPU_PRDY_N")
	)
	(arc
		(start 137.324084 -64.029336)
		(mid 137.464163 -64.172072)
		(end 137.655808 -64.229234)
		(width 0.0889)
		(layer "In11.Cu")
		(net "XDP_CPU_PRDY_N")
	)
	(arc
		(start 136.833864 -63.734188)
		(mid 137.117081 -63.818469)
		(end 137.324084 -64.029336)
		(width 0.0889)
		(layer "In11.Cu")
		(net "XDP_CPU_PRDY_N")
	)
	(arc
		(start 298.725336 -58.581036)
		(mid 298.586592 -58.723069)
		(end 298.39666 -58.780934)
		(width 0.0889)
		(layer "In11.Cu")
		(net "XDP_CPU_PRDY_N")
	)
	(arc
		(start 306.087526 -56.304434)
		(mid 305.802102 -56.387901)
		(end 305.593496 -56.599836)
		(width 0.0889)
		(layer "In11.Cu")
		(net "XDP_CPU_PRDY_N")
	)
	(arc
		(start 139.041124 -65.019936)
		(mid 139.181203 -65.162672)
		(end 139.372848 -65.219834)
		(width 0.0889)
		(layer "In11.Cu")
		(net "XDP_CPU_PRDY_N")
	)
	(arc
		(start 302.324516 -57.095136)
		(mid 301.812706 -56.799597)
		(end 301.300896 -57.095136)
		(width 0.0889)
		(layer "In11.Cu")
		(net "XDP_CPU_PRDY_N")
	)
	(arc
		(start 296.15003 -61.057536)
		(mid 296.070808 -61.346654)
		(end 296.14368 -61.637418)
		(width 0.0889)
		(layer "In11.Cu")
		(net "XDP_CPU_PRDY_N")
	)
	(arc
		(start 296.15003 -60.066936)
		(mid 296.070808 -60.356054)
		(end 296.14368 -60.646818)
		(width 0.0889)
		(layer "In11.Cu")
		(net "XDP_CPU_PRDY_N")
	)
	(arc
		(start 303.508156 -56.799988)
		(mid 303.224939 -56.884269)
		(end 303.017936 -57.095136)
		(width 0.0889)
		(layer "In11.Cu")
		(net "XDP_CPU_PRDY_N")
	)
	(arc
		(start 134.583424 -63.038736)
		(mid 134.790428 -62.827872)
		(end 135.073644 -62.743588)
		(width 0.0889)
		(layer "In11.Cu")
		(net "XDP_CPU_PRDY_N")
	)
	(arc
		(start 135.607044 -63.038736)
		(mid 135.747123 -63.181472)
		(end 135.938768 -63.238634)
		(width 0.0889)
		(layer "In11.Cu")
		(net "XDP_CPU_PRDY_N")
	)
	(arc
		(start 135.971534 -63.238634)
		(mid 136.256958 -63.322101)
		(end 136.465564 -63.534036)
		(width 0.0889)
		(layer "In11.Cu")
		(net "XDP_CPU_PRDY_N")
	)
	(arc
		(start 138.550904 -64.724788)
		(mid 138.834121 -64.809069)
		(end 139.041124 -65.019936)
		(width 0.0889)
		(layer "In11.Cu")
		(net "XDP_CPU_PRDY_N")
	)
	(arc
		(start 139.405614 -65.219834)
		(mid 139.691038 -65.303301)
		(end 139.899644 -65.515236)
		(width 0.0889)
		(layer "In11.Cu")
		(net "XDP_CPU_PRDY_N")
	)
	(arc
		(start 132.537454 -63.238634)
		(mid 132.822878 -63.322101)
		(end 133.031484 -63.534036)
		(width 0.0889)
		(layer "In11.Cu")
		(net "XDP_CPU_PRDY_N")
	)
	(arc
		(start 134.2517 -63.238634)
		(mid 134.443342 -63.181468)
		(end 134.583424 -63.038736)
		(width 0.0889)
		(layer "In11.Cu")
		(net "XDP_CPU_PRDY_N")
	)
	(arc
		(start 299.224192 -58.285634)
		(mid 298.936047 -58.367953)
		(end 298.725336 -58.581036)
		(width 0.0889)
		(layer "In11.Cu")
		(net "XDP_CPU_PRDY_N")
	)
	(arc
		(start 299.583856 -58.085736)
		(mid 299.443777 -58.228472)
		(end 299.252132 -58.285634)
		(width 0.0889)
		(layer "In11.Cu")
		(net "XDP_CPU_PRDY_N")
	)
	(arc
		(start 138.182604 -64.524636)
		(mid 138.324287 -64.66844)
		(end 138.518138 -64.724788)
		(width 0.0889)
		(layer "In11.Cu")
		(net "XDP_CPU_PRDY_N")
	)
	(arc
		(start 140.267944 -65.715388)
		(mid 140.551161 -65.799669)
		(end 140.758164 -66.010536)
		(width 0.0889)
		(layer "In11.Cu")
		(net "XDP_CPU_PRDY_N")
	)
	(arc
		(start 296.154856 -60.666122)
		(mid 296.203611 -60.862474)
		(end 296.15003 -61.057536)
		(width 0.0889)
		(layer "In11.Cu")
		(net "XDP_CPU_PRDY_N")
	)
	(arc
		(start 296.648886 -59.771534)
		(mid 296.360741 -59.853853)
		(end 296.15003 -60.066936)
		(width 0.0889)
		(layer "In11.Cu")
		(net "XDP_CPU_PRDY_N")
	)
	(arc
		(start 133.031484 -63.534036)
		(mid 133.173167 -63.67784)
		(end 133.367018 -63.734188)
		(width 0.0889)
		(layer "In11.Cu")
		(net "XDP_CPU_PRDY_N")
	)
	(arc
		(start 296.15003 -63.038736)
		(mid 296.009951 -63.181472)
		(end 295.818306 -63.238634)
		(width 0.0889)
		(layer "In11.Cu")
		(net "XDP_CPU_PRDY_N")
	)
	(arc
		(start 295.28516 -63.544704)
		(mid 295.224764 -63.707977)
		(end 295.214548 -63.881762)
		(width 0.0889)
		(layer "In11.Cu")
		(net "XDP_CPU_PRDY_N")
	)
	(arc
		(start 132.007864 -63.534036)
		(mid 132.216472 -63.322104)
		(end 132.501894 -63.238634)
		(width 0.0889)
		(layer "In11.Cu")
		(net "XDP_CPU_PRDY_N")
	)
	(arc
		(start 133.38937 -63.734188)
		(mid 133.58322 -63.677838)
		(end 133.724904 -63.534036)
		(width 0.0889)
		(layer "In11.Cu")
		(net "XDP_CPU_PRDY_N")
	)
	(arc
		(start 133.724904 -63.534036)
		(mid 133.933512 -63.322104)
		(end 134.218934 -63.238634)
		(width 0.0889)
		(layer "In11.Cu")
		(net "XDP_CPU_PRDY_N")
	)
	(arc
		(start 300.936406 -57.295034)
		(mid 300.650982 -57.378501)
		(end 300.442376 -57.590436)
		(width 0.0889)
		(layer "In11.Cu")
		(net "XDP_CPU_PRDY_N")
	)
	(arc
		(start 297.498516 -59.276234)
		(mid 297.215299 -59.360515)
		(end 297.008296 -59.571382)
		(width 0.0889)
		(layer "In11.Cu")
		(net "XDP_CPU_PRDY_N")
	)
	(segment
		(start 298.665646 -64.819784)
		(end 299.237146 -64.819784)
		(width 0.1016)
		(layer "F.Cu")
		(net "XDP_CPU_MBP1_N")
	)
	(segment
		(start 133.665214 -64.819784)
		(end 134.236714 -64.819784)
		(width 0.1016)
		(layer "F.Cu")
		(net "XDP_CPU_MBP1_N")
	)
	(via
		(at 332.3336 -66.8782)
		(size 0.6604)
		(drill 0.3302)
		(layers "F.Cu" "B.Cu")
		(net "XDP_CPU_MBP1_N")
	)
	(via
		(at 324.486016 -63.587884)
		(size 0.508)
		(drill 0.254)
		(layers "F.Cu" "B.Cu")
		(net "XDP_CPU_MBP1_N")
	)
	(via
		(at 182.091076 -21.347938)
		(size 0.508)
		(drill 0.254)
		(layers "F.Cu" "B.Cu")
		(net "XDP_CPU_MBP1_N")
	)
	(via
		(at 299.237146 -64.819784)
		(size 0.508)
		(drill 0.254)
		(layers "F.Cu" "B.Cu")
		(net "XDP_CPU_MBP1_N")
	)
	(via
		(at 134.236714 -64.819784)
		(size 0.508)
		(drill 0.254)
		(layers "F.Cu" "B.Cu")
		(net "XDP_CPU_MBP1_N")
	)
	(via
		(at 332.2828 -64.9732)
		(size 0.508)
		(drill 0.254)
		(layers "F.Cu" "B.Cu")
		(net "XDP_CPU_MBP1_N")
	)
	(via
		(at 163.531042 -73.5711)
		(size 0.508)
		(drill 0.254)
		(layers "F.Cu" "B.Cu")
		(net "XDP_CPU_MBP1_N")
	)
	(via
		(at 157.6959 -64.367664)
		(size 0.508)
		(drill 0.254)
		(layers "F.Cu" "B.Cu")
		(net "XDP_CPU_MBP1_N")
	)
	(segment
		(start 330.97216 -67.26936)
		(end 331.94244 -67.26936)
		(width 0.10795)
		(layer "B.Cu")
		(net "XDP_CPU_MBP1_N")
	)
	(segment
		(start 331.94244 -67.26936)
		(end 332.3336 -66.8782)
		(width 0.10795)
		(layer "B.Cu")
		(net "XDP_CPU_MBP1_N")
	)
	(segment
		(start 332.3336 -66.8782)
		(end 332.6384 -66.5734)
		(width 0.10795)
		(layer "B.Cu")
		(net "XDP_CPU_MBP1_N")
	)
	(segment
		(start 332.6384 -66.5734)
		(end 332.6384 -65.3288)
		(width 0.10795)
		(layer "B.Cu")
		(net "XDP_CPU_MBP1_N")
	)
	(segment
		(start 163.531042 -72.871076)
		(end 163.531042 -73.5711)
		(width 0.10795)
		(layer "B.Cu")
		(net "XDP_CPU_MBP1_N")
	)
	(segment
		(start 332.6384 -65.3288)
		(end 332.2828 -64.9732)
		(width 0.10795)
		(layer "B.Cu")
		(net "XDP_CPU_MBP1_N")
	)
	(segment
		(start 158.877 -65.548764)
		(end 157.6959 -64.367664)
		(width 0.089408)
		(layer "In9.Cu")
		(net "XDP_CPU_MBP1_N")
	)
	(segment
		(start 324.588124 -50.693066)
		(end 323.131688 -49.23663)
		(width 0.089408)
		(layer "In9.Cu")
		(net "XDP_CPU_MBP1_N")
	)
	(segment
		(start 323.74967 -32.361124)
		(end 323.74967 -30.327346)
		(width 0.089408)
		(layer "In9.Cu")
		(net "XDP_CPU_MBP1_N")
	)
	(segment
		(start 162.84829 -72.609456)
		(end 158.877 -68.638166)
		(width 0.089408)
		(layer "In9.Cu")
		(net "XDP_CPU_MBP1_N")
	)
	(segment
		(start 265.73861 -18.043398)
		(end 265.166348 -18.61566)
		(width 0.089408)
		(layer "In9.Cu")
		(net "XDP_CPU_MBP1_N")
	)
	(segment
		(start 257.911854 -14.656308)
		(end 195.71081 -14.656308)
		(width 0.089408)
		(layer "In9.Cu")
		(net "XDP_CPU_MBP1_N")
	)
	(segment
		(start 186.477656 -20.299934)
		(end 186.477402 -20.29968)
		(width 0.089408)
		(layer "In9.Cu")
		(net "XDP_CPU_MBP1_N")
	)
	(segment
		(start 265.166348 -18.61566)
		(end 265.166348 -18.987262)
		(width 0.089408)
		(layer "In9.Cu")
		(net "XDP_CPU_MBP1_N")
	)
	(segment
		(start 322.626736 -21.999448)
		(end 322.626736 -17.398238)
		(width 0.089408)
		(layer "In9.Cu")
		(net "XDP_CPU_MBP1_N")
	)
	(segment
		(start 323.74967 -30.327346)
		(end 321.506088 -28.083764)
		(width 0.089408)
		(layer "In9.Cu")
		(net "XDP_CPU_MBP1_N")
	)
	(segment
		(start 322.765166 -61.1251)
		(end 322.765166 -54.714394)
		(width 0.089408)
		(layer "In9.Cu")
		(net "XDP_CPU_MBP1_N")
	)
	(segment
		(start 258.746498 -15.473172)
		(end 258.728718 -15.473172)
		(width 0.089408)
		(layer "In9.Cu")
		(net "XDP_CPU_MBP1_N")
	)
	(segment
		(start 258.728718 -15.473172)
		(end 257.911854 -14.656308)
		(width 0.089408)
		(layer "In9.Cu")
		(net "XDP_CPU_MBP1_N")
	)
	(segment
		(start 324.588124 -52.891436)
		(end 324.588124 -50.693066)
		(width 0.089408)
		(layer "In9.Cu")
		(net "XDP_CPU_MBP1_N")
	)
	(segment
		(start 325.60514 -45.007784)
		(end 325.60514 -42.669714)
		(width 0.089408)
		(layer "In9.Cu")
		(net "XDP_CPU_MBP1_N")
	)
	(segment
		(start 195.71081 -14.656308)
		(end 192.162684 -18.204434)
		(width 0.089408)
		(layer "In9.Cu")
		(net "XDP_CPU_MBP1_N")
	)
	(segment
		(start 185.886852 -20.29968)
		(end 185.06694 -21.119592)
		(width 0.089408)
		(layer "In9.Cu")
		(net "XDP_CPU_MBP1_N")
	)
	(segment
		(start 321.750182 -24.726392)
		(end 321.750182 -22.876002)
		(width 0.089408)
		(layer "In9.Cu")
		(net "XDP_CPU_MBP1_N")
	)
	(segment
		(start 264.22477 -19.92884)
		(end 263.184386 -19.92884)
		(width 0.089408)
		(layer "In9.Cu")
		(net "XDP_CPU_MBP1_N")
	)
	(segment
		(start 189.869318 -19.699224)
		(end 187.320682 -19.699224)
		(width 0.089408)
		(layer "In9.Cu")
		(net "XDP_CPU_MBP1_N")
	)
	(segment
		(start 321.083432 -15.854934)
		(end 266.382754 -15.854934)
		(width 0.089408)
		(layer "In9.Cu")
		(net "XDP_CPU_MBP1_N")
	)
	(segment
		(start 186.477402 -20.29968)
		(end 185.886852 -20.29968)
		(width 0.089408)
		(layer "In9.Cu")
		(net "XDP_CPU_MBP1_N")
	)
	(segment
		(start 325.60514 -42.669714)
		(end 326.055482 -42.219372)
		(width 0.089408)
		(layer "In9.Cu")
		(net "XDP_CPU_MBP1_N")
	)
	(segment
		(start 259.494528 -16.221202)
		(end 258.746498 -15.473172)
		(width 0.089408)
		(layer "In9.Cu")
		(net "XDP_CPU_MBP1_N")
	)
	(segment
		(start 321.750182 -22.876002)
		(end 322.626736 -21.999448)
		(width 0.089408)
		(layer "In9.Cu")
		(net "XDP_CPU_MBP1_N")
	)
	(segment
		(start 191.434212 -19.495008)
		(end 190.073534 -19.495008)
		(width 0.089408)
		(layer "In9.Cu")
		(net "XDP_CPU_MBP1_N")
	)
	(segment
		(start 321.506088 -24.970486)
		(end 321.750182 -24.726392)
		(width 0.089408)
		(layer "In9.Cu")
		(net "XDP_CPU_MBP1_N")
	)
	(segment
		(start 265.406886 -16.427704)
		(end 265.406886 -17.054068)
		(width 0.089408)
		(layer "In9.Cu")
		(net "XDP_CPU_MBP1_N")
	)
	(segment
		(start 265.73861 -17.385792)
		(end 265.73861 -18.043398)
		(width 0.089408)
		(layer "In9.Cu")
		(net "XDP_CPU_MBP1_N")
	)
	(segment
		(start 323.131688 -47.481236)
		(end 325.60514 -45.007784)
		(width 0.089408)
		(layer "In9.Cu")
		(net "XDP_CPU_MBP1_N")
	)
	(segment
		(start 259.494528 -16.238982)
		(end 259.494528 -16.221202)
		(width 0.089408)
		(layer "In9.Cu")
		(net "XDP_CPU_MBP1_N")
	)
	(segment
		(start 163.531042 -73.5711)
		(end 162.84829 -72.888348)
		(width 0.089408)
		(layer "In9.Cu")
		(net "XDP_CPU_MBP1_N")
	)
	(segment
		(start 324.487286 -62.84722)
		(end 322.765166 -61.1251)
		(width 0.089408)
		(layer "In9.Cu")
		(net "XDP_CPU_MBP1_N")
	)
	(segment
		(start 322.626736 -17.398238)
		(end 321.083432 -15.854934)
		(width 0.089408)
		(layer "In9.Cu")
		(net "XDP_CPU_MBP1_N")
	)
	(segment
		(start 263.184386 -19.92884)
		(end 259.494528 -16.238982)
		(width 0.089408)
		(layer "In9.Cu")
		(net "XDP_CPU_MBP1_N")
	)
	(segment
		(start 186.719972 -20.299934)
		(end 186.477656 -20.299934)
		(width 0.089408)
		(layer "In9.Cu")
		(net "XDP_CPU_MBP1_N")
	)
	(segment
		(start 190.073534 -19.495008)
		(end 189.869318 -19.699224)
		(width 0.089408)
		(layer "In9.Cu")
		(net "XDP_CPU_MBP1_N")
	)
	(segment
		(start 325.155306 -35.617912)
		(end 325.155306 -33.76676)
		(width 0.089408)
		(layer "In9.Cu")
		(net "XDP_CPU_MBP1_N")
	)
	(segment
		(start 322.765166 -54.714394)
		(end 324.588124 -52.891436)
		(width 0.089408)
		(layer "In9.Cu")
		(net "XDP_CPU_MBP1_N")
	)
	(segment
		(start 324.487286 -63.586614)
		(end 324.487286 -62.84722)
		(width 0.089408)
		(layer "In9.Cu")
		(net "XDP_CPU_MBP1_N")
	)
	(segment
		(start 326.055482 -42.219372)
		(end 326.055482 -36.518088)
		(width 0.089408)
		(layer "In9.Cu")
		(net "XDP_CPU_MBP1_N")
	)
	(segment
		(start 266.382754 -15.854934)
		(end 266.215622 -16.022066)
		(width 0.089408)
		(layer "In9.Cu")
		(net "XDP_CPU_MBP1_N")
	)
	(segment
		(start 321.506088 -28.083764)
		(end 321.506088 -24.970486)
		(width 0.089408)
		(layer "In9.Cu")
		(net "XDP_CPU_MBP1_N")
	)
	(segment
		(start 187.320682 -19.699224)
		(end 186.719972 -20.299934)
		(width 0.089408)
		(layer "In9.Cu")
		(net "XDP_CPU_MBP1_N")
	)
	(segment
		(start 265.406886 -17.054068)
		(end 265.73861 -17.385792)
		(width 0.089408)
		(layer "In9.Cu")
		(net "XDP_CPU_MBP1_N")
	)
	(segment
		(start 265.812524 -16.022066)
		(end 265.406886 -16.427704)
		(width 0.089408)
		(layer "In9.Cu")
		(net "XDP_CPU_MBP1_N")
	)
	(segment
		(start 265.166348 -18.987262)
		(end 264.22477 -19.92884)
		(width 0.089408)
		(layer "In9.Cu")
		(net "XDP_CPU_MBP1_N")
	)
	(segment
		(start 323.131688 -49.23663)
		(end 323.131688 -47.481236)
		(width 0.089408)
		(layer "In9.Cu")
		(net "XDP_CPU_MBP1_N")
	)
	(segment
		(start 158.877 -68.638166)
		(end 158.877 -65.548764)
		(width 0.089408)
		(layer "In9.Cu")
		(net "XDP_CPU_MBP1_N")
	)
	(segment
		(start 162.84829 -72.888348)
		(end 162.84829 -72.609456)
		(width 0.089408)
		(layer "In9.Cu")
		(net "XDP_CPU_MBP1_N")
	)
	(segment
		(start 324.486016 -63.587884)
		(end 324.487286 -63.586614)
		(width 0.089408)
		(layer "In9.Cu")
		(net "XDP_CPU_MBP1_N")
	)
	(segment
		(start 182.319422 -21.119592)
		(end 182.091076 -21.347938)
		(width 0.089408)
		(layer "In9.Cu")
		(net "XDP_CPU_MBP1_N")
	)
	(segment
		(start 185.06694 -21.119592)
		(end 182.319422 -21.119592)
		(width 0.089408)
		(layer "In9.Cu")
		(net "XDP_CPU_MBP1_N")
	)
	(segment
		(start 325.155306 -33.76676)
		(end 323.74967 -32.361124)
		(width 0.089408)
		(layer "In9.Cu")
		(net "XDP_CPU_MBP1_N")
	)
	(segment
		(start 266.215622 -16.022066)
		(end 265.812524 -16.022066)
		(width 0.089408)
		(layer "In9.Cu")
		(net "XDP_CPU_MBP1_N")
	)
	(segment
		(start 192.162684 -18.204434)
		(end 192.162684 -18.766536)
		(width 0.089408)
		(layer "In9.Cu")
		(net "XDP_CPU_MBP1_N")
	)
	(segment
		(start 326.055482 -36.518088)
		(end 325.155306 -35.617912)
		(width 0.089408)
		(layer "In9.Cu")
		(net "XDP_CPU_MBP1_N")
	)
	(segment
		(start 192.162684 -18.766536)
		(end 191.434212 -19.495008)
		(width 0.089408)
		(layer "In9.Cu")
		(net "XDP_CPU_MBP1_N")
	)
	(segment
		(start 157.740604 -62.947804)
		(end 155.9814 -61.1886)
		(width 0.089408)
		(layer "In11.Cu")
		(net "XDP_CPU_MBP1_N")
	)
	(segment
		(start 138.518138 -66.705988)
		(end 138.550904 -66.705988)
		(width 0.0889)
		(layer "In11.Cu")
		(net "XDP_CPU_MBP1_N")
	)
	(segment
		(start 182.091076 -21.775166)
		(end 182.091076 -21.347938)
		(width 0.089408)
		(layer "In11.Cu")
		(net "XDP_CPU_MBP1_N")
	)
	(segment
		(start 140.235178 -67.696588)
		(end 140.267944 -67.696588)
		(width 0.0889)
		(layer "In11.Cu")
		(net "XDP_CPU_MBP1_N")
	)
	(segment
		(start 181.102 -30.3784)
		(end 181.102 -23.495)
		(width 0.089408)
		(layer "In11.Cu")
		(net "XDP_CPU_MBP1_N")
	)
	(segment
		(start 149.225 -52.1716)
		(end 160.274 -41.1226)
		(width 0.089408)
		(layer "In11.Cu")
		(net "XDP_CPU_MBP1_N")
	)
	(segment
		(start 307.695854 -63.238634)
		(end 310.961532 -63.238634)
		(width 0.0889)
		(layer "In11.Cu")
		(net "XDP_CPU_MBP1_N")
	)
	(segment
		(start 323.127878 -63.587884)
		(end 324.484746 -63.587884)
		(width 0.089408)
		(layer "In11.Cu")
		(net "XDP_CPU_MBP1_N")
	)
	(segment
		(start 170.3578 -41.1226)
		(end 181.102 -30.3784)
		(width 0.089408)
		(layer "In11.Cu")
		(net "XDP_CPU_MBP1_N")
	)
	(segment
		(start 181.531768 -22.334474)
		(end 182.091076 -21.775166)
		(width 0.089408)
		(layer "In11.Cu")
		(net "XDP_CPU_MBP1_N")
	)
	(segment
		(start 311.911238 -64.18834)
		(end 311.918858 -64.18834)
		(width 0.0889)
		(layer "In11.Cu")
		(net "XDP_CPU_MBP1_N")
	)
	(segment
		(start 299.530262 -64.988948)
		(end 299.61967 -64.964818)
		(width 0.0889)
		(layer "In11.Cu")
		(net "XDP_CPU_MBP1_N")
	)
	(segment
		(start 144.653 -68.70065)
		(end 153.362914 -68.70065)
		(width 0.089408)
		(layer "In11.Cu")
		(net "XDP_CPU_MBP1_N")
	)
	(segment
		(start 303.508156 -63.734188)
		(end 303.551336 -63.734188)
		(width 0.0889)
		(layer "In11.Cu")
		(net "XDP_CPU_MBP1_N")
	)
	(segment
		(start 157.740604 -64.32296)
		(end 157.740604 -62.947804)
		(width 0.089408)
		(layer "In11.Cu")
		(net "XDP_CPU_MBP1_N")
	)
	(segment
		(start 306.352702 -63.238888)
		(end 306.516278 -63.402464)
		(width 0.0889)
		(layer "In11.Cu")
		(net "XDP_CPU_MBP1_N")
	)
	(segment
		(start 135.938768 -65.219834)
		(end 135.971534 -65.219834)
		(width 0.0889)
		(layer "In11.Cu")
		(net "XDP_CPU_MBP1_N")
	)
	(segment
		(start 136.801098 -65.715388)
		(end 136.833864 -65.715388)
		(width 0.0889)
		(layer "In11.Cu")
		(net "XDP_CPU_MBP1_N")
	)
	(segment
		(start 311.918858 -64.18834)
		(end 313.188604 -65.458086)
		(width 0.0889)
		(layer "In11.Cu")
		(net "XDP_CPU_MBP1_N")
	)
	(segment
		(start 299.237146 -64.819784)
		(end 299.530262 -64.988948)
		(width 0.0889)
		(layer "In11.Cu")
		(net "XDP_CPU_MBP1_N")
	)
	(segment
		(start 324.484746 -63.589154)
		(end 324.484746 -63.587884)
		(width 0.089408)
		(layer "In11.Cu")
		(net "XDP_CPU_MBP1_N")
	)
	(segment
		(start 300.936406 -64.229234)
		(end 300.969172 -64.229234)
		(width 0.0889)
		(layer "In11.Cu")
		(net "XDP_CPU_MBP1_N")
	)
	(segment
		(start 306.95265 -63.734188)
		(end 307.130196 -63.734188)
		(width 0.0889)
		(layer "In11.Cu")
		(net "XDP_CPU_MBP1_N")
	)
	(segment
		(start 149.6822 -57.6326)
		(end 149.6822 -55.5752)
		(width 0.089408)
		(layer "In11.Cu")
		(net "XDP_CPU_MBP1_N")
	)
	(segment
		(start 155.9814 -61.1886)
		(end 153.2382 -61.1886)
		(width 0.089408)
		(layer "In11.Cu")
		(net "XDP_CPU_MBP1_N")
	)
	(segment
		(start 324.487286 -63.589154)
		(end 324.484746 -63.589154)
		(width 0.089408)
		(layer "In11.Cu")
		(net "XDP_CPU_MBP1_N")
	)
	(segment
		(start 302.65624 -64.229234)
		(end 302.686212 -64.229234)
		(width 0.0889)
		(layer "In11.Cu")
		(net "XDP_CPU_MBP1_N")
	)
	(segment
		(start 141.952218 -68.687188)
		(end 143.058388 -68.687188)
		(width 0.0889)
		(layer "In11.Cu")
		(net "XDP_CPU_MBP1_N")
	)
	(segment
		(start 313.188604 -65.458086)
		(end 321.257676 -65.458086)
		(width 0.0889)
		(layer "In11.Cu")
		(net "XDP_CPU_MBP1_N")
	)
	(segment
		(start 143.07185 -68.70065)
		(end 144.653 -68.70065)
		(width 0.0889)
		(layer "In11.Cu")
		(net "XDP_CPU_MBP1_N")
	)
	(segment
		(start 332.2828 -64.9732)
		(end 325.871332 -64.9732)
		(width 0.089408)
		(layer "In11.Cu")
		(net "XDP_CPU_MBP1_N")
	)
	(segment
		(start 304.37328 -64.229234)
		(end 304.403252 -64.229234)
		(width 0.0889)
		(layer "In11.Cu")
		(net "XDP_CPU_MBP1_N")
	)
	(segment
		(start 139.372848 -67.201034)
		(end 139.405614 -67.201034)
		(width 0.0889)
		(layer "In11.Cu")
		(net "XDP_CPU_MBP1_N")
	)
	(segment
		(start 321.257676 -65.458086)
		(end 323.127878 -63.587884)
		(width 0.089408)
		(layer "In11.Cu")
		(net "XDP_CPU_MBP1_N")
	)
	(segment
		(start 305.225196 -63.734188)
		(end 305.257962 -63.734188)
		(width 0.0889)
		(layer "In11.Cu")
		(net "XDP_CPU_MBP1_N")
	)
	(segment
		(start 141.089888 -68.191634)
		(end 141.122654 -68.191634)
		(width 0.0889)
		(layer "In11.Cu")
		(net "XDP_CPU_MBP1_N")
	)
	(segment
		(start 157.6959 -64.367664)
		(end 157.740604 -64.32296)
		(width 0.089408)
		(layer "In11.Cu")
		(net "XDP_CPU_MBP1_N")
	)
	(segment
		(start 160.274 -41.1226)
		(end 170.3578 -41.1226)
		(width 0.089408)
		(layer "In11.Cu")
		(net "XDP_CPU_MBP1_N")
	)
	(segment
		(start 153.362914 -68.70065)
		(end 157.6959 -64.367664)
		(width 0.089408)
		(layer "In11.Cu")
		(net "XDP_CPU_MBP1_N")
	)
	(segment
		(start 310.961532 -63.238634)
		(end 311.911238 -64.18834)
		(width 0.0889)
		(layer "In11.Cu")
		(net "XDP_CPU_MBP1_N")
	)
	(segment
		(start 153.2382 -61.1886)
		(end 149.6822 -57.6326)
		(width 0.089408)
		(layer "In11.Cu")
		(net "XDP_CPU_MBP1_N")
	)
	(segment
		(start 137.655808 -66.210434)
		(end 137.688574 -66.210434)
		(width 0.0889)
		(layer "In11.Cu")
		(net "XDP_CPU_MBP1_N")
	)
	(segment
		(start 300.074076 -64.724788)
		(end 300.106842 -64.724788)
		(width 0.0889)
		(layer "In11.Cu")
		(net "XDP_CPU_MBP1_N")
	)
	(segment
		(start 181.102 -23.495)
		(end 181.531768 -23.065232)
		(width 0.089408)
		(layer "In11.Cu")
		(net "XDP_CPU_MBP1_N")
	)
	(segment
		(start 143.058388 -68.687188)
		(end 143.07185 -68.70065)
		(width 0.0889)
		(layer "In11.Cu")
		(net "XDP_CPU_MBP1_N")
	)
	(segment
		(start 149.6822 -55.5752)
		(end 149.225 -55.118)
		(width 0.089408)
		(layer "In11.Cu")
		(net "XDP_CPU_MBP1_N")
	)
	(segment
		(start 149.225 -55.118)
		(end 149.225 -52.1716)
		(width 0.089408)
		(layer "In11.Cu")
		(net "XDP_CPU_MBP1_N")
	)
	(segment
		(start 181.531768 -23.065232)
		(end 181.531768 -22.334474)
		(width 0.089408)
		(layer "In11.Cu")
		(net "XDP_CPU_MBP1_N")
	)
	(segment
		(start 301.791116 -63.734188)
		(end 301.834296 -63.734188)
		(width 0.0889)
		(layer "In11.Cu")
		(net "XDP_CPU_MBP1_N")
	)
	(segment
		(start 306.080414 -63.238888)
		(end 306.352702 -63.238888)
		(width 0.0889)
		(layer "In11.Cu")
		(net "XDP_CPU_MBP1_N")
	)
	(segment
		(start 325.871332 -64.9732)
		(end 324.487286 -63.589154)
		(width 0.089408)
		(layer "In11.Cu")
		(net "XDP_CPU_MBP1_N")
	)
	(segment
		(start 324.484746 -63.587884)
		(end 324.486016 -63.587884)
		(width 0.089408)
		(layer "In11.Cu")
		(net "XDP_CPU_MBP1_N")
	)
	(arc
		(start 305.257962 -63.734188)
		(mid 305.451812 -63.677838)
		(end 305.593496 -63.534036)
		(width 0.0889)
		(layer "In11.Cu")
		(net "XDP_CPU_MBP1_N")
	)
	(arc
		(start 135.971534 -65.219834)
		(mid 136.256958 -65.303301)
		(end 136.465564 -65.515236)
		(width 0.0889)
		(layer "In11.Cu")
		(net "XDP_CPU_MBP1_N")
	)
	(arc
		(start 139.041124 -67.001136)
		(mid 139.181203 -67.143872)
		(end 139.372848 -67.201034)
		(width 0.0889)
		(layer "In11.Cu")
		(net "XDP_CPU_MBP1_N")
	)
	(arc
		(start 140.758164 -67.991736)
		(mid 140.898243 -68.134472)
		(end 141.089888 -68.191634)
		(width 0.0889)
		(layer "In11.Cu")
		(net "XDP_CPU_MBP1_N")
	)
	(arc
		(start 304.403252 -64.229234)
		(mid 304.594894 -64.172068)
		(end 304.734976 -64.029336)
		(width 0.0889)
		(layer "In11.Cu")
		(net "XDP_CPU_MBP1_N")
	)
	(arc
		(start 302.686212 -64.229234)
		(mid 302.877854 -64.172068)
		(end 303.017936 -64.029336)
		(width 0.0889)
		(layer "In11.Cu")
		(net "XDP_CPU_MBP1_N")
	)
	(arc
		(start 138.550904 -66.705988)
		(mid 138.834121 -66.790269)
		(end 139.041124 -67.001136)
		(width 0.0889)
		(layer "In11.Cu")
		(net "XDP_CPU_MBP1_N")
	)
	(arc
		(start 300.969172 -64.229234)
		(mid 301.160814 -64.172068)
		(end 301.300896 -64.029336)
		(width 0.0889)
		(layer "In11.Cu")
		(net "XDP_CPU_MBP1_N")
	)
	(arc
		(start 301.300896 -64.029336)
		(mid 301.5079 -63.818472)
		(end 301.791116 -63.734188)
		(width 0.0889)
		(layer "In11.Cu")
		(net "XDP_CPU_MBP1_N")
	)
	(arc
		(start 304.734976 -64.029336)
		(mid 304.94198 -63.818472)
		(end 305.225196 -63.734188)
		(width 0.0889)
		(layer "In11.Cu")
		(net "XDP_CPU_MBP1_N")
	)
	(arc
		(start 139.899644 -67.496436)
		(mid 140.041327 -67.64024)
		(end 140.235178 -67.696588)
		(width 0.0889)
		(layer "In11.Cu")
		(net "XDP_CPU_MBP1_N")
	)
	(arc
		(start 134.236714 -64.819784)
		(mid 134.639516 -64.822842)
		(end 135.039608 -64.776096)
		(width 0.0889)
		(layer "In11.Cu")
		(net "XDP_CPU_MBP1_N")
	)
	(arc
		(start 306.516278 -63.402464)
		(mid 306.57103 -63.464929)
		(end 306.617116 -63.534036)
		(width 0.0889)
		(layer "In11.Cu")
		(net "XDP_CPU_MBP1_N")
	)
	(arc
		(start 301.834296 -63.734188)
		(mid 302.117513 -63.818469)
		(end 302.324516 -64.029336)
		(width 0.0889)
		(layer "In11.Cu")
		(net "XDP_CPU_MBP1_N")
	)
	(arc
		(start 305.593496 -63.534036)
		(mid 305.799055 -63.323939)
		(end 306.080414 -63.238888)
		(width 0.0889)
		(layer "In11.Cu")
		(net "XDP_CPU_MBP1_N")
	)
	(arc
		(start 307.130196 -63.734188)
		(mid 307.255683 -63.654355)
		(end 307.346858 -63.53683)
		(width 0.0889)
		(layer "In11.Cu")
		(net "XDP_CPU_MBP1_N")
	)
	(arc
		(start 307.346858 -63.53683)
		(mid 307.492958 -63.354496)
		(end 307.695854 -63.238634)
		(width 0.0889)
		(layer "In11.Cu")
		(net "XDP_CPU_MBP1_N")
	)
	(arc
		(start 136.465564 -65.515236)
		(mid 136.607247 -65.65904)
		(end 136.801098 -65.715388)
		(width 0.0889)
		(layer "In11.Cu")
		(net "XDP_CPU_MBP1_N")
	)
	(arc
		(start 138.182604 -66.505836)
		(mid 138.324287 -66.64964)
		(end 138.518138 -66.705988)
		(width 0.0889)
		(layer "In11.Cu")
		(net "XDP_CPU_MBP1_N")
	)
	(arc
		(start 303.551336 -63.734188)
		(mid 303.834553 -63.818469)
		(end 304.041556 -64.029336)
		(width 0.0889)
		(layer "In11.Cu")
		(net "XDP_CPU_MBP1_N")
	)
	(arc
		(start 135.421624 -64.940434)
		(mid 135.644865 -65.145536)
		(end 135.938768 -65.219834)
		(width 0.0889)
		(layer "In11.Cu")
		(net "XDP_CPU_MBP1_N")
	)
	(arc
		(start 137.688574 -66.210434)
		(mid 137.973998 -66.293901)
		(end 138.182604 -66.505836)
		(width 0.0889)
		(layer "In11.Cu")
		(net "XDP_CPU_MBP1_N")
	)
	(arc
		(start 139.405614 -67.201034)
		(mid 139.691038 -67.284501)
		(end 139.899644 -67.496436)
		(width 0.0889)
		(layer "In11.Cu")
		(net "XDP_CPU_MBP1_N")
	)
	(arc
		(start 303.017936 -64.029336)
		(mid 303.22494 -63.818472)
		(end 303.508156 -63.734188)
		(width 0.0889)
		(layer "In11.Cu")
		(net "XDP_CPU_MBP1_N")
	)
	(arc
		(start 135.039608 -64.776096)
		(mid 135.255331 -64.800804)
		(end 135.421624 -64.940434)
		(width 0.0889)
		(layer "In11.Cu")
		(net "XDP_CPU_MBP1_N")
	)
	(arc
		(start 141.122654 -68.191634)
		(mid 141.408078 -68.275101)
		(end 141.616684 -68.487036)
		(width 0.0889)
		(layer "In11.Cu")
		(net "XDP_CPU_MBP1_N")
	)
	(arc
		(start 141.616684 -68.487036)
		(mid 141.758367 -68.63084)
		(end 141.952218 -68.687188)
		(width 0.0889)
		(layer "In11.Cu")
		(net "XDP_CPU_MBP1_N")
	)
	(arc
		(start 299.61967 -64.964818)
		(mid 299.819415 -64.792824)
		(end 300.074076 -64.724788)
		(width 0.0889)
		(layer "In11.Cu")
		(net "XDP_CPU_MBP1_N")
	)
	(arc
		(start 300.106842 -64.724788)
		(mid 300.300692 -64.668438)
		(end 300.442376 -64.524636)
		(width 0.0889)
		(layer "In11.Cu")
		(net "XDP_CPU_MBP1_N")
	)
	(arc
		(start 137.324084 -66.010536)
		(mid 137.464163 -66.153272)
		(end 137.655808 -66.210434)
		(width 0.0889)
		(layer "In11.Cu")
		(net "XDP_CPU_MBP1_N")
	)
	(arc
		(start 136.833864 -65.715388)
		(mid 137.117081 -65.799669)
		(end 137.324084 -66.010536)
		(width 0.0889)
		(layer "In11.Cu")
		(net "XDP_CPU_MBP1_N")
	)
	(arc
		(start 306.617116 -63.534036)
		(mid 306.758799 -63.67784)
		(end 306.95265 -63.734188)
		(width 0.0889)
		(layer "In11.Cu")
		(net "XDP_CPU_MBP1_N")
	)
	(arc
		(start 300.442376 -64.524636)
		(mid 300.650984 -64.312704)
		(end 300.936406 -64.229234)
		(width 0.0889)
		(layer "In11.Cu")
		(net "XDP_CPU_MBP1_N")
	)
	(arc
		(start 140.267944 -67.696588)
		(mid 140.551161 -67.780869)
		(end 140.758164 -67.991736)
		(width 0.0889)
		(layer "In11.Cu")
		(net "XDP_CPU_MBP1_N")
	)
	(arc
		(start 302.324516 -64.029336)
		(mid 302.464595 -64.172072)
		(end 302.65624 -64.229234)
		(width 0.0889)
		(layer "In11.Cu")
		(net "XDP_CPU_MBP1_N")
	)
	(arc
		(start 304.041556 -64.029336)
		(mid 304.181635 -64.172072)
		(end 304.37328 -64.229234)
		(width 0.0889)
		(layer "In11.Cu")
		(net "XDP_CPU_MBP1_N")
	)
	(segment
		(start 134.523734 -65.315338)
		(end 135.095234 -65.315338)
		(width 0.1016)
		(layer "F.Cu")
		(net "XDP_CPU_MBP0_N")
	)
	(segment
		(start 299.524166 -65.315338)
		(end 300.095666 -65.315338)
		(width 0.1016)
		(layer "F.Cu")
		(net "XDP_CPU_MBP0_N")
	)
	(via
		(at 181.932072 -22.525482)
		(size 0.508)
		(drill 0.254)
		(layers "F.Cu" "B.Cu")
		(net "XDP_CPU_MBP0_N")
	)
	(via
		(at 135.095234 -65.315338)
		(size 0.508)
		(drill 0.254)
		(layers "F.Cu" "B.Cu")
		(net "XDP_CPU_MBP0_N")
	)
	(via
		(at 331.87259 -65.5955)
		(size 0.508)
		(drill 0.254)
		(layers "F.Cu" "B.Cu")
		(net "XDP_CPU_MBP0_N")
	)
	(via
		(at 157.77591 -65.04305)
		(size 0.508)
		(drill 0.254)
		(layers "F.Cu" "B.Cu")
		(net "XDP_CPU_MBP0_N")
	)
	(via
		(at 162.463988 -73.71334)
		(size 0.508)
		(drill 0.254)
		(layers "F.Cu" "B.Cu")
		(net "XDP_CPU_MBP0_N")
	)
	(via
		(at 300.095666 -65.315338)
		(size 0.508)
		(drill 0.254)
		(layers "F.Cu" "B.Cu")
		(net "XDP_CPU_MBP0_N")
	)
	(via
		(at 323.996558 -64.293242)
		(size 0.508)
		(drill 0.254)
		(layers "F.Cu" "B.Cu")
		(net "XDP_CPU_MBP0_N")
	)
	(segment
		(start 331.87259 -65.5955)
		(end 331.87259 -66.02857)
		(width 0.10795)
		(layer "B.Cu")
		(net "XDP_CPU_MBP0_N")
	)
	(segment
		(start 331.6478 -66.25336)
		(end 330.97216 -66.25336)
		(width 0.10795)
		(layer "B.Cu")
		(net "XDP_CPU_MBP0_N")
	)
	(segment
		(start 162.463988 -72.871076)
		(end 162.463988 -73.71334)
		(width 0.10795)
		(layer "B.Cu")
		(net "XDP_CPU_MBP0_N")
	)
	(segment
		(start 331.87259 -66.02857)
		(end 331.6478 -66.25336)
		(width 0.10795)
		(layer "B.Cu")
		(net "XDP_CPU_MBP0_N")
	)
	(segment
		(start 322.163948 -54.487572)
		(end 324.002908 -52.648612)
		(width 0.089408)
		(layer "In9.Cu")
		(net "XDP_CPU_MBP0_N")
	)
	(segment
		(start 323.160644 -34.50463)
		(end 317.071756 -34.50463)
		(width 0.089408)
		(layer "In9.Cu")
		(net "XDP_CPU_MBP0_N")
	)
	(segment
		(start 258.503674 -16.058388)
		(end 258.485894 -16.058388)
		(width 0.089408)
		(layer "In9.Cu")
		(net "XDP_CPU_MBP0_N")
	)
	(segment
		(start 188.307726 -20.28444)
		(end 187.179966 -21.4122)
		(width 0.089408)
		(layer "In9.Cu")
		(net "XDP_CPU_MBP0_N")
	)
	(segment
		(start 325.470266 -36.814252)
		(end 323.160644 -34.50463)
		(width 0.089408)
		(layer "In9.Cu")
		(net "XDP_CPU_MBP0_N")
	)
	(segment
		(start 315.975746 -33.40862)
		(end 315.975746 -32.471868)
		(width 0.089408)
		(layer "In9.Cu")
		(net "XDP_CPU_MBP0_N")
	)
	(segment
		(start 325.019924 -44.76496)
		(end 325.019924 -42.33545)
		(width 0.089408)
		(layer "In9.Cu")
		(net "XDP_CPU_MBP0_N")
	)
	(segment
		(start 262.03783 -24.580596)
		(end 262.03783 -19.610324)
		(width 0.089408)
		(layer "In9.Cu")
		(net "XDP_CPU_MBP0_N")
	)
	(segment
		(start 158.565088 -65.832228)
		(end 158.565088 -68.740274)
		(width 0.089408)
		(layer "In9.Cu")
		(net "XDP_CPU_MBP0_N")
	)
	(segment
		(start 315.975746 -32.471868)
		(end 307.726842 -24.222964)
		(width 0.089408)
		(layer "In9.Cu")
		(net "XDP_CPU_MBP0_N")
	)
	(segment
		(start 325.470266 -41.885108)
		(end 325.470266 -36.814252)
		(width 0.089408)
		(layer "In9.Cu")
		(net "XDP_CPU_MBP0_N")
	)
	(segment
		(start 264.232644 -25.544526)
		(end 263.261856 -25.544526)
		(width 0.089408)
		(layer "In9.Cu")
		(net "XDP_CPU_MBP0_N")
	)
	(segment
		(start 323.996558 -64.293242)
		(end 323.996558 -63.753746)
		(width 0.089408)
		(layer "In9.Cu")
		(net "XDP_CPU_MBP0_N")
	)
	(segment
		(start 307.726842 -24.222964)
		(end 306.80914 -24.222964)
		(width 0.089408)
		(layer "In9.Cu")
		(net "XDP_CPU_MBP0_N")
	)
	(segment
		(start 258.909312 -16.481806)
		(end 258.909312 -16.464026)
		(width 0.089408)
		(layer "In9.Cu")
		(net "XDP_CPU_MBP0_N")
	)
	(segment
		(start 191.68618 -20.0914)
		(end 190.305182 -20.0914)
		(width 0.089408)
		(layer "In9.Cu")
		(net "XDP_CPU_MBP0_N")
	)
	(segment
		(start 263.261602 -25.54478)
		(end 263.002014 -25.54478)
		(width 0.089408)
		(layer "In9.Cu")
		(net "XDP_CPU_MBP0_N")
	)
	(segment
		(start 266.603226 -27.915108)
		(end 264.232644 -25.544526)
		(width 0.089408)
		(layer "In9.Cu")
		(net "XDP_CPU_MBP0_N")
	)
	(segment
		(start 274.97024 -27.915108)
		(end 266.603226 -27.915108)
		(width 0.089408)
		(layer "In9.Cu")
		(net "XDP_CPU_MBP0_N")
	)
	(segment
		(start 162.463988 -72.639682)
		(end 162.463988 -73.71334)
		(width 0.089408)
		(layer "In9.Cu")
		(net "XDP_CPU_MBP0_N")
	)
	(segment
		(start 258.485894 -16.058388)
		(end 257.66903 -15.241524)
		(width 0.089408)
		(layer "In9.Cu")
		(net "XDP_CPU_MBP0_N")
	)
	(segment
		(start 323.996558 -63.753746)
		(end 322.163948 -61.921136)
		(width 0.089408)
		(layer "In9.Cu")
		(net "XDP_CPU_MBP0_N")
	)
	(segment
		(start 324.002908 -52.648612)
		(end 324.002908 -50.93589)
		(width 0.089408)
		(layer "In9.Cu")
		(net "XDP_CPU_MBP0_N")
	)
	(segment
		(start 262.03783 -19.610324)
		(end 258.909312 -16.481806)
		(width 0.089408)
		(layer "In9.Cu")
		(net "XDP_CPU_MBP0_N")
	)
	(segment
		(start 182.748682 -21.4122)
		(end 181.932072 -22.22881)
		(width 0.089408)
		(layer "In9.Cu")
		(net "XDP_CPU_MBP0_N")
	)
	(segment
		(start 258.909312 -16.464026)
		(end 258.503674 -16.058388)
		(width 0.089408)
		(layer "In9.Cu")
		(net "XDP_CPU_MBP0_N")
	)
	(segment
		(start 195.953634 -15.241524)
		(end 192.7479 -18.447258)
		(width 0.089408)
		(layer "In9.Cu")
		(net "XDP_CPU_MBP0_N")
	)
	(segment
		(start 306.808886 -24.223218)
		(end 278.66213 -24.223218)
		(width 0.089408)
		(layer "In9.Cu")
		(net "XDP_CPU_MBP0_N")
	)
	(segment
		(start 325.019924 -42.33545)
		(end 325.470266 -41.885108)
		(width 0.089408)
		(layer "In9.Cu")
		(net "XDP_CPU_MBP0_N")
	)
	(segment
		(start 322.528946 -47.255938)
		(end 325.019924 -44.76496)
		(width 0.089408)
		(layer "In9.Cu")
		(net "XDP_CPU_MBP0_N")
	)
	(segment
		(start 257.66903 -15.241524)
		(end 195.953634 -15.241524)
		(width 0.089408)
		(layer "In9.Cu")
		(net "XDP_CPU_MBP0_N")
	)
	(segment
		(start 187.179966 -21.4122)
		(end 182.748682 -21.4122)
		(width 0.089408)
		(layer "In9.Cu")
		(net "XDP_CPU_MBP0_N")
	)
	(segment
		(start 324.002908 -50.93589)
		(end 322.528946 -49.461928)
		(width 0.089408)
		(layer "In9.Cu")
		(net "XDP_CPU_MBP0_N")
	)
	(segment
		(start 278.66213 -24.223218)
		(end 274.97024 -27.915108)
		(width 0.089408)
		(layer "In9.Cu")
		(net "XDP_CPU_MBP0_N")
	)
	(segment
		(start 322.163948 -61.921136)
		(end 322.163948 -54.487572)
		(width 0.089408)
		(layer "In9.Cu")
		(net "XDP_CPU_MBP0_N")
	)
	(segment
		(start 317.071756 -34.50463)
		(end 315.975746 -33.40862)
		(width 0.089408)
		(layer "In9.Cu")
		(net "XDP_CPU_MBP0_N")
	)
	(segment
		(start 162.463734 -72.63892)
		(end 162.463988 -72.639682)
		(width 0.089408)
		(layer "In9.Cu")
		(net "XDP_CPU_MBP0_N")
	)
	(segment
		(start 157.77591 -65.04305)
		(end 158.565088 -65.832228)
		(width 0.089408)
		(layer "In9.Cu")
		(net "XDP_CPU_MBP0_N")
	)
	(segment
		(start 192.7479 -19.02968)
		(end 191.68618 -20.0914)
		(width 0.089408)
		(layer "In9.Cu")
		(net "XDP_CPU_MBP0_N")
	)
	(segment
		(start 263.002014 -25.54478)
		(end 262.03783 -24.580596)
		(width 0.089408)
		(layer "In9.Cu")
		(net "XDP_CPU_MBP0_N")
	)
	(segment
		(start 190.112142 -20.28444)
		(end 188.307726 -20.28444)
		(width 0.089408)
		(layer "In9.Cu")
		(net "XDP_CPU_MBP0_N")
	)
	(segment
		(start 263.261856 -25.544526)
		(end 263.261602 -25.54478)
		(width 0.089408)
		(layer "In9.Cu")
		(net "XDP_CPU_MBP0_N")
	)
	(segment
		(start 181.932072 -22.22881)
		(end 181.932072 -22.525482)
		(width 0.089408)
		(layer "In9.Cu")
		(net "XDP_CPU_MBP0_N")
	)
	(segment
		(start 306.80914 -24.222964)
		(end 306.808886 -24.223218)
		(width 0.089408)
		(layer "In9.Cu")
		(net "XDP_CPU_MBP0_N")
	)
	(segment
		(start 190.305182 -20.0914)
		(end 190.112142 -20.28444)
		(width 0.089408)
		(layer "In9.Cu")
		(net "XDP_CPU_MBP0_N")
	)
	(segment
		(start 322.528946 -49.461928)
		(end 322.528946 -47.255938)
		(width 0.089408)
		(layer "In9.Cu")
		(net "XDP_CPU_MBP0_N")
	)
	(segment
		(start 158.565088 -68.740274)
		(end 162.463734 -72.63892)
		(width 0.089408)
		(layer "In9.Cu")
		(net "XDP_CPU_MBP0_N")
	)
	(segment
		(start 192.7479 -18.447258)
		(end 192.7479 -19.02968)
		(width 0.089408)
		(layer "In9.Cu")
		(net "XDP_CPU_MBP0_N")
	)
	(segment
		(start 136.794494 -65.905888)
		(end 136.82726 -65.905888)
		(width 0.0889)
		(layer "In11.Cu")
		(net "XDP_CPU_MBP0_N")
	)
	(segment
		(start 323.996558 -64.293242)
		(end 324.166738 -64.293242)
		(width 0.089408)
		(layer "In11.Cu")
		(net "XDP_CPU_MBP0_N")
	)
	(segment
		(start 311.7977 -64.48044)
		(end 311.79008 -64.48044)
		(width 0.0889)
		(layer "In11.Cu")
		(net "XDP_CPU_MBP0_N")
	)
	(segment
		(start 181.4576 -30.49016)
		(end 181.4576 -23.7236)
		(width 0.089408)
		(layer "In11.Cu")
		(net "XDP_CPU_MBP0_N")
	)
	(segment
		(start 181.4576 -23.7236)
		(end 181.932072 -23.249128)
		(width 0.089408)
		(layer "In11.Cu")
		(net "XDP_CPU_MBP0_N")
	)
	(segment
		(start 306.388516 -63.545974)
		(end 306.27193 -63.429388)
		(width 0.0889)
		(layer "In11.Cu")
		(net "XDP_CPU_MBP0_N")
	)
	(segment
		(start 149.56028 -52.29352)
		(end 160.2486 -41.6052)
		(width 0.089408)
		(layer "In11.Cu")
		(net "XDP_CPU_MBP0_N")
	)
	(segment
		(start 300.113446 -64.915288)
		(end 300.08068 -64.915288)
		(width 0.0889)
		(layer "In11.Cu")
		(net "XDP_CPU_MBP0_N")
	)
	(segment
		(start 137.649204 -66.400934)
		(end 137.68197 -66.400934)
		(width 0.0889)
		(layer "In11.Cu")
		(net "XDP_CPU_MBP0_N")
	)
	(segment
		(start 308.29504 -63.429134)
		(end 307.732176 -63.429134)
		(width 0.0889)
		(layer "In11.Cu")
		(net "XDP_CPU_MBP0_N")
	)
	(segment
		(start 300.975776 -64.419734)
		(end 300.94301 -64.419734)
		(width 0.0889)
		(layer "In11.Cu")
		(net "XDP_CPU_MBP0_N")
	)
	(segment
		(start 321.379342 -65.75044)
		(end 313.0677 -65.75044)
		(width 0.0889)
		(layer "In11.Cu")
		(net "XDP_CPU_MBP0_N")
	)
	(segment
		(start 322.83654 -64.293242)
		(end 321.869816 -65.259966)
		(width 0.089408)
		(layer "In11.Cu")
		(net "XDP_CPU_MBP0_N")
	)
	(segment
		(start 139.366244 -67.391534)
		(end 139.39901 -67.391534)
		(width 0.0889)
		(layer "In11.Cu")
		(net "XDP_CPU_MBP0_N")
	)
	(segment
		(start 306.27193 -63.429388)
		(end 306.087272 -63.429388)
		(width 0.0889)
		(layer "In11.Cu")
		(net "XDP_CPU_MBP0_N")
	)
	(segment
		(start 181.932072 -23.249128)
		(end 181.932072 -22.525482)
		(width 0.089408)
		(layer "In11.Cu")
		(net "XDP_CPU_MBP0_N")
	)
	(segment
		(start 311.79008 -64.48044)
		(end 310.91632 -63.60668)
		(width 0.0889)
		(layer "In11.Cu")
		(net "XDP_CPU_MBP0_N")
	)
	(segment
		(start 158.104332 -64.714628)
		(end 158.104332 -62.727332)
		(width 0.089408)
		(layer "In11.Cu")
		(net "XDP_CPU_MBP0_N")
	)
	(segment
		(start 301.827692 -63.924688)
		(end 301.79772 -63.924688)
		(width 0.0889)
		(layer "In11.Cu")
		(net "XDP_CPU_MBP0_N")
	)
	(segment
		(start 158.104332 -62.727332)
		(end 156.1084 -60.7314)
		(width 0.089408)
		(layer "In11.Cu")
		(net "XDP_CPU_MBP0_N")
	)
	(segment
		(start 157.77591 -65.04305)
		(end 158.104332 -64.714628)
		(width 0.089408)
		(layer "In11.Cu")
		(net "XDP_CPU_MBP0_N")
	)
	(segment
		(start 140.228574 -67.887088)
		(end 140.26134 -67.887088)
		(width 0.0889)
		(layer "In11.Cu")
		(net "XDP_CPU_MBP0_N")
	)
	(segment
		(start 310.91632 -63.60668)
		(end 308.472586 -63.60668)
		(width 0.0889)
		(layer "In11.Cu")
		(net "XDP_CPU_MBP0_N")
	)
	(segment
		(start 142.867634 -68.877688)
		(end 143.027146 -69.0372)
		(width 0.0889)
		(layer "In11.Cu")
		(net "XDP_CPU_MBP0_N")
	)
	(segment
		(start 323.996558 -64.293242)
		(end 322.83654 -64.293242)
		(width 0.089408)
		(layer "In11.Cu")
		(net "XDP_CPU_MBP0_N")
	)
	(segment
		(start 302.692816 -64.419734)
		(end 302.649636 -64.419734)
		(width 0.0889)
		(layer "In11.Cu")
		(net "XDP_CPU_MBP0_N")
	)
	(segment
		(start 149.56028 -54.97068)
		(end 149.56028 -52.29352)
		(width 0.089408)
		(layer "In11.Cu")
		(net "XDP_CPU_MBP0_N")
	)
	(segment
		(start 150.0124 -57.3786)
		(end 150.0124 -55.4228)
		(width 0.089408)
		(layer "In11.Cu")
		(net "XDP_CPU_MBP0_N")
	)
	(segment
		(start 304.409856 -64.419734)
		(end 304.366676 -64.419734)
		(width 0.0889)
		(layer "In11.Cu")
		(net "XDP_CPU_MBP0_N")
	)
	(segment
		(start 331.82179 -65.5447)
		(end 331.87259 -65.5955)
		(width 0.089408)
		(layer "In11.Cu")
		(net "XDP_CPU_MBP0_N")
	)
	(segment
		(start 135.932164 -65.410334)
		(end 135.96493 -65.410334)
		(width 0.0889)
		(layer "In11.Cu")
		(net "XDP_CPU_MBP0_N")
	)
	(segment
		(start 144.68475 -69.0372)
		(end 153.78176 -69.0372)
		(width 0.089408)
		(layer "In11.Cu")
		(net "XDP_CPU_MBP0_N")
	)
	(segment
		(start 141.083284 -68.382134)
		(end 141.11605 -68.382134)
		(width 0.0889)
		(layer "In11.Cu")
		(net "XDP_CPU_MBP0_N")
	)
	(segment
		(start 299.80255 -65.146174)
		(end 300.095666 -65.315338)
		(width 0.0889)
		(layer "In11.Cu")
		(net "XDP_CPU_MBP0_N")
	)
	(segment
		(start 308.472586 -63.60668)
		(end 308.29504 -63.429134)
		(width 0.0889)
		(layer "In11.Cu")
		(net "XDP_CPU_MBP0_N")
	)
	(segment
		(start 156.1084 -60.7314)
		(end 153.3652 -60.7314)
		(width 0.089408)
		(layer "In11.Cu")
		(net "XDP_CPU_MBP0_N")
	)
	(segment
		(start 153.3652 -60.7314)
		(end 150.0124 -57.3786)
		(width 0.089408)
		(layer "In11.Cu")
		(net "XDP_CPU_MBP0_N")
	)
	(segment
		(start 138.511534 -66.896488)
		(end 138.5443 -66.896488)
		(width 0.0889)
		(layer "In11.Cu")
		(net "XDP_CPU_MBP0_N")
	)
	(segment
		(start 299.781468 -65.067434)
		(end 299.80255 -65.146174)
		(width 0.0889)
		(layer "In11.Cu")
		(net "XDP_CPU_MBP0_N")
	)
	(segment
		(start 324.166738 -64.293242)
		(end 325.418196 -65.5447)
		(width 0.089408)
		(layer "In11.Cu")
		(net "XDP_CPU_MBP0_N")
	)
	(segment
		(start 141.945614 -68.877688)
		(end 142.867634 -68.877688)
		(width 0.0889)
		(layer "In11.Cu")
		(net "XDP_CPU_MBP0_N")
	)
	(segment
		(start 321.869816 -65.259966)
		(end 321.379342 -65.75044)
		(width 0.0889)
		(layer "In11.Cu")
		(net "XDP_CPU_MBP0_N")
	)
	(segment
		(start 325.418196 -65.5447)
		(end 331.82179 -65.5447)
		(width 0.089408)
		(layer "In11.Cu")
		(net "XDP_CPU_MBP0_N")
	)
	(segment
		(start 170.34256 -41.6052)
		(end 181.4576 -30.49016)
		(width 0.089408)
		(layer "In11.Cu")
		(net "XDP_CPU_MBP0_N")
	)
	(segment
		(start 313.0677 -65.75044)
		(end 311.7977 -64.48044)
		(width 0.0889)
		(layer "In11.Cu")
		(net "XDP_CPU_MBP0_N")
	)
	(segment
		(start 153.78176 -69.0372)
		(end 157.77591 -65.04305)
		(width 0.089408)
		(layer "In11.Cu")
		(net "XDP_CPU_MBP0_N")
	)
	(segment
		(start 143.027146 -69.0372)
		(end 144.68475 -69.0372)
		(width 0.0889)
		(layer "In11.Cu")
		(net "XDP_CPU_MBP0_N")
	)
	(segment
		(start 307.166518 -63.924688)
		(end 306.946046 -63.924688)
		(width 0.0889)
		(layer "In11.Cu")
		(net "XDP_CPU_MBP0_N")
	)
	(segment
		(start 160.2486 -41.6052)
		(end 170.34256 -41.6052)
		(width 0.089408)
		(layer "In11.Cu")
		(net "XDP_CPU_MBP0_N")
	)
	(segment
		(start 150.0124 -55.4228)
		(end 149.56028 -54.97068)
		(width 0.089408)
		(layer "In11.Cu")
		(net "XDP_CPU_MBP0_N")
	)
	(segment
		(start 303.544732 -63.924688)
		(end 303.51476 -63.924688)
		(width 0.0889)
		(layer "In11.Cu")
		(net "XDP_CPU_MBP0_N")
	)
	(segment
		(start 305.264566 -63.924688)
		(end 305.2318 -63.924688)
		(width 0.0889)
		(layer "In11.Cu")
		(net "XDP_CPU_MBP0_N")
	)
	(arc
		(start 306.452016 -63.629286)
		(mid 306.423011 -63.585537)
		(end 306.388516 -63.545974)
		(width 0.0889)
		(layer "In11.Cu")
		(net "XDP_CPU_MBP0_N")
	)
	(arc
		(start 307.515514 -63.626492)
		(mid 307.369414 -63.808826)
		(end 307.166518 -63.924688)
		(width 0.0889)
		(layer "In11.Cu")
		(net "XDP_CPU_MBP0_N")
	)
	(arc
		(start 307.732176 -63.429134)
		(mid 307.606689 -63.508967)
		(end 307.515514 -63.626492)
		(width 0.0889)
		(layer "In11.Cu")
		(net "XDP_CPU_MBP0_N")
	)
	(arc
		(start 138.876024 -67.096386)
		(mid 139.083028 -67.30725)
		(end 139.366244 -67.391534)
		(width 0.0889)
		(layer "In11.Cu")
		(net "XDP_CPU_MBP0_N")
	)
	(arc
		(start 300.94301 -64.419734)
		(mid 300.74916 -64.476084)
		(end 300.607476 -64.619886)
		(width 0.0889)
		(layer "In11.Cu")
		(net "XDP_CPU_MBP0_N")
	)
	(arc
		(start 138.017504 -66.601086)
		(mid 138.226112 -66.813018)
		(end 138.511534 -66.896488)
		(width 0.0889)
		(layer "In11.Cu")
		(net "XDP_CPU_MBP0_N")
	)
	(arc
		(start 302.649636 -64.419734)
		(mid 302.366419 -64.335453)
		(end 302.159416 -64.124586)
		(width 0.0889)
		(layer "In11.Cu")
		(net "XDP_CPU_MBP0_N")
	)
	(arc
		(start 137.158984 -66.105786)
		(mid 137.365988 -66.31665)
		(end 137.649204 -66.400934)
		(width 0.0889)
		(layer "In11.Cu")
		(net "XDP_CPU_MBP0_N")
	)
	(arc
		(start 303.876456 -64.124586)
		(mid 303.736377 -63.98185)
		(end 303.544732 -63.924688)
		(width 0.0889)
		(layer "In11.Cu")
		(net "XDP_CPU_MBP0_N")
	)
	(arc
		(start 141.451584 -68.582286)
		(mid 141.660192 -68.794218)
		(end 141.945614 -68.877688)
		(width 0.0889)
		(layer "In11.Cu")
		(net "XDP_CPU_MBP0_N")
	)
	(arc
		(start 301.465996 -64.124586)
		(mid 301.258992 -64.33545)
		(end 300.975776 -64.419734)
		(width 0.0889)
		(layer "In11.Cu")
		(net "XDP_CPU_MBP0_N")
	)
	(arc
		(start 136.82726 -65.905888)
		(mid 137.018902 -65.963054)
		(end 137.158984 -66.105786)
		(width 0.0889)
		(layer "In11.Cu")
		(net "XDP_CPU_MBP0_N")
	)
	(arc
		(start 305.2318 -63.924688)
		(mid 305.040158 -63.981854)
		(end 304.900076 -64.124586)
		(width 0.0889)
		(layer "In11.Cu")
		(net "XDP_CPU_MBP0_N")
	)
	(arc
		(start 304.900076 -64.124586)
		(mid 304.693072 -64.33545)
		(end 304.409856 -64.419734)
		(width 0.0889)
		(layer "In11.Cu")
		(net "XDP_CPU_MBP0_N")
	)
	(arc
		(start 136.300464 -65.610486)
		(mid 136.509072 -65.822418)
		(end 136.794494 -65.905888)
		(width 0.0889)
		(layer "In11.Cu")
		(net "XDP_CPU_MBP0_N")
	)
	(arc
		(start 140.26134 -67.887088)
		(mid 140.452982 -67.944254)
		(end 140.593064 -68.086986)
		(width 0.0889)
		(layer "In11.Cu")
		(net "XDP_CPU_MBP0_N")
	)
	(arc
		(start 304.366676 -64.419734)
		(mid 304.083459 -64.335453)
		(end 303.876456 -64.124586)
		(width 0.0889)
		(layer "In11.Cu")
		(net "XDP_CPU_MBP0_N")
	)
	(arc
		(start 135.96493 -65.410334)
		(mid 136.15878 -65.466684)
		(end 136.300464 -65.610486)
		(width 0.0889)
		(layer "In11.Cu")
		(net "XDP_CPU_MBP0_N")
	)
	(arc
		(start 141.11605 -68.382134)
		(mid 141.3099 -68.438484)
		(end 141.451584 -68.582286)
		(width 0.0889)
		(layer "In11.Cu")
		(net "XDP_CPU_MBP0_N")
	)
	(arc
		(start 302.159416 -64.124586)
		(mid 302.019337 -63.98185)
		(end 301.827692 -63.924688)
		(width 0.0889)
		(layer "In11.Cu")
		(net "XDP_CPU_MBP0_N")
	)
	(arc
		(start 137.68197 -66.400934)
		(mid 137.87582 -66.457284)
		(end 138.017504 -66.601086)
		(width 0.0889)
		(layer "In11.Cu")
		(net "XDP_CPU_MBP0_N")
	)
	(arc
		(start 301.79772 -63.924688)
		(mid 301.606078 -63.981854)
		(end 301.465996 -64.124586)
		(width 0.0889)
		(layer "In11.Cu")
		(net "XDP_CPU_MBP0_N")
	)
	(arc
		(start 300.08068 -64.915288)
		(mid 299.914386 -64.958522)
		(end 299.781468 -65.067434)
		(width 0.0889)
		(layer "In11.Cu")
		(net "XDP_CPU_MBP0_N")
	)
	(arc
		(start 306.087272 -63.429388)
		(mid 305.897343 -63.487258)
		(end 305.758596 -63.629286)
		(width 0.0889)
		(layer "In11.Cu")
		(net "XDP_CPU_MBP0_N")
	)
	(arc
		(start 306.946046 -63.924688)
		(mid 306.660622 -63.841221)
		(end 306.452016 -63.629286)
		(width 0.0889)
		(layer "In11.Cu")
		(net "XDP_CPU_MBP0_N")
	)
	(arc
		(start 300.607476 -64.619886)
		(mid 300.398868 -64.831818)
		(end 300.113446 -64.915288)
		(width 0.0889)
		(layer "In11.Cu")
		(net "XDP_CPU_MBP0_N")
	)
	(arc
		(start 305.758596 -63.629286)
		(mid 305.549988 -63.841218)
		(end 305.264566 -63.924688)
		(width 0.0889)
		(layer "In11.Cu")
		(net "XDP_CPU_MBP0_N")
	)
	(arc
		(start 303.183036 -64.124586)
		(mid 302.976032 -64.33545)
		(end 302.692816 -64.419734)
		(width 0.0889)
		(layer "In11.Cu")
		(net "XDP_CPU_MBP0_N")
	)
	(arc
		(start 303.51476 -63.924688)
		(mid 303.323118 -63.981854)
		(end 303.183036 -64.124586)
		(width 0.0889)
		(layer "In11.Cu")
		(net "XDP_CPU_MBP0_N")
	)
	(arc
		(start 135.095234 -65.315338)
		(mid 135.511012 -65.386508)
		(end 135.932164 -65.410334)
		(width 0.0889)
		(layer "In11.Cu")
		(net "XDP_CPU_MBP0_N")
	)
	(arc
		(start 140.593064 -68.086986)
		(mid 140.800068 -68.29785)
		(end 141.083284 -68.382134)
		(width 0.0889)
		(layer "In11.Cu")
		(net "XDP_CPU_MBP0_N")
	)
	(arc
		(start 139.39901 -67.391534)
		(mid 139.59286 -67.447884)
		(end 139.734544 -67.591686)
		(width 0.0889)
		(layer "In11.Cu")
		(net "XDP_CPU_MBP0_N")
	)
	(arc
		(start 138.5443 -66.896488)
		(mid 138.735942 -66.953654)
		(end 138.876024 -67.096386)
		(width 0.0889)
		(layer "In11.Cu")
		(net "XDP_CPU_MBP0_N")
	)
	(arc
		(start 139.734544 -67.591686)
		(mid 139.943152 -67.803618)
		(end 140.228574 -67.887088)
		(width 0.0889)
		(layer "In11.Cu")
		(net "XDP_CPU_MBP0_N")
	)
	(segment
		(start 131.089908 -62.343538)
		(end 131.661408 -62.343538)
		(width 0.1016)
		(layer "F.Cu")
		(net "XDP_CPU1_TDI")
	)
	(via
		(at 426.85208 -113.033048)
		(size 0.6604)
		(drill 0.3302)
		(layers "F.Cu" "B.Cu")
		(net "XDP_CPU1_TDI")
	)
	(via
		(at 131.661408 -62.343538)
		(size 0.508)
		(drill 0.254)
		(layers "F.Cu" "B.Cu")
		(net "XDP_CPU1_TDI")
	)
	(via
		(at 467.9823 -128.91008)
		(size 0.508)
		(drill 0.254)
		(layers "F.Cu" "B.Cu")
		(net "XDP_CPU1_TDI")
	)
	(via
		(at 325.692008 3.745738)
		(size 0.508)
		(drill 0.254)
		(layers "F.Cu" "B.Cu")
		(net "XDP_CPU1_TDI")
	)
	(via
		(at 427.013116 -114.118644)
		(size 0.508)
		(drill 0.254)
		(layers "F.Cu" "B.Cu")
		(net "XDP_CPU1_TDI")
	)
	(via
		(at 460.629 -133.731)
		(size 0.508)
		(drill 0.254)
		(layers "F.Cu" "B.Cu")
		(net "XDP_CPU1_TDI")
	)
	(via
		(at 178.77663 -22.56282)
		(size 0.508)
		(drill 0.254)
		(layers "F.Cu" "B.Cu")
		(net "XDP_CPU1_TDI")
	)
	(via
		(at 462.3816 -127.2794)
		(size 0.508)
		(drill 0.254)
		(layers "F.Cu" "B.Cu")
		(net "XDP_CPU1_TDI")
	)
	(via
		(at 423.409872 -66.195194)
		(size 0.508)
		(drill 0.254)
		(layers "F.Cu" "B.Cu")
		(net "XDP_CPU1_TDI")
	)
	(via
		(at 494.01095 -57.404254)
		(size 0.508)
		(drill 0.254)
		(layers "F.Cu" "B.Cu")
		(net "XDP_CPU1_TDI")
	)
	(via
		(at 426.728382 4.244594)
		(size 0.508)
		(drill 0.254)
		(layers "F.Cu" "B.Cu")
		(net "XDP_CPU1_TDI")
	)
	(via
		(at 473.53347 -64.47155)
		(size 0.508)
		(drill 0.254)
		(layers "F.Cu" "B.Cu")
		(net "XDP_CPU1_TDI")
	)
	(via
		(at 322.061586 -12.00023)
		(size 0.508)
		(drill 0.254)
		(layers "F.Cu" "B.Cu")
		(net "XDP_CPU1_TDI")
	)
	(via
		(at 466.6488 -133.5278)
		(size 0.508)
		(drill 0.254)
		(layers "F.Cu" "B.Cu")
		(net "XDP_CPU1_TDI")
	)
	(segment
		(start 425.10456 -110.021116)
		(end 425.10456 -80.397096)
		(width 0.10795)
		(layer "B.Cu")
		(net "XDP_CPU1_TDI")
	)
	(segment
		(start 426.85208 -113.957608)
		(end 426.85208 -113.033048)
		(width 0.10795)
		(layer "B.Cu")
		(net "XDP_CPU1_TDI")
	)
	(segment
		(start 426.85208 -113.033048)
		(end 426.85208 -111.768636)
		(width 0.10795)
		(layer "B.Cu")
		(net "XDP_CPU1_TDI")
	)
	(segment
		(start 424.875198 -73.538334)
		(end 424.59275 -73.255886)
		(width 0.10795)
		(layer "B.Cu")
		(net "XDP_CPU1_TDI")
	)
	(segment
		(start 423.318686 -70.673214)
		(end 423.318686 -66.28638)
		(width 0.10795)
		(layer "B.Cu")
		(net "XDP_CPU1_TDI")
	)
	(segment
		(start 425.10456 -80.397096)
		(end 424.875198 -80.167734)
		(width 0.10795)
		(layer "B.Cu")
		(net "XDP_CPU1_TDI")
	)
	(segment
		(start 424.59275 -71.947278)
		(end 423.318686 -70.673214)
		(width 0.10795)
		(layer "B.Cu")
		(net "XDP_CPU1_TDI")
	)
	(segment
		(start 427.013116 -114.118644)
		(end 426.85208 -113.957608)
		(width 0.10795)
		(layer "B.Cu")
		(net "XDP_CPU1_TDI")
	)
	(segment
		(start 424.59275 -73.255886)
		(end 424.59275 -71.947278)
		(width 0.10795)
		(layer "B.Cu")
		(net "XDP_CPU1_TDI")
	)
	(segment
		(start 178.795426 -22.473412)
		(end 178.795426 -21.0439)
		(width 0.10795)
		(layer "B.Cu")
		(net "XDP_CPU1_TDI")
	)
	(segment
		(start 426.85208 -111.768636)
		(end 425.10456 -110.021116)
		(width 0.10795)
		(layer "B.Cu")
		(net "XDP_CPU1_TDI")
	)
	(segment
		(start 462.0514 -127.2794)
		(end 461.751172 -127.579628)
		(width 0.10795)
		(layer "B.Cu")
		(net "XDP_CPU1_TDI")
	)
	(segment
		(start 424.875198 -80.167734)
		(end 424.875198 -73.538334)
		(width 0.10795)
		(layer "B.Cu")
		(net "XDP_CPU1_TDI")
	)
	(segment
		(start 178.77663 -22.56282)
		(end 178.77663 -22.492208)
		(width 0.10795)
		(layer "B.Cu")
		(net "XDP_CPU1_TDI")
	)
	(segment
		(start 461.751172 -127.579628)
		(end 461.751172 -127.9144)
		(width 0.10795)
		(layer "B.Cu")
		(net "XDP_CPU1_TDI")
	)
	(segment
		(start 462.3816 -127.2794)
		(end 462.0514 -127.2794)
		(width 0.10795)
		(layer "B.Cu")
		(net "XDP_CPU1_TDI")
	)
	(segment
		(start 178.77663 -22.492208)
		(end 178.795426 -22.473412)
		(width 0.10795)
		(layer "B.Cu")
		(net "XDP_CPU1_TDI")
	)
	(segment
		(start 423.318686 -66.28638)
		(end 423.409872 -66.195194)
		(width 0.10795)
		(layer "B.Cu")
		(net "XDP_CPU1_TDI")
	)
	(segment
		(start 460.668116 -135.254492)
		(end 460.577946 -135.164322)
		(width 0.089408)
		(layer "In2.Cu")
		(net "XDP_CPU1_TDI")
	)
	(segment
		(start 471.427302 -4.092956)
		(end 467.2584 0.075946)
		(width 0.089408)
		(layer "In2.Cu")
		(net "XDP_CPU1_TDI")
	)
	(segment
		(start 499.174008 -35.173412)
		(end 501.181878 -33.165542)
		(width 0.089408)
		(layer "In2.Cu")
		(net "XDP_CPU1_TDI")
	)
	(segment
		(start 494.03 -57.314592)
		(end 494.118392 -57.2262)
		(width 0.089408)
		(layer "In2.Cu")
		(net "XDP_CPU1_TDI")
	)
	(segment
		(start 460.577946 -135.164322)
		(end 460.577946 -133.782054)
		(width 0.089408)
		(layer "In2.Cu")
		(net "XDP_CPU1_TDI")
	)
	(segment
		(start 467.2584 0.075946)
		(end 467.2584 1.574546)
		(width 0.089408)
		(layer "In2.Cu")
		(net "XDP_CPU1_TDI")
	)
	(segment
		(start 476.699326 -4.092956)
		(end 471.427302 -4.092956)
		(width 0.089408)
		(layer "In2.Cu")
		(net "XDP_CPU1_TDI")
	)
	(segment
		(start 501.181878 -19.096228)
		(end 500.143526 -18.057876)
		(width 0.089408)
		(layer "In2.Cu")
		(net "XDP_CPU1_TDI")
	)
	(segment
		(start 500.143526 -18.057876)
		(end 494.880392 -18.057876)
		(width 0.089408)
		(layer "In2.Cu")
		(net "XDP_CPU1_TDI")
	)
	(segment
		(start 479.213164 -8.637524)
		(end 479.213164 -5.618226)
		(width 0.089408)
		(layer "In2.Cu")
		(net "XDP_CPU1_TDI")
	)
	(segment
		(start 497.459 -36.349686)
		(end 498.635274 -35.173412)
		(width 0.089408)
		(layer "In2.Cu")
		(net "XDP_CPU1_TDI")
	)
	(segment
		(start 322.061586 -12.00023)
		(end 323.409564 -12.00023)
		(width 0.089408)
		(layer "In2.Cu")
		(net "XDP_CPU1_TDI")
	)
	(segment
		(start 466.6488 -133.5278)
		(end 465.3026 -134.874)
		(width 0.089408)
		(layer "In2.Cu")
		(net "XDP_CPU1_TDI")
	)
	(segment
		(start 467.2584 1.574546)
		(end 465.9122 2.920746)
		(width 0.089408)
		(layer "In2.Cu")
		(net "XDP_CPU1_TDI")
	)
	(segment
		(start 479.21291 -9.397238)
		(end 479.21291 -8.637778)
		(width 0.089408)
		(layer "In2.Cu")
		(net "XDP_CPU1_TDI")
	)
	(segment
		(start 482.954076 -16.850868)
		(end 480.408488 -14.30528)
		(width 0.089408)
		(layer "In2.Cu")
		(net "XDP_CPU1_TDI")
	)
	(segment
		(start 478.110804 -5.153152)
		(end 477.863408 -5.153152)
		(width 0.089408)
		(layer "In2.Cu")
		(net "XDP_CPU1_TDI")
	)
	(segment
		(start 465.9122 3.868166)
		(end 464.693254 5.087112)
		(width 0.089408)
		(layer "In2.Cu")
		(net "XDP_CPU1_TDI")
	)
	(segment
		(start 497.92128 -49.277016)
		(end 497.92128 -46.65726)
		(width 0.089408)
		(layer "In2.Cu")
		(net "XDP_CPU1_TDI")
	)
	(segment
		(start 427.5709 5.087112)
		(end 426.728382 4.244594)
		(width 0.089408)
		(layer "In2.Cu")
		(net "XDP_CPU1_TDI")
	)
	(segment
		(start 494.010696 -57.404254)
		(end 494.010696 -57.404)
		(width 0.089408)
		(layer "In2.Cu")
		(net "XDP_CPU1_TDI")
	)
	(segment
		(start 479.21291 -8.637778)
		(end 479.213164 -8.637524)
		(width 0.089408)
		(layer "In2.Cu")
		(net "XDP_CPU1_TDI")
	)
	(segment
		(start 494.118392 -57.2262)
		(end 494.118392 -52.253388)
		(width 0.089408)
		(layer "In2.Cu")
		(net "XDP_CPU1_TDI")
	)
	(segment
		(start 477.861884 -5.151628)
		(end 477.757998 -5.151628)
		(width 0.089408)
		(layer "In2.Cu")
		(net "XDP_CPU1_TDI")
	)
	(segment
		(start 497.459 -46.19498)
		(end 497.459 -36.349686)
		(width 0.089408)
		(layer "In2.Cu")
		(net "XDP_CPU1_TDI")
	)
	(segment
		(start 462.280508 -135.254492)
		(end 460.668116 -135.254492)
		(width 0.089408)
		(layer "In2.Cu")
		(net "XDP_CPU1_TDI")
	)
	(segment
		(start 478.111058 -5.152898)
		(end 478.110804 -5.153152)
		(width 0.089408)
		(layer "In2.Cu")
		(net "XDP_CPU1_TDI")
	)
	(segment
		(start 501.181878 -33.165542)
		(end 501.181878 -19.096228)
		(width 0.089408)
		(layer "In2.Cu")
		(net "XDP_CPU1_TDI")
	)
	(segment
		(start 494.01095 -57.404254)
		(end 494.010696 -57.404254)
		(width 0.089408)
		(layer "In2.Cu")
		(net "XDP_CPU1_TDI")
	)
	(segment
		(start 479.213164 -5.618226)
		(end 478.747836 -5.152898)
		(width 0.089408)
		(layer "In2.Cu")
		(net "XDP_CPU1_TDI")
	)
	(segment
		(start 464.693254 5.087112)
		(end 427.5709 5.087112)
		(width 0.089408)
		(layer "In2.Cu")
		(net "XDP_CPU1_TDI")
	)
	(segment
		(start 465.3026 -134.874)
		(end 462.661 -134.874)
		(width 0.089408)
		(layer "In2.Cu")
		(net "XDP_CPU1_TDI")
	)
	(segment
		(start 494.880392 -18.057876)
		(end 493.675924 -16.853408)
		(width 0.089408)
		(layer "In2.Cu")
		(net "XDP_CPU1_TDI")
	)
	(segment
		(start 325.692008 3.526028)
		(end 325.692008 3.745738)
		(width 0.089408)
		(layer "In2.Cu")
		(net "XDP_CPU1_TDI")
	)
	(segment
		(start 323.409564 -12.00023)
		(end 323.633592 -11.776202)
		(width 0.089408)
		(layer "In2.Cu")
		(net "XDP_CPU1_TDI")
	)
	(segment
		(start 494.03 -57.404)
		(end 494.03 -57.314592)
		(width 0.089408)
		(layer "In2.Cu")
		(net "XDP_CPU1_TDI")
	)
	(segment
		(start 496.068096 -51.1302)
		(end 497.92128 -49.277016)
		(width 0.089408)
		(layer "In2.Cu")
		(net "XDP_CPU1_TDI")
	)
	(segment
		(start 477.757998 -5.151628)
		(end 476.699326 -4.092956)
		(width 0.089408)
		(layer "In2.Cu")
		(net "XDP_CPU1_TDI")
	)
	(segment
		(start 323.633592 -11.776202)
		(end 323.633592 1.467612)
		(width 0.089408)
		(layer "In2.Cu")
		(net "XDP_CPU1_TDI")
	)
	(segment
		(start 480.408488 -10.592816)
		(end 479.21291 -9.397238)
		(width 0.089408)
		(layer "In2.Cu")
		(net "XDP_CPU1_TDI")
	)
	(segment
		(start 488.542838 -18.070068)
		(end 487.157522 -18.070068)
		(width 0.089408)
		(layer "In2.Cu")
		(net "XDP_CPU1_TDI")
	)
	(segment
		(start 477.863408 -5.153152)
		(end 477.861884 -5.151628)
		(width 0.089408)
		(layer "In2.Cu")
		(net "XDP_CPU1_TDI")
	)
	(segment
		(start 323.633592 1.467612)
		(end 325.692008 3.526028)
		(width 0.089408)
		(layer "In2.Cu")
		(net "XDP_CPU1_TDI")
	)
	(segment
		(start 489.759498 -16.853408)
		(end 488.542838 -18.070068)
		(width 0.089408)
		(layer "In2.Cu")
		(net "XDP_CPU1_TDI")
	)
	(segment
		(start 478.747836 -5.152898)
		(end 478.111058 -5.152898)
		(width 0.089408)
		(layer "In2.Cu")
		(net "XDP_CPU1_TDI")
	)
	(segment
		(start 480.408488 -14.30528)
		(end 480.408488 -10.592816)
		(width 0.089408)
		(layer "In2.Cu")
		(net "XDP_CPU1_TDI")
	)
	(segment
		(start 494.118392 -52.253388)
		(end 495.24158 -51.1302)
		(width 0.089408)
		(layer "In2.Cu")
		(net "XDP_CPU1_TDI")
	)
	(segment
		(start 493.675924 -16.853408)
		(end 489.759498 -16.853408)
		(width 0.089408)
		(layer "In2.Cu")
		(net "XDP_CPU1_TDI")
	)
	(segment
		(start 497.92128 -46.65726)
		(end 497.459 -46.19498)
		(width 0.089408)
		(layer "In2.Cu")
		(net "XDP_CPU1_TDI")
	)
	(segment
		(start 460.577946 -133.782054)
		(end 460.629 -133.731)
		(width 0.089408)
		(layer "In2.Cu")
		(net "XDP_CPU1_TDI")
	)
	(segment
		(start 462.661 -134.874)
		(end 462.280508 -135.254492)
		(width 0.089408)
		(layer "In2.Cu")
		(net "XDP_CPU1_TDI")
	)
	(segment
		(start 495.24158 -51.1302)
		(end 496.068096 -51.1302)
		(width 0.089408)
		(layer "In2.Cu")
		(net "XDP_CPU1_TDI")
	)
	(segment
		(start 465.9122 2.920746)
		(end 465.9122 3.868166)
		(width 0.089408)
		(layer "In2.Cu")
		(net "XDP_CPU1_TDI")
	)
	(segment
		(start 487.157522 -18.070068)
		(end 485.938322 -16.850868)
		(width 0.089408)
		(layer "In2.Cu")
		(net "XDP_CPU1_TDI")
	)
	(segment
		(start 485.938322 -16.850868)
		(end 482.954076 -16.850868)
		(width 0.089408)
		(layer "In2.Cu")
		(net "XDP_CPU1_TDI")
	)
	(segment
		(start 494.010696 -57.404)
		(end 494.03 -57.404)
		(width 0.089408)
		(layer "In2.Cu")
		(net "XDP_CPU1_TDI")
	)
	(segment
		(start 498.635274 -35.173412)
		(end 499.174008 -35.173412)
		(width 0.089408)
		(layer "In2.Cu")
		(net "XDP_CPU1_TDI")
	)
	(segment
		(start 467.1314 -129.76098)
		(end 467.9823 -128.91008)
		(width 0.089408)
		(layer "In4.Cu")
		(net "XDP_CPU1_TDI")
	)
	(segment
		(start 425.096178 -65.790318)
		(end 424.724576 -66.16192)
		(width 0.089408)
		(layer "In4.Cu")
		(net "XDP_CPU1_TDI")
	)
	(segment
		(start 472.214702 -65.790318)
		(end 425.096178 -65.790318)
		(width 0.089408)
		(layer "In4.Cu")
		(net "XDP_CPU1_TDI")
	)
	(segment
		(start 466.6488 -133.5278)
		(end 467.1314 -133.0452)
		(width 0.089408)
		(layer "In4.Cu")
		(net "XDP_CPU1_TDI")
	)
	(segment
		(start 423.443146 -66.16192)
		(end 423.409872 -66.195194)
		(width 0.089408)
		(layer "In4.Cu")
		(net "XDP_CPU1_TDI")
	)
	(segment
		(start 467.1314 -133.0452)
		(end 467.1314 -129.76098)
		(width 0.089408)
		(layer "In4.Cu")
		(net "XDP_CPU1_TDI")
	)
	(segment
		(start 473.53347 -64.47155)
		(end 472.214702 -65.790318)
		(width 0.089408)
		(layer "In4.Cu")
		(net "XDP_CPU1_TDI")
	)
	(segment
		(start 424.724576 -66.16192)
		(end 423.443146 -66.16192)
		(width 0.089408)
		(layer "In4.Cu")
		(net "XDP_CPU1_TDI")
	)
	(segment
		(start 428.06747 -117.767608)
		(end 428.067216 -117.767608)
		(width 0.089408)
		(layer "In9.Cu")
		(net "XDP_CPU1_TDI")
	)
	(segment
		(start 425.474892 5.498084)
		(end 368.543078 5.498084)
		(width 0.089408)
		(layer "In9.Cu")
		(net "XDP_CPU1_TDI")
	)
	(segment
		(start 186.782202 -16.783304)
		(end 186.782202 -18.017744)
		(width 0.089408)
		(layer "In9.Cu")
		(net "XDP_CPU1_TDI")
	)
	(segment
		(start 440.854846 -126.894082)
		(end 440.854846 -127.80899)
		(width 0.089408)
		(layer "In9.Cu")
		(net "XDP_CPU1_TDI")
	)
	(segment
		(start 187.074048 -16.491458)
		(end 186.782202 -16.783304)
		(width 0.089408)
		(layer "In9.Cu")
		(net "XDP_CPU1_TDI")
	)
	(segment
		(start 184.15635 -19.509232)
		(end 181.239414 -19.509232)
		(width 0.089408)
		(layer "In9.Cu")
		(net "XDP_CPU1_TDI")
	)
	(segment
		(start 186.782202 -18.017744)
		(end 186.402472 -18.397474)
		(width 0.089408)
		(layer "In9.Cu")
		(net "XDP_CPU1_TDI")
	)
	(segment
		(start 367.491264 0.132842)
		(end 363.25175 -4.106672)
		(width 0.089408)
		(layer "In9.Cu")
		(net "XDP_CPU1_TDI")
	)
	(segment
		(start 428.210218 -122.022616)
		(end 428.210218 -123.915424)
		(width 0.089408)
		(layer "In9.Cu")
		(net "XDP_CPU1_TDI")
	)
	(segment
		(start 428.210218 -123.915424)
		(end 428.563786 -124.268992)
		(width 0.089408)
		(layer "In9.Cu")
		(net "XDP_CPU1_TDI")
	)
	(segment
		(start 449.737988 -135.419846)
		(end 453.479154 -135.419846)
		(width 0.089408)
		(layer "In9.Cu")
		(net "XDP_CPU1_TDI")
	)
	(segment
		(start 187.074048 -16.256762)
		(end 187.074048 -16.491458)
		(width 0.089408)
		(layer "In9.Cu")
		(net "XDP_CPU1_TDI")
	)
	(segment
		(start 265.75512 -14.805152)
		(end 265.069066 -14.805152)
		(width 0.089408)
		(layer "In9.Cu")
		(net "XDP_CPU1_TDI")
	)
	(segment
		(start 453.479154 -135.419846)
		(end 456.872086 -132.026914)
		(width 0.089408)
		(layer "In9.Cu")
		(net "XDP_CPU1_TDI")
	)
	(segment
		(start 321.59321 -14.341856)
		(end 321.343782 -14.591284)
		(width 0.089408)
		(layer "In9.Cu")
		(net "XDP_CPU1_TDI")
	)
	(segment
		(start 186.402472 -18.397474)
		(end 185.268108 -18.397474)
		(width 0.089408)
		(layer "In9.Cu")
		(net "XDP_CPU1_TDI")
	)
	(segment
		(start 440.854846 -127.80899)
		(end 446.539112 -133.493256)
		(width 0.089408)
		(layer "In9.Cu")
		(net "XDP_CPU1_TDI")
	)
	(segment
		(start 428.422054 -119.826786)
		(end 428.422054 -121.81078)
		(width 0.089408)
		(layer "In9.Cu")
		(net "XDP_CPU1_TDI")
	)
	(segment
		(start 262.532114 -15.443708)
		(end 262.155686 -15.06728)
		(width 0.089408)
		(layer "In9.Cu")
		(net "XDP_CPU1_TDI")
	)
	(segment
		(start 192.748154 -13.748512)
		(end 191.041274 -15.455392)
		(width 0.089408)
		(layer "In9.Cu")
		(net "XDP_CPU1_TDI")
	)
	(segment
		(start 459.663038 -133.915404)
		(end 460.444596 -133.915404)
		(width 0.089408)
		(layer "In9.Cu")
		(net "XDP_CPU1_TDI")
	)
	(segment
		(start 428.067216 -117.767608)
		(end 427.649894 -118.18493)
		(width 0.089408)
		(layer "In9.Cu")
		(net "XDP_CPU1_TDI")
	)
	(segment
		(start 181.239414 -19.509232)
		(end 178.77663 -21.972016)
		(width 0.089408)
		(layer "In9.Cu")
		(net "XDP_CPU1_TDI")
	)
	(segment
		(start 446.539112 -133.493256)
		(end 447.811398 -133.493256)
		(width 0.089408)
		(layer "In9.Cu")
		(net "XDP_CPU1_TDI")
	)
	(segment
		(start 428.663608 -115.638326)
		(end 428.663608 -117.17147)
		(width 0.089408)
		(layer "In9.Cu")
		(net "XDP_CPU1_TDI")
	)
	(segment
		(start 428.422054 -121.81078)
		(end 428.210218 -122.022616)
		(width 0.089408)
		(layer "In9.Cu")
		(net "XDP_CPU1_TDI")
	)
	(segment
		(start 427.013116 -114.118644)
		(end 427.143926 -114.118644)
		(width 0.089408)
		(layer "In9.Cu")
		(net "XDP_CPU1_TDI")
	)
	(segment
		(start 460.444596 -133.915404)
		(end 460.629 -133.731)
		(width 0.089408)
		(layer "In9.Cu")
		(net "XDP_CPU1_TDI")
	)
	(segment
		(start 321.343782 -14.591284)
		(end 265.968988 -14.591284)
		(width 0.089408)
		(layer "In9.Cu")
		(net "XDP_CPU1_TDI")
	)
	(segment
		(start 264.43051 -15.443708)
		(end 262.532114 -15.443708)
		(width 0.089408)
		(layer "In9.Cu")
		(net "XDP_CPU1_TDI")
	)
	(segment
		(start 265.069066 -14.805152)
		(end 264.43051 -15.443708)
		(width 0.089408)
		(layer "In9.Cu")
		(net "XDP_CPU1_TDI")
	)
	(segment
		(start 192.748154 -13.01623)
		(end 192.748154 -13.748512)
		(width 0.089408)
		(layer "In9.Cu")
		(net "XDP_CPU1_TDI")
	)
	(segment
		(start 427.143926 -114.118644)
		(end 428.663608 -115.638326)
		(width 0.089408)
		(layer "In9.Cu")
		(net "XDP_CPU1_TDI")
	)
	(segment
		(start 265.968988 -14.591284)
		(end 265.75512 -14.805152)
		(width 0.089408)
		(layer "In9.Cu")
		(net "XDP_CPU1_TDI")
	)
	(segment
		(start 322.530216 -13.559028)
		(end 322.530216 -13.965174)
		(width 0.089408)
		(layer "In9.Cu")
		(net "XDP_CPU1_TDI")
	)
	(segment
		(start 426.728382 4.244594)
		(end 425.474892 5.498084)
		(width 0.089408)
		(layer "In9.Cu")
		(net "XDP_CPU1_TDI")
	)
	(segment
		(start 194.902836 -10.861548)
		(end 192.748154 -13.01623)
		(width 0.089408)
		(layer "In9.Cu")
		(net "XDP_CPU1_TDI")
	)
	(segment
		(start 428.563786 -124.268992)
		(end 437.90616 -124.268992)
		(width 0.089408)
		(layer "In9.Cu")
		(net "XDP_CPU1_TDI")
	)
	(segment
		(start 439.437526 -125.800358)
		(end 439.761122 -125.800358)
		(width 0.089408)
		(layer "In9.Cu")
		(net "XDP_CPU1_TDI")
	)
	(segment
		(start 178.77663 -21.972016)
		(end 178.77663 -22.56282)
		(width 0.089408)
		(layer "In9.Cu")
		(net "XDP_CPU1_TDI")
	)
	(segment
		(start 326.841104 3.841496)
		(end 326.5932 4.0894)
		(width 0.089408)
		(layer "In9.Cu")
		(net "XDP_CPU1_TDI")
	)
	(segment
		(start 355.320092 -4.106672)
		(end 354.724208 -3.510788)
		(width 0.089408)
		(layer "In9.Cu")
		(net "XDP_CPU1_TDI")
	)
	(segment
		(start 459.428596 -133.680962)
		(end 459.663038 -133.915404)
		(width 0.089408)
		(layer "In9.Cu")
		(net "XDP_CPU1_TDI")
	)
	(segment
		(start 322.530216 -13.965174)
		(end 322.153534 -14.341856)
		(width 0.089408)
		(layer "In9.Cu")
		(net "XDP_CPU1_TDI")
	)
	(segment
		(start 353.7204 -0.128778)
		(end 353.7204 4.47421)
		(width 0.089408)
		(layer "In9.Cu")
		(net "XDP_CPU1_TDI")
	)
	(segment
		(start 322.061586 -13.090398)
		(end 322.530216 -13.559028)
		(width 0.089408)
		(layer "In9.Cu")
		(net "XDP_CPU1_TDI")
	)
	(segment
		(start 326.5932 4.0894)
		(end 326.03567 4.0894)
		(width 0.089408)
		(layer "In9.Cu")
		(net "XDP_CPU1_TDI")
	)
	(segment
		(start 456.872086 -132.026914)
		(end 458.361034 -132.026914)
		(width 0.089408)
		(layer "In9.Cu")
		(net "XDP_CPU1_TDI")
	)
	(segment
		(start 327.503028 4.959604)
		(end 327.503028 4.02844)
		(width 0.089408)
		(layer "In9.Cu")
		(net "XDP_CPU1_TDI")
	)
	(segment
		(start 187.875418 -15.455392)
		(end 187.074048 -16.256762)
		(width 0.089408)
		(layer "In9.Cu")
		(net "XDP_CPU1_TDI")
	)
	(segment
		(start 354.724208 -1.132586)
		(end 353.7204 -0.128778)
		(width 0.089408)
		(layer "In9.Cu")
		(net "XDP_CPU1_TDI")
	)
	(segment
		(start 367.491264 4.44627)
		(end 367.491264 0.132842)
		(width 0.089408)
		(layer "In9.Cu")
		(net "XDP_CPU1_TDI")
	)
	(segment
		(start 326.03567 4.0894)
		(end 325.692008 3.745738)
		(width 0.089408)
		(layer "In9.Cu")
		(net "XDP_CPU1_TDI")
	)
	(segment
		(start 437.90616 -124.268992)
		(end 439.437526 -125.800358)
		(width 0.089408)
		(layer "In9.Cu")
		(net "XDP_CPU1_TDI")
	)
	(segment
		(start 458.361034 -132.026914)
		(end 459.428596 -133.094476)
		(width 0.089408)
		(layer "In9.Cu")
		(net "XDP_CPU1_TDI")
	)
	(segment
		(start 354.724208 -3.510788)
		(end 354.724208 -1.132586)
		(width 0.089408)
		(layer "In9.Cu")
		(net "XDP_CPU1_TDI")
	)
	(segment
		(start 327.316084 3.841496)
		(end 326.841104 3.841496)
		(width 0.089408)
		(layer "In9.Cu")
		(net "XDP_CPU1_TDI")
	)
	(segment
		(start 191.041274 -15.455392)
		(end 187.875418 -15.455392)
		(width 0.089408)
		(layer "In9.Cu")
		(net "XDP_CPU1_TDI")
	)
	(segment
		(start 328.040746 5.497322)
		(end 327.503028 4.959604)
		(width 0.089408)
		(layer "In9.Cu")
		(net "XDP_CPU1_TDI")
	)
	(segment
		(start 428.663608 -117.17147)
		(end 428.06747 -117.767608)
		(width 0.089408)
		(layer "In9.Cu")
		(net "XDP_CPU1_TDI")
	)
	(segment
		(start 427.649894 -118.18493)
		(end 427.649894 -119.054626)
		(width 0.089408)
		(layer "In9.Cu")
		(net "XDP_CPU1_TDI")
	)
	(segment
		(start 322.153534 -14.341856)
		(end 321.59321 -14.341856)
		(width 0.089408)
		(layer "In9.Cu")
		(net "XDP_CPU1_TDI")
	)
	(segment
		(start 459.428596 -133.094476)
		(end 459.428596 -133.680962)
		(width 0.089408)
		(layer "In9.Cu")
		(net "XDP_CPU1_TDI")
	)
	(segment
		(start 353.7204 4.47421)
		(end 352.697288 5.497322)
		(width 0.089408)
		(layer "In9.Cu")
		(net "XDP_CPU1_TDI")
	)
	(segment
		(start 447.811398 -133.493256)
		(end 449.737988 -135.419846)
		(width 0.089408)
		(layer "In9.Cu")
		(net "XDP_CPU1_TDI")
	)
	(segment
		(start 260.998716 -14.230604)
		(end 260.998716 -12.163552)
		(width 0.089408)
		(layer "In9.Cu")
		(net "XDP_CPU1_TDI")
	)
	(segment
		(start 322.061586 -12.00023)
		(end 322.061586 -13.090398)
		(width 0.089408)
		(layer "In9.Cu")
		(net "XDP_CPU1_TDI")
	)
	(segment
		(start 363.25175 -4.106672)
		(end 355.320092 -4.106672)
		(width 0.089408)
		(layer "In9.Cu")
		(net "XDP_CPU1_TDI")
	)
	(segment
		(start 259.696712 -10.861548)
		(end 194.902836 -10.861548)
		(width 0.089408)
		(layer "In9.Cu")
		(net "XDP_CPU1_TDI")
	)
	(segment
		(start 368.543078 5.498084)
		(end 367.491264 4.44627)
		(width 0.089408)
		(layer "In9.Cu")
		(net "XDP_CPU1_TDI")
	)
	(segment
		(start 427.649894 -119.054626)
		(end 428.422054 -119.826786)
		(width 0.089408)
		(layer "In9.Cu")
		(net "XDP_CPU1_TDI")
	)
	(segment
		(start 327.503028 4.02844)
		(end 327.316084 3.841496)
		(width 0.089408)
		(layer "In9.Cu")
		(net "XDP_CPU1_TDI")
	)
	(segment
		(start 185.268108 -18.397474)
		(end 184.15635 -19.509232)
		(width 0.089408)
		(layer "In9.Cu")
		(net "XDP_CPU1_TDI")
	)
	(segment
		(start 352.697288 5.497322)
		(end 328.040746 5.497322)
		(width 0.089408)
		(layer "In9.Cu")
		(net "XDP_CPU1_TDI")
	)
	(segment
		(start 262.155686 -15.06728)
		(end 261.835392 -15.06728)
		(width 0.089408)
		(layer "In9.Cu")
		(net "XDP_CPU1_TDI")
	)
	(segment
		(start 439.761122 -125.800358)
		(end 440.854846 -126.894082)
		(width 0.089408)
		(layer "In9.Cu")
		(net "XDP_CPU1_TDI")
	)
	(segment
		(start 260.998716 -12.163552)
		(end 259.696712 -10.861548)
		(width 0.089408)
		(layer "In9.Cu")
		(net "XDP_CPU1_TDI")
	)
	(segment
		(start 261.835392 -15.06728)
		(end 260.998716 -14.230604)
		(width 0.089408)
		(layer "In9.Cu")
		(net "XDP_CPU1_TDI")
	)
	(segment
		(start 474.56344 -64.604392)
		(end 477.890332 -61.2775)
		(width 0.089408)
		(layer "In11.Cu")
		(net "XDP_CPU1_TDI")
	)
	(segment
		(start 138.3792 -58.8264)
		(end 137.8966 -59.309)
		(width 0.089408)
		(layer "In11.Cu")
		(net "XDP_CPU1_TDI")
	)
	(segment
		(start 133.38937 -61.752988)
		(end 133.356604 -61.752988)
		(width 0.0889)
		(layer "In11.Cu")
		(net "XDP_CPU1_TDI")
	)
	(segment
		(start 137.4902 -59.309)
		(end 136.8552 -59.944)
		(width 0.089408)
		(layer "In11.Cu")
		(net "XDP_CPU1_TDI")
	)
	(segment
		(start 141.224 -57.3786)
		(end 140.9192 -57.3786)
		(width 0.089408)
		(layer "In11.Cu")
		(net "XDP_CPU1_TDI")
	)
	(segment
		(start 467.1695 -128.0922)
		(end 464.3882 -128.0922)
		(width 0.089408)
		(layer "In11.Cu")
		(net "XDP_CPU1_TDI")
	)
	(segment
		(start 493.649 -57.404)
		(end 494.010696 -57.404)
		(width 0.089408)
		(layer "In11.Cu")
		(net "XDP_CPU1_TDI")
	)
	(segment
		(start 143.633444 -56.940196)
		(end 143.27124 -57.3024)
		(width 0.089408)
		(layer "In11.Cu")
		(net "XDP_CPU1_TDI")
	)
	(segment
		(start 467.9823 -128.91008)
		(end 467.1695 -128.09728)
		(width 0.089408)
		(layer "In11.Cu")
		(net "XDP_CPU1_TDI")
	)
	(segment
		(start 464.3882 -128.0922)
		(end 463.5754 -127.2794)
		(width 0.089408)
		(layer "In11.Cu")
		(net "XDP_CPU1_TDI")
	)
	(segment
		(start 139.5984 -58.3184)
		(end 139.1666 -58.3184)
		(width 0.089408)
		(layer "In11.Cu")
		(net "XDP_CPU1_TDI")
	)
	(segment
		(start 483.371398 -61.2775)
		(end 484.749094 -59.899804)
		(width 0.089408)
		(layer "In11.Cu")
		(net "XDP_CPU1_TDI")
	)
	(segment
		(start 173.1264 -29.949902)
		(end 172.874432 -30.558232)
		(width 0.089408)
		(layer "In11.Cu")
		(net "XDP_CPU1_TDI")
	)
	(segment
		(start 140.9192 -57.3786)
		(end 140.462 -57.8358)
		(width 0.089408)
		(layer "In11.Cu")
		(net "XDP_CPU1_TDI")
	)
	(segment
		(start 484.749094 -59.899804)
		(end 486.459276 -59.899804)
		(width 0.089408)
		(layer "In11.Cu")
		(net "XDP_CPU1_TDI")
	)
	(segment
		(start 175.094646 -25.006554)
		(end 174.651924 -25.449276)
		(width 0.089408)
		(layer "In11.Cu")
		(net "XDP_CPU1_TDI")
	)
	(segment
		(start 140.462 -57.8358)
		(end 140.081 -57.8358)
		(width 0.089408)
		(layer "In11.Cu")
		(net "XDP_CPU1_TDI")
	)
	(segment
		(start 494.010696 -57.404)
		(end 494.010696 -57.404254)
		(width 0.089408)
		(layer "In11.Cu")
		(net "XDP_CPU1_TDI")
	)
	(segment
		(start 463.5754 -127.2794)
		(end 462.3816 -127.2794)
		(width 0.089408)
		(layer "In11.Cu")
		(net "XDP_CPU1_TDI")
	)
	(segment
		(start 135.116824 -60.762388)
		(end 135.073644 -60.762388)
		(width 0.0889)
		(layer "In11.Cu")
		(net "XDP_CPU1_TDI")
	)
	(segment
		(start 158.949898 -35.690302)
		(end 146.741134 -47.899066)
		(width 0.089408)
		(layer "In11.Cu")
		(net "XDP_CPU1_TDI")
	)
	(segment
		(start 177.696368 -23.928832)
		(end 175.094646 -25.006554)
		(width 0.089408)
		(layer "In11.Cu")
		(net "XDP_CPU1_TDI")
	)
	(segment
		(start 141.6558 -56.9468)
		(end 141.224 -57.3786)
		(width 0.089408)
		(layer "In11.Cu")
		(net "XDP_CPU1_TDI")
	)
	(segment
		(start 140.081 -57.8358)
		(end 139.5984 -58.3184)
		(width 0.089408)
		(layer "In11.Cu")
		(net "XDP_CPU1_TDI")
	)
	(segment
		(start 145.034 -52.020216)
		(end 145.034 -53.558694)
		(width 0.089408)
		(layer "In11.Cu")
		(net "XDP_CPU1_TDI")
	)
	(segment
		(start 135.8138 -60.3504)
		(end 135.383524 -60.780676)
		(width 0.089408)
		(layer "In11.Cu")
		(net "XDP_CPU1_TDI")
	)
	(segment
		(start 165.028626 -33.1724)
		(end 158.949898 -35.690302)
		(width 0.089408)
		(layer "In11.Cu")
		(net "XDP_CPU1_TDI")
	)
	(segment
		(start 132.53466 -62.248034)
		(end 132.501894 -62.248034)
		(width 0.0889)
		(layer "In11.Cu")
		(net "XDP_CPU1_TDI")
	)
	(segment
		(start 146.741134 -47.899066)
		(end 145.034 -52.020216)
		(width 0.089408)
		(layer "In11.Cu")
		(net "XDP_CPU1_TDI")
	)
	(segment
		(start 477.890332 -61.2775)
		(end 483.371398 -61.2775)
		(width 0.089408)
		(layer "In11.Cu")
		(net "XDP_CPU1_TDI")
	)
	(segment
		(start 486.459276 -59.899804)
		(end 490.301534 -56.057546)
		(width 0.089408)
		(layer "In11.Cu")
		(net "XDP_CPU1_TDI")
	)
	(segment
		(start 473.53347 -64.47155)
		(end 473.666312 -64.604392)
		(width 0.089408)
		(layer "In11.Cu")
		(net "XDP_CPU1_TDI")
	)
	(segment
		(start 168.743122 -33.1724)
		(end 165.028626 -33.1724)
		(width 0.089408)
		(layer "In11.Cu")
		(net "XDP_CPU1_TDI")
	)
	(segment
		(start 492.302546 -56.057546)
		(end 493.649 -57.404)
		(width 0.089408)
		(layer "In11.Cu")
		(net "XDP_CPU1_TDI")
	)
	(segment
		(start 138.6586 -58.8264)
		(end 138.3792 -58.8264)
		(width 0.089408)
		(layer "In11.Cu")
		(net "XDP_CPU1_TDI")
	)
	(segment
		(start 494.010696 -57.404254)
		(end 494.01095 -57.404254)
		(width 0.089408)
		(layer "In11.Cu")
		(net "XDP_CPU1_TDI")
	)
	(segment
		(start 171.332906 -32.099758)
		(end 168.743122 -33.1724)
		(width 0.089408)
		(layer "In11.Cu")
		(net "XDP_CPU1_TDI")
	)
	(segment
		(start 490.301534 -56.057546)
		(end 492.302546 -56.057546)
		(width 0.089408)
		(layer "In11.Cu")
		(net "XDP_CPU1_TDI")
	)
	(segment
		(start 467.1695 -128.09728)
		(end 467.1695 -128.0922)
		(width 0.089408)
		(layer "In11.Cu")
		(net "XDP_CPU1_TDI")
	)
	(segment
		(start 178.77663 -22.84857)
		(end 177.696368 -23.928832)
		(width 0.089408)
		(layer "In11.Cu")
		(net "XDP_CPU1_TDI")
	)
	(segment
		(start 136.8552 -59.944)
		(end 136.6012 -59.944)
		(width 0.089408)
		(layer "In11.Cu")
		(net "XDP_CPU1_TDI")
	)
	(segment
		(start 136.6012 -59.944)
		(end 136.1948 -60.3504)
		(width 0.089408)
		(layer "In11.Cu")
		(net "XDP_CPU1_TDI")
	)
	(segment
		(start 137.8966 -59.309)
		(end 137.4902 -59.309)
		(width 0.089408)
		(layer "In11.Cu")
		(net "XDP_CPU1_TDI")
	)
	(segment
		(start 172.874432 -30.558232)
		(end 171.332906 -32.099758)
		(width 0.089408)
		(layer "In11.Cu")
		(net "XDP_CPU1_TDI")
	)
	(segment
		(start 134.2517 -61.257434)
		(end 134.218934 -61.257434)
		(width 0.0889)
		(layer "In11.Cu")
		(net "XDP_CPU1_TDI")
	)
	(segment
		(start 178.77663 -22.56282)
		(end 178.77663 -22.84857)
		(width 0.089408)
		(layer "In11.Cu")
		(net "XDP_CPU1_TDI")
	)
	(segment
		(start 145.034 -53.558694)
		(end 143.633444 -56.940196)
		(width 0.089408)
		(layer "In11.Cu")
		(net "XDP_CPU1_TDI")
	)
	(segment
		(start 142.5702 -57.3024)
		(end 142.2146 -56.9468)
		(width 0.089408)
		(layer "In11.Cu")
		(net "XDP_CPU1_TDI")
	)
	(segment
		(start 143.27124 -57.3024)
		(end 142.5702 -57.3024)
		(width 0.089408)
		(layer "In11.Cu")
		(net "XDP_CPU1_TDI")
	)
	(segment
		(start 142.2146 -56.9468)
		(end 141.6558 -56.9468)
		(width 0.089408)
		(layer "In11.Cu")
		(net "XDP_CPU1_TDI")
	)
	(segment
		(start 174.651924 -25.449276)
		(end 173.1264 -29.132276)
		(width 0.089408)
		(layer "In11.Cu")
		(net "XDP_CPU1_TDI")
	)
	(segment
		(start 473.666312 -64.604392)
		(end 474.56344 -64.604392)
		(width 0.089408)
		(layer "In11.Cu")
		(net "XDP_CPU1_TDI")
	)
	(segment
		(start 136.1948 -60.3504)
		(end 135.8138 -60.3504)
		(width 0.089408)
		(layer "In11.Cu")
		(net "XDP_CPU1_TDI")
	)
	(segment
		(start 173.1264 -29.132276)
		(end 173.1264 -29.949902)
		(width 0.089408)
		(layer "In11.Cu")
		(net "XDP_CPU1_TDI")
	)
	(segment
		(start 139.1666 -58.3184)
		(end 138.6586 -58.8264)
		(width 0.089408)
		(layer "In11.Cu")
		(net "XDP_CPU1_TDI")
	)
	(segment
		(start 135.383524 -60.780676)
		(end 135.2423 -60.780676)
		(width 0.0889)
		(layer "In11.Cu")
		(net "XDP_CPU1_TDI")
	)
	(arc
		(start 134.583424 -61.057536)
		(mid 134.443345 -61.200272)
		(end 134.2517 -61.257434)
		(width 0.0889)
		(layer "In11.Cu")
		(net "XDP_CPU1_TDI")
	)
	(arc
		(start 135.073644 -60.762388)
		(mid 134.790427 -60.846669)
		(end 134.583424 -61.057536)
		(width 0.0889)
		(layer "In11.Cu")
		(net "XDP_CPU1_TDI")
	)
	(arc
		(start 133.724904 -61.552836)
		(mid 133.583221 -61.69664)
		(end 133.38937 -61.752988)
		(width 0.0889)
		(layer "In11.Cu")
		(net "XDP_CPU1_TDI")
	)
	(arc
		(start 133.356604 -61.752988)
		(mid 133.073387 -61.837269)
		(end 132.866384 -62.048136)
		(width 0.0889)
		(layer "In11.Cu")
		(net "XDP_CPU1_TDI")
	)
	(arc
		(start 132.501894 -62.248034)
		(mid 132.078947 -62.271987)
		(end 131.661408 -62.343538)
		(width 0.0889)
		(layer "In11.Cu")
		(net "XDP_CPU1_TDI")
	)
	(arc
		(start 134.218934 -61.257434)
		(mid 133.93351 -61.340901)
		(end 133.724904 -61.552836)
		(width 0.0889)
		(layer "In11.Cu")
		(net "XDP_CPU1_TDI")
	)
	(arc
		(start 135.2423 -60.780676)
		(mid 135.180055 -60.768147)
		(end 135.116824 -60.762388)
		(width 0.0889)
		(layer "In11.Cu")
		(net "XDP_CPU1_TDI")
	)
	(arc
		(start 132.866384 -62.048136)
		(mid 132.726305 -62.190872)
		(end 132.53466 -62.248034)
		(width 0.0889)
		(layer "In11.Cu")
		(net "XDP_CPU1_TDI")
	)
	(segment
		(start 296.66184 -63.334138)
		(end 296.09034 -63.334138)
		(width 0.1016)
		(layer "F.Cu")
		(net "XDP_CPU0_TDO")
	)
	(via
		(at 355.99751 -58.27649)
		(size 0.508)
		(drill 0.254)
		(layers "F.Cu" "B.Cu")
		(net "XDP_CPU0_TDO")
	)
	(via
		(at 354.70338 -83.823556)
		(size 0.508)
		(drill 0.254)
		(layers "F.Cu" "B.Cu")
		(net "XDP_CPU0_TDO")
	)
	(via
		(at 296.66184 -63.334138)
		(size 0.508)
		(drill 0.254)
		(layers "F.Cu" "B.Cu")
		(net "XDP_CPU0_TDO")
	)
	(via
		(at 459.6638 -128.74625)
		(size 0.508)
		(drill 0.254)
		(layers "F.Cu" "B.Cu")
		(net "XDP_CPU0_TDO")
	)
	(segment
		(start 459.37805 -127.9144)
		(end 459.486 -128.02235)
		(width 0.10795)
		(layer "B.Cu")
		(net "XDP_CPU0_TDO")
	)
	(segment
		(start 460.739744 -129.015998)
		(end 460.191104 -129.015998)
		(width 0.10795)
		(layer "B.Cu")
		(net "XDP_CPU0_TDO")
	)
	(segment
		(start 296.229024 -65.038986)
		(end 296.229024 -64.481964)
		(width 0.10795)
		(layer "B.Cu")
		(net "XDP_CPU0_TDO")
	)
	(segment
		(start 459.5114 -129.2606)
		(end 459.0034 -128.7526)
		(width 0.10795)
		(layer "B.Cu")
		(net "XDP_CPU0_TDO")
	)
	(segment
		(start 296.66184 -63.588138)
		(end 296.66184 -63.334138)
		(width 0.10795)
		(layer "B.Cu")
		(net "XDP_CPU0_TDO")
	)
	(segment
		(start 296.229024 -64.481964)
		(end 296.185336 -64.438276)
		(width 0.10795)
		(layer "B.Cu")
		(net "XDP_CPU0_TDO")
	)
	(segment
		(start 296.185336 -64.438276)
		(end 296.185336 -64.064642)
		(width 0.10795)
		(layer "B.Cu")
		(net "XDP_CPU0_TDO")
	)
	(segment
		(start 296.0116 -65.462404)
		(end 296.0116 -65.25641)
		(width 0.10795)
		(layer "B.Cu")
		(net "XDP_CPU0_TDO")
	)
	(segment
		(start 296.0116 -65.25641)
		(end 296.229024 -65.038986)
		(width 0.10795)
		(layer "B.Cu")
		(net "XDP_CPU0_TDO")
	)
	(segment
		(start 459.486 -128.56845)
		(end 459.6638 -128.74625)
		(width 0.10795)
		(layer "B.Cu")
		(net "XDP_CPU0_TDO")
	)
	(segment
		(start 459.0034 -127.9144)
		(end 459.37805 -127.9144)
		(width 0.10795)
		(layer "B.Cu")
		(net "XDP_CPU0_TDO")
	)
	(segment
		(start 461.101186 -129.6924)
		(end 461.101186 -129.37744)
		(width 0.10795)
		(layer "B.Cu")
		(net "XDP_CPU0_TDO")
	)
	(segment
		(start 296.185336 -64.064642)
		(end 296.66184 -63.588138)
		(width 0.10795)
		(layer "B.Cu")
		(net "XDP_CPU0_TDO")
	)
	(segment
		(start 459.0034 -128.7526)
		(end 459.0034 -127.9144)
		(width 0.10795)
		(layer "B.Cu")
		(net "XDP_CPU0_TDO")
	)
	(segment
		(start 459.946502 -129.2606)
		(end 459.5114 -129.2606)
		(width 0.10795)
		(layer "B.Cu")
		(net "XDP_CPU0_TDO")
	)
	(segment
		(start 459.486 -128.02235)
		(end 459.486 -128.56845)
		(width 0.10795)
		(layer "B.Cu")
		(net "XDP_CPU0_TDO")
	)
	(segment
		(start 460.191104 -129.015998)
		(end 459.946502 -129.2606)
		(width 0.10795)
		(layer "B.Cu")
		(net "XDP_CPU0_TDO")
	)
	(segment
		(start 461.101186 -129.37744)
		(end 460.739744 -129.015998)
		(width 0.10795)
		(layer "B.Cu")
		(net "XDP_CPU0_TDO")
	)
	(segment
		(start 420.199058 -142.324836)
		(end 419.272974 -143.25092)
		(width 0.089408)
		(layer "In4.Cu")
		(net "XDP_CPU0_TDO")
	)
	(segment
		(start 443.103 -142.113)
		(end 442.536834 -142.113)
		(width 0.089408)
		(layer "In4.Cu")
		(net "XDP_CPU0_TDO")
	)
	(segment
		(start 385.305808 -141.44752)
		(end 384.656584 -142.096744)
		(width 0.089408)
		(layer "In4.Cu")
		(net "XDP_CPU0_TDO")
	)
	(segment
		(start 338.689696 -130.363214)
		(end 339.378798 -129.674112)
		(width 0.089408)
		(layer "In4.Cu")
		(net "XDP_CPU0_TDO")
	)
	(segment
		(start 364.669832 -141.160754)
		(end 362.347764 -141.160754)
		(width 0.089408)
		(layer "In4.Cu")
		(net "XDP_CPU0_TDO")
	)
	(segment
		(start 343.346278 -116.313712)
		(end 343.015062 -115.982496)
		(width 0.089408)
		(layer "In4.Cu")
		(net "XDP_CPU0_TDO")
	)
	(segment
		(start 454.767696 -144.633696)
		(end 453.358504 -144.633696)
		(width 0.089408)
		(layer "In4.Cu")
		(net "XDP_CPU0_TDO")
	)
	(segment
		(start 362.286296 -141.099286)
		(end 361.001818 -141.099286)
		(width 0.089408)
		(layer "In4.Cu")
		(net "XDP_CPU0_TDO")
	)
	(segment
		(start 462.629504 -145.66138)
		(end 460.902558 -147.388326)
		(width 0.089408)
		(layer "In4.Cu")
		(net "XDP_CPU0_TDO")
	)
	(segment
		(start 409.7528 -147.259802)
		(end 408.25801 -148.754592)
		(width 0.089408)
		(layer "In4.Cu")
		(net "XDP_CPU0_TDO")
	)
	(segment
		(start 461.066896 -133.074156)
		(end 461.066896 -133.834378)
		(width 0.089408)
		(layer "In4.Cu")
		(net "XDP_CPU0_TDO")
	)
	(segment
		(start 339.704426 -129.444496)
		(end 342.287606 -126.861316)
		(width 0.089408)
		(layer "In4.Cu")
		(net "XDP_CPU0_TDO")
	)
	(segment
		(start 457.398374 -147.264374)
		(end 454.767696 -144.633696)
		(width 0.089408)
		(layer "In4.Cu")
		(net "XDP_CPU0_TDO")
	)
	(segment
		(start 338.689696 -132.59435)
		(end 338.689696 -130.363214)
		(width 0.089408)
		(layer "In4.Cu")
		(net "XDP_CPU0_TDO")
	)
	(segment
		(start 392.856212 -141.948662)
		(end 392.35507 -141.44752)
		(width 0.089408)
		(layer "In4.Cu")
		(net "XDP_CPU0_TDO")
	)
	(segment
		(start 460.902558 -147.388326)
		(end 460.285846 -147.388326)
		(width 0.089408)
		(layer "In4.Cu")
		(net "XDP_CPU0_TDO")
	)
	(segment
		(start 403.81428 -145.851372)
		(end 402.6916 -145.851372)
		(width 0.089408)
		(layer "In4.Cu")
		(net "XDP_CPU0_TDO")
	)
	(segment
		(start 353.309936 -85.217)
		(end 354.70338 -83.823556)
		(width 0.089408)
		(layer "In4.Cu")
		(net "XDP_CPU0_TDO")
	)
	(segment
		(start 332.8543 -95.750634)
		(end 337.901534 -90.7034)
		(width 0.089408)
		(layer "In4.Cu")
		(net "XDP_CPU0_TDO")
	)
	(segment
		(start 406.7175 -148.754592)
		(end 403.81428 -145.851372)
		(width 0.089408)
		(layer "In4.Cu")
		(net "XDP_CPU0_TDO")
	)
	(segment
		(start 402.6916 -145.851372)
		(end 402.420074 -146.122898)
		(width 0.089408)
		(layer "In4.Cu")
		(net "XDP_CPU0_TDO")
	)
	(segment
		(start 382.778508 -141.620748)
		(end 371.125496 -141.620748)
		(width 0.089408)
		(layer "In4.Cu")
		(net "XDP_CPU0_TDO")
	)
	(segment
		(start 352.752406 -138.858752)
		(end 348.83852 -138.858752)
		(width 0.089408)
		(layer "In4.Cu")
		(net "XDP_CPU0_TDO")
	)
	(segment
		(start 384.656584 -142.096744)
		(end 383.254504 -142.096744)
		(width 0.089408)
		(layer "In4.Cu")
		(net "XDP_CPU0_TDO")
	)
	(segment
		(start 340.6394 -90.0176)
		(end 348.520004 -90.0176)
		(width 0.089408)
		(layer "In4.Cu")
		(net "XDP_CPU0_TDO")
	)
	(segment
		(start 383.254504 -142.096744)
		(end 382.778508 -141.620748)
		(width 0.089408)
		(layer "In4.Cu")
		(net "XDP_CPU0_TDO")
	)
	(segment
		(start 370.92128 -141.824964)
		(end 365.334042 -141.824964)
		(width 0.089408)
		(layer "In4.Cu")
		(net "XDP_CPU0_TDO")
	)
	(segment
		(start 440.631834 -144.018)
		(end 436.626 -144.018)
		(width 0.089408)
		(layer "In4.Cu")
		(net "XDP_CPU0_TDO")
	)
	(segment
		(start 419.272974 -143.25092)
		(end 419.272974 -144.370806)
		(width 0.089408)
		(layer "In4.Cu")
		(net "XDP_CPU0_TDO")
	)
	(segment
		(start 453.358504 -144.633696)
		(end 452.628 -145.3642)
		(width 0.089408)
		(layer "In4.Cu")
		(net "XDP_CPU0_TDO")
	)
	(segment
		(start 399.051018 -144.060418)
		(end 396.939262 -141.948662)
		(width 0.089408)
		(layer "In4.Cu")
		(net "XDP_CPU0_TDO")
	)
	(segment
		(start 461.066896 -133.834378)
		(end 461.964278 -134.73176)
		(width 0.089408)
		(layer "In4.Cu")
		(net "XDP_CPU0_TDO")
	)
	(segment
		(start 410.524198 -147.259802)
		(end 409.7528 -147.259802)
		(width 0.089408)
		(layer "In4.Cu")
		(net "XDP_CPU0_TDO")
	)
	(segment
		(start 434.932836 -142.324836)
		(end 420.199058 -142.324836)
		(width 0.089408)
		(layer "In4.Cu")
		(net "XDP_CPU0_TDO")
	)
	(segment
		(start 349.2754 -85.96122)
		(end 350.01962 -85.217)
		(width 0.089408)
		(layer "In4.Cu")
		(net "XDP_CPU0_TDO")
	)
	(segment
		(start 396.939262 -141.948662)
		(end 392.856212 -141.948662)
		(width 0.089408)
		(layer "In4.Cu")
		(net "XDP_CPU0_TDO")
	)
	(segment
		(start 365.334042 -141.824964)
		(end 364.669832 -141.160754)
		(width 0.089408)
		(layer "In4.Cu")
		(net "XDP_CPU0_TDO")
	)
	(segment
		(start 461.372712 -132.76834)
		(end 461.066896 -133.074156)
		(width 0.089408)
		(layer "In4.Cu")
		(net "XDP_CPU0_TDO")
	)
	(segment
		(start 342.353646 -120.527318)
		(end 343.664286 -119.216678)
		(width 0.089408)
		(layer "In4.Cu")
		(net "XDP_CPU0_TDO")
	)
	(segment
		(start 343.015062 -115.982496)
		(end 342.57869 -115.982496)
		(width 0.089408)
		(layer "In4.Cu")
		(net "XDP_CPU0_TDO")
	)
	(segment
		(start 442.536834 -142.113)
		(end 440.631834 -144.018)
		(width 0.089408)
		(layer "In4.Cu")
		(net "XDP_CPU0_TDO")
	)
	(segment
		(start 452.628 -145.3642)
		(end 449.3768 -145.3642)
		(width 0.089408)
		(layer "In4.Cu")
		(net "XDP_CPU0_TDO")
	)
	(segment
		(start 461.964278 -137.453878)
		(end 462.629504 -138.119104)
		(width 0.089408)
		(layer "In4.Cu")
		(net "XDP_CPU0_TDO")
	)
	(segment
		(start 362.347764 -141.160754)
		(end 362.286296 -141.099286)
		(width 0.089408)
		(layer "In4.Cu")
		(net "XDP_CPU0_TDO")
	)
	(segment
		(start 342.287606 -126.861316)
		(end 342.287606 -125.406404)
		(width 0.089408)
		(layer "In4.Cu")
		(net "XDP_CPU0_TDO")
	)
	(segment
		(start 419.272974 -144.370806)
		(end 417.748212 -145.895568)
		(width 0.089408)
		(layer "In4.Cu")
		(net "XDP_CPU0_TDO")
	)
	(segment
		(start 348.83852 -138.858752)
		(end 347.665294 -137.685526)
		(width 0.089408)
		(layer "In4.Cu")
		(net "XDP_CPU0_TDO")
	)
	(segment
		(start 449.3768 -145.3642)
		(end 449.130166 -145.610834)
		(width 0.089408)
		(layer "In4.Cu")
		(net "XDP_CPU0_TDO")
	)
	(segment
		(start 361.001818 -141.099286)
		(end 358.713532 -138.811)
		(width 0.089408)
		(layer "In4.Cu")
		(net "XDP_CPU0_TDO")
	)
	(segment
		(start 339.642704 -129.444496)
		(end 339.704426 -129.444496)
		(width 0.089408)
		(layer "In4.Cu")
		(net "XDP_CPU0_TDO")
	)
	(segment
		(start 417.748212 -145.895568)
		(end 411.888432 -145.895568)
		(width 0.089408)
		(layer "In4.Cu")
		(net "XDP_CPU0_TDO")
	)
	(segment
		(start 343.346278 -116.918486)
		(end 343.346278 -116.313712)
		(width 0.089408)
		(layer "In4.Cu")
		(net "XDP_CPU0_TDO")
	)
	(segment
		(start 408.25801 -148.754592)
		(end 406.7175 -148.754592)
		(width 0.089408)
		(layer "In4.Cu")
		(net "XDP_CPU0_TDO")
	)
	(segment
		(start 337.901534 -90.7034)
		(end 339.9536 -90.7034)
		(width 0.089408)
		(layer "In4.Cu")
		(net "XDP_CPU0_TDO")
	)
	(segment
		(start 349.2754 -89.262204)
		(end 349.2754 -85.96122)
		(width 0.089408)
		(layer "In4.Cu")
		(net "XDP_CPU0_TDO")
	)
	(segment
		(start 448.4878 -145.4658)
		(end 446.4558 -145.4658)
		(width 0.089408)
		(layer "In4.Cu")
		(net "XDP_CPU0_TDO")
	)
	(segment
		(start 342.57869 -115.982496)
		(end 341.103712 -114.507518)
		(width 0.089408)
		(layer "In4.Cu")
		(net "XDP_CPU0_TDO")
	)
	(segment
		(start 332.8543 -96.478598)
		(end 332.8543 -95.750634)
		(width 0.089408)
		(layer "In4.Cu")
		(net "XDP_CPU0_TDO")
	)
	(segment
		(start 341.87638 -124.995178)
		(end 341.87638 -120.965976)
		(width 0.089408)
		(layer "In4.Cu")
		(net "XDP_CPU0_TDO")
	)
	(segment
		(start 332.854554 -96.478852)
		(end 332.8543 -96.478598)
		(width 0.089408)
		(layer "In4.Cu")
		(net "XDP_CPU0_TDO")
	)
	(segment
		(start 461.372712 -130.455162)
		(end 461.372712 -132.76834)
		(width 0.089408)
		(layer "In4.Cu")
		(net "XDP_CPU0_TDO")
	)
	(segment
		(start 343.664286 -119.216678)
		(end 343.664286 -117.236494)
		(width 0.089408)
		(layer "In4.Cu")
		(net "XDP_CPU0_TDO")
	)
	(segment
		(start 342.315038 -120.527318)
		(end 342.353646 -120.527318)
		(width 0.089408)
		(layer "In4.Cu")
		(net "XDP_CPU0_TDO")
	)
	(segment
		(start 462.629504 -138.119104)
		(end 462.629504 -145.66138)
		(width 0.089408)
		(layer "In4.Cu")
		(net "XDP_CPU0_TDO")
	)
	(segment
		(start 341.87638 -120.965976)
		(end 342.315038 -120.527318)
		(width 0.089408)
		(layer "In4.Cu")
		(net "XDP_CPU0_TDO")
	)
	(segment
		(start 348.520004 -90.0176)
		(end 349.2754 -89.262204)
		(width 0.089408)
		(layer "In4.Cu")
		(net "XDP_CPU0_TDO")
	)
	(segment
		(start 339.413088 -129.674112)
		(end 339.642704 -129.444496)
		(width 0.089408)
		(layer "In4.Cu")
		(net "XDP_CPU0_TDO")
	)
	(segment
		(start 350.01962 -85.217)
		(end 353.309936 -85.217)
		(width 0.089408)
		(layer "In4.Cu")
		(net "XDP_CPU0_TDO")
	)
	(segment
		(start 332.854554 -103.023416)
		(end 332.854554 -96.478852)
		(width 0.089408)
		(layer "In4.Cu")
		(net "XDP_CPU0_TDO")
	)
	(segment
		(start 402.420074 -146.122898)
		(end 400.147536 -146.122898)
		(width 0.089408)
		(layer "In4.Cu")
		(net "XDP_CPU0_TDO")
	)
	(segment
		(start 459.6638 -128.74625)
		(end 461.372712 -130.455162)
		(width 0.089408)
		(layer "In4.Cu")
		(net "XDP_CPU0_TDO")
	)
	(segment
		(start 411.888432 -145.895568)
		(end 410.524198 -147.259802)
		(width 0.089408)
		(layer "In4.Cu")
		(net "XDP_CPU0_TDO")
	)
	(segment
		(start 342.287606 -125.406404)
		(end 341.87638 -124.995178)
		(width 0.089408)
		(layer "In4.Cu")
		(net "XDP_CPU0_TDO")
	)
	(segment
		(start 399.051018 -145.02638)
		(end 399.051018 -144.060418)
		(width 0.089408)
		(layer "In4.Cu")
		(net "XDP_CPU0_TDO")
	)
	(segment
		(start 341.103712 -105.914698)
		(end 340.380574 -105.19156)
		(width 0.089408)
		(layer "In4.Cu")
		(net "XDP_CPU0_TDO")
	)
	(segment
		(start 371.125496 -141.620748)
		(end 370.92128 -141.824964)
		(width 0.089408)
		(layer "In4.Cu")
		(net "XDP_CPU0_TDO")
	)
	(segment
		(start 449.130166 -145.610834)
		(end 448.632834 -145.610834)
		(width 0.089408)
		(layer "In4.Cu")
		(net "XDP_CPU0_TDO")
	)
	(segment
		(start 460.161894 -147.264374)
		(end 457.398374 -147.264374)
		(width 0.089408)
		(layer "In4.Cu")
		(net "XDP_CPU0_TDO")
	)
	(segment
		(start 343.780872 -137.685526)
		(end 338.689696 -132.59435)
		(width 0.089408)
		(layer "In4.Cu")
		(net "XDP_CPU0_TDO")
	)
	(segment
		(start 341.103712 -114.507518)
		(end 341.103712 -105.914698)
		(width 0.089408)
		(layer "In4.Cu")
		(net "XDP_CPU0_TDO")
	)
	(segment
		(start 436.626 -144.018)
		(end 434.932836 -142.324836)
		(width 0.089408)
		(layer "In4.Cu")
		(net "XDP_CPU0_TDO")
	)
	(segment
		(start 460.285846 -147.388326)
		(end 460.161894 -147.264374)
		(width 0.089408)
		(layer "In4.Cu")
		(net "XDP_CPU0_TDO")
	)
	(segment
		(start 335.022698 -105.19156)
		(end 332.854554 -103.023416)
		(width 0.089408)
		(layer "In4.Cu")
		(net "XDP_CPU0_TDO")
	)
	(segment
		(start 358.713532 -138.811)
		(end 352.800158 -138.811)
		(width 0.089408)
		(layer "In4.Cu")
		(net "XDP_CPU0_TDO")
	)
	(segment
		(start 339.9536 -90.7034)
		(end 340.6394 -90.0176)
		(width 0.089408)
		(layer "In4.Cu")
		(net "XDP_CPU0_TDO")
	)
	(segment
		(start 392.35507 -141.44752)
		(end 385.305808 -141.44752)
		(width 0.089408)
		(layer "In4.Cu")
		(net "XDP_CPU0_TDO")
	)
	(segment
		(start 343.664286 -117.236494)
		(end 343.346278 -116.918486)
		(width 0.089408)
		(layer "In4.Cu")
		(net "XDP_CPU0_TDO")
	)
	(segment
		(start 347.665294 -137.685526)
		(end 343.780872 -137.685526)
		(width 0.089408)
		(layer "In4.Cu")
		(net "XDP_CPU0_TDO")
	)
	(segment
		(start 448.632834 -145.610834)
		(end 448.4878 -145.4658)
		(width 0.089408)
		(layer "In4.Cu")
		(net "XDP_CPU0_TDO")
	)
	(segment
		(start 446.4558 -145.4658)
		(end 443.103 -142.113)
		(width 0.089408)
		(layer "In4.Cu")
		(net "XDP_CPU0_TDO")
	)
	(segment
		(start 461.964278 -134.73176)
		(end 461.964278 -137.453878)
		(width 0.089408)
		(layer "In4.Cu")
		(net "XDP_CPU0_TDO")
	)
	(segment
		(start 352.800158 -138.811)
		(end 352.752406 -138.858752)
		(width 0.089408)
		(layer "In4.Cu")
		(net "XDP_CPU0_TDO")
	)
	(segment
		(start 400.147536 -146.122898)
		(end 399.051018 -145.02638)
		(width 0.089408)
		(layer "In4.Cu")
		(net "XDP_CPU0_TDO")
	)
	(segment
		(start 340.380574 -105.19156)
		(end 335.022698 -105.19156)
		(width 0.089408)
		(layer "In4.Cu")
		(net "XDP_CPU0_TDO")
	)
	(segment
		(start 339.378798 -129.674112)
		(end 339.413088 -129.674112)
		(width 0.089408)
		(layer "In4.Cu")
		(net "XDP_CPU0_TDO")
	)
	(segment
		(start 356.058724 -62.32398)
		(end 356.451408 -61.931296)
		(width 0.089408)
		(layer "In9.Cu")
		(net "XDP_CPU0_TDO")
	)
	(segment
		(start 354.569014 -65.657222)
		(end 356.058724 -64.167512)
		(width 0.089408)
		(layer "In9.Cu")
		(net "XDP_CPU0_TDO")
	)
	(segment
		(start 356.451408 -61.931296)
		(end 356.451408 -58.730388)
		(width 0.089408)
		(layer "In9.Cu")
		(net "XDP_CPU0_TDO")
	)
	(segment
		(start 354.569268 -70.095872)
		(end 354.569268 -66.767456)
		(width 0.089408)
		(layer "In9.Cu")
		(net "XDP_CPU0_TDO")
	)
	(segment
		(start 356.451408 -58.730388)
		(end 355.99751 -58.27649)
		(width 0.089408)
		(layer "In9.Cu")
		(net "XDP_CPU0_TDO")
	)
	(segment
		(start 354.569268 -66.767456)
		(end 354.569014 -66.767202)
		(width 0.089408)
		(layer "In9.Cu")
		(net "XDP_CPU0_TDO")
	)
	(segment
		(start 352.552 -72.11314)
		(end 354.569268 -70.095872)
		(width 0.089408)
		(layer "In9.Cu")
		(net "XDP_CPU0_TDO")
	)
	(segment
		(start 354.5078 -83.58124)
		(end 352.552 -81.62544)
		(width 0.089408)
		(layer "In9.Cu")
		(net "XDP_CPU0_TDO")
	)
	(segment
		(start 354.70338 -83.823556)
		(end 354.5078 -83.627976)
		(width 0.089408)
		(layer "In9.Cu")
		(net "XDP_CPU0_TDO")
	)
	(segment
		(start 354.5078 -83.627976)
		(end 354.5078 -83.58124)
		(width 0.089408)
		(layer "In9.Cu")
		(net "XDP_CPU0_TDO")
	)
	(segment
		(start 352.552 -81.62544)
		(end 352.552 -72.11314)
		(width 0.089408)
		(layer "In9.Cu")
		(net "XDP_CPU0_TDO")
	)
	(segment
		(start 354.569014 -66.767202)
		(end 354.569014 -65.657222)
		(width 0.089408)
		(layer "In9.Cu")
		(net "XDP_CPU0_TDO")
	)
	(segment
		(start 356.058724 -64.167512)
		(end 356.058724 -62.32398)
		(width 0.089408)
		(layer "In9.Cu")
		(net "XDP_CPU0_TDO")
	)
	(segment
		(start 308.691026 -60.899294)
		(end 311.165494 -60.899294)
		(width 0.0889)
		(layer "In11.Cu")
		(net "XDP_CPU0_TDO")
	)
	(segment
		(start 306.680616 -61.636148)
		(end 306.821078 -61.77661)
		(width 0.0889)
		(layer "In11.Cu")
		(net "XDP_CPU0_TDO")
	)
	(segment
		(start 311.165494 -60.899294)
		(end 313.59856 -63.33236)
		(width 0.0889)
		(layer "In11.Cu")
		(net "XDP_CPU0_TDO")
	)
	(segment
		(start 307.630576 -61.257688)
		(end 308.332632 -61.257688)
		(width 0.0889)
		(layer "In11.Cu")
		(net "XDP_CPU0_TDO")
	)
	(segment
		(start 308.332632 -61.257688)
		(end 308.691026 -60.899294)
		(width 0.0889)
		(layer "In11.Cu")
		(net "XDP_CPU0_TDO")
	)
	(segment
		(start 322.448936 -60.615576)
		(end 323.447156 -60.615576)
		(width 0.089408)
		(layer "In11.Cu")
		(net "XDP_CPU0_TDO")
	)
	(segment
		(start 297.502326 -62.248034)
		(end 297.535092 -62.248034)
		(width 0.0889)
		(layer "In11.Cu")
		(net "XDP_CPU0_TDO")
	)
	(segment
		(start 313.59856 -63.33236)
		(end 319.732152 -63.33236)
		(width 0.089408)
		(layer "In11.Cu")
		(net "XDP_CPU0_TDO")
	)
	(segment
		(start 332.79842 -60.190634)
		(end 333.305912 -60.698126)
		(width 0.089408)
		(layer "In11.Cu")
		(net "XDP_CPU0_TDO")
	)
	(segment
		(start 323.68744 -60.85586)
		(end 325.413116 -60.85586)
		(width 0.089408)
		(layer "In11.Cu")
		(net "XDP_CPU0_TDO")
	)
	(segment
		(start 300.936406 -61.257434)
		(end 300.971966 -61.257434)
		(width 0.0889)
		(layer "In11.Cu")
		(net "XDP_CPU0_TDO")
	)
	(segment
		(start 300.08449 -61.752988)
		(end 300.106842 -61.752988)
		(width 0.0889)
		(layer "In11.Cu")
		(net "XDP_CPU0_TDO")
	)
	(segment
		(start 356.1588 -60.7568)
		(end 356.1588 -58.43778)
		(width 0.089408)
		(layer "In11.Cu")
		(net "XDP_CPU0_TDO")
	)
	(segment
		(start 306.821078 -61.77661)
		(end 307.111654 -61.77661)
		(width 0.0889)
		(layer "In11.Cu")
		(net "XDP_CPU0_TDO")
	)
	(segment
		(start 356.1588 -58.43778)
		(end 355.99751 -58.27649)
		(width 0.089408)
		(layer "In11.Cu")
		(net "XDP_CPU0_TDO")
	)
	(segment
		(start 333.305912 -60.814712)
		(end 334.13192 -61.64072)
		(width 0.089408)
		(layer "In11.Cu")
		(net "XDP_CPU0_TDO")
	)
	(segment
		(start 296.66184 -63.334138)
		(end 296.954702 -63.165228)
		(width 0.0889)
		(layer "In11.Cu")
		(net "XDP_CPU0_TDO")
	)
	(segment
		(start 299.219366 -61.257434)
		(end 299.254926 -61.257434)
		(width 0.0889)
		(layer "In11.Cu")
		(net "XDP_CPU0_TDO")
	)
	(segment
		(start 298.357036 -61.752988)
		(end 298.389802 -61.752988)
		(width 0.0889)
		(layer "In11.Cu")
		(net "XDP_CPU0_TDO")
	)
	(segment
		(start 304.370486 -61.257434)
		(end 304.406046 -61.257434)
		(width 0.0889)
		(layer "In11.Cu")
		(net "XDP_CPU0_TDO")
	)
	(segment
		(start 302.653446 -61.257434)
		(end 302.689006 -61.257434)
		(width 0.0889)
		(layer "In11.Cu")
		(net "XDP_CPU0_TDO")
	)
	(segment
		(start 334.13192 -61.64072)
		(end 355.27488 -61.64072)
		(width 0.089408)
		(layer "In11.Cu")
		(net "XDP_CPU0_TDO")
	)
	(segment
		(start 333.305912 -60.698126)
		(end 333.305912 -60.814712)
		(width 0.089408)
		(layer "In11.Cu")
		(net "XDP_CPU0_TDO")
	)
	(segment
		(start 296.999406 -62.558676)
		(end 297.008296 -62.543436)
		(width 0.0889)
		(layer "In11.Cu")
		(net "XDP_CPU0_TDO")
	)
	(segment
		(start 319.732152 -63.33236)
		(end 322.448936 -60.615576)
		(width 0.089408)
		(layer "In11.Cu")
		(net "XDP_CPU0_TDO")
	)
	(segment
		(start 307.111654 -61.77661)
		(end 307.630576 -61.257688)
		(width 0.0889)
		(layer "In11.Cu")
		(net "XDP_CPU0_TDO")
	)
	(segment
		(start 296.954702 -63.165228)
		(end 296.978578 -63.07582)
		(width 0.0889)
		(layer "In11.Cu")
		(net "XDP_CPU0_TDO")
	)
	(segment
		(start 355.27488 -61.64072)
		(end 356.1588 -60.7568)
		(width 0.089408)
		(layer "In11.Cu")
		(net "XDP_CPU0_TDO")
	)
	(segment
		(start 323.447156 -60.615576)
		(end 323.68744 -60.85586)
		(width 0.089408)
		(layer "In11.Cu")
		(net "XDP_CPU0_TDO")
	)
	(segment
		(start 306.087526 -61.257434)
		(end 306.123086 -61.257434)
		(width 0.0889)
		(layer "In11.Cu")
		(net "XDP_CPU0_TDO")
	)
	(segment
		(start 325.413116 -60.85586)
		(end 326.078342 -60.190634)
		(width 0.089408)
		(layer "In11.Cu")
		(net "XDP_CPU0_TDO")
	)
	(segment
		(start 326.078342 -60.190634)
		(end 332.79842 -60.190634)
		(width 0.089408)
		(layer "In11.Cu")
		(net "XDP_CPU0_TDO")
	)
	(arc
		(start 298.389802 -61.752988)
		(mid 298.583652 -61.696638)
		(end 298.725336 -61.552836)
		(width 0.0889)
		(layer "In11.Cu")
		(net "XDP_CPU0_TDO")
	)
	(arc
		(start 297.866816 -62.048136)
		(mid 298.07382 -61.837272)
		(end 298.357036 -61.752988)
		(width 0.0889)
		(layer "In11.Cu")
		(net "XDP_CPU0_TDO")
	)
	(arc
		(start 297.008296 -62.543436)
		(mid 297.216904 -62.331504)
		(end 297.502326 -62.248034)
		(width 0.0889)
		(layer "In11.Cu")
		(net "XDP_CPU0_TDO")
	)
	(arc
		(start 300.971966 -61.257434)
		(mid 301.25739 -61.340901)
		(end 301.465996 -61.552836)
		(width 0.0889)
		(layer "In11.Cu")
		(net "XDP_CPU0_TDO")
	)
	(arc
		(start 304.406046 -61.257434)
		(mid 304.69147 -61.340901)
		(end 304.900076 -61.552836)
		(width 0.0889)
		(layer "In11.Cu")
		(net "XDP_CPU0_TDO")
	)
	(arc
		(start 296.978578 -63.07582)
		(mid 296.929348 -62.814841)
		(end 296.999406 -62.558676)
		(width 0.0889)
		(layer "In11.Cu")
		(net "XDP_CPU0_TDO")
	)
	(arc
		(start 300.442376 -61.552836)
		(mid 300.650984 -61.340904)
		(end 300.936406 -61.257434)
		(width 0.0889)
		(layer "In11.Cu")
		(net "XDP_CPU0_TDO")
	)
	(arc
		(start 301.465996 -61.552836)
		(mid 301.812706 -61.753147)
		(end 302.159416 -61.552836)
		(width 0.0889)
		(layer "In11.Cu")
		(net "XDP_CPU0_TDO")
	)
	(arc
		(start 302.159416 -61.552836)
		(mid 302.368024 -61.340904)
		(end 302.653446 -61.257434)
		(width 0.0889)
		(layer "In11.Cu")
		(net "XDP_CPU0_TDO")
	)
	(arc
		(start 300.106842 -61.752988)
		(mid 300.300692 -61.696638)
		(end 300.442376 -61.552836)
		(width 0.0889)
		(layer "In11.Cu")
		(net "XDP_CPU0_TDO")
	)
	(arc
		(start 299.254926 -61.257434)
		(mid 299.54035 -61.340901)
		(end 299.748956 -61.552836)
		(width 0.0889)
		(layer "In11.Cu")
		(net "XDP_CPU0_TDO")
	)
	(arc
		(start 306.617116 -61.552836)
		(mid 306.646121 -61.596585)
		(end 306.680616 -61.636148)
		(width 0.0889)
		(layer "In11.Cu")
		(net "XDP_CPU0_TDO")
	)
	(arc
		(start 299.748956 -61.552836)
		(mid 299.890639 -61.69664)
		(end 300.08449 -61.752988)
		(width 0.0889)
		(layer "In11.Cu")
		(net "XDP_CPU0_TDO")
	)
	(arc
		(start 306.123086 -61.257434)
		(mid 306.40851 -61.340901)
		(end 306.617116 -61.552836)
		(width 0.0889)
		(layer "In11.Cu")
		(net "XDP_CPU0_TDO")
	)
	(arc
		(start 303.876456 -61.552836)
		(mid 304.085064 -61.340904)
		(end 304.370486 -61.257434)
		(width 0.0889)
		(layer "In11.Cu")
		(net "XDP_CPU0_TDO")
	)
	(arc
		(start 302.689006 -61.257434)
		(mid 302.97443 -61.340901)
		(end 303.183036 -61.552836)
		(width 0.0889)
		(layer "In11.Cu")
		(net "XDP_CPU0_TDO")
	)
	(arc
		(start 304.900076 -61.552836)
		(mid 305.246786 -61.753147)
		(end 305.593496 -61.552836)
		(width 0.0889)
		(layer "In11.Cu")
		(net "XDP_CPU0_TDO")
	)
	(arc
		(start 303.183036 -61.552836)
		(mid 303.529746 -61.753147)
		(end 303.876456 -61.552836)
		(width 0.0889)
		(layer "In11.Cu")
		(net "XDP_CPU0_TDO")
	)
	(arc
		(start 298.725336 -61.552836)
		(mid 298.933944 -61.340904)
		(end 299.219366 -61.257434)
		(width 0.0889)
		(layer "In11.Cu")
		(net "XDP_CPU0_TDO")
	)
	(arc
		(start 297.535092 -62.248034)
		(mid 297.726734 -62.190868)
		(end 297.866816 -62.048136)
		(width 0.0889)
		(layer "In11.Cu")
		(net "XDP_CPU0_TDO")
	)
	(arc
		(start 305.593496 -61.552836)
		(mid 305.802104 -61.340904)
		(end 306.087526 -61.257434)
		(width 0.0889)
		(layer "In11.Cu")
		(net "XDP_CPU0_TDO")
	)
	(segment
		(start 67.749166 -68.46824)
		(end 68.036186 -67.972686)
		(width 0.254)
		(layer "F.Cu")
		(net "VSENSE_VCCINR2PMAX_CPU1")
	)
	(segment
		(start 66.51244 -68.46824)
		(end 53.2765 -55.2323)
		(width 0.254)
		(layer "F.Cu")
		(net "VSENSE_VCCINR2PMAX_CPU1")
	)
	(segment
		(start 67.749166 -68.46824)
		(end 66.51244 -68.46824)
		(width 0.254)
		(layer "F.Cu")
		(net "VSENSE_VCCINR2PMAX_CPU1")
	)
	(segment
		(start 53.2765 -55.2323)
		(end 49.3776 -51.3334)
		(width 0.254)
		(layer "F.Cu")
		(net "VSENSE_VCCINR2PMAX_CPU1")
	)
	(segment
		(start 49.3776 -51.3334)
		(end 45.5041 -51.3334)
		(width 0.254)
		(layer "F.Cu")
		(net "VSENSE_VCCINR2PMAX_CPU1")
	)
	(segment
		(start 68.036186 -67.972686)
		(end 68.607686 -67.972686)
		(width 0.254)
		(layer "F.Cu")
		(net "VSENSE_VCCINR2PMAX_CPU1")
	)
	(via
		(at 53.2765 -55.2323)
		(size 0.762)
		(drill 0.381)
		(layers "F.Cu" "B.Cu")
		(net "VSENSE_VCCINR2PMAX_CPU1")
	)
	(segment
		(start 232.749598 -68.46824)
		(end 230.95204 -68.46824)
		(width 0.254)
		(layer "F.Cu")
		(net "VSENSE_VCCINR2PMAX_CPU0")
	)
	(segment
		(start 230.95204 -68.46824)
		(end 219.4179 -56.9341)
		(width 0.254)
		(layer "F.Cu")
		(net "VSENSE_VCCINR2PMAX_CPU0")
	)
	(segment
		(start 219.4179 -56.9341)
		(end 212.468968 -49.985168)
		(width 0.254)
		(layer "F.Cu")
		(net "VSENSE_VCCINR2PMAX_CPU0")
	)
	(segment
		(start 233.608118 -67.972686)
		(end 233.245152 -67.972686)
		(width 0.254)
		(layer "F.Cu")
		(net "VSENSE_VCCINR2PMAX_CPU0")
	)
	(segment
		(start 212.468968 -49.985168)
		(end 209.296 -49.985168)
		(width 0.254)
		(layer "F.Cu")
		(net "VSENSE_VCCINR2PMAX_CPU0")
	)
	(segment
		(start 233.245152 -67.972686)
		(end 232.749598 -68.46824)
		(width 0.254)
		(layer "F.Cu")
		(net "VSENSE_VCCINR2PMAX_CPU0")
	)
	(via
		(at 219.4179 -56.9341)
		(size 0.762)
		(drill 0.381)
		(layers "F.Cu" "B.Cu")
		(net "VSENSE_VCCINR2PMAX_CPU0")
	)
	(segment
		(start 76.334366 -81.34604)
		(end 75.762866 -81.34604)
		(width 0.127)
		(layer "F.Cu")
		(net "VSENSE_PVSA_CPU1_SKT_VSEN")
	)
	(segment
		(start 42.58056 -102.829868)
		(end 42.479976 -102.729284)
		(width 0.254)
		(layer "F.Cu")
		(net "VSENSE_PVSA_CPU1_SKT_VSEN")
	)
	(segment
		(start 42.479976 -102.729284)
		(end 41.49725 -102.729284)
		(width 0.254)
		(layer "F.Cu")
		(net "VSENSE_PVSA_CPU1_SKT_VSEN")
	)
	(via
		(at 42.58056 -102.829868)
		(size 0.508)
		(drill 0.254)
		(layers "F.Cu" "B.Cu")
		(net "VSENSE_PVSA_CPU1_SKT_VSEN")
	)
	(via
		(at 75.762866 -81.34604)
		(size 0.508)
		(drill 0.254)
		(layers "F.Cu" "B.Cu")
		(net "VSENSE_PVSA_CPU1_SKT_VSEN")
	)
	(segment
		(start 51.95316 -91.157298)
		(end 62.687708 -80.42275)
		(width 0.127)
		(layer "In4.Cu")
		(net "VSENSE_PVSA_CPU1_SKT_VSEN")
	)
	(segment
		(start 51.95316 -93.080586)
		(end 51.95316 -91.157298)
		(width 0.127)
		(layer "In4.Cu")
		(net "VSENSE_PVSA_CPU1_SKT_VSEN")
	)
	(segment
		(start 42.58056 -102.829868)
		(end 42.761154 -103.010462)
		(width 0.127)
		(layer "In4.Cu")
		(net "VSENSE_PVSA_CPU1_SKT_VSEN")
	)
	(segment
		(start 51.39182 -95.620078)
		(end 51.39182 -93.641926)
		(width 0.127)
		(layer "In4.Cu")
		(net "VSENSE_PVSA_CPU1_SKT_VSEN")
	)
	(segment
		(start 74.88936 -82.241136)
		(end 74.919332 -82.241136)
		(width 0.0889)
		(layer "In4.Cu")
		(net "VSENSE_PVSA_CPU1_SKT_VSEN")
	)
	(segment
		(start 69.311774 -79.91475)
		(end 69.371972 -80.041242)
		(width 0.0889)
		(layer "In4.Cu")
		(net "VSENSE_PVSA_CPU1_SKT_VSEN")
	)
	(segment
		(start 44.726606 -101.558852)
		(end 46.900084 -99.385374)
		(width 0.127)
		(layer "In4.Cu")
		(net "VSENSE_PVSA_CPU1_SKT_VSEN")
	)
	(segment
		(start 46.900084 -99.004374)
		(end 48.419258 -97.4852)
		(width 0.127)
		(layer "In4.Cu")
		(net "VSENSE_PVSA_CPU1_SKT_VSEN")
	)
	(segment
		(start 51.39182 -93.641926)
		(end 51.95316 -93.080586)
		(width 0.127)
		(layer "In4.Cu")
		(net "VSENSE_PVSA_CPU1_SKT_VSEN")
	)
	(segment
		(start 46.900084 -99.385374)
		(end 46.900084 -99.004374)
		(width 0.127)
		(layer "In4.Cu")
		(net "VSENSE_PVSA_CPU1_SKT_VSEN")
	)
	(segment
		(start 75.762866 -81.684114)
		(end 75.762866 -81.34604)
		(width 0.0889)
		(layer "In4.Cu")
		(net "VSENSE_PVSA_CPU1_SKT_VSEN")
	)
	(segment
		(start 72.31761 -80.75549)
		(end 72.350376 -80.75549)
		(width 0.0889)
		(layer "In4.Cu")
		(net "VSENSE_PVSA_CPU1_SKT_VSEN")
	)
	(segment
		(start 69.618352 -80.259936)
		(end 69.768212 -80.259936)
		(width 0.0889)
		(layer "In4.Cu")
		(net "VSENSE_PVSA_CPU1_SKT_VSEN")
	)
	(segment
		(start 74.03465 -81.74609)
		(end 74.067416 -81.74609)
		(width 0.0889)
		(layer "In4.Cu")
		(net "VSENSE_PVSA_CPU1_SKT_VSEN")
	)
	(segment
		(start 66.2686 -80.42275)
		(end 66.28765 -80.4418)
		(width 0.0889)
		(layer "In4.Cu")
		(net "VSENSE_PVSA_CPU1_SKT_VSEN")
	)
	(segment
		(start 75.697842 -81.749138)
		(end 75.762866 -81.684114)
		(width 0.0889)
		(layer "In4.Cu")
		(net "VSENSE_PVSA_CPU1_SKT_VSEN")
	)
	(segment
		(start 43.40606 -102.671372)
		(end 43.40606 -102.294944)
		(width 0.127)
		(layer "In4.Cu")
		(net "VSENSE_PVSA_CPU1_SKT_VSEN")
	)
	(segment
		(start 71.45528 -80.259936)
		(end 71.488046 -80.259936)
		(width 0.0889)
		(layer "In4.Cu")
		(net "VSENSE_PVSA_CPU1_SKT_VSEN")
	)
	(segment
		(start 66.246502 -80.42275)
		(end 66.2686 -80.42275)
		(width 0.0889)
		(layer "In4.Cu")
		(net "VSENSE_PVSA_CPU1_SKT_VSEN")
	)
	(segment
		(start 48.419258 -97.4852)
		(end 49.526698 -97.4852)
		(width 0.127)
		(layer "In4.Cu")
		(net "VSENSE_PVSA_CPU1_SKT_VSEN")
	)
	(segment
		(start 62.687708 -80.42275)
		(end 66.246502 -80.42275)
		(width 0.127)
		(layer "In4.Cu")
		(net "VSENSE_PVSA_CPU1_SKT_VSEN")
	)
	(segment
		(start 73.17232 -81.250536)
		(end 73.205086 -81.250536)
		(width 0.0889)
		(layer "In4.Cu")
		(net "VSENSE_PVSA_CPU1_SKT_VSEN")
	)
	(segment
		(start 43.40606 -102.294944)
		(end 44.142152 -101.558852)
		(width 0.127)
		(layer "In4.Cu")
		(net "VSENSE_PVSA_CPU1_SKT_VSEN")
	)
	(segment
		(start 66.790316 -80.4418)
		(end 67.556126 -79.67599)
		(width 0.0889)
		(layer "In4.Cu")
		(net "VSENSE_PVSA_CPU1_SKT_VSEN")
	)
	(segment
		(start 44.142152 -101.558852)
		(end 44.726606 -101.558852)
		(width 0.127)
		(layer "In4.Cu")
		(net "VSENSE_PVSA_CPU1_SKT_VSEN")
	)
	(segment
		(start 70.590156 -79.76489)
		(end 70.633336 -79.76489)
		(width 0.0889)
		(layer "In4.Cu")
		(net "VSENSE_PVSA_CPU1_SKT_VSEN")
	)
	(segment
		(start 49.526698 -97.4852)
		(end 51.39182 -95.620078)
		(width 0.127)
		(layer "In4.Cu")
		(net "VSENSE_PVSA_CPU1_SKT_VSEN")
	)
	(segment
		(start 42.761154 -103.010462)
		(end 43.06697 -103.010462)
		(width 0.127)
		(layer "In4.Cu")
		(net "VSENSE_PVSA_CPU1_SKT_VSEN")
	)
	(segment
		(start 67.556126 -79.67599)
		(end 68.811394 -79.67599)
		(width 0.0889)
		(layer "In4.Cu")
		(net "VSENSE_PVSA_CPU1_SKT_VSEN")
	)
	(segment
		(start 43.06697 -103.010462)
		(end 43.40606 -102.671372)
		(width 0.127)
		(layer "In4.Cu")
		(net "VSENSE_PVSA_CPU1_SKT_VSEN")
	)
	(segment
		(start 66.28765 -80.4418)
		(end 66.790316 -80.4418)
		(width 0.0889)
		(layer "In4.Cu")
		(net "VSENSE_PVSA_CPU1_SKT_VSEN")
	)
	(arc
		(start 74.067416 -81.74609)
		(mid 74.350633 -81.830371)
		(end 74.557636 -82.041238)
		(width 0.0889)
		(layer "In4.Cu")
		(net "VSENSE_PVSA_CPU1_SKT_VSEN")
	)
	(arc
		(start 71.488046 -80.259936)
		(mid 71.77347 -80.343403)
		(end 71.982076 -80.555338)
		(width 0.0889)
		(layer "In4.Cu")
		(net "VSENSE_PVSA_CPU1_SKT_VSEN")
	)
	(arc
		(start 73.699116 -81.545938)
		(mid 73.840799 -81.689742)
		(end 74.03465 -81.74609)
		(width 0.0889)
		(layer "In4.Cu")
		(net "VSENSE_PVSA_CPU1_SKT_VSEN")
	)
	(arc
		(start 74.919332 -82.241136)
		(mid 75.110974 -82.18397)
		(end 75.251056 -82.041238)
		(width 0.0889)
		(layer "In4.Cu")
		(net "VSENSE_PVSA_CPU1_SKT_VSEN")
	)
	(arc
		(start 70.633336 -79.76489)
		(mid 70.916553 -79.849171)
		(end 71.123556 -80.060038)
		(width 0.0889)
		(layer "In4.Cu")
		(net "VSENSE_PVSA_CPU1_SKT_VSEN")
	)
	(arc
		(start 73.205086 -81.250536)
		(mid 73.49051 -81.334003)
		(end 73.699116 -81.545938)
		(width 0.0889)
		(layer "In4.Cu")
		(net "VSENSE_PVSA_CPU1_SKT_VSEN")
	)
	(arc
		(start 68.811394 -79.67599)
		(mid 69.089304 -79.73726)
		(end 69.311774 -79.91475)
		(width 0.0889)
		(layer "In4.Cu")
		(net "VSENSE_PVSA_CPU1_SKT_VSEN")
	)
	(arc
		(start 74.557636 -82.041238)
		(mid 74.697715 -82.183974)
		(end 74.88936 -82.241136)
		(width 0.0889)
		(layer "In4.Cu")
		(net "VSENSE_PVSA_CPU1_SKT_VSEN")
	)
	(arc
		(start 71.123556 -80.060038)
		(mid 71.263635 -80.202774)
		(end 71.45528 -80.259936)
		(width 0.0889)
		(layer "In4.Cu")
		(net "VSENSE_PVSA_CPU1_SKT_VSEN")
	)
	(arc
		(start 72.350376 -80.75549)
		(mid 72.633593 -80.839771)
		(end 72.840596 -81.050638)
		(width 0.0889)
		(layer "In4.Cu")
		(net "VSENSE_PVSA_CPU1_SKT_VSEN")
	)
	(arc
		(start 70.099936 -80.060038)
		(mid 70.30694 -79.849174)
		(end 70.590156 -79.76489)
		(width 0.0889)
		(layer "In4.Cu")
		(net "VSENSE_PVSA_CPU1_SKT_VSEN")
	)
	(arc
		(start 71.982076 -80.555338)
		(mid 72.123759 -80.699142)
		(end 72.31761 -80.75549)
		(width 0.0889)
		(layer "In4.Cu")
		(net "VSENSE_PVSA_CPU1_SKT_VSEN")
	)
	(arc
		(start 72.840596 -81.050638)
		(mid 72.980675 -81.193374)
		(end 73.17232 -81.250536)
		(width 0.0889)
		(layer "In4.Cu")
		(net "VSENSE_PVSA_CPU1_SKT_VSEN")
	)
	(arc
		(start 69.768212 -80.259936)
		(mid 69.959854 -80.20277)
		(end 70.099936 -80.060038)
		(width 0.0889)
		(layer "In4.Cu")
		(net "VSENSE_PVSA_CPU1_SKT_VSEN")
	)
	(arc
		(start 75.251056 -82.041238)
		(mid 75.439584 -81.841865)
		(end 75.697842 -81.749138)
		(width 0.0889)
		(layer "In4.Cu")
		(net "VSENSE_PVSA_CPU1_SKT_VSEN")
	)
	(arc
		(start 69.371972 -80.041242)
		(mid 69.472946 -80.17562)
		(end 69.618352 -80.259936)
		(width 0.0889)
		(layer "In4.Cu")
		(net "VSENSE_PVSA_CPU1_SKT_VSEN")
	)
	(segment
		(start 76.334366 -82.33664)
		(end 75.762866 -82.33664)
		(width 0.127)
		(layer "F.Cu")
		(net "VSENSE_PVSA_CPU1_SKT_VRTN")
	)
	(segment
		(start 42.59072 -103.74376)
		(end 42.338244 -103.491284)
		(width 0.254)
		(layer "F.Cu")
		(net "VSENSE_PVSA_CPU1_SKT_VRTN")
	)
	(segment
		(start 42.338244 -103.491284)
		(end 41.49725 -103.491284)
		(width 0.254)
		(layer "F.Cu")
		(net "VSENSE_PVSA_CPU1_SKT_VRTN")
	)
	(via
		(at 42.59072 -103.74376)
		(size 0.508)
		(drill 0.254)
		(layers "F.Cu" "B.Cu")
		(net "VSENSE_PVSA_CPU1_SKT_VRTN")
	)
	(via
		(at 75.762866 -82.33664)
		(size 0.508)
		(drill 0.254)
		(layers "F.Cu" "B.Cu")
		(net "VSENSE_PVSA_CPU1_SKT_VRTN")
	)
	(segment
		(start 71.448676 -80.450436)
		(end 71.481442 -80.450436)
		(width 0.0889)
		(layer "In4.Cu")
		(net "VSENSE_PVSA_CPU1_SKT_VRTN")
	)
	(segment
		(start 48.514 -97.7138)
		(end 49.62144 -97.7138)
		(width 0.127)
		(layer "In4.Cu")
		(net "VSENSE_PVSA_CPU1_SKT_VRTN")
	)
	(segment
		(start 67.63512 -79.86649)
		(end 68.81368 -79.86649)
		(width 0.0889)
		(layer "In4.Cu")
		(net "VSENSE_PVSA_CPU1_SKT_VRTN")
	)
	(segment
		(start 47.128684 -99.480116)
		(end 47.128684 -99.099116)
		(width 0.127)
		(layer "In4.Cu")
		(net "VSENSE_PVSA_CPU1_SKT_VRTN")
	)
	(segment
		(start 52.18176 -91.25204)
		(end 62.78245 -80.65135)
		(width 0.127)
		(layer "In4.Cu")
		(net "VSENSE_PVSA_CPU1_SKT_VRTN")
	)
	(segment
		(start 51.62042 -93.736668)
		(end 52.18176 -93.175328)
		(width 0.127)
		(layer "In4.Cu")
		(net "VSENSE_PVSA_CPU1_SKT_VRTN")
	)
	(segment
		(start 43.63466 -102.389686)
		(end 44.236894 -101.787452)
		(width 0.127)
		(layer "In4.Cu")
		(net "VSENSE_PVSA_CPU1_SKT_VRTN")
	)
	(segment
		(start 44.821348 -101.787452)
		(end 47.128684 -99.480116)
		(width 0.127)
		(layer "In4.Cu")
		(net "VSENSE_PVSA_CPU1_SKT_VRTN")
	)
	(segment
		(start 73.165716 -81.441036)
		(end 73.198482 -81.441036)
		(width 0.0889)
		(layer "In4.Cu")
		(net "VSENSE_PVSA_CPU1_SKT_VRTN")
	)
	(segment
		(start 52.18176 -93.175328)
		(end 52.18176 -91.25204)
		(width 0.127)
		(layer "In4.Cu")
		(net "VSENSE_PVSA_CPU1_SKT_VRTN")
	)
	(segment
		(start 47.128684 -99.099116)
		(end 48.514 -97.7138)
		(width 0.127)
		(layer "In4.Cu")
		(net "VSENSE_PVSA_CPU1_SKT_VRTN")
	)
	(segment
		(start 43.6372 -102.768654)
		(end 43.63466 -102.766114)
		(width 0.127)
		(layer "In4.Cu")
		(net "VSENSE_PVSA_CPU1_SKT_VRTN")
	)
	(segment
		(start 42.694606 -103.74376)
		(end 43.6372 -102.801166)
		(width 0.127)
		(layer "In4.Cu")
		(net "VSENSE_PVSA_CPU1_SKT_VRTN")
	)
	(segment
		(start 42.59072 -103.74376)
		(end 42.694606 -103.74376)
		(width 0.127)
		(layer "In4.Cu")
		(net "VSENSE_PVSA_CPU1_SKT_VRTN")
	)
	(segment
		(start 62.78245 -80.65135)
		(end 66.246502 -80.65135)
		(width 0.127)
		(layer "In4.Cu")
		(net "VSENSE_PVSA_CPU1_SKT_VRTN")
	)
	(segment
		(start 66.28765 -80.6323)
		(end 66.86931 -80.6323)
		(width 0.0889)
		(layer "In4.Cu")
		(net "VSENSE_PVSA_CPU1_SKT_VRTN")
	)
	(segment
		(start 69.588888 -80.450436)
		(end 69.774816 -80.450436)
		(width 0.0889)
		(layer "In4.Cu")
		(net "VSENSE_PVSA_CPU1_SKT_VRTN")
	)
	(segment
		(start 66.246502 -80.65135)
		(end 66.2686 -80.65135)
		(width 0.0889)
		(layer "In4.Cu")
		(net "VSENSE_PVSA_CPU1_SKT_VRTN")
	)
	(segment
		(start 75.762866 -81.998566)
		(end 75.762866 -82.33664)
		(width 0.0889)
		(layer "In4.Cu")
		(net "VSENSE_PVSA_CPU1_SKT_VRTN")
	)
	(segment
		(start 51.62042 -95.71482)
		(end 51.62042 -93.736668)
		(width 0.127)
		(layer "In4.Cu")
		(net "VSENSE_PVSA_CPU1_SKT_VRTN")
	)
	(segment
		(start 43.63466 -102.766114)
		(end 43.63466 -102.389686)
		(width 0.127)
		(layer "In4.Cu")
		(net "VSENSE_PVSA_CPU1_SKT_VRTN")
	)
	(segment
		(start 70.59676 -79.95539)
		(end 70.626732 -79.95539)
		(width 0.0889)
		(layer "In4.Cu")
		(net "VSENSE_PVSA_CPU1_SKT_VRTN")
	)
	(segment
		(start 74.028046 -81.93659)
		(end 74.060812 -81.93659)
		(width 0.0889)
		(layer "In4.Cu")
		(net "VSENSE_PVSA_CPU1_SKT_VRTN")
	)
	(segment
		(start 44.236894 -101.787452)
		(end 44.821348 -101.787452)
		(width 0.127)
		(layer "In4.Cu")
		(net "VSENSE_PVSA_CPU1_SKT_VRTN")
	)
	(segment
		(start 72.311006 -80.94599)
		(end 72.343772 -80.94599)
		(width 0.0889)
		(layer "In4.Cu")
		(net "VSENSE_PVSA_CPU1_SKT_VRTN")
	)
	(segment
		(start 75.704954 -81.940654)
		(end 75.762866 -81.998566)
		(width 0.0889)
		(layer "In4.Cu")
		(net "VSENSE_PVSA_CPU1_SKT_VRTN")
	)
	(segment
		(start 66.86931 -80.6323)
		(end 67.63512 -79.86649)
		(width 0.0889)
		(layer "In4.Cu")
		(net "VSENSE_PVSA_CPU1_SKT_VRTN")
	)
	(segment
		(start 43.6372 -102.801166)
		(end 43.6372 -102.768654)
		(width 0.127)
		(layer "In4.Cu")
		(net "VSENSE_PVSA_CPU1_SKT_VRTN")
	)
	(segment
		(start 49.62144 -97.7138)
		(end 51.62042 -95.71482)
		(width 0.127)
		(layer "In4.Cu")
		(net "VSENSE_PVSA_CPU1_SKT_VRTN")
	)
	(segment
		(start 66.2686 -80.65135)
		(end 66.28765 -80.6323)
		(width 0.0889)
		(layer "In4.Cu")
		(net "VSENSE_PVSA_CPU1_SKT_VRTN")
	)
	(segment
		(start 69.149468 -80.01762)
		(end 69.19976 -80.123284)
		(width 0.0889)
		(layer "In4.Cu")
		(net "VSENSE_PVSA_CPU1_SKT_VRTN")
	)
	(arc
		(start 71.481442 -80.450436)
		(mid 71.675292 -80.506786)
		(end 71.816976 -80.650588)
		(width 0.0889)
		(layer "In4.Cu")
		(net "VSENSE_PVSA_CPU1_SKT_VRTN")
	)
	(arc
		(start 72.343772 -80.94599)
		(mid 72.535414 -81.003156)
		(end 72.675496 -81.145888)
		(width 0.0889)
		(layer "In4.Cu")
		(net "VSENSE_PVSA_CPU1_SKT_VRTN")
	)
	(arc
		(start 70.626732 -79.95539)
		(mid 70.818374 -80.012556)
		(end 70.958456 -80.155288)
		(width 0.0889)
		(layer "In4.Cu")
		(net "VSENSE_PVSA_CPU1_SKT_VRTN")
	)
	(arc
		(start 70.958456 -80.155288)
		(mid 71.16546 -80.366152)
		(end 71.448676 -80.450436)
		(width 0.0889)
		(layer "In4.Cu")
		(net "VSENSE_PVSA_CPU1_SKT_VRTN")
	)
	(arc
		(start 74.882248 -82.431636)
		(mid 74.904346 -82.432049)
		(end 74.926444 -82.431636)
		(width 0.0889)
		(layer "In4.Cu")
		(net "VSENSE_PVSA_CPU1_SKT_VRTN")
	)
	(arc
		(start 70.265036 -80.155288)
		(mid 70.405115 -80.012552)
		(end 70.59676 -79.95539)
		(width 0.0889)
		(layer "In4.Cu")
		(net "VSENSE_PVSA_CPU1_SKT_VRTN")
	)
	(arc
		(start 74.060812 -81.93659)
		(mid 74.252454 -81.993756)
		(end 74.392536 -82.136488)
		(width 0.0889)
		(layer "In4.Cu")
		(net "VSENSE_PVSA_CPU1_SKT_VRTN")
	)
	(arc
		(start 71.816976 -80.650588)
		(mid 72.025584 -80.86252)
		(end 72.311006 -80.94599)
		(width 0.0889)
		(layer "In4.Cu")
		(net "VSENSE_PVSA_CPU1_SKT_VRTN")
	)
	(arc
		(start 73.198482 -81.441036)
		(mid 73.392332 -81.497386)
		(end 73.534016 -81.641188)
		(width 0.0889)
		(layer "In4.Cu")
		(net "VSENSE_PVSA_CPU1_SKT_VRTN")
	)
	(arc
		(start 69.774816 -80.450436)
		(mid 70.058033 -80.366155)
		(end 70.265036 -80.155288)
		(width 0.0889)
		(layer "In4.Cu")
		(net "VSENSE_PVSA_CPU1_SKT_VRTN")
	)
	(arc
		(start 73.534016 -81.641188)
		(mid 73.742624 -81.85312)
		(end 74.028046 -81.93659)
		(width 0.0889)
		(layer "In4.Cu")
		(net "VSENSE_PVSA_CPU1_SKT_VRTN")
	)
	(arc
		(start 75.416156 -82.136488)
		(mid 75.538101 -82.005456)
		(end 75.704954 -81.940654)
		(width 0.0889)
		(layer "In4.Cu")
		(net "VSENSE_PVSA_CPU1_SKT_VRTN")
	)
	(arc
		(start 68.81368 -79.86649)
		(mid 68.998251 -79.905027)
		(end 69.149468 -80.01762)
		(width 0.0889)
		(layer "In4.Cu")
		(net "VSENSE_PVSA_CPU1_SKT_VRTN")
	)
	(arc
		(start 69.19976 -80.123284)
		(mid 69.358819 -80.329084)
		(end 69.588888 -80.450436)
		(width 0.0889)
		(layer "In4.Cu")
		(net "VSENSE_PVSA_CPU1_SKT_VRTN")
	)
	(arc
		(start 72.675496 -81.145888)
		(mid 72.8825 -81.356752)
		(end 73.165716 -81.441036)
		(width 0.0889)
		(layer "In4.Cu")
		(net "VSENSE_PVSA_CPU1_SKT_VRTN")
	)
	(arc
		(start 74.926444 -82.431636)
		(mid 75.20938 -82.34724)
		(end 75.416156 -82.136488)
		(width 0.0889)
		(layer "In4.Cu")
		(net "VSENSE_PVSA_CPU1_SKT_VRTN")
	)
	(arc
		(start 74.392536 -82.136488)
		(mid 74.599323 -82.347221)
		(end 74.882248 -82.431636)
		(width 0.0889)
		(layer "In4.Cu")
		(net "VSENSE_PVSA_CPU1_SKT_VRTN")
	)
	(segment
		(start 24.230584 -95.827596)
		(end 24.757888 -96.3549)
		(width 0.254)
		(layer "F.Cu")
		(net "VSENSE_PVSA_CPU1_P")
	)
	(segment
		(start 39.723568 -102.616)
		(end 40.034972 -102.616)
		(width 0.254)
		(layer "F.Cu")
		(net "VSENSE_PVSA_CPU1_P")
	)
	(segment
		(start 40.148256 -102.729284)
		(end 40.60825 -102.729284)
		(width 0.254)
		(layer "F.Cu")
		(net "VSENSE_PVSA_CPU1_P")
	)
	(segment
		(start 24.757888 -96.3549)
		(end 24.757888 -96.757236)
		(width 0.254)
		(layer "F.Cu")
		(net "VSENSE_PVSA_CPU1_P")
	)
	(segment
		(start 40.034972 -102.616)
		(end 40.148256 -102.729284)
		(width 0.254)
		(layer "F.Cu")
		(net "VSENSE_PVSA_CPU1_P")
	)
	(segment
		(start 39.723568 -102.616)
		(end 38.961568 -102.616)
		(width 0.254)
		(layer "F.Cu")
		(net "VSENSE_PVSA_CPU1_P")
	)
	(via
		(at 24.757888 -96.757236)
		(size 0.508)
		(drill 0.254)
		(layers "F.Cu" "B.Cu")
		(net "VSENSE_PVSA_CPU1_P")
	)
	(via
		(at 38.961568 -102.616)
		(size 0.508)
		(drill 0.254)
		(layers "F.Cu" "B.Cu")
		(net "VSENSE_PVSA_CPU1_P")
	)
	(segment
		(start 40.936418 -103.482648)
		(end 40.277288 -103.482648)
		(width 0.254)
		(layer "B.Cu")
		(net "VSENSE_PVSA_CPU1_P")
	)
	(segment
		(start 40.277288 -103.482648)
		(end 39.41064 -102.616)
		(width 0.254)
		(layer "B.Cu")
		(net "VSENSE_PVSA_CPU1_P")
	)
	(segment
		(start 39.41064 -102.616)
		(end 38.961568 -102.616)
		(width 0.254)
		(layer "B.Cu")
		(net "VSENSE_PVSA_CPU1_P")
	)
	(segment
		(start 24.757888 -99.64039)
		(end 23.650448 -100.74783)
		(width 0.127)
		(layer "In2.Cu")
		(net "VSENSE_PVSA_CPU1_P")
	)
	(segment
		(start 23.650448 -104.555798)
		(end 25.55494 -106.46029)
		(width 0.127)
		(layer "In2.Cu")
		(net "VSENSE_PVSA_CPU1_P")
	)
	(segment
		(start 36.647374 -103.77043)
		(end 37.471604 -102.9462)
		(width 0.127)
		(layer "In2.Cu")
		(net "VSENSE_PVSA_CPU1_P")
	)
	(segment
		(start 25.55494 -106.46029)
		(end 27.79776 -106.46029)
		(width 0.127)
		(layer "In2.Cu")
		(net "VSENSE_PVSA_CPU1_P")
	)
	(segment
		(start 29.103828 -104.354884)
		(end 29.688282 -103.77043)
		(width 0.127)
		(layer "In2.Cu")
		(net "VSENSE_PVSA_CPU1_P")
	)
	(segment
		(start 27.79776 -106.46029)
		(end 29.103828 -105.154222)
		(width 0.127)
		(layer "In2.Cu")
		(net "VSENSE_PVSA_CPU1_P")
	)
	(segment
		(start 29.103828 -105.154222)
		(end 29.103828 -104.354884)
		(width 0.127)
		(layer "In2.Cu")
		(net "VSENSE_PVSA_CPU1_P")
	)
	(segment
		(start 29.688282 -103.77043)
		(end 36.647374 -103.77043)
		(width 0.127)
		(layer "In2.Cu")
		(net "VSENSE_PVSA_CPU1_P")
	)
	(segment
		(start 23.650448 -100.74783)
		(end 23.650448 -104.555798)
		(width 0.127)
		(layer "In2.Cu")
		(net "VSENSE_PVSA_CPU1_P")
	)
	(segment
		(start 37.471604 -102.9462)
		(end 38.631114 -102.9462)
		(width 0.127)
		(layer "In2.Cu")
		(net "VSENSE_PVSA_CPU1_P")
	)
	(segment
		(start 24.757888 -96.757236)
		(end 24.757888 -99.64039)
		(width 0.127)
		(layer "In2.Cu")
		(net "VSENSE_PVSA_CPU1_P")
	)
	(segment
		(start 38.631114 -102.9462)
		(end 38.961568 -102.616)
		(width 0.127)
		(layer "In2.Cu")
		(net "VSENSE_PVSA_CPU1_P")
	)
	(segment
		(start 39.737284 -103.491284)
		(end 39.723568 -103.505)
		(width 0.254)
		(layer "F.Cu")
		(net "VSENSE_PVSA_CPU1_N")
	)
	(segment
		(start 23.366984 -95.827596)
		(end 23.802848 -96.26346)
		(width 0.254)
		(layer "F.Cu")
		(net "VSENSE_PVSA_CPU1_N")
	)
	(segment
		(start 23.366984 -95.827596)
		(end 23.084536 -95.827596)
		(width 0.254)
		(layer "F.Cu")
		(net "VSENSE_PVSA_CPU1_N")
	)
	(segment
		(start 40.60825 -103.491284)
		(end 39.737284 -103.491284)
		(width 0.254)
		(layer "F.Cu")
		(net "VSENSE_PVSA_CPU1_N")
	)
	(segment
		(start 23.084536 -95.827596)
		(end 22.75078 -95.49384)
		(width 0.254)
		(layer "F.Cu")
		(net "VSENSE_PVSA_CPU1_N")
	)
	(segment
		(start 23.802848 -96.26346)
		(end 23.802848 -96.648778)
		(width 0.254)
		(layer "F.Cu")
		(net "VSENSE_PVSA_CPU1_N")
	)
	(segment
		(start 22.593554 -94.655894)
		(end 22.3266 -94.655894)
		(width 0.2032)
		(layer "F.Cu")
		(net "VSENSE_PVSA_CPU1_N")
	)
	(segment
		(start 22.75078 -94.81312)
		(end 22.593554 -94.655894)
		(width 0.2032)
		(layer "F.Cu")
		(net "VSENSE_PVSA_CPU1_N")
	)
	(segment
		(start 39.723568 -103.505)
		(end 38.961568 -103.505)
		(width 0.254)
		(layer "F.Cu")
		(net "VSENSE_PVSA_CPU1_N")
	)
	(segment
		(start 22.75078 -95.49384)
		(end 22.75078 -94.81312)
		(width 0.254)
		(layer "F.Cu")
		(net "VSENSE_PVSA_CPU1_N")
	)
	(via
		(at 40.075104 -104.252776)
		(size 0.6604)
		(drill 0.3302)
		(layers "F.Cu" "B.Cu")
		(net "VSENSE_PVSA_CPU1_N")
	)
	(via
		(at 38.961568 -103.505)
		(size 0.508)
		(drill 0.254)
		(layers "F.Cu" "B.Cu")
		(net "VSENSE_PVSA_CPU1_N")
	)
	(via
		(at 23.802848 -96.648778)
		(size 0.508)
		(drill 0.254)
		(layers "F.Cu" "B.Cu")
		(net "VSENSE_PVSA_CPU1_N")
	)
	(segment
		(start 40.075104 -104.252776)
		(end 40.050212 -104.252776)
		(width 0.254)
		(layer "B.Cu")
		(net "VSENSE_PVSA_CPU1_N")
	)
	(segment
		(start 39.302436 -103.505)
		(end 38.961568 -103.505)
		(width 0.254)
		(layer "B.Cu")
		(net "VSENSE_PVSA_CPU1_N")
	)
	(segment
		(start 40.050212 -104.252776)
		(end 39.302436 -103.505)
		(width 0.254)
		(layer "B.Cu")
		(net "VSENSE_PVSA_CPU1_N")
	)
	(segment
		(start 40.994838 -104.252776)
		(end 40.075104 -104.252776)
		(width 0.254)
		(layer "B.Cu")
		(net "VSENSE_PVSA_CPU1_N")
	)
	(segment
		(start 24.529288 -99.545648)
		(end 23.421848 -100.653088)
		(width 0.127)
		(layer "In2.Cu")
		(net "VSENSE_PVSA_CPU1_N")
	)
	(segment
		(start 29.332428 -104.449626)
		(end 29.783024 -103.99903)
		(width 0.127)
		(layer "In2.Cu")
		(net "VSENSE_PVSA_CPU1_N")
	)
	(segment
		(start 27.892502 -106.68889)
		(end 29.332428 -105.248964)
		(width 0.127)
		(layer "In2.Cu")
		(net "VSENSE_PVSA_CPU1_N")
	)
	(segment
		(start 29.332428 -105.248964)
		(end 29.332428 -104.449626)
		(width 0.127)
		(layer "In2.Cu")
		(net "VSENSE_PVSA_CPU1_N")
	)
	(segment
		(start 24.529288 -97.375218)
		(end 24.529288 -99.545648)
		(width 0.127)
		(layer "In2.Cu")
		(net "VSENSE_PVSA_CPU1_N")
	)
	(segment
		(start 36.742116 -103.99903)
		(end 37.566346 -103.1748)
		(width 0.127)
		(layer "In2.Cu")
		(net "VSENSE_PVSA_CPU1_N")
	)
	(segment
		(start 23.421848 -100.653088)
		(end 23.421848 -104.65054)
		(width 0.127)
		(layer "In2.Cu")
		(net "VSENSE_PVSA_CPU1_N")
	)
	(segment
		(start 23.421848 -104.65054)
		(end 25.460198 -106.68889)
		(width 0.127)
		(layer "In2.Cu")
		(net "VSENSE_PVSA_CPU1_N")
	)
	(segment
		(start 38.631368 -103.1748)
		(end 38.961568 -103.505)
		(width 0.127)
		(layer "In2.Cu")
		(net "VSENSE_PVSA_CPU1_N")
	)
	(segment
		(start 29.783024 -103.99903)
		(end 36.742116 -103.99903)
		(width 0.127)
		(layer "In2.Cu")
		(net "VSENSE_PVSA_CPU1_N")
	)
	(segment
		(start 25.460198 -106.68889)
		(end 27.892502 -106.68889)
		(width 0.127)
		(layer "In2.Cu")
		(net "VSENSE_PVSA_CPU1_N")
	)
	(segment
		(start 23.802848 -96.648778)
		(end 24.529288 -97.375218)
		(width 0.127)
		(layer "In2.Cu")
		(net "VSENSE_PVSA_CPU1_N")
	)
	(segment
		(start 37.566346 -103.1748)
		(end 38.631368 -103.1748)
		(width 0.127)
		(layer "In2.Cu")
		(net "VSENSE_PVSA_CPU1_N")
	)
	(segment
		(start 22.3266 -94.256098)
		(end 22.988778 -94.256098)
		(width 0.2032)
		(layer "F.Cu")
		(net "VSENSE_PVSA_CPU1_BVSP")
	)
	(segment
		(start 25.438862 -95.558356)
		(end 24.819102 -94.938596)
		(width 0.254)
		(layer "F.Cu")
		(net "VSENSE_PVSA_CPU1_BVSP")
	)
	(segment
		(start 22.988778 -94.256098)
		(end 23.366984 -94.634304)
		(width 0.254)
		(layer "F.Cu")
		(net "VSENSE_PVSA_CPU1_BVSP")
	)
	(segment
		(start 23.366984 -94.634304)
		(end 23.366984 -94.938596)
		(width 0.254)
		(layer "F.Cu")
		(net "VSENSE_PVSA_CPU1_BVSP")
	)
	(segment
		(start 24.819102 -94.938596)
		(end 24.230584 -94.938596)
		(width 0.254)
		(layer "F.Cu")
		(net "VSENSE_PVSA_CPU1_BVSP")
	)
	(segment
		(start 23.366984 -94.938596)
		(end 24.230584 -94.938596)
		(width 0.254)
		(layer "F.Cu")
		(net "VSENSE_PVSA_CPU1_BVSP")
	)
	(via
		(at 25.438862 -95.558356)
		(size 0.762)
		(drill 0.381)
		(layers "F.Cu" "B.Cu")
		(net "VSENSE_PVSA_CPU1_BVSP")
	)
	(segment
		(start 208.275682 -101.503226)
		(end 208.275682 -102.616)
		(width 0.254)
		(layer "F.Cu")
		(net "VSENSE_PVSA_CPU0_SKT_VSEN")
	)
	(segment
		(start 241.334798 -81.34604)
		(end 240.763298 -81.34604)
		(width 0.127)
		(layer "F.Cu")
		(net "VSENSE_PVSA_CPU0_SKT_VSEN")
	)
	(segment
		(start 212.00237 -100.983034)
		(end 208.795874 -100.983034)
		(width 0.254)
		(layer "F.Cu")
		(net "VSENSE_PVSA_CPU0_SKT_VSEN")
	)
	(segment
		(start 207.391 -102.616)
		(end 207.137 -102.616)
		(width 0.254)
		(layer "F.Cu")
		(net "VSENSE_PVSA_CPU0_SKT_VSEN")
	)
	(segment
		(start 208.275682 -102.616)
		(end 208.021682 -102.87)
		(width 0.254)
		(layer "F.Cu")
		(net "VSENSE_PVSA_CPU0_SKT_VSEN")
	)
	(segment
		(start 212.927438 -99.607878)
		(end 212.927438 -100.057966)
		(width 0.254)
		(layer "F.Cu")
		(net "VSENSE_PVSA_CPU0_SKT_VSEN")
	)
	(segment
		(start 207.645 -102.87)
		(end 207.391 -102.616)
		(width 0.254)
		(layer "F.Cu")
		(net "VSENSE_PVSA_CPU0_SKT_VSEN")
	)
	(segment
		(start 208.021682 -102.87)
		(end 207.645 -102.87)
		(width 0.254)
		(layer "F.Cu")
		(net "VSENSE_PVSA_CPU0_SKT_VSEN")
	)
	(segment
		(start 208.795874 -100.983034)
		(end 208.275682 -101.503226)
		(width 0.254)
		(layer "F.Cu")
		(net "VSENSE_PVSA_CPU0_SKT_VSEN")
	)
	(segment
		(start 212.927438 -100.057966)
		(end 212.00237 -100.983034)
		(width 0.254)
		(layer "F.Cu")
		(net "VSENSE_PVSA_CPU0_SKT_VSEN")
	)
	(segment
		(start 212.74024 -99.42068)
		(end 212.927438 -99.607878)
		(width 0.254)
		(layer "F.Cu")
		(net "VSENSE_PVSA_CPU0_SKT_VSEN")
	)
	(segment
		(start 212.667088 -99.42068)
		(end 212.74024 -99.42068)
		(width 0.254)
		(layer "F.Cu")
		(net "VSENSE_PVSA_CPU0_SKT_VSEN")
	)
	(via
		(at 212.667088 -99.42068)
		(size 0.508)
		(drill 0.254)
		(layers "F.Cu" "B.Cu")
		(net "VSENSE_PVSA_CPU0_SKT_VSEN")
	)
	(via
		(at 240.763298 -81.34604)
		(size 0.508)
		(drill 0.254)
		(layers "F.Cu" "B.Cu")
		(net "VSENSE_PVSA_CPU0_SKT_VSEN")
	)
	(segment
		(start 212.667088 -99.42068)
		(end 213.0298 -99.057968)
		(width 0.127)
		(layer "In11.Cu")
		(net "VSENSE_PVSA_CPU0_SKT_VSEN")
	)
	(segment
		(start 213.0298 -99.057968)
		(end 213.0298 -95.53321)
		(width 0.127)
		(layer "In11.Cu")
		(net "VSENSE_PVSA_CPU0_SKT_VSEN")
	)
	(segment
		(start 231.27335 -84.71789)
		(end 232.268268 -84.71789)
		(width 0.0889)
		(layer "In11.Cu")
		(net "VSENSE_PVSA_CPU0_SKT_VSEN")
	)
	(segment
		(start 237.307628 -81.74609)
		(end 237.340394 -81.74609)
		(width 0.0889)
		(layer "In11.Cu")
		(net "VSENSE_PVSA_CPU0_SKT_VSEN")
	)
	(segment
		(start 230.859076 -84.68868)
		(end 231.24414 -84.68868)
		(width 0.127)
		(layer "In11.Cu")
		(net "VSENSE_PVSA_CPU0_SKT_VSEN")
	)
	(segment
		(start 233.873548 -83.72729)
		(end 233.906314 -83.72729)
		(width 0.0889)
		(layer "In11.Cu")
		(net "VSENSE_PVSA_CPU0_SKT_VSEN")
	)
	(segment
		(start 239.889792 -81.250536)
		(end 239.922558 -81.250536)
		(width 0.0889)
		(layer "In11.Cu")
		(net "VSENSE_PVSA_CPU0_SKT_VSEN")
	)
	(segment
		(start 240.703608 -81.741772)
		(end 240.763298 -81.682082)
		(width 0.0889)
		(layer "In11.Cu")
		(net "VSENSE_PVSA_CPU0_SKT_VSEN")
	)
	(segment
		(start 236.457744 -82.241136)
		(end 236.485684 -82.241136)
		(width 0.0889)
		(layer "In11.Cu")
		(net "VSENSE_PVSA_CPU0_SKT_VSEN")
	)
	(segment
		(start 231.24414 -84.68868)
		(end 231.27335 -84.71789)
		(width 0.0889)
		(layer "In11.Cu")
		(net "VSENSE_PVSA_CPU0_SKT_VSEN")
	)
	(segment
		(start 226.9998 -84.3788)
		(end 230.549196 -84.3788)
		(width 0.127)
		(layer "In11.Cu")
		(net "VSENSE_PVSA_CPU0_SKT_VSEN")
	)
	(segment
		(start 232.833926 -84.222336)
		(end 233.051604 -84.222336)
		(width 0.0889)
		(layer "In11.Cu")
		(net "VSENSE_PVSA_CPU0_SKT_VSEN")
	)
	(segment
		(start 240.763298 -81.682082)
		(end 240.763298 -81.34604)
		(width 0.0889)
		(layer "In11.Cu")
		(net "VSENSE_PVSA_CPU0_SKT_VSEN")
	)
	(segment
		(start 238.169958 -81.250536)
		(end 238.202724 -81.250536)
		(width 0.0889)
		(layer "In11.Cu")
		(net "VSENSE_PVSA_CPU0_SKT_VSEN")
	)
	(segment
		(start 217.424508 -93.954092)
		(end 226.9998 -84.3788)
		(width 0.127)
		(layer "In11.Cu")
		(net "VSENSE_PVSA_CPU0_SKT_VSEN")
	)
	(segment
		(start 234.735878 -83.231736)
		(end 234.771692 -83.231736)
		(width 0.0889)
		(layer "In11.Cu")
		(net "VSENSE_PVSA_CPU0_SKT_VSEN")
	)
	(segment
		(start 213.0298 -95.53321)
		(end 214.608918 -93.954092)
		(width 0.127)
		(layer "In11.Cu")
		(net "VSENSE_PVSA_CPU0_SKT_VSEN")
	)
	(segment
		(start 214.608918 -93.954092)
		(end 217.424508 -93.954092)
		(width 0.127)
		(layer "In11.Cu")
		(net "VSENSE_PVSA_CPU0_SKT_VSEN")
	)
	(segment
		(start 235.590588 -82.73669)
		(end 235.623354 -82.73669)
		(width 0.0889)
		(layer "In11.Cu")
		(net "VSENSE_PVSA_CPU0_SKT_VSEN")
	)
	(segment
		(start 230.549196 -84.3788)
		(end 230.859076 -84.68868)
		(width 0.127)
		(layer "In11.Cu")
		(net "VSENSE_PVSA_CPU0_SKT_VSEN")
	)
	(arc
		(start 239.922558 -81.250536)
		(mid 240.207982 -81.334003)
		(end 240.416588 -81.545938)
		(width 0.0889)
		(layer "In11.Cu")
		(net "VSENSE_PVSA_CPU0_SKT_VSEN")
	)
	(arc
		(start 235.100368 -83.031838)
		(mid 235.307372 -82.820974)
		(end 235.590588 -82.73669)
		(width 0.0889)
		(layer "In11.Cu")
		(net "VSENSE_PVSA_CPU0_SKT_VSEN")
	)
	(arc
		(start 232.48493 -84.520532)
		(mid 232.63103 -84.338198)
		(end 232.833926 -84.222336)
		(width 0.0889)
		(layer "In11.Cu")
		(net "VSENSE_PVSA_CPU0_SKT_VSEN")
	)
	(arc
		(start 236.817408 -82.041238)
		(mid 237.024412 -81.830374)
		(end 237.307628 -81.74609)
		(width 0.0889)
		(layer "In11.Cu")
		(net "VSENSE_PVSA_CPU0_SKT_VSEN")
	)
	(arc
		(start 237.340394 -81.74609)
		(mid 237.534244 -81.68974)
		(end 237.675928 -81.545938)
		(width 0.0889)
		(layer "In11.Cu")
		(net "VSENSE_PVSA_CPU0_SKT_VSEN")
	)
	(arc
		(start 235.623354 -82.73669)
		(mid 235.817204 -82.68034)
		(end 235.958888 -82.536538)
		(width 0.0889)
		(layer "In11.Cu")
		(net "VSENSE_PVSA_CPU0_SKT_VSEN")
	)
	(arc
		(start 236.485684 -82.241136)
		(mid 236.677326 -82.18397)
		(end 236.817408 -82.041238)
		(width 0.0889)
		(layer "In11.Cu")
		(net "VSENSE_PVSA_CPU0_SKT_VSEN")
	)
	(arc
		(start 238.534448 -81.050638)
		(mid 239.046258 -80.755099)
		(end 239.558068 -81.050638)
		(width 0.0889)
		(layer "In11.Cu")
		(net "VSENSE_PVSA_CPU0_SKT_VSEN")
	)
	(arc
		(start 232.268268 -84.71789)
		(mid 232.393755 -84.638057)
		(end 232.48493 -84.520532)
		(width 0.0889)
		(layer "In11.Cu")
		(net "VSENSE_PVSA_CPU0_SKT_VSEN")
	)
	(arc
		(start 233.051604 -84.222336)
		(mid 233.243246 -84.16517)
		(end 233.383328 -84.022438)
		(width 0.0889)
		(layer "In11.Cu")
		(net "VSENSE_PVSA_CPU0_SKT_VSEN")
	)
	(arc
		(start 233.906314 -83.72729)
		(mid 234.100164 -83.67094)
		(end 234.241848 -83.527138)
		(width 0.0889)
		(layer "In11.Cu")
		(net "VSENSE_PVSA_CPU0_SKT_VSEN")
	)
	(arc
		(start 239.558068 -81.050638)
		(mid 239.698147 -81.193374)
		(end 239.889792 -81.250536)
		(width 0.0889)
		(layer "In11.Cu")
		(net "VSENSE_PVSA_CPU0_SKT_VSEN")
	)
	(arc
		(start 233.383328 -84.022438)
		(mid 233.590332 -83.811574)
		(end 233.873548 -83.72729)
		(width 0.0889)
		(layer "In11.Cu")
		(net "VSENSE_PVSA_CPU0_SKT_VSEN")
	)
	(arc
		(start 234.241848 -83.527138)
		(mid 234.450456 -83.315206)
		(end 234.735878 -83.231736)
		(width 0.0889)
		(layer "In11.Cu")
		(net "VSENSE_PVSA_CPU0_SKT_VSEN")
	)
	(arc
		(start 240.416588 -81.545938)
		(mid 240.537736 -81.676629)
		(end 240.703608 -81.741772)
		(width 0.0889)
		(layer "In11.Cu")
		(net "VSENSE_PVSA_CPU0_SKT_VSEN")
	)
	(arc
		(start 235.958888 -82.536538)
		(mid 236.169601 -82.323459)
		(end 236.457744 -82.241136)
		(width 0.0889)
		(layer "In11.Cu")
		(net "VSENSE_PVSA_CPU0_SKT_VSEN")
	)
	(arc
		(start 237.675928 -81.545938)
		(mid 237.884536 -81.334006)
		(end 238.169958 -81.250536)
		(width 0.0889)
		(layer "In11.Cu")
		(net "VSENSE_PVSA_CPU0_SKT_VSEN")
	)
	(arc
		(start 234.771692 -83.231736)
		(mid 234.961621 -83.173866)
		(end 235.100368 -83.031838)
		(width 0.0889)
		(layer "In11.Cu")
		(net "VSENSE_PVSA_CPU0_SKT_VSEN")
	)
	(arc
		(start 238.202724 -81.250536)
		(mid 238.394366 -81.19337)
		(end 238.534448 -81.050638)
		(width 0.0889)
		(layer "In11.Cu")
		(net "VSENSE_PVSA_CPU0_SKT_VSEN")
	)
	(segment
		(start 208.953862 -101.364034)
		(end 208.656682 -101.661214)
		(width 0.254)
		(layer "F.Cu")
		(net "VSENSE_PVSA_CPU0_SKT_VRTN")
	)
	(segment
		(start 208.656682 -102.773988)
		(end 208.17967 -103.251)
		(width 0.254)
		(layer "F.Cu")
		(net "VSENSE_PVSA_CPU0_SKT_VRTN")
	)
	(segment
		(start 212.160358 -101.364034)
		(end 208.953862 -101.364034)
		(width 0.254)
		(layer "F.Cu")
		(net "VSENSE_PVSA_CPU0_SKT_VRTN")
	)
	(segment
		(start 207.645 -103.251)
		(end 207.391 -103.505)
		(width 0.254)
		(layer "F.Cu")
		(net "VSENSE_PVSA_CPU0_SKT_VRTN")
	)
	(segment
		(start 208.656682 -101.661214)
		(end 208.656682 -102.773988)
		(width 0.254)
		(layer "F.Cu")
		(net "VSENSE_PVSA_CPU0_SKT_VRTN")
	)
	(segment
		(start 213.519766 -99.41052)
		(end 213.308438 -99.621848)
		(width 0.254)
		(layer "F.Cu")
		(net "VSENSE_PVSA_CPU0_SKT_VRTN")
	)
	(segment
		(start 213.581234 -99.41052)
		(end 213.519766 -99.41052)
		(width 0.254)
		(layer "F.Cu")
		(net "VSENSE_PVSA_CPU0_SKT_VRTN")
	)
	(segment
		(start 213.308438 -100.215954)
		(end 212.160358 -101.364034)
		(width 0.254)
		(layer "F.Cu")
		(net "VSENSE_PVSA_CPU0_SKT_VRTN")
	)
	(segment
		(start 208.17967 -103.251)
		(end 207.645 -103.251)
		(width 0.254)
		(layer "F.Cu")
		(net "VSENSE_PVSA_CPU0_SKT_VRTN")
	)
	(segment
		(start 207.391 -103.505)
		(end 207.137 -103.505)
		(width 0.254)
		(layer "F.Cu")
		(net "VSENSE_PVSA_CPU0_SKT_VRTN")
	)
	(segment
		(start 241.334798 -82.33664)
		(end 240.763298 -82.33664)
		(width 0.127)
		(layer "F.Cu")
		(net "VSENSE_PVSA_CPU0_SKT_VRTN")
	)
	(segment
		(start 213.308438 -99.621848)
		(end 213.308438 -100.215954)
		(width 0.254)
		(layer "F.Cu")
		(net "VSENSE_PVSA_CPU0_SKT_VRTN")
	)
	(via
		(at 240.763298 -82.33664)
		(size 0.4826)
		(drill 0.254)
		(layers "F.Cu" "B.Cu")
		(net "VSENSE_PVSA_CPU0_SKT_VRTN")
	)
	(via
		(at 213.581234 -99.41052)
		(size 0.508)
		(drill 0.254)
		(layers "F.Cu" "B.Cu")
		(net "VSENSE_PVSA_CPU0_SKT_VRTN")
	)
	(segment
		(start 232.870248 -84.412836)
		(end 233.058208 -84.412836)
		(width 0.0889)
		(layer "In11.Cu")
		(net "VSENSE_PVSA_CPU0_SKT_VRTN")
	)
	(segment
		(start 240.695734 -81.933034)
		(end 240.763298 -82.000598)
		(width 0.0889)
		(layer "In11.Cu")
		(net "VSENSE_PVSA_CPU0_SKT_VRTN")
	)
	(segment
		(start 240.763298 -82.000598)
		(end 240.763298 -82.33664)
		(width 0.0889)
		(layer "In11.Cu")
		(net "VSENSE_PVSA_CPU0_SKT_VRTN")
	)
	(segment
		(start 238.176562 -81.441036)
		(end 238.209328 -81.441036)
		(width 0.0889)
		(layer "In11.Cu")
		(net "VSENSE_PVSA_CPU0_SKT_VRTN")
	)
	(segment
		(start 235.601002 -82.92719)
		(end 235.633768 -82.92719)
		(width 0.0889)
		(layer "In11.Cu")
		(net "VSENSE_PVSA_CPU0_SKT_VRTN")
	)
	(segment
		(start 213.2584 -95.627952)
		(end 214.70366 -94.182692)
		(width 0.127)
		(layer "In11.Cu")
		(net "VSENSE_PVSA_CPU0_SKT_VRTN")
	)
	(segment
		(start 214.70366 -94.182692)
		(end 217.51925 -94.182692)
		(width 0.127)
		(layer "In11.Cu")
		(net "VSENSE_PVSA_CPU0_SKT_VRTN")
	)
	(segment
		(start 230.764334 -84.91728)
		(end 231.20604 -84.91728)
		(width 0.127)
		(layer "In11.Cu")
		(net "VSENSE_PVSA_CPU0_SKT_VRTN")
	)
	(segment
		(start 230.454454 -84.6074)
		(end 230.764334 -84.91728)
		(width 0.127)
		(layer "In11.Cu")
		(net "VSENSE_PVSA_CPU0_SKT_VRTN")
	)
	(segment
		(start 233.880152 -83.91779)
		(end 233.912918 -83.91779)
		(width 0.0889)
		(layer "In11.Cu")
		(net "VSENSE_PVSA_CPU0_SKT_VRTN")
	)
	(segment
		(start 213.2584 -99.087686)
		(end 213.2584 -95.627952)
		(width 0.127)
		(layer "In11.Cu")
		(net "VSENSE_PVSA_CPU0_SKT_VRTN")
	)
	(segment
		(start 213.581234 -99.41052)
		(end 213.2584 -99.087686)
		(width 0.127)
		(layer "In11.Cu")
		(net "VSENSE_PVSA_CPU0_SKT_VRTN")
	)
	(segment
		(start 231.21493 -84.90839)
		(end 232.30459 -84.90839)
		(width 0.0889)
		(layer "In11.Cu")
		(net "VSENSE_PVSA_CPU0_SKT_VRTN")
	)
	(segment
		(start 231.20604 -84.91728)
		(end 231.21493 -84.90839)
		(width 0.0889)
		(layer "In11.Cu")
		(net "VSENSE_PVSA_CPU0_SKT_VRTN")
	)
	(segment
		(start 234.735624 -83.42249)
		(end 234.775248 -83.42249)
		(width 0.0889)
		(layer "In11.Cu")
		(net "VSENSE_PVSA_CPU0_SKT_VRTN")
	)
	(segment
		(start 227.094542 -84.6074)
		(end 230.454454 -84.6074)
		(width 0.127)
		(layer "In11.Cu")
		(net "VSENSE_PVSA_CPU0_SKT_VRTN")
	)
	(segment
		(start 236.459522 -82.43189)
		(end 236.483652 -82.43189)
		(width 0.0889)
		(layer "In11.Cu")
		(net "VSENSE_PVSA_CPU0_SKT_VRTN")
	)
	(segment
		(start 239.883188 -81.441036)
		(end 239.915954 -81.441036)
		(width 0.0889)
		(layer "In11.Cu")
		(net "VSENSE_PVSA_CPU0_SKT_VRTN")
	)
	(segment
		(start 237.314232 -81.93659)
		(end 237.346998 -81.93659)
		(width 0.0889)
		(layer "In11.Cu")
		(net "VSENSE_PVSA_CPU0_SKT_VRTN")
	)
	(segment
		(start 217.51925 -94.182692)
		(end 227.094542 -84.6074)
		(width 0.127)
		(layer "In11.Cu")
		(net "VSENSE_PVSA_CPU0_SKT_VRTN")
	)
	(arc
		(start 236.123988 -82.632042)
		(mid 236.265671 -82.488238)
		(end 236.459522 -82.43189)
		(width 0.0889)
		(layer "In11.Cu")
		(net "VSENSE_PVSA_CPU0_SKT_VRTN")
	)
	(arc
		(start 234.406948 -83.622388)
		(mid 234.545692 -83.480355)
		(end 234.735624 -83.42249)
		(width 0.0889)
		(layer "In11.Cu")
		(net "VSENSE_PVSA_CPU0_SKT_VRTN")
	)
	(arc
		(start 240.251488 -81.641188)
		(mid 240.430322 -81.834086)
		(end 240.67516 -81.93024)
		(width 0.0889)
		(layer "In11.Cu")
		(net "VSENSE_PVSA_CPU0_SKT_VRTN")
	)
	(arc
		(start 236.982508 -82.136488)
		(mid 237.122587 -81.993752)
		(end 237.314232 -81.93659)
		(width 0.0889)
		(layer "In11.Cu")
		(net "VSENSE_PVSA_CPU0_SKT_VRTN")
	)
	(arc
		(start 233.058208 -84.412836)
		(mid 233.341425 -84.328555)
		(end 233.548428 -84.117688)
		(width 0.0889)
		(layer "In11.Cu")
		(net "VSENSE_PVSA_CPU0_SKT_VRTN")
	)
	(arc
		(start 235.633768 -82.92719)
		(mid 235.916985 -82.842909)
		(end 236.123988 -82.632042)
		(width 0.0889)
		(layer "In11.Cu")
		(net "VSENSE_PVSA_CPU0_SKT_VRTN")
	)
	(arc
		(start 234.775248 -83.42249)
		(mid 235.058465 -83.338209)
		(end 235.265468 -83.127342)
		(width 0.0889)
		(layer "In11.Cu")
		(net "VSENSE_PVSA_CPU0_SKT_VRTN")
	)
	(arc
		(start 233.548428 -84.117688)
		(mid 233.688507 -83.974952)
		(end 233.880152 -83.91779)
		(width 0.0889)
		(layer "In11.Cu")
		(net "VSENSE_PVSA_CPU0_SKT_VRTN")
	)
	(arc
		(start 235.265468 -83.127342)
		(mid 235.407151 -82.983538)
		(end 235.601002 -82.92719)
		(width 0.0889)
		(layer "In11.Cu")
		(net "VSENSE_PVSA_CPU0_SKT_VRTN")
	)
	(arc
		(start 232.653586 -84.610194)
		(mid 232.7447 -84.492602)
		(end 232.870248 -84.412836)
		(width 0.0889)
		(layer "In11.Cu")
		(net "VSENSE_PVSA_CPU0_SKT_VRTN")
	)
	(arc
		(start 238.209328 -81.441036)
		(mid 238.492545 -81.356755)
		(end 238.699548 -81.145888)
		(width 0.0889)
		(layer "In11.Cu")
		(net "VSENSE_PVSA_CPU0_SKT_VRTN")
	)
	(arc
		(start 240.67516 -81.93024)
		(mid 240.685435 -81.931725)
		(end 240.695734 -81.933034)
		(width 0.0889)
		(layer "In11.Cu")
		(net "VSENSE_PVSA_CPU0_SKT_VRTN")
	)
	(arc
		(start 239.915954 -81.441036)
		(mid 240.109804 -81.497386)
		(end 240.251488 -81.641188)
		(width 0.0889)
		(layer "In11.Cu")
		(net "VSENSE_PVSA_CPU0_SKT_VRTN")
	)
	(arc
		(start 238.699548 -81.145888)
		(mid 239.046258 -80.945704)
		(end 239.392968 -81.145888)
		(width 0.0889)
		(layer "In11.Cu")
		(net "VSENSE_PVSA_CPU0_SKT_VRTN")
	)
	(arc
		(start 239.392968 -81.145888)
		(mid 239.599972 -81.356752)
		(end 239.883188 -81.441036)
		(width 0.0889)
		(layer "In11.Cu")
		(net "VSENSE_PVSA_CPU0_SKT_VRTN")
	)
	(arc
		(start 236.483652 -82.43189)
		(mid 236.771797 -82.349571)
		(end 236.982508 -82.136488)
		(width 0.0889)
		(layer "In11.Cu")
		(net "VSENSE_PVSA_CPU0_SKT_VRTN")
	)
	(arc
		(start 237.841028 -81.641188)
		(mid 237.982711 -81.497384)
		(end 238.176562 -81.441036)
		(width 0.0889)
		(layer "In11.Cu")
		(net "VSENSE_PVSA_CPU0_SKT_VRTN")
	)
	(arc
		(start 237.346998 -81.93659)
		(mid 237.632422 -81.853123)
		(end 237.841028 -81.641188)
		(width 0.0889)
		(layer "In11.Cu")
		(net "VSENSE_PVSA_CPU0_SKT_VRTN")
	)
	(arc
		(start 232.30459 -84.90839)
		(mid 232.507488 -84.79253)
		(end 232.653586 -84.610194)
		(width 0.0889)
		(layer "In11.Cu")
		(net "VSENSE_PVSA_CPU0_SKT_VRTN")
	)
	(arc
		(start 233.912918 -83.91779)
		(mid 234.198342 -83.834323)
		(end 234.406948 -83.622388)
		(width 0.0889)
		(layer "In11.Cu")
		(net "VSENSE_PVSA_CPU0_SKT_VRTN")
	)
	(segment
		(start 190.08598 -78.105762)
		(end 188.791342 -79.4004)
		(width 0.127)
		(layer "F.Cu")
		(net "VSENSE_PVSA_CPU0_P")
	)
	(segment
		(start 189.357254 -73.893426)
		(end 189.357254 -74.947272)
		(width 0.127)
		(layer "F.Cu")
		(net "VSENSE_PVSA_CPU0_P")
	)
	(segment
		(start 204.8383 -102.5906)
		(end 204.8637 -102.616)
		(width 0.127)
		(layer "F.Cu")
		(net "VSENSE_PVSA_CPU0_P")
	)
	(segment
		(start 190.08598 -75.675998)
		(end 190.08598 -78.105762)
		(width 0.127)
		(layer "F.Cu")
		(net "VSENSE_PVSA_CPU0_P")
	)
	(segment
		(start 204.8637 -102.616)
		(end 205.486 -102.616)
		(width 0.127)
		(layer "F.Cu")
		(net "VSENSE_PVSA_CPU0_P")
	)
	(segment
		(start 188.791342 -79.4004)
		(end 188.190124 -79.4004)
		(width 0.127)
		(layer "F.Cu")
		(net "VSENSE_PVSA_CPU0_P")
	)
	(segment
		(start 188.190124 -79.4004)
		(end 187.9854 -79.605124)
		(width 0.127)
		(layer "F.Cu")
		(net "VSENSE_PVSA_CPU0_P")
	)
	(segment
		(start 189.357254 -74.947272)
		(end 190.08598 -75.675998)
		(width 0.127)
		(layer "F.Cu")
		(net "VSENSE_PVSA_CPU0_P")
	)
	(segment
		(start 204.6224 -102.5906)
		(end 204.8383 -102.5906)
		(width 0.127)
		(layer "F.Cu")
		(net "VSENSE_PVSA_CPU0_P")
	)
	(segment
		(start 187.9854 -79.788004)
		(end 188.344048 -80.146652)
		(width 0.127)
		(layer "F.Cu")
		(net "VSENSE_PVSA_CPU0_P")
	)
	(segment
		(start 189.70498 -73.5457)
		(end 189.357254 -73.893426)
		(width 0.127)
		(layer "F.Cu")
		(net "VSENSE_PVSA_CPU0_P")
	)
	(segment
		(start 187.9854 -79.605124)
		(end 187.9854 -79.788004)
		(width 0.127)
		(layer "F.Cu")
		(net "VSENSE_PVSA_CPU0_P")
	)
	(segment
		(start 205.486 -102.616)
		(end 206.248 -102.616)
		(width 0.127)
		(layer "F.Cu")
		(net "VSENSE_PVSA_CPU0_P")
	)
	(via
		(at 224.12452 -90.243406)
		(size 0.508)
		(drill 0.254)
		(layers "F.Cu" "B.Cu")
		(net "VSENSE_PVSA_CPU0_P")
	)
	(via
		(at 188.344048 -80.146652)
		(size 0.508)
		(drill 0.254)
		(layers "F.Cu" "B.Cu")
		(net "VSENSE_PVSA_CPU0_P")
	)
	(via
		(at 204.6224 -102.5906)
		(size 0.508)
		(drill 0.254)
		(layers "F.Cu" "B.Cu")
		(net "VSENSE_PVSA_CPU0_P")
	)
	(segment
		(start 227.769166 -86.962234)
		(end 226.095814 -86.962234)
		(width 0.254)
		(layer "B.Cu")
		(net "VSENSE_PVSA_CPU0_P")
	)
	(segment
		(start 211.67852 -102.982522)
		(end 208.951322 -102.982522)
		(width 0.254)
		(layer "B.Cu")
		(net "VSENSE_PVSA_CPU0_P")
	)
	(segment
		(start 224.12452 -88.933528)
		(end 224.12452 -90.243406)
		(width 0.254)
		(layer "B.Cu")
		(net "VSENSE_PVSA_CPU0_P")
	)
	(segment
		(start 208.951322 -102.982522)
		(end 207.9498 -101.981)
		(width 0.254)
		(layer "B.Cu")
		(net "VSENSE_PVSA_CPU0_P")
	)
	(segment
		(start 212.318092 -102.34295)
		(end 211.67852 -102.982522)
		(width 0.254)
		(layer "B.Cu")
		(net "VSENSE_PVSA_CPU0_P")
	)
	(segment
		(start 204.901546 -102.869746)
		(end 204.6224 -102.5906)
		(width 0.254)
		(layer "B.Cu")
		(net "VSENSE_PVSA_CPU0_P")
	)
	(segment
		(start 207.9498 -101.981)
		(end 206.344012 -101.981)
		(width 0.254)
		(layer "B.Cu")
		(net "VSENSE_PVSA_CPU0_P")
	)
	(segment
		(start 206.344012 -101.981)
		(end 205.455266 -102.869746)
		(width 0.254)
		(layer "B.Cu")
		(net "VSENSE_PVSA_CPU0_P")
	)
	(segment
		(start 226.095814 -86.962234)
		(end 224.12452 -88.933528)
		(width 0.254)
		(layer "B.Cu")
		(net "VSENSE_PVSA_CPU0_P")
	)
	(segment
		(start 228.1174 -86.614)
		(end 227.769166 -86.962234)
		(width 0.254)
		(layer "B.Cu")
		(net "VSENSE_PVSA_CPU0_P")
	)
	(segment
		(start 224.12452 -91.71178)
		(end 213.49335 -102.34295)
		(width 0.254)
		(layer "B.Cu")
		(net "VSENSE_PVSA_CPU0_P")
	)
	(segment
		(start 213.49335 -102.34295)
		(end 212.318092 -102.34295)
		(width 0.254)
		(layer "B.Cu")
		(net "VSENSE_PVSA_CPU0_P")
	)
	(segment
		(start 205.455266 -102.869746)
		(end 204.901546 -102.869746)
		(width 0.254)
		(layer "B.Cu")
		(net "VSENSE_PVSA_CPU0_P")
	)
	(segment
		(start 224.12452 -90.243406)
		(end 224.12452 -91.71178)
		(width 0.254)
		(layer "B.Cu")
		(net "VSENSE_PVSA_CPU0_P")
	)
	(segment
		(start 202.8444 -101.9302)
		(end 203.8096 -102.8954)
		(width 0.127)
		(layer "In4.Cu")
		(net "VSENSE_PVSA_CPU0_P")
	)
	(segment
		(start 204.3176 -102.8954)
		(end 204.6224 -102.5906)
		(width 0.127)
		(layer "In4.Cu")
		(net "VSENSE_PVSA_CPU0_P")
	)
	(segment
		(start 188.344048 -80.146652)
		(end 187.658248 -80.832452)
		(width 0.127)
		(layer "In4.Cu")
		(net "VSENSE_PVSA_CPU0_P")
	)
	(segment
		(start 203.8096 -102.8954)
		(end 204.3176 -102.8954)
		(width 0.127)
		(layer "In4.Cu")
		(net "VSENSE_PVSA_CPU0_P")
	)
	(segment
		(start 201.52868 -102.45852)
		(end 202.057 -101.9302)
		(width 0.127)
		(layer "In4.Cu")
		(net "VSENSE_PVSA_CPU0_P")
	)
	(segment
		(start 202.057 -101.9302)
		(end 202.8444 -101.9302)
		(width 0.127)
		(layer "In4.Cu")
		(net "VSENSE_PVSA_CPU0_P")
	)
	(segment
		(start 196.05752 -103.1494)
		(end 196.56552 -103.1494)
		(width 0.127)
		(layer "In4.Cu")
		(net "VSENSE_PVSA_CPU0_P")
	)
	(segment
		(start 197.2564 -102.45852)
		(end 201.52868 -102.45852)
		(width 0.127)
		(layer "In4.Cu")
		(net "VSENSE_PVSA_CPU0_P")
	)
	(segment
		(start 196.56552 -103.1494)
		(end 197.2564 -102.45852)
		(width 0.127)
		(layer "In4.Cu")
		(net "VSENSE_PVSA_CPU0_P")
	)
	(segment
		(start 187.658248 -80.832452)
		(end 187.658248 -101.932994)
		(width 0.127)
		(layer "In4.Cu")
		(net "VSENSE_PVSA_CPU0_P")
	)
	(segment
		(start 188.259974 -102.53472)
		(end 195.44284 -102.53472)
		(width 0.127)
		(layer "In4.Cu")
		(net "VSENSE_PVSA_CPU0_P")
	)
	(segment
		(start 195.44284 -102.53472)
		(end 196.05752 -103.1494)
		(width 0.127)
		(layer "In4.Cu")
		(net "VSENSE_PVSA_CPU0_P")
	)
	(segment
		(start 187.658248 -101.932994)
		(end 188.259974 -102.53472)
		(width 0.127)
		(layer "In4.Cu")
		(net "VSENSE_PVSA_CPU0_P")
	)
	(segment
		(start 188.522356 -73.533)
		(end 188.73978 -73.533)
		(width 0.127)
		(layer "F.Cu")
		(net "VSENSE_PVSA_CPU0_N")
	)
	(segment
		(start 187.1726 -72.049894)
		(end 187.365894 -72.049894)
		(width 0.127)
		(layer "F.Cu")
		(net "VSENSE_PVSA_CPU0_N")
	)
	(segment
		(start 189.128654 -75.042014)
		(end 189.85738 -75.77074)
		(width 0.127)
		(layer "F.Cu")
		(net "VSENSE_PVSA_CPU0_N")
	)
	(segment
		(start 187.365894 -72.049894)
		(end 188.010546 -72.694546)
		(width 0.127)
		(layer "F.Cu")
		(net "VSENSE_PVSA_CPU0_N")
	)
	(segment
		(start 188.73978 -73.533)
		(end 189.128654 -73.921874)
		(width 0.127)
		(layer "F.Cu")
		(net "VSENSE_PVSA_CPU0_N")
	)
	(segment
		(start 188.010546 -72.694546)
		(end 188.010546 -73.02119)
		(width 0.127)
		(layer "F.Cu")
		(net "VSENSE_PVSA_CPU0_N")
	)
	(segment
		(start 204.563218 -103.4796)
		(end 204.7621 -103.4796)
		(width 0.127)
		(layer "F.Cu")
		(net "VSENSE_PVSA_CPU0_N")
	)
	(segment
		(start 187.7568 -79.510382)
		(end 187.7568 -79.809848)
		(width 0.127)
		(layer "F.Cu")
		(net "VSENSE_PVSA_CPU0_N")
	)
	(segment
		(start 189.128654 -73.921874)
		(end 189.128654 -75.042014)
		(width 0.127)
		(layer "F.Cu")
		(net "VSENSE_PVSA_CPU0_N")
	)
	(segment
		(start 188.6966 -79.1718)
		(end 188.095382 -79.1718)
		(width 0.127)
		(layer "F.Cu")
		(net "VSENSE_PVSA_CPU0_N")
	)
	(segment
		(start 188.010546 -73.02119)
		(end 188.522356 -73.533)
		(width 0.127)
		(layer "F.Cu")
		(net "VSENSE_PVSA_CPU0_N")
	)
	(segment
		(start 204.7621 -103.4796)
		(end 204.7875 -103.505)
		(width 0.127)
		(layer "F.Cu")
		(net "VSENSE_PVSA_CPU0_N")
	)
	(segment
		(start 189.85738 -75.77074)
		(end 189.85738 -78.01102)
		(width 0.127)
		(layer "F.Cu")
		(net "VSENSE_PVSA_CPU0_N")
	)
	(segment
		(start 205.486 -103.505)
		(end 206.248 -103.505)
		(width 0.127)
		(layer "F.Cu")
		(net "VSENSE_PVSA_CPU0_N")
	)
	(segment
		(start 188.095382 -79.1718)
		(end 187.7568 -79.510382)
		(width 0.127)
		(layer "F.Cu")
		(net "VSENSE_PVSA_CPU0_N")
	)
	(segment
		(start 187.7568 -79.809848)
		(end 187.429648 -80.137)
		(width 0.127)
		(layer "F.Cu")
		(net "VSENSE_PVSA_CPU0_N")
	)
	(segment
		(start 189.85738 -78.01102)
		(end 188.6966 -79.1718)
		(width 0.127)
		(layer "F.Cu")
		(net "VSENSE_PVSA_CPU0_N")
	)
	(segment
		(start 204.7875 -103.505)
		(end 205.486 -103.505)
		(width 0.127)
		(layer "F.Cu")
		(net "VSENSE_PVSA_CPU0_N")
	)
	(via
		(at 204.563218 -103.4796)
		(size 0.508)
		(drill 0.254)
		(layers "F.Cu" "B.Cu")
		(net "VSENSE_PVSA_CPU0_N")
	)
	(via
		(at 187.429648 -80.137)
		(size 0.508)
		(drill 0.254)
		(layers "F.Cu" "B.Cu")
		(net "VSENSE_PVSA_CPU0_N")
	)
	(segment
		(start 205.613254 -103.250746)
		(end 204.792072 -103.250746)
		(width 0.254)
		(layer "B.Cu")
		(net "VSENSE_PVSA_CPU0_N")
	)
	(segment
		(start 212.47608 -102.72395)
		(end 211.836508 -103.363522)
		(width 0.254)
		(layer "B.Cu")
		(net "VSENSE_PVSA_CPU0_N")
	)
	(segment
		(start 208.793334 -103.363522)
		(end 207.791812 -102.362)
		(width 0.254)
		(layer "B.Cu")
		(net "VSENSE_PVSA_CPU0_N")
	)
	(segment
		(start 227.881434 -87.343234)
		(end 226.253802 -87.343234)
		(width 0.254)
		(layer "B.Cu")
		(net "VSENSE_PVSA_CPU0_N")
	)
	(segment
		(start 226.253802 -87.343234)
		(end 224.50552 -89.091516)
		(width 0.254)
		(layer "B.Cu")
		(net "VSENSE_PVSA_CPU0_N")
	)
	(segment
		(start 224.50552 -89.091516)
		(end 224.50552 -91.869768)
		(width 0.254)
		(layer "B.Cu")
		(net "VSENSE_PVSA_CPU0_N")
	)
	(segment
		(start 213.651338 -102.72395)
		(end 212.47608 -102.72395)
		(width 0.254)
		(layer "B.Cu")
		(net "VSENSE_PVSA_CPU0_N")
	)
	(segment
		(start 224.50552 -91.869768)
		(end 213.651338 -102.72395)
		(width 0.254)
		(layer "B.Cu")
		(net "VSENSE_PVSA_CPU0_N")
	)
	(segment
		(start 206.502 -102.362)
		(end 205.613254 -103.250746)
		(width 0.254)
		(layer "B.Cu")
		(net "VSENSE_PVSA_CPU0_N")
	)
	(segment
		(start 228.1174 -87.5792)
		(end 227.881434 -87.343234)
		(width 0.254)
		(layer "B.Cu")
		(net "VSENSE_PVSA_CPU0_N")
	)
	(segment
		(start 207.791812 -102.362)
		(end 206.502 -102.362)
		(width 0.254)
		(layer "B.Cu")
		(net "VSENSE_PVSA_CPU0_N")
	)
	(segment
		(start 204.792072 -103.250746)
		(end 204.563218 -103.4796)
		(width 0.254)
		(layer "B.Cu")
		(net "VSENSE_PVSA_CPU0_N")
	)
	(segment
		(start 211.836508 -103.363522)
		(end 208.793334 -103.363522)
		(width 0.254)
		(layer "B.Cu")
		(net "VSENSE_PVSA_CPU0_N")
	)
	(segment
		(start 187.429648 -80.137)
		(end 187.429648 -102.027736)
		(width 0.127)
		(layer "In4.Cu")
		(net "VSENSE_PVSA_CPU0_N")
	)
	(segment
		(start 195.962778 -103.378)
		(end 196.660262 -103.378)
		(width 0.127)
		(layer "In4.Cu")
		(net "VSENSE_PVSA_CPU0_N")
	)
	(segment
		(start 195.348098 -102.76332)
		(end 195.962778 -103.378)
		(width 0.127)
		(layer "In4.Cu")
		(net "VSENSE_PVSA_CPU0_N")
	)
	(segment
		(start 203.714858 -103.124)
		(end 204.207618 -103.124)
		(width 0.127)
		(layer "In4.Cu")
		(net "VSENSE_PVSA_CPU0_N")
	)
	(segment
		(start 202.151742 -102.1588)
		(end 202.749658 -102.1588)
		(width 0.127)
		(layer "In4.Cu")
		(net "VSENSE_PVSA_CPU0_N")
	)
	(segment
		(start 187.429648 -102.027736)
		(end 188.165232 -102.76332)
		(width 0.127)
		(layer "In4.Cu")
		(net "VSENSE_PVSA_CPU0_N")
	)
	(segment
		(start 204.207618 -103.124)
		(end 204.563218 -103.4796)
		(width 0.127)
		(layer "In4.Cu")
		(net "VSENSE_PVSA_CPU0_N")
	)
	(segment
		(start 197.351142 -102.68712)
		(end 201.623422 -102.68712)
		(width 0.127)
		(layer "In4.Cu")
		(net "VSENSE_PVSA_CPU0_N")
	)
	(segment
		(start 196.660262 -103.378)
		(end 197.351142 -102.68712)
		(width 0.127)
		(layer "In4.Cu")
		(net "VSENSE_PVSA_CPU0_N")
	)
	(segment
		(start 188.165232 -102.76332)
		(end 195.348098 -102.76332)
		(width 0.127)
		(layer "In4.Cu")
		(net "VSENSE_PVSA_CPU0_N")
	)
	(segment
		(start 201.623422 -102.68712)
		(end 202.151742 -102.1588)
		(width 0.127)
		(layer "In4.Cu")
		(net "VSENSE_PVSA_CPU0_N")
	)
	(segment
		(start 202.749658 -102.1588)
		(end 203.714858 -103.124)
		(width 0.127)
		(layer "In4.Cu")
		(net "VSENSE_PVSA_CPU0_N")
	)
	(segment
		(start 189.223904 -72.644)
		(end 189.236604 -72.6567)
		(width 0.127)
		(layer "F.Cu")
		(net "VSENSE_PVSA_CPU0_BVSP")
	)
	(segment
		(start 190.900812 -72.433434)
		(end 190.677546 -72.6567)
		(width 0.127)
		(layer "F.Cu")
		(net "VSENSE_PVSA_CPU0_BVSP")
	)
	(segment
		(start 189.236604 -72.6567)
		(end 189.70498 -72.6567)
		(width 0.127)
		(layer "F.Cu")
		(net "VSENSE_PVSA_CPU0_BVSP")
	)
	(segment
		(start 190.677546 -72.6567)
		(end 189.70498 -72.6567)
		(width 0.127)
		(layer "F.Cu")
		(net "VSENSE_PVSA_CPU0_BVSP")
	)
	(segment
		(start 187.745878 -71.650098)
		(end 188.73978 -72.644)
		(width 0.127)
		(layer "F.Cu")
		(net "VSENSE_PVSA_CPU0_BVSP")
	)
	(segment
		(start 188.73978 -72.644)
		(end 189.223904 -72.644)
		(width 0.127)
		(layer "F.Cu")
		(net "VSENSE_PVSA_CPU0_BVSP")
	)
	(segment
		(start 187.1726 -71.650098)
		(end 187.745878 -71.650098)
		(width 0.127)
		(layer "F.Cu")
		(net "VSENSE_PVSA_CPU0_BVSP")
	)
	(via
		(at 190.900812 -72.433434)
		(size 0.762)
		(drill 0.381)
		(layers "F.Cu" "B.Cu")
		(net "VSENSE_PVSA_CPU0_BVSP")
	)
	(segment
		(start 129.372868 -77.202538)
		(end 129.944368 -77.202538)
		(width 0.127)
		(layer "F.Cu")
		(net "VSENSE_PVCCMCP_CPU1_SKT_VSEN")
	)
	(segment
		(start 168.425114 -43.817286)
		(end 167.7924 -44.45)
		(width 0.127)
		(layer "F.Cu")
		(net "VSENSE_PVCCMCP_CPU1_SKT_VSEN")
	)
	(segment
		(start 168.425114 -43.80103)
		(end 168.425114 -43.817286)
		(width 0.127)
		(layer "F.Cu")
		(net "VSENSE_PVCCMCP_CPU1_SKT_VSEN")
	)
	(via
		(at 129.944368 -77.202538)
		(size 0.508)
		(drill 0.254)
		(layers "F.Cu" "B.Cu")
		(net "VSENSE_PVCCMCP_CPU1_SKT_VSEN")
	)
	(via
		(at 167.7924 -44.45)
		(size 0.508)
		(drill 0.254)
		(layers "F.Cu" "B.Cu")
		(net "VSENSE_PVCCMCP_CPU1_SKT_VSEN")
	)
	(segment
		(start 141.898116 -74.35342)
		(end 143.116808 -74.35342)
		(width 0.0889)
		(layer "In2.Cu")
		(net "VSENSE_PVCCMCP_CPU1_SKT_VSEN")
	)
	(segment
		(start 167.6654 -43.9674)
		(end 167.7924 -44.0944)
		(width 0.127)
		(layer "In2.Cu")
		(net "VSENSE_PVCCMCP_CPU1_SKT_VSEN")
	)
	(segment
		(start 141.37513 -73.830434)
		(end 141.898116 -74.35342)
		(width 0.0889)
		(layer "In2.Cu")
		(net "VSENSE_PVCCMCP_CPU1_SKT_VSEN")
	)
	(segment
		(start 143.116808 -74.35342)
		(end 143.546322 -73.923906)
		(width 0.0889)
		(layer "In2.Cu")
		(net "VSENSE_PVCCMCP_CPU1_SKT_VSEN")
	)
	(segment
		(start 167.7924 -44.0944)
		(end 167.7924 -44.45)
		(width 0.127)
		(layer "In2.Cu")
		(net "VSENSE_PVCCMCP_CPU1_SKT_VSEN")
	)
	(segment
		(start 159.23514 -50.72507)
		(end 165.99281 -43.9674)
		(width 0.127)
		(layer "In2.Cu")
		(net "VSENSE_PVCCMCP_CPU1_SKT_VSEN")
	)
	(segment
		(start 131.643628 -76.802488)
		(end 131.679188 -76.802488)
		(width 0.0889)
		(layer "In2.Cu")
		(net "VSENSE_PVCCMCP_CPU1_SKT_VSEN")
	)
	(segment
		(start 139.376658 -73.335134)
		(end 139.39901 -73.335134)
		(width 0.0889)
		(layer "In2.Cu")
		(net "VSENSE_PVCCMCP_CPU1_SKT_VSEN")
	)
	(segment
		(start 153.51887 -61.33846)
		(end 155.36291 -59.49442)
		(width 0.127)
		(layer "In2.Cu")
		(net "VSENSE_PVCCMCP_CPU1_SKT_VSEN")
	)
	(segment
		(start 152.22601 -73.69302)
		(end 153.51887 -72.40016)
		(width 0.127)
		(layer "In2.Cu")
		(net "VSENSE_PVCCMCP_CPU1_SKT_VSEN")
	)
	(segment
		(start 159.23514 -58.06821)
		(end 159.23514 -50.72507)
		(width 0.127)
		(layer "In2.Cu")
		(net "VSENSE_PVCCMCP_CPU1_SKT_VSEN")
	)
	(segment
		(start 133.363208 -75.811888)
		(end 133.395974 -75.811888)
		(width 0.0889)
		(layer "In2.Cu")
		(net "VSENSE_PVCCMCP_CPU1_SKT_VSEN")
	)
	(segment
		(start 138.51128 -73.830434)
		(end 138.554206 -73.830434)
		(width 0.0889)
		(layer "In2.Cu")
		(net "VSENSE_PVCCMCP_CPU1_SKT_VSEN")
	)
	(segment
		(start 132.519674 -76.306934)
		(end 132.541264 -76.306934)
		(width 0.0889)
		(layer "In2.Cu")
		(net "VSENSE_PVCCMCP_CPU1_SKT_VSEN")
	)
	(segment
		(start 129.944368 -76.864464)
		(end 130.009646 -76.799186)
		(width 0.0889)
		(layer "In2.Cu")
		(net "VSENSE_PVCCMCP_CPU1_SKT_VSEN")
	)
	(segment
		(start 129.944368 -77.202538)
		(end 129.944368 -76.864464)
		(width 0.0889)
		(layer "In2.Cu")
		(net "VSENSE_PVCCMCP_CPU1_SKT_VSEN")
	)
	(segment
		(start 155.36291 -59.49442)
		(end 157.80893 -59.49442)
		(width 0.127)
		(layer "In2.Cu")
		(net "VSENSE_PVCCMCP_CPU1_SKT_VSEN")
	)
	(segment
		(start 143.572484 -73.923906)
		(end 143.587978 -73.908412)
		(width 0.0889)
		(layer "In2.Cu")
		(net "VSENSE_PVCCMCP_CPU1_SKT_VSEN")
	)
	(segment
		(start 135.090408 -74.821034)
		(end 135.10006 -74.821034)
		(width 0.0889)
		(layer "In2.Cu")
		(net "VSENSE_PVCCMCP_CPU1_SKT_VSEN")
	)
	(segment
		(start 130.791712 -76.306934)
		(end 130.814064 -76.306934)
		(width 0.0889)
		(layer "In2.Cu")
		(net "VSENSE_PVCCMCP_CPU1_SKT_VSEN")
	)
	(segment
		(start 165.99281 -43.9674)
		(end 167.6654 -43.9674)
		(width 0.127)
		(layer "In2.Cu")
		(net "VSENSE_PVCCMCP_CPU1_SKT_VSEN")
	)
	(segment
		(start 143.80337 -73.69302)
		(end 152.22601 -73.69302)
		(width 0.127)
		(layer "In2.Cu")
		(net "VSENSE_PVCCMCP_CPU1_SKT_VSEN")
	)
	(segment
		(start 157.80893 -59.49442)
		(end 159.23514 -58.06821)
		(width 0.127)
		(layer "In2.Cu")
		(net "VSENSE_PVCCMCP_CPU1_SKT_VSEN")
	)
	(segment
		(start 135.932164 -75.316334)
		(end 135.975344 -75.316334)
		(width 0.0889)
		(layer "In2.Cu")
		(net "VSENSE_PVCCMCP_CPU1_SKT_VSEN")
	)
	(segment
		(start 136.807448 -74.821034)
		(end 136.825228 -74.821034)
		(width 0.0889)
		(layer "In2.Cu")
		(net "VSENSE_PVCCMCP_CPU1_SKT_VSEN")
	)
	(segment
		(start 134.225538 -75.316334)
		(end 134.258304 -75.316334)
		(width 0.0889)
		(layer "In2.Cu")
		(net "VSENSE_PVCCMCP_CPU1_SKT_VSEN")
	)
	(segment
		(start 143.546322 -73.923906)
		(end 143.572484 -73.923906)
		(width 0.0889)
		(layer "In2.Cu")
		(net "VSENSE_PVCCMCP_CPU1_SKT_VSEN")
	)
	(segment
		(start 143.587978 -73.908412)
		(end 143.80337 -73.69302)
		(width 0.127)
		(layer "In2.Cu")
		(net "VSENSE_PVCCMCP_CPU1_SKT_VSEN")
	)
	(segment
		(start 153.51887 -72.40016)
		(end 153.51887 -61.33846)
		(width 0.127)
		(layer "In2.Cu")
		(net "VSENSE_PVCCMCP_CPU1_SKT_VSEN")
	)
	(segment
		(start 137.655808 -74.325734)
		(end 137.688574 -74.325734)
		(width 0.0889)
		(layer "In2.Cu")
		(net "VSENSE_PVCCMCP_CPU1_SKT_VSEN")
	)
	(segment
		(start 140.224256 -73.830434)
		(end 141.37513 -73.830434)
		(width 0.0889)
		(layer "In2.Cu")
		(net "VSENSE_PVCCMCP_CPU1_SKT_VSEN")
	)
	(segment
		(start 132.173218 -76.507086)
		(end 132.17652 -76.501244)
		(width 0.0889)
		(layer "In2.Cu")
		(net "VSENSE_PVCCMCP_CPU1_SKT_VSEN")
	)
	(arc
		(start 133.395974 -75.811888)
		(mid 133.681398 -75.728421)
		(end 133.890004 -75.516486)
		(width 0.0889)
		(layer "In2.Cu")
		(net "VSENSE_PVCCMCP_CPU1_SKT_VSEN")
	)
	(arc
		(start 139.734544 -73.535286)
		(mid 139.941298 -73.746105)
		(end 140.224256 -73.830434)
		(width 0.0889)
		(layer "In2.Cu")
		(net "VSENSE_PVCCMCP_CPU1_SKT_VSEN")
	)
	(arc
		(start 139.39901 -73.335134)
		(mid 139.59286 -73.391484)
		(end 139.734544 -73.535286)
		(width 0.0889)
		(layer "In2.Cu")
		(net "VSENSE_PVCCMCP_CPU1_SKT_VSEN")
	)
	(arc
		(start 139.041124 -73.535286)
		(mid 139.182807 -73.391482)
		(end 139.376658 -73.335134)
		(width 0.0889)
		(layer "In2.Cu")
		(net "VSENSE_PVCCMCP_CPU1_SKT_VSEN")
	)
	(arc
		(start 138.182604 -74.030332)
		(mid 138.321348 -73.888299)
		(end 138.51128 -73.830434)
		(width 0.0889)
		(layer "In2.Cu")
		(net "VSENSE_PVCCMCP_CPU1_SKT_VSEN")
	)
	(arc
		(start 136.465564 -75.021186)
		(mid 136.610012 -74.875855)
		(end 136.807448 -74.821034)
		(width 0.0889)
		(layer "In2.Cu")
		(net "VSENSE_PVCCMCP_CPU1_SKT_VSEN")
	)
	(arc
		(start 132.17652 -76.501244)
		(mid 132.322486 -76.358845)
		(end 132.519674 -76.306934)
		(width 0.0889)
		(layer "In2.Cu")
		(net "VSENSE_PVCCMCP_CPU1_SKT_VSEN")
	)
	(arc
		(start 134.748524 -75.021186)
		(mid 134.892972 -74.875855)
		(end 135.090408 -74.821034)
		(width 0.0889)
		(layer "In2.Cu")
		(net "VSENSE_PVCCMCP_CPU1_SKT_VSEN")
	)
	(arc
		(start 136.825228 -74.821034)
		(mid 137.113373 -74.738715)
		(end 137.324084 -74.525632)
		(width 0.0889)
		(layer "In2.Cu")
		(net "VSENSE_PVCCMCP_CPU1_SKT_VSEN")
	)
	(arc
		(start 131.149598 -76.507086)
		(mid 131.358206 -76.719018)
		(end 131.643628 -76.802488)
		(width 0.0889)
		(layer "In2.Cu")
		(net "VSENSE_PVCCMCP_CPU1_SKT_VSEN")
	)
	(arc
		(start 133.031484 -76.011786)
		(mid 133.171563 -75.86905)
		(end 133.363208 -75.811888)
		(width 0.0889)
		(layer "In2.Cu")
		(net "VSENSE_PVCCMCP_CPU1_SKT_VSEN")
	)
	(arc
		(start 134.258304 -75.316334)
		(mid 134.541521 -75.232053)
		(end 134.748524 -75.021186)
		(width 0.0889)
		(layer "In2.Cu")
		(net "VSENSE_PVCCMCP_CPU1_SKT_VSEN")
	)
	(arc
		(start 133.890004 -75.516486)
		(mid 134.031687 -75.372682)
		(end 134.225538 -75.316334)
		(width 0.0889)
		(layer "In2.Cu")
		(net "VSENSE_PVCCMCP_CPU1_SKT_VSEN")
	)
	(arc
		(start 131.679188 -76.802488)
		(mid 131.964612 -76.719021)
		(end 132.173218 -76.507086)
		(width 0.0889)
		(layer "In2.Cu")
		(net "VSENSE_PVCCMCP_CPU1_SKT_VSEN")
	)
	(arc
		(start 138.554206 -73.830434)
		(mid 138.835568 -73.745388)
		(end 139.041124 -73.535286)
		(width 0.0889)
		(layer "In2.Cu")
		(net "VSENSE_PVCCMCP_CPU1_SKT_VSEN")
	)
	(arc
		(start 130.009646 -76.799186)
		(mid 130.267783 -76.706432)
		(end 130.456178 -76.507086)
		(width 0.0889)
		(layer "In2.Cu")
		(net "VSENSE_PVCCMCP_CPU1_SKT_VSEN")
	)
	(arc
		(start 135.975344 -75.316334)
		(mid 136.258561 -75.232053)
		(end 136.465564 -75.021186)
		(width 0.0889)
		(layer "In2.Cu")
		(net "VSENSE_PVCCMCP_CPU1_SKT_VSEN")
	)
	(arc
		(start 135.10006 -74.821034)
		(mid 135.297495 -74.875857)
		(end 135.441944 -75.021186)
		(width 0.0889)
		(layer "In2.Cu")
		(net "VSENSE_PVCCMCP_CPU1_SKT_VSEN")
	)
	(arc
		(start 137.324084 -74.525632)
		(mid 137.464163 -74.382896)
		(end 137.655808 -74.325734)
		(width 0.0889)
		(layer "In2.Cu")
		(net "VSENSE_PVCCMCP_CPU1_SKT_VSEN")
	)
	(arc
		(start 130.814064 -76.306934)
		(mid 131.007914 -76.363284)
		(end 131.149598 -76.507086)
		(width 0.0889)
		(layer "In2.Cu")
		(net "VSENSE_PVCCMCP_CPU1_SKT_VSEN")
	)
	(arc
		(start 132.541264 -76.306934)
		(mid 132.824481 -76.222653)
		(end 133.031484 -76.011786)
		(width 0.0889)
		(layer "In2.Cu")
		(net "VSENSE_PVCCMCP_CPU1_SKT_VSEN")
	)
	(arc
		(start 130.456178 -76.507086)
		(mid 130.597861 -76.363282)
		(end 130.791712 -76.306934)
		(width 0.0889)
		(layer "In2.Cu")
		(net "VSENSE_PVCCMCP_CPU1_SKT_VSEN")
	)
	(arc
		(start 137.688574 -74.325734)
		(mid 137.973998 -74.242267)
		(end 138.182604 -74.030332)
		(width 0.0889)
		(layer "In2.Cu")
		(net "VSENSE_PVCCMCP_CPU1_SKT_VSEN")
	)
	(arc
		(start 135.441944 -75.021186)
		(mid 135.648948 -75.23205)
		(end 135.932164 -75.316334)
		(width 0.0889)
		(layer "In2.Cu")
		(net "VSENSE_PVCCMCP_CPU1_SKT_VSEN")
	)
	(segment
		(start 168.4274 -42.545)
		(end 168.425114 -42.53103)
		(width 0.127)
		(layer "F.Cu")
		(net "VSENSE_PVCCMCP_CPU1_SKT_VRTN")
	)
	(segment
		(start 129.372868 -76.211938)
		(end 129.944368 -76.211938)
		(width 0.127)
		(layer "F.Cu")
		(net "VSENSE_PVCCMCP_CPU1_SKT_VRTN")
	)
	(segment
		(start 167.7924 -43.18)
		(end 168.4274 -42.545)
		(width 0.127)
		(layer "F.Cu")
		(net "VSENSE_PVCCMCP_CPU1_SKT_VRTN")
	)
	(via
		(at 167.7924 -43.18)
		(size 0.508)
		(drill 0.254)
		(layers "F.Cu" "B.Cu")
		(net "VSENSE_PVCCMCP_CPU1_SKT_VRTN")
	)
	(via
		(at 129.944368 -76.211938)
		(size 0.508)
		(drill 0.254)
		(layers "F.Cu" "B.Cu")
		(net "VSENSE_PVCCMCP_CPU1_SKT_VRTN")
	)
	(segment
		(start 158.98114 -57.9628)
		(end 158.98114 -50.61966)
		(width 0.127)
		(layer "In2.Cu")
		(net "VSENSE_PVCCMCP_CPU1_SKT_VRTN")
	)
	(segment
		(start 165.8874 -43.7134)
		(end 167.64 -43.7134)
		(width 0.127)
		(layer "In2.Cu")
		(net "VSENSE_PVCCMCP_CPU1_SKT_VRTN")
	)
	(segment
		(start 141.95171 -74.13752)
		(end 143.026892 -74.13752)
		(width 0.0889)
		(layer "In2.Cu")
		(net "VSENSE_PVCCMCP_CPU1_SKT_VRTN")
	)
	(segment
		(start 140.22832 -73.639934)
		(end 141.454124 -73.639934)
		(width 0.0889)
		(layer "In2.Cu")
		(net "VSENSE_PVCCMCP_CPU1_SKT_VRTN")
	)
	(segment
		(start 152.1206 -73.43902)
		(end 153.26487 -72.29475)
		(width 0.127)
		(layer "In2.Cu")
		(net "VSENSE_PVCCMCP_CPU1_SKT_VRTN")
	)
	(segment
		(start 158.98114 -50.61966)
		(end 165.8874 -43.7134)
		(width 0.127)
		(layer "In2.Cu")
		(net "VSENSE_PVCCMCP_CPU1_SKT_VRTN")
	)
	(segment
		(start 129.944368 -76.550012)
		(end 130.00228 -76.607924)
		(width 0.0889)
		(layer "In2.Cu")
		(net "VSENSE_PVCCMCP_CPU1_SKT_VRTN")
	)
	(segment
		(start 131.650232 -76.611988)
		(end 131.661408 -76.611988)
		(width 0.0889)
		(layer "In2.Cu")
		(net "VSENSE_PVCCMCP_CPU1_SKT_VRTN")
	)
	(segment
		(start 132.501894 -76.116434)
		(end 132.53466 -76.116434)
		(width 0.0889)
		(layer "In2.Cu")
		(net "VSENSE_PVCCMCP_CPU1_SKT_VRTN")
	)
	(segment
		(start 143.392906 -73.771506)
		(end 143.392906 -73.744074)
		(width 0.0889)
		(layer "In2.Cu")
		(net "VSENSE_PVCCMCP_CPU1_SKT_VRTN")
	)
	(segment
		(start 153.26487 -72.29475)
		(end 153.26487 -61.23305)
		(width 0.127)
		(layer "In2.Cu")
		(net "VSENSE_PVCCMCP_CPU1_SKT_VRTN")
	)
	(segment
		(start 132.004562 -76.417678)
		(end 132.007864 -76.411836)
		(width 0.0889)
		(layer "In2.Cu")
		(net "VSENSE_PVCCMCP_CPU1_SKT_VRTN")
	)
	(segment
		(start 143.4084 -73.72858)
		(end 143.69796 -73.43902)
		(width 0.127)
		(layer "In2.Cu")
		(net "VSENSE_PVCCMCP_CPU1_SKT_VRTN")
	)
	(segment
		(start 167.7924 -43.561)
		(end 167.7924 -43.18)
		(width 0.127)
		(layer "In2.Cu")
		(net "VSENSE_PVCCMCP_CPU1_SKT_VRTN")
	)
	(segment
		(start 143.69796 -73.43902)
		(end 152.1206 -73.43902)
		(width 0.127)
		(layer "In2.Cu")
		(net "VSENSE_PVCCMCP_CPU1_SKT_VRTN")
	)
	(segment
		(start 155.2575 -59.24042)
		(end 157.70352 -59.24042)
		(width 0.127)
		(layer "In2.Cu")
		(net "VSENSE_PVCCMCP_CPU1_SKT_VRTN")
	)
	(segment
		(start 138.504422 -73.639934)
		(end 138.547348 -73.639934)
		(width 0.0889)
		(layer "In2.Cu")
		(net "VSENSE_PVCCMCP_CPU1_SKT_VRTN")
	)
	(segment
		(start 136.79932 -74.630534)
		(end 136.8171 -74.630534)
		(width 0.0889)
		(layer "In2.Cu")
		(net "VSENSE_PVCCMCP_CPU1_SKT_VRTN")
	)
	(segment
		(start 139.370054 -73.144634)
		(end 139.405614 -73.144634)
		(width 0.0889)
		(layer "In2.Cu")
		(net "VSENSE_PVCCMCP_CPU1_SKT_VRTN")
	)
	(segment
		(start 134.218934 -75.125834)
		(end 134.2517 -75.125834)
		(width 0.0889)
		(layer "In2.Cu")
		(net "VSENSE_PVCCMCP_CPU1_SKT_VRTN")
	)
	(segment
		(start 130.785108 -76.116434)
		(end 130.820668 -76.116434)
		(width 0.0889)
		(layer "In2.Cu")
		(net "VSENSE_PVCCMCP_CPU1_SKT_VRTN")
	)
	(segment
		(start 135.938768 -75.125834)
		(end 135.96874 -75.125834)
		(width 0.0889)
		(layer "In2.Cu")
		(net "VSENSE_PVCCMCP_CPU1_SKT_VRTN")
	)
	(segment
		(start 133.356604 -75.621388)
		(end 133.38937 -75.621388)
		(width 0.0889)
		(layer "In2.Cu")
		(net "VSENSE_PVCCMCP_CPU1_SKT_VRTN")
	)
	(segment
		(start 143.392906 -73.744074)
		(end 143.4084 -73.72858)
		(width 0.0889)
		(layer "In2.Cu")
		(net "VSENSE_PVCCMCP_CPU1_SKT_VRTN")
	)
	(segment
		(start 137.649204 -74.135234)
		(end 137.68197 -74.135234)
		(width 0.0889)
		(layer "In2.Cu")
		(net "VSENSE_PVCCMCP_CPU1_SKT_VRTN")
	)
	(segment
		(start 153.26487 -61.23305)
		(end 155.2575 -59.24042)
		(width 0.127)
		(layer "In2.Cu")
		(net "VSENSE_PVCCMCP_CPU1_SKT_VRTN")
	)
	(segment
		(start 167.64 -43.7134)
		(end 167.7924 -43.561)
		(width 0.127)
		(layer "In2.Cu")
		(net "VSENSE_PVCCMCP_CPU1_SKT_VRTN")
	)
	(segment
		(start 143.026892 -74.13752)
		(end 143.392906 -73.771506)
		(width 0.0889)
		(layer "In2.Cu")
		(net "VSENSE_PVCCMCP_CPU1_SKT_VRTN")
	)
	(segment
		(start 157.70352 -59.24042)
		(end 158.98114 -57.9628)
		(width 0.127)
		(layer "In2.Cu")
		(net "VSENSE_PVCCMCP_CPU1_SKT_VRTN")
	)
	(segment
		(start 135.08228 -74.630534)
		(end 135.108188 -74.630534)
		(width 0.0889)
		(layer "In2.Cu")
		(net "VSENSE_PVCCMCP_CPU1_SKT_VRTN")
	)
	(segment
		(start 129.944368 -76.211938)
		(end 129.944368 -76.550012)
		(width 0.0889)
		(layer "In2.Cu")
		(net "VSENSE_PVCCMCP_CPU1_SKT_VRTN")
	)
	(segment
		(start 141.454124 -73.639934)
		(end 141.95171 -74.13752)
		(width 0.0889)
		(layer "In2.Cu")
		(net "VSENSE_PVCCMCP_CPU1_SKT_VRTN")
	)
	(arc
		(start 138.017504 -73.935082)
		(mid 138.223063 -73.724985)
		(end 138.504422 -73.639934)
		(width 0.0889)
		(layer "In2.Cu")
		(net "VSENSE_PVCCMCP_CPU1_SKT_VRTN")
	)
	(arc
		(start 137.68197 -74.135234)
		(mid 137.87582 -74.078884)
		(end 138.017504 -73.935082)
		(width 0.0889)
		(layer "In2.Cu")
		(net "VSENSE_PVCCMCP_CPU1_SKT_VRTN")
	)
	(arc
		(start 139.405614 -73.144634)
		(mid 139.691038 -73.228101)
		(end 139.899644 -73.440036)
		(width 0.0889)
		(layer "In2.Cu")
		(net "VSENSE_PVCCMCP_CPU1_SKT_VRTN")
	)
	(arc
		(start 136.8171 -74.630534)
		(mid 137.014535 -74.575711)
		(end 137.158984 -74.430382)
		(width 0.0889)
		(layer "In2.Cu")
		(net "VSENSE_PVCCMCP_CPU1_SKT_VRTN")
	)
	(arc
		(start 131.661408 -76.611988)
		(mid 131.858569 -76.560029)
		(end 132.004562 -76.417678)
		(width 0.0889)
		(layer "In2.Cu")
		(net "VSENSE_PVCCMCP_CPU1_SKT_VRTN")
	)
	(arc
		(start 138.876024 -73.440036)
		(mid 139.084632 -73.228104)
		(end 139.370054 -73.144634)
		(width 0.0889)
		(layer "In2.Cu")
		(net "VSENSE_PVCCMCP_CPU1_SKT_VRTN")
	)
	(arc
		(start 135.607044 -74.925936)
		(mid 135.747123 -75.068672)
		(end 135.938768 -75.125834)
		(width 0.0889)
		(layer "In2.Cu")
		(net "VSENSE_PVCCMCP_CPU1_SKT_VRTN")
	)
	(arc
		(start 132.53466 -76.116434)
		(mid 132.726302 -76.059268)
		(end 132.866384 -75.916536)
		(width 0.0889)
		(layer "In2.Cu")
		(net "VSENSE_PVCCMCP_CPU1_SKT_VRTN")
	)
	(arc
		(start 138.547348 -73.639934)
		(mid 138.737277 -73.582064)
		(end 138.876024 -73.440036)
		(width 0.0889)
		(layer "In2.Cu")
		(net "VSENSE_PVCCMCP_CPU1_SKT_VRTN")
	)
	(arc
		(start 135.96874 -75.125834)
		(mid 136.160382 -75.068668)
		(end 136.300464 -74.925936)
		(width 0.0889)
		(layer "In2.Cu")
		(net "VSENSE_PVCCMCP_CPU1_SKT_VRTN")
	)
	(arc
		(start 130.00228 -76.607924)
		(mid 130.169181 -76.543024)
		(end 130.291078 -76.411836)
		(width 0.0889)
		(layer "In2.Cu")
		(net "VSENSE_PVCCMCP_CPU1_SKT_VRTN")
	)
	(arc
		(start 133.724904 -75.421236)
		(mid 133.933512 -75.209304)
		(end 134.218934 -75.125834)
		(width 0.0889)
		(layer "In2.Cu")
		(net "VSENSE_PVCCMCP_CPU1_SKT_VRTN")
	)
	(arc
		(start 131.314698 -76.411836)
		(mid 131.456381 -76.55564)
		(end 131.650232 -76.611988)
		(width 0.0889)
		(layer "In2.Cu")
		(net "VSENSE_PVCCMCP_CPU1_SKT_VRTN")
	)
	(arc
		(start 135.108188 -74.630534)
		(mid 135.396333 -74.712853)
		(end 135.607044 -74.925936)
		(width 0.0889)
		(layer "In2.Cu")
		(net "VSENSE_PVCCMCP_CPU1_SKT_VRTN")
	)
	(arc
		(start 130.291078 -76.411836)
		(mid 130.499686 -76.199904)
		(end 130.785108 -76.116434)
		(width 0.0889)
		(layer "In2.Cu")
		(net "VSENSE_PVCCMCP_CPU1_SKT_VRTN")
	)
	(arc
		(start 132.866384 -75.916536)
		(mid 133.073388 -75.705672)
		(end 133.356604 -75.621388)
		(width 0.0889)
		(layer "In2.Cu")
		(net "VSENSE_PVCCMCP_CPU1_SKT_VRTN")
	)
	(arc
		(start 134.583424 -74.925936)
		(mid 134.794137 -74.712857)
		(end 135.08228 -74.630534)
		(width 0.0889)
		(layer "In2.Cu")
		(net "VSENSE_PVCCMCP_CPU1_SKT_VRTN")
	)
	(arc
		(start 139.899644 -73.440036)
		(mid 140.038388 -73.582069)
		(end 140.22832 -73.639934)
		(width 0.0889)
		(layer "In2.Cu")
		(net "VSENSE_PVCCMCP_CPU1_SKT_VRTN")
	)
	(arc
		(start 134.2517 -75.125834)
		(mid 134.443342 -75.068668)
		(end 134.583424 -74.925936)
		(width 0.0889)
		(layer "In2.Cu")
		(net "VSENSE_PVCCMCP_CPU1_SKT_VRTN")
	)
	(arc
		(start 130.820668 -76.116434)
		(mid 131.106092 -76.199901)
		(end 131.314698 -76.411836)
		(width 0.0889)
		(layer "In2.Cu")
		(net "VSENSE_PVCCMCP_CPU1_SKT_VRTN")
	)
	(arc
		(start 137.158984 -74.430382)
		(mid 137.365988 -74.219518)
		(end 137.649204 -74.135234)
		(width 0.0889)
		(layer "In2.Cu")
		(net "VSENSE_PVCCMCP_CPU1_SKT_VRTN")
	)
	(arc
		(start 132.007864 -76.411836)
		(mid 132.216472 -76.199904)
		(end 132.501894 -76.116434)
		(width 0.0889)
		(layer "In2.Cu")
		(net "VSENSE_PVCCMCP_CPU1_SKT_VRTN")
	)
	(arc
		(start 133.38937 -75.621388)
		(mid 133.58322 -75.565038)
		(end 133.724904 -75.421236)
		(width 0.0889)
		(layer "In2.Cu")
		(net "VSENSE_PVCCMCP_CPU1_SKT_VRTN")
	)
	(arc
		(start 136.300464 -74.925936)
		(mid 136.511177 -74.712857)
		(end 136.79932 -74.630534)
		(width 0.0889)
		(layer "In2.Cu")
		(net "VSENSE_PVCCMCP_CPU1_SKT_VRTN")
	)
	(segment
		(start 334.0481 -43.1673)
		(end 334.05572 -43.1673)
		(width 0.127)
		(layer "F.Cu")
		(net "VSENSE_PVCCMCP_CPU0_SKT_VSEN")
	)
	(segment
		(start 294.3733 -77.202538)
		(end 294.9448 -77.202538)
		(width 0.127)
		(layer "F.Cu")
		(net "VSENSE_PVCCMCP_CPU0_SKT_VSEN")
	)
	(segment
		(start 333.404972 -43.80103)
		(end 333.4004 -43.815)
		(width 0.127)
		(layer "F.Cu")
		(net "VSENSE_PVCCMCP_CPU0_SKT_VSEN")
	)
	(segment
		(start 333.4004 -43.815)
		(end 334.0481 -43.1673)
		(width 0.127)
		(layer "F.Cu")
		(net "VSENSE_PVCCMCP_CPU0_SKT_VSEN")
	)
	(via
		(at 334.05572 -43.1673)
		(size 0.508)
		(drill 0.254)
		(layers "F.Cu" "B.Cu")
		(net "VSENSE_PVCCMCP_CPU0_SKT_VSEN")
	)
	(via
		(at 294.9448 -77.202538)
		(size 0.508)
		(drill 0.254)
		(layers "F.Cu" "B.Cu")
		(net "VSENSE_PVCCMCP_CPU0_SKT_VSEN")
	)
	(segment
		(start 294.9448 -76.864464)
		(end 294.9448 -77.202538)
		(width 0.0889)
		(layer "In2.Cu")
		(net "VSENSE_PVCCMCP_CPU0_SKT_VSEN")
	)
	(segment
		(start 333.73822 -43.4848)
		(end 333.73822 -45.656754)
		(width 0.127)
		(layer "In2.Cu")
		(net "VSENSE_PVCCMCP_CPU0_SKT_VSEN")
	)
	(segment
		(start 296.67962 -76.802488)
		(end 296.64406 -76.802488)
		(width 0.0889)
		(layer "In2.Cu")
		(net "VSENSE_PVCCMCP_CPU0_SKT_VSEN")
	)
	(segment
		(start 297.176952 -76.501244)
		(end 297.17365 -76.507086)
		(width 0.0889)
		(layer "In2.Cu")
		(net "VSENSE_PVCCMCP_CPU0_SKT_VSEN")
	)
	(segment
		(start 308.383178 -74.368914)
		(end 307.277516 -74.368914)
		(width 0.127)
		(layer "In2.Cu")
		(net "VSENSE_PVCCMCP_CPU0_SKT_VSEN")
	)
	(segment
		(start 297.541696 -76.306934)
		(end 297.520106 -76.306934)
		(width 0.0889)
		(layer "In2.Cu")
		(net "VSENSE_PVCCMCP_CPU0_SKT_VSEN")
	)
	(segment
		(start 298.393612 -75.811888)
		(end 298.36364 -75.811888)
		(width 0.0889)
		(layer "In2.Cu")
		(net "VSENSE_PVCCMCP_CPU0_SKT_VSEN")
	)
	(segment
		(start 333.73822 -45.656754)
		(end 316.11316 -63.281814)
		(width 0.127)
		(layer "In2.Cu")
		(net "VSENSE_PVCCMCP_CPU0_SKT_VSEN")
	)
	(segment
		(start 301.830486 -74.821288)
		(end 301.79772 -74.821288)
		(width 0.0889)
		(layer "In2.Cu")
		(net "VSENSE_PVCCMCP_CPU0_SKT_VSEN")
	)
	(segment
		(start 307.277516 -74.368914)
		(end 307.234336 -74.325734)
		(width 0.0889)
		(layer "In2.Cu")
		(net "VSENSE_PVCCMCP_CPU0_SKT_VSEN")
	)
	(segment
		(start 300.975776 -75.316334)
		(end 300.94301 -75.316334)
		(width 0.0889)
		(layer "In2.Cu")
		(net "VSENSE_PVCCMCP_CPU0_SKT_VSEN")
	)
	(segment
		(start 302.692816 -74.325734)
		(end 302.66005 -74.325734)
		(width 0.0889)
		(layer "In2.Cu")
		(net "VSENSE_PVCCMCP_CPU0_SKT_VSEN")
	)
	(segment
		(start 307.234336 -74.325734)
		(end 305.978306 -74.325734)
		(width 0.0889)
		(layer "In2.Cu")
		(net "VSENSE_PVCCMCP_CPU0_SKT_VSEN")
	)
	(segment
		(start 303.547526 -73.830688)
		(end 303.51476 -73.830688)
		(width 0.0889)
		(layer "In2.Cu")
		(net "VSENSE_PVCCMCP_CPU0_SKT_VSEN")
	)
	(segment
		(start 300.113446 -75.811888)
		(end 300.08068 -75.811888)
		(width 0.0889)
		(layer "In2.Cu")
		(net "VSENSE_PVCCMCP_CPU0_SKT_VSEN")
	)
	(segment
		(start 316.11316 -66.638932)
		(end 308.383178 -74.368914)
		(width 0.127)
		(layer "In2.Cu")
		(net "VSENSE_PVCCMCP_CPU0_SKT_VSEN")
	)
	(segment
		(start 305.413664 -73.830688)
		(end 305.229006 -73.830688)
		(width 0.0889)
		(layer "In2.Cu")
		(net "VSENSE_PVCCMCP_CPU0_SKT_VSEN")
	)
	(segment
		(start 299.258736 -76.306934)
		(end 299.215556 -76.306934)
		(width 0.0889)
		(layer "In2.Cu")
		(net "VSENSE_PVCCMCP_CPU0_SKT_VSEN")
	)
	(segment
		(start 295.010078 -76.799186)
		(end 294.9448 -76.864464)
		(width 0.0889)
		(layer "In2.Cu")
		(net "VSENSE_PVCCMCP_CPU0_SKT_VSEN")
	)
	(segment
		(start 316.11316 -63.281814)
		(end 316.11316 -66.638932)
		(width 0.127)
		(layer "In2.Cu")
		(net "VSENSE_PVCCMCP_CPU0_SKT_VSEN")
	)
	(segment
		(start 334.05572 -43.1673)
		(end 333.73822 -43.4848)
		(width 0.127)
		(layer "In2.Cu")
		(net "VSENSE_PVCCMCP_CPU0_SKT_VSEN")
	)
	(arc
		(start 299.215556 -76.306934)
		(mid 298.932339 -76.222653)
		(end 298.725336 -76.011786)
		(width 0.0889)
		(layer "In2.Cu")
		(net "VSENSE_PVCCMCP_CPU0_SKT_VSEN")
	)
	(arc
		(start 303.183036 -74.030586)
		(mid 302.976032 -74.24145)
		(end 302.692816 -74.325734)
		(width 0.0889)
		(layer "In2.Cu")
		(net "VSENSE_PVCCMCP_CPU0_SKT_VSEN")
	)
	(arc
		(start 301.465996 -75.021186)
		(mid 301.258992 -75.23205)
		(end 300.975776 -75.316334)
		(width 0.0889)
		(layer "In2.Cu")
		(net "VSENSE_PVCCMCP_CPU0_SKT_VSEN")
	)
	(arc
		(start 305.978306 -74.325734)
		(mid 305.775712 -74.209916)
		(end 305.629818 -74.027792)
		(width 0.0889)
		(layer "In2.Cu")
		(net "VSENSE_PVCCMCP_CPU0_SKT_VSEN")
	)
	(arc
		(start 295.45661 -76.507086)
		(mid 295.268187 -76.70639)
		(end 295.010078 -76.799186)
		(width 0.0889)
		(layer "In2.Cu")
		(net "VSENSE_PVCCMCP_CPU0_SKT_VSEN")
	)
	(arc
		(start 304.041556 -73.535286)
		(mid 303.832948 -73.747218)
		(end 303.547526 -73.830688)
		(width 0.0889)
		(layer "In2.Cu")
		(net "VSENSE_PVCCMCP_CPU0_SKT_VSEN")
	)
	(arc
		(start 296.64406 -76.802488)
		(mid 296.358636 -76.719021)
		(end 296.15003 -76.507086)
		(width 0.0889)
		(layer "In2.Cu")
		(net "VSENSE_PVCCMCP_CPU0_SKT_VSEN")
	)
	(arc
		(start 297.17365 -76.507086)
		(mid 296.965042 -76.719018)
		(end 296.67962 -76.802488)
		(width 0.0889)
		(layer "In2.Cu")
		(net "VSENSE_PVCCMCP_CPU0_SKT_VSEN")
	)
	(arc
		(start 300.08068 -75.811888)
		(mid 299.889038 -75.869054)
		(end 299.748956 -76.011786)
		(width 0.0889)
		(layer "In2.Cu")
		(net "VSENSE_PVCCMCP_CPU0_SKT_VSEN")
	)
	(arc
		(start 305.629818 -74.027792)
		(mid 305.538874 -73.910449)
		(end 305.413664 -73.830688)
		(width 0.0889)
		(layer "In2.Cu")
		(net "VSENSE_PVCCMCP_CPU0_SKT_VSEN")
	)
	(arc
		(start 303.51476 -73.830688)
		(mid 303.323118 -73.887854)
		(end 303.183036 -74.030586)
		(width 0.0889)
		(layer "In2.Cu")
		(net "VSENSE_PVCCMCP_CPU0_SKT_VSEN")
	)
	(arc
		(start 304.734976 -73.535286)
		(mid 304.388266 -73.334975)
		(end 304.041556 -73.535286)
		(width 0.0889)
		(layer "In2.Cu")
		(net "VSENSE_PVCCMCP_CPU0_SKT_VSEN")
	)
	(arc
		(start 300.94301 -75.316334)
		(mid 300.74916 -75.372684)
		(end 300.607476 -75.516486)
		(width 0.0889)
		(layer "In2.Cu")
		(net "VSENSE_PVCCMCP_CPU0_SKT_VSEN")
	)
	(arc
		(start 298.36364 -75.811888)
		(mid 298.171998 -75.869054)
		(end 298.031916 -76.011786)
		(width 0.0889)
		(layer "In2.Cu")
		(net "VSENSE_PVCCMCP_CPU0_SKT_VSEN")
	)
	(arc
		(start 296.15003 -76.507086)
		(mid 295.80332 -76.306775)
		(end 295.45661 -76.507086)
		(width 0.0889)
		(layer "In2.Cu")
		(net "VSENSE_PVCCMCP_CPU0_SKT_VSEN")
	)
	(arc
		(start 297.520106 -76.306934)
		(mid 297.322945 -76.358893)
		(end 297.176952 -76.501244)
		(width 0.0889)
		(layer "In2.Cu")
		(net "VSENSE_PVCCMCP_CPU0_SKT_VSEN")
	)
	(arc
		(start 301.79772 -74.821288)
		(mid 301.606078 -74.878454)
		(end 301.465996 -75.021186)
		(width 0.0889)
		(layer "In2.Cu")
		(net "VSENSE_PVCCMCP_CPU0_SKT_VSEN")
	)
	(arc
		(start 298.725336 -76.011786)
		(mid 298.585257 -75.86905)
		(end 298.393612 -75.811888)
		(width 0.0889)
		(layer "In2.Cu")
		(net "VSENSE_PVCCMCP_CPU0_SKT_VSEN")
	)
	(arc
		(start 305.229006 -73.830688)
		(mid 304.943582 -73.747221)
		(end 304.734976 -73.535286)
		(width 0.0889)
		(layer "In2.Cu")
		(net "VSENSE_PVCCMCP_CPU0_SKT_VSEN")
	)
	(arc
		(start 299.748956 -76.011786)
		(mid 299.541952 -76.22265)
		(end 299.258736 -76.306934)
		(width 0.0889)
		(layer "In2.Cu")
		(net "VSENSE_PVCCMCP_CPU0_SKT_VSEN")
	)
	(arc
		(start 298.031916 -76.011786)
		(mid 297.824912 -76.22265)
		(end 297.541696 -76.306934)
		(width 0.0889)
		(layer "In2.Cu")
		(net "VSENSE_PVCCMCP_CPU0_SKT_VSEN")
	)
	(arc
		(start 300.607476 -75.516486)
		(mid 300.398868 -75.728418)
		(end 300.113446 -75.811888)
		(width 0.0889)
		(layer "In2.Cu")
		(net "VSENSE_PVCCMCP_CPU0_SKT_VSEN")
	)
	(arc
		(start 302.66005 -74.325734)
		(mid 302.4662 -74.382084)
		(end 302.324516 -74.525886)
		(width 0.0889)
		(layer "In2.Cu")
		(net "VSENSE_PVCCMCP_CPU0_SKT_VSEN")
	)
	(arc
		(start 302.324516 -74.525886)
		(mid 302.115908 -74.737818)
		(end 301.830486 -74.821288)
		(width 0.0889)
		(layer "In2.Cu")
		(net "VSENSE_PVCCMCP_CPU0_SKT_VSEN")
	)
	(segment
		(start 333.404972 -42.53103)
		(end 333.4004 -42.545)
		(width 0.127)
		(layer "F.Cu")
		(net "VSENSE_PVCCMCP_CPU0_SKT_VRTN")
	)
	(segment
		(start 294.3733 -76.211938)
		(end 294.9448 -76.211938)
		(width 0.127)
		(layer "F.Cu")
		(net "VSENSE_PVCCMCP_CPU0_SKT_VRTN")
	)
	(segment
		(start 334.04302 -41.90238)
		(end 334.04302 -41.87698)
		(width 0.127)
		(layer "F.Cu")
		(net "VSENSE_PVCCMCP_CPU0_SKT_VRTN")
	)
	(segment
		(start 333.4004 -42.545)
		(end 334.04302 -41.90238)
		(width 0.127)
		(layer "F.Cu")
		(net "VSENSE_PVCCMCP_CPU0_SKT_VRTN")
	)
	(via
		(at 334.04302 -41.87698)
		(size 0.508)
		(drill 0.254)
		(layers "F.Cu" "B.Cu")
		(net "VSENSE_PVCCMCP_CPU0_SKT_VRTN")
	)
	(via
		(at 294.9448 -76.211938)
		(size 0.508)
		(drill 0.254)
		(layers "F.Cu" "B.Cu")
		(net "VSENSE_PVCCMCP_CPU0_SKT_VRTN")
	)
	(segment
		(start 298.400216 -75.621388)
		(end 298.357036 -75.621388)
		(width 0.0889)
		(layer "In2.Cu")
		(net "VSENSE_PVCCMCP_CPU0_SKT_VRTN")
	)
	(segment
		(start 333.48422 -42.43578)
		(end 333.48422 -45.551344)
		(width 0.127)
		(layer "In2.Cu")
		(net "VSENSE_PVCCMCP_CPU0_SKT_VRTN")
	)
	(segment
		(start 295.8211 -76.116434)
		(end 295.78554 -76.116434)
		(width 0.0889)
		(layer "In2.Cu")
		(net "VSENSE_PVCCMCP_CPU0_SKT_VRTN")
	)
	(segment
		(start 294.9448 -76.550012)
		(end 294.9448 -76.211938)
		(width 0.0889)
		(layer "In2.Cu")
		(net "VSENSE_PVCCMCP_CPU0_SKT_VRTN")
	)
	(segment
		(start 305.449986 -73.640188)
		(end 305.23561 -73.640188)
		(width 0.0889)
		(layer "In2.Cu")
		(net "VSENSE_PVCCMCP_CPU0_SKT_VRTN")
	)
	(segment
		(start 297.008296 -76.411836)
		(end 297.004994 -76.417678)
		(width 0.0889)
		(layer "In2.Cu")
		(net "VSENSE_PVCCMCP_CPU0_SKT_VRTN")
	)
	(segment
		(start 300.106842 -75.621388)
		(end 300.074076 -75.621388)
		(width 0.0889)
		(layer "In2.Cu")
		(net "VSENSE_PVCCMCP_CPU0_SKT_VRTN")
	)
	(segment
		(start 315.85916 -63.176404)
		(end 315.85916 -66.533522)
		(width 0.127)
		(layer "In2.Cu")
		(net "VSENSE_PVCCMCP_CPU0_SKT_VRTN")
	)
	(segment
		(start 295.002712 -76.607924)
		(end 294.9448 -76.550012)
		(width 0.0889)
		(layer "In2.Cu")
		(net "VSENSE_PVCCMCP_CPU0_SKT_VRTN")
	)
	(segment
		(start 304.406046 -73.144634)
		(end 304.370486 -73.144634)
		(width 0.0889)
		(layer "In2.Cu")
		(net "VSENSE_PVCCMCP_CPU0_SKT_VRTN")
	)
	(segment
		(start 301.823882 -74.630788)
		(end 301.791116 -74.630788)
		(width 0.0889)
		(layer "In2.Cu")
		(net "VSENSE_PVCCMCP_CPU0_SKT_VRTN")
	)
	(segment
		(start 300.969172 -75.125834)
		(end 300.936406 -75.125834)
		(width 0.0889)
		(layer "In2.Cu")
		(net "VSENSE_PVCCMCP_CPU0_SKT_VRTN")
	)
	(segment
		(start 334.04302 -41.87698)
		(end 333.48422 -42.43578)
		(width 0.127)
		(layer "In2.Cu")
		(net "VSENSE_PVCCMCP_CPU0_SKT_VRTN")
	)
	(segment
		(start 297.535092 -76.116434)
		(end 297.502326 -76.116434)
		(width 0.0889)
		(layer "In2.Cu")
		(net "VSENSE_PVCCMCP_CPU0_SKT_VRTN")
	)
	(segment
		(start 303.540922 -73.640188)
		(end 303.508156 -73.640188)
		(width 0.0889)
		(layer "In2.Cu")
		(net "VSENSE_PVCCMCP_CPU0_SKT_VRTN")
	)
	(segment
		(start 307.277516 -74.114914)
		(end 307.257196 -74.135234)
		(width 0.0889)
		(layer "In2.Cu")
		(net "VSENSE_PVCCMCP_CPU0_SKT_VRTN")
	)
	(segment
		(start 333.48422 -45.551344)
		(end 315.85916 -63.176404)
		(width 0.127)
		(layer "In2.Cu")
		(net "VSENSE_PVCCMCP_CPU0_SKT_VRTN")
	)
	(segment
		(start 302.686212 -74.135234)
		(end 302.653446 -74.135234)
		(width 0.0889)
		(layer "In2.Cu")
		(net "VSENSE_PVCCMCP_CPU0_SKT_VRTN")
	)
	(segment
		(start 299.252132 -76.116434)
		(end 299.22216 -76.116434)
		(width 0.0889)
		(layer "In2.Cu")
		(net "VSENSE_PVCCMCP_CPU0_SKT_VRTN")
	)
	(segment
		(start 315.85916 -66.533522)
		(end 308.277768 -74.114914)
		(width 0.127)
		(layer "In2.Cu")
		(net "VSENSE_PVCCMCP_CPU0_SKT_VRTN")
	)
	(segment
		(start 307.257196 -74.135234)
		(end 306.014628 -74.135234)
		(width 0.0889)
		(layer "In2.Cu")
		(net "VSENSE_PVCCMCP_CPU0_SKT_VRTN")
	)
	(segment
		(start 308.277768 -74.114914)
		(end 307.277516 -74.114914)
		(width 0.127)
		(layer "In2.Cu")
		(net "VSENSE_PVCCMCP_CPU0_SKT_VRTN")
	)
	(arc
		(start 303.017936 -73.935336)
		(mid 302.877857 -74.078072)
		(end 302.686212 -74.135234)
		(width 0.0889)
		(layer "In2.Cu")
		(net "VSENSE_PVCCMCP_CPU0_SKT_VRTN")
	)
	(arc
		(start 301.791116 -74.630788)
		(mid 301.507899 -74.715069)
		(end 301.300896 -74.925936)
		(width 0.0889)
		(layer "In2.Cu")
		(net "VSENSE_PVCCMCP_CPU0_SKT_VRTN")
	)
	(arc
		(start 296.31513 -76.411836)
		(mid 296.106522 -76.199904)
		(end 295.8211 -76.116434)
		(width 0.0889)
		(layer "In2.Cu")
		(net "VSENSE_PVCCMCP_CPU0_SKT_VRTN")
	)
	(arc
		(start 305.798474 -73.93813)
		(mid 305.652549 -73.756043)
		(end 305.449986 -73.640188)
		(width 0.0889)
		(layer "In2.Cu")
		(net "VSENSE_PVCCMCP_CPU0_SKT_VRTN")
	)
	(arc
		(start 299.22216 -76.116434)
		(mid 299.030518 -76.059268)
		(end 298.890436 -75.916536)
		(width 0.0889)
		(layer "In2.Cu")
		(net "VSENSE_PVCCMCP_CPU0_SKT_VRTN")
	)
	(arc
		(start 298.357036 -75.621388)
		(mid 298.073819 -75.705669)
		(end 297.866816 -75.916536)
		(width 0.0889)
		(layer "In2.Cu")
		(net "VSENSE_PVCCMCP_CPU0_SKT_VRTN")
	)
	(arc
		(start 301.300896 -74.925936)
		(mid 301.160817 -75.068672)
		(end 300.969172 -75.125834)
		(width 0.0889)
		(layer "In2.Cu")
		(net "VSENSE_PVCCMCP_CPU0_SKT_VRTN")
	)
	(arc
		(start 304.900076 -73.440036)
		(mid 304.691468 -73.228104)
		(end 304.406046 -73.144634)
		(width 0.0889)
		(layer "In2.Cu")
		(net "VSENSE_PVCCMCP_CPU0_SKT_VRTN")
	)
	(arc
		(start 303.876456 -73.440036)
		(mid 303.734773 -73.58384)
		(end 303.540922 -73.640188)
		(width 0.0889)
		(layer "In2.Cu")
		(net "VSENSE_PVCCMCP_CPU0_SKT_VRTN")
	)
	(arc
		(start 302.653446 -74.135234)
		(mid 302.368022 -74.218701)
		(end 302.159416 -74.430636)
		(width 0.0889)
		(layer "In2.Cu")
		(net "VSENSE_PVCCMCP_CPU0_SKT_VRTN")
	)
	(arc
		(start 295.78554 -76.116434)
		(mid 295.500116 -76.199901)
		(end 295.29151 -76.411836)
		(width 0.0889)
		(layer "In2.Cu")
		(net "VSENSE_PVCCMCP_CPU0_SKT_VRTN")
	)
	(arc
		(start 300.074076 -75.621388)
		(mid 299.790859 -75.705669)
		(end 299.583856 -75.916536)
		(width 0.0889)
		(layer "In2.Cu")
		(net "VSENSE_PVCCMCP_CPU0_SKT_VRTN")
	)
	(arc
		(start 300.936406 -75.125834)
		(mid 300.650982 -75.209301)
		(end 300.442376 -75.421236)
		(width 0.0889)
		(layer "In2.Cu")
		(net "VSENSE_PVCCMCP_CPU0_SKT_VRTN")
	)
	(arc
		(start 298.890436 -75.916536)
		(mid 298.683432 -75.705672)
		(end 298.400216 -75.621388)
		(width 0.0889)
		(layer "In2.Cu")
		(net "VSENSE_PVCCMCP_CPU0_SKT_VRTN")
	)
	(arc
		(start 300.442376 -75.421236)
		(mid 300.300693 -75.56504)
		(end 300.106842 -75.621388)
		(width 0.0889)
		(layer "In2.Cu")
		(net "VSENSE_PVCCMCP_CPU0_SKT_VRTN")
	)
	(arc
		(start 295.29151 -76.411836)
		(mid 295.169619 -76.543032)
		(end 295.002712 -76.607924)
		(width 0.0889)
		(layer "In2.Cu")
		(net "VSENSE_PVCCMCP_CPU0_SKT_VRTN")
	)
	(arc
		(start 297.866816 -75.916536)
		(mid 297.726737 -76.059272)
		(end 297.535092 -76.116434)
		(width 0.0889)
		(layer "In2.Cu")
		(net "VSENSE_PVCCMCP_CPU0_SKT_VRTN")
	)
	(arc
		(start 306.014628 -74.135234)
		(mid 305.889427 -74.055463)
		(end 305.798474 -73.93813)
		(width 0.0889)
		(layer "In2.Cu")
		(net "VSENSE_PVCCMCP_CPU0_SKT_VRTN")
	)
	(arc
		(start 302.159416 -74.430636)
		(mid 302.017733 -74.57444)
		(end 301.823882 -74.630788)
		(width 0.0889)
		(layer "In2.Cu")
		(net "VSENSE_PVCCMCP_CPU0_SKT_VRTN")
	)
	(arc
		(start 299.583856 -75.916536)
		(mid 299.443777 -76.059272)
		(end 299.252132 -76.116434)
		(width 0.0889)
		(layer "In2.Cu")
		(net "VSENSE_PVCCMCP_CPU0_SKT_VRTN")
	)
	(arc
		(start 297.502326 -76.116434)
		(mid 297.216902 -76.199901)
		(end 297.008296 -76.411836)
		(width 0.0889)
		(layer "In2.Cu")
		(net "VSENSE_PVCCMCP_CPU0_SKT_VRTN")
	)
	(arc
		(start 297.004994 -76.417678)
		(mid 296.658421 -76.612028)
		(end 296.31513 -76.411836)
		(width 0.0889)
		(layer "In2.Cu")
		(net "VSENSE_PVCCMCP_CPU0_SKT_VRTN")
	)
	(arc
		(start 305.23561 -73.640188)
		(mid 305.04176 -73.583838)
		(end 304.900076 -73.440036)
		(width 0.0889)
		(layer "In2.Cu")
		(net "VSENSE_PVCCMCP_CPU0_SKT_VRTN")
	)
	(arc
		(start 303.508156 -73.640188)
		(mid 303.224939 -73.724469)
		(end 303.017936 -73.935336)
		(width 0.0889)
		(layer "In2.Cu")
		(net "VSENSE_PVCCMCP_CPU0_SKT_VRTN")
	)
	(arc
		(start 304.370486 -73.144634)
		(mid 304.085062 -73.228101)
		(end 303.876456 -73.440036)
		(width 0.0889)
		(layer "In2.Cu")
		(net "VSENSE_PVCCMCP_CPU0_SKT_VRTN")
	)
	(segment
		(start -3.429 -124.333)
		(end -3.429 -123.5456)
		(width 0.127)
		(layer "F.Cu")
		(net "VSENSE_PVDDQ_KLM_P")
	)
	(via
		(at -3.429 -123.5456)
		(size 0.508)
		(drill 0.254)
		(layers "F.Cu" "B.Cu")
		(net "VSENSE_PVDDQ_KLM_P")
	)
	(via
		(at 21.90242 -157.5435)
		(size 0.508)
		(drill 0.254)
		(layers "F.Cu" "B.Cu")
		(net "VSENSE_PVDDQ_KLM_P")
	)
	(via
		(at 93.37421 -124.74448)
		(size 0.1016)
		(drill 0.0508)
		(layers "F.Cu" "B.Cu")
		(net "VSENSE_PVDDQ_KLM_P")
	)
	(segment
		(start 98.98634 -125.661166)
		(end 98.069654 -124.74448)
		(width 0.127)
		(layer "B.Cu")
		(net "VSENSE_PVDDQ_KLM_P")
	)
	(segment
		(start 22.253702 -157.894782)
		(end 22.253702 -157.901894)
		(width 0.127)
		(layer "B.Cu")
		(net "VSENSE_PVDDQ_KLM_P")
	)
	(segment
		(start 21.90242 -157.5435)
		(end 22.253702 -157.894782)
		(width 0.127)
		(layer "B.Cu")
		(net "VSENSE_PVDDQ_KLM_P")
	)
	(segment
		(start 86.754208 -125.026166)
		(end 87.035894 -124.74448)
		(width 0.127)
		(layer "B.Cu")
		(net "VSENSE_PVDDQ_KLM_P")
	)
	(segment
		(start 86.754208 -125.498352)
		(end 86.754208 -125.026166)
		(width 0.127)
		(layer "B.Cu")
		(net "VSENSE_PVDDQ_KLM_P")
	)
	(segment
		(start 22.253702 -157.901894)
		(end 22.903688 -158.55188)
		(width 0.127)
		(layer "B.Cu")
		(net "VSENSE_PVDDQ_KLM_P")
	)
	(segment
		(start 86.436708 -125.99162)
		(end 85.547708 -125.99162)
		(width 0.127)
		(layer "B.Cu")
		(net "VSENSE_PVDDQ_KLM_P")
	)
	(segment
		(start 97.50552 -158.01848)
		(end 97.50552 -129.48285)
		(width 0.127)
		(layer "B.Cu")
		(net "VSENSE_PVDDQ_KLM_P")
	)
	(segment
		(start 96.97212 -158.55188)
		(end 97.50552 -158.01848)
		(width 0.127)
		(layer "B.Cu")
		(net "VSENSE_PVDDQ_KLM_P")
	)
	(segment
		(start 86.436708 -125.815852)
		(end 86.754208 -125.498352)
		(width 0.127)
		(layer "B.Cu")
		(net "VSENSE_PVDDQ_KLM_P")
	)
	(segment
		(start 98.98634 -128.00203)
		(end 98.98634 -125.661166)
		(width 0.127)
		(layer "B.Cu")
		(net "VSENSE_PVDDQ_KLM_P")
	)
	(segment
		(start 86.436708 -125.99162)
		(end 86.436708 -125.815852)
		(width 0.127)
		(layer "B.Cu")
		(net "VSENSE_PVDDQ_KLM_P")
	)
	(segment
		(start 22.903688 -158.55188)
		(end 96.97212 -158.55188)
		(width 0.127)
		(layer "B.Cu")
		(net "VSENSE_PVDDQ_KLM_P")
	)
	(segment
		(start 97.50552 -129.48285)
		(end 98.98634 -128.00203)
		(width 0.127)
		(layer "B.Cu")
		(net "VSENSE_PVDDQ_KLM_P")
	)
	(segment
		(start 87.035894 -124.74448)
		(end 93.37421 -124.74448)
		(width 0.127)
		(layer "B.Cu")
		(net "VSENSE_PVDDQ_KLM_P")
	)
	(segment
		(start 98.069654 -124.74448)
		(end 93.37421 -124.74448)
		(width 0.127)
		(layer "B.Cu")
		(net "VSENSE_PVDDQ_KLM_P")
	)
	(segment
		(start -2.481326 -125.36932)
		(end -1.198118 -125.36932)
		(width 0.127)
		(layer "In4.Cu")
		(net "VSENSE_PVDDQ_KLM_P")
	)
	(segment
		(start 7.220204 -122.05462)
		(end 13.998956 -122.05462)
		(width 0.127)
		(layer "In4.Cu")
		(net "VSENSE_PVDDQ_KLM_P")
	)
	(segment
		(start 17.537938 -125.593602)
		(end 17.537938 -129.316988)
		(width 0.127)
		(layer "In4.Cu")
		(net "VSENSE_PVDDQ_KLM_P")
	)
	(segment
		(start 21.3106 -156.44114)
		(end 21.90242 -157.03296)
		(width 0.127)
		(layer "In4.Cu")
		(net "VSENSE_PVDDQ_KLM_P")
	)
	(segment
		(start 5.780024 -123.4948)
		(end 7.220204 -122.05462)
		(width 0.127)
		(layer "In4.Cu")
		(net "VSENSE_PVDDQ_KLM_P")
	)
	(segment
		(start 0.676402 -123.4948)
		(end 5.780024 -123.4948)
		(width 0.127)
		(layer "In4.Cu")
		(net "VSENSE_PVDDQ_KLM_P")
	)
	(segment
		(start 18.89506 -130.67411)
		(end 18.89506 -133.26872)
		(width 0.127)
		(layer "In4.Cu")
		(net "VSENSE_PVDDQ_KLM_P")
	)
	(segment
		(start 18.89506 -133.26872)
		(end 21.3106 -135.68426)
		(width 0.127)
		(layer "In4.Cu")
		(net "VSENSE_PVDDQ_KLM_P")
	)
	(segment
		(start 21.3106 -135.68426)
		(end 21.3106 -156.44114)
		(width 0.127)
		(layer "In4.Cu")
		(net "VSENSE_PVDDQ_KLM_P")
	)
	(segment
		(start -1.198118 -125.36932)
		(end 0.676402 -123.4948)
		(width 0.127)
		(layer "In4.Cu")
		(net "VSENSE_PVDDQ_KLM_P")
	)
	(segment
		(start 17.537938 -129.316988)
		(end 18.89506 -130.67411)
		(width 0.127)
		(layer "In4.Cu")
		(net "VSENSE_PVDDQ_KLM_P")
	)
	(segment
		(start 21.90242 -157.03296)
		(end 21.90242 -157.5435)
		(width 0.127)
		(layer "In4.Cu")
		(net "VSENSE_PVDDQ_KLM_P")
	)
	(segment
		(start -3.429 -123.5456)
		(end -3.0988 -123.8758)
		(width 0.127)
		(layer "In4.Cu")
		(net "VSENSE_PVDDQ_KLM_P")
	)
	(segment
		(start 13.998956 -122.05462)
		(end 17.537938 -125.593602)
		(width 0.127)
		(layer "In4.Cu")
		(net "VSENSE_PVDDQ_KLM_P")
	)
	(segment
		(start -3.0988 -123.8758)
		(end -3.0988 -124.751846)
		(width 0.127)
		(layer "In4.Cu")
		(net "VSENSE_PVDDQ_KLM_P")
	)
	(segment
		(start -3.0988 -124.751846)
		(end -2.481326 -125.36932)
		(width 0.127)
		(layer "In4.Cu")
		(net "VSENSE_PVDDQ_KLM_P")
	)
	(segment
		(start -1.6129 -124.5235)
		(end -0.3937 -125.7427)
		(width 0.127)
		(layer "F.Cu")
		(net "VSENSE_PVDDQ_KLM_N")
	)
	(segment
		(start -0.3937 -125.7427)
		(end -0.3937 -126.165102)
		(width 0.127)
		(layer "F.Cu")
		(net "VSENSE_PVDDQ_KLM_N")
	)
	(segment
		(start -2.5146 -123.5456)
		(end -2.5146 -124.333)
		(width 0.127)
		(layer "F.Cu")
		(net "VSENSE_PVDDQ_KLM_N")
	)
	(segment
		(start -2.5146 -124.333)
		(end -2.5146 -124.3965)
		(width 0.127)
		(layer "F.Cu")
		(net "VSENSE_PVDDQ_KLM_N")
	)
	(segment
		(start -2.5146 -124.3965)
		(end -2.3876 -124.5235)
		(width 0.127)
		(layer "F.Cu")
		(net "VSENSE_PVDDQ_KLM_N")
	)
	(segment
		(start -2.3876 -124.5235)
		(end -1.6129 -124.5235)
		(width 0.127)
		(layer "F.Cu")
		(net "VSENSE_PVDDQ_KLM_N")
	)
	(via
		(at -2.5146 -123.5456)
		(size 0.508)
		(drill 0.254)
		(layers "F.Cu" "B.Cu")
		(net "VSENSE_PVDDQ_KLM_N")
	)
	(via
		(at 22.69744 -157.55874)
		(size 0.508)
		(drill 0.254)
		(layers "F.Cu" "B.Cu")
		(net "VSENSE_PVDDQ_KLM_N")
	)
	(via
		(at 88.073992 -124.99848)
		(size 0.1016)
		(drill 0.0508)
		(layers "F.Cu" "B.Cu")
		(net "VSENSE_PVDDQ_KLM_N")
	)
	(segment
		(start 87.325708 -125.99162)
		(end 87.325708 -125.832108)
		(width 0.127)
		(layer "B.Cu")
		(net "VSENSE_PVDDQ_KLM_N")
	)
	(segment
		(start 87.046816 -125.553216)
		(end 87.046816 -125.12548)
		(width 0.127)
		(layer "B.Cu")
		(net "VSENSE_PVDDQ_KLM_N")
	)
	(segment
		(start 87.325708 -125.99162)
		(end 88.214708 -125.99162)
		(width 0.127)
		(layer "B.Cu")
		(net "VSENSE_PVDDQ_KLM_N")
	)
	(segment
		(start 23.009098 -158.29788)
		(end 96.86671 -158.29788)
		(width 0.127)
		(layer "B.Cu")
		(net "VSENSE_PVDDQ_KLM_N")
	)
	(segment
		(start 98.73234 -125.766576)
		(end 97.964244 -124.99848)
		(width 0.127)
		(layer "B.Cu")
		(net "VSENSE_PVDDQ_KLM_N")
	)
	(segment
		(start 97.25152 -129.37744)
		(end 98.73234 -127.89662)
		(width 0.127)
		(layer "B.Cu")
		(net "VSENSE_PVDDQ_KLM_N")
	)
	(segment
		(start 97.964244 -124.99848)
		(end 88.073992 -124.99848)
		(width 0.127)
		(layer "B.Cu")
		(net "VSENSE_PVDDQ_KLM_N")
	)
	(segment
		(start 87.173816 -124.99848)
		(end 88.073992 -124.99848)
		(width 0.127)
		(layer "B.Cu")
		(net "VSENSE_PVDDQ_KLM_N")
	)
	(segment
		(start 96.86671 -158.29788)
		(end 97.25152 -157.91307)
		(width 0.127)
		(layer "B.Cu")
		(net "VSENSE_PVDDQ_KLM_N")
	)
	(segment
		(start 87.046816 -125.12548)
		(end 87.173816 -124.99848)
		(width 0.127)
		(layer "B.Cu")
		(net "VSENSE_PVDDQ_KLM_N")
	)
	(segment
		(start 97.25152 -157.91307)
		(end 97.25152 -129.37744)
		(width 0.127)
		(layer "B.Cu")
		(net "VSENSE_PVDDQ_KLM_N")
	)
	(segment
		(start 22.69744 -157.986222)
		(end 23.009098 -158.29788)
		(width 0.127)
		(layer "B.Cu")
		(net "VSENSE_PVDDQ_KLM_N")
	)
	(segment
		(start 87.325708 -125.832108)
		(end 87.046816 -125.553216)
		(width 0.127)
		(layer "B.Cu")
		(net "VSENSE_PVDDQ_KLM_N")
	)
	(segment
		(start 22.69744 -157.55874)
		(end 22.69744 -157.986222)
		(width 0.127)
		(layer "B.Cu")
		(net "VSENSE_PVDDQ_KLM_N")
	)
	(segment
		(start 98.73234 -127.89662)
		(end 98.73234 -125.766576)
		(width 0.127)
		(layer "B.Cu")
		(net "VSENSE_PVDDQ_KLM_N")
	)
	(segment
		(start -2.8448 -124.646436)
		(end -2.375916 -125.11532)
		(width 0.127)
		(layer "In4.Cu")
		(net "VSENSE_PVDDQ_KLM_N")
	)
	(segment
		(start -2.375916 -125.11532)
		(end -1.303528 -125.11532)
		(width 0.127)
		(layer "In4.Cu")
		(net "VSENSE_PVDDQ_KLM_N")
	)
	(segment
		(start 14.104366 -121.80062)
		(end 17.791938 -125.488192)
		(width 0.127)
		(layer "In4.Cu")
		(net "VSENSE_PVDDQ_KLM_N")
	)
	(segment
		(start -1.303528 -125.11532)
		(end 0.570992 -123.2408)
		(width 0.127)
		(layer "In4.Cu")
		(net "VSENSE_PVDDQ_KLM_N")
	)
	(segment
		(start 7.114794 -121.80062)
		(end 14.104366 -121.80062)
		(width 0.127)
		(layer "In4.Cu")
		(net "VSENSE_PVDDQ_KLM_N")
	)
	(segment
		(start 21.5646 -156.33573)
		(end 22.69744 -157.46857)
		(width 0.127)
		(layer "In4.Cu")
		(net "VSENSE_PVDDQ_KLM_N")
	)
	(segment
		(start 0.570992 -123.2408)
		(end 5.674614 -123.2408)
		(width 0.127)
		(layer "In4.Cu")
		(net "VSENSE_PVDDQ_KLM_N")
	)
	(segment
		(start 21.5646 -135.57885)
		(end 21.5646 -156.33573)
		(width 0.127)
		(layer "In4.Cu")
		(net "VSENSE_PVDDQ_KLM_N")
	)
	(segment
		(start 19.14906 -133.16331)
		(end 21.5646 -135.57885)
		(width 0.127)
		(layer "In4.Cu")
		(net "VSENSE_PVDDQ_KLM_N")
	)
	(segment
		(start 19.14906 -130.5687)
		(end 19.14906 -133.16331)
		(width 0.127)
		(layer "In4.Cu")
		(net "VSENSE_PVDDQ_KLM_N")
	)
	(segment
		(start 17.791938 -125.488192)
		(end 17.791938 -129.211578)
		(width 0.127)
		(layer "In4.Cu")
		(net "VSENSE_PVDDQ_KLM_N")
	)
	(segment
		(start 5.674614 -123.2408)
		(end 7.114794 -121.80062)
		(width 0.127)
		(layer "In4.Cu")
		(net "VSENSE_PVDDQ_KLM_N")
	)
	(segment
		(start 22.69744 -157.46857)
		(end 22.69744 -157.55874)
		(width 0.127)
		(layer "In4.Cu")
		(net "VSENSE_PVDDQ_KLM_N")
	)
	(segment
		(start 17.791938 -129.211578)
		(end 19.14906 -130.5687)
		(width 0.127)
		(layer "In4.Cu")
		(net "VSENSE_PVDDQ_KLM_N")
	)
	(segment
		(start -2.8448 -123.8758)
		(end -2.8448 -124.646436)
		(width 0.127)
		(layer "In4.Cu")
		(net "VSENSE_PVDDQ_KLM_N")
	)
	(segment
		(start -2.5146 -123.5456)
		(end -2.8448 -123.8758)
		(width 0.127)
		(layer "In4.Cu")
		(net "VSENSE_PVDDQ_KLM_N")
	)
	(segment
		(start 6.5913 -4.757674)
		(end 6.800088 -4.548886)
		(width 0.127)
		(layer "F.Cu")
		(net "VSENSE_PVDDQ_GHJ_P")
	)
	(segment
		(start 6.800088 -4.548886)
		(end 7.137146 -4.548886)
		(width 0.127)
		(layer "F.Cu")
		(net "VSENSE_PVDDQ_GHJ_P")
	)
	(segment
		(start 6.026912 -4.757674)
		(end 6.5913 -4.757674)
		(width 0.127)
		(layer "F.Cu")
		(net "VSENSE_PVDDQ_GHJ_P")
	)
	(via
		(at 6.026912 -4.757674)
		(size 0.508)
		(drill 0.254)
		(layers "F.Cu" "B.Cu")
		(net "VSENSE_PVDDQ_GHJ_P")
	)
	(via
		(at 18.077688 4.695444)
		(size 0.508)
		(drill 0.254)
		(layers "F.Cu" "B.Cu")
		(net "VSENSE_PVDDQ_GHJ_P")
	)
	(segment
		(start 97.50044 -21.36267)
		(end 97.50044 -23.84679)
		(width 0.127)
		(layer "B.Cu")
		(net "VSENSE_PVDDQ_GHJ_P")
	)
	(segment
		(start 97.50552 -11.8237)
		(end 97.50552 -14.3637)
		(width 0.127)
		(layer "B.Cu")
		(net "VSENSE_PVDDQ_GHJ_P")
	)
	(segment
		(start 97.76968 -16.3195)
		(end 97.50552 -16.58366)
		(width 0.127)
		(layer "B.Cu")
		(net "VSENSE_PVDDQ_GHJ_P")
	)
	(segment
		(start 97.22358 -20.20824)
		(end 97.22358 -21.08581)
		(width 0.127)
		(layer "B.Cu")
		(net "VSENSE_PVDDQ_GHJ_P")
	)
	(segment
		(start 18.077688 4.695444)
		(end 18.089118 4.695444)
		(width 0.127)
		(layer "B.Cu")
		(net "VSENSE_PVDDQ_GHJ_P")
	)
	(segment
		(start 99.53752 -27.99207)
		(end 102.52583 -30.98038)
		(width 0.127)
		(layer "B.Cu")
		(net "VSENSE_PVDDQ_GHJ_P")
	)
	(segment
		(start 99.53752 -25.11933)
		(end 99.53752 -27.99207)
		(width 0.127)
		(layer "B.Cu")
		(net "VSENSE_PVDDQ_GHJ_P")
	)
	(segment
		(start 84.69122 5.11556)
		(end 96.14408 5.11556)
		(width 0.127)
		(layer "B.Cu")
		(net "VSENSE_PVDDQ_GHJ_P")
	)
	(segment
		(start 97.50552 -19.9263)
		(end 97.22358 -20.20824)
		(width 0.127)
		(layer "B.Cu")
		(net "VSENSE_PVDDQ_GHJ_P")
	)
	(segment
		(start 97.22358 -21.08581)
		(end 97.50044 -21.36267)
		(width 0.127)
		(layer "B.Cu")
		(net "VSENSE_PVDDQ_GHJ_P")
	)
	(segment
		(start 112.1664 -30.98038)
		(end 112.300512 -30.846268)
		(width 0.127)
		(layer "B.Cu")
		(net "VSENSE_PVDDQ_GHJ_P")
	)
	(segment
		(start 97.49536 3.76428)
		(end 97.49536 -9.20496)
		(width 0.127)
		(layer "B.Cu")
		(net "VSENSE_PVDDQ_GHJ_P")
	)
	(segment
		(start 111.983012 -29.94152)
		(end 111.094012 -29.94152)
		(width 0.127)
		(layer "B.Cu")
		(net "VSENSE_PVDDQ_GHJ_P")
	)
	(segment
		(start 84.341462 5.465318)
		(end 84.69122 5.11556)
		(width 0.127)
		(layer "B.Cu")
		(net "VSENSE_PVDDQ_GHJ_P")
	)
	(segment
		(start 97.49536 -9.20496)
		(end 97.90176 -9.61136)
		(width 0.127)
		(layer "B.Cu")
		(net "VSENSE_PVDDQ_GHJ_P")
	)
	(segment
		(start 97.96907 -24.31542)
		(end 98.73361 -24.31542)
		(width 0.127)
		(layer "B.Cu")
		(net "VSENSE_PVDDQ_GHJ_P")
	)
	(segment
		(start 112.300512 -30.846268)
		(end 112.300512 -30.666436)
		(width 0.127)
		(layer "B.Cu")
		(net "VSENSE_PVDDQ_GHJ_P")
	)
	(segment
		(start 97.50044 -23.84679)
		(end 97.96907 -24.31542)
		(width 0.127)
		(layer "B.Cu")
		(net "VSENSE_PVDDQ_GHJ_P")
	)
	(segment
		(start 18.089118 4.695444)
		(end 18.459196 5.065522)
		(width 0.127)
		(layer "B.Cu")
		(net "VSENSE_PVDDQ_GHJ_P")
	)
	(segment
		(start 18.459196 5.065522)
		(end 18.459196 5.216144)
		(width 0.127)
		(layer "B.Cu")
		(net "VSENSE_PVDDQ_GHJ_P")
	)
	(segment
		(start 97.90176 -11.42746)
		(end 97.50552 -11.8237)
		(width 0.127)
		(layer "B.Cu")
		(net "VSENSE_PVDDQ_GHJ_P")
	)
	(segment
		(start 102.52583 -30.98038)
		(end 112.1664 -30.98038)
		(width 0.127)
		(layer "B.Cu")
		(net "VSENSE_PVDDQ_GHJ_P")
	)
	(segment
		(start 18.70837 5.465318)
		(end 84.341462 5.465318)
		(width 0.127)
		(layer "B.Cu")
		(net "VSENSE_PVDDQ_GHJ_P")
	)
	(segment
		(start 18.459196 5.216144)
		(end 18.70837 5.465318)
		(width 0.127)
		(layer "B.Cu")
		(net "VSENSE_PVDDQ_GHJ_P")
	)
	(segment
		(start 97.50552 -14.3637)
		(end 97.76968 -14.62786)
		(width 0.127)
		(layer "B.Cu")
		(net "VSENSE_PVDDQ_GHJ_P")
	)
	(segment
		(start 98.73361 -24.31542)
		(end 99.53752 -25.11933)
		(width 0.127)
		(layer "B.Cu")
		(net "VSENSE_PVDDQ_GHJ_P")
	)
	(segment
		(start 97.50552 -16.58366)
		(end 97.50552 -19.9263)
		(width 0.127)
		(layer "B.Cu")
		(net "VSENSE_PVDDQ_GHJ_P")
	)
	(segment
		(start 97.90176 -9.61136)
		(end 97.90176 -11.42746)
		(width 0.127)
		(layer "B.Cu")
		(net "VSENSE_PVDDQ_GHJ_P")
	)
	(segment
		(start 112.300512 -30.666436)
		(end 111.983012 -30.348936)
		(width 0.127)
		(layer "B.Cu")
		(net "VSENSE_PVDDQ_GHJ_P")
	)
	(segment
		(start 111.983012 -30.348936)
		(end 111.983012 -29.94152)
		(width 0.127)
		(layer "B.Cu")
		(net "VSENSE_PVDDQ_GHJ_P")
	)
	(segment
		(start 97.76968 -14.62786)
		(end 97.76968 -16.3195)
		(width 0.127)
		(layer "B.Cu")
		(net "VSENSE_PVDDQ_GHJ_P")
	)
	(segment
		(start 96.14408 5.11556)
		(end 97.49536 3.76428)
		(width 0.127)
		(layer "B.Cu")
		(net "VSENSE_PVDDQ_GHJ_P")
	)
	(segment
		(start 5.187442 -3.83667)
		(end 6.026912 -4.67614)
		(width 0.127)
		(layer "In2.Cu")
		(net "VSENSE_PVDDQ_GHJ_P")
	)
	(segment
		(start 6.026912 -4.67614)
		(end 6.026912 -4.757674)
		(width 0.127)
		(layer "In2.Cu")
		(net "VSENSE_PVDDQ_GHJ_P")
	)
	(segment
		(start 5.187442 -2.548636)
		(end 5.187442 -3.83667)
		(width 0.127)
		(layer "In2.Cu")
		(net "VSENSE_PVDDQ_GHJ_P")
	)
	(segment
		(start 17.715992 4.333748)
		(end 16.123666 4.333748)
		(width 0.127)
		(layer "In2.Cu")
		(net "VSENSE_PVDDQ_GHJ_P")
	)
	(segment
		(start 18.077688 4.695444)
		(end 17.715992 4.333748)
		(width 0.127)
		(layer "In2.Cu")
		(net "VSENSE_PVDDQ_GHJ_P")
	)
	(segment
		(start 9.884664 4.550156)
		(end 7.993634 4.550156)
		(width 0.127)
		(layer "In2.Cu")
		(net "VSENSE_PVDDQ_GHJ_P")
	)
	(segment
		(start 11.470132 5.282692)
		(end 10.6172 5.282692)
		(width 0.127)
		(layer "In2.Cu")
		(net "VSENSE_PVDDQ_GHJ_P")
	)
	(segment
		(start 15.000224 4.669536)
		(end 12.083288 4.669536)
		(width 0.127)
		(layer "In2.Cu")
		(net "VSENSE_PVDDQ_GHJ_P")
	)
	(segment
		(start 15.438628 4.231132)
		(end 15.000224 4.669536)
		(width 0.127)
		(layer "In2.Cu")
		(net "VSENSE_PVDDQ_GHJ_P")
	)
	(segment
		(start 12.083288 4.669536)
		(end 11.470132 5.282692)
		(width 0.127)
		(layer "In2.Cu")
		(net "VSENSE_PVDDQ_GHJ_P")
	)
	(segment
		(start 16.123666 4.333748)
		(end 16.02105 4.231132)
		(width 0.127)
		(layer "In2.Cu")
		(net "VSENSE_PVDDQ_GHJ_P")
	)
	(segment
		(start 16.02105 4.231132)
		(end 15.438628 4.231132)
		(width 0.127)
		(layer "In2.Cu")
		(net "VSENSE_PVDDQ_GHJ_P")
	)
	(segment
		(start 7.09676 3.653282)
		(end 7.09676 -0.639318)
		(width 0.127)
		(layer "In2.Cu")
		(net "VSENSE_PVDDQ_GHJ_P")
	)
	(segment
		(start 10.6172 5.282692)
		(end 9.884664 4.550156)
		(width 0.127)
		(layer "In2.Cu")
		(net "VSENSE_PVDDQ_GHJ_P")
	)
	(segment
		(start 7.993634 4.550156)
		(end 7.09676 3.653282)
		(width 0.127)
		(layer "In2.Cu")
		(net "VSENSE_PVDDQ_GHJ_P")
	)
	(segment
		(start 7.09676 -0.639318)
		(end 5.187442 -2.548636)
		(width 0.127)
		(layer "In2.Cu")
		(net "VSENSE_PVDDQ_GHJ_P")
	)
	(segment
		(start 7.137146 -3.198622)
		(end 8.132318 -2.20345)
		(width 0.10795)
		(layer "F.Cu")
		(net "VSENSE_PVDDQ_GHJ_N")
	)
	(segment
		(start 7.137146 -3.659886)
		(end 7.137146 -3.198622)
		(width 0.10795)
		(layer "F.Cu")
		(net "VSENSE_PVDDQ_GHJ_N")
	)
	(segment
		(start 8.132318 -2.20345)
		(end 8.232902 -2.20345)
		(width 0.10795)
		(layer "F.Cu")
		(net "VSENSE_PVDDQ_GHJ_N")
	)
	(segment
		(start 6.36524 -4.118356)
		(end 6.82371 -3.659886)
		(width 0.10795)
		(layer "F.Cu")
		(net "VSENSE_PVDDQ_GHJ_N")
	)
	(segment
		(start 6.82371 -3.659886)
		(end 7.137146 -3.659886)
		(width 0.10795)
		(layer "F.Cu")
		(net "VSENSE_PVDDQ_GHJ_N")
	)
	(via
		(at 108.498132 -31.23438)
		(size 0.508)
		(drill 0.254)
		(layers "F.Cu" "B.Cu")
		(net "VSENSE_PVDDQ_GHJ_N")
	)
	(via
		(at 18.894044 4.683506)
		(size 0.508)
		(drill 0.254)
		(layers "F.Cu" "B.Cu")
		(net "VSENSE_PVDDQ_GHJ_N")
	)
	(via
		(at 6.36524 -4.118356)
		(size 0.508)
		(drill 0.254)
		(layers "F.Cu" "B.Cu")
		(net "VSENSE_PVDDQ_GHJ_N")
	)
	(segment
		(start 97.24644 -21.46808)
		(end 97.24644 -23.9522)
		(width 0.127)
		(layer "B.Cu")
		(net "VSENSE_PVDDQ_GHJ_N")
	)
	(segment
		(start 97.24136 -9.31037)
		(end 97.64776 -9.71677)
		(width 0.127)
		(layer "B.Cu")
		(net "VSENSE_PVDDQ_GHJ_N")
	)
	(segment
		(start 98.6282 -24.56942)
		(end 99.28352 -25.22474)
		(width 0.127)
		(layer "B.Cu")
		(net "VSENSE_PVDDQ_GHJ_N")
	)
	(segment
		(start 97.25152 -19.82089)
		(end 96.96958 -20.10283)
		(width 0.127)
		(layer "B.Cu")
		(net "VSENSE_PVDDQ_GHJ_N")
	)
	(segment
		(start 96.96958 -20.10283)
		(end 96.96958 -21.19122)
		(width 0.127)
		(layer "B.Cu")
		(net "VSENSE_PVDDQ_GHJ_N")
	)
	(segment
		(start 97.24644 -23.9522)
		(end 97.86366 -24.56942)
		(width 0.127)
		(layer "B.Cu")
		(net "VSENSE_PVDDQ_GHJ_N")
	)
	(segment
		(start 97.51568 -14.73327)
		(end 97.51568 -16.21409)
		(width 0.127)
		(layer "B.Cu")
		(net "VSENSE_PVDDQ_GHJ_N")
	)
	(segment
		(start 97.24136 3.65887)
		(end 97.24136 -9.31037)
		(width 0.127)
		(layer "B.Cu")
		(net "VSENSE_PVDDQ_GHJ_N")
	)
	(segment
		(start 102.42042 -31.23438)
		(end 108.498132 -31.23438)
		(width 0.127)
		(layer "B.Cu")
		(net "VSENSE_PVDDQ_GHJ_N")
	)
	(segment
		(start 84.58581 4.86156)
		(end 96.03867 4.86156)
		(width 0.127)
		(layer "B.Cu")
		(net "VSENSE_PVDDQ_GHJ_N")
	)
	(segment
		(start 112.872012 -29.94152)
		(end 113.761012 -29.94152)
		(width 0.127)
		(layer "B.Cu")
		(net "VSENSE_PVDDQ_GHJ_N")
	)
	(segment
		(start 112.872012 -30.348936)
		(end 112.872012 -29.94152)
		(width 0.127)
		(layer "B.Cu")
		(net "VSENSE_PVDDQ_GHJ_N")
	)
	(segment
		(start 18.713196 5.110734)
		(end 18.81378 5.211318)
		(width 0.127)
		(layer "B.Cu")
		(net "VSENSE_PVDDQ_GHJ_N")
	)
	(segment
		(start 99.28352 -28.09748)
		(end 102.42042 -31.23438)
		(width 0.127)
		(layer "B.Cu")
		(net "VSENSE_PVDDQ_GHJ_N")
	)
	(segment
		(start 97.25152 -14.46911)
		(end 97.51568 -14.73327)
		(width 0.127)
		(layer "B.Cu")
		(net "VSENSE_PVDDQ_GHJ_N")
	)
	(segment
		(start 99.28352 -25.22474)
		(end 99.28352 -28.09748)
		(width 0.127)
		(layer "B.Cu")
		(net "VSENSE_PVDDQ_GHJ_N")
	)
	(segment
		(start 97.25152 -16.47825)
		(end 97.25152 -19.82089)
		(width 0.127)
		(layer "B.Cu")
		(net "VSENSE_PVDDQ_GHJ_N")
	)
	(segment
		(start 112.27181 -31.23438)
		(end 112.554512 -30.951678)
		(width 0.127)
		(layer "B.Cu")
		(net "VSENSE_PVDDQ_GHJ_N")
	)
	(segment
		(start 18.713196 4.864354)
		(end 18.713196 5.110734)
		(width 0.127)
		(layer "B.Cu")
		(net "VSENSE_PVDDQ_GHJ_N")
	)
	(segment
		(start 112.554512 -30.951678)
		(end 112.554512 -30.666436)
		(width 0.127)
		(layer "B.Cu")
		(net "VSENSE_PVDDQ_GHJ_N")
	)
	(segment
		(start 18.894044 4.683506)
		(end 18.713196 4.864354)
		(width 0.127)
		(layer "B.Cu")
		(net "VSENSE_PVDDQ_GHJ_N")
	)
	(segment
		(start 108.498132 -31.23438)
		(end 112.27181 -31.23438)
		(width 0.127)
		(layer "B.Cu")
		(net "VSENSE_PVDDQ_GHJ_N")
	)
	(segment
		(start 97.64776 -9.71677)
		(end 97.64776 -11.32205)
		(width 0.127)
		(layer "B.Cu")
		(net "VSENSE_PVDDQ_GHJ_N")
	)
	(segment
		(start 96.03867 4.86156)
		(end 97.24136 3.65887)
		(width 0.127)
		(layer "B.Cu")
		(net "VSENSE_PVDDQ_GHJ_N")
	)
	(segment
		(start 84.236052 5.211318)
		(end 84.58581 4.86156)
		(width 0.127)
		(layer "B.Cu")
		(net "VSENSE_PVDDQ_GHJ_N")
	)
	(segment
		(start 18.81378 5.211318)
		(end 84.236052 5.211318)
		(width 0.127)
		(layer "B.Cu")
		(net "VSENSE_PVDDQ_GHJ_N")
	)
	(segment
		(start 97.86366 -24.56942)
		(end 98.6282 -24.56942)
		(width 0.127)
		(layer "B.Cu")
		(net "VSENSE_PVDDQ_GHJ_N")
	)
	(segment
		(start 97.25152 -11.71829)
		(end 97.25152 -14.46911)
		(width 0.127)
		(layer "B.Cu")
		(net "VSENSE_PVDDQ_GHJ_N")
	)
	(segment
		(start 112.554512 -30.666436)
		(end 112.872012 -30.348936)
		(width 0.127)
		(layer "B.Cu")
		(net "VSENSE_PVDDQ_GHJ_N")
	)
	(segment
		(start 97.64776 -11.32205)
		(end 97.25152 -11.71829)
		(width 0.127)
		(layer "B.Cu")
		(net "VSENSE_PVDDQ_GHJ_N")
	)
	(segment
		(start 97.51568 -16.21409)
		(end 97.25152 -16.47825)
		(width 0.127)
		(layer "B.Cu")
		(net "VSENSE_PVDDQ_GHJ_N")
	)
	(segment
		(start 96.96958 -21.19122)
		(end 97.24644 -21.46808)
		(width 0.127)
		(layer "B.Cu")
		(net "VSENSE_PVDDQ_GHJ_N")
	)
	(segment
		(start 10.72261 5.028692)
		(end 9.990074 4.296156)
		(width 0.127)
		(layer "In2.Cu")
		(net "VSENSE_PVDDQ_GHJ_N")
	)
	(segment
		(start 5.441442 -2.654046)
		(end 5.441442 -3.73126)
		(width 0.127)
		(layer "In2.Cu")
		(net "VSENSE_PVDDQ_GHJ_N")
	)
	(segment
		(start 9.990074 4.296156)
		(end 8.099044 4.296156)
		(width 0.127)
		(layer "In2.Cu")
		(net "VSENSE_PVDDQ_GHJ_N")
	)
	(segment
		(start 5.441442 -3.73126)
		(end 5.828538 -4.118356)
		(width 0.127)
		(layer "In2.Cu")
		(net "VSENSE_PVDDQ_GHJ_N")
	)
	(segment
		(start 11.364722 5.028692)
		(end 10.72261 5.028692)
		(width 0.127)
		(layer "In2.Cu")
		(net "VSENSE_PVDDQ_GHJ_N")
	)
	(segment
		(start 7.35076 -0.744728)
		(end 5.441442 -2.654046)
		(width 0.127)
		(layer "In2.Cu")
		(net "VSENSE_PVDDQ_GHJ_N")
	)
	(segment
		(start 14.894814 4.415536)
		(end 11.977878 4.415536)
		(width 0.127)
		(layer "In2.Cu")
		(net "VSENSE_PVDDQ_GHJ_N")
	)
	(segment
		(start 8.099044 4.296156)
		(end 7.35076 3.547872)
		(width 0.127)
		(layer "In2.Cu")
		(net "VSENSE_PVDDQ_GHJ_N")
	)
	(segment
		(start 11.977878 4.415536)
		(end 11.364722 5.028692)
		(width 0.127)
		(layer "In2.Cu")
		(net "VSENSE_PVDDQ_GHJ_N")
	)
	(segment
		(start 16.12646 3.977132)
		(end 15.333218 3.977132)
		(width 0.127)
		(layer "In2.Cu")
		(net "VSENSE_PVDDQ_GHJ_N")
	)
	(segment
		(start 15.333218 3.977132)
		(end 14.894814 4.415536)
		(width 0.127)
		(layer "In2.Cu")
		(net "VSENSE_PVDDQ_GHJ_N")
	)
	(segment
		(start 18.894044 4.683506)
		(end 18.290286 4.079748)
		(width 0.127)
		(layer "In2.Cu")
		(net "VSENSE_PVDDQ_GHJ_N")
	)
	(segment
		(start 16.229076 4.079748)
		(end 16.12646 3.977132)
		(width 0.127)
		(layer "In2.Cu")
		(net "VSENSE_PVDDQ_GHJ_N")
	)
	(segment
		(start 18.290286 4.079748)
		(end 16.229076 4.079748)
		(width 0.127)
		(layer "In2.Cu")
		(net "VSENSE_PVDDQ_GHJ_N")
	)
	(segment
		(start 7.35076 3.547872)
		(end 7.35076 -0.744728)
		(width 0.127)
		(layer "In2.Cu")
		(net "VSENSE_PVDDQ_GHJ_N")
	)
	(segment
		(start 5.828538 -4.118356)
		(end 6.36524 -4.118356)
		(width 0.127)
		(layer "In2.Cu")
		(net "VSENSE_PVDDQ_GHJ_N")
	)
	(segment
		(start 364.78464 -141.77137)
		(end 364.78464 -142.5448)
		(width 0.127)
		(layer "F.Cu")
		(net "VSENSE_PVDDQ_DEF_P")
	)
	(via
		(at 364.78464 -142.5448)
		(size 0.508)
		(drill 0.254)
		(layers "F.Cu" "B.Cu")
		(net "VSENSE_PVDDQ_DEF_P")
	)
	(via
		(at 353.276154 -157.655006)
		(size 0.508)
		(drill 0.254)
		(layers "F.Cu" "B.Cu")
		(net "VSENSE_PVDDQ_DEF_P")
	)
	(via
		(at 263.564878 -123.7742)
		(size 0.1016)
		(drill 0.0508)
		(layers "F.Cu" "B.Cu")
		(net "VSENSE_PVDDQ_DEF_P")
	)
	(segment
		(start 263.564878 -123.7742)
		(end 262.91159 -123.7742)
		(width 0.127)
		(layer "B.Cu")
		(net "VSENSE_PVDDQ_DEF_P")
	)
	(segment
		(start 266.931902 -158.579312)
		(end 352.619818 -158.579312)
		(width 0.127)
		(layer "B.Cu")
		(net "VSENSE_PVDDQ_DEF_P")
	)
	(segment
		(start 261.7216 -124.96419)
		(end 261.7216 -133.65861)
		(width 0.127)
		(layer "B.Cu")
		(net "VSENSE_PVDDQ_DEF_P")
	)
	(segment
		(start 262.91159 -123.7742)
		(end 261.7216 -124.96419)
		(width 0.127)
		(layer "B.Cu")
		(net "VSENSE_PVDDQ_DEF_P")
	)
	(segment
		(start 262.2296 -155.98521)
		(end 263.31799 -157.0736)
		(width 0.127)
		(layer "B.Cu")
		(net "VSENSE_PVDDQ_DEF_P")
	)
	(segment
		(start 263.564878 -123.7742)
		(end 265.062716 -123.7742)
		(width 0.127)
		(layer "B.Cu")
		(net "VSENSE_PVDDQ_DEF_P")
	)
	(segment
		(start 265.42619 -157.0736)
		(end 266.931902 -158.579312)
		(width 0.127)
		(layer "B.Cu")
		(net "VSENSE_PVDDQ_DEF_P")
	)
	(segment
		(start 261.7216 -133.65861)
		(end 262.2296 -134.16661)
		(width 0.127)
		(layer "B.Cu")
		(net "VSENSE_PVDDQ_DEF_P")
	)
	(segment
		(start 352.619818 -158.579312)
		(end 352.895408 -158.303722)
		(width 0.127)
		(layer "B.Cu")
		(net "VSENSE_PVDDQ_DEF_P")
	)
	(segment
		(start 263.31799 -157.0736)
		(end 265.42619 -157.0736)
		(width 0.127)
		(layer "B.Cu")
		(net "VSENSE_PVDDQ_DEF_P")
	)
	(segment
		(start 352.895408 -158.303722)
		(end 352.895408 -158.035752)
		(width 0.127)
		(layer "B.Cu")
		(net "VSENSE_PVDDQ_DEF_P")
	)
	(segment
		(start 265.062716 -123.7742)
		(end 265.8872 -124.598684)
		(width 0.127)
		(layer "B.Cu")
		(net "VSENSE_PVDDQ_DEF_P")
	)
	(segment
		(start 352.895408 -158.035752)
		(end 353.276154 -157.655006)
		(width 0.127)
		(layer "B.Cu")
		(net "VSENSE_PVDDQ_DEF_P")
	)
	(segment
		(start 265.8872 -124.6886)
		(end 266.7762 -124.6886)
		(width 0.127)
		(layer "B.Cu")
		(net "VSENSE_PVDDQ_DEF_P")
	)
	(segment
		(start 265.8872 -124.598684)
		(end 265.8872 -124.6886)
		(width 0.127)
		(layer "B.Cu")
		(net "VSENSE_PVDDQ_DEF_P")
	)
	(segment
		(start 262.2296 -134.16661)
		(end 262.2296 -155.98521)
		(width 0.127)
		(layer "B.Cu")
		(net "VSENSE_PVDDQ_DEF_P")
	)
	(segment
		(start 364.78464 -142.5448)
		(end 364.4392 -142.89024)
		(width 0.127)
		(layer "In2.Cu")
		(net "VSENSE_PVDDQ_DEF_P")
	)
	(segment
		(start 353.314 -156.46781)
		(end 352.8822 -156.89961)
		(width 0.127)
		(layer "In2.Cu")
		(net "VSENSE_PVDDQ_DEF_P")
	)
	(segment
		(start 352.8822 -157.3276)
		(end 353.209606 -157.655006)
		(width 0.127)
		(layer "In2.Cu")
		(net "VSENSE_PVDDQ_DEF_P")
	)
	(segment
		(start 356.743 -150.749)
		(end 353.314 -154.178)
		(width 0.127)
		(layer "In2.Cu")
		(net "VSENSE_PVDDQ_DEF_P")
	)
	(segment
		(start 365.5695 -149.619208)
		(end 364.439708 -150.749)
		(width 0.127)
		(layer "In2.Cu")
		(net "VSENSE_PVDDQ_DEF_P")
	)
	(segment
		(start 353.314 -154.178)
		(end 353.314 -156.46781)
		(width 0.127)
		(layer "In2.Cu")
		(net "VSENSE_PVDDQ_DEF_P")
	)
	(segment
		(start 364.4392 -142.89024)
		(end 364.4392 -143.08328)
		(width 0.127)
		(layer "In2.Cu")
		(net "VSENSE_PVDDQ_DEF_P")
	)
	(segment
		(start 353.209606 -157.655006)
		(end 353.276154 -157.655006)
		(width 0.127)
		(layer "In2.Cu")
		(net "VSENSE_PVDDQ_DEF_P")
	)
	(segment
		(start 365.5695 -144.21358)
		(end 365.5695 -149.619208)
		(width 0.127)
		(layer "In2.Cu")
		(net "VSENSE_PVDDQ_DEF_P")
	)
	(segment
		(start 364.4392 -143.08328)
		(end 365.5695 -144.21358)
		(width 0.127)
		(layer "In2.Cu")
		(net "VSENSE_PVDDQ_DEF_P")
	)
	(segment
		(start 364.439708 -150.749)
		(end 356.743 -150.749)
		(width 0.127)
		(layer "In2.Cu")
		(net "VSENSE_PVDDQ_DEF_P")
	)
	(segment
		(start 352.8822 -156.89961)
		(end 352.8822 -157.3276)
		(width 0.127)
		(layer "In2.Cu")
		(net "VSENSE_PVDDQ_DEF_P")
	)
	(segment
		(start 361.74934 -139.964668)
		(end 361.74934 -140.21054)
		(width 0.127)
		(layer "F.Cu")
		(net "VSENSE_PVDDQ_DEF_N")
	)
	(segment
		(start 361.74934 -140.21054)
		(end 363.31017 -141.77137)
		(width 0.127)
		(layer "F.Cu")
		(net "VSENSE_PVDDQ_DEF_N")
	)
	(segment
		(start 363.87024 -141.77137)
		(end 363.87024 -142.53464)
		(width 0.127)
		(layer "F.Cu")
		(net "VSENSE_PVDDQ_DEF_N")
	)
	(segment
		(start 363.31017 -141.77137)
		(end 363.87024 -141.77137)
		(width 0.127)
		(layer "F.Cu")
		(net "VSENSE_PVDDQ_DEF_N")
	)
	(via
		(at 363.87024 -142.53464)
		(size 0.508)
		(drill 0.254)
		(layers "F.Cu" "B.Cu")
		(net "VSENSE_PVDDQ_DEF_N")
	)
	(via
		(at 352.277934 -157.655006)
		(size 0.508)
		(drill 0.254)
		(layers "F.Cu" "B.Cu")
		(net "VSENSE_PVDDQ_DEF_N")
	)
	(segment
		(start 263.017 -124.0282)
		(end 261.9756 -125.0696)
		(width 0.127)
		(layer "B.Cu")
		(net "VSENSE_PVDDQ_DEF_N")
	)
	(segment
		(start 265.5316 -156.8196)
		(end 267.037312 -158.325312)
		(width 0.127)
		(layer "B.Cu")
		(net "VSENSE_PVDDQ_DEF_N")
	)
	(segment
		(start 263.4234 -156.8196)
		(end 265.5316 -156.8196)
		(width 0.127)
		(layer "B.Cu")
		(net "VSENSE_PVDDQ_DEF_N")
	)
	(segment
		(start 352.641408 -158.198312)
		(end 352.641408 -158.01848)
		(width 0.127)
		(layer "B.Cu")
		(net "VSENSE_PVDDQ_DEF_N")
	)
	(segment
		(start 261.9756 -125.0696)
		(end 261.9756 -133.5532)
		(width 0.127)
		(layer "B.Cu")
		(net "VSENSE_PVDDQ_DEF_N")
	)
	(segment
		(start 264.668 -124.0282)
		(end 263.017 -124.0282)
		(width 0.127)
		(layer "B.Cu")
		(net "VSENSE_PVDDQ_DEF_N")
	)
	(segment
		(start 262.4836 -134.0612)
		(end 262.4836 -155.8798)
		(width 0.127)
		(layer "B.Cu")
		(net "VSENSE_PVDDQ_DEF_N")
	)
	(segment
		(start 352.641408 -158.01848)
		(end 352.277934 -157.655006)
		(width 0.127)
		(layer "B.Cu")
		(net "VSENSE_PVDDQ_DEF_N")
	)
	(segment
		(start 267.037312 -158.325312)
		(end 352.514408 -158.325312)
		(width 0.127)
		(layer "B.Cu")
		(net "VSENSE_PVDDQ_DEF_N")
	)
	(segment
		(start 352.514408 -158.325312)
		(end 352.641408 -158.198312)
		(width 0.127)
		(layer "B.Cu")
		(net "VSENSE_PVDDQ_DEF_N")
	)
	(segment
		(start 262.4836 -155.8798)
		(end 263.4234 -156.8196)
		(width 0.127)
		(layer "B.Cu")
		(net "VSENSE_PVDDQ_DEF_N")
	)
	(segment
		(start 261.9756 -133.5532)
		(end 262.4836 -134.0612)
		(width 0.127)
		(layer "B.Cu")
		(net "VSENSE_PVDDQ_DEF_N")
	)
	(segment
		(start 264.9982 -124.6886)
		(end 264.1346 -124.6886)
		(width 0.127)
		(layer "B.Cu")
		(net "VSENSE_PVDDQ_DEF_N")
	)
	(segment
		(start 264.9982 -124.6886)
		(end 264.9982 -124.3584)
		(width 0.127)
		(layer "B.Cu")
		(net "VSENSE_PVDDQ_DEF_N")
	)
	(segment
		(start 264.9982 -124.3584)
		(end 264.668 -124.0282)
		(width 0.127)
		(layer "B.Cu")
		(net "VSENSE_PVDDQ_DEF_N")
	)
	(segment
		(start 353.06 -154.07259)
		(end 353.06 -156.3624)
		(width 0.127)
		(layer "In2.Cu")
		(net "VSENSE_PVDDQ_DEF_N")
	)
	(segment
		(start 364.334298 -150.495)
		(end 356.63759 -150.495)
		(width 0.127)
		(layer "In2.Cu")
		(net "VSENSE_PVDDQ_DEF_N")
	)
	(segment
		(start 363.87024 -142.53464)
		(end 364.1852 -142.8496)
		(width 0.127)
		(layer "In2.Cu")
		(net "VSENSE_PVDDQ_DEF_N")
	)
	(segment
		(start 365.3155 -144.31899)
		(end 365.3155 -149.513798)
		(width 0.127)
		(layer "In2.Cu")
		(net "VSENSE_PVDDQ_DEF_N")
	)
	(segment
		(start 352.300794 -157.655006)
		(end 352.277934 -157.655006)
		(width 0.127)
		(layer "In2.Cu")
		(net "VSENSE_PVDDQ_DEF_N")
	)
	(segment
		(start 364.1852 -143.18869)
		(end 365.3155 -144.31899)
		(width 0.127)
		(layer "In2.Cu")
		(net "VSENSE_PVDDQ_DEF_N")
	)
	(segment
		(start 352.6282 -157.3276)
		(end 352.300794 -157.655006)
		(width 0.127)
		(layer "In2.Cu")
		(net "VSENSE_PVDDQ_DEF_N")
	)
	(segment
		(start 356.63759 -150.495)
		(end 353.06 -154.07259)
		(width 0.127)
		(layer "In2.Cu")
		(net "VSENSE_PVDDQ_DEF_N")
	)
	(segment
		(start 365.3155 -149.513798)
		(end 364.334298 -150.495)
		(width 0.127)
		(layer "In2.Cu")
		(net "VSENSE_PVDDQ_DEF_N")
	)
	(segment
		(start 364.1852 -142.8496)
		(end 364.1852 -143.18869)
		(width 0.127)
		(layer "In2.Cu")
		(net "VSENSE_PVDDQ_DEF_N")
	)
	(segment
		(start 352.6282 -156.7942)
		(end 352.6282 -157.3276)
		(width 0.127)
		(layer "In2.Cu")
		(net "VSENSE_PVDDQ_DEF_N")
	)
	(segment
		(start 353.06 -156.3624)
		(end 352.6282 -156.7942)
		(width 0.127)
		(layer "In2.Cu")
		(net "VSENSE_PVDDQ_DEF_N")
	)
	(segment
		(start 337.310984 -13.97)
		(end 337.947 -13.97)
		(width 0.127)
		(layer "F.Cu")
		(net "VSENSE_PVDDQ_ABC_P")
	)
	(segment
		(start 337.172808 -14.108176)
		(end 337.310984 -13.97)
		(width 0.127)
		(layer "F.Cu")
		(net "VSENSE_PVDDQ_ABC_P")
	)
	(via
		(at 328.629264 3.437382)
		(size 0.508)
		(drill 0.254)
		(layers "F.Cu" "B.Cu")
		(net "VSENSE_PVDDQ_ABC_P")
	)
	(via
		(at 273.797268 -28.632658)
		(size 0.508)
		(drill 0.254)
		(layers "F.Cu" "B.Cu")
		(net "VSENSE_PVDDQ_ABC_P")
	)
	(via
		(at 337.172808 -14.108176)
		(size 0.508)
		(drill 0.254)
		(layers "F.Cu" "B.Cu")
		(net "VSENSE_PVDDQ_ABC_P")
	)
	(segment
		(start 262.4836 -16.61541)
		(end 262.9154 -16.18361)
		(width 0.127)
		(layer "B.Cu")
		(net "VSENSE_PVDDQ_ABC_P")
	)
	(segment
		(start 262.9154 -16.18361)
		(end 262.9154 -14.405102)
		(width 0.127)
		(layer "B.Cu")
		(net "VSENSE_PVDDQ_ABC_P")
	)
	(segment
		(start 262.508238 -11.848084)
		(end 262.9916 -11.364722)
		(width 0.127)
		(layer "B.Cu")
		(net "VSENSE_PVDDQ_ABC_P")
	)
	(segment
		(start 276.0472 -29.337)
		(end 276.9362 -29.337)
		(width 0.127)
		(layer "B.Cu")
		(net "VSENSE_PVDDQ_ABC_P")
	)
	(segment
		(start 262.3058 -19.25701)
		(end 262.4836 -19.07921)
		(width 0.127)
		(layer "B.Cu")
		(net "VSENSE_PVDDQ_ABC_P")
	)
	(segment
		(start 328.048112 4.097274)
		(end 328.048112 4.018534)
		(width 0.127)
		(layer "B.Cu")
		(net "VSENSE_PVDDQ_ABC_P")
	)
	(segment
		(start 326.963786 5.1816)
		(end 328.048112 4.097274)
		(width 0.127)
		(layer "B.Cu")
		(net "VSENSE_PVDDQ_ABC_P")
	)
	(segment
		(start 265.63701 -27.7368)
		(end 264.7442 -26.84399)
		(width 0.127)
		(layer "B.Cu")
		(net "VSENSE_PVDDQ_ABC_P")
	)
	(segment
		(start 263.07161 -24.257)
		(end 262.3058 -23.49119)
		(width 0.127)
		(layer "B.Cu")
		(net "VSENSE_PVDDQ_ABC_P")
	)
	(segment
		(start 264.7442 -26.84399)
		(end 264.7442 -25.47239)
		(width 0.127)
		(layer "B.Cu")
		(net "VSENSE_PVDDQ_ABC_P")
	)
	(segment
		(start 264.7442 -25.47239)
		(end 263.52881 -24.257)
		(width 0.127)
		(layer "B.Cu")
		(net "VSENSE_PVDDQ_ABC_P")
	)
	(segment
		(start 265.107928 5.1816)
		(end 326.963786 5.1816)
		(width 0.127)
		(layer "B.Cu")
		(net "VSENSE_PVDDQ_ABC_P")
	)
	(segment
		(start 262.4836 2.557272)
		(end 265.107928 5.1816)
		(width 0.127)
		(layer "B.Cu")
		(net "VSENSE_PVDDQ_ABC_P")
	)
	(segment
		(start 262.9154 -14.405102)
		(end 262.508238 -13.99794)
		(width 0.127)
		(layer "B.Cu")
		(net "VSENSE_PVDDQ_ABC_P")
	)
	(segment
		(start 262.4836 -19.07921)
		(end 262.4836 -16.61541)
		(width 0.127)
		(layer "B.Cu")
		(net "VSENSE_PVDDQ_ABC_P")
	)
	(segment
		(start 262.3058 -23.49119)
		(end 262.3058 -19.25701)
		(width 0.127)
		(layer "B.Cu")
		(net "VSENSE_PVDDQ_ABC_P")
	)
	(segment
		(start 328.048112 4.018534)
		(end 328.629264 3.437382)
		(width 0.127)
		(layer "B.Cu")
		(net "VSENSE_PVDDQ_ABC_P")
	)
	(segment
		(start 276.808946 -29.860748)
		(end 276.9362 -29.733494)
		(width 0.127)
		(layer "B.Cu")
		(net "VSENSE_PVDDQ_ABC_P")
	)
	(segment
		(start 262.9916 -10.15619)
		(end 262.4836 -9.64819)
		(width 0.127)
		(layer "B.Cu")
		(net "VSENSE_PVDDQ_ABC_P")
	)
	(segment
		(start 262.4836 -9.64819)
		(end 262.4836 2.557272)
		(width 0.127)
		(layer "B.Cu")
		(net "VSENSE_PVDDQ_ABC_P")
	)
	(segment
		(start 275.025358 -29.860748)
		(end 276.808946 -29.860748)
		(width 0.127)
		(layer "B.Cu")
		(net "VSENSE_PVDDQ_ABC_P")
	)
	(segment
		(start 272.90141 -27.7368)
		(end 265.63701 -27.7368)
		(width 0.127)
		(layer "B.Cu")
		(net "VSENSE_PVDDQ_ABC_P")
	)
	(segment
		(start 262.508238 -13.99794)
		(end 262.508238 -11.848084)
		(width 0.127)
		(layer "B.Cu")
		(net "VSENSE_PVDDQ_ABC_P")
	)
	(segment
		(start 263.52881 -24.257)
		(end 263.07161 -24.257)
		(width 0.127)
		(layer "B.Cu")
		(net "VSENSE_PVDDQ_ABC_P")
	)
	(segment
		(start 273.797268 -28.632658)
		(end 275.025358 -29.860748)
		(width 0.127)
		(layer "B.Cu")
		(net "VSENSE_PVDDQ_ABC_P")
	)
	(segment
		(start 262.9916 -11.364722)
		(end 262.9916 -10.15619)
		(width 0.127)
		(layer "B.Cu")
		(net "VSENSE_PVDDQ_ABC_P")
	)
	(segment
		(start 276.9362 -29.733494)
		(end 276.9362 -29.337)
		(width 0.127)
		(layer "B.Cu")
		(net "VSENSE_PVDDQ_ABC_P")
	)
	(segment
		(start 273.797268 -28.632658)
		(end 272.90141 -27.7368)
		(width 0.127)
		(layer "B.Cu")
		(net "VSENSE_PVDDQ_ABC_P")
	)
	(segment
		(start 331.687424 -13.755624)
		(end 336.869024 -13.755624)
		(width 0.127)
		(layer "In4.Cu")
		(net "VSENSE_PVDDQ_ABC_P")
	)
	(segment
		(start 329.6793 -1.1811)
		(end 329.6793 -4.825492)
		(width 0.127)
		(layer "In4.Cu")
		(net "VSENSE_PVDDQ_ABC_P")
	)
	(segment
		(start 330.4032 -12.4714)
		(end 331.687424 -13.755624)
		(width 0.127)
		(layer "In4.Cu")
		(net "VSENSE_PVDDQ_ABC_P")
	)
	(segment
		(start 330.4032 -5.549392)
		(end 330.4032 -12.4714)
		(width 0.127)
		(layer "In4.Cu")
		(net "VSENSE_PVDDQ_ABC_P")
	)
	(segment
		(start 328.972164 -0.473964)
		(end 329.6793 -1.1811)
		(width 0.127)
		(layer "In4.Cu")
		(net "VSENSE_PVDDQ_ABC_P")
	)
	(segment
		(start 328.629264 3.437382)
		(end 328.972164 3.094482)
		(width 0.127)
		(layer "In4.Cu")
		(net "VSENSE_PVDDQ_ABC_P")
	)
	(segment
		(start 328.972164 3.094482)
		(end 328.972164 -0.473964)
		(width 0.127)
		(layer "In4.Cu")
		(net "VSENSE_PVDDQ_ABC_P")
	)
	(segment
		(start 329.6793 -4.825492)
		(end 330.4032 -5.549392)
		(width 0.127)
		(layer "In4.Cu")
		(net "VSENSE_PVDDQ_ABC_P")
	)
	(segment
		(start 336.869024 -13.755624)
		(end 337.172808 -14.108176)
		(width 0.127)
		(layer "In4.Cu")
		(net "VSENSE_PVDDQ_ABC_P")
	)
	(segment
		(start 342.2269 -13.566902)
		(end 341.400638 -12.74064)
		(width 0.127)
		(layer "F.Cu")
		(net "VSENSE_PVDDQ_ABC_N")
	)
	(segment
		(start 340.93277 -12.74064)
		(end 340.84514 -12.74064)
		(width 0.127)
		(layer "F.Cu")
		(net "VSENSE_PVDDQ_ABC_N")
	)
	(segment
		(start 340.614 -12.5095)
		(end 338.6201 -12.5095)
		(width 0.127)
		(layer "F.Cu")
		(net "VSENSE_PVDDQ_ABC_N")
	)
	(segment
		(start 337.185 -13.092938)
		(end 337.274662 -13.1826)
		(width 0.127)
		(layer "F.Cu")
		(net "VSENSE_PVDDQ_ABC_N")
	)
	(segment
		(start 337.274662 -13.1826)
		(end 337.947 -13.1826)
		(width 0.127)
		(layer "F.Cu")
		(net "VSENSE_PVDDQ_ABC_N")
	)
	(segment
		(start 340.84514 -12.74064)
		(end 340.614 -12.5095)
		(width 0.127)
		(layer "F.Cu")
		(net "VSENSE_PVDDQ_ABC_N")
	)
	(segment
		(start 341.400638 -12.74064)
		(end 340.93277 -12.74064)
		(width 0.127)
		(layer "F.Cu")
		(net "VSENSE_PVDDQ_ABC_N")
	)
	(segment
		(start 338.6201 -12.5095)
		(end 337.947 -13.1826)
		(width 0.127)
		(layer "F.Cu")
		(net "VSENSE_PVDDQ_ABC_N")
	)
	(via
		(at 328.5744 4.318)
		(size 0.508)
		(drill 0.254)
		(layers "F.Cu" "B.Cu")
		(net "VSENSE_PVDDQ_ABC_N")
	)
	(via
		(at 337.185 -13.092938)
		(size 0.508)
		(drill 0.254)
		(layers "F.Cu" "B.Cu")
		(net "VSENSE_PVDDQ_ABC_N")
	)
	(via
		(at 340.93277 -12.74064)
		(size 0.762)
		(drill 0.381)
		(layers "F.Cu" "B.Cu")
		(net "VSENSE_PVDDQ_ABC_N")
	)
	(segment
		(start 262.0518 -19.1516)
		(end 262.2296 -18.9738)
		(width 0.127)
		(layer "B.Cu")
		(net "VSENSE_PVDDQ_ABC_N")
	)
	(segment
		(start 264.4902 -26.9494)
		(end 264.4902 -25.5778)
		(width 0.127)
		(layer "B.Cu")
		(net "VSENSE_PVDDQ_ABC_N")
	)
	(segment
		(start 277.8252 -29.337)
		(end 277.8252 -29.73832)
		(width 0.127)
		(layer "B.Cu")
		(net "VSENSE_PVDDQ_ABC_N")
	)
	(segment
		(start 262.7376 -11.259312)
		(end 262.7376 -10.2616)
		(width 0.127)
		(layer "B.Cu")
		(net "VSENSE_PVDDQ_ABC_N")
	)
	(segment
		(start 262.2296 -16.51)
		(end 262.6614 -16.0782)
		(width 0.127)
		(layer "B.Cu")
		(net "VSENSE_PVDDQ_ABC_N")
	)
	(segment
		(start 277.8252 -29.73832)
		(end 277.448772 -30.114748)
		(width 0.127)
		(layer "B.Cu")
		(net "VSENSE_PVDDQ_ABC_N")
	)
	(segment
		(start 264.4902 -25.5778)
		(end 263.4234 -24.511)
		(width 0.127)
		(layer "B.Cu")
		(net "VSENSE_PVDDQ_ABC_N")
	)
	(segment
		(start 265.002518 5.4356)
		(end 327.069196 5.4356)
		(width 0.127)
		(layer "B.Cu")
		(net "VSENSE_PVDDQ_ABC_N")
	)
	(segment
		(start 263.4234 -24.511)
		(end 262.9662 -24.511)
		(width 0.127)
		(layer "B.Cu")
		(net "VSENSE_PVDDQ_ABC_N")
	)
	(segment
		(start 262.6614 -14.510512)
		(end 262.254238 -14.10335)
		(width 0.127)
		(layer "B.Cu")
		(net "VSENSE_PVDDQ_ABC_N")
	)
	(segment
		(start 272.796 -27.9908)
		(end 265.5316 -27.9908)
		(width 0.127)
		(layer "B.Cu")
		(net "VSENSE_PVDDQ_ABC_N")
	)
	(segment
		(start 262.254238 -11.742674)
		(end 262.7376 -11.259312)
		(width 0.127)
		(layer "B.Cu")
		(net "VSENSE_PVDDQ_ABC_N")
	)
	(segment
		(start 327.069196 5.4356)
		(end 328.186796 4.318)
		(width 0.127)
		(layer "B.Cu")
		(net "VSENSE_PVDDQ_ABC_N")
	)
	(segment
		(start 262.0518 -23.5966)
		(end 262.0518 -19.1516)
		(width 0.127)
		(layer "B.Cu")
		(net "VSENSE_PVDDQ_ABC_N")
	)
	(segment
		(start 262.6614 -16.0782)
		(end 262.6614 -14.510512)
		(width 0.127)
		(layer "B.Cu")
		(net "VSENSE_PVDDQ_ABC_N")
	)
	(segment
		(start 262.254238 -14.10335)
		(end 262.254238 -11.742674)
		(width 0.127)
		(layer "B.Cu")
		(net "VSENSE_PVDDQ_ABC_N")
	)
	(segment
		(start 265.5316 -27.9908)
		(end 264.4902 -26.9494)
		(width 0.127)
		(layer "B.Cu")
		(net "VSENSE_PVDDQ_ABC_N")
	)
	(segment
		(start 262.2296 2.662682)
		(end 265.002518 5.4356)
		(width 0.127)
		(layer "B.Cu")
		(net "VSENSE_PVDDQ_ABC_N")
	)
	(segment
		(start 262.9662 -24.511)
		(end 262.0518 -23.5966)
		(width 0.127)
		(layer "B.Cu")
		(net "VSENSE_PVDDQ_ABC_N")
	)
	(segment
		(start 277.448772 -30.114748)
		(end 274.919948 -30.114748)
		(width 0.127)
		(layer "B.Cu")
		(net "VSENSE_PVDDQ_ABC_N")
	)
	(segment
		(start 262.2296 -9.7536)
		(end 262.2296 2.662682)
		(width 0.127)
		(layer "B.Cu")
		(net "VSENSE_PVDDQ_ABC_N")
	)
	(segment
		(start 262.7376 -10.2616)
		(end 262.2296 -9.7536)
		(width 0.127)
		(layer "B.Cu")
		(net "VSENSE_PVDDQ_ABC_N")
	)
	(segment
		(start 278.7142 -29.337)
		(end 277.8252 -29.337)
		(width 0.127)
		(layer "B.Cu")
		(net "VSENSE_PVDDQ_ABC_N")
	)
	(segment
		(start 274.919948 -30.114748)
		(end 272.796 -27.9908)
		(width 0.127)
		(layer "B.Cu")
		(net "VSENSE_PVDDQ_ABC_N")
	)
	(segment
		(start 328.186796 4.318)
		(end 328.5744 4.318)
		(width 0.127)
		(layer "B.Cu")
		(net "VSENSE_PVDDQ_ABC_N")
	)
	(segment
		(start 262.2296 -18.9738)
		(end 262.2296 -16.51)
		(width 0.127)
		(layer "B.Cu")
		(net "VSENSE_PVDDQ_ABC_N")
	)
	(segment
		(start 336.709004 -13.501624)
		(end 337.185 -13.092938)
		(width 0.127)
		(layer "In4.Cu")
		(net "VSENSE_PVDDQ_ABC_N")
	)
	(segment
		(start 331.792834 -13.501624)
		(end 336.709004 -13.501624)
		(width 0.127)
		(layer "In4.Cu")
		(net "VSENSE_PVDDQ_ABC_N")
	)
	(segment
		(start 330.6572 -5.443982)
		(end 330.6572 -12.36599)
		(width 0.127)
		(layer "In4.Cu")
		(net "VSENSE_PVDDQ_ABC_N")
	)
	(segment
		(start 329.226164 3.666236)
		(end 329.226164 -0.368554)
		(width 0.127)
		(layer "In4.Cu")
		(net "VSENSE_PVDDQ_ABC_N")
	)
	(segment
		(start 328.5744 4.318)
		(end 329.226164 3.666236)
		(width 0.127)
		(layer "In4.Cu")
		(net "VSENSE_PVDDQ_ABC_N")
	)
	(segment
		(start 329.9333 -4.720082)
		(end 330.6572 -5.443982)
		(width 0.127)
		(layer "In4.Cu")
		(net "VSENSE_PVDDQ_ABC_N")
	)
	(segment
		(start 329.226164 -0.368554)
		(end 329.9333 -1.07569)
		(width 0.127)
		(layer "In4.Cu")
		(net "VSENSE_PVDDQ_ABC_N")
	)
	(segment
		(start 330.6572 -12.36599)
		(end 331.792834 -13.501624)
		(width 0.127)
		(layer "In4.Cu")
		(net "VSENSE_PVDDQ_ABC_N")
	)
	(segment
		(start 329.9333 -1.07569)
		(end 329.9333 -4.720082)
		(width 0.127)
		(layer "In4.Cu")
		(net "VSENSE_PVDDQ_ABC_N")
	)
	(segment
		(start 159.403542 -65.2018)
		(end 160.909 -65.2018)
		(width 0.127)
		(layer "F.Cu")
		(net "VSENSE_PVCCIO_CPU1_SKT_VSEN")
	)
	(segment
		(start 160.88614 -69.75094)
		(end 160.375092 -69.239892)
		(width 0.127)
		(layer "F.Cu")
		(net "VSENSE_PVCCIO_CPU1_SKT_VSEN")
	)
	(segment
		(start 158.7754 -65.829942)
		(end 159.403542 -65.2018)
		(width 0.127)
		(layer "F.Cu")
		(net "VSENSE_PVCCIO_CPU1_SKT_VSEN")
	)
	(segment
		(start 161.2138 -64.897)
		(end 161.6456 -64.897)
		(width 0.127)
		(layer "F.Cu")
		(net "VSENSE_PVCCIO_CPU1_SKT_VSEN")
	)
	(segment
		(start 161.671 -64.8716)
		(end 161.6456 -64.897)
		(width 0.127)
		(layer "F.Cu")
		(net "VSENSE_PVCCIO_CPU1_SKT_VSEN")
	)
	(segment
		(start 159.67075 -69.239892)
		(end 158.7754 -68.344542)
		(width 0.127)
		(layer "F.Cu")
		(net "VSENSE_PVCCIO_CPU1_SKT_VSEN")
	)
	(segment
		(start 160.909 -65.2018)
		(end 161.2138 -64.897)
		(width 0.127)
		(layer "F.Cu")
		(net "VSENSE_PVCCIO_CPU1_SKT_VSEN")
	)
	(segment
		(start 162.306 -64.8716)
		(end 161.671 -64.8716)
		(width 0.127)
		(layer "F.Cu")
		(net "VSENSE_PVCCIO_CPU1_SKT_VSEN")
	)
	(segment
		(start 160.375092 -69.239892)
		(end 159.67075 -69.239892)
		(width 0.127)
		(layer "F.Cu")
		(net "VSENSE_PVCCIO_CPU1_SKT_VSEN")
	)
	(segment
		(start 138.816334 -74.725784)
		(end 139.387834 -74.725784)
		(width 0.127)
		(layer "F.Cu")
		(net "VSENSE_PVCCIO_CPU1_SKT_VSEN")
	)
	(segment
		(start 158.7754 -68.344542)
		(end 158.7754 -65.829942)
		(width 0.127)
		(layer "F.Cu")
		(net "VSENSE_PVCCIO_CPU1_SKT_VSEN")
	)
	(via
		(at 139.387834 -74.725784)
		(size 0.508)
		(drill 0.254)
		(layers "F.Cu" "B.Cu")
		(net "VSENSE_PVCCIO_CPU1_SKT_VSEN")
	)
	(via
		(at 160.88614 -69.75094)
		(size 0.508)
		(drill 0.254)
		(layers "F.Cu" "B.Cu")
		(net "VSENSE_PVCCIO_CPU1_SKT_VSEN")
	)
	(segment
		(start 140.41247 -74.821034)
		(end 140.2334 -74.821034)
		(width 0.0889)
		(layer "In2.Cu")
		(net "VSENSE_PVCCIO_CPU1_SKT_VSEN")
	)
	(segment
		(start 139.445746 -74.329798)
		(end 139.387834 -74.38771)
		(width 0.0889)
		(layer "In2.Cu")
		(net "VSENSE_PVCCIO_CPU1_SKT_VSEN")
	)
	(segment
		(start 143.0274 -75.335384)
		(end 143.00835 -75.316334)
		(width 0.0889)
		(layer "In2.Cu")
		(net "VSENSE_PVCCIO_CPU1_SKT_VSEN")
	)
	(segment
		(start 160.88614 -69.75094)
		(end 160.3502 -69.215)
		(width 0.127)
		(layer "In2.Cu")
		(net "VSENSE_PVCCIO_CPU1_SKT_VSEN")
	)
	(segment
		(start 143.049498 -75.335384)
		(end 143.0274 -75.335384)
		(width 0.0889)
		(layer "In2.Cu")
		(net "VSENSE_PVCCIO_CPU1_SKT_VSEN")
	)
	(segment
		(start 159.766 -69.215)
		(end 153.645616 -75.335384)
		(width 0.127)
		(layer "In2.Cu")
		(net "VSENSE_PVCCIO_CPU1_SKT_VSEN")
	)
	(segment
		(start 160.3502 -69.215)
		(end 159.766 -69.215)
		(width 0.127)
		(layer "In2.Cu")
		(net "VSENSE_PVCCIO_CPU1_SKT_VSEN")
	)
	(segment
		(start 143.00835 -75.316334)
		(end 140.977874 -75.316334)
		(width 0.0889)
		(layer "In2.Cu")
		(net "VSENSE_PVCCIO_CPU1_SKT_VSEN")
	)
	(segment
		(start 153.645616 -75.335384)
		(end 143.049498 -75.335384)
		(width 0.127)
		(layer "In2.Cu")
		(net "VSENSE_PVCCIO_CPU1_SKT_VSEN")
	)
	(segment
		(start 139.387834 -74.38771)
		(end 139.387834 -74.725784)
		(width 0.0889)
		(layer "In2.Cu")
		(net "VSENSE_PVCCIO_CPU1_SKT_VSEN")
	)
	(arc
		(start 140.629386 -75.018392)
		(mid 140.538146 -74.900779)
		(end 140.41247 -74.821034)
		(width 0.0889)
		(layer "In2.Cu")
		(net "VSENSE_PVCCIO_CPU1_SKT_VSEN")
	)
	(arc
		(start 140.2334 -74.821034)
		(mid 139.945255 -74.738715)
		(end 139.734544 -74.525632)
		(width 0.0889)
		(layer "In2.Cu")
		(net "VSENSE_PVCCIO_CPU1_SKT_VSEN")
	)
	(arc
		(start 140.977874 -75.316334)
		(mid 140.77528 -75.200516)
		(end 140.629386 -75.018392)
		(width 0.0889)
		(layer "In2.Cu")
		(net "VSENSE_PVCCIO_CPU1_SKT_VSEN")
	)
	(arc
		(start 139.734544 -74.525632)
		(mid 139.612599 -74.3946)
		(end 139.445746 -74.329798)
		(width 0.0889)
		(layer "In2.Cu")
		(net "VSENSE_PVCCIO_CPU1_SKT_VSEN")
	)
	(segment
		(start 160.355788 -69.011292)
		(end 159.765492 -69.011292)
		(width 0.127)
		(layer "F.Cu")
		(net "VSENSE_PVCCIO_CPU1_SKT_VRTN")
	)
	(segment
		(start 161.2646 -65.786)
		(end 161.6456 -65.786)
		(width 0.127)
		(layer "F.Cu")
		(net "VSENSE_PVCCIO_CPU1_SKT_VRTN")
	)
	(segment
		(start 159.004 -68.2498)
		(end 159.004 -65.924684)
		(width 0.127)
		(layer "F.Cu")
		(net "VSENSE_PVCCIO_CPU1_SKT_VRTN")
	)
	(segment
		(start 159.498284 -65.4304)
		(end 160.909 -65.4304)
		(width 0.127)
		(layer "F.Cu")
		(net "VSENSE_PVCCIO_CPU1_SKT_VRTN")
	)
	(segment
		(start 161.671 -65.7606)
		(end 161.6456 -65.786)
		(width 0.127)
		(layer "F.Cu")
		(net "VSENSE_PVCCIO_CPU1_SKT_VRTN")
	)
	(segment
		(start 138.816334 -73.735184)
		(end 139.387834 -73.735184)
		(width 0.127)
		(layer "F.Cu")
		(net "VSENSE_PVCCIO_CPU1_SKT_VRTN")
	)
	(segment
		(start 162.306 -65.7606)
		(end 161.671 -65.7606)
		(width 0.127)
		(layer "F.Cu")
		(net "VSENSE_PVCCIO_CPU1_SKT_VRTN")
	)
	(segment
		(start 159.004 -65.924684)
		(end 159.498284 -65.4304)
		(width 0.127)
		(layer "F.Cu")
		(net "VSENSE_PVCCIO_CPU1_SKT_VRTN")
	)
	(segment
		(start 160.909 -65.4304)
		(end 161.2646 -65.786)
		(width 0.127)
		(layer "F.Cu")
		(net "VSENSE_PVCCIO_CPU1_SKT_VRTN")
	)
	(segment
		(start 160.88614 -68.48094)
		(end 160.355788 -69.011292)
		(width 0.127)
		(layer "F.Cu")
		(net "VSENSE_PVCCIO_CPU1_SKT_VRTN")
	)
	(segment
		(start 159.765492 -69.011292)
		(end 159.004 -68.2498)
		(width 0.127)
		(layer "F.Cu")
		(net "VSENSE_PVCCIO_CPU1_SKT_VRTN")
	)
	(via
		(at 160.88614 -68.48094)
		(size 0.508)
		(drill 0.254)
		(layers "F.Cu" "B.Cu")
		(net "VSENSE_PVCCIO_CPU1_SKT_VRTN")
	)
	(via
		(at 139.387834 -73.735184)
		(size 0.508)
		(drill 0.254)
		(layers "F.Cu" "B.Cu")
		(net "VSENSE_PVCCIO_CPU1_SKT_VRTN")
	)
	(segment
		(start 153.550874 -75.106784)
		(end 143.049498 -75.106784)
		(width 0.127)
		(layer "In2.Cu")
		(net "VSENSE_PVCCIO_CPU1_SKT_VRTN")
	)
	(segment
		(start 160.38068 -68.9864)
		(end 159.671258 -68.9864)
		(width 0.127)
		(layer "In2.Cu")
		(net "VSENSE_PVCCIO_CPU1_SKT_VRTN")
	)
	(segment
		(start 159.671258 -68.9864)
		(end 153.550874 -75.106784)
		(width 0.127)
		(layer "In2.Cu")
		(net "VSENSE_PVCCIO_CPU1_SKT_VRTN")
	)
	(segment
		(start 160.88614 -68.48094)
		(end 160.38068 -68.9864)
		(width 0.127)
		(layer "In2.Cu")
		(net "VSENSE_PVCCIO_CPU1_SKT_VRTN")
	)
	(segment
		(start 140.448792 -74.630534)
		(end 140.241528 -74.630534)
		(width 0.0889)
		(layer "In2.Cu")
		(net "VSENSE_PVCCIO_CPU1_SKT_VRTN")
	)
	(segment
		(start 139.452858 -74.138282)
		(end 139.387834 -74.073258)
		(width 0.0889)
		(layer "In2.Cu")
		(net "VSENSE_PVCCIO_CPU1_SKT_VRTN")
	)
	(segment
		(start 143.00835 -75.125834)
		(end 141.014196 -75.125834)
		(width 0.0889)
		(layer "In2.Cu")
		(net "VSENSE_PVCCIO_CPU1_SKT_VRTN")
	)
	(segment
		(start 143.0274 -75.106784)
		(end 143.00835 -75.125834)
		(width 0.0889)
		(layer "In2.Cu")
		(net "VSENSE_PVCCIO_CPU1_SKT_VRTN")
	)
	(segment
		(start 143.049498 -75.106784)
		(end 143.0274 -75.106784)
		(width 0.0889)
		(layer "In2.Cu")
		(net "VSENSE_PVCCIO_CPU1_SKT_VRTN")
	)
	(segment
		(start 139.387834 -74.073258)
		(end 139.387834 -73.735184)
		(width 0.0889)
		(layer "In2.Cu")
		(net "VSENSE_PVCCIO_CPU1_SKT_VRTN")
	)
	(arc
		(start 139.899644 -74.430382)
		(mid 139.711116 -74.231009)
		(end 139.452858 -74.138282)
		(width 0.0889)
		(layer "In2.Cu")
		(net "VSENSE_PVCCIO_CPU1_SKT_VRTN")
	)
	(arc
		(start 140.241528 -74.630534)
		(mid 140.044093 -74.575711)
		(end 139.899644 -74.430382)
		(width 0.0889)
		(layer "In2.Cu")
		(net "VSENSE_PVCCIO_CPU1_SKT_VRTN")
	)
	(arc
		(start 140.798042 -74.92873)
		(mid 140.651812 -74.746382)
		(end 140.448792 -74.630534)
		(width 0.0889)
		(layer "In2.Cu")
		(net "VSENSE_PVCCIO_CPU1_SKT_VRTN")
	)
	(arc
		(start 141.014196 -75.125834)
		(mid 140.888995 -75.046063)
		(end 140.798042 -74.92873)
		(width 0.0889)
		(layer "In2.Cu")
		(net "VSENSE_PVCCIO_CPU1_SKT_VRTN")
	)
	(segment
		(start 164.084 -64.512952)
		(end 164.084 -64.9224)
		(width 0.127)
		(layer "F.Cu")
		(net "VSENSE_PVCCIO_CPU1_AVSP")
	)
	(segment
		(start 163.400232 -63.829184)
		(end 164.084 -64.512952)
		(width 0.127)
		(layer "F.Cu")
		(net "VSENSE_PVCCIO_CPU1_AVSP")
	)
	(segment
		(start 162.871912 -63.829184)
		(end 163.400232 -63.829184)
		(width 0.127)
		(layer "F.Cu")
		(net "VSENSE_PVCCIO_CPU1_AVSP")
	)
	(segment
		(start 162.8394 -63.861696)
		(end 162.871912 -63.829184)
		(width 0.127)
		(layer "F.Cu")
		(net "VSENSE_PVCCIO_CPU1_AVSP")
	)
	(segment
		(start 162.8394 -64.8716)
		(end 162.8394 -63.861696)
		(width 0.127)
		(layer "F.Cu")
		(net "VSENSE_PVCCIO_CPU1_AVSP")
	)
	(segment
		(start 303.816766 -74.725784)
		(end 304.388266 -74.725784)
		(width 0.127)
		(layer "F.Cu")
		(net "VSENSE_PVCCIO_CPU0_SKT_VSEN")
	)
	(via
		(at 342.536526 -53.07584)
		(size 0.508)
		(drill 0.254)
		(layers "F.Cu" "B.Cu")
		(net "VSENSE_PVCCIO_CPU0_SKT_VSEN")
	)
	(via
		(at 304.388266 -74.725784)
		(size 0.508)
		(drill 0.254)
		(layers "F.Cu" "B.Cu")
		(net "VSENSE_PVCCIO_CPU0_SKT_VSEN")
	)
	(via
		(at 352.967798 -65.566798)
		(size 0.508)
		(drill 0.254)
		(layers "F.Cu" "B.Cu")
		(net "VSENSE_PVCCIO_CPU0_SKT_VSEN")
	)
	(segment
		(start 351.180654 -68.9356)
		(end 352.552 -67.564254)
		(width 0.127)
		(layer "B.Cu")
		(net "VSENSE_PVCCIO_CPU0_SKT_VSEN")
	)
	(segment
		(start 343.07018 -52.905914)
		(end 343.07018 -52.078128)
		(width 0.127)
		(layer "B.Cu")
		(net "VSENSE_PVCCIO_CPU0_SKT_VSEN")
	)
	(segment
		(start 360.863642 -75.1713)
		(end 350.01708 -75.1713)
		(width 0.127)
		(layer "B.Cu")
		(net "VSENSE_PVCCIO_CPU0_SKT_VSEN")
	)
	(segment
		(start 342.536526 -53.07584)
		(end 342.900254 -53.07584)
		(width 0.127)
		(layer "B.Cu")
		(net "VSENSE_PVCCIO_CPU0_SKT_VSEN")
	)
	(segment
		(start 361.9246 -76.232258)
		(end 360.863642 -75.1713)
		(width 0.127)
		(layer "B.Cu")
		(net "VSENSE_PVCCIO_CPU0_SKT_VSEN")
	)
	(segment
		(start 346.74937 -54.42077)
		(end 348.816168 -56.487568)
		(width 0.127)
		(layer "B.Cu")
		(net "VSENSE_PVCCIO_CPU0_SKT_VSEN")
	)
	(segment
		(start 355.349048 -86.312248)
		(end 355.349048 -86.93404)
		(width 0.127)
		(layer "B.Cu")
		(net "VSENSE_PVCCIO_CPU0_SKT_VSEN")
	)
	(segment
		(start 355.0158 -84.7852)
		(end 357.163878 -82.637122)
		(width 0.127)
		(layer "B.Cu")
		(net "VSENSE_PVCCIO_CPU0_SKT_VSEN")
	)
	(segment
		(start 357.163878 -82.637122)
		(end 359.449624 -82.637122)
		(width 0.127)
		(layer "B.Cu")
		(net "VSENSE_PVCCIO_CPU0_SKT_VSEN")
	)
	(segment
		(start 361.9246 -80.162146)
		(end 361.9246 -76.232258)
		(width 0.127)
		(layer "B.Cu")
		(net "VSENSE_PVCCIO_CPU0_SKT_VSEN")
	)
	(segment
		(start 355.348794 -85.981794)
		(end 355.0158 -85.6488)
		(width 0.127)
		(layer "B.Cu")
		(net "VSENSE_PVCCIO_CPU0_SKT_VSEN")
	)
	(segment
		(start 356.455218 -59.5884)
		(end 356.455218 -62.079378)
		(width 0.127)
		(layer "B.Cu")
		(net "VSENSE_PVCCIO_CPU0_SKT_VSEN")
	)
	(segment
		(start 343.35339 -51.794918)
		(end 345.871546 -51.794918)
		(width 0.127)
		(layer "B.Cu")
		(net "VSENSE_PVCCIO_CPU0_SKT_VSEN")
	)
	(segment
		(start 359.449624 -82.637122)
		(end 361.9246 -80.162146)
		(width 0.127)
		(layer "B.Cu")
		(net "VSENSE_PVCCIO_CPU0_SKT_VSEN")
	)
	(segment
		(start 354.52304 -56.487568)
		(end 355.373178 -55.63743)
		(width 0.127)
		(layer "B.Cu")
		(net "VSENSE_PVCCIO_CPU0_SKT_VSEN")
	)
	(segment
		(start 345.871546 -51.794918)
		(end 346.74937 -52.672742)
		(width 0.127)
		(layer "B.Cu")
		(net "VSENSE_PVCCIO_CPU0_SKT_VSEN")
	)
	(segment
		(start 352.552 -65.982596)
		(end 352.967798 -65.566798)
		(width 0.127)
		(layer "B.Cu")
		(net "VSENSE_PVCCIO_CPU0_SKT_VSEN")
	)
	(segment
		(start 346.74937 -52.672742)
		(end 346.74937 -54.42077)
		(width 0.127)
		(layer "B.Cu")
		(net "VSENSE_PVCCIO_CPU0_SKT_VSEN")
	)
	(segment
		(start 357.469948 -55.63743)
		(end 358.345232 -56.512714)
		(width 0.127)
		(layer "B.Cu")
		(net "VSENSE_PVCCIO_CPU0_SKT_VSEN")
	)
	(segment
		(start 350.01708 -75.1713)
		(end 348.3102 -73.46442)
		(width 0.127)
		(layer "B.Cu")
		(net "VSENSE_PVCCIO_CPU0_SKT_VSEN")
	)
	(segment
		(start 358.345232 -56.512714)
		(end 358.345232 -57.698386)
		(width 0.127)
		(layer "B.Cu")
		(net "VSENSE_PVCCIO_CPU0_SKT_VSEN")
	)
	(segment
		(start 348.816168 -56.487568)
		(end 354.52304 -56.487568)
		(width 0.127)
		(layer "B.Cu")
		(net "VSENSE_PVCCIO_CPU0_SKT_VSEN")
	)
	(segment
		(start 355.349048 -86.312248)
		(end 355.348794 -85.981794)
		(width 0.127)
		(layer "B.Cu")
		(net "VSENSE_PVCCIO_CPU0_SKT_VSEN")
	)
	(segment
		(start 343.07018 -52.078128)
		(end 343.35339 -51.794918)
		(width 0.127)
		(layer "B.Cu")
		(net "VSENSE_PVCCIO_CPU0_SKT_VSEN")
	)
	(segment
		(start 355.373178 -55.63743)
		(end 357.469948 -55.63743)
		(width 0.127)
		(layer "B.Cu")
		(net "VSENSE_PVCCIO_CPU0_SKT_VSEN")
	)
	(segment
		(start 348.3102 -71.178674)
		(end 350.553274 -68.9356)
		(width 0.127)
		(layer "B.Cu")
		(net "VSENSE_PVCCIO_CPU0_SKT_VSEN")
	)
	(segment
		(start 358.345232 -57.698386)
		(end 356.455218 -59.5884)
		(width 0.127)
		(layer "B.Cu")
		(net "VSENSE_PVCCIO_CPU0_SKT_VSEN")
	)
	(segment
		(start 348.3102 -73.46442)
		(end 348.3102 -71.178674)
		(width 0.127)
		(layer "B.Cu")
		(net "VSENSE_PVCCIO_CPU0_SKT_VSEN")
	)
	(segment
		(start 350.553274 -68.9356)
		(end 351.180654 -68.9356)
		(width 0.127)
		(layer "B.Cu")
		(net "VSENSE_PVCCIO_CPU0_SKT_VSEN")
	)
	(segment
		(start 342.900254 -53.07584)
		(end 343.07018 -52.905914)
		(width 0.127)
		(layer "B.Cu")
		(net "VSENSE_PVCCIO_CPU0_SKT_VSEN")
	)
	(segment
		(start 356.455218 -62.079378)
		(end 352.967798 -65.566798)
		(width 0.127)
		(layer "B.Cu")
		(net "VSENSE_PVCCIO_CPU0_SKT_VSEN")
	)
	(segment
		(start 355.0158 -85.6488)
		(end 355.0158 -84.7852)
		(width 0.127)
		(layer "B.Cu")
		(net "VSENSE_PVCCIO_CPU0_SKT_VSEN")
	)
	(segment
		(start 352.552 -67.564254)
		(end 352.552 -65.982596)
		(width 0.127)
		(layer "B.Cu")
		(net "VSENSE_PVCCIO_CPU0_SKT_VSEN")
	)
	(segment
		(start 307.515514 -75.338178)
		(end 307.493416 -75.31608)
		(width 0.0889)
		(layer "In2.Cu")
		(net "VSENSE_PVCCIO_CPU0_SKT_VSEN")
	)
	(segment
		(start 342.536526 -53.07584)
		(end 342.70823 -53.07584)
		(width 0.127)
		(layer "In2.Cu")
		(net "VSENSE_PVCCIO_CPU0_SKT_VSEN")
	)
	(segment
		(start 331.301598 -50.64633)
		(end 317.951866 -63.996062)
		(width 0.127)
		(layer "In2.Cu")
		(net "VSENSE_PVCCIO_CPU0_SKT_VSEN")
	)
	(segment
		(start 305.496722 -75.31608)
		(end 304.828956 -74.648568)
		(width 0.0889)
		(layer "In2.Cu")
		(net "VSENSE_PVCCIO_CPU0_SKT_VSEN")
	)
	(segment
		(start 317.951866 -67.257676)
		(end 309.871364 -75.338178)
		(width 0.127)
		(layer "In2.Cu")
		(net "VSENSE_PVCCIO_CPU0_SKT_VSEN")
	)
	(segment
		(start 342.70823 -53.07584)
		(end 342.83523 -52.94884)
		(width 0.127)
		(layer "In2.Cu")
		(net "VSENSE_PVCCIO_CPU0_SKT_VSEN")
	)
	(segment
		(start 340.842346 -50.64633)
		(end 331.301598 -50.64633)
		(width 0.127)
		(layer "In2.Cu")
		(net "VSENSE_PVCCIO_CPU0_SKT_VSEN")
	)
	(segment
		(start 342.83523 -52.639214)
		(end 340.842346 -50.64633)
		(width 0.127)
		(layer "In2.Cu")
		(net "VSENSE_PVCCIO_CPU0_SKT_VSEN")
	)
	(segment
		(start 304.446178 -74.329798)
		(end 304.388266 -74.38771)
		(width 0.0889)
		(layer "In2.Cu")
		(net "VSENSE_PVCCIO_CPU0_SKT_VSEN")
	)
	(segment
		(start 307.493416 -75.31608)
		(end 305.496722 -75.31608)
		(width 0.0889)
		(layer "In2.Cu")
		(net "VSENSE_PVCCIO_CPU0_SKT_VSEN")
	)
	(segment
		(start 309.871364 -75.338178)
		(end 307.515514 -75.338178)
		(width 0.127)
		(layer "In2.Cu")
		(net "VSENSE_PVCCIO_CPU0_SKT_VSEN")
	)
	(segment
		(start 342.83523 -52.94884)
		(end 342.83523 -52.639214)
		(width 0.127)
		(layer "In2.Cu")
		(net "VSENSE_PVCCIO_CPU0_SKT_VSEN")
	)
	(segment
		(start 304.388266 -74.38771)
		(end 304.388266 -74.725784)
		(width 0.0889)
		(layer "In2.Cu")
		(net "VSENSE_PVCCIO_CPU0_SKT_VSEN")
	)
	(segment
		(start 317.951866 -63.996062)
		(end 317.951866 -67.257676)
		(width 0.127)
		(layer "In2.Cu")
		(net "VSENSE_PVCCIO_CPU0_SKT_VSEN")
	)
	(arc
		(start 304.734976 -74.525886)
		(mid 304.613085 -74.39469)
		(end 304.446178 -74.329798)
		(width 0.0889)
		(layer "In2.Cu")
		(net "VSENSE_PVCCIO_CPU0_SKT_VSEN")
	)
	(arc
		(start 304.828956 -74.648568)
		(mid 304.777941 -74.590311)
		(end 304.734976 -74.525886)
		(width 0.0889)
		(layer "In2.Cu")
		(net "VSENSE_PVCCIO_CPU0_SKT_VSEN")
	)
	(segment
		(start 303.816766 -73.735184)
		(end 304.388266 -73.735184)
		(width 0.127)
		(layer "F.Cu")
		(net "VSENSE_PVCCIO_CPU0_SKT_VRTN")
	)
	(via
		(at 343.806526 -53.07584)
		(size 0.508)
		(drill 0.254)
		(layers "F.Cu" "B.Cu")
		(net "VSENSE_PVCCIO_CPU0_SKT_VRTN")
	)
	(via
		(at 355.06914 -63.14186)
		(size 0.508)
		(drill 0.254)
		(layers "F.Cu" "B.Cu")
		(net "VSENSE_PVCCIO_CPU0_SKT_VRTN")
	)
	(via
		(at 304.388266 -73.735184)
		(size 0.508)
		(drill 0.254)
		(layers "F.Cu" "B.Cu")
		(net "VSENSE_PVCCIO_CPU0_SKT_VRTN")
	)
	(segment
		(start 348.0816 -73.559162)
		(end 348.0816 -71.083932)
		(width 0.127)
		(layer "B.Cu")
		(net "VSENSE_PVCCIO_CPU0_SKT_VRTN")
	)
	(segment
		(start 343.448132 -52.023518)
		(end 345.776804 -52.023518)
		(width 0.127)
		(layer "B.Cu")
		(net "VSENSE_PVCCIO_CPU0_SKT_VRTN")
	)
	(segment
		(start 354.7872 -85.6488)
		(end 354.7872 -84.690458)
		(width 0.127)
		(layer "B.Cu")
		(net "VSENSE_PVCCIO_CPU0_SKT_VRTN")
	)
	(segment
		(start 360.7689 -75.3999)
		(end 349.922338 -75.3999)
		(width 0.127)
		(layer "B.Cu")
		(net "VSENSE_PVCCIO_CPU0_SKT_VRTN")
	)
	(segment
		(start 350.458532 -68.707)
		(end 351.085912 -68.707)
		(width 0.127)
		(layer "B.Cu")
		(net "VSENSE_PVCCIO_CPU0_SKT_VRTN")
	)
	(segment
		(start 346.52077 -54.515512)
		(end 348.721426 -56.716168)
		(width 0.127)
		(layer "B.Cu")
		(net "VSENSE_PVCCIO_CPU0_SKT_VRTN")
	)
	(segment
		(start 355.46792 -55.86603)
		(end 357.375206 -55.86603)
		(width 0.127)
		(layer "B.Cu")
		(net "VSENSE_PVCCIO_CPU0_SKT_VRTN")
	)
	(segment
		(start 343.29878 -52.17287)
		(end 343.448132 -52.023518)
		(width 0.127)
		(layer "B.Cu")
		(net "VSENSE_PVCCIO_CPU0_SKT_VRTN")
	)
	(segment
		(start 346.52077 -52.767484)
		(end 346.52077 -54.515512)
		(width 0.127)
		(layer "B.Cu")
		(net "VSENSE_PVCCIO_CPU0_SKT_VRTN")
	)
	(segment
		(start 348.0816 -71.083932)
		(end 350.458532 -68.707)
		(width 0.127)
		(layer "B.Cu")
		(net "VSENSE_PVCCIO_CPU0_SKT_VRTN")
	)
	(segment
		(start 356.226618 -59.493658)
		(end 356.226618 -61.984636)
		(width 0.127)
		(layer "B.Cu")
		(net "VSENSE_PVCCIO_CPU0_SKT_VRTN")
	)
	(segment
		(start 354.460048 -86.312248)
		(end 354.460048 -86.93404)
		(width 0.127)
		(layer "B.Cu")
		(net "VSENSE_PVCCIO_CPU0_SKT_VRTN")
	)
	(segment
		(start 343.469214 -53.07584)
		(end 343.29878 -52.905406)
		(width 0.127)
		(layer "B.Cu")
		(net "VSENSE_PVCCIO_CPU0_SKT_VRTN")
	)
	(segment
		(start 357.069136 -82.408522)
		(end 359.354882 -82.408522)
		(width 0.127)
		(layer "B.Cu")
		(net "VSENSE_PVCCIO_CPU0_SKT_VRTN")
	)
	(segment
		(start 351.085912 -68.707)
		(end 352.3234 -67.469512)
		(width 0.127)
		(layer "B.Cu")
		(net "VSENSE_PVCCIO_CPU0_SKT_VRTN")
	)
	(segment
		(start 343.806526 -53.07584)
		(end 343.469214 -53.07584)
		(width 0.127)
		(layer "B.Cu")
		(net "VSENSE_PVCCIO_CPU0_SKT_VRTN")
	)
	(segment
		(start 355.069394 -63.14186)
		(end 355.06914 -63.14186)
		(width 0.127)
		(layer "B.Cu")
		(net "VSENSE_PVCCIO_CPU0_SKT_VRTN")
	)
	(segment
		(start 348.721426 -56.716168)
		(end 354.617782 -56.716168)
		(width 0.127)
		(layer "B.Cu")
		(net "VSENSE_PVCCIO_CPU0_SKT_VRTN")
	)
	(segment
		(start 349.922338 -75.3999)
		(end 348.0816 -73.559162)
		(width 0.127)
		(layer "B.Cu")
		(net "VSENSE_PVCCIO_CPU0_SKT_VRTN")
	)
	(segment
		(start 354.460048 -85.975952)
		(end 354.7872 -85.6488)
		(width 0.127)
		(layer "B.Cu")
		(net "VSENSE_PVCCIO_CPU0_SKT_VRTN")
	)
	(segment
		(start 357.375206 -55.86603)
		(end 358.116632 -56.607456)
		(width 0.127)
		(layer "B.Cu")
		(net "VSENSE_PVCCIO_CPU0_SKT_VRTN")
	)
	(segment
		(start 354.617782 -56.716168)
		(end 355.46792 -55.86603)
		(width 0.127)
		(layer "B.Cu")
		(net "VSENSE_PVCCIO_CPU0_SKT_VRTN")
	)
	(segment
		(start 354.7872 -84.690458)
		(end 357.069136 -82.408522)
		(width 0.127)
		(layer "B.Cu")
		(net "VSENSE_PVCCIO_CPU0_SKT_VRTN")
	)
	(segment
		(start 343.29878 -52.905406)
		(end 343.29878 -52.17287)
		(width 0.127)
		(layer "B.Cu")
		(net "VSENSE_PVCCIO_CPU0_SKT_VRTN")
	)
	(segment
		(start 352.3234 -67.469512)
		(end 352.3234 -65.887854)
		(width 0.127)
		(layer "B.Cu")
		(net "VSENSE_PVCCIO_CPU0_SKT_VRTN")
	)
	(segment
		(start 345.776804 -52.023518)
		(end 346.52077 -52.767484)
		(width 0.127)
		(layer "B.Cu")
		(net "VSENSE_PVCCIO_CPU0_SKT_VRTN")
	)
	(segment
		(start 355.06914 -63.142114)
		(end 355.06914 -63.14186)
		(width 0.127)
		(layer "B.Cu")
		(net "VSENSE_PVCCIO_CPU0_SKT_VRTN")
	)
	(segment
		(start 358.116632 -56.607456)
		(end 358.116632 -57.603644)
		(width 0.127)
		(layer "B.Cu")
		(net "VSENSE_PVCCIO_CPU0_SKT_VRTN")
	)
	(segment
		(start 361.696 -76.327)
		(end 360.7689 -75.3999)
		(width 0.127)
		(layer "B.Cu")
		(net "VSENSE_PVCCIO_CPU0_SKT_VRTN")
	)
	(segment
		(start 352.3234 -65.887854)
		(end 355.06914 -63.142114)
		(width 0.127)
		(layer "B.Cu")
		(net "VSENSE_PVCCIO_CPU0_SKT_VRTN")
	)
	(segment
		(start 354.460048 -86.312248)
		(end 354.460048 -85.975952)
		(width 0.127)
		(layer "B.Cu")
		(net "VSENSE_PVCCIO_CPU0_SKT_VRTN")
	)
	(segment
		(start 358.116632 -57.603644)
		(end 356.226618 -59.493658)
		(width 0.127)
		(layer "B.Cu")
		(net "VSENSE_PVCCIO_CPU0_SKT_VRTN")
	)
	(segment
		(start 361.696 -80.067404)
		(end 361.696 -76.327)
		(width 0.127)
		(layer "B.Cu")
		(net "VSENSE_PVCCIO_CPU0_SKT_VRTN")
	)
	(segment
		(start 356.226618 -61.984636)
		(end 355.069394 -63.14186)
		(width 0.127)
		(layer "B.Cu")
		(net "VSENSE_PVCCIO_CPU0_SKT_VRTN")
	)
	(segment
		(start 359.354882 -82.408522)
		(end 361.696 -80.067404)
		(width 0.127)
		(layer "B.Cu")
		(net "VSENSE_PVCCIO_CPU0_SKT_VRTN")
	)
	(segment
		(start 331.206856 -50.41773)
		(end 317.723266 -63.90132)
		(width 0.127)
		(layer "In2.Cu")
		(net "VSENSE_PVCCIO_CPU0_SKT_VRTN")
	)
	(segment
		(start 304.388266 -74.073258)
		(end 304.388266 -73.735184)
		(width 0.0889)
		(layer "In2.Cu")
		(net "VSENSE_PVCCIO_CPU0_SKT_VRTN")
	)
	(segment
		(start 305.575716 -75.12558)
		(end 304.96383 -74.513694)
		(width 0.0889)
		(layer "In2.Cu")
		(net "VSENSE_PVCCIO_CPU0_SKT_VRTN")
	)
	(segment
		(start 340.937088 -50.41773)
		(end 331.206856 -50.41773)
		(width 0.127)
		(layer "In2.Cu")
		(net "VSENSE_PVCCIO_CPU0_SKT_VRTN")
	)
	(segment
		(start 343.450926 -53.07584)
		(end 343.06383 -52.688744)
		(width 0.127)
		(layer "In2.Cu")
		(net "VSENSE_PVCCIO_CPU0_SKT_VRTN")
	)
	(segment
		(start 343.06383 -52.544472)
		(end 340.937088 -50.41773)
		(width 0.127)
		(layer "In2.Cu")
		(net "VSENSE_PVCCIO_CPU0_SKT_VRTN")
	)
	(segment
		(start 343.806526 -53.07584)
		(end 343.450926 -53.07584)
		(width 0.127)
		(layer "In2.Cu")
		(net "VSENSE_PVCCIO_CPU0_SKT_VRTN")
	)
	(segment
		(start 304.453544 -74.138536)
		(end 304.388266 -74.073258)
		(width 0.0889)
		(layer "In2.Cu")
		(net "VSENSE_PVCCIO_CPU0_SKT_VRTN")
	)
	(segment
		(start 307.515514 -75.109578)
		(end 307.499512 -75.12558)
		(width 0.0889)
		(layer "In2.Cu")
		(net "VSENSE_PVCCIO_CPU0_SKT_VRTN")
	)
	(segment
		(start 343.06383 -52.688744)
		(end 343.06383 -52.544472)
		(width 0.127)
		(layer "In2.Cu")
		(net "VSENSE_PVCCIO_CPU0_SKT_VRTN")
	)
	(segment
		(start 307.499512 -75.12558)
		(end 305.575716 -75.12558)
		(width 0.0889)
		(layer "In2.Cu")
		(net "VSENSE_PVCCIO_CPU0_SKT_VRTN")
	)
	(segment
		(start 309.776622 -75.109578)
		(end 307.515514 -75.109578)
		(width 0.127)
		(layer "In2.Cu")
		(net "VSENSE_PVCCIO_CPU0_SKT_VRTN")
	)
	(segment
		(start 317.723266 -63.90132)
		(end 317.723266 -67.162934)
		(width 0.127)
		(layer "In2.Cu")
		(net "VSENSE_PVCCIO_CPU0_SKT_VRTN")
	)
	(segment
		(start 317.723266 -67.162934)
		(end 309.776622 -75.109578)
		(width 0.127)
		(layer "In2.Cu")
		(net "VSENSE_PVCCIO_CPU0_SKT_VRTN")
	)
	(arc
		(start 304.96383 -74.513694)
		(mid 304.929224 -74.474259)
		(end 304.900076 -74.430636)
		(width 0.0889)
		(layer "In2.Cu")
		(net "VSENSE_PVCCIO_CPU0_SKT_VRTN")
	)
	(arc
		(start 304.900076 -74.430636)
		(mid 304.711653 -74.231332)
		(end 304.453544 -74.138536)
		(width 0.0889)
		(layer "In2.Cu")
		(net "VSENSE_PVCCIO_CPU0_SKT_VRTN")
	)
	(via
		(at 338.709 -90.551)
		(size 0.6604)
		(drill 0.3302)
		(layers "F.Cu" "B.Cu")
		(net "VSENSE_PVCCIO_CPU0_AVSP")
	)
	(via
		(at 340.856316 -91.533472)
		(size 0.508)
		(drill 0.254)
		(layers "F.Cu" "B.Cu")
		(net "VSENSE_PVCCIO_CPU0_AVSP")
	)
	(via
		(at 354.14204 -89.19718)
		(size 0.508)
		(drill 0.254)
		(layers "F.Cu" "B.Cu")
		(net "VSENSE_PVCCIO_CPU0_AVSP")
	)
	(segment
		(start 338.709 -90.551)
		(end 339.691472 -91.533472)
		(width 0.127)
		(layer "B.Cu")
		(net "VSENSE_PVCCIO_CPU0_AVSP")
	)
	(segment
		(start 339.717126 -90.049604)
		(end 339.210396 -90.049604)
		(width 0.127)
		(layer "B.Cu")
		(net "VSENSE_PVCCIO_CPU0_AVSP")
	)
	(segment
		(start 354.267262 -88.64092)
		(end 354.631244 -88.64092)
		(width 0.127)
		(layer "B.Cu")
		(net "VSENSE_PVCCIO_CPU0_AVSP")
	)
	(segment
		(start 354.597208 -89.97188)
		(end 354.14204 -89.516712)
		(width 0.127)
		(layer "B.Cu")
		(net "VSENSE_PVCCIO_CPU0_AVSP")
	)
	(segment
		(start 354.141278 -88.766904)
		(end 354.267262 -88.64092)
		(width 0.127)
		(layer "B.Cu")
		(net "VSENSE_PVCCIO_CPU0_AVSP")
	)
	(segment
		(start 339.210396 -90.049604)
		(end 338.709 -90.551)
		(width 0.127)
		(layer "B.Cu")
		(net "VSENSE_PVCCIO_CPU0_AVSP")
	)
	(segment
		(start 354.14204 -89.19718)
		(end 354.141278 -88.766904)
		(width 0.127)
		(layer "B.Cu")
		(net "VSENSE_PVCCIO_CPU0_AVSP")
	)
	(segment
		(start 355.0158 -87.800688)
		(end 355.349048 -87.46744)
		(width 0.127)
		(layer "B.Cu")
		(net "VSENSE_PVCCIO_CPU0_AVSP")
	)
	(segment
		(start 355.0158 -88.256364)
		(end 355.0158 -87.800688)
		(width 0.127)
		(layer "B.Cu")
		(net "VSENSE_PVCCIO_CPU0_AVSP")
	)
	(segment
		(start 354.631244 -88.64092)
		(end 355.0158 -88.256364)
		(width 0.127)
		(layer "B.Cu")
		(net "VSENSE_PVCCIO_CPU0_AVSP")
	)
	(segment
		(start 339.691472 -91.533472)
		(end 340.856316 -91.533472)
		(width 0.127)
		(layer "B.Cu")
		(net "VSENSE_PVCCIO_CPU0_AVSP")
	)
	(segment
		(start 354.14204 -89.516712)
		(end 354.14204 -89.19718)
		(width 0.127)
		(layer "B.Cu")
		(net "VSENSE_PVCCIO_CPU0_AVSP")
	)
	(segment
		(start 340.856316 -91.533472)
		(end 340.856062 -91.533472)
		(width 0.127)
		(layer "In11.Cu")
		(net "VSENSE_PVCCIO_CPU0_AVSP")
	)
	(segment
		(start 342.09736 -92.2528)
		(end 343.540588 -90.809572)
		(width 0.127)
		(layer "In11.Cu")
		(net "VSENSE_PVCCIO_CPU0_AVSP")
	)
	(segment
		(start 341.57539 -92.2528)
		(end 342.09736 -92.2528)
		(width 0.127)
		(layer "In11.Cu")
		(net "VSENSE_PVCCIO_CPU0_AVSP")
	)
	(segment
		(start 352.056954 -90.809572)
		(end 353.669346 -89.19718)
		(width 0.127)
		(layer "In11.Cu")
		(net "VSENSE_PVCCIO_CPU0_AVSP")
	)
	(segment
		(start 343.540588 -90.809572)
		(end 352.056954 -90.809572)
		(width 0.127)
		(layer "In11.Cu")
		(net "VSENSE_PVCCIO_CPU0_AVSP")
	)
	(segment
		(start 340.856062 -91.533472)
		(end 341.57539 -92.2528)
		(width 0.127)
		(layer "In11.Cu")
		(net "VSENSE_PVCCIO_CPU0_AVSP")
	)
	(segment
		(start 353.669346 -89.19718)
		(end 354.14204 -89.19718)
		(width 0.127)
		(layer "In11.Cu")
		(net "VSENSE_PVCCIO_CPU0_AVSP")
	)
	(segment
		(start 41.348152 -50.9651)
		(end 40.954452 -50.5714)
		(width 0.127)
		(layer "F.Cu")
		(net "VSENSE_PVCCIN_CPU1_SKT_VSEN")
	)
	(segment
		(start 40.954452 -50.5714)
		(end 40.5638 -50.5714)
		(width 0.127)
		(layer "F.Cu")
		(net "VSENSE_PVCCIN_CPU1_SKT_VSEN")
	)
	(segment
		(start 67.749166 -69.45884)
		(end 67.101466 -69.45884)
		(width 0.127)
		(layer "F.Cu")
		(net "VSENSE_PVCCIN_CPU1_SKT_VSEN")
	)
	(via
		(at 41.348152 -50.9651)
		(size 0.508)
		(drill 0.254)
		(layers "F.Cu" "B.Cu")
		(net "VSENSE_PVCCIN_CPU1_SKT_VSEN")
	)
	(via
		(at 67.101466 -69.45884)
		(size 0.508)
		(drill 0.254)
		(layers "F.Cu" "B.Cu")
		(net "VSENSE_PVCCIN_CPU1_SKT_VSEN")
	)
	(segment
		(start 67.333368 -68.983606)
		(end 67.407536 -69.123814)
		(width 0.127)
		(layer "In2.Cu")
		(net "VSENSE_PVCCIN_CPU1_SKT_VSEN")
	)
	(segment
		(start 61.743082 -69.035422)
		(end 65.292732 -69.035422)
		(width 0.127)
		(layer "In2.Cu")
		(net "VSENSE_PVCCIN_CPU1_SKT_VSEN")
	)
	(segment
		(start 43.07586 -50.3682)
		(end 61.743082 -69.035422)
		(width 0.127)
		(layer "In2.Cu")
		(net "VSENSE_PVCCIN_CPU1_SKT_VSEN")
	)
	(segment
		(start 67.107562 -68.7578)
		(end 67.333368 -68.983606)
		(width 0.127)
		(layer "In2.Cu")
		(net "VSENSE_PVCCIN_CPU1_SKT_VSEN")
	)
	(segment
		(start 41.348152 -50.9143)
		(end 41.894252 -50.3682)
		(width 0.127)
		(layer "In2.Cu")
		(net "VSENSE_PVCCIN_CPU1_SKT_VSEN")
	)
	(segment
		(start 67.407536 -69.123814)
		(end 67.344798 -69.329808)
		(width 0.127)
		(layer "In2.Cu")
		(net "VSENSE_PVCCIN_CPU1_SKT_VSEN")
	)
	(segment
		(start 65.292732 -69.035422)
		(end 65.570354 -68.7578)
		(width 0.127)
		(layer "In2.Cu")
		(net "VSENSE_PVCCIN_CPU1_SKT_VSEN")
	)
	(segment
		(start 41.348152 -50.9651)
		(end 41.348152 -50.9143)
		(width 0.127)
		(layer "In2.Cu")
		(net "VSENSE_PVCCIN_CPU1_SKT_VSEN")
	)
	(segment
		(start 41.894252 -50.3682)
		(end 43.07586 -50.3682)
		(width 0.127)
		(layer "In2.Cu")
		(net "VSENSE_PVCCIN_CPU1_SKT_VSEN")
	)
	(segment
		(start 67.344798 -69.329808)
		(end 67.101466 -69.45884)
		(width 0.127)
		(layer "In2.Cu")
		(net "VSENSE_PVCCIN_CPU1_SKT_VSEN")
	)
	(segment
		(start 65.570354 -68.7578)
		(end 67.107562 -68.7578)
		(width 0.127)
		(layer "In2.Cu")
		(net "VSENSE_PVCCIN_CPU1_SKT_VSEN")
	)
	(segment
		(start 41.3512 -49.6824)
		(end 40.5638 -49.6824)
		(width 0.127)
		(layer "F.Cu")
		(net "VSENSE_PVCCIN_CPU1_SKT_VRTN")
	)
	(segment
		(start 68.607686 -68.963286)
		(end 68.036186 -68.963286)
		(width 0.127)
		(layer "F.Cu")
		(net "VSENSE_PVCCIN_CPU1_SKT_VRTN")
	)
	(via
		(at 41.3512 -49.6824)
		(size 0.508)
		(drill 0.254)
		(layers "F.Cu" "B.Cu")
		(net "VSENSE_PVCCIN_CPU1_SKT_VRTN")
	)
	(via
		(at 68.036186 -68.963286)
		(size 0.508)
		(drill 0.254)
		(layers "F.Cu" "B.Cu")
		(net "VSENSE_PVCCIN_CPU1_SKT_VRTN")
	)
	(segment
		(start 67.621658 -69.039232)
		(end 67.793362 -69.092064)
		(width 0.127)
		(layer "In2.Cu")
		(net "VSENSE_PVCCIN_CPU1_SKT_VRTN")
	)
	(segment
		(start 67.202304 -68.5292)
		(end 67.519296 -68.846192)
		(width 0.127)
		(layer "In2.Cu")
		(net "VSENSE_PVCCIN_CPU1_SKT_VRTN")
	)
	(segment
		(start 65.19799 -68.806822)
		(end 65.475612 -68.5292)
		(width 0.127)
		(layer "In2.Cu")
		(net "VSENSE_PVCCIN_CPU1_SKT_VRTN")
	)
	(segment
		(start 67.793362 -69.092064)
		(end 68.036186 -68.963286)
		(width 0.127)
		(layer "In2.Cu")
		(net "VSENSE_PVCCIN_CPU1_SKT_VRTN")
	)
	(segment
		(start 65.475612 -68.5292)
		(end 67.202304 -68.5292)
		(width 0.127)
		(layer "In2.Cu")
		(net "VSENSE_PVCCIN_CPU1_SKT_VRTN")
	)
	(segment
		(start 41.8084 -50.1396)
		(end 43.170602 -50.1396)
		(width 0.127)
		(layer "In2.Cu")
		(net "VSENSE_PVCCIN_CPU1_SKT_VRTN")
	)
	(segment
		(start 61.837824 -68.806822)
		(end 65.19799 -68.806822)
		(width 0.127)
		(layer "In2.Cu")
		(net "VSENSE_PVCCIN_CPU1_SKT_VRTN")
	)
	(segment
		(start 67.519296 -68.846192)
		(end 67.621658 -69.039232)
		(width 0.127)
		(layer "In2.Cu")
		(net "VSENSE_PVCCIN_CPU1_SKT_VRTN")
	)
	(segment
		(start 43.170602 -50.1396)
		(end 61.837824 -68.806822)
		(width 0.127)
		(layer "In2.Cu")
		(net "VSENSE_PVCCIN_CPU1_SKT_VRTN")
	)
	(segment
		(start 41.3512 -49.6824)
		(end 41.8084 -50.1396)
		(width 0.127)
		(layer "In2.Cu")
		(net "VSENSE_PVCCIN_CPU1_SKT_VRTN")
	)
	(segment
		(start 22.352 -87.3506)
		(end 21.6408 -87.3506)
		(width 0.127)
		(layer "F.Cu")
		(net "VSENSE_PVCCIN_CPU1_P")
	)
	(segment
		(start 38.9128 -50.5714)
		(end 39.6748 -50.5714)
		(width 0.127)
		(layer "F.Cu")
		(net "VSENSE_PVCCIN_CPU1_P")
	)
	(segment
		(start 38.1 -50.7619)
		(end 38.2905 -50.5714)
		(width 0.127)
		(layer "F.Cu")
		(net "VSENSE_PVCCIN_CPU1_P")
	)
	(segment
		(start 38.2905 -50.5714)
		(end 38.9128 -50.5714)
		(width 0.127)
		(layer "F.Cu")
		(net "VSENSE_PVCCIN_CPU1_P")
	)
	(via
		(at 22.352 -87.3506)
		(size 0.508)
		(drill 0.254)
		(layers "F.Cu" "B.Cu")
		(net "VSENSE_PVCCIN_CPU1_P")
	)
	(via
		(at 38.1 -50.7619)
		(size 0.508)
		(drill 0.254)
		(layers "F.Cu" "B.Cu")
		(net "VSENSE_PVCCIN_CPU1_P")
	)
	(segment
		(start 38.5572 -50.2412)
		(end 38.1 -50.6984)
		(width 0.127)
		(layer "B.Cu")
		(net "VSENSE_PVCCIN_CPU1_P")
	)
	(segment
		(start 53.2638 -48.9966)
		(end 41.130728 -48.9966)
		(width 0.127)
		(layer "B.Cu")
		(net "VSENSE_PVCCIN_CPU1_P")
	)
	(segment
		(start 41.130728 -48.9966)
		(end 39.886128 -50.2412)
		(width 0.127)
		(layer "B.Cu")
		(net "VSENSE_PVCCIN_CPU1_P")
	)
	(segment
		(start 39.886128 -50.2412)
		(end 38.5572 -50.2412)
		(width 0.127)
		(layer "B.Cu")
		(net "VSENSE_PVCCIN_CPU1_P")
	)
	(segment
		(start 63.627 -59.3598)
		(end 53.2638 -48.9966)
		(width 0.127)
		(layer "B.Cu")
		(net "VSENSE_PVCCIN_CPU1_P")
	)
	(segment
		(start 38.1 -50.6984)
		(end 38.1 -50.7619)
		(width 0.127)
		(layer "B.Cu")
		(net "VSENSE_PVCCIN_CPU1_P")
	)
	(segment
		(start 63.246 -64.7954)
		(end 63.627 -64.4144)
		(width 0.127)
		(layer "B.Cu")
		(net "VSENSE_PVCCIN_CPU1_P")
	)
	(segment
		(start 63.627 -64.4144)
		(end 63.627 -59.3598)
		(width 0.127)
		(layer "B.Cu")
		(net "VSENSE_PVCCIN_CPU1_P")
	)
	(segment
		(start 25.1206 -74.288142)
		(end 25.469342 -73.9394)
		(width 0.127)
		(layer "In2.Cu")
		(net "VSENSE_PVCCIN_CPU1_P")
	)
	(segment
		(start 25.469596 -73.9394)
		(end 25.6032 -73.805796)
		(width 0.127)
		(layer "In2.Cu")
		(net "VSENSE_PVCCIN_CPU1_P")
	)
	(segment
		(start 22.97176 -85.474302)
		(end 24.918162 -83.5279)
		(width 0.127)
		(layer "In2.Cu")
		(net "VSENSE_PVCCIN_CPU1_P")
	)
	(segment
		(start 28.876244 -54.036214)
		(end 29.151326 -53.761132)
		(width 0.127)
		(layer "In2.Cu")
		(net "VSENSE_PVCCIN_CPU1_P")
	)
	(segment
		(start 22.97176 -85.911182)
		(end 22.97176 -85.474302)
		(width 0.127)
		(layer "In2.Cu")
		(net "VSENSE_PVCCIN_CPU1_P")
	)
	(segment
		(start 25.469342 -73.9394)
		(end 25.469596 -73.9394)
		(width 0.127)
		(layer "In2.Cu")
		(net "VSENSE_PVCCIN_CPU1_P")
	)
	(segment
		(start 25.1206 -78.3844)
		(end 25.1206 -74.288142)
		(width 0.127)
		(layer "In2.Cu")
		(net "VSENSE_PVCCIN_CPU1_P")
	)
	(segment
		(start 24.918162 -78.586838)
		(end 25.1206 -78.3844)
		(width 0.127)
		(layer "In2.Cu")
		(net "VSENSE_PVCCIN_CPU1_P")
	)
	(segment
		(start 28.876244 -54.658006)
		(end 28.876244 -54.036214)
		(width 0.127)
		(layer "In2.Cu")
		(net "VSENSE_PVCCIN_CPU1_P")
	)
	(segment
		(start 32.895286 -50.2412)
		(end 37.9603 -50.2412)
		(width 0.127)
		(layer "In2.Cu")
		(net "VSENSE_PVCCIN_CPU1_P")
	)
	(segment
		(start 26.6446 -56.88965)
		(end 28.876244 -54.658006)
		(width 0.127)
		(layer "In2.Cu")
		(net "VSENSE_PVCCIN_CPU1_P")
	)
	(segment
		(start 37.9603 -50.2412)
		(end 38.1 -50.3809)
		(width 0.127)
		(layer "In2.Cu")
		(net "VSENSE_PVCCIN_CPU1_P")
	)
	(segment
		(start 24.918162 -83.5279)
		(end 24.918162 -78.586838)
		(width 0.127)
		(layer "In2.Cu")
		(net "VSENSE_PVCCIN_CPU1_P")
	)
	(segment
		(start 25.6032 -69.017896)
		(end 26.6446 -67.976496)
		(width 0.127)
		(layer "In2.Cu")
		(net "VSENSE_PVCCIN_CPU1_P")
	)
	(segment
		(start 29.151326 -53.761132)
		(end 29.375354 -53.761132)
		(width 0.127)
		(layer "In2.Cu")
		(net "VSENSE_PVCCIN_CPU1_P")
	)
	(segment
		(start 22.13102 -86.751922)
		(end 22.97176 -85.911182)
		(width 0.127)
		(layer "In2.Cu")
		(net "VSENSE_PVCCIN_CPU1_P")
	)
	(segment
		(start 22.352 -87.3506)
		(end 22.13102 -87.12962)
		(width 0.127)
		(layer "In2.Cu")
		(net "VSENSE_PVCCIN_CPU1_P")
	)
	(segment
		(start 26.6446 -67.976496)
		(end 26.6446 -56.88965)
		(width 0.127)
		(layer "In2.Cu")
		(net "VSENSE_PVCCIN_CPU1_P")
	)
	(segment
		(start 29.375354 -53.761132)
		(end 32.895286 -50.2412)
		(width 0.127)
		(layer "In2.Cu")
		(net "VSENSE_PVCCIN_CPU1_P")
	)
	(segment
		(start 38.1 -50.3809)
		(end 38.1 -50.7619)
		(width 0.127)
		(layer "In2.Cu")
		(net "VSENSE_PVCCIN_CPU1_P")
	)
	(segment
		(start 25.6032 -73.805796)
		(end 25.6032 -69.017896)
		(width 0.127)
		(layer "In2.Cu")
		(net "VSENSE_PVCCIN_CPU1_P")
	)
	(segment
		(start 22.13102 -87.12962)
		(end 22.13102 -86.751922)
		(width 0.127)
		(layer "In2.Cu")
		(net "VSENSE_PVCCIN_CPU1_P")
	)
	(segment
		(start 20.831048 -89.074752)
		(end 21.6408 -88.265)
		(width 0.127)
		(layer "F.Cu")
		(net "VSENSE_PVCCIN_CPU1_N")
	)
	(segment
		(start 38.1 -49.4919)
		(end 38.2905 -49.6824)
		(width 0.127)
		(layer "F.Cu")
		(net "VSENSE_PVCCIN_CPU1_N")
	)
	(segment
		(start 38.2905 -49.6824)
		(end 38.9128 -49.6824)
		(width 0.127)
		(layer "F.Cu")
		(net "VSENSE_PVCCIN_CPU1_N")
	)
	(segment
		(start 21.7678 -88.265)
		(end 21.6408 -88.138)
		(width 0.127)
		(layer "F.Cu")
		(net "VSENSE_PVCCIN_CPU1_N")
	)
	(segment
		(start 38.9128 -49.6824)
		(end 39.6748 -49.6824)
		(width 0.127)
		(layer "F.Cu")
		(net "VSENSE_PVCCIN_CPU1_N")
	)
	(segment
		(start 21.6408 -88.265)
		(end 21.6408 -88.138)
		(width 0.127)
		(layer "F.Cu")
		(net "VSENSE_PVCCIN_CPU1_N")
	)
	(segment
		(start 20.831048 -89.5604)
		(end 20.831048 -89.074752)
		(width 0.127)
		(layer "F.Cu")
		(net "VSENSE_PVCCIN_CPU1_N")
	)
	(segment
		(start 22.3266 -88.265)
		(end 21.7678 -88.265)
		(width 0.127)
		(layer "F.Cu")
		(net "VSENSE_PVCCIN_CPU1_N")
	)
	(via
		(at 22.3266 -88.265)
		(size 0.508)
		(drill 0.254)
		(layers "F.Cu" "B.Cu")
		(net "VSENSE_PVCCIN_CPU1_N")
	)
	(via
		(at 38.1 -49.4919)
		(size 0.508)
		(drill 0.254)
		(layers "F.Cu" "B.Cu")
		(net "VSENSE_PVCCIN_CPU1_N")
	)
	(segment
		(start 63.881 -64.4144)
		(end 63.881 -59.25439)
		(width 0.127)
		(layer "B.Cu")
		(net "VSENSE_PVCCIN_CPU1_N")
	)
	(segment
		(start 64.262 -64.7954)
		(end 63.881 -64.4144)
		(width 0.127)
		(layer "B.Cu")
		(net "VSENSE_PVCCIN_CPU1_N")
	)
	(segment
		(start 39.791386 -50.0126)
		(end 38.5826 -50.0126)
		(width 0.127)
		(layer "B.Cu")
		(net "VSENSE_PVCCIN_CPU1_N")
	)
	(segment
		(start 38.1 -49.53)
		(end 38.1 -49.4919)
		(width 0.127)
		(layer "B.Cu")
		(net "VSENSE_PVCCIN_CPU1_N")
	)
	(segment
		(start 38.5826 -50.0126)
		(end 38.1 -49.53)
		(width 0.127)
		(layer "B.Cu")
		(net "VSENSE_PVCCIN_CPU1_N")
	)
	(segment
		(start 41.061386 -48.7426)
		(end 39.791386 -50.0126)
		(width 0.127)
		(layer "B.Cu")
		(net "VSENSE_PVCCIN_CPU1_N")
	)
	(segment
		(start 53.36921 -48.7426)
		(end 41.061386 -48.7426)
		(width 0.127)
		(layer "B.Cu")
		(net "VSENSE_PVCCIN_CPU1_N")
	)
	(segment
		(start 63.881 -59.25439)
		(end 53.36921 -48.7426)
		(width 0.127)
		(layer "B.Cu")
		(net "VSENSE_PVCCIN_CPU1_N")
	)
	(segment
		(start 26.416 -56.794908)
		(end 26.416 -67.881754)
		(width 0.127)
		(layer "In2.Cu")
		(net "VSENSE_PVCCIN_CPU1_N")
	)
	(segment
		(start 24.892 -74.1934)
		(end 24.892 -78.289658)
		(width 0.127)
		(layer "In2.Cu")
		(net "VSENSE_PVCCIN_CPU1_N")
	)
	(segment
		(start 24.689562 -78.492096)
		(end 24.689562 -83.433158)
		(width 0.127)
		(layer "In2.Cu")
		(net "VSENSE_PVCCIN_CPU1_N")
	)
	(segment
		(start 22.3266 -87.989918)
		(end 22.3266 -88.265)
		(width 0.127)
		(layer "In2.Cu")
		(net "VSENSE_PVCCIN_CPU1_N")
	)
	(segment
		(start 28.647644 -54.563264)
		(end 26.416 -56.794908)
		(width 0.127)
		(layer "In2.Cu")
		(net "VSENSE_PVCCIN_CPU1_N")
	)
	(segment
		(start 21.90242 -86.65718)
		(end 21.90242 -87.135462)
		(width 0.127)
		(layer "In2.Cu")
		(net "VSENSE_PVCCIN_CPU1_N")
	)
	(segment
		(start 38.1 -49.4919)
		(end 38.1 -49.8602)
		(width 0.127)
		(layer "In2.Cu")
		(net "VSENSE_PVCCIN_CPU1_N")
	)
	(segment
		(start 24.689562 -83.433158)
		(end 22.74316 -85.37956)
		(width 0.127)
		(layer "In2.Cu")
		(net "VSENSE_PVCCIN_CPU1_N")
	)
	(segment
		(start 21.90242 -87.135462)
		(end 21.8821 -87.155782)
		(width 0.127)
		(layer "In2.Cu")
		(net "VSENSE_PVCCIN_CPU1_N")
	)
	(segment
		(start 21.8821 -87.545418)
		(end 22.3266 -87.989918)
		(width 0.127)
		(layer "In2.Cu")
		(net "VSENSE_PVCCIN_CPU1_N")
	)
	(segment
		(start 26.416 -67.881754)
		(end 25.3746 -68.923154)
		(width 0.127)
		(layer "In2.Cu")
		(net "VSENSE_PVCCIN_CPU1_N")
	)
	(segment
		(start 21.8821 -87.155782)
		(end 21.8821 -87.545418)
		(width 0.127)
		(layer "In2.Cu")
		(net "VSENSE_PVCCIN_CPU1_N")
	)
	(segment
		(start 29.056584 -53.532532)
		(end 28.647644 -53.941472)
		(width 0.127)
		(layer "In2.Cu")
		(net "VSENSE_PVCCIN_CPU1_N")
	)
	(segment
		(start 25.3746 -73.7108)
		(end 24.892 -74.1934)
		(width 0.127)
		(layer "In2.Cu")
		(net "VSENSE_PVCCIN_CPU1_N")
	)
	(segment
		(start 24.892 -78.289658)
		(end 24.689562 -78.492096)
		(width 0.127)
		(layer "In2.Cu")
		(net "VSENSE_PVCCIN_CPU1_N")
	)
	(segment
		(start 28.647644 -53.941472)
		(end 28.647644 -54.563264)
		(width 0.127)
		(layer "In2.Cu")
		(net "VSENSE_PVCCIN_CPU1_N")
	)
	(segment
		(start 25.3746 -68.923154)
		(end 25.3746 -73.7108)
		(width 0.127)
		(layer "In2.Cu")
		(net "VSENSE_PVCCIN_CPU1_N")
	)
	(segment
		(start 29.280612 -53.532532)
		(end 29.056584 -53.532532)
		(width 0.127)
		(layer "In2.Cu")
		(net "VSENSE_PVCCIN_CPU1_N")
	)
	(segment
		(start 32.800544 -50.0126)
		(end 29.280612 -53.532532)
		(width 0.127)
		(layer "In2.Cu")
		(net "VSENSE_PVCCIN_CPU1_N")
	)
	(segment
		(start 22.74316 -85.81644)
		(end 21.90242 -86.65718)
		(width 0.127)
		(layer "In2.Cu")
		(net "VSENSE_PVCCIN_CPU1_N")
	)
	(segment
		(start 37.947092 -50.0126)
		(end 32.800544 -50.0126)
		(width 0.127)
		(layer "In2.Cu")
		(net "VSENSE_PVCCIN_CPU1_N")
	)
	(segment
		(start 38.1 -49.8602)
		(end 37.947092 -50.0126)
		(width 0.127)
		(layer "In2.Cu")
		(net "VSENSE_PVCCIN_CPU1_N")
	)
	(segment
		(start 22.74316 -85.37956)
		(end 22.74316 -85.81644)
		(width 0.127)
		(layer "In2.Cu")
		(net "VSENSE_PVCCIN_CPU1_N")
	)
	(segment
		(start 20.7518 -88.138)
		(end 20.7518 -87.3506)
		(width 0.127)
		(layer "F.Cu")
		(net "VSENSE_PVCCIN_CPU1_AVSP")
	)
	(segment
		(start 20.430998 -88.941402)
		(end 20.7518 -88.6206)
		(width 0.127)
		(layer "F.Cu")
		(net "VSENSE_PVCCIN_CPU1_AVSP")
	)
	(segment
		(start 20.430998 -89.5604)
		(end 20.430998 -88.941402)
		(width 0.127)
		(layer "F.Cu")
		(net "VSENSE_PVCCIN_CPU1_AVSP")
	)
	(segment
		(start 20.7518 -88.6206)
		(end 20.7518 -88.138)
		(width 0.127)
		(layer "F.Cu")
		(net "VSENSE_PVCCIN_CPU1_AVSP")
	)
	(segment
		(start 205.9178 -50.5714)
		(end 206.629 -50.5714)
		(width 0.127)
		(layer "F.Cu")
		(net "VSENSE_PVCCIN_CPU0_SKT_VSEN")
	)
	(segment
		(start 232.749598 -69.45884)
		(end 232.101898 -69.45884)
		(width 0.127)
		(layer "F.Cu")
		(net "VSENSE_PVCCIN_CPU0_SKT_VSEN")
	)
	(segment
		(start 206.629 -50.5714)
		(end 206.6798 -50.5206)
		(width 0.127)
		(layer "F.Cu")
		(net "VSENSE_PVCCIN_CPU0_SKT_VSEN")
	)
	(via
		(at 206.6798 -50.5206)
		(size 0.508)
		(drill 0.254)
		(layers "F.Cu" "B.Cu")
		(net "VSENSE_PVCCIN_CPU0_SKT_VSEN")
	)
	(via
		(at 232.101898 -69.45884)
		(size 0.508)
		(drill 0.254)
		(layers "F.Cu" "B.Cu")
		(net "VSENSE_PVCCIN_CPU0_SKT_VSEN")
	)
	(segment
		(start 232.400602 -69.148452)
		(end 232.31094 -68.979288)
		(width 0.127)
		(layer "In2.Cu")
		(net "VSENSE_PVCCIN_CPU0_SKT_VSEN")
	)
	(segment
		(start 232.400348 -69.148706)
		(end 232.400602 -69.148452)
		(width 0.127)
		(layer "In2.Cu")
		(net "VSENSE_PVCCIN_CPU0_SKT_VSEN")
	)
	(segment
		(start 232.31094 -68.979288)
		(end 232.089706 -68.7578)
		(width 0.127)
		(layer "In2.Cu")
		(net "VSENSE_PVCCIN_CPU0_SKT_VSEN")
	)
	(segment
		(start 231.314498 -68.7578)
		(end 231.085898 -68.9864)
		(width 0.127)
		(layer "In2.Cu")
		(net "VSENSE_PVCCIN_CPU0_SKT_VSEN")
	)
	(segment
		(start 232.34523 -69.329808)
		(end 232.400348 -69.148706)
		(width 0.127)
		(layer "In2.Cu")
		(net "VSENSE_PVCCIN_CPU0_SKT_VSEN")
	)
	(segment
		(start 209.088736 -50.2666)
		(end 206.9338 -50.2666)
		(width 0.127)
		(layer "In2.Cu")
		(net "VSENSE_PVCCIN_CPU0_SKT_VSEN")
	)
	(segment
		(start 206.9338 -50.2666)
		(end 206.6798 -50.5206)
		(width 0.127)
		(layer "In2.Cu")
		(net "VSENSE_PVCCIN_CPU0_SKT_VSEN")
	)
	(segment
		(start 227.808536 -68.9864)
		(end 209.088736 -50.2666)
		(width 0.127)
		(layer "In2.Cu")
		(net "VSENSE_PVCCIN_CPU0_SKT_VSEN")
	)
	(segment
		(start 232.089706 -68.7578)
		(end 231.314498 -68.7578)
		(width 0.127)
		(layer "In2.Cu")
		(net "VSENSE_PVCCIN_CPU0_SKT_VSEN")
	)
	(segment
		(start 231.085898 -68.9864)
		(end 227.808536 -68.9864)
		(width 0.127)
		(layer "In2.Cu")
		(net "VSENSE_PVCCIN_CPU0_SKT_VSEN")
	)
	(segment
		(start 232.101898 -69.45884)
		(end 232.34523 -69.329808)
		(width 0.127)
		(layer "In2.Cu")
		(net "VSENSE_PVCCIN_CPU0_SKT_VSEN")
	)
	(segment
		(start 205.9178 -49.6824)
		(end 206.6798 -49.6824)
		(width 0.127)
		(layer "F.Cu")
		(net "VSENSE_PVCCIN_CPU0_SKT_VRTN")
	)
	(segment
		(start 233.608118 -68.963286)
		(end 233.036618 -68.963286)
		(width 0.127)
		(layer "F.Cu")
		(net "VSENSE_PVCCIN_CPU0_SKT_VRTN")
	)
	(via
		(at 206.6798 -49.6824)
		(size 0.508)
		(drill 0.254)
		(layers "F.Cu" "B.Cu")
		(net "VSENSE_PVCCIN_CPU0_SKT_VRTN")
	)
	(via
		(at 233.036618 -68.963286)
		(size 0.508)
		(drill 0.254)
		(layers "F.Cu" "B.Cu")
		(net "VSENSE_PVCCIN_CPU0_SKT_VRTN")
	)
	(segment
		(start 233.036618 -68.963286)
		(end 232.793794 -69.092064)
		(width 0.127)
		(layer "In2.Cu")
		(net "VSENSE_PVCCIN_CPU0_SKT_VRTN")
	)
	(segment
		(start 227.913946 -68.7324)
		(end 209.194146 -50.0126)
		(width 0.127)
		(layer "In2.Cu")
		(net "VSENSE_PVCCIN_CPU0_SKT_VRTN")
	)
	(segment
		(start 232.793794 -69.092064)
		(end 232.631742 -69.042026)
		(width 0.127)
		(layer "In2.Cu")
		(net "VSENSE_PVCCIN_CPU0_SKT_VRTN")
	)
	(segment
		(start 231.209088 -68.5038)
		(end 230.980488 -68.7324)
		(width 0.127)
		(layer "In2.Cu")
		(net "VSENSE_PVCCIN_CPU0_SKT_VRTN")
	)
	(segment
		(start 209.194146 -50.0126)
		(end 207.01 -50.0126)
		(width 0.127)
		(layer "In2.Cu")
		(net "VSENSE_PVCCIN_CPU0_SKT_VRTN")
	)
	(segment
		(start 232.195116 -68.5038)
		(end 231.209088 -68.5038)
		(width 0.127)
		(layer "In2.Cu")
		(net "VSENSE_PVCCIN_CPU0_SKT_VRTN")
	)
	(segment
		(start 232.631742 -69.042026)
		(end 232.51795 -68.826634)
		(width 0.127)
		(layer "In2.Cu")
		(net "VSENSE_PVCCIN_CPU0_SKT_VRTN")
	)
	(segment
		(start 232.51795 -68.826634)
		(end 232.195116 -68.5038)
		(width 0.127)
		(layer "In2.Cu")
		(net "VSENSE_PVCCIN_CPU0_SKT_VRTN")
	)
	(segment
		(start 230.980488 -68.7324)
		(end 227.913946 -68.7324)
		(width 0.127)
		(layer "In2.Cu")
		(net "VSENSE_PVCCIN_CPU0_SKT_VRTN")
	)
	(segment
		(start 207.01 -50.0126)
		(end 206.6798 -49.6824)
		(width 0.127)
		(layer "In2.Cu")
		(net "VSENSE_PVCCIN_CPU0_SKT_VRTN")
	)
	(segment
		(start 204.2668 -50.5714)
		(end 205.0288 -50.5714)
		(width 0.127)
		(layer "F.Cu")
		(net "VSENSE_PVCCIN_CPU0_P")
	)
	(segment
		(start 204.2668 -50.5714)
		(end 203.0222 -50.5714)
		(width 0.127)
		(layer "F.Cu")
		(net "VSENSE_PVCCIN_CPU0_P")
	)
	(segment
		(start 187.833 -63.627)
		(end 187.833 -62.865)
		(width 0.127)
		(layer "F.Cu")
		(net "VSENSE_PVCCIN_CPU0_P")
	)
	(via
		(at 203.0222 -50.5714)
		(size 0.508)
		(drill 0.254)
		(layers "F.Cu" "B.Cu")
		(net "VSENSE_PVCCIN_CPU0_P")
	)
	(via
		(at 187.833 -62.865)
		(size 0.508)
		(drill 0.254)
		(layers "F.Cu" "B.Cu")
		(net "VSENSE_PVCCIN_CPU0_P")
	)
	(segment
		(start 220.2688 -52.2732)
		(end 210.3882 -52.2732)
		(width 0.127)
		(layer "B.Cu")
		(net "VSENSE_PVCCIN_CPU0_P")
	)
	(segment
		(start 228.7905 -60.7949)
		(end 220.2688 -52.2732)
		(width 0.127)
		(layer "B.Cu")
		(net "VSENSE_PVCCIN_CPU0_P")
	)
	(segment
		(start 208.64703 -50.53203)
		(end 207.737202 -50.53203)
		(width 0.127)
		(layer "B.Cu")
		(net "VSENSE_PVCCIN_CPU0_P")
	)
	(segment
		(start 207.54086 -50.877724)
		(end 207.036924 -51.38166)
		(width 0.127)
		(layer "B.Cu")
		(net "VSENSE_PVCCIN_CPU0_P")
	)
	(segment
		(start 204.69225 -50.292)
		(end 203.3016 -50.292)
		(width 0.127)
		(layer "B.Cu")
		(net "VSENSE_PVCCIN_CPU0_P")
	)
	(segment
		(start 210.3882 -52.2732)
		(end 208.64703 -50.53203)
		(width 0.127)
		(layer "B.Cu")
		(net "VSENSE_PVCCIN_CPU0_P")
	)
	(segment
		(start 207.54086 -50.728372)
		(end 207.54086 -50.877724)
		(width 0.127)
		(layer "B.Cu")
		(net "VSENSE_PVCCIN_CPU0_P")
	)
	(segment
		(start 205.78191 -51.38166)
		(end 204.69225 -50.292)
		(width 0.127)
		(layer "B.Cu")
		(net "VSENSE_PVCCIN_CPU0_P")
	)
	(segment
		(start 203.3016 -50.292)
		(end 203.0222 -50.5714)
		(width 0.127)
		(layer "B.Cu")
		(net "VSENSE_PVCCIN_CPU0_P")
	)
	(segment
		(start 228.7905 -64.3255)
		(end 228.7905 -60.7949)
		(width 0.127)
		(layer "B.Cu")
		(net "VSENSE_PVCCIN_CPU0_P")
	)
	(segment
		(start 207.737202 -50.53203)
		(end 207.54086 -50.728372)
		(width 0.127)
		(layer "B.Cu")
		(net "VSENSE_PVCCIN_CPU0_P")
	)
	(segment
		(start 207.036924 -51.38166)
		(end 205.78191 -51.38166)
		(width 0.127)
		(layer "B.Cu")
		(net "VSENSE_PVCCIN_CPU0_P")
	)
	(segment
		(start 228.4603 -64.6557)
		(end 228.7905 -64.3255)
		(width 0.127)
		(layer "B.Cu")
		(net "VSENSE_PVCCIN_CPU0_P")
	)
	(segment
		(start 187.098432 -62.11951)
		(end 187.70473 -62.11951)
		(width 0.127)
		(layer "In2.Cu")
		(net "VSENSE_PVCCIN_CPU0_P")
	)
	(segment
		(start 192.151 -58.586624)
		(end 192.151 -53.6702)
		(width 0.127)
		(layer "In2.Cu")
		(net "VSENSE_PVCCIN_CPU0_P")
	)
	(segment
		(start 187.70473 -62.11951)
		(end 189.334902 -60.489338)
		(width 0.127)
		(layer "In2.Cu")
		(net "VSENSE_PVCCIN_CPU0_P")
	)
	(segment
		(start 192.151 -53.6702)
		(end 195.58 -50.2412)
		(width 0.127)
		(layer "In2.Cu")
		(net "VSENSE_PVCCIN_CPU0_P")
	)
	(segment
		(start 202.692 -50.2412)
		(end 203.0222 -50.5714)
		(width 0.127)
		(layer "In2.Cu")
		(net "VSENSE_PVCCIN_CPU0_P")
	)
	(segment
		(start 187.833 -63.382398)
		(end 187.697872 -63.517526)
		(width 0.127)
		(layer "In2.Cu")
		(net "VSENSE_PVCCIN_CPU0_P")
	)
	(segment
		(start 186.667648 -63.15837)
		(end 186.667648 -62.550294)
		(width 0.127)
		(layer "In2.Cu")
		(net "VSENSE_PVCCIN_CPU0_P")
	)
	(segment
		(start 187.697872 -63.517526)
		(end 187.026804 -63.517526)
		(width 0.127)
		(layer "In2.Cu")
		(net "VSENSE_PVCCIN_CPU0_P")
	)
	(segment
		(start 189.334902 -60.489338)
		(end 190.248286 -60.489338)
		(width 0.127)
		(layer "In2.Cu")
		(net "VSENSE_PVCCIN_CPU0_P")
	)
	(segment
		(start 187.833 -62.865)
		(end 187.833 -63.382398)
		(width 0.127)
		(layer "In2.Cu")
		(net "VSENSE_PVCCIN_CPU0_P")
	)
	(segment
		(start 195.58 -50.2412)
		(end 202.692 -50.2412)
		(width 0.127)
		(layer "In2.Cu")
		(net "VSENSE_PVCCIN_CPU0_P")
	)
	(segment
		(start 186.667648 -62.550294)
		(end 187.098432 -62.11951)
		(width 0.127)
		(layer "In2.Cu")
		(net "VSENSE_PVCCIN_CPU0_P")
	)
	(segment
		(start 190.248286 -60.489338)
		(end 192.151 -58.586624)
		(width 0.127)
		(layer "In2.Cu")
		(net "VSENSE_PVCCIN_CPU0_P")
	)
	(segment
		(start 187.026804 -63.517526)
		(end 186.667648 -63.15837)
		(width 0.127)
		(layer "In2.Cu")
		(net "VSENSE_PVCCIN_CPU0_P")
	)
	(segment
		(start 204.2668 -49.6824)
		(end 203.0222 -49.6824)
		(width 0.127)
		(layer "F.Cu")
		(net "VSENSE_PVCCIN_CPU0_N")
	)
	(segment
		(start 187.198 -64.9732)
		(end 187.198 -64.77)
		(width 0.127)
		(layer "F.Cu")
		(net "VSENSE_PVCCIN_CPU0_N")
	)
	(segment
		(start 187.6044 -64.3636)
		(end 187.198 -64.77)
		(width 0.127)
		(layer "F.Cu")
		(net "VSENSE_PVCCIN_CPU0_N")
	)
	(segment
		(start 185.677048 -66.9544)
		(end 185.677048 -66.240152)
		(width 0.127)
		(layer "F.Cu")
		(net "VSENSE_PVCCIN_CPU0_N")
	)
	(segment
		(start 204.2668 -49.6824)
		(end 205.0288 -49.6824)
		(width 0.127)
		(layer "F.Cu")
		(net "VSENSE_PVCCIN_CPU0_N")
	)
	(segment
		(start 187.8076 -64.3636)
		(end 187.6044 -64.3636)
		(width 0.127)
		(layer "F.Cu")
		(net "VSENSE_PVCCIN_CPU0_N")
	)
	(segment
		(start 185.677048 -66.240152)
		(end 186.6265 -65.2907)
		(width 0.127)
		(layer "F.Cu")
		(net "VSENSE_PVCCIN_CPU0_N")
	)
	(segment
		(start 186.8805 -65.2907)
		(end 187.198 -64.9732)
		(width 0.127)
		(layer "F.Cu")
		(net "VSENSE_PVCCIN_CPU0_N")
	)
	(segment
		(start 186.6265 -65.2907)
		(end 186.8805 -65.2907)
		(width 0.127)
		(layer "F.Cu")
		(net "VSENSE_PVCCIN_CPU0_N")
	)
	(via
		(at 187.8076 -64.3636)
		(size 0.508)
		(drill 0.254)
		(layers "F.Cu" "B.Cu")
		(net "VSENSE_PVCCIN_CPU0_N")
	)
	(via
		(at 203.0222 -49.6824)
		(size 0.508)
		(drill 0.254)
		(layers "F.Cu" "B.Cu")
		(net "VSENSE_PVCCIN_CPU0_N")
	)
	(segment
		(start 207.28686 -50.772314)
		(end 206.931514 -51.12766)
		(width 0.127)
		(layer "B.Cu")
		(net "VSENSE_PVCCIN_CPU0_N")
	)
	(segment
		(start 229.0445 -60.68949)
		(end 220.37421 -52.0192)
		(width 0.127)
		(layer "B.Cu")
		(net "VSENSE_PVCCIN_CPU0_N")
	)
	(segment
		(start 206.931514 -51.12766)
		(end 205.88732 -51.12766)
		(width 0.127)
		(layer "B.Cu")
		(net "VSENSE_PVCCIN_CPU0_N")
	)
	(segment
		(start 207.28686 -50.622962)
		(end 207.28686 -50.772314)
		(width 0.127)
		(layer "B.Cu")
		(net "VSENSE_PVCCIN_CPU0_N")
	)
	(segment
		(start 229.3747 -64.6303)
		(end 229.0445 -64.3001)
		(width 0.127)
		(layer "B.Cu")
		(net "VSENSE_PVCCIN_CPU0_N")
	)
	(segment
		(start 204.79766 -50.038)
		(end 203.3778 -50.038)
		(width 0.127)
		(layer "B.Cu")
		(net "VSENSE_PVCCIN_CPU0_N")
	)
	(segment
		(start 203.3778 -50.038)
		(end 203.0222 -49.6824)
		(width 0.127)
		(layer "B.Cu")
		(net "VSENSE_PVCCIN_CPU0_N")
	)
	(segment
		(start 205.88732 -51.12766)
		(end 204.79766 -50.038)
		(width 0.127)
		(layer "B.Cu")
		(net "VSENSE_PVCCIN_CPU0_N")
	)
	(segment
		(start 208.75244 -50.27803)
		(end 207.631792 -50.27803)
		(width 0.127)
		(layer "B.Cu")
		(net "VSENSE_PVCCIN_CPU0_N")
	)
	(segment
		(start 210.49361 -52.0192)
		(end 208.75244 -50.27803)
		(width 0.127)
		(layer "B.Cu")
		(net "VSENSE_PVCCIN_CPU0_N")
	)
	(segment
		(start 220.37421 -52.0192)
		(end 210.49361 -52.0192)
		(width 0.127)
		(layer "B.Cu")
		(net "VSENSE_PVCCIN_CPU0_N")
	)
	(segment
		(start 229.0445 -64.3001)
		(end 229.0445 -60.68949)
		(width 0.127)
		(layer "B.Cu")
		(net "VSENSE_PVCCIN_CPU0_N")
	)
	(segment
		(start 207.631792 -50.27803)
		(end 207.28686 -50.622962)
		(width 0.127)
		(layer "B.Cu")
		(net "VSENSE_PVCCIN_CPU0_N")
	)
	(segment
		(start 195.47459 -49.9872)
		(end 202.7174 -49.9872)
		(width 0.127)
		(layer "In2.Cu")
		(net "VSENSE_PVCCIN_CPU0_N")
	)
	(segment
		(start 186.993022 -61.86551)
		(end 187.59932 -61.86551)
		(width 0.127)
		(layer "In2.Cu")
		(net "VSENSE_PVCCIN_CPU0_N")
	)
	(segment
		(start 186.413648 -62.444884)
		(end 186.993022 -61.86551)
		(width 0.127)
		(layer "In2.Cu")
		(net "VSENSE_PVCCIN_CPU0_N")
	)
	(segment
		(start 187.8076 -64.3636)
		(end 187.8076 -63.906654)
		(width 0.127)
		(layer "In2.Cu")
		(net "VSENSE_PVCCIN_CPU0_N")
	)
	(segment
		(start 190.142876 -60.235338)
		(end 191.897 -58.481214)
		(width 0.127)
		(layer "In2.Cu")
		(net "VSENSE_PVCCIN_CPU0_N")
	)
	(segment
		(start 186.413648 -63.26378)
		(end 186.413648 -62.444884)
		(width 0.127)
		(layer "In2.Cu")
		(net "VSENSE_PVCCIN_CPU0_N")
	)
	(segment
		(start 191.897 -53.56479)
		(end 195.47459 -49.9872)
		(width 0.127)
		(layer "In2.Cu")
		(net "VSENSE_PVCCIN_CPU0_N")
	)
	(segment
		(start 202.7174 -49.9872)
		(end 203.0222 -49.6824)
		(width 0.127)
		(layer "In2.Cu")
		(net "VSENSE_PVCCIN_CPU0_N")
	)
	(segment
		(start 186.921394 -63.771526)
		(end 186.413648 -63.26378)
		(width 0.127)
		(layer "In2.Cu")
		(net "VSENSE_PVCCIN_CPU0_N")
	)
	(segment
		(start 187.672472 -63.771526)
		(end 186.921394 -63.771526)
		(width 0.127)
		(layer "In2.Cu")
		(net "VSENSE_PVCCIN_CPU0_N")
	)
	(segment
		(start 187.59932 -61.86551)
		(end 189.229492 -60.235338)
		(width 0.127)
		(layer "In2.Cu")
		(net "VSENSE_PVCCIN_CPU0_N")
	)
	(segment
		(start 187.8076 -63.906654)
		(end 187.672472 -63.771526)
		(width 0.127)
		(layer "In2.Cu")
		(net "VSENSE_PVCCIN_CPU0_N")
	)
	(segment
		(start 191.897 -58.481214)
		(end 191.897 -53.56479)
		(width 0.127)
		(layer "In2.Cu")
		(net "VSENSE_PVCCIN_CPU0_N")
	)
	(segment
		(start 189.229492 -60.235338)
		(end 190.142876 -60.235338)
		(width 0.127)
		(layer "In2.Cu")
		(net "VSENSE_PVCCIN_CPU0_N")
	)
	(segment
		(start 186.944 -62.7888)
		(end 186.551316 -62.396116)
		(width 0.127)
		(layer "F.Cu")
		(net "VSENSE_PVCCIN_CPU0_AVSP")
	)
	(segment
		(start 186.944 -63.627)
		(end 186.944 -62.7888)
		(width 0.127)
		(layer "F.Cu")
		(net "VSENSE_PVCCIN_CPU0_AVSP")
	)
	(segment
		(start 186.309 -64.9224)
		(end 186.309 -64.77)
		(width 0.127)
		(layer "F.Cu")
		(net "VSENSE_PVCCIN_CPU0_AVSP")
	)
	(segment
		(start 186.309 -64.262)
		(end 186.944 -63.627)
		(width 0.127)
		(layer "F.Cu")
		(net "VSENSE_PVCCIN_CPU0_AVSP")
	)
	(segment
		(start 185.276998 -66.9544)
		(end 185.276998 -65.954402)
		(width 0.127)
		(layer "F.Cu")
		(net "VSENSE_PVCCIN_CPU0_AVSP")
	)
	(segment
		(start 185.276998 -65.954402)
		(end 186.309 -64.9224)
		(width 0.127)
		(layer "F.Cu")
		(net "VSENSE_PVCCIN_CPU0_AVSP")
	)
	(segment
		(start 186.309 -64.77)
		(end 186.309 -64.262)
		(width 0.127)
		(layer "F.Cu")
		(net "VSENSE_PVCCIN_CPU0_AVSP")
	)
	(via
		(at 186.551316 -62.396116)
		(size 0.762)
		(drill 0.381)
		(layers "F.Cu" "B.Cu")
		(net "VSENSE_PVCCIN_CPU0_AVSP")
	)
	(segment
		(start 108.712 -68.199)
		(end 108.839 -68.072)
		(width 0.254)
		(layer "F.Cu")
		(net "VSENSE_PMAX_CPU1")
	)
	(segment
		(start 108.712 -68.961)
		(end 108.712 -68.199)
		(width 0.254)
		(layer "F.Cu")
		(net "VSENSE_PMAX_CPU1")
	)
	(segment
		(start 109.177836 -67.257422)
		(end 109.177836 -67.504564)
		(width 0.254)
		(layer "F.Cu")
		(net "VSENSE_PMAX_CPU1")
	)
	(segment
		(start 107.910376 -62.838584)
		(end 107.338876 -62.838584)
		(width 0.254)
		(layer "F.Cu")
		(net "VSENSE_PMAX_CPU1")
	)
	(segment
		(start 109.177836 -67.504564)
		(end 108.839 -67.8434)
		(width 0.254)
		(layer "F.Cu")
		(net "VSENSE_PMAX_CPU1")
	)
	(segment
		(start 108.839 -67.8434)
		(end 108.839 -68.072)
		(width 0.254)
		(layer "F.Cu")
		(net "VSENSE_PMAX_CPU1")
	)
	(segment
		(start 109.164374 -67.257422)
		(end 109.177836 -67.257422)
		(width 0.254)
		(layer "F.Cu")
		(net "VSENSE_PMAX_CPU1")
	)
	(via
		(at 109.164374 -67.257422)
		(size 0.508)
		(drill 0.254)
		(layers "F.Cu" "B.Cu")
		(net "VSENSE_PMAX_CPU1")
	)
	(via
		(at 107.338876 -62.838584)
		(size 0.508)
		(drill 0.254)
		(layers "F.Cu" "B.Cu")
		(net "VSENSE_PMAX_CPU1")
	)
	(segment
		(start 109.177836 -65.99809)
		(end 108.349034 -65.169288)
		(width 0.254)
		(layer "In11.Cu")
		(net "VSENSE_PMAX_CPU1")
	)
	(segment
		(start 108.1278 -64.464438)
		(end 107.53598 -63.035688)
		(width 0.254)
		(layer "In11.Cu")
		(net "VSENSE_PMAX_CPU1")
	)
	(segment
		(start 108.349034 -65.169288)
		(end 108.1278 -64.589914)
		(width 0.254)
		(layer "In11.Cu")
		(net "VSENSE_PMAX_CPU1")
	)
	(segment
		(start 108.1278 -64.589914)
		(end 108.1278 -64.464438)
		(width 0.254)
		(layer "In11.Cu")
		(net "VSENSE_PMAX_CPU1")
	)
	(segment
		(start 107.53598 -63.035688)
		(end 107.338876 -62.838584)
		(width 0.254)
		(layer "In11.Cu")
		(net "VSENSE_PMAX_CPU1")
	)
	(segment
		(start 109.164374 -67.257422)
		(end 109.177836 -67.257422)
		(width 0.254)
		(layer "In11.Cu")
		(net "VSENSE_PMAX_CPU1")
	)
	(segment
		(start 109.177836 -67.257422)
		(end 109.177836 -65.99809)
		(width 0.254)
		(layer "In11.Cu")
		(net "VSENSE_PMAX_CPU1")
	)
	(segment
		(start 274.284186 -67.31)
		(end 273.8628 -67.731386)
		(width 0.254)
		(layer "F.Cu")
		(net "VSENSE_PMAX_CPU0")
	)
	(segment
		(start 272.910808 -62.838584)
		(end 272.339308 -62.838584)
		(width 0.1651)
		(layer "F.Cu")
		(net "VSENSE_PMAX_CPU0")
	)
	(segment
		(start 273.558 -69.088)
		(end 273.558 -68.3768)
		(width 0.254)
		(layer "F.Cu")
		(net "VSENSE_PMAX_CPU0")
	)
	(segment
		(start 273.8628 -67.731386)
		(end 273.8628 -68.072)
		(width 0.254)
		(layer "F.Cu")
		(net "VSENSE_PMAX_CPU0")
	)
	(segment
		(start 273.558 -68.3768)
		(end 273.8628 -68.072)
		(width 0.254)
		(layer "F.Cu")
		(net "VSENSE_PMAX_CPU0")
	)
	(via
		(at 274.284186 -67.31)
		(size 0.508)
		(drill 0.254)
		(layers "F.Cu" "B.Cu")
		(net "VSENSE_PMAX_CPU0")
	)
	(via
		(at 272.339308 -62.838584)
		(size 0.508)
		(drill 0.254)
		(layers "F.Cu" "B.Cu")
		(net "VSENSE_PMAX_CPU0")
	)
	(segment
		(start 274.241514 -66.9798)
		(end 274.284186 -67.31)
		(width 0.254)
		(layer "In11.Cu")
		(net "VSENSE_PMAX_CPU0")
	)
	(segment
		(start 273.540474 -65.757552)
		(end 274.241514 -66.9798)
		(width 0.254)
		(layer "In11.Cu")
		(net "VSENSE_PMAX_CPU0")
	)
	(segment
		(start 272.339308 -62.838584)
		(end 272.8214 -63.7032)
		(width 0.254)
		(layer "In11.Cu")
		(net "VSENSE_PMAX_CPU0")
	)
	(segment
		(start 272.8214 -63.7032)
		(end 273.540474 -65.757552)
		(width 0.254)
		(layer "In11.Cu")
		(net "VSENSE_PMAX_CPU0")
	)
	(segment
		(start 128.514348 -78.688438)
		(end 129.085848 -78.688438)
		(width 0.127)
		(layer "F.Cu")
		(net "VSENSE_PVCCIOMCP_CPU1_SKT_VSEN")
	)
	(segment
		(start 172.7708 -109.7534)
		(end 172.787564 -109.7534)
		(width 0.127)
		(layer "F.Cu")
		(net "VSENSE_PVCCIOMCP_CPU1_SKT_VSEN")
	)
	(segment
		(start 172.787564 -109.7534)
		(end 173.505114 -110.47095)
		(width 0.127)
		(layer "F.Cu")
		(net "VSENSE_PVCCIOMCP_CPU1_SKT_VSEN")
	)
	(via
		(at 129.085848 -78.688438)
		(size 0.508)
		(drill 0.254)
		(layers "F.Cu" "B.Cu")
		(net "VSENSE_PVCCIOMCP_CPU1_SKT_VSEN")
	)
	(via
		(at 172.7708 -109.7534)
		(size 0.508)
		(drill 0.254)
		(layers "F.Cu" "B.Cu")
		(net "VSENSE_PVCCIOMCP_CPU1_SKT_VSEN")
	)
	(segment
		(start 145.758916 -92.191332)
		(end 145.131282 -91.564206)
		(width 0.127)
		(layer "In11.Cu")
		(net "VSENSE_PVCCIOMCP_CPU1_SKT_VSEN")
	)
	(segment
		(start 129.40284 -78.946756)
		(end 129.378964 -78.857348)
		(width 0.0889)
		(layer "In11.Cu")
		(net "VSENSE_PVCCIOMCP_CPU1_SKT_VSEN")
	)
	(segment
		(start 142.130272 -89.680288)
		(end 141.945614 -89.680288)
		(width 0.0889)
		(layer "In11.Cu")
		(net "VSENSE_PVCCIOMCP_CPU1_SKT_VSEN")
	)
	(segment
		(start 140.26134 -88.689688)
		(end 140.228574 -88.689688)
		(width 0.0889)
		(layer "In11.Cu")
		(net "VSENSE_PVCCIOMCP_CPU1_SKT_VSEN")
	)
	(segment
		(start 156.226002 -109.31398)
		(end 145.758916 -98.846894)
		(width 0.127)
		(layer "In11.Cu")
		(net "VSENSE_PVCCIOMCP_CPU1_SKT_VSEN")
	)
	(segment
		(start 136.82726 -86.708488)
		(end 136.794494 -86.708488)
		(width 0.0889)
		(layer "In11.Cu")
		(net "VSENSE_PVCCIOMCP_CPU1_SKT_VSEN")
	)
	(segment
		(start 129.432558 -79.478886)
		(end 129.426208 -79.468218)
		(width 0.0889)
		(layer "In11.Cu")
		(net "VSENSE_PVCCIOMCP_CPU1_SKT_VSEN")
	)
	(segment
		(start 141.11605 -89.184734)
		(end 141.083284 -89.184734)
		(width 0.0889)
		(layer "In11.Cu")
		(net "VSENSE_PVCCIOMCP_CPU1_SKT_VSEN")
	)
	(segment
		(start 129.437384 -79.487522)
		(end 129.432558 -79.478886)
		(width 0.0889)
		(layer "In11.Cu")
		(net "VSENSE_PVCCIOMCP_CPU1_SKT_VSEN")
	)
	(segment
		(start 129.437384 -80.478122)
		(end 129.432558 -80.469486)
		(width 0.0889)
		(layer "In11.Cu")
		(net "VSENSE_PVCCIOMCP_CPU1_SKT_VSEN")
	)
	(segment
		(start 130.814064 -83.241134)
		(end 130.781298 -83.241134)
		(width 0.0889)
		(layer "In11.Cu")
		(net "VSENSE_PVCCIOMCP_CPU1_SKT_VSEN")
	)
	(segment
		(start 129.959354 -82.746088)
		(end 129.931414 -82.746088)
		(width 0.0889)
		(layer "In11.Cu")
		(net "VSENSE_PVCCIOMCP_CPU1_SKT_VSEN")
	)
	(segment
		(start 139.39901 -88.194134)
		(end 139.366244 -88.194134)
		(width 0.0889)
		(layer "In11.Cu")
		(net "VSENSE_PVCCIOMCP_CPU1_SKT_VSEN")
	)
	(segment
		(start 138.5443 -87.699088)
		(end 138.511534 -87.699088)
		(width 0.0889)
		(layer "In11.Cu")
		(net "VSENSE_PVCCIOMCP_CPU1_SKT_VSEN")
	)
	(segment
		(start 143.204438 -90.153236)
		(end 143.080232 -90.172794)
		(width 0.0889)
		(layer "In11.Cu")
		(net "VSENSE_PVCCIOMCP_CPU1_SKT_VSEN")
	)
	(segment
		(start 145.115788 -91.521788)
		(end 143.747236 -90.153236)
		(width 0.0889)
		(layer "In11.Cu")
		(net "VSENSE_PVCCIOMCP_CPU1_SKT_VSEN")
	)
	(segment
		(start 145.131282 -91.564206)
		(end 145.115788 -91.548712)
		(width 0.0889)
		(layer "In11.Cu")
		(net "VSENSE_PVCCIOMCP_CPU1_SKT_VSEN")
	)
	(segment
		(start 135.11022 -85.717888)
		(end 135.077454 -85.717888)
		(width 0.0889)
		(layer "In11.Cu")
		(net "VSENSE_PVCCIOMCP_CPU1_SKT_VSEN")
	)
	(segment
		(start 129.432558 -81.460086)
		(end 129.426208 -81.449418)
		(width 0.0889)
		(layer "In11.Cu")
		(net "VSENSE_PVCCIOMCP_CPU1_SKT_VSEN")
	)
	(segment
		(start 131.661408 -83.736688)
		(end 131.643628 -83.736688)
		(width 0.0889)
		(layer "In11.Cu")
		(net "VSENSE_PVCCIOMCP_CPU1_SKT_VSEN")
	)
	(segment
		(start 172.6438 -109.31398)
		(end 156.226002 -109.31398)
		(width 0.127)
		(layer "In11.Cu")
		(net "VSENSE_PVCCIOMCP_CPU1_SKT_VSEN")
	)
	(segment
		(start 143.080232 -90.172794)
		(end 143.066008 -90.162126)
		(width 0.0889)
		(layer "In11.Cu")
		(net "VSENSE_PVCCIOMCP_CPU1_SKT_VSEN")
	)
	(segment
		(start 143.066008 -90.162126)
		(end 142.808198 -90.20302)
		(width 0.0889)
		(layer "In11.Cu")
		(net "VSENSE_PVCCIOMCP_CPU1_SKT_VSEN")
	)
	(segment
		(start 135.96493 -86.212934)
		(end 135.932164 -86.212934)
		(width 0.0889)
		(layer "In11.Cu")
		(net "VSENSE_PVCCIOMCP_CPU1_SKT_VSEN")
	)
	(segment
		(start 172.7708 -109.7534)
		(end 172.7708 -109.44098)
		(width 0.127)
		(layer "In11.Cu")
		(net "VSENSE_PVCCIOMCP_CPU1_SKT_VSEN")
	)
	(segment
		(start 145.115788 -91.548712)
		(end 145.115788 -91.521788)
		(width 0.0889)
		(layer "In11.Cu")
		(net "VSENSE_PVCCIOMCP_CPU1_SKT_VSEN")
	)
	(segment
		(start 145.758916 -98.846894)
		(end 145.758916 -92.191332)
		(width 0.127)
		(layer "In11.Cu")
		(net "VSENSE_PVCCIOMCP_CPU1_SKT_VSEN")
	)
	(segment
		(start 129.432558 -80.469486)
		(end 129.426208 -80.458818)
		(width 0.0889)
		(layer "In11.Cu")
		(net "VSENSE_PVCCIOMCP_CPU1_SKT_VSEN")
	)
	(segment
		(start 134.24789 -85.222334)
		(end 134.215124 -85.222334)
		(width 0.0889)
		(layer "In11.Cu")
		(net "VSENSE_PVCCIOMCP_CPU1_SKT_VSEN")
	)
	(segment
		(start 129.378964 -78.857348)
		(end 129.085848 -78.688438)
		(width 0.0889)
		(layer "In11.Cu")
		(net "VSENSE_PVCCIOMCP_CPU1_SKT_VSEN")
	)
	(segment
		(start 132.007864 -83.93684)
		(end 132.004562 -83.930998)
		(width 0.0889)
		(layer "In11.Cu")
		(net "VSENSE_PVCCIOMCP_CPU1_SKT_VSEN")
	)
	(segment
		(start 143.747236 -90.153236)
		(end 143.204438 -90.153236)
		(width 0.0889)
		(layer "In11.Cu")
		(net "VSENSE_PVCCIOMCP_CPU1_SKT_VSEN")
	)
	(segment
		(start 172.7708 -109.44098)
		(end 172.6438 -109.31398)
		(width 0.127)
		(layer "In11.Cu")
		(net "VSENSE_PVCCIOMCP_CPU1_SKT_VSEN")
	)
	(segment
		(start 133.39318 -84.727288)
		(end 133.360414 -84.727288)
		(width 0.0889)
		(layer "In11.Cu")
		(net "VSENSE_PVCCIOMCP_CPU1_SKT_VSEN")
	)
	(segment
		(start 132.53085 -84.231734)
		(end 132.494782 -84.231734)
		(width 0.0889)
		(layer "In11.Cu")
		(net "VSENSE_PVCCIOMCP_CPU1_SKT_VSEN")
	)
	(segment
		(start 137.68197 -87.203534)
		(end 137.649204 -87.203534)
		(width 0.0889)
		(layer "In11.Cu")
		(net "VSENSE_PVCCIOMCP_CPU1_SKT_VSEN")
	)
	(arc
		(start 132.004562 -83.930998)
		(mid 131.858596 -83.788599)
		(end 131.661408 -83.736688)
		(width 0.0889)
		(layer "In11.Cu")
		(net "VSENSE_PVCCIOMCP_CPU1_SKT_VSEN")
	)
	(arc
		(start 139.734544 -88.394286)
		(mid 139.592861 -88.250482)
		(end 139.39901 -88.194134)
		(width 0.0889)
		(layer "In11.Cu")
		(net "VSENSE_PVCCIOMCP_CPU1_SKT_VSEN")
	)
	(arc
		(start 132.866384 -84.431886)
		(mid 132.724701 -84.288082)
		(end 132.53085 -84.231734)
		(width 0.0889)
		(layer "In11.Cu")
		(net "VSENSE_PVCCIOMCP_CPU1_SKT_VSEN")
	)
	(arc
		(start 138.876024 -87.898986)
		(mid 138.735945 -87.75625)
		(end 138.5443 -87.699088)
		(width 0.0889)
		(layer "In11.Cu")
		(net "VSENSE_PVCCIOMCP_CPU1_SKT_VSEN")
	)
	(arc
		(start 135.932164 -86.212934)
		(mid 135.648947 -86.128653)
		(end 135.441944 -85.917786)
		(width 0.0889)
		(layer "In11.Cu")
		(net "VSENSE_PVCCIOMCP_CPU1_SKT_VSEN")
	)
	(arc
		(start 138.511534 -87.699088)
		(mid 138.22611 -87.615621)
		(end 138.017504 -87.403686)
		(width 0.0889)
		(layer "In11.Cu")
		(net "VSENSE_PVCCIOMCP_CPU1_SKT_VSEN")
	)
	(arc
		(start 141.945614 -89.680288)
		(mid 141.66019 -89.596821)
		(end 141.451584 -89.384886)
		(width 0.0889)
		(layer "In11.Cu")
		(net "VSENSE_PVCCIOMCP_CPU1_SKT_VSEN")
	)
	(arc
		(start 133.360414 -84.727288)
		(mid 133.07499 -84.643821)
		(end 132.866384 -84.431886)
		(width 0.0889)
		(layer "In11.Cu")
		(net "VSENSE_PVCCIOMCP_CPU1_SKT_VSEN")
	)
	(arc
		(start 142.346426 -89.877392)
		(mid 142.255482 -89.760049)
		(end 142.130272 -89.680288)
		(width 0.0889)
		(layer "In11.Cu")
		(net "VSENSE_PVCCIOMCP_CPU1_SKT_VSEN")
	)
	(arc
		(start 136.300464 -86.413086)
		(mid 136.158781 -86.269282)
		(end 135.96493 -86.212934)
		(width 0.0889)
		(layer "In11.Cu")
		(net "VSENSE_PVCCIOMCP_CPU1_SKT_VSEN")
	)
	(arc
		(start 129.426208 -79.468218)
		(mid 129.353813 -79.210206)
		(end 129.40284 -78.946756)
		(width 0.0889)
		(layer "In11.Cu")
		(net "VSENSE_PVCCIOMCP_CPU1_SKT_VSEN")
	)
	(arc
		(start 130.291078 -82.945986)
		(mid 130.150999 -82.80325)
		(end 129.959354 -82.746088)
		(width 0.0889)
		(layer "In11.Cu")
		(net "VSENSE_PVCCIOMCP_CPU1_SKT_VSEN")
	)
	(arc
		(start 142.808198 -90.20302)
		(mid 142.538406 -90.095391)
		(end 142.346426 -89.877392)
		(width 0.0889)
		(layer "In11.Cu")
		(net "VSENSE_PVCCIOMCP_CPU1_SKT_VSEN")
	)
	(arc
		(start 139.366244 -88.194134)
		(mid 139.083027 -88.109853)
		(end 138.876024 -87.898986)
		(width 0.0889)
		(layer "In11.Cu")
		(net "VSENSE_PVCCIOMCP_CPU1_SKT_VSEN")
	)
	(arc
		(start 134.583424 -85.422486)
		(mid 134.441741 -85.278682)
		(end 134.24789 -85.222334)
		(width 0.0889)
		(layer "In11.Cu")
		(net "VSENSE_PVCCIOMCP_CPU1_SKT_VSEN")
	)
	(arc
		(start 138.017504 -87.403686)
		(mid 137.875821 -87.259882)
		(end 137.68197 -87.203534)
		(width 0.0889)
		(layer "In11.Cu")
		(net "VSENSE_PVCCIOMCP_CPU1_SKT_VSEN")
	)
	(arc
		(start 140.228574 -88.689688)
		(mid 139.94315 -88.606221)
		(end 139.734544 -88.394286)
		(width 0.0889)
		(layer "In11.Cu")
		(net "VSENSE_PVCCIOMCP_CPU1_SKT_VSEN")
	)
	(arc
		(start 129.931414 -82.746088)
		(mid 129.429405 -82.445164)
		(end 129.432558 -81.859882)
		(width 0.0889)
		(layer "In11.Cu")
		(net "VSENSE_PVCCIOMCP_CPU1_SKT_VSEN")
	)
	(arc
		(start 132.494782 -84.231734)
		(mid 132.213482 -84.146768)
		(end 132.007864 -83.93684)
		(width 0.0889)
		(layer "In11.Cu")
		(net "VSENSE_PVCCIOMCP_CPU1_SKT_VSEN")
	)
	(arc
		(start 136.794494 -86.708488)
		(mid 136.50907 -86.625021)
		(end 136.300464 -86.413086)
		(width 0.0889)
		(layer "In11.Cu")
		(net "VSENSE_PVCCIOMCP_CPU1_SKT_VSEN")
	)
	(arc
		(start 129.432558 -79.878936)
		(mid 129.486028 -79.683873)
		(end 129.437384 -79.487522)
		(width 0.0889)
		(layer "In11.Cu")
		(net "VSENSE_PVCCIOMCP_CPU1_SKT_VSEN")
	)
	(arc
		(start 129.426208 -81.449418)
		(mid 129.35341 -81.158655)
		(end 129.432558 -80.869536)
		(width 0.0889)
		(layer "In11.Cu")
		(net "VSENSE_PVCCIOMCP_CPU1_SKT_VSEN")
	)
	(arc
		(start 141.451584 -89.384886)
		(mid 141.309901 -89.241082)
		(end 141.11605 -89.184734)
		(width 0.0889)
		(layer "In11.Cu")
		(net "VSENSE_PVCCIOMCP_CPU1_SKT_VSEN")
	)
	(arc
		(start 141.083284 -89.184734)
		(mid 140.800067 -89.100453)
		(end 140.593064 -88.889586)
		(width 0.0889)
		(layer "In11.Cu")
		(net "VSENSE_PVCCIOMCP_CPU1_SKT_VSEN")
	)
	(arc
		(start 133.724904 -84.927186)
		(mid 133.584825 -84.78445)
		(end 133.39318 -84.727288)
		(width 0.0889)
		(layer "In11.Cu")
		(net "VSENSE_PVCCIOMCP_CPU1_SKT_VSEN")
	)
	(arc
		(start 129.426208 -80.458818)
		(mid 129.35341 -80.168055)
		(end 129.432558 -79.878936)
		(width 0.0889)
		(layer "In11.Cu")
		(net "VSENSE_PVCCIOMCP_CPU1_SKT_VSEN")
	)
	(arc
		(start 129.432558 -81.859882)
		(mid 129.486057 -81.659984)
		(end 129.432558 -81.460086)
		(width 0.0889)
		(layer "In11.Cu")
		(net "VSENSE_PVCCIOMCP_CPU1_SKT_VSEN")
	)
	(arc
		(start 134.215124 -85.222334)
		(mid 133.931907 -85.138053)
		(end 133.724904 -84.927186)
		(width 0.0889)
		(layer "In11.Cu")
		(net "VSENSE_PVCCIOMCP_CPU1_SKT_VSEN")
	)
	(arc
		(start 131.643628 -83.736688)
		(mid 131.358204 -83.653221)
		(end 131.149598 -83.441286)
		(width 0.0889)
		(layer "In11.Cu")
		(net "VSENSE_PVCCIOMCP_CPU1_SKT_VSEN")
	)
	(arc
		(start 137.158984 -86.908386)
		(mid 137.018905 -86.76565)
		(end 136.82726 -86.708488)
		(width 0.0889)
		(layer "In11.Cu")
		(net "VSENSE_PVCCIOMCP_CPU1_SKT_VSEN")
	)
	(arc
		(start 135.077454 -85.717888)
		(mid 134.79203 -85.634421)
		(end 134.583424 -85.422486)
		(width 0.0889)
		(layer "In11.Cu")
		(net "VSENSE_PVCCIOMCP_CPU1_SKT_VSEN")
	)
	(arc
		(start 130.781298 -83.241134)
		(mid 130.498081 -83.156853)
		(end 130.291078 -82.945986)
		(width 0.0889)
		(layer "In11.Cu")
		(net "VSENSE_PVCCIOMCP_CPU1_SKT_VSEN")
	)
	(arc
		(start 131.149598 -83.441286)
		(mid 131.007915 -83.297482)
		(end 130.814064 -83.241134)
		(width 0.0889)
		(layer "In11.Cu")
		(net "VSENSE_PVCCIOMCP_CPU1_SKT_VSEN")
	)
	(arc
		(start 135.441944 -85.917786)
		(mid 135.301865 -85.77505)
		(end 135.11022 -85.717888)
		(width 0.0889)
		(layer "In11.Cu")
		(net "VSENSE_PVCCIOMCP_CPU1_SKT_VSEN")
	)
	(arc
		(start 140.593064 -88.889586)
		(mid 140.452985 -88.74685)
		(end 140.26134 -88.689688)
		(width 0.0889)
		(layer "In11.Cu")
		(net "VSENSE_PVCCIOMCP_CPU1_SKT_VSEN")
	)
	(arc
		(start 129.432558 -80.869536)
		(mid 129.486028 -80.674473)
		(end 129.437384 -80.478122)
		(width 0.0889)
		(layer "In11.Cu")
		(net "VSENSE_PVCCIOMCP_CPU1_SKT_VSEN")
	)
	(arc
		(start 137.649204 -87.203534)
		(mid 137.365987 -87.119253)
		(end 137.158984 -86.908386)
		(width 0.0889)
		(layer "In11.Cu")
		(net "VSENSE_PVCCIOMCP_CPU1_SKT_VSEN")
	)
	(segment
		(start 173.36135 -109.20095)
		(end 172.81398 -108.65358)
		(width 0.127)
		(layer "F.Cu")
		(net "VSENSE_PVCCIOMCP_CPU1_SKT_VRTN")
	)
	(segment
		(start 173.505114 -109.20095)
		(end 173.36135 -109.20095)
		(width 0.127)
		(layer "F.Cu")
		(net "VSENSE_PVCCIOMCP_CPU1_SKT_VRTN")
	)
	(segment
		(start 129.372868 -79.183738)
		(end 129.944368 -79.183738)
		(width 0.127)
		(layer "F.Cu")
		(net "VSENSE_PVCCIOMCP_CPU1_SKT_VRTN")
	)
	(via
		(at 129.944368 -79.183738)
		(size 0.508)
		(drill 0.254)
		(layers "F.Cu" "B.Cu")
		(net "VSENSE_PVCCIOMCP_CPU1_SKT_VRTN")
	)
	(via
		(at 172.81398 -108.65358)
		(size 0.508)
		(drill 0.254)
		(layers "F.Cu" "B.Cu")
		(net "VSENSE_PVCCIOMCP_CPU1_SKT_VRTN")
	)
	(segment
		(start 129.604008 -79.394304)
		(end 129.597658 -79.383636)
		(width 0.0889)
		(layer "In11.Cu")
		(net "VSENSE_PVCCIOMCP_CPU1_SKT_VRTN")
	)
	(segment
		(start 129.604008 -80.384904)
		(end 129.597658 -80.374236)
		(width 0.0889)
		(layer "In11.Cu")
		(net "VSENSE_PVCCIOMCP_CPU1_SKT_VRTN")
	)
	(segment
		(start 129.604008 -81.375504)
		(end 129.597658 -81.364836)
		(width 0.0889)
		(layer "In11.Cu")
		(net "VSENSE_PVCCIOMCP_CPU1_SKT_VRTN")
	)
	(segment
		(start 146.012916 -98.741484)
		(end 146.012916 -92.085922)
		(width 0.127)
		(layer "In11.Cu")
		(net "VSENSE_PVCCIOMCP_CPU1_SKT_VRTN")
	)
	(segment
		(start 134.254494 -85.031834)
		(end 134.221728 -85.031834)
		(width 0.0889)
		(layer "In11.Cu")
		(net "VSENSE_PVCCIOMCP_CPU1_SKT_VRTN")
	)
	(segment
		(start 138.550904 -87.508588)
		(end 138.518138 -87.508588)
		(width 0.0889)
		(layer "In11.Cu")
		(net "VSENSE_PVCCIOMCP_CPU1_SKT_VRTN")
	)
	(segment
		(start 172.68698 -109.05998)
		(end 156.331412 -109.05998)
		(width 0.127)
		(layer "In11.Cu")
		(net "VSENSE_PVCCIOMCP_CPU1_SKT_VRTN")
	)
	(segment
		(start 129.572512 -79.036164)
		(end 129.651252 -79.014828)
		(width 0.0889)
		(layer "In11.Cu")
		(net "VSENSE_PVCCIOMCP_CPU1_SKT_VRTN")
	)
	(segment
		(start 142.166594 -89.489788)
		(end 141.952218 -89.489788)
		(width 0.0889)
		(layer "In11.Cu")
		(net "VSENSE_PVCCIOMCP_CPU1_SKT_VRTN")
	)
	(segment
		(start 145.295874 -91.36888)
		(end 145.268442 -91.36888)
		(width 0.0889)
		(layer "In11.Cu")
		(net "VSENSE_PVCCIOMCP_CPU1_SKT_VRTN")
	)
	(segment
		(start 129.957322 -82.555334)
		(end 129.933192 -82.555334)
		(width 0.0889)
		(layer "In11.Cu")
		(net "VSENSE_PVCCIOMCP_CPU1_SKT_VRTN")
	)
	(segment
		(start 129.651252 -79.014828)
		(end 129.944368 -79.183738)
		(width 0.0889)
		(layer "In11.Cu")
		(net "VSENSE_PVCCIOMCP_CPU1_SKT_VRTN")
	)
	(segment
		(start 143.18742 -89.937336)
		(end 143.046704 -89.959434)
		(width 0.0889)
		(layer "In11.Cu")
		(net "VSENSE_PVCCIOMCP_CPU1_SKT_VRTN")
	)
	(segment
		(start 140.267944 -88.499188)
		(end 140.235178 -88.499188)
		(width 0.0889)
		(layer "In11.Cu")
		(net "VSENSE_PVCCIOMCP_CPU1_SKT_VRTN")
	)
	(segment
		(start 135.116824 -85.527388)
		(end 135.084058 -85.527388)
		(width 0.0889)
		(layer "In11.Cu")
		(net "VSENSE_PVCCIOMCP_CPU1_SKT_VRTN")
	)
	(segment
		(start 137.688574 -87.013034)
		(end 137.655808 -87.013034)
		(width 0.0889)
		(layer "In11.Cu")
		(net "VSENSE_PVCCIOMCP_CPU1_SKT_VRTN")
	)
	(segment
		(start 143.03629 -89.973658)
		(end 142.810484 -90.009218)
		(width 0.0889)
		(layer "In11.Cu")
		(net "VSENSE_PVCCIOMCP_CPU1_SKT_VRTN")
	)
	(segment
		(start 172.81398 -108.93298)
		(end 172.68698 -109.05998)
		(width 0.127)
		(layer "In11.Cu")
		(net "VSENSE_PVCCIOMCP_CPU1_SKT_VRTN")
	)
	(segment
		(start 139.405614 -88.003634)
		(end 139.372848 -88.003634)
		(width 0.0889)
		(layer "In11.Cu")
		(net "VSENSE_PVCCIOMCP_CPU1_SKT_VRTN")
	)
	(segment
		(start 143.046704 -89.959434)
		(end 143.04645 -89.959434)
		(width 0.0889)
		(layer "In11.Cu")
		(net "VSENSE_PVCCIOMCP_CPU1_SKT_VRTN")
	)
	(segment
		(start 136.833864 -86.517988)
		(end 136.801098 -86.517988)
		(width 0.0889)
		(layer "In11.Cu")
		(net "VSENSE_PVCCIOMCP_CPU1_SKT_VRTN")
	)
	(segment
		(start 146.012916 -92.085922)
		(end 145.311368 -91.384374)
		(width 0.127)
		(layer "In11.Cu")
		(net "VSENSE_PVCCIOMCP_CPU1_SKT_VRTN")
	)
	(segment
		(start 129.597658 -80.374236)
		(end 129.592832 -80.3656)
		(width 0.0889)
		(layer "In11.Cu")
		(net "VSENSE_PVCCIOMCP_CPU1_SKT_VRTN")
	)
	(segment
		(start 141.122654 -88.994234)
		(end 141.089888 -88.994234)
		(width 0.0889)
		(layer "In11.Cu")
		(net "VSENSE_PVCCIOMCP_CPU1_SKT_VRTN")
	)
	(segment
		(start 131.6863 -83.546188)
		(end 131.650232 -83.546188)
		(width 0.0889)
		(layer "In11.Cu")
		(net "VSENSE_PVCCIOMCP_CPU1_SKT_VRTN")
	)
	(segment
		(start 145.268442 -91.36888)
		(end 143.836898 -89.937336)
		(width 0.0889)
		(layer "In11.Cu")
		(net "VSENSE_PVCCIOMCP_CPU1_SKT_VRTN")
	)
	(segment
		(start 145.311368 -91.384374)
		(end 145.295874 -91.36888)
		(width 0.0889)
		(layer "In11.Cu")
		(net "VSENSE_PVCCIOMCP_CPU1_SKT_VRTN")
	)
	(segment
		(start 172.81398 -108.65358)
		(end 172.81398 -108.93298)
		(width 0.127)
		(layer "In11.Cu")
		(net "VSENSE_PVCCIOMCP_CPU1_SKT_VRTN")
	)
	(segment
		(start 143.836898 -89.937336)
		(end 143.18742 -89.937336)
		(width 0.0889)
		(layer "In11.Cu")
		(net "VSENSE_PVCCIOMCP_CPU1_SKT_VRTN")
	)
	(segment
		(start 129.597658 -81.364836)
		(end 129.592832 -81.3562)
		(width 0.0889)
		(layer "In11.Cu")
		(net "VSENSE_PVCCIOMCP_CPU1_SKT_VRTN")
	)
	(segment
		(start 132.17652 -83.846924)
		(end 132.173218 -83.841082)
		(width 0.0889)
		(layer "In11.Cu")
		(net "VSENSE_PVCCIOMCP_CPU1_SKT_VRTN")
	)
	(segment
		(start 156.331412 -109.05998)
		(end 146.012916 -98.741484)
		(width 0.127)
		(layer "In11.Cu")
		(net "VSENSE_PVCCIOMCP_CPU1_SKT_VRTN")
	)
	(segment
		(start 132.537454 -84.041234)
		(end 132.519674 -84.041234)
		(width 0.0889)
		(layer "In11.Cu")
		(net "VSENSE_PVCCIOMCP_CPU1_SKT_VRTN")
	)
	(segment
		(start 143.04645 -89.959434)
		(end 143.03629 -89.973658)
		(width 0.0889)
		(layer "In11.Cu")
		(net "VSENSE_PVCCIOMCP_CPU1_SKT_VRTN")
	)
	(segment
		(start 135.971534 -86.022434)
		(end 135.938768 -86.022434)
		(width 0.0889)
		(layer "In11.Cu")
		(net "VSENSE_PVCCIOMCP_CPU1_SKT_VRTN")
	)
	(segment
		(start 130.820668 -83.050634)
		(end 130.787902 -83.050634)
		(width 0.0889)
		(layer "In11.Cu")
		(net "VSENSE_PVCCIOMCP_CPU1_SKT_VRTN")
	)
	(segment
		(start 133.399784 -84.536788)
		(end 133.367018 -84.536788)
		(width 0.0889)
		(layer "In11.Cu")
		(net "VSENSE_PVCCIOMCP_CPU1_SKT_VRTN")
	)
	(arc
		(start 129.597658 -81.955386)
		(mid 129.67688 -81.666268)
		(end 129.604008 -81.375504)
		(width 0.0889)
		(layer "In11.Cu")
		(net "VSENSE_PVCCIOMCP_CPU1_SKT_VRTN")
	)
	(arc
		(start 141.089888 -88.994234)
		(mid 140.898246 -88.937068)
		(end 140.758164 -88.794336)
		(width 0.0889)
		(layer "In11.Cu")
		(net "VSENSE_PVCCIOMCP_CPU1_SKT_VRTN")
	)
	(arc
		(start 130.787902 -83.050634)
		(mid 130.59626 -82.993468)
		(end 130.456178 -82.850736)
		(width 0.0889)
		(layer "In11.Cu")
		(net "VSENSE_PVCCIOMCP_CPU1_SKT_VRTN")
	)
	(arc
		(start 134.221728 -85.031834)
		(mid 134.030086 -84.974668)
		(end 133.890004 -84.831936)
		(width 0.0889)
		(layer "In11.Cu")
		(net "VSENSE_PVCCIOMCP_CPU1_SKT_VRTN")
	)
	(arc
		(start 138.518138 -87.508588)
		(mid 138.324288 -87.452238)
		(end 138.182604 -87.308436)
		(width 0.0889)
		(layer "In11.Cu")
		(net "VSENSE_PVCCIOMCP_CPU1_SKT_VRTN")
	)
	(arc
		(start 141.952218 -89.489788)
		(mid 141.758368 -89.433438)
		(end 141.616684 -89.289636)
		(width 0.0889)
		(layer "In11.Cu")
		(net "VSENSE_PVCCIOMCP_CPU1_SKT_VRTN")
	)
	(arc
		(start 133.031484 -84.336636)
		(mid 132.822876 -84.124704)
		(end 132.537454 -84.041234)
		(width 0.0889)
		(layer "In11.Cu")
		(net "VSENSE_PVCCIOMCP_CPU1_SKT_VRTN")
	)
	(arc
		(start 129.933192 -82.555334)
		(mid 129.595077 -82.350632)
		(end 129.597658 -81.955386)
		(width 0.0889)
		(layer "In11.Cu")
		(net "VSENSE_PVCCIOMCP_CPU1_SKT_VRTN")
	)
	(arc
		(start 135.607044 -85.822536)
		(mid 135.40004 -85.611672)
		(end 135.116824 -85.527388)
		(width 0.0889)
		(layer "In11.Cu")
		(net "VSENSE_PVCCIOMCP_CPU1_SKT_VRTN")
	)
	(arc
		(start 139.372848 -88.003634)
		(mid 139.181206 -87.946468)
		(end 139.041124 -87.803736)
		(width 0.0889)
		(layer "In11.Cu")
		(net "VSENSE_PVCCIOMCP_CPU1_SKT_VRTN")
	)
	(arc
		(start 138.182604 -87.308436)
		(mid 137.973996 -87.096504)
		(end 137.688574 -87.013034)
		(width 0.0889)
		(layer "In11.Cu")
		(net "VSENSE_PVCCIOMCP_CPU1_SKT_VRTN")
	)
	(arc
		(start 142.515082 -89.78773)
		(mid 142.369157 -89.605643)
		(end 142.166594 -89.489788)
		(width 0.0889)
		(layer "In11.Cu")
		(net "VSENSE_PVCCIOMCP_CPU1_SKT_VRTN")
	)
	(arc
		(start 129.592832 -81.3562)
		(mid 129.544077 -81.159848)
		(end 129.597658 -80.964786)
		(width 0.0889)
		(layer "In11.Cu")
		(net "VSENSE_PVCCIOMCP_CPU1_SKT_VRTN")
	)
	(arc
		(start 139.041124 -87.803736)
		(mid 138.83412 -87.592872)
		(end 138.550904 -87.508588)
		(width 0.0889)
		(layer "In11.Cu")
		(net "VSENSE_PVCCIOMCP_CPU1_SKT_VRTN")
	)
	(arc
		(start 131.650232 -83.546188)
		(mid 131.456382 -83.489838)
		(end 131.314698 -83.346036)
		(width 0.0889)
		(layer "In11.Cu")
		(net "VSENSE_PVCCIOMCP_CPU1_SKT_VRTN")
	)
	(arc
		(start 135.084058 -85.527388)
		(mid 134.890208 -85.471038)
		(end 134.748524 -85.327236)
		(width 0.0889)
		(layer "In11.Cu")
		(net "VSENSE_PVCCIOMCP_CPU1_SKT_VRTN")
	)
	(arc
		(start 133.890004 -84.831936)
		(mid 133.683 -84.621072)
		(end 133.399784 -84.536788)
		(width 0.0889)
		(layer "In11.Cu")
		(net "VSENSE_PVCCIOMCP_CPU1_SKT_VRTN")
	)
	(arc
		(start 137.324084 -86.813136)
		(mid 137.11708 -86.602272)
		(end 136.833864 -86.517988)
		(width 0.0889)
		(layer "In11.Cu")
		(net "VSENSE_PVCCIOMCP_CPU1_SKT_VRTN")
	)
	(arc
		(start 129.597658 -79.383636)
		(mid 129.545324 -79.212787)
		(end 129.572512 -79.036164)
		(width 0.0889)
		(layer "In11.Cu")
		(net "VSENSE_PVCCIOMCP_CPU1_SKT_VRTN")
	)
	(arc
		(start 139.899644 -88.299036)
		(mid 139.691036 -88.087104)
		(end 139.405614 -88.003634)
		(width 0.0889)
		(layer "In11.Cu")
		(net "VSENSE_PVCCIOMCP_CPU1_SKT_VRTN")
	)
	(arc
		(start 140.235178 -88.499188)
		(mid 140.041328 -88.442838)
		(end 139.899644 -88.299036)
		(width 0.0889)
		(layer "In11.Cu")
		(net "VSENSE_PVCCIOMCP_CPU1_SKT_VRTN")
	)
	(arc
		(start 135.938768 -86.022434)
		(mid 135.747126 -85.965268)
		(end 135.607044 -85.822536)
		(width 0.0889)
		(layer "In11.Cu")
		(net "VSENSE_PVCCIOMCP_CPU1_SKT_VRTN")
	)
	(arc
		(start 129.597658 -79.974186)
		(mid 129.67688 -79.685068)
		(end 129.604008 -79.394304)
		(width 0.0889)
		(layer "In11.Cu")
		(net "VSENSE_PVCCIOMCP_CPU1_SKT_VRTN")
	)
	(arc
		(start 132.519674 -84.041234)
		(mid 132.322513 -83.989275)
		(end 132.17652 -83.846924)
		(width 0.0889)
		(layer "In11.Cu")
		(net "VSENSE_PVCCIOMCP_CPU1_SKT_VRTN")
	)
	(arc
		(start 134.748524 -85.327236)
		(mid 134.539916 -85.115304)
		(end 134.254494 -85.031834)
		(width 0.0889)
		(layer "In11.Cu")
		(net "VSENSE_PVCCIOMCP_CPU1_SKT_VRTN")
	)
	(arc
		(start 133.367018 -84.536788)
		(mid 133.173168 -84.480438)
		(end 133.031484 -84.336636)
		(width 0.0889)
		(layer "In11.Cu")
		(net "VSENSE_PVCCIOMCP_CPU1_SKT_VRTN")
	)
	(arc
		(start 131.314698 -83.346036)
		(mid 131.10609 -83.134104)
		(end 130.820668 -83.050634)
		(width 0.0889)
		(layer "In11.Cu")
		(net "VSENSE_PVCCIOMCP_CPU1_SKT_VRTN")
	)
	(arc
		(start 141.616684 -89.289636)
		(mid 141.408076 -89.077704)
		(end 141.122654 -88.994234)
		(width 0.0889)
		(layer "In11.Cu")
		(net "VSENSE_PVCCIOMCP_CPU1_SKT_VRTN")
	)
	(arc
		(start 140.758164 -88.794336)
		(mid 140.55116 -88.583472)
		(end 140.267944 -88.499188)
		(width 0.0889)
		(layer "In11.Cu")
		(net "VSENSE_PVCCIOMCP_CPU1_SKT_VRTN")
	)
	(arc
		(start 129.597658 -80.964786)
		(mid 129.67688 -80.675668)
		(end 129.604008 -80.384904)
		(width 0.0889)
		(layer "In11.Cu")
		(net "VSENSE_PVCCIOMCP_CPU1_SKT_VRTN")
	)
	(arc
		(start 137.655808 -87.013034)
		(mid 137.464166 -86.955868)
		(end 137.324084 -86.813136)
		(width 0.0889)
		(layer "In11.Cu")
		(net "VSENSE_PVCCIOMCP_CPU1_SKT_VRTN")
	)
	(arc
		(start 132.173218 -83.841082)
		(mid 131.967597 -83.631159)
		(end 131.6863 -83.546188)
		(width 0.0889)
		(layer "In11.Cu")
		(net "VSENSE_PVCCIOMCP_CPU1_SKT_VRTN")
	)
	(arc
		(start 136.801098 -86.517988)
		(mid 136.607248 -86.461638)
		(end 136.465564 -86.317836)
		(width 0.0889)
		(layer "In11.Cu")
		(net "VSENSE_PVCCIOMCP_CPU1_SKT_VRTN")
	)
	(arc
		(start 142.810484 -90.009218)
		(mid 142.638054 -89.931472)
		(end 142.515082 -89.78773)
		(width 0.0889)
		(layer "In11.Cu")
		(net "VSENSE_PVCCIOMCP_CPU1_SKT_VRTN")
	)
	(arc
		(start 130.456178 -82.850736)
		(mid 130.245465 -82.637657)
		(end 129.957322 -82.555334)
		(width 0.0889)
		(layer "In11.Cu")
		(net "VSENSE_PVCCIOMCP_CPU1_SKT_VRTN")
	)
	(arc
		(start 136.465564 -86.317836)
		(mid 136.256956 -86.105904)
		(end 135.971534 -86.022434)
		(width 0.0889)
		(layer "In11.Cu")
		(net "VSENSE_PVCCIOMCP_CPU1_SKT_VRTN")
	)
	(arc
		(start 129.592832 -80.3656)
		(mid 129.544077 -80.169248)
		(end 129.597658 -79.974186)
		(width 0.0889)
		(layer "In11.Cu")
		(net "VSENSE_PVCCIOMCP_CPU1_SKT_VRTN")
	)
	(segment
		(start 338.484972 -110.47095)
		(end 338.4804 -110.49)
		(width 0.127)
		(layer "F.Cu")
		(net "VSENSE_PVCCIOMCP_CPU0_SKT_VSEN")
	)
	(segment
		(start 338.4804 -110.49)
		(end 339.1154 -109.855)
		(width 0.127)
		(layer "F.Cu")
		(net "VSENSE_PVCCIOMCP_CPU0_SKT_VSEN")
	)
	(segment
		(start 293.51478 -78.688438)
		(end 294.08628 -78.688438)
		(width 0.127)
		(layer "F.Cu")
		(net "VSENSE_PVCCIOMCP_CPU0_SKT_VSEN")
	)
	(via
		(at 335.101438 -75.407012)
		(size 0.508)
		(drill 0.254)
		(layers "F.Cu" "B.Cu")
		(net "VSENSE_PVCCIOMCP_CPU0_SKT_VSEN")
	)
	(via
		(at 294.08628 -78.688438)
		(size 0.508)
		(drill 0.254)
		(layers "F.Cu" "B.Cu")
		(net "VSENSE_PVCCIOMCP_CPU0_SKT_VSEN")
	)
	(via
		(at 339.1154 -109.855)
		(size 0.508)
		(drill 0.254)
		(layers "F.Cu" "B.Cu")
		(net "VSENSE_PVCCIOMCP_CPU0_SKT_VSEN")
	)
	(segment
		(start 339.254338 -109.324902)
		(end 339.541104 -109.324902)
		(width 0.127)
		(layer "In9.Cu")
		(net "VSENSE_PVCCIOMCP_CPU0_SKT_VSEN")
	)
	(segment
		(start 335.5086 -89.124536)
		(end 334.657446 -88.273382)
		(width 0.127)
		(layer "In9.Cu")
		(net "VSENSE_PVCCIOMCP_CPU0_SKT_VSEN")
	)
	(segment
		(start 339.1154 -109.46384)
		(end 339.254338 -109.324902)
		(width 0.127)
		(layer "In9.Cu")
		(net "VSENSE_PVCCIOMCP_CPU0_SKT_VSEN")
	)
	(segment
		(start 339.541104 -109.324902)
		(end 339.93074 -108.935266)
		(width 0.127)
		(layer "In9.Cu")
		(net "VSENSE_PVCCIOMCP_CPU0_SKT_VSEN")
	)
	(segment
		(start 339.93074 -108.935266)
		(end 339.93074 -106.007154)
		(width 0.127)
		(layer "In9.Cu")
		(net "VSENSE_PVCCIOMCP_CPU0_SKT_VSEN")
	)
	(segment
		(start 334.657446 -81.04632)
		(end 336.03438 -79.669386)
		(width 0.127)
		(layer "In9.Cu")
		(net "VSENSE_PVCCIOMCP_CPU0_SKT_VSEN")
	)
	(segment
		(start 336.03438 -76.156312)
		(end 335.75879 -75.880722)
		(width 0.127)
		(layer "In9.Cu")
		(net "VSENSE_PVCCIOMCP_CPU0_SKT_VSEN")
	)
	(segment
		(start 334.657446 -88.273382)
		(end 334.657446 -81.04632)
		(width 0.127)
		(layer "In9.Cu")
		(net "VSENSE_PVCCIOMCP_CPU0_SKT_VSEN")
	)
	(segment
		(start 335.5086 -90.75039)
		(end 335.5086 -89.124536)
		(width 0.127)
		(layer "In9.Cu")
		(net "VSENSE_PVCCIOMCP_CPU0_SKT_VSEN")
	)
	(segment
		(start 336.03438 -79.669386)
		(end 336.03438 -76.156312)
		(width 0.127)
		(layer "In9.Cu")
		(net "VSENSE_PVCCIOMCP_CPU0_SKT_VSEN")
	)
	(segment
		(start 339.93074 -106.007154)
		(end 339.20557 -105.281984)
		(width 0.127)
		(layer "In9.Cu")
		(net "VSENSE_PVCCIOMCP_CPU0_SKT_VSEN")
	)
	(segment
		(start 335.575148 -75.880722)
		(end 335.101438 -75.407012)
		(width 0.127)
		(layer "In9.Cu")
		(net "VSENSE_PVCCIOMCP_CPU0_SKT_VSEN")
	)
	(segment
		(start 339.74786 -99.16668)
		(end 339.74786 -94.98965)
		(width 0.127)
		(layer "In9.Cu")
		(net "VSENSE_PVCCIOMCP_CPU0_SKT_VSEN")
	)
	(segment
		(start 339.74786 -94.98965)
		(end 335.5086 -90.75039)
		(width 0.127)
		(layer "In9.Cu")
		(net "VSENSE_PVCCIOMCP_CPU0_SKT_VSEN")
	)
	(segment
		(start 339.20557 -99.70897)
		(end 339.74786 -99.16668)
		(width 0.127)
		(layer "In9.Cu")
		(net "VSENSE_PVCCIOMCP_CPU0_SKT_VSEN")
	)
	(segment
		(start 339.1154 -109.855)
		(end 339.1154 -109.46384)
		(width 0.127)
		(layer "In9.Cu")
		(net "VSENSE_PVCCIOMCP_CPU0_SKT_VSEN")
	)
	(segment
		(start 339.20557 -105.281984)
		(end 339.20557 -99.70897)
		(width 0.127)
		(layer "In9.Cu")
		(net "VSENSE_PVCCIOMCP_CPU0_SKT_VSEN")
	)
	(segment
		(start 335.75879 -75.880722)
		(end 335.575148 -75.880722)
		(width 0.127)
		(layer "In9.Cu")
		(net "VSENSE_PVCCIOMCP_CPU0_SKT_VSEN")
	)
	(segment
		(start 302.68926 -79.088234)
		(end 302.653446 -79.088234)
		(width 0.0889)
		(layer "In11.Cu")
		(net "VSENSE_PVCCIOMCP_CPU0_SKT_VSEN")
	)
	(segment
		(start 296.66184 -79.583788)
		(end 296.650664 -79.583788)
		(width 0.0889)
		(layer "In11.Cu")
		(net "VSENSE_PVCCIOMCP_CPU0_SKT_VSEN")
	)
	(segment
		(start 295.8211 -79.088234)
		(end 295.785286 -79.088234)
		(width 0.0889)
		(layer "In11.Cu")
		(net "VSENSE_PVCCIOMCP_CPU0_SKT_VSEN")
	)
	(segment
		(start 301.823882 -79.583788)
		(end 301.80153 -79.583788)
		(width 0.0889)
		(layer "In11.Cu")
		(net "VSENSE_PVCCIOMCP_CPU0_SKT_VSEN")
	)
	(segment
		(start 300.971966 -79.088234)
		(end 300.936406 -79.088234)
		(width 0.0889)
		(layer "In11.Cu")
		(net "VSENSE_PVCCIOMCP_CPU0_SKT_VSEN")
	)
	(segment
		(start 300.106842 -79.583788)
		(end 300.08449 -79.583788)
		(width 0.0889)
		(layer "In11.Cu")
		(net "VSENSE_PVCCIOMCP_CPU0_SKT_VSEN")
	)
	(segment
		(start 309.703216 -77.935074)
		(end 308.45379 -79.1845)
		(width 0.127)
		(layer "In11.Cu")
		(net "VSENSE_PVCCIOMCP_CPU0_SKT_VSEN")
	)
	(segment
		(start 333.866998 -75.7809)
		(end 332.594204 -77.053694)
		(width 0.127)
		(layer "In11.Cu")
		(net "VSENSE_PVCCIOMCP_CPU0_SKT_VSEN")
	)
	(segment
		(start 305.040792 -79.056738)
		(end 305.018694 -79.056738)
		(width 0.0889)
		(layer "In11.Cu")
		(net "VSENSE_PVCCIOMCP_CPU0_SKT_VSEN")
	)
	(segment
		(start 303.551336 -78.593188)
		(end 303.508156 -78.593188)
		(width 0.0889)
		(layer "In11.Cu")
		(net "VSENSE_PVCCIOMCP_CPU0_SKT_VSEN")
	)
	(segment
		(start 305.830986 -79.1845)
		(end 305.703224 -79.056738)
		(width 0.127)
		(layer "In11.Cu")
		(net "VSENSE_PVCCIOMCP_CPU0_SKT_VSEN")
	)
	(segment
		(start 294.468804 -78.833218)
		(end 294.379396 -78.857348)
		(width 0.0889)
		(layer "In11.Cu")
		(net "VSENSE_PVCCIOMCP_CPU0_SKT_VSEN")
	)
	(segment
		(start 297.537886 -79.088234)
		(end 297.502326 -79.088234)
		(width 0.0889)
		(layer "In11.Cu")
		(net "VSENSE_PVCCIOMCP_CPU0_SKT_VSEN")
	)
	(segment
		(start 294.96639 -78.593188)
		(end 294.92321 -78.593188)
		(width 0.0889)
		(layer "In11.Cu")
		(net "VSENSE_PVCCIOMCP_CPU0_SKT_VSEN")
	)
	(segment
		(start 299.254926 -79.088234)
		(end 299.219366 -79.088234)
		(width 0.0889)
		(layer "In11.Cu")
		(net "VSENSE_PVCCIOMCP_CPU0_SKT_VSEN")
	)
	(segment
		(start 335.101438 -75.407012)
		(end 334.72755 -75.7809)
		(width 0.127)
		(layer "In11.Cu")
		(net "VSENSE_PVCCIOMCP_CPU0_SKT_VSEN")
	)
	(segment
		(start 332.594204 -77.053694)
		(end 331.357224 -77.053694)
		(width 0.127)
		(layer "In11.Cu")
		(net "VSENSE_PVCCIOMCP_CPU0_SKT_VSEN")
	)
	(segment
		(start 297.008296 -79.383636)
		(end 297.004994 -79.389478)
		(width 0.0889)
		(layer "In11.Cu")
		(net "VSENSE_PVCCIOMCP_CPU0_SKT_VSEN")
	)
	(segment
		(start 334.72755 -75.7809)
		(end 333.866998 -75.7809)
		(width 0.127)
		(layer "In11.Cu")
		(net "VSENSE_PVCCIOMCP_CPU0_SKT_VSEN")
	)
	(segment
		(start 304.987198 -79.088234)
		(end 304.370232 -79.088234)
		(width 0.0889)
		(layer "In11.Cu")
		(net "VSENSE_PVCCIOMCP_CPU0_SKT_VSEN")
	)
	(segment
		(start 305.018694 -79.056738)
		(end 304.987198 -79.088234)
		(width 0.0889)
		(layer "In11.Cu")
		(net "VSENSE_PVCCIOMCP_CPU0_SKT_VSEN")
	)
	(segment
		(start 294.379396 -78.857348)
		(end 294.08628 -78.688438)
		(width 0.0889)
		(layer "In11.Cu")
		(net "VSENSE_PVCCIOMCP_CPU0_SKT_VSEN")
	)
	(segment
		(start 305.703224 -79.056738)
		(end 305.040792 -79.056738)
		(width 0.127)
		(layer "In11.Cu")
		(net "VSENSE_PVCCIOMCP_CPU0_SKT_VSEN")
	)
	(segment
		(start 298.389802 -79.583788)
		(end 298.36745 -79.583788)
		(width 0.0889)
		(layer "In11.Cu")
		(net "VSENSE_PVCCIOMCP_CPU0_SKT_VSEN")
	)
	(segment
		(start 331.357224 -77.053694)
		(end 330.475844 -77.935074)
		(width 0.127)
		(layer "In11.Cu")
		(net "VSENSE_PVCCIOMCP_CPU0_SKT_VSEN")
	)
	(segment
		(start 308.45379 -79.1845)
		(end 305.830986 -79.1845)
		(width 0.127)
		(layer "In11.Cu")
		(net "VSENSE_PVCCIOMCP_CPU0_SKT_VSEN")
	)
	(segment
		(start 330.475844 -77.935074)
		(end 309.703216 -77.935074)
		(width 0.127)
		(layer "In11.Cu")
		(net "VSENSE_PVCCIOMCP_CPU0_SKT_VSEN")
	)
	(arc
		(start 298.031916 -79.383636)
		(mid 297.823308 -79.171704)
		(end 297.537886 -79.088234)
		(width 0.0889)
		(layer "In11.Cu")
		(net "VSENSE_PVCCIOMCP_CPU0_SKT_VSEN")
	)
	(arc
		(start 304.041556 -78.888336)
		(mid 303.834552 -78.677472)
		(end 303.551336 -78.593188)
		(width 0.0889)
		(layer "In11.Cu")
		(net "VSENSE_PVCCIOMCP_CPU0_SKT_VSEN")
	)
	(arc
		(start 294.92321 -78.593188)
		(mid 294.668545 -78.661217)
		(end 294.468804 -78.833218)
		(width 0.0889)
		(layer "In11.Cu")
		(net "VSENSE_PVCCIOMCP_CPU0_SKT_VSEN")
	)
	(arc
		(start 301.465996 -79.383636)
		(mid 301.257388 -79.171704)
		(end 300.971966 -79.088234)
		(width 0.0889)
		(layer "In11.Cu")
		(net "VSENSE_PVCCIOMCP_CPU0_SKT_VSEN")
	)
	(arc
		(start 300.08449 -79.583788)
		(mid 299.89064 -79.527438)
		(end 299.748956 -79.383636)
		(width 0.0889)
		(layer "In11.Cu")
		(net "VSENSE_PVCCIOMCP_CPU0_SKT_VSEN")
	)
	(arc
		(start 299.219366 -79.088234)
		(mid 298.933942 -79.171701)
		(end 298.725336 -79.383636)
		(width 0.0889)
		(layer "In11.Cu")
		(net "VSENSE_PVCCIOMCP_CPU0_SKT_VSEN")
	)
	(arc
		(start 299.748956 -79.383636)
		(mid 299.540348 -79.171704)
		(end 299.254926 -79.088234)
		(width 0.0889)
		(layer "In11.Cu")
		(net "VSENSE_PVCCIOMCP_CPU0_SKT_VSEN")
	)
	(arc
		(start 303.017936 -78.888336)
		(mid 302.879192 -79.030369)
		(end 302.68926 -79.088234)
		(width 0.0889)
		(layer "In11.Cu")
		(net "VSENSE_PVCCIOMCP_CPU0_SKT_VSEN")
	)
	(arc
		(start 296.650664 -79.583788)
		(mid 296.456814 -79.527438)
		(end 296.31513 -79.383636)
		(width 0.0889)
		(layer "In11.Cu")
		(net "VSENSE_PVCCIOMCP_CPU0_SKT_VSEN")
	)
	(arc
		(start 297.004994 -79.389478)
		(mid 296.859028 -79.531877)
		(end 296.66184 -79.583788)
		(width 0.0889)
		(layer "In11.Cu")
		(net "VSENSE_PVCCIOMCP_CPU0_SKT_VSEN")
	)
	(arc
		(start 295.785286 -79.088234)
		(mid 295.595357 -79.030364)
		(end 295.45661 -78.888336)
		(width 0.0889)
		(layer "In11.Cu")
		(net "VSENSE_PVCCIOMCP_CPU0_SKT_VSEN")
	)
	(arc
		(start 304.370232 -79.088234)
		(mid 304.180303 -79.030364)
		(end 304.041556 -78.888336)
		(width 0.0889)
		(layer "In11.Cu")
		(net "VSENSE_PVCCIOMCP_CPU0_SKT_VSEN")
	)
	(arc
		(start 300.936406 -79.088234)
		(mid 300.650982 -79.171701)
		(end 300.442376 -79.383636)
		(width 0.0889)
		(layer "In11.Cu")
		(net "VSENSE_PVCCIOMCP_CPU0_SKT_VSEN")
	)
	(arc
		(start 295.45661 -78.888336)
		(mid 295.249606 -78.677472)
		(end 294.96639 -78.593188)
		(width 0.0889)
		(layer "In11.Cu")
		(net "VSENSE_PVCCIOMCP_CPU0_SKT_VSEN")
	)
	(arc
		(start 298.725336 -79.383636)
		(mid 298.583653 -79.52744)
		(end 298.389802 -79.583788)
		(width 0.0889)
		(layer "In11.Cu")
		(net "VSENSE_PVCCIOMCP_CPU0_SKT_VSEN")
	)
	(arc
		(start 302.159416 -79.383636)
		(mid 302.017733 -79.52744)
		(end 301.823882 -79.583788)
		(width 0.0889)
		(layer "In11.Cu")
		(net "VSENSE_PVCCIOMCP_CPU0_SKT_VSEN")
	)
	(arc
		(start 300.442376 -79.383636)
		(mid 300.300693 -79.52744)
		(end 300.106842 -79.583788)
		(width 0.0889)
		(layer "In11.Cu")
		(net "VSENSE_PVCCIOMCP_CPU0_SKT_VSEN")
	)
	(arc
		(start 296.31513 -79.383636)
		(mid 296.106522 -79.171704)
		(end 295.8211 -79.088234)
		(width 0.0889)
		(layer "In11.Cu")
		(net "VSENSE_PVCCIOMCP_CPU0_SKT_VSEN")
	)
	(arc
		(start 298.36745 -79.583788)
		(mid 298.1736 -79.527438)
		(end 298.031916 -79.383636)
		(width 0.0889)
		(layer "In11.Cu")
		(net "VSENSE_PVCCIOMCP_CPU0_SKT_VSEN")
	)
	(arc
		(start 302.653446 -79.088234)
		(mid 302.368022 -79.171701)
		(end 302.159416 -79.383636)
		(width 0.0889)
		(layer "In11.Cu")
		(net "VSENSE_PVCCIOMCP_CPU0_SKT_VSEN")
	)
	(arc
		(start 301.80153 -79.583788)
		(mid 301.60768 -79.527438)
		(end 301.465996 -79.383636)
		(width 0.0889)
		(layer "In11.Cu")
		(net "VSENSE_PVCCIOMCP_CPU0_SKT_VSEN")
	)
	(arc
		(start 303.508156 -78.593188)
		(mid 303.224939 -78.677469)
		(end 303.017936 -78.888336)
		(width 0.0889)
		(layer "In11.Cu")
		(net "VSENSE_PVCCIOMCP_CPU0_SKT_VSEN")
	)
	(arc
		(start 297.502326 -79.088234)
		(mid 297.216902 -79.171701)
		(end 297.008296 -79.383636)
		(width 0.0889)
		(layer "In11.Cu")
		(net "VSENSE_PVCCIOMCP_CPU0_SKT_VSEN")
	)
	(segment
		(start 338.4804 -109.22)
		(end 338.484972 -109.20095)
		(width 0.127)
		(layer "F.Cu")
		(net "VSENSE_PVCCIOMCP_CPU0_SKT_VRTN")
	)
	(segment
		(start 294.3733 -79.183738)
		(end 294.9448 -79.183738)
		(width 0.127)
		(layer "F.Cu")
		(net "VSENSE_PVCCIOMCP_CPU0_SKT_VRTN")
	)
	(segment
		(start 339.1154 -108.585)
		(end 338.4804 -109.22)
		(width 0.127)
		(layer "F.Cu")
		(net "VSENSE_PVCCIOMCP_CPU0_SKT_VRTN")
	)
	(via
		(at 294.9448 -79.183738)
		(size 0.508)
		(drill 0.254)
		(layers "F.Cu" "B.Cu")
		(net "VSENSE_PVCCIOMCP_CPU0_SKT_VRTN")
	)
	(via
		(at 335.10474 -76.40193)
		(size 0.508)
		(drill 0.254)
		(layers "F.Cu" "B.Cu")
		(net "VSENSE_PVCCIOMCP_CPU0_SKT_VRTN")
	)
	(via
		(at 339.1154 -108.585)
		(size 0.508)
		(drill 0.254)
		(layers "F.Cu" "B.Cu")
		(net "VSENSE_PVCCIOMCP_CPU0_SKT_VRTN")
	)
	(segment
		(start 335.2546 -90.8558)
		(end 335.2546 -89.229946)
		(width 0.127)
		(layer "In9.Cu")
		(net "VSENSE_PVCCIOMCP_CPU0_SKT_VRTN")
	)
	(segment
		(start 339.435694 -109.070902)
		(end 339.67674 -108.829856)
		(width 0.127)
		(layer "In9.Cu")
		(net "VSENSE_PVCCIOMCP_CPU0_SKT_VRTN")
	)
	(segment
		(start 334.403446 -80.94091)
		(end 335.78038 -79.563976)
		(width 0.127)
		(layer "In9.Cu")
		(net "VSENSE_PVCCIOMCP_CPU0_SKT_VRTN")
	)
	(segment
		(start 338.95157 -105.387394)
		(end 338.95157 -99.60356)
		(width 0.127)
		(layer "In9.Cu")
		(net "VSENSE_PVCCIOMCP_CPU0_SKT_VRTN")
	)
	(segment
		(start 339.67674 -108.829856)
		(end 339.67674 -106.112564)
		(width 0.127)
		(layer "In9.Cu")
		(net "VSENSE_PVCCIOMCP_CPU0_SKT_VRTN")
	)
	(segment
		(start 339.49386 -99.06127)
		(end 339.49386 -95.09506)
		(width 0.127)
		(layer "In9.Cu")
		(net "VSENSE_PVCCIOMCP_CPU0_SKT_VRTN")
	)
	(segment
		(start 338.95157 -99.60356)
		(end 339.49386 -99.06127)
		(width 0.127)
		(layer "In9.Cu")
		(net "VSENSE_PVCCIOMCP_CPU0_SKT_VRTN")
	)
	(segment
		(start 339.242654 -109.070902)
		(end 339.435694 -109.070902)
		(width 0.127)
		(layer "In9.Cu")
		(net "VSENSE_PVCCIOMCP_CPU0_SKT_VRTN")
	)
	(segment
		(start 335.78038 -76.261722)
		(end 335.65338 -76.134722)
		(width 0.127)
		(layer "In9.Cu")
		(net "VSENSE_PVCCIOMCP_CPU0_SKT_VRTN")
	)
	(segment
		(start 335.65338 -76.134722)
		(end 335.371948 -76.134722)
		(width 0.127)
		(layer "In9.Cu")
		(net "VSENSE_PVCCIOMCP_CPU0_SKT_VRTN")
	)
	(segment
		(start 334.403446 -88.378792)
		(end 334.403446 -80.94091)
		(width 0.127)
		(layer "In9.Cu")
		(net "VSENSE_PVCCIOMCP_CPU0_SKT_VRTN")
	)
	(segment
		(start 335.78038 -79.563976)
		(end 335.78038 -76.261722)
		(width 0.127)
		(layer "In9.Cu")
		(net "VSENSE_PVCCIOMCP_CPU0_SKT_VRTN")
	)
	(segment
		(start 335.371948 -76.134722)
		(end 335.10474 -76.40193)
		(width 0.127)
		(layer "In9.Cu")
		(net "VSENSE_PVCCIOMCP_CPU0_SKT_VRTN")
	)
	(segment
		(start 339.1154 -108.943648)
		(end 339.242654 -109.070902)
		(width 0.127)
		(layer "In9.Cu")
		(net "VSENSE_PVCCIOMCP_CPU0_SKT_VRTN")
	)
	(segment
		(start 339.49386 -95.09506)
		(end 335.2546 -90.8558)
		(width 0.127)
		(layer "In9.Cu")
		(net "VSENSE_PVCCIOMCP_CPU0_SKT_VRTN")
	)
	(segment
		(start 339.1154 -108.585)
		(end 339.1154 -108.943648)
		(width 0.127)
		(layer "In9.Cu")
		(net "VSENSE_PVCCIOMCP_CPU0_SKT_VRTN")
	)
	(segment
		(start 339.67674 -106.112564)
		(end 338.95157 -105.387394)
		(width 0.127)
		(layer "In9.Cu")
		(net "VSENSE_PVCCIOMCP_CPU0_SKT_VRTN")
	)
	(segment
		(start 335.2546 -89.229946)
		(end 334.403446 -88.378792)
		(width 0.127)
		(layer "In9.Cu")
		(net "VSENSE_PVCCIOMCP_CPU0_SKT_VRTN")
	)
	(segment
		(start 305.725576 -79.4385)
		(end 308.5592 -79.4385)
		(width 0.127)
		(layer "In11.Cu")
		(net "VSENSE_PVCCIOMCP_CPU0_SKT_VRTN")
	)
	(segment
		(start 294.651684 -79.014828)
		(end 294.630602 -78.936088)
		(width 0.0889)
		(layer "In11.Cu")
		(net "VSENSE_PVCCIOMCP_CPU0_SKT_VRTN")
	)
	(segment
		(start 305.018694 -79.310738)
		(end 305.040792 -79.310738)
		(width 0.0889)
		(layer "In11.Cu")
		(net "VSENSE_PVCCIOMCP_CPU0_SKT_VRTN")
	)
	(segment
		(start 305.040792 -79.310738)
		(end 305.597814 -79.310738)
		(width 0.127)
		(layer "In11.Cu")
		(net "VSENSE_PVCCIOMCP_CPU0_SKT_VRTN")
	)
	(segment
		(start 294.9448 -79.183738)
		(end 294.651684 -79.014828)
		(width 0.0889)
		(layer "In11.Cu")
		(net "VSENSE_PVCCIOMCP_CPU0_SKT_VRTN")
	)
	(segment
		(start 332.699614 -77.307694)
		(end 333.972408 -76.0349)
		(width 0.127)
		(layer "In11.Cu")
		(net "VSENSE_PVCCIOMCP_CPU0_SKT_VRTN")
	)
	(segment
		(start 294.933624 -78.783688)
		(end 294.955976 -78.783688)
		(width 0.0889)
		(layer "In11.Cu")
		(net "VSENSE_PVCCIOMCP_CPU0_SKT_VRTN")
	)
	(segment
		(start 300.077886 -79.774288)
		(end 300.113446 -79.774288)
		(width 0.0889)
		(layer "In11.Cu")
		(net "VSENSE_PVCCIOMCP_CPU0_SKT_VRTN")
	)
	(segment
		(start 334.731106 -76.0349)
		(end 335.101438 -76.405232)
		(width 0.127)
		(layer "In11.Cu")
		(net "VSENSE_PVCCIOMCP_CPU0_SKT_VRTN")
	)
	(segment
		(start 330.581254 -78.189074)
		(end 331.462634 -77.307694)
		(width 0.127)
		(layer "In11.Cu")
		(net "VSENSE_PVCCIOMCP_CPU0_SKT_VRTN")
	)
	(segment
		(start 304.986944 -79.278988)
		(end 305.018694 -79.310738)
		(width 0.0889)
		(layer "In11.Cu")
		(net "VSENSE_PVCCIOMCP_CPU0_SKT_VRTN")
	)
	(segment
		(start 299.219112 -79.278988)
		(end 299.25518 -79.278988)
		(width 0.0889)
		(layer "In11.Cu")
		(net "VSENSE_PVCCIOMCP_CPU0_SKT_VRTN")
	)
	(segment
		(start 302.653192 -79.278988)
		(end 302.692816 -79.278988)
		(width 0.0889)
		(layer "In11.Cu")
		(net "VSENSE_PVCCIOMCP_CPU0_SKT_VRTN")
	)
	(segment
		(start 297.507914 -79.278988)
		(end 297.53814 -79.278988)
		(width 0.0889)
		(layer "In11.Cu")
		(net "VSENSE_PVCCIOMCP_CPU0_SKT_VRTN")
	)
	(segment
		(start 298.360846 -79.774288)
		(end 298.396406 -79.774288)
		(width 0.0889)
		(layer "In11.Cu")
		(net "VSENSE_PVCCIOMCP_CPU0_SKT_VRTN")
	)
	(segment
		(start 335.101438 -76.40193)
		(end 335.10474 -76.40193)
		(width 0.127)
		(layer "In11.Cu")
		(net "VSENSE_PVCCIOMCP_CPU0_SKT_VRTN")
	)
	(segment
		(start 303.51857 -78.783688)
		(end 303.540922 -78.783688)
		(width 0.0889)
		(layer "In11.Cu")
		(net "VSENSE_PVCCIOMCP_CPU0_SKT_VRTN")
	)
	(segment
		(start 309.808626 -78.189074)
		(end 330.581254 -78.189074)
		(width 0.127)
		(layer "In11.Cu")
		(net "VSENSE_PVCCIOMCP_CPU0_SKT_VRTN")
	)
	(segment
		(start 304.366676 -79.278988)
		(end 304.986944 -79.278988)
		(width 0.0889)
		(layer "In11.Cu")
		(net "VSENSE_PVCCIOMCP_CPU0_SKT_VRTN")
	)
	(segment
		(start 333.972408 -76.0349)
		(end 334.731106 -76.0349)
		(width 0.127)
		(layer "In11.Cu")
		(net "VSENSE_PVCCIOMCP_CPU0_SKT_VRTN")
	)
	(segment
		(start 300.936152 -79.278988)
		(end 300.97222 -79.278988)
		(width 0.0889)
		(layer "In11.Cu")
		(net "VSENSE_PVCCIOMCP_CPU0_SKT_VRTN")
	)
	(segment
		(start 296.64406 -79.774288)
		(end 296.67962 -79.774288)
		(width 0.0889)
		(layer "In11.Cu")
		(net "VSENSE_PVCCIOMCP_CPU0_SKT_VRTN")
	)
	(segment
		(start 301.794926 -79.774288)
		(end 301.830486 -79.774288)
		(width 0.0889)
		(layer "In11.Cu")
		(net "VSENSE_PVCCIOMCP_CPU0_SKT_VRTN")
	)
	(segment
		(start 331.462634 -77.307694)
		(end 332.699614 -77.307694)
		(width 0.127)
		(layer "In11.Cu")
		(net "VSENSE_PVCCIOMCP_CPU0_SKT_VRTN")
	)
	(segment
		(start 295.78173 -79.278988)
		(end 295.821354 -79.278988)
		(width 0.0889)
		(layer "In11.Cu")
		(net "VSENSE_PVCCIOMCP_CPU0_SKT_VRTN")
	)
	(segment
		(start 335.101438 -76.405232)
		(end 335.101438 -76.40193)
		(width 0.127)
		(layer "In11.Cu")
		(net "VSENSE_PVCCIOMCP_CPU0_SKT_VRTN")
	)
	(segment
		(start 305.597814 -79.310738)
		(end 305.725576 -79.4385)
		(width 0.127)
		(layer "In11.Cu")
		(net "VSENSE_PVCCIOMCP_CPU0_SKT_VRTN")
	)
	(segment
		(start 308.5592 -79.4385)
		(end 309.808626 -78.189074)
		(width 0.127)
		(layer "In11.Cu")
		(net "VSENSE_PVCCIOMCP_CPU0_SKT_VRTN")
	)
	(arc
		(start 299.583856 -79.478886)
		(mid 299.792464 -79.690818)
		(end 300.077886 -79.774288)
		(width 0.0889)
		(layer "In11.Cu")
		(net "VSENSE_PVCCIOMCP_CPU0_SKT_VRTN")
	)
	(arc
		(start 297.866816 -79.478886)
		(mid 298.075424 -79.690818)
		(end 298.360846 -79.774288)
		(width 0.0889)
		(layer "In11.Cu")
		(net "VSENSE_PVCCIOMCP_CPU0_SKT_VRTN")
	)
	(arc
		(start 294.630602 -78.936088)
		(mid 294.765164 -78.826176)
		(end 294.933624 -78.783688)
		(width 0.0889)
		(layer "In11.Cu")
		(net "VSENSE_PVCCIOMCP_CPU0_SKT_VRTN")
	)
	(arc
		(start 297.17365 -79.478886)
		(mid 297.314807 -79.335501)
		(end 297.507914 -79.278988)
		(width 0.0889)
		(layer "In11.Cu")
		(net "VSENSE_PVCCIOMCP_CPU0_SKT_VRTN")
	)
	(arc
		(start 302.692816 -79.278988)
		(mid 302.976033 -79.194707)
		(end 303.183036 -78.98384)
		(width 0.0889)
		(layer "In11.Cu")
		(net "VSENSE_PVCCIOMCP_CPU0_SKT_VRTN")
	)
	(arc
		(start 300.97222 -79.278988)
		(mid 301.162149 -79.336858)
		(end 301.300896 -79.478886)
		(width 0.0889)
		(layer "In11.Cu")
		(net "VSENSE_PVCCIOMCP_CPU0_SKT_VRTN")
	)
	(arc
		(start 297.53814 -79.278988)
		(mid 297.728069 -79.336858)
		(end 297.866816 -79.478886)
		(width 0.0889)
		(layer "In11.Cu")
		(net "VSENSE_PVCCIOMCP_CPU0_SKT_VRTN")
	)
	(arc
		(start 303.183036 -78.98384)
		(mid 303.324719 -78.840036)
		(end 303.51857 -78.783688)
		(width 0.0889)
		(layer "In11.Cu")
		(net "VSENSE_PVCCIOMCP_CPU0_SKT_VRTN")
	)
	(arc
		(start 298.396406 -79.774288)
		(mid 298.68183 -79.690821)
		(end 298.890436 -79.478886)
		(width 0.0889)
		(layer "In11.Cu")
		(net "VSENSE_PVCCIOMCP_CPU0_SKT_VRTN")
	)
	(arc
		(start 300.113446 -79.774288)
		(mid 300.39887 -79.690821)
		(end 300.607476 -79.478886)
		(width 0.0889)
		(layer "In11.Cu")
		(net "VSENSE_PVCCIOMCP_CPU0_SKT_VRTN")
	)
	(arc
		(start 301.300896 -79.478886)
		(mid 301.509504 -79.690818)
		(end 301.794926 -79.774288)
		(width 0.0889)
		(layer "In11.Cu")
		(net "VSENSE_PVCCIOMCP_CPU0_SKT_VRTN")
	)
	(arc
		(start 298.890436 -79.478886)
		(mid 299.02918 -79.336853)
		(end 299.219112 -79.278988)
		(width 0.0889)
		(layer "In11.Cu")
		(net "VSENSE_PVCCIOMCP_CPU0_SKT_VRTN")
	)
	(arc
		(start 301.830486 -79.774288)
		(mid 302.11591 -79.690821)
		(end 302.324516 -79.478886)
		(width 0.0889)
		(layer "In11.Cu")
		(net "VSENSE_PVCCIOMCP_CPU0_SKT_VRTN")
	)
	(arc
		(start 302.324516 -79.478886)
		(mid 302.46326 -79.336853)
		(end 302.653192 -79.278988)
		(width 0.0889)
		(layer "In11.Cu")
		(net "VSENSE_PVCCIOMCP_CPU0_SKT_VRTN")
	)
	(arc
		(start 303.876456 -78.98384)
		(mid 304.08346 -79.194704)
		(end 304.366676 -79.278988)
		(width 0.0889)
		(layer "In11.Cu")
		(net "VSENSE_PVCCIOMCP_CPU0_SKT_VRTN")
	)
	(arc
		(start 303.540922 -78.783688)
		(mid 303.734772 -78.840038)
		(end 303.876456 -78.98384)
		(width 0.0889)
		(layer "In11.Cu")
		(net "VSENSE_PVCCIOMCP_CPU0_SKT_VRTN")
	)
	(arc
		(start 295.29151 -78.98384)
		(mid 295.498514 -79.194704)
		(end 295.78173 -79.278988)
		(width 0.0889)
		(layer "In11.Cu")
		(net "VSENSE_PVCCIOMCP_CPU0_SKT_VRTN")
	)
	(arc
		(start 299.25518 -79.278988)
		(mid 299.445109 -79.336858)
		(end 299.583856 -79.478886)
		(width 0.0889)
		(layer "In11.Cu")
		(net "VSENSE_PVCCIOMCP_CPU0_SKT_VRTN")
	)
	(arc
		(start 296.67962 -79.774288)
		(mid 296.965044 -79.690821)
		(end 297.17365 -79.478886)
		(width 0.0889)
		(layer "In11.Cu")
		(net "VSENSE_PVCCIOMCP_CPU0_SKT_VRTN")
	)
	(arc
		(start 296.15003 -79.478886)
		(mid 296.358638 -79.690818)
		(end 296.64406 -79.774288)
		(width 0.0889)
		(layer "In11.Cu")
		(net "VSENSE_PVCCIOMCP_CPU0_SKT_VRTN")
	)
	(arc
		(start 300.607476 -79.478886)
		(mid 300.74622 -79.336853)
		(end 300.936152 -79.278988)
		(width 0.0889)
		(layer "In11.Cu")
		(net "VSENSE_PVCCIOMCP_CPU0_SKT_VRTN")
	)
	(arc
		(start 295.821354 -79.278988)
		(mid 296.011283 -79.336858)
		(end 296.15003 -79.478886)
		(width 0.0889)
		(layer "In11.Cu")
		(net "VSENSE_PVCCIOMCP_CPU0_SKT_VRTN")
	)
	(arc
		(start 294.955976 -78.783688)
		(mid 295.149826 -78.840038)
		(end 295.29151 -78.98384)
		(width 0.0889)
		(layer "In11.Cu")
		(net "VSENSE_PVCCIOMCP_CPU0_SKT_VRTN")
	)
	(segment
		(start 171.983146 -146.429222)
		(end 172.086778 -146.429222)
		(width 0.254)
		(layer "F.Cu")
		(net "VR_PVTT_KLM_VREF")
	)
	(segment
		(start 172.848778 -145.667222)
		(end 173.507146 -145.667222)
		(width 0.254)
		(layer "F.Cu")
		(net "VR_PVTT_KLM_VREF")
	)
	(segment
		(start 172.086778 -146.429222)
		(end 172.848778 -145.667222)
		(width 0.254)
		(layer "F.Cu")
		(net "VR_PVTT_KLM_VREF")
	)
	(segment
		(start 175.85436 -145.5039)
		(end 175.44796 -145.0975)
		(width 0.254)
		(layer "F.Cu")
		(net "VR_PVTT_KLM_VREF")
	)
	(segment
		(start 173.761146 -145.0975)
		(end 173.507146 -145.3515)
		(width 0.254)
		(layer "F.Cu")
		(net "VR_PVTT_KLM_VREF")
	)
	(segment
		(start 173.507146 -145.3515)
		(end 173.507146 -145.667222)
		(width 0.254)
		(layer "F.Cu")
		(net "VR_PVTT_KLM_VREF")
	)
	(segment
		(start 175.44796 -145.0975)
		(end 173.761146 -145.0975)
		(width 0.254)
		(layer "F.Cu")
		(net "VR_PVTT_KLM_VREF")
	)
	(via
		(at 175.85436 -145.5039)
		(size 0.762)
		(drill 0.381)
		(layers "F.Cu" "B.Cu")
		(net "VR_PVTT_KLM_VREF")
	)
	(segment
		(start 173.173898 -2.358898)
		(end 173.609 -2.794)
		(width 0.254)
		(layer "F.Cu")
		(net "VR_PVTT_GHJ_VREF")
	)
	(segment
		(start 172.252894 -2.358898)
		(end 172.80382 -2.358898)
		(width 0.254)
		(layer "F.Cu")
		(net "VR_PVTT_GHJ_VREF")
	)
	(segment
		(start 172.80382 -2.358898)
		(end 173.173898 -2.358898)
		(width 0.254)
		(layer "F.Cu")
		(net "VR_PVTT_GHJ_VREF")
	)
	(segment
		(start 171.8818 -3.175)
		(end 171.8818 -2.729992)
		(width 0.254)
		(layer "F.Cu")
		(net "VR_PVTT_GHJ_VREF")
	)
	(segment
		(start 171.8818 -2.729992)
		(end 172.252894 -2.358898)
		(width 0.254)
		(layer "F.Cu")
		(net "VR_PVTT_GHJ_VREF")
	)
	(via
		(at 172.80382 -2.358898)
		(size 0.508)
		(drill 0.254)
		(layers "F.Cu" "B.Cu")
		(net "VR_PVTT_GHJ_VREF")
	)
	(segment
		(start 181.636924 -147.9677)
		(end 181.255924 -147.9677)
		(width 0.254)
		(layer "F.Cu")
		(net "VR_PVTT_DEF_VREF")
	)
	(segment
		(start 179.2732 -146.5072)
		(end 179.578 -146.812)
		(width 0.254)
		(layer "F.Cu")
		(net "VR_PVTT_DEF_VREF")
	)
	(segment
		(start 181.255924 -147.9677)
		(end 180.594 -147.305776)
		(width 0.254)
		(layer "F.Cu")
		(net "VR_PVTT_DEF_VREF")
	)
	(segment
		(start 180.594 -147.305776)
		(end 180.594 -146.812)
		(width 0.254)
		(layer "F.Cu")
		(net "VR_PVTT_DEF_VREF")
	)
	(segment
		(start 181.890924 -148.2217)
		(end 181.636924 -147.9677)
		(width 0.254)
		(layer "F.Cu")
		(net "VR_PVTT_DEF_VREF")
	)
	(segment
		(start 179.578 -146.812)
		(end 180.594 -146.812)
		(width 0.254)
		(layer "F.Cu")
		(net "VR_PVTT_DEF_VREF")
	)
	(segment
		(start 181.890924 -148.3487)
		(end 181.890924 -148.2217)
		(width 0.254)
		(layer "F.Cu")
		(net "VR_PVTT_DEF_VREF")
	)
	(segment
		(start 179.2732 -146.4056)
		(end 179.2732 -146.5072)
		(width 0.254)
		(layer "F.Cu")
		(net "VR_PVTT_DEF_VREF")
	)
	(via
		(at 179.2732 -146.4056)
		(size 0.762)
		(drill 0.381)
		(layers "F.Cu" "B.Cu")
		(net "VR_PVTT_DEF_VREF")
	)
	(segment
		(start 32.352234 -93.625162)
		(end 32.352234 -94.371414)
		(width 0.508)
		(layer "F.Cu")
		(net "VR_PVSA_CPU1_VCIN")
	)
	(segment
		(start 32.352234 -94.371414)
		(end 32.36468 -94.38386)
		(width 0.508)
		(layer "F.Cu")
		(net "VR_PVSA_CPU1_VCIN")
	)
	(segment
		(start 32.54502 -94.5642)
		(end 32.36468 -94.38386)
		(width 0.254)
		(layer "F.Cu")
		(net "VR_PVSA_CPU1_VCIN")
	)
	(segment
		(start 32.54502 -95.284544)
		(end 32.54502 -94.5642)
		(width 0.254)
		(layer "F.Cu")
		(net "VR_PVSA_CPU1_VCIN")
	)
	(via
		(at 32.36468 -94.38386)
		(size 0.508)
		(drill 0.254)
		(layers "F.Cu" "B.Cu")
		(net "VR_PVSA_CPU1_VCIN")
	)
	(via
		(at 30.230572 -93.926914)
		(size 0.6604)
		(drill 0.3302)
		(layers "F.Cu" "B.Cu")
		(net "VR_PVSA_CPU1_VCIN")
	)
	(segment
		(start 32.258 -95.1484)
		(end 32.258 -94.49054)
		(width 0.4064)
		(layer "B.Cu")
		(net "VR_PVSA_CPU1_VCIN")
	)
	(segment
		(start 31.2928 -93.926914)
		(end 30.230572 -93.926914)
		(width 0.4064)
		(layer "B.Cu")
		(net "VR_PVSA_CPU1_VCIN")
	)
	(segment
		(start 31.868364 -94.234)
		(end 31.599886 -94.234)
		(width 0.4064)
		(layer "B.Cu")
		(net "VR_PVSA_CPU1_VCIN")
	)
	(segment
		(start 31.599886 -94.234)
		(end 31.2928 -93.926914)
		(width 0.4064)
		(layer "B.Cu")
		(net "VR_PVSA_CPU1_VCIN")
	)
	(segment
		(start 32.36468 -94.38386)
		(end 32.018224 -94.38386)
		(width 0.4064)
		(layer "B.Cu")
		(net "VR_PVSA_CPU1_VCIN")
	)
	(segment
		(start 32.258 -94.49054)
		(end 32.36468 -94.38386)
		(width 0.4064)
		(layer "B.Cu")
		(net "VR_PVSA_CPU1_VCIN")
	)
	(segment
		(start 32.018224 -94.38386)
		(end 31.868364 -94.234)
		(width 0.4064)
		(layer "B.Cu")
		(net "VR_PVSA_CPU1_VCIN")
	)
	(segment
		(start 16.5354 -94.655894)
		(end 16.103854 -94.655894)
		(width 0.2032)
		(layer "F.Cu")
		(net "VR_PVSA_CPU1_PWM")
	)
	(segment
		(start 29.869638 -97.9297)
		(end 29.734002 -97.794064)
		(width 0.254)
		(layer "F.Cu")
		(net "VR_PVSA_CPU1_PWM")
	)
	(segment
		(start 31.02991 -97.9297)
		(end 29.869638 -97.9297)
		(width 0.254)
		(layer "F.Cu")
		(net "VR_PVSA_CPU1_PWM")
	)
	(segment
		(start 15.9004 -94.859348)
		(end 15.9004 -95.2754)
		(width 0.2032)
		(layer "F.Cu")
		(net "VR_PVSA_CPU1_PWM")
	)
	(segment
		(start 16.103854 -94.655894)
		(end 15.9004 -94.859348)
		(width 0.2032)
		(layer "F.Cu")
		(net "VR_PVSA_CPU1_PWM")
	)
	(via
		(at 29.734002 -97.794064)
		(size 0.508)
		(drill 0.254)
		(layers "F.Cu" "B.Cu")
		(net "VR_PVSA_CPU1_PWM")
	)
	(via
		(at 15.9004 -95.2754)
		(size 0.508)
		(drill 0.254)
		(layers "F.Cu" "B.Cu")
		(net "VR_PVSA_CPU1_PWM")
	)
	(segment
		(start 27.032204 -97.794064)
		(end 24.74976 -95.51162)
		(width 0.254)
		(layer "In2.Cu")
		(net "VR_PVSA_CPU1_PWM")
	)
	(segment
		(start 16.13662 -95.51162)
		(end 15.9004 -95.2754)
		(width 0.254)
		(layer "In2.Cu")
		(net "VR_PVSA_CPU1_PWM")
	)
	(segment
		(start 29.734002 -97.794064)
		(end 27.032204 -97.794064)
		(width 0.254)
		(layer "In2.Cu")
		(net "VR_PVSA_CPU1_PWM")
	)
	(segment
		(start 24.74976 -95.51162)
		(end 16.13662 -95.51162)
		(width 0.254)
		(layer "In2.Cu")
		(net "VR_PVSA_CPU1_PWM")
	)
	(segment
		(start 30.644084 -98.829876)
		(end 31.02991 -98.829876)
		(width 0.254)
		(layer "F.Cu")
		(net "VR_PVSA_CPU1_PHASE")
	)
	(segment
		(start 30.21965 -99.25431)
		(end 30.644084 -98.829876)
		(width 0.254)
		(layer "F.Cu")
		(net "VR_PVSA_CPU1_PHASE")
	)
	(segment
		(start 29.87294 -99.60102)
		(end 30.21965 -99.25431)
		(width 0.508)
		(layer "F.Cu")
		(net "VR_PVSA_CPU1_PHASE")
	)
	(segment
		(start 29.72308 -99.60102)
		(end 29.87294 -99.60102)
		(width 0.508)
		(layer "F.Cu")
		(net "VR_PVSA_CPU1_PHASE")
	)
	(segment
		(start 28.09748 -98.59772)
		(end 28.09748 -99.09302)
		(width 0.508)
		(layer "F.Cu")
		(net "VR_PVSA_CPU1_BOOT")
	)
	(segment
		(start 28.60548 -99.60102)
		(end 28.83408 -99.60102)
		(width 0.508)
		(layer "F.Cu")
		(net "VR_PVSA_CPU1_BOOT")
	)
	(segment
		(start 28.09748 -99.09302)
		(end 28.60548 -99.60102)
		(width 0.508)
		(layer "F.Cu")
		(net "VR_PVSA_CPU1_BOOT")
	)
	(segment
		(start 197.226428 -94.331028)
		(end 197.3834 -94.488)
		(width 0.508)
		(layer "F.Cu")
		(net "VR_PVSA_CPU0_VCIN")
	)
	(segment
		(start 197.3834 -94.6404)
		(end 197.3834 -94.488)
		(width 0.254)
		(layer "F.Cu")
		(net "VR_PVSA_CPU0_VCIN")
	)
	(segment
		(start 197.532752 -95.284544)
		(end 197.532752 -94.789752)
		(width 0.254)
		(layer "F.Cu")
		(net "VR_PVSA_CPU0_VCIN")
	)
	(segment
		(start 197.532752 -94.789752)
		(end 197.3834 -94.6404)
		(width 0.254)
		(layer "F.Cu")
		(net "VR_PVSA_CPU0_VCIN")
	)
	(segment
		(start 197.226428 -93.734382)
		(end 197.226428 -94.331028)
		(width 0.508)
		(layer "F.Cu")
		(net "VR_PVSA_CPU0_VCIN")
	)
	(via
		(at 197.3834 -94.488)
		(size 0.508)
		(drill 0.254)
		(layers "F.Cu" "B.Cu")
		(net "VR_PVSA_CPU0_VCIN")
	)
	(via
		(at 196.72046 -93.85808)
		(size 0.6604)
		(drill 0.3302)
		(layers "F.Cu" "B.Cu")
		(net "VR_PVSA_CPU0_VCIN")
	)
	(segment
		(start 197.067678 -94.205298)
		(end 197.100698 -94.205298)
		(width 0.1143)
		(layer "B.Cu")
		(net "VR_PVSA_CPU0_VCIN")
	)
	(segment
		(start 197.100698 -94.205298)
		(end 197.3834 -94.488)
		(width 0.1143)
		(layer "B.Cu")
		(net "VR_PVSA_CPU0_VCIN")
	)
	(segment
		(start 197.226428 -94.644972)
		(end 197.226428 -95.171006)
		(width 0.4064)
		(layer "B.Cu")
		(net "VR_PVSA_CPU0_VCIN")
	)
	(segment
		(start 197.3834 -94.488)
		(end 197.226428 -94.644972)
		(width 0.4064)
		(layer "B.Cu")
		(net "VR_PVSA_CPU0_VCIN")
	)
	(segment
		(start 196.72046 -93.85808)
		(end 197.067678 -94.205298)
		(width 0.1143)
		(layer "B.Cu")
		(net "VR_PVSA_CPU0_VCIN")
	)
	(segment
		(start 179.5272 -71.714868)
		(end 179.5272 -71.6026)
		(width 0.2032)
		(layer "F.Cu")
		(net "VR_PVSA_CPU0_PWM")
	)
	(segment
		(start 180.993288 -72.049894)
		(end 180.685186 -72.357996)
		(width 0.2032)
		(layer "F.Cu")
		(net "VR_PVSA_CPU0_PWM")
	)
	(segment
		(start 180.170328 -72.357996)
		(end 179.5272 -71.714868)
		(width 0.2032)
		(layer "F.Cu")
		(net "VR_PVSA_CPU0_PWM")
	)
	(segment
		(start 181.3814 -72.049894)
		(end 180.993288 -72.049894)
		(width 0.2032)
		(layer "F.Cu")
		(net "VR_PVSA_CPU0_PWM")
	)
	(segment
		(start 194.85737 -97.9297)
		(end 196.017642 -97.9297)
		(width 0.254)
		(layer "F.Cu")
		(net "VR_PVSA_CPU0_PWM")
	)
	(segment
		(start 180.685186 -72.357996)
		(end 180.170328 -72.357996)
		(width 0.2032)
		(layer "F.Cu")
		(net "VR_PVSA_CPU0_PWM")
	)
	(via
		(at 194.85737 -97.9297)
		(size 0.508)
		(drill 0.254)
		(layers "F.Cu" "B.Cu")
		(net "VR_PVSA_CPU0_PWM")
	)
	(via
		(at 179.5272 -71.6026)
		(size 0.508)
		(drill 0.254)
		(layers "F.Cu" "B.Cu")
		(net "VR_PVSA_CPU0_PWM")
	)
	(segment
		(start 179.5272 -71.7042)
		(end 180.4543 -72.6313)
		(width 0.254)
		(layer "In2.Cu")
		(net "VR_PVSA_CPU0_PWM")
	)
	(segment
		(start 186.24042 -73.13422)
		(end 186.24042 -74.41438)
		(width 0.254)
		(layer "In2.Cu")
		(net "VR_PVSA_CPU0_PWM")
	)
	(segment
		(start 189.0268 -81.153)
		(end 192.3034 -84.4296)
		(width 0.254)
		(layer "In2.Cu")
		(net "VR_PVSA_CPU0_PWM")
	)
	(segment
		(start 192.3034 -92.489782)
		(end 193.210942 -93.397324)
		(width 0.254)
		(layer "In2.Cu")
		(net "VR_PVSA_CPU0_PWM")
	)
	(segment
		(start 180.4543 -72.6313)
		(end 185.7375 -72.6313)
		(width 0.254)
		(layer "In2.Cu")
		(net "VR_PVSA_CPU0_PWM")
	)
	(segment
		(start 185.398918 -75.255882)
		(end 185.398918 -79.054198)
		(width 0.254)
		(layer "In2.Cu")
		(net "VR_PVSA_CPU0_PWM")
	)
	(segment
		(start 187.49772 -81.153)
		(end 189.0268 -81.153)
		(width 0.254)
		(layer "In2.Cu")
		(net "VR_PVSA_CPU0_PWM")
	)
	(segment
		(start 185.7375 -72.6313)
		(end 186.24042 -73.13422)
		(width 0.254)
		(layer "In2.Cu")
		(net "VR_PVSA_CPU0_PWM")
	)
	(segment
		(start 185.398918 -79.054198)
		(end 187.49772 -81.153)
		(width 0.254)
		(layer "In2.Cu")
		(net "VR_PVSA_CPU0_PWM")
	)
	(segment
		(start 192.3034 -84.4296)
		(end 192.3034 -92.489782)
		(width 0.254)
		(layer "In2.Cu")
		(net "VR_PVSA_CPU0_PWM")
	)
	(segment
		(start 193.210942 -93.397324)
		(end 193.210942 -96.918272)
		(width 0.254)
		(layer "In2.Cu")
		(net "VR_PVSA_CPU0_PWM")
	)
	(segment
		(start 193.210942 -96.918272)
		(end 194.22237 -97.9297)
		(width 0.254)
		(layer "In2.Cu")
		(net "VR_PVSA_CPU0_PWM")
	)
	(segment
		(start 186.24042 -74.41438)
		(end 185.398918 -75.255882)
		(width 0.254)
		(layer "In2.Cu")
		(net "VR_PVSA_CPU0_PWM")
	)
	(segment
		(start 179.5272 -71.6026)
		(end 179.5272 -71.7042)
		(width 0.254)
		(layer "In2.Cu")
		(net "VR_PVSA_CPU0_PWM")
	)
	(segment
		(start 194.22237 -97.9297)
		(end 194.85737 -97.9297)
		(width 0.254)
		(layer "In2.Cu")
		(net "VR_PVSA_CPU0_PWM")
	)
	(segment
		(start 195.420742 -98.829876)
		(end 195.12661 -99.124008)
		(width 0.254)
		(layer "F.Cu")
		(net "VR_PVSA_CPU0_PHASE")
	)
	(segment
		(start 195.12661 -99.124008)
		(end 195.12661 -99.43719)
		(width 0.254)
		(layer "F.Cu")
		(net "VR_PVSA_CPU0_PHASE")
	)
	(segment
		(start 195.12661 -99.43719)
		(end 194.6402 -99.9236)
		(width 0.508)
		(layer "F.Cu")
		(net "VR_PVSA_CPU0_PHASE")
	)
	(segment
		(start 196.017642 -98.829876)
		(end 195.420742 -98.829876)
		(width 0.254)
		(layer "F.Cu")
		(net "VR_PVSA_CPU0_PHASE")
	)
	(segment
		(start 193.7512 -99.9236)
		(end 193.0146 -99.187)
		(width 0.508)
		(layer "F.Cu")
		(net "VR_PVSA_CPU0_BOOT")
	)
	(segment
		(start 193.0146 -99.187)
		(end 193.0146 -98.7298)
		(width 0.508)
		(layer "F.Cu")
		(net "VR_PVSA_CPU0_BOOT")
	)
	(segment
		(start 193.066162 -101.091238)
		(end 193.7512 -100.4062)
		(width 0.508)
		(layer "F.Cu")
		(net "VR_PVSA_CPU0_BOOT")
	)
	(segment
		(start 193.7512 -100.4062)
		(end 193.7512 -99.9236)
		(width 0.508)
		(layer "F.Cu")
		(net "VR_PVSA_CPU0_BOOT")
	)
	(via
		(at 193.066162 -101.091238)
		(size 0.762)
		(drill 0.381)
		(layers "F.Cu" "B.Cu")
		(net "VR_PVSA_CPU0_BOOT")
	)
	(segment
		(start 177.673 -137.8458)
		(end 178.926236 -136.592564)
		(width 0.254)
		(layer "F.Cu")
		(net "VR_PVPP_KLM_PHASE")
	)
	(segment
		(start 178.926236 -136.592564)
		(end 180.5051 -136.592564)
		(width 0.254)
		(layer "F.Cu")
		(net "VR_PVPP_KLM_PHASE")
	)
	(segment
		(start 173.5074 -134.366)
		(end 173.101 -134.7724)
		(width 0.508)
		(layer "F.Cu")
		(net "VR_PVPP_KLM_BOOT")
	)
	(segment
		(start 173.101 -134.7724)
		(end 173.101 -135.509)
		(width 0.508)
		(layer "F.Cu")
		(net "VR_PVPP_KLM_BOOT")
	)
	(segment
		(start 174.184564 -136.592564)
		(end 174.8409 -136.592564)
		(width 0.254)
		(layer "F.Cu")
		(net "VR_PVPP_KLM_BOOT")
	)
	(segment
		(start 173.5074 -133.604)
		(end 173.5074 -134.366)
		(width 0.508)
		(layer "F.Cu")
		(net "VR_PVPP_KLM_BOOT")
	)
	(segment
		(start 173.456346 -135.864346)
		(end 174.184564 -136.592564)
		(width 0.254)
		(layer "F.Cu")
		(net "VR_PVPP_KLM_BOOT")
	)
	(segment
		(start 173.101 -135.509)
		(end 173.456346 -135.864346)
		(width 0.508)
		(layer "F.Cu")
		(net "VR_PVPP_KLM_BOOT")
	)
	(segment
		(start 174.349664 -13.085064)
		(end 174.8409 -13.085064)
		(width 0.254)
		(layer "F.Cu")
		(net "VR_PVPP_GHJ_BOOT")
	)
	(segment
		(start 173.093888 -11.829288)
		(end 173.99 -12.7254)
		(width 0.4064)
		(layer "F.Cu")
		(net "VR_PVPP_GHJ_BOOT")
	)
	(segment
		(start 173.99 -12.7254)
		(end 174.349664 -13.085064)
		(width 0.254)
		(layer "F.Cu")
		(net "VR_PVPP_GHJ_BOOT")
	)
	(segment
		(start 173.093888 -10.255504)
		(end 173.093888 -11.829288)
		(width 0.4064)
		(layer "F.Cu")
		(net "VR_PVPP_GHJ_BOOT")
	)
	(segment
		(start 344.043 -133.858)
		(end 345.296236 -132.604764)
		(width 0.254)
		(layer "F.Cu")
		(net "VR_PVPP_DEF_PHASE")
	)
	(segment
		(start 345.296236 -132.604764)
		(end 346.8751 -132.604764)
		(width 0.254)
		(layer "F.Cu")
		(net "VR_PVPP_DEF_PHASE")
	)
	(segment
		(start 339.869526 -132.284216)
		(end 339.562694 -131.977384)
		(width 0.508)
		(layer "F.Cu")
		(net "VR_PVPP_DEF_BOOT")
	)
	(segment
		(start 341.2109 -132.604764)
		(end 340.190074 -132.604764)
		(width 0.254)
		(layer "F.Cu")
		(net "VR_PVPP_DEF_BOOT")
	)
	(segment
		(start 340.190074 -132.604764)
		(end 339.869526 -132.284216)
		(width 0.254)
		(layer "F.Cu")
		(net "VR_PVPP_DEF_BOOT")
	)
	(segment
		(start 339.562694 -131.977384)
		(end 339.258656 -131.977384)
		(width 0.508)
		(layer "F.Cu")
		(net "VR_PVPP_DEF_BOOT")
	)
	(segment
		(start 6.0452 -129.8829)
		(end 5.788152 -129.625852)
		(width 0.508)
		(layer "F.Cu")
		(net "VR_PVDDQ_KLM_VDD")
	)
	(segment
		(start 5.788152 -129.625852)
		(end 5.527548 -129.365248)
		(width 0.2032)
		(layer "F.Cu")
		(net "VR_PVDDQ_KLM_VDD")
	)
	(segment
		(start 5.527548 -129.365248)
		(end 4.5085 -129.365248)
		(width 0.2032)
		(layer "F.Cu")
		(net "VR_PVDDQ_KLM_VDD")
	)
	(segment
		(start 6.9342 -129.65176)
		(end 6.92912 -129.64668)
		(width 0.508)
		(layer "F.Cu")
		(net "VR_PVDDQ_KLM_VDD")
	)
	(segment
		(start 6.0452 -130.302)
		(end 6.0452 -129.8829)
		(width 0.508)
		(layer "F.Cu")
		(net "VR_PVDDQ_KLM_VDD")
	)
	(segment
		(start 6.9342 -130.302)
		(end 6.0452 -130.302)
		(width 0.508)
		(layer "F.Cu")
		(net "VR_PVDDQ_KLM_VDD")
	)
	(segment
		(start 6.9342 -130.302)
		(end 6.9342 -129.65176)
		(width 0.508)
		(layer "F.Cu")
		(net "VR_PVDDQ_KLM_VDD")
	)
	(via
		(at 6.92912 -129.64668)
		(size 0.508)
		(drill 0.254)
		(layers "F.Cu" "B.Cu")
		(net "VR_PVDDQ_KLM_VDD")
	)
	(segment
		(start 6.92912 -129.64668)
		(end 6.92912 -129.80924)
		(width 0.508)
		(layer "B.Cu")
		(net "VR_PVDDQ_KLM_VDD")
	)
	(segment
		(start 8.0264 -130.90652)
		(end 8.0264 -131.4704)
		(width 0.508)
		(layer "B.Cu")
		(net "VR_PVDDQ_KLM_VDD")
	)
	(segment
		(start 6.92912 -129.80924)
		(end 8.0264 -130.90652)
		(width 0.508)
		(layer "B.Cu")
		(net "VR_PVDDQ_KLM_VDD")
	)
	(segment
		(start -2.149348 -147.578318)
		(end -2.687066 -147.0406)
		(width 0.254)
		(layer "F.Cu")
		(net "VR_PVDDQ_KLM_PWM2")
	)
	(segment
		(start -2.687066 -147.0406)
		(end -3.2004 -147.0406)
		(width 0.254)
		(layer "F.Cu")
		(net "VR_PVDDQ_KLM_PWM2")
	)
	(segment
		(start 2.9972 -131.318)
		(end 2.657348 -130.978148)
		(width 0.2032)
		(layer "F.Cu")
		(net "VR_PVDDQ_KLM_PWM2")
	)
	(segment
		(start -0.497586 -147.578318)
		(end -2.149348 -147.578318)
		(width 0.254)
		(layer "F.Cu")
		(net "VR_PVDDQ_KLM_PWM2")
	)
	(segment
		(start 2.657348 -130.978148)
		(end 2.657348 -130.4163)
		(width 0.2032)
		(layer "F.Cu")
		(net "VR_PVDDQ_KLM_PWM2")
	)
	(segment
		(start 3.7338 -131.318)
		(end 2.9972 -131.318)
		(width 0.2032)
		(layer "F.Cu")
		(net "VR_PVDDQ_KLM_PWM2")
	)
	(via
		(at -3.2004 -147.0406)
		(size 0.508)
		(drill 0.254)
		(layers "F.Cu" "B.Cu")
		(net "VR_PVDDQ_KLM_PWM2")
	)
	(via
		(at 3.7338 -131.318)
		(size 0.508)
		(drill 0.254)
		(layers "F.Cu" "B.Cu")
		(net "VR_PVDDQ_KLM_PWM2")
	)
	(segment
		(start 3.7338 -131.318)
		(end 3.67792 -131.37388)
		(width 0.254)
		(layer "In2.Cu")
		(net "VR_PVDDQ_KLM_PWM2")
	)
	(segment
		(start -0.6858 -136.613646)
		(end -0.6858 -137.384028)
		(width 0.254)
		(layer "In2.Cu")
		(net "VR_PVDDQ_KLM_PWM2")
	)
	(segment
		(start -3.4417 -140.139928)
		(end -3.4417 -146.7993)
		(width 0.254)
		(layer "In2.Cu")
		(net "VR_PVDDQ_KLM_PWM2")
	)
	(segment
		(start -3.4417 -146.7993)
		(end -3.2004 -147.0406)
		(width 0.254)
		(layer "In2.Cu")
		(net "VR_PVDDQ_KLM_PWM2")
	)
	(segment
		(start 3.67792 -131.37388)
		(end 3.67792 -133.60146)
		(width 0.254)
		(layer "In2.Cu")
		(net "VR_PVDDQ_KLM_PWM2")
	)
	(segment
		(start -0.6858 -137.384028)
		(end -3.4417 -140.139928)
		(width 0.254)
		(layer "In2.Cu")
		(net "VR_PVDDQ_KLM_PWM2")
	)
	(segment
		(start 0.172466 -135.75538)
		(end -0.6858 -136.613646)
		(width 0.254)
		(layer "In2.Cu")
		(net "VR_PVDDQ_KLM_PWM2")
	)
	(segment
		(start 3.67792 -133.60146)
		(end 1.524 -135.75538)
		(width 0.254)
		(layer "In2.Cu")
		(net "VR_PVDDQ_KLM_PWM2")
	)
	(segment
		(start 1.524 -135.75538)
		(end 0.172466 -135.75538)
		(width 0.254)
		(layer "In2.Cu")
		(net "VR_PVDDQ_KLM_PWM2")
	)
	(segment
		(start 2.257298 -132.475224)
		(end 2.257298 -130.4163)
		(width 0.2032)
		(layer "F.Cu")
		(net "VR_PVDDQ_KLM_PWM1")
	)
	(segment
		(start -2.195576 -138.26109)
		(end -2.250948 -138.205718)
		(width 0.254)
		(layer "F.Cu")
		(net "VR_PVDDQ_KLM_PWM1")
	)
	(segment
		(start -2.250948 -138.205718)
		(end -2.780538 -138.205718)
		(width 0.254)
		(layer "F.Cu")
		(net "VR_PVDDQ_KLM_PWM1")
	)
	(segment
		(start -0.497586 -138.434318)
		(end -1.157986 -138.434318)
		(width 0.254)
		(layer "F.Cu")
		(net "VR_PVDDQ_KLM_PWM1")
	)
	(segment
		(start -1.331214 -138.26109)
		(end -2.195576 -138.26109)
		(width 0.254)
		(layer "F.Cu")
		(net "VR_PVDDQ_KLM_PWM1")
	)
	(segment
		(start -1.157986 -138.434318)
		(end -1.331214 -138.26109)
		(width 0.254)
		(layer "F.Cu")
		(net "VR_PVDDQ_KLM_PWM1")
	)
	(segment
		(start 2.776728 -132.994654)
		(end 2.257298 -132.475224)
		(width 0.2032)
		(layer "F.Cu")
		(net "VR_PVDDQ_KLM_PWM1")
	)
	(via
		(at -2.780538 -138.205718)
		(size 0.508)
		(drill 0.254)
		(layers "F.Cu" "B.Cu")
		(net "VR_PVDDQ_KLM_PWM1")
	)
	(via
		(at 2.776728 -132.994654)
		(size 0.508)
		(drill 0.254)
		(layers "F.Cu" "B.Cu")
		(net "VR_PVDDQ_KLM_PWM1")
	)
	(segment
		(start -1.43764 -135.570722)
		(end -1.43764 -135.919972)
		(width 0.254)
		(layer "In4.Cu")
		(net "VR_PVDDQ_KLM_PWM1")
	)
	(segment
		(start -1.43764 -135.919972)
		(end -2.780538 -137.26287)
		(width 0.254)
		(layer "In4.Cu")
		(net "VR_PVDDQ_KLM_PWM1")
	)
	(segment
		(start 2.776728 -132.994654)
		(end 1.138428 -132.994654)
		(width 0.254)
		(layer "In4.Cu")
		(net "VR_PVDDQ_KLM_PWM1")
	)
	(segment
		(start 1.138428 -132.994654)
		(end -1.43764 -135.570722)
		(width 0.254)
		(layer "In4.Cu")
		(net "VR_PVDDQ_KLM_PWM1")
	)
	(segment
		(start -2.780538 -137.26287)
		(end -2.780538 -138.205718)
		(width 0.254)
		(layer "In4.Cu")
		(net "VR_PVDDQ_KLM_PWM1")
	)
	(segment
		(start 8.509 -147.32)
		(end 8.616188 -147.212812)
		(width 0.508)
		(layer "F.Cu")
		(net "VR_PVDDQ_KLM_PH2_SW")
	)
	(segment
		(start 8.616188 -147.212812)
		(end 8.616188 -142.883128)
		(width 0.508)
		(layer "F.Cu")
		(net "VR_PVDDQ_KLM_PH2_SW")
	)
	(segment
		(start 1.017524 -135.789162)
		(end 1.017524 -135.282178)
		(width 0.254)
		(layer "F.Cu")
		(net "VR_PVDDQ_KLM_PH1_VCIN")
	)
	(segment
		(start 1.017524 -135.282178)
		(end 0.9144 -135.179054)
		(width 0.254)
		(layer "F.Cu")
		(net "VR_PVDDQ_KLM_PH1_VCIN")
	)
	(segment
		(start 0.889 -134.3152)
		(end 0.889 -134.9248)
		(width 0.4064)
		(layer "F.Cu")
		(net "VR_PVDDQ_KLM_PH1_VCIN")
	)
	(segment
		(start 0.9144 -135.179054)
		(end 0.9144 -134.9502)
		(width 0.254)
		(layer "F.Cu")
		(net "VR_PVDDQ_KLM_PH1_VCIN")
	)
	(segment
		(start 0.889 -134.9248)
		(end 0.9144 -134.9502)
		(width 0.4064)
		(layer "F.Cu")
		(net "VR_PVDDQ_KLM_PH1_VCIN")
	)
	(via
		(at 0.106172 -135.763)
		(size 0.6604)
		(drill 0.3302)
		(layers "F.Cu" "B.Cu")
		(net "VR_PVDDQ_KLM_PH1_VCIN")
	)
	(via
		(at 0.9144 -134.9502)
		(size 0.508)
		(drill 0.254)
		(layers "F.Cu" "B.Cu")
		(net "VR_PVDDQ_KLM_PH1_VCIN")
	)
	(segment
		(start 0.889 -135.763)
		(end 0.106172 -135.763)
		(width 0.508)
		(layer "B.Cu")
		(net "VR_PVDDQ_KLM_PH1_VCIN")
	)
	(segment
		(start 0.889 -134.9756)
		(end 0.9144 -134.9502)
		(width 0.4064)
		(layer "B.Cu")
		(net "VR_PVDDQ_KLM_PH1_VCIN")
	)
	(segment
		(start 0.889 -135.763)
		(end 0.889 -134.9756)
		(width 0.4064)
		(layer "B.Cu")
		(net "VR_PVDDQ_KLM_PH1_VCIN")
	)
	(segment
		(start 7.68731 -134.383526)
		(end 7.05231 -134.383526)
		(width 0.508)
		(layer "F.Cu")
		(net "VR_PVDDQ_KLM_PH1_SW")
	)
	(segment
		(start 8.348218 -135.869426)
		(end 8.348218 -135.044434)
		(width 0.508)
		(layer "F.Cu")
		(net "VR_PVDDQ_KLM_PH1_SW")
	)
	(segment
		(start 8.348218 -135.044434)
		(end 7.68731 -134.383526)
		(width 0.508)
		(layer "F.Cu")
		(net "VR_PVDDQ_KLM_PH1_SW")
	)
	(segment
		(start -1.900682 -140.048996)
		(end -1.764538 -140.048996)
		(width 0.508)
		(layer "F.Cu")
		(net "VR_PVDDQ_KLM_PH1_PHASE")
	)
	(segment
		(start -1.293114 -139.577572)
		(end -1.050036 -139.334494)
		(width 0.254)
		(layer "F.Cu")
		(net "VR_PVDDQ_KLM_PH1_PHASE")
	)
	(segment
		(start -1.764538 -140.048996)
		(end -1.293114 -139.577572)
		(width 0.508)
		(layer "F.Cu")
		(net "VR_PVDDQ_KLM_PH1_PHASE")
	)
	(segment
		(start -1.050036 -139.334494)
		(end -0.497586 -139.334494)
		(width 0.254)
		(layer "F.Cu")
		(net "VR_PVDDQ_KLM_PH1_PHASE")
	)
	(segment
		(start -4.021074 -139.783566)
		(end -4.021074 -139.00531)
		(width 0.508)
		(layer "F.Cu")
		(net "VR_PVDDQ_KLM_PH1_BOOT")
	)
	(segment
		(start -3.130042 -140.048996)
		(end -3.154426 -140.07338)
		(width 0.508)
		(layer "F.Cu")
		(net "VR_PVDDQ_KLM_PH1_BOOT")
	)
	(segment
		(start -3.73126 -140.07338)
		(end -4.021074 -139.783566)
		(width 0.508)
		(layer "F.Cu")
		(net "VR_PVDDQ_KLM_PH1_BOOT")
	)
	(segment
		(start -2.789682 -140.048996)
		(end -3.130042 -140.048996)
		(width 0.508)
		(layer "F.Cu")
		(net "VR_PVDDQ_KLM_PH1_BOOT")
	)
	(segment
		(start -3.154426 -140.07338)
		(end -3.73126 -140.07338)
		(width 0.508)
		(layer "F.Cu")
		(net "VR_PVDDQ_KLM_PH1_BOOT")
	)
	(via
		(at -3.73126 -140.07338)
		(size 0.762)
		(drill 0.381)
		(layers "F.Cu" "B.Cu")
		(net "VR_PVDDQ_KLM_PH1_BOOT")
	)
	(segment
		(start 14.358112 4.266184)
		(end 14.36116 4.269232)
		(width 0.508)
		(layer "F.Cu")
		(net "VR_PVDDQ_GHJ_VDD")
	)
	(segment
		(start 13.54836 4.266184)
		(end 14.358112 4.266184)
		(width 0.508)
		(layer "F.Cu")
		(net "VR_PVDDQ_GHJ_VDD")
	)
	(segment
		(start 14.36116 4.269232)
		(end 15.26794 4.269232)
		(width 0.508)
		(layer "F.Cu")
		(net "VR_PVDDQ_GHJ_VDD")
	)
	(segment
		(start 13.050012 4.266184)
		(end 12.836906 4.053078)
		(width 0.2032)
		(layer "F.Cu")
		(net "VR_PVDDQ_GHJ_VDD")
	)
	(segment
		(start 12.339066 3.27025)
		(end 11.641836 3.27025)
		(width 0.2032)
		(layer "F.Cu")
		(net "VR_PVDDQ_GHJ_VDD")
	)
	(segment
		(start 12.836906 3.76809)
		(end 12.339066 3.27025)
		(width 0.2032)
		(layer "F.Cu")
		(net "VR_PVDDQ_GHJ_VDD")
	)
	(segment
		(start 13.54836 4.266184)
		(end 13.050012 4.266184)
		(width 0.2032)
		(layer "F.Cu")
		(net "VR_PVDDQ_GHJ_VDD")
	)
	(segment
		(start 11.433048 3.061462)
		(end 11.433048 2.69875)
		(width 0.2032)
		(layer "F.Cu")
		(net "VR_PVDDQ_GHJ_VDD")
	)
	(segment
		(start 11.641836 3.27025)
		(end 11.433048 3.061462)
		(width 0.2032)
		(layer "F.Cu")
		(net "VR_PVDDQ_GHJ_VDD")
	)
	(segment
		(start 15.26794 4.269232)
		(end 15.871444 4.872736)
		(width 0.508)
		(layer "F.Cu")
		(net "VR_PVDDQ_GHJ_VDD")
	)
	(segment
		(start 12.836906 4.053078)
		(end 12.836906 3.76809)
		(width 0.2032)
		(layer "F.Cu")
		(net "VR_PVDDQ_GHJ_VDD")
	)
	(via
		(at 15.871444 4.872736)
		(size 0.508)
		(drill 0.254)
		(layers "F.Cu" "B.Cu")
		(net "VR_PVDDQ_GHJ_VDD")
	)
	(segment
		(start 15.536164 4.537456)
		(end 15.871444 4.872736)
		(width 0.508)
		(layer "B.Cu")
		(net "VR_PVDDQ_GHJ_VDD")
	)
	(segment
		(start 14.810232 4.537456)
		(end 15.536164 4.537456)
		(width 0.508)
		(layer "B.Cu")
		(net "VR_PVDDQ_GHJ_VDD")
	)
	(segment
		(start 1.785112 -17.710912)
		(end 1.6891 -17.6149)
		(width 0.2032)
		(layer "F.Cu")
		(net "VR_PVDDQ_GHJ_PWM2")
	)
	(segment
		(start 0.988568 -17.2974)
		(end 0.351028 -17.2974)
		(width 0.254)
		(layer "F.Cu")
		(net "VR_PVDDQ_GHJ_PWM2")
	)
	(segment
		(start 2.150364 -17.710912)
		(end 1.785112 -17.710912)
		(width 0.2032)
		(layer "F.Cu")
		(net "VR_PVDDQ_GHJ_PWM2")
	)
	(segment
		(start 13.396976 1.109472)
		(end 13.292582 1.109472)
		(width 0.2032)
		(layer "F.Cu")
		(net "VR_PVDDQ_GHJ_PWM2")
	)
	(segment
		(start 1.276604 -17.585436)
		(end 0.988568 -17.2974)
		(width 0.254)
		(layer "F.Cu")
		(net "VR_PVDDQ_GHJ_PWM2")
	)
	(segment
		(start 13.030708 0.847598)
		(end 12.4841 0.847598)
		(width 0.2032)
		(layer "F.Cu")
		(net "VR_PVDDQ_GHJ_PWM2")
	)
	(segment
		(start 1.6891 -17.6149)
		(end 1.5113 -17.6149)
		(width 0.2032)
		(layer "F.Cu")
		(net "VR_PVDDQ_GHJ_PWM2")
	)
	(segment
		(start 1.5113 -17.6149)
		(end 1.481836 -17.585436)
		(width 0.2032)
		(layer "F.Cu")
		(net "VR_PVDDQ_GHJ_PWM2")
	)
	(segment
		(start 1.481836 -17.585436)
		(end 1.276604 -17.585436)
		(width 0.254)
		(layer "F.Cu")
		(net "VR_PVDDQ_GHJ_PWM2")
	)
	(segment
		(start 13.292582 1.109472)
		(end 13.030708 0.847598)
		(width 0.2032)
		(layer "F.Cu")
		(net "VR_PVDDQ_GHJ_PWM2")
	)
	(via
		(at 0.351028 -17.2974)
		(size 0.508)
		(drill 0.254)
		(layers "F.Cu" "B.Cu")
		(net "VR_PVDDQ_GHJ_PWM2")
	)
	(via
		(at 13.396976 1.109472)
		(size 0.508)
		(drill 0.254)
		(layers "F.Cu" "B.Cu")
		(net "VR_PVDDQ_GHJ_PWM2")
	)
	(segment
		(start 1.680718 -16.810482)
		(end 1.680718 -14.279118)
		(width 0.254)
		(layer "In4.Cu")
		(net "VR_PVDDQ_GHJ_PWM2")
	)
	(segment
		(start 0.364236 -12.962636)
		(end 0.364236 -11.50366)
		(width 0.254)
		(layer "In4.Cu")
		(net "VR_PVDDQ_GHJ_PWM2")
	)
	(segment
		(start 1.680718 -14.279118)
		(end 0.364236 -12.962636)
		(width 0.254)
		(layer "In4.Cu")
		(net "VR_PVDDQ_GHJ_PWM2")
	)
	(segment
		(start 1.397 -5.278628)
		(end 7.214362 0.538734)
		(width 0.254)
		(layer "In4.Cu")
		(net "VR_PVDDQ_GHJ_PWM2")
	)
	(segment
		(start 0.364236 -11.50366)
		(end 1.397 -10.470896)
		(width 0.254)
		(layer "In4.Cu")
		(net "VR_PVDDQ_GHJ_PWM2")
	)
	(segment
		(start 1.1938 -17.2974)
		(end 1.680718 -16.810482)
		(width 0.254)
		(layer "In4.Cu")
		(net "VR_PVDDQ_GHJ_PWM2")
	)
	(segment
		(start 7.214362 0.538734)
		(end 12.826238 0.538734)
		(width 0.254)
		(layer "In4.Cu")
		(net "VR_PVDDQ_GHJ_PWM2")
	)
	(segment
		(start 1.397 -10.470896)
		(end 1.397 -5.278628)
		(width 0.254)
		(layer "In4.Cu")
		(net "VR_PVDDQ_GHJ_PWM2")
	)
	(segment
		(start 0.351028 -17.2974)
		(end 1.1938 -17.2974)
		(width 0.254)
		(layer "In4.Cu")
		(net "VR_PVDDQ_GHJ_PWM2")
	)
	(segment
		(start 12.826238 0.538734)
		(end 13.396976 1.109472)
		(width 0.254)
		(layer "In4.Cu")
		(net "VR_PVDDQ_GHJ_PWM2")
	)
	(segment
		(start 0.895604 -9.743694)
		(end 0.881888 -9.729978)
		(width 0.254)
		(layer "F.Cu")
		(net "VR_PVDDQ_GHJ_PWM1")
	)
	(segment
		(start 2.067814 -9.743694)
		(end 0.895604 -9.743694)
		(width 0.254)
		(layer "F.Cu")
		(net "VR_PVDDQ_GHJ_PWM1")
	)
	(segment
		(start 0.881888 -9.729978)
		(end 0.399288 -9.729978)
		(width 0.254)
		(layer "F.Cu")
		(net "VR_PVDDQ_GHJ_PWM1")
	)
	(segment
		(start 12.4841 0.447548)
		(end 13.409422 0.447548)
		(width 0.2032)
		(layer "F.Cu")
		(net "VR_PVDDQ_GHJ_PWM1")
	)
	(segment
		(start 13.409422 0.447548)
		(end 13.559028 0.297942)
		(width 0.254)
		(layer "F.Cu")
		(net "VR_PVDDQ_GHJ_PWM1")
	)
	(via
		(at 13.559028 0.297942)
		(size 0.508)
		(drill 0.254)
		(layers "F.Cu" "B.Cu")
		(net "VR_PVDDQ_GHJ_PWM1")
	)
	(via
		(at 0.399288 -9.729978)
		(size 0.508)
		(drill 0.254)
		(layers "F.Cu" "B.Cu")
		(net "VR_PVDDQ_GHJ_PWM1")
	)
	(segment
		(start 3.870706 -5.361686)
		(end 2.493264 -5.361686)
		(width 0.254)
		(layer "In2.Cu")
		(net "VR_PVDDQ_GHJ_PWM1")
	)
	(segment
		(start 9.666986 -0.588518)
		(end 9.187688 -1.067816)
		(width 0.254)
		(layer "In2.Cu")
		(net "VR_PVDDQ_GHJ_PWM1")
	)
	(segment
		(start 1.428496 -6.426454)
		(end 1.428496 -7.75462)
		(width 0.254)
		(layer "In2.Cu")
		(net "VR_PVDDQ_GHJ_PWM1")
	)
	(segment
		(start 13.559028 0.297942)
		(end 12.672568 -0.588518)
		(width 0.254)
		(layer "In2.Cu")
		(net "VR_PVDDQ_GHJ_PWM1")
	)
	(segment
		(start 12.672568 -0.588518)
		(end 9.666986 -0.588518)
		(width 0.254)
		(layer "In2.Cu")
		(net "VR_PVDDQ_GHJ_PWM1")
	)
	(segment
		(start 0.235458 -9.566148)
		(end 0.399288 -9.729978)
		(width 0.254)
		(layer "In2.Cu")
		(net "VR_PVDDQ_GHJ_PWM1")
	)
	(segment
		(start 7.015988 -3.532124)
		(end 7.015988 -4.860798)
		(width 0.254)
		(layer "In2.Cu")
		(net "VR_PVDDQ_GHJ_PWM1")
	)
	(segment
		(start 9.187688 -1.360424)
		(end 7.015988 -3.532124)
		(width 0.254)
		(layer "In2.Cu")
		(net "VR_PVDDQ_GHJ_PWM1")
	)
	(segment
		(start 7.015988 -4.860798)
		(end 6.229858 -5.646928)
		(width 0.254)
		(layer "In2.Cu")
		(net "VR_PVDDQ_GHJ_PWM1")
	)
	(segment
		(start 4.155948 -5.646928)
		(end 3.870706 -5.361686)
		(width 0.254)
		(layer "In2.Cu")
		(net "VR_PVDDQ_GHJ_PWM1")
	)
	(segment
		(start 2.493264 -5.361686)
		(end 1.428496 -6.426454)
		(width 0.254)
		(layer "In2.Cu")
		(net "VR_PVDDQ_GHJ_PWM1")
	)
	(segment
		(start 1.428496 -7.75462)
		(end 0.235458 -8.947658)
		(width 0.254)
		(layer "In2.Cu")
		(net "VR_PVDDQ_GHJ_PWM1")
	)
	(segment
		(start 6.229858 -5.646928)
		(end 4.155948 -5.646928)
		(width 0.254)
		(layer "In2.Cu")
		(net "VR_PVDDQ_GHJ_PWM1")
	)
	(segment
		(start 9.187688 -1.067816)
		(end 9.187688 -1.360424)
		(width 0.254)
		(layer "In2.Cu")
		(net "VR_PVDDQ_GHJ_PWM1")
	)
	(segment
		(start 0.235458 -8.947658)
		(end 0.235458 -9.566148)
		(width 0.254)
		(layer "In2.Cu")
		(net "VR_PVDDQ_GHJ_PWM1")
	)
	(segment
		(start 3.56235 -14.277594)
		(end 3.665474 -14.380718)
		(width 0.254)
		(layer "F.Cu")
		(net "VR_PVDDQ_GHJ_PH2_VCIN")
	)
	(segment
		(start 3.56235 -14.277594)
		(end 3.384042 -14.099286)
		(width 0.4064)
		(layer "F.Cu")
		(net "VR_PVDDQ_GHJ_PH2_VCIN")
	)
	(segment
		(start 3.384042 -14.099286)
		(end 3.384042 -13.599414)
		(width 0.4064)
		(layer "F.Cu")
		(net "VR_PVDDQ_GHJ_PH2_VCIN")
	)
	(segment
		(start 3.665474 -14.380718)
		(end 3.665474 -15.065756)
		(width 0.254)
		(layer "F.Cu")
		(net "VR_PVDDQ_GHJ_PH2_VCIN")
	)
	(via
		(at 3.56235 -14.277594)
		(size 0.508)
		(drill 0.254)
		(layers "F.Cu" "B.Cu")
		(net "VR_PVDDQ_GHJ_PH2_VCIN")
	)
	(via
		(at 2.8702 -13.52296)
		(size 0.6604)
		(drill 0.3302)
		(layers "F.Cu" "B.Cu")
		(net "VR_PVDDQ_GHJ_PH2_VCIN")
	)
	(segment
		(start 2.8702 -13.52296)
		(end 2.8702 -13.585444)
		(width 0.254)
		(layer "B.Cu")
		(net "VR_PVDDQ_GHJ_PH2_VCIN")
	)
	(segment
		(start 3.499104 -14.34084)
		(end 3.499104 -15.15237)
		(width 0.508)
		(layer "B.Cu")
		(net "VR_PVDDQ_GHJ_PH2_VCIN")
	)
	(segment
		(start 3.56235 -14.277594)
		(end 3.499104 -14.34084)
		(width 0.508)
		(layer "B.Cu")
		(net "VR_PVDDQ_GHJ_PH2_VCIN")
	)
	(segment
		(start 2.8702 -13.585444)
		(end 3.56235 -14.277594)
		(width 0.254)
		(layer "B.Cu")
		(net "VR_PVDDQ_GHJ_PH2_VCIN")
	)
	(segment
		(start 1.2192 -19.2151)
		(end 1.823212 -18.611088)
		(width 0.1524)
		(layer "F.Cu")
		(net "VR_PVDDQ_GHJ_PH2_PHASE")
	)
	(segment
		(start 1.082548 -19.2151)
		(end 1.2192 -19.2151)
		(width 0.1524)
		(layer "F.Cu")
		(net "VR_PVDDQ_GHJ_PH2_PHASE")
	)
	(segment
		(start 0.5588 -19.2151)
		(end 1.082548 -19.2151)
		(width 0.3048)
		(layer "F.Cu")
		(net "VR_PVDDQ_GHJ_PH2_PHASE")
	)
	(segment
		(start 1.823212 -18.611088)
		(end 2.150364 -18.611088)
		(width 0.1524)
		(layer "F.Cu")
		(net "VR_PVDDQ_GHJ_PH2_PHASE")
	)
	(segment
		(start 3.483864 -6.26364)
		(end 3.2004 -5.980176)
		(width 0.4064)
		(layer "F.Cu")
		(net "VR_PVDDQ_GHJ_PH1_VCIN")
	)
	(segment
		(start 3.582924 -7.098538)
		(end 3.582924 -6.413754)
		(width 0.254)
		(layer "F.Cu")
		(net "VR_PVDDQ_GHJ_PH1_VCIN")
	)
	(segment
		(start 3.582924 -6.413754)
		(end 3.483864 -6.314694)
		(width 0.254)
		(layer "F.Cu")
		(net "VR_PVDDQ_GHJ_PH1_VCIN")
	)
	(segment
		(start 3.483864 -6.314694)
		(end 3.483864 -6.26364)
		(width 0.4064)
		(layer "F.Cu")
		(net "VR_PVDDQ_GHJ_PH1_VCIN")
	)
	(segment
		(start 3.2004 -5.980176)
		(end 3.2004 -5.675376)
		(width 0.4064)
		(layer "F.Cu")
		(net "VR_PVDDQ_GHJ_PH1_VCIN")
	)
	(via
		(at 3.483864 -6.314694)
		(size 0.508)
		(drill 0.254)
		(layers "F.Cu" "B.Cu")
		(net "VR_PVDDQ_GHJ_PH1_VCIN")
	)
	(segment
		(start 3.04292 -5.41782)
		(end 3.04292 -5.87375)
		(width 0.4064)
		(layer "B.Cu")
		(net "VR_PVDDQ_GHJ_PH1_VCIN")
	)
	(segment
		(start 3.04292 -5.87375)
		(end 3.483864 -6.314694)
		(width 0.4064)
		(layer "B.Cu")
		(net "VR_PVDDQ_GHJ_PH1_VCIN")
	)
	(segment
		(start 1.64084 -10.64387)
		(end 1.38684 -10.89787)
		(width 0.254)
		(layer "F.Cu")
		(net "VR_PVDDQ_GHJ_PH1_PHASE")
	)
	(segment
		(start 2.067814 -10.64387)
		(end 1.64084 -10.64387)
		(width 0.254)
		(layer "F.Cu")
		(net "VR_PVDDQ_GHJ_PH1_PHASE")
	)
	(segment
		(start 1.38684 -12.92098)
		(end 1.44018 -12.97432)
		(width 0.254)
		(layer "F.Cu")
		(net "VR_PVDDQ_GHJ_PH1_PHASE")
	)
	(segment
		(start 1.38684 -10.89787)
		(end 1.38684 -12.92098)
		(width 0.254)
		(layer "F.Cu")
		(net "VR_PVDDQ_GHJ_PH1_PHASE")
	)
	(segment
		(start 0.55118 -12.19454)
		(end 0.74676 -11.99896)
		(width 0.508)
		(layer "F.Cu")
		(net "VR_PVDDQ_GHJ_PH1_BOOT")
	)
	(segment
		(start 0.55118 -12.97432)
		(end 0.55118 -12.19454)
		(width 0.508)
		(layer "F.Cu")
		(net "VR_PVDDQ_GHJ_PH1_BOOT")
	)
	(segment
		(start 8.026146 -3.659886)
		(end 8.026146 -3.137154)
		(width 0.127)
		(layer "F.Cu")
		(net "VR_PVDDQ_GHJ_AVSP")
	)
	(segment
		(start 8.026146 -3.137154)
		(end 8.632952 -2.530348)
		(width 0.127)
		(layer "F.Cu")
		(net "VR_PVDDQ_GHJ_AVSP")
	)
	(segment
		(start 8.026146 -3.659886)
		(end 8.026146 -4.548886)
		(width 0.10795)
		(layer "F.Cu")
		(net "VR_PVDDQ_GHJ_AVSP")
	)
	(segment
		(start 8.632952 -2.530348)
		(end 8.632952 -2.20345)
		(width 0.127)
		(layer "F.Cu")
		(net "VR_PVDDQ_GHJ_AVSP")
	)
	(via
		(at 353.1362 -135.9154)
		(size 0.762)
		(drill 0.381)
		(layers "F.Cu" "B.Cu")
		(net "VR_PVDDQ_DEF_VDD")
	)
	(segment
		(start 351.010728 -145.043906)
		(end 351.0915 -145.124678)
		(width 0.254)
		(layer "F.Cu")
		(net "VR_PVDDQ_DEF_PWM2")
	)
	(segment
		(start 351.0915 -145.124678)
		(end 351.843594 -145.124678)
		(width 0.254)
		(layer "F.Cu")
		(net "VR_PVDDQ_DEF_PWM2")
	)
	(segment
		(start 350.357186 -145.043906)
		(end 351.010728 -145.043906)
		(width 0.254)
		(layer "F.Cu")
		(net "VR_PVDDQ_DEF_PWM2")
	)
	(segment
		(start 352.548444 -145.829528)
		(end 352.548444 -146.03984)
		(width 0.254)
		(layer "F.Cu")
		(net "VR_PVDDQ_DEF_PWM2")
	)
	(segment
		(start 351.843594 -145.124678)
		(end 352.548444 -145.829528)
		(width 0.254)
		(layer "F.Cu")
		(net "VR_PVDDQ_DEF_PWM2")
	)
	(segment
		(start 358.263444 -134.84479)
		(end 358.263444 -134.567168)
		(width 0.2032)
		(layer "F.Cu")
		(net "VR_PVDDQ_DEF_PWM2")
	)
	(segment
		(start 358.698292 -135.71347)
		(end 358.698292 -135.279638)
		(width 0.2032)
		(layer "F.Cu")
		(net "VR_PVDDQ_DEF_PWM2")
	)
	(segment
		(start 358.698292 -135.279638)
		(end 358.263444 -134.84479)
		(width 0.2032)
		(layer "F.Cu")
		(net "VR_PVDDQ_DEF_PWM2")
	)
	(via
		(at 358.263444 -134.567168)
		(size 0.508)
		(drill 0.254)
		(layers "F.Cu" "B.Cu")
		(net "VR_PVDDQ_DEF_PWM2")
	)
	(via
		(at 352.548444 -146.03984)
		(size 0.508)
		(drill 0.254)
		(layers "F.Cu" "B.Cu")
		(net "VR_PVDDQ_DEF_PWM2")
	)
	(via
		(at 352.7044 -146.7612)
		(size 0.6604)
		(drill 0.3302)
		(layers "F.Cu" "B.Cu")
		(net "VR_PVDDQ_DEF_PWM2")
	)
	(segment
		(start 352.7044 -146.7612)
		(end 352.7044 -146.741896)
		(width 0.254)
		(layer "B.Cu")
		(net "VR_PVDDQ_DEF_PWM2")
	)
	(segment
		(start 352.548444 -146.58594)
		(end 352.548444 -146.03984)
		(width 0.254)
		(layer "B.Cu")
		(net "VR_PVDDQ_DEF_PWM2")
	)
	(segment
		(start 352.7044 -146.741896)
		(end 352.548444 -146.58594)
		(width 0.254)
		(layer "B.Cu")
		(net "VR_PVDDQ_DEF_PWM2")
	)
	(segment
		(start 352.548444 -143.568928)
		(end 357.791512 -138.32586)
		(width 0.254)
		(layer "In2.Cu")
		(net "VR_PVDDQ_DEF_PWM2")
	)
	(segment
		(start 352.548444 -146.03984)
		(end 352.548444 -143.568928)
		(width 0.254)
		(layer "In2.Cu")
		(net "VR_PVDDQ_DEF_PWM2")
	)
	(segment
		(start 358.263444 -135.324596)
		(end 358.263444 -134.567168)
		(width 0.254)
		(layer "In2.Cu")
		(net "VR_PVDDQ_DEF_PWM2")
	)
	(segment
		(start 357.438452 -136.149588)
		(end 358.263444 -135.324596)
		(width 0.254)
		(layer "In2.Cu")
		(net "VR_PVDDQ_DEF_PWM2")
	)
	(segment
		(start 357.438452 -136.779)
		(end 357.438452 -136.149588)
		(width 0.254)
		(layer "In2.Cu")
		(net "VR_PVDDQ_DEF_PWM2")
	)
	(segment
		(start 357.791512 -137.13206)
		(end 357.438452 -136.779)
		(width 0.254)
		(layer "In2.Cu")
		(net "VR_PVDDQ_DEF_PWM2")
	)
	(segment
		(start 357.791512 -138.32586)
		(end 357.791512 -137.13206)
		(width 0.254)
		(layer "In2.Cu")
		(net "VR_PVDDQ_DEF_PWM2")
	)
	(segment
		(start 351.7646 -153.0604)
		(end 351.79 -153.0858)
		(width 0.254)
		(layer "F.Cu")
		(net "VR_PVDDQ_DEF_PWM1")
	)
	(segment
		(start 359.098342 -135.71347)
		(end 359.098342 -134.994142)
		(width 0.2032)
		(layer "F.Cu")
		(net "VR_PVDDQ_DEF_PWM1")
	)
	(segment
		(start 350.357186 -152.968706)
		(end 351.517458 -152.968706)
		(width 0.254)
		(layer "F.Cu")
		(net "VR_PVDDQ_DEF_PWM1")
	)
	(segment
		(start 359.098342 -134.994142)
		(end 359.0544 -134.9502)
		(width 0.2032)
		(layer "F.Cu")
		(net "VR_PVDDQ_DEF_PWM1")
	)
	(segment
		(start 351.517458 -152.968706)
		(end 351.609152 -153.0604)
		(width 0.254)
		(layer "F.Cu")
		(net "VR_PVDDQ_DEF_PWM1")
	)
	(segment
		(start 351.609152 -153.0604)
		(end 351.7646 -153.0604)
		(width 0.254)
		(layer "F.Cu")
		(net "VR_PVDDQ_DEF_PWM1")
	)
	(via
		(at 359.0544 -134.9502)
		(size 0.508)
		(drill 0.254)
		(layers "F.Cu" "B.Cu")
		(net "VR_PVDDQ_DEF_PWM1")
	)
	(via
		(at 351.79 -153.0858)
		(size 0.508)
		(drill 0.254)
		(layers "F.Cu" "B.Cu")
		(net "VR_PVDDQ_DEF_PWM1")
	)
	(segment
		(start 360.749088 -140.72997)
		(end 359.0544 -139.035282)
		(width 0.254)
		(layer "In2.Cu")
		(net "VR_PVDDQ_DEF_PWM1")
	)
	(segment
		(start 351.79 -153.0858)
		(end 352.2726 -152.6032)
		(width 0.254)
		(layer "In2.Cu")
		(net "VR_PVDDQ_DEF_PWM1")
	)
	(segment
		(start 361.762802 -140.72997)
		(end 360.749088 -140.72997)
		(width 0.254)
		(layer "In2.Cu")
		(net "VR_PVDDQ_DEF_PWM1")
	)
	(segment
		(start 352.2726 -149.479)
		(end 353.7966 -147.955)
		(width 0.254)
		(layer "In2.Cu")
		(net "VR_PVDDQ_DEF_PWM1")
	)
	(segment
		(start 363.05744 -142.024608)
		(end 361.762802 -140.72997)
		(width 0.254)
		(layer "In2.Cu")
		(net "VR_PVDDQ_DEF_PWM1")
	)
	(segment
		(start 353.7966 -147.955)
		(end 361.361736 -147.955)
		(width 0.254)
		(layer "In2.Cu")
		(net "VR_PVDDQ_DEF_PWM1")
	)
	(segment
		(start 359.0544 -139.035282)
		(end 359.0544 -134.9502)
		(width 0.254)
		(layer "In2.Cu")
		(net "VR_PVDDQ_DEF_PWM1")
	)
	(segment
		(start 361.361736 -147.955)
		(end 363.05744 -146.259296)
		(width 0.254)
		(layer "In2.Cu")
		(net "VR_PVDDQ_DEF_PWM1")
	)
	(segment
		(start 363.05744 -146.259296)
		(end 363.05744 -142.024608)
		(width 0.254)
		(layer "In2.Cu")
		(net "VR_PVDDQ_DEF_PWM1")
	)
	(segment
		(start 352.2726 -152.6032)
		(end 352.2726 -149.479)
		(width 0.254)
		(layer "In2.Cu")
		(net "VR_PVDDQ_DEF_PWM1")
	)
	(segment
		(start 348.842076 -147.689062)
		(end 348.842076 -148.4249)
		(width 0.254)
		(layer "F.Cu")
		(net "VR_PVDDQ_DEF_PH2_VCIN")
	)
	(segment
		(start 348.9198 -148.807424)
		(end 349.2246 -149.112224)
		(width 0.4064)
		(layer "F.Cu")
		(net "VR_PVDDQ_DEF_PH2_VCIN")
	)
	(segment
		(start 348.842076 -148.4249)
		(end 348.9198 -148.502624)
		(width 0.254)
		(layer "F.Cu")
		(net "VR_PVDDQ_DEF_PH2_VCIN")
	)
	(segment
		(start 348.9198 -148.502624)
		(end 348.9198 -148.807424)
		(width 0.4064)
		(layer "F.Cu")
		(net "VR_PVDDQ_DEF_PH2_VCIN")
	)
	(via
		(at 349.9358 -149.225)
		(size 0.6604)
		(drill 0.3302)
		(layers "F.Cu" "B.Cu")
		(net "VR_PVDDQ_DEF_PH2_VCIN")
	)
	(via
		(at 348.9198 -148.502624)
		(size 0.508)
		(drill 0.254)
		(layers "F.Cu" "B.Cu")
		(net "VR_PVDDQ_DEF_PH2_VCIN")
	)
	(segment
		(start 349.2246 -147.715224)
		(end 349.2246 -148.0312)
		(width 0.4064)
		(layer "B.Cu")
		(net "VR_PVDDQ_DEF_PH2_VCIN")
	)
	(segment
		(start 349.1738 -148.9456)
		(end 348.9198 -148.6916)
		(width 0.254)
		(layer "B.Cu")
		(net "VR_PVDDQ_DEF_PH2_VCIN")
	)
	(segment
		(start 348.9198 -148.6916)
		(end 348.9198 -148.502624)
		(width 0.254)
		(layer "B.Cu")
		(net "VR_PVDDQ_DEF_PH2_VCIN")
	)
	(segment
		(start 349.6564 -148.9456)
		(end 349.1738 -148.9456)
		(width 0.254)
		(layer "B.Cu")
		(net "VR_PVDDQ_DEF_PH2_VCIN")
	)
	(segment
		(start 348.9198 -148.336)
		(end 348.9198 -148.502624)
		(width 0.4064)
		(layer "B.Cu")
		(net "VR_PVDDQ_DEF_PH2_VCIN")
	)
	(segment
		(start 349.9358 -149.225)
		(end 349.6564 -148.9456)
		(width 0.254)
		(layer "B.Cu")
		(net "VR_PVDDQ_DEF_PH2_VCIN")
	)
	(segment
		(start 349.2246 -148.0312)
		(end 348.9198 -148.336)
		(width 0.4064)
		(layer "B.Cu")
		(net "VR_PVDDQ_DEF_PH2_VCIN")
	)
	(segment
		(start 351.186242 -143.714216)
		(end 350.756728 -144.14373)
		(width 0.254)
		(layer "F.Cu")
		(net "VR_PVDDQ_DEF_PH2_PHASE")
	)
	(segment
		(start 350.756728 -144.14373)
		(end 350.357186 -144.14373)
		(width 0.254)
		(layer "F.Cu")
		(net "VR_PVDDQ_DEF_PH2_PHASE")
	)
	(segment
		(start 351.870518 -143.483076)
		(end 351.417382 -143.483076)
		(width 0.508)
		(layer "F.Cu")
		(net "VR_PVDDQ_DEF_PH2_PHASE")
	)
	(segment
		(start 351.417382 -143.483076)
		(end 351.186242 -143.714216)
		(width 0.508)
		(layer "F.Cu")
		(net "VR_PVDDQ_DEF_PH2_PHASE")
	)
	(segment
		(start 352.759518 -143.162274)
		(end 352.759518 -143.483076)
		(width 0.508)
		(layer "F.Cu")
		(net "VR_PVDDQ_DEF_PH2_BOOT")
	)
	(segment
		(start 352.759518 -143.483076)
		(end 353.216464 -143.963644)
		(width 0.508)
		(layer "F.Cu")
		(net "VR_PVDDQ_DEF_PH2_BOOT")
	)
	(segment
		(start 353.216464 -143.963644)
		(end 353.216464 -144.502378)
		(width 0.508)
		(layer "F.Cu")
		(net "VR_PVDDQ_DEF_PH2_BOOT")
	)
	(segment
		(start 353.267772 -142.65402)
		(end 352.759518 -143.162274)
		(width 0.508)
		(layer "F.Cu")
		(net "VR_PVDDQ_DEF_PH2_BOOT")
	)
	(segment
		(start 353.66706 -142.65402)
		(end 353.267772 -142.65402)
		(width 0.508)
		(layer "F.Cu")
		(net "VR_PVDDQ_DEF_PH2_BOOT")
	)
	(via
		(at 353.66706 -142.65402)
		(size 0.762)
		(drill 0.381)
		(layers "F.Cu" "B.Cu")
		(net "VR_PVDDQ_DEF_PH2_BOOT")
	)
	(segment
		(start 349.073724 -156.623766)
		(end 349.073724 -156.639006)
		(width 0.4064)
		(layer "F.Cu")
		(net "VR_PVDDQ_DEF_PH1_VCIN")
	)
	(segment
		(start 348.8436 -156.159708)
		(end 348.8436 -156.393642)
		(width 0.254)
		(layer "F.Cu")
		(net "VR_PVDDQ_DEF_PH1_VCIN")
	)
	(segment
		(start 348.8436 -156.393642)
		(end 348.954852 -156.504894)
		(width 0.254)
		(layer "F.Cu")
		(net "VR_PVDDQ_DEF_PH1_VCIN")
	)
	(segment
		(start 349.1738 -156.739082)
		(end 349.1738 -157.2768)
		(width 0.4064)
		(layer "F.Cu")
		(net "VR_PVDDQ_DEF_PH1_VCIN")
	)
	(segment
		(start 348.842076 -155.613862)
		(end 348.842076 -156.158184)
		(width 0.254)
		(layer "F.Cu")
		(net "VR_PVDDQ_DEF_PH1_VCIN")
	)
	(segment
		(start 349.073724 -156.639006)
		(end 349.1738 -156.739082)
		(width 0.4064)
		(layer "F.Cu")
		(net "VR_PVDDQ_DEF_PH1_VCIN")
	)
	(segment
		(start 348.954852 -156.504894)
		(end 349.073724 -156.623766)
		(width 0.4064)
		(layer "F.Cu")
		(net "VR_PVDDQ_DEF_PH1_VCIN")
	)
	(segment
		(start 348.842076 -156.158184)
		(end 348.8436 -156.159708)
		(width 0.254)
		(layer "F.Cu")
		(net "VR_PVDDQ_DEF_PH1_VCIN")
	)
	(via
		(at 348.954852 -156.504894)
		(size 0.508)
		(drill 0.254)
		(layers "F.Cu" "B.Cu")
		(net "VR_PVDDQ_DEF_PH1_VCIN")
	)
	(via
		(at 350.24822 -155.69692)
		(size 0.6604)
		(drill 0.3302)
		(layers "F.Cu" "B.Cu")
		(net "VR_PVDDQ_DEF_PH1_VCIN")
	)
	(segment
		(start 348.954852 -156.504894)
		(end 348.954852 -156.366972)
		(width 0.4064)
		(layer "B.Cu")
		(net "VR_PVDDQ_DEF_PH1_VCIN")
	)
	(segment
		(start 349.0214 -156.300424)
		(end 349.0214 -155.7274)
		(width 0.4064)
		(layer "B.Cu")
		(net "VR_PVDDQ_DEF_PH1_VCIN")
	)
	(segment
		(start 349.05188 -155.69692)
		(end 350.24822 -155.69692)
		(width 0.4064)
		(layer "B.Cu")
		(net "VR_PVDDQ_DEF_PH1_VCIN")
	)
	(segment
		(start 348.954852 -156.366972)
		(end 349.0214 -156.300424)
		(width 0.4064)
		(layer "B.Cu")
		(net "VR_PVDDQ_DEF_PH1_VCIN")
	)
	(segment
		(start 349.0214 -155.7274)
		(end 349.05188 -155.69692)
		(width 0.4064)
		(layer "B.Cu")
		(net "VR_PVDDQ_DEF_PH1_VCIN")
	)
	(segment
		(start 350.827848 -152.06853)
		(end 351.157286 -151.739092)
		(width 0.254)
		(layer "F.Cu")
		(net "VR_PVDDQ_DEF_PH1_PHASE")
	)
	(segment
		(start 351.157286 -151.739092)
		(end 351.157286 -151.638)
		(width 0.254)
		(layer "F.Cu")
		(net "VR_PVDDQ_DEF_PH1_PHASE")
	)
	(segment
		(start 351.538286 -151.257)
		(end 352.1075 -151.257)
		(width 0.508)
		(layer "F.Cu")
		(net "VR_PVDDQ_DEF_PH1_PHASE")
	)
	(segment
		(start 351.157286 -151.638)
		(end 351.283016 -151.51227)
		(width 0.254)
		(layer "F.Cu")
		(net "VR_PVDDQ_DEF_PH1_PHASE")
	)
	(segment
		(start 350.357186 -152.06853)
		(end 350.827848 -152.06853)
		(width 0.254)
		(layer "F.Cu")
		(net "VR_PVDDQ_DEF_PH1_PHASE")
	)
	(segment
		(start 351.283016 -151.51227)
		(end 351.538286 -151.257)
		(width 0.508)
		(layer "F.Cu")
		(net "VR_PVDDQ_DEF_PH1_PHASE")
	)
	(segment
		(start 352.9965 -151.7015)
		(end 353.2505 -151.9555)
		(width 0.508)
		(layer "F.Cu")
		(net "VR_PVDDQ_DEF_PH1_BOOT")
	)
	(segment
		(start 353.2505 -151.9555)
		(end 353.2505 -152.273)
		(width 0.508)
		(layer "F.Cu")
		(net "VR_PVDDQ_DEF_PH1_BOOT")
	)
	(segment
		(start 352.9965 -151.257)
		(end 354.08362 -151.257)
		(width 0.508)
		(layer "F.Cu")
		(net "VR_PVDDQ_DEF_PH1_BOOT")
	)
	(segment
		(start 352.9965 -151.257)
		(end 352.9965 -151.7015)
		(width 0.508)
		(layer "F.Cu")
		(net "VR_PVDDQ_DEF_PH1_BOOT")
	)
	(via
		(at 354.08362 -151.257)
		(size 0.762)
		(drill 0.381)
		(layers "F.Cu" "B.Cu")
		(net "VR_PVDDQ_DEF_PH1_BOOT")
	)
	(segment
		(start 362.30052 -139.86256)
		(end 362.30052 -139.70762)
		(width 0.127)
		(layer "F.Cu")
		(net "VR_PVDDQ_DEF_AVSP")
	)
	(segment
		(start 365.70158 -140.07846)
		(end 365.7092 -140.07846)
		(width 0.1016)
		(layer "F.Cu")
		(net "VR_PVDDQ_DEF_AVSP")
	)
	(segment
		(start 363.87024 -140.88237)
		(end 363.32033 -140.88237)
		(width 0.127)
		(layer "F.Cu")
		(net "VR_PVDDQ_DEF_AVSP")
	)
	(segment
		(start 363.87024 -140.88237)
		(end 364.78464 -140.88237)
		(width 0.127)
		(layer "F.Cu")
		(net "VR_PVDDQ_DEF_AVSP")
	)
	(segment
		(start 364.89767 -140.88237)
		(end 365.70158 -140.07846)
		(width 0.1016)
		(layer "F.Cu")
		(net "VR_PVDDQ_DEF_AVSP")
	)
	(segment
		(start 362.30052 -139.70762)
		(end 362.157518 -139.564618)
		(width 0.127)
		(layer "F.Cu")
		(net "VR_PVDDQ_DEF_AVSP")
	)
	(segment
		(start 362.157518 -139.564618)
		(end 361.74934 -139.564618)
		(width 0.127)
		(layer "F.Cu")
		(net "VR_PVDDQ_DEF_AVSP")
	)
	(segment
		(start 363.32033 -140.88237)
		(end 362.30052 -139.86256)
		(width 0.127)
		(layer "F.Cu")
		(net "VR_PVDDQ_DEF_AVSP")
	)
	(segment
		(start 364.78464 -140.88237)
		(end 364.89767 -140.88237)
		(width 0.1016)
		(layer "F.Cu")
		(net "VR_PVDDQ_DEF_AVSP")
	)
	(via
		(at 365.7092 -140.07846)
		(size 0.762)
		(drill 0.381)
		(layers "F.Cu" "B.Cu")
		(net "VR_PVDDQ_DEF_AVSP")
	)
	(segment
		(start 355.852476 -137.164572)
		(end 355.838252 -137.150348)
		(width 0.254)
		(layer "F.Cu")
		(net "VR_PVDDQ_DEF_AIINSEN")
	)
	(segment
		(start 354.244656 -137.389108)
		(end 353.670108 -137.389108)
		(width 0.254)
		(layer "F.Cu")
		(net "VR_PVDDQ_DEF_AIINSEN")
	)
	(segment
		(start 354.570792 -137.389108)
		(end 354.244656 -137.389108)
		(width 0.254)
		(layer "F.Cu")
		(net "VR_PVDDQ_DEF_AIINSEN")
	)
	(segment
		(start 356.266242 -137.164572)
		(end 355.852476 -137.164572)
		(width 0.254)
		(layer "F.Cu")
		(net "VR_PVDDQ_DEF_AIINSEN")
	)
	(segment
		(start 355.838252 -137.150348)
		(end 355.149404 -137.150348)
		(width 0.254)
		(layer "F.Cu")
		(net "VR_PVDDQ_DEF_AIINSEN")
	)
	(segment
		(start 354.809552 -137.150348)
		(end 354.570792 -137.389108)
		(width 0.254)
		(layer "F.Cu")
		(net "VR_PVDDQ_DEF_AIINSEN")
	)
	(segment
		(start 355.149404 -137.150348)
		(end 354.809552 -137.150348)
		(width 0.254)
		(layer "F.Cu")
		(net "VR_PVDDQ_DEF_AIINSEN")
	)
	(segment
		(start 353.670108 -137.389108)
		(end 353.187 -136.906)
		(width 0.254)
		(layer "F.Cu")
		(net "VR_PVDDQ_DEF_AIINSEN")
	)
	(segment
		(start 356.84714 -137.164572)
		(end 356.266242 -137.164572)
		(width 0.2032)
		(layer "F.Cu")
		(net "VR_PVDDQ_DEF_AIINSEN")
	)
	(via
		(at 353.187 -136.906)
		(size 0.508)
		(drill 0.254)
		(layers "F.Cu" "B.Cu")
		(net "VR_PVDDQ_DEF_AIINSEN")
	)
	(segment
		(start 353.187 -136.906)
		(end 353.712272 -136.380728)
		(width 0.254)
		(layer "B.Cu")
		(net "VR_PVDDQ_DEF_AIINSEN")
	)
	(segment
		(start 353.712272 -136.060688)
		(end 354.45446 -135.3185)
		(width 0.254)
		(layer "B.Cu")
		(net "VR_PVDDQ_DEF_AIINSEN")
	)
	(segment
		(start 353.712272 -136.380728)
		(end 353.712272 -136.060688)
		(width 0.254)
		(layer "B.Cu")
		(net "VR_PVDDQ_DEF_AIINSEN")
	)
	(segment
		(start 354.45446 -135.3185)
		(end 354.45446 -135.1915)
		(width 0.254)
		(layer "B.Cu")
		(net "VR_PVDDQ_DEF_AIINSEN")
	)
	(segment
		(start 349.123 -12.827)
		(end 349.123 -12.6492)
		(width 0.254)
		(layer "F.Cu")
		(net "VR_PVDDQ_ABC_XADDR2")
	)
	(segment
		(start 347.907864 -14.169136)
		(end 347.709998 -14.367002)
		(width 0.2032)
		(layer "F.Cu")
		(net "VR_PVDDQ_ABC_XADDR2")
	)
	(segment
		(start 347.709998 -14.367002)
		(end 347.1291 -14.367002)
		(width 0.2032)
		(layer "F.Cu")
		(net "VR_PVDDQ_ABC_XADDR2")
	)
	(segment
		(start 348.869 -12.3952)
		(end 348.46514 -12.3952)
		(width 0.254)
		(layer "F.Cu")
		(net "VR_PVDDQ_ABC_XADDR2")
	)
	(segment
		(start 349.123 -12.6492)
		(end 348.869 -12.3952)
		(width 0.254)
		(layer "F.Cu")
		(net "VR_PVDDQ_ABC_XADDR2")
	)
	(segment
		(start 348.46514 -13.61186)
		(end 347.907864 -14.169136)
		(width 0.254)
		(layer "F.Cu")
		(net "VR_PVDDQ_ABC_XADDR2")
	)
	(segment
		(start 348.46514 -12.3952)
		(end 348.46514 -13.61186)
		(width 0.254)
		(layer "F.Cu")
		(net "VR_PVDDQ_ABC_XADDR2")
	)
	(via
		(at 348.46514 -12.3952)
		(size 0.508)
		(drill 0.254)
		(layers "F.Cu" "B.Cu")
		(net "VR_PVDDQ_ABC_XADDR2")
	)
	(segment
		(start 348.548452 -14.859)
		(end 348.421452 -14.986)
		(width 0.254)
		(layer "F.Cu")
		(net "VR_PVDDQ_ABC_XADDR1")
	)
	(segment
		(start 349.123 -14.859)
		(end 348.548452 -14.859)
		(width 0.254)
		(layer "F.Cu")
		(net "VR_PVDDQ_ABC_XADDR1")
	)
	(segment
		(start 348.421452 -14.986)
		(end 348.284292 -14.986)
		(width 0.254)
		(layer "F.Cu")
		(net "VR_PVDDQ_ABC_XADDR1")
	)
	(segment
		(start 347.653102 -15.566898)
		(end 348.145354 -15.074646)
		(width 0.2032)
		(layer "F.Cu")
		(net "VR_PVDDQ_ABC_XADDR1")
	)
	(segment
		(start 348.284292 -14.986)
		(end 348.195646 -15.074646)
		(width 0.254)
		(layer "F.Cu")
		(net "VR_PVDDQ_ABC_XADDR1")
	)
	(segment
		(start 348.145354 -15.074646)
		(end 348.195646 -15.074646)
		(width 0.2032)
		(layer "F.Cu")
		(net "VR_PVDDQ_ABC_XADDR1")
	)
	(segment
		(start 347.1291 -15.566898)
		(end 347.653102 -15.566898)
		(width 0.2032)
		(layer "F.Cu")
		(net "VR_PVDDQ_ABC_XADDR1")
	)
	(via
		(at 348.195646 -15.074646)
		(size 0.508)
		(drill 0.254)
		(layers "F.Cu" "B.Cu")
		(net "VR_PVDDQ_ABC_XADDR1")
	)
	(segment
		(start 348.22765 -17.07515)
		(end 347.82887 -17.07515)
		(width 0.2032)
		(layer "F.Cu")
		(net "VR_PVDDQ_ABC_VDD")
	)
	(segment
		(start 347.520768 -16.767048)
		(end 347.1291 -16.767048)
		(width 0.2032)
		(layer "F.Cu")
		(net "VR_PVDDQ_ABC_VDD")
	)
	(segment
		(start 347.82887 -17.07515)
		(end 347.520768 -16.767048)
		(width 0.2032)
		(layer "F.Cu")
		(net "VR_PVDDQ_ABC_VDD")
	)
	(via
		(at 348.22765 -17.07515)
		(size 0.508)
		(drill 0.254)
		(layers "F.Cu" "B.Cu")
		(net "VR_PVDDQ_ABC_VDD")
	)
	(segment
		(start 348.22765 -17.07515)
		(end 348.5515 -17.399)
		(width 0.508)
		(layer "B.Cu")
		(net "VR_PVDDQ_ABC_VDD")
	)
	(segment
		(start 348.5515 -17.399)
		(end 349.377 -17.399)
		(width 0.508)
		(layer "B.Cu")
		(net "VR_PVDDQ_ABC_VDD")
	)
	(segment
		(start 345.277948 -18.379948)
		(end 345.475814 -18.577814)
		(width 0.2032)
		(layer "F.Cu")
		(net "VR_PVDDQ_ABC_PWM2")
	)
	(segment
		(start 350.139254 1.991614)
		(end 350.242378 1.88849)
		(width 0.254)
		(layer "F.Cu")
		(net "VR_PVDDQ_ABC_PWM2")
	)
	(segment
		(start 345.791028 -19.121628)
		(end 346.329 -19.6596)
		(width 0.254)
		(layer "F.Cu")
		(net "VR_PVDDQ_ABC_PWM2")
	)
	(segment
		(start 350.586294 1.88849)
		(end 351.066354 1.40843)
		(width 0.254)
		(layer "F.Cu")
		(net "VR_PVDDQ_ABC_PWM2")
	)
	(segment
		(start 349.262192 1.991614)
		(end 350.139254 1.991614)
		(width 0.254)
		(layer "F.Cu")
		(net "VR_PVDDQ_ABC_PWM2")
	)
	(segment
		(start 345.791028 -18.893028)
		(end 345.791028 -19.121628)
		(width 0.254)
		(layer "F.Cu")
		(net "VR_PVDDQ_ABC_PWM2")
	)
	(segment
		(start 345.277948 -17.8181)
		(end 345.277948 -18.379948)
		(width 0.2032)
		(layer "F.Cu")
		(net "VR_PVDDQ_ABC_PWM2")
	)
	(segment
		(start 345.475814 -18.577814)
		(end 345.791028 -18.893028)
		(width 0.254)
		(layer "F.Cu")
		(net "VR_PVDDQ_ABC_PWM2")
	)
	(segment
		(start 350.242378 1.88849)
		(end 350.586294 1.88849)
		(width 0.254)
		(layer "F.Cu")
		(net "VR_PVDDQ_ABC_PWM2")
	)
	(via
		(at 346.329 -19.6596)
		(size 0.508)
		(drill 0.254)
		(layers "F.Cu" "B.Cu")
		(net "VR_PVDDQ_ABC_PWM2")
	)
	(via
		(at 351.066354 1.40843)
		(size 0.508)
		(drill 0.254)
		(layers "F.Cu" "B.Cu")
		(net "VR_PVDDQ_ABC_PWM2")
	)
	(segment
		(start 353.751896 -2.813812)
		(end 353.751896 -3.902964)
		(width 0.254)
		(layer "In2.Cu")
		(net "VR_PVDDQ_ABC_PWM2")
	)
	(segment
		(start 351.465134 -10.836148)
		(end 351.465134 -12.029948)
		(width 0.254)
		(layer "In2.Cu")
		(net "VR_PVDDQ_ABC_PWM2")
	)
	(segment
		(start 351.558352 -13.671804)
		(end 350.079564 -15.150592)
		(width 0.254)
		(layer "In2.Cu")
		(net "VR_PVDDQ_ABC_PWM2")
	)
	(segment
		(start 351.465134 -12.029948)
		(end 351.558352 -12.123166)
		(width 0.254)
		(layer "In2.Cu")
		(net "VR_PVDDQ_ABC_PWM2")
	)
	(segment
		(start 353.751896 -3.902964)
		(end 354.889562 -5.04063)
		(width 0.254)
		(layer "In2.Cu")
		(net "VR_PVDDQ_ABC_PWM2")
	)
	(segment
		(start 350.079564 -16.958818)
		(end 349.013018 -18.025364)
		(width 0.254)
		(layer "In2.Cu")
		(net "VR_PVDDQ_ABC_PWM2")
	)
	(segment
		(start 349.013018 -18.025364)
		(end 349.013018 -18.631662)
		(width 0.254)
		(layer "In2.Cu")
		(net "VR_PVDDQ_ABC_PWM2")
	)
	(segment
		(start 349.013018 -18.631662)
		(end 347.98508 -19.6596)
		(width 0.254)
		(layer "In2.Cu")
		(net "VR_PVDDQ_ABC_PWM2")
	)
	(segment
		(start 350.079564 -15.150592)
		(end 350.079564 -16.958818)
		(width 0.254)
		(layer "In2.Cu")
		(net "VR_PVDDQ_ABC_PWM2")
	)
	(segment
		(start 354.889562 -7.41172)
		(end 351.465134 -10.836148)
		(width 0.254)
		(layer "In2.Cu")
		(net "VR_PVDDQ_ABC_PWM2")
	)
	(segment
		(start 347.98508 -19.6596)
		(end 346.329 -19.6596)
		(width 0.254)
		(layer "In2.Cu")
		(net "VR_PVDDQ_ABC_PWM2")
	)
	(segment
		(start 351.558352 -12.123166)
		(end 351.558352 -13.671804)
		(width 0.254)
		(layer "In2.Cu")
		(net "VR_PVDDQ_ABC_PWM2")
	)
	(segment
		(start 351.066354 1.40843)
		(end 351.174812 1.299972)
		(width 0.254)
		(layer "In2.Cu")
		(net "VR_PVDDQ_ABC_PWM2")
	)
	(segment
		(start 351.174812 1.299972)
		(end 351.174812 -0.236728)
		(width 0.254)
		(layer "In2.Cu")
		(net "VR_PVDDQ_ABC_PWM2")
	)
	(segment
		(start 354.889562 -5.04063)
		(end 354.889562 -7.41172)
		(width 0.254)
		(layer "In2.Cu")
		(net "VR_PVDDQ_ABC_PWM2")
	)
	(segment
		(start 351.174812 -0.236728)
		(end 353.751896 -2.813812)
		(width 0.254)
		(layer "In2.Cu")
		(net "VR_PVDDQ_ABC_PWM2")
	)
	(segment
		(start 344.877898 -17.8181)
		(end 344.877898 -18.741898)
		(width 0.2032)
		(layer "F.Cu")
		(net "VR_PVDDQ_ABC_PWM1")
	)
	(segment
		(start 350.56826 -6.209284)
		(end 349.832168 -6.209284)
		(width 0.254)
		(layer "F.Cu")
		(net "VR_PVDDQ_ABC_PWM1")
	)
	(segment
		(start 349.832168 -6.209284)
		(end 349.765366 -6.142482)
		(width 0.254)
		(layer "F.Cu")
		(net "VR_PVDDQ_ABC_PWM1")
	)
	(segment
		(start 344.877898 -18.741898)
		(end 345.059 -18.923)
		(width 0.2032)
		(layer "F.Cu")
		(net "VR_PVDDQ_ABC_PWM1")
	)
	(segment
		(start 350.937068 -6.578092)
		(end 350.56826 -6.209284)
		(width 0.254)
		(layer "F.Cu")
		(net "VR_PVDDQ_ABC_PWM1")
	)
	(segment
		(start 349.765366 -6.142482)
		(end 349.341186 -6.142482)
		(width 0.254)
		(layer "F.Cu")
		(net "VR_PVDDQ_ABC_PWM1")
	)
	(via
		(at 345.059 -18.923)
		(size 0.508)
		(drill 0.254)
		(layers "F.Cu" "B.Cu")
		(net "VR_PVDDQ_ABC_PWM1")
	)
	(via
		(at 350.937068 -6.578092)
		(size 0.508)
		(drill 0.254)
		(layers "F.Cu" "B.Cu")
		(net "VR_PVDDQ_ABC_PWM1")
	)
	(segment
		(start 350.647 -2.9972)
		(end 350.3422 -2.6924)
		(width 0.254)
		(layer "In2.Cu")
		(net "VR_PVDDQ_ABC_PWM1")
	)
	(segment
		(start 347.4974 -2.6924)
		(end 346.7354 -1.9304)
		(width 0.254)
		(layer "In2.Cu")
		(net "VR_PVDDQ_ABC_PWM1")
	)
	(segment
		(start 343.0905 -16.178784)
		(end 345.059 -18.147284)
		(width 0.254)
		(layer "In2.Cu")
		(net "VR_PVDDQ_ABC_PWM1")
	)
	(segment
		(start 345.059 -18.147284)
		(end 345.059 -18.923)
		(width 0.254)
		(layer "In2.Cu")
		(net "VR_PVDDQ_ABC_PWM1")
	)
	(segment
		(start 350.937068 -6.578092)
		(end 350.647 -6.288024)
		(width 0.254)
		(layer "In2.Cu")
		(net "VR_PVDDQ_ABC_PWM1")
	)
	(segment
		(start 342.44788 -16.178784)
		(end 343.0905 -16.178784)
		(width 0.254)
		(layer "In2.Cu")
		(net "VR_PVDDQ_ABC_PWM1")
	)
	(segment
		(start 340.0298 -11.3792)
		(end 340.0298 -13.760704)
		(width 0.254)
		(layer "In2.Cu")
		(net "VR_PVDDQ_ABC_PWM1")
	)
	(segment
		(start 340.0298 -13.760704)
		(end 342.44788 -16.178784)
		(width 0.254)
		(layer "In2.Cu")
		(net "VR_PVDDQ_ABC_PWM1")
	)
	(segment
		(start 346.7354 -1.9304)
		(end 343.969848 -1.9304)
		(width 0.254)
		(layer "In2.Cu")
		(net "VR_PVDDQ_ABC_PWM1")
	)
	(segment
		(start 343.969848 -1.9304)
		(end 342.537542 -3.362706)
		(width 0.254)
		(layer "In2.Cu")
		(net "VR_PVDDQ_ABC_PWM1")
	)
	(segment
		(start 342.537542 -3.362706)
		(end 342.537542 -8.871458)
		(width 0.254)
		(layer "In2.Cu")
		(net "VR_PVDDQ_ABC_PWM1")
	)
	(segment
		(start 350.3422 -2.6924)
		(end 347.4974 -2.6924)
		(width 0.254)
		(layer "In2.Cu")
		(net "VR_PVDDQ_ABC_PWM1")
	)
	(segment
		(start 350.647 -6.288024)
		(end 350.647 -2.9972)
		(width 0.254)
		(layer "In2.Cu")
		(net "VR_PVDDQ_ABC_PWM1")
	)
	(segment
		(start 342.537542 -8.871458)
		(end 340.0298 -11.3792)
		(width 0.254)
		(layer "In2.Cu")
		(net "VR_PVDDQ_ABC_PWM1")
	)
	(segment
		(start 347.850206 -2.254504)
		(end 347.850206 -1.492504)
		(width 0.508)
		(layer "F.Cu")
		(net "VR_PVDDQ_ABC_PH2_VCIN")
	)
	(segment
		(start 347.747082 -0.653542)
		(end 347.747082 -1.160526)
		(width 0.254)
		(layer "F.Cu")
		(net "VR_PVDDQ_ABC_PH2_VCIN")
	)
	(segment
		(start 347.747082 -1.160526)
		(end 347.824806 -1.23825)
		(width 0.254)
		(layer "F.Cu")
		(net "VR_PVDDQ_ABC_PH2_VCIN")
	)
	(segment
		(start 347.824806 -1.23825)
		(end 347.824806 -1.467104)
		(width 0.254)
		(layer "F.Cu")
		(net "VR_PVDDQ_ABC_PH2_VCIN")
	)
	(segment
		(start 347.850206 -1.492504)
		(end 347.824806 -1.467104)
		(width 0.508)
		(layer "F.Cu")
		(net "VR_PVDDQ_ABC_PH2_VCIN")
	)
	(via
		(at 347.824806 -1.467104)
		(size 0.508)
		(drill 0.254)
		(layers "F.Cu" "B.Cu")
		(net "VR_PVDDQ_ABC_PH2_VCIN")
	)
	(via
		(at 349.303848 -0.245618)
		(size 0.6604)
		(drill 0.3302)
		(layers "F.Cu" "B.Cu")
		(net "VR_PVDDQ_ABC_PH2_VCIN")
	)
	(segment
		(start 348.129606 -0.679704)
		(end 348.129606 -1.086104)
		(width 0.4064)
		(layer "B.Cu")
		(net "VR_PVDDQ_ABC_PH2_VCIN")
	)
	(segment
		(start 349.303848 -0.245618)
		(end 348.869762 -0.679704)
		(width 0.4064)
		(layer "B.Cu")
		(net "VR_PVDDQ_ABC_PH2_VCIN")
	)
	(segment
		(start 347.824806 -1.390904)
		(end 347.824806 -1.467104)
		(width 0.4064)
		(layer "B.Cu")
		(net "VR_PVDDQ_ABC_PH2_VCIN")
	)
	(segment
		(start 348.869762 -0.679704)
		(end 348.129606 -0.679704)
		(width 0.4064)
		(layer "B.Cu")
		(net "VR_PVDDQ_ABC_PH2_VCIN")
	)
	(segment
		(start 348.129606 -1.086104)
		(end 347.824806 -1.390904)
		(width 0.4064)
		(layer "B.Cu")
		(net "VR_PVDDQ_ABC_PH2_VCIN")
	)
	(segment
		(start 340.38286 1.1049)
		(end 341.049864 1.771904)
		(width 0.508)
		(layer "F.Cu")
		(net "VR_PVDDQ_ABC_PH2_SW")
	)
	(segment
		(start 340.38286 -2.02438)
		(end 340.38286 1.1049)
		(width 0.508)
		(layer "F.Cu")
		(net "VR_PVDDQ_ABC_PH2_SW")
	)
	(segment
		(start 341.049864 1.771904)
		(end 341.049864 1.898904)
		(width 0.508)
		(layer "F.Cu")
		(net "VR_PVDDQ_ABC_PH2_SW")
	)
	(segment
		(start 349.901002 2.89179)
		(end 350.259396 3.250184)
		(width 0.254)
		(layer "F.Cu")
		(net "VR_PVDDQ_ABC_PH2_PHASE")
	)
	(segment
		(start 350.259396 3.250184)
		(end 350.540066 3.530854)
		(width 0.508)
		(layer "F.Cu")
		(net "VR_PVDDQ_ABC_PH2_PHASE")
	)
	(segment
		(start 349.262192 2.89179)
		(end 349.901002 2.89179)
		(width 0.254)
		(layer "F.Cu")
		(net "VR_PVDDQ_ABC_PH2_PHASE")
	)
	(segment
		(start 350.540066 3.530854)
		(end 350.890332 3.530854)
		(width 0.508)
		(layer "F.Cu")
		(net "VR_PVDDQ_ABC_PH2_PHASE")
	)
	(segment
		(start 352.487738 3.268472)
		(end 352.487738 2.51079)
		(width 0.508)
		(layer "F.Cu")
		(net "VR_PVDDQ_ABC_PH2_BOOT")
	)
	(segment
		(start 351.779332 3.530854)
		(end 352.225356 3.530854)
		(width 0.508)
		(layer "F.Cu")
		(net "VR_PVDDQ_ABC_PH2_BOOT")
	)
	(segment
		(start 352.225356 3.530854)
		(end 352.487738 3.268472)
		(width 0.508)
		(layer "F.Cu")
		(net "VR_PVDDQ_ABC_PH2_BOOT")
	)
	(segment
		(start 347.9038 -9.906)
		(end 348.2086 -10.2108)
		(width 0.4064)
		(layer "F.Cu")
		(net "VR_PVDDQ_ABC_PH1_VCIN")
	)
	(segment
		(start 347.826076 -8.787638)
		(end 347.826076 -9.523476)
		(width 0.254)
		(layer "F.Cu")
		(net "VR_PVDDQ_ABC_PH1_VCIN")
	)
	(segment
		(start 347.826076 -9.523476)
		(end 347.9038 -9.6012)
		(width 0.254)
		(layer "F.Cu")
		(net "VR_PVDDQ_ABC_PH1_VCIN")
	)
	(segment
		(start 347.9038 -9.6012)
		(end 347.9038 -9.906)
		(width 0.4064)
		(layer "F.Cu")
		(net "VR_PVDDQ_ABC_PH1_VCIN")
	)
	(via
		(at 348.265242 -10.422382)
		(size 0.6604)
		(drill 0.3302)
		(layers "F.Cu" "B.Cu")
		(net "VR_PVDDQ_ABC_PH1_VCIN")
	)
	(via
		(at 347.9038 -9.6012)
		(size 0.508)
		(drill 0.254)
		(layers "F.Cu" "B.Cu")
		(net "VR_PVDDQ_ABC_PH1_VCIN")
	)
	(segment
		(start 348.2086 -9.112504)
		(end 347.9038 -9.417304)
		(width 0.381)
		(layer "B.Cu")
		(net "VR_PVDDQ_ABC_PH1_VCIN")
	)
	(segment
		(start 348.2086 -8.8138)
		(end 348.2086 -9.112504)
		(width 0.381)
		(layer "B.Cu")
		(net "VR_PVDDQ_ABC_PH1_VCIN")
	)
	(segment
		(start 347.9038 -10.06094)
		(end 348.265242 -10.422382)
		(width 0.4064)
		(layer "B.Cu")
		(net "VR_PVDDQ_ABC_PH1_VCIN")
	)
	(segment
		(start 347.9038 -9.6012)
		(end 347.9038 -10.06094)
		(width 0.4064)
		(layer "B.Cu")
		(net "VR_PVDDQ_ABC_PH1_VCIN")
	)
	(segment
		(start 347.9038 -9.417304)
		(end 347.9038 -9.6012)
		(width 0.381)
		(layer "B.Cu")
		(net "VR_PVDDQ_ABC_PH1_VCIN")
	)
	(segment
		(start 337.82 -8.509)
		(end 337.82 -10.3378)
		(width 0.508)
		(layer "F.Cu")
		(net "VR_PVDDQ_ABC_PH1_SW")
	)
	(segment
		(start 338.5058 -7.8232)
		(end 337.82 -8.509)
		(width 0.508)
		(layer "F.Cu")
		(net "VR_PVDDQ_ABC_PH1_SW")
	)
	(segment
		(start 350.025462 -5.056378)
		(end 350.407224 -5.056378)
		(width 0.381)
		(layer "F.Cu")
		(net "VR_PVDDQ_ABC_PH1_PHASE")
	)
	(segment
		(start 349.839534 -5.242306)
		(end 350.025462 -5.056378)
		(width 0.254)
		(layer "F.Cu")
		(net "VR_PVDDQ_ABC_PH1_PHASE")
	)
	(segment
		(start 349.341186 -5.242306)
		(end 349.839534 -5.242306)
		(width 0.254)
		(layer "F.Cu")
		(net "VR_PVDDQ_ABC_PH1_PHASE")
	)
	(segment
		(start 350.407224 -4.167378)
		(end 351.280984 -4.167378)
		(width 0.508)
		(layer "F.Cu")
		(net "VR_PVDDQ_ABC_PH1_BOOT")
	)
	(segment
		(start 351.280984 -4.167378)
		(end 351.410524 -4.296918)
		(width 0.508)
		(layer "F.Cu")
		(net "VR_PVDDQ_ABC_PH1_BOOT")
	)
	(segment
		(start 338.836 -13.1826)
		(end 338.836 -13.97)
		(width 0.2032)
		(layer "F.Cu")
		(net "VR_PVDDQ_ABC_AVSP")
	)
	(segment
		(start 342.2269 -13.966952)
		(end 341.497412 -13.966952)
		(width 0.2032)
		(layer "F.Cu")
		(net "VR_PVDDQ_ABC_AVSP")
	)
	(segment
		(start 339.725 -13.1826)
		(end 338.836 -13.1826)
		(width 0.2032)
		(layer "F.Cu")
		(net "VR_PVDDQ_ABC_AVSP")
	)
	(segment
		(start 340.19998 -13.65758)
		(end 339.725 -13.1826)
		(width 0.2032)
		(layer "F.Cu")
		(net "VR_PVDDQ_ABC_AVSP")
	)
	(segment
		(start 341.18804 -13.65758)
		(end 340.19998 -13.65758)
		(width 0.2032)
		(layer "F.Cu")
		(net "VR_PVDDQ_ABC_AVSP")
	)
	(segment
		(start 341.497412 -13.966952)
		(end 341.18804 -13.65758)
		(width 0.2032)
		(layer "F.Cu")
		(net "VR_PVDDQ_ABC_AVSP")
	)
	(via
		(at 341.18804 -13.65758)
		(size 0.508)
		(drill 0.254)
		(layers "F.Cu" "B.Cu")
		(net "VR_PVDDQ_ABC_AVSP")
	)
	(segment
		(start 349.735648 -20.314412)
		(end 351.223834 -18.826226)
		(width 0.254)
		(layer "F.Cu")
		(net "VR_PVDDQ_ABC_AIINSEN")
	)
	(segment
		(start 349.040958 -16.632428)
		(end 349.877634 -16.632428)
		(width 0.254)
		(layer "F.Cu")
		(net "VR_PVDDQ_ABC_AIINSEN")
	)
	(segment
		(start 347.659198 -16.366998)
		(end 347.1291 -16.366998)
		(width 0.2032)
		(layer "F.Cu")
		(net "VR_PVDDQ_ABC_AIINSEN")
	)
	(segment
		(start 350.69145 -16.64081)
		(end 349.886016 -16.64081)
		(width 0.254)
		(layer "F.Cu")
		(net "VR_PVDDQ_ABC_AIINSEN")
	)
	(segment
		(start 347.8276 -16.5354)
		(end 347.659198 -16.366998)
		(width 0.2032)
		(layer "F.Cu")
		(net "VR_PVDDQ_ABC_AIINSEN")
	)
	(segment
		(start 351.223834 -18.826226)
		(end 351.223834 -17.173194)
		(width 0.254)
		(layer "F.Cu")
		(net "VR_PVDDQ_ABC_AIINSEN")
	)
	(segment
		(start 348.546928 -16.5354)
		(end 347.8276 -16.5354)
		(width 0.254)
		(layer "F.Cu")
		(net "VR_PVDDQ_ABC_AIINSEN")
	)
	(segment
		(start 351.223834 -17.173194)
		(end 350.69145 -16.64081)
		(width 0.254)
		(layer "F.Cu")
		(net "VR_PVDDQ_ABC_AIINSEN")
	)
	(segment
		(start 348.643956 -16.632428)
		(end 348.546928 -16.5354)
		(width 0.254)
		(layer "F.Cu")
		(net "VR_PVDDQ_ABC_AIINSEN")
	)
	(segment
		(start 349.040958 -16.632428)
		(end 348.643956 -16.632428)
		(width 0.254)
		(layer "F.Cu")
		(net "VR_PVDDQ_ABC_AIINSEN")
	)
	(segment
		(start 349.877634 -16.632428)
		(end 349.886016 -16.64081)
		(width 0.254)
		(layer "F.Cu")
		(net "VR_PVDDQ_ABC_AIINSEN")
	)
	(segment
		(start 20.030948 -95.773748)
		(end 20.3708 -96.1136)
		(width 0.2032)
		(layer "F.Cu")
		(net "VR_PVCCIN_CPU1_XADDR2")
	)
	(segment
		(start 20.030948 -95.3516)
		(end 20.030948 -95.773748)
		(width 0.2032)
		(layer "F.Cu")
		(net "VR_PVCCIN_CPU1_XADDR2")
	)
	(segment
		(start 20.3708 -96.1136)
		(end 20.3708 -96.4438)
		(width 0.2032)
		(layer "F.Cu")
		(net "VR_PVCCIN_CPU1_XADDR2")
	)
	(via
		(at 20.3708 -96.4438)
		(size 0.508)
		(drill 0.254)
		(layers "F.Cu" "B.Cu")
		(net "VR_PVCCIN_CPU1_XADDR2")
	)
	(segment
		(start 20.193 -95.5294)
		(end 20.193 -96.266)
		(width 0.4064)
		(layer "B.Cu")
		(net "VR_PVCCIN_CPU1_XADDR2")
	)
	(segment
		(start 20.193 -96.266)
		(end 20.3708 -96.4438)
		(width 0.4064)
		(layer "B.Cu")
		(net "VR_PVCCIN_CPU1_XADDR2")
	)
	(segment
		(start 18.831052 -96.275652)
		(end 18.9992 -96.4438)
		(width 0.2032)
		(layer "F.Cu")
		(net "VR_PVCCIN_CPU1_XADDR1")
	)
	(segment
		(start 18.831052 -95.3516)
		(end 18.831052 -96.275652)
		(width 0.2032)
		(layer "F.Cu")
		(net "VR_PVCCIN_CPU1_XADDR1")
	)
	(via
		(at 18.9992 -96.4438)
		(size 0.508)
		(drill 0.254)
		(layers "F.Cu" "B.Cu")
		(net "VR_PVCCIN_CPU1_XADDR1")
	)
	(segment
		(start 19.05 -96.393)
		(end 18.9992 -96.4438)
		(width 0.4064)
		(layer "B.Cu")
		(net "VR_PVCCIN_CPU1_XADDR1")
	)
	(segment
		(start 19.05 -95.5294)
		(end 19.05 -96.393)
		(width 0.4064)
		(layer "B.Cu")
		(net "VR_PVCCIN_CPU1_XADDR1")
	)
	(segment
		(start 17.3228 -96.2152)
		(end 17.630902 -95.907098)
		(width 0.254)
		(layer "F.Cu")
		(net "VR_PVCCIN_CPU1_VDD")
	)
	(segment
		(start 17.630902 -95.907098)
		(end 17.630902 -95.3516)
		(width 0.2032)
		(layer "F.Cu")
		(net "VR_PVCCIN_CPU1_VDD")
	)
	(via
		(at 16.51 -97.282)
		(size 0.508)
		(drill 0.254)
		(layers "F.Cu" "B.Cu")
		(net "VR_PVCCIN_CPU1_VDD")
	)
	(via
		(at 15.38351 -96.553274)
		(size 0.508)
		(drill 0.254)
		(layers "F.Cu" "B.Cu")
		(net "VR_PVCCIN_CPU1_VD12")
	)
	(segment
		(start 29.869638 -89.8017)
		(end 29.734002 -89.666064)
		(width 0.254)
		(layer "F.Cu")
		(net "VR_PVCCIN_CPU1_PWM5")
	)
	(segment
		(start 14.6812 -95.347536)
		(end 14.6812 -95.5294)
		(width 0.2032)
		(layer "F.Cu")
		(net "VR_PVCCIN_CPU1_PWM5")
	)
	(segment
		(start 31.02991 -89.8017)
		(end 29.869638 -89.8017)
		(width 0.254)
		(layer "F.Cu")
		(net "VR_PVCCIN_CPU1_PWM5")
	)
	(segment
		(start 16.172688 -93.856048)
		(end 14.6812 -95.347536)
		(width 0.2032)
		(layer "F.Cu")
		(net "VR_PVCCIN_CPU1_PWM5")
	)
	(segment
		(start 16.5354 -93.856048)
		(end 16.172688 -93.856048)
		(width 0.2032)
		(layer "F.Cu")
		(net "VR_PVCCIN_CPU1_PWM5")
	)
	(via
		(at 14.6812 -95.5294)
		(size 0.508)
		(drill 0.254)
		(layers "F.Cu" "B.Cu")
		(net "VR_PVCCIN_CPU1_PWM5")
	)
	(via
		(at 29.734002 -89.666064)
		(size 0.508)
		(drill 0.254)
		(layers "F.Cu" "B.Cu")
		(net "VR_PVCCIN_CPU1_PWM5")
	)
	(segment
		(start 15.5575 -94.6531)
		(end 14.6812 -95.5294)
		(width 0.254)
		(layer "In2.Cu")
		(net "VR_PVCCIN_CPU1_PWM5")
	)
	(segment
		(start 29.348176 -94.606364)
		(end 29.06522 -94.88932)
		(width 0.254)
		(layer "In2.Cu")
		(net "VR_PVCCIN_CPU1_PWM5")
	)
	(segment
		(start 29.06522 -94.88932)
		(end 26.77922 -94.88932)
		(width 0.254)
		(layer "In2.Cu")
		(net "VR_PVCCIN_CPU1_PWM5")
	)
	(segment
		(start 25.09012 -94.6531)
		(end 15.5575 -94.6531)
		(width 0.254)
		(layer "In2.Cu")
		(net "VR_PVCCIN_CPU1_PWM5")
	)
	(segment
		(start 29.734002 -89.666064)
		(end 29.348176 -90.05189)
		(width 0.254)
		(layer "In2.Cu")
		(net "VR_PVCCIN_CPU1_PWM5")
	)
	(segment
		(start 26.77922 -94.88932)
		(end 26.44902 -95.21952)
		(width 0.254)
		(layer "In2.Cu")
		(net "VR_PVCCIN_CPU1_PWM5")
	)
	(segment
		(start 26.44902 -95.21952)
		(end 25.65654 -95.21952)
		(width 0.254)
		(layer "In2.Cu")
		(net "VR_PVCCIN_CPU1_PWM5")
	)
	(segment
		(start 25.65654 -95.21952)
		(end 25.09012 -94.6531)
		(width 0.254)
		(layer "In2.Cu")
		(net "VR_PVCCIN_CPU1_PWM5")
	)
	(segment
		(start 29.348176 -90.05189)
		(end 29.348176 -94.606364)
		(width 0.254)
		(layer "In2.Cu")
		(net "VR_PVCCIN_CPU1_PWM5")
	)
	(segment
		(start 29.869638 -81.6737)
		(end 29.734002 -81.538064)
		(width 0.254)
		(layer "F.Cu")
		(net "VR_PVCCIN_CPU1_PWM4")
	)
	(segment
		(start 16.5354 -93.455998)
		(end 15.9512 -93.455998)
		(width 0.2032)
		(layer "F.Cu")
		(net "VR_PVCCIN_CPU1_PWM4")
	)
	(segment
		(start 15.748 -93.659198)
		(end 15.748 -93.657674)
		(width 0.2032)
		(layer "F.Cu")
		(net "VR_PVCCIN_CPU1_PWM4")
	)
	(segment
		(start 31.02991 -81.6737)
		(end 29.869638 -81.6737)
		(width 0.254)
		(layer "F.Cu")
		(net "VR_PVCCIN_CPU1_PWM4")
	)
	(segment
		(start 15.9512 -93.455998)
		(end 15.748 -93.659198)
		(width 0.2032)
		(layer "F.Cu")
		(net "VR_PVCCIN_CPU1_PWM4")
	)
	(segment
		(start 15.748 -93.657674)
		(end 15.726156 -93.657674)
		(width 0.2032)
		(layer "F.Cu")
		(net "VR_PVCCIN_CPU1_PWM4")
	)
	(via
		(at 15.726156 -93.657674)
		(size 0.508)
		(drill 0.254)
		(layers "F.Cu" "B.Cu")
		(net "VR_PVCCIN_CPU1_PWM4")
	)
	(via
		(at 29.734002 -81.538064)
		(size 0.508)
		(drill 0.254)
		(layers "F.Cu" "B.Cu")
		(net "VR_PVCCIN_CPU1_PWM4")
	)
	(segment
		(start 28.09494 -88.3412)
		(end 28.09494 -92.26296)
		(width 0.254)
		(layer "In2.Cu")
		(net "VR_PVCCIN_CPU1_PWM4")
	)
	(segment
		(start 29.734002 -82.047588)
		(end 29.295598 -82.485992)
		(width 0.254)
		(layer "In2.Cu")
		(net "VR_PVCCIN_CPU1_PWM4")
	)
	(segment
		(start 28.66136 -86.39302)
		(end 28.66136 -87.77478)
		(width 0.254)
		(layer "In2.Cu")
		(net "VR_PVCCIN_CPU1_PWM4")
	)
	(segment
		(start 28.09494 -92.26296)
		(end 27.474164 -92.883736)
		(width 0.254)
		(layer "In2.Cu")
		(net "VR_PVCCIN_CPU1_PWM4")
	)
	(segment
		(start 27.474164 -92.883736)
		(end 23.328376 -92.883736)
		(width 0.254)
		(layer "In2.Cu")
		(net "VR_PVCCIN_CPU1_PWM4")
	)
	(segment
		(start 22.87778 -92.43314)
		(end 17.4498 -92.43314)
		(width 0.254)
		(layer "In2.Cu")
		(net "VR_PVCCIN_CPU1_PWM4")
	)
	(segment
		(start 29.734002 -81.538064)
		(end 29.734002 -82.047588)
		(width 0.254)
		(layer "In2.Cu")
		(net "VR_PVCCIN_CPU1_PWM4")
	)
	(segment
		(start 16.225266 -93.657674)
		(end 15.726156 -93.657674)
		(width 0.254)
		(layer "In2.Cu")
		(net "VR_PVCCIN_CPU1_PWM4")
	)
	(segment
		(start 23.328376 -92.883736)
		(end 22.87778 -92.43314)
		(width 0.254)
		(layer "In2.Cu")
		(net "VR_PVCCIN_CPU1_PWM4")
	)
	(segment
		(start 17.4498 -92.43314)
		(end 16.225266 -93.657674)
		(width 0.254)
		(layer "In2.Cu")
		(net "VR_PVCCIN_CPU1_PWM4")
	)
	(segment
		(start 29.295598 -82.485992)
		(end 29.295598 -85.758782)
		(width 0.254)
		(layer "In2.Cu")
		(net "VR_PVCCIN_CPU1_PWM4")
	)
	(segment
		(start 28.66136 -87.77478)
		(end 28.09494 -88.3412)
		(width 0.254)
		(layer "In2.Cu")
		(net "VR_PVCCIN_CPU1_PWM4")
	)
	(segment
		(start 29.295598 -85.758782)
		(end 28.66136 -86.39302)
		(width 0.254)
		(layer "In2.Cu")
		(net "VR_PVCCIN_CPU1_PWM4")
	)
	(segment
		(start 14.2748 -94.4118)
		(end 14.097 -94.4118)
		(width 0.2032)
		(layer "F.Cu")
		(net "VR_PVCCIN_CPU1_PWM3")
	)
	(segment
		(start 29.869638 -73.5457)
		(end 29.734002 -73.410064)
		(width 0.254)
		(layer "F.Cu")
		(net "VR_PVCCIN_CPU1_PWM3")
	)
	(segment
		(start 31.02991 -73.5457)
		(end 29.869638 -73.5457)
		(width 0.254)
		(layer "F.Cu")
		(net "VR_PVCCIN_CPU1_PWM3")
	)
	(segment
		(start 16.5354 -93.055948)
		(end 15.630652 -93.055948)
		(width 0.2032)
		(layer "F.Cu")
		(net "VR_PVCCIN_CPU1_PWM3")
	)
	(segment
		(start 15.630652 -93.055948)
		(end 14.2748 -94.4118)
		(width 0.2032)
		(layer "F.Cu")
		(net "VR_PVCCIN_CPU1_PWM3")
	)
	(via
		(at 14.097 -94.4118)
		(size 0.508)
		(drill 0.254)
		(layers "F.Cu" "B.Cu")
		(net "VR_PVCCIN_CPU1_PWM3")
	)
	(via
		(at 27.813 -93.98)
		(size 0.508)
		(drill 0.254)
		(layers "F.Cu" "B.Cu")
		(net "VR_PVCCIN_CPU1_PWM3")
	)
	(via
		(at 29.734002 -73.410064)
		(size 0.508)
		(drill 0.254)
		(layers "F.Cu" "B.Cu")
		(net "VR_PVCCIN_CPU1_PWM3")
	)
	(segment
		(start 15.619476 -93.016324)
		(end 14.224 -94.4118)
		(width 0.254)
		(layer "In4.Cu")
		(net "VR_PVCCIN_CPU1_PWM3")
	)
	(segment
		(start 26.27884 -95.51416)
		(end 23.51278 -95.51416)
		(width 0.254)
		(layer "In4.Cu")
		(net "VR_PVCCIN_CPU1_PWM3")
	)
	(segment
		(start 21.014944 -93.016324)
		(end 15.619476 -93.016324)
		(width 0.254)
		(layer "In4.Cu")
		(net "VR_PVCCIN_CPU1_PWM3")
	)
	(segment
		(start 23.51278 -95.51416)
		(end 21.014944 -93.016324)
		(width 0.254)
		(layer "In4.Cu")
		(net "VR_PVCCIN_CPU1_PWM3")
	)
	(segment
		(start 14.224 -94.4118)
		(end 14.097 -94.4118)
		(width 0.254)
		(layer "In4.Cu")
		(net "VR_PVCCIN_CPU1_PWM3")
	)
	(segment
		(start 27.813 -93.98)
		(end 26.27884 -95.51416)
		(width 0.254)
		(layer "In4.Cu")
		(net "VR_PVCCIN_CPU1_PWM3")
	)
	(segment
		(start 27.5082 -90.551)
		(end 27.5082 -89.16416)
		(width 0.254)
		(layer "In9.Cu")
		(net "VR_PVCCIN_CPU1_PWM3")
	)
	(segment
		(start 28.67152 -86.45652)
		(end 28.1686 -85.9536)
		(width 0.254)
		(layer "In9.Cu")
		(net "VR_PVCCIN_CPU1_PWM3")
	)
	(segment
		(start 28.702 -83.566)
		(end 28.702 -78.52156)
		(width 0.254)
		(layer "In9.Cu")
		(net "VR_PVCCIN_CPU1_PWM3")
	)
	(segment
		(start 27.5082 -89.16416)
		(end 28.67152 -88.00084)
		(width 0.254)
		(layer "In9.Cu")
		(net "VR_PVCCIN_CPU1_PWM3")
	)
	(segment
		(start 28.1432 -77.96276)
		(end 28.1432 -74.35596)
		(width 0.254)
		(layer "In9.Cu")
		(net "VR_PVCCIN_CPU1_PWM3")
	)
	(segment
		(start 29.083 -73.41616)
		(end 29.727906 -73.41616)
		(width 0.254)
		(layer "In9.Cu")
		(net "VR_PVCCIN_CPU1_PWM3")
	)
	(segment
		(start 28.702 -78.52156)
		(end 28.1432 -77.96276)
		(width 0.254)
		(layer "In9.Cu")
		(net "VR_PVCCIN_CPU1_PWM3")
	)
	(segment
		(start 29.727906 -73.41616)
		(end 29.734002 -73.410064)
		(width 0.254)
		(layer "In9.Cu")
		(net "VR_PVCCIN_CPU1_PWM3")
	)
	(segment
		(start 28.1686 -84.0994)
		(end 28.702 -83.566)
		(width 0.254)
		(layer "In9.Cu")
		(net "VR_PVCCIN_CPU1_PWM3")
	)
	(segment
		(start 28.67152 -88.00084)
		(end 28.67152 -86.45652)
		(width 0.254)
		(layer "In9.Cu")
		(net "VR_PVCCIN_CPU1_PWM3")
	)
	(segment
		(start 28.1686 -85.9536)
		(end 28.1686 -84.0994)
		(width 0.254)
		(layer "In9.Cu")
		(net "VR_PVCCIN_CPU1_PWM3")
	)
	(segment
		(start 28.1432 -74.35596)
		(end 29.083 -73.41616)
		(width 0.254)
		(layer "In9.Cu")
		(net "VR_PVCCIN_CPU1_PWM3")
	)
	(segment
		(start 27.813 -93.98)
		(end 27.813 -90.8558)
		(width 0.254)
		(layer "In9.Cu")
		(net "VR_PVCCIN_CPU1_PWM3")
	)
	(segment
		(start 27.813 -90.8558)
		(end 27.5082 -90.551)
		(width 0.254)
		(layer "In9.Cu")
		(net "VR_PVCCIN_CPU1_PWM3")
	)
	(segment
		(start 29.869638 -65.4177)
		(end 29.734002 -65.282064)
		(width 0.254)
		(layer "F.Cu")
		(net "VR_PVCCIN_CPU1_PWM2")
	)
	(segment
		(start 16.5354 -92.655898)
		(end 15.344648 -92.655898)
		(width 0.2032)
		(layer "F.Cu")
		(net "VR_PVCCIN_CPU1_PWM2")
	)
	(segment
		(start 15.138146 -92.8624)
		(end 14.88186 -92.8624)
		(width 0.254)
		(layer "F.Cu")
		(net "VR_PVCCIN_CPU1_PWM2")
	)
	(segment
		(start 31.02991 -65.4177)
		(end 29.869638 -65.4177)
		(width 0.254)
		(layer "F.Cu")
		(net "VR_PVCCIN_CPU1_PWM2")
	)
	(segment
		(start 15.344648 -92.655898)
		(end 15.138146 -92.8624)
		(width 0.2032)
		(layer "F.Cu")
		(net "VR_PVCCIN_CPU1_PWM2")
	)
	(segment
		(start 14.88186 -92.8624)
		(end 14.57833 -93.16593)
		(width 0.254)
		(layer "F.Cu")
		(net "VR_PVCCIN_CPU1_PWM2")
	)
	(via
		(at 14.57833 -93.16593)
		(size 0.508)
		(drill 0.254)
		(layers "F.Cu" "B.Cu")
		(net "VR_PVCCIN_CPU1_PWM2")
	)
	(via
		(at 29.734002 -65.282064)
		(size 0.508)
		(drill 0.254)
		(layers "F.Cu" "B.Cu")
		(net "VR_PVCCIN_CPU1_PWM2")
	)
	(segment
		(start 27.945588 -85.683852)
		(end 27.945588 -85.998558)
		(width 0.254)
		(layer "In2.Cu")
		(net "VR_PVCCIN_CPU1_PWM2")
	)
	(segment
		(start 23.343362 -90.37066)
		(end 23.343108 -90.370914)
		(width 0.254)
		(layer "In2.Cu")
		(net "VR_PVCCIN_CPU1_PWM2")
	)
	(segment
		(start 28.0035 -74.2315)
		(end 28.0035 -77.96022)
		(width 0.254)
		(layer "In2.Cu")
		(net "VR_PVCCIN_CPU1_PWM2")
	)
	(segment
		(start 23.343108 -90.370914)
		(end 22.712172 -90.370914)
		(width 0.254)
		(layer "In2.Cu")
		(net "VR_PVCCIN_CPU1_PWM2")
	)
	(segment
		(start 28.680918 -73.554082)
		(end 28.0035 -74.2315)
		(width 0.254)
		(layer "In2.Cu")
		(net "VR_PVCCIN_CPU1_PWM2")
	)
	(segment
		(start 28.07081 -82.633058)
		(end 28.07081 -85.55863)
		(width 0.254)
		(layer "In2.Cu")
		(net "VR_PVCCIN_CPU1_PWM2")
	)
	(segment
		(start 22.712172 -90.370914)
		(end 22.711918 -90.37066)
		(width 0.254)
		(layer "In2.Cu")
		(net "VR_PVCCIN_CPU1_PWM2")
	)
	(segment
		(start 14.5288 -93.16593)
		(end 14.57833 -93.16593)
		(width 0.254)
		(layer "In2.Cu")
		(net "VR_PVCCIN_CPU1_PWM2")
	)
	(segment
		(start 26.34742 -90.81516)
		(end 24.05888 -90.81516)
		(width 0.254)
		(layer "In2.Cu")
		(net "VR_PVCCIN_CPU1_PWM2")
	)
	(segment
		(start 29.277056 -68.780152)
		(end 28.680918 -69.37629)
		(width 0.254)
		(layer "In2.Cu")
		(net "VR_PVCCIN_CPU1_PWM2")
	)
	(segment
		(start 28.07081 -85.55863)
		(end 27.945588 -85.683852)
		(width 0.254)
		(layer "In2.Cu")
		(net "VR_PVCCIN_CPU1_PWM2")
	)
	(segment
		(start 23.61438 -90.37066)
		(end 23.343362 -90.37066)
		(width 0.254)
		(layer "In2.Cu")
		(net "VR_PVCCIN_CPU1_PWM2")
	)
	(segment
		(start 26.91892 -90.24366)
		(end 26.34742 -90.81516)
		(width 0.254)
		(layer "In2.Cu")
		(net "VR_PVCCIN_CPU1_PWM2")
	)
	(segment
		(start 24.05888 -90.81516)
		(end 23.61438 -90.37066)
		(width 0.254)
		(layer "In2.Cu")
		(net "VR_PVCCIN_CPU1_PWM2")
	)
	(segment
		(start 14.67866 -93.0656)
		(end 14.5796 -93.0656)
		(width 0.254)
		(layer "In2.Cu")
		(net "VR_PVCCIN_CPU1_PWM2")
	)
	(segment
		(start 28.59151 -82.112358)
		(end 28.07081 -82.633058)
		(width 0.254)
		(layer "In2.Cu")
		(net "VR_PVCCIN_CPU1_PWM2")
	)
	(segment
		(start 29.734002 -65.282064)
		(end 29.277056 -65.73901)
		(width 0.254)
		(layer "In2.Cu")
		(net "VR_PVCCIN_CPU1_PWM2")
	)
	(segment
		(start 28.59151 -78.54823)
		(end 28.59151 -82.112358)
		(width 0.254)
		(layer "In2.Cu")
		(net "VR_PVCCIN_CPU1_PWM2")
	)
	(segment
		(start 27.945588 -85.998558)
		(end 26.91892 -87.025226)
		(width 0.254)
		(layer "In2.Cu")
		(net "VR_PVCCIN_CPU1_PWM2")
	)
	(segment
		(start 14.5796 -93.0656)
		(end 14.5288 -93.1164)
		(width 0.254)
		(layer "In2.Cu")
		(net "VR_PVCCIN_CPU1_PWM2")
	)
	(segment
		(start 28.680918 -69.37629)
		(end 28.680918 -73.554082)
		(width 0.254)
		(layer "In2.Cu")
		(net "VR_PVCCIN_CPU1_PWM2")
	)
	(segment
		(start 16.58874 -91.36634)
		(end 16.58874 -92.233242)
		(width 0.254)
		(layer "In2.Cu")
		(net "VR_PVCCIN_CPU1_PWM2")
	)
	(segment
		(start 26.91892 -87.025226)
		(end 26.91892 -90.24366)
		(width 0.254)
		(layer "In2.Cu")
		(net "VR_PVCCIN_CPU1_PWM2")
	)
	(segment
		(start 14.5288 -93.1164)
		(end 14.5288 -93.16593)
		(width 0.254)
		(layer "In2.Cu")
		(net "VR_PVCCIN_CPU1_PWM2")
	)
	(segment
		(start 29.277056 -65.73901)
		(end 29.277056 -68.780152)
		(width 0.254)
		(layer "In2.Cu")
		(net "VR_PVCCIN_CPU1_PWM2")
	)
	(segment
		(start 22.711918 -90.37066)
		(end 17.58442 -90.37066)
		(width 0.254)
		(layer "In2.Cu")
		(net "VR_PVCCIN_CPU1_PWM2")
	)
	(segment
		(start 28.0035 -77.96022)
		(end 28.59151 -78.54823)
		(width 0.254)
		(layer "In2.Cu")
		(net "VR_PVCCIN_CPU1_PWM2")
	)
	(segment
		(start 17.58442 -90.37066)
		(end 16.58874 -91.36634)
		(width 0.254)
		(layer "In2.Cu")
		(net "VR_PVCCIN_CPU1_PWM2")
	)
	(segment
		(start 14.886178 -92.858082)
		(end 14.67866 -93.0656)
		(width 0.254)
		(layer "In2.Cu")
		(net "VR_PVCCIN_CPU1_PWM2")
	)
	(segment
		(start 16.58874 -92.233242)
		(end 15.9639 -92.858082)
		(width 0.254)
		(layer "In2.Cu")
		(net "VR_PVCCIN_CPU1_PWM2")
	)
	(segment
		(start 15.9639 -92.858082)
		(end 14.886178 -92.858082)
		(width 0.254)
		(layer "In2.Cu")
		(net "VR_PVCCIN_CPU1_PWM2")
	)
	(segment
		(start 29.73832 -57.23382)
		(end 29.75864 -57.25414)
		(width 0.254)
		(layer "F.Cu")
		(net "VR_PVCCIN_CPU1_PWM1")
	)
	(segment
		(start 29.75864 -57.25414)
		(end 29.834078 -57.25414)
		(width 0.254)
		(layer "F.Cu")
		(net "VR_PVCCIN_CPU1_PWM1")
	)
	(segment
		(start 15.707614 -92.256102)
		(end 16.5354 -92.256102)
		(width 0.2032)
		(layer "F.Cu")
		(net "VR_PVCCIN_CPU1_PWM1")
	)
	(segment
		(start 15.477236 -92.025978)
		(end 15.477236 -92.025724)
		(width 0.2032)
		(layer "F.Cu")
		(net "VR_PVCCIN_CPU1_PWM1")
	)
	(segment
		(start 29.869638 -57.2897)
		(end 31.02991 -57.2897)
		(width 0.254)
		(layer "F.Cu")
		(net "VR_PVCCIN_CPU1_PWM1")
	)
	(segment
		(start 15.477236 -92.025724)
		(end 15.707614 -92.256102)
		(width 0.2032)
		(layer "F.Cu")
		(net "VR_PVCCIN_CPU1_PWM1")
	)
	(segment
		(start 29.834078 -57.25414)
		(end 29.869638 -57.2897)
		(width 0.254)
		(layer "F.Cu")
		(net "VR_PVCCIN_CPU1_PWM1")
	)
	(via
		(at 29.73832 -57.23382)
		(size 0.508)
		(drill 0.254)
		(layers "F.Cu" "B.Cu")
		(net "VR_PVCCIN_CPU1_PWM1")
	)
	(via
		(at 15.477236 -92.025978)
		(size 0.508)
		(drill 0.254)
		(layers "F.Cu" "B.Cu")
		(net "VR_PVCCIN_CPU1_PWM1")
	)
	(segment
		(start 24.01062 -87.65286)
		(end 24.01062 -88.62568)
		(width 0.254)
		(layer "In2.Cu")
		(net "VR_PVCCIN_CPU1_PWM1")
	)
	(segment
		(start 28.82138 -57.23382)
		(end 28.139898 -57.915302)
		(width 0.254)
		(layer "In2.Cu")
		(net "VR_PVCCIN_CPU1_PWM1")
	)
	(segment
		(start 28.139898 -57.915302)
		(end 28.139898 -68.827142)
		(width 0.254)
		(layer "In2.Cu")
		(net "VR_PVCCIN_CPU1_PWM1")
	)
	(segment
		(start 17.205706 -89.659714)
		(end 15.477236 -91.388184)
		(width 0.254)
		(layer "In2.Cu")
		(net "VR_PVCCIN_CPU1_PWM1")
	)
	(segment
		(start 24.26462 -87.39886)
		(end 24.01062 -87.65286)
		(width 0.254)
		(layer "In2.Cu")
		(net "VR_PVCCIN_CPU1_PWM1")
	)
	(segment
		(start 23.02764 -89.60866)
		(end 17.268698 -89.60866)
		(width 0.254)
		(layer "In2.Cu")
		(net "VR_PVCCIN_CPU1_PWM1")
	)
	(segment
		(start 17.217644 -89.659714)
		(end 17.205706 -89.659714)
		(width 0.254)
		(layer "In2.Cu")
		(net "VR_PVCCIN_CPU1_PWM1")
	)
	(segment
		(start 29.73832 -57.23382)
		(end 28.82138 -57.23382)
		(width 0.254)
		(layer "In2.Cu")
		(net "VR_PVCCIN_CPU1_PWM1")
	)
	(segment
		(start 15.477236 -91.388184)
		(end 15.477236 -92.025978)
		(width 0.254)
		(layer "In2.Cu")
		(net "VR_PVCCIN_CPU1_PWM1")
	)
	(segment
		(start 24.01062 -88.62568)
		(end 23.02764 -89.60866)
		(width 0.254)
		(layer "In2.Cu")
		(net "VR_PVCCIN_CPU1_PWM1")
	)
	(segment
		(start 25.30094 -87.39886)
		(end 24.26462 -87.39886)
		(width 0.254)
		(layer "In2.Cu")
		(net "VR_PVCCIN_CPU1_PWM1")
	)
	(segment
		(start 27.183588 -69.783452)
		(end 27.183588 -85.516212)
		(width 0.254)
		(layer "In2.Cu")
		(net "VR_PVCCIN_CPU1_PWM1")
	)
	(segment
		(start 27.183588 -85.516212)
		(end 25.30094 -87.39886)
		(width 0.254)
		(layer "In2.Cu")
		(net "VR_PVCCIN_CPU1_PWM1")
	)
	(segment
		(start 28.139898 -68.827142)
		(end 27.183588 -69.783452)
		(width 0.254)
		(layer "In2.Cu")
		(net "VR_PVCCIN_CPU1_PWM1")
	)
	(segment
		(start 17.268698 -89.60866)
		(end 17.217644 -89.659714)
		(width 0.254)
		(layer "In2.Cu")
		(net "VR_PVCCIN_CPU1_PWM1")
	)
	(segment
		(start 39.37 -77.978)
		(end 39.1414 -77.7494)
		(width 0.508)
		(layer "F.Cu")
		(net "VR_PVCCIN_CPU1_PHASE4")
	)
	(segment
		(start 39.37 -79.248)
		(end 39.37 -77.978)
		(width 0.508)
		(layer "F.Cu")
		(net "VR_PVCCIN_CPU1_PHASE4")
	)
	(segment
		(start 39.8018 -69.9389)
		(end 39.8018 -69.3166)
		(width 0.508)
		(layer "F.Cu")
		(net "VR_PVCCIN_CPU1_PHASE3")
	)
	(segment
		(start 39.751 -71.374)
		(end 39.751 -69.9897)
		(width 0.508)
		(layer "F.Cu")
		(net "VR_PVCCIN_CPU1_PHASE3")
	)
	(segment
		(start 39.751 -69.9897)
		(end 39.8018 -69.9389)
		(width 0.508)
		(layer "F.Cu")
		(net "VR_PVCCIN_CPU1_PHASE3")
	)
	(segment
		(start 39.4208 -61.595508)
		(end 38.91534 -61.090048)
		(width 0.508)
		(layer "F.Cu")
		(net "VR_PVCCIN_CPU1_PHASE2")
	)
	(segment
		(start 39.4208 -63.0428)
		(end 39.4208 -61.595508)
		(width 0.508)
		(layer "F.Cu")
		(net "VR_PVCCIN_CPU1_PHASE2")
	)
	(segment
		(start 39.88181 -53.69941)
		(end 39.0906 -52.9082)
		(width 0.508)
		(layer "F.Cu")
		(net "VR_PVCCIN_CPU1_PHASE1")
	)
	(segment
		(start 39.88181 -55.11419)
		(end 39.88181 -53.69941)
		(width 0.508)
		(layer "F.Cu")
		(net "VR_PVCCIN_CPU1_PHASE1")
	)
	(segment
		(start 32.289496 -77.351382)
		(end 32.289496 -78.009496)
		(width 0.508)
		(layer "F.Cu")
		(net "VR_PVCCIN_CPU1_PH4_VCIN")
	)
	(segment
		(start 32.289496 -78.009496)
		(end 32.385 -78.105)
		(width 0.508)
		(layer "F.Cu")
		(net "VR_PVCCIN_CPU1_PH4_VCIN")
	)
	(segment
		(start 32.54502 -78.47584)
		(end 32.385 -78.31582)
		(width 0.254)
		(layer "F.Cu")
		(net "VR_PVCCIN_CPU1_PH4_VCIN")
	)
	(segment
		(start 32.54502 -79.028544)
		(end 32.54502 -78.47584)
		(width 0.254)
		(layer "F.Cu")
		(net "VR_PVCCIN_CPU1_PH4_VCIN")
	)
	(segment
		(start 32.385 -78.31582)
		(end 32.385 -78.105)
		(width 0.254)
		(layer "F.Cu")
		(net "VR_PVCCIN_CPU1_PH4_VCIN")
	)
	(via
		(at 31.5976 -77.49032)
		(size 0.6604)
		(drill 0.3302)
		(layers "F.Cu" "B.Cu")
		(net "VR_PVCCIN_CPU1_PH4_VCIN")
	)
	(via
		(at 32.385 -78.105)
		(size 0.508)
		(drill 0.254)
		(layers "F.Cu" "B.Cu")
		(net "VR_PVCCIN_CPU1_PH4_VCIN")
	)
	(segment
		(start 31.6865 -77.851)
		(end 31.6865 -77.57922)
		(width 0.254)
		(layer "B.Cu")
		(net "VR_PVCCIN_CPU1_PH4_VCIN")
	)
	(segment
		(start 31.6865 -77.57922)
		(end 31.5976 -77.49032)
		(width 0.254)
		(layer "B.Cu")
		(net "VR_PVCCIN_CPU1_PH4_VCIN")
	)
	(segment
		(start 32.385 -78.105)
		(end 31.9405 -78.105)
		(width 0.254)
		(layer "B.Cu")
		(net "VR_PVCCIN_CPU1_PH4_VCIN")
	)
	(segment
		(start 32.2834 -78.9432)
		(end 32.2834 -78.2066)
		(width 0.4064)
		(layer "B.Cu")
		(net "VR_PVCCIN_CPU1_PH4_VCIN")
	)
	(segment
		(start 31.9405 -78.105)
		(end 31.6865 -77.851)
		(width 0.254)
		(layer "B.Cu")
		(net "VR_PVCCIN_CPU1_PH4_VCIN")
	)
	(segment
		(start 32.2834 -78.2066)
		(end 32.385 -78.105)
		(width 0.4064)
		(layer "B.Cu")
		(net "VR_PVCCIN_CPU1_PH4_VCIN")
	)
	(segment
		(start 31.02991 -82.573876)
		(end 30.511496 -82.573876)
		(width 0.254)
		(layer "F.Cu")
		(net "VR_PVCCIN_CPU1_PH4_PHASE")
	)
	(segment
		(start 30.282642 -82.80273)
		(end 29.951172 -83.1342)
		(width 0.508)
		(layer "F.Cu")
		(net "VR_PVCCIN_CPU1_PH4_PHASE")
	)
	(segment
		(start 29.951172 -83.1342)
		(end 29.718 -83.1342)
		(width 0.508)
		(layer "F.Cu")
		(net "VR_PVCCIN_CPU1_PH4_PHASE")
	)
	(segment
		(start 30.511496 -82.573876)
		(end 30.282642 -82.80273)
		(width 0.254)
		(layer "F.Cu")
		(net "VR_PVCCIN_CPU1_PH4_PHASE")
	)
	(segment
		(start 28.829 -83.1342)
		(end 27.86126 -83.1342)
		(width 0.508)
		(layer "F.Cu")
		(net "VR_PVCCIN_CPU1_PH4_BOOT")
	)
	(segment
		(start 27.74442 -83.01736)
		(end 27.4828 -82.75574)
		(width 0.508)
		(layer "F.Cu")
		(net "VR_PVCCIN_CPU1_PH4_BOOT")
	)
	(segment
		(start 27.86126 -83.1342)
		(end 27.74442 -83.01736)
		(width 0.508)
		(layer "F.Cu")
		(net "VR_PVCCIN_CPU1_PH4_BOOT")
	)
	(segment
		(start 27.4828 -82.75574)
		(end 27.4828 -81.915)
		(width 0.508)
		(layer "F.Cu")
		(net "VR_PVCCIN_CPU1_PH4_BOOT")
	)
	(via
		(at 27.74442 -83.01736)
		(size 0.762)
		(drill 0.381)
		(layers "F.Cu" "B.Cu")
		(net "VR_PVCCIN_CPU1_PH4_BOOT")
	)
	(segment
		(start 32.416496 -69.223382)
		(end 32.416496 -69.945504)
		(width 0.508)
		(layer "F.Cu")
		(net "VR_PVCCIN_CPU1_PH3_VCIN")
	)
	(segment
		(start 32.54502 -70.34403)
		(end 32.385 -70.18401)
		(width 0.254)
		(layer "F.Cu")
		(net "VR_PVCCIN_CPU1_PH3_VCIN")
	)
	(segment
		(start 32.54502 -70.900544)
		(end 32.54502 -70.34403)
		(width 0.254)
		(layer "F.Cu")
		(net "VR_PVCCIN_CPU1_PH3_VCIN")
	)
	(segment
		(start 32.416496 -69.945504)
		(end 32.385 -69.977)
		(width 0.508)
		(layer "F.Cu")
		(net "VR_PVCCIN_CPU1_PH3_VCIN")
	)
	(segment
		(start 32.385 -70.18401)
		(end 32.385 -69.977)
		(width 0.254)
		(layer "F.Cu")
		(net "VR_PVCCIN_CPU1_PH3_VCIN")
	)
	(via
		(at 32.385 -69.977)
		(size 0.508)
		(drill 0.254)
		(layers "F.Cu" "B.Cu")
		(net "VR_PVCCIN_CPU1_PH3_VCIN")
	)
	(via
		(at 31.86684 -69.36232)
		(size 0.6604)
		(drill 0.3302)
		(layers "F.Cu" "B.Cu")
		(net "VR_PVCCIN_CPU1_PH3_VCIN")
	)
	(segment
		(start 32.3088 -70.0532)
		(end 32.385 -69.977)
		(width 0.4064)
		(layer "B.Cu")
		(net "VR_PVCCIN_CPU1_PH3_VCIN")
	)
	(segment
		(start 31.86684 -69.723)
		(end 31.86684 -69.36232)
		(width 0.254)
		(layer "B.Cu")
		(net "VR_PVCCIN_CPU1_PH3_VCIN")
	)
	(segment
		(start 32.3088 -70.7898)
		(end 32.3088 -70.0532)
		(width 0.4064)
		(layer "B.Cu")
		(net "VR_PVCCIN_CPU1_PH3_VCIN")
	)
	(segment
		(start 32.385 -69.977)
		(end 32.12084 -69.977)
		(width 0.254)
		(layer "B.Cu")
		(net "VR_PVCCIN_CPU1_PH3_VCIN")
	)
	(segment
		(start 32.12084 -69.977)
		(end 31.86684 -69.723)
		(width 0.254)
		(layer "B.Cu")
		(net "VR_PVCCIN_CPU1_PH3_VCIN")
	)
	(segment
		(start 29.057346 -75.304142)
		(end 29.576268 -75.304142)
		(width 0.508)
		(layer "F.Cu")
		(net "VR_PVCCIN_CPU1_PH3_PHASE")
	)
	(segment
		(start 30.642814 -74.445876)
		(end 30.297628 -74.791062)
		(width 0.254)
		(layer "F.Cu")
		(net "VR_PVCCIN_CPU1_PH3_PHASE")
	)
	(segment
		(start 30.297628 -74.791062)
		(end 29.784548 -75.304142)
		(width 0.508)
		(layer "F.Cu")
		(net "VR_PVCCIN_CPU1_PH3_PHASE")
	)
	(segment
		(start 28.777946 -75.024742)
		(end 29.057346 -75.304142)
		(width 0.508)
		(layer "F.Cu")
		(net "VR_PVCCIN_CPU1_PH3_PHASE")
	)
	(segment
		(start 31.02991 -74.445876)
		(end 30.642814 -74.445876)
		(width 0.254)
		(layer "F.Cu")
		(net "VR_PVCCIN_CPU1_PH3_PHASE")
	)
	(segment
		(start 29.784548 -75.304142)
		(end 29.576268 -75.304142)
		(width 0.508)
		(layer "F.Cu")
		(net "VR_PVCCIN_CPU1_PH3_PHASE")
	)
	(via
		(at 29.576268 -75.304142)
		(size 0.508)
		(drill 0.254)
		(layers "F.Cu" "B.Cu")
		(net "VR_PVCCIN_CPU1_PH3_PHASE")
	)
	(segment
		(start 27.888946 -75.024742)
		(end 27.888946 -74.20991)
		(width 0.508)
		(layer "F.Cu")
		(net "VR_PVCCIN_CPU1_PH3_BOOT")
	)
	(segment
		(start 27.423364 -72.609964)
		(end 27.423364 -73.744328)
		(width 0.508)
		(layer "F.Cu")
		(net "VR_PVCCIN_CPU1_PH3_BOOT")
	)
	(segment
		(start 27.888946 -74.20991)
		(end 27.423364 -73.744328)
		(width 0.508)
		(layer "F.Cu")
		(net "VR_PVCCIN_CPU1_PH3_BOOT")
	)
	(segment
		(start 26.7716 -71.9582)
		(end 27.423364 -72.609964)
		(width 0.508)
		(layer "F.Cu")
		(net "VR_PVCCIN_CPU1_PH3_BOOT")
	)
	(via
		(at 26.7716 -71.9582)
		(size 0.762)
		(drill 0.381)
		(layers "F.Cu" "B.Cu")
		(net "VR_PVCCIN_CPU1_PH3_BOOT")
	)
	(segment
		(start 32.289496 -61.753496)
		(end 32.385 -61.849)
		(width 0.508)
		(layer "F.Cu")
		(net "VR_PVCCIN_CPU1_PH2_VCIN")
	)
	(segment
		(start 32.289496 -61.095382)
		(end 32.289496 -61.753496)
		(width 0.508)
		(layer "F.Cu")
		(net "VR_PVCCIN_CPU1_PH2_VCIN")
	)
	(segment
		(start 32.54502 -62.772544)
		(end 32.54502 -62.00902)
		(width 0.254)
		(layer "F.Cu")
		(net "VR_PVCCIN_CPU1_PH2_VCIN")
	)
	(segment
		(start 32.54502 -62.00902)
		(end 32.385 -61.849)
		(width 0.254)
		(layer "F.Cu")
		(net "VR_PVCCIN_CPU1_PH2_VCIN")
	)
	(via
		(at 32.385 -61.849)
		(size 0.508)
		(drill 0.254)
		(layers "F.Cu" "B.Cu")
		(net "VR_PVCCIN_CPU1_PH2_VCIN")
	)
	(via
		(at 31.74492 -61.31052)
		(size 0.6604)
		(drill 0.3302)
		(layers "F.Cu" "B.Cu")
		(net "VR_PVCCIN_CPU1_PH2_VCIN")
	)
	(segment
		(start 31.84652 -61.31052)
		(end 31.74492 -61.31052)
		(width 0.254)
		(layer "B.Cu")
		(net "VR_PVCCIN_CPU1_PH2_VCIN")
	)
	(segment
		(start 32.258 -61.976)
		(end 32.385 -61.849)
		(width 0.4064)
		(layer "B.Cu")
		(net "VR_PVCCIN_CPU1_PH2_VCIN")
	)
	(segment
		(start 32.258 -62.6364)
		(end 32.258 -61.976)
		(width 0.4064)
		(layer "B.Cu")
		(net "VR_PVCCIN_CPU1_PH2_VCIN")
	)
	(segment
		(start 32.385 -61.849)
		(end 31.84652 -61.31052)
		(width 0.254)
		(layer "B.Cu")
		(net "VR_PVCCIN_CPU1_PH2_VCIN")
	)
	(segment
		(start 30.23362 -66.41338)
		(end 30.329124 -66.317876)
		(width 0.254)
		(layer "F.Cu")
		(net "VR_PVCCIN_CPU1_PH2_PHASE")
	)
	(segment
		(start 30.329124 -66.317876)
		(end 31.02991 -66.317876)
		(width 0.254)
		(layer "F.Cu")
		(net "VR_PVCCIN_CPU1_PH2_PHASE")
	)
	(segment
		(start 29.718 -66.929)
		(end 30.23362 -66.41338)
		(width 0.508)
		(layer "F.Cu")
		(net "VR_PVCCIN_CPU1_PH2_PHASE")
	)
	(segment
		(start 28.3718 -66.929)
		(end 28.829 -66.929)
		(width 0.508)
		(layer "F.Cu")
		(net "VR_PVCCIN_CPU1_PH2_BOOT")
	)
	(segment
		(start 27.559 -65.913)
		(end 27.559 -66.1162)
		(width 0.508)
		(layer "F.Cu")
		(net "VR_PVCCIN_CPU1_PH2_BOOT")
	)
	(segment
		(start 27.655266 -67.705478)
		(end 27.655266 -67.645534)
		(width 0.508)
		(layer "F.Cu")
		(net "VR_PVCCIN_CPU1_PH2_BOOT")
	)
	(segment
		(start 27.559 -66.1162)
		(end 28.3718 -66.929)
		(width 0.508)
		(layer "F.Cu")
		(net "VR_PVCCIN_CPU1_PH2_BOOT")
	)
	(segment
		(start 27.655266 -67.645534)
		(end 28.3718 -66.929)
		(width 0.508)
		(layer "F.Cu")
		(net "VR_PVCCIN_CPU1_PH2_BOOT")
	)
	(via
		(at 27.655266 -67.705478)
		(size 0.762)
		(drill 0.381)
		(layers "F.Cu" "B.Cu")
		(net "VR_PVCCIN_CPU1_PH2_BOOT")
	)
	(segment
		(start 32.54502 -53.997606)
		(end 32.449516 -53.902102)
		(width 0.254)
		(layer "F.Cu")
		(net "VR_PVCCIN_CPU1_PH1_VCIN")
	)
	(segment
		(start 32.449516 -53.429916)
		(end 32.449516 -53.810662)
		(width 0.4064)
		(layer "F.Cu")
		(net "VR_PVCCIN_CPU1_PH1_VCIN")
	)
	(segment
		(start 32.54502 -54.644544)
		(end 32.54502 -53.997606)
		(width 0.254)
		(layer "F.Cu")
		(net "VR_PVCCIN_CPU1_PH1_VCIN")
	)
	(segment
		(start 33.0581 -51.8033)
		(end 32.8803 -51.8033)
		(width 0.254)
		(layer "F.Cu")
		(net "VR_PVCCIN_CPU1_PH1_VCIN")
	)
	(segment
		(start 32.1564 -53.1368)
		(end 32.449516 -53.429916)
		(width 0.4064)
		(layer "F.Cu")
		(net "VR_PVCCIN_CPU1_PH1_VCIN")
	)
	(segment
		(start 32.449516 -53.902102)
		(end 32.449516 -53.810662)
		(width 0.254)
		(layer "F.Cu")
		(net "VR_PVCCIN_CPU1_PH1_VCIN")
	)
	(segment
		(start 32.1564 -52.5272)
		(end 32.1564 -53.1368)
		(width 0.254)
		(layer "F.Cu")
		(net "VR_PVCCIN_CPU1_PH1_VCIN")
	)
	(segment
		(start 32.8803 -51.8033)
		(end 32.1564 -52.5272)
		(width 0.254)
		(layer "F.Cu")
		(net "VR_PVCCIN_CPU1_PH1_VCIN")
	)
	(via
		(at 33.0581 -51.8033)
		(size 0.762)
		(drill 0.381)
		(layers "F.Cu" "B.Cu")
		(net "VR_PVCCIN_CPU1_PH1_VCIN")
	)
	(via
		(at 32.449516 -53.810662)
		(size 0.508)
		(drill 0.254)
		(layers "F.Cu" "B.Cu")
		(net "VR_PVCCIN_CPU1_PH1_VCIN")
	)
	(segment
		(start 32.3342 -53.925978)
		(end 32.449516 -53.810662)
		(width 0.4064)
		(layer "B.Cu")
		(net "VR_PVCCIN_CPU1_PH1_VCIN")
	)
	(segment
		(start 32.3342 -54.5084)
		(end 32.3342 -53.925978)
		(width 0.4064)
		(layer "B.Cu")
		(net "VR_PVCCIN_CPU1_PH1_VCIN")
	)
	(segment
		(start 30.02915 -58.45175)
		(end 29.6926 -58.7883)
		(width 0.508)
		(layer "F.Cu")
		(net "VR_PVCCIN_CPU1_PH1_PHASE")
	)
	(segment
		(start 30.291024 -58.189876)
		(end 30.02915 -58.45175)
		(width 0.254)
		(layer "F.Cu")
		(net "VR_PVCCIN_CPU1_PH1_PHASE")
	)
	(segment
		(start 31.02991 -58.189876)
		(end 30.291024 -58.189876)
		(width 0.254)
		(layer "F.Cu")
		(net "VR_PVCCIN_CPU1_PH1_PHASE")
	)
	(segment
		(start 27.559 -58.2803)
		(end 27.559 -57.785)
		(width 0.508)
		(layer "F.Cu")
		(net "VR_PVCCIN_CPU1_PH1_BOOT")
	)
	(segment
		(start 28.067 -58.7883)
		(end 27.559 -58.2803)
		(width 0.508)
		(layer "F.Cu")
		(net "VR_PVCCIN_CPU1_PH1_BOOT")
	)
	(segment
		(start 27.559 -57.785)
		(end 26.41854 -57.785)
		(width 0.508)
		(layer "F.Cu")
		(net "VR_PVCCIN_CPU1_PH1_BOOT")
	)
	(segment
		(start 28.8036 -58.7883)
		(end 28.067 -58.7883)
		(width 0.508)
		(layer "F.Cu")
		(net "VR_PVCCIN_CPU1_PH1_BOOT")
	)
	(via
		(at 26.41854 -57.785)
		(size 0.762)
		(drill 0.381)
		(layers "F.Cu" "B.Cu")
		(net "VR_PVCCIN_CPU1_PH1_BOOT")
	)
	(segment
		(start 21.377656 -96.72066)
		(end 20.831048 -96.174052)
		(width 0.2032)
		(layer "F.Cu")
		(net "PU_VR_PVCCIN_CPU1_IMON")
	)
	(segment
		(start 22.4282 -97.30994)
		(end 21.966936 -97.30994)
		(width 0.2032)
		(layer "F.Cu")
		(net "PU_VR_PVCCIN_CPU1_IMON")
	)
	(segment
		(start 20.831048 -96.174052)
		(end 20.831048 -95.3516)
		(width 0.2032)
		(layer "F.Cu")
		(net "PU_VR_PVCCIN_CPU1_IMON")
	)
	(segment
		(start 21.966936 -97.30994)
		(end 21.377656 -96.72066)
		(width 0.2032)
		(layer "F.Cu")
		(net "PU_VR_PVCCIN_CPU1_IMON")
	)
	(via
		(at 21.377656 -96.72066)
		(size 0.508)
		(drill 0.254)
		(layers "F.Cu" "B.Cu")
		(net "PU_VR_PVCCIN_CPU1_IMON")
	)
	(segment
		(start 18.1102 -96.3168)
		(end 18.431002 -95.995998)
		(width 0.2032)
		(layer "F.Cu")
		(net "VR_PVCCIN_CPU1_AVINSEN")
	)
	(segment
		(start 18.431002 -95.995998)
		(end 18.431002 -95.3516)
		(width 0.2032)
		(layer "F.Cu")
		(net "VR_PVCCIN_CPU1_AVINSEN")
	)
	(segment
		(start 18.288 -96.87814)
		(end 18.1102 -96.70034)
		(width 0.2032)
		(layer "F.Cu")
		(net "VR_PVCCIN_CPU1_AVINSEN")
	)
	(segment
		(start 18.288 -97.917)
		(end 18.288 -96.87814)
		(width 0.2032)
		(layer "F.Cu")
		(net "VR_PVCCIN_CPU1_AVINSEN")
	)
	(segment
		(start 18.1102 -96.70034)
		(end 18.1102 -96.3168)
		(width 0.2032)
		(layer "F.Cu")
		(net "VR_PVCCIN_CPU1_AVINSEN")
	)
	(segment
		(start 18.288 -99.441)
		(end 18.288 -98.7044)
		(width 0.254)
		(layer "F.Cu")
		(net "VR_PVCCIN_CPU1_AVINSEN")
	)
	(segment
		(start 18.288 -98.7044)
		(end 18.288 -97.917)
		(width 0.254)
		(layer "F.Cu")
		(net "VR_PVCCIN_CPU1_AVINSEN")
	)
	(via
		(at 18.1102 -96.70034)
		(size 0.762)
		(drill 0.381)
		(layers "F.Cu" "B.Cu")
		(net "VR_PVCCIN_CPU1_AVINSEN")
	)
	(segment
		(start 184.876948 -73.358248)
		(end 185.308748 -73.790048)
		(width 0.2032)
		(layer "F.Cu")
		(net "VR_PVCCIN_CPU0_XADDR2")
	)
	(segment
		(start 185.308748 -73.790048)
		(end 185.308748 -73.84415)
		(width 0.2032)
		(layer "F.Cu")
		(net "VR_PVCCIN_CPU0_XADDR2")
	)
	(segment
		(start 185.308748 -73.84415)
		(end 185.26887 -73.84415)
		(width 0.2032)
		(layer "F.Cu")
		(net "VR_PVCCIN_CPU0_XADDR2")
	)
	(segment
		(start 184.876948 -72.7456)
		(end 184.876948 -73.358248)
		(width 0.2032)
		(layer "F.Cu")
		(net "VR_PVCCIN_CPU0_XADDR2")
	)
	(via
		(at 185.26887 -73.84415)
		(size 0.508)
		(drill 0.254)
		(layers "F.Cu" "B.Cu")
		(net "VR_PVCCIN_CPU0_XADDR2")
	)
	(segment
		(start 185.26887 -73.84415)
		(end 185.039 -73.61428)
		(width 0.4064)
		(layer "B.Cu")
		(net "VR_PVCCIN_CPU0_XADDR2")
	)
	(segment
		(start 185.039 -73.61428)
		(end 185.039 -72.898)
		(width 0.4064)
		(layer "B.Cu")
		(net "VR_PVCCIN_CPU0_XADDR2")
	)
	(segment
		(start 183.733948 -73.310242)
		(end 183.677052 -73.253346)
		(width 0.2032)
		(layer "F.Cu")
		(net "VR_PVCCIN_CPU0_XADDR1")
	)
	(segment
		(start 183.677052 -73.253346)
		(end 183.677052 -72.7456)
		(width 0.2032)
		(layer "F.Cu")
		(net "VR_PVCCIN_CPU0_XADDR1")
	)
	(segment
		(start 183.733948 -73.68286)
		(end 183.733948 -73.310242)
		(width 0.2032)
		(layer "F.Cu")
		(net "VR_PVCCIN_CPU0_XADDR1")
	)
	(segment
		(start 183.896 -74.0918)
		(end 183.896 -73.844912)
		(width 0.2032)
		(layer "F.Cu")
		(net "VR_PVCCIN_CPU0_XADDR1")
	)
	(segment
		(start 183.896 -73.844912)
		(end 183.733948 -73.68286)
		(width 0.2032)
		(layer "F.Cu")
		(net "VR_PVCCIN_CPU0_XADDR1")
	)
	(via
		(at 183.896 -74.0918)
		(size 0.508)
		(drill 0.254)
		(layers "F.Cu" "B.Cu")
		(net "VR_PVCCIN_CPU0_XADDR1")
	)
	(segment
		(start 183.896 -73.2282)
		(end 183.515 -72.8472)
		(width 0.4064)
		(layer "B.Cu")
		(net "VR_PVCCIN_CPU0_XADDR1")
	)
	(segment
		(start 183.896 -74.0918)
		(end 183.896 -73.2282)
		(width 0.4064)
		(layer "B.Cu")
		(net "VR_PVCCIN_CPU0_XADDR1")
	)
	(segment
		(start 182.476902 -73.224898)
		(end 182.3085 -73.3933)
		(width 0.1778)
		(layer "F.Cu")
		(net "VR_PVCCIN_CPU0_VDD")
	)
	(segment
		(start 181.83225 -77.31125)
		(end 181.75605 -77.31125)
		(width 0.381)
		(layer "F.Cu")
		(net "VR_PVCCIN_CPU0_VDD")
	)
	(segment
		(start 181.1147 -75.3491)
		(end 181.1147 -75.68565)
		(width 0.508)
		(layer "F.Cu")
		(net "VR_PVCCIN_CPU0_VDD")
	)
	(segment
		(start 182.476902 -72.7456)
		(end 182.476902 -73.224898)
		(width 0.1778)
		(layer "F.Cu")
		(net "VR_PVCCIN_CPU0_VDD")
	)
	(segment
		(start 181.1147 -77.31125)
		(end 181.1147 -76.52385)
		(width 0.508)
		(layer "F.Cu")
		(net "VR_PVCCIN_CPU0_VDD")
	)
	(segment
		(start 182.0926 -77.5716)
		(end 181.83225 -77.31125)
		(width 0.381)
		(layer "F.Cu")
		(net "VR_PVCCIN_CPU0_VDD")
	)
	(segment
		(start 182.3085 -73.8124)
		(end 182.3085 -74.1553)
		(width 0.508)
		(layer "F.Cu")
		(net "VR_PVCCIN_CPU0_VDD")
	)
	(segment
		(start 181.1147 -76.52385)
		(end 181.1147 -75.68565)
		(width 0.508)
		(layer "F.Cu")
		(net "VR_PVCCIN_CPU0_VDD")
	)
	(segment
		(start 182.3085 -74.1553)
		(end 181.1147 -75.3491)
		(width 0.508)
		(layer "F.Cu")
		(net "VR_PVCCIN_CPU0_VDD")
	)
	(segment
		(start 182.3085 -73.3933)
		(end 182.3085 -73.8124)
		(width 0.1778)
		(layer "F.Cu")
		(net "VR_PVCCIN_CPU0_VDD")
	)
	(segment
		(start 181.75605 -77.31125)
		(end 181.1147 -77.31125)
		(width 0.4064)
		(layer "F.Cu")
		(net "VR_PVCCIN_CPU0_VDD")
	)
	(via
		(at 182.0926 -77.5716)
		(size 0.762)
		(drill 0.381)
		(layers "F.Cu" "B.Cu")
		(net "VR_PVCCIN_CPU0_VDD")
	)
	(via
		(at 181.3306 -74.041)
		(size 0.762)
		(drill 0.381)
		(layers "F.Cu" "B.Cu")
		(net "VR_PVCCIN_CPU0_VD12")
	)
	(segment
		(start 194.778376 -89.710006)
		(end 194.749928 -89.710006)
		(width 0.254)
		(layer "F.Cu")
		(net "VR_PVCCIN_CPU0_PWM5")
	)
	(segment
		(start 196.030342 -89.8017)
		(end 194.87007 -89.8017)
		(width 0.254)
		(layer "F.Cu")
		(net "VR_PVCCIN_CPU0_PWM5")
	)
	(segment
		(start 181.3814 -71.250048)
		(end 180.753766 -71.250048)
		(width 0.2032)
		(layer "F.Cu")
		(net "VR_PVCCIN_CPU0_PWM5")
	)
	(segment
		(start 180.753766 -71.250048)
		(end 180.409088 -71.594726)
		(width 0.2032)
		(layer "F.Cu")
		(net "VR_PVCCIN_CPU0_PWM5")
	)
	(segment
		(start 194.87007 -89.8017)
		(end 194.778376 -89.710006)
		(width 0.254)
		(layer "F.Cu")
		(net "VR_PVCCIN_CPU0_PWM5")
	)
	(segment
		(start 180.409088 -71.594726)
		(end 180.409088 -71.605394)
		(width 0.2032)
		(layer "F.Cu")
		(net "VR_PVCCIN_CPU0_PWM5")
	)
	(via
		(at 194.749928 -89.710006)
		(size 0.508)
		(drill 0.254)
		(layers "F.Cu" "B.Cu")
		(net "VR_PVCCIN_CPU0_PWM5")
	)
	(via
		(at 180.409088 -71.605394)
		(size 0.508)
		(drill 0.254)
		(layers "F.Cu" "B.Cu")
		(net "VR_PVCCIN_CPU0_PWM5")
	)
	(segment
		(start 193.0654 -83.1088)
		(end 190.0809 -80.1243)
		(width 0.254)
		(layer "In2.Cu")
		(net "VR_PVCCIN_CPU0_PWM5")
	)
	(segment
		(start 190.0809 -80.1243)
		(end 190.0809 -74.96048)
		(width 0.254)
		(layer "In2.Cu")
		(net "VR_PVCCIN_CPU0_PWM5")
	)
	(segment
		(start 194.485006 -89.710006)
		(end 193.0654 -88.2904)
		(width 0.254)
		(layer "In2.Cu")
		(net "VR_PVCCIN_CPU0_PWM5")
	)
	(segment
		(start 193.0654 -88.2904)
		(end 193.0654 -83.1088)
		(width 0.254)
		(layer "In2.Cu")
		(net "VR_PVCCIN_CPU0_PWM5")
	)
	(segment
		(start 186.725814 -71.605394)
		(end 180.409088 -71.605394)
		(width 0.254)
		(layer "In2.Cu")
		(net "VR_PVCCIN_CPU0_PWM5")
	)
	(segment
		(start 194.749928 -89.710006)
		(end 194.485006 -89.710006)
		(width 0.254)
		(layer "In2.Cu")
		(net "VR_PVCCIN_CPU0_PWM5")
	)
	(segment
		(start 190.0809 -74.96048)
		(end 186.725814 -71.605394)
		(width 0.254)
		(layer "In2.Cu")
		(net "VR_PVCCIN_CPU0_PWM5")
	)
	(segment
		(start 180.44287 -71.100442)
		(end 180.053234 -71.100442)
		(width 0.2032)
		(layer "F.Cu")
		(net "VR_PVCCIN_CPU0_PWM4")
	)
	(segment
		(start 180.053234 -71.100442)
		(end 179.590192 -70.6374)
		(width 0.2032)
		(layer "F.Cu")
		(net "VR_PVCCIN_CPU0_PWM4")
	)
	(segment
		(start 181.3814 -70.849998)
		(end 180.693314 -70.849998)
		(width 0.2032)
		(layer "F.Cu")
		(net "VR_PVCCIN_CPU0_PWM4")
	)
	(segment
		(start 179.590192 -70.6374)
		(end 179.5272 -70.6374)
		(width 0.2032)
		(layer "F.Cu")
		(net "VR_PVCCIN_CPU0_PWM4")
	)
	(segment
		(start 196.030342 -81.6737)
		(end 194.87007 -81.6737)
		(width 0.254)
		(layer "F.Cu")
		(net "VR_PVCCIN_CPU0_PWM4")
	)
	(segment
		(start 194.778376 -81.582006)
		(end 194.749928 -81.582006)
		(width 0.254)
		(layer "F.Cu")
		(net "VR_PVCCIN_CPU0_PWM4")
	)
	(segment
		(start 194.87007 -81.6737)
		(end 194.778376 -81.582006)
		(width 0.254)
		(layer "F.Cu")
		(net "VR_PVCCIN_CPU0_PWM4")
	)
	(segment
		(start 180.693314 -70.849998)
		(end 180.44287 -71.100442)
		(width 0.2032)
		(layer "F.Cu")
		(net "VR_PVCCIN_CPU0_PWM4")
	)
	(via
		(at 194.749928 -81.582006)
		(size 0.508)
		(drill 0.254)
		(layers "F.Cu" "B.Cu")
		(net "VR_PVCCIN_CPU0_PWM4")
	)
	(via
		(at 179.5272 -70.6374)
		(size 0.508)
		(drill 0.254)
		(layers "F.Cu" "B.Cu")
		(net "VR_PVCCIN_CPU0_PWM4")
	)
	(segment
		(start 191.590676 -78.890876)
		(end 191.590676 -74.715116)
		(width 0.254)
		(layer "In2.Cu")
		(net "VR_PVCCIN_CPU0_PWM4")
	)
	(segment
		(start 179.5272 -70.7771)
		(end 179.5272 -70.6374)
		(width 0.254)
		(layer "In2.Cu")
		(net "VR_PVCCIN_CPU0_PWM4")
	)
	(segment
		(start 179.8701 -71.12)
		(end 179.5272 -70.7771)
		(width 0.254)
		(layer "In2.Cu")
		(net "VR_PVCCIN_CPU0_PWM4")
	)
	(segment
		(start 194.281806 -81.582006)
		(end 191.590676 -78.890876)
		(width 0.254)
		(layer "In2.Cu")
		(net "VR_PVCCIN_CPU0_PWM4")
	)
	(segment
		(start 187.050172 -70.174612)
		(end 182.631588 -70.174612)
		(width 0.254)
		(layer "In2.Cu")
		(net "VR_PVCCIN_CPU0_PWM4")
	)
	(segment
		(start 194.749928 -81.582006)
		(end 194.281806 -81.582006)
		(width 0.254)
		(layer "In2.Cu")
		(net "VR_PVCCIN_CPU0_PWM4")
	)
	(segment
		(start 182.631588 -70.174612)
		(end 181.6862 -71.12)
		(width 0.254)
		(layer "In2.Cu")
		(net "VR_PVCCIN_CPU0_PWM4")
	)
	(segment
		(start 181.6862 -71.12)
		(end 179.8701 -71.12)
		(width 0.254)
		(layer "In2.Cu")
		(net "VR_PVCCIN_CPU0_PWM4")
	)
	(segment
		(start 191.590676 -74.715116)
		(end 187.050172 -70.174612)
		(width 0.254)
		(layer "In2.Cu")
		(net "VR_PVCCIN_CPU0_PWM4")
	)
	(segment
		(start 194.7799 -73.30694)
		(end 194.71132 -73.30694)
		(width 0.254)
		(layer "F.Cu")
		(net "VR_PVCCIN_CPU0_PWM3")
	)
	(segment
		(start 181.3814 -70.449948)
		(end 180.425852 -70.449948)
		(width 0.2032)
		(layer "F.Cu")
		(net "VR_PVCCIN_CPU0_PWM3")
	)
	(segment
		(start 194.5513 -73.14692)
		(end 194.30492 -73.14692)
		(width 0.254)
		(layer "F.Cu")
		(net "VR_PVCCIN_CPU0_PWM3")
	)
	(segment
		(start 180.425852 -70.449948)
		(end 180.2384 -70.6374)
		(width 0.2032)
		(layer "F.Cu")
		(net "VR_PVCCIN_CPU0_PWM3")
	)
	(segment
		(start 196.030342 -73.5457)
		(end 195.01866 -73.5457)
		(width 0.254)
		(layer "F.Cu")
		(net "VR_PVCCIN_CPU0_PWM3")
	)
	(segment
		(start 194.71132 -73.30694)
		(end 194.5513 -73.14692)
		(width 0.254)
		(layer "F.Cu")
		(net "VR_PVCCIN_CPU0_PWM3")
	)
	(segment
		(start 195.01866 -73.5457)
		(end 194.7799 -73.30694)
		(width 0.254)
		(layer "F.Cu")
		(net "VR_PVCCIN_CPU0_PWM3")
	)
	(via
		(at 180.2384 -70.6374)
		(size 0.508)
		(drill 0.254)
		(layers "F.Cu" "B.Cu")
		(net "VR_PVCCIN_CPU0_PWM3")
	)
	(via
		(at 194.30492 -73.14692)
		(size 0.508)
		(drill 0.254)
		(layers "F.Cu" "B.Cu")
		(net "VR_PVCCIN_CPU0_PWM3")
	)
	(segment
		(start 187.58916 -69.25056)
		(end 188.376306 -70.037706)
		(width 0.254)
		(layer "In2.Cu")
		(net "VR_PVCCIN_CPU0_PWM3")
	)
	(segment
		(start 181.4068 -70.6374)
		(end 182.79364 -69.25056)
		(width 0.254)
		(layer "In2.Cu")
		(net "VR_PVCCIN_CPU0_PWM3")
	)
	(segment
		(start 193.771774 -73.16978)
		(end 194.28206 -73.16978)
		(width 0.254)
		(layer "In2.Cu")
		(net "VR_PVCCIN_CPU0_PWM3")
	)
	(segment
		(start 190.6397 -70.037706)
		(end 193.771774 -73.16978)
		(width 0.254)
		(layer "In2.Cu")
		(net "VR_PVCCIN_CPU0_PWM3")
	)
	(segment
		(start 194.28206 -73.16978)
		(end 194.30492 -73.14692)
		(width 0.254)
		(layer "In2.Cu")
		(net "VR_PVCCIN_CPU0_PWM3")
	)
	(segment
		(start 188.376306 -70.037706)
		(end 190.6397 -70.037706)
		(width 0.254)
		(layer "In2.Cu")
		(net "VR_PVCCIN_CPU0_PWM3")
	)
	(segment
		(start 182.79364 -69.25056)
		(end 187.58916 -69.25056)
		(width 0.254)
		(layer "In2.Cu")
		(net "VR_PVCCIN_CPU0_PWM3")
	)
	(segment
		(start 180.2384 -70.6374)
		(end 181.4068 -70.6374)
		(width 0.254)
		(layer "In2.Cu")
		(net "VR_PVCCIN_CPU0_PWM3")
	)
	(segment
		(start 181.3814 -70.049898)
		(end 180.336698 -70.049898)
		(width 0.2032)
		(layer "F.Cu")
		(net "VR_PVCCIN_CPU0_PWM2")
	)
	(segment
		(start 194.80022 -65.4177)
		(end 196.030342 -65.4177)
		(width 0.254)
		(layer "F.Cu")
		(net "VR_PVCCIN_CPU0_PWM2")
	)
	(segment
		(start 180.336698 -70.049898)
		(end 180.2638 -69.977)
		(width 0.2032)
		(layer "F.Cu")
		(net "VR_PVCCIN_CPU0_PWM2")
	)
	(segment
		(start 194.724528 -65.342008)
		(end 194.80022 -65.4177)
		(width 0.254)
		(layer "F.Cu")
		(net "VR_PVCCIN_CPU0_PWM2")
	)
	(via
		(at 181.164992 -70.229476)
		(size 0.6604)
		(drill 0.3302)
		(layers "F.Cu" "B.Cu")
		(net "VR_PVCCIN_CPU0_PWM2")
	)
	(via
		(at 180.2638 -69.977)
		(size 0.508)
		(drill 0.254)
		(layers "F.Cu" "B.Cu")
		(net "VR_PVCCIN_CPU0_PWM2")
	)
	(via
		(at 194.724528 -65.342008)
		(size 0.508)
		(drill 0.254)
		(layers "F.Cu" "B.Cu")
		(net "VR_PVCCIN_CPU0_PWM2")
	)
	(segment
		(start 180.912516 -69.977)
		(end 180.2638 -69.977)
		(width 0.254)
		(layer "B.Cu")
		(net "VR_PVCCIN_CPU0_PWM2")
	)
	(segment
		(start 181.164992 -70.229476)
		(end 180.912516 -69.977)
		(width 0.254)
		(layer "B.Cu")
		(net "VR_PVCCIN_CPU0_PWM2")
	)
	(segment
		(start 181.9656 -68.49364)
		(end 181.9656 -69.1642)
		(width 0.254)
		(layer "In2.Cu")
		(net "VR_PVCCIN_CPU0_PWM2")
	)
	(segment
		(start 194.683126 -65.300606)
		(end 194.033394 -65.300606)
		(width 0.254)
		(layer "In2.Cu")
		(net "VR_PVCCIN_CPU0_PWM2")
	)
	(segment
		(start 181.1528 -69.977)
		(end 180.2638 -69.977)
		(width 0.254)
		(layer "In2.Cu")
		(net "VR_PVCCIN_CPU0_PWM2")
	)
	(segment
		(start 194.724528 -65.342008)
		(end 194.683126 -65.300606)
		(width 0.254)
		(layer "In2.Cu")
		(net "VR_PVCCIN_CPU0_PWM2")
	)
	(segment
		(start 187.47994 -67.76466)
		(end 182.69458 -67.76466)
		(width 0.254)
		(layer "In2.Cu")
		(net "VR_PVCCIN_CPU0_PWM2")
	)
	(segment
		(start 182.69458 -67.76466)
		(end 181.9656 -68.49364)
		(width 0.254)
		(layer "In2.Cu")
		(net "VR_PVCCIN_CPU0_PWM2")
	)
	(segment
		(start 194.033394 -65.300606)
		(end 192.6336 -66.7004)
		(width 0.254)
		(layer "In2.Cu")
		(net "VR_PVCCIN_CPU0_PWM2")
	)
	(segment
		(start 181.9656 -69.1642)
		(end 181.1528 -69.977)
		(width 0.254)
		(layer "In2.Cu")
		(net "VR_PVCCIN_CPU0_PWM2")
	)
	(segment
		(start 188.5442 -66.7004)
		(end 187.47994 -67.76466)
		(width 0.254)
		(layer "In2.Cu")
		(net "VR_PVCCIN_CPU0_PWM2")
	)
	(segment
		(start 192.6336 -66.7004)
		(end 188.5442 -66.7004)
		(width 0.254)
		(layer "In2.Cu")
		(net "VR_PVCCIN_CPU0_PWM2")
	)
	(segment
		(start 194.778376 -57.198006)
		(end 194.749928 -57.198006)
		(width 0.254)
		(layer "F.Cu")
		(net "VR_PVCCIN_CPU0_PWM1")
	)
	(segment
		(start 181.3814 -69.650102)
		(end 180.72481 -69.650102)
		(width 0.2032)
		(layer "F.Cu")
		(net "VR_PVCCIN_CPU0_PWM1")
	)
	(segment
		(start 196.030342 -57.2897)
		(end 194.87007 -57.2897)
		(width 0.254)
		(layer "F.Cu")
		(net "VR_PVCCIN_CPU0_PWM1")
	)
	(segment
		(start 180.72481 -69.650102)
		(end 180.327046 -69.252338)
		(width 0.2032)
		(layer "F.Cu")
		(net "VR_PVCCIN_CPU0_PWM1")
	)
	(segment
		(start 194.87007 -57.2897)
		(end 194.778376 -57.198006)
		(width 0.254)
		(layer "F.Cu")
		(net "VR_PVCCIN_CPU0_PWM1")
	)
	(via
		(at 180.327046 -69.252338)
		(size 0.508)
		(drill 0.254)
		(layers "F.Cu" "B.Cu")
		(net "VR_PVCCIN_CPU0_PWM1")
	)
	(via
		(at 194.749928 -57.198006)
		(size 0.508)
		(drill 0.254)
		(layers "F.Cu" "B.Cu")
		(net "VR_PVCCIN_CPU0_PWM1")
	)
	(segment
		(start 193.383408 -60.82792)
		(end 192.799716 -60.82792)
		(width 0.254)
		(layer "In2.Cu")
		(net "VR_PVCCIN_CPU0_PWM1")
	)
	(segment
		(start 181.18582 -68.70954)
		(end 180.643022 -69.252338)
		(width 0.254)
		(layer "In2.Cu")
		(net "VR_PVCCIN_CPU0_PWM1")
	)
	(segment
		(start 182.398416 -66.97472)
		(end 181.18582 -68.187316)
		(width 0.254)
		(layer "In2.Cu")
		(net "VR_PVCCIN_CPU0_PWM1")
	)
	(segment
		(start 187.192158 -66.97472)
		(end 182.398416 -66.97472)
		(width 0.254)
		(layer "In2.Cu")
		(net "VR_PVCCIN_CPU0_PWM1")
	)
	(segment
		(start 194.749928 -59.4614)
		(end 193.383408 -60.82792)
		(width 0.254)
		(layer "In2.Cu")
		(net "VR_PVCCIN_CPU0_PWM1")
	)
	(segment
		(start 189.32398 -64.842898)
		(end 187.192158 -66.97472)
		(width 0.254)
		(layer "In2.Cu")
		(net "VR_PVCCIN_CPU0_PWM1")
	)
	(segment
		(start 180.643022 -69.252338)
		(end 180.327046 -69.252338)
		(width 0.254)
		(layer "In2.Cu")
		(net "VR_PVCCIN_CPU0_PWM1")
	)
	(segment
		(start 194.749928 -57.198006)
		(end 194.749928 -59.4614)
		(width 0.254)
		(layer "In2.Cu")
		(net "VR_PVCCIN_CPU0_PWM1")
	)
	(segment
		(start 181.18582 -68.187316)
		(end 181.18582 -68.70954)
		(width 0.254)
		(layer "In2.Cu")
		(net "VR_PVCCIN_CPU0_PWM1")
	)
	(segment
		(start 189.32398 -64.303656)
		(end 189.32398 -64.842898)
		(width 0.254)
		(layer "In2.Cu")
		(net "VR_PVCCIN_CPU0_PWM1")
	)
	(segment
		(start 192.799716 -60.82792)
		(end 189.32398 -64.303656)
		(width 0.254)
		(layer "In2.Cu")
		(net "VR_PVCCIN_CPU0_PWM1")
	)
	(segment
		(start 205.036928 -89.289382)
		(end 205.036928 -85.936328)
		(width 0.508)
		(layer "F.Cu")
		(net "VR_PVCCIN_CPU0_PHASE5")
	)
	(segment
		(start 205.036928 -85.936328)
		(end 204.5462 -85.4456)
		(width 0.508)
		(layer "F.Cu")
		(net "VR_PVCCIN_CPU0_PHASE5")
	)
	(segment
		(start 204.8764 -61.214)
		(end 204.8764 -62.7634)
		(width 0.508)
		(layer "F.Cu")
		(net "VR_PVCCIN_CPU0_PHASE2")
	)
	(segment
		(start 205.036928 -62.923928)
		(end 205.036928 -65.159382)
		(width 0.508)
		(layer "F.Cu")
		(net "VR_PVCCIN_CPU0_PHASE2")
	)
	(segment
		(start 204.8764 -62.7634)
		(end 205.036928 -62.923928)
		(width 0.508)
		(layer "F.Cu")
		(net "VR_PVCCIN_CPU0_PHASE2")
	)
	(segment
		(start 205.036928 -54.520592)
		(end 204.723492 -54.207156)
		(width 0.508)
		(layer "F.Cu")
		(net "VR_PVCCIN_CPU0_PHASE1")
	)
	(segment
		(start 204.723492 -53.402992)
		(end 204.0509 -52.7304)
		(width 0.508)
		(layer "F.Cu")
		(net "VR_PVCCIN_CPU0_PHASE1")
	)
	(segment
		(start 204.723492 -54.207156)
		(end 204.723492 -53.402992)
		(width 0.508)
		(layer "F.Cu")
		(net "VR_PVCCIN_CPU0_PHASE1")
	)
	(segment
		(start 205.036928 -57.031382)
		(end 205.036928 -54.520592)
		(width 0.508)
		(layer "F.Cu")
		(net "VR_PVCCIN_CPU0_PHASE1")
	)
	(segment
		(start 197.545452 -87.156544)
		(end 197.545452 -86.509606)
		(width 0.254)
		(layer "F.Cu")
		(net "VR_PVCCIN_CPU0_PH5_VCIN")
	)
	(segment
		(start 197.545452 -86.509606)
		(end 197.404228 -86.368382)
		(width 0.254)
		(layer "F.Cu")
		(net "VR_PVCCIN_CPU0_PH5_VCIN")
	)
	(segment
		(start 197.162928 -85.733382)
		(end 197.404228 -85.974682)
		(width 0.4064)
		(layer "F.Cu")
		(net "VR_PVCCIN_CPU0_PH5_VCIN")
	)
	(segment
		(start 197.404228 -85.974682)
		(end 197.404228 -86.368382)
		(width 0.4064)
		(layer "F.Cu")
		(net "VR_PVCCIN_CPU0_PH5_VCIN")
	)
	(via
		(at 197.404228 -86.368382)
		(size 0.508)
		(drill 0.254)
		(layers "F.Cu" "B.Cu")
		(net "VR_PVCCIN_CPU0_PH5_VCIN")
	)
	(via
		(at 196.71284 -85.5218)
		(size 0.6604)
		(drill 0.3302)
		(layers "F.Cu" "B.Cu")
		(net "VR_PVCCIN_CPU0_PH5_VCIN")
	)
	(segment
		(start 197.239128 -86.707726)
		(end 197.239128 -87.043006)
		(width 0.4064)
		(layer "B.Cu")
		(net "VR_PVCCIN_CPU0_PH5_VCIN")
	)
	(segment
		(start 197.404228 -86.368382)
		(end 197.404228 -86.542626)
		(width 0.4064)
		(layer "B.Cu")
		(net "VR_PVCCIN_CPU0_PH5_VCIN")
	)
	(segment
		(start 196.71284 -85.5218)
		(end 196.71284 -85.676994)
		(width 0.254)
		(layer "B.Cu")
		(net "VR_PVCCIN_CPU0_PH5_VCIN")
	)
	(segment
		(start 196.71284 -85.676994)
		(end 197.404228 -86.368382)
		(width 0.254)
		(layer "B.Cu")
		(net "VR_PVCCIN_CPU0_PH5_VCIN")
	)
	(segment
		(start 197.404228 -86.542626)
		(end 197.239128 -86.707726)
		(width 0.4064)
		(layer "B.Cu")
		(net "VR_PVCCIN_CPU0_PH5_VCIN")
	)
	(segment
		(start 194.7672 -91.3892)
		(end 195.243196 -90.913204)
		(width 0.508)
		(layer "F.Cu")
		(net "VR_PVCCIN_CPU0_PH5_PHASE")
	)
	(segment
		(start 195.454524 -90.701876)
		(end 196.030342 -90.701876)
		(width 0.254)
		(layer "F.Cu")
		(net "VR_PVCCIN_CPU0_PH5_PHASE")
	)
	(segment
		(start 195.243196 -90.913204)
		(end 195.454524 -90.701876)
		(width 0.254)
		(layer "F.Cu")
		(net "VR_PVCCIN_CPU0_PH5_PHASE")
	)
	(segment
		(start 192.62725 -90.3859)
		(end 192.62725 -90.84945)
		(width 0.508)
		(layer "F.Cu")
		(net "VR_PVCCIN_CPU0_PH5_BOOT")
	)
	(segment
		(start 193.8782 -91.3892)
		(end 193.167 -91.3892)
		(width 0.508)
		(layer "F.Cu")
		(net "VR_PVCCIN_CPU0_PH5_BOOT")
	)
	(segment
		(start 192.62725 -90.84945)
		(end 193.167 -91.3892)
		(width 0.508)
		(layer "F.Cu")
		(net "VR_PVCCIN_CPU0_PH5_BOOT")
	)
	(via
		(at 193.167 -91.3892)
		(size 0.508)
		(drill 0.254)
		(layers "F.Cu" "B.Cu")
		(net "VR_PVCCIN_CPU0_PH5_BOOT")
	)
	(segment
		(start 197.066154 -61.557154)
		(end 197.358 -61.849)
		(width 0.508)
		(layer "F.Cu")
		(net "VR_PVCCIN_CPU0_PH2_VCIN")
	)
	(segment
		(start 197.545452 -62.036452)
		(end 197.358 -61.849)
		(width 0.254)
		(layer "F.Cu")
		(net "VR_PVCCIN_CPU0_PH2_VCIN")
	)
	(segment
		(start 197.545452 -62.772544)
		(end 197.545452 -62.036452)
		(width 0.254)
		(layer "F.Cu")
		(net "VR_PVCCIN_CPU0_PH2_VCIN")
	)
	(segment
		(start 197.066154 -61.205364)
		(end 197.066154 -61.557154)
		(width 0.508)
		(layer "F.Cu")
		(net "VR_PVCCIN_CPU0_PH2_VCIN")
	)
	(via
		(at 196.0245 -61.49848)
		(size 0.6604)
		(drill 0.3302)
		(layers "F.Cu" "B.Cu")
		(net "VR_PVCCIN_CPU0_PH2_VCIN")
	)
	(via
		(at 197.358 -61.849)
		(size 0.508)
		(drill 0.254)
		(layers "F.Cu" "B.Cu")
		(net "VR_PVCCIN_CPU0_PH2_VCIN")
	)
	(segment
		(start 196.3674 -62.0522)
		(end 196.974206 -62.659006)
		(width 0.254)
		(layer "B.Cu")
		(net "VR_PVCCIN_CPU0_PH2_VCIN")
	)
	(segment
		(start 197.239128 -62.659006)
		(end 197.239128 -61.967872)
		(width 0.4064)
		(layer "B.Cu")
		(net "VR_PVCCIN_CPU0_PH2_VCIN")
	)
	(segment
		(start 196.3674 -61.84138)
		(end 196.3674 -62.0522)
		(width 0.254)
		(layer "B.Cu")
		(net "VR_PVCCIN_CPU0_PH2_VCIN")
	)
	(segment
		(start 197.239128 -61.967872)
		(end 197.358 -61.849)
		(width 0.4064)
		(layer "B.Cu")
		(net "VR_PVCCIN_CPU0_PH2_VCIN")
	)
	(segment
		(start 196.0245 -61.49848)
		(end 196.3674 -61.84138)
		(width 0.254)
		(layer "B.Cu")
		(net "VR_PVCCIN_CPU0_PH2_VCIN")
	)
	(segment
		(start 196.974206 -62.659006)
		(end 197.239128 -62.659006)
		(width 0.254)
		(layer "B.Cu")
		(net "VR_PVCCIN_CPU0_PH2_VCIN")
	)
	(segment
		(start 196.030342 -66.317876)
		(end 195.606924 -66.317876)
		(width 0.254)
		(layer "F.Cu")
		(net "VR_PVCCIN_CPU0_PH2_PHASE")
	)
	(segment
		(start 194.818 -67.1068)
		(end 194.818 -67.1576)
		(width 0.508)
		(layer "F.Cu")
		(net "VR_PVCCIN_CPU0_PH2_PHASE")
	)
	(segment
		(start 195.606924 -66.317876)
		(end 195.0974 -66.8274)
		(width 0.254)
		(layer "F.Cu")
		(net "VR_PVCCIN_CPU0_PH2_PHASE")
	)
	(segment
		(start 195.0974 -66.8274)
		(end 194.818 -67.1068)
		(width 0.508)
		(layer "F.Cu")
		(net "VR_PVCCIN_CPU0_PH2_PHASE")
	)
	(segment
		(start 192.786 -66.06667)
		(end 193.87693 -67.1576)
		(width 0.508)
		(layer "F.Cu")
		(net "VR_PVCCIN_CPU0_PH2_BOOT")
	)
	(segment
		(start 193.87693 -67.1576)
		(end 193.929 -67.1576)
		(width 0.508)
		(layer "F.Cu")
		(net "VR_PVCCIN_CPU0_PH2_BOOT")
	)
	(segment
		(start 192.786 -66.06667)
		(end 192.786 -67.818)
		(width 0.508)
		(layer "F.Cu")
		(net "VR_PVCCIN_CPU0_PH2_BOOT")
	)
	(via
		(at 192.786 -67.818)
		(size 0.762)
		(drill 0.381)
		(layers "F.Cu" "B.Cu")
		(net "VR_PVCCIN_CPU0_PH2_BOOT")
	)
	(segment
		(start 197.404228 -53.462682)
		(end 197.162928 -53.221382)
		(width 0.4064)
		(layer "F.Cu")
		(net "VR_PVCCIN_CPU0_PH1_VCIN")
	)
	(segment
		(start 197.162928 -53.221382)
		(end 197.162928 -52.163472)
		(width 0.254)
		(layer "F.Cu")
		(net "VR_PVCCIN_CPU0_PH1_VCIN")
	)
	(segment
		(start 197.162928 -52.163472)
		(end 197.3834 -51.943)
		(width 0.254)
		(layer "F.Cu")
		(net "VR_PVCCIN_CPU0_PH1_VCIN")
	)
	(segment
		(start 197.404228 -53.856382)
		(end 197.404228 -53.462682)
		(width 0.4064)
		(layer "F.Cu")
		(net "VR_PVCCIN_CPU0_PH1_VCIN")
	)
	(segment
		(start 197.545452 -53.997606)
		(end 197.404228 -53.856382)
		(width 0.254)
		(layer "F.Cu")
		(net "VR_PVCCIN_CPU0_PH1_VCIN")
	)
	(segment
		(start 197.545452 -54.644544)
		(end 197.545452 -53.997606)
		(width 0.254)
		(layer "F.Cu")
		(net "VR_PVCCIN_CPU0_PH1_VCIN")
	)
	(via
		(at 197.404228 -53.856382)
		(size 0.508)
		(drill 0.254)
		(layers "F.Cu" "B.Cu")
		(net "VR_PVCCIN_CPU0_PH1_VCIN")
	)
	(via
		(at 197.3834 -51.943)
		(size 0.762)
		(drill 0.381)
		(layers "F.Cu" "B.Cu")
		(net "VR_PVCCIN_CPU0_PH1_VCIN")
	)
	(segment
		(start 197.404228 -54.017926)
		(end 197.239128 -54.183026)
		(width 0.4064)
		(layer "B.Cu")
		(net "VR_PVCCIN_CPU0_PH1_VCIN")
	)
	(segment
		(start 197.404228 -53.856382)
		(end 197.404228 -54.017926)
		(width 0.4064)
		(layer "B.Cu")
		(net "VR_PVCCIN_CPU0_PH1_VCIN")
	)
	(segment
		(start 197.239128 -54.183026)
		(end 197.239128 -54.531006)
		(width 0.4064)
		(layer "B.Cu")
		(net "VR_PVCCIN_CPU0_PH1_VCIN")
	)
	(segment
		(start 195.505324 -58.189876)
		(end 196.030342 -58.189876)
		(width 0.254)
		(layer "F.Cu")
		(net "VR_PVCCIN_CPU0_PH1_PHASE")
	)
	(segment
		(start 194.7672 -58.928)
		(end 195.260722 -58.434478)
		(width 0.508)
		(layer "F.Cu")
		(net "VR_PVCCIN_CPU0_PH1_PHASE")
	)
	(segment
		(start 195.260722 -58.434478)
		(end 195.505324 -58.189876)
		(width 0.254)
		(layer "F.Cu")
		(net "VR_PVCCIN_CPU0_PH1_PHASE")
	)
	(segment
		(start 192.9638 -58.928)
		(end 193.8782 -58.928)
		(width 0.508)
		(layer "F.Cu")
		(net "VR_PVCCIN_CPU0_PH1_BOOT")
	)
	(segment
		(start 192.532 -58.4962)
		(end 192.9638 -58.928)
		(width 0.508)
		(layer "F.Cu")
		(net "VR_PVCCIN_CPU0_PH1_BOOT")
	)
	(segment
		(start 192.532 -57.912)
		(end 192.532 -58.4962)
		(width 0.508)
		(layer "F.Cu")
		(net "VR_PVCCIN_CPU0_PH1_BOOT")
	)
	(via
		(at 192.9638 -58.928)
		(size 0.508)
		(drill 0.254)
		(layers "F.Cu" "B.Cu")
		(net "VR_PVCCIN_CPU0_PH1_BOOT")
	)
	(segment
		(start 183.0832 -76.3778)
		(end 183.0832 -75.565)
		(width 0.508)
		(layer "F.Cu")
		(net "VR_PVCCIN_CPU0_AVINSEN")
	)
	(segment
		(start 183.0832 -77.8002)
		(end 182.3466 -78.5368)
		(width 0.508)
		(layer "F.Cu")
		(net "VR_PVCCIN_CPU0_AVINSEN")
	)
	(segment
		(start 183.0832 -73.9648)
		(end 183.277002 -73.770998)
		(width 0.508)
		(layer "F.Cu")
		(net "VR_PVCCIN_CPU0_AVINSEN")
	)
	(segment
		(start 183.0832 -75.565)
		(end 183.0832 -73.9648)
		(width 0.508)
		(layer "F.Cu")
		(net "VR_PVCCIN_CPU0_AVINSEN")
	)
	(segment
		(start 183.277002 -73.499726)
		(end 183.277002 -72.7456)
		(width 0.1778)
		(layer "F.Cu")
		(net "VR_PVCCIN_CPU0_AVINSEN")
	)
	(segment
		(start 183.0832 -76.3778)
		(end 183.0832 -77.8002)
		(width 0.508)
		(layer "F.Cu")
		(net "VR_PVCCIN_CPU0_AVINSEN")
	)
	(segment
		(start 183.277002 -73.770998)
		(end 183.277002 -73.499726)
		(width 0.508)
		(layer "F.Cu")
		(net "VR_PVCCIN_CPU0_AVINSEN")
	)
	(segment
		(start 19.558 -72.2376)
		(end 19.558 -72.136762)
		(width 0.254)
		(layer "F.Cu")
		(net "P12V_HSC_VCC")
	)
	(segment
		(start 18.91157 -72.88403)
		(end 19.558 -72.2376)
		(width 0.254)
		(layer "F.Cu")
		(net "P12V_HSC_VCC")
	)
	(segment
		(start 18.91157 -73.3425)
		(end 18.91157 -72.88403)
		(width 0.254)
		(layer "F.Cu")
		(net "P12V_HSC_VCC")
	)
	(segment
		(start 19.5072 -72.1106)
		(end 19.584162 -72.1106)
		(width 0.254)
		(layer "F.Cu")
		(net "P12V_HSC_VCC")
	)
	(segment
		(start 18.669 -70.866)
		(end 18.669 -71.2724)
		(width 0.254)
		(layer "F.Cu")
		(net "P12V_HSC_VCC")
	)
	(segment
		(start 19.558 -72.136762)
		(end 19.584162 -72.1106)
		(width 0.254)
		(layer "F.Cu")
		(net "P12V_HSC_VCC")
	)
	(segment
		(start 18.669 -71.2724)
		(end 19.5072 -72.1106)
		(width 0.254)
		(layer "F.Cu")
		(net "P12V_HSC_VCC")
	)
	(via
		(at 19.584162 -72.1106)
		(size 0.508)
		(drill 0.254)
		(layers "F.Cu" "B.Cu")
		(net "P12V_HSC_VCC")
	)
	(segment
		(start 19.584162 -72.1106)
		(end 19.177 -71.703438)
		(width 0.254)
		(layer "B.Cu")
		(net "P12V_HSC_VCC")
	)
	(segment
		(start 19.177 -71.703438)
		(end 19.177 -70.993)
		(width 0.254)
		(layer "B.Cu")
		(net "P12V_HSC_VCC")
	)
	(segment
		(start 15.8115 -75.94219)
		(end 15.11681 -75.94219)
		(width 0.254)
		(layer "F.Cu")
		(net "A_HSC_VOUT")
	)
	(segment
		(start 14.9098 -76.1492)
		(end 14.859 -76.2)
		(width 0.254)
		(layer "F.Cu")
		(net "A_HSC_VOUT")
	)
	(segment
		(start 14.859 -76.2)
		(end 14.224 -76.2)
		(width 0.254)
		(layer "F.Cu")
		(net "A_HSC_VOUT")
	)
	(segment
		(start 15.11681 -75.94219)
		(end 14.9098 -76.1492)
		(width 0.254)
		(layer "F.Cu")
		(net "A_HSC_VOUT")
	)
	(via
		(at 15.952978 -77.570584)
		(size 0.6604)
		(drill 0.3302)
		(layers "F.Cu" "B.Cu")
		(net "A_HSC_VOUT")
	)
	(via
		(at 14.9098 -76.1492)
		(size 0.508)
		(drill 0.254)
		(layers "F.Cu" "B.Cu")
		(net "A_HSC_VOUT")
	)
	(segment
		(start 15.75308 -76.37272)
		(end 15.75308 -77.370686)
		(width 0.254)
		(layer "B.Cu")
		(net "A_HSC_VOUT")
	)
	(segment
		(start 15.75308 -77.370686)
		(end 15.952978 -77.570584)
		(width 0.254)
		(layer "B.Cu")
		(net "A_HSC_VOUT")
	)
	(segment
		(start 15.13332 -76.37272)
		(end 14.9098 -76.1492)
		(width 0.254)
		(layer "B.Cu")
		(net "A_HSC_VOUT")
	)
	(segment
		(start 15.75308 -76.37272)
		(end 15.13332 -76.37272)
		(width 0.254)
		(layer "B.Cu")
		(net "A_HSC_VOUT")
	)
	(segment
		(start 23.114 -76.327)
		(end 23.3934 -76.327)
		(width 0.254)
		(layer "F.Cu")
		(net "A_HSC_VCAP")
	)
	(segment
		(start 25.1968 -73.9648)
		(end 25.6032 -74.3712)
		(width 0.254)
		(layer "F.Cu")
		(net "A_HSC_VCAP")
	)
	(segment
		(start 23.114 -78.613)
		(end 23.114 -79.629)
		(width 0.254)
		(layer "F.Cu")
		(net "A_HSC_VCAP")
	)
	(segment
		(start 23.114 -74.2696)
		(end 23.114 -74.549)
		(width 0.254)
		(layer "F.Cu")
		(net "A_HSC_VCAP")
	)
	(segment
		(start 23.7744 -76.708)
		(end 23.7744 -77.9526)
		(width 0.254)
		(layer "F.Cu")
		(net "A_HSC_VCAP")
	)
	(segment
		(start 24.384 -73.9648)
		(end 23.984204 -74.364596)
		(width 0.254)
		(layer "F.Cu")
		(net "A_HSC_VCAP")
	)
	(segment
		(start 23.7744 -77.9526)
		(end 23.114 -78.613)
		(width 0.254)
		(layer "F.Cu")
		(net "A_HSC_VCAP")
	)
	(segment
		(start 20.88515 -74.44105)
		(end 21.2852 -74.041)
		(width 0.254)
		(layer "F.Cu")
		(net "A_HSC_VCAP")
	)
	(segment
		(start 23.984204 -74.364596)
		(end 23.984204 -74.549)
		(width 0.254)
		(layer "F.Cu")
		(net "A_HSC_VCAP")
	)
	(segment
		(start 23.114 -74.549)
		(end 23.984204 -74.549)
		(width 0.254)
		(layer "F.Cu")
		(net "A_HSC_VCAP")
	)
	(segment
		(start 24.257 -74.821796)
		(end 24.257 -75.4634)
		(width 0.254)
		(layer "F.Cu")
		(net "A_HSC_VCAP")
	)
	(segment
		(start 22.8854 -74.041)
		(end 23.114 -74.2696)
		(width 0.254)
		(layer "F.Cu")
		(net "A_HSC_VCAP")
	)
	(segment
		(start 24.384 -73.9648)
		(end 25.1968 -73.9648)
		(width 0.254)
		(layer "F.Cu")
		(net "A_HSC_VCAP")
	)
	(segment
		(start 24.257 -75.4634)
		(end 23.3934 -76.327)
		(width 0.254)
		(layer "F.Cu")
		(net "A_HSC_VCAP")
	)
	(segment
		(start 23.114 -73.406)
		(end 23.114 -74.2696)
		(width 0.254)
		(layer "F.Cu")
		(net "A_HSC_VCAP")
	)
	(segment
		(start 20.5105 -74.44105)
		(end 20.88515 -74.44105)
		(width 0.254)
		(layer "F.Cu")
		(net "A_HSC_VCAP")
	)
	(segment
		(start 23.3934 -76.327)
		(end 23.7744 -76.708)
		(width 0.254)
		(layer "F.Cu")
		(net "A_HSC_VCAP")
	)
	(segment
		(start 21.2852 -74.041)
		(end 22.8854 -74.041)
		(width 0.254)
		(layer "F.Cu")
		(net "A_HSC_VCAP")
	)
	(segment
		(start 23.984204 -74.549)
		(end 24.257 -74.821796)
		(width 0.254)
		(layer "F.Cu")
		(net "A_HSC_VCAP")
	)
	(via
		(at 25.6032 -74.3712)
		(size 0.762)
		(drill 0.381)
		(layers "F.Cu" "B.Cu")
		(net "A_HSC_VCAP")
	)
	(segment
		(start 20.447 -71.76643)
		(end 20.804124 -72.123554)
		(width 0.381)
		(layer "F.Cu")
		(net "A_HSC_UV")
	)
	(segment
		(start 20.2057 -72.7075)
		(end 20.76577 -72.14743)
		(width 0.254)
		(layer "F.Cu")
		(net "A_HSC_UV")
	)
	(segment
		(start 20.447 -70.866)
		(end 19.558 -70.866)
		(width 0.381)
		(layer "F.Cu")
		(net "A_HSC_UV")
	)
	(segment
		(start 19.41195 -73.3425)
		(end 19.41195 -72.96785)
		(width 0.254)
		(layer "F.Cu")
		(net "A_HSC_UV")
	)
	(segment
		(start 20.447 -70.866)
		(end 20.447 -71.76643)
		(width 0.381)
		(layer "F.Cu")
		(net "A_HSC_UV")
	)
	(segment
		(start 20.76577 -72.14743)
		(end 20.816824 -72.14743)
		(width 0.254)
		(layer "F.Cu")
		(net "A_HSC_UV")
	)
	(segment
		(start 19.6723 -72.7075)
		(end 20.2057 -72.7075)
		(width 0.254)
		(layer "F.Cu")
		(net "A_HSC_UV")
	)
	(segment
		(start 20.804124 -72.123554)
		(end 20.8407 -72.123554)
		(width 0.381)
		(layer "F.Cu")
		(net "A_HSC_UV")
	)
	(segment
		(start 20.816824 -72.14743)
		(end 20.8407 -72.123554)
		(width 0.254)
		(layer "F.Cu")
		(net "A_HSC_UV")
	)
	(segment
		(start 19.41195 -72.96785)
		(end 19.6723 -72.7075)
		(width 0.254)
		(layer "F.Cu")
		(net "A_HSC_UV")
	)
	(via
		(at 20.8407 -72.123554)
		(size 0.508)
		(drill 0.254)
		(layers "F.Cu" "B.Cu")
		(net "A_HSC_UV")
	)
	(segment
		(start 20.447 -71.729854)
		(end 20.447 -70.739)
		(width 0.254)
		(layer "B.Cu")
		(net "A_HSC_UV")
	)
	(segment
		(start 20.8407 -72.123554)
		(end 20.447 -71.729854)
		(width 0.254)
		(layer "B.Cu")
		(net "A_HSC_UV")
	)
	(segment
		(start 21.1455 -68.6943)
		(end 21.863812 -68.6943)
		(width 0.254)
		(layer "F.Cu")
		(net "A_HSC_TEMP")
	)
	(segment
		(start 17.5768 -69.2404)
		(end 19.1008 -69.2404)
		(width 0.254)
		(layer "F.Cu")
		(net "A_HSC_TEMP")
	)
	(segment
		(start 17.5768 -69.2404)
		(end 17.5768 -70.5358)
		(width 0.254)
		(layer "F.Cu")
		(net "A_HSC_TEMP")
	)
	(segment
		(start 20.965668 -68.514468)
		(end 21.1455 -68.6943)
		(width 0.254)
		(layer "F.Cu")
		(net "A_HSC_TEMP")
	)
	(segment
		(start 19.826732 -68.514468)
		(end 20.965668 -68.514468)
		(width 0.254)
		(layer "F.Cu")
		(net "A_HSC_TEMP")
	)
	(segment
		(start 16.6624 -71.4502)
		(end 16.6624 -71.964296)
		(width 0.254)
		(layer "F.Cu")
		(net "A_HSC_TEMP")
	)
	(segment
		(start 16.40967 -72.924924)
		(end 16.40967 -73.3425)
		(width 0.254)
		(layer "F.Cu")
		(net "A_HSC_TEMP")
	)
	(segment
		(start 22.955504 -68.6943)
		(end 23.057612 -68.796408)
		(width 0.254)
		(layer "F.Cu")
		(net "A_HSC_TEMP")
	)
	(segment
		(start 19.1008 -69.2404)
		(end 19.826732 -68.514468)
		(width 0.254)
		(layer "F.Cu")
		(net "A_HSC_TEMP")
	)
	(segment
		(start 16.6624 -71.964296)
		(end 16.2814 -72.345296)
		(width 0.254)
		(layer "F.Cu")
		(net "A_HSC_TEMP")
	)
	(segment
		(start 16.2814 -72.796654)
		(end 16.40967 -72.924924)
		(width 0.254)
		(layer "F.Cu")
		(net "A_HSC_TEMP")
	)
	(segment
		(start 21.863812 -68.6943)
		(end 22.955504 -68.6943)
		(width 0.254)
		(layer "F.Cu")
		(net "A_HSC_TEMP")
	)
	(segment
		(start 16.2814 -72.345296)
		(end 16.2814 -72.796654)
		(width 0.254)
		(layer "F.Cu")
		(net "A_HSC_TEMP")
	)
	(segment
		(start 17.5768 -70.5358)
		(end 16.6624 -71.4502)
		(width 0.254)
		(layer "F.Cu")
		(net "A_HSC_TEMP")
	)
	(via
		(at 17.5768 -69.2404)
		(size 0.762)
		(drill 0.381)
		(layers "F.Cu" "B.Cu")
		(net "A_HSC_TEMP")
	)
	(segment
		(start 15.3162 -78.2193)
		(end 14.097 -79.4385)
		(width 0.10795)
		(layer "F.Cu")
		(net "PD_HSC_RETRY_N")
	)
	(segment
		(start 15.3162 -77.724254)
		(end 15.3162 -78.2193)
		(width 0.10795)
		(layer "F.Cu")
		(net "PD_HSC_RETRY_N")
	)
	(segment
		(start 15.597124 -77.44333)
		(end 15.3162 -77.724254)
		(width 0.10795)
		(layer "F.Cu")
		(net "PD_HSC_RETRY_N")
	)
	(segment
		(start 15.8115 -77.44333)
		(end 15.597124 -77.44333)
		(width 0.10795)
		(layer "F.Cu")
		(net "PD_HSC_RETRY_N")
	)
	(segment
		(start 14.93139 -75.44181)
		(end 14.8844 -75.4888)
		(width 0.254)
		(layer "F.Cu")
		(net "A_HSC_PWGIN")
	)
	(segment
		(start 15.8115 -75.44181)
		(end 14.93139 -75.44181)
		(width 0.254)
		(layer "F.Cu")
		(net "A_HSC_PWGIN")
	)
	(via
		(at 13.080492 -75.04938)
		(size 0.6604)
		(drill 0.3302)
		(layers "F.Cu" "B.Cu")
		(net "A_HSC_PWGIN")
	)
	(via
		(at 14.8844 -75.4888)
		(size 0.508)
		(drill 0.254)
		(layers "F.Cu" "B.Cu")
		(net "A_HSC_PWGIN")
	)
	(segment
		(start 13.83411 -75.2348)
		(end 14.224 -75.2348)
		(width 0.254)
		(layer "B.Cu")
		(net "A_HSC_PWGIN")
	)
	(segment
		(start 13.64869 -75.04938)
		(end 13.83411 -75.2348)
		(width 0.254)
		(layer "B.Cu")
		(net "A_HSC_PWGIN")
	)
	(segment
		(start 15.44574 -75.35672)
		(end 15.77848 -75.35672)
		(width 0.254)
		(layer "B.Cu")
		(net "A_HSC_PWGIN")
	)
	(segment
		(start 14.224 -75.2348)
		(end 14.6304 -75.2348)
		(width 0.254)
		(layer "B.Cu")
		(net "A_HSC_PWGIN")
	)
	(segment
		(start 15.31366 -75.4888)
		(end 15.44574 -75.35672)
		(width 0.254)
		(layer "B.Cu")
		(net "A_HSC_PWGIN")
	)
	(segment
		(start 14.6304 -75.2348)
		(end 14.8844 -75.4888)
		(width 0.254)
		(layer "B.Cu")
		(net "A_HSC_PWGIN")
	)
	(segment
		(start 14.8844 -75.4888)
		(end 15.31366 -75.4888)
		(width 0.254)
		(layer "B.Cu")
		(net "A_HSC_PWGIN")
	)
	(segment
		(start 13.080492 -75.04938)
		(end 13.64869 -75.04938)
		(width 0.254)
		(layer "B.Cu")
		(net "A_HSC_PWGIN")
	)
	(segment
		(start 22.225 -73.406)
		(end 22.225 -72.4662)
		(width 0.254)
		(layer "F.Cu")
		(net "A_HSC_PSET")
	)
	(segment
		(start 20.5105 -73.94067)
		(end 21.04517 -73.406)
		(width 0.254)
		(layer "F.Cu")
		(net "A_HSC_PSET")
	)
	(segment
		(start 22.225 -72.4662)
		(end 22.225 -71.6788)
		(width 0.254)
		(layer "F.Cu")
		(net "A_HSC_PSET")
	)
	(segment
		(start 21.04517 -73.406)
		(end 21.4122 -73.406)
		(width 0.254)
		(layer "F.Cu")
		(net "A_HSC_PSET")
	)
	(segment
		(start 22.225 -73.406)
		(end 21.4122 -73.406)
		(width 0.254)
		(layer "F.Cu")
		(net "A_HSC_PSET")
	)
	(via
		(at 21.4122 -73.406)
		(size 0.508)
		(drill 0.254)
		(layers "F.Cu" "B.Cu")
		(net "A_HSC_PSET")
	)
	(segment
		(start 22.225 -70.866)
		(end 21.336 -70.866)
		(width 0.254)
		(layer "F.Cu")
		(net "A_HSC_OV")
	)
	(segment
		(start 23.2664 -70.7898)
		(end 23.1902 -70.866)
		(width 0.254)
		(layer "F.Cu")
		(net "A_HSC_OV")
	)
	(segment
		(start 20.17395 -73.08088)
		(end 20.642072 -73.08088)
		(width 0.254)
		(layer "F.Cu")
		(net "A_HSC_OV")
	)
	(segment
		(start 21.336 -72.386952)
		(end 21.336 -70.866)
		(width 0.254)
		(layer "F.Cu")
		(net "A_HSC_OV")
	)
	(segment
		(start 19.91233 -73.3425)
		(end 20.17395 -73.08088)
		(width 0.254)
		(layer "F.Cu")
		(net "A_HSC_OV")
	)
	(segment
		(start 20.642072 -73.08088)
		(end 21.336 -72.386952)
		(width 0.254)
		(layer "F.Cu")
		(net "A_HSC_OV")
	)
	(segment
		(start 23.1902 -70.866)
		(end 22.225 -70.866)
		(width 0.254)
		(layer "F.Cu")
		(net "A_HSC_OV")
	)
	(via
		(at 23.2664 -70.7898)
		(size 0.508)
		(drill 0.254)
		(layers "F.Cu" "B.Cu")
		(net "A_HSC_OV")
	)
	(segment
		(start 23.220934 -70.744334)
		(end 21.722334 -70.744334)
		(width 0.254)
		(layer "B.Cu")
		(net "A_HSC_OV")
	)
	(segment
		(start 21.722334 -70.744334)
		(end 21.717 -70.739)
		(width 0.254)
		(layer "B.Cu")
		(net "A_HSC_OV")
	)
	(segment
		(start 23.2664 -70.7898)
		(end 23.220934 -70.744334)
		(width 0.254)
		(layer "B.Cu")
		(net "A_HSC_OV")
	)
	(segment
		(start 14.9098 -71.8693)
		(end 14.986 -71.7931)
		(width 0.381)
		(layer "F.Cu")
		(net "A_HSC_MOP")
	)
	(segment
		(start 14.859 -71.247)
		(end 14.986 -71.247)
		(width 0.381)
		(layer "F.Cu")
		(net "A_HSC_MOP")
	)
	(segment
		(start 14.224 -70.612)
		(end 14.859 -71.247)
		(width 0.381)
		(layer "F.Cu")
		(net "A_HSC_MOP")
	)
	(segment
		(start 14.9098 -71.882)
		(end 14.9098 -71.8693)
		(width 0.381)
		(layer "F.Cu")
		(net "A_HSC_MOP")
	)
	(segment
		(start 14.224 -69.977)
		(end 14.224 -70.612)
		(width 0.381)
		(layer "F.Cu")
		(net "A_HSC_MOP")
	)
	(segment
		(start 14.986 -71.7931)
		(end 14.986 -71.247)
		(width 0.381)
		(layer "F.Cu")
		(net "A_HSC_MOP")
	)
	(segment
		(start 18.41119 -73.3425)
		(end 18.41119 -72.470518)
		(width 0.254)
		(layer "F.Cu")
		(net "A_HSC_MOP")
	)
	(segment
		(start 18.41119 -72.470518)
		(end 18.517616 -72.364092)
		(width 0.254)
		(layer "F.Cu")
		(net "A_HSC_MOP")
	)
	(via
		(at 14.9098 -71.882)
		(size 0.508)
		(drill 0.254)
		(layers "F.Cu" "B.Cu")
		(net "A_HSC_MOP")
	)
	(via
		(at 18.517616 -72.364092)
		(size 0.508)
		(drill 0.254)
		(layers "F.Cu" "B.Cu")
		(net "A_HSC_MOP")
	)
	(segment
		(start 18.415508 -72.4662)
		(end 18.517616 -72.364092)
		(width 0.381)
		(layer "B.Cu")
		(net "A_HSC_MOP")
	)
	(segment
		(start 16.7894 -71.758048)
		(end 16.7894 -71.754746)
		(width 0.381)
		(layer "B.Cu")
		(net "A_HSC_MOP")
	)
	(segment
		(start 15.377922 -71.2343)
		(end 14.9098 -71.702422)
		(width 0.381)
		(layer "B.Cu")
		(net "A_HSC_MOP")
	)
	(segment
		(start 17.497552 -72.4662)
		(end 16.7894 -71.758048)
		(width 0.381)
		(layer "B.Cu")
		(net "A_HSC_MOP")
	)
	(segment
		(start 18.415508 -72.4662)
		(end 17.497552 -72.4662)
		(width 0.381)
		(layer "B.Cu")
		(net "A_HSC_MOP")
	)
	(segment
		(start 14.9098 -71.702422)
		(end 14.9098 -71.882)
		(width 0.381)
		(layer "B.Cu")
		(net "A_HSC_MOP")
	)
	(segment
		(start 18.415 -72.466708)
		(end 18.415508 -72.4662)
		(width 0.381)
		(layer "B.Cu")
		(net "A_HSC_MOP")
	)
	(segment
		(start 18.415 -73.406)
		(end 18.415 -72.466708)
		(width 0.381)
		(layer "B.Cu")
		(net "A_HSC_MOP")
	)
	(segment
		(start 16.7894 -71.754746)
		(end 16.268954 -71.2343)
		(width 0.381)
		(layer "B.Cu")
		(net "A_HSC_MOP")
	)
	(segment
		(start 16.268954 -71.2343)
		(end 15.377922 -71.2343)
		(width 0.381)
		(layer "B.Cu")
		(net "A_HSC_MOP")
	)
	(segment
		(start 16.049752 -71.247)
		(end 15.875 -71.247)
		(width 0.381)
		(layer "F.Cu")
		(net "A_HSC_MON")
	)
	(segment
		(start 16.91005 -72.67575)
		(end 16.8402 -72.6059)
		(width 0.254)
		(layer "F.Cu")
		(net "A_HSC_MON")
	)
	(segment
		(start 15.77213 -71.75627)
		(end 15.875 -71.6534)
		(width 0.381)
		(layer "F.Cu")
		(net "A_HSC_MON")
	)
	(segment
		(start 15.65275 -71.933054)
		(end 15.77213 -71.813674)
		(width 0.381)
		(layer "F.Cu")
		(net "A_HSC_MON")
	)
	(segment
		(start 16.764 -70.532752)
		(end 16.049752 -71.247)
		(width 0.381)
		(layer "F.Cu")
		(net "A_HSC_MON")
	)
	(segment
		(start 15.875 -71.6534)
		(end 15.875 -71.247)
		(width 0.381)
		(layer "F.Cu")
		(net "A_HSC_MON")
	)
	(segment
		(start 16.764 -69.977)
		(end 16.764 -70.532752)
		(width 0.381)
		(layer "F.Cu")
		(net "A_HSC_MON")
	)
	(segment
		(start 15.77213 -71.813674)
		(end 15.77213 -71.75627)
		(width 0.381)
		(layer "F.Cu")
		(net "A_HSC_MON")
	)
	(segment
		(start 16.91005 -73.3425)
		(end 16.91005 -72.67575)
		(width 0.254)
		(layer "F.Cu")
		(net "A_HSC_MON")
	)
	(via
		(at 16.8402 -72.6059)
		(size 0.508)
		(drill 0.254)
		(layers "F.Cu" "B.Cu")
		(net "A_HSC_MON")
	)
	(via
		(at 15.65275 -71.933054)
		(size 0.508)
		(drill 0.254)
		(layers "F.Cu" "B.Cu")
		(net "A_HSC_MON")
	)
	(segment
		(start 16.8402 -72.6186)
		(end 16.8402 -72.6059)
		(width 0.381)
		(layer "B.Cu")
		(net "A_HSC_MON")
	)
	(segment
		(start 16.8275 -72.6059)
		(end 16.8402 -72.6059)
		(width 0.381)
		(layer "B.Cu")
		(net "A_HSC_MON")
	)
	(segment
		(start 15.65275 -71.933054)
		(end 16.154654 -71.933054)
		(width 0.381)
		(layer "B.Cu")
		(net "A_HSC_MON")
	)
	(segment
		(start 17.526 -73.3044)
		(end 16.8402 -72.6186)
		(width 0.381)
		(layer "B.Cu")
		(net "A_HSC_MON")
	)
	(segment
		(start 16.154654 -71.933054)
		(end 16.8275 -72.6059)
		(width 0.381)
		(layer "B.Cu")
		(net "A_HSC_MON")
	)
	(segment
		(start 17.526 -73.406)
		(end 17.526 -73.3044)
		(width 0.381)
		(layer "B.Cu")
		(net "A_HSC_MON")
	)
	(segment
		(start 22.225 -75.438)
		(end 22.22119 -75.44181)
		(width 0.254)
		(layer "F.Cu")
		(net "A_HSC_ISTART")
	)
	(segment
		(start 22.22119 -75.44181)
		(end 20.5105 -75.44181)
		(width 0.254)
		(layer "F.Cu")
		(net "A_HSC_ISTART")
	)
	(segment
		(start 22.225 -75.438)
		(end 22.225 -76.327)
		(width 0.254)
		(layer "F.Cu")
		(net "A_HSC_ISTART")
	)
	(segment
		(start 10.3632 -70.8152)
		(end 9.398 -69.85)
		(width 0.4064)
		(layer "F.Cu")
		(net "A_HSC_HSP")
	)
	(segment
		(start 9.398 -69.760338)
		(end 9.398 -68.9483)
		(width 0.381)
		(layer "F.Cu")
		(net "A_HSC_HSP")
	)
	(segment
		(start 9.398 -69.85)
		(end 9.398 -69.760338)
		(width 0.4064)
		(layer "F.Cu")
		(net "A_HSC_HSP")
	)
	(segment
		(start 11.6586 -70.7898)
		(end 11.6332 -70.8152)
		(width 0.381)
		(layer "F.Cu")
		(net "A_HSC_HSP")
	)
	(segment
		(start 15.113 -69.977)
		(end 15.113 -69.5198)
		(width 0.4064)
		(layer "F.Cu")
		(net "A_HSC_HSP")
	)
	(segment
		(start 11.6332 -70.8152)
		(end 10.3632 -70.8152)
		(width 0.4064)
		(layer "F.Cu")
		(net "A_HSC_HSP")
	)
	(segment
		(start 13.3096 -69.1388)
		(end 11.6586 -70.7898)
		(width 0.4064)
		(layer "F.Cu")
		(net "A_HSC_HSP")
	)
	(segment
		(start 17.91081 -71.62419)
		(end 18.0086 -71.5264)
		(width 0.254)
		(layer "F.Cu")
		(net "A_HSC_HSP")
	)
	(segment
		(start 17.91081 -73.3425)
		(end 17.91081 -71.62419)
		(width 0.254)
		(layer "F.Cu")
		(net "A_HSC_HSP")
	)
	(segment
		(start 15.113 -69.5198)
		(end 14.732 -69.1388)
		(width 0.4064)
		(layer "F.Cu")
		(net "A_HSC_HSP")
	)
	(segment
		(start 15.113 -69.977)
		(end 15.113 -70.612)
		(width 0.381)
		(layer "F.Cu")
		(net "A_HSC_HSP")
	)
	(segment
		(start 14.732 -69.1388)
		(end 13.3096 -69.1388)
		(width 0.4064)
		(layer "F.Cu")
		(net "A_HSC_HSP")
	)
	(via
		(at 18.0086 -71.5264)
		(size 0.508)
		(drill 0.254)
		(layers "F.Cu" "B.Cu")
		(net "A_HSC_HSP")
	)
	(via
		(at 15.113 -70.612)
		(size 0.508)
		(drill 0.254)
		(layers "F.Cu" "B.Cu")
		(net "A_HSC_HSP")
	)
	(via
		(at 15.5448 -69.6722)
		(size 0.508)
		(drill 0.254)
		(layers "F.Cu" "B.Cu")
		(net "A_HSC_HSP")
	)
	(via
		(at 9.398 -69.85)
		(size 0.508)
		(drill 0.254)
		(layers "F.Cu" "B.Cu")
		(net "A_HSC_HSP")
	)
	(segment
		(start 15.875 -69.342)
		(end 15.5448 -69.6722)
		(width 0.381)
		(layer "B.Cu")
		(net "A_HSC_HSP")
	)
	(segment
		(start 15.113 -70.104)
		(end 15.5448 -69.6722)
		(width 0.381)
		(layer "B.Cu")
		(net "A_HSC_HSP")
	)
	(segment
		(start 16.9164 -69.342)
		(end 15.875 -69.342)
		(width 0.381)
		(layer "B.Cu")
		(net "A_HSC_HSP")
	)
	(segment
		(start 18.0086 -71.5264)
		(end 17.9578 -71.4756)
		(width 0.381)
		(layer "B.Cu")
		(net "A_HSC_HSP")
	)
	(segment
		(start 15.113 -70.612)
		(end 15.113 -70.104)
		(width 0.381)
		(layer "B.Cu")
		(net "A_HSC_HSP")
	)
	(segment
		(start 17.9578 -70.3834)
		(end 16.9164 -69.342)
		(width 0.381)
		(layer "B.Cu")
		(net "A_HSC_HSP")
	)
	(segment
		(start 9.398 -69.85)
		(end 9.398 -68.9356)
		(width 0.381)
		(layer "B.Cu")
		(net "A_HSC_HSP")
	)
	(segment
		(start 17.9578 -71.4756)
		(end 17.9578 -70.3834)
		(width 0.381)
		(layer "B.Cu")
		(net "A_HSC_HSP")
	)
	(segment
		(start 13.0302 -68.58)
		(end 15.0622 -68.58)
		(width 0.4064)
		(layer "F.Cu")
		(net "A_HSC_HSN")
	)
	(segment
		(start 11.4046 -70.2056)
		(end 13.0302 -68.58)
		(width 0.4064)
		(layer "F.Cu")
		(net "A_HSC_HSN")
	)
	(segment
		(start 15.0622 -68.58)
		(end 15.875 -69.3928)
		(width 0.4064)
		(layer "F.Cu")
		(net "A_HSC_HSN")
	)
	(segment
		(start 10.859262 -70.2056)
		(end 11.4046 -70.2056)
		(width 0.4064)
		(layer "F.Cu")
		(net "A_HSC_HSN")
	)
	(segment
		(start 17.41043 -73.3425)
		(end 17.41043 -71.58863)
		(width 0.254)
		(layer "F.Cu")
		(net "A_HSC_HSN")
	)
	(segment
		(start 10.414 -69.760338)
		(end 10.859262 -70.2056)
		(width 0.4064)
		(layer "F.Cu")
		(net "A_HSC_HSN")
	)
	(segment
		(start 15.875 -70.485)
		(end 15.748 -70.612)
		(width 0.381)
		(layer "F.Cu")
		(net "A_HSC_HSN")
	)
	(segment
		(start 15.875 -69.977)
		(end 15.875 -70.485)
		(width 0.381)
		(layer "F.Cu")
		(net "A_HSC_HSN")
	)
	(segment
		(start 15.875 -69.3928)
		(end 15.875 -69.977)
		(width 0.4064)
		(layer "F.Cu")
		(net "A_HSC_HSN")
	)
	(segment
		(start 10.414 -68.9483)
		(end 10.414 -69.760338)
		(width 0.381)
		(layer "F.Cu")
		(net "A_HSC_HSN")
	)
	(segment
		(start 17.41043 -71.58863)
		(end 17.3482 -71.5264)
		(width 0.254)
		(layer "F.Cu")
		(net "A_HSC_HSN")
	)
	(via
		(at 15.748 -70.612)
		(size 0.508)
		(drill 0.254)
		(layers "F.Cu" "B.Cu")
		(net "A_HSC_HSN")
	)
	(via
		(at 17.3482 -71.5264)
		(size 0.508)
		(drill 0.254)
		(layers "F.Cu" "B.Cu")
		(net "A_HSC_HSN")
	)
	(via
		(at 17.145 -70.3072)
		(size 0.508)
		(drill 0.254)
		(layers "F.Cu" "B.Cu")
		(net "A_HSC_HSN")
	)
	(via
		(at 10.414 -69.760338)
		(size 0.508)
		(drill 0.254)
		(layers "F.Cu" "B.Cu")
		(net "A_HSC_HSN")
	)
	(segment
		(start 15.748 -70.3072)
		(end 16.0782 -69.977)
		(width 0.381)
		(layer "B.Cu")
		(net "A_HSC_HSN")
	)
	(segment
		(start 10.414 -69.760338)
		(end 10.414 -68.9356)
		(width 0.381)
		(layer "B.Cu")
		(net "A_HSC_HSN")
	)
	(segment
		(start 16.0782 -69.977)
		(end 16.8148 -69.977)
		(width 0.381)
		(layer "B.Cu")
		(net "A_HSC_HSN")
	)
	(segment
		(start 17.3482 -71.5264)
		(end 17.4498 -71.4248)
		(width 0.381)
		(layer "B.Cu")
		(net "A_HSC_HSN")
	)
	(segment
		(start 16.8148 -69.977)
		(end 17.145 -70.3072)
		(width 0.381)
		(layer "B.Cu")
		(net "A_HSC_HSN")
	)
	(segment
		(start 15.748 -70.612)
		(end 15.748 -70.3072)
		(width 0.381)
		(layer "B.Cu")
		(net "A_HSC_HSN")
	)
	(segment
		(start 17.4498 -70.612)
		(end 17.145 -70.3072)
		(width 0.381)
		(layer "B.Cu")
		(net "A_HSC_HSN")
	)
	(segment
		(start 17.4498 -71.4248)
		(end 17.4498 -70.612)
		(width 0.381)
		(layer "B.Cu")
		(net "A_HSC_HSN")
	)
	(segment
		(start 21.082 -66.7258)
		(end 22.74316 -66.7258)
		(width 0.4064)
		(layer "F.Cu")
		(net "A_HSC_GATE3_R")
	)
	(segment
		(start 22.74316 -66.7258)
		(end 22.84476 -66.6242)
		(width 0.4064)
		(layer "F.Cu")
		(net "A_HSC_GATE3_R")
	)
	(segment
		(start 22.84476 -66.6242)
		(end 22.87016 -66.6242)
		(width 0.4064)
		(layer "F.Cu")
		(net "A_HSC_GATE3_R")
	)
	(segment
		(start 22.87016 -66.6242)
		(end 23.7998 -66.6242)
		(width 0.4064)
		(layer "F.Cu")
		(net "A_HSC_GATE3_R")
	)
	(via
		(at 22.87016 -66.6242)
		(size 0.762)
		(drill 0.381)
		(layers "F.Cu" "B.Cu")
		(net "A_HSC_GATE3_R")
	)
	(via
		(at 22.9362 -56.9976)
		(size 0.6604)
		(drill 0.3302)
		(layers "F.Cu" "B.Cu")
		(net "A_HSC_GATE2_R")
	)
	(segment
		(start 23.5966 -56.9976)
		(end 22.9362 -56.9976)
		(width 0.4064)
		(layer "B.Cu")
		(net "A_HSC_GATE2_R")
	)
	(segment
		(start 23.749 -56.8452)
		(end 23.5966 -56.9976)
		(width 0.4064)
		(layer "B.Cu")
		(net "A_HSC_GATE2_R")
	)
	(segment
		(start 21.9964 -56.9976)
		(end 21.8948 -57.0992)
		(width 0.4064)
		(layer "B.Cu")
		(net "A_HSC_GATE2_R")
	)
	(segment
		(start 22.9362 -56.9976)
		(end 21.9964 -56.9976)
		(width 0.4064)
		(layer "B.Cu")
		(net "A_HSC_GATE2_R")
	)
	(segment
		(start 21.8948 -57.0992)
		(end 21.209 -57.0992)
		(width 0.4064)
		(layer "B.Cu")
		(net "A_HSC_GATE2_R")
	)
	(segment
		(start 21.222462 -60.9092)
		(end 22.962108 -60.9092)
		(width 0.4064)
		(layer "F.Cu")
		(net "A_HSC_GATE1_R")
	)
	(segment
		(start 22.962108 -60.9092)
		(end 23.001732 -60.948824)
		(width 0.4064)
		(layer "F.Cu")
		(net "A_HSC_GATE1_R")
	)
	(segment
		(start 23.089108 -61.0362)
		(end 23.839932 -61.0362)
		(width 0.4064)
		(layer "F.Cu")
		(net "A_HSC_GATE1_R")
	)
	(segment
		(start 23.001732 -60.948824)
		(end 23.089108 -61.0362)
		(width 0.4064)
		(layer "F.Cu")
		(net "A_HSC_GATE1_R")
	)
	(via
		(at 23.001732 -60.948824)
		(size 0.762)
		(drill 0.381)
		(layers "F.Cu" "B.Cu")
		(net "A_HSC_GATE1_R")
	)
	(segment
		(start 24.6888 -66.6242)
		(end 24.6888 -67.31)
		(width 0.4064)
		(layer "F.Cu")
		(net "A_HSC_GATE")
	)
	(segment
		(start 25.937972 -67.35572)
		(end 26.2255 -67.35572)
		(width 0.4064)
		(layer "F.Cu")
		(net "A_HSC_GATE")
	)
	(segment
		(start 15.7226 -73.4568)
		(end 15.7226 -72.6948)
		(width 0.381)
		(layer "F.Cu")
		(net "A_HSC_GATE")
	)
	(segment
		(start 15.8115 -73.94067)
		(end 15.7226 -73.85177)
		(width 0.254)
		(layer "F.Cu")
		(net "A_HSC_GATE")
	)
	(segment
		(start 25.338532 -61.0362)
		(end 24.728932 -61.0362)
		(width 0.4064)
		(layer "F.Cu")
		(net "A_HSC_GATE")
	)
	(segment
		(start 15.7226 -73.85177)
		(end 15.7226 -73.4568)
		(width 0.254)
		(layer "F.Cu")
		(net "A_HSC_GATE")
	)
	(segment
		(start 25.206452 -66.6242)
		(end 25.937972 -67.35572)
		(width 0.4064)
		(layer "F.Cu")
		(net "A_HSC_GATE")
	)
	(segment
		(start 24.6888 -66.6242)
		(end 25.206452 -66.6242)
		(width 0.4064)
		(layer "F.Cu")
		(net "A_HSC_GATE")
	)
	(via
		(at 25.338532 -61.0362)
		(size 0.508)
		(drill 0.254)
		(layers "F.Cu" "B.Cu")
		(net "A_HSC_GATE")
	)
	(via
		(at 15.7226 -72.6948)
		(size 0.508)
		(drill 0.254)
		(layers "F.Cu" "B.Cu")
		(net "A_HSC_GATE")
	)
	(via
		(at 24.6888 -67.31)
		(size 0.508)
		(drill 0.254)
		(layers "F.Cu" "B.Cu")
		(net "A_HSC_GATE")
	)
	(via
		(at 25.273 -56.8452)
		(size 0.508)
		(drill 0.254)
		(layers "F.Cu" "B.Cu")
		(net "A_HSC_GATE")
	)
	(segment
		(start 24.638 -56.8452)
		(end 25.273 -56.8452)
		(width 0.4064)
		(layer "B.Cu")
		(net "A_HSC_GATE")
	)
	(segment
		(start 26.23312 -67.31)
		(end 24.6888 -67.31)
		(width 0.508)
		(layer "In9.Cu")
		(net "A_HSC_GATE")
	)
	(segment
		(start 21.39569 -70.60311)
		(end 17.003014 -70.60311)
		(width 0.508)
		(layer "In9.Cu")
		(net "A_HSC_GATE")
	)
	(segment
		(start 16.495014 -71.11111)
		(end 16.495014 -72.023986)
		(width 0.508)
		(layer "In9.Cu")
		(net "A_HSC_GATE")
	)
	(segment
		(start 26.7716 -66.77152)
		(end 26.23312 -67.31)
		(width 0.508)
		(layer "In9.Cu")
		(net "A_HSC_GATE")
	)
	(segment
		(start 27.041856 -59.332876)
		(end 27.041856 -58.614056)
		(width 0.508)
		(layer "In9.Cu")
		(net "A_HSC_GATE")
	)
	(segment
		(start 26.7716 -62.469268)
		(end 26.7716 -66.77152)
		(width 0.508)
		(layer "In9.Cu")
		(net "A_HSC_GATE")
	)
	(segment
		(start 24.6888 -67.31)
		(end 21.39569 -70.60311)
		(width 0.508)
		(layer "In9.Cu")
		(net "A_HSC_GATE")
	)
	(segment
		(start 25.338532 -61.0362)
		(end 26.7716 -62.469268)
		(width 0.508)
		(layer "In9.Cu")
		(net "A_HSC_GATE")
	)
	(segment
		(start 15.8242 -72.6948)
		(end 15.7226 -72.6948)
		(width 0.508)
		(layer "In9.Cu")
		(net "A_HSC_GATE")
	)
	(segment
		(start 17.003014 -70.60311)
		(end 16.495014 -71.11111)
		(width 0.508)
		(layer "In9.Cu")
		(net "A_HSC_GATE")
	)
	(segment
		(start 25.338532 -61.0362)
		(end 27.041856 -59.332876)
		(width 0.508)
		(layer "In9.Cu")
		(net "A_HSC_GATE")
	)
	(segment
		(start 16.495014 -72.023986)
		(end 15.8242 -72.6948)
		(width 0.508)
		(layer "In9.Cu")
		(net "A_HSC_GATE")
	)
	(segment
		(start 27.041856 -58.614056)
		(end 25.273 -56.8452)
		(width 0.508)
		(layer "In9.Cu")
		(net "A_HSC_GATE")
	)
	(segment
		(start 20.707858 -77.44333)
		(end 20.9804 -77.715872)
		(width 0.10795)
		(layer "F.Cu")
		(net "FM_P12V_HSC_ADR2")
	)
	(segment
		(start 20.5105 -77.44333)
		(end 20.707858 -77.44333)
		(width 0.10795)
		(layer "F.Cu")
		(net "FM_P12V_HSC_ADR2")
	)
	(segment
		(start 20.9804 -77.715872)
		(end 20.9804 -78.486)
		(width 0.10795)
		(layer "F.Cu")
		(net "FM_P12V_HSC_ADR2")
	)
	(segment
		(start 20.9804 -78.486)
		(end 21.4122 -78.9178)
		(width 0.10795)
		(layer "F.Cu")
		(net "FM_P12V_HSC_ADR2")
	)
	(segment
		(start 22.225 -79.629)
		(end 21.5138 -78.9178)
		(width 0.10795)
		(layer "F.Cu")
		(net "FM_P12V_HSC_ADR2")
	)
	(segment
		(start 21.5138 -78.9178)
		(end 21.4122 -78.9178)
		(width 0.10795)
		(layer "F.Cu")
		(net "FM_P12V_HSC_ADR2")
	)
	(via
		(at 21.4122 -78.9178)
		(size 0.508)
		(drill 0.254)
		(layers "F.Cu" "B.Cu")
		(net "FM_P12V_HSC_ADR2")
	)
	(segment
		(start 20.3454 -78.0542)
		(end 20.5486 -78.0542)
		(width 0.10795)
		(layer "B.Cu")
		(net "FM_P12V_HSC_ADR2")
	)
	(segment
		(start 20.5486 -78.0542)
		(end 21.4122 -78.9178)
		(width 0.10795)
		(layer "B.Cu")
		(net "FM_P12V_HSC_ADR2")
	)
	(segment
		(start 20.83435 -76.94295)
		(end 21.4122 -77.5208)
		(width 0.10795)
		(layer "F.Cu")
		(net "FM_P12V_HSC_ADR1")
	)
	(segment
		(start 22.225 -78.613)
		(end 21.7932 -78.1812)
		(width 0.10795)
		(layer "F.Cu")
		(net "FM_P12V_HSC_ADR1")
	)
	(segment
		(start 21.7932 -78.0288)
		(end 21.4122 -77.6478)
		(width 0.10795)
		(layer "F.Cu")
		(net "FM_P12V_HSC_ADR1")
	)
	(segment
		(start 20.5105 -76.94295)
		(end 20.83435 -76.94295)
		(width 0.10795)
		(layer "F.Cu")
		(net "FM_P12V_HSC_ADR1")
	)
	(segment
		(start 21.7932 -78.1812)
		(end 21.7932 -78.0288)
		(width 0.10795)
		(layer "F.Cu")
		(net "FM_P12V_HSC_ADR1")
	)
	(segment
		(start 21.4122 -77.5208)
		(end 21.4122 -77.6478)
		(width 0.10795)
		(layer "F.Cu")
		(net "FM_P12V_HSC_ADR1")
	)
	(via
		(at 21.4122 -77.6478)
		(size 0.508)
		(drill 0.254)
		(layers "F.Cu" "B.Cu")
		(net "FM_P12V_HSC_ADR1")
	)
	(segment
		(start 22.606 -77.724)
		(end 21.4884 -77.724)
		(width 0.10795)
		(layer "B.Cu")
		(net "FM_P12V_HSC_ADR1")
	)
	(segment
		(start 21.4884 -77.724)
		(end 21.4122 -77.6478)
		(width 0.10795)
		(layer "B.Cu")
		(net "FM_P12V_HSC_ADR1")
	)
	(via
		(at -2.536698 -12.928346)
		(size 0.508)
		(drill 0.254)
		(layers "F.Cu" "B.Cu")
		(net "VR_FET_SW_P12V_STBY_PVDDQ_GHJ")
	)
	(via
		(at -0.48768 -12.01166)
		(size 0.508)
		(drill 0.254)
		(layers "F.Cu" "B.Cu")
		(net "VR_FET_SW_P12V_STBY_PVDDQ_GHJ")
	)
	(via
		(at -1.52654 -15.50162)
		(size 0.508)
		(drill 0.254)
		(layers "F.Cu" "B.Cu")
		(net "VR_FET_SW_P12V_STBY_PVDDQ_GHJ")
	)
	(via
		(at 3.55854 -12.59078)
		(size 0.508)
		(drill 0.254)
		(layers "F.Cu" "B.Cu")
		(net "VR_FET_SW_P12V_STBY_PVDDQ_GHJ")
	)
	(via
		(at 2.34315 -21.454618)
		(size 0.508)
		(drill 0.254)
		(layers "F.Cu" "B.Cu")
		(net "VR_FET_SW_P12V_STBY_PVDDQ_GHJ")
	)
	(via
		(at 2.39395 -22.369018)
		(size 0.508)
		(drill 0.254)
		(layers "F.Cu" "B.Cu")
		(net "VR_FET_SW_P12V_STBY_PVDDQ_GHJ")
	)
	(via
		(at -2.38506 -17.12214)
		(size 0.508)
		(drill 0.254)
		(layers "F.Cu" "B.Cu")
		(net "VR_FET_SW_P12V_STBY_PVDDQ_GHJ")
	)
	(via
		(at 2.31775 -20.641818)
		(size 0.508)
		(drill 0.254)
		(layers "F.Cu" "B.Cu")
		(net "VR_FET_SW_P12V_STBY_PVDDQ_GHJ")
	)
	(via
		(at -0.90424 -8.79348)
		(size 0.508)
		(drill 0.254)
		(layers "F.Cu" "B.Cu")
		(net "VR_FET_SW_P12V_STBY_PVDDQ_GHJ")
	)
	(via
		(at -2.65938 -16.3703)
		(size 0.508)
		(drill 0.254)
		(layers "F.Cu" "B.Cu")
		(net "VR_FET_SW_P12V_STBY_PVDDQ_GHJ")
	)
	(via
		(at 0.882396 -12.337288)
		(size 0.6604)
		(drill 0.3302)
		(layers "F.Cu" "B.Cu")
		(net "VR_FET_SW_P12V_STBY_PVDDQ_GHJ")
	)
	(via
		(at -3.45694 -16.34744)
		(size 0.508)
		(drill 0.254)
		(layers "F.Cu" "B.Cu")
		(net "VR_FET_SW_P12V_STBY_PVDDQ_GHJ")
	)
	(via
		(at -1.7907 -12.9286)
		(size 0.508)
		(drill 0.254)
		(layers "F.Cu" "B.Cu")
		(net "VR_FET_SW_P12V_STBY_PVDDQ_GHJ")
	)
	(via
		(at 1.651 -21.4376)
		(size 0.508)
		(drill 0.254)
		(layers "F.Cu" "B.Cu")
		(net "VR_FET_SW_P12V_STBY_PVDDQ_GHJ")
	)
	(via
		(at -0.4445 -11.00328)
		(size 0.508)
		(drill 0.254)
		(layers "F.Cu" "B.Cu")
		(net "VR_FET_SW_P12V_STBY_PVDDQ_GHJ")
	)
	(via
		(at 0.510032 -20.141692)
		(size 0.6604)
		(drill 0.3302)
		(layers "F.Cu" "B.Cu")
		(net "VR_FET_SW_P12V_STBY_PVDDQ_GHJ")
	)
	(via
		(at 3.013456 -18.108676)
		(size 0.508)
		(drill 0.254)
		(layers "F.Cu" "B.Cu")
		(net "VR_FET_SW_P12V_STBY_PVDDQ_GHJ")
	)
	(via
		(at -2.18694 -15.19174)
		(size 0.508)
		(drill 0.254)
		(layers "F.Cu" "B.Cu")
		(net "VR_FET_SW_P12V_STBY_PVDDQ_GHJ")
	)
	(via
		(at 2.97815 -21.454618)
		(size 0.508)
		(drill 0.254)
		(layers "F.Cu" "B.Cu")
		(net "VR_FET_SW_P12V_STBY_PVDDQ_GHJ")
	)
	(via
		(at 1.6764 -22.3266)
		(size 0.508)
		(drill 0.254)
		(layers "F.Cu" "B.Cu")
		(net "VR_FET_SW_P12V_STBY_PVDDQ_GHJ")
	)
	(via
		(at 2.930906 -11.970258)
		(size 0.508)
		(drill 0.254)
		(layers "F.Cu" "B.Cu")
		(net "VR_FET_SW_P12V_STBY_PVDDQ_GHJ")
	)
	(via
		(at 3.02895 -22.369018)
		(size 0.508)
		(drill 0.254)
		(layers "F.Cu" "B.Cu")
		(net "VR_FET_SW_P12V_STBY_PVDDQ_GHJ")
	)
	(via
		(at 2.2098 -12.6238)
		(size 0.508)
		(drill 0.254)
		(layers "F.Cu" "B.Cu")
		(net "VR_FET_SW_P12V_STBY_PVDDQ_GHJ")
	)
	(via
		(at 3.013456 -19.937476)
		(size 0.508)
		(drill 0.254)
		(layers "F.Cu" "B.Cu")
		(net "VR_FET_SW_P12V_STBY_PVDDQ_GHJ")
	)
	(via
		(at 3.02895 -19.016218)
		(size 0.508)
		(drill 0.254)
		(layers "F.Cu" "B.Cu")
		(net "VR_FET_SW_P12V_STBY_PVDDQ_GHJ")
	)
	(via
		(at 1.397 -19.670776)
		(size 0.508)
		(drill 0.254)
		(layers "F.Cu" "B.Cu")
		(net "VR_FET_SW_P12V_STBY_PVDDQ_GHJ")
	)
	(via
		(at 2.921 -11.0236)
		(size 0.508)
		(drill 0.254)
		(layers "F.Cu" "B.Cu")
		(net "VR_FET_SW_P12V_STBY_PVDDQ_GHJ")
	)
	(via
		(at 2.8448 -12.5984)
		(size 0.508)
		(drill 0.254)
		(layers "F.Cu" "B.Cu")
		(net "VR_FET_SW_P12V_STBY_PVDDQ_GHJ")
	)
	(via
		(at 2.930906 -10.141458)
		(size 0.508)
		(drill 0.254)
		(layers "F.Cu" "B.Cu")
		(net "VR_FET_SW_P12V_STBY_PVDDQ_GHJ")
	)
	(via
		(at -2.7559 -7.8232)
		(size 0.508)
		(drill 0.254)
		(layers "F.Cu" "B.Cu")
		(net "VR_FET_SW_P12V_STBY_PVDDQ_GHJ")
	)
	(via
		(at -2.12598 -15.9004)
		(size 0.508)
		(drill 0.254)
		(layers "F.Cu" "B.Cu")
		(net "VR_FET_SW_P12V_STBY_PVDDQ_GHJ")
	)
	(via
		(at 1.4224 -20.432776)
		(size 0.508)
		(drill 0.254)
		(layers "F.Cu" "B.Cu")
		(net "VR_FET_SW_P12V_STBY_PVDDQ_GHJ")
	)
	(via
		(at 2.95275 -20.641818)
		(size 0.508)
		(drill 0.254)
		(layers "F.Cu" "B.Cu")
		(net "VR_FET_SW_P12V_STBY_PVDDQ_GHJ")
	)
	(segment
		(start 395.224 -118.46687)
		(end 395.658848 -118.6688)
		(width 0.10795)
		(layer "F.Cu")
		(net "TP_USB3_P04_TXP")
	)
	(segment
		(start 395.16685 -118.4402)
		(end 395.224 -118.46687)
		(width 0.10795)
		(layer "F.Cu")
		(net "TP_USB3_P04_TXP")
	)
	(segment
		(start 395.658848 -118.6688)
		(end 395.66215 -118.670324)
		(width 0.10795)
		(layer "F.Cu")
		(net "TP_USB3_P04_TXP")
	)
	(via
		(at 395.66215 -118.670324)
		(size 0.508)
		(drill 0.254)
		(layers "F.Cu" "B.Cu")
		(net "TP_USB3_P04_TXP")
	)
	(segment
		(start 395.66215 -119.29872)
		(end 396.15745 -119.528844)
		(width 0.10795)
		(layer "F.Cu")
		(net "TP_USB3_P04_TXN")
	)
	(via
		(at 396.15745 -119.528844)
		(size 0.508)
		(drill 0.254)
		(layers "F.Cu" "B.Cu")
		(net "TP_USB3_P04_TXN")
	)
	(segment
		(start 255.92913 -87.784686)
		(end 255.35763 -87.784686)
		(width 0.10795)
		(layer "F.Cu")
		(net "FM_CPU0_SM_WP")
	)
	(via
		(at 337.1596 -83.10753)
		(size 0.6604)
		(drill 0.3302)
		(layers "F.Cu" "B.Cu")
		(net "FM_CPU0_SM_WP")
	)
	(via
		(at 335.6864 -74.8538)
		(size 0.508)
		(drill 0.254)
		(layers "F.Cu" "B.Cu")
		(net "FM_CPU0_SM_WP")
	)
	(via
		(at 255.35763 -87.784686)
		(size 0.508)
		(drill 0.254)
		(layers "F.Cu" "B.Cu")
		(net "FM_CPU0_SM_WP")
	)
	(segment
		(start 336.565748 -75.733148)
		(end 336.565748 -79.565246)
		(width 0.10795)
		(layer "B.Cu")
		(net "FM_CPU0_SM_WP")
	)
	(segment
		(start 335.89722 -84.82584)
		(end 335.90484 -84.81822)
		(width 0.10795)
		(layer "B.Cu")
		(net "FM_CPU0_SM_WP")
	)
	(segment
		(start 337.1596 -83.10753)
		(end 337.1596 -84.81822)
		(width 0.10795)
		(layer "B.Cu")
		(net "FM_CPU0_SM_WP")
	)
	(segment
		(start 336.565748 -79.565246)
		(end 337.1596 -80.159098)
		(width 0.10795)
		(layer "B.Cu")
		(net "FM_CPU0_SM_WP")
	)
	(segment
		(start 335.90484 -84.81822)
		(end 337.1596 -84.81822)
		(width 0.10795)
		(layer "B.Cu")
		(net "FM_CPU0_SM_WP")
	)
	(segment
		(start 335.6864 -74.8538)
		(end 336.565748 -75.733148)
		(width 0.10795)
		(layer "B.Cu")
		(net "FM_CPU0_SM_WP")
	)
	(segment
		(start 337.1596 -80.159098)
		(end 337.1596 -83.10753)
		(width 0.10795)
		(layer "B.Cu")
		(net "FM_CPU0_SM_WP")
	)
	(segment
		(start 307.807614 -78.164944)
		(end 304.810414 -78.164944)
		(width 0.0889)
		(layer "In11.Cu")
		(net "FM_CPU0_SM_WP")
	)
	(segment
		(start 335.6864 -74.8538)
		(end 333.673196 -74.8538)
		(width 0.089408)
		(layer "In11.Cu")
		(net "FM_CPU0_SM_WP")
	)
	(segment
		(start 261.4168 -86.4616)
		(end 261.4168 -87.56142)
		(width 0.089408)
		(layer "In11.Cu")
		(net "FM_CPU0_SM_WP")
	)
	(segment
		(start 332.089506 -76.43749)
		(end 331.096366 -76.43749)
		(width 0.089408)
		(layer "In11.Cu")
		(net "FM_CPU0_SM_WP")
	)
	(segment
		(start 288.935414 -78.288388)
		(end 288.934906 -78.288388)
		(width 0.0889)
		(layer "In11.Cu")
		(net "FM_CPU0_SM_WP")
	)
	(segment
		(start 304.810414 -78.164944)
		(end 304.438558 -77.793088)
		(width 0.0889)
		(layer "In11.Cu")
		(net "FM_CPU0_SM_WP")
	)
	(segment
		(start 260.18744 -88.35644)
		(end 259.86359 -88.68029)
		(width 0.0889)
		(layer "In11.Cu")
		(net "FM_CPU0_SM_WP")
	)
	(segment
		(start 257.95478 -87.68969)
		(end 257.9116 -87.68969)
		(width 0.0889)
		(layer "In11.Cu")
		(net "FM_CPU0_SM_WP")
	)
	(segment
		(start 285.93288 -78.78064)
		(end 285.42742 -79.2861)
		(width 0.089408)
		(layer "In11.Cu")
		(net "FM_CPU0_SM_WP")
	)
	(segment
		(start 276.080474 -86.862666)
		(end 265.424666 -86.862666)
		(width 0.089408)
		(layer "In11.Cu")
		(net "FM_CPU0_SM_WP")
	)
	(segment
		(start 286.424624 -78.78064)
		(end 285.93288 -78.78064)
		(width 0.089408)
		(layer "In11.Cu")
		(net "FM_CPU0_SM_WP")
	)
	(segment
		(start 333.673196 -74.8538)
		(end 332.089506 -76.43749)
		(width 0.089408)
		(layer "In11.Cu")
		(net "FM_CPU0_SM_WP")
	)
	(segment
		(start 285.42742 -79.2861)
		(end 285.42742 -81.2673)
		(width 0.089408)
		(layer "In11.Cu")
		(net "FM_CPU0_SM_WP")
	)
	(segment
		(start 263.9441 -85.3821)
		(end 262.4963 -85.3821)
		(width 0.089408)
		(layer "In11.Cu")
		(net "FM_CPU0_SM_WP")
	)
	(segment
		(start 290.652454 -78.288388)
		(end 290.651946 -78.288388)
		(width 0.0889)
		(layer "In11.Cu")
		(net "FM_CPU0_SM_WP")
	)
	(segment
		(start 293.24554 -77.793088)
		(end 293.212774 -77.793088)
		(width 0.0889)
		(layer "In11.Cu")
		(net "FM_CPU0_SM_WP")
	)
	(segment
		(start 331.096366 -76.43749)
		(end 330.214986 -77.31887)
		(width 0.089408)
		(layer "In11.Cu")
		(net "FM_CPU0_SM_WP")
	)
	(segment
		(start 280.98877 -81.95437)
		(end 276.080474 -86.862666)
		(width 0.089408)
		(layer "In11.Cu")
		(net "FM_CPU0_SM_WP")
	)
	(segment
		(start 281.96667 -81.95437)
		(end 280.98877 -81.95437)
		(width 0.089408)
		(layer "In11.Cu")
		(net "FM_CPU0_SM_WP")
	)
	(segment
		(start 282.67152 -82.65922)
		(end 281.96667 -81.95437)
		(width 0.089408)
		(layer "In11.Cu")
		(net "FM_CPU0_SM_WP")
	)
	(segment
		(start 257.089656 -88.184736)
		(end 257.059684 -88.184736)
		(width 0.0889)
		(layer "In11.Cu")
		(net "FM_CPU0_SM_WP")
	)
	(segment
		(start 261.4168 -87.56142)
		(end 261.10692 -87.8713)
		(width 0.089408)
		(layer "In11.Cu")
		(net "FM_CPU0_SM_WP")
	)
	(segment
		(start 261.10692 -87.8713)
		(end 260.62178 -88.35644)
		(width 0.0889)
		(layer "In11.Cu")
		(net "FM_CPU0_SM_WP")
	)
	(segment
		(start 256.179066 -87.68969)
		(end 255.35763 -87.784686)
		(width 0.0889)
		(layer "In11.Cu")
		(net "FM_CPU0_SM_WP")
	)
	(segment
		(start 308.653688 -77.31887)
		(end 307.807614 -78.164944)
		(width 0.0889)
		(layer "In11.Cu")
		(net "FM_CPU0_SM_WP")
	)
	(segment
		(start 262.4963 -85.3821)
		(end 261.4168 -86.4616)
		(width 0.089408)
		(layer "In11.Cu")
		(net "FM_CPU0_SM_WP")
	)
	(segment
		(start 289.794442 -78.783688)
		(end 289.792918 -78.783688)
		(width 0.0889)
		(layer "In11.Cu")
		(net "FM_CPU0_SM_WP")
	)
	(segment
		(start 259.86359 -88.68029)
		(end 259.639054 -88.68029)
		(width 0.0889)
		(layer "In11.Cu")
		(net "FM_CPU0_SM_WP")
	)
	(segment
		(start 284.0355 -82.65922)
		(end 282.67152 -82.65922)
		(width 0.089408)
		(layer "In11.Cu")
		(net "FM_CPU0_SM_WP")
	)
	(segment
		(start 256.23774 -87.68969)
		(end 256.179066 -87.68969)
		(width 0.0889)
		(layer "In11.Cu")
		(net "FM_CPU0_SM_WP")
	)
	(segment
		(start 258.80949 -88.184736)
		(end 258.776724 -88.184736)
		(width 0.0889)
		(layer "In11.Cu")
		(net "FM_CPU0_SM_WP")
	)
	(segment
		(start 265.424666 -86.862666)
		(end 263.9441 -85.3821)
		(width 0.089408)
		(layer "In11.Cu")
		(net "FM_CPU0_SM_WP")
	)
	(segment
		(start 285.42742 -81.2673)
		(end 284.0355 -82.65922)
		(width 0.089408)
		(layer "In11.Cu")
		(net "FM_CPU0_SM_WP")
	)
	(segment
		(start 297.176952 -77.491844)
		(end 297.17365 -77.497686)
		(width 0.0889)
		(layer "In11.Cu")
		(net "FM_CPU0_SM_WP")
	)
	(segment
		(start 260.62178 -88.35644)
		(end 260.18744 -88.35644)
		(width 0.0889)
		(layer "In11.Cu")
		(net "FM_CPU0_SM_WP")
	)
	(segment
		(start 330.214986 -77.31887)
		(end 308.653688 -77.31887)
		(width 0.089408)
		(layer "In11.Cu")
		(net "FM_CPU0_SM_WP")
	)
	(segment
		(start 287.231074 -78.288388)
		(end 287.206944 -78.288388)
		(width 0.0889)
		(layer "In11.Cu")
		(net "FM_CPU0_SM_WP")
	)
	(segment
		(start 288.091626 -77.793088)
		(end 288.061654 -77.793088)
		(width 0.0889)
		(layer "In11.Cu")
		(net "FM_CPU0_SM_WP")
	)
	(segment
		(start 304.438558 -77.793088)
		(end 303.511966 -77.793088)
		(width 0.0889)
		(layer "In11.Cu")
		(net "FM_CPU0_SM_WP")
	)
	(arc
		(start 257.42138 -87.984838)
		(mid 257.281301 -88.127574)
		(end 257.089656 -88.184736)
		(width 0.0889)
		(layer "In11.Cu")
		(net "FM_CPU0_SM_WP")
	)
	(arc
		(start 300.607476 -77.497686)
		(mid 300.095666 -77.793353)
		(end 299.583856 -77.497686)
		(width 0.0889)
		(layer "In11.Cu")
		(net "FM_CPU0_SM_WP")
	)
	(arc
		(start 289.792918 -78.783688)
		(mid 289.497837 -78.704603)
		(end 289.28187 -78.48854)
		(width 0.0889)
		(layer "In11.Cu")
		(net "FM_CPU0_SM_WP")
	)
	(arc
		(start 256.72796 -87.984838)
		(mid 256.520956 -87.773974)
		(end 256.23774 -87.68969)
		(width 0.0889)
		(layer "In11.Cu")
		(net "FM_CPU0_SM_WP")
	)
	(arc
		(start 296.15003 -77.497686)
		(mid 295.80332 -77.297375)
		(end 295.45661 -77.497686)
		(width 0.0889)
		(layer "In11.Cu")
		(net "FM_CPU0_SM_WP")
	)
	(arc
		(start 298.890436 -77.497686)
		(mid 298.378626 -77.793353)
		(end 297.866816 -77.497686)
		(width 0.0889)
		(layer "In11.Cu")
		(net "FM_CPU0_SM_WP")
	)
	(arc
		(start 291.85743 -77.992986)
		(mid 291.51072 -77.792802)
		(end 291.16401 -77.992986)
		(width 0.0889)
		(layer "In11.Cu")
		(net "FM_CPU0_SM_WP")
	)
	(arc
		(start 258.445 -87.984838)
		(mid 258.237996 -87.773974)
		(end 257.95478 -87.68969)
		(width 0.0889)
		(layer "In11.Cu")
		(net "FM_CPU0_SM_WP")
	)
	(arc
		(start 288.42335 -77.992986)
		(mid 288.283271 -77.85025)
		(end 288.091626 -77.793088)
		(width 0.0889)
		(layer "In11.Cu")
		(net "FM_CPU0_SM_WP")
	)
	(arc
		(start 297.866816 -77.497686)
		(mid 297.523526 -77.29739)
		(end 297.176952 -77.491844)
		(width 0.0889)
		(layer "In11.Cu")
		(net "FM_CPU0_SM_WP")
	)
	(arc
		(start 287.72993 -77.992986)
		(mid 287.519217 -78.206065)
		(end 287.231074 -78.288388)
		(width 0.0889)
		(layer "In11.Cu")
		(net "FM_CPU0_SM_WP")
	)
	(arc
		(start 257.059684 -88.184736)
		(mid 256.868042 -88.12757)
		(end 256.72796 -87.984838)
		(width 0.0889)
		(layer "In11.Cu")
		(net "FM_CPU0_SM_WP")
	)
	(arc
		(start 259.639054 -88.68029)
		(mid 259.445204 -88.62394)
		(end 259.30352 -88.480138)
		(width 0.0889)
		(layer "In11.Cu")
		(net "FM_CPU0_SM_WP")
	)
	(arc
		(start 297.17365 -77.497686)
		(mid 296.66184 -77.793353)
		(end 296.15003 -77.497686)
		(width 0.0889)
		(layer "In11.Cu")
		(net "FM_CPU0_SM_WP")
	)
	(arc
		(start 295.45661 -77.497686)
		(mid 294.9448 -77.793353)
		(end 294.43299 -77.497686)
		(width 0.0889)
		(layer "In11.Cu")
		(net "FM_CPU0_SM_WP")
	)
	(arc
		(start 301.300896 -77.497686)
		(mid 300.954186 -77.297375)
		(end 300.607476 -77.497686)
		(width 0.0889)
		(layer "In11.Cu")
		(net "FM_CPU0_SM_WP")
	)
	(arc
		(start 290.651946 -78.288388)
		(mid 290.451873 -78.342012)
		(end 290.30549 -78.48854)
		(width 0.0889)
		(layer "In11.Cu")
		(net "FM_CPU0_SM_WP")
	)
	(arc
		(start 288.061654 -77.793088)
		(mid 287.870012 -77.850254)
		(end 287.72993 -77.992986)
		(width 0.0889)
		(layer "In11.Cu")
		(net "FM_CPU0_SM_WP")
	)
	(arc
		(start 290.30549 -78.48854)
		(mid 290.089516 -78.70459)
		(end 289.794442 -78.783688)
		(width 0.0889)
		(layer "In11.Cu")
		(net "FM_CPU0_SM_WP")
	)
	(arc
		(start 289.28187 -78.48854)
		(mid 289.135457 -78.342065)
		(end 288.935414 -78.288388)
		(width 0.0889)
		(layer "In11.Cu")
		(net "FM_CPU0_SM_WP")
	)
	(arc
		(start 302.324516 -77.497686)
		(mid 301.812706 -77.793353)
		(end 301.300896 -77.497686)
		(width 0.0889)
		(layer "In11.Cu")
		(net "FM_CPU0_SM_WP")
	)
	(arc
		(start 294.43299 -77.497686)
		(mid 294.08628 -77.297375)
		(end 293.73957 -77.497686)
		(width 0.0889)
		(layer "In11.Cu")
		(net "FM_CPU0_SM_WP")
	)
	(arc
		(start 299.583856 -77.497686)
		(mid 299.237146 -77.297375)
		(end 298.890436 -77.497686)
		(width 0.0889)
		(layer "In11.Cu")
		(net "FM_CPU0_SM_WP")
	)
	(arc
		(start 303.511966 -77.793088)
		(mid 303.226542 -77.709621)
		(end 303.017936 -77.497686)
		(width 0.0889)
		(layer "In11.Cu")
		(net "FM_CPU0_SM_WP")
	)
	(arc
		(start 258.776724 -88.184736)
		(mid 258.585082 -88.12757)
		(end 258.445 -87.984838)
		(width 0.0889)
		(layer "In11.Cu")
		(net "FM_CPU0_SM_WP")
	)
	(arc
		(start 292.88105 -77.992986)
		(mid 292.36924 -78.288525)
		(end 291.85743 -77.992986)
		(width 0.0889)
		(layer "In11.Cu")
		(net "FM_CPU0_SM_WP")
	)
	(arc
		(start 293.212774 -77.793088)
		(mid 293.021132 -77.850254)
		(end 292.88105 -77.992986)
		(width 0.0889)
		(layer "In11.Cu")
		(net "FM_CPU0_SM_WP")
	)
	(arc
		(start 287.206944 -78.288388)
		(mid 287.013094 -78.344738)
		(end 286.87141 -78.48854)
		(width 0.0889)
		(layer "In11.Cu")
		(net "FM_CPU0_SM_WP")
	)
	(arc
		(start 259.30352 -88.480138)
		(mid 259.094912 -88.268206)
		(end 258.80949 -88.184736)
		(width 0.0889)
		(layer "In11.Cu")
		(net "FM_CPU0_SM_WP")
	)
	(arc
		(start 286.87141 -78.48854)
		(mid 286.682882 -78.687913)
		(end 286.424624 -78.78064)
		(width 0.0889)
		(layer "In11.Cu")
		(net "FM_CPU0_SM_WP")
	)
	(arc
		(start 288.934906 -78.288388)
		(mid 288.639556 -78.209226)
		(end 288.42335 -77.992986)
		(width 0.0889)
		(layer "In11.Cu")
		(net "FM_CPU0_SM_WP")
	)
	(arc
		(start 257.9116 -87.68969)
		(mid 257.628383 -87.773971)
		(end 257.42138 -87.984838)
		(width 0.0889)
		(layer "In11.Cu")
		(net "FM_CPU0_SM_WP")
	)
	(arc
		(start 293.73957 -77.497686)
		(mid 293.530962 -77.709618)
		(end 293.24554 -77.793088)
		(width 0.0889)
		(layer "In11.Cu")
		(net "FM_CPU0_SM_WP")
	)
	(arc
		(start 303.017936 -77.497686)
		(mid 302.671226 -77.297375)
		(end 302.324516 -77.497686)
		(width 0.0889)
		(layer "In11.Cu")
		(net "FM_CPU0_SM_WP")
	)
	(arc
		(start 291.16401 -77.992986)
		(mid 290.947826 -78.209265)
		(end 290.652454 -78.288388)
		(width 0.0889)
		(layer "In11.Cu")
		(net "FM_CPU0_SM_WP")
	)
	(segment
		(start 128.514348 -61.847984)
		(end 129.085848 -61.847984)
		(width 0.10795)
		(layer "F.Cu")
		(net "TP_CPU1_PROC_DIS_G_N")
	)
	(via
		(at 129.085848 -61.847984)
		(size 0.508)
		(drill 0.254)
		(layers "F.Cu" "B.Cu")
		(net "TP_CPU1_PROC_DIS_G_N")
	)
	(segment
		(start 19.685 -78.6638)
		(end 19.685 -79.375)
		(width 0.10795)
		(layer "F.Cu")
		(net "TP_HSC_MCLK")
	)
	(segment
		(start 19.41195 -78.0415)
		(end 19.41195 -78.39075)
		(width 0.10795)
		(layer "F.Cu")
		(net "TP_HSC_MCLK")
	)
	(segment
		(start 19.41195 -78.39075)
		(end 19.685 -78.6638)
		(width 0.10795)
		(layer "F.Cu")
		(net "TP_HSC_MCLK")
	)
	(via
		(at 19.685 -79.375)
		(size 0.508)
		(drill 0.254)
		(layers "F.Cu" "B.Cu")
		(net "TP_HSC_MCLK")
	)
	(segment
		(start 131.089908 -67.296538)
		(end 131.661408 -67.296538)
		(width 0.10795)
		(layer "F.Cu")
		(net "TP_CPU1_RSVD_TEST_5")
	)
	(via
		(at 131.661408 -67.296538)
		(size 0.508)
		(drill 0.254)
		(layers "F.Cu" "B.Cu")
		(net "TP_CPU1_RSVD_TEST_5")
	)
	(segment
		(start 296.09034 -67.296538)
		(end 295.2242 -67.296538)
		(width 0.10795)
		(layer "F.Cu")
		(net "TP_CPU0_RSVD_TEST_5")
	)
	(via
		(at 295.2242 -67.296538)
		(size 0.508)
		(drill 0.254)
		(layers "F.Cu" "B.Cu")
		(net "TP_CPU0_RSVD_TEST_5")
	)
	(segment
		(start 298.665646 -67.791584)
		(end 299.237146 -67.791584)
		(width 0.10795)
		(layer "F.Cu")
		(net "TP_NMI_CPU0")
	)
	(via
		(at 299.237146 -67.791584)
		(size 0.508)
		(drill 0.254)
		(layers "F.Cu" "B.Cu")
		(net "TP_NMI_CPU0")
	)
	(segment
		(start 414.290256 -41.73474)
		(end 414.290002 -41.73474)
		(width 0.10795)
		(layer "F.Cu")
		(net "PD_PEREXT")
	)
	(segment
		(start 414.290002 -41.73474)
		(end 413.890206 -42.134536)
		(width 0.10795)
		(layer "F.Cu")
		(net "PD_PEREXT")
	)
	(via
		(at 413.890206 -42.134536)
		(size 0.4572)
		(drill 0.2032)
		(layers "F.Cu" "B.Cu")
		(net "PD_PEREXT")
	)
	(segment
		(start 413.431736 -42.593006)
		(end 413.890206 -42.134536)
		(width 0.10795)
		(layer "B.Cu")
		(net "PD_PEREXT")
	)
	(segment
		(start 412.892494 -42.593006)
		(end 413.431736 -42.593006)
		(width 0.10795)
		(layer "B.Cu")
		(net "PD_PEREXT")
	)
	(segment
		(start 412.4325 -43.053)
		(end 412.892494 -42.593006)
		(width 0.10795)
		(layer "B.Cu")
		(net "PD_PEREXT")
	)
	(segment
		(start 129.372868 -90.080338)
		(end 129.944368 -90.080338)
		(width 0.10795)
		(layer "F.Cu")
		(net "TP_CPU1_UPI2_RSVD_DB15")
	)
	(via
		(at 129.944368 -90.080338)
		(size 0.4826)
		(drill 0.254)
		(layers "F.Cu" "B.Cu")
		(net "TP_CPU1_UPI2_RSVD_DB15")
	)
	(segment
		(start 131.948174 -89.584784)
		(end 132.519674 -89.584784)
		(width 0.10795)
		(layer "F.Cu")
		(net "TP_CPU1_UPI2_RSVD_DD15")
	)
	(via
		(at 132.519674 -89.584784)
		(size 0.4826)
		(drill 0.254)
		(layers "F.Cu" "B.Cu")
		(net "TP_CPU1_UPI2_RSVD_DD15")
	)
	(segment
		(start 131.089908 -88.099138)
		(end 131.661408 -88.099138)
		(width 0.10795)
		(layer "F.Cu")
		(net "TP_CPU1_UPI2_RSVD_DE16")
	)
	(via
		(at 131.661408 -88.099138)
		(size 0.4826)
		(drill 0.254)
		(layers "F.Cu" "B.Cu")
		(net "TP_CPU1_UPI2_RSVD_DE16")
	)
	(segment
		(start 131.948174 -85.622384)
		(end 132.519674 -85.622384)
		(width 0.10795)
		(layer "F.Cu")
		(net "TP_CPU1_UPI2_RSVD_DF17")
	)
	(via
		(at 132.519674 -85.622384)
		(size 0.4826)
		(drill 0.254)
		(layers "F.Cu" "B.Cu")
		(net "TP_CPU1_UPI2_RSVD_DF17")
	)
	(segment
		(start 131.948174 -84.631784)
		(end 132.519674 -84.631784)
		(width 0.10795)
		(layer "F.Cu")
		(net "TP_CPU1_UPI2_RSVD_DH17")
	)
	(via
		(at 132.519674 -84.631784)
		(size 0.4826)
		(drill 0.254)
		(layers "F.Cu" "B.Cu")
		(net "TP_CPU1_UPI2_RSVD_DH17")
	)
	(segment
		(start 132.806694 -84.136738)
		(end 133.378194 -84.136738)
		(width 0.10795)
		(layer "F.Cu")
		(net "TP_CPU1_UPI2_RSVD_DJ18")
	)
	(via
		(at 133.378194 -84.136738)
		(size 0.4826)
		(drill 0.254)
		(layers "F.Cu" "B.Cu")
		(net "TP_CPU1_UPI2_RSVD_DJ18")
	)
	(segment
		(start 133.665214 -83.641184)
		(end 134.236714 -83.641184)
		(width 0.10795)
		(layer "F.Cu")
		(net "TP_CPU1_UPI2_RSVD_DJ20")
	)
	(via
		(at 134.236714 -83.641184)
		(size 0.4826)
		(drill 0.254)
		(layers "F.Cu" "B.Cu")
		(net "TP_CPU1_UPI2_RSVD_DJ20")
	)
	(segment
		(start 133.665214 -82.650584)
		(end 134.236714 -82.650584)
		(width 0.10795)
		(layer "F.Cu")
		(net "TP_CPU1_UPI2_RSVD_DK19")
	)
	(via
		(at 134.236714 -82.650584)
		(size 0.4826)
		(drill 0.254)
		(layers "F.Cu" "B.Cu")
		(net "TP_CPU1_UPI2_RSVD_DK19")
	)
	(segment
		(start 125.080268 -97.509584)
		(end 125.651768 -97.509584)
		(width 0.10795)
		(layer "F.Cu")
		(net "TP_CPU1_UPI2_RSVD_CA12")
	)
	(via
		(at 125.651768 -97.509584)
		(size 0.4826)
		(drill 0.254)
		(layers "F.Cu" "B.Cu")
		(net "TP_CPU1_UPI2_RSVD_CA12")
	)
	(segment
		(start 125.938788 -97.014538)
		(end 126.510288 -97.014538)
		(width 0.10795)
		(layer "F.Cu")
		(net "TP_CPU1_UPI2_RSVD_CB11")
	)
	(via
		(at 126.510288 -97.014538)
		(size 0.4826)
		(drill 0.254)
		(layers "F.Cu" "B.Cu")
		(net "TP_CPU1_UPI2_RSVD_CB11")
	)
	(segment
		(start 126.797308 -95.528384)
		(end 127.368808 -95.528384)
		(width 0.10795)
		(layer "F.Cu")
		(net "TP_CPU1_UPI2_RSVD_CD11")
	)
	(via
		(at 127.368808 -95.528384)
		(size 0.4826)
		(drill 0.254)
		(layers "F.Cu" "B.Cu")
		(net "TP_CPU1_UPI2_RSVD_CD11")
	)
	(segment
		(start 127.655828 -95.033084)
		(end 128.227328 -95.033084)
		(width 0.10795)
		(layer "F.Cu")
		(net "TP_CPU1_UPI2_RSVD_CG12")
	)
	(via
		(at 128.227328 -95.033084)
		(size 0.4826)
		(drill 0.254)
		(layers "F.Cu" "B.Cu")
		(net "TP_CPU1_UPI2_RSVD_CG12")
	)
	(segment
		(start 128.514348 -94.538038)
		(end 129.085848 -94.538038)
		(width 0.10795)
		(layer "F.Cu")
		(net "TP_CPU1_UPI2_RSVD_CH13")
	)
	(via
		(at 129.085848 -94.538038)
		(size 0.4826)
		(drill 0.254)
		(layers "F.Cu" "B.Cu")
		(net "TP_CPU1_UPI2_RSVD_CH13")
	)
	(segment
		(start 128.514348 -93.547184)
		(end 129.085848 -93.547184)
		(width 0.10795)
		(layer "F.Cu")
		(net "TP_CPU1_UPI2_RSVD_CK13")
	)
	(via
		(at 129.085848 -93.547184)
		(size 0.4826)
		(drill 0.254)
		(layers "F.Cu" "B.Cu")
		(net "TP_CPU1_UPI2_RSVD_CK13")
	)
	(segment
		(start 129.372868 -93.052138)
		(end 129.944368 -93.052138)
		(width 0.10795)
		(layer "F.Cu")
		(net "TP_CPU1_UPI2_RSVD_CR14")
	)
	(via
		(at 129.944368 -93.052138)
		(size 0.4826)
		(drill 0.254)
		(layers "F.Cu" "B.Cu")
		(net "TP_CPU1_UPI2_RSVD_CR14")
	)
	(segment
		(start 130.231388 -92.556584)
		(end 130.802888 -92.556584)
		(width 0.10795)
		(layer "F.Cu")
		(net "TP_CPU1_UPI2_RSVD_CV13")
	)
	(via
		(at 130.802888 -92.556584)
		(size 0.4826)
		(drill 0.254)
		(layers "F.Cu" "B.Cu")
		(net "TP_CPU1_UPI2_RSVD_CV13")
	)
	(segment
		(start 130.231388 -91.565984)
		(end 130.802888 -91.565984)
		(width 0.10795)
		(layer "F.Cu")
		(net "TP_CPU1_UPI2_RSVD_CW16")
	)
	(via
		(at 130.802888 -91.565984)
		(size 0.4826)
		(drill 0.254)
		(layers "F.Cu" "B.Cu")
		(net "TP_CPU1_UPI2_RSVD_CW16")
	)
	(segment
		(start 133.665214 -81.659984)
		(end 134.236714 -81.659984)
		(width 0.10795)
		(layer "F.Cu")
		(net "TP_CPU1_UPI2_RSVD_DN20")
	)
	(via
		(at 134.236714 -81.659984)
		(size 0.4826)
		(drill 0.254)
		(layers "F.Cu" "B.Cu")
		(net "TP_CPU1_UPI2_RSVD_DN20")
	)
	(segment
		(start 132.806694 -81.164938)
		(end 133.378194 -81.164938)
		(width 0.10795)
		(layer "F.Cu")
		(net "TP_CPU1_UPI2_RSVD_DP21")
	)
	(via
		(at 133.378194 -81.164938)
		(size 0.4826)
		(drill 0.254)
		(layers "F.Cu" "B.Cu")
		(net "TP_CPU1_UPI2_RSVD_DP21")
	)
	(segment
		(start 129.372868 -91.070938)
		(end 129.944368 -91.070938)
		(width 0.10795)
		(layer "F.Cu")
		(net "TP_CPU1_UPI2_RSVD_DC16")
	)
	(via
		(at 129.944368 -91.070938)
		(size 0.4826)
		(drill 0.254)
		(layers "F.Cu" "B.Cu")
		(net "TP_CPU1_UPI2_RSVD_DC16")
	)
	(segment
		(start 131.089908 -90.080338)
		(end 131.661408 -90.080338)
		(width 0.10795)
		(layer "F.Cu")
		(net "TP_CPU1_UPI2_RSVD_DF15")
	)
	(via
		(at 131.661408 -90.080338)
		(size 0.4826)
		(drill 0.254)
		(layers "F.Cu" "B.Cu")
		(net "TP_CPU1_UPI2_RSVD_DF15")
	)
	(segment
		(start 131.089908 -89.089738)
		(end 131.661408 -89.089738)
		(width 0.10795)
		(layer "F.Cu")
		(net "TP_CPU1_UPI2_RSVD_DD17")
	)
	(via
		(at 131.661408 -89.089738)
		(size 0.4826)
		(drill 0.254)
		(layers "F.Cu" "B.Cu")
		(net "TP_CPU1_UPI2_RSVD_DD17")
	)
	(segment
		(start 131.948174 -86.612984)
		(end 132.519674 -86.612984)
		(width 0.10795)
		(layer "F.Cu")
		(net "TP_CPU1_UPI2_RSVD_DG18")
	)
	(via
		(at 132.519674 -86.612984)
		(size 0.4826)
		(drill 0.254)
		(layers "F.Cu" "B.Cu")
		(net "TP_CPU1_UPI2_RSVD_DG18")
	)
	(segment
		(start 131.089908 -85.127338)
		(end 131.661408 -85.127338)
		(width 0.10795)
		(layer "F.Cu")
		(net "TP_CPU1_UPI2_RSVD_DK17")
	)
	(via
		(at 131.661408 -85.127338)
		(size 0.4826)
		(drill 0.254)
		(layers "F.Cu" "B.Cu")
		(net "TP_CPU1_UPI2_RSVD_DK17")
	)
	(segment
		(start 131.948174 -83.641184)
		(end 132.519674 -83.641184)
		(width 0.10795)
		(layer "F.Cu")
		(net "TP_CPU1_UPI2_RSVD_DH19")
	)
	(via
		(at 132.519674 -83.641184)
		(size 0.4826)
		(drill 0.254)
		(layers "F.Cu" "B.Cu")
		(net "TP_CPU1_UPI2_RSVD_DH19")
	)
	(segment
		(start 133.665214 -84.631784)
		(end 134.236714 -84.631784)
		(width 0.10795)
		(layer "F.Cu")
		(net "TP_CPU1_UPI2_RSVD_DG20")
	)
	(via
		(at 134.236714 -84.631784)
		(size 0.4826)
		(drill 0.254)
		(layers "F.Cu" "B.Cu")
		(net "TP_CPU1_UPI2_RSVD_DG20")
	)
	(segment
		(start 132.806694 -83.146138)
		(end 133.378194 -83.146138)
		(width 0.10795)
		(layer "F.Cu")
		(net "TP_CPU1_UPI2_RSVD_DL20")
	)
	(via
		(at 133.378194 -83.146138)
		(size 0.4826)
		(drill 0.254)
		(layers "F.Cu" "B.Cu")
		(net "TP_CPU1_UPI2_RSVD_DL20")
	)
	(segment
		(start 125.080268 -98.500184)
		(end 125.651768 -98.500184)
		(width 0.10795)
		(layer "F.Cu")
		(net "TP_CPU1_UPI2_RSVD_CC12")
	)
	(via
		(at 125.651768 -98.500184)
		(size 0.4826)
		(drill 0.254)
		(layers "F.Cu" "B.Cu")
		(net "TP_CPU1_UPI2_RSVD_CC12")
	)
	(segment
		(start 125.080268 -96.518984)
		(end 125.651768 -96.518984)
		(width 0.10795)
		(layer "F.Cu")
		(net "TP_CPU1_UPI2_RSVD_CC10")
	)
	(via
		(at 125.651768 -96.518984)
		(size 0.4826)
		(drill 0.254)
		(layers "F.Cu" "B.Cu")
		(net "TP_CPU1_UPI2_RSVD_CC10")
	)
	(segment
		(start 125.938788 -96.023938)
		(end 126.510288 -96.023938)
		(width 0.10795)
		(layer "F.Cu")
		(net "TP_CPU1_UPI2_RSVD_CE12")
	)
	(via
		(at 126.510288 -96.023938)
		(size 0.4826)
		(drill 0.254)
		(layers "F.Cu" "B.Cu")
		(net "TP_CPU1_UPI2_RSVD_CE12")
	)
	(segment
		(start 126.797308 -94.538038)
		(end 127.368808 -94.538038)
		(width 0.10795)
		(layer "F.Cu")
		(net "TP_CPU1_UPI2_RSVD_CF13")
	)
	(via
		(at 127.368808 -94.538038)
		(size 0.508)
		(drill 0.254)
		(layers "F.Cu" "B.Cu")
		(net "TP_CPU1_UPI2_RSVD_CF13")
	)
	(segment
		(start 128.514348 -95.528384)
		(end 129.085848 -95.528384)
		(width 0.10795)
		(layer "F.Cu")
		(net "TP_CPU1_UPI2_RSVD_CJ14")
	)
	(via
		(at 129.085848 -95.528384)
		(size 0.508)
		(drill 0.254)
		(layers "F.Cu" "B.Cu")
		(net "TP_CPU1_UPI2_RSVD_CJ14")
	)
	(segment
		(start 127.655828 -94.042738)
		(end 128.227328 -94.042738)
		(width 0.10795)
		(layer "F.Cu")
		(net "TP_CPU1_UPI2_RSVD_CM13")
	)
	(via
		(at 128.227328 -94.042738)
		(size 0.508)
		(drill 0.254)
		(layers "F.Cu" "B.Cu")
		(net "TP_CPU1_UPI2_RSVD_CM13")
	)
	(segment
		(start 128.514348 -92.556584)
		(end 129.085848 -92.556584)
		(width 0.10795)
		(layer "F.Cu")
		(net "TP_CPU1_UPI2_RSVD_CU14")
	)
	(via
		(at 129.085848 -92.556584)
		(size 0.4826)
		(drill 0.254)
		(layers "F.Cu" "B.Cu")
		(net "TP_CPU1_UPI2_RSVD_CU14")
	)
	(segment
		(start 130.231388 -93.547184)
		(end 130.802888 -93.547184)
		(width 0.10795)
		(layer "F.Cu")
		(net "TP_CPU1_UPI2_RSVD_CW14")
	)
	(via
		(at 130.802888 -93.547184)
		(size 0.4826)
		(drill 0.254)
		(layers "F.Cu" "B.Cu")
		(net "TP_CPU1_UPI2_RSVD_CW14")
	)
	(segment
		(start 129.372868 -92.061538)
		(end 129.944368 -92.061538)
		(width 0.10795)
		(layer "F.Cu")
		(net "TP_CPU1_UPI2_RSVD_DA16")
	)
	(via
		(at 129.944368 -92.061538)
		(size 0.4826)
		(drill 0.254)
		(layers "F.Cu" "B.Cu")
		(net "TP_CPU1_UPI2_RSVD_DA16")
	)
	(segment
		(start 134.523734 -82.155284)
		(end 135.095234 -82.155284)
		(width 0.10795)
		(layer "F.Cu")
		(net "TP_CPU1_UPI2_RSVD_DM21")
	)
	(via
		(at 135.095234 -82.155284)
		(size 0.4826)
		(drill 0.254)
		(layers "F.Cu" "B.Cu")
		(net "TP_CPU1_UPI2_RSVD_DM21")
	)
	(segment
		(start 132.806694 -82.155284)
		(end 133.378194 -82.155284)
		(width 0.10795)
		(layer "F.Cu")
		(net "TP_CPU1_UPI2_RSVD_DT21")
	)
	(via
		(at 133.378194 -82.155284)
		(size 0.4826)
		(drill 0.254)
		(layers "F.Cu" "B.Cu")
		(net "TP_CPU1_UPI2_RSVD_DT21")
	)
	(segment
		(start 139.674854 -88.099138)
		(end 140.246354 -88.099138)
		(width 0.10795)
		(layer "F.Cu")
		(net "TP_CPU1_DMI_TX_DP3")
	)
	(via
		(at 140.246354 -88.099138)
		(size 0.4826)
		(drill 0.254)
		(layers "F.Cu" "B.Cu")
		(net "TP_CPU1_DMI_TX_DP3")
	)
	(segment
		(start 140.533374 -86.612984)
		(end 141.104874 -86.612984)
		(width 0.10795)
		(layer "F.Cu")
		(net "TP_CPU1_DMI_TX_DP2")
	)
	(via
		(at 141.104874 -86.612984)
		(size 0.4826)
		(drill 0.254)
		(layers "F.Cu" "B.Cu")
		(net "TP_CPU1_DMI_TX_DP2")
	)
	(segment
		(start 139.674854 -86.117938)
		(end 140.246354 -86.117938)
		(width 0.10795)
		(layer "F.Cu")
		(net "TP_CPU1_DMI_TX_DP1")
	)
	(via
		(at 140.246354 -86.117938)
		(size 0.4826)
		(drill 0.254)
		(layers "F.Cu" "B.Cu")
		(net "TP_CPU1_DMI_TX_DP1")
	)
	(segment
		(start 138.816334 -84.631784)
		(end 139.387834 -84.631784)
		(width 0.10795)
		(layer "F.Cu")
		(net "TP_CPU1_DMI_TX_DP0")
	)
	(via
		(at 139.387834 -84.631784)
		(size 0.4826)
		(drill 0.254)
		(layers "F.Cu" "B.Cu")
		(net "TP_CPU1_DMI_TX_DP0")
	)
	(segment
		(start 138.816334 -87.603584)
		(end 139.387834 -87.603584)
		(width 0.10795)
		(layer "F.Cu")
		(net "TP_CPU1_DMI_TX_DN3")
	)
	(via
		(at 139.387834 -87.603584)
		(size 0.4826)
		(drill 0.254)
		(layers "F.Cu" "B.Cu")
		(net "TP_CPU1_DMI_TX_DN3")
	)
	(segment
		(start 139.674854 -87.108538)
		(end 140.246354 -87.108538)
		(width 0.10795)
		(layer "F.Cu")
		(net "TP_CPU1_DMI_TX_DN2")
	)
	(via
		(at 140.246354 -87.108538)
		(size 0.4826)
		(drill 0.254)
		(layers "F.Cu" "B.Cu")
		(net "TP_CPU1_DMI_TX_DN2")
	)
	(segment
		(start 139.674854 -85.127338)
		(end 140.246354 -85.127338)
		(width 0.10795)
		(layer "F.Cu")
		(net "TP_CPU1_DMI_TX_DN1")
	)
	(via
		(at 140.246354 -85.127338)
		(size 0.4826)
		(drill 0.254)
		(layers "F.Cu" "B.Cu")
		(net "TP_CPU1_DMI_TX_DN1")
	)
	(segment
		(start 139.674854 -84.136738)
		(end 140.246354 -84.136738)
		(width 0.10795)
		(layer "F.Cu")
		(net "TP_CPU1_DMI_TX_DN0")
	)
	(via
		(at 140.246354 -84.136738)
		(size 0.4826)
		(drill 0.254)
		(layers "F.Cu" "B.Cu")
		(net "TP_CPU1_DMI_TX_DN0")
	)
	(segment
		(start 294.3733 -90.080338)
		(end 294.9448 -90.080338)
		(width 0.10795)
		(layer "F.Cu")
		(net "TP_CPU0_UPI2_RSVD_DB15")
	)
	(via
		(at 294.9448 -90.080338)
		(size 0.508)
		(drill 0.254)
		(layers "F.Cu" "B.Cu")
		(net "TP_CPU0_UPI2_RSVD_DB15")
	)
	(segment
		(start 296.948606 -89.584784)
		(end 297.520106 -89.584784)
		(width 0.10795)
		(layer "F.Cu")
		(net "TP_CPU0_UPI2_RSVD_DD15")
	)
	(via
		(at 297.520106 -89.584784)
		(size 0.508)
		(drill 0.254)
		(layers "F.Cu" "B.Cu")
		(net "TP_CPU0_UPI2_RSVD_DD15")
	)
	(segment
		(start 296.66184 -88.099138)
		(end 296.09034 -88.099138)
		(width 0.10795)
		(layer "F.Cu")
		(net "TP_CPU0_UPI2_RSVD_DE16")
	)
	(via
		(at 296.66184 -88.099138)
		(size 0.508)
		(drill 0.254)
		(layers "F.Cu" "B.Cu")
		(net "TP_CPU0_UPI2_RSVD_DE16")
	)
	(segment
		(start 296.948606 -85.622384)
		(end 297.520106 -85.622384)
		(width 0.10795)
		(layer "F.Cu")
		(net "TP_CPU0_UPI2_RSVD_DF17")
	)
	(via
		(at 297.520106 -85.622384)
		(size 0.508)
		(drill 0.254)
		(layers "F.Cu" "B.Cu")
		(net "TP_CPU0_UPI2_RSVD_DF17")
	)
	(segment
		(start 296.948606 -84.631784)
		(end 297.520106 -84.631784)
		(width 0.10795)
		(layer "F.Cu")
		(net "TP_CPU0_UPI2_RSVD_DH17")
	)
	(via
		(at 297.520106 -84.631784)
		(size 0.508)
		(drill 0.254)
		(layers "F.Cu" "B.Cu")
		(net "TP_CPU0_UPI2_RSVD_DH17")
	)
	(segment
		(start 297.807126 -84.136738)
		(end 298.378626 -84.136738)
		(width 0.10795)
		(layer "F.Cu")
		(net "TP_CPU0_UPI2_RSVD_DJ18")
	)
	(via
		(at 298.378626 -84.136738)
		(size 0.508)
		(drill 0.254)
		(layers "F.Cu" "B.Cu")
		(net "TP_CPU0_UPI2_RSVD_DJ18")
	)
	(segment
		(start 298.665646 -83.641184)
		(end 299.237146 -83.641184)
		(width 0.10795)
		(layer "F.Cu")
		(net "TP_CPU0_UPI2_RSVD_DJ20")
	)
	(via
		(at 299.237146 -83.641184)
		(size 0.508)
		(drill 0.254)
		(layers "F.Cu" "B.Cu")
		(net "TP_CPU0_UPI2_RSVD_DJ20")
	)
	(segment
		(start 298.665646 -82.650584)
		(end 299.237146 -82.650584)
		(width 0.10795)
		(layer "F.Cu")
		(net "TP_CPU0_UPI2_RSVD_DK19")
	)
	(via
		(at 299.237146 -82.650584)
		(size 0.508)
		(drill 0.254)
		(layers "F.Cu" "B.Cu")
		(net "TP_CPU0_UPI2_RSVD_DK19")
	)
	(segment
		(start 290.0807 -97.509584)
		(end 290.6522 -97.509584)
		(width 0.10795)
		(layer "F.Cu")
		(net "TP_CPU0_UPI2_RSVD_CA12")
	)
	(via
		(at 290.6522 -97.509584)
		(size 0.508)
		(drill 0.254)
		(layers "F.Cu" "B.Cu")
		(net "TP_CPU0_UPI2_RSVD_CA12")
	)
	(segment
		(start 290.93922 -97.014538)
		(end 291.51072 -97.014538)
		(width 0.10795)
		(layer "F.Cu")
		(net "TP_CPU0_UPI2_RSVD_CB11")
	)
	(via
		(at 291.51072 -97.014538)
		(size 0.508)
		(drill 0.254)
		(layers "F.Cu" "B.Cu")
		(net "TP_CPU0_UPI2_RSVD_CB11")
	)
	(segment
		(start 291.79774 -95.528384)
		(end 292.36924 -95.528384)
		(width 0.10795)
		(layer "F.Cu")
		(net "TP_CPU0_UPI2_RSVD_CD11")
	)
	(via
		(at 292.36924 -95.528384)
		(size 0.508)
		(drill 0.254)
		(layers "F.Cu" "B.Cu")
		(net "TP_CPU0_UPI2_RSVD_CD11")
	)
	(segment
		(start 293.22776 -95.033084)
		(end 292.65626 -95.033084)
		(width 0.10795)
		(layer "F.Cu")
		(net "TP_CPU0_UPI2_RSVD_CG12")
	)
	(via
		(at 293.22776 -95.033084)
		(size 0.508)
		(drill 0.254)
		(layers "F.Cu" "B.Cu")
		(net "TP_CPU0_UPI2_RSVD_CG12")
	)
	(segment
		(start 293.51478 -94.538038)
		(end 294.086026 -94.538038)
		(width 0.10795)
		(layer "F.Cu")
		(net "TP_CPU0_UPI2_RSVD_CH13")
	)
	(segment
		(start 294.086026 -94.538038)
		(end 294.08628 -94.537784)
		(width 0.10795)
		(layer "F.Cu")
		(net "TP_CPU0_UPI2_RSVD_CH13")
	)
	(via
		(at 294.08628 -94.537784)
		(size 0.508)
		(drill 0.254)
		(layers "F.Cu" "B.Cu")
		(net "TP_CPU0_UPI2_RSVD_CH13")
	)
	(segment
		(start 294.08628 -93.547184)
		(end 293.51478 -93.547184)
		(width 0.10795)
		(layer "F.Cu")
		(net "TP_CPU0_UPI2_RSVD_CK13")
	)
	(via
		(at 294.08628 -93.547184)
		(size 0.508)
		(drill 0.254)
		(layers "F.Cu" "B.Cu")
		(net "TP_CPU0_UPI2_RSVD_CK13")
	)
	(segment
		(start 294.3733 -93.052138)
		(end 294.9448 -93.052138)
		(width 0.10795)
		(layer "F.Cu")
		(net "TP_CPU0_UPI2_RSVD_CR14")
	)
	(via
		(at 294.9448 -93.052138)
		(size 0.508)
		(drill 0.254)
		(layers "F.Cu" "B.Cu")
		(net "TP_CPU0_UPI2_RSVD_CR14")
	)
	(segment
		(start 295.23182 -92.556584)
		(end 295.80332 -92.556584)
		(width 0.10795)
		(layer "F.Cu")
		(net "TP_CPU0_UPI2_RSVD_CV13")
	)
	(via
		(at 295.80332 -92.556584)
		(size 0.508)
		(drill 0.254)
		(layers "F.Cu" "B.Cu")
		(net "TP_CPU0_UPI2_RSVD_CV13")
	)
	(segment
		(start 295.23182 -91.565984)
		(end 295.80332 -91.565984)
		(width 0.10795)
		(layer "F.Cu")
		(net "TP_CPU0_UPI2_RSVD_CW16")
	)
	(via
		(at 295.80332 -91.565984)
		(size 0.508)
		(drill 0.254)
		(layers "F.Cu" "B.Cu")
		(net "TP_CPU0_UPI2_RSVD_CW16")
	)
	(segment
		(start 298.665646 -81.659984)
		(end 299.237146 -81.659984)
		(width 0.10795)
		(layer "F.Cu")
		(net "TP_CPU0_UPI2_RSVD_DN20")
	)
	(via
		(at 299.237146 -81.659984)
		(size 0.508)
		(drill 0.254)
		(layers "F.Cu" "B.Cu")
		(net "TP_CPU0_UPI2_RSVD_DN20")
	)
	(segment
		(start 297.807126 -81.164938)
		(end 298.378626 -81.164938)
		(width 0.10795)
		(layer "F.Cu")
		(net "TP_CPU0_UPI2_RSVD_DP21")
	)
	(via
		(at 298.378626 -81.164938)
		(size 0.508)
		(drill 0.254)
		(layers "F.Cu" "B.Cu")
		(net "TP_CPU0_UPI2_RSVD_DP21")
	)
	(segment
		(start 294.3733 -91.070938)
		(end 294.9448 -91.070938)
		(width 0.10795)
		(layer "F.Cu")
		(net "TP_CPU0_UPI2_RSVD_DC16")
	)
	(via
		(at 294.9448 -91.070938)
		(size 0.508)
		(drill 0.254)
		(layers "F.Cu" "B.Cu")
		(net "TP_CPU0_UPI2_RSVD_DC16")
	)
	(segment
		(start 296.66184 -90.080338)
		(end 296.09034 -90.080338)
		(width 0.10795)
		(layer "F.Cu")
		(net "TP_CPU0_UPI2_RSVD_DF15")
	)
	(via
		(at 296.66184 -90.080338)
		(size 0.508)
		(drill 0.254)
		(layers "F.Cu" "B.Cu")
		(net "TP_CPU0_UPI2_RSVD_DF15")
	)
	(segment
		(start 296.66184 -89.089738)
		(end 296.09034 -89.089738)
		(width 0.10795)
		(layer "F.Cu")
		(net "TP_CPU0_UPI2_RSVD_DD17")
	)
	(via
		(at 296.66184 -89.089738)
		(size 0.508)
		(drill 0.254)
		(layers "F.Cu" "B.Cu")
		(net "TP_CPU0_UPI2_RSVD_DD17")
	)
	(segment
		(start 296.948606 -86.612984)
		(end 297.520106 -86.612984)
		(width 0.10795)
		(layer "F.Cu")
		(net "TP_CPU0_UPI2_RSVD_DG18")
	)
	(via
		(at 297.520106 -86.612984)
		(size 0.508)
		(drill 0.254)
		(layers "F.Cu" "B.Cu")
		(net "TP_CPU0_UPI2_RSVD_DG18")
	)
	(segment
		(start 296.66184 -85.127338)
		(end 296.09034 -85.127338)
		(width 0.10795)
		(layer "F.Cu")
		(net "TP_CPU0_UPI2_RSVD_DK17")
	)
	(via
		(at 296.66184 -85.127338)
		(size 0.508)
		(drill 0.254)
		(layers "F.Cu" "B.Cu")
		(net "TP_CPU0_UPI2_RSVD_DK17")
	)
	(segment
		(start 296.948606 -83.641184)
		(end 297.520106 -83.641184)
		(width 0.10795)
		(layer "F.Cu")
		(net "TP_CPU0_UPI2_RSVD_DH19")
	)
	(via
		(at 297.520106 -83.641184)
		(size 0.508)
		(drill 0.254)
		(layers "F.Cu" "B.Cu")
		(net "TP_CPU0_UPI2_RSVD_DH19")
	)
	(segment
		(start 298.665646 -84.631784)
		(end 299.237146 -84.631784)
		(width 0.10795)
		(layer "F.Cu")
		(net "TP_CPU0_UPI2_RSVD_DG20")
	)
	(via
		(at 299.237146 -84.631784)
		(size 0.508)
		(drill 0.254)
		(layers "F.Cu" "B.Cu")
		(net "TP_CPU0_UPI2_RSVD_DG20")
	)
	(segment
		(start 297.807126 -83.146138)
		(end 298.378626 -83.146138)
		(width 0.10795)
		(layer "F.Cu")
		(net "TP_CPU0_UPI2_RSVD_DL20")
	)
	(via
		(at 298.378626 -83.146138)
		(size 0.508)
		(drill 0.254)
		(layers "F.Cu" "B.Cu")
		(net "TP_CPU0_UPI2_RSVD_DL20")
	)
	(segment
		(start 290.0807 -98.500184)
		(end 290.6522 -98.500184)
		(width 0.10795)
		(layer "F.Cu")
		(net "TP_CPU0_UPI2_RSVD_CC12")
	)
	(via
		(at 290.6522 -98.500184)
		(size 0.508)
		(drill 0.254)
		(layers "F.Cu" "B.Cu")
		(net "TP_CPU0_UPI2_RSVD_CC12")
	)
	(segment
		(start 290.0807 -96.518984)
		(end 290.6522 -96.518984)
		(width 0.10795)
		(layer "F.Cu")
		(net "TP_CPU0_UPI2_RSVD_CC10")
	)
	(via
		(at 290.6522 -96.518984)
		(size 0.508)
		(drill 0.254)
		(layers "F.Cu" "B.Cu")
		(net "TP_CPU0_UPI2_RSVD_CC10")
	)
	(segment
		(start 290.93922 -96.023938)
		(end 291.51072 -96.023938)
		(width 0.10795)
		(layer "F.Cu")
		(net "TP_CPU0_UPI2_RSVD_CE12")
	)
	(via
		(at 291.51072 -96.023938)
		(size 0.508)
		(drill 0.254)
		(layers "F.Cu" "B.Cu")
		(net "TP_CPU0_UPI2_RSVD_CE12")
	)
	(segment
		(start 291.79774 -94.538038)
		(end 292.368986 -94.538038)
		(width 0.10795)
		(layer "F.Cu")
		(net "TP_CPU0_UPI2_RSVD_CF13")
	)
	(segment
		(start 292.368986 -94.538038)
		(end 292.36924 -94.537784)
		(width 0.10795)
		(layer "F.Cu")
		(net "TP_CPU0_UPI2_RSVD_CF13")
	)
	(via
		(at 292.36924 -94.537784)
		(size 0.508)
		(drill 0.254)
		(layers "F.Cu" "B.Cu")
		(net "TP_CPU0_UPI2_RSVD_CF13")
	)
	(segment
		(start 293.51478 -95.528384)
		(end 294.08628 -95.528384)
		(width 0.10795)
		(layer "F.Cu")
		(net "TP_CPU0_UPI2_RSVD_CJ14")
	)
	(via
		(at 294.08628 -95.528384)
		(size 0.508)
		(drill 0.254)
		(layers "F.Cu" "B.Cu")
		(net "TP_CPU0_UPI2_RSVD_CJ14")
	)
	(segment
		(start 292.65626 -94.042738)
		(end 293.227506 -94.042738)
		(width 0.10795)
		(layer "F.Cu")
		(net "TP_CPU0_UPI2_RSVD_CM13")
	)
	(segment
		(start 293.227506 -94.042738)
		(end 293.22776 -94.042484)
		(width 0.10795)
		(layer "F.Cu")
		(net "TP_CPU0_UPI2_RSVD_CM13")
	)
	(via
		(at 293.22776 -94.042484)
		(size 0.508)
		(drill 0.254)
		(layers "F.Cu" "B.Cu")
		(net "TP_CPU0_UPI2_RSVD_CM13")
	)
	(segment
		(start 293.51478 -92.556584)
		(end 294.08628 -92.556584)
		(width 0.10795)
		(layer "F.Cu")
		(net "TP_CPU0_UPI2_RSVD_CU14")
	)
	(via
		(at 294.08628 -92.556584)
		(size 0.508)
		(drill 0.254)
		(layers "F.Cu" "B.Cu")
		(net "TP_CPU0_UPI2_RSVD_CU14")
	)
	(segment
		(start 295.23182 -93.547184)
		(end 295.80332 -93.547184)
		(width 0.10795)
		(layer "F.Cu")
		(net "TP_CPU0_UPI2_RSVD_CW14")
	)
	(via
		(at 295.80332 -93.547184)
		(size 0.508)
		(drill 0.254)
		(layers "F.Cu" "B.Cu")
		(net "TP_CPU0_UPI2_RSVD_CW14")
	)
	(segment
		(start 294.3733 -92.061538)
		(end 294.9448 -92.061538)
		(width 0.10795)
		(layer "F.Cu")
		(net "TP_CPU0_UPI2_RSVD_DA16")
	)
	(via
		(at 294.9448 -92.061538)
		(size 0.508)
		(drill 0.254)
		(layers "F.Cu" "B.Cu")
		(net "TP_CPU0_UPI2_RSVD_DA16")
	)
	(segment
		(start 299.524166 -82.155284)
		(end 300.095666 -82.155284)
		(width 0.10795)
		(layer "F.Cu")
		(net "TP_CPU0_UPI2_RSVD_DM21")
	)
	(via
		(at 300.095666 -82.155284)
		(size 0.508)
		(drill 0.254)
		(layers "F.Cu" "B.Cu")
		(net "TP_CPU0_UPI2_RSVD_DM21")
	)
	(segment
		(start 297.807126 -82.155284)
		(end 298.378626 -82.155284)
		(width 0.10795)
		(layer "F.Cu")
		(net "TP_CPU0_UPI2_RSVD_DT21")
	)
	(via
		(at 298.378626 -82.155284)
		(size 0.508)
		(drill 0.254)
		(layers "F.Cu" "B.Cu")
		(net "TP_CPU0_UPI2_RSVD_DT21")
	)
	(via
		(at 156.349446 -150.774146)
		(size 0.508)
		(drill 0.254)
		(layers "F.Cu" "B.Cu")
		(net "TP_CH_M_DIMM_M1_RFU_2")
	)
	(segment
		(start 156.349446 -152.078436)
		(end 156.349446 -150.774146)
		(width 0.10795)
		(layer "B.Cu")
		(net "TP_CH_M_DIMM_M1_RFU_2")
	)
	(via
		(at 104.499664 -148.773388)
		(size 0.4572)
		(drill 0.2032)
		(layers "F.Cu" "B.Cu")
		(net "TP_CH_M_DIMM_M1_RFU_1")
	)
	(segment
		(start 104.49941 -148.773134)
		(end 104.499664 -148.773388)
		(width 0.10795)
		(layer "B.Cu")
		(net "TP_CH_M_DIMM_M1_RFU_1")
	)
	(segment
		(start 104.49941 -147.478496)
		(end 104.49941 -148.773134)
		(width 0.10795)
		(layer "B.Cu")
		(net "TP_CH_M_DIMM_M1_RFU_1")
	)
	(via
		(at 80.699356 -148.771356)
		(size 0.4572)
		(drill 0.2032)
		(layers "F.Cu" "B.Cu")
		(net "TP_CH_M_DIMM_M1_RFU_0")
	)
	(segment
		(start 80.699356 -148.771356)
		(end 80.699356 -147.478496)
		(width 0.10795)
		(layer "B.Cu")
		(net "TP_CH_M_DIMM_M1_RFU_0")
	)
	(segment
		(start 156.349446 -152.273)
		(end 156.349446 -153.542746)
		(width 0.10795)
		(layer "F.Cu")
		(net "TP_CH_M_DIMM_M0_RFU_2")
	)
	(via
		(at 156.349446 -153.542746)
		(size 0.508)
		(drill 0.254)
		(layers "F.Cu" "B.Cu")
		(net "TP_CH_M_DIMM_M0_RFU_2")
	)
	(segment
		(start 104.49941 -156.87294)
		(end 104.49941 -154.905456)
		(width 0.10795)
		(layer "F.Cu")
		(net "TP_CH_M_DIMM_M0_RFU_1")
	)
	(via
		(at 104.49941 -154.905456)
		(size 0.508)
		(drill 0.254)
		(layers "F.Cu" "B.Cu")
		(net "TP_CH_M_DIMM_M0_RFU_1")
	)
	(segment
		(start 80.699356 -156.87294)
		(end 80.699356 -154.905456)
		(width 0.10795)
		(layer "F.Cu")
		(net "TP_CH_M_DIMM_M0_RFU_0")
	)
	(via
		(at 80.699356 -154.905456)
		(size 0.508)
		(drill 0.254)
		(layers "F.Cu" "B.Cu")
		(net "TP_CH_M_DIMM_M0_RFU_0")
	)
	(segment
		(start 156.349446 -142.6718)
		(end 156.349446 -143.941546)
		(width 0.10795)
		(layer "F.Cu")
		(net "TP_CH_L_DIMM_L0_RFU_2")
	)
	(via
		(at 156.349446 -143.941546)
		(size 0.508)
		(drill 0.254)
		(layers "F.Cu" "B.Cu")
		(net "TP_CH_L_DIMM_L0_RFU_2")
	)
	(segment
		(start 104.49941 -146.013932)
		(end 104.499664 -146.013678)
		(width 0.10795)
		(layer "F.Cu")
		(net "TP_CH_L_DIMM_L0_RFU_1")
	)
	(segment
		(start 104.499664 -146.013678)
		(end 104.499664 -145.988278)
		(width 0.10795)
		(layer "F.Cu")
		(net "TP_CH_L_DIMM_L0_RFU_1")
	)
	(segment
		(start 104.49941 -147.27174)
		(end 104.49941 -146.013932)
		(width 0.10795)
		(layer "F.Cu")
		(net "TP_CH_L_DIMM_L0_RFU_1")
	)
	(via
		(at 104.499664 -145.988278)
		(size 0.4572)
		(drill 0.2032)
		(layers "F.Cu" "B.Cu")
		(net "TP_CH_L_DIMM_L0_RFU_1")
	)
	(segment
		(start 80.699356 -147.27174)
		(end 80.699356 -145.988278)
		(width 0.10795)
		(layer "F.Cu")
		(net "TP_CH_L_DIMM_L0_RFU_0")
	)
	(via
		(at 80.699356 -145.988278)
		(size 0.4572)
		(drill 0.2032)
		(layers "F.Cu" "B.Cu")
		(net "TP_CH_L_DIMM_L0_RFU_0")
	)
	(via
		(at 156.349446 -141.172946)
		(size 0.508)
		(drill 0.254)
		(layers "F.Cu" "B.Cu")
		(net "TP_CH_L_DIMM0_RFU_2")
	)
	(segment
		(start 156.349446 -142.477236)
		(end 156.349446 -141.172946)
		(width 0.10795)
		(layer "B.Cu")
		(net "TP_CH_L_DIMM0_RFU_2")
	)
	(via
		(at 104.49941 -139.171934)
		(size 0.4572)
		(drill 0.2032)
		(layers "F.Cu" "B.Cu")
		(net "TP_CH_L_DIMM0_RFU_1")
	)
	(segment
		(start 104.49941 -139.171934)
		(end 104.49941 -137.877296)
		(width 0.10795)
		(layer "B.Cu")
		(net "TP_CH_L_DIMM0_RFU_1")
	)
	(via
		(at 80.699356 -139.170156)
		(size 0.4572)
		(drill 0.2032)
		(layers "F.Cu" "B.Cu")
		(net "TP_CH_L_DIMM0_RFU_0")
	)
	(segment
		(start 80.699356 -139.170156)
		(end 80.699356 -137.877296)
		(width 0.10795)
		(layer "B.Cu")
		(net "TP_CH_L_DIMM0_RFU_0")
	)
	(segment
		(start 156.349446 -133.0706)
		(end 156.349446 -134.340346)
		(width 0.10795)
		(layer "F.Cu")
		(net "TP_CH_K_DIMM_K0_RFU_2")
	)
	(via
		(at 156.349446 -134.340346)
		(size 0.508)
		(drill 0.254)
		(layers "F.Cu" "B.Cu")
		(net "TP_CH_K_DIMM_K0_RFU_2")
	)
	(segment
		(start 104.49941 -136.412732)
		(end 104.499664 -136.412478)
		(width 0.10795)
		(layer "F.Cu")
		(net "TP_CH_K_DIMM_K0_RFU_1")
	)
	(segment
		(start 104.499664 -136.412478)
		(end 104.499664 -136.387078)
		(width 0.10795)
		(layer "F.Cu")
		(net "TP_CH_K_DIMM_K0_RFU_1")
	)
	(segment
		(start 104.49941 -137.67054)
		(end 104.49941 -136.412732)
		(width 0.10795)
		(layer "F.Cu")
		(net "TP_CH_K_DIMM_K0_RFU_1")
	)
	(via
		(at 104.499664 -136.387078)
		(size 0.4572)
		(drill 0.2032)
		(layers "F.Cu" "B.Cu")
		(net "TP_CH_K_DIMM_K0_RFU_1")
	)
	(segment
		(start 80.699356 -137.67054)
		(end 80.699356 -136.387078)
		(width 0.10795)
		(layer "F.Cu")
		(net "TP_CH_K_DIMM_K0_RFU_0")
	)
	(via
		(at 80.699356 -136.387078)
		(size 0.4572)
		(drill 0.2032)
		(layers "F.Cu" "B.Cu")
		(net "TP_CH_K_DIMM_K0_RFU_0")
	)
	(via
		(at 156.349446 -131.571746)
		(size 0.508)
		(drill 0.254)
		(layers "F.Cu" "B.Cu")
		(net "TP_CH_K_DIMM0_RFU_2")
	)
	(segment
		(start 156.349446 -132.876036)
		(end 156.349446 -131.571746)
		(width 0.10795)
		(layer "B.Cu")
		(net "TP_CH_K_DIMM0_RFU_2")
	)
	(via
		(at 104.49941 -129.568956)
		(size 0.508)
		(drill 0.254)
		(layers "F.Cu" "B.Cu")
		(net "TP_CH_K_DIMM0_RFU_1")
	)
	(segment
		(start 104.49941 -128.276096)
		(end 104.49941 -129.568956)
		(width 0.10795)
		(layer "B.Cu")
		(net "TP_CH_K_DIMM0_RFU_1")
	)
	(via
		(at 80.699356 -129.568956)
		(size 0.508)
		(drill 0.254)
		(layers "F.Cu" "B.Cu")
		(net "TP_CH_K_DIMM0_RFU_0")
	)
	(segment
		(start 80.699356 -128.276096)
		(end 80.699356 -129.568956)
		(width 0.10795)
		(layer "B.Cu")
		(net "TP_CH_K_DIMM0_RFU_0")
	)
	(via
		(at 156.349446 -4.317746)
		(size 0.508)
		(drill 0.254)
		(layers "F.Cu" "B.Cu")
		(net "TP_CH_J_DIMM_J1_RFU_2")
	)
	(segment
		(start 156.349446 -5.621782)
		(end 156.349446 -4.317746)
		(width 0.10795)
		(layer "B.Cu")
		(net "TP_CH_J_DIMM_J1_RFU_2")
	)
	(via
		(at 104.499664 -2.316988)
		(size 0.4572)
		(drill 0.2032)
		(layers "F.Cu" "B.Cu")
		(net "TP_CH_J_DIMM_J1_RFU_1")
	)
	(segment
		(start 104.49941 -1.021842)
		(end 104.49941 -2.316734)
		(width 0.10795)
		(layer "B.Cu")
		(net "TP_CH_J_DIMM_J1_RFU_1")
	)
	(segment
		(start 104.49941 -2.316734)
		(end 104.499664 -2.316988)
		(width 0.10795)
		(layer "B.Cu")
		(net "TP_CH_J_DIMM_J1_RFU_1")
	)
	(via
		(at 80.699356 -2.314956)
		(size 0.4572)
		(drill 0.2032)
		(layers "F.Cu" "B.Cu")
		(net "TP_CH_J_DIMM_J1_RFU_0")
	)
	(segment
		(start 80.699356 -1.021842)
		(end 80.699356 -2.314956)
		(width 0.10795)
		(layer "B.Cu")
		(net "TP_CH_J_DIMM_J1_RFU_0")
	)
	(segment
		(start 156.349446 3.778758)
		(end 156.349446 2.514854)
		(width 0.10795)
		(layer "F.Cu")
		(net "TP_CH_J_DIMM_J0_RFU_2")
	)
	(via
		(at 156.349446 2.514854)
		(size 0.508)
		(drill 0.254)
		(layers "F.Cu" "B.Cu")
		(net "TP_CH_J_DIMM_J0_RFU_2")
	)
	(segment
		(start 104.49941 -0.821182)
		(end 104.49941 1.152144)
		(width 0.10795)
		(layer "F.Cu")
		(net "TP_CH_J_DIMM_J0_RFU_1")
	)
	(via
		(at 104.49941 1.152144)
		(size 0.508)
		(drill 0.254)
		(layers "F.Cu" "B.Cu")
		(net "TP_CH_J_DIMM_J0_RFU_1")
	)
	(segment
		(start 80.699356 -0.821182)
		(end 80.699356 1.152144)
		(width 0.10795)
		(layer "F.Cu")
		(net "TP_CH_J_DIMM_J0_RFU_0")
	)
	(via
		(at 80.699356 1.152144)
		(size 0.508)
		(drill 0.254)
		(layers "F.Cu" "B.Cu")
		(net "TP_CH_J_DIMM_J0_RFU_0")
	)
	(segment
		(start 156.349446 -5.822442)
		(end 156.349446 -7.086346)
		(width 0.10795)
		(layer "F.Cu")
		(net "TP_CH_H_DIMM_H0_RFU_2")
	)
	(via
		(at 156.349446 -7.086346)
		(size 0.508)
		(drill 0.254)
		(layers "F.Cu" "B.Cu")
		(net "TP_CH_H_DIMM_H0_RFU_2")
	)
	(segment
		(start 104.49941 -10.422382)
		(end 104.49941 -9.158732)
		(width 0.10795)
		(layer "F.Cu")
		(net "TP_CH_H_DIMM_H0_RFU_1")
	)
	(via
		(at 104.49941 -9.158732)
		(size 0.4572)
		(drill 0.2032)
		(layers "F.Cu" "B.Cu")
		(net "TP_CH_H_DIMM_H0_RFU_1")
	)
	(segment
		(start 80.699356 -9.133078)
		(end 80.699356 -10.422382)
		(width 0.10795)
		(layer "F.Cu")
		(net "TP_CH_H_DIMM_H0_RFU_0")
	)
	(via
		(at 80.699356 -9.133078)
		(size 0.4572)
		(drill 0.2032)
		(layers "F.Cu" "B.Cu")
		(net "TP_CH_H_DIMM_H0_RFU_0")
	)
	(via
		(at 156.349446 -13.918946)
		(size 0.508)
		(drill 0.254)
		(layers "F.Cu" "B.Cu")
		(net "TP_CH_H_DIMM0_RFU_2")
	)
	(segment
		(start 156.349446 -15.222982)
		(end 156.349446 -13.918946)
		(width 0.10795)
		(layer "B.Cu")
		(net "TP_CH_H_DIMM0_RFU_2")
	)
	(via
		(at 104.499664 -11.918188)
		(size 0.4572)
		(drill 0.2032)
		(layers "F.Cu" "B.Cu")
		(net "TP_CH_H_DIMM0_RFU_1")
	)
	(segment
		(start 104.49941 -11.917934)
		(end 104.499664 -11.918188)
		(width 0.10795)
		(layer "B.Cu")
		(net "TP_CH_H_DIMM0_RFU_1")
	)
	(segment
		(start 104.49941 -10.623042)
		(end 104.49941 -11.917934)
		(width 0.10795)
		(layer "B.Cu")
		(net "TP_CH_H_DIMM0_RFU_1")
	)
	(via
		(at 80.699356 -11.916156)
		(size 0.4572)
		(drill 0.2032)
		(layers "F.Cu" "B.Cu")
		(net "TP_CH_H_DIMM0_RFU_0")
	)
	(segment
		(start 80.699356 -10.623042)
		(end 80.699356 -11.916156)
		(width 0.10795)
		(layer "B.Cu")
		(net "TP_CH_H_DIMM0_RFU_0")
	)
	(segment
		(start 156.349446 -15.423642)
		(end 156.349446 -16.687546)
		(width 0.10795)
		(layer "F.Cu")
		(net "TP_CH_G_DIMM_G0_RFU_2")
	)
	(via
		(at 156.349446 -16.687546)
		(size 0.508)
		(drill 0.254)
		(layers "F.Cu" "B.Cu")
		(net "TP_CH_G_DIMM_G0_RFU_2")
	)
	(segment
		(start 104.49941 -18.759932)
		(end 104.499664 -18.759678)
		(width 0.10795)
		(layer "F.Cu")
		(net "TP_CH_G_DIMM_G0_RFU_1")
	)
	(segment
		(start 104.499664 -18.759678)
		(end 104.499664 -18.734278)
		(width 0.10795)
		(layer "F.Cu")
		(net "TP_CH_G_DIMM_G0_RFU_1")
	)
	(segment
		(start 104.49941 -20.023582)
		(end 104.49941 -18.759932)
		(width 0.10795)
		(layer "F.Cu")
		(net "TP_CH_G_DIMM_G0_RFU_1")
	)
	(via
		(at 104.499664 -18.734278)
		(size 0.4572)
		(drill 0.2032)
		(layers "F.Cu" "B.Cu")
		(net "TP_CH_G_DIMM_G0_RFU_1")
	)
	(segment
		(start 80.699356 -18.734278)
		(end 80.699356 -20.023582)
		(width 0.10795)
		(layer "F.Cu")
		(net "TP_CH_G_DIMM_G0_RFU_0")
	)
	(via
		(at 80.699356 -18.734278)
		(size 0.4572)
		(drill 0.2032)
		(layers "F.Cu" "B.Cu")
		(net "TP_CH_G_DIMM_G0_RFU_0")
	)
	(via
		(at 156.349446 -23.520146)
		(size 0.508)
		(drill 0.254)
		(layers "F.Cu" "B.Cu")
		(net "TP_CH_G_DIMM0_RFU_2")
	)
	(segment
		(start 156.349446 -23.520146)
		(end 156.349446 -24.824182)
		(width 0.10795)
		(layer "B.Cu")
		(net "TP_CH_G_DIMM0_RFU_2")
	)
	(via
		(at 104.49941 -21.517356)
		(size 0.508)
		(drill 0.254)
		(layers "F.Cu" "B.Cu")
		(net "TP_CH_G_DIMM0_RFU_1")
	)
	(segment
		(start 104.49941 -20.224242)
		(end 104.49941 -21.517356)
		(width 0.10795)
		(layer "B.Cu")
		(net "TP_CH_G_DIMM0_RFU_1")
	)
	(via
		(at 80.699356 -21.517356)
		(size 0.508)
		(drill 0.254)
		(layers "F.Cu" "B.Cu")
		(net "TP_CH_G_DIMM0_RFU_0")
	)
	(segment
		(start 80.699356 -20.224242)
		(end 80.699356 -21.517356)
		(width 0.10795)
		(layer "B.Cu")
		(net "TP_CH_G_DIMM0_RFU_0")
	)
	(via
		(at 321.349878 -150.774146)
		(size 0.508)
		(drill 0.254)
		(layers "F.Cu" "B.Cu")
		(net "TP_CH_F_DIMM_F1_RFU_2")
	)
	(segment
		(start 321.350386 -152.078436)
		(end 321.350386 -150.774654)
		(width 0.10795)
		(layer "B.Cu")
		(net "TP_CH_F_DIMM_F1_RFU_2")
	)
	(segment
		(start 321.350386 -150.774654)
		(end 321.349878 -150.774146)
		(width 0.10795)
		(layer "B.Cu")
		(net "TP_CH_F_DIMM_F1_RFU_2")
	)
	(via
		(at 269.500096 -148.773388)
		(size 0.4572)
		(drill 0.2032)
		(layers "F.Cu" "B.Cu")
		(net "TP_CH_F_DIMM_F1_RFU_1")
	)
	(segment
		(start 269.50035 -148.773134)
		(end 269.500096 -148.773388)
		(width 0.10795)
		(layer "B.Cu")
		(net "TP_CH_F_DIMM_F1_RFU_1")
	)
	(segment
		(start 269.50035 -147.478496)
		(end 269.50035 -148.773134)
		(width 0.10795)
		(layer "B.Cu")
		(net "TP_CH_F_DIMM_F1_RFU_1")
	)
	(via
		(at 245.699788 -148.771356)
		(size 0.4572)
		(drill 0.2032)
		(layers "F.Cu" "B.Cu")
		(net "TP_CH_F_DIMM_F1_RFU_0")
	)
	(segment
		(start 245.700296 -148.770848)
		(end 245.699788 -148.771356)
		(width 0.10795)
		(layer "B.Cu")
		(net "TP_CH_F_DIMM_F1_RFU_0")
	)
	(segment
		(start 245.700296 -147.478496)
		(end 245.700296 -148.770848)
		(width 0.10795)
		(layer "B.Cu")
		(net "TP_CH_F_DIMM_F1_RFU_0")
	)
	(segment
		(start 321.350386 -152.273)
		(end 321.349878 -153.536904)
		(width 0.10795)
		(layer "F.Cu")
		(net "TP_CH_F_DIMM_F0_RFU_2")
	)
	(via
		(at 321.349878 -153.536904)
		(size 0.508)
		(drill 0.254)
		(layers "F.Cu" "B.Cu")
		(net "TP_CH_F_DIMM_F0_RFU_2")
	)
	(segment
		(start 269.50035 -156.87294)
		(end 269.499842 -154.905456)
		(width 0.10795)
		(layer "F.Cu")
		(net "TP_CH_F_DIMM_F0_RFU_1")
	)
	(via
		(at 269.499842 -154.905456)
		(size 0.508)
		(drill 0.254)
		(layers "F.Cu" "B.Cu")
		(net "TP_CH_F_DIMM_F0_RFU_1")
	)
	(segment
		(start 245.700296 -156.87294)
		(end 245.699788 -154.905456)
		(width 0.10795)
		(layer "F.Cu")
		(net "TP_CH_F_DIMM_F0_RFU_0")
	)
	(via
		(at 245.699788 -154.905456)
		(size 0.508)
		(drill 0.254)
		(layers "F.Cu" "B.Cu")
		(net "TP_CH_F_DIMM_F0_RFU_0")
	)
	(via
		(at 321.349878 -141.172946)
		(size 0.508)
		(drill 0.254)
		(layers "F.Cu" "B.Cu")
		(net "TP_CH_E_DIMM_E1_RFU_2")
	)
	(segment
		(start 321.350386 -141.173454)
		(end 321.349878 -141.172946)
		(width 0.10795)
		(layer "B.Cu")
		(net "TP_CH_E_DIMM_E1_RFU_2")
	)
	(segment
		(start 321.350386 -142.477236)
		(end 321.350386 -141.173454)
		(width 0.10795)
		(layer "B.Cu")
		(net "TP_CH_E_DIMM_E1_RFU_2")
	)
	(via
		(at 269.500096 -139.172188)
		(size 0.4572)
		(drill 0.2032)
		(layers "F.Cu" "B.Cu")
		(net "TP_CH_E_DIMM_E1_RFU_1")
	)
	(segment
		(start 269.50035 -139.171934)
		(end 269.500096 -139.172188)
		(width 0.10795)
		(layer "B.Cu")
		(net "TP_CH_E_DIMM_E1_RFU_1")
	)
	(segment
		(start 269.50035 -137.877296)
		(end 269.50035 -139.171934)
		(width 0.10795)
		(layer "B.Cu")
		(net "TP_CH_E_DIMM_E1_RFU_1")
	)
	(via
		(at 245.699788 -139.170156)
		(size 0.4572)
		(drill 0.2032)
		(layers "F.Cu" "B.Cu")
		(net "TP_CH_E_DIMM_E1_RFU_0")
	)
	(segment
		(start 245.700296 -139.169648)
		(end 245.699788 -139.170156)
		(width 0.10795)
		(layer "B.Cu")
		(net "TP_CH_E_DIMM_E1_RFU_0")
	)
	(segment
		(start 245.700296 -137.877296)
		(end 245.700296 -139.169648)
		(width 0.10795)
		(layer "B.Cu")
		(net "TP_CH_E_DIMM_E1_RFU_0")
	)
	(segment
		(start 321.350386 -142.6718)
		(end 321.349878 -143.935704)
		(width 0.10795)
		(layer "F.Cu")
		(net "TP_CH_E_DIMM_E0_RFU_2")
	)
	(via
		(at 321.349878 -143.935704)
		(size 0.508)
		(drill 0.254)
		(layers "F.Cu" "B.Cu")
		(net "TP_CH_E_DIMM_E0_RFU_2")
	)
	(segment
		(start 269.50035 -147.27174)
		(end 269.500096 -145.988278)
		(width 0.10795)
		(layer "F.Cu")
		(net "TP_CH_E_DIMM_E0_RFU_1")
	)
	(via
		(at 269.500096 -145.988278)
		(size 0.4572)
		(drill 0.2032)
		(layers "F.Cu" "B.Cu")
		(net "TP_CH_E_DIMM_E0_RFU_1")
	)
	(segment
		(start 245.700296 -147.27174)
		(end 245.699788 -145.988278)
		(width 0.10795)
		(layer "F.Cu")
		(net "TP_CH_E_DIMM_E0_RFU_0")
	)
	(via
		(at 245.699788 -145.988278)
		(size 0.4572)
		(drill 0.2032)
		(layers "F.Cu" "B.Cu")
		(net "TP_CH_E_DIMM_E0_RFU_0")
	)
	(via
		(at 321.349878 -131.571746)
		(size 0.508)
		(drill 0.254)
		(layers "F.Cu" "B.Cu")
		(net "TP_CH_D_DIMM_D1_RFU_2")
	)
	(segment
		(start 321.350386 -131.572254)
		(end 321.349878 -131.571746)
		(width 0.10795)
		(layer "B.Cu")
		(net "TP_CH_D_DIMM_D1_RFU_2")
	)
	(segment
		(start 321.350386 -132.876036)
		(end 321.350386 -131.572254)
		(width 0.10795)
		(layer "B.Cu")
		(net "TP_CH_D_DIMM_D1_RFU_2")
	)
	(via
		(at 269.499842 -129.568956)
		(size 0.508)
		(drill 0.254)
		(layers "F.Cu" "B.Cu")
		(net "TP_CH_D_DIMM_D1_RFU_1")
	)
	(segment
		(start 269.50035 -129.568448)
		(end 269.499842 -129.568956)
		(width 0.10795)
		(layer "B.Cu")
		(net "TP_CH_D_DIMM_D1_RFU_1")
	)
	(segment
		(start 269.50035 -128.276096)
		(end 269.50035 -129.568448)
		(width 0.10795)
		(layer "B.Cu")
		(net "TP_CH_D_DIMM_D1_RFU_1")
	)
	(via
		(at 245.699788 -129.568956)
		(size 0.508)
		(drill 0.254)
		(layers "F.Cu" "B.Cu")
		(net "TP_CH_D_DIMM_D1_RFU_0")
	)
	(segment
		(start 245.700296 -128.276096)
		(end 245.700296 -129.568448)
		(width 0.10795)
		(layer "B.Cu")
		(net "TP_CH_D_DIMM_D1_RFU_0")
	)
	(segment
		(start 245.700296 -129.568448)
		(end 245.699788 -129.568956)
		(width 0.10795)
		(layer "B.Cu")
		(net "TP_CH_D_DIMM_D1_RFU_0")
	)
	(segment
		(start 321.350386 -133.0706)
		(end 321.349878 -134.334504)
		(width 0.10795)
		(layer "F.Cu")
		(net "TP_CH_D_DIMM_D0_RFU_2")
	)
	(via
		(at 321.349878 -134.334504)
		(size 0.508)
		(drill 0.254)
		(layers "F.Cu" "B.Cu")
		(net "TP_CH_D_DIMM_D0_RFU_2")
	)
	(segment
		(start 269.50035 -137.67054)
		(end 269.500096 -136.387078)
		(width 0.10795)
		(layer "F.Cu")
		(net "TP_CH_D_DIMM_D0_RFU_1")
	)
	(via
		(at 269.500096 -136.387078)
		(size 0.4572)
		(drill 0.2032)
		(layers "F.Cu" "B.Cu")
		(net "TP_CH_D_DIMM_D0_RFU_1")
	)
	(segment
		(start 245.700296 -137.67054)
		(end 245.699788 -136.387078)
		(width 0.10795)
		(layer "F.Cu")
		(net "TP_CH_D_DIMM_D0_RFU_0")
	)
	(via
		(at 245.699788 -136.387078)
		(size 0.4572)
		(drill 0.2032)
		(layers "F.Cu" "B.Cu")
		(net "TP_CH_D_DIMM_D0_RFU_0")
	)
	(via
		(at 321.349878 -4.317746)
		(size 0.508)
		(drill 0.254)
		(layers "F.Cu" "B.Cu")
		(net "TP_CH_C_DIMM_C1_RFU_2")
	)
	(segment
		(start 321.350386 -4.318254)
		(end 321.349878 -4.317746)
		(width 0.10795)
		(layer "B.Cu")
		(net "TP_CH_C_DIMM_C1_RFU_2")
	)
	(segment
		(start 321.350386 -5.621782)
		(end 321.350386 -4.318254)
		(width 0.10795)
		(layer "B.Cu")
		(net "TP_CH_C_DIMM_C1_RFU_2")
	)
	(via
		(at 269.500096 -2.316988)
		(size 0.4572)
		(drill 0.2032)
		(layers "F.Cu" "B.Cu")
		(net "TP_CH_C_DIMM_C1_RFU_1")
	)
	(segment
		(start 269.50035 -2.316734)
		(end 269.500096 -2.316988)
		(width 0.10795)
		(layer "B.Cu")
		(net "TP_CH_C_DIMM_C1_RFU_1")
	)
	(segment
		(start 269.50035 -1.021842)
		(end 269.50035 -2.316734)
		(width 0.10795)
		(layer "B.Cu")
		(net "TP_CH_C_DIMM_C1_RFU_1")
	)
	(via
		(at 245.699788 -2.314956)
		(size 0.4572)
		(drill 0.2032)
		(layers "F.Cu" "B.Cu")
		(net "TP_CH_C_DIMM_C1_RFU_0")
	)
	(segment
		(start 245.700296 -1.021842)
		(end 245.700296 -2.314448)
		(width 0.10795)
		(layer "B.Cu")
		(net "TP_CH_C_DIMM_C1_RFU_0")
	)
	(segment
		(start 245.700296 -2.314448)
		(end 245.699788 -2.314956)
		(width 0.10795)
		(layer "B.Cu")
		(net "TP_CH_C_DIMM_C1_RFU_0")
	)
	(segment
		(start 321.349878 2.60096)
		(end 321.349878 2.514854)
		(width 0.10795)
		(layer "F.Cu")
		(net "TP_CH_C_DIMM_C0_RFU_2")
	)
	(segment
		(start 321.350386 3.778758)
		(end 321.349878 2.60096)
		(width 0.10795)
		(layer "F.Cu")
		(net "TP_CH_C_DIMM_C0_RFU_2")
	)
	(via
		(at 321.349878 2.514854)
		(size 0.508)
		(drill 0.254)
		(layers "F.Cu" "B.Cu")
		(net "TP_CH_C_DIMM_C0_RFU_2")
	)
	(segment
		(start 269.50035 -0.821182)
		(end 269.499842 1.152144)
		(width 0.10795)
		(layer "F.Cu")
		(net "TP_CH_C_DIMM_C0_RFU_1")
	)
	(via
		(at 269.499842 1.152144)
		(size 0.508)
		(drill 0.254)
		(layers "F.Cu" "B.Cu")
		(net "TP_CH_C_DIMM_C0_RFU_1")
	)
	(segment
		(start 245.700296 -0.821182)
		(end 245.699788 1.152144)
		(width 0.10795)
		(layer "F.Cu")
		(net "TP_CH_C_DIMM_C0_RFU_0")
	)
	(via
		(at 245.699788 1.152144)
		(size 0.508)
		(drill 0.254)
		(layers "F.Cu" "B.Cu")
		(net "TP_CH_C_DIMM_C0_RFU_0")
	)
	(via
		(at 321.349878 -13.918946)
		(size 0.508)
		(drill 0.254)
		(layers "F.Cu" "B.Cu")
		(net "TP_CH_B_DIMM_B1_RFU_2")
	)
	(segment
		(start 321.350386 -15.222982)
		(end 321.350386 -13.919454)
		(width 0.10795)
		(layer "B.Cu")
		(net "TP_CH_B_DIMM_B1_RFU_2")
	)
	(segment
		(start 321.350386 -13.919454)
		(end 321.349878 -13.918946)
		(width 0.10795)
		(layer "B.Cu")
		(net "TP_CH_B_DIMM_B1_RFU_2")
	)
	(via
		(at 269.500096 -11.918188)
		(size 0.4572)
		(drill 0.2032)
		(layers "F.Cu" "B.Cu")
		(net "TP_CH_B_DIMM_B1_RFU_1")
	)
	(segment
		(start 269.50035 -10.623042)
		(end 269.50035 -11.917934)
		(width 0.10795)
		(layer "B.Cu")
		(net "TP_CH_B_DIMM_B1_RFU_1")
	)
	(segment
		(start 269.50035 -11.917934)
		(end 269.500096 -11.918188)
		(width 0.10795)
		(layer "B.Cu")
		(net "TP_CH_B_DIMM_B1_RFU_1")
	)
	(via
		(at 245.699788 -11.916156)
		(size 0.4572)
		(drill 0.2032)
		(layers "F.Cu" "B.Cu")
		(net "TP_CH_B_DIMM_B1_RFU_0")
	)
	(segment
		(start 245.700296 -10.623042)
		(end 245.700296 -11.915648)
		(width 0.10795)
		(layer "B.Cu")
		(net "TP_CH_B_DIMM_B1_RFU_0")
	)
	(segment
		(start 245.700296 -11.915648)
		(end 245.699788 -11.916156)
		(width 0.10795)
		(layer "B.Cu")
		(net "TP_CH_B_DIMM_B1_RFU_0")
	)
	(segment
		(start 321.350386 -5.822442)
		(end 321.349878 -7.086346)
		(width 0.10795)
		(layer "F.Cu")
		(net "TP_CH_B_DIMM_B0_RFU_2")
	)
	(via
		(at 321.349878 -7.086346)
		(size 0.508)
		(drill 0.254)
		(layers "F.Cu" "B.Cu")
		(net "TP_CH_B_DIMM_B0_RFU_2")
	)
	(segment
		(start 269.50035 -10.422382)
		(end 269.500096 -9.133078)
		(width 0.10795)
		(layer "F.Cu")
		(net "TP_CH_B_DIMM_B0_RFU_1")
	)
	(via
		(at 269.500096 -9.133078)
		(size 0.4572)
		(drill 0.2032)
		(layers "F.Cu" "B.Cu")
		(net "TP_CH_B_DIMM_B0_RFU_1")
	)
	(segment
		(start 245.700296 -10.422382)
		(end 245.699788 -9.133078)
		(width 0.10795)
		(layer "F.Cu")
		(net "TP_CH_B_DIMM_B0_RFU_0")
	)
	(via
		(at 245.699788 -9.133078)
		(size 0.4572)
		(drill 0.2032)
		(layers "F.Cu" "B.Cu")
		(net "TP_CH_B_DIMM_B0_RFU_0")
	)
	(via
		(at 321.349878 -23.520146)
		(size 0.508)
		(drill 0.254)
		(layers "F.Cu" "B.Cu")
		(net "TP_CH_A_DIMM_A1_RFU_2")
	)
	(segment
		(start 321.350386 -23.520654)
		(end 321.349878 -23.520146)
		(width 0.10795)
		(layer "B.Cu")
		(net "TP_CH_A_DIMM_A1_RFU_2")
	)
	(segment
		(start 321.350386 -24.824182)
		(end 321.350386 -23.520654)
		(width 0.10795)
		(layer "B.Cu")
		(net "TP_CH_A_DIMM_A1_RFU_2")
	)
	(via
		(at 269.499842 -21.517356)
		(size 0.508)
		(drill 0.254)
		(layers "F.Cu" "B.Cu")
		(net "TP_CH_A_DIMM_A1_RFU_1")
	)
	(segment
		(start 269.50035 -21.516848)
		(end 269.499842 -21.517356)
		(width 0.10795)
		(layer "B.Cu")
		(net "TP_CH_A_DIMM_A1_RFU_1")
	)
	(segment
		(start 269.50035 -20.224242)
		(end 269.50035 -21.516848)
		(width 0.10795)
		(layer "B.Cu")
		(net "TP_CH_A_DIMM_A1_RFU_1")
	)
	(via
		(at 245.699788 -21.517356)
		(size 0.508)
		(drill 0.254)
		(layers "F.Cu" "B.Cu")
		(net "TP_CH_A_DIMM_A1_RFU_0")
	)
	(segment
		(start 245.700296 -20.224242)
		(end 245.700296 -21.516848)
		(width 0.10795)
		(layer "B.Cu")
		(net "TP_CH_A_DIMM_A1_RFU_0")
	)
	(segment
		(start 245.700296 -21.516848)
		(end 245.699788 -21.517356)
		(width 0.10795)
		(layer "B.Cu")
		(net "TP_CH_A_DIMM_A1_RFU_0")
	)
	(segment
		(start 321.350386 -15.423642)
		(end 321.349878 -16.687546)
		(width 0.10795)
		(layer "F.Cu")
		(net "TP_CH_A_DIMM_A0_RFU_2")
	)
	(via
		(at 321.349878 -16.687546)
		(size 0.508)
		(drill 0.254)
		(layers "F.Cu" "B.Cu")
		(net "TP_CH_A_DIMM_A0_RFU_2")
	)
	(segment
		(start 269.50035 -20.023582)
		(end 269.500096 -18.734278)
		(width 0.10795)
		(layer "F.Cu")
		(net "TP_CH_A_DIMM_A0_RFU_1")
	)
	(via
		(at 269.500096 -18.734278)
		(size 0.4572)
		(drill 0.2032)
		(layers "F.Cu" "B.Cu")
		(net "TP_CH_A_DIMM_A0_RFU_1")
	)
	(segment
		(start 245.700296 -20.023582)
		(end 245.699788 -18.734278)
		(width 0.10795)
		(layer "F.Cu")
		(net "TP_CH_A_DIMM_A0_RFU_0")
	)
	(via
		(at 245.699788 -18.734278)
		(size 0.4572)
		(drill 0.2032)
		(layers "F.Cu" "B.Cu")
		(net "TP_CH_A_DIMM_A0_RFU_0")
	)
	(segment
		(start 123.363228 -75.716384)
		(end 123.934728 -75.716384)
		(width 0.10795)
		(layer "F.Cu")
		(net "TP_CD_HFI1_CPU1_RESET_N")
	)
	(via
		(at 123.934728 -75.716384)
		(size 0.508)
		(drill 0.254)
		(layers "F.Cu" "B.Cu")
		(net "TP_CD_HFI1_CPU1_RESET_N")
	)
	(segment
		(start 126.797308 -78.688438)
		(end 127.368808 -78.688438)
		(width 0.10795)
		(layer "F.Cu")
		(net "TP_CD_HFI1_CPU1_MODPRST_N")
	)
	(via
		(at 127.368808 -78.688438)
		(size 0.508)
		(drill 0.254)
		(layers "F.Cu" "B.Cu")
		(net "TP_CD_HFI1_CPU1_MODPRST_N")
	)
	(segment
		(start 123.363228 -76.706984)
		(end 123.934728 -76.706984)
		(width 0.10795)
		(layer "F.Cu")
		(net "TP_CD_HFI1_CPU1_LED_N")
	)
	(via
		(at 123.934728 -76.706984)
		(size 0.508)
		(drill 0.254)
		(layers "F.Cu" "B.Cu")
		(net "TP_CD_HFI1_CPU1_LED_N")
	)
	(segment
		(start 125.080268 -76.706984)
		(end 125.651768 -76.706984)
		(width 0.10795)
		(layer "F.Cu")
		(net "TP_CD_HFI1_CPU1_INT_N")
	)
	(via
		(at 125.651768 -76.706984)
		(size 0.508)
		(drill 0.254)
		(layers "F.Cu" "B.Cu")
		(net "TP_CD_HFI1_CPU1_INT_N")
	)
	(segment
		(start 124.221748 -75.221338)
		(end 124.793248 -75.221338)
		(width 0.10795)
		(layer "F.Cu")
		(net "TP_CD_HFI1_CPU1_I2CLK")
	)
	(via
		(at 124.793248 -75.221338)
		(size 0.508)
		(drill 0.254)
		(layers "F.Cu" "B.Cu")
		(net "TP_CD_HFI1_CPU1_I2CLK")
	)
	(segment
		(start 123.363228 -74.725784)
		(end 123.934728 -74.725784)
		(width 0.10795)
		(layer "F.Cu")
		(net "TP_CD_HFI1_CPU1_I2CDAT")
	)
	(via
		(at 123.934728 -74.725784)
		(size 0.508)
		(drill 0.254)
		(layers "F.Cu" "B.Cu")
		(net "TP_CD_HFI1_CPU1_I2CDAT")
	)
	(segment
		(start 122.504708 -77.202538)
		(end 123.076208 -77.202538)
		(width 0.10795)
		(layer "F.Cu")
		(net "TP_RST_CPU1_CD_HFI0_N")
	)
	(via
		(at 123.076208 -77.202538)
		(size 0.508)
		(drill 0.254)
		(layers "F.Cu" "B.Cu")
		(net "TP_RST_CPU1_CD_HFI0_N")
	)
	(segment
		(start 125.938788 -78.193138)
		(end 126.510288 -78.193138)
		(width 0.10795)
		(layer "F.Cu")
		(net "TP_FM_CPU1_CD_HFI0_MODPRST_N")
	)
	(via
		(at 126.510288 -78.193138)
		(size 0.508)
		(drill 0.254)
		(layers "F.Cu" "B.Cu")
		(net "TP_FM_CPU1_CD_HFI0_MODPRST_N")
	)
	(segment
		(start 125.080268 -75.716384)
		(end 125.651768 -75.716384)
		(width 0.10795)
		(layer "F.Cu")
		(net "TP_LED_CPU1_CD_HFI0_N")
	)
	(via
		(at 125.651768 -75.716384)
		(size 0.508)
		(drill 0.254)
		(layers "F.Cu" "B.Cu")
		(net "TP_LED_CPU1_CD_HFI0_N")
	)
	(segment
		(start 126.797308 -77.697584)
		(end 127.368808 -77.697584)
		(width 0.10795)
		(layer "F.Cu")
		(net "TP_IRQ_CPU1_CD_HFI0_N")
	)
	(via
		(at 127.368808 -77.697584)
		(size 0.508)
		(drill 0.254)
		(layers "F.Cu" "B.Cu")
		(net "TP_IRQ_CPU1_CD_HFI0_N")
	)
	(segment
		(start 124.221748 -77.202538)
		(end 124.793248 -77.202538)
		(width 0.10795)
		(layer "F.Cu")
		(net "TP_SMB_CPU1_CD_HFI0_I2CCLK")
	)
	(via
		(at 124.793248 -77.202538)
		(size 0.508)
		(drill 0.254)
		(layers "F.Cu" "B.Cu")
		(net "TP_SMB_CPU1_CD_HFI0_I2CCLK")
	)
	(segment
		(start 123.363228 -77.697584)
		(end 123.934728 -77.697584)
		(width 0.10795)
		(layer "F.Cu")
		(net "TP_SMB_CPU1_CD_HFI0_I2CDAT")
	)
	(via
		(at 123.934728 -77.697584)
		(size 0.508)
		(drill 0.254)
		(layers "F.Cu" "B.Cu")
		(net "TP_SMB_CPU1_CD_HFI0_I2CDAT")
	)
	(segment
		(start -1.695704 -127.4572)
		(end -1.0668 -127.4572)
		(width 0.10795)
		(layer "F.Cu")
		(net "SVID_VDIO_PVDDQ_KLM")
	)
	(segment
		(start -2.2606 -127.4572)
		(end -1.695704 -127.4572)
		(width 0.10795)
		(layer "F.Cu")
		(net "SVID_VDIO_PVDDQ_KLM")
	)
	(segment
		(start -0.758698 -127.765302)
		(end -0.3937 -127.765302)
		(width 0.10795)
		(layer "F.Cu")
		(net "SVID_VDIO_PVDDQ_KLM")
	)
	(segment
		(start -2.5146 -127.7112)
		(end -2.2606 -127.4572)
		(width 0.10795)
		(layer "F.Cu")
		(net "SVID_VDIO_PVDDQ_KLM")
	)
	(segment
		(start -1.0668 -127.4572)
		(end -0.758698 -127.765302)
		(width 0.10795)
		(layer "F.Cu")
		(net "SVID_VDIO_PVDDQ_KLM")
	)
	(via
		(at -1.422908 -126.649734)
		(size 0.6604)
		(drill 0.3302)
		(layers "F.Cu" "B.Cu")
		(net "SVID_VDIO_PVDDQ_KLM")
	)
	(via
		(at -1.695704 -127.4572)
		(size 0.508)
		(drill 0.254)
		(layers "F.Cu" "B.Cu")
		(net "SVID_VDIO_PVDDQ_KLM")
	)
	(segment
		(start -1.695704 -126.92253)
		(end -1.422908 -126.649734)
		(width 0.10795)
		(layer "B.Cu")
		(net "SVID_VDIO_PVDDQ_KLM")
	)
	(segment
		(start -1.695704 -127.4572)
		(end -1.695704 -126.92253)
		(width 0.10795)
		(layer "B.Cu")
		(net "SVID_VDIO_PVDDQ_KLM")
	)
	(segment
		(start 10.362184 -3.372104)
		(end 9.833102 -2.843022)
		(width 0.10795)
		(layer "F.Cu")
		(net "SVID_VDIO_PVDDQ_GHJ")
	)
	(segment
		(start 9.833102 -2.843022)
		(end 9.833102 -2.20345)
		(width 0.10795)
		(layer "F.Cu")
		(net "SVID_VDIO_PVDDQ_GHJ")
	)
	(segment
		(start 10.362184 -3.532124)
		(end 10.362184 -3.372104)
		(width 0.10795)
		(layer "F.Cu")
		(net "SVID_VDIO_PVDDQ_GHJ")
	)
	(segment
		(start 363.87024 -138.41857)
		(end 363.51083 -138.41857)
		(width 0.10795)
		(layer "F.Cu")
		(net "SVID_VDIO_PVDDQ_DEF")
	)
	(segment
		(start 362.589826 -138.714226)
		(end 362.783374 -138.714226)
		(width 0.10795)
		(layer "F.Cu")
		(net "SVID_VDIO_PVDDQ_DEF")
	)
	(segment
		(start 363.215174 -138.714226)
		(end 362.783374 -138.714226)
		(width 0.10795)
		(layer "F.Cu")
		(net "SVID_VDIO_PVDDQ_DEF")
	)
	(segment
		(start 363.51083 -138.41857)
		(end 363.215174 -138.714226)
		(width 0.10795)
		(layer "F.Cu")
		(net "SVID_VDIO_PVDDQ_DEF")
	)
	(segment
		(start 362.240068 -138.364468)
		(end 362.589826 -138.714226)
		(width 0.10795)
		(layer "F.Cu")
		(net "SVID_VDIO_PVDDQ_DEF")
	)
	(segment
		(start 361.74934 -138.364468)
		(end 362.240068 -138.364468)
		(width 0.10795)
		(layer "F.Cu")
		(net "SVID_VDIO_PVDDQ_DEF")
	)
	(via
		(at 362.783374 -138.714226)
		(size 0.508)
		(drill 0.254)
		(layers "F.Cu" "B.Cu")
		(net "SVID_VDIO_PVDDQ_DEF")
	)
	(segment
		(start 342.2269 -15.167102)
		(end 341.048594 -15.167102)
		(width 0.10795)
		(layer "F.Cu")
		(net "SVID_VDIO_PVDDQ_ABC")
	)
	(segment
		(start 340.703408 -15.512288)
		(end 339.832696 -16.383)
		(width 0.10795)
		(layer "F.Cu")
		(net "SVID_VDIO_PVDDQ_ABC")
	)
	(segment
		(start 339.832696 -16.383)
		(end 338.836 -16.383)
		(width 0.10795)
		(layer "F.Cu")
		(net "SVID_VDIO_PVDDQ_ABC")
	)
	(segment
		(start 341.048594 -15.167102)
		(end 340.703408 -15.512288)
		(width 0.10795)
		(layer "F.Cu")
		(net "SVID_VDIO_PVDDQ_ABC")
	)
	(via
		(at 340.703408 -15.512288)
		(size 0.762)
		(drill 0.381)
		(layers "F.Cu" "B.Cu")
		(net "SVID_VDIO_PVDDQ_ABC")
	)
	(segment
		(start 18.74647 -88.08847)
		(end 19.231102 -88.573102)
		(width 0.10795)
		(layer "F.Cu")
		(net "SVID_VDIO_PVCCIN_CPU1")
	)
	(segment
		(start 18.288 -87.7062)
		(end 18.67027 -88.08847)
		(width 0.10795)
		(layer "F.Cu")
		(net "SVID_VDIO_PVCCIN_CPU1")
	)
	(segment
		(start 18.67027 -88.08847)
		(end 18.74647 -88.08847)
		(width 0.10795)
		(layer "F.Cu")
		(net "SVID_VDIO_PVCCIN_CPU1")
	)
	(segment
		(start 19.231102 -88.573102)
		(end 19.231102 -89.5604)
		(width 0.10795)
		(layer "F.Cu")
		(net "SVID_VDIO_PVCCIN_CPU1")
	)
	(segment
		(start 184.077102 -65.70599)
		(end 183.769 -65.397888)
		(width 0.10795)
		(layer "F.Cu")
		(net "SVID_VDIO_PVCCIN_CPU0")
	)
	(segment
		(start 184.077102 -66.9544)
		(end 184.077102 -65.70599)
		(width 0.10795)
		(layer "F.Cu")
		(net "SVID_VDIO_PVCCIN_CPU0")
	)
	(segment
		(start 183.769 -65.397888)
		(end 183.769 -65.024)
		(width 0.10795)
		(layer "F.Cu")
		(net "SVID_VDIO_PVCCIN_CPU0")
	)
	(segment
		(start 18.5928 -88.392)
		(end 18.321274 -88.392)
		(width 0.10795)
		(layer "F.Cu")
		(net "SVID_VCLK_PVCCIN_CPU1")
	)
	(segment
		(start 18.321274 -88.392)
		(end 18.0594 -88.392)
		(width 0.10795)
		(layer "F.Cu")
		(net "SVID_VCLK_PVCCIN_CPU1")
	)
	(segment
		(start 18.831052 -88.630252)
		(end 18.5928 -88.392)
		(width 0.10795)
		(layer "F.Cu")
		(net "SVID_VCLK_PVCCIN_CPU1")
	)
	(segment
		(start 18.0594 -88.392)
		(end 17.526 -87.8586)
		(width 0.10795)
		(layer "F.Cu")
		(net "SVID_VCLK_PVCCIN_CPU1")
	)
	(segment
		(start 18.831052 -89.5604)
		(end 18.831052 -88.630252)
		(width 0.10795)
		(layer "F.Cu")
		(net "SVID_VCLK_PVCCIN_CPU1")
	)
	(segment
		(start 17.526 -87.8586)
		(end 17.526 -87.7062)
		(width 0.10795)
		(layer "F.Cu")
		(net "SVID_VCLK_PVCCIN_CPU1")
	)
	(via
		(at 18.321274 -88.392)
		(size 0.508)
		(drill 0.254)
		(layers "F.Cu" "B.Cu")
		(net "SVID_VCLK_PVCCIN_CPU1")
	)
	(segment
		(start 183.677052 -66.075052)
		(end 183.367934 -65.765934)
		(width 0.10795)
		(layer "F.Cu")
		(net "SVID_VCLK_PVCCIN_CPU0")
	)
	(segment
		(start 183.367934 -65.765934)
		(end 183.007 -65.405)
		(width 0.10795)
		(layer "F.Cu")
		(net "SVID_VCLK_PVCCIN_CPU0")
	)
	(segment
		(start 183.677052 -66.9544)
		(end 183.677052 -66.075052)
		(width 0.10795)
		(layer "F.Cu")
		(net "SVID_VCLK_PVCCIN_CPU0")
	)
	(segment
		(start 183.007 -65.405)
		(end 183.007 -65.024)
		(width 0.10795)
		(layer "F.Cu")
		(net "SVID_VCLK_PVCCIN_CPU0")
	)
	(via
		(at 183.367934 -65.765934)
		(size 0.508)
		(drill 0.254)
		(layers "F.Cu" "B.Cu")
		(net "SVID_VCLK_PVCCIN_CPU0")
	)
	(segment
		(start 19.630898 -88.566498)
		(end 19.630898 -89.5604)
		(width 0.10795)
		(layer "F.Cu")
		(net "SVID_VALERT_VCCIN_CPU1")
	)
	(segment
		(start 19.082004 -87.916258)
		(end 19.082004 -88.017604)
		(width 0.10795)
		(layer "F.Cu")
		(net "SVID_VALERT_VCCIN_CPU1")
	)
	(segment
		(start 19.05 -87.63)
		(end 19.05 -87.884254)
		(width 0.10795)
		(layer "F.Cu")
		(net "SVID_VALERT_VCCIN_CPU1")
	)
	(segment
		(start 19.05 -87.884254)
		(end 19.082004 -87.916258)
		(width 0.10795)
		(layer "F.Cu")
		(net "SVID_VALERT_VCCIN_CPU1")
	)
	(segment
		(start 19.431 -88.3666)
		(end 19.630898 -88.566498)
		(width 0.10795)
		(layer "F.Cu")
		(net "SVID_VALERT_VCCIN_CPU1")
	)
	(segment
		(start 19.082004 -88.017604)
		(end 19.431 -88.3666)
		(width 0.10795)
		(layer "F.Cu")
		(net "SVID_VALERT_VCCIN_CPU1")
	)
	(via
		(at 19.431 -88.3666)
		(size 0.508)
		(drill 0.254)
		(layers "F.Cu" "B.Cu")
		(net "SVID_VALERT_VCCIN_CPU1")
	)
	(segment
		(start 184.531 -65.474088)
		(end 184.531 -65.024)
		(width 0.10795)
		(layer "F.Cu")
		(net "SVID_VALERT_VCCIN_CPU0")
	)
	(segment
		(start 184.476898 -66.9544)
		(end 184.476898 -65.780666)
		(width 0.10795)
		(layer "F.Cu")
		(net "SVID_VALERT_VCCIN_CPU0")
	)
	(segment
		(start 184.476898 -65.780666)
		(end 184.476898 -65.52819)
		(width 0.10795)
		(layer "F.Cu")
		(net "SVID_VALERT_VCCIN_CPU0")
	)
	(segment
		(start 184.476898 -65.52819)
		(end 184.531 -65.474088)
		(width 0.10795)
		(layer "F.Cu")
		(net "SVID_VALERT_VCCIN_CPU0")
	)
	(via
		(at 184.476898 -65.780666)
		(size 0.508)
		(drill 0.254)
		(layers "F.Cu" "B.Cu")
		(net "SVID_VALERT_VCCIN_CPU0")
	)
	(segment
		(start -3.6576 -127.7112)
		(end -3.4036 -127.7112)
		(width 0.10795)
		(layer "F.Cu")
		(net "SVID_DIO1_CPU1_R")
	)
	(segment
		(start 38.441122 -106.415586)
		(end 38.157912 -106.415586)
		(width 0.10795)
		(layer "F.Cu")
		(net "SVID_DIO1_CPU1_R")
	)
	(segment
		(start -4.2418 -126.3396)
		(end -4.445 -126.3396)
		(width 0.10795)
		(layer "F.Cu")
		(net "SVID_DIO1_CPU1_R")
	)
	(segment
		(start 189.46622 -109.25302)
		(end 189.41415 -109.20095)
		(width 0.10795)
		(layer "F.Cu")
		(net "SVID_DIO1_CPU1_R")
	)
	(segment
		(start -4.8006 -127.115316)
		(end -4.46659 -127.449326)
		(width 0.10795)
		(layer "F.Cu")
		(net "SVID_DIO1_CPU1_R")
	)
	(segment
		(start 189.41415 -109.20095)
		(end 188.745114 -109.20095)
		(width 0.10795)
		(layer "F.Cu")
		(net "SVID_DIO1_CPU1_R")
	)
	(segment
		(start 10.362184 -5.068316)
		(end 10.29462 -5.13588)
		(width 0.10795)
		(layer "F.Cu")
		(net "SVID_DIO1_CPU1_R")
	)
	(segment
		(start 10.362184 -4.421124)
		(end 10.362184 -5.068316)
		(width 0.10795)
		(layer "F.Cu")
		(net "SVID_DIO1_CPU1_R")
	)
	(segment
		(start -3.919474 -127.449326)
		(end -3.6576 -127.7112)
		(width 0.10795)
		(layer "F.Cu")
		(net "SVID_DIO1_CPU1_R")
	)
	(segment
		(start -4.445 -126.3396)
		(end -4.8006 -126.6952)
		(width 0.10795)
		(layer "F.Cu")
		(net "SVID_DIO1_CPU1_R")
	)
	(segment
		(start 189.51702 -109.25302)
		(end 189.46622 -109.25302)
		(width 0.10795)
		(layer "F.Cu")
		(net "SVID_DIO1_CPU1_R")
	)
	(segment
		(start -4.8006 -126.6952)
		(end -4.8006 -127.115316)
		(width 0.10795)
		(layer "F.Cu")
		(net "SVID_DIO1_CPU1_R")
	)
	(segment
		(start -4.46659 -127.449326)
		(end -3.919474 -127.449326)
		(width 0.10795)
		(layer "F.Cu")
		(net "SVID_DIO1_CPU1_R")
	)
	(segment
		(start 38.157912 -106.415586)
		(end 37.761164 -106.018838)
		(width 0.10795)
		(layer "F.Cu")
		(net "SVID_DIO1_CPU1_R")
	)
	(via
		(at -4.2418 -126.3396)
		(size 0.508)
		(drill 0.254)
		(layers "F.Cu" "B.Cu")
		(net "SVID_DIO1_CPU1_R")
	)
	(via
		(at 172.1612 -123.3424)
		(size 0.508)
		(drill 0.254)
		(layers "F.Cu" "B.Cu")
		(net "SVID_DIO1_CPU1_R")
	)
	(via
		(at 37.761164 -106.018838)
		(size 0.508)
		(drill 0.254)
		(layers "F.Cu" "B.Cu")
		(net "SVID_DIO1_CPU1_R")
	)
	(via
		(at 189.51702 -109.25302)
		(size 0.508)
		(drill 0.254)
		(layers "F.Cu" "B.Cu")
		(net "SVID_DIO1_CPU1_R")
	)
	(via
		(at 10.29462 -5.13588)
		(size 0.508)
		(drill 0.254)
		(layers "F.Cu" "B.Cu")
		(net "SVID_DIO1_CPU1_R")
	)
	(segment
		(start -3.4036 -127.152654)
		(end -3.4036 -127.7112)
		(width 0.10795)
		(layer "B.Cu")
		(net "SVID_DIO1_CPU1_R")
	)
	(segment
		(start 10.29462 -5.13588)
		(end 10.29462 -4.869688)
		(width 0.10795)
		(layer "B.Cu")
		(net "SVID_DIO1_CPU1_R")
	)
	(segment
		(start 37.986462 -106.922316)
		(end 37.761164 -106.697018)
		(width 0.10795)
		(layer "B.Cu")
		(net "SVID_DIO1_CPU1_R")
	)
	(segment
		(start 38.445694 -106.922316)
		(end 37.986462 -106.922316)
		(width 0.10795)
		(layer "B.Cu")
		(net "SVID_DIO1_CPU1_R")
	)
	(segment
		(start -4.2418 -126.3396)
		(end -4.216654 -126.3396)
		(width 0.10795)
		(layer "B.Cu")
		(net "SVID_DIO1_CPU1_R")
	)
	(segment
		(start 10.551668 -4.61264)
		(end 10.551668 -4.210812)
		(width 0.10795)
		(layer "B.Cu")
		(net "SVID_DIO1_CPU1_R")
	)
	(segment
		(start -4.216654 -126.3396)
		(end -3.4036 -127.152654)
		(width 0.10795)
		(layer "B.Cu")
		(net "SVID_DIO1_CPU1_R")
	)
	(segment
		(start 10.29462 -4.869688)
		(end 10.551668 -4.61264)
		(width 0.10795)
		(layer "B.Cu")
		(net "SVID_DIO1_CPU1_R")
	)
	(segment
		(start 37.761164 -106.697018)
		(end 37.761164 -106.018838)
		(width 0.10795)
		(layer "B.Cu")
		(net "SVID_DIO1_CPU1_R")
	)
	(segment
		(start -0.572008 -41.524174)
		(end -4.780534 -45.7327)
		(width 0.089408)
		(layer "In2.Cu")
		(net "SVID_DIO1_CPU1_R")
	)
	(segment
		(start -4.44881 -86.547198)
		(end -2.258314 -88.737694)
		(width 0.089408)
		(layer "In2.Cu")
		(net "SVID_DIO1_CPU1_R")
	)
	(segment
		(start -4.44881 -86.189058)
		(end -4.449064 -86.189312)
		(width 0.089408)
		(layer "In2.Cu")
		(net "SVID_DIO1_CPU1_R")
	)
	(segment
		(start -4.612386 -126.045214)
		(end -4.318 -126.3396)
		(width 0.089408)
		(layer "In2.Cu")
		(net "SVID_DIO1_CPU1_R")
	)
	(segment
		(start -4.44881 -78.499208)
		(end -4.44881 -86.189058)
		(width 0.089408)
		(layer "In2.Cu")
		(net "SVID_DIO1_CPU1_R")
	)
	(segment
		(start -4.449064 -86.189312)
		(end -4.449064 -86.515956)
		(width 0.089408)
		(layer "In2.Cu")
		(net "SVID_DIO1_CPU1_R")
	)
	(segment
		(start 7.9502 -105.558844)
		(end 7.9502 -112.444784)
		(width 0.089408)
		(layer "In2.Cu")
		(net "SVID_DIO1_CPU1_R")
	)
	(segment
		(start 21.24202 -5.663946)
		(end 21.83257 -6.254496)
		(width 0.089408)
		(layer "In2.Cu")
		(net "SVID_DIO1_CPU1_R")
	)
	(segment
		(start -2.258314 -88.737694)
		(end 7.997952 -88.737694)
		(width 0.089408)
		(layer "In2.Cu")
		(net "SVID_DIO1_CPU1_R")
	)
	(segment
		(start 10.822686 -5.663946)
		(end 21.24202 -5.663946)
		(width 0.089408)
		(layer "In2.Cu")
		(net "SVID_DIO1_CPU1_R")
	)
	(segment
		(start 7.997952 -88.737694)
		(end 9.922002 -90.661744)
		(width 0.089408)
		(layer "In2.Cu")
		(net "SVID_DIO1_CPU1_R")
	)
	(segment
		(start 21.83257 -21.017738)
		(end 21.0566 -21.793708)
		(width 0.089408)
		(layer "In2.Cu")
		(net "SVID_DIO1_CPU1_R")
	)
	(segment
		(start -2.65811 -76.708508)
		(end -4.44881 -78.499208)
		(width 0.089408)
		(layer "In2.Cu")
		(net "SVID_DIO1_CPU1_R")
	)
	(segment
		(start 9.922002 -90.661744)
		(end 9.922002 -103.587042)
		(width 0.089408)
		(layer "In2.Cu")
		(net "SVID_DIO1_CPU1_R")
	)
	(segment
		(start 21.0566 -21.793708)
		(end 15.21587 -21.793708)
		(width 0.089408)
		(layer "In2.Cu")
		(net "SVID_DIO1_CPU1_R")
	)
	(segment
		(start 189.51702 -109.25302)
		(end 189.474094 -109.295946)
		(width 0.089408)
		(layer "In2.Cu")
		(net "SVID_DIO1_CPU1_R")
	)
	(segment
		(start 185.471054 -113.207546)
		(end 181.180232 -113.207546)
		(width 0.089408)
		(layer "In2.Cu")
		(net "SVID_DIO1_CPU1_R")
	)
	(segment
		(start 7.9502 -112.444784)
		(end 6.518148 -113.876836)
		(width 0.089408)
		(layer "In2.Cu")
		(net "SVID_DIO1_CPU1_R")
	)
	(segment
		(start -4.318 -126.3396)
		(end -4.2418 -126.3396)
		(width 0.089408)
		(layer "In2.Cu")
		(net "SVID_DIO1_CPU1_R")
	)
	(segment
		(start 172.1612 -122.226578)
		(end 172.1612 -123.3424)
		(width 0.089408)
		(layer "In2.Cu")
		(net "SVID_DIO1_CPU1_R")
	)
	(segment
		(start -4.780534 -45.7327)
		(end -4.780534 -60.343542)
		(width 0.089408)
		(layer "In2.Cu")
		(net "SVID_DIO1_CPU1_R")
	)
	(segment
		(start 189.382654 -109.295946)
		(end 185.471054 -113.207546)
		(width 0.089408)
		(layer "In2.Cu")
		(net "SVID_DIO1_CPU1_R")
	)
	(segment
		(start -4.780534 -60.343542)
		(end -2.65811 -62.465966)
		(width 0.089408)
		(layer "In2.Cu")
		(net "SVID_DIO1_CPU1_R")
	)
	(segment
		(start 4.77266 -113.876836)
		(end -4.612386 -123.261882)
		(width 0.089408)
		(layer "In2.Cu")
		(net "SVID_DIO1_CPU1_R")
	)
	(segment
		(start 181.180232 -113.207546)
		(end 172.1612 -122.226578)
		(width 0.089408)
		(layer "In2.Cu")
		(net "SVID_DIO1_CPU1_R")
	)
	(segment
		(start 12.34948 -41.524174)
		(end -0.572008 -41.524174)
		(width 0.089408)
		(layer "In2.Cu")
		(net "SVID_DIO1_CPU1_R")
	)
	(segment
		(start -4.44881 -86.51621)
		(end -4.44881 -86.547198)
		(width 0.089408)
		(layer "In2.Cu")
		(net "SVID_DIO1_CPU1_R")
	)
	(segment
		(start 189.474094 -109.295946)
		(end 189.382654 -109.295946)
		(width 0.089408)
		(layer "In2.Cu")
		(net "SVID_DIO1_CPU1_R")
	)
	(segment
		(start 10.29462 -5.13588)
		(end 10.822686 -5.663946)
		(width 0.089408)
		(layer "In2.Cu")
		(net "SVID_DIO1_CPU1_R")
	)
	(segment
		(start 15.21587 -21.793708)
		(end 14.249908 -22.75967)
		(width 0.089408)
		(layer "In2.Cu")
		(net "SVID_DIO1_CPU1_R")
	)
	(segment
		(start 9.922002 -103.587042)
		(end 7.9502 -105.558844)
		(width 0.089408)
		(layer "In2.Cu")
		(net "SVID_DIO1_CPU1_R")
	)
	(segment
		(start -4.612386 -123.261882)
		(end -4.612386 -126.045214)
		(width 0.089408)
		(layer "In2.Cu")
		(net "SVID_DIO1_CPU1_R")
	)
	(segment
		(start 21.83257 -6.254496)
		(end 21.83257 -21.017738)
		(width 0.089408)
		(layer "In2.Cu")
		(net "SVID_DIO1_CPU1_R")
	)
	(segment
		(start -4.449064 -86.515956)
		(end -4.44881 -86.51621)
		(width 0.089408)
		(layer "In2.Cu")
		(net "SVID_DIO1_CPU1_R")
	)
	(segment
		(start -2.65811 -62.465966)
		(end -2.65811 -76.708508)
		(width 0.089408)
		(layer "In2.Cu")
		(net "SVID_DIO1_CPU1_R")
	)
	(segment
		(start 14.249908 -39.623746)
		(end 12.34948 -41.524174)
		(width 0.089408)
		(layer "In2.Cu")
		(net "SVID_DIO1_CPU1_R")
	)
	(segment
		(start 14.249908 -22.75967)
		(end 14.249908 -39.623746)
		(width 0.089408)
		(layer "In2.Cu")
		(net "SVID_DIO1_CPU1_R")
	)
	(segment
		(start 6.518148 -113.876836)
		(end 4.77266 -113.876836)
		(width 0.089408)
		(layer "In2.Cu")
		(net "SVID_DIO1_CPU1_R")
	)
	(segment
		(start 17.78508 -119.712486)
		(end 17.956276 -119.54129)
		(width 0.089408)
		(layer "In4.Cu")
		(net "SVID_DIO1_CPU1_R")
	)
	(segment
		(start 34.844482 -110.40872)
		(end 37.187124 -108.066078)
		(width 0.089408)
		(layer "In4.Cu")
		(net "SVID_DIO1_CPU1_R")
	)
	(segment
		(start -4.2418 -126.3396)
		(end -4.624324 -125.957076)
		(width 0.089408)
		(layer "In4.Cu")
		(net "SVID_DIO1_CPU1_R")
	)
	(segment
		(start 37.187124 -106.458258)
		(end 37.626544 -106.018838)
		(width 0.089408)
		(layer "In4.Cu")
		(net "SVID_DIO1_CPU1_R")
	)
	(segment
		(start 15.456662 -120.752108)
		(end 16.243046 -119.965724)
		(width 0.089408)
		(layer "In4.Cu")
		(net "SVID_DIO1_CPU1_R")
	)
	(segment
		(start 37.626544 -106.018838)
		(end 37.761164 -106.018838)
		(width 0.089408)
		(layer "In4.Cu")
		(net "SVID_DIO1_CPU1_R")
	)
	(segment
		(start 6.228334 -120.752108)
		(end 15.456662 -120.752108)
		(width 0.089408)
		(layer "In4.Cu")
		(net "SVID_DIO1_CPU1_R")
	)
	(segment
		(start 34.090102 -110.40872)
		(end 34.844482 -110.40872)
		(width 0.089408)
		(layer "In4.Cu")
		(net "SVID_DIO1_CPU1_R")
	)
	(segment
		(start 16.243046 -119.965724)
		(end 17.532096 -119.965724)
		(width 0.089408)
		(layer "In4.Cu")
		(net "SVID_DIO1_CPU1_R")
	)
	(segment
		(start 4.68376 -122.03684)
		(end 5.968746 -120.751854)
		(width 0.089408)
		(layer "In4.Cu")
		(net "SVID_DIO1_CPU1_R")
	)
	(segment
		(start -4.624324 -125.957076)
		(end -4.624324 -123.287282)
		(width 0.089408)
		(layer "In4.Cu")
		(net "SVID_DIO1_CPU1_R")
	)
	(segment
		(start 17.532096 -119.965724)
		(end 17.78508 -119.71274)
		(width 0.089408)
		(layer "In4.Cu")
		(net "SVID_DIO1_CPU1_R")
	)
	(segment
		(start 5.968746 -120.751854)
		(end 6.22808 -120.751854)
		(width 0.089408)
		(layer "In4.Cu")
		(net "SVID_DIO1_CPU1_R")
	)
	(segment
		(start -1.896872 -120.55983)
		(end 1.58115 -120.55983)
		(width 0.089408)
		(layer "In4.Cu")
		(net "SVID_DIO1_CPU1_R")
	)
	(segment
		(start -4.624324 -123.287282)
		(end -1.896872 -120.55983)
		(width 0.089408)
		(layer "In4.Cu")
		(net "SVID_DIO1_CPU1_R")
	)
	(segment
		(start 24.957532 -119.54129)
		(end 34.090102 -110.40872)
		(width 0.089408)
		(layer "In4.Cu")
		(net "SVID_DIO1_CPU1_R")
	)
	(segment
		(start 6.22808 -120.751854)
		(end 6.228334 -120.752108)
		(width 0.089408)
		(layer "In4.Cu")
		(net "SVID_DIO1_CPU1_R")
	)
	(segment
		(start 3.05816 -122.03684)
		(end 4.68376 -122.03684)
		(width 0.089408)
		(layer "In4.Cu")
		(net "SVID_DIO1_CPU1_R")
	)
	(segment
		(start 17.78508 -119.71274)
		(end 17.78508 -119.712486)
		(width 0.089408)
		(layer "In4.Cu")
		(net "SVID_DIO1_CPU1_R")
	)
	(segment
		(start 37.187124 -108.066078)
		(end 37.187124 -106.458258)
		(width 0.089408)
		(layer "In4.Cu")
		(net "SVID_DIO1_CPU1_R")
	)
	(segment
		(start 1.58115 -120.55983)
		(end 3.05816 -122.03684)
		(width 0.089408)
		(layer "In4.Cu")
		(net "SVID_DIO1_CPU1_R")
	)
	(segment
		(start 17.956276 -119.54129)
		(end 24.957532 -119.54129)
		(width 0.089408)
		(layer "In4.Cu")
		(net "SVID_DIO1_CPU1_R")
	)
	(segment
		(start 159.612838 -125.947932)
		(end 159.613346 -125.947932)
		(width 0.089408)
		(layer "In9.Cu")
		(net "SVID_DIO1_CPU1_R")
	)
	(segment
		(start 164.23132 -120.258078)
		(end 164.588952 -120.258078)
		(width 0.089408)
		(layer "In9.Cu")
		(net "SVID_DIO1_CPU1_R")
	)
	(segment
		(start 156.308044 -125.441964)
		(end 156.814012 -125.947932)
		(width 0.089408)
		(layer "In9.Cu")
		(net "SVID_DIO1_CPU1_R")
	)
	(segment
		(start 52.667154 -120.3071)
		(end 147.6883 -120.3071)
		(width 0.089408)
		(layer "In9.Cu")
		(net "SVID_DIO1_CPU1_R")
	)
	(segment
		(start 161.840164 -122.649234)
		(end 164.23132 -120.258078)
		(width 0.089408)
		(layer "In9.Cu")
		(net "SVID_DIO1_CPU1_R")
	)
	(segment
		(start 38.311582 -105.951528)
		(end 52.667154 -120.3071)
		(width 0.089408)
		(layer "In9.Cu")
		(net "SVID_DIO1_CPU1_R")
	)
	(segment
		(start 164.589206 -120.258332)
		(end 169.23766 -120.258332)
		(width 0.089408)
		(layer "In9.Cu")
		(net "SVID_DIO1_CPU1_R")
	)
	(segment
		(start 37.82822 -106.018838)
		(end 37.89553 -105.951528)
		(width 0.089408)
		(layer "In9.Cu")
		(net "SVID_DIO1_CPU1_R")
	)
	(segment
		(start 159.613346 -125.947932)
		(end 161.840164 -123.721114)
		(width 0.089408)
		(layer "In9.Cu")
		(net "SVID_DIO1_CPU1_R")
	)
	(segment
		(start 169.23766 -120.258332)
		(end 172.1612 -123.181872)
		(width 0.089408)
		(layer "In9.Cu")
		(net "SVID_DIO1_CPU1_R")
	)
	(segment
		(start 156.83865 -125.947932)
		(end 156.843984 -125.953266)
		(width 0.089408)
		(layer "In9.Cu")
		(net "SVID_DIO1_CPU1_R")
	)
	(segment
		(start 152.823164 -125.441964)
		(end 156.308044 -125.441964)
		(width 0.089408)
		(layer "In9.Cu")
		(net "SVID_DIO1_CPU1_R")
	)
	(segment
		(start 164.588952 -120.258078)
		(end 164.589206 -120.258332)
		(width 0.089408)
		(layer "In9.Cu")
		(net "SVID_DIO1_CPU1_R")
	)
	(segment
		(start 156.814012 -125.947932)
		(end 156.83865 -125.947932)
		(width 0.089408)
		(layer "In9.Cu")
		(net "SVID_DIO1_CPU1_R")
	)
	(segment
		(start 161.840164 -123.721114)
		(end 161.840164 -122.649234)
		(width 0.089408)
		(layer "In9.Cu")
		(net "SVID_DIO1_CPU1_R")
	)
	(segment
		(start 37.89553 -105.951528)
		(end 38.311582 -105.951528)
		(width 0.089408)
		(layer "In9.Cu")
		(net "SVID_DIO1_CPU1_R")
	)
	(segment
		(start 37.761164 -106.018838)
		(end 37.82822 -106.018838)
		(width 0.089408)
		(layer "In9.Cu")
		(net "SVID_DIO1_CPU1_R")
	)
	(segment
		(start 159.607504 -125.953266)
		(end 159.612838 -125.947932)
		(width 0.089408)
		(layer "In9.Cu")
		(net "SVID_DIO1_CPU1_R")
	)
	(segment
		(start 147.6883 -120.3071)
		(end 152.823164 -125.441964)
		(width 0.089408)
		(layer "In9.Cu")
		(net "SVID_DIO1_CPU1_R")
	)
	(segment
		(start 172.1612 -123.181872)
		(end 172.1612 -123.3424)
		(width 0.089408)
		(layer "In9.Cu")
		(net "SVID_DIO1_CPU1_R")
	)
	(segment
		(start 156.843984 -125.953266)
		(end 159.607504 -125.953266)
		(width 0.089408)
		(layer "In9.Cu")
		(net "SVID_DIO1_CPU1_R")
	)
	(segment
		(start 103.806244 -93.23324)
		(end 104.161844 -92.87764)
		(width 0.10795)
		(layer "F.Cu")
		(net "SVID_DIO1_CPU1")
	)
	(segment
		(start 104.161844 -92.87764)
		(end 104.532938 -92.87764)
		(width 0.10795)
		(layer "F.Cu")
		(net "SVID_DIO1_CPU1")
	)
	(via
		(at 41.86682 -107.274106)
		(size 0.6604)
		(drill 0.3302)
		(layers "F.Cu" "B.Cu")
		(net "SVID_DIO1_CPU1")
	)
	(via
		(at 104.532938 -92.87764)
		(size 0.508)
		(drill 0.254)
		(layers "F.Cu" "B.Cu")
		(net "SVID_DIO1_CPU1")
	)
	(segment
		(start 83.733386 -92.25788)
		(end 84.156804 -91.834462)
		(width 0.10795)
		(layer "B.Cu")
		(net "SVID_DIO1_CPU1")
	)
	(segment
		(start 102.942898 -91.2876)
		(end 104.532938 -92.87764)
		(width 0.10795)
		(layer "B.Cu")
		(net "SVID_DIO1_CPU1")
	)
	(segment
		(start 72.820784 -94.310708)
		(end 73.553828 -94.310708)
		(width 0.10795)
		(layer "B.Cu")
		(net "SVID_DIO1_CPU1")
	)
	(segment
		(start 82.263996 -91.834462)
		(end 82.825082 -91.834462)
		(width 0.10795)
		(layer "B.Cu")
		(net "SVID_DIO1_CPU1")
	)
	(segment
		(start 81.163414 -92.746068)
		(end 81.752948 -92.156534)
		(width 0.10795)
		(layer "B.Cu")
		(net "SVID_DIO1_CPU1")
	)
	(segment
		(start 99.993704 -90.843862)
		(end 100.410772 -91.26093)
		(width 0.10795)
		(layer "B.Cu")
		(net "SVID_DIO1_CPU1")
	)
	(segment
		(start 94.415356 -91.737434)
		(end 94.893384 -91.737434)
		(width 0.10795)
		(layer "B.Cu")
		(net "SVID_DIO1_CPU1")
	)
	(segment
		(start 69.87159 -95.2246)
		(end 70.410832 -94.685358)
		(width 0.10795)
		(layer "B.Cu")
		(net "SVID_DIO1_CPU1")
	)
	(segment
		(start 81.941924 -92.156534)
		(end 82.263996 -91.834462)
		(width 0.10795)
		(layer "B.Cu")
		(net "SVID_DIO1_CPU1")
	)
	(segment
		(start 88.451944 -92.155264)
		(end 88.847676 -92.155264)
		(width 0.10795)
		(layer "B.Cu")
		(net "SVID_DIO1_CPU1")
	)
	(segment
		(start 88.847676 -92.155264)
		(end 89.270078 -91.732862)
		(width 0.10795)
		(layer "B.Cu")
		(net "SVID_DIO1_CPU1")
	)
	(segment
		(start 96.552512 -91.694254)
		(end 97.013522 -92.155264)
		(width 0.10795)
		(layer "B.Cu")
		(net "SVID_DIO1_CPU1")
	)
	(segment
		(start 63.1444 -95.2246)
		(end 69.87159 -95.2246)
		(width 0.10795)
		(layer "B.Cu")
		(net "SVID_DIO1_CPU1")
	)
	(segment
		(start 51.26228 -107.10672)
		(end 63.1444 -95.2246)
		(width 0.10795)
		(layer "B.Cu")
		(net "SVID_DIO1_CPU1")
	)
	(segment
		(start 76.254864 -94.310708)
		(end 76.987908 -94.310708)
		(width 0.10795)
		(layer "B.Cu")
		(net "SVID_DIO1_CPU1")
	)
	(segment
		(start 74.537824 -94.310708)
		(end 75.270868 -94.310708)
		(width 0.10795)
		(layer "B.Cu")
		(net "SVID_DIO1_CPU1")
	)
	(segment
		(start 97.013522 -92.155264)
		(end 97.400872 -92.155264)
		(width 0.10795)
		(layer "B.Cu")
		(net "SVID_DIO1_CPU1")
	)
	(segment
		(start 89.760806 -91.732862)
		(end 90.183208 -92.155264)
		(width 0.10795)
		(layer "B.Cu")
		(net "SVID_DIO1_CPU1")
	)
	(segment
		(start 86.694264 -92.155264)
		(end 87.114126 -92.155264)
		(width 0.10795)
		(layer "B.Cu")
		(net "SVID_DIO1_CPU1")
	)
	(segment
		(start 85.788246 -91.744292)
		(end 86.283292 -91.744292)
		(width 0.10795)
		(layer "B.Cu")
		(net "SVID_DIO1_CPU1")
	)
	(segment
		(start 40.095932 -107.314746)
		(end 41.82618 -107.314746)
		(width 0.10795)
		(layer "B.Cu")
		(net "SVID_DIO1_CPU1")
	)
	(segment
		(start 100.410772 -91.26093)
		(end 100.893372 -91.26093)
		(width 0.10795)
		(layer "B.Cu")
		(net "SVID_DIO1_CPU1")
	)
	(segment
		(start 90.959686 -91.723718)
		(end 91.44508 -91.723718)
		(width 0.10795)
		(layer "B.Cu")
		(net "SVID_DIO1_CPU1")
	)
	(segment
		(start 83.2485 -92.25788)
		(end 83.733386 -92.25788)
		(width 0.10795)
		(layer "B.Cu")
		(net "SVID_DIO1_CPU1")
	)
	(segment
		(start 77.650848 -94.631764)
		(end 77.973174 -94.309438)
		(width 0.10795)
		(layer "B.Cu")
		(net "SVID_DIO1_CPU1")
	)
	(segment
		(start 84.839556 -92.155264)
		(end 85.377274 -92.155264)
		(width 0.10795)
		(layer "B.Cu")
		(net "SVID_DIO1_CPU1")
	)
	(segment
		(start 102.1842 -91.2876)
		(end 102.942898 -91.2876)
		(width 0.10795)
		(layer "B.Cu")
		(net "SVID_DIO1_CPU1")
	)
	(segment
		(start 39.703502 -106.922316)
		(end 40.095932 -107.314746)
		(width 0.10795)
		(layer "B.Cu")
		(net "SVID_DIO1_CPU1")
	)
	(segment
		(start 93.95079 -92.202)
		(end 94.415356 -91.737434)
		(width 0.10795)
		(layer "B.Cu")
		(net "SVID_DIO1_CPU1")
	)
	(segment
		(start 77.973174 -94.309438)
		(end 78.53172 -94.309438)
		(width 0.10795)
		(layer "B.Cu")
		(net "SVID_DIO1_CPU1")
	)
	(segment
		(start 95.722186 -92.155264)
		(end 96.183196 -91.694254)
		(width 0.10795)
		(layer "B.Cu")
		(net "SVID_DIO1_CPU1")
	)
	(segment
		(start 88.015826 -91.719146)
		(end 88.451944 -92.155264)
		(width 0.10795)
		(layer "B.Cu")
		(net "SVID_DIO1_CPU1")
	)
	(segment
		(start 99.58705 -90.843862)
		(end 99.993704 -90.843862)
		(width 0.10795)
		(layer "B.Cu")
		(net "SVID_DIO1_CPU1")
	)
	(segment
		(start 81.752948 -92.156534)
		(end 81.941924 -92.156534)
		(width 0.10795)
		(layer "B.Cu")
		(net "SVID_DIO1_CPU1")
	)
	(segment
		(start 86.283292 -91.744292)
		(end 86.694264 -92.155264)
		(width 0.10795)
		(layer "B.Cu")
		(net "SVID_DIO1_CPU1")
	)
	(segment
		(start 72.499728 -94.631764)
		(end 72.820784 -94.310708)
		(width 0.10795)
		(layer "B.Cu")
		(net "SVID_DIO1_CPU1")
	)
	(segment
		(start 101.740462 -90.843862)
		(end 102.1842 -91.2876)
		(width 0.10795)
		(layer "B.Cu")
		(net "SVID_DIO1_CPU1")
	)
	(segment
		(start 97.400872 -92.155264)
		(end 97.868486 -91.68765)
		(width 0.10795)
		(layer "B.Cu")
		(net "SVID_DIO1_CPU1")
	)
	(segment
		(start 98.380296 -91.68765)
		(end 98.754946 -91.313)
		(width 0.10795)
		(layer "B.Cu")
		(net "SVID_DIO1_CPU1")
	)
	(segment
		(start 93.133418 -92.740988)
		(end 93.672406 -92.202)
		(width 0.10795)
		(layer "B.Cu")
		(net "SVID_DIO1_CPU1")
	)
	(segment
		(start 79.02702 -93.814138)
		(end 79.243174 -93.814138)
		(width 0.10795)
		(layer "B.Cu")
		(net "SVID_DIO1_CPU1")
	)
	(segment
		(start 89.270078 -91.732862)
		(end 89.760806 -91.732862)
		(width 0.10795)
		(layer "B.Cu")
		(net "SVID_DIO1_CPU1")
	)
	(segment
		(start 73.553828 -94.310708)
		(end 73.874884 -94.631764)
		(width 0.10795)
		(layer "B.Cu")
		(net "SVID_DIO1_CPU1")
	)
	(segment
		(start 74.216768 -94.631764)
		(end 74.537824 -94.310708)
		(width 0.10795)
		(layer "B.Cu")
		(net "SVID_DIO1_CPU1")
	)
	(segment
		(start 98.754946 -91.313)
		(end 99.117912 -91.313)
		(width 0.10795)
		(layer "B.Cu")
		(net "SVID_DIO1_CPU1")
	)
	(segment
		(start 101.31044 -90.843862)
		(end 101.740462 -90.843862)
		(width 0.10795)
		(layer "B.Cu")
		(net "SVID_DIO1_CPU1")
	)
	(segment
		(start 95.311214 -92.155264)
		(end 95.722186 -92.155264)
		(width 0.10795)
		(layer "B.Cu")
		(net "SVID_DIO1_CPU1")
	)
	(segment
		(start 92.140532 -92.155264)
		(end 92.726256 -92.740988)
		(width 0.10795)
		(layer "B.Cu")
		(net "SVID_DIO1_CPU1")
	)
	(segment
		(start 82.825082 -91.834462)
		(end 83.2485 -92.25788)
		(width 0.10795)
		(layer "B.Cu")
		(net "SVID_DIO1_CPU1")
	)
	(segment
		(start 96.183196 -91.694254)
		(end 96.552512 -91.694254)
		(width 0.10795)
		(layer "B.Cu")
		(net "SVID_DIO1_CPU1")
	)
	(segment
		(start 90.183208 -92.155264)
		(end 90.52814 -92.155264)
		(width 0.10795)
		(layer "B.Cu")
		(net "SVID_DIO1_CPU1")
	)
	(segment
		(start 76.987908 -94.310708)
		(end 77.308964 -94.631764)
		(width 0.10795)
		(layer "B.Cu")
		(net "SVID_DIO1_CPU1")
	)
	(segment
		(start 42.034206 -107.10672)
		(end 51.26228 -107.10672)
		(width 0.10795)
		(layer "B.Cu")
		(net "SVID_DIO1_CPU1")
	)
	(segment
		(start 78.53172 -94.309438)
		(end 79.02702 -93.814138)
		(width 0.10795)
		(layer "B.Cu")
		(net "SVID_DIO1_CPU1")
	)
	(segment
		(start 77.308964 -94.631764)
		(end 77.650848 -94.631764)
		(width 0.10795)
		(layer "B.Cu")
		(net "SVID_DIO1_CPU1")
	)
	(segment
		(start 41.86682 -107.274106)
		(end 42.034206 -107.10672)
		(width 0.10795)
		(layer "B.Cu")
		(net "SVID_DIO1_CPU1")
	)
	(segment
		(start 75.591924 -94.631764)
		(end 75.933808 -94.631764)
		(width 0.10795)
		(layer "B.Cu")
		(net "SVID_DIO1_CPU1")
	)
	(segment
		(start 91.876626 -92.155264)
		(end 92.140532 -92.155264)
		(width 0.10795)
		(layer "B.Cu")
		(net "SVID_DIO1_CPU1")
	)
	(segment
		(start 71.836788 -94.310708)
		(end 72.157844 -94.631764)
		(width 0.10795)
		(layer "B.Cu")
		(net "SVID_DIO1_CPU1")
	)
	(segment
		(start 87.550244 -91.719146)
		(end 88.015826 -91.719146)
		(width 0.10795)
		(layer "B.Cu")
		(net "SVID_DIO1_CPU1")
	)
	(segment
		(start 93.672406 -92.202)
		(end 93.95079 -92.202)
		(width 0.10795)
		(layer "B.Cu")
		(net "SVID_DIO1_CPU1")
	)
	(segment
		(start 100.893372 -91.26093)
		(end 101.31044 -90.843862)
		(width 0.10795)
		(layer "B.Cu")
		(net "SVID_DIO1_CPU1")
	)
	(segment
		(start 72.157844 -94.631764)
		(end 72.499728 -94.631764)
		(width 0.10795)
		(layer "B.Cu")
		(net "SVID_DIO1_CPU1")
	)
	(segment
		(start 90.52814 -92.155264)
		(end 90.959686 -91.723718)
		(width 0.10795)
		(layer "B.Cu")
		(net "SVID_DIO1_CPU1")
	)
	(segment
		(start 71.103744 -94.310708)
		(end 71.836788 -94.310708)
		(width 0.10795)
		(layer "B.Cu")
		(net "SVID_DIO1_CPU1")
	)
	(segment
		(start 73.874884 -94.631764)
		(end 74.216768 -94.631764)
		(width 0.10795)
		(layer "B.Cu")
		(net "SVID_DIO1_CPU1")
	)
	(segment
		(start 79.243174 -93.814138)
		(end 79.910178 -93.147134)
		(width 0.10795)
		(layer "B.Cu")
		(net "SVID_DIO1_CPU1")
	)
	(segment
		(start 80.62595 -92.746068)
		(end 81.163414 -92.746068)
		(width 0.10795)
		(layer "B.Cu")
		(net "SVID_DIO1_CPU1")
	)
	(segment
		(start 85.377274 -92.155264)
		(end 85.788246 -91.744292)
		(width 0.10795)
		(layer "B.Cu")
		(net "SVID_DIO1_CPU1")
	)
	(segment
		(start 94.893384 -91.737434)
		(end 95.311214 -92.155264)
		(width 0.10795)
		(layer "B.Cu")
		(net "SVID_DIO1_CPU1")
	)
	(segment
		(start 84.518754 -91.834462)
		(end 84.839556 -92.155264)
		(width 0.10795)
		(layer "B.Cu")
		(net "SVID_DIO1_CPU1")
	)
	(segment
		(start 75.933808 -94.631764)
		(end 76.254864 -94.310708)
		(width 0.10795)
		(layer "B.Cu")
		(net "SVID_DIO1_CPU1")
	)
	(segment
		(start 39.334694 -106.922316)
		(end 39.703502 -106.922316)
		(width 0.10795)
		(layer "B.Cu")
		(net "SVID_DIO1_CPU1")
	)
	(segment
		(start 79.910178 -93.147134)
		(end 80.224884 -93.147134)
		(width 0.10795)
		(layer "B.Cu")
		(net "SVID_DIO1_CPU1")
	)
	(segment
		(start 70.729094 -94.685358)
		(end 71.103744 -94.310708)
		(width 0.10795)
		(layer "B.Cu")
		(net "SVID_DIO1_CPU1")
	)
	(segment
		(start 99.117912 -91.313)
		(end 99.58705 -90.843862)
		(width 0.10795)
		(layer "B.Cu")
		(net "SVID_DIO1_CPU1")
	)
	(segment
		(start 41.82618 -107.314746)
		(end 41.86682 -107.274106)
		(width 0.10795)
		(layer "B.Cu")
		(net "SVID_DIO1_CPU1")
	)
	(segment
		(start 91.44508 -91.723718)
		(end 91.876626 -92.155264)
		(width 0.10795)
		(layer "B.Cu")
		(net "SVID_DIO1_CPU1")
	)
	(segment
		(start 84.156804 -91.834462)
		(end 84.518754 -91.834462)
		(width 0.10795)
		(layer "B.Cu")
		(net "SVID_DIO1_CPU1")
	)
	(segment
		(start 92.726256 -92.740988)
		(end 93.133418 -92.740988)
		(width 0.10795)
		(layer "B.Cu")
		(net "SVID_DIO1_CPU1")
	)
	(segment
		(start 87.114126 -92.155264)
		(end 87.550244 -91.719146)
		(width 0.10795)
		(layer "B.Cu")
		(net "SVID_DIO1_CPU1")
	)
	(segment
		(start 97.868486 -91.68765)
		(end 98.380296 -91.68765)
		(width 0.10795)
		(layer "B.Cu")
		(net "SVID_DIO1_CPU1")
	)
	(segment
		(start 80.224884 -93.147134)
		(end 80.62595 -92.746068)
		(width 0.10795)
		(layer "B.Cu")
		(net "SVID_DIO1_CPU1")
	)
	(segment
		(start 75.270868 -94.310708)
		(end 75.591924 -94.631764)
		(width 0.10795)
		(layer "B.Cu")
		(net "SVID_DIO1_CPU1")
	)
	(segment
		(start 70.410832 -94.685358)
		(end 70.729094 -94.685358)
		(width 0.10795)
		(layer "B.Cu")
		(net "SVID_DIO1_CPU1")
	)
	(segment
		(start 358.590596 -88.549734)
		(end 358.590596 -90.252042)
		(width 0.10795)
		(layer "F.Cu")
		(net "SVID_DIO1_CPU0_R")
	)
	(segment
		(start 337.947 -16.383)
		(end 337.947 -16.51)
		(width 0.10795)
		(layer "F.Cu")
		(net "SVID_DIO1_CPU0_R")
	)
	(segment
		(start 365.391954 -137.930382)
		(end 365.454946 -137.86739)
		(width 0.10795)
		(layer "F.Cu")
		(net "SVID_DIO1_CPU0_R")
	)
	(segment
		(start 354.3554 -108.585)
		(end 353.724972 -109.20095)
		(width 0.10795)
		(layer "F.Cu")
		(net "SVID_DIO1_CPU0_R")
	)
	(segment
		(start 323.98716 -129.844546)
		(end 323.98716 -130.42646)
		(width 0.10795)
		(layer "F.Cu")
		(net "SVID_DIO1_CPU0_R")
	)
	(segment
		(start 364.953296 -138.41857)
		(end 365.391954 -137.979912)
		(width 0.10795)
		(layer "F.Cu")
		(net "SVID_DIO1_CPU0_R")
	)
	(segment
		(start 365.391954 -137.979912)
		(end 365.391954 -137.930382)
		(width 0.10795)
		(layer "F.Cu")
		(net "SVID_DIO1_CPU0_R")
	)
	(segment
		(start 347.456252 -75.473052)
		(end 357.0732 -75.473052)
		(width 0.10795)
		(layer "F.Cu")
		(net "SVID_DIO1_CPU0_R")
	)
	(segment
		(start 358.59085 -90.252296)
		(end 358.59085 -90.277696)
		(width 0.10795)
		(layer "F.Cu")
		(net "SVID_DIO1_CPU0_R")
	)
	(segment
		(start 358.59085 -90.277696)
		(end 359.194354 -90.8812)
		(width 0.10795)
		(layer "F.Cu")
		(net "SVID_DIO1_CPU0_R")
	)
	(segment
		(start 359.194354 -90.8812)
		(end 359.612946 -90.8812)
		(width 0.10795)
		(layer "F.Cu")
		(net "SVID_DIO1_CPU0_R")
	)
	(segment
		(start 323.516498 -129.373884)
		(end 323.742304 -129.59969)
		(width 0.10795)
		(layer "F.Cu")
		(net "SVID_DIO1_CPU0_R")
	)
	(segment
		(start 323.516498 -128.902714)
		(end 323.516498 -129.373884)
		(width 0.10795)
		(layer "F.Cu")
		(net "SVID_DIO1_CPU0_R")
	)
	(segment
		(start 354.685346 -108.1278)
		(end 354.3554 -108.457746)
		(width 0.10795)
		(layer "F.Cu")
		(net "SVID_DIO1_CPU0_R")
	)
	(segment
		(start 361.510834 -85.629496)
		(end 358.590596 -88.549734)
		(width 0.10795)
		(layer "F.Cu")
		(net "SVID_DIO1_CPU0_R")
	)
	(segment
		(start 361.510834 -76.486512)
		(end 361.510834 -85.629496)
		(width 0.10795)
		(layer "F.Cu")
		(net "SVID_DIO1_CPU0_R")
	)
	(segment
		(start 323.742304 -129.59969)
		(end 323.98716 -129.844546)
		(width 0.10795)
		(layer "F.Cu")
		(net "SVID_DIO1_CPU0_R")
	)
	(segment
		(start 354.3554 -108.457746)
		(end 354.3554 -108.585)
		(width 0.10795)
		(layer "F.Cu")
		(net "SVID_DIO1_CPU0_R")
	)
	(segment
		(start 337.947 -16.51)
		(end 337.185 -17.272)
		(width 0.10795)
		(layer "F.Cu")
		(net "SVID_DIO1_CPU0_R")
	)
	(segment
		(start 357.0732 -75.473052)
		(end 360.497374 -75.473052)
		(width 0.10795)
		(layer "F.Cu")
		(net "SVID_DIO1_CPU0_R")
	)
	(segment
		(start 358.590596 -90.252042)
		(end 358.59085 -90.252296)
		(width 0.10795)
		(layer "F.Cu")
		(net "SVID_DIO1_CPU0_R")
	)
	(segment
		(start 361.80395 -106.419904)
		(end 360.096054 -108.1278)
		(width 0.10795)
		(layer "F.Cu")
		(net "SVID_DIO1_CPU0_R")
	)
	(segment
		(start 344.3732 -72.39)
		(end 347.456252 -75.473052)
		(width 0.10795)
		(layer "F.Cu")
		(net "SVID_DIO1_CPU0_R")
	)
	(segment
		(start 361.80395 -93.072204)
		(end 361.80395 -106.419904)
		(width 0.10795)
		(layer "F.Cu")
		(net "SVID_DIO1_CPU0_R")
	)
	(segment
		(start 360.096054 -108.1278)
		(end 354.685346 -108.1278)
		(width 0.10795)
		(layer "F.Cu")
		(net "SVID_DIO1_CPU0_R")
	)
	(segment
		(start 364.75924 -138.41857)
		(end 364.953296 -138.41857)
		(width 0.10795)
		(layer "F.Cu")
		(net "SVID_DIO1_CPU0_R")
	)
	(segment
		(start 360.497374 -75.473052)
		(end 361.510834 -76.486512)
		(width 0.10795)
		(layer "F.Cu")
		(net "SVID_DIO1_CPU0_R")
	)
	(segment
		(start 359.612946 -90.8812)
		(end 361.80395 -93.072204)
		(width 0.10795)
		(layer "F.Cu")
		(net "SVID_DIO1_CPU0_R")
	)
	(via
		(at 357.0732 -75.473052)
		(size 0.762)
		(drill 0.381)
		(layers "F.Cu" "B.Cu")
		(net "SVID_DIO1_CPU0_R")
	)
	(via
		(at 354.3554 -108.585)
		(size 0.508)
		(drill 0.254)
		(layers "F.Cu" "B.Cu")
		(net "SVID_DIO1_CPU0_R")
	)
	(via
		(at 345.313 -53.1368)
		(size 0.508)
		(drill 0.254)
		(layers "F.Cu" "B.Cu")
		(net "SVID_DIO1_CPU0_R")
	)
	(via
		(at 365.454946 -137.86739)
		(size 0.508)
		(drill 0.254)
		(layers "F.Cu" "B.Cu")
		(net "SVID_DIO1_CPU0_R")
	)
	(via
		(at 344.3732 -72.39)
		(size 0.508)
		(drill 0.254)
		(layers "F.Cu" "B.Cu")
		(net "SVID_DIO1_CPU0_R")
	)
	(via
		(at 337.185 -17.272)
		(size 0.508)
		(drill 0.254)
		(layers "F.Cu" "B.Cu")
		(net "SVID_DIO1_CPU0_R")
	)
	(via
		(at 323.742304 -129.59969)
		(size 0.508)
		(drill 0.254)
		(layers "F.Cu" "B.Cu")
		(net "SVID_DIO1_CPU0_R")
	)
	(segment
		(start 366.309148 -136.528302)
		(end 366.90173 -135.93572)
		(width 0.10795)
		(layer "B.Cu")
		(net "SVID_DIO1_CPU0_R")
	)
	(segment
		(start 354.8761 -111.1885)
		(end 354.8761 -109.0422)
		(width 0.10795)
		(layer "B.Cu")
		(net "SVID_DIO1_CPU0_R")
	)
	(segment
		(start 344.66149 -126.272544)
		(end 344.66149 -121.786904)
		(width 0.10795)
		(layer "B.Cu")
		(net "SVID_DIO1_CPU0_R")
	)
	(segment
		(start 346.347796 -127.95885)
		(end 344.66149 -126.272544)
		(width 0.10795)
		(layer "B.Cu")
		(net "SVID_DIO1_CPU0_R")
	)
	(segment
		(start 344.66149 -121.786904)
		(end 347.976444 -118.47195)
		(width 0.10795)
		(layer "B.Cu")
		(net "SVID_DIO1_CPU0_R")
	)
	(segment
		(start 347.976444 -118.47195)
		(end 349.967804 -118.47195)
		(width 0.10795)
		(layer "B.Cu")
		(net "SVID_DIO1_CPU0_R")
	)
	(segment
		(start 352.425 -113.6396)
		(end 354.8761 -111.1885)
		(width 0.10795)
		(layer "B.Cu")
		(net "SVID_DIO1_CPU0_R")
	)
	(segment
		(start 337.8454 -17.272)
		(end 337.185 -17.272)
		(width 0.10795)
		(layer "B.Cu")
		(net "SVID_DIO1_CPU0_R")
	)
	(segment
		(start 364.25759 -130.33629)
		(end 359.047796 -130.33629)
		(width 0.10795)
		(layer "B.Cu")
		(net "SVID_DIO1_CPU0_R")
	)
	(segment
		(start 349.967804 -118.47195)
		(end 352.425 -116.014754)
		(width 0.10795)
		(layer "B.Cu")
		(net "SVID_DIO1_CPU0_R")
	)
	(segment
		(start 366.90173 -132.98043)
		(end 364.25759 -130.33629)
		(width 0.10795)
		(layer "B.Cu")
		(net "SVID_DIO1_CPU0_R")
	)
	(segment
		(start 359.047796 -130.33629)
		(end 359.003346 -130.29184)
		(width 0.10795)
		(layer "B.Cu")
		(net "SVID_DIO1_CPU0_R")
	)
	(segment
		(start 366.90173 -135.93572)
		(end 366.90173 -132.98043)
		(width 0.10795)
		(layer "B.Cu")
		(net "SVID_DIO1_CPU0_R")
	)
	(segment
		(start 356.658164 -127.95885)
		(end 346.347796 -127.95885)
		(width 0.10795)
		(layer "B.Cu")
		(net "SVID_DIO1_CPU0_R")
	)
	(segment
		(start 366.309148 -137.451592)
		(end 366.309148 -136.528302)
		(width 0.10795)
		(layer "B.Cu")
		(net "SVID_DIO1_CPU0_R")
	)
	(segment
		(start 352.425 -116.014754)
		(end 352.425 -113.6396)
		(width 0.10795)
		(layer "B.Cu")
		(net "SVID_DIO1_CPU0_R")
	)
	(segment
		(start 365.454946 -137.86739)
		(end 365.89335 -137.86739)
		(width 0.10795)
		(layer "B.Cu")
		(net "SVID_DIO1_CPU0_R")
	)
	(segment
		(start 354.4189 -108.585)
		(end 354.3554 -108.585)
		(width 0.10795)
		(layer "B.Cu")
		(net "SVID_DIO1_CPU0_R")
	)
	(segment
		(start 365.454946 -137.86739)
		(end 364.903766 -138.41857)
		(width 0.10795)
		(layer "B.Cu")
		(net "SVID_DIO1_CPU0_R")
	)
	(segment
		(start 365.89335 -137.86739)
		(end 366.309148 -137.451592)
		(width 0.10795)
		(layer "B.Cu")
		(net "SVID_DIO1_CPU0_R")
	)
	(segment
		(start 364.903766 -138.41857)
		(end 364.75924 -138.41857)
		(width 0.10795)
		(layer "B.Cu")
		(net "SVID_DIO1_CPU0_R")
	)
	(segment
		(start 354.8761 -109.0422)
		(end 354.4189 -108.585)
		(width 0.10795)
		(layer "B.Cu")
		(net "SVID_DIO1_CPU0_R")
	)
	(segment
		(start 358.991154 -130.29184)
		(end 356.658164 -127.95885)
		(width 0.10795)
		(layer "B.Cu")
		(net "SVID_DIO1_CPU0_R")
	)
	(segment
		(start 359.003346 -130.29184)
		(end 358.991154 -130.29184)
		(width 0.10795)
		(layer "B.Cu")
		(net "SVID_DIO1_CPU0_R")
	)
	(segment
		(start 333.691484 -21.424138)
		(end 333.691484 -21.114258)
		(width 0.089408)
		(layer "In2.Cu")
		(net "SVID_DIO1_CPU0_R")
	)
	(segment
		(start 339.543898 -127.736092)
		(end 339.985604 -128.177798)
		(width 0.089408)
		(layer "In2.Cu")
		(net "SVID_DIO1_CPU0_R")
	)
	(segment
		(start 337.3628 -17.272)
		(end 337.185 -17.272)
		(width 0.089408)
		(layer "In2.Cu")
		(net "SVID_DIO1_CPU0_R")
	)
	(segment
		(start 360.043476 -128.77673)
		(end 361.98302 -130.716274)
		(width 0.089408)
		(layer "In2.Cu")
		(net "SVID_DIO1_CPU0_R")
	)
	(segment
		(start 323.846698 -129.704084)
		(end 324.473062 -129.704084)
		(width 0.089408)
		(layer "In2.Cu")
		(net "SVID_DIO1_CPU0_R")
	)
	(segment
		(start 365.0742 -135.507222)
		(end 365.0742 -137.513822)
		(width 0.089408)
		(layer "In2.Cu")
		(net "SVID_DIO1_CPU0_R")
	)
	(segment
		(start 348.57309 -128.918716)
		(end 354.907342 -128.918716)
		(width 0.089408)
		(layer "In2.Cu")
		(net "SVID_DIO1_CPU0_R")
	)
	(segment
		(start 335.695798 -129.13106)
		(end 337.090766 -127.736092)
		(width 0.089408)
		(layer "In2.Cu")
		(net "SVID_DIO1_CPU0_R")
	)
	(segment
		(start 337.77555 -35.448748)
		(end 337.620356 -35.293554)
		(width 0.089408)
		(layer "In2.Cu")
		(net "SVID_DIO1_CPU0_R")
	)
	(segment
		(start 328.92492 -29.152342)
		(end 328.92492 -26.190702)
		(width 0.089408)
		(layer "In2.Cu")
		(net "SVID_DIO1_CPU0_R")
	)
	(segment
		(start 339.000846 -35.448748)
		(end 337.77555 -35.448748)
		(width 0.089408)
		(layer "In2.Cu")
		(net "SVID_DIO1_CPU0_R")
	)
	(segment
		(start 337.620356 -35.293554)
		(end 336.872072 -35.293554)
		(width 0.089408)
		(layer "In2.Cu")
		(net "SVID_DIO1_CPU0_R")
	)
	(segment
		(start 355.12375 -128.702308)
		(end 359.969308 -128.702308)
		(width 0.089408)
		(layer "In2.Cu")
		(net "SVID_DIO1_CPU0_R")
	)
	(segment
		(start 348.190566 -128.536192)
		(end 348.57309 -128.918716)
		(width 0.089408)
		(layer "In2.Cu")
		(net "SVID_DIO1_CPU0_R")
	)
	(segment
		(start 361.98302 -132.68706)
		(end 363.658912 -134.362952)
		(width 0.089408)
		(layer "In2.Cu")
		(net "SVID_DIO1_CPU0_R")
	)
	(segment
		(start 339.765386 -46.408086)
		(end 339.765386 -36.213288)
		(width 0.089408)
		(layer "In2.Cu")
		(net "SVID_DIO1_CPU0_R")
	)
	(segment
		(start 329.667362 -32.95777)
		(end 329.667362 -29.894784)
		(width 0.089408)
		(layer "In2.Cu")
		(net "SVID_DIO1_CPU0_R")
	)
	(segment
		(start 361.98302 -130.716274)
		(end 361.98302 -132.68706)
		(width 0.089408)
		(layer "In2.Cu")
		(net "SVID_DIO1_CPU0_R")
	)
	(segment
		(start 332.15834 -35.448748)
		(end 329.667362 -32.95777)
		(width 0.089408)
		(layer "In2.Cu")
		(net "SVID_DIO1_CPU0_R")
	)
	(segment
		(start 336.872072 -35.293554)
		(end 336.716878 -35.448748)
		(width 0.089408)
		(layer "In2.Cu")
		(net "SVID_DIO1_CPU0_R")
	)
	(segment
		(start 337.090766 -127.736092)
		(end 339.543898 -127.736092)
		(width 0.089408)
		(layer "In2.Cu")
		(net "SVID_DIO1_CPU0_R")
	)
	(segment
		(start 345.313 -51.9557)
		(end 339.765386 -46.408086)
		(width 0.089408)
		(layer "In2.Cu")
		(net "SVID_DIO1_CPU0_R")
	)
	(segment
		(start 360.043476 -128.776476)
		(end 360.043476 -128.77673)
		(width 0.089408)
		(layer "In2.Cu")
		(net "SVID_DIO1_CPU0_R")
	)
	(segment
		(start 334.663034 -20.350988)
		(end 335.062322 -19.9517)
		(width 0.089408)
		(layer "In2.Cu")
		(net "SVID_DIO1_CPU0_R")
	)
	(segment
		(start 335.062322 -19.9517)
		(end 337.538314 -19.9517)
		(width 0.089408)
		(layer "In2.Cu")
		(net "SVID_DIO1_CPU0_R")
	)
	(segment
		(start 363.92993 -134.362952)
		(end 365.0742 -135.507222)
		(width 0.089408)
		(layer "In2.Cu")
		(net "SVID_DIO1_CPU0_R")
	)
	(segment
		(start 363.658912 -134.362952)
		(end 363.92993 -134.362952)
		(width 0.089408)
		(layer "In2.Cu")
		(net "SVID_DIO1_CPU0_R")
	)
	(segment
		(start 324.473062 -129.704084)
		(end 326.0598 -128.117346)
		(width 0.089408)
		(layer "In2.Cu")
		(net "SVID_DIO1_CPU0_R")
	)
	(segment
		(start 344.788744 -128.177798)
		(end 345.147138 -128.536192)
		(width 0.089408)
		(layer "In2.Cu")
		(net "SVID_DIO1_CPU0_R")
	)
	(segment
		(start 334.454754 -20.350988)
		(end 334.663034 -20.350988)
		(width 0.089408)
		(layer "In2.Cu")
		(net "SVID_DIO1_CPU0_R")
	)
	(segment
		(start 323.742304 -129.59969)
		(end 323.846698 -129.704084)
		(width 0.089408)
		(layer "In2.Cu")
		(net "SVID_DIO1_CPU0_R")
	)
	(segment
		(start 365.427768 -137.86739)
		(end 365.454946 -137.86739)
		(width 0.089408)
		(layer "In2.Cu")
		(net "SVID_DIO1_CPU0_R")
	)
	(segment
		(start 331.218794 -129.13106)
		(end 335.695798 -129.13106)
		(width 0.089408)
		(layer "In2.Cu")
		(net "SVID_DIO1_CPU0_R")
	)
	(segment
		(start 326.0598 -128.117346)
		(end 328.659744 -128.117346)
		(width 0.089408)
		(layer "In2.Cu")
		(net "SVID_DIO1_CPU0_R")
	)
	(segment
		(start 337.538314 -19.9517)
		(end 338.138516 -19.351498)
		(width 0.089408)
		(layer "In2.Cu")
		(net "SVID_DIO1_CPU0_R")
	)
	(segment
		(start 345.313 -53.1368)
		(end 345.313 -51.9557)
		(width 0.089408)
		(layer "In2.Cu")
		(net "SVID_DIO1_CPU0_R")
	)
	(segment
		(start 330.333858 -128.246124)
		(end 331.218794 -129.13106)
		(width 0.089408)
		(layer "In2.Cu")
		(net "SVID_DIO1_CPU0_R")
	)
	(segment
		(start 339.765386 -36.213288)
		(end 339.000846 -35.448748)
		(width 0.089408)
		(layer "In2.Cu")
		(net "SVID_DIO1_CPU0_R")
	)
	(segment
		(start 336.716878 -35.448748)
		(end 332.15834 -35.448748)
		(width 0.089408)
		(layer "In2.Cu")
		(net "SVID_DIO1_CPU0_R")
	)
	(segment
		(start 339.985604 -128.177798)
		(end 344.788744 -128.177798)
		(width 0.089408)
		(layer "In2.Cu")
		(net "SVID_DIO1_CPU0_R")
	)
	(segment
		(start 333.691484 -21.114258)
		(end 334.454754 -20.350988)
		(width 0.089408)
		(layer "In2.Cu")
		(net "SVID_DIO1_CPU0_R")
	)
	(segment
		(start 365.0742 -137.513822)
		(end 365.427768 -137.86739)
		(width 0.089408)
		(layer "In2.Cu")
		(net "SVID_DIO1_CPU0_R")
	)
	(segment
		(start 328.788522 -128.246124)
		(end 330.333858 -128.246124)
		(width 0.089408)
		(layer "In2.Cu")
		(net "SVID_DIO1_CPU0_R")
	)
	(segment
		(start 329.667362 -29.894784)
		(end 328.92492 -29.152342)
		(width 0.089408)
		(layer "In2.Cu")
		(net "SVID_DIO1_CPU0_R")
	)
	(segment
		(start 345.147138 -128.536192)
		(end 348.190566 -128.536192)
		(width 0.089408)
		(layer "In2.Cu")
		(net "SVID_DIO1_CPU0_R")
	)
	(segment
		(start 328.659744 -128.117346)
		(end 328.788522 -128.246124)
		(width 0.089408)
		(layer "In2.Cu")
		(net "SVID_DIO1_CPU0_R")
	)
	(segment
		(start 359.969308 -128.702308)
		(end 360.043476 -128.776476)
		(width 0.089408)
		(layer "In2.Cu")
		(net "SVID_DIO1_CPU0_R")
	)
	(segment
		(start 354.907342 -128.918716)
		(end 355.12375 -128.702308)
		(width 0.089408)
		(layer "In2.Cu")
		(net "SVID_DIO1_CPU0_R")
	)
	(segment
		(start 338.138516 -19.351498)
		(end 338.138516 -18.047716)
		(width 0.089408)
		(layer "In2.Cu")
		(net "SVID_DIO1_CPU0_R")
	)
	(segment
		(start 328.92492 -26.190702)
		(end 333.691484 -21.424138)
		(width 0.089408)
		(layer "In2.Cu")
		(net "SVID_DIO1_CPU0_R")
	)
	(segment
		(start 338.138516 -18.047716)
		(end 337.3628 -17.272)
		(width 0.089408)
		(layer "In2.Cu")
		(net "SVID_DIO1_CPU0_R")
	)
	(segment
		(start 345.6686 -58.69178)
		(end 345.6686 -62.114684)
		(width 0.089408)
		(layer "In9.Cu")
		(net "SVID_DIO1_CPU0_R")
	)
	(segment
		(start 348.227396 -64.67348)
		(end 348.227396 -68.535804)
		(width 0.089408)
		(layer "In9.Cu")
		(net "SVID_DIO1_CPU0_R")
	)
	(segment
		(start 348.227396 -68.535804)
		(end 344.3732 -72.39)
		(width 0.089408)
		(layer "In9.Cu")
		(net "SVID_DIO1_CPU0_R")
	)
	(segment
		(start 345.313 -58.33618)
		(end 345.6686 -58.69178)
		(width 0.089408)
		(layer "In9.Cu")
		(net "SVID_DIO1_CPU0_R")
	)
	(segment
		(start 345.6686 -62.114684)
		(end 348.227396 -64.67348)
		(width 0.089408)
		(layer "In9.Cu")
		(net "SVID_DIO1_CPU0_R")
	)
	(segment
		(start 345.313 -53.1368)
		(end 345.313 -58.33618)
		(width 0.089408)
		(layer "In9.Cu")
		(net "SVID_DIO1_CPU0_R")
	)
	(segment
		(start 322.876672 -127.236474)
		(end 322.562474 -126.922276)
		(width 0.10795)
		(layer "F.Cu")
		(net "SVID_DIO1_CPU0")
	)
	(segment
		(start 268.806676 -93.23324)
		(end 270.350234 -93.23324)
		(width 0.10795)
		(layer "F.Cu")
		(net "SVID_DIO1_CPU0")
	)
	(segment
		(start 322.562474 -126.922276)
		(end 321.966336 -126.922276)
		(width 0.10795)
		(layer "F.Cu")
		(net "SVID_DIO1_CPU0")
	)
	(segment
		(start 323.200522 -127.236474)
		(end 322.876672 -127.236474)
		(width 0.10795)
		(layer "F.Cu")
		(net "SVID_DIO1_CPU0")
	)
	(segment
		(start 323.516498 -127.55245)
		(end 323.200522 -127.236474)
		(width 0.10795)
		(layer "F.Cu")
		(net "SVID_DIO1_CPU0")
	)
	(segment
		(start 323.516498 -128.013714)
		(end 323.516498 -127.55245)
		(width 0.10795)
		(layer "F.Cu")
		(net "SVID_DIO1_CPU0")
	)
	(via
		(at 321.966336 -126.922276)
		(size 0.508)
		(drill 0.254)
		(layers "F.Cu" "B.Cu")
		(net "SVID_DIO1_CPU0")
	)
	(via
		(at 270.350234 -93.23324)
		(size 0.508)
		(drill 0.254)
		(layers "F.Cu" "B.Cu")
		(net "SVID_DIO1_CPU0")
	)
	(segment
		(start 298.396406 -105.918)
		(end 295.768014 -103.289608)
		(width 0.089408)
		(layer "In4.Cu")
		(net "SVID_DIO1_CPU0")
	)
	(segment
		(start 291.9349 -100.7491)
		(end 291.9349 -99.742244)
		(width 0.089408)
		(layer "In4.Cu")
		(net "SVID_DIO1_CPU0")
	)
	(segment
		(start 291.084 -94.213172)
		(end 290.818062 -93.947234)
		(width 0.089408)
		(layer "In4.Cu")
		(net "SVID_DIO1_CPU0")
	)
	(segment
		(start 290.486338 -93.947234)
		(end 290.25215 -93.713046)
		(width 0.089408)
		(layer "In4.Cu")
		(net "SVID_DIO1_CPU0")
	)
	(segment
		(start 280.73858 -91.96578)
		(end 280.184098 -91.96578)
		(width 0.0889)
		(layer "In4.Cu")
		(net "SVID_DIO1_CPU0")
	)
	(segment
		(start 287.82772 -91.58478)
		(end 287.403032 -91.160092)
		(width 0.0889)
		(layer "In4.Cu")
		(net "SVID_DIO1_CPU0")
	)
	(segment
		(start 275.449284 -92.117164)
		(end 274.967192 -92.117164)
		(width 0.089408)
		(layer "In4.Cu")
		(net "SVID_DIO1_CPU0")
	)
	(segment
		(start 293.772336 -103.289608)
		(end 292.30066 -101.817932)
		(width 0.089408)
		(layer "In4.Cu")
		(net "SVID_DIO1_CPU0")
	)
	(segment
		(start 276.35835 -92.479114)
		(end 275.811234 -92.479114)
		(width 0.0889)
		(layer "In4.Cu")
		(net "SVID_DIO1_CPU0")
	)
	(segment
		(start 277.552912 -92.463112)
		(end 277.09622 -92.00642)
		(width 0.089408)
		(layer "In4.Cu")
		(net "SVID_DIO1_CPU0")
	)
	(segment
		(start 316.104016 -121.90222)
		(end 300.119796 -105.918)
		(width 0.089408)
		(layer "In4.Cu")
		(net "SVID_DIO1_CPU0")
	)
	(segment
		(start 321.284854 -127.45847)
		(end 320.528442 -127.45847)
		(width 0.089408)
		(layer "In4.Cu")
		(net "SVID_DIO1_CPU0")
	)
	(segment
		(start 274.967192 -92.117164)
		(end 274.564602 -92.519754)
		(width 0.089408)
		(layer "In4.Cu")
		(net "SVID_DIO1_CPU0")
	)
	(segment
		(start 287.403032 -91.160092)
		(end 287.04032 -91.160092)
		(width 0.0889)
		(layer "In4.Cu")
		(net "SVID_DIO1_CPU0")
	)
	(segment
		(start 273.656044 -92.08516)
		(end 273.29384 -92.08516)
		(width 0.089408)
		(layer "In4.Cu")
		(net "SVID_DIO1_CPU0")
	)
	(segment
		(start 274.090638 -92.519754)
		(end 273.656044 -92.08516)
		(width 0.089408)
		(layer "In4.Cu")
		(net "SVID_DIO1_CPU0")
	)
	(segment
		(start 319.089278 -121.90222)
		(end 316.104016 -121.90222)
		(width 0.089408)
		(layer "In4.Cu")
		(net "SVID_DIO1_CPU0")
	)
	(segment
		(start 272.8214 -92.5576)
		(end 271.025874 -92.5576)
		(width 0.089408)
		(layer "In4.Cu")
		(net "SVID_DIO1_CPU0")
	)
	(segment
		(start 319.996312 -125.415548)
		(end 319.996312 -122.809254)
		(width 0.089408)
		(layer "In4.Cu")
		(net "SVID_DIO1_CPU0")
	)
	(segment
		(start 288.388044 -91.58478)
		(end 287.82772 -91.58478)
		(width 0.089408)
		(layer "In4.Cu")
		(net "SVID_DIO1_CPU0")
	)
	(segment
		(start 284.254702 -91.661488)
		(end 283.950156 -91.966034)
		(width 0.089408)
		(layer "In4.Cu")
		(net "SVID_DIO1_CPU0")
	)
	(segment
		(start 283.441394 -91.966034)
		(end 283.136848 -91.661488)
		(width 0.089408)
		(layer "In4.Cu")
		(net "SVID_DIO1_CPU0")
	)
	(segment
		(start 283.136848 -91.661488)
		(end 282.759912 -91.661488)
		(width 0.089408)
		(layer "In4.Cu")
		(net "SVID_DIO1_CPU0")
	)
	(segment
		(start 319.846198 -126.776226)
		(end 319.846198 -125.565662)
		(width 0.089408)
		(layer "In4.Cu")
		(net "SVID_DIO1_CPU0")
	)
	(segment
		(start 275.811234 -92.479114)
		(end 275.449284 -92.117164)
		(width 0.089408)
		(layer "In4.Cu")
		(net "SVID_DIO1_CPU0")
	)
	(segment
		(start 278.152098 -92.463112)
		(end 277.552912 -92.463112)
		(width 0.089408)
		(layer "In4.Cu")
		(net "SVID_DIO1_CPU0")
	)
	(segment
		(start 282.448 -91.9734)
		(end 281.75712 -91.9734)
		(width 0.089408)
		(layer "In4.Cu")
		(net "SVID_DIO1_CPU0")
	)
	(segment
		(start 285.184088 -91.966034)
		(end 284.879542 -91.661488)
		(width 0.089408)
		(layer "In4.Cu")
		(net "SVID_DIO1_CPU0")
	)
	(segment
		(start 289.959542 -92.652088)
		(end 289.804348 -92.652088)
		(width 0.089408)
		(layer "In4.Cu")
		(net "SVID_DIO1_CPU0")
	)
	(segment
		(start 286.670496 -91.529916)
		(end 286.203898 -91.529916)
		(width 0.089408)
		(layer "In4.Cu")
		(net "SVID_DIO1_CPU0")
	)
	(segment
		(start 279.879806 -91.661488)
		(end 279.325832 -91.661488)
		(width 0.089408)
		(layer "In4.Cu")
		(net "SVID_DIO1_CPU0")
	)
	(segment
		(start 289.118294 -91.966034)
		(end 288.769298 -91.966034)
		(width 0.089408)
		(layer "In4.Cu")
		(net "SVID_DIO1_CPU0")
	)
	(segment
		(start 292.30066 -101.817932)
		(end 292.30066 -101.11486)
		(width 0.089408)
		(layer "In4.Cu")
		(net "SVID_DIO1_CPU0")
	)
	(segment
		(start 288.769298 -91.966034)
		(end 288.388044 -91.58478)
		(width 0.089408)
		(layer "In4.Cu")
		(net "SVID_DIO1_CPU0")
	)
	(segment
		(start 271.025874 -92.5576)
		(end 270.350234 -93.23324)
		(width 0.089408)
		(layer "In4.Cu")
		(net "SVID_DIO1_CPU0")
	)
	(segment
		(start 276.831044 -92.00642)
		(end 276.35835 -92.479114)
		(width 0.089408)
		(layer "In4.Cu")
		(net "SVID_DIO1_CPU0")
	)
	(segment
		(start 281.445208 -91.661488)
		(end 281.042872 -91.661488)
		(width 0.089408)
		(layer "In4.Cu")
		(net "SVID_DIO1_CPU0")
	)
	(segment
		(start 289.804348 -92.652088)
		(end 289.118294 -91.966034)
		(width 0.089408)
		(layer "In4.Cu")
		(net "SVID_DIO1_CPU0")
	)
	(segment
		(start 284.879542 -91.661488)
		(end 284.254702 -91.661488)
		(width 0.089408)
		(layer "In4.Cu")
		(net "SVID_DIO1_CPU0")
	)
	(segment
		(start 290.818062 -93.947234)
		(end 290.486338 -93.947234)
		(width 0.089408)
		(layer "In4.Cu")
		(net "SVID_DIO1_CPU0")
	)
	(segment
		(start 281.75712 -91.9734)
		(end 281.445208 -91.661488)
		(width 0.089408)
		(layer "In4.Cu")
		(net "SVID_DIO1_CPU0")
	)
	(segment
		(start 300.119796 -105.918)
		(end 298.396406 -105.918)
		(width 0.089408)
		(layer "In4.Cu")
		(net "SVID_DIO1_CPU0")
	)
	(segment
		(start 280.184098 -91.96578)
		(end 280.166318 -91.948)
		(width 0.0889)
		(layer "In4.Cu")
		(net "SVID_DIO1_CPU0")
	)
	(segment
		(start 295.768014 -103.289608)
		(end 293.772336 -103.289608)
		(width 0.089408)
		(layer "In4.Cu")
		(net "SVID_DIO1_CPU0")
	)
	(segment
		(start 282.759912 -91.661488)
		(end 282.448 -91.9734)
		(width 0.089408)
		(layer "In4.Cu")
		(net "SVID_DIO1_CPU0")
	)
	(segment
		(start 278.649176 -91.966034)
		(end 278.152098 -92.463112)
		(width 0.089408)
		(layer "In4.Cu")
		(net "SVID_DIO1_CPU0")
	)
	(segment
		(start 291.338 -99.4918)
		(end 291.084 -99.2378)
		(width 0.089408)
		(layer "In4.Cu")
		(net "SVID_DIO1_CPU0")
	)
	(segment
		(start 291.684456 -99.4918)
		(end 291.338 -99.4918)
		(width 0.089408)
		(layer "In4.Cu")
		(net "SVID_DIO1_CPU0")
	)
	(segment
		(start 319.996312 -122.809254)
		(end 319.089278 -121.90222)
		(width 0.089408)
		(layer "In4.Cu")
		(net "SVID_DIO1_CPU0")
	)
	(segment
		(start 280.75636 -91.948)
		(end 280.73858 -91.96578)
		(width 0.0889)
		(layer "In4.Cu")
		(net "SVID_DIO1_CPU0")
	)
	(segment
		(start 286.203898 -91.529916)
		(end 285.76778 -91.966034)
		(width 0.089408)
		(layer "In4.Cu")
		(net "SVID_DIO1_CPU0")
	)
	(segment
		(start 277.09622 -92.00642)
		(end 276.831044 -92.00642)
		(width 0.089408)
		(layer "In4.Cu")
		(net "SVID_DIO1_CPU0")
	)
	(segment
		(start 292.30066 -101.11486)
		(end 291.9349 -100.7491)
		(width 0.089408)
		(layer "In4.Cu")
		(net "SVID_DIO1_CPU0")
	)
	(segment
		(start 287.04032 -91.160092)
		(end 286.670496 -91.529916)
		(width 0.089408)
		(layer "In4.Cu")
		(net "SVID_DIO1_CPU0")
	)
	(segment
		(start 280.166318 -91.948)
		(end 279.879806 -91.661488)
		(width 0.089408)
		(layer "In4.Cu")
		(net "SVID_DIO1_CPU0")
	)
	(segment
		(start 321.966336 -126.922276)
		(end 321.829176 -127.059436)
		(width 0.089408)
		(layer "In4.Cu")
		(net "SVID_DIO1_CPU0")
	)
	(segment
		(start 279.021286 -91.966034)
		(end 278.649176 -91.966034)
		(width 0.089408)
		(layer "In4.Cu")
		(net "SVID_DIO1_CPU0")
	)
	(segment
		(start 319.846198 -125.565662)
		(end 319.996312 -125.415548)
		(width 0.089408)
		(layer "In4.Cu")
		(net "SVID_DIO1_CPU0")
	)
	(segment
		(start 320.528442 -127.45847)
		(end 319.846198 -126.776226)
		(width 0.089408)
		(layer "In4.Cu")
		(net "SVID_DIO1_CPU0")
	)
	(segment
		(start 291.084 -99.2378)
		(end 291.084 -94.213172)
		(width 0.089408)
		(layer "In4.Cu")
		(net "SVID_DIO1_CPU0")
	)
	(segment
		(start 274.564602 -92.519754)
		(end 274.090638 -92.519754)
		(width 0.0889)
		(layer "In4.Cu")
		(net "SVID_DIO1_CPU0")
	)
	(segment
		(start 290.25215 -92.944696)
		(end 289.959542 -92.652088)
		(width 0.089408)
		(layer "In4.Cu")
		(net "SVID_DIO1_CPU0")
	)
	(segment
		(start 281.042872 -91.661488)
		(end 280.75636 -91.948)
		(width 0.089408)
		(layer "In4.Cu")
		(net "SVID_DIO1_CPU0")
	)
	(segment
		(start 291.9349 -99.742244)
		(end 291.684456 -99.4918)
		(width 0.089408)
		(layer "In4.Cu")
		(net "SVID_DIO1_CPU0")
	)
	(segment
		(start 321.829176 -127.059436)
		(end 321.683888 -127.059436)
		(width 0.089408)
		(layer "In4.Cu")
		(net "SVID_DIO1_CPU0")
	)
	(segment
		(start 290.25215 -93.713046)
		(end 290.25215 -92.944696)
		(width 0.089408)
		(layer "In4.Cu")
		(net "SVID_DIO1_CPU0")
	)
	(segment
		(start 279.325832 -91.661488)
		(end 279.021286 -91.966034)
		(width 0.089408)
		(layer "In4.Cu")
		(net "SVID_DIO1_CPU0")
	)
	(segment
		(start 321.683888 -127.059436)
		(end 321.284854 -127.45847)
		(width 0.089408)
		(layer "In4.Cu")
		(net "SVID_DIO1_CPU0")
	)
	(segment
		(start 285.76778 -91.966034)
		(end 285.184088 -91.966034)
		(width 0.089408)
		(layer "In4.Cu")
		(net "SVID_DIO1_CPU0")
	)
	(segment
		(start 283.950156 -91.966034)
		(end 283.441394 -91.966034)
		(width 0.089408)
		(layer "In4.Cu")
		(net "SVID_DIO1_CPU0")
	)
	(segment
		(start 273.29384 -92.08516)
		(end 272.8214 -92.5576)
		(width 0.089408)
		(layer "In4.Cu")
		(net "SVID_DIO1_CPU0")
	)
	(segment
		(start 188.1378 -115.9764)
		(end 188.1378 -114.888264)
		(width 0.10795)
		(layer "F.Cu")
		(net "SVID_DIO0_CPU1_R")
	)
	(segment
		(start 184.2516 -119.8626)
		(end 188.1378 -115.9764)
		(width 0.10795)
		(layer "F.Cu")
		(net "SVID_DIO0_CPU1_R")
	)
	(segment
		(start 183.910224 -123.277376)
		(end 184.2516 -122.936)
		(width 0.10795)
		(layer "F.Cu")
		(net "SVID_DIO0_CPU1_R")
	)
	(segment
		(start 157.22854 -119.33682)
		(end 157.32506 -119.2403)
		(width 0.10795)
		(layer "F.Cu")
		(net "SVID_DIO0_CPU1_R")
	)
	(segment
		(start 18.288 -86.8172)
		(end 18.288 -86.0552)
		(width 0.10795)
		(layer "F.Cu")
		(net "SVID_DIO0_CPU1_R")
	)
	(segment
		(start 157.022038 -119.33682)
		(end 157.22854 -119.33682)
		(width 0.10795)
		(layer "F.Cu")
		(net "SVID_DIO0_CPU1_R")
	)
	(segment
		(start 183.910224 -123.30303)
		(end 183.910224 -123.277376)
		(width 0.10795)
		(layer "F.Cu")
		(net "SVID_DIO0_CPU1_R")
	)
	(segment
		(start 156.421836 -119.267986)
		(end 156.953204 -119.267986)
		(width 0.10795)
		(layer "F.Cu")
		(net "SVID_DIO0_CPU1_R")
	)
	(segment
		(start 183.210454 -124.0028)
		(end 183.910224 -123.30303)
		(width 0.10795)
		(layer "F.Cu")
		(net "SVID_DIO0_CPU1_R")
	)
	(segment
		(start 164.211 -68.1482)
		(end 163.86556 -68.49364)
		(width 0.10795)
		(layer "F.Cu")
		(net "SVID_DIO0_CPU1_R")
	)
	(segment
		(start 163.86556 -68.49364)
		(end 163.28517 -68.49364)
		(width 0.10795)
		(layer "F.Cu")
		(net "SVID_DIO0_CPU1_R")
	)
	(segment
		(start 184.2516 -122.936)
		(end 184.2516 -119.8626)
		(width 0.10795)
		(layer "F.Cu")
		(net "SVID_DIO0_CPU1_R")
	)
	(segment
		(start 157.817566 -119.33682)
		(end 157.988 -119.166386)
		(width 0.10795)
		(layer "F.Cu")
		(net "SVID_DIO0_CPU1_R")
	)
	(segment
		(start 157.32506 -119.2403)
		(end 157.42158 -119.33682)
		(width 0.10795)
		(layer "F.Cu")
		(net "SVID_DIO0_CPU1_R")
	)
	(segment
		(start 156.953204 -119.267986)
		(end 157.022038 -119.33682)
		(width 0.10795)
		(layer "F.Cu")
		(net "SVID_DIO0_CPU1_R")
	)
	(segment
		(start 157.42158 -119.33682)
		(end 157.817566 -119.33682)
		(width 0.10795)
		(layer "F.Cu")
		(net "SVID_DIO0_CPU1_R")
	)
	(segment
		(start 188.1378 -114.888264)
		(end 188.745114 -114.28095)
		(width 0.10795)
		(layer "F.Cu")
		(net "SVID_DIO0_CPU1_R")
	)
	(via
		(at 163.28517 -68.49364)
		(size 0.508)
		(drill 0.254)
		(layers "F.Cu" "B.Cu")
		(net "SVID_DIO0_CPU1_R")
	)
	(via
		(at 183.210454 -124.0028)
		(size 0.508)
		(drill 0.254)
		(layers "F.Cu" "B.Cu")
		(net "SVID_DIO0_CPU1_R")
	)
	(via
		(at 18.288 -86.0552)
		(size 0.508)
		(drill 0.254)
		(layers "F.Cu" "B.Cu")
		(net "SVID_DIO0_CPU1_R")
	)
	(via
		(at 157.32506 -119.2403)
		(size 0.508)
		(drill 0.254)
		(layers "F.Cu" "B.Cu")
		(net "SVID_DIO0_CPU1_R")
	)
	(via
		(at 23.8252 -157.000194)
		(size 0.508)
		(drill 0.254)
		(layers "F.Cu" "B.Cu")
		(net "SVID_DIO0_CPU1_R")
	)
	(segment
		(start 164.084 -68.199)
		(end 163.78936 -68.49364)
		(width 0.10795)
		(layer "B.Cu")
		(net "SVID_DIO0_CPU1_R")
	)
	(segment
		(start 163.78936 -68.49364)
		(end 163.28517 -68.49364)
		(width 0.10795)
		(layer "B.Cu")
		(net "SVID_DIO0_CPU1_R")
	)
	(segment
		(start 18.288 -86.8172)
		(end 18.288 -86.0552)
		(width 0.10795)
		(layer "B.Cu")
		(net "SVID_DIO0_CPU1_R")
	)
	(segment
		(start 163.424362 -72.380094)
		(end 162.976306 -72.82815)
		(width 0.089408)
		(layer "In2.Cu")
		(net "SVID_DIO0_CPU1_R")
	)
	(segment
		(start 165.152324 -128.420876)
		(end 166.624 -126.9492)
		(width 0.089408)
		(layer "In2.Cu")
		(net "SVID_DIO0_CPU1_R")
	)
	(segment
		(start 159.295084 -129.727198)
		(end 159.29483 -129.726944)
		(width 0.089408)
		(layer "In2.Cu")
		(net "SVID_DIO0_CPU1_R")
	)
	(segment
		(start 171.042838 -125.9586)
		(end 171.607226 -125.394212)
		(width 0.089408)
		(layer "In2.Cu")
		(net "SVID_DIO0_CPU1_R")
	)
	(segment
		(start 159.698182 -98.153982)
		(end 161.989516 -100.445316)
		(width 0.089408)
		(layer "In2.Cu")
		(net "SVID_DIO0_CPU1_R")
	)
	(segment
		(start 156.804614 -119.119396)
		(end 157.022038 -119.33682)
		(width 0.089408)
		(layer "In2.Cu")
		(net "SVID_DIO0_CPU1_R")
	)
	(segment
		(start 157.501082 -157.305502)
		(end 157.501336 -157.305756)
		(width 0.089408)
		(layer "In2.Cu")
		(net "SVID_DIO0_CPU1_R")
	)
	(segment
		(start 162.987736 -70.50278)
		(end 163.424362 -70.939406)
		(width 0.089408)
		(layer "In2.Cu")
		(net "SVID_DIO0_CPU1_R")
	)
	(segment
		(start 159.29483 -129.369312)
		(end 160.243266 -128.420876)
		(width 0.089408)
		(layer "In2.Cu")
		(net "SVID_DIO0_CPU1_R")
	)
	(segment
		(start 174.79137 -123.622308)
		(end 178.549808 -123.622308)
		(width 0.089408)
		(layer "In2.Cu")
		(net "SVID_DIO0_CPU1_R")
	)
	(segment
		(start 157.072076 -156.9212)
		(end 157.456378 -157.305502)
		(width 0.089408)
		(layer "In2.Cu")
		(net "SVID_DIO0_CPU1_R")
	)
	(segment
		(start 170.4594 -125.9586)
		(end 171.042838 -125.9586)
		(width 0.089408)
		(layer "In2.Cu")
		(net "SVID_DIO0_CPU1_R")
	)
	(segment
		(start 160.079436 -152.103836)
		(end 159.295084 -151.319484)
		(width 0.089408)
		(layer "In2.Cu")
		(net "SVID_DIO0_CPU1_R")
	)
	(segment
		(start 95.993966 -157.78734)
		(end 96.860106 -156.9212)
		(width 0.089408)
		(layer "In2.Cu")
		(net "SVID_DIO0_CPU1_R")
	)
	(segment
		(start 164.443918 -155.624784)
		(end 164.443918 -153.627074)
		(width 0.089408)
		(layer "In2.Cu")
		(net "SVID_DIO0_CPU1_R")
	)
	(segment
		(start 162.987736 -68.791074)
		(end 162.987736 -70.50278)
		(width 0.089408)
		(layer "In2.Cu")
		(net "SVID_DIO0_CPU1_R")
	)
	(segment
		(start 169.4688 -126.9492)
		(end 170.4594 -125.9586)
		(width 0.089408)
		(layer "In2.Cu")
		(net "SVID_DIO0_CPU1_R")
	)
	(segment
		(start 163.28517 -68.49364)
		(end 162.987736 -68.791074)
		(width 0.089408)
		(layer "In2.Cu")
		(net "SVID_DIO0_CPU1_R")
	)
	(segment
		(start 161.989516 -108.712508)
		(end 157.204664 -113.49736)
		(width 0.089408)
		(layer "In2.Cu")
		(net "SVID_DIO0_CPU1_R")
	)
	(segment
		(start 162.976306 -74.02195)
		(end 159.698182 -77.300074)
		(width 0.089408)
		(layer "In2.Cu")
		(net "SVID_DIO0_CPU1_R")
	)
	(segment
		(start 156.804614 -117.863112)
		(end 156.804614 -119.119396)
		(width 0.089408)
		(layer "In2.Cu")
		(net "SVID_DIO0_CPU1_R")
	)
	(segment
		(start 162.976306 -72.82815)
		(end 162.976306 -74.02195)
		(width 0.089408)
		(layer "In2.Cu")
		(net "SVID_DIO0_CPU1_R")
	)
	(segment
		(start 159.29483 -129.726944)
		(end 159.29483 -129.369312)
		(width 0.089408)
		(layer "In2.Cu")
		(net "SVID_DIO0_CPU1_R")
	)
	(segment
		(start 173.019466 -125.394212)
		(end 174.79137 -123.622308)
		(width 0.089408)
		(layer "In2.Cu")
		(net "SVID_DIO0_CPU1_R")
	)
	(segment
		(start 96.860106 -156.9212)
		(end 157.072076 -156.9212)
		(width 0.089408)
		(layer "In2.Cu")
		(net "SVID_DIO0_CPU1_R")
	)
	(segment
		(start 161.989516 -100.445316)
		(end 161.989516 -108.712508)
		(width 0.089408)
		(layer "In2.Cu")
		(net "SVID_DIO0_CPU1_R")
	)
	(segment
		(start 162.92068 -152.103836)
		(end 160.079436 -152.103836)
		(width 0.089408)
		(layer "In2.Cu")
		(net "SVID_DIO0_CPU1_R")
	)
	(segment
		(start 162.762946 -157.305756)
		(end 164.443918 -155.624784)
		(width 0.089408)
		(layer "In2.Cu")
		(net "SVID_DIO0_CPU1_R")
	)
	(segment
		(start 171.607226 -125.394212)
		(end 173.019466 -125.394212)
		(width 0.089408)
		(layer "In2.Cu")
		(net "SVID_DIO0_CPU1_R")
	)
	(segment
		(start 157.22854 -119.33682)
		(end 157.32506 -119.2403)
		(width 0.089408)
		(layer "In2.Cu")
		(net "SVID_DIO0_CPU1_R")
	)
	(segment
		(start 164.443918 -153.627074)
		(end 162.92068 -152.103836)
		(width 0.089408)
		(layer "In2.Cu")
		(net "SVID_DIO0_CPU1_R")
	)
	(segment
		(start 90.58275 -156.466794)
		(end 91.903296 -157.78734)
		(width 0.089408)
		(layer "In2.Cu")
		(net "SVID_DIO0_CPU1_R")
	)
	(segment
		(start 157.456378 -157.305502)
		(end 157.501082 -157.305502)
		(width 0.089408)
		(layer "In2.Cu")
		(net "SVID_DIO0_CPU1_R")
	)
	(segment
		(start 91.903296 -157.78734)
		(end 95.993966 -157.78734)
		(width 0.089408)
		(layer "In2.Cu")
		(net "SVID_DIO0_CPU1_R")
	)
	(segment
		(start 157.204664 -113.49736)
		(end 157.204664 -117.463062)
		(width 0.089408)
		(layer "In2.Cu")
		(net "SVID_DIO0_CPU1_R")
	)
	(segment
		(start 163.424362 -70.939406)
		(end 163.424362 -72.380094)
		(width 0.089408)
		(layer "In2.Cu")
		(net "SVID_DIO0_CPU1_R")
	)
	(segment
		(start 157.022038 -119.33682)
		(end 157.22854 -119.33682)
		(width 0.089408)
		(layer "In2.Cu")
		(net "SVID_DIO0_CPU1_R")
	)
	(segment
		(start 23.8252 -157.000194)
		(end 87.516462 -157.000194)
		(width 0.089408)
		(layer "In2.Cu")
		(net "SVID_DIO0_CPU1_R")
	)
	(segment
		(start 88.049862 -156.466794)
		(end 90.58275 -156.466794)
		(width 0.089408)
		(layer "In2.Cu")
		(net "SVID_DIO0_CPU1_R")
	)
	(segment
		(start 87.516462 -157.000194)
		(end 88.049862 -156.466794)
		(width 0.089408)
		(layer "In2.Cu")
		(net "SVID_DIO0_CPU1_R")
	)
	(segment
		(start 160.243266 -128.420876)
		(end 165.152324 -128.420876)
		(width 0.089408)
		(layer "In2.Cu")
		(net "SVID_DIO0_CPU1_R")
	)
	(segment
		(start 157.501336 -157.305756)
		(end 162.762946 -157.305756)
		(width 0.089408)
		(layer "In2.Cu")
		(net "SVID_DIO0_CPU1_R")
	)
	(segment
		(start 166.624 -126.9492)
		(end 169.4688 -126.9492)
		(width 0.089408)
		(layer "In2.Cu")
		(net "SVID_DIO0_CPU1_R")
	)
	(segment
		(start 159.698182 -77.300074)
		(end 159.698182 -98.153982)
		(width 0.089408)
		(layer "In2.Cu")
		(net "SVID_DIO0_CPU1_R")
	)
	(segment
		(start 157.204664 -117.463062)
		(end 156.804614 -117.863112)
		(width 0.089408)
		(layer "In2.Cu")
		(net "SVID_DIO0_CPU1_R")
	)
	(segment
		(start 178.549808 -123.622308)
		(end 178.9303 -124.0028)
		(width 0.089408)
		(layer "In2.Cu")
		(net "SVID_DIO0_CPU1_R")
	)
	(segment
		(start 178.9303 -124.0028)
		(end 183.210454 -124.0028)
		(width 0.089408)
		(layer "In2.Cu")
		(net "SVID_DIO0_CPU1_R")
	)
	(segment
		(start 159.295084 -151.319484)
		(end 159.295084 -129.727198)
		(width 0.089408)
		(layer "In2.Cu")
		(net "SVID_DIO0_CPU1_R")
	)
	(segment
		(start 165.328092 -74.190606)
		(end 163.600892 -72.463406)
		(width 0.089408)
		(layer "In11.Cu")
		(net "SVID_DIO0_CPU1_R")
	)
	(segment
		(start 18.12671 -100.382324)
		(end 18.12671 -99.246944)
		(width 0.089408)
		(layer "In11.Cu")
		(net "SVID_DIO0_CPU1_R")
	)
	(segment
		(start 19.214084 -89.05875)
		(end 19.214084 -88.07704)
		(width 0.089408)
		(layer "In11.Cu")
		(net "SVID_DIO0_CPU1_R")
	)
	(segment
		(start 15.212314 -90.7796)
		(end 16.960342 -90.7796)
		(width 0.089408)
		(layer "In11.Cu")
		(net "SVID_DIO0_CPU1_R")
	)
	(segment
		(start 18.125948 -100.383086)
		(end 18.12671 -100.382324)
		(width 0.089408)
		(layer "In11.Cu")
		(net "SVID_DIO0_CPU1_R")
	)
	(segment
		(start 19.29384 -109.38256)
		(end 18.60042 -108.68914)
		(width 0.089408)
		(layer "In11.Cu")
		(net "SVID_DIO0_CPU1_R")
	)
	(segment
		(start 18.357342 -89.915492)
		(end 19.214084 -89.05875)
		(width 0.089408)
		(layer "In11.Cu")
		(net "SVID_DIO0_CPU1_R")
	)
	(segment
		(start 175.603916 -88.767412)
		(end 173.971204 -87.1347)
		(width 0.089408)
		(layer "In11.Cu")
		(net "SVID_DIO0_CPU1_R")
	)
	(segment
		(start 19.214084 -88.07704)
		(end 18.288 -87.150956)
		(width 0.089408)
		(layer "In11.Cu")
		(net "SVID_DIO0_CPU1_R")
	)
	(segment
		(start 183.41086 -123.420886)
		(end 184.187084 -122.644662)
		(width 0.089408)
		(layer "In11.Cu")
		(net "SVID_DIO0_CPU1_R")
	)
	(segment
		(start 162.9791 -70.81266)
		(end 162.9791 -68.79971)
		(width 0.089408)
		(layer "In11.Cu")
		(net "SVID_DIO0_CPU1_R")
	)
	(segment
		(start 18.60042 -108.68914)
		(end 18.600166 -108.68914)
		(width 0.089408)
		(layer "In11.Cu")
		(net "SVID_DIO0_CPU1_R")
	)
	(segment
		(start 21.591016 -130.039364)
		(end 23.02764 -128.60274)
		(width 0.089408)
		(layer "In11.Cu")
		(net "SVID_DIO0_CPU1_R")
	)
	(segment
		(start 183.210454 -124.0028)
		(end 183.41086 -123.802394)
		(width 0.089408)
		(layer "In11.Cu")
		(net "SVID_DIO0_CPU1_R")
	)
	(segment
		(start 173.971204 -87.1347)
		(end 164.523674 -87.1347)
		(width 0.089408)
		(layer "In11.Cu")
		(net "SVID_DIO0_CPU1_R")
	)
	(segment
		(start 16.096234 -98.449892)
		(end 14.51356 -100.032566)
		(width 0.089408)
		(layer "In11.Cu")
		(net "SVID_DIO0_CPU1_R")
	)
	(segment
		(start 13.434822 -100.032566)
		(end 12.78382 -99.381564)
		(width 0.089408)
		(layer "In11.Cu")
		(net "SVID_DIO0_CPU1_R")
	)
	(segment
		(start 164.523674 -87.1347)
		(end 163.27247 -85.883496)
		(width 0.089408)
		(layer "In11.Cu")
		(net "SVID_DIO0_CPU1_R")
	)
	(segment
		(start 23.428198 -156.603192)
		(end 23.09241 -156.603192)
		(width 0.089408)
		(layer "In11.Cu")
		(net "SVID_DIO0_CPU1_R")
	)
	(segment
		(start 19.29384 -111.703612)
		(end 19.29384 -109.38256)
		(width 0.089408)
		(layer "In11.Cu")
		(net "SVID_DIO0_CPU1_R")
	)
	(segment
		(start 178.492658 -102.84968)
		(end 176.54524 -100.902262)
		(width 0.089408)
		(layer "In11.Cu")
		(net "SVID_DIO0_CPU1_R")
	)
	(segment
		(start 18.125948 -101.473254)
		(end 18.125948 -100.383086)
		(width 0.089408)
		(layer "In11.Cu")
		(net "SVID_DIO0_CPU1_R")
	)
	(segment
		(start 25.66162 -128.60274)
		(end 26.389076 -127.875284)
		(width 0.089408)
		(layer "In11.Cu")
		(net "SVID_DIO0_CPU1_R")
	)
	(segment
		(start 23.09241 -156.603192)
		(end 22.084538 -155.59532)
		(width 0.089408)
		(layer "In11.Cu")
		(net "SVID_DIO0_CPU1_R")
	)
	(segment
		(start 163.906708 -77.444092)
		(end 164.45865 -77.444092)
		(width 0.089408)
		(layer "In11.Cu")
		(net "SVID_DIO0_CPU1_R")
	)
	(segment
		(start 18.126456 -108.21543)
		(end 18.126456 -101.473762)
		(width 0.089408)
		(layer "In11.Cu")
		(net "SVID_DIO0_CPU1_R")
	)
	(segment
		(start 12.78382 -99.381564)
		(end 12.78382 -93.208094)
		(width 0.089408)
		(layer "In11.Cu")
		(net "SVID_DIO0_CPU1_R")
	)
	(segment
		(start 17.82445 -89.915492)
		(end 18.357342 -89.915492)
		(width 0.089408)
		(layer "In11.Cu")
		(net "SVID_DIO0_CPU1_R")
	)
	(segment
		(start 21.591016 -134.520178)
		(end 21.591016 -130.039364)
		(width 0.089408)
		(layer "In11.Cu")
		(net "SVID_DIO0_CPU1_R")
	)
	(segment
		(start 176.54524 -100.902262)
		(end 176.54524 -92.200984)
		(width 0.089408)
		(layer "In11.Cu")
		(net "SVID_DIO0_CPU1_R")
	)
	(segment
		(start 163.600892 -71.434452)
		(end 162.9791 -70.81266)
		(width 0.089408)
		(layer "In11.Cu")
		(net "SVID_DIO0_CPU1_R")
	)
	(segment
		(start 16.960342 -90.7796)
		(end 17.82445 -89.915492)
		(width 0.089408)
		(layer "In11.Cu")
		(net "SVID_DIO0_CPU1_R")
	)
	(segment
		(start 163.600892 -72.463406)
		(end 163.600892 -71.434452)
		(width 0.089408)
		(layer "In11.Cu")
		(net "SVID_DIO0_CPU1_R")
	)
	(segment
		(start 163.27247 -85.858096)
		(end 163.264088 -85.849714)
		(width 0.089408)
		(layer "In11.Cu")
		(net "SVID_DIO0_CPU1_R")
	)
	(segment
		(start 163.27247 -85.883496)
		(end 163.27247 -85.858096)
		(width 0.089408)
		(layer "In11.Cu")
		(net "SVID_DIO0_CPU1_R")
	)
	(segment
		(start 17.329658 -98.449892)
		(end 16.096234 -98.449892)
		(width 0.089408)
		(layer "In11.Cu")
		(net "SVID_DIO0_CPU1_R")
	)
	(segment
		(start 14.51356 -100.032566)
		(end 13.434822 -100.032566)
		(width 0.089408)
		(layer "In11.Cu")
		(net "SVID_DIO0_CPU1_R")
	)
	(segment
		(start 179.129182 -102.84968)
		(end 178.492658 -102.84968)
		(width 0.089408)
		(layer "In11.Cu")
		(net "SVID_DIO0_CPU1_R")
	)
	(segment
		(start 175.603916 -91.25966)
		(end 175.603916 -88.767412)
		(width 0.089408)
		(layer "In11.Cu")
		(net "SVID_DIO0_CPU1_R")
	)
	(segment
		(start 163.264088 -85.849714)
		(end 163.264088 -78.086712)
		(width 0.089408)
		(layer "In11.Cu")
		(net "SVID_DIO0_CPU1_R")
	)
	(segment
		(start 183.41086 -123.802394)
		(end 183.41086 -123.420886)
		(width 0.089408)
		(layer "In11.Cu")
		(net "SVID_DIO0_CPU1_R")
	)
	(segment
		(start 22.084538 -155.59532)
		(end 22.084538 -135.0137)
		(width 0.089408)
		(layer "In11.Cu")
		(net "SVID_DIO0_CPU1_R")
	)
	(segment
		(start 165.328092 -76.57465)
		(end 165.328092 -74.190606)
		(width 0.089408)
		(layer "In11.Cu")
		(net "SVID_DIO0_CPU1_R")
	)
	(segment
		(start 26.389076 -127.875284)
		(end 26.389076 -118.798848)
		(width 0.089408)
		(layer "In11.Cu")
		(net "SVID_DIO0_CPU1_R")
	)
	(segment
		(start 184.187084 -122.644662)
		(end 184.187084 -107.907582)
		(width 0.089408)
		(layer "In11.Cu")
		(net "SVID_DIO0_CPU1_R")
	)
	(segment
		(start 22.084538 -135.0137)
		(end 21.591016 -134.520178)
		(width 0.089408)
		(layer "In11.Cu")
		(net "SVID_DIO0_CPU1_R")
	)
	(segment
		(start 12.78382 -93.208094)
		(end 15.212314 -90.7796)
		(width 0.089408)
		(layer "In11.Cu")
		(net "SVID_DIO0_CPU1_R")
	)
	(segment
		(start 163.264088 -78.086712)
		(end 163.906708 -77.444092)
		(width 0.089408)
		(layer "In11.Cu")
		(net "SVID_DIO0_CPU1_R")
	)
	(segment
		(start 23.8252 -157.000194)
		(end 23.428198 -156.603192)
		(width 0.089408)
		(layer "In11.Cu")
		(net "SVID_DIO0_CPU1_R")
	)
	(segment
		(start 18.600166 -108.68914)
		(end 18.126456 -108.21543)
		(width 0.089408)
		(layer "In11.Cu")
		(net "SVID_DIO0_CPU1_R")
	)
	(segment
		(start 184.187084 -107.907582)
		(end 179.129182 -102.84968)
		(width 0.089408)
		(layer "In11.Cu")
		(net "SVID_DIO0_CPU1_R")
	)
	(segment
		(start 18.12671 -99.246944)
		(end 17.329658 -98.449892)
		(width 0.089408)
		(layer "In11.Cu")
		(net "SVID_DIO0_CPU1_R")
	)
	(segment
		(start 162.9791 -68.79971)
		(end 163.28517 -68.49364)
		(width 0.089408)
		(layer "In11.Cu")
		(net "SVID_DIO0_CPU1_R")
	)
	(segment
		(start 26.389076 -118.798848)
		(end 19.29384 -111.703612)
		(width 0.089408)
		(layer "In11.Cu")
		(net "SVID_DIO0_CPU1_R")
	)
	(segment
		(start 18.288 -87.150956)
		(end 18.288 -86.0552)
		(width 0.089408)
		(layer "In11.Cu")
		(net "SVID_DIO0_CPU1_R")
	)
	(segment
		(start 176.54524 -92.200984)
		(end 175.603916 -91.25966)
		(width 0.089408)
		(layer "In11.Cu")
		(net "SVID_DIO0_CPU1_R")
	)
	(segment
		(start 23.02764 -128.60274)
		(end 25.66162 -128.60274)
		(width 0.089408)
		(layer "In11.Cu")
		(net "SVID_DIO0_CPU1_R")
	)
	(segment
		(start 164.45865 -77.444092)
		(end 165.328092 -76.57465)
		(width 0.089408)
		(layer "In11.Cu")
		(net "SVID_DIO0_CPU1_R")
	)
	(segment
		(start 18.126456 -101.473762)
		(end 18.125948 -101.473254)
		(width 0.089408)
		(layer "In11.Cu")
		(net "SVID_DIO0_CPU1_R")
	)
	(segment
		(start 102.947724 -89.765886)
		(end 102.376224 -89.765886)
		(width 0.10795)
		(layer "F.Cu")
		(net "SVID_DIO0_CPU1")
	)
	(segment
		(start 155.532836 -119.267986)
		(end 154.910536 -119.267986)
		(width 0.10795)
		(layer "F.Cu")
		(net "SVID_DIO0_CPU1")
	)
	(segment
		(start 154.910536 -119.267986)
		(end 154.6352 -118.99265)
		(width 0.10795)
		(layer "F.Cu")
		(net "SVID_DIO0_CPU1")
	)
	(via
		(at 102.376224 -89.765886)
		(size 0.508)
		(drill 0.254)
		(layers "F.Cu" "B.Cu")
		(net "SVID_DIO0_CPU1")
	)
	(via
		(at 154.6352 -118.99265)
		(size 0.508)
		(drill 0.254)
		(layers "F.Cu" "B.Cu")
		(net "SVID_DIO0_CPU1")
	)
	(segment
		(start 115.820444 -91.470988)
		(end 116.567712 -91.470988)
		(width 0.0889)
		(layer "In4.Cu")
		(net "SVID_DIO0_CPU1")
	)
	(segment
		(start 136.29386 -105.918)
		(end 149.446234 -119.070374)
		(width 0.089408)
		(layer "In4.Cu")
		(net "SVID_DIO0_CPU1")
	)
	(segment
		(start 111.74984 -91.166188)
		(end 112.081564 -91.166188)
		(width 0.0889)
		(layer "In4.Cu")
		(net "SVID_DIO0_CPU1")
	)
	(segment
		(start 149.446234 -119.070374)
		(end 154.557476 -119.070374)
		(width 0.089408)
		(layer "In4.Cu")
		(net "SVID_DIO0_CPU1")
	)
	(segment
		(start 118.949724 -91.166188)
		(end 119.398796 -91.61526)
		(width 0.0889)
		(layer "In4.Cu")
		(net "SVID_DIO0_CPU1")
	)
	(segment
		(start 102.376224 -89.765886)
		(end 102.97033 -89.765886)
		(width 0.089408)
		(layer "In4.Cu")
		(net "SVID_DIO0_CPU1")
	)
	(segment
		(start 115.515644 -91.166188)
		(end 115.820444 -91.470988)
		(width 0.0889)
		(layer "In4.Cu")
		(net "SVID_DIO0_CPU1")
	)
	(segment
		(start 120.307354 -91.966034)
		(end 120.827546 -91.966034)
		(width 0.0889)
		(layer "In4.Cu")
		(net "SVID_DIO0_CPU1")
	)
	(segment
		(start 133.957568 -105.918)
		(end 136.29386 -105.918)
		(width 0.089408)
		(layer "In4.Cu")
		(net "SVID_DIO0_CPU1")
	)
	(segment
		(start 128.295146 -101.473)
		(end 129.260346 -102.4382)
		(width 0.089408)
		(layer "In4.Cu")
		(net "SVID_DIO0_CPU1")
	)
	(segment
		(start 117.684296 -91.6178)
		(end 118.166388 -91.6178)
		(width 0.0889)
		(layer "In4.Cu")
		(net "SVID_DIO0_CPU1")
	)
	(segment
		(start 124.985018 -93.556582)
		(end 125.408436 -93.98)
		(width 0.0889)
		(layer "In4.Cu")
		(net "SVID_DIO0_CPU1")
	)
	(segment
		(start 113.132108 -91.50096)
		(end 113.46688 -91.166188)
		(width 0.0889)
		(layer "In4.Cu")
		(net "SVID_DIO0_CPU1")
	)
	(segment
		(start 125.659642 -93.98)
		(end 126.110238 -94.430596)
		(width 0.089408)
		(layer "In4.Cu")
		(net "SVID_DIO0_CPU1")
	)
	(segment
		(start 112.416336 -91.50096)
		(end 113.132108 -91.50096)
		(width 0.0889)
		(layer "In4.Cu")
		(net "SVID_DIO0_CPU1")
	)
	(segment
		(start 123.919742 -92.956634)
		(end 123.952508 -92.956634)
		(width 0.0889)
		(layer "In4.Cu")
		(net "SVID_DIO0_CPU1")
	)
	(segment
		(start 116.872512 -91.166188)
		(end 117.232684 -91.166188)
		(width 0.0889)
		(layer "In4.Cu")
		(net "SVID_DIO0_CPU1")
	)
	(segment
		(start 107.305348 -91.607894)
		(end 107.868212 -91.607894)
		(width 0.089408)
		(layer "In4.Cu")
		(net "SVID_DIO0_CPU1")
	)
	(segment
		(start 118.166388 -91.6178)
		(end 118.618 -91.166188)
		(width 0.0889)
		(layer "In4.Cu")
		(net "SVID_DIO0_CPU1")
	)
	(segment
		(start 109.999272 -91.166188)
		(end 110.364778 -91.166188)
		(width 0.0889)
		(layer "In4.Cu")
		(net "SVID_DIO0_CPU1")
	)
	(segment
		(start 109.62386 -91.5416)
		(end 109.999272 -91.166188)
		(width 0.0889)
		(layer "In4.Cu")
		(net "SVID_DIO0_CPU1")
	)
	(segment
		(start 122.701558 -92.213176)
		(end 122.729498 -92.261436)
		(width 0.0889)
		(layer "In4.Cu")
		(net "SVID_DIO0_CPU1")
	)
	(segment
		(start 120.827546 -91.966034)
		(end 121.131838 -91.661742)
		(width 0.0889)
		(layer "In4.Cu")
		(net "SVID_DIO0_CPU1")
	)
	(segment
		(start 124.50699 -93.39961)
		(end 124.663962 -93.556582)
		(width 0.0889)
		(layer "In4.Cu")
		(net "SVID_DIO0_CPU1")
	)
	(segment
		(start 103.875332 -90.670888)
		(end 106.368342 -90.670888)
		(width 0.089408)
		(layer "In4.Cu")
		(net "SVID_DIO0_CPU1")
	)
	(segment
		(start 108.226098 -91.96578)
		(end 108.8644 -91.96578)
		(width 0.0889)
		(layer "In4.Cu")
		(net "SVID_DIO0_CPU1")
	)
	(segment
		(start 126.110238 -100.1522)
		(end 126.344426 -100.386388)
		(width 0.089408)
		(layer "In4.Cu")
		(net "SVID_DIO0_CPU1")
	)
	(segment
		(start 154.557476 -119.070374)
		(end 154.6352 -118.99265)
		(width 0.089408)
		(layer "In4.Cu")
		(net "SVID_DIO0_CPU1")
	)
	(segment
		(start 114.222276 -91.58986)
		(end 114.71402 -91.58986)
		(width 0.0889)
		(layer "In4.Cu")
		(net "SVID_DIO0_CPU1")
	)
	(segment
		(start 108.079032 -91.818714)
		(end 108.226098 -91.96578)
		(width 0.0889)
		(layer "In4.Cu")
		(net "SVID_DIO0_CPU1")
	)
	(segment
		(start 112.081564 -91.166188)
		(end 112.416336 -91.50096)
		(width 0.0889)
		(layer "In4.Cu")
		(net "SVID_DIO0_CPU1")
	)
	(segment
		(start 126.344426 -100.386388)
		(end 126.709424 -100.386388)
		(width 0.089408)
		(layer "In4.Cu")
		(net "SVID_DIO0_CPU1")
	)
	(segment
		(start 122.507248 -91.966034)
		(end 122.52833 -91.987116)
		(width 0.0889)
		(layer "In4.Cu")
		(net "SVID_DIO0_CPU1")
	)
	(segment
		(start 129.260346 -102.4382)
		(end 130.124454 -102.4382)
		(width 0.089408)
		(layer "In4.Cu")
		(net "SVID_DIO0_CPU1")
	)
	(segment
		(start 113.798604 -91.166188)
		(end 114.222276 -91.58986)
		(width 0.0889)
		(layer "In4.Cu")
		(net "SVID_DIO0_CPU1")
	)
	(segment
		(start 115.137692 -91.166188)
		(end 115.515644 -91.166188)
		(width 0.0889)
		(layer "In4.Cu")
		(net "SVID_DIO0_CPU1")
	)
	(segment
		(start 117.232684 -91.166188)
		(end 117.684296 -91.6178)
		(width 0.0889)
		(layer "In4.Cu")
		(net "SVID_DIO0_CPU1")
	)
	(segment
		(start 119.398796 -91.61526)
		(end 119.95658 -91.61526)
		(width 0.0889)
		(layer "In4.Cu")
		(net "SVID_DIO0_CPU1")
	)
	(segment
		(start 130.657854 -102.9716)
		(end 131.011168 -102.9716)
		(width 0.089408)
		(layer "In4.Cu")
		(net "SVID_DIO0_CPU1")
	)
	(segment
		(start 127.796036 -101.473)
		(end 128.295146 -101.473)
		(width 0.089408)
		(layer "In4.Cu")
		(net "SVID_DIO0_CPU1")
	)
	(segment
		(start 114.71402 -91.58986)
		(end 115.137692 -91.166188)
		(width 0.0889)
		(layer "In4.Cu")
		(net "SVID_DIO0_CPU1")
	)
	(segment
		(start 113.46688 -91.166188)
		(end 113.798604 -91.166188)
		(width 0.0889)
		(layer "In4.Cu")
		(net "SVID_DIO0_CPU1")
	)
	(segment
		(start 107.868212 -91.607894)
		(end 107.952032 -91.691714)
		(width 0.0889)
		(layer "In4.Cu")
		(net "SVID_DIO0_CPU1")
	)
	(segment
		(start 102.97033 -89.765886)
		(end 103.875332 -90.670888)
		(width 0.089408)
		(layer "In4.Cu")
		(net "SVID_DIO0_CPU1")
	)
	(segment
		(start 116.567712 -91.470988)
		(end 116.872512 -91.166188)
		(width 0.0889)
		(layer "In4.Cu")
		(net "SVID_DIO0_CPU1")
	)
	(segment
		(start 106.368342 -90.670888)
		(end 107.305348 -91.607894)
		(width 0.089408)
		(layer "In4.Cu")
		(net "SVID_DIO0_CPU1")
	)
	(segment
		(start 123.065032 -92.461588)
		(end 123.097798 -92.461588)
		(width 0.0889)
		(layer "In4.Cu")
		(net "SVID_DIO0_CPU1")
	)
	(segment
		(start 126.110238 -94.430596)
		(end 126.110238 -100.1522)
		(width 0.089408)
		(layer "In4.Cu")
		(net "SVID_DIO0_CPU1")
	)
	(segment
		(start 121.52503 -91.661742)
		(end 121.829322 -91.966034)
		(width 0.0889)
		(layer "In4.Cu")
		(net "SVID_DIO0_CPU1")
	)
	(segment
		(start 131.011168 -102.9716)
		(end 133.957568 -105.918)
		(width 0.089408)
		(layer "In4.Cu")
		(net "SVID_DIO0_CPU1")
	)
	(segment
		(start 130.124454 -102.4382)
		(end 130.657854 -102.9716)
		(width 0.089408)
		(layer "In4.Cu")
		(net "SVID_DIO0_CPU1")
	)
	(segment
		(start 110.68431 -91.48572)
		(end 111.430308 -91.48572)
		(width 0.0889)
		(layer "In4.Cu")
		(net "SVID_DIO0_CPU1")
	)
	(segment
		(start 111.430308 -91.48572)
		(end 111.74984 -91.166188)
		(width 0.0889)
		(layer "In4.Cu")
		(net "SVID_DIO0_CPU1")
	)
	(segment
		(start 121.131838 -91.661742)
		(end 121.52503 -91.661742)
		(width 0.0889)
		(layer "In4.Cu")
		(net "SVID_DIO0_CPU1")
	)
	(segment
		(start 110.364778 -91.166188)
		(end 110.68431 -91.48572)
		(width 0.0889)
		(layer "In4.Cu")
		(net "SVID_DIO0_CPU1")
	)
	(segment
		(start 119.95658 -91.61526)
		(end 120.307354 -91.966034)
		(width 0.0889)
		(layer "In4.Cu")
		(net "SVID_DIO0_CPU1")
	)
	(segment
		(start 107.952032 -91.691714)
		(end 108.079032 -91.818714)
		(width 0.089408)
		(layer "In4.Cu")
		(net "SVID_DIO0_CPU1")
	)
	(segment
		(start 118.618 -91.166188)
		(end 118.949724 -91.166188)
		(width 0.0889)
		(layer "In4.Cu")
		(net "SVID_DIO0_CPU1")
	)
	(segment
		(start 124.663962 -93.556582)
		(end 124.985018 -93.556582)
		(width 0.0889)
		(layer "In4.Cu")
		(net "SVID_DIO0_CPU1")
	)
	(segment
		(start 121.829322 -91.966034)
		(end 122.507248 -91.966034)
		(width 0.0889)
		(layer "In4.Cu")
		(net "SVID_DIO0_CPU1")
	)
	(segment
		(start 108.8644 -91.96578)
		(end 109.28858 -91.5416)
		(width 0.0889)
		(layer "In4.Cu")
		(net "SVID_DIO0_CPU1")
	)
	(segment
		(start 125.408436 -93.98)
		(end 125.659642 -93.98)
		(width 0.089408)
		(layer "In4.Cu")
		(net "SVID_DIO0_CPU1")
	)
	(segment
		(start 109.28858 -91.5416)
		(end 109.62386 -91.5416)
		(width 0.0889)
		(layer "In4.Cu")
		(net "SVID_DIO0_CPU1")
	)
	(segment
		(start 126.709424 -100.386388)
		(end 127.796036 -101.473)
		(width 0.089408)
		(layer "In4.Cu")
		(net "SVID_DIO0_CPU1")
	)
	(arc
		(start 123.952508 -92.956634)
		(mid 124.303586 -93.085655)
		(end 124.50699 -93.39961)
		(width 0.0889)
		(layer "In4.Cu")
		(net "SVID_DIO0_CPU1")
	)
	(arc
		(start 122.729498 -92.261436)
		(mid 122.871181 -92.40524)
		(end 123.065032 -92.461588)
		(width 0.0889)
		(layer "In4.Cu")
		(net "SVID_DIO0_CPU1")
	)
	(arc
		(start 122.52833 -91.987116)
		(mid 122.622371 -92.094455)
		(end 122.701558 -92.213176)
		(width 0.0889)
		(layer "In4.Cu")
		(net "SVID_DIO0_CPU1")
	)
	(arc
		(start 123.097798 -92.461588)
		(mid 123.381015 -92.545869)
		(end 123.588018 -92.756736)
		(width 0.0889)
		(layer "In4.Cu")
		(net "SVID_DIO0_CPU1")
	)
	(arc
		(start 123.588018 -92.756736)
		(mid 123.728097 -92.899472)
		(end 123.919742 -92.956634)
		(width 0.0889)
		(layer "In4.Cu")
		(net "SVID_DIO0_CPU1")
	)
	(segment
		(start 202.819 -105.791)
		(end 203.708 -106.68)
		(width 0.10795)
		(layer "F.Cu")
		(net "SVID_DIO0_CPU0_R")
	)
	(segment
		(start 183.769 -63.4746)
		(end 183.769 -62.865)
		(width 0.10795)
		(layer "F.Cu")
		(net "SVID_DIO0_CPU0_R")
	)
	(segment
		(start 202.819 -104.8004)
		(end 202.819 -105.791)
		(width 0.10795)
		(layer "F.Cu")
		(net "SVID_DIO0_CPU0_R")
	)
	(segment
		(start 183.7436 -63.5)
		(end 183.769 -63.4746)
		(width 0.10795)
		(layer "F.Cu")
		(net "SVID_DIO0_CPU0_R")
	)
	(segment
		(start 183.769 -64.135)
		(end 183.769 -63.5254)
		(width 0.10795)
		(layer "F.Cu")
		(net "SVID_DIO0_CPU0_R")
	)
	(segment
		(start 353.724972 -114.28095)
		(end 354.3554 -113.665)
		(width 0.10795)
		(layer "F.Cu")
		(net "SVID_DIO0_CPU0_R")
	)
	(segment
		(start 203.708 -106.68)
		(end 204.089 -106.68)
		(width 0.10795)
		(layer "F.Cu")
		(net "SVID_DIO0_CPU0_R")
	)
	(segment
		(start 183.769 -63.5254)
		(end 183.7436 -63.5)
		(width 0.10795)
		(layer "F.Cu")
		(net "SVID_DIO0_CPU0_R")
	)
	(via
		(at 340.257638 -88.838024)
		(size 0.508)
		(drill 0.254)
		(layers "F.Cu" "B.Cu")
		(net "SVID_DIO0_CPU0_R")
	)
	(via
		(at 202.819 -104.8004)
		(size 0.508)
		(drill 0.254)
		(layers "F.Cu" "B.Cu")
		(net "SVID_DIO0_CPU0_R")
	)
	(via
		(at 334.47228 -106.4006)
		(size 0.508)
		(drill 0.254)
		(layers "F.Cu" "B.Cu")
		(net "SVID_DIO0_CPU0_R")
	)
	(via
		(at 354.3554 -113.665)
		(size 0.508)
		(drill 0.254)
		(layers "F.Cu" "B.Cu")
		(net "SVID_DIO0_CPU0_R")
	)
	(via
		(at 316.48654 -101.62794)
		(size 0.508)
		(drill 0.254)
		(layers "F.Cu" "B.Cu")
		(net "SVID_DIO0_CPU0_R")
	)
	(via
		(at 183.7436 -63.5)
		(size 0.508)
		(drill 0.254)
		(layers "F.Cu" "B.Cu")
		(net "SVID_DIO0_CPU0_R")
	)
	(segment
		(start 340.74608 -87.936832)
		(end 340.74608 -87.58936)
		(width 0.10795)
		(layer "B.Cu")
		(net "SVID_DIO0_CPU0_R")
	)
	(segment
		(start 340.88324 -87.4522)
		(end 341.1982 -87.4522)
		(width 0.10795)
		(layer "B.Cu")
		(net "SVID_DIO0_CPU0_R")
	)
	(segment
		(start 340.3092 -88.0872)
		(end 340.595712 -88.0872)
		(width 0.10795)
		(layer "B.Cu")
		(net "SVID_DIO0_CPU0_R")
	)
	(segment
		(start 340.3092 -88.786462)
		(end 340.3092 -88.0872)
		(width 0.10795)
		(layer "B.Cu")
		(net "SVID_DIO0_CPU0_R")
	)
	(segment
		(start 340.595712 -88.0872)
		(end 340.74608 -87.936832)
		(width 0.10795)
		(layer "B.Cu")
		(net "SVID_DIO0_CPU0_R")
	)
	(segment
		(start 340.74608 -87.58936)
		(end 340.88324 -87.4522)
		(width 0.10795)
		(layer "B.Cu")
		(net "SVID_DIO0_CPU0_R")
	)
	(segment
		(start 204.119734 -105.537)
		(end 204.851 -105.537)
		(width 0.10795)
		(layer "B.Cu")
		(net "SVID_DIO0_CPU0_R")
	)
	(segment
		(start 340.257638 -88.838024)
		(end 340.3092 -88.786462)
		(width 0.10795)
		(layer "B.Cu")
		(net "SVID_DIO0_CPU0_R")
	)
	(segment
		(start 202.819 -104.8004)
		(end 203.383134 -104.8004)
		(width 0.10795)
		(layer "B.Cu")
		(net "SVID_DIO0_CPU0_R")
	)
	(segment
		(start 203.383134 -104.8004)
		(end 204.119734 -105.537)
		(width 0.10795)
		(layer "B.Cu")
		(net "SVID_DIO0_CPU0_R")
	)
	(segment
		(start 339.957156 -104.941878)
		(end 342.63457 -107.619292)
		(width 0.089408)
		(layer "In2.Cu")
		(net "SVID_DIO0_CPU0_R")
	)
	(segment
		(start 181.764178 -81.431892)
		(end 180.566568 -81.431892)
		(width 0.089408)
		(layer "In2.Cu")
		(net "SVID_DIO0_CPU0_R")
	)
	(segment
		(start 180.64734 -64.7446)
		(end 182.499 -64.7446)
		(width 0.089408)
		(layer "In2.Cu")
		(net "SVID_DIO0_CPU0_R")
	)
	(segment
		(start 187.01893 -107.536996)
		(end 182.177182 -102.695248)
		(width 0.089408)
		(layer "In2.Cu")
		(net "SVID_DIO0_CPU0_R")
	)
	(segment
		(start 182.629048 -97.008696)
		(end 182.629048 -82.296762)
		(width 0.089408)
		(layer "In2.Cu")
		(net "SVID_DIO0_CPU0_R")
	)
	(segment
		(start 182.177182 -97.460562)
		(end 182.629048 -97.008696)
		(width 0.089408)
		(layer "In2.Cu")
		(net "SVID_DIO0_CPU0_R")
	)
	(segment
		(start 196.18706 -105.114344)
		(end 196.18706 -106.67619)
		(width 0.089408)
		(layer "In2.Cu")
		(net "SVID_DIO0_CPU0_R")
	)
	(segment
		(start 177.964592 -78.310486)
		(end 177.964592 -73.645014)
		(width 0.089408)
		(layer "In2.Cu")
		(net "SVID_DIO0_CPU0_R")
	)
	(segment
		(start 334.47228 -106.4006)
		(end 334.47228 -105.611168)
		(width 0.089408)
		(layer "In2.Cu")
		(net "SVID_DIO0_CPU0_R")
	)
	(segment
		(start 202.921362 -103.918004)
		(end 202.667616 -103.664258)
		(width 0.089408)
		(layer "In2.Cu")
		(net "SVID_DIO0_CPU0_R")
	)
	(segment
		(start 202.819 -104.8004)
		(end 202.921362 -104.698038)
		(width 0.089408)
		(layer "In2.Cu")
		(net "SVID_DIO0_CPU0_R")
	)
	(segment
		(start 353.60991 -112.91951)
		(end 354.3554 -113.665)
		(width 0.089408)
		(layer "In2.Cu")
		(net "SVID_DIO0_CPU0_R")
	)
	(segment
		(start 353.60991 -108.296964)
		(end 353.60991 -112.91951)
		(width 0.089408)
		(layer "In2.Cu")
		(net "SVID_DIO0_CPU0_R")
	)
	(segment
		(start 180.566568 -81.431892)
		(end 180.241448 -81.757012)
		(width 0.089408)
		(layer "In2.Cu")
		(net "SVID_DIO0_CPU0_R")
	)
	(segment
		(start 177.804572 -80.687672)
		(end 177.804572 -78.470506)
		(width 0.089408)
		(layer "In2.Cu")
		(net "SVID_DIO0_CPU0_R")
	)
	(segment
		(start 196.18706 -106.67619)
		(end 195.326254 -107.536996)
		(width 0.089408)
		(layer "In2.Cu")
		(net "SVID_DIO0_CPU0_R")
	)
	(segment
		(start 179.18938 -67.150488)
		(end 179.18938 -66.20256)
		(width 0.089408)
		(layer "In2.Cu")
		(net "SVID_DIO0_CPU0_R")
	)
	(segment
		(start 334.47228 -105.611168)
		(end 335.14157 -104.941878)
		(width 0.089408)
		(layer "In2.Cu")
		(net "SVID_DIO0_CPU0_R")
	)
	(segment
		(start 177.964592 -73.645014)
		(end 177.165 -72.845422)
		(width 0.089408)
		(layer "In2.Cu")
		(net "SVID_DIO0_CPU0_R")
	)
	(segment
		(start 335.14157 -104.941878)
		(end 339.957156 -104.941878)
		(width 0.089408)
		(layer "In2.Cu")
		(net "SVID_DIO0_CPU0_R")
	)
	(segment
		(start 202.921362 -104.698038)
		(end 202.921362 -103.918004)
		(width 0.089408)
		(layer "In2.Cu")
		(net "SVID_DIO0_CPU0_R")
	)
	(segment
		(start 179.18938 -66.20256)
		(end 180.64734 -64.7446)
		(width 0.089408)
		(layer "In2.Cu")
		(net "SVID_DIO0_CPU0_R")
	)
	(segment
		(start 177.804572 -78.470506)
		(end 177.964592 -78.310486)
		(width 0.089408)
		(layer "In2.Cu")
		(net "SVID_DIO0_CPU0_R")
	)
	(segment
		(start 178.873912 -81.757012)
		(end 177.804572 -80.687672)
		(width 0.089408)
		(layer "In2.Cu")
		(net "SVID_DIO0_CPU0_R")
	)
	(segment
		(start 342.63457 -107.619292)
		(end 352.932238 -107.619292)
		(width 0.089408)
		(layer "In2.Cu")
		(net "SVID_DIO0_CPU0_R")
	)
	(segment
		(start 182.499 -64.7446)
		(end 183.7436 -63.5)
		(width 0.089408)
		(layer "In2.Cu")
		(net "SVID_DIO0_CPU0_R")
	)
	(segment
		(start 177.165 -72.845422)
		(end 177.165 -69.174868)
		(width 0.089408)
		(layer "In2.Cu")
		(net "SVID_DIO0_CPU0_R")
	)
	(segment
		(start 197.637146 -103.664258)
		(end 196.18706 -105.114344)
		(width 0.089408)
		(layer "In2.Cu")
		(net "SVID_DIO0_CPU0_R")
	)
	(segment
		(start 182.177182 -102.695248)
		(end 182.177182 -97.460562)
		(width 0.089408)
		(layer "In2.Cu")
		(net "SVID_DIO0_CPU0_R")
	)
	(segment
		(start 202.667616 -103.664258)
		(end 197.637146 -103.664258)
		(width 0.089408)
		(layer "In2.Cu")
		(net "SVID_DIO0_CPU0_R")
	)
	(segment
		(start 180.241448 -81.757012)
		(end 178.873912 -81.757012)
		(width 0.089408)
		(layer "In2.Cu")
		(net "SVID_DIO0_CPU0_R")
	)
	(segment
		(start 182.629048 -82.296762)
		(end 181.764178 -81.431892)
		(width 0.089408)
		(layer "In2.Cu")
		(net "SVID_DIO0_CPU0_R")
	)
	(segment
		(start 195.326254 -107.536996)
		(end 187.01893 -107.536996)
		(width 0.089408)
		(layer "In2.Cu")
		(net "SVID_DIO0_CPU0_R")
	)
	(segment
		(start 352.932238 -107.619292)
		(end 353.60991 -108.296964)
		(width 0.089408)
		(layer "In2.Cu")
		(net "SVID_DIO0_CPU0_R")
	)
	(segment
		(start 177.165 -69.174868)
		(end 179.18938 -67.150488)
		(width 0.089408)
		(layer "In2.Cu")
		(net "SVID_DIO0_CPU0_R")
	)
	(segment
		(start 318.97574 -115.891818)
		(end 318.849248 -115.765326)
		(width 0.089408)
		(layer "In4.Cu")
		(net "SVID_DIO0_CPU0_R")
	)
	(segment
		(start 229.57282 -148.620734)
		(end 229.57282 -150.55342)
		(width 0.089408)
		(layer "In4.Cu")
		(net "SVID_DIO0_CPU0_R")
	)
	(segment
		(start 319.249552 -146.332448)
		(end 319.249552 -140.997686)
		(width 0.089408)
		(layer "In4.Cu")
		(net "SVID_DIO0_CPU0_R")
	)
	(segment
		(start 318.2112 -147.3708)
		(end 319.249552 -146.332448)
		(width 0.089408)
		(layer "In4.Cu")
		(net "SVID_DIO0_CPU0_R")
	)
	(segment
		(start 319.000124 -114.98199)
		(end 318.596264 -115.38585)
		(width 0.089408)
		(layer "In4.Cu")
		(net "SVID_DIO0_CPU0_R")
	)
	(segment
		(start 287.65627 -151.686768)
		(end 301.449232 -151.686768)
		(width 0.089408)
		(layer "In4.Cu")
		(net "SVID_DIO0_CPU0_R")
	)
	(segment
		(start 193.045588 -116.924074)
		(end 193.045588 -146.354546)
		(width 0.089408)
		(layer "In4.Cu")
		(net "SVID_DIO0_CPU0_R")
	)
	(segment
		(start 178.23942 -77.010514)
		(end 179.052474 -77.823568)
		(width 0.089408)
		(layer "In4.Cu")
		(net "SVID_DIO0_CPU0_R")
	)
	(segment
		(start 183.25084 -63.00724)
		(end 182.050182 -63.00724)
		(width 0.089408)
		(layer "In4.Cu")
		(net "SVID_DIO0_CPU0_R")
	)
	(segment
		(start 318.494156 -114.476022)
		(end 318.090296 -114.879882)
		(width 0.089408)
		(layer "In4.Cu")
		(net "SVID_DIO0_CPU0_R")
	)
	(segment
		(start 321.372992 -129.179574)
		(end 321.373246 -129.179828)
		(width 0.089408)
		(layer "In4.Cu")
		(net "SVID_DIO0_CPU0_R")
	)
	(segment
		(start 321.801744 -124.201936)
		(end 321.801744 -120.132856)
		(width 0.089408)
		(layer "In4.Cu")
		(net "SVID_DIO0_CPU0_R")
	)
	(segment
		(start 230.706168 -151.686768)
		(end 260.827012 -151.686768)
		(width 0.089408)
		(layer "In4.Cu")
		(net "SVID_DIO0_CPU0_R")
	)
	(segment
		(start 193.045588 -146.354546)
		(end 194.498214 -147.807172)
		(width 0.089408)
		(layer "In4.Cu")
		(net "SVID_DIO0_CPU0_R")
	)
	(segment
		(start 315.91377 -111.769144)
		(end 315.91377 -102.20071)
		(width 0.089408)
		(layer "In4.Cu")
		(net "SVID_DIO0_CPU0_R")
	)
	(segment
		(start 286.950912 -150.4061)
		(end 286.9438 -150.413212)
		(width 0.089408)
		(layer "In4.Cu")
		(net "SVID_DIO0_CPU0_R")
	)
	(segment
		(start 179.905914 -77.823568)
		(end 180.494432 -78.412086)
		(width 0.089408)
		(layer "In4.Cu")
		(net "SVID_DIO0_CPU0_R")
	)
	(segment
		(start 180.494432 -78.412086)
		(end 180.494432 -79.480664)
		(width 0.089408)
		(layer "In4.Cu")
		(net "SVID_DIO0_CPU0_R")
	)
	(segment
		(start 323.706998 -127.553212)
		(end 323.706998 -126.10719)
		(width 0.089408)
		(layer "In4.Cu")
		(net "SVID_DIO0_CPU0_R")
	)
	(segment
		(start 322.080382 -129.179828)
		(end 323.706998 -127.553212)
		(width 0.089408)
		(layer "In4.Cu")
		(net "SVID_DIO0_CPU0_R")
	)
	(segment
		(start 286.9438 -150.413212)
		(end 286.9438 -150.974298)
		(width 0.089408)
		(layer "In4.Cu")
		(net "SVID_DIO0_CPU0_R")
	)
	(segment
		(start 319.759076 -115.61445)
		(end 319.632584 -115.487958)
		(width 0.089408)
		(layer "In4.Cu")
		(net "SVID_DIO0_CPU0_R")
	)
	(segment
		(start 183.3372 -82.323432)
		(end 183.3372 -103.926386)
		(width 0.089408)
		(layer "In4.Cu")
		(net "SVID_DIO0_CPU0_R")
	)
	(segment
		(start 303.790858 -147.3708)
		(end 318.2112 -147.3708)
		(width 0.089408)
		(layer "In4.Cu")
		(net "SVID_DIO0_CPU0_R")
	)
	(segment
		(start 319.253108 -115.108482)
		(end 319.126616 -114.98199)
		(width 0.089408)
		(layer "In4.Cu")
		(net "SVID_DIO0_CPU0_R")
	)
	(segment
		(start 318.34328 -115.132866)
		(end 318.74714 -114.729006)
		(width 0.089408)
		(layer "In4.Cu")
		(net "SVID_DIO0_CPU0_R")
	)
	(segment
		(start 319.249552 -140.997686)
		(end 320.949574 -139.297664)
		(width 0.089408)
		(layer "In4.Cu")
		(net "SVID_DIO0_CPU0_R")
	)
	(segment
		(start 319.861184 -116.777262)
		(end 319.861184 -116.65077)
		(width 0.089408)
		(layer "In4.Cu")
		(net "SVID_DIO0_CPU0_R")
	)
	(segment
		(start 318.620648 -114.476022)
		(end 318.494156 -114.476022)
		(width 0.089408)
		(layer "In4.Cu")
		(net "SVID_DIO0_CPU0_R")
	)
	(segment
		(start 183.3372 -103.926386)
		(end 184.004966 -104.594152)
		(width 0.089408)
		(layer "In4.Cu")
		(net "SVID_DIO0_CPU0_R")
	)
	(segment
		(start 319.632584 -115.487958)
		(end 319.506092 -115.487958)
		(width 0.089408)
		(layer "In4.Cu")
		(net "SVID_DIO0_CPU0_R")
	)
	(segment
		(start 318.469772 -115.38585)
		(end 318.34328 -115.259358)
		(width 0.089408)
		(layer "In4.Cu")
		(net "SVID_DIO0_CPU0_R")
	)
	(segment
		(start 319.987676 -116.903754)
		(end 319.861184 -116.777262)
		(width 0.089408)
		(layer "In4.Cu")
		(net "SVID_DIO0_CPU0_R")
	)
	(segment
		(start 318.74714 -114.602514)
		(end 318.620648 -114.476022)
		(width 0.089408)
		(layer "In4.Cu")
		(net "SVID_DIO0_CPU0_R")
	)
	(segment
		(start 318.74714 -114.729006)
		(end 318.74714 -114.602514)
		(width 0.089408)
		(layer "In4.Cu")
		(net "SVID_DIO0_CPU0_R")
	)
	(segment
		(start 261.65048 -148.994622)
		(end 262.981948 -147.663154)
		(width 0.089408)
		(layer "In4.Cu")
		(net "SVID_DIO0_CPU0_R")
	)
	(segment
		(start 286.950912 -149.418294)
		(end 286.950912 -150.4061)
		(width 0.089408)
		(layer "In4.Cu")
		(net "SVID_DIO0_CPU0_R")
	)
	(segment
		(start 320.949574 -139.297664)
		(end 320.949574 -129.414016)
		(width 0.089408)
		(layer "In4.Cu")
		(net "SVID_DIO0_CPU0_R")
	)
	(segment
		(start 177.419 -69.441568)
		(end 177.419 -74.757534)
		(width 0.089408)
		(layer "In4.Cu")
		(net "SVID_DIO0_CPU0_R")
	)
	(segment
		(start 182.050182 -63.00724)
		(end 179.628292 -65.42913)
		(width 0.089408)
		(layer "In4.Cu")
		(net "SVID_DIO0_CPU0_R")
	)
	(segment
		(start 320.265044 -116.120418)
		(end 320.138552 -115.993926)
		(width 0.089408)
		(layer "In4.Cu")
		(net "SVID_DIO0_CPU0_R")
	)
	(segment
		(start 177.419 -74.757534)
		(end 178.23942 -75.577954)
		(width 0.089408)
		(layer "In4.Cu")
		(net "SVID_DIO0_CPU0_R")
	)
	(segment
		(start 321.184016 -129.179574)
		(end 321.372992 -129.179574)
		(width 0.089408)
		(layer "In4.Cu")
		(net "SVID_DIO0_CPU0_R")
	)
	(segment
		(start 317.837312 -114.75339)
		(end 317.837312 -114.626898)
		(width 0.089408)
		(layer "In4.Cu")
		(net "SVID_DIO0_CPU0_R")
	)
	(segment
		(start 320.265044 -116.24691)
		(end 320.265044 -116.120418)
		(width 0.089408)
		(layer "In4.Cu")
		(net "SVID_DIO0_CPU0_R")
	)
	(segment
		(start 317.837312 -114.626898)
		(end 318.241172 -114.223038)
		(width 0.089408)
		(layer "In4.Cu")
		(net "SVID_DIO0_CPU0_R")
	)
	(segment
		(start 318.596264 -115.38585)
		(end 318.469772 -115.38585)
		(width 0.089408)
		(layer "In4.Cu")
		(net "SVID_DIO0_CPU0_R")
	)
	(segment
		(start 261.65048 -150.8633)
		(end 261.65048 -148.994622)
		(width 0.089408)
		(layer "In4.Cu")
		(net "SVID_DIO0_CPU0_R")
	)
	(segment
		(start 262.981948 -147.663154)
		(end 285.195772 -147.663154)
		(width 0.089408)
		(layer "In4.Cu")
		(net "SVID_DIO0_CPU0_R")
	)
	(segment
		(start 319.102232 -115.891818)
		(end 318.97574 -115.891818)
		(width 0.089408)
		(layer "In4.Cu")
		(net "SVID_DIO0_CPU0_R")
	)
	(segment
		(start 318.090296 -114.879882)
		(end 317.963804 -114.879882)
		(width 0.089408)
		(layer "In4.Cu")
		(net "SVID_DIO0_CPU0_R")
	)
	(segment
		(start 302.387 -150.749)
		(end 302.387 -148.774658)
		(width 0.089408)
		(layer "In4.Cu")
		(net "SVID_DIO0_CPU0_R")
	)
	(segment
		(start 317.963804 -114.879882)
		(end 317.837312 -114.75339)
		(width 0.089408)
		(layer "In4.Cu")
		(net "SVID_DIO0_CPU0_R")
	)
	(segment
		(start 184.004966 -104.594152)
		(end 184.004966 -107.883452)
		(width 0.089408)
		(layer "In4.Cu")
		(net "SVID_DIO0_CPU0_R")
	)
	(segment
		(start 319.126616 -114.98199)
		(end 319.000124 -114.98199)
		(width 0.089408)
		(layer "In4.Cu")
		(net "SVID_DIO0_CPU0_R")
	)
	(segment
		(start 320.518028 -116.499894)
		(end 320.114168 -116.903754)
		(width 0.089408)
		(layer "In4.Cu")
		(net "SVID_DIO0_CPU0_R")
	)
	(segment
		(start 318.849248 -115.765326)
		(end 318.849248 -115.638834)
		(width 0.089408)
		(layer "In4.Cu")
		(net "SVID_DIO0_CPU0_R")
	)
	(segment
		(start 322.325492 -118.180866)
		(end 320.64452 -116.499894)
		(width 0.089408)
		(layer "In4.Cu")
		(net "SVID_DIO0_CPU0_R")
	)
	(segment
		(start 285.195772 -147.663154)
		(end 286.950912 -149.418294)
		(width 0.089408)
		(layer "In4.Cu")
		(net "SVID_DIO0_CPU0_R")
	)
	(segment
		(start 319.861184 -116.65077)
		(end 320.265044 -116.24691)
		(width 0.089408)
		(layer "In4.Cu")
		(net "SVID_DIO0_CPU0_R")
	)
	(segment
		(start 228.759258 -147.807172)
		(end 229.57282 -148.620734)
		(width 0.089408)
		(layer "In4.Cu")
		(net "SVID_DIO0_CPU0_R")
	)
	(segment
		(start 322.325492 -119.609108)
		(end 322.325492 -118.180866)
		(width 0.089408)
		(layer "In4.Cu")
		(net "SVID_DIO0_CPU0_R")
	)
	(segment
		(start 184.004966 -107.883452)
		(end 193.045588 -116.924074)
		(width 0.089408)
		(layer "In4.Cu")
		(net "SVID_DIO0_CPU0_R")
	)
	(segment
		(start 315.91377 -102.20071)
		(end 316.48654 -101.62794)
		(width 0.089408)
		(layer "In4.Cu")
		(net "SVID_DIO0_CPU0_R")
	)
	(segment
		(start 319.355216 -116.144802)
		(end 319.759076 -115.740942)
		(width 0.089408)
		(layer "In4.Cu")
		(net "SVID_DIO0_CPU0_R")
	)
	(segment
		(start 320.114168 -116.903754)
		(end 319.987676 -116.903754)
		(width 0.089408)
		(layer "In4.Cu")
		(net "SVID_DIO0_CPU0_R")
	)
	(segment
		(start 319.6082 -116.397786)
		(end 319.481708 -116.397786)
		(width 0.089408)
		(layer "In4.Cu")
		(net "SVID_DIO0_CPU0_R")
	)
	(segment
		(start 194.498214 -147.807172)
		(end 228.759258 -147.807172)
		(width 0.089408)
		(layer "In4.Cu")
		(net "SVID_DIO0_CPU0_R")
	)
	(segment
		(start 319.253108 -115.234974)
		(end 319.253108 -115.108482)
		(width 0.089408)
		(layer "In4.Cu")
		(net "SVID_DIO0_CPU0_R")
	)
	(segment
		(start 320.138552 -115.993926)
		(end 320.01206 -115.993926)
		(width 0.089408)
		(layer "In4.Cu")
		(net "SVID_DIO0_CPU0_R")
	)
	(segment
		(start 179.052474 -77.823568)
		(end 179.905914 -77.823568)
		(width 0.089408)
		(layer "In4.Cu")
		(net "SVID_DIO0_CPU0_R")
	)
	(segment
		(start 321.801744 -120.132856)
		(end 322.325492 -119.609108)
		(width 0.089408)
		(layer "In4.Cu")
		(net "SVID_DIO0_CPU0_R")
	)
	(segment
		(start 178.23942 -75.577954)
		(end 178.23942 -77.010514)
		(width 0.089408)
		(layer "In4.Cu")
		(net "SVID_DIO0_CPU0_R")
	)
	(segment
		(start 320.64452 -116.499894)
		(end 320.518028 -116.499894)
		(width 0.089408)
		(layer "In4.Cu")
		(net "SVID_DIO0_CPU0_R")
	)
	(segment
		(start 229.57282 -150.55342)
		(end 230.706168 -151.686768)
		(width 0.089408)
		(layer "In4.Cu")
		(net "SVID_DIO0_CPU0_R")
	)
	(segment
		(start 323.706998 -126.10719)
		(end 321.801744 -124.201936)
		(width 0.089408)
		(layer "In4.Cu")
		(net "SVID_DIO0_CPU0_R")
	)
	(segment
		(start 319.506092 -115.487958)
		(end 319.102232 -115.891818)
		(width 0.089408)
		(layer "In4.Cu")
		(net "SVID_DIO0_CPU0_R")
	)
	(segment
		(start 319.481708 -116.397786)
		(end 319.355216 -116.271294)
		(width 0.089408)
		(layer "In4.Cu")
		(net "SVID_DIO0_CPU0_R")
	)
	(segment
		(start 301.449232 -151.686768)
		(end 302.387 -150.749)
		(width 0.089408)
		(layer "In4.Cu")
		(net "SVID_DIO0_CPU0_R")
	)
	(segment
		(start 319.355216 -116.271294)
		(end 319.355216 -116.144802)
		(width 0.089408)
		(layer "In4.Cu")
		(net "SVID_DIO0_CPU0_R")
	)
	(segment
		(start 302.387 -148.774658)
		(end 303.790858 -147.3708)
		(width 0.089408)
		(layer "In4.Cu")
		(net "SVID_DIO0_CPU0_R")
	)
	(segment
		(start 320.01206 -115.993926)
		(end 319.6082 -116.397786)
		(width 0.089408)
		(layer "In4.Cu")
		(net "SVID_DIO0_CPU0_R")
	)
	(segment
		(start 286.9438 -150.974298)
		(end 287.65627 -151.686768)
		(width 0.089408)
		(layer "In4.Cu")
		(net "SVID_DIO0_CPU0_R")
	)
	(segment
		(start 319.759076 -115.740942)
		(end 319.759076 -115.61445)
		(width 0.089408)
		(layer "In4.Cu")
		(net "SVID_DIO0_CPU0_R")
	)
	(segment
		(start 320.949574 -129.414016)
		(end 321.184016 -129.179574)
		(width 0.089408)
		(layer "In4.Cu")
		(net "SVID_DIO0_CPU0_R")
	)
	(segment
		(start 318.241172 -114.223038)
		(end 318.241172 -114.096546)
		(width 0.089408)
		(layer "In4.Cu")
		(net "SVID_DIO0_CPU0_R")
	)
	(segment
		(start 318.34328 -115.259358)
		(end 318.34328 -115.132866)
		(width 0.089408)
		(layer "In4.Cu")
		(net "SVID_DIO0_CPU0_R")
	)
	(segment
		(start 318.849248 -115.638834)
		(end 319.253108 -115.234974)
		(width 0.089408)
		(layer "In4.Cu")
		(net "SVID_DIO0_CPU0_R")
	)
	(segment
		(start 260.827012 -151.686768)
		(end 261.65048 -150.8633)
		(width 0.089408)
		(layer "In4.Cu")
		(net "SVID_DIO0_CPU0_R")
	)
	(segment
		(start 179.628292 -67.232276)
		(end 177.419 -69.441568)
		(width 0.089408)
		(layer "In4.Cu")
		(net "SVID_DIO0_CPU0_R")
	)
	(segment
		(start 183.7436 -63.5)
		(end 183.25084 -63.00724)
		(width 0.089408)
		(layer "In4.Cu")
		(net "SVID_DIO0_CPU0_R")
	)
	(segment
		(start 318.241172 -114.096546)
		(end 315.91377 -111.769144)
		(width 0.089408)
		(layer "In4.Cu")
		(net "SVID_DIO0_CPU0_R")
	)
	(segment
		(start 180.494432 -79.480664)
		(end 183.3372 -82.323432)
		(width 0.089408)
		(layer "In4.Cu")
		(net "SVID_DIO0_CPU0_R")
	)
	(segment
		(start 321.373246 -129.179828)
		(end 322.080382 -129.179828)
		(width 0.089408)
		(layer "In4.Cu")
		(net "SVID_DIO0_CPU0_R")
	)
	(segment
		(start 179.628292 -65.42913)
		(end 179.628292 -67.232276)
		(width 0.089408)
		(layer "In4.Cu")
		(net "SVID_DIO0_CPU0_R")
	)
	(segment
		(start 342.604852 -90.943176)
		(end 340.4997 -88.838024)
		(width 0.089408)
		(layer "In9.Cu")
		(net "SVID_DIO0_CPU0_R")
	)
	(segment
		(start 342.604852 -98.92792)
		(end 342.604852 -90.943176)
		(width 0.089408)
		(layer "In9.Cu")
		(net "SVID_DIO0_CPU0_R")
	)
	(segment
		(start 341.309706 -100.581206)
		(end 342.605106 -99.285806)
		(width 0.089408)
		(layer "In9.Cu")
		(net "SVID_DIO0_CPU0_R")
	)
	(segment
		(start 353.138486 -115.45824)
		(end 351.311464 -117.285262)
		(width 0.089408)
		(layer "In9.Cu")
		(net "SVID_DIO0_CPU0_R")
	)
	(segment
		(start 353.450906 -115.45824)
		(end 353.138486 -115.45824)
		(width 0.089408)
		(layer "In9.Cu")
		(net "SVID_DIO0_CPU0_R")
	)
	(segment
		(start 342.605106 -99.285806)
		(end 342.605106 -98.928174)
		(width 0.089408)
		(layer "In9.Cu")
		(net "SVID_DIO0_CPU0_R")
	)
	(segment
		(start 344.588592 -116.265198)
		(end 344.588592 -113.311432)
		(width 0.089408)
		(layer "In9.Cu")
		(net "SVID_DIO0_CPU0_R")
	)
	(segment
		(start 344.588592 -113.311432)
		(end 345.100148 -112.799876)
		(width 0.089408)
		(layer "In9.Cu")
		(net "SVID_DIO0_CPU0_R")
	)
	(segment
		(start 353.6188 -115.290346)
		(end 353.450906 -115.45824)
		(width 0.089408)
		(layer "In9.Cu")
		(net "SVID_DIO0_CPU0_R")
	)
	(segment
		(start 342.605106 -98.928174)
		(end 342.604852 -98.92792)
		(width 0.089408)
		(layer "In9.Cu")
		(net "SVID_DIO0_CPU0_R")
	)
	(segment
		(start 345.0463 -116.722906)
		(end 344.588592 -116.265198)
		(width 0.089408)
		(layer "In9.Cu")
		(net "SVID_DIO0_CPU0_R")
	)
	(segment
		(start 346.851224 -116.722906)
		(end 345.0463 -116.722906)
		(width 0.089408)
		(layer "In9.Cu")
		(net "SVID_DIO0_CPU0_R")
	)
	(segment
		(start 347.41358 -117.285262)
		(end 346.851224 -116.722906)
		(width 0.089408)
		(layer "In9.Cu")
		(net "SVID_DIO0_CPU0_R")
	)
	(segment
		(start 353.6188 -114.4016)
		(end 353.6188 -115.290346)
		(width 0.089408)
		(layer "In9.Cu")
		(net "SVID_DIO0_CPU0_R")
	)
	(segment
		(start 351.311464 -117.285262)
		(end 347.41358 -117.285262)
		(width 0.089408)
		(layer "In9.Cu")
		(net "SVID_DIO0_CPU0_R")
	)
	(segment
		(start 341.309706 -103.90632)
		(end 341.309706 -100.581206)
		(width 0.089408)
		(layer "In9.Cu")
		(net "SVID_DIO0_CPU0_R")
	)
	(segment
		(start 345.100148 -112.799876)
		(end 345.100148 -107.696762)
		(width 0.089408)
		(layer "In9.Cu")
		(net "SVID_DIO0_CPU0_R")
	)
	(segment
		(start 345.100148 -107.696762)
		(end 341.309706 -103.90632)
		(width 0.089408)
		(layer "In9.Cu")
		(net "SVID_DIO0_CPU0_R")
	)
	(segment
		(start 340.4997 -88.838024)
		(end 340.257638 -88.838024)
		(width 0.089408)
		(layer "In9.Cu")
		(net "SVID_DIO0_CPU0_R")
	)
	(segment
		(start 354.3554 -113.665)
		(end 353.6188 -114.4016)
		(width 0.089408)
		(layer "In9.Cu")
		(net "SVID_DIO0_CPU0_R")
	)
	(segment
		(start 329.896978 -106.4006)
		(end 327.19137 -103.694992)
		(width 0.089408)
		(layer "In11.Cu")
		(net "SVID_DIO0_CPU0_R")
	)
	(segment
		(start 316.5602 -101.7016)
		(end 316.48654 -101.62794)
		(width 0.089408)
		(layer "In11.Cu")
		(net "SVID_DIO0_CPU0_R")
	)
	(segment
		(start 334.47228 -106.4006)
		(end 329.896978 -106.4006)
		(width 0.089408)
		(layer "In11.Cu")
		(net "SVID_DIO0_CPU0_R")
	)
	(segment
		(start 321.565778 -101.7016)
		(end 316.5602 -101.7016)
		(width 0.089408)
		(layer "In11.Cu")
		(net "SVID_DIO0_CPU0_R")
	)
	(segment
		(start 327.19137 -103.694992)
		(end 323.55917 -103.694992)
		(width 0.089408)
		(layer "In11.Cu")
		(net "SVID_DIO0_CPU0_R")
	)
	(segment
		(start 323.55917 -103.694992)
		(end 321.565778 -101.7016)
		(width 0.089408)
		(layer "In11.Cu")
		(net "SVID_DIO0_CPU0_R")
	)
	(segment
		(start 267.948156 -89.765886)
		(end 267.376656 -89.765886)
		(width 0.10795)
		(layer "F.Cu")
		(net "SVID_DIO0_CPU0")
	)
	(via
		(at 267.376656 -89.765886)
		(size 0.508)
		(drill 0.254)
		(layers "F.Cu" "B.Cu")
		(net "SVID_DIO0_CPU0")
	)
	(via
		(at 230.281988 -88.487758)
		(size 0.6604)
		(drill 0.3302)
		(layers "F.Cu" "B.Cu")
		(net "SVID_DIO0_CPU0")
	)
	(segment
		(start 250.394724 -85.316568)
		(end 250.039124 -85.316568)
		(width 0.10795)
		(layer "B.Cu")
		(net "SVID_DIO0_CPU0")
	)
	(segment
		(start 258.61772 -89.250012)
		(end 258.190746 -88.823038)
		(width 0.10795)
		(layer "B.Cu")
		(net "SVID_DIO0_CPU0")
	)
	(segment
		(start 226.4156 -92.310966)
		(end 226.4156 -90.065606)
		(width 0.10795)
		(layer "B.Cu")
		(net "SVID_DIO0_CPU0")
	)
	(segment
		(start 251.192792 -85.8012)
		(end 250.879356 -85.8012)
		(width 0.10795)
		(layer "B.Cu")
		(net "SVID_DIO0_CPU0")
	)
	(segment
		(start 239.21593 -85.889592)
		(end 238.876586 -85.889592)
		(width 0.10795)
		(layer "B.Cu")
		(net "SVID_DIO0_CPU0")
	)
	(segment
		(start 205.74 -105.537)
		(end 206.248 -105.537)
		(width 0.10795)
		(layer "B.Cu")
		(net "SVID_DIO0_CPU0")
	)
	(segment
		(start 238.876586 -85.889592)
		(end 238.553244 -86.212934)
		(width 0.10795)
		(layer "B.Cu")
		(net "SVID_DIO0_CPU0")
	)
	(segment
		(start 257.314954 -89.23782)
		(end 256.85242 -89.23782)
		(width 0.10795)
		(layer "B.Cu")
		(net "SVID_DIO0_CPU0")
	)
	(segment
		(start 264.9474 -89.7636)
		(end 264.671556 -89.7636)
		(width 0.10795)
		(layer "B.Cu")
		(net "SVID_DIO0_CPU0")
	)
	(segment
		(start 265.736832 -90.2716)
		(end 265.4554 -90.2716)
		(width 0.10795)
		(layer "B.Cu")
		(net "SVID_DIO0_CPU0")
	)
	(segment
		(start 235.78185 -85.889592)
		(end 235.442506 -85.889592)
		(width 0.10795)
		(layer "B.Cu")
		(net "SVID_DIO0_CPU0")
	)
	(segment
		(start 263.47039 -88.8873)
		(end 263.238234 -88.8873)
		(width 0.10795)
		(layer "B.Cu")
		(net "SVID_DIO0_CPU0")
	)
	(segment
		(start 243.234464 -85.320378)
		(end 242.722908 -85.831934)
		(width 0.10795)
		(layer "B.Cu")
		(net "SVID_DIO0_CPU0")
	)
	(segment
		(start 252.127512 -85.269832)
		(end 251.72416 -85.269832)
		(width 0.10795)
		(layer "B.Cu")
		(net "SVID_DIO0_CPU0")
	)
	(segment
		(start 262.104632 -88.274398)
		(end 261.635748 -88.743282)
		(width 0.10795)
		(layer "B.Cu")
		(net "SVID_DIO0_CPU0")
	)
	(segment
		(start 247.3452 -85.7758)
		(end 246.9642 -85.3948)
		(width 0.10795)
		(layer "B.Cu")
		(net "SVID_DIO0_CPU0")
	)
	(segment
		(start 240.593626 -85.889592)
		(end 240.270284 -86.212934)
		(width 0.10795)
		(layer "B.Cu")
		(net "SVID_DIO0_CPU0")
	)
	(segment
		(start 267.376656 -89.765886)
		(end 267.31722 -89.70645)
		(width 0.10795)
		(layer "B.Cu")
		(net "SVID_DIO0_CPU0")
	)
	(segment
		(start 230.281988 -88.421718)
		(end 230.281988 -88.487758)
		(width 0.10795)
		(layer "B.Cu")
		(net "SVID_DIO0_CPU0")
	)
	(segment
		(start 262.509508 -88.274398)
		(end 262.104632 -88.274398)
		(width 0.10795)
		(layer "B.Cu")
		(net "SVID_DIO0_CPU0")
	)
	(segment
		(start 263.01827 -88.78316)
		(end 262.509508 -88.274398)
		(width 0.10795)
		(layer "B.Cu")
		(net "SVID_DIO0_CPU0")
	)
	(segment
		(start 261.140702 -88.743282)
		(end 260.57352 -89.310464)
		(width 0.10795)
		(layer "B.Cu")
		(net "SVID_DIO0_CPU0")
	)
	(segment
		(start 259.456936 -89.79662)
		(end 258.910328 -89.250012)
		(width 0.10795)
		(layer "B.Cu")
		(net "SVID_DIO0_CPU0")
	)
	(segment
		(start 235.119164 -86.212934)
		(end 234.697778 -86.212934)
		(width 0.10795)
		(layer "B.Cu")
		(net "SVID_DIO0_CPU0")
	)
	(segment
		(start 255.190244 -87.33663)
		(end 254.716788 -86.863174)
		(width 0.10795)
		(layer "B.Cu")
		(net "SVID_DIO0_CPU0")
	)
	(segment
		(start 234.093766 -86.816946)
		(end 233.673142 -86.816946)
		(width 0.10795)
		(layer "B.Cu")
		(net "SVID_DIO0_CPU0")
	)
	(segment
		(start 255.805178 -87.993982)
		(end 255.805178 -87.516208)
		(width 0.10795)
		(layer "B.Cu")
		(net "SVID_DIO0_CPU0")
	)
	(segment
		(start 266.301982 -89.70645)
		(end 265.736832 -90.2716)
		(width 0.10795)
		(layer "B.Cu")
		(net "SVID_DIO0_CPU0")
	)
	(segment
		(start 239.539272 -86.212934)
		(end 239.21593 -85.889592)
		(width 0.10795)
		(layer "B.Cu")
		(net "SVID_DIO0_CPU0")
	)
	(segment
		(start 241.808 -86.2838)
		(end 241.327178 -86.2838)
		(width 0.10795)
		(layer "B.Cu")
		(net "SVID_DIO0_CPU0")
	)
	(segment
		(start 247.777 -85.7758)
		(end 247.3452 -85.7758)
		(width 0.10795)
		(layer "B.Cu")
		(net "SVID_DIO0_CPU0")
	)
	(segment
		(start 256.02946 -88.82888)
		(end 255.66116 -88.46058)
		(width 0.10795)
		(layer "B.Cu")
		(net "SVID_DIO0_CPU0")
	)
	(segment
		(start 259.855462 -89.79662)
		(end 259.456936 -89.79662)
		(width 0.10795)
		(layer "B.Cu")
		(net "SVID_DIO0_CPU0")
	)
	(segment
		(start 255.66116 -88.46058)
		(end 255.66116 -88.138)
		(width 0.10795)
		(layer "B.Cu")
		(net "SVID_DIO0_CPU0")
	)
	(segment
		(start 258.190746 -88.823038)
		(end 257.729736 -88.823038)
		(width 0.10795)
		(layer "B.Cu")
		(net "SVID_DIO0_CPU0")
	)
	(segment
		(start 256.44348 -88.82888)
		(end 256.02946 -88.82888)
		(width 0.10795)
		(layer "B.Cu")
		(net "SVID_DIO0_CPU0")
	)
	(segment
		(start 263.134094 -88.78316)
		(end 263.01827 -88.78316)
		(width 0.10795)
		(layer "B.Cu")
		(net "SVID_DIO0_CPU0")
	)
	(segment
		(start 264.01014 -89.102184)
		(end 263.685274 -89.102184)
		(width 0.10795)
		(layer "B.Cu")
		(net "SVID_DIO0_CPU0")
	)
	(segment
		(start 252.837696 -85.7504)
		(end 252.60808 -85.7504)
		(width 0.10795)
		(layer "B.Cu")
		(net "SVID_DIO0_CPU0")
	)
	(segment
		(start 228.746812 -89.33307)
		(end 229.043484 -89.036398)
		(width 0.10795)
		(layer "B.Cu")
		(net "SVID_DIO0_CPU0")
	)
	(segment
		(start 241.327178 -86.2838)
		(end 240.93297 -85.889592)
		(width 0.10795)
		(layer "B.Cu")
		(net "SVID_DIO0_CPU0")
	)
	(segment
		(start 253.784862 -86.348062)
		(end 253.435358 -86.348062)
		(width 0.10795)
		(layer "B.Cu")
		(net "SVID_DIO0_CPU0")
	)
	(segment
		(start 226.415854 -92.31122)
		(end 226.4156 -92.310966)
		(width 0.10795)
		(layer "B.Cu")
		(net "SVID_DIO0_CPU0")
	)
	(segment
		(start 255.805178 -87.516208)
		(end 255.6256 -87.33663)
		(width 0.10795)
		(layer "B.Cu")
		(net "SVID_DIO0_CPU0")
	)
	(segment
		(start 206.248 -105.537)
		(end 207.058006 -104.726994)
		(width 0.10795)
		(layer "B.Cu")
		(net "SVID_DIO0_CPU0")
	)
	(segment
		(start 261.635748 -88.743282)
		(end 261.140702 -88.743282)
		(width 0.10795)
		(layer "B.Cu")
		(net "SVID_DIO0_CPU0")
	)
	(segment
		(start 232.741216 -86.384638)
		(end 232.308654 -86.8172)
		(width 0.10795)
		(layer "B.Cu")
		(net "SVID_DIO0_CPU0")
	)
	(segment
		(start 214.372952 -104.726994)
		(end 214.373206 -104.727248)
		(width 0.10795)
		(layer "B.Cu")
		(net "SVID_DIO0_CPU0")
	)
	(segment
		(start 233.673142 -86.816946)
		(end 233.240834 -86.384638)
		(width 0.10795)
		(layer "B.Cu")
		(net "SVID_DIO0_CPU0")
	)
	(segment
		(start 226.4156 -90.065606)
		(end 227.148136 -89.33307)
		(width 0.10795)
		(layer "B.Cu")
		(net "SVID_DIO0_CPU0")
	)
	(segment
		(start 234.697778 -86.212934)
		(end 234.093766 -86.816946)
		(width 0.10795)
		(layer "B.Cu")
		(net "SVID_DIO0_CPU0")
	)
	(segment
		(start 250.879356 -85.8012)
		(end 250.394724 -85.316568)
		(width 0.10795)
		(layer "B.Cu")
		(net "SVID_DIO0_CPU0")
	)
	(segment
		(start 235.442506 -85.889592)
		(end 235.119164 -86.212934)
		(width 0.10795)
		(layer "B.Cu")
		(net "SVID_DIO0_CPU0")
	)
	(segment
		(start 245.251478 -85.320378)
		(end 243.234464 -85.320378)
		(width 0.10795)
		(layer "B.Cu")
		(net "SVID_DIO0_CPU0")
	)
	(segment
		(start 237.159546 -85.889592)
		(end 236.836204 -86.212934)
		(width 0.10795)
		(layer "B.Cu")
		(net "SVID_DIO0_CPU0")
	)
	(segment
		(start 242.722908 -85.831934)
		(end 242.259866 -85.831934)
		(width 0.10795)
		(layer "B.Cu")
		(net "SVID_DIO0_CPU0")
	)
	(segment
		(start 264.671556 -89.7636)
		(end 264.01014 -89.102184)
		(width 0.10795)
		(layer "B.Cu")
		(net "SVID_DIO0_CPU0")
	)
	(segment
		(start 246.4816 -85.3948)
		(end 246.14378 -85.73262)
		(width 0.10795)
		(layer "B.Cu")
		(net "SVID_DIO0_CPU0")
	)
	(segment
		(start 226.415854 -92.6846)
		(end 226.415854 -92.31122)
		(width 0.10795)
		(layer "B.Cu")
		(net "SVID_DIO0_CPU0")
	)
	(segment
		(start 236.105192 -86.212934)
		(end 235.78185 -85.889592)
		(width 0.10795)
		(layer "B.Cu")
		(net "SVID_DIO0_CPU0")
	)
	(segment
		(start 255.6256 -87.33663)
		(end 255.190244 -87.33663)
		(width 0.10795)
		(layer "B.Cu")
		(net "SVID_DIO0_CPU0")
	)
	(segment
		(start 229.043484 -89.036398)
		(end 229.733348 -89.036398)
		(width 0.10795)
		(layer "B.Cu")
		(net "SVID_DIO0_CPU0")
	)
	(segment
		(start 250.039124 -85.316568)
		(end 249.605292 -85.7504)
		(width 0.10795)
		(layer "B.Cu")
		(net "SVID_DIO0_CPU0")
	)
	(segment
		(start 246.9642 -85.3948)
		(end 246.4816 -85.3948)
		(width 0.10795)
		(layer "B.Cu")
		(net "SVID_DIO0_CPU0")
	)
	(segment
		(start 254.299974 -86.863174)
		(end 253.784862 -86.348062)
		(width 0.10795)
		(layer "B.Cu")
		(net "SVID_DIO0_CPU0")
	)
	(segment
		(start 236.836204 -86.212934)
		(end 236.105192 -86.212934)
		(width 0.10795)
		(layer "B.Cu")
		(net "SVID_DIO0_CPU0")
	)
	(segment
		(start 257.729736 -88.823038)
		(end 257.314954 -89.23782)
		(width 0.10795)
		(layer "B.Cu")
		(net "SVID_DIO0_CPU0")
	)
	(segment
		(start 231.886506 -86.8172)
		(end 230.281988 -88.421718)
		(width 0.10795)
		(layer "B.Cu")
		(net "SVID_DIO0_CPU0")
	)
	(segment
		(start 249.605292 -85.7504)
		(end 249.160792 -85.7504)
		(width 0.10795)
		(layer "B.Cu")
		(net "SVID_DIO0_CPU0")
	)
	(segment
		(start 227.148136 -89.33307)
		(end 228.746812 -89.33307)
		(width 0.10795)
		(layer "B.Cu")
		(net "SVID_DIO0_CPU0")
	)
	(segment
		(start 248.285 -85.2678)
		(end 247.777 -85.7758)
		(width 0.10795)
		(layer "B.Cu")
		(net "SVID_DIO0_CPU0")
	)
	(segment
		(start 252.60808 -85.7504)
		(end 252.127512 -85.269832)
		(width 0.10795)
		(layer "B.Cu")
		(net "SVID_DIO0_CPU0")
	)
	(segment
		(start 251.72416 -85.269832)
		(end 251.192792 -85.8012)
		(width 0.10795)
		(layer "B.Cu")
		(net "SVID_DIO0_CPU0")
	)
	(segment
		(start 254.716788 -86.863174)
		(end 254.299974 -86.863174)
		(width 0.10795)
		(layer "B.Cu")
		(net "SVID_DIO0_CPU0")
	)
	(segment
		(start 207.058006 -104.726994)
		(end 214.372952 -104.726994)
		(width 0.10795)
		(layer "B.Cu")
		(net "SVID_DIO0_CPU0")
	)
	(segment
		(start 258.910328 -89.250012)
		(end 258.61772 -89.250012)
		(width 0.10795)
		(layer "B.Cu")
		(net "SVID_DIO0_CPU0")
	)
	(segment
		(start 255.66116 -88.138)
		(end 255.805178 -87.993982)
		(width 0.10795)
		(layer "B.Cu")
		(net "SVID_DIO0_CPU0")
	)
	(segment
		(start 229.733348 -89.036398)
		(end 230.281988 -88.487758)
		(width 0.10795)
		(layer "B.Cu")
		(net "SVID_DIO0_CPU0")
	)
	(segment
		(start 256.85242 -89.23782)
		(end 256.44348 -88.82888)
		(width 0.10795)
		(layer "B.Cu")
		(net "SVID_DIO0_CPU0")
	)
	(segment
		(start 240.93297 -85.889592)
		(end 240.593626 -85.889592)
		(width 0.10795)
		(layer "B.Cu")
		(net "SVID_DIO0_CPU0")
	)
	(segment
		(start 237.822232 -86.212934)
		(end 237.49889 -85.889592)
		(width 0.10795)
		(layer "B.Cu")
		(net "SVID_DIO0_CPU0")
	)
	(segment
		(start 267.31722 -89.70645)
		(end 266.301982 -89.70645)
		(width 0.10795)
		(layer "B.Cu")
		(net "SVID_DIO0_CPU0")
	)
	(segment
		(start 233.240834 -86.384638)
		(end 232.741216 -86.384638)
		(width 0.10795)
		(layer "B.Cu")
		(net "SVID_DIO0_CPU0")
	)
	(segment
		(start 245.66372 -85.73262)
		(end 245.251478 -85.320378)
		(width 0.10795)
		(layer "B.Cu")
		(net "SVID_DIO0_CPU0")
	)
	(segment
		(start 237.49889 -85.889592)
		(end 237.159546 -85.889592)
		(width 0.10795)
		(layer "B.Cu")
		(net "SVID_DIO0_CPU0")
	)
	(segment
		(start 248.678192 -85.2678)
		(end 248.285 -85.2678)
		(width 0.10795)
		(layer "B.Cu")
		(net "SVID_DIO0_CPU0")
	)
	(segment
		(start 249.160792 -85.7504)
		(end 248.678192 -85.2678)
		(width 0.10795)
		(layer "B.Cu")
		(net "SVID_DIO0_CPU0")
	)
	(segment
		(start 240.270284 -86.212934)
		(end 239.539272 -86.212934)
		(width 0.10795)
		(layer "B.Cu")
		(net "SVID_DIO0_CPU0")
	)
	(segment
		(start 242.259866 -85.831934)
		(end 241.808 -86.2838)
		(width 0.10795)
		(layer "B.Cu")
		(net "SVID_DIO0_CPU0")
	)
	(segment
		(start 238.553244 -86.212934)
		(end 237.822232 -86.212934)
		(width 0.10795)
		(layer "B.Cu")
		(net "SVID_DIO0_CPU0")
	)
	(segment
		(start 246.14378 -85.73262)
		(end 245.66372 -85.73262)
		(width 0.10795)
		(layer "B.Cu")
		(net "SVID_DIO0_CPU0")
	)
	(segment
		(start 253.435358 -86.348062)
		(end 252.837696 -85.7504)
		(width 0.10795)
		(layer "B.Cu")
		(net "SVID_DIO0_CPU0")
	)
	(segment
		(start 263.238234 -88.8873)
		(end 263.134094 -88.78316)
		(width 0.10795)
		(layer "B.Cu")
		(net "SVID_DIO0_CPU0")
	)
	(segment
		(start 260.57352 -89.310464)
		(end 260.341618 -89.310464)
		(width 0.10795)
		(layer "B.Cu")
		(net "SVID_DIO0_CPU0")
	)
	(segment
		(start 260.341618 -89.310464)
		(end 259.855462 -89.79662)
		(width 0.10795)
		(layer "B.Cu")
		(net "SVID_DIO0_CPU0")
	)
	(segment
		(start 265.4554 -90.2716)
		(end 264.9474 -89.7636)
		(width 0.10795)
		(layer "B.Cu")
		(net "SVID_DIO0_CPU0")
	)
	(segment
		(start 232.308654 -86.8172)
		(end 231.886506 -86.8172)
		(width 0.10795)
		(layer "B.Cu")
		(net "SVID_DIO0_CPU0")
	)
	(segment
		(start 263.685274 -89.102184)
		(end 263.47039 -88.8873)
		(width 0.10795)
		(layer "B.Cu")
		(net "SVID_DIO0_CPU0")
	)
	(segment
		(start 214.373206 -104.727248)
		(end 226.415854 -92.6846)
		(width 0.10795)
		(layer "B.Cu")
		(net "SVID_DIO0_CPU0")
	)
	(segment
		(start -1.118362 -128.3716)
		(end -1.5748 -128.3716)
		(width 0.10795)
		(layer "F.Cu")
		(net "SVID_CLK_PVDDQ_KLM")
	)
	(segment
		(start -0.3937 -128.165098)
		(end -0.91186 -128.165098)
		(width 0.10795)
		(layer "F.Cu")
		(net "SVID_CLK_PVDDQ_KLM")
	)
	(segment
		(start -1.8796 -128.3716)
		(end -1.5748 -128.3716)
		(width 0.10795)
		(layer "F.Cu")
		(net "SVID_CLK_PVDDQ_KLM")
	)
	(segment
		(start -2.1082 -128.6002)
		(end -1.8796 -128.3716)
		(width 0.10795)
		(layer "F.Cu")
		(net "SVID_CLK_PVDDQ_KLM")
	)
	(segment
		(start -0.91186 -128.165098)
		(end -1.118362 -128.3716)
		(width 0.10795)
		(layer "F.Cu")
		(net "SVID_CLK_PVDDQ_KLM")
	)
	(segment
		(start -2.667 -128.6002)
		(end -2.1082 -128.6002)
		(width 0.10795)
		(layer "F.Cu")
		(net "SVID_CLK_PVDDQ_KLM")
	)
	(via
		(at -1.5748 -128.3716)
		(size 0.508)
		(drill 0.254)
		(layers "F.Cu" "B.Cu")
		(net "SVID_CLK_PVDDQ_KLM")
	)
	(segment
		(start 11.130026 -3.530854)
		(end 11.130026 -3.502406)
		(width 0.10795)
		(layer "F.Cu")
		(net "SVID_CLK_PVDDQ_GHJ")
	)
	(segment
		(start 10.232898 -2.605278)
		(end 10.232898 -2.20345)
		(width 0.10795)
		(layer "F.Cu")
		(net "SVID_CLK_PVDDQ_GHJ")
	)
	(segment
		(start 11.130026 -3.502406)
		(end 10.232898 -2.605278)
		(width 0.10795)
		(layer "F.Cu")
		(net "SVID_CLK_PVDDQ_GHJ")
	)
	(segment
		(start 363.87024 -137.52957)
		(end 363.08157 -137.52957)
		(width 0.10795)
		(layer "F.Cu")
		(net "SVID_CLK_PVDDQ_DEF")
	)
	(segment
		(start 361.74934 -137.964672)
		(end 362.428536 -137.964672)
		(width 0.10795)
		(layer "F.Cu")
		(net "SVID_CLK_PVDDQ_DEF")
	)
	(segment
		(start 363.08157 -137.52957)
		(end 362.972604 -137.420604)
		(width 0.10795)
		(layer "F.Cu")
		(net "SVID_CLK_PVDDQ_DEF")
	)
	(segment
		(start 362.428536 -137.964672)
		(end 362.972604 -137.420604)
		(width 0.10795)
		(layer "F.Cu")
		(net "SVID_CLK_PVDDQ_DEF")
	)
	(via
		(at 362.972604 -137.420604)
		(size 0.508)
		(drill 0.254)
		(layers "F.Cu" "B.Cu")
		(net "SVID_CLK_PVDDQ_DEF")
	)
	(segment
		(start 339.41004 -17.272)
		(end 338.836 -17.272)
		(width 0.10795)
		(layer "F.Cu")
		(net "SVID_CLK_PVDDQ_ABC")
	)
	(segment
		(start 339.89264 -16.9672)
		(end 339.71484 -16.9672)
		(width 0.10795)
		(layer "F.Cu")
		(net "SVID_CLK_PVDDQ_ABC")
	)
	(segment
		(start 339.71484 -16.9672)
		(end 339.41004 -17.272)
		(width 0.10795)
		(layer "F.Cu")
		(net "SVID_CLK_PVDDQ_ABC")
	)
	(segment
		(start 342.2269 -15.566898)
		(end 341.455756 -15.566898)
		(width 0.10795)
		(layer "F.Cu")
		(net "SVID_CLK_PVDDQ_ABC")
	)
	(segment
		(start 340.055454 -16.9672)
		(end 339.89264 -16.9672)
		(width 0.10795)
		(layer "F.Cu")
		(net "SVID_CLK_PVDDQ_ABC")
	)
	(segment
		(start 341.455756 -15.566898)
		(end 340.055454 -16.9672)
		(width 0.10795)
		(layer "F.Cu")
		(net "SVID_CLK_PVDDQ_ABC")
	)
	(via
		(at 339.89264 -16.9672)
		(size 0.762)
		(drill 0.381)
		(layers "F.Cu" "B.Cu")
		(net "SVID_CLK_PVDDQ_ABC")
	)
	(segment
		(start 11.130026 -5.189474)
		(end 11.16584 -5.225288)
		(width 0.10795)
		(layer "F.Cu")
		(net "SVID_CLK1_CPU1_R")
	)
	(segment
		(start 189.052962 -110.47095)
		(end 188.745114 -110.47095)
		(width 0.10795)
		(layer "F.Cu")
		(net "SVID_CLK1_CPU1_R")
	)
	(segment
		(start -4.268216 -128.6002)
		(end -3.556 -128.6002)
		(width 0.10795)
		(layer "F.Cu")
		(net "SVID_CLK1_CPU1_R")
	)
	(segment
		(start 189.522354 -110.001558)
		(end 189.052962 -110.47095)
		(width 0.10795)
		(layer "F.Cu")
		(net "SVID_CLK1_CPU1_R")
	)
	(segment
		(start 11.130026 -4.419854)
		(end 11.130026 -5.189474)
		(width 0.10795)
		(layer "F.Cu")
		(net "SVID_CLK1_CPU1_R")
	)
	(segment
		(start -4.394708 -128.726692)
		(end -4.268216 -128.6002)
		(width 0.10795)
		(layer "F.Cu")
		(net "SVID_CLK1_CPU1_R")
	)
	(via
		(at 11.16584 -5.225288)
		(size 0.508)
		(drill 0.254)
		(layers "F.Cu" "B.Cu")
		(net "SVID_CLK1_CPU1_R")
	)
	(via
		(at 171.47032 -123.33478)
		(size 0.508)
		(drill 0.254)
		(layers "F.Cu" "B.Cu")
		(net "SVID_CLK1_CPU1_R")
	)
	(via
		(at 37.6682 -105.3084)
		(size 0.508)
		(drill 0.254)
		(layers "F.Cu" "B.Cu")
		(net "SVID_CLK1_CPU1_R")
	)
	(via
		(at 189.522354 -110.001558)
		(size 0.508)
		(drill 0.254)
		(layers "F.Cu" "B.Cu")
		(net "SVID_CLK1_CPU1_R")
	)
	(via
		(at -4.394708 -128.726692)
		(size 0.508)
		(drill 0.254)
		(layers "F.Cu" "B.Cu")
		(net "SVID_CLK1_CPU1_R")
	)
	(segment
		(start -4.394708 -128.726692)
		(end -4.268216 -128.6002)
		(width 0.10795)
		(layer "B.Cu")
		(net "SVID_CLK1_CPU1_R")
	)
	(segment
		(start 11.16584 -4.910582)
		(end 11.313668 -4.762754)
		(width 0.10795)
		(layer "B.Cu")
		(net "SVID_CLK1_CPU1_R")
	)
	(segment
		(start 11.313668 -4.762754)
		(end 11.313668 -4.210812)
		(width 0.10795)
		(layer "B.Cu")
		(net "SVID_CLK1_CPU1_R")
	)
	(segment
		(start 38.418516 -106.085386)
		(end 38.418516 -106.058716)
		(width 0.10795)
		(layer "B.Cu")
		(net "SVID_CLK1_CPU1_R")
	)
	(segment
		(start 38.418516 -106.058716)
		(end 37.6682 -105.3084)
		(width 0.10795)
		(layer "B.Cu")
		(net "SVID_CLK1_CPU1_R")
	)
	(segment
		(start -4.268216 -128.6002)
		(end -3.4036 -128.6002)
		(width 0.10795)
		(layer "B.Cu")
		(net "SVID_CLK1_CPU1_R")
	)
	(segment
		(start 11.16584 -5.225288)
		(end 11.16584 -4.910582)
		(width 0.10795)
		(layer "B.Cu")
		(net "SVID_CLK1_CPU1_R")
	)
	(segment
		(start -3.81 -128.141984)
		(end -4.394708 -128.726692)
		(width 0.089408)
		(layer "In2.Cu")
		(net "SVID_CLK1_CPU1_R")
	)
	(segment
		(start 10.35431 -90.396314)
		(end 10.35431 -103.766366)
		(width 0.089408)
		(layer "In2.Cu")
		(net "SVID_CLK1_CPU1_R")
	)
	(segment
		(start -4.016502 -86.077552)
		(end -1.788668 -88.305386)
		(width 0.089408)
		(layer "In2.Cu")
		(net "SVID_CLK1_CPU1_R")
	)
	(segment
		(start 4.95173 -114.309144)
		(end -4.180078 -123.440952)
		(width 0.089408)
		(layer "In2.Cu")
		(net "SVID_CLK1_CPU1_R")
	)
	(segment
		(start -2.225802 -62.286896)
		(end -2.225802 -77.1398)
		(width 0.089408)
		(layer "In2.Cu")
		(net "SVID_CLK1_CPU1_R")
	)
	(segment
		(start -0.392938 -42.029888)
		(end -4.348226 -45.985176)
		(width 0.089408)
		(layer "In2.Cu")
		(net "SVID_CLK1_CPU1_R")
	)
	(segment
		(start -4.180078 -124.529342)
		(end -3.81 -124.89942)
		(width 0.089408)
		(layer "In2.Cu")
		(net "SVID_CLK1_CPU1_R")
	)
	(segment
		(start 189.71006 -108.7501)
		(end 189.9666 -109.00664)
		(width 0.089408)
		(layer "In2.Cu")
		(net "SVID_CLK1_CPU1_R")
	)
	(segment
		(start 12.49045 -42.029888)
		(end -0.392938 -42.029888)
		(width 0.089408)
		(layer "In2.Cu")
		(net "SVID_CLK1_CPU1_R")
	)
	(segment
		(start 189.9666 -109.557312)
		(end 189.522354 -110.001558)
		(width 0.089408)
		(layer "In2.Cu")
		(net "SVID_CLK1_CPU1_R")
	)
	(segment
		(start -4.180078 -123.440952)
		(end -4.180078 -124.529342)
		(width 0.089408)
		(layer "In2.Cu")
		(net "SVID_CLK1_CPU1_R")
	)
	(segment
		(start -4.348226 -45.985176)
		(end -4.348226 -60.164472)
		(width 0.089408)
		(layer "In2.Cu")
		(net "SVID_CLK1_CPU1_R")
	)
	(segment
		(start 171.47032 -123.33478)
		(end 171.47032 -122.30608)
		(width 0.089408)
		(layer "In2.Cu")
		(net "SVID_CLK1_CPU1_R")
	)
	(segment
		(start 189.004448 -108.886752)
		(end 189.334394 -108.7501)
		(width 0.089408)
		(layer "In2.Cu")
		(net "SVID_CLK1_CPU1_R")
	)
	(segment
		(start 181.001416 -112.774984)
		(end 181.359048 -112.774984)
		(width 0.089408)
		(layer "In2.Cu")
		(net "SVID_CLK1_CPU1_R")
	)
	(segment
		(start 14.682216 -39.838122)
		(end 12.49045 -42.029888)
		(width 0.089408)
		(layer "In2.Cu")
		(net "SVID_CLK1_CPU1_R")
	)
	(segment
		(start 10.35431 -103.766366)
		(end 8.457438 -105.663238)
		(width 0.089408)
		(layer "In2.Cu")
		(net "SVID_CLK1_CPU1_R")
	)
	(segment
		(start -1.788668 -88.305386)
		(end 8.263382 -88.305386)
		(width 0.089408)
		(layer "In2.Cu")
		(net "SVID_CLK1_CPU1_R")
	)
	(segment
		(start 11.16584 -5.225288)
		(end 21.436584 -5.225288)
		(width 0.089408)
		(layer "In2.Cu")
		(net "SVID_CLK1_CPU1_R")
	)
	(segment
		(start 22.3012 -21.209)
		(end 21.284184 -22.226016)
		(width 0.089408)
		(layer "In2.Cu")
		(net "SVID_CLK1_CPU1_R")
	)
	(segment
		(start -3.81 -124.89942)
		(end -3.81 -128.141984)
		(width 0.089408)
		(layer "In2.Cu")
		(net "SVID_CLK1_CPU1_R")
	)
	(segment
		(start 6.77164 -114.309144)
		(end 4.95173 -114.309144)
		(width 0.089408)
		(layer "In2.Cu")
		(net "SVID_CLK1_CPU1_R")
	)
	(segment
		(start -4.016502 -78.9305)
		(end -4.016502 -86.077552)
		(width 0.089408)
		(layer "In2.Cu")
		(net "SVID_CLK1_CPU1_R")
	)
	(segment
		(start 14.682216 -23.087584)
		(end 14.682216 -39.838122)
		(width 0.089408)
		(layer "In2.Cu")
		(net "SVID_CLK1_CPU1_R")
	)
	(segment
		(start -2.225802 -77.1398)
		(end -4.016502 -78.9305)
		(width 0.089408)
		(layer "In2.Cu")
		(net "SVID_CLK1_CPU1_R")
	)
	(segment
		(start 189.334394 -108.7501)
		(end 189.71006 -108.7501)
		(width 0.089408)
		(layer "In2.Cu")
		(net "SVID_CLK1_CPU1_R")
	)
	(segment
		(start 21.436584 -5.225288)
		(end 22.3012 -6.089904)
		(width 0.089408)
		(layer "In2.Cu")
		(net "SVID_CLK1_CPU1_R")
	)
	(segment
		(start 189.9666 -109.00664)
		(end 189.9666 -109.557312)
		(width 0.089408)
		(layer "In2.Cu")
		(net "SVID_CLK1_CPU1_R")
	)
	(segment
		(start 8.263382 -88.305386)
		(end 10.35431 -90.396314)
		(width 0.089408)
		(layer "In2.Cu")
		(net "SVID_CLK1_CPU1_R")
	)
	(segment
		(start 181.359048 -112.774984)
		(end 181.359302 -112.775238)
		(width 0.089408)
		(layer "In2.Cu")
		(net "SVID_CLK1_CPU1_R")
	)
	(segment
		(start 171.47032 -122.30608)
		(end 181.001416 -112.774984)
		(width 0.089408)
		(layer "In2.Cu")
		(net "SVID_CLK1_CPU1_R")
	)
	(segment
		(start 185.115962 -112.775238)
		(end 189.004448 -108.886752)
		(width 0.089408)
		(layer "In2.Cu")
		(net "SVID_CLK1_CPU1_R")
	)
	(segment
		(start 15.543784 -22.226016)
		(end 14.682216 -23.087584)
		(width 0.089408)
		(layer "In2.Cu")
		(net "SVID_CLK1_CPU1_R")
	)
	(segment
		(start -4.348226 -60.164472)
		(end -2.225802 -62.286896)
		(width 0.089408)
		(layer "In2.Cu")
		(net "SVID_CLK1_CPU1_R")
	)
	(segment
		(start 8.457438 -105.663238)
		(end 8.457438 -112.623346)
		(width 0.089408)
		(layer "In2.Cu")
		(net "SVID_CLK1_CPU1_R")
	)
	(segment
		(start 22.3012 -6.089904)
		(end 22.3012 -21.209)
		(width 0.089408)
		(layer "In2.Cu")
		(net "SVID_CLK1_CPU1_R")
	)
	(segment
		(start 21.284184 -22.226016)
		(end 15.543784 -22.226016)
		(width 0.089408)
		(layer "In2.Cu")
		(net "SVID_CLK1_CPU1_R")
	)
	(segment
		(start 8.457438 -112.623346)
		(end 6.77164 -114.309144)
		(width 0.089408)
		(layer "In2.Cu")
		(net "SVID_CLK1_CPU1_R")
	)
	(segment
		(start 181.359302 -112.775238)
		(end 185.115962 -112.775238)
		(width 0.089408)
		(layer "In2.Cu")
		(net "SVID_CLK1_CPU1_R")
	)
	(segment
		(start 4.50469 -121.604532)
		(end 5.789676 -120.319546)
		(width 0.089408)
		(layer "In4.Cu")
		(net "SVID_CLK1_CPU1_R")
	)
	(segment
		(start 36.71443 -107.927394)
		(end 36.71443 -106.26217)
		(width 0.089408)
		(layer "In4.Cu")
		(net "SVID_CLK1_CPU1_R")
	)
	(segment
		(start 15.277592 -120.3198)
		(end 16.063976 -119.533416)
		(width 0.089408)
		(layer "In4.Cu")
		(net "SVID_CLK1_CPU1_R")
	)
	(segment
		(start 1.76022 -120.127522)
		(end 3.23723 -121.604532)
		(width 0.089408)
		(layer "In4.Cu")
		(net "SVID_CLK1_CPU1_R")
	)
	(segment
		(start -2.32918 -120.380506)
		(end -2.076196 -120.127522)
		(width 0.089408)
		(layer "In4.Cu")
		(net "SVID_CLK1_CPU1_R")
	)
	(segment
		(start 24.778462 -119.108982)
		(end 34.017204 -109.87024)
		(width 0.089408)
		(layer "In4.Cu")
		(net "SVID_CLK1_CPU1_R")
	)
	(segment
		(start -5.056632 -123.108212)
		(end -2.32918 -120.38076)
		(width 0.089408)
		(layer "In4.Cu")
		(net "SVID_CLK1_CPU1_R")
	)
	(segment
		(start -2.32918 -120.38076)
		(end -2.32918 -120.380506)
		(width 0.089408)
		(layer "In4.Cu")
		(net "SVID_CLK1_CPU1_R")
	)
	(segment
		(start 34.771584 -109.87024)
		(end 36.71443 -107.927394)
		(width 0.089408)
		(layer "In4.Cu")
		(net "SVID_CLK1_CPU1_R")
	)
	(segment
		(start 6.407658 -120.3198)
		(end 15.277592 -120.3198)
		(width 0.089408)
		(layer "In4.Cu")
		(net "SVID_CLK1_CPU1_R")
	)
	(segment
		(start -4.394708 -128.726692)
		(end -5.056632 -128.064768)
		(width 0.089408)
		(layer "In4.Cu")
		(net "SVID_CLK1_CPU1_R")
	)
	(segment
		(start 5.789676 -120.319546)
		(end 6.407404 -120.319546)
		(width 0.089408)
		(layer "In4.Cu")
		(net "SVID_CLK1_CPU1_R")
	)
	(segment
		(start 16.063976 -119.533416)
		(end 17.352772 -119.533416)
		(width 0.089408)
		(layer "In4.Cu")
		(net "SVID_CLK1_CPU1_R")
	)
	(segment
		(start 3.23723 -121.604532)
		(end 4.50469 -121.604532)
		(width 0.089408)
		(layer "In4.Cu")
		(net "SVID_CLK1_CPU1_R")
	)
	(segment
		(start 34.017204 -109.87024)
		(end 34.771584 -109.87024)
		(width 0.089408)
		(layer "In4.Cu")
		(net "SVID_CLK1_CPU1_R")
	)
	(segment
		(start 17.777206 -119.108982)
		(end 24.778462 -119.108982)
		(width 0.089408)
		(layer "In4.Cu")
		(net "SVID_CLK1_CPU1_R")
	)
	(segment
		(start -2.076196 -120.127522)
		(end 1.76022 -120.127522)
		(width 0.089408)
		(layer "In4.Cu")
		(net "SVID_CLK1_CPU1_R")
	)
	(segment
		(start -5.056632 -128.064768)
		(end -5.056632 -123.108212)
		(width 0.089408)
		(layer "In4.Cu")
		(net "SVID_CLK1_CPU1_R")
	)
	(segment
		(start 17.352772 -119.533416)
		(end 17.777206 -119.108982)
		(width 0.089408)
		(layer "In4.Cu")
		(net "SVID_CLK1_CPU1_R")
	)
	(segment
		(start 6.407404 -120.319546)
		(end 6.407658 -120.3198)
		(width 0.089408)
		(layer "In4.Cu")
		(net "SVID_CLK1_CPU1_R")
	)
	(segment
		(start 36.71443 -106.26217)
		(end 37.6682 -105.3084)
		(width 0.089408)
		(layer "In4.Cu")
		(net "SVID_CLK1_CPU1_R")
	)
	(segment
		(start 52.711096 -120.96242)
		(end 147.732242 -120.96242)
		(width 0.089408)
		(layer "In9.Cu")
		(net "SVID_CLK1_CPU1_R")
	)
	(segment
		(start 156.465016 -126.385574)
		(end 159.787082 -126.385574)
		(width 0.089408)
		(layer "In9.Cu")
		(net "SVID_CLK1_CPU1_R")
	)
	(segment
		(start 160.045654 -126.127002)
		(end 162.272472 -123.900184)
		(width 0.089408)
		(layer "In9.Cu")
		(net "SVID_CLK1_CPU1_R")
	)
	(segment
		(start 39.12235 -107.373674)
		(end 52.711096 -120.96242)
		(width 0.089408)
		(layer "In9.Cu")
		(net "SVID_CLK1_CPU1_R")
	)
	(segment
		(start 159.792416 -126.38024)
		(end 159.79267 -126.38024)
		(width 0.089408)
		(layer "In9.Cu")
		(net "SVID_CLK1_CPU1_R")
	)
	(segment
		(start 171.47032 -123.10237)
		(end 171.47032 -123.33478)
		(width 0.089408)
		(layer "In9.Cu")
		(net "SVID_CLK1_CPU1_R")
	)
	(segment
		(start 37.2618 -106.172)
		(end 37.582094 -106.492294)
		(width 0.089408)
		(layer "In9.Cu")
		(net "SVID_CLK1_CPU1_R")
	)
	(segment
		(start 162.272472 -123.900184)
		(end 162.272472 -122.828304)
		(width 0.089408)
		(layer "In9.Cu")
		(net "SVID_CLK1_CPU1_R")
	)
	(segment
		(start 38.870636 -107.373674)
		(end 39.12235 -107.373674)
		(width 0.089408)
		(layer "In9.Cu")
		(net "SVID_CLK1_CPU1_R")
	)
	(segment
		(start 37.989256 -106.492294)
		(end 38.870636 -107.373674)
		(width 0.089408)
		(layer "In9.Cu")
		(net "SVID_CLK1_CPU1_R")
	)
	(segment
		(start 159.79267 -126.38024)
		(end 160.045654 -126.127256)
		(width 0.089408)
		(layer "In9.Cu")
		(net "SVID_CLK1_CPU1_R")
	)
	(segment
		(start 152.644094 -125.874272)
		(end 155.953714 -125.874272)
		(width 0.089408)
		(layer "In9.Cu")
		(net "SVID_CLK1_CPU1_R")
	)
	(segment
		(start 160.045654 -126.127256)
		(end 160.045654 -126.127002)
		(width 0.089408)
		(layer "In9.Cu")
		(net "SVID_CLK1_CPU1_R")
	)
	(segment
		(start 37.465 -105.3084)
		(end 37.2618 -105.5116)
		(width 0.089408)
		(layer "In9.Cu")
		(net "SVID_CLK1_CPU1_R")
	)
	(segment
		(start 155.953714 -125.874272)
		(end 156.465016 -126.385574)
		(width 0.089408)
		(layer "In9.Cu")
		(net "SVID_CLK1_CPU1_R")
	)
	(segment
		(start 147.732242 -120.96242)
		(end 152.644094 -125.874272)
		(width 0.089408)
		(layer "In9.Cu")
		(net "SVID_CLK1_CPU1_R")
	)
	(segment
		(start 37.6682 -105.3084)
		(end 37.465 -105.3084)
		(width 0.089408)
		(layer "In9.Cu")
		(net "SVID_CLK1_CPU1_R")
	)
	(segment
		(start 159.787082 -126.385574)
		(end 159.792416 -126.38024)
		(width 0.089408)
		(layer "In9.Cu")
		(net "SVID_CLK1_CPU1_R")
	)
	(segment
		(start 164.410136 -120.69064)
		(end 169.05859 -120.69064)
		(width 0.089408)
		(layer "In9.Cu")
		(net "SVID_CLK1_CPU1_R")
	)
	(segment
		(start 37.582094 -106.492294)
		(end 37.989256 -106.492294)
		(width 0.089408)
		(layer "In9.Cu")
		(net "SVID_CLK1_CPU1_R")
	)
	(segment
		(start 37.2618 -105.5116)
		(end 37.2618 -106.172)
		(width 0.089408)
		(layer "In9.Cu")
		(net "SVID_CLK1_CPU1_R")
	)
	(segment
		(start 169.05859 -120.69064)
		(end 171.47032 -123.10237)
		(width 0.089408)
		(layer "In9.Cu")
		(net "SVID_CLK1_CPU1_R")
	)
	(segment
		(start 162.272472 -122.828304)
		(end 164.410136 -120.69064)
		(width 0.089408)
		(layer "In9.Cu")
		(net "SVID_CLK1_CPU1_R")
	)
	(segment
		(start 103.806244 -92.24264)
		(end 104.507538 -92.24264)
		(width 0.10795)
		(layer "F.Cu")
		(net "SVID_CLK1_CPU1")
	)
	(via
		(at 104.507538 -92.24264)
		(size 0.508)
		(drill 0.254)
		(layers "F.Cu" "B.Cu")
		(net "SVID_CLK1_CPU1")
	)
	(via
		(at 66.04 -94.234)
		(size 0.6604)
		(drill 0.3302)
		(layers "F.Cu" "B.Cu")
		(net "SVID_CLK1_CPU1")
	)
	(segment
		(start 74.411078 -93.642688)
		(end 74.734674 -93.319092)
		(width 0.10795)
		(layer "B.Cu")
		(net "SVID_CLK1_CPU1")
	)
	(segment
		(start 81.489296 -91.306904)
		(end 81.996788 -91.306904)
		(width 0.10795)
		(layer "B.Cu")
		(net "SVID_CLK1_CPU1")
	)
	(segment
		(start 94.009718 -91.313)
		(end 94.480126 -90.842592)
		(width 0.10795)
		(layer "B.Cu")
		(net "SVID_CLK1_CPU1")
	)
	(segment
		(start 73.384664 -93.21165)
		(end 73.815702 -93.642688)
		(width 0.10795)
		(layer "B.Cu")
		(net "SVID_CLK1_CPU1")
	)
	(segment
		(start 92.565474 -91.66098)
		(end 93.251274 -91.66098)
		(width 0.10795)
		(layer "B.Cu")
		(net "SVID_CLK1_CPU1")
	)
	(segment
		(start 79.02702 -92.823792)
		(end 79.389986 -92.823792)
		(width 0.10795)
		(layer "B.Cu")
		(net "SVID_CLK1_CPU1")
	)
	(segment
		(start 90.632026 -91.256612)
		(end 91.046046 -90.842592)
		(width 0.10795)
		(layer "B.Cu")
		(net "SVID_CLK1_CPU1")
	)
	(segment
		(start 94.821502 -90.842592)
		(end 95.25635 -91.27744)
		(width 0.10795)
		(layer "B.Cu")
		(net "SVID_CLK1_CPU1")
	)
	(segment
		(start 69.902324 -94.234)
		(end 70.322186 -93.814138)
		(width 0.10795)
		(layer "B.Cu")
		(net "SVID_CLK1_CPU1")
	)
	(segment
		(start 39.60114 -106.085386)
		(end 40.147494 -106.63174)
		(width 0.10795)
		(layer "B.Cu")
		(net "SVID_CLK1_CPU1")
	)
	(segment
		(start 63.372746 -94.234)
		(end 66.04 -94.234)
		(width 0.10795)
		(layer "B.Cu")
		(net "SVID_CLK1_CPU1")
	)
	(segment
		(start 88.43137 -91.259406)
		(end 88.912192 -91.259406)
		(width 0.10795)
		(layer "B.Cu")
		(net "SVID_CLK1_CPU1")
	)
	(segment
		(start 72.976232 -93.21165)
		(end 73.384664 -93.21165)
		(width 0.10795)
		(layer "B.Cu")
		(net "SVID_CLK1_CPU1")
	)
	(segment
		(start 81.996788 -91.306904)
		(end 82.4611 -90.842592)
		(width 0.10795)
		(layer "B.Cu")
		(net "SVID_CLK1_CPU1")
	)
	(segment
		(start 71.287386 -93.189044)
		(end 71.703438 -93.189044)
		(width 0.10795)
		(layer "B.Cu")
		(net "SVID_CLK1_CPU1")
	)
	(segment
		(start 85.013546 -91.277948)
		(end 85.459824 -91.277948)
		(width 0.10795)
		(layer "B.Cu")
		(net "SVID_CLK1_CPU1")
	)
	(segment
		(start 91.933522 -91.338908)
		(end 92.243402 -91.338908)
		(width 0.10795)
		(layer "B.Cu")
		(net "SVID_CLK1_CPU1")
	)
	(segment
		(start 89.329006 -90.842592)
		(end 89.707212 -90.842592)
		(width 0.10795)
		(layer "B.Cu")
		(net "SVID_CLK1_CPU1")
	)
	(segment
		(start 98.73361 -90.23223)
		(end 99.096068 -90.23223)
		(width 0.10795)
		(layer "B.Cu")
		(net "SVID_CLK1_CPU1")
	)
	(segment
		(start 100.8126 -90.2462)
		(end 101.236018 -89.822782)
		(width 0.10795)
		(layer "B.Cu")
		(net "SVID_CLK1_CPU1")
	)
	(segment
		(start 84.57819 -90.842592)
		(end 85.013546 -91.277948)
		(width 0.10795)
		(layer "B.Cu")
		(net "SVID_CLK1_CPU1")
	)
	(segment
		(start 77.310234 -93.642688)
		(end 77.812646 -93.642688)
		(width 0.10795)
		(layer "B.Cu")
		(net "SVID_CLK1_CPU1")
	)
	(segment
		(start 82.4611 -90.842592)
		(end 82.84083 -90.842592)
		(width 0.10795)
		(layer "B.Cu")
		(net "SVID_CLK1_CPU1")
	)
	(segment
		(start 86.304374 -90.842592)
		(end 86.730586 -91.268804)
		(width 0.10795)
		(layer "B.Cu")
		(net "SVID_CLK1_CPU1")
	)
	(segment
		(start 97.902014 -90.805)
		(end 98.16084 -90.805)
		(width 0.10795)
		(layer "B.Cu")
		(net "SVID_CLK1_CPU1")
	)
	(segment
		(start 79.88554 -92.328238)
		(end 80.05318 -92.328238)
		(width 0.10795)
		(layer "B.Cu")
		(net "SVID_CLK1_CPU1")
	)
	(segment
		(start 97.055686 -91.303348)
		(end 97.403666 -91.303348)
		(width 0.10795)
		(layer "B.Cu")
		(net "SVID_CLK1_CPU1")
	)
	(segment
		(start 96.59493 -90.842592)
		(end 97.055686 -91.303348)
		(width 0.10795)
		(layer "B.Cu")
		(net "SVID_CLK1_CPU1")
	)
	(segment
		(start 66.04 -94.234)
		(end 69.902324 -94.234)
		(width 0.10795)
		(layer "B.Cu")
		(net "SVID_CLK1_CPU1")
	)
	(segment
		(start 82.84083 -90.842592)
		(end 83.210146 -91.211908)
		(width 0.10795)
		(layer "B.Cu")
		(net "SVID_CLK1_CPU1")
	)
	(segment
		(start 76.986638 -93.319092)
		(end 77.310234 -93.642688)
		(width 0.10795)
		(layer "B.Cu")
		(net "SVID_CLK1_CPU1")
	)
	(segment
		(start 99.096068 -90.23223)
		(end 99.505516 -89.822782)
		(width 0.10795)
		(layer "B.Cu")
		(net "SVID_CLK1_CPU1")
	)
	(segment
		(start 100.008182 -89.822782)
		(end 100.4316 -90.2462)
		(width 0.10795)
		(layer "B.Cu")
		(net "SVID_CLK1_CPU1")
	)
	(segment
		(start 84.17814 -90.842592)
		(end 84.57819 -90.842592)
		(width 0.10795)
		(layer "B.Cu")
		(net "SVID_CLK1_CPU1")
	)
	(segment
		(start 85.89518 -90.842592)
		(end 86.304374 -90.842592)
		(width 0.10795)
		(layer "B.Cu")
		(net "SVID_CLK1_CPU1")
	)
	(segment
		(start 83.210146 -91.211908)
		(end 83.808824 -91.211908)
		(width 0.10795)
		(layer "B.Cu")
		(net "SVID_CLK1_CPU1")
	)
	(segment
		(start 80.05318 -92.328238)
		(end 80.687418 -91.694)
		(width 0.10795)
		(layer "B.Cu")
		(net "SVID_CLK1_CPU1")
	)
	(segment
		(start 77.812646 -93.642688)
		(end 78.3082 -93.147134)
		(width 0.10795)
		(layer "B.Cu")
		(net "SVID_CLK1_CPU1")
	)
	(segment
		(start 87.61222 -90.842592)
		(end 88.014556 -90.842592)
		(width 0.10795)
		(layer "B.Cu")
		(net "SVID_CLK1_CPU1")
	)
	(segment
		(start 99.505516 -89.822782)
		(end 100.008182 -89.822782)
		(width 0.10795)
		(layer "B.Cu")
		(net "SVID_CLK1_CPU1")
	)
	(segment
		(start 72.545194 -93.642688)
		(end 72.976232 -93.21165)
		(width 0.10795)
		(layer "B.Cu")
		(net "SVID_CLK1_CPU1")
	)
	(segment
		(start 93.599254 -91.313)
		(end 94.009718 -91.313)
		(width 0.10795)
		(layer "B.Cu")
		(net "SVID_CLK1_CPU1")
	)
	(segment
		(start 95.744284 -91.27744)
		(end 96.179132 -90.842592)
		(width 0.10795)
		(layer "B.Cu")
		(net "SVID_CLK1_CPU1")
	)
	(segment
		(start 83.808824 -91.211908)
		(end 84.17814 -90.842592)
		(width 0.10795)
		(layer "B.Cu")
		(net "SVID_CLK1_CPU1")
	)
	(segment
		(start 70.662292 -93.814138)
		(end 71.287386 -93.189044)
		(width 0.10795)
		(layer "B.Cu")
		(net "SVID_CLK1_CPU1")
	)
	(segment
		(start 40.147494 -106.63174)
		(end 50.975006 -106.63174)
		(width 0.10795)
		(layer "B.Cu")
		(net "SVID_CLK1_CPU1")
	)
	(segment
		(start 91.046046 -90.842592)
		(end 91.437206 -90.842592)
		(width 0.10795)
		(layer "B.Cu")
		(net "SVID_CLK1_CPU1")
	)
	(segment
		(start 95.25635 -91.27744)
		(end 95.744284 -91.27744)
		(width 0.10795)
		(layer "B.Cu")
		(net "SVID_CLK1_CPU1")
	)
	(segment
		(start 76.451714 -93.319092)
		(end 76.986638 -93.319092)
		(width 0.10795)
		(layer "B.Cu")
		(net "SVID_CLK1_CPU1")
	)
	(segment
		(start 85.459824 -91.277948)
		(end 85.89518 -90.842592)
		(width 0.10795)
		(layer "B.Cu")
		(net "SVID_CLK1_CPU1")
	)
	(segment
		(start 101.786182 -89.822782)
		(end 102.2604 -90.297)
		(width 0.10795)
		(layer "B.Cu")
		(net "SVID_CLK1_CPU1")
	)
	(segment
		(start 76.02982 -93.740986)
		(end 76.451714 -93.319092)
		(width 0.10795)
		(layer "B.Cu")
		(net "SVID_CLK1_CPU1")
	)
	(segment
		(start 101.236018 -89.822782)
		(end 101.786182 -89.822782)
		(width 0.10795)
		(layer "B.Cu")
		(net "SVID_CLK1_CPU1")
	)
	(segment
		(start 94.480126 -90.842592)
		(end 94.821502 -90.842592)
		(width 0.10795)
		(layer "B.Cu")
		(net "SVID_CLK1_CPU1")
	)
	(segment
		(start 102.561898 -90.297)
		(end 104.507538 -92.24264)
		(width 0.10795)
		(layer "B.Cu")
		(net "SVID_CLK1_CPU1")
	)
	(segment
		(start 86.730586 -91.268804)
		(end 87.186008 -91.268804)
		(width 0.10795)
		(layer "B.Cu")
		(net "SVID_CLK1_CPU1")
	)
	(segment
		(start 75.508612 -93.740986)
		(end 76.02982 -93.740986)
		(width 0.10795)
		(layer "B.Cu")
		(net "SVID_CLK1_CPU1")
	)
	(segment
		(start 78.703678 -93.147134)
		(end 79.02702 -92.823792)
		(width 0.10795)
		(layer "B.Cu")
		(net "SVID_CLK1_CPU1")
	)
	(segment
		(start 98.16084 -90.805)
		(end 98.73361 -90.23223)
		(width 0.10795)
		(layer "B.Cu")
		(net "SVID_CLK1_CPU1")
	)
	(segment
		(start 72.157082 -93.642688)
		(end 72.545194 -93.642688)
		(width 0.10795)
		(layer "B.Cu")
		(net "SVID_CLK1_CPU1")
	)
	(segment
		(start 80.687418 -91.694)
		(end 81.1022 -91.694)
		(width 0.10795)
		(layer "B.Cu")
		(net "SVID_CLK1_CPU1")
	)
	(segment
		(start 39.307516 -106.085386)
		(end 39.60114 -106.085386)
		(width 0.10795)
		(layer "B.Cu")
		(net "SVID_CLK1_CPU1")
	)
	(segment
		(start 88.014556 -90.842592)
		(end 88.43137 -91.259406)
		(width 0.10795)
		(layer "B.Cu")
		(net "SVID_CLK1_CPU1")
	)
	(segment
		(start 81.1022 -91.694)
		(end 81.489296 -91.306904)
		(width 0.10795)
		(layer "B.Cu")
		(net "SVID_CLK1_CPU1")
	)
	(segment
		(start 71.703438 -93.189044)
		(end 72.157082 -93.642688)
		(width 0.10795)
		(layer "B.Cu")
		(net "SVID_CLK1_CPU1")
	)
	(segment
		(start 100.4316 -90.2462)
		(end 100.8126 -90.2462)
		(width 0.10795)
		(layer "B.Cu")
		(net "SVID_CLK1_CPU1")
	)
	(segment
		(start 97.403666 -91.303348)
		(end 97.902014 -90.805)
		(width 0.10795)
		(layer "B.Cu")
		(net "SVID_CLK1_CPU1")
	)
	(segment
		(start 78.3082 -93.147134)
		(end 78.703678 -93.147134)
		(width 0.10795)
		(layer "B.Cu")
		(net "SVID_CLK1_CPU1")
	)
	(segment
		(start 75.086718 -93.319092)
		(end 75.508612 -93.740986)
		(width 0.10795)
		(layer "B.Cu")
		(net "SVID_CLK1_CPU1")
	)
	(segment
		(start 50.975006 -106.63174)
		(end 63.372746 -94.234)
		(width 0.10795)
		(layer "B.Cu")
		(net "SVID_CLK1_CPU1")
	)
	(segment
		(start 88.912192 -91.259406)
		(end 89.329006 -90.842592)
		(width 0.10795)
		(layer "B.Cu")
		(net "SVID_CLK1_CPU1")
	)
	(segment
		(start 73.815702 -93.642688)
		(end 74.411078 -93.642688)
		(width 0.10795)
		(layer "B.Cu")
		(net "SVID_CLK1_CPU1")
	)
	(segment
		(start 89.707212 -90.842592)
		(end 90.121232 -91.256612)
		(width 0.10795)
		(layer "B.Cu")
		(net "SVID_CLK1_CPU1")
	)
	(segment
		(start 102.2604 -90.297)
		(end 102.561898 -90.297)
		(width 0.10795)
		(layer "B.Cu")
		(net "SVID_CLK1_CPU1")
	)
	(segment
		(start 74.734674 -93.319092)
		(end 75.086718 -93.319092)
		(width 0.10795)
		(layer "B.Cu")
		(net "SVID_CLK1_CPU1")
	)
	(segment
		(start 90.121232 -91.256612)
		(end 90.632026 -91.256612)
		(width 0.10795)
		(layer "B.Cu")
		(net "SVID_CLK1_CPU1")
	)
	(segment
		(start 70.322186 -93.814138)
		(end 70.662292 -93.814138)
		(width 0.10795)
		(layer "B.Cu")
		(net "SVID_CLK1_CPU1")
	)
	(segment
		(start 87.186008 -91.268804)
		(end 87.61222 -90.842592)
		(width 0.10795)
		(layer "B.Cu")
		(net "SVID_CLK1_CPU1")
	)
	(segment
		(start 93.251274 -91.66098)
		(end 93.599254 -91.313)
		(width 0.10795)
		(layer "B.Cu")
		(net "SVID_CLK1_CPU1")
	)
	(segment
		(start 79.389986 -92.823792)
		(end 79.88554 -92.328238)
		(width 0.10795)
		(layer "B.Cu")
		(net "SVID_CLK1_CPU1")
	)
	(segment
		(start 91.437206 -90.842592)
		(end 91.933522 -91.338908)
		(width 0.10795)
		(layer "B.Cu")
		(net "SVID_CLK1_CPU1")
	)
	(segment
		(start 92.243402 -91.338908)
		(end 92.565474 -91.66098)
		(width 0.10795)
		(layer "B.Cu")
		(net "SVID_CLK1_CPU1")
	)
	(segment
		(start 96.179132 -90.842592)
		(end 96.59493 -90.842592)
		(width 0.10795)
		(layer "B.Cu")
		(net "SVID_CLK1_CPU1")
	)
	(segment
		(start 326.002396 -127.481838)
		(end 324.569582 -128.914652)
		(width 0.10795)
		(layer "F.Cu")
		(net "SVID_CLK1_CPU0_R")
	)
	(segment
		(start 324.569582 -128.914652)
		(end 324.282816 -128.914652)
		(width 0.10795)
		(layer "F.Cu")
		(net "SVID_CLK1_CPU0_R")
	)
	(segment
		(start 347.14688 -76.02728)
		(end 360.467656 -76.02728)
		(width 0.10795)
		(layer "F.Cu")
		(net "SVID_CLK1_CPU0_R")
	)
	(segment
		(start 361.3912 -93.2434)
		(end 361.3912 -106.248708)
		(width 0.10795)
		(layer "F.Cu")
		(net "SVID_CLK1_CPU0_R")
	)
	(segment
		(start 353.691952 -109.855)
		(end 354.3554 -109.855)
		(width 0.10795)
		(layer "F.Cu")
		(net "SVID_CLK1_CPU0_R")
	)
	(segment
		(start 358.177592 -88.378792)
		(end 358.177592 -88.720676)
		(width 0.10795)
		(layer "F.Cu")
		(net "SVID_CLK1_CPU0_R")
	)
	(segment
		(start 360.467656 -76.02728)
		(end 361.098084 -76.657708)
		(width 0.10795)
		(layer "F.Cu")
		(net "SVID_CLK1_CPU0_R")
	)
	(segment
		(start 358.177592 -88.720676)
		(end 358.177846 -88.72093)
		(width 0.10795)
		(layer "F.Cu")
		(net "SVID_CLK1_CPU0_R")
	)
	(segment
		(start 358.177846 -88.72093)
		(end 358.177846 -90.423238)
		(width 0.10795)
		(layer "F.Cu")
		(net "SVID_CLK1_CPU0_R")
	)
	(segment
		(start 358.1781 -90.448892)
		(end 359.042208 -91.313)
		(width 0.10795)
		(layer "F.Cu")
		(net "SVID_CLK1_CPU0_R")
	)
	(segment
		(start 354.5205 -107.7087)
		(end 353.2378 -108.9914)
		(width 0.10795)
		(layer "F.Cu")
		(net "SVID_CLK1_CPU0_R")
	)
	(segment
		(start 343.5096 -72.39)
		(end 347.14688 -76.02728)
		(width 0.10795)
		(layer "F.Cu")
		(net "SVID_CLK1_CPU0_R")
	)
	(segment
		(start 364.75924 -137.52957)
		(end 365.06277 -137.52957)
		(width 0.10795)
		(layer "F.Cu")
		(net "SVID_CLK1_CPU0_R")
	)
	(segment
		(start 361.098084 -85.4583)
		(end 358.177592 -88.378792)
		(width 0.10795)
		(layer "F.Cu")
		(net "SVID_CLK1_CPU0_R")
	)
	(segment
		(start 361.3912 -106.248708)
		(end 359.931208 -107.7087)
		(width 0.10795)
		(layer "F.Cu")
		(net "SVID_CLK1_CPU0_R")
	)
	(segment
		(start 359.042208 -91.313)
		(end 359.4608 -91.313)
		(width 0.10795)
		(layer "F.Cu")
		(net "SVID_CLK1_CPU0_R")
	)
	(segment
		(start 358.177846 -90.423238)
		(end 358.1781 -90.423492)
		(width 0.10795)
		(layer "F.Cu")
		(net "SVID_CLK1_CPU0_R")
	)
	(segment
		(start 358.1781 -90.423492)
		(end 358.1781 -90.448892)
		(width 0.10795)
		(layer "F.Cu")
		(net "SVID_CLK1_CPU0_R")
	)
	(segment
		(start 353.2378 -108.9914)
		(end 353.2378 -109.400848)
		(width 0.10795)
		(layer "F.Cu")
		(net "SVID_CLK1_CPU0_R")
	)
	(segment
		(start 365.06277 -137.52957)
		(end 365.264192 -137.328148)
		(width 0.10795)
		(layer "F.Cu")
		(net "SVID_CLK1_CPU0_R")
	)
	(segment
		(start 337.366356 -17.979644)
		(end 337.947 -17.399)
		(width 0.10795)
		(layer "F.Cu")
		(net "SVID_CLK1_CPU0_R")
	)
	(segment
		(start 365.264192 -137.328148)
		(end 365.264192 -136.945624)
		(width 0.10795)
		(layer "F.Cu")
		(net "SVID_CLK1_CPU0_R")
	)
	(segment
		(start 354.3554 -109.855)
		(end 353.724972 -110.47095)
		(width 0.10795)
		(layer "F.Cu")
		(net "SVID_CLK1_CPU0_R")
	)
	(segment
		(start 353.2378 -109.400848)
		(end 353.691952 -109.855)
		(width 0.10795)
		(layer "F.Cu")
		(net "SVID_CLK1_CPU0_R")
	)
	(segment
		(start 361.098084 -76.657708)
		(end 361.098084 -85.4583)
		(width 0.10795)
		(layer "F.Cu")
		(net "SVID_CLK1_CPU0_R")
	)
	(segment
		(start 337.176618 -17.979644)
		(end 337.366356 -17.979644)
		(width 0.10795)
		(layer "F.Cu")
		(net "SVID_CLK1_CPU0_R")
	)
	(segment
		(start 337.947 -17.399)
		(end 337.947 -17.272)
		(width 0.10795)
		(layer "F.Cu")
		(net "SVID_CLK1_CPU0_R")
	)
	(segment
		(start 359.931208 -107.7087)
		(end 354.5205 -107.7087)
		(width 0.10795)
		(layer "F.Cu")
		(net "SVID_CLK1_CPU0_R")
	)
	(segment
		(start 365.264192 -136.945624)
		(end 365.714788 -136.495028)
		(width 0.10795)
		(layer "F.Cu")
		(net "SVID_CLK1_CPU0_R")
	)
	(segment
		(start 327.09358 -127.481838)
		(end 326.002396 -127.481838)
		(width 0.10795)
		(layer "F.Cu")
		(net "SVID_CLK1_CPU0_R")
	)
	(segment
		(start 359.4608 -91.313)
		(end 361.3912 -93.2434)
		(width 0.10795)
		(layer "F.Cu")
		(net "SVID_CLK1_CPU0_R")
	)
	(via
		(at 337.176618 -17.979644)
		(size 0.508)
		(drill 0.254)
		(layers "F.Cu" "B.Cu")
		(net "SVID_CLK1_CPU0_R")
	)
	(via
		(at 343.5096 -72.39)
		(size 0.508)
		(drill 0.254)
		(layers "F.Cu" "B.Cu")
		(net "SVID_CLK1_CPU0_R")
	)
	(via
		(at 354.3554 -109.855)
		(size 0.508)
		(drill 0.254)
		(layers "F.Cu" "B.Cu")
		(net "SVID_CLK1_CPU0_R")
	)
	(via
		(at 327.09358 -127.481838)
		(size 0.508)
		(drill 0.254)
		(layers "F.Cu" "B.Cu")
		(net "SVID_CLK1_CPU0_R")
	)
	(via
		(at 365.714788 -136.495028)
		(size 0.508)
		(drill 0.254)
		(layers "F.Cu" "B.Cu")
		(net "SVID_CLK1_CPU0_R")
	)
	(via
		(at 344.659204 -53.1114)
		(size 0.508)
		(drill 0.254)
		(layers "F.Cu" "B.Cu")
		(net "SVID_CLK1_CPU0_R")
	)
	(segment
		(start 352.1964 -113.1951)
		(end 351.4979 -113.1951)
		(width 0.10795)
		(layer "B.Cu")
		(net "SVID_CLK1_CPU0_R")
	)
	(segment
		(start 365.714788 -136.267952)
		(end 365.714788 -136.495028)
		(width 0.10795)
		(layer "B.Cu")
		(net "SVID_CLK1_CPU0_R")
	)
	(segment
		(start 344.21064 -126.459488)
		(end 346.160852 -128.4097)
		(width 0.10795)
		(layer "B.Cu")
		(net "SVID_CLK1_CPU0_R")
	)
	(segment
		(start 365.132366 -137.07745)
		(end 365.132366 -137.156444)
		(width 0.10795)
		(layer "B.Cu")
		(net "SVID_CLK1_CPU0_R")
	)
	(segment
		(start 346.160852 -128.4097)
		(end 356.47122 -128.4097)
		(width 0.10795)
		(layer "B.Cu")
		(net "SVID_CLK1_CPU0_R")
	)
	(segment
		(start 354.34905 -111.077756)
		(end 353.134676 -112.29213)
		(width 0.10795)
		(layer "B.Cu")
		(net "SVID_CLK1_CPU0_R")
	)
	(segment
		(start 354.34905 -111.04245)
		(end 354.34905 -111.077756)
		(width 0.10795)
		(layer "B.Cu")
		(net "SVID_CLK1_CPU0_R")
	)
	(segment
		(start 365.132366 -137.156444)
		(end 364.75924 -137.52957)
		(width 0.10795)
		(layer "B.Cu")
		(net "SVID_CLK1_CPU0_R")
	)
	(segment
		(start 364.258606 -130.9751)
		(end 366.45088 -133.167374)
		(width 0.10795)
		(layer "B.Cu")
		(net "SVID_CLK1_CPU0_R")
	)
	(segment
		(start 348.315788 -118.0211)
		(end 348.315534 -118.020846)
		(width 0.10795)
		(layer "B.Cu")
		(net "SVID_CLK1_CPU0_R")
	)
	(segment
		(start 354.3554 -111.0361)
		(end 354.34905 -111.04245)
		(width 0.10795)
		(layer "B.Cu")
		(net "SVID_CLK1_CPU0_R")
	)
	(segment
		(start 354.3554 -109.855)
		(end 354.3554 -111.0361)
		(width 0.10795)
		(layer "B.Cu")
		(net "SVID_CLK1_CPU0_R")
	)
	(segment
		(start 337.176618 -18.05559)
		(end 337.176618 -17.979644)
		(width 0.10795)
		(layer "B.Cu")
		(net "SVID_CLK1_CPU0_R")
	)
	(segment
		(start 351.4979 -113.1951)
		(end 351.282 -113.411)
		(width 0.10795)
		(layer "B.Cu")
		(net "SVID_CLK1_CPU0_R")
	)
	(segment
		(start 349.78086 -118.0211)
		(end 348.315788 -118.0211)
		(width 0.10795)
		(layer "B.Cu")
		(net "SVID_CLK1_CPU0_R")
	)
	(segment
		(start 353.09937 -112.29213)
		(end 352.1964 -113.1951)
		(width 0.10795)
		(layer "B.Cu")
		(net "SVID_CLK1_CPU0_R")
	)
	(segment
		(start 353.134676 -112.29213)
		(end 353.09937 -112.29213)
		(width 0.10795)
		(layer "B.Cu")
		(net "SVID_CLK1_CPU0_R")
	)
	(segment
		(start 356.47122 -128.4097)
		(end 359.03662 -130.9751)
		(width 0.10795)
		(layer "B.Cu")
		(net "SVID_CLK1_CPU0_R")
	)
	(segment
		(start 344.21064 -121.59996)
		(end 344.21064 -126.459488)
		(width 0.10795)
		(layer "B.Cu")
		(net "SVID_CLK1_CPU0_R")
	)
	(segment
		(start 347.789754 -118.020846)
		(end 344.21064 -121.59996)
		(width 0.10795)
		(layer "B.Cu")
		(net "SVID_CLK1_CPU0_R")
	)
	(segment
		(start 337.8454 -18.16354)
		(end 337.284568 -18.16354)
		(width 0.10795)
		(layer "B.Cu")
		(net "SVID_CLK1_CPU0_R")
	)
	(segment
		(start 365.714788 -136.495028)
		(end 365.132366 -137.07745)
		(width 0.10795)
		(layer "B.Cu")
		(net "SVID_CLK1_CPU0_R")
	)
	(segment
		(start 366.45088 -133.167374)
		(end 366.45088 -135.53186)
		(width 0.10795)
		(layer "B.Cu")
		(net "SVID_CLK1_CPU0_R")
	)
	(segment
		(start 366.45088 -135.53186)
		(end 365.714788 -136.267952)
		(width 0.10795)
		(layer "B.Cu")
		(net "SVID_CLK1_CPU0_R")
	)
	(segment
		(start 359.03662 -130.9751)
		(end 364.258606 -130.9751)
		(width 0.10795)
		(layer "B.Cu")
		(net "SVID_CLK1_CPU0_R")
	)
	(segment
		(start 351.282 -113.411)
		(end 351.282 -116.51996)
		(width 0.10795)
		(layer "B.Cu")
		(net "SVID_CLK1_CPU0_R")
	)
	(segment
		(start 348.315534 -118.020846)
		(end 347.789754 -118.020846)
		(width 0.10795)
		(layer "B.Cu")
		(net "SVID_CLK1_CPU0_R")
	)
	(segment
		(start 337.284568 -18.16354)
		(end 337.176618 -18.05559)
		(width 0.10795)
		(layer "B.Cu")
		(net "SVID_CLK1_CPU0_R")
	)
	(segment
		(start 351.282 -116.51996)
		(end 349.78086 -118.0211)
		(width 0.10795)
		(layer "B.Cu")
		(net "SVID_CLK1_CPU0_R")
	)
	(segment
		(start 338.66201 -44.37888)
		(end 338.66201 -44.200064)
		(width 0.089408)
		(layer "In2.Cu")
		(net "SVID_CLK1_CPU0_R")
	)
	(segment
		(start 339.203792 -43.753024)
		(end 338.751418 -43.753024)
		(width 0.089408)
		(layer "In2.Cu")
		(net "SVID_CLK1_CPU0_R")
	)
	(segment
		(start 345.348814 -128.102868)
		(end 344.991436 -127.74549)
		(width 0.089408)
		(layer "In2.Cu")
		(net "SVID_CLK1_CPU0_R")
	)
	(segment
		(start 335.56448 -128.651)
		(end 331.6097 -128.651)
		(width 0.089408)
		(layer "In2.Cu")
		(net "SVID_CLK1_CPU0_R")
	)
	(segment
		(start 328.967592 -127.813816)
		(end 328.740008 -127.586232)
		(width 0.089408)
		(layer "In2.Cu")
		(net "SVID_CLK1_CPU0_R")
	)
	(segment
		(start 339.2932 -44.736512)
		(end 339.2932 -44.557696)
		(width 0.089408)
		(layer "In2.Cu")
		(net "SVID_CLK1_CPU0_R")
	)
	(segment
		(start 336.911696 -127.303784)
		(end 335.56448 -128.651)
		(width 0.089408)
		(layer "In2.Cu")
		(net "SVID_CLK1_CPU0_R")
	)
	(segment
		(start 339.2932 -44.557696)
		(end 339.203792 -44.468288)
		(width 0.089408)
		(layer "In2.Cu")
		(net "SVID_CLK1_CPU0_R")
	)
	(segment
		(start 348.752668 -128.486408)
		(end 348.369128 -128.102868)
		(width 0.089408)
		(layer "In2.Cu")
		(net "SVID_CLK1_CPU0_R")
	)
	(segment
		(start 338.66201 -45.094144)
		(end 338.66201 -44.915328)
		(width 0.089408)
		(layer "In2.Cu")
		(net "SVID_CLK1_CPU0_R")
	)
	(segment
		(start 339.203792 -44.468288)
		(end 338.751418 -44.468288)
		(width 0.089408)
		(layer "In2.Cu")
		(net "SVID_CLK1_CPU0_R")
	)
	(segment
		(start 362.415328 -130.462528)
		(end 360.2228 -128.27)
		(width 0.089408)
		(layer "In2.Cu")
		(net "SVID_CLK1_CPU0_R")
	)
	(segment
		(start 330.772516 -127.813816)
		(end 328.967592 -127.813816)
		(width 0.089408)
		(layer "In2.Cu")
		(net "SVID_CLK1_CPU0_R")
	)
	(segment
		(start 344.991436 -127.74549)
		(end 340.164674 -127.74549)
		(width 0.089408)
		(layer "In2.Cu")
		(net "SVID_CLK1_CPU0_R")
	)
	(segment
		(start 328.492612 -29.331412)
		(end 328.492612 -26.011632)
		(width 0.089408)
		(layer "In2.Cu")
		(net "SVID_CLK1_CPU0_R")
	)
	(segment
		(start 365.506762 -135.328406)
		(end 364.108746 -133.93039)
		(width 0.089408)
		(layer "In2.Cu")
		(net "SVID_CLK1_CPU0_R")
	)
	(segment
		(start 339.2932 -43.842432)
		(end 339.203792 -43.753024)
		(width 0.089408)
		(layer "In2.Cu")
		(net "SVID_CLK1_CPU0_R")
	)
	(segment
		(start 338.751418 -44.468288)
		(end 338.66201 -44.37888)
		(width 0.089408)
		(layer "In2.Cu")
		(net "SVID_CLK1_CPU0_R")
	)
	(segment
		(start 338.66201 -43.663616)
		(end 338.66201 -36.946586)
		(width 0.089408)
		(layer "In2.Cu")
		(net "SVID_CLK1_CPU0_R")
	)
	(segment
		(start 338.751418 -44.110656)
		(end 339.203792 -44.110656)
		(width 0.089408)
		(layer "In2.Cu")
		(net "SVID_CLK1_CPU0_R")
	)
	(segment
		(start 363.869224 -133.93039)
		(end 362.415328 -132.476494)
		(width 0.089408)
		(layer "In2.Cu")
		(net "SVID_CLK1_CPU0_R")
	)
	(segment
		(start 364.108746 -133.93039)
		(end 363.869224 -133.93039)
		(width 0.089408)
		(layer "In2.Cu")
		(net "SVID_CLK1_CPU0_R")
	)
	(segment
		(start 331.6097 -128.651)
		(end 330.772516 -127.813816)
		(width 0.089408)
		(layer "In2.Cu")
		(net "SVID_CLK1_CPU0_R")
	)
	(segment
		(start 334.275684 -19.91868)
		(end 334.483964 -19.91868)
		(width 0.089408)
		(layer "In2.Cu")
		(net "SVID_CLK1_CPU0_R")
	)
	(segment
		(start 354.728272 -128.486408)
		(end 348.752668 -128.486408)
		(width 0.089408)
		(layer "In2.Cu")
		(net "SVID_CLK1_CPU0_R")
	)
	(segment
		(start 344.659204 -53.1114)
		(end 344.659204 -51.955192)
		(width 0.089408)
		(layer "In2.Cu")
		(net "SVID_CLK1_CPU0_R")
	)
	(segment
		(start 338.751418 -45.183552)
		(end 338.66201 -45.094144)
		(width 0.089408)
		(layer "In2.Cu")
		(net "SVID_CLK1_CPU0_R")
	)
	(segment
		(start 339.203792 -45.541184)
		(end 339.2932 -45.451776)
		(width 0.089408)
		(layer "In2.Cu")
		(net "SVID_CLK1_CPU0_R")
	)
	(segment
		(start 338.66201 -36.946586)
		(end 337.441286 -35.725862)
		(width 0.089408)
		(layer "In2.Cu")
		(net "SVID_CLK1_CPU0_R")
	)
	(segment
		(start 362.415328 -132.476494)
		(end 362.415328 -130.462528)
		(width 0.089408)
		(layer "In2.Cu")
		(net "SVID_CLK1_CPU0_R")
	)
	(segment
		(start 339.722968 -127.303784)
		(end 336.911696 -127.303784)
		(width 0.089408)
		(layer "In2.Cu")
		(net "SVID_CLK1_CPU0_R")
	)
	(segment
		(start 328.740008 -127.586232)
		(end 327.385426 -127.586232)
		(width 0.089408)
		(layer "In2.Cu")
		(net "SVID_CLK1_CPU0_R")
	)
	(segment
		(start 339.203792 -45.183552)
		(end 338.751418 -45.183552)
		(width 0.089408)
		(layer "In2.Cu")
		(net "SVID_CLK1_CPU0_R")
	)
	(segment
		(start 339.2932 -44.021248)
		(end 339.2932 -43.842432)
		(width 0.089408)
		(layer "In2.Cu")
		(net "SVID_CLK1_CPU0_R")
	)
	(segment
		(start 337.706208 -19.172428)
		(end 337.706208 -18.509234)
		(width 0.089408)
		(layer "In2.Cu")
		(net "SVID_CLK1_CPU0_R")
	)
	(segment
		(start 333.258922 -20.935442)
		(end 334.275684 -19.91868)
		(width 0.089408)
		(layer "In2.Cu")
		(net "SVID_CLK1_CPU0_R")
	)
	(segment
		(start 339.203792 -44.110656)
		(end 339.2932 -44.021248)
		(width 0.089408)
		(layer "In2.Cu")
		(net "SVID_CLK1_CPU0_R")
	)
	(segment
		(start 338.751418 -43.753024)
		(end 338.66201 -43.663616)
		(width 0.089408)
		(layer "In2.Cu")
		(net "SVID_CLK1_CPU0_R")
	)
	(segment
		(start 338.66201 -45.957998)
		(end 338.66201 -45.630592)
		(width 0.089408)
		(layer "In2.Cu")
		(net "SVID_CLK1_CPU0_R")
	)
	(segment
		(start 338.66201 -45.630592)
		(end 338.751418 -45.541184)
		(width 0.089408)
		(layer "In2.Cu")
		(net "SVID_CLK1_CPU0_R")
	)
	(segment
		(start 337.373976 -19.50466)
		(end 337.706208 -19.172428)
		(width 0.089408)
		(layer "In2.Cu")
		(net "SVID_CLK1_CPU0_R")
	)
	(segment
		(start 337.441286 -35.725862)
		(end 337.051142 -35.725862)
		(width 0.089408)
		(layer "In2.Cu")
		(net "SVID_CLK1_CPU0_R")
	)
	(segment
		(start 329.2348 -30.0736)
		(end 328.492612 -29.331412)
		(width 0.089408)
		(layer "In2.Cu")
		(net "SVID_CLK1_CPU0_R")
	)
	(segment
		(start 344.659204 -51.955192)
		(end 338.66201 -45.957998)
		(width 0.089408)
		(layer "In2.Cu")
		(net "SVID_CLK1_CPU0_R")
	)
	(segment
		(start 354.94468 -128.27)
		(end 354.728272 -128.486408)
		(width 0.089408)
		(layer "In2.Cu")
		(net "SVID_CLK1_CPU0_R")
	)
	(segment
		(start 328.492612 -26.011632)
		(end 333.258922 -21.245322)
		(width 0.089408)
		(layer "In2.Cu")
		(net "SVID_CLK1_CPU0_R")
	)
	(segment
		(start 348.369128 -128.102868)
		(end 345.348814 -128.102868)
		(width 0.089408)
		(layer "In2.Cu")
		(net "SVID_CLK1_CPU0_R")
	)
	(segment
		(start 339.203792 -44.82592)
		(end 339.2932 -44.736512)
		(width 0.089408)
		(layer "In2.Cu")
		(net "SVID_CLK1_CPU0_R")
	)
	(segment
		(start 334.483964 -19.91868)
		(end 334.897984 -19.50466)
		(width 0.089408)
		(layer "In2.Cu")
		(net "SVID_CLK1_CPU0_R")
	)
	(segment
		(start 338.66201 -44.200064)
		(end 338.751418 -44.110656)
		(width 0.089408)
		(layer "In2.Cu")
		(net "SVID_CLK1_CPU0_R")
	)
	(segment
		(start 337.706208 -18.509234)
		(end 337.176618 -17.979644)
		(width 0.089408)
		(layer "In2.Cu")
		(net "SVID_CLK1_CPU0_R")
	)
	(segment
		(start 327.385426 -127.586232)
		(end 327.281032 -127.481838)
		(width 0.089408)
		(layer "In2.Cu")
		(net "SVID_CLK1_CPU0_R")
	)
	(segment
		(start 329.2348 -33.136586)
		(end 329.2348 -30.0736)
		(width 0.089408)
		(layer "In2.Cu")
		(net "SVID_CLK1_CPU0_R")
	)
	(segment
		(start 338.751418 -45.541184)
		(end 339.203792 -45.541184)
		(width 0.089408)
		(layer "In2.Cu")
		(net "SVID_CLK1_CPU0_R")
	)
	(segment
		(start 337.051142 -35.725862)
		(end 336.895948 -35.881056)
		(width 0.089408)
		(layer "In2.Cu")
		(net "SVID_CLK1_CPU0_R")
	)
	(segment
		(start 339.2932 -45.27296)
		(end 339.203792 -45.183552)
		(width 0.089408)
		(layer "In2.Cu")
		(net "SVID_CLK1_CPU0_R")
	)
	(segment
		(start 334.897984 -19.50466)
		(end 337.373976 -19.50466)
		(width 0.089408)
		(layer "In2.Cu")
		(net "SVID_CLK1_CPU0_R")
	)
	(segment
		(start 338.66201 -44.915328)
		(end 338.751418 -44.82592)
		(width 0.089408)
		(layer "In2.Cu")
		(net "SVID_CLK1_CPU0_R")
	)
	(segment
		(start 338.751418 -44.82592)
		(end 339.203792 -44.82592)
		(width 0.089408)
		(layer "In2.Cu")
		(net "SVID_CLK1_CPU0_R")
	)
	(segment
		(start 333.258922 -21.245322)
		(end 333.258922 -20.935442)
		(width 0.089408)
		(layer "In2.Cu")
		(net "SVID_CLK1_CPU0_R")
	)
	(segment
		(start 360.2228 -128.27)
		(end 354.94468 -128.27)
		(width 0.089408)
		(layer "In2.Cu")
		(net "SVID_CLK1_CPU0_R")
	)
	(segment
		(start 336.895948 -35.881056)
		(end 331.97927 -35.881056)
		(width 0.089408)
		(layer "In2.Cu")
		(net "SVID_CLK1_CPU0_R")
	)
	(segment
		(start 331.97927 -35.881056)
		(end 329.2348 -33.136586)
		(width 0.089408)
		(layer "In2.Cu")
		(net "SVID_CLK1_CPU0_R")
	)
	(segment
		(start 327.281032 -127.481838)
		(end 327.09358 -127.481838)
		(width 0.089408)
		(layer "In2.Cu")
		(net "SVID_CLK1_CPU0_R")
	)
	(segment
		(start 365.506762 -136.287002)
		(end 365.506762 -135.328406)
		(width 0.089408)
		(layer "In2.Cu")
		(net "SVID_CLK1_CPU0_R")
	)
	(segment
		(start 365.714788 -136.495028)
		(end 365.506762 -136.287002)
		(width 0.089408)
		(layer "In2.Cu")
		(net "SVID_CLK1_CPU0_R")
	)
	(segment
		(start 339.2932 -45.451776)
		(end 339.2932 -45.27296)
		(width 0.089408)
		(layer "In2.Cu")
		(net "SVID_CLK1_CPU0_R")
	)
	(segment
		(start 340.164674 -127.74549)
		(end 339.722968 -127.303784)
		(width 0.089408)
		(layer "In2.Cu")
		(net "SVID_CLK1_CPU0_R")
	)
	(segment
		(start 345.698826 -70.073774)
		(end 343.5096 -72.263)
		(width 0.089408)
		(layer "In9.Cu")
		(net "SVID_CLK1_CPU0_R")
	)
	(segment
		(start 344.659204 -61.716666)
		(end 345.698826 -62.756288)
		(width 0.089408)
		(layer "In9.Cu")
		(net "SVID_CLK1_CPU0_R")
	)
	(segment
		(start 345.698826 -62.756288)
		(end 345.698826 -70.073774)
		(width 0.089408)
		(layer "In9.Cu")
		(net "SVID_CLK1_CPU0_R")
	)
	(segment
		(start 343.5096 -72.263)
		(end 343.5096 -72.39)
		(width 0.089408)
		(layer "In9.Cu")
		(net "SVID_CLK1_CPU0_R")
	)
	(segment
		(start 344.659204 -53.1114)
		(end 344.659204 -61.716666)
		(width 0.089408)
		(layer "In9.Cu")
		(net "SVID_CLK1_CPU0_R")
	)
	(segment
		(start 323.06133 -126.823724)
		(end 323.422264 -126.823724)
		(width 0.10795)
		(layer "F.Cu")
		(net "SVID_CLK1_CPU0")
	)
	(segment
		(start 322.86067 -126.623064)
		(end 323.06133 -126.823724)
		(width 0.10795)
		(layer "F.Cu")
		(net "SVID_CLK1_CPU0")
	)
	(segment
		(start 323.422264 -126.823724)
		(end 324.282816 -127.684276)
		(width 0.10795)
		(layer "F.Cu")
		(net "SVID_CLK1_CPU0")
	)
	(segment
		(start 324.282816 -127.684276)
		(end 324.282816 -128.025652)
		(width 0.10795)
		(layer "F.Cu")
		(net "SVID_CLK1_CPU0")
	)
	(segment
		(start 268.806676 -92.24264)
		(end 269.50797 -92.24264)
		(width 0.10795)
		(layer "F.Cu")
		(net "SVID_CLK1_CPU0")
	)
	(via
		(at 269.50797 -92.24264)
		(size 0.508)
		(drill 0.254)
		(layers "F.Cu" "B.Cu")
		(net "SVID_CLK1_CPU0")
	)
	(via
		(at 322.86067 -126.623064)
		(size 0.508)
		(drill 0.254)
		(layers "F.Cu" "B.Cu")
		(net "SVID_CLK1_CPU0")
	)
	(segment
		(start 273.218402 -91.167458)
		(end 273.14652 -91.23934)
		(width 0.0889)
		(layer "In4.Cu")
		(net "SVID_CLK1_CPU0")
	)
	(segment
		(start 292.8112 -99.36861)
		(end 292.42639 -98.9838)
		(width 0.089408)
		(layer "In4.Cu")
		(net "SVID_CLK1_CPU0")
	)
	(segment
		(start 295.969944 -102.879144)
		(end 294.149018 -102.879144)
		(width 0.089408)
		(layer "In4.Cu")
		(net "SVID_CLK1_CPU0")
	)
	(segment
		(start 273.14652 -91.23934)
		(end 272.79346 -91.5924)
		(width 0.089408)
		(layer "In4.Cu")
		(net "SVID_CLK1_CPU0")
	)
	(segment
		(start 320.302128 -125.777752)
		(end 320.42862 -125.65126)
		(width 0.089408)
		(layer "In4.Cu")
		(net "SVID_CLK1_CPU0")
	)
	(segment
		(start 275.535644 -91.167204)
		(end 274.810474 -91.167204)
		(width 0.089408)
		(layer "In4.Cu")
		(net "SVID_CLK1_CPU0")
	)
	(segment
		(start 285.197296 -90.97391)
		(end 284.895798 -90.672412)
		(width 0.0889)
		(layer "In4.Cu")
		(net "SVID_CLK1_CPU0")
	)
	(segment
		(start 277.466044 -91.549982)
		(end 277.083266 -91.167204)
		(width 0.089408)
		(layer "In4.Cu")
		(net "SVID_CLK1_CPU0")
	)
	(segment
		(start 280.029158 -90.97391)
		(end 279.72766 -90.672412)
		(width 0.0889)
		(layer "In4.Cu")
		(net "SVID_CLK1_CPU0")
	)
	(segment
		(start 276.52726 -91.167204)
		(end 276.223476 -91.470988)
		(width 0.089408)
		(layer "In4.Cu")
		(net "SVID_CLK1_CPU0")
	)
	(segment
		(start 273.79676 -91.23934)
		(end 273.724878 -91.167458)
		(width 0.0889)
		(layer "In4.Cu")
		(net "SVID_CLK1_CPU0")
	)
	(segment
		(start 289.132518 -90.97518)
		(end 288.769552 -90.97518)
		(width 0.0889)
		(layer "In4.Cu")
		(net "SVID_CLK1_CPU0")
	)
	(segment
		(start 276.223476 -91.470988)
		(end 275.839428 -91.470988)
		(width 0.0889)
		(layer "In4.Cu")
		(net "SVID_CLK1_CPU0")
	)
	(segment
		(start 316.283086 -121.469912)
		(end 300.298866 -105.485692)
		(width 0.089408)
		(layer "In4.Cu")
		(net "SVID_CLK1_CPU0")
	)
	(segment
		(start 288.055558 -90.671142)
		(end 287.561274 -90.176858)
		(width 0.0889)
		(layer "In4.Cu")
		(net "SVID_CLK1_CPU0")
	)
	(segment
		(start 321.633088 -126.498858)
		(end 321.162172 -126.969774)
		(width 0.089408)
		(layer "In4.Cu")
		(net "SVID_CLK1_CPU0")
	)
	(segment
		(start 291.110924 -93.215968)
		(end 291.110924 -92.451682)
		(width 0.0889)
		(layer "In4.Cu")
		(net "SVID_CLK1_CPU0")
	)
	(segment
		(start 278.505666 -91.031314)
		(end 278.269192 -91.267788)
		(width 0.0889)
		(layer "In4.Cu")
		(net "SVID_CLK1_CPU0")
	)
	(segment
		(start 278.851868 -91.031314)
		(end 278.505666 -91.031314)
		(width 0.0889)
		(layer "In4.Cu")
		(net "SVID_CLK1_CPU0")
	)
	(segment
		(start 321.162172 -126.969774)
		(end 320.681604 -126.969774)
		(width 0.089408)
		(layer "In4.Cu")
		(net "SVID_CLK1_CPU0")
	)
	(segment
		(start 281.48534 -90.672412)
		(end 280.923746 -90.672412)
		(width 0.0889)
		(layer "In4.Cu")
		(net "SVID_CLK1_CPU0")
	)
	(segment
		(start 282.677616 -90.672412)
		(end 282.376118 -90.97391)
		(width 0.0889)
		(layer "In4.Cu")
		(net "SVID_CLK1_CPU0")
	)
	(segment
		(start 300.298866 -105.485692)
		(end 298.576492 -105.485692)
		(width 0.089408)
		(layer "In4.Cu")
		(net "SVID_CLK1_CPU0")
	)
	(segment
		(start 291.95014 -98.645218)
		(end 291.95014 -94.00032)
		(width 0.089408)
		(layer "In4.Cu")
		(net "SVID_CLK1_CPU0")
	)
	(segment
		(start 272.79346 -91.5924)
		(end 271.018 -91.5924)
		(width 0.089408)
		(layer "In4.Cu")
		(net "SVID_CLK1_CPU0")
	)
	(segment
		(start 291.95014 -93.918532)
		(end 291.483542 -93.451934)
		(width 0.0889)
		(layer "In4.Cu")
		(net "SVID_CLK1_CPU0")
	)
	(segment
		(start 292.8112 -101.541326)
		(end 292.8112 -99.36861)
		(width 0.089408)
		(layer "In4.Cu")
		(net "SVID_CLK1_CPU0")
	)
	(segment
		(start 277.083266 -91.167204)
		(end 276.52726 -91.167204)
		(width 0.089408)
		(layer "In4.Cu")
		(net "SVID_CLK1_CPU0")
	)
	(segment
		(start 284.016704 -90.97391)
		(end 283.475938 -90.97391)
		(width 0.0889)
		(layer "In4.Cu")
		(net "SVID_CLK1_CPU0")
	)
	(segment
		(start 283.17444 -90.672412)
		(end 282.677616 -90.672412)
		(width 0.0889)
		(layer "In4.Cu")
		(net "SVID_CLK1_CPU0")
	)
	(segment
		(start 271.018 -91.5924)
		(end 270.36776 -92.24264)
		(width 0.089408)
		(layer "In4.Cu")
		(net "SVID_CLK1_CPU0")
	)
	(segment
		(start 284.895798 -90.672412)
		(end 284.318202 -90.672412)
		(width 0.0889)
		(layer "In4.Cu")
		(net "SVID_CLK1_CPU0")
	)
	(segment
		(start 282.376118 -90.97391)
		(end 281.786838 -90.97391)
		(width 0.0889)
		(layer "In4.Cu")
		(net "SVID_CLK1_CPU0")
	)
	(segment
		(start 291.110924 -92.451682)
		(end 290.81603 -92.156788)
		(width 0.0889)
		(layer "In4.Cu")
		(net "SVID_CLK1_CPU0")
	)
	(segment
		(start 279.21077 -90.672412)
		(end 278.851868 -91.031314)
		(width 0.0889)
		(layer "In4.Cu")
		(net "SVID_CLK1_CPU0")
	)
	(segment
		(start 319.268348 -121.469912)
		(end 316.283086 -121.469912)
		(width 0.089408)
		(layer "In4.Cu")
		(net "SVID_CLK1_CPU0")
	)
	(segment
		(start 322.86067 -126.623064)
		(end 322.736464 -126.498858)
		(width 0.089408)
		(layer "In4.Cu")
		(net "SVID_CLK1_CPU0")
	)
	(segment
		(start 322.736464 -126.498858)
		(end 321.633088 -126.498858)
		(width 0.089408)
		(layer "In4.Cu")
		(net "SVID_CLK1_CPU0")
	)
	(segment
		(start 280.622248 -90.97391)
		(end 280.029158 -90.97391)
		(width 0.0889)
		(layer "In4.Cu")
		(net "SVID_CLK1_CPU0")
	)
	(segment
		(start 289.628072 -91.470734)
		(end 289.132518 -90.97518)
		(width 0.0889)
		(layer "In4.Cu")
		(net "SVID_CLK1_CPU0")
	)
	(segment
		(start 320.42862 -122.630184)
		(end 319.268348 -121.469912)
		(width 0.089408)
		(layer "In4.Cu")
		(net "SVID_CLK1_CPU0")
	)
	(segment
		(start 291.34689 -93.451934)
		(end 291.110924 -93.215968)
		(width 0.0889)
		(layer "In4.Cu")
		(net "SVID_CLK1_CPU0")
	)
	(segment
		(start 274.028408 -91.470988)
		(end 273.79676 -91.23934)
		(width 0.089408)
		(layer "In4.Cu")
		(net "SVID_CLK1_CPU0")
	)
	(segment
		(start 287.561274 -90.176858)
		(end 286.99587 -90.176858)
		(width 0.0889)
		(layer "In4.Cu")
		(net "SVID_CLK1_CPU0")
	)
	(segment
		(start 292.42639 -98.9838)
		(end 292.288722 -98.9838)
		(width 0.089408)
		(layer "In4.Cu")
		(net "SVID_CLK1_CPU0")
	)
	(segment
		(start 320.681604 -126.969774)
		(end 320.302128 -126.590298)
		(width 0.089408)
		(layer "In4.Cu")
		(net "SVID_CLK1_CPU0")
	)
	(segment
		(start 273.724878 -91.167458)
		(end 273.218402 -91.167458)
		(width 0.0889)
		(layer "In4.Cu")
		(net "SVID_CLK1_CPU0")
	)
	(segment
		(start 292.288722 -98.9838)
		(end 291.95014 -98.645218)
		(width 0.089408)
		(layer "In4.Cu")
		(net "SVID_CLK1_CPU0")
	)
	(segment
		(start 274.50669 -91.470988)
		(end 274.028408 -91.470988)
		(width 0.0889)
		(layer "In4.Cu")
		(net "SVID_CLK1_CPU0")
	)
	(segment
		(start 286.114744 -90.591894)
		(end 285.732728 -90.97391)
		(width 0.0889)
		(layer "In4.Cu")
		(net "SVID_CLK1_CPU0")
	)
	(segment
		(start 280.923746 -90.672412)
		(end 280.622248 -90.97391)
		(width 0.0889)
		(layer "In4.Cu")
		(net "SVID_CLK1_CPU0")
	)
	(segment
		(start 290.558728 -92.156788)
		(end 289.872674 -91.470734)
		(width 0.0889)
		(layer "In4.Cu")
		(net "SVID_CLK1_CPU0")
	)
	(segment
		(start 290.81603 -92.156788)
		(end 290.558728 -92.156788)
		(width 0.0889)
		(layer "In4.Cu")
		(net "SVID_CLK1_CPU0")
	)
	(segment
		(start 285.732728 -90.97391)
		(end 285.197296 -90.97391)
		(width 0.0889)
		(layer "In4.Cu")
		(net "SVID_CLK1_CPU0")
	)
	(segment
		(start 320.302128 -126.590298)
		(end 320.302128 -125.777752)
		(width 0.089408)
		(layer "In4.Cu")
		(net "SVID_CLK1_CPU0")
	)
	(segment
		(start 298.576492 -105.485692)
		(end 295.969944 -102.879144)
		(width 0.089408)
		(layer "In4.Cu")
		(net "SVID_CLK1_CPU0")
	)
	(segment
		(start 294.149018 -102.879144)
		(end 292.8112 -101.541326)
		(width 0.089408)
		(layer "In4.Cu")
		(net "SVID_CLK1_CPU0")
	)
	(segment
		(start 286.99587 -90.176858)
		(end 286.580834 -90.591894)
		(width 0.0889)
		(layer "In4.Cu")
		(net "SVID_CLK1_CPU0")
	)
	(segment
		(start 283.475938 -90.97391)
		(end 283.17444 -90.672412)
		(width 0.0889)
		(layer "In4.Cu")
		(net "SVID_CLK1_CPU0")
	)
	(segment
		(start 320.42862 -125.65126)
		(end 320.42862 -122.630184)
		(width 0.089408)
		(layer "In4.Cu")
		(net "SVID_CLK1_CPU0")
	)
	(segment
		(start 274.810474 -91.167204)
		(end 274.50669 -91.470988)
		(width 0.089408)
		(layer "In4.Cu")
		(net "SVID_CLK1_CPU0")
	)
	(segment
		(start 279.72766 -90.672412)
		(end 279.21077 -90.672412)
		(width 0.0889)
		(layer "In4.Cu")
		(net "SVID_CLK1_CPU0")
	)
	(segment
		(start 288.465514 -90.671142)
		(end 288.055558 -90.671142)
		(width 0.0889)
		(layer "In4.Cu")
		(net "SVID_CLK1_CPU0")
	)
	(segment
		(start 278.269192 -91.267788)
		(end 277.986998 -91.549982)
		(width 0.089408)
		(layer "In4.Cu")
		(net "SVID_CLK1_CPU0")
	)
	(segment
		(start 281.786838 -90.97391)
		(end 281.48534 -90.672412)
		(width 0.0889)
		(layer "In4.Cu")
		(net "SVID_CLK1_CPU0")
	)
	(segment
		(start 284.318202 -90.672412)
		(end 284.016704 -90.97391)
		(width 0.0889)
		(layer "In4.Cu")
		(net "SVID_CLK1_CPU0")
	)
	(segment
		(start 275.839428 -91.470988)
		(end 275.535644 -91.167204)
		(width 0.089408)
		(layer "In4.Cu")
		(net "SVID_CLK1_CPU0")
	)
	(segment
		(start 291.95014 -94.00032)
		(end 291.95014 -93.918532)
		(width 0.0889)
		(layer "In4.Cu")
		(net "SVID_CLK1_CPU0")
	)
	(segment
		(start 289.872674 -91.470734)
		(end 289.628072 -91.470734)
		(width 0.0889)
		(layer "In4.Cu")
		(net "SVID_CLK1_CPU0")
	)
	(segment
		(start 288.769552 -90.97518)
		(end 288.465514 -90.671142)
		(width 0.0889)
		(layer "In4.Cu")
		(net "SVID_CLK1_CPU0")
	)
	(segment
		(start 277.986998 -91.549982)
		(end 277.466044 -91.549982)
		(width 0.0889)
		(layer "In4.Cu")
		(net "SVID_CLK1_CPU0")
	)
	(segment
		(start 270.36776 -92.24264)
		(end 269.50797 -92.24264)
		(width 0.089408)
		(layer "In4.Cu")
		(net "SVID_CLK1_CPU0")
	)
	(segment
		(start 291.483542 -93.451934)
		(end 291.34689 -93.451934)
		(width 0.0889)
		(layer "In4.Cu")
		(net "SVID_CLK1_CPU0")
	)
	(segment
		(start 286.580834 -90.591894)
		(end 286.114744 -90.591894)
		(width 0.0889)
		(layer "In4.Cu")
		(net "SVID_CLK1_CPU0")
	)
	(segment
		(start 183.843168 -124.243592)
		(end 184.674002 -123.412758)
		(width 0.10795)
		(layer "F.Cu")
		(net "SVID_CLK0_CPU1_R")
	)
	(segment
		(start 188.745114 -115.953032)
		(end 188.745114 -115.55095)
		(width 0.10795)
		(layer "F.Cu")
		(net "SVID_CLK0_CPU1_R")
	)
	(segment
		(start 184.674002 -123.412758)
		(end 184.674002 -120.024144)
		(width 0.10795)
		(layer "F.Cu")
		(net "SVID_CLK0_CPU1_R")
	)
	(segment
		(start 17.526 -86.8172)
		(end 17.526 -86.0552)
		(width 0.10795)
		(layer "F.Cu")
		(net "SVID_CLK0_CPU1_R")
	)
	(segment
		(start 157.5816 -117.85346)
		(end 157.5816 -117.938042)
		(width 0.10795)
		(layer "F.Cu")
		(net "SVID_CLK0_CPU1_R")
	)
	(segment
		(start 163.449 -69.814948)
		(end 163.449 -69.816472)
		(width 0.10795)
		(layer "F.Cu")
		(net "SVID_CLK0_CPU1_R")
	)
	(segment
		(start 156.858208 -118.045992)
		(end 156.5402 -118.364)
		(width 0.10795)
		(layer "F.Cu")
		(net "SVID_CLK0_CPU1_R")
	)
	(segment
		(start 184.674002 -120.024144)
		(end 188.745114 -115.953032)
		(width 0.10795)
		(layer "F.Cu")
		(net "SVID_CLK0_CPU1_R")
	)
	(segment
		(start 164.084 -69.088)
		(end 164.084 -69.179948)
		(width 0.10795)
		(layer "F.Cu")
		(net "SVID_CLK0_CPU1_R")
	)
	(segment
		(start 157.47365 -118.045992)
		(end 156.858208 -118.045992)
		(width 0.10795)
		(layer "F.Cu")
		(net "SVID_CLK0_CPU1_R")
	)
	(segment
		(start 157.5816 -117.938042)
		(end 157.47365 -118.045992)
		(width 0.10795)
		(layer "F.Cu")
		(net "SVID_CLK0_CPU1_R")
	)
	(segment
		(start 164.084 -69.179948)
		(end 163.449 -69.814948)
		(width 0.10795)
		(layer "F.Cu")
		(net "SVID_CLK0_CPU1_R")
	)
	(via
		(at 157.5816 -117.85346)
		(size 0.508)
		(drill 0.254)
		(layers "F.Cu" "B.Cu")
		(net "SVID_CLK0_CPU1_R")
	)
	(via
		(at 183.843168 -124.243592)
		(size 0.508)
		(drill 0.254)
		(layers "F.Cu" "B.Cu")
		(net "SVID_CLK0_CPU1_R")
	)
	(via
		(at 17.526 -86.0552)
		(size 0.508)
		(drill 0.254)
		(layers "F.Cu" "B.Cu")
		(net "SVID_CLK0_CPU1_R")
	)
	(via
		(at 23.1521 -157.0355)
		(size 0.508)
		(drill 0.254)
		(layers "F.Cu" "B.Cu")
		(net "SVID_CLK0_CPU1_R")
	)
	(via
		(at 163.449 -69.816472)
		(size 0.508)
		(drill 0.254)
		(layers "F.Cu" "B.Cu")
		(net "SVID_CLK0_CPU1_R")
	)
	(segment
		(start 164.084 -69.088)
		(end 164.084 -69.181472)
		(width 0.10795)
		(layer "B.Cu")
		(net "SVID_CLK0_CPU1_R")
	)
	(segment
		(start 164.084 -69.181472)
		(end 163.449 -69.816472)
		(width 0.10795)
		(layer "B.Cu")
		(net "SVID_CLK0_CPU1_R")
	)
	(segment
		(start 17.526 -86.8172)
		(end 17.526 -86.0552)
		(width 0.10795)
		(layer "B.Cu")
		(net "SVID_CLK0_CPU1_R")
	)
	(segment
		(start 158.152592 -116.092478)
		(end 158.242 -116.00307)
		(width 0.089408)
		(layer "In2.Cu")
		(net "SVID_CLK0_CPU1_R")
	)
	(segment
		(start 91.717622 -158.29026)
		(end 96.21774 -158.29026)
		(width 0.089408)
		(layer "In2.Cu")
		(net "SVID_CLK0_CPU1_R")
	)
	(segment
		(start 163.449 -70.352666)
		(end 163.449 -69.816472)
		(width 0.089408)
		(layer "In2.Cu")
		(net "SVID_CLK0_CPU1_R")
	)
	(segment
		(start 157.6578 -115.466622)
		(end 157.747208 -115.377214)
		(width 0.089408)
		(layer "In2.Cu")
		(net "SVID_CLK0_CPU1_R")
	)
	(segment
		(start 157.6578 -114.930174)
		(end 157.6578 -113.655602)
		(width 0.089408)
		(layer "In2.Cu")
		(net "SVID_CLK0_CPU1_R")
	)
	(segment
		(start 160.13049 -77.479144)
		(end 162.928554 -74.68108)
		(width 0.089408)
		(layer "In2.Cu")
		(net "SVID_CLK0_CPU1_R")
	)
	(segment
		(start 157.703774 -116.181886)
		(end 157.793182 -116.092478)
		(width 0.089408)
		(layer "In2.Cu")
		(net "SVID_CLK0_CPU1_R")
	)
	(segment
		(start 178.666394 -124.350526)
		(end 178.666648 -124.350526)
		(width 0.089408)
		(layer "In2.Cu")
		(net "SVID_CLK0_CPU1_R")
	)
	(segment
		(start 159.727392 -129.548128)
		(end 160.422336 -128.853184)
		(width 0.089408)
		(layer "In2.Cu")
		(net "SVID_CLK0_CPU1_R")
	)
	(segment
		(start 178.75123 -124.435108)
		(end 183.651652 -124.435108)
		(width 0.089408)
		(layer "In2.Cu")
		(net "SVID_CLK0_CPU1_R")
	)
	(segment
		(start 164.3634 -72.9996)
		(end 163.85667 -72.49287)
		(width 0.089408)
		(layer "In2.Cu")
		(net "SVID_CLK0_CPU1_R")
	)
	(segment
		(start 163.16071 -151.545036)
		(end 160.38957 -151.545036)
		(width 0.089408)
		(layer "In2.Cu")
		(net "SVID_CLK0_CPU1_R")
	)
	(segment
		(start 163.078668 -157.738064)
		(end 164.94252 -155.874212)
		(width 0.089408)
		(layer "In2.Cu")
		(net "SVID_CLK0_CPU1_R")
	)
	(segment
		(start 164.94252 -153.326846)
		(end 163.16071 -151.545036)
		(width 0.089408)
		(layer "In2.Cu")
		(net "SVID_CLK0_CPU1_R")
	)
	(segment
		(start 158.242 -115.10899)
		(end 158.152592 -115.019582)
		(width 0.089408)
		(layer "In2.Cu")
		(net "SVID_CLK0_CPU1_R")
	)
	(segment
		(start 162.168586 -109.144816)
		(end 162.16884 -109.144816)
		(width 0.089408)
		(layer "In2.Cu")
		(net "SVID_CLK0_CPU1_R")
	)
	(segment
		(start 164.05352 -74.68108)
		(end 164.3634 -74.3712)
		(width 0.089408)
		(layer "In2.Cu")
		(net "SVID_CLK0_CPU1_R")
	)
	(segment
		(start 163.85667 -70.760336)
		(end 163.449 -70.352666)
		(width 0.089408)
		(layer "In2.Cu")
		(net "SVID_CLK0_CPU1_R")
	)
	(segment
		(start 87.690706 -157.441646)
		(end 88.23325 -156.899102)
		(width 0.089408)
		(layer "In2.Cu")
		(net "SVID_CLK0_CPU1_R")
	)
	(segment
		(start 163.85667 -72.49287)
		(end 163.85667 -70.760336)
		(width 0.089408)
		(layer "In2.Cu")
		(net "SVID_CLK0_CPU1_R")
	)
	(segment
		(start 162.421824 -108.891832)
		(end 162.421824 -100.266246)
		(width 0.089408)
		(layer "In2.Cu")
		(net "SVID_CLK0_CPU1_R")
	)
	(segment
		(start 159.727392 -150.882858)
		(end 159.727392 -129.548128)
		(width 0.089408)
		(layer "In2.Cu")
		(net "SVID_CLK0_CPU1_R")
	)
	(segment
		(start 160.38957 -151.545036)
		(end 159.727392 -150.882858)
		(width 0.089408)
		(layer "In2.Cu")
		(net "SVID_CLK0_CPU1_R")
	)
	(segment
		(start 157.793182 -116.092478)
		(end 158.152592 -116.092478)
		(width 0.089408)
		(layer "In2.Cu")
		(net "SVID_CLK0_CPU1_R")
	)
	(segment
		(start 158.242 -115.824254)
		(end 158.152592 -115.734846)
		(width 0.089408)
		(layer "In2.Cu")
		(net "SVID_CLK0_CPU1_R")
	)
	(segment
		(start 157.6578 -113.655602)
		(end 162.168586 -109.144816)
		(width 0.089408)
		(layer "In2.Cu")
		(net "SVID_CLK0_CPU1_R")
	)
	(segment
		(start 157.5816 -117.85346)
		(end 157.703774 -117.731286)
		(width 0.089408)
		(layer "In2.Cu")
		(net "SVID_CLK0_CPU1_R")
	)
	(segment
		(start 156.789374 -157.36062)
		(end 157.166818 -157.738064)
		(width 0.089408)
		(layer "In2.Cu")
		(net "SVID_CLK0_CPU1_R")
	)
	(segment
		(start 178.370738 -124.054616)
		(end 178.41341 -124.097288)
		(width 0.089408)
		(layer "In2.Cu")
		(net "SVID_CLK0_CPU1_R")
	)
	(segment
		(start 162.421824 -100.266246)
		(end 160.13049 -97.974912)
		(width 0.089408)
		(layer "In2.Cu")
		(net "SVID_CLK0_CPU1_R")
	)
	(segment
		(start 178.41341 -124.097288)
		(end 178.41341 -124.097542)
		(width 0.089408)
		(layer "In2.Cu")
		(net "SVID_CLK0_CPU1_R")
	)
	(segment
		(start 158.242 -116.00307)
		(end 158.242 -115.824254)
		(width 0.089408)
		(layer "In2.Cu")
		(net "SVID_CLK0_CPU1_R")
	)
	(segment
		(start 171.786296 -125.82652)
		(end 173.198536 -125.82652)
		(width 0.089408)
		(layer "In2.Cu")
		(net "SVID_CLK0_CPU1_R")
	)
	(segment
		(start 158.242 -115.287806)
		(end 158.242 -115.10899)
		(width 0.089408)
		(layer "In2.Cu")
		(net "SVID_CLK0_CPU1_R")
	)
	(segment
		(start 158.152592 -115.734846)
		(end 157.747208 -115.734846)
		(width 0.089408)
		(layer "In2.Cu")
		(net "SVID_CLK0_CPU1_R")
	)
	(segment
		(start 158.152592 -115.377214)
		(end 158.242 -115.287806)
		(width 0.089408)
		(layer "In2.Cu")
		(net "SVID_CLK0_CPU1_R")
	)
	(segment
		(start 169.597578 -127.4318)
		(end 170.613578 -126.4158)
		(width 0.089408)
		(layer "In2.Cu")
		(net "SVID_CLK0_CPU1_R")
	)
	(segment
		(start 157.747208 -115.019582)
		(end 157.6578 -114.930174)
		(width 0.089408)
		(layer "In2.Cu")
		(net "SVID_CLK0_CPU1_R")
	)
	(segment
		(start 157.747208 -115.377214)
		(end 158.152592 -115.377214)
		(width 0.089408)
		(layer "In2.Cu")
		(net "SVID_CLK0_CPU1_R")
	)
	(segment
		(start 23.65502 -157.441646)
		(end 87.690706 -157.441646)
		(width 0.089408)
		(layer "In2.Cu")
		(net "SVID_CLK0_CPU1_R")
	)
	(segment
		(start 157.6578 -115.645438)
		(end 157.6578 -115.466622)
		(width 0.089408)
		(layer "In2.Cu")
		(net "SVID_CLK0_CPU1_R")
	)
	(segment
		(start 23.495254 -157.28188)
		(end 23.65502 -157.441646)
		(width 0.089408)
		(layer "In2.Cu")
		(net "SVID_CLK0_CPU1_R")
	)
	(segment
		(start 165.331394 -128.853184)
		(end 166.752778 -127.4318)
		(width 0.089408)
		(layer "In2.Cu")
		(net "SVID_CLK0_CPU1_R")
	)
	(segment
		(start 170.613578 -126.4158)
		(end 171.197016 -126.4158)
		(width 0.089408)
		(layer "In2.Cu")
		(net "SVID_CLK0_CPU1_R")
	)
	(segment
		(start 183.651652 -124.435108)
		(end 183.843168 -124.243592)
		(width 0.089408)
		(layer "In2.Cu")
		(net "SVID_CLK0_CPU1_R")
	)
	(segment
		(start 173.198536 -125.82652)
		(end 174.97044 -124.054616)
		(width 0.089408)
		(layer "In2.Cu")
		(net "SVID_CLK0_CPU1_R")
	)
	(segment
		(start 157.703774 -117.731286)
		(end 157.703774 -116.181886)
		(width 0.089408)
		(layer "In2.Cu")
		(net "SVID_CLK0_CPU1_R")
	)
	(segment
		(start 162.928554 -74.68108)
		(end 164.05352 -74.68108)
		(width 0.089408)
		(layer "In2.Cu")
		(net "SVID_CLK0_CPU1_R")
	)
	(segment
		(start 88.23325 -156.899102)
		(end 90.326464 -156.899102)
		(width 0.089408)
		(layer "In2.Cu")
		(net "SVID_CLK0_CPU1_R")
	)
	(segment
		(start 23.39848 -157.28188)
		(end 23.495254 -157.28188)
		(width 0.089408)
		(layer "In2.Cu")
		(net "SVID_CLK0_CPU1_R")
	)
	(segment
		(start 166.752778 -127.4318)
		(end 169.597578 -127.4318)
		(width 0.089408)
		(layer "In2.Cu")
		(net "SVID_CLK0_CPU1_R")
	)
	(segment
		(start 157.747208 -115.734846)
		(end 157.6578 -115.645438)
		(width 0.089408)
		(layer "In2.Cu")
		(net "SVID_CLK0_CPU1_R")
	)
	(segment
		(start 178.41341 -124.097542)
		(end 178.666394 -124.350526)
		(width 0.089408)
		(layer "In2.Cu")
		(net "SVID_CLK0_CPU1_R")
	)
	(segment
		(start 23.1521 -157.0355)
		(end 23.39848 -157.28188)
		(width 0.089408)
		(layer "In2.Cu")
		(net "SVID_CLK0_CPU1_R")
	)
	(segment
		(start 164.94252 -155.874212)
		(end 164.94252 -153.326846)
		(width 0.089408)
		(layer "In2.Cu")
		(net "SVID_CLK0_CPU1_R")
	)
	(segment
		(start 96.21774 -158.29026)
		(end 97.14738 -157.36062)
		(width 0.089408)
		(layer "In2.Cu")
		(net "SVID_CLK0_CPU1_R")
	)
	(segment
		(start 160.13049 -97.974912)
		(end 160.13049 -77.479144)
		(width 0.089408)
		(layer "In2.Cu")
		(net "SVID_CLK0_CPU1_R")
	)
	(segment
		(start 171.197016 -126.4158)
		(end 171.786296 -125.82652)
		(width 0.089408)
		(layer "In2.Cu")
		(net "SVID_CLK0_CPU1_R")
	)
	(segment
		(start 178.666648 -124.350526)
		(end 178.75123 -124.435108)
		(width 0.089408)
		(layer "In2.Cu")
		(net "SVID_CLK0_CPU1_R")
	)
	(segment
		(start 162.16884 -109.144816)
		(end 162.421824 -108.891832)
		(width 0.089408)
		(layer "In2.Cu")
		(net "SVID_CLK0_CPU1_R")
	)
	(segment
		(start 174.97044 -124.054616)
		(end 178.370738 -124.054616)
		(width 0.089408)
		(layer "In2.Cu")
		(net "SVID_CLK0_CPU1_R")
	)
	(segment
		(start 90.326464 -156.899102)
		(end 91.717622 -158.29026)
		(width 0.089408)
		(layer "In2.Cu")
		(net "SVID_CLK0_CPU1_R")
	)
	(segment
		(start 157.166818 -157.738064)
		(end 163.078668 -157.738064)
		(width 0.089408)
		(layer "In2.Cu")
		(net "SVID_CLK0_CPU1_R")
	)
	(segment
		(start 97.14738 -157.36062)
		(end 156.789374 -157.36062)
		(width 0.089408)
		(layer "In2.Cu")
		(net "SVID_CLK0_CPU1_R")
	)
	(segment
		(start 158.152592 -115.019582)
		(end 157.747208 -115.019582)
		(width 0.089408)
		(layer "In2.Cu")
		(net "SVID_CLK0_CPU1_R")
	)
	(segment
		(start 160.422336 -128.853184)
		(end 165.331394 -128.853184)
		(width 0.089408)
		(layer "In2.Cu")
		(net "SVID_CLK0_CPU1_R")
	)
	(segment
		(start 164.3634 -74.3712)
		(end 164.3634 -72.9996)
		(width 0.089408)
		(layer "In2.Cu")
		(net "SVID_CLK0_CPU1_R")
	)
	(segment
		(start 17.64538 -89.483184)
		(end 18.178272 -89.483184)
		(width 0.089408)
		(layer "In11.Cu")
		(net "SVID_CLK0_CPU1_R")
	)
	(segment
		(start 25.956768 -127.685038)
		(end 25.956768 -118.977918)
		(width 0.089408)
		(layer "In11.Cu")
		(net "SVID_CLK0_CPU1_R")
	)
	(segment
		(start 165.7604 -74.011536)
		(end 165.7604 -76.75372)
		(width 0.089408)
		(layer "In11.Cu")
		(net "SVID_CLK0_CPU1_R")
	)
	(segment
		(start 17.694402 -100.203254)
		(end 17.694402 -99.426014)
		(width 0.089408)
		(layer "In11.Cu")
		(net "SVID_CLK0_CPU1_R")
	)
	(segment
		(start 17.150588 -98.8822)
		(end 16.275304 -98.8822)
		(width 0.089408)
		(layer "In11.Cu")
		(net "SVID_CLK0_CPU1_R")
	)
	(segment
		(start 16.275304 -98.8822)
		(end 14.69263 -100.464874)
		(width 0.089408)
		(layer "In11.Cu")
		(net "SVID_CLK0_CPU1_R")
	)
	(segment
		(start 14.427708 -90.636344)
		(end 15.154656 -89.909396)
		(width 0.089408)
		(layer "In11.Cu")
		(net "SVID_CLK0_CPU1_R")
	)
	(segment
		(start 164.0332 -71.255382)
		(end 164.0332 -72.284336)
		(width 0.089408)
		(layer "In11.Cu")
		(net "SVID_CLK0_CPU1_R")
	)
	(segment
		(start 163.704778 -78.326742)
		(end 163.704778 -85.704426)
		(width 0.089408)
		(layer "In11.Cu")
		(net "SVID_CLK0_CPU1_R")
	)
	(segment
		(start 177.00244 -92.046806)
		(end 177.00244 -100.748084)
		(width 0.089408)
		(layer "In11.Cu")
		(net "SVID_CLK0_CPU1_R")
	)
	(segment
		(start 23.1521 -157.0355)
		(end 22.91334 -157.0355)
		(width 0.089408)
		(layer "In11.Cu")
		(net "SVID_CLK0_CPU1_R")
	)
	(segment
		(start 18.42135 -109.121448)
		(end 18.421096 -109.121448)
		(width 0.089408)
		(layer "In11.Cu")
		(net "SVID_CLK0_CPU1_R")
	)
	(segment
		(start 15.154656 -89.909396)
		(end 17.219168 -89.909396)
		(width 0.089408)
		(layer "In11.Cu")
		(net "SVID_CLK0_CPU1_R")
	)
	(segment
		(start 18.861532 -111.882682)
		(end 18.861532 -109.56163)
		(width 0.089408)
		(layer "In11.Cu")
		(net "SVID_CLK0_CPU1_R")
	)
	(segment
		(start 18.861532 -109.56163)
		(end 18.42135 -109.121448)
		(width 0.089408)
		(layer "In11.Cu")
		(net "SVID_CLK0_CPU1_R")
	)
	(segment
		(start 21.158708 -129.860294)
		(end 22.84857 -128.170432)
		(width 0.089408)
		(layer "In11.Cu")
		(net "SVID_CLK0_CPU1_R")
	)
	(segment
		(start 13.255752 -100.464874)
		(end 12.351512 -99.560634)
		(width 0.089408)
		(layer "In11.Cu")
		(net "SVID_CLK0_CPU1_R")
	)
	(segment
		(start 184.684162 -122.758962)
		(end 183.843168 -123.599956)
		(width 0.089408)
		(layer "In11.Cu")
		(net "SVID_CLK0_CPU1_R")
	)
	(segment
		(start 18.421096 -109.121448)
		(end 17.694148 -108.3945)
		(width 0.089408)
		(layer "In11.Cu")
		(net "SVID_CLK0_CPU1_R")
	)
	(segment
		(start 163.704778 -85.704426)
		(end 164.702744 -86.702392)
		(width 0.089408)
		(layer "In11.Cu")
		(net "SVID_CLK0_CPU1_R")
	)
	(segment
		(start 17.694148 -108.3945)
		(end 17.694148 -101.652832)
		(width 0.089408)
		(layer "In11.Cu")
		(net "SVID_CLK0_CPU1_R")
	)
	(segment
		(start 25.471374 -128.170432)
		(end 25.956768 -127.685038)
		(width 0.089408)
		(layer "In11.Cu")
		(net "SVID_CLK0_CPU1_R")
	)
	(segment
		(start 165.7604 -76.75372)
		(end 164.63772 -77.8764)
		(width 0.089408)
		(layer "In11.Cu")
		(net "SVID_CLK0_CPU1_R")
	)
	(segment
		(start 174.15002 -86.702138)
		(end 176.036224 -88.588342)
		(width 0.089408)
		(layer "In11.Cu")
		(net "SVID_CLK0_CPU1_R")
	)
	(segment
		(start 178.667156 -102.4128)
		(end 179.3494 -102.4128)
		(width 0.089408)
		(layer "In11.Cu")
		(net "SVID_CLK0_CPU1_R")
	)
	(segment
		(start 14.69263 -100.464874)
		(end 13.255752 -100.464874)
		(width 0.089408)
		(layer "In11.Cu")
		(net "SVID_CLK0_CPU1_R")
	)
	(segment
		(start 12.351512 -99.560634)
		(end 12.351512 -92.974668)
		(width 0.089408)
		(layer "In11.Cu")
		(net "SVID_CLK0_CPU1_R")
	)
	(segment
		(start 17.219168 -89.909396)
		(end 17.64538 -89.483184)
		(width 0.089408)
		(layer "In11.Cu")
		(net "SVID_CLK0_CPU1_R")
	)
	(segment
		(start 17.526 -87.000334)
		(end 17.526 -86.0552)
		(width 0.089408)
		(layer "In11.Cu")
		(net "SVID_CLK0_CPU1_R")
	)
	(segment
		(start 179.3494 -102.4128)
		(end 184.684162 -107.747562)
		(width 0.089408)
		(layer "In11.Cu")
		(net "SVID_CLK0_CPU1_R")
	)
	(segment
		(start 173.792388 -86.702138)
		(end 174.15002 -86.702138)
		(width 0.089408)
		(layer "In11.Cu")
		(net "SVID_CLK0_CPU1_R")
	)
	(segment
		(start 173.792134 -86.702392)
		(end 173.792388 -86.702138)
		(width 0.089408)
		(layer "In11.Cu")
		(net "SVID_CLK0_CPU1_R")
	)
	(segment
		(start 18.779744 -88.881712)
		(end 18.779744 -88.254078)
		(width 0.089408)
		(layer "In11.Cu")
		(net "SVID_CLK0_CPU1_R")
	)
	(segment
		(start 163.449 -69.816472)
		(end 163.449 -70.671182)
		(width 0.089408)
		(layer "In11.Cu")
		(net "SVID_CLK0_CPU1_R")
	)
	(segment
		(start 12.351512 -92.974668)
		(end 14.427708 -90.898472)
		(width 0.089408)
		(layer "In11.Cu")
		(net "SVID_CLK0_CPU1_R")
	)
	(segment
		(start 164.63772 -77.8764)
		(end 164.15512 -77.8764)
		(width 0.089408)
		(layer "In11.Cu")
		(net "SVID_CLK0_CPU1_R")
	)
	(segment
		(start 22.84857 -128.170432)
		(end 25.471374 -128.170432)
		(width 0.089408)
		(layer "In11.Cu")
		(net "SVID_CLK0_CPU1_R")
	)
	(segment
		(start 176.036224 -88.588342)
		(end 176.036224 -91.08059)
		(width 0.089408)
		(layer "In11.Cu")
		(net "SVID_CLK0_CPU1_R")
	)
	(segment
		(start 177.00244 -100.748084)
		(end 178.667156 -102.4128)
		(width 0.089408)
		(layer "In11.Cu")
		(net "SVID_CLK0_CPU1_R")
	)
	(segment
		(start 25.956768 -118.977918)
		(end 18.861532 -111.882682)
		(width 0.089408)
		(layer "In11.Cu")
		(net "SVID_CLK0_CPU1_R")
	)
	(segment
		(start 164.15512 -77.8764)
		(end 163.704778 -78.326742)
		(width 0.089408)
		(layer "In11.Cu")
		(net "SVID_CLK0_CPU1_R")
	)
	(segment
		(start 14.427708 -90.898472)
		(end 14.427708 -90.636344)
		(width 0.089408)
		(layer "In11.Cu")
		(net "SVID_CLK0_CPU1_R")
	)
	(segment
		(start 17.694148 -101.652832)
		(end 17.69364 -101.652324)
		(width 0.089408)
		(layer "In11.Cu")
		(net "SVID_CLK0_CPU1_R")
	)
	(segment
		(start 164.702744 -86.702392)
		(end 173.792134 -86.702392)
		(width 0.089408)
		(layer "In11.Cu")
		(net "SVID_CLK0_CPU1_R")
	)
	(segment
		(start 164.0332 -72.284336)
		(end 165.7604 -74.011536)
		(width 0.089408)
		(layer "In11.Cu")
		(net "SVID_CLK0_CPU1_R")
	)
	(segment
		(start 17.694402 -99.426014)
		(end 17.150588 -98.8822)
		(width 0.089408)
		(layer "In11.Cu")
		(net "SVID_CLK0_CPU1_R")
	)
	(segment
		(start 21.65223 -155.77439)
		(end 21.65223 -135.19785)
		(width 0.089408)
		(layer "In11.Cu")
		(net "SVID_CLK0_CPU1_R")
	)
	(segment
		(start 183.843168 -123.599956)
		(end 183.843168 -124.243592)
		(width 0.089408)
		(layer "In11.Cu")
		(net "SVID_CLK0_CPU1_R")
	)
	(segment
		(start 163.449 -70.671182)
		(end 164.0332 -71.255382)
		(width 0.089408)
		(layer "In11.Cu")
		(net "SVID_CLK0_CPU1_R")
	)
	(segment
		(start 17.69364 -101.652324)
		(end 17.69364 -100.204016)
		(width 0.089408)
		(layer "In11.Cu")
		(net "SVID_CLK0_CPU1_R")
	)
	(segment
		(start 22.91334 -157.0355)
		(end 21.65223 -155.77439)
		(width 0.089408)
		(layer "In11.Cu")
		(net "SVID_CLK0_CPU1_R")
	)
	(segment
		(start 176.036224 -91.08059)
		(end 177.00244 -92.046806)
		(width 0.089408)
		(layer "In11.Cu")
		(net "SVID_CLK0_CPU1_R")
	)
	(segment
		(start 21.65223 -135.19785)
		(end 21.158708 -134.704328)
		(width 0.089408)
		(layer "In11.Cu")
		(net "SVID_CLK0_CPU1_R")
	)
	(segment
		(start 18.178272 -89.483184)
		(end 18.779744 -88.881712)
		(width 0.089408)
		(layer "In11.Cu")
		(net "SVID_CLK0_CPU1_R")
	)
	(segment
		(start 17.69364 -100.204016)
		(end 17.694402 -100.203254)
		(width 0.089408)
		(layer "In11.Cu")
		(net "SVID_CLK0_CPU1_R")
	)
	(segment
		(start 184.684162 -107.747562)
		(end 184.684162 -122.758962)
		(width 0.089408)
		(layer "In11.Cu")
		(net "SVID_CLK0_CPU1_R")
	)
	(segment
		(start 18.779744 -88.254078)
		(end 17.526 -87.000334)
		(width 0.089408)
		(layer "In11.Cu")
		(net "SVID_CLK0_CPU1_R")
	)
	(segment
		(start 21.158708 -134.704328)
		(end 21.158708 -129.860294)
		(width 0.089408)
		(layer "In11.Cu")
		(net "SVID_CLK0_CPU1_R")
	)
	(segment
		(start 103.806244 -90.26144)
		(end 104.415844 -90.26144)
		(width 0.10795)
		(layer "F.Cu")
		(net "SVID_CLK0_CPU1")
	)
	(segment
		(start 155.6512 -118.364)
		(end 155.27655 -118.364)
		(width 0.10795)
		(layer "F.Cu")
		(net "SVID_CLK0_CPU1")
	)
	(segment
		(start 155.27655 -118.364)
		(end 154.6352 -117.72265)
		(width 0.10795)
		(layer "F.Cu")
		(net "SVID_CLK0_CPU1")
	)
	(via
		(at 154.6352 -117.72265)
		(size 0.508)
		(drill 0.254)
		(layers "F.Cu" "B.Cu")
		(net "SVID_CLK0_CPU1")
	)
	(via
		(at 104.415844 -90.26144)
		(size 0.508)
		(drill 0.254)
		(layers "F.Cu" "B.Cu")
		(net "SVID_CLK0_CPU1")
	)
	(segment
		(start 126.632462 -93.599)
		(end 126.968758 -93.935296)
		(width 0.089408)
		(layer "In4.Cu")
		(net "SVID_CLK0_CPU1")
	)
	(segment
		(start 109.873034 -90.146378)
		(end 110.362238 -90.146378)
		(width 0.0889)
		(layer "In4.Cu")
		(net "SVID_CLK0_CPU1")
	)
	(segment
		(start 113.383314 -90.119708)
		(end 113.802414 -90.119708)
		(width 0.0889)
		(layer "In4.Cu")
		(net "SVID_CLK0_CPU1")
	)
	(segment
		(start 130.96494 -101.93274)
		(end 131.52882 -102.49662)
		(width 0.089408)
		(layer "In4.Cu")
		(net "SVID_CLK0_CPU1")
	)
	(segment
		(start 153.392124 -118.51259)
		(end 154.182064 -117.72265)
		(width 0.089408)
		(layer "In4.Cu")
		(net "SVID_CLK0_CPU1")
	)
	(segment
		(start 130.58902 -101.93274)
		(end 130.96494 -101.93274)
		(width 0.089408)
		(layer "In4.Cu")
		(net "SVID_CLK0_CPU1")
	)
	(segment
		(start 122.846592 -91.526614)
		(end 123.227592 -91.526614)
		(width 0.0889)
		(layer "In4.Cu")
		(net "SVID_CLK0_CPU1")
	)
	(segment
		(start 104.415844 -90.26144)
		(end 106.854752 -90.26144)
		(width 0.089408)
		(layer "In4.Cu")
		(net "SVID_CLK0_CPU1")
	)
	(segment
		(start 122.051826 -91.166188)
		(end 122.486166 -91.166188)
		(width 0.0889)
		(layer "In4.Cu")
		(net "SVID_CLK0_CPU1")
	)
	(segment
		(start 127.202946 -99.890834)
		(end 127.47752 -99.890834)
		(width 0.089408)
		(layer "In4.Cu")
		(net "SVID_CLK0_CPU1")
	)
	(segment
		(start 113.802414 -90.119708)
		(end 114.250724 -90.568018)
		(width 0.0889)
		(layer "In4.Cu")
		(net "SVID_CLK0_CPU1")
	)
	(segment
		(start 108.660946 -91.018614)
		(end 109.04728 -90.63228)
		(width 0.0889)
		(layer "In4.Cu")
		(net "SVID_CLK0_CPU1")
	)
	(segment
		(start 121.143522 -91.471242)
		(end 121.746772 -91.471242)
		(width 0.0889)
		(layer "In4.Cu")
		(net "SVID_CLK0_CPU1")
	)
	(segment
		(start 118.065804 -90.559128)
		(end 118.487444 -90.137488)
		(width 0.0889)
		(layer "In4.Cu")
		(net "SVID_CLK0_CPU1")
	)
	(segment
		(start 126.968758 -99.656646)
		(end 127.202946 -99.890834)
		(width 0.089408)
		(layer "In4.Cu")
		(net "SVID_CLK0_CPU1")
	)
	(segment
		(start 108.100876 -90.908378)
		(end 108.211112 -91.018614)
		(width 0.0889)
		(layer "In4.Cu")
		(net "SVID_CLK0_CPU1")
	)
	(segment
		(start 154.182064 -117.72265)
		(end 154.6352 -117.72265)
		(width 0.089408)
		(layer "In4.Cu")
		(net "SVID_CLK0_CPU1")
	)
	(segment
		(start 106.854752 -90.26144)
		(end 107.2642 -90.670888)
		(width 0.089408)
		(layer "In4.Cu")
		(net "SVID_CLK0_CPU1")
	)
	(segment
		(start 119.455184 -90.63736)
		(end 119.80418 -90.63736)
		(width 0.0889)
		(layer "In4.Cu")
		(net "SVID_CLK0_CPU1")
	)
	(segment
		(start 125.553978 -93.091)
		(end 125.956568 -93.091)
		(width 0.089408)
		(layer "In4.Cu")
		(net "SVID_CLK0_CPU1")
	)
	(segment
		(start 126.464568 -93.599)
		(end 126.632462 -93.599)
		(width 0.089408)
		(layer "In4.Cu")
		(net "SVID_CLK0_CPU1")
	)
	(segment
		(start 118.487444 -90.137488)
		(end 118.955312 -90.137488)
		(width 0.0889)
		(layer "In4.Cu")
		(net "SVID_CLK0_CPU1")
	)
	(segment
		(start 127.47752 -99.890834)
		(end 128.16332 -100.576634)
		(width 0.089408)
		(layer "In4.Cu")
		(net "SVID_CLK0_CPU1")
	)
	(segment
		(start 108.211112 -91.018614)
		(end 108.660946 -91.018614)
		(width 0.0889)
		(layer "In4.Cu")
		(net "SVID_CLK0_CPU1")
	)
	(segment
		(start 125.005592 -92.542614)
		(end 125.553978 -93.091)
		(width 0.089408)
		(layer "In4.Cu")
		(net "SVID_CLK0_CPU1")
	)
	(segment
		(start 134.698486 -105.41)
		(end 136.497568 -105.41)
		(width 0.089408)
		(layer "In4.Cu")
		(net "SVID_CLK0_CPU1")
	)
	(segment
		(start 116.897912 -90.088974)
		(end 117.2464 -90.088974)
		(width 0.0889)
		(layer "In4.Cu")
		(net "SVID_CLK0_CPU1")
	)
	(segment
		(start 107.863386 -90.670888)
		(end 108.100876 -90.908378)
		(width 0.089408)
		(layer "In4.Cu")
		(net "SVID_CLK0_CPU1")
	)
	(segment
		(start 111.656876 -90.172794)
		(end 112.130078 -90.172794)
		(width 0.0889)
		(layer "In4.Cu")
		(net "SVID_CLK0_CPU1")
	)
	(segment
		(start 117.2464 -90.088974)
		(end 117.716554 -90.559128)
		(width 0.0889)
		(layer "In4.Cu")
		(net "SVID_CLK0_CPU1")
	)
	(segment
		(start 112.915446 -90.587576)
		(end 113.383314 -90.119708)
		(width 0.0889)
		(layer "In4.Cu")
		(net "SVID_CLK0_CPU1")
	)
	(segment
		(start 123.735592 -92.034614)
		(end 123.989592 -92.034614)
		(width 0.0889)
		(layer "In4.Cu")
		(net "SVID_CLK0_CPU1")
	)
	(segment
		(start 136.497568 -105.41)
		(end 149.600158 -118.51259)
		(width 0.089408)
		(layer "In4.Cu")
		(net "SVID_CLK0_CPU1")
	)
	(segment
		(start 125.956568 -93.091)
		(end 126.464568 -93.599)
		(width 0.089408)
		(layer "In4.Cu")
		(net "SVID_CLK0_CPU1")
	)
	(segment
		(start 129.36982 -101.45268)
		(end 130.10896 -101.45268)
		(width 0.089408)
		(layer "In4.Cu")
		(net "SVID_CLK0_CPU1")
	)
	(segment
		(start 120.74652 -91.07424)
		(end 121.143522 -91.471242)
		(width 0.0889)
		(layer "In4.Cu")
		(net "SVID_CLK0_CPU1")
	)
	(segment
		(start 109.387132 -90.63228)
		(end 109.873034 -90.146378)
		(width 0.0889)
		(layer "In4.Cu")
		(net "SVID_CLK0_CPU1")
	)
	(segment
		(start 122.486166 -91.166188)
		(end 122.846592 -91.526614)
		(width 0.0889)
		(layer "In4.Cu")
		(net "SVID_CLK0_CPU1")
	)
	(segment
		(start 121.746772 -91.471242)
		(end 122.051826 -91.166188)
		(width 0.0889)
		(layer "In4.Cu")
		(net "SVID_CLK0_CPU1")
	)
	(segment
		(start 130.10896 -101.45268)
		(end 130.58902 -101.93274)
		(width 0.089408)
		(layer "In4.Cu")
		(net "SVID_CLK0_CPU1")
	)
	(segment
		(start 109.04728 -90.63228)
		(end 109.387132 -90.63228)
		(width 0.0889)
		(layer "In4.Cu")
		(net "SVID_CLK0_CPU1")
	)
	(segment
		(start 131.785106 -102.49662)
		(end 134.698486 -105.41)
		(width 0.089408)
		(layer "In4.Cu")
		(net "SVID_CLK0_CPU1")
	)
	(segment
		(start 119.80418 -90.63736)
		(end 120.24106 -91.07424)
		(width 0.0889)
		(layer "In4.Cu")
		(net "SVID_CLK0_CPU1")
	)
	(segment
		(start 112.54486 -90.587576)
		(end 112.915446 -90.587576)
		(width 0.0889)
		(layer "In4.Cu")
		(net "SVID_CLK0_CPU1")
	)
	(segment
		(start 116.447824 -90.539062)
		(end 116.897912 -90.088974)
		(width 0.0889)
		(layer "In4.Cu")
		(net "SVID_CLK0_CPU1")
	)
	(segment
		(start 115.13185 -90.146378)
		(end 115.515898 -90.146378)
		(width 0.0889)
		(layer "In4.Cu")
		(net "SVID_CLK0_CPU1")
	)
	(segment
		(start 115.908582 -90.539062)
		(end 116.447824 -90.539062)
		(width 0.0889)
		(layer "In4.Cu")
		(net "SVID_CLK0_CPU1")
	)
	(segment
		(start 120.24106 -91.07424)
		(end 120.74652 -91.07424)
		(width 0.0889)
		(layer "In4.Cu")
		(net "SVID_CLK0_CPU1")
	)
	(segment
		(start 107.2642 -90.670888)
		(end 107.863386 -90.670888)
		(width 0.089408)
		(layer "In4.Cu")
		(net "SVID_CLK0_CPU1")
	)
	(segment
		(start 114.250724 -90.568018)
		(end 114.71021 -90.568018)
		(width 0.0889)
		(layer "In4.Cu")
		(net "SVID_CLK0_CPU1")
	)
	(segment
		(start 111.22533 -90.60434)
		(end 111.656876 -90.172794)
		(width 0.0889)
		(layer "In4.Cu")
		(net "SVID_CLK0_CPU1")
	)
	(segment
		(start 128.493774 -100.576634)
		(end 129.36982 -101.45268)
		(width 0.089408)
		(layer "In4.Cu")
		(net "SVID_CLK0_CPU1")
	)
	(segment
		(start 149.600158 -118.51259)
		(end 153.392124 -118.51259)
		(width 0.089408)
		(layer "In4.Cu")
		(net "SVID_CLK0_CPU1")
	)
	(segment
		(start 126.968758 -93.935296)
		(end 126.968758 -99.656646)
		(width 0.089408)
		(layer "In4.Cu")
		(net "SVID_CLK0_CPU1")
	)
	(segment
		(start 118.955312 -90.137488)
		(end 119.455184 -90.63736)
		(width 0.0889)
		(layer "In4.Cu")
		(net "SVID_CLK0_CPU1")
	)
	(segment
		(start 117.716554 -90.559128)
		(end 118.065804 -90.559128)
		(width 0.0889)
		(layer "In4.Cu")
		(net "SVID_CLK0_CPU1")
	)
	(segment
		(start 110.8202 -90.60434)
		(end 111.22533 -90.60434)
		(width 0.0889)
		(layer "In4.Cu")
		(net "SVID_CLK0_CPU1")
	)
	(segment
		(start 131.52882 -102.49662)
		(end 131.785106 -102.49662)
		(width 0.089408)
		(layer "In4.Cu")
		(net "SVID_CLK0_CPU1")
	)
	(segment
		(start 112.130078 -90.172794)
		(end 112.54486 -90.587576)
		(width 0.0889)
		(layer "In4.Cu")
		(net "SVID_CLK0_CPU1")
	)
	(segment
		(start 123.989592 -92.034614)
		(end 124.497592 -92.542614)
		(width 0.0889)
		(layer "In4.Cu")
		(net "SVID_CLK0_CPU1")
	)
	(segment
		(start 123.227592 -91.526614)
		(end 123.735592 -92.034614)
		(width 0.0889)
		(layer "In4.Cu")
		(net "SVID_CLK0_CPU1")
	)
	(segment
		(start 115.515898 -90.146378)
		(end 115.908582 -90.539062)
		(width 0.0889)
		(layer "In4.Cu")
		(net "SVID_CLK0_CPU1")
	)
	(segment
		(start 114.71021 -90.568018)
		(end 115.13185 -90.146378)
		(width 0.0889)
		(layer "In4.Cu")
		(net "SVID_CLK0_CPU1")
	)
	(segment
		(start 128.16332 -100.576634)
		(end 128.493774 -100.576634)
		(width 0.089408)
		(layer "In4.Cu")
		(net "SVID_CLK0_CPU1")
	)
	(segment
		(start 124.497592 -92.542614)
		(end 125.005592 -92.542614)
		(width 0.089408)
		(layer "In4.Cu")
		(net "SVID_CLK0_CPU1")
	)
	(segment
		(start 110.362238 -90.146378)
		(end 110.8202 -90.60434)
		(width 0.0889)
		(layer "In4.Cu")
		(net "SVID_CLK0_CPU1")
	)
	(segment
		(start 183.007 -64.135)
		(end 183.007 -63.5)
		(width 0.10795)
		(layer "F.Cu")
		(net "SVID_CLK0_CPU0_R")
	)
	(segment
		(start 183.007 -63.4746)
		(end 183.007 -62.865)
		(width 0.10795)
		(layer "F.Cu")
		(net "SVID_CLK0_CPU0_R")
	)
	(segment
		(start 353.0854 -114.935)
		(end 353.70135 -115.55095)
		(width 0.10795)
		(layer "F.Cu")
		(net "SVID_CLK0_CPU0_R")
	)
	(segment
		(start 183.007 -63.5)
		(end 182.9943 -63.4873)
		(width 0.10795)
		(layer "F.Cu")
		(net "SVID_CLK0_CPU0_R")
	)
	(segment
		(start 353.70135 -115.55095)
		(end 353.724972 -115.55095)
		(width 0.10795)
		(layer "F.Cu")
		(net "SVID_CLK0_CPU0_R")
	)
	(segment
		(start 182.9943 -63.4873)
		(end 183.007 -63.4746)
		(width 0.10795)
		(layer "F.Cu")
		(net "SVID_CLK0_CPU0_R")
	)
	(via
		(at 353.0854 -114.935)
		(size 0.508)
		(drill 0.254)
		(layers "F.Cu" "B.Cu")
		(net "SVID_CLK0_CPU0_R")
	)
	(via
		(at 202.4888 -104.09682)
		(size 0.508)
		(drill 0.254)
		(layers "F.Cu" "B.Cu")
		(net "SVID_CLK0_CPU0_R")
	)
	(via
		(at 182.9943 -63.4873)
		(size 0.508)
		(drill 0.254)
		(layers "F.Cu" "B.Cu")
		(net "SVID_CLK0_CPU0_R")
	)
	(via
		(at 335.10728 -106.4006)
		(size 0.508)
		(drill 0.254)
		(layers "F.Cu" "B.Cu")
		(net "SVID_CLK0_CPU0_R")
	)
	(via
		(at 339.1535 -86.7029)
		(size 0.6604)
		(drill 0.3302)
		(layers "F.Cu" "B.Cu")
		(net "SVID_CLK0_CPU0_R")
	)
	(via
		(at 339.1535 -87.4395)
		(size 0.508)
		(drill 0.254)
		(layers "F.Cu" "B.Cu")
		(net "SVID_CLK0_CPU0_R")
	)
	(via
		(at 315.823346 -101.178106)
		(size 0.508)
		(drill 0.254)
		(layers "F.Cu" "B.Cu")
		(net "SVID_CLK0_CPU0_R")
	)
	(segment
		(start 339.8266 -85.5472)
		(end 339.1535 -86.2203)
		(width 0.10795)
		(layer "B.Cu")
		(net "SVID_CLK0_CPU0_R")
	)
	(segment
		(start 340.3092 -85.5472)
		(end 339.8266 -85.5472)
		(width 0.10795)
		(layer "B.Cu")
		(net "SVID_CLK0_CPU0_R")
	)
	(segment
		(start 203.995782 -104.775)
		(end 204.851 -104.775)
		(width 0.10795)
		(layer "B.Cu")
		(net "SVID_CLK0_CPU0_R")
	)
	(segment
		(start 340.746588 -85.5472)
		(end 341.1982 -85.998812)
		(width 0.10795)
		(layer "B.Cu")
		(net "SVID_CLK0_CPU0_R")
	)
	(segment
		(start 339.1535 -86.2203)
		(end 339.1535 -86.7029)
		(width 0.10795)
		(layer "B.Cu")
		(net "SVID_CLK0_CPU0_R")
	)
	(segment
		(start 339.1535 -86.7029)
		(end 339.1535 -87.4395)
		(width 0.10795)
		(layer "B.Cu")
		(net "SVID_CLK0_CPU0_R")
	)
	(segment
		(start 203.317602 -104.09682)
		(end 203.995782 -104.775)
		(width 0.10795)
		(layer "B.Cu")
		(net "SVID_CLK0_CPU0_R")
	)
	(segment
		(start 202.4888 -104.09682)
		(end 203.317602 -104.09682)
		(width 0.10795)
		(layer "B.Cu")
		(net "SVID_CLK0_CPU0_R")
	)
	(segment
		(start 341.1982 -85.998812)
		(end 341.1982 -86.5632)
		(width 0.10795)
		(layer "B.Cu")
		(net "SVID_CLK0_CPU0_R")
	)
	(segment
		(start 340.3092 -85.5472)
		(end 340.746588 -85.5472)
		(width 0.10795)
		(layer "B.Cu")
		(net "SVID_CLK0_CPU0_R")
	)
	(segment
		(start 177.372264 -80.866996)
		(end 177.372264 -78.291436)
		(width 0.089408)
		(layer "In2.Cu")
		(net "SVID_CLK0_CPU0_R")
	)
	(segment
		(start 178.694588 -82.18932)
		(end 177.372264 -80.866996)
		(width 0.089408)
		(layer "In2.Cu")
		(net "SVID_CLK0_CPU0_R")
	)
	(segment
		(start 176.6824 -69.04609)
		(end 178.757072 -66.971418)
		(width 0.089408)
		(layer "In2.Cu")
		(net "SVID_CLK0_CPU0_R")
	)
	(segment
		(start 178.757072 -66.020696)
		(end 180.465476 -64.312292)
		(width 0.089408)
		(layer "In2.Cu")
		(net "SVID_CLK0_CPU0_R")
	)
	(segment
		(start 177.372264 -78.291436)
		(end 177.532284 -78.131416)
		(width 0.089408)
		(layer "In2.Cu")
		(net "SVID_CLK0_CPU0_R")
	)
	(segment
		(start 182.9943 -63.637922)
		(end 182.9943 -63.4873)
		(width 0.089408)
		(layer "In2.Cu")
		(net "SVID_CLK0_CPU0_R")
	)
	(segment
		(start 196.619368 -105.293414)
		(end 196.619368 -106.85526)
		(width 0.089408)
		(layer "In2.Cu")
		(net "SVID_CLK0_CPU0_R")
	)
	(segment
		(start 335.344262 -105.374186)
		(end 339.778086 -105.374186)
		(width 0.089408)
		(layer "In2.Cu")
		(net "SVID_CLK0_CPU0_R")
	)
	(segment
		(start 181.585108 -81.8642)
		(end 180.745638 -81.8642)
		(width 0.089408)
		(layer "In2.Cu")
		(net "SVID_CLK0_CPU0_R")
	)
	(segment
		(start 180.673756 -81.936336)
		(end 180.420772 -82.18932)
		(width 0.089408)
		(layer "In2.Cu")
		(net "SVID_CLK0_CPU0_R")
	)
	(segment
		(start 352.5774 -114.427)
		(end 353.0854 -114.935)
		(width 0.089408)
		(layer "In2.Cu")
		(net "SVID_CLK0_CPU0_R")
	)
	(segment
		(start 195.505324 -107.969304)
		(end 186.83986 -107.969304)
		(width 0.089408)
		(layer "In2.Cu")
		(net "SVID_CLK0_CPU0_R")
	)
	(segment
		(start 197.802246 -104.110536)
		(end 196.619368 -105.293414)
		(width 0.089408)
		(layer "In2.Cu")
		(net "SVID_CLK0_CPU0_R")
	)
	(segment
		(start 186.83986 -107.969304)
		(end 181.744874 -102.874318)
		(width 0.089408)
		(layer "In2.Cu")
		(net "SVID_CLK0_CPU0_R")
	)
	(segment
		(start 177.532284 -73.824084)
		(end 176.6824 -72.9742)
		(width 0.089408)
		(layer "In2.Cu")
		(net "SVID_CLK0_CPU0_R")
	)
	(segment
		(start 180.745638 -81.8642)
		(end 180.673756 -81.936082)
		(width 0.089408)
		(layer "In2.Cu")
		(net "SVID_CLK0_CPU0_R")
	)
	(segment
		(start 335.10728 -105.611168)
		(end 335.344262 -105.374186)
		(width 0.089408)
		(layer "In2.Cu")
		(net "SVID_CLK0_CPU0_R")
	)
	(segment
		(start 177.532284 -78.131416)
		(end 177.532284 -73.824084)
		(width 0.089408)
		(layer "In2.Cu")
		(net "SVID_CLK0_CPU0_R")
	)
	(segment
		(start 180.420772 -82.18932)
		(end 178.694588 -82.18932)
		(width 0.089408)
		(layer "In2.Cu")
		(net "SVID_CLK0_CPU0_R")
	)
	(segment
		(start 202.475084 -104.110536)
		(end 197.802246 -104.110536)
		(width 0.089408)
		(layer "In2.Cu")
		(net "SVID_CLK0_CPU0_R")
	)
	(segment
		(start 182.1561 -96.870266)
		(end 182.1561 -82.435192)
		(width 0.089408)
		(layer "In2.Cu")
		(net "SVID_CLK0_CPU0_R")
	)
	(segment
		(start 335.10728 -106.4006)
		(end 335.10728 -105.611168)
		(width 0.089408)
		(layer "In2.Cu")
		(net "SVID_CLK0_CPU0_R")
	)
	(segment
		(start 202.4888 -104.09682)
		(end 202.475084 -104.110536)
		(width 0.089408)
		(layer "In2.Cu")
		(net "SVID_CLK0_CPU0_R")
	)
	(segment
		(start 351.9805 -108.0516)
		(end 352.5774 -108.6485)
		(width 0.089408)
		(layer "In2.Cu")
		(net "SVID_CLK0_CPU0_R")
	)
	(segment
		(start 196.619368 -106.85526)
		(end 195.505324 -107.969304)
		(width 0.089408)
		(layer "In2.Cu")
		(net "SVID_CLK0_CPU0_R")
	)
	(segment
		(start 176.6824 -72.9742)
		(end 176.6824 -69.04609)
		(width 0.089408)
		(layer "In2.Cu")
		(net "SVID_CLK0_CPU0_R")
	)
	(segment
		(start 181.744874 -97.281492)
		(end 182.1561 -96.870266)
		(width 0.089408)
		(layer "In2.Cu")
		(net "SVID_CLK0_CPU0_R")
	)
	(segment
		(start 178.757072 -66.971418)
		(end 178.757072 -66.020696)
		(width 0.089408)
		(layer "In2.Cu")
		(net "SVID_CLK0_CPU0_R")
	)
	(segment
		(start 180.465476 -64.312292)
		(end 182.31993 -64.312292)
		(width 0.089408)
		(layer "In2.Cu")
		(net "SVID_CLK0_CPU0_R")
	)
	(segment
		(start 342.4555 -108.0516)
		(end 351.9805 -108.0516)
		(width 0.089408)
		(layer "In2.Cu")
		(net "SVID_CLK0_CPU0_R")
	)
	(segment
		(start 352.5774 -108.6485)
		(end 352.5774 -114.427)
		(width 0.089408)
		(layer "In2.Cu")
		(net "SVID_CLK0_CPU0_R")
	)
	(segment
		(start 339.778086 -105.374186)
		(end 342.4555 -108.0516)
		(width 0.089408)
		(layer "In2.Cu")
		(net "SVID_CLK0_CPU0_R")
	)
	(segment
		(start 181.744874 -102.874318)
		(end 181.744874 -97.281492)
		(width 0.089408)
		(layer "In2.Cu")
		(net "SVID_CLK0_CPU0_R")
	)
	(segment
		(start 180.673756 -81.936082)
		(end 180.673756 -81.936336)
		(width 0.089408)
		(layer "In2.Cu")
		(net "SVID_CLK0_CPU0_R")
	)
	(segment
		(start 182.1561 -82.435192)
		(end 181.585108 -81.8642)
		(width 0.089408)
		(layer "In2.Cu")
		(net "SVID_CLK0_CPU0_R")
	)
	(segment
		(start 182.31993 -64.312292)
		(end 182.9943 -63.637922)
		(width 0.089408)
		(layer "In2.Cu")
		(net "SVID_CLK0_CPU0_R")
	)
	(segment
		(start 318.173862 -116.971826)
		(end 318.300354 -116.971826)
		(width 0.089408)
		(layer "In4.Cu")
		(net "SVID_CLK0_CPU0_R")
	)
	(segment
		(start 181.64302 -64.02578)
		(end 182.45582 -64.02578)
		(width 0.089408)
		(layer "In4.Cu")
		(net "SVID_CLK0_CPU0_R")
	)
	(segment
		(start 317.541402 -116.212874)
		(end 317.541402 -116.339366)
		(width 0.089408)
		(layer "In4.Cu")
		(net "SVID_CLK0_CPU0_R")
	)
	(segment
		(start 317.542164 -115.200176)
		(end 317.035434 -115.706906)
		(width 0.089408)
		(layer "In4.Cu")
		(net "SVID_CLK0_CPU0_R")
	)
	(segment
		(start 260.634988 -151.25446)
		(end 231.646984 -151.25446)
		(width 0.089408)
		(layer "In4.Cu")
		(net "SVID_CLK0_CPU0_R")
	)
	(segment
		(start 301.223172 -148.648674)
		(end 301.223172 -150.4061)
		(width 0.089408)
		(layer "In4.Cu")
		(net "SVID_CLK0_CPU0_R")
	)
	(segment
		(start 287.748726 -150.4061)
		(end 287.748726 -149.010624)
		(width 0.089408)
		(layer "In4.Cu")
		(net "SVID_CLK0_CPU0_R")
	)
	(segment
		(start 183.7944 -82.169254)
		(end 180.92674 -79.301594)
		(width 0.089408)
		(layer "In4.Cu")
		(net "SVID_CLK0_CPU0_R")
	)
	(segment
		(start 180.073046 -77.379322)
		(end 179.219606 -77.379322)
		(width 0.089408)
		(layer "In4.Cu")
		(net "SVID_CLK0_CPU0_R")
	)
	(segment
		(start 318.350138 -140.890752)
		(end 318.350138 -146.17954)
		(width 0.089408)
		(layer "In4.Cu")
		(net "SVID_CLK0_CPU0_R")
	)
	(segment
		(start 318.350138 -146.17954)
		(end 317.717678 -146.812)
		(width 0.089408)
		(layer "In4.Cu")
		(net "SVID_CLK0_CPU0_R")
	)
	(segment
		(start 184.437274 -104.415082)
		(end 183.7944 -103.772208)
		(width 0.089408)
		(layer "In4.Cu")
		(net "SVID_CLK0_CPU0_R")
	)
	(segment
		(start 318.806322 -117.477794)
		(end 319.313052 -116.971064)
		(width 0.089408)
		(layer "In4.Cu")
		(net "SVID_CLK0_CPU0_R")
	)
	(segment
		(start 318.048132 -115.579652)
		(end 318.048132 -115.706144)
		(width 0.089408)
		(layer "In4.Cu")
		(net "SVID_CLK0_CPU0_R")
	)
	(segment
		(start 321.369436 -124.381006)
		(end 323.269356 -126.280926)
		(width 0.089408)
		(layer "In4.Cu")
		(net "SVID_CLK0_CPU0_R")
	)
	(segment
		(start 178.671728 -76.831444)
		(end 178.671728 -75.398884)
		(width 0.089408)
		(layer "In4.Cu")
		(net "SVID_CLK0_CPU0_R")
	)
	(segment
		(start 319.566036 -117.097556)
		(end 319.566036 -117.224048)
		(width 0.089408)
		(layer "In4.Cu")
		(net "SVID_CLK0_CPU0_R")
	)
	(segment
		(start 318.67983 -117.477794)
		(end 318.806322 -117.477794)
		(width 0.089408)
		(layer "In4.Cu")
		(net "SVID_CLK0_CPU0_R")
	)
	(segment
		(start 287.80105 -148.584412)
		(end 286.447484 -147.230846)
		(width 0.089408)
		(layer "In4.Cu")
		(net "SVID_CLK0_CPU0_R")
	)
	(segment
		(start 319.059306 -117.85727)
		(end 321.369436 -120.1674)
		(width 0.089408)
		(layer "In4.Cu")
		(net "SVID_CLK0_CPU0_R")
	)
	(segment
		(start 317.035434 -115.833398)
		(end 317.161926 -115.95989)
		(width 0.089408)
		(layer "In4.Cu")
		(net "SVID_CLK0_CPU0_R")
	)
	(segment
		(start 301.223172 -150.4061)
		(end 300.374812 -151.25446)
		(width 0.089408)
		(layer "In4.Cu")
		(net "SVID_CLK0_CPU0_R")
	)
	(segment
		(start 319.439544 -116.971064)
		(end 319.566036 -117.097556)
		(width 0.089408)
		(layer "In4.Cu")
		(net "SVID_CLK0_CPU0_R")
	)
	(segment
		(start 317.288418 -115.95989)
		(end 317.795148 -115.45316)
		(width 0.089408)
		(layer "In4.Cu")
		(net "SVID_CLK0_CPU0_R")
	)
	(segment
		(start 318.04737 -116.718842)
		(end 318.04737 -116.845334)
		(width 0.089408)
		(layer "In4.Cu")
		(net "SVID_CLK0_CPU0_R")
	)
	(segment
		(start 318.427608 -115.959128)
		(end 318.5541 -116.08562)
		(width 0.089408)
		(layer "In4.Cu")
		(net "SVID_CLK0_CPU0_R")
	)
	(segment
		(start 230.850948 -148.584412)
		(end 229.6414 -147.374864)
		(width 0.089408)
		(layer "In4.Cu")
		(net "SVID_CLK0_CPU0_R")
	)
	(segment
		(start 179.219606 -77.379322)
		(end 178.671728 -76.831444)
		(width 0.089408)
		(layer "In4.Cu")
		(net "SVID_CLK0_CPU0_R")
	)
	(segment
		(start 193.477896 -146.175476)
		(end 193.477896 -116.745004)
		(width 0.089408)
		(layer "In4.Cu")
		(net "SVID_CLK0_CPU0_R")
	)
	(segment
		(start 261.20598 -150.683468)
		(end 260.634988 -151.25446)
		(width 0.089408)
		(layer "In4.Cu")
		(net "SVID_CLK0_CPU0_R")
	)
	(segment
		(start 287.80105 -148.9583)
		(end 287.80105 -148.584412)
		(width 0.089408)
		(layer "In4.Cu")
		(net "SVID_CLK0_CPU0_R")
	)
	(segment
		(start 318.5541 -116.212112)
		(end 318.04737 -116.718842)
		(width 0.089408)
		(layer "In4.Cu")
		(net "SVID_CLK0_CPU0_R")
	)
	(segment
		(start 230.798624 -149.159976)
		(end 230.850948 -149.107652)
		(width 0.089408)
		(layer "In4.Cu")
		(net "SVID_CLK0_CPU0_R")
	)
	(segment
		(start 321.892422 -128.747266)
		(end 320.76644 -128.747266)
		(width 0.089408)
		(layer "In4.Cu")
		(net "SVID_CLK0_CPU0_R")
	)
	(segment
		(start 288.597086 -151.25446)
		(end 287.748726 -150.4061)
		(width 0.089408)
		(layer "In4.Cu")
		(net "SVID_CLK0_CPU0_R")
	)
	(segment
		(start 286.447484 -147.230846)
		(end 262.802878 -147.230846)
		(width 0.089408)
		(layer "In4.Cu")
		(net "SVID_CLK0_CPU0_R")
	)
	(segment
		(start 318.048132 -115.706144)
		(end 317.541402 -116.212874)
		(width 0.089408)
		(layer "In4.Cu")
		(net "SVID_CLK0_CPU0_R")
	)
	(segment
		(start 180.0606 -65.6082)
		(end 181.64302 -64.02578)
		(width 0.089408)
		(layer "In4.Cu")
		(net "SVID_CLK0_CPU0_R")
	)
	(segment
		(start 320.09969 -129.414016)
		(end 320.09969 -139.29741)
		(width 0.089408)
		(layer "In4.Cu")
		(net "SVID_CLK0_CPU0_R")
	)
	(segment
		(start 193.477896 -116.745004)
		(end 184.437274 -107.704382)
		(width 0.089408)
		(layer "In4.Cu")
		(net "SVID_CLK0_CPU0_R")
	)
	(segment
		(start 320.76644 -128.747266)
		(end 320.09969 -129.414016)
		(width 0.089408)
		(layer "In4.Cu")
		(net "SVID_CLK0_CPU0_R")
	)
	(segment
		(start 300.374812 -151.25446)
		(end 288.597086 -151.25446)
		(width 0.089408)
		(layer "In4.Cu")
		(net "SVID_CLK0_CPU0_R")
	)
	(segment
		(start 318.5541 -116.08562)
		(end 318.5541 -116.212112)
		(width 0.089408)
		(layer "In4.Cu")
		(net "SVID_CLK0_CPU0_R")
	)
	(segment
		(start 183.7944 -103.772208)
		(end 183.7944 -82.169254)
		(width 0.089408)
		(layer "In4.Cu")
		(net "SVID_CLK0_CPU0_R")
	)
	(segment
		(start 180.92674 -78.233016)
		(end 180.073046 -77.379322)
		(width 0.089408)
		(layer "In4.Cu")
		(net "SVID_CLK0_CPU0_R")
	)
	(segment
		(start 231.646984 -151.25446)
		(end 230.798624 -150.4061)
		(width 0.089408)
		(layer "In4.Cu")
		(net "SVID_CLK0_CPU0_R")
	)
	(segment
		(start 230.850948 -149.107652)
		(end 230.850948 -148.584412)
		(width 0.089408)
		(layer "In4.Cu")
		(net "SVID_CLK0_CPU0_R")
	)
	(segment
		(start 229.6414 -147.374864)
		(end 194.677284 -147.374864)
		(width 0.089408)
		(layer "In4.Cu")
		(net "SVID_CLK0_CPU0_R")
	)
	(segment
		(start 182.45582 -64.02578)
		(end 182.9943 -63.4873)
		(width 0.089408)
		(layer "In4.Cu")
		(net "SVID_CLK0_CPU0_R")
	)
	(segment
		(start 320.09969 -139.29741)
		(end 319.815718 -139.581382)
		(width 0.089408)
		(layer "In4.Cu")
		(net "SVID_CLK0_CPU0_R")
	)
	(segment
		(start 318.301116 -115.959128)
		(end 318.427608 -115.959128)
		(width 0.089408)
		(layer "In4.Cu")
		(net "SVID_CLK0_CPU0_R")
	)
	(segment
		(start 317.794386 -116.465858)
		(end 318.301116 -115.959128)
		(width 0.089408)
		(layer "In4.Cu")
		(net "SVID_CLK0_CPU0_R")
	)
	(segment
		(start 194.677284 -147.374864)
		(end 193.477896 -146.175476)
		(width 0.089408)
		(layer "In4.Cu")
		(net "SVID_CLK0_CPU0_R")
	)
	(segment
		(start 317.224664 -114.756184)
		(end 317.542164 -115.073684)
		(width 0.089408)
		(layer "In4.Cu")
		(net "SVID_CLK0_CPU0_R")
	)
	(segment
		(start 317.795148 -115.45316)
		(end 317.92164 -115.45316)
		(width 0.089408)
		(layer "In4.Cu")
		(net "SVID_CLK0_CPU0_R")
	)
	(segment
		(start 319.815718 -139.581382)
		(end 319.659508 -139.581382)
		(width 0.089408)
		(layer "In4.Cu")
		(net "SVID_CLK0_CPU0_R")
	)
	(segment
		(start 319.060068 -116.71808)
		(end 318.553338 -117.22481)
		(width 0.089408)
		(layer "In4.Cu")
		(net "SVID_CLK0_CPU0_R")
	)
	(segment
		(start 303.059846 -146.812)
		(end 301.223172 -148.648674)
		(width 0.089408)
		(layer "In4.Cu")
		(net "SVID_CLK0_CPU0_R")
	)
	(segment
		(start 317.717678 -146.812)
		(end 303.059846 -146.812)
		(width 0.089408)
		(layer "In4.Cu")
		(net "SVID_CLK0_CPU0_R")
	)
	(segment
		(start 319.060068 -116.591588)
		(end 319.060068 -116.71808)
		(width 0.089408)
		(layer "In4.Cu")
		(net "SVID_CLK0_CPU0_R")
	)
	(segment
		(start 318.553338 -117.351302)
		(end 318.67983 -117.477794)
		(width 0.089408)
		(layer "In4.Cu")
		(net "SVID_CLK0_CPU0_R")
	)
	(segment
		(start 180.0606 -67.411346)
		(end 180.0606 -65.6082)
		(width 0.089408)
		(layer "In4.Cu")
		(net "SVID_CLK0_CPU0_R")
	)
	(segment
		(start 319.059306 -117.730778)
		(end 319.059306 -117.85727)
		(width 0.089408)
		(layer "In4.Cu")
		(net "SVID_CLK0_CPU0_R")
	)
	(segment
		(start 317.161926 -115.95989)
		(end 317.288418 -115.95989)
		(width 0.089408)
		(layer "In4.Cu")
		(net "SVID_CLK0_CPU0_R")
	)
	(segment
		(start 180.92674 -79.301594)
		(end 180.92674 -78.233016)
		(width 0.089408)
		(layer "In4.Cu")
		(net "SVID_CLK0_CPU0_R")
	)
	(segment
		(start 177.882296 -74.609452)
		(end 177.882296 -69.58965)
		(width 0.089408)
		(layer "In4.Cu")
		(net "SVID_CLK0_CPU0_R")
	)
	(segment
		(start 318.807084 -116.465096)
		(end 318.933576 -116.465096)
		(width 0.089408)
		(layer "In4.Cu")
		(net "SVID_CLK0_CPU0_R")
	)
	(segment
		(start 317.541402 -116.339366)
		(end 317.667894 -116.465858)
		(width 0.089408)
		(layer "In4.Cu")
		(net "SVID_CLK0_CPU0_R")
	)
	(segment
		(start 319.566036 -117.224048)
		(end 319.059306 -117.730778)
		(width 0.089408)
		(layer "In4.Cu")
		(net "SVID_CLK0_CPU0_R")
	)
	(segment
		(start 318.300354 -116.971826)
		(end 318.807084 -116.465096)
		(width 0.089408)
		(layer "In4.Cu")
		(net "SVID_CLK0_CPU0_R")
	)
	(segment
		(start 315.823346 -101.178106)
		(end 315.3537 -101.647752)
		(width 0.089408)
		(layer "In4.Cu")
		(net "SVID_CLK0_CPU0_R")
	)
	(segment
		(start 319.659508 -139.581382)
		(end 318.350138 -140.890752)
		(width 0.089408)
		(layer "In4.Cu")
		(net "SVID_CLK0_CPU0_R")
	)
	(segment
		(start 315.3537 -111.909098)
		(end 317.224664 -113.780062)
		(width 0.089408)
		(layer "In4.Cu")
		(net "SVID_CLK0_CPU0_R")
	)
	(segment
		(start 318.933576 -116.465096)
		(end 319.060068 -116.591588)
		(width 0.089408)
		(layer "In4.Cu")
		(net "SVID_CLK0_CPU0_R")
	)
	(segment
		(start 321.369436 -120.1674)
		(end 321.369436 -124.381006)
		(width 0.089408)
		(layer "In4.Cu")
		(net "SVID_CLK0_CPU0_R")
	)
	(segment
		(start 319.313052 -116.971064)
		(end 319.439544 -116.971064)
		(width 0.089408)
		(layer "In4.Cu")
		(net "SVID_CLK0_CPU0_R")
	)
	(segment
		(start 177.882296 -69.58965)
		(end 180.0606 -67.411346)
		(width 0.089408)
		(layer "In4.Cu")
		(net "SVID_CLK0_CPU0_R")
	)
	(segment
		(start 262.802878 -147.230846)
		(end 261.20598 -148.827744)
		(width 0.089408)
		(layer "In4.Cu")
		(net "SVID_CLK0_CPU0_R")
	)
	(segment
		(start 318.553338 -117.22481)
		(end 318.553338 -117.351302)
		(width 0.089408)
		(layer "In4.Cu")
		(net "SVID_CLK0_CPU0_R")
	)
	(segment
		(start 287.748726 -149.010624)
		(end 287.80105 -148.9583)
		(width 0.089408)
		(layer "In4.Cu")
		(net "SVID_CLK0_CPU0_R")
	)
	(segment
		(start 318.04737 -116.845334)
		(end 318.173862 -116.971826)
		(width 0.089408)
		(layer "In4.Cu")
		(net "SVID_CLK0_CPU0_R")
	)
	(segment
		(start 317.035434 -115.706906)
		(end 317.035434 -115.833398)
		(width 0.089408)
		(layer "In4.Cu")
		(net "SVID_CLK0_CPU0_R")
	)
	(segment
		(start 323.269356 -126.280926)
		(end 323.269356 -127.370332)
		(width 0.089408)
		(layer "In4.Cu")
		(net "SVID_CLK0_CPU0_R")
	)
	(segment
		(start 178.671728 -75.398884)
		(end 177.882296 -74.609452)
		(width 0.089408)
		(layer "In4.Cu")
		(net "SVID_CLK0_CPU0_R")
	)
	(segment
		(start 317.224664 -113.780062)
		(end 317.224664 -114.756184)
		(width 0.089408)
		(layer "In4.Cu")
		(net "SVID_CLK0_CPU0_R")
	)
	(segment
		(start 184.437274 -107.704382)
		(end 184.437274 -104.415082)
		(width 0.089408)
		(layer "In4.Cu")
		(net "SVID_CLK0_CPU0_R")
	)
	(segment
		(start 261.20598 -148.827744)
		(end 261.20598 -150.683468)
		(width 0.089408)
		(layer "In4.Cu")
		(net "SVID_CLK0_CPU0_R")
	)
	(segment
		(start 317.667894 -116.465858)
		(end 317.794386 -116.465858)
		(width 0.089408)
		(layer "In4.Cu")
		(net "SVID_CLK0_CPU0_R")
	)
	(segment
		(start 230.798624 -150.4061)
		(end 230.798624 -149.159976)
		(width 0.089408)
		(layer "In4.Cu")
		(net "SVID_CLK0_CPU0_R")
	)
	(segment
		(start 317.92164 -115.45316)
		(end 318.048132 -115.579652)
		(width 0.089408)
		(layer "In4.Cu")
		(net "SVID_CLK0_CPU0_R")
	)
	(segment
		(start 315.3537 -101.647752)
		(end 315.3537 -111.909098)
		(width 0.089408)
		(layer "In4.Cu")
		(net "SVID_CLK0_CPU0_R")
	)
	(segment
		(start 317.542164 -115.073684)
		(end 317.542164 -115.200176)
		(width 0.089408)
		(layer "In4.Cu")
		(net "SVID_CLK0_CPU0_R")
	)
	(segment
		(start 323.269356 -127.370332)
		(end 321.892422 -128.747266)
		(width 0.089408)
		(layer "In4.Cu")
		(net "SVID_CLK0_CPU0_R")
	)
	(segment
		(start 352.68154 -114.935)
		(end 353.0854 -114.935)
		(width 0.089408)
		(layer "In9.Cu")
		(net "SVID_CLK0_CPU0_R")
	)
	(segment
		(start 345.0209 -113.490502)
		(end 345.0209 -115.194334)
		(width 0.089408)
		(layer "In9.Cu")
		(net "SVID_CLK0_CPU0_R")
	)
	(segment
		(start 343.0651 -99.43719)
		(end 341.742014 -100.760276)
		(width 0.089408)
		(layer "In9.Cu")
		(net "SVID_CLK0_CPU0_R")
	)
	(segment
		(start 345.0209 -115.194334)
		(end 346.11691 -116.290344)
		(width 0.089408)
		(layer "In9.Cu")
		(net "SVID_CLK0_CPU0_R")
	)
	(segment
		(start 341.742014 -100.760276)
		(end 341.742014 -103.72725)
		(width 0.089408)
		(layer "In9.Cu")
		(net "SVID_CLK0_CPU0_R")
	)
	(segment
		(start 347.03004 -116.290344)
		(end 347.59265 -116.852954)
		(width 0.089408)
		(layer "In9.Cu")
		(net "SVID_CLK0_CPU0_R")
	)
	(segment
		(start 350.763586 -116.852954)
		(end 352.68154 -114.935)
		(width 0.089408)
		(layer "In9.Cu")
		(net "SVID_CLK0_CPU0_R")
	)
	(segment
		(start 345.532456 -112.978946)
		(end 345.0209 -113.490502)
		(width 0.089408)
		(layer "In9.Cu")
		(net "SVID_CLK0_CPU0_R")
	)
	(segment
		(start 341.742014 -103.72725)
		(end 345.532456 -107.517692)
		(width 0.089408)
		(layer "In9.Cu")
		(net "SVID_CLK0_CPU0_R")
	)
	(segment
		(start 343.0651 -90.792046)
		(end 343.0651 -99.43719)
		(width 0.089408)
		(layer "In9.Cu")
		(net "SVID_CLK0_CPU0_R")
	)
	(segment
		(start 339.712554 -87.4395)
		(end 343.0651 -90.792046)
		(width 0.089408)
		(layer "In9.Cu")
		(net "SVID_CLK0_CPU0_R")
	)
	(segment
		(start 346.11691 -116.290344)
		(end 347.03004 -116.290344)
		(width 0.089408)
		(layer "In9.Cu")
		(net "SVID_CLK0_CPU0_R")
	)
	(segment
		(start 345.532456 -107.517692)
		(end 345.532456 -112.978946)
		(width 0.089408)
		(layer "In9.Cu")
		(net "SVID_CLK0_CPU0_R")
	)
	(segment
		(start 339.1535 -87.4395)
		(end 339.712554 -87.4395)
		(width 0.089408)
		(layer "In9.Cu")
		(net "SVID_CLK0_CPU0_R")
	)
	(segment
		(start 347.59265 -116.852954)
		(end 350.763586 -116.852954)
		(width 0.089408)
		(layer "In9.Cu")
		(net "SVID_CLK0_CPU0_R")
	)
	(segment
		(start 316.650878 -101.195378)
		(end 316.633606 -101.178106)
		(width 0.089408)
		(layer "In11.Cu")
		(net "SVID_CLK0_CPU0_R")
	)
	(segment
		(start 334.674972 -105.968292)
		(end 330.076048 -105.968292)
		(width 0.089408)
		(layer "In11.Cu")
		(net "SVID_CLK0_CPU0_R")
	)
	(segment
		(start 335.10728 -106.4006)
		(end 334.674972 -105.968292)
		(width 0.089408)
		(layer "In11.Cu")
		(net "SVID_CLK0_CPU0_R")
	)
	(segment
		(start 327.37044 -103.262684)
		(end 323.73824 -103.262684)
		(width 0.089408)
		(layer "In11.Cu")
		(net "SVID_CLK0_CPU0_R")
	)
	(segment
		(start 323.73824 -103.262684)
		(end 321.744848 -101.269292)
		(width 0.089408)
		(layer "In11.Cu")
		(net "SVID_CLK0_CPU0_R")
	)
	(segment
		(start 316.633606 -101.178106)
		(end 315.823346 -101.178106)
		(width 0.089408)
		(layer "In11.Cu")
		(net "SVID_CLK0_CPU0_R")
	)
	(segment
		(start 330.076048 -105.968292)
		(end 327.37044 -103.262684)
		(width 0.089408)
		(layer "In11.Cu")
		(net "SVID_CLK0_CPU0_R")
	)
	(segment
		(start 316.665356 -101.195378)
		(end 316.650878 -101.195378)
		(width 0.089408)
		(layer "In11.Cu")
		(net "SVID_CLK0_CPU0_R")
	)
	(segment
		(start 316.73927 -101.269292)
		(end 316.665356 -101.195378)
		(width 0.089408)
		(layer "In11.Cu")
		(net "SVID_CLK0_CPU0_R")
	)
	(segment
		(start 321.744848 -101.269292)
		(end 316.73927 -101.269292)
		(width 0.089408)
		(layer "In11.Cu")
		(net "SVID_CLK0_CPU0_R")
	)
	(segment
		(start 268.806676 -90.26144)
		(end 269.416276 -90.26144)
		(width 0.10795)
		(layer "F.Cu")
		(net "SVID_CLK0_CPU0")
	)
	(via
		(at 231.25557 -86.523576)
		(size 0.6604)
		(drill 0.3302)
		(layers "F.Cu" "B.Cu")
		(net "SVID_CLK0_CPU0")
	)
	(via
		(at 269.416276 -90.26144)
		(size 0.508)
		(drill 0.254)
		(layers "F.Cu" "B.Cu")
		(net "SVID_CLK0_CPU0")
	)
	(segment
		(start 236.236002 -85.222334)
		(end 236.705394 -85.222334)
		(width 0.10795)
		(layer "B.Cu")
		(net "SVID_CLK0_CPU0")
	)
	(segment
		(start 264.250424 -88.576404)
		(end 267.593064 -88.576404)
		(width 0.10795)
		(layer "B.Cu")
		(net "SVID_CLK0_CPU0")
	)
	(segment
		(start 262.83539 -87.583264)
		(end 263.494266 -88.24214)
		(width 0.10795)
		(layer "B.Cu")
		(net "SVID_CLK0_CPU0")
	)
	(segment
		(start 248.340372 -84.3534)
		(end 248.666 -84.3534)
		(width 0.10795)
		(layer "B.Cu")
		(net "SVID_CLK0_CPU0")
	)
	(segment
		(start 226.961192 -88.88222)
		(end 228.559868 -88.88222)
		(width 0.10795)
		(layer "B.Cu")
		(net "SVID_CLK0_CPU0")
	)
	(segment
		(start 245.2116 -84.349844)
		(end 245.699534 -84.837778)
		(width 0.10795)
		(layer "B.Cu")
		(net "SVID_CLK0_CPU0")
	)
	(segment
		(start 258.95046 -88.24468)
		(end 259.36448 -87.83066)
		(width 0.10795)
		(layer "B.Cu")
		(net "SVID_CLK0_CPU0")
	)
	(segment
		(start 231.25557 -86.477856)
		(end 231.906826 -85.8266)
		(width 0.10795)
		(layer "B.Cu")
		(net "SVID_CLK0_CPU0")
	)
	(segment
		(start 256.043684 -86.75116)
		(end 256.392426 -86.75116)
		(width 0.10795)
		(layer "B.Cu")
		(net "SVID_CLK0_CPU0")
	)
	(segment
		(start 231.906826 -85.8266)
		(end 232.384854 -85.8266)
		(width 0.10795)
		(layer "B.Cu")
		(net "SVID_CLK0_CPU0")
	)
	(segment
		(start 237.953042 -85.222334)
		(end 238.553244 -85.222334)
		(width 0.10795)
		(layer "B.Cu")
		(net "SVID_CLK0_CPU0")
	)
	(segment
		(start 237.159546 -84.768182)
		(end 237.49889 -84.768182)
		(width 0.10795)
		(layer "B.Cu")
		(net "SVID_CLK0_CPU0")
	)
	(segment
		(start 239.21593 -84.898992)
		(end 239.539272 -85.222334)
		(width 0.10795)
		(layer "B.Cu")
		(net "SVID_CLK0_CPU0")
	)
	(segment
		(start 228.559868 -88.88222)
		(end 228.85654 -88.585548)
		(width 0.10795)
		(layer "B.Cu")
		(net "SVID_CLK0_CPU0")
	)
	(segment
		(start 263.91616 -88.24214)
		(end 264.250424 -88.576404)
		(width 0.10795)
		(layer "B.Cu")
		(net "SVID_CLK0_CPU0")
	)
	(segment
		(start 234.64012 -85.222334)
		(end 234.970574 -85.222334)
		(width 0.10795)
		(layer "B.Cu")
		(net "SVID_CLK0_CPU0")
	)
	(segment
		(start 234.112054 -85.7504)
		(end 234.64012 -85.222334)
		(width 0.10795)
		(layer "B.Cu")
		(net "SVID_CLK0_CPU0")
	)
	(segment
		(start 233.299254 -85.3694)
		(end 233.680254 -85.7504)
		(width 0.10795)
		(layer "B.Cu")
		(net "SVID_CLK0_CPU0")
	)
	(segment
		(start 234.970574 -85.222334)
		(end 235.433616 -84.759292)
		(width 0.10795)
		(layer "B.Cu")
		(net "SVID_CLK0_CPU0")
	)
	(segment
		(start 244.898418 -84.349844)
		(end 245.2116 -84.349844)
		(width 0.10795)
		(layer "B.Cu")
		(net "SVID_CLK0_CPU0")
	)
	(segment
		(start 242.251992 -84.777326)
		(end 242.771676 -84.777326)
		(width 0.10795)
		(layer "B.Cu")
		(net "SVID_CLK0_CPU0")
	)
	(segment
		(start 269.2781 -90.26144)
		(end 269.416276 -90.26144)
		(width 0.10795)
		(layer "B.Cu")
		(net "SVID_CLK0_CPU0")
	)
	(segment
		(start 259.36448 -87.83066)
		(end 259.7658 -87.83066)
		(width 0.10795)
		(layer "B.Cu")
		(net "SVID_CLK0_CPU0")
	)
	(segment
		(start 229.193598 -88.585548)
		(end 231.25557 -86.523576)
		(width 0.10795)
		(layer "B.Cu")
		(net "SVID_CLK0_CPU0")
	)
	(segment
		(start 262.349742 -87.30488)
		(end 262.628126 -87.583264)
		(width 0.10795)
		(layer "B.Cu")
		(net "SVID_CLK0_CPU0")
	)
	(segment
		(start 235.77296 -84.759292)
		(end 236.236002 -85.222334)
		(width 0.10795)
		(layer "B.Cu")
		(net "SVID_CLK0_CPU0")
	)
	(segment
		(start 238.553244 -85.222334)
		(end 238.876586 -84.898992)
		(width 0.10795)
		(layer "B.Cu")
		(net "SVID_CLK0_CPU0")
	)
	(segment
		(start 253.7968 -85.2424)
		(end 254.33274 -85.77834)
		(width 0.10795)
		(layer "B.Cu")
		(net "SVID_CLK0_CPU0")
	)
	(segment
		(start 240.602516 -84.76361)
		(end 240.94186 -84.76361)
		(width 0.10795)
		(layer "B.Cu")
		(net "SVID_CLK0_CPU0")
	)
	(segment
		(start 240.143792 -85.222334)
		(end 240.602516 -84.76361)
		(width 0.10795)
		(layer "B.Cu")
		(net "SVID_CLK0_CPU0")
	)
	(segment
		(start 262.628126 -87.583264)
		(end 262.83539 -87.583264)
		(width 0.10795)
		(layer "B.Cu")
		(net "SVID_CLK0_CPU0")
	)
	(segment
		(start 225.96475 -92.49791)
		(end 225.96475 -89.878662)
		(width 0.10795)
		(layer "B.Cu")
		(net "SVID_CLK0_CPU0")
	)
	(segment
		(start 228.85654 -88.585548)
		(end 229.193598 -88.585548)
		(width 0.10795)
		(layer "B.Cu")
		(net "SVID_CLK0_CPU0")
	)
	(segment
		(start 254.713994 -85.77834)
		(end 255.195832 -86.260178)
		(width 0.10795)
		(layer "B.Cu")
		(net "SVID_CLK0_CPU0")
	)
	(segment
		(start 206.796386 -104.276144)
		(end 214.186516 -104.276144)
		(width 0.10795)
		(layer "B.Cu")
		(net "SVID_CLK0_CPU0")
	)
	(segment
		(start 245.699534 -84.837778)
		(end 246.145558 -84.837778)
		(width 0.10795)
		(layer "B.Cu")
		(net "SVID_CLK0_CPU0")
	)
	(segment
		(start 255.195832 -86.260178)
		(end 255.552702 -86.260178)
		(width 0.10795)
		(layer "B.Cu")
		(net "SVID_CLK0_CPU0")
	)
	(segment
		(start 247.869202 -84.82457)
		(end 248.340372 -84.3534)
		(width 0.10795)
		(layer "B.Cu")
		(net "SVID_CLK0_CPU0")
	)
	(segment
		(start 244.40515 -84.843112)
		(end 244.898418 -84.349844)
		(width 0.10795)
		(layer "B.Cu")
		(net "SVID_CLK0_CPU0")
	)
	(segment
		(start 205.74 -104.775)
		(end 205.74127 -104.77627)
		(width 0.10795)
		(layer "B.Cu")
		(net "SVID_CLK0_CPU0")
	)
	(segment
		(start 232.384854 -85.8266)
		(end 232.842054 -85.3694)
		(width 0.10795)
		(layer "B.Cu")
		(net "SVID_CLK0_CPU0")
	)
	(segment
		(start 247.400318 -84.82457)
		(end 247.869202 -84.82457)
		(width 0.10795)
		(layer "B.Cu")
		(net "SVID_CLK0_CPU0")
	)
	(segment
		(start 250.947428 -84.8106)
		(end 251.3076 -84.8106)
		(width 0.10795)
		(layer "B.Cu")
		(net "SVID_CLK0_CPU0")
	)
	(segment
		(start 256.885186 -87.24392)
		(end 257.2639 -87.24392)
		(width 0.10795)
		(layer "B.Cu")
		(net "SVID_CLK0_CPU0")
	)
	(segment
		(start 235.433616 -84.759292)
		(end 235.77296 -84.759292)
		(width 0.10795)
		(layer "B.Cu")
		(net "SVID_CLK0_CPU0")
	)
	(segment
		(start 243.543328 -84.387944)
		(end 243.998496 -84.843112)
		(width 0.10795)
		(layer "B.Cu")
		(net "SVID_CLK0_CPU0")
	)
	(segment
		(start 257.773678 -87.753698)
		(end 258.11861 -87.753698)
		(width 0.10795)
		(layer "B.Cu")
		(net "SVID_CLK0_CPU0")
	)
	(segment
		(start 249.490992 -84.7852)
		(end 249.96521 -84.310982)
		(width 0.10795)
		(layer "B.Cu")
		(net "SVID_CLK0_CPU0")
	)
	(segment
		(start 260.29158 -87.30488)
		(end 262.349742 -87.30488)
		(width 0.10795)
		(layer "B.Cu")
		(net "SVID_CLK0_CPU0")
	)
	(segment
		(start 258.11861 -87.753698)
		(end 258.609592 -88.24468)
		(width 0.10795)
		(layer "B.Cu")
		(net "SVID_CLK0_CPU0")
	)
	(segment
		(start 243.161058 -84.387944)
		(end 243.543328 -84.387944)
		(width 0.10795)
		(layer "B.Cu")
		(net "SVID_CLK0_CPU0")
	)
	(segment
		(start 243.998496 -84.843112)
		(end 244.40515 -84.843112)
		(width 0.10795)
		(layer "B.Cu")
		(net "SVID_CLK0_CPU0")
	)
	(segment
		(start 249.0978 -84.7852)
		(end 249.490992 -84.7852)
		(width 0.10795)
		(layer "B.Cu")
		(net "SVID_CLK0_CPU0")
	)
	(segment
		(start 246.604536 -84.3788)
		(end 246.954548 -84.3788)
		(width 0.10795)
		(layer "B.Cu")
		(net "SVID_CLK0_CPU0")
	)
	(segment
		(start 258.609592 -88.24468)
		(end 258.95046 -88.24468)
		(width 0.10795)
		(layer "B.Cu")
		(net "SVID_CLK0_CPU0")
	)
	(segment
		(start 238.876586 -84.898992)
		(end 239.21593 -84.898992)
		(width 0.10795)
		(layer "B.Cu")
		(net "SVID_CLK0_CPU0")
	)
	(segment
		(start 259.7658 -87.83066)
		(end 260.29158 -87.30488)
		(width 0.10795)
		(layer "B.Cu")
		(net "SVID_CLK0_CPU0")
	)
	(segment
		(start 236.705394 -85.222334)
		(end 237.159546 -84.768182)
		(width 0.10795)
		(layer "B.Cu")
		(net "SVID_CLK0_CPU0")
	)
	(segment
		(start 246.954548 -84.3788)
		(end 247.400318 -84.82457)
		(width 0.10795)
		(layer "B.Cu")
		(net "SVID_CLK0_CPU0")
	)
	(segment
		(start 205.74127 -104.77627)
		(end 206.29626 -104.77627)
		(width 0.10795)
		(layer "B.Cu")
		(net "SVID_CLK0_CPU0")
	)
	(segment
		(start 248.666 -84.3534)
		(end 249.0978 -84.7852)
		(width 0.10795)
		(layer "B.Cu")
		(net "SVID_CLK0_CPU0")
	)
	(segment
		(start 249.96521 -84.310982)
		(end 250.44781 -84.310982)
		(width 0.10795)
		(layer "B.Cu")
		(net "SVID_CLK0_CPU0")
	)
	(segment
		(start 251.3076 -84.8106)
		(end 251.7394 -84.3788)
		(width 0.10795)
		(layer "B.Cu")
		(net "SVID_CLK0_CPU0")
	)
	(segment
		(start 267.593064 -88.576404)
		(end 269.2781 -90.26144)
		(width 0.10795)
		(layer "B.Cu")
		(net "SVID_CLK0_CPU0")
	)
	(segment
		(start 214.186516 -104.276144)
		(end 225.96475 -92.49791)
		(width 0.10795)
		(layer "B.Cu")
		(net "SVID_CLK0_CPU0")
	)
	(segment
		(start 251.7394 -84.3788)
		(end 252.0696 -84.3788)
		(width 0.10795)
		(layer "B.Cu")
		(net "SVID_CLK0_CPU0")
	)
	(segment
		(start 237.49889 -84.768182)
		(end 237.953042 -85.222334)
		(width 0.10795)
		(layer "B.Cu")
		(net "SVID_CLK0_CPU0")
	)
	(segment
		(start 253.4666 -85.2424)
		(end 253.7968 -85.2424)
		(width 0.10795)
		(layer "B.Cu")
		(net "SVID_CLK0_CPU0")
	)
	(segment
		(start 231.25557 -86.523576)
		(end 231.25557 -86.477856)
		(width 0.10795)
		(layer "B.Cu")
		(net "SVID_CLK0_CPU0")
	)
	(segment
		(start 256.392426 -86.75116)
		(end 256.885186 -87.24392)
		(width 0.10795)
		(layer "B.Cu")
		(net "SVID_CLK0_CPU0")
	)
	(segment
		(start 263.494266 -88.24214)
		(end 263.91616 -88.24214)
		(width 0.10795)
		(layer "B.Cu")
		(net "SVID_CLK0_CPU0")
	)
	(segment
		(start 206.29626 -104.77627)
		(end 206.796386 -104.276144)
		(width 0.10795)
		(layer "B.Cu")
		(net "SVID_CLK0_CPU0")
	)
	(segment
		(start 254.33274 -85.77834)
		(end 254.713994 -85.77834)
		(width 0.10795)
		(layer "B.Cu")
		(net "SVID_CLK0_CPU0")
	)
	(segment
		(start 246.145558 -84.837778)
		(end 246.604536 -84.3788)
		(width 0.10795)
		(layer "B.Cu")
		(net "SVID_CLK0_CPU0")
	)
	(segment
		(start 241.806984 -85.222334)
		(end 242.251992 -84.777326)
		(width 0.10795)
		(layer "B.Cu")
		(net "SVID_CLK0_CPU0")
	)
	(segment
		(start 242.771676 -84.777326)
		(end 243.161058 -84.387944)
		(width 0.10795)
		(layer "B.Cu")
		(net "SVID_CLK0_CPU0")
	)
	(segment
		(start 253.0348 -84.8106)
		(end 253.4666 -85.2424)
		(width 0.10795)
		(layer "B.Cu")
		(net "SVID_CLK0_CPU0")
	)
	(segment
		(start 250.44781 -84.310982)
		(end 250.947428 -84.8106)
		(width 0.10795)
		(layer "B.Cu")
		(net "SVID_CLK0_CPU0")
	)
	(segment
		(start 252.5014 -84.8106)
		(end 253.0348 -84.8106)
		(width 0.10795)
		(layer "B.Cu")
		(net "SVID_CLK0_CPU0")
	)
	(segment
		(start 241.400584 -85.222334)
		(end 241.806984 -85.222334)
		(width 0.10795)
		(layer "B.Cu")
		(net "SVID_CLK0_CPU0")
	)
	(segment
		(start 252.0696 -84.3788)
		(end 252.5014 -84.8106)
		(width 0.10795)
		(layer "B.Cu")
		(net "SVID_CLK0_CPU0")
	)
	(segment
		(start 233.680254 -85.7504)
		(end 234.112054 -85.7504)
		(width 0.10795)
		(layer "B.Cu")
		(net "SVID_CLK0_CPU0")
	)
	(segment
		(start 257.2639 -87.24392)
		(end 257.773678 -87.753698)
		(width 0.10795)
		(layer "B.Cu")
		(net "SVID_CLK0_CPU0")
	)
	(segment
		(start 239.539272 -85.222334)
		(end 240.143792 -85.222334)
		(width 0.10795)
		(layer "B.Cu")
		(net "SVID_CLK0_CPU0")
	)
	(segment
		(start 255.552702 -86.260178)
		(end 256.043684 -86.75116)
		(width 0.10795)
		(layer "B.Cu")
		(net "SVID_CLK0_CPU0")
	)
	(segment
		(start 232.842054 -85.3694)
		(end 233.299254 -85.3694)
		(width 0.10795)
		(layer "B.Cu")
		(net "SVID_CLK0_CPU0")
	)
	(segment
		(start 225.96475 -89.878662)
		(end 226.961192 -88.88222)
		(width 0.10795)
		(layer "B.Cu")
		(net "SVID_CLK0_CPU0")
	)
	(segment
		(start 240.94186 -84.76361)
		(end 241.400584 -85.222334)
		(width 0.10795)
		(layer "B.Cu")
		(net "SVID_CLK0_CPU0")
	)
	(segment
		(start -0.726948 -127.365252)
		(end -1.27 -126.8222)
		(width 0.10795)
		(layer "F.Cu")
		(net "SVID_ALERT_PVDDQ_KLM")
	)
	(segment
		(start -1.27 -126.8222)
		(end -1.69164 -126.8222)
		(width 0.10795)
		(layer "F.Cu")
		(net "SVID_ALERT_PVDDQ_KLM")
	)
	(segment
		(start -0.3937 -127.365252)
		(end -0.726948 -127.365252)
		(width 0.10795)
		(layer "F.Cu")
		(net "SVID_ALERT_PVDDQ_KLM")
	)
	(segment
		(start -1.69164 -126.8222)
		(end -2.5146 -126.8222)
		(width 0.10795)
		(layer "F.Cu")
		(net "SVID_ALERT_PVDDQ_KLM")
	)
	(via
		(at -1.69164 -126.8222)
		(size 0.508)
		(drill 0.254)
		(layers "F.Cu" "B.Cu")
		(net "SVID_ALERT_PVDDQ_KLM")
	)
	(segment
		(start 9.585706 -3.355848)
		(end 9.433052 -3.203194)
		(width 0.10795)
		(layer "F.Cu")
		(net "SVID_ALERT_PVDDQ_GHJ")
	)
	(segment
		(start 9.433052 -3.203194)
		(end 9.433052 -2.20345)
		(width 0.10795)
		(layer "F.Cu")
		(net "SVID_ALERT_PVDDQ_GHJ")
	)
	(segment
		(start 361.74934 -138.764518)
		(end 362.194348 -138.764518)
		(width 0.10795)
		(layer "F.Cu")
		(net "SVID_ALERT_PVDDQ_DEF")
	)
	(segment
		(start 363.024166 -139.30757)
		(end 363.87024 -139.30757)
		(width 0.10795)
		(layer "F.Cu")
		(net "SVID_ALERT_PVDDQ_DEF")
	)
	(segment
		(start 362.7374 -139.30757)
		(end 363.024166 -139.30757)
		(width 0.10795)
		(layer "F.Cu")
		(net "SVID_ALERT_PVDDQ_DEF")
	)
	(segment
		(start 362.194348 -138.764518)
		(end 362.7374 -139.30757)
		(width 0.10795)
		(layer "F.Cu")
		(net "SVID_ALERT_PVDDQ_DEF")
	)
	(via
		(at 363.024166 -139.30757)
		(size 0.508)
		(drill 0.254)
		(layers "F.Cu" "B.Cu")
		(net "SVID_ALERT_PVDDQ_DEF")
	)
	(segment
		(start 339.5726 -15.6464)
		(end 339.4202 -15.494)
		(width 0.10795)
		(layer "F.Cu")
		(net "SVID_ALERT_PVDDQ_ABC")
	)
	(segment
		(start 339.4202 -15.494)
		(end 338.836 -15.494)
		(width 0.10795)
		(layer "F.Cu")
		(net "SVID_ALERT_PVDDQ_ABC")
	)
	(segment
		(start 340.451948 -14.767052)
		(end 339.5726 -15.6464)
		(width 0.10795)
		(layer "F.Cu")
		(net "SVID_ALERT_PVDDQ_ABC")
	)
	(segment
		(start 342.2269 -14.767052)
		(end 340.451948 -14.767052)
		(width 0.10795)
		(layer "F.Cu")
		(net "SVID_ALERT_PVDDQ_ABC")
	)
	(via
		(at 339.5726 -15.6464)
		(size 0.508)
		(drill 0.254)
		(layers "F.Cu" "B.Cu")
		(net "SVID_ALERT_PVDDQ_ABC")
	)
	(segment
		(start -3.4036 -126.8222)
		(end -4.05384 -126.8222)
		(width 0.10795)
		(layer "F.Cu")
		(net "SVID_ALERT1_CPU1_R_N")
	)
	(segment
		(start 37.695886 -107.248706)
		(end 37.802312 -107.355132)
		(width 0.10795)
		(layer "F.Cu")
		(net "SVID_ALERT1_CPU1_R_N")
	)
	(segment
		(start 187.96381 -113.660682)
		(end 187.942982 -113.639854)
		(width 0.10795)
		(layer "F.Cu")
		(net "SVID_ALERT1_CPU1_R_N")
	)
	(segment
		(start 187.4774 -114.3)
		(end 187.96381 -113.81359)
		(width 0.10795)
		(layer "F.Cu")
		(net "SVID_ALERT1_CPU1_R_N")
	)
	(segment
		(start 37.802312 -107.355132)
		(end 38.433756 -107.355132)
		(width 0.10795)
		(layer "F.Cu")
		(net "SVID_ALERT1_CPU1_R_N")
	)
	(segment
		(start 187.475114 -114.28095)
		(end 187.4774 -114.3)
		(width 0.10795)
		(layer "F.Cu")
		(net "SVID_ALERT1_CPU1_R_N")
	)
	(segment
		(start -4.05384 -126.8222)
		(end -4.258564 -127.026924)
		(width 0.10795)
		(layer "F.Cu")
		(net "SVID_ALERT1_CPU1_R_N")
	)
	(segment
		(start 187.96381 -113.81359)
		(end 187.96381 -113.660682)
		(width 0.10795)
		(layer "F.Cu")
		(net "SVID_ALERT1_CPU1_R_N")
	)
	(segment
		(start 9.585706 -4.953254)
		(end 9.585706 -4.244848)
		(width 0.10795)
		(layer "F.Cu")
		(net "SVID_ALERT1_CPU1_R_N")
	)
	(via
		(at 37.695886 -107.248706)
		(size 0.508)
		(drill 0.254)
		(layers "F.Cu" "B.Cu")
		(net "SVID_ALERT1_CPU1_R_N")
	)
	(via
		(at -4.258564 -127.026924)
		(size 0.508)
		(drill 0.254)
		(layers "F.Cu" "B.Cu")
		(net "SVID_ALERT1_CPU1_R_N")
	)
	(via
		(at 9.585706 -4.953254)
		(size 0.508)
		(drill 0.254)
		(layers "F.Cu" "B.Cu")
		(net "SVID_ALERT1_CPU1_R_N")
	)
	(via
		(at 172.7962 -123.3678)
		(size 0.508)
		(drill 0.254)
		(layers "F.Cu" "B.Cu")
		(net "SVID_ALERT1_CPU1_R_N")
	)
	(via
		(at 187.942982 -113.639854)
		(size 0.508)
		(drill 0.254)
		(layers "F.Cu" "B.Cu")
		(net "SVID_ALERT1_CPU1_R_N")
	)
	(segment
		(start 37.873686 -107.807506)
		(end 38.440614 -107.807506)
		(width 0.10795)
		(layer "B.Cu")
		(net "SVID_ALERT1_CPU1_R_N")
	)
	(segment
		(start 37.695886 -107.248706)
		(end 37.695886 -107.629706)
		(width 0.10795)
		(layer "B.Cu")
		(net "SVID_ALERT1_CPU1_R_N")
	)
	(segment
		(start 37.695886 -107.629706)
		(end 37.873686 -107.807506)
		(width 0.10795)
		(layer "B.Cu")
		(net "SVID_ALERT1_CPU1_R_N")
	)
	(segment
		(start 9.474962 -90.826082)
		(end 9.474962 -103.422196)
		(width 0.089408)
		(layer "In2.Cu")
		(net "SVID_ALERT1_CPU1_R_N")
	)
	(segment
		(start 12.03198 -41.055544)
		(end -0.756412 -41.055544)
		(width 0.089408)
		(layer "In2.Cu")
		(net "SVID_ALERT1_CPU1_R_N")
	)
	(segment
		(start 13.8176 -22.5806)
		(end 13.8176 -39.269924)
		(width 0.089408)
		(layer "In2.Cu")
		(net "SVID_ALERT1_CPU1_R_N")
	)
	(segment
		(start -0.756412 -41.055544)
		(end -5.212842 -45.511974)
		(width 0.089408)
		(layer "In2.Cu")
		(net "SVID_ALERT1_CPU1_R_N")
	)
	(segment
		(start -5.044694 -126.240794)
		(end -4.258564 -127.026924)
		(width 0.089408)
		(layer "In2.Cu")
		(net "SVID_ALERT1_CPU1_R_N")
	)
	(segment
		(start -3.110738 -62.624716)
		(end -3.110738 -76.549758)
		(width 0.089408)
		(layer "In2.Cu")
		(net "SVID_ALERT1_CPU1_R_N")
	)
	(segment
		(start -4.881372 -78.320392)
		(end -4.881372 -86.735666)
		(width 0.089408)
		(layer "In2.Cu")
		(net "SVID_ALERT1_CPU1_R_N")
	)
	(segment
		(start -2.447036 -89.170002)
		(end 7.818882 -89.170002)
		(width 0.089408)
		(layer "In2.Cu")
		(net "SVID_ALERT1_CPU1_R_N")
	)
	(segment
		(start 21.061426 -6.185916)
		(end 21.400262 -6.524752)
		(width 0.089408)
		(layer "In2.Cu")
		(net "SVID_ALERT1_CPU1_R_N")
	)
	(segment
		(start 15.0368 -21.3614)
		(end 13.8176 -22.5806)
		(width 0.089408)
		(layer "In2.Cu")
		(net "SVID_ALERT1_CPU1_R_N")
	)
	(segment
		(start 21.400262 -20.838668)
		(end 20.87753 -21.3614)
		(width 0.089408)
		(layer "In2.Cu")
		(net "SVID_ALERT1_CPU1_R_N")
	)
	(segment
		(start 20.87753 -21.3614)
		(end 15.0368 -21.3614)
		(width 0.089408)
		(layer "In2.Cu")
		(net "SVID_ALERT1_CPU1_R_N")
	)
	(segment
		(start 9.585706 -5.357368)
		(end 10.414254 -6.185916)
		(width 0.089408)
		(layer "In2.Cu")
		(net "SVID_ALERT1_CPU1_R_N")
	)
	(segment
		(start -3.110738 -76.549758)
		(end -4.881372 -78.320392)
		(width 0.089408)
		(layer "In2.Cu")
		(net "SVID_ALERT1_CPU1_R_N")
	)
	(segment
		(start 7.818882 -89.170002)
		(end 9.474962 -90.826082)
		(width 0.089408)
		(layer "In2.Cu")
		(net "SVID_ALERT1_CPU1_R_N")
	)
	(segment
		(start 13.8176 -39.269924)
		(end 12.03198 -41.055544)
		(width 0.089408)
		(layer "In2.Cu")
		(net "SVID_ALERT1_CPU1_R_N")
	)
	(segment
		(start 21.400262 -6.524752)
		(end 21.400262 -20.838668)
		(width 0.089408)
		(layer "In2.Cu")
		(net "SVID_ALERT1_CPU1_R_N")
	)
	(segment
		(start 9.585706 -4.953254)
		(end 9.585706 -5.357368)
		(width 0.089408)
		(layer "In2.Cu")
		(net "SVID_ALERT1_CPU1_R_N")
	)
	(segment
		(start -5.044694 -123.082812)
		(end -5.044694 -126.240794)
		(width 0.089408)
		(layer "In2.Cu")
		(net "SVID_ALERT1_CPU1_R_N")
	)
	(segment
		(start 7.375652 -105.521506)
		(end 7.375652 -112.358932)
		(width 0.089408)
		(layer "In2.Cu")
		(net "SVID_ALERT1_CPU1_R_N")
	)
	(segment
		(start 181.359302 -113.639854)
		(end 187.942982 -113.639854)
		(width 0.089408)
		(layer "In2.Cu")
		(net "SVID_ALERT1_CPU1_R_N")
	)
	(segment
		(start 10.414254 -6.185916)
		(end 21.061426 -6.185916)
		(width 0.089408)
		(layer "In2.Cu")
		(net "SVID_ALERT1_CPU1_R_N")
	)
	(segment
		(start 4.669282 -113.368836)
		(end -5.044694 -123.082812)
		(width 0.089408)
		(layer "In2.Cu")
		(net "SVID_ALERT1_CPU1_R_N")
	)
	(segment
		(start 9.474962 -103.422196)
		(end 7.375652 -105.521506)
		(width 0.089408)
		(layer "In2.Cu")
		(net "SVID_ALERT1_CPU1_R_N")
	)
	(segment
		(start 6.365748 -113.368836)
		(end 4.669282 -113.368836)
		(width 0.089408)
		(layer "In2.Cu")
		(net "SVID_ALERT1_CPU1_R_N")
	)
	(segment
		(start -4.881372 -86.735666)
		(end -2.447036 -89.170002)
		(width 0.089408)
		(layer "In2.Cu")
		(net "SVID_ALERT1_CPU1_R_N")
	)
	(segment
		(start 172.7962 -123.3678)
		(end 172.7962 -122.202956)
		(width 0.089408)
		(layer "In2.Cu")
		(net "SVID_ALERT1_CPU1_R_N")
	)
	(segment
		(start 172.7962 -122.202956)
		(end 181.359302 -113.639854)
		(width 0.089408)
		(layer "In2.Cu")
		(net "SVID_ALERT1_CPU1_R_N")
	)
	(segment
		(start -5.212842 -60.522612)
		(end -3.110738 -62.624716)
		(width 0.089408)
		(layer "In2.Cu")
		(net "SVID_ALERT1_CPU1_R_N")
	)
	(segment
		(start 7.375652 -112.358932)
		(end 6.365748 -113.368836)
		(width 0.089408)
		(layer "In2.Cu")
		(net "SVID_ALERT1_CPU1_R_N")
	)
	(segment
		(start -5.212842 -45.511974)
		(end -5.212842 -60.522612)
		(width 0.089408)
		(layer "In2.Cu")
		(net "SVID_ALERT1_CPU1_R_N")
	)
	(segment
		(start 2.878836 -122.469148)
		(end 2.87909 -122.469148)
		(width 0.089408)
		(layer "In4.Cu")
		(net "SVID_ALERT1_CPU1_R_N")
	)
	(segment
		(start 3.236976 -122.469402)
		(end 3.23723 -122.469148)
		(width 0.089408)
		(layer "In4.Cu")
		(net "SVID_ALERT1_CPU1_R_N")
	)
	(segment
		(start 34.9504 -110.91418)
		(end 37.695886 -108.168694)
		(width 0.089408)
		(layer "In4.Cu")
		(net "SVID_ALERT1_CPU1_R_N")
	)
	(segment
		(start 2.625852 -122.21591)
		(end 2.625852 -122.216164)
		(width 0.089408)
		(layer "In4.Cu")
		(net "SVID_ALERT1_CPU1_R_N")
	)
	(segment
		(start -4.258564 -127.026924)
		(end -3.775456 -126.543816)
		(width 0.089408)
		(layer "In4.Cu")
		(net "SVID_ALERT1_CPU1_R_N")
	)
	(segment
		(start 1.40208 -120.992138)
		(end 2.625852 -122.21591)
		(width 0.089408)
		(layer "In4.Cu")
		(net "SVID_ALERT1_CPU1_R_N")
	)
	(segment
		(start 18.1356 -119.973598)
		(end 25.136602 -119.973598)
		(width 0.089408)
		(layer "In4.Cu")
		(net "SVID_ALERT1_CPU1_R_N")
	)
	(segment
		(start 3.23723 -122.469148)
		(end 4.86283 -122.469148)
		(width 0.089408)
		(layer "In4.Cu")
		(net "SVID_ALERT1_CPU1_R_N")
	)
	(segment
		(start -4.192016 -125.69952)
		(end -4.192016 -123.466352)
		(width 0.089408)
		(layer "In4.Cu")
		(net "SVID_ALERT1_CPU1_R_N")
	)
	(segment
		(start 15.635732 -121.184416)
		(end 16.422116 -120.398032)
		(width 0.089408)
		(layer "In4.Cu")
		(net "SVID_ALERT1_CPU1_R_N")
	)
	(segment
		(start 37.695886 -108.168694)
		(end 37.695886 -107.248706)
		(width 0.089408)
		(layer "In4.Cu")
		(net "SVID_ALERT1_CPU1_R_N")
	)
	(segment
		(start 2.625852 -122.216164)
		(end 2.878836 -122.469148)
		(width 0.089408)
		(layer "In4.Cu")
		(net "SVID_ALERT1_CPU1_R_N")
	)
	(segment
		(start 6.147562 -121.184416)
		(end 15.635732 -121.184416)
		(width 0.089408)
		(layer "In4.Cu")
		(net "SVID_ALERT1_CPU1_R_N")
	)
	(segment
		(start 25.136602 -119.973598)
		(end 34.19602 -110.91418)
		(width 0.089408)
		(layer "In4.Cu")
		(net "SVID_ALERT1_CPU1_R_N")
	)
	(segment
		(start -1.717802 -120.992138)
		(end 1.40208 -120.992138)
		(width 0.089408)
		(layer "In4.Cu")
		(net "SVID_ALERT1_CPU1_R_N")
	)
	(segment
		(start 2.879344 -122.469402)
		(end 3.236976 -122.469402)
		(width 0.089408)
		(layer "In4.Cu")
		(net "SVID_ALERT1_CPU1_R_N")
	)
	(segment
		(start 34.19602 -110.91418)
		(end 34.9504 -110.91418)
		(width 0.089408)
		(layer "In4.Cu")
		(net "SVID_ALERT1_CPU1_R_N")
	)
	(segment
		(start -4.192016 -123.466352)
		(end -1.717802 -120.992138)
		(width 0.089408)
		(layer "In4.Cu")
		(net "SVID_ALERT1_CPU1_R_N")
	)
	(segment
		(start 17.711166 -120.398032)
		(end 18.1356 -119.973598)
		(width 0.089408)
		(layer "In4.Cu")
		(net "SVID_ALERT1_CPU1_R_N")
	)
	(segment
		(start 16.422116 -120.398032)
		(end 17.711166 -120.398032)
		(width 0.089408)
		(layer "In4.Cu")
		(net "SVID_ALERT1_CPU1_R_N")
	)
	(segment
		(start -3.775456 -126.11608)
		(end -4.192016 -125.69952)
		(width 0.089408)
		(layer "In4.Cu")
		(net "SVID_ALERT1_CPU1_R_N")
	)
	(segment
		(start 4.86283 -122.469148)
		(end 6.147562 -121.184416)
		(width 0.089408)
		(layer "In4.Cu")
		(net "SVID_ALERT1_CPU1_R_N")
	)
	(segment
		(start 2.87909 -122.469148)
		(end 2.879344 -122.469402)
		(width 0.089408)
		(layer "In4.Cu")
		(net "SVID_ALERT1_CPU1_R_N")
	)
	(segment
		(start -3.775456 -126.543816)
		(end -3.775456 -126.11608)
		(width 0.089408)
		(layer "In4.Cu")
		(net "SVID_ALERT1_CPU1_R_N")
	)
	(segment
		(start 161.35477 -123.594622)
		(end 159.428434 -125.520958)
		(width 0.089408)
		(layer "In9.Cu")
		(net "SVID_ALERT1_CPU1_R_N")
	)
	(segment
		(start 38.270434 -105.2703)
		(end 38.270434 -105.248456)
		(width 0.089408)
		(layer "In9.Cu")
		(net "SVID_ALERT1_CPU1_R_N")
	)
	(segment
		(start 36.4998 -105.283)
		(end 36.4998 -106.68)
		(width 0.089408)
		(layer "In9.Cu")
		(net "SVID_ALERT1_CPU1_R_N")
	)
	(segment
		(start 157.023308 -125.520958)
		(end 156.453078 -124.950728)
		(width 0.089408)
		(layer "In9.Cu")
		(net "SVID_ALERT1_CPU1_R_N")
	)
	(segment
		(start 37.068506 -107.248706)
		(end 37.695886 -107.248706)
		(width 0.089408)
		(layer "In9.Cu")
		(net "SVID_ALERT1_CPU1_R_N")
	)
	(segment
		(start 169.45864 -119.72544)
		(end 164.12718 -119.72544)
		(width 0.089408)
		(layer "In9.Cu")
		(net "SVID_ALERT1_CPU1_R_N")
	)
	(segment
		(start 52.888134 -119.866156)
		(end 38.52672 -105.504742)
		(width 0.089408)
		(layer "In9.Cu")
		(net "SVID_ALERT1_CPU1_R_N")
	)
	(segment
		(start 37.897816 -104.875838)
		(end 36.906962 -104.875838)
		(width 0.089408)
		(layer "In9.Cu")
		(net "SVID_ALERT1_CPU1_R_N")
	)
	(segment
		(start 172.7962 -123.3678)
		(end 172.7962 -123.063)
		(width 0.089408)
		(layer "In9.Cu")
		(net "SVID_ALERT1_CPU1_R_N")
	)
	(segment
		(start 152.943306 -124.950728)
		(end 147.858734 -119.866156)
		(width 0.089408)
		(layer "In9.Cu")
		(net "SVID_ALERT1_CPU1_R_N")
	)
	(segment
		(start 172.7962 -123.063)
		(end 169.45864 -119.72544)
		(width 0.089408)
		(layer "In9.Cu")
		(net "SVID_ALERT1_CPU1_R_N")
	)
	(segment
		(start 38.52672 -105.504742)
		(end 38.504876 -105.504742)
		(width 0.089408)
		(layer "In9.Cu")
		(net "SVID_ALERT1_CPU1_R_N")
	)
	(segment
		(start 36.906962 -104.875838)
		(end 36.4998 -105.283)
		(width 0.089408)
		(layer "In9.Cu")
		(net "SVID_ALERT1_CPU1_R_N")
	)
	(segment
		(start 156.453078 -124.950728)
		(end 152.943306 -124.950728)
		(width 0.089408)
		(layer "In9.Cu")
		(net "SVID_ALERT1_CPU1_R_N")
	)
	(segment
		(start 161.35477 -122.49785)
		(end 161.35477 -123.594622)
		(width 0.089408)
		(layer "In9.Cu")
		(net "SVID_ALERT1_CPU1_R_N")
	)
	(segment
		(start 38.504876 -105.504742)
		(end 38.270434 -105.2703)
		(width 0.089408)
		(layer "In9.Cu")
		(net "SVID_ALERT1_CPU1_R_N")
	)
	(segment
		(start 38.270434 -105.248456)
		(end 37.897816 -104.875838)
		(width 0.089408)
		(layer "In9.Cu")
		(net "SVID_ALERT1_CPU1_R_N")
	)
	(segment
		(start 147.858734 -119.866156)
		(end 52.888134 -119.866156)
		(width 0.089408)
		(layer "In9.Cu")
		(net "SVID_ALERT1_CPU1_R_N")
	)
	(segment
		(start 159.428434 -125.520958)
		(end 157.023308 -125.520958)
		(width 0.089408)
		(layer "In9.Cu")
		(net "SVID_ALERT1_CPU1_R_N")
	)
	(segment
		(start 36.4998 -106.68)
		(end 37.068506 -107.248706)
		(width 0.089408)
		(layer "In9.Cu")
		(net "SVID_ALERT1_CPU1_R_N")
	)
	(segment
		(start 164.12718 -119.72544)
		(end 161.35477 -122.49785)
		(width 0.089408)
		(layer "In9.Cu")
		(net "SVID_ALERT1_CPU1_R_N")
	)
	(segment
		(start 103.806244 -94.223586)
		(end 103.987854 -94.223586)
		(width 0.10795)
		(layer "F.Cu")
		(net "SVID_ALERT1_CPU1_N")
	)
	(segment
		(start 104.532938 -93.678502)
		(end 104.532938 -93.53804)
		(width 0.10795)
		(layer "F.Cu")
		(net "SVID_ALERT1_CPU1_N")
	)
	(segment
		(start 103.987854 -94.223586)
		(end 104.532938 -93.678502)
		(width 0.10795)
		(layer "F.Cu")
		(net "SVID_ALERT1_CPU1_N")
	)
	(via
		(at 57.413906 -101.844348)
		(size 0.6604)
		(drill 0.3302)
		(layers "F.Cu" "B.Cu")
		(net "SVID_ALERT1_CPU1_N")
	)
	(via
		(at 104.532938 -93.53804)
		(size 0.508)
		(drill 0.254)
		(layers "F.Cu" "B.Cu")
		(net "SVID_ALERT1_CPU1_N")
	)
	(segment
		(start 96.56064 -92.77096)
		(end 96.97974 -93.19006)
		(width 0.10795)
		(layer "B.Cu")
		(net "SVID_ALERT1_CPU1_N")
	)
	(segment
		(start 80.959452 -93.815408)
		(end 81.5594 -93.21546)
		(width 0.10795)
		(layer "B.Cu")
		(net "SVID_ALERT1_CPU1_N")
	)
	(segment
		(start 85.869526 -92.7735)
		(end 86.25078 -92.7735)
		(width 0.10795)
		(layer "B.Cu")
		(net "SVID_ALERT1_CPU1_N")
	)
	(segment
		(start 102.59314 -92.26042)
		(end 103.562912 -93.230192)
		(width 0.10795)
		(layer "B.Cu")
		(net "SVID_ALERT1_CPU1_N")
	)
	(segment
		(start 63.068454 -96.1898)
		(end 70.047866 -96.1898)
		(width 0.10795)
		(layer "B.Cu")
		(net "SVID_ALERT1_CPU1_N")
	)
	(segment
		(start 95.7707 -93.19006)
		(end 96.1898 -92.77096)
		(width 0.10795)
		(layer "B.Cu")
		(net "SVID_ALERT1_CPU1_N")
	)
	(segment
		(start 98.86696 -92.17406)
		(end 99.12604 -92.17406)
		(width 0.10795)
		(layer "B.Cu")
		(net "SVID_ALERT1_CPU1_N")
	)
	(segment
		(start 74.308716 -95.718122)
		(end 74.72553 -95.301308)
		(width 0.10795)
		(layer "B.Cu")
		(net "SVID_ALERT1_CPU1_N")
	)
	(segment
		(start 72.503538 -95.749364)
		(end 72.951594 -95.301308)
		(width 0.10795)
		(layer "B.Cu")
		(net "SVID_ALERT1_CPU1_N")
	)
	(segment
		(start 72.154034 -95.749364)
		(end 72.503538 -95.749364)
		(width 0.10795)
		(layer "B.Cu")
		(net "SVID_ALERT1_CPU1_N")
	)
	(segment
		(start 91.92006 -93.21292)
		(end 92.26804 -93.21292)
		(width 0.10795)
		(layer "B.Cu")
		(net "SVID_ALERT1_CPU1_N")
	)
	(segment
		(start 74.72553 -95.301308)
		(end 75.140058 -95.301308)
		(width 0.10795)
		(layer "B.Cu")
		(net "SVID_ALERT1_CPU1_N")
	)
	(segment
		(start 85.412834 -93.230192)
		(end 85.869526 -92.7735)
		(width 0.10795)
		(layer "B.Cu")
		(net "SVID_ALERT1_CPU1_N")
	)
	(segment
		(start 89.72296 -92.75318)
		(end 90.18778 -93.218)
		(width 0.10795)
		(layer "B.Cu")
		(net "SVID_ALERT1_CPU1_N")
	)
	(segment
		(start 77.318616 -95.78086)
		(end 77.66812 -95.78086)
		(width 0.10795)
		(layer "B.Cu")
		(net "SVID_ALERT1_CPU1_N")
	)
	(segment
		(start 85.048852 -93.230192)
		(end 85.412834 -93.230192)
		(width 0.10795)
		(layer "B.Cu")
		(net "SVID_ALERT1_CPU1_N")
	)
	(segment
		(start 88.80856 -93.22308)
		(end 89.27846 -92.75318)
		(width 0.10795)
		(layer "B.Cu")
		(net "SVID_ALERT1_CPU1_N")
	)
	(segment
		(start 88.46312 -93.22308)
		(end 88.80856 -93.22308)
		(width 0.10795)
		(layer "B.Cu")
		(net "SVID_ALERT1_CPU1_N")
	)
	(segment
		(start 75.140058 -95.301308)
		(end 75.588114 -95.749364)
		(width 0.10795)
		(layer "B.Cu")
		(net "SVID_ALERT1_CPU1_N")
	)
	(segment
		(start 86.25078 -92.7735)
		(end 86.64448 -93.1672)
		(width 0.10795)
		(layer "B.Cu")
		(net "SVID_ALERT1_CPU1_N")
	)
	(segment
		(start 71.705978 -95.301308)
		(end 72.154034 -95.749364)
		(width 0.10795)
		(layer "B.Cu")
		(net "SVID_ALERT1_CPU1_N")
	)
	(segment
		(start 70.047866 -96.1898)
		(end 70.442074 -95.795592)
		(width 0.10795)
		(layer "B.Cu")
		(net "SVID_ALERT1_CPU1_N")
	)
	(segment
		(start 76.839064 -95.301308)
		(end 77.318616 -95.78086)
		(width 0.10795)
		(layer "B.Cu")
		(net "SVID_ALERT1_CPU1_N")
	)
	(segment
		(start 81.98104 -93.21546)
		(end 82.4103 -92.7862)
		(width 0.10795)
		(layer "B.Cu")
		(net "SVID_ALERT1_CPU1_N")
	)
	(segment
		(start 82.4103 -92.7862)
		(end 82.8294 -92.7862)
		(width 0.10795)
		(layer "B.Cu")
		(net "SVID_ALERT1_CPU1_N")
	)
	(segment
		(start 80.669638 -93.815408)
		(end 80.959452 -93.815408)
		(width 0.10795)
		(layer "B.Cu")
		(net "SVID_ALERT1_CPU1_N")
	)
	(segment
		(start 90.18778 -93.218)
		(end 90.56116 -93.218)
		(width 0.10795)
		(layer "B.Cu")
		(net "SVID_ALERT1_CPU1_N")
	)
	(segment
		(start 90.97772 -92.80144)
		(end 91.50858 -92.80144)
		(width 0.10795)
		(layer "B.Cu")
		(net "SVID_ALERT1_CPU1_N")
	)
	(segment
		(start 104.22509 -93.230192)
		(end 104.532938 -93.53804)
		(width 0.10795)
		(layer "B.Cu")
		(net "SVID_ALERT1_CPU1_N")
	)
	(segment
		(start 79.389986 -94.804992)
		(end 79.88554 -94.309438)
		(width 0.10795)
		(layer "B.Cu")
		(net "SVID_ALERT1_CPU1_N")
	)
	(segment
		(start 43.260518 -107.807506)
		(end 43.481752 -107.586272)
		(width 0.10795)
		(layer "B.Cu")
		(net "SVID_ALERT1_CPU1_N")
	)
	(segment
		(start 71.301102 -95.301308)
		(end 71.705978 -95.301308)
		(width 0.10795)
		(layer "B.Cu")
		(net "SVID_ALERT1_CPU1_N")
	)
	(segment
		(start 80.261714 -94.226888)
		(end 80.55356 -93.935042)
		(width 0.10795)
		(layer "B.Cu")
		(net "SVID_ALERT1_CPU1_N")
	)
	(segment
		(start 78.148942 -95.300038)
		(end 78.531974 -95.300038)
		(width 0.10795)
		(layer "B.Cu")
		(net "SVID_ALERT1_CPU1_N")
	)
	(segment
		(start 91.50858 -92.80144)
		(end 91.92006 -93.21292)
		(width 0.10795)
		(layer "B.Cu")
		(net "SVID_ALERT1_CPU1_N")
	)
	(segment
		(start 96.1898 -92.77096)
		(end 96.56064 -92.77096)
		(width 0.10795)
		(layer "B.Cu")
		(net "SVID_ALERT1_CPU1_N")
	)
	(segment
		(start 88.01354 -92.7735)
		(end 88.46312 -93.22308)
		(width 0.10795)
		(layer "B.Cu")
		(net "SVID_ALERT1_CPU1_N")
	)
	(segment
		(start 97.45726 -93.19006)
		(end 97.86112 -92.7862)
		(width 0.10795)
		(layer "B.Cu")
		(net "SVID_ALERT1_CPU1_N")
	)
	(segment
		(start 92.26804 -93.21292)
		(end 92.80398 -93.74886)
		(width 0.10795)
		(layer "B.Cu")
		(net "SVID_ALERT1_CPU1_N")
	)
	(segment
		(start 77.66812 -95.78086)
		(end 78.148942 -95.300038)
		(width 0.10795)
		(layer "B.Cu")
		(net "SVID_ALERT1_CPU1_N")
	)
	(segment
		(start 51.671982 -107.586272)
		(end 57.413906 -101.844348)
		(width 0.10795)
		(layer "B.Cu")
		(net "SVID_ALERT1_CPU1_N")
	)
	(segment
		(start 80.55356 -93.931486)
		(end 80.669638 -93.815408)
		(width 0.10795)
		(layer "B.Cu")
		(net "SVID_ALERT1_CPU1_N")
	)
	(segment
		(start 98.25482 -92.7862)
		(end 98.86696 -92.17406)
		(width 0.10795)
		(layer "B.Cu")
		(net "SVID_ALERT1_CPU1_N")
	)
	(segment
		(start 79.88554 -94.309438)
		(end 80.175608 -94.309438)
		(width 0.10795)
		(layer "B.Cu")
		(net "SVID_ALERT1_CPU1_N")
	)
	(segment
		(start 73.358248 -95.301308)
		(end 73.775062 -95.718122)
		(width 0.10795)
		(layer "B.Cu")
		(net "SVID_ALERT1_CPU1_N")
	)
	(segment
		(start 73.775062 -95.718122)
		(end 74.308716 -95.718122)
		(width 0.10795)
		(layer "B.Cu")
		(net "SVID_ALERT1_CPU1_N")
	)
	(segment
		(start 99.12604 -92.17406)
		(end 99.59848 -91.70162)
		(width 0.10795)
		(layer "B.Cu")
		(net "SVID_ALERT1_CPU1_N")
	)
	(segment
		(start 43.481752 -107.586272)
		(end 51.671982 -107.586272)
		(width 0.10795)
		(layer "B.Cu")
		(net "SVID_ALERT1_CPU1_N")
	)
	(segment
		(start 90.56116 -93.218)
		(end 90.97772 -92.80144)
		(width 0.10795)
		(layer "B.Cu")
		(net "SVID_ALERT1_CPU1_N")
	)
	(segment
		(start 87.52078 -92.7735)
		(end 88.01354 -92.7735)
		(width 0.10795)
		(layer "B.Cu")
		(net "SVID_ALERT1_CPU1_N")
	)
	(segment
		(start 103.562912 -93.230192)
		(end 104.22509 -93.230192)
		(width 0.10795)
		(layer "B.Cu")
		(net "SVID_ALERT1_CPU1_N")
	)
	(segment
		(start 99.59848 -91.70162)
		(end 100.01504 -91.70162)
		(width 0.10795)
		(layer "B.Cu")
		(net "SVID_ALERT1_CPU1_N")
	)
	(segment
		(start 78.531974 -95.300038)
		(end 79.02702 -94.804992)
		(width 0.10795)
		(layer "B.Cu")
		(net "SVID_ALERT1_CPU1_N")
	)
	(segment
		(start 75.588114 -95.749364)
		(end 75.937618 -95.749364)
		(width 0.10795)
		(layer "B.Cu")
		(net "SVID_ALERT1_CPU1_N")
	)
	(segment
		(start 93.0783 -93.74886)
		(end 93.59646 -93.2307)
		(width 0.10795)
		(layer "B.Cu")
		(net "SVID_ALERT1_CPU1_N")
	)
	(segment
		(start 76.385674 -95.301308)
		(end 76.839064 -95.301308)
		(width 0.10795)
		(layer "B.Cu")
		(net "SVID_ALERT1_CPU1_N")
	)
	(segment
		(start 92.80398 -93.74886)
		(end 93.0783 -93.74886)
		(width 0.10795)
		(layer "B.Cu")
		(net "SVID_ALERT1_CPU1_N")
	)
	(segment
		(start 87.12708 -93.1672)
		(end 87.52078 -92.7735)
		(width 0.10795)
		(layer "B.Cu")
		(net "SVID_ALERT1_CPU1_N")
	)
	(segment
		(start 80.55356 -93.935042)
		(end 80.55356 -93.931486)
		(width 0.10795)
		(layer "B.Cu")
		(net "SVID_ALERT1_CPU1_N")
	)
	(segment
		(start 102.26802 -92.26042)
		(end 102.59314 -92.26042)
		(width 0.10795)
		(layer "B.Cu")
		(net "SVID_ALERT1_CPU1_N")
	)
	(segment
		(start 94.30766 -92.81414)
		(end 94.91726 -92.81414)
		(width 0.10795)
		(layer "B.Cu")
		(net "SVID_ALERT1_CPU1_N")
	)
	(segment
		(start 93.59646 -93.2307)
		(end 93.8911 -93.2307)
		(width 0.10795)
		(layer "B.Cu")
		(net "SVID_ALERT1_CPU1_N")
	)
	(segment
		(start 101.71176 -91.70416)
		(end 102.26802 -92.26042)
		(width 0.10795)
		(layer "B.Cu")
		(net "SVID_ALERT1_CPU1_N")
	)
	(segment
		(start 75.937618 -95.749364)
		(end 76.385674 -95.301308)
		(width 0.10795)
		(layer "B.Cu")
		(net "SVID_ALERT1_CPU1_N")
	)
	(segment
		(start 93.8911 -93.2307)
		(end 94.30766 -92.81414)
		(width 0.10795)
		(layer "B.Cu")
		(net "SVID_ALERT1_CPU1_N")
	)
	(segment
		(start 70.806818 -95.795592)
		(end 71.301102 -95.301308)
		(width 0.10795)
		(layer "B.Cu")
		(net "SVID_ALERT1_CPU1_N")
	)
	(segment
		(start 70.442074 -95.795592)
		(end 70.806818 -95.795592)
		(width 0.10795)
		(layer "B.Cu")
		(net "SVID_ALERT1_CPU1_N")
	)
	(segment
		(start 84.61756 -92.7989)
		(end 85.048852 -93.230192)
		(width 0.10795)
		(layer "B.Cu")
		(net "SVID_ALERT1_CPU1_N")
	)
	(segment
		(start 79.02702 -94.804992)
		(end 79.389986 -94.804992)
		(width 0.10795)
		(layer "B.Cu")
		(net "SVID_ALERT1_CPU1_N")
	)
	(segment
		(start 94.91726 -92.81414)
		(end 95.29318 -93.19006)
		(width 0.10795)
		(layer "B.Cu")
		(net "SVID_ALERT1_CPU1_N")
	)
	(segment
		(start 82.8294 -92.7862)
		(end 83.273392 -93.230192)
		(width 0.10795)
		(layer "B.Cu")
		(net "SVID_ALERT1_CPU1_N")
	)
	(segment
		(start 100.01504 -91.70162)
		(end 100.55098 -92.23756)
		(width 0.10795)
		(layer "B.Cu")
		(net "SVID_ALERT1_CPU1_N")
	)
	(segment
		(start 80.175608 -94.309438)
		(end 80.258158 -94.226888)
		(width 0.10795)
		(layer "B.Cu")
		(net "SVID_ALERT1_CPU1_N")
	)
	(segment
		(start 83.273392 -93.230192)
		(end 83.695794 -93.230192)
		(width 0.10795)
		(layer "B.Cu")
		(net "SVID_ALERT1_CPU1_N")
	)
	(segment
		(start 84.127086 -92.7989)
		(end 84.61756 -92.7989)
		(width 0.10795)
		(layer "B.Cu")
		(net "SVID_ALERT1_CPU1_N")
	)
	(segment
		(start 96.97974 -93.19006)
		(end 97.45726 -93.19006)
		(width 0.10795)
		(layer "B.Cu")
		(net "SVID_ALERT1_CPU1_N")
	)
	(segment
		(start 100.55098 -92.23756)
		(end 100.78466 -92.23756)
		(width 0.10795)
		(layer "B.Cu")
		(net "SVID_ALERT1_CPU1_N")
	)
	(segment
		(start 80.258158 -94.226888)
		(end 80.261714 -94.226888)
		(width 0.10795)
		(layer "B.Cu")
		(net "SVID_ALERT1_CPU1_N")
	)
	(segment
		(start 89.27846 -92.75318)
		(end 89.72296 -92.75318)
		(width 0.10795)
		(layer "B.Cu")
		(net "SVID_ALERT1_CPU1_N")
	)
	(segment
		(start 100.78466 -92.23756)
		(end 101.31806 -91.70416)
		(width 0.10795)
		(layer "B.Cu")
		(net "SVID_ALERT1_CPU1_N")
	)
	(segment
		(start 97.86112 -92.7862)
		(end 98.25482 -92.7862)
		(width 0.10795)
		(layer "B.Cu")
		(net "SVID_ALERT1_CPU1_N")
	)
	(segment
		(start 86.64448 -93.1672)
		(end 87.12708 -93.1672)
		(width 0.10795)
		(layer "B.Cu")
		(net "SVID_ALERT1_CPU1_N")
	)
	(segment
		(start 39.329614 -107.807506)
		(end 43.260518 -107.807506)
		(width 0.10795)
		(layer "B.Cu")
		(net "SVID_ALERT1_CPU1_N")
	)
	(segment
		(start 83.695794 -93.230192)
		(end 84.127086 -92.7989)
		(width 0.10795)
		(layer "B.Cu")
		(net "SVID_ALERT1_CPU1_N")
	)
	(segment
		(start 72.951594 -95.301308)
		(end 73.358248 -95.301308)
		(width 0.10795)
		(layer "B.Cu")
		(net "SVID_ALERT1_CPU1_N")
	)
	(segment
		(start 57.413906 -101.844348)
		(end 63.068454 -96.1898)
		(width 0.10795)
		(layer "B.Cu")
		(net "SVID_ALERT1_CPU1_N")
	)
	(segment
		(start 95.29318 -93.19006)
		(end 95.7707 -93.19006)
		(width 0.10795)
		(layer "B.Cu")
		(net "SVID_ALERT1_CPU1_N")
	)
	(segment
		(start 101.31806 -91.70416)
		(end 101.71176 -91.70416)
		(width 0.10795)
		(layer "B.Cu")
		(net "SVID_ALERT1_CPU1_N")
	)
	(segment
		(start 81.5594 -93.21546)
		(end 81.98104 -93.21546)
		(width 0.10795)
		(layer "B.Cu")
		(net "SVID_ALERT1_CPU1_N")
	)
	(segment
		(start 362.216954 -106.590846)
		(end 360.26725 -108.54055)
		(width 0.10795)
		(layer "F.Cu")
		(net "SVID_ALERT1_CPU0_R_N")
	)
	(segment
		(start 360.531918 -74.92365)
		(end 361.923584 -76.315316)
		(width 0.10795)
		(layer "F.Cu")
		(net "SVID_ALERT1_CPU0_R_N")
	)
	(segment
		(start 362.2167 -92.875354)
		(end 362.2167 -106.248708)
		(width 0.10795)
		(layer "F.Cu")
		(net "SVID_ALERT1_CPU0_R_N")
	)
	(segment
		(start 362.2167 -106.248708)
		(end 362.216954 -106.248962)
		(width 0.10795)
		(layer "F.Cu")
		(net "SVID_ALERT1_CPU0_R_N")
	)
	(segment
		(start 355.418136 -108.54055)
		(end 355.08819 -108.870496)
		(width 0.10795)
		(layer "F.Cu")
		(net "SVID_ALERT1_CPU0_R_N")
	)
	(segment
		(start 364.861348 -139.30757)
		(end 365.537242 -138.631676)
		(width 0.10795)
		(layer "F.Cu")
		(net "SVID_ALERT1_CPU0_R_N")
	)
	(segment
		(start 337.185 -16.5862)
		(end 337.185 -16.256)
		(width 0.10795)
		(layer "F.Cu")
		(net "SVID_ALERT1_CPU0_R_N")
	)
	(segment
		(start 359.3465 -90.424)
		(end 359.765346 -90.424)
		(width 0.10795)
		(layer "F.Cu")
		(net "SVID_ALERT1_CPU0_R_N")
	)
	(segment
		(start 359.025698 -90.103198)
		(end 359.3465 -90.424)
		(width 0.10795)
		(layer "F.Cu")
		(net "SVID_ALERT1_CPU0_R_N")
	)
	(segment
		(start 353.0346 -113.6396)
		(end 352.454972 -114.219228)
		(width 0.10795)
		(layer "F.Cu")
		(net "SVID_ALERT1_CPU0_R_N")
	)
	(segment
		(start 355.08819 -108.870496)
		(end 355.08819 -110.40491)
		(width 0.10795)
		(layer "F.Cu")
		(net "SVID_ALERT1_CPU0_R_N")
	)
	(segment
		(start 359.765346 -90.424)
		(end 362.2167 -92.875354)
		(width 0.10795)
		(layer "F.Cu")
		(net "SVID_ALERT1_CPU0_R_N")
	)
	(segment
		(start 322.9102 -129.6924)
		(end 322.48856 -129.27076)
		(width 0.10795)
		(layer "F.Cu")
		(net "SVID_ALERT1_CPU0_R_N")
	)
	(segment
		(start 360.26725 -108.54055)
		(end 355.418136 -108.54055)
		(width 0.10795)
		(layer "F.Cu")
		(net "SVID_ALERT1_CPU0_R_N")
	)
	(segment
		(start 353.3902 -111.0869)
		(end 353.0854 -111.3917)
		(width 0.10795)
		(layer "F.Cu")
		(net "SVID_ALERT1_CPU0_R_N")
	)
	(segment
		(start 352.454972 -114.219228)
		(end 352.454972 -114.28095)
		(width 0.10795)
		(layer "F.Cu")
		(net "SVID_ALERT1_CPU0_R_N")
	)
	(segment
		(start 362.216954 -106.248962)
		(end 362.216954 -106.590846)
		(width 0.10795)
		(layer "F.Cu")
		(net "SVID_ALERT1_CPU0_R_N")
	)
	(segment
		(start 354.4062 -111.0869)
		(end 353.3902 -111.0869)
		(width 0.10795)
		(layer "F.Cu")
		(net "SVID_ALERT1_CPU0_R_N")
	)
	(segment
		(start 347.92539 -74.92365)
		(end 355.727 -74.92365)
		(width 0.10795)
		(layer "F.Cu")
		(net "SVID_ALERT1_CPU0_R_N")
	)
	(segment
		(start 345.36634 -72.3646)
		(end 347.92539 -74.92365)
		(width 0.10795)
		(layer "F.Cu")
		(net "SVID_ALERT1_CPU0_R_N")
	)
	(segment
		(start 364.75924 -139.30757)
		(end 364.861348 -139.30757)
		(width 0.10795)
		(layer "F.Cu")
		(net "SVID_ALERT1_CPU0_R_N")
	)
	(segment
		(start 322.48856 -129.27076)
		(end 322.27647 -129.27076)
		(width 0.10795)
		(layer "F.Cu")
		(net "SVID_ALERT1_CPU0_R_N")
	)
	(segment
		(start 353.0854 -111.3917)
		(end 353.0854 -113.5888)
		(width 0.10795)
		(layer "F.Cu")
		(net "SVID_ALERT1_CPU0_R_N")
	)
	(segment
		(start 361.923584 -85.800692)
		(end 359.025698 -88.698578)
		(width 0.10795)
		(layer "F.Cu")
		(net "SVID_ALERT1_CPU0_R_N")
	)
	(segment
		(start 337.185 -16.256)
		(end 337.947 -15.494)
		(width 0.10795)
		(layer "F.Cu")
		(net "SVID_ALERT1_CPU0_R_N")
	)
	(segment
		(start 355.08819 -110.40491)
		(end 354.4062 -111.0869)
		(width 0.10795)
		(layer "F.Cu")
		(net "SVID_ALERT1_CPU0_R_N")
	)
	(segment
		(start 323.10324 -130.45186)
		(end 323.10324 -130.11404)
		(width 0.10795)
		(layer "F.Cu")
		(net "SVID_ALERT1_CPU0_R_N")
	)
	(segment
		(start 365.537242 -138.631676)
		(end 365.537242 -138.504676)
		(width 0.10795)
		(layer "F.Cu")
		(net "SVID_ALERT1_CPU0_R_N")
	)
	(segment
		(start 353.0854 -113.5888)
		(end 353.0346 -113.6396)
		(width 0.10795)
		(layer "F.Cu")
		(net "SVID_ALERT1_CPU0_R_N")
	)
	(segment
		(start 359.025698 -88.698578)
		(end 359.025698 -90.103198)
		(width 0.10795)
		(layer "F.Cu")
		(net "SVID_ALERT1_CPU0_R_N")
	)
	(segment
		(start 322.9102 -129.921)
		(end 322.9102 -129.6924)
		(width 0.10795)
		(layer "F.Cu")
		(net "SVID_ALERT1_CPU0_R_N")
	)
	(segment
		(start 323.10324 -130.11404)
		(end 322.9102 -129.921)
		(width 0.10795)
		(layer "F.Cu")
		(net "SVID_ALERT1_CPU0_R_N")
	)
	(segment
		(start 355.727 -74.92365)
		(end 360.531918 -74.92365)
		(width 0.10795)
		(layer "F.Cu")
		(net "SVID_ALERT1_CPU0_R_N")
	)
	(segment
		(start 361.923584 -76.315316)
		(end 361.923584 -85.800692)
		(width 0.10795)
		(layer "F.Cu")
		(net "SVID_ALERT1_CPU0_R_N")
	)
	(segment
		(start 345.186 -72.3646)
		(end 345.36634 -72.3646)
		(width 0.10795)
		(layer "F.Cu")
		(net "SVID_ALERT1_CPU0_R_N")
	)
	(via
		(at 355.727 -74.92365)
		(size 0.762)
		(drill 0.381)
		(layers "F.Cu" "B.Cu")
		(net "SVID_ALERT1_CPU0_R_N")
	)
	(via
		(at 322.9102 -129.6924)
		(size 0.508)
		(drill 0.254)
		(layers "F.Cu" "B.Cu")
		(net "SVID_ALERT1_CPU0_R_N")
	)
	(via
		(at 353.0346 -113.6396)
		(size 0.508)
		(drill 0.254)
		(layers "F.Cu" "B.Cu")
		(net "SVID_ALERT1_CPU0_R_N")
	)
	(via
		(at 345.186 -72.3646)
		(size 0.508)
		(drill 0.254)
		(layers "F.Cu" "B.Cu")
		(net "SVID_ALERT1_CPU0_R_N")
	)
	(via
		(at 337.185 -16.5862)
		(size 0.508)
		(drill 0.254)
		(layers "F.Cu" "B.Cu")
		(net "SVID_ALERT1_CPU0_R_N")
	)
	(via
		(at 365.537242 -138.504676)
		(size 0.508)
		(drill 0.254)
		(layers "F.Cu" "B.Cu")
		(net "SVID_ALERT1_CPU0_R_N")
	)
	(via
		(at 345.948 -53.1622)
		(size 0.508)
		(drill 0.254)
		(layers "F.Cu" "B.Cu")
		(net "SVID_ALERT1_CPU0_R_N")
	)
	(segment
		(start 350.58604 -118.9228)
		(end 348.175834 -118.9228)
		(width 0.10795)
		(layer "B.Cu")
		(net "SVID_ALERT1_CPU0_R_N")
	)
	(segment
		(start 353.1616 -116.8654)
		(end 352.64344 -116.8654)
		(width 0.10795)
		(layer "B.Cu")
		(net "SVID_ALERT1_CPU0_R_N")
	)
	(segment
		(start 345.11234 -121.986294)
		(end 345.11234 -126.0856)
		(width 0.10795)
		(layer "B.Cu")
		(net "SVID_ALERT1_CPU0_R_N")
	)
	(segment
		(start 366.759998 -136.715246)
		(end 366.759998 -138.014202)
		(width 0.10795)
		(layer "B.Cu")
		(net "SVID_ALERT1_CPU0_R_N")
	)
	(segment
		(start 367.35258 -136.122664)
		(end 366.759998 -136.715246)
		(width 0.10795)
		(layer "B.Cu")
		(net "SVID_ALERT1_CPU0_R_N")
	)
	(segment
		(start 348.175834 -118.9228)
		(end 345.11234 -121.986294)
		(width 0.10795)
		(layer "B.Cu")
		(net "SVID_ALERT1_CPU0_R_N")
	)
	(segment
		(start 346.53474 -127.508)
		(end 356.8573 -127.508)
		(width 0.10795)
		(layer "B.Cu")
		(net "SVID_ALERT1_CPU0_R_N")
	)
	(segment
		(start 367.35258 -132.74548)
		(end 367.35258 -136.122664)
		(width 0.10795)
		(layer "B.Cu")
		(net "SVID_ALERT1_CPU0_R_N")
	)
	(segment
		(start 345.11234 -126.0856)
		(end 346.53474 -127.508)
		(width 0.10795)
		(layer "B.Cu")
		(net "SVID_ALERT1_CPU0_R_N")
	)
	(segment
		(start 352.64344 -116.8654)
		(end 350.58604 -118.9228)
		(width 0.10795)
		(layer "B.Cu")
		(net "SVID_ALERT1_CPU0_R_N")
	)
	(segment
		(start 353.0346 -113.6396)
		(end 353.0346 -113.8936)
		(width 0.10795)
		(layer "B.Cu")
		(net "SVID_ALERT1_CPU0_R_N")
	)
	(segment
		(start 353.695 -114.554)
		(end 353.695 -116.332)
		(width 0.10795)
		(layer "B.Cu")
		(net "SVID_ALERT1_CPU0_R_N")
	)
	(segment
		(start 364.49254 -129.88544)
		(end 367.35258 -132.74548)
		(width 0.10795)
		(layer "B.Cu")
		(net "SVID_ALERT1_CPU0_R_N")
	)
	(segment
		(start 353.695 -116.332)
		(end 353.1616 -116.8654)
		(width 0.10795)
		(layer "B.Cu")
		(net "SVID_ALERT1_CPU0_R_N")
	)
	(segment
		(start 353.0346 -113.8936)
		(end 353.695 -114.554)
		(width 0.10795)
		(layer "B.Cu")
		(net "SVID_ALERT1_CPU0_R_N")
	)
	(segment
		(start 366.269524 -138.504676)
		(end 365.537242 -138.504676)
		(width 0.10795)
		(layer "B.Cu")
		(net "SVID_ALERT1_CPU0_R_N")
	)
	(segment
		(start 359.23474 -129.88544)
		(end 364.49254 -129.88544)
		(width 0.10795)
		(layer "B.Cu")
		(net "SVID_ALERT1_CPU0_R_N")
	)
	(segment
		(start 356.8573 -127.508)
		(end 359.23474 -129.88544)
		(width 0.10795)
		(layer "B.Cu")
		(net "SVID_ALERT1_CPU0_R_N")
	)
	(segment
		(start 366.759998 -138.014202)
		(end 366.269524 -138.504676)
		(width 0.10795)
		(layer "B.Cu")
		(net "SVID_ALERT1_CPU0_R_N")
	)
	(segment
		(start 322.9102 -129.6924)
		(end 323.098922 -129.6924)
		(width 0.089408)
		(layer "In2.Cu")
		(net "SVID_ALERT1_CPU0_R_N")
	)
	(segment
		(start 338.595716 -17.869916)
		(end 337.312 -16.5862)
		(width 0.089408)
		(layer "In2.Cu")
		(net "SVID_ALERT1_CPU0_R_N")
	)
	(segment
		(start 337.799426 -34.861246)
		(end 336.693002 -34.861246)
		(width 0.089408)
		(layer "In2.Cu")
		(net "SVID_ALERT1_CPU0_R_N")
	)
	(segment
		(start 330.13904 -128.678432)
		(end 331.127608 -129.667)
		(width 0.089408)
		(layer "In2.Cu")
		(net "SVID_ALERT1_CPU0_R_N")
	)
	(segment
		(start 329.357228 -28.973272)
		(end 329.357228 -26.369772)
		(width 0.089408)
		(layer "In2.Cu")
		(net "SVID_ALERT1_CPU0_R_N")
	)
	(segment
		(start 334.842104 -20.783296)
		(end 335.241392 -20.384008)
		(width 0.089408)
		(layer "In2.Cu")
		(net "SVID_ALERT1_CPU0_R_N")
	)
	(segment
		(start 361.4039 -130.748532)
		(end 361.4039 -132.79628)
		(width 0.089408)
		(layer "In2.Cu")
		(net "SVID_ALERT1_CPU0_R_N")
	)
	(segment
		(start 338.595716 -19.521678)
		(end 338.595716 -17.869916)
		(width 0.089408)
		(layer "In2.Cu")
		(net "SVID_ALERT1_CPU0_R_N")
	)
	(segment
		(start 337.733132 -20.384262)
		(end 338.595716 -19.521678)
		(width 0.089408)
		(layer "In2.Cu")
		(net "SVID_ALERT1_CPU0_R_N")
	)
	(segment
		(start 365.453676 -138.504676)
		(end 365.537242 -138.504676)
		(width 0.089408)
		(layer "In2.Cu")
		(net "SVID_ALERT1_CPU0_R_N")
	)
	(segment
		(start 336.537808 -35.01644)
		(end 332.33741 -35.01644)
		(width 0.089408)
		(layer "In2.Cu")
		(net "SVID_ALERT1_CPU0_R_N")
	)
	(segment
		(start 328.480674 -128.549654)
		(end 328.609452 -128.678432)
		(width 0.089408)
		(layer "In2.Cu")
		(net "SVID_ALERT1_CPU0_R_N")
	)
	(segment
		(start 329.357228 -26.369772)
		(end 334.123792 -21.603208)
		(width 0.089408)
		(layer "In2.Cu")
		(net "SVID_ALERT1_CPU0_R_N")
	)
	(segment
		(start 339.364828 -128.1684)
		(end 339.806534 -128.610106)
		(width 0.089408)
		(layer "In2.Cu")
		(net "SVID_ALERT1_CPU0_R_N")
	)
	(segment
		(start 334.123792 -21.293328)
		(end 334.633824 -20.783296)
		(width 0.089408)
		(layer "In2.Cu")
		(net "SVID_ALERT1_CPU0_R_N")
	)
	(segment
		(start 326.23887 -128.549654)
		(end 328.480674 -128.549654)
		(width 0.089408)
		(layer "In2.Cu")
		(net "SVID_ALERT1_CPU0_R_N")
	)
	(segment
		(start 337.28406 -20.384262)
		(end 337.733132 -20.384262)
		(width 0.089408)
		(layer "In2.Cu")
		(net "SVID_ALERT1_CPU0_R_N")
	)
	(segment
		(start 337.95462 -35.01644)
		(end 337.799426 -34.861246)
		(width 0.089408)
		(layer "In2.Cu")
		(net "SVID_ALERT1_CPU0_R_N")
	)
	(segment
		(start 363.75086 -134.79526)
		(end 364.641892 -135.686292)
		(width 0.089408)
		(layer "In2.Cu")
		(net "SVID_ALERT1_CPU0_R_N")
	)
	(segment
		(start 339.806534 -128.610106)
		(end 344.560906 -128.610106)
		(width 0.089408)
		(layer "In2.Cu")
		(net "SVID_ALERT1_CPU0_R_N")
	)
	(segment
		(start 364.641892 -135.686292)
		(end 364.641892 -137.692892)
		(width 0.089408)
		(layer "In2.Cu")
		(net "SVID_ALERT1_CPU0_R_N")
	)
	(segment
		(start 345.948 -51.975766)
		(end 341.016336 -47.044102)
		(width 0.089408)
		(layer "In2.Cu")
		(net "SVID_ALERT1_CPU0_R_N")
	)
	(segment
		(start 348.39402 -129.351024)
		(end 355.086666 -129.351024)
		(width 0.089408)
		(layer "In2.Cu")
		(net "SVID_ALERT1_CPU0_R_N")
	)
	(segment
		(start 336.693002 -34.861246)
		(end 336.537808 -35.01644)
		(width 0.089408)
		(layer "In2.Cu")
		(net "SVID_ALERT1_CPU0_R_N")
	)
	(segment
		(start 334.123792 -21.603208)
		(end 334.123792 -21.293328)
		(width 0.089408)
		(layer "In2.Cu")
		(net "SVID_ALERT1_CPU0_R_N")
	)
	(segment
		(start 330.09967 -32.7787)
		(end 330.09967 -29.715714)
		(width 0.089408)
		(layer "In2.Cu")
		(net "SVID_ALERT1_CPU0_R_N")
	)
	(segment
		(start 339.716872 -35.01644)
		(end 337.95462 -35.01644)
		(width 0.089408)
		(layer "In2.Cu")
		(net "SVID_ALERT1_CPU0_R_N")
	)
	(segment
		(start 344.560906 -128.610106)
		(end 344.9193 -128.9685)
		(width 0.089408)
		(layer "In2.Cu")
		(net "SVID_ALERT1_CPU0_R_N")
	)
	(segment
		(start 328.609452 -128.678432)
		(end 330.13904 -128.678432)
		(width 0.089408)
		(layer "In2.Cu")
		(net "SVID_ALERT1_CPU0_R_N")
	)
	(segment
		(start 323.098922 -129.6924)
		(end 323.542914 -130.136392)
		(width 0.089408)
		(layer "In2.Cu")
		(net "SVID_ALERT1_CPU0_R_N")
	)
	(segment
		(start 344.9193 -128.9685)
		(end 348.011496 -128.9685)
		(width 0.089408)
		(layer "In2.Cu")
		(net "SVID_ALERT1_CPU0_R_N")
	)
	(segment
		(start 337.312 -16.5862)
		(end 337.185 -16.5862)
		(width 0.089408)
		(layer "In2.Cu")
		(net "SVID_ALERT1_CPU0_R_N")
	)
	(segment
		(start 355.086666 -129.351024)
		(end 355.303074 -129.134616)
		(width 0.089408)
		(layer "In2.Cu")
		(net "SVID_ALERT1_CPU0_R_N")
	)
	(segment
		(start 345.948 -53.1622)
		(end 345.948 -51.975766)
		(width 0.089408)
		(layer "In2.Cu")
		(net "SVID_ALERT1_CPU0_R_N")
	)
	(segment
		(start 364.641892 -137.692892)
		(end 365.453676 -138.504676)
		(width 0.089408)
		(layer "In2.Cu")
		(net "SVID_ALERT1_CPU0_R_N")
	)
	(segment
		(start 363.40288 -134.79526)
		(end 363.75086 -134.79526)
		(width 0.089408)
		(layer "In2.Cu")
		(net "SVID_ALERT1_CPU0_R_N")
	)
	(segment
		(start 323.542914 -130.136392)
		(end 324.652132 -130.136392)
		(width 0.089408)
		(layer "In2.Cu")
		(net "SVID_ALERT1_CPU0_R_N")
	)
	(segment
		(start 355.303074 -129.134616)
		(end 359.789984 -129.134616)
		(width 0.089408)
		(layer "In2.Cu")
		(net "SVID_ALERT1_CPU0_R_N")
	)
	(segment
		(start 361.4039 -132.79628)
		(end 363.40288 -134.79526)
		(width 0.089408)
		(layer "In2.Cu")
		(net "SVID_ALERT1_CPU0_R_N")
	)
	(segment
		(start 341.016336 -47.044102)
		(end 341.016336 -36.315904)
		(width 0.089408)
		(layer "In2.Cu")
		(net "SVID_ALERT1_CPU0_R_N")
	)
	(segment
		(start 359.789984 -129.134616)
		(end 361.4039 -130.748532)
		(width 0.089408)
		(layer "In2.Cu")
		(net "SVID_ALERT1_CPU0_R_N")
	)
	(segment
		(start 335.241392 -20.384008)
		(end 337.283806 -20.384008)
		(width 0.089408)
		(layer "In2.Cu")
		(net "SVID_ALERT1_CPU0_R_N")
	)
	(segment
		(start 335.915 -129.667)
		(end 337.4136 -128.1684)
		(width 0.089408)
		(layer "In2.Cu")
		(net "SVID_ALERT1_CPU0_R_N")
	)
	(segment
		(start 341.016336 -36.315904)
		(end 339.716872 -35.01644)
		(width 0.089408)
		(layer "In2.Cu")
		(net "SVID_ALERT1_CPU0_R_N")
	)
	(segment
		(start 324.652132 -130.136392)
		(end 326.23887 -128.549654)
		(width 0.089408)
		(layer "In2.Cu")
		(net "SVID_ALERT1_CPU0_R_N")
	)
	(segment
		(start 337.4136 -128.1684)
		(end 339.364828 -128.1684)
		(width 0.089408)
		(layer "In2.Cu")
		(net "SVID_ALERT1_CPU0_R_N")
	)
	(segment
		(start 348.011496 -128.9685)
		(end 348.39402 -129.351024)
		(width 0.089408)
		(layer "In2.Cu")
		(net "SVID_ALERT1_CPU0_R_N")
	)
	(segment
		(start 330.09967 -29.715714)
		(end 329.357228 -28.973272)
		(width 0.089408)
		(layer "In2.Cu")
		(net "SVID_ALERT1_CPU0_R_N")
	)
	(segment
		(start 332.33741 -35.01644)
		(end 330.09967 -32.7787)
		(width 0.089408)
		(layer "In2.Cu")
		(net "SVID_ALERT1_CPU0_R_N")
	)
	(segment
		(start 337.283806 -20.384008)
		(end 337.28406 -20.384262)
		(width 0.089408)
		(layer "In2.Cu")
		(net "SVID_ALERT1_CPU0_R_N")
	)
	(segment
		(start 334.633824 -20.783296)
		(end 334.842104 -20.783296)
		(width 0.089408)
		(layer "In2.Cu")
		(net "SVID_ALERT1_CPU0_R_N")
	)
	(segment
		(start 331.127608 -129.667)
		(end 335.915 -129.667)
		(width 0.089408)
		(layer "In2.Cu")
		(net "SVID_ALERT1_CPU0_R_N")
	)
	(segment
		(start 348.742762 -64.438784)
		(end 348.742762 -68.807838)
		(width 0.089408)
		(layer "In9.Cu")
		(net "SVID_ALERT1_CPU0_R_N")
	)
	(segment
		(start 346.10548 -53.31968)
		(end 346.10548 -61.801502)
		(width 0.089408)
		(layer "In9.Cu")
		(net "SVID_ALERT1_CPU0_R_N")
	)
	(segment
		(start 348.742762 -68.807838)
		(end 345.186 -72.3646)
		(width 0.089408)
		(layer "In9.Cu")
		(net "SVID_ALERT1_CPU0_R_N")
	)
	(segment
		(start 346.10548 -61.801502)
		(end 348.742762 -64.438784)
		(width 0.089408)
		(layer "In9.Cu")
		(net "SVID_ALERT1_CPU0_R_N")
	)
	(segment
		(start 345.948 -53.1622)
		(end 346.10548 -53.31968)
		(width 0.089408)
		(layer "In9.Cu")
		(net "SVID_ALERT1_CPU0_R_N")
	)
	(segment
		(start 322.379086 -128.279144)
		(end 322.27647 -128.38176)
		(width 0.10795)
		(layer "F.Cu")
		(net "SVID_ALERT1_CPU0_N")
	)
	(segment
		(start 268.806676 -94.223586)
		(end 269.484602 -94.223586)
		(width 0.10795)
		(layer "F.Cu")
		(net "SVID_ALERT1_CPU0_N")
	)
	(segment
		(start 322.379086 -127.451358)
		(end 322.379086 -128.279144)
		(width 0.10795)
		(layer "F.Cu")
		(net "SVID_ALERT1_CPU0_N")
	)
	(via
		(at 269.484602 -94.223586)
		(size 0.508)
		(drill 0.254)
		(layers "F.Cu" "B.Cu")
		(net "SVID_ALERT1_CPU0_N")
	)
	(via
		(at 322.379086 -127.451358)
		(size 0.508)
		(drill 0.254)
		(layers "F.Cu" "B.Cu")
		(net "SVID_ALERT1_CPU0_N")
	)
	(segment
		(start 277.940516 -93.452188)
		(end 278.24557 -93.147134)
		(width 0.089408)
		(layer "In4.Cu")
		(net "SVID_ALERT1_CPU0_N")
	)
	(segment
		(start 282.25877 -92.98178)
		(end 282.624784 -92.615766)
		(width 0.089408)
		(layer "In4.Cu")
		(net "SVID_ALERT1_CPU0_N")
	)
	(segment
		(start 318.795908 -126.339092)
		(end 320.391536 -127.93472)
		(width 0.089408)
		(layer "In4.Cu")
		(net "SVID_ALERT1_CPU0_N")
	)
	(segment
		(start 270.724122 -94.223586)
		(end 271.409668 -93.53804)
		(width 0.089408)
		(layer "In4.Cu")
		(net "SVID_ALERT1_CPU0_N")
	)
	(segment
		(start 318.795654 -125.953774)
		(end 318.795908 -125.954028)
		(width 0.089408)
		(layer "In4.Cu")
		(net "SVID_ALERT1_CPU0_N")
	)
	(segment
		(start 277.608792 -93.452188)
		(end 277.940516 -93.452188)
		(width 0.089408)
		(layer "In4.Cu")
		(net "SVID_ALERT1_CPU0_N")
	)
	(segment
		(start 293.542974 -103.755952)
		(end 295.62298 -103.755952)
		(width 0.089408)
		(layer "In4.Cu")
		(net "SVID_ALERT1_CPU0_N")
	)
	(segment
		(start 286.503872 -92.511372)
		(end 287.01873 -91.996514)
		(width 0.0889)
		(layer "In4.Cu")
		(net "SVID_ALERT1_CPU0_N")
	)
	(segment
		(start 318.46266 -125.51918)
		(end 318.795654 -125.852174)
		(width 0.089408)
		(layer "In4.Cu")
		(net "SVID_ALERT1_CPU0_N")
	)
	(segment
		(start 281.003756 -92.467176)
		(end 281.394154 -92.467176)
		(width 0.089408)
		(layer "In4.Cu")
		(net "SVID_ALERT1_CPU0_N")
	)
	(segment
		(start 321.895724 -127.93472)
		(end 322.379086 -127.451358)
		(width 0.089408)
		(layer "In4.Cu")
		(net "SVID_ALERT1_CPU0_N")
	)
	(segment
		(start 278.70277 -93.147134)
		(end 279.27427 -92.575634)
		(width 0.089408)
		(layer "In4.Cu")
		(net "SVID_ALERT1_CPU0_N")
	)
	(segment
		(start 287.01873 -91.996514)
		(end 287.446212 -91.996514)
		(width 0.0889)
		(layer "In4.Cu")
		(net "SVID_ALERT1_CPU0_N")
	)
	(segment
		(start 275.586698 -93.147134)
		(end 275.891752 -93.452188)
		(width 0.089408)
		(layer "In4.Cu")
		(net "SVID_ALERT1_CPU0_N")
	)
	(segment
		(start 285.65856 -92.971874)
		(end 286.119062 -92.511372)
		(width 0.089408)
		(layer "In4.Cu")
		(net "SVID_ALERT1_CPU0_N")
	)
	(segment
		(start 284.852364 -92.503244)
		(end 285.320994 -92.971874)
		(width 0.089408)
		(layer "In4.Cu")
		(net "SVID_ALERT1_CPU0_N")
	)
	(segment
		(start 273.869912 -93.147134)
		(end 274.174966 -93.452188)
		(width 0.089408)
		(layer "In4.Cu")
		(net "SVID_ALERT1_CPU0_N")
	)
	(segment
		(start 281.394154 -92.467176)
		(end 281.908758 -92.98178)
		(width 0.089408)
		(layer "In4.Cu")
		(net "SVID_ALERT1_CPU0_N")
	)
	(segment
		(start 274.174966 -93.452188)
		(end 274.50669 -93.452188)
		(width 0.089408)
		(layer "In4.Cu")
		(net "SVID_ALERT1_CPU0_N")
	)
	(segment
		(start 271.409668 -93.53804)
		(end 272.730214 -93.53804)
		(width 0.089408)
		(layer "In4.Cu")
		(net "SVID_ALERT1_CPU0_N")
	)
	(segment
		(start 276.223476 -93.452188)
		(end 276.52853 -93.147134)
		(width 0.089408)
		(layer "In4.Cu")
		(net "SVID_ALERT1_CPU0_N")
	)
	(segment
		(start 317.617348 -122.334528)
		(end 318.46266 -123.17984)
		(width 0.089408)
		(layer "In4.Cu")
		(net "SVID_ALERT1_CPU0_N")
	)
	(segment
		(start 280.102564 -92.969842)
		(end 280.50109 -92.969842)
		(width 0.089408)
		(layer "In4.Cu")
		(net "SVID_ALERT1_CPU0_N")
	)
	(segment
		(start 299.940726 -106.350308)
		(end 315.924946 -122.334528)
		(width 0.089408)
		(layer "In4.Cu")
		(net "SVID_ALERT1_CPU0_N")
	)
	(segment
		(start 281.908758 -92.98178)
		(end 282.25877 -92.98178)
		(width 0.089408)
		(layer "In4.Cu")
		(net "SVID_ALERT1_CPU0_N")
	)
	(segment
		(start 289.927792 -94.522036)
		(end 290.217606 -94.81185)
		(width 0.089408)
		(layer "In4.Cu")
		(net "SVID_ALERT1_CPU0_N")
	)
	(segment
		(start 295.62298 -103.755952)
		(end 298.217336 -106.350308)
		(width 0.089408)
		(layer "In4.Cu")
		(net "SVID_ALERT1_CPU0_N")
	)
	(segment
		(start 290.217606 -94.81185)
		(end 290.217606 -100.639626)
		(width 0.089408)
		(layer "In4.Cu")
		(net "SVID_ALERT1_CPU0_N")
	)
	(segment
		(start 290.217606 -100.639626)
		(end 290.583112 -101.005132)
		(width 0.089408)
		(layer "In4.Cu")
		(net "SVID_ALERT1_CPU0_N")
	)
	(segment
		(start 283.641546 -92.989654)
		(end 284.031944 -92.989654)
		(width 0.089408)
		(layer "In4.Cu")
		(net "SVID_ALERT1_CPU0_N")
	)
	(segment
		(start 288.769552 -92.95638)
		(end 288.90976 -92.95638)
		(width 0.0889)
		(layer "In4.Cu")
		(net "SVID_ALERT1_CPU0_N")
	)
	(segment
		(start 318.46266 -123.17984)
		(end 318.46266 -125.51918)
		(width 0.089408)
		(layer "In4.Cu")
		(net "SVID_ALERT1_CPU0_N")
	)
	(segment
		(start 272.730214 -93.53804)
		(end 273.12112 -93.147134)
		(width 0.089408)
		(layer "In4.Cu")
		(net "SVID_ALERT1_CPU0_N")
	)
	(segment
		(start 283.267658 -92.615766)
		(end 283.641546 -92.989654)
		(width 0.089408)
		(layer "In4.Cu")
		(net "SVID_ALERT1_CPU0_N")
	)
	(segment
		(start 290.583112 -101.005132)
		(end 290.792154 -101.005132)
		(width 0.089408)
		(layer "In4.Cu")
		(net "SVID_ALERT1_CPU0_N")
	)
	(segment
		(start 274.50669 -93.452188)
		(end 274.811744 -93.147134)
		(width 0.089408)
		(layer "In4.Cu")
		(net "SVID_ALERT1_CPU0_N")
	)
	(segment
		(start 279.708356 -92.575634)
		(end 280.102564 -92.969842)
		(width 0.089408)
		(layer "In4.Cu")
		(net "SVID_ALERT1_CPU0_N")
	)
	(segment
		(start 269.484602 -94.223586)
		(end 270.724122 -94.223586)
		(width 0.089408)
		(layer "In4.Cu")
		(net "SVID_ALERT1_CPU0_N")
	)
	(segment
		(start 298.217336 -106.350308)
		(end 299.940726 -106.350308)
		(width 0.089408)
		(layer "In4.Cu")
		(net "SVID_ALERT1_CPU0_N")
	)
	(segment
		(start 277.303738 -93.147134)
		(end 277.608792 -93.452188)
		(width 0.089408)
		(layer "In4.Cu")
		(net "SVID_ALERT1_CPU0_N")
	)
	(segment
		(start 273.12112 -93.147134)
		(end 273.869912 -93.147134)
		(width 0.089408)
		(layer "In4.Cu")
		(net "SVID_ALERT1_CPU0_N")
	)
	(segment
		(start 282.624784 -92.615766)
		(end 283.267658 -92.615766)
		(width 0.089408)
		(layer "In4.Cu")
		(net "SVID_ALERT1_CPU0_N")
	)
	(segment
		(start 318.795654 -125.852174)
		(end 318.795654 -125.953774)
		(width 0.089408)
		(layer "In4.Cu")
		(net "SVID_ALERT1_CPU0_N")
	)
	(segment
		(start 288.90976 -92.95638)
		(end 289.3568 -93.40342)
		(width 0.0889)
		(layer "In4.Cu")
		(net "SVID_ALERT1_CPU0_N")
	)
	(segment
		(start 290.792154 -101.005132)
		(end 293.542974 -103.755952)
		(width 0.089408)
		(layer "In4.Cu")
		(net "SVID_ALERT1_CPU0_N")
	)
	(segment
		(start 276.52853 -93.147134)
		(end 277.303738 -93.147134)
		(width 0.089408)
		(layer "In4.Cu")
		(net "SVID_ALERT1_CPU0_N")
	)
	(segment
		(start 278.24557 -93.147134)
		(end 278.70277 -93.147134)
		(width 0.089408)
		(layer "In4.Cu")
		(net "SVID_ALERT1_CPU0_N")
	)
	(segment
		(start 285.320994 -92.971874)
		(end 285.65856 -92.971874)
		(width 0.089408)
		(layer "In4.Cu")
		(net "SVID_ALERT1_CPU0_N")
	)
	(segment
		(start 318.795908 -125.954028)
		(end 318.795908 -126.339092)
		(width 0.089408)
		(layer "In4.Cu")
		(net "SVID_ALERT1_CPU0_N")
	)
	(segment
		(start 279.27427 -92.575634)
		(end 279.708356 -92.575634)
		(width 0.089408)
		(layer "In4.Cu")
		(net "SVID_ALERT1_CPU0_N")
	)
	(segment
		(start 315.924946 -122.334528)
		(end 317.617348 -122.334528)
		(width 0.089408)
		(layer "In4.Cu")
		(net "SVID_ALERT1_CPU0_N")
	)
	(segment
		(start 275.891752 -93.452188)
		(end 276.223476 -93.452188)
		(width 0.089408)
		(layer "In4.Cu")
		(net "SVID_ALERT1_CPU0_N")
	)
	(segment
		(start 289.3568 -93.40342)
		(end 289.3568 -94.264734)
		(width 0.0889)
		(layer "In4.Cu")
		(net "SVID_ALERT1_CPU0_N")
	)
	(segment
		(start 287.997392 -92.547694)
		(end 288.360866 -92.547694)
		(width 0.0889)
		(layer "In4.Cu")
		(net "SVID_ALERT1_CPU0_N")
	)
	(segment
		(start 284.031944 -92.989654)
		(end 284.518354 -92.503244)
		(width 0.089408)
		(layer "In4.Cu")
		(net "SVID_ALERT1_CPU0_N")
	)
	(segment
		(start 284.518354 -92.503244)
		(end 284.852364 -92.503244)
		(width 0.089408)
		(layer "In4.Cu")
		(net "SVID_ALERT1_CPU0_N")
	)
	(segment
		(start 280.50109 -92.969842)
		(end 281.003756 -92.467176)
		(width 0.089408)
		(layer "In4.Cu")
		(net "SVID_ALERT1_CPU0_N")
	)
	(segment
		(start 320.391536 -127.93472)
		(end 321.895724 -127.93472)
		(width 0.089408)
		(layer "In4.Cu")
		(net "SVID_ALERT1_CPU0_N")
	)
	(segment
		(start 288.360866 -92.547694)
		(end 288.769552 -92.95638)
		(width 0.0889)
		(layer "In4.Cu")
		(net "SVID_ALERT1_CPU0_N")
	)
	(segment
		(start 289.3568 -94.264734)
		(end 289.614102 -94.522036)
		(width 0.089408)
		(layer "In4.Cu")
		(net "SVID_ALERT1_CPU0_N")
	)
	(segment
		(start 286.119062 -92.511372)
		(end 286.503872 -92.511372)
		(width 0.089408)
		(layer "In4.Cu")
		(net "SVID_ALERT1_CPU0_N")
	)
	(segment
		(start 274.811744 -93.147134)
		(end 275.586698 -93.147134)
		(width 0.089408)
		(layer "In4.Cu")
		(net "SVID_ALERT1_CPU0_N")
	)
	(segment
		(start 287.446212 -91.996514)
		(end 287.997392 -92.547694)
		(width 0.0889)
		(layer "In4.Cu")
		(net "SVID_ALERT1_CPU0_N")
	)
	(segment
		(start 289.614102 -94.522036)
		(end 289.927792 -94.522036)
		(width 0.089408)
		(layer "In4.Cu")
		(net "SVID_ALERT1_CPU0_N")
	)
	(segment
		(start 163.8554 -67.5386)
		(end 163.747196 -67.5386)
		(width 0.10795)
		(layer "F.Cu")
		(net "SVID_ALERT0_CPU1_R_N")
	)
	(segment
		(start 19.05 -86.1187)
		(end 18.9992 -86.0679)
		(width 0.10795)
		(layer "F.Cu")
		(net "SVID_ALERT0_CPU1_R_N")
	)
	(segment
		(start 156.91485 -120.523)
		(end 157.1752 -120.523)
		(width 0.10795)
		(layer "F.Cu")
		(net "SVID_ALERT0_CPU1_R_N")
	)
	(segment
		(start 183.83885 -122.51055)
		(end 183.83885 -119.691404)
		(width 0.10795)
		(layer "F.Cu")
		(net "SVID_ALERT0_CPU1_R_N")
	)
	(segment
		(start 157.617414 -120.080786)
		(end 157.988 -120.080786)
		(width 0.10795)
		(layer "F.Cu")
		(net "SVID_ALERT0_CPU1_R_N")
	)
	(segment
		(start 187.475114 -116.05514)
		(end 187.475114 -115.55095)
		(width 0.10795)
		(layer "F.Cu")
		(net "SVID_ALERT0_CPU1_R_N")
	)
	(segment
		(start 163.747196 -67.5386)
		(end 163.472114 -67.813682)
		(width 0.10795)
		(layer "F.Cu")
		(net "SVID_ALERT0_CPU1_R_N")
	)
	(segment
		(start 164.084 -67.31)
		(end 163.8554 -67.5386)
		(width 0.10795)
		(layer "F.Cu")
		(net "SVID_ALERT0_CPU1_R_N")
	)
	(segment
		(start 183.83885 -119.691404)
		(end 187.475114 -116.05514)
		(width 0.10795)
		(layer "F.Cu")
		(net "SVID_ALERT0_CPU1_R_N")
	)
	(segment
		(start 19.05 -86.741)
		(end 19.05 -86.1187)
		(width 0.10795)
		(layer "F.Cu")
		(net "SVID_ALERT0_CPU1_R_N")
	)
	(segment
		(start 156.472636 -120.080786)
		(end 156.91485 -120.523)
		(width 0.10795)
		(layer "F.Cu")
		(net "SVID_ALERT0_CPU1_R_N")
	)
	(segment
		(start 182.9562 -123.3932)
		(end 183.83885 -122.51055)
		(width 0.10795)
		(layer "F.Cu")
		(net "SVID_ALERT0_CPU1_R_N")
	)
	(segment
		(start 157.1752 -120.523)
		(end 157.617414 -120.080786)
		(width 0.10795)
		(layer "F.Cu")
		(net "SVID_ALERT0_CPU1_R_N")
	)
	(via
		(at 19.4564 -86.868)
		(size 0.6604)
		(drill 0.3302)
		(layers "F.Cu" "B.Cu")
		(net "SVID_ALERT0_CPU1_R_N")
	)
	(via
		(at 163.472114 -67.813682)
		(size 0.508)
		(drill 0.254)
		(layers "F.Cu" "B.Cu")
		(net "SVID_ALERT0_CPU1_R_N")
	)
	(via
		(at 157.1752 -120.523)
		(size 0.508)
		(drill 0.254)
		(layers "F.Cu" "B.Cu")
		(net "SVID_ALERT0_CPU1_R_N")
	)
	(via
		(at 182.9562 -123.3932)
		(size 0.508)
		(drill 0.254)
		(layers "F.Cu" "B.Cu")
		(net "SVID_ALERT0_CPU1_R_N")
	)
	(via
		(at 18.9992 -86.0679)
		(size 0.508)
		(drill 0.254)
		(layers "F.Cu" "B.Cu")
		(net "SVID_ALERT0_CPU1_R_N")
	)
	(via
		(at 25.967944 -155.998418)
		(size 0.508)
		(drill 0.254)
		(layers "F.Cu" "B.Cu")
		(net "SVID_ALERT0_CPU1_R_N")
	)
	(segment
		(start 19.4564 -86.868)
		(end 18.9992 -86.4108)
		(width 0.10795)
		(layer "B.Cu")
		(net "SVID_ALERT0_CPU1_R_N")
	)
	(segment
		(start 18.9992 -86.4108)
		(end 18.9992 -86.0679)
		(width 0.10795)
		(layer "B.Cu")
		(net "SVID_ALERT0_CPU1_R_N")
	)
	(segment
		(start 160.064196 -127.988568)
		(end 158.862522 -129.190242)
		(width 0.089408)
		(layer "In2.Cu")
		(net "SVID_ALERT0_CPU1_R_N")
	)
	(segment
		(start 178.8541 -123.19)
		(end 174.6123 -123.19)
		(width 0.089408)
		(layer "In2.Cu")
		(net "SVID_ALERT0_CPU1_R_N")
	)
	(segment
		(start 167.267128 -126.427484)
		(end 167.17772 -126.516892)
		(width 0.089408)
		(layer "In2.Cu")
		(net "SVID_ALERT0_CPU1_R_N")
	)
	(segment
		(start 168.697656 -125.593348)
		(end 168.697656 -126.427484)
		(width 0.089408)
		(layer "In2.Cu")
		(net "SVID_ALERT0_CPU1_R_N")
	)
	(segment
		(start 92.184982 -157.355032)
		(end 90.864436 -156.034486)
		(width 0.089408)
		(layer "In2.Cu")
		(net "SVID_ALERT0_CPU1_R_N")
	)
	(segment
		(start 167.62476 -126.427484)
		(end 167.62476 -125.593348)
		(width 0.089408)
		(layer "In2.Cu")
		(net "SVID_ALERT0_CPU1_R_N")
	)
	(segment
		(start 168.697656 -126.427484)
		(end 168.608248 -126.516892)
		(width 0.089408)
		(layer "In2.Cu")
		(net "SVID_ALERT0_CPU1_R_N")
	)
	(segment
		(start 162.063684 -74.323194)
		(end 159.265874 -77.121004)
		(width 0.089408)
		(layer "In2.Cu")
		(net "SVID_ALERT0_CPU1_R_N")
	)
	(segment
		(start 158.862522 -151.4983)
		(end 159.900366 -152.536144)
		(width 0.089408)
		(layer "In2.Cu")
		(net "SVID_ALERT0_CPU1_R_N")
	)
	(segment
		(start 169.502328 -125.50394)
		(end 169.41292 -125.593348)
		(width 0.089408)
		(layer "In2.Cu")
		(net "SVID_ALERT0_CPU1_R_N")
	)
	(segment
		(start 170.88612 -125.50394)
		(end 169.502328 -125.50394)
		(width 0.089408)
		(layer "In2.Cu")
		(net "SVID_ALERT0_CPU1_R_N")
	)
	(segment
		(start 168.608248 -126.516892)
		(end 168.429432 -126.516892)
		(width 0.089408)
		(layer "In2.Cu")
		(net "SVID_ALERT0_CPU1_R_N")
	)
	(segment
		(start 169.055288 -126.344426)
		(end 169.055288 -125.593348)
		(width 0.089408)
		(layer "In2.Cu")
		(net "SVID_ALERT0_CPU1_R_N")
	)
	(segment
		(start 95.733108 -157.355032)
		(end 92.184982 -157.355032)
		(width 0.089408)
		(layer "In2.Cu")
		(net "SVID_ALERT0_CPU1_R_N")
	)
	(segment
		(start 159.900366 -152.536144)
		(end 162.74161 -152.536144)
		(width 0.089408)
		(layer "In2.Cu")
		(net "SVID_ALERT0_CPU1_R_N")
	)
	(segment
		(start 174.6123 -123.19)
		(end 172.840396 -124.961904)
		(width 0.089408)
		(layer "In2.Cu")
		(net "SVID_ALERT0_CPU1_R_N")
	)
	(segment
		(start 158.862522 -129.190242)
		(end 158.862522 -151.4983)
		(width 0.089408)
		(layer "In2.Cu")
		(net "SVID_ALERT0_CPU1_R_N")
	)
	(segment
		(start 166.641272 -125.50394)
		(end 166.551864 -125.593348)
		(width 0.089408)
		(layer "In2.Cu")
		(net "SVID_ALERT0_CPU1_R_N")
	)
	(segment
		(start 167.267128 -125.593348)
		(end 167.267128 -126.427484)
		(width 0.089408)
		(layer "In2.Cu")
		(net "SVID_ALERT0_CPU1_R_N")
	)
	(segment
		(start 168.96588 -125.50394)
		(end 168.787064 -125.50394)
		(width 0.089408)
		(layer "In2.Cu")
		(net "SVID_ALERT0_CPU1_R_N")
	)
	(segment
		(start 166.551864 -125.593348)
		(end 166.551864 -126.335536)
		(width 0.089408)
		(layer "In2.Cu")
		(net "SVID_ALERT0_CPU1_R_N")
	)
	(segment
		(start 166.551864 -126.335536)
		(end 164.898832 -127.988568)
		(width 0.089408)
		(layer "In2.Cu")
		(net "SVID_ALERT0_CPU1_R_N")
	)
	(segment
		(start 169.323512 -126.433834)
		(end 169.144696 -126.433834)
		(width 0.089408)
		(layer "In2.Cu")
		(net "SVID_ALERT0_CPU1_R_N")
	)
	(segment
		(start 171.428156 -124.961904)
		(end 170.88612 -125.50394)
		(width 0.089408)
		(layer "In2.Cu")
		(net "SVID_ALERT0_CPU1_R_N")
	)
	(segment
		(start 168.340024 -125.593348)
		(end 168.250616 -125.50394)
		(width 0.089408)
		(layer "In2.Cu")
		(net "SVID_ALERT0_CPU1_R_N")
	)
	(segment
		(start 167.892984 -126.516892)
		(end 167.714168 -126.516892)
		(width 0.089408)
		(layer "In2.Cu")
		(net "SVID_ALERT0_CPU1_R_N")
	)
	(segment
		(start 162.063684 -73.547478)
		(end 162.063684 -74.323194)
		(width 0.089408)
		(layer "In2.Cu")
		(net "SVID_ALERT0_CPU1_R_N")
	)
	(segment
		(start 163.964874 -153.759408)
		(end 163.964874 -155.419552)
		(width 0.089408)
		(layer "In2.Cu")
		(net "SVID_ALERT0_CPU1_R_N")
	)
	(segment
		(start 157.251146 -156.488892)
		(end 96.599248 -156.488892)
		(width 0.089408)
		(layer "In2.Cu")
		(net "SVID_ALERT0_CPU1_R_N")
	)
	(segment
		(start 168.429432 -126.516892)
		(end 168.340024 -126.427484)
		(width 0.089408)
		(layer "In2.Cu")
		(net "SVID_ALERT0_CPU1_R_N")
	)
	(segment
		(start 159.265874 -98.333306)
		(end 159.518858 -98.58629)
		(width 0.089408)
		(layer "In2.Cu")
		(net "SVID_ALERT0_CPU1_R_N")
	)
	(segment
		(start 161.557208 -100.624386)
		(end 161.557208 -108.533438)
		(width 0.089408)
		(layer "In2.Cu")
		(net "SVID_ALERT0_CPU1_R_N")
	)
	(segment
		(start 182.9562 -123.3932)
		(end 182.9054 -123.444)
		(width 0.089408)
		(layer "In2.Cu")
		(net "SVID_ALERT0_CPU1_R_N")
	)
	(segment
		(start 166.820088 -125.50394)
		(end 166.641272 -125.50394)
		(width 0.089408)
		(layer "In2.Cu")
		(net "SVID_ALERT0_CPU1_R_N")
	)
	(segment
		(start 163.35375 -67.813682)
		(end 162.522408 -68.645024)
		(width 0.089408)
		(layer "In2.Cu")
		(net "SVID_ALERT0_CPU1_R_N")
	)
	(segment
		(start 168.250616 -125.50394)
		(end 168.0718 -125.50394)
		(width 0.089408)
		(layer "In2.Cu")
		(net "SVID_ALERT0_CPU1_R_N")
	)
	(segment
		(start 166.909496 -125.593348)
		(end 166.820088 -125.50394)
		(width 0.089408)
		(layer "In2.Cu")
		(net "SVID_ALERT0_CPU1_R_N")
	)
	(segment
		(start 159.519112 -98.58629)
		(end 161.557208 -100.624386)
		(width 0.089408)
		(layer "In2.Cu")
		(net "SVID_ALERT0_CPU1_R_N")
	)
	(segment
		(start 167.982392 -126.427484)
		(end 167.892984 -126.516892)
		(width 0.089408)
		(layer "In2.Cu")
		(net "SVID_ALERT0_CPU1_R_N")
	)
	(segment
		(start 159.518858 -98.58629)
		(end 159.519112 -98.58629)
		(width 0.089408)
		(layer "In2.Cu")
		(net "SVID_ALERT0_CPU1_R_N")
	)
	(segment
		(start 167.714168 -126.516892)
		(end 167.62476 -126.427484)
		(width 0.089408)
		(layer "In2.Cu")
		(net "SVID_ALERT0_CPU1_R_N")
	)
	(segment
		(start 172.840396 -124.961904)
		(end 171.428156 -124.961904)
		(width 0.089408)
		(layer "In2.Cu")
		(net "SVID_ALERT0_CPU1_R_N")
	)
	(segment
		(start 169.41292 -126.344426)
		(end 169.323512 -126.433834)
		(width 0.089408)
		(layer "In2.Cu")
		(net "SVID_ALERT0_CPU1_R_N")
	)
	(segment
		(start 156.372306 -117.63502)
		(end 156.372306 -119.720106)
		(width 0.089408)
		(layer "In2.Cu")
		(net "SVID_ALERT0_CPU1_R_N")
	)
	(segment
		(start 166.909496 -126.427484)
		(end 166.909496 -125.593348)
		(width 0.089408)
		(layer "In2.Cu")
		(net "SVID_ALERT0_CPU1_R_N")
	)
	(segment
		(start 162.522408 -73.088754)
		(end 162.063684 -73.547478)
		(width 0.089408)
		(layer "In2.Cu")
		(net "SVID_ALERT0_CPU1_R_N")
	)
	(segment
		(start 169.144696 -126.433834)
		(end 169.055288 -126.344426)
		(width 0.089408)
		(layer "In2.Cu")
		(net "SVID_ALERT0_CPU1_R_N")
	)
	(segment
		(start 96.599248 -156.488892)
		(end 95.733108 -157.355032)
		(width 0.089408)
		(layer "In2.Cu")
		(net "SVID_ALERT0_CPU1_R_N")
	)
	(segment
		(start 156.718 -117.289326)
		(end 156.372306 -117.63502)
		(width 0.089408)
		(layer "In2.Cu")
		(net "SVID_ALERT0_CPU1_R_N")
	)
	(segment
		(start 156.718 -113.372646)
		(end 156.718 -117.289326)
		(width 0.089408)
		(layer "In2.Cu")
		(net "SVID_ALERT0_CPU1_R_N")
	)
	(segment
		(start 159.265874 -77.121004)
		(end 159.265874 -98.333306)
		(width 0.089408)
		(layer "In2.Cu")
		(net "SVID_ALERT0_CPU1_R_N")
	)
	(segment
		(start 179.1081 -123.444)
		(end 178.8541 -123.19)
		(width 0.089408)
		(layer "In2.Cu")
		(net "SVID_ALERT0_CPU1_R_N")
	)
	(segment
		(start 156.372306 -119.720106)
		(end 157.1752 -120.523)
		(width 0.089408)
		(layer "In2.Cu")
		(net "SVID_ALERT0_CPU1_R_N")
	)
	(segment
		(start 167.17772 -126.516892)
		(end 166.998904 -126.516892)
		(width 0.089408)
		(layer "In2.Cu")
		(net "SVID_ALERT0_CPU1_R_N")
	)
	(segment
		(start 162.511232 -156.873194)
		(end 157.635448 -156.873194)
		(width 0.089408)
		(layer "In2.Cu")
		(net "SVID_ALERT0_CPU1_R_N")
	)
	(segment
		(start 168.340024 -126.427484)
		(end 168.340024 -125.593348)
		(width 0.089408)
		(layer "In2.Cu")
		(net "SVID_ALERT0_CPU1_R_N")
	)
	(segment
		(start 169.41292 -125.593348)
		(end 169.41292 -126.344426)
		(width 0.089408)
		(layer "In2.Cu")
		(net "SVID_ALERT0_CPU1_R_N")
	)
	(segment
		(start 87.362792 -156.542486)
		(end 26.483056 -156.542486)
		(width 0.089408)
		(layer "In2.Cu")
		(net "SVID_ALERT0_CPU1_R_N")
	)
	(segment
		(start 167.982392 -125.593348)
		(end 167.982392 -126.427484)
		(width 0.089408)
		(layer "In2.Cu")
		(net "SVID_ALERT0_CPU1_R_N")
	)
	(segment
		(start 163.964874 -155.419552)
		(end 162.511232 -156.873194)
		(width 0.089408)
		(layer "In2.Cu")
		(net "SVID_ALERT0_CPU1_R_N")
	)
	(segment
		(start 166.998904 -126.516892)
		(end 166.909496 -126.427484)
		(width 0.089408)
		(layer "In2.Cu")
		(net "SVID_ALERT0_CPU1_R_N")
	)
	(segment
		(start 168.787064 -125.50394)
		(end 168.697656 -125.593348)
		(width 0.089408)
		(layer "In2.Cu")
		(net "SVID_ALERT0_CPU1_R_N")
	)
	(segment
		(start 26.483056 -156.542486)
		(end 25.967944 -156.027374)
		(width 0.089408)
		(layer "In2.Cu")
		(net "SVID_ALERT0_CPU1_R_N")
	)
	(segment
		(start 87.870792 -156.034486)
		(end 87.362792 -156.542486)
		(width 0.089408)
		(layer "In2.Cu")
		(net "SVID_ALERT0_CPU1_R_N")
	)
	(segment
		(start 161.557208 -108.533438)
		(end 156.718 -113.372646)
		(width 0.089408)
		(layer "In2.Cu")
		(net "SVID_ALERT0_CPU1_R_N")
	)
	(segment
		(start 157.635448 -156.873194)
		(end 157.251146 -156.488892)
		(width 0.089408)
		(layer "In2.Cu")
		(net "SVID_ALERT0_CPU1_R_N")
	)
	(segment
		(start 167.535352 -125.50394)
		(end 167.356536 -125.50394)
		(width 0.089408)
		(layer "In2.Cu")
		(net "SVID_ALERT0_CPU1_R_N")
	)
	(segment
		(start 25.967944 -156.027374)
		(end 25.967944 -155.998418)
		(width 0.089408)
		(layer "In2.Cu")
		(net "SVID_ALERT0_CPU1_R_N")
	)
	(segment
		(start 167.62476 -125.593348)
		(end 167.535352 -125.50394)
		(width 0.089408)
		(layer "In2.Cu")
		(net "SVID_ALERT0_CPU1_R_N")
	)
	(segment
		(start 162.74161 -152.536144)
		(end 163.964874 -153.759408)
		(width 0.089408)
		(layer "In2.Cu")
		(net "SVID_ALERT0_CPU1_R_N")
	)
	(segment
		(start 90.864436 -156.034486)
		(end 87.870792 -156.034486)
		(width 0.089408)
		(layer "In2.Cu")
		(net "SVID_ALERT0_CPU1_R_N")
	)
	(segment
		(start 164.898832 -127.988568)
		(end 160.064196 -127.988568)
		(width 0.089408)
		(layer "In2.Cu")
		(net "SVID_ALERT0_CPU1_R_N")
	)
	(segment
		(start 167.356536 -125.50394)
		(end 167.267128 -125.593348)
		(width 0.089408)
		(layer "In2.Cu")
		(net "SVID_ALERT0_CPU1_R_N")
	)
	(segment
		(start 168.0718 -125.50394)
		(end 167.982392 -125.593348)
		(width 0.089408)
		(layer "In2.Cu")
		(net "SVID_ALERT0_CPU1_R_N")
	)
	(segment
		(start 162.522408 -68.645024)
		(end 162.522408 -73.088754)
		(width 0.089408)
		(layer "In2.Cu")
		(net "SVID_ALERT0_CPU1_R_N")
	)
	(segment
		(start 169.055288 -125.593348)
		(end 168.96588 -125.50394)
		(width 0.089408)
		(layer "In2.Cu")
		(net "SVID_ALERT0_CPU1_R_N")
	)
	(segment
		(start 182.9054 -123.444)
		(end 179.1081 -123.444)
		(width 0.089408)
		(layer "In2.Cu")
		(net "SVID_ALERT0_CPU1_R_N")
	)
	(segment
		(start 163.472114 -67.813682)
		(end 163.35375 -67.813682)
		(width 0.089408)
		(layer "In2.Cu")
		(net "SVID_ALERT0_CPU1_R_N")
	)
	(segment
		(start 163.35375 -67.813682)
		(end 163.472114 -67.813682)
		(width 0.089408)
		(layer "In11.Cu")
		(net "SVID_ALERT0_CPU1_R_N")
	)
	(segment
		(start 18.9992 -86.0679)
		(end 18.9992 -87.250778)
		(width 0.089408)
		(layer "In11.Cu")
		(net "SVID_ALERT0_CPU1_R_N")
	)
	(segment
		(start 26.821384 -118.619778)
		(end 26.821384 -128.069848)
		(width 0.089408)
		(layer "In11.Cu")
		(net "SVID_ALERT0_CPU1_R_N")
	)
	(segment
		(start 162.83178 -86.054184)
		(end 162.83178 -77.907642)
		(width 0.089408)
		(layer "In11.Cu")
		(net "SVID_ALERT0_CPU1_R_N")
	)
	(segment
		(start 18.536412 -90.3478)
		(end 18.00352 -90.3478)
		(width 0.089408)
		(layer "In11.Cu")
		(net "SVID_ALERT0_CPU1_R_N")
	)
	(segment
		(start 182.9562 -123.3932)
		(end 182.9562 -123.264168)
		(width 0.089408)
		(layer "In11.Cu")
		(net "SVID_ALERT0_CPU1_R_N")
	)
	(segment
		(start 183.5658 -122.654568)
		(end 183.5658 -107.897676)
		(width 0.089408)
		(layer "In11.Cu")
		(net "SVID_ALERT0_CPU1_R_N")
	)
	(segment
		(start 26.821384 -128.069848)
		(end 26.140664 -128.750568)
		(width 0.089408)
		(layer "In11.Cu")
		(net "SVID_ALERT0_CPU1_R_N")
	)
	(segment
		(start 19.726148 -111.524542)
		(end 26.821384 -118.619778)
		(width 0.089408)
		(layer "In11.Cu")
		(net "SVID_ALERT0_CPU1_R_N")
	)
	(segment
		(start 19.646392 -87.89797)
		(end 19.646392 -89.23782)
		(width 0.089408)
		(layer "In11.Cu")
		(net "SVID_ALERT0_CPU1_R_N")
	)
	(segment
		(start 26.382218 -155.165298)
		(end 26.382218 -155.584144)
		(width 0.089408)
		(layer "In11.Cu")
		(net "SVID_ALERT0_CPU1_R_N")
	)
	(segment
		(start 178.313588 -103.281988)
		(end 176.10074 -101.06914)
		(width 0.089408)
		(layer "In11.Cu")
		(net "SVID_ALERT0_CPU1_R_N")
	)
	(segment
		(start 162.83178 -77.907642)
		(end 163.727638 -77.011784)
		(width 0.089408)
		(layer "In11.Cu")
		(net "SVID_ALERT0_CPU1_R_N")
	)
	(segment
		(start 17.508728 -98.017584)
		(end 18.559018 -99.067874)
		(width 0.089408)
		(layer "In11.Cu")
		(net "SVID_ALERT0_CPU1_R_N")
	)
	(segment
		(start 176.10074 -101.06914)
		(end 176.10074 -92.367862)
		(width 0.089408)
		(layer "In11.Cu")
		(net "SVID_ALERT0_CPU1_R_N")
	)
	(segment
		(start 175.171608 -88.946482)
		(end 173.792134 -87.567008)
		(width 0.089408)
		(layer "In11.Cu")
		(net "SVID_ALERT0_CPU1_R_N")
	)
	(segment
		(start 13.252196 -99.238562)
		(end 13.613638 -99.600004)
		(width 0.089408)
		(layer "In11.Cu")
		(net "SVID_ALERT0_CPU1_R_N")
	)
	(segment
		(start 17.139412 -91.211908)
		(end 15.391384 -91.211908)
		(width 0.089408)
		(layer "In11.Cu")
		(net "SVID_ALERT0_CPU1_R_N")
	)
	(segment
		(start 13.252196 -93.351096)
		(end 13.252196 -99.238562)
		(width 0.089408)
		(layer "In11.Cu")
		(net "SVID_ALERT0_CPU1_R_N")
	)
	(segment
		(start 18.558256 -101.294184)
		(end 18.558764 -101.294692)
		(width 0.089408)
		(layer "In11.Cu")
		(net "SVID_ALERT0_CPU1_R_N")
	)
	(segment
		(start 15.391384 -91.211908)
		(end 13.252196 -93.351096)
		(width 0.089408)
		(layer "In11.Cu")
		(net "SVID_ALERT0_CPU1_R_N")
	)
	(segment
		(start 178.950112 -103.281988)
		(end 178.313588 -103.281988)
		(width 0.089408)
		(layer "In11.Cu")
		(net "SVID_ALERT0_CPU1_R_N")
	)
	(segment
		(start 14.334744 -99.600004)
		(end 15.917164 -98.017584)
		(width 0.089408)
		(layer "In11.Cu")
		(net "SVID_ALERT0_CPU1_R_N")
	)
	(segment
		(start 164.895784 -74.369676)
		(end 163.168584 -72.642476)
		(width 0.089408)
		(layer "In11.Cu")
		(net "SVID_ALERT0_CPU1_R_N")
	)
	(segment
		(start 18.9992 -87.250778)
		(end 19.646392 -87.89797)
		(width 0.089408)
		(layer "In11.Cu")
		(net "SVID_ALERT0_CPU1_R_N")
	)
	(segment
		(start 26.29916 -155.08224)
		(end 26.382218 -155.165298)
		(width 0.089408)
		(layer "In11.Cu")
		(net "SVID_ALERT0_CPU1_R_N")
	)
	(segment
		(start 18.558764 -108.036106)
		(end 19.726148 -109.20349)
		(width 0.089408)
		(layer "In11.Cu")
		(net "SVID_ALERT0_CPU1_R_N")
	)
	(segment
		(start 162.5219 -68.645532)
		(end 163.35375 -67.813682)
		(width 0.089408)
		(layer "In11.Cu")
		(net "SVID_ALERT0_CPU1_R_N")
	)
	(segment
		(start 19.646392 -89.23782)
		(end 18.536412 -90.3478)
		(width 0.089408)
		(layer "In11.Cu")
		(net "SVID_ALERT0_CPU1_R_N")
	)
	(segment
		(start 19.726148 -109.20349)
		(end 19.726148 -111.524542)
		(width 0.089408)
		(layer "In11.Cu")
		(net "SVID_ALERT0_CPU1_R_N")
	)
	(segment
		(start 163.168584 -72.642476)
		(end 163.168584 -72.318118)
		(width 0.089408)
		(layer "In11.Cu")
		(net "SVID_ALERT0_CPU1_R_N")
	)
	(segment
		(start 164.27958 -77.011784)
		(end 164.895784 -76.39558)
		(width 0.089408)
		(layer "In11.Cu")
		(net "SVID_ALERT0_CPU1_R_N")
	)
	(segment
		(start 18.559018 -99.067874)
		(end 18.559018 -100.561394)
		(width 0.089408)
		(layer "In11.Cu")
		(net "SVID_ALERT0_CPU1_R_N")
	)
	(segment
		(start 176.10074 -92.367862)
		(end 175.171608 -91.43873)
		(width 0.089408)
		(layer "In11.Cu")
		(net "SVID_ALERT0_CPU1_R_N")
	)
	(segment
		(start 163.727638 -77.011784)
		(end 164.27958 -77.011784)
		(width 0.089408)
		(layer "In11.Cu")
		(net "SVID_ALERT0_CPU1_R_N")
	)
	(segment
		(start 164.344604 -87.567008)
		(end 162.83178 -86.054184)
		(width 0.089408)
		(layer "In11.Cu")
		(net "SVID_ALERT0_CPU1_R_N")
	)
	(segment
		(start 26.140664 -131.509008)
		(end 26.29916 -131.667504)
		(width 0.089408)
		(layer "In11.Cu")
		(net "SVID_ALERT0_CPU1_R_N")
	)
	(segment
		(start 26.140664 -128.750568)
		(end 26.140664 -131.509008)
		(width 0.089408)
		(layer "In11.Cu")
		(net "SVID_ALERT0_CPU1_R_N")
	)
	(segment
		(start 183.5658 -107.897676)
		(end 178.950112 -103.281988)
		(width 0.089408)
		(layer "In11.Cu")
		(net "SVID_ALERT0_CPU1_R_N")
	)
	(segment
		(start 163.168584 -72.318118)
		(end 162.5219 -71.671434)
		(width 0.089408)
		(layer "In11.Cu")
		(net "SVID_ALERT0_CPU1_R_N")
	)
	(segment
		(start 182.9562 -123.264168)
		(end 183.5658 -122.654568)
		(width 0.089408)
		(layer "In11.Cu")
		(net "SVID_ALERT0_CPU1_R_N")
	)
	(segment
		(start 173.792134 -87.567008)
		(end 164.344604 -87.567008)
		(width 0.089408)
		(layer "In11.Cu")
		(net "SVID_ALERT0_CPU1_R_N")
	)
	(segment
		(start 175.171608 -91.43873)
		(end 175.171608 -88.946482)
		(width 0.089408)
		(layer "In11.Cu")
		(net "SVID_ALERT0_CPU1_R_N")
	)
	(segment
		(start 13.613638 -99.600004)
		(end 14.334744 -99.600004)
		(width 0.089408)
		(layer "In11.Cu")
		(net "SVID_ALERT0_CPU1_R_N")
	)
	(segment
		(start 18.559018 -100.561394)
		(end 18.558256 -100.562156)
		(width 0.089408)
		(layer "In11.Cu")
		(net "SVID_ALERT0_CPU1_R_N")
	)
	(segment
		(start 15.917164 -98.017584)
		(end 17.508728 -98.017584)
		(width 0.089408)
		(layer "In11.Cu")
		(net "SVID_ALERT0_CPU1_R_N")
	)
	(segment
		(start 18.00352 -90.3478)
		(end 17.139412 -91.211908)
		(width 0.089408)
		(layer "In11.Cu")
		(net "SVID_ALERT0_CPU1_R_N")
	)
	(segment
		(start 164.895784 -76.39558)
		(end 164.895784 -74.369676)
		(width 0.089408)
		(layer "In11.Cu")
		(net "SVID_ALERT0_CPU1_R_N")
	)
	(segment
		(start 18.558764 -101.294692)
		(end 18.558764 -108.036106)
		(width 0.089408)
		(layer "In11.Cu")
		(net "SVID_ALERT0_CPU1_R_N")
	)
	(segment
		(start 26.382218 -155.584144)
		(end 25.967944 -155.998418)
		(width 0.089408)
		(layer "In11.Cu")
		(net "SVID_ALERT0_CPU1_R_N")
	)
	(segment
		(start 26.29916 -131.667504)
		(end 26.29916 -155.08224)
		(width 0.089408)
		(layer "In11.Cu")
		(net "SVID_ALERT0_CPU1_R_N")
	)
	(segment
		(start 162.5219 -71.671434)
		(end 162.5219 -68.645532)
		(width 0.089408)
		(layer "In11.Cu")
		(net "SVID_ALERT0_CPU1_R_N")
	)
	(segment
		(start 18.558256 -100.562156)
		(end 18.558256 -101.294184)
		(width 0.089408)
		(layer "In11.Cu")
		(net "SVID_ALERT0_CPU1_R_N")
	)
	(segment
		(start 154.817064 -120.080786)
		(end 154.6352 -120.26265)
		(width 0.10795)
		(layer "F.Cu")
		(net "SVID_ALERT0_CPU1_N")
	)
	(segment
		(start 103.806244 -91.25204)
		(end 104.48036 -91.25204)
		(width 0.10795)
		(layer "F.Cu")
		(net "SVID_ALERT0_CPU1_N")
	)
	(segment
		(start 104.48036 -91.25204)
		(end 104.503474 -91.275154)
		(width 0.10795)
		(layer "F.Cu")
		(net "SVID_ALERT0_CPU1_N")
	)
	(segment
		(start 155.583636 -120.080786)
		(end 154.817064 -120.080786)
		(width 0.10795)
		(layer "F.Cu")
		(net "SVID_ALERT0_CPU1_N")
	)
	(via
		(at 104.503474 -91.275154)
		(size 0.508)
		(drill 0.254)
		(layers "F.Cu" "B.Cu")
		(net "SVID_ALERT0_CPU1_N")
	)
	(via
		(at 154.6352 -120.26265)
		(size 0.508)
		(drill 0.254)
		(layers "F.Cu" "B.Cu")
		(net "SVID_ALERT0_CPU1_N")
	)
	(segment
		(start 127.1524 -101.5238)
		(end 128.6764 -103.0478)
		(width 0.089408)
		(layer "In4.Cu")
		(net "SVID_ALERT0_CPU1_N")
	)
	(segment
		(start 121.148856 -92.479368)
		(end 121.509536 -92.479368)
		(width 0.0889)
		(layer "In4.Cu")
		(net "SVID_ALERT0_CPU1_N")
	)
	(segment
		(start 121.509536 -92.479368)
		(end 121.751598 -92.237306)
		(width 0.0889)
		(layer "In4.Cu")
		(net "SVID_ALERT0_CPU1_N")
	)
	(segment
		(start 123.058428 -92.652088)
		(end 123.091194 -92.652088)
		(width 0.0889)
		(layer "In4.Cu")
		(net "SVID_ALERT0_CPU1_N")
	)
	(segment
		(start 109.322616 -92.652088)
		(end 109.358176 -92.652088)
		(width 0.0889)
		(layer "In4.Cu")
		(net "SVID_ALERT0_CPU1_N")
	)
	(segment
		(start 119.40286 -92.465144)
		(end 119.886476 -92.465144)
		(width 0.0889)
		(layer "In4.Cu")
		(net "SVID_ALERT0_CPU1_N")
	)
	(segment
		(start 111.039402 -92.652088)
		(end 111.074962 -92.652088)
		(width 0.0889)
		(layer "In4.Cu")
		(net "SVID_ALERT0_CPU1_N")
	)
	(segment
		(start 125.824742 -100.881688)
		(end 126.466854 -101.5238)
		(width 0.089408)
		(layer "In4.Cu")
		(net "SVID_ALERT0_CPU1_N")
	)
	(segment
		(start 125.240288 -100.63607)
		(end 125.485906 -100.881688)
		(width 0.089408)
		(layer "In4.Cu")
		(net "SVID_ALERT0_CPU1_N")
	)
	(segment
		(start 108.173012 -92.156534)
		(end 108.493052 -92.156534)
		(width 0.0889)
		(layer "In4.Cu")
		(net "SVID_ALERT0_CPU1_N")
	)
	(segment
		(start 120.826022 -92.156534)
		(end 121.148856 -92.479368)
		(width 0.0889)
		(layer "In4.Cu")
		(net "SVID_ALERT0_CPU1_N")
	)
	(segment
		(start 136.217914 -106.553)
		(end 149.446488 -119.781574)
		(width 0.089408)
		(layer "In4.Cu")
		(net "SVID_ALERT0_CPU1_N")
	)
	(segment
		(start 126.466854 -101.5238)
		(end 127.1524 -101.5238)
		(width 0.089408)
		(layer "In4.Cu")
		(net "SVID_ALERT0_CPU1_N")
	)
	(segment
		(start 124.334524 -94.212156)
		(end 124.668026 -94.545658)
		(width 0.0889)
		(layer "In4.Cu")
		(net "SVID_ALERT0_CPU1_N")
	)
	(segment
		(start 117.674898 -92.48648)
		(end 118.222522 -92.48648)
		(width 0.0889)
		(layer "In4.Cu")
		(net "SVID_ALERT0_CPU1_N")
	)
	(segment
		(start 115.083082 -92.14866)
		(end 115.442238 -92.14866)
		(width 0.0889)
		(layer "In4.Cu")
		(net "SVID_ALERT0_CPU1_N")
	)
	(segment
		(start 112.756442 -92.652088)
		(end 112.792002 -92.652088)
		(width 0.0889)
		(layer "In4.Cu")
		(net "SVID_ALERT0_CPU1_N")
	)
	(segment
		(start 114.766598 -92.465144)
		(end 115.083082 -92.14866)
		(width 0.0889)
		(layer "In4.Cu")
		(net "SVID_ALERT0_CPU1_N")
	)
	(segment
		(start 115.442238 -92.14866)
		(end 115.92941 -91.661488)
		(width 0.0889)
		(layer "In4.Cu")
		(net "SVID_ALERT0_CPU1_N")
	)
	(segment
		(start 125.240288 -94.807532)
		(end 125.240288 -100.63607)
		(width 0.089408)
		(layer "In4.Cu")
		(net "SVID_ALERT0_CPU1_N")
	)
	(segment
		(start 120.195086 -92.156534)
		(end 120.826022 -92.156534)
		(width 0.0889)
		(layer "In4.Cu")
		(net "SVID_ALERT0_CPU1_N")
	)
	(segment
		(start 118.603014 -92.105988)
		(end 119.043704 -92.105988)
		(width 0.0889)
		(layer "In4.Cu")
		(net "SVID_ALERT0_CPU1_N")
	)
	(segment
		(start 113.979452 -92.356686)
		(end 114.08791 -92.465144)
		(width 0.0889)
		(layer "In4.Cu")
		(net "SVID_ALERT0_CPU1_N")
	)
	(segment
		(start 149.446488 -119.781574)
		(end 154.154124 -119.781574)
		(width 0.089408)
		(layer "In4.Cu")
		(net "SVID_ALERT0_CPU1_N")
	)
	(segment
		(start 123.913138 -93.147134)
		(end 123.945904 -93.147134)
		(width 0.0889)
		(layer "In4.Cu")
		(net "SVID_ALERT0_CPU1_N")
	)
	(segment
		(start 107.848146 -92.4814)
		(end 108.173012 -92.156534)
		(width 0.0889)
		(layer "In4.Cu")
		(net "SVID_ALERT0_CPU1_N")
	)
	(segment
		(start 129.920746 -103.0478)
		(end 133.425946 -106.553)
		(width 0.089408)
		(layer "In4.Cu")
		(net "SVID_ALERT0_CPU1_N")
	)
	(segment
		(start 122.45721 -92.228924)
		(end 122.496834 -92.268548)
		(width 0.0889)
		(layer "In4.Cu")
		(net "SVID_ALERT0_CPU1_N")
	)
	(segment
		(start 104.503474 -91.275154)
		(end 106.032554 -91.275154)
		(width 0.089408)
		(layer "In4.Cu")
		(net "SVID_ALERT0_CPU1_N")
	)
	(segment
		(start 124.334524 -93.546676)
		(end 124.334524 -94.212156)
		(width 0.0889)
		(layer "In4.Cu")
		(net "SVID_ALERT0_CPU1_N")
	)
	(segment
		(start 106.032554 -91.275154)
		(end 107.2388 -92.4814)
		(width 0.089408)
		(layer "In4.Cu")
		(net "SVID_ALERT0_CPU1_N")
	)
	(segment
		(start 121.94667 -92.156534)
		(end 122.282458 -92.156534)
		(width 0.0889)
		(layer "In4.Cu")
		(net "SVID_ALERT0_CPU1_N")
	)
	(segment
		(start 125.485906 -100.881688)
		(end 125.824742 -100.881688)
		(width 0.089408)
		(layer "In4.Cu")
		(net "SVID_ALERT0_CPU1_N")
	)
	(segment
		(start 114.08791 -92.465144)
		(end 114.766598 -92.465144)
		(width 0.0889)
		(layer "In4.Cu")
		(net "SVID_ALERT0_CPU1_N")
	)
	(segment
		(start 124.978414 -94.545658)
		(end 125.240288 -94.807532)
		(width 0.089408)
		(layer "In4.Cu")
		(net "SVID_ALERT0_CPU1_N")
	)
	(segment
		(start 119.043704 -92.105988)
		(end 119.40286 -92.465144)
		(width 0.0889)
		(layer "In4.Cu")
		(net "SVID_ALERT0_CPU1_N")
	)
	(segment
		(start 133.425946 -106.553)
		(end 136.217914 -106.553)
		(width 0.089408)
		(layer "In4.Cu")
		(net "SVID_ALERT0_CPU1_N")
	)
	(segment
		(start 119.886476 -92.465144)
		(end 120.195086 -92.156534)
		(width 0.0889)
		(layer "In4.Cu")
		(net "SVID_ALERT0_CPU1_N")
	)
	(segment
		(start 117.319298 -92.13088)
		(end 117.674898 -92.48648)
		(width 0.0889)
		(layer "In4.Cu")
		(net "SVID_ALERT0_CPU1_N")
	)
	(segment
		(start 116.959888 -92.13088)
		(end 117.319298 -92.13088)
		(width 0.0889)
		(layer "In4.Cu")
		(net "SVID_ALERT0_CPU1_N")
	)
	(segment
		(start 154.154124 -119.781574)
		(end 154.6352 -120.26265)
		(width 0.089408)
		(layer "In4.Cu")
		(net "SVID_ALERT0_CPU1_N")
	)
	(segment
		(start 124.668026 -94.545658)
		(end 124.978414 -94.545658)
		(width 0.089408)
		(layer "In4.Cu")
		(net "SVID_ALERT0_CPU1_N")
	)
	(segment
		(start 115.92941 -91.661488)
		(end 116.490496 -91.661488)
		(width 0.0889)
		(layer "In4.Cu")
		(net "SVID_ALERT0_CPU1_N")
	)
	(segment
		(start 107.2388 -92.4814)
		(end 107.848146 -92.4814)
		(width 0.089408)
		(layer "In4.Cu")
		(net "SVID_ALERT0_CPU1_N")
	)
	(segment
		(start 118.222522 -92.48648)
		(end 118.603014 -92.105988)
		(width 0.0889)
		(layer "In4.Cu")
		(net "SVID_ALERT0_CPU1_N")
	)
	(segment
		(start 128.6764 -103.0478)
		(end 129.920746 -103.0478)
		(width 0.089408)
		(layer "In4.Cu")
		(net "SVID_ALERT0_CPU1_N")
	)
	(segment
		(start 110.54207 -92.350844)
		(end 110.545372 -92.356686)
		(width 0.0889)
		(layer "In4.Cu")
		(net "SVID_ALERT0_CPU1_N")
	)
	(segment
		(start 116.490496 -91.661488)
		(end 116.959888 -92.13088)
		(width 0.0889)
		(layer "In4.Cu")
		(net "SVID_ALERT0_CPU1_N")
	)
	(arc
		(start 121.751598 -92.237306)
		(mid 121.841098 -92.177504)
		(end 121.94667 -92.156534)
		(width 0.0889)
		(layer "In4.Cu")
		(net "SVID_ALERT0_CPU1_N")
	)
	(arc
		(start 122.496834 -92.268548)
		(mid 122.533505 -92.310402)
		(end 122.564398 -92.356686)
		(width 0.0889)
		(layer "In4.Cu")
		(net "SVID_ALERT0_CPU1_N")
	)
	(arc
		(start 108.493052 -92.156534)
		(mid 108.686902 -92.212884)
		(end 108.828586 -92.356686)
		(width 0.0889)
		(layer "In4.Cu")
		(net "SVID_ALERT0_CPU1_N")
	)
	(arc
		(start 123.945904 -93.147134)
		(mid 124.221281 -93.268026)
		(end 124.334524 -93.546676)
		(width 0.0889)
		(layer "In4.Cu")
		(net "SVID_ALERT0_CPU1_N")
	)
	(arc
		(start 123.422918 -92.851986)
		(mid 123.629922 -93.06285)
		(end 123.913138 -93.147134)
		(width 0.0889)
		(layer "In4.Cu")
		(net "SVID_ALERT0_CPU1_N")
	)
	(arc
		(start 110.545372 -92.356686)
		(mid 110.75398 -92.568618)
		(end 111.039402 -92.652088)
		(width 0.0889)
		(layer "In4.Cu")
		(net "SVID_ALERT0_CPU1_N")
	)
	(arc
		(start 112.262412 -92.356686)
		(mid 112.47102 -92.568618)
		(end 112.756442 -92.652088)
		(width 0.0889)
		(layer "In4.Cu")
		(net "SVID_ALERT0_CPU1_N")
	)
	(arc
		(start 109.852206 -92.356686)
		(mid 110.195496 -92.15639)
		(end 110.54207 -92.350844)
		(width 0.0889)
		(layer "In4.Cu")
		(net "SVID_ALERT0_CPU1_N")
	)
	(arc
		(start 122.282458 -92.156534)
		(mid 122.377035 -92.175347)
		(end 122.45721 -92.228924)
		(width 0.0889)
		(layer "In4.Cu")
		(net "SVID_ALERT0_CPU1_N")
	)
	(arc
		(start 122.564398 -92.356686)
		(mid 122.773006 -92.568618)
		(end 123.058428 -92.652088)
		(width 0.0889)
		(layer "In4.Cu")
		(net "SVID_ALERT0_CPU1_N")
	)
	(arc
		(start 108.828586 -92.356686)
		(mid 109.037194 -92.568618)
		(end 109.322616 -92.652088)
		(width 0.0889)
		(layer "In4.Cu")
		(net "SVID_ALERT0_CPU1_N")
	)
	(arc
		(start 111.568992 -92.356686)
		(mid 111.915702 -92.156375)
		(end 112.262412 -92.356686)
		(width 0.0889)
		(layer "In4.Cu")
		(net "SVID_ALERT0_CPU1_N")
	)
	(arc
		(start 113.286032 -92.356686)
		(mid 113.632742 -92.156375)
		(end 113.979452 -92.356686)
		(width 0.0889)
		(layer "In4.Cu")
		(net "SVID_ALERT0_CPU1_N")
	)
	(arc
		(start 123.091194 -92.652088)
		(mid 123.282836 -92.709254)
		(end 123.422918 -92.851986)
		(width 0.0889)
		(layer "In4.Cu")
		(net "SVID_ALERT0_CPU1_N")
	)
	(arc
		(start 111.074962 -92.652088)
		(mid 111.360386 -92.568621)
		(end 111.568992 -92.356686)
		(width 0.0889)
		(layer "In4.Cu")
		(net "SVID_ALERT0_CPU1_N")
	)
	(arc
		(start 112.792002 -92.652088)
		(mid 113.077426 -92.568621)
		(end 113.286032 -92.356686)
		(width 0.0889)
		(layer "In4.Cu")
		(net "SVID_ALERT0_CPU1_N")
	)
	(arc
		(start 109.358176 -92.652088)
		(mid 109.6436 -92.568621)
		(end 109.852206 -92.356686)
		(width 0.0889)
		(layer "In4.Cu")
		(net "SVID_ALERT0_CPU1_N")
	)
	(segment
		(start 203.581 -105.918)
		(end 204.089 -105.918)
		(width 0.10795)
		(layer "F.Cu")
		(net "SVID_ALERT0_CPU0_R_N")
	)
	(segment
		(start 203.35748 -105.69448)
		(end 203.581 -105.918)
		(width 0.10795)
		(layer "F.Cu")
		(net "SVID_ALERT0_CPU0_R_N")
	)
	(segment
		(start 184.531 -63.538354)
		(end 184.531 -64.135)
		(width 0.10795)
		(layer "F.Cu")
		(net "SVID_ALERT0_CPU0_R_N")
	)
	(segment
		(start 352.454972 -115.55095)
		(end 352.454972 -115.574572)
		(width 0.10795)
		(layer "F.Cu")
		(net "SVID_ALERT0_CPU0_R_N")
	)
	(segment
		(start 184.487312 -63.494666)
		(end 184.531 -63.538354)
		(width 0.10795)
		(layer "F.Cu")
		(net "SVID_ALERT0_CPU0_R_N")
	)
	(segment
		(start 203.35748 -105.41254)
		(end 203.35748 -105.69448)
		(width 0.10795)
		(layer "F.Cu")
		(net "SVID_ALERT0_CPU0_R_N")
	)
	(segment
		(start 352.454972 -115.574572)
		(end 353.0854 -116.205)
		(width 0.10795)
		(layer "F.Cu")
		(net "SVID_ALERT0_CPU0_R_N")
	)
	(segment
		(start 203.35494 -105.41)
		(end 203.35748 -105.41254)
		(width 0.10795)
		(layer "F.Cu")
		(net "SVID_ALERT0_CPU0_R_N")
	)
	(via
		(at 334.47228 -107.0356)
		(size 0.508)
		(drill 0.254)
		(layers "F.Cu" "B.Cu")
		(net "SVID_ALERT0_CPU0_R_N")
	)
	(via
		(at 317.30442 -102.113588)
		(size 0.508)
		(drill 0.254)
		(layers "F.Cu" "B.Cu")
		(net "SVID_ALERT0_CPU0_R_N")
	)
	(via
		(at 339.569044 -89.182702)
		(size 0.508)
		(drill 0.254)
		(layers "F.Cu" "B.Cu")
		(net "SVID_ALERT0_CPU0_R_N")
	)
	(via
		(at 184.487312 -63.494666)
		(size 0.508)
		(drill 0.254)
		(layers "F.Cu" "B.Cu")
		(net "SVID_ALERT0_CPU0_R_N")
	)
	(via
		(at 203.9366 -106.07421)
		(size 0.6604)
		(drill 0.3302)
		(layers "F.Cu" "B.Cu")
		(net "SVID_ALERT0_CPU0_R_N")
	)
	(via
		(at 353.0854 -116.205)
		(size 0.508)
		(drill 0.254)
		(layers "F.Cu" "B.Cu")
		(net "SVID_ALERT0_CPU0_R_N")
	)
	(via
		(at 203.35494 -105.41)
		(size 0.508)
		(drill 0.254)
		(layers "F.Cu" "B.Cu")
		(net "SVID_ALERT0_CPU0_R_N")
	)
	(segment
		(start 339.690456 -89.304114)
		(end 340.657688 -89.304114)
		(width 0.10795)
		(layer "B.Cu")
		(net "SVID_ALERT0_CPU0_R_N")
	)
	(segment
		(start 204.16139 -106.299)
		(end 203.9366 -106.07421)
		(width 0.10795)
		(layer "B.Cu")
		(net "SVID_ALERT0_CPU0_R_N")
	)
	(segment
		(start 203.9366 -106.07421)
		(end 203.35494 -105.49255)
		(width 0.10795)
		(layer "B.Cu")
		(net "SVID_ALERT0_CPU0_R_N")
	)
	(segment
		(start 204.851 -106.299)
		(end 204.16139 -106.299)
		(width 0.10795)
		(layer "B.Cu")
		(net "SVID_ALERT0_CPU0_R_N")
	)
	(segment
		(start 203.35494 -105.49255)
		(end 203.35494 -105.41)
		(width 0.10795)
		(layer "B.Cu")
		(net "SVID_ALERT0_CPU0_R_N")
	)
	(segment
		(start 340.657688 -89.304114)
		(end 341.1982 -88.763602)
		(width 0.10795)
		(layer "B.Cu")
		(net "SVID_ALERT0_CPU0_R_N")
	)
	(segment
		(start 339.569044 -89.182702)
		(end 339.690456 -89.304114)
		(width 0.10795)
		(layer "B.Cu")
		(net "SVID_ALERT0_CPU0_R_N")
	)
	(segment
		(start 341.1982 -88.763602)
		(end 341.1982 -88.3412)
		(width 0.10795)
		(layer "B.Cu")
		(net "SVID_ALERT0_CPU0_R_N")
	)
	(segment
		(start 180.387498 -80.999584)
		(end 180.062378 -81.324704)
		(width 0.089408)
		(layer "In2.Cu")
		(net "SVID_ALERT0_CPU0_R_N")
	)
	(segment
		(start 202.846686 -103.23195)
		(end 197.438264 -103.23195)
		(width 0.089408)
		(layer "In2.Cu")
		(net "SVID_ALERT0_CPU0_R_N")
	)
	(segment
		(start 354.94722 -108.41736)
		(end 353.716844 -107.186984)
		(width 0.089408)
		(layer "In2.Cu")
		(net "SVID_ALERT0_CPU0_R_N")
	)
	(segment
		(start 353.716844 -107.186984)
		(end 342.81364 -107.186984)
		(width 0.089408)
		(layer "In2.Cu")
		(net "SVID_ALERT0_CPU0_R_N")
	)
	(segment
		(start 183.061356 -97.187766)
		(end 183.061356 -82.117692)
		(width 0.089408)
		(layer "In2.Cu")
		(net "SVID_ALERT0_CPU0_R_N")
	)
	(segment
		(start 203.35494 -105.41)
		(end 203.35494 -103.740204)
		(width 0.089408)
		(layer "In2.Cu")
		(net "SVID_ALERT0_CPU0_R_N")
	)
	(segment
		(start 353.0854 -116.205)
		(end 353.0854 -115.742212)
		(width 0.089408)
		(layer "In2.Cu")
		(net "SVID_ALERT0_CPU0_R_N")
	)
	(segment
		(start 203.35494 -103.740204)
		(end 202.846686 -103.23195)
		(width 0.089408)
		(layer "In2.Cu")
		(net "SVID_ALERT0_CPU0_R_N")
	)
	(segment
		(start 187.204096 -107.090718)
		(end 182.60949 -102.496112)
		(width 0.089408)
		(layer "In2.Cu")
		(net "SVID_ALERT0_CPU0_R_N")
	)
	(segment
		(start 182.60949 -97.639632)
		(end 183.061356 -97.187766)
		(width 0.089408)
		(layer "In2.Cu")
		(net "SVID_ALERT0_CPU0_R_N")
	)
	(segment
		(start 178.23688 -80.446626)
		(end 178.23688 -78.649576)
		(width 0.089408)
		(layer "In2.Cu")
		(net "SVID_ALERT0_CPU0_R_N")
	)
	(segment
		(start 340.389464 -104.762554)
		(end 340.13648 -104.50957)
		(width 0.089408)
		(layer "In2.Cu")
		(net "SVID_ALERT0_CPU0_R_N")
	)
	(segment
		(start 179.629308 -67.322192)
		(end 179.629308 -66.395092)
		(width 0.089408)
		(layer "In2.Cu")
		(net "SVID_ALERT0_CPU0_R_N")
	)
	(segment
		(start 334.049878 -106.58983)
		(end 334.049878 -106.613198)
		(width 0.089408)
		(layer "In2.Cu")
		(net "SVID_ALERT0_CPU0_R_N")
	)
	(segment
		(start 195.740782 -106.491278)
		(end 195.141342 -107.090718)
		(width 0.089408)
		(layer "In2.Cu")
		(net "SVID_ALERT0_CPU0_R_N")
	)
	(segment
		(start 179.629308 -66.395092)
		(end 180.847492 -65.176908)
		(width 0.089408)
		(layer "In2.Cu")
		(net "SVID_ALERT0_CPU0_R_N")
	)
	(segment
		(start 181.943248 -80.999584)
		(end 180.387498 -80.999584)
		(width 0.089408)
		(layer "In2.Cu")
		(net "SVID_ALERT0_CPU0_R_N")
	)
	(segment
		(start 182.60949 -102.496112)
		(end 182.60949 -97.639632)
		(width 0.089408)
		(layer "In2.Cu")
		(net "SVID_ALERT0_CPU0_R_N")
	)
	(segment
		(start 342.81364 -107.186984)
		(end 340.389464 -104.762808)
		(width 0.089408)
		(layer "In2.Cu")
		(net "SVID_ALERT0_CPU0_R_N")
	)
	(segment
		(start 182.906416 -81.962752)
		(end 182.906416 -81.961736)
		(width 0.089408)
		(layer "In2.Cu")
		(net "SVID_ALERT0_CPU0_R_N")
	)
	(segment
		(start 334.049878 -105.422192)
		(end 334.039972 -105.432098)
		(width 0.089408)
		(layer "In2.Cu")
		(net "SVID_ALERT0_CPU0_R_N")
	)
	(segment
		(start 197.438264 -103.23195)
		(end 195.740782 -104.929432)
		(width 0.089408)
		(layer "In2.Cu")
		(net "SVID_ALERT0_CPU0_R_N")
	)
	(segment
		(start 178.23688 -78.649576)
		(end 178.4096 -78.476856)
		(width 0.089408)
		(layer "In2.Cu")
		(net "SVID_ALERT0_CPU0_R_N")
	)
	(segment
		(start 177.6476 -72.716644)
		(end 177.6476 -69.3039)
		(width 0.089408)
		(layer "In2.Cu")
		(net "SVID_ALERT0_CPU0_R_N")
	)
	(segment
		(start 195.141342 -107.090718)
		(end 187.204096 -107.090718)
		(width 0.089408)
		(layer "In2.Cu")
		(net "SVID_ALERT0_CPU0_R_N")
	)
	(segment
		(start 334.039972 -105.432098)
		(end 334.039972 -106.579924)
		(width 0.089408)
		(layer "In2.Cu")
		(net "SVID_ALERT0_CPU0_R_N")
	)
	(segment
		(start 184.360312 -63.494666)
		(end 184.487312 -63.494666)
		(width 0.089408)
		(layer "In2.Cu")
		(net "SVID_ALERT0_CPU0_R_N")
	)
	(segment
		(start 334.960722 -104.50957)
		(end 334.049878 -105.420414)
		(width 0.089408)
		(layer "In2.Cu")
		(net "SVID_ALERT0_CPU0_R_N")
	)
	(segment
		(start 180.847492 -65.176908)
		(end 182.67807 -65.176908)
		(width 0.089408)
		(layer "In2.Cu")
		(net "SVID_ALERT0_CPU0_R_N")
	)
	(segment
		(start 182.268368 -81.324704)
		(end 181.943248 -80.999584)
		(width 0.089408)
		(layer "In2.Cu")
		(net "SVID_ALERT0_CPU0_R_N")
	)
	(segment
		(start 353.0854 -115.742212)
		(end 354.94722 -113.880392)
		(width 0.089408)
		(layer "In2.Cu")
		(net "SVID_ALERT0_CPU0_R_N")
	)
	(segment
		(start 195.740782 -104.929432)
		(end 195.740782 -106.491278)
		(width 0.089408)
		(layer "In2.Cu")
		(net "SVID_ALERT0_CPU0_R_N")
	)
	(segment
		(start 177.6476 -69.3039)
		(end 179.629308 -67.322192)
		(width 0.089408)
		(layer "In2.Cu")
		(net "SVID_ALERT0_CPU0_R_N")
	)
	(segment
		(start 182.67807 -65.176908)
		(end 184.360312 -63.494666)
		(width 0.089408)
		(layer "In2.Cu")
		(net "SVID_ALERT0_CPU0_R_N")
	)
	(segment
		(start 340.389464 -104.762808)
		(end 340.389464 -104.762554)
		(width 0.089408)
		(layer "In2.Cu")
		(net "SVID_ALERT0_CPU0_R_N")
	)
	(segment
		(start 182.906416 -81.961736)
		(end 182.269384 -81.324704)
		(width 0.089408)
		(layer "In2.Cu")
		(net "SVID_ALERT0_CPU0_R_N")
	)
	(segment
		(start 340.13648 -104.50957)
		(end 334.960722 -104.50957)
		(width 0.089408)
		(layer "In2.Cu")
		(net "SVID_ALERT0_CPU0_R_N")
	)
	(segment
		(start 334.049878 -106.613198)
		(end 334.47228 -107.0356)
		(width 0.089408)
		(layer "In2.Cu")
		(net "SVID_ALERT0_CPU0_R_N")
	)
	(segment
		(start 334.049878 -105.420414)
		(end 334.049878 -105.422192)
		(width 0.089408)
		(layer "In2.Cu")
		(net "SVID_ALERT0_CPU0_R_N")
	)
	(segment
		(start 180.062378 -81.324704)
		(end 179.114958 -81.324704)
		(width 0.089408)
		(layer "In2.Cu")
		(net "SVID_ALERT0_CPU0_R_N")
	)
	(segment
		(start 334.039972 -106.579924)
		(end 334.049878 -106.58983)
		(width 0.089408)
		(layer "In2.Cu")
		(net "SVID_ALERT0_CPU0_R_N")
	)
	(segment
		(start 179.114958 -81.324704)
		(end 178.23688 -80.446626)
		(width 0.089408)
		(layer "In2.Cu")
		(net "SVID_ALERT0_CPU0_R_N")
	)
	(segment
		(start 178.4096 -73.478644)
		(end 177.6476 -72.716644)
		(width 0.089408)
		(layer "In2.Cu")
		(net "SVID_ALERT0_CPU0_R_N")
	)
	(segment
		(start 182.269384 -81.324704)
		(end 182.268368 -81.324704)
		(width 0.089408)
		(layer "In2.Cu")
		(net "SVID_ALERT0_CPU0_R_N")
	)
	(segment
		(start 178.4096 -78.476856)
		(end 178.4096 -73.478644)
		(width 0.089408)
		(layer "In2.Cu")
		(net "SVID_ALERT0_CPU0_R_N")
	)
	(segment
		(start 354.94722 -113.880392)
		(end 354.94722 -108.41736)
		(width 0.089408)
		(layer "In2.Cu")
		(net "SVID_ALERT0_CPU0_R_N")
	)
	(segment
		(start 183.061356 -82.117692)
		(end 182.906416 -81.962752)
		(width 0.089408)
		(layer "In2.Cu")
		(net "SVID_ALERT0_CPU0_R_N")
	)
	(segment
		(start 177.807112 -75.757024)
		(end 176.98212 -74.932032)
		(width 0.089408)
		(layer "In4.Cu")
		(net "SVID_ALERT0_CPU0_R_N")
	)
	(segment
		(start 179.805584 -64.634364)
		(end 181.905148 -62.5348)
		(width 0.089408)
		(layer "In4.Cu")
		(net "SVID_ALERT0_CPU0_R_N")
	)
	(segment
		(start 262.083042 -149.173438)
		(end 262.083042 -151.042116)
		(width 0.089408)
		(layer "In4.Cu")
		(net "SVID_ALERT0_CPU0_R_N")
	)
	(segment
		(start 317.30442 -102.117906)
		(end 316.360302 -103.062024)
		(width 0.089408)
		(layer "In4.Cu")
		(net "SVID_ALERT0_CPU0_R_N")
	)
	(segment
		(start 323.65696 -124.66066)
		(end 323.65696 -125.445774)
		(width 0.089408)
		(layer "In4.Cu")
		(net "SVID_ALERT0_CPU0_R_N")
	)
	(segment
		(start 228.243638 -148.580348)
		(end 227.979478 -148.316188)
		(width 0.089408)
		(layer "In4.Cu")
		(net "SVID_ALERT0_CPU0_R_N")
	)
	(segment
		(start 321.7672 -130.127756)
		(end 321.7672 -139.339574)
		(width 0.089408)
		(layer "In4.Cu")
		(net "SVID_ALERT0_CPU0_R_N")
	)
	(segment
		(start 324.144894 -125.933708)
		(end 324.144894 -127.750062)
		(width 0.089408)
		(layer "In4.Cu")
		(net "SVID_ALERT0_CPU0_R_N")
	)
	(segment
		(start 318.2747 -147.955)
		(end 304.52822 -147.955)
		(width 0.089408)
		(layer "In4.Cu")
		(net "SVID_ALERT0_CPU0_R_N")
	)
	(segment
		(start 284.297374 -148.095462)
		(end 263.161018 -148.095462)
		(width 0.089408)
		(layer "In4.Cu")
		(net "SVID_ALERT0_CPU0_R_N")
	)
	(segment
		(start 182.88 -82.490818)
		(end 180.062124 -79.672942)
		(width 0.089408)
		(layer "In4.Cu")
		(net "SVID_ALERT0_CPU0_R_N")
	)
	(segment
		(start 176.98212 -69.26707)
		(end 179.195984 -67.053206)
		(width 0.089408)
		(layer "In4.Cu")
		(net "SVID_ALERT0_CPU0_R_N")
	)
	(segment
		(start 323.699124 -124.618496)
		(end 323.65696 -124.66066)
		(width 0.089408)
		(layer "In4.Cu")
		(net "SVID_ALERT0_CPU0_R_N")
	)
	(segment
		(start 320.0908 -141.015974)
		(end 320.0908 -146.1389)
		(width 0.089408)
		(layer "In4.Cu")
		(net "SVID_ALERT0_CPU0_R_N")
	)
	(segment
		(start 180.062124 -79.672942)
		(end 180.062124 -78.591156)
		(width 0.089408)
		(layer "In4.Cu")
		(net "SVID_ALERT0_CPU0_R_N")
	)
	(segment
		(start 192.5193 -117.009164)
		(end 183.572658 -108.062522)
		(width 0.089408)
		(layer "In4.Cu")
		(net "SVID_ALERT0_CPU0_R_N")
	)
	(segment
		(start 179.195984 -65.25006)
		(end 179.805584 -64.64046)
		(width 0.089408)
		(layer "In4.Cu")
		(net "SVID_ALERT0_CPU0_R_N")
	)
	(segment
		(start 317.30442 -102.113588)
		(end 317.30442 -102.117906)
		(width 0.089408)
		(layer "In4.Cu")
		(net "SVID_ALERT0_CPU0_R_N")
	)
	(segment
		(start 303.7078 -150.771606)
		(end 302.315626 -152.16378)
		(width 0.089408)
		(layer "In4.Cu")
		(net "SVID_ALERT0_CPU0_R_N")
	)
	(segment
		(start 322.7578 -118.001796)
		(end 322.7578 -118.6307)
		(width 0.089408)
		(layer "In4.Cu")
		(net "SVID_ALERT0_CPU0_R_N")
	)
	(segment
		(start 316.360302 -111.604298)
		(end 322.7578 -118.001796)
		(width 0.089408)
		(layer "In4.Cu")
		(net "SVID_ALERT0_CPU0_R_N")
	)
	(segment
		(start 179.195984 -67.053206)
		(end 179.195984 -65.25006)
		(width 0.089408)
		(layer "In4.Cu")
		(net "SVID_ALERT0_CPU0_R_N")
	)
	(segment
		(start 227.979478 -148.316188)
		(end 227.978462 -148.316188)
		(width 0.089408)
		(layer "In4.Cu")
		(net "SVID_ALERT0_CPU0_R_N")
	)
	(segment
		(start 303.7078 -148.77542)
		(end 303.7078 -150.771606)
		(width 0.089408)
		(layer "In4.Cu")
		(net "SVID_ALERT0_CPU0_R_N")
	)
	(segment
		(start 192.5193 -146.542506)
		(end 192.5193 -117.009164)
		(width 0.089408)
		(layer "In4.Cu")
		(net "SVID_ALERT0_CPU0_R_N")
	)
	(segment
		(start 181.905148 -62.5348)
		(end 183.740806 -62.5348)
		(width 0.089408)
		(layer "In4.Cu")
		(net "SVID_ALERT0_CPU0_R_N")
	)
	(segment
		(start 323.699124 -119.572024)
		(end 323.699124 -124.618496)
		(width 0.089408)
		(layer "In4.Cu")
		(net "SVID_ALERT0_CPU0_R_N")
	)
	(segment
		(start 194.216274 -148.23948)
		(end 192.5193 -146.542506)
		(width 0.089408)
		(layer "In4.Cu")
		(net "SVID_ALERT0_CPU0_R_N")
	)
	(segment
		(start 227.901754 -148.23948)
		(end 194.216274 -148.23948)
		(width 0.089408)
		(layer "In4.Cu")
		(net "SVID_ALERT0_CPU0_R_N")
	)
	(segment
		(start 228.243638 -148.581364)
		(end 228.243638 -148.580348)
		(width 0.089408)
		(layer "In4.Cu")
		(net "SVID_ALERT0_CPU0_R_N")
	)
	(segment
		(start 261.006082 -152.119076)
		(end 229.096062 -152.119076)
		(width 0.089408)
		(layer "In4.Cu")
		(net "SVID_ALERT0_CPU0_R_N")
	)
	(segment
		(start 322.7578 -118.6307)
		(end 323.699124 -119.572024)
		(width 0.089408)
		(layer "In4.Cu")
		(net "SVID_ALERT0_CPU0_R_N")
	)
	(segment
		(start 183.572658 -104.773222)
		(end 182.88 -104.080564)
		(width 0.089408)
		(layer "In4.Cu")
		(net "SVID_ALERT0_CPU0_R_N")
	)
	(segment
		(start 178.900582 -78.283054)
		(end 177.807112 -77.189584)
		(width 0.089408)
		(layer "In4.Cu")
		(net "SVID_ALERT0_CPU0_R_N")
	)
	(segment
		(start 324.144894 -127.750062)
		(end 321.7672 -130.127756)
		(width 0.089408)
		(layer "In4.Cu")
		(net "SVID_ALERT0_CPU0_R_N")
	)
	(segment
		(start 323.65696 -125.445774)
		(end 324.144894 -125.933708)
		(width 0.089408)
		(layer "In4.Cu")
		(net "SVID_ALERT0_CPU0_R_N")
	)
	(segment
		(start 321.7672 -139.339574)
		(end 320.0908 -141.015974)
		(width 0.089408)
		(layer "In4.Cu")
		(net "SVID_ALERT0_CPU0_R_N")
	)
	(segment
		(start 263.161018 -148.095462)
		(end 262.083042 -149.173438)
		(width 0.089408)
		(layer "In4.Cu")
		(net "SVID_ALERT0_CPU0_R_N")
	)
	(segment
		(start 227.978462 -148.316188)
		(end 227.901754 -148.23948)
		(width 0.089408)
		(layer "In4.Cu")
		(net "SVID_ALERT0_CPU0_R_N")
	)
	(segment
		(start 286.048704 -150.69058)
		(end 286.048704 -149.846792)
		(width 0.089408)
		(layer "In4.Cu")
		(net "SVID_ALERT0_CPU0_R_N")
	)
	(segment
		(start 182.88 -104.080564)
		(end 182.88 -82.490818)
		(width 0.089408)
		(layer "In4.Cu")
		(net "SVID_ALERT0_CPU0_R_N")
	)
	(segment
		(start 229.096062 -152.119076)
		(end 228.32822 -151.351234)
		(width 0.089408)
		(layer "In4.Cu")
		(net "SVID_ALERT0_CPU0_R_N")
	)
	(segment
		(start 183.740806 -62.5348)
		(end 184.487312 -63.281306)
		(width 0.089408)
		(layer "In4.Cu")
		(net "SVID_ALERT0_CPU0_R_N")
	)
	(segment
		(start 177.807112 -77.189584)
		(end 177.807112 -75.757024)
		(width 0.089408)
		(layer "In4.Cu")
		(net "SVID_ALERT0_CPU0_R_N")
	)
	(segment
		(start 287.521904 -152.16378)
		(end 286.048704 -150.69058)
		(width 0.089408)
		(layer "In4.Cu")
		(net "SVID_ALERT0_CPU0_R_N")
	)
	(segment
		(start 304.52822 -147.955)
		(end 303.7078 -148.77542)
		(width 0.089408)
		(layer "In4.Cu")
		(net "SVID_ALERT0_CPU0_R_N")
	)
	(segment
		(start 176.98212 -74.932032)
		(end 176.98212 -69.26707)
		(width 0.089408)
		(layer "In4.Cu")
		(net "SVID_ALERT0_CPU0_R_N")
	)
	(segment
		(start 228.32822 -151.351234)
		(end 228.32822 -148.665946)
		(width 0.089408)
		(layer "In4.Cu")
		(net "SVID_ALERT0_CPU0_R_N")
	)
	(segment
		(start 180.062124 -78.591156)
		(end 179.754022 -78.283054)
		(width 0.089408)
		(layer "In4.Cu")
		(net "SVID_ALERT0_CPU0_R_N")
	)
	(segment
		(start 179.805584 -64.64046)
		(end 179.805584 -64.634364)
		(width 0.089408)
		(layer "In4.Cu")
		(net "SVID_ALERT0_CPU0_R_N")
	)
	(segment
		(start 183.572658 -108.062522)
		(end 183.572658 -104.773222)
		(width 0.089408)
		(layer "In4.Cu")
		(net "SVID_ALERT0_CPU0_R_N")
	)
	(segment
		(start 184.487312 -63.281306)
		(end 184.487312 -63.494666)
		(width 0.089408)
		(layer "In4.Cu")
		(net "SVID_ALERT0_CPU0_R_N")
	)
	(segment
		(start 286.048704 -149.846792)
		(end 284.297374 -148.095462)
		(width 0.089408)
		(layer "In4.Cu")
		(net "SVID_ALERT0_CPU0_R_N")
	)
	(segment
		(start 320.0908 -146.1389)
		(end 318.2747 -147.955)
		(width 0.089408)
		(layer "In4.Cu")
		(net "SVID_ALERT0_CPU0_R_N")
	)
	(segment
		(start 179.754022 -78.283054)
		(end 178.900582 -78.283054)
		(width 0.089408)
		(layer "In4.Cu")
		(net "SVID_ALERT0_CPU0_R_N")
	)
	(segment
		(start 302.315626 -152.16378)
		(end 287.521904 -152.16378)
		(width 0.089408)
		(layer "In4.Cu")
		(net "SVID_ALERT0_CPU0_R_N")
	)
	(segment
		(start 316.360302 -103.062024)
		(end 316.360302 -111.604298)
		(width 0.089408)
		(layer "In4.Cu")
		(net "SVID_ALERT0_CPU0_R_N")
	)
	(segment
		(start 262.083042 -151.042116)
		(end 261.006082 -152.119076)
		(width 0.089408)
		(layer "In4.Cu")
		(net "SVID_ALERT0_CPU0_R_N")
	)
	(segment
		(start 228.32822 -148.665946)
		(end 228.243638 -148.581364)
		(width 0.089408)
		(layer "In4.Cu")
		(net "SVID_ALERT0_CPU0_R_N")
	)
	(segment
		(start 340.877398 -104.08539)
		(end 340.877398 -100.402136)
		(width 0.089408)
		(layer "In9.Cu")
		(net "SVID_ALERT0_CPU0_R_N")
	)
	(segment
		(start 342.172544 -91.122246)
		(end 340.359746 -89.309448)
		(width 0.089408)
		(layer "In9.Cu")
		(net "SVID_ALERT0_CPU0_R_N")
	)
	(segment
		(start 344.409522 -112.879124)
		(end 344.66784 -112.620806)
		(width 0.089408)
		(layer "In9.Cu")
		(net "SVID_ALERT0_CPU0_R_N")
	)
	(segment
		(start 344.156284 -116.46916)
		(end 344.156284 -113.132108)
		(width 0.089408)
		(layer "In9.Cu")
		(net "SVID_ALERT0_CPU0_R_N")
	)
	(segment
		(start 340.359746 -89.309448)
		(end 339.69579 -89.309448)
		(width 0.089408)
		(layer "In9.Cu")
		(net "SVID_ALERT0_CPU0_R_N")
	)
	(segment
		(start 342.172544 -99.10699)
		(end 342.172544 -91.122246)
		(width 0.089408)
		(layer "In9.Cu")
		(net "SVID_ALERT0_CPU0_R_N")
	)
	(segment
		(start 344.409268 -112.879124)
		(end 344.409522 -112.879124)
		(width 0.089408)
		(layer "In9.Cu")
		(net "SVID_ALERT0_CPU0_R_N")
	)
	(segment
		(start 339.69579 -89.309448)
		(end 339.569044 -89.182702)
		(width 0.089408)
		(layer "In9.Cu")
		(net "SVID_ALERT0_CPU0_R_N")
	)
	(segment
		(start 340.877398 -100.402136)
		(end 342.172544 -99.10699)
		(width 0.089408)
		(layer "In9.Cu")
		(net "SVID_ALERT0_CPU0_R_N")
	)
	(segment
		(start 346.71381 -117.19687)
		(end 344.883994 -117.19687)
		(width 0.089408)
		(layer "In9.Cu")
		(net "SVID_ALERT0_CPU0_R_N")
	)
	(segment
		(start 344.66784 -112.620806)
		(end 344.66784 -107.875832)
		(width 0.089408)
		(layer "In9.Cu")
		(net "SVID_ALERT0_CPU0_R_N")
	)
	(segment
		(start 344.66784 -107.875832)
		(end 340.877398 -104.08539)
		(width 0.089408)
		(layer "In9.Cu")
		(net "SVID_ALERT0_CPU0_R_N")
	)
	(segment
		(start 344.883994 -117.19687)
		(end 344.156284 -116.46916)
		(width 0.089408)
		(layer "In9.Cu")
		(net "SVID_ALERT0_CPU0_R_N")
	)
	(segment
		(start 353.0854 -116.205)
		(end 351.57283 -117.71757)
		(width 0.089408)
		(layer "In9.Cu")
		(net "SVID_ALERT0_CPU0_R_N")
	)
	(segment
		(start 344.156284 -113.132108)
		(end 344.409268 -112.879124)
		(width 0.089408)
		(layer "In9.Cu")
		(net "SVID_ALERT0_CPU0_R_N")
	)
	(segment
		(start 347.23451 -117.71757)
		(end 346.71381 -117.19687)
		(width 0.089408)
		(layer "In9.Cu")
		(net "SVID_ALERT0_CPU0_R_N")
	)
	(segment
		(start 351.57283 -117.71757)
		(end 347.23451 -117.71757)
		(width 0.089408)
		(layer "In9.Cu")
		(net "SVID_ALERT0_CPU0_R_N")
	)
	(segment
		(start 329.718416 -106.833416)
		(end 334.270096 -106.833416)
		(width 0.089408)
		(layer "In11.Cu")
		(net "SVID_ALERT0_CPU0_R_N")
	)
	(segment
		(start 317.30442 -102.113588)
		(end 317.375032 -102.1842)
		(width 0.089408)
		(layer "In11.Cu")
		(net "SVID_ALERT0_CPU0_R_N")
	)
	(segment
		(start 321.437 -102.1842)
		(end 323.3801 -104.1273)
		(width 0.089408)
		(layer "In11.Cu")
		(net "SVID_ALERT0_CPU0_R_N")
	)
	(segment
		(start 327.0123 -104.1273)
		(end 329.718416 -106.833416)
		(width 0.089408)
		(layer "In11.Cu")
		(net "SVID_ALERT0_CPU0_R_N")
	)
	(segment
		(start 334.270096 -106.833416)
		(end 334.47228 -107.0356)
		(width 0.089408)
		(layer "In11.Cu")
		(net "SVID_ALERT0_CPU0_R_N")
	)
	(segment
		(start 317.375032 -102.1842)
		(end 321.437 -102.1842)
		(width 0.089408)
		(layer "In11.Cu")
		(net "SVID_ALERT0_CPU0_R_N")
	)
	(segment
		(start 323.3801 -104.1273)
		(end 327.0123 -104.1273)
		(width 0.089408)
		(layer "In11.Cu")
		(net "SVID_ALERT0_CPU0_R_N")
	)
	(segment
		(start 269.480792 -91.25204)
		(end 269.503906 -91.275154)
		(width 0.10795)
		(layer "F.Cu")
		(net "SVID_ALERT0_CPU0_N")
	)
	(segment
		(start 268.806676 -91.25204)
		(end 269.480792 -91.25204)
		(width 0.10795)
		(layer "F.Cu")
		(net "SVID_ALERT0_CPU0_N")
	)
	(via
		(at 269.503906 -91.275154)
		(size 0.508)
		(drill 0.254)
		(layers "F.Cu" "B.Cu")
		(net "SVID_ALERT0_CPU0_N")
	)
	(via
		(at 229.249986 -89.535)
		(size 0.6604)
		(drill 0.3302)
		(layers "F.Cu" "B.Cu")
		(net "SVID_ALERT0_CPU0_N")
	)
	(segment
		(start 250.7488 -86.7156)
		(end 251.2822 -86.7156)
		(width 0.10795)
		(layer "B.Cu")
		(net "SVID_ALERT0_CPU0_N")
	)
	(segment
		(start 237.182406 -86.801706)
		(end 237.468918 -86.801706)
		(width 0.10795)
		(layer "B.Cu")
		(net "SVID_ALERT0_CPU0_N")
	)
	(segment
		(start 235.40466 -86.817962)
		(end 235.7755 -86.817962)
		(width 0.10795)
		(layer "B.Cu")
		(net "SVID_ALERT0_CPU0_N")
	)
	(segment
		(start 237.468918 -86.801706)
		(end 237.870746 -87.203534)
		(width 0.10795)
		(layer "B.Cu")
		(net "SVID_ALERT0_CPU0_N")
	)
	(segment
		(start 263.755886 -90.24874)
		(end 264.208006 -90.24874)
		(width 0.10795)
		(layer "B.Cu")
		(net "SVID_ALERT0_CPU0_N")
	)
	(segment
		(start 232.81132 -87.279734)
		(end 233.290872 -87.279734)
		(width 0.10795)
		(layer "B.Cu")
		(net "SVID_ALERT0_CPU0_N")
	)
	(segment
		(start 253.825756 -87.282274)
		(end 254.291338 -87.747856)
		(width 0.10795)
		(layer "B.Cu")
		(net "SVID_ALERT0_CPU0_N")
	)
	(segment
		(start 260.639306 -90.323416)
		(end 261.18693 -89.775792)
		(width 0.10795)
		(layer "B.Cu")
		(net "SVID_ALERT0_CPU0_N")
	)
	(segment
		(start 240.93297 -86.880192)
		(end 241.392456 -87.339678)
		(width 0.10795)
		(layer "B.Cu")
		(net "SVID_ALERT0_CPU0_N")
	)
	(segment
		(start 232.257854 -87.8332)
		(end 232.81132 -87.279734)
		(width 0.10795)
		(layer "B.Cu")
		(net "SVID_ALERT0_CPU0_N")
	)
	(segment
		(start 239.683544 -87.297006)
		(end 240.139728 -87.297006)
		(width 0.10795)
		(layer "B.Cu")
		(net "SVID_ALERT0_CPU0_N")
	)
	(segment
		(start 205.74 -106.299)
		(end 206.248 -106.299)
		(width 0.10795)
		(layer "B.Cu")
		(net "SVID_ALERT0_CPU0_N")
	)
	(segment
		(start 207.368902 -105.178098)
		(end 214.56015 -105.178098)
		(width 0.10795)
		(layer "B.Cu")
		(net "SVID_ALERT0_CPU0_N")
	)
	(segment
		(start 265.918696 -91.179904)
		(end 266.2936 -90.805)
		(width 0.10795)
		(layer "B.Cu")
		(net "SVID_ALERT0_CPU0_N")
	)
	(segment
		(start 248.2342 -86.3854)
		(end 248.7168 -86.3854)
		(width 0.10795)
		(layer "B.Cu")
		(net "SVID_ALERT0_CPU0_N")
	)
	(segment
		(start 238.414052 -87.203534)
		(end 238.788956 -86.82863)
		(width 0.10795)
		(layer "B.Cu")
		(net "SVID_ALERT0_CPU0_N")
	)
	(segment
		(start 240.139728 -87.297006)
		(end 240.556542 -86.880192)
		(width 0.10795)
		(layer "B.Cu")
		(net "SVID_ALERT0_CPU0_N")
	)
	(segment
		(start 249.047 -86.7156)
		(end 249.6312 -86.7156)
		(width 0.10795)
		(layer "B.Cu")
		(net "SVID_ALERT0_CPU0_N")
	)
	(segment
		(start 226.941634 -92.796614)
		(end 226.941634 -90.177366)
		(width 0.10795)
		(layer "B.Cu")
		(net "SVID_ALERT0_CPU0_N")
	)
	(segment
		(start 253.446534 -87.282274)
		(end 253.825756 -87.282274)
		(width 0.10795)
		(layer "B.Cu")
		(net "SVID_ALERT0_CPU0_N")
	)
	(segment
		(start 236.681264 -87.302848)
		(end 237.182406 -86.801706)
		(width 0.10795)
		(layer "B.Cu")
		(net "SVID_ALERT0_CPU0_N")
	)
	(segment
		(start 251.2822 -86.7156)
		(end 251.6124 -86.3854)
		(width 0.10795)
		(layer "B.Cu")
		(net "SVID_ALERT0_CPU0_N")
	)
	(segment
		(start 229.249986 -89.535)
		(end 230.225346 -89.535)
		(width 0.10795)
		(layer "B.Cu")
		(net "SVID_ALERT0_CPU0_N")
	)
	(segment
		(start 255.29794 -89.33434)
		(end 255.63322 -89.33434)
		(width 0.10795)
		(layer "B.Cu")
		(net "SVID_ALERT0_CPU0_N")
	)
	(segment
		(start 252.1458 -86.3854)
		(end 252.5268 -86.7664)
		(width 0.10795)
		(layer "B.Cu")
		(net "SVID_ALERT0_CPU0_N")
	)
	(segment
		(start 262.987282 -89.853262)
		(end 263.360408 -89.853262)
		(width 0.10795)
		(layer "B.Cu")
		(net "SVID_ALERT0_CPU0_N")
	)
	(segment
		(start 234.502706 -87.315548)
		(end 234.907074 -87.315548)
		(width 0.10795)
		(layer "B.Cu")
		(net "SVID_ALERT0_CPU0_N")
	)
	(segment
		(start 246.998236 -86.368636)
		(end 247.3452 -86.7156)
		(width 0.10795)
		(layer "B.Cu")
		(net "SVID_ALERT0_CPU0_N")
	)
	(segment
		(start 243.135404 -86.277196)
		(end 243.5225 -86.277196)
		(width 0.10795)
		(layer "B.Cu")
		(net "SVID_ALERT0_CPU0_N")
	)
	(segment
		(start 206.248 -106.299)
		(end 207.368902 -105.178098)
		(width 0.10795)
		(layer "B.Cu")
		(net "SVID_ALERT0_CPU0_N")
	)
	(segment
		(start 254.291338 -87.747856)
		(end 254.72136 -87.747856)
		(width 0.10795)
		(layer "B.Cu")
		(net "SVID_ALERT0_CPU0_N")
	)
	(segment
		(start 256.453894 -89.776554)
		(end 256.92354 -90.2462)
		(width 0.10795)
		(layer "B.Cu")
		(net "SVID_ALERT0_CPU0_N")
	)
	(segment
		(start 261.18693 -89.775792)
		(end 261.585202 -89.775792)
		(width 0.10795)
		(layer "B.Cu")
		(net "SVID_ALERT0_CPU0_N")
	)
	(segment
		(start 254.89662 -88.93302)
		(end 255.29794 -89.33434)
		(width 0.10795)
		(layer "B.Cu")
		(net "SVID_ALERT0_CPU0_N")
	)
	(segment
		(start 229.001066 -89.78392)
		(end 229.249986 -89.535)
		(width 0.10795)
		(layer "B.Cu")
		(net "SVID_ALERT0_CPU0_N")
	)
	(segment
		(start 214.56015 -105.178098)
		(end 226.941634 -92.796614)
		(width 0.10795)
		(layer "B.Cu")
		(net "SVID_ALERT0_CPU0_N")
	)
	(segment
		(start 254.72136 -87.747856)
		(end 255.065022 -88.091518)
		(width 0.10795)
		(layer "B.Cu")
		(net "SVID_ALERT0_CPU0_N")
	)
	(segment
		(start 249.6312 -86.7156)
		(end 249.9614 -86.3854)
		(width 0.10795)
		(layer "B.Cu")
		(net "SVID_ALERT0_CPU0_N")
	)
	(segment
		(start 239.215168 -86.82863)
		(end 239.683544 -87.297006)
		(width 0.10795)
		(layer "B.Cu")
		(net "SVID_ALERT0_CPU0_N")
	)
	(segment
		(start 237.870746 -87.203534)
		(end 238.414052 -87.203534)
		(width 0.10795)
		(layer "B.Cu")
		(net "SVID_ALERT0_CPU0_N")
	)
	(segment
		(start 255.63322 -89.33434)
		(end 256.05994 -89.76106)
		(width 0.10795)
		(layer "B.Cu")
		(net "SVID_ALERT0_CPU0_N")
	)
	(segment
		(start 254.89662 -88.62314)
		(end 254.89662 -88.93302)
		(width 0.10795)
		(layer "B.Cu")
		(net "SVID_ALERT0_CPU0_N")
	)
	(segment
		(start 259.84835 -90.707972)
		(end 260.232906 -90.323416)
		(width 0.10795)
		(layer "B.Cu")
		(net "SVID_ALERT0_CPU0_N")
	)
	(segment
		(start 256.05994 -89.76106)
		(end 256.453894 -89.76106)
		(width 0.10795)
		(layer "B.Cu")
		(net "SVID_ALERT0_CPU0_N")
	)
	(segment
		(start 264.208006 -90.24874)
		(end 264.738104 -90.778838)
		(width 0.10795)
		(layer "B.Cu")
		(net "SVID_ALERT0_CPU0_N")
	)
	(segment
		(start 247.904 -86.7156)
		(end 248.2342 -86.3854)
		(width 0.10795)
		(layer "B.Cu")
		(net "SVID_ALERT0_CPU0_N")
	)
	(segment
		(start 262.03783 -89.323164)
		(end 262.457184 -89.323164)
		(width 0.10795)
		(layer "B.Cu")
		(net "SVID_ALERT0_CPU0_N")
	)
	(segment
		(start 242.385088 -86.7918)
		(end 242.6208 -86.7918)
		(width 0.10795)
		(layer "B.Cu")
		(net "SVID_ALERT0_CPU0_N")
	)
	(segment
		(start 255.065022 -88.454738)
		(end 254.89662 -88.62314)
		(width 0.10795)
		(layer "B.Cu")
		(net "SVID_ALERT0_CPU0_N")
	)
	(segment
		(start 264.738104 -90.778838)
		(end 265.048238 -90.778838)
		(width 0.10795)
		(layer "B.Cu")
		(net "SVID_ALERT0_CPU0_N")
	)
	(segment
		(start 265.449304 -91.179904)
		(end 265.918696 -91.179904)
		(width 0.10795)
		(layer "B.Cu")
		(net "SVID_ALERT0_CPU0_N")
	)
	(segment
		(start 226.941634 -90.177366)
		(end 227.33508 -89.78392)
		(width 0.10795)
		(layer "B.Cu")
		(net "SVID_ALERT0_CPU0_N")
	)
	(segment
		(start 241.392456 -87.339678)
		(end 241.83721 -87.339678)
		(width 0.10795)
		(layer "B.Cu")
		(net "SVID_ALERT0_CPU0_N")
	)
	(segment
		(start 238.788956 -86.82863)
		(end 239.215168 -86.82863)
		(width 0.10795)
		(layer "B.Cu")
		(net "SVID_ALERT0_CPU0_N")
	)
	(segment
		(start 269.436342 -91.20759)
		(end 269.503906 -91.275154)
		(width 0.10795)
		(layer "B.Cu")
		(net "SVID_ALERT0_CPU0_N")
	)
	(segment
		(start 235.7755 -86.817962)
		(end 236.260386 -87.302848)
		(width 0.10795)
		(layer "B.Cu")
		(net "SVID_ALERT0_CPU0_N")
	)
	(segment
		(start 257.181096 -90.2462)
		(end 257.711702 -89.715594)
		(width 0.10795)
		(layer "B.Cu")
		(net "SVID_ALERT0_CPU0_N")
	)
	(segment
		(start 233.290872 -87.279734)
		(end 233.768138 -87.757)
		(width 0.10795)
		(layer "B.Cu")
		(net "SVID_ALERT0_CPU0_N")
	)
	(segment
		(start 252.93066 -86.7664)
		(end 253.446534 -87.282274)
		(width 0.10795)
		(layer "B.Cu")
		(net "SVID_ALERT0_CPU0_N")
	)
	(segment
		(start 230.225346 -89.535)
		(end 231.927146 -87.8332)
		(width 0.10795)
		(layer "B.Cu")
		(net "SVID_ALERT0_CPU0_N")
	)
	(segment
		(start 258.931918 -90.176858)
		(end 259.463032 -90.707972)
		(width 0.10795)
		(layer "B.Cu")
		(net "SVID_ALERT0_CPU0_N")
	)
	(segment
		(start 262.457184 -89.323164)
		(end 262.987282 -89.853262)
		(width 0.10795)
		(layer "B.Cu")
		(net "SVID_ALERT0_CPU0_N")
	)
	(segment
		(start 233.768138 -87.757)
		(end 234.061254 -87.757)
		(width 0.10795)
		(layer "B.Cu")
		(net "SVID_ALERT0_CPU0_N")
	)
	(segment
		(start 246.202708 -86.008464)
		(end 246.56288 -86.368636)
		(width 0.10795)
		(layer "B.Cu")
		(net "SVID_ALERT0_CPU0_N")
	)
	(segment
		(start 252.5268 -86.7664)
		(end 252.93066 -86.7664)
		(width 0.10795)
		(layer "B.Cu")
		(net "SVID_ALERT0_CPU0_N")
	)
	(segment
		(start 256.92354 -90.2462)
		(end 257.181096 -90.2462)
		(width 0.10795)
		(layer "B.Cu")
		(net "SVID_ALERT0_CPU0_N")
	)
	(segment
		(start 267.17879 -91.20759)
		(end 269.436342 -91.20759)
		(width 0.10795)
		(layer "B.Cu")
		(net "SVID_ALERT0_CPU0_N")
	)
	(segment
		(start 231.927146 -87.8332)
		(end 232.257854 -87.8332)
		(width 0.10795)
		(layer "B.Cu")
		(net "SVID_ALERT0_CPU0_N")
	)
	(segment
		(start 246.56288 -86.368636)
		(end 246.998236 -86.368636)
		(width 0.10795)
		(layer "B.Cu")
		(net "SVID_ALERT0_CPU0_N")
	)
	(segment
		(start 227.33508 -89.78392)
		(end 229.001066 -89.78392)
		(width 0.10795)
		(layer "B.Cu")
		(net "SVID_ALERT0_CPU0_N")
	)
	(segment
		(start 266.7762 -90.805)
		(end 267.17879 -91.20759)
		(width 0.10795)
		(layer "B.Cu")
		(net "SVID_ALERT0_CPU0_N")
	)
	(segment
		(start 249.9614 -86.3854)
		(end 250.4186 -86.3854)
		(width 0.10795)
		(layer "B.Cu")
		(net "SVID_ALERT0_CPU0_N")
	)
	(segment
		(start 265.048238 -90.778838)
		(end 265.449304 -91.179904)
		(width 0.10795)
		(layer "B.Cu")
		(net "SVID_ALERT0_CPU0_N")
	)
	(segment
		(start 266.2936 -90.805)
		(end 266.7762 -90.805)
		(width 0.10795)
		(layer "B.Cu")
		(net "SVID_ALERT0_CPU0_N")
	)
	(segment
		(start 234.907074 -87.315548)
		(end 235.40466 -86.817962)
		(width 0.10795)
		(layer "B.Cu")
		(net "SVID_ALERT0_CPU0_N")
	)
	(segment
		(start 243.791232 -86.008464)
		(end 246.202708 -86.008464)
		(width 0.10795)
		(layer "B.Cu")
		(net "SVID_ALERT0_CPU0_N")
	)
	(segment
		(start 261.585202 -89.775792)
		(end 262.03783 -89.323164)
		(width 0.10795)
		(layer "B.Cu")
		(net "SVID_ALERT0_CPU0_N")
	)
	(segment
		(start 243.5225 -86.277196)
		(end 243.791232 -86.008464)
		(width 0.10795)
		(layer "B.Cu")
		(net "SVID_ALERT0_CPU0_N")
	)
	(segment
		(start 248.7168 -86.3854)
		(end 249.047 -86.7156)
		(width 0.10795)
		(layer "B.Cu")
		(net "SVID_ALERT0_CPU0_N")
	)
	(segment
		(start 250.4186 -86.3854)
		(end 250.7488 -86.7156)
		(width 0.10795)
		(layer "B.Cu")
		(net "SVID_ALERT0_CPU0_N")
	)
	(segment
		(start 241.83721 -87.339678)
		(end 242.385088 -86.7918)
		(width 0.10795)
		(layer "B.Cu")
		(net "SVID_ALERT0_CPU0_N")
	)
	(segment
		(start 263.360408 -89.853262)
		(end 263.755886 -90.24874)
		(width 0.10795)
		(layer "B.Cu")
		(net "SVID_ALERT0_CPU0_N")
	)
	(segment
		(start 251.6124 -86.3854)
		(end 252.1458 -86.3854)
		(width 0.10795)
		(layer "B.Cu")
		(net "SVID_ALERT0_CPU0_N")
	)
	(segment
		(start 256.453894 -89.76106)
		(end 256.453894 -89.776554)
		(width 0.10795)
		(layer "B.Cu")
		(net "SVID_ALERT0_CPU0_N")
	)
	(segment
		(start 257.711702 -89.715594)
		(end 258.112768 -89.715594)
		(width 0.10795)
		(layer "B.Cu")
		(net "SVID_ALERT0_CPU0_N")
	)
	(segment
		(start 258.574032 -90.176858)
		(end 258.931918 -90.176858)
		(width 0.10795)
		(layer "B.Cu")
		(net "SVID_ALERT0_CPU0_N")
	)
	(segment
		(start 258.112768 -89.715594)
		(end 258.574032 -90.176858)
		(width 0.10795)
		(layer "B.Cu")
		(net "SVID_ALERT0_CPU0_N")
	)
	(segment
		(start 242.6208 -86.7918)
		(end 243.135404 -86.277196)
		(width 0.10795)
		(layer "B.Cu")
		(net "SVID_ALERT0_CPU0_N")
	)
	(segment
		(start 260.232906 -90.323416)
		(end 260.639306 -90.323416)
		(width 0.10795)
		(layer "B.Cu")
		(net "SVID_ALERT0_CPU0_N")
	)
	(segment
		(start 259.463032 -90.707972)
		(end 259.84835 -90.707972)
		(width 0.10795)
		(layer "B.Cu")
		(net "SVID_ALERT0_CPU0_N")
	)
	(segment
		(start 236.260386 -87.302848)
		(end 236.681264 -87.302848)
		(width 0.10795)
		(layer "B.Cu")
		(net "SVID_ALERT0_CPU0_N")
	)
	(segment
		(start 240.556542 -86.880192)
		(end 240.93297 -86.880192)
		(width 0.10795)
		(layer "B.Cu")
		(net "SVID_ALERT0_CPU0_N")
	)
	(segment
		(start 234.061254 -87.757)
		(end 234.502706 -87.315548)
		(width 0.10795)
		(layer "B.Cu")
		(net "SVID_ALERT0_CPU0_N")
	)
	(segment
		(start 247.3452 -86.7156)
		(end 247.904 -86.7156)
		(width 0.10795)
		(layer "B.Cu")
		(net "SVID_ALERT0_CPU0_N")
	)
	(segment
		(start 255.065022 -88.091518)
		(end 255.065022 -88.454738)
		(width 0.10795)
		(layer "B.Cu")
		(net "SVID_ALERT0_CPU0_N")
	)
	(segment
		(start 376.67438 -93.363796)
		(end 376.301 -92.990416)
		(width 0.0889)
		(layer "F.Cu")
		(net "SPI_PCH_MOSI_R")
	)
	(segment
		(start 376.301 -92.990416)
		(end 376.301 -92.837)
		(width 0.0889)
		(layer "F.Cu")
		(net "SPI_PCH_MOSI_R")
	)
	(segment
		(start 376.301 -90.174318)
		(end 375.158 -89.031318)
		(width 0.10795)
		(layer "F.Cu")
		(net "SPI_PCH_MOSI_R")
	)
	(segment
		(start 377.484894 -94.790006)
		(end 376.961146 -94.790006)
		(width 0.0889)
		(layer "F.Cu")
		(net "SPI_PCH_MOSI_R")
	)
	(segment
		(start 376.301 -92.837)
		(end 376.301 -90.174318)
		(width 0.10795)
		(layer "F.Cu")
		(net "SPI_PCH_MOSI_R")
	)
	(segment
		(start 376.961146 -94.790006)
		(end 376.628152 -94.457012)
		(width 0.0889)
		(layer "F.Cu")
		(net "SPI_PCH_MOSI_R")
	)
	(segment
		(start 376.628152 -94.035626)
		(end 376.67438 -93.989398)
		(width 0.0889)
		(layer "F.Cu")
		(net "SPI_PCH_MOSI_R")
	)
	(segment
		(start 375.158 -89.031318)
		(end 375.158 -88.2015)
		(width 0.10795)
		(layer "F.Cu")
		(net "SPI_PCH_MOSI_R")
	)
	(segment
		(start 376.67438 -93.989398)
		(end 376.67438 -93.363796)
		(width 0.0889)
		(layer "F.Cu")
		(net "SPI_PCH_MOSI_R")
	)
	(segment
		(start 376.628152 -94.457012)
		(end 376.628152 -94.035626)
		(width 0.0889)
		(layer "F.Cu")
		(net "SPI_PCH_MOSI_R")
	)
	(segment
		(start 395.647418 -73.101454)
		(end 395.40434 -72.858376)
		(width 0.10795)
		(layer "F.Cu")
		(net "SPI_PCH_MOSI")
	)
	(segment
		(start 406.9461 -64.135)
		(end 406.9461 -63.373)
		(width 0.10795)
		(layer "F.Cu")
		(net "SPI_PCH_MOSI")
	)
	(segment
		(start 375.158 -86.206584)
		(end 375.158 -87.3125)
		(width 0.10795)
		(layer "F.Cu")
		(net "SPI_PCH_MOSI")
	)
	(segment
		(start 407.350214 -69.301868)
		(end 407.350214 -68.574412)
		(width 0.10795)
		(layer "F.Cu")
		(net "SPI_PCH_MOSI")
	)
	(segment
		(start 376.776996 -85.156802)
		(end 376.207782 -85.156802)
		(width 0.10795)
		(layer "F.Cu")
		(net "SPI_PCH_MOSI")
	)
	(segment
		(start 377.275598 -84.6582)
		(end 376.776996 -85.156802)
		(width 0.10795)
		(layer "F.Cu")
		(net "SPI_PCH_MOSI")
	)
	(segment
		(start 393.9032 -74.775568)
		(end 394.087858 -74.59091)
		(width 0.10795)
		(layer "F.Cu")
		(net "SPI_PCH_MOSI")
	)
	(segment
		(start 395.91742 -71.89978)
		(end 404.752302 -71.89978)
		(width 0.10795)
		(layer "F.Cu")
		(net "SPI_PCH_MOSI")
	)
	(segment
		(start 406.9461 -65.890902)
		(end 406.9461 -64.897)
		(width 0.10795)
		(layer "F.Cu")
		(net "SPI_PCH_MOSI")
	)
	(segment
		(start 406.9461 -63.373)
		(end 406.577546 -63.373)
		(width 0.10795)
		(layer "F.Cu")
		(net "SPI_PCH_MOSI")
	)
	(segment
		(start 406.541478 -63.409068)
		(end 406.197054 -63.409068)
		(width 0.10795)
		(layer "F.Cu")
		(net "SPI_PCH_MOSI")
	)
	(segment
		(start 406.9461 -64.897)
		(end 406.9461 -64.135)
		(width 0.10795)
		(layer "F.Cu")
		(net "SPI_PCH_MOSI")
	)
	(segment
		(start 407.350214 -68.574412)
		(end 407.028142 -68.25234)
		(width 0.10795)
		(layer "F.Cu")
		(net "SPI_PCH_MOSI")
	)
	(segment
		(start 406.577546 -63.373)
		(end 406.541478 -63.409068)
		(width 0.10795)
		(layer "F.Cu")
		(net "SPI_PCH_MOSI")
	)
	(segment
		(start 407.028142 -68.25234)
		(end 407.028142 -65.972944)
		(width 0.10795)
		(layer "F.Cu")
		(net "SPI_PCH_MOSI")
	)
	(segment
		(start 396.76578 -74.40422)
		(end 396.76578 -73.263506)
		(width 0.10795)
		(layer "F.Cu")
		(net "SPI_PCH_MOSI")
	)
	(segment
		(start 407.028142 -65.972944)
		(end 406.9461 -65.890902)
		(width 0.10795)
		(layer "F.Cu")
		(net "SPI_PCH_MOSI")
	)
	(segment
		(start 396.603728 -73.101454)
		(end 395.647418 -73.101454)
		(width 0.10795)
		(layer "F.Cu")
		(net "SPI_PCH_MOSI")
	)
	(segment
		(start 377.698 -84.6582)
		(end 377.275598 -84.6582)
		(width 0.10795)
		(layer "F.Cu")
		(net "SPI_PCH_MOSI")
	)
	(segment
		(start 404.752302 -71.89978)
		(end 407.350214 -69.301868)
		(width 0.10795)
		(layer "F.Cu")
		(net "SPI_PCH_MOSI")
	)
	(segment
		(start 396.76578 -73.263506)
		(end 396.603728 -73.101454)
		(width 0.10795)
		(layer "F.Cu")
		(net "SPI_PCH_MOSI")
	)
	(segment
		(start 395.40434 -72.41286)
		(end 395.91742 -71.89978)
		(width 0.10795)
		(layer "F.Cu")
		(net "SPI_PCH_MOSI")
	)
	(segment
		(start 396.57909 -74.59091)
		(end 396.76578 -74.40422)
		(width 0.10795)
		(layer "F.Cu")
		(net "SPI_PCH_MOSI")
	)
	(segment
		(start 393.9032 -75.2348)
		(end 393.9032 -74.775568)
		(width 0.10795)
		(layer "F.Cu")
		(net "SPI_PCH_MOSI")
	)
	(segment
		(start 376.207782 -85.156802)
		(end 375.158 -86.206584)
		(width 0.10795)
		(layer "F.Cu")
		(net "SPI_PCH_MOSI")
	)
	(segment
		(start 395.40434 -72.858376)
		(end 395.40434 -72.41286)
		(width 0.10795)
		(layer "F.Cu")
		(net "SPI_PCH_MOSI")
	)
	(segment
		(start 394.087858 -74.59091)
		(end 396.57909 -74.59091)
		(width 0.10795)
		(layer "F.Cu")
		(net "SPI_PCH_MOSI")
	)
	(via
		(at 381.898652 -80.789272)
		(size 0.508)
		(drill 0.254)
		(layers "F.Cu" "B.Cu")
		(net "SPI_PCH_MOSI")
	)
	(via
		(at 385.220464 -52.206398)
		(size 0.508)
		(drill 0.254)
		(layers "F.Cu" "B.Cu")
		(net "SPI_PCH_MOSI")
	)
	(via
		(at 391.914888 -75.376532)
		(size 0.6604)
		(drill 0.3302)
		(layers "F.Cu" "B.Cu")
		(net "SPI_PCH_MOSI")
	)
	(via
		(at 393.9032 -75.2348)
		(size 0.508)
		(drill 0.254)
		(layers "F.Cu" "B.Cu")
		(net "SPI_PCH_MOSI")
	)
	(via
		(at 377.698 -84.6582)
		(size 0.508)
		(drill 0.254)
		(layers "F.Cu" "B.Cu")
		(net "SPI_PCH_MOSI")
	)
	(segment
		(start 384.39598 -80.60182)
		(end 384.8227 -80.60182)
		(width 0.10795)
		(layer "B.Cu")
		(net "SPI_PCH_MOSI")
	)
	(segment
		(start 387.601968 -78.404212)
		(end 388.01675 -78.404212)
		(width 0.10795)
		(layer "B.Cu")
		(net "SPI_PCH_MOSI")
	)
	(segment
		(start 389.892032 -76.324968)
		(end 390.03478 -76.18222)
		(width 0.10795)
		(layer "B.Cu")
		(net "SPI_PCH_MOSI")
	)
	(segment
		(start 382.335024 -80.3529)
		(end 384.14706 -80.3529)
		(width 0.10795)
		(layer "B.Cu")
		(net "SPI_PCH_MOSI")
	)
	(segment
		(start 390.800336 -75.416664)
		(end 390.840468 -75.376532)
		(width 0.10795)
		(layer "B.Cu")
		(net "SPI_PCH_MOSI")
	)
	(segment
		(start 390.840468 -75.376532)
		(end 391.914888 -75.376532)
		(width 0.10795)
		(layer "B.Cu")
		(net "SPI_PCH_MOSI")
	)
	(segment
		(start 383.7051 -52.2605)
		(end 382.5875 -52.2605)
		(width 0.10795)
		(layer "B.Cu")
		(net "SPI_PCH_MOSI")
	)
	(segment
		(start 386.27304 -81.08696)
		(end 387.04774 -80.31226)
		(width 0.10795)
		(layer "B.Cu")
		(net "SPI_PCH_MOSI")
	)
	(segment
		(start 388.264146 -78.156816)
		(end 388.264146 -77.092556)
		(width 0.10795)
		(layer "B.Cu")
		(net "SPI_PCH_MOSI")
	)
	(segment
		(start 388.01675 -78.404212)
		(end 388.264146 -78.156816)
		(width 0.10795)
		(layer "B.Cu")
		(net "SPI_PCH_MOSI")
	)
	(segment
		(start 381.898652 -80.789272)
		(end 382.335024 -80.3529)
		(width 0.10795)
		(layer "B.Cu")
		(net "SPI_PCH_MOSI")
	)
	(segment
		(start 384.14706 -80.3529)
		(end 384.39598 -80.60182)
		(width 0.10795)
		(layer "B.Cu")
		(net "SPI_PCH_MOSI")
	)
	(segment
		(start 389.031734 -76.324968)
		(end 389.892032 -76.324968)
		(width 0.10795)
		(layer "B.Cu")
		(net "SPI_PCH_MOSI")
	)
	(segment
		(start 388.264146 -77.092556)
		(end 389.031734 -76.324968)
		(width 0.10795)
		(layer "B.Cu")
		(net "SPI_PCH_MOSI")
	)
	(segment
		(start 387.04774 -80.31226)
		(end 387.04774 -78.95844)
		(width 0.10795)
		(layer "B.Cu")
		(net "SPI_PCH_MOSI")
	)
	(segment
		(start 385.30784 -81.08696)
		(end 386.27304 -81.08696)
		(width 0.10795)
		(layer "B.Cu")
		(net "SPI_PCH_MOSI")
	)
	(segment
		(start 387.04774 -78.95844)
		(end 387.601968 -78.404212)
		(width 0.10795)
		(layer "B.Cu")
		(net "SPI_PCH_MOSI")
	)
	(segment
		(start 385.220464 -52.206398)
		(end 384.71221 -52.206398)
		(width 0.10795)
		(layer "B.Cu")
		(net "SPI_PCH_MOSI")
	)
	(segment
		(start 384.391408 -52.5272)
		(end 383.9718 -52.5272)
		(width 0.10795)
		(layer "B.Cu")
		(net "SPI_PCH_MOSI")
	)
	(segment
		(start 384.8227 -80.60182)
		(end 385.30784 -81.08696)
		(width 0.10795)
		(layer "B.Cu")
		(net "SPI_PCH_MOSI")
	)
	(segment
		(start 393.761468 -75.376532)
		(end 393.9032 -75.2348)
		(width 0.10795)
		(layer "B.Cu")
		(net "SPI_PCH_MOSI")
	)
	(segment
		(start 384.71221 -52.206398)
		(end 384.391408 -52.5272)
		(width 0.10795)
		(layer "B.Cu")
		(net "SPI_PCH_MOSI")
	)
	(segment
		(start 390.800336 -75.423014)
		(end 390.800336 -75.416664)
		(width 0.10795)
		(layer "B.Cu")
		(net "SPI_PCH_MOSI")
	)
	(segment
		(start 391.914888 -75.376532)
		(end 393.761468 -75.376532)
		(width 0.10795)
		(layer "B.Cu")
		(net "SPI_PCH_MOSI")
	)
	(segment
		(start 390.04113 -76.18222)
		(end 390.800336 -75.423014)
		(width 0.10795)
		(layer "B.Cu")
		(net "SPI_PCH_MOSI")
	)
	(segment
		(start 390.03478 -76.18222)
		(end 390.04113 -76.18222)
		(width 0.10795)
		(layer "B.Cu")
		(net "SPI_PCH_MOSI")
	)
	(segment
		(start 383.9718 -52.5272)
		(end 383.7051 -52.2605)
		(width 0.10795)
		(layer "B.Cu")
		(net "SPI_PCH_MOSI")
	)
	(segment
		(start 383.54635 -68.623434)
		(end 383.635758 -68.534026)
		(width 0.089408)
		(layer "In9.Cu")
		(net "SPI_PCH_MOSI")
	)
	(segment
		(start 383.832608 -68.153026)
		(end 383.7432 -68.063618)
		(width 0.089408)
		(layer "In9.Cu")
		(net "SPI_PCH_MOSI")
	)
	(segment
		(start 383.827274 -60.774834)
		(end 384.72364 -59.878468)
		(width 0.089408)
		(layer "In9.Cu")
		(net "SPI_PCH_MOSI")
	)
	(segment
		(start 386.19557 -58.3438)
		(end 386.38099 -58.3438)
		(width 0.089408)
		(layer "In9.Cu")
		(net "SPI_PCH_MOSI")
	)
	(segment
		(start 383.580894 -67.59321)
		(end 383.7432 -67.59321)
		(width 0.089408)
		(layer "In9.Cu")
		(net "SPI_PCH_MOSI")
	)
	(segment
		(start 384.85445 -56.7182)
		(end 385.03987 -56.7182)
		(width 0.089408)
		(layer "In9.Cu")
		(net "SPI_PCH_MOSI")
	)
	(segment
		(start 385.28498 -52.270914)
		(end 385.220464 -52.206398)
		(width 0.089408)
		(layer "In9.Cu")
		(net "SPI_PCH_MOSI")
	)
	(segment
		(start 385.601464 -52.270914)
		(end 385.28498 -52.270914)
		(width 0.089408)
		(layer "In9.Cu")
		(net "SPI_PCH_MOSI")
	)
	(segment
		(start 384.279648 -66.12001)
		(end 384.279648 -68.81368)
		(width 0.089408)
		(layer "In9.Cu")
		(net "SPI_PCH_MOSI")
	)
	(segment
		(start 386.5118 -53.497734)
		(end 386.32765 -53.313584)
		(width 0.089408)
		(layer "In9.Cu")
		(net "SPI_PCH_MOSI")
	)
	(segment
		(start 385.93395 -53.201316)
		(end 386.06476 -53.332126)
		(width 0.089408)
		(layer "In9.Cu")
		(net "SPI_PCH_MOSI")
	)
	(segment
		(start 383.54635 -68.915026)
		(end 383.54635 -68.623434)
		(width 0.089408)
		(layer "In9.Cu")
		(net "SPI_PCH_MOSI")
	)
	(segment
		(start 383.580894 -68.063618)
		(end 383.491486 -67.97421)
		(width 0.089408)
		(layer "In9.Cu")
		(net "SPI_PCH_MOSI")
	)
	(segment
		(start 385.48691 -58.3438)
		(end 385.61772 -58.21299)
		(width 0.089408)
		(layer "In9.Cu")
		(net "SPI_PCH_MOSI")
	)
	(segment
		(start 386.06476 -53.332126)
		(end 386.06476 -58.21299)
		(width 0.089408)
		(layer "In9.Cu")
		(net "SPI_PCH_MOSI")
	)
	(segment
		(start 383.963418 -65.9892)
		(end 384.148838 -65.9892)
		(width 0.089408)
		(layer "In9.Cu")
		(net "SPI_PCH_MOSI")
	)
	(segment
		(start 384.406648 -68.94068)
		(end 384.599688 -68.94068)
		(width 0.089408)
		(layer "In9.Cu")
		(net "SPI_PCH_MOSI")
	)
	(segment
		(start 384.192272 -61.762894)
		(end 383.827274 -61.397896)
		(width 0.089408)
		(layer "In9.Cu")
		(net "SPI_PCH_MOSI")
	)
	(segment
		(start 383.491486 -67.97421)
		(end 383.491486 -67.682618)
		(width 0.089408)
		(layer "In9.Cu")
		(net "SPI_PCH_MOSI")
	)
	(segment
		(start 384.192272 -64.236092)
		(end 384.192272 -61.762894)
		(width 0.089408)
		(layer "In9.Cu")
		(net "SPI_PCH_MOSI")
	)
	(segment
		(start 377.698 -84.6582)
		(end 377.368308 -84.328508)
		(width 0.089408)
		(layer "In9.Cu")
		(net "SPI_PCH_MOSI")
	)
	(segment
		(start 377.368308 -84.328508)
		(end 377.368308 -83.413346)
		(width 0.089408)
		(layer "In9.Cu")
		(net "SPI_PCH_MOSI")
	)
	(segment
		(start 386.06476 -58.21299)
		(end 386.19557 -58.3438)
		(width 0.089408)
		(layer "In9.Cu")
		(net "SPI_PCH_MOSI")
	)
	(segment
		(start 383.827274 -61.397896)
		(end 383.827274 -60.774834)
		(width 0.089408)
		(layer "In9.Cu")
		(net "SPI_PCH_MOSI")
	)
	(segment
		(start 383.7432 -68.534026)
		(end 383.832608 -68.444618)
		(width 0.089408)
		(layer "In9.Cu")
		(net "SPI_PCH_MOSI")
	)
	(segment
		(start 383.832608 -67.503802)
		(end 383.832608 -66.12001)
		(width 0.089408)
		(layer "In9.Cu")
		(net "SPI_PCH_MOSI")
	)
	(segment
		(start 383.7432 -67.59321)
		(end 383.832608 -67.503802)
		(width 0.089408)
		(layer "In9.Cu")
		(net "SPI_PCH_MOSI")
	)
	(segment
		(start 383.7432 -69.004434)
		(end 383.635758 -69.004434)
		(width 0.089408)
		(layer "In9.Cu")
		(net "SPI_PCH_MOSI")
	)
	(segment
		(start 384.72364 -56.84901)
		(end 384.85445 -56.7182)
		(width 0.089408)
		(layer "In9.Cu")
		(net "SPI_PCH_MOSI")
	)
	(segment
		(start 382.78308 -71.72579)
		(end 382.78308 -70.525132)
		(width 0.089408)
		(layer "In9.Cu")
		(net "SPI_PCH_MOSI")
	)
	(segment
		(start 383.635758 -68.534026)
		(end 383.7432 -68.534026)
		(width 0.089408)
		(layer "In9.Cu")
		(net "SPI_PCH_MOSI")
	)
	(segment
		(start 383.7432 -68.063618)
		(end 383.580894 -68.063618)
		(width 0.089408)
		(layer "In9.Cu")
		(net "SPI_PCH_MOSI")
	)
	(segment
		(start 385.675632 -49.257458)
		(end 385.675632 -52.196746)
		(width 0.089408)
		(layer "In9.Cu")
		(net "SPI_PCH_MOSI")
	)
	(segment
		(start 382.051814 -72.457056)
		(end 382.78308 -71.72579)
		(width 0.089408)
		(layer "In9.Cu")
		(net "SPI_PCH_MOSI")
	)
	(segment
		(start 385.17068 -58.21299)
		(end 385.30149 -58.3438)
		(width 0.089408)
		(layer "In9.Cu")
		(net "SPI_PCH_MOSI")
	)
	(segment
		(start 386.32765 -53.313584)
		(end 386.32765 -49.293526)
		(width 0.089408)
		(layer "In9.Cu")
		(net "SPI_PCH_MOSI")
	)
	(segment
		(start 385.675632 -52.196746)
		(end 385.601464 -52.270914)
		(width 0.089408)
		(layer "In9.Cu")
		(net "SPI_PCH_MOSI")
	)
	(segment
		(start 384.599688 -68.94068)
		(end 384.726688 -68.81368)
		(width 0.089408)
		(layer "In9.Cu")
		(net "SPI_PCH_MOSI")
	)
	(segment
		(start 384.148838 -65.9892)
		(end 384.279648 -66.12001)
		(width 0.089408)
		(layer "In9.Cu")
		(net "SPI_PCH_MOSI")
	)
	(segment
		(start 383.832608 -69.093842)
		(end 383.7432 -69.004434)
		(width 0.089408)
		(layer "In9.Cu")
		(net "SPI_PCH_MOSI")
	)
	(segment
		(start 385.811014 -49.122076)
		(end 385.675632 -49.257458)
		(width 0.089408)
		(layer "In9.Cu")
		(net "SPI_PCH_MOSI")
	)
	(segment
		(start 382.051814 -75.711812)
		(end 382.051814 -72.457056)
		(width 0.089408)
		(layer "In9.Cu")
		(net "SPI_PCH_MOSI")
	)
	(segment
		(start 386.38099 -58.3438)
		(end 386.5118 -58.21299)
		(width 0.089408)
		(layer "In9.Cu")
		(net "SPI_PCH_MOSI")
	)
	(segment
		(start 380.74219 -80.039464)
		(end 380.74219 -77.021436)
		(width 0.089408)
		(layer "In9.Cu")
		(net "SPI_PCH_MOSI")
	)
	(segment
		(start 380.74219 -77.021436)
		(end 382.051814 -75.711812)
		(width 0.089408)
		(layer "In9.Cu")
		(net "SPI_PCH_MOSI")
	)
	(segment
		(start 383.832608 -66.12001)
		(end 383.963418 -65.9892)
		(width 0.089408)
		(layer "In9.Cu")
		(net "SPI_PCH_MOSI")
	)
	(segment
		(start 385.74853 -53.201316)
		(end 385.93395 -53.201316)
		(width 0.089408)
		(layer "In9.Cu")
		(net "SPI_PCH_MOSI")
	)
	(segment
		(start 385.61772 -53.332126)
		(end 385.74853 -53.201316)
		(width 0.089408)
		(layer "In9.Cu")
		(net "SPI_PCH_MOSI")
	)
	(segment
		(start 386.5118 -58.21299)
		(end 386.5118 -53.497734)
		(width 0.089408)
		(layer "In9.Cu")
		(net "SPI_PCH_MOSI")
	)
	(segment
		(start 383.832608 -68.444618)
		(end 383.832608 -68.153026)
		(width 0.089408)
		(layer "In9.Cu")
		(net "SPI_PCH_MOSI")
	)
	(segment
		(start 384.72364 -59.878468)
		(end 384.72364 -56.84901)
		(width 0.089408)
		(layer "In9.Cu")
		(net "SPI_PCH_MOSI")
	)
	(segment
		(start 382.78308 -70.525132)
		(end 383.832608 -69.475604)
		(width 0.089408)
		(layer "In9.Cu")
		(net "SPI_PCH_MOSI")
	)
	(segment
		(start 383.491486 -67.682618)
		(end 383.580894 -67.59321)
		(width 0.089408)
		(layer "In9.Cu")
		(net "SPI_PCH_MOSI")
	)
	(segment
		(start 386.1562 -49.122076)
		(end 385.811014 -49.122076)
		(width 0.089408)
		(layer "In9.Cu")
		(net "SPI_PCH_MOSI")
	)
	(segment
		(start 384.726688 -64.770508)
		(end 384.192272 -64.236092)
		(width 0.089408)
		(layer "In9.Cu")
		(net "SPI_PCH_MOSI")
	)
	(segment
		(start 385.17068 -56.84901)
		(end 385.17068 -58.21299)
		(width 0.089408)
		(layer "In9.Cu")
		(net "SPI_PCH_MOSI")
	)
	(segment
		(start 377.368308 -83.413346)
		(end 380.74219 -80.039464)
		(width 0.089408)
		(layer "In9.Cu")
		(net "SPI_PCH_MOSI")
	)
	(segment
		(start 384.279648 -68.81368)
		(end 384.406648 -68.94068)
		(width 0.089408)
		(layer "In9.Cu")
		(net "SPI_PCH_MOSI")
	)
	(segment
		(start 385.61772 -58.21299)
		(end 385.61772 -53.332126)
		(width 0.089408)
		(layer "In9.Cu")
		(net "SPI_PCH_MOSI")
	)
	(segment
		(start 383.635758 -69.004434)
		(end 383.54635 -68.915026)
		(width 0.089408)
		(layer "In9.Cu")
		(net "SPI_PCH_MOSI")
	)
	(segment
		(start 385.30149 -58.3438)
		(end 385.48691 -58.3438)
		(width 0.089408)
		(layer "In9.Cu")
		(net "SPI_PCH_MOSI")
	)
	(segment
		(start 383.832608 -69.475604)
		(end 383.832608 -69.093842)
		(width 0.089408)
		(layer "In9.Cu")
		(net "SPI_PCH_MOSI")
	)
	(segment
		(start 385.03987 -56.7182)
		(end 385.17068 -56.84901)
		(width 0.089408)
		(layer "In9.Cu")
		(net "SPI_PCH_MOSI")
	)
	(segment
		(start 384.726688 -68.81368)
		(end 384.726688 -64.770508)
		(width 0.089408)
		(layer "In9.Cu")
		(net "SPI_PCH_MOSI")
	)
	(segment
		(start 386.32765 -49.293526)
		(end 386.1562 -49.122076)
		(width 0.089408)
		(layer "In9.Cu")
		(net "SPI_PCH_MOSI")
	)
	(segment
		(start 381.898652 -80.789272)
		(end 379.753368 -80.789272)
		(width 0.089408)
		(layer "In11.Cu")
		(net "SPI_PCH_MOSI")
	)
	(segment
		(start 378.4092 -82.13344)
		(end 378.4092 -83.947)
		(width 0.089408)
		(layer "In11.Cu")
		(net "SPI_PCH_MOSI")
	)
	(segment
		(start 378.4092 -83.947)
		(end 377.698 -84.6582)
		(width 0.089408)
		(layer "In11.Cu")
		(net "SPI_PCH_MOSI")
	)
	(segment
		(start 379.753368 -80.789272)
		(end 378.4092 -82.13344)
		(width 0.089408)
		(layer "In11.Cu")
		(net "SPI_PCH_MOSI")
	)
	(segment
		(start 378.87021 -93.195902)
		(end 378.967746 -93.098366)
		(width 0.10795)
		(layer "F.Cu")
		(net "SPI_PCH_MISO")
	)
	(segment
		(start 378.985018 -94.37497)
		(end 378.985018 -94.019878)
		(width 0.0889)
		(layer "F.Cu")
		(net "SPI_PCH_MISO")
	)
	(segment
		(start 378.985018 -94.019878)
		(end 378.689362 -93.724222)
		(width 0.0889)
		(layer "F.Cu")
		(net "SPI_PCH_MISO")
	)
	(segment
		(start 378.967746 -91.766898)
		(end 378.073666 -90.872818)
		(width 0.10795)
		(layer "F.Cu")
		(net "SPI_PCH_MISO")
	)
	(segment
		(start 405.56815 -63.47333)
		(end 405.4602 -63.58128)
		(width 0.10795)
		(layer "F.Cu")
		(net "SPI_PCH_MISO")
	)
	(segment
		(start 378.689362 -93.377004)
		(end 378.87021 -93.196156)
		(width 0.0889)
		(layer "F.Cu")
		(net "SPI_PCH_MISO")
	)
	(segment
		(start 378.689362 -93.724222)
		(end 378.689362 -93.377004)
		(width 0.0889)
		(layer "F.Cu")
		(net "SPI_PCH_MISO")
	)
	(segment
		(start 378.87021 -93.196156)
		(end 378.87021 -93.195902)
		(width 0.0889)
		(layer "F.Cu")
		(net "SPI_PCH_MISO")
	)
	(segment
		(start 405.873458 -62.986666)
		(end 405.863298 -62.996826)
		(width 0.10795)
		(layer "F.Cu")
		(net "SPI_PCH_MISO")
	)
	(segment
		(start 406.917906 -62.611)
		(end 406.54224 -62.986666)
		(width 0.10795)
		(layer "F.Cu")
		(net "SPI_PCH_MISO")
	)
	(segment
		(start 405.56815 -63.17869)
		(end 405.56815 -63.47333)
		(width 0.10795)
		(layer "F.Cu")
		(net "SPI_PCH_MISO")
	)
	(segment
		(start 405.863298 -62.996826)
		(end 405.750014 -62.996826)
		(width 0.10795)
		(layer "F.Cu")
		(net "SPI_PCH_MISO")
	)
	(segment
		(start 406.9461 -62.611)
		(end 406.917906 -62.611)
		(width 0.10795)
		(layer "F.Cu")
		(net "SPI_PCH_MISO")
	)
	(segment
		(start 378.967746 -93.098366)
		(end 378.967746 -91.766898)
		(width 0.10795)
		(layer "F.Cu")
		(net "SPI_PCH_MISO")
	)
	(segment
		(start 405.750014 -62.996826)
		(end 405.56815 -63.17869)
		(width 0.10795)
		(layer "F.Cu")
		(net "SPI_PCH_MISO")
	)
	(segment
		(start 406.54224 -62.986666)
		(end 405.873458 -62.986666)
		(width 0.10795)
		(layer "F.Cu")
		(net "SPI_PCH_MISO")
	)
	(via
		(at 385.219702 -61.126624)
		(size 0.508)
		(drill 0.254)
		(layers "F.Cu" "B.Cu")
		(net "SPI_PCH_MISO")
	)
	(via
		(at 405.4602 -63.58128)
		(size 0.508)
		(drill 0.254)
		(layers "F.Cu" "B.Cu")
		(net "SPI_PCH_MISO")
	)
	(via
		(at 383.90576 -63.747396)
		(size 0.6604)
		(drill 0.3302)
		(layers "F.Cu" "B.Cu")
		(net "SPI_PCH_MISO")
	)
	(via
		(at 378.073666 -90.872818)
		(size 0.508)
		(drill 0.254)
		(layers "F.Cu" "B.Cu")
		(net "SPI_PCH_MISO")
	)
	(segment
		(start 385.115562 -61.230764)
		(end 385.219702 -61.126624)
		(width 0.10795)
		(layer "B.Cu")
		(net "SPI_PCH_MISO")
	)
	(segment
		(start 383.90576 -63.747396)
		(end 383.380742 -63.747396)
		(width 0.10795)
		(layer "B.Cu")
		(net "SPI_PCH_MISO")
	)
	(segment
		(start 384.71094 -63.747396)
		(end 385.115562 -63.342774)
		(width 0.10795)
		(layer "B.Cu")
		(net "SPI_PCH_MISO")
	)
	(segment
		(start 383.0574 -63.424054)
		(end 383.0574 -62.690756)
		(width 0.10795)
		(layer "B.Cu")
		(net "SPI_PCH_MISO")
	)
	(segment
		(start 375.8184 -56.6039)
		(end 375.285 -56.6039)
		(width 0.10795)
		(layer "B.Cu")
		(net "SPI_PCH_MISO")
	)
	(segment
		(start 383.380742 -63.747396)
		(end 383.0574 -63.424054)
		(width 0.10795)
		(layer "B.Cu")
		(net "SPI_PCH_MISO")
	)
	(segment
		(start 382.258062 -61.891418)
		(end 381.44196 -61.891418)
		(width 0.10795)
		(layer "B.Cu")
		(net "SPI_PCH_MISO")
	)
	(segment
		(start 383.90576 -63.747396)
		(end 384.71094 -63.747396)
		(width 0.10795)
		(layer "B.Cu")
		(net "SPI_PCH_MISO")
	)
	(segment
		(start 375.94286 -56.1594)
		(end 375.94286 -56.47944)
		(width 0.10795)
		(layer "B.Cu")
		(net "SPI_PCH_MISO")
	)
	(segment
		(start 375.94286 -56.47944)
		(end 375.8184 -56.6039)
		(width 0.10795)
		(layer "B.Cu")
		(net "SPI_PCH_MISO")
	)
	(segment
		(start 385.115562 -63.342774)
		(end 385.115562 -61.230764)
		(width 0.10795)
		(layer "B.Cu")
		(net "SPI_PCH_MISO")
	)
	(segment
		(start 383.0574 -62.690756)
		(end 382.258062 -61.891418)
		(width 0.10795)
		(layer "B.Cu")
		(net "SPI_PCH_MISO")
	)
	(segment
		(start 381.44196 -61.891418)
		(end 379.788674 -60.238132)
		(width 0.10795)
		(layer "B.Cu")
		(net "SPI_PCH_MISO")
	)
	(segment
		(start 377.89231 -55.983632)
		(end 376.118628 -55.983632)
		(width 0.10795)
		(layer "B.Cu")
		(net "SPI_PCH_MISO")
	)
	(segment
		(start 379.788674 -57.879996)
		(end 377.89231 -55.983632)
		(width 0.10795)
		(layer "B.Cu")
		(net "SPI_PCH_MISO")
	)
	(segment
		(start 379.788674 -60.238132)
		(end 379.788674 -57.879996)
		(width 0.10795)
		(layer "B.Cu")
		(net "SPI_PCH_MISO")
	)
	(segment
		(start 376.118628 -55.983632)
		(end 375.94286 -56.1594)
		(width 0.10795)
		(layer "B.Cu")
		(net "SPI_PCH_MISO")
	)
	(segment
		(start 382.471422 -73.367138)
		(end 382.9812 -73.876916)
		(width 0.089408)
		(layer "In2.Cu")
		(net "SPI_PCH_MISO")
	)
	(segment
		(start 384.64617 -68.7578)
		(end 382.471422 -70.932548)
		(width 0.089408)
		(layer "In2.Cu")
		(net "SPI_PCH_MISO")
	)
	(segment
		(start 381.367792 -84.571078)
		(end 381.367792 -85.537548)
		(width 0.089408)
		(layer "In2.Cu")
		(net "SPI_PCH_MISO")
	)
	(segment
		(start 381.899668 -78.489048)
		(end 381.567944 -78.820772)
		(width 0.089408)
		(layer "In2.Cu")
		(net "SPI_PCH_MISO")
	)
	(segment
		(start 385.219702 -61.126624)
		(end 385.173982 -61.172344)
		(width 0.089408)
		(layer "In2.Cu")
		(net "SPI_PCH_MISO")
	)
	(segment
		(start 382.9812 -73.876916)
		(end 382.9812 -76.24064)
		(width 0.089408)
		(layer "In2.Cu")
		(net "SPI_PCH_MISO")
	)
	(segment
		(start 381.567944 -78.820772)
		(end 381.567944 -79.927196)
		(width 0.089408)
		(layer "In2.Cu")
		(net "SPI_PCH_MISO")
	)
	(segment
		(start 380.016258 -87.389462)
		(end 378.398786 -87.389462)
		(width 0.089408)
		(layer "In2.Cu")
		(net "SPI_PCH_MISO")
	)
	(segment
		(start 381.567944 -79.927196)
		(end 380.47168 -81.02346)
		(width 0.089408)
		(layer "In2.Cu")
		(net "SPI_PCH_MISO")
	)
	(segment
		(start 378.398786 -87.389462)
		(end 377.375928 -88.41232)
		(width 0.089408)
		(layer "In2.Cu")
		(net "SPI_PCH_MISO")
	)
	(segment
		(start 385.173982 -63.638938)
		(end 384.64617 -64.16675)
		(width 0.089408)
		(layer "In2.Cu")
		(net "SPI_PCH_MISO")
	)
	(segment
		(start 380.41834 -86.98738)
		(end 380.016258 -87.389462)
		(width 0.089408)
		(layer "In2.Cu")
		(net "SPI_PCH_MISO")
	)
	(segment
		(start 381.367792 -85.537548)
		(end 381.03048 -85.87486)
		(width 0.089408)
		(layer "In2.Cu")
		(net "SPI_PCH_MISO")
	)
	(segment
		(start 380.47168 -83.674966)
		(end 381.367792 -84.571078)
		(width 0.089408)
		(layer "In2.Cu")
		(net "SPI_PCH_MISO")
	)
	(segment
		(start 384.64617 -64.16675)
		(end 384.64617 -68.7578)
		(width 0.089408)
		(layer "In2.Cu")
		(net "SPI_PCH_MISO")
	)
	(segment
		(start 381.03048 -85.87486)
		(end 381.03048 -86.03742)
		(width 0.089408)
		(layer "In2.Cu")
		(net "SPI_PCH_MISO")
	)
	(segment
		(start 381.899668 -77.322172)
		(end 381.899668 -78.489048)
		(width 0.089408)
		(layer "In2.Cu")
		(net "SPI_PCH_MISO")
	)
	(segment
		(start 380.47168 -81.02346)
		(end 380.47168 -83.674966)
		(width 0.089408)
		(layer "In2.Cu")
		(net "SPI_PCH_MISO")
	)
	(segment
		(start 377.375928 -90.17508)
		(end 378.073666 -90.872818)
		(width 0.089408)
		(layer "In2.Cu")
		(net "SPI_PCH_MISO")
	)
	(segment
		(start 381.03048 -86.03742)
		(end 380.41834 -86.64956)
		(width 0.089408)
		(layer "In2.Cu")
		(net "SPI_PCH_MISO")
	)
	(segment
		(start 382.471422 -70.932548)
		(end 382.471422 -73.367138)
		(width 0.089408)
		(layer "In2.Cu")
		(net "SPI_PCH_MISO")
	)
	(segment
		(start 380.41834 -86.64956)
		(end 380.41834 -86.98738)
		(width 0.089408)
		(layer "In2.Cu")
		(net "SPI_PCH_MISO")
	)
	(segment
		(start 382.9812 -76.24064)
		(end 381.899668 -77.322172)
		(width 0.089408)
		(layer "In2.Cu")
		(net "SPI_PCH_MISO")
	)
	(segment
		(start 385.173982 -61.172344)
		(end 385.173982 -63.638938)
		(width 0.089408)
		(layer "In2.Cu")
		(net "SPI_PCH_MISO")
	)
	(segment
		(start 377.375928 -88.41232)
		(end 377.375928 -90.17508)
		(width 0.089408)
		(layer "In2.Cu")
		(net "SPI_PCH_MISO")
	)
	(segment
		(start 390.95172 -61.474858)
		(end 390.94283 -61.465968)
		(width 0.089408)
		(layer "In4.Cu")
		(net "SPI_PCH_MISO")
	)
	(segment
		(start 393.775692 -61.119512)
		(end 393.746228 -61.119512)
		(width 0.089408)
		(layer "In4.Cu")
		(net "SPI_PCH_MISO")
	)
	(segment
		(start 394.212572 -61.556392)
		(end 393.775692 -61.119512)
		(width 0.089408)
		(layer "In4.Cu")
		(net "SPI_PCH_MISO")
	)
	(segment
		(start 392.162792 -61.793628)
		(end 391.276078 -61.793628)
		(width 0.089408)
		(layer "In4.Cu")
		(net "SPI_PCH_MISO")
	)
	(segment
		(start 391.276078 -61.793628)
		(end 390.957308 -61.474858)
		(width 0.089408)
		(layer "In4.Cu")
		(net "SPI_PCH_MISO")
	)
	(segment
		(start 392.84656 -61.10986)
		(end 392.162792 -61.793628)
		(width 0.089408)
		(layer "In4.Cu")
		(net "SPI_PCH_MISO")
	)
	(segment
		(start 387.913372 -61.465968)
		(end 387.3119 -62.06744)
		(width 0.089408)
		(layer "In4.Cu")
		(net "SPI_PCH_MISO")
	)
	(segment
		(start 393.746228 -61.119512)
		(end 393.736576 -61.10986)
		(width 0.089408)
		(layer "In4.Cu")
		(net "SPI_PCH_MISO")
	)
	(segment
		(start 393.736576 -61.10986)
		(end 392.84656 -61.10986)
		(width 0.089408)
		(layer "In4.Cu")
		(net "SPI_PCH_MISO")
	)
	(segment
		(start 385.389374 -61.296296)
		(end 385.219702 -61.126624)
		(width 0.089408)
		(layer "In4.Cu")
		(net "SPI_PCH_MISO")
	)
	(segment
		(start 390.94283 -61.465968)
		(end 387.913372 -61.465968)
		(width 0.089408)
		(layer "In4.Cu")
		(net "SPI_PCH_MISO")
	)
	(segment
		(start 405.4602 -63.58128)
		(end 404.589488 -62.710568)
		(width 0.089408)
		(layer "In4.Cu")
		(net "SPI_PCH_MISO")
	)
	(segment
		(start 386.7531 -62.06744)
		(end 385.981956 -61.296296)
		(width 0.089408)
		(layer "In4.Cu")
		(net "SPI_PCH_MISO")
	)
	(segment
		(start 390.957308 -61.474858)
		(end 390.95172 -61.474858)
		(width 0.089408)
		(layer "In4.Cu")
		(net "SPI_PCH_MISO")
	)
	(segment
		(start 404.589488 -62.710568)
		(end 399.671794 -62.710568)
		(width 0.089408)
		(layer "In4.Cu")
		(net "SPI_PCH_MISO")
	)
	(segment
		(start 399.671794 -62.710568)
		(end 398.517618 -61.556392)
		(width 0.089408)
		(layer "In4.Cu")
		(net "SPI_PCH_MISO")
	)
	(segment
		(start 398.517618 -61.556392)
		(end 394.212572 -61.556392)
		(width 0.089408)
		(layer "In4.Cu")
		(net "SPI_PCH_MISO")
	)
	(segment
		(start 385.981956 -61.296296)
		(end 385.389374 -61.296296)
		(width 0.089408)
		(layer "In4.Cu")
		(net "SPI_PCH_MISO")
	)
	(segment
		(start 387.3119 -62.06744)
		(end 386.7531 -62.06744)
		(width 0.089408)
		(layer "In4.Cu")
		(net "SPI_PCH_MISO")
	)
	(segment
		(start 375.285 -55.7149)
		(end 375.721626 -55.278274)
		(width 0.10795)
		(layer "B.Cu")
		(net "SPI_PCH_MISO_R")
	)
	(segment
		(start 375.721626 -55.278274)
		(end 375.721626 -54.035198)
		(width 0.10795)
		(layer "B.Cu")
		(net "SPI_PCH_MISO_R")
	)
	(segment
		(start 376.226324 -53.5305)
		(end 377.1265 -53.5305)
		(width 0.10795)
		(layer "B.Cu")
		(net "SPI_PCH_MISO_R")
	)
	(segment
		(start 375.721626 -54.035198)
		(end 376.226324 -53.5305)
		(width 0.10795)
		(layer "B.Cu")
		(net "SPI_PCH_MISO_R")
	)
	(segment
		(start 377.004072 -87.3125)
		(end 376.682 -87.3125)
		(width 0.10795)
		(layer "F.Cu")
		(net "SPI_PCH_IO3")
	)
	(segment
		(start 377.698 -88.2015)
		(end 377.698 -89.812622)
		(width 0.10795)
		(layer "F.Cu")
		(net "SPI_PCH_IO3")
	)
	(segment
		(start 376.682 -86.682834)
		(end 376.682 -87.3125)
		(width 0.10795)
		(layer "F.Cu")
		(net "SPI_PCH_IO3")
	)
	(segment
		(start 378.546106 -90.833194)
		(end 379.177296 -91.464384)
		(width 0.10795)
		(layer "F.Cu")
		(net "SPI_PCH_IO3")
	)
	(segment
		(start 377.385834 -88.2015)
		(end 377.202954 -88.01862)
		(width 0.10795)
		(layer "F.Cu")
		(net "SPI_PCH_IO3")
	)
	(segment
		(start 377.698 -88.2015)
		(end 377.385834 -88.2015)
		(width 0.10795)
		(layer "F.Cu")
		(net "SPI_PCH_IO3")
	)
	(segment
		(start 378.546106 -90.660728)
		(end 378.546106 -90.833194)
		(width 0.10795)
		(layer "F.Cu")
		(net "SPI_PCH_IO3")
	)
	(segment
		(start 376.57659 -86.577424)
		(end 376.682 -86.682834)
		(width 0.10795)
		(layer "F.Cu")
		(net "SPI_PCH_IO3")
	)
	(segment
		(start 379.177296 -93.35262)
		(end 378.985018 -93.544898)
		(width 0.10795)
		(layer "F.Cu")
		(net "SPI_PCH_IO3")
	)
	(segment
		(start 377.698 -89.812622)
		(end 378.546106 -90.660728)
		(width 0.10795)
		(layer "F.Cu")
		(net "SPI_PCH_IO3")
	)
	(segment
		(start 377.202954 -87.511382)
		(end 377.004072 -87.3125)
		(width 0.10795)
		(layer "F.Cu")
		(net "SPI_PCH_IO3")
	)
	(segment
		(start 379.177296 -91.464384)
		(end 379.177296 -93.35262)
		(width 0.10795)
		(layer "F.Cu")
		(net "SPI_PCH_IO3")
	)
	(segment
		(start 377.202954 -88.01862)
		(end 377.202954 -87.511382)
		(width 0.10795)
		(layer "F.Cu")
		(net "SPI_PCH_IO3")
	)
	(via
		(at 376.57659 -86.577424)
		(size 0.508)
		(drill 0.254)
		(layers "F.Cu" "B.Cu")
		(net "SPI_PCH_IO3")
	)
	(via
		(at 385.203446 -59.506612)
		(size 0.508)
		(drill 0.254)
		(layers "F.Cu" "B.Cu")
		(net "SPI_PCH_IO3")
	)
	(via
		(at 377.4059 -87.5284)
		(size 0.6604)
		(drill 0.3302)
		(layers "F.Cu" "B.Cu")
		(net "SPI_PCH_IO3")
	)
	(segment
		(start 385.203446 -59.506612)
		(end 385.599178 -59.506612)
		(width 0.10795)
		(layer "B.Cu")
		(net "SPI_PCH_IO3")
	)
	(segment
		(start 376.57659 -86.69909)
		(end 376.57659 -86.577424)
		(width 0.10795)
		(layer "B.Cu")
		(net "SPI_PCH_IO3")
	)
	(segment
		(start 377.4059 -87.5284)
		(end 376.57659 -86.69909)
		(width 0.10795)
		(layer "B.Cu")
		(net "SPI_PCH_IO3")
	)
	(segment
		(start 385.599178 -59.506612)
		(end 385.778248 -59.327542)
		(width 0.10795)
		(layer "B.Cu")
		(net "SPI_PCH_IO3")
	)
	(segment
		(start 385.778248 -59.327542)
		(end 385.778248 -58.809128)
		(width 0.10795)
		(layer "B.Cu")
		(net "SPI_PCH_IO3")
	)
	(segment
		(start 383.075688 -71.847202)
		(end 383.075688 -70.646544)
		(width 0.089408)
		(layer "In9.Cu")
		(net "SPI_PCH_IO3")
	)
	(segment
		(start 378.20854 -82.993992)
		(end 380.567438 -80.635094)
		(width 0.089408)
		(layer "In9.Cu")
		(net "SPI_PCH_IO3")
	)
	(segment
		(start 381.034798 -77.142848)
		(end 382.344422 -75.833224)
		(width 0.089408)
		(layer "In9.Cu")
		(net "SPI_PCH_IO3")
	)
	(segment
		(start 376.57659 -86.577424)
		(end 376.57659 -86.094824)
		(width 0.089408)
		(layer "In9.Cu")
		(net "SPI_PCH_IO3")
	)
	(segment
		(start 384.765296 -60.579)
		(end 385.203446 -60.14085)
		(width 0.089408)
		(layer "In9.Cu")
		(net "SPI_PCH_IO3")
	)
	(segment
		(start 380.567438 -80.628236)
		(end 381.034798 -80.160876)
		(width 0.089408)
		(layer "In9.Cu")
		(net "SPI_PCH_IO3")
	)
	(segment
		(start 377.70054 -85.2424)
		(end 378.20854 -84.7344)
		(width 0.089408)
		(layer "In9.Cu")
		(net "SPI_PCH_IO3")
	)
	(segment
		(start 376.57659 -86.094824)
		(end 377.429014 -85.2424)
		(width 0.089408)
		(layer "In9.Cu")
		(net "SPI_PCH_IO3")
	)
	(segment
		(start 384.15468 -69.82968)
		(end 385.104386 -68.879974)
		(width 0.089408)
		(layer "In9.Cu")
		(net "SPI_PCH_IO3")
	)
	(segment
		(start 381.034798 -80.160876)
		(end 381.034798 -77.142848)
		(width 0.089408)
		(layer "In9.Cu")
		(net "SPI_PCH_IO3")
	)
	(segment
		(start 377.429014 -85.2424)
		(end 377.70054 -85.2424)
		(width 0.089408)
		(layer "In9.Cu")
		(net "SPI_PCH_IO3")
	)
	(segment
		(start 382.344422 -75.833224)
		(end 382.344422 -72.578468)
		(width 0.089408)
		(layer "In9.Cu")
		(net "SPI_PCH_IO3")
	)
	(segment
		(start 380.567438 -80.635094)
		(end 380.567438 -80.628236)
		(width 0.089408)
		(layer "In9.Cu")
		(net "SPI_PCH_IO3")
	)
	(segment
		(start 385.104386 -68.879974)
		(end 385.104386 -61.598556)
		(width 0.089408)
		(layer "In9.Cu")
		(net "SPI_PCH_IO3")
	)
	(segment
		(start 385.104386 -61.598556)
		(end 384.765296 -61.259466)
		(width 0.089408)
		(layer "In9.Cu")
		(net "SPI_PCH_IO3")
	)
	(segment
		(start 385.203446 -60.14085)
		(end 385.203446 -59.506612)
		(width 0.089408)
		(layer "In9.Cu")
		(net "SPI_PCH_IO3")
	)
	(segment
		(start 383.075688 -70.646544)
		(end 383.892552 -69.82968)
		(width 0.089408)
		(layer "In9.Cu")
		(net "SPI_PCH_IO3")
	)
	(segment
		(start 378.20854 -84.7344)
		(end 378.20854 -82.993992)
		(width 0.089408)
		(layer "In9.Cu")
		(net "SPI_PCH_IO3")
	)
	(segment
		(start 383.892552 -69.82968)
		(end 384.15468 -69.82968)
		(width 0.089408)
		(layer "In9.Cu")
		(net "SPI_PCH_IO3")
	)
	(segment
		(start 382.344422 -72.578468)
		(end 383.075688 -71.847202)
		(width 0.089408)
		(layer "In9.Cu")
		(net "SPI_PCH_IO3")
	)
	(segment
		(start 384.765296 -61.259466)
		(end 384.765296 -60.579)
		(width 0.089408)
		(layer "In9.Cu")
		(net "SPI_PCH_IO3")
	)
	(via
		(at 385.1783 -57.660794)
		(size 0.6604)
		(drill 0.3302)
		(layers "F.Cu" "B.Cu")
		(net "SPI_PCH_IO3_R1")
	)
	(segment
		(start 384.889248 -57.949846)
		(end 385.1783 -57.660794)
		(width 0.10795)
		(layer "B.Cu")
		(net "SPI_PCH_IO3_R1")
	)
	(segment
		(start 384.224784 -58.9915)
		(end 382.7653 -58.9915)
		(width 0.10795)
		(layer "B.Cu")
		(net "SPI_PCH_IO3_R1")
	)
	(segment
		(start 384.407156 -58.809128)
		(end 384.224784 -58.9915)
		(width 0.10795)
		(layer "B.Cu")
		(net "SPI_PCH_IO3_R1")
	)
	(segment
		(start 384.889248 -58.809128)
		(end 384.889248 -57.949846)
		(width 0.10795)
		(layer "B.Cu")
		(net "SPI_PCH_IO3_R1")
	)
	(segment
		(start 384.889248 -58.809128)
		(end 384.407156 -58.809128)
		(width 0.10795)
		(layer "B.Cu")
		(net "SPI_PCH_IO3_R1")
	)
	(segment
		(start 372.589552 -90.502486)
		(end 372.589552 -89.032588)
		(width 0.10795)
		(layer "F.Cu")
		(net "SPI_PCH_IO2")
	)
	(segment
		(start 375.596404 -84.189316)
		(end 375.596404 -83.965796)
		(width 0.10795)
		(layer "F.Cu")
		(net "SPI_PCH_IO2")
	)
	(segment
		(start 375.978166 -83.807554)
		(end 376.5677 -84.397088)
		(width 0.10795)
		(layer "F.Cu")
		(net "SPI_PCH_IO2")
	)
	(segment
		(start 375.596404 -83.965796)
		(end 375.754646 -83.807554)
		(width 0.10795)
		(layer "F.Cu")
		(net "SPI_PCH_IO2")
	)
	(segment
		(start 375.8565 -94.171008)
		(end 375.8565 -93.9165)
		(width 0.10795)
		(layer "F.Cu")
		(net "SPI_PCH_IO2")
	)
	(segment
		(start 372.2116 -90.880438)
		(end 372.589552 -90.502486)
		(width 0.10795)
		(layer "F.Cu")
		(net "SPI_PCH_IO2")
	)
	(segment
		(start 375.031 -93.091)
		(end 375.031 -92.44965)
		(width 0.10795)
		(layer "F.Cu")
		(net "SPI_PCH_IO2")
	)
	(segment
		(start 375.222262 -85.342222)
		(end 374.85828 -84.97824)
		(width 0.10795)
		(layer "F.Cu")
		(net "SPI_PCH_IO2")
	)
	(segment
		(start 372.74754 -88.8746)
		(end 372.971314 -88.8746)
		(width 0.10795)
		(layer "F.Cu")
		(net "SPI_PCH_IO2")
	)
	(segment
		(start 374.923812 -91.2622)
		(end 372.369588 -91.2622)
		(width 0.10795)
		(layer "F.Cu")
		(net "SPI_PCH_IO2")
	)
	(segment
		(start 375.629424 -84.98586)
		(end 375.852944 -84.98586)
		(width 0.10795)
		(layer "F.Cu")
		(net "SPI_PCH_IO2")
	)
	(segment
		(start 372.369588 -91.2622)
		(end 372.2116 -91.104212)
		(width 0.10795)
		(layer "F.Cu")
		(net "SPI_PCH_IO2")
	)
	(segment
		(start 376.011186 -84.827618)
		(end 376.011186 -84.604098)
		(width 0.10795)
		(layer "F.Cu")
		(net "SPI_PCH_IO2")
	)
	(segment
		(start 375.0818 -91.420188)
		(end 374.923812 -91.2622)
		(width 0.10795)
		(layer "F.Cu")
		(net "SPI_PCH_IO2")
	)
	(segment
		(start 375.0818 -91.643962)
		(end 375.0818 -91.420188)
		(width 0.10795)
		(layer "F.Cu")
		(net "SPI_PCH_IO2")
	)
	(segment
		(start 372.589552 -89.032588)
		(end 372.74754 -88.8746)
		(width 0.10795)
		(layer "F.Cu")
		(net "SPI_PCH_IO2")
	)
	(segment
		(start 374.92305 -90.72245)
		(end 375.031 -90.6145)
		(width 0.10795)
		(layer "F.Cu")
		(net "SPI_PCH_IO2")
	)
	(segment
		(start 375.852944 -84.98586)
		(end 376.011186 -84.827618)
		(width 0.10795)
		(layer "F.Cu")
		(net "SPI_PCH_IO2")
	)
	(segment
		(start 374.92305 -92.3417)
		(end 373.360188 -92.3417)
		(width 0.10795)
		(layer "F.Cu")
		(net "SPI_PCH_IO2")
	)
	(segment
		(start 375.031 -89.662)
		(end 374.4595 -89.0905)
		(width 0.10795)
		(layer "F.Cu")
		(net "SPI_PCH_IO2")
	)
	(segment
		(start 376.598942 -95.00362)
		(end 376.319796 -94.724474)
		(width 0.0889)
		(layer "F.Cu")
		(net "SPI_PCH_IO2")
	)
	(segment
		(start 372.971314 -88.8746)
		(end 373.129302 -89.032588)
		(width 0.10795)
		(layer "F.Cu")
		(net "SPI_PCH_IO2")
	)
	(segment
		(start 374.015 -88.2015)
		(end 374.4595 -88.2015)
		(width 0.10795)
		(layer "F.Cu")
		(net "SPI_PCH_IO2")
	)
	(segment
		(start 373.28729 -90.72245)
		(end 374.92305 -90.72245)
		(width 0.10795)
		(layer "F.Cu")
		(net "SPI_PCH_IO2")
	)
	(segment
		(start 374.923812 -91.80195)
		(end 375.0818 -91.643962)
		(width 0.10795)
		(layer "F.Cu")
		(net "SPI_PCH_IO2")
	)
	(segment
		(start 376.5677 -84.397088)
		(end 376.5677 -84.7344)
		(width 0.10795)
		(layer "F.Cu")
		(net "SPI_PCH_IO2")
	)
	(segment
		(start 374.65 -88.011)
		(end 374.65 -86.188804)
		(width 0.10795)
		(layer "F.Cu")
		(net "SPI_PCH_IO2")
	)
	(segment
		(start 375.754646 -83.807554)
		(end 375.978166 -83.807554)
		(width 0.10795)
		(layer "F.Cu")
		(net "SPI_PCH_IO2")
	)
	(segment
		(start 375.016522 -84.545678)
		(end 375.189242 -84.545678)
		(width 0.10795)
		(layer "F.Cu")
		(net "SPI_PCH_IO2")
	)
	(segment
		(start 373.129302 -90.564462)
		(end 373.28729 -90.72245)
		(width 0.10795)
		(layer "F.Cu")
		(net "SPI_PCH_IO2")
	)
	(segment
		(start 372.2116 -91.104212)
		(end 372.2116 -90.880438)
		(width 0.10795)
		(layer "F.Cu")
		(net "SPI_PCH_IO2")
	)
	(segment
		(start 373.360188 -92.3417)
		(end 373.2022 -92.183712)
		(width 0.10795)
		(layer "F.Cu")
		(net "SPI_PCH_IO2")
	)
	(segment
		(start 376.011186 -84.604098)
		(end 375.596404 -84.189316)
		(width 0.10795)
		(layer "F.Cu")
		(net "SPI_PCH_IO2")
	)
	(segment
		(start 375.8565 -93.9165)
		(end 375.031 -93.091)
		(width 0.10795)
		(layer "F.Cu")
		(net "SPI_PCH_IO2")
	)
	(segment
		(start 373.2022 -92.183712)
		(end 373.2022 -91.959938)
		(width 0.10795)
		(layer "F.Cu")
		(net "SPI_PCH_IO2")
	)
	(segment
		(start 374.85828 -84.97824)
		(end 374.85828 -84.70392)
		(width 0.10795)
		(layer "F.Cu")
		(net "SPI_PCH_IO2")
	)
	(segment
		(start 375.031 -92.44965)
		(end 374.92305 -92.3417)
		(width 0.10795)
		(layer "F.Cu")
		(net "SPI_PCH_IO2")
	)
	(segment
		(start 376.319796 -94.724474)
		(end 376.003566 -94.724474)
		(width 0.0889)
		(layer "F.Cu")
		(net "SPI_PCH_IO2")
	)
	(segment
		(start 374.4595 -88.2015)
		(end 374.65 -88.011)
		(width 0.10795)
		(layer "F.Cu")
		(net "SPI_PCH_IO2")
	)
	(segment
		(start 373.360188 -91.80195)
		(end 374.923812 -91.80195)
		(width 0.10795)
		(layer "F.Cu")
		(net "SPI_PCH_IO2")
	)
	(segment
		(start 373.129302 -89.032588)
		(end 373.129302 -90.564462)
		(width 0.10795)
		(layer "F.Cu")
		(net "SPI_PCH_IO2")
	)
	(segment
		(start 374.4595 -89.0905)
		(end 374.015 -89.0905)
		(width 0.10795)
		(layer "F.Cu")
		(net "SPI_PCH_IO2")
	)
	(segment
		(start 374.015 -88.2015)
		(end 374.015 -89.0905)
		(width 0.10795)
		(layer "F.Cu")
		(net "SPI_PCH_IO2")
	)
	(segment
		(start 374.85828 -84.70392)
		(end 375.016522 -84.545678)
		(width 0.10795)
		(layer "F.Cu")
		(net "SPI_PCH_IO2")
	)
	(segment
		(start 373.2022 -91.959938)
		(end 373.360188 -91.80195)
		(width 0.10795)
		(layer "F.Cu")
		(net "SPI_PCH_IO2")
	)
	(segment
		(start 374.65 -86.188804)
		(end 375.222262 -85.616542)
		(width 0.10795)
		(layer "F.Cu")
		(net "SPI_PCH_IO2")
	)
	(segment
		(start 375.031 -90.6145)
		(end 375.031 -89.662)
		(width 0.10795)
		(layer "F.Cu")
		(net "SPI_PCH_IO2")
	)
	(segment
		(start 375.189242 -84.545678)
		(end 375.629424 -84.98586)
		(width 0.10795)
		(layer "F.Cu")
		(net "SPI_PCH_IO2")
	)
	(segment
		(start 376.003566 -94.724474)
		(end 375.8565 -94.577408)
		(width 0.0889)
		(layer "F.Cu")
		(net "SPI_PCH_IO2")
	)
	(segment
		(start 375.8565 -94.577408)
		(end 375.8565 -94.171008)
		(width 0.0889)
		(layer "F.Cu")
		(net "SPI_PCH_IO2")
	)
	(segment
		(start 375.222262 -85.616542)
		(end 375.222262 -85.342222)
		(width 0.10795)
		(layer "F.Cu")
		(net "SPI_PCH_IO2")
	)
	(via
		(at 383.492756 -62.79261)
		(size 0.508)
		(drill 0.254)
		(layers "F.Cu" "B.Cu")
		(net "SPI_PCH_IO2")
	)
	(via
		(at 376.5677 -84.7344)
		(size 0.508)
		(drill 0.254)
		(layers "F.Cu" "B.Cu")
		(net "SPI_PCH_IO2")
	)
	(via
		(at 386.64134 -59.48426)
		(size 0.6604)
		(drill 0.3302)
		(layers "F.Cu" "B.Cu")
		(net "SPI_PCH_IO2")
	)
	(segment
		(start 384.036824 -61.787278)
		(end 384.416554 -61.407548)
		(width 0.10795)
		(layer "B.Cu")
		(net "SPI_PCH_IO2")
	)
	(segment
		(start 383.492756 -62.79261)
		(end 384.036824 -62.248542)
		(width 0.10795)
		(layer "B.Cu")
		(net "SPI_PCH_IO2")
	)
	(segment
		(start 385.59613 -60.63107)
		(end 385.7625 -60.4647)
		(width 0.10795)
		(layer "B.Cu")
		(net "SPI_PCH_IO2")
	)
	(segment
		(start 384.671062 -60.910978)
		(end 384.95097 -60.63107)
		(width 0.10795)
		(layer "B.Cu")
		(net "SPI_PCH_IO2")
	)
	(segment
		(start 384.671062 -61.160152)
		(end 384.671062 -60.910978)
		(width 0.10795)
		(layer "B.Cu")
		(net "SPI_PCH_IO2")
	)
	(segment
		(start 384.416554 -61.407548)
		(end 384.423666 -61.407548)
		(width 0.10795)
		(layer "B.Cu")
		(net "SPI_PCH_IO2")
	)
	(segment
		(start 385.7625 -60.198)
		(end 386.47624 -59.48426)
		(width 0.10795)
		(layer "B.Cu")
		(net "SPI_PCH_IO2")
	)
	(segment
		(start 384.036824 -62.248542)
		(end 384.036824 -61.787278)
		(width 0.10795)
		(layer "B.Cu")
		(net "SPI_PCH_IO2")
	)
	(segment
		(start 385.7625 -60.4647)
		(end 385.7625 -60.198)
		(width 0.10795)
		(layer "B.Cu")
		(net "SPI_PCH_IO2")
	)
	(segment
		(start 386.47624 -59.48426)
		(end 386.64134 -59.48426)
		(width 0.10795)
		(layer "B.Cu")
		(net "SPI_PCH_IO2")
	)
	(segment
		(start 384.423666 -61.407548)
		(end 384.671062 -61.160152)
		(width 0.10795)
		(layer "B.Cu")
		(net "SPI_PCH_IO2")
	)
	(segment
		(start 384.95097 -60.63107)
		(end 385.59613 -60.63107)
		(width 0.10795)
		(layer "B.Cu")
		(net "SPI_PCH_IO2")
	)
	(segment
		(start 383.656078 -64.527938)
		(end 383.656078 -65.414906)
		(width 0.089408)
		(layer "In9.Cu")
		(net "SPI_PCH_IO2")
	)
	(segment
		(start 379.76683 -76.774802)
		(end 379.76683 -76.775056)
		(width 0.089408)
		(layer "In9.Cu")
		(net "SPI_PCH_IO2")
	)
	(segment
		(start 383.656078 -65.414906)
		(end 383.6162 -65.454784)
		(width 0.089408)
		(layer "In9.Cu")
		(net "SPI_PCH_IO2")
	)
	(segment
		(start 383.6162 -65.4558)
		(end 383.229104 -65.842896)
		(width 0.089408)
		(layer "In9.Cu")
		(net "SPI_PCH_IO2")
	)
	(segment
		(start 383.492756 -62.79261)
		(end 383.492756 -64.364616)
		(width 0.089408)
		(layer "In9.Cu")
		(net "SPI_PCH_IO2")
	)
	(segment
		(start 382.579372 -69.9008)
		(end 382.197864 -70.282308)
		(width 0.089408)
		(layer "In9.Cu")
		(net "SPI_PCH_IO2")
	)
	(segment
		(start 382.197864 -70.282308)
		(end 382.197864 -71.482712)
		(width 0.089408)
		(layer "In9.Cu")
		(net "SPI_PCH_IO2")
	)
	(segment
		(start 379.521974 -80.35798)
		(end 377.558554 -82.3214)
		(width 0.089408)
		(layer "In9.Cu")
		(net "SPI_PCH_IO2")
	)
	(segment
		(start 381.466598 -73.372472)
		(end 380.623318 -74.215752)
		(width 0.089408)
		(layer "In9.Cu")
		(net "SPI_PCH_IO2")
	)
	(segment
		(start 382.353312 -67.480942)
		(end 382.353312 -69.343778)
		(width 0.089408)
		(layer "In9.Cu")
		(net "SPI_PCH_IO2")
	)
	(segment
		(start 379.72238 -77.472286)
		(end 379.521974 -77.672692)
		(width 0.089408)
		(layer "In9.Cu")
		(net "SPI_PCH_IO2")
	)
	(segment
		(start 383.229104 -65.842896)
		(end 383.229104 -66.60515)
		(width 0.089408)
		(layer "In9.Cu")
		(net "SPI_PCH_IO2")
	)
	(segment
		(start 379.76683 -76.775056)
		(end 379.72238 -76.819506)
		(width 0.089408)
		(layer "In9.Cu")
		(net "SPI_PCH_IO2")
	)
	(segment
		(start 376.239532 -82.687668)
		(end 376.239532 -84.406232)
		(width 0.089408)
		(layer "In9.Cu")
		(net "SPI_PCH_IO2")
	)
	(segment
		(start 382.353312 -69.343778)
		(end 382.579372 -69.569838)
		(width 0.089408)
		(layer "In9.Cu")
		(net "SPI_PCH_IO2")
	)
	(segment
		(start 376.6058 -82.3214)
		(end 376.239532 -82.687668)
		(width 0.089408)
		(layer "In9.Cu")
		(net "SPI_PCH_IO2")
	)
	(segment
		(start 379.521974 -77.672692)
		(end 379.521974 -80.35798)
		(width 0.089408)
		(layer "In9.Cu")
		(net "SPI_PCH_IO2")
	)
	(segment
		(start 379.72238 -76.819506)
		(end 379.72238 -77.472286)
		(width 0.089408)
		(layer "In9.Cu")
		(net "SPI_PCH_IO2")
	)
	(segment
		(start 377.558554 -82.3214)
		(end 376.6058 -82.3214)
		(width 0.089408)
		(layer "In9.Cu")
		(net "SPI_PCH_IO2")
	)
	(segment
		(start 383.6162 -65.454784)
		(end 383.6162 -65.4558)
		(width 0.089408)
		(layer "In9.Cu")
		(net "SPI_PCH_IO2")
	)
	(segment
		(start 381.466598 -72.213978)
		(end 381.466598 -73.372472)
		(width 0.089408)
		(layer "In9.Cu")
		(net "SPI_PCH_IO2")
	)
	(segment
		(start 380.623318 -75.225148)
		(end 380.034546 -75.81392)
		(width 0.089408)
		(layer "In9.Cu")
		(net "SPI_PCH_IO2")
	)
	(segment
		(start 383.492756 -64.364616)
		(end 383.656078 -64.527938)
		(width 0.089408)
		(layer "In9.Cu")
		(net "SPI_PCH_IO2")
	)
	(segment
		(start 383.229104 -66.60515)
		(end 382.353312 -67.480942)
		(width 0.089408)
		(layer "In9.Cu")
		(net "SPI_PCH_IO2")
	)
	(segment
		(start 382.197864 -71.482712)
		(end 381.466598 -72.213978)
		(width 0.089408)
		(layer "In9.Cu")
		(net "SPI_PCH_IO2")
	)
	(segment
		(start 380.623318 -74.215752)
		(end 380.623318 -75.225148)
		(width 0.089408)
		(layer "In9.Cu")
		(net "SPI_PCH_IO2")
	)
	(segment
		(start 376.239532 -84.406232)
		(end 376.5677 -84.7344)
		(width 0.089408)
		(layer "In9.Cu")
		(net "SPI_PCH_IO2")
	)
	(segment
		(start 380.034546 -76.507086)
		(end 379.76683 -76.774802)
		(width 0.089408)
		(layer "In9.Cu")
		(net "SPI_PCH_IO2")
	)
	(segment
		(start 382.579372 -69.569838)
		(end 382.579372 -69.9008)
		(width 0.089408)
		(layer "In9.Cu")
		(net "SPI_PCH_IO2")
	)
	(segment
		(start 380.034546 -75.81392)
		(end 380.034546 -76.507086)
		(width 0.089408)
		(layer "In9.Cu")
		(net "SPI_PCH_IO2")
	)
	(segment
		(start 382.7653 -60.8965)
		(end 383.64668 -60.8965)
		(width 0.10795)
		(layer "B.Cu")
		(net "SPI_PCH_IO2_R1")
	)
	(segment
		(start 383.64668 -60.8965)
		(end 384.34518 -60.198)
		(width 0.10795)
		(layer "B.Cu")
		(net "SPI_PCH_IO2_R1")
	)
	(segment
		(start 384.34518 -60.198)
		(end 384.8735 -60.198)
		(width 0.10795)
		(layer "B.Cu")
		(net "SPI_PCH_IO2_R1")
	)
	(segment
		(start 375.729754 -88.624156)
		(end 375.92 -88.43391)
		(width 0.10795)
		(layer "F.Cu")
		(net "SPI_PCH_CS0_R_N")
	)
	(segment
		(start 377.508262 -92.647262)
		(end 377.444 -92.583)
		(width 0.0889)
		(layer "F.Cu")
		(net "SPI_PCH_CS0_R_N")
	)
	(segment
		(start 375.92 -88.43391)
		(end 375.92 -88.2015)
		(width 0.10795)
		(layer "F.Cu")
		(net "SPI_PCH_CS0_R_N")
	)
	(segment
		(start 377.444 -90.551)
		(end 376.989848 -90.096848)
		(width 0.10795)
		(layer "F.Cu")
		(net "SPI_PCH_CS0_R_N")
	)
	(segment
		(start 377.98502 -94.37497)
		(end 377.508262 -93.898212)
		(width 0.0889)
		(layer "F.Cu")
		(net "SPI_PCH_CS0_R_N")
	)
	(segment
		(start 376.735594 -90.096848)
		(end 375.729754 -89.091008)
		(width 0.10795)
		(layer "F.Cu")
		(net "SPI_PCH_CS0_R_N")
	)
	(segment
		(start 377.444 -92.583)
		(end 377.444 -90.551)
		(width 0.10795)
		(layer "F.Cu")
		(net "SPI_PCH_CS0_R_N")
	)
	(segment
		(start 375.729754 -89.091008)
		(end 375.729754 -88.624156)
		(width 0.10795)
		(layer "F.Cu")
		(net "SPI_PCH_CS0_R_N")
	)
	(segment
		(start 377.508262 -93.898212)
		(end 377.508262 -92.647262)
		(width 0.0889)
		(layer "F.Cu")
		(net "SPI_PCH_CS0_R_N")
	)
	(segment
		(start 376.989848 -90.096848)
		(end 376.735594 -90.096848)
		(width 0.10795)
		(layer "F.Cu")
		(net "SPI_PCH_CS0_R_N")
	)
	(segment
		(start 369.795806 -18.7198)
		(end 369.795806 -19.027394)
		(width 0.10795)
		(layer "F.Cu")
		(net "SPI_BMC_BT_DO")
	)
	(segment
		(start 368.728244 -19.28622)
		(end 368.581686 -19.139662)
		(width 0.10795)
		(layer "F.Cu")
		(net "SPI_BMC_BT_DO")
	)
	(segment
		(start 377.961906 -44.256706)
		(end 377.66752 -43.96232)
		(width 0.10795)
		(layer "F.Cu")
		(net "SPI_BMC_BT_DO")
	)
	(segment
		(start 369.795806 -19.027394)
		(end 369.53698 -19.28622)
		(width 0.10795)
		(layer "F.Cu")
		(net "SPI_BMC_BT_DO")
	)
	(segment
		(start 378.422408 -44.256706)
		(end 377.961906 -44.256706)
		(width 0.10795)
		(layer "F.Cu")
		(net "SPI_BMC_BT_DO")
	)
	(segment
		(start 369.53698 -19.28622)
		(end 368.728244 -19.28622)
		(width 0.10795)
		(layer "F.Cu")
		(net "SPI_BMC_BT_DO")
	)
	(segment
		(start 379.095 -44.929298)
		(end 378.422408 -44.256706)
		(width 0.10795)
		(layer "F.Cu")
		(net "SPI_BMC_BT_DO")
	)
	(segment
		(start 377.66752 -43.96232)
		(end 376.639328 -43.96232)
		(width 0.10795)
		(layer "F.Cu")
		(net "SPI_BMC_BT_DO")
	)
	(segment
		(start 368.581686 -19.139662)
		(end 367.329466 -19.139662)
		(width 0.10795)
		(layer "F.Cu")
		(net "SPI_BMC_BT_DO")
	)
	(via
		(at 405.699976 -11.0998)
		(size 0.6604)
		(drill 0.3302)
		(layers "F.Cu" "B.Cu")
		(net "SPI_BMC_BT_DO")
	)
	(via
		(at 369.795806 -18.7198)
		(size 0.508)
		(drill 0.254)
		(layers "F.Cu" "B.Cu")
		(net "SPI_BMC_BT_DO")
	)
	(via
		(at 421.8432 -46.2026)
		(size 0.508)
		(drill 0.254)
		(layers "F.Cu" "B.Cu")
		(net "SPI_BMC_BT_DO")
	)
	(via
		(at 368.64671 -44.707556)
		(size 0.508)
		(drill 0.254)
		(layers "F.Cu" "B.Cu")
		(net "SPI_BMC_BT_DO")
	)
	(via
		(at 405.8412 -6.1722)
		(size 0.508)
		(drill 0.254)
		(layers "F.Cu" "B.Cu")
		(net "SPI_BMC_BT_DO")
	)
	(via
		(at 379.095 -44.929298)
		(size 0.508)
		(drill 0.254)
		(layers "F.Cu" "B.Cu")
		(net "SPI_BMC_BT_DO")
	)
	(via
		(at 405.3967 -19.1516)
		(size 0.508)
		(drill 0.254)
		(layers "F.Cu" "B.Cu")
		(net "SPI_BMC_BT_DO")
	)
	(segment
		(start 406.071578 -10.728198)
		(end 406.071578 -6.511036)
		(width 0.10795)
		(layer "B.Cu")
		(net "SPI_BMC_BT_DO")
	)
	(segment
		(start 405.699976 -11.0998)
		(end 406.071578 -10.728198)
		(width 0.10795)
		(layer "B.Cu")
		(net "SPI_BMC_BT_DO")
	)
	(segment
		(start 406.071578 -6.511036)
		(end 405.8412 -6.280658)
		(width 0.10795)
		(layer "B.Cu")
		(net "SPI_BMC_BT_DO")
	)
	(segment
		(start 404.101808 -17.504664)
		(end 404.101808 -18.137124)
		(width 0.10795)
		(layer "B.Cu")
		(net "SPI_BMC_BT_DO")
	)
	(segment
		(start 405.699976 -12.206224)
		(end 404.9649 -12.9413)
		(width 0.10795)
		(layer "B.Cu")
		(net "SPI_BMC_BT_DO")
	)
	(segment
		(start 421.812466 -45.536612)
		(end 421.812466 -44.647612)
		(width 0.10795)
		(layer "B.Cu")
		(net "SPI_BMC_BT_DO")
	)
	(segment
		(start 421.812466 -46.171866)
		(end 421.8432 -46.2026)
		(width 0.10795)
		(layer "B.Cu")
		(net "SPI_BMC_BT_DO")
	)
	(segment
		(start 405.699976 -11.0998)
		(end 405.699976 -12.206224)
		(width 0.10795)
		(layer "B.Cu")
		(net "SPI_BMC_BT_DO")
	)
	(segment
		(start 405.3967 -19.1389)
		(end 405.3967 -19.1516)
		(width 0.10795)
		(layer "B.Cu")
		(net "SPI_BMC_BT_DO")
	)
	(segment
		(start 404.9649 -16.641572)
		(end 404.101808 -17.504664)
		(width 0.10795)
		(layer "B.Cu")
		(net "SPI_BMC_BT_DO")
	)
	(segment
		(start 421.812466 -45.536612)
		(end 421.812466 -46.171866)
		(width 0.10795)
		(layer "B.Cu")
		(net "SPI_BMC_BT_DO")
	)
	(segment
		(start 405.8412 -6.280658)
		(end 405.8412 -6.1722)
		(width 0.10795)
		(layer "B.Cu")
		(net "SPI_BMC_BT_DO")
	)
	(segment
		(start 404.9649 -12.9413)
		(end 404.9649 -16.641572)
		(width 0.10795)
		(layer "B.Cu")
		(net "SPI_BMC_BT_DO")
	)
	(segment
		(start 404.101808 -18.137124)
		(end 404.374604 -18.40992)
		(width 0.10795)
		(layer "B.Cu")
		(net "SPI_BMC_BT_DO")
	)
	(segment
		(start 404.374604 -18.40992)
		(end 404.66772 -18.40992)
		(width 0.10795)
		(layer "B.Cu")
		(net "SPI_BMC_BT_DO")
	)
	(segment
		(start 404.66772 -18.40992)
		(end 405.3967 -19.1389)
		(width 0.10795)
		(layer "B.Cu")
		(net "SPI_BMC_BT_DO")
	)
	(segment
		(start 368.650266 -44.704)
		(end 369.43792 -44.704)
		(width 0.089408)
		(layer "In4.Cu")
		(net "SPI_BMC_BT_DO")
	)
	(segment
		(start 377.798838 -45.277024)
		(end 378.747274 -45.277024)
		(width 0.089408)
		(layer "In4.Cu")
		(net "SPI_BMC_BT_DO")
	)
	(segment
		(start 378.747274 -45.277024)
		(end 379.095 -44.929298)
		(width 0.089408)
		(layer "In4.Cu")
		(net "SPI_BMC_BT_DO")
	)
	(segment
		(start 369.43792 -44.704)
		(end 370.605812 -43.536108)
		(width 0.089408)
		(layer "In4.Cu")
		(net "SPI_BMC_BT_DO")
	)
	(segment
		(start 376.2629 -44.2849)
		(end 376.806714 -44.2849)
		(width 0.089408)
		(layer "In4.Cu")
		(net "SPI_BMC_BT_DO")
	)
	(segment
		(start 370.605812 -43.536108)
		(end 375.514108 -43.536108)
		(width 0.089408)
		(layer "In4.Cu")
		(net "SPI_BMC_BT_DO")
	)
	(segment
		(start 376.806714 -44.2849)
		(end 377.798838 -45.277024)
		(width 0.089408)
		(layer "In4.Cu")
		(net "SPI_BMC_BT_DO")
	)
	(segment
		(start 368.64671 -44.707556)
		(end 368.650266 -44.704)
		(width 0.089408)
		(layer "In4.Cu")
		(net "SPI_BMC_BT_DO")
	)
	(segment
		(start 375.514108 -43.536108)
		(end 376.2629 -44.2849)
		(width 0.089408)
		(layer "In4.Cu")
		(net "SPI_BMC_BT_DO")
	)
	(segment
		(start 408.873452 -24.221948)
		(end 408.873452 -20.862798)
		(width 0.089408)
		(layer "In11.Cu")
		(net "SPI_BMC_BT_DO")
	)
	(segment
		(start 419.294056 -43.297856)
		(end 414.368996 -43.297856)
		(width 0.089408)
		(layer "In11.Cu")
		(net "SPI_BMC_BT_DO")
	)
	(segment
		(start 374.3452 -9.304782)
		(end 376.228864 -11.188446)
		(width 0.089408)
		(layer "In11.Cu")
		(net "SPI_BMC_BT_DO")
	)
	(segment
		(start 414.31718 -43.24604)
		(end 411.659324 -43.24604)
		(width 0.089408)
		(layer "In11.Cu")
		(net "SPI_BMC_BT_DO")
	)
	(segment
		(start 406.5397 -20.1676)
		(end 405.892 -19.5199)
		(width 0.089408)
		(layer "In11.Cu")
		(net "SPI_BMC_BT_DO")
	)
	(segment
		(start 367.73612 -29.250894)
		(end 367.73612 -29.008578)
		(width 0.089408)
		(layer "In11.Cu")
		(net "SPI_BMC_BT_DO")
	)
	(segment
		(start 407.3144 -41.17594)
		(end 407.3144 -40.12438)
		(width 0.089408)
		(layer "In11.Cu")
		(net "SPI_BMC_BT_DO")
	)
	(segment
		(start 421.8432 -45.847)
		(end 419.294056 -43.297856)
		(width 0.089408)
		(layer "In11.Cu")
		(net "SPI_BMC_BT_DO")
	)
	(segment
		(start 407.3144 -40.12438)
		(end 407.048208 -39.858188)
		(width 0.089408)
		(layer "In11.Cu")
		(net "SPI_BMC_BT_DO")
	)
	(segment
		(start 407.795222 -27.481022)
		(end 407.795222 -25.300178)
		(width 0.089408)
		(layer "In11.Cu")
		(net "SPI_BMC_BT_DO")
	)
	(segment
		(start 394.449554 -11.188446)
		(end 397.373348 -8.264652)
		(width 0.089408)
		(layer "In11.Cu")
		(net "SPI_BMC_BT_DO")
	)
	(segment
		(start 408.88666 -42.7482)
		(end 407.3144 -41.17594)
		(width 0.089408)
		(layer "In11.Cu")
		(net "SPI_BMC_BT_DO")
	)
	(segment
		(start 367.736374 -29.008324)
		(end 367.736374 -20.779232)
		(width 0.089408)
		(layer "In11.Cu")
		(net "SPI_BMC_BT_DO")
	)
	(segment
		(start 408.934666 -31.359602)
		(end 409.232354 -31.359602)
		(width 0.089408)
		(layer "In11.Cu")
		(net "SPI_BMC_BT_DO")
	)
	(segment
		(start 408.664664 -31.54553)
		(end 408.850338 -31.359856)
		(width 0.089408)
		(layer "In11.Cu")
		(net "SPI_BMC_BT_DO")
	)
	(segment
		(start 405.892 -19.5199)
		(end 405.5872 -19.5199)
		(width 0.089408)
		(layer "In11.Cu")
		(net "SPI_BMC_BT_DO")
	)
	(segment
		(start 405.5872 -19.5199)
		(end 405.3967 -19.3294)
		(width 0.089408)
		(layer "In11.Cu")
		(net "SPI_BMC_BT_DO")
	)
	(segment
		(start 408.870404 -29.713936)
		(end 408.68219 -29.525722)
		(width 0.089408)
		(layer "In11.Cu")
		(net "SPI_BMC_BT_DO")
	)
	(segment
		(start 368.980212 -30.522164)
		(end 367.736374 -29.278326)
		(width 0.089408)
		(layer "In11.Cu")
		(net "SPI_BMC_BT_DO")
	)
	(segment
		(start 405.3967 -19.3294)
		(end 405.3967 -19.1516)
		(width 0.089408)
		(layer "In11.Cu")
		(net "SPI_BMC_BT_DO")
	)
	(segment
		(start 368.1984 -44.2976)
		(end 368.1984 -40.59682)
		(width 0.089408)
		(layer "In11.Cu")
		(net "SPI_BMC_BT_DO")
	)
	(segment
		(start 414.368996 -43.297856)
		(end 414.31718 -43.24604)
		(width 0.089408)
		(layer "In11.Cu")
		(net "SPI_BMC_BT_DO")
	)
	(segment
		(start 373.346218 -9.304782)
		(end 374.3452 -9.304782)
		(width 0.089408)
		(layer "In11.Cu")
		(net "SPI_BMC_BT_DO")
	)
	(segment
		(start 368.608356 -44.707556)
		(end 368.1984 -44.2976)
		(width 0.089408)
		(layer "In11.Cu")
		(net "SPI_BMC_BT_DO")
	)
	(segment
		(start 409.232354 -31.359602)
		(end 409.50388 -31.088076)
		(width 0.089408)
		(layer "In11.Cu")
		(net "SPI_BMC_BT_DO")
	)
	(segment
		(start 408.934412 -31.359856)
		(end 408.934666 -31.359602)
		(width 0.089408)
		(layer "In11.Cu")
		(net "SPI_BMC_BT_DO")
	)
	(segment
		(start 421.8432 -46.2026)
		(end 421.8432 -45.847)
		(width 0.089408)
		(layer "In11.Cu")
		(net "SPI_BMC_BT_DO")
	)
	(segment
		(start 367.736374 -29.278326)
		(end 367.736374 -29.251148)
		(width 0.089408)
		(layer "In11.Cu")
		(net "SPI_BMC_BT_DO")
	)
	(segment
		(start 407.10485 -38.738302)
		(end 407.10485 -38.655498)
		(width 0.089408)
		(layer "In11.Cu")
		(net "SPI_BMC_BT_DO")
	)
	(segment
		(start 408.351228 -32.20339)
		(end 408.445208 -32.10941)
		(width 0.089408)
		(layer "In11.Cu")
		(net "SPI_BMC_BT_DO")
	)
	(segment
		(start 407.105358 -38.65499)
		(end 407.105358 -35.836352)
		(width 0.089408)
		(layer "In11.Cu")
		(net "SPI_BMC_BT_DO")
	)
	(segment
		(start 409.285948 -29.713936)
		(end 408.870404 -29.713936)
		(width 0.089408)
		(layer "In11.Cu")
		(net "SPI_BMC_BT_DO")
	)
	(segment
		(start 408.351228 -32.328866)
		(end 408.351228 -32.20339)
		(width 0.089408)
		(layer "In11.Cu")
		(net "SPI_BMC_BT_DO")
	)
	(segment
		(start 407.105358 -35.836352)
		(end 406.680416 -35.41141)
		(width 0.089408)
		(layer "In11.Cu")
		(net "SPI_BMC_BT_DO")
	)
	(segment
		(start 408.873452 -20.862798)
		(end 408.178254 -20.1676)
		(width 0.089408)
		(layer "In11.Cu")
		(net "SPI_BMC_BT_DO")
	)
	(segment
		(start 407.048208 -39.858188)
		(end 407.048208 -38.794944)
		(width 0.089408)
		(layer "In11.Cu")
		(net "SPI_BMC_BT_DO")
	)
	(segment
		(start 367.736374 -20.779232)
		(end 369.795806 -18.7198)
		(width 0.089408)
		(layer "In11.Cu")
		(net "SPI_BMC_BT_DO")
	)
	(segment
		(start 408.445208 -32.10941)
		(end 408.445462 -32.10941)
		(width 0.089408)
		(layer "In11.Cu")
		(net "SPI_BMC_BT_DO")
	)
	(segment
		(start 397.373348 -8.264652)
		(end 404.274782 -8.264652)
		(width 0.089408)
		(layer "In11.Cu")
		(net "SPI_BMC_BT_DO")
	)
	(segment
		(start 408.664918 -31.579058)
		(end 408.664664 -31.578804)
		(width 0.089408)
		(layer "In11.Cu")
		(net "SPI_BMC_BT_DO")
	)
	(segment
		(start 373.037608 -9.613392)
		(end 373.346218 -9.304782)
		(width 0.089408)
		(layer "In11.Cu")
		(net "SPI_BMC_BT_DO")
	)
	(segment
		(start 406.680416 -33.999678)
		(end 408.351228 -32.328866)
		(width 0.089408)
		(layer "In11.Cu")
		(net "SPI_BMC_BT_DO")
	)
	(segment
		(start 367.73612 -29.008578)
		(end 367.736374 -29.008324)
		(width 0.089408)
		(layer "In11.Cu")
		(net "SPI_BMC_BT_DO")
	)
	(segment
		(start 408.68219 -28.36799)
		(end 407.795222 -27.481022)
		(width 0.089408)
		(layer "In11.Cu")
		(net "SPI_BMC_BT_DO")
	)
	(segment
		(start 407.795222 -25.300178)
		(end 408.873452 -24.221948)
		(width 0.089408)
		(layer "In11.Cu")
		(net "SPI_BMC_BT_DO")
	)
	(segment
		(start 406.680416 -35.41141)
		(end 406.680416 -33.999678)
		(width 0.089408)
		(layer "In11.Cu")
		(net "SPI_BMC_BT_DO")
	)
	(segment
		(start 407.048208 -38.794944)
		(end 407.10485 -38.738302)
		(width 0.089408)
		(layer "In11.Cu")
		(net "SPI_BMC_BT_DO")
	)
	(segment
		(start 368.980212 -34.492946)
		(end 368.980212 -30.522164)
		(width 0.089408)
		(layer "In11.Cu")
		(net "SPI_BMC_BT_DO")
	)
	(segment
		(start 373.037608 -15.477998)
		(end 373.037608 -9.613392)
		(width 0.089408)
		(layer "In11.Cu")
		(net "SPI_BMC_BT_DO")
	)
	(segment
		(start 408.850338 -31.359856)
		(end 408.934412 -31.359856)
		(width 0.089408)
		(layer "In11.Cu")
		(net "SPI_BMC_BT_DO")
	)
	(segment
		(start 411.659324 -43.24604)
		(end 411.605476 -43.299888)
		(width 0.089408)
		(layer "In11.Cu")
		(net "SPI_BMC_BT_DO")
	)
	(segment
		(start 408.178254 -20.1676)
		(end 406.5397 -20.1676)
		(width 0.089408)
		(layer "In11.Cu")
		(net "SPI_BMC_BT_DO")
	)
	(segment
		(start 408.445462 -32.10941)
		(end 408.664918 -31.889954)
		(width 0.089408)
		(layer "In11.Cu")
		(net "SPI_BMC_BT_DO")
	)
	(segment
		(start 407.10485 -38.655498)
		(end 407.105358 -38.65499)
		(width 0.089408)
		(layer "In11.Cu")
		(net "SPI_BMC_BT_DO")
	)
	(segment
		(start 368.64671 -44.707556)
		(end 368.608356 -44.707556)
		(width 0.089408)
		(layer "In11.Cu")
		(net "SPI_BMC_BT_DO")
	)
	(segment
		(start 409.50388 -31.088076)
		(end 409.50388 -29.931868)
		(width 0.089408)
		(layer "In11.Cu")
		(net "SPI_BMC_BT_DO")
	)
	(segment
		(start 405.8412 -6.698234)
		(end 405.8412 -6.1722)
		(width 0.089408)
		(layer "In11.Cu")
		(net "SPI_BMC_BT_DO")
	)
	(segment
		(start 367.736374 -29.251148)
		(end 367.73612 -29.250894)
		(width 0.089408)
		(layer "In11.Cu")
		(net "SPI_BMC_BT_DO")
	)
	(segment
		(start 408.664664 -31.578804)
		(end 408.664664 -31.54553)
		(width 0.089408)
		(layer "In11.Cu")
		(net "SPI_BMC_BT_DO")
	)
	(segment
		(start 409.50388 -29.931868)
		(end 409.285948 -29.713936)
		(width 0.089408)
		(layer "In11.Cu")
		(net "SPI_BMC_BT_DO")
	)
	(segment
		(start 376.228864 -11.188446)
		(end 394.449554 -11.188446)
		(width 0.089408)
		(layer "In11.Cu")
		(net "SPI_BMC_BT_DO")
	)
	(segment
		(start 368.1984 -40.59682)
		(end 369.415822 -39.379398)
		(width 0.089408)
		(layer "In11.Cu")
		(net "SPI_BMC_BT_DO")
	)
	(segment
		(start 369.415822 -39.379398)
		(end 369.415822 -34.928556)
		(width 0.089408)
		(layer "In11.Cu")
		(net "SPI_BMC_BT_DO")
	)
	(segment
		(start 411.605476 -43.299888)
		(end 411.294834 -43.299888)
		(width 0.089408)
		(layer "In11.Cu")
		(net "SPI_BMC_BT_DO")
	)
	(segment
		(start 369.795806 -18.7198)
		(end 373.037608 -15.477998)
		(width 0.089408)
		(layer "In11.Cu")
		(net "SPI_BMC_BT_DO")
	)
	(segment
		(start 411.294834 -43.299888)
		(end 410.743146 -42.7482)
		(width 0.089408)
		(layer "In11.Cu")
		(net "SPI_BMC_BT_DO")
	)
	(segment
		(start 408.664918 -31.889954)
		(end 408.664918 -31.579058)
		(width 0.089408)
		(layer "In11.Cu")
		(net "SPI_BMC_BT_DO")
	)
	(segment
		(start 369.415822 -34.928556)
		(end 368.980212 -34.492946)
		(width 0.089408)
		(layer "In11.Cu")
		(net "SPI_BMC_BT_DO")
	)
	(segment
		(start 408.68219 -29.525722)
		(end 408.68219 -28.36799)
		(width 0.089408)
		(layer "In11.Cu")
		(net "SPI_BMC_BT_DO")
	)
	(segment
		(start 404.274782 -8.264652)
		(end 405.8412 -6.698234)
		(width 0.089408)
		(layer "In11.Cu")
		(net "SPI_BMC_BT_DO")
	)
	(segment
		(start 410.743146 -42.7482)
		(end 408.88666 -42.7482)
		(width 0.089408)
		(layer "In11.Cu")
		(net "SPI_BMC_BT_DO")
	)
	(segment
		(start 419.090094 -40.13454)
		(end 419.490144 -40.53459)
		(width 0.10795)
		(layer "F.Cu")
		(net "SPI_BMC_BT_DI")
	)
	(via
		(at 368.611912 -35.880294)
		(size 0.508)
		(drill 0.254)
		(layers "F.Cu" "B.Cu")
		(net "SPI_BMC_BT_DI")
	)
	(via
		(at 375.097294 -38.79215)
		(size 0.508)
		(drill 0.254)
		(layers "F.Cu" "B.Cu")
		(net "SPI_BMC_BT_DI")
	)
	(via
		(at 419.490144 -40.53459)
		(size 0.4572)
		(drill 0.2032)
		(layers "F.Cu" "B.Cu")
		(net "SPI_BMC_BT_DI")
	)
	(via
		(at 419.987984 -42.620946)
		(size 0.6604)
		(drill 0.3302)
		(layers "F.Cu" "B.Cu")
		(net "SPI_BMC_BT_DI")
	)
	(via
		(at 378.505212 -28.52801)
		(size 0.508)
		(drill 0.254)
		(layers "F.Cu" "B.Cu")
		(net "SPI_BMC_BT_DI")
	)
	(segment
		(start 419.6588 -41.7322)
		(end 419.3286 -41.7322)
		(width 0.10795)
		(layer "B.Cu")
		(net "SPI_BMC_BT_DI")
	)
	(segment
		(start 420.077646 -44.650152)
		(end 420.077646 -44.22775)
		(width 0.10795)
		(layer "B.Cu")
		(net "SPI_BMC_BT_DI")
	)
	(segment
		(start 368.611658 -35.887406)
		(end 368.611658 -35.880294)
		(width 0.10795)
		(layer "B.Cu")
		(net "SPI_BMC_BT_DI")
	)
	(segment
		(start 419.987984 -42.620946)
		(end 419.987984 -42.061384)
		(width 0.10795)
		(layer "B.Cu")
		(net "SPI_BMC_BT_DI")
	)
	(segment
		(start 420.077646 -44.22775)
		(end 419.987984 -44.138088)
		(width 0.10795)
		(layer "B.Cu")
		(net "SPI_BMC_BT_DI")
	)
	(segment
		(start 368.611658 -35.880294)
		(end 368.611912 -35.880294)
		(width 0.10795)
		(layer "B.Cu")
		(net "SPI_BMC_BT_DI")
	)
	(segment
		(start 378.505212 -28.265628)
		(end 377.493022 -27.253438)
		(width 0.10795)
		(layer "B.Cu")
		(net "SPI_BMC_BT_DI")
	)
	(segment
		(start 367.637314 -35.364166)
		(end 368.088418 -35.364166)
		(width 0.10795)
		(layer "B.Cu")
		(net "SPI_BMC_BT_DI")
	)
	(segment
		(start 419.3286 -41.7322)
		(end 419.0873 -41.4909)
		(width 0.10795)
		(layer "B.Cu")
		(net "SPI_BMC_BT_DI")
	)
	(segment
		(start 378.505212 -28.52801)
		(end 378.505212 -28.265628)
		(width 0.10795)
		(layer "B.Cu")
		(net "SPI_BMC_BT_DI")
	)
	(segment
		(start 419.987984 -44.138088)
		(end 419.987984 -42.620946)
		(width 0.10795)
		(layer "B.Cu")
		(net "SPI_BMC_BT_DI")
	)
	(segment
		(start 419.0873 -41.4909)
		(end 419.0873 -40.937434)
		(width 0.10795)
		(layer "B.Cu")
		(net "SPI_BMC_BT_DI")
	)
	(segment
		(start 368.088418 -35.364166)
		(end 368.611658 -35.887406)
		(width 0.10795)
		(layer "B.Cu")
		(net "SPI_BMC_BT_DI")
	)
	(segment
		(start 419.987984 -42.061384)
		(end 419.6588 -41.7322)
		(width 0.10795)
		(layer "B.Cu")
		(net "SPI_BMC_BT_DI")
	)
	(segment
		(start 419.0873 -40.937434)
		(end 419.490144 -40.53459)
		(width 0.10795)
		(layer "B.Cu")
		(net "SPI_BMC_BT_DI")
	)
	(segment
		(start 375.097294 -38.79215)
		(end 375.097294 -37.576506)
		(width 0.089408)
		(layer "In2.Cu")
		(net "SPI_BMC_BT_DI")
	)
	(segment
		(start 377.868688 -28.965398)
		(end 378.306076 -28.52801)
		(width 0.089408)
		(layer "In2.Cu")
		(net "SPI_BMC_BT_DI")
	)
	(segment
		(start 378.306076 -28.52801)
		(end 378.505212 -28.52801)
		(width 0.089408)
		(layer "In2.Cu")
		(net "SPI_BMC_BT_DI")
	)
	(segment
		(start 377.868688 -34.805112)
		(end 377.868688 -28.965398)
		(width 0.089408)
		(layer "In2.Cu")
		(net "SPI_BMC_BT_DI")
	)
	(segment
		(start 375.097294 -37.576506)
		(end 377.868688 -34.805112)
		(width 0.089408)
		(layer "In2.Cu")
		(net "SPI_BMC_BT_DI")
	)
	(segment
		(start 400.667982 -34.95802)
		(end 399.550128 -36.075874)
		(width 0.089408)
		(layer "In4.Cu")
		(net "SPI_BMC_BT_DI")
	)
	(segment
		(start 375.8692 -38.036754)
		(end 375.113804 -38.79215)
		(width 0.089408)
		(layer "In4.Cu")
		(net "SPI_BMC_BT_DI")
	)
	(segment
		(start 375.087388 -38.765734)
		(end 375.087388 -38.689534)
		(width 0.089408)
		(layer "In4.Cu")
		(net "SPI_BMC_BT_DI")
	)
	(segment
		(start 396.882366 -37.178234)
		(end 394.78458 -37.178234)
		(width 0.089408)
		(layer "In4.Cu")
		(net "SPI_BMC_BT_DI")
	)
	(segment
		(start 411.13075 -39.093648)
		(end 411.13075 -38.045136)
		(width 0.089408)
		(layer "In4.Cu")
		(net "SPI_BMC_BT_DI")
	)
	(segment
		(start 394.78458 -37.178234)
		(end 394.19022 -36.583874)
		(width 0.089408)
		(layer "In4.Cu")
		(net "SPI_BMC_BT_DI")
	)
	(segment
		(start 373.344948 -36.947094)
		(end 370.987066 -36.947094)
		(width 0.089408)
		(layer "In4.Cu")
		(net "SPI_BMC_BT_DI")
	)
	(segment
		(start 405.413464 -37.316664)
		(end 404.494492 -37.316664)
		(width 0.089408)
		(layer "In4.Cu")
		(net "SPI_BMC_BT_DI")
	)
	(segment
		(start 419.115494 -40.15994)
		(end 418.54628 -40.15994)
		(width 0.089408)
		(layer "In4.Cu")
		(net "SPI_BMC_BT_DI")
	)
	(segment
		(start 384.597656 -33.417002)
		(end 383.396744 -33.417002)
		(width 0.089408)
		(layer "In4.Cu")
		(net "SPI_BMC_BT_DI")
	)
	(segment
		(start 375.087388 -38.689534)
		(end 374.979692 -38.581838)
		(width 0.089408)
		(layer "In4.Cu")
		(net "SPI_BMC_BT_DI")
	)
	(segment
		(start 385.623054 -34.4424)
		(end 384.597656 -33.417002)
		(width 0.089408)
		(layer "In4.Cu")
		(net "SPI_BMC_BT_DI")
	)
	(segment
		(start 410.845762 -37.760148)
		(end 408.826208 -37.760148)
		(width 0.089408)
		(layer "In4.Cu")
		(net "SPI_BMC_BT_DI")
	)
	(segment
		(start 369.920266 -35.880294)
		(end 368.611912 -35.880294)
		(width 0.089408)
		(layer "In4.Cu")
		(net "SPI_BMC_BT_DI")
	)
	(segment
		(start 375.097294 -38.79215)
		(end 375.113804 -38.79215)
		(width 0.089408)
		(layer "In4.Cu")
		(net "SPI_BMC_BT_DI")
	)
	(segment
		(start 399.550128 -36.075874)
		(end 397.984726 -36.075874)
		(width 0.089408)
		(layer "In4.Cu")
		(net "SPI_BMC_BT_DI")
	)
	(segment
		(start 375.8692 -36.999672)
		(end 375.8692 -38.036754)
		(width 0.089408)
		(layer "In4.Cu")
		(net "SPI_BMC_BT_DI")
	)
	(segment
		(start 393.79398 -36.187634)
		(end 392.730482 -35.124136)
		(width 0.089408)
		(layer "In4.Cu")
		(net "SPI_BMC_BT_DI")
	)
	(segment
		(start 418.54628 -40.15994)
		(end 418.214048 -39.827708)
		(width 0.089408)
		(layer "In4.Cu")
		(net "SPI_BMC_BT_DI")
	)
	(segment
		(start 388.265416 -35.301936)
		(end 387.40588 -34.4424)
		(width 0.089408)
		(layer "In4.Cu")
		(net "SPI_BMC_BT_DI")
	)
	(segment
		(start 374.979692 -38.574472)
		(end 374.314212 -37.908992)
		(width 0.089408)
		(layer "In4.Cu")
		(net "SPI_BMC_BT_DI")
	)
	(segment
		(start 370.987066 -36.947094)
		(end 369.920266 -35.880294)
		(width 0.089408)
		(layer "In4.Cu")
		(net "SPI_BMC_BT_DI")
	)
	(segment
		(start 392.730482 -35.124136)
		(end 389.831834 -35.124136)
		(width 0.089408)
		(layer "In4.Cu")
		(net "SPI_BMC_BT_DI")
	)
	(segment
		(start 408.446478 -37.944298)
		(end 408.35961 -37.944298)
		(width 0.089408)
		(layer "In4.Cu")
		(net "SPI_BMC_BT_DI")
	)
	(segment
		(start 393.79398 -36.192714)
		(end 393.79398 -36.187634)
		(width 0.089408)
		(layer "In4.Cu")
		(net "SPI_BMC_BT_DI")
	)
	(segment
		(start 411.13075 -38.045136)
		(end 410.845762 -37.760148)
		(width 0.089408)
		(layer "In4.Cu")
		(net "SPI_BMC_BT_DI")
	)
	(segment
		(start 374.979692 -38.581838)
		(end 374.979692 -38.574472)
		(width 0.089408)
		(layer "In4.Cu")
		(net "SPI_BMC_BT_DI")
	)
	(segment
		(start 374.314212 -37.908992)
		(end 374.306846 -37.908992)
		(width 0.089408)
		(layer "In4.Cu")
		(net "SPI_BMC_BT_DI")
	)
	(segment
		(start 406.59304 -38.159944)
		(end 406.256744 -38.159944)
		(width 0.089408)
		(layer "In4.Cu")
		(net "SPI_BMC_BT_DI")
	)
	(segment
		(start 408.826208 -37.760148)
		(end 408.642312 -37.944044)
		(width 0.089408)
		(layer "In4.Cu")
		(net "SPI_BMC_BT_DI")
	)
	(segment
		(start 382.494536 -34.31921)
		(end 378.549662 -34.31921)
		(width 0.089408)
		(layer "In4.Cu")
		(net "SPI_BMC_BT_DI")
	)
	(segment
		(start 407.613866 -38.690042)
		(end 407.123138 -38.690042)
		(width 0.089408)
		(layer "In4.Cu")
		(net "SPI_BMC_BT_DI")
	)
	(segment
		(start 374.306846 -37.908992)
		(end 373.344948 -36.947094)
		(width 0.089408)
		(layer "In4.Cu")
		(net "SPI_BMC_BT_DI")
	)
	(segment
		(start 394.19022 -36.583874)
		(end 394.18514 -36.583874)
		(width 0.089408)
		(layer "In4.Cu")
		(net "SPI_BMC_BT_DI")
	)
	(segment
		(start 402.339302 -36.03498)
		(end 401.262342 -34.95802)
		(width 0.089408)
		(layer "In4.Cu")
		(net "SPI_BMC_BT_DI")
	)
	(segment
		(start 407.123138 -38.690042)
		(end 406.59304 -38.159944)
		(width 0.089408)
		(layer "In4.Cu")
		(net "SPI_BMC_BT_DI")
	)
	(segment
		(start 383.396744 -33.417002)
		(end 382.494536 -34.31921)
		(width 0.089408)
		(layer "In4.Cu")
		(net "SPI_BMC_BT_DI")
	)
	(segment
		(start 419.490144 -40.53459)
		(end 419.115494 -40.15994)
		(width 0.089408)
		(layer "In4.Cu")
		(net "SPI_BMC_BT_DI")
	)
	(segment
		(start 387.40588 -34.4424)
		(end 385.623054 -34.4424)
		(width 0.089408)
		(layer "In4.Cu")
		(net "SPI_BMC_BT_DI")
	)
	(segment
		(start 404.494492 -37.316664)
		(end 403.212808 -36.03498)
		(width 0.089408)
		(layer "In4.Cu")
		(net "SPI_BMC_BT_DI")
	)
	(segment
		(start 389.831834 -35.124136)
		(end 389.654034 -35.301936)
		(width 0.089408)
		(layer "In4.Cu")
		(net "SPI_BMC_BT_DI")
	)
	(segment
		(start 408.35961 -37.944298)
		(end 407.613866 -38.690042)
		(width 0.089408)
		(layer "In4.Cu")
		(net "SPI_BMC_BT_DI")
	)
	(segment
		(start 401.262342 -34.95802)
		(end 400.667982 -34.95802)
		(width 0.089408)
		(layer "In4.Cu")
		(net "SPI_BMC_BT_DI")
	)
	(segment
		(start 375.113804 -38.79215)
		(end 375.087388 -38.765734)
		(width 0.089408)
		(layer "In4.Cu")
		(net "SPI_BMC_BT_DI")
	)
	(segment
		(start 408.642312 -37.944044)
		(end 408.446732 -37.944044)
		(width 0.089408)
		(layer "In4.Cu")
		(net "SPI_BMC_BT_DI")
	)
	(segment
		(start 394.18514 -36.583874)
		(end 393.79398 -36.192714)
		(width 0.089408)
		(layer "In4.Cu")
		(net "SPI_BMC_BT_DI")
	)
	(segment
		(start 397.984726 -36.075874)
		(end 396.882366 -37.178234)
		(width 0.089408)
		(layer "In4.Cu")
		(net "SPI_BMC_BT_DI")
	)
	(segment
		(start 411.86481 -39.827708)
		(end 411.13075 -39.093648)
		(width 0.089408)
		(layer "In4.Cu")
		(net "SPI_BMC_BT_DI")
	)
	(segment
		(start 408.446732 -37.944044)
		(end 408.446478 -37.944298)
		(width 0.089408)
		(layer "In4.Cu")
		(net "SPI_BMC_BT_DI")
	)
	(segment
		(start 403.212808 -36.03498)
		(end 402.339302 -36.03498)
		(width 0.089408)
		(layer "In4.Cu")
		(net "SPI_BMC_BT_DI")
	)
	(segment
		(start 418.214048 -39.827708)
		(end 411.86481 -39.827708)
		(width 0.089408)
		(layer "In4.Cu")
		(net "SPI_BMC_BT_DI")
	)
	(segment
		(start 378.549662 -34.31921)
		(end 375.8692 -36.999672)
		(width 0.089408)
		(layer "In4.Cu")
		(net "SPI_BMC_BT_DI")
	)
	(segment
		(start 406.256744 -38.159944)
		(end 405.413464 -37.316664)
		(width 0.089408)
		(layer "In4.Cu")
		(net "SPI_BMC_BT_DI")
	)
	(segment
		(start 389.654034 -35.301936)
		(end 388.265416 -35.301936)
		(width 0.089408)
		(layer "In4.Cu")
		(net "SPI_BMC_BT_DI")
	)
	(segment
		(start 427.072044 -44.040044)
		(end 427.56836 -44.53636)
		(width 0.10795)
		(layer "F.Cu")
		(net "SPI_BMC_BT_CS_N")
	)
	(segment
		(start 367.088928 -37.61232)
		(end 368.187732 -37.61232)
		(width 0.10795)
		(layer "F.Cu")
		(net "SPI_BMC_BT_CS_N")
	)
	(segment
		(start 368.187732 -37.61232)
		(end 368.613182 -37.18687)
		(width 0.10795)
		(layer "F.Cu")
		(net "SPI_BMC_BT_CS_N")
	)
	(segment
		(start 427.56836 -44.53636)
		(end 427.56836 -44.983654)
		(width 0.10795)
		(layer "F.Cu")
		(net "SPI_BMC_BT_CS_N")
	)
	(segment
		(start 426.1104 -43.8658)
		(end 426.284644 -44.040044)
		(width 0.10795)
		(layer "F.Cu")
		(net "SPI_BMC_BT_CS_N")
	)
	(segment
		(start 426.284644 -44.040044)
		(end 427.072044 -44.040044)
		(width 0.10795)
		(layer "F.Cu")
		(net "SPI_BMC_BT_CS_N")
	)
	(via
		(at 426.1104 -43.8658)
		(size 0.508)
		(drill 0.254)
		(layers "F.Cu" "B.Cu")
		(net "SPI_BMC_BT_CS_N")
	)
	(via
		(at 368.613182 -37.18687)
		(size 0.508)
		(drill 0.254)
		(layers "F.Cu" "B.Cu")
		(net "SPI_BMC_BT_CS_N")
	)
	(segment
		(start 368.394234 -36.967922)
		(end 368.613182 -37.18687)
		(width 0.10795)
		(layer "B.Cu")
		(net "SPI_BMC_BT_CS_N")
	)
	(segment
		(start 367.646712 -36.967922)
		(end 368.394234 -36.967922)
		(width 0.10795)
		(layer "B.Cu")
		(net "SPI_BMC_BT_CS_N")
	)
	(segment
		(start 374.687084 -38.813486)
		(end 374.075198 -38.2016)
		(width 0.089408)
		(layer "In4.Cu")
		(net "SPI_BMC_BT_CS_N")
	)
	(segment
		(start 381.141224 -41.561512)
		(end 380.535688 -41.561512)
		(width 0.089408)
		(layer "In4.Cu")
		(net "SPI_BMC_BT_CS_N")
	)
	(segment
		(start 378.339096 -41.472104)
		(end 377.64085 -41.472104)
		(width 0.089408)
		(layer "In4.Cu")
		(net "SPI_BMC_BT_CS_N")
	)
	(segment
		(start 407.072846 -45.142658)
		(end 402.545804 -45.142658)
		(width 0.089408)
		(layer "In4.Cu")
		(net "SPI_BMC_BT_CS_N")
	)
	(segment
		(start 413.13608 -47.27321)
		(end 412.945326 -47.463964)
		(width 0.089408)
		(layer "In4.Cu")
		(net "SPI_BMC_BT_CS_N")
	)
	(segment
		(start 419.199314 -46.179232)
		(end 419.082474 -46.062392)
		(width 0.089408)
		(layer "In4.Cu")
		(net "SPI_BMC_BT_CS_N")
	)
	(segment
		(start 425.89069 -43.8658)
		(end 425.474384 -44.282106)
		(width 0.089408)
		(layer "In4.Cu")
		(net "SPI_BMC_BT_CS_N")
	)
	(segment
		(start 407.85542 -47.320962)
		(end 407.85542 -46.581314)
		(width 0.089408)
		(layer "In4.Cu")
		(net "SPI_BMC_BT_CS_N")
	)
	(segment
		(start 385.284218 -38.142418)
		(end 384.73507 -38.142418)
		(width 0.089408)
		(layer "In4.Cu")
		(net "SPI_BMC_BT_CS_N")
	)
	(segment
		(start 407.848054 -46.573948)
		(end 407.848054 -46.573186)
		(width 0.089408)
		(layer "In4.Cu")
		(net "SPI_BMC_BT_CS_N")
	)
	(segment
		(start 398.817338 -43.253914)
		(end 398.63395 -43.253914)
		(width 0.089408)
		(layer "In4.Cu")
		(net "SPI_BMC_BT_CS_N")
	)
	(segment
		(start 407.586688 -46.31182)
		(end 407.586688 -45.6565)
		(width 0.089408)
		(layer "In4.Cu")
		(net "SPI_BMC_BT_CS_N")
	)
	(segment
		(start 384.73507 -38.142418)
		(end 384.345688 -38.5318)
		(width 0.089408)
		(layer "In4.Cu")
		(net "SPI_BMC_BT_CS_N")
	)
	(segment
		(start 419.082474 -46.062392)
		(end 419.081966 -46.062392)
		(width 0.089408)
		(layer "In4.Cu")
		(net "SPI_BMC_BT_CS_N")
	)
	(segment
		(start 413.136334 -47.27321)
		(end 413.13608 -47.27321)
		(width 0.089408)
		(layer "In4.Cu")
		(net "SPI_BMC_BT_CS_N")
	)
	(segment
		(start 419.081966 -46.062392)
		(end 418.69868 -45.679106)
		(width 0.089408)
		(layer "In4.Cu")
		(net "SPI_BMC_BT_CS_N")
	)
	(segment
		(start 423.314876 -45.063664)
		(end 420.823136 -45.063664)
		(width 0.089408)
		(layer "In4.Cu")
		(net "SPI_BMC_BT_CS_N")
	)
	(segment
		(start 383.2606 -39.2176)
		(end 383.2606 -39.442136)
		(width 0.089408)
		(layer "In4.Cu")
		(net "SPI_BMC_BT_CS_N")
	)
	(segment
		(start 425.474384 -44.282106)
		(end 425.035218 -44.282106)
		(width 0.089408)
		(layer "In4.Cu")
		(net "SPI_BMC_BT_CS_N")
	)
	(segment
		(start 394.335 -41.529)
		(end 393.875006 -41.988994)
		(width 0.089408)
		(layer "In4.Cu")
		(net "SPI_BMC_BT_CS_N")
	)
	(segment
		(start 407.848054 -46.573186)
		(end 407.586688 -46.31182)
		(width 0.089408)
		(layer "In4.Cu")
		(net "SPI_BMC_BT_CS_N")
	)
	(segment
		(start 378.885704 -40.925496)
		(end 378.339096 -41.472104)
		(width 0.089408)
		(layer "In4.Cu")
		(net "SPI_BMC_BT_CS_N")
	)
	(segment
		(start 420.823136 -45.063664)
		(end 419.707568 -46.179232)
		(width 0.089408)
		(layer "In4.Cu")
		(net "SPI_BMC_BT_CS_N")
	)
	(segment
		(start 399.122392 -43.558968)
		(end 398.817338 -43.253914)
		(width 0.089408)
		(layer "In4.Cu")
		(net "SPI_BMC_BT_CS_N")
	)
	(segment
		(start 369.627912 -38.2016)
		(end 368.613182 -37.18687)
		(width 0.089408)
		(layer "In4.Cu")
		(net "SPI_BMC_BT_CS_N")
	)
	(segment
		(start 375.3612 -39.192454)
		(end 374.931432 -39.192454)
		(width 0.089408)
		(layer "In4.Cu")
		(net "SPI_BMC_BT_CS_N")
	)
	(segment
		(start 407.85542 -46.581314)
		(end 407.848054 -46.573948)
		(width 0.089408)
		(layer "In4.Cu")
		(net "SPI_BMC_BT_CS_N")
	)
	(segment
		(start 389.363712 -38.896544)
		(end 386.038344 -38.896544)
		(width 0.089408)
		(layer "In4.Cu")
		(net "SPI_BMC_BT_CS_N")
	)
	(segment
		(start 380.190756 -41.561512)
		(end 380.118112 -41.561512)
		(width 0.089408)
		(layer "In4.Cu")
		(net "SPI_BMC_BT_CS_N")
	)
	(segment
		(start 386.038344 -38.896544)
		(end 385.284218 -38.142418)
		(width 0.089408)
		(layer "In4.Cu")
		(net "SPI_BMC_BT_CS_N")
	)
	(segment
		(start 374.931432 -39.192454)
		(end 374.687084 -38.948106)
		(width 0.089408)
		(layer "In4.Cu")
		(net "SPI_BMC_BT_CS_N")
	)
	(segment
		(start 418.69868 -45.679106)
		(end 414.730438 -45.679106)
		(width 0.089408)
		(layer "In4.Cu")
		(net "SPI_BMC_BT_CS_N")
	)
	(segment
		(start 377.64085 -41.472104)
		(end 375.3612 -39.192454)
		(width 0.089408)
		(layer "In4.Cu")
		(net "SPI_BMC_BT_CS_N")
	)
	(segment
		(start 414.730438 -45.679106)
		(end 413.136334 -47.27321)
		(width 0.089408)
		(layer "In4.Cu")
		(net "SPI_BMC_BT_CS_N")
	)
	(segment
		(start 380.535688 -41.561512)
		(end 380.529084 -41.568116)
		(width 0.089408)
		(layer "In4.Cu")
		(net "SPI_BMC_BT_CS_N")
	)
	(segment
		(start 380.19736 -41.568116)
		(end 380.190756 -41.561512)
		(width 0.089408)
		(layer "In4.Cu")
		(net "SPI_BMC_BT_CS_N")
	)
	(segment
		(start 390.218168 -39.751)
		(end 389.363712 -38.896544)
		(width 0.089408)
		(layer "In4.Cu")
		(net "SPI_BMC_BT_CS_N")
	)
	(segment
		(start 398.301972 -42.921936)
		(end 396.990824 -42.921936)
		(width 0.089408)
		(layer "In4.Cu")
		(net "SPI_BMC_BT_CS_N")
	)
	(segment
		(start 426.1104 -43.8658)
		(end 425.89069 -43.8658)
		(width 0.089408)
		(layer "In4.Cu")
		(net "SPI_BMC_BT_CS_N")
	)
	(segment
		(start 395.597888 -41.529)
		(end 394.335 -41.529)
		(width 0.089408)
		(layer "In4.Cu")
		(net "SPI_BMC_BT_CS_N")
	)
	(segment
		(start 423.533824 -44.844716)
		(end 423.314876 -45.063664)
		(width 0.089408)
		(layer "In4.Cu")
		(net "SPI_BMC_BT_CS_N")
	)
	(segment
		(start 374.687084 -38.948106)
		(end 374.687084 -38.813486)
		(width 0.089408)
		(layer "In4.Cu")
		(net "SPI_BMC_BT_CS_N")
	)
	(segment
		(start 398.63395 -43.253914)
		(end 398.301972 -42.921936)
		(width 0.089408)
		(layer "In4.Cu")
		(net "SPI_BMC_BT_CS_N")
	)
	(segment
		(start 412.945326 -47.464218)
		(end 412.632906 -47.776638)
		(width 0.089408)
		(layer "In4.Cu")
		(net "SPI_BMC_BT_CS_N")
	)
	(segment
		(start 383.9464 -38.5318)
		(end 383.2606 -39.2176)
		(width 0.089408)
		(layer "In4.Cu")
		(net "SPI_BMC_BT_CS_N")
	)
	(segment
		(start 412.945326 -47.463964)
		(end 412.945326 -47.464218)
		(width 0.089408)
		(layer "In4.Cu")
		(net "SPI_BMC_BT_CS_N")
	)
	(segment
		(start 390.218168 -39.95293)
		(end 390.218168 -39.751)
		(width 0.089408)
		(layer "In4.Cu")
		(net "SPI_BMC_BT_CS_N")
	)
	(segment
		(start 396.990824 -42.921936)
		(end 395.597888 -41.529)
		(width 0.089408)
		(layer "In4.Cu")
		(net "SPI_BMC_BT_CS_N")
	)
	(segment
		(start 374.075198 -38.2016)
		(end 369.627912 -38.2016)
		(width 0.089408)
		(layer "In4.Cu")
		(net "SPI_BMC_BT_CS_N")
	)
	(segment
		(start 408.311096 -47.776638)
		(end 407.85542 -47.320962)
		(width 0.089408)
		(layer "In4.Cu")
		(net "SPI_BMC_BT_CS_N")
	)
	(segment
		(start 424.472608 -44.844716)
		(end 423.533824 -44.844716)
		(width 0.089408)
		(layer "In4.Cu")
		(net "SPI_BMC_BT_CS_N")
	)
	(segment
		(start 400.962114 -43.558968)
		(end 399.122392 -43.558968)
		(width 0.089408)
		(layer "In4.Cu")
		(net "SPI_BMC_BT_CS_N")
	)
	(segment
		(start 380.529084 -41.568116)
		(end 380.19736 -41.568116)
		(width 0.089408)
		(layer "In4.Cu")
		(net "SPI_BMC_BT_CS_N")
	)
	(segment
		(start 419.707568 -46.179232)
		(end 419.199314 -46.179232)
		(width 0.089408)
		(layer "In4.Cu")
		(net "SPI_BMC_BT_CS_N")
	)
	(segment
		(start 384.345688 -38.5318)
		(end 383.9464 -38.5318)
		(width 0.089408)
		(layer "In4.Cu")
		(net "SPI_BMC_BT_CS_N")
	)
	(segment
		(start 425.035218 -44.282106)
		(end 424.472608 -44.844716)
		(width 0.089408)
		(layer "In4.Cu")
		(net "SPI_BMC_BT_CS_N")
	)
	(segment
		(start 407.586688 -45.6565)
		(end 407.072846 -45.142658)
		(width 0.089408)
		(layer "In4.Cu")
		(net "SPI_BMC_BT_CS_N")
	)
	(segment
		(start 379.482096 -40.925496)
		(end 378.885704 -40.925496)
		(width 0.089408)
		(layer "In4.Cu")
		(net "SPI_BMC_BT_CS_N")
	)
	(segment
		(start 393.875006 -41.988994)
		(end 392.254232 -41.988994)
		(width 0.089408)
		(layer "In4.Cu")
		(net "SPI_BMC_BT_CS_N")
	)
	(segment
		(start 412.632906 -47.776638)
		(end 408.311096 -47.776638)
		(width 0.089408)
		(layer "In4.Cu")
		(net "SPI_BMC_BT_CS_N")
	)
	(segment
		(start 380.118112 -41.561512)
		(end 379.482096 -40.925496)
		(width 0.089408)
		(layer "In4.Cu")
		(net "SPI_BMC_BT_CS_N")
	)
	(segment
		(start 392.254232 -41.988994)
		(end 390.218168 -39.95293)
		(width 0.089408)
		(layer "In4.Cu")
		(net "SPI_BMC_BT_CS_N")
	)
	(segment
		(start 383.2606 -39.442136)
		(end 381.141224 -41.561512)
		(width 0.089408)
		(layer "In4.Cu")
		(net "SPI_BMC_BT_CS_N")
	)
	(segment
		(start 402.545804 -45.142658)
		(end 400.962114 -43.558968)
		(width 0.089408)
		(layer "In4.Cu")
		(net "SPI_BMC_BT_CS_N")
	)
	(segment
		(start 367.329466 -17.869662)
		(end 368.643408 -17.869662)
		(width 0.10795)
		(layer "F.Cu")
		(net "SPI_BMC_BT_CLK")
	)
	(segment
		(start 369.118134 -18.344388)
		(end 369.118134 -18.7325)
		(width 0.10795)
		(layer "F.Cu")
		(net "SPI_BMC_BT_CLK")
	)
	(segment
		(start 433.0319 -44.2849)
		(end 433.6034 -44.8564)
		(width 0.10795)
		(layer "F.Cu")
		(net "SPI_BMC_BT_CLK")
	)
	(segment
		(start 432.6509 -44.2849)
		(end 433.0319 -44.2849)
		(width 0.10795)
		(layer "F.Cu")
		(net "SPI_BMC_BT_CLK")
	)
	(segment
		(start 378.228352 -44.87672)
		(end 377.872752 -45.23232)
		(width 0.10795)
		(layer "F.Cu")
		(net "SPI_BMC_BT_CLK")
	)
	(segment
		(start 433.6034 -44.8564)
		(end 433.6034 -47.8282)
		(width 0.10795)
		(layer "F.Cu")
		(net "SPI_BMC_BT_CLK")
	)
	(segment
		(start 377.872752 -45.23232)
		(end 376.639328 -45.23232)
		(width 0.10795)
		(layer "F.Cu")
		(net "SPI_BMC_BT_CLK")
	)
	(segment
		(start 368.643408 -17.869662)
		(end 369.118134 -18.344388)
		(width 0.10795)
		(layer "F.Cu")
		(net "SPI_BMC_BT_CLK")
	)
	(segment
		(start 431.7746 -44.2849)
		(end 432.6509 -44.2849)
		(width 0.10795)
		(layer "F.Cu")
		(net "SPI_BMC_BT_CLK")
	)
	(via
		(at 433.6034 -47.8282)
		(size 0.508)
		(drill 0.254)
		(layers "F.Cu" "B.Cu")
		(net "SPI_BMC_BT_CLK")
	)
	(via
		(at 368.435128 -45.306488)
		(size 0.508)
		(drill 0.254)
		(layers "F.Cu" "B.Cu")
		(net "SPI_BMC_BT_CLK")
	)
	(via
		(at 462.2292 -0.5334)
		(size 0.508)
		(drill 0.254)
		(layers "F.Cu" "B.Cu")
		(net "SPI_BMC_BT_CLK")
	)
	(via
		(at 369.118134 -18.7325)
		(size 0.508)
		(drill 0.254)
		(layers "F.Cu" "B.Cu")
		(net "SPI_BMC_BT_CLK")
	)
	(via
		(at 378.228352 -44.87672)
		(size 0.508)
		(drill 0.254)
		(layers "F.Cu" "B.Cu")
		(net "SPI_BMC_BT_CLK")
	)
	(segment
		(start 368.003328 -44.151042)
		(end 368.003328 -45.10024)
		(width 0.089408)
		(layer "In4.Cu")
		(net "SPI_BMC_BT_CLK")
	)
	(segment
		(start 368.493294 -43.661076)
		(end 368.003328 -44.151042)
		(width 0.089408)
		(layer "In4.Cu")
		(net "SPI_BMC_BT_CLK")
	)
	(segment
		(start 369.59413 -43.661076)
		(end 368.493294 -43.661076)
		(width 0.089408)
		(layer "In4.Cu")
		(net "SPI_BMC_BT_CLK")
	)
	(segment
		(start 376.384312 -43.992292)
		(end 375.63552 -43.2435)
		(width 0.089408)
		(layer "In4.Cu")
		(net "SPI_BMC_BT_CLK")
	)
	(segment
		(start 377.812554 -44.87672)
		(end 376.928126 -43.992292)
		(width 0.089408)
		(layer "In4.Cu")
		(net "SPI_BMC_BT_CLK")
	)
	(segment
		(start 368.003328 -45.10024)
		(end 368.209576 -45.306488)
		(width 0.089408)
		(layer "In4.Cu")
		(net "SPI_BMC_BT_CLK")
	)
	(segment
		(start 378.228352 -44.87672)
		(end 377.812554 -44.87672)
		(width 0.089408)
		(layer "In4.Cu")
		(net "SPI_BMC_BT_CLK")
	)
	(segment
		(start 375.63552 -43.2435)
		(end 370.011706 -43.2435)
		(width 0.089408)
		(layer "In4.Cu")
		(net "SPI_BMC_BT_CLK")
	)
	(segment
		(start 368.209576 -45.306488)
		(end 368.435128 -45.306488)
		(width 0.089408)
		(layer "In4.Cu")
		(net "SPI_BMC_BT_CLK")
	)
	(segment
		(start 370.011706 -43.2435)
		(end 369.59413 -43.661076)
		(width 0.089408)
		(layer "In4.Cu")
		(net "SPI_BMC_BT_CLK")
	)
	(segment
		(start 376.928126 -43.992292)
		(end 376.384312 -43.992292)
		(width 0.089408)
		(layer "In4.Cu")
		(net "SPI_BMC_BT_CLK")
	)
	(segment
		(start 448.889882 -43.616372)
		(end 452.422514 -43.616372)
		(width 0.089408)
		(layer "In9.Cu")
		(net "SPI_BMC_BT_CLK")
	)
	(segment
		(start 434.918104 -47.390304)
		(end 437.541162 -47.390304)
		(width 0.089408)
		(layer "In9.Cu")
		(net "SPI_BMC_BT_CLK")
	)
	(segment
		(start 465.73948 -9.687814)
		(end 465.73948 -9.388094)
		(width 0.089408)
		(layer "In9.Cu")
		(net "SPI_BMC_BT_CLK")
	)
	(segment
		(start 461.536034 -32.906208)
		(end 461.770476 -32.671766)
		(width 0.089408)
		(layer "In9.Cu")
		(net "SPI_BMC_BT_CLK")
	)
	(segment
		(start 461.545686 -4.798314)
		(end 462.501488 -3.842512)
		(width 0.089408)
		(layer "In9.Cu")
		(net "SPI_BMC_BT_CLK")
	)
	(segment
		(start 462.501488 -0.805688)
		(end 462.2292 -0.5334)
		(width 0.089408)
		(layer "In9.Cu")
		(net "SPI_BMC_BT_CLK")
	)
	(segment
		(start 461.770476 -32.671766)
		(end 461.770476 -32.340042)
		(width 0.089408)
		(layer "In9.Cu")
		(net "SPI_BMC_BT_CLK")
	)
	(segment
		(start 447.5734 -44.932854)
		(end 448.889882 -43.616372)
		(width 0.089408)
		(layer "In9.Cu")
		(net "SPI_BMC_BT_CLK")
	)
	(segment
		(start 456.484736 -41.636442)
		(end 456.484736 -36.198048)
		(width 0.089408)
		(layer "In9.Cu")
		(net "SPI_BMC_BT_CLK")
	)
	(segment
		(start 461.969866 -20.797266)
		(end 461.969866 -19.465036)
		(width 0.089408)
		(layer "In9.Cu")
		(net "SPI_BMC_BT_CLK")
	)
	(segment
		(start 460.64297 -33.607248)
		(end 461.34401 -32.906208)
		(width 0.089408)
		(layer "In9.Cu")
		(net "SPI_BMC_BT_CLK")
	)
	(segment
		(start 464.185 -18.133314)
		(end 464.185 -17.526)
		(width 0.089408)
		(layer "In9.Cu")
		(net "SPI_BMC_BT_CLK")
	)
	(segment
		(start 452.422514 -43.616372)
		(end 452.743316 -43.29557)
		(width 0.089408)
		(layer "In9.Cu")
		(net "SPI_BMC_BT_CLK")
	)
	(segment
		(start 461.239362 -31.808928)
		(end 460.699866 -31.808928)
		(width 0.089408)
		(layer "In9.Cu")
		(net "SPI_BMC_BT_CLK")
	)
	(segment
		(start 460.642462 -33.928304)
		(end 460.642462 -33.648396)
		(width 0.089408)
		(layer "In9.Cu")
		(net "SPI_BMC_BT_CLK")
	)
	(segment
		(start 460.234284 -31.343346)
		(end 460.234284 -29.85389)
		(width 0.089408)
		(layer "In9.Cu")
		(net "SPI_BMC_BT_CLK")
	)
	(segment
		(start 434.701696 -47.173896)
		(end 434.918104 -47.390304)
		(width 0.089408)
		(layer "In9.Cu")
		(net "SPI_BMC_BT_CLK")
	)
	(segment
		(start 433.6034 -47.719234)
		(end 434.148738 -47.173896)
		(width 0.089408)
		(layer "In9.Cu")
		(net "SPI_BMC_BT_CLK")
	)
	(segment
		(start 462.1784 -27.909774)
		(end 462.1784 -21.0058)
		(width 0.089408)
		(layer "In9.Cu")
		(net "SPI_BMC_BT_CLK")
	)
	(segment
		(start 466.312504 -10.260838)
		(end 465.73948 -9.687814)
		(width 0.089408)
		(layer "In9.Cu")
		(net "SPI_BMC_BT_CLK")
	)
	(segment
		(start 460.699866 -31.808928)
		(end 460.234284 -31.343346)
		(width 0.089408)
		(layer "In9.Cu")
		(net "SPI_BMC_BT_CLK")
	)
	(segment
		(start 461.969866 -19.465036)
		(end 462.410302 -19.0246)
		(width 0.089408)
		(layer "In9.Cu")
		(net "SPI_BMC_BT_CLK")
	)
	(segment
		(start 453.856598 -43.29557)
		(end 454.66 -42.492168)
		(width 0.089408)
		(layer "In9.Cu")
		(net "SPI_BMC_BT_CLK")
	)
	(segment
		(start 461.545686 -5.799074)
		(end 461.545686 -4.798314)
		(width 0.089408)
		(layer "In9.Cu")
		(net "SPI_BMC_BT_CLK")
	)
	(segment
		(start 456.484736 -36.198048)
		(end 457.022454 -35.66033)
		(width 0.089408)
		(layer "In9.Cu")
		(net "SPI_BMC_BT_CLK")
	)
	(segment
		(start 463.700114 -7.953502)
		(end 461.545686 -5.799074)
		(width 0.089408)
		(layer "In9.Cu")
		(net "SPI_BMC_BT_CLK")
	)
	(segment
		(start 446.58026 -46.224952)
		(end 447.5734 -45.231812)
		(width 0.089408)
		(layer "In9.Cu")
		(net "SPI_BMC_BT_CLK")
	)
	(segment
		(start 458.910436 -35.66033)
		(end 460.642462 -33.928304)
		(width 0.089408)
		(layer "In9.Cu")
		(net "SPI_BMC_BT_CLK")
	)
	(segment
		(start 452.743316 -43.29557)
		(end 453.856598 -43.29557)
		(width 0.089408)
		(layer "In9.Cu")
		(net "SPI_BMC_BT_CLK")
	)
	(segment
		(start 437.541162 -47.390304)
		(end 438.706514 -46.224952)
		(width 0.089408)
		(layer "In9.Cu")
		(net "SPI_BMC_BT_CLK")
	)
	(segment
		(start 464.304888 -7.953502)
		(end 463.700114 -7.953502)
		(width 0.089408)
		(layer "In9.Cu")
		(net "SPI_BMC_BT_CLK")
	)
	(segment
		(start 434.148738 -47.173896)
		(end 434.701696 -47.173896)
		(width 0.089408)
		(layer "In9.Cu")
		(net "SPI_BMC_BT_CLK")
	)
	(segment
		(start 457.022454 -35.66033)
		(end 458.910436 -35.66033)
		(width 0.089408)
		(layer "In9.Cu")
		(net "SPI_BMC_BT_CLK")
	)
	(segment
		(start 466.312504 -10.635996)
		(end 466.312504 -10.260838)
		(width 0.089408)
		(layer "In9.Cu")
		(net "SPI_BMC_BT_CLK")
	)
	(segment
		(start 460.642462 -33.648396)
		(end 460.64297 -33.647888)
		(width 0.089408)
		(layer "In9.Cu")
		(net "SPI_BMC_BT_CLK")
	)
	(segment
		(start 460.64297 -33.647888)
		(end 460.64297 -33.607248)
		(width 0.089408)
		(layer "In9.Cu")
		(net "SPI_BMC_BT_CLK")
	)
	(segment
		(start 438.706514 -46.224952)
		(end 446.58026 -46.224952)
		(width 0.089408)
		(layer "In9.Cu")
		(net "SPI_BMC_BT_CLK")
	)
	(segment
		(start 465.729828 -15.981172)
		(end 465.729828 -11.218672)
		(width 0.089408)
		(layer "In9.Cu")
		(net "SPI_BMC_BT_CLK")
	)
	(segment
		(start 460.234284 -29.85389)
		(end 462.1784 -27.909774)
		(width 0.089408)
		(layer "In9.Cu")
		(net "SPI_BMC_BT_CLK")
	)
	(segment
		(start 462.1784 -21.0058)
		(end 461.969866 -20.797266)
		(width 0.089408)
		(layer "In9.Cu")
		(net "SPI_BMC_BT_CLK")
	)
	(segment
		(start 465.729828 -11.218672)
		(end 466.312504 -10.635996)
		(width 0.089408)
		(layer "In9.Cu")
		(net "SPI_BMC_BT_CLK")
	)
	(segment
		(start 462.410302 -19.0246)
		(end 463.293714 -19.0246)
		(width 0.089408)
		(layer "In9.Cu")
		(net "SPI_BMC_BT_CLK")
	)
	(segment
		(start 463.293714 -19.0246)
		(end 464.185 -18.133314)
		(width 0.089408)
		(layer "In9.Cu")
		(net "SPI_BMC_BT_CLK")
	)
	(segment
		(start 465.73948 -9.388094)
		(end 464.304888 -7.953502)
		(width 0.089408)
		(layer "In9.Cu")
		(net "SPI_BMC_BT_CLK")
	)
	(segment
		(start 454.66 -42.492168)
		(end 455.62901 -42.492168)
		(width 0.089408)
		(layer "In9.Cu")
		(net "SPI_BMC_BT_CLK")
	)
	(segment
		(start 461.34401 -32.906208)
		(end 461.536034 -32.906208)
		(width 0.089408)
		(layer "In9.Cu")
		(net "SPI_BMC_BT_CLK")
	)
	(segment
		(start 447.5734 -45.231812)
		(end 447.5734 -44.932854)
		(width 0.089408)
		(layer "In9.Cu")
		(net "SPI_BMC_BT_CLK")
	)
	(segment
		(start 462.501488 -3.842512)
		(end 462.501488 -0.805688)
		(width 0.089408)
		(layer "In9.Cu")
		(net "SPI_BMC_BT_CLK")
	)
	(segment
		(start 461.770476 -32.340042)
		(end 461.239362 -31.808928)
		(width 0.089408)
		(layer "In9.Cu")
		(net "SPI_BMC_BT_CLK")
	)
	(segment
		(start 464.185 -17.526)
		(end 465.729828 -15.981172)
		(width 0.089408)
		(layer "In9.Cu")
		(net "SPI_BMC_BT_CLK")
	)
	(segment
		(start 433.6034 -47.8282)
		(end 433.6034 -47.719234)
		(width 0.089408)
		(layer "In9.Cu")
		(net "SPI_BMC_BT_CLK")
	)
	(segment
		(start 455.62901 -42.492168)
		(end 456.484736 -41.636442)
		(width 0.089408)
		(layer "In9.Cu")
		(net "SPI_BMC_BT_CLK")
	)
	(segment
		(start 447.35115 -3.952748)
		(end 447.350896 -3.953002)
		(width 0.089408)
		(layer "In11.Cu")
		(net "SPI_BMC_BT_CLK")
	)
	(segment
		(start 368.435128 -45.306488)
		(end 367.825782 -44.697142)
		(width 0.089408)
		(layer "In11.Cu")
		(net "SPI_BMC_BT_CLK")
	)
	(segment
		(start 403.62124 -7.959852)
		(end 397.264128 -7.959852)
		(width 0.089408)
		(layer "In11.Cu")
		(net "SPI_BMC_BT_CLK")
	)
	(segment
		(start 425.044108 -4.535424)
		(end 424.586908 -4.992624)
		(width 0.089408)
		(layer "In11.Cu")
		(net "SPI_BMC_BT_CLK")
	)
	(segment
		(start 413.973772 -5.927344)
		(end 407.526744 -5.927344)
		(width 0.089408)
		(layer "In11.Cu")
		(net "SPI_BMC_BT_CLK")
	)
	(segment
		(start 462.2292 -0.8636)
		(end 461.3402 -1.7526)
		(width 0.089408)
		(layer "In11.Cu")
		(net "SPI_BMC_BT_CLK")
	)
	(segment
		(start 460.106268 -1.7526)
		(end 459.674468 -1.3208)
		(width 0.089408)
		(layer "In11.Cu")
		(net "SPI_BMC_BT_CLK")
	)
	(segment
		(start 394.328142 -10.895838)
		(end 376.350276 -10.895838)
		(width 0.089408)
		(layer "In11.Cu")
		(net "SPI_BMC_BT_CLK")
	)
	(segment
		(start 459.674468 -1.3208)
		(end 451.054724 -1.3208)
		(width 0.089408)
		(layer "In11.Cu")
		(net "SPI_BMC_BT_CLK")
	)
	(segment
		(start 424.586908 -4.992624)
		(end 418.187378 -4.992624)
		(width 0.089408)
		(layer "In11.Cu")
		(net "SPI_BMC_BT_CLK")
	)
	(segment
		(start 367.373154 -29.329126)
		(end 367.373154 -20.47748)
		(width 0.089408)
		(layer "In11.Cu")
		(net "SPI_BMC_BT_CLK")
	)
	(segment
		(start 372.744492 -8.839708)
		(end 372.744492 -15.106142)
		(width 0.089408)
		(layer "In11.Cu")
		(net "SPI_BMC_BT_CLK")
	)
	(segment
		(start 368.687604 -34.614358)
		(end 368.687604 -30.643576)
		(width 0.089408)
		(layer "In11.Cu")
		(net "SPI_BMC_BT_CLK")
	)
	(segment
		(start 367.373154 -20.47748)
		(end 369.118134 -18.7325)
		(width 0.089408)
		(layer "In11.Cu")
		(net "SPI_BMC_BT_CLK")
	)
	(segment
		(start 440.335162 -4.535424)
		(end 425.044108 -4.535424)
		(width 0.089408)
		(layer "In11.Cu")
		(net "SPI_BMC_BT_CLK")
	)
	(segment
		(start 416.90544 -6.274562)
		(end 414.32099 -6.274562)
		(width 0.089408)
		(layer "In11.Cu")
		(net "SPI_BMC_BT_CLK")
	)
	(segment
		(start 369.123214 -39.257986)
		(end 369.123214 -35.049968)
		(width 0.089408)
		(layer "In11.Cu")
		(net "SPI_BMC_BT_CLK")
	)
	(segment
		(start 369.123214 -35.049968)
		(end 368.687604 -34.614358)
		(width 0.089408)
		(layer "In11.Cu")
		(net "SPI_BMC_BT_CLK")
	)
	(segment
		(start 414.32099 -6.274562)
		(end 413.973772 -5.927344)
		(width 0.089408)
		(layer "In11.Cu")
		(net "SPI_BMC_BT_CLK")
	)
	(segment
		(start 407.526744 -5.927344)
		(end 407.162 -5.5626)
		(width 0.089408)
		(layer "In11.Cu")
		(net "SPI_BMC_BT_CLK")
	)
	(segment
		(start 372.744492 -15.106142)
		(end 369.118134 -18.7325)
		(width 0.089408)
		(layer "In11.Cu")
		(net "SPI_BMC_BT_CLK")
	)
	(segment
		(start 373.1768 -8.4074)
		(end 372.744492 -8.839708)
		(width 0.089408)
		(layer "In11.Cu")
		(net "SPI_BMC_BT_CLK")
	)
	(segment
		(start 373.7356 -8.4074)
		(end 373.1768 -8.4074)
		(width 0.089408)
		(layer "In11.Cu")
		(net "SPI_BMC_BT_CLK")
	)
	(segment
		(start 367.825782 -44.697142)
		(end 367.825782 -40.555418)
		(width 0.089408)
		(layer "In11.Cu")
		(net "SPI_BMC_BT_CLK")
	)
	(segment
		(start 367.825782 -40.555418)
		(end 369.123214 -39.257986)
		(width 0.089408)
		(layer "In11.Cu")
		(net "SPI_BMC_BT_CLK")
	)
	(segment
		(start 461.3402 -1.7526)
		(end 460.106268 -1.7526)
		(width 0.089408)
		(layer "In11.Cu")
		(net "SPI_BMC_BT_CLK")
	)
	(segment
		(start 397.264128 -7.959852)
		(end 394.328142 -10.895838)
		(width 0.089408)
		(layer "In11.Cu")
		(net "SPI_BMC_BT_CLK")
	)
	(segment
		(start 403.621494 -7.960106)
		(end 403.62124 -7.959852)
		(width 0.089408)
		(layer "In11.Cu")
		(net "SPI_BMC_BT_CLK")
	)
	(segment
		(start 440.917584 -3.953002)
		(end 440.335162 -4.535424)
		(width 0.089408)
		(layer "In11.Cu")
		(net "SPI_BMC_BT_CLK")
	)
	(segment
		(start 368.687604 -30.643576)
		(end 367.373154 -29.329126)
		(width 0.089408)
		(layer "In11.Cu")
		(net "SPI_BMC_BT_CLK")
	)
	(segment
		(start 405.691086 -5.5626)
		(end 405.360886 -5.8928)
		(width 0.089408)
		(layer "In11.Cu")
		(net "SPI_BMC_BT_CLK")
	)
	(segment
		(start 374.340374 -9.012174)
		(end 373.7356 -8.4074)
		(width 0.089408)
		(layer "In11.Cu")
		(net "SPI_BMC_BT_CLK")
	)
	(segment
		(start 374.466612 -9.012174)
		(end 374.340374 -9.012174)
		(width 0.089408)
		(layer "In11.Cu")
		(net "SPI_BMC_BT_CLK")
	)
	(segment
		(start 447.350896 -3.953002)
		(end 440.917584 -3.953002)
		(width 0.089408)
		(layer "In11.Cu")
		(net "SPI_BMC_BT_CLK")
	)
	(segment
		(start 376.350276 -10.895838)
		(end 374.466612 -9.012174)
		(width 0.089408)
		(layer "In11.Cu")
		(net "SPI_BMC_BT_CLK")
	)
	(segment
		(start 448.422776 -3.952748)
		(end 447.35115 -3.952748)
		(width 0.089408)
		(layer "In11.Cu")
		(net "SPI_BMC_BT_CLK")
	)
	(segment
		(start 405.360886 -6.537198)
		(end 403.937978 -7.960106)
		(width 0.089408)
		(layer "In11.Cu")
		(net "SPI_BMC_BT_CLK")
	)
	(segment
		(start 403.937978 -7.960106)
		(end 403.621494 -7.960106)
		(width 0.089408)
		(layer "In11.Cu")
		(net "SPI_BMC_BT_CLK")
	)
	(segment
		(start 418.187378 -4.992624)
		(end 416.90544 -6.274562)
		(width 0.089408)
		(layer "In11.Cu")
		(net "SPI_BMC_BT_CLK")
	)
	(segment
		(start 462.2292 -0.5334)
		(end 462.2292 -0.8636)
		(width 0.089408)
		(layer "In11.Cu")
		(net "SPI_BMC_BT_CLK")
	)
	(segment
		(start 407.162 -5.5626)
		(end 405.691086 -5.5626)
		(width 0.089408)
		(layer "In11.Cu")
		(net "SPI_BMC_BT_CLK")
	)
	(segment
		(start 405.360886 -5.8928)
		(end 405.360886 -6.537198)
		(width 0.089408)
		(layer "In11.Cu")
		(net "SPI_BMC_BT_CLK")
	)
	(segment
		(start 451.054724 -1.3208)
		(end 448.422776 -3.952748)
		(width 0.089408)
		(layer "In11.Cu")
		(net "SPI_BMC_BT_CLK")
	)
	(segment
		(start 421.171116 -25.2476)
		(end 421.1574 -25.2476)
		(width 0.10795)
		(layer "F.Cu")
		(net "SP1_BMC_HOST_UART_TX")
	)
	(segment
		(start 381.3937 -74.6125)
		(end 381.3937 -74.8157)
		(width 0.10795)
		(layer "F.Cu")
		(net "SP1_BMC_HOST_UART_TX")
	)
	(segment
		(start 378.4346 -75.8952)
		(end 378.034296 -75.494896)
		(width 0.10795)
		(layer "F.Cu")
		(net "SP1_BMC_HOST_UART_TX")
	)
	(segment
		(start 420.69004 -25.99436)
		(end 420.69004 -26.534618)
		(width 0.10795)
		(layer "F.Cu")
		(net "SP1_BMC_HOST_UART_TX")
	)
	(segment
		(start 379.239526 -75.9968)
		(end 379.137926 -75.8952)
		(width 0.10795)
		(layer "F.Cu")
		(net "SP1_BMC_HOST_UART_TX")
	)
	(segment
		(start 379.137926 -75.8952)
		(end 378.4346 -75.8952)
		(width 0.10795)
		(layer "F.Cu")
		(net "SP1_BMC_HOST_UART_TX")
	)
	(segment
		(start 381.3937 -74.8157)
		(end 380.2126 -75.9968)
		(width 0.10795)
		(layer "F.Cu")
		(net "SP1_BMC_HOST_UART_TX")
	)
	(segment
		(start 421.1574 -25.2476)
		(end 421.1574 -25.527)
		(width 0.10795)
		(layer "F.Cu")
		(net "SP1_BMC_HOST_UART_TX")
	)
	(segment
		(start 380.2126 -75.9968)
		(end 379.239526 -75.9968)
		(width 0.10795)
		(layer "F.Cu")
		(net "SP1_BMC_HOST_UART_TX")
	)
	(segment
		(start 378.034296 -75.494896)
		(end 377.944888 -75.494896)
		(width 0.10795)
		(layer "F.Cu")
		(net "SP1_BMC_HOST_UART_TX")
	)
	(segment
		(start 421.1574 -25.527)
		(end 420.69004 -25.99436)
		(width 0.10795)
		(layer "F.Cu")
		(net "SP1_BMC_HOST_UART_TX")
	)
	(via
		(at 381.3937 -74.6125)
		(size 0.508)
		(drill 0.254)
		(layers "F.Cu" "B.Cu")
		(net "SP1_BMC_HOST_UART_TX")
	)
	(via
		(at 495.537236 -36.50742)
		(size 0.508)
		(drill 0.254)
		(layers "F.Cu" "B.Cu")
		(net "SP1_BMC_HOST_UART_TX")
	)
	(via
		(at 421.171116 -25.2476)
		(size 0.4572)
		(drill 0.2032)
		(layers "F.Cu" "B.Cu")
		(net "SP1_BMC_HOST_UART_TX")
	)
	(via
		(at 382.071118 -74.90206)
		(size 0.6604)
		(drill 0.3302)
		(layers "F.Cu" "B.Cu")
		(net "SP1_BMC_HOST_UART_TX")
	)
	(via
		(at 487.261408 -22.6822)
		(size 0.508)
		(drill 0.254)
		(layers "F.Cu" "B.Cu")
		(net "SP1_BMC_HOST_UART_TX")
	)
	(segment
		(start 495.586766 -36.45789)
		(end 496.919504 -36.45789)
		(width 0.10795)
		(layer "B.Cu")
		(net "SP1_BMC_HOST_UART_TX")
	)
	(segment
		(start 382.071118 -74.90206)
		(end 381.68326 -74.90206)
		(width 0.10795)
		(layer "B.Cu")
		(net "SP1_BMC_HOST_UART_TX")
	)
	(segment
		(start 381.68326 -74.90206)
		(end 381.3937 -74.6125)
		(width 0.10795)
		(layer "B.Cu")
		(net "SP1_BMC_HOST_UART_TX")
	)
	(segment
		(start 495.537236 -36.50742)
		(end 495.586766 -36.45789)
		(width 0.10795)
		(layer "B.Cu")
		(net "SP1_BMC_HOST_UART_TX")
	)
	(segment
		(start 381 -74.2188)
		(end 379.34011 -74.2188)
		(width 0.089408)
		(layer "In2.Cu")
		(net "SP1_BMC_HOST_UART_TX")
	)
	(segment
		(start 383.233168 -64.05372)
		(end 382.376172 -63.196724)
		(width 0.089408)
		(layer "In2.Cu")
		(net "SP1_BMC_HOST_UART_TX")
	)
	(segment
		(start 400.494754 -29.394912)
		(end 403.74316 -29.394912)
		(width 0.089408)
		(layer "In2.Cu")
		(net "SP1_BMC_HOST_UART_TX")
	)
	(segment
		(start 411.879542 -28.114498)
		(end 412.02483 -27.96921)
		(width 0.089408)
		(layer "In2.Cu")
		(net "SP1_BMC_HOST_UART_TX")
	)
	(segment
		(start 406.715214 -27.496008)
		(end 407.333704 -28.114498)
		(width 0.089408)
		(layer "In2.Cu")
		(net "SP1_BMC_HOST_UART_TX")
	)
	(segment
		(start 433.578508 -20.8534)
		(end 432.59502 -21.836888)
		(width 0.089408)
		(layer "In2.Cu")
		(net "SP1_BMC_HOST_UART_TX")
	)
	(segment
		(start 382.267968 -56.184546)
		(end 382.267968 -51.714908)
		(width 0.089408)
		(layer "In2.Cu")
		(net "SP1_BMC_HOST_UART_TX")
	)
	(segment
		(start 382.457706 -51.52517)
		(end 382.457706 -51.040538)
		(width 0.089408)
		(layer "In2.Cu")
		(net "SP1_BMC_HOST_UART_TX")
	)
	(segment
		(start 421.630348 -25.720548)
		(end 421.1574 -25.2476)
		(width 0.089408)
		(layer "In2.Cu")
		(net "SP1_BMC_HOST_UART_TX")
	)
	(segment
		(start 483.43947 -26.094944)
		(end 480.55657 -23.212044)
		(width 0.089408)
		(layer "In2.Cu")
		(net "SP1_BMC_HOST_UART_TX")
	)
	(segment
		(start 480.55657 -23.212044)
		(end 476.321374 -23.212044)
		(width 0.089408)
		(layer "In2.Cu")
		(net "SP1_BMC_HOST_UART_TX")
	)
	(segment
		(start 392.011408 -31.406592)
		(end 394.476478 -28.941522)
		(width 0.089408)
		(layer "In2.Cu")
		(net "SP1_BMC_HOST_UART_TX")
	)
	(segment
		(start 413.619442 -26.391108)
		(end 418.704776 -26.391108)
		(width 0.089408)
		(layer "In2.Cu")
		(net "SP1_BMC_HOST_UART_TX")
	)
	(segment
		(start 412.04134 -27.96921)
		(end 413.619442 -26.391108)
		(width 0.089408)
		(layer "In2.Cu")
		(net "SP1_BMC_HOST_UART_TX")
	)
	(segment
		(start 419.6588 -25.437084)
		(end 420.967916 -25.437084)
		(width 0.089408)
		(layer "In2.Cu")
		(net "SP1_BMC_HOST_UART_TX")
	)
	(segment
		(start 382.376172 -63.196724)
		(end 382.376172 -61.468)
		(width 0.089408)
		(layer "In2.Cu")
		(net "SP1_BMC_HOST_UART_TX")
	)
	(segment
		(start 394.476478 -28.941522)
		(end 400.041364 -28.941522)
		(width 0.089408)
		(layer "In2.Cu")
		(net "SP1_BMC_HOST_UART_TX")
	)
	(segment
		(start 449.0974 -21.7678)
		(end 448.31 -21.7678)
		(width 0.089408)
		(layer "In2.Cu")
		(net "SP1_BMC_HOST_UART_TX")
	)
	(segment
		(start 405.930608 -27.496008)
		(end 406.715214 -27.496008)
		(width 0.089408)
		(layer "In2.Cu")
		(net "SP1_BMC_HOST_UART_TX")
	)
	(segment
		(start 383.233168 -66.329814)
		(end 383.233168 -64.05372)
		(width 0.089408)
		(layer "In2.Cu")
		(net "SP1_BMC_HOST_UART_TX")
	)
	(segment
		(start 386.779262 -35.149282)
		(end 387.7564 -34.172144)
		(width 0.089408)
		(layer "In2.Cu")
		(net "SP1_BMC_HOST_UART_TX")
	)
	(segment
		(start 430.316894 -22.266402)
		(end 430.014888 -22.266402)
		(width 0.089408)
		(layer "In2.Cu")
		(net "SP1_BMC_HOST_UART_TX")
	)
	(segment
		(start 430.014888 -22.266402)
		(end 430.014634 -22.266656)
		(width 0.089408)
		(layer "In2.Cu")
		(net "SP1_BMC_HOST_UART_TX")
	)
	(segment
		(start 442.91758 -20.964144)
		(end 442.806836 -20.8534)
		(width 0.089408)
		(layer "In2.Cu")
		(net "SP1_BMC_HOST_UART_TX")
	)
	(segment
		(start 380.317248 -69.926454)
		(end 380.319026 -69.924676)
		(width 0.089408)
		(layer "In2.Cu")
		(net "SP1_BMC_HOST_UART_TX")
	)
	(segment
		(start 425.609766 -24.0157)
		(end 424.537378 -24.0157)
		(width 0.089408)
		(layer "In2.Cu")
		(net "SP1_BMC_HOST_UART_TX")
	)
	(segment
		(start 404.241 -28.897072)
		(end 404.241 -28.170378)
		(width 0.089408)
		(layer "In2.Cu")
		(net "SP1_BMC_HOST_UART_TX")
	)
	(segment
		(start 447.22415 -20.68195)
		(end 445.351408 -20.68195)
		(width 0.089408)
		(layer "In2.Cu")
		(net "SP1_BMC_HOST_UART_TX")
	)
	(segment
		(start 381.1016 -68.461382)
		(end 383.233168 -66.329814)
		(width 0.089408)
		(layer "In2.Cu")
		(net "SP1_BMC_HOST_UART_TX")
	)
	(segment
		(start 486.305606 -24.767794)
		(end 484.978456 -26.094944)
		(width 0.089408)
		(layer "In2.Cu")
		(net "SP1_BMC_HOST_UART_TX")
	)
	(segment
		(start 378.792994 -71.162672)
		(end 380.029212 -69.926454)
		(width 0.089408)
		(layer "In2.Cu")
		(net "SP1_BMC_HOST_UART_TX")
	)
	(segment
		(start 387.7564 -34.172144)
		(end 387.7564 -33.393126)
		(width 0.089408)
		(layer "In2.Cu")
		(net "SP1_BMC_HOST_UART_TX")
	)
	(segment
		(start 404.241 -28.170378)
		(end 405.171402 -27.239976)
		(width 0.089408)
		(layer "In2.Cu")
		(net "SP1_BMC_HOST_UART_TX")
	)
	(segment
		(start 420.967916 -25.437084)
		(end 421.1574 -25.2476)
		(width 0.089408)
		(layer "In2.Cu")
		(net "SP1_BMC_HOST_UART_TX")
	)
	(segment
		(start 445.06642 -20.964144)
		(end 442.91758 -20.964144)
		(width 0.089408)
		(layer "In2.Cu")
		(net "SP1_BMC_HOST_UART_TX")
	)
	(segment
		(start 383.90068 -38.950392)
		(end 386.779262 -36.07181)
		(width 0.089408)
		(layer "In2.Cu")
		(net "SP1_BMC_HOST_UART_TX")
	)
	(segment
		(start 430.320196 -22.269704)
		(end 430.316894 -22.266402)
		(width 0.089408)
		(layer "In2.Cu")
		(net "SP1_BMC_HOST_UART_TX")
	)
	(segment
		(start 386.779262 -36.07181)
		(end 386.779262 -35.149282)
		(width 0.089408)
		(layer "In2.Cu")
		(net "SP1_BMC_HOST_UART_TX")
	)
	(segment
		(start 432.59502 -21.836888)
		(end 431.697892 -21.836888)
		(width 0.089408)
		(layer "In2.Cu")
		(net "SP1_BMC_HOST_UART_TX")
	)
	(segment
		(start 442.806836 -20.8534)
		(end 433.578508 -20.8534)
		(width 0.089408)
		(layer "In2.Cu")
		(net "SP1_BMC_HOST_UART_TX")
	)
	(segment
		(start 487.261408 -22.6822)
		(end 486.7148 -22.6822)
		(width 0.089408)
		(layer "In2.Cu")
		(net "SP1_BMC_HOST_UART_TX")
	)
	(segment
		(start 469.94445 -29.254704)
		(end 468.211154 -27.521408)
		(width 0.089408)
		(layer "In2.Cu")
		(net "SP1_BMC_HOST_UART_TX")
	)
	(segment
		(start 383.90068 -40.315642)
		(end 383.90068 -38.950392)
		(width 0.089408)
		(layer "In2.Cu")
		(net "SP1_BMC_HOST_UART_TX")
	)
	(segment
		(start 384.640582 -44.497498)
		(end 384.640582 -41.055544)
		(width 0.089408)
		(layer "In2.Cu")
		(net "SP1_BMC_HOST_UART_TX")
	)
	(segment
		(start 445.329564 -20.701)
		(end 445.06642 -20.964144)
		(width 0.089408)
		(layer "In2.Cu")
		(net "SP1_BMC_HOST_UART_TX")
	)
	(segment
		(start 380.029212 -69.926454)
		(end 380.317248 -69.926454)
		(width 0.089408)
		(layer "In2.Cu")
		(net "SP1_BMC_HOST_UART_TX")
	)
	(segment
		(start 472.328748 -28.818332)
		(end 471.892376 -29.254704)
		(width 0.089408)
		(layer "In2.Cu")
		(net "SP1_BMC_HOST_UART_TX")
	)
	(segment
		(start 379.34011 -74.2188)
		(end 378.792994 -73.671684)
		(width 0.089408)
		(layer "In2.Cu")
		(net "SP1_BMC_HOST_UART_TX")
	)
	(segment
		(start 459.447392 -27.521408)
		(end 455.096372 -23.170388)
		(width 0.089408)
		(layer "In2.Cu")
		(net "SP1_BMC_HOST_UART_TX")
	)
	(segment
		(start 389.285734 -31.863792)
		(end 390.799828 -31.863792)
		(width 0.089408)
		(layer "In2.Cu")
		(net "SP1_BMC_HOST_UART_TX")
	)
	(segment
		(start 390.799828 -31.863792)
		(end 391.257028 -31.406592)
		(width 0.089408)
		(layer "In2.Cu")
		(net "SP1_BMC_HOST_UART_TX")
	)
	(segment
		(start 412.02483 -27.96921)
		(end 412.04134 -27.96921)
		(width 0.089408)
		(layer "In2.Cu")
		(net "SP1_BMC_HOST_UART_TX")
	)
	(segment
		(start 418.704776 -26.391108)
		(end 419.6588 -25.437084)
		(width 0.089408)
		(layer "In2.Cu")
		(net "SP1_BMC_HOST_UART_TX")
	)
	(segment
		(start 380.319026 -69.924676)
		(end 380.59995 -69.924676)
		(width 0.089408)
		(layer "In2.Cu")
		(net "SP1_BMC_HOST_UART_TX")
	)
	(segment
		(start 382.457706 -51.040538)
		(end 382.457198 -51.04003)
		(width 0.089408)
		(layer "In2.Cu")
		(net "SP1_BMC_HOST_UART_TX")
	)
	(segment
		(start 429.109886 -22.266656)
		(end 429.106838 -22.269704)
		(width 0.089408)
		(layer "In2.Cu")
		(net "SP1_BMC_HOST_UART_TX")
	)
	(segment
		(start 382.457198 -51.04003)
		(end 382.457198 -46.680882)
		(width 0.089408)
		(layer "In2.Cu")
		(net "SP1_BMC_HOST_UART_TX")
	)
	(segment
		(start 476.321374 -23.212044)
		(end 472.328748 -27.20467)
		(width 0.089408)
		(layer "In2.Cu")
		(net "SP1_BMC_HOST_UART_TX")
	)
	(segment
		(start 448.31 -21.7678)
		(end 447.22415 -20.68195)
		(width 0.089408)
		(layer "In2.Cu")
		(net "SP1_BMC_HOST_UART_TX")
	)
	(segment
		(start 472.328748 -27.20467)
		(end 472.328748 -28.818332)
		(width 0.089408)
		(layer "In2.Cu")
		(net "SP1_BMC_HOST_UART_TX")
	)
	(segment
		(start 422.832784 -25.720548)
		(end 421.630348 -25.720548)
		(width 0.089408)
		(layer "In2.Cu")
		(net "SP1_BMC_HOST_UART_TX")
	)
	(segment
		(start 405.171402 -27.239976)
		(end 405.674576 -27.239976)
		(width 0.089408)
		(layer "In2.Cu")
		(net "SP1_BMC_HOST_UART_TX")
	)
	(segment
		(start 384.640582 -41.055544)
		(end 383.90068 -40.315642)
		(width 0.089408)
		(layer "In2.Cu")
		(net "SP1_BMC_HOST_UART_TX")
	)
	(segment
		(start 382.536954 -61.307218)
		(end 382.536954 -56.453532)
		(width 0.089408)
		(layer "In2.Cu")
		(net "SP1_BMC_HOST_UART_TX")
	)
	(segment
		(start 431.697892 -21.836888)
		(end 431.265076 -22.269704)
		(width 0.089408)
		(layer "In2.Cu")
		(net "SP1_BMC_HOST_UART_TX")
	)
	(segment
		(start 382.536954 -56.453532)
		(end 382.267968 -56.184546)
		(width 0.089408)
		(layer "In2.Cu")
		(net "SP1_BMC_HOST_UART_TX")
	)
	(segment
		(start 381.3937 -74.6125)
		(end 381 -74.2188)
		(width 0.089408)
		(layer "In2.Cu")
		(net "SP1_BMC_HOST_UART_TX")
	)
	(segment
		(start 445.351408 -20.68195)
		(end 445.332358 -20.701)
		(width 0.089408)
		(layer "In2.Cu")
		(net "SP1_BMC_HOST_UART_TX")
	)
	(segment
		(start 431.265076 -22.269704)
		(end 430.320196 -22.269704)
		(width 0.089408)
		(layer "In2.Cu")
		(net "SP1_BMC_HOST_UART_TX")
	)
	(segment
		(start 421.1574 -25.2476)
		(end 421.171116 -25.2476)
		(width 0.089408)
		(layer "In2.Cu")
		(net "SP1_BMC_HOST_UART_TX")
	)
	(segment
		(start 471.892376 -29.254704)
		(end 469.94445 -29.254704)
		(width 0.089408)
		(layer "In2.Cu")
		(net "SP1_BMC_HOST_UART_TX")
	)
	(segment
		(start 400.041364 -28.941522)
		(end 400.494754 -29.394912)
		(width 0.089408)
		(layer "In2.Cu")
		(net "SP1_BMC_HOST_UART_TX")
	)
	(segment
		(start 382.267968 -51.714908)
		(end 382.457706 -51.52517)
		(width 0.089408)
		(layer "In2.Cu")
		(net "SP1_BMC_HOST_UART_TX")
	)
	(segment
		(start 382.376172 -61.468)
		(end 382.536954 -61.307218)
		(width 0.089408)
		(layer "In2.Cu")
		(net "SP1_BMC_HOST_UART_TX")
	)
	(segment
		(start 381.1016 -69.423026)
		(end 381.1016 -68.461382)
		(width 0.089408)
		(layer "In2.Cu")
		(net "SP1_BMC_HOST_UART_TX")
	)
	(segment
		(start 427.355762 -22.269704)
		(end 425.609766 -24.0157)
		(width 0.089408)
		(layer "In2.Cu")
		(net "SP1_BMC_HOST_UART_TX")
	)
	(segment
		(start 424.537378 -24.0157)
		(end 423.292016 -25.261316)
		(width 0.089408)
		(layer "In2.Cu")
		(net "SP1_BMC_HOST_UART_TX")
	)
	(segment
		(start 450.499988 -23.170388)
		(end 449.0974 -21.7678)
		(width 0.089408)
		(layer "In2.Cu")
		(net "SP1_BMC_HOST_UART_TX")
	)
	(segment
		(start 407.333704 -28.114498)
		(end 411.879542 -28.114498)
		(width 0.089408)
		(layer "In2.Cu")
		(net "SP1_BMC_HOST_UART_TX")
	)
	(segment
		(start 445.332358 -20.701)
		(end 445.329564 -20.701)
		(width 0.089408)
		(layer "In2.Cu")
		(net "SP1_BMC_HOST_UART_TX")
	)
	(segment
		(start 486.7148 -22.6822)
		(end 486.305606 -23.091394)
		(width 0.089408)
		(layer "In2.Cu")
		(net "SP1_BMC_HOST_UART_TX")
	)
	(segment
		(start 423.292016 -25.261316)
		(end 422.832784 -25.720548)
		(width 0.089408)
		(layer "In2.Cu")
		(net "SP1_BMC_HOST_UART_TX")
	)
	(segment
		(start 455.096372 -23.170388)
		(end 450.499988 -23.170388)
		(width 0.089408)
		(layer "In2.Cu")
		(net "SP1_BMC_HOST_UART_TX")
	)
	(segment
		(start 486.305606 -23.091394)
		(end 486.305606 -24.767794)
		(width 0.089408)
		(layer "In2.Cu")
		(net "SP1_BMC_HOST_UART_TX")
	)
	(segment
		(start 380.59995 -69.924676)
		(end 381.1016 -69.423026)
		(width 0.089408)
		(layer "In2.Cu")
		(net "SP1_BMC_HOST_UART_TX")
	)
	(segment
		(start 430.014634 -22.266656)
		(end 429.109886 -22.266656)
		(width 0.089408)
		(layer "In2.Cu")
		(net "SP1_BMC_HOST_UART_TX")
	)
	(segment
		(start 387.7564 -33.393126)
		(end 389.285734 -31.863792)
		(width 0.089408)
		(layer "In2.Cu")
		(net "SP1_BMC_HOST_UART_TX")
	)
	(segment
		(start 484.978456 -26.094944)
		(end 483.43947 -26.094944)
		(width 0.089408)
		(layer "In2.Cu")
		(net "SP1_BMC_HOST_UART_TX")
	)
	(segment
		(start 378.792994 -73.671684)
		(end 378.792994 -71.162672)
		(width 0.089408)
		(layer "In2.Cu")
		(net "SP1_BMC_HOST_UART_TX")
	)
	(segment
		(start 429.106838 -22.269704)
		(end 427.355762 -22.269704)
		(width 0.089408)
		(layer "In2.Cu")
		(net "SP1_BMC_HOST_UART_TX")
	)
	(segment
		(start 405.674576 -27.239976)
		(end 405.930608 -27.496008)
		(width 0.089408)
		(layer "In2.Cu")
		(net "SP1_BMC_HOST_UART_TX")
	)
	(segment
		(start 391.257028 -31.406592)
		(end 392.011408 -31.406592)
		(width 0.089408)
		(layer "In2.Cu")
		(net "SP1_BMC_HOST_UART_TX")
	)
	(segment
		(start 468.211154 -27.521408)
		(end 459.447392 -27.521408)
		(width 0.089408)
		(layer "In2.Cu")
		(net "SP1_BMC_HOST_UART_TX")
	)
	(segment
		(start 403.74316 -29.394912)
		(end 404.241 -28.897072)
		(width 0.089408)
		(layer "In2.Cu")
		(net "SP1_BMC_HOST_UART_TX")
	)
	(segment
		(start 382.457198 -46.680882)
		(end 384.640582 -44.497498)
		(width 0.089408)
		(layer "In2.Cu")
		(net "SP1_BMC_HOST_UART_TX")
	)
	(segment
		(start 487.261408 -22.6822)
		(end 487.261408 -23.228808)
		(width 0.089408)
		(layer "In4.Cu")
		(net "SP1_BMC_HOST_UART_TX")
	)
	(segment
		(start 492.31169 -30.032452)
		(end 492.31169 -32.41421)
		(width 0.089408)
		(layer "In4.Cu")
		(net "SP1_BMC_HOST_UART_TX")
	)
	(segment
		(start 492.31169 -32.41421)
		(end 495.3 -35.40252)
		(width 0.089408)
		(layer "In4.Cu")
		(net "SP1_BMC_HOST_UART_TX")
	)
	(segment
		(start 487.261408 -23.228808)
		(end 487.84891 -23.81631)
		(width 0.089408)
		(layer "In4.Cu")
		(net "SP1_BMC_HOST_UART_TX")
	)
	(segment
		(start 487.84891 -25.569672)
		(end 492.31169 -30.032452)
		(width 0.089408)
		(layer "In4.Cu")
		(net "SP1_BMC_HOST_UART_TX")
	)
	(segment
		(start 495.3 -36.208462)
		(end 495.537236 -36.445698)
		(width 0.089408)
		(layer "In4.Cu")
		(net "SP1_BMC_HOST_UART_TX")
	)
	(segment
		(start 487.84891 -23.81631)
		(end 487.84891 -25.569672)
		(width 0.089408)
		(layer "In4.Cu")
		(net "SP1_BMC_HOST_UART_TX")
	)
	(segment
		(start 495.537236 -36.445698)
		(end 495.537236 -36.50742)
		(width 0.089408)
		(layer "In4.Cu")
		(net "SP1_BMC_HOST_UART_TX")
	)
	(segment
		(start 495.3 -35.40252)
		(end 495.3 -36.208462)
		(width 0.089408)
		(layer "In4.Cu")
		(net "SP1_BMC_HOST_UART_TX")
	)
	(segment
		(start 421.979598 -25.899872)
		(end 421.504872 -26.374598)
		(width 0.10795)
		(layer "F.Cu")
		(net "SP1_BMC_HOST_UART_RX")
	)
	(segment
		(start 422.373298 -24.976328)
		(end 422.373298 -25.505918)
		(width 0.10795)
		(layer "F.Cu")
		(net "SP1_BMC_HOST_UART_RX")
	)
	(segment
		(start 424.359832 -23.167086)
		(end 424.359832 -23.538688)
		(width 0.10795)
		(layer "F.Cu")
		(net "SP1_BMC_HOST_UART_RX")
	)
	(segment
		(start 377.544838 -75.894692)
		(end 377.145042 -75.494896)
		(width 0.10795)
		(layer "F.Cu")
		(net "SP1_BMC_HOST_UART_RX")
	)
	(segment
		(start 421.504872 -26.374598)
		(end 421.504618 -26.374598)
		(width 0.10795)
		(layer "F.Cu")
		(net "SP1_BMC_HOST_UART_RX")
	)
	(segment
		(start 421.504618 -26.374598)
		(end 421.49014 -26.389076)
		(width 0.10795)
		(layer "F.Cu")
		(net "SP1_BMC_HOST_UART_RX")
	)
	(segment
		(start 423.544746 -22.352)
		(end 424.359832 -23.167086)
		(width 0.10795)
		(layer "F.Cu")
		(net "SP1_BMC_HOST_UART_RX")
	)
	(segment
		(start 423.418 -22.352)
		(end 423.544746 -22.352)
		(width 0.10795)
		(layer "F.Cu")
		(net "SP1_BMC_HOST_UART_RX")
	)
	(segment
		(start 423.162222 -24.736298)
		(end 422.613328 -24.736298)
		(width 0.10795)
		(layer "F.Cu")
		(net "SP1_BMC_HOST_UART_RX")
	)
	(segment
		(start 422.373298 -25.505918)
		(end 421.979598 -25.899618)
		(width 0.10795)
		(layer "F.Cu")
		(net "SP1_BMC_HOST_UART_RX")
	)
	(segment
		(start 424.359832 -23.538688)
		(end 423.162222 -24.736298)
		(width 0.10795)
		(layer "F.Cu")
		(net "SP1_BMC_HOST_UART_RX")
	)
	(segment
		(start 421.49014 -26.389076)
		(end 421.49014 -26.534618)
		(width 0.10795)
		(layer "F.Cu")
		(net "SP1_BMC_HOST_UART_RX")
	)
	(segment
		(start 421.979598 -25.899618)
		(end 421.979598 -25.899872)
		(width 0.10795)
		(layer "F.Cu")
		(net "SP1_BMC_HOST_UART_RX")
	)
	(segment
		(start 422.613328 -24.736298)
		(end 422.373298 -24.976328)
		(width 0.10795)
		(layer "F.Cu")
		(net "SP1_BMC_HOST_UART_RX")
	)
	(via
		(at 385.667504 -28.320746)
		(size 0.508)
		(drill 0.254)
		(layers "F.Cu" "B.Cu")
		(net "SP1_BMC_HOST_UART_RX")
	)
	(via
		(at 423.418 -22.352)
		(size 0.508)
		(drill 0.254)
		(layers "F.Cu" "B.Cu")
		(net "SP1_BMC_HOST_UART_RX")
	)
	(via
		(at 487.22534 -24.410162)
		(size 0.508)
		(drill 0.254)
		(layers "F.Cu" "B.Cu")
		(net "SP1_BMC_HOST_UART_RX")
	)
	(via
		(at 377.544838 -75.894692)
		(size 0.4572)
		(drill 0.2032)
		(layers "F.Cu" "B.Cu")
		(net "SP1_BMC_HOST_UART_RX")
	)
	(via
		(at 492.0234 -37.3126)
		(size 0.762)
		(drill 0.3048)
		(layers "F.Cu" "B.Cu")
		(net "SP1_BMC_HOST_UART_RX")
	)
	(segment
		(start 491.9218 -37.3126)
		(end 492.0234 -37.3126)
		(width 0.10795)
		(layer "B.Cu")
		(net "SP1_BMC_HOST_UART_RX")
	)
	(segment
		(start 490.203998 -36.444936)
		(end 491.054136 -36.444936)
		(width 0.10795)
		(layer "B.Cu")
		(net "SP1_BMC_HOST_UART_RX")
	)
	(segment
		(start 492.2266 -37.3126)
		(end 492.9886 -38.0746)
		(width 0.10795)
		(layer "B.Cu")
		(net "SP1_BMC_HOST_UART_RX")
	)
	(segment
		(start 491.054136 -36.444936)
		(end 491.9218 -37.3126)
		(width 0.10795)
		(layer "B.Cu")
		(net "SP1_BMC_HOST_UART_RX")
	)
	(segment
		(start 492.0234 -37.3126)
		(end 492.2266 -37.3126)
		(width 0.10795)
		(layer "B.Cu")
		(net "SP1_BMC_HOST_UART_RX")
	)
	(segment
		(start 433.478178 -20.127976)
		(end 443.022228 -20.127976)
		(width 0.089408)
		(layer "In2.Cu")
		(net "SP1_BMC_HOST_UART_RX")
	)
	(segment
		(start 427.502066 -21.024088)
		(end 427.670976 -20.855178)
		(width 0.089408)
		(layer "In2.Cu")
		(net "SP1_BMC_HOST_UART_RX")
	)
	(segment
		(start 469.205056 -27.440636)
		(end 470.16162 -28.3972)
		(width 0.089408)
		(layer "In2.Cu")
		(net "SP1_BMC_HOST_UART_RX")
	)
	(segment
		(start 487.7308 -22.225)
		(end 488.1118 -22.606)
		(width 0.089408)
		(layer "In2.Cu")
		(net "SP1_BMC_HOST_UART_RX")
	)
	(segment
		(start 462.318608 -23.991062)
		(end 463.879946 -25.5524)
		(width 0.089408)
		(layer "In2.Cu")
		(net "SP1_BMC_HOST_UART_RX")
	)
	(segment
		(start 480.64547 -22.958806)
		(end 482.898704 -25.21204)
		(width 0.089408)
		(layer "In2.Cu")
		(net "SP1_BMC_HOST_UART_RX")
	)
	(segment
		(start 476.232474 -22.958806)
		(end 480.64547 -22.958806)
		(width 0.089408)
		(layer "In2.Cu")
		(net "SP1_BMC_HOST_UART_RX")
	)
	(segment
		(start 427.670976 -20.855178)
		(end 432.550316 -20.855178)
		(width 0.089408)
		(layer "In2.Cu")
		(net "SP1_BMC_HOST_UART_RX")
	)
	(segment
		(start 485.519222 -25.21204)
		(end 486.013252 -24.71801)
		(width 0.089408)
		(layer "In2.Cu")
		(net "SP1_BMC_HOST_UART_RX")
	)
	(segment
		(start 432.550316 -20.855178)
		(end 433.277772 -20.127722)
		(width 0.089408)
		(layer "In2.Cu")
		(net "SP1_BMC_HOST_UART_RX")
	)
	(segment
		(start 433.277772 -20.127722)
		(end 433.477924 -20.127722)
		(width 0.089408)
		(layer "In2.Cu")
		(net "SP1_BMC_HOST_UART_RX")
	)
	(segment
		(start 472.0844 -27.10688)
		(end 476.232474 -22.958806)
		(width 0.089408)
		(layer "In2.Cu")
		(net "SP1_BMC_HOST_UART_RX")
	)
	(segment
		(start 448.59067 -20.333208)
		(end 454.016872 -20.333208)
		(width 0.089408)
		(layer "In2.Cu")
		(net "SP1_BMC_HOST_UART_RX")
	)
	(segment
		(start 445.66078 -19.423126)
		(end 445.980566 -19.742912)
		(width 0.089408)
		(layer "In2.Cu")
		(net "SP1_BMC_HOST_UART_RX")
	)
	(segment
		(start 433.477924 -20.127722)
		(end 433.478178 -20.127976)
		(width 0.089408)
		(layer "In2.Cu")
		(net "SP1_BMC_HOST_UART_RX")
	)
	(segment
		(start 466.25637 -25.371298)
		(end 467.714838 -26.829766)
		(width 0.089408)
		(layer "In2.Cu")
		(net "SP1_BMC_HOST_UART_RX")
	)
	(segment
		(start 456.740768 -23.057104)
		(end 457.595986 -23.057104)
		(width 0.089408)
		(layer "In2.Cu")
		(net "SP1_BMC_HOST_UART_RX")
	)
	(segment
		(start 423.418 -22.352)
		(end 424.100498 -21.669502)
		(width 0.089408)
		(layer "In2.Cu")
		(net "SP1_BMC_HOST_UART_RX")
	)
	(segment
		(start 467.91499 -26.829766)
		(end 467.915244 -26.829512)
		(width 0.089408)
		(layer "In2.Cu")
		(net "SP1_BMC_HOST_UART_RX")
	)
	(segment
		(start 462.318608 -22.721062)
		(end 462.318608 -23.991062)
		(width 0.089408)
		(layer "In2.Cu")
		(net "SP1_BMC_HOST_UART_RX")
	)
	(segment
		(start 463.879946 -25.5524)
		(end 464.659218 -25.5524)
		(width 0.089408)
		(layer "In2.Cu")
		(net "SP1_BMC_HOST_UART_RX")
	)
	(segment
		(start 486.6386 -22.225)
		(end 487.7308 -22.225)
		(width 0.089408)
		(layer "In2.Cu")
		(net "SP1_BMC_HOST_UART_RX")
	)
	(segment
		(start 482.898704 -25.21204)
		(end 485.519222 -25.21204)
		(width 0.089408)
		(layer "In2.Cu")
		(net "SP1_BMC_HOST_UART_RX")
	)
	(segment
		(start 471.8812 -28.3972)
		(end 472.0844 -28.194)
		(width 0.089408)
		(layer "In2.Cu")
		(net "SP1_BMC_HOST_UART_RX")
	)
	(segment
		(start 488.1118 -22.606)
		(end 488.1118 -23.523702)
		(width 0.089408)
		(layer "In2.Cu")
		(net "SP1_BMC_HOST_UART_RX")
	)
	(segment
		(start 424.100498 -21.669502)
		(end 426.701458 -21.669502)
		(width 0.089408)
		(layer "In2.Cu")
		(net "SP1_BMC_HOST_UART_RX")
	)
	(segment
		(start 426.701458 -21.669502)
		(end 427.346872 -21.024088)
		(width 0.089408)
		(layer "In2.Cu")
		(net "SP1_BMC_HOST_UART_RX")
	)
	(segment
		(start 454.016872 -20.333208)
		(end 456.740768 -23.057104)
		(width 0.089408)
		(layer "In2.Cu")
		(net "SP1_BMC_HOST_UART_RX")
	)
	(segment
		(start 464.659218 -25.5524)
		(end 464.84032 -25.371298)
		(width 0.089408)
		(layer "In2.Cu")
		(net "SP1_BMC_HOST_UART_RX")
	)
	(segment
		(start 488.1118 -23.523702)
		(end 487.22534 -24.410162)
		(width 0.089408)
		(layer "In2.Cu")
		(net "SP1_BMC_HOST_UART_RX")
	)
	(segment
		(start 427.346872 -21.024088)
		(end 427.502066 -21.024088)
		(width 0.089408)
		(layer "In2.Cu")
		(net "SP1_BMC_HOST_UART_RX")
	)
	(segment
		(start 448.000374 -19.742912)
		(end 448.59067 -20.333208)
		(width 0.089408)
		(layer "In2.Cu")
		(net "SP1_BMC_HOST_UART_RX")
	)
	(segment
		(start 486.013252 -24.71801)
		(end 486.013252 -22.850348)
		(width 0.089408)
		(layer "In2.Cu")
		(net "SP1_BMC_HOST_UART_RX")
	)
	(segment
		(start 464.84032 -25.371298)
		(end 466.25637 -25.371298)
		(width 0.089408)
		(layer "In2.Cu")
		(net "SP1_BMC_HOST_UART_RX")
	)
	(segment
		(start 472.0844 -28.194)
		(end 472.0844 -27.10688)
		(width 0.089408)
		(layer "In2.Cu")
		(net "SP1_BMC_HOST_UART_RX")
	)
	(segment
		(start 443.727078 -19.423126)
		(end 445.66078 -19.423126)
		(width 0.089408)
		(layer "In2.Cu")
		(net "SP1_BMC_HOST_UART_RX")
	)
	(segment
		(start 457.595986 -23.057104)
		(end 459.03642 -21.61667)
		(width 0.089408)
		(layer "In2.Cu")
		(net "SP1_BMC_HOST_UART_RX")
	)
	(segment
		(start 461.214216 -21.61667)
		(end 462.318608 -22.721062)
		(width 0.089408)
		(layer "In2.Cu")
		(net "SP1_BMC_HOST_UART_RX")
	)
	(segment
		(start 467.915244 -26.829512)
		(end 468.60714 -26.829512)
		(width 0.089408)
		(layer "In2.Cu")
		(net "SP1_BMC_HOST_UART_RX")
	)
	(segment
		(start 443.022228 -20.127976)
		(end 443.727078 -19.423126)
		(width 0.089408)
		(layer "In2.Cu")
		(net "SP1_BMC_HOST_UART_RX")
	)
	(segment
		(start 459.03642 -21.61667)
		(end 461.214216 -21.61667)
		(width 0.089408)
		(layer "In2.Cu")
		(net "SP1_BMC_HOST_UART_RX")
	)
	(segment
		(start 470.16162 -28.3972)
		(end 471.8812 -28.3972)
		(width 0.089408)
		(layer "In2.Cu")
		(net "SP1_BMC_HOST_UART_RX")
	)
	(segment
		(start 467.714838 -26.829766)
		(end 467.91499 -26.829766)
		(width 0.089408)
		(layer "In2.Cu")
		(net "SP1_BMC_HOST_UART_RX")
	)
	(segment
		(start 468.60714 -26.829512)
		(end 469.205056 -27.427428)
		(width 0.089408)
		(layer "In2.Cu")
		(net "SP1_BMC_HOST_UART_RX")
	)
	(segment
		(start 445.980566 -19.742912)
		(end 448.000374 -19.742912)
		(width 0.089408)
		(layer "In2.Cu")
		(net "SP1_BMC_HOST_UART_RX")
	)
	(segment
		(start 486.013252 -22.850348)
		(end 486.6386 -22.225)
		(width 0.089408)
		(layer "In2.Cu")
		(net "SP1_BMC_HOST_UART_RX")
	)
	(segment
		(start 469.205056 -27.427428)
		(end 469.205056 -27.440636)
		(width 0.089408)
		(layer "In2.Cu")
		(net "SP1_BMC_HOST_UART_RX")
	)
	(segment
		(start 421.572944 -21.265896)
		(end 422.131744 -21.824696)
		(width 0.089408)
		(layer "In4.Cu")
		(net "SP1_BMC_HOST_UART_RX")
	)
	(segment
		(start 385.51739 -25.2349)
		(end 386.192268 -25.2349)
		(width 0.089408)
		(layer "In4.Cu")
		(net "SP1_BMC_HOST_UART_RX")
	)
	(segment
		(start 409.718256 -23.081742)
		(end 412.782258 -23.081742)
		(width 0.089408)
		(layer "In4.Cu")
		(net "SP1_BMC_HOST_UART_RX")
	)
	(segment
		(start 397.940022 -25.646126)
		(end 400.664172 -25.646126)
		(width 0.089408)
		(layer "In4.Cu")
		(net "SP1_BMC_HOST_UART_RX")
	)
	(segment
		(start 416.655758 -21.844254)
		(end 417.084002 -21.844254)
		(width 0.089408)
		(layer "In4.Cu")
		(net "SP1_BMC_HOST_UART_RX")
	)
	(segment
		(start 392.732514 -27.04973)
		(end 394.11783 -27.04973)
		(width 0.089408)
		(layer "In4.Cu")
		(net "SP1_BMC_HOST_UART_RX")
	)
	(segment
		(start 487.601006 -24.785828)
		(end 487.22534 -24.410162)
		(width 0.089408)
		(layer "In4.Cu")
		(net "SP1_BMC_HOST_UART_RX")
	)
	(segment
		(start 385.282948 -25.469342)
		(end 385.51739 -25.2349)
		(width 0.089408)
		(layer "In4.Cu")
		(net "SP1_BMC_HOST_UART_RX")
	)
	(segment
		(start 386.192268 -25.2349)
		(end 386.637784 -25.680416)
		(width 0.089408)
		(layer "In4.Cu")
		(net "SP1_BMC_HOST_UART_RX")
	)
	(segment
		(start 392.15314 -26.470356)
		(end 392.732514 -27.04973)
		(width 0.089408)
		(layer "In4.Cu")
		(net "SP1_BMC_HOST_UART_RX")
	)
	(segment
		(start 407.02611 -24.555704)
		(end 407.55316 -24.555704)
		(width 0.089408)
		(layer "In4.Cu")
		(net "SP1_BMC_HOST_UART_RX")
	)
	(segment
		(start 385.667504 -28.320746)
		(end 385.667504 -27.641804)
		(width 0.089408)
		(layer "In4.Cu")
		(net "SP1_BMC_HOST_UART_RX")
	)
	(segment
		(start 400.664172 -25.646126)
		(end 401.129246 -26.1112)
		(width 0.089408)
		(layer "In4.Cu")
		(net "SP1_BMC_HOST_UART_RX")
	)
	(segment
		(start 388.6708 -25.680416)
		(end 389.46074 -26.470356)
		(width 0.089408)
		(layer "In4.Cu")
		(net "SP1_BMC_HOST_UART_RX")
	)
	(segment
		(start 408.202638 -24.435054)
		(end 408.364944 -24.435054)
		(width 0.089408)
		(layer "In4.Cu")
		(net "SP1_BMC_HOST_UART_RX")
	)
	(segment
		(start 422.890696 -21.824696)
		(end 423.418 -22.352)
		(width 0.089408)
		(layer "In4.Cu")
		(net "SP1_BMC_HOST_UART_RX")
	)
	(segment
		(start 385.667504 -27.641804)
		(end 385.282948 -27.257248)
		(width 0.089408)
		(layer "In4.Cu")
		(net "SP1_BMC_HOST_UART_RX")
	)
	(segment
		(start 417.084002 -21.844254)
		(end 417.66236 -21.265896)
		(width 0.089408)
		(layer "In4.Cu")
		(net "SP1_BMC_HOST_UART_RX")
	)
	(segment
		(start 401.129246 -26.1112)
		(end 405.470614 -26.1112)
		(width 0.089408)
		(layer "In4.Cu")
		(net "SP1_BMC_HOST_UART_RX")
	)
	(segment
		(start 409.706064 -23.093934)
		(end 409.718256 -23.081742)
		(width 0.089408)
		(layer "In4.Cu")
		(net "SP1_BMC_HOST_UART_RX")
	)
	(segment
		(start 417.66236 -21.265896)
		(end 421.572944 -21.265896)
		(width 0.089408)
		(layer "In4.Cu")
		(net "SP1_BMC_HOST_UART_RX")
	)
	(segment
		(start 385.282948 -27.257248)
		(end 385.282948 -25.469342)
		(width 0.089408)
		(layer "In4.Cu")
		(net "SP1_BMC_HOST_UART_RX")
	)
	(segment
		(start 492.252 -33.001204)
		(end 492.033306 -32.78251)
		(width 0.089408)
		(layer "In4.Cu")
		(net "SP1_BMC_HOST_UART_RX")
	)
	(segment
		(start 397.271748 -26.3144)
		(end 397.940022 -25.646126)
		(width 0.089408)
		(layer "In4.Cu")
		(net "SP1_BMC_HOST_UART_RX")
	)
	(segment
		(start 492.033306 -30.104842)
		(end 487.601006 -25.672542)
		(width 0.089408)
		(layer "In4.Cu")
		(net "SP1_BMC_HOST_UART_RX")
	)
	(segment
		(start 409.492704 -23.303738)
		(end 409.702508 -23.093934)
		(width 0.089408)
		(layer "In4.Cu")
		(net "SP1_BMC_HOST_UART_RX")
	)
	(segment
		(start 492.033306 -32.78251)
		(end 492.033306 -30.104842)
		(width 0.089408)
		(layer "In4.Cu")
		(net "SP1_BMC_HOST_UART_RX")
	)
	(segment
		(start 407.673556 -24.435308)
		(end 408.202384 -24.435308)
		(width 0.089408)
		(layer "In4.Cu")
		(net "SP1_BMC_HOST_UART_RX")
	)
	(segment
		(start 394.11783 -27.04973)
		(end 394.85316 -26.3144)
		(width 0.089408)
		(layer "In4.Cu")
		(net "SP1_BMC_HOST_UART_RX")
	)
	(segment
		(start 394.85316 -26.3144)
		(end 397.271748 -26.3144)
		(width 0.089408)
		(layer "In4.Cu")
		(net "SP1_BMC_HOST_UART_RX")
	)
	(segment
		(start 409.702508 -23.093934)
		(end 409.706064 -23.093934)
		(width 0.089408)
		(layer "In4.Cu")
		(net "SP1_BMC_HOST_UART_RX")
	)
	(segment
		(start 408.364944 -24.435054)
		(end 409.492704 -23.307294)
		(width 0.089408)
		(layer "In4.Cu")
		(net "SP1_BMC_HOST_UART_RX")
	)
	(segment
		(start 492.0234 -37.3126)
		(end 492.252 -37.084)
		(width 0.089408)
		(layer "In4.Cu")
		(net "SP1_BMC_HOST_UART_RX")
	)
	(segment
		(start 389.46074 -26.470356)
		(end 392.15314 -26.470356)
		(width 0.089408)
		(layer "In4.Cu")
		(net "SP1_BMC_HOST_UART_RX")
	)
	(segment
		(start 492.252 -37.084)
		(end 492.252 -33.001204)
		(width 0.089408)
		(layer "In4.Cu")
		(net "SP1_BMC_HOST_UART_RX")
	)
	(segment
		(start 412.782258 -23.081742)
		(end 414.02 -21.844)
		(width 0.089408)
		(layer "In4.Cu")
		(net "SP1_BMC_HOST_UART_RX")
	)
	(segment
		(start 407.55316 -24.555704)
		(end 407.673556 -24.435308)
		(width 0.089408)
		(layer "In4.Cu")
		(net "SP1_BMC_HOST_UART_RX")
	)
	(segment
		(start 416.655504 -21.844)
		(end 416.655758 -21.844254)
		(width 0.089408)
		(layer "In4.Cu")
		(net "SP1_BMC_HOST_UART_RX")
	)
	(segment
		(start 386.637784 -25.680416)
		(end 388.6708 -25.680416)
		(width 0.089408)
		(layer "In4.Cu")
		(net "SP1_BMC_HOST_UART_RX")
	)
	(segment
		(start 405.470614 -26.1112)
		(end 407.02611 -24.555704)
		(width 0.089408)
		(layer "In4.Cu")
		(net "SP1_BMC_HOST_UART_RX")
	)
	(segment
		(start 408.202384 -24.435308)
		(end 408.202638 -24.435054)
		(width 0.089408)
		(layer "In4.Cu")
		(net "SP1_BMC_HOST_UART_RX")
	)
	(segment
		(start 487.601006 -25.672542)
		(end 487.601006 -24.785828)
		(width 0.089408)
		(layer "In4.Cu")
		(net "SP1_BMC_HOST_UART_RX")
	)
	(segment
		(start 409.492704 -23.307294)
		(end 409.492704 -23.303738)
		(width 0.089408)
		(layer "In4.Cu")
		(net "SP1_BMC_HOST_UART_RX")
	)
	(segment
		(start 414.02 -21.844)
		(end 416.655504 -21.844)
		(width 0.089408)
		(layer "In4.Cu")
		(net "SP1_BMC_HOST_UART_RX")
	)
	(segment
		(start 422.131744 -21.824696)
		(end 422.890696 -21.824696)
		(width 0.089408)
		(layer "In4.Cu")
		(net "SP1_BMC_HOST_UART_RX")
	)
	(segment
		(start 383.217166 -46.419262)
		(end 382.864614 -46.771814)
		(width 0.089408)
		(layer "In9.Cu")
		(net "SP1_BMC_HOST_UART_RX")
	)
	(segment
		(start 383.338324 -38.480238)
		(end 383.210816 -38.607746)
		(width 0.089408)
		(layer "In9.Cu")
		(net "SP1_BMC_HOST_UART_RX")
	)
	(segment
		(start 385.336288 -28.651962)
		(end 385.336288 -32.163512)
		(width 0.089408)
		(layer "In9.Cu")
		(net "SP1_BMC_HOST_UART_RX")
	)
	(segment
		(start 379.74905 -69.8754)
		(end 379.41885 -70.2056)
		(width 0.089408)
		(layer "In9.Cu")
		(net "SP1_BMC_HOST_UART_RX")
	)
	(segment
		(start 377.171458 -72.540622)
		(end 377.171458 -73.92924)
		(width 0.089408)
		(layer "In9.Cu")
		(net "SP1_BMC_HOST_UART_RX")
	)
	(segment
		(start 383.217166 -41.024048)
		(end 383.217166 -46.419262)
		(width 0.089408)
		(layer "In9.Cu")
		(net "SP1_BMC_HOST_UART_RX")
	)
	(segment
		(start 382.930146 -59.468512)
		(end 382.163066 -60.235592)
		(width 0.089408)
		(layer "In9.Cu")
		(net "SP1_BMC_HOST_UART_RX")
	)
	(segment
		(start 383.547366 -35.044634)
		(end 382.944624 -35.647376)
		(width 0.089408)
		(layer "In9.Cu")
		(net "SP1_BMC_HOST_UART_RX")
	)
	(segment
		(start 377.971304 -72.133714)
		(end 377.78309 -72.321928)
		(width 0.089408)
		(layer "In9.Cu")
		(net "SP1_BMC_HOST_UART_RX")
	)
	(segment
		(start 385.667504 -28.320746)
		(end 385.336288 -28.651962)
		(width 0.089408)
		(layer "In9.Cu")
		(net "SP1_BMC_HOST_UART_RX")
	)
	(segment
		(start 383.210816 -38.607746)
		(end 383.210816 -41.017698)
		(width 0.089408)
		(layer "In9.Cu")
		(net "SP1_BMC_HOST_UART_RX")
	)
	(segment
		(start 382.864614 -54.436518)
		(end 383.3876 -54.959504)
		(width 0.089408)
		(layer "In9.Cu")
		(net "SP1_BMC_HOST_UART_RX")
	)
	(segment
		(start 384.250184 -33.249616)
		(end 383.94513 -33.249616)
		(width 0.089408)
		(layer "In9.Cu")
		(net "SP1_BMC_HOST_UART_RX")
	)
	(segment
		(start 380.606808 -65.77965)
		(end 380.606808 -68.241926)
		(width 0.089408)
		(layer "In9.Cu")
		(net "SP1_BMC_HOST_UART_RX")
	)
	(segment
		(start 379.41885 -70.2056)
		(end 378.6886 -70.2056)
		(width 0.089408)
		(layer "In9.Cu")
		(net "SP1_BMC_HOST_UART_RX")
	)
	(segment
		(start 381.244602 -65.141856)
		(end 380.606808 -65.77965)
		(width 0.089408)
		(layer "In9.Cu")
		(net "SP1_BMC_HOST_UART_RX")
	)
	(segment
		(start 377.171458 -73.92924)
		(end 377.918218 -74.676)
		(width 0.089408)
		(layer "In9.Cu")
		(net "SP1_BMC_HOST_UART_RX")
	)
	(segment
		(start 383.3876 -55.66791)
		(end 382.930146 -56.124856)
		(width 0.089408)
		(layer "In9.Cu")
		(net "SP1_BMC_HOST_UART_RX")
	)
	(segment
		(start 381.244602 -64.633602)
		(end 381.244602 -65.141856)
		(width 0.089408)
		(layer "In9.Cu")
		(net "SP1_BMC_HOST_UART_RX")
	)
	(segment
		(start 382.163066 -61.57849)
		(end 380.465584 -63.275972)
		(width 0.089408)
		(layer "In9.Cu")
		(net "SP1_BMC_HOST_UART_RX")
	)
	(segment
		(start 383.94513 -33.249616)
		(end 383.547366 -33.64738)
		(width 0.089408)
		(layer "In9.Cu")
		(net "SP1_BMC_HOST_UART_RX")
	)
	(segment
		(start 377.78309 -72.321928)
		(end 377.390152 -72.321928)
		(width 0.089408)
		(layer "In9.Cu")
		(net "SP1_BMC_HOST_UART_RX")
	)
	(segment
		(start 382.944624 -35.647376)
		(end 382.944624 -36.490148)
		(width 0.089408)
		(layer "In9.Cu")
		(net "SP1_BMC_HOST_UART_RX")
	)
	(segment
		(start 380.606808 -68.241926)
		(end 379.74905 -69.099684)
		(width 0.089408)
		(layer "In9.Cu")
		(net "SP1_BMC_HOST_UART_RX")
	)
	(segment
		(start 382.944624 -36.490148)
		(end 383.338324 -36.883848)
		(width 0.089408)
		(layer "In9.Cu")
		(net "SP1_BMC_HOST_UART_RX")
	)
	(segment
		(start 378.6886 -70.2056)
		(end 377.971304 -70.922896)
		(width 0.089408)
		(layer "In9.Cu")
		(net "SP1_BMC_HOST_UART_RX")
	)
	(segment
		(start 383.338324 -36.883848)
		(end 383.338324 -38.480238)
		(width 0.089408)
		(layer "In9.Cu")
		(net "SP1_BMC_HOST_UART_RX")
	)
	(segment
		(start 377.390152 -72.321928)
		(end 377.171458 -72.540622)
		(width 0.089408)
		(layer "In9.Cu")
		(net "SP1_BMC_HOST_UART_RX")
	)
	(segment
		(start 377.918218 -74.676)
		(end 377.918218 -75.521312)
		(width 0.089408)
		(layer "In9.Cu")
		(net "SP1_BMC_HOST_UART_RX")
	)
	(segment
		(start 383.3876 -54.959504)
		(end 383.3876 -55.66791)
		(width 0.089408)
		(layer "In9.Cu")
		(net "SP1_BMC_HOST_UART_RX")
	)
	(segment
		(start 382.163066 -60.235592)
		(end 382.163066 -61.57849)
		(width 0.089408)
		(layer "In9.Cu")
		(net "SP1_BMC_HOST_UART_RX")
	)
	(segment
		(start 379.74905 -69.099684)
		(end 379.74905 -69.8754)
		(width 0.089408)
		(layer "In9.Cu")
		(net "SP1_BMC_HOST_UART_RX")
	)
	(segment
		(start 382.930146 -56.124856)
		(end 382.930146 -59.468512)
		(width 0.089408)
		(layer "In9.Cu")
		(net "SP1_BMC_HOST_UART_RX")
	)
	(segment
		(start 382.864614 -46.771814)
		(end 382.864614 -54.436518)
		(width 0.089408)
		(layer "In9.Cu")
		(net "SP1_BMC_HOST_UART_RX")
	)
	(segment
		(start 380.465584 -63.854584)
		(end 381.244602 -64.633602)
		(width 0.089408)
		(layer "In9.Cu")
		(net "SP1_BMC_HOST_UART_RX")
	)
	(segment
		(start 377.971304 -70.922896)
		(end 377.971304 -72.133714)
		(width 0.089408)
		(layer "In9.Cu")
		(net "SP1_BMC_HOST_UART_RX")
	)
	(segment
		(start 383.210816 -41.017698)
		(end 383.217166 -41.024048)
		(width 0.089408)
		(layer "In9.Cu")
		(net "SP1_BMC_HOST_UART_RX")
	)
	(segment
		(start 385.336288 -32.163512)
		(end 384.250184 -33.249616)
		(width 0.089408)
		(layer "In9.Cu")
		(net "SP1_BMC_HOST_UART_RX")
	)
	(segment
		(start 377.918218 -75.521312)
		(end 377.544838 -75.894692)
		(width 0.089408)
		(layer "In9.Cu")
		(net "SP1_BMC_HOST_UART_RX")
	)
	(segment
		(start 383.547366 -33.64738)
		(end 383.547366 -35.044634)
		(width 0.089408)
		(layer "In9.Cu")
		(net "SP1_BMC_HOST_UART_RX")
	)
	(segment
		(start 380.465584 -63.275972)
		(end 380.465584 -63.854584)
		(width 0.089408)
		(layer "In9.Cu")
		(net "SP1_BMC_HOST_UART_RX")
	)
	(segment
		(start 395.982698 -149.458934)
		(end 395.982698 -151.3459)
		(width 0.10795)
		(layer "F.Cu")
		(net "SMB_VR_STBY_LVC3_SDA")
	)
	(segment
		(start 359.44937 -133.077204)
		(end 359.222294 -133.30428)
		(width 0.10795)
		(layer "F.Cu")
		(net "SMB_VR_STBY_LVC3_SDA")
	)
	(segment
		(start 346.12326 -21.00707)
		(end 346.04833 -21.082)
		(width 0.10795)
		(layer "F.Cu")
		(net "SMB_VR_STBY_LVC3_SDA")
	)
	(segment
		(start 182.069232 -127.403352)
		(end 182.753 -128.08712)
		(width 0.10795)
		(layer "F.Cu")
		(net "SMB_VR_STBY_LVC3_SDA")
	)
	(segment
		(start 13.82395 -90.894154)
		(end 14.547596 -91.6178)
		(width 0.10795)
		(layer "F.Cu")
		(net "SMB_VR_STBY_LVC3_SDA")
	)
	(segment
		(start 345.03614 -20.80514)
		(end 345.03614 -19.53514)
		(width 0.10795)
		(layer "F.Cu")
		(net "SMB_VR_STBY_LVC3_SDA")
	)
	(segment
		(start 418.9222 -17.0053)
		(end 418.465 -17.4625)
		(width 0.10795)
		(layer "F.Cu")
		(net "SMB_VR_STBY_LVC3_SDA")
	)
	(segment
		(start 180.51526 -68.68922)
		(end 179.15128 -68.68922)
		(width 0.10795)
		(layer "F.Cu")
		(net "SMB_VR_STBY_LVC3_SDA")
	)
	(segment
		(start 179.15128 -68.68922)
		(end 178.785012 -68.68922)
		(width 0.1016)
		(layer "F.Cu")
		(net "SMB_VR_STBY_LVC3_SDA")
	)
	(segment
		(start 395.424152 -148.900388)
		(end 395.982698 -149.458934)
		(width 0.10795)
		(layer "F.Cu")
		(net "SMB_VR_STBY_LVC3_SDA")
	)
	(segment
		(start 169.027602 -72.221598)
		(end 168.91 -72.3392)
		(width 0.10795)
		(layer "F.Cu")
		(net "SMB_VR_STBY_LVC3_SDA")
	)
	(segment
		(start 1.857502 -131.179824)
		(end 1.857502 -130.4163)
		(width 0.1016)
		(layer "F.Cu")
		(net "SMB_VR_STBY_LVC3_SDA")
	)
	(segment
		(start 169.024554 -71.297038)
		(end 169.027602 -71.300086)
		(width 0.10795)
		(layer "F.Cu")
		(net "SMB_VR_STBY_LVC3_SDA")
	)
	(segment
		(start 182.753 -128.08712)
		(end 182.753 -128.796288)
		(width 0.10795)
		(layer "F.Cu")
		(net "SMB_VR_STBY_LVC3_SDA")
	)
	(segment
		(start 176.99228 -71.14032)
		(end 176.149 -71.9836)
		(width 0.1016)
		(layer "F.Cu")
		(net "SMB_VR_STBY_LVC3_SDA")
	)
	(segment
		(start 359.3592 -132.4356)
		(end 359.44937 -132.52577)
		(width 0.10795)
		(layer "F.Cu")
		(net "SMB_VR_STBY_LVC3_SDA")
	)
	(segment
		(start 359.498138 -135.71347)
		(end 359.498138 -134.723378)
		(width 0.10795)
		(layer "F.Cu")
		(net "SMB_VR_STBY_LVC3_SDA")
	)
	(segment
		(start 186.7662 -114.842036)
		(end 186.7662 -115.748054)
		(width 0.10795)
		(layer "F.Cu")
		(net "SMB_VR_STBY_LVC3_SDA")
	)
	(segment
		(start 169.027602 -70.838822)
		(end 169.024554 -70.84187)
		(width 0.10795)
		(layer "F.Cu")
		(net "SMB_VR_STBY_LVC3_SDA")
	)
	(segment
		(start 183.007 -122.539252)
		(end 182.069232 -123.47702)
		(width 0.10795)
		(layer "F.Cu")
		(net "SMB_VR_STBY_LVC3_SDA")
	)
	(segment
		(start 183.007 -119.507254)
		(end 183.007 -122.539252)
		(width 0.10795)
		(layer "F.Cu")
		(net "SMB_VR_STBY_LVC3_SDA")
	)
	(segment
		(start 13.04671 0.047752)
		(end 12.4841 0.047752)
		(width 0.10795)
		(layer "F.Cu")
		(net "SMB_VR_STBY_LVC3_SDA")
	)
	(segment
		(start 169.024554 -70.84187)
		(end 169.024554 -71.297038)
		(width 0.10795)
		(layer "F.Cu")
		(net "SMB_VR_STBY_LVC3_SDA")
	)
	(segment
		(start 418.9222 -16.970502)
		(end 418.9222 -17.0053)
		(width 0.10795)
		(layer "F.Cu")
		(net "SMB_VR_STBY_LVC3_SDA")
	)
	(segment
		(start 14.547596 -91.6178)
		(end 15.875 -91.6178)
		(width 0.10795)
		(layer "F.Cu")
		(net "SMB_VR_STBY_LVC3_SDA")
	)
	(segment
		(start 176.99228 -70.481952)
		(end 176.99228 -71.14032)
		(width 0.1016)
		(layer "F.Cu")
		(net "SMB_VR_STBY_LVC3_SDA")
	)
	(segment
		(start 176.149 -71.9836)
		(end 175.438054 -71.9836)
		(width 0.1016)
		(layer "F.Cu")
		(net "SMB_VR_STBY_LVC3_SDA")
	)
	(segment
		(start 13.262864 -0.168402)
		(end 13.04671 0.047752)
		(width 0.10795)
		(layer "F.Cu")
		(net "SMB_VR_STBY_LVC3_SDA")
	)
	(segment
		(start 351.184972 -114.28095)
		(end 351.282 -114.186208)
		(width 0.10795)
		(layer "F.Cu")
		(net "SMB_VR_STBY_LVC3_SDA")
	)
	(segment
		(start 169.027602 -71.300086)
		(end 169.027602 -72.221598)
		(width 0.10795)
		(layer "F.Cu")
		(net "SMB_VR_STBY_LVC3_SDA")
	)
	(segment
		(start 16.113252 -91.856052)
		(end 16.5354 -91.856052)
		(width 0.10795)
		(layer "F.Cu")
		(net "SMB_VR_STBY_LVC3_SDA")
	)
	(segment
		(start 175.438054 -71.9836)
		(end 175.272192 -72.149462)
		(width 0.1016)
		(layer "F.Cu")
		(net "SMB_VR_STBY_LVC3_SDA")
	)
	(segment
		(start 12.82954 -91.24696)
		(end 13.182346 -90.894154)
		(width 0.10795)
		(layer "F.Cu")
		(net "SMB_VR_STBY_LVC3_SDA")
	)
	(segment
		(start 359.44937 -132.52577)
		(end 359.44937 -133.077204)
		(width 0.10795)
		(layer "F.Cu")
		(net "SMB_VR_STBY_LVC3_SDA")
	)
	(segment
		(start 186.7662 -115.748054)
		(end 183.007 -119.507254)
		(width 0.10795)
		(layer "F.Cu")
		(net "SMB_VR_STBY_LVC3_SDA")
	)
	(segment
		(start 419.322504 -16.570198)
		(end 418.9222 -16.970502)
		(width 0.10795)
		(layer "F.Cu")
		(net "SMB_VR_STBY_LVC3_SDA")
	)
	(segment
		(start 345.03614 -19.53514)
		(end 344.478102 -18.977102)
		(width 0.10795)
		(layer "F.Cu")
		(net "SMB_VR_STBY_LVC3_SDA")
	)
	(segment
		(start 1.713992 -131.323334)
		(end 1.857502 -131.179824)
		(width 0.10795)
		(layer "F.Cu")
		(net "SMB_VR_STBY_LVC3_SDA")
	)
	(segment
		(start 168.989502 -69.84238)
		(end 169.027602 -69.88048)
		(width 0.10795)
		(layer "F.Cu")
		(net "SMB_VR_STBY_LVC3_SDA")
	)
	(segment
		(start 359.442258 -133.524244)
		(end 359.222294 -133.30428)
		(width 0.10795)
		(layer "F.Cu")
		(net "SMB_VR_STBY_LVC3_SDA")
	)
	(segment
		(start 182.753 -128.796288)
		(end 183.239156 -129.282444)
		(width 0.10795)
		(layer "F.Cu")
		(net "SMB_VR_STBY_LVC3_SDA")
	)
	(segment
		(start 351.282 -114.186208)
		(end 351.8154 -113.665)
		(width 0.10795)
		(layer "F.Cu")
		(net "SMB_VR_STBY_LVC3_SDA")
	)
	(segment
		(start 395.070076 -148.900388)
		(end 395.424152 -148.900388)
		(width 0.10795)
		(layer "F.Cu")
		(net "SMB_VR_STBY_LVC3_SDA")
	)
	(segment
		(start 394.806932 -149.163532)
		(end 395.070076 -148.900388)
		(width 0.10795)
		(layer "F.Cu")
		(net "SMB_VR_STBY_LVC3_SDA")
	)
	(segment
		(start 346.04833 -21.082)
		(end 345.313 -21.082)
		(width 0.10795)
		(layer "F.Cu")
		(net "SMB_VR_STBY_LVC3_SDA")
	)
	(segment
		(start 418.465 -17.4625)
		(end 418.465 -17.8562)
		(width 0.10795)
		(layer "F.Cu")
		(net "SMB_VR_STBY_LVC3_SDA")
	)
	(segment
		(start 15.875 -91.6178)
		(end 16.113252 -91.856052)
		(width 0.10795)
		(layer "F.Cu")
		(net "SMB_VR_STBY_LVC3_SDA")
	)
	(segment
		(start 359.442258 -134.667498)
		(end 359.442258 -133.524244)
		(width 0.10795)
		(layer "F.Cu")
		(net "SMB_VR_STBY_LVC3_SDA")
	)
	(segment
		(start 13.798042 -0.168402)
		(end 13.262864 -0.168402)
		(width 0.10795)
		(layer "F.Cu")
		(net "SMB_VR_STBY_LVC3_SDA")
	)
	(segment
		(start 13.182346 -90.894154)
		(end 13.82395 -90.894154)
		(width 0.10795)
		(layer "F.Cu")
		(net "SMB_VR_STBY_LVC3_SDA")
	)
	(segment
		(start 182.069232 -123.47702)
		(end 182.069232 -127.403352)
		(width 0.10795)
		(layer "F.Cu")
		(net "SMB_VR_STBY_LVC3_SDA")
	)
	(segment
		(start 15.818104 0.670306)
		(end 14.63675 0.670306)
		(width 0.10795)
		(layer "F.Cu")
		(net "SMB_VR_STBY_LVC3_SDA")
	)
	(segment
		(start 344.478102 -18.977102)
		(end 344.478102 -17.8181)
		(width 0.10795)
		(layer "F.Cu")
		(net "SMB_VR_STBY_LVC3_SDA")
	)
	(segment
		(start 186.205114 -114.28095)
		(end 186.7662 -114.842036)
		(width 0.10795)
		(layer "F.Cu")
		(net "SMB_VR_STBY_LVC3_SDA")
	)
	(segment
		(start 168.989502 -69.2531)
		(end 168.989502 -69.84238)
		(width 0.10795)
		(layer "F.Cu")
		(net "SMB_VR_STBY_LVC3_SDA")
	)
	(segment
		(start 345.313 -21.082)
		(end 345.03614 -20.80514)
		(width 0.10795)
		(layer "F.Cu")
		(net "SMB_VR_STBY_LVC3_SDA")
	)
	(segment
		(start 181.3814 -69.250052)
		(end 181.076092 -69.250052)
		(width 0.10795)
		(layer "F.Cu")
		(net "SMB_VR_STBY_LVC3_SDA")
	)
	(segment
		(start 181.076092 -69.250052)
		(end 180.51526 -68.68922)
		(width 0.10795)
		(layer "F.Cu")
		(net "SMB_VR_STBY_LVC3_SDA")
	)
	(segment
		(start 178.785012 -68.68922)
		(end 176.99228 -70.481952)
		(width 0.1016)
		(layer "F.Cu")
		(net "SMB_VR_STBY_LVC3_SDA")
	)
	(segment
		(start 359.498138 -134.723378)
		(end 359.442258 -134.667498)
		(width 0.10795)
		(layer "F.Cu")
		(net "SMB_VR_STBY_LVC3_SDA")
	)
	(segment
		(start 169.027602 -69.88048)
		(end 169.027602 -70.838822)
		(width 0.10795)
		(layer "F.Cu")
		(net "SMB_VR_STBY_LVC3_SDA")
	)
	(segment
		(start 14.63675 0.670306)
		(end 13.798042 -0.168402)
		(width 0.10795)
		(layer "F.Cu")
		(net "SMB_VR_STBY_LVC3_SDA")
	)
	(segment
		(start 15.884144 0.604266)
		(end 15.818104 0.670306)
		(width 0.10795)
		(layer "F.Cu")
		(net "SMB_VR_STBY_LVC3_SDA")
	)
	(via
		(at 183.239156 -129.282444)
		(size 0.508)
		(drill 0.254)
		(layers "F.Cu" "B.Cu")
		(net "SMB_VR_STBY_LVC3_SDA")
	)
	(via
		(at 1.713992 -131.323334)
		(size 0.508)
		(drill 0.254)
		(layers "F.Cu" "B.Cu")
		(net "SMB_VR_STBY_LVC3_SDA")
	)
	(via
		(at 425.781216 -114.247676)
		(size 0.508)
		(drill 0.254)
		(layers "F.Cu" "B.Cu")
		(net "SMB_VR_STBY_LVC3_SDA")
	)
	(via
		(at 168.91 -72.3392)
		(size 0.508)
		(drill 0.254)
		(layers "F.Cu" "B.Cu")
		(net "SMB_VR_STBY_LVC3_SDA")
	)
	(via
		(at 394.806932 -149.163532)
		(size 0.508)
		(drill 0.254)
		(layers "F.Cu" "B.Cu")
		(net "SMB_VR_STBY_LVC3_SDA")
	)
	(via
		(at 359.3592 -132.4356)
		(size 0.508)
		(drill 0.254)
		(layers "F.Cu" "B.Cu")
		(net "SMB_VR_STBY_LVC3_SDA")
	)
	(via
		(at 397.764 -86.614)
		(size 0.508)
		(drill 0.254)
		(layers "F.Cu" "B.Cu")
		(net "SMB_VR_STBY_LVC3_SDA")
	)
	(via
		(at 421.955722 -99.807522)
		(size 0.508)
		(drill 0.254)
		(layers "F.Cu" "B.Cu")
		(net "SMB_VR_STBY_LVC3_SDA")
	)
	(via
		(at 359.222294 -133.30428)
		(size 0.762)
		(drill 0.381)
		(layers "F.Cu" "B.Cu")
		(net "SMB_VR_STBY_LVC3_SDA")
	)
	(via
		(at 12.82954 -91.24696)
		(size 0.508)
		(drill 0.254)
		(layers "F.Cu" "B.Cu")
		(net "SMB_VR_STBY_LVC3_SDA")
	)
	(via
		(at 398.909794 -19.150584)
		(size 0.508)
		(drill 0.254)
		(layers "F.Cu" "B.Cu")
		(net "SMB_VR_STBY_LVC3_SDA")
	)
	(via
		(at 192.205356 -5.87502)
		(size 0.508)
		(drill 0.254)
		(layers "F.Cu" "B.Cu")
		(net "SMB_VR_STBY_LVC3_SDA")
	)
	(via
		(at 164.1348 -126.9238)
		(size 0.508)
		(drill 0.254)
		(layers "F.Cu" "B.Cu")
		(net "SMB_VR_STBY_LVC3_SDA")
	)
	(via
		(at 368.5921 -145.5928)
		(size 0.508)
		(drill 0.254)
		(layers "F.Cu" "B.Cu")
		(net "SMB_VR_STBY_LVC3_SDA")
	)
	(via
		(at 180.367178 5.039106)
		(size 0.508)
		(drill 0.254)
		(layers "F.Cu" "B.Cu")
		(net "SMB_VR_STBY_LVC3_SDA")
	)
	(via
		(at 347.2688 -81.6864)
		(size 0.508)
		(drill 0.254)
		(layers "F.Cu" "B.Cu")
		(net "SMB_VR_STBY_LVC3_SDA")
	)
	(via
		(at 346.12326 -21.00707)
		(size 0.762)
		(drill 0.381)
		(layers "F.Cu" "B.Cu")
		(net "SMB_VR_STBY_LVC3_SDA")
	)
	(via
		(at 394.826236 -6.059424)
		(size 0.508)
		(drill 0.254)
		(layers "F.Cu" "B.Cu")
		(net "SMB_VR_STBY_LVC3_SDA")
	)
	(via
		(at 159.43707 -155.441142)
		(size 0.508)
		(drill 0.254)
		(layers "F.Cu" "B.Cu")
		(net "SMB_VR_STBY_LVC3_SDA")
	)
	(via
		(at 345.313 -21.082)
		(size 0.508)
		(drill 0.254)
		(layers "F.Cu" "B.Cu")
		(net "SMB_VR_STBY_LVC3_SDA")
	)
	(via
		(at 336.048604 -33.864042)
		(size 0.508)
		(drill 0.254)
		(layers "F.Cu" "B.Cu")
		(net "SMB_VR_STBY_LVC3_SDA")
	)
	(via
		(at 419.322504 -16.570198)
		(size 0.508)
		(drill 0.254)
		(layers "F.Cu" "B.Cu")
		(net "SMB_VR_STBY_LVC3_SDA")
	)
	(via
		(at 351.8154 -113.665)
		(size 0.508)
		(drill 0.254)
		(layers "F.Cu" "B.Cu")
		(net "SMB_VR_STBY_LVC3_SDA")
	)
	(via
		(at 356.3493 -129.7051)
		(size 0.508)
		(drill 0.254)
		(layers "F.Cu" "B.Cu")
		(net "SMB_VR_STBY_LVC3_SDA")
	)
	(via
		(at 15.884144 0.604266)
		(size 0.508)
		(drill 0.254)
		(layers "F.Cu" "B.Cu")
		(net "SMB_VR_STBY_LVC3_SDA")
	)
	(via
		(at 175.272192 -72.149462)
		(size 0.508)
		(drill 0.254)
		(layers "F.Cu" "B.Cu")
		(net "SMB_VR_STBY_LVC3_SDA")
	)
	(segment
		(start 399.799048 -6.96722)
		(end 400.557492 -7.725664)
		(width 0.10795)
		(layer "B.Cu")
		(net "SMB_VR_STBY_LVC3_SDA")
	)
	(segment
		(start 180.367178 5.039106)
		(end 180.510942 4.895342)
		(width 0.10795)
		(layer "B.Cu")
		(net "SMB_VR_STBY_LVC3_SDA")
	)
	(segment
		(start 394.64615 -6.62686)
		(end 394.98651 -6.96722)
		(width 0.10795)
		(layer "B.Cu")
		(net "SMB_VR_STBY_LVC3_SDA")
	)
	(segment
		(start 398.453102 -19.589496)
		(end 398.561052 -19.697446)
		(width 0.10795)
		(layer "B.Cu")
		(net "SMB_VR_STBY_LVC3_SDA")
	)
	(segment
		(start 359.3592 -132.13588)
		(end 358.964992 -131.741672)
		(width 0.10795)
		(layer "B.Cu")
		(net "SMB_VR_STBY_LVC3_SDA")
	)
	(segment
		(start 398.91589 -19.697446)
		(end 399.109692 -19.503644)
		(width 0.10795)
		(layer "B.Cu")
		(net "SMB_VR_STBY_LVC3_SDA")
	)
	(segment
		(start 346.075762 -84.417408)
		(end 346.332302 -84.673948)
		(width 0.10795)
		(layer "B.Cu")
		(net "SMB_VR_STBY_LVC3_SDA")
	)
	(segment
		(start 180.594 -6.495288)
		(end 180.594 -6.961124)
		(width 0.10795)
		(layer "B.Cu")
		(net "SMB_VR_STBY_LVC3_SDA")
	)
	(segment
		(start 346.903802 -82.502756)
		(end 346.075762 -83.330796)
		(width 0.10795)
		(layer "B.Cu")
		(net "SMB_VR_STBY_LVC3_SDA")
	)
	(segment
		(start 191.778382 -5.450332)
		(end 192.20307 -5.87502)
		(width 0.10795)
		(layer "B.Cu")
		(net "SMB_VR_STBY_LVC3_SDA")
	)
	(segment
		(start 400.557492 -13.088874)
		(end 399.485612 -14.160754)
		(width 0.10795)
		(layer "B.Cu")
		(net "SMB_VR_STBY_LVC3_SDA")
	)
	(segment
		(start 356.572312 -129.928112)
		(end 356.3493 -129.7051)
		(width 0.10795)
		(layer "B.Cu")
		(net "SMB_VR_STBY_LVC3_SDA")
	)
	(segment
		(start 394.64615 -6.23951)
		(end 394.64615 -6.62686)
		(width 0.10795)
		(layer "B.Cu")
		(net "SMB_VR_STBY_LVC3_SDA")
	)
	(segment
		(start 179.936648 -3.832352)
		(end 179.578 -4.191)
		(width 0.10795)
		(layer "B.Cu")
		(net "SMB_VR_STBY_LVC3_SDA")
	)
	(segment
		(start 398.900904 -15.31239)
		(end 398.900904 -17.42059)
		(width 0.10795)
		(layer "B.Cu")
		(net "SMB_VR_STBY_LVC3_SDA")
	)
	(segment
		(start 184.884314 -7.366)
		(end 186.799982 -5.450332)
		(width 0.10795)
		(layer "B.Cu")
		(net "SMB_VR_STBY_LVC3_SDA")
	)
	(segment
		(start 399.485612 -14.727682)
		(end 398.900904 -15.31239)
		(width 0.10795)
		(layer "B.Cu")
		(net "SMB_VR_STBY_LVC3_SDA")
	)
	(segment
		(start 180.15077 4.150868)
		(end 179.936648 3.936746)
		(width 0.10795)
		(layer "B.Cu")
		(net "SMB_VR_STBY_LVC3_SDA")
	)
	(segment
		(start 400.557492 -7.725664)
		(end 400.557492 -13.088874)
		(width 0.10795)
		(layer "B.Cu")
		(net "SMB_VR_STBY_LVC3_SDA")
	)
	(segment
		(start 179.578 -4.191)
		(end 179.578 -5.479288)
		(width 0.10795)
		(layer "B.Cu")
		(net "SMB_VR_STBY_LVC3_SDA")
	)
	(segment
		(start 398.453102 -17.868392)
		(end 398.453102 -19.589496)
		(width 0.10795)
		(layer "B.Cu")
		(net "SMB_VR_STBY_LVC3_SDA")
	)
	(segment
		(start 398.900904 -17.42059)
		(end 398.453102 -17.868392)
		(width 0.10795)
		(layer "B.Cu")
		(net "SMB_VR_STBY_LVC3_SDA")
	)
	(segment
		(start 346.905326 -82.430366)
		(end 346.903802 -82.43189)
		(width 0.10795)
		(layer "B.Cu")
		(net "SMB_VR_STBY_LVC3_SDA")
	)
	(segment
		(start 359.3592 -132.4356)
		(end 359.3592 -132.13588)
		(width 0.10795)
		(layer "B.Cu")
		(net "SMB_VR_STBY_LVC3_SDA")
	)
	(segment
		(start 394.98651 -6.96722)
		(end 399.799048 -6.96722)
		(width 0.10795)
		(layer "B.Cu")
		(net "SMB_VR_STBY_LVC3_SDA")
	)
	(segment
		(start 178.310794 -69.230494)
		(end 177.583338 -69.230494)
		(width 0.10795)
		(layer "B.Cu")
		(net "SMB_VR_STBY_LVC3_SDA")
	)
	(segment
		(start 397.764 -85.9155)
		(end 397.764 -86.614)
		(width 0.10795)
		(layer "B.Cu")
		(net "SMB_VR_STBY_LVC3_SDA")
	)
	(segment
		(start 356.572312 -130.828288)
		(end 356.572312 -129.928112)
		(width 0.10795)
		(layer "B.Cu")
		(net "SMB_VR_STBY_LVC3_SDA")
	)
	(segment
		(start 346.903802 -82.43189)
		(end 346.903802 -82.502756)
		(width 0.10795)
		(layer "B.Cu")
		(net "SMB_VR_STBY_LVC3_SDA")
	)
	(segment
		(start 180.510942 4.895342)
		(end 180.510942 4.51485)
		(width 0.10795)
		(layer "B.Cu")
		(net "SMB_VR_STBY_LVC3_SDA")
	)
	(segment
		(start 179.936648 3.936746)
		(end 179.936648 -3.832352)
		(width 0.10795)
		(layer "B.Cu")
		(net "SMB_VR_STBY_LVC3_SDA")
	)
	(segment
		(start 177.583338 -69.230494)
		(end 177.073052 -69.74078)
		(width 0.10795)
		(layer "B.Cu")
		(net "SMB_VR_STBY_LVC3_SDA")
	)
	(segment
		(start 186.799982 -5.450332)
		(end 191.778382 -5.450332)
		(width 0.10795)
		(layer "B.Cu")
		(net "SMB_VR_STBY_LVC3_SDA")
	)
	(segment
		(start 192.20307 -5.87502)
		(end 192.205356 -5.87502)
		(width 0.10795)
		(layer "B.Cu")
		(net "SMB_VR_STBY_LVC3_SDA")
	)
	(segment
		(start 346.905326 -82.049874)
		(end 346.905326 -82.430366)
		(width 0.10795)
		(layer "B.Cu")
		(net "SMB_VR_STBY_LVC3_SDA")
	)
	(segment
		(start 180.594 -6.961124)
		(end 180.998876 -7.366)
		(width 0.10795)
		(layer "B.Cu")
		(net "SMB_VR_STBY_LVC3_SDA")
	)
	(segment
		(start 394.826236 -6.059424)
		(end 394.64615 -6.23951)
		(width 0.10795)
		(layer "B.Cu")
		(net "SMB_VR_STBY_LVC3_SDA")
	)
	(segment
		(start 179.578 -5.479288)
		(end 180.594 -6.495288)
		(width 0.10795)
		(layer "B.Cu")
		(net "SMB_VR_STBY_LVC3_SDA")
	)
	(segment
		(start 398.561052 -19.697446)
		(end 398.91589 -19.697446)
		(width 0.10795)
		(layer "B.Cu")
		(net "SMB_VR_STBY_LVC3_SDA")
	)
	(segment
		(start 358.964992 -131.741672)
		(end 357.485696 -131.741672)
		(width 0.10795)
		(layer "B.Cu")
		(net "SMB_VR_STBY_LVC3_SDA")
	)
	(segment
		(start 177.073052 -70.348602)
		(end 175.272192 -72.149462)
		(width 0.10795)
		(layer "B.Cu")
		(net "SMB_VR_STBY_LVC3_SDA")
	)
	(segment
		(start 397.764 -86.614)
		(end 398.4244 -87.2744)
		(width 0.10795)
		(layer "B.Cu")
		(net "SMB_VR_STBY_LVC3_SDA")
	)
	(segment
		(start 399.109692 -19.503644)
		(end 399.109692 -19.350482)
		(width 0.10795)
		(layer "B.Cu")
		(net "SMB_VR_STBY_LVC3_SDA")
	)
	(segment
		(start 346.075762 -83.330796)
		(end 346.075762 -84.417408)
		(width 0.10795)
		(layer "B.Cu")
		(net "SMB_VR_STBY_LVC3_SDA")
	)
	(segment
		(start 180.15077 4.154678)
		(end 180.15077 4.150868)
		(width 0.10795)
		(layer "B.Cu")
		(net "SMB_VR_STBY_LVC3_SDA")
	)
	(segment
		(start 357.485696 -131.741672)
		(end 356.572312 -130.828288)
		(width 0.10795)
		(layer "B.Cu")
		(net "SMB_VR_STBY_LVC3_SDA")
	)
	(segment
		(start 399.485612 -14.160754)
		(end 399.485612 -14.727682)
		(width 0.10795)
		(layer "B.Cu")
		(net "SMB_VR_STBY_LVC3_SDA")
	)
	(segment
		(start 180.998876 -7.366)
		(end 184.884314 -7.366)
		(width 0.10795)
		(layer "B.Cu")
		(net "SMB_VR_STBY_LVC3_SDA")
	)
	(segment
		(start 346.332302 -84.673948)
		(end 346.332302 -85.0011)
		(width 0.10795)
		(layer "B.Cu")
		(net "SMB_VR_STBY_LVC3_SDA")
	)
	(segment
		(start 399.109692 -19.350482)
		(end 398.909794 -19.150584)
		(width 0.10795)
		(layer "B.Cu")
		(net "SMB_VR_STBY_LVC3_SDA")
	)
	(segment
		(start 180.510942 4.51485)
		(end 180.15077 4.154678)
		(width 0.10795)
		(layer "B.Cu")
		(net "SMB_VR_STBY_LVC3_SDA")
	)
	(segment
		(start 398.4244 -87.2744)
		(end 398.4244 -87.3887)
		(width 0.10795)
		(layer "B.Cu")
		(net "SMB_VR_STBY_LVC3_SDA")
	)
	(segment
		(start 347.2688 -81.6864)
		(end 346.905326 -82.049874)
		(width 0.10795)
		(layer "B.Cu")
		(net "SMB_VR_STBY_LVC3_SDA")
	)
	(segment
		(start 177.073052 -69.74078)
		(end 177.073052 -70.348602)
		(width 0.10795)
		(layer "B.Cu")
		(net "SMB_VR_STBY_LVC3_SDA")
	)
	(segment
		(start 164.857938 -126.134368)
		(end 163.768024 -125.044454)
		(width 0.089408)
		(layer "In2.Cu")
		(net "SMB_VR_STBY_LVC3_SDA")
	)
	(segment
		(start 157.353 -134.239)
		(end 157.353 -132.08)
		(width 0.089408)
		(layer "In2.Cu")
		(net "SMB_VR_STBY_LVC3_SDA")
	)
	(segment
		(start 422.316402 -103.060754)
		(end 422.316402 -100.168202)
		(width 0.089408)
		(layer "In2.Cu")
		(net "SMB_VR_STBY_LVC3_SDA")
	)
	(segment
		(start 158.08833 -131.34467)
		(end 158.08833 -128.956816)
		(width 0.089408)
		(layer "In2.Cu")
		(net "SMB_VR_STBY_LVC3_SDA")
	)
	(segment
		(start 165.379654 -122.730514)
		(end 165.379654 -116.63553)
		(width 0.089408)
		(layer "In2.Cu")
		(net "SMB_VR_STBY_LVC3_SDA")
	)
	(segment
		(start 340.892892 -20.384008)
		(end 339.2043 -22.0726)
		(width 0.089408)
		(layer "In2.Cu")
		(net "SMB_VR_STBY_LVC3_SDA")
	)
	(segment
		(start 422.316402 -100.168202)
		(end 421.955722 -99.807522)
		(width 0.089408)
		(layer "In2.Cu")
		(net "SMB_VR_STBY_LVC3_SDA")
	)
	(segment
		(start 166.148004 -115.86718)
		(end 166.148004 -105.885996)
		(width 0.089408)
		(layer "In2.Cu")
		(net "SMB_VR_STBY_LVC3_SDA")
	)
	(segment
		(start 344.264488 -20.384008)
		(end 340.892892 -20.384008)
		(width 0.089408)
		(layer "In2.Cu")
		(net "SMB_VR_STBY_LVC3_SDA")
	)
	(segment
		(start 163.782248 -127.276352)
		(end 164.1348 -126.9238)
		(width 0.089408)
		(layer "In2.Cu")
		(net "SMB_VR_STBY_LVC3_SDA")
	)
	(segment
		(start 159.62757 -155.250642)
		(end 159.62757 -154.920188)
		(width 0.089408)
		(layer "In2.Cu")
		(net "SMB_VR_STBY_LVC3_SDA")
	)
	(segment
		(start 164.857938 -126.505462)
		(end 164.857938 -126.134368)
		(width 0.089408)
		(layer "In2.Cu")
		(net "SMB_VR_STBY_LVC3_SDA")
	)
	(segment
		(start 344.96248 -21.082)
		(end 344.264488 -20.384008)
		(width 0.089408)
		(layer "In2.Cu")
		(net "SMB_VR_STBY_LVC3_SDA")
	)
	(segment
		(start 175.71212 -72.124316)
		(end 175.622712 -72.034908)
		(width 0.089408)
		(layer "In2.Cu")
		(net "SMB_VR_STBY_LVC3_SDA")
	)
	(segment
		(start 175.622712 -72.034908)
		(end 175.386746 -72.034908)
		(width 0.089408)
		(layer "In2.Cu")
		(net "SMB_VR_STBY_LVC3_SDA")
	)
	(segment
		(start 331.736192 -32.155892)
		(end 333.2353 -33.655)
		(width 0.089408)
		(layer "In2.Cu")
		(net "SMB_VR_STBY_LVC3_SDA")
	)
	(segment
		(start 336.423 -22.0726)
		(end 331.736192 -26.759408)
		(width 0.089408)
		(layer "In2.Cu")
		(net "SMB_VR_STBY_LVC3_SDA")
	)
	(segment
		(start 163.768024 -125.044454)
		(end 163.768024 -124.342144)
		(width 0.089408)
		(layer "In2.Cu")
		(net "SMB_VR_STBY_LVC3_SDA")
	)
	(segment
		(start 175.500792 -73.241408)
		(end 175.71212 -73.03008)
		(width 0.089408)
		(layer "In2.Cu")
		(net "SMB_VR_STBY_LVC3_SDA")
	)
	(segment
		(start 421.119808 -112.232694)
		(end 421.119808 -104.257348)
		(width 0.089408)
		(layer "In2.Cu")
		(net "SMB_VR_STBY_LVC3_SDA")
	)
	(segment
		(start 425.511214 -114.517678)
		(end 424.715686 -114.517678)
		(width 0.089408)
		(layer "In2.Cu")
		(net "SMB_VR_STBY_LVC3_SDA")
	)
	(segment
		(start 163.768024 -124.342144)
		(end 165.379654 -122.730514)
		(width 0.089408)
		(layer "In2.Cu")
		(net "SMB_VR_STBY_LVC3_SDA")
	)
	(segment
		(start 173.355 -96.774)
		(end 175.500792 -94.628208)
		(width 0.089408)
		(layer "In2.Cu")
		(net "SMB_VR_STBY_LVC3_SDA")
	)
	(segment
		(start 424.715686 -114.517678)
		(end 424.60799 -114.625374)
		(width 0.089408)
		(layer "In2.Cu")
		(net "SMB_VR_STBY_LVC3_SDA")
	)
	(segment
		(start 424.60799 -114.625374)
		(end 423.512488 -114.625374)
		(width 0.089408)
		(layer "In2.Cu")
		(net "SMB_VR_STBY_LVC3_SDA")
	)
	(segment
		(start 165.379654 -116.63553)
		(end 166.148004 -115.86718)
		(width 0.089408)
		(layer "In2.Cu")
		(net "SMB_VR_STBY_LVC3_SDA")
	)
	(segment
		(start 159.768794 -127.276352)
		(end 163.782248 -127.276352)
		(width 0.089408)
		(layer "In2.Cu")
		(net "SMB_VR_STBY_LVC3_SDA")
	)
	(segment
		(start 159.43707 -155.441142)
		(end 159.62757 -155.250642)
		(width 0.089408)
		(layer "In2.Cu")
		(net "SMB_VR_STBY_LVC3_SDA")
	)
	(segment
		(start 164.1348 -126.9238)
		(end 164.4396 -126.9238)
		(width 0.089408)
		(layer "In2.Cu")
		(net "SMB_VR_STBY_LVC3_SDA")
	)
	(segment
		(start 175.386746 -72.034908)
		(end 175.272192 -72.149462)
		(width 0.089408)
		(layer "In2.Cu")
		(net "SMB_VR_STBY_LVC3_SDA")
	)
	(segment
		(start 175.500792 -94.628208)
		(end 175.500792 -73.241408)
		(width 0.089408)
		(layer "In2.Cu")
		(net "SMB_VR_STBY_LVC3_SDA")
	)
	(segment
		(start 425.781216 -114.247676)
		(end 425.511214 -114.517678)
		(width 0.089408)
		(layer "In2.Cu")
		(net "SMB_VR_STBY_LVC3_SDA")
	)
	(segment
		(start 158.088584 -153.381202)
		(end 158.088584 -134.974584)
		(width 0.089408)
		(layer "In2.Cu")
		(net "SMB_VR_STBY_LVC3_SDA")
	)
	(segment
		(start 345.313 -21.082)
		(end 344.96248 -21.082)
		(width 0.089408)
		(layer "In2.Cu")
		(net "SMB_VR_STBY_LVC3_SDA")
	)
	(segment
		(start 159.62757 -154.920188)
		(end 158.088584 -153.381202)
		(width 0.089408)
		(layer "In2.Cu")
		(net "SMB_VR_STBY_LVC3_SDA")
	)
	(segment
		(start 158.088584 -134.974584)
		(end 157.353 -134.239)
		(width 0.089408)
		(layer "In2.Cu")
		(net "SMB_VR_STBY_LVC3_SDA")
	)
	(segment
		(start 339.2043 -22.0726)
		(end 336.423 -22.0726)
		(width 0.089408)
		(layer "In2.Cu")
		(net "SMB_VR_STBY_LVC3_SDA")
	)
	(segment
		(start 157.353 -132.08)
		(end 158.08833 -131.34467)
		(width 0.089408)
		(layer "In2.Cu")
		(net "SMB_VR_STBY_LVC3_SDA")
	)
	(segment
		(start 173.355 -98.679)
		(end 173.355 -96.774)
		(width 0.089408)
		(layer "In2.Cu")
		(net "SMB_VR_STBY_LVC3_SDA")
	)
	(segment
		(start 166.148004 -105.885996)
		(end 173.355 -98.679)
		(width 0.089408)
		(layer "In2.Cu")
		(net "SMB_VR_STBY_LVC3_SDA")
	)
	(segment
		(start 333.2353 -33.655)
		(end 335.839562 -33.655)
		(width 0.089408)
		(layer "In2.Cu")
		(net "SMB_VR_STBY_LVC3_SDA")
	)
	(segment
		(start 335.839562 -33.655)
		(end 336.048604 -33.864042)
		(width 0.089408)
		(layer "In2.Cu")
		(net "SMB_VR_STBY_LVC3_SDA")
	)
	(segment
		(start 158.08833 -128.956816)
		(end 159.768794 -127.276352)
		(width 0.089408)
		(layer "In2.Cu")
		(net "SMB_VR_STBY_LVC3_SDA")
	)
	(segment
		(start 421.119808 -104.257348)
		(end 422.316402 -103.060754)
		(width 0.089408)
		(layer "In2.Cu")
		(net "SMB_VR_STBY_LVC3_SDA")
	)
	(segment
		(start 175.71212 -73.03008)
		(end 175.71212 -72.124316)
		(width 0.089408)
		(layer "In2.Cu")
		(net "SMB_VR_STBY_LVC3_SDA")
	)
	(segment
		(start 423.512488 -114.625374)
		(end 421.119808 -112.232694)
		(width 0.089408)
		(layer "In2.Cu")
		(net "SMB_VR_STBY_LVC3_SDA")
	)
	(segment
		(start 164.4396 -126.9238)
		(end 164.857938 -126.505462)
		(width 0.089408)
		(layer "In2.Cu")
		(net "SMB_VR_STBY_LVC3_SDA")
	)
	(segment
		(start 331.736192 -26.759408)
		(end 331.736192 -32.155892)
		(width 0.089408)
		(layer "In2.Cu")
		(net "SMB_VR_STBY_LVC3_SDA")
	)
	(segment
		(start 356.070408 -128.916684)
		(end 352.551746 -128.916684)
		(width 0.089408)
		(layer "In4.Cu")
		(net "SMB_VR_STBY_LVC3_SDA")
	)
	(segment
		(start 417.429442 -85.504274)
		(end 418.308536 -86.383368)
		(width 0.089408)
		(layer "In4.Cu")
		(net "SMB_VR_STBY_LVC3_SDA")
	)
	(segment
		(start 399.067274 -85.89772)
		(end 399.51533 -85.449664)
		(width 0.089408)
		(layer "In4.Cu")
		(net "SMB_VR_STBY_LVC3_SDA")
	)
	(segment
		(start 402.082 -152.411938)
		(end 402.082 -157.6324)
		(width 0.089408)
		(layer "In4.Cu")
		(net "SMB_VR_STBY_LVC3_SDA")
	)
	(segment
		(start 473.458794 -132.480812)
		(end 475.091252 -134.114794)
		(width 0.089408)
		(layer "In4.Cu")
		(net "SMB_VR_STBY_LVC3_SDA")
	)
	(segment
		(start 193.034666 -19.128486)
		(end 193.034666 -7.75208)
		(width 0.089408)
		(layer "In4.Cu")
		(net "SMB_VR_STBY_LVC3_SDA")
	)
	(segment
		(start 173.7868 -60.066682)
		(end 173.7868 -52.76469)
		(width 0.089408)
		(layer "In4.Cu")
		(net "SMB_VR_STBY_LVC3_SDA")
	)
	(segment
		(start 464.382866 -115.467384)
		(end 465.475066 -116.559584)
		(width 0.089408)
		(layer "In4.Cu")
		(net "SMB_VR_STBY_LVC3_SDA")
	)
	(segment
		(start 349.732092 -126.09703)
		(end 349.732092 -120.028208)
		(width 0.089408)
		(layer "In4.Cu")
		(net "SMB_VR_STBY_LVC3_SDA")
	)
	(segment
		(start 394.806932 -149.163532)
		(end 395.909292 -149.163532)
		(width 0.089408)
		(layer "In4.Cu")
		(net "SMB_VR_STBY_LVC3_SDA")
	)
	(segment
		(start 475.091252 -136.749536)
		(end 474.239336 -137.601452)
		(width 0.089408)
		(layer "In4.Cu")
		(net "SMB_VR_STBY_LVC3_SDA")
	)
	(segment
		(start 473.141802 -128.96215)
		(end 473.141802 -130.65633)
		(width 0.089408)
		(layer "In4.Cu")
		(net "SMB_VR_STBY_LVC3_SDA")
	)
	(segment
		(start 171.684696 -49.447704)
		(end 173.4312 -47.7012)
		(width 0.089408)
		(layer "In4.Cu")
		(net "SMB_VR_STBY_LVC3_SDA")
	)
	(segment
		(start 175.514254 -71.9074)
		(end 175.72482 -71.9074)
		(width 0.089408)
		(layer "In4.Cu")
		(net "SMB_VR_STBY_LVC3_SDA")
	)
	(segment
		(start 418.308536 -96.490282)
		(end 421.435784 -99.61753)
		(width 0.089408)
		(layer "In4.Cu")
		(net "SMB_VR_STBY_LVC3_SDA")
	)
	(segment
		(start 432.611276 -119.669814)
		(end 435.865524 -116.415566)
		(width 0.089408)
		(layer "In4.Cu")
		(net "SMB_VR_STBY_LVC3_SDA")
	)
	(segment
		(start 475.091252 -134.114794)
		(end 475.091252 -136.749536)
		(width 0.089408)
		(layer "In4.Cu")
		(net "SMB_VR_STBY_LVC3_SDA")
	)
	(segment
		(start 171.684696 -50.662586)
		(end 171.684696 -49.447704)
		(width 0.089408)
		(layer "In4.Cu")
		(net "SMB_VR_STBY_LVC3_SDA")
	)
	(segment
		(start 177.111152 -63.391034)
		(end 173.7868 -60.066682)
		(width 0.089408)
		(layer "In4.Cu")
		(net "SMB_VR_STBY_LVC3_SDA")
	)
	(segment
		(start 184.981596 -22.24786)
		(end 185.563256 -21.6662)
		(width 0.089408)
		(layer "In4.Cu")
		(net "SMB_VR_STBY_LVC3_SDA")
	)
	(segment
		(start 349.732092 -120.028208)
		(end 351.0915 -118.6688)
		(width 0.089408)
		(layer "In4.Cu")
		(net "SMB_VR_STBY_LVC3_SDA")
	)
	(segment
		(start 176.166272 -67.739514)
		(end 177.111152 -66.794634)
		(width 0.089408)
		(layer "In4.Cu")
		(net "SMB_VR_STBY_LVC3_SDA")
	)
	(segment
		(start 474.239336 -147.562062)
		(end 471.59164 -150.209758)
		(width 0.089408)
		(layer "In4.Cu")
		(net "SMB_VR_STBY_LVC3_SDA")
	)
	(segment
		(start 399.792698 -150.122636)
		(end 402.082 -152.411938)
		(width 0.089408)
		(layer "In4.Cu")
		(net "SMB_VR_STBY_LVC3_SDA")
	)
	(segment
		(start 473.458794 -130.973322)
		(end 473.458794 -132.480812)
		(width 0.089408)
		(layer "In4.Cu")
		(net "SMB_VR_STBY_LVC3_SDA")
	)
	(segment
		(start 356.3493 -129.7051)
		(end 356.3493 -129.195576)
		(width 0.089408)
		(layer "In4.Cu")
		(net "SMB_VR_STBY_LVC3_SDA")
	)
	(segment
		(start 472.729306 -117.689884)
		(end 474.049598 -119.010176)
		(width 0.089408)
		(layer "In4.Cu")
		(net "SMB_VR_STBY_LVC3_SDA")
	)
	(segment
		(start 463.277204 -158.598108)
		(end 464.73491 -157.140402)
		(width 0.089408)
		(layer "In4.Cu")
		(net "SMB_VR_STBY_LVC3_SDA")
	)
	(segment
		(start 400.490944 -85.480398)
		(end 402.305774 -85.480398)
		(width 0.089408)
		(layer "In4.Cu")
		(net "SMB_VR_STBY_LVC3_SDA")
	)
	(segment
		(start 413.085026 -86.061804)
		(end 413.642556 -85.504274)
		(width 0.089408)
		(layer "In4.Cu")
		(net "SMB_VR_STBY_LVC3_SDA")
	)
	(segment
		(start 188.1632 -20.742656)
		(end 191.420496 -20.742656)
		(width 0.089408)
		(layer "In4.Cu")
		(net "SMB_VR_STBY_LVC3_SDA")
	)
	(segment
		(start 421.76573 -99.61753)
		(end 421.955722 -99.807522)
		(width 0.089408)
		(layer "In4.Cu")
		(net "SMB_VR_STBY_LVC3_SDA")
	)
	(segment
		(start 426.454062 -114.920522)
		(end 426.454062 -116.345462)
		(width 0.089408)
		(layer "In4.Cu")
		(net "SMB_VR_STBY_LVC3_SDA")
	)
	(segment
		(start 435.865524 -116.415566)
		(end 441.525406 -116.415566)
		(width 0.089408)
		(layer "In4.Cu")
		(net "SMB_VR_STBY_LVC3_SDA")
	)
	(segment
		(start 426.454062 -116.345462)
		(end 427.586648 -117.478048)
		(width 0.089408)
		(layer "In4.Cu")
		(net "SMB_VR_STBY_LVC3_SDA")
	)
	(segment
		(start 356.3493 -129.195576)
		(end 356.070408 -128.916684)
		(width 0.089408)
		(layer "In4.Cu")
		(net "SMB_VR_STBY_LVC3_SDA")
	)
	(segment
		(start 184.981596 -26.016204)
		(end 184.981596 -22.24786)
		(width 0.089408)
		(layer "In4.Cu")
		(net "SMB_VR_STBY_LVC3_SDA")
	)
	(segment
		(start 395.909292 -149.163532)
		(end 396.868396 -150.122636)
		(width 0.089408)
		(layer "In4.Cu")
		(net "SMB_VR_STBY_LVC3_SDA")
	)
	(segment
		(start 191.420496 -20.742656)
		(end 193.034666 -19.128486)
		(width 0.089408)
		(layer "In4.Cu")
		(net "SMB_VR_STBY_LVC3_SDA")
	)
	(segment
		(start 465.511896 -156.363416)
		(end 464.73491 -157.140402)
		(width 0.089408)
		(layer "In4.Cu")
		(net "SMB_VR_STBY_LVC3_SDA")
	)
	(segment
		(start 425.781216 -114.247676)
		(end 426.454062 -114.920522)
		(width 0.089408)
		(layer "In4.Cu")
		(net "SMB_VR_STBY_LVC3_SDA")
	)
	(segment
		(start 396.868396 -150.122636)
		(end 399.792698 -150.122636)
		(width 0.089408)
		(layer "In4.Cu")
		(net "SMB_VR_STBY_LVC3_SDA")
	)
	(segment
		(start 411.678374 -87.470488)
		(end 413.085026 -86.063836)
		(width 0.089408)
		(layer "In4.Cu")
		(net "SMB_VR_STBY_LVC3_SDA")
	)
	(segment
		(start 402.082 -157.6324)
		(end 403.047708 -158.598108)
		(width 0.089408)
		(layer "In4.Cu")
		(net "SMB_VR_STBY_LVC3_SDA")
	)
	(segment
		(start 173.7868 -52.76469)
		(end 171.684696 -50.662586)
		(width 0.089408)
		(layer "In4.Cu")
		(net "SMB_VR_STBY_LVC3_SDA")
	)
	(segment
		(start 175.72482 -71.9074)
		(end 176.166272 -71.465948)
		(width 0.089408)
		(layer "In4.Cu")
		(net "SMB_VR_STBY_LVC3_SDA")
	)
	(segment
		(start 352.551746 -128.916684)
		(end 349.732092 -126.09703)
		(width 0.089408)
		(layer "In4.Cu")
		(net "SMB_VR_STBY_LVC3_SDA")
	)
	(segment
		(start 397.503904 -86.188042)
		(end 397.794226 -85.89772)
		(width 0.089408)
		(layer "In4.Cu")
		(net "SMB_VR_STBY_LVC3_SDA")
	)
	(segment
		(start 413.085026 -86.063836)
		(end 413.085026 -86.061804)
		(width 0.089408)
		(layer "In4.Cu")
		(net "SMB_VR_STBY_LVC3_SDA")
	)
	(segment
		(start 474.955616 -124.03836)
		(end 474.955616 -127.148336)
		(width 0.089408)
		(layer "In4.Cu")
		(net "SMB_VR_STBY_LVC3_SDA")
	)
	(segment
		(start 427.586648 -117.478048)
		(end 427.586648 -118.153434)
		(width 0.089408)
		(layer "In4.Cu")
		(net "SMB_VR_STBY_LVC3_SDA")
	)
	(segment
		(start 177.111152 -66.794634)
		(end 177.111152 -63.391034)
		(width 0.089408)
		(layer "In4.Cu")
		(net "SMB_VR_STBY_LVC3_SDA")
	)
	(segment
		(start 474.239336 -137.601452)
		(end 474.239336 -147.562062)
		(width 0.089408)
		(layer "In4.Cu")
		(net "SMB_VR_STBY_LVC3_SDA")
	)
	(segment
		(start 410.023056 -86.927944)
		(end 410.5656 -87.470488)
		(width 0.089408)
		(layer "In4.Cu")
		(net "SMB_VR_STBY_LVC3_SDA")
	)
	(segment
		(start 418.308536 -86.383368)
		(end 418.308536 -96.490282)
		(width 0.089408)
		(layer "In4.Cu")
		(net "SMB_VR_STBY_LVC3_SDA")
	)
	(segment
		(start 187.239656 -21.6662)
		(end 188.1632 -20.742656)
		(width 0.089408)
		(layer "In4.Cu")
		(net "SMB_VR_STBY_LVC3_SDA")
	)
	(segment
		(start 413.642556 -85.504274)
		(end 417.429442 -85.504274)
		(width 0.089408)
		(layer "In4.Cu")
		(net "SMB_VR_STBY_LVC3_SDA")
	)
	(segment
		(start 173.4312 -47.7012)
		(end 173.4312 -37.5666)
		(width 0.089408)
		(layer "In4.Cu")
		(net "SMB_VR_STBY_LVC3_SDA")
	)
	(segment
		(start 402.73478 -85.909404)
		(end 404.646384 -85.909404)
		(width 0.089408)
		(layer "In4.Cu")
		(net "SMB_VR_STBY_LVC3_SDA")
	)
	(segment
		(start 405.664924 -86.927944)
		(end 410.023056 -86.927944)
		(width 0.089408)
		(layer "In4.Cu")
		(net "SMB_VR_STBY_LVC3_SDA")
	)
	(segment
		(start 403.047708 -158.598108)
		(end 463.277204 -158.598108)
		(width 0.089408)
		(layer "In4.Cu")
		(net "SMB_VR_STBY_LVC3_SDA")
	)
	(segment
		(start 351.8154 -114.3127)
		(end 351.8154 -113.665)
		(width 0.089408)
		(layer "In4.Cu")
		(net "SMB_VR_STBY_LVC3_SDA")
	)
	(segment
		(start 173.4312 -37.5666)
		(end 184.981596 -26.016204)
		(width 0.089408)
		(layer "In4.Cu")
		(net "SMB_VR_STBY_LVC3_SDA")
	)
	(segment
		(start 410.5656 -87.470488)
		(end 411.678374 -87.470488)
		(width 0.089408)
		(layer "In4.Cu")
		(net "SMB_VR_STBY_LVC3_SDA")
	)
	(segment
		(start 185.563256 -21.6662)
		(end 187.239656 -21.6662)
		(width 0.089408)
		(layer "In4.Cu")
		(net "SMB_VR_STBY_LVC3_SDA")
	)
	(segment
		(start 427.586648 -118.153434)
		(end 429.103028 -119.669814)
		(width 0.089408)
		(layer "In4.Cu")
		(net "SMB_VR_STBY_LVC3_SDA")
	)
	(segment
		(start 470.447624 -116.559584)
		(end 471.577924 -117.689884)
		(width 0.089408)
		(layer "In4.Cu")
		(net "SMB_VR_STBY_LVC3_SDA")
	)
	(segment
		(start 176.166272 -71.465948)
		(end 176.166272 -67.739514)
		(width 0.089408)
		(layer "In4.Cu")
		(net "SMB_VR_STBY_LVC3_SDA")
	)
	(segment
		(start 429.103028 -119.669814)
		(end 432.611276 -119.669814)
		(width 0.089408)
		(layer "In4.Cu")
		(net "SMB_VR_STBY_LVC3_SDA")
	)
	(segment
		(start 404.646384 -85.909404)
		(end 405.664924 -86.927944)
		(width 0.089408)
		(layer "In4.Cu")
		(net "SMB_VR_STBY_LVC3_SDA")
	)
	(segment
		(start 402.305774 -85.480398)
		(end 402.73478 -85.909404)
		(width 0.089408)
		(layer "In4.Cu")
		(net "SMB_VR_STBY_LVC3_SDA")
	)
	(segment
		(start 397.794226 -85.89772)
		(end 399.067274 -85.89772)
		(width 0.089408)
		(layer "In4.Cu")
		(net "SMB_VR_STBY_LVC3_SDA")
	)
	(segment
		(start 471.372946 -150.209758)
		(end 465.511896 -156.070808)
		(width 0.089408)
		(layer "In4.Cu")
		(net "SMB_VR_STBY_LVC3_SDA")
	)
	(segment
		(start 421.435784 -99.61753)
		(end 421.76573 -99.61753)
		(width 0.089408)
		(layer "In4.Cu")
		(net "SMB_VR_STBY_LVC3_SDA")
	)
	(segment
		(start 474.955616 -127.148336)
		(end 473.141802 -128.96215)
		(width 0.089408)
		(layer "In4.Cu")
		(net "SMB_VR_STBY_LVC3_SDA")
	)
	(segment
		(start 193.034666 -7.75208)
		(end 192.205356 -6.92277)
		(width 0.089408)
		(layer "In4.Cu")
		(net "SMB_VR_STBY_LVC3_SDA")
	)
	(segment
		(start 351.0915 -115.0366)
		(end 351.8154 -114.3127)
		(width 0.089408)
		(layer "In4.Cu")
		(net "SMB_VR_STBY_LVC3_SDA")
	)
	(segment
		(start 175.272192 -72.149462)
		(end 175.514254 -71.9074)
		(width 0.089408)
		(layer "In4.Cu")
		(net "SMB_VR_STBY_LVC3_SDA")
	)
	(segment
		(start 465.475066 -116.559584)
		(end 470.447624 -116.559584)
		(width 0.089408)
		(layer "In4.Cu")
		(net "SMB_VR_STBY_LVC3_SDA")
	)
	(segment
		(start 441.525406 -116.415566)
		(end 442.473588 -115.467384)
		(width 0.089408)
		(layer "In4.Cu")
		(net "SMB_VR_STBY_LVC3_SDA")
	)
	(segment
		(start 471.577924 -117.689884)
		(end 472.729306 -117.689884)
		(width 0.089408)
		(layer "In4.Cu")
		(net "SMB_VR_STBY_LVC3_SDA")
	)
	(segment
		(start 399.51533 -85.449664)
		(end 400.46021 -85.449664)
		(width 0.089408)
		(layer "In4.Cu")
		(net "SMB_VR_STBY_LVC3_SDA")
	)
	(segment
		(start 465.511896 -156.070808)
		(end 465.511896 -156.363416)
		(width 0.089408)
		(layer "In4.Cu")
		(net "SMB_VR_STBY_LVC3_SDA")
	)
	(segment
		(start 351.0915 -118.6688)
		(end 351.0915 -115.0366)
		(width 0.089408)
		(layer "In4.Cu")
		(net "SMB_VR_STBY_LVC3_SDA")
	)
	(segment
		(start 474.049598 -119.010176)
		(end 474.049598 -123.132342)
		(width 0.089408)
		(layer "In4.Cu")
		(net "SMB_VR_STBY_LVC3_SDA")
	)
	(segment
		(start 400.46021 -85.449664)
		(end 400.490944 -85.480398)
		(width 0.089408)
		(layer "In4.Cu")
		(net "SMB_VR_STBY_LVC3_SDA")
	)
	(segment
		(start 442.473588 -115.467384)
		(end 464.382866 -115.467384)
		(width 0.089408)
		(layer "In4.Cu")
		(net "SMB_VR_STBY_LVC3_SDA")
	)
	(segment
		(start 473.141802 -130.65633)
		(end 473.458794 -130.973322)
		(width 0.089408)
		(layer "In4.Cu")
		(net "SMB_VR_STBY_LVC3_SDA")
	)
	(segment
		(start 397.764 -86.614)
		(end 397.503904 -86.353904)
		(width 0.089408)
		(layer "In4.Cu")
		(net "SMB_VR_STBY_LVC3_SDA")
	)
	(segment
		(start 471.59164 -150.209758)
		(end 471.372946 -150.209758)
		(width 0.089408)
		(layer "In4.Cu")
		(net "SMB_VR_STBY_LVC3_SDA")
	)
	(segment
		(start 474.049598 -123.132342)
		(end 474.955616 -124.03836)
		(width 0.089408)
		(layer "In4.Cu")
		(net "SMB_VR_STBY_LVC3_SDA")
	)
	(segment
		(start 397.503904 -86.353904)
		(end 397.503904 -86.188042)
		(width 0.089408)
		(layer "In4.Cu")
		(net "SMB_VR_STBY_LVC3_SDA")
	)
	(segment
		(start 192.205356 -6.92277)
		(end 192.205356 -5.87502)
		(width 0.089408)
		(layer "In4.Cu")
		(net "SMB_VR_STBY_LVC3_SDA")
	)
	(segment
		(start 21.4376 -136.8806)
		(end 20.6756 -136.1186)
		(width 0.089408)
		(layer "In9.Cu")
		(net "SMB_VR_STBY_LVC3_SDA")
	)
	(segment
		(start 346.465398 -115.628928)
		(end 347.298772 -115.628928)
		(width 0.089408)
		(layer "In9.Cu")
		(net "SMB_VR_STBY_LVC3_SDA")
	)
	(segment
		(start 382.5494 -149.471634)
		(end 390.962134 -149.471634)
		(width 0.089408)
		(layer "In9.Cu")
		(net "SMB_VR_STBY_LVC3_SDA")
	)
	(segment
		(start 262.335264 -137.934192)
		(end 322.059808 -137.934192)
		(width 0.089408)
		(layer "In9.Cu")
		(net "SMB_VR_STBY_LVC3_SDA")
	)
	(segment
		(start 29.044392 -154.647392)
		(end 26.67 -152.273)
		(width 0.089408)
		(layer "In9.Cu")
		(net "SMB_VR_STBY_LVC3_SDA")
	)
	(segment
		(start 188.214508 -133.24332)
		(end 189.645798 -133.24332)
		(width 0.089408)
		(layer "In9.Cu")
		(net "SMB_VR_STBY_LVC3_SDA")
	)
	(segment
		(start 347.2688 -81.6864)
		(end 346.964 -81.9912)
		(width 0.089408)
		(layer "In9.Cu")
		(net "SMB_VR_STBY_LVC3_SDA")
	)
	(segment
		(start 334.899 -129.502662)
		(end 338.620354 -125.781308)
		(width 0.089408)
		(layer "In9.Cu")
		(net "SMB_VR_STBY_LVC3_SDA")
	)
	(segment
		(start 343.726516 -84.741512)
		(end 343.726516 -99.744784)
		(width 0.089408)
		(layer "In9.Cu")
		(net "SMB_VR_STBY_LVC3_SDA")
	)
	(segment
		(start 159.034988 -156.375608)
		(end 99.568 -156.375608)
		(width 0.089408)
		(layer "In9.Cu")
		(net "SMB_VR_STBY_LVC3_SDA")
	)
	(segment
		(start 322.059808 -137.934192)
		(end 323.531992 -136.462008)
		(width 0.089408)
		(layer "In9.Cu")
		(net "SMB_VR_STBY_LVC3_SDA")
	)
	(segment
		(start 368.5921 -145.5928)
		(end 368.8715 -145.3134)
		(width 0.089408)
		(layer "In9.Cu")
		(net "SMB_VR_STBY_LVC3_SDA")
	)
	(segment
		(start 344.320114 -130.090164)
		(end 347.887036 -130.090164)
		(width 0.089408)
		(layer "In9.Cu")
		(net "SMB_VR_STBY_LVC3_SDA")
	)
	(segment
		(start 183.239156 -129.282444)
		(end 183.096408 -129.425192)
		(width 0.089408)
		(layer "In9.Cu")
		(net "SMB_VR_STBY_LVC3_SDA")
	)
	(segment
		(start 323.531992 -135.664702)
		(end 325.921624 -133.27507)
		(width 0.089408)
		(layer "In9.Cu")
		(net "SMB_VR_STBY_LVC3_SDA")
	)
	(segment
		(start 3.546094 -134.591044)
		(end 2.129282 -134.591044)
		(width 0.089408)
		(layer "In9.Cu")
		(net "SMB_VR_STBY_LVC3_SDA")
	)
	(segment
		(start 351.226882 -114.253518)
		(end 351.8154 -113.665)
		(width 0.089408)
		(layer "In9.Cu")
		(net "SMB_VR_STBY_LVC3_SDA")
	)
	(segment
		(start 259.730494 -138.563096)
		(end 260.48081 -139.313412)
		(width 0.089408)
		(layer "In9.Cu")
		(net "SMB_VR_STBY_LVC3_SDA")
	)
	(segment
		(start 356.610158 -129.965958)
		(end 356.3493 -129.7051)
		(width 0.089408)
		(layer "In9.Cu")
		(net "SMB_VR_STBY_LVC3_SDA")
	)
	(segment
		(start 346.964 -82.55)
		(end 346.01404 -83.49996)
		(width 0.089408)
		(layer "In9.Cu")
		(net "SMB_VR_STBY_LVC3_SDA")
	)
	(segment
		(start 351.226882 -115.253008)
		(end 351.226882 -114.253518)
		(width 0.089408)
		(layer "In9.Cu")
		(net "SMB_VR_STBY_LVC3_SDA")
	)
	(segment
		(start 342.40343 -103.45293)
		(end 346.2401 -107.2896)
		(width 0.089408)
		(layer "In9.Cu")
		(net "SMB_VR_STBY_LVC3_SDA")
	)
	(segment
		(start 0.733298 -132.304028)
		(end 1.713992 -131.323334)
		(width 0.089408)
		(layer "In9.Cu")
		(net "SMB_VR_STBY_LVC3_SDA")
	)
	(segment
		(start 342.40343 -101.06787)
		(end 342.40343 -103.45293)
		(width 0.089408)
		(layer "In9.Cu")
		(net "SMB_VR_STBY_LVC3_SDA")
	)
	(segment
		(start 346.2401 -115.40363)
		(end 346.465398 -115.628928)
		(width 0.089408)
		(layer "In9.Cu")
		(net "SMB_VR_STBY_LVC3_SDA")
	)
	(segment
		(start 19.05254 -136.1186)
		(end 17.763744 -134.829804)
		(width 0.089408)
		(layer "In9.Cu")
		(net "SMB_VR_STBY_LVC3_SDA")
	)
	(segment
		(start 344.31986 -130.090418)
		(end 344.320114 -130.090164)
		(width 0.089408)
		(layer "In9.Cu")
		(net "SMB_VR_STBY_LVC3_SDA")
	)
	(segment
		(start 346.2401 -107.2896)
		(end 346.2401 -115.40363)
		(width 0.089408)
		(layer "In9.Cu")
		(net "SMB_VR_STBY_LVC3_SDA")
	)
	(segment
		(start 259.73024 -138.563096)
		(end 259.730494 -138.563096)
		(width 0.089408)
		(layer "In9.Cu")
		(net "SMB_VR_STBY_LVC3_SDA")
	)
	(segment
		(start 347.318076 -115.648232)
		(end 350.831912 -115.648232)
		(width 0.089408)
		(layer "In9.Cu")
		(net "SMB_VR_STBY_LVC3_SDA")
	)
	(segment
		(start 325.921624 -133.27507)
		(end 329.92568 -133.27507)
		(width 0.089408)
		(layer "In9.Cu")
		(net "SMB_VR_STBY_LVC3_SDA")
	)
	(segment
		(start 2.129282 -134.591044)
		(end 0.733298 -133.19506)
		(width 0.089408)
		(layer "In9.Cu")
		(net "SMB_VR_STBY_LVC3_SDA")
	)
	(segment
		(start 10.895076 -133.91769)
		(end 4.219448 -133.91769)
		(width 0.089408)
		(layer "In9.Cu")
		(net "SMB_VR_STBY_LVC3_SDA")
	)
	(segment
		(start 190.975234 -134.572756)
		(end 190.975234 -137.19302)
		(width 0.089408)
		(layer "In9.Cu")
		(net "SMB_VR_STBY_LVC3_SDA")
	)
	(segment
		(start 99.568 -156.375608)
		(end 99.314 -156.629608)
		(width 0.089408)
		(layer "In9.Cu")
		(net "SMB_VR_STBY_LVC3_SDA")
	)
	(segment
		(start 260.956044 -139.313412)
		(end 262.335264 -137.934192)
		(width 0.089408)
		(layer "In9.Cu")
		(net "SMB_VR_STBY_LVC3_SDA")
	)
	(segment
		(start 26.67 -152.273)
		(end 23.064724 -152.273)
		(width 0.089408)
		(layer "In9.Cu")
		(net "SMB_VR_STBY_LVC3_SDA")
	)
	(segment
		(start 165.393878 -127.573024)
		(end 164.749226 -126.928372)
		(width 0.089408)
		(layer "In9.Cu")
		(net "SMB_VR_STBY_LVC3_SDA")
	)
	(segment
		(start 183.239156 -129.282444)
		(end 185.56732 -131.610608)
		(width 0.089408)
		(layer "In9.Cu")
		(net "SMB_VR_STBY_LVC3_SDA")
	)
	(segment
		(start 332.631034 -129.502662)
		(end 334.899 -129.502662)
		(width 0.089408)
		(layer "In9.Cu")
		(net "SMB_VR_STBY_LVC3_SDA")
	)
	(segment
		(start 259.20192 -138.034776)
		(end 259.73024 -138.563096)
		(width 0.089408)
		(layer "In9.Cu")
		(net "SMB_VR_STBY_LVC3_SDA")
	)
	(segment
		(start 344.968068 -83.49996)
		(end 343.726516 -84.741512)
		(width 0.089408)
		(layer "In9.Cu")
		(net "SMB_VR_STBY_LVC3_SDA")
	)
	(segment
		(start 372.583456 -147.68449)
		(end 380.762256 -147.68449)
		(width 0.089408)
		(layer "In9.Cu")
		(net "SMB_VR_STBY_LVC3_SDA")
	)
	(segment
		(start 21.4376 -150.645876)
		(end 21.4376 -136.8806)
		(width 0.089408)
		(layer "In9.Cu")
		(net "SMB_VR_STBY_LVC3_SDA")
	)
	(segment
		(start 183.096408 -129.425192)
		(end 176.691798 -129.425192)
		(width 0.089408)
		(layer "In9.Cu")
		(net "SMB_VR_STBY_LVC3_SDA")
	)
	(segment
		(start 176.691544 -129.424938)
		(end 176.391062 -129.424938)
		(width 0.089408)
		(layer "In9.Cu")
		(net "SMB_VR_STBY_LVC3_SDA")
	)
	(segment
		(start 356.610158 -130.09245)
		(end 356.610158 -129.965958)
		(width 0.089408)
		(layer "In9.Cu")
		(net "SMB_VR_STBY_LVC3_SDA")
	)
	(segment
		(start 343.101422 -129.114296)
		(end 344.077544 -130.090418)
		(width 0.089408)
		(layer "In9.Cu")
		(net "SMB_VR_STBY_LVC3_SDA")
	)
	(segment
		(start 17.763744 -134.829804)
		(end 11.80719 -134.829804)
		(width 0.089408)
		(layer "In9.Cu")
		(net "SMB_VR_STBY_LVC3_SDA")
	)
	(segment
		(start 342.092026 -125.781308)
		(end 343.101422 -126.790704)
		(width 0.089408)
		(layer "In9.Cu")
		(net "SMB_VR_STBY_LVC3_SDA")
	)
	(segment
		(start 20.6756 -136.1186)
		(end 19.05254 -136.1186)
		(width 0.089408)
		(layer "In9.Cu")
		(net "SMB_VR_STBY_LVC3_SDA")
	)
	(segment
		(start 347.298772 -115.628928)
		(end 347.318076 -115.648232)
		(width 0.089408)
		(layer "In9.Cu")
		(net "SMB_VR_STBY_LVC3_SDA")
	)
	(segment
		(start 331.392022 -130.741674)
		(end 332.631034 -129.502662)
		(width 0.089408)
		(layer "In9.Cu")
		(net "SMB_VR_STBY_LVC3_SDA")
	)
	(segment
		(start 191.81699 -138.034776)
		(end 259.20192 -138.034776)
		(width 0.089408)
		(layer "In9.Cu")
		(net "SMB_VR_STBY_LVC3_SDA")
	)
	(segment
		(start 29.044392 -155.536646)
		(end 29.044392 -154.647392)
		(width 0.089408)
		(layer "In9.Cu")
		(net "SMB_VR_STBY_LVC3_SDA")
	)
	(segment
		(start 352.94443 -129.70637)
		(end 354.41382 -131.17576)
		(width 0.089408)
		(layer "In9.Cu")
		(net "SMB_VR_STBY_LVC3_SDA")
	)
	(segment
		(start 343.101422 -126.790704)
		(end 343.101422 -129.114296)
		(width 0.089408)
		(layer "In9.Cu")
		(net "SMB_VR_STBY_LVC3_SDA")
	)
	(segment
		(start 99.314 -156.629608)
		(end 30.137354 -156.629608)
		(width 0.089408)
		(layer "In9.Cu")
		(net "SMB_VR_STBY_LVC3_SDA")
	)
	(segment
		(start 350.831912 -115.648232)
		(end 351.226882 -115.253008)
		(width 0.089408)
		(layer "In9.Cu")
		(net "SMB_VR_STBY_LVC3_SDA")
	)
	(segment
		(start 23.064724 -152.273)
		(end 21.4376 -150.645876)
		(width 0.089408)
		(layer "In9.Cu")
		(net "SMB_VR_STBY_LVC3_SDA")
	)
	(segment
		(start 11.80719 -134.829804)
		(end 10.895076 -133.91769)
		(width 0.089408)
		(layer "In9.Cu")
		(net "SMB_VR_STBY_LVC3_SDA")
	)
	(segment
		(start 344.077544 -130.090418)
		(end 344.31986 -130.090418)
		(width 0.089408)
		(layer "In9.Cu")
		(net "SMB_VR_STBY_LVC3_SDA")
	)
	(segment
		(start 331.392022 -131.808728)
		(end 331.392022 -130.741674)
		(width 0.089408)
		(layer "In9.Cu")
		(net "SMB_VR_STBY_LVC3_SDA")
	)
	(segment
		(start 348.27083 -129.70637)
		(end 352.94443 -129.70637)
		(width 0.089408)
		(layer "In9.Cu")
		(net "SMB_VR_STBY_LVC3_SDA")
	)
	(segment
		(start 394.275564 -149.6949)
		(end 394.806932 -149.163532)
		(width 0.089408)
		(layer "In9.Cu")
		(net "SMB_VR_STBY_LVC3_SDA")
	)
	(segment
		(start 391.1854 -149.6949)
		(end 394.275564 -149.6949)
		(width 0.089408)
		(layer "In9.Cu")
		(net "SMB_VR_STBY_LVC3_SDA")
	)
	(segment
		(start 189.645798 -133.24332)
		(end 190.975234 -134.572756)
		(width 0.089408)
		(layer "In9.Cu")
		(net "SMB_VR_STBY_LVC3_SDA")
	)
	(segment
		(start 346.964 -81.9912)
		(end 346.964 -82.55)
		(width 0.089408)
		(layer "In9.Cu")
		(net "SMB_VR_STBY_LVC3_SDA")
	)
	(segment
		(start 355.259894 -131.17576)
		(end 356.096316 -130.339338)
		(width 0.089408)
		(layer "In9.Cu")
		(net "SMB_VR_STBY_LVC3_SDA")
	)
	(segment
		(start 380.762256 -147.68449)
		(end 382.5494 -149.471634)
		(width 0.089408)
		(layer "In9.Cu")
		(net "SMB_VR_STBY_LVC3_SDA")
	)
	(segment
		(start 343.726516 -99.744784)
		(end 342.40343 -101.06787)
		(width 0.089408)
		(layer "In9.Cu")
		(net "SMB_VR_STBY_LVC3_SDA")
	)
	(segment
		(start 30.137354 -156.629608)
		(end 29.044392 -155.536646)
		(width 0.089408)
		(layer "In9.Cu")
		(net "SMB_VR_STBY_LVC3_SDA")
	)
	(segment
		(start 0.733298 -133.19506)
		(end 0.733298 -132.304028)
		(width 0.089408)
		(layer "In9.Cu")
		(net "SMB_VR_STBY_LVC3_SDA")
	)
	(segment
		(start 4.219448 -133.91769)
		(end 3.546094 -134.591044)
		(width 0.089408)
		(layer "In9.Cu")
		(net "SMB_VR_STBY_LVC3_SDA")
	)
	(segment
		(start 176.391062 -129.424938)
		(end 174.917862 -130.898138)
		(width 0.089408)
		(layer "In9.Cu")
		(net "SMB_VR_STBY_LVC3_SDA")
	)
	(segment
		(start 190.975234 -137.19302)
		(end 191.81699 -138.034776)
		(width 0.089408)
		(layer "In9.Cu")
		(net "SMB_VR_STBY_LVC3_SDA")
	)
	(segment
		(start 159.43707 -155.441142)
		(end 159.43707 -155.973526)
		(width 0.089408)
		(layer "In9.Cu")
		(net "SMB_VR_STBY_LVC3_SDA")
	)
	(segment
		(start 390.962134 -149.471634)
		(end 391.1854 -149.6949)
		(width 0.089408)
		(layer "In9.Cu")
		(net "SMB_VR_STBY_LVC3_SDA")
	)
	(segment
		(start 164.749226 -126.928372)
		(end 164.139372 -126.928372)
		(width 0.089408)
		(layer "In9.Cu")
		(net "SMB_VR_STBY_LVC3_SDA")
	)
	(segment
		(start 159.43707 -155.973526)
		(end 159.034988 -156.375608)
		(width 0.089408)
		(layer "In9.Cu")
		(net "SMB_VR_STBY_LVC3_SDA")
	)
	(segment
		(start 356.36327 -130.339338)
		(end 356.610158 -130.09245)
		(width 0.089408)
		(layer "In9.Cu")
		(net "SMB_VR_STBY_LVC3_SDA")
	)
	(segment
		(start 356.096316 -130.339338)
		(end 356.36327 -130.339338)
		(width 0.089408)
		(layer "In9.Cu")
		(net "SMB_VR_STBY_LVC3_SDA")
	)
	(segment
		(start 370.212366 -145.3134)
		(end 372.583456 -147.68449)
		(width 0.089408)
		(layer "In9.Cu")
		(net "SMB_VR_STBY_LVC3_SDA")
	)
	(segment
		(start 347.887036 -130.090164)
		(end 348.27083 -129.70637)
		(width 0.089408)
		(layer "In9.Cu")
		(net "SMB_VR_STBY_LVC3_SDA")
	)
	(segment
		(start 185.56732 -131.610608)
		(end 186.581796 -131.610608)
		(width 0.089408)
		(layer "In9.Cu")
		(net "SMB_VR_STBY_LVC3_SDA")
	)
	(segment
		(start 170.988482 -130.898138)
		(end 167.663368 -127.573024)
		(width 0.089408)
		(layer "In9.Cu")
		(net "SMB_VR_STBY_LVC3_SDA")
	)
	(segment
		(start 174.917862 -130.898138)
		(end 170.988482 -130.898138)
		(width 0.089408)
		(layer "In9.Cu")
		(net "SMB_VR_STBY_LVC3_SDA")
	)
	(segment
		(start 186.581796 -131.610608)
		(end 188.214508 -133.24332)
		(width 0.089408)
		(layer "In9.Cu")
		(net "SMB_VR_STBY_LVC3_SDA")
	)
	(segment
		(start 368.8715 -145.3134)
		(end 370.212366 -145.3134)
		(width 0.089408)
		(layer "In9.Cu")
		(net "SMB_VR_STBY_LVC3_SDA")
	)
	(segment
		(start 338.620354 -125.781308)
		(end 342.092026 -125.781308)
		(width 0.089408)
		(layer "In9.Cu")
		(net "SMB_VR_STBY_LVC3_SDA")
	)
	(segment
		(start 176.691798 -129.425192)
		(end 176.691544 -129.424938)
		(width 0.089408)
		(layer "In9.Cu")
		(net "SMB_VR_STBY_LVC3_SDA")
	)
	(segment
		(start 346.01404 -83.49996)
		(end 344.968068 -83.49996)
		(width 0.089408)
		(layer "In9.Cu")
		(net "SMB_VR_STBY_LVC3_SDA")
	)
	(segment
		(start 354.41382 -131.17576)
		(end 355.259894 -131.17576)
		(width 0.089408)
		(layer "In9.Cu")
		(net "SMB_VR_STBY_LVC3_SDA")
	)
	(segment
		(start 323.531992 -136.462008)
		(end 323.531992 -135.664702)
		(width 0.089408)
		(layer "In9.Cu")
		(net "SMB_VR_STBY_LVC3_SDA")
	)
	(segment
		(start 164.139372 -126.928372)
		(end 164.1348 -126.9238)
		(width 0.089408)
		(layer "In9.Cu")
		(net "SMB_VR_STBY_LVC3_SDA")
	)
	(segment
		(start 329.92568 -133.27507)
		(end 331.392022 -131.808728)
		(width 0.089408)
		(layer "In9.Cu")
		(net "SMB_VR_STBY_LVC3_SDA")
	)
	(segment
		(start 167.663368 -127.573024)
		(end 165.393878 -127.573024)
		(width 0.089408)
		(layer "In9.Cu")
		(net "SMB_VR_STBY_LVC3_SDA")
	)
	(segment
		(start 260.48081 -139.313412)
		(end 260.956044 -139.313412)
		(width 0.089408)
		(layer "In9.Cu")
		(net "SMB_VR_STBY_LVC3_SDA")
	)
	(segment
		(start 370.523516 -10.273284)
		(end 370.523516 -8.842248)
		(width 0.089408)
		(layer "In11.Cu")
		(net "SMB_VR_STBY_LVC3_SDA")
	)
	(segment
		(start 329.84821 -4.514596)
		(end 329.84821 -1.363218)
		(width 0.089408)
		(layer "In11.Cu")
		(net "SMB_VR_STBY_LVC3_SDA")
	)
	(segment
		(start 16.948912 -43.04411)
		(end 16.948912 -46.834298)
		(width 0.089408)
		(layer "In11.Cu")
		(net "SMB_VR_STBY_LVC3_SDA")
	)
	(segment
		(start 344.925904 -20.992592)
		(end 344.925904 -20.231862)
		(width 0.089408)
		(layer "In11.Cu")
		(net "SMB_VR_STBY_LVC3_SDA")
	)
	(segment
		(start 340.528656 -18.51152)
		(end 340.528656 -14.555724)
		(width 0.089408)
		(layer "In11.Cu")
		(net "SMB_VR_STBY_LVC3_SDA")
	)
	(segment
		(start 1.339088 -130.480054)
		(end 0.76962 -129.910586)
		(width 0.089408)
		(layer "In11.Cu")
		(net "SMB_VR_STBY_LVC3_SDA")
	)
	(segment
		(start 14.583664 -105.51541)
		(end 13.848842 -104.780588)
		(width 0.089408)
		(layer "In11.Cu")
		(net "SMB_VR_STBY_LVC3_SDA")
	)
	(segment
		(start 13.848842 -104.780588)
		(end 13.439394 -104.780588)
		(width 0.089408)
		(layer "In11.Cu")
		(net "SMB_VR_STBY_LVC3_SDA")
	)
	(segment
		(start 14.97584 -29.458412)
		(end 14.966696 -29.467556)
		(width 0.089408)
		(layer "In11.Cu")
		(net "SMB_VR_STBY_LVC3_SDA")
	)
	(segment
		(start 12.329668 -70.949312)
		(end 11.83132 -71.44766)
		(width 0.089408)
		(layer "In11.Cu")
		(net "SMB_VR_STBY_LVC3_SDA")
	)
	(segment
		(start 362.645198 -27.683714)
		(end 362.645198 -18.151602)
		(width 0.089408)
		(layer "In11.Cu")
		(net "SMB_VR_STBY_LVC3_SDA")
	)
	(segment
		(start 363.325156 -140.885672)
		(end 359.664 -137.224516)
		(width 0.089408)
		(layer "In11.Cu")
		(net "SMB_VR_STBY_LVC3_SDA")
	)
	(segment
		(start 0.195834 -125.654562)
		(end 2.68351 -125.654562)
		(width 0.089408)
		(layer "In11.Cu")
		(net "SMB_VR_STBY_LVC3_SDA")
	)
	(segment
		(start 363.907324 -140.885672)
		(end 363.325156 -140.885672)
		(width 0.089408)
		(layer "In11.Cu")
		(net "SMB_VR_STBY_LVC3_SDA")
	)
	(segment
		(start 359.664 -137.224516)
		(end 359.664 -132.7404)
		(width 0.089408)
		(layer "In11.Cu")
		(net "SMB_VR_STBY_LVC3_SDA")
	)
	(segment
		(start 329.3999 4.577842)
		(end 328.670666 5.307076)
		(width 0.089408)
		(layer "In11.Cu")
		(net "SMB_VR_STBY_LVC3_SDA")
	)
	(segment
		(start 22.36216 -5.742178)
		(end 22.36216 -21.470366)
		(width 0.089408)
		(layer "In11.Cu")
		(net "SMB_VR_STBY_LVC3_SDA")
	)
	(segment
		(start 14.814296 -1.619758)
		(end 14.814296 -4.669282)
		(width 0.089408)
		(layer "In11.Cu")
		(net "SMB_VR_STBY_LVC3_SDA")
	)
	(segment
		(start 402.705316 -13.884656)
		(end 417.27882 -13.884656)
		(width 0.089408)
		(layer "In11.Cu")
		(net "SMB_VR_STBY_LVC3_SDA")
	)
	(segment
		(start 368.5921 -145.5928)
		(end 368.3889 -145.3896)
		(width 0.089408)
		(layer "In11.Cu")
		(net "SMB_VR_STBY_LVC3_SDA")
	)
	(segment
		(start 345.015312 -21.082)
		(end 344.925904 -20.992592)
		(width 0.089408)
		(layer "In11.Cu")
		(net "SMB_VR_STBY_LVC3_SDA")
	)
	(segment
		(start 332.329028 -8.755634)
		(end 331.204824 -8.755634)
		(width 0.089408)
		(layer "In11.Cu")
		(net "SMB_VR_STBY_LVC3_SDA")
	)
	(segment
		(start 372.306088 -7.059676)
		(end 379.875796 -7.059676)
		(width 0.089408)
		(layer "In11.Cu")
		(net "SMB_VR_STBY_LVC3_SDA")
	)
	(segment
		(start 11.83132 -79.96428)
		(end 13.0556 -81.18856)
		(width 0.089408)
		(layer "In11.Cu")
		(net "SMB_VR_STBY_LVC3_SDA")
	)
	(segment
		(start 379.875796 -7.059676)
		(end 381.58166 -8.76554)
		(width 0.089408)
		(layer "In11.Cu")
		(net "SMB_VR_STBY_LVC3_SDA")
	)
	(segment
		(start -0.271272 -129.47396)
		(end -0.271272 -126.121668)
		(width 0.089408)
		(layer "In11.Cu")
		(net "SMB_VR_STBY_LVC3_SDA")
	)
	(segment
		(start 14.814296 -4.669282)
		(end 15.251938 -5.106924)
		(width 0.089408)
		(layer "In11.Cu")
		(net "SMB_VR_STBY_LVC3_SDA")
	)
	(segment
		(start 367.921794 -145.3896)
		(end 365.337344 -142.80515)
		(width 0.089408)
		(layer "In11.Cu")
		(net "SMB_VR_STBY_LVC3_SDA")
	)
	(segment
		(start 15.314422 -109.494574)
		(end 15.308326 -109.494574)
		(width 0.089408)
		(layer "In11.Cu")
		(net "SMB_VR_STBY_LVC3_SDA")
	)
	(segment
		(start 392.545824 -8.339836)
		(end 394.826236 -6.059424)
		(width 0.089408)
		(layer "In11.Cu")
		(net "SMB_VR_STBY_LVC3_SDA")
	)
	(segment
		(start 1.713992 -131.323334)
		(end 1.339088 -130.94843)
		(width 0.089408)
		(layer "In11.Cu")
		(net "SMB_VR_STBY_LVC3_SDA")
	)
	(segment
		(start 14.97584 -28.580588)
		(end 14.97584 -29.458412)
		(width 0.089408)
		(layer "In11.Cu")
		(net "SMB_VR_STBY_LVC3_SDA")
	)
	(segment
		(start 338.196936 -12.224004)
		(end 335.797398 -12.224004)
		(width 0.089408)
		(layer "In11.Cu")
		(net "SMB_VR_STBY_LVC3_SDA")
	)
	(segment
		(start 14.583664 -108.763816)
		(end 14.583664 -105.51541)
		(width 0.089408)
		(layer "In11.Cu")
		(net "SMB_VR_STBY_LVC3_SDA")
	)
	(segment
		(start 419.0746 -16.296894)
		(end 419.322504 -16.544798)
		(width 0.089408)
		(layer "In11.Cu")
		(net "SMB_VR_STBY_LVC3_SDA")
	)
	(segment
		(start 14.966696 -29.467556)
		(end 14.966696 -29.841444)
		(width 0.089408)
		(layer "In11.Cu")
		(net "SMB_VR_STBY_LVC3_SDA")
	)
	(segment
		(start 17.772126 -111.952278)
		(end 15.314422 -109.494574)
		(width 0.089408)
		(layer "In11.Cu")
		(net "SMB_VR_STBY_LVC3_SDA")
	)
	(segment
		(start 355.156008 -35.172904)
		(end 362.645198 -27.683714)
		(width 0.089408)
		(layer "In11.Cu")
		(net "SMB_VR_STBY_LVC3_SDA")
	)
	(segment
		(start 338.140294 -35.172904)
		(end 355.156008 -35.172904)
		(width 0.089408)
		(layer "In11.Cu")
		(net "SMB_VR_STBY_LVC3_SDA")
	)
	(segment
		(start 175.272192 -72.149462)
		(end 175.221138 -72.098408)
		(width 0.089408)
		(layer "In11.Cu")
		(net "SMB_VR_STBY_LVC3_SDA")
	)
	(segment
		(start 16.948912 -46.834298)
		(end 11.83132 -51.95189)
		(width 0.089408)
		(layer "In11.Cu")
		(net "SMB_VR_STBY_LVC3_SDA")
	)
	(segment
		(start 21.726906 -5.106924)
		(end 22.36216 -5.742178)
		(width 0.089408)
		(layer "In11.Cu")
		(net "SMB_VR_STBY_LVC3_SDA")
	)
	(segment
		(start 13.439394 -104.780588)
		(end 11.609324 -102.950518)
		(width 0.089408)
		(layer "In11.Cu")
		(net "SMB_VR_STBY_LVC3_SDA")
	)
	(segment
		(start 344.009472 -19.31543)
		(end 341.332566 -19.31543)
		(width 0.089408)
		(layer "In11.Cu")
		(net "SMB_VR_STBY_LVC3_SDA")
	)
	(segment
		(start 11.83132 -71.44766)
		(end 11.83132 -79.96428)
		(width 0.089408)
		(layer "In11.Cu")
		(net "SMB_VR_STBY_LVC3_SDA")
	)
	(segment
		(start 13.0556 -83.368896)
		(end 12.045696 -84.3788)
		(width 0.089408)
		(layer "In11.Cu")
		(net "SMB_VR_STBY_LVC3_SDA")
	)
	(segment
		(start 11.83132 -51.95189)
		(end 11.83132 -66.965322)
		(width 0.089408)
		(layer "In11.Cu")
		(net "SMB_VR_STBY_LVC3_SDA")
	)
	(segment
		(start 337.025488 -34.840926)
		(end 337.808316 -34.840926)
		(width 0.089408)
		(layer "In11.Cu")
		(net "SMB_VR_STBY_LVC3_SDA")
	)
	(segment
		(start 362.645198 -18.151602)
		(end 370.523516 -10.273284)
		(width 0.089408)
		(layer "In11.Cu")
		(net "SMB_VR_STBY_LVC3_SDA")
	)
	(segment
		(start 398.909794 -19.150584)
		(end 399.117312 -18.943066)
		(width 0.089408)
		(layer "In11.Cu")
		(net "SMB_VR_STBY_LVC3_SDA")
	)
	(segment
		(start 181.08676 5.307076)
		(end 180.65623 4.876546)
		(width 0.089408)
		(layer "In11.Cu")
		(net "SMB_VR_STBY_LVC3_SDA")
	)
	(segment
		(start 4.591304 -123.746768)
		(end 7.059168 -123.746768)
		(width 0.089408)
		(layer "In11.Cu")
		(net "SMB_VR_STBY_LVC3_SDA")
	)
	(segment
		(start 12.045696 -90.463116)
		(end 12.82954 -91.24696)
		(width 0.089408)
		(layer "In11.Cu")
		(net "SMB_VR_STBY_LVC3_SDA")
	)
	(segment
		(start 365.337344 -142.80515)
		(end 365.337344 -142.315692)
		(width 0.089408)
		(layer "In11.Cu")
		(net "SMB_VR_STBY_LVC3_SDA")
	)
	(segment
		(start 15.251938 -5.106924)
		(end 21.726906 -5.106924)
		(width 0.089408)
		(layer "In11.Cu")
		(net "SMB_VR_STBY_LVC3_SDA")
	)
	(segment
		(start 399.117312 -18.943066)
		(end 399.117312 -17.47266)
		(width 0.089408)
		(layer "In11.Cu")
		(net "SMB_VR_STBY_LVC3_SDA")
	)
	(segment
		(start 15.308326 -109.494574)
		(end 15.044166 -109.230414)
		(width 0.089408)
		(layer "In11.Cu")
		(net "SMB_VR_STBY_LVC3_SDA")
	)
	(segment
		(start 359.664 -132.7404)
		(end 359.3592 -132.4356)
		(width 0.089408)
		(layer "In11.Cu")
		(net "SMB_VR_STBY_LVC3_SDA")
	)
	(segment
		(start 390.558528 -8.76554)
		(end 390.984232 -8.339836)
		(width 0.089408)
		(layer "In11.Cu")
		(net "SMB_VR_STBY_LVC3_SDA")
	)
	(segment
		(start 331.204824 -8.755634)
		(end 330.989432 -8.540242)
		(width 0.089408)
		(layer "In11.Cu")
		(net "SMB_VR_STBY_LVC3_SDA")
	)
	(segment
		(start 168.91 -71.898256)
		(end 168.91 -72.3392)
		(width 0.089408)
		(layer "In11.Cu")
		(net "SMB_VR_STBY_LVC3_SDA")
	)
	(segment
		(start 15.044166 -109.224318)
		(end 14.583664 -108.763816)
		(width 0.089408)
		(layer "In11.Cu")
		(net "SMB_VR_STBY_LVC3_SDA")
	)
	(segment
		(start -0.271272 -126.121668)
		(end 0.195834 -125.654562)
		(width 0.089408)
		(layer "In11.Cu")
		(net "SMB_VR_STBY_LVC3_SDA")
	)
	(segment
		(start 12.045696 -84.3788)
		(end 12.045696 -90.463116)
		(width 0.089408)
		(layer "In11.Cu")
		(net "SMB_VR_STBY_LVC3_SDA")
	)
	(segment
		(start 16.171164 -0.26289)
		(end 14.814296 -1.619758)
		(width 0.089408)
		(layer "In11.Cu")
		(net "SMB_VR_STBY_LVC3_SDA")
	)
	(segment
		(start 330.989432 -5.655818)
		(end 329.84821 -4.514596)
		(width 0.089408)
		(layer "In11.Cu")
		(net "SMB_VR_STBY_LVC3_SDA")
	)
	(segment
		(start 175.094392 -72.098408)
		(end 174.699676 -72.493124)
		(width 0.089408)
		(layer "In11.Cu")
		(net "SMB_VR_STBY_LVC3_SDA")
	)
	(segment
		(start 381.58166 -8.76554)
		(end 390.558528 -8.76554)
		(width 0.089408)
		(layer "In11.Cu")
		(net "SMB_VR_STBY_LVC3_SDA")
	)
	(segment
		(start 175.221138 -72.098408)
		(end 175.094392 -72.098408)
		(width 0.089408)
		(layer "In11.Cu")
		(net "SMB_VR_STBY_LVC3_SDA")
	)
	(segment
		(start 11.83132 -66.965322)
		(end 12.329668 -67.46367)
		(width 0.089408)
		(layer "In11.Cu")
		(net "SMB_VR_STBY_LVC3_SDA")
	)
	(segment
		(start 399.117312 -17.47266)
		(end 402.705316 -13.884656)
		(width 0.089408)
		(layer "In11.Cu")
		(net "SMB_VR_STBY_LVC3_SDA")
	)
	(segment
		(start 14.966696 -29.841444)
		(end 14.915896 -29.892244)
		(width 0.089408)
		(layer "In11.Cu")
		(net "SMB_VR_STBY_LVC3_SDA")
	)
	(segment
		(start 14.97584 -22.543008)
		(end 14.97584 -28.188412)
		(width 0.089408)
		(layer "In11.Cu")
		(net "SMB_VR_STBY_LVC3_SDA")
	)
	(segment
		(start 14.966696 -28.197556)
		(end 14.966696 -28.571444)
		(width 0.089408)
		(layer "In11.Cu")
		(net "SMB_VR_STBY_LVC3_SDA")
	)
	(segment
		(start 22.36216 -21.470366)
		(end 21.549868 -22.282658)
		(width 0.089408)
		(layer "In11.Cu")
		(net "SMB_VR_STBY_LVC3_SDA")
	)
	(segment
		(start 17.772126 -119.038116)
		(end 17.772126 -111.952278)
		(width 0.089408)
		(layer "In11.Cu")
		(net "SMB_VR_STBY_LVC3_SDA")
	)
	(segment
		(start 370.523516 -8.842248)
		(end 372.306088 -7.059676)
		(width 0.089408)
		(layer "In11.Cu")
		(net "SMB_VR_STBY_LVC3_SDA")
	)
	(segment
		(start 15.044166 -109.230414)
		(end 15.044166 -109.224318)
		(width 0.089408)
		(layer "In11.Cu")
		(net "SMB_VR_STBY_LVC3_SDA")
	)
	(segment
		(start 174.699676 -72.493124)
		(end 172.309536 -72.493124)
		(width 0.089408)
		(layer "In11.Cu")
		(net "SMB_VR_STBY_LVC3_SDA")
	)
	(segment
		(start 335.797398 -12.224004)
		(end 332.329028 -8.755634)
		(width 0.089408)
		(layer "In11.Cu")
		(net "SMB_VR_STBY_LVC3_SDA")
	)
	(segment
		(start 13.0556 -81.18856)
		(end 13.0556 -83.368896)
		(width 0.089408)
		(layer "In11.Cu")
		(net "SMB_VR_STBY_LVC3_SDA")
	)
	(segment
		(start 340.528656 -14.555724)
		(end 338.196936 -12.224004)
		(width 0.089408)
		(layer "In11.Cu")
		(net "SMB_VR_STBY_LVC3_SDA")
	)
	(segment
		(start 330.989432 -8.540242)
		(end 330.989432 -5.655818)
		(width 0.089408)
		(layer "In11.Cu")
		(net "SMB_VR_STBY_LVC3_SDA")
	)
	(segment
		(start 390.984232 -8.339836)
		(end 392.545824 -8.339836)
		(width 0.089408)
		(layer "In11.Cu")
		(net "SMB_VR_STBY_LVC3_SDA")
	)
	(segment
		(start 417.27882 -13.884656)
		(end 419.0746 -15.680436)
		(width 0.089408)
		(layer "In11.Cu")
		(net "SMB_VR_STBY_LVC3_SDA")
	)
	(segment
		(start 14.915896 -41.011094)
		(end 16.948912 -43.04411)
		(width 0.089408)
		(layer "In11.Cu")
		(net "SMB_VR_STBY_LVC3_SDA")
	)
	(segment
		(start 419.0746 -15.680436)
		(end 419.0746 -16.296894)
		(width 0.089408)
		(layer "In11.Cu")
		(net "SMB_VR_STBY_LVC3_SDA")
	)
	(segment
		(start 180.529738 4.876546)
		(end 180.367178 5.039106)
		(width 0.089408)
		(layer "In11.Cu")
		(net "SMB_VR_STBY_LVC3_SDA")
	)
	(segment
		(start 12.329668 -67.46367)
		(end 12.329668 -70.949312)
		(width 0.089408)
		(layer "In11.Cu")
		(net "SMB_VR_STBY_LVC3_SDA")
	)
	(segment
		(start 169.177208 -71.631048)
		(end 168.91 -71.898256)
		(width 0.089408)
		(layer "In11.Cu")
		(net "SMB_VR_STBY_LVC3_SDA")
	)
	(segment
		(start 14.915896 -29.892244)
		(end 14.915896 -41.011094)
		(width 0.089408)
		(layer "In11.Cu")
		(net "SMB_VR_STBY_LVC3_SDA")
	)
	(segment
		(start 172.309536 -72.493124)
		(end 171.44746 -71.631048)
		(width 0.089408)
		(layer "In11.Cu")
		(net "SMB_VR_STBY_LVC3_SDA")
	)
	(segment
		(start 328.670666 5.307076)
		(end 181.08676 5.307076)
		(width 0.089408)
		(layer "In11.Cu")
		(net "SMB_VR_STBY_LVC3_SDA")
	)
	(segment
		(start 21.549868 -22.282658)
		(end 15.23619 -22.282658)
		(width 0.089408)
		(layer "In11.Cu")
		(net "SMB_VR_STBY_LVC3_SDA")
	)
	(segment
		(start 7.059168 -123.746768)
		(end 7.229094 -123.916694)
		(width 0.089408)
		(layer "In11.Cu")
		(net "SMB_VR_STBY_LVC3_SDA")
	)
	(segment
		(start 16.171164 0.317246)
		(end 16.171164 -0.26289)
		(width 0.089408)
		(layer "In11.Cu")
		(net "SMB_VR_STBY_LVC3_SDA")
	)
	(segment
		(start 2.68351 -125.654562)
		(end 4.591304 -123.746768)
		(width 0.089408)
		(layer "In11.Cu")
		(net "SMB_VR_STBY_LVC3_SDA")
	)
	(segment
		(start 11.609324 -92.467176)
		(end 12.82954 -91.24696)
		(width 0.089408)
		(layer "In11.Cu")
		(net "SMB_VR_STBY_LVC3_SDA")
	)
	(segment
		(start 341.332566 -19.31543)
		(end 340.528656 -18.51152)
		(width 0.089408)
		(layer "In11.Cu")
		(net "SMB_VR_STBY_LVC3_SDA")
	)
	(segment
		(start 337.808316 -34.840926)
		(end 338.140294 -35.172904)
		(width 0.089408)
		(layer "In11.Cu")
		(net "SMB_VR_STBY_LVC3_SDA")
	)
	(segment
		(start 15.273782 -121.53646)
		(end 17.772126 -119.038116)
		(width 0.089408)
		(layer "In11.Cu")
		(net "SMB_VR_STBY_LVC3_SDA")
	)
	(segment
		(start 15.23619 -22.282658)
		(end 14.97584 -22.543008)
		(width 0.089408)
		(layer "In11.Cu")
		(net "SMB_VR_STBY_LVC3_SDA")
	)
	(segment
		(start 171.44746 -71.631048)
		(end 169.177208 -71.631048)
		(width 0.089408)
		(layer "In11.Cu")
		(net "SMB_VR_STBY_LVC3_SDA")
	)
	(segment
		(start 7.229094 -123.916694)
		(end 9.85139 -123.916694)
		(width 0.089408)
		(layer "In11.Cu")
		(net "SMB_VR_STBY_LVC3_SDA")
	)
	(segment
		(start 368.3889 -145.3896)
		(end 367.921794 -145.3896)
		(width 0.089408)
		(layer "In11.Cu")
		(net "SMB_VR_STBY_LVC3_SDA")
	)
	(segment
		(start 11.609324 -102.950518)
		(end 11.609324 -92.467176)
		(width 0.089408)
		(layer "In11.Cu")
		(net "SMB_VR_STBY_LVC3_SDA")
	)
	(segment
		(start 14.97584 -28.188412)
		(end 14.966696 -28.197556)
		(width 0.089408)
		(layer "In11.Cu")
		(net "SMB_VR_STBY_LVC3_SDA")
	)
	(segment
		(start 419.322504 -16.544798)
		(end 419.322504 -16.570198)
		(width 0.089408)
		(layer "In11.Cu")
		(net "SMB_VR_STBY_LVC3_SDA")
	)
	(segment
		(start 15.884144 0.604266)
		(end 16.171164 0.317246)
		(width 0.089408)
		(layer "In11.Cu")
		(net "SMB_VR_STBY_LVC3_SDA")
	)
	(segment
		(start 329.3999 -0.914908)
		(end 329.3999 4.577842)
		(width 0.089408)
		(layer "In11.Cu")
		(net "SMB_VR_STBY_LVC3_SDA")
	)
	(segment
		(start 0.76962 -129.910586)
		(end 0.165354 -129.910586)
		(width 0.089408)
		(layer "In11.Cu")
		(net "SMB_VR_STBY_LVC3_SDA")
	)
	(segment
		(start 1.339088 -130.94843)
		(end 1.339088 -130.480054)
		(width 0.089408)
		(layer "In11.Cu")
		(net "SMB_VR_STBY_LVC3_SDA")
	)
	(segment
		(start 365.337344 -142.315692)
		(end 363.907324 -140.885672)
		(width 0.089408)
		(layer "In11.Cu")
		(net "SMB_VR_STBY_LVC3_SDA")
	)
	(segment
		(start 345.313 -21.082)
		(end 345.015312 -21.082)
		(width 0.089408)
		(layer "In11.Cu")
		(net "SMB_VR_STBY_LVC3_SDA")
	)
	(segment
		(start 344.925904 -20.231862)
		(end 344.009472 -19.31543)
		(width 0.089408)
		(layer "In11.Cu")
		(net "SMB_VR_STBY_LVC3_SDA")
	)
	(segment
		(start 329.84821 -1.363218)
		(end 329.3999 -0.914908)
		(width 0.089408)
		(layer "In11.Cu")
		(net "SMB_VR_STBY_LVC3_SDA")
	)
	(segment
		(start 9.85139 -123.916694)
		(end 12.231624 -121.53646)
		(width 0.089408)
		(layer "In11.Cu")
		(net "SMB_VR_STBY_LVC3_SDA")
	)
	(segment
		(start 0.165354 -129.910586)
		(end -0.271272 -129.47396)
		(width 0.089408)
		(layer "In11.Cu")
		(net "SMB_VR_STBY_LVC3_SDA")
	)
	(segment
		(start 14.966696 -28.571444)
		(end 14.97584 -28.580588)
		(width 0.089408)
		(layer "In11.Cu")
		(net "SMB_VR_STBY_LVC3_SDA")
	)
	(segment
		(start 180.65623 4.876546)
		(end 180.529738 4.876546)
		(width 0.089408)
		(layer "In11.Cu")
		(net "SMB_VR_STBY_LVC3_SDA")
	)
	(segment
		(start 336.048604 -33.864042)
		(end 337.025488 -34.840926)
		(width 0.089408)
		(layer "In11.Cu")
		(net "SMB_VR_STBY_LVC3_SDA")
	)
	(segment
		(start 12.231624 -121.53646)
		(end 15.273782 -121.53646)
		(width 0.089408)
		(layer "In11.Cu")
		(net "SMB_VR_STBY_LVC3_SDA")
	)
	(segment
		(start 359.785412 -132.796788)
		(end 360.1212 -132.461)
		(width 0.10795)
		(layer "F.Cu")
		(net "SMB_VR_STBY_LVC3_SCL")
	)
	(segment
		(start 180.618384 -68.477638)
		(end 178.673252 -68.477638)
		(width 0.10795)
		(layer "F.Cu")
		(net "SMB_VR_STBY_LVC3_SCL")
	)
	(segment
		(start 181.82463 -127.491236)
		(end 182.495952 -128.162558)
		(width 0.10795)
		(layer "F.Cu")
		(net "SMB_VR_STBY_LVC3_SCL")
	)
	(segment
		(start 181.3814 -68.850002)
		(end 180.990748 -68.850002)
		(width 0.10795)
		(layer "F.Cu")
		(net "SMB_VR_STBY_LVC3_SCL")
	)
	(segment
		(start 417.957 -17.8562)
		(end 417.5506 -17.8562)
		(width 0.10795)
		(layer "F.Cu")
		(net "SMB_VR_STBY_LVC3_SCL")
	)
	(segment
		(start 168.1988 -72.3392)
		(end 168.4782 -72.0598)
		(width 0.10795)
		(layer "F.Cu")
		(net "SMB_VR_STBY_LVC3_SCL")
	)
	(segment
		(start 180.990748 -68.850002)
		(end 180.618384 -68.477638)
		(width 0.10795)
		(layer "F.Cu")
		(net "SMB_VR_STBY_LVC3_SCL")
	)
	(segment
		(start 1.457452 -130.748786)
		(end 1.457452 -130.4163)
		(width 0.1016)
		(layer "F.Cu")
		(net "SMB_VR_STBY_LVC3_SCL")
	)
	(segment
		(start 168.771824 -70.832218)
		(end 168.4782 -71.125842)
		(width 0.10795)
		(layer "F.Cu")
		(net "SMB_VR_STBY_LVC3_SCL")
	)
	(segment
		(start 15.746476 -0.091948)
		(end 15.329662 0.324866)
		(width 0.10795)
		(layer "F.Cu")
		(net "SMB_VR_STBY_LVC3_SCL")
	)
	(segment
		(start 168.4782 -72.0598)
		(end 168.4782 -71.58228)
		(width 0.10795)
		(layer "F.Cu")
		(net "SMB_VR_STBY_LVC3_SCL")
	)
	(segment
		(start 12.98702 -0.352298)
		(end 12.4841 -0.352298)
		(width 0.10795)
		(layer "F.Cu")
		(net "SMB_VR_STBY_LVC3_SCL")
	)
	(segment
		(start 177.115978 -70.034912)
		(end 176.76368 -70.38721)
		(width 0.1016)
		(layer "F.Cu")
		(net "SMB_VR_STBY_LVC3_SCL")
	)
	(segment
		(start 168.771824 -70.358508)
		(end 168.771824 -70.832218)
		(width 0.10795)
		(layer "F.Cu")
		(net "SMB_VR_STBY_LVC3_SCL")
	)
	(segment
		(start 344.078052 -18.958052)
		(end 344.078052 -17.8181)
		(width 0.10795)
		(layer "F.Cu")
		(net "SMB_VR_STBY_LVC3_SCL")
	)
	(segment
		(start 186.2074 -115.887754)
		(end 182.68315 -119.412004)
		(width 0.10795)
		(layer "F.Cu")
		(net "SMB_VR_STBY_LVC3_SCL")
	)
	(segment
		(start 394.31341 -148.631402)
		(end 393.95146 -148.993352)
		(width 0.10795)
		(layer "F.Cu")
		(net "SMB_VR_STBY_LVC3_SCL")
	)
	(segment
		(start 16.011398 -91.456002)
		(end 16.5354 -91.456002)
		(width 0.10795)
		(layer "F.Cu")
		(net "SMB_VR_STBY_LVC3_SCL")
	)
	(segment
		(start 12.18438 -91.27363)
		(end 12.82192 -90.63609)
		(width 0.10795)
		(layer "F.Cu")
		(net "SMB_VR_STBY_LVC3_SCL")
	)
	(segment
		(start 359.80624 -134.54507)
		(end 359.991914 -134.359396)
		(width 0.10795)
		(layer "F.Cu")
		(net "SMB_VR_STBY_LVC3_SCL")
	)
	(segment
		(start 182.68315 -119.412004)
		(end 182.68315 -122.530616)
		(width 0.10795)
		(layer "F.Cu")
		(net "SMB_VR_STBY_LVC3_SCL")
	)
	(segment
		(start 351.184972 -115.55095)
		(end 351.800922 -114.935)
		(width 0.10795)
		(layer "F.Cu")
		(net "SMB_VR_STBY_LVC3_SCL")
	)
	(segment
		(start 359.80624 -135.24357)
		(end 359.80624 -134.54507)
		(width 0.10795)
		(layer "F.Cu")
		(net "SMB_VR_STBY_LVC3_SCL")
	)
	(segment
		(start 395.569694 -148.631402)
		(end 394.31341 -148.631402)
		(width 0.10795)
		(layer "F.Cu")
		(net "SMB_VR_STBY_LVC3_SCL")
	)
	(segment
		(start 13.918692 -0.42037)
		(end 13.055092 -0.42037)
		(width 0.10795)
		(layer "F.Cu")
		(net "SMB_VR_STBY_LVC3_SCL")
	)
	(segment
		(start 186.2074 -115.57)
		(end 186.2074 -115.887754)
		(width 0.10795)
		(layer "F.Cu")
		(net "SMB_VR_STBY_LVC3_SCL")
	)
	(segment
		(start 344.47988 -19.35988)
		(end 344.078052 -18.958052)
		(width 0.10795)
		(layer "F.Cu")
		(net "SMB_VR_STBY_LVC3_SCL")
	)
	(segment
		(start 359.991914 -134.359396)
		(end 359.785412 -134.152894)
		(width 0.10795)
		(layer "F.Cu")
		(net "SMB_VR_STBY_LVC3_SCL")
	)
	(segment
		(start 13.9192 -90.63609)
		(end 14.6812 -91.39809)
		(width 0.10795)
		(layer "F.Cu")
		(net "SMB_VR_STBY_LVC3_SCL")
	)
	(segment
		(start 359.898188 -135.71347)
		(end 359.898188 -135.335518)
		(width 0.10795)
		(layer "F.Cu")
		(net "SMB_VR_STBY_LVC3_SCL")
	)
	(segment
		(start 14.663928 0.324866)
		(end 13.918692 -0.42037)
		(width 0.10795)
		(layer "F.Cu")
		(net "SMB_VR_STBY_LVC3_SCL")
	)
	(segment
		(start 12.82192 -90.63609)
		(end 13.9192 -90.63609)
		(width 0.10795)
		(layer "F.Cu")
		(net "SMB_VR_STBY_LVC3_SCL")
	)
	(segment
		(start 14.6812 -91.39809)
		(end 15.953486 -91.39809)
		(width 0.10795)
		(layer "F.Cu")
		(net "SMB_VR_STBY_LVC3_SCL")
	)
	(segment
		(start 15.329662 0.324866)
		(end 14.663928 0.324866)
		(width 0.10795)
		(layer "F.Cu")
		(net "SMB_VR_STBY_LVC3_SCL")
	)
	(segment
		(start 176.76368 -70.38721)
		(end 176.76368 -71.02348)
		(width 0.1016)
		(layer "F.Cu")
		(net "SMB_VR_STBY_LVC3_SCL")
	)
	(segment
		(start 396.382748 -149.444456)
		(end 395.569694 -148.631402)
		(width 0.10795)
		(layer "F.Cu")
		(net "SMB_VR_STBY_LVC3_SCL")
	)
	(segment
		(start 418.662104 -16.909542)
		(end 418.042598 -17.529048)
		(width 0.10795)
		(layer "F.Cu")
		(net "SMB_VR_STBY_LVC3_SCL")
	)
	(segment
		(start 182.495952 -129.352294)
		(end 183.02351 -129.879852)
		(width 0.10795)
		(layer "F.Cu")
		(net "SMB_VR_STBY_LVC3_SCL")
	)
	(segment
		(start 359.785412 -134.152894)
		(end 359.785412 -132.796788)
		(width 0.10795)
		(layer "F.Cu")
		(net "SMB_VR_STBY_LVC3_SCL")
	)
	(segment
		(start 178.673252 -68.477638)
		(end 177.115978 -70.034912)
		(width 0.1016)
		(layer "F.Cu")
		(net "SMB_VR_STBY_LVC3_SCL")
	)
	(segment
		(start 13.055092 -0.42037)
		(end 12.98702 -0.352298)
		(width 0.10795)
		(layer "F.Cu")
		(net "SMB_VR_STBY_LVC3_SCL")
	)
	(segment
		(start 359.898188 -135.335518)
		(end 359.80624 -135.24357)
		(width 0.10795)
		(layer "F.Cu")
		(net "SMB_VR_STBY_LVC3_SCL")
	)
	(segment
		(start 181.82463 -123.389136)
		(end 181.82463 -127.491236)
		(width 0.10795)
		(layer "F.Cu")
		(net "SMB_VR_STBY_LVC3_SCL")
	)
	(segment
		(start 182.68315 -122.530616)
		(end 181.82463 -123.389136)
		(width 0.10795)
		(layer "F.Cu")
		(net "SMB_VR_STBY_LVC3_SCL")
	)
	(segment
		(start 176.03216 -71.755)
		(end 175.63973 -71.755)
		(width 0.1016)
		(layer "F.Cu")
		(net "SMB_VR_STBY_LVC3_SCL")
	)
	(segment
		(start 168.4782 -71.125842)
		(end 168.4782 -71.58228)
		(width 0.10795)
		(layer "F.Cu")
		(net "SMB_VR_STBY_LVC3_SCL")
	)
	(segment
		(start 175.63973 -71.755)
		(end 175.272192 -71.387462)
		(width 0.1016)
		(layer "F.Cu")
		(net "SMB_VR_STBY_LVC3_SCL")
	)
	(segment
		(start 351.800922 -114.935)
		(end 351.8154 -114.935)
		(width 0.10795)
		(layer "F.Cu")
		(net "SMB_VR_STBY_LVC3_SCL")
	)
	(segment
		(start 0.851916 -131.354322)
		(end 1.457452 -130.748786)
		(width 0.1016)
		(layer "F.Cu")
		(net "SMB_VR_STBY_LVC3_SCL")
	)
	(segment
		(start 344.7034 -20.3962)
		(end 344.47988 -20.17268)
		(width 0.10795)
		(layer "F.Cu")
		(net "SMB_VR_STBY_LVC3_SCL")
	)
	(segment
		(start 418.662104 -16.566134)
		(end 418.662104 -16.909542)
		(width 0.10795)
		(layer "F.Cu")
		(net "SMB_VR_STBY_LVC3_SCL")
	)
	(segment
		(start 418.042598 -17.529048)
		(end 418.042598 -17.770602)
		(width 0.10795)
		(layer "F.Cu")
		(net "SMB_VR_STBY_LVC3_SCL")
	)
	(segment
		(start 396.382748 -151.3459)
		(end 396.382748 -149.444456)
		(width 0.10795)
		(layer "F.Cu")
		(net "SMB_VR_STBY_LVC3_SCL")
	)
	(segment
		(start 12.18438 -91.3257)
		(end 12.18438 -91.27363)
		(width 0.10795)
		(layer "F.Cu")
		(net "SMB_VR_STBY_LVC3_SCL")
	)
	(segment
		(start 168.589452 -70.176136)
		(end 168.771824 -70.358508)
		(width 0.10795)
		(layer "F.Cu")
		(net "SMB_VR_STBY_LVC3_SCL")
	)
	(segment
		(start 15.953486 -91.39809)
		(end 16.011398 -91.456002)
		(width 0.10795)
		(layer "F.Cu")
		(net "SMB_VR_STBY_LVC3_SCL")
	)
	(segment
		(start 344.47988 -19.89582)
		(end 344.47988 -19.35988)
		(width 0.10795)
		(layer "F.Cu")
		(net "SMB_VR_STBY_LVC3_SCL")
	)
	(segment
		(start 344.297 -21.082)
		(end 344.7034 -20.6756)
		(width 0.10795)
		(layer "F.Cu")
		(net "SMB_VR_STBY_LVC3_SCL")
	)
	(segment
		(start 344.7034 -20.6756)
		(end 344.7034 -20.3962)
		(width 0.10795)
		(layer "F.Cu")
		(net "SMB_VR_STBY_LVC3_SCL")
	)
	(segment
		(start 186.205114 -115.55095)
		(end 186.2074 -115.57)
		(width 0.10795)
		(layer "F.Cu")
		(net "SMB_VR_STBY_LVC3_SCL")
	)
	(segment
		(start 418.042598 -17.770602)
		(end 417.957 -17.8562)
		(width 0.10795)
		(layer "F.Cu")
		(net "SMB_VR_STBY_LVC3_SCL")
	)
	(segment
		(start 176.76368 -71.02348)
		(end 176.03216 -71.755)
		(width 0.1016)
		(layer "F.Cu")
		(net "SMB_VR_STBY_LVC3_SCL")
	)
	(segment
		(start 344.47988 -20.17268)
		(end 344.47988 -19.89582)
		(width 0.10795)
		(layer "F.Cu")
		(net "SMB_VR_STBY_LVC3_SCL")
	)
	(segment
		(start 182.495952 -128.162558)
		(end 182.495952 -129.352294)
		(width 0.10795)
		(layer "F.Cu")
		(net "SMB_VR_STBY_LVC3_SCL")
	)
	(segment
		(start 168.589452 -69.2531)
		(end 168.589452 -70.176136)
		(width 0.10795)
		(layer "F.Cu")
		(net "SMB_VR_STBY_LVC3_SCL")
	)
	(via
		(at 177.115978 -70.034912)
		(size 0.508)
		(drill 0.254)
		(layers "F.Cu" "B.Cu")
		(net "SMB_VR_STBY_LVC3_SCL")
	)
	(via
		(at 399.561304 -19.133312)
		(size 0.508)
		(drill 0.254)
		(layers "F.Cu" "B.Cu")
		(net "SMB_VR_STBY_LVC3_SCL")
	)
	(via
		(at 368.5921 -144.7546)
		(size 0.508)
		(drill 0.254)
		(layers "F.Cu" "B.Cu")
		(net "SMB_VR_STBY_LVC3_SCL")
	)
	(via
		(at 359.991914 -134.359396)
		(size 0.762)
		(drill 0.381)
		(layers "F.Cu" "B.Cu")
		(net "SMB_VR_STBY_LVC3_SCL")
	)
	(via
		(at 418.662104 -16.566134)
		(size 0.508)
		(drill 0.254)
		(layers "F.Cu" "B.Cu")
		(net "SMB_VR_STBY_LVC3_SCL")
	)
	(via
		(at 191.43345 -5.902706)
		(size 0.508)
		(drill 0.254)
		(layers "F.Cu" "B.Cu")
		(net "SMB_VR_STBY_LVC3_SCL")
	)
	(via
		(at 164.59835 -127.40005)
		(size 0.508)
		(drill 0.254)
		(layers "F.Cu" "B.Cu")
		(net "SMB_VR_STBY_LVC3_SCL")
	)
	(via
		(at 160.014158 -155.708096)
		(size 0.508)
		(drill 0.254)
		(layers "F.Cu" "B.Cu")
		(net "SMB_VR_STBY_LVC3_SCL")
	)
	(via
		(at 397.002 -86.614)
		(size 0.508)
		(drill 0.254)
		(layers "F.Cu" "B.Cu")
		(net "SMB_VR_STBY_LVC3_SCL")
	)
	(via
		(at 394.165836 -6.059424)
		(size 0.508)
		(drill 0.254)
		(layers "F.Cu" "B.Cu")
		(net "SMB_VR_STBY_LVC3_SCL")
	)
	(via
		(at 0.851916 -131.354322)
		(size 0.508)
		(drill 0.254)
		(layers "F.Cu" "B.Cu")
		(net "SMB_VR_STBY_LVC3_SCL")
	)
	(via
		(at 15.746476 -0.091948)
		(size 0.508)
		(drill 0.254)
		(layers "F.Cu" "B.Cu")
		(net "SMB_VR_STBY_LVC3_SCL")
	)
	(via
		(at 351.8154 -114.935)
		(size 0.508)
		(drill 0.254)
		(layers "F.Cu" "B.Cu")
		(net "SMB_VR_STBY_LVC3_SCL")
	)
	(via
		(at 168.1988 -72.3392)
		(size 0.508)
		(drill 0.254)
		(layers "F.Cu" "B.Cu")
		(net "SMB_VR_STBY_LVC3_SCL")
	)
	(via
		(at 179.91582 4.522724)
		(size 0.508)
		(drill 0.254)
		(layers "F.Cu" "B.Cu")
		(net "SMB_VR_STBY_LVC3_SCL")
	)
	(via
		(at 183.02351 -129.879852)
		(size 0.508)
		(drill 0.254)
		(layers "F.Cu" "B.Cu")
		(net "SMB_VR_STBY_LVC3_SCL")
	)
	(via
		(at 168.4782 -71.58228)
		(size 0.762)
		(drill 0.381)
		(layers "F.Cu" "B.Cu")
		(net "SMB_VR_STBY_LVC3_SCL")
	)
	(via
		(at 12.18438 -91.3257)
		(size 0.508)
		(drill 0.254)
		(layers "F.Cu" "B.Cu")
		(net "SMB_VR_STBY_LVC3_SCL")
	)
	(via
		(at 336.810604 -33.864042)
		(size 0.508)
		(drill 0.254)
		(layers "F.Cu" "B.Cu")
		(net "SMB_VR_STBY_LVC3_SCL")
	)
	(via
		(at 425.776898 -113.599976)
		(size 0.508)
		(drill 0.254)
		(layers "F.Cu" "B.Cu")
		(net "SMB_VR_STBY_LVC3_SCL")
	)
	(via
		(at 344.47988 -19.89582)
		(size 0.762)
		(drill 0.381)
		(layers "F.Cu" "B.Cu")
		(net "SMB_VR_STBY_LVC3_SCL")
	)
	(via
		(at 346.3798 -81.6864)
		(size 0.508)
		(drill 0.254)
		(layers "F.Cu" "B.Cu")
		(net "SMB_VR_STBY_LVC3_SCL")
	)
	(via
		(at 360.1212 -132.461)
		(size 0.508)
		(drill 0.254)
		(layers "F.Cu" "B.Cu")
		(net "SMB_VR_STBY_LVC3_SCL")
	)
	(via
		(at 357.1113 -129.7051)
		(size 0.508)
		(drill 0.254)
		(layers "F.Cu" "B.Cu")
		(net "SMB_VR_STBY_LVC3_SCL")
	)
	(via
		(at 344.297 -21.082)
		(size 0.508)
		(drill 0.254)
		(layers "F.Cu" "B.Cu")
		(net "SMB_VR_STBY_LVC3_SCL")
	)
	(via
		(at 421.955722 -99.152456)
		(size 0.508)
		(drill 0.254)
		(layers "F.Cu" "B.Cu")
		(net "SMB_VR_STBY_LVC3_SCL")
	)
	(via
		(at 175.272192 -71.387462)
		(size 0.508)
		(drill 0.254)
		(layers "F.Cu" "B.Cu")
		(net "SMB_VR_STBY_LVC3_SCL")
	)
	(via
		(at 393.95146 -148.993352)
		(size 0.508)
		(drill 0.254)
		(layers "F.Cu" "B.Cu")
		(net "SMB_VR_STBY_LVC3_SCL")
	)
	(via
		(at 345.835732 -82.789268)
		(size 0.6604)
		(drill 0.3302)
		(layers "F.Cu" "B.Cu")
		(net "SMB_VR_STBY_LVC3_SCL")
	)
	(segment
		(start 360.1212 -132.461)
		(end 360.07294 -132.461)
		(width 0.10795)
		(layer "B.Cu")
		(net "SMB_VR_STBY_LVC3_SCL")
	)
	(segment
		(start 177.766726 -68.71462)
		(end 177.944018 -68.71462)
		(width 0.10795)
		(layer "B.Cu")
		(net "SMB_VR_STBY_LVC3_SCL")
	)
	(segment
		(start 360.07294 -132.461)
		(end 359.093262 -131.481322)
		(width 0.10795)
		(layer "B.Cu")
		(net "SMB_VR_STBY_LVC3_SCL")
	)
	(segment
		(start 175.272192 -71.387462)
		(end 175.699928 -71.387462)
		(width 0.10795)
		(layer "B.Cu")
		(net "SMB_VR_STBY_LVC3_SCL")
	)
	(segment
		(start 398.665954 -15.17015)
		(end 398.665954 -17.323054)
		(width 0.10795)
		(layer "B.Cu")
		(net "SMB_VR_STBY_LVC3_SCL")
	)
	(segment
		(start 398.45996 -19.932396)
		(end 399.013426 -19.932396)
		(width 0.10795)
		(layer "B.Cu")
		(net "SMB_VR_STBY_LVC3_SCL")
	)
	(segment
		(start 399.013426 -19.932396)
		(end 399.344642 -19.60118)
		(width 0.10795)
		(layer "B.Cu")
		(net "SMB_VR_STBY_LVC3_SCL")
	)
	(segment
		(start 176.838102 -70.251066)
		(end 176.838102 -69.643244)
		(width 0.10795)
		(layer "B.Cu")
		(net "SMB_VR_STBY_LVC3_SCL")
	)
	(segment
		(start 398.218152 -19.690588)
		(end 398.45996 -19.932396)
		(width 0.10795)
		(layer "B.Cu")
		(net "SMB_VR_STBY_LVC3_SCL")
	)
	(segment
		(start 345.7956 -82.8294)
		(end 345.7956 -84.543392)
		(width 0.10795)
		(layer "B.Cu")
		(net "SMB_VR_STBY_LVC3_SCL")
	)
	(segment
		(start 399.250662 -14.063218)
		(end 399.250662 -14.585442)
		(width 0.10795)
		(layer "B.Cu")
		(net "SMB_VR_STBY_LVC3_SCL")
	)
	(segment
		(start 176.838102 -69.643244)
		(end 177.766726 -68.71462)
		(width 0.10795)
		(layer "B.Cu")
		(net "SMB_VR_STBY_LVC3_SCL")
	)
	(segment
		(start 356.84714 -129.96926)
		(end 357.1113 -129.7051)
		(width 0.10795)
		(layer "B.Cu")
		(net "SMB_VR_STBY_LVC3_SCL")
	)
	(segment
		(start 179.91582 4.522724)
		(end 179.91582 4.248404)
		(width 0.10795)
		(layer "B.Cu")
		(net "SMB_VR_STBY_LVC3_SCL")
	)
	(segment
		(start 346.3798 -81.6864)
		(end 346.668852 -81.975452)
		(width 0.10795)
		(layer "B.Cu")
		(net "SMB_VR_STBY_LVC3_SCL")
	)
	(segment
		(start 176.086008 -71.001382)
		(end 176.087786 -71.001382)
		(width 0.10795)
		(layer "B.Cu")
		(net "SMB_VR_STBY_LVC3_SCL")
	)
	(segment
		(start 345.835732 -82.789268)
		(end 345.7956 -82.8294)
		(width 0.10795)
		(layer "B.Cu")
		(net "SMB_VR_STBY_LVC3_SCL")
	)
	(segment
		(start 400.322542 -7.840472)
		(end 400.322542 -12.991338)
		(width 0.10795)
		(layer "B.Cu")
		(net "SMB_VR_STBY_LVC3_SCL")
	)
	(segment
		(start 398.665954 -17.323054)
		(end 398.218152 -17.770856)
		(width 0.10795)
		(layer "B.Cu")
		(net "SMB_VR_STBY_LVC3_SCL")
	)
	(segment
		(start 179.324 -5.593588)
		(end 180.33365 -6.603238)
		(width 0.10795)
		(layer "B.Cu")
		(net "SMB_VR_STBY_LVC3_SCL")
	)
	(segment
		(start 179.701698 4.034282)
		(end 179.701698 -3.686302)
		(width 0.10795)
		(layer "B.Cu")
		(net "SMB_VR_STBY_LVC3_SCL")
	)
	(segment
		(start 345.8718 -82.7532)
		(end 345.835732 -82.789268)
		(width 0.10795)
		(layer "B.Cu")
		(net "SMB_VR_STBY_LVC3_SCL")
	)
	(segment
		(start 399.250662 -14.585442)
		(end 398.665954 -15.17015)
		(width 0.10795)
		(layer "B.Cu")
		(net "SMB_VR_STBY_LVC3_SCL")
	)
	(segment
		(start 399.344642 -19.60118)
		(end 399.344642 -19.349974)
		(width 0.10795)
		(layer "B.Cu")
		(net "SMB_VR_STBY_LVC3_SCL")
	)
	(segment
		(start 184.95645 -7.62635)
		(end 186.872118 -5.710682)
		(width 0.10795)
		(layer "B.Cu")
		(net "SMB_VR_STBY_LVC3_SCL")
	)
	(segment
		(start 176.087786 -71.001382)
		(end 176.838102 -70.251066)
		(width 0.10795)
		(layer "B.Cu")
		(net "SMB_VR_STBY_LVC3_SCL")
	)
	(segment
		(start 179.91582 4.248404)
		(end 179.701698 4.034282)
		(width 0.10795)
		(layer "B.Cu")
		(net "SMB_VR_STBY_LVC3_SCL")
	)
	(segment
		(start 345.7956 -84.543392)
		(end 345.932252 -84.680044)
		(width 0.10795)
		(layer "B.Cu")
		(net "SMB_VR_STBY_LVC3_SCL")
	)
	(segment
		(start 346.668852 -82.40522)
		(end 346.320872 -82.7532)
		(width 0.10795)
		(layer "B.Cu")
		(net "SMB_VR_STBY_LVC3_SCL")
	)
	(segment
		(start 397.002 -86.614)
		(end 397.002 -86.6902)
		(width 0.10795)
		(layer "B.Cu")
		(net "SMB_VR_STBY_LVC3_SCL")
	)
	(segment
		(start 177.944018 -68.71462)
		(end 178.317144 -68.341494)
		(width 0.10795)
		(layer "B.Cu")
		(net "SMB_VR_STBY_LVC3_SCL")
	)
	(segment
		(start 180.890926 -7.62635)
		(end 184.95645 -7.62635)
		(width 0.10795)
		(layer "B.Cu")
		(net "SMB_VR_STBY_LVC3_SCL")
	)
	(segment
		(start 357.624888 -131.481322)
		(end 356.84714 -130.703574)
		(width 0.10795)
		(layer "B.Cu")
		(net "SMB_VR_STBY_LVC3_SCL")
	)
	(segment
		(start 180.33365 -6.603238)
		(end 180.33365 -7.069074)
		(width 0.10795)
		(layer "B.Cu")
		(net "SMB_VR_STBY_LVC3_SCL")
	)
	(segment
		(start 186.872118 -5.710682)
		(end 191.241426 -5.710682)
		(width 0.10795)
		(layer "B.Cu")
		(net "SMB_VR_STBY_LVC3_SCL")
	)
	(segment
		(start 346.320872 -82.7532)
		(end 345.8718 -82.7532)
		(width 0.10795)
		(layer "B.Cu")
		(net "SMB_VR_STBY_LVC3_SCL")
	)
	(segment
		(start 397.002 -85.9155)
		(end 397.002 -86.614)
		(width 0.10795)
		(layer "B.Cu")
		(net "SMB_VR_STBY_LVC3_SCL")
	)
	(segment
		(start 399.344642 -19.349974)
		(end 399.561304 -19.133312)
		(width 0.10795)
		(layer "B.Cu")
		(net "SMB_VR_STBY_LVC3_SCL")
	)
	(segment
		(start 398.218152 -17.770856)
		(end 398.218152 -19.690588)
		(width 0.10795)
		(layer "B.Cu")
		(net "SMB_VR_STBY_LVC3_SCL")
	)
	(segment
		(start 394.3858 -6.279388)
		(end 394.3858 -6.77164)
		(width 0.10795)
		(layer "B.Cu")
		(net "SMB_VR_STBY_LVC3_SCL")
	)
	(segment
		(start 359.093262 -131.481322)
		(end 357.624888 -131.481322)
		(width 0.10795)
		(layer "B.Cu")
		(net "SMB_VR_STBY_LVC3_SCL")
	)
	(segment
		(start 175.699928 -71.387462)
		(end 176.086008 -71.001382)
		(width 0.10795)
		(layer "B.Cu")
		(net "SMB_VR_STBY_LVC3_SCL")
	)
	(segment
		(start 397.002 -86.6902)
		(end 397.637 -87.3252)
		(width 0.10795)
		(layer "B.Cu")
		(net "SMB_VR_STBY_LVC3_SCL")
	)
	(segment
		(start 179.324 -4.064)
		(end 179.324 -5.593588)
		(width 0.10795)
		(layer "B.Cu")
		(net "SMB_VR_STBY_LVC3_SCL")
	)
	(segment
		(start 394.3858 -6.77164)
		(end 394.81633 -7.20217)
		(width 0.10795)
		(layer "B.Cu")
		(net "SMB_VR_STBY_LVC3_SCL")
	)
	(segment
		(start 179.701698 -3.686302)
		(end 179.324 -4.064)
		(width 0.10795)
		(layer "B.Cu")
		(net "SMB_VR_STBY_LVC3_SCL")
	)
	(segment
		(start 345.932252 -84.680044)
		(end 345.932252 -85.0011)
		(width 0.10795)
		(layer "B.Cu")
		(net "SMB_VR_STBY_LVC3_SCL")
	)
	(segment
		(start 180.33365 -7.069074)
		(end 180.890926 -7.62635)
		(width 0.10795)
		(layer "B.Cu")
		(net "SMB_VR_STBY_LVC3_SCL")
	)
	(segment
		(start 399.68424 -7.20217)
		(end 400.322542 -7.840472)
		(width 0.10795)
		(layer "B.Cu")
		(net "SMB_VR_STBY_LVC3_SCL")
	)
	(segment
		(start 356.84714 -130.703574)
		(end 356.84714 -129.96926)
		(width 0.10795)
		(layer "B.Cu")
		(net "SMB_VR_STBY_LVC3_SCL")
	)
	(segment
		(start 394.165836 -6.059424)
		(end 394.3858 -6.279388)
		(width 0.10795)
		(layer "B.Cu")
		(net "SMB_VR_STBY_LVC3_SCL")
	)
	(segment
		(start 346.668852 -81.975452)
		(end 346.668852 -82.40522)
		(width 0.10795)
		(layer "B.Cu")
		(net "SMB_VR_STBY_LVC3_SCL")
	)
	(segment
		(start 191.241426 -5.710682)
		(end 191.43345 -5.902706)
		(width 0.10795)
		(layer "B.Cu")
		(net "SMB_VR_STBY_LVC3_SCL")
	)
	(segment
		(start 394.81633 -7.20217)
		(end 399.68424 -7.20217)
		(width 0.10795)
		(layer "B.Cu")
		(net "SMB_VR_STBY_LVC3_SCL")
	)
	(segment
		(start 400.322542 -12.991338)
		(end 399.250662 -14.063218)
		(width 0.10795)
		(layer "B.Cu")
		(net "SMB_VR_STBY_LVC3_SCL")
	)
	(segment
		(start 425.776898 -113.599976)
		(end 425.776898 -113.673636)
		(width 0.089408)
		(layer "In2.Cu")
		(net "SMB_VR_STBY_LVC3_SCL")
	)
	(segment
		(start 157.594808 -134.13867)
		(end 157.594808 -132.18033)
		(width 0.089408)
		(layer "In2.Cu")
		(net "SMB_VR_STBY_LVC3_SCL")
	)
	(segment
		(start 159.84601 -154.79649)
		(end 158.330392 -153.280872)
		(width 0.089408)
		(layer "In2.Cu")
		(net "SMB_VR_STBY_LVC3_SCL")
	)
	(segment
		(start 344.207592 -20.676616)
		(end 341.014304 -20.676616)
		(width 0.089408)
		(layer "In2.Cu")
		(net "SMB_VR_STBY_LVC3_SCL")
	)
	(segment
		(start 164.59835 -127.107188)
		(end 165.099746 -126.605792)
		(width 0.089408)
		(layer "In2.Cu")
		(net "SMB_VR_STBY_LVC3_SCL")
	)
	(segment
		(start 164.59835 -127.40005)
		(end 164.59835 -127.107188)
		(width 0.089408)
		(layer "In2.Cu")
		(net "SMB_VR_STBY_LVC3_SCL")
	)
	(segment
		(start 422.50741 -99.704144)
		(end 421.955722 -99.152456)
		(width 0.089408)
		(layer "In2.Cu")
		(net "SMB_VR_STBY_LVC3_SCL")
	)
	(segment
		(start 175.780954 -71.7931)
		(end 175.67783 -71.7931)
		(width 0.089408)
		(layer "In2.Cu")
		(net "SMB_VR_STBY_LVC3_SCL")
	)
	(segment
		(start 331.978 -32.004)
		(end 333.375 -33.401)
		(width 0.089408)
		(layer "In2.Cu")
		(net "SMB_VR_STBY_LVC3_SCL")
	)
	(segment
		(start 336.347562 -33.401)
		(end 336.810604 -33.864042)
		(width 0.089408)
		(layer "In2.Cu")
		(net "SMB_VR_STBY_LVC3_SCL")
	)
	(segment
		(start 336.4992 -22.4282)
		(end 331.978 -26.9494)
		(width 0.089408)
		(layer "In2.Cu")
		(net "SMB_VR_STBY_LVC3_SCL")
	)
	(segment
		(start 166.389812 -106.025188)
		(end 173.661578 -98.753422)
		(width 0.089408)
		(layer "In2.Cu")
		(net "SMB_VR_STBY_LVC3_SCL")
	)
	(segment
		(start 165.099746 -126.605792)
		(end 165.099746 -126.034038)
		(width 0.089408)
		(layer "In2.Cu")
		(net "SMB_VR_STBY_LVC3_SCL")
	)
	(segment
		(start 175.67783 -71.7931)
		(end 175.272192 -71.387462)
		(width 0.089408)
		(layer "In2.Cu")
		(net "SMB_VR_STBY_LVC3_SCL")
	)
	(segment
		(start 164.009832 -124.944124)
		(end 164.009832 -124.442474)
		(width 0.089408)
		(layer "In2.Cu")
		(net "SMB_VR_STBY_LVC3_SCL")
	)
	(segment
		(start 173.661578 -98.753422)
		(end 173.661578 -96.873822)
		(width 0.089408)
		(layer "In2.Cu")
		(net "SMB_VR_STBY_LVC3_SCL")
	)
	(segment
		(start 331.978 -26.9494)
		(end 331.978 -32.004)
		(width 0.089408)
		(layer "In2.Cu")
		(net "SMB_VR_STBY_LVC3_SCL")
	)
	(segment
		(start 158.330138 -129.057146)
		(end 159.869124 -127.51816)
		(width 0.089408)
		(layer "In2.Cu")
		(net "SMB_VR_STBY_LVC3_SCL")
	)
	(segment
		(start 175.7426 -94.7928)
		(end 175.7426 -73.304654)
		(width 0.089408)
		(layer "In2.Cu")
		(net "SMB_VR_STBY_LVC3_SCL")
	)
	(segment
		(start 422.50741 -103.140256)
		(end 422.50741 -99.704144)
		(width 0.089408)
		(layer "In2.Cu")
		(net "SMB_VR_STBY_LVC3_SCL")
	)
	(segment
		(start 164.48024 -127.51816)
		(end 164.59835 -127.40005)
		(width 0.089408)
		(layer "In2.Cu")
		(net "SMB_VR_STBY_LVC3_SCL")
	)
	(segment
		(start 421.310816 -112.153446)
		(end 421.310816 -104.33685)
		(width 0.089408)
		(layer "In2.Cu")
		(net "SMB_VR_STBY_LVC3_SCL")
	)
	(segment
		(start 160.014158 -155.708096)
		(end 159.84601 -155.539948)
		(width 0.089408)
		(layer "In2.Cu")
		(net "SMB_VR_STBY_LVC3_SCL")
	)
	(segment
		(start 158.330392 -134.874254)
		(end 157.594808 -134.13867)
		(width 0.089408)
		(layer "In2.Cu")
		(net "SMB_VR_STBY_LVC3_SCL")
	)
	(segment
		(start 175.953928 -71.966074)
		(end 175.780954 -71.7931)
		(width 0.089408)
		(layer "In2.Cu")
		(net "SMB_VR_STBY_LVC3_SCL")
	)
	(segment
		(start 344.297 -21.082)
		(end 344.297 -20.766024)
		(width 0.089408)
		(layer "In2.Cu")
		(net "SMB_VR_STBY_LVC3_SCL")
	)
	(segment
		(start 165.099746 -126.034038)
		(end 164.009832 -124.944124)
		(width 0.089408)
		(layer "In2.Cu")
		(net "SMB_VR_STBY_LVC3_SCL")
	)
	(segment
		(start 164.009832 -124.442474)
		(end 165.597586 -122.85472)
		(width 0.089408)
		(layer "In2.Cu")
		(net "SMB_VR_STBY_LVC3_SCL")
	)
	(segment
		(start 158.330392 -153.280872)
		(end 158.330392 -134.874254)
		(width 0.089408)
		(layer "In2.Cu")
		(net "SMB_VR_STBY_LVC3_SCL")
	)
	(segment
		(start 173.661578 -96.873822)
		(end 175.7426 -94.7928)
		(width 0.089408)
		(layer "In2.Cu")
		(net "SMB_VR_STBY_LVC3_SCL")
	)
	(segment
		(start 166.389812 -115.951508)
		(end 166.389812 -106.025188)
		(width 0.089408)
		(layer "In2.Cu")
		(net "SMB_VR_STBY_LVC3_SCL")
	)
	(segment
		(start 159.869124 -127.51816)
		(end 164.48024 -127.51816)
		(width 0.089408)
		(layer "In2.Cu")
		(net "SMB_VR_STBY_LVC3_SCL")
	)
	(segment
		(start 165.597586 -116.743734)
		(end 166.389812 -115.951508)
		(width 0.089408)
		(layer "In2.Cu")
		(net "SMB_VR_STBY_LVC3_SCL")
	)
	(segment
		(start 424.528742 -114.434366)
		(end 423.591736 -114.434366)
		(width 0.089408)
		(layer "In2.Cu")
		(net "SMB_VR_STBY_LVC3_SCL")
	)
	(segment
		(start 339.26272 -22.4282)
		(end 336.4992 -22.4282)
		(width 0.089408)
		(layer "In2.Cu")
		(net "SMB_VR_STBY_LVC3_SCL")
	)
	(segment
		(start 421.310816 -104.33685)
		(end 422.50741 -103.140256)
		(width 0.089408)
		(layer "In2.Cu")
		(net "SMB_VR_STBY_LVC3_SCL")
	)
	(segment
		(start 158.330138 -131.445)
		(end 158.330138 -129.057146)
		(width 0.089408)
		(layer "In2.Cu")
		(net "SMB_VR_STBY_LVC3_SCL")
	)
	(segment
		(start 175.953928 -73.093326)
		(end 175.953928 -71.966074)
		(width 0.089408)
		(layer "In2.Cu")
		(net "SMB_VR_STBY_LVC3_SCL")
	)
	(segment
		(start 344.297 -20.766024)
		(end 344.207592 -20.676616)
		(width 0.089408)
		(layer "In2.Cu")
		(net "SMB_VR_STBY_LVC3_SCL")
	)
	(segment
		(start 341.014304 -20.676616)
		(end 339.26272 -22.4282)
		(width 0.089408)
		(layer "In2.Cu")
		(net "SMB_VR_STBY_LVC3_SCL")
	)
	(segment
		(start 424.636438 -114.32667)
		(end 424.528742 -114.434366)
		(width 0.089408)
		(layer "In2.Cu")
		(net "SMB_VR_STBY_LVC3_SCL")
	)
	(segment
		(start 175.7426 -73.304654)
		(end 175.953928 -73.093326)
		(width 0.089408)
		(layer "In2.Cu")
		(net "SMB_VR_STBY_LVC3_SCL")
	)
	(segment
		(start 165.597586 -122.85472)
		(end 165.597586 -116.743734)
		(width 0.089408)
		(layer "In2.Cu")
		(net "SMB_VR_STBY_LVC3_SCL")
	)
	(segment
		(start 333.375 -33.401)
		(end 336.347562 -33.401)
		(width 0.089408)
		(layer "In2.Cu")
		(net "SMB_VR_STBY_LVC3_SCL")
	)
	(segment
		(start 423.591736 -114.434366)
		(end 421.310816 -112.153446)
		(width 0.089408)
		(layer "In2.Cu")
		(net "SMB_VR_STBY_LVC3_SCL")
	)
	(segment
		(start 157.594808 -132.18033)
		(end 158.330138 -131.445)
		(width 0.089408)
		(layer "In2.Cu")
		(net "SMB_VR_STBY_LVC3_SCL")
	)
	(segment
		(start 425.123864 -114.32667)
		(end 424.636438 -114.32667)
		(width 0.089408)
		(layer "In2.Cu")
		(net "SMB_VR_STBY_LVC3_SCL")
	)
	(segment
		(start 159.84601 -155.539948)
		(end 159.84601 -154.79649)
		(width 0.089408)
		(layer "In2.Cu")
		(net "SMB_VR_STBY_LVC3_SCL")
	)
	(segment
		(start 425.776898 -113.673636)
		(end 425.123864 -114.32667)
		(width 0.089408)
		(layer "In2.Cu")
		(net "SMB_VR_STBY_LVC3_SCL")
	)
	(segment
		(start 173.595538 -52.843684)
		(end 173.595538 -60.145676)
		(width 0.089408)
		(layer "In4.Cu")
		(net "SMB_VR_STBY_LVC3_SCL")
	)
	(segment
		(start 404.746714 -85.667596)
		(end 405.816054 -86.736936)
		(width 0.089408)
		(layer "In4.Cu")
		(net "SMB_VR_STBY_LVC3_SCL")
	)
	(segment
		(start 470.347294 -116.801392)
		(end 471.426794 -117.880892)
		(width 0.089408)
		(layer "In4.Cu")
		(net "SMB_VR_STBY_LVC3_SCL")
	)
	(segment
		(start 173.595538 -60.145676)
		(end 176.920144 -63.470282)
		(width 0.089408)
		(layer "In4.Cu")
		(net "SMB_VR_STBY_LVC3_SCL")
	)
	(segment
		(start 425.722542 -114.64798)
		(end 426.263054 -115.188492)
		(width 0.089408)
		(layer "In4.Cu")
		(net "SMB_VR_STBY_LVC3_SCL")
	)
	(segment
		(start 465.199222 -155.12034)
		(end 461.674972 -155.12034)
		(width 0.089408)
		(layer "In4.Cu")
		(net "SMB_VR_STBY_LVC3_SCL")
	)
	(segment
		(start 426.263054 -116.501926)
		(end 427.321218 -117.56009)
		(width 0.089408)
		(layer "In4.Cu")
		(net "SMB_VR_STBY_LVC3_SCL")
	)
	(segment
		(start 425.776898 -113.599976)
		(end 425.776898 -113.673382)
		(width 0.089408)
		(layer "In4.Cu")
		(net "SMB_VR_STBY_LVC3_SCL")
	)
	(segment
		(start 397.262096 -86.087712)
		(end 397.693896 -85.655912)
		(width 0.089408)
		(layer "In4.Cu")
		(net "SMB_VR_STBY_LVC3_SCL")
	)
	(segment
		(start 412.894018 -85.982556)
		(end 413.563308 -85.313266)
		(width 0.089408)
		(layer "In4.Cu")
		(net "SMB_VR_STBY_LVC3_SCL")
	)
	(segment
		(start 425.615354 -114.64798)
		(end 425.722542 -114.64798)
		(width 0.089408)
		(layer "In4.Cu")
		(net "SMB_VR_STBY_LVC3_SCL")
	)
	(segment
		(start 410.644848 -87.27948)
		(end 411.599126 -87.27948)
		(width 0.089408)
		(layer "In4.Cu")
		(net "SMB_VR_STBY_LVC3_SCL")
	)
	(segment
		(start 425.776898 -113.673382)
		(end 425.380912 -114.069368)
		(width 0.089408)
		(layer "In4.Cu")
		(net "SMB_VR_STBY_LVC3_SCL")
	)
	(segment
		(start 441.625736 -116.657374)
		(end 442.624718 -115.658392)
		(width 0.089408)
		(layer "In4.Cu")
		(net "SMB_VR_STBY_LVC3_SCL")
	)
	(segment
		(start 357.1113 -129.7051)
		(end 356.936548 -129.7051)
		(width 0.089408)
		(layer "In4.Cu")
		(net "SMB_VR_STBY_LVC3_SCL")
	)
	(segment
		(start 472.950794 -130.783838)
		(end 473.217748 -131.050792)
		(width 0.089408)
		(layer "In4.Cu")
		(net "SMB_VR_STBY_LVC3_SCL")
	)
	(segment
		(start 399.871946 -149.931628)
		(end 402.273008 -152.33269)
		(width 0.089408)
		(layer "In4.Cu")
		(net "SMB_VR_STBY_LVC3_SCL")
	)
	(segment
		(start 411.599126 -87.27948)
		(end 412.894018 -85.984588)
		(width 0.089408)
		(layer "In4.Cu")
		(net "SMB_VR_STBY_LVC3_SCL")
	)
	(segment
		(start 397.262096 -86.353904)
		(end 397.262096 -86.087712)
		(width 0.089408)
		(layer "In4.Cu")
		(net "SMB_VR_STBY_LVC3_SCL")
	)
	(segment
		(start 474.764608 -124.18949)
		(end 474.764608 -127.037592)
		(width 0.089408)
		(layer "In4.Cu")
		(net "SMB_VR_STBY_LVC3_SCL")
	)
	(segment
		(start 356.936548 -129.7051)
		(end 356.591108 -129.35966)
		(width 0.089408)
		(layer "In4.Cu")
		(net "SMB_VR_STBY_LVC3_SCL")
	)
	(segment
		(start 356.170738 -128.674876)
		(end 352.652076 -128.674876)
		(width 0.089408)
		(layer "In4.Cu")
		(net "SMB_VR_STBY_LVC3_SCL")
	)
	(segment
		(start 471.426794 -117.880892)
		(end 472.650058 -117.880892)
		(width 0.089408)
		(layer "In4.Cu")
		(net "SMB_VR_STBY_LVC3_SCL")
	)
	(segment
		(start 470.388442 -149.93112)
		(end 465.199222 -155.12034)
		(width 0.089408)
		(layer "In4.Cu")
		(net "SMB_VR_STBY_LVC3_SCL")
	)
	(segment
		(start 349.9739 -120.2182)
		(end 351.3963 -118.7958)
		(width 0.089408)
		(layer "In4.Cu")
		(net "SMB_VR_STBY_LVC3_SCL")
	)
	(segment
		(start 461.674972 -155.12034)
		(end 459.65491 -157.140402)
		(width 0.089408)
		(layer "In4.Cu")
		(net "SMB_VR_STBY_LVC3_SCL")
	)
	(segment
		(start 176.920144 -66.715386)
		(end 175.924464 -67.711066)
		(width 0.089408)
		(layer "In4.Cu")
		(net "SMB_VR_STBY_LVC3_SCL")
	)
	(segment
		(start 473.954094 -137.502646)
		(end 473.954094 -147.577048)
		(width 0.089408)
		(layer "In4.Cu")
		(net "SMB_VR_STBY_LVC3_SCL")
	)
	(segment
		(start 191.43345 -5.902706)
		(end 191.963548 -6.432804)
		(width 0.089408)
		(layer "In4.Cu")
		(net "SMB_VR_STBY_LVC3_SCL")
	)
	(segment
		(start 400.570192 -85.28939)
		(end 402.456904 -85.28939)
		(width 0.089408)
		(layer "In4.Cu")
		(net "SMB_VR_STBY_LVC3_SCL")
	)
	(segment
		(start 427.321218 -117.56009)
		(end 427.321218 -118.15826)
		(width 0.089408)
		(layer "In4.Cu")
		(net "SMB_VR_STBY_LVC3_SCL")
	)
	(segment
		(start 418.499544 -96.339152)
		(end 421.472868 -99.312476)
		(width 0.089408)
		(layer "In4.Cu")
		(net "SMB_VR_STBY_LVC3_SCL")
	)
	(segment
		(start 425.380912 -114.413538)
		(end 425.615354 -114.64798)
		(width 0.089408)
		(layer "In4.Cu")
		(net "SMB_VR_STBY_LVC3_SCL")
	)
	(segment
		(start 435.965854 -116.657374)
		(end 441.625736 -116.657374)
		(width 0.089408)
		(layer "In4.Cu")
		(net "SMB_VR_STBY_LVC3_SCL")
	)
	(segment
		(start 351.3963 -115.3541)
		(end 351.8154 -114.935)
		(width 0.089408)
		(layer "In4.Cu")
		(net "SMB_VR_STBY_LVC3_SCL")
	)
	(segment
		(start 402.273008 -152.33269)
		(end 402.273008 -157.467808)
		(width 0.089408)
		(layer "In4.Cu")
		(net "SMB_VR_STBY_LVC3_SCL")
	)
	(segment
		(start 173.189392 -37.46627)
		(end 173.189392 -47.672752)
		(width 0.089408)
		(layer "In4.Cu")
		(net "SMB_VR_STBY_LVC3_SCL")
	)
	(segment
		(start 184.739788 -25.915874)
		(end 173.189392 -37.46627)
		(width 0.089408)
		(layer "In4.Cu")
		(net "SMB_VR_STBY_LVC3_SCL")
	)
	(segment
		(start 394.972794 -148.763228)
		(end 395.06779 -148.858224)
		(width 0.089408)
		(layer "In4.Cu")
		(net "SMB_VR_STBY_LVC3_SCL")
	)
	(segment
		(start 185.484008 -21.475192)
		(end 184.739788 -22.219412)
		(width 0.089408)
		(layer "In4.Cu")
		(net "SMB_VR_STBY_LVC3_SCL")
	)
	(segment
		(start 394.410946 -148.993352)
		(end 394.64107 -148.763228)
		(width 0.089408)
		(layer "In4.Cu")
		(net "SMB_VR_STBY_LVC3_SCL")
	)
	(segment
		(start 176.920144 -63.470282)
		(end 176.920144 -66.715386)
		(width 0.089408)
		(layer "In4.Cu")
		(net "SMB_VR_STBY_LVC3_SCL")
	)
	(segment
		(start 395.883384 -148.858224)
		(end 396.956788 -149.931628)
		(width 0.089408)
		(layer "In4.Cu")
		(net "SMB_VR_STBY_LVC3_SCL")
	)
	(segment
		(start 175.650652 -71.63943)
		(end 175.52416 -71.63943)
		(width 0.089408)
		(layer "In4.Cu")
		(net "SMB_VR_STBY_LVC3_SCL")
	)
	(segment
		(start 175.924464 -71.365618)
		(end 175.650652 -71.63943)
		(width 0.089408)
		(layer "In4.Cu")
		(net "SMB_VR_STBY_LVC3_SCL")
	)
	(segment
		(start 426.263054 -115.188492)
		(end 426.263054 -116.501926)
		(width 0.089408)
		(layer "In4.Cu")
		(net "SMB_VR_STBY_LVC3_SCL")
	)
	(segment
		(start 474.900244 -136.556496)
		(end 473.954094 -137.502646)
		(width 0.089408)
		(layer "In4.Cu")
		(net "SMB_VR_STBY_LVC3_SCL")
	)
	(segment
		(start 173.189392 -47.672752)
		(end 171.493688 -49.368456)
		(width 0.089408)
		(layer "In4.Cu")
		(net "SMB_VR_STBY_LVC3_SCL")
	)
	(segment
		(start 175.924464 -67.711066)
		(end 175.924464 -71.365618)
		(width 0.089408)
		(layer "In4.Cu")
		(net "SMB_VR_STBY_LVC3_SCL")
	)
	(segment
		(start 432.762406 -119.860822)
		(end 435.965854 -116.657374)
		(width 0.089408)
		(layer "In4.Cu")
		(net "SMB_VR_STBY_LVC3_SCL")
	)
	(segment
		(start 474.900244 -134.351776)
		(end 474.900244 -136.556496)
		(width 0.089408)
		(layer "In4.Cu")
		(net "SMB_VR_STBY_LVC3_SCL")
	)
	(segment
		(start 192.800224 -19.092672)
		(end 191.341248 -20.551648)
		(width 0.089408)
		(layer "In4.Cu")
		(net "SMB_VR_STBY_LVC3_SCL")
	)
	(segment
		(start 403.2123 -158.4071)
		(end 458.388212 -158.4071)
		(width 0.089408)
		(layer "In4.Cu")
		(net "SMB_VR_STBY_LVC3_SCL")
	)
	(segment
		(start 425.380912 -114.069368)
		(end 425.380912 -114.413538)
		(width 0.089408)
		(layer "In4.Cu")
		(net "SMB_VR_STBY_LVC3_SCL")
	)
	(segment
		(start 473.217748 -131.050792)
		(end 473.217748 -132.668264)
		(width 0.089408)
		(layer "In4.Cu")
		(net "SMB_VR_STBY_LVC3_SCL")
	)
	(segment
		(start 356.591108 -129.095246)
		(end 356.170738 -128.674876)
		(width 0.089408)
		(layer "In4.Cu")
		(net "SMB_VR_STBY_LVC3_SCL")
	)
	(segment
		(start 413.563308 -85.313266)
		(end 417.50869 -85.313266)
		(width 0.089408)
		(layer "In4.Cu")
		(net "SMB_VR_STBY_LVC3_SCL")
	)
	(segment
		(start 398.966944 -85.655912)
		(end 399.400268 -85.222588)
		(width 0.089408)
		(layer "In4.Cu")
		(net "SMB_VR_STBY_LVC3_SCL")
	)
	(segment
		(start 417.50869 -85.313266)
		(end 418.499544 -86.30412)
		(width 0.089408)
		(layer "In4.Cu")
		(net "SMB_VR_STBY_LVC3_SCL")
	)
	(segment
		(start 191.341248 -20.551648)
		(end 188.083952 -20.551648)
		(width 0.089408)
		(layer "In4.Cu")
		(net "SMB_VR_STBY_LVC3_SCL")
	)
	(segment
		(start 429.02378 -119.860822)
		(end 432.762406 -119.860822)
		(width 0.089408)
		(layer "In4.Cu")
		(net "SMB_VR_STBY_LVC3_SCL")
	)
	(segment
		(start 412.894018 -85.984588)
		(end 412.894018 -85.982556)
		(width 0.089408)
		(layer "In4.Cu")
		(net "SMB_VR_STBY_LVC3_SCL")
	)
	(segment
		(start 356.591108 -129.35966)
		(end 356.591108 -129.095246)
		(width 0.089408)
		(layer "In4.Cu")
		(net "SMB_VR_STBY_LVC3_SCL")
	)
	(segment
		(start 472.650058 -117.880892)
		(end 473.80779 -119.038624)
		(width 0.089408)
		(layer "In4.Cu")
		(net "SMB_VR_STBY_LVC3_SCL")
	)
	(segment
		(start 188.083952 -20.551648)
		(end 187.160408 -21.475192)
		(width 0.089408)
		(layer "In4.Cu")
		(net "SMB_VR_STBY_LVC3_SCL")
	)
	(segment
		(start 395.06779 -148.858224)
		(end 395.883384 -148.858224)
		(width 0.089408)
		(layer "In4.Cu")
		(net "SMB_VR_STBY_LVC3_SCL")
	)
	(segment
		(start 349.9739 -125.9967)
		(end 349.9739 -120.2182)
		(width 0.089408)
		(layer "In4.Cu")
		(net "SMB_VR_STBY_LVC3_SCL")
	)
	(segment
		(start 473.217748 -132.668264)
		(end 474.900244 -134.351776)
		(width 0.089408)
		(layer "In4.Cu")
		(net "SMB_VR_STBY_LVC3_SCL")
	)
	(segment
		(start 418.499544 -86.30412)
		(end 418.499544 -96.339152)
		(width 0.089408)
		(layer "In4.Cu")
		(net "SMB_VR_STBY_LVC3_SCL")
	)
	(segment
		(start 171.493688 -49.368456)
		(end 171.493688 -50.741834)
		(width 0.089408)
		(layer "In4.Cu")
		(net "SMB_VR_STBY_LVC3_SCL")
	)
	(segment
		(start 405.816054 -86.736936)
		(end 410.102304 -86.736936)
		(width 0.089408)
		(layer "In4.Cu")
		(net "SMB_VR_STBY_LVC3_SCL")
	)
	(segment
		(start 427.321218 -118.15826)
		(end 429.02378 -119.860822)
		(width 0.089408)
		(layer "In4.Cu")
		(net "SMB_VR_STBY_LVC3_SCL")
	)
	(segment
		(start 458.388212 -158.4071)
		(end 459.65491 -157.140402)
		(width 0.089408)
		(layer "In4.Cu")
		(net "SMB_VR_STBY_LVC3_SCL")
	)
	(segment
		(start 191.963548 -6.432804)
		(end 191.963548 -7.0231)
		(width 0.089408)
		(layer "In4.Cu")
		(net "SMB_VR_STBY_LVC3_SCL")
	)
	(segment
		(start 192.800224 -7.859776)
		(end 192.800224 -19.092672)
		(width 0.089408)
		(layer "In4.Cu")
		(net "SMB_VR_STBY_LVC3_SCL")
	)
	(segment
		(start 175.52416 -71.63943)
		(end 175.272192 -71.387462)
		(width 0.089408)
		(layer "In4.Cu")
		(net "SMB_VR_STBY_LVC3_SCL")
	)
	(segment
		(start 473.80779 -119.038624)
		(end 473.80779 -123.232672)
		(width 0.089408)
		(layer "In4.Cu")
		(net "SMB_VR_STBY_LVC3_SCL")
	)
	(segment
		(start 465.374736 -116.801392)
		(end 470.347294 -116.801392)
		(width 0.089408)
		(layer "In4.Cu")
		(net "SMB_VR_STBY_LVC3_SCL")
	)
	(segment
		(start 393.95146 -148.993352)
		(end 394.410946 -148.993352)
		(width 0.089408)
		(layer "In4.Cu")
		(net "SMB_VR_STBY_LVC3_SCL")
	)
	(segment
		(start 464.231736 -115.658392)
		(end 465.374736 -116.801392)
		(width 0.089408)
		(layer "In4.Cu")
		(net "SMB_VR_STBY_LVC3_SCL")
	)
	(segment
		(start 421.472868 -99.312476)
		(end 421.795702 -99.312476)
		(width 0.089408)
		(layer "In4.Cu")
		(net "SMB_VR_STBY_LVC3_SCL")
	)
	(segment
		(start 396.956788 -149.931628)
		(end 399.871946 -149.931628)
		(width 0.089408)
		(layer "In4.Cu")
		(net "SMB_VR_STBY_LVC3_SCL")
	)
	(segment
		(start 352.652076 -128.674876)
		(end 349.9739 -125.9967)
		(width 0.089408)
		(layer "In4.Cu")
		(net "SMB_VR_STBY_LVC3_SCL")
	)
	(segment
		(start 184.739788 -22.219412)
		(end 184.739788 -25.915874)
		(width 0.089408)
		(layer "In4.Cu")
		(net "SMB_VR_STBY_LVC3_SCL")
	)
	(segment
		(start 400.50339 -85.222588)
		(end 400.570192 -85.28939)
		(width 0.089408)
		(layer "In4.Cu")
		(net "SMB_VR_STBY_LVC3_SCL")
	)
	(segment
		(start 397.693896 -85.655912)
		(end 398.966944 -85.655912)
		(width 0.089408)
		(layer "In4.Cu")
		(net "SMB_VR_STBY_LVC3_SCL")
	)
	(segment
		(start 402.83511 -85.667596)
		(end 404.746714 -85.667596)
		(width 0.089408)
		(layer "In4.Cu")
		(net "SMB_VR_STBY_LVC3_SCL")
	)
	(segment
		(start 187.160408 -21.475192)
		(end 185.484008 -21.475192)
		(width 0.089408)
		(layer "In4.Cu")
		(net "SMB_VR_STBY_LVC3_SCL")
	)
	(segment
		(start 471.600022 -149.93112)
		(end 470.388442 -149.93112)
		(width 0.089408)
		(layer "In4.Cu")
		(net "SMB_VR_STBY_LVC3_SCL")
	)
	(segment
		(start 473.954094 -147.577048)
		(end 471.600022 -149.93112)
		(width 0.089408)
		(layer "In4.Cu")
		(net "SMB_VR_STBY_LVC3_SCL")
	)
	(segment
		(start 474.764608 -127.037592)
		(end 472.950794 -128.851406)
		(width 0.089408)
		(layer "In4.Cu")
		(net "SMB_VR_STBY_LVC3_SCL")
	)
	(segment
		(start 402.456904 -85.28939)
		(end 402.83511 -85.667596)
		(width 0.089408)
		(layer "In4.Cu")
		(net "SMB_VR_STBY_LVC3_SCL")
	)
	(segment
		(start 442.624718 -115.658392)
		(end 464.231736 -115.658392)
		(width 0.089408)
		(layer "In4.Cu")
		(net "SMB_VR_STBY_LVC3_SCL")
	)
	(segment
		(start 402.273008 -157.467808)
		(end 403.2123 -158.4071)
		(width 0.089408)
		(layer "In4.Cu")
		(net "SMB_VR_STBY_LVC3_SCL")
	)
	(segment
		(start 473.80779 -123.232672)
		(end 474.764608 -124.18949)
		(width 0.089408)
		(layer "In4.Cu")
		(net "SMB_VR_STBY_LVC3_SCL")
	)
	(segment
		(start 191.963548 -7.0231)
		(end 192.800224 -7.859776)
		(width 0.089408)
		(layer "In4.Cu")
		(net "SMB_VR_STBY_LVC3_SCL")
	)
	(segment
		(start 421.795702 -99.312476)
		(end 421.955722 -99.152456)
		(width 0.089408)
		(layer "In4.Cu")
		(net "SMB_VR_STBY_LVC3_SCL")
	)
	(segment
		(start 351.3963 -118.7958)
		(end 351.3963 -115.3541)
		(width 0.089408)
		(layer "In4.Cu")
		(net "SMB_VR_STBY_LVC3_SCL")
	)
	(segment
		(start 410.102304 -86.736936)
		(end 410.644848 -87.27948)
		(width 0.089408)
		(layer "In4.Cu")
		(net "SMB_VR_STBY_LVC3_SCL")
	)
	(segment
		(start 397.002 -86.614)
		(end 397.262096 -86.353904)
		(width 0.089408)
		(layer "In4.Cu")
		(net "SMB_VR_STBY_LVC3_SCL")
	)
	(segment
		(start 171.493688 -50.741834)
		(end 173.595538 -52.843684)
		(width 0.089408)
		(layer "In4.Cu")
		(net "SMB_VR_STBY_LVC3_SCL")
	)
	(segment
		(start 394.64107 -148.763228)
		(end 394.972794 -148.763228)
		(width 0.089408)
		(layer "In4.Cu")
		(net "SMB_VR_STBY_LVC3_SCL")
	)
	(segment
		(start 472.950794 -128.851406)
		(end 472.950794 -130.783838)
		(width 0.089408)
		(layer "In4.Cu")
		(net "SMB_VR_STBY_LVC3_SCL")
	)
	(segment
		(start 399.400268 -85.222588)
		(end 400.50339 -85.222588)
		(width 0.089408)
		(layer "In4.Cu")
		(net "SMB_VR_STBY_LVC3_SCL")
	)
	(segment
		(start 322.1736 -138.176)
		(end 323.7738 -136.5758)
		(width 0.089408)
		(layer "In9.Cu")
		(net "SMB_VR_STBY_LVC3_SCL")
	)
	(segment
		(start 380.841504 -147.493482)
		(end 382.577848 -149.229826)
		(width 0.089408)
		(layer "In9.Cu")
		(net "SMB_VR_STBY_LVC3_SCL")
	)
	(segment
		(start 183.195722 -129.70764)
		(end 183.322214 -129.70764)
		(width 0.089408)
		(layer "In9.Cu")
		(net "SMB_VR_STBY_LVC3_SCL")
	)
	(segment
		(start 261.056374 -139.55522)
		(end 262.435594 -138.176)
		(width 0.089408)
		(layer "In9.Cu")
		(net "SMB_VR_STBY_LVC3_SCL")
	)
	(segment
		(start 259.10159 -138.276584)
		(end 259.62991 -138.804904)
		(width 0.089408)
		(layer "In9.Cu")
		(net "SMB_VR_STBY_LVC3_SCL")
	)
	(segment
		(start 2.028952 -134.832852)
		(end 0.49911 -133.30301)
		(width 0.089408)
		(layer "In9.Cu")
		(net "SMB_VR_STBY_LVC3_SCL")
	)
	(segment
		(start 4.258564 -134.14883)
		(end 3.574542 -134.832852)
		(width 0.089408)
		(layer "In9.Cu")
		(net "SMB_VR_STBY_LVC3_SCL")
	)
	(segment
		(start 22.964394 -152.514808)
		(end 21.195792 -150.746206)
		(width 0.089408)
		(layer "In9.Cu")
		(net "SMB_VR_STBY_LVC3_SCL")
	)
	(segment
		(start 347.238828 -115.83924)
		(end 350.91116 -115.83924)
		(width 0.089408)
		(layer "In9.Cu")
		(net "SMB_VR_STBY_LVC3_SCL")
	)
	(segment
		(start 11.70686 -135.071612)
		(end 10.784078 -134.14883)
		(width 0.089408)
		(layer "In9.Cu")
		(net "SMB_VR_STBY_LVC3_SCL")
	)
	(segment
		(start 28.802584 -154.747722)
		(end 26.56967 -152.514808)
		(width 0.089408)
		(layer "In9.Cu")
		(net "SMB_VR_STBY_LVC3_SCL")
	)
	(segment
		(start 354.311458 -131.417568)
		(end 355.401372 -131.417568)
		(width 0.089408)
		(layer "In9.Cu")
		(net "SMB_VR_STBY_LVC3_SCL")
	)
	(segment
		(start 259.630164 -138.804904)
		(end 260.38048 -139.55522)
		(width 0.089408)
		(layer "In9.Cu")
		(net "SMB_VR_STBY_LVC3_SCL")
	)
	(segment
		(start 331.63383 -130.842004)
		(end 332.731364 -129.74447)
		(width 0.089408)
		(layer "In9.Cu")
		(net "SMB_VR_STBY_LVC3_SCL")
	)
	(segment
		(start 183.322214 -129.70764)
		(end 185.46699 -131.852416)
		(width 0.089408)
		(layer "In9.Cu")
		(net "SMB_VR_STBY_LVC3_SCL")
	)
	(segment
		(start 346.049092 -107.368848)
		(end 346.049092 -115.482878)
		(width 0.089408)
		(layer "In9.Cu")
		(net "SMB_VR_STBY_LVC3_SCL")
	)
	(segment
		(start 164.59835 -127.40005)
		(end 164.918898 -127.40005)
		(width 0.089408)
		(layer "In9.Cu")
		(net "SMB_VR_STBY_LVC3_SCL")
	)
	(segment
		(start 393.49172 -149.453092)
		(end 393.95146 -148.993352)
		(width 0.089408)
		(layer "In9.Cu")
		(net "SMB_VR_STBY_LVC3_SCL")
	)
	(segment
		(start 356.4636 -130.581146)
		(end 356.915212 -130.129534)
		(width 0.089408)
		(layer "In9.Cu")
		(net "SMB_VR_STBY_LVC3_SCL")
	)
	(segment
		(start 30.037024 -156.871416)
		(end 28.802584 -155.636976)
		(width 0.089408)
		(layer "In9.Cu")
		(net "SMB_VR_STBY_LVC3_SCL")
	)
	(segment
		(start 346.6592 -81.9658)
		(end 346.6592 -82.4738)
		(width 0.089408)
		(layer "In9.Cu")
		(net "SMB_VR_STBY_LVC3_SCL")
	)
	(segment
		(start 391.28573 -149.453092)
		(end 393.49172 -149.453092)
		(width 0.089408)
		(layer "In9.Cu")
		(net "SMB_VR_STBY_LVC3_SCL")
	)
	(segment
		(start 3.574542 -134.832852)
		(end 2.028952 -134.832852)
		(width 0.089408)
		(layer "In9.Cu")
		(net "SMB_VR_STBY_LVC3_SCL")
	)
	(segment
		(start 175.018192 -131.139946)
		(end 176.491392 -129.666746)
		(width 0.089408)
		(layer "In9.Cu")
		(net "SMB_VR_STBY_LVC3_SCL")
	)
	(segment
		(start 331.63383 -131.909058)
		(end 331.63383 -130.842004)
		(width 0.089408)
		(layer "In9.Cu")
		(net "SMB_VR_STBY_LVC3_SCL")
	)
	(segment
		(start 189.545468 -133.485128)
		(end 190.733426 -134.673086)
		(width 0.089408)
		(layer "In9.Cu")
		(net "SMB_VR_STBY_LVC3_SCL")
	)
	(segment
		(start 346.38615 -115.819936)
		(end 347.219524 -115.819936)
		(width 0.089408)
		(layer "In9.Cu")
		(net "SMB_VR_STBY_LVC3_SCL")
	)
	(segment
		(start 347.219524 -115.819936)
		(end 347.238828 -115.83924)
		(width 0.089408)
		(layer "In9.Cu")
		(net "SMB_VR_STBY_LVC3_SCL")
	)
	(segment
		(start 323.7738 -135.765032)
		(end 326.021954 -133.516878)
		(width 0.089408)
		(layer "In9.Cu")
		(net "SMB_VR_STBY_LVC3_SCL")
	)
	(segment
		(start 190.733426 -137.29335)
		(end 191.71666 -138.276584)
		(width 0.089408)
		(layer "In9.Cu")
		(net "SMB_VR_STBY_LVC3_SCL")
	)
	(segment
		(start 342.212422 -100.988622)
		(end 342.212422 -103.532178)
		(width 0.089408)
		(layer "In9.Cu")
		(net "SMB_VR_STBY_LVC3_SCL")
	)
	(segment
		(start 356.237794 -130.581146)
		(end 356.4636 -130.581146)
		(width 0.089408)
		(layer "In9.Cu")
		(net "SMB_VR_STBY_LVC3_SCL")
	)
	(segment
		(start 167.565324 -127.889)
		(end 170.81627 -131.139946)
		(width 0.089408)
		(layer "In9.Cu")
		(net "SMB_VR_STBY_LVC3_SCL")
	)
	(segment
		(start 176.491392 -129.666746)
		(end 176.591214 -129.666746)
		(width 0.089408)
		(layer "In9.Cu")
		(net "SMB_VR_STBY_LVC3_SCL")
	)
	(segment
		(start 183.02351 -129.879852)
		(end 183.195722 -129.70764)
		(width 0.089408)
		(layer "In9.Cu")
		(net "SMB_VR_STBY_LVC3_SCL")
	)
	(segment
		(start 28.802584 -155.636976)
		(end 28.802584 -154.747722)
		(width 0.089408)
		(layer "In9.Cu")
		(net "SMB_VR_STBY_LVC3_SCL")
	)
	(segment
		(start 259.62991 -138.804904)
		(end 259.630164 -138.804904)
		(width 0.089408)
		(layer "In9.Cu")
		(net "SMB_VR_STBY_LVC3_SCL")
	)
	(segment
		(start 99.41433 -156.871416)
		(end 30.037024 -156.871416)
		(width 0.089408)
		(layer "In9.Cu")
		(net "SMB_VR_STBY_LVC3_SCL")
	)
	(segment
		(start 356.915212 -130.129534)
		(end 356.915212 -129.901188)
		(width 0.089408)
		(layer "In9.Cu")
		(net "SMB_VR_STBY_LVC3_SCL")
	)
	(segment
		(start 345.824048 -83.308952)
		(end 344.816938 -83.308952)
		(width 0.089408)
		(layer "In9.Cu")
		(net "SMB_VR_STBY_LVC3_SCL")
	)
	(segment
		(start 372.734586 -147.493482)
		(end 380.841504 -147.493482)
		(width 0.089408)
		(layer "In9.Cu")
		(net "SMB_VR_STBY_LVC3_SCL")
	)
	(segment
		(start 323.7738 -136.5758)
		(end 323.7738 -135.765032)
		(width 0.089408)
		(layer "In9.Cu")
		(net "SMB_VR_STBY_LVC3_SCL")
	)
	(segment
		(start 99.66833 -156.617416)
		(end 99.41433 -156.871416)
		(width 0.089408)
		(layer "In9.Cu")
		(net "SMB_VR_STBY_LVC3_SCL")
	)
	(segment
		(start 0.49911 -132.121148)
		(end 0.851916 -131.768342)
		(width 0.089408)
		(layer "In9.Cu")
		(net "SMB_VR_STBY_LVC3_SCL")
	)
	(segment
		(start 344.816938 -83.308952)
		(end 343.535508 -84.590382)
		(width 0.089408)
		(layer "In9.Cu")
		(net "SMB_VR_STBY_LVC3_SCL")
	)
	(segment
		(start 164.918898 -127.40005)
		(end 165.407848 -127.889)
		(width 0.089408)
		(layer "In9.Cu")
		(net "SMB_VR_STBY_LVC3_SCL")
	)
	(segment
		(start 342.212422 -103.532178)
		(end 346.049092 -107.368848)
		(width 0.089408)
		(layer "In9.Cu")
		(net "SMB_VR_STBY_LVC3_SCL")
	)
	(segment
		(start 10.784078 -134.14883)
		(end 4.258564 -134.14883)
		(width 0.089408)
		(layer "In9.Cu")
		(net "SMB_VR_STBY_LVC3_SCL")
	)
	(segment
		(start 334.99933 -129.74447)
		(end 338.771484 -125.972316)
		(width 0.089408)
		(layer "In9.Cu")
		(net "SMB_VR_STBY_LVC3_SCL")
	)
	(segment
		(start 159.104838 -156.617416)
		(end 99.66833 -156.617416)
		(width 0.089408)
		(layer "In9.Cu")
		(net "SMB_VR_STBY_LVC3_SCL")
	)
	(segment
		(start 343.535508 -99.665536)
		(end 342.212422 -100.988622)
		(width 0.089408)
		(layer "In9.Cu")
		(net "SMB_VR_STBY_LVC3_SCL")
	)
	(segment
		(start 26.56967 -152.514808)
		(end 22.964394 -152.514808)
		(width 0.089408)
		(layer "In9.Cu")
		(net "SMB_VR_STBY_LVC3_SCL")
	)
	(segment
		(start 262.435594 -138.176)
		(end 322.1736 -138.176)
		(width 0.089408)
		(layer "In9.Cu")
		(net "SMB_VR_STBY_LVC3_SCL")
	)
	(segment
		(start 348.37116 -129.948178)
		(end 352.841814 -129.948178)
		(width 0.089408)
		(layer "In9.Cu")
		(net "SMB_VR_STBY_LVC3_SCL")
	)
	(segment
		(start 260.38048 -139.55522)
		(end 261.056374 -139.55522)
		(width 0.089408)
		(layer "In9.Cu")
		(net "SMB_VR_STBY_LVC3_SCL")
	)
	(segment
		(start 330.02601 -133.516878)
		(end 331.63383 -131.909058)
		(width 0.089408)
		(layer "In9.Cu")
		(net "SMB_VR_STBY_LVC3_SCL")
	)
	(segment
		(start 21.195792 -136.98093)
		(end 20.57527 -136.360408)
		(width 0.089408)
		(layer "In9.Cu")
		(net "SMB_VR_STBY_LVC3_SCL")
	)
	(segment
		(start 20.57527 -136.360408)
		(end 18.95221 -136.360408)
		(width 0.089408)
		(layer "In9.Cu")
		(net "SMB_VR_STBY_LVC3_SCL")
	)
	(segment
		(start 176.591214 -129.666746)
		(end 176.591468 -129.667)
		(width 0.089408)
		(layer "In9.Cu")
		(net "SMB_VR_STBY_LVC3_SCL")
	)
	(segment
		(start 185.46699 -131.852416)
		(end 186.481466 -131.852416)
		(width 0.089408)
		(layer "In9.Cu")
		(net "SMB_VR_STBY_LVC3_SCL")
	)
	(segment
		(start 346.3798 -81.6864)
		(end 346.6592 -81.9658)
		(width 0.089408)
		(layer "In9.Cu")
		(net "SMB_VR_STBY_LVC3_SCL")
	)
	(segment
		(start 186.481466 -131.852416)
		(end 188.114178 -133.485128)
		(width 0.089408)
		(layer "In9.Cu")
		(net "SMB_VR_STBY_LVC3_SCL")
	)
	(segment
		(start 343.535508 -84.590382)
		(end 343.535508 -99.665536)
		(width 0.089408)
		(layer "In9.Cu")
		(net "SMB_VR_STBY_LVC3_SCL")
	)
	(segment
		(start 176.591468 -129.667)
		(end 182.810658 -129.667)
		(width 0.089408)
		(layer "In9.Cu")
		(net "SMB_VR_STBY_LVC3_SCL")
	)
	(segment
		(start 0.49911 -133.30301)
		(end 0.49911 -132.121148)
		(width 0.089408)
		(layer "In9.Cu")
		(net "SMB_VR_STBY_LVC3_SCL")
	)
	(segment
		(start 391.062464 -149.229826)
		(end 391.28573 -149.453092)
		(width 0.089408)
		(layer "In9.Cu")
		(net "SMB_VR_STBY_LVC3_SCL")
	)
	(segment
		(start 17.663414 -135.071612)
		(end 11.70686 -135.071612)
		(width 0.089408)
		(layer "In9.Cu")
		(net "SMB_VR_STBY_LVC3_SCL")
	)
	(segment
		(start 343.97696 -130.331972)
		(end 347.987366 -130.331972)
		(width 0.089408)
		(layer "In9.Cu")
		(net "SMB_VR_STBY_LVC3_SCL")
	)
	(segment
		(start 338.771484 -125.972316)
		(end 341.957152 -125.972316)
		(width 0.089408)
		(layer "In9.Cu")
		(net "SMB_VR_STBY_LVC3_SCL")
	)
	(segment
		(start 347.987366 -130.331972)
		(end 348.37116 -129.948178)
		(width 0.089408)
		(layer "In9.Cu")
		(net "SMB_VR_STBY_LVC3_SCL")
	)
	(segment
		(start 21.195792 -150.746206)
		(end 21.195792 -136.98093)
		(width 0.089408)
		(layer "In9.Cu")
		(net "SMB_VR_STBY_LVC3_SCL")
	)
	(segment
		(start 346.049092 -115.482878)
		(end 346.38615 -115.819936)
		(width 0.089408)
		(layer "In9.Cu")
		(net "SMB_VR_STBY_LVC3_SCL")
	)
	(segment
		(start 190.733426 -134.673086)
		(end 190.733426 -137.29335)
		(width 0.089408)
		(layer "In9.Cu")
		(net "SMB_VR_STBY_LVC3_SCL")
	)
	(segment
		(start 356.915212 -129.901188)
		(end 357.1113 -129.7051)
		(width 0.089408)
		(layer "In9.Cu")
		(net "SMB_VR_STBY_LVC3_SCL")
	)
	(segment
		(start 355.401372 -131.417568)
		(end 356.237794 -130.581146)
		(width 0.089408)
		(layer "In9.Cu")
		(net "SMB_VR_STBY_LVC3_SCL")
	)
	(segment
		(start 341.957152 -125.972316)
		(end 342.910414 -126.925578)
		(width 0.089408)
		(layer "In9.Cu")
		(net "SMB_VR_STBY_LVC3_SCL")
	)
	(segment
		(start 170.81627 -131.139946)
		(end 175.018192 -131.139946)
		(width 0.089408)
		(layer "In9.Cu")
		(net "SMB_VR_STBY_LVC3_SCL")
	)
	(segment
		(start 326.021954 -133.516878)
		(end 330.02601 -133.516878)
		(width 0.089408)
		(layer "In9.Cu")
		(net "SMB_VR_STBY_LVC3_SCL")
	)
	(segment
		(start 342.910414 -129.265426)
		(end 343.97696 -130.331972)
		(width 0.089408)
		(layer "In9.Cu")
		(net "SMB_VR_STBY_LVC3_SCL")
	)
	(segment
		(start 350.91116 -115.83924)
		(end 351.8154 -114.935)
		(width 0.089408)
		(layer "In9.Cu")
		(net "SMB_VR_STBY_LVC3_SCL")
	)
	(segment
		(start 352.841814 -129.948178)
		(end 354.311458 -131.417568)
		(width 0.089408)
		(layer "In9.Cu")
		(net "SMB_VR_STBY_LVC3_SCL")
	)
	(segment
		(start 370.287296 -145.046192)
		(end 372.734586 -147.493482)
		(width 0.089408)
		(layer "In9.Cu")
		(net "SMB_VR_STBY_LVC3_SCL")
	)
	(segment
		(start 191.71666 -138.276584)
		(end 259.10159 -138.276584)
		(width 0.089408)
		(layer "In9.Cu")
		(net "SMB_VR_STBY_LVC3_SCL")
	)
	(segment
		(start 182.810658 -129.667)
		(end 183.02351 -129.879852)
		(width 0.089408)
		(layer "In9.Cu")
		(net "SMB_VR_STBY_LVC3_SCL")
	)
	(segment
		(start 342.910414 -126.925578)
		(end 342.910414 -129.265426)
		(width 0.089408)
		(layer "In9.Cu")
		(net "SMB_VR_STBY_LVC3_SCL")
	)
	(segment
		(start 346.6592 -82.4738)
		(end 345.824048 -83.308952)
		(width 0.089408)
		(layer "In9.Cu")
		(net "SMB_VR_STBY_LVC3_SCL")
	)
	(segment
		(start 0.851916 -131.768342)
		(end 0.851916 -131.354322)
		(width 0.089408)
		(layer "In9.Cu")
		(net "SMB_VR_STBY_LVC3_SCL")
	)
	(segment
		(start 165.407848 -127.889)
		(end 167.565324 -127.889)
		(width 0.089408)
		(layer "In9.Cu")
		(net "SMB_VR_STBY_LVC3_SCL")
	)
	(segment
		(start 160.014158 -155.708096)
		(end 159.104838 -156.617416)
		(width 0.089408)
		(layer "In9.Cu")
		(net "SMB_VR_STBY_LVC3_SCL")
	)
	(segment
		(start 18.95221 -136.360408)
		(end 17.663414 -135.071612)
		(width 0.089408)
		(layer "In9.Cu")
		(net "SMB_VR_STBY_LVC3_SCL")
	)
	(segment
		(start 368.5921 -144.7546)
		(end 368.883692 -145.046192)
		(width 0.089408)
		(layer "In9.Cu")
		(net "SMB_VR_STBY_LVC3_SCL")
	)
	(segment
		(start 188.114178 -133.485128)
		(end 189.545468 -133.485128)
		(width 0.089408)
		(layer "In9.Cu")
		(net "SMB_VR_STBY_LVC3_SCL")
	)
	(segment
		(start 368.883692 -145.046192)
		(end 370.287296 -145.046192)
		(width 0.089408)
		(layer "In9.Cu")
		(net "SMB_VR_STBY_LVC3_SCL")
	)
	(segment
		(start 332.731364 -129.74447)
		(end 334.99933 -129.74447)
		(width 0.089408)
		(layer "In9.Cu")
		(net "SMB_VR_STBY_LVC3_SCL")
	)
	(segment
		(start 382.577848 -149.229826)
		(end 391.062464 -149.229826)
		(width 0.089408)
		(layer "In9.Cu")
		(net "SMB_VR_STBY_LVC3_SCL")
	)
	(segment
		(start 12.152376 -121.345452)
		(end 9.822942 -123.674886)
		(width 0.089408)
		(layer "In11.Cu")
		(net "SMB_VR_STBY_LVC3_SCL")
	)
	(segment
		(start 390.407398 -8.574532)
		(end 390.833102 -8.148828)
		(width 0.089408)
		(layer "In11.Cu")
		(net "SMB_VR_STBY_LVC3_SCL")
	)
	(segment
		(start 362.40339 -18.051272)
		(end 370.281708 -10.172954)
		(width 0.089408)
		(layer "In11.Cu")
		(net "SMB_VR_STBY_LVC3_SCL")
	)
	(segment
		(start 15.150592 -5.351272)
		(end 14.569948 -4.770628)
		(width 0.089408)
		(layer "In11.Cu")
		(net "SMB_VR_STBY_LVC3_SCL")
	)
	(segment
		(start 9.822942 -123.674886)
		(end 7.266686 -123.674886)
		(width 0.089408)
		(layer "In11.Cu")
		(net "SMB_VR_STBY_LVC3_SCL")
	)
	(segment
		(start 359.956608 -132.625592)
		(end 359.956608 -137.103104)
		(width 0.089408)
		(layer "In11.Cu")
		(net "SMB_VR_STBY_LVC3_SCL")
	)
	(segment
		(start 338.049362 -12.418568)
		(end 335.721706 -12.418568)
		(width 0.089408)
		(layer "In11.Cu")
		(net "SMB_VR_STBY_LVC3_SCL")
	)
	(segment
		(start 399.35912 -18.931128)
		(end 399.35912 -17.501108)
		(width 0.089408)
		(layer "In11.Cu")
		(net "SMB_VR_STBY_LVC3_SCL")
	)
	(segment
		(start 363.98581 -140.59281)
		(end 365.620808 -142.227808)
		(width 0.089408)
		(layer "In11.Cu")
		(net "SMB_VR_STBY_LVC3_SCL")
	)
	(segment
		(start 11.389868 -92.344494)
		(end 11.389868 -103.06812)
		(width 0.089408)
		(layer "In11.Cu")
		(net "SMB_VR_STBY_LVC3_SCL")
	)
	(segment
		(start 0.01905 -130.101594)
		(end 0.690372 -130.101594)
		(width 0.089408)
		(layer "In11.Cu")
		(net "SMB_VR_STBY_LVC3_SCL")
	)
	(segment
		(start 11.854688 -84.299552)
		(end 12.864592 -83.289648)
		(width 0.089408)
		(layer "In11.Cu")
		(net "SMB_VR_STBY_LVC3_SCL")
	)
	(segment
		(start 367.977166 -145.03781)
		(end 368.30889 -145.03781)
		(width 0.089408)
		(layer "In11.Cu")
		(net "SMB_VR_STBY_LVC3_SCL")
	)
	(segment
		(start 329.181968 4.525518)
		(end 328.591418 5.116068)
		(width 0.089408)
		(layer "In11.Cu")
		(net "SMB_VR_STBY_LVC3_SCL")
	)
	(segment
		(start 331.125576 -8.946642)
		(end 330.798424 -8.61949)
		(width 0.089408)
		(layer "In11.Cu")
		(net "SMB_VR_STBY_LVC3_SCL")
	)
	(segment
		(start 4.490974 -123.50496)
		(end 2.53238 -125.463554)
		(width 0.089408)
		(layer "In11.Cu")
		(net "SMB_VR_STBY_LVC3_SCL")
	)
	(segment
		(start 336.810604 -33.864042)
		(end 337.59648 -34.649918)
		(width 0.089408)
		(layer "In11.Cu")
		(net "SMB_VR_STBY_LVC3_SCL")
	)
	(segment
		(start 399.561304 -19.133312)
		(end 399.35912 -18.931128)
		(width 0.089408)
		(layer "In11.Cu")
		(net "SMB_VR_STBY_LVC3_SCL")
	)
	(segment
		(start 14.341856 -108.859066)
		(end 17.345406 -111.862616)
		(width 0.089408)
		(layer "In11.Cu")
		(net "SMB_VR_STBY_LVC3_SCL")
	)
	(segment
		(start 381.73279 -8.574532)
		(end 390.407398 -8.574532)
		(width 0.089408)
		(layer "In11.Cu")
		(net "SMB_VR_STBY_LVC3_SCL")
	)
	(segment
		(start 14.724888 -41.162224)
		(end 14.724888 -22.448266)
		(width 0.089408)
		(layer "In11.Cu")
		(net "SMB_VR_STBY_LVC3_SCL")
	)
	(segment
		(start 363.446314 -140.59281)
		(end 363.98581 -140.59281)
		(width 0.089408)
		(layer "In11.Cu")
		(net "SMB_VR_STBY_LVC3_SCL")
	)
	(segment
		(start 390.833102 -8.148828)
		(end 392.076432 -8.148828)
		(width 0.089408)
		(layer "In11.Cu")
		(net "SMB_VR_STBY_LVC3_SCL")
	)
	(segment
		(start 337.59648 -34.649918)
		(end 337.887564 -34.649918)
		(width 0.089408)
		(layer "In11.Cu")
		(net "SMB_VR_STBY_LVC3_SCL")
	)
	(segment
		(start 13.339064 -105.022396)
		(end 13.709396 -105.022396)
		(width 0.089408)
		(layer "In11.Cu")
		(net "SMB_VR_STBY_LVC3_SCL")
	)
	(segment
		(start 15.134844 -22.03831)
		(end 21.448522 -22.03831)
		(width 0.089408)
		(layer "In11.Cu")
		(net "SMB_VR_STBY_LVC3_SCL")
	)
	(segment
		(start 14.341856 -105.654856)
		(end 14.341856 -108.859066)
		(width 0.089408)
		(layer "In11.Cu")
		(net "SMB_VR_STBY_LVC3_SCL")
	)
	(segment
		(start 340.286848 -14.656054)
		(end 338.049362 -12.418568)
		(width 0.089408)
		(layer "In11.Cu")
		(net "SMB_VR_STBY_LVC3_SCL")
	)
	(segment
		(start 365.620808 -142.227808)
		(end 365.620808 -142.681452)
		(width 0.089408)
		(layer "In11.Cu")
		(net "SMB_VR_STBY_LVC3_SCL")
	)
	(segment
		(start 17.345406 -111.862616)
		(end 17.345406 -119.19458)
		(width 0.089408)
		(layer "In11.Cu")
		(net "SMB_VR_STBY_LVC3_SCL")
	)
	(segment
		(start 11.640312 -67.04457)
		(end 11.640312 -51.80076)
		(width 0.089408)
		(layer "In11.Cu")
		(net "SMB_VR_STBY_LVC3_SCL")
	)
	(segment
		(start 11.389868 -103.06812)
		(end 12.61364 -104.291892)
		(width 0.089408)
		(layer "In11.Cu")
		(net "SMB_VR_STBY_LVC3_SCL")
	)
	(segment
		(start 360.1212 -132.461)
		(end 359.956608 -132.625592)
		(width 0.089408)
		(layer "In11.Cu")
		(net "SMB_VR_STBY_LVC3_SCL")
	)
	(segment
		(start 21.448522 -22.03831)
		(end 22.117812 -21.36902)
		(width 0.089408)
		(layer "In11.Cu")
		(net "SMB_VR_STBY_LVC3_SCL")
	)
	(segment
		(start 340.286848 -18.61185)
		(end 340.286848 -14.656054)
		(width 0.089408)
		(layer "In11.Cu")
		(net "SMB_VR_STBY_LVC3_SCL")
	)
	(segment
		(start 418.662104 -16.540734)
		(end 418.662104 -16.566134)
		(width 0.089408)
		(layer "In11.Cu")
		(net "SMB_VR_STBY_LVC3_SCL")
	)
	(segment
		(start 12.61364 -104.296972)
		(end 13.339064 -105.022396)
		(width 0.089408)
		(layer "In11.Cu")
		(net "SMB_VR_STBY_LVC3_SCL")
	)
	(segment
		(start 21.62556 -5.351272)
		(end 15.150592 -5.351272)
		(width 0.089408)
		(layer "In11.Cu")
		(net "SMB_VR_STBY_LVC3_SCL")
	)
	(segment
		(start 370.281708 -8.8138)
		(end 372.22684 -6.868668)
		(width 0.089408)
		(layer "In11.Cu")
		(net "SMB_VR_STBY_LVC3_SCL")
	)
	(segment
		(start 180.725064 4.636516)
		(end 180.029612 4.636516)
		(width 0.089408)
		(layer "In11.Cu")
		(net "SMB_VR_STBY_LVC3_SCL")
	)
	(segment
		(start 12.18438 -91.549982)
		(end 11.389868 -92.344494)
		(width 0.089408)
		(layer "In11.Cu")
		(net "SMB_VR_STBY_LVC3_SCL")
	)
	(segment
		(start 12.61364 -104.291892)
		(end 12.61364 -104.296972)
		(width 0.089408)
		(layer "In11.Cu")
		(net "SMB_VR_STBY_LVC3_SCL")
	)
	(segment
		(start 15.194534 -121.345452)
		(end 12.152376 -121.345452)
		(width 0.089408)
		(layer "In11.Cu")
		(net "SMB_VR_STBY_LVC3_SCL")
	)
	(segment
		(start 338.219542 -34.981896)
		(end 355.07676 -34.981896)
		(width 0.089408)
		(layer "In11.Cu")
		(net "SMB_VR_STBY_LVC3_SCL")
	)
	(segment
		(start 362.40339 -27.655266)
		(end 362.40339 -18.051272)
		(width 0.089408)
		(layer "In11.Cu")
		(net "SMB_VR_STBY_LVC3_SCL")
	)
	(segment
		(start 365.620808 -142.681452)
		(end 367.977166 -145.03781)
		(width 0.089408)
		(layer "In11.Cu")
		(net "SMB_VR_STBY_LVC3_SCL")
	)
	(segment
		(start 355.07676 -34.981896)
		(end 362.40339 -27.655266)
		(width 0.089408)
		(layer "In11.Cu")
		(net "SMB_VR_STBY_LVC3_SCL")
	)
	(segment
		(start 368.30889 -145.03781)
		(end 368.5921 -144.7546)
		(width 0.089408)
		(layer "In11.Cu")
		(net "SMB_VR_STBY_LVC3_SCL")
	)
	(segment
		(start 12.13866 -67.542918)
		(end 11.640312 -67.04457)
		(width 0.089408)
		(layer "In11.Cu")
		(net "SMB_VR_STBY_LVC3_SCL")
	)
	(segment
		(start 180.029612 4.636516)
		(end 179.91582 4.522724)
		(width 0.089408)
		(layer "In11.Cu")
		(net "SMB_VR_STBY_LVC3_SCL")
	)
	(segment
		(start 2.53238 -125.463554)
		(end 0.116586 -125.463554)
		(width 0.089408)
		(layer "In11.Cu")
		(net "SMB_VR_STBY_LVC3_SCL")
	)
	(segment
		(start 181.204616 5.116068)
		(end 180.725064 4.636516)
		(width 0.089408)
		(layer "In11.Cu")
		(net "SMB_VR_STBY_LVC3_SCL")
	)
	(segment
		(start 344.684096 -20.992592)
		(end 344.684096 -20.332192)
		(width 0.089408)
		(layer "In11.Cu")
		(net "SMB_VR_STBY_LVC3_SCL")
	)
	(segment
		(start 344.684096 -20.332192)
		(end 343.909142 -19.557238)
		(width 0.089408)
		(layer "In11.Cu")
		(net "SMB_VR_STBY_LVC3_SCL")
	)
	(segment
		(start 329.657202 -4.665726)
		(end 329.657202 -1.514348)
		(width 0.089408)
		(layer "In11.Cu")
		(net "SMB_VR_STBY_LVC3_SCL")
	)
	(segment
		(start 11.640312 -51.80076)
		(end 16.707104 -46.733968)
		(width 0.089408)
		(layer "In11.Cu")
		(net "SMB_VR_STBY_LVC3_SCL")
	)
	(segment
		(start -0.46228 -126.04242)
		(end -0.46228 -129.620264)
		(width 0.089408)
		(layer "In11.Cu")
		(net "SMB_VR_STBY_LVC3_SCL")
	)
	(segment
		(start 12.13866 -70.829932)
		(end 12.13866 -67.542918)
		(width 0.089408)
		(layer "In11.Cu")
		(net "SMB_VR_STBY_LVC3_SCL")
	)
	(segment
		(start 399.35912 -17.501108)
		(end 402.784564 -14.075664)
		(width 0.089408)
		(layer "In11.Cu")
		(net "SMB_VR_STBY_LVC3_SCL")
	)
	(segment
		(start 12.18438 -91.3257)
		(end 12.18438 -91.549982)
		(width 0.089408)
		(layer "In11.Cu")
		(net "SMB_VR_STBY_LVC3_SCL")
	)
	(segment
		(start 380.026926 -6.868668)
		(end 381.73279 -8.574532)
		(width 0.089408)
		(layer "In11.Cu")
		(net "SMB_VR_STBY_LVC3_SCL")
	)
	(segment
		(start 13.709396 -105.022396)
		(end 14.341856 -105.654856)
		(width 0.089408)
		(layer "In11.Cu")
		(net "SMB_VR_STBY_LVC3_SCL")
	)
	(segment
		(start 22.117812 -5.843524)
		(end 21.62556 -5.351272)
		(width 0.089408)
		(layer "In11.Cu")
		(net "SMB_VR_STBY_LVC3_SCL")
	)
	(segment
		(start 418.832792 -15.708884)
		(end 418.832792 -16.370046)
		(width 0.089408)
		(layer "In11.Cu")
		(net "SMB_VR_STBY_LVC3_SCL")
	)
	(segment
		(start 16.707104 -43.14444)
		(end 14.724888 -41.162224)
		(width 0.089408)
		(layer "In11.Cu")
		(net "SMB_VR_STBY_LVC3_SCL")
	)
	(segment
		(start 1.14808 -131.058158)
		(end 0.851916 -131.354322)
		(width 0.089408)
		(layer "In11.Cu")
		(net "SMB_VR_STBY_LVC3_SCL")
	)
	(segment
		(start 344.594688 -21.082)
		(end 344.684096 -20.992592)
		(width 0.089408)
		(layer "In11.Cu")
		(net "SMB_VR_STBY_LVC3_SCL")
	)
	(segment
		(start 175.272192 -71.387462)
		(end 175.272192 -71.516494)
		(width 0.089408)
		(layer "In11.Cu")
		(net "SMB_VR_STBY_LVC3_SCL")
	)
	(segment
		(start 11.854688 -90.614246)
		(end 11.854688 -84.299552)
		(width 0.089408)
		(layer "In11.Cu")
		(net "SMB_VR_STBY_LVC3_SCL")
	)
	(segment
		(start 417.199572 -14.075664)
		(end 418.832792 -15.708884)
		(width 0.089408)
		(layer "In11.Cu")
		(net "SMB_VR_STBY_LVC3_SCL")
	)
	(segment
		(start 330.798424 -8.61949)
		(end 330.798424 -5.806948)
		(width 0.089408)
		(layer "In11.Cu")
		(net "SMB_VR_STBY_LVC3_SCL")
	)
	(segment
		(start 12.18438 -91.3257)
		(end 12.18438 -90.943938)
		(width 0.089408)
		(layer "In11.Cu")
		(net "SMB_VR_STBY_LVC3_SCL")
	)
	(segment
		(start 11.640312 -71.32828)
		(end 12.13866 -70.829932)
		(width 0.089408)
		(layer "In11.Cu")
		(net "SMB_VR_STBY_LVC3_SCL")
	)
	(segment
		(start 7.266686 -123.674886)
		(end 7.09676 -123.50496)
		(width 0.089408)
		(layer "In11.Cu")
		(net "SMB_VR_STBY_LVC3_SCL")
	)
	(segment
		(start 7.09676 -123.50496)
		(end 4.490974 -123.50496)
		(width 0.089408)
		(layer "In11.Cu")
		(net "SMB_VR_STBY_LVC3_SCL")
	)
	(segment
		(start 372.22684 -6.868668)
		(end 380.026926 -6.868668)
		(width 0.089408)
		(layer "In11.Cu")
		(net "SMB_VR_STBY_LVC3_SCL")
	)
	(segment
		(start 392.076432 -8.148828)
		(end 394.165836 -6.059424)
		(width 0.089408)
		(layer "In11.Cu")
		(net "SMB_VR_STBY_LVC3_SCL")
	)
	(segment
		(start 175.272192 -71.516494)
		(end 174.50435 -72.284336)
		(width 0.089408)
		(layer "In11.Cu")
		(net "SMB_VR_STBY_LVC3_SCL")
	)
	(segment
		(start 341.232236 -19.557238)
		(end 340.286848 -18.61185)
		(width 0.089408)
		(layer "In11.Cu")
		(net "SMB_VR_STBY_LVC3_SCL")
	)
	(segment
		(start 12.864592 -83.289648)
		(end 12.864592 -81.267808)
		(width 0.089408)
		(layer "In11.Cu")
		(net "SMB_VR_STBY_LVC3_SCL")
	)
	(segment
		(start 169.09796 -71.44004)
		(end 168.1988 -72.3392)
		(width 0.089408)
		(layer "In11.Cu")
		(net "SMB_VR_STBY_LVC3_SCL")
	)
	(segment
		(start 335.721706 -12.418568)
		(end 332.24978 -8.946642)
		(width 0.089408)
		(layer "In11.Cu")
		(net "SMB_VR_STBY_LVC3_SCL")
	)
	(segment
		(start 14.724888 -22.448266)
		(end 15.134844 -22.03831)
		(width 0.089408)
		(layer "In11.Cu")
		(net "SMB_VR_STBY_LVC3_SCL")
	)
	(segment
		(start 171.526708 -71.44004)
		(end 169.09796 -71.44004)
		(width 0.089408)
		(layer "In11.Cu")
		(net "SMB_VR_STBY_LVC3_SCL")
	)
	(segment
		(start 12.864592 -81.267808)
		(end 11.640312 -80.043528)
		(width 0.089408)
		(layer "In11.Cu")
		(net "SMB_VR_STBY_LVC3_SCL")
	)
	(segment
		(start 402.784564 -14.075664)
		(end 417.199572 -14.075664)
		(width 0.089408)
		(layer "In11.Cu")
		(net "SMB_VR_STBY_LVC3_SCL")
	)
	(segment
		(start 329.181968 -1.039114)
		(end 329.181968 4.525518)
		(width 0.089408)
		(layer "In11.Cu")
		(net "SMB_VR_STBY_LVC3_SCL")
	)
	(segment
		(start 14.569948 -1.268476)
		(end 15.746476 -0.091948)
		(width 0.089408)
		(layer "In11.Cu")
		(net "SMB_VR_STBY_LVC3_SCL")
	)
	(segment
		(start 22.117812 -21.36902)
		(end 22.117812 -5.843524)
		(width 0.089408)
		(layer "In11.Cu")
		(net "SMB_VR_STBY_LVC3_SCL")
	)
	(segment
		(start -0.46228 -129.620264)
		(end 0.01905 -130.101594)
		(width 0.089408)
		(layer "In11.Cu")
		(net "SMB_VR_STBY_LVC3_SCL")
	)
	(segment
		(start 16.707104 -46.733968)
		(end 16.707104 -43.14444)
		(width 0.089408)
		(layer "In11.Cu")
		(net "SMB_VR_STBY_LVC3_SCL")
	)
	(segment
		(start 344.297 -21.082)
		(end 344.594688 -21.082)
		(width 0.089408)
		(layer "In11.Cu")
		(net "SMB_VR_STBY_LVC3_SCL")
	)
	(segment
		(start 0.690372 -130.101594)
		(end 1.14808 -130.559302)
		(width 0.089408)
		(layer "In11.Cu")
		(net "SMB_VR_STBY_LVC3_SCL")
	)
	(segment
		(start 1.14808 -130.559302)
		(end 1.14808 -131.058158)
		(width 0.089408)
		(layer "In11.Cu")
		(net "SMB_VR_STBY_LVC3_SCL")
	)
	(segment
		(start 17.345406 -119.19458)
		(end 15.194534 -121.345452)
		(width 0.089408)
		(layer "In11.Cu")
		(net "SMB_VR_STBY_LVC3_SCL")
	)
	(segment
		(start 370.281708 -10.172954)
		(end 370.281708 -8.8138)
		(width 0.089408)
		(layer "In11.Cu")
		(net "SMB_VR_STBY_LVC3_SCL")
	)
	(segment
		(start 14.569948 -4.770628)
		(end 14.569948 -1.268476)
		(width 0.089408)
		(layer "In11.Cu")
		(net "SMB_VR_STBY_LVC3_SCL")
	)
	(segment
		(start 332.24978 -8.946642)
		(end 331.125576 -8.946642)
		(width 0.089408)
		(layer "In11.Cu")
		(net "SMB_VR_STBY_LVC3_SCL")
	)
	(segment
		(start 330.798424 -5.806948)
		(end 329.657202 -4.665726)
		(width 0.089408)
		(layer "In11.Cu")
		(net "SMB_VR_STBY_LVC3_SCL")
	)
	(segment
		(start 328.591418 5.116068)
		(end 181.204616 5.116068)
		(width 0.089408)
		(layer "In11.Cu")
		(net "SMB_VR_STBY_LVC3_SCL")
	)
	(segment
		(start 337.887564 -34.649918)
		(end 338.219542 -34.981896)
		(width 0.089408)
		(layer "In11.Cu")
		(net "SMB_VR_STBY_LVC3_SCL")
	)
	(segment
		(start 343.909142 -19.557238)
		(end 341.232236 -19.557238)
		(width 0.089408)
		(layer "In11.Cu")
		(net "SMB_VR_STBY_LVC3_SCL")
	)
	(segment
		(start 11.640312 -80.043528)
		(end 11.640312 -71.32828)
		(width 0.089408)
		(layer "In11.Cu")
		(net "SMB_VR_STBY_LVC3_SCL")
	)
	(segment
		(start 359.956608 -137.103104)
		(end 363.446314 -140.59281)
		(width 0.089408)
		(layer "In11.Cu")
		(net "SMB_VR_STBY_LVC3_SCL")
	)
	(segment
		(start 172.371004 -72.284336)
		(end 171.526708 -71.44004)
		(width 0.089408)
		(layer "In11.Cu")
		(net "SMB_VR_STBY_LVC3_SCL")
	)
	(segment
		(start 174.50435 -72.284336)
		(end 172.371004 -72.284336)
		(width 0.089408)
		(layer "In11.Cu")
		(net "SMB_VR_STBY_LVC3_SCL")
	)
	(segment
		(start 418.832792 -16.370046)
		(end 418.662104 -16.540734)
		(width 0.089408)
		(layer "In11.Cu")
		(net "SMB_VR_STBY_LVC3_SCL")
	)
	(segment
		(start 0.116586 -125.463554)
		(end -0.46228 -126.04242)
		(width 0.089408)
		(layer "In11.Cu")
		(net "SMB_VR_STBY_LVC3_SCL")
	)
	(segment
		(start 329.657202 -1.514348)
		(end 329.181968 -1.039114)
		(width 0.089408)
		(layer "In11.Cu")
		(net "SMB_VR_STBY_LVC3_SCL")
	)
	(segment
		(start 12.18438 -90.943938)
		(end 11.854688 -90.614246)
		(width 0.089408)
		(layer "In11.Cu")
		(net "SMB_VR_STBY_LVC3_SCL")
	)
	(segment
		(start 419.336474 -22.547072)
		(end 419.336474 -22.906228)
		(width 0.10795)
		(layer "F.Cu")
		(net "SMB_BMC_PMBUS_STBY_LVC3_SDA_R")
	)
	(segment
		(start 418.290248 -26.534618)
		(end 418.112702 -26.357072)
		(width 0.10795)
		(layer "F.Cu")
		(net "SMB_BMC_PMBUS_STBY_LVC3_SDA_R")
	)
	(segment
		(start 419.862 -21.6535)
		(end 419.862 -22.021546)
		(width 0.10795)
		(layer "F.Cu")
		(net "SMB_BMC_PMBUS_STBY_LVC3_SDA_R")
	)
	(segment
		(start 419.336474 -24.205692)
		(end 419.336474 -22.906228)
		(width 0.10795)
		(layer "F.Cu")
		(net "SMB_BMC_PMBUS_STBY_LVC3_SDA_R")
	)
	(segment
		(start 419.862 -22.021546)
		(end 419.336474 -22.547072)
		(width 0.10795)
		(layer "F.Cu")
		(net "SMB_BMC_PMBUS_STBY_LVC3_SDA_R")
	)
	(segment
		(start 418.112702 -25.429464)
		(end 419.336474 -24.205692)
		(width 0.10795)
		(layer "F.Cu")
		(net "SMB_BMC_PMBUS_STBY_LVC3_SDA_R")
	)
	(segment
		(start 418.112702 -26.357072)
		(end 418.112702 -25.429464)
		(width 0.10795)
		(layer "F.Cu")
		(net "SMB_BMC_PMBUS_STBY_LVC3_SDA_R")
	)
	(via
		(at 419.336474 -22.906228)
		(size 0.762)
		(drill 0.381)
		(layers "F.Cu" "B.Cu")
		(net "SMB_BMC_PMBUS_STBY_LVC3_SDA_R")
	)
	(segment
		(start 417.852352 -25.181814)
		(end 418.487352 -24.546814)
		(width 0.10795)
		(layer "F.Cu")
		(net "SMB_BMC_PMBUS_STBY_LVC3_SCL_R")
	)
	(segment
		(start 419.0746 -21.9964)
		(end 418.487352 -22.583648)
		(width 0.10795)
		(layer "F.Cu")
		(net "SMB_BMC_PMBUS_STBY_LVC3_SCL_R")
	)
	(segment
		(start 418.487352 -24.546814)
		(end 418.487352 -23.957788)
		(width 0.10795)
		(layer "F.Cu")
		(net "SMB_BMC_PMBUS_STBY_LVC3_SCL_R")
	)
	(segment
		(start 417.490148 -27.334718)
		(end 417.852352 -26.972514)
		(width 0.10795)
		(layer "F.Cu")
		(net "SMB_BMC_PMBUS_STBY_LVC3_SCL_R")
	)
	(segment
		(start 417.852352 -26.972514)
		(end 417.852352 -25.181814)
		(width 0.10795)
		(layer "F.Cu")
		(net "SMB_BMC_PMBUS_STBY_LVC3_SCL_R")
	)
	(segment
		(start 418.487352 -22.583648)
		(end 418.487352 -23.957788)
		(width 0.10795)
		(layer "F.Cu")
		(net "SMB_BMC_PMBUS_STBY_LVC3_SCL_R")
	)
	(segment
		(start 419.0746 -21.6535)
		(end 419.0746 -21.9964)
		(width 0.10795)
		(layer "F.Cu")
		(net "SMB_BMC_PMBUS_STBY_LVC3_SCL_R")
	)
	(via
		(at 418.487352 -23.957788)
		(size 0.762)
		(drill 0.381)
		(layers "F.Cu" "B.Cu")
		(net "SMB_BMC_PMBUS_STBY_LVC3_SCL_R")
	)
	(segment
		(start 400.489674 -32.61614)
		(end 400.530314 -32.61614)
		(width 0.10795)
		(layer "F.Cu")
		(net "SMB_HOST_STBY_LVC3_SDA_R")
	)
	(segment
		(start 402.95449 -33.188402)
		(end 403.48154 -33.188402)
		(width 0.10795)
		(layer "F.Cu")
		(net "SMB_HOST_STBY_LVC3_SDA_R")
	)
	(segment
		(start 406.450546 -32.588454)
		(end 407.544016 -32.588454)
		(width 0.10795)
		(layer "F.Cu")
		(net "SMB_HOST_STBY_LVC3_SDA_R")
	)
	(segment
		(start 402.66874 -32.5374)
		(end 402.66874 -32.902652)
		(width 0.10795)
		(layer "F.Cu")
		(net "SMB_HOST_STBY_LVC3_SDA_R")
	)
	(segment
		(start 400.924014 -32.22244)
		(end 402.35378 -32.22244)
		(width 0.10795)
		(layer "F.Cu")
		(net "SMB_HOST_STBY_LVC3_SDA_R")
	)
	(segment
		(start 402.35378 -32.22244)
		(end 402.66874 -32.5374)
		(width 0.10795)
		(layer "F.Cu")
		(net "SMB_HOST_STBY_LVC3_SDA_R")
	)
	(segment
		(start 407.544016 -32.588454)
		(end 407.890218 -32.934656)
		(width 0.10795)
		(layer "F.Cu")
		(net "SMB_HOST_STBY_LVC3_SDA_R")
	)
	(segment
		(start 403.48154 -33.188402)
		(end 405.850598 -33.188402)
		(width 0.10795)
		(layer "F.Cu")
		(net "SMB_HOST_STBY_LVC3_SDA_R")
	)
	(segment
		(start 402.66874 -32.902652)
		(end 402.95449 -33.188402)
		(width 0.10795)
		(layer "F.Cu")
		(net "SMB_HOST_STBY_LVC3_SDA_R")
	)
	(segment
		(start 405.850598 -33.188402)
		(end 406.450546 -32.588454)
		(width 0.10795)
		(layer "F.Cu")
		(net "SMB_HOST_STBY_LVC3_SDA_R")
	)
	(segment
		(start 400.530314 -32.61614)
		(end 400.924014 -32.22244)
		(width 0.10795)
		(layer "F.Cu")
		(net "SMB_HOST_STBY_LVC3_SDA_R")
	)
	(via
		(at 403.48154 -33.188402)
		(size 0.508)
		(drill 0.254)
		(layers "F.Cu" "B.Cu")
		(net "SMB_HOST_STBY_LVC3_SDA_R")
	)
	(segment
		(start 406.472644 -32.934656)
		(end 405.9301 -33.4772)
		(width 0.10795)
		(layer "F.Cu")
		(net "SMB_HOST_STBY_LVC3_SCL_R")
	)
	(segment
		(start 402.66874 -33.664652)
		(end 402.66874 -33.98266)
		(width 0.10795)
		(layer "F.Cu")
		(net "SMB_HOST_STBY_LVC3_SCL_R")
	)
	(segment
		(start 402.59 -34.0614)
		(end 402.59 -34.426652)
		(width 0.10795)
		(layer "F.Cu")
		(net "SMB_HOST_STBY_LVC3_SCL_R")
	)
	(segment
		(start 405.9301 -33.4772)
		(end 404.72868 -33.4772)
		(width 0.10795)
		(layer "F.Cu")
		(net "SMB_HOST_STBY_LVC3_SCL_R")
	)
	(segment
		(start 404.72868 -33.4772)
		(end 402.856192 -33.4772)
		(width 0.10795)
		(layer "F.Cu")
		(net "SMB_HOST_STBY_LVC3_SCL_R")
	)
	(segment
		(start 407.090118 -32.934656)
		(end 406.472644 -32.934656)
		(width 0.10795)
		(layer "F.Cu")
		(net "SMB_HOST_STBY_LVC3_SCL_R")
	)
	(segment
		(start 402.66874 -33.98266)
		(end 402.59 -34.0614)
		(width 0.10795)
		(layer "F.Cu")
		(net "SMB_HOST_STBY_LVC3_SCL_R")
	)
	(segment
		(start 402.856192 -33.4772)
		(end 402.66874 -33.664652)
		(width 0.10795)
		(layer "F.Cu")
		(net "SMB_HOST_STBY_LVC3_SCL_R")
	)
	(via
		(at 404.72868 -33.4772)
		(size 0.508)
		(drill 0.254)
		(layers "F.Cu" "B.Cu")
		(net "SMB_HOST_STBY_LVC3_SCL_R")
	)
	(segment
		(start 128.514348 -62.838584)
		(end 129.085848 -62.838584)
		(width 0.1016)
		(layer "F.Cu")
		(net "SMB_DDR_KLM_SDA_G_R")
	)
	(via
		(at 155.8798 -120.53824)
		(size 0.6604)
		(drill 0.3302)
		(layers "F.Cu" "B.Cu")
		(net "SMB_DDR_KLM_SDA_G_R")
	)
	(via
		(at 129.085848 -62.838584)
		(size 0.508)
		(drill 0.254)
		(layers "F.Cu" "B.Cu")
		(net "SMB_DDR_KLM_SDA_G_R")
	)
	(via
		(at 155.2575 -121.0945)
		(size 0.508)
		(drill 0.254)
		(layers "F.Cu" "B.Cu")
		(net "SMB_DDR_KLM_SDA_G_R")
	)
	(segment
		(start 155.8798 -120.53824)
		(end 155.98267 -120.53824)
		(width 0.10795)
		(layer "B.Cu")
		(net "SMB_DDR_KLM_SDA_G_R")
	)
	(segment
		(start 155.98267 -120.53824)
		(end 156.19222 -120.74779)
		(width 0.10795)
		(layer "B.Cu")
		(net "SMB_DDR_KLM_SDA_G_R")
	)
	(segment
		(start 156.19222 -120.74779)
		(end 156.19222 -121.4247)
		(width 0.10795)
		(layer "B.Cu")
		(net "SMB_DDR_KLM_SDA_G_R")
	)
	(segment
		(start 155.40736 -120.53824)
		(end 155.2575 -120.6881)
		(width 0.10795)
		(layer "B.Cu")
		(net "SMB_DDR_KLM_SDA_G_R")
	)
	(segment
		(start 155.2575 -120.6881)
		(end 155.2575 -121.0945)
		(width 0.10795)
		(layer "B.Cu")
		(net "SMB_DDR_KLM_SDA_G_R")
	)
	(segment
		(start 155.8798 -120.53824)
		(end 155.40736 -120.53824)
		(width 0.10795)
		(layer "B.Cu")
		(net "SMB_DDR_KLM_SDA_G_R")
	)
	(segment
		(start 131.656582 -74.630534)
		(end 131.679188 -74.630534)
		(width 0.0889)
		(layer "In9.Cu")
		(net "SMB_DDR_KLM_SDA_G_R")
	)
	(segment
		(start 129.070862 -63.238634)
		(end 129.103628 -63.238634)
		(width 0.0889)
		(layer "In9.Cu")
		(net "SMB_DDR_KLM_SDA_G_R")
	)
	(segment
		(start 128.792732 -63.007748)
		(end 128.77165 -63.086488)
		(width 0.0889)
		(layer "In9.Cu")
		(net "SMB_DDR_KLM_SDA_G_R")
	)
	(segment
		(start 141.872462 -81.564734)
		(end 142.293848 -81.564734)
		(width 0.0889)
		(layer "In9.Cu")
		(net "SMB_DDR_KLM_SDA_G_R")
	)
	(segment
		(start 136.801098 -77.602588)
		(end 136.833864 -77.602588)
		(width 0.0889)
		(layer "In9.Cu")
		(net "SMB_DDR_KLM_SDA_G_R")
	)
	(segment
		(start 133.367018 -75.621388)
		(end 133.399784 -75.621388)
		(width 0.0889)
		(layer "In9.Cu")
		(net "SMB_DDR_KLM_SDA_G_R")
	)
	(segment
		(start 149.424644 -99.839018)
		(end 150.048722 -100.968302)
		(width 0.089408)
		(layer "In9.Cu")
		(net "SMB_DDR_KLM_SDA_G_R")
	)
	(segment
		(start 155.199334 -120.779286)
		(end 155.199334 -121.036334)
		(width 0.089408)
		(layer "In9.Cu")
		(net "SMB_DDR_KLM_SDA_G_R")
	)
	(segment
		(start 131.309872 -71.4502)
		(end 131.314698 -71.458836)
		(width 0.0889)
		(layer "In9.Cu")
		(net "SMB_DDR_KLM_SDA_G_R")
	)
	(segment
		(start 137.655808 -78.097634)
		(end 137.683748 -78.097634)
		(width 0.0889)
		(layer "In9.Cu")
		(net "SMB_DDR_KLM_SDA_G_R")
	)
	(segment
		(start 131.314698 -72.449436)
		(end 131.321048 -72.460104)
		(width 0.0889)
		(layer "In9.Cu")
		(net "SMB_DDR_KLM_SDA_G_R")
	)
	(segment
		(start 132.173218 -74.925682)
		(end 132.17652 -74.931524)
		(width 0.0889)
		(layer "In9.Cu")
		(net "SMB_DDR_KLM_SDA_G_R")
	)
	(segment
		(start 150.076154 -100.993448)
		(end 153.884376 -113.960402)
		(width 0.089408)
		(layer "In9.Cu")
		(net "SMB_DDR_KLM_SDA_G_R")
	)
	(segment
		(start 138.518138 -78.593188)
		(end 138.550904 -78.593188)
		(width 0.0889)
		(layer "In9.Cu")
		(net "SMB_DDR_KLM_SDA_G_R")
	)
	(segment
		(start 155.199334 -121.036334)
		(end 155.2575 -121.0945)
		(width 0.089408)
		(layer "In9.Cu")
		(net "SMB_DDR_KLM_SDA_G_R")
	)
	(segment
		(start 153.884376 -113.960402)
		(end 155.3591 -117.136418)
		(width 0.089408)
		(layer "In9.Cu")
		(net "SMB_DDR_KLM_SDA_G_R")
	)
	(segment
		(start 141.01191 -81.040478)
		(end 141.278356 -81.06029)
		(width 0.0889)
		(layer "In9.Cu")
		(net "SMB_DDR_KLM_SDA_G_R")
	)
	(segment
		(start 150.048722 -100.968302)
		(end 150.076154 -100.993448)
		(width 0.089408)
		(layer "In9.Cu")
		(net "SMB_DDR_KLM_SDA_G_R")
	)
	(segment
		(start 132.519674 -75.125834)
		(end 132.537454 -75.125834)
		(width 0.0889)
		(layer "In9.Cu")
		(net "SMB_DDR_KLM_SDA_G_R")
	)
	(segment
		(start 140.235178 -79.583788)
		(end 140.449554 -79.583788)
		(width 0.0889)
		(layer "In9.Cu")
		(net "SMB_DDR_KLM_SDA_G_R")
	)
	(segment
		(start 135.084058 -76.611988)
		(end 135.116824 -76.611988)
		(width 0.0889)
		(layer "In9.Cu")
		(net "SMB_DDR_KLM_SDA_G_R")
	)
	(segment
		(start 131.314698 -68.487036)
		(end 131.321048 -68.497704)
		(width 0.0889)
		(layer "In9.Cu")
		(net "SMB_DDR_KLM_SDA_G_R")
	)
	(segment
		(start 139.3698 -79.088234)
		(end 139.405614 -79.088234)
		(width 0.0889)
		(layer "In9.Cu")
		(net "SMB_DDR_KLM_SDA_G_R")
	)
	(segment
		(start 129.085848 -62.838584)
		(end 128.792732 -63.007748)
		(width 0.0889)
		(layer "In9.Cu")
		(net "SMB_DDR_KLM_SDA_G_R")
	)
	(segment
		(start 135.938768 -77.107034)
		(end 135.971534 -77.107034)
		(width 0.0889)
		(layer "In9.Cu")
		(net "SMB_DDR_KLM_SDA_G_R")
	)
	(segment
		(start 131.309872 -69.469)
		(end 131.314698 -69.477636)
		(width 0.0889)
		(layer "In9.Cu")
		(net "SMB_DDR_KLM_SDA_G_R")
	)
	(segment
		(start 131.314698 -74.030332)
		(end 131.309872 -74.038968)
		(width 0.0889)
		(layer "In9.Cu")
		(net "SMB_DDR_KLM_SDA_G_R")
	)
	(segment
		(start 144.974564 -83.135978)
		(end 149.424644 -99.839018)
		(width 0.089408)
		(layer "In9.Cu")
		(net "SMB_DDR_KLM_SDA_G_R")
	)
	(segment
		(start 155.3591 -117.136418)
		(end 155.3591 -120.61952)
		(width 0.089408)
		(layer "In9.Cu")
		(net "SMB_DDR_KLM_SDA_G_R")
	)
	(segment
		(start 131.195064 -66.069464)
		(end 131.195064 -68.156836)
		(width 0.0889)
		(layer "In9.Cu")
		(net "SMB_DDR_KLM_SDA_G_R")
	)
	(segment
		(start 142.293848 -81.564734)
		(end 144.931384 -82.988912)
		(width 0.0889)
		(layer "In9.Cu")
		(net "SMB_DDR_KLM_SDA_G_R")
	)
	(segment
		(start 144.931384 -82.988912)
		(end 144.974564 -83.135978)
		(width 0.089408)
		(layer "In9.Cu")
		(net "SMB_DDR_KLM_SDA_G_R")
	)
	(segment
		(start 131.314698 -69.477636)
		(end 131.321048 -69.488304)
		(width 0.0889)
		(layer "In9.Cu")
		(net "SMB_DDR_KLM_SDA_G_R")
	)
	(segment
		(start 129.830322 -64.708278)
		(end 129.833878 -64.708278)
		(width 0.0889)
		(layer "In9.Cu")
		(net "SMB_DDR_KLM_SDA_G_R")
	)
	(segment
		(start 134.221728 -76.116434)
		(end 134.254494 -76.116434)
		(width 0.0889)
		(layer "In9.Cu")
		(net "SMB_DDR_KLM_SDA_G_R")
	)
	(segment
		(start 131.309872 -72.4408)
		(end 131.314698 -72.449436)
		(width 0.0889)
		(layer "In9.Cu")
		(net "SMB_DDR_KLM_SDA_G_R")
	)
	(segment
		(start 131.314698 -71.458836)
		(end 131.321048 -71.469504)
		(width 0.0889)
		(layer "In9.Cu")
		(net "SMB_DDR_KLM_SDA_G_R")
	)
	(segment
		(start 129.833878 -64.708278)
		(end 131.195064 -66.069464)
		(width 0.0889)
		(layer "In9.Cu")
		(net "SMB_DDR_KLM_SDA_G_R")
	)
	(segment
		(start 155.3591 -120.61952)
		(end 155.199334 -120.779286)
		(width 0.089408)
		(layer "In9.Cu")
		(net "SMB_DDR_KLM_SDA_G_R")
	)
	(segment
		(start 131.309872 -73.4314)
		(end 131.314698 -73.440036)
		(width 0.0889)
		(layer "In9.Cu")
		(net "SMB_DDR_KLM_SDA_G_R")
	)
	(arc
		(start 139.405614 -79.088234)
		(mid 139.691038 -79.171701)
		(end 139.899644 -79.383636)
		(width 0.0889)
		(layer "In9.Cu")
		(net "SMB_DDR_KLM_SDA_G_R")
	)
	(arc
		(start 131.314698 -69.077586)
		(mid 131.261228 -69.272649)
		(end 131.309872 -69.469)
		(width 0.0889)
		(layer "In9.Cu")
		(net "SMB_DDR_KLM_SDA_G_R")
	)
	(arc
		(start 131.314698 -72.049386)
		(mid 131.261228 -72.244449)
		(end 131.309872 -72.4408)
		(width 0.0889)
		(layer "In9.Cu")
		(net "SMB_DDR_KLM_SDA_G_R")
	)
	(arc
		(start 136.833864 -77.602588)
		(mid 137.117081 -77.686869)
		(end 137.324084 -77.897736)
		(width 0.0889)
		(layer "In9.Cu")
		(net "SMB_DDR_KLM_SDA_G_R")
	)
	(arc
		(start 131.321048 -68.497704)
		(mid 131.393846 -68.788467)
		(end 131.314698 -69.077586)
		(width 0.0889)
		(layer "In9.Cu")
		(net "SMB_DDR_KLM_SDA_G_R")
	)
	(arc
		(start 131.314698 -70.467982)
		(mid 131.393829 -70.763384)
		(end 131.314698 -71.058786)
		(width 0.0889)
		(layer "In9.Cu")
		(net "SMB_DDR_KLM_SDA_G_R")
	)
	(arc
		(start 128.77165 -63.086488)
		(mid 128.904531 -63.195471)
		(end 129.070862 -63.238634)
		(width 0.0889)
		(layer "In9.Cu")
		(net "SMB_DDR_KLM_SDA_G_R")
	)
	(arc
		(start 134.254494 -76.116434)
		(mid 134.539918 -76.199901)
		(end 134.748524 -76.411836)
		(width 0.0889)
		(layer "In9.Cu")
		(net "SMB_DDR_KLM_SDA_G_R")
	)
	(arc
		(start 135.971534 -77.107034)
		(mid 136.256958 -77.190501)
		(end 136.465564 -77.402436)
		(width 0.0889)
		(layer "In9.Cu")
		(net "SMB_DDR_KLM_SDA_G_R")
	)
	(arc
		(start 141.278356 -81.06029)
		(mid 141.498653 -81.17556)
		(end 141.656562 -81.36763)
		(width 0.0889)
		(layer "In9.Cu")
		(net "SMB_DDR_KLM_SDA_G_R")
	)
	(arc
		(start 131.195064 -68.156836)
		(mid 131.240356 -68.327197)
		(end 131.314698 -68.487036)
		(width 0.0889)
		(layer "In9.Cu")
		(net "SMB_DDR_KLM_SDA_G_R")
	)
	(arc
		(start 141.656562 -81.36763)
		(mid 141.74738 -81.484952)
		(end 141.872462 -81.564734)
		(width 0.0889)
		(layer "In9.Cu")
		(net "SMB_DDR_KLM_SDA_G_R")
	)
	(arc
		(start 131.314698 -70.068186)
		(mid 131.261199 -70.268084)
		(end 131.314698 -70.467982)
		(width 0.0889)
		(layer "In9.Cu")
		(net "SMB_DDR_KLM_SDA_G_R")
	)
	(arc
		(start 140.796518 -80.85074)
		(mid 140.888416 -80.963542)
		(end 141.01191 -81.040478)
		(width 0.0889)
		(layer "In9.Cu")
		(net "SMB_DDR_KLM_SDA_G_R")
	)
	(arc
		(start 140.78077 -80.537812)
		(mid 140.751295 -80.696164)
		(end 140.796518 -80.85074)
		(width 0.0889)
		(layer "In9.Cu")
		(net "SMB_DDR_KLM_SDA_G_R")
	)
	(arc
		(start 140.449554 -79.583788)
		(mid 140.652148 -79.699606)
		(end 140.798042 -79.88173)
		(width 0.0889)
		(layer "In9.Cu")
		(net "SMB_DDR_KLM_SDA_G_R")
	)
	(arc
		(start 132.537454 -75.125834)
		(mid 132.822878 -75.209301)
		(end 133.031484 -75.421236)
		(width 0.0889)
		(layer "In9.Cu")
		(net "SMB_DDR_KLM_SDA_G_R")
	)
	(arc
		(start 136.465564 -77.402436)
		(mid 136.607247 -77.54624)
		(end 136.801098 -77.602588)
		(width 0.0889)
		(layer "In9.Cu")
		(net "SMB_DDR_KLM_SDA_G_R")
	)
	(arc
		(start 131.314698 -73.440036)
		(mid 131.393703 -73.735184)
		(end 131.314698 -74.030332)
		(width 0.0889)
		(layer "In9.Cu")
		(net "SMB_DDR_KLM_SDA_G_R")
	)
	(arc
		(start 129.597658 -64.124586)
		(mid 129.57263 -64.472734)
		(end 129.830322 -64.708278)
		(width 0.0889)
		(layer "In9.Cu")
		(net "SMB_DDR_KLM_SDA_G_R")
	)
	(arc
		(start 132.17652 -74.931524)
		(mid 132.322486 -75.073923)
		(end 132.519674 -75.125834)
		(width 0.0889)
		(layer "In9.Cu")
		(net "SMB_DDR_KLM_SDA_G_R")
	)
	(arc
		(start 129.103628 -63.238634)
		(mid 129.601879 -63.541474)
		(end 129.597658 -64.124586)
		(width 0.0889)
		(layer "In9.Cu")
		(net "SMB_DDR_KLM_SDA_G_R")
	)
	(arc
		(start 135.607044 -76.907136)
		(mid 135.747123 -77.049872)
		(end 135.938768 -77.107034)
		(width 0.0889)
		(layer "In9.Cu")
		(net "SMB_DDR_KLM_SDA_G_R")
	)
	(arc
		(start 139.041124 -78.888336)
		(mid 139.179868 -79.030369)
		(end 139.3698 -79.088234)
		(width 0.0889)
		(layer "In9.Cu")
		(net "SMB_DDR_KLM_SDA_G_R")
	)
	(arc
		(start 131.321048 -71.469504)
		(mid 131.393846 -71.760267)
		(end 131.314698 -72.049386)
		(width 0.0889)
		(layer "In9.Cu")
		(net "SMB_DDR_KLM_SDA_G_R")
	)
	(arc
		(start 131.309872 -74.038968)
		(mid 131.31616 -74.432623)
		(end 131.656582 -74.630534)
		(width 0.0889)
		(layer "In9.Cu")
		(net "SMB_DDR_KLM_SDA_G_R")
	)
	(arc
		(start 139.899644 -79.383636)
		(mid 140.041327 -79.52744)
		(end 140.235178 -79.583788)
		(width 0.0889)
		(layer "In9.Cu")
		(net "SMB_DDR_KLM_SDA_G_R")
	)
	(arc
		(start 138.550904 -78.593188)
		(mid 138.834121 -78.677469)
		(end 139.041124 -78.888336)
		(width 0.0889)
		(layer "In9.Cu")
		(net "SMB_DDR_KLM_SDA_G_R")
	)
	(arc
		(start 131.314698 -71.058786)
		(mid 131.261228 -71.253849)
		(end 131.309872 -71.4502)
		(width 0.0889)
		(layer "In9.Cu")
		(net "SMB_DDR_KLM_SDA_G_R")
	)
	(arc
		(start 138.182604 -78.393036)
		(mid 138.324287 -78.53684)
		(end 138.518138 -78.593188)
		(width 0.0889)
		(layer "In9.Cu")
		(net "SMB_DDR_KLM_SDA_G_R")
	)
	(arc
		(start 134.748524 -76.411836)
		(mid 134.890207 -76.55564)
		(end 135.084058 -76.611988)
		(width 0.0889)
		(layer "In9.Cu")
		(net "SMB_DDR_KLM_SDA_G_R")
	)
	(arc
		(start 135.116824 -76.611988)
		(mid 135.400041 -76.696269)
		(end 135.607044 -76.907136)
		(width 0.0889)
		(layer "In9.Cu")
		(net "SMB_DDR_KLM_SDA_G_R")
	)
	(arc
		(start 131.314698 -73.039986)
		(mid 131.261228 -73.235049)
		(end 131.309872 -73.4314)
		(width 0.0889)
		(layer "In9.Cu")
		(net "SMB_DDR_KLM_SDA_G_R")
	)
	(arc
		(start 133.031484 -75.421236)
		(mid 133.173167 -75.56504)
		(end 133.367018 -75.621388)
		(width 0.0889)
		(layer "In9.Cu")
		(net "SMB_DDR_KLM_SDA_G_R")
	)
	(arc
		(start 137.683748 -78.097634)
		(mid 137.971893 -78.179953)
		(end 138.182604 -78.393036)
		(width 0.0889)
		(layer "In9.Cu")
		(net "SMB_DDR_KLM_SDA_G_R")
	)
	(arc
		(start 140.798042 -79.88173)
		(mid 140.875595 -80.21203)
		(end 140.78077 -80.537812)
		(width 0.0889)
		(layer "In9.Cu")
		(net "SMB_DDR_KLM_SDA_G_R")
	)
	(arc
		(start 137.324084 -77.897736)
		(mid 137.464163 -78.040472)
		(end 137.655808 -78.097634)
		(width 0.0889)
		(layer "In9.Cu")
		(net "SMB_DDR_KLM_SDA_G_R")
	)
	(arc
		(start 131.321048 -72.460104)
		(mid 131.393846 -72.750867)
		(end 131.314698 -73.039986)
		(width 0.0889)
		(layer "In9.Cu")
		(net "SMB_DDR_KLM_SDA_G_R")
	)
	(arc
		(start 131.321048 -69.488304)
		(mid 131.393846 -69.779067)
		(end 131.314698 -70.068186)
		(width 0.0889)
		(layer "In9.Cu")
		(net "SMB_DDR_KLM_SDA_G_R")
	)
	(arc
		(start 133.399784 -75.621388)
		(mid 133.683001 -75.705669)
		(end 133.890004 -75.916536)
		(width 0.0889)
		(layer "In9.Cu")
		(net "SMB_DDR_KLM_SDA_G_R")
	)
	(arc
		(start 131.679188 -74.630534)
		(mid 131.96455 -74.713922)
		(end 132.173218 -74.925682)
		(width 0.0889)
		(layer "In9.Cu")
		(net "SMB_DDR_KLM_SDA_G_R")
	)
	(arc
		(start 133.890004 -75.916536)
		(mid 134.030083 -76.059272)
		(end 134.221728 -76.116434)
		(width 0.0889)
		(layer "In9.Cu")
		(net "SMB_DDR_KLM_SDA_G_R")
	)
	(segment
		(start 127.655828 -63.334138)
		(end 128.227328 -63.334138)
		(width 0.1016)
		(layer "F.Cu")
		(net "SMB_DDR_KLM_SCL_G_R")
	)
	(via
		(at 128.227328 -63.334138)
		(size 0.508)
		(drill 0.254)
		(layers "F.Cu" "B.Cu")
		(net "SMB_DDR_KLM_SCL_G_R")
	)
	(via
		(at 154.80538 -122.95124)
		(size 0.508)
		(drill 0.254)
		(layers "F.Cu" "B.Cu")
		(net "SMB_DDR_KLM_SCL_G_R")
	)
	(segment
		(start 155.378404 -124.0917)
		(end 156.06522 -124.0917)
		(width 0.10795)
		(layer "B.Cu")
		(net "SMB_DDR_KLM_SCL_G_R")
	)
	(segment
		(start 154.80538 -123.518676)
		(end 155.378404 -124.0917)
		(width 0.10795)
		(layer "B.Cu")
		(net "SMB_DDR_KLM_SCL_G_R")
	)
	(segment
		(start 154.80538 -122.95124)
		(end 154.80538 -123.518676)
		(width 0.10795)
		(layer "B.Cu")
		(net "SMB_DDR_KLM_SCL_G_R")
	)
	(segment
		(start 149.151086 -99.949)
		(end 144.691608 -83.211162)
		(width 0.089408)
		(layer "In9.Cu")
		(net "SMB_DDR_KLM_SCL_G_R")
	)
	(segment
		(start 128.609852 -63.189104)
		(end 128.520444 -63.164974)
		(width 0.0889)
		(layer "In9.Cu")
		(net "SMB_DDR_KLM_SCL_G_R")
	)
	(segment
		(start 131.152138 -68.587112)
		(end 131.085336 -68.467478)
		(width 0.0889)
		(layer "In9.Cu")
		(net "SMB_DDR_KLM_SCL_G_R")
	)
	(segment
		(start 136.82726 -77.793088)
		(end 136.794494 -77.793088)
		(width 0.0889)
		(layer "In9.Cu")
		(net "SMB_DDR_KLM_SCL_G_R")
	)
	(segment
		(start 155.066492 -117.201442)
		(end 153.609548 -114.064288)
		(width 0.089408)
		(layer "In9.Cu")
		(net "SMB_DDR_KLM_SCL_G_R")
	)
	(segment
		(start 131.154424 -70.572122)
		(end 131.149598 -70.563486)
		(width 0.0889)
		(layer "In9.Cu")
		(net "SMB_DDR_KLM_SCL_G_R")
	)
	(segment
		(start 142.174468 -81.755234)
		(end 141.837664 -81.755234)
		(width 0.0889)
		(layer "In9.Cu")
		(net "SMB_DDR_KLM_SCL_G_R")
	)
	(segment
		(start 140.413232 -79.774288)
		(end 140.228574 -79.774288)
		(width 0.0889)
		(layer "In9.Cu")
		(net "SMB_DDR_KLM_SCL_G_R")
	)
	(segment
		(start 153.609548 -114.064288)
		(end 149.819614 -101.15931)
		(width 0.089408)
		(layer "In9.Cu")
		(net "SMB_DDR_KLM_SCL_G_R")
	)
	(segment
		(start 154.80538 -122.95124)
		(end 154.80538 -122.81662)
		(width 0.089408)
		(layer "In9.Cu")
		(net "SMB_DDR_KLM_SCL_G_R")
	)
	(segment
		(start 135.96493 -77.297534)
		(end 135.932164 -77.297534)
		(width 0.0889)
		(layer "In9.Cu")
		(net "SMB_DDR_KLM_SCL_G_R")
	)
	(segment
		(start 134.24789 -76.306934)
		(end 134.215124 -76.306934)
		(width 0.0889)
		(layer "In9.Cu")
		(net "SMB_DDR_KLM_SCL_G_R")
	)
	(segment
		(start 141.240256 -81.24825)
		(end 140.96873 -81.228184)
		(width 0.0889)
		(layer "In9.Cu")
		(net "SMB_DDR_KLM_SCL_G_R")
	)
	(segment
		(start 131.004564 -66.15176)
		(end 129.726944 -64.87414)
		(width 0.0889)
		(layer "In9.Cu")
		(net "SMB_DDR_KLM_SCL_G_R")
	)
	(segment
		(start 131.149598 -71.554086)
		(end 131.143248 -71.543418)
		(width 0.0889)
		(layer "In9.Cu")
		(net "SMB_DDR_KLM_SCL_G_R")
	)
	(segment
		(start 154.8257 -120.7389)
		(end 155.066492 -120.498108)
		(width 0.089408)
		(layer "In9.Cu")
		(net "SMB_DDR_KLM_SCL_G_R")
	)
	(segment
		(start 142.789402 -82.086958)
		(end 142.174468 -81.755234)
		(width 0.0889)
		(layer "In9.Cu")
		(net "SMB_DDR_KLM_SCL_G_R")
	)
	(segment
		(start 133.39318 -75.811888)
		(end 133.360414 -75.811888)
		(width 0.0889)
		(layer "In9.Cu")
		(net "SMB_DDR_KLM_SCL_G_R")
	)
	(segment
		(start 131.149598 -69.572886)
		(end 131.143248 -69.562218)
		(width 0.0889)
		(layer "In9.Cu")
		(net "SMB_DDR_KLM_SCL_G_R")
	)
	(segment
		(start 131.149598 -73.535286)
		(end 131.143248 -73.524618)
		(width 0.0889)
		(layer "In9.Cu")
		(net "SMB_DDR_KLM_SCL_G_R")
	)
	(segment
		(start 128.520444 -63.164974)
		(end 128.227328 -63.334138)
		(width 0.0889)
		(layer "In9.Cu")
		(net "SMB_DDR_KLM_SCL_G_R")
	)
	(segment
		(start 131.154424 -72.553322)
		(end 131.149598 -72.544686)
		(width 0.0889)
		(layer "In9.Cu")
		(net "SMB_DDR_KLM_SCL_G_R")
	)
	(segment
		(start 131.143248 -73.94575)
		(end 131.149598 -73.935082)
		(width 0.0889)
		(layer "In9.Cu")
		(net "SMB_DDR_KLM_SCL_G_R")
	)
	(segment
		(start 131.149598 -72.544686)
		(end 131.143248 -72.534018)
		(width 0.0889)
		(layer "In9.Cu")
		(net "SMB_DDR_KLM_SCL_G_R")
	)
	(segment
		(start 154.8257 -121.36628)
		(end 154.8257 -120.7389)
		(width 0.089408)
		(layer "In9.Cu")
		(net "SMB_DDR_KLM_SCL_G_R")
	)
	(segment
		(start 155.18638 -122.43562)
		(end 155.18638 -121.72696)
		(width 0.089408)
		(layer "In9.Cu")
		(net "SMB_DDR_KLM_SCL_G_R")
	)
	(segment
		(start 137.68197 -78.288388)
		(end 137.65784 -78.288388)
		(width 0.0889)
		(layer "In9.Cu")
		(net "SMB_DDR_KLM_SCL_G_R")
	)
	(segment
		(start 149.819614 -101.15931)
		(end 149.151086 -99.949)
		(width 0.089408)
		(layer "In9.Cu")
		(net "SMB_DDR_KLM_SCL_G_R")
	)
	(segment
		(start 138.54049 -78.783688)
		(end 138.507724 -78.783688)
		(width 0.0889)
		(layer "In9.Cu")
		(net "SMB_DDR_KLM_SCL_G_R")
	)
	(segment
		(start 154.80538 -122.81662)
		(end 155.18638 -122.43562)
		(width 0.089408)
		(layer "In9.Cu")
		(net "SMB_DDR_KLM_SCL_G_R")
	)
	(segment
		(start 131.661408 -74.821034)
		(end 131.648454 -74.821034)
		(width 0.0889)
		(layer "In9.Cu")
		(net "SMB_DDR_KLM_SCL_G_R")
	)
	(segment
		(start 155.18638 -121.72696)
		(end 154.8257 -121.36628)
		(width 0.089408)
		(layer "In9.Cu")
		(net "SMB_DDR_KLM_SCL_G_R")
	)
	(segment
		(start 132.53085 -75.316334)
		(end 132.494782 -75.316334)
		(width 0.0889)
		(layer "In9.Cu")
		(net "SMB_DDR_KLM_SCL_G_R")
	)
	(segment
		(start 155.066492 -120.498108)
		(end 155.066492 -117.201442)
		(width 0.089408)
		(layer "In9.Cu")
		(net "SMB_DDR_KLM_SCL_G_R")
	)
	(segment
		(start 139.405868 -79.278988)
		(end 139.366244 -79.278988)
		(width 0.0889)
		(layer "In9.Cu")
		(net "SMB_DDR_KLM_SCL_G_R")
	)
	(segment
		(start 131.154424 -71.562722)
		(end 131.149598 -71.554086)
		(width 0.0889)
		(layer "In9.Cu")
		(net "SMB_DDR_KLM_SCL_G_R")
	)
	(segment
		(start 135.11022 -76.802488)
		(end 135.077454 -76.802488)
		(width 0.0889)
		(layer "In9.Cu")
		(net "SMB_DDR_KLM_SCL_G_R")
	)
	(segment
		(start 131.004564 -68.156836)
		(end 131.004564 -66.15176)
		(width 0.0889)
		(layer "In9.Cu")
		(net "SMB_DDR_KLM_SCL_G_R")
	)
	(segment
		(start 144.691608 -83.211162)
		(end 142.789402 -82.086958)
		(width 0.089408)
		(layer "In9.Cu")
		(net "SMB_DDR_KLM_SCL_G_R")
	)
	(segment
		(start 132.007864 -75.02144)
		(end 131.99999 -75.007724)
		(width 0.0889)
		(layer "In9.Cu")
		(net "SMB_DDR_KLM_SCL_G_R")
	)
	(segment
		(start 129.097024 -63.429134)
		(end 129.064258 -63.429134)
		(width 0.0889)
		(layer "In9.Cu")
		(net "SMB_DDR_KLM_SCL_G_R")
	)
	(segment
		(start 141.837664 -81.755234)
		(end 141.836902 -81.755488)
		(width 0.0889)
		(layer "In9.Cu")
		(net "SMB_DDR_KLM_SCL_G_R")
	)
	(arc
		(start 140.631164 -80.945228)
		(mid 140.559896 -80.763145)
		(end 140.543534 -80.568292)
		(width 0.0889)
		(layer "In9.Cu")
		(net "SMB_DDR_KLM_SCL_G_R")
	)
	(arc
		(start 135.441944 -77.002386)
		(mid 135.301865 -76.85965)
		(end 135.11022 -76.802488)
		(width 0.0889)
		(layer "In9.Cu")
		(net "SMB_DDR_KLM_SCL_G_R")
	)
	(arc
		(start 140.228574 -79.774288)
		(mid 139.94315 -79.690821)
		(end 139.734544 -79.478886)
		(width 0.0889)
		(layer "In9.Cu")
		(net "SMB_DDR_KLM_SCL_G_R")
	)
	(arc
		(start 139.366244 -79.278988)
		(mid 139.083027 -79.194707)
		(end 138.876024 -78.98384)
		(width 0.0889)
		(layer "In9.Cu")
		(net "SMB_DDR_KLM_SCL_G_R")
	)
	(arc
		(start 138.876024 -78.98384)
		(mid 138.734341 -78.840036)
		(end 138.54049 -78.783688)
		(width 0.0889)
		(layer "In9.Cu")
		(net "SMB_DDR_KLM_SCL_G_R")
	)
	(arc
		(start 131.149598 -70.963536)
		(mid 131.203068 -70.768473)
		(end 131.154424 -70.572122)
		(width 0.0889)
		(layer "In9.Cu")
		(net "SMB_DDR_KLM_SCL_G_R")
	)
	(arc
		(start 140.629386 -79.971392)
		(mid 140.538442 -79.854049)
		(end 140.413232 -79.774288)
		(width 0.0889)
		(layer "In9.Cu")
		(net "SMB_DDR_KLM_SCL_G_R")
	)
	(arc
		(start 133.360414 -75.811888)
		(mid 133.07499 -75.728421)
		(end 132.866384 -75.516486)
		(width 0.0889)
		(layer "In9.Cu")
		(net "SMB_DDR_KLM_SCL_G_R")
	)
	(arc
		(start 132.866384 -75.516486)
		(mid 132.724701 -75.372682)
		(end 132.53085 -75.316334)
		(width 0.0889)
		(layer "In9.Cu")
		(net "SMB_DDR_KLM_SCL_G_R")
	)
	(arc
		(start 140.96873 -81.228184)
		(mid 140.774562 -81.116995)
		(end 140.631164 -80.945228)
		(width 0.0889)
		(layer "In9.Cu")
		(net "SMB_DDR_KLM_SCL_G_R")
	)
	(arc
		(start 135.932164 -77.297534)
		(mid 135.648947 -77.213253)
		(end 135.441944 -77.002386)
		(width 0.0889)
		(layer "In9.Cu")
		(net "SMB_DDR_KLM_SCL_G_R")
	)
	(arc
		(start 141.487906 -81.457292)
		(mid 141.38434 -81.32878)
		(end 141.240256 -81.24825)
		(width 0.0889)
		(layer "In9.Cu")
		(net "SMB_DDR_KLM_SCL_G_R")
	)
	(arc
		(start 131.085336 -68.467478)
		(mid 131.025093 -68.317321)
		(end 131.004564 -68.156836)
		(width 0.0889)
		(layer "In9.Cu")
		(net "SMB_DDR_KLM_SCL_G_R")
	)
	(arc
		(start 131.648454 -74.821034)
		(mid 131.149573 -74.525597)
		(end 131.143248 -73.94575)
		(width 0.0889)
		(layer "In9.Cu")
		(net "SMB_DDR_KLM_SCL_G_R")
	)
	(arc
		(start 131.143248 -69.562218)
		(mid 131.07045 -69.271455)
		(end 131.149598 -68.982336)
		(width 0.0889)
		(layer "In9.Cu")
		(net "SMB_DDR_KLM_SCL_G_R")
	)
	(arc
		(start 134.583424 -76.507086)
		(mid 134.441741 -76.363282)
		(end 134.24789 -76.306934)
		(width 0.0889)
		(layer "In9.Cu")
		(net "SMB_DDR_KLM_SCL_G_R")
	)
	(arc
		(start 131.149598 -72.944736)
		(mid 131.203068 -72.749673)
		(end 131.154424 -72.553322)
		(width 0.0889)
		(layer "In9.Cu")
		(net "SMB_DDR_KLM_SCL_G_R")
	)
	(arc
		(start 141.836902 -81.755488)
		(mid 141.634004 -81.639628)
		(end 141.487906 -81.457292)
		(width 0.0889)
		(layer "In9.Cu")
		(net "SMB_DDR_KLM_SCL_G_R")
	)
	(arc
		(start 140.543534 -80.568292)
		(mid 140.562783 -80.474007)
		(end 140.617448 -80.39481)
		(width 0.0889)
		(layer "In9.Cu")
		(net "SMB_DDR_KLM_SCL_G_R")
	)
	(arc
		(start 131.143248 -73.524618)
		(mid 131.07045 -73.233855)
		(end 131.149598 -72.944736)
		(width 0.0889)
		(layer "In9.Cu")
		(net "SMB_DDR_KLM_SCL_G_R")
	)
	(arc
		(start 134.215124 -76.306934)
		(mid 133.931907 -76.222653)
		(end 133.724904 -76.011786)
		(width 0.0889)
		(layer "In9.Cu")
		(net "SMB_DDR_KLM_SCL_G_R")
	)
	(arc
		(start 131.149598 -70.563486)
		(mid 131.070467 -70.268084)
		(end 131.149598 -69.972682)
		(width 0.0889)
		(layer "In9.Cu")
		(net "SMB_DDR_KLM_SCL_G_R")
	)
	(arc
		(start 136.300464 -77.497686)
		(mid 136.158781 -77.353882)
		(end 135.96493 -77.297534)
		(width 0.0889)
		(layer "In9.Cu")
		(net "SMB_DDR_KLM_SCL_G_R")
	)
	(arc
		(start 133.724904 -76.011786)
		(mid 133.584825 -75.86905)
		(end 133.39318 -75.811888)
		(width 0.0889)
		(layer "In9.Cu")
		(net "SMB_DDR_KLM_SCL_G_R")
	)
	(arc
		(start 131.143248 -72.534018)
		(mid 131.07045 -72.243255)
		(end 131.149598 -71.954136)
		(width 0.0889)
		(layer "In9.Cu")
		(net "SMB_DDR_KLM_SCL_G_R")
	)
	(arc
		(start 131.99999 -75.007724)
		(mid 131.854736 -74.870777)
		(end 131.661408 -74.821034)
		(width 0.0889)
		(layer "In9.Cu")
		(net "SMB_DDR_KLM_SCL_G_R")
	)
	(arc
		(start 140.617448 -80.39481)
		(mid 140.679213 -80.184674)
		(end 140.629386 -79.971392)
		(width 0.0889)
		(layer "In9.Cu")
		(net "SMB_DDR_KLM_SCL_G_R")
	)
	(arc
		(start 131.149598 -68.982336)
		(mid 131.203088 -68.785053)
		(end 131.152138 -68.587112)
		(width 0.0889)
		(layer "In9.Cu")
		(net "SMB_DDR_KLM_SCL_G_R")
	)
	(arc
		(start 137.158984 -77.992986)
		(mid 137.018905 -77.85025)
		(end 136.82726 -77.793088)
		(width 0.0889)
		(layer "In9.Cu")
		(net "SMB_DDR_KLM_SCL_G_R")
	)
	(arc
		(start 131.149598 -71.954136)
		(mid 131.203068 -71.759073)
		(end 131.154424 -71.562722)
		(width 0.0889)
		(layer "In9.Cu")
		(net "SMB_DDR_KLM_SCL_G_R")
	)
	(arc
		(start 138.017504 -78.48854)
		(mid 137.875821 -78.344736)
		(end 137.68197 -78.288388)
		(width 0.0889)
		(layer "In9.Cu")
		(net "SMB_DDR_KLM_SCL_G_R")
	)
	(arc
		(start 129.432558 -64.029336)
		(mid 129.435306 -63.633869)
		(end 129.097024 -63.429134)
		(width 0.0889)
		(layer "In9.Cu")
		(net "SMB_DDR_KLM_SCL_G_R")
	)
	(arc
		(start 138.507724 -78.783688)
		(mid 138.224507 -78.699407)
		(end 138.017504 -78.48854)
		(width 0.0889)
		(layer "In9.Cu")
		(net "SMB_DDR_KLM_SCL_G_R")
	)
	(arc
		(start 132.494782 -75.316334)
		(mid 132.213482 -75.231368)
		(end 132.007864 -75.02144)
		(width 0.0889)
		(layer "In9.Cu")
		(net "SMB_DDR_KLM_SCL_G_R")
	)
	(arc
		(start 131.143248 -71.543418)
		(mid 131.07045 -71.252655)
		(end 131.149598 -70.963536)
		(width 0.0889)
		(layer "In9.Cu")
		(net "SMB_DDR_KLM_SCL_G_R")
	)
	(arc
		(start 136.794494 -77.793088)
		(mid 136.50907 -77.709621)
		(end 136.300464 -77.497686)
		(width 0.0889)
		(layer "In9.Cu")
		(net "SMB_DDR_KLM_SCL_G_R")
	)
	(arc
		(start 137.65784 -78.288388)
		(mid 137.369695 -78.206069)
		(end 137.158984 -77.992986)
		(width 0.0889)
		(layer "In9.Cu")
		(net "SMB_DDR_KLM_SCL_G_R")
	)
	(arc
		(start 129.064258 -63.429134)
		(mid 128.809593 -63.361105)
		(end 128.609852 -63.189104)
		(width 0.0889)
		(layer "In9.Cu")
		(net "SMB_DDR_KLM_SCL_G_R")
	)
	(arc
		(start 135.077454 -76.802488)
		(mid 134.79203 -76.719021)
		(end 134.583424 -76.507086)
		(width 0.0889)
		(layer "In9.Cu")
		(net "SMB_DDR_KLM_SCL_G_R")
	)
	(arc
		(start 131.149598 -73.935082)
		(mid 131.203097 -73.735184)
		(end 131.149598 -73.535286)
		(width 0.0889)
		(layer "In9.Cu")
		(net "SMB_DDR_KLM_SCL_G_R")
	)
	(arc
		(start 139.734544 -79.478886)
		(mid 139.5958 -79.336853)
		(end 139.405868 -79.278988)
		(width 0.0889)
		(layer "In9.Cu")
		(net "SMB_DDR_KLM_SCL_G_R")
	)
	(arc
		(start 129.726944 -64.87414)
		(mid 129.386402 -64.519133)
		(end 129.432558 -64.029336)
		(width 0.0889)
		(layer "In9.Cu")
		(net "SMB_DDR_KLM_SCL_G_R")
	)
	(arc
		(start 131.149598 -69.972682)
		(mid 131.203097 -69.772784)
		(end 131.149598 -69.572886)
		(width 0.0889)
		(layer "In9.Cu")
		(net "SMB_DDR_KLM_SCL_G_R")
	)
	(segment
		(start 161.27222 -122.41022)
		(end 160.269428 -122.41022)
		(width 0.10795)
		(layer "F.Cu")
		(net "SMB_DDR_KLM_VPP_SDA_R")
	)
	(segment
		(start 159.2072 -122.005598)
		(end 158.894526 -122.318272)
		(width 0.10795)
		(layer "F.Cu")
		(net "SMB_DDR_KLM_VPP_SDA_R")
	)
	(segment
		(start 160.269428 -122.41022)
		(end 159.864806 -122.005598)
		(width 0.10795)
		(layer "F.Cu")
		(net "SMB_DDR_KLM_VPP_SDA_R")
	)
	(segment
		(start 159.864806 -122.005598)
		(end 159.2072 -122.005598)
		(width 0.10795)
		(layer "F.Cu")
		(net "SMB_DDR_KLM_VPP_SDA_R")
	)
	(via
		(at 161.6964 -122.1486)
		(size 0.6604)
		(drill 0.3302)
		(layers "F.Cu" "B.Cu")
		(net "SMB_DDR_KLM_VPP_SDA_R")
	)
	(via
		(at 158.894526 -122.318272)
		(size 0.508)
		(drill 0.254)
		(layers "F.Cu" "B.Cu")
		(net "SMB_DDR_KLM_VPP_SDA_R")
	)
	(segment
		(start 158.894526 -122.318272)
		(end 159.2072 -122.005598)
		(width 0.10795)
		(layer "B.Cu")
		(net "SMB_DDR_KLM_VPP_SDA_R")
	)
	(segment
		(start 161.6456 -122.1994)
		(end 160.4264 -122.1994)
		(width 0.10795)
		(layer "B.Cu")
		(net "SMB_DDR_KLM_VPP_SDA_R")
	)
	(segment
		(start 158.6738 -122.9614)
		(end 158.6738 -122.538998)
		(width 0.10795)
		(layer "B.Cu")
		(net "SMB_DDR_KLM_VPP_SDA_R")
	)
	(segment
		(start 159.2072 -122.005598)
		(end 159.864806 -122.005598)
		(width 0.10795)
		(layer "B.Cu")
		(net "SMB_DDR_KLM_VPP_SDA_R")
	)
	(segment
		(start 159.864806 -122.005598)
		(end 160.058608 -122.1994)
		(width 0.10795)
		(layer "B.Cu")
		(net "SMB_DDR_KLM_VPP_SDA_R")
	)
	(segment
		(start 161.6964 -122.1486)
		(end 161.6456 -122.1994)
		(width 0.10795)
		(layer "B.Cu")
		(net "SMB_DDR_KLM_VPP_SDA_R")
	)
	(segment
		(start 158.6738 -122.538998)
		(end 158.894526 -122.318272)
		(width 0.10795)
		(layer "B.Cu")
		(net "SMB_DDR_KLM_VPP_SDA_R")
	)
	(segment
		(start 160.058608 -122.1994)
		(end 160.4264 -122.1994)
		(width 0.10795)
		(layer "B.Cu")
		(net "SMB_DDR_KLM_VPP_SDA_R")
	)
	(segment
		(start 153.79954 -137.67054)
		(end 153.79954 -136.412478)
		(width 0.10795)
		(layer "F.Cu")
		(net "SMB_DDR_KLM_VPP_SDA")
	)
	(segment
		(start 153.79954 -156.87294)
		(end 153.79954 -155.614878)
		(width 0.10795)
		(layer "F.Cu")
		(net "SMB_DDR_KLM_VPP_SDA")
	)
	(segment
		(start 153.79954 -147.27174)
		(end 153.79954 -146.013678)
		(width 0.10795)
		(layer "F.Cu")
		(net "SMB_DDR_KLM_VPP_SDA")
	)
	(via
		(at 159.258 -121.4882)
		(size 0.508)
		(drill 0.254)
		(layers "F.Cu" "B.Cu")
		(net "SMB_DDR_KLM_VPP_SDA")
	)
	(via
		(at 153.79954 -136.412478)
		(size 0.508)
		(drill 0.254)
		(layers "F.Cu" "B.Cu")
		(net "SMB_DDR_KLM_VPP_SDA")
	)
	(via
		(at 153.79954 -148.782278)
		(size 0.508)
		(drill 0.254)
		(layers "F.Cu" "B.Cu")
		(net "SMB_DDR_KLM_VPP_SDA")
	)
	(via
		(at 153.79954 -139.181078)
		(size 0.508)
		(drill 0.254)
		(layers "F.Cu" "B.Cu")
		(net "SMB_DDR_KLM_VPP_SDA")
	)
	(via
		(at 153.79954 -129.579878)
		(size 0.508)
		(drill 0.254)
		(layers "F.Cu" "B.Cu")
		(net "SMB_DDR_KLM_VPP_SDA")
	)
	(via
		(at 153.79954 -155.614878)
		(size 0.508)
		(drill 0.254)
		(layers "F.Cu" "B.Cu")
		(net "SMB_DDR_KLM_VPP_SDA")
	)
	(via
		(at 153.79954 -146.013678)
		(size 0.508)
		(drill 0.254)
		(layers "F.Cu" "B.Cu")
		(net "SMB_DDR_KLM_VPP_SDA")
	)
	(segment
		(start 153.79954 -137.877296)
		(end 153.79954 -139.181078)
		(width 0.10795)
		(layer "B.Cu")
		(net "SMB_DDR_KLM_VPP_SDA")
	)
	(segment
		(start 159.4358 -121.3104)
		(end 159.258 -121.4882)
		(width 0.10795)
		(layer "B.Cu")
		(net "SMB_DDR_KLM_VPP_SDA")
	)
	(segment
		(start 153.79954 -128.276096)
		(end 153.79954 -129.579878)
		(width 0.10795)
		(layer "B.Cu")
		(net "SMB_DDR_KLM_VPP_SDA")
	)
	(segment
		(start 160.4264 -121.3104)
		(end 159.4358 -121.3104)
		(width 0.10795)
		(layer "B.Cu")
		(net "SMB_DDR_KLM_VPP_SDA")
	)
	(segment
		(start 153.79954 -147.478496)
		(end 153.79954 -148.782278)
		(width 0.10795)
		(layer "B.Cu")
		(net "SMB_DDR_KLM_VPP_SDA")
	)
	(segment
		(start 153.79954 -149.961346)
		(end 153.371042 -150.389844)
		(width 0.089408)
		(layer "In11.Cu")
		(net "SMB_DDR_KLM_VPP_SDA")
	)
	(segment
		(start 153.382472 -140.073888)
		(end 153.382472 -145.59661)
		(width 0.089408)
		(layer "In11.Cu")
		(net "SMB_DDR_KLM_VPP_SDA")
	)
	(segment
		(start 153.371042 -155.18638)
		(end 153.79954 -155.614878)
		(width 0.089408)
		(layer "In11.Cu")
		(net "SMB_DDR_KLM_VPP_SDA")
	)
	(segment
		(start 153.371042 -150.389844)
		(end 153.371042 -155.18638)
		(width 0.089408)
		(layer "In11.Cu")
		(net "SMB_DDR_KLM_VPP_SDA")
	)
	(segment
		(start 153.79954 -130.30835)
		(end 153.393902 -130.713988)
		(width 0.089408)
		(layer "In11.Cu")
		(net "SMB_DDR_KLM_VPP_SDA")
	)
	(segment
		(start 158.242 -125.137418)
		(end 153.79954 -129.579878)
		(width 0.089408)
		(layer "In11.Cu")
		(net "SMB_DDR_KLM_VPP_SDA")
	)
	(segment
		(start 158.242 -122.0216)
		(end 158.242 -125.137418)
		(width 0.089408)
		(layer "In11.Cu")
		(net "SMB_DDR_KLM_VPP_SDA")
	)
	(segment
		(start 153.79954 -146.013678)
		(end 153.79954 -148.782278)
		(width 0.089408)
		(layer "In11.Cu")
		(net "SMB_DDR_KLM_VPP_SDA")
	)
	(segment
		(start 153.79954 -139.65682)
		(end 153.382472 -140.073888)
		(width 0.089408)
		(layer "In11.Cu")
		(net "SMB_DDR_KLM_VPP_SDA")
	)
	(segment
		(start 153.393902 -136.00684)
		(end 153.79954 -136.412478)
		(width 0.089408)
		(layer "In11.Cu")
		(net "SMB_DDR_KLM_VPP_SDA")
	)
	(segment
		(start 153.79954 -136.412478)
		(end 153.79954 -139.181078)
		(width 0.089408)
		(layer "In11.Cu")
		(net "SMB_DDR_KLM_VPP_SDA")
	)
	(segment
		(start 153.79954 -148.782278)
		(end 153.79954 -149.961346)
		(width 0.089408)
		(layer "In11.Cu")
		(net "SMB_DDR_KLM_VPP_SDA")
	)
	(segment
		(start 153.393902 -130.713988)
		(end 153.393902 -136.00684)
		(width 0.089408)
		(layer "In11.Cu")
		(net "SMB_DDR_KLM_VPP_SDA")
	)
	(segment
		(start 158.7754 -121.4882)
		(end 158.242 -122.0216)
		(width 0.089408)
		(layer "In11.Cu")
		(net "SMB_DDR_KLM_VPP_SDA")
	)
	(segment
		(start 159.258 -121.4882)
		(end 158.7754 -121.4882)
		(width 0.089408)
		(layer "In11.Cu")
		(net "SMB_DDR_KLM_VPP_SDA")
	)
	(segment
		(start 153.79954 -129.579878)
		(end 153.79954 -130.30835)
		(width 0.089408)
		(layer "In11.Cu")
		(net "SMB_DDR_KLM_VPP_SDA")
	)
	(segment
		(start 153.382472 -145.59661)
		(end 153.79954 -146.013678)
		(width 0.089408)
		(layer "In11.Cu")
		(net "SMB_DDR_KLM_VPP_SDA")
	)
	(segment
		(start 153.79954 -139.181078)
		(end 153.79954 -139.65682)
		(width 0.089408)
		(layer "In11.Cu")
		(net "SMB_DDR_KLM_VPP_SDA")
	)
	(segment
		(start 159.6898 -122.428)
		(end 160.32226 -123.06046)
		(width 0.10795)
		(layer "F.Cu")
		(net "SMB_DDR_KLM_VPP_SCL_R")
	)
	(segment
		(start 160.32226 -123.06046)
		(end 161.27222 -123.06046)
		(width 0.10795)
		(layer "F.Cu")
		(net "SMB_DDR_KLM_VPP_SCL_R")
	)
	(via
		(at 159.6898 -122.428)
		(size 0.508)
		(drill 0.254)
		(layers "F.Cu" "B.Cu")
		(net "SMB_DDR_KLM_VPP_SCL_R")
	)
	(via
		(at 162.941 -123.7996)
		(size 0.6604)
		(drill 0.3302)
		(layers "F.Cu" "B.Cu")
		(net "SMB_DDR_KLM_VPP_SCL_R")
	)
	(segment
		(start 162.2171 -123.0757)
		(end 161.78022 -123.0757)
		(width 0.10795)
		(layer "B.Cu")
		(net "SMB_DDR_KLM_VPP_SCL_R")
	)
	(segment
		(start 162.941 -123.7996)
		(end 162.2171 -123.0757)
		(width 0.10795)
		(layer "B.Cu")
		(net "SMB_DDR_KLM_VPP_SCL_R")
	)
	(segment
		(start 161.78022 -123.0757)
		(end 160.76422 -123.0757)
		(width 0.10795)
		(layer "B.Cu")
		(net "SMB_DDR_KLM_VPP_SCL_R")
	)
	(segment
		(start 159.6898 -122.428)
		(end 160.3375 -123.0757)
		(width 0.10795)
		(layer "B.Cu")
		(net "SMB_DDR_KLM_VPP_SCL_R")
	)
	(segment
		(start 160.3375 -123.0757)
		(end 160.76422 -123.0757)
		(width 0.10795)
		(layer "B.Cu")
		(net "SMB_DDR_KLM_VPP_SCL_R")
	)
	(segment
		(start 153.79954 -152.273)
		(end 153.79954 -153.542746)
		(width 0.10795)
		(layer "F.Cu")
		(net "SMB_DDR_KLM_VPP_SCL")
	)
	(segment
		(start 153.79954 -142.6718)
		(end 153.79954 -143.941546)
		(width 0.10795)
		(layer "F.Cu")
		(net "SMB_DDR_KLM_VPP_SCL")
	)
	(segment
		(start 153.79954 -133.0706)
		(end 153.79954 -134.340346)
		(width 0.10795)
		(layer "F.Cu")
		(net "SMB_DDR_KLM_VPP_SCL")
	)
	(via
		(at 153.79954 -131.571746)
		(size 0.508)
		(drill 0.254)
		(layers "F.Cu" "B.Cu")
		(net "SMB_DDR_KLM_VPP_SCL")
	)
	(via
		(at 153.79954 -143.941546)
		(size 0.508)
		(drill 0.254)
		(layers "F.Cu" "B.Cu")
		(net "SMB_DDR_KLM_VPP_SCL")
	)
	(via
		(at 161.671 -125.456696)
		(size 0.508)
		(drill 0.254)
		(layers "F.Cu" "B.Cu")
		(net "SMB_DDR_KLM_VPP_SCL")
	)
	(via
		(at 153.79954 -150.774146)
		(size 0.508)
		(drill 0.254)
		(layers "F.Cu" "B.Cu")
		(net "SMB_DDR_KLM_VPP_SCL")
	)
	(via
		(at 153.79954 -141.172946)
		(size 0.508)
		(drill 0.254)
		(layers "F.Cu" "B.Cu")
		(net "SMB_DDR_KLM_VPP_SCL")
	)
	(via
		(at 153.79954 -153.542746)
		(size 0.508)
		(drill 0.254)
		(layers "F.Cu" "B.Cu")
		(net "SMB_DDR_KLM_VPP_SCL")
	)
	(via
		(at 153.79954 -134.340346)
		(size 0.508)
		(drill 0.254)
		(layers "F.Cu" "B.Cu")
		(net "SMB_DDR_KLM_VPP_SCL")
	)
	(segment
		(start 161.78022 -124.384054)
		(end 161.51352 -124.650754)
		(width 0.10795)
		(layer "B.Cu")
		(net "SMB_DDR_KLM_VPP_SCL")
	)
	(segment
		(start 161.78022 -123.9647)
		(end 161.78022 -124.384054)
		(width 0.10795)
		(layer "B.Cu")
		(net "SMB_DDR_KLM_VPP_SCL")
	)
	(segment
		(start 153.79954 -132.876036)
		(end 153.79954 -131.571746)
		(width 0.10795)
		(layer "B.Cu")
		(net "SMB_DDR_KLM_VPP_SCL")
	)
	(segment
		(start 161.51352 -125.299216)
		(end 161.671 -125.456696)
		(width 0.10795)
		(layer "B.Cu")
		(net "SMB_DDR_KLM_VPP_SCL")
	)
	(segment
		(start 153.79954 -152.078436)
		(end 153.79954 -150.774146)
		(width 0.10795)
		(layer "B.Cu")
		(net "SMB_DDR_KLM_VPP_SCL")
	)
	(segment
		(start 153.79954 -142.477236)
		(end 153.79954 -141.172946)
		(width 0.10795)
		(layer "B.Cu")
		(net "SMB_DDR_KLM_VPP_SCL")
	)
	(segment
		(start 161.51352 -124.650754)
		(end 161.51352 -125.299216)
		(width 0.10795)
		(layer "B.Cu")
		(net "SMB_DDR_KLM_VPP_SCL")
	)
	(segment
		(start 153.79954 -134.340346)
		(end 153.79954 -135.077454)
		(width 0.089408)
		(layer "In11.Cu")
		(net "SMB_DDR_KLM_VPP_SCL")
	)
	(segment
		(start 153.79954 -141.172946)
		(end 153.79954 -143.941546)
		(width 0.089408)
		(layer "In11.Cu")
		(net "SMB_DDR_KLM_VPP_SCL")
	)
	(segment
		(start 153.79954 -135.077454)
		(end 154.223974 -135.501888)
		(width 0.089408)
		(layer "In11.Cu")
		(net "SMB_DDR_KLM_VPP_SCL")
	)
	(segment
		(start 158.1658 -129.35712)
		(end 158.1658 -130.5941)
		(width 0.089408)
		(layer "In11.Cu")
		(net "SMB_DDR_KLM_VPP_SCL")
	)
	(segment
		(start 154.223974 -140.748512)
		(end 153.79954 -141.172946)
		(width 0.089408)
		(layer "In11.Cu")
		(net "SMB_DDR_KLM_VPP_SCL")
	)
	(segment
		(start 157.60192 -131.15798)
		(end 154.213306 -131.15798)
		(width 0.089408)
		(layer "In11.Cu")
		(net "SMB_DDR_KLM_VPP_SCL")
	)
	(segment
		(start 161.671 -125.456696)
		(end 161.671 -125.85192)
		(width 0.089408)
		(layer "In11.Cu")
		(net "SMB_DDR_KLM_VPP_SCL")
	)
	(segment
		(start 161.671 -125.85192)
		(end 158.1658 -129.35712)
		(width 0.089408)
		(layer "In11.Cu")
		(net "SMB_DDR_KLM_VPP_SCL")
	)
	(segment
		(start 154.235404 -145.362676)
		(end 154.235404 -150.338282)
		(width 0.089408)
		(layer "In11.Cu")
		(net "SMB_DDR_KLM_VPP_SCL")
	)
	(segment
		(start 154.223974 -135.501888)
		(end 154.223974 -140.748512)
		(width 0.089408)
		(layer "In11.Cu")
		(net "SMB_DDR_KLM_VPP_SCL")
	)
	(segment
		(start 153.79954 -143.941546)
		(end 153.79954 -144.926812)
		(width 0.089408)
		(layer "In11.Cu")
		(net "SMB_DDR_KLM_VPP_SCL")
	)
	(segment
		(start 154.213306 -131.15798)
		(end 153.79954 -131.571746)
		(width 0.089408)
		(layer "In11.Cu")
		(net "SMB_DDR_KLM_VPP_SCL")
	)
	(segment
		(start 154.235404 -150.338282)
		(end 153.79954 -150.774146)
		(width 0.089408)
		(layer "In11.Cu")
		(net "SMB_DDR_KLM_VPP_SCL")
	)
	(segment
		(start 153.79954 -131.571746)
		(end 153.79954 -134.340346)
		(width 0.089408)
		(layer "In11.Cu")
		(net "SMB_DDR_KLM_VPP_SCL")
	)
	(segment
		(start 153.79954 -144.926812)
		(end 154.235404 -145.362676)
		(width 0.089408)
		(layer "In11.Cu")
		(net "SMB_DDR_KLM_VPP_SCL")
	)
	(segment
		(start 153.79954 -150.774146)
		(end 153.79954 -153.542746)
		(width 0.089408)
		(layer "In11.Cu")
		(net "SMB_DDR_KLM_VPP_SCL")
	)
	(segment
		(start 158.1658 -130.5941)
		(end 157.60192 -131.15798)
		(width 0.089408)
		(layer "In11.Cu")
		(net "SMB_DDR_KLM_VPP_SCL")
	)
	(segment
		(start 155.234386 -122.41022)
		(end 156.70022 -122.41022)
		(width 0.10795)
		(layer "F.Cu")
		(net "SMB_DDR_KLM_SDA_G")
	)
	(segment
		(start 154.758136 -121.93397)
		(end 155.234386 -122.41022)
		(width 0.10795)
		(layer "F.Cu")
		(net "SMB_DDR_KLM_SDA_G")
	)
	(via
		(at 154.758136 -121.93397)
		(size 0.508)
		(drill 0.254)
		(layers "F.Cu" "B.Cu")
		(net "SMB_DDR_KLM_SDA_G")
	)
	(segment
		(start 155.137866 -122.3137)
		(end 156.19222 -122.3137)
		(width 0.10795)
		(layer "B.Cu")
		(net "SMB_DDR_KLM_SDA_G")
	)
	(segment
		(start 154.758136 -121.93397)
		(end 155.137866 -122.3137)
		(width 0.10795)
		(layer "B.Cu")
		(net "SMB_DDR_KLM_SDA_G")
	)
	(segment
		(start 156.19222 -122.3137)
		(end 157.08122 -122.3137)
		(width 0.10795)
		(layer "B.Cu")
		(net "SMB_DDR_KLM_SDA_G")
	)
	(segment
		(start 155.448 -122.936)
		(end 155.57246 -123.06046)
		(width 0.10795)
		(layer "F.Cu")
		(net "SMB_DDR_KLM_SCL_G")
	)
	(segment
		(start 155.57246 -123.06046)
		(end 156.70022 -123.06046)
		(width 0.10795)
		(layer "F.Cu")
		(net "SMB_DDR_KLM_SCL_G")
	)
	(via
		(at 156.17698 -125.006862)
		(size 0.6604)
		(drill 0.3302)
		(layers "F.Cu" "B.Cu")
		(net "SMB_DDR_KLM_SCL_G")
	)
	(via
		(at 155.448 -122.936)
		(size 0.508)
		(drill 0.254)
		(layers "F.Cu" "B.Cu")
		(net "SMB_DDR_KLM_SCL_G")
	)
	(segment
		(start 156.95422 -123.2027)
		(end 157.08122 -123.2027)
		(width 0.10795)
		(layer "B.Cu")
		(net "SMB_DDR_KLM_SCL_G")
	)
	(segment
		(start 156.06522 -123.2027)
		(end 155.7147 -123.2027)
		(width 0.10795)
		(layer "B.Cu")
		(net "SMB_DDR_KLM_SCL_G")
	)
	(segment
		(start 156.17698 -125.006862)
		(end 156.17698 -124.879862)
		(width 0.10795)
		(layer "B.Cu")
		(net "SMB_DDR_KLM_SCL_G")
	)
	(segment
		(start 156.51353 -124.543312)
		(end 156.51353 -123.64339)
		(width 0.10795)
		(layer "B.Cu")
		(net "SMB_DDR_KLM_SCL_G")
	)
	(segment
		(start 156.50718 -122.76074)
		(end 156.905452 -122.76074)
		(width 0.10795)
		(layer "B.Cu")
		(net "SMB_DDR_KLM_SCL_G")
	)
	(segment
		(start 157.08122 -122.936508)
		(end 157.08122 -123.2027)
		(width 0.10795)
		(layer "B.Cu")
		(net "SMB_DDR_KLM_SCL_G")
	)
	(segment
		(start 156.905452 -122.76074)
		(end 157.08122 -122.936508)
		(width 0.10795)
		(layer "B.Cu")
		(net "SMB_DDR_KLM_SCL_G")
	)
	(segment
		(start 156.51353 -123.64339)
		(end 156.95422 -123.2027)
		(width 0.10795)
		(layer "B.Cu")
		(net "SMB_DDR_KLM_SCL_G")
	)
	(segment
		(start 155.7147 -123.2027)
		(end 155.448 -122.936)
		(width 0.10795)
		(layer "B.Cu")
		(net "SMB_DDR_KLM_SCL_G")
	)
	(segment
		(start 156.06522 -123.2027)
		(end 156.50718 -122.76074)
		(width 0.10795)
		(layer "B.Cu")
		(net "SMB_DDR_KLM_SCL_G")
	)
	(segment
		(start 156.17698 -124.879862)
		(end 156.51353 -124.543312)
		(width 0.10795)
		(layer "B.Cu")
		(net "SMB_DDR_KLM_SCL_G")
	)
	(segment
		(start 128.514348 -63.829184)
		(end 129.085848 -63.829184)
		(width 0.1016)
		(layer "F.Cu")
		(net "SMB_DDR_GHJ_SDA_G_R")
	)
	(via
		(at 129.085848 -63.829184)
		(size 0.508)
		(drill 0.254)
		(layers "F.Cu" "B.Cu")
		(net "SMB_DDR_GHJ_SDA_G_R")
	)
	(via
		(at 170.38193 -22.654006)
		(size 0.508)
		(drill 0.254)
		(layers "F.Cu" "B.Cu")
		(net "SMB_DDR_GHJ_SDA_G_R")
	)
	(segment
		(start 169.770552 -22.654006)
		(end 170.38193 -22.654006)
		(width 0.10795)
		(layer "B.Cu")
		(net "SMB_DDR_GHJ_SDA_G_R")
	)
	(segment
		(start 168.07053 -22.34946)
		(end 167.767 -22.65299)
		(width 0.089408)
		(layer "In11.Cu")
		(net "SMB_DDR_GHJ_SDA_G_R")
	)
	(segment
		(start 129.426208 -57.675018)
		(end 129.432558 -57.685686)
		(width 0.0889)
		(layer "In11.Cu")
		(net "SMB_DDR_GHJ_SDA_G_R")
	)
	(segment
		(start 166.453312 -24.11984)
		(end 160.900618 -26.420064)
		(width 0.089408)
		(layer "In11.Cu")
		(net "SMB_DDR_GHJ_SDA_G_R")
	)
	(segment
		(start 129.432558 -56.695086)
		(end 129.437384 -56.703722)
		(width 0.0889)
		(layer "In11.Cu")
		(net "SMB_DDR_GHJ_SDA_G_R")
	)
	(segment
		(start 132.007864 -53.627782)
		(end 132.004562 -53.633624)
		(width 0.0889)
		(layer "In11.Cu")
		(net "SMB_DDR_GHJ_SDA_G_R")
	)
	(segment
		(start 133.396228 -52.837334)
		(end 133.360414 -52.837334)
		(width 0.0889)
		(layer "In11.Cu")
		(net "SMB_DDR_GHJ_SDA_G_R")
	)
	(segment
		(start 129.432558 -60.657486)
		(end 129.437384 -60.666122)
		(width 0.0889)
		(layer "In11.Cu")
		(net "SMB_DDR_GHJ_SDA_G_R")
	)
	(segment
		(start 136.830308 -52.837334)
		(end 136.79424 -52.837334)
		(width 0.0889)
		(layer "In11.Cu")
		(net "SMB_DDR_GHJ_SDA_G_R")
	)
	(segment
		(start 129.432558 -59.076336)
		(end 129.426208 -59.087004)
		(width 0.0889)
		(layer "In11.Cu")
		(net "SMB_DDR_GHJ_SDA_G_R")
	)
	(segment
		(start 137.754614 -52.338986)
		(end 137.675874 -52.338986)
		(width 0.0889)
		(layer "In11.Cu")
		(net "SMB_DDR_GHJ_SDA_G_R")
	)
	(segment
		(start 129.426208 -60.646818)
		(end 129.432558 -60.657486)
		(width 0.0889)
		(layer "In11.Cu")
		(net "SMB_DDR_GHJ_SDA_G_R")
	)
	(segment
		(start 160.900618 -26.420064)
		(end 160.896046 -26.421842)
		(width 0.089408)
		(layer "In11.Cu")
		(net "SMB_DDR_GHJ_SDA_G_R")
	)
	(segment
		(start 129.432558 -62.638686)
		(end 129.437384 -62.647322)
		(width 0.0889)
		(layer "In11.Cu")
		(net "SMB_DDR_GHJ_SDA_G_R")
	)
	(segment
		(start 129.432558 -57.685686)
		(end 129.437384 -57.694322)
		(width 0.0889)
		(layer "In11.Cu")
		(net "SMB_DDR_GHJ_SDA_G_R")
	)
	(segment
		(start 167.767 -22.806152)
		(end 166.453312 -24.11984)
		(width 0.089408)
		(layer "In11.Cu")
		(net "SMB_DDR_GHJ_SDA_G_R")
	)
	(segment
		(start 131.661408 -53.827934)
		(end 131.648454 -53.827934)
		(width 0.0889)
		(layer "In11.Cu")
		(net "SMB_DDR_GHJ_SDA_G_R")
	)
	(segment
		(start 157.76829 -29.464)
		(end 155.040584 -36.048188)
		(width 0.089408)
		(layer "In11.Cu")
		(net "SMB_DDR_GHJ_SDA_G_R")
	)
	(segment
		(start 129.432558 -61.648086)
		(end 129.437384 -61.656722)
		(width 0.0889)
		(layer "In11.Cu")
		(net "SMB_DDR_GHJ_SDA_G_R")
	)
	(segment
		(start 160.887664 -26.425398)
		(end 160.858454 -26.437336)
		(width 0.089408)
		(layer "In11.Cu")
		(net "SMB_DDR_GHJ_SDA_G_R")
	)
	(segment
		(start 129.432558 -59.666886)
		(end 129.437384 -59.675522)
		(width 0.0889)
		(layer "In11.Cu")
		(net "SMB_DDR_GHJ_SDA_G_R")
	)
	(segment
		(start 130.817874 -54.323234)
		(end 130.785108 -54.323234)
		(width 0.0889)
		(layer "In11.Cu")
		(net "SMB_DDR_GHJ_SDA_G_R")
	)
	(segment
		(start 129.426208 -61.637418)
		(end 129.432558 -61.648086)
		(width 0.0889)
		(layer "In11.Cu")
		(net "SMB_DDR_GHJ_SDA_G_R")
	)
	(segment
		(start 170.38193 -22.654006)
		(end 170.077384 -22.34946)
		(width 0.0889)
		(layer "In11.Cu")
		(net "SMB_DDR_GHJ_SDA_G_R")
	)
	(segment
		(start 129.426208 -55.693818)
		(end 129.432558 -55.704486)
		(width 0.0889)
		(layer "In11.Cu")
		(net "SMB_DDR_GHJ_SDA_G_R")
	)
	(segment
		(start 138.891772 -52.197)
		(end 137.8966 -52.197)
		(width 0.089408)
		(layer "In11.Cu")
		(net "SMB_DDR_GHJ_SDA_G_R")
	)
	(segment
		(start 155.040584 -36.048188)
		(end 138.891772 -52.197)
		(width 0.089408)
		(layer "In11.Cu")
		(net "SMB_DDR_GHJ_SDA_G_R")
	)
	(segment
		(start 129.426208 -56.684418)
		(end 129.432558 -56.695086)
		(width 0.0889)
		(layer "In11.Cu")
		(net "SMB_DDR_GHJ_SDA_G_R")
	)
	(segment
		(start 170.077384 -22.34946)
		(end 169.6466 -22.34946)
		(width 0.0889)
		(layer "In11.Cu")
		(net "SMB_DDR_GHJ_SDA_G_R")
	)
	(segment
		(start 160.896046 -26.421842)
		(end 160.887664 -26.425398)
		(width 0.089408)
		(layer "In11.Cu")
		(net "SMB_DDR_GHJ_SDA_G_R")
	)
	(segment
		(start 135.113268 -52.837334)
		(end 135.0772 -52.837334)
		(width 0.0889)
		(layer "In11.Cu")
		(net "SMB_DDR_GHJ_SDA_G_R")
	)
	(segment
		(start 160.858454 -26.437336)
		(end 160.750504 -26.481532)
		(width 0.089408)
		(layer "In11.Cu")
		(net "SMB_DDR_GHJ_SDA_G_R")
	)
	(segment
		(start 167.767 -22.65299)
		(end 167.767 -22.806152)
		(width 0.089408)
		(layer "In11.Cu")
		(net "SMB_DDR_GHJ_SDA_G_R")
	)
	(segment
		(start 160.750504 -26.481532)
		(end 157.76829 -29.464)
		(width 0.089408)
		(layer "In11.Cu")
		(net "SMB_DDR_GHJ_SDA_G_R")
	)
	(segment
		(start 129.955544 -54.818788)
		(end 129.922778 -54.818788)
		(width 0.0889)
		(layer "In11.Cu")
		(net "SMB_DDR_GHJ_SDA_G_R")
	)
	(segment
		(start 129.432558 -55.704486)
		(end 129.437384 -55.713122)
		(width 0.0889)
		(layer "In11.Cu")
		(net "SMB_DDR_GHJ_SDA_G_R")
	)
	(segment
		(start 129.426208 -62.628018)
		(end 129.432558 -62.638686)
		(width 0.0889)
		(layer "In11.Cu")
		(net "SMB_DDR_GHJ_SDA_G_R")
	)
	(segment
		(start 137.8966 -52.197)
		(end 137.754614 -52.338986)
		(width 0.089408)
		(layer "In11.Cu")
		(net "SMB_DDR_GHJ_SDA_G_R")
	)
	(segment
		(start 132.537708 -53.332634)
		(end 132.498084 -53.332634)
		(width 0.0889)
		(layer "In11.Cu")
		(net "SMB_DDR_GHJ_SDA_G_R")
	)
	(segment
		(start 169.6466 -22.34946)
		(end 168.07053 -22.34946)
		(width 0.089408)
		(layer "In11.Cu")
		(net "SMB_DDR_GHJ_SDA_G_R")
	)
	(arc
		(start 134.748524 -52.637436)
		(mid 134.236714 -52.341897)
		(end 133.724904 -52.637436)
		(width 0.0889)
		(layer "In11.Cu")
		(net "SMB_DDR_GHJ_SDA_G_R")
	)
	(arc
		(start 137.675874 -52.338986)
		(mid 137.377465 -52.418971)
		(end 137.158984 -52.637436)
		(width 0.0889)
		(layer "In11.Cu")
		(net "SMB_DDR_GHJ_SDA_G_R")
	)
	(arc
		(start 129.922778 -54.818788)
		(mid 129.430388 -55.117721)
		(end 129.426208 -55.693818)
		(width 0.0889)
		(layer "In11.Cu")
		(net "SMB_DDR_GHJ_SDA_G_R")
	)
	(arc
		(start 129.437384 -62.647322)
		(mid 129.486139 -62.843674)
		(end 129.432558 -63.038736)
		(width 0.0889)
		(layer "In11.Cu")
		(net "SMB_DDR_GHJ_SDA_G_R")
	)
	(arc
		(start 131.149598 -54.123336)
		(mid 131.009519 -54.266072)
		(end 130.817874 -54.323234)
		(width 0.0889)
		(layer "In11.Cu")
		(net "SMB_DDR_GHJ_SDA_G_R")
	)
	(arc
		(start 132.866384 -53.132736)
		(mid 132.72764 -53.274769)
		(end 132.537708 -53.332634)
		(width 0.0889)
		(layer "In11.Cu")
		(net "SMB_DDR_GHJ_SDA_G_R")
	)
	(arc
		(start 129.432558 -63.038736)
		(mid 129.23752 -63.424449)
		(end 129.085848 -63.829184)
		(width 0.0889)
		(layer "In11.Cu")
		(net "SMB_DDR_GHJ_SDA_G_R")
	)
	(arc
		(start 130.785108 -54.323234)
		(mid 130.499684 -54.406701)
		(end 130.291078 -54.618636)
		(width 0.0889)
		(layer "In11.Cu")
		(net "SMB_DDR_GHJ_SDA_G_R")
	)
	(arc
		(start 129.437384 -57.694322)
		(mid 129.486139 -57.890674)
		(end 129.432558 -58.085736)
		(width 0.0889)
		(layer "In11.Cu")
		(net "SMB_DDR_GHJ_SDA_G_R")
	)
	(arc
		(start 133.360414 -52.837334)
		(mid 133.07499 -52.920801)
		(end 132.866384 -53.132736)
		(width 0.0889)
		(layer "In11.Cu")
		(net "SMB_DDR_GHJ_SDA_G_R")
	)
	(arc
		(start 129.432558 -56.104536)
		(mid 129.353336 -56.393654)
		(end 129.426208 -56.684418)
		(width 0.0889)
		(layer "In11.Cu")
		(net "SMB_DDR_GHJ_SDA_G_R")
	)
	(arc
		(start 135.0772 -52.837334)
		(mid 134.887271 -52.779464)
		(end 134.748524 -52.637436)
		(width 0.0889)
		(layer "In11.Cu")
		(net "SMB_DDR_GHJ_SDA_G_R")
	)
	(arc
		(start 129.432558 -61.057536)
		(mid 129.353336 -61.346654)
		(end 129.426208 -61.637418)
		(width 0.0889)
		(layer "In11.Cu")
		(net "SMB_DDR_GHJ_SDA_G_R")
	)
	(arc
		(start 129.432558 -62.048136)
		(mid 129.353336 -62.337254)
		(end 129.426208 -62.628018)
		(width 0.0889)
		(layer "In11.Cu")
		(net "SMB_DDR_GHJ_SDA_G_R")
	)
	(arc
		(start 129.432558 -60.066936)
		(mid 129.353336 -60.356054)
		(end 129.426208 -60.646818)
		(width 0.0889)
		(layer "In11.Cu")
		(net "SMB_DDR_GHJ_SDA_G_R")
	)
	(arc
		(start 132.004562 -53.633624)
		(mid 131.858596 -53.776023)
		(end 131.661408 -53.827934)
		(width 0.0889)
		(layer "In11.Cu")
		(net "SMB_DDR_GHJ_SDA_G_R")
	)
	(arc
		(start 130.291078 -54.618636)
		(mid 130.149395 -54.76244)
		(end 129.955544 -54.818788)
		(width 0.0889)
		(layer "In11.Cu")
		(net "SMB_DDR_GHJ_SDA_G_R")
	)
	(arc
		(start 136.465564 -52.637436)
		(mid 135.953754 -52.341897)
		(end 135.441944 -52.637436)
		(width 0.0889)
		(layer "In11.Cu")
		(net "SMB_DDR_GHJ_SDA_G_R")
	)
	(arc
		(start 129.432558 -58.085736)
		(mid 129.353427 -58.381138)
		(end 129.432558 -58.67654)
		(width 0.0889)
		(layer "In11.Cu")
		(net "SMB_DDR_GHJ_SDA_G_R")
	)
	(arc
		(start 129.426208 -59.087004)
		(mid 129.35341 -59.377767)
		(end 129.432558 -59.666886)
		(width 0.0889)
		(layer "In11.Cu")
		(net "SMB_DDR_GHJ_SDA_G_R")
	)
	(arc
		(start 135.441944 -52.637436)
		(mid 135.3032 -52.779469)
		(end 135.113268 -52.837334)
		(width 0.0889)
		(layer "In11.Cu")
		(net "SMB_DDR_GHJ_SDA_G_R")
	)
	(arc
		(start 129.432558 -58.67654)
		(mid 129.486057 -58.876438)
		(end 129.432558 -59.076336)
		(width 0.0889)
		(layer "In11.Cu")
		(net "SMB_DDR_GHJ_SDA_G_R")
	)
	(arc
		(start 132.498084 -53.332634)
		(mid 132.214867 -53.416915)
		(end 132.007864 -53.627782)
		(width 0.0889)
		(layer "In11.Cu")
		(net "SMB_DDR_GHJ_SDA_G_R")
	)
	(arc
		(start 131.648454 -53.827934)
		(mid 131.360309 -53.910253)
		(end 131.149598 -54.123336)
		(width 0.0889)
		(layer "In11.Cu")
		(net "SMB_DDR_GHJ_SDA_G_R")
	)
	(arc
		(start 133.724904 -52.637436)
		(mid 133.58616 -52.779469)
		(end 133.396228 -52.837334)
		(width 0.0889)
		(layer "In11.Cu")
		(net "SMB_DDR_GHJ_SDA_G_R")
	)
	(arc
		(start 129.437384 -55.713122)
		(mid 129.486139 -55.909474)
		(end 129.432558 -56.104536)
		(width 0.0889)
		(layer "In11.Cu")
		(net "SMB_DDR_GHJ_SDA_G_R")
	)
	(arc
		(start 129.437384 -61.656722)
		(mid 129.486139 -61.853074)
		(end 129.432558 -62.048136)
		(width 0.0889)
		(layer "In11.Cu")
		(net "SMB_DDR_GHJ_SDA_G_R")
	)
	(arc
		(start 137.158984 -52.637436)
		(mid 137.02024 -52.779469)
		(end 136.830308 -52.837334)
		(width 0.0889)
		(layer "In11.Cu")
		(net "SMB_DDR_GHJ_SDA_G_R")
	)
	(arc
		(start 129.437384 -60.666122)
		(mid 129.486139 -60.862474)
		(end 129.432558 -61.057536)
		(width 0.0889)
		(layer "In11.Cu")
		(net "SMB_DDR_GHJ_SDA_G_R")
	)
	(arc
		(start 129.432558 -57.095136)
		(mid 129.353336 -57.384254)
		(end 129.426208 -57.675018)
		(width 0.0889)
		(layer "In11.Cu")
		(net "SMB_DDR_GHJ_SDA_G_R")
	)
	(arc
		(start 129.437384 -59.675522)
		(mid 129.486139 -59.871874)
		(end 129.432558 -60.066936)
		(width 0.0889)
		(layer "In11.Cu")
		(net "SMB_DDR_GHJ_SDA_G_R")
	)
	(arc
		(start 136.79424 -52.837334)
		(mid 136.604311 -52.779464)
		(end 136.465564 -52.637436)
		(width 0.0889)
		(layer "In11.Cu")
		(net "SMB_DDR_GHJ_SDA_G_R")
	)
	(arc
		(start 129.437384 -56.703722)
		(mid 129.486139 -56.900074)
		(end 129.432558 -57.095136)
		(width 0.0889)
		(layer "In11.Cu")
		(net "SMB_DDR_GHJ_SDA_G_R")
	)
	(segment
		(start 127.655828 -65.315338)
		(end 128.227328 -65.315338)
		(width 0.1016)
		(layer "F.Cu")
		(net "SMB_DDR_GHJ_SCL_G_R")
	)
	(via
		(at 168.237408 -22.749764)
		(size 0.508)
		(drill 0.254)
		(layers "F.Cu" "B.Cu")
		(net "SMB_DDR_GHJ_SCL_G_R")
	)
	(via
		(at 128.227328 -65.315338)
		(size 0.508)
		(drill 0.254)
		(layers "F.Cu" "B.Cu")
		(net "SMB_DDR_GHJ_SCL_G_R")
	)
	(segment
		(start 167.61587 -22.749764)
		(end 168.237408 -22.749764)
		(width 0.10795)
		(layer "B.Cu")
		(net "SMB_DDR_GHJ_SCL_G_R")
	)
	(segment
		(start 132.537454 -53.523388)
		(end 132.507482 -53.523388)
		(width 0.0889)
		(layer "In11.Cu")
		(net "SMB_DDR_GHJ_SCL_G_R")
	)
	(segment
		(start 161.006028 -26.693114)
		(end 161.001964 -26.694892)
		(width 0.089408)
		(layer "In11.Cu")
		(net "SMB_DDR_GHJ_SCL_G_R")
	)
	(segment
		(start 138.970004 -52.532788)
		(end 137.9474 -52.532788)
		(width 0.089408)
		(layer "In11.Cu")
		(net "SMB_DDR_GHJ_SCL_G_R")
	)
	(segment
		(start 129.597658 -61.552836)
		(end 129.604008 -61.563504)
		(width 0.0889)
		(layer "In11.Cu")
		(net "SMB_DDR_GHJ_SCL_G_R")
	)
	(segment
		(start 130.824478 -54.513734)
		(end 130.791712 -54.513734)
		(width 0.0889)
		(layer "In11.Cu")
		(net "SMB_DDR_GHJ_SCL_G_R")
	)
	(segment
		(start 129.592832 -62.5348)
		(end 129.597658 -62.543436)
		(width 0.0889)
		(layer "In11.Cu")
		(net "SMB_DDR_GHJ_SCL_G_R")
	)
	(segment
		(start 129.604008 -59.160918)
		(end 129.597658 -59.171586)
		(width 0.0889)
		(layer "In11.Cu")
		(net "SMB_DDR_GHJ_SCL_G_R")
	)
	(segment
		(start 133.399784 -53.028088)
		(end 133.36016 -53.028088)
		(width 0.0889)
		(layer "In11.Cu")
		(net "SMB_DDR_GHJ_SCL_G_R")
	)
	(segment
		(start 135.116824 -53.028088)
		(end 135.073644 -53.028088)
		(width 0.0889)
		(layer "In11.Cu")
		(net "SMB_DDR_GHJ_SCL_G_R")
	)
	(segment
		(start 129.592832 -56.5912)
		(end 129.597658 -56.599836)
		(width 0.0889)
		(layer "In11.Cu")
		(net "SMB_DDR_GHJ_SCL_G_R")
	)
	(segment
		(start 129.597658 -60.562236)
		(end 129.604008 -60.572904)
		(width 0.0889)
		(layer "In11.Cu")
		(net "SMB_DDR_GHJ_SCL_G_R")
	)
	(segment
		(start 155.288996 -36.213796)
		(end 138.970004 -52.532788)
		(width 0.089408)
		(layer "In11.Cu")
		(net "SMB_DDR_GHJ_SCL_G_R")
	)
	(segment
		(start 161.001964 -26.694892)
		(end 160.916112 -26.730198)
		(width 0.089408)
		(layer "In11.Cu")
		(net "SMB_DDR_GHJ_SCL_G_R")
	)
	(segment
		(start 129.592832 -58.5724)
		(end 129.597658 -58.581036)
		(width 0.0889)
		(layer "In11.Cu")
		(net "SMB_DDR_GHJ_SCL_G_R")
	)
	(segment
		(start 158.016448 -29.629862)
		(end 155.288996 -36.213796)
		(width 0.089408)
		(layer "In11.Cu")
		(net "SMB_DDR_GHJ_SCL_G_R")
	)
	(segment
		(start 166.61892 -24.368252)
		(end 161.00806 -26.692352)
		(width 0.089408)
		(layer "In11.Cu")
		(net "SMB_DDR_GHJ_SCL_G_R")
	)
	(segment
		(start 129.592832 -61.5442)
		(end 129.597658 -61.552836)
		(width 0.0889)
		(layer "In11.Cu")
		(net "SMB_DDR_GHJ_SCL_G_R")
	)
	(segment
		(start 129.962148 -55.009288)
		(end 129.929382 -55.009288)
		(width 0.0889)
		(layer "In11.Cu")
		(net "SMB_DDR_GHJ_SCL_G_R")
	)
	(segment
		(start 129.597658 -57.590436)
		(end 129.604008 -57.601104)
		(width 0.0889)
		(layer "In11.Cu")
		(net "SMB_DDR_GHJ_SCL_G_R")
	)
	(segment
		(start 129.592832 -57.5818)
		(end 129.597658 -57.590436)
		(width 0.0889)
		(layer "In11.Cu")
		(net "SMB_DDR_GHJ_SCL_G_R")
	)
	(segment
		(start 129.592832 -60.5536)
		(end 129.597658 -60.562236)
		(width 0.0889)
		(layer "In11.Cu")
		(net "SMB_DDR_GHJ_SCL_G_R")
	)
	(segment
		(start 131.674362 -54.018688)
		(end 131.646422 -54.018688)
		(width 0.0889)
		(layer "In11.Cu")
		(net "SMB_DDR_GHJ_SCL_G_R")
	)
	(segment
		(start 161.00806 -26.692352)
		(end 161.006028 -26.693114)
		(width 0.089408)
		(layer "In11.Cu")
		(net "SMB_DDR_GHJ_SCL_G_R")
	)
	(segment
		(start 160.916112 -26.730198)
		(end 158.016448 -29.629862)
		(width 0.089408)
		(layer "In11.Cu")
		(net "SMB_DDR_GHJ_SCL_G_R")
	)
	(segment
		(start 129.597658 -62.543436)
		(end 129.604008 -62.554104)
		(width 0.0889)
		(layer "In11.Cu")
		(net "SMB_DDR_GHJ_SCL_G_R")
	)
	(segment
		(start 168.237408 -22.749764)
		(end 166.61892 -24.368252)
		(width 0.089408)
		(layer "In11.Cu")
		(net "SMB_DDR_GHJ_SCL_G_R")
	)
	(segment
		(start 129.597658 -56.599836)
		(end 129.604008 -56.610504)
		(width 0.0889)
		(layer "In11.Cu")
		(net "SMB_DDR_GHJ_SCL_G_R")
	)
	(segment
		(start 137.9474 -52.532788)
		(end 137.659618 -52.532788)
		(width 0.0889)
		(layer "In11.Cu")
		(net "SMB_DDR_GHJ_SCL_G_R")
	)
	(segment
		(start 129.597658 -55.609236)
		(end 129.604008 -55.619904)
		(width 0.0889)
		(layer "In11.Cu")
		(net "SMB_DDR_GHJ_SCL_G_R")
	)
	(segment
		(start 129.280666 -64.262)
		(end 128.227328 -65.315338)
		(width 0.089408)
		(layer "In11.Cu")
		(net "SMB_DDR_GHJ_SCL_G_R")
	)
	(segment
		(start 129.592832 -55.6006)
		(end 129.597658 -55.609236)
		(width 0.0889)
		(layer "In11.Cu")
		(net "SMB_DDR_GHJ_SCL_G_R")
	)
	(segment
		(start 136.833864 -53.028088)
		(end 136.790684 -53.028088)
		(width 0.0889)
		(layer "In11.Cu")
		(net "SMB_DDR_GHJ_SCL_G_R")
	)
	(arc
		(start 129.604008 -61.563504)
		(mid 129.676806 -61.854267)
		(end 129.597658 -62.143386)
		(width 0.0889)
		(layer "In11.Cu")
		(net "SMB_DDR_GHJ_SCL_G_R")
	)
	(arc
		(start 129.929382 -55.009288)
		(mid 129.596464 -55.211279)
		(end 129.592832 -55.6006)
		(width 0.0889)
		(layer "In11.Cu")
		(net "SMB_DDR_GHJ_SCL_G_R")
	)
	(arc
		(start 129.604008 -55.619904)
		(mid 129.676806 -55.910667)
		(end 129.597658 -56.199786)
		(width 0.0889)
		(layer "In11.Cu")
		(net "SMB_DDR_GHJ_SCL_G_R")
	)
	(arc
		(start 133.890004 -52.73294)
		(mid 133.683 -52.943804)
		(end 133.399784 -53.028088)
		(width 0.0889)
		(layer "In11.Cu")
		(net "SMB_DDR_GHJ_SCL_G_R")
	)
	(arc
		(start 130.791712 -54.513734)
		(mid 130.597862 -54.570084)
		(end 130.456178 -54.713886)
		(width 0.0889)
		(layer "In11.Cu")
		(net "SMB_DDR_GHJ_SCL_G_R")
	)
	(arc
		(start 134.583424 -52.73294)
		(mid 134.236714 -52.532629)
		(end 133.890004 -52.73294)
		(width 0.0889)
		(layer "In11.Cu")
		(net "SMB_DDR_GHJ_SCL_G_R")
	)
	(arc
		(start 135.607044 -52.73294)
		(mid 135.40004 -52.943804)
		(end 135.116824 -53.028088)
		(width 0.0889)
		(layer "In11.Cu")
		(net "SMB_DDR_GHJ_SCL_G_R")
	)
	(arc
		(start 137.659618 -52.532788)
		(mid 137.465768 -52.589138)
		(end 137.324084 -52.73294)
		(width 0.0889)
		(layer "In11.Cu")
		(net "SMB_DDR_GHJ_SCL_G_R")
	)
	(arc
		(start 129.604008 -56.610504)
		(mid 129.676806 -56.901267)
		(end 129.597658 -57.190386)
		(width 0.0889)
		(layer "In11.Cu")
		(net "SMB_DDR_GHJ_SCL_G_R")
	)
	(arc
		(start 129.597658 -57.190386)
		(mid 129.544188 -57.385449)
		(end 129.592832 -57.5818)
		(width 0.0889)
		(layer "In11.Cu")
		(net "SMB_DDR_GHJ_SCL_G_R")
	)
	(arc
		(start 129.597658 -60.162186)
		(mid 129.544188 -60.357249)
		(end 129.592832 -60.5536)
		(width 0.0889)
		(layer "In11.Cu")
		(net "SMB_DDR_GHJ_SCL_G_R")
	)
	(arc
		(start 129.597658 -63.133986)
		(mid 129.502064 -63.394748)
		(end 129.500376 -63.672466)
		(width 0.0889)
		(layer "In11.Cu")
		(net "SMB_DDR_GHJ_SCL_G_R")
	)
	(arc
		(start 129.597658 -58.180986)
		(mid 129.544188 -58.376049)
		(end 129.592832 -58.5724)
		(width 0.0889)
		(layer "In11.Cu")
		(net "SMB_DDR_GHJ_SCL_G_R")
	)
	(arc
		(start 137.324084 -52.73294)
		(mid 137.11708 -52.943804)
		(end 136.833864 -53.028088)
		(width 0.0889)
		(layer "In11.Cu")
		(net "SMB_DDR_GHJ_SCL_G_R")
	)
	(arc
		(start 132.507482 -53.523388)
		(mid 132.314379 -53.579907)
		(end 132.173218 -53.723286)
		(width 0.0889)
		(layer "In11.Cu")
		(net "SMB_DDR_GHJ_SCL_G_R")
	)
	(arc
		(start 129.597658 -62.143386)
		(mid 129.544188 -62.338449)
		(end 129.592832 -62.5348)
		(width 0.0889)
		(layer "In11.Cu")
		(net "SMB_DDR_GHJ_SCL_G_R")
	)
	(arc
		(start 131.646422 -54.018688)
		(mid 131.45478 -54.075854)
		(end 131.314698 -54.218586)
		(width 0.0889)
		(layer "In11.Cu")
		(net "SMB_DDR_GHJ_SCL_G_R")
	)
	(arc
		(start 129.597658 -59.171586)
		(mid 129.544159 -59.371484)
		(end 129.597658 -59.571382)
		(width 0.0889)
		(layer "In11.Cu")
		(net "SMB_DDR_GHJ_SCL_G_R")
	)
	(arc
		(start 129.500376 -63.672466)
		(mid 129.469367 -63.996602)
		(end 129.280666 -64.262)
		(width 0.0889)
		(layer "In11.Cu")
		(net "SMB_DDR_GHJ_SCL_G_R")
	)
	(arc
		(start 129.597658 -56.199786)
		(mid 129.544188 -56.394849)
		(end 129.592832 -56.5912)
		(width 0.0889)
		(layer "In11.Cu")
		(net "SMB_DDR_GHJ_SCL_G_R")
	)
	(arc
		(start 129.604008 -57.601104)
		(mid 129.676806 -57.891867)
		(end 129.597658 -58.180986)
		(width 0.0889)
		(layer "In11.Cu")
		(net "SMB_DDR_GHJ_SCL_G_R")
	)
	(arc
		(start 131.314698 -54.218586)
		(mid 131.107694 -54.42945)
		(end 130.824478 -54.513734)
		(width 0.0889)
		(layer "In11.Cu")
		(net "SMB_DDR_GHJ_SCL_G_R")
	)
	(arc
		(start 136.790684 -53.028088)
		(mid 136.507467 -52.943807)
		(end 136.300464 -52.73294)
		(width 0.0889)
		(layer "In11.Cu")
		(net "SMB_DDR_GHJ_SCL_G_R")
	)
	(arc
		(start 129.604008 -62.554104)
		(mid 129.676806 -62.844867)
		(end 129.597658 -63.133986)
		(width 0.0889)
		(layer "In11.Cu")
		(net "SMB_DDR_GHJ_SCL_G_R")
	)
	(arc
		(start 132.173218 -53.723286)
		(mid 131.962505 -53.936365)
		(end 131.674362 -54.018688)
		(width 0.0889)
		(layer "In11.Cu")
		(net "SMB_DDR_GHJ_SCL_G_R")
	)
	(arc
		(start 136.300464 -52.73294)
		(mid 135.953754 -52.532629)
		(end 135.607044 -52.73294)
		(width 0.0889)
		(layer "In11.Cu")
		(net "SMB_DDR_GHJ_SCL_G_R")
	)
	(arc
		(start 135.073644 -53.028088)
		(mid 134.790427 -52.943807)
		(end 134.583424 -52.73294)
		(width 0.0889)
		(layer "In11.Cu")
		(net "SMB_DDR_GHJ_SCL_G_R")
	)
	(arc
		(start 129.597658 -61.152786)
		(mid 129.544188 -61.347849)
		(end 129.592832 -61.5442)
		(width 0.0889)
		(layer "In11.Cu")
		(net "SMB_DDR_GHJ_SCL_G_R")
	)
	(arc
		(start 133.031484 -53.227986)
		(mid 132.822876 -53.439918)
		(end 132.537454 -53.523388)
		(width 0.0889)
		(layer "In11.Cu")
		(net "SMB_DDR_GHJ_SCL_G_R")
	)
	(arc
		(start 129.597658 -58.581036)
		(mid 129.67688 -58.870154)
		(end 129.604008 -59.160918)
		(width 0.0889)
		(layer "In11.Cu")
		(net "SMB_DDR_GHJ_SCL_G_R")
	)
	(arc
		(start 133.36016 -53.028088)
		(mid 133.170231 -53.085958)
		(end 133.031484 -53.227986)
		(width 0.0889)
		(layer "In11.Cu")
		(net "SMB_DDR_GHJ_SCL_G_R")
	)
	(arc
		(start 129.604008 -60.572904)
		(mid 129.676806 -60.863667)
		(end 129.597658 -61.152786)
		(width 0.0889)
		(layer "In11.Cu")
		(net "SMB_DDR_GHJ_SCL_G_R")
	)
	(arc
		(start 129.597658 -59.571382)
		(mid 129.676789 -59.866784)
		(end 129.597658 -60.162186)
		(width 0.0889)
		(layer "In11.Cu")
		(net "SMB_DDR_GHJ_SCL_G_R")
	)
	(arc
		(start 130.456178 -54.713886)
		(mid 130.24757 -54.925818)
		(end 129.962148 -55.009288)
		(width 0.0889)
		(layer "In11.Cu")
		(net "SMB_DDR_GHJ_SCL_G_R")
	)
	(segment
		(start 165.64102 3.79222)
		(end 165.64102 2.87782)
		(width 0.10795)
		(layer "F.Cu")
		(net "SMB_DDR_GHJ_VPP_SDA_R")
	)
	(segment
		(start 165.4556 2.6924)
		(end 164.719 2.6924)
		(width 0.10795)
		(layer "F.Cu")
		(net "SMB_DDR_GHJ_VPP_SDA_R")
	)
	(segment
		(start 164.719 2.6924)
		(end 164.338 3.0734)
		(width 0.10795)
		(layer "F.Cu")
		(net "SMB_DDR_GHJ_VPP_SDA_R")
	)
	(segment
		(start 165.64102 2.87782)
		(end 165.4556 2.6924)
		(width 0.10795)
		(layer "F.Cu")
		(net "SMB_DDR_GHJ_VPP_SDA_R")
	)
	(via
		(at 164.338 3.0734)
		(size 0.508)
		(drill 0.254)
		(layers "F.Cu" "B.Cu")
		(net "SMB_DDR_GHJ_VPP_SDA_R")
	)
	(segment
		(start 165.9001 3.2385)
		(end 166.0779 3.0607)
		(width 0.10795)
		(layer "B.Cu")
		(net "SMB_DDR_GHJ_VPP_SDA_R")
	)
	(segment
		(start 164.338 3.0734)
		(end 165.2016 3.0734)
		(width 0.10795)
		(layer "B.Cu")
		(net "SMB_DDR_GHJ_VPP_SDA_R")
	)
	(segment
		(start 165.2016 3.0734)
		(end 165.8874 2.3876)
		(width 0.10795)
		(layer "B.Cu")
		(net "SMB_DDR_GHJ_VPP_SDA_R")
	)
	(segment
		(start 165.9001 3.556)
		(end 165.9001 3.2385)
		(width 0.10795)
		(layer "B.Cu")
		(net "SMB_DDR_GHJ_VPP_SDA_R")
	)
	(segment
		(start 166.0779 2.4765)
		(end 165.8874 2.286)
		(width 0.10795)
		(layer "B.Cu")
		(net "SMB_DDR_GHJ_VPP_SDA_R")
	)
	(segment
		(start 166.0779 3.0607)
		(end 166.0779 2.4765)
		(width 0.10795)
		(layer "B.Cu")
		(net "SMB_DDR_GHJ_VPP_SDA_R")
	)
	(segment
		(start 165.8874 2.3876)
		(end 165.8874 2.286)
		(width 0.10795)
		(layer "B.Cu")
		(net "SMB_DDR_GHJ_VPP_SDA_R")
	)
	(segment
		(start 153.79954 -10.422382)
		(end 153.79954 -9.158478)
		(width 0.10795)
		(layer "F.Cu")
		(net "SMB_DDR_GHJ_VPP_SDA")
	)
	(segment
		(start 153.79954 -0.821182)
		(end 153.79954 0.442722)
		(width 0.10795)
		(layer "F.Cu")
		(net "SMB_DDR_GHJ_VPP_SDA")
	)
	(segment
		(start 153.79954 -20.023582)
		(end 153.79954 -18.759678)
		(width 0.10795)
		(layer "F.Cu")
		(net "SMB_DDR_GHJ_VPP_SDA")
	)
	(via
		(at 153.79954 -18.759678)
		(size 0.508)
		(drill 0.254)
		(layers "F.Cu" "B.Cu")
		(net "SMB_DDR_GHJ_VPP_SDA")
	)
	(via
		(at 153.79954 -9.158478)
		(size 0.508)
		(drill 0.254)
		(layers "F.Cu" "B.Cu")
		(net "SMB_DDR_GHJ_VPP_SDA")
	)
	(via
		(at 153.79954 -21.528278)
		(size 0.508)
		(drill 0.254)
		(layers "F.Cu" "B.Cu")
		(net "SMB_DDR_GHJ_VPP_SDA")
	)
	(via
		(at 153.79954 0.442722)
		(size 0.508)
		(drill 0.254)
		(layers "F.Cu" "B.Cu")
		(net "SMB_DDR_GHJ_VPP_SDA")
	)
	(via
		(at 153.79954 -2.325878)
		(size 0.508)
		(drill 0.254)
		(layers "F.Cu" "B.Cu")
		(net "SMB_DDR_GHJ_VPP_SDA")
	)
	(via
		(at 164.338 2.413)
		(size 0.508)
		(drill 0.254)
		(layers "F.Cu" "B.Cu")
		(net "SMB_DDR_GHJ_VPP_SDA")
	)
	(via
		(at 153.79954 -11.927078)
		(size 0.508)
		(drill 0.254)
		(layers "F.Cu" "B.Cu")
		(net "SMB_DDR_GHJ_VPP_SDA")
	)
	(segment
		(start 164.9984 2.286)
		(end 164.465 2.286)
		(width 0.10795)
		(layer "B.Cu")
		(net "SMB_DDR_GHJ_VPP_SDA")
	)
	(segment
		(start 153.79954 -20.224242)
		(end 153.79954 -21.528278)
		(width 0.10795)
		(layer "B.Cu")
		(net "SMB_DDR_GHJ_VPP_SDA")
	)
	(segment
		(start 164.465 2.286)
		(end 164.338 2.413)
		(width 0.10795)
		(layer "B.Cu")
		(net "SMB_DDR_GHJ_VPP_SDA")
	)
	(segment
		(start 153.79954 -1.021842)
		(end 153.79954 -2.325878)
		(width 0.10795)
		(layer "B.Cu")
		(net "SMB_DDR_GHJ_VPP_SDA")
	)
	(segment
		(start 153.79954 -10.623042)
		(end 153.79954 -11.927078)
		(width 0.10795)
		(layer "B.Cu")
		(net "SMB_DDR_GHJ_VPP_SDA")
	)
	(segment
		(start 154.226768 -12.354306)
		(end 153.79954 -11.927078)
		(width 0.089408)
		(layer "In2.Cu")
		(net "SMB_DDR_GHJ_VPP_SDA")
	)
	(segment
		(start 154.5336 1.3462)
		(end 153.79954 0.61214)
		(width 0.089408)
		(layer "In2.Cu")
		(net "SMB_DDR_GHJ_VPP_SDA")
	)
	(segment
		(start 164.6047 2.413)
		(end 164.8968 2.1209)
		(width 0.089408)
		(layer "In2.Cu")
		(net "SMB_DDR_GHJ_VPP_SDA")
	)
	(segment
		(start 153.79954 -18.759678)
		(end 154.226768 -18.33245)
		(width 0.089408)
		(layer "In2.Cu")
		(net "SMB_DDR_GHJ_VPP_SDA")
	)
	(segment
		(start 153.79954 -21.528278)
		(end 153.79954 -18.759678)
		(width 0.089408)
		(layer "In2.Cu")
		(net "SMB_DDR_GHJ_VPP_SDA")
	)
	(segment
		(start 164.8968 2.1209)
		(end 164.8968 1.524)
		(width 0.089408)
		(layer "In2.Cu")
		(net "SMB_DDR_GHJ_VPP_SDA")
	)
	(segment
		(start 164.8968 1.524)
		(end 162.7124 -0.6604)
		(width 0.089408)
		(layer "In2.Cu")
		(net "SMB_DDR_GHJ_VPP_SDA")
	)
	(segment
		(start 153.79954 -2.325878)
		(end 153.79954 0.442722)
		(width 0.089408)
		(layer "In2.Cu")
		(net "SMB_DDR_GHJ_VPP_SDA")
	)
	(segment
		(start 158.2674 -0.6604)
		(end 156.2608 1.3462)
		(width 0.089408)
		(layer "In2.Cu")
		(net "SMB_DDR_GHJ_VPP_SDA")
	)
	(segment
		(start 154.226768 -2.753106)
		(end 153.79954 -2.325878)
		(width 0.089408)
		(layer "In2.Cu")
		(net "SMB_DDR_GHJ_VPP_SDA")
	)
	(segment
		(start 154.226768 -8.73125)
		(end 154.226768 -2.753106)
		(width 0.089408)
		(layer "In2.Cu")
		(net "SMB_DDR_GHJ_VPP_SDA")
	)
	(segment
		(start 164.338 2.413)
		(end 164.6047 2.413)
		(width 0.089408)
		(layer "In2.Cu")
		(net "SMB_DDR_GHJ_VPP_SDA")
	)
	(segment
		(start 153.79954 0.61214)
		(end 153.79954 0.442722)
		(width 0.089408)
		(layer "In2.Cu")
		(net "SMB_DDR_GHJ_VPP_SDA")
	)
	(segment
		(start 153.79954 -9.158478)
		(end 154.226768 -8.73125)
		(width 0.089408)
		(layer "In2.Cu")
		(net "SMB_DDR_GHJ_VPP_SDA")
	)
	(segment
		(start 153.79954 -11.927078)
		(end 153.79954 -9.158478)
		(width 0.089408)
		(layer "In2.Cu")
		(net "SMB_DDR_GHJ_VPP_SDA")
	)
	(segment
		(start 162.7124 -0.6604)
		(end 158.2674 -0.6604)
		(width 0.089408)
		(layer "In2.Cu")
		(net "SMB_DDR_GHJ_VPP_SDA")
	)
	(segment
		(start 154.226768 -18.33245)
		(end 154.226768 -12.354306)
		(width 0.089408)
		(layer "In2.Cu")
		(net "SMB_DDR_GHJ_VPP_SDA")
	)
	(segment
		(start 156.2608 1.3462)
		(end 154.5336 1.3462)
		(width 0.089408)
		(layer "In2.Cu")
		(net "SMB_DDR_GHJ_VPP_SDA")
	)
	(segment
		(start 167.600122 2.881122)
		(end 167.386 2.667)
		(width 0.10795)
		(layer "F.Cu")
		(net "SMB_DDR_GHJ_VPP_SCL_R")
	)
	(segment
		(start 167.386 2.667)
		(end 166.624 2.667)
		(width 0.10795)
		(layer "F.Cu")
		(net "SMB_DDR_GHJ_VPP_SCL_R")
	)
	(segment
		(start 166.29126 2.99974)
		(end 166.29126 3.79222)
		(width 0.10795)
		(layer "F.Cu")
		(net "SMB_DDR_GHJ_VPP_SCL_R")
	)
	(segment
		(start 166.624 2.667)
		(end 166.29126 2.99974)
		(width 0.10795)
		(layer "F.Cu")
		(net "SMB_DDR_GHJ_VPP_SCL_R")
	)
	(segment
		(start 167.600122 3.057144)
		(end 167.600122 2.881122)
		(width 0.10795)
		(layer "F.Cu")
		(net "SMB_DDR_GHJ_VPP_SCL_R")
	)
	(segment
		(start 167.575738 3.081528)
		(end 167.600122 3.057144)
		(width 0.10795)
		(layer "F.Cu")
		(net "SMB_DDR_GHJ_VPP_SCL_R")
	)
	(via
		(at 167.575738 3.081528)
		(size 0.508)
		(drill 0.254)
		(layers "F.Cu" "B.Cu")
		(net "SMB_DDR_GHJ_VPP_SCL_R")
	)
	(segment
		(start 166.4462 3.2512)
		(end 166.751 3.556)
		(width 0.10795)
		(layer "B.Cu")
		(net "SMB_DDR_GHJ_VPP_SCL_R")
	)
	(segment
		(start 166.68877 2.209546)
		(end 166.68877 2.444242)
		(width 0.10795)
		(layer "B.Cu")
		(net "SMB_DDR_GHJ_VPP_SCL_R")
	)
	(segment
		(start 167.326056 3.081528)
		(end 167.575738 3.081528)
		(width 0.10795)
		(layer "B.Cu")
		(net "SMB_DDR_GHJ_VPP_SCL_R")
	)
	(segment
		(start 166.68877 2.444242)
		(end 167.326056 3.081528)
		(width 0.10795)
		(layer "B.Cu")
		(net "SMB_DDR_GHJ_VPP_SCL_R")
	)
	(segment
		(start 166.4462 2.452116)
		(end 166.4462 3.2512)
		(width 0.10795)
		(layer "B.Cu")
		(net "SMB_DDR_GHJ_VPP_SCL_R")
	)
	(segment
		(start 166.68877 2.209546)
		(end 166.4462 2.452116)
		(width 0.10795)
		(layer "B.Cu")
		(net "SMB_DDR_GHJ_VPP_SCL_R")
	)
	(segment
		(start 153.79954 3.778758)
		(end 153.79954 2.514854)
		(width 0.10795)
		(layer "F.Cu")
		(net "SMB_DDR_GHJ_VPP_SCL")
	)
	(segment
		(start 153.79954 -15.423642)
		(end 153.79954 -16.687546)
		(width 0.10795)
		(layer "F.Cu")
		(net "SMB_DDR_GHJ_VPP_SCL")
	)
	(segment
		(start 153.79954 -5.822442)
		(end 153.79954 -7.086346)
		(width 0.10795)
		(layer "F.Cu")
		(net "SMB_DDR_GHJ_VPP_SCL")
	)
	(via
		(at 164.4396 1.7526)
		(size 0.508)
		(drill 0.254)
		(layers "F.Cu" "B.Cu")
		(net "SMB_DDR_GHJ_VPP_SCL")
	)
	(via
		(at 153.79954 -7.086346)
		(size 0.508)
		(drill 0.254)
		(layers "F.Cu" "B.Cu")
		(net "SMB_DDR_GHJ_VPP_SCL")
	)
	(via
		(at 153.79954 -13.918946)
		(size 0.508)
		(drill 0.254)
		(layers "F.Cu" "B.Cu")
		(net "SMB_DDR_GHJ_VPP_SCL")
	)
	(via
		(at 153.79954 2.514854)
		(size 0.508)
		(drill 0.254)
		(layers "F.Cu" "B.Cu")
		(net "SMB_DDR_GHJ_VPP_SCL")
	)
	(via
		(at 153.79954 -23.520146)
		(size 0.508)
		(drill 0.254)
		(layers "F.Cu" "B.Cu")
		(net "SMB_DDR_GHJ_VPP_SCL")
	)
	(via
		(at 153.79954 -16.687546)
		(size 0.508)
		(drill 0.254)
		(layers "F.Cu" "B.Cu")
		(net "SMB_DDR_GHJ_VPP_SCL")
	)
	(via
		(at 153.79954 -4.317746)
		(size 0.508)
		(drill 0.254)
		(layers "F.Cu" "B.Cu")
		(net "SMB_DDR_GHJ_VPP_SCL")
	)
	(segment
		(start 153.79954 -5.621782)
		(end 153.79954 -4.317746)
		(width 0.10795)
		(layer "B.Cu")
		(net "SMB_DDR_GHJ_VPP_SCL")
	)
	(segment
		(start 167.57777 1.911858)
		(end 167.57777 2.209546)
		(width 0.10795)
		(layer "B.Cu")
		(net "SMB_DDR_GHJ_VPP_SCL")
	)
	(segment
		(start 167.418512 1.7526)
		(end 167.57777 1.911858)
		(width 0.10795)
		(layer "B.Cu")
		(net "SMB_DDR_GHJ_VPP_SCL")
	)
	(segment
		(start 153.79954 -15.222982)
		(end 153.79954 -13.918946)
		(width 0.10795)
		(layer "B.Cu")
		(net "SMB_DDR_GHJ_VPP_SCL")
	)
	(segment
		(start 164.4396 1.7526)
		(end 167.418512 1.7526)
		(width 0.10795)
		(layer "B.Cu")
		(net "SMB_DDR_GHJ_VPP_SCL")
	)
	(segment
		(start 153.79954 -23.520146)
		(end 153.79954 -24.824182)
		(width 0.10795)
		(layer "B.Cu")
		(net "SMB_DDR_GHJ_VPP_SCL")
	)
	(segment
		(start 158.5722 -0.3556)
		(end 156.4894 1.7272)
		(width 0.089408)
		(layer "In2.Cu")
		(net "SMB_DDR_GHJ_VPP_SCL")
	)
	(segment
		(start 153.37917 2.094484)
		(end 153.37917 -3.897376)
		(width 0.089408)
		(layer "In2.Cu")
		(net "SMB_DDR_GHJ_VPP_SCL")
	)
	(segment
		(start 154.5336 1.7272)
		(end 153.79954 2.46126)
		(width 0.089408)
		(layer "In2.Cu")
		(net "SMB_DDR_GHJ_VPP_SCL")
	)
	(segment
		(start 153.79954 2.514854)
		(end 153.37917 2.094484)
		(width 0.089408)
		(layer "In2.Cu")
		(net "SMB_DDR_GHJ_VPP_SCL")
	)
	(segment
		(start 153.37917 -17.107916)
		(end 153.37917 -23.099776)
		(width 0.089408)
		(layer "In2.Cu")
		(net "SMB_DDR_GHJ_VPP_SCL")
	)
	(segment
		(start 164.3634 1.6764)
		(end 164.3634 1.4478)
		(width 0.089408)
		(layer "In2.Cu")
		(net "SMB_DDR_GHJ_VPP_SCL")
	)
	(segment
		(start 153.37917 -13.498576)
		(end 153.79954 -13.918946)
		(width 0.089408)
		(layer "In2.Cu")
		(net "SMB_DDR_GHJ_VPP_SCL")
	)
	(segment
		(start 156.4894 1.7272)
		(end 154.5336 1.7272)
		(width 0.089408)
		(layer "In2.Cu")
		(net "SMB_DDR_GHJ_VPP_SCL")
	)
	(segment
		(start 153.37917 -23.099776)
		(end 153.79954 -23.520146)
		(width 0.089408)
		(layer "In2.Cu")
		(net "SMB_DDR_GHJ_VPP_SCL")
	)
	(segment
		(start 153.79954 -13.918946)
		(end 153.79954 -16.687546)
		(width 0.089408)
		(layer "In2.Cu")
		(net "SMB_DDR_GHJ_VPP_SCL")
	)
	(segment
		(start 164.4396 1.7526)
		(end 164.3634 1.6764)
		(width 0.089408)
		(layer "In2.Cu")
		(net "SMB_DDR_GHJ_VPP_SCL")
	)
	(segment
		(start 153.37917 -7.506716)
		(end 153.37917 -13.498576)
		(width 0.089408)
		(layer "In2.Cu")
		(net "SMB_DDR_GHJ_VPP_SCL")
	)
	(segment
		(start 162.56 -0.3556)
		(end 158.5722 -0.3556)
		(width 0.089408)
		(layer "In2.Cu")
		(net "SMB_DDR_GHJ_VPP_SCL")
	)
	(segment
		(start 153.79954 -4.317746)
		(end 153.79954 -7.086346)
		(width 0.089408)
		(layer "In2.Cu")
		(net "SMB_DDR_GHJ_VPP_SCL")
	)
	(segment
		(start 153.79954 -7.086346)
		(end 153.37917 -7.506716)
		(width 0.089408)
		(layer "In2.Cu")
		(net "SMB_DDR_GHJ_VPP_SCL")
	)
	(segment
		(start 153.79954 -16.687546)
		(end 153.37917 -17.107916)
		(width 0.089408)
		(layer "In2.Cu")
		(net "SMB_DDR_GHJ_VPP_SCL")
	)
	(segment
		(start 164.3634 1.4478)
		(end 162.56 -0.3556)
		(width 0.089408)
		(layer "In2.Cu")
		(net "SMB_DDR_GHJ_VPP_SCL")
	)
	(segment
		(start 153.37917 -3.897376)
		(end 153.79954 -4.317746)
		(width 0.089408)
		(layer "In2.Cu")
		(net "SMB_DDR_GHJ_VPP_SCL")
	)
	(segment
		(start 153.79954 2.46126)
		(end 153.79954 2.514854)
		(width 0.089408)
		(layer "In2.Cu")
		(net "SMB_DDR_GHJ_VPP_SCL")
	)
	(segment
		(start 165.36035 -7.825232)
		(end 165.466268 -7.93115)
		(width 0.10795)
		(layer "F.Cu")
		(net "SMB_DDR_GHJ_SDA_G")
	)
	(segment
		(start 165.341554 0.841502)
		(end 164.30371 0.841502)
		(width 0.10795)
		(layer "F.Cu")
		(net "SMB_DDR_GHJ_SDA_G")
	)
	(segment
		(start 165.64102 0.542036)
		(end 165.341554 0.841502)
		(width 0.10795)
		(layer "F.Cu")
		(net "SMB_DDR_GHJ_SDA_G")
	)
	(segment
		(start 165.36035 -7.088886)
		(end 165.36035 -7.825232)
		(width 0.10795)
		(layer "F.Cu")
		(net "SMB_DDR_GHJ_SDA_G")
	)
	(segment
		(start 163.946586 -0.934974)
		(end 164.2872 -1.275588)
		(width 0.10795)
		(layer "F.Cu")
		(net "SMB_DDR_GHJ_SDA_G")
	)
	(segment
		(start 165.64102 -0.77978)
		(end 165.64102 0.542036)
		(width 0.10795)
		(layer "F.Cu")
		(net "SMB_DDR_GHJ_SDA_G")
	)
	(segment
		(start 163.946586 0.484378)
		(end 163.946586 -0.934974)
		(width 0.10795)
		(layer "F.Cu")
		(net "SMB_DDR_GHJ_SDA_G")
	)
	(segment
		(start 164.2872 -6.015736)
		(end 165.36035 -7.088886)
		(width 0.10795)
		(layer "F.Cu")
		(net "SMB_DDR_GHJ_SDA_G")
	)
	(segment
		(start 164.2872 -1.275588)
		(end 164.2872 -6.015736)
		(width 0.10795)
		(layer "F.Cu")
		(net "SMB_DDR_GHJ_SDA_G")
	)
	(segment
		(start 164.30371 0.841502)
		(end 163.946586 0.484378)
		(width 0.10795)
		(layer "F.Cu")
		(net "SMB_DDR_GHJ_SDA_G")
	)
	(via
		(at 169.6466 -21.3614)
		(size 0.6604)
		(drill 0.3302)
		(layers "F.Cu" "B.Cu")
		(net "SMB_DDR_GHJ_SDA_G")
	)
	(via
		(at 165.466268 -7.93115)
		(size 0.508)
		(drill 0.254)
		(layers "F.Cu" "B.Cu")
		(net "SMB_DDR_GHJ_SDA_G")
	)
	(via
		(at 168.775634 -21.859494)
		(size 0.508)
		(drill 0.254)
		(layers "F.Cu" "B.Cu")
		(net "SMB_DDR_GHJ_SDA_G")
	)
	(segment
		(start 168.881552 -22.558248)
		(end 169.6466 -21.7932)
		(width 0.10795)
		(layer "B.Cu")
		(net "SMB_DDR_GHJ_SDA_G")
	)
	(segment
		(start 169.6466 -21.3614)
		(end 169.273728 -21.3614)
		(width 0.10795)
		(layer "B.Cu")
		(net "SMB_DDR_GHJ_SDA_G")
	)
	(segment
		(start 169.6466 -21.7932)
		(end 169.6466 -21.3614)
		(width 0.10795)
		(layer "B.Cu")
		(net "SMB_DDR_GHJ_SDA_G")
	)
	(segment
		(start 169.273728 -21.3614)
		(end 168.775634 -21.859494)
		(width 0.10795)
		(layer "B.Cu")
		(net "SMB_DDR_GHJ_SDA_G")
	)
	(segment
		(start 168.881552 -22.654006)
		(end 168.881552 -22.558248)
		(width 0.10795)
		(layer "B.Cu")
		(net "SMB_DDR_GHJ_SDA_G")
	)
	(segment
		(start 168.881552 -22.654006)
		(end 168.881552 -23.562564)
		(width 0.10795)
		(layer "B.Cu")
		(net "SMB_DDR_GHJ_SDA_G")
	)
	(segment
		(start 164.69487 -11.681206)
		(end 164.69487 -19.76247)
		(width 0.089408)
		(layer "In11.Cu")
		(net "SMB_DDR_GHJ_SDA_G")
	)
	(segment
		(start 165.265608 -11.093704)
		(end 165.227 -11.132312)
		(width 0.089408)
		(layer "In11.Cu")
		(net "SMB_DDR_GHJ_SDA_G")
	)
	(segment
		(start 166.791894 -21.859494)
		(end 168.775634 -21.859494)
		(width 0.089408)
		(layer "In11.Cu")
		(net "SMB_DDR_GHJ_SDA_G")
	)
	(segment
		(start 165.466268 -7.93115)
		(end 165.265608 -8.13181)
		(width 0.089408)
		(layer "In11.Cu")
		(net "SMB_DDR_GHJ_SDA_G")
	)
	(segment
		(start 165.227 -11.132312)
		(end 165.227 -11.149076)
		(width 0.089408)
		(layer "In11.Cu")
		(net "SMB_DDR_GHJ_SDA_G")
	)
	(segment
		(start 165.227 -11.149076)
		(end 164.69487 -11.681206)
		(width 0.089408)
		(layer "In11.Cu")
		(net "SMB_DDR_GHJ_SDA_G")
	)
	(segment
		(start 165.265608 -8.13181)
		(end 165.265608 -11.093704)
		(width 0.089408)
		(layer "In11.Cu")
		(net "SMB_DDR_GHJ_SDA_G")
	)
	(segment
		(start 164.69487 -19.76247)
		(end 166.791894 -21.859494)
		(width 0.089408)
		(layer "In11.Cu")
		(net "SMB_DDR_GHJ_SDA_G")
	)
	(segment
		(start 164.9984 -7.75335)
		(end 164.9984 -7.239)
		(width 0.10795)
		(layer "F.Cu")
		(net "SMB_DDR_GHJ_SCL_G")
	)
	(segment
		(start 166.29126 0.65405)
		(end 166.29126 -0.77978)
		(width 0.10795)
		(layer "F.Cu")
		(net "SMB_DDR_GHJ_SCL_G")
	)
	(segment
		(start 164.812218 -7.939532)
		(end 164.9984 -7.75335)
		(width 0.10795)
		(layer "F.Cu")
		(net "SMB_DDR_GHJ_SCL_G")
	)
	(segment
		(start 163.565586 -1.087374)
		(end 163.565586 0.615442)
		(width 0.10795)
		(layer "F.Cu")
		(net "SMB_DDR_GHJ_SCL_G")
	)
	(segment
		(start 165.732968 1.212342)
		(end 166.29126 0.65405)
		(width 0.10795)
		(layer "F.Cu")
		(net "SMB_DDR_GHJ_SCL_G")
	)
	(segment
		(start 164.162486 1.212342)
		(end 165.732968 1.212342)
		(width 0.10795)
		(layer "F.Cu")
		(net "SMB_DDR_GHJ_SCL_G")
	)
	(segment
		(start 163.565586 0.615442)
		(end 164.162486 1.212342)
		(width 0.10795)
		(layer "F.Cu")
		(net "SMB_DDR_GHJ_SCL_G")
	)
	(segment
		(start 164.9984 -7.239)
		(end 163.9062 -6.1468)
		(width 0.10795)
		(layer "F.Cu")
		(net "SMB_DDR_GHJ_SCL_G")
	)
	(segment
		(start 163.9062 -6.1468)
		(end 163.9062 -1.427988)
		(width 0.10795)
		(layer "F.Cu")
		(net "SMB_DDR_GHJ_SCL_G")
	)
	(segment
		(start 163.9062 -1.427988)
		(end 163.565586 -1.087374)
		(width 0.10795)
		(layer "F.Cu")
		(net "SMB_DDR_GHJ_SCL_G")
	)
	(via
		(at 164.812218 -7.939532)
		(size 0.508)
		(drill 0.254)
		(layers "F.Cu" "B.Cu")
		(net "SMB_DDR_GHJ_SCL_G")
	)
	(via
		(at 167.7924 -21.5392)
		(size 0.6604)
		(drill 0.3302)
		(layers "F.Cu" "B.Cu")
		(net "SMB_DDR_GHJ_SCL_G")
	)
	(via
		(at 165.790372 -23.845774)
		(size 0.508)
		(drill 0.254)
		(layers "F.Cu" "B.Cu")
		(net "SMB_DDR_GHJ_SCL_G")
	)
	(segment
		(start 167.7924 -21.5392)
		(end 167.1066 -21.5392)
		(width 0.10795)
		(layer "B.Cu")
		(net "SMB_DDR_GHJ_SCL_G")
	)
	(segment
		(start 166.72687 -21.91893)
		(end 166.72687 -22.749764)
		(width 0.10795)
		(layer "B.Cu")
		(net "SMB_DDR_GHJ_SCL_G")
	)
	(segment
		(start 166.727124 -22.750018)
		(end 166.727124 -23.562564)
		(width 0.10795)
		(layer "B.Cu")
		(net "SMB_DDR_GHJ_SCL_G")
	)
	(segment
		(start 167.1066 -21.5392)
		(end 166.72687 -21.91893)
		(width 0.10795)
		(layer "B.Cu")
		(net "SMB_DDR_GHJ_SCL_G")
	)
	(segment
		(start 166.073582 -23.562564)
		(end 165.790372 -23.845774)
		(width 0.10795)
		(layer "B.Cu")
		(net "SMB_DDR_GHJ_SCL_G")
	)
	(segment
		(start 166.727124 -23.562564)
		(end 166.073582 -23.562564)
		(width 0.10795)
		(layer "B.Cu")
		(net "SMB_DDR_GHJ_SCL_G")
	)
	(segment
		(start 166.72687 -22.749764)
		(end 166.727124 -22.750018)
		(width 0.10795)
		(layer "B.Cu")
		(net "SMB_DDR_GHJ_SCL_G")
	)
	(segment
		(start 164.293804 -11.651488)
		(end 164.293804 -19.793204)
		(width 0.089408)
		(layer "In11.Cu")
		(net "SMB_DDR_GHJ_SCL_G")
	)
	(segment
		(start 166.25443 -21.75383)
		(end 166.25443 -23.381716)
		(width 0.089408)
		(layer "In11.Cu")
		(net "SMB_DDR_GHJ_SCL_G")
	)
	(segment
		(start 164.973 -8.100314)
		(end 164.973 -10.972292)
		(width 0.089408)
		(layer "In11.Cu")
		(net "SMB_DDR_GHJ_SCL_G")
	)
	(segment
		(start 166.25443 -23.381716)
		(end 165.790372 -23.845774)
		(width 0.089408)
		(layer "In11.Cu")
		(net "SMB_DDR_GHJ_SCL_G")
	)
	(segment
		(start 164.973 -10.972292)
		(end 164.293804 -11.651488)
		(width 0.089408)
		(layer "In11.Cu")
		(net "SMB_DDR_GHJ_SCL_G")
	)
	(segment
		(start 164.812218 -7.939532)
		(end 164.973 -8.100314)
		(width 0.089408)
		(layer "In11.Cu")
		(net "SMB_DDR_GHJ_SCL_G")
	)
	(segment
		(start 164.293804 -19.793204)
		(end 166.25443 -21.75383)
		(width 0.089408)
		(layer "In11.Cu")
		(net "SMB_DDR_GHJ_SCL_G")
	)
	(via
		(at 318.516 -121.23674)
		(size 0.6604)
		(drill 0.3302)
		(layers "F.Cu" "B.Cu")
		(net "SMB_DDR_DEF_VPP_SDA_R")
	)
	(segment
		(start 317.1952 -121.2342)
		(end 317.1952 -120.828308)
		(width 0.10795)
		(layer "B.Cu")
		(net "SMB_DDR_DEF_VPP_SDA_R")
	)
	(segment
		(start 320.07048 -121.51868)
		(end 319.78854 -121.23674)
		(width 0.10795)
		(layer "B.Cu")
		(net "SMB_DDR_DEF_VPP_SDA_R")
	)
	(segment
		(start 317.1952 -120.828308)
		(end 317.1698 -120.802908)
		(width 0.10795)
		(layer "B.Cu")
		(net "SMB_DDR_DEF_VPP_SDA_R")
	)
	(segment
		(start 317.1698 -120.802908)
		(end 317.1698 -120.3198)
		(width 0.10795)
		(layer "B.Cu")
		(net "SMB_DDR_DEF_VPP_SDA_R")
	)
	(segment
		(start 320.9544 -121.51868)
		(end 320.07048 -121.51868)
		(width 0.10795)
		(layer "B.Cu")
		(net "SMB_DDR_DEF_VPP_SDA_R")
	)
	(segment
		(start 318.516 -121.23674)
		(end 317.19774 -121.23674)
		(width 0.10795)
		(layer "B.Cu")
		(net "SMB_DDR_DEF_VPP_SDA_R")
	)
	(segment
		(start 319.78854 -121.23674)
		(end 318.516 -121.23674)
		(width 0.10795)
		(layer "B.Cu")
		(net "SMB_DDR_DEF_VPP_SDA_R")
	)
	(segment
		(start 317.19774 -121.23674)
		(end 317.1952 -121.2342)
		(width 0.10795)
		(layer "B.Cu")
		(net "SMB_DDR_DEF_VPP_SDA_R")
	)
	(segment
		(start 318.80048 -147.27174)
		(end 318.80048 -146.007836)
		(width 0.10795)
		(layer "F.Cu")
		(net "SMB_DDR_DEF_VPP_SDA")
	)
	(segment
		(start 318.80048 -137.67054)
		(end 318.80048 -136.406636)
		(width 0.10795)
		(layer "F.Cu")
		(net "SMB_DDR_DEF_VPP_SDA")
	)
	(segment
		(start 318.80048 -155.609036)
		(end 318.80048 -156.87294)
		(width 0.10795)
		(layer "F.Cu")
		(net "SMB_DDR_DEF_VPP_SDA")
	)
	(via
		(at 318.80048 -155.609036)
		(size 0.508)
		(drill 0.254)
		(layers "F.Cu" "B.Cu")
		(net "SMB_DDR_DEF_VPP_SDA")
	)
	(via
		(at 317.112396 -124.183902)
		(size 0.508)
		(drill 0.254)
		(layers "F.Cu" "B.Cu")
		(net "SMB_DDR_DEF_VPP_SDA")
	)
	(via
		(at 315.4934 -122.9614)
		(size 0.6604)
		(drill 0.3302)
		(layers "F.Cu" "B.Cu")
		(net "SMB_DDR_DEF_VPP_SDA")
	)
	(via
		(at 318.80048 -136.406636)
		(size 0.508)
		(drill 0.254)
		(layers "F.Cu" "B.Cu")
		(net "SMB_DDR_DEF_VPP_SDA")
	)
	(via
		(at 318.80048 -146.007836)
		(size 0.508)
		(drill 0.254)
		(layers "F.Cu" "B.Cu")
		(net "SMB_DDR_DEF_VPP_SDA")
	)
	(via
		(at 318.80048 -129.580132)
		(size 0.508)
		(drill 0.254)
		(layers "F.Cu" "B.Cu")
		(net "SMB_DDR_DEF_VPP_SDA")
	)
	(segment
		(start 315.4934 -123.824746)
		(end 315.976254 -124.3076)
		(width 0.10795)
		(layer "B.Cu")
		(net "SMB_DDR_DEF_VPP_SDA")
	)
	(segment
		(start 318.80048 -136.406636)
		(end 318.80048 -137.877296)
		(width 0.10795)
		(layer "B.Cu")
		(net "SMB_DDR_DEF_VPP_SDA")
	)
	(segment
		(start 316.026546 -121.2342)
		(end 315.4934 -121.767346)
		(width 0.10795)
		(layer "B.Cu")
		(net "SMB_DDR_DEF_VPP_SDA")
	)
	(segment
		(start 318.80048 -129.580132)
		(end 318.80048 -128.276096)
		(width 0.10795)
		(layer "B.Cu")
		(net "SMB_DDR_DEF_VPP_SDA")
	)
	(segment
		(start 315.4934 -121.767346)
		(end 315.4934 -122.9614)
		(width 0.10795)
		(layer "B.Cu")
		(net "SMB_DDR_DEF_VPP_SDA")
	)
	(segment
		(start 316.988698 -124.3076)
		(end 317.112396 -124.183902)
		(width 0.10795)
		(layer "B.Cu")
		(net "SMB_DDR_DEF_VPP_SDA")
	)
	(segment
		(start 318.80048 -147.478496)
		(end 318.80048 -146.007836)
		(width 0.10795)
		(layer "B.Cu")
		(net "SMB_DDR_DEF_VPP_SDA")
	)
	(segment
		(start 316.3062 -121.2342)
		(end 316.026546 -121.2342)
		(width 0.10795)
		(layer "B.Cu")
		(net "SMB_DDR_DEF_VPP_SDA")
	)
	(segment
		(start 315.4934 -122.9614)
		(end 315.4934 -123.824746)
		(width 0.10795)
		(layer "B.Cu")
		(net "SMB_DDR_DEF_VPP_SDA")
	)
	(segment
		(start 315.976254 -124.3076)
		(end 316.988698 -124.3076)
		(width 0.10795)
		(layer "B.Cu")
		(net "SMB_DDR_DEF_VPP_SDA")
	)
	(segment
		(start 319.200784 -136.006332)
		(end 319.200784 -129.980436)
		(width 0.089408)
		(layer "In2.Cu")
		(net "SMB_DDR_DEF_VPP_SDA")
	)
	(segment
		(start 319.200784 -129.980436)
		(end 318.80048 -129.580132)
		(width 0.089408)
		(layer "In2.Cu")
		(net "SMB_DDR_DEF_VPP_SDA")
	)
	(segment
		(start 319.200784 -145.607532)
		(end 319.200784 -136.80694)
		(width 0.089408)
		(layer "In2.Cu")
		(net "SMB_DDR_DEF_VPP_SDA")
	)
	(segment
		(start 318.80048 -136.406636)
		(end 319.200784 -136.006332)
		(width 0.089408)
		(layer "In2.Cu")
		(net "SMB_DDR_DEF_VPP_SDA")
	)
	(segment
		(start 318.80048 -146.007836)
		(end 319.200784 -145.607532)
		(width 0.089408)
		(layer "In2.Cu")
		(net "SMB_DDR_DEF_VPP_SDA")
	)
	(segment
		(start 319.200784 -136.80694)
		(end 318.80048 -136.406636)
		(width 0.089408)
		(layer "In2.Cu")
		(net "SMB_DDR_DEF_VPP_SDA")
	)
	(segment
		(start 318.80048 -127.88646)
		(end 318.325246 -127.411226)
		(width 0.089408)
		(layer "In4.Cu")
		(net "SMB_DDR_DEF_VPP_SDA")
	)
	(segment
		(start 318.325246 -127.411226)
		(end 318.325246 -126.047246)
		(width 0.089408)
		(layer "In4.Cu")
		(net "SMB_DDR_DEF_VPP_SDA")
	)
	(segment
		(start 317.695326 -125.417326)
		(end 317.695326 -124.528072)
		(width 0.089408)
		(layer "In4.Cu")
		(net "SMB_DDR_DEF_VPP_SDA")
	)
	(segment
		(start 318.80048 -129.580132)
		(end 318.80048 -127.88646)
		(width 0.089408)
		(layer "In4.Cu")
		(net "SMB_DDR_DEF_VPP_SDA")
	)
	(segment
		(start 317.351156 -124.183902)
		(end 317.112396 -124.183902)
		(width 0.089408)
		(layer "In4.Cu")
		(net "SMB_DDR_DEF_VPP_SDA")
	)
	(segment
		(start 317.695326 -124.528072)
		(end 317.351156 -124.183902)
		(width 0.089408)
		(layer "In4.Cu")
		(net "SMB_DDR_DEF_VPP_SDA")
	)
	(segment
		(start 318.325246 -126.047246)
		(end 317.695326 -125.417326)
		(width 0.089408)
		(layer "In4.Cu")
		(net "SMB_DDR_DEF_VPP_SDA")
	)
	(segment
		(start 318.400176 -155.208732)
		(end 318.80048 -155.609036)
		(width 0.089408)
		(layer "In11.Cu")
		(net "SMB_DDR_DEF_VPP_SDA")
	)
	(segment
		(start 318.400176 -146.40814)
		(end 318.400176 -155.208732)
		(width 0.089408)
		(layer "In11.Cu")
		(net "SMB_DDR_DEF_VPP_SDA")
	)
	(segment
		(start 318.80048 -146.007836)
		(end 318.400176 -146.40814)
		(width 0.089408)
		(layer "In11.Cu")
		(net "SMB_DDR_DEF_VPP_SDA")
	)
	(via
		(at 317.373 -122.8852)
		(size 0.6604)
		(drill 0.3302)
		(layers "F.Cu" "B.Cu")
		(net "SMB_DDR_DEF_VPP_SCL_R")
	)
	(segment
		(start 317.93434 -124.78766)
		(end 317.93434 -123.44654)
		(width 0.10795)
		(layer "B.Cu")
		(net "SMB_DDR_DEF_VPP_SCL_R")
	)
	(segment
		(start 319.72758 -122.16892)
		(end 319.60566 -122.047)
		(width 0.10795)
		(layer "B.Cu")
		(net "SMB_DDR_DEF_VPP_SCL_R")
	)
	(segment
		(start 317.373 -122.53214)
		(end 317.373 -122.8852)
		(width 0.10795)
		(layer "B.Cu")
		(net "SMB_DDR_DEF_VPP_SCL_R")
	)
	(segment
		(start 317.72606 -125.42774)
		(end 317.72606 -124.99594)
		(width 0.10795)
		(layer "B.Cu")
		(net "SMB_DDR_DEF_VPP_SCL_R")
	)
	(segment
		(start 317.72606 -125.42774)
		(end 318.61506 -125.42774)
		(width 0.10795)
		(layer "B.Cu")
		(net "SMB_DDR_DEF_VPP_SCL_R")
	)
	(segment
		(start 317.93434 -123.44654)
		(end 317.373 -122.8852)
		(width 0.10795)
		(layer "B.Cu")
		(net "SMB_DDR_DEF_VPP_SCL_R")
	)
	(segment
		(start 317.72606 -124.99594)
		(end 317.93434 -124.78766)
		(width 0.10795)
		(layer "B.Cu")
		(net "SMB_DDR_DEF_VPP_SCL_R")
	)
	(segment
		(start 319.60566 -122.047)
		(end 317.85814 -122.047)
		(width 0.10795)
		(layer "B.Cu")
		(net "SMB_DDR_DEF_VPP_SCL_R")
	)
	(segment
		(start 320.9544 -122.16892)
		(end 319.72758 -122.16892)
		(width 0.10795)
		(layer "B.Cu")
		(net "SMB_DDR_DEF_VPP_SCL_R")
	)
	(segment
		(start 317.85814 -122.047)
		(end 317.373 -122.53214)
		(width 0.10795)
		(layer "B.Cu")
		(net "SMB_DDR_DEF_VPP_SCL_R")
	)
	(segment
		(start 318.80048 -152.273)
		(end 318.80048 -150.7744)
		(width 0.10795)
		(layer "F.Cu")
		(net "SMB_DDR_DEF_VPP_SCL")
	)
	(segment
		(start 318.80048 -133.0706)
		(end 318.80048 -131.572)
		(width 0.10795)
		(layer "F.Cu")
		(net "SMB_DDR_DEF_VPP_SCL")
	)
	(segment
		(start 318.80048 -142.6718)
		(end 318.80048 -141.006576)
		(width 0.10795)
		(layer "F.Cu")
		(net "SMB_DDR_DEF_VPP_SCL")
	)
	(via
		(at 318.80048 -131.572)
		(size 0.508)
		(drill 0.254)
		(layers "F.Cu" "B.Cu")
		(net "SMB_DDR_DEF_VPP_SCL")
	)
	(via
		(at 317.295022 -124.792232)
		(size 0.508)
		(drill 0.254)
		(layers "F.Cu" "B.Cu")
		(net "SMB_DDR_DEF_VPP_SCL")
	)
	(via
		(at 316.5602 -125.73)
		(size 0.6604)
		(drill 0.3302)
		(layers "F.Cu" "B.Cu")
		(net "SMB_DDR_DEF_VPP_SCL")
	)
	(via
		(at 318.80048 -141.006576)
		(size 0.508)
		(drill 0.254)
		(layers "F.Cu" "B.Cu")
		(net "SMB_DDR_DEF_VPP_SCL")
	)
	(via
		(at 318.80048 -150.7744)
		(size 0.508)
		(drill 0.254)
		(layers "F.Cu" "B.Cu")
		(net "SMB_DDR_DEF_VPP_SCL")
	)
	(segment
		(start 318.80048 -132.876036)
		(end 318.80048 -131.572)
		(width 0.10795)
		(layer "B.Cu")
		(net "SMB_DDR_DEF_VPP_SCL")
	)
	(segment
		(start 317.72606 -126.31674)
		(end 317.14694 -126.31674)
		(width 0.10795)
		(layer "B.Cu")
		(net "SMB_DDR_DEF_VPP_SCL")
	)
	(segment
		(start 316.5602 -125.73)
		(end 316.5602 -125.1839)
		(width 0.10795)
		(layer "B.Cu")
		(net "SMB_DDR_DEF_VPP_SCL")
	)
	(segment
		(start 317.14694 -126.31674)
		(end 316.5602 -125.73)
		(width 0.10795)
		(layer "B.Cu")
		(net "SMB_DDR_DEF_VPP_SCL")
	)
	(segment
		(start 318.80048 -142.477236)
		(end 318.80048 -141.006576)
		(width 0.10795)
		(layer "B.Cu")
		(net "SMB_DDR_DEF_VPP_SCL")
	)
	(segment
		(start 316.951868 -124.792232)
		(end 317.295022 -124.792232)
		(width 0.10795)
		(layer "B.Cu")
		(net "SMB_DDR_DEF_VPP_SCL")
	)
	(segment
		(start 316.5602 -125.1839)
		(end 316.951868 -124.792232)
		(width 0.10795)
		(layer "B.Cu")
		(net "SMB_DDR_DEF_VPP_SCL")
	)
	(segment
		(start 318.80048 -152.078436)
		(end 318.80048 -150.7744)
		(width 0.10795)
		(layer "B.Cu")
		(net "SMB_DDR_DEF_VPP_SCL")
	)
	(segment
		(start 318.389 -141.418056)
		(end 318.80048 -141.006576)
		(width 0.089408)
		(layer "In2.Cu")
		(net "SMB_DDR_DEF_VPP_SCL")
	)
	(segment
		(start 318.80048 -150.7744)
		(end 318.389 -150.36292)
		(width 0.089408)
		(layer "In2.Cu")
		(net "SMB_DDR_DEF_VPP_SCL")
	)
	(segment
		(start 318.80048 -141.006576)
		(end 318.389 -140.595096)
		(width 0.089408)
		(layer "In2.Cu")
		(net "SMB_DDR_DEF_VPP_SCL")
	)
	(segment
		(start 318.389 -140.595096)
		(end 318.389 -131.98348)
		(width 0.089408)
		(layer "In2.Cu")
		(net "SMB_DDR_DEF_VPP_SCL")
	)
	(segment
		(start 318.389 -150.36292)
		(end 318.389 -141.418056)
		(width 0.089408)
		(layer "In2.Cu")
		(net "SMB_DDR_DEF_VPP_SCL")
	)
	(segment
		(start 318.389 -131.98348)
		(end 318.80048 -131.572)
		(width 0.089408)
		(layer "In2.Cu")
		(net "SMB_DDR_DEF_VPP_SCL")
	)
	(segment
		(start 318.350138 -129.882138)
		(end 318.350138 -127.850138)
		(width 0.089408)
		(layer "In4.Cu")
		(net "SMB_DDR_DEF_VPP_SCL")
	)
	(segment
		(start 317.295022 -125.652022)
		(end 317.295022 -124.792232)
		(width 0.089408)
		(layer "In4.Cu")
		(net "SMB_DDR_DEF_VPP_SCL")
	)
	(segment
		(start 317.881 -127.381)
		(end 317.881 -126.238)
		(width 0.089408)
		(layer "In4.Cu")
		(net "SMB_DDR_DEF_VPP_SCL")
	)
	(segment
		(start 318.350138 -127.850138)
		(end 317.881 -127.381)
		(width 0.089408)
		(layer "In4.Cu")
		(net "SMB_DDR_DEF_VPP_SCL")
	)
	(segment
		(start 317.881 -126.238)
		(end 317.295022 -125.652022)
		(width 0.089408)
		(layer "In4.Cu")
		(net "SMB_DDR_DEF_VPP_SCL")
	)
	(segment
		(start 318.80048 -131.572)
		(end 318.80048 -130.33248)
		(width 0.089408)
		(layer "In4.Cu")
		(net "SMB_DDR_DEF_VPP_SCL")
	)
	(segment
		(start 318.80048 -130.33248)
		(end 318.350138 -129.882138)
		(width 0.089408)
		(layer "In4.Cu")
		(net "SMB_DDR_DEF_VPP_SCL")
	)
	(segment
		(start 293.51478 -62.838584)
		(end 294.08628 -62.838584)
		(width 0.1016)
		(layer "F.Cu")
		(net "SMB_DDR_DEF_SDA_G_R")
	)
	(via
		(at 294.08628 -62.838584)
		(size 0.508)
		(drill 0.254)
		(layers "F.Cu" "B.Cu")
		(net "SMB_DDR_DEF_SDA_G_R")
	)
	(via
		(at 328.906886 -63.095886)
		(size 0.6604)
		(drill 0.3302)
		(layers "F.Cu" "B.Cu")
		(net "SMB_DDR_DEF_SDA_G_R")
	)
	(via
		(at 338.600796 -54.991)
		(size 0.508)
		(drill 0.254)
		(layers "F.Cu" "B.Cu")
		(net "SMB_DDR_DEF_SDA_G_R")
	)
	(segment
		(start 329.369928 -60.550806)
		(end 328.44105 -61.479684)
		(width 0.10795)
		(layer "B.Cu")
		(net "SMB_DDR_DEF_SDA_G_R")
	)
	(segment
		(start 328.44105 -61.479684)
		(end 328.44105 -62.63005)
		(width 0.10795)
		(layer "B.Cu")
		(net "SMB_DDR_DEF_SDA_G_R")
	)
	(segment
		(start 330.30414 -60.550806)
		(end 329.369928 -60.550806)
		(width 0.10795)
		(layer "B.Cu")
		(net "SMB_DDR_DEF_SDA_G_R")
	)
	(segment
		(start 329.798934 -63.095886)
		(end 330.091288 -63.38824)
		(width 0.10795)
		(layer "B.Cu")
		(net "SMB_DDR_DEF_SDA_G_R")
	)
	(segment
		(start 338.651596 -54.991)
		(end 338.8614 -55.200804)
		(width 0.10795)
		(layer "B.Cu")
		(net "SMB_DDR_DEF_SDA_G_R")
	)
	(segment
		(start 338.8614 -55.200804)
		(end 338.8614 -57.3024)
		(width 0.10795)
		(layer "B.Cu")
		(net "SMB_DDR_DEF_SDA_G_R")
	)
	(segment
		(start 332.863444 -57.991502)
		(end 330.30414 -60.550806)
		(width 0.10795)
		(layer "B.Cu")
		(net "SMB_DDR_DEF_SDA_G_R")
	)
	(segment
		(start 328.906886 -63.095886)
		(end 329.798934 -63.095886)
		(width 0.10795)
		(layer "B.Cu")
		(net "SMB_DDR_DEF_SDA_G_R")
	)
	(segment
		(start 338.8614 -57.3024)
		(end 338.172298 -57.991502)
		(width 0.10795)
		(layer "B.Cu")
		(net "SMB_DDR_DEF_SDA_G_R")
	)
	(segment
		(start 338.172298 -57.991502)
		(end 332.863444 -57.991502)
		(width 0.10795)
		(layer "B.Cu")
		(net "SMB_DDR_DEF_SDA_G_R")
	)
	(segment
		(start 328.44105 -62.63005)
		(end 328.906886 -63.095886)
		(width 0.10795)
		(layer "B.Cu")
		(net "SMB_DDR_DEF_SDA_G_R")
	)
	(segment
		(start 338.600796 -54.991)
		(end 338.651596 -54.991)
		(width 0.10795)
		(layer "B.Cu")
		(net "SMB_DDR_DEF_SDA_G_R")
	)
	(segment
		(start 294.59809 -61.552836)
		(end 294.60444 -61.563504)
		(width 0.0889)
		(layer "In11.Cu")
		(net "SMB_DDR_DEF_SDA_G_R")
	)
	(segment
		(start 302.692816 -54.513734)
		(end 302.66005 -54.513734)
		(width 0.0889)
		(layer "In11.Cu")
		(net "SMB_DDR_DEF_SDA_G_R")
	)
	(segment
		(start 310.780684 -51.676808)
		(end 306.18811 -51.676808)
		(width 0.089408)
		(layer "In11.Cu")
		(net "SMB_DDR_DEF_SDA_G_R")
	)
	(segment
		(start 295.816274 -58.476388)
		(end 295.792144 -58.476388)
		(width 0.0889)
		(layer "In11.Cu")
		(net "SMB_DDR_DEF_SDA_G_R")
	)
	(segment
		(start 311.211722 -52.107846)
		(end 310.780684 -51.676808)
		(width 0.089408)
		(layer "In11.Cu")
		(net "SMB_DDR_DEF_SDA_G_R")
	)
	(segment
		(start 294.59809 -60.562236)
		(end 294.60444 -60.572904)
		(width 0.0889)
		(layer "In11.Cu")
		(net "SMB_DDR_DEF_SDA_G_R")
	)
	(segment
		(start 338.350606 -54.166008)
		(end 323.018658 -54.166008)
		(width 0.089408)
		(layer "In11.Cu")
		(net "SMB_DDR_DEF_SDA_G_R")
	)
	(segment
		(start 304.210212 -53.546248)
		(end 304.16373 -53.591968)
		(width 0.0889)
		(layer "In11.Cu")
		(net "SMB_DDR_DEF_SDA_G_R")
	)
	(segment
		(start 338.600796 -54.991)
		(end 338.810092 -54.781704)
		(width 0.089408)
		(layer "In11.Cu")
		(net "SMB_DDR_DEF_SDA_G_R")
	)
	(segment
		(start 303.5427 -54.018688)
		(end 303.51476 -54.018688)
		(width 0.0889)
		(layer "In11.Cu")
		(net "SMB_DDR_DEF_SDA_G_R")
	)
	(segment
		(start 294.593264 -60.5536)
		(end 294.59809 -60.562236)
		(width 0.0889)
		(layer "In11.Cu")
		(net "SMB_DDR_DEF_SDA_G_R")
	)
	(segment
		(start 323.018658 -54.166008)
		(end 318.315848 -58.868818)
		(width 0.089408)
		(layer "In11.Cu")
		(net "SMB_DDR_DEF_SDA_G_R")
	)
	(segment
		(start 301.830486 -55.009288)
		(end 301.79772 -55.009288)
		(width 0.0889)
		(layer "In11.Cu")
		(net "SMB_DDR_DEF_SDA_G_R")
	)
	(segment
		(start 294.96639 -58.971688)
		(end 294.926766 -58.971688)
		(width 0.0889)
		(layer "In11.Cu")
		(net "SMB_DDR_DEF_SDA_G_R")
	)
	(segment
		(start 304.825654 -53.039264)
		(end 304.75301 -53.039264)
		(width 0.089408)
		(layer "In11.Cu")
		(net "SMB_DDR_DEF_SDA_G_R")
	)
	(segment
		(start 318.315848 -58.868818)
		(end 316.443868 -58.868818)
		(width 0.089408)
		(layer "In11.Cu")
		(net "SMB_DDR_DEF_SDA_G_R")
	)
	(segment
		(start 299.258736 -56.494934)
		(end 299.22597 -56.494934)
		(width 0.0889)
		(layer "In11.Cu")
		(net "SMB_DDR_DEF_SDA_G_R")
	)
	(segment
		(start 306.18811 -51.676808)
		(end 304.825654 -53.039264)
		(width 0.089408)
		(layer "In11.Cu")
		(net "SMB_DDR_DEF_SDA_G_R")
	)
	(segment
		(start 297.541696 -57.485534)
		(end 297.520106 -57.485534)
		(width 0.0889)
		(layer "In11.Cu")
		(net "SMB_DDR_DEF_SDA_G_R")
	)
	(segment
		(start 313.036712 -55.461662)
		(end 313.036712 -53.174138)
		(width 0.089408)
		(layer "In11.Cu")
		(net "SMB_DDR_DEF_SDA_G_R")
	)
	(segment
		(start 338.810092 -54.625494)
		(end 338.350606 -54.166008)
		(width 0.089408)
		(layer "In11.Cu")
		(net "SMB_DDR_DEF_SDA_G_R")
	)
	(segment
		(start 294.593264 -61.5442)
		(end 294.59809 -61.552836)
		(width 0.0889)
		(layer "In11.Cu")
		(net "SMB_DDR_DEF_SDA_G_R")
	)
	(segment
		(start 296.67962 -57.981088)
		(end 296.646854 -57.981088)
		(width 0.0889)
		(layer "In11.Cu")
		(net "SMB_DDR_DEF_SDA_G_R")
	)
	(segment
		(start 313.036712 -53.174138)
		(end 311.97042 -52.107846)
		(width 0.089408)
		(layer "In11.Cu")
		(net "SMB_DDR_DEF_SDA_G_R")
	)
	(segment
		(start 304.244248 -53.546756)
		(end 304.210212 -53.546248)
		(width 0.0889)
		(layer "In11.Cu")
		(net "SMB_DDR_DEF_SDA_G_R")
	)
	(segment
		(start 304.75301 -53.039264)
		(end 304.244248 -53.546756)
		(width 0.0889)
		(layer "In11.Cu")
		(net "SMB_DDR_DEF_SDA_G_R")
	)
	(segment
		(start 297.176952 -57.679844)
		(end 297.17365 -57.685686)
		(width 0.0889)
		(layer "In11.Cu")
		(net "SMB_DDR_DEF_SDA_G_R")
	)
	(segment
		(start 338.810092 -54.781704)
		(end 338.810092 -54.625494)
		(width 0.089408)
		(layer "In11.Cu")
		(net "SMB_DDR_DEF_SDA_G_R")
	)
	(segment
		(start 300.975776 -55.504334)
		(end 300.94301 -55.504334)
		(width 0.0889)
		(layer "In11.Cu")
		(net "SMB_DDR_DEF_SDA_G_R")
	)
	(segment
		(start 300.113446 -55.999888)
		(end 300.08068 -55.999888)
		(width 0.0889)
		(layer "In11.Cu")
		(net "SMB_DDR_DEF_SDA_G_R")
	)
	(segment
		(start 316.443868 -58.868818)
		(end 313.036712 -55.461662)
		(width 0.089408)
		(layer "In11.Cu")
		(net "SMB_DDR_DEF_SDA_G_R")
	)
	(segment
		(start 311.97042 -52.107846)
		(end 311.211722 -52.107846)
		(width 0.089408)
		(layer "In11.Cu")
		(net "SMB_DDR_DEF_SDA_G_R")
	)
	(segment
		(start 298.396406 -56.990488)
		(end 298.36364 -56.990488)
		(width 0.0889)
		(layer "In11.Cu")
		(net "SMB_DDR_DEF_SDA_G_R")
	)
	(arc
		(start 294.59809 -61.152786)
		(mid 294.54462 -61.347849)
		(end 294.593264 -61.5442)
		(width 0.0889)
		(layer "In11.Cu")
		(net "SMB_DDR_DEF_SDA_G_R")
	)
	(arc
		(start 294.515794 -62.253876)
		(mid 294.282907 -62.532912)
		(end 294.08628 -62.838584)
		(width 0.0889)
		(layer "In11.Cu")
		(net "SMB_DDR_DEF_SDA_G_R")
	)
	(arc
		(start 298.36364 -56.990488)
		(mid 298.171998 -57.047654)
		(end 298.031916 -57.190386)
		(width 0.0889)
		(layer "In11.Cu")
		(net "SMB_DDR_DEF_SDA_G_R")
	)
	(arc
		(start 294.926766 -58.971688)
		(mid 294.59385 -59.17914)
		(end 294.59809 -59.571382)
		(width 0.0889)
		(layer "In11.Cu")
		(net "SMB_DDR_DEF_SDA_G_R")
	)
	(arc
		(start 297.520106 -57.485534)
		(mid 297.322945 -57.537493)
		(end 297.176952 -57.679844)
		(width 0.0889)
		(layer "In11.Cu")
		(net "SMB_DDR_DEF_SDA_G_R")
	)
	(arc
		(start 303.183036 -54.218586)
		(mid 302.976032 -54.42945)
		(end 302.692816 -54.513734)
		(width 0.0889)
		(layer "In11.Cu")
		(net "SMB_DDR_DEF_SDA_G_R")
	)
	(arc
		(start 295.792144 -58.476388)
		(mid 295.598294 -58.532738)
		(end 295.45661 -58.67654)
		(width 0.0889)
		(layer "In11.Cu")
		(net "SMB_DDR_DEF_SDA_G_R")
	)
	(arc
		(start 295.45661 -58.67654)
		(mid 295.249606 -58.887404)
		(end 294.96639 -58.971688)
		(width 0.0889)
		(layer "In11.Cu")
		(net "SMB_DDR_DEF_SDA_G_R")
	)
	(arc
		(start 304.16373 -53.591968)
		(mid 304.095184 -53.650689)
		(end 304.041556 -53.723286)
		(width 0.0889)
		(layer "In11.Cu")
		(net "SMB_DDR_DEF_SDA_G_R")
	)
	(arc
		(start 297.17365 -57.685686)
		(mid 296.965042 -57.897618)
		(end 296.67962 -57.981088)
		(width 0.0889)
		(layer "In11.Cu")
		(net "SMB_DDR_DEF_SDA_G_R")
	)
	(arc
		(start 294.59809 -60.162186)
		(mid 294.54462 -60.357249)
		(end 294.593264 -60.5536)
		(width 0.0889)
		(layer "In11.Cu")
		(net "SMB_DDR_DEF_SDA_G_R")
	)
	(arc
		(start 298.031916 -57.190386)
		(mid 297.824912 -57.40125)
		(end 297.541696 -57.485534)
		(width 0.0889)
		(layer "In11.Cu")
		(net "SMB_DDR_DEF_SDA_G_R")
	)
	(arc
		(start 300.607476 -55.704486)
		(mid 300.398868 -55.916418)
		(end 300.113446 -55.999888)
		(width 0.0889)
		(layer "In11.Cu")
		(net "SMB_DDR_DEF_SDA_G_R")
	)
	(arc
		(start 302.66005 -54.513734)
		(mid 302.4662 -54.570084)
		(end 302.324516 -54.713886)
		(width 0.0889)
		(layer "In11.Cu")
		(net "SMB_DDR_DEF_SDA_G_R")
	)
	(arc
		(start 294.60444 -61.563504)
		(mid 294.67245 -61.923091)
		(end 294.515794 -62.253876)
		(width 0.0889)
		(layer "In11.Cu")
		(net "SMB_DDR_DEF_SDA_G_R")
	)
	(arc
		(start 294.60444 -60.572904)
		(mid 294.677238 -60.863667)
		(end 294.59809 -61.152786)
		(width 0.0889)
		(layer "In11.Cu")
		(net "SMB_DDR_DEF_SDA_G_R")
	)
	(arc
		(start 303.51476 -54.018688)
		(mid 303.323118 -54.075854)
		(end 303.183036 -54.218586)
		(width 0.0889)
		(layer "In11.Cu")
		(net "SMB_DDR_DEF_SDA_G_R")
	)
	(arc
		(start 296.31513 -58.180986)
		(mid 296.104417 -58.394065)
		(end 295.816274 -58.476388)
		(width 0.0889)
		(layer "In11.Cu")
		(net "SMB_DDR_DEF_SDA_G_R")
	)
	(arc
		(start 299.748956 -56.199786)
		(mid 299.541952 -56.41065)
		(end 299.258736 -56.494934)
		(width 0.0889)
		(layer "In11.Cu")
		(net "SMB_DDR_DEF_SDA_G_R")
	)
	(arc
		(start 301.465996 -55.209186)
		(mid 301.258992 -55.42005)
		(end 300.975776 -55.504334)
		(width 0.0889)
		(layer "In11.Cu")
		(net "SMB_DDR_DEF_SDA_G_R")
	)
	(arc
		(start 300.94301 -55.504334)
		(mid 300.74916 -55.560684)
		(end 300.607476 -55.704486)
		(width 0.0889)
		(layer "In11.Cu")
		(net "SMB_DDR_DEF_SDA_G_R")
	)
	(arc
		(start 298.890436 -56.695086)
		(mid 298.681828 -56.907018)
		(end 298.396406 -56.990488)
		(width 0.0889)
		(layer "In11.Cu")
		(net "SMB_DDR_DEF_SDA_G_R")
	)
	(arc
		(start 304.041556 -53.723286)
		(mid 303.830843 -53.936365)
		(end 303.5427 -54.018688)
		(width 0.0889)
		(layer "In11.Cu")
		(net "SMB_DDR_DEF_SDA_G_R")
	)
	(arc
		(start 302.324516 -54.713886)
		(mid 302.115908 -54.925818)
		(end 301.830486 -55.009288)
		(width 0.0889)
		(layer "In11.Cu")
		(net "SMB_DDR_DEF_SDA_G_R")
	)
	(arc
		(start 300.08068 -55.999888)
		(mid 299.889038 -56.057054)
		(end 299.748956 -56.199786)
		(width 0.0889)
		(layer "In11.Cu")
		(net "SMB_DDR_DEF_SDA_G_R")
	)
	(arc
		(start 301.79772 -55.009288)
		(mid 301.606078 -55.066454)
		(end 301.465996 -55.209186)
		(width 0.0889)
		(layer "In11.Cu")
		(net "SMB_DDR_DEF_SDA_G_R")
	)
	(arc
		(start 299.22597 -56.494934)
		(mid 299.03212 -56.551284)
		(end 298.890436 -56.695086)
		(width 0.0889)
		(layer "In11.Cu")
		(net "SMB_DDR_DEF_SDA_G_R")
	)
	(arc
		(start 296.646854 -57.981088)
		(mid 296.455212 -58.038254)
		(end 296.31513 -58.180986)
		(width 0.0889)
		(layer "In11.Cu")
		(net "SMB_DDR_DEF_SDA_G_R")
	)
	(arc
		(start 294.59809 -59.571382)
		(mid 294.677221 -59.866784)
		(end 294.59809 -60.162186)
		(width 0.0889)
		(layer "In11.Cu")
		(net "SMB_DDR_DEF_SDA_G_R")
	)
	(via
		(at 327.787 -121.9708)
		(size 0.508)
		(drill 0.254)
		(layers "F.Cu" "B.Cu")
		(net "SMB_DDR_DEF_SDA_G")
	)
	(via
		(at 335.5086 -81.6102)
		(size 0.508)
		(drill 0.254)
		(layers "F.Cu" "B.Cu")
		(net "SMB_DDR_DEF_SDA_G")
	)
	(via
		(at 334.054958 -75.482958)
		(size 0.6604)
		(drill 0.3302)
		(layers "F.Cu" "B.Cu")
		(net "SMB_DDR_DEF_SDA_G")
	)
	(segment
		(start 325.5264 -121.51868)
		(end 326.56018 -121.51868)
		(width 0.10795)
		(layer "B.Cu")
		(net "SMB_DDR_DEF_SDA_G")
	)
	(segment
		(start 327.558654 -122.199146)
		(end 327.787 -121.9708)
		(width 0.10795)
		(layer "B.Cu")
		(net "SMB_DDR_DEF_SDA_G")
	)
	(segment
		(start 333.03845 -68.570602)
		(end 333.4893 -68.119752)
		(width 0.10795)
		(layer "B.Cu")
		(net "SMB_DDR_DEF_SDA_G")
	)
	(segment
		(start 334.054958 -75.482958)
		(end 334.054958 -74.416158)
		(width 0.10795)
		(layer "B.Cu")
		(net "SMB_DDR_DEF_SDA_G")
	)
	(segment
		(start 333.502 -78.0034)
		(end 333.502 -76.57084)
		(width 0.10795)
		(layer "B.Cu")
		(net "SMB_DDR_DEF_SDA_G")
	)
	(segment
		(start 331.67066 -63.094108)
		(end 331.376528 -63.38824)
		(width 0.10795)
		(layer "B.Cu")
		(net "SMB_DDR_DEF_SDA_G")
	)
	(segment
		(start 326.56018 -121.51868)
		(end 327.240646 -122.199146)
		(width 0.10795)
		(layer "B.Cu")
		(net "SMB_DDR_DEF_SDA_G")
	)
	(segment
		(start 333.502 -76.57084)
		(end 334.054958 -76.017882)
		(width 0.10795)
		(layer "B.Cu")
		(net "SMB_DDR_DEF_SDA_G")
	)
	(segment
		(start 333.4893 -64.004698)
		(end 332.57871 -63.094108)
		(width 0.10795)
		(layer "B.Cu")
		(net "SMB_DDR_DEF_SDA_G")
	)
	(segment
		(start 332.57871 -63.094108)
		(end 331.67066 -63.094108)
		(width 0.10795)
		(layer "B.Cu")
		(net "SMB_DDR_DEF_SDA_G")
	)
	(segment
		(start 335.62925 -80.13065)
		(end 333.502 -78.0034)
		(width 0.10795)
		(layer "B.Cu")
		(net "SMB_DDR_DEF_SDA_G")
	)
	(segment
		(start 334.054958 -76.017882)
		(end 334.054958 -75.482958)
		(width 0.10795)
		(layer "B.Cu")
		(net "SMB_DDR_DEF_SDA_G")
	)
	(segment
		(start 335.62925 -81.48955)
		(end 335.62925 -80.13065)
		(width 0.10795)
		(layer "B.Cu")
		(net "SMB_DDR_DEF_SDA_G")
	)
	(segment
		(start 330.980288 -63.38824)
		(end 330.980288 -64.17564)
		(width 0.10795)
		(layer "B.Cu")
		(net "SMB_DDR_DEF_SDA_G")
	)
	(segment
		(start 334.054958 -74.416158)
		(end 333.03845 -73.39965)
		(width 0.10795)
		(layer "B.Cu")
		(net "SMB_DDR_DEF_SDA_G")
	)
	(segment
		(start 333.03845 -73.39965)
		(end 333.03845 -68.570602)
		(width 0.10795)
		(layer "B.Cu")
		(net "SMB_DDR_DEF_SDA_G")
	)
	(segment
		(start 333.4893 -68.119752)
		(end 333.4893 -64.004698)
		(width 0.10795)
		(layer "B.Cu")
		(net "SMB_DDR_DEF_SDA_G")
	)
	(segment
		(start 331.376528 -63.38824)
		(end 330.980288 -63.38824)
		(width 0.10795)
		(layer "B.Cu")
		(net "SMB_DDR_DEF_SDA_G")
	)
	(segment
		(start 335.5086 -81.6102)
		(end 335.62925 -81.48955)
		(width 0.10795)
		(layer "B.Cu")
		(net "SMB_DDR_DEF_SDA_G")
	)
	(segment
		(start 327.240646 -122.199146)
		(end 327.558654 -122.199146)
		(width 0.10795)
		(layer "B.Cu")
		(net "SMB_DDR_DEF_SDA_G")
	)
	(segment
		(start 340.365334 -94.6912)
		(end 340.365334 -99.42068)
		(width 0.089408)
		(layer "In9.Cu")
		(net "SMB_DDR_DEF_SDA_G")
	)
	(segment
		(start 339.767164 -94.09303)
		(end 340.365334 -94.6912)
		(width 0.089408)
		(layer "In9.Cu")
		(net "SMB_DDR_DEF_SDA_G")
	)
	(segment
		(start 339.767164 -93.066616)
		(end 339.767164 -94.09303)
		(width 0.089408)
		(layer "In9.Cu")
		(net "SMB_DDR_DEF_SDA_G")
	)
	(segment
		(start 342.093042 -117.131084)
		(end 342.488266 -117.526308)
		(width 0.089408)
		(layer "In9.Cu")
		(net "SMB_DDR_DEF_SDA_G")
	)
	(segment
		(start 339.821774 -99.96424)
		(end 339.821774 -104.83596)
		(width 0.089408)
		(layer "In9.Cu")
		(net "SMB_DDR_DEF_SDA_G")
	)
	(segment
		(start 342.488266 -117.985032)
		(end 342.294718 -118.17858)
		(width 0.089408)
		(layer "In9.Cu")
		(net "SMB_DDR_DEF_SDA_G")
	)
	(segment
		(start 336.9056 -89.61374)
		(end 336.9056 -90.205052)
		(width 0.089408)
		(layer "In9.Cu")
		(net "SMB_DDR_DEF_SDA_G")
	)
	(segment
		(start 336.9056 -90.205052)
		(end 339.767164 -93.066616)
		(width 0.089408)
		(layer "In9.Cu")
		(net "SMB_DDR_DEF_SDA_G")
	)
	(segment
		(start 342.093042 -107.107228)
		(end 342.093042 -117.131084)
		(width 0.089408)
		(layer "In9.Cu")
		(net "SMB_DDR_DEF_SDA_G")
	)
	(segment
		(start 335.805018 -81.906618)
		(end 335.805018 -88.513158)
		(width 0.089408)
		(layer "In9.Cu")
		(net "SMB_DDR_DEF_SDA_G")
	)
	(segment
		(start 342.294718 -118.17858)
		(end 340.357714 -118.17858)
		(width 0.089408)
		(layer "In9.Cu")
		(net "SMB_DDR_DEF_SDA_G")
	)
	(segment
		(start 327.9013 -122.0851)
		(end 327.787 -121.9708)
		(width 0.089408)
		(layer "In9.Cu")
		(net "SMB_DDR_DEF_SDA_G")
	)
	(segment
		(start 335.805018 -88.513158)
		(end 336.9056 -89.61374)
		(width 0.089408)
		(layer "In9.Cu")
		(net "SMB_DDR_DEF_SDA_G")
	)
	(segment
		(start 342.488266 -117.526308)
		(end 342.488266 -117.985032)
		(width 0.089408)
		(layer "In9.Cu")
		(net "SMB_DDR_DEF_SDA_G")
	)
	(segment
		(start 328.12228 -122.0851)
		(end 327.9013 -122.0851)
		(width 0.089408)
		(layer "In9.Cu")
		(net "SMB_DDR_DEF_SDA_G")
	)
	(segment
		(start 339.821774 -104.83596)
		(end 342.093042 -107.107228)
		(width 0.089408)
		(layer "In9.Cu")
		(net "SMB_DDR_DEF_SDA_G")
	)
	(segment
		(start 336.758788 -121.777506)
		(end 328.429874 -121.777506)
		(width 0.089408)
		(layer "In9.Cu")
		(net "SMB_DDR_DEF_SDA_G")
	)
	(segment
		(start 340.365334 -99.42068)
		(end 339.821774 -99.96424)
		(width 0.089408)
		(layer "In9.Cu")
		(net "SMB_DDR_DEF_SDA_G")
	)
	(segment
		(start 328.429874 -121.777506)
		(end 328.12228 -122.0851)
		(width 0.089408)
		(layer "In9.Cu")
		(net "SMB_DDR_DEF_SDA_G")
	)
	(segment
		(start 335.5086 -81.6102)
		(end 335.805018 -81.906618)
		(width 0.089408)
		(layer "In9.Cu")
		(net "SMB_DDR_DEF_SDA_G")
	)
	(segment
		(start 340.357714 -118.17858)
		(end 336.758788 -121.777506)
		(width 0.089408)
		(layer "In9.Cu")
		(net "SMB_DDR_DEF_SDA_G")
	)
	(segment
		(start 292.65626 -63.334138)
		(end 293.22776 -63.334138)
		(width 0.1016)
		(layer "F.Cu")
		(net "SMB_DDR_DEF_SCL_G_R")
	)
	(via
		(at 339.362796 -54.991)
		(size 0.508)
		(drill 0.254)
		(layers "F.Cu" "B.Cu")
		(net "SMB_DDR_DEF_SCL_G_R")
	)
	(via
		(at 338.9884 -58.0136)
		(size 0.6604)
		(drill 0.3302)
		(layers "F.Cu" "B.Cu")
		(net "SMB_DDR_DEF_SCL_G_R")
	)
	(via
		(at 293.22776 -63.334138)
		(size 0.508)
		(drill 0.254)
		(layers "F.Cu" "B.Cu")
		(net "SMB_DDR_DEF_SCL_G_R")
	)
	(segment
		(start 338.9884 -58.0136)
		(end 338.648548 -58.353452)
		(width 0.10795)
		(layer "B.Cu")
		(net "SMB_DDR_DEF_SCL_G_R")
	)
	(segment
		(start 339.311996 -54.991)
		(end 339.362796 -54.991)
		(width 0.10795)
		(layer "B.Cu")
		(net "SMB_DDR_DEF_SCL_G_R")
	)
	(segment
		(start 339.22335 -57.77865)
		(end 339.22335 -55.079646)
		(width 0.10795)
		(layer "B.Cu")
		(net "SMB_DDR_DEF_SCL_G_R")
	)
	(segment
		(start 328.803 -62.280292)
		(end 329.256644 -62.733936)
		(width 0.10795)
		(layer "B.Cu")
		(net "SMB_DDR_DEF_SCL_G_R")
	)
	(segment
		(start 338.648548 -58.353452)
		(end 333.013558 -58.353452)
		(width 0.10795)
		(layer "B.Cu")
		(net "SMB_DDR_DEF_SCL_G_R")
	)
	(segment
		(start 330.449174 -60.917836)
		(end 329.514962 -60.917836)
		(width 0.10795)
		(layer "B.Cu")
		(net "SMB_DDR_DEF_SCL_G_R")
	)
	(segment
		(start 333.013558 -58.353452)
		(end 330.449174 -60.917836)
		(width 0.10795)
		(layer "B.Cu")
		(net "SMB_DDR_DEF_SCL_G_R")
	)
	(segment
		(start 329.514962 -60.917836)
		(end 328.803 -61.629798)
		(width 0.10795)
		(layer "B.Cu")
		(net "SMB_DDR_DEF_SCL_G_R")
	)
	(segment
		(start 329.83932 -62.733936)
		(end 330.116434 -62.456822)
		(width 0.10795)
		(layer "B.Cu")
		(net "SMB_DDR_DEF_SCL_G_R")
	)
	(segment
		(start 338.9884 -58.0136)
		(end 339.22335 -57.77865)
		(width 0.10795)
		(layer "B.Cu")
		(net "SMB_DDR_DEF_SCL_G_R")
	)
	(segment
		(start 329.256644 -62.733936)
		(end 329.83932 -62.733936)
		(width 0.10795)
		(layer "B.Cu")
		(net "SMB_DDR_DEF_SCL_G_R")
	)
	(segment
		(start 339.22335 -55.079646)
		(end 339.311996 -54.991)
		(width 0.10795)
		(layer "B.Cu")
		(net "SMB_DDR_DEF_SCL_G_R")
	)
	(segment
		(start 328.803 -61.629798)
		(end 328.803 -62.280292)
		(width 0.10795)
		(layer "B.Cu")
		(net "SMB_DDR_DEF_SCL_G_R")
	)
	(segment
		(start 339.1027 -54.504082)
		(end 338.472018 -53.8734)
		(width 0.089408)
		(layer "In11.Cu")
		(net "SMB_DDR_DEF_SCL_G_R")
	)
	(segment
		(start 306.066698 -51.3842)
		(end 304.277522 -53.173376)
		(width 0.089408)
		(layer "In11.Cu")
		(net "SMB_DDR_DEF_SCL_G_R")
	)
	(segment
		(start 310.902096 -51.3842)
		(end 306.066698 -51.3842)
		(width 0.089408)
		(layer "In11.Cu")
		(net "SMB_DDR_DEF_SCL_G_R")
	)
	(segment
		(start 301.823882 -54.818788)
		(end 301.791116 -54.818788)
		(width 0.0889)
		(layer "In11.Cu")
		(net "SMB_DDR_DEF_SCL_G_R")
	)
	(segment
		(start 338.472018 -53.8734)
		(end 322.897246 -53.8734)
		(width 0.089408)
		(layer "In11.Cu")
		(net "SMB_DDR_DEF_SCL_G_R")
	)
	(segment
		(start 294.43299 -60.657486)
		(end 294.437816 -60.666122)
		(width 0.0889)
		(layer "In11.Cu")
		(net "SMB_DDR_DEF_SCL_G_R")
	)
	(segment
		(start 311.333134 -51.815238)
		(end 310.902096 -51.3842)
		(width 0.089408)
		(layer "In11.Cu")
		(net "SMB_DDR_DEF_SCL_G_R")
	)
	(segment
		(start 295.818306 -58.285634)
		(end 295.790366 -58.285634)
		(width 0.0889)
		(layer "In11.Cu")
		(net "SMB_DDR_DEF_SCL_G_R")
	)
	(segment
		(start 322.897246 -53.8734)
		(end 318.274446 -58.4962)
		(width 0.089408)
		(layer "In11.Cu")
		(net "SMB_DDR_DEF_SCL_G_R")
	)
	(segment
		(start 304.07483 -53.374544)
		(end 304.074576 -53.40858)
		(width 0.0889)
		(layer "In11.Cu")
		(net "SMB_DDR_DEF_SCL_G_R")
	)
	(segment
		(start 297.008296 -57.590436)
		(end 297.004994 -57.596278)
		(width 0.0889)
		(layer "In11.Cu")
		(net "SMB_DDR_DEF_SCL_G_R")
	)
	(segment
		(start 316.48527 -58.4962)
		(end 313.32932 -55.34025)
		(width 0.089408)
		(layer "In11.Cu")
		(net "SMB_DDR_DEF_SCL_G_R")
	)
	(segment
		(start 313.32932 -55.34025)
		(end 313.32932 -53.052726)
		(width 0.089408)
		(layer "In11.Cu")
		(net "SMB_DDR_DEF_SCL_G_R")
	)
	(segment
		(start 296.66184 -57.790588)
		(end 296.64025 -57.790588)
		(width 0.0889)
		(layer "In11.Cu")
		(net "SMB_DDR_DEF_SCL_G_R")
	)
	(segment
		(start 339.362796 -54.991)
		(end 339.1027 -54.730904)
		(width 0.089408)
		(layer "In11.Cu")
		(net "SMB_DDR_DEF_SCL_G_R")
	)
	(segment
		(start 304.074576 -53.40858)
		(end 304.028348 -53.4543)
		(width 0.0889)
		(layer "In11.Cu")
		(net "SMB_DDR_DEF_SCL_G_R")
	)
	(segment
		(start 300.969172 -55.313834)
		(end 300.936406 -55.313834)
		(width 0.0889)
		(layer "In11.Cu")
		(net "SMB_DDR_DEF_SCL_G_R")
	)
	(segment
		(start 339.1027 -54.730904)
		(end 339.1027 -54.504082)
		(width 0.089408)
		(layer "In11.Cu")
		(net "SMB_DDR_DEF_SCL_G_R")
	)
	(segment
		(start 312.091832 -51.815238)
		(end 311.333134 -51.815238)
		(width 0.089408)
		(layer "In11.Cu")
		(net "SMB_DDR_DEF_SCL_G_R")
	)
	(segment
		(start 294.42664 -61.637418)
		(end 294.43299 -61.648086)
		(width 0.0889)
		(layer "In11.Cu")
		(net "SMB_DDR_DEF_SCL_G_R")
	)
	(segment
		(start 318.274446 -58.4962)
		(end 316.48527 -58.4962)
		(width 0.089408)
		(layer "In11.Cu")
		(net "SMB_DDR_DEF_SCL_G_R")
	)
	(segment
		(start 294.43299 -59.666886)
		(end 294.437816 -59.675522)
		(width 0.0889)
		(layer "In11.Cu")
		(net "SMB_DDR_DEF_SCL_G_R")
	)
	(segment
		(start 294.962834 -58.780934)
		(end 294.92702 -58.780934)
		(width 0.0889)
		(layer "In11.Cu")
		(net "SMB_DDR_DEF_SCL_G_R")
	)
	(segment
		(start 313.32932 -53.052726)
		(end 312.091832 -51.815238)
		(width 0.089408)
		(layer "In11.Cu")
		(net "SMB_DDR_DEF_SCL_G_R")
	)
	(segment
		(start 303.540922 -53.827934)
		(end 303.516792 -53.827934)
		(width 0.0889)
		(layer "In11.Cu")
		(net "SMB_DDR_DEF_SCL_G_R")
	)
	(segment
		(start 294.43299 -61.648086)
		(end 294.437816 -61.656722)
		(width 0.0889)
		(layer "In11.Cu")
		(net "SMB_DDR_DEF_SCL_G_R")
	)
	(segment
		(start 297.535092 -57.295034)
		(end 297.502326 -57.295034)
		(width 0.0889)
		(layer "In11.Cu")
		(net "SMB_DDR_DEF_SCL_G_R")
	)
	(segment
		(start 294.42664 -60.646818)
		(end 294.43299 -60.657486)
		(width 0.0889)
		(layer "In11.Cu")
		(net "SMB_DDR_DEF_SCL_G_R")
	)
	(segment
		(start 294.101266 -62.248034)
		(end 294.0685 -62.248034)
		(width 0.0889)
		(layer "In11.Cu")
		(net "SMB_DDR_DEF_SCL_G_R")
	)
	(segment
		(start 299.252132 -56.304434)
		(end 299.219366 -56.304434)
		(width 0.0889)
		(layer "In11.Cu")
		(net "SMB_DDR_DEF_SCL_G_R")
	)
	(segment
		(start 300.106842 -55.809388)
		(end 300.074076 -55.809388)
		(width 0.0889)
		(layer "In11.Cu")
		(net "SMB_DDR_DEF_SCL_G_R")
	)
	(segment
		(start 304.277522 -53.173376)
		(end 304.07483 -53.374544)
		(width 0.0889)
		(layer "In11.Cu")
		(net "SMB_DDR_DEF_SCL_G_R")
	)
	(segment
		(start 302.686212 -54.323234)
		(end 302.653446 -54.323234)
		(width 0.0889)
		(layer "In11.Cu")
		(net "SMB_DDR_DEF_SCL_G_R")
	)
	(segment
		(start 298.389802 -56.799988)
		(end 298.357036 -56.799988)
		(width 0.0889)
		(layer "In11.Cu")
		(net "SMB_DDR_DEF_SCL_G_R")
	)
	(arc
		(start 304.028348 -53.4543)
		(mid 303.943853 -53.533556)
		(end 303.876456 -53.627782)
		(width 0.0889)
		(layer "In11.Cu")
		(net "SMB_DDR_DEF_SCL_G_R")
	)
	(arc
		(start 298.357036 -56.799988)
		(mid 298.073819 -56.884269)
		(end 297.866816 -57.095136)
		(width 0.0889)
		(layer "In11.Cu")
		(net "SMB_DDR_DEF_SCL_G_R")
	)
	(arc
		(start 297.004994 -57.596278)
		(mid 296.859028 -57.738677)
		(end 296.66184 -57.790588)
		(width 0.0889)
		(layer "In11.Cu")
		(net "SMB_DDR_DEF_SCL_G_R")
	)
	(arc
		(start 296.15003 -58.085736)
		(mid 296.009951 -58.228472)
		(end 295.818306 -58.285634)
		(width 0.0889)
		(layer "In11.Cu")
		(net "SMB_DDR_DEF_SCL_G_R")
	)
	(arc
		(start 299.583856 -56.104536)
		(mid 299.443777 -56.247272)
		(end 299.252132 -56.304434)
		(width 0.0889)
		(layer "In11.Cu")
		(net "SMB_DDR_DEF_SCL_G_R")
	)
	(arc
		(start 295.29151 -58.581036)
		(mid 295.152766 -58.723069)
		(end 294.962834 -58.780934)
		(width 0.0889)
		(layer "In11.Cu")
		(net "SMB_DDR_DEF_SCL_G_R")
	)
	(arc
		(start 300.936406 -55.313834)
		(mid 300.650982 -55.397301)
		(end 300.442376 -55.609236)
		(width 0.0889)
		(layer "In11.Cu")
		(net "SMB_DDR_DEF_SCL_G_R")
	)
	(arc
		(start 297.866816 -57.095136)
		(mid 297.726737 -57.237872)
		(end 297.535092 -57.295034)
		(width 0.0889)
		(layer "In11.Cu")
		(net "SMB_DDR_DEF_SCL_G_R")
	)
	(arc
		(start 299.219366 -56.304434)
		(mid 298.933942 -56.387901)
		(end 298.725336 -56.599836)
		(width 0.0889)
		(layer "In11.Cu")
		(net "SMB_DDR_DEF_SCL_G_R")
	)
	(arc
		(start 296.64025 -57.790588)
		(mid 296.357033 -57.874869)
		(end 296.15003 -58.085736)
		(width 0.0889)
		(layer "In11.Cu")
		(net "SMB_DDR_DEF_SCL_G_R")
	)
	(arc
		(start 302.159416 -54.618636)
		(mid 302.017733 -54.76244)
		(end 301.823882 -54.818788)
		(width 0.0889)
		(layer "In11.Cu")
		(net "SMB_DDR_DEF_SCL_G_R")
	)
	(arc
		(start 294.437816 -61.656722)
		(mid 294.434069 -62.045978)
		(end 294.101266 -62.248034)
		(width 0.0889)
		(layer "In11.Cu")
		(net "SMB_DDR_DEF_SCL_G_R")
	)
	(arc
		(start 301.791116 -54.818788)
		(mid 301.507899 -54.903069)
		(end 301.300896 -55.113936)
		(width 0.0889)
		(layer "In11.Cu")
		(net "SMB_DDR_DEF_SCL_G_R")
	)
	(arc
		(start 295.790366 -58.285634)
		(mid 295.502221 -58.367953)
		(end 295.29151 -58.581036)
		(width 0.0889)
		(layer "In11.Cu")
		(net "SMB_DDR_DEF_SCL_G_R")
	)
	(arc
		(start 298.725336 -56.599836)
		(mid 298.583653 -56.74364)
		(end 298.389802 -56.799988)
		(width 0.0889)
		(layer "In11.Cu")
		(net "SMB_DDR_DEF_SCL_G_R")
	)
	(arc
		(start 294.92702 -58.780934)
		(mid 294.428769 -59.083774)
		(end 294.43299 -59.666886)
		(width 0.0889)
		(layer "In11.Cu")
		(net "SMB_DDR_DEF_SCL_G_R")
	)
	(arc
		(start 303.876456 -53.627782)
		(mid 303.734773 -53.771586)
		(end 303.540922 -53.827934)
		(width 0.0889)
		(layer "In11.Cu")
		(net "SMB_DDR_DEF_SCL_G_R")
	)
	(arc
		(start 294.0685 -62.248034)
		(mid 293.738111 -62.361254)
		(end 293.529258 -62.641226)
		(width 0.0889)
		(layer "In11.Cu")
		(net "SMB_DDR_DEF_SCL_G_R")
	)
	(arc
		(start 294.437816 -60.666122)
		(mid 294.486571 -60.862474)
		(end 294.43299 -61.057536)
		(width 0.0889)
		(layer "In11.Cu")
		(net "SMB_DDR_DEF_SCL_G_R")
	)
	(arc
		(start 297.502326 -57.295034)
		(mid 297.216902 -57.378501)
		(end 297.008296 -57.590436)
		(width 0.0889)
		(layer "In11.Cu")
		(net "SMB_DDR_DEF_SCL_G_R")
	)
	(arc
		(start 300.442376 -55.609236)
		(mid 300.300693 -55.75304)
		(end 300.106842 -55.809388)
		(width 0.0889)
		(layer "In11.Cu")
		(net "SMB_DDR_DEF_SCL_G_R")
	)
	(arc
		(start 303.516792 -53.827934)
		(mid 303.228647 -53.910253)
		(end 303.017936 -54.123336)
		(width 0.0889)
		(layer "In11.Cu")
		(net "SMB_DDR_DEF_SCL_G_R")
	)
	(arc
		(start 303.017936 -54.123336)
		(mid 302.877857 -54.266072)
		(end 302.686212 -54.323234)
		(width 0.0889)
		(layer "In11.Cu")
		(net "SMB_DDR_DEF_SCL_G_R")
	)
	(arc
		(start 294.43299 -61.057536)
		(mid 294.353768 -61.346654)
		(end 294.42664 -61.637418)
		(width 0.0889)
		(layer "In11.Cu")
		(net "SMB_DDR_DEF_SCL_G_R")
	)
	(arc
		(start 301.300896 -55.113936)
		(mid 301.160817 -55.256672)
		(end 300.969172 -55.313834)
		(width 0.0889)
		(layer "In11.Cu")
		(net "SMB_DDR_DEF_SCL_G_R")
	)
	(arc
		(start 293.529258 -62.641226)
		(mid 293.390619 -62.992951)
		(end 293.22776 -63.334138)
		(width 0.0889)
		(layer "In11.Cu")
		(net "SMB_DDR_DEF_SCL_G_R")
	)
	(arc
		(start 294.437816 -59.675522)
		(mid 294.486571 -59.871874)
		(end 294.43299 -60.066936)
		(width 0.0889)
		(layer "In11.Cu")
		(net "SMB_DDR_DEF_SCL_G_R")
	)
	(arc
		(start 302.653446 -54.323234)
		(mid 302.368022 -54.406701)
		(end 302.159416 -54.618636)
		(width 0.0889)
		(layer "In11.Cu")
		(net "SMB_DDR_DEF_SCL_G_R")
	)
	(arc
		(start 300.074076 -55.809388)
		(mid 299.790859 -55.893669)
		(end 299.583856 -56.104536)
		(width 0.0889)
		(layer "In11.Cu")
		(net "SMB_DDR_DEF_SCL_G_R")
	)
	(arc
		(start 294.43299 -60.066936)
		(mid 294.353768 -60.356054)
		(end 294.42664 -60.646818)
		(width 0.0889)
		(layer "In11.Cu")
		(net "SMB_DDR_DEF_SCL_G_R")
	)
	(via
		(at 327.787 -122.6058)
		(size 0.508)
		(drill 0.254)
		(layers "F.Cu" "B.Cu")
		(net "SMB_DDR_DEF_SCL_G")
	)
	(via
		(at 334.056482 -73.638918)
		(size 0.6604)
		(drill 0.3302)
		(layers "F.Cu" "B.Cu")
		(net "SMB_DDR_DEF_SCL_G")
	)
	(via
		(at 336.2325 -81.2165)
		(size 0.508)
		(drill 0.254)
		(layers "F.Cu" "B.Cu")
		(net "SMB_DDR_DEF_SCL_G")
	)
	(segment
		(start 331.005434 -62.456822)
		(end 331.005434 -62.019434)
		(width 0.10795)
		(layer "B.Cu")
		(net "SMB_DDR_DEF_SCL_G")
	)
	(segment
		(start 333.4004 -68.720716)
		(end 333.88046 -68.240656)
		(width 0.10795)
		(layer "B.Cu")
		(net "SMB_DDR_DEF_SCL_G")
	)
	(segment
		(start 330.1365 -61.74105)
		(end 330.1365 -61.341)
		(width 0.10795)
		(layer "B.Cu")
		(net "SMB_DDR_DEF_SCL_G")
	)
	(segment
		(start 326.68972 -122.16892)
		(end 327.1266 -122.6058)
		(width 0.10795)
		(layer "B.Cu")
		(net "SMB_DDR_DEF_SCL_G")
	)
	(segment
		(start 335.9912 -80.9752)
		(end 335.9912 -79.883)
		(width 0.10795)
		(layer "B.Cu")
		(net "SMB_DDR_DEF_SCL_G")
	)
	(segment
		(start 334.056482 -73.638918)
		(end 333.4004 -72.982836)
		(width 0.10795)
		(layer "B.Cu")
		(net "SMB_DDR_DEF_SCL_G")
	)
	(segment
		(start 330.24445 -61.849)
		(end 330.1365 -61.74105)
		(width 0.10795)
		(layer "B.Cu")
		(net "SMB_DDR_DEF_SCL_G")
	)
	(segment
		(start 335.9912 -79.883)
		(end 333.883 -77.7748)
		(width 0.10795)
		(layer "B.Cu")
		(net "SMB_DDR_DEF_SCL_G")
	)
	(segment
		(start 331.360018 -62.456822)
		(end 331.005434 -62.456822)
		(width 0.10795)
		(layer "B.Cu")
		(net "SMB_DDR_DEF_SCL_G")
	)
	(segment
		(start 331.005434 -62.019434)
		(end 330.835 -61.849)
		(width 0.10795)
		(layer "B.Cu")
		(net "SMB_DDR_DEF_SCL_G")
	)
	(segment
		(start 333.88046 -68.240656)
		(end 333.88046 -63.883794)
		(width 0.10795)
		(layer "B.Cu")
		(net "SMB_DDR_DEF_SCL_G")
	)
	(segment
		(start 336.2325 -81.2165)
		(end 335.9912 -80.9752)
		(width 0.10795)
		(layer "B.Cu")
		(net "SMB_DDR_DEF_SCL_G")
	)
	(segment
		(start 330.835 -61.849)
		(end 330.24445 -61.849)
		(width 0.10795)
		(layer "B.Cu")
		(net "SMB_DDR_DEF_SCL_G")
	)
	(segment
		(start 327.1266 -122.6058)
		(end 327.787 -122.6058)
		(width 0.10795)
		(layer "B.Cu")
		(net "SMB_DDR_DEF_SCL_G")
	)
	(segment
		(start 334.554576 -74.137012)
		(end 334.056482 -73.638918)
		(width 0.10795)
		(layer "B.Cu")
		(net "SMB_DDR_DEF_SCL_G")
	)
	(segment
		(start 333.88046 -63.883794)
		(end 332.728824 -62.732158)
		(width 0.10795)
		(layer "B.Cu")
		(net "SMB_DDR_DEF_SCL_G")
	)
	(segment
		(start 333.883 -77.7748)
		(end 333.883 -76.720192)
		(width 0.10795)
		(layer "B.Cu")
		(net "SMB_DDR_DEF_SCL_G")
	)
	(segment
		(start 325.5264 -122.16892)
		(end 326.68972 -122.16892)
		(width 0.10795)
		(layer "B.Cu")
		(net "SMB_DDR_DEF_SCL_G")
	)
	(segment
		(start 331.635354 -62.732158)
		(end 331.360018 -62.456822)
		(width 0.10795)
		(layer "B.Cu")
		(net "SMB_DDR_DEF_SCL_G")
	)
	(segment
		(start 332.728824 -62.732158)
		(end 331.635354 -62.732158)
		(width 0.10795)
		(layer "B.Cu")
		(net "SMB_DDR_DEF_SCL_G")
	)
	(segment
		(start 333.4004 -72.982836)
		(end 333.4004 -68.720716)
		(width 0.10795)
		(layer "B.Cu")
		(net "SMB_DDR_DEF_SCL_G")
	)
	(segment
		(start 334.554576 -76.048616)
		(end 334.554576 -74.137012)
		(width 0.10795)
		(layer "B.Cu")
		(net "SMB_DDR_DEF_SCL_G")
	)
	(segment
		(start 333.883 -76.720192)
		(end 334.554576 -76.048616)
		(width 0.10795)
		(layer "B.Cu")
		(net "SMB_DDR_DEF_SCL_G")
	)
	(segment
		(start 342.811608 -118.156482)
		(end 342.811608 -117.369336)
		(width 0.089408)
		(layer "In9.Cu")
		(net "SMB_DDR_DEF_SCL_G")
	)
	(segment
		(start 327.787 -122.6058)
		(end 328.0156 -122.6058)
		(width 0.089408)
		(layer "In9.Cu")
		(net "SMB_DDR_DEF_SCL_G")
	)
	(segment
		(start 337.198208 -89.492328)
		(end 336.097626 -88.391746)
		(width 0.089408)
		(layer "In9.Cu")
		(net "SMB_DDR_DEF_SCL_G")
	)
	(segment
		(start 340.47811 -118.472204)
		(end 342.495886 -118.472204)
		(width 0.089408)
		(layer "In9.Cu")
		(net "SMB_DDR_DEF_SCL_G")
	)
	(segment
		(start 340.075774 -93.870272)
		(end 340.075774 -92.961206)
		(width 0.089408)
		(layer "In9.Cu")
		(net "SMB_DDR_DEF_SCL_G")
	)
	(segment
		(start 336.8802 -122.070114)
		(end 340.47811 -118.472204)
		(width 0.089408)
		(layer "In9.Cu")
		(net "SMB_DDR_DEF_SCL_G")
	)
	(segment
		(start 328.0156 -122.6058)
		(end 328.551286 -122.070114)
		(width 0.089408)
		(layer "In9.Cu")
		(net "SMB_DDR_DEF_SCL_G")
	)
	(segment
		(start 340.075774 -92.961206)
		(end 337.198208 -90.08364)
		(width 0.089408)
		(layer "In9.Cu")
		(net "SMB_DDR_DEF_SCL_G")
	)
	(segment
		(start 340.657942 -94.45244)
		(end 340.075774 -93.870272)
		(width 0.089408)
		(layer "In9.Cu")
		(net "SMB_DDR_DEF_SCL_G")
	)
	(segment
		(start 336.097626 -88.391746)
		(end 336.097626 -82.054954)
		(width 0.089408)
		(layer "In9.Cu")
		(net "SMB_DDR_DEF_SCL_G")
	)
	(segment
		(start 336.2325 -81.92008)
		(end 336.2325 -81.2165)
		(width 0.089408)
		(layer "In9.Cu")
		(net "SMB_DDR_DEF_SCL_G")
	)
	(segment
		(start 342.495886 -118.472204)
		(end 342.811608 -118.156482)
		(width 0.089408)
		(layer "In9.Cu")
		(net "SMB_DDR_DEF_SCL_G")
	)
	(segment
		(start 340.657942 -99.542092)
		(end 340.657942 -94.45244)
		(width 0.089408)
		(layer "In9.Cu")
		(net "SMB_DDR_DEF_SCL_G")
	)
	(segment
		(start 340.114382 -104.575864)
		(end 340.114382 -100.085652)
		(width 0.089408)
		(layer "In9.Cu")
		(net "SMB_DDR_DEF_SCL_G")
	)
	(segment
		(start 328.551286 -122.070114)
		(end 336.8802 -122.070114)
		(width 0.089408)
		(layer "In9.Cu")
		(net "SMB_DDR_DEF_SCL_G")
	)
	(segment
		(start 337.198208 -90.08364)
		(end 337.198208 -89.492328)
		(width 0.089408)
		(layer "In9.Cu")
		(net "SMB_DDR_DEF_SCL_G")
	)
	(segment
		(start 342.38565 -116.943378)
		(end 342.38565 -106.847132)
		(width 0.089408)
		(layer "In9.Cu")
		(net "SMB_DDR_DEF_SCL_G")
	)
	(segment
		(start 342.38565 -106.847132)
		(end 340.114382 -104.575864)
		(width 0.089408)
		(layer "In9.Cu")
		(net "SMB_DDR_DEF_SCL_G")
	)
	(segment
		(start 340.114382 -100.085652)
		(end 340.657942 -99.542092)
		(width 0.089408)
		(layer "In9.Cu")
		(net "SMB_DDR_DEF_SCL_G")
	)
	(segment
		(start 342.811608 -117.369336)
		(end 342.38565 -116.943378)
		(width 0.089408)
		(layer "In9.Cu")
		(net "SMB_DDR_DEF_SCL_G")
	)
	(segment
		(start 336.097626 -82.054954)
		(end 336.2325 -81.92008)
		(width 0.089408)
		(layer "In9.Cu")
		(net "SMB_DDR_DEF_SCL_G")
	)
	(segment
		(start 322.30822 -27.85618)
		(end 322.30822 -26.67762)
		(width 0.10795)
		(layer "F.Cu")
		(net "SMB_DDR_ABC_VPP_SDA_R")
	)
	(segment
		(start 322.30822 -26.67762)
		(end 322.2244 -26.5938)
		(width 0.10795)
		(layer "F.Cu")
		(net "SMB_DDR_ABC_VPP_SDA_R")
	)
	(via
		(at 322.2244 -26.5938)
		(size 0.508)
		(drill 0.254)
		(layers "F.Cu" "B.Cu")
		(net "SMB_DDR_ABC_VPP_SDA_R")
	)
	(segment
		(start 322.0847 -26.7335)
		(end 322.2244 -26.5938)
		(width 0.10795)
		(layer "B.Cu")
		(net "SMB_DDR_ABC_VPP_SDA_R")
	)
	(segment
		(start 322.0847 -27.34818)
		(end 322.0847 -26.7335)
		(width 0.10795)
		(layer "B.Cu")
		(net "SMB_DDR_ABC_VPP_SDA_R")
	)
	(segment
		(start 322.0847 -28.36418)
		(end 322.0847 -27.34818)
		(width 0.10795)
		(layer "B.Cu")
		(net "SMB_DDR_ABC_VPP_SDA_R")
	)
	(segment
		(start 318.799972 -10.422382)
		(end 318.799972 -9.158478)
		(width 0.10795)
		(layer "F.Cu")
		(net "SMB_DDR_ABC_VPP_SDA")
	)
	(segment
		(start 318.80048 -20.023582)
		(end 318.799972 -20.023582)
		(width 0.10795)
		(layer "F.Cu")
		(net "SMB_DDR_ABC_VPP_SDA")
	)
	(segment
		(start 318.80048 -0.821182)
		(end 318.799972 -0.821182)
		(width 0.10795)
		(layer "F.Cu")
		(net "SMB_DDR_ABC_VPP_SDA")
	)
	(segment
		(start 318.80048 -10.422382)
		(end 318.799972 -10.422382)
		(width 0.10795)
		(layer "F.Cu")
		(net "SMB_DDR_ABC_VPP_SDA")
	)
	(segment
		(start 318.799972 -0.821182)
		(end 318.799972 0.442722)
		(width 0.10795)
		(layer "F.Cu")
		(net "SMB_DDR_ABC_VPP_SDA")
	)
	(segment
		(start 318.799972 -20.023582)
		(end 318.799972 -18.759678)
		(width 0.10795)
		(layer "F.Cu")
		(net "SMB_DDR_ABC_VPP_SDA")
	)
	(via
		(at 318.799972 0.442722)
		(size 0.508)
		(drill 0.254)
		(layers "F.Cu" "B.Cu")
		(net "SMB_DDR_ABC_VPP_SDA")
	)
	(via
		(at 318.799972 -18.759678)
		(size 0.508)
		(drill 0.254)
		(layers "F.Cu" "B.Cu")
		(net "SMB_DDR_ABC_VPP_SDA")
	)
	(via
		(at 322.199 -25.9334)
		(size 0.508)
		(drill 0.254)
		(layers "F.Cu" "B.Cu")
		(net "SMB_DDR_ABC_VPP_SDA")
	)
	(via
		(at 318.799972 -11.927078)
		(size 0.508)
		(drill 0.254)
		(layers "F.Cu" "B.Cu")
		(net "SMB_DDR_ABC_VPP_SDA")
	)
	(via
		(at 318.799972 -21.528278)
		(size 0.508)
		(drill 0.254)
		(layers "F.Cu" "B.Cu")
		(net "SMB_DDR_ABC_VPP_SDA")
	)
	(via
		(at 318.799972 -2.325878)
		(size 0.508)
		(drill 0.254)
		(layers "F.Cu" "B.Cu")
		(net "SMB_DDR_ABC_VPP_SDA")
	)
	(via
		(at 318.799972 -9.158478)
		(size 0.508)
		(drill 0.254)
		(layers "F.Cu" "B.Cu")
		(net "SMB_DDR_ABC_VPP_SDA")
	)
	(segment
		(start 321.1957 -26.9113)
		(end 322.1736 -25.9334)
		(width 0.10795)
		(layer "B.Cu")
		(net "SMB_DDR_ABC_VPP_SDA")
	)
	(segment
		(start 318.799972 -20.224242)
		(end 318.799972 -21.528278)
		(width 0.10795)
		(layer "B.Cu")
		(net "SMB_DDR_ABC_VPP_SDA")
	)
	(segment
		(start 318.799972 -10.623042)
		(end 318.799972 -11.927078)
		(width 0.10795)
		(layer "B.Cu")
		(net "SMB_DDR_ABC_VPP_SDA")
	)
	(segment
		(start 318.80048 -1.021842)
		(end 318.799972 -1.021842)
		(width 0.10795)
		(layer "B.Cu")
		(net "SMB_DDR_ABC_VPP_SDA")
	)
	(segment
		(start 318.80048 -10.623042)
		(end 318.799972 -10.623042)
		(width 0.10795)
		(layer "B.Cu")
		(net "SMB_DDR_ABC_VPP_SDA")
	)
	(segment
		(start 321.1957 -27.34818)
		(end 321.1957 -26.9113)
		(width 0.10795)
		(layer "B.Cu")
		(net "SMB_DDR_ABC_VPP_SDA")
	)
	(segment
		(start 318.799972 -1.021842)
		(end 318.799972 -2.325878)
		(width 0.10795)
		(layer "B.Cu")
		(net "SMB_DDR_ABC_VPP_SDA")
	)
	(segment
		(start 318.80048 -20.224242)
		(end 318.799972 -20.224242)
		(width 0.10795)
		(layer "B.Cu")
		(net "SMB_DDR_ABC_VPP_SDA")
	)
	(segment
		(start 322.1736 -25.9334)
		(end 322.199 -25.9334)
		(width 0.10795)
		(layer "B.Cu")
		(net "SMB_DDR_ABC_VPP_SDA")
	)
	(segment
		(start 318.799972 -8.665972)
		(end 318.799972 -9.158478)
		(width 0.089408)
		(layer "In4.Cu")
		(net "SMB_DDR_ABC_VPP_SDA")
	)
	(segment
		(start 318.389 -17.0434)
		(end 318.799972 -17.454372)
		(width 0.089408)
		(layer "In4.Cu")
		(net "SMB_DDR_ABC_VPP_SDA")
	)
	(segment
		(start 318.799972 -11.927078)
		(end 318.389 -12.33805)
		(width 0.089408)
		(layer "In4.Cu")
		(net "SMB_DDR_ABC_VPP_SDA")
	)
	(segment
		(start 318.389 -12.33805)
		(end 318.389 -17.0434)
		(width 0.089408)
		(layer "In4.Cu")
		(net "SMB_DDR_ABC_VPP_SDA")
	)
	(segment
		(start 318.799972 -18.759678)
		(end 318.799972 -21.528278)
		(width 0.089408)
		(layer "In4.Cu")
		(net "SMB_DDR_ABC_VPP_SDA")
	)
	(segment
		(start 318.389 -23.7109)
		(end 319.9003 -25.2222)
		(width 0.089408)
		(layer "In4.Cu")
		(net "SMB_DDR_ABC_VPP_SDA")
	)
	(segment
		(start 318.799972 -9.158478)
		(end 318.799972 -11.927078)
		(width 0.089408)
		(layer "In4.Cu")
		(net "SMB_DDR_ABC_VPP_SDA")
	)
	(segment
		(start 318.799972 -2.325878)
		(end 318.389 -2.73685)
		(width 0.089408)
		(layer "In4.Cu")
		(net "SMB_DDR_ABC_VPP_SDA")
	)
	(segment
		(start 319.9003 -25.2222)
		(end 321.4878 -25.2222)
		(width 0.089408)
		(layer "In4.Cu")
		(net "SMB_DDR_ABC_VPP_SDA")
	)
	(segment
		(start 318.389 -2.73685)
		(end 318.389 -8.255)
		(width 0.089408)
		(layer "In4.Cu")
		(net "SMB_DDR_ABC_VPP_SDA")
	)
	(segment
		(start 321.4878 -25.2222)
		(end 322.199 -25.9334)
		(width 0.089408)
		(layer "In4.Cu")
		(net "SMB_DDR_ABC_VPP_SDA")
	)
	(segment
		(start 318.389 -8.255)
		(end 318.799972 -8.665972)
		(width 0.089408)
		(layer "In4.Cu")
		(net "SMB_DDR_ABC_VPP_SDA")
	)
	(segment
		(start 318.799972 -17.454372)
		(end 318.799972 -18.759678)
		(width 0.089408)
		(layer "In4.Cu")
		(net "SMB_DDR_ABC_VPP_SDA")
	)
	(segment
		(start 318.389 -21.93925)
		(end 318.389 -23.7109)
		(width 0.089408)
		(layer "In4.Cu")
		(net "SMB_DDR_ABC_VPP_SDA")
	)
	(segment
		(start 318.799972 -21.528278)
		(end 318.389 -21.93925)
		(width 0.089408)
		(layer "In4.Cu")
		(net "SMB_DDR_ABC_VPP_SDA")
	)
	(segment
		(start 318.799972 0.442722)
		(end 318.799972 -2.325878)
		(width 0.089408)
		(layer "In11.Cu")
		(net "SMB_DDR_ABC_VPP_SDA")
	)
	(segment
		(start 322.95846 -26.5938)
		(end 322.95846 -27.85618)
		(width 0.10795)
		(layer "F.Cu")
		(net "SMB_DDR_ABC_VPP_SCL_R")
	)
	(via
		(at 322.95846 -26.5938)
		(size 0.508)
		(drill 0.254)
		(layers "F.Cu" "B.Cu")
		(net "SMB_DDR_ABC_VPP_SCL_R")
	)
	(segment
		(start 322.9737 -26.60904)
		(end 322.95846 -26.5938)
		(width 0.10795)
		(layer "B.Cu")
		(net "SMB_DDR_ABC_VPP_SCL_R")
	)
	(segment
		(start 322.9737 -27.411172)
		(end 322.9737 -26.60904)
		(width 0.10795)
		(layer "B.Cu")
		(net "SMB_DDR_ABC_VPP_SCL_R")
	)
	(segment
		(start 322.9737 -28.36418)
		(end 322.9737 -27.411172)
		(width 0.10795)
		(layer "B.Cu")
		(net "SMB_DDR_ABC_VPP_SCL_R")
	)
	(segment
		(start 318.80048 3.778758)
		(end 318.799972 3.778758)
		(width 0.10795)
		(layer "F.Cu")
		(net "SMB_DDR_ABC_VPP_SCL")
	)
	(segment
		(start 318.799972 -15.423642)
		(end 318.799972 -16.687546)
		(width 0.10795)
		(layer "F.Cu")
		(net "SMB_DDR_ABC_VPP_SCL")
	)
	(segment
		(start 318.799972 3.778758)
		(end 318.799972 2.514854)
		(width 0.10795)
		(layer "F.Cu")
		(net "SMB_DDR_ABC_VPP_SCL")
	)
	(segment
		(start 318.80048 -15.423642)
		(end 318.799972 -15.423642)
		(width 0.10795)
		(layer "F.Cu")
		(net "SMB_DDR_ABC_VPP_SCL")
	)
	(segment
		(start 318.80048 -5.822442)
		(end 318.799972 -5.822442)
		(width 0.10795)
		(layer "F.Cu")
		(net "SMB_DDR_ABC_VPP_SCL")
	)
	(segment
		(start 318.799972 -5.822442)
		(end 318.799972 -7.086346)
		(width 0.10795)
		(layer "F.Cu")
		(net "SMB_DDR_ABC_VPP_SCL")
	)
	(via
		(at 318.799972 -4.317746)
		(size 0.508)
		(drill 0.254)
		(layers "F.Cu" "B.Cu")
		(net "SMB_DDR_ABC_VPP_SCL")
	)
	(via
		(at 318.799972 -23.520146)
		(size 0.508)
		(drill 0.254)
		(layers "F.Cu" "B.Cu")
		(net "SMB_DDR_ABC_VPP_SCL")
	)
	(via
		(at 318.799972 2.514854)
		(size 0.508)
		(drill 0.254)
		(layers "F.Cu" "B.Cu")
		(net "SMB_DDR_ABC_VPP_SCL")
	)
	(via
		(at 318.799972 -13.918946)
		(size 0.508)
		(drill 0.254)
		(layers "F.Cu" "B.Cu")
		(net "SMB_DDR_ABC_VPP_SCL")
	)
	(via
		(at 322.961 -25.9334)
		(size 0.508)
		(drill 0.254)
		(layers "F.Cu" "B.Cu")
		(net "SMB_DDR_ABC_VPP_SCL")
	)
	(via
		(at 318.799972 -16.687546)
		(size 0.508)
		(drill 0.254)
		(layers "F.Cu" "B.Cu")
		(net "SMB_DDR_ABC_VPP_SCL")
	)
	(via
		(at 318.799972 -7.086346)
		(size 0.508)
		(drill 0.254)
		(layers "F.Cu" "B.Cu")
		(net "SMB_DDR_ABC_VPP_SCL")
	)
	(segment
		(start 318.799972 -5.621782)
		(end 318.799972 -4.317746)
		(width 0.10795)
		(layer "B.Cu")
		(net "SMB_DDR_ABC_VPP_SCL")
	)
	(segment
		(start 318.80048 -5.621782)
		(end 318.799972 -5.621782)
		(width 0.10795)
		(layer "B.Cu")
		(net "SMB_DDR_ABC_VPP_SCL")
	)
	(segment
		(start 318.799972 -24.824182)
		(end 318.799972 -23.520146)
		(width 0.10795)
		(layer "B.Cu")
		(net "SMB_DDR_ABC_VPP_SCL")
	)
	(segment
		(start 323.8627 -26.6827)
		(end 323.8627 -27.411172)
		(width 0.10795)
		(layer "B.Cu")
		(net "SMB_DDR_ABC_VPP_SCL")
	)
	(segment
		(start 323.1134 -25.9334)
		(end 323.8627 -26.6827)
		(width 0.10795)
		(layer "B.Cu")
		(net "SMB_DDR_ABC_VPP_SCL")
	)
	(segment
		(start 322.961 -25.9334)
		(end 323.1134 -25.9334)
		(width 0.10795)
		(layer "B.Cu")
		(net "SMB_DDR_ABC_VPP_SCL")
	)
	(segment
		(start 318.799972 -15.222982)
		(end 318.799972 -13.918946)
		(width 0.10795)
		(layer "B.Cu")
		(net "SMB_DDR_ABC_VPP_SCL")
	)
	(segment
		(start 318.80048 -15.222982)
		(end 318.799972 -15.222982)
		(width 0.10795)
		(layer "B.Cu")
		(net "SMB_DDR_ABC_VPP_SCL")
	)
	(segment
		(start 318.80048 -24.824182)
		(end 318.799972 -24.824182)
		(width 0.10795)
		(layer "B.Cu")
		(net "SMB_DDR_ABC_VPP_SCL")
	)
	(segment
		(start 318.799972 -13.918946)
		(end 318.799972 -16.687546)
		(width 0.089408)
		(layer "In4.Cu")
		(net "SMB_DDR_ABC_VPP_SCL")
	)
	(segment
		(start 318.799972 -23.707852)
		(end 319.98412 -24.892)
		(width 0.089408)
		(layer "In4.Cu")
		(net "SMB_DDR_ABC_VPP_SCL")
	)
	(segment
		(start 318.799972 -23.007828)
		(end 318.799972 -23.520146)
		(width 0.089408)
		(layer "In4.Cu")
		(net "SMB_DDR_ABC_VPP_SCL")
	)
	(segment
		(start 319.98412 -24.892)
		(end 321.9196 -24.892)
		(width 0.089408)
		(layer "In4.Cu")
		(net "SMB_DDR_ABC_VPP_SCL")
	)
	(segment
		(start 319.2272 -7.513574)
		(end 319.2272 -12.4206)
		(width 0.089408)
		(layer "In4.Cu")
		(net "SMB_DDR_ABC_VPP_SCL")
	)
	(segment
		(start 319.2018 -17.089374)
		(end 319.2018 -22.606)
		(width 0.089408)
		(layer "In4.Cu")
		(net "SMB_DDR_ABC_VPP_SCL")
	)
	(segment
		(start 318.799972 -23.520146)
		(end 318.799972 -23.707852)
		(width 0.089408)
		(layer "In4.Cu")
		(net "SMB_DDR_ABC_VPP_SCL")
	)
	(segment
		(start 321.9196 -24.892)
		(end 322.961 -25.9334)
		(width 0.089408)
		(layer "In4.Cu")
		(net "SMB_DDR_ABC_VPP_SCL")
	)
	(segment
		(start 318.799972 -4.317746)
		(end 318.799972 -7.086346)
		(width 0.089408)
		(layer "In4.Cu")
		(net "SMB_DDR_ABC_VPP_SCL")
	)
	(segment
		(start 318.799972 -16.687546)
		(end 319.2018 -17.089374)
		(width 0.089408)
		(layer "In4.Cu")
		(net "SMB_DDR_ABC_VPP_SCL")
	)
	(segment
		(start 319.2272 -12.4206)
		(end 318.799972 -12.847828)
		(width 0.089408)
		(layer "In4.Cu")
		(net "SMB_DDR_ABC_VPP_SCL")
	)
	(segment
		(start 318.799972 -7.086346)
		(end 319.2272 -7.513574)
		(width 0.089408)
		(layer "In4.Cu")
		(net "SMB_DDR_ABC_VPP_SCL")
	)
	(segment
		(start 319.2018 -22.606)
		(end 318.799972 -23.007828)
		(width 0.089408)
		(layer "In4.Cu")
		(net "SMB_DDR_ABC_VPP_SCL")
	)
	(segment
		(start 318.799972 -12.847828)
		(end 318.799972 -13.918946)
		(width 0.089408)
		(layer "In4.Cu")
		(net "SMB_DDR_ABC_VPP_SCL")
	)
	(segment
		(start 319.2272 -3.0988)
		(end 318.799972 -3.526028)
		(width 0.089408)
		(layer "In11.Cu")
		(net "SMB_DDR_ABC_VPP_SCL")
	)
	(segment
		(start 319.2272 2.087626)
		(end 319.2272 -3.0988)
		(width 0.089408)
		(layer "In11.Cu")
		(net "SMB_DDR_ABC_VPP_SCL")
	)
	(segment
		(start 318.799972 2.514854)
		(end 319.2272 2.087626)
		(width 0.089408)
		(layer "In11.Cu")
		(net "SMB_DDR_ABC_VPP_SCL")
	)
	(segment
		(start 318.799972 -3.526028)
		(end 318.799972 -4.317746)
		(width 0.089408)
		(layer "In11.Cu")
		(net "SMB_DDR_ABC_VPP_SCL")
	)
	(segment
		(start 293.51478 -63.829184)
		(end 294.08628 -63.829184)
		(width 0.1016)
		(layer "F.Cu")
		(net "SMB_DDR_ABC_SDA_G_R")
	)
	(via
		(at 314.96254 -36.767516)
		(size 0.508)
		(drill 0.254)
		(layers "F.Cu" "B.Cu")
		(net "SMB_DDR_ABC_SDA_G_R")
	)
	(via
		(at 294.08628 -63.829184)
		(size 0.508)
		(drill 0.254)
		(layers "F.Cu" "B.Cu")
		(net "SMB_DDR_ABC_SDA_G_R")
	)
	(segment
		(start 316.211966 -32.192214)
		(end 315.585602 -32.818578)
		(width 0.10795)
		(layer "B.Cu")
		(net "SMB_DDR_ABC_SDA_G_R")
	)
	(segment
		(start 314.534042 -35.84448)
		(end 314.534042 -36.20897)
		(width 0.10795)
		(layer "B.Cu")
		(net "SMB_DDR_ABC_SDA_G_R")
	)
	(segment
		(start 314.96254 -36.637468)
		(end 314.96254 -36.767516)
		(width 0.10795)
		(layer "B.Cu")
		(net "SMB_DDR_ABC_SDA_G_R")
	)
	(segment
		(start 315.585602 -32.818578)
		(end 315.585602 -34.79292)
		(width 0.10795)
		(layer "B.Cu")
		(net "SMB_DDR_ABC_SDA_G_R")
	)
	(segment
		(start 316.32779 -32.093408)
		(end 316.228984 -32.192214)
		(width 0.10795)
		(layer "B.Cu")
		(net "SMB_DDR_ABC_SDA_G_R")
	)
	(segment
		(start 320.78168 -32.93618)
		(end 319.536064 -31.690564)
		(width 0.10795)
		(layer "B.Cu")
		(net "SMB_DDR_ABC_SDA_G_R")
	)
	(segment
		(start 316.32779 -32.07639)
		(end 316.32779 -32.093408)
		(width 0.10795)
		(layer "B.Cu")
		(net "SMB_DDR_ABC_SDA_G_R")
	)
	(segment
		(start 321.1957 -32.93618)
		(end 320.78168 -32.93618)
		(width 0.10795)
		(layer "B.Cu")
		(net "SMB_DDR_ABC_SDA_G_R")
	)
	(segment
		(start 319.536064 -31.690564)
		(end 316.713616 -31.690564)
		(width 0.10795)
		(layer "B.Cu")
		(net "SMB_DDR_ABC_SDA_G_R")
	)
	(segment
		(start 316.228984 -32.192214)
		(end 316.211966 -32.192214)
		(width 0.10795)
		(layer "B.Cu")
		(net "SMB_DDR_ABC_SDA_G_R")
	)
	(segment
		(start 316.713616 -31.690564)
		(end 316.32779 -32.07639)
		(width 0.10795)
		(layer "B.Cu")
		(net "SMB_DDR_ABC_SDA_G_R")
	)
	(segment
		(start 315.585602 -34.79292)
		(end 314.534042 -35.84448)
		(width 0.10795)
		(layer "B.Cu")
		(net "SMB_DDR_ABC_SDA_G_R")
	)
	(segment
		(start 314.534042 -36.20897)
		(end 314.96254 -36.637468)
		(width 0.10795)
		(layer "B.Cu")
		(net "SMB_DDR_ABC_SDA_G_R")
	)
	(segment
		(start 298.396406 -55.999888)
		(end 298.36364 -55.999888)
		(width 0.0889)
		(layer "In11.Cu")
		(net "SMB_DDR_ABC_SDA_G_R")
	)
	(segment
		(start 294.96258 -57.981088)
		(end 294.929814 -57.981088)
		(width 0.0889)
		(layer "In11.Cu")
		(net "SMB_DDR_ABC_SDA_G_R")
	)
	(segment
		(start 292.957504 -63.772288)
		(end 293.0144 -63.829184)
		(width 0.0889)
		(layer "In11.Cu")
		(net "SMB_DDR_ABC_SDA_G_R")
	)
	(segment
		(start 302.689006 -53.523388)
		(end 302.653192 -53.523388)
		(width 0.0889)
		(layer "In11.Cu")
		(net "SMB_DDR_ABC_SDA_G_R")
	)
	(segment
		(start 293.0144 -63.829184)
		(end 294.08628 -63.829184)
		(width 0.0889)
		(layer "In11.Cu")
		(net "SMB_DDR_ABC_SDA_G_R")
	)
	(segment
		(start 303.89449 -52.544218)
		(end 303.385728 -53.05171)
		(width 0.0889)
		(layer "In11.Cu")
		(net "SMB_DDR_ABC_SDA_G_R")
	)
	(segment
		(start 303.351692 -53.051202)
		(end 303.30521 -53.096922)
		(width 0.0889)
		(layer "In11.Cu")
		(net "SMB_DDR_ABC_SDA_G_R")
	)
	(segment
		(start 294.099234 -58.476388)
		(end 294.075104 -58.476388)
		(width 0.0889)
		(layer "In11.Cu")
		(net "SMB_DDR_ABC_SDA_G_R")
	)
	(segment
		(start 292.88105 -63.534036)
		(end 292.8874 -63.544704)
		(width 0.0889)
		(layer "In11.Cu")
		(net "SMB_DDR_ABC_SDA_G_R")
	)
	(segment
		(start 293.74592 -60.646818)
		(end 293.73957 -60.657486)
		(width 0.0889)
		(layer "In11.Cu")
		(net "SMB_DDR_ABC_SDA_G_R")
	)
	(segment
		(start 300.975776 -54.513734)
		(end 300.94301 -54.513734)
		(width 0.0889)
		(layer "In11.Cu")
		(net "SMB_DDR_ABC_SDA_G_R")
	)
	(segment
		(start 314.96254 -36.767516)
		(end 314.772294 -36.577524)
		(width 0.0889)
		(layer "In11.Cu")
		(net "SMB_DDR_ABC_SDA_G_R")
	)
	(segment
		(start 292.876224 -63.5254)
		(end 292.88105 -63.534036)
		(width 0.0889)
		(layer "In11.Cu")
		(net "SMB_DDR_ABC_SDA_G_R")
	)
	(segment
		(start 293.73957 -59.076336)
		(end 293.74592 -59.087004)
		(width 0.0889)
		(layer "In11.Cu")
		(net "SMB_DDR_ABC_SDA_G_R")
	)
	(segment
		(start 297.176952 -56.689244)
		(end 297.17365 -56.695086)
		(width 0.0889)
		(layer "In11.Cu")
		(net "SMB_DDR_ABC_SDA_G_R")
	)
	(segment
		(start 303.385728 -53.05171)
		(end 303.351692 -53.051202)
		(width 0.0889)
		(layer "In11.Cu")
		(net "SMB_DDR_ABC_SDA_G_R")
	)
	(segment
		(start 305.435 -45.708316)
		(end 305.435 -49.363122)
		(width 0.089408)
		(layer "In11.Cu")
		(net "SMB_DDR_ABC_SDA_G_R")
	)
	(segment
		(start 305.435 -51.003708)
		(end 303.89449 -52.544218)
		(width 0.0889)
		(layer "In11.Cu")
		(net "SMB_DDR_ABC_SDA_G_R")
	)
	(segment
		(start 292.876224 -62.5348)
		(end 292.88105 -62.543436)
		(width 0.0889)
		(layer "In11.Cu")
		(net "SMB_DDR_ABC_SDA_G_R")
	)
	(segment
		(start 297.541696 -56.494934)
		(end 297.520106 -56.494934)
		(width 0.0889)
		(layer "In11.Cu")
		(net "SMB_DDR_ABC_SDA_G_R")
	)
	(segment
		(start 295.82491 -57.485534)
		(end 295.792144 -57.485534)
		(width 0.0889)
		(layer "In11.Cu")
		(net "SMB_DDR_ABC_SDA_G_R")
	)
	(segment
		(start 305.435 -49.363122)
		(end 305.435 -51.003708)
		(width 0.0889)
		(layer "In11.Cu")
		(net "SMB_DDR_ABC_SDA_G_R")
	)
	(segment
		(start 299.258736 -55.504334)
		(end 299.22597 -55.504334)
		(width 0.0889)
		(layer "In11.Cu")
		(net "SMB_DDR_ABC_SDA_G_R")
	)
	(segment
		(start 314.772294 -36.577524)
		(end 314.565792 -36.577524)
		(width 0.0889)
		(layer "In11.Cu")
		(net "SMB_DDR_ABC_SDA_G_R")
	)
	(segment
		(start 296.67962 -56.990488)
		(end 296.646854 -56.990488)
		(width 0.0889)
		(layer "In11.Cu")
		(net "SMB_DDR_ABC_SDA_G_R")
	)
	(segment
		(start 293.73957 -60.657486)
		(end 293.734744 -60.666122)
		(width 0.0889)
		(layer "In11.Cu")
		(net "SMB_DDR_ABC_SDA_G_R")
	)
	(segment
		(start 301.82566 -54.018688)
		(end 301.79772 -54.018688)
		(width 0.0889)
		(layer "In11.Cu")
		(net "SMB_DDR_ABC_SDA_G_R")
	)
	(segment
		(start 293.73957 -59.666886)
		(end 293.734744 -59.675522)
		(width 0.0889)
		(layer "In11.Cu")
		(net "SMB_DDR_ABC_SDA_G_R")
	)
	(segment
		(start 292.88105 -62.543436)
		(end 292.8874 -62.554104)
		(width 0.0889)
		(layer "In11.Cu")
		(net "SMB_DDR_ABC_SDA_G_R")
	)
	(segment
		(start 300.113446 -55.009288)
		(end 300.08068 -55.009288)
		(width 0.0889)
		(layer "In11.Cu")
		(net "SMB_DDR_ABC_SDA_G_R")
	)
	(segment
		(start 293.24554 -61.943488)
		(end 293.212774 -61.943488)
		(width 0.0889)
		(layer "In11.Cu")
		(net "SMB_DDR_ABC_SDA_G_R")
	)
	(segment
		(start 314.565792 -36.577524)
		(end 305.435 -45.708316)
		(width 0.0889)
		(layer "In11.Cu")
		(net "SMB_DDR_ABC_SDA_G_R")
	)
	(arc
		(start 295.792144 -57.485534)
		(mid 295.598294 -57.541884)
		(end 295.45661 -57.685686)
		(width 0.0889)
		(layer "In11.Cu")
		(net "SMB_DDR_ABC_SDA_G_R")
	)
	(arc
		(start 303.30521 -53.096922)
		(mid 303.285592 -53.111079)
		(end 303.266856 -53.126386)
		(width 0.0889)
		(layer "In11.Cu")
		(net "SMB_DDR_ABC_SDA_G_R")
	)
	(arc
		(start 303.266856 -53.126386)
		(mid 303.25664 -53.135459)
		(end 303.24679 -53.144928)
		(width 0.0889)
		(layer "In11.Cu")
		(net "SMB_DDR_ABC_SDA_G_R")
	)
	(arc
		(start 301.465996 -54.218586)
		(mid 301.258992 -54.42945)
		(end 300.975776 -54.513734)
		(width 0.0889)
		(layer "In11.Cu")
		(net "SMB_DDR_ABC_SDA_G_R")
	)
	(arc
		(start 298.031916 -56.199786)
		(mid 297.824912 -56.41065)
		(end 297.541696 -56.494934)
		(width 0.0889)
		(layer "In11.Cu")
		(net "SMB_DDR_ABC_SDA_G_R")
	)
	(arc
		(start 303.24679 -53.144928)
		(mid 303.212184 -53.184363)
		(end 303.183036 -53.227986)
		(width 0.0889)
		(layer "In11.Cu")
		(net "SMB_DDR_ABC_SDA_G_R")
	)
	(arc
		(start 295.45661 -57.685686)
		(mid 295.248002 -57.897618)
		(end 294.96258 -57.981088)
		(width 0.0889)
		(layer "In11.Cu")
		(net "SMB_DDR_ABC_SDA_G_R")
	)
	(arc
		(start 294.59809 -58.180986)
		(mid 294.387377 -58.394065)
		(end 294.099234 -58.476388)
		(width 0.0889)
		(layer "In11.Cu")
		(net "SMB_DDR_ABC_SDA_G_R")
	)
	(arc
		(start 300.607476 -54.713886)
		(mid 300.398868 -54.925818)
		(end 300.113446 -55.009288)
		(width 0.0889)
		(layer "In11.Cu")
		(net "SMB_DDR_ABC_SDA_G_R")
	)
	(arc
		(start 303.183036 -53.227986)
		(mid 302.974428 -53.439918)
		(end 302.689006 -53.523388)
		(width 0.0889)
		(layer "In11.Cu")
		(net "SMB_DDR_ABC_SDA_G_R")
	)
	(arc
		(start 293.73957 -60.066936)
		(mid 293.818792 -60.356054)
		(end 293.74592 -60.646818)
		(width 0.0889)
		(layer "In11.Cu")
		(net "SMB_DDR_ABC_SDA_G_R")
	)
	(arc
		(start 293.734744 -59.675522)
		(mid 293.685989 -59.871874)
		(end 293.73957 -60.066936)
		(width 0.0889)
		(layer "In11.Cu")
		(net "SMB_DDR_ABC_SDA_G_R")
	)
	(arc
		(start 293.212774 -61.943488)
		(mid 292.879856 -62.145479)
		(end 292.876224 -62.5348)
		(width 0.0889)
		(layer "In11.Cu")
		(net "SMB_DDR_ABC_SDA_G_R")
	)
	(arc
		(start 297.17365 -56.695086)
		(mid 296.965042 -56.907018)
		(end 296.67962 -56.990488)
		(width 0.0889)
		(layer "In11.Cu")
		(net "SMB_DDR_ABC_SDA_G_R")
	)
	(arc
		(start 300.94301 -54.513734)
		(mid 300.74916 -54.570084)
		(end 300.607476 -54.713886)
		(width 0.0889)
		(layer "In11.Cu")
		(net "SMB_DDR_ABC_SDA_G_R")
	)
	(arc
		(start 298.890436 -55.704486)
		(mid 298.681828 -55.916418)
		(end 298.396406 -55.999888)
		(width 0.0889)
		(layer "In11.Cu")
		(net "SMB_DDR_ABC_SDA_G_R")
	)
	(arc
		(start 302.653192 -53.523388)
		(mid 302.463263 -53.581258)
		(end 302.324516 -53.723286)
		(width 0.0889)
		(layer "In11.Cu")
		(net "SMB_DDR_ABC_SDA_G_R")
	)
	(arc
		(start 301.79772 -54.018688)
		(mid 301.606078 -54.075854)
		(end 301.465996 -54.218586)
		(width 0.0889)
		(layer "In11.Cu")
		(net "SMB_DDR_ABC_SDA_G_R")
	)
	(arc
		(start 294.075104 -58.476388)
		(mid 293.736989 -58.68109)
		(end 293.73957 -59.076336)
		(width 0.0889)
		(layer "In11.Cu")
		(net "SMB_DDR_ABC_SDA_G_R")
	)
	(arc
		(start 294.929814 -57.981088)
		(mid 294.738172 -58.038254)
		(end 294.59809 -58.180986)
		(width 0.0889)
		(layer "In11.Cu")
		(net "SMB_DDR_ABC_SDA_G_R")
	)
	(arc
		(start 292.88105 -63.133986)
		(mid 292.82758 -63.329049)
		(end 292.876224 -63.5254)
		(width 0.0889)
		(layer "In11.Cu")
		(net "SMB_DDR_ABC_SDA_G_R")
	)
	(arc
		(start 299.748956 -55.209186)
		(mid 299.541952 -55.42005)
		(end 299.258736 -55.504334)
		(width 0.0889)
		(layer "In11.Cu")
		(net "SMB_DDR_ABC_SDA_G_R")
	)
	(arc
		(start 298.36364 -55.999888)
		(mid 298.171998 -56.057054)
		(end 298.031916 -56.199786)
		(width 0.0889)
		(layer "In11.Cu")
		(net "SMB_DDR_ABC_SDA_G_R")
	)
	(arc
		(start 292.8874 -63.544704)
		(mid 292.934038 -63.654927)
		(end 292.957504 -63.772288)
		(width 0.0889)
		(layer "In11.Cu")
		(net "SMB_DDR_ABC_SDA_G_R")
	)
	(arc
		(start 297.520106 -56.494934)
		(mid 297.322945 -56.546893)
		(end 297.176952 -56.689244)
		(width 0.0889)
		(layer "In11.Cu")
		(net "SMB_DDR_ABC_SDA_G_R")
	)
	(arc
		(start 293.74592 -59.087004)
		(mid 293.818718 -59.377767)
		(end 293.73957 -59.666886)
		(width 0.0889)
		(layer "In11.Cu")
		(net "SMB_DDR_ABC_SDA_G_R")
	)
	(arc
		(start 292.8874 -62.554104)
		(mid 292.960198 -62.844867)
		(end 292.88105 -63.133986)
		(width 0.0889)
		(layer "In11.Cu")
		(net "SMB_DDR_ABC_SDA_G_R")
	)
	(arc
		(start 296.31513 -57.190386)
		(mid 296.108126 -57.40125)
		(end 295.82491 -57.485534)
		(width 0.0889)
		(layer "In11.Cu")
		(net "SMB_DDR_ABC_SDA_G_R")
	)
	(arc
		(start 296.646854 -56.990488)
		(mid 296.455212 -57.047654)
		(end 296.31513 -57.190386)
		(width 0.0889)
		(layer "In11.Cu")
		(net "SMB_DDR_ABC_SDA_G_R")
	)
	(arc
		(start 299.22597 -55.504334)
		(mid 299.03212 -55.560684)
		(end 298.890436 -55.704486)
		(width 0.0889)
		(layer "In11.Cu")
		(net "SMB_DDR_ABC_SDA_G_R")
	)
	(arc
		(start 293.73957 -61.057536)
		(mid 293.743899 -61.640708)
		(end 293.24554 -61.943488)
		(width 0.0889)
		(layer "In11.Cu")
		(net "SMB_DDR_ABC_SDA_G_R")
	)
	(arc
		(start 302.324516 -53.723286)
		(mid 302.113803 -53.936365)
		(end 301.82566 -54.018688)
		(width 0.0889)
		(layer "In11.Cu")
		(net "SMB_DDR_ABC_SDA_G_R")
	)
	(arc
		(start 300.08068 -55.009288)
		(mid 299.889038 -55.066454)
		(end 299.748956 -55.209186)
		(width 0.0889)
		(layer "In11.Cu")
		(net "SMB_DDR_ABC_SDA_G_R")
	)
	(arc
		(start 293.734744 -60.666122)
		(mid 293.685989 -60.862474)
		(end 293.73957 -61.057536)
		(width 0.0889)
		(layer "In11.Cu")
		(net "SMB_DDR_ABC_SDA_G_R")
	)
	(segment
		(start 321.790568 -30.604968)
		(end 320.93916 -30.604968)
		(width 0.10795)
		(layer "F.Cu")
		(net "SMB_DDR_ABC_SDA_G")
	)
	(segment
		(start 320.93916 -30.604968)
		(end 320.062098 -31.48203)
		(width 0.10795)
		(layer "F.Cu")
		(net "SMB_DDR_ABC_SDA_G")
	)
	(segment
		(start 322.3006 -31.115)
		(end 321.790568 -30.604968)
		(width 0.10795)
		(layer "F.Cu")
		(net "SMB_DDR_ABC_SDA_G")
	)
	(segment
		(start 322.30822 -32.42818)
		(end 322.30822 -31.12262)
		(width 0.10795)
		(layer "F.Cu")
		(net "SMB_DDR_ABC_SDA_G")
	)
	(segment
		(start 322.30822 -31.12262)
		(end 322.3006 -31.115)
		(width 0.10795)
		(layer "F.Cu")
		(net "SMB_DDR_ABC_SDA_G")
	)
	(via
		(at 322.3006 -31.115)
		(size 0.508)
		(drill 0.254)
		(layers "F.Cu" "B.Cu")
		(net "SMB_DDR_ABC_SDA_G")
	)
	(via
		(at 320.062098 -31.48203)
		(size 0.762)
		(drill 0.381)
		(layers "F.Cu" "B.Cu")
		(net "SMB_DDR_ABC_SDA_G")
	)
	(segment
		(start 322.3006 -31.12262)
		(end 322.0847 -31.33852)
		(width 0.10795)
		(layer "B.Cu")
		(net "SMB_DDR_ABC_SDA_G")
	)
	(segment
		(start 322.3006 -31.115)
		(end 322.3006 -31.12262)
		(width 0.10795)
		(layer "B.Cu")
		(net "SMB_DDR_ABC_SDA_G")
	)
	(segment
		(start 322.0847 -32.93618)
		(end 322.0847 -31.92018)
		(width 0.10795)
		(layer "B.Cu")
		(net "SMB_DDR_ABC_SDA_G")
	)
	(segment
		(start 322.0847 -31.33852)
		(end 322.0847 -31.92018)
		(width 0.10795)
		(layer "B.Cu")
		(net "SMB_DDR_ABC_SDA_G")
	)
	(segment
		(start 292.65626 -65.315338)
		(end 293.22776 -65.315338)
		(width 0.1016)
		(layer "F.Cu")
		(net "SMB_DDR_ABC_SCL_G_R")
	)
	(via
		(at 319.880234 -32.809434)
		(size 0.6604)
		(drill 0.3302)
		(layers "F.Cu" "B.Cu")
		(net "SMB_DDR_ABC_SCL_G_R")
	)
	(via
		(at 293.22776 -65.315338)
		(size 0.508)
		(drill 0.254)
		(layers "F.Cu" "B.Cu")
		(net "SMB_DDR_ABC_SCL_G_R")
	)
	(via
		(at 314.965588 -36.010342)
		(size 0.508)
		(drill 0.254)
		(layers "F.Cu" "B.Cu")
		(net "SMB_DDR_ABC_SCL_G_R")
	)
	(segment
		(start 323.8627 -32.93618)
		(end 323.8627 -33.3121)
		(width 0.10795)
		(layer "B.Cu")
		(net "SMB_DDR_ABC_SCL_G_R")
	)
	(segment
		(start 323.723 -33.4518)
		(end 320.5226 -33.4518)
		(width 0.10795)
		(layer "B.Cu")
		(net "SMB_DDR_ABC_SCL_G_R")
	)
	(segment
		(start 315.98235 -32.994346)
		(end 315.98235 -34.99358)
		(width 0.10795)
		(layer "B.Cu")
		(net "SMB_DDR_ABC_SCL_G_R")
	)
	(segment
		(start 316.924182 -32.052514)
		(end 315.98235 -32.994346)
		(width 0.10795)
		(layer "B.Cu")
		(net "SMB_DDR_ABC_SCL_G_R")
	)
	(segment
		(start 320.5226 -33.4518)
		(end 319.880234 -32.809434)
		(width 0.10795)
		(layer "B.Cu")
		(net "SMB_DDR_ABC_SCL_G_R")
	)
	(segment
		(start 319.880234 -32.809434)
		(end 319.123314 -32.052514)
		(width 0.10795)
		(layer "B.Cu")
		(net "SMB_DDR_ABC_SCL_G_R")
	)
	(segment
		(start 323.8627 -33.3121)
		(end 323.723 -33.4518)
		(width 0.10795)
		(layer "B.Cu")
		(net "SMB_DDR_ABC_SCL_G_R")
	)
	(segment
		(start 319.123314 -32.052514)
		(end 316.924182 -32.052514)
		(width 0.10795)
		(layer "B.Cu")
		(net "SMB_DDR_ABC_SCL_G_R")
	)
	(segment
		(start 315.98235 -34.99358)
		(end 314.965588 -36.010342)
		(width 0.10795)
		(layer "B.Cu")
		(net "SMB_DDR_ABC_SCL_G_R")
	)
	(segment
		(start 292.7096 -62.628018)
		(end 292.71595 -62.638686)
		(width 0.0889)
		(layer "In11.Cu")
		(net "SMB_DDR_ABC_SCL_G_R")
	)
	(segment
		(start 292.71595 -62.638686)
		(end 292.720776 -62.647322)
		(width 0.0889)
		(layer "In11.Cu")
		(net "SMB_DDR_ABC_SCL_G_R")
	)
	(segment
		(start 314.690506 -36.285424)
		(end 314.38977 -36.285424)
		(width 0.0889)
		(layer "In11.Cu")
		(net "SMB_DDR_ABC_SCL_G_R")
	)
	(segment
		(start 293.162482 -64.911986)
		(end 293.22776 -64.977264)
		(width 0.0889)
		(layer "In11.Cu")
		(net "SMB_DDR_ABC_SCL_G_R")
	)
	(segment
		(start 293.57447 -60.562236)
		(end 293.56812 -60.572904)
		(width 0.0889)
		(layer "In11.Cu")
		(net "SMB_DDR_ABC_SCL_G_R")
	)
	(segment
		(start 303.821846 -52.202842)
		(end 303.216056 -52.808632)
		(width 0.0889)
		(layer "In11.Cu")
		(net "SMB_DDR_ABC_SCL_G_R")
	)
	(segment
		(start 296.66184 -56.799988)
		(end 296.64025 -56.799988)
		(width 0.0889)
		(layer "In11.Cu")
		(net "SMB_DDR_ABC_SCL_G_R")
	)
	(segment
		(start 299.252132 -55.313834)
		(end 299.219366 -55.313834)
		(width 0.0889)
		(layer "In11.Cu")
		(net "SMB_DDR_ABC_SCL_G_R")
	)
	(segment
		(start 297.008296 -56.599836)
		(end 297.004994 -56.605678)
		(width 0.0889)
		(layer "In11.Cu")
		(net "SMB_DDR_ABC_SCL_G_R")
	)
	(segment
		(start 293.22776 -64.977264)
		(end 293.22776 -65.315338)
		(width 0.0889)
		(layer "In11.Cu")
		(net "SMB_DDR_ABC_SCL_G_R")
	)
	(segment
		(start 313.12231 -37.55263)
		(end 305.054 -45.62094)
		(width 0.089408)
		(layer "In11.Cu")
		(net "SMB_DDR_ABC_SCL_G_R")
	)
	(segment
		(start 305.054 -45.62094)
		(end 305.054 -50.970688)
		(width 0.089408)
		(layer "In11.Cu")
		(net "SMB_DDR_ABC_SCL_G_R")
	)
	(segment
		(start 314.38977 -36.285424)
		(end 314.299092 -36.376102)
		(width 0.0889)
		(layer "In11.Cu")
		(net "SMB_DDR_ABC_SCL_G_R")
	)
	(segment
		(start 300.106842 -54.818788)
		(end 300.074076 -54.818788)
		(width 0.0889)
		(layer "In11.Cu")
		(net "SMB_DDR_ABC_SCL_G_R")
	)
	(segment
		(start 295.818306 -57.295034)
		(end 295.78554 -57.295034)
		(width 0.0889)
		(layer "In11.Cu")
		(net "SMB_DDR_ABC_SCL_G_R")
	)
	(segment
		(start 294.955976 -57.790588)
		(end 294.92321 -57.790588)
		(width 0.0889)
		(layer "In11.Cu")
		(net "SMB_DDR_ABC_SCL_G_R")
	)
	(segment
		(start 314.965588 -36.010342)
		(end 314.690506 -36.285424)
		(width 0.0889)
		(layer "In11.Cu")
		(net "SMB_DDR_ABC_SCL_G_R")
	)
	(segment
		(start 292.71595 -63.629286)
		(end 292.720776 -63.637922)
		(width 0.0889)
		(layer "In11.Cu")
		(net "SMB_DDR_ABC_SCL_G_R")
	)
	(segment
		(start 301.823882 -53.827934)
		(end 301.799752 -53.827934)
		(width 0.0889)
		(layer "In11.Cu")
		(net "SMB_DDR_ABC_SCL_G_R")
	)
	(segment
		(start 293.579296 -61.5442)
		(end 293.57447 -61.552836)
		(width 0.0889)
		(layer "In11.Cu")
		(net "SMB_DDR_ABC_SCL_G_R")
	)
	(segment
		(start 303.216056 -52.913534)
		(end 303.169828 -52.959254)
		(width 0.0889)
		(layer "In11.Cu")
		(net "SMB_DDR_ABC_SCL_G_R")
	)
	(segment
		(start 302.68926 -53.332634)
		(end 302.649636 -53.332634)
		(width 0.0889)
		(layer "In11.Cu")
		(net "SMB_DDR_ABC_SCL_G_R")
	)
	(segment
		(start 293.579296 -60.5536)
		(end 293.57447 -60.562236)
		(width 0.0889)
		(layer "In11.Cu")
		(net "SMB_DDR_ABC_SCL_G_R")
	)
	(segment
		(start 293.56812 -59.160918)
		(end 293.57447 -59.171586)
		(width 0.0889)
		(layer "In11.Cu")
		(net "SMB_DDR_ABC_SCL_G_R")
	)
	(segment
		(start 294.101266 -58.285634)
		(end 294.073326 -58.285634)
		(width 0.0889)
		(layer "In11.Cu")
		(net "SMB_DDR_ABC_SCL_G_R")
	)
	(segment
		(start 305.054 -50.970688)
		(end 303.821846 -52.202842)
		(width 0.089408)
		(layer "In11.Cu")
		(net "SMB_DDR_ABC_SCL_G_R")
	)
	(segment
		(start 292.7096 -64.609218)
		(end 292.71595 -64.619886)
		(width 0.0889)
		(layer "In11.Cu")
		(net "SMB_DDR_ABC_SCL_G_R")
	)
	(segment
		(start 298.389802 -55.809388)
		(end 298.357036 -55.809388)
		(width 0.0889)
		(layer "In11.Cu")
		(net "SMB_DDR_ABC_SCL_G_R")
	)
	(segment
		(start 303.216056 -52.808632)
		(end 303.216056 -52.913534)
		(width 0.0889)
		(layer "In11.Cu")
		(net "SMB_DDR_ABC_SCL_G_R")
	)
	(segment
		(start 297.535092 -56.304434)
		(end 297.502326 -56.304434)
		(width 0.0889)
		(layer "In11.Cu")
		(net "SMB_DDR_ABC_SCL_G_R")
	)
	(segment
		(start 300.969172 -54.323234)
		(end 300.936406 -54.323234)
		(width 0.0889)
		(layer "In11.Cu")
		(net "SMB_DDR_ABC_SCL_G_R")
	)
	(segment
		(start 292.7096 -63.618618)
		(end 292.71595 -63.629286)
		(width 0.0889)
		(layer "In11.Cu")
		(net "SMB_DDR_ABC_SCL_G_R")
	)
	(segment
		(start 293.238936 -61.752988)
		(end 293.20617 -61.752988)
		(width 0.0889)
		(layer "In11.Cu")
		(net "SMB_DDR_ABC_SCL_G_R")
	)
	(segment
		(start 314.299092 -36.376102)
		(end 314.298838 -36.376102)
		(width 0.0889)
		(layer "In11.Cu")
		(net "SMB_DDR_ABC_SCL_G_R")
	)
	(segment
		(start 314.298838 -36.376102)
		(end 313.12231 -37.55263)
		(width 0.0889)
		(layer "In11.Cu")
		(net "SMB_DDR_ABC_SCL_G_R")
	)
	(arc
		(start 294.073326 -58.285634)
		(mid 293.785181 -58.367953)
		(end 293.57447 -58.581036)
		(width 0.0889)
		(layer "In11.Cu")
		(net "SMB_DDR_ABC_SCL_G_R")
	)
	(arc
		(start 292.71595 -64.029336)
		(mid 292.636728 -64.318454)
		(end 292.7096 -64.609218)
		(width 0.0889)
		(layer "In11.Cu")
		(net "SMB_DDR_ABC_SCL_G_R")
	)
	(arc
		(start 297.866816 -56.104536)
		(mid 297.726737 -56.247272)
		(end 297.535092 -56.304434)
		(width 0.0889)
		(layer "In11.Cu")
		(net "SMB_DDR_ABC_SCL_G_R")
	)
	(arc
		(start 303.169828 -52.959254)
		(mid 303.085333 -53.03851)
		(end 303.017936 -53.132736)
		(width 0.0889)
		(layer "In11.Cu")
		(net "SMB_DDR_ABC_SCL_G_R")
	)
	(arc
		(start 301.300896 -54.123336)
		(mid 301.160817 -54.266072)
		(end 300.969172 -54.323234)
		(width 0.0889)
		(layer "In11.Cu")
		(net "SMB_DDR_ABC_SCL_G_R")
	)
	(arc
		(start 293.57447 -61.552836)
		(mid 293.432787 -61.69664)
		(end 293.238936 -61.752988)
		(width 0.0889)
		(layer "In11.Cu")
		(net "SMB_DDR_ABC_SCL_G_R")
	)
	(arc
		(start 293.20617 -61.752988)
		(mid 292.922953 -61.837269)
		(end 292.71595 -62.048136)
		(width 0.0889)
		(layer "In11.Cu")
		(net "SMB_DDR_ABC_SCL_G_R")
	)
	(arc
		(start 293.57447 -60.162186)
		(mid 293.62794 -60.357249)
		(end 293.579296 -60.5536)
		(width 0.0889)
		(layer "In11.Cu")
		(net "SMB_DDR_ABC_SCL_G_R")
	)
	(arc
		(start 292.71595 -64.619886)
		(mid 292.904373 -64.81919)
		(end 293.162482 -64.911986)
		(width 0.0889)
		(layer "In11.Cu")
		(net "SMB_DDR_ABC_SCL_G_R")
	)
	(arc
		(start 296.64025 -56.799988)
		(mid 296.357033 -56.884269)
		(end 296.15003 -57.095136)
		(width 0.0889)
		(layer "In11.Cu")
		(net "SMB_DDR_ABC_SCL_G_R")
	)
	(arc
		(start 294.43299 -58.085736)
		(mid 294.292911 -58.228472)
		(end 294.101266 -58.285634)
		(width 0.0889)
		(layer "In11.Cu")
		(net "SMB_DDR_ABC_SCL_G_R")
	)
	(arc
		(start 298.357036 -55.809388)
		(mid 298.073819 -55.893669)
		(end 297.866816 -56.104536)
		(width 0.0889)
		(layer "In11.Cu")
		(net "SMB_DDR_ABC_SCL_G_R")
	)
	(arc
		(start 300.442376 -54.618636)
		(mid 300.300693 -54.76244)
		(end 300.106842 -54.818788)
		(width 0.0889)
		(layer "In11.Cu")
		(net "SMB_DDR_ABC_SCL_G_R")
	)
	(arc
		(start 301.799752 -53.827934)
		(mid 301.511607 -53.910253)
		(end 301.300896 -54.123336)
		(width 0.0889)
		(layer "In11.Cu")
		(net "SMB_DDR_ABC_SCL_G_R")
	)
	(arc
		(start 292.71595 -62.048136)
		(mid 292.636728 -62.337254)
		(end 292.7096 -62.628018)
		(width 0.0889)
		(layer "In11.Cu")
		(net "SMB_DDR_ABC_SCL_G_R")
	)
	(arc
		(start 297.004994 -56.605678)
		(mid 296.859028 -56.748077)
		(end 296.66184 -56.799988)
		(width 0.0889)
		(layer "In11.Cu")
		(net "SMB_DDR_ABC_SCL_G_R")
	)
	(arc
		(start 302.649636 -53.332634)
		(mid 302.366419 -53.416915)
		(end 302.159416 -53.627782)
		(width 0.0889)
		(layer "In11.Cu")
		(net "SMB_DDR_ABC_SCL_G_R")
	)
	(arc
		(start 297.502326 -56.304434)
		(mid 297.216902 -56.387901)
		(end 297.008296 -56.599836)
		(width 0.0889)
		(layer "In11.Cu")
		(net "SMB_DDR_ABC_SCL_G_R")
	)
	(arc
		(start 293.57447 -58.581036)
		(mid 293.495248 -58.870154)
		(end 293.56812 -59.160918)
		(width 0.0889)
		(layer "In11.Cu")
		(net "SMB_DDR_ABC_SCL_G_R")
	)
	(arc
		(start 296.15003 -57.095136)
		(mid 296.009951 -57.237872)
		(end 295.818306 -57.295034)
		(width 0.0889)
		(layer "In11.Cu")
		(net "SMB_DDR_ABC_SCL_G_R")
	)
	(arc
		(start 298.725336 -55.609236)
		(mid 298.583653 -55.75304)
		(end 298.389802 -55.809388)
		(width 0.0889)
		(layer "In11.Cu")
		(net "SMB_DDR_ABC_SCL_G_R")
	)
	(arc
		(start 295.78554 -57.295034)
		(mid 295.500116 -57.378501)
		(end 295.29151 -57.590436)
		(width 0.0889)
		(layer "In11.Cu")
		(net "SMB_DDR_ABC_SCL_G_R")
	)
	(arc
		(start 303.017936 -53.132736)
		(mid 302.879192 -53.274769)
		(end 302.68926 -53.332634)
		(width 0.0889)
		(layer "In11.Cu")
		(net "SMB_DDR_ABC_SCL_G_R")
	)
	(arc
		(start 293.57447 -61.152786)
		(mid 293.62794 -61.347849)
		(end 293.579296 -61.5442)
		(width 0.0889)
		(layer "In11.Cu")
		(net "SMB_DDR_ABC_SCL_G_R")
	)
	(arc
		(start 300.936406 -54.323234)
		(mid 300.650982 -54.406701)
		(end 300.442376 -54.618636)
		(width 0.0889)
		(layer "In11.Cu")
		(net "SMB_DDR_ABC_SCL_G_R")
	)
	(arc
		(start 300.074076 -54.818788)
		(mid 299.790859 -54.903069)
		(end 299.583856 -55.113936)
		(width 0.0889)
		(layer "In11.Cu")
		(net "SMB_DDR_ABC_SCL_G_R")
	)
	(arc
		(start 294.92321 -57.790588)
		(mid 294.639993 -57.874869)
		(end 294.43299 -58.085736)
		(width 0.0889)
		(layer "In11.Cu")
		(net "SMB_DDR_ABC_SCL_G_R")
	)
	(arc
		(start 299.583856 -55.113936)
		(mid 299.443777 -55.256672)
		(end 299.252132 -55.313834)
		(width 0.0889)
		(layer "In11.Cu")
		(net "SMB_DDR_ABC_SCL_G_R")
	)
	(arc
		(start 293.57447 -59.171586)
		(mid 293.627969 -59.371484)
		(end 293.57447 -59.571382)
		(width 0.0889)
		(layer "In11.Cu")
		(net "SMB_DDR_ABC_SCL_G_R")
	)
	(arc
		(start 293.56812 -60.572904)
		(mid 293.495322 -60.863667)
		(end 293.57447 -61.152786)
		(width 0.0889)
		(layer "In11.Cu")
		(net "SMB_DDR_ABC_SCL_G_R")
	)
	(arc
		(start 299.219366 -55.313834)
		(mid 298.933942 -55.397301)
		(end 298.725336 -55.609236)
		(width 0.0889)
		(layer "In11.Cu")
		(net "SMB_DDR_ABC_SCL_G_R")
	)
	(arc
		(start 293.57447 -59.571382)
		(mid 293.495339 -59.866784)
		(end 293.57447 -60.162186)
		(width 0.0889)
		(layer "In11.Cu")
		(net "SMB_DDR_ABC_SCL_G_R")
	)
	(arc
		(start 295.29151 -57.590436)
		(mid 295.149827 -57.73424)
		(end 294.955976 -57.790588)
		(width 0.0889)
		(layer "In11.Cu")
		(net "SMB_DDR_ABC_SCL_G_R")
	)
	(arc
		(start 302.159416 -53.627782)
		(mid 302.017733 -53.771586)
		(end 301.823882 -53.827934)
		(width 0.0889)
		(layer "In11.Cu")
		(net "SMB_DDR_ABC_SCL_G_R")
	)
	(arc
		(start 292.71595 -63.038736)
		(mid 292.636728 -63.327854)
		(end 292.7096 -63.618618)
		(width 0.0889)
		(layer "In11.Cu")
		(net "SMB_DDR_ABC_SCL_G_R")
	)
	(arc
		(start 292.720776 -62.647322)
		(mid 292.769531 -62.843674)
		(end 292.71595 -63.038736)
		(width 0.0889)
		(layer "In11.Cu")
		(net "SMB_DDR_ABC_SCL_G_R")
	)
	(arc
		(start 292.720776 -63.637922)
		(mid 292.769531 -63.834274)
		(end 292.71595 -64.029336)
		(width 0.0889)
		(layer "In11.Cu")
		(net "SMB_DDR_ABC_SCL_G_R")
	)
	(segment
		(start 322.961 -31.115)
		(end 322.961 -31.1404)
		(width 0.10795)
		(layer "F.Cu")
		(net "SMB_DDR_ABC_SCL_G")
	)
	(segment
		(start 322.961 -31.1404)
		(end 322.95846 -31.14294)
		(width 0.10795)
		(layer "F.Cu")
		(net "SMB_DDR_ABC_SCL_G")
	)
	(segment
		(start 322.95846 -31.14294)
		(end 322.95846 -32.42818)
		(width 0.10795)
		(layer "F.Cu")
		(net "SMB_DDR_ABC_SCL_G")
	)
	(via
		(at 322.961 -31.115)
		(size 0.508)
		(drill 0.254)
		(layers "F.Cu" "B.Cu")
		(net "SMB_DDR_ABC_SCL_G")
	)
	(segment
		(start 322.9737 -32.93618)
		(end 322.9737 -31.967678)
		(width 0.10795)
		(layer "B.Cu")
		(net "SMB_DDR_ABC_SCL_G")
	)
	(segment
		(start 322.9737 -31.967678)
		(end 322.9737 -31.1277)
		(width 0.10795)
		(layer "B.Cu")
		(net "SMB_DDR_ABC_SCL_G")
	)
	(segment
		(start 322.9737 -31.1277)
		(end 322.961 -31.115)
		(width 0.10795)
		(layer "B.Cu")
		(net "SMB_DDR_ABC_SCL_G")
	)
	(segment
		(start 16.91005 -78.53045)
		(end 16.91005 -78.0415)
		(width 0.10795)
		(layer "F.Cu")
		(net "SMB_3V3SB_HSC_SDA_R")
	)
	(segment
		(start 17.55775 -79.24165)
		(end 17.55775 -78.89875)
		(width 0.10795)
		(layer "F.Cu")
		(net "SMB_3V3SB_HSC_SDA_R")
	)
	(segment
		(start 17.55775 -78.89875)
		(end 17.27835 -78.89875)
		(width 0.10795)
		(layer "F.Cu")
		(net "SMB_3V3SB_HSC_SDA_R")
	)
	(segment
		(start 16.891 -79.5655)
		(end 17.2339 -79.5655)
		(width 0.10795)
		(layer "F.Cu")
		(net "SMB_3V3SB_HSC_SDA_R")
	)
	(segment
		(start 17.2339 -79.5655)
		(end 17.55775 -79.24165)
		(width 0.10795)
		(layer "F.Cu")
		(net "SMB_3V3SB_HSC_SDA_R")
	)
	(segment
		(start 17.27835 -78.89875)
		(end 16.91005 -78.53045)
		(width 0.10795)
		(layer "F.Cu")
		(net "SMB_3V3SB_HSC_SDA_R")
	)
	(via
		(at 17.6022 -77.724)
		(size 0.6604)
		(drill 0.3302)
		(layers "F.Cu" "B.Cu")
		(net "SMB_3V3SB_HSC_SDA_R")
	)
	(via
		(at 17.55775 -78.89875)
		(size 0.508)
		(drill 0.254)
		(layers "F.Cu" "B.Cu")
		(net "SMB_3V3SB_HSC_SDA_R")
	)
	(segment
		(start 17.55775 -78.89875)
		(end 17.55775 -78.07325)
		(width 0.10795)
		(layer "B.Cu")
		(net "SMB_3V3SB_HSC_SDA_R")
	)
	(segment
		(start 17.6022 -78.0288)
		(end 17.6022 -77.724)
		(width 0.10795)
		(layer "B.Cu")
		(net "SMB_3V3SB_HSC_SDA_R")
	)
	(segment
		(start 17.55775 -78.07325)
		(end 17.6022 -78.0288)
		(width 0.10795)
		(layer "B.Cu")
		(net "SMB_3V3SB_HSC_SDA_R")
	)
	(segment
		(start 15.494 -79.197454)
		(end 15.697454 -78.994)
		(width 0.10795)
		(layer "F.Cu")
		(net "SMB_3V3SB_HSC_SCL_R")
	)
	(segment
		(start 16.40967 -78.487524)
		(end 16.4592 -78.537054)
		(width 0.10795)
		(layer "F.Cu")
		(net "SMB_3V3SB_HSC_SCL_R")
	)
	(segment
		(start 16.4592 -78.84795)
		(end 16.4338 -78.87335)
		(width 0.10795)
		(layer "F.Cu")
		(net "SMB_3V3SB_HSC_SCL_R")
	)
	(segment
		(start 16.40967 -78.0415)
		(end 16.40967 -78.487524)
		(width 0.10795)
		(layer "F.Cu")
		(net "SMB_3V3SB_HSC_SCL_R")
	)
	(segment
		(start 15.494 -79.5655)
		(end 15.494 -79.197454)
		(width 0.10795)
		(layer "F.Cu")
		(net "SMB_3V3SB_HSC_SCL_R")
	)
	(segment
		(start 16.31315 -78.994)
		(end 16.4338 -78.87335)
		(width 0.10795)
		(layer "F.Cu")
		(net "SMB_3V3SB_HSC_SCL_R")
	)
	(segment
		(start 16.4592 -78.537054)
		(end 16.4592 -78.84795)
		(width 0.10795)
		(layer "F.Cu")
		(net "SMB_3V3SB_HSC_SCL_R")
	)
	(segment
		(start 15.697454 -78.994)
		(end 16.31315 -78.994)
		(width 0.10795)
		(layer "F.Cu")
		(net "SMB_3V3SB_HSC_SCL_R")
	)
	(via
		(at 16.4338 -78.87335)
		(size 0.508)
		(drill 0.254)
		(layers "F.Cu" "B.Cu")
		(net "SMB_3V3SB_HSC_SCL_R")
	)
	(segment
		(start 390.339072 -130.848354)
		(end 390.605772 -130.848354)
		(width 0.0889)
		(layer "F.Cu")
		(net "SATA6G_S1_TX_DP")
	)
	(segment
		(start 393.02817 -132.645912)
		(end 393.16025 -132.777992)
		(width 0.0889)
		(layer "F.Cu")
		(net "SATA6G_S1_TX_DP")
	)
	(segment
		(start 387.422898 -129.33045)
		(end 387.611366 -129.519172)
		(width 0.0889)
		(layer "F.Cu")
		(net "SATA6G_S1_TX_DP")
	)
	(segment
		(start 389.894572 -130.759454)
		(end 390.161272 -130.759454)
		(width 0.0889)
		(layer "F.Cu")
		(net "SATA6G_S1_TX_DP")
	)
	(segment
		(start 432.644042 -139.313412)
		(end 432.644042 -139.1666)
		(width 0.1143)
		(layer "F.Cu")
		(net "SATA6G_S1_TX_DP")
	)
	(segment
		(start 397.429736 -132.920994)
		(end 397.451834 -132.920994)
		(width 0.0889)
		(layer "F.Cu")
		(net "SATA6G_S1_TX_DP")
	)
	(segment
		(start 427.811946 -137.97407)
		(end 428.134526 -137.97407)
		(width 0.1143)
		(layer "F.Cu")
		(net "SATA6G_S1_TX_DP")
	)
	(segment
		(start 411.8229 -136.9568)
		(end 418.10686 -136.9568)
		(width 0.1143)
		(layer "F.Cu")
		(net "SATA6G_S1_TX_DP")
	)
	(segment
		(start 393.88796 -132.984494)
		(end 394.15466 -132.984494)
		(width 0.0889)
		(layer "F.Cu")
		(net "SATA6G_S1_TX_DP")
	)
	(segment
		(start 428.910242 -138.29538)
		(end 430.104804 -139.489942)
		(width 0.1143)
		(layer "F.Cu")
		(net "SATA6G_S1_TX_DP")
	)
	(segment
		(start 397.404336 -132.895594)
		(end 397.429736 -132.920994)
		(width 0.0889)
		(layer "F.Cu")
		(net "SATA6G_S1_TX_DP")
	)
	(segment
		(start 391.200132 -130.818128)
		(end 391.330688 -130.948684)
		(width 0.0889)
		(layer "F.Cu")
		(net "SATA6G_S1_TX_DP")
	)
	(segment
		(start 405.007064 -130.04165)
		(end 407.88463 -130.04165)
		(width 0.1143)
		(layer "F.Cu")
		(net "SATA6G_S1_TX_DP")
	)
	(segment
		(start 431.255678 -139.9667)
		(end 431.990754 -139.9667)
		(width 0.1143)
		(layer "F.Cu")
		(net "SATA6G_S1_TX_DP")
	)
	(segment
		(start 432.96586 -138.844782)
		(end 433.158392 -138.844782)
		(width 0.1143)
		(layer "F.Cu")
		(net "SATA6G_S1_TX_DP")
	)
	(segment
		(start 394.33246 -132.895594)
		(end 394.59916 -132.895594)
		(width 0.0889)
		(layer "F.Cu")
		(net "SATA6G_S1_TX_DP")
	)
	(segment
		(start 390.783572 -130.759454)
		(end 391.058908 -130.759454)
		(width 0.0889)
		(layer "F.Cu")
		(net "SATA6G_S1_TX_DP")
	)
	(segment
		(start 386.499862 -125.765052)
		(end 386.499862 -126.419356)
		(width 0.0889)
		(layer "F.Cu")
		(net "SATA6G_S1_TX_DP")
	)
	(segment
		(start 386.484876 -125.750066)
		(end 386.499862 -125.765052)
		(width 0.0889)
		(layer "F.Cu")
		(net "SATA6G_S1_TX_DP")
	)
	(segment
		(start 425.037758 -136.676638)
		(end 425.744386 -136.676638)
		(width 0.1143)
		(layer "F.Cu")
		(net "SATA6G_S1_TX_DP")
	)
	(segment
		(start 395.22146 -132.895594)
		(end 395.48816 -132.895594)
		(width 0.0889)
		(layer "F.Cu")
		(net "SATA6G_S1_TX_DP")
	)
	(segment
		(start 386.6515 -126.570994)
		(end 386.6515 -128.356614)
		(width 0.0889)
		(layer "F.Cu")
		(net "SATA6G_S1_TX_DP")
	)
	(segment
		(start 386.794248 -128.7018)
		(end 386.982716 -128.890522)
		(width 0.0889)
		(layer "F.Cu")
		(net "SATA6G_S1_TX_DP")
	)
	(segment
		(start 388.303008 -130.33629)
		(end 388.491476 -130.525012)
		(width 0.0889)
		(layer "F.Cu")
		(net "SATA6G_S1_TX_DP")
	)
	(segment
		(start 402.06803 -132.663946)
		(end 404.466298 -130.265678)
		(width 0.1143)
		(layer "F.Cu")
		(net "SATA6G_S1_TX_DP")
	)
	(segment
		(start 396.11046 -132.895594)
		(end 396.37716 -132.895594)
		(width 0.0889)
		(layer "F.Cu")
		(net "SATA6G_S1_TX_DP")
	)
	(segment
		(start 393.44346 -132.895594)
		(end 393.71016 -132.895594)
		(width 0.0889)
		(layer "F.Cu")
		(net "SATA6G_S1_TX_DP")
	)
	(segment
		(start 387.674358 -129.70764)
		(end 387.862826 -129.896362)
		(width 0.0889)
		(layer "F.Cu")
		(net "SATA6G_S1_TX_DP")
	)
	(segment
		(start 387.045708 -129.07899)
		(end 387.234176 -129.267712)
		(width 0.0889)
		(layer "F.Cu")
		(net "SATA6G_S1_TX_DP")
	)
	(segment
		(start 397.451834 -132.920994)
		(end 400.506184 -132.920994)
		(width 0.1143)
		(layer "F.Cu")
		(net "SATA6G_S1_TX_DP")
	)
	(segment
		(start 408.182064 -130.16484)
		(end 409.884626 -131.867402)
		(width 0.1143)
		(layer "F.Cu")
		(net "SATA6G_S1_TX_DP")
	)
	(segment
		(start 396.99946 -132.895594)
		(end 397.404336 -132.895594)
		(width 0.0889)
		(layer "F.Cu")
		(net "SATA6G_S1_TX_DP")
	)
	(segment
		(start 424.041824 -137.86231)
		(end 424.041824 -137.672572)
		(width 0.1143)
		(layer "F.Cu")
		(net "SATA6G_S1_TX_DP")
	)
	(segment
		(start 395.66596 -132.984494)
		(end 395.93266 -132.984494)
		(width 0.0889)
		(layer "F.Cu")
		(net "SATA6G_S1_TX_DP")
	)
	(segment
		(start 410.1973 -132.62229)
		(end 410.1973 -135.3312)
		(width 0.1143)
		(layer "F.Cu")
		(net "SATA6G_S1_TX_DP")
	)
	(segment
		(start 396.55496 -132.984494)
		(end 396.82166 -132.984494)
		(width 0.0889)
		(layer "F.Cu")
		(net "SATA6G_S1_TX_DP")
	)
	(segment
		(start 392.65098 -132.394706)
		(end 392.839702 -132.583174)
		(width 0.0889)
		(layer "F.Cu")
		(net "SATA6G_S1_TX_DP")
	)
	(segment
		(start 388.051548 -129.9591)
		(end 388.240016 -130.147822)
		(width 0.0889)
		(layer "F.Cu")
		(net "SATA6G_S1_TX_DP")
	)
	(segment
		(start 392.02233 -131.766056)
		(end 392.210798 -131.954524)
		(width 0.0889)
		(layer "F.Cu")
		(net "SATA6G_S1_TX_DP")
	)
	(segment
		(start 426.296328 -136.905238)
		(end 427.049184 -137.658094)
		(width 0.1143)
		(layer "F.Cu")
		(net "SATA6G_S1_TX_DP")
	)
	(segment
		(start 392.39952 -132.017516)
		(end 392.588242 -132.205984)
		(width 0.0889)
		(layer "F.Cu")
		(net "SATA6G_S1_TX_DP")
	)
	(segment
		(start 389.450072 -130.848354)
		(end 389.716772 -130.848354)
		(width 0.0889)
		(layer "F.Cu")
		(net "SATA6G_S1_TX_DP")
	)
	(segment
		(start 400.506184 -132.920994)
		(end 401.447254 -132.920994)
		(width 0.1143)
		(layer "F.Cu")
		(net "SATA6G_S1_TX_DP")
	)
	(segment
		(start 388.681468 -130.58902)
		(end 388.74319 -130.650742)
		(width 0.0889)
		(layer "F.Cu")
		(net "SATA6G_S1_TX_DP")
	)
	(segment
		(start 418.804598 -137.245852)
		(end 419.967918 -138.409172)
		(width 0.1143)
		(layer "F.Cu")
		(net "SATA6G_S1_TX_DP")
	)
	(segment
		(start 420.553642 -138.651742)
		(end 423.252392 -138.651742)
		(width 0.1143)
		(layer "F.Cu")
		(net "SATA6G_S1_TX_DP")
	)
	(segment
		(start 386.499862 -126.419356)
		(end 386.6515 -126.570994)
		(width 0.0889)
		(layer "F.Cu")
		(net "SATA6G_S1_TX_DP")
	)
	(segment
		(start 391.77087 -131.388866)
		(end 391.959338 -131.577334)
		(width 0.0889)
		(layer "F.Cu")
		(net "SATA6G_S1_TX_DP")
	)
	(segment
		(start 389.005572 -130.759454)
		(end 389.272272 -130.759454)
		(width 0.0889)
		(layer "F.Cu")
		(net "SATA6G_S1_TX_DP")
	)
	(segment
		(start 388.679944 -130.58775)
		(end 388.681468 -130.58902)
		(width 0.0889)
		(layer "F.Cu")
		(net "SATA6G_S1_TX_DP")
	)
	(segment
		(start 391.39368 -131.137406)
		(end 391.582148 -131.325874)
		(width 0.0889)
		(layer "F.Cu")
		(net "SATA6G_S1_TX_DP")
	)
	(segment
		(start 394.77696 -132.984494)
		(end 395.04366 -132.984494)
		(width 0.0889)
		(layer "F.Cu")
		(net "SATA6G_S1_TX_DP")
	)
	(via
		(at 433.158392 -138.844782)
		(size 0.508)
		(drill 0.254)
		(layers "F.Cu" "B.Cu")
		(net "SATA6G_S1_TX_DP")
	)
	(via
		(at 400.506184 -132.920994)
		(size 0.508)
		(drill 0.254)
		(layers "F.Cu" "B.Cu")
		(net "SATA6G_S1_TX_DP")
	)
	(arc
		(start 386.982716 -128.890522)
		(mid 387.007112 -128.934744)
		(end 387.014212 -128.984756)
		(width 0.0889)
		(layer "F.Cu")
		(net "SATA6G_S1_TX_DP")
	)
	(arc
		(start 396.82166 -132.984494)
		(mid 396.870186 -132.970429)
		(end 396.91056 -132.940044)
		(width 0.0889)
		(layer "F.Cu")
		(net "SATA6G_S1_TX_DP")
	)
	(arc
		(start 396.46606 -132.940044)
		(mid 396.506416 -132.970465)
		(end 396.55496 -132.984494)
		(width 0.0889)
		(layer "F.Cu")
		(net "SATA6G_S1_TX_DP")
	)
	(arc
		(start 389.272272 -130.759454)
		(mid 389.320798 -130.773519)
		(end 389.361172 -130.803904)
		(width 0.0889)
		(layer "F.Cu")
		(net "SATA6G_S1_TX_DP")
	)
	(arc
		(start 387.32841 -129.298954)
		(mid 387.378539 -129.306031)
		(end 387.422898 -129.33045)
		(width 0.0889)
		(layer "F.Cu")
		(net "SATA6G_S1_TX_DP")
	)
	(arc
		(start 387.95706 -129.927604)
		(mid 388.007189 -129.934681)
		(end 388.051548 -129.9591)
		(width 0.0889)
		(layer "F.Cu")
		(net "SATA6G_S1_TX_DP")
	)
	(arc
		(start 392.210798 -131.954524)
		(mid 392.25514 -131.97896)
		(end 392.305286 -131.98602)
		(width 0.0889)
		(layer "F.Cu")
		(net "SATA6G_S1_TX_DP")
	)
	(arc
		(start 389.805672 -130.803904)
		(mid 389.846028 -130.773483)
		(end 389.894572 -130.759454)
		(width 0.0889)
		(layer "F.Cu")
		(net "SATA6G_S1_TX_DP")
	)
	(arc
		(start 391.362184 -131.043172)
		(mid 391.36923 -131.093208)
		(end 391.39368 -131.137406)
		(width 0.0889)
		(layer "F.Cu")
		(net "SATA6G_S1_TX_DP")
	)
	(arc
		(start 392.305286 -131.98602)
		(mid 392.355322 -131.993066)
		(end 392.39952 -132.017516)
		(width 0.0889)
		(layer "F.Cu")
		(net "SATA6G_S1_TX_DP")
	)
	(arc
		(start 389.361172 -130.803904)
		(mid 389.401528 -130.834325)
		(end 389.450072 -130.848354)
		(width 0.0889)
		(layer "F.Cu")
		(net "SATA6G_S1_TX_DP")
	)
	(arc
		(start 391.676636 -131.35737)
		(mid 391.726672 -131.364416)
		(end 391.77087 -131.388866)
		(width 0.0889)
		(layer "F.Cu")
		(net "SATA6G_S1_TX_DP")
	)
	(arc
		(start 428.134526 -137.97407)
		(mid 428.55434 -138.057576)
		(end 428.910242 -138.29538)
		(width 0.1143)
		(layer "F.Cu")
		(net "SATA6G_S1_TX_DP")
	)
	(arc
		(start 393.71016 -132.895594)
		(mid 393.758686 -132.909659)
		(end 393.79906 -132.940044)
		(width 0.0889)
		(layer "F.Cu")
		(net "SATA6G_S1_TX_DP")
	)
	(arc
		(start 387.014212 -128.984756)
		(mid 387.021258 -129.034792)
		(end 387.045708 -129.07899)
		(width 0.0889)
		(layer "F.Cu")
		(net "SATA6G_S1_TX_DP")
	)
	(arc
		(start 396.91056 -132.940044)
		(mid 396.950916 -132.909623)
		(end 396.99946 -132.895594)
		(width 0.0889)
		(layer "F.Cu")
		(net "SATA6G_S1_TX_DP")
	)
	(arc
		(start 387.642862 -129.613406)
		(mid 387.649908 -129.663442)
		(end 387.674358 -129.70764)
		(width 0.0889)
		(layer "F.Cu")
		(net "SATA6G_S1_TX_DP")
	)
	(arc
		(start 431.990754 -139.9667)
		(mid 432.452698 -139.775356)
		(end 432.644042 -139.313412)
		(width 0.1143)
		(layer "F.Cu")
		(net "SATA6G_S1_TX_DP")
	)
	(arc
		(start 396.37716 -132.895594)
		(mid 396.425686 -132.909659)
		(end 396.46606 -132.940044)
		(width 0.0889)
		(layer "F.Cu")
		(net "SATA6G_S1_TX_DP")
	)
	(arc
		(start 387.862826 -129.896362)
		(mid 387.907082 -129.920591)
		(end 387.95706 -129.927604)
		(width 0.0889)
		(layer "F.Cu")
		(net "SATA6G_S1_TX_DP")
	)
	(arc
		(start 387.234176 -129.267712)
		(mid 387.278432 -129.291941)
		(end 387.32841 -129.298954)
		(width 0.0889)
		(layer "F.Cu")
		(net "SATA6G_S1_TX_DP")
	)
	(arc
		(start 395.57706 -132.940044)
		(mid 395.617416 -132.970465)
		(end 395.66596 -132.984494)
		(width 0.0889)
		(layer "F.Cu")
		(net "SATA6G_S1_TX_DP")
	)
	(arc
		(start 387.611366 -129.519172)
		(mid 387.635762 -129.563394)
		(end 387.642862 -129.613406)
		(width 0.0889)
		(layer "F.Cu")
		(net "SATA6G_S1_TX_DP")
	)
	(arc
		(start 394.59916 -132.895594)
		(mid 394.647686 -132.909659)
		(end 394.68806 -132.940044)
		(width 0.0889)
		(layer "F.Cu")
		(net "SATA6G_S1_TX_DP")
	)
	(arc
		(start 392.619484 -132.300472)
		(mid 392.626611 -132.350464)
		(end 392.65098 -132.394706)
		(width 0.0889)
		(layer "F.Cu")
		(net "SATA6G_S1_TX_DP")
	)
	(arc
		(start 392.588242 -132.205984)
		(mid 392.612511 -132.25036)
		(end 392.619484 -132.300472)
		(width 0.0889)
		(layer "F.Cu")
		(net "SATA6G_S1_TX_DP")
	)
	(arc
		(start 404.466298 -130.265678)
		(mid 404.714404 -130.099899)
		(end 405.007064 -130.04165)
		(width 0.1143)
		(layer "F.Cu")
		(net "SATA6G_S1_TX_DP")
	)
	(arc
		(start 430.104804 -139.489942)
		(mid 430.632829 -139.842757)
		(end 431.255678 -139.9667)
		(width 0.1143)
		(layer "F.Cu")
		(net "SATA6G_S1_TX_DP")
	)
	(arc
		(start 394.68806 -132.940044)
		(mid 394.728416 -132.970465)
		(end 394.77696 -132.984494)
		(width 0.0889)
		(layer "F.Cu")
		(net "SATA6G_S1_TX_DP")
	)
	(arc
		(start 391.058908 -130.759454)
		(mid 391.135352 -130.774753)
		(end 391.200132 -130.818128)
		(width 0.0889)
		(layer "F.Cu")
		(net "SATA6G_S1_TX_DP")
	)
	(arc
		(start 407.88463 -130.04165)
		(mid 408.045596 -130.073668)
		(end 408.182064 -130.16484)
		(width 0.1143)
		(layer "F.Cu")
		(net "SATA6G_S1_TX_DP")
	)
	(arc
		(start 396.02156 -132.940044)
		(mid 396.061916 -132.909623)
		(end 396.11046 -132.895594)
		(width 0.0889)
		(layer "F.Cu")
		(net "SATA6G_S1_TX_DP")
	)
	(arc
		(start 395.48816 -132.895594)
		(mid 395.536686 -132.909659)
		(end 395.57706 -132.940044)
		(width 0.0889)
		(layer "F.Cu")
		(net "SATA6G_S1_TX_DP")
	)
	(arc
		(start 391.582148 -131.325874)
		(mid 391.62649 -131.35031)
		(end 391.676636 -131.35737)
		(width 0.0889)
		(layer "F.Cu")
		(net "SATA6G_S1_TX_DP")
	)
	(arc
		(start 388.271512 -130.242056)
		(mid 388.278568 -130.292083)
		(end 388.303008 -130.33629)
		(width 0.0889)
		(layer "F.Cu")
		(net "SATA6G_S1_TX_DP")
	)
	(arc
		(start 390.161272 -130.759454)
		(mid 390.209798 -130.773519)
		(end 390.250172 -130.803904)
		(width 0.0889)
		(layer "F.Cu")
		(net "SATA6G_S1_TX_DP")
	)
	(arc
		(start 424.041824 -137.672572)
		(mid 424.333526 -136.96834)
		(end 425.037758 -136.676638)
		(width 0.1143)
		(layer "F.Cu")
		(net "SATA6G_S1_TX_DP")
	)
	(arc
		(start 393.79906 -132.940044)
		(mid 393.839416 -132.970465)
		(end 393.88796 -132.984494)
		(width 0.0889)
		(layer "F.Cu")
		(net "SATA6G_S1_TX_DP")
	)
	(arc
		(start 425.744386 -136.676638)
		(mid 426.043086 -136.736053)
		(end 426.296328 -136.905238)
		(width 0.1143)
		(layer "F.Cu")
		(net "SATA6G_S1_TX_DP")
	)
	(arc
		(start 391.959338 -131.577334)
		(mid 391.983774 -131.621676)
		(end 391.990834 -131.671822)
		(width 0.0889)
		(layer "F.Cu")
		(net "SATA6G_S1_TX_DP")
	)
	(arc
		(start 388.58571 -130.556254)
		(mid 388.635702 -130.563381)
		(end 388.679944 -130.58775)
		(width 0.0889)
		(layer "F.Cu")
		(net "SATA6G_S1_TX_DP")
	)
	(arc
		(start 394.15466 -132.984494)
		(mid 394.203186 -132.970429)
		(end 394.24356 -132.940044)
		(width 0.0889)
		(layer "F.Cu")
		(net "SATA6G_S1_TX_DP")
	)
	(arc
		(start 423.252392 -138.651742)
		(mid 423.810605 -138.420523)
		(end 424.041824 -137.86231)
		(width 0.1143)
		(layer "F.Cu")
		(net "SATA6G_S1_TX_DP")
	)
	(arc
		(start 390.694672 -130.803904)
		(mid 390.735028 -130.773483)
		(end 390.783572 -130.759454)
		(width 0.0889)
		(layer "F.Cu")
		(net "SATA6G_S1_TX_DP")
	)
	(arc
		(start 391.990834 -131.671822)
		(mid 391.99788 -131.721858)
		(end 392.02233 -131.766056)
		(width 0.0889)
		(layer "F.Cu")
		(net "SATA6G_S1_TX_DP")
	)
	(arc
		(start 390.250172 -130.803904)
		(mid 390.290528 -130.834325)
		(end 390.339072 -130.848354)
		(width 0.0889)
		(layer "F.Cu")
		(net "SATA6G_S1_TX_DP")
	)
	(arc
		(start 395.13256 -132.940044)
		(mid 395.172916 -132.909623)
		(end 395.22146 -132.895594)
		(width 0.0889)
		(layer "F.Cu")
		(net "SATA6G_S1_TX_DP")
	)
	(arc
		(start 393.16025 -132.777992)
		(mid 393.290144 -132.865004)
		(end 393.44346 -132.895594)
		(width 0.0889)
		(layer "F.Cu")
		(net "SATA6G_S1_TX_DP")
	)
	(arc
		(start 391.330688 -130.948684)
		(mid 391.355124 -130.993026)
		(end 391.362184 -131.043172)
		(width 0.0889)
		(layer "F.Cu")
		(net "SATA6G_S1_TX_DP")
	)
	(arc
		(start 419.967918 -138.409172)
		(mid 420.23665 -138.588733)
		(end 420.553642 -138.651742)
		(width 0.1143)
		(layer "F.Cu")
		(net "SATA6G_S1_TX_DP")
	)
	(arc
		(start 388.491476 -130.525012)
		(mid 388.535723 -130.549284)
		(end 388.58571 -130.556254)
		(width 0.0889)
		(layer "F.Cu")
		(net "SATA6G_S1_TX_DP")
	)
	(arc
		(start 392.933936 -132.61467)
		(mid 392.98393 -132.62162)
		(end 393.02817 -132.645912)
		(width 0.0889)
		(layer "F.Cu")
		(net "SATA6G_S1_TX_DP")
	)
	(arc
		(start 427.049184 -137.658094)
		(mid 427.399142 -137.891929)
		(end 427.811946 -137.97407)
		(width 0.1143)
		(layer "F.Cu")
		(net "SATA6G_S1_TX_DP")
	)
	(arc
		(start 395.04366 -132.984494)
		(mid 395.092186 -132.970429)
		(end 395.13256 -132.940044)
		(width 0.0889)
		(layer "F.Cu")
		(net "SATA6G_S1_TX_DP")
	)
	(arc
		(start 392.839702 -132.583174)
		(mid 392.883933 -132.607526)
		(end 392.933936 -132.61467)
		(width 0.0889)
		(layer "F.Cu")
		(net "SATA6G_S1_TX_DP")
	)
	(arc
		(start 432.644042 -139.1666)
		(mid 432.7383 -138.93904)
		(end 432.96586 -138.844782)
		(width 0.1143)
		(layer "F.Cu")
		(net "SATA6G_S1_TX_DP")
	)
	(arc
		(start 418.10686 -136.9568)
		(mid 418.484474 -137.03193)
		(end 418.804598 -137.245852)
		(width 0.1143)
		(layer "F.Cu")
		(net "SATA6G_S1_TX_DP")
	)
	(arc
		(start 410.1973 -135.3312)
		(mid 410.673427 -136.480673)
		(end 411.8229 -136.9568)
		(width 0.1143)
		(layer "F.Cu")
		(net "SATA6G_S1_TX_DP")
	)
	(arc
		(start 395.93266 -132.984494)
		(mid 395.981186 -132.970429)
		(end 396.02156 -132.940044)
		(width 0.0889)
		(layer "F.Cu")
		(net "SATA6G_S1_TX_DP")
	)
	(arc
		(start 386.6515 -128.356614)
		(mid 386.688559 -128.543392)
		(end 386.794248 -128.7018)
		(width 0.0889)
		(layer "F.Cu")
		(net "SATA6G_S1_TX_DP")
	)
	(arc
		(start 409.884626 -131.867402)
		(mid 410.116047 -132.213748)
		(end 410.1973 -132.62229)
		(width 0.1143)
		(layer "F.Cu")
		(net "SATA6G_S1_TX_DP")
	)
	(arc
		(start 394.24356 -132.940044)
		(mid 394.283916 -132.909623)
		(end 394.33246 -132.895594)
		(width 0.0889)
		(layer "F.Cu")
		(net "SATA6G_S1_TX_DP")
	)
	(arc
		(start 388.74319 -130.650742)
		(mid 388.863572 -130.731179)
		(end 389.005572 -130.759454)
		(width 0.0889)
		(layer "F.Cu")
		(net "SATA6G_S1_TX_DP")
	)
	(arc
		(start 390.605772 -130.848354)
		(mid 390.654298 -130.834289)
		(end 390.694672 -130.803904)
		(width 0.0889)
		(layer "F.Cu")
		(net "SATA6G_S1_TX_DP")
	)
	(arc
		(start 401.447254 -132.920994)
		(mid 401.783197 -132.854189)
		(end 402.06803 -132.663946)
		(width 0.1143)
		(layer "F.Cu")
		(net "SATA6G_S1_TX_DP")
	)
	(arc
		(start 388.240016 -130.147822)
		(mid 388.264412 -130.192044)
		(end 388.271512 -130.242056)
		(width 0.0889)
		(layer "F.Cu")
		(net "SATA6G_S1_TX_DP")
	)
	(arc
		(start 389.716772 -130.848354)
		(mid 389.765298 -130.834289)
		(end 389.805672 -130.803904)
		(width 0.0889)
		(layer "F.Cu")
		(net "SATA6G_S1_TX_DP")
	)
	(segment
		(start 433.354734 -141.261338)
		(end 433.354734 -139.9032)
		(width 0.1143)
		(layer "B.Cu")
		(net "SATA6G_S1_TX_DP")
	)
	(segment
		(start 432.040538 -141.695678)
		(end 432.920394 -141.695678)
		(width 0.1143)
		(layer "B.Cu")
		(net "SATA6G_S1_TX_DP")
	)
	(segment
		(start 431.74412 -141.939518)
		(end 431.950876 -141.732762)
		(width 0.1143)
		(layer "B.Cu")
		(net "SATA6G_S1_TX_DP")
	)
	(segment
		(start 432.780948 -139.124182)
		(end 432.780694 -139.124436)
		(width 0.1143)
		(layer "B.Cu")
		(net "SATA6G_S1_TX_DP")
	)
	(segment
		(start 432.907694 -138.844782)
		(end 433.158392 -138.844782)
		(width 0.1143)
		(layer "B.Cu")
		(net "SATA6G_S1_TX_DP")
	)
	(segment
		(start 433.247292 -139.643104)
		(end 433.110386 -139.506452)
		(width 0.1143)
		(layer "B.Cu")
		(net "SATA6G_S1_TX_DP")
	)
	(segment
		(start 433.110386 -139.506452)
		(end 432.818032 -139.214098)
		(width 0.1143)
		(layer "B.Cu")
		(net "SATA6G_S1_TX_DP")
	)
	(segment
		(start 432.780694 -139.124436)
		(end 432.780694 -138.971782)
		(width 0.1143)
		(layer "B.Cu")
		(net "SATA6G_S1_TX_DP")
	)
	(arc
		(start 432.920394 -141.695678)
		(mid 433.227519 -141.568463)
		(end 433.354734 -141.261338)
		(width 0.1143)
		(layer "B.Cu")
		(net "SATA6G_S1_TX_DP")
	)
	(arc
		(start 433.354734 -139.9032)
		(mid 433.326802 -139.762507)
		(end 433.247292 -139.643104)
		(width 0.1143)
		(layer "B.Cu")
		(net "SATA6G_S1_TX_DP")
	)
	(arc
		(start 431.950876 -141.732762)
		(mid 431.992027 -141.705329)
		(end 432.040538 -141.695678)
		(width 0.1143)
		(layer "B.Cu")
		(net "SATA6G_S1_TX_DP")
	)
	(arc
		(start 432.780694 -138.971782)
		(mid 432.817891 -138.881979)
		(end 432.907694 -138.844782)
		(width 0.1143)
		(layer "B.Cu")
		(net "SATA6G_S1_TX_DP")
	)
	(arc
		(start 432.818032 -139.214098)
		(mid 432.79055 -139.172829)
		(end 432.780948 -139.124182)
		(width 0.1143)
		(layer "B.Cu")
		(net "SATA6G_S1_TX_DP")
	)
	(segment
		(start 386.690362 -126.340362)
		(end 386.690362 -126.072138)
		(width 0.0889)
		(layer "F.Cu")
		(net "SATA6G_S1_TX_DN")
	)
	(segment
		(start 410.5529 -133.6167)
		(end 410.5529 -133.2738)
		(width 0.1143)
		(layer "F.Cu")
		(net "SATA6G_S1_TX_DN")
	)
	(segment
		(start 423.252392 -138.410442)
		(end 422.839642 -138.410442)
		(width 0.1143)
		(layer "F.Cu")
		(net "SATA6G_S1_TX_DN")
	)
	(segment
		(start 410.055314 -131.696714)
		(end 409.812744 -131.454144)
		(width 0.1143)
		(layer "F.Cu")
		(net "SATA6G_S1_TX_DN")
	)
	(segment
		(start 430.275492 -139.319254)
		(end 429.08093 -138.124692)
		(width 0.1143)
		(layer "F.Cu")
		(net "SATA6G_S1_TX_DN")
	)
	(segment
		(start 393.295124 -132.643372)
		(end 391.335006 -130.683254)
		(width 0.0889)
		(layer "F.Cu")
		(net "SATA6G_S1_TX_DN")
	)
	(segment
		(start 421.468042 -138.296142)
		(end 421.125142 -138.296142)
		(width 0.1143)
		(layer "F.Cu")
		(net "SATA6G_S1_TX_DN")
	)
	(segment
		(start 386.842 -128.356614)
		(end 386.842 -126.492)
		(width 0.0889)
		(layer "F.Cu")
		(net "SATA6G_S1_TX_DN")
	)
	(segment
		(start 410.4386 -135.3312)
		(end 410.4386 -134.9883)
		(width 0.1143)
		(layer "F.Cu")
		(net "SATA6G_S1_TX_DN")
	)
	(segment
		(start 410.4386 -133.0452)
		(end 410.4386 -132.62229)
		(width 0.1143)
		(layer "F.Cu")
		(net "SATA6G_S1_TX_DN")
	)
	(segment
		(start 431.888392 -138.844782)
		(end 432.080924 -138.844782)
		(width 0.1143)
		(layer "F.Cu")
		(net "SATA6G_S1_TX_DN")
	)
	(segment
		(start 404.29561 -130.09499)
		(end 401.897342 -132.493258)
		(width 0.1143)
		(layer "F.Cu")
		(net "SATA6G_S1_TX_DN")
	)
	(segment
		(start 401.447254 -132.679694)
		(end 398.034256 -132.679694)
		(width 0.1143)
		(layer "F.Cu")
		(net "SATA6G_S1_TX_DN")
	)
	(segment
		(start 432.402742 -139.1666)
		(end 432.402742 -139.313412)
		(width 0.1143)
		(layer "F.Cu")
		(net "SATA6G_S1_TX_DN")
	)
	(segment
		(start 409.247086 -130.888486)
		(end 408.352752 -129.994152)
		(width 0.1143)
		(layer "F.Cu")
		(net "SATA6G_S1_TX_DN")
	)
	(segment
		(start 388.816088 -130.454146)
		(end 386.929122 -128.566926)
		(width 0.0889)
		(layer "F.Cu")
		(net "SATA6G_S1_TX_DN")
	)
	(segment
		(start 410.4386 -134.1882)
		(end 410.4386 -133.8453)
		(width 0.1143)
		(layer "F.Cu")
		(net "SATA6G_S1_TX_DN")
	)
	(segment
		(start 397.451834 -132.679694)
		(end 397.429736 -132.679694)
		(width 0.0889)
		(layer "F.Cu")
		(net "SATA6G_S1_TX_DN")
	)
	(segment
		(start 388.816342 -130.454146)
		(end 388.816088 -130.454146)
		(width 0.0889)
		(layer "F.Cu")
		(net "SATA6G_S1_TX_DN")
	)
	(segment
		(start 410.5529 -134.7597)
		(end 410.5529 -134.4168)
		(width 0.1143)
		(layer "F.Cu")
		(net "SATA6G_S1_TX_DN")
	)
	(segment
		(start 422.039542 -138.410442)
		(end 421.696642 -138.410442)
		(width 0.1143)
		(layer "F.Cu")
		(net "SATA6G_S1_TX_DN")
	)
	(segment
		(start 386.842 -126.492)
		(end 386.690362 -126.340362)
		(width 0.0889)
		(layer "F.Cu")
		(net "SATA6G_S1_TX_DN")
	)
	(segment
		(start 418.107114 -136.7155)
		(end 411.8229 -136.7155)
		(width 0.1143)
		(layer "F.Cu")
		(net "SATA6G_S1_TX_DN")
	)
	(segment
		(start 422.611042 -138.296142)
		(end 422.268142 -138.296142)
		(width 0.1143)
		(layer "F.Cu")
		(net "SATA6G_S1_TX_DN")
	)
	(segment
		(start 386.799074 -125.809502)
		(end 386.799074 -125.641608)
		(width 0.0889)
		(layer "F.Cu")
		(net "SATA6G_S1_TX_DN")
	)
	(segment
		(start 409.731972 -131.211828)
		(end 409.489656 -130.969258)
		(width 0.1143)
		(layer "F.Cu")
		(net "SATA6G_S1_TX_DN")
	)
	(segment
		(start 386.68198 -125.447806)
		(end 386.484876 -124.919994)
		(width 0.0889)
		(layer "F.Cu")
		(net "SATA6G_S1_TX_DN")
	)
	(segment
		(start 398.034256 -132.679694)
		(end 397.451834 -132.679694)
		(width 0.1143)
		(layer "F.Cu")
		(net "SATA6G_S1_TX_DN")
	)
	(segment
		(start 423.800524 -137.672572)
		(end 423.800524 -137.86231)
		(width 0.1143)
		(layer "F.Cu")
		(net "SATA6G_S1_TX_DN")
	)
	(segment
		(start 426.473366 -136.7409)
		(end 426.467016 -136.734804)
		(width 0.1143)
		(layer "F.Cu")
		(net "SATA6G_S1_TX_DN")
	)
	(segment
		(start 428.13478 -137.73277)
		(end 427.8122 -137.73277)
		(width 0.1143)
		(layer "F.Cu")
		(net "SATA6G_S1_TX_DN")
	)
	(segment
		(start 407.88463 -129.80035)
		(end 405.007064 -129.80035)
		(width 0.1143)
		(layer "F.Cu")
		(net "SATA6G_S1_TX_DN")
	)
	(segment
		(start 425.744386 -136.435338)
		(end 425.037758 -136.435338)
		(width 0.1143)
		(layer "F.Cu")
		(net "SATA6G_S1_TX_DN")
	)
	(segment
		(start 388.878064 -130.515868)
		(end 388.816342 -130.454146)
		(width 0.0889)
		(layer "F.Cu")
		(net "SATA6G_S1_TX_DN")
	)
	(segment
		(start 427.219872 -137.487406)
		(end 426.473366 -136.7409)
		(width 0.1143)
		(layer "F.Cu")
		(net "SATA6G_S1_TX_DN")
	)
	(segment
		(start 397.429736 -132.679694)
		(end 397.404336 -132.705094)
		(width 0.0889)
		(layer "F.Cu")
		(net "SATA6G_S1_TX_DN")
	)
	(segment
		(start 397.404336 -132.705094)
		(end 393.443714 -132.705094)
		(width 0.0889)
		(layer "F.Cu")
		(net "SATA6G_S1_TX_DN")
	)
	(segment
		(start 391.058908 -130.568954)
		(end 389.005572 -130.568954)
		(width 0.0889)
		(layer "F.Cu")
		(net "SATA6G_S1_TX_DN")
	)
	(segment
		(start 431.990754 -139.7254)
		(end 431.255932 -139.7254)
		(width 0.1143)
		(layer "F.Cu")
		(net "SATA6G_S1_TX_DN")
	)
	(segment
		(start 420.896542 -138.410442)
		(end 420.553642 -138.410442)
		(width 0.1143)
		(layer "F.Cu")
		(net "SATA6G_S1_TX_DN")
	)
	(segment
		(start 386.690362 -126.072138)
		(end 386.799074 -125.809502)
		(width 0.0889)
		(layer "F.Cu")
		(net "SATA6G_S1_TX_DN")
	)
	(segment
		(start 386.799074 -125.641608)
		(end 386.68198 -125.447806)
		(width 0.0889)
		(layer "F.Cu")
		(net "SATA6G_S1_TX_DN")
	)
	(segment
		(start 420.138606 -138.238484)
		(end 418.975286 -137.075164)
		(width 0.1143)
		(layer "F.Cu")
		(net "SATA6G_S1_TX_DN")
	)
	(via
		(at 431.888392 -138.844782)
		(size 0.508)
		(drill 0.254)
		(layers "F.Cu" "B.Cu")
		(net "SATA6G_S1_TX_DN")
	)
	(via
		(at 398.034256 -132.679694)
		(size 0.508)
		(drill 0.254)
		(layers "F.Cu" "B.Cu")
		(net "SATA6G_S1_TX_DN")
	)
	(arc
		(start 391.335006 -130.683254)
		(mid 391.208317 -130.598666)
		(end 391.058908 -130.568954)
		(width 0.0889)
		(layer "F.Cu")
		(net "SATA6G_S1_TX_DN")
	)
	(arc
		(start 432.402742 -139.313412)
		(mid 432.282074 -139.604732)
		(end 431.990754 -139.7254)
		(width 0.1143)
		(layer "F.Cu")
		(net "SATA6G_S1_TX_DN")
	)
	(arc
		(start 427.8122 -137.73277)
		(mid 427.491629 -137.669004)
		(end 427.219872 -137.487406)
		(width 0.1143)
		(layer "F.Cu")
		(net "SATA6G_S1_TX_DN")
	)
	(arc
		(start 410.49575 -134.3025)
		(mid 410.455696 -134.251095)
		(end 410.4386 -134.1882)
		(width 0.1143)
		(layer "F.Cu")
		(net "SATA6G_S1_TX_DN")
	)
	(arc
		(start 408.352752 -129.994152)
		(mid 408.137962 -129.850697)
		(end 407.88463 -129.80035)
		(width 0.1143)
		(layer "F.Cu")
		(net "SATA6G_S1_TX_DN")
	)
	(arc
		(start 409.772358 -131.332986)
		(mid 409.764357 -131.268343)
		(end 409.731972 -131.211828)
		(width 0.1143)
		(layer "F.Cu")
		(net "SATA6G_S1_TX_DN")
	)
	(arc
		(start 423.800524 -137.86231)
		(mid 423.63998 -138.249898)
		(end 423.252392 -138.410442)
		(width 0.1143)
		(layer "F.Cu")
		(net "SATA6G_S1_TX_DN")
	)
	(arc
		(start 422.839642 -138.410442)
		(mid 422.776728 -138.393385)
		(end 422.725342 -138.353292)
		(width 0.1143)
		(layer "F.Cu")
		(net "SATA6G_S1_TX_DN")
	)
	(arc
		(start 421.125142 -138.296142)
		(mid 421.062228 -138.313199)
		(end 421.010842 -138.353292)
		(width 0.1143)
		(layer "F.Cu")
		(net "SATA6G_S1_TX_DN")
	)
	(arc
		(start 431.255932 -139.7254)
		(mid 430.725309 -139.619852)
		(end 430.275492 -139.319254)
		(width 0.1143)
		(layer "F.Cu")
		(net "SATA6G_S1_TX_DN")
	)
	(arc
		(start 410.4386 -133.8453)
		(mid 410.455657 -133.782386)
		(end 410.49575 -133.731)
		(width 0.1143)
		(layer "F.Cu")
		(net "SATA6G_S1_TX_DN")
	)
	(arc
		(start 425.037758 -136.435338)
		(mid 424.162901 -136.797715)
		(end 423.800524 -137.672572)
		(width 0.1143)
		(layer "F.Cu")
		(net "SATA6G_S1_TX_DN")
	)
	(arc
		(start 401.897342 -132.493258)
		(mid 401.69084 -132.631238)
		(end 401.447254 -132.679694)
		(width 0.1143)
		(layer "F.Cu")
		(net "SATA6G_S1_TX_DN")
	)
	(arc
		(start 429.08093 -138.124692)
		(mid 428.646833 -137.834637)
		(end 428.13478 -137.73277)
		(width 0.1143)
		(layer "F.Cu")
		(net "SATA6G_S1_TX_DN")
	)
	(arc
		(start 421.696642 -138.410442)
		(mid 421.633728 -138.393385)
		(end 421.582342 -138.353292)
		(width 0.1143)
		(layer "F.Cu")
		(net "SATA6G_S1_TX_DN")
	)
	(arc
		(start 432.080924 -138.844782)
		(mid 432.308484 -138.93904)
		(end 432.402742 -139.1666)
		(width 0.1143)
		(layer "F.Cu")
		(net "SATA6G_S1_TX_DN")
	)
	(arc
		(start 426.467016 -136.734804)
		(mid 426.135499 -136.513165)
		(end 425.744386 -136.435338)
		(width 0.1143)
		(layer "F.Cu")
		(net "SATA6G_S1_TX_DN")
	)
	(arc
		(start 421.010842 -138.353292)
		(mid 420.959437 -138.393346)
		(end 420.896542 -138.410442)
		(width 0.1143)
		(layer "F.Cu")
		(net "SATA6G_S1_TX_DN")
	)
	(arc
		(start 409.368244 -130.928872)
		(mid 409.303601 -130.920871)
		(end 409.247086 -130.888486)
		(width 0.1143)
		(layer "F.Cu")
		(net "SATA6G_S1_TX_DN")
	)
	(arc
		(start 393.443714 -132.705094)
		(mid 393.36326 -132.689055)
		(end 393.295124 -132.643372)
		(width 0.0889)
		(layer "F.Cu")
		(net "SATA6G_S1_TX_DN")
	)
	(arc
		(start 420.553642 -138.410442)
		(mid 420.329009 -138.36576)
		(end 420.138606 -138.238484)
		(width 0.1143)
		(layer "F.Cu")
		(net "SATA6G_S1_TX_DN")
	)
	(arc
		(start 405.007064 -129.80035)
		(mid 404.622034 -129.876919)
		(end 404.29561 -130.09499)
		(width 0.1143)
		(layer "F.Cu")
		(net "SATA6G_S1_TX_DN")
	)
	(arc
		(start 422.725342 -138.353292)
		(mid 422.673937 -138.313238)
		(end 422.611042 -138.296142)
		(width 0.1143)
		(layer "F.Cu")
		(net "SATA6G_S1_TX_DN")
	)
	(arc
		(start 409.489656 -130.969258)
		(mid 409.433021 -130.936833)
		(end 409.368244 -130.928872)
		(width 0.1143)
		(layer "F.Cu")
		(net "SATA6G_S1_TX_DN")
	)
	(arc
		(start 422.153842 -138.353292)
		(mid 422.102437 -138.393346)
		(end 422.039542 -138.410442)
		(width 0.1143)
		(layer "F.Cu")
		(net "SATA6G_S1_TX_DN")
	)
	(arc
		(start 409.812744 -131.454144)
		(mid 409.780359 -131.397629)
		(end 409.772358 -131.332986)
		(width 0.1143)
		(layer "F.Cu")
		(net "SATA6G_S1_TX_DN")
	)
	(arc
		(start 421.582342 -138.353292)
		(mid 421.530937 -138.313238)
		(end 421.468042 -138.296142)
		(width 0.1143)
		(layer "F.Cu")
		(net "SATA6G_S1_TX_DN")
	)
	(arc
		(start 410.49575 -134.874)
		(mid 410.535804 -134.822595)
		(end 410.5529 -134.7597)
		(width 0.1143)
		(layer "F.Cu")
		(net "SATA6G_S1_TX_DN")
	)
	(arc
		(start 386.929122 -128.566926)
		(mid 386.864648 -128.470434)
		(end 386.842 -128.356614)
		(width 0.0889)
		(layer "F.Cu")
		(net "SATA6G_S1_TX_DN")
	)
	(arc
		(start 410.5529 -134.4168)
		(mid 410.535843 -134.353886)
		(end 410.49575 -134.3025)
		(width 0.1143)
		(layer "F.Cu")
		(net "SATA6G_S1_TX_DN")
	)
	(arc
		(start 418.975286 -137.075164)
		(mid 418.576965 -136.809015)
		(end 418.107114 -136.7155)
		(width 0.1143)
		(layer "F.Cu")
		(net "SATA6G_S1_TX_DN")
	)
	(arc
		(start 410.5529 -133.2738)
		(mid 410.535843 -133.210886)
		(end 410.49575 -133.1595)
		(width 0.1143)
		(layer "F.Cu")
		(net "SATA6G_S1_TX_DN")
	)
	(arc
		(start 411.8229 -136.7155)
		(mid 410.844052 -136.310048)
		(end 410.4386 -135.3312)
		(width 0.1143)
		(layer "F.Cu")
		(net "SATA6G_S1_TX_DN")
	)
	(arc
		(start 389.005572 -130.568954)
		(mid 388.93653 -130.555109)
		(end 388.878064 -130.515868)
		(width 0.0889)
		(layer "F.Cu")
		(net "SATA6G_S1_TX_DN")
	)
	(arc
		(start 410.4386 -132.62229)
		(mid 410.338984 -132.121396)
		(end 410.055314 -131.696714)
		(width 0.1143)
		(layer "F.Cu")
		(net "SATA6G_S1_TX_DN")
	)
	(arc
		(start 410.4386 -134.9883)
		(mid 410.455657 -134.925386)
		(end 410.49575 -134.874)
		(width 0.1143)
		(layer "F.Cu")
		(net "SATA6G_S1_TX_DN")
	)
	(arc
		(start 410.49575 -133.731)
		(mid 410.535804 -133.679595)
		(end 410.5529 -133.6167)
		(width 0.1143)
		(layer "F.Cu")
		(net "SATA6G_S1_TX_DN")
	)
	(arc
		(start 410.49575 -133.1595)
		(mid 410.455696 -133.108095)
		(end 410.4386 -133.0452)
		(width 0.1143)
		(layer "F.Cu")
		(net "SATA6G_S1_TX_DN")
	)
	(arc
		(start 422.268142 -138.296142)
		(mid 422.205228 -138.313199)
		(end 422.153842 -138.353292)
		(width 0.1143)
		(layer "F.Cu")
		(net "SATA6G_S1_TX_DN")
	)
	(segment
		(start 432.022758 -141.379956)
		(end 431.74412 -141.101318)
		(width 0.1143)
		(layer "B.Cu")
		(net "SATA6G_S1_TX_DN")
	)
	(segment
		(start 433.113434 -141.10589)
		(end 433.113434 -141.261338)
		(width 0.1143)
		(layer "B.Cu")
		(net "SATA6G_S1_TX_DN")
	)
	(segment
		(start 431.888392 -138.844782)
		(end 432.412394 -138.844782)
		(width 0.1143)
		(layer "B.Cu")
		(net "SATA6G_S1_TX_DN")
	)
	(segment
		(start 432.999134 -140.53439)
		(end 432.999134 -140.87729)
		(width 0.1143)
		(layer "B.Cu")
		(net "SATA6G_S1_TX_DN")
	)
	(segment
		(start 432.539394 -138.971782)
		(end 432.539394 -139.124182)
		(width 0.1143)
		(layer "B.Cu")
		(net "SATA6G_S1_TX_DN")
	)
	(segment
		(start 433.113434 -139.903454)
		(end 433.113434 -140.30579)
		(width 0.1143)
		(layer "B.Cu")
		(net "SATA6G_S1_TX_DN")
	)
	(segment
		(start 432.920394 -141.454378)
		(end 432.202336 -141.454378)
		(width 0.1143)
		(layer "B.Cu")
		(net "SATA6G_S1_TX_DN")
	)
	(segment
		(start 432.647344 -139.384786)
		(end 433.07635 -139.813792)
		(width 0.1143)
		(layer "B.Cu")
		(net "SATA6G_S1_TX_DN")
	)
	(arc
		(start 432.539394 -139.124182)
		(mid 432.567464 -139.265207)
		(end 432.647344 -139.384786)
		(width 0.1143)
		(layer "B.Cu")
		(net "SATA6G_S1_TX_DN")
	)
	(arc
		(start 433.113434 -140.30579)
		(mid 433.096377 -140.368704)
		(end 433.056284 -140.42009)
		(width 0.1143)
		(layer "B.Cu")
		(net "SATA6G_S1_TX_DN")
	)
	(arc
		(start 433.113434 -141.261338)
		(mid 433.056894 -141.397838)
		(end 432.920394 -141.454378)
		(width 0.1143)
		(layer "B.Cu")
		(net "SATA6G_S1_TX_DN")
	)
	(arc
		(start 432.999134 -140.87729)
		(mid 433.016191 -140.940204)
		(end 433.056284 -140.99159)
		(width 0.1143)
		(layer "B.Cu")
		(net "SATA6G_S1_TX_DN")
	)
	(arc
		(start 432.202336 -141.454378)
		(mid 432.105134 -141.435043)
		(end 432.022758 -141.379956)
		(width 0.1143)
		(layer "B.Cu")
		(net "SATA6G_S1_TX_DN")
	)
	(arc
		(start 433.056284 -140.42009)
		(mid 433.01623 -140.471495)
		(end 432.999134 -140.53439)
		(width 0.1143)
		(layer "B.Cu")
		(net "SATA6G_S1_TX_DN")
	)
	(arc
		(start 433.056284 -140.99159)
		(mid 433.096338 -141.042995)
		(end 433.113434 -141.10589)
		(width 0.1143)
		(layer "B.Cu")
		(net "SATA6G_S1_TX_DN")
	)
	(arc
		(start 433.07635 -139.813792)
		(mid 433.103783 -139.854943)
		(end 433.113434 -139.903454)
		(width 0.1143)
		(layer "B.Cu")
		(net "SATA6G_S1_TX_DN")
	)
	(arc
		(start 432.412394 -138.844782)
		(mid 432.502197 -138.881979)
		(end 432.539394 -138.971782)
		(width 0.1143)
		(layer "B.Cu")
		(net "SATA6G_S1_TX_DN")
	)
	(segment
		(start 430.33442 -136.911842)
		(end 430.33442 -136.97077)
		(width 0.1143)
		(layer "B.Cu")
		(net "SATA6G_S1_TX_C_DP")
	)
	(segment
		(start 430.630584 -141.714982)
		(end 430.85512 -141.939518)
		(width 0.1143)
		(layer "B.Cu")
		(net "SATA6G_S1_TX_C_DP")
	)
	(segment
		(start 429.795686 -137.714482)
		(end 429.795686 -141.11986)
		(width 0.1143)
		(layer "B.Cu")
		(net "SATA6G_S1_TX_C_DP")
	)
	(segment
		(start 429.82007 -136.344914)
		(end 430.297336 -136.82218)
		(width 0.1143)
		(layer "B.Cu")
		(net "SATA6G_S1_TX_C_DP")
	)
	(segment
		(start 430.297082 -137.06094)
		(end 429.90389 -137.454132)
		(width 0.1143)
		(layer "B.Cu")
		(net "SATA6G_S1_TX_C_DP")
	)
	(segment
		(start 430.353724 -141.677898)
		(end 430.540922 -141.677898)
		(width 0.1143)
		(layer "B.Cu")
		(net "SATA6G_S1_TX_C_DP")
	)
	(arc
		(start 430.33442 -136.97077)
		(mid 430.324714 -137.019565)
		(end 430.297082 -137.06094)
		(width 0.1143)
		(layer "B.Cu")
		(net "SATA6G_S1_TX_C_DP")
	)
	(arc
		(start 430.297336 -136.82218)
		(mid 430.324769 -136.863331)
		(end 430.33442 -136.911842)
		(width 0.1143)
		(layer "B.Cu")
		(net "SATA6G_S1_TX_C_DP")
	)
	(arc
		(start 430.540922 -141.677898)
		(mid 430.58944 -141.687531)
		(end 430.630584 -141.714982)
		(width 0.1143)
		(layer "B.Cu")
		(net "SATA6G_S1_TX_C_DP")
	)
	(arc
		(start 429.90389 -137.454132)
		(mid 429.82391 -137.573552)
		(end 429.795686 -137.714482)
		(width 0.1143)
		(layer "B.Cu")
		(net "SATA6G_S1_TX_C_DP")
	)
	(arc
		(start 429.795686 -141.11986)
		(mid 429.959132 -141.514452)
		(end 430.353724 -141.677898)
		(width 0.1143)
		(layer "B.Cu")
		(net "SATA6G_S1_TX_C_DP")
	)
	(segment
		(start 430.036986 -137.892282)
		(end 430.036986 -137.71499)
		(width 0.1143)
		(layer "B.Cu")
		(net "SATA6G_S1_TX_C_DN")
	)
	(segment
		(start 430.151286 -138.463782)
		(end 430.151286 -138.120882)
		(width 0.1143)
		(layer "B.Cu")
		(net "SATA6G_S1_TX_C_DN")
	)
	(segment
		(start 430.036986 -139.035282)
		(end 430.036986 -138.692382)
		(width 0.1143)
		(layer "B.Cu")
		(net "SATA6G_S1_TX_C_DN")
	)
	(segment
		(start 430.036986 -140.178282)
		(end 430.036986 -139.835382)
		(width 0.1143)
		(layer "B.Cu")
		(net "SATA6G_S1_TX_C_DN")
	)
	(segment
		(start 430.151286 -139.606782)
		(end 430.151286 -139.263882)
		(width 0.1143)
		(layer "B.Cu")
		(net "SATA6G_S1_TX_C_DN")
	)
	(segment
		(start 430.178718 -137.52068)
		(end 430.46777 -137.231628)
		(width 0.1143)
		(layer "B.Cu")
		(net "SATA6G_S1_TX_C_DN")
	)
	(segment
		(start 430.036986 -141.11986)
		(end 430.036986 -140.978382)
		(width 0.1143)
		(layer "B.Cu")
		(net "SATA6G_S1_TX_C_DN")
	)
	(segment
		(start 430.467262 -141.436598)
		(end 430.353724 -141.436598)
		(width 0.1143)
		(layer "B.Cu")
		(net "SATA6G_S1_TX_C_DN")
	)
	(segment
		(start 430.57572 -136.97077)
		(end 430.57572 -136.783826)
		(width 0.1143)
		(layer "B.Cu")
		(net "SATA6G_S1_TX_C_DN")
	)
	(segment
		(start 430.151286 -140.749782)
		(end 430.151286 -140.406882)
		(width 0.1143)
		(layer "B.Cu")
		(net "SATA6G_S1_TX_C_DN")
	)
	(segment
		(start 430.074578 -137.625074)
		(end 430.178718 -137.52068)
		(width 0.1143)
		(layer "B.Cu")
		(net "SATA6G_S1_TX_C_DN")
	)
	(segment
		(start 430.85512 -141.101318)
		(end 430.556924 -141.399514)
		(width 0.1143)
		(layer "B.Cu")
		(net "SATA6G_S1_TX_C_DN")
	)
	(arc
		(start 430.094136 -140.864082)
		(mid 430.13419 -140.812677)
		(end 430.151286 -140.749782)
		(width 0.1143)
		(layer "B.Cu")
		(net "SATA6G_S1_TX_C_DN")
	)
	(arc
		(start 430.556924 -141.399514)
		(mid 430.515773 -141.426947)
		(end 430.467262 -141.436598)
		(width 0.1143)
		(layer "B.Cu")
		(net "SATA6G_S1_TX_C_DN")
	)
	(arc
		(start 430.036986 -139.835382)
		(mid 430.054043 -139.772468)
		(end 430.094136 -139.721082)
		(width 0.1143)
		(layer "B.Cu")
		(net "SATA6G_S1_TX_C_DN")
	)
	(arc
		(start 430.151286 -140.406882)
		(mid 430.134229 -140.343968)
		(end 430.094136 -140.292582)
		(width 0.1143)
		(layer "B.Cu")
		(net "SATA6G_S1_TX_C_DN")
	)
	(arc
		(start 430.036986 -138.692382)
		(mid 430.054043 -138.629468)
		(end 430.094136 -138.578082)
		(width 0.1143)
		(layer "B.Cu")
		(net "SATA6G_S1_TX_C_DN")
	)
	(arc
		(start 430.57572 -136.783826)
		(mid 430.731665 -136.445719)
		(end 431.09007 -136.344914)
		(width 0.1143)
		(layer "B.Cu")
		(net "SATA6G_S1_TX_C_DN")
	)
	(arc
		(start 430.151286 -138.120882)
		(mid 430.134229 -138.057968)
		(end 430.094136 -138.006582)
		(width 0.1143)
		(layer "B.Cu")
		(net "SATA6G_S1_TX_C_DN")
	)
	(arc
		(start 430.036986 -137.71499)
		(mid 430.046873 -137.666317)
		(end 430.074578 -137.625074)
		(width 0.1143)
		(layer "B.Cu")
		(net "SATA6G_S1_TX_C_DN")
	)
	(arc
		(start 430.151286 -139.263882)
		(mid 430.134229 -139.200968)
		(end 430.094136 -139.149582)
		(width 0.1143)
		(layer "B.Cu")
		(net "SATA6G_S1_TX_C_DN")
	)
	(arc
		(start 430.46777 -137.231628)
		(mid 430.547686 -137.111931)
		(end 430.57572 -136.97077)
		(width 0.1143)
		(layer "B.Cu")
		(net "SATA6G_S1_TX_C_DN")
	)
	(arc
		(start 430.353724 -141.436598)
		(mid 430.129756 -141.343828)
		(end 430.036986 -141.11986)
		(width 0.1143)
		(layer "B.Cu")
		(net "SATA6G_S1_TX_C_DN")
	)
	(arc
		(start 430.094136 -140.292582)
		(mid 430.054082 -140.241177)
		(end 430.036986 -140.178282)
		(width 0.1143)
		(layer "B.Cu")
		(net "SATA6G_S1_TX_C_DN")
	)
	(arc
		(start 430.094136 -139.721082)
		(mid 430.13419 -139.669677)
		(end 430.151286 -139.606782)
		(width 0.1143)
		(layer "B.Cu")
		(net "SATA6G_S1_TX_C_DN")
	)
	(arc
		(start 430.036986 -140.978382)
		(mid 430.054043 -140.915468)
		(end 430.094136 -140.864082)
		(width 0.1143)
		(layer "B.Cu")
		(net "SATA6G_S1_TX_C_DN")
	)
	(arc
		(start 430.094136 -139.149582)
		(mid 430.054082 -139.098177)
		(end 430.036986 -139.035282)
		(width 0.1143)
		(layer "B.Cu")
		(net "SATA6G_S1_TX_C_DN")
	)
	(arc
		(start 430.094136 -138.006582)
		(mid 430.054082 -137.955177)
		(end 430.036986 -137.892282)
		(width 0.1143)
		(layer "B.Cu")
		(net "SATA6G_S1_TX_C_DN")
	)
	(arc
		(start 430.094136 -138.578082)
		(mid 430.13419 -138.526677)
		(end 430.151286 -138.463782)
		(width 0.1143)
		(layer "B.Cu")
		(net "SATA6G_S1_TX_C_DN")
	)
	(segment
		(start 392.69035 -121.01576)
		(end 393.18565 -121.245884)
		(width 0.1143)
		(layer "F.Cu")
		(net "SATA6G_S1_RX_DP")
	)
	(via
		(at 393.18565 -121.245884)
		(size 0.508)
		(drill 0.254)
		(layers "F.Cu" "B.Cu")
		(net "SATA6G_S1_RX_DP")
	)
	(via
		(at 400.419316 -138.952224)
		(size 0.508)
		(drill 0.254)
		(layers "F.Cu" "B.Cu")
		(net "SATA6G_S1_RX_DP")
	)
	(segment
		(start 400.419316 -138.952224)
		(end 397.22044 -135.753348)
		(width 0.1143)
		(layer "B.Cu")
		(net "SATA6G_S1_RX_DP")
	)
	(segment
		(start 396.085568 -135.71982)
		(end 396.060168 -135.69442)
		(width 0.0889)
		(layer "B.Cu")
		(net "SATA6G_S1_RX_DP")
	)
	(segment
		(start 432.849274 -142.6718)
		(end 434.516784 -142.6718)
		(width 0.1143)
		(layer "B.Cu")
		(net "SATA6G_S1_RX_DP")
	)
	(segment
		(start 418.747956 -138.59002)
		(end 419.89375 -137.44448)
		(width 0.1143)
		(layer "B.Cu")
		(net "SATA6G_S1_RX_DP")
	)
	(segment
		(start 402.196554 -140.326618)
		(end 409.653232 -140.326618)
		(width 0.1143)
		(layer "B.Cu")
		(net "SATA6G_S1_RX_DP")
	)
	(segment
		(start 435.314852 -141.891512)
		(end 435.381654 -141.891512)
		(width 0.1143)
		(layer "B.Cu")
		(net "SATA6G_S1_RX_DP")
	)
	(segment
		(start 429.520604 -142.9131)
		(end 432.36388 -142.9131)
		(width 0.1143)
		(layer "B.Cu")
		(net "SATA6G_S1_RX_DP")
	)
	(segment
		(start 390.6139 -122.9741)
		(end 390.6139 -122.951748)
		(width 0.0889)
		(layer "B.Cu")
		(net "SATA6G_S1_RX_DP")
	)
	(segment
		(start 390.6139 -121.25706)
		(end 390.6139 -121.224294)
		(width 0.0889)
		(layer "B.Cu")
		(net "SATA6G_S1_RX_DP")
	)
	(segment
		(start 420.1922 -136.796526)
		(end 420.1922 -135.201914)
		(width 0.1143)
		(layer "B.Cu")
		(net "SATA6G_S1_RX_DP")
	)
	(segment
		(start 410.237178 -140.02639)
		(end 415.280602 -140.02639)
		(width 0.1143)
		(layer "B.Cu")
		(net "SATA6G_S1_RX_DP")
	)
	(segment
		(start 432.699668 -142.773908)
		(end 432.768248 -142.705328)
		(width 0.1143)
		(layer "B.Cu")
		(net "SATA6G_S1_RX_DP")
	)
	(segment
		(start 397.139668 -135.71982)
		(end 396.107666 -135.71982)
		(width 0.1143)
		(layer "B.Cu")
		(net "SATA6G_S1_RX_DP")
	)
	(segment
		(start 427.727364 -137.803128)
		(end 427.727364 -137.803382)
		(width 0.1143)
		(layer "B.Cu")
		(net "SATA6G_S1_RX_DP")
	)
	(segment
		(start 426.68317 -136.75868)
		(end 427.727364 -137.803128)
		(width 0.1143)
		(layer "B.Cu")
		(net "SATA6G_S1_RX_DP")
	)
	(segment
		(start 396.107666 -135.71982)
		(end 396.085568 -135.71982)
		(width 0.0889)
		(layer "B.Cu")
		(net "SATA6G_S1_RX_DP")
	)
	(segment
		(start 390.733788 -124.78385)
		(end 390.200388 -124.25045)
		(width 0.0889)
		(layer "B.Cu")
		(net "SATA6G_S1_RX_DP")
	)
	(segment
		(start 395.352524 -135.612632)
		(end 390.878314 -131.138422)
		(width 0.0889)
		(layer "B.Cu")
		(net "SATA6G_S1_RX_DP")
	)
	(segment
		(start 427.727364 -137.803382)
		(end 428.771558 -138.848084)
		(width 0.1143)
		(layer "B.Cu")
		(net "SATA6G_S1_RX_DP")
	)
	(segment
		(start 428.80534 -138.92911)
		(end 428.80534 -142.197836)
		(width 0.1143)
		(layer "B.Cu")
		(net "SATA6G_S1_RX_DP")
	)
	(segment
		(start 400.419316 -138.952224)
		(end 401.50923 -140.042138)
		(width 0.1143)
		(layer "B.Cu")
		(net "SATA6G_S1_RX_DP")
	)
	(segment
		(start 391.1092 -120.39854)
		(end 391.1092 -120.365774)
		(width 0.0889)
		(layer "B.Cu")
		(net "SATA6G_S1_RX_DP")
	)
	(segment
		(start 396.060168 -135.69442)
		(end 395.550136 -135.69442)
		(width 0.0889)
		(layer "B.Cu")
		(net "SATA6G_S1_RX_DP")
	)
	(segment
		(start 425.662852 -136.719818)
		(end 426.589444 -136.719818)
		(width 0.1143)
		(layer "B.Cu")
		(net "SATA6G_S1_RX_DP")
	)
	(segment
		(start 390.1186 -124.052838)
		(end 390.1186 -123.799854)
		(width 0.0889)
		(layer "B.Cu")
		(net "SATA6G_S1_RX_DP")
	)
	(segment
		(start 420.374826 -135.019288)
		(end 423.517568 -135.019288)
		(width 0.1143)
		(layer "B.Cu")
		(net "SATA6G_S1_RX_DP")
	)
	(segment
		(start 390.75995 -130.852672)
		(end 390.75995 -124.846842)
		(width 0.0889)
		(layer "B.Cu")
		(net "SATA6G_S1_RX_DP")
	)
	(segment
		(start 410.002482 -140.181838)
		(end 410.10205 -140.08227)
		(width 0.1143)
		(layer "B.Cu")
		(net "SATA6G_S1_RX_DP")
	)
	(segment
		(start 423.82186 -135.145272)
		(end 425.207938 -136.53135)
		(width 0.1143)
		(layer "B.Cu")
		(net "SATA6G_S1_RX_DP")
	)
	(segment
		(start 393.2809 -120.365774)
		(end 393.2809 -120.408954)
		(width 0.0889)
		(layer "B.Cu")
		(net "SATA6G_S1_RX_DP")
	)
	(segment
		(start 390.1186 -122.125994)
		(end 390.1186 -122.082814)
		(width 0.0889)
		(layer "B.Cu")
		(net "SATA6G_S1_RX_DP")
	)
	(segment
		(start 419.89375 -137.44448)
		(end 419.993572 -137.329418)
		(width 0.1143)
		(layer "B.Cu")
		(net "SATA6G_S1_RX_DP")
	)
	(arc
		(start 432.36388 -142.9131)
		(mid 432.545608 -142.876876)
		(end 432.699668 -142.773908)
		(width 0.1143)
		(layer "B.Cu")
		(net "SATA6G_S1_RX_DP")
	)
	(arc
		(start 390.909048 -120.734074)
		(mid 391.052852 -120.592391)
		(end 391.1092 -120.39854)
		(width 0.0889)
		(layer "B.Cu")
		(net "SATA6G_S1_RX_DP")
	)
	(arc
		(start 390.6139 -122.951748)
		(mid 390.55755 -122.757898)
		(end 390.413748 -122.616214)
		(width 0.0889)
		(layer "B.Cu")
		(net "SATA6G_S1_RX_DP")
	)
	(arc
		(start 432.768248 -142.705328)
		(mid 432.805423 -142.680488)
		(end 432.849274 -142.6718)
		(width 0.1143)
		(layer "B.Cu")
		(net "SATA6G_S1_RX_DP")
	)
	(arc
		(start 425.207938 -136.53135)
		(mid 425.416654 -136.67081)
		(end 425.662852 -136.719818)
		(width 0.1143)
		(layer "B.Cu")
		(net "SATA6G_S1_RX_DP")
	)
	(arc
		(start 434.840888 -142.537688)
		(mid 434.93079 -142.402956)
		(end 434.9623 -142.244064)
		(width 0.1143)
		(layer "B.Cu")
		(net "SATA6G_S1_RX_DP")
	)
	(arc
		(start 392.985752 -119.875554)
		(mid 393.196616 -120.082558)
		(end 393.2809 -120.365774)
		(width 0.0889)
		(layer "B.Cu")
		(net "SATA6G_S1_RX_DP")
	)
	(arc
		(start 415.280602 -140.02639)
		(mid 417.157122 -139.653033)
		(end 418.747956 -138.59002)
		(width 0.1143)
		(layer "B.Cu")
		(net "SATA6G_S1_RX_DP")
	)
	(arc
		(start 390.1186 -123.799854)
		(mid 390.202881 -123.516637)
		(end 390.413748 -123.309634)
		(width 0.0889)
		(layer "B.Cu")
		(net "SATA6G_S1_RX_DP")
	)
	(arc
		(start 390.413748 -122.616214)
		(mid 390.202884 -122.40921)
		(end 390.1186 -122.125994)
		(width 0.0889)
		(layer "B.Cu")
		(net "SATA6G_S1_RX_DP")
	)
	(arc
		(start 397.22044 -135.753348)
		(mid 397.183381 -135.728586)
		(end 397.139668 -135.71982)
		(width 0.1143)
		(layer "B.Cu")
		(net "SATA6G_S1_RX_DP")
	)
	(arc
		(start 390.413748 -121.592594)
		(mid 390.557552 -121.450911)
		(end 390.6139 -121.25706)
		(width 0.0889)
		(layer "B.Cu")
		(net "SATA6G_S1_RX_DP")
	)
	(arc
		(start 391.404348 -119.875554)
		(mid 391.69975 -119.796423)
		(end 391.995152 -119.875554)
		(width 0.0889)
		(layer "B.Cu")
		(net "SATA6G_S1_RX_DP")
	)
	(arc
		(start 390.6139 -121.224294)
		(mid 390.698181 -120.941077)
		(end 390.909048 -120.734074)
		(width 0.0889)
		(layer "B.Cu")
		(net "SATA6G_S1_RX_DP")
	)
	(arc
		(start 423.517568 -135.019288)
		(mid 423.682242 -135.052026)
		(end 423.82186 -135.145272)
		(width 0.1143)
		(layer "B.Cu")
		(net "SATA6G_S1_RX_DP")
	)
	(arc
		(start 395.550136 -135.69442)
		(mid 395.443214 -135.673152)
		(end 395.352524 -135.612632)
		(width 0.0889)
		(layer "B.Cu")
		(net "SATA6G_S1_RX_DP")
	)
	(arc
		(start 419.993572 -137.329418)
		(mid 420.066509 -137.231081)
		(end 420.123874 -137.122916)
		(width 0.1143)
		(layer "B.Cu")
		(net "SATA6G_S1_RX_DP")
	)
	(arc
		(start 434.516784 -142.6718)
		(mid 434.692189 -142.637003)
		(end 434.840888 -142.537688)
		(width 0.1143)
		(layer "B.Cu")
		(net "SATA6G_S1_RX_DP")
	)
	(arc
		(start 420.123874 -137.122916)
		(mid 420.174928 -136.963259)
		(end 420.1922 -136.796526)
		(width 0.1143)
		(layer "B.Cu")
		(net "SATA6G_S1_RX_DP")
	)
	(arc
		(start 391.1092 -120.365774)
		(mid 391.193481 -120.082557)
		(end 391.404348 -119.875554)
		(width 0.0889)
		(layer "B.Cu")
		(net "SATA6G_S1_RX_DP")
	)
	(arc
		(start 426.589444 -136.719818)
		(mid 426.640169 -136.729926)
		(end 426.68317 -136.75868)
		(width 0.1143)
		(layer "B.Cu")
		(net "SATA6G_S1_RX_DP")
	)
	(arc
		(start 393.2809 -120.408954)
		(mid 393.257012 -120.830121)
		(end 393.18565 -121.245884)
		(width 0.0889)
		(layer "B.Cu")
		(net "SATA6G_S1_RX_DP")
	)
	(arc
		(start 392.394948 -119.875554)
		(mid 392.69035 -119.796423)
		(end 392.985752 -119.875554)
		(width 0.0889)
		(layer "B.Cu")
		(net "SATA6G_S1_RX_DP")
	)
	(arc
		(start 409.653232 -140.326618)
		(mid 409.84225 -140.288944)
		(end 410.002482 -140.181838)
		(width 0.1143)
		(layer "B.Cu")
		(net "SATA6G_S1_RX_DP")
	)
	(arc
		(start 390.200388 -124.25045)
		(mid 390.139807 -124.159785)
		(end 390.1186 -124.052838)
		(width 0.0889)
		(layer "B.Cu")
		(net "SATA6G_S1_RX_DP")
	)
	(arc
		(start 390.413748 -123.309634)
		(mid 390.557552 -123.167951)
		(end 390.6139 -122.9741)
		(width 0.0889)
		(layer "B.Cu")
		(net "SATA6G_S1_RX_DP")
	)
	(arc
		(start 390.878314 -131.138422)
		(mid 390.790714 -131.007319)
		(end 390.75995 -130.852672)
		(width 0.0889)
		(layer "B.Cu")
		(net "SATA6G_S1_RX_DP")
	)
	(arc
		(start 401.50923 -140.042138)
		(mid 401.824593 -140.252734)
		(end 402.196554 -140.326618)
		(width 0.1143)
		(layer "B.Cu")
		(net "SATA6G_S1_RX_DP")
	)
	(arc
		(start 420.1922 -135.201914)
		(mid 420.24569 -135.072778)
		(end 420.374826 -135.019288)
		(width 0.1143)
		(layer "B.Cu")
		(net "SATA6G_S1_RX_DP")
	)
	(arc
		(start 391.995152 -119.875554)
		(mid 392.19505 -119.929053)
		(end 392.394948 -119.875554)
		(width 0.0889)
		(layer "B.Cu")
		(net "SATA6G_S1_RX_DP")
	)
	(arc
		(start 390.75995 -124.846842)
		(mid 390.753148 -124.812738)
		(end 390.733788 -124.78385)
		(width 0.0889)
		(layer "B.Cu")
		(net "SATA6G_S1_RX_DP")
	)
	(arc
		(start 390.1186 -122.082814)
		(mid 390.202881 -121.799597)
		(end 390.413748 -121.592594)
		(width 0.0889)
		(layer "B.Cu")
		(net "SATA6G_S1_RX_DP")
	)
	(arc
		(start 428.80534 -142.197836)
		(mid 429.014836 -142.703604)
		(end 429.520604 -142.9131)
		(width 0.1143)
		(layer "B.Cu")
		(net "SATA6G_S1_RX_DP")
	)
	(arc
		(start 428.771558 -138.848084)
		(mid 428.79648 -138.885244)
		(end 428.80534 -138.92911)
		(width 0.1143)
		(layer "B.Cu")
		(net "SATA6G_S1_RX_DP")
	)
	(arc
		(start 410.10205 -140.08227)
		(mid 410.164047 -140.040845)
		(end 410.237178 -140.02639)
		(width 0.1143)
		(layer "B.Cu")
		(net "SATA6G_S1_RX_DP")
	)
	(arc
		(start 434.9623 -142.244064)
		(mid 435.06556 -141.994772)
		(end 435.314852 -141.891512)
		(width 0.1143)
		(layer "B.Cu")
		(net "SATA6G_S1_RX_DP")
	)
	(segment
		(start 392.19505 -120.15724)
		(end 392.69035 -120.387364)
		(width 0.1143)
		(layer "F.Cu")
		(net "SATA6G_S1_RX_DN")
	)
	(via
		(at 392.69035 -120.387364)
		(size 0.508)
		(drill 0.254)
		(layers "F.Cu" "B.Cu")
		(net "SATA6G_S1_RX_DN")
	)
	(via
		(at 397.680434 -135.871966)
		(size 0.508)
		(drill 0.254)
		(layers "F.Cu" "B.Cu")
		(net "SATA6G_S1_RX_DN")
	)
	(segment
		(start 434.368194 -141.891512)
		(end 434.365654 -141.891512)
		(width 0.1143)
		(layer "B.Cu")
		(net "SATA6G_S1_RX_DN")
	)
	(segment
		(start 390.3091 -122.11558)
		(end 390.3091 -122.093228)
		(width 0.0889)
		(layer "B.Cu")
		(net "SATA6G_S1_RX_DN")
	)
	(segment
		(start 428.700184 -138.434826)
		(end 428.9425 -138.677396)
		(width 0.1143)
		(layer "B.Cu")
		(net "SATA6G_S1_RX_DN")
	)
	(segment
		(start 428.376842 -137.94994)
		(end 428.619412 -138.19251)
		(width 0.1143)
		(layer "B.Cu")
		(net "SATA6G_S1_RX_DN")
	)
	(segment
		(start 396.060168 -135.50392)
		(end 395.549882 -135.50392)
		(width 0.0889)
		(layer "B.Cu")
		(net "SATA6G_S1_RX_DN")
	)
	(segment
		(start 392.836146 -132.700776)
		(end 392.647678 -132.512308)
		(width 0.0889)
		(layer "B.Cu")
		(net "SATA6G_S1_RX_DN")
	)
	(segment
		(start 391.578846 -131.443476)
		(end 391.390378 -131.255008)
		(width 0.0889)
		(layer "B.Cu")
		(net "SATA6G_S1_RX_DN")
	)
	(segment
		(start 412.522924 -139.78509)
		(end 412.865824 -139.78509)
		(width 0.1143)
		(layer "B.Cu")
		(net "SATA6G_S1_RX_DN")
	)
	(segment
		(start 425.662852 -136.478518)
		(end 426.589698 -136.478518)
		(width 0.1143)
		(layer "B.Cu")
		(net "SATA6G_S1_RX_DN")
	)
	(segment
		(start 391.03935 -129.200402)
		(end 391.03935 -128.933702)
		(width 0.0889)
		(layer "B.Cu")
		(net "SATA6G_S1_RX_DN")
	)
	(segment
		(start 419.716712 -137.279888)
		(end 419.810946 -137.171176)
		(width 0.1143)
		(layer "B.Cu")
		(net "SATA6G_S1_RX_DN")
	)
	(segment
		(start 394.973556 -134.963916)
		(end 394.785088 -134.775448)
		(width 0.0889)
		(layer "B.Cu")
		(net "SATA6G_S1_RX_DN")
	)
	(segment
		(start 394.722096 -134.586726)
		(end 394.533628 -134.398258)
		(width 0.0889)
		(layer "B.Cu")
		(net "SATA6G_S1_RX_DN")
	)
	(segment
		(start 392.207496 -132.072126)
		(end 392.019028 -131.883658)
		(width 0.0889)
		(layer "B.Cu")
		(net "SATA6G_S1_RX_DN")
	)
	(segment
		(start 390.3091 -124.053092)
		(end 390.3091 -123.810268)
		(width 0.0889)
		(layer "B.Cu")
		(net "SATA6G_S1_RX_DN")
	)
	(segment
		(start 429.520604 -142.6718)
		(end 431.006504 -142.6718)
		(width 0.1143)
		(layer "B.Cu")
		(net "SATA6G_S1_RX_DN")
	)
	(segment
		(start 429.04664 -138.92911)
		(end 429.04664 -142.197836)
		(width 0.1143)
		(layer "B.Cu")
		(net "SATA6G_S1_RX_DN")
	)
	(segment
		(start 413.094424 -139.67079)
		(end 413.437324 -139.67079)
		(width 0.1143)
		(layer "B.Cu")
		(net "SATA6G_S1_RX_DN")
	)
	(segment
		(start 390.309354 -124.052838)
		(end 390.3091 -124.053092)
		(width 0.0889)
		(layer "B.Cu")
		(net "SATA6G_S1_RX_DN")
	)
	(segment
		(start 432.52898 -142.60322)
		(end 432.59756 -142.53464)
		(width 0.1143)
		(layer "B.Cu")
		(net "SATA6G_S1_RX_DN")
	)
	(segment
		(start 391.03935 -126.533402)
		(end 391.03935 -126.266702)
		(width 0.0889)
		(layer "B.Cu")
		(net "SATA6G_S1_RX_DN")
	)
	(segment
		(start 390.95045 -125.199902)
		(end 390.95045 -124.847096)
		(width 0.0889)
		(layer "B.Cu")
		(net "SATA6G_S1_RX_DN")
	)
	(segment
		(start 391.03935 -127.422402)
		(end 391.03935 -127.155702)
		(width 0.0889)
		(layer "B.Cu")
		(net "SATA6G_S1_RX_DN")
	)
	(segment
		(start 391.03935 -128.311402)
		(end 391.03935 -128.044702)
		(width 0.0889)
		(layer "B.Cu")
		(net "SATA6G_S1_RX_DN")
	)
	(segment
		(start 396.107666 -135.47852)
		(end 396.085568 -135.47852)
		(width 0.0889)
		(layer "B.Cu")
		(net "SATA6G_S1_RX_DN")
	)
	(segment
		(start 390.95045 -127.866902)
		(end 390.95045 -127.600202)
		(width 0.0889)
		(layer "B.Cu")
		(net "SATA6G_S1_RX_DN")
	)
	(segment
		(start 396.085568 -135.47852)
		(end 396.060168 -135.50392)
		(width 0.0889)
		(layer "B.Cu")
		(net "SATA6G_S1_RX_DN")
	)
	(segment
		(start 402.1963 -140.085318)
		(end 409.652978 -140.085318)
		(width 0.1143)
		(layer "B.Cu")
		(net "SATA6G_S1_RX_DN")
	)
	(segment
		(start 393.0904 -120.376188)
		(end 393.0904 -120.408954)
		(width 0.0889)
		(layer "B.Cu")
		(net "SATA6G_S1_RX_DN")
	)
	(segment
		(start 432.849274 -142.4305)
		(end 434.516784 -142.4305)
		(width 0.1143)
		(layer "B.Cu")
		(net "SATA6G_S1_RX_DN")
	)
	(segment
		(start 411.379924 -139.78509)
		(end 411.722824 -139.78509)
		(width 0.1143)
		(layer "B.Cu")
		(net "SATA6G_S1_RX_DN")
	)
	(segment
		(start 390.95045 -128.755902)
		(end 390.95045 -128.489202)
		(width 0.0889)
		(layer "B.Cu")
		(net "SATA6G_S1_RX_DN")
	)
	(segment
		(start 431.806604 -142.6718)
		(end 432.363626 -142.6718)
		(width 0.1143)
		(layer "B.Cu")
		(net "SATA6G_S1_RX_DN")
	)
	(segment
		(start 427.89221 -137.626344)
		(end 428.134526 -137.868914)
		(width 0.1143)
		(layer "B.Cu")
		(net "SATA6G_S1_RX_DN")
	)
	(segment
		(start 395.487398 -135.477758)
		(end 395.413738 -135.404098)
		(width 0.0889)
		(layer "B.Cu")
		(net "SATA6G_S1_RX_DN")
	)
	(segment
		(start 397.139922 -135.47852)
		(end 396.107666 -135.47852)
		(width 0.1143)
		(layer "B.Cu")
		(net "SATA6G_S1_RX_DN")
	)
	(segment
		(start 390.868408 -124.648976)
		(end 390.335262 -124.115576)
		(width 0.0889)
		(layer "B.Cu")
		(net "SATA6G_S1_RX_DN")
	)
	(segment
		(start 431.235104 -142.5575)
		(end 431.578004 -142.5575)
		(width 0.1143)
		(layer "B.Cu")
		(net "SATA6G_S1_RX_DN")
	)
	(segment
		(start 423.992548 -134.974584)
		(end 425.378626 -136.360662)
		(width 0.1143)
		(layer "B.Cu")
		(net "SATA6G_S1_RX_DN")
	)
	(segment
		(start 393.082272 -120.646698)
		(end 393.082272 -120.647206)
		(width 0.0889)
		(layer "B.Cu")
		(net "SATA6G_S1_RX_DN")
	)
	(segment
		(start 410.236924 -139.78509)
		(end 410.579824 -139.78509)
		(width 0.1143)
		(layer "B.Cu")
		(net "SATA6G_S1_RX_DN")
	)
	(segment
		(start 427.568868 -137.141458)
		(end 427.811184 -137.384028)
		(width 0.1143)
		(layer "B.Cu")
		(net "SATA6G_S1_RX_DN")
	)
	(segment
		(start 391.2997 -120.408954)
		(end 391.2997 -120.376188)
		(width 0.0889)
		(layer "B.Cu")
		(net "SATA6G_S1_RX_DN")
	)
	(segment
		(start 390.95045 -129.644902)
		(end 390.95045 -129.378202)
		(width 0.0889)
		(layer "B.Cu")
		(net "SATA6G_S1_RX_DN")
	)
	(segment
		(start 390.95045 -126.977902)
		(end 390.95045 -126.711202)
		(width 0.0889)
		(layer "B.Cu")
		(net "SATA6G_S1_RX_DN")
	)
	(segment
		(start 393.464796 -133.329426)
		(end 393.276328 -133.140958)
		(width 0.0889)
		(layer "B.Cu")
		(net "SATA6G_S1_RX_DN")
	)
	(segment
		(start 419.950646 -136.796526)
		(end 419.9509 -136.79678)
		(width 0.1143)
		(layer "B.Cu")
		(net "SATA6G_S1_RX_DN")
	)
	(segment
		(start 391.830306 -131.820666)
		(end 391.641838 -131.632198)
		(width 0.0889)
		(layer "B.Cu")
		(net "SATA6G_S1_RX_DN")
	)
	(segment
		(start 391.03935 -130.089402)
		(end 391.03935 -129.822702)
		(width 0.0889)
		(layer "B.Cu")
		(net "SATA6G_S1_RX_DN")
	)
	(segment
		(start 409.831794 -140.01115)
		(end 409.931362 -139.911582)
		(width 0.1143)
		(layer "B.Cu")
		(net "SATA6G_S1_RX_DN")
	)
	(segment
		(start 392.458956 -132.449316)
		(end 392.270488 -132.260848)
		(width 0.0889)
		(layer "B.Cu")
		(net "SATA6G_S1_RX_DN")
	)
	(segment
		(start 397.680434 -135.871966)
		(end 397.391128 -135.58266)
		(width 0.1143)
		(layer "B.Cu")
		(net "SATA6G_S1_RX_DN")
	)
	(segment
		(start 413.665924 -139.78509)
		(end 415.280348 -139.78509)
		(width 0.1143)
		(layer "B.Cu")
		(net "SATA6G_S1_RX_DN")
	)
	(segment
		(start 394.344906 -134.335266)
		(end 394.156438 -134.146798)
		(width 0.0889)
		(layer "B.Cu")
		(net "SATA6G_S1_RX_DN")
	)
	(segment
		(start 393.087606 -133.077966)
		(end 392.899138 -132.889498)
		(width 0.0889)
		(layer "B.Cu")
		(net "SATA6G_S1_RX_DN")
	)
	(segment
		(start 397.680434 -135.871966)
		(end 401.679918 -139.87145)
		(width 0.1143)
		(layer "B.Cu")
		(net "SATA6G_S1_RX_DN")
	)
	(segment
		(start 392.864594 -120.836944)
		(end 392.86434 -120.836944)
		(width 0.0889)
		(layer "B.Cu")
		(net "SATA6G_S1_RX_DN")
	)
	(segment
		(start 390.95045 -126.088902)
		(end 390.95045 -125.822202)
		(width 0.0889)
		(layer "B.Cu")
		(net "SATA6G_S1_RX_DN")
	)
	(segment
		(start 390.95045 -130.852672)
		(end 390.95045 -130.267202)
		(width 0.0889)
		(layer "B.Cu")
		(net "SATA6G_S1_RX_DN")
	)
	(segment
		(start 418.577268 -138.419332)
		(end 419.716712 -137.279888)
		(width 0.1143)
		(layer "B.Cu")
		(net "SATA6G_S1_RX_DN")
	)
	(segment
		(start 419.9509 -136.79678)
		(end 419.9509 -135.201914)
		(width 0.1143)
		(layer "B.Cu")
		(net "SATA6G_S1_RX_DN")
	)
	(segment
		(start 391.201656 -131.192016)
		(end 391.013188 -131.003548)
		(width 0.0889)
		(layer "B.Cu")
		(net "SATA6G_S1_RX_DN")
	)
	(segment
		(start 394.093446 -133.958076)
		(end 393.904978 -133.769608)
		(width 0.0889)
		(layer "B.Cu")
		(net "SATA6G_S1_RX_DN")
	)
	(segment
		(start 411.951424 -139.67079)
		(end 412.294324 -139.67079)
		(width 0.1143)
		(layer "B.Cu")
		(net "SATA6G_S1_RX_DN")
	)
	(segment
		(start 420.374826 -134.777988)
		(end 423.517568 -134.777988)
		(width 0.1143)
		(layer "B.Cu")
		(net "SATA6G_S1_RX_DN")
	)
	(segment
		(start 390.8044 -121.267474)
		(end 390.8044 -121.234708)
		(width 0.0889)
		(layer "B.Cu")
		(net "SATA6G_S1_RX_DN")
	)
	(segment
		(start 410.808424 -139.67079)
		(end 411.151324 -139.67079)
		(width 0.1143)
		(layer "B.Cu")
		(net "SATA6G_S1_RX_DN")
	)
	(segment
		(start 391.03935 -125.644402)
		(end 391.03935 -125.377702)
		(width 0.0889)
		(layer "B.Cu")
		(net "SATA6G_S1_RX_DN")
	)
	(segment
		(start 390.8044 -122.984514)
		(end 390.8044 -122.941334)
		(width 0.0889)
		(layer "B.Cu")
		(net "SATA6G_S1_RX_DN")
	)
	(segment
		(start 426.853858 -136.587992)
		(end 427.326298 -137.060686)
		(width 0.1143)
		(layer "B.Cu")
		(net "SATA6G_S1_RX_DN")
	)
	(segment
		(start 392.674602 -120.61952)
		(end 392.69035 -120.387364)
		(width 0.0889)
		(layer "B.Cu")
		(net "SATA6G_S1_RX_DN")
	)
	(segment
		(start 395.350746 -135.215376)
		(end 395.162278 -135.026908)
		(width 0.0889)
		(layer "B.Cu")
		(net "SATA6G_S1_RX_DN")
	)
	(segment
		(start 393.716256 -133.706616)
		(end 393.527788 -133.518148)
		(width 0.0889)
		(layer "B.Cu")
		(net "SATA6G_S1_RX_DN")
	)
	(arc
		(start 411.722824 -139.78509)
		(mid 411.785738 -139.768033)
		(end 411.837124 -139.72794)
		(width 0.1143)
		(layer "B.Cu")
		(net "SATA6G_S1_RX_DN")
	)
	(arc
		(start 427.811184 -137.384028)
		(mid 427.843569 -137.440543)
		(end 427.85157 -137.505186)
		(width 0.1143)
		(layer "B.Cu")
		(net "SATA6G_S1_RX_DN")
	)
	(arc
		(start 431.692304 -142.61465)
		(mid 431.743709 -142.654704)
		(end 431.806604 -142.6718)
		(width 0.1143)
		(layer "B.Cu")
		(net "SATA6G_S1_RX_DN")
	)
	(arc
		(start 390.95045 -125.822202)
		(mid 390.964515 -125.773676)
		(end 390.9949 -125.733302)
		(width 0.0889)
		(layer "B.Cu")
		(net "SATA6G_S1_RX_DN")
	)
	(arc
		(start 427.85157 -137.505186)
		(mid 427.859686 -137.569859)
		(end 427.89221 -137.626344)
		(width 0.1143)
		(layer "B.Cu")
		(net "SATA6G_S1_RX_DN")
	)
	(arc
		(start 427.326298 -137.060686)
		(mid 427.382933 -137.093111)
		(end 427.44771 -137.101072)
		(width 0.1143)
		(layer "B.Cu")
		(net "SATA6G_S1_RX_DN")
	)
	(arc
		(start 419.90264 -137.026142)
		(mid 419.938568 -136.913825)
		(end 419.950646 -136.796526)
		(width 0.1143)
		(layer "B.Cu")
		(net "SATA6G_S1_RX_DN")
	)
	(arc
		(start 390.8044 -121.234708)
		(mid 390.86075 -121.040858)
		(end 391.004552 -120.899174)
		(width 0.0889)
		(layer "B.Cu")
		(net "SATA6G_S1_RX_DN")
	)
	(arc
		(start 392.490452 -120.040654)
		(mid 392.69035 -119.987155)
		(end 392.890248 -120.040654)
		(width 0.0889)
		(layer "B.Cu")
		(net "SATA6G_S1_RX_DN")
	)
	(arc
		(start 394.753592 -134.681214)
		(mid 394.746586 -134.63105)
		(end 394.722096 -134.586726)
		(width 0.0889)
		(layer "B.Cu")
		(net "SATA6G_S1_RX_DN")
	)
	(arc
		(start 390.9949 -127.511302)
		(mid 391.025321 -127.470946)
		(end 391.03935 -127.422402)
		(width 0.0889)
		(layer "B.Cu")
		(net "SATA6G_S1_RX_DN")
	)
	(arc
		(start 390.9949 -128.400302)
		(mid 391.025321 -128.359946)
		(end 391.03935 -128.311402)
		(width 0.0889)
		(layer "B.Cu")
		(net "SATA6G_S1_RX_DN")
	)
	(arc
		(start 432.363626 -142.6718)
		(mid 432.453149 -142.653993)
		(end 432.52898 -142.60322)
		(width 0.1143)
		(layer "B.Cu")
		(net "SATA6G_S1_RX_DN")
	)
	(arc
		(start 390.509252 -121.757694)
		(mid 390.720116 -121.55069)
		(end 390.8044 -121.267474)
		(width 0.0889)
		(layer "B.Cu")
		(net "SATA6G_S1_RX_DN")
	)
	(arc
		(start 412.408624 -139.72794)
		(mid 412.460029 -139.767994)
		(end 412.522924 -139.78509)
		(width 0.1143)
		(layer "B.Cu")
		(net "SATA6G_S1_RX_DN")
	)
	(arc
		(start 428.255684 -137.909554)
		(mid 428.320327 -137.917555)
		(end 428.376842 -137.94994)
		(width 0.1143)
		(layer "B.Cu")
		(net "SATA6G_S1_RX_DN")
	)
	(arc
		(start 394.533628 -134.398258)
		(mid 394.489397 -134.373906)
		(end 394.439394 -134.366762)
		(width 0.0889)
		(layer "B.Cu")
		(net "SATA6G_S1_RX_DN")
	)
	(arc
		(start 391.03935 -128.933702)
		(mid 391.025285 -128.885176)
		(end 390.9949 -128.844802)
		(width 0.0889)
		(layer "B.Cu")
		(net "SATA6G_S1_RX_DN")
	)
	(arc
		(start 394.439394 -134.366762)
		(mid 394.38923 -134.359756)
		(end 394.344906 -134.335266)
		(width 0.0889)
		(layer "B.Cu")
		(net "SATA6G_S1_RX_DN")
	)
	(arc
		(start 419.9509 -135.201914)
		(mid 420.075065 -134.902153)
		(end 420.374826 -134.777988)
		(width 0.1143)
		(layer "B.Cu")
		(net "SATA6G_S1_RX_DN")
	)
	(arc
		(start 390.9949 -125.733302)
		(mid 391.025321 -125.692946)
		(end 391.03935 -125.644402)
		(width 0.0889)
		(layer "B.Cu")
		(net "SATA6G_S1_RX_DN")
	)
	(arc
		(start 393.0904 -120.408954)
		(mid 393.088338 -120.527894)
		(end 393.082272 -120.646698)
		(width 0.0889)
		(layer "B.Cu")
		(net "SATA6G_S1_RX_DN")
	)
	(arc
		(start 390.9949 -129.289302)
		(mid 391.025321 -129.248946)
		(end 391.03935 -129.200402)
		(width 0.0889)
		(layer "B.Cu")
		(net "SATA6G_S1_RX_DN")
	)
	(arc
		(start 390.509252 -122.451114)
		(mid 390.365448 -122.309431)
		(end 390.3091 -122.11558)
		(width 0.0889)
		(layer "B.Cu")
		(net "SATA6G_S1_RX_DN")
	)
	(arc
		(start 390.9949 -128.844802)
		(mid 390.964479 -128.804446)
		(end 390.95045 -128.755902)
		(width 0.0889)
		(layer "B.Cu")
		(net "SATA6G_S1_RX_DN")
	)
	(arc
		(start 393.496292 -133.423914)
		(mid 393.489286 -133.37375)
		(end 393.464796 -133.329426)
		(width 0.0889)
		(layer "B.Cu")
		(net "SATA6G_S1_RX_DN")
	)
	(arc
		(start 427.44771 -137.101072)
		(mid 427.512353 -137.109073)
		(end 427.568868 -137.141458)
		(width 0.1143)
		(layer "B.Cu")
		(net "SATA6G_S1_RX_DN")
	)
	(arc
		(start 429.04664 -142.197836)
		(mid 429.185461 -142.532979)
		(end 429.520604 -142.6718)
		(width 0.1143)
		(layer "B.Cu")
		(net "SATA6G_S1_RX_DN")
	)
	(arc
		(start 390.95045 -126.711202)
		(mid 390.964515 -126.662676)
		(end 390.9949 -126.622302)
		(width 0.0889)
		(layer "B.Cu")
		(net "SATA6G_S1_RX_DN")
	)
	(arc
		(start 434.721 -142.244318)
		(mid 434.617666 -141.994846)
		(end 434.368194 -141.891512)
		(width 0.1143)
		(layer "B.Cu")
		(net "SATA6G_S1_RX_DN")
	)
	(arc
		(start 397.391128 -135.58266)
		(mid 397.275875 -135.50562)
		(end 397.139922 -135.47852)
		(width 0.1143)
		(layer "B.Cu")
		(net "SATA6G_S1_RX_DN")
	)
	(arc
		(start 393.182094 -133.109462)
		(mid 393.13193 -133.102456)
		(end 393.087606 -133.077966)
		(width 0.0889)
		(layer "B.Cu")
		(net "SATA6G_S1_RX_DN")
	)
	(arc
		(start 392.867642 -132.795264)
		(mid 392.860636 -132.7451)
		(end 392.836146 -132.700776)
		(width 0.0889)
		(layer "B.Cu")
		(net "SATA6G_S1_RX_DN")
	)
	(arc
		(start 392.019028 -131.883658)
		(mid 391.974797 -131.859306)
		(end 391.924794 -131.852162)
		(width 0.0889)
		(layer "B.Cu")
		(net "SATA6G_S1_RX_DN")
	)
	(arc
		(start 393.082272 -120.647206)
		(mid 393.012729 -120.787158)
		(end 392.864594 -120.836944)
		(width 0.0889)
		(layer "B.Cu")
		(net "SATA6G_S1_RX_DN")
	)
	(arc
		(start 394.785088 -134.775448)
		(mid 394.760736 -134.731217)
		(end 394.753592 -134.681214)
		(width 0.0889)
		(layer "B.Cu")
		(net "SATA6G_S1_RX_DN")
	)
	(arc
		(start 393.527788 -133.518148)
		(mid 393.503436 -133.473917)
		(end 393.496292 -133.423914)
		(width 0.0889)
		(layer "B.Cu")
		(net "SATA6G_S1_RX_DN")
	)
	(arc
		(start 395.413738 -135.404098)
		(mid 395.389386 -135.359867)
		(end 395.382242 -135.309864)
		(width 0.0889)
		(layer "B.Cu")
		(net "SATA6G_S1_RX_DN")
	)
	(arc
		(start 390.95045 -129.378202)
		(mid 390.964515 -129.329676)
		(end 390.9949 -129.289302)
		(width 0.0889)
		(layer "B.Cu")
		(net "SATA6G_S1_RX_DN")
	)
	(arc
		(start 390.8044 -122.941334)
		(mid 390.720119 -122.658117)
		(end 390.509252 -122.451114)
		(width 0.0889)
		(layer "B.Cu")
		(net "SATA6G_S1_RX_DN")
	)
	(arc
		(start 410.579824 -139.78509)
		(mid 410.642738 -139.768033)
		(end 410.694124 -139.72794)
		(width 0.1143)
		(layer "B.Cu")
		(net "SATA6G_S1_RX_DN")
	)
	(arc
		(start 395.549882 -135.50392)
		(mid 395.516052 -135.497022)
		(end 395.487398 -135.477758)
		(width 0.0889)
		(layer "B.Cu")
		(net "SATA6G_S1_RX_DN")
	)
	(arc
		(start 411.265624 -139.72794)
		(mid 411.317029 -139.767994)
		(end 411.379924 -139.78509)
		(width 0.1143)
		(layer "B.Cu")
		(net "SATA6G_S1_RX_DN")
	)
	(arc
		(start 419.810946 -137.171176)
		(mid 419.862256 -137.102114)
		(end 419.90264 -137.026142)
		(width 0.1143)
		(layer "B.Cu")
		(net "SATA6G_S1_RX_DN")
	)
	(arc
		(start 411.837124 -139.72794)
		(mid 411.888529 -139.687886)
		(end 411.951424 -139.67079)
		(width 0.1143)
		(layer "B.Cu")
		(net "SATA6G_S1_RX_DN")
	)
	(arc
		(start 390.95045 -127.600202)
		(mid 390.964515 -127.551676)
		(end 390.9949 -127.511302)
		(width 0.0889)
		(layer "B.Cu")
		(net "SATA6G_S1_RX_DN")
	)
	(arc
		(start 390.9949 -126.177802)
		(mid 390.964479 -126.137446)
		(end 390.95045 -126.088902)
		(width 0.0889)
		(layer "B.Cu")
		(net "SATA6G_S1_RX_DN")
	)
	(arc
		(start 401.679918 -139.87145)
		(mid 401.916822 -140.029807)
		(end 402.1963 -140.085318)
		(width 0.1143)
		(layer "B.Cu")
		(net "SATA6G_S1_RX_DN")
	)
	(arc
		(start 390.509252 -123.474734)
		(mid 390.720116 -123.26773)
		(end 390.8044 -122.984514)
		(width 0.0889)
		(layer "B.Cu")
		(net "SATA6G_S1_RX_DN")
	)
	(arc
		(start 392.553444 -132.480812)
		(mid 392.50328 -132.473806)
		(end 392.458956 -132.449316)
		(width 0.0889)
		(layer "B.Cu")
		(net "SATA6G_S1_RX_DN")
	)
	(arc
		(start 391.03935 -127.155702)
		(mid 391.025285 -127.107176)
		(end 390.9949 -127.066802)
		(width 0.0889)
		(layer "B.Cu")
		(net "SATA6G_S1_RX_DN")
	)
	(arc
		(start 428.619412 -138.19251)
		(mid 428.651797 -138.249025)
		(end 428.659798 -138.313668)
		(width 0.1143)
		(layer "B.Cu")
		(net "SATA6G_S1_RX_DN")
	)
	(arc
		(start 391.013188 -131.003548)
		(mid 390.966798 -130.934355)
		(end 390.95045 -130.852672)
		(width 0.0889)
		(layer "B.Cu")
		(net "SATA6G_S1_RX_DN")
	)
	(arc
		(start 428.9425 -138.677396)
		(mid 429.019559 -138.792912)
		(end 429.04664 -138.92911)
		(width 0.1143)
		(layer "B.Cu")
		(net "SATA6G_S1_RX_DN")
	)
	(arc
		(start 395.162278 -135.026908)
		(mid 395.118047 -135.002556)
		(end 395.068044 -134.995412)
		(width 0.0889)
		(layer "B.Cu")
		(net "SATA6G_S1_RX_DN")
	)
	(arc
		(start 391.899648 -120.040654)
		(mid 392.19505 -120.119785)
		(end 392.490452 -120.040654)
		(width 0.0889)
		(layer "B.Cu")
		(net "SATA6G_S1_RX_DN")
	)
	(arc
		(start 413.437324 -139.67079)
		(mid 413.500238 -139.687847)
		(end 413.551624 -139.72794)
		(width 0.1143)
		(layer "B.Cu")
		(net "SATA6G_S1_RX_DN")
	)
	(arc
		(start 392.890248 -120.040654)
		(mid 393.034052 -120.182337)
		(end 393.0904 -120.376188)
		(width 0.0889)
		(layer "B.Cu")
		(net "SATA6G_S1_RX_DN")
	)
	(arc
		(start 390.335262 -124.115576)
		(mid 390.316029 -124.086792)
		(end 390.309354 -124.052838)
		(width 0.0889)
		(layer "B.Cu")
		(net "SATA6G_S1_RX_DN")
	)
	(arc
		(start 391.924794 -131.852162)
		(mid 391.87463 -131.845156)
		(end 391.830306 -131.820666)
		(width 0.0889)
		(layer "B.Cu")
		(net "SATA6G_S1_RX_DN")
	)
	(arc
		(start 390.3091 -122.093228)
		(mid 390.36545 -121.899378)
		(end 390.509252 -121.757694)
		(width 0.0889)
		(layer "B.Cu")
		(net "SATA6G_S1_RX_DN")
	)
	(arc
		(start 395.382242 -135.309864)
		(mid 395.375236 -135.2597)
		(end 395.350746 -135.215376)
		(width 0.0889)
		(layer "B.Cu")
		(net "SATA6G_S1_RX_DN")
	)
	(arc
		(start 392.86434 -120.836944)
		(mid 392.72441 -120.76756)
		(end 392.674602 -120.61952)
		(width 0.0889)
		(layer "B.Cu")
		(net "SATA6G_S1_RX_DN")
	)
	(arc
		(start 391.03935 -125.377702)
		(mid 391.025285 -125.329176)
		(end 390.9949 -125.288802)
		(width 0.0889)
		(layer "B.Cu")
		(net "SATA6G_S1_RX_DN")
	)
	(arc
		(start 409.652978 -140.085318)
		(mid 409.749791 -140.066061)
		(end 409.831794 -140.01115)
		(width 0.1143)
		(layer "B.Cu")
		(net "SATA6G_S1_RX_DN")
	)
	(arc
		(start 415.280348 -139.78509)
		(mid 417.064663 -139.43015)
		(end 418.577268 -138.419332)
		(width 0.1143)
		(layer "B.Cu")
		(net "SATA6G_S1_RX_DN")
	)
	(arc
		(start 390.9949 -125.288802)
		(mid 390.964479 -125.248446)
		(end 390.95045 -125.199902)
		(width 0.0889)
		(layer "B.Cu")
		(net "SATA6G_S1_RX_DN")
	)
	(arc
		(start 413.551624 -139.72794)
		(mid 413.603029 -139.767994)
		(end 413.665924 -139.78509)
		(width 0.1143)
		(layer "B.Cu")
		(net "SATA6G_S1_RX_DN")
	)
	(arc
		(start 390.9949 -129.733802)
		(mid 390.964479 -129.693446)
		(end 390.95045 -129.644902)
		(width 0.0889)
		(layer "B.Cu")
		(net "SATA6G_S1_RX_DN")
	)
	(arc
		(start 409.931362 -139.911582)
		(mid 410.071569 -139.817962)
		(end 410.236924 -139.78509)
		(width 0.1143)
		(layer "B.Cu")
		(net "SATA6G_S1_RX_DN")
	)
	(arc
		(start 391.390378 -131.255008)
		(mid 391.346147 -131.230656)
		(end 391.296144 -131.223512)
		(width 0.0889)
		(layer "B.Cu")
		(net "SATA6G_S1_RX_DN")
	)
	(arc
		(start 425.378626 -136.360662)
		(mid 425.509001 -136.447903)
		(end 425.662852 -136.478518)
		(width 0.1143)
		(layer "B.Cu")
		(net "SATA6G_S1_RX_DN")
	)
	(arc
		(start 394.124942 -134.052564)
		(mid 394.117936 -134.0024)
		(end 394.093446 -133.958076)
		(width 0.0889)
		(layer "B.Cu")
		(net "SATA6G_S1_RX_DN")
	)
	(arc
		(start 412.980124 -139.72794)
		(mid 413.031529 -139.687886)
		(end 413.094424 -139.67079)
		(width 0.1143)
		(layer "B.Cu")
		(net "SATA6G_S1_RX_DN")
	)
	(arc
		(start 393.276328 -133.140958)
		(mid 393.232097 -133.116606)
		(end 393.182094 -133.109462)
		(width 0.0889)
		(layer "B.Cu")
		(net "SATA6G_S1_RX_DN")
	)
	(arc
		(start 410.694124 -139.72794)
		(mid 410.745529 -139.687886)
		(end 410.808424 -139.67079)
		(width 0.1143)
		(layer "B.Cu")
		(net "SATA6G_S1_RX_DN")
	)
	(arc
		(start 392.647678 -132.512308)
		(mid 392.603447 -132.487956)
		(end 392.553444 -132.480812)
		(width 0.0889)
		(layer "B.Cu")
		(net "SATA6G_S1_RX_DN")
	)
	(arc
		(start 434.6702 -142.367)
		(mid 434.70781 -142.310713)
		(end 434.721 -142.244318)
		(width 0.1143)
		(layer "B.Cu")
		(net "SATA6G_S1_RX_DN")
	)
	(arc
		(start 391.004552 -120.899174)
		(mid 391.215416 -120.69217)
		(end 391.2997 -120.408954)
		(width 0.0889)
		(layer "B.Cu")
		(net "SATA6G_S1_RX_DN")
	)
	(arc
		(start 391.610342 -131.537964)
		(mid 391.603336 -131.4878)
		(end 391.578846 -131.443476)
		(width 0.0889)
		(layer "B.Cu")
		(net "SATA6G_S1_RX_DN")
	)
	(arc
		(start 432.59756 -142.53464)
		(mid 432.713076 -142.457581)
		(end 432.849274 -142.4305)
		(width 0.1143)
		(layer "B.Cu")
		(net "SATA6G_S1_RX_DN")
	)
	(arc
		(start 431.578004 -142.5575)
		(mid 431.640918 -142.574557)
		(end 431.692304 -142.61465)
		(width 0.1143)
		(layer "B.Cu")
		(net "SATA6G_S1_RX_DN")
	)
	(arc
		(start 390.95045 -130.267202)
		(mid 390.964515 -130.218676)
		(end 390.9949 -130.178302)
		(width 0.0889)
		(layer "B.Cu")
		(net "SATA6G_S1_RX_DN")
	)
	(arc
		(start 390.9949 -127.066802)
		(mid 390.964479 -127.026446)
		(end 390.95045 -126.977902)
		(width 0.0889)
		(layer "B.Cu")
		(net "SATA6G_S1_RX_DN")
	)
	(arc
		(start 390.3091 -123.810268)
		(mid 390.36545 -123.616418)
		(end 390.509252 -123.474734)
		(width 0.0889)
		(layer "B.Cu")
		(net "SATA6G_S1_RX_DN")
	)
	(arc
		(start 390.95045 -124.847096)
		(mid 390.929162 -124.739872)
		(end 390.868408 -124.648976)
		(width 0.0889)
		(layer "B.Cu")
		(net "SATA6G_S1_RX_DN")
	)
	(arc
		(start 428.659798 -138.313668)
		(mid 428.667799 -138.378311)
		(end 428.700184 -138.434826)
		(width 0.1143)
		(layer "B.Cu")
		(net "SATA6G_S1_RX_DN")
	)
	(arc
		(start 390.95045 -128.489202)
		(mid 390.964515 -128.440676)
		(end 390.9949 -128.400302)
		(width 0.0889)
		(layer "B.Cu")
		(net "SATA6G_S1_RX_DN")
	)
	(arc
		(start 391.2997 -120.376188)
		(mid 391.35605 -120.182338)
		(end 391.499852 -120.040654)
		(width 0.0889)
		(layer "B.Cu")
		(net "SATA6G_S1_RX_DN")
	)
	(arc
		(start 391.499852 -120.040654)
		(mid 391.69975 -119.987155)
		(end 391.899648 -120.040654)
		(width 0.0889)
		(layer "B.Cu")
		(net "SATA6G_S1_RX_DN")
	)
	(arc
		(start 431.120804 -142.61465)
		(mid 431.172209 -142.574596)
		(end 431.235104 -142.5575)
		(width 0.1143)
		(layer "B.Cu")
		(net "SATA6G_S1_RX_DN")
	)
	(arc
		(start 392.899138 -132.889498)
		(mid 392.874786 -132.845267)
		(end 392.867642 -132.795264)
		(width 0.0889)
		(layer "B.Cu")
		(net "SATA6G_S1_RX_DN")
	)
	(arc
		(start 390.9949 -126.622302)
		(mid 391.025321 -126.581946)
		(end 391.03935 -126.533402)
		(width 0.0889)
		(layer "B.Cu")
		(net "SATA6G_S1_RX_DN")
	)
	(arc
		(start 434.516784 -142.4305)
		(mid 434.599794 -142.413988)
		(end 434.6702 -142.367)
		(width 0.1143)
		(layer "B.Cu")
		(net "SATA6G_S1_RX_DN")
	)
	(arc
		(start 391.296144 -131.223512)
		(mid 391.24598 -131.216506)
		(end 391.201656 -131.192016)
		(width 0.0889)
		(layer "B.Cu")
		(net "SATA6G_S1_RX_DN")
	)
	(arc
		(start 392.238992 -132.166614)
		(mid 392.231986 -132.11645)
		(end 392.207496 -132.072126)
		(width 0.0889)
		(layer "B.Cu")
		(net "SATA6G_S1_RX_DN")
	)
	(arc
		(start 393.810744 -133.738112)
		(mid 393.76058 -133.731106)
		(end 393.716256 -133.706616)
		(width 0.0889)
		(layer "B.Cu")
		(net "SATA6G_S1_RX_DN")
	)
	(arc
		(start 431.006504 -142.6718)
		(mid 431.069418 -142.654743)
		(end 431.120804 -142.61465)
		(width 0.1143)
		(layer "B.Cu")
		(net "SATA6G_S1_RX_DN")
	)
	(arc
		(start 395.068044 -134.995412)
		(mid 395.01788 -134.988406)
		(end 394.973556 -134.963916)
		(width 0.0889)
		(layer "B.Cu")
		(net "SATA6G_S1_RX_DN")
	)
	(arc
		(start 391.03935 -126.266702)
		(mid 391.025285 -126.218176)
		(end 390.9949 -126.177802)
		(width 0.0889)
		(layer "B.Cu")
		(net "SATA6G_S1_RX_DN")
	)
	(arc
		(start 412.865824 -139.78509)
		(mid 412.928738 -139.768033)
		(end 412.980124 -139.72794)
		(width 0.1143)
		(layer "B.Cu")
		(net "SATA6G_S1_RX_DN")
	)
	(arc
		(start 423.517568 -134.777988)
		(mid 423.774597 -134.829079)
		(end 423.992548 -134.974584)
		(width 0.1143)
		(layer "B.Cu")
		(net "SATA6G_S1_RX_DN")
	)
	(arc
		(start 394.156438 -134.146798)
		(mid 394.132086 -134.102567)
		(end 394.124942 -134.052564)
		(width 0.0889)
		(layer "B.Cu")
		(net "SATA6G_S1_RX_DN")
	)
	(arc
		(start 391.03935 -129.822702)
		(mid 391.025285 -129.774176)
		(end 390.9949 -129.733802)
		(width 0.0889)
		(layer "B.Cu")
		(net "SATA6G_S1_RX_DN")
	)
	(arc
		(start 393.904978 -133.769608)
		(mid 393.860747 -133.745256)
		(end 393.810744 -133.738112)
		(width 0.0889)
		(layer "B.Cu")
		(net "SATA6G_S1_RX_DN")
	)
	(arc
		(start 390.9949 -130.178302)
		(mid 391.025321 -130.137946)
		(end 391.03935 -130.089402)
		(width 0.0889)
		(layer "B.Cu")
		(net "SATA6G_S1_RX_DN")
	)
	(arc
		(start 390.9949 -127.955802)
		(mid 390.964479 -127.915446)
		(end 390.95045 -127.866902)
		(width 0.0889)
		(layer "B.Cu")
		(net "SATA6G_S1_RX_DN")
	)
	(arc
		(start 391.03935 -128.044702)
		(mid 391.025285 -127.996176)
		(end 390.9949 -127.955802)
		(width 0.0889)
		(layer "B.Cu")
		(net "SATA6G_S1_RX_DN")
	)
	(arc
		(start 411.151324 -139.67079)
		(mid 411.214238 -139.687847)
		(end 411.265624 -139.72794)
		(width 0.1143)
		(layer "B.Cu")
		(net "SATA6G_S1_RX_DN")
	)
	(arc
		(start 412.294324 -139.67079)
		(mid 412.357238 -139.687847)
		(end 412.408624 -139.72794)
		(width 0.1143)
		(layer "B.Cu")
		(net "SATA6G_S1_RX_DN")
	)
	(arc
		(start 426.589698 -136.478518)
		(mid 426.732642 -136.507027)
		(end 426.853858 -136.587992)
		(width 0.1143)
		(layer "B.Cu")
		(net "SATA6G_S1_RX_DN")
	)
	(arc
		(start 391.641838 -131.632198)
		(mid 391.617486 -131.587967)
		(end 391.610342 -131.537964)
		(width 0.0889)
		(layer "B.Cu")
		(net "SATA6G_S1_RX_DN")
	)
	(arc
		(start 392.270488 -132.260848)
		(mid 392.246136 -132.216617)
		(end 392.238992 -132.166614)
		(width 0.0889)
		(layer "B.Cu")
		(net "SATA6G_S1_RX_DN")
	)
	(arc
		(start 428.134526 -137.868914)
		(mid 428.191012 -137.901434)
		(end 428.255684 -137.909554)
		(width 0.1143)
		(layer "B.Cu")
		(net "SATA6G_S1_RX_DN")
	)
	(segment
		(start 434.110892 -136.825736)
		(end 433.63007 -136.344914)
		(width 0.1143)
		(layer "B.Cu")
		(net "SATA6G_S1_RX_C_DN")
	)
	(segment
		(start 434.719476 -137.899648)
		(end 434.24856 -137.428732)
		(width 0.1143)
		(layer "B.Cu")
		(net "SATA6G_S1_RX_C_DN")
	)
	(segment
		(start 434.365654 -141.002512)
		(end 434.719476 -140.64869)
		(width 0.1143)
		(layer "B.Cu")
		(net "SATA6G_S1_RX_C_DN")
	)
	(segment
		(start 434.753004 -140.567918)
		(end 434.753004 -137.980166)
		(width 0.1143)
		(layer "B.Cu")
		(net "SATA6G_S1_RX_C_DN")
	)
	(segment
		(start 434.753004 -137.980166)
		(end 434.75275 -137.98042)
		(width 0.1143)
		(layer "B.Cu")
		(net "SATA6G_S1_RX_C_DN")
	)
	(segment
		(start 434.14442 -137.177526)
		(end 434.14442 -136.906508)
		(width 0.1143)
		(layer "B.Cu")
		(net "SATA6G_S1_RX_C_DN")
	)
	(arc
		(start 434.75275 -137.98042)
		(mid 434.744167 -137.936709)
		(end 434.719476 -137.899648)
		(width 0.1143)
		(layer "B.Cu")
		(net "SATA6G_S1_RX_C_DN")
	)
	(arc
		(start 434.24856 -137.428732)
		(mid 434.17152 -137.313479)
		(end 434.14442 -137.177526)
		(width 0.1143)
		(layer "B.Cu")
		(net "SATA6G_S1_RX_C_DN")
	)
	(arc
		(start 434.14442 -136.906508)
		(mid 434.135704 -136.862782)
		(end 434.110892 -136.825736)
		(width 0.1143)
		(layer "B.Cu")
		(net "SATA6G_S1_RX_C_DN")
	)
	(arc
		(start 434.719476 -140.64869)
		(mid 434.744238 -140.611631)
		(end 434.753004 -140.567918)
		(width 0.1143)
		(layer "B.Cu")
		(net "SATA6G_S1_RX_C_DN")
	)
	(segment
		(start 434.994304 -140.567918)
		(end 434.994304 -137.98042)
		(width 0.1143)
		(layer "B.Cu")
		(net "SATA6G_S1_RX_C_DP")
	)
	(segment
		(start 434.890164 -137.72896)
		(end 434.419248 -137.258044)
		(width 0.1143)
		(layer "B.Cu")
		(net "SATA6G_S1_RX_C_DP")
	)
	(segment
		(start 435.381654 -141.002512)
		(end 435.027832 -140.64869)
		(width 0.1143)
		(layer "B.Cu")
		(net "SATA6G_S1_RX_C_DP")
	)
	(segment
		(start 434.419248 -136.825736)
		(end 434.90007 -136.344914)
		(width 0.1143)
		(layer "B.Cu")
		(net "SATA6G_S1_RX_C_DP")
	)
	(segment
		(start 434.38572 -137.177272)
		(end 434.38572 -136.906508)
		(width 0.1143)
		(layer "B.Cu")
		(net "SATA6G_S1_RX_C_DP")
	)
	(arc
		(start 435.027832 -140.64869)
		(mid 435.00307 -140.611631)
		(end 434.994304 -140.567918)
		(width 0.1143)
		(layer "B.Cu")
		(net "SATA6G_S1_RX_C_DP")
	)
	(arc
		(start 434.419248 -137.258044)
		(mid 434.394486 -137.220985)
		(end 434.38572 -137.177272)
		(width 0.1143)
		(layer "B.Cu")
		(net "SATA6G_S1_RX_C_DP")
	)
	(arc
		(start 434.994304 -137.98042)
		(mid 434.967236 -137.844338)
		(end 434.890164 -137.72896)
		(width 0.1143)
		(layer "B.Cu")
		(net "SATA6G_S1_RX_C_DP")
	)
	(arc
		(start 434.38572 -136.906508)
		(mid 434.394436 -136.862782)
		(end 434.419248 -136.825736)
		(width 0.1143)
		(layer "B.Cu")
		(net "SATA6G_S1_RX_C_DP")
	)
	(segment
		(start 378.06249 -33.15589)
		(end 377.670314 -33.15589)
		(width 0.1143)
		(layer "F.Cu")
		(net "SATA6G_S0_TX_DP")
	)
	(segment
		(start 377.670314 -33.15589)
		(end 377.38177 -33.444434)
		(width 0.1143)
		(layer "F.Cu")
		(net "SATA6G_S0_TX_DP")
	)
	(segment
		(start 387.32206 -127.190754)
		(end 387.32206 -127.7366)
		(width 0.0889)
		(layer "F.Cu")
		(net "SATA6G_S0_TX_DP")
	)
	(segment
		(start 386.985002 -126.165102)
		(end 387.12394 -126.30404)
		(width 0.0889)
		(layer "F.Cu")
		(net "SATA6G_S0_TX_DP")
	)
	(segment
		(start 387.12394 -126.992634)
		(end 387.32206 -127.190754)
		(width 0.0889)
		(layer "F.Cu")
		(net "SATA6G_S0_TX_DP")
	)
	(segment
		(start 387.32206 -127.7366)
		(end 387.55066 -127.9652)
		(width 0.0889)
		(layer "F.Cu")
		(net "SATA6G_S0_TX_DP")
	)
	(segment
		(start 387.55066 -127.9652)
		(end 387.731 -127.9652)
		(width 0.0889)
		(layer "F.Cu")
		(net "SATA6G_S0_TX_DP")
	)
	(segment
		(start 378.254768 -33.7185)
		(end 378.254768 -33.348168)
		(width 0.1143)
		(layer "F.Cu")
		(net "SATA6G_S0_TX_DP")
	)
	(segment
		(start 378.254768 -33.348168)
		(end 378.06249 -33.15589)
		(width 0.1143)
		(layer "F.Cu")
		(net "SATA6G_S0_TX_DP")
	)
	(segment
		(start 387.12394 -126.30404)
		(end 387.12394 -126.992634)
		(width 0.0889)
		(layer "F.Cu")
		(net "SATA6G_S0_TX_DP")
	)
	(via
		(at 377.38177 -33.444434)
		(size 0.508)
		(drill 0.254)
		(layers "F.Cu" "B.Cu")
		(net "SATA6G_S0_TX_DP")
	)
	(via
		(at 387.731 -127.9652)
		(size 0.508)
		(drill 0.254)
		(layers "F.Cu" "B.Cu")
		(net "SATA6G_S0_TX_DP")
	)
	(segment
		(start 403.394672 -75.207876)
		(end 403.493986 -74.901044)
		(width 0.1143)
		(layer "In11.Cu")
		(net "SATA6G_S0_TX_DP")
	)
	(segment
		(start 399.479008 -113.69294)
		(end 399.54454 -113.69294)
		(width 0.0889)
		(layer "In11.Cu")
		(net "SATA6G_S0_TX_DP")
	)
	(segment
		(start 390.871202 -50.67046)
		(end 391.25144 -48.801528)
		(width 0.1143)
		(layer "In11.Cu")
		(net "SATA6G_S0_TX_DP")
	)
	(segment
		(start 400.480022 -111.952532)
		(end 401.051776 -111.57458)
		(width 0.1143)
		(layer "In11.Cu")
		(net "SATA6G_S0_TX_DP")
	)
	(segment
		(start 401.565618 -111.469932)
		(end 404.191216 -110.935262)
		(width 0.1143)
		(layer "In11.Cu")
		(net "SATA6G_S0_TX_DP")
	)
	(segment
		(start 404.337774 -70.39737)
		(end 404.411434 -70.062344)
		(width 0.1143)
		(layer "In11.Cu")
		(net "SATA6G_S0_TX_DP")
	)
	(segment
		(start 404.7744 -68.412868)
		(end 404.84806 -68.077842)
		(width 0.1143)
		(layer "In11.Cu")
		(net "SATA6G_S0_TX_DP")
	)
	(segment
		(start 391.6045 -122.984514)
		(end 391.6045 -122.941334)
		(width 0.0889)
		(layer "In11.Cu")
		(net "SATA6G_S0_TX_DP")
	)
	(segment
		(start 401.051776 -111.57458)
		(end 401.564602 -111.470186)
		(width 0.1143)
		(layer "In11.Cu")
		(net "SATA6G_S0_TX_DP")
	)
	(segment
		(start 403.972522 -79.185516)
		(end 403.496526 -76.908914)
		(width 0.1143)
		(layer "In11.Cu")
		(net "SATA6G_S0_TX_DP")
	)
	(segment
		(start 404.495762 -96.042988)
		(end 405.128476 -92.934282)
		(width 0.1143)
		(layer "In11.Cu")
		(net "SATA6G_S0_TX_DP")
	)
	(segment
		(start 403.493986 -74.901044)
		(end 403.49424 -74.900536)
		(width 0.1143)
		(layer "In11.Cu")
		(net "SATA6G_S0_TX_DP")
	)
	(segment
		(start 393.595352 -52.319936)
		(end 391.70864 -51.936142)
		(width 0.1143)
		(layer "In11.Cu")
		(net "SATA6G_S0_TX_DP")
	)
	(segment
		(start 404.68169 -69.601842)
		(end 404.55596 -69.404992)
		(width 0.1143)
		(layer "In11.Cu")
		(net "SATA6G_S0_TX_DP")
	)
	(segment
		(start 404.93188 -64.581532)
		(end 403.120606 -61.84519)
		(width 0.1143)
		(layer "In11.Cu")
		(net "SATA6G_S0_TX_DP")
	)
	(segment
		(start 404.411434 -70.062344)
		(end 404.60803 -69.936614)
		(width 0.1143)
		(layer "In11.Cu")
		(net "SATA6G_S0_TX_DP")
	)
	(segment
		(start 380.232158 -36.261294)
		(end 378.080524 -33.010602)
		(width 0.1143)
		(layer "In11.Cu")
		(net "SATA6G_S0_TX_DP")
	)
	(segment
		(start 405.433784 -84.756498)
		(end 405.434038 -84.756498)
		(width 0.1143)
		(layer "In11.Cu")
		(net "SATA6G_S0_TX_DP")
	)
	(segment
		(start 405.128476 -92.934282)
		(end 405.841962 -92.462096)
		(width 0.1143)
		(layer "In11.Cu")
		(net "SATA6G_S0_TX_DP")
	)
	(segment
		(start 399.869914 -113.563654)
		(end 400.302222 -113.131346)
		(width 0.0889)
		(layer "In11.Cu")
		(net "SATA6G_S0_TX_DP")
	)
	(segment
		(start 387.50875 -127.74295)
		(end 387.304026 -127.74295)
		(width 0.0889)
		(layer "In11.Cu")
		(net "SATA6G_S0_TX_DP")
	)
	(segment
		(start 406.202388 -105.53827)
		(end 406.44572 -104.342692)
		(width 0.1143)
		(layer "In11.Cu")
		(net "SATA6G_S0_TX_DP")
	)
	(segment
		(start 387.304026 -127.74295)
		(end 387.10362 -127.542544)
		(width 0.0889)
		(layer "In11.Cu")
		(net "SATA6G_S0_TX_DP")
	)
	(segment
		(start 403.562312 -74.689716)
		(end 404.463504 -70.593966)
		(width 0.1143)
		(layer "In11.Cu")
		(net "SATA6G_S0_TX_DP")
	)
	(segment
		(start 403.120606 -61.84519)
		(end 397.389604 -58.0517)
		(width 0.1143)
		(layer "In11.Cu")
		(net "SATA6G_S0_TX_DP")
	)
	(segment
		(start 404.60803 -69.936614)
		(end 404.68169 -69.601842)
		(width 0.1143)
		(layer "In11.Cu")
		(net "SATA6G_S0_TX_DP")
	)
	(segment
		(start 406.42159 -89.612724)
		(end 405.433784 -84.756498)
		(width 0.1143)
		(layer "In11.Cu")
		(net "SATA6G_S0_TX_DP")
	)
	(segment
		(start 404.84806 -68.077842)
		(end 405.044656 -67.952112)
		(width 0.1143)
		(layer "In11.Cu")
		(net "SATA6G_S0_TX_DP")
	)
	(segment
		(start 377.655582 -32.957008)
		(end 377.512326 -33.031684)
		(width 0.1143)
		(layer "In11.Cu")
		(net "SATA6G_S0_TX_DP")
	)
	(segment
		(start 380.487936 -37.517324)
		(end 380.232158 -36.261294)
		(width 0.1143)
		(layer "In11.Cu")
		(net "SATA6G_S0_TX_DP")
	)
	(segment
		(start 400.251422 -112.90935)
		(end 400.251422 -112.376966)
		(width 0.1143)
		(layer "In11.Cu")
		(net "SATA6G_S0_TX_DP")
	)
	(segment
		(start 387.10362 -126.117858)
		(end 388.799578 -124.4219)
		(width 0.0889)
		(layer "In11.Cu")
		(net "SATA6G_S0_TX_DP")
	)
	(segment
		(start 406.205944 -103.163624)
		(end 405.20747 -101.65588)
		(width 0.1143)
		(layer "In11.Cu")
		(net "SATA6G_S0_TX_DP")
	)
	(segment
		(start 391.70864 -51.936142)
		(end 390.871202 -50.67046)
		(width 0.1143)
		(layer "In11.Cu")
		(net "SATA6G_S0_TX_DP")
	)
	(segment
		(start 398.5387 -114.3889)
		(end 398.5387 -114.356134)
		(width 0.0889)
		(layer "In11.Cu")
		(net "SATA6G_S0_TX_DP")
	)
	(segment
		(start 406.44572 -104.342692)
		(end 406.205944 -103.163624)
		(width 0.1143)
		(layer "In11.Cu")
		(net "SATA6G_S0_TX_DP")
	)
	(segment
		(start 403.629876 -76.075286)
		(end 403.394672 -75.207876)
		(width 0.1143)
		(layer "In11.Cu")
		(net "SATA6G_S0_TX_DP")
	)
	(segment
		(start 405.219154 -99.598988)
		(end 404.495762 -96.042988)
		(width 0.1143)
		(layer "In11.Cu")
		(net "SATA6G_S0_TX_DP")
	)
	(segment
		(start 386.517642 -45.15485)
		(end 384.240024 -41.71315)
		(width 0.1143)
		(layer "In11.Cu")
		(net "SATA6G_S0_TX_DP")
	)
	(segment
		(start 392.0998 -124.010674)
		(end 392.0998 -123.810268)
		(width 0.0889)
		(layer "In11.Cu")
		(net "SATA6G_S0_TX_DP")
	)
	(segment
		(start 405.363172 -107.333542)
		(end 405.654764 -105.900982)
		(width 0.1143)
		(layer "In11.Cu")
		(net "SATA6G_S0_TX_DP")
	)
	(segment
		(start 405.434038 -84.756498)
		(end 404.445978 -79.900018)
		(width 0.1143)
		(layer "In11.Cu")
		(net "SATA6G_S0_TX_DP")
	)
	(segment
		(start 404.62962 -69.07022)
		(end 404.82647 -68.94449)
		(width 0.1143)
		(layer "In11.Cu")
		(net "SATA6G_S0_TX_DP")
	)
	(segment
		(start 397.389604 -58.0517)
		(end 393.595352 -52.319936)
		(width 0.1143)
		(layer "In11.Cu")
		(net "SATA6G_S0_TX_DP")
	)
	(segment
		(start 404.445978 -79.900018)
		(end 403.972522 -79.185516)
		(width 0.1143)
		(layer "In11.Cu")
		(net "SATA6G_S0_TX_DP")
	)
	(segment
		(start 388.799578 -124.4219)
		(end 391.688574 -124.4219)
		(width 0.0889)
		(layer "In11.Cu")
		(net "SATA6G_S0_TX_DP")
	)
	(segment
		(start 398.0434 -115.24742)
		(end 398.0434 -115.214654)
		(width 0.0889)
		(layer "In11.Cu")
		(net "SATA6G_S0_TX_DP")
	)
	(segment
		(start 405.20747 -101.65588)
		(end 405.00427 -100.655882)
		(width 0.1143)
		(layer "In11.Cu")
		(net "SATA6G_S0_TX_DP")
	)
	(segment
		(start 404.90013 -68.609464)
		(end 404.7744 -68.412868)
		(width 0.1143)
		(layer "In11.Cu")
		(net "SATA6G_S0_TX_DP")
	)
	(segment
		(start 405.263096 -66.959734)
		(end 405.342344 -66.599308)
		(width 0.1143)
		(layer "In11.Cu")
		(net "SATA6G_S0_TX_DP")
	)
	(segment
		(start 384.240024 -41.71315)
		(end 383.112772 -41.483788)
		(width 0.1143)
		(layer "In11.Cu")
		(net "SATA6G_S0_TX_DP")
	)
	(segment
		(start 405.261572 -66.203322)
		(end 404.93188 -64.581532)
		(width 0.1143)
		(layer "In11.Cu")
		(net "SATA6G_S0_TX_DP")
	)
	(segment
		(start 403.49424 -74.900536)
		(end 403.562312 -74.689716)
		(width 0.1143)
		(layer "In11.Cu")
		(net "SATA6G_S0_TX_DP")
	)
	(segment
		(start 377.817634 -32.957008)
		(end 377.655582 -32.957008)
		(width 0.1143)
		(layer "In11.Cu")
		(net "SATA6G_S0_TX_DP")
	)
	(segment
		(start 400.251422 -112.376966)
		(end 400.480022 -111.952532)
		(width 0.1143)
		(layer "In11.Cu")
		(net "SATA6G_S0_TX_DP")
	)
	(segment
		(start 392.5951 -119.54002)
		(end 392.5951 -119.507254)
		(width 0.0889)
		(layer "In11.Cu")
		(net "SATA6G_S0_TX_DP")
	)
	(segment
		(start 396.5575 -116.10594)
		(end 396.5575 -116.073174)
		(width 0.0889)
		(layer "In11.Cu")
		(net "SATA6G_S0_TX_DP")
	)
	(segment
		(start 378.080524 -33.010602)
		(end 377.817634 -32.957008)
		(width 0.1143)
		(layer "In11.Cu")
		(net "SATA6G_S0_TX_DP")
	)
	(segment
		(start 392.0998 -120.408954)
		(end 392.0998 -120.365774)
		(width 0.0889)
		(layer "In11.Cu")
		(net "SATA6G_S0_TX_DP")
	)
	(segment
		(start 405.261826 -66.203322)
		(end 405.261572 -66.203322)
		(width 0.1143)
		(layer "In11.Cu")
		(net "SATA6G_S0_TX_DP")
	)
	(segment
		(start 405.044656 -67.952112)
		(end 405.118316 -67.61734)
		(width 0.1143)
		(layer "In11.Cu")
		(net "SATA6G_S0_TX_DP")
	)
	(segment
		(start 393.0904 -118.6815)
		(end 393.0904 -118.648734)
		(width 0.0889)
		(layer "In11.Cu")
		(net "SATA6G_S0_TX_DP")
	)
	(segment
		(start 396.0622 -116.96446)
		(end 396.0622 -116.931694)
		(width 0.0889)
		(layer "In11.Cu")
		(net "SATA6G_S0_TX_DP")
	)
	(segment
		(start 387.10362 -127.542544)
		(end 387.10362 -126.117858)
		(width 0.0889)
		(layer "In11.Cu")
		(net "SATA6G_S0_TX_DP")
	)
	(segment
		(start 404.55596 -69.404992)
		(end 404.62962 -69.07022)
		(width 0.1143)
		(layer "In11.Cu")
		(net "SATA6G_S0_TX_DP")
	)
	(segment
		(start 392.5951 -121.25706)
		(end 392.5951 -121.234708)
		(width 0.0889)
		(layer "In11.Cu")
		(net "SATA6G_S0_TX_DP")
	)
	(segment
		(start 383.112772 -41.483788)
		(end 380.487936 -37.517324)
		(width 0.1143)
		(layer "In11.Cu")
		(net "SATA6G_S0_TX_DP")
	)
	(segment
		(start 405.118316 -67.61734)
		(end 404.992586 -67.42049)
		(width 0.1143)
		(layer "In11.Cu")
		(net "SATA6G_S0_TX_DP")
	)
	(segment
		(start 389.198358 -45.699934)
		(end 386.517642 -45.15485)
		(width 0.1143)
		(layer "In11.Cu")
		(net "SATA6G_S0_TX_DP")
	)
	(segment
		(start 377.512326 -33.031684)
		(end 377.38177 -33.444434)
		(width 0.1143)
		(layer "In11.Cu")
		(net "SATA6G_S0_TX_DP")
	)
	(segment
		(start 405.841962 -92.462096)
		(end 406.42159 -89.612724)
		(width 0.1143)
		(layer "In11.Cu")
		(net "SATA6G_S0_TX_DP")
	)
	(segment
		(start 405.342344 -66.599308)
		(end 405.261826 -66.203322)
		(width 0.1143)
		(layer "In11.Cu")
		(net "SATA6G_S0_TX_DP")
	)
	(segment
		(start 404.191216 -110.935262)
		(end 405.102568 -110.332266)
		(width 0.1143)
		(layer "In11.Cu")
		(net "SATA6G_S0_TX_DP")
	)
	(segment
		(start 392.0998 -122.11558)
		(end 392.0998 -122.082814)
		(width 0.0889)
		(layer "In11.Cu")
		(net "SATA6G_S0_TX_DP")
	)
	(segment
		(start 403.496526 -76.908914)
		(end 403.629876 -76.075286)
		(width 0.1143)
		(layer "In11.Cu")
		(net "SATA6G_S0_TX_DP")
	)
	(segment
		(start 400.302222 -113.131346)
		(end 400.302222 -112.982248)
		(width 0.0889)
		(layer "In11.Cu")
		(net "SATA6G_S0_TX_DP")
	)
	(segment
		(start 391.25144 -48.801528)
		(end 389.198358 -45.699934)
		(width 0.1143)
		(layer "In11.Cu")
		(net "SATA6G_S0_TX_DP")
	)
	(segment
		(start 400.302222 -112.982248)
		(end 400.251422 -112.931448)
		(width 0.0889)
		(layer "In11.Cu")
		(net "SATA6G_S0_TX_DP")
	)
	(segment
		(start 395.5669 -117.82298)
		(end 395.5669 -117.790214)
		(width 0.0889)
		(layer "In11.Cu")
		(net "SATA6G_S0_TX_DP")
	)
	(segment
		(start 400.251422 -112.931448)
		(end 400.251422 -112.90935)
		(width 0.0889)
		(layer "In11.Cu")
		(net "SATA6G_S0_TX_DP")
	)
	(segment
		(start 387.731 -127.9652)
		(end 387.50875 -127.74295)
		(width 0.0889)
		(layer "In11.Cu")
		(net "SATA6G_S0_TX_DP")
	)
	(segment
		(start 405.066246 -67.085718)
		(end 405.263096 -66.959734)
		(width 0.1143)
		(layer "In11.Cu")
		(net "SATA6G_S0_TX_DP")
	)
	(segment
		(start 405.654764 -105.900982)
		(end 406.202388 -105.53827)
		(width 0.1143)
		(layer "In11.Cu")
		(net "SATA6G_S0_TX_DP")
	)
	(segment
		(start 405.609552 -108.544614)
		(end 405.363172 -107.333542)
		(width 0.1143)
		(layer "In11.Cu")
		(net "SATA6G_S0_TX_DP")
	)
	(segment
		(start 405.102568 -110.332266)
		(end 405.309324 -110.019846)
		(width 0.1143)
		(layer "In11.Cu")
		(net "SATA6G_S0_TX_DP")
	)
	(segment
		(start 401.564602 -111.470186)
		(end 401.565618 -111.469932)
		(width 0.1143)
		(layer "In11.Cu")
		(net "SATA6G_S0_TX_DP")
	)
	(segment
		(start 404.992586 -67.42049)
		(end 405.066246 -67.085718)
		(width 0.1143)
		(layer "In11.Cu")
		(net "SATA6G_S0_TX_DP")
	)
	(segment
		(start 404.82647 -68.94449)
		(end 404.90013 -68.609464)
		(width 0.1143)
		(layer "In11.Cu")
		(net "SATA6G_S0_TX_DP")
	)
	(segment
		(start 405.00427 -100.655882)
		(end 405.219154 -99.598988)
		(width 0.1143)
		(layer "In11.Cu")
		(net "SATA6G_S0_TX_DP")
	)
	(segment
		(start 405.309324 -110.019846)
		(end 405.609552 -108.544614)
		(width 0.1143)
		(layer "In11.Cu")
		(net "SATA6G_S0_TX_DP")
	)
	(segment
		(start 404.463504 -70.593966)
		(end 404.337774 -70.39737)
		(width 0.1143)
		(layer "In11.Cu")
		(net "SATA6G_S0_TX_DP")
	)
	(arc
		(start 393.385548 -118.158514)
		(mid 393.68095 -118.079383)
		(end 393.976352 -118.158514)
		(width 0.0889)
		(layer "In11.Cu")
		(net "SATA6G_S0_TX_DP")
	)
	(arc
		(start 392.0998 -122.082814)
		(mid 392.184081 -121.799597)
		(end 392.394948 -121.592594)
		(width 0.0889)
		(layer "In11.Cu")
		(net "SATA6G_S0_TX_DP")
	)
	(arc
		(start 398.833848 -113.865914)
		(mid 399.145042 -113.736975)
		(end 399.479008 -113.69294)
		(width 0.0889)
		(layer "In11.Cu")
		(net "SATA6G_S0_TX_DP")
	)
	(arc
		(start 392.890248 -119.017034)
		(mid 393.034052 -118.875351)
		(end 393.0904 -118.6815)
		(width 0.0889)
		(layer "In11.Cu")
		(net "SATA6G_S0_TX_DP")
	)
	(arc
		(start 396.0622 -116.931694)
		(mid 396.146481 -116.648477)
		(end 396.357348 -116.441474)
		(width 0.0889)
		(layer "In11.Cu")
		(net "SATA6G_S0_TX_DP")
	)
	(arc
		(start 392.0998 -120.365774)
		(mid 392.184081 -120.082557)
		(end 392.394948 -119.875554)
		(width 0.0889)
		(layer "In11.Cu")
		(net "SATA6G_S0_TX_DP")
	)
	(arc
		(start 392.394948 -119.875554)
		(mid 392.538752 -119.733871)
		(end 392.5951 -119.54002)
		(width 0.0889)
		(layer "In11.Cu")
		(net "SATA6G_S0_TX_DP")
	)
	(arc
		(start 392.394948 -120.899174)
		(mid 392.184084 -120.69217)
		(end 392.0998 -120.408954)
		(width 0.0889)
		(layer "In11.Cu")
		(net "SATA6G_S0_TX_DP")
	)
	(arc
		(start 391.899648 -122.451114)
		(mid 392.043452 -122.309431)
		(end 392.0998 -122.11558)
		(width 0.0889)
		(layer "In11.Cu")
		(net "SATA6G_S0_TX_DP")
	)
	(arc
		(start 395.862048 -117.299994)
		(mid 396.005852 -117.158311)
		(end 396.0622 -116.96446)
		(width 0.0889)
		(layer "In11.Cu")
		(net "SATA6G_S0_TX_DP")
	)
	(arc
		(start 393.0904 -118.648734)
		(mid 393.174681 -118.365517)
		(end 393.385548 -118.158514)
		(width 0.0889)
		(layer "In11.Cu")
		(net "SATA6G_S0_TX_DP")
	)
	(arc
		(start 391.899648 -123.474734)
		(mid 391.688784 -123.26773)
		(end 391.6045 -122.984514)
		(width 0.0889)
		(layer "In11.Cu")
		(net "SATA6G_S0_TX_DP")
	)
	(arc
		(start 397.443452 -115.582954)
		(mid 397.64335 -115.636453)
		(end 397.843248 -115.582954)
		(width 0.0889)
		(layer "In11.Cu")
		(net "SATA6G_S0_TX_DP")
	)
	(arc
		(start 395.5669 -117.790214)
		(mid 395.651181 -117.506997)
		(end 395.862048 -117.299994)
		(width 0.0889)
		(layer "In11.Cu")
		(net "SATA6G_S0_TX_DP")
	)
	(arc
		(start 392.5951 -119.507254)
		(mid 392.679381 -119.224037)
		(end 392.890248 -119.017034)
		(width 0.0889)
		(layer "In11.Cu")
		(net "SATA6G_S0_TX_DP")
	)
	(arc
		(start 398.338548 -114.724434)
		(mid 398.482352 -114.582751)
		(end 398.5387 -114.3889)
		(width 0.0889)
		(layer "In11.Cu")
		(net "SATA6G_S0_TX_DP")
	)
	(arc
		(start 393.976352 -118.158514)
		(mid 394.17625 -118.212013)
		(end 394.376148 -118.158514)
		(width 0.0889)
		(layer "In11.Cu")
		(net "SATA6G_S0_TX_DP")
	)
	(arc
		(start 396.5575 -116.073174)
		(mid 396.641781 -115.789957)
		(end 396.852648 -115.582954)
		(width 0.0889)
		(layer "In11.Cu")
		(net "SATA6G_S0_TX_DP")
	)
	(arc
		(start 392.5951 -121.234708)
		(mid 392.53875 -121.040858)
		(end 392.394948 -120.899174)
		(width 0.0889)
		(layer "In11.Cu")
		(net "SATA6G_S0_TX_DP")
	)
	(arc
		(start 394.966952 -118.158514)
		(mid 395.16685 -118.212013)
		(end 395.366748 -118.158514)
		(width 0.0889)
		(layer "In11.Cu")
		(net "SATA6G_S0_TX_DP")
	)
	(arc
		(start 395.366748 -118.158514)
		(mid 395.510552 -118.016831)
		(end 395.5669 -117.82298)
		(width 0.0889)
		(layer "In11.Cu")
		(net "SATA6G_S0_TX_DP")
	)
	(arc
		(start 392.0998 -123.810268)
		(mid 392.04345 -123.616418)
		(end 391.899648 -123.474734)
		(width 0.0889)
		(layer "In11.Cu")
		(net "SATA6G_S0_TX_DP")
	)
	(arc
		(start 392.394948 -121.592594)
		(mid 392.538752 -121.450911)
		(end 392.5951 -121.25706)
		(width 0.0889)
		(layer "In11.Cu")
		(net "SATA6G_S0_TX_DP")
	)
	(arc
		(start 394.376148 -118.158514)
		(mid 394.67155 -118.079383)
		(end 394.966952 -118.158514)
		(width 0.0889)
		(layer "In11.Cu")
		(net "SATA6G_S0_TX_DP")
	)
	(arc
		(start 398.5387 -114.356134)
		(mid 398.622981 -114.072917)
		(end 398.833848 -113.865914)
		(width 0.0889)
		(layer "In11.Cu")
		(net "SATA6G_S0_TX_DP")
	)
	(arc
		(start 391.6045 -122.941334)
		(mid 391.688781 -122.658117)
		(end 391.899648 -122.451114)
		(width 0.0889)
		(layer "In11.Cu")
		(net "SATA6G_S0_TX_DP")
	)
	(arc
		(start 397.843248 -115.582954)
		(mid 397.987052 -115.441271)
		(end 398.0434 -115.24742)
		(width 0.0889)
		(layer "In11.Cu")
		(net "SATA6G_S0_TX_DP")
	)
	(arc
		(start 391.688574 -124.4219)
		(mid 391.979355 -124.301455)
		(end 392.0998 -124.010674)
		(width 0.0889)
		(layer "In11.Cu")
		(net "SATA6G_S0_TX_DP")
	)
	(arc
		(start 396.357348 -116.441474)
		(mid 396.501152 -116.299791)
		(end 396.5575 -116.10594)
		(width 0.0889)
		(layer "In11.Cu")
		(net "SATA6G_S0_TX_DP")
	)
	(arc
		(start 399.54454 -113.69294)
		(mid 399.720556 -113.661854)
		(end 399.869914 -113.563654)
		(width 0.0889)
		(layer "In11.Cu")
		(net "SATA6G_S0_TX_DP")
	)
	(arc
		(start 396.852648 -115.582954)
		(mid 397.14805 -115.503823)
		(end 397.443452 -115.582954)
		(width 0.0889)
		(layer "In11.Cu")
		(net "SATA6G_S0_TX_DP")
	)
	(arc
		(start 398.0434 -115.214654)
		(mid 398.127681 -114.931437)
		(end 398.338548 -114.724434)
		(width 0.0889)
		(layer "In11.Cu")
		(net "SATA6G_S0_TX_DP")
	)
	(segment
		(start 377.933966 -32.642302)
		(end 378.254768 -32.3215)
		(width 0.1143)
		(layer "F.Cu")
		(net "SATA6G_S0_TX_DN")
	)
	(segment
		(start 386.985002 -125.370082)
		(end 387.31444 -126.166118)
		(width 0.0889)
		(layer "F.Cu")
		(net "SATA6G_S0_TX_DN")
	)
	(segment
		(start 387.31444 -126.91364)
		(end 387.731 -127.3302)
		(width 0.0889)
		(layer "F.Cu")
		(net "SATA6G_S0_TX_DN")
	)
	(segment
		(start 376.964702 -32.642302)
		(end 377.933966 -32.642302)
		(width 0.1143)
		(layer "F.Cu")
		(net "SATA6G_S0_TX_DN")
	)
	(segment
		(start 387.31444 -126.166118)
		(end 387.31444 -126.91364)
		(width 0.0889)
		(layer "F.Cu")
		(net "SATA6G_S0_TX_DN")
	)
	(segment
		(start 386.985002 -125.33503)
		(end 386.985002 -125.370082)
		(width 0.0889)
		(layer "F.Cu")
		(net "SATA6G_S0_TX_DN")
	)
	(via
		(at 376.964702 -32.642302)
		(size 0.508)
		(drill 0.254)
		(layers "F.Cu" "B.Cu")
		(net "SATA6G_S0_TX_DN")
	)
	(via
		(at 387.731 -127.3302)
		(size 0.508)
		(drill 0.254)
		(layers "F.Cu" "B.Cu")
		(net "SATA6G_S0_TX_DN")
	)
	(segment
		(start 405.302466 -100.655882)
		(end 405.51735 -99.598988)
		(width 0.1143)
		(layer "In11.Cu")
		(net "SATA6G_S0_TX_DN")
	)
	(segment
		(start 400.543522 -112.931448)
		(end 400.543522 -112.90935)
		(width 0.0889)
		(layer "In11.Cu")
		(net "SATA6G_S0_TX_DN")
	)
	(segment
		(start 389.554974 -124.6124)
		(end 389.643874 -124.7013)
		(width 0.0889)
		(layer "In11.Cu")
		(net "SATA6G_S0_TX_DN")
	)
	(segment
		(start 405.390858 -93.11132)
		(end 406.104344 -92.639134)
		(width 0.1143)
		(layer "In11.Cu")
		(net "SATA6G_S0_TX_DN")
	)
	(segment
		(start 398.2339 -115.257834)
		(end 398.2339 -115.225068)
		(width 0.0889)
		(layer "In11.Cu")
		(net "SATA6G_S0_TX_DN")
	)
	(segment
		(start 406.481026 -103.049578)
		(end 405.482552 -101.541834)
		(width 0.1143)
		(layer "In11.Cu")
		(net "SATA6G_S0_TX_DN")
	)
	(segment
		(start 384.417062 -41.450768)
		(end 383.28981 -41.221406)
		(width 0.1143)
		(layer "In11.Cu")
		(net "SATA6G_S0_TX_DN")
	)
	(segment
		(start 406.719786 -89.61247)
		(end 404.72106 -79.785972)
		(width 0.1143)
		(layer "In11.Cu")
		(net "SATA6G_S0_TX_DN")
	)
	(segment
		(start 396.2527 -116.974874)
		(end 396.2527 -116.942108)
		(width 0.0889)
		(layer "In11.Cu")
		(net "SATA6G_S0_TX_DN")
	)
	(segment
		(start 405.313388 -110.543086)
		(end 405.584406 -110.133892)
		(width 0.1143)
		(layer "In11.Cu")
		(net "SATA6G_S0_TX_DN")
	)
	(segment
		(start 388.29996 -125.191012)
		(end 388.878572 -124.6124)
		(width 0.0889)
		(layer "In11.Cu")
		(net "SATA6G_S0_TX_DN")
	)
	(segment
		(start 377.37669 -32.772858)
		(end 376.964702 -32.642302)
		(width 0.1143)
		(layer "In11.Cu")
		(net "SATA6G_S0_TX_DN")
	)
	(segment
		(start 400.004534 -113.698528)
		(end 400.492722 -113.21034)
		(width 0.0889)
		(layer "In11.Cu")
		(net "SATA6G_S0_TX_DN")
	)
	(segment
		(start 398.7292 -114.399314)
		(end 398.7292 -114.360198)
		(width 0.0889)
		(layer "In11.Cu")
		(net "SATA6G_S0_TX_DN")
	)
	(segment
		(start 397.558768 -57.777888)
		(end 393.77239 -52.057554)
		(width 0.1143)
		(layer "In11.Cu")
		(net "SATA6G_S0_TX_DN")
	)
	(segment
		(start 406.104344 -92.639134)
		(end 406.719786 -89.61247)
		(width 0.1143)
		(layer "In11.Cu")
		(net "SATA6G_S0_TX_DN")
	)
	(segment
		(start 391.885678 -51.67376)
		(end 391.18159 -50.610008)
		(width 0.1143)
		(layer "In11.Cu")
		(net "SATA6G_S0_TX_DN")
	)
	(segment
		(start 390.977374 -124.6124)
		(end 391.066274 -124.7013)
		(width 0.0889)
		(layer "In11.Cu")
		(net "SATA6G_S0_TX_DN")
	)
	(segment
		(start 393.77239 -52.057554)
		(end 391.885678 -51.67376)
		(width 0.1143)
		(layer "In11.Cu")
		(net "SATA6G_S0_TX_DN")
	)
	(segment
		(start 391.332974 -124.7013)
		(end 391.421874 -124.6124)
		(width 0.0889)
		(layer "In11.Cu")
		(net "SATA6G_S0_TX_DN")
	)
	(segment
		(start 387.482588 -126.008384)
		(end 387.608318 -126.008384)
		(width 0.0889)
		(layer "In11.Cu")
		(net "SATA6G_S0_TX_DN")
	)
	(segment
		(start 388.878572 -124.6124)
		(end 389.554974 -124.6124)
		(width 0.0889)
		(layer "In11.Cu")
		(net "SATA6G_S0_TX_DN")
	)
	(segment
		(start 404.247096 -79.070962)
		(end 403.793706 -76.901802)
		(width 0.1143)
		(layer "In11.Cu")
		(net "SATA6G_S0_TX_DN")
	)
	(segment
		(start 391.561828 -48.741076)
		(end 389.375142 -45.437806)
		(width 0.1143)
		(layer "In11.Cu")
		(net "SATA6G_S0_TX_DN")
	)
	(segment
		(start 377.847352 -32.664908)
		(end 377.583954 -32.664908)
		(width 0.1143)
		(layer "In11.Cu")
		(net "SATA6G_S0_TX_DN")
	)
	(segment
		(start 406.743916 -104.342692)
		(end 406.481026 -103.049578)
		(width 0.1143)
		(layer "In11.Cu")
		(net "SATA6G_S0_TX_DN")
	)
	(segment
		(start 404.305262 -111.210598)
		(end 405.313388 -110.543086)
		(width 0.1143)
		(layer "In11.Cu")
		(net "SATA6G_S0_TX_DN")
	)
	(segment
		(start 406.464516 -105.715054)
		(end 406.743916 -104.342692)
		(width 0.1143)
		(layer "In11.Cu")
		(net "SATA6G_S0_TX_DN")
	)
	(segment
		(start 405.584406 -110.133892)
		(end 405.907748 -108.544614)
		(width 0.1143)
		(layer "In11.Cu")
		(net "SATA6G_S0_TX_DN")
	)
	(segment
		(start 399.479262 -113.88344)
		(end 399.539206 -113.88344)
		(width 0.0889)
		(layer "In11.Cu")
		(net "SATA6G_S0_TX_DN")
	)
	(segment
		(start 397.600424 -57.84088)
		(end 397.558768 -57.777888)
		(width 0.1143)
		(layer "In11.Cu")
		(net "SATA6G_S0_TX_DN")
	)
	(segment
		(start 377.583954 -32.664908)
		(end 377.377452 -32.77235)
		(width 0.1143)
		(layer "In11.Cu")
		(net "SATA6G_S0_TX_DN")
	)
	(segment
		(start 405.641048 -66.601594)
		(end 405.206962 -64.467486)
		(width 0.1143)
		(layer "In11.Cu")
		(net "SATA6G_S0_TX_DN")
	)
	(segment
		(start 404.72106 -79.785972)
		(end 404.247096 -79.070962)
		(width 0.1143)
		(layer "In11.Cu")
		(net "SATA6G_S0_TX_DN")
	)
	(segment
		(start 389.999474 -124.6124)
		(end 390.266174 -124.6124)
		(width 0.0889)
		(layer "In11.Cu")
		(net "SATA6G_S0_TX_DN")
	)
	(segment
		(start 403.793706 -76.901802)
		(end 403.928326 -76.059538)
		(width 0.1143)
		(layer "In11.Cu")
		(net "SATA6G_S0_TX_DN")
	)
	(segment
		(start 390.621774 -124.7013)
		(end 390.710674 -124.6124)
		(width 0.0889)
		(layer "In11.Cu")
		(net "SATA6G_S0_TX_DN")
	)
	(segment
		(start 405.482552 -101.541834)
		(end 405.302466 -100.655882)
		(width 0.1143)
		(layer "In11.Cu")
		(net "SATA6G_S0_TX_DN")
	)
	(segment
		(start 389.375142 -45.437806)
		(end 386.69468 -44.892468)
		(width 0.1143)
		(layer "In11.Cu")
		(net "SATA6G_S0_TX_DN")
	)
	(segment
		(start 390.266174 -124.6124)
		(end 390.355074 -124.7013)
		(width 0.0889)
		(layer "In11.Cu")
		(net "SATA6G_S0_TX_DN")
	)
	(segment
		(start 387.38302 -127.55245)
		(end 387.29412 -127.46355)
		(width 0.0889)
		(layer "In11.Cu")
		(net "SATA6G_S0_TX_DN")
	)
	(segment
		(start 396.748 -116.116354)
		(end 396.748 -116.083588)
		(width 0.0889)
		(layer "In11.Cu")
		(net "SATA6G_S0_TX_DN")
	)
	(segment
		(start 387.731 -127.3302)
		(end 387.50875 -127.55245)
		(width 0.0889)
		(layer "In11.Cu")
		(net "SATA6G_S0_TX_DN")
	)
	(segment
		(start 403.331426 -61.63437)
		(end 397.600424 -57.84088)
		(width 0.1143)
		(layer "In11.Cu")
		(net "SATA6G_S0_TX_DN")
	)
	(segment
		(start 405.916892 -106.077766)
		(end 406.464516 -105.715054)
		(width 0.1143)
		(layer "In11.Cu")
		(net "SATA6G_S0_TX_DN")
	)
	(segment
		(start 393.2809 -118.691914)
		(end 393.2809 -118.659148)
		(width 0.0889)
		(layer "In11.Cu")
		(net "SATA6G_S0_TX_DN")
	)
	(segment
		(start 391.421874 -124.6124)
		(end 391.688574 -124.6124)
		(width 0.0889)
		(layer "In11.Cu")
		(net "SATA6G_S0_TX_DN")
	)
	(segment
		(start 404.793958 -96.042988)
		(end 405.390858 -93.11132)
		(width 0.1143)
		(layer "In11.Cu")
		(net "SATA6G_S0_TX_DN")
	)
	(segment
		(start 389.910574 -124.7013)
		(end 389.999474 -124.6124)
		(width 0.0889)
		(layer "In11.Cu")
		(net "SATA6G_S0_TX_DN")
	)
	(segment
		(start 405.907748 -108.544614)
		(end 405.661368 -107.333542)
		(width 0.1143)
		(layer "In11.Cu")
		(net "SATA6G_S0_TX_DN")
	)
	(segment
		(start 392.2903 -124.010674)
		(end 392.2903 -123.807728)
		(width 0.0889)
		(layer "In11.Cu")
		(net "SATA6G_S0_TX_DN")
	)
	(segment
		(start 377.377452 -32.77235)
		(end 377.37669 -32.772858)
		(width 0.1143)
		(layer "In11.Cu")
		(net "SATA6G_S0_TX_DN")
	)
	(segment
		(start 403.928326 -76.059538)
		(end 403.699472 -75.215242)
		(width 0.1143)
		(layer "In11.Cu")
		(net "SATA6G_S0_TX_DN")
	)
	(segment
		(start 389.643874 -124.7013)
		(end 389.910574 -124.7013)
		(width 0.0889)
		(layer "In11.Cu")
		(net "SATA6G_S0_TX_DN")
	)
	(segment
		(start 387.985508 -125.505464)
		(end 388.111238 -125.505464)
		(width 0.0889)
		(layer "In11.Cu")
		(net "SATA6G_S0_TX_DN")
	)
	(segment
		(start 405.206962 -64.467486)
		(end 403.331426 -61.63437)
		(width 0.1143)
		(layer "In11.Cu")
		(net "SATA6G_S0_TX_DN")
	)
	(segment
		(start 387.79704 -125.819662)
		(end 387.79704 -125.693932)
		(width 0.0889)
		(layer "In11.Cu")
		(net "SATA6G_S0_TX_DN")
	)
	(segment
		(start 383.28981 -41.221406)
		(end 380.763018 -37.403278)
		(width 0.1143)
		(layer "In11.Cu")
		(net "SATA6G_S0_TX_DN")
	)
	(segment
		(start 400.543522 -112.90935)
		(end 400.543522 -112.45088)
		(width 0.1143)
		(layer "In11.Cu")
		(net "SATA6G_S0_TX_DN")
	)
	(segment
		(start 390.710674 -124.6124)
		(end 390.977374 -124.6124)
		(width 0.0889)
		(layer "In11.Cu")
		(net "SATA6G_S0_TX_DN")
	)
	(segment
		(start 400.543522 -112.45088)
		(end 400.702526 -112.155986)
		(width 0.1143)
		(layer "In11.Cu")
		(net "SATA6G_S0_TX_DN")
	)
	(segment
		(start 403.84476 -74.766424)
		(end 405.641048 -66.601594)
		(width 0.1143)
		(layer "In11.Cu")
		(net "SATA6G_S0_TX_DN")
	)
	(segment
		(start 388.111238 -125.505464)
		(end 388.29996 -125.316742)
		(width 0.0889)
		(layer "In11.Cu")
		(net "SATA6G_S0_TX_DN")
	)
	(segment
		(start 386.69468 -44.892468)
		(end 384.417062 -41.450768)
		(width 0.1143)
		(layer "In11.Cu")
		(net "SATA6G_S0_TX_DN")
	)
	(segment
		(start 387.79704 -125.693932)
		(end 387.985508 -125.505464)
		(width 0.0889)
		(layer "In11.Cu")
		(net "SATA6G_S0_TX_DN")
	)
	(segment
		(start 380.763018 -37.403278)
		(end 380.50724 -36.147248)
		(width 0.1143)
		(layer "In11.Cu")
		(net "SATA6G_S0_TX_DN")
	)
	(segment
		(start 390.355074 -124.7013)
		(end 390.621774 -124.7013)
		(width 0.0889)
		(layer "In11.Cu")
		(net "SATA6G_S0_TX_DN")
	)
	(segment
		(start 392.7856 -119.550434)
		(end 392.7856 -119.517668)
		(width 0.0889)
		(layer "In11.Cu")
		(net "SATA6G_S0_TX_DN")
	)
	(segment
		(start 387.608318 -126.008384)
		(end 387.79704 -125.819662)
		(width 0.0889)
		(layer "In11.Cu")
		(net "SATA6G_S0_TX_DN")
	)
	(segment
		(start 392.2903 -122.125994)
		(end 392.2903 -122.093228)
		(width 0.0889)
		(layer "In11.Cu")
		(net "SATA6G_S0_TX_DN")
	)
	(segment
		(start 391.066274 -124.7013)
		(end 391.332974 -124.7013)
		(width 0.0889)
		(layer "In11.Cu")
		(net "SATA6G_S0_TX_DN")
	)
	(segment
		(start 391.795 -122.9741)
		(end 391.795 -122.951748)
		(width 0.0889)
		(layer "In11.Cu")
		(net "SATA6G_S0_TX_DN")
	)
	(segment
		(start 403.699472 -75.215242)
		(end 403.84476 -74.766424)
		(width 0.1143)
		(layer "In11.Cu")
		(net "SATA6G_S0_TX_DN")
	)
	(segment
		(start 400.492722 -113.21034)
		(end 400.492722 -112.982248)
		(width 0.0889)
		(layer "In11.Cu")
		(net "SATA6G_S0_TX_DN")
	)
	(segment
		(start 405.661368 -107.333542)
		(end 405.916892 -106.077766)
		(width 0.1143)
		(layer "In11.Cu")
		(net "SATA6G_S0_TX_DN")
	)
	(segment
		(start 392.7856 -121.267474)
		(end 392.7856 -121.224294)
		(width 0.0889)
		(layer "In11.Cu")
		(net "SATA6G_S0_TX_DN")
	)
	(segment
		(start 401.165568 -111.849662)
		(end 404.305262 -111.210598)
		(width 0.1143)
		(layer "In11.Cu")
		(net "SATA6G_S0_TX_DN")
	)
	(segment
		(start 378.257308 -32.748474)
		(end 377.847352 -32.664908)
		(width 0.1143)
		(layer "In11.Cu")
		(net "SATA6G_S0_TX_DN")
	)
	(segment
		(start 400.492722 -112.982248)
		(end 400.543522 -112.931448)
		(width 0.0889)
		(layer "In11.Cu")
		(net "SATA6G_S0_TX_DN")
	)
	(segment
		(start 387.29412 -126.196852)
		(end 387.482588 -126.008384)
		(width 0.0889)
		(layer "In11.Cu")
		(net "SATA6G_S0_TX_DN")
	)
	(segment
		(start 392.2903 -120.39854)
		(end 392.2903 -120.376188)
		(width 0.0889)
		(layer "In11.Cu")
		(net "SATA6G_S0_TX_DN")
	)
	(segment
		(start 400.702526 -112.155986)
		(end 401.165568 -111.849662)
		(width 0.1143)
		(layer "In11.Cu")
		(net "SATA6G_S0_TX_DN")
	)
	(segment
		(start 405.51735 -99.598988)
		(end 404.793958 -96.042988)
		(width 0.1143)
		(layer "In11.Cu")
		(net "SATA6G_S0_TX_DN")
	)
	(segment
		(start 380.50724 -36.147248)
		(end 378.257308 -32.748474)
		(width 0.1143)
		(layer "In11.Cu")
		(net "SATA6G_S0_TX_DN")
	)
	(segment
		(start 395.7574 -117.833394)
		(end 395.7574 -117.800628)
		(width 0.0889)
		(layer "In11.Cu")
		(net "SATA6G_S0_TX_DN")
	)
	(segment
		(start 387.29412 -127.46355)
		(end 387.29412 -126.196852)
		(width 0.0889)
		(layer "In11.Cu")
		(net "SATA6G_S0_TX_DN")
	)
	(segment
		(start 388.29996 -125.316742)
		(end 388.29996 -125.191012)
		(width 0.0889)
		(layer "In11.Cu")
		(net "SATA6G_S0_TX_DN")
	)
	(segment
		(start 391.18159 -50.610008)
		(end 391.561828 -48.741076)
		(width 0.1143)
		(layer "In11.Cu")
		(net "SATA6G_S0_TX_DN")
	)
	(segment
		(start 387.50875 -127.55245)
		(end 387.38302 -127.55245)
		(width 0.0889)
		(layer "In11.Cu")
		(net "SATA6G_S0_TX_DN")
	)
	(arc
		(start 391.995152 -122.616214)
		(mid 392.206016 -122.40921)
		(end 392.2903 -122.125994)
		(width 0.0889)
		(layer "In11.Cu")
		(net "SATA6G_S0_TX_DN")
	)
	(arc
		(start 398.7292 -114.360198)
		(mid 398.786935 -114.169956)
		(end 398.929098 -114.031014)
		(width 0.0889)
		(layer "In11.Cu")
		(net "SATA6G_S0_TX_DN")
	)
	(arc
		(start 396.748 -116.083588)
		(mid 396.804203 -115.889746)
		(end 396.947898 -115.748054)
		(width 0.0889)
		(layer "In11.Cu")
		(net "SATA6G_S0_TX_DN")
	)
	(arc
		(start 397.347948 -115.748054)
		(mid 397.643177 -115.827185)
		(end 397.938498 -115.748308)
		(width 0.0889)
		(layer "In11.Cu")
		(net "SATA6G_S0_TX_DN")
	)
	(arc
		(start 392.490452 -121.757694)
		(mid 392.701316 -121.55069)
		(end 392.7856 -121.267474)
		(width 0.0889)
		(layer "In11.Cu")
		(net "SATA6G_S0_TX_DN")
	)
	(arc
		(start 391.995152 -123.309634)
		(mid 391.851348 -123.167951)
		(end 391.795 -122.9741)
		(width 0.0889)
		(layer "In11.Cu")
		(net "SATA6G_S0_TX_DN")
	)
	(arc
		(start 397.938498 -115.748308)
		(mid 398.149606 -115.541246)
		(end 398.2339 -115.257834)
		(width 0.0889)
		(layer "In11.Cu")
		(net "SATA6G_S0_TX_DN")
	)
	(arc
		(start 392.2903 -122.093228)
		(mid 392.34665 -121.899378)
		(end 392.490452 -121.757694)
		(width 0.0889)
		(layer "In11.Cu")
		(net "SATA6G_S0_TX_DN")
	)
	(arc
		(start 398.2339 -115.225068)
		(mid 398.29025 -115.031218)
		(end 398.434052 -114.889534)
		(width 0.0889)
		(layer "In11.Cu")
		(net "SATA6G_S0_TX_DN")
	)
	(arc
		(start 392.2903 -123.807728)
		(mid 392.210979 -123.518231)
		(end 391.995152 -123.309634)
		(width 0.0889)
		(layer "In11.Cu")
		(net "SATA6G_S0_TX_DN")
	)
	(arc
		(start 396.2527 -116.942108)
		(mid 396.30905 -116.748258)
		(end 396.452852 -116.606574)
		(width 0.0889)
		(layer "In11.Cu")
		(net "SATA6G_S0_TX_DN")
	)
	(arc
		(start 392.7856 -121.224294)
		(mid 392.701319 -120.941077)
		(end 392.490452 -120.734074)
		(width 0.0889)
		(layer "In11.Cu")
		(net "SATA6G_S0_TX_DN")
	)
	(arc
		(start 392.490452 -120.734074)
		(mid 392.346648 -120.592391)
		(end 392.2903 -120.39854)
		(width 0.0889)
		(layer "In11.Cu")
		(net "SATA6G_S0_TX_DN")
	)
	(arc
		(start 392.7856 -119.517668)
		(mid 392.84195 -119.323818)
		(end 392.985752 -119.182134)
		(width 0.0889)
		(layer "In11.Cu")
		(net "SATA6G_S0_TX_DN")
	)
	(arc
		(start 393.480798 -118.323614)
		(mid 393.68084 -118.269988)
		(end 393.880848 -118.323614)
		(width 0.0889)
		(layer "In11.Cu")
		(net "SATA6G_S0_TX_DN")
	)
	(arc
		(start 394.471652 -118.323614)
		(mid 394.67155 -118.270115)
		(end 394.871448 -118.323614)
		(width 0.0889)
		(layer "In11.Cu")
		(net "SATA6G_S0_TX_DN")
	)
	(arc
		(start 395.7574 -117.800628)
		(mid 395.81375 -117.606778)
		(end 395.957552 -117.465094)
		(width 0.0889)
		(layer "In11.Cu")
		(net "SATA6G_S0_TX_DN")
	)
	(arc
		(start 396.947898 -115.748054)
		(mid 397.14794 -115.694428)
		(end 397.347948 -115.748054)
		(width 0.0889)
		(layer "In11.Cu")
		(net "SATA6G_S0_TX_DN")
	)
	(arc
		(start 396.452852 -116.606574)
		(mid 396.663716 -116.39957)
		(end 396.748 -116.116354)
		(width 0.0889)
		(layer "In11.Cu")
		(net "SATA6G_S0_TX_DN")
	)
	(arc
		(start 393.2809 -118.659148)
		(mid 393.337103 -118.465306)
		(end 393.480798 -118.323614)
		(width 0.0889)
		(layer "In11.Cu")
		(net "SATA6G_S0_TX_DN")
	)
	(arc
		(start 391.688574 -124.6124)
		(mid 392.114059 -124.436159)
		(end 392.2903 -124.010674)
		(width 0.0889)
		(layer "In11.Cu")
		(net "SATA6G_S0_TX_DN")
	)
	(arc
		(start 398.929098 -114.031014)
		(mid 399.194456 -113.920975)
		(end 399.479262 -113.88344)
		(width 0.0889)
		(layer "In11.Cu")
		(net "SATA6G_S0_TX_DN")
	)
	(arc
		(start 392.490452 -120.040654)
		(mid 392.701316 -119.83365)
		(end 392.7856 -119.550434)
		(width 0.0889)
		(layer "In11.Cu")
		(net "SATA6G_S0_TX_DN")
	)
	(arc
		(start 395.957552 -117.465094)
		(mid 396.168416 -117.25809)
		(end 396.2527 -116.974874)
		(width 0.0889)
		(layer "In11.Cu")
		(net "SATA6G_S0_TX_DN")
	)
	(arc
		(start 392.985752 -119.182134)
		(mid 393.196616 -118.97513)
		(end 393.2809 -118.691914)
		(width 0.0889)
		(layer "In11.Cu")
		(net "SATA6G_S0_TX_DN")
	)
	(arc
		(start 395.461998 -118.323868)
		(mid 395.673106 -118.116806)
		(end 395.7574 -117.833394)
		(width 0.0889)
		(layer "In11.Cu")
		(net "SATA6G_S0_TX_DN")
	)
	(arc
		(start 399.539206 -113.88344)
		(mid 399.790917 -113.838945)
		(end 400.004534 -113.698528)
		(width 0.0889)
		(layer "In11.Cu")
		(net "SATA6G_S0_TX_DN")
	)
	(arc
		(start 392.2903 -120.376188)
		(mid 392.34665 -120.182338)
		(end 392.490452 -120.040654)
		(width 0.0889)
		(layer "In11.Cu")
		(net "SATA6G_S0_TX_DN")
	)
	(arc
		(start 398.434052 -114.889534)
		(mid 398.644916 -114.68253)
		(end 398.7292 -114.399314)
		(width 0.0889)
		(layer "In11.Cu")
		(net "SATA6G_S0_TX_DN")
	)
	(arc
		(start 393.880848 -118.323614)
		(mid 394.17625 -118.402745)
		(end 394.471652 -118.323614)
		(width 0.0889)
		(layer "In11.Cu")
		(net "SATA6G_S0_TX_DN")
	)
	(arc
		(start 394.871448 -118.323614)
		(mid 395.166677 -118.402745)
		(end 395.461998 -118.323868)
		(width 0.0889)
		(layer "In11.Cu")
		(net "SATA6G_S0_TX_DN")
	)
	(arc
		(start 391.795 -122.951748)
		(mid 391.85135 -122.757898)
		(end 391.995152 -122.616214)
		(width 0.0889)
		(layer "In11.Cu")
		(net "SATA6G_S0_TX_DN")
	)
	(segment
		(start 377.313444 -29.439108)
		(end 377.5202 -29.232352)
		(width 0.1143)
		(layer "F.Cu")
		(net "SATA6G_S0_RX_DP")
	)
	(segment
		(start 393.68095 -121.01576)
		(end 394.17625 -121.245884)
		(width 0.1143)
		(layer "F.Cu")
		(net "SATA6G_S0_RX_DP")
	)
	(segment
		(start 376.774964 -29.439108)
		(end 377.313444 -29.439108)
		(width 0.1143)
		(layer "F.Cu")
		(net "SATA6G_S0_RX_DP")
	)
	(via
		(at 394.17625 -121.245884)
		(size 0.508)
		(drill 0.254)
		(layers "F.Cu" "B.Cu")
		(net "SATA6G_S0_RX_DP")
	)
	(via
		(at 376.774964 -29.439108)
		(size 0.508)
		(drill 0.254)
		(layers "F.Cu" "B.Cu")
		(net "SATA6G_S0_RX_DP")
	)
	(segment
		(start 403.420072 -112.603534)
		(end 403.508972 -112.692434)
		(width 0.0889)
		(layer "In11.Cu")
		(net "SATA6G_S0_RX_DP")
	)
	(segment
		(start 405.158194 -74.803)
		(end 405.539448 -72.940164)
		(width 0.1143)
		(layer "In11.Cu")
		(net "SATA6G_S0_RX_DP")
	)
	(segment
		(start 409.274518 -97.901252)
		(end 408.454098 -97.080578)
		(width 0.1143)
		(layer "In11.Cu")
		(net "SATA6G_S0_RX_DP")
	)
	(segment
		(start 381.90805 -34.72815)
		(end 380.768098 -34.496248)
		(width 0.1143)
		(layer "In11.Cu")
		(net "SATA6G_S0_RX_DP")
	)
	(segment
		(start 408.180032 -102.658926)
		(end 409.274518 -101.56444)
		(width 0.1143)
		(layer "In11.Cu")
		(net "SATA6G_S0_RX_DP")
	)
	(segment
		(start 394.7668 -119.550434)
		(end 394.7668 -119.517668)
		(width 0.0889)
		(layer "In11.Cu")
		(net "SATA6G_S0_RX_DP")
	)
	(segment
		(start 394.861034 -51.977544)
		(end 395.146276 -50.575464)
		(width 0.1143)
		(layer "In11.Cu")
		(net "SATA6G_S0_RX_DP")
	)
	(segment
		(start 377.250198 -29.914342)
		(end 376.774964 -29.439108)
		(width 0.1143)
		(layer "In11.Cu")
		(net "SATA6G_S0_RX_DP")
	)
	(segment
		(start 383.812542 -38.056566)
		(end 383.882646 -37.712142)
		(width 0.1143)
		(layer "In11.Cu")
		(net "SATA6G_S0_RX_DP")
	)
	(segment
		(start 383.882646 -37.712142)
		(end 383.8829 -37.712142)
		(width 0.1143)
		(layer "In11.Cu")
		(net "SATA6G_S0_RX_DP")
	)
	(segment
		(start 403.153372 -112.603534)
		(end 403.420072 -112.603534)
		(width 0.0889)
		(layer "In11.Cu")
		(net "SATA6G_S0_RX_DP")
	)
	(segment
		(start 400.874738 -114.109246)
		(end 401.06346 -113.920524)
		(width 0.0889)
		(layer "In11.Cu")
		(net "SATA6G_S0_RX_DP")
	)
	(segment
		(start 396.2527 -118.691914)
		(end 396.2527 -118.659148)
		(width 0.0889)
		(layer "In11.Cu")
		(net "SATA6G_S0_RX_DP")
	)
	(segment
		(start 394.2715 -120.408954)
		(end 394.2715 -120.376188)
		(width 0.0889)
		(layer "In11.Cu")
		(net "SATA6G_S0_RX_DP")
	)
	(segment
		(start 408.01036 -106.16184)
		(end 408.180032 -105.991914)
		(width 0.1143)
		(layer "In11.Cu")
		(net "SATA6G_S0_RX_DP")
	)
	(segment
		(start 389.502904 -43.92676)
		(end 386.91566 -43.400472)
		(width 0.1143)
		(layer "In11.Cu")
		(net "SATA6G_S0_RX_DP")
	)
	(segment
		(start 403.864572 -112.603534)
		(end 404.24989 -112.603534)
		(width 0.0889)
		(layer "In11.Cu")
		(net "SATA6G_S0_RX_DP")
	)
	(segment
		(start 400.05762 -114.800634)
		(end 400.246088 -114.612166)
		(width 0.0889)
		(layer "In11.Cu")
		(net "SATA6G_S0_RX_DP")
	)
	(segment
		(start 406.645872 -107.431078)
		(end 406.731978 -107.008168)
		(width 0.1143)
		(layer "In11.Cu")
		(net "SATA6G_S0_RX_DP")
	)
	(segment
		(start 404.761192 -112.654334)
		(end 405.308562 -112.292638)
		(width 0.1143)
		(layer "In11.Cu")
		(net "SATA6G_S0_RX_DP")
	)
	(segment
		(start 399.359374 -115.49888)
		(end 399.743168 -115.115086)
		(width 0.0889)
		(layer "In11.Cu")
		(net "SATA6G_S0_RX_DP")
	)
	(segment
		(start 408.079194 -69.102732)
		(end 408.377644 -67.635628)
		(width 0.1143)
		(layer "In11.Cu")
		(net "SATA6G_S0_RX_DP")
	)
	(segment
		(start 398.7292 -116.116354)
		(end 398.7292 -116.094764)
		(width 0.0889)
		(layer "In11.Cu")
		(net "SATA6G_S0_RX_DP")
	)
	(segment
		(start 406.907746 -108.71708)
		(end 406.645872 -107.431078)
		(width 0.1143)
		(layer "In11.Cu")
		(net "SATA6G_S0_RX_DP")
	)
	(segment
		(start 407.36139 -62.639956)
		(end 406.64765 -61.561472)
		(width 0.1143)
		(layer "In11.Cu")
		(net "SATA6G_S0_RX_DP")
	)
	(segment
		(start 401.06346 -113.920524)
		(end 401.06346 -113.794794)
		(width 0.0889)
		(layer "In11.Cu")
		(net "SATA6G_S0_RX_DP")
	)
	(segment
		(start 405.55926 -79.183738)
		(end 405.152606 -78.569312)
		(width 0.1143)
		(layer "In11.Cu")
		(net "SATA6G_S0_RX_DP")
	)
	(segment
		(start 402.708872 -112.603534)
		(end 402.797772 -112.692434)
		(width 0.0889)
		(layer "In11.Cu")
		(net "SATA6G_S0_RX_DP")
	)
	(segment
		(start 408.454098 -97.080578)
		(end 408.128978 -97.080578)
		(width 0.1143)
		(layer "In11.Cu")
		(net "SATA6G_S0_RX_DP")
	)
	(segment
		(start 397.2433 -116.974874)
		(end 397.2433 -116.942108)
		(width 0.0889)
		(layer "In11.Cu")
		(net "SATA6G_S0_RX_DP")
	)
	(segment
		(start 402.442172 -112.603534)
		(end 402.708872 -112.603534)
		(width 0.0889)
		(layer "In11.Cu")
		(net "SATA6G_S0_RX_DP")
	)
	(segment
		(start 403.508972 -112.692434)
		(end 403.775672 -112.692434)
		(width 0.0889)
		(layer "In11.Cu")
		(net "SATA6G_S0_RX_DP")
	)
	(segment
		(start 399.05178 -115.654074)
		(end 399.206974 -115.49888)
		(width 0.0889)
		(layer "In11.Cu")
		(net "SATA6G_S0_RX_DP")
	)
	(segment
		(start 399.743168 -115.115086)
		(end 399.868898 -115.115086)
		(width 0.0889)
		(layer "In11.Cu")
		(net "SATA6G_S0_RX_DP")
	)
	(segment
		(start 383.470404 -39.738808)
		(end 383.812542 -38.056566)
		(width 0.1143)
		(layer "In11.Cu")
		(net "SATA6G_S0_RX_DP")
	)
	(segment
		(start 407.71826 -89.796112)
		(end 405.55926 -79.183738)
		(width 0.1143)
		(layer "In11.Cu")
		(net "SATA6G_S0_RX_DP")
	)
	(segment
		(start 408.377644 -67.635628)
		(end 407.36139 -62.639956)
		(width 0.1143)
		(layer "In11.Cu")
		(net "SATA6G_S0_RX_DP")
	)
	(segment
		(start 383.885694 -40.366442)
		(end 383.470404 -39.738808)
		(width 0.1143)
		(layer "In11.Cu")
		(net "SATA6G_S0_RX_DP")
	)
	(segment
		(start 405.539448 -72.940164)
		(end 408.079194 -69.102732)
		(width 0.1143)
		(layer "In11.Cu")
		(net "SATA6G_S0_RX_DP")
	)
	(segment
		(start 401.411186 -113.447068)
		(end 401.411186 -112.92332)
		(width 0.0889)
		(layer "In11.Cu")
		(net "SATA6G_S0_RX_DP")
	)
	(segment
		(start 395.146276 -50.575464)
		(end 394.21181 -49.163732)
		(width 0.1143)
		(layer "In11.Cu")
		(net "SATA6G_S0_RX_DP")
	)
	(segment
		(start 394.00734 -121.539)
		(end 393.9286 -121.560082)
		(width 0.0889)
		(layer "In11.Cu")
		(net "SATA6G_S0_RX_DP")
	)
	(segment
		(start 400.05762 -114.926364)
		(end 400.05762 -114.800634)
		(width 0.0889)
		(layer "In11.Cu")
		(net "SATA6G_S0_RX_DP")
	)
	(segment
		(start 398.297908 -57.17032)
		(end 394.861034 -51.977544)
		(width 0.1143)
		(layer "In11.Cu")
		(net "SATA6G_S0_RX_DP")
	)
	(segment
		(start 385.066032 -40.606726)
		(end 383.885694 -40.366442)
		(width 0.1143)
		(layer "In11.Cu")
		(net "SATA6G_S0_RX_DP")
	)
	(segment
		(start 394.17625 -121.245884)
		(end 394.00734 -121.539)
		(width 0.0889)
		(layer "In11.Cu")
		(net "SATA6G_S0_RX_DP")
	)
	(segment
		(start 379.33122 -32.326072)
		(end 378.717556 -31.919672)
		(width 0.1143)
		(layer "In11.Cu")
		(net "SATA6G_S0_RX_DP")
	)
	(segment
		(start 399.868898 -115.115086)
		(end 400.05762 -114.926364)
		(width 0.0889)
		(layer "In11.Cu")
		(net "SATA6G_S0_RX_DP")
	)
	(segment
		(start 399.206974 -115.49888)
		(end 399.359374 -115.49888)
		(width 0.0889)
		(layer "In11.Cu")
		(net "SATA6G_S0_RX_DP")
	)
	(segment
		(start 409.274518 -101.56444)
		(end 409.274518 -97.901252)
		(width 0.1143)
		(layer "In11.Cu")
		(net "SATA6G_S0_RX_DP")
	)
	(segment
		(start 392.775948 -48.871632)
		(end 389.502904 -43.92676)
		(width 0.1143)
		(layer "In11.Cu")
		(net "SATA6G_S0_RX_DP")
	)
	(segment
		(start 400.56054 -114.423444)
		(end 400.56054 -114.297714)
		(width 0.0889)
		(layer "In11.Cu")
		(net "SATA6G_S0_RX_DP")
	)
	(segment
		(start 404.322788 -112.654334)
		(end 404.761192 -112.654334)
		(width 0.1143)
		(layer "In11.Cu")
		(net "SATA6G_S0_RX_DP")
	)
	(segment
		(start 406.872186 -108.771182)
		(end 406.907746 -108.71708)
		(width 0.1143)
		(layer "In11.Cu")
		(net "SATA6G_S0_RX_DP")
	)
	(segment
		(start 400.56054 -114.297714)
		(end 400.749008 -114.109246)
		(width 0.0889)
		(layer "In11.Cu")
		(net "SATA6G_S0_RX_DP")
	)
	(segment
		(start 407.71826 -96.669606)
		(end 407.71826 -89.796112)
		(width 0.1143)
		(layer "In11.Cu")
		(net "SATA6G_S0_RX_DP")
	)
	(segment
		(start 408.180032 -105.991914)
		(end 408.180032 -102.658926)
		(width 0.1143)
		(layer "In11.Cu")
		(net "SATA6G_S0_RX_DP")
	)
	(segment
		(start 402.353272 -112.692434)
		(end 402.442172 -112.603534)
		(width 0.0889)
		(layer "In11.Cu")
		(net "SATA6G_S0_RX_DP")
	)
	(segment
		(start 404.804118 -76.5683)
		(end 404.82901 -76.411582)
		(width 0.1143)
		(layer "In11.Cu")
		(net "SATA6G_S0_RX_DP")
	)
	(segment
		(start 404.82901 -76.411582)
		(end 405.158194 -74.803)
		(width 0.1143)
		(layer "In11.Cu")
		(net "SATA6G_S0_RX_DP")
	)
	(segment
		(start 406.731978 -107.008168)
		(end 408.01036 -106.16184)
		(width 0.1143)
		(layer "In11.Cu")
		(net "SATA6G_S0_RX_DP")
	)
	(segment
		(start 404.172166 -61.058298)
		(end 398.297908 -57.17032)
		(width 0.1143)
		(layer "In11.Cu")
		(net "SATA6G_S0_RX_DP")
	)
	(segment
		(start 406.520904 -110.497112)
		(end 406.872186 -108.771182)
		(width 0.1143)
		(layer "In11.Cu")
		(net "SATA6G_S0_RX_DP")
	)
	(segment
		(start 402.797772 -112.692434)
		(end 403.064472 -112.692434)
		(width 0.0889)
		(layer "In11.Cu")
		(net "SATA6G_S0_RX_DP")
	)
	(segment
		(start 394.21181 -49.163732)
		(end 392.775948 -48.871632)
		(width 0.1143)
		(layer "In11.Cu")
		(net "SATA6G_S0_RX_DP")
	)
	(segment
		(start 377.98502 -30.81274)
		(end 377.98502 -30.377384)
		(width 0.1143)
		(layer "In11.Cu")
		(net "SATA6G_S0_RX_DP")
	)
	(segment
		(start 404.30069 -112.654334)
		(end 404.322788 -112.654334)
		(width 0.0889)
		(layer "In11.Cu")
		(net "SATA6G_S0_RX_DP")
	)
	(segment
		(start 403.064472 -112.692434)
		(end 403.153372 -112.603534)
		(width 0.0889)
		(layer "In11.Cu")
		(net "SATA6G_S0_RX_DP")
	)
	(segment
		(start 403.775672 -112.692434)
		(end 403.864572 -112.603534)
		(width 0.0889)
		(layer "In11.Cu")
		(net "SATA6G_S0_RX_DP")
	)
	(segment
		(start 401.411186 -112.92332)
		(end 401.730972 -112.603534)
		(width 0.0889)
		(layer "In11.Cu")
		(net "SATA6G_S0_RX_DP")
	)
	(segment
		(start 401.730972 -112.603534)
		(end 401.997672 -112.603534)
		(width 0.0889)
		(layer "In11.Cu")
		(net "SATA6G_S0_RX_DP")
	)
	(segment
		(start 401.997672 -112.603534)
		(end 402.086572 -112.692434)
		(width 0.0889)
		(layer "In11.Cu")
		(net "SATA6G_S0_RX_DP")
	)
	(segment
		(start 380.768098 -34.496248)
		(end 379.33122 -32.326072)
		(width 0.1143)
		(layer "In11.Cu")
		(net "SATA6G_S0_RX_DP")
	)
	(segment
		(start 405.308562 -112.292638)
		(end 406.520904 -110.497112)
		(width 0.1143)
		(layer "In11.Cu")
		(net "SATA6G_S0_RX_DP")
	)
	(segment
		(start 400.246088 -114.612166)
		(end 400.371818 -114.612166)
		(width 0.0889)
		(layer "In11.Cu")
		(net "SATA6G_S0_RX_DP")
	)
	(segment
		(start 393.7762 -121.25706)
		(end 393.7762 -121.234708)
		(width 0.0889)
		(layer "In11.Cu")
		(net "SATA6G_S0_RX_DP")
	)
	(segment
		(start 404.24989 -112.603534)
		(end 404.30069 -112.654334)
		(width 0.0889)
		(layer "In11.Cu")
		(net "SATA6G_S0_RX_DP")
	)
	(segment
		(start 405.152606 -78.569312)
		(end 404.804118 -76.5683)
		(width 0.1143)
		(layer "In11.Cu")
		(net "SATA6G_S0_RX_DP")
	)
	(segment
		(start 401.06346 -113.794794)
		(end 401.411186 -113.447068)
		(width 0.0889)
		(layer "In11.Cu")
		(net "SATA6G_S0_RX_DP")
	)
	(segment
		(start 406.64765 -61.561472)
		(end 404.172166 -61.058298)
		(width 0.1143)
		(layer "In11.Cu")
		(net "SATA6G_S0_RX_DP")
	)
	(segment
		(start 377.98502 -30.377384)
		(end 377.521978 -29.914342)
		(width 0.1143)
		(layer "In11.Cu")
		(net "SATA6G_S0_RX_DP")
	)
	(segment
		(start 377.521978 -29.914342)
		(end 377.250198 -29.914342)
		(width 0.1143)
		(layer "In11.Cu")
		(net "SATA6G_S0_RX_DP")
	)
	(segment
		(start 396.748 -117.833394)
		(end 396.748 -117.800628)
		(width 0.0889)
		(layer "In11.Cu")
		(net "SATA6G_S0_RX_DP")
	)
	(segment
		(start 383.8829 -37.712142)
		(end 381.90805 -34.72815)
		(width 0.1143)
		(layer "In11.Cu")
		(net "SATA6G_S0_RX_DP")
	)
	(segment
		(start 400.749008 -114.109246)
		(end 400.874738 -114.109246)
		(width 0.0889)
		(layer "In11.Cu")
		(net "SATA6G_S0_RX_DP")
	)
	(segment
		(start 386.91566 -43.400472)
		(end 385.066032 -40.606726)
		(width 0.1143)
		(layer "In11.Cu")
		(net "SATA6G_S0_RX_DP")
	)
	(segment
		(start 408.128978 -97.080578)
		(end 407.71826 -96.669606)
		(width 0.1143)
		(layer "In11.Cu")
		(net "SATA6G_S0_RX_DP")
	)
	(segment
		(start 400.371818 -114.612166)
		(end 400.56054 -114.423444)
		(width 0.0889)
		(layer "In11.Cu")
		(net "SATA6G_S0_RX_DP")
	)
	(segment
		(start 402.086572 -112.692434)
		(end 402.353272 -112.692434)
		(width 0.0889)
		(layer "In11.Cu")
		(net "SATA6G_S0_RX_DP")
	)
	(segment
		(start 378.717556 -31.919672)
		(end 377.98502 -30.81274)
		(width 0.1143)
		(layer "In11.Cu")
		(net "SATA6G_S0_RX_DP")
	)
	(arc
		(start 396.748 -117.800628)
		(mid 396.80435 -117.606778)
		(end 396.948152 -117.465094)
		(width 0.0889)
		(layer "In11.Cu")
		(net "SATA6G_S0_RX_DP")
	)
	(arc
		(start 395.957552 -119.182134)
		(mid 396.168416 -118.97513)
		(end 396.2527 -118.691914)
		(width 0.0889)
		(layer "In11.Cu")
		(net "SATA6G_S0_RX_DP")
	)
	(arc
		(start 396.948152 -117.465094)
		(mid 397.159016 -117.25809)
		(end 397.2433 -116.974874)
		(width 0.0889)
		(layer "In11.Cu")
		(net "SATA6G_S0_RX_DP")
	)
	(arc
		(start 397.843248 -116.606574)
		(mid 398.13865 -116.685705)
		(end 398.434052 -116.606574)
		(width 0.0889)
		(layer "In11.Cu")
		(net "SATA6G_S0_RX_DP")
	)
	(arc
		(start 394.966952 -119.182134)
		(mid 395.16685 -119.128635)
		(end 395.366748 -119.182134)
		(width 0.0889)
		(layer "In11.Cu")
		(net "SATA6G_S0_RX_DP")
	)
	(arc
		(start 393.9286 -121.560082)
		(mid 393.818688 -121.42552)
		(end 393.7762 -121.25706)
		(width 0.0889)
		(layer "In11.Cu")
		(net "SATA6G_S0_RX_DP")
	)
	(arc
		(start 395.366748 -119.182134)
		(mid 395.66215 -119.261265)
		(end 395.957552 -119.182134)
		(width 0.0889)
		(layer "In11.Cu")
		(net "SATA6G_S0_RX_DP")
	)
	(arc
		(start 398.929352 -115.748054)
		(mid 398.99338 -115.70532)
		(end 399.051272 -115.654582)
		(width 0.0889)
		(layer "In11.Cu")
		(net "SATA6G_S0_RX_DP")
	)
	(arc
		(start 393.7762 -121.234708)
		(mid 393.83255 -121.040858)
		(end 393.976352 -120.899174)
		(width 0.0889)
		(layer "In11.Cu")
		(net "SATA6G_S0_RX_DP")
	)
	(arc
		(start 398.7292 -116.094764)
		(mid 398.782888 -115.89463)
		(end 398.929352 -115.748054)
		(width 0.0889)
		(layer "In11.Cu")
		(net "SATA6G_S0_RX_DP")
	)
	(arc
		(start 394.7668 -119.517668)
		(mid 394.82315 -119.323818)
		(end 394.966952 -119.182134)
		(width 0.0889)
		(layer "In11.Cu")
		(net "SATA6G_S0_RX_DP")
	)
	(arc
		(start 393.976352 -120.899174)
		(mid 394.187216 -120.69217)
		(end 394.2715 -120.408954)
		(width 0.0889)
		(layer "In11.Cu")
		(net "SATA6G_S0_RX_DP")
	)
	(arc
		(start 398.434052 -116.606574)
		(mid 398.644916 -116.39957)
		(end 398.7292 -116.116354)
		(width 0.0889)
		(layer "In11.Cu")
		(net "SATA6G_S0_RX_DP")
	)
	(arc
		(start 396.452852 -118.323614)
		(mid 396.663716 -118.11661)
		(end 396.748 -117.833394)
		(width 0.0889)
		(layer "In11.Cu")
		(net "SATA6G_S0_RX_DP")
	)
	(arc
		(start 399.051272 -115.654582)
		(mid 399.051526 -115.654328)
		(end 399.05178 -115.654074)
		(width 0.0889)
		(layer "In11.Cu")
		(net "SATA6G_S0_RX_DP")
	)
	(arc
		(start 396.2527 -118.659148)
		(mid 396.30905 -118.465298)
		(end 396.452852 -118.323614)
		(width 0.0889)
		(layer "In11.Cu")
		(net "SATA6G_S0_RX_DP")
	)
	(arc
		(start 394.471652 -120.040654)
		(mid 394.682516 -119.83365)
		(end 394.7668 -119.550434)
		(width 0.0889)
		(layer "In11.Cu")
		(net "SATA6G_S0_RX_DP")
	)
	(arc
		(start 397.2433 -116.942108)
		(mid 397.29965 -116.748258)
		(end 397.443452 -116.606574)
		(width 0.0889)
		(layer "In11.Cu")
		(net "SATA6G_S0_RX_DP")
	)
	(arc
		(start 397.443452 -116.606574)
		(mid 397.64335 -116.553075)
		(end 397.843248 -116.606574)
		(width 0.0889)
		(layer "In11.Cu")
		(net "SATA6G_S0_RX_DP")
	)
	(arc
		(start 394.2715 -120.376188)
		(mid 394.32785 -120.182338)
		(end 394.471652 -120.040654)
		(width 0.0889)
		(layer "In11.Cu")
		(net "SATA6G_S0_RX_DP")
	)
	(segment
		(start 393.612116 -122.0724)
		(end 393.68095 -122.104404)
		(width 0.1143)
		(layer "F.Cu")
		(net "SATA6G_S0_RX_DN")
	)
	(segment
		(start 376.774964 -30.669484)
		(end 376.851164 -30.745684)
		(width 0.1143)
		(layer "F.Cu")
		(net "SATA6G_S0_RX_DN")
	)
	(segment
		(start 393.18565 -121.87428)
		(end 393.612116 -122.0724)
		(width 0.1143)
		(layer "F.Cu")
		(net "SATA6G_S0_RX_DN")
	)
	(segment
		(start 376.851164 -30.745684)
		(end 377.403868 -30.745684)
		(width 0.1143)
		(layer "F.Cu")
		(net "SATA6G_S0_RX_DN")
	)
	(segment
		(start 377.403868 -30.745684)
		(end 377.5202 -30.629352)
		(width 0.1143)
		(layer "F.Cu")
		(net "SATA6G_S0_RX_DN")
	)
	(via
		(at 376.774964 -30.669484)
		(size 0.508)
		(drill 0.254)
		(layers "F.Cu" "B.Cu")
		(net "SATA6G_S0_RX_DN")
	)
	(via
		(at 393.68095 -122.104404)
		(size 0.508)
		(drill 0.254)
		(layers "F.Cu" "B.Cu")
		(net "SATA6G_S0_RX_DN")
	)
	(segment
		(start 408.9019 -97.941892)
		(end 408.332686 -97.372678)
		(width 0.1143)
		(layer "In11.Cu")
		(net "SATA6G_S0_RX_DN")
	)
	(segment
		(start 401.220686 -113.368074)
		(end 401.220686 -112.844326)
		(width 0.0889)
		(layer "In11.Cu")
		(net "SATA6G_S0_RX_DN")
	)
	(segment
		(start 386.738876 -43.6626)
		(end 384.889248 -40.868854)
		(width 0.1143)
		(layer "In11.Cu")
		(net "SATA6G_S0_RX_DN")
	)
	(segment
		(start 394.835634 -50.635916)
		(end 394.034772 -49.426114)
		(width 0.1143)
		(layer "In11.Cu")
		(net "SATA6G_S0_RX_DN")
	)
	(segment
		(start 396.5575 -117.82298)
		(end 396.5575 -117.790214)
		(width 0.0889)
		(layer "In11.Cu")
		(net "SATA6G_S0_RX_DN")
	)
	(segment
		(start 398.916906 -115.519454)
		(end 398.916906 -115.5192)
		(width 0.0889)
		(layer "In11.Cu")
		(net "SATA6G_S0_RX_DN")
	)
	(segment
		(start 396.0622 -118.6815)
		(end 396.0622 -118.648734)
		(width 0.0889)
		(layer "In11.Cu")
		(net "SATA6G_S0_RX_DN")
	)
	(segment
		(start 401.220686 -112.844326)
		(end 401.651978 -112.413034)
		(width 0.0889)
		(layer "In11.Cu")
		(net "SATA6G_S0_RX_DN")
	)
	(segment
		(start 408.332686 -97.372678)
		(end 408.00782 -97.372678)
		(width 0.1143)
		(layer "In11.Cu")
		(net "SATA6G_S0_RX_DN")
	)
	(segment
		(start 384.889248 -40.868854)
		(end 383.708656 -40.628824)
		(width 0.1143)
		(layer "In11.Cu")
		(net "SATA6G_S0_RX_DN")
	)
	(segment
		(start 408.982418 -98.022664)
		(end 408.901646 -97.941892)
		(width 0.1143)
		(layer "In11.Cu")
		(net "SATA6G_S0_RX_DN")
	)
	(segment
		(start 407.550874 -65.037462)
		(end 407.356056 -64.90843)
		(width 0.1143)
		(layer "In11.Cu")
		(net "SATA6G_S0_RX_DN")
	)
	(segment
		(start 405.967946 -71.463662)
		(end 406.157176 -71.177912)
		(width 0.1143)
		(layer "In11.Cu")
		(net "SATA6G_S0_RX_DN")
	)
	(segment
		(start 393.5857 -121.267474)
		(end 393.5857 -121.224294)
		(width 0.0889)
		(layer "In11.Cu")
		(net "SATA6G_S0_RX_DN")
	)
	(segment
		(start 394.5763 -119.54002)
		(end 394.5763 -119.507254)
		(width 0.0889)
		(layer "In11.Cu")
		(net "SATA6G_S0_RX_DN")
	)
	(segment
		(start 377.40082 -30.206442)
		(end 377.238006 -30.206442)
		(width 0.1143)
		(layer "In11.Cu")
		(net "SATA6G_S0_RX_DN")
	)
	(segment
		(start 406.246076 -110.381796)
		(end 406.597104 -108.656628)
		(width 0.1143)
		(layer "In11.Cu")
		(net "SATA6G_S0_RX_DN")
	)
	(segment
		(start 406.718008 -70.330568)
		(end 406.946862 -70.283832)
		(width 0.1143)
		(layer "In11.Cu")
		(net "SATA6G_S0_RX_DN")
	)
	(segment
		(start 404.05812 -61.33338)
		(end 398.087088 -57.38114)
		(width 0.1143)
		(layer "In11.Cu")
		(net "SATA6G_S0_RX_DN")
	)
	(segment
		(start 404.859998 -74.803)
		(end 405.26462 -72.825864)
		(width 0.1143)
		(layer "In11.Cu")
		(net "SATA6G_S0_RX_DN")
	)
	(segment
		(start 383.159762 -39.79926)
		(end 383.514346 -38.056566)
		(width 0.1143)
		(layer "In11.Cu")
		(net "SATA6G_S0_RX_DN")
	)
	(segment
		(start 407.507694 -69.436488)
		(end 407.804112 -68.988686)
		(width 0.1143)
		(layer "In11.Cu")
		(net "SATA6G_S0_RX_DN")
	)
	(segment
		(start 405.825198 -71.97852)
		(end 406.014428 -71.692516)
		(width 0.1143)
		(layer "In11.Cu")
		(net "SATA6G_S0_RX_DN")
	)
	(segment
		(start 392.59891 -49.134014)
		(end 389.325866 -44.189142)
		(width 0.1143)
		(layer "In11.Cu")
		(net "SATA6G_S0_RX_DN")
	)
	(segment
		(start 406.470612 -61.823854)
		(end 404.05812 -61.33338)
		(width 0.1143)
		(layer "In11.Cu")
		(net "SATA6G_S0_RX_DN")
	)
	(segment
		(start 404.507954 -76.570586)
		(end 404.541482 -76.359258)
		(width 0.1143)
		(layer "In11.Cu")
		(net "SATA6G_S0_RX_DN")
	)
	(segment
		(start 407.348182 -64.041782)
		(end 407.153618 -63.91275)
		(width 0.1143)
		(layer "In11.Cu")
		(net "SATA6G_S0_RX_DN")
	)
	(segment
		(start 383.708656 -40.628824)
		(end 383.159762 -39.79926)
		(width 0.1143)
		(layer "In11.Cu")
		(net "SATA6G_S0_RX_DN")
	)
	(segment
		(start 405.284178 -79.297784)
		(end 404.875238 -78.679548)
		(width 0.1143)
		(layer "In11.Cu")
		(net "SATA6G_S0_RX_DN")
	)
	(segment
		(start 407.416762 -64.377824)
		(end 407.348182 -64.041782)
		(width 0.1143)
		(layer "In11.Cu")
		(net "SATA6G_S0_RX_DN")
	)
	(segment
		(start 393.84986 -121.811288)
		(end 393.82573 -121.72188)
		(width 0.0889)
		(layer "In11.Cu")
		(net "SATA6G_S0_RX_DN")
	)
	(segment
		(start 377.238006 -30.206442)
		(end 376.774964 -30.669484)
		(width 0.1143)
		(layer "In11.Cu")
		(net "SATA6G_S0_RX_DN")
	)
	(segment
		(start 389.325866 -44.189142)
		(end 386.738876 -43.6626)
		(width 0.1143)
		(layer "In11.Cu")
		(net "SATA6G_S0_RX_DN")
	)
	(segment
		(start 377.69292 -30.900878)
		(end 377.69292 -30.498542)
		(width 0.1143)
		(layer "In11.Cu")
		(net "SATA6G_S0_RX_DN")
	)
	(segment
		(start 408.00782 -97.372678)
		(end 407.42616 -96.790764)
		(width 0.1143)
		(layer "In11.Cu")
		(net "SATA6G_S0_RX_DN")
	)
	(segment
		(start 404.30069 -112.362234)
		(end 404.322788 -112.362234)
		(width 0.0889)
		(layer "In11.Cu")
		(net "SATA6G_S0_RX_DN")
	)
	(segment
		(start 406.014428 -71.692516)
		(end 405.967946 -71.463662)
		(width 0.1143)
		(layer "In11.Cu")
		(net "SATA6G_S0_RX_DN")
	)
	(segment
		(start 404.541482 -76.359258)
		(end 404.859998 -74.803)
		(width 0.1143)
		(layer "In11.Cu")
		(net "SATA6G_S0_RX_DN")
	)
	(segment
		(start 394.550646 -52.037996)
		(end 394.835634 -50.635916)
		(width 0.1143)
		(layer "In11.Cu")
		(net "SATA6G_S0_RX_DN")
	)
	(segment
		(start 408.079448 -67.635628)
		(end 407.550874 -65.037462)
		(width 0.1143)
		(layer "In11.Cu")
		(net "SATA6G_S0_RX_DN")
	)
	(segment
		(start 404.322788 -112.362234)
		(end 404.673308 -112.362234)
		(width 0.1143)
		(layer "In11.Cu")
		(net "SATA6G_S0_RX_DN")
	)
	(segment
		(start 407.08961 -69.768974)
		(end 407.27884 -69.483224)
		(width 0.1143)
		(layer "In11.Cu")
		(net "SATA6G_S0_RX_DN")
	)
	(segment
		(start 379.1204 -32.536892)
		(end 378.506736 -32.130492)
		(width 0.1143)
		(layer "In11.Cu")
		(net "SATA6G_S0_RX_DN")
	)
	(segment
		(start 406.347676 -107.431078)
		(end 406.421336 -107.068874)
		(width 0.1143)
		(layer "In11.Cu")
		(net "SATA6G_S0_RX_DN")
	)
	(segment
		(start 407.42616 -89.825576)
		(end 406.355042 -84.561426)
		(width 0.1143)
		(layer "In11.Cu")
		(net "SATA6G_S0_RX_DN")
	)
	(segment
		(start 378.506736 -32.130492)
		(end 377.69292 -30.900878)
		(width 0.1143)
		(layer "In11.Cu")
		(net "SATA6G_S0_RX_DN")
	)
	(segment
		(start 407.086308 -62.754002)
		(end 406.470612 -61.823854)
		(width 0.1143)
		(layer "In11.Cu")
		(net "SATA6G_S0_RX_DN")
	)
	(segment
		(start 406.946862 -70.283832)
		(end 407.136092 -69.997828)
		(width 0.1143)
		(layer "In11.Cu")
		(net "SATA6G_S0_RX_DN")
	)
	(segment
		(start 399.12798 -115.30838)
		(end 399.28038 -115.30838)
		(width 0.0889)
		(layer "In11.Cu")
		(net "SATA6G_S0_RX_DN")
	)
	(segment
		(start 407.21407 -63.382144)
		(end 407.086308 -62.754002)
		(width 0.1143)
		(layer "In11.Cu")
		(net "SATA6G_S0_RX_DN")
	)
	(segment
		(start 404.24989 -112.413034)
		(end 404.30069 -112.362234)
		(width 0.0889)
		(layer "In11.Cu")
		(net "SATA6G_S0_RX_DN")
	)
	(segment
		(start 407.824432 -105.934256)
		(end 407.887932 -105.870756)
		(width 0.1143)
		(layer "In11.Cu")
		(net "SATA6G_S0_RX_DN")
	)
	(segment
		(start 407.356056 -64.90843)
		(end 407.28773 -64.572388)
		(width 0.1143)
		(layer "In11.Cu")
		(net "SATA6G_S0_RX_DN")
	)
	(segment
		(start 407.28773 -64.572388)
		(end 407.416762 -64.377824)
		(width 0.1143)
		(layer "In11.Cu")
		(net "SATA6G_S0_RX_DN")
	)
	(segment
		(start 405.26462 -72.825864)
		(end 405.453596 -72.53986)
		(width 0.1143)
		(layer "In11.Cu")
		(net "SATA6G_S0_RX_DN")
	)
	(segment
		(start 405.098758 -112.080802)
		(end 406.246076 -110.381796)
		(width 0.1143)
		(layer "In11.Cu")
		(net "SATA6G_S0_RX_DN")
	)
	(segment
		(start 399.28038 -115.30838)
		(end 401.220686 -113.368074)
		(width 0.0889)
		(layer "In11.Cu")
		(net "SATA6G_S0_RX_DN")
	)
	(segment
		(start 407.085292 -63.576962)
		(end 407.21407 -63.382144)
		(width 0.1143)
		(layer "In11.Cu")
		(net "SATA6G_S0_RX_DN")
	)
	(segment
		(start 405.453596 -72.53986)
		(end 405.407114 -72.311006)
		(width 0.1143)
		(layer "In11.Cu")
		(net "SATA6G_S0_RX_DN")
	)
	(segment
		(start 404.875238 -78.679548)
		(end 404.507954 -76.570586)
		(width 0.1143)
		(layer "In11.Cu")
		(net "SATA6G_S0_RX_DN")
	)
	(segment
		(start 406.57526 -70.845172)
		(end 406.528778 -70.616318)
		(width 0.1143)
		(layer "In11.Cu")
		(net "SATA6G_S0_RX_DN")
	)
	(segment
		(start 404.673308 -112.362234)
		(end 405.098758 -112.080802)
		(width 0.1143)
		(layer "In11.Cu")
		(net "SATA6G_S0_RX_DN")
	)
	(segment
		(start 406.421336 -107.068874)
		(end 406.421336 -107.06862)
		(width 0.1143)
		(layer "In11.Cu")
		(net "SATA6G_S0_RX_DN")
	)
	(segment
		(start 377.69292 -30.498542)
		(end 377.40082 -30.206442)
		(width 0.1143)
		(layer "In11.Cu")
		(net "SATA6G_S0_RX_DN")
	)
	(segment
		(start 398.916652 -115.519708)
		(end 398.916906 -115.519454)
		(width 0.0889)
		(layer "In11.Cu")
		(net "SATA6G_S0_RX_DN")
	)
	(segment
		(start 407.887932 -105.870756)
		(end 407.887932 -102.537768)
		(width 0.1143)
		(layer "In11.Cu")
		(net "SATA6G_S0_RX_DN")
	)
	(segment
		(start 406.157176 -71.177912)
		(end 406.38603 -71.131176)
		(width 0.1143)
		(layer "In11.Cu")
		(net "SATA6G_S0_RX_DN")
	)
	(segment
		(start 405.596344 -72.025256)
		(end 405.825198 -71.97852)
		(width 0.1143)
		(layer "In11.Cu")
		(net "SATA6G_S0_RX_DN")
	)
	(segment
		(start 398.087088 -57.38114)
		(end 394.550646 -52.037996)
		(width 0.1143)
		(layer "In11.Cu")
		(net "SATA6G_S0_RX_DN")
	)
	(segment
		(start 398.5387 -116.10594)
		(end 398.5387 -116.09451)
		(width 0.0889)
		(layer "In11.Cu")
		(net "SATA6G_S0_RX_DN")
	)
	(segment
		(start 407.136092 -69.997828)
		(end 407.08961 -69.768974)
		(width 0.1143)
		(layer "In11.Cu")
		(net "SATA6G_S0_RX_DN")
	)
	(segment
		(start 406.421336 -107.06862)
		(end 406.469596 -106.831384)
		(width 0.1143)
		(layer "In11.Cu")
		(net "SATA6G_S0_RX_DN")
	)
	(segment
		(start 406.469596 -106.831384)
		(end 407.824432 -105.934256)
		(width 0.1143)
		(layer "In11.Cu")
		(net "SATA6G_S0_RX_DN")
	)
	(segment
		(start 398.91716 -115.5192)
		(end 399.12798 -115.30838)
		(width 0.0889)
		(layer "In11.Cu")
		(net "SATA6G_S0_RX_DN")
	)
	(segment
		(start 394.034772 -49.426114)
		(end 392.59891 -49.134014)
		(width 0.1143)
		(layer "In11.Cu")
		(net "SATA6G_S0_RX_DN")
	)
	(segment
		(start 407.42616 -96.790764)
		(end 407.42616 -89.825576)
		(width 0.1143)
		(layer "In11.Cu")
		(net "SATA6G_S0_RX_DN")
	)
	(segment
		(start 406.355042 -84.561426)
		(end 406.354788 -84.561426)
		(width 0.1143)
		(layer "In11.Cu")
		(net "SATA6G_S0_RX_DN")
	)
	(segment
		(start 406.354788 -84.561426)
		(end 405.284178 -79.297784)
		(width 0.1143)
		(layer "In11.Cu")
		(net "SATA6G_S0_RX_DN")
	)
	(segment
		(start 407.804112 -68.988686)
		(end 408.079448 -67.635628)
		(width 0.1143)
		(layer "In11.Cu")
		(net "SATA6G_S0_RX_DN")
	)
	(segment
		(start 406.528778 -70.616318)
		(end 406.718008 -70.330568)
		(width 0.1143)
		(layer "In11.Cu")
		(net "SATA6G_S0_RX_DN")
	)
	(segment
		(start 398.916906 -115.5192)
		(end 398.91716 -115.5192)
		(width 0.0889)
		(layer "In11.Cu")
		(net "SATA6G_S0_RX_DN")
	)
	(segment
		(start 397.0528 -116.96446)
		(end 397.0528 -116.931694)
		(width 0.0889)
		(layer "In11.Cu")
		(net "SATA6G_S0_RX_DN")
	)
	(segment
		(start 393.68095 -122.104404)
		(end 393.84986 -121.811288)
		(width 0.0889)
		(layer "In11.Cu")
		(net "SATA6G_S0_RX_DN")
	)
	(segment
		(start 406.597104 -108.656628)
		(end 406.347676 -107.431078)
		(width 0.1143)
		(layer "In11.Cu")
		(net "SATA6G_S0_RX_DN")
	)
	(segment
		(start 406.38603 -71.131176)
		(end 406.57526 -70.845172)
		(width 0.1143)
		(layer "In11.Cu")
		(net "SATA6G_S0_RX_DN")
	)
	(segment
		(start 407.27884 -69.483224)
		(end 407.507694 -69.436488)
		(width 0.1143)
		(layer "In11.Cu")
		(net "SATA6G_S0_RX_DN")
	)
	(segment
		(start 401.651978 -112.413034)
		(end 404.24989 -112.413034)
		(width 0.0889)
		(layer "In11.Cu")
		(net "SATA6G_S0_RX_DN")
	)
	(segment
		(start 408.982418 -101.443282)
		(end 408.982418 -98.022664)
		(width 0.1143)
		(layer "In11.Cu")
		(net "SATA6G_S0_RX_DN")
	)
	(segment
		(start 394.081 -120.39854)
		(end 394.081 -120.365774)
		(width 0.0889)
		(layer "In11.Cu")
		(net "SATA6G_S0_RX_DN")
	)
	(segment
		(start 407.887932 -102.537768)
		(end 408.982418 -101.443282)
		(width 0.1143)
		(layer "In11.Cu")
		(net "SATA6G_S0_RX_DN")
	)
	(segment
		(start 383.572258 -37.772594)
		(end 381.731012 -34.990532)
		(width 0.1143)
		(layer "In11.Cu")
		(net "SATA6G_S0_RX_DN")
	)
	(segment
		(start 383.514346 -38.056566)
		(end 383.572258 -37.772594)
		(width 0.1143)
		(layer "In11.Cu")
		(net "SATA6G_S0_RX_DN")
	)
	(segment
		(start 407.153618 -63.91275)
		(end 407.085292 -63.576962)
		(width 0.1143)
		(layer "In11.Cu")
		(net "SATA6G_S0_RX_DN")
	)
	(segment
		(start 381.731012 -34.990532)
		(end 380.591314 -34.758376)
		(width 0.1143)
		(layer "In11.Cu")
		(net "SATA6G_S0_RX_DN")
	)
	(segment
		(start 405.407114 -72.311006)
		(end 405.596344 -72.025256)
		(width 0.1143)
		(layer "In11.Cu")
		(net "SATA6G_S0_RX_DN")
	)
	(segment
		(start 408.901646 -97.941892)
		(end 408.9019 -97.941892)
		(width 0.1143)
		(layer "In11.Cu")
		(net "SATA6G_S0_RX_DN")
	)
	(segment
		(start 380.591314 -34.758376)
		(end 379.1204 -32.536892)
		(width 0.1143)
		(layer "In11.Cu")
		(net "SATA6G_S0_RX_DN")
	)
	(arc
		(start 397.347948 -116.441474)
		(mid 397.64335 -116.362343)
		(end 397.938752 -116.441474)
		(width 0.0889)
		(layer "In11.Cu")
		(net "SATA6G_S0_RX_DN")
	)
	(arc
		(start 394.081 -120.365774)
		(mid 394.165281 -120.082557)
		(end 394.376148 -119.875554)
		(width 0.0889)
		(layer "In11.Cu")
		(net "SATA6G_S0_RX_DN")
	)
	(arc
		(start 394.871448 -119.017034)
		(mid 395.16685 -118.937903)
		(end 395.462252 -119.017034)
		(width 0.0889)
		(layer "In11.Cu")
		(net "SATA6G_S0_RX_DN")
	)
	(arc
		(start 398.5387 -116.09451)
		(mid 398.617989 -115.799243)
		(end 398.834102 -115.582954)
		(width 0.0889)
		(layer "In11.Cu")
		(net "SATA6G_S0_RX_DN")
	)
	(arc
		(start 398.834102 -115.582954)
		(mid 398.877461 -115.55405)
		(end 398.916652 -115.519708)
		(width 0.0889)
		(layer "In11.Cu")
		(net "SATA6G_S0_RX_DN")
	)
	(arc
		(start 393.880848 -120.734074)
		(mid 394.024652 -120.592391)
		(end 394.081 -120.39854)
		(width 0.0889)
		(layer "In11.Cu")
		(net "SATA6G_S0_RX_DN")
	)
	(arc
		(start 395.462252 -119.017034)
		(mid 395.66215 -119.070533)
		(end 395.862048 -119.017034)
		(width 0.0889)
		(layer "In11.Cu")
		(net "SATA6G_S0_RX_DN")
	)
	(arc
		(start 396.852648 -117.299994)
		(mid 396.996452 -117.158311)
		(end 397.0528 -116.96446)
		(width 0.0889)
		(layer "In11.Cu")
		(net "SATA6G_S0_RX_DN")
	)
	(arc
		(start 398.338548 -116.441474)
		(mid 398.482352 -116.299791)
		(end 398.5387 -116.10594)
		(width 0.0889)
		(layer "In11.Cu")
		(net "SATA6G_S0_RX_DN")
	)
	(arc
		(start 394.5763 -119.507254)
		(mid 394.660581 -119.224037)
		(end 394.871448 -119.017034)
		(width 0.0889)
		(layer "In11.Cu")
		(net "SATA6G_S0_RX_DN")
	)
	(arc
		(start 396.5575 -117.790214)
		(mid 396.641781 -117.506997)
		(end 396.852648 -117.299994)
		(width 0.0889)
		(layer "In11.Cu")
		(net "SATA6G_S0_RX_DN")
	)
	(arc
		(start 393.5857 -121.224294)
		(mid 393.669981 -120.941077)
		(end 393.880848 -120.734074)
		(width 0.0889)
		(layer "In11.Cu")
		(net "SATA6G_S0_RX_DN")
	)
	(arc
		(start 394.376148 -119.875554)
		(mid 394.519952 -119.733871)
		(end 394.5763 -119.54002)
		(width 0.0889)
		(layer "In11.Cu")
		(net "SATA6G_S0_RX_DN")
	)
	(arc
		(start 397.938752 -116.441474)
		(mid 398.13865 -116.494973)
		(end 398.338548 -116.441474)
		(width 0.0889)
		(layer "In11.Cu")
		(net "SATA6G_S0_RX_DN")
	)
	(arc
		(start 393.82573 -121.72188)
		(mid 393.653736 -121.522135)
		(end 393.5857 -121.267474)
		(width 0.0889)
		(layer "In11.Cu")
		(net "SATA6G_S0_RX_DN")
	)
	(arc
		(start 396.357348 -118.158514)
		(mid 396.501152 -118.016831)
		(end 396.5575 -117.82298)
		(width 0.0889)
		(layer "In11.Cu")
		(net "SATA6G_S0_RX_DN")
	)
	(arc
		(start 395.862048 -119.017034)
		(mid 396.005852 -118.875351)
		(end 396.0622 -118.6815)
		(width 0.0889)
		(layer "In11.Cu")
		(net "SATA6G_S0_RX_DN")
	)
	(arc
		(start 397.0528 -116.931694)
		(mid 397.137081 -116.648477)
		(end 397.347948 -116.441474)
		(width 0.0889)
		(layer "In11.Cu")
		(net "SATA6G_S0_RX_DN")
	)
	(arc
		(start 396.0622 -118.648734)
		(mid 396.146481 -118.365517)
		(end 396.357348 -118.158514)
		(width 0.0889)
		(layer "In11.Cu")
		(net "SATA6G_S0_RX_DN")
	)
	(segment
		(start 377.83135 -101.039676)
		(end 377.33605 -101.2698)
		(width 0.10795)
		(layer "F.Cu")
		(net "RST_SRTCRST_N")
	)
	(via
		(at 374.9294 -99.06)
		(size 0.6604)
		(drill 0.3302)
		(layers "F.Cu" "B.Cu")
		(net "RST_SRTCRST_N")
	)
	(via
		(at 377.83135 -101.039676)
		(size 0.508)
		(drill 0.254)
		(layers "F.Cu" "B.Cu")
		(net "RST_SRTCRST_N")
	)
	(segment
		(start 376.662442 -100.935282)
		(end 376.253502 -100.935282)
		(width 0.10795)
		(layer "B.Cu")
		(net "RST_SRTCRST_N")
	)
	(segment
		(start 375.666 -101.1936)
		(end 375.666 -100.3046)
		(width 0.10795)
		(layer "B.Cu")
		(net "RST_SRTCRST_N")
	)
	(segment
		(start 375.666 -99.7966)
		(end 374.9294 -99.06)
		(width 0.10795)
		(layer "B.Cu")
		(net "RST_SRTCRST_N")
	)
	(segment
		(start 377.83135 -101.039676)
		(end 376.766836 -101.039676)
		(width 0.10795)
		(layer "B.Cu")
		(net "RST_SRTCRST_N")
	)
	(segment
		(start 375.995184 -101.1936)
		(end 375.666 -101.1936)
		(width 0.10795)
		(layer "B.Cu")
		(net "RST_SRTCRST_N")
	)
	(segment
		(start 376.253502 -100.935282)
		(end 375.995184 -101.1936)
		(width 0.10795)
		(layer "B.Cu")
		(net "RST_SRTCRST_N")
	)
	(segment
		(start 376.766836 -101.039676)
		(end 376.662442 -100.935282)
		(width 0.10795)
		(layer "B.Cu")
		(net "RST_SRTCRST_N")
	)
	(segment
		(start 375.666 -100.3046)
		(end 375.666 -99.7966)
		(width 0.10795)
		(layer "B.Cu")
		(net "RST_SRTCRST_N")
	)
	(segment
		(start 380.30785 -97.83572)
		(end 380.80315 -97.605596)
		(width 0.10795)
		(layer "F.Cu")
		(net "RST_RTCRST_N")
	)
	(via
		(at 380.80315 -97.605596)
		(size 0.508)
		(drill 0.254)
		(layers "F.Cu" "B.Cu")
		(net "RST_RTCRST_N")
	)
	(via
		(at 459.289404 -34.587434)
		(size 0.508)
		(drill 0.254)
		(layers "F.Cu" "B.Cu")
		(net "RST_RTCRST_N")
	)
	(via
		(at 379.93574 -86.6648)
		(size 0.508)
		(drill 0.254)
		(layers "F.Cu" "B.Cu")
		(net "RST_RTCRST_N")
	)
	(via
		(at 379.8062 -95.0214)
		(size 0.6604)
		(drill 0.3302)
		(layers "F.Cu" "B.Cu")
		(net "RST_RTCRST_N")
	)
	(via
		(at 394.589 -30.734)
		(size 0.508)
		(drill 0.254)
		(layers "F.Cu" "B.Cu")
		(net "RST_RTCRST_N")
	)
	(segment
		(start 374.278398 -90.700352)
		(end 374.700546 -91.1225)
		(width 0.10795)
		(layer "B.Cu")
		(net "RST_RTCRST_N")
	)
	(segment
		(start 375.053606 -91.959684)
		(end 375.053606 -91.872816)
		(width 0.10795)
		(layer "B.Cu")
		(net "RST_RTCRST_N")
	)
	(segment
		(start 374.796812 -91.616022)
		(end 374.796812 -91.1225)
		(width 0.10795)
		(layer "B.Cu")
		(net "RST_RTCRST_N")
	)
	(segment
		(start 378.384562 -93.822774)
		(end 377.625102 -93.822774)
		(width 0.10795)
		(layer "B.Cu")
		(net "RST_RTCRST_N")
	)
	(segment
		(start 378.670058 -94.10827)
		(end 378.384562 -93.822774)
		(width 0.10795)
		(layer "B.Cu")
		(net "RST_RTCRST_N")
	)
	(segment
		(start 375.053606 -91.872816)
		(end 374.796812 -91.616022)
		(width 0.10795)
		(layer "B.Cu")
		(net "RST_RTCRST_N")
	)
	(segment
		(start 373.498618 -89.78011)
		(end 373.972074 -89.78011)
		(width 0.10795)
		(layer "B.Cu")
		(net "RST_RTCRST_N")
	)
	(segment
		(start 374.278398 -90.086434)
		(end 374.278398 -90.700352)
		(width 0.10795)
		(layer "B.Cu")
		(net "RST_RTCRST_N")
	)
	(segment
		(start 380.80315 -97.605596)
		(end 380.80315 -96.665034)
		(width 0.10795)
		(layer "B.Cu")
		(net "RST_RTCRST_N")
	)
	(segment
		(start 380.29769 -95.51289)
		(end 379.8062 -95.0214)
		(width 0.10795)
		(layer "B.Cu")
		(net "RST_RTCRST_N")
	)
	(segment
		(start 372.609618 -89.78011)
		(end 373.498618 -89.78011)
		(width 0.10795)
		(layer "B.Cu")
		(net "RST_RTCRST_N")
	)
	(segment
		(start 379.8062 -95.0214)
		(end 378.89307 -94.10827)
		(width 0.10795)
		(layer "B.Cu")
		(net "RST_RTCRST_N")
	)
	(segment
		(start 375.522744 -92.428822)
		(end 375.053606 -91.959684)
		(width 0.10795)
		(layer "B.Cu")
		(net "RST_RTCRST_N")
	)
	(segment
		(start 376.584464 -93.305122)
		(end 375.708164 -92.428822)
		(width 0.10795)
		(layer "B.Cu")
		(net "RST_RTCRST_N")
	)
	(segment
		(start 380.29769 -96.159574)
		(end 380.29769 -95.51289)
		(width 0.10795)
		(layer "B.Cu")
		(net "RST_RTCRST_N")
	)
	(segment
		(start 380.80315 -96.665034)
		(end 380.29769 -96.159574)
		(width 0.10795)
		(layer "B.Cu")
		(net "RST_RTCRST_N")
	)
	(segment
		(start 374.700546 -91.1225)
		(end 374.777 -91.1225)
		(width 0.10795)
		(layer "B.Cu")
		(net "RST_RTCRST_N")
	)
	(segment
		(start 377.625102 -93.822774)
		(end 377.10745 -93.305122)
		(width 0.10795)
		(layer "B.Cu")
		(net "RST_RTCRST_N")
	)
	(segment
		(start 377.10745 -93.305122)
		(end 376.584464 -93.305122)
		(width 0.10795)
		(layer "B.Cu")
		(net "RST_RTCRST_N")
	)
	(segment
		(start 374.796812 -91.1225)
		(end 374.777 -91.1225)
		(width 0.10795)
		(layer "B.Cu")
		(net "RST_RTCRST_N")
	)
	(segment
		(start 378.89307 -94.10827)
		(end 378.670058 -94.10827)
		(width 0.10795)
		(layer "B.Cu")
		(net "RST_RTCRST_N")
	)
	(segment
		(start 375.708164 -92.428822)
		(end 375.522744 -92.428822)
		(width 0.10795)
		(layer "B.Cu")
		(net "RST_RTCRST_N")
	)
	(segment
		(start 373.972074 -89.78011)
		(end 374.278398 -90.086434)
		(width 0.10795)
		(layer "B.Cu")
		(net "RST_RTCRST_N")
	)
	(segment
		(start 383.63398 -55.831994)
		(end 383.211578 -56.254396)
		(width 0.089408)
		(layer "In2.Cu")
		(net "RST_RTCRST_N")
	)
	(segment
		(start 384.136392 -48.932846)
		(end 384.159252 -48.955706)
		(width 0.089408)
		(layer "In2.Cu")
		(net "RST_RTCRST_N")
	)
	(segment
		(start 379.859286 -84.503514)
		(end 379.4252 -84.9376)
		(width 0.089408)
		(layer "In2.Cu")
		(net "RST_RTCRST_N")
	)
	(segment
		(start 381.856234 -73.600818)
		(end 382.290828 -74.035412)
		(width 0.089408)
		(layer "In2.Cu")
		(net "RST_RTCRST_N")
	)
	(segment
		(start 381.381 -71.131938)
		(end 381.381 -71.160894)
		(width 0.089408)
		(layer "In2.Cu")
		(net "RST_RTCRST_N")
	)
	(segment
		(start 387.98627 -37.587682)
		(end 385.366006 -40.207946)
		(width 0.089408)
		(layer "In2.Cu")
		(net "RST_RTCRST_N")
	)
	(segment
		(start 381.381 -71.160894)
		(end 381.380746 -71.161148)
		(width 0.089408)
		(layer "In2.Cu")
		(net "RST_RTCRST_N")
	)
	(segment
		(start 381.381 -72.244966)
		(end 381.856234 -72.7202)
		(width 0.089408)
		(layer "In2.Cu")
		(net "RST_RTCRST_N")
	)
	(segment
		(start 384.159252 -49.885346)
		(end 383.43205 -50.612548)
		(width 0.089408)
		(layer "In2.Cu")
		(net "RST_RTCRST_N")
	)
	(segment
		(start 394.589 -30.734)
		(end 394.499846 -30.823154)
		(width 0.089408)
		(layer "In2.Cu")
		(net "RST_RTCRST_N")
	)
	(segment
		(start 383.050796 -61.976)
		(end 383.050796 -62.916816)
		(width 0.089408)
		(layer "In2.Cu")
		(net "RST_RTCRST_N")
	)
	(segment
		(start 382.290828 -75.744324)
		(end 381.255016 -76.780136)
		(width 0.089408)
		(layer "In2.Cu")
		(net "RST_RTCRST_N")
	)
	(segment
		(start 381.856234 -72.7202)
		(end 381.856234 -73.600818)
		(width 0.089408)
		(layer "In2.Cu")
		(net "RST_RTCRST_N")
	)
	(segment
		(start 382.290828 -74.035412)
		(end 382.290828 -75.744324)
		(width 0.089408)
		(layer "In2.Cu")
		(net "RST_RTCRST_N")
	)
	(segment
		(start 380.928118 -78.478634)
		(end 380.928118 -79.587598)
		(width 0.089408)
		(layer "In2.Cu")
		(net "RST_RTCRST_N")
	)
	(segment
		(start 385.366006 -44.798488)
		(end 383.228088 -46.936406)
		(width 0.089408)
		(layer "In2.Cu")
		(net "RST_RTCRST_N")
	)
	(segment
		(start 383.228088 -48.013874)
		(end 384.136392 -48.922178)
		(width 0.089408)
		(layer "In2.Cu")
		(net "RST_RTCRST_N")
	)
	(segment
		(start 383.050796 -62.916816)
		(end 383.907792 -63.773812)
		(width 0.089408)
		(layer "In2.Cu")
		(net "RST_RTCRST_N")
	)
	(segment
		(start 385.366006 -40.207946)
		(end 385.366006 -44.798488)
		(width 0.089408)
		(layer "In2.Cu")
		(net "RST_RTCRST_N")
	)
	(segment
		(start 389.780018 -35.034728)
		(end 387.98627 -36.828476)
		(width 0.089408)
		(layer "In2.Cu")
		(net "RST_RTCRST_N")
	)
	(segment
		(start 394.499846 -30.823154)
		(end 393.610846 -30.823154)
		(width 0.089408)
		(layer "In2.Cu")
		(net "RST_RTCRST_N")
	)
	(segment
		(start 383.211578 -61.815218)
		(end 383.050796 -61.976)
		(width 0.089408)
		(layer "In2.Cu")
		(net "RST_RTCRST_N")
	)
	(segment
		(start 389.780018 -34.205672)
		(end 389.780018 -35.034728)
		(width 0.089408)
		(layer "In2.Cu")
		(net "RST_RTCRST_N")
	)
	(segment
		(start 391.454386 -32.531304)
		(end 389.780018 -34.205672)
		(width 0.089408)
		(layer "In2.Cu")
		(net "RST_RTCRST_N")
	)
	(segment
		(start 387.98627 -36.828476)
		(end 387.98627 -37.587682)
		(width 0.089408)
		(layer "In2.Cu")
		(net "RST_RTCRST_N")
	)
	(segment
		(start 391.572242 -32.531304)
		(end 391.454386 -32.531304)
		(width 0.089408)
		(layer "In2.Cu")
		(net "RST_RTCRST_N")
	)
	(segment
		(start 383.43205 -53.67655)
		(end 383.63398 -53.87848)
		(width 0.089408)
		(layer "In2.Cu")
		(net "RST_RTCRST_N")
	)
	(segment
		(start 381.381 -71.403718)
		(end 381.381 -72.244966)
		(width 0.089408)
		(layer "In2.Cu")
		(net "RST_RTCRST_N")
	)
	(segment
		(start 381.380746 -71.161148)
		(end 381.380746 -71.403464)
		(width 0.089408)
		(layer "In2.Cu")
		(net "RST_RTCRST_N")
	)
	(segment
		(start 379.859286 -80.65643)
		(end 379.859286 -84.503514)
		(width 0.089408)
		(layer "In2.Cu")
		(net "RST_RTCRST_N")
	)
	(segment
		(start 393.610846 -30.823154)
		(end 391.90295 -32.53105)
		(width 0.089408)
		(layer "In2.Cu")
		(net "RST_RTCRST_N")
	)
	(segment
		(start 379.4252 -86.28126)
		(end 379.80874 -86.6648)
		(width 0.089408)
		(layer "In2.Cu")
		(net "RST_RTCRST_N")
	)
	(segment
		(start 383.907792 -68.605146)
		(end 381.381 -71.131938)
		(width 0.089408)
		(layer "In2.Cu")
		(net "RST_RTCRST_N")
	)
	(segment
		(start 381.380746 -71.403464)
		(end 381.381 -71.403718)
		(width 0.089408)
		(layer "In2.Cu")
		(net "RST_RTCRST_N")
	)
	(segment
		(start 384.159252 -48.955706)
		(end 384.159252 -49.885346)
		(width 0.089408)
		(layer "In2.Cu")
		(net "RST_RTCRST_N")
	)
	(segment
		(start 383.211578 -56.254396)
		(end 383.211578 -61.815218)
		(width 0.089408)
		(layer "In2.Cu")
		(net "RST_RTCRST_N")
	)
	(segment
		(start 380.928118 -79.587598)
		(end 379.859286 -80.65643)
		(width 0.089408)
		(layer "In2.Cu")
		(net "RST_RTCRST_N")
	)
	(segment
		(start 383.228088 -46.936406)
		(end 383.228088 -48.013874)
		(width 0.089408)
		(layer "In2.Cu")
		(net "RST_RTCRST_N")
	)
	(segment
		(start 381.255016 -76.780136)
		(end 381.255016 -78.151736)
		(width 0.089408)
		(layer "In2.Cu")
		(net "RST_RTCRST_N")
	)
	(segment
		(start 383.907792 -63.773812)
		(end 383.907792 -68.605146)
		(width 0.089408)
		(layer "In2.Cu")
		(net "RST_RTCRST_N")
	)
	(segment
		(start 379.4252 -84.9376)
		(end 379.4252 -86.28126)
		(width 0.089408)
		(layer "In2.Cu")
		(net "RST_RTCRST_N")
	)
	(segment
		(start 391.572496 -32.53105)
		(end 391.572242 -32.531304)
		(width 0.089408)
		(layer "In2.Cu")
		(net "RST_RTCRST_N")
	)
	(segment
		(start 384.136392 -48.922178)
		(end 384.136392 -48.932846)
		(width 0.089408)
		(layer "In2.Cu")
		(net "RST_RTCRST_N")
	)
	(segment
		(start 381.255016 -78.151736)
		(end 380.928118 -78.478634)
		(width 0.089408)
		(layer "In2.Cu")
		(net "RST_RTCRST_N")
	)
	(segment
		(start 383.63398 -53.87848)
		(end 383.63398 -55.831994)
		(width 0.089408)
		(layer "In2.Cu")
		(net "RST_RTCRST_N")
	)
	(segment
		(start 391.90295 -32.53105)
		(end 391.572496 -32.53105)
		(width 0.089408)
		(layer "In2.Cu")
		(net "RST_RTCRST_N")
	)
	(segment
		(start 379.80874 -86.6648)
		(end 379.93574 -86.6648)
		(width 0.089408)
		(layer "In2.Cu")
		(net "RST_RTCRST_N")
	)
	(segment
		(start 383.43205 -50.612548)
		(end 383.43205 -53.67655)
		(width 0.089408)
		(layer "In2.Cu")
		(net "RST_RTCRST_N")
	)
	(segment
		(start 459.289404 -34.587434)
		(end 459.05801 -34.35604)
		(width 0.089408)
		(layer "In4.Cu")
		(net "RST_RTCRST_N")
	)
	(segment
		(start 437.91251 -24.28875)
		(end 437.670448 -24.046688)
		(width 0.089408)
		(layer "In4.Cu")
		(net "RST_RTCRST_N")
	)
	(segment
		(start 424.33875 -28.588208)
		(end 423.910506 -28.159964)
		(width 0.089408)
		(layer "In4.Cu")
		(net "RST_RTCRST_N")
	)
	(segment
		(start 435.112922 -24.971502)
		(end 435.112922 -24.971756)
		(width 0.089408)
		(layer "In4.Cu")
		(net "RST_RTCRST_N")
	)
	(segment
		(start 419.936422 -29.566108)
		(end 419.689026 -29.813504)
		(width 0.089408)
		(layer "In4.Cu")
		(net "RST_RTCRST_N")
	)
	(segment
		(start 431.741326 -27.014678)
		(end 429.79594 -28.960064)
		(width 0.089408)
		(layer "In4.Cu")
		(net "RST_RTCRST_N")
	)
	(segment
		(start 420.79164 -29.566108)
		(end 419.936422 -29.566108)
		(width 0.089408)
		(layer "In4.Cu")
		(net "RST_RTCRST_N")
	)
	(segment
		(start 429.79594 -28.960064)
		(end 424.634152 -28.960064)
		(width 0.089408)
		(layer "In4.Cu")
		(net "RST_RTCRST_N")
	)
	(segment
		(start 433.112418 -26.972006)
		(end 433.069746 -27.014678)
		(width 0.089408)
		(layer "In4.Cu")
		(net "RST_RTCRST_N")
	)
	(segment
		(start 433.069746 -27.014678)
		(end 431.741326 -27.014678)
		(width 0.089408)
		(layer "In4.Cu")
		(net "RST_RTCRST_N")
	)
	(segment
		(start 406.381458 -31.273242)
		(end 405.634952 -31.273242)
		(width 0.089408)
		(layer "In4.Cu")
		(net "RST_RTCRST_N")
	)
	(segment
		(start 405.634952 -31.273242)
		(end 405.481282 -31.119572)
		(width 0.089408)
		(layer "In4.Cu")
		(net "RST_RTCRST_N")
	)
	(segment
		(start 420.934896 -29.709364)
		(end 420.79164 -29.566108)
		(width 0.089408)
		(layer "In4.Cu")
		(net "RST_RTCRST_N")
	)
	(segment
		(start 444.84671 -24.69896)
		(end 443.65037 -23.50262)
		(width 0.089408)
		(layer "In4.Cu")
		(net "RST_RTCRST_N")
	)
	(segment
		(start 418.40531 -30.53461)
		(end 407.12009 -30.53461)
		(width 0.089408)
		(layer "In4.Cu")
		(net "RST_RTCRST_N")
	)
	(segment
		(start 433.112672 -26.972006)
		(end 433.112418 -26.972006)
		(width 0.089408)
		(layer "In4.Cu")
		(net "RST_RTCRST_N")
	)
	(segment
		(start 424.634152 -28.960064)
		(end 424.33875 -28.664662)
		(width 0.089408)
		(layer "In4.Cu")
		(net "RST_RTCRST_N")
	)
	(segment
		(start 423.910506 -28.159964)
		(end 422.534842 -28.159964)
		(width 0.089408)
		(layer "In4.Cu")
		(net "RST_RTCRST_N")
	)
	(segment
		(start 405.481282 -31.119572)
		(end 405.217122 -31.119572)
		(width 0.089408)
		(layer "In4.Cu")
		(net "RST_RTCRST_N")
	)
	(segment
		(start 421.46474 -29.489908)
		(end 421.245284 -29.709364)
		(width 0.089408)
		(layer "In4.Cu")
		(net "RST_RTCRST_N")
	)
	(segment
		(start 401.496022 -30.000194)
		(end 395.322806 -30.000194)
		(width 0.089408)
		(layer "In4.Cu")
		(net "RST_RTCRST_N")
	)
	(segment
		(start 446.5193 -30.847538)
		(end 444.84671 -29.174948)
		(width 0.089408)
		(layer "In4.Cu")
		(net "RST_RTCRST_N")
	)
	(segment
		(start 422.076626 -28.960064)
		(end 421.734996 -28.960064)
		(width 0.089408)
		(layer "In4.Cu")
		(net "RST_RTCRST_N")
	)
	(segment
		(start 422.31564 -28.379166)
		(end 422.31564 -28.72105)
		(width 0.089408)
		(layer "In4.Cu")
		(net "RST_RTCRST_N")
	)
	(segment
		(start 421.46474 -29.23032)
		(end 421.46474 -29.489908)
		(width 0.089408)
		(layer "In4.Cu")
		(net "RST_RTCRST_N")
	)
	(segment
		(start 419.126416 -29.813504)
		(end 418.40531 -30.53461)
		(width 0.089408)
		(layer "In4.Cu")
		(net "RST_RTCRST_N")
	)
	(segment
		(start 421.734996 -28.960064)
		(end 421.46474 -29.23032)
		(width 0.089408)
		(layer "In4.Cu")
		(net "RST_RTCRST_N")
	)
	(segment
		(start 449.286376 -30.847538)
		(end 446.5193 -30.847538)
		(width 0.089408)
		(layer "In4.Cu")
		(net "RST_RTCRST_N")
	)
	(segment
		(start 435.112922 -24.971756)
		(end 433.112672 -26.972006)
		(width 0.089408)
		(layer "In4.Cu")
		(net "RST_RTCRST_N")
	)
	(segment
		(start 422.31564 -28.72105)
		(end 422.076626 -28.960064)
		(width 0.089408)
		(layer "In4.Cu")
		(net "RST_RTCRST_N")
	)
	(segment
		(start 405.217122 -31.119572)
		(end 404.6347 -30.53715)
		(width 0.089408)
		(layer "In4.Cu")
		(net "RST_RTCRST_N")
	)
	(segment
		(start 437.670448 -24.046688)
		(end 436.037736 -24.046688)
		(width 0.089408)
		(layer "In4.Cu")
		(net "RST_RTCRST_N")
	)
	(segment
		(start 442.173614 -23.50262)
		(end 441.387484 -24.28875)
		(width 0.089408)
		(layer "In4.Cu")
		(net "RST_RTCRST_N")
	)
	(segment
		(start 421.245284 -29.709364)
		(end 420.934896 -29.709364)
		(width 0.089408)
		(layer "In4.Cu")
		(net "RST_RTCRST_N")
	)
	(segment
		(start 419.689026 -29.813504)
		(end 419.126416 -29.813504)
		(width 0.089408)
		(layer "In4.Cu")
		(net "RST_RTCRST_N")
	)
	(segment
		(start 441.387484 -24.28875)
		(end 437.91251 -24.28875)
		(width 0.089408)
		(layer "In4.Cu")
		(net "RST_RTCRST_N")
	)
	(segment
		(start 459.05801 -34.35604)
		(end 452.794878 -34.35604)
		(width 0.089408)
		(layer "In4.Cu")
		(net "RST_RTCRST_N")
	)
	(segment
		(start 424.33875 -28.664662)
		(end 424.33875 -28.588208)
		(width 0.089408)
		(layer "In4.Cu")
		(net "RST_RTCRST_N")
	)
	(segment
		(start 452.794878 -34.35604)
		(end 449.286376 -30.847538)
		(width 0.089408)
		(layer "In4.Cu")
		(net "RST_RTCRST_N")
	)
	(segment
		(start 407.12009 -30.53461)
		(end 406.381458 -31.273242)
		(width 0.089408)
		(layer "In4.Cu")
		(net "RST_RTCRST_N")
	)
	(segment
		(start 422.534842 -28.159964)
		(end 422.31564 -28.379166)
		(width 0.089408)
		(layer "In4.Cu")
		(net "RST_RTCRST_N")
	)
	(segment
		(start 395.322806 -30.000194)
		(end 394.589 -30.734)
		(width 0.089408)
		(layer "In4.Cu")
		(net "RST_RTCRST_N")
	)
	(segment
		(start 443.65037 -23.50262)
		(end 442.173614 -23.50262)
		(width 0.089408)
		(layer "In4.Cu")
		(net "RST_RTCRST_N")
	)
	(segment
		(start 402.032978 -30.53715)
		(end 401.496022 -30.000194)
		(width 0.089408)
		(layer "In4.Cu")
		(net "RST_RTCRST_N")
	)
	(segment
		(start 444.84671 -29.174948)
		(end 444.84671 -24.69896)
		(width 0.089408)
		(layer "In4.Cu")
		(net "RST_RTCRST_N")
	)
	(segment
		(start 436.037736 -24.046688)
		(end 435.112922 -24.971502)
		(width 0.089408)
		(layer "In4.Cu")
		(net "RST_RTCRST_N")
	)
	(segment
		(start 404.6347 -30.53715)
		(end 402.032978 -30.53715)
		(width 0.089408)
		(layer "In4.Cu")
		(net "RST_RTCRST_N")
	)
	(segment
		(start 461.8482 -21.09216)
		(end 461.671416 -20.915376)
		(width 0.089408)
		(layer "In9.Cu")
		(net "RST_RTCRST_N")
	)
	(segment
		(start 458.66431 -0.210312)
		(end 458.17409 -0.210312)
		(width 0.089408)
		(layer "In9.Cu")
		(net "RST_RTCRST_N")
	)
	(segment
		(start 458.828394 -0.191262)
		(end 458.68336 -0.191262)
		(width 0.089408)
		(layer "In9.Cu")
		(net "RST_RTCRST_N")
	)
	(segment
		(start 463.578702 -8.24611)
		(end 463.578448 -8.245856)
		(width 0.089408)
		(layer "In9.Cu")
		(net "RST_RTCRST_N")
	)
	(segment
		(start 461.088486 -4.772914)
		(end 462.20888 -3.65252)
		(width 0.089408)
		(layer "In9.Cu")
		(net "RST_RTCRST_N")
	)
	(segment
		(start 461.088486 -5.8293)
		(end 461.088486 -4.772914)
		(width 0.089408)
		(layer "In9.Cu")
		(net "RST_RTCRST_N")
	)
	(segment
		(start 460.697834 -32.1056)
		(end 460.465678 -32.1056)
		(width 0.089408)
		(layer "In9.Cu")
		(net "RST_RTCRST_N")
	)
	(segment
		(start 462.20888 -1.146556)
		(end 461.214724 -0.1524)
		(width 0.089408)
		(layer "In9.Cu")
		(net "RST_RTCRST_N")
	)
	(segment
		(start 465.43722 -9.499854)
		(end 464.183476 -8.24611)
		(width 0.089408)
		(layer "In9.Cu")
		(net "RST_RTCRST_N")
	)
	(segment
		(start 461.8482 -27.80157)
		(end 461.8482 -21.09216)
		(width 0.089408)
		(layer "In9.Cu")
		(net "RST_RTCRST_N")
	)
	(segment
		(start 458.68336 -0.191262)
		(end 458.66431 -0.210312)
		(width 0.089408)
		(layer "In9.Cu")
		(net "RST_RTCRST_N")
	)
	(segment
		(start 461.214724 -0.1524)
		(end 458.867256 -0.1524)
		(width 0.089408)
		(layer "In9.Cu")
		(net "RST_RTCRST_N")
	)
	(segment
		(start 459.941676 -31.581598)
		(end 459.941676 -29.708094)
		(width 0.089408)
		(layer "In9.Cu")
		(net "RST_RTCRST_N")
	)
	(segment
		(start 458.17409 -0.210312)
		(end 458.154786 -0.191008)
		(width 0.089408)
		(layer "In9.Cu")
		(net "RST_RTCRST_N")
	)
	(segment
		(start 461.671416 -17.94891)
		(end 462.517236 -17.10309)
		(width 0.089408)
		(layer "In9.Cu")
		(net "RST_RTCRST_N")
	)
	(segment
		(start 462.20888 -3.65252)
		(end 462.20888 -1.146556)
		(width 0.089408)
		(layer "In9.Cu")
		(net "RST_RTCRST_N")
	)
	(segment
		(start 465.43722 -15.537434)
		(end 465.43722 -9.499854)
		(width 0.089408)
		(layer "In9.Cu")
		(net "RST_RTCRST_N")
	)
	(segment
		(start 458.867256 -0.1524)
		(end 458.828394 -0.191262)
		(width 0.089408)
		(layer "In9.Cu")
		(net "RST_RTCRST_N")
	)
	(segment
		(start 463.871564 -17.10309)
		(end 465.43722 -15.537434)
		(width 0.089408)
		(layer "In9.Cu")
		(net "RST_RTCRST_N")
	)
	(segment
		(start 460.932276 -32.903922)
		(end 460.932276 -32.340042)
		(width 0.089408)
		(layer "In9.Cu")
		(net "RST_RTCRST_N")
	)
	(segment
		(start 454.047352 -0.191008)
		(end 454.008744 -0.1524)
		(width 0.089408)
		(layer "In9.Cu")
		(net "RST_RTCRST_N")
	)
	(segment
		(start 463.578448 -8.245856)
		(end 463.505042 -8.245856)
		(width 0.089408)
		(layer "In9.Cu")
		(net "RST_RTCRST_N")
	)
	(segment
		(start 462.517236 -17.10309)
		(end 463.871564 -17.10309)
		(width 0.089408)
		(layer "In9.Cu")
		(net "RST_RTCRST_N")
	)
	(segment
		(start 460.465678 -32.1056)
		(end 459.941676 -31.581598)
		(width 0.089408)
		(layer "In9.Cu")
		(net "RST_RTCRST_N")
	)
	(segment
		(start 460.932276 -32.340042)
		(end 460.697834 -32.1056)
		(width 0.089408)
		(layer "In9.Cu")
		(net "RST_RTCRST_N")
	)
	(segment
		(start 459.941676 -29.708094)
		(end 461.8482 -27.80157)
		(width 0.089408)
		(layer "In9.Cu")
		(net "RST_RTCRST_N")
	)
	(segment
		(start 459.289404 -34.546794)
		(end 460.932276 -32.903922)
		(width 0.089408)
		(layer "In9.Cu")
		(net "RST_RTCRST_N")
	)
	(segment
		(start 463.505042 -8.245856)
		(end 461.088486 -5.8293)
		(width 0.089408)
		(layer "In9.Cu")
		(net "RST_RTCRST_N")
	)
	(segment
		(start 454.008744 -0.1524)
		(end 453.416416 -0.1524)
		(width 0.089408)
		(layer "In9.Cu")
		(net "RST_RTCRST_N")
	)
	(segment
		(start 453.416416 -0.1524)
		(end 451.994016 1.27)
		(width 0.089408)
		(layer "In9.Cu")
		(net "RST_RTCRST_N")
	)
	(segment
		(start 461.671416 -20.915376)
		(end 461.671416 -17.94891)
		(width 0.089408)
		(layer "In9.Cu")
		(net "RST_RTCRST_N")
	)
	(segment
		(start 459.289404 -34.587434)
		(end 459.289404 -34.546794)
		(width 0.089408)
		(layer "In9.Cu")
		(net "RST_RTCRST_N")
	)
	(segment
		(start 464.183476 -8.24611)
		(end 463.578702 -8.24611)
		(width 0.089408)
		(layer "In9.Cu")
		(net "RST_RTCRST_N")
	)
	(segment
		(start 458.154786 -0.191008)
		(end 454.047352 -0.191008)
		(width 0.089408)
		(layer "In9.Cu")
		(net "RST_RTCRST_N")
	)
	(segment
		(start 381.381 -97.282)
		(end 381.126746 -97.282)
		(width 0.089408)
		(layer "In11.Cu")
		(net "RST_RTCRST_N")
	)
	(segment
		(start 379.336808 -88.297258)
		(end 379.336808 -92.570808)
		(width 0.089408)
		(layer "In11.Cu")
		(net "RST_RTCRST_N")
	)
	(segment
		(start 381.32258 -94.55658)
		(end 381.32258 -96.111568)
		(width 0.089408)
		(layer "In11.Cu")
		(net "RST_RTCRST_N")
	)
	(segment
		(start 379.336808 -92.570808)
		(end 381.32258 -94.55658)
		(width 0.089408)
		(layer "In11.Cu")
		(net "RST_RTCRST_N")
	)
	(segment
		(start 381.762 -96.550988)
		(end 381.762 -96.901)
		(width 0.089408)
		(layer "In11.Cu")
		(net "RST_RTCRST_N")
	)
	(segment
		(start 379.93574 -87.698326)
		(end 379.336808 -88.297258)
		(width 0.089408)
		(layer "In11.Cu")
		(net "RST_RTCRST_N")
	)
	(segment
		(start 381.762 -96.901)
		(end 381.381 -97.282)
		(width 0.089408)
		(layer "In11.Cu")
		(net "RST_RTCRST_N")
	)
	(segment
		(start 381.32258 -96.111568)
		(end 381.762 -96.550988)
		(width 0.089408)
		(layer "In11.Cu")
		(net "RST_RTCRST_N")
	)
	(segment
		(start 381.126746 -97.282)
		(end 380.80315 -97.605596)
		(width 0.089408)
		(layer "In11.Cu")
		(net "RST_RTCRST_N")
	)
	(segment
		(start 379.93574 -86.6648)
		(end 379.93574 -87.698326)
		(width 0.089408)
		(layer "In11.Cu")
		(net "RST_RTCRST_N")
	)
	(segment
		(start 380.30785 -99.55276)
		(end 380.80315 -99.322636)
		(width 0.10795)
		(layer "F.Cu")
		(net "RST_RSMRST_N")
	)
	(segment
		(start 471.319098 -145.138902)
		(end 471.1827 -145.2753)
		(width 0.10795)
		(layer "F.Cu")
		(net "RST_RSMRST_N")
	)
	(segment
		(start 467.392766 -144.876266)
		(end 467.011258 -144.876266)
		(width 0.10795)
		(layer "F.Cu")
		(net "RST_RSMRST_N")
	)
	(segment
		(start 468.5411 -145.2753)
		(end 468.1728 -144.907)
		(width 0.10795)
		(layer "F.Cu")
		(net "RST_RSMRST_N")
	)
	(segment
		(start 476.4659 -144.0688)
		(end 475.395798 -145.138902)
		(width 0.10795)
		(layer "F.Cu")
		(net "RST_RSMRST_N")
	)
	(segment
		(start 475.395798 -145.138902)
		(end 471.319098 -145.138902)
		(width 0.10795)
		(layer "F.Cu")
		(net "RST_RSMRST_N")
	)
	(segment
		(start 471.1827 -145.2753)
		(end 468.5411 -145.2753)
		(width 0.10795)
		(layer "F.Cu")
		(net "RST_RSMRST_N")
	)
	(segment
		(start 468.1728 -144.907)
		(end 467.4235 -144.907)
		(width 0.10795)
		(layer "F.Cu")
		(net "RST_RSMRST_N")
	)
	(segment
		(start 467.011258 -144.876266)
		(end 466.980524 -144.907)
		(width 0.10795)
		(layer "F.Cu")
		(net "RST_RSMRST_N")
	)
	(segment
		(start 466.980524 -144.907)
		(end 466.54212 -144.907)
		(width 0.10795)
		(layer "F.Cu")
		(net "RST_RSMRST_N")
	)
	(segment
		(start 467.4235 -144.907)
		(end 467.392766 -144.876266)
		(width 0.10795)
		(layer "F.Cu")
		(net "RST_RSMRST_N")
	)
	(via
		(at 394.251434 -33.782)
		(size 0.508)
		(drill 0.254)
		(layers "F.Cu" "B.Cu")
		(net "RST_RSMRST_N")
	)
	(via
		(at 379.99162 -67.98691)
		(size 0.4572)
		(drill 0.2032)
		(layers "F.Cu" "B.Cu")
		(net "RST_RSMRST_N")
	)
	(via
		(at 380.590298 -67.225164)
		(size 0.6604)
		(drill 0.3302)
		(layers "F.Cu" "B.Cu")
		(net "RST_RSMRST_N")
	)
	(via
		(at 384.7084 -32.1691)
		(size 0.508)
		(drill 0.254)
		(layers "F.Cu" "B.Cu")
		(net "RST_RSMRST_N")
	)
	(via
		(at 476.4659 -144.0688)
		(size 0.508)
		(drill 0.254)
		(layers "F.Cu" "B.Cu")
		(net "RST_RSMRST_N")
	)
	(via
		(at 380.80315 -99.322636)
		(size 0.508)
		(drill 0.254)
		(layers "F.Cu" "B.Cu")
		(net "RST_RSMRST_N")
	)
	(via
		(at 376.9614 -83.84921)
		(size 0.508)
		(drill 0.254)
		(layers "F.Cu" "B.Cu")
		(net "RST_RSMRST_N")
	)
	(via
		(at 368.745262 -80.694784)
		(size 0.4572)
		(drill 0.2032)
		(layers "F.Cu" "B.Cu")
		(net "RST_RSMRST_N")
	)
	(segment
		(start 380.590298 -67.225164)
		(end 380.590298 -67.645788)
		(width 0.10795)
		(layer "B.Cu")
		(net "RST_RSMRST_N")
	)
	(segment
		(start 379.3363 -66.32956)
		(end 380.353824 -66.32956)
		(width 0.10795)
		(layer "B.Cu")
		(net "RST_RSMRST_N")
	)
	(segment
		(start 380.590298 -66.566034)
		(end 380.590298 -67.225164)
		(width 0.10795)
		(layer "B.Cu")
		(net "RST_RSMRST_N")
	)
	(segment
		(start 380.590298 -67.645788)
		(end 380.249176 -67.98691)
		(width 0.10795)
		(layer "B.Cu")
		(net "RST_RSMRST_N")
	)
	(segment
		(start 380.353824 -66.32956)
		(end 380.590298 -66.566034)
		(width 0.10795)
		(layer "B.Cu")
		(net "RST_RSMRST_N")
	)
	(segment
		(start 380.249176 -67.98691)
		(end 379.99162 -67.98691)
		(width 0.10795)
		(layer "B.Cu")
		(net "RST_RSMRST_N")
	)
	(segment
		(start 378.53874 -66.32956)
		(end 379.3363 -66.32956)
		(width 0.10795)
		(layer "B.Cu")
		(net "RST_RSMRST_N")
	)
	(segment
		(start 394.251434 -33.139634)
		(end 394.251434 -33.782)
		(width 0.10795)
		(layer "B.Cu")
		(net "RST_RSMRST_N")
	)
	(segment
		(start 393.777724 -105.497376)
		(end 393.777724 -105.167176)
		(width 0.0889)
		(layer "In2.Cu")
		(net "RST_RSMRST_N")
	)
	(segment
		(start 388.1374 -99.344226)
		(end 388.1374 -99.31146)
		(width 0.0889)
		(layer "In2.Cu")
		(net "RST_RSMRST_N")
	)
	(segment
		(start 374.284494 -84.555076)
		(end 373.229886 -84.555076)
		(width 0.089408)
		(layer "In2.Cu")
		(net "RST_RSMRST_N")
	)
	(segment
		(start 377.77928 -99.367086)
		(end 377.77928 -99.052126)
		(width 0.089408)
		(layer "In2.Cu")
		(net "RST_RSMRST_N")
	)
	(segment
		(start 396.0622 -111.823754)
		(end 396.0622 -111.790988)
		(width 0.0889)
		(layer "In2.Cu")
		(net "RST_RSMRST_N")
	)
	(segment
		(start 374.44045 -84.711032)
		(end 374.284494 -84.555076)
		(width 0.089408)
		(layer "In2.Cu")
		(net "RST_RSMRST_N")
	)
	(segment
		(start 395.565884 -110.942628)
		(end 395.565884 -110.613952)
		(width 0.0889)
		(layer "In2.Cu")
		(net "RST_RSMRST_N")
	)
	(segment
		(start 407.946606 -119.969026)
		(end 404.625048 -116.647468)
		(width 0.089408)
		(layer "In2.Cu")
		(net "RST_RSMRST_N")
	)
	(segment
		(start 376.231404 -83.03895)
		(end 376.9614 -83.768946)
		(width 0.089408)
		(layer "In2.Cu")
		(net "RST_RSMRST_N")
	)
	(segment
		(start 393.735306 -106.478578)
		(end 393.948412 -106.265472)
		(width 0.0889)
		(layer "In2.Cu")
		(net "RST_RSMRST_N")
	)
	(segment
		(start 376.680984 -97.95383)
		(end 376.273568 -97.95383)
		(width 0.089408)
		(layer "In2.Cu")
		(net "RST_RSMRST_N")
	)
	(segment
		(start 388.6327 -100.202746)
		(end 388.6327 -100.16998)
		(width 0.0889)
		(layer "In2.Cu")
		(net "RST_RSMRST_N")
	)
	(segment
		(start 393.948412 -105.668064)
		(end 393.777724 -105.497376)
		(width 0.0889)
		(layer "In2.Cu")
		(net "RST_RSMRST_N")
	)
	(segment
		(start 374.44045 -87.504778)
		(end 374.44045 -84.711032)
		(width 0.089408)
		(layer "In2.Cu")
		(net "RST_RSMRST_N")
	)
	(segment
		(start 404.625048 -114.699542)
		(end 404.352506 -114.427)
		(width 0.089408)
		(layer "In2.Cu")
		(net "RST_RSMRST_N")
	)
	(segment
		(start 400.111468 -112.392968)
		(end 399.62455 -112.392968)
		(width 0.0889)
		(layer "In2.Cu")
		(net "RST_RSMRST_N")
	)
	(segment
		(start 477.745298 -135.35914)
		(end 477.745298 -126.945136)
		(width 0.089408)
		(layer "In2.Cu")
		(net "RST_RSMRST_N")
	)
	(segment
		(start 375.328688 -75.468226)
		(end 374.126506 -75.468226)
		(width 0.089408)
		(layer "In2.Cu")
		(net "RST_RSMRST_N")
	)
	(segment
		(start 435.500526 -120.54078)
		(end 434.536596 -121.50471)
		(width 0.089408)
		(layer "In2.Cu")
		(net "RST_RSMRST_N")
	)
	(segment
		(start 419.1254 -121.9708)
		(end 418.609272 -122.486928)
		(width 0.089408)
		(layer "In2.Cu")
		(net "RST_RSMRST_N")
	)
	(segment
		(start 377.77928 -99.052126)
		(end 376.680984 -97.95383)
		(width 0.089408)
		(layer "In2.Cu")
		(net "RST_RSMRST_N")
	)
	(segment
		(start 389.6233 -101.919786)
		(end 389.6233 -101.88702)
		(width 0.0889)
		(layer "In2.Cu")
		(net "RST_RSMRST_N")
	)
	(segment
		(start 380.80315 -99.322636)
		(end 380.38786 -99.737926)
		(width 0.089408)
		(layer "In2.Cu")
		(net "RST_RSMRST_N")
	)
	(segment
		(start 376.273568 -97.95383)
		(end 375.970546 -97.650808)
		(width 0.089408)
		(layer "In2.Cu")
		(net "RST_RSMRST_N")
	)
	(segment
		(start 375.518172 -75.278742)
		(end 375.328688 -75.468226)
		(width 0.089408)
		(layer "In2.Cu")
		(net "RST_RSMRST_N")
	)
	(segment
		(start 373.971312 -75.62342)
		(end 373.971312 -79.249524)
		(width 0.089408)
		(layer "In2.Cu")
		(net "RST_RSMRST_N")
	)
	(segment
		(start 394.92809 -108.332016)
		(end 393.735306 -107.139232)
		(width 0.0889)
		(layer "In2.Cu")
		(net "RST_RSMRST_N")
	)
	(segment
		(start 395.5669 -108.787946)
		(end 395.5669 -108.75518)
		(width 0.0889)
		(layer "In2.Cu")
		(net "RST_RSMRST_N")
	)
	(segment
		(start 472.509088 -122.207274)
		(end 472.509088 -122.199908)
		(width 0.089408)
		(layer "In2.Cu")
		(net "RST_RSMRST_N")
	)
	(segment
		(start 389.128 -101.061266)
		(end 389.128 -101.0285)
		(width 0.0889)
		(layer "In2.Cu")
		(net "RST_RSMRST_N")
	)
	(segment
		(start 374.126506 -75.468226)
		(end 373.971312 -75.62342)
		(width 0.089408)
		(layer "In2.Cu")
		(net "RST_RSMRST_N")
	)
	(segment
		(start 419.989 -121.9708)
		(end 419.1254 -121.9708)
		(width 0.089408)
		(layer "In2.Cu")
		(net "RST_RSMRST_N")
	)
	(segment
		(start 393.735306 -107.139232)
		(end 393.735306 -106.478578)
		(width 0.0889)
		(layer "In2.Cu")
		(net "RST_RSMRST_N")
	)
	(segment
		(start 402.1455 -114.427)
		(end 400.2405 -112.522)
		(width 0.089408)
		(layer "In2.Cu")
		(net "RST_RSMRST_N")
	)
	(segment
		(start 472.922092 -122.612912)
		(end 472.914726 -122.612912)
		(width 0.089408)
		(layer "In2.Cu")
		(net "RST_RSMRST_N")
	)
	(segment
		(start 374.190006 -79.468218)
		(end 374.59412 -79.468218)
		(width 0.089408)
		(layer "In2.Cu")
		(net "RST_RSMRST_N")
	)
	(segment
		(start 423.281348 -122.301)
		(end 420.3192 -122.301)
		(width 0.089408)
		(layer "In2.Cu")
		(net "RST_RSMRST_N")
	)
	(segment
		(start 394.273024 -104.671876)
		(end 394.273024 -104.308656)
		(width 0.0889)
		(layer "In2.Cu")
		(net "RST_RSMRST_N")
	)
	(segment
		(start 373.222012 -93.307662)
		(end 373.222012 -88.723216)
		(width 0.089408)
		(layer "In2.Cu")
		(net "RST_RSMRST_N")
	)
	(segment
		(start 423.808652 -121.773696)
		(end 423.281348 -122.301)
		(width 0.089408)
		(layer "In2.Cu")
		(net "RST_RSMRST_N")
	)
	(segment
		(start 480.829366 -136.4488)
		(end 478.834958 -136.4488)
		(width 0.089408)
		(layer "In2.Cu")
		(net "RST_RSMRST_N")
	)
	(segment
		(start 440.4868 -119.119904)
		(end 439.065924 -120.54078)
		(width 0.089408)
		(layer "In2.Cu")
		(net "RST_RSMRST_N")
	)
	(segment
		(start 481.486972 -142.5702)
		(end 482.981 -141.076172)
		(width 0.089408)
		(layer "In2.Cu")
		(net "RST_RSMRST_N")
	)
	(segment
		(start 476.833946 -143.464788)
		(end 477.728534 -142.5702)
		(width 0.089408)
		(layer "In2.Cu")
		(net "RST_RSMRST_N")
	)
	(segment
		(start 476.019114 -125.709934)
		(end 472.922092 -122.612912)
		(width 0.089408)
		(layer "In2.Cu")
		(net "RST_RSMRST_N")
	)
	(segment
		(start 404.352506 -114.427)
		(end 402.1455 -114.427)
		(width 0.089408)
		(layer "In2.Cu")
		(net "RST_RSMRST_N")
	)
	(segment
		(start 476.4659 -144.0688)
		(end 476.833946 -143.700754)
		(width 0.089408)
		(layer "In2.Cu")
		(net "RST_RSMRST_N")
	)
	(segment
		(start 464.597496 -119.119904)
		(end 440.4868 -119.119904)
		(width 0.089408)
		(layer "In2.Cu")
		(net "RST_RSMRST_N")
	)
	(segment
		(start 374.197118 -94.060264)
		(end 373.974614 -94.060264)
		(width 0.089408)
		(layer "In2.Cu")
		(net "RST_RSMRST_N")
	)
	(segment
		(start 476.510096 -125.709934)
		(end 476.019114 -125.709934)
		(width 0.089408)
		(layer "In2.Cu")
		(net "RST_RSMRST_N")
	)
	(segment
		(start 378.15012 -99.737926)
		(end 377.77928 -99.367086)
		(width 0.089408)
		(layer "In2.Cu")
		(net "RST_RSMRST_N")
	)
	(segment
		(start 380.38786 -99.737926)
		(end 378.15012 -99.737926)
		(width 0.089408)
		(layer "In2.Cu")
		(net "RST_RSMRST_N")
	)
	(segment
		(start 478.834958 -136.4488)
		(end 477.745298 -135.35914)
		(width 0.089408)
		(layer "In2.Cu")
		(net "RST_RSMRST_N")
	)
	(segment
		(start 375.970546 -95.833692)
		(end 374.197118 -94.060264)
		(width 0.089408)
		(layer "In2.Cu")
		(net "RST_RSMRST_N")
	)
	(segment
		(start 465.836 -120.358408)
		(end 464.597496 -119.119904)
		(width 0.089408)
		(layer "In2.Cu")
		(net "RST_RSMRST_N")
	)
	(segment
		(start 374.59412 -79.468218)
		(end 376.231404 -81.105502)
		(width 0.089408)
		(layer "In2.Cu")
		(net "RST_RSMRST_N")
	)
	(segment
		(start 476.833946 -143.700754)
		(end 476.833946 -143.464788)
		(width 0.089408)
		(layer "In2.Cu")
		(net "RST_RSMRST_N")
	)
	(segment
		(start 381.593852 -98.975926)
		(end 381.156718 -99.228148)
		(width 0.0889)
		(layer "In2.Cu")
		(net "RST_RSMRST_N")
	)
	(segment
		(start 377.16714 -70.721728)
		(end 376.590052 -70.721728)
		(width 0.089408)
		(layer "In2.Cu")
		(net "RST_RSMRST_N")
	)
	(segment
		(start 369.749832 -81.075022)
		(end 369.1255 -81.075022)
		(width 0.089408)
		(layer "In2.Cu")
		(net "RST_RSMRST_N")
	)
	(segment
		(start 375.518172 -74.646028)
		(end 375.518172 -75.278742)
		(width 0.089408)
		(layer "In2.Cu")
		(net "RST_RSMRST_N")
	)
	(segment
		(start 376.3264 -70.98538)
		(end 376.3264 -73.8378)
		(width 0.089408)
		(layer "In2.Cu")
		(net "RST_RSMRST_N")
	)
	(segment
		(start 472.509088 -122.199908)
		(end 470.667588 -120.358408)
		(width 0.089408)
		(layer "In2.Cu")
		(net "RST_RSMRST_N")
	)
	(segment
		(start 434.536596 -121.50471)
		(end 428.401988 -121.50471)
		(width 0.089408)
		(layer "In2.Cu")
		(net "RST_RSMRST_N")
	)
	(segment
		(start 482.981 -138.600434)
		(end 480.829366 -136.4488)
		(width 0.089408)
		(layer "In2.Cu")
		(net "RST_RSMRST_N")
	)
	(segment
		(start 395.25067 -108.332016)
		(end 394.92809 -108.332016)
		(width 0.0889)
		(layer "In2.Cu")
		(net "RST_RSMRST_N")
	)
	(segment
		(start 373.971312 -79.249524)
		(end 374.190006 -79.468218)
		(width 0.089408)
		(layer "In2.Cu")
		(net "RST_RSMRST_N")
	)
	(segment
		(start 418.609272 -122.486928)
		(end 412.028132 -122.486928)
		(width 0.089408)
		(layer "In2.Cu")
		(net "RST_RSMRST_N")
	)
	(segment
		(start 376.231404 -81.105502)
		(end 376.231404 -83.03895)
		(width 0.089408)
		(layer "In2.Cu")
		(net "RST_RSMRST_N")
	)
	(segment
		(start 404.625048 -116.647468)
		(end 404.625048 -114.699542)
		(width 0.089408)
		(layer "In2.Cu")
		(net "RST_RSMRST_N")
	)
	(segment
		(start 393.777724 -105.167176)
		(end 394.273024 -104.671876)
		(width 0.0889)
		(layer "In2.Cu")
		(net "RST_RSMRST_N")
	)
	(segment
		(start 412.028132 -122.486928)
		(end 411.45714 -123.05792)
		(width 0.089408)
		(layer "In2.Cu")
		(net "RST_RSMRST_N")
	)
	(segment
		(start 376.3264 -73.8378)
		(end 375.518172 -74.646028)
		(width 0.089408)
		(layer "In2.Cu")
		(net "RST_RSMRST_N")
	)
	(segment
		(start 393.948412 -106.265472)
		(end 393.948412 -105.668064)
		(width 0.0889)
		(layer "In2.Cu")
		(net "RST_RSMRST_N")
	)
	(segment
		(start 428.133002 -121.773696)
		(end 423.808652 -121.773696)
		(width 0.089408)
		(layer "In2.Cu")
		(net "RST_RSMRST_N")
	)
	(segment
		(start 409.858972 -123.05792)
		(end 407.946606 -121.145554)
		(width 0.089408)
		(layer "In2.Cu")
		(net "RST_RSMRST_N")
	)
	(segment
		(start 428.401988 -121.50471)
		(end 428.133002 -121.773696)
		(width 0.089408)
		(layer "In2.Cu")
		(net "RST_RSMRST_N")
	)
	(segment
		(start 373.222012 -88.723216)
		(end 374.44045 -87.504778)
		(width 0.089408)
		(layer "In2.Cu")
		(net "RST_RSMRST_N")
	)
	(segment
		(start 411.45714 -123.05792)
		(end 409.858972 -123.05792)
		(width 0.089408)
		(layer "In2.Cu")
		(net "RST_RSMRST_N")
	)
	(segment
		(start 375.970546 -97.650808)
		(end 375.970546 -95.833692)
		(width 0.089408)
		(layer "In2.Cu")
		(net "RST_RSMRST_N")
	)
	(segment
		(start 472.914726 -122.612912)
		(end 472.509088 -122.207274)
		(width 0.089408)
		(layer "In2.Cu")
		(net "RST_RSMRST_N")
	)
	(segment
		(start 482.981 -141.076172)
		(end 482.981 -138.600434)
		(width 0.089408)
		(layer "In2.Cu")
		(net "RST_RSMRST_N")
	)
	(segment
		(start 407.946606 -121.145554)
		(end 407.946606 -119.969026)
		(width 0.089408)
		(layer "In2.Cu")
		(net "RST_RSMRST_N")
	)
	(segment
		(start 394.273024 -104.308656)
		(end 394.5763 -104.00538)
		(width 0.0889)
		(layer "In2.Cu")
		(net "RST_RSMRST_N")
	)
	(segment
		(start 390.1186 -102.778306)
		(end 390.1186 -102.74554)
		(width 0.0889)
		(layer "In2.Cu")
		(net "RST_RSMRST_N")
	)
	(segment
		(start 379.99162 -67.98691)
		(end 379.901958 -67.98691)
		(width 0.089408)
		(layer "In2.Cu")
		(net "RST_RSMRST_N")
	)
	(segment
		(start 379.901958 -67.98691)
		(end 377.16714 -70.721728)
		(width 0.089408)
		(layer "In2.Cu")
		(net "RST_RSMRST_N")
	)
	(segment
		(start 369.1255 -81.075022)
		(end 368.745262 -80.694784)
		(width 0.089408)
		(layer "In2.Cu")
		(net "RST_RSMRST_N")
	)
	(segment
		(start 477.728534 -142.5702)
		(end 481.486972 -142.5702)
		(width 0.089408)
		(layer "In2.Cu")
		(net "RST_RSMRST_N")
	)
	(segment
		(start 376.590052 -70.721728)
		(end 376.3264 -70.98538)
		(width 0.089408)
		(layer "In2.Cu")
		(net "RST_RSMRST_N")
	)
	(segment
		(start 477.745298 -126.945136)
		(end 476.510096 -125.709934)
		(width 0.089408)
		(layer "In2.Cu")
		(net "RST_RSMRST_N")
	)
	(segment
		(start 373.974614 -94.060264)
		(end 373.222012 -93.307662)
		(width 0.089408)
		(layer "In2.Cu")
		(net "RST_RSMRST_N")
	)
	(segment
		(start 394.5763 -104.00538)
		(end 394.5763 -103.60406)
		(width 0.0889)
		(layer "In2.Cu")
		(net "RST_RSMRST_N")
	)
	(segment
		(start 400.2405 -112.522)
		(end 400.111468 -112.392968)
		(width 0.0889)
		(layer "In2.Cu")
		(net "RST_RSMRST_N")
	)
	(segment
		(start 376.9614 -83.768946)
		(end 376.9614 -83.84921)
		(width 0.089408)
		(layer "In2.Cu")
		(net "RST_RSMRST_N")
	)
	(segment
		(start 373.229886 -84.555076)
		(end 369.749832 -81.075022)
		(width 0.089408)
		(layer "In2.Cu")
		(net "RST_RSMRST_N")
	)
	(segment
		(start 439.065924 -120.54078)
		(end 435.500526 -120.54078)
		(width 0.089408)
		(layer "In2.Cu")
		(net "RST_RSMRST_N")
	)
	(segment
		(start 420.3192 -122.301)
		(end 419.989 -121.9708)
		(width 0.089408)
		(layer "In2.Cu")
		(net "RST_RSMRST_N")
	)
	(segment
		(start 470.667588 -120.358408)
		(end 465.836 -120.358408)
		(width 0.089408)
		(layer "In2.Cu")
		(net "RST_RSMRST_N")
	)
	(arc
		(start 390.1186 -102.74554)
		(mid 390.06225 -102.55169)
		(end 389.918448 -102.410006)
		(width 0.0889)
		(layer "In2.Cu")
		(net "RST_RSMRST_N")
	)
	(arc
		(start 397.938752 -112.313974)
		(mid 397.64335 -112.393105)
		(end 397.347948 -112.313974)
		(width 0.0889)
		(layer "In2.Cu")
		(net "RST_RSMRST_N")
	)
	(arc
		(start 388.1374 -99.31146)
		(mid 387.932698 -98.973345)
		(end 387.537452 -98.975926)
		(width 0.0889)
		(layer "In2.Cu")
		(net "RST_RSMRST_N")
	)
	(arc
		(start 382.984248 -98.975926)
		(mid 382.78435 -98.922427)
		(end 382.584452 -98.975926)
		(width 0.0889)
		(layer "In2.Cu")
		(net "RST_RSMRST_N")
	)
	(arc
		(start 388.6327 -100.16998)
		(mid 388.57635 -99.97613)
		(end 388.432548 -99.834446)
		(width 0.0889)
		(layer "In2.Cu")
		(net "RST_RSMRST_N")
	)
	(arc
		(start 394.5763 -103.60406)
		(mid 394.371598 -103.265945)
		(end 393.976352 -103.268526)
		(width 0.0889)
		(layer "In2.Cu")
		(net "RST_RSMRST_N")
	)
	(arc
		(start 398.338548 -112.313974)
		(mid 398.13865 -112.260475)
		(end 397.938752 -112.313974)
		(width 0.0889)
		(layer "In2.Cu")
		(net "RST_RSMRST_N")
	)
	(arc
		(start 383.974848 -98.975926)
		(mid 383.77495 -98.922427)
		(end 383.575052 -98.975926)
		(width 0.0889)
		(layer "In2.Cu")
		(net "RST_RSMRST_N")
	)
	(arc
		(start 393.385548 -103.268526)
		(mid 393.18565 -103.215027)
		(end 392.985752 -103.268526)
		(width 0.0889)
		(layer "In2.Cu")
		(net "RST_RSMRST_N")
	)
	(arc
		(start 399.329148 -112.313974)
		(mid 399.12925 -112.260475)
		(end 398.929352 -112.313974)
		(width 0.0889)
		(layer "In2.Cu")
		(net "RST_RSMRST_N")
	)
	(arc
		(start 395.862048 -111.455454)
		(mid 395.645153 -111.238761)
		(end 395.565884 -110.942628)
		(width 0.0889)
		(layer "In2.Cu")
		(net "RST_RSMRST_N")
	)
	(arc
		(start 395.366748 -108.419646)
		(mid 395.306012 -108.379405)
		(end 395.25067 -108.332016)
		(width 0.0889)
		(layer "In2.Cu")
		(net "RST_RSMRST_N")
	)
	(arc
		(start 381.156718 -99.228148)
		(mid 380.986149 -99.298655)
		(end 380.80315 -99.322636)
		(width 0.0889)
		(layer "In2.Cu")
		(net "RST_RSMRST_N")
	)
	(arc
		(start 382.584452 -98.975926)
		(mid 382.28905 -99.055057)
		(end 381.993648 -98.975926)
		(width 0.0889)
		(layer "In2.Cu")
		(net "RST_RSMRST_N")
	)
	(arc
		(start 386.946648 -98.975926)
		(mid 386.74675 -98.922427)
		(end 386.546852 -98.975926)
		(width 0.0889)
		(layer "In2.Cu")
		(net "RST_RSMRST_N")
	)
	(arc
		(start 396.948152 -112.313974)
		(mid 396.366644 -112.319228)
		(end 396.0622 -111.823754)
		(width 0.0889)
		(layer "In2.Cu")
		(net "RST_RSMRST_N")
	)
	(arc
		(start 397.347948 -112.313974)
		(mid 397.14805 -112.260475)
		(end 396.948152 -112.313974)
		(width 0.0889)
		(layer "In2.Cu")
		(net "RST_RSMRST_N")
	)
	(arc
		(start 381.993648 -98.975926)
		(mid 381.79375 -98.922427)
		(end 381.593852 -98.975926)
		(width 0.0889)
		(layer "In2.Cu")
		(net "RST_RSMRST_N")
	)
	(arc
		(start 396.0622 -111.790988)
		(mid 396.00585 -111.597138)
		(end 395.862048 -111.455454)
		(width 0.0889)
		(layer "In2.Cu")
		(net "RST_RSMRST_N")
	)
	(arc
		(start 384.565652 -98.975926)
		(mid 384.27025 -99.055057)
		(end 383.974848 -98.975926)
		(width 0.0889)
		(layer "In2.Cu")
		(net "RST_RSMRST_N")
	)
	(arc
		(start 391.995152 -103.268526)
		(mid 391.69975 -103.347657)
		(end 391.404348 -103.268526)
		(width 0.0889)
		(layer "In2.Cu")
		(net "RST_RSMRST_N")
	)
	(arc
		(start 384.965448 -98.975926)
		(mid 384.76555 -98.922427)
		(end 384.565652 -98.975926)
		(width 0.0889)
		(layer "In2.Cu")
		(net "RST_RSMRST_N")
	)
	(arc
		(start 388.927848 -100.692966)
		(mid 388.716984 -100.485962)
		(end 388.6327 -100.202746)
		(width 0.0889)
		(layer "In2.Cu")
		(net "RST_RSMRST_N")
	)
	(arc
		(start 389.423148 -101.551486)
		(mid 389.212284 -101.344482)
		(end 389.128 -101.061266)
		(width 0.0889)
		(layer "In2.Cu")
		(net "RST_RSMRST_N")
	)
	(arc
		(start 395.5669 -108.75518)
		(mid 395.51055 -108.56133)
		(end 395.366748 -108.419646)
		(width 0.0889)
		(layer "In2.Cu")
		(net "RST_RSMRST_N")
	)
	(arc
		(start 395.565884 -110.613952)
		(mid 395.643484 -110.260269)
		(end 395.862048 -109.971586)
		(width 0.0889)
		(layer "In2.Cu")
		(net "RST_RSMRST_N")
	)
	(arc
		(start 388.432548 -99.834446)
		(mid 388.221684 -99.627442)
		(end 388.1374 -99.344226)
		(width 0.0889)
		(layer "In2.Cu")
		(net "RST_RSMRST_N")
	)
	(arc
		(start 392.394948 -103.268526)
		(mid 392.19505 -103.215027)
		(end 391.995152 -103.268526)
		(width 0.0889)
		(layer "In2.Cu")
		(net "RST_RSMRST_N")
	)
	(arc
		(start 385.556252 -98.975926)
		(mid 385.26085 -99.055057)
		(end 384.965448 -98.975926)
		(width 0.0889)
		(layer "In2.Cu")
		(net "RST_RSMRST_N")
	)
	(arc
		(start 399.62455 -112.392968)
		(mid 399.471648 -112.372916)
		(end 399.329148 -112.313974)
		(width 0.0889)
		(layer "In2.Cu")
		(net "RST_RSMRST_N")
	)
	(arc
		(start 393.976352 -103.268526)
		(mid 393.68095 -103.347657)
		(end 393.385548 -103.268526)
		(width 0.0889)
		(layer "In2.Cu")
		(net "RST_RSMRST_N")
	)
	(arc
		(start 392.985752 -103.268526)
		(mid 392.69035 -103.347657)
		(end 392.394948 -103.268526)
		(width 0.0889)
		(layer "In2.Cu")
		(net "RST_RSMRST_N")
	)
	(arc
		(start 389.128 -101.0285)
		(mid 389.07165 -100.83465)
		(end 388.927848 -100.692966)
		(width 0.0889)
		(layer "In2.Cu")
		(net "RST_RSMRST_N")
	)
	(arc
		(start 391.004552 -103.268526)
		(mid 390.423044 -103.27378)
		(end 390.1186 -102.778306)
		(width 0.0889)
		(layer "In2.Cu")
		(net "RST_RSMRST_N")
	)
	(arc
		(start 389.6233 -101.88702)
		(mid 389.56695 -101.69317)
		(end 389.423148 -101.551486)
		(width 0.0889)
		(layer "In2.Cu")
		(net "RST_RSMRST_N")
	)
	(arc
		(start 398.929352 -112.313974)
		(mid 398.63395 -112.393105)
		(end 398.338548 -112.313974)
		(width 0.0889)
		(layer "In2.Cu")
		(net "RST_RSMRST_N")
	)
	(arc
		(start 389.918448 -102.410006)
		(mid 389.707584 -102.203002)
		(end 389.6233 -101.919786)
		(width 0.0889)
		(layer "In2.Cu")
		(net "RST_RSMRST_N")
	)
	(arc
		(start 395.862048 -109.971586)
		(mid 396.062359 -109.624876)
		(end 395.862048 -109.278166)
		(width 0.0889)
		(layer "In2.Cu")
		(net "RST_RSMRST_N")
	)
	(arc
		(start 387.537452 -98.975926)
		(mid 387.24205 -99.055057)
		(end 386.946648 -98.975926)
		(width 0.0889)
		(layer "In2.Cu")
		(net "RST_RSMRST_N")
	)
	(arc
		(start 391.404348 -103.268526)
		(mid 391.20445 -103.215027)
		(end 391.004552 -103.268526)
		(width 0.0889)
		(layer "In2.Cu")
		(net "RST_RSMRST_N")
	)
	(arc
		(start 385.956048 -98.975926)
		(mid 385.75615 -98.922427)
		(end 385.556252 -98.975926)
		(width 0.0889)
		(layer "In2.Cu")
		(net "RST_RSMRST_N")
	)
	(arc
		(start 386.546852 -98.975926)
		(mid 386.25145 -99.055057)
		(end 385.956048 -98.975926)
		(width 0.0889)
		(layer "In2.Cu")
		(net "RST_RSMRST_N")
	)
	(arc
		(start 395.862048 -109.278166)
		(mid 395.651184 -109.071162)
		(end 395.5669 -108.787946)
		(width 0.0889)
		(layer "In2.Cu")
		(net "RST_RSMRST_N")
	)
	(arc
		(start 383.575052 -98.975926)
		(mid 383.27965 -99.055057)
		(end 382.984248 -98.975926)
		(width 0.0889)
		(layer "In2.Cu")
		(net "RST_RSMRST_N")
	)
	(segment
		(start 384.7084 -32.93237)
		(end 384.7084 -32.1691)
		(width 0.089408)
		(layer "In4.Cu")
		(net "RST_RSMRST_N")
	)
	(segment
		(start 385.450842 -33.674812)
		(end 384.7084 -32.93237)
		(width 0.089408)
		(layer "In4.Cu")
		(net "RST_RSMRST_N")
	)
	(segment
		(start 389.482838 -33.039812)
		(end 389.350758 -32.907732)
		(width 0.089408)
		(layer "In4.Cu")
		(net "RST_RSMRST_N")
	)
	(segment
		(start 376.579384 -83.467194)
		(end 376.9614 -83.84921)
		(width 0.089408)
		(layer "In4.Cu")
		(net "RST_RSMRST_N")
	)
	(segment
		(start 389.350758 -32.907732)
		(end 386.81279 -32.907732)
		(width 0.089408)
		(layer "In4.Cu")
		(net "RST_RSMRST_N")
	)
	(segment
		(start 368.745262 -80.694784)
		(end 371.517672 -83.467194)
		(width 0.089408)
		(layer "In4.Cu")
		(net "RST_RSMRST_N")
	)
	(segment
		(start 394.251434 -33.782)
		(end 393.509246 -33.039812)
		(width 0.089408)
		(layer "In4.Cu")
		(net "RST_RSMRST_N")
	)
	(segment
		(start 386.04571 -33.674812)
		(end 385.450842 -33.674812)
		(width 0.089408)
		(layer "In4.Cu")
		(net "RST_RSMRST_N")
	)
	(segment
		(start 393.509246 -33.039812)
		(end 389.482838 -33.039812)
		(width 0.089408)
		(layer "In4.Cu")
		(net "RST_RSMRST_N")
	)
	(segment
		(start 371.517672 -83.467194)
		(end 376.579384 -83.467194)
		(width 0.089408)
		(layer "In4.Cu")
		(net "RST_RSMRST_N")
	)
	(segment
		(start 386.81279 -32.907732)
		(end 386.04571 -33.674812)
		(width 0.089408)
		(layer "In4.Cu")
		(net "RST_RSMRST_N")
	)
	(segment
		(start 382.78435 -41.66235)
		(end 382.78435 -46.135544)
		(width 0.089408)
		(layer "In9.Cu")
		(net "RST_RSMRST_N")
	)
	(segment
		(start 381.692912 -60.030868)
		(end 381.692912 -61.401452)
		(width 0.089408)
		(layer "In9.Cu")
		(net "RST_RSMRST_N")
	)
	(segment
		(start 378.872242 -65.11036)
		(end 379.484636 -65.722754)
		(width 0.089408)
		(layer "In9.Cu")
		(net "RST_RSMRST_N")
	)
	(segment
		(start 382.466342 -56.300878)
		(end 382.466342 -59.257438)
		(width 0.089408)
		(layer "In9.Cu")
		(net "RST_RSMRST_N")
	)
	(segment
		(start 382.524 -41.402)
		(end 382.78435 -41.66235)
		(width 0.089408)
		(layer "In9.Cu")
		(net "RST_RSMRST_N")
	)
	(segment
		(start 382.298702 -56.133238)
		(end 382.466342 -56.300878)
		(width 0.089408)
		(layer "In9.Cu")
		(net "RST_RSMRST_N")
	)
	(segment
		(start 382.345946 -35.687254)
		(end 381.634492 -35.687254)
		(width 0.089408)
		(layer "In9.Cu")
		(net "RST_RSMRST_N")
	)
	(segment
		(start 382.43383 -36.591748)
		(end 382.905 -37.062918)
		(width 0.089408)
		(layer "In9.Cu")
		(net "RST_RSMRST_N")
	)
	(segment
		(start 379.484636 -66.114422)
		(end 379.99162 -66.621406)
		(width 0.089408)
		(layer "In9.Cu")
		(net "RST_RSMRST_N")
	)
	(segment
		(start 384.7084 -32.1691)
		(end 383.9337 -32.9438)
		(width 0.089408)
		(layer "In9.Cu")
		(net "RST_RSMRST_N")
	)
	(segment
		(start 382.78435 -46.135544)
		(end 382.298194 -46.6217)
		(width 0.089408)
		(layer "In9.Cu")
		(net "RST_RSMRST_N")
	)
	(segment
		(start 383.9337 -32.9438)
		(end 383.753614 -32.9438)
		(width 0.089408)
		(layer "In9.Cu")
		(net "RST_RSMRST_N")
	)
	(segment
		(start 379.971554 -63.633604)
		(end 378.872242 -64.732916)
		(width 0.089408)
		(layer "In9.Cu")
		(net "RST_RSMRST_N")
	)
	(segment
		(start 381.634492 -35.687254)
		(end 381.381 -35.940746)
		(width 0.089408)
		(layer "In9.Cu")
		(net "RST_RSMRST_N")
	)
	(segment
		(start 381.381 -35.940746)
		(end 381.381 -36.258246)
		(width 0.089408)
		(layer "In9.Cu")
		(net "RST_RSMRST_N")
	)
	(segment
		(start 382.298194 -46.6217)
		(end 382.298702 -46.622208)
		(width 0.089408)
		(layer "In9.Cu")
		(net "RST_RSMRST_N")
	)
	(segment
		(start 378.872242 -64.732916)
		(end 378.872242 -65.11036)
		(width 0.089408)
		(layer "In9.Cu")
		(net "RST_RSMRST_N")
	)
	(segment
		(start 379.971554 -63.12281)
		(end 379.971554 -63.633604)
		(width 0.089408)
		(layer "In9.Cu")
		(net "RST_RSMRST_N")
	)
	(segment
		(start 383.254758 -34.778442)
		(end 382.345946 -35.687254)
		(width 0.089408)
		(layer "In9.Cu")
		(net "RST_RSMRST_N")
	)
	(segment
		(start 381.714502 -36.591748)
		(end 382.43383 -36.591748)
		(width 0.089408)
		(layer "In9.Cu")
		(net "RST_RSMRST_N")
	)
	(segment
		(start 383.254758 -33.442656)
		(end 383.254758 -34.778442)
		(width 0.089408)
		(layer "In9.Cu")
		(net "RST_RSMRST_N")
	)
	(segment
		(start 382.298702 -46.622208)
		(end 382.298702 -56.133238)
		(width 0.089408)
		(layer "In9.Cu")
		(net "RST_RSMRST_N")
	)
	(segment
		(start 382.466342 -59.257438)
		(end 381.692912 -60.030868)
		(width 0.089408)
		(layer "In9.Cu")
		(net "RST_RSMRST_N")
	)
	(segment
		(start 381.692912 -61.401452)
		(end 379.971554 -63.12281)
		(width 0.089408)
		(layer "In9.Cu")
		(net "RST_RSMRST_N")
	)
	(segment
		(start 382.905 -37.062918)
		(end 382.905 -37.719)
		(width 0.089408)
		(layer "In9.Cu")
		(net "RST_RSMRST_N")
	)
	(segment
		(start 379.99162 -66.621406)
		(end 379.99162 -67.98691)
		(width 0.089408)
		(layer "In9.Cu")
		(net "RST_RSMRST_N")
	)
	(segment
		(start 382.905 -37.719)
		(end 382.524 -38.1)
		(width 0.089408)
		(layer "In9.Cu")
		(net "RST_RSMRST_N")
	)
	(segment
		(start 382.524 -38.1)
		(end 382.524 -41.402)
		(width 0.089408)
		(layer "In9.Cu")
		(net "RST_RSMRST_N")
	)
	(segment
		(start 383.753614 -32.9438)
		(end 383.254758 -33.442656)
		(width 0.089408)
		(layer "In9.Cu")
		(net "RST_RSMRST_N")
	)
	(segment
		(start 381.381 -36.258246)
		(end 381.714502 -36.591748)
		(width 0.089408)
		(layer "In9.Cu")
		(net "RST_RSMRST_N")
	)
	(segment
		(start 379.484636 -65.722754)
		(end 379.484636 -66.114422)
		(width 0.089408)
		(layer "In9.Cu")
		(net "RST_RSMRST_N")
	)
	(segment
		(start 420.11981 -55.178706)
		(end 419.941502 -55.357014)
		(width 0.10795)
		(layer "F.Cu")
		(net "RST_PLTRST_N")
	)
	(segment
		(start 419.941502 -55.914798)
		(end 419.1635 -56.6928)
		(width 0.10795)
		(layer "F.Cu")
		(net "RST_PLTRST_N")
	)
	(segment
		(start 419.1635 -56.6928)
		(end 419.1635 -57.1881)
		(width 0.10795)
		(layer "F.Cu")
		(net "RST_PLTRST_N")
	)
	(segment
		(start 419.941502 -55.357014)
		(end 419.941502 -55.914798)
		(width 0.10795)
		(layer "F.Cu")
		(net "RST_PLTRST_N")
	)
	(segment
		(start 367.145316 -71.095108)
		(end 367.545112 -71.494904)
		(width 0.10795)
		(layer "F.Cu")
		(net "RST_PLTRST_N")
	)
	(segment
		(start 398.63395 -101.039676)
		(end 398.13865 -101.2698)
		(width 0.10795)
		(layer "F.Cu")
		(net "RST_PLTRST_N")
	)
	(via
		(at 487.062272 -51.10861)
		(size 0.508)
		(drill 0.254)
		(layers "F.Cu" "B.Cu")
		(net "RST_PLTRST_N")
	)
	(via
		(at 435.136798 -54.137052)
		(size 0.6604)
		(drill 0.3302)
		(layers "F.Cu" "B.Cu")
		(net "RST_PLTRST_N")
	)
	(via
		(at 394.4366 -71.5518)
		(size 0.508)
		(drill 0.254)
		(layers "F.Cu" "B.Cu")
		(net "RST_PLTRST_N")
	)
	(via
		(at 471.705432 -139.727432)
		(size 0.508)
		(drill 0.254)
		(layers "F.Cu" "B.Cu")
		(net "RST_PLTRST_N")
	)
	(via
		(at 398.63395 -101.039676)
		(size 0.508)
		(drill 0.254)
		(layers "F.Cu" "B.Cu")
		(net "RST_PLTRST_N")
	)
	(via
		(at 367.145316 -71.095108)
		(size 0.4572)
		(drill 0.2032)
		(layers "F.Cu" "B.Cu")
		(net "RST_PLTRST_N")
	)
	(via
		(at 493.268 -111.887)
		(size 0.508)
		(drill 0.254)
		(layers "F.Cu" "B.Cu")
		(net "RST_PLTRST_N")
	)
	(via
		(at 420.11981 -55.178706)
		(size 0.508)
		(drill 0.254)
		(layers "F.Cu" "B.Cu")
		(net "RST_PLTRST_N")
	)
	(segment
		(start 481.34778 -50.5968)
		(end 482.88702 -50.5968)
		(width 0.10795)
		(layer "B.Cu")
		(net "RST_PLTRST_N")
	)
	(segment
		(start 423.833544 -53.342032)
		(end 422.58488 -53.342032)
		(width 0.10795)
		(layer "B.Cu")
		(net "RST_PLTRST_N")
	)
	(segment
		(start 424.731942 -54.219348)
		(end 423.90314 -53.390546)
		(width 0.10795)
		(layer "B.Cu")
		(net "RST_PLTRST_N")
	)
	(segment
		(start 423.882058 -53.390546)
		(end 423.833544 -53.342032)
		(width 0.10795)
		(layer "B.Cu")
		(net "RST_PLTRST_N")
	)
	(segment
		(start 434.593746 -53.594)
		(end 428.625 -53.594)
		(width 0.10795)
		(layer "B.Cu")
		(net "RST_PLTRST_N")
	)
	(segment
		(start 473.660216 -139.087352)
		(end 472.345512 -139.087352)
		(width 0.10795)
		(layer "B.Cu")
		(net "RST_PLTRST_N")
	)
	(segment
		(start 468.02548 -51.8414)
		(end 470.12479 -51.8414)
		(width 0.10795)
		(layer "B.Cu")
		(net "RST_PLTRST_N")
	)
	(segment
		(start 422.019476 -54.832504)
		(end 421.673274 -55.178706)
		(width 0.10795)
		(layer "B.Cu")
		(net "RST_PLTRST_N")
	)
	(segment
		(start 428.625 -53.594)
		(end 427.999652 -54.219348)
		(width 0.10795)
		(layer "B.Cu")
		(net "RST_PLTRST_N")
	)
	(segment
		(start 436.171848 -55.172102)
		(end 464.694778 -55.172102)
		(width 0.10795)
		(layer "B.Cu")
		(net "RST_PLTRST_N")
	)
	(segment
		(start 486.858056 -50.904394)
		(end 487.062272 -51.10861)
		(width 0.10795)
		(layer "B.Cu")
		(net "RST_PLTRST_N")
	)
	(segment
		(start 435.136798 -54.137052)
		(end 434.593746 -53.594)
		(width 0.10795)
		(layer "B.Cu")
		(net "RST_PLTRST_N")
	)
	(segment
		(start 484.9749 -50.140108)
		(end 485.739186 -50.904394)
		(width 0.10795)
		(layer "B.Cu")
		(net "RST_PLTRST_N")
	)
	(segment
		(start 478.8408 -50.19802)
		(end 478.93732 -50.1015)
		(width 0.10795)
		(layer "B.Cu")
		(net "RST_PLTRST_N")
	)
	(segment
		(start 470.12479 -51.8414)
		(end 472.43619 -49.53)
		(width 0.10795)
		(layer "B.Cu")
		(net "RST_PLTRST_N")
	)
	(segment
		(start 464.694778 -55.172102)
		(end 468.02548 -51.8414)
		(width 0.10795)
		(layer "B.Cu")
		(net "RST_PLTRST_N")
	)
	(segment
		(start 476.89262 -50.19802)
		(end 478.8408 -50.19802)
		(width 0.10795)
		(layer "B.Cu")
		(net "RST_PLTRST_N")
	)
	(segment
		(start 422.034462 -53.89245)
		(end 422.034462 -53.907182)
		(width 0.10795)
		(layer "B.Cu")
		(net "RST_PLTRST_N")
	)
	(segment
		(start 422.024302 -54.559454)
		(end 422.019476 -54.56428)
		(width 0.10795)
		(layer "B.Cu")
		(net "RST_PLTRST_N")
	)
	(segment
		(start 478.93732 -50.1015)
		(end 480.85248 -50.1015)
		(width 0.10795)
		(layer "B.Cu")
		(net "RST_PLTRST_N")
	)
	(segment
		(start 472.345512 -139.087352)
		(end 471.705432 -139.727432)
		(width 0.10795)
		(layer "B.Cu")
		(net "RST_PLTRST_N")
	)
	(segment
		(start 421.673274 -55.178706)
		(end 420.11981 -55.178706)
		(width 0.10795)
		(layer "B.Cu")
		(net "RST_PLTRST_N")
	)
	(segment
		(start 423.90314 -53.390546)
		(end 423.882058 -53.390546)
		(width 0.10795)
		(layer "B.Cu")
		(net "RST_PLTRST_N")
	)
	(segment
		(start 482.88702 -50.5968)
		(end 483.62362 -49.8602)
		(width 0.10795)
		(layer "B.Cu")
		(net "RST_PLTRST_N")
	)
	(segment
		(start 422.024302 -53.917342)
		(end 422.024302 -54.559454)
		(width 0.10795)
		(layer "B.Cu")
		(net "RST_PLTRST_N")
	)
	(segment
		(start 435.136798 -54.137052)
		(end 436.171848 -55.172102)
		(width 0.10795)
		(layer "B.Cu")
		(net "RST_PLTRST_N")
	)
	(segment
		(start 422.019476 -54.56428)
		(end 422.019476 -54.832504)
		(width 0.10795)
		(layer "B.Cu")
		(net "RST_PLTRST_N")
	)
	(segment
		(start 480.85248 -50.1015)
		(end 481.34778 -50.5968)
		(width 0.10795)
		(layer "B.Cu")
		(net "RST_PLTRST_N")
	)
	(segment
		(start 422.58488 -53.342032)
		(end 422.034462 -53.89245)
		(width 0.10795)
		(layer "B.Cu")
		(net "RST_PLTRST_N")
	)
	(segment
		(start 422.034462 -53.907182)
		(end 422.024302 -53.917342)
		(width 0.10795)
		(layer "B.Cu")
		(net "RST_PLTRST_N")
	)
	(segment
		(start 472.43619 -49.53)
		(end 476.2246 -49.53)
		(width 0.10795)
		(layer "B.Cu")
		(net "RST_PLTRST_N")
	)
	(segment
		(start 476.2246 -49.53)
		(end 476.89262 -50.19802)
		(width 0.10795)
		(layer "B.Cu")
		(net "RST_PLTRST_N")
	)
	(segment
		(start 485.739186 -50.904394)
		(end 486.858056 -50.904394)
		(width 0.10795)
		(layer "B.Cu")
		(net "RST_PLTRST_N")
	)
	(segment
		(start 483.62362 -49.8602)
		(end 484.9749 -49.8602)
		(width 0.10795)
		(layer "B.Cu")
		(net "RST_PLTRST_N")
	)
	(segment
		(start 427.999652 -54.219348)
		(end 424.731942 -54.219348)
		(width 0.10795)
		(layer "B.Cu")
		(net "RST_PLTRST_N")
	)
	(segment
		(start 484.9749 -49.8602)
		(end 484.9749 -50.140108)
		(width 0.10795)
		(layer "B.Cu")
		(net "RST_PLTRST_N")
	)
	(segment
		(start 393.902946 -80.696308)
		(end 393.902946 -79.526384)
		(width 0.089408)
		(layer "In2.Cu")
		(net "RST_PLTRST_N")
	)
	(segment
		(start 427.270418 -66.49085)
		(end 427.270672 -66.491104)
		(width 0.089408)
		(layer "In2.Cu")
		(net "RST_PLTRST_N")
	)
	(segment
		(start 393.361672 -78.36408)
		(end 393.396978 -78.328774)
		(width 0.089408)
		(layer "In2.Cu")
		(net "RST_PLTRST_N")
	)
	(segment
		(start 487.337862 -51.3842)
		(end 487.062272 -51.10861)
		(width 0.089408)
		(layer "In2.Cu")
		(net "RST_PLTRST_N")
	)
	(segment
		(start 393.396978 -78.252828)
		(end 395.594078 -76.055728)
		(width 0.089408)
		(layer "In2.Cu")
		(net "RST_PLTRST_N")
	)
	(segment
		(start 393.6746 -83.065366)
		(end 393.825222 -82.914744)
		(width 0.089408)
		(layer "In2.Cu")
		(net "RST_PLTRST_N")
	)
	(segment
		(start 396.94358 -94.305882)
		(end 396.94358 -90.775282)
		(width 0.089408)
		(layer "In2.Cu")
		(net "RST_PLTRST_N")
	)
	(segment
		(start 483.724712 -110.842298)
		(end 427.725078 -110.842298)
		(width 0.089408)
		(layer "In2.Cu")
		(net "RST_PLTRST_N")
	)
	(segment
		(start 393.361672 -78.98511)
		(end 393.361672 -78.36408)
		(width 0.089408)
		(layer "In2.Cu")
		(net "RST_PLTRST_N")
	)
	(segment
		(start 463.70748 -66.491358)
		(end 465.227924 -66.491358)
		(width 0.089408)
		(layer "In2.Cu")
		(net "RST_PLTRST_N")
	)
	(segment
		(start 425.890182 -75.936602)
		(end 425.198794 -75.245214)
		(width 0.089408)
		(layer "In2.Cu")
		(net "RST_PLTRST_N")
	)
	(segment
		(start 426.51045 -109.62767)
		(end 426.51045 -80.762094)
		(width 0.089408)
		(layer "In2.Cu")
		(net "RST_PLTRST_N")
	)
	(segment
		(start 397.738854 -96.76765)
		(end 397.738854 -96.465644)
		(width 0.089408)
		(layer "In2.Cu")
		(net "RST_PLTRST_N")
	)
	(segment
		(start 393.591542 -81.007712)
		(end 393.902946 -80.696308)
		(width 0.089408)
		(layer "In2.Cu")
		(net "RST_PLTRST_N")
	)
	(segment
		(start 394.6144 -72.2884)
		(end 394.6144 -71.7296)
		(width 0.089408)
		(layer "In2.Cu")
		(net "RST_PLTRST_N")
	)
	(segment
		(start 426.510704 -80.603852)
		(end 426.510958 -80.603598)
		(width 0.089408)
		(layer "In2.Cu")
		(net "RST_PLTRST_N")
	)
	(segment
		(start 395.0462 -89.0778)
		(end 394.5128 -88.5444)
		(width 0.089408)
		(layer "In2.Cu")
		(net "RST_PLTRST_N")
	)
	(segment
		(start 493.190784 -111.964216)
		(end 484.84663 -111.964216)
		(width 0.089408)
		(layer "In2.Cu")
		(net "RST_PLTRST_N")
	)
	(segment
		(start 465.227924 -66.491358)
		(end 465.228178 -66.491104)
		(width 0.089408)
		(layer "In2.Cu")
		(net "RST_PLTRST_N")
	)
	(segment
		(start 490.2962 -51.3842)
		(end 487.337862 -51.3842)
		(width 0.089408)
		(layer "In2.Cu")
		(net "RST_PLTRST_N")
	)
	(segment
		(start 479.437192 -61.12764)
		(end 484.379778 -61.12764)
		(width 0.089408)
		(layer "In2.Cu")
		(net "RST_PLTRST_N")
	)
	(segment
		(start 394.5128 -88.5444)
		(end 394.5128 -87.9602)
		(width 0.089408)
		(layer "In2.Cu")
		(net "RST_PLTRST_N")
	)
	(segment
		(start 393.825222 -82.914744)
		(end 393.825222 -81.74736)
		(width 0.089408)
		(layer "In2.Cu")
		(net "RST_PLTRST_N")
	)
	(segment
		(start 465.228178 -66.491104)
		(end 474.073728 -66.491104)
		(width 0.089408)
		(layer "In2.Cu")
		(net "RST_PLTRST_N")
	)
	(segment
		(start 398.63395 -101.039676)
		(end 398.305528 -100.711254)
		(width 0.089408)
		(layer "In2.Cu")
		(net "RST_PLTRST_N")
	)
	(segment
		(start 396.47114 -90.302842)
		(end 395.385036 -90.302842)
		(width 0.089408)
		(layer "In2.Cu")
		(net "RST_PLTRST_N")
	)
	(segment
		(start 474.073728 -66.491104)
		(end 479.437192 -61.12764)
		(width 0.089408)
		(layer "In2.Cu")
		(net "RST_PLTRST_N")
	)
	(segment
		(start 427.11243 -66.49085)
		(end 427.270418 -66.49085)
		(width 0.089408)
		(layer "In2.Cu")
		(net "RST_PLTRST_N")
	)
	(segment
		(start 395.594078 -76.055728)
		(end 395.594078 -73.268078)
		(width 0.089408)
		(layer "In2.Cu")
		(net "RST_PLTRST_N")
	)
	(segment
		(start 395.594078 -73.268078)
		(end 394.6144 -72.2884)
		(width 0.089408)
		(layer "In2.Cu")
		(net "RST_PLTRST_N")
	)
	(segment
		(start 393.591542 -81.51368)
		(end 393.591542 -81.007712)
		(width 0.089408)
		(layer "In2.Cu")
		(net "RST_PLTRST_N")
	)
	(segment
		(start 395.385036 -90.302842)
		(end 395.0462 -89.964006)
		(width 0.089408)
		(layer "In2.Cu")
		(net "RST_PLTRST_N")
	)
	(segment
		(start 425.198794 -68.404486)
		(end 427.11243 -66.49085)
		(width 0.089408)
		(layer "In2.Cu")
		(net "RST_PLTRST_N")
	)
	(segment
		(start 425.198794 -75.245214)
		(end 425.198794 -68.404486)
		(width 0.089408)
		(layer "In2.Cu")
		(net "RST_PLTRST_N")
	)
	(segment
		(start 426.51045 -78.324964)
		(end 425.890182 -77.704696)
		(width 0.089408)
		(layer "In2.Cu")
		(net "RST_PLTRST_N")
	)
	(segment
		(start 426.510958 -79.083154)
		(end 426.51045 -79.082646)
		(width 0.089408)
		(layer "In2.Cu")
		(net "RST_PLTRST_N")
	)
	(segment
		(start 425.890182 -77.704696)
		(end 425.890182 -75.936602)
		(width 0.089408)
		(layer "In2.Cu")
		(net "RST_PLTRST_N")
	)
	(segment
		(start 493.268 -111.887)
		(end 493.190784 -111.964216)
		(width 0.089408)
		(layer "In2.Cu")
		(net "RST_PLTRST_N")
	)
	(segment
		(start 463.707226 -66.491104)
		(end 463.70748 -66.491358)
		(width 0.089408)
		(layer "In2.Cu")
		(net "RST_PLTRST_N")
	)
	(segment
		(start 426.510704 -80.76184)
		(end 426.510704 -80.603852)
		(width 0.089408)
		(layer "In2.Cu")
		(net "RST_PLTRST_N")
	)
	(segment
		(start 397.738854 -96.465644)
		(end 398.049242 -96.155256)
		(width 0.089408)
		(layer "In2.Cu")
		(net "RST_PLTRST_N")
	)
	(segment
		(start 398.138904 -100.642166)
		(end 398.13738 -100.642166)
		(width 0.089408)
		(layer "In2.Cu")
		(net "RST_PLTRST_N")
	)
	(segment
		(start 398.049242 -95.411544)
		(end 396.94358 -94.305882)
		(width 0.089408)
		(layer "In2.Cu")
		(net "RST_PLTRST_N")
	)
	(segment
		(start 427.270672 -66.491104)
		(end 463.707226 -66.491104)
		(width 0.089408)
		(layer "In2.Cu")
		(net "RST_PLTRST_N")
	)
	(segment
		(start 398.13738 -100.642166)
		(end 397.938752 -100.527612)
		(width 0.089408)
		(layer "In2.Cu")
		(net "RST_PLTRST_N")
	)
	(segment
		(start 395.0462 -89.964006)
		(end 395.0462 -89.0778)
		(width 0.089408)
		(layer "In2.Cu")
		(net "RST_PLTRST_N")
	)
	(segment
		(start 491.378748 -54.12867)
		(end 491.378748 -52.466748)
		(width 0.089408)
		(layer "In2.Cu")
		(net "RST_PLTRST_N")
	)
	(segment
		(start 426.510958 -80.603598)
		(end 426.510958 -79.083154)
		(width 0.089408)
		(layer "In2.Cu")
		(net "RST_PLTRST_N")
	)
	(segment
		(start 393.825222 -81.74736)
		(end 393.591542 -81.51368)
		(width 0.089408)
		(layer "In2.Cu")
		(net "RST_PLTRST_N")
	)
	(segment
		(start 394.5128 -87.9602)
		(end 393.6746 -87.122)
		(width 0.089408)
		(layer "In2.Cu")
		(net "RST_PLTRST_N")
	)
	(segment
		(start 426.51045 -80.762094)
		(end 426.510704 -80.76184)
		(width 0.089408)
		(layer "In2.Cu")
		(net "RST_PLTRST_N")
	)
	(segment
		(start 427.725078 -110.842298)
		(end 426.51045 -109.62767)
		(width 0.089408)
		(layer "In2.Cu")
		(net "RST_PLTRST_N")
	)
	(segment
		(start 484.379778 -61.12764)
		(end 491.378748 -54.12867)
		(width 0.089408)
		(layer "In2.Cu")
		(net "RST_PLTRST_N")
	)
	(segment
		(start 393.6746 -87.122)
		(end 393.6746 -83.065366)
		(width 0.089408)
		(layer "In2.Cu")
		(net "RST_PLTRST_N")
	)
	(segment
		(start 426.51045 -79.082646)
		(end 426.51045 -78.324964)
		(width 0.089408)
		(layer "In2.Cu")
		(net "RST_PLTRST_N")
	)
	(segment
		(start 397.738854 -100.193348)
		(end 397.738854 -100.160582)
		(width 0.089408)
		(layer "In2.Cu")
		(net "RST_PLTRST_N")
	)
	(segment
		(start 398.049242 -96.155256)
		(end 398.049242 -95.411544)
		(width 0.089408)
		(layer "In2.Cu")
		(net "RST_PLTRST_N")
	)
	(segment
		(start 393.902946 -79.526384)
		(end 393.361672 -78.98511)
		(width 0.089408)
		(layer "In2.Cu")
		(net "RST_PLTRST_N")
	)
	(segment
		(start 484.84663 -111.964216)
		(end 483.724712 -110.842298)
		(width 0.089408)
		(layer "In2.Cu")
		(net "RST_PLTRST_N")
	)
	(segment
		(start 396.94358 -90.775282)
		(end 396.47114 -90.302842)
		(width 0.089408)
		(layer "In2.Cu")
		(net "RST_PLTRST_N")
	)
	(segment
		(start 491.378748 -52.466748)
		(end 490.2962 -51.3842)
		(width 0.089408)
		(layer "In2.Cu")
		(net "RST_PLTRST_N")
	)
	(segment
		(start 394.6144 -71.7296)
		(end 394.4366 -71.5518)
		(width 0.089408)
		(layer "In2.Cu")
		(net "RST_PLTRST_N")
	)
	(segment
		(start 393.396978 -78.328774)
		(end 393.396978 -78.252828)
		(width 0.089408)
		(layer "In2.Cu")
		(net "RST_PLTRST_N")
	)
	(arc
		(start 397.443452 -98.97618)
		(mid 397.654736 -98.768651)
		(end 397.738854 -98.48469)
		(width 0.089408)
		(layer "In2.Cu")
		(net "RST_PLTRST_N")
	)
	(arc
		(start 397.738854 -100.160582)
		(mid 397.654736 -99.876621)
		(end 397.443452 -99.669092)
		(width 0.089408)
		(layer "In2.Cu")
		(net "RST_PLTRST_N")
	)
	(arc
		(start 397.443452 -97.25914)
		(mid 397.654736 -97.051611)
		(end 397.738854 -96.76765)
		(width 0.089408)
		(layer "In2.Cu")
		(net "RST_PLTRST_N")
	)
	(arc
		(start 397.738854 -98.48469)
		(mid 397.73748 -98.417589)
		(end 397.72844 -98.351086)
		(width 0.089408)
		(layer "In2.Cu")
		(net "RST_PLTRST_N")
	)
	(arc
		(start 397.938752 -100.527612)
		(mid 397.795367 -100.386455)
		(end 397.738854 -100.193348)
		(width 0.089408)
		(layer "In2.Cu")
		(net "RST_PLTRST_N")
	)
	(arc
		(start 397.443452 -97.952052)
		(mid 397.243361 -97.605596)
		(end 397.443452 -97.25914)
		(width 0.089408)
		(layer "In2.Cu")
		(net "RST_PLTRST_N")
	)
	(arc
		(start 397.443452 -99.669092)
		(mid 397.243361 -99.322636)
		(end 397.443452 -98.97618)
		(width 0.089408)
		(layer "In2.Cu")
		(net "RST_PLTRST_N")
	)
	(arc
		(start 398.305528 -100.711254)
		(mid 398.229095 -100.66012)
		(end 398.138904 -100.642166)
		(width 0.089408)
		(layer "In2.Cu")
		(net "RST_PLTRST_N")
	)
	(arc
		(start 397.72844 -98.351086)
		(mid 397.629257 -98.120652)
		(end 397.443452 -97.952052)
		(width 0.089408)
		(layer "In2.Cu")
		(net "RST_PLTRST_N")
	)
	(segment
		(start 376.355356 -70.07479)
		(end 376.355356 -70.5231)
		(width 0.089408)
		(layer "In4.Cu")
		(net "RST_PLTRST_N")
	)
	(segment
		(start 376.508264 -69.921882)
		(end 376.355356 -70.07479)
		(width 0.089408)
		(layer "In4.Cu")
		(net "RST_PLTRST_N")
	)
	(segment
		(start 367.518696 -71.468488)
		(end 367.145316 -71.095108)
		(width 0.089408)
		(layer "In4.Cu")
		(net "RST_PLTRST_N")
	)
	(segment
		(start 381.405892 -70.505828)
		(end 381.015748 -70.115684)
		(width 0.089408)
		(layer "In4.Cu")
		(net "RST_PLTRST_N")
	)
	(segment
		(start 378.370084 -70.115684)
		(end 378.176282 -69.921882)
		(width 0.089408)
		(layer "In4.Cu")
		(net "RST_PLTRST_N")
	)
	(segment
		(start 374.499378 -71.468488)
		(end 367.518696 -71.468488)
		(width 0.089408)
		(layer "In4.Cu")
		(net "RST_PLTRST_N")
	)
	(segment
		(start 386.476494 -71.33844)
		(end 385.643882 -70.505828)
		(width 0.089408)
		(layer "In4.Cu")
		(net "RST_PLTRST_N")
	)
	(segment
		(start 385.643882 -70.505828)
		(end 381.405892 -70.505828)
		(width 0.089408)
		(layer "In4.Cu")
		(net "RST_PLTRST_N")
	)
	(segment
		(start 376.156728 -70.721728)
		(end 374.990106 -70.721728)
		(width 0.089408)
		(layer "In4.Cu")
		(net "RST_PLTRST_N")
	)
	(segment
		(start 374.734836 -70.976998)
		(end 374.734836 -71.23303)
		(width 0.089408)
		(layer "In4.Cu")
		(net "RST_PLTRST_N")
	)
	(segment
		(start 394.4366 -71.5518)
		(end 394.22324 -71.33844)
		(width 0.089408)
		(layer "In4.Cu")
		(net "RST_PLTRST_N")
	)
	(segment
		(start 381.015748 -70.115684)
		(end 378.370084 -70.115684)
		(width 0.089408)
		(layer "In4.Cu")
		(net "RST_PLTRST_N")
	)
	(segment
		(start 374.734836 -71.23303)
		(end 374.499378 -71.468488)
		(width 0.089408)
		(layer "In4.Cu")
		(net "RST_PLTRST_N")
	)
	(segment
		(start 378.176282 -69.921882)
		(end 376.508264 -69.921882)
		(width 0.089408)
		(layer "In4.Cu")
		(net "RST_PLTRST_N")
	)
	(segment
		(start 374.990106 -70.721728)
		(end 374.734836 -70.976998)
		(width 0.089408)
		(layer "In4.Cu")
		(net "RST_PLTRST_N")
	)
	(segment
		(start 394.22324 -71.33844)
		(end 386.476494 -71.33844)
		(width 0.089408)
		(layer "In4.Cu")
		(net "RST_PLTRST_N")
	)
	(segment
		(start 376.355356 -70.5231)
		(end 376.156728 -70.721728)
		(width 0.089408)
		(layer "In4.Cu")
		(net "RST_PLTRST_N")
	)
	(segment
		(start 418.295836 -55.577486)
		(end 415.101532 -58.77179)
		(width 0.089408)
		(layer "In9.Cu")
		(net "RST_PLTRST_N")
	)
	(segment
		(start 415.101532 -63.772796)
		(end 414.896046 -63.978282)
		(width 0.089408)
		(layer "In9.Cu")
		(net "RST_PLTRST_N")
	)
	(segment
		(start 415.101532 -61.859668)
		(end 415.101532 -63.772796)
		(width 0.089408)
		(layer "In9.Cu")
		(net "RST_PLTRST_N")
	)
	(segment
		(start 406.72639 -88.654382)
		(end 406.72639 -89.54643)
		(width 0.089408)
		(layer "In9.Cu")
		(net "RST_PLTRST_N")
	)
	(segment
		(start 414.329372 -68.151248)
		(end 414.329372 -70.556374)
		(width 0.089408)
		(layer "In9.Cu")
		(net "RST_PLTRST_N")
	)
	(segment
		(start 408.564334 -86.816438)
		(end 406.72639 -88.654382)
		(width 0.089408)
		(layer "In9.Cu")
		(net "RST_PLTRST_N")
	)
	(segment
		(start 413.953198 -71.815198)
		(end 413.953198 -78.600554)
		(width 0.089408)
		(layer "In9.Cu")
		(net "RST_PLTRST_N")
	)
	(segment
		(start 414.896046 -67.584574)
		(end 414.329372 -68.151248)
		(width 0.089408)
		(layer "In9.Cu")
		(net "RST_PLTRST_N")
	)
	(segment
		(start 409.538678 -86.029292)
		(end 408.751532 -86.816438)
		(width 0.089408)
		(layer "In9.Cu")
		(net "RST_PLTRST_N")
	)
	(segment
		(start 415.246312 -60.306204)
		(end 415.246312 -61.714888)
		(width 0.089408)
		(layer "In9.Cu")
		(net "RST_PLTRST_N")
	)
	(segment
		(start 408.751532 -86.816438)
		(end 408.564334 -86.816438)
		(width 0.089408)
		(layer "In9.Cu")
		(net "RST_PLTRST_N")
	)
	(segment
		(start 419.72103 -55.577486)
		(end 418.295836 -55.577486)
		(width 0.089408)
		(layer "In9.Cu")
		(net "RST_PLTRST_N")
	)
	(segment
		(start 403.171914 -96.707452)
		(end 402.424138 -97.455228)
		(width 0.089408)
		(layer "In9.Cu")
		(net "RST_PLTRST_N")
	)
	(segment
		(start 406.72639 -89.54643)
		(end 403.171914 -93.100906)
		(width 0.089408)
		(layer "In9.Cu")
		(net "RST_PLTRST_N")
	)
	(segment
		(start 402.424138 -97.455228)
		(end 402.424138 -97.455482)
		(width 0.089408)
		(layer "In9.Cu")
		(net "RST_PLTRST_N")
	)
	(segment
		(start 413.953198 -78.600554)
		(end 409.538678 -83.015074)
		(width 0.089408)
		(layer "In9.Cu")
		(net "RST_PLTRST_N")
	)
	(segment
		(start 415.101532 -60.161424)
		(end 415.246312 -60.306204)
		(width 0.089408)
		(layer "In9.Cu")
		(net "RST_PLTRST_N")
	)
	(segment
		(start 413.766 -71.628)
		(end 413.953198 -71.815198)
		(width 0.089408)
		(layer "In9.Cu")
		(net "RST_PLTRST_N")
	)
	(segment
		(start 413.766 -71.119746)
		(end 413.766 -71.628)
		(width 0.089408)
		(layer "In9.Cu")
		(net "RST_PLTRST_N")
	)
	(segment
		(start 398.63395 -100.112322)
		(end 398.63395 -101.039676)
		(width 0.089408)
		(layer "In9.Cu")
		(net "RST_PLTRST_N")
	)
	(segment
		(start 415.246312 -61.714888)
		(end 415.101532 -61.859668)
		(width 0.089408)
		(layer "In9.Cu")
		(net "RST_PLTRST_N")
	)
	(segment
		(start 415.101532 -58.77179)
		(end 415.101532 -60.161424)
		(width 0.089408)
		(layer "In9.Cu")
		(net "RST_PLTRST_N")
	)
	(segment
		(start 400.097244 -99.782376)
		(end 398.963896 -99.782376)
		(width 0.089408)
		(layer "In9.Cu")
		(net "RST_PLTRST_N")
	)
	(segment
		(start 414.896046 -63.978282)
		(end 414.896046 -67.584574)
		(width 0.089408)
		(layer "In9.Cu")
		(net "RST_PLTRST_N")
	)
	(segment
		(start 414.329372 -70.556374)
		(end 413.766 -71.119746)
		(width 0.089408)
		(layer "In9.Cu")
		(net "RST_PLTRST_N")
	)
	(segment
		(start 409.538678 -83.015074)
		(end 409.538678 -86.029292)
		(width 0.089408)
		(layer "In9.Cu")
		(net "RST_PLTRST_N")
	)
	(segment
		(start 398.963896 -99.782376)
		(end 398.63395 -100.112322)
		(width 0.089408)
		(layer "In9.Cu")
		(net "RST_PLTRST_N")
	)
	(segment
		(start 420.11981 -55.178706)
		(end 419.72103 -55.577486)
		(width 0.089408)
		(layer "In9.Cu")
		(net "RST_PLTRST_N")
	)
	(segment
		(start 403.171914 -93.100906)
		(end 403.171914 -96.707452)
		(width 0.089408)
		(layer "In9.Cu")
		(net "RST_PLTRST_N")
	)
	(segment
		(start 402.424138 -97.455482)
		(end 400.097244 -99.782376)
		(width 0.089408)
		(layer "In9.Cu")
		(net "RST_PLTRST_N")
	)
	(segment
		(start 478.464118 -122.601482)
		(end 475.4372 -125.6284)
		(width 0.089408)
		(layer "In11.Cu")
		(net "RST_PLTRST_N")
	)
	(segment
		(start 471.760804 -139.026138)
		(end 471.760804 -139.67206)
		(width 0.089408)
		(layer "In11.Cu")
		(net "RST_PLTRST_N")
	)
	(segment
		(start 475.4372 -129.14122)
		(end 472.91498 -131.66344)
		(width 0.089408)
		(layer "In11.Cu")
		(net "RST_PLTRST_N")
	)
	(segment
		(start 471.760804 -139.67206)
		(end 471.705432 -139.727432)
		(width 0.089408)
		(layer "In11.Cu")
		(net "RST_PLTRST_N")
	)
	(segment
		(start 471.658696 -134.958836)
		(end 471.658696 -138.92403)
		(width 0.089408)
		(layer "In11.Cu")
		(net "RST_PLTRST_N")
	)
	(segment
		(start 471.47988 -132.49402)
		(end 471.47988 -134.78002)
		(width 0.089408)
		(layer "In11.Cu")
		(net "RST_PLTRST_N")
	)
	(segment
		(start 475.4372 -125.6284)
		(end 475.4372 -129.14122)
		(width 0.089408)
		(layer "In11.Cu")
		(net "RST_PLTRST_N")
	)
	(segment
		(start 478.625662 -116.35359)
		(end 478.464118 -116.515134)
		(width 0.089408)
		(layer "In11.Cu")
		(net "RST_PLTRST_N")
	)
	(segment
		(start 472.31046 -131.66344)
		(end 471.47988 -132.49402)
		(width 0.089408)
		(layer "In11.Cu")
		(net "RST_PLTRST_N")
	)
	(segment
		(start 493.268 -111.887)
		(end 479.3996 -111.887)
		(width 0.089408)
		(layer "In11.Cu")
		(net "RST_PLTRST_N")
	)
	(segment
		(start 471.658696 -138.92403)
		(end 471.760804 -139.026138)
		(width 0.089408)
		(layer "In11.Cu")
		(net "RST_PLTRST_N")
	)
	(segment
		(start 478.625662 -112.660938)
		(end 478.625662 -116.35359)
		(width 0.089408)
		(layer "In11.Cu")
		(net "RST_PLTRST_N")
	)
	(segment
		(start 478.464118 -116.515134)
		(end 478.464118 -122.601482)
		(width 0.089408)
		(layer "In11.Cu")
		(net "RST_PLTRST_N")
	)
	(segment
		(start 471.47988 -134.78002)
		(end 471.658696 -134.958836)
		(width 0.089408)
		(layer "In11.Cu")
		(net "RST_PLTRST_N")
	)
	(segment
		(start 479.3996 -111.887)
		(end 478.625662 -112.660938)
		(width 0.089408)
		(layer "In11.Cu")
		(net "RST_PLTRST_N")
	)
	(segment
		(start 472.91498 -131.66344)
		(end 472.31046 -131.66344)
		(width 0.089408)
		(layer "In11.Cu")
		(net "RST_PLTRST_N")
	)
	(segment
		(start 413.340804 -47.00397)
		(end 413.340804 -46.420786)
		(width 0.10795)
		(layer "F.Cu")
		(net "RST_PLTRST_BUF_N")
	)
	(segment
		(start 398.51838 -80.44942)
		(end 397.997172 -80.970628)
		(width 0.10795)
		(layer "F.Cu")
		(net "RST_PLTRST_BUF_N")
	)
	(segment
		(start 397.997172 -82.7913)
		(end 398.379188 -83.173316)
		(width 0.10795)
		(layer "F.Cu")
		(net "RST_PLTRST_BUF_N")
	)
	(segment
		(start 399.372074 -83.452462)
		(end 399.372074 -84.309204)
		(width 0.10795)
		(layer "F.Cu")
		(net "RST_PLTRST_BUF_N")
	)
	(segment
		(start 398.405096 -79.47279)
		(end 398.51838 -79.586074)
		(width 0.10795)
		(layer "F.Cu")
		(net "RST_PLTRST_BUF_N")
	)
	(segment
		(start 397.997172 -80.970628)
		(end 397.997172 -82.7913)
		(width 0.10795)
		(layer "F.Cu")
		(net "RST_PLTRST_BUF_N")
	)
	(segment
		(start 412.971234 -47.842678)
		(end 412.971234 -47.37354)
		(width 0.10795)
		(layer "F.Cu")
		(net "RST_PLTRST_BUF_N")
	)
	(segment
		(start 407.718006 -67.243198)
		(end 407.61666 -67.243198)
		(width 0.10795)
		(layer "F.Cu")
		(net "RST_PLTRST_BUF_N")
	)
	(segment
		(start 412.742888 -48.071024)
		(end 412.971234 -47.842678)
		(width 0.10795)
		(layer "F.Cu")
		(net "RST_PLTRST_BUF_N")
	)
	(segment
		(start 409.166568 -65.529968)
		(end 410.340048 -65.529968)
		(width 0.10795)
		(layer "F.Cu")
		(net "RST_PLTRST_BUF_N")
	)
	(segment
		(start 401.66798 -72.270874)
		(end 404.897336 -72.270874)
		(width 0.10795)
		(layer "F.Cu")
		(net "RST_PLTRST_BUF_N")
	)
	(segment
		(start 401.593558 -72.34555)
		(end 401.593558 -72.345296)
		(width 0.10795)
		(layer "F.Cu")
		(net "RST_PLTRST_BUF_N")
	)
	(segment
		(start 399.092928 -83.173316)
		(end 399.372074 -83.452462)
		(width 0.10795)
		(layer "F.Cu")
		(net "RST_PLTRST_BUF_N")
	)
	(segment
		(start 407.965402 -67.490594)
		(end 407.718006 -67.243198)
		(width 0.10795)
		(layer "F.Cu")
		(net "RST_PLTRST_BUF_N")
	)
	(segment
		(start 412.971234 -47.37354)
		(end 413.340804 -47.00397)
		(width 0.10795)
		(layer "F.Cu")
		(net "RST_PLTRST_BUF_N")
	)
	(segment
		(start 407.569416 -65.414144)
		(end 409.050744 -65.414144)
		(width 0.10795)
		(layer "F.Cu")
		(net "RST_PLTRST_BUF_N")
	)
	(segment
		(start 407.390092 -67.01663)
		(end 407.390092 -65.593468)
		(width 0.10795)
		(layer "F.Cu")
		(net "RST_PLTRST_BUF_N")
	)
	(segment
		(start 404.897336 -72.270874)
		(end 407.965402 -69.202808)
		(width 0.10795)
		(layer "F.Cu")
		(net "RST_PLTRST_BUF_N")
	)
	(segment
		(start 407.965402 -69.202808)
		(end 407.965402 -67.490594)
		(width 0.10795)
		(layer "F.Cu")
		(net "RST_PLTRST_BUF_N")
	)
	(segment
		(start 409.050744 -65.414144)
		(end 409.166568 -65.529968)
		(width 0.10795)
		(layer "F.Cu")
		(net "RST_PLTRST_BUF_N")
	)
	(segment
		(start 401.593558 -72.345296)
		(end 401.66798 -72.270874)
		(width 0.10795)
		(layer "F.Cu")
		(net "RST_PLTRST_BUF_N")
	)
	(segment
		(start 370.345208 -75.894692)
		(end 370.745004 -75.494896)
		(width 0.10795)
		(layer "F.Cu")
		(net "RST_PLTRST_BUF_N")
	)
	(segment
		(start 398.379188 -83.173316)
		(end 399.092928 -83.173316)
		(width 0.10795)
		(layer "F.Cu")
		(net "RST_PLTRST_BUF_N")
	)
	(segment
		(start 407.61666 -67.243198)
		(end 407.390092 -67.01663)
		(width 0.10795)
		(layer "F.Cu")
		(net "RST_PLTRST_BUF_N")
	)
	(segment
		(start 398.51838 -79.586074)
		(end 398.51838 -80.44942)
		(width 0.10795)
		(layer "F.Cu")
		(net "RST_PLTRST_BUF_N")
	)
	(segment
		(start 407.390092 -65.593468)
		(end 407.569416 -65.414144)
		(width 0.10795)
		(layer "F.Cu")
		(net "RST_PLTRST_BUF_N")
	)
	(via
		(at 414.232344 -50.18024)
		(size 0.508)
		(drill 0.254)
		(layers "F.Cu" "B.Cu")
		(net "RST_PLTRST_BUF_N")
	)
	(via
		(at 398.405096 -79.47279)
		(size 0.508)
		(drill 0.254)
		(layers "F.Cu" "B.Cu")
		(net "RST_PLTRST_BUF_N")
	)
	(via
		(at 401.593558 -72.34555)
		(size 0.508)
		(drill 0.254)
		(layers "F.Cu" "B.Cu")
		(net "RST_PLTRST_BUF_N")
	)
	(via
		(at 413.340804 -46.420786)
		(size 0.508)
		(drill 0.254)
		(layers "F.Cu" "B.Cu")
		(net "RST_PLTRST_BUF_N")
	)
	(via
		(at 370.345208 -75.894692)
		(size 0.4572)
		(drill 0.2032)
		(layers "F.Cu" "B.Cu")
		(net "RST_PLTRST_BUF_N")
	)
	(segment
		(start 421.576754 -50.578004)
		(end 421.329358 -50.8254)
		(width 0.10795)
		(layer "B.Cu")
		(net "RST_PLTRST_BUF_N")
	)
	(segment
		(start 413.118554 -46.420786)
		(end 412.75 -46.052232)
		(width 0.10795)
		(layer "B.Cu")
		(net "RST_PLTRST_BUF_N")
	)
	(segment
		(start 428.712884 -49.437544)
		(end 427.697138 -50.45329)
		(width 0.10795)
		(layer "B.Cu")
		(net "RST_PLTRST_BUF_N")
	)
	(segment
		(start 423.949114 -50.45329)
		(end 423.8244 -50.578004)
		(width 0.10795)
		(layer "B.Cu")
		(net "RST_PLTRST_BUF_N")
	)
	(segment
		(start 414.559242 -51.538632)
		(end 414.232344 -51.211734)
		(width 0.10795)
		(layer "B.Cu")
		(net "RST_PLTRST_BUF_N")
	)
	(segment
		(start 414.232344 -51.211734)
		(end 414.232344 -50.18024)
		(width 0.10795)
		(layer "B.Cu")
		(net "RST_PLTRST_BUF_N")
	)
	(segment
		(start 428.712884 -48.257968)
		(end 428.712884 -49.437544)
		(width 0.10795)
		(layer "B.Cu")
		(net "RST_PLTRST_BUF_N")
	)
	(segment
		(start 423.8244 -50.578004)
		(end 421.576754 -50.578004)
		(width 0.10795)
		(layer "B.Cu")
		(net "RST_PLTRST_BUF_N")
	)
	(segment
		(start 413.340804 -46.420786)
		(end 413.118554 -46.420786)
		(width 0.10795)
		(layer "B.Cu")
		(net "RST_PLTRST_BUF_N")
	)
	(segment
		(start 421.329358 -51.095656)
		(end 420.886382 -51.538632)
		(width 0.10795)
		(layer "B.Cu")
		(net "RST_PLTRST_BUF_N")
	)
	(segment
		(start 428.223934 -47.769018)
		(end 428.712884 -48.257968)
		(width 0.10795)
		(layer "B.Cu")
		(net "RST_PLTRST_BUF_N")
	)
	(segment
		(start 421.329358 -50.8254)
		(end 421.329358 -51.095656)
		(width 0.10795)
		(layer "B.Cu")
		(net "RST_PLTRST_BUF_N")
	)
	(segment
		(start 423.342054 -45.595794)
		(end 426.5295 -45.595794)
		(width 0.089408)
		(layer "B.Cu")
		(net "RST_PLTRST_BUF_N")
	)
	(segment
		(start 420.886382 -51.538632)
		(end 414.559242 -51.538632)
		(width 0.10795)
		(layer "B.Cu")
		(net "RST_PLTRST_BUF_N")
	)
	(segment
		(start 427.697138 -50.45329)
		(end 423.949114 -50.45329)
		(width 0.10795)
		(layer "B.Cu")
		(net "RST_PLTRST_BUF_N")
	)
	(segment
		(start 428.223934 -46.19498)
		(end 428.223934 -47.769018)
		(width 0.10795)
		(layer "B.Cu")
		(net "RST_PLTRST_BUF_N")
	)
	(segment
		(start 426.5295 -45.595794)
		(end 427.624748 -45.595794)
		(width 0.10795)
		(layer "B.Cu")
		(net "RST_PLTRST_BUF_N")
	)
	(segment
		(start 427.624748 -45.595794)
		(end 428.223934 -46.19498)
		(width 0.10795)
		(layer "B.Cu")
		(net "RST_PLTRST_BUF_N")
	)
	(segment
		(start 414.232344 -49.809908)
		(end 414.232344 -50.18024)
		(width 0.089408)
		(layer "In2.Cu")
		(net "RST_PLTRST_BUF_N")
	)
	(segment
		(start 414.232344 -48.939958)
		(end 414.232344 -49.424844)
		(width 0.089408)
		(layer "In2.Cu")
		(net "RST_PLTRST_BUF_N")
	)
	(segment
		(start 414.226756 -49.430432)
		(end 414.226756 -49.80432)
		(width 0.089408)
		(layer "In2.Cu")
		(net "RST_PLTRST_BUF_N")
	)
	(segment
		(start 413.340804 -46.420786)
		(end 413.593534 -46.673516)
		(width 0.089408)
		(layer "In2.Cu")
		(net "RST_PLTRST_BUF_N")
	)
	(segment
		(start 413.593534 -46.673516)
		(end 413.593534 -48.301148)
		(width 0.089408)
		(layer "In2.Cu")
		(net "RST_PLTRST_BUF_N")
	)
	(segment
		(start 413.593534 -48.301148)
		(end 414.232344 -48.939958)
		(width 0.089408)
		(layer "In2.Cu")
		(net "RST_PLTRST_BUF_N")
	)
	(segment
		(start 414.232344 -49.424844)
		(end 414.226756 -49.430432)
		(width 0.089408)
		(layer "In2.Cu")
		(net "RST_PLTRST_BUF_N")
	)
	(segment
		(start 414.226756 -49.80432)
		(end 414.232344 -49.809908)
		(width 0.089408)
		(layer "In2.Cu")
		(net "RST_PLTRST_BUF_N")
	)
	(segment
		(start 394.449046 -74.403712)
		(end 394.306806 -74.261472)
		(width 0.089408)
		(layer "In4.Cu")
		(net "RST_PLTRST_BUF_N")
	)
	(segment
		(start 400.556984 -72.178164)
		(end 400.556984 -72.297036)
		(width 0.089408)
		(layer "In4.Cu")
		(net "RST_PLTRST_BUF_N")
	)
	(segment
		(start 401.593558 -72.34555)
		(end 401.593304 -72.34555)
		(width 0.089408)
		(layer "In4.Cu")
		(net "RST_PLTRST_BUF_N")
	)
	(segment
		(start 374.771412 -74.9935)
		(end 374.499378 -74.721466)
		(width 0.089408)
		(layer "In4.Cu")
		(net "RST_PLTRST_BUF_N")
	)
	(segment
		(start 375.043192 -75.521312)
		(end 374.771412 -75.249532)
		(width 0.089408)
		(layer "In4.Cu")
		(net "RST_PLTRST_BUF_N")
	)
	(segment
		(start 379.23978 -75.521312)
		(end 375.043192 -75.521312)
		(width 0.089408)
		(layer "In4.Cu")
		(net "RST_PLTRST_BUF_N")
	)
	(segment
		(start 374.499378 -74.721466)
		(end 370.990622 -74.721466)
		(width 0.089408)
		(layer "In4.Cu")
		(net "RST_PLTRST_BUF_N")
	)
	(segment
		(start 398.286478 -73.667366)
		(end 397.626332 -74.327512)
		(width 0.089408)
		(layer "In4.Cu")
		(net "RST_PLTRST_BUF_N")
	)
	(segment
		(start 391.49401 -75.59167)
		(end 385.973828 -75.59167)
		(width 0.089408)
		(layer "In4.Cu")
		(net "RST_PLTRST_BUF_N")
	)
	(segment
		(start 401.107402 -71.859648)
		(end 400.865086 -71.859648)
		(width 0.089408)
		(layer "In4.Cu")
		(net "RST_PLTRST_BUF_N")
	)
	(segment
		(start 370.764054 -75.475846)
		(end 370.345208 -75.894692)
		(width 0.089408)
		(layer "In4.Cu")
		(net "RST_PLTRST_BUF_N")
	)
	(segment
		(start 392.824208 -74.261472)
		(end 391.49401 -75.59167)
		(width 0.089408)
		(layer "In4.Cu")
		(net "RST_PLTRST_BUF_N")
	)
	(segment
		(start 370.990622 -74.721466)
		(end 370.764054 -74.948034)
		(width 0.089408)
		(layer "In4.Cu")
		(net "RST_PLTRST_BUF_N")
	)
	(segment
		(start 400.865086 -71.859648)
		(end 400.617436 -72.107298)
		(width 0.089408)
		(layer "In4.Cu")
		(net "RST_PLTRST_BUF_N")
	)
	(segment
		(start 401.593304 -72.34555)
		(end 401.107402 -71.859648)
		(width 0.089408)
		(layer "In4.Cu")
		(net "RST_PLTRST_BUF_N")
	)
	(segment
		(start 379.961902 -75.88758)
		(end 379.606048 -75.88758)
		(width 0.089408)
		(layer "In4.Cu")
		(net "RST_PLTRST_BUF_N")
	)
	(segment
		(start 379.606048 -75.88758)
		(end 379.23978 -75.521312)
		(width 0.089408)
		(layer "In4.Cu")
		(net "RST_PLTRST_BUF_N")
	)
	(segment
		(start 395.24051 -74.327512)
		(end 395.16431 -74.403712)
		(width 0.089408)
		(layer "In4.Cu")
		(net "RST_PLTRST_BUF_N")
	)
	(segment
		(start 380.452122 -75.39736)
		(end 379.961902 -75.88758)
		(width 0.089408)
		(layer "In4.Cu")
		(net "RST_PLTRST_BUF_N")
	)
	(segment
		(start 400.617436 -72.117712)
		(end 400.556984 -72.178164)
		(width 0.089408)
		(layer "In4.Cu")
		(net "RST_PLTRST_BUF_N")
	)
	(segment
		(start 400.556984 -72.297036)
		(end 399.186654 -73.667366)
		(width 0.089408)
		(layer "In4.Cu")
		(net "RST_PLTRST_BUF_N")
	)
	(segment
		(start 385.973828 -75.59167)
		(end 385.779518 -75.39736)
		(width 0.089408)
		(layer "In4.Cu")
		(net "RST_PLTRST_BUF_N")
	)
	(segment
		(start 394.306806 -74.261472)
		(end 392.824208 -74.261472)
		(width 0.089408)
		(layer "In4.Cu")
		(net "RST_PLTRST_BUF_N")
	)
	(segment
		(start 374.771412 -75.249532)
		(end 374.771412 -74.9935)
		(width 0.089408)
		(layer "In4.Cu")
		(net "RST_PLTRST_BUF_N")
	)
	(segment
		(start 395.16431 -74.403712)
		(end 394.449046 -74.403712)
		(width 0.089408)
		(layer "In4.Cu")
		(net "RST_PLTRST_BUF_N")
	)
	(segment
		(start 370.764054 -74.948034)
		(end 370.764054 -75.475846)
		(width 0.089408)
		(layer "In4.Cu")
		(net "RST_PLTRST_BUF_N")
	)
	(segment
		(start 400.617436 -72.107298)
		(end 400.617436 -72.117712)
		(width 0.089408)
		(layer "In4.Cu")
		(net "RST_PLTRST_BUF_N")
	)
	(segment
		(start 385.779518 -75.39736)
		(end 380.452122 -75.39736)
		(width 0.089408)
		(layer "In4.Cu")
		(net "RST_PLTRST_BUF_N")
	)
	(segment
		(start 397.626332 -74.327512)
		(end 395.24051 -74.327512)
		(width 0.089408)
		(layer "In4.Cu")
		(net "RST_PLTRST_BUF_N")
	)
	(segment
		(start 399.186654 -73.667366)
		(end 398.286478 -73.667366)
		(width 0.089408)
		(layer "In4.Cu")
		(net "RST_PLTRST_BUF_N")
	)
	(segment
		(start 405.450802 -69.903848)
		(end 402.8948 -72.45985)
		(width 0.089408)
		(layer "In9.Cu")
		(net "RST_PLTRST_BUF_N")
	)
	(segment
		(start 401.707858 -72.45985)
		(end 401.593558 -72.34555)
		(width 0.089408)
		(layer "In9.Cu")
		(net "RST_PLTRST_BUF_N")
	)
	(segment
		(start 405.898604 -66.635884)
		(end 405.898604 -66.694558)
		(width 0.089408)
		(layer "In9.Cu")
		(net "RST_PLTRST_BUF_N")
	)
	(segment
		(start 406.342088 -60.68314)
		(end 405.134826 -61.890402)
		(width 0.089408)
		(layer "In9.Cu")
		(net "RST_PLTRST_BUF_N")
	)
	(segment
		(start 405.134826 -62.74181)
		(end 405.378412 -62.985396)
		(width 0.089408)
		(layer "In9.Cu")
		(net "RST_PLTRST_BUF_N")
	)
	(segment
		(start 413.340804 -46.420786)
		(end 412.766764 -46.420786)
		(width 0.089408)
		(layer "In9.Cu")
		(net "RST_PLTRST_BUF_N")
	)
	(segment
		(start 398.405096 -79.47279)
		(end 399.476468 -78.401418)
		(width 0.089408)
		(layer "In9.Cu")
		(net "RST_PLTRST_BUF_N")
	)
	(segment
		(start 405.378412 -62.985396)
		(end 405.808942 -62.985396)
		(width 0.089408)
		(layer "In9.Cu")
		(net "RST_PLTRST_BUF_N")
	)
	(segment
		(start 405.898096 -66.635376)
		(end 405.898604 -66.635884)
		(width 0.089408)
		(layer "In9.Cu")
		(net "RST_PLTRST_BUF_N")
	)
	(segment
		(start 405.898096 -66.095372)
		(end 405.898096 -66.635376)
		(width 0.089408)
		(layer "In9.Cu")
		(net "RST_PLTRST_BUF_N")
	)
	(segment
		(start 401.035012 -72.903842)
		(end 401.593304 -72.34555)
		(width 0.089408)
		(layer "In9.Cu")
		(net "RST_PLTRST_BUF_N")
	)
	(segment
		(start 401.035012 -73.305162)
		(end 401.035012 -72.903842)
		(width 0.089408)
		(layer "In9.Cu")
		(net "RST_PLTRST_BUF_N")
	)
	(segment
		(start 409.51912 -49.276)
		(end 409.51912 -50.106072)
		(width 0.089408)
		(layer "In9.Cu")
		(net "RST_PLTRST_BUF_N")
	)
	(segment
		(start 399.476468 -77.922628)
		(end 400.722592 -76.676504)
		(width 0.089408)
		(layer "In9.Cu")
		(net "RST_PLTRST_BUF_N")
	)
	(segment
		(start 409.51912 -50.106072)
		(end 406.342088 -53.283104)
		(width 0.089408)
		(layer "In9.Cu")
		(net "RST_PLTRST_BUF_N")
	)
	(segment
		(start 400.571716 -74.697082)
		(end 400.571716 -73.768458)
		(width 0.089408)
		(layer "In9.Cu")
		(net "RST_PLTRST_BUF_N")
	)
	(segment
		(start 402.8948 -72.45985)
		(end 401.707858 -72.45985)
		(width 0.089408)
		(layer "In9.Cu")
		(net "RST_PLTRST_BUF_N")
	)
	(segment
		(start 406.342088 -53.283104)
		(end 406.342088 -60.68314)
		(width 0.089408)
		(layer "In9.Cu")
		(net "RST_PLTRST_BUF_N")
	)
	(segment
		(start 405.450802 -67.14236)
		(end 405.450802 -69.903848)
		(width 0.089408)
		(layer "In9.Cu")
		(net "RST_PLTRST_BUF_N")
	)
	(segment
		(start 412.766764 -46.420786)
		(end 412.451042 -46.737016)
		(width 0.089408)
		(layer "In9.Cu")
		(net "RST_PLTRST_BUF_N")
	)
	(segment
		(start 405.134826 -61.890402)
		(end 405.134826 -62.74181)
		(width 0.089408)
		(layer "In9.Cu")
		(net "RST_PLTRST_BUF_N")
	)
	(segment
		(start 411.38983 -47.40529)
		(end 409.51912 -49.276)
		(width 0.089408)
		(layer "In9.Cu")
		(net "RST_PLTRST_BUF_N")
	)
	(segment
		(start 400.722592 -76.676504)
		(end 400.722592 -74.847958)
		(width 0.089408)
		(layer "In9.Cu")
		(net "RST_PLTRST_BUF_N")
	)
	(segment
		(start 405.898604 -66.694558)
		(end 405.450802 -67.14236)
		(width 0.089408)
		(layer "In9.Cu")
		(net "RST_PLTRST_BUF_N")
	)
	(segment
		(start 412.451042 -47.171102)
		(end 412.216854 -47.40529)
		(width 0.089408)
		(layer "In9.Cu")
		(net "RST_PLTRST_BUF_N")
	)
	(segment
		(start 412.216854 -47.40529)
		(end 411.38983 -47.40529)
		(width 0.089408)
		(layer "In9.Cu")
		(net "RST_PLTRST_BUF_N")
	)
	(segment
		(start 405.808942 -62.985396)
		(end 406.126442 -63.302896)
		(width 0.089408)
		(layer "In9.Cu")
		(net "RST_PLTRST_BUF_N")
	)
	(segment
		(start 401.593304 -72.34555)
		(end 401.593558 -72.34555)
		(width 0.089408)
		(layer "In9.Cu")
		(net "RST_PLTRST_BUF_N")
	)
	(segment
		(start 406.541224 -64.466724)
		(end 406.541224 -65.452244)
		(width 0.089408)
		(layer "In9.Cu")
		(net "RST_PLTRST_BUF_N")
	)
	(segment
		(start 399.476468 -78.401418)
		(end 399.476468 -77.922628)
		(width 0.089408)
		(layer "In9.Cu")
		(net "RST_PLTRST_BUF_N")
	)
	(segment
		(start 406.126442 -63.302896)
		(end 406.126442 -64.051942)
		(width 0.089408)
		(layer "In9.Cu")
		(net "RST_PLTRST_BUF_N")
	)
	(segment
		(start 406.541224 -65.452244)
		(end 405.898096 -66.095372)
		(width 0.089408)
		(layer "In9.Cu")
		(net "RST_PLTRST_BUF_N")
	)
	(segment
		(start 400.722592 -74.847958)
		(end 400.571716 -74.697082)
		(width 0.089408)
		(layer "In9.Cu")
		(net "RST_PLTRST_BUF_N")
	)
	(segment
		(start 412.451042 -46.737016)
		(end 412.451042 -47.171102)
		(width 0.089408)
		(layer "In9.Cu")
		(net "RST_PLTRST_BUF_N")
	)
	(segment
		(start 406.126442 -64.051942)
		(end 406.541224 -64.466724)
		(width 0.089408)
		(layer "In9.Cu")
		(net "RST_PLTRST_BUF_N")
	)
	(segment
		(start 400.571716 -73.768458)
		(end 401.035012 -73.305162)
		(width 0.089408)
		(layer "In9.Cu")
		(net "RST_PLTRST_BUF_N")
	)
	(segment
		(start 175.57496 -99.069906)
		(end 175.559466 -99.0854)
		(width 0.10795)
		(layer "F.Cu")
		(net "RST_CPU1_LVC3_N")
	)
	(segment
		(start 175.425862 -99.0854)
		(end 175.231806 -99.279456)
		(width 0.10795)
		(layer "F.Cu")
		(net "RST_CPU1_LVC3_N")
	)
	(segment
		(start 175.282098 -101.421946)
		(end 175.282098 -102.279704)
		(width 0.10795)
		(layer "F.Cu")
		(net "RST_CPU1_LVC3_N")
	)
	(segment
		(start 173.978824 -100.118672)
		(end 175.282098 -101.421946)
		(width 0.10795)
		(layer "F.Cu")
		(net "RST_CPU1_LVC3_N")
	)
	(segment
		(start 173.978824 -99.390454)
		(end 173.978824 -100.118672)
		(width 0.10795)
		(layer "F.Cu")
		(net "RST_CPU1_LVC3_N")
	)
	(segment
		(start 174.089822 -99.279456)
		(end 173.978824 -99.390454)
		(width 0.10795)
		(layer "F.Cu")
		(net "RST_CPU1_LVC3_N")
	)
	(segment
		(start 175.559466 -99.0854)
		(end 175.425862 -99.0854)
		(width 0.10795)
		(layer "F.Cu")
		(net "RST_CPU1_LVC3_N")
	)
	(segment
		(start 175.231806 -99.279456)
		(end 174.089822 -99.279456)
		(width 0.10795)
		(layer "F.Cu")
		(net "RST_CPU1_LVC3_N")
	)
	(via
		(at 354.820982 -54.803802)
		(size 0.508)
		(drill 0.254)
		(layers "F.Cu" "B.Cu")
		(net "RST_CPU1_LVC3_N")
	)
	(via
		(at 175.57496 -99.069906)
		(size 0.508)
		(drill 0.254)
		(layers "F.Cu" "B.Cu")
		(net "RST_CPU1_LVC3_N")
	)
	(segment
		(start 358.843326 -58.147204)
		(end 358.843326 -63.913004)
		(width 0.10795)
		(layer "B.Cu")
		(net "RST_CPU1_LVC3_N")
	)
	(segment
		(start 354.820982 -54.803802)
		(end 354.85832 -54.84114)
		(width 0.10795)
		(layer "B.Cu")
		(net "RST_CPU1_LVC3_N")
	)
	(segment
		(start 357.886254 -54.40045)
		(end 359.248202 -55.762398)
		(width 0.10795)
		(layer "B.Cu")
		(net "RST_CPU1_LVC3_N")
	)
	(segment
		(start 352.667062 -74.473562)
		(end 352.7425 -74.549)
		(width 0.10795)
		(layer "B.Cu")
		(net "RST_CPU1_LVC3_N")
	)
	(segment
		(start 355.408992 -54.84114)
		(end 355.849682 -54.40045)
		(width 0.10795)
		(layer "B.Cu")
		(net "RST_CPU1_LVC3_N")
	)
	(segment
		(start 349.9231 -73.027286)
		(end 351.369376 -74.473562)
		(width 0.10795)
		(layer "B.Cu")
		(net "RST_CPU1_LVC3_N")
	)
	(segment
		(start 354.85832 -54.84114)
		(end 355.408992 -54.84114)
		(width 0.10795)
		(layer "B.Cu")
		(net "RST_CPU1_LVC3_N")
	)
	(segment
		(start 359.248202 -57.742328)
		(end 358.843326 -58.147204)
		(width 0.10795)
		(layer "B.Cu")
		(net "RST_CPU1_LVC3_N")
	)
	(segment
		(start 349.9231 -71.646542)
		(end 349.9231 -73.027286)
		(width 0.10795)
		(layer "B.Cu")
		(net "RST_CPU1_LVC3_N")
	)
	(segment
		(start 354.49637 -68.25996)
		(end 353.309682 -68.25996)
		(width 0.10795)
		(layer "B.Cu")
		(net "RST_CPU1_LVC3_N")
	)
	(segment
		(start 358.843326 -63.913004)
		(end 354.49637 -68.25996)
		(width 0.10795)
		(layer "B.Cu")
		(net "RST_CPU1_LVC3_N")
	)
	(segment
		(start 351.369376 -74.473562)
		(end 352.667062 -74.473562)
		(width 0.10795)
		(layer "B.Cu")
		(net "RST_CPU1_LVC3_N")
	)
	(segment
		(start 353.309682 -68.25996)
		(end 349.9231 -71.646542)
		(width 0.10795)
		(layer "B.Cu")
		(net "RST_CPU1_LVC3_N")
	)
	(segment
		(start 355.849682 -54.40045)
		(end 357.886254 -54.40045)
		(width 0.10795)
		(layer "B.Cu")
		(net "RST_CPU1_LVC3_N")
	)
	(segment
		(start 359.248202 -55.762398)
		(end 359.248202 -57.742328)
		(width 0.10795)
		(layer "B.Cu")
		(net "RST_CPU1_LVC3_N")
	)
	(segment
		(start 317.212472 -48.051974)
		(end 320.883534 -48.051974)
		(width 0.089408)
		(layer "In11.Cu")
		(net "RST_CPU1_LVC3_N")
	)
	(segment
		(start 175.495712 -92.449904)
		(end 174.421546 -91.375738)
		(width 0.089408)
		(layer "In11.Cu")
		(net "RST_CPU1_LVC3_N")
	)
	(segment
		(start 326.407018 -53.575458)
		(end 338.893658 -53.575458)
		(width 0.089408)
		(layer "In11.Cu")
		(net "RST_CPU1_LVC3_N")
	)
	(segment
		(start 158.470854 -66.8401)
		(end 161.16935 -64.141604)
		(width 0.089408)
		(layer "In11.Cu")
		(net "RST_CPU1_LVC3_N")
	)
	(segment
		(start 320.245994 -31.750762)
		(end 317.486792 -34.509964)
		(width 0.089408)
		(layer "In11.Cu")
		(net "RST_CPU1_LVC3_N")
	)
	(segment
		(start 350.92005 -53.31587)
		(end 353.951286 -53.31587)
		(width 0.089408)
		(layer "In11.Cu")
		(net "RST_CPU1_LVC3_N")
	)
	(segment
		(start 320.933064 -2.70383)
		(end 320.08699 -3.549904)
		(width 0.089408)
		(layer "In11.Cu")
		(net "RST_CPU1_LVC3_N")
	)
	(segment
		(start 190.481966 -20.574)
		(end 195.1355 -15.920466)
		(width 0.089408)
		(layer "In11.Cu")
		(net "RST_CPU1_LVC3_N")
	)
	(segment
		(start 314.512198 -38.143942)
		(end 313.41314 -38.143942)
		(width 0.089408)
		(layer "In11.Cu")
		(net "RST_CPU1_LVC3_N")
	)
	(segment
		(start 164.444172 -89.393268)
		(end 164.444172 -89.234772)
		(width 0.089408)
		(layer "In11.Cu")
		(net "RST_CPU1_LVC3_N")
	)
	(segment
		(start 195.1355 2.666746)
		(end 195.674742 3.205988)
		(width 0.089408)
		(layer "In11.Cu")
		(net "RST_CPU1_LVC3_N")
	)
	(segment
		(start 309.28564 -46.616112)
		(end 311.441084 -48.771556)
		(width 0.089408)
		(layer "In11.Cu")
		(net "RST_CPU1_LVC3_N")
	)
	(segment
		(start 161.16935 -63.142876)
		(end 161.31159 -63.000636)
		(width 0.089408)
		(layer "In11.Cu")
		(net "RST_CPU1_LVC3_N")
	)
	(segment
		(start 311.441084 -48.771556)
		(end 316.49289 -48.771556)
		(width 0.089408)
		(layer "In11.Cu")
		(net "RST_CPU1_LVC3_N")
	)
	(segment
		(start 320.245994 -30.642052)
		(end 320.245994 -31.750762)
		(width 0.089408)
		(layer "In11.Cu")
		(net "RST_CPU1_LVC3_N")
	)
	(segment
		(start 161.31159 -63.000636)
		(end 161.31159 -54.232556)
		(width 0.089408)
		(layer "In11.Cu")
		(net "RST_CPU1_LVC3_N")
	)
	(segment
		(start 175.495712 -98.990658)
		(end 175.495712 -92.449904)
		(width 0.089408)
		(layer "In11.Cu")
		(net "RST_CPU1_LVC3_N")
	)
	(segment
		(start 338.893658 -53.575458)
		(end 340.348824 -55.030624)
		(width 0.089408)
		(layer "In11.Cu")
		(net "RST_CPU1_LVC3_N")
	)
	(segment
		(start 161.16935 -64.141604)
		(end 161.16935 -63.142876)
		(width 0.089408)
		(layer "In11.Cu")
		(net "RST_CPU1_LVC3_N")
	)
	(segment
		(start 184.675272 -21.860002)
		(end 185.961274 -20.574)
		(width 0.089408)
		(layer "In11.Cu")
		(net "RST_CPU1_LVC3_N")
	)
	(segment
		(start 317.486792 -34.509964)
		(end 317.045086 -34.509964)
		(width 0.089408)
		(layer "In11.Cu")
		(net "RST_CPU1_LVC3_N")
	)
	(segment
		(start 320.933064 2.64795)
		(end 320.933064 -2.70383)
		(width 0.089408)
		(layer "In11.Cu")
		(net "RST_CPU1_LVC3_N")
	)
	(segment
		(start 161.31159 -54.232556)
		(end 184.675272 -30.868874)
		(width 0.089408)
		(layer "In11.Cu")
		(net "RST_CPU1_LVC3_N")
	)
	(segment
		(start 185.961274 -20.574)
		(end 190.481966 -20.574)
		(width 0.089408)
		(layer "In11.Cu")
		(net "RST_CPU1_LVC3_N")
	)
	(segment
		(start 321.596004 -29.292042)
		(end 320.245994 -30.642052)
		(width 0.089408)
		(layer "In11.Cu")
		(net "RST_CPU1_LVC3_N")
	)
	(segment
		(start 173.837346 -89.7128)
		(end 164.763704 -89.7128)
		(width 0.089408)
		(layer "In11.Cu")
		(net "RST_CPU1_LVC3_N")
	)
	(segment
		(start 316.49289 -48.771556)
		(end 317.212472 -48.051974)
		(width 0.089408)
		(layer "In11.Cu")
		(net "RST_CPU1_LVC3_N")
	)
	(segment
		(start 175.57496 -99.069906)
		(end 175.495712 -98.990658)
		(width 0.089408)
		(layer "In11.Cu")
		(net "RST_CPU1_LVC3_N")
	)
	(segment
		(start 195.1355 -15.920466)
		(end 195.1355 2.666746)
		(width 0.089408)
		(layer "In11.Cu")
		(net "RST_CPU1_LVC3_N")
	)
	(segment
		(start 315.443108 -37.213032)
		(end 314.512198 -38.143942)
		(width 0.089408)
		(layer "In11.Cu")
		(net "RST_CPU1_LVC3_N")
	)
	(segment
		(start 158.470854 -83.261454)
		(end 158.470854 -66.8401)
		(width 0.089408)
		(layer "In11.Cu")
		(net "RST_CPU1_LVC3_N")
	)
	(segment
		(start 164.444172 -89.234772)
		(end 158.470854 -83.261454)
		(width 0.089408)
		(layer "In11.Cu")
		(net "RST_CPU1_LVC3_N")
	)
	(segment
		(start 354.820982 -54.185566)
		(end 354.820982 -54.803802)
		(width 0.089408)
		(layer "In11.Cu")
		(net "RST_CPU1_LVC3_N")
	)
	(segment
		(start 340.348824 -55.030624)
		(end 349.205296 -55.030624)
		(width 0.089408)
		(layer "In11.Cu")
		(net "RST_CPU1_LVC3_N")
	)
	(segment
		(start 315.443108 -36.111942)
		(end 315.443108 -37.213032)
		(width 0.089408)
		(layer "In11.Cu")
		(net "RST_CPU1_LVC3_N")
	)
	(segment
		(start 174.421546 -91.375738)
		(end 174.421546 -90.297)
		(width 0.089408)
		(layer "In11.Cu")
		(net "RST_CPU1_LVC3_N")
	)
	(segment
		(start 164.763704 -89.7128)
		(end 164.444172 -89.393268)
		(width 0.089408)
		(layer "In11.Cu")
		(net "RST_CPU1_LVC3_N")
	)
	(segment
		(start 309.28564 -42.271442)
		(end 309.28564 -46.616112)
		(width 0.089408)
		(layer "In11.Cu")
		(net "RST_CPU1_LVC3_N")
	)
	(segment
		(start 320.08699 -14.66977)
		(end 320.933064 -15.515844)
		(width 0.089408)
		(layer "In11.Cu")
		(net "RST_CPU1_LVC3_N")
	)
	(segment
		(start 349.205296 -55.030624)
		(end 350.92005 -53.31587)
		(width 0.089408)
		(layer "In11.Cu")
		(net "RST_CPU1_LVC3_N")
	)
	(segment
		(start 317.045086 -34.509964)
		(end 315.443108 -36.111942)
		(width 0.089408)
		(layer "In11.Cu")
		(net "RST_CPU1_LVC3_N")
	)
	(segment
		(start 353.951286 -53.31587)
		(end 354.820982 -54.185566)
		(width 0.089408)
		(layer "In11.Cu")
		(net "RST_CPU1_LVC3_N")
	)
	(segment
		(start 174.421546 -90.297)
		(end 173.837346 -89.7128)
		(width 0.089408)
		(layer "In11.Cu")
		(net "RST_CPU1_LVC3_N")
	)
	(segment
		(start 320.375026 3.205988)
		(end 320.933064 2.64795)
		(width 0.089408)
		(layer "In11.Cu")
		(net "RST_CPU1_LVC3_N")
	)
	(segment
		(start 320.933064 -27.225752)
		(end 321.596004 -27.888692)
		(width 0.089408)
		(layer "In11.Cu")
		(net "RST_CPU1_LVC3_N")
	)
	(segment
		(start 320.08699 -3.549904)
		(end 320.08699 -14.66977)
		(width 0.089408)
		(layer "In11.Cu")
		(net "RST_CPU1_LVC3_N")
	)
	(segment
		(start 184.675272 -30.868874)
		(end 184.675272 -21.860002)
		(width 0.089408)
		(layer "In11.Cu")
		(net "RST_CPU1_LVC3_N")
	)
	(segment
		(start 320.883534 -48.051974)
		(end 326.407018 -53.575458)
		(width 0.089408)
		(layer "In11.Cu")
		(net "RST_CPU1_LVC3_N")
	)
	(segment
		(start 195.674742 3.205988)
		(end 320.375026 3.205988)
		(width 0.089408)
		(layer "In11.Cu")
		(net "RST_CPU1_LVC3_N")
	)
	(segment
		(start 321.596004 -27.888692)
		(end 321.596004 -29.292042)
		(width 0.089408)
		(layer "In11.Cu")
		(net "RST_CPU1_LVC3_N")
	)
	(segment
		(start 313.41314 -38.143942)
		(end 309.28564 -42.271442)
		(width 0.089408)
		(layer "In11.Cu")
		(net "RST_CPU1_LVC3_N")
	)
	(segment
		(start 320.933064 -15.515844)
		(end 320.933064 -27.225752)
		(width 0.089408)
		(layer "In11.Cu")
		(net "RST_CPU1_LVC3_N")
	)
	(segment
		(start 162.2298 -71.7804)
		(end 162.2298 -70.2564)
		(width 0.10795)
		(layer "F.Cu")
		(net "RST_CPU1_G_N")
	)
	(segment
		(start 125.080268 -67.791584)
		(end 125.651768 -67.791584)
		(width 0.1016)
		(layer "F.Cu")
		(net "RST_CPU1_G_N")
	)
	(segment
		(start 175.282098 -96.310704)
		(end 175.282098 -97.692972)
		(width 0.10795)
		(layer "F.Cu")
		(net "RST_CPU1_G_N")
	)
	(segment
		(start 160.3375 -73.305416)
		(end 161.506916 -72.136)
		(width 0.10795)
		(layer "F.Cu")
		(net "RST_CPU1_G_N")
	)
	(segment
		(start 174.781464 -98.193606)
		(end 172.797216 -98.193606)
		(width 0.10795)
		(layer "F.Cu")
		(net "RST_CPU1_G_N")
	)
	(segment
		(start 162.38728 -70.09892)
		(end 162.38728 -69.7357)
		(width 0.10795)
		(layer "F.Cu")
		(net "RST_CPU1_G_N")
	)
	(segment
		(start 172.797216 -98.193606)
		(end 172.598842 -97.995232)
		(width 0.10795)
		(layer "F.Cu")
		(net "RST_CPU1_G_N")
	)
	(segment
		(start 162.2298 -70.2564)
		(end 162.38728 -70.09892)
		(width 0.10795)
		(layer "F.Cu")
		(net "RST_CPU1_G_N")
	)
	(segment
		(start 161.8742 -72.136)
		(end 162.2298 -71.7804)
		(width 0.10795)
		(layer "F.Cu")
		(net "RST_CPU1_G_N")
	)
	(segment
		(start 161.506916 -72.136)
		(end 161.8742 -72.136)
		(width 0.10795)
		(layer "F.Cu")
		(net "RST_CPU1_G_N")
	)
	(segment
		(start 175.282098 -97.692972)
		(end 174.781464 -98.193606)
		(width 0.10795)
		(layer "F.Cu")
		(net "RST_CPU1_G_N")
	)
	(segment
		(start 160.3375 -73.5711)
		(end 160.3375 -73.305416)
		(width 0.10795)
		(layer "F.Cu")
		(net "RST_CPU1_G_N")
	)
	(via
		(at 160.3375 -73.5711)
		(size 0.508)
		(drill 0.254)
		(layers "F.Cu" "B.Cu")
		(net "RST_CPU1_G_N")
	)
	(via
		(at 125.651768 -67.791584)
		(size 0.508)
		(drill 0.254)
		(layers "F.Cu" "B.Cu")
		(net "RST_CPU1_G_N")
	)
	(via
		(at 172.598842 -97.995232)
		(size 0.508)
		(drill 0.254)
		(layers "F.Cu" "B.Cu")
		(net "RST_CPU1_G_N")
	)
	(segment
		(start 161.67227 -74.435208)
		(end 162.870388 -74.435208)
		(width 0.089408)
		(layer "In4.Cu")
		(net "RST_CPU1_G_N")
	)
	(segment
		(start 136.79424 -69.677534)
		(end 136.830308 -69.677534)
		(width 0.0889)
		(layer "In4.Cu")
		(net "RST_CPU1_G_N")
	)
	(segment
		(start 164.33292 -74.876406)
		(end 164.719254 -75.26274)
		(width 0.089408)
		(layer "In4.Cu")
		(net "RST_CPU1_G_N")
	)
	(segment
		(start 127.351028 -69.182234)
		(end 127.386588 -69.182234)
		(width 0.0889)
		(layer "In4.Cu")
		(net "RST_CPU1_G_N")
	)
	(segment
		(start 130.785108 -69.182234)
		(end 130.820668 -69.182234)
		(width 0.0889)
		(layer "In4.Cu")
		(net "RST_CPU1_G_N")
	)
	(segment
		(start 140.22832 -69.677534)
		(end 140.264388 -69.677534)
		(width 0.0889)
		(layer "In4.Cu")
		(net "RST_CPU1_G_N")
	)
	(segment
		(start 141.867636 -69.7484)
		(end 142.4686 -69.7484)
		(width 0.0889)
		(layer "In4.Cu")
		(net "RST_CPU1_G_N")
	)
	(segment
		(start 141.087094 -69.182234)
		(end 141.122654 -69.182234)
		(width 0.0889)
		(layer "In4.Cu")
		(net "RST_CPU1_G_N")
	)
	(segment
		(start 137.653014 -69.182234)
		(end 137.688574 -69.182234)
		(width 0.0889)
		(layer "In4.Cu")
		(net "RST_CPU1_G_N")
	)
	(segment
		(start 172.882052 -97.712022)
		(end 172.598842 -97.995232)
		(width 0.089408)
		(layer "In4.Cu")
		(net "RST_CPU1_G_N")
	)
	(segment
		(start 171.48556 -92.28836)
		(end 171.48556 -94.01556)
		(width 0.089408)
		(layer "In4.Cu")
		(net "RST_CPU1_G_N")
	)
	(segment
		(start 142.4686 -69.7484)
		(end 142.858998 -69.358002)
		(width 0.089408)
		(layer "In4.Cu")
		(net "RST_CPU1_G_N")
	)
	(segment
		(start 132.501894 -69.182234)
		(end 132.537454 -69.182234)
		(width 0.0889)
		(layer "In4.Cu")
		(net "RST_CPU1_G_N")
	)
	(segment
		(start 159.224726 -73.720452)
		(end 160.188148 -73.720452)
		(width 0.089408)
		(layer "In4.Cu")
		(net "RST_CPU1_G_N")
	)
	(segment
		(start 169.4688 -90.2716)
		(end 171.48556 -92.28836)
		(width 0.089408)
		(layer "In4.Cu")
		(net "RST_CPU1_G_N")
	)
	(segment
		(start 168.922446 -87.634826)
		(end 169.4688 -88.18118)
		(width 0.089408)
		(layer "In4.Cu")
		(net "RST_CPU1_G_N")
	)
	(segment
		(start 131.643374 -69.677534)
		(end 131.6736 -69.677534)
		(width 0.0889)
		(layer "In4.Cu")
		(net "RST_CPU1_G_N")
	)
	(segment
		(start 160.188148 -73.720452)
		(end 160.3375 -73.5711)
		(width 0.089408)
		(layer "In4.Cu")
		(net "RST_CPU1_G_N")
	)
	(segment
		(start 126.163578 -68.487036)
		(end 126.169928 -68.497704)
		(width 0.0889)
		(layer "In4.Cu")
		(net "RST_CPU1_G_N")
	)
	(segment
		(start 172.882052 -95.412052)
		(end 172.882052 -97.712022)
		(width 0.089408)
		(layer "In4.Cu")
		(net "RST_CPU1_G_N")
	)
	(segment
		(start 164.719254 -84.18703)
		(end 168.16705 -87.634826)
		(width 0.089408)
		(layer "In4.Cu")
		(net "RST_CPU1_G_N")
	)
	(segment
		(start 138.51128 -69.677534)
		(end 138.547348 -69.677534)
		(width 0.0889)
		(layer "In4.Cu")
		(net "RST_CPU1_G_N")
	)
	(segment
		(start 164.719254 -75.26274)
		(end 164.719254 -84.18703)
		(width 0.089408)
		(layer "In4.Cu")
		(net "RST_CPU1_G_N")
	)
	(segment
		(start 141.680184 -69.560948)
		(end 141.867636 -69.7484)
		(width 0.0889)
		(layer "In4.Cu")
		(net "RST_CPU1_G_N")
	)
	(segment
		(start 139.370054 -69.182234)
		(end 139.405614 -69.182234)
		(width 0.0889)
		(layer "In4.Cu")
		(net "RST_CPU1_G_N")
	)
	(segment
		(start 161.14903 -73.911968)
		(end 161.67227 -74.435208)
		(width 0.089408)
		(layer "In4.Cu")
		(net "RST_CPU1_G_N")
	)
	(segment
		(start 162.870388 -74.435208)
		(end 163.311586 -74.876406)
		(width 0.089408)
		(layer "In4.Cu")
		(net "RST_CPU1_G_N")
	)
	(segment
		(start 154.862276 -69.358002)
		(end 159.224726 -73.720452)
		(width 0.089408)
		(layer "In4.Cu")
		(net "RST_CPU1_G_N")
	)
	(segment
		(start 160.3375 -73.5711)
		(end 160.678368 -73.911968)
		(width 0.089408)
		(layer "In4.Cu")
		(net "RST_CPU1_G_N")
	)
	(segment
		(start 169.4688 -88.18118)
		(end 169.4688 -90.2716)
		(width 0.089408)
		(layer "In4.Cu")
		(net "RST_CPU1_G_N")
	)
	(segment
		(start 129.068068 -69.182234)
		(end 129.103628 -69.182234)
		(width 0.0889)
		(layer "In4.Cu")
		(net "RST_CPU1_G_N")
	)
	(segment
		(start 133.36016 -69.677534)
		(end 133.396228 -69.677534)
		(width 0.0889)
		(layer "In4.Cu")
		(net "RST_CPU1_G_N")
	)
	(segment
		(start 135.935974 -69.182234)
		(end 135.971534 -69.182234)
		(width 0.0889)
		(layer "In4.Cu")
		(net "RST_CPU1_G_N")
	)
	(segment
		(start 142.858998 -69.358002)
		(end 154.862276 -69.358002)
		(width 0.089408)
		(layer "In4.Cu")
		(net "RST_CPU1_G_N")
	)
	(segment
		(start 125.651768 -67.791584)
		(end 126.163578 -68.487036)
		(width 0.0889)
		(layer "In4.Cu")
		(net "RST_CPU1_G_N")
	)
	(segment
		(start 163.311586 -74.876406)
		(end 164.33292 -74.876406)
		(width 0.089408)
		(layer "In4.Cu")
		(net "RST_CPU1_G_N")
	)
	(segment
		(start 168.16705 -87.634826)
		(end 168.922446 -87.634826)
		(width 0.089408)
		(layer "In4.Cu")
		(net "RST_CPU1_G_N")
	)
	(segment
		(start 134.218934 -69.182234)
		(end 134.254494 -69.182234)
		(width 0.0889)
		(layer "In4.Cu")
		(net "RST_CPU1_G_N")
	)
	(segment
		(start 171.48556 -94.01556)
		(end 172.882052 -95.412052)
		(width 0.089408)
		(layer "In4.Cu")
		(net "RST_CPU1_G_N")
	)
	(segment
		(start 160.678368 -73.911968)
		(end 161.14903 -73.911968)
		(width 0.089408)
		(layer "In4.Cu")
		(net "RST_CPU1_G_N")
	)
	(arc
		(start 141.122654 -69.182234)
		(mid 141.408078 -69.265701)
		(end 141.616684 -69.477636)
		(width 0.0889)
		(layer "In4.Cu")
		(net "RST_CPU1_G_N")
	)
	(arc
		(start 135.441944 -69.477636)
		(mid 135.650552 -69.265704)
		(end 135.935974 -69.182234)
		(width 0.0889)
		(layer "In4.Cu")
		(net "RST_CPU1_G_N")
	)
	(arc
		(start 131.314698 -69.477636)
		(mid 131.453442 -69.619669)
		(end 131.643374 -69.677534)
		(width 0.0889)
		(layer "In4.Cu")
		(net "RST_CPU1_G_N")
	)
	(arc
		(start 126.169928 -68.497704)
		(mid 126.242726 -68.788467)
		(end 126.163578 -69.077586)
		(width 0.0889)
		(layer "In4.Cu")
		(net "RST_CPU1_G_N")
	)
	(arc
		(start 140.264388 -69.677534)
		(mid 140.454317 -69.619664)
		(end 140.593064 -69.477636)
		(width 0.0889)
		(layer "In4.Cu")
		(net "RST_CPU1_G_N")
	)
	(arc
		(start 130.291078 -69.477636)
		(mid 130.499686 -69.265704)
		(end 130.785108 -69.182234)
		(width 0.0889)
		(layer "In4.Cu")
		(net "RST_CPU1_G_N")
	)
	(arc
		(start 137.158984 -69.477636)
		(mid 137.367592 -69.265704)
		(end 137.653014 -69.182234)
		(width 0.0889)
		(layer "In4.Cu")
		(net "RST_CPU1_G_N")
	)
	(arc
		(start 136.830308 -69.677534)
		(mid 137.020237 -69.619664)
		(end 137.158984 -69.477636)
		(width 0.0889)
		(layer "In4.Cu")
		(net "RST_CPU1_G_N")
	)
	(arc
		(start 134.748524 -69.477636)
		(mid 135.095234 -69.677947)
		(end 135.441944 -69.477636)
		(width 0.0889)
		(layer "In4.Cu")
		(net "RST_CPU1_G_N")
	)
	(arc
		(start 127.880618 -69.477636)
		(mid 128.227328 -69.677947)
		(end 128.574038 -69.477636)
		(width 0.0889)
		(layer "In4.Cu")
		(net "RST_CPU1_G_N")
	)
	(arc
		(start 138.182604 -69.477636)
		(mid 138.321348 -69.619669)
		(end 138.51128 -69.677534)
		(width 0.0889)
		(layer "In4.Cu")
		(net "RST_CPU1_G_N")
	)
	(arc
		(start 126.163578 -69.077586)
		(mid 126.310231 -69.624503)
		(end 126.856998 -69.477636)
		(width 0.0889)
		(layer "In4.Cu")
		(net "RST_CPU1_G_N")
	)
	(arc
		(start 132.537454 -69.182234)
		(mid 132.822878 -69.265701)
		(end 133.031484 -69.477636)
		(width 0.0889)
		(layer "In4.Cu")
		(net "RST_CPU1_G_N")
	)
	(arc
		(start 134.254494 -69.182234)
		(mid 134.539918 -69.265701)
		(end 134.748524 -69.477636)
		(width 0.0889)
		(layer "In4.Cu")
		(net "RST_CPU1_G_N")
	)
	(arc
		(start 138.547348 -69.677534)
		(mid 138.737277 -69.619664)
		(end 138.876024 -69.477636)
		(width 0.0889)
		(layer "In4.Cu")
		(net "RST_CPU1_G_N")
	)
	(arc
		(start 137.688574 -69.182234)
		(mid 137.973998 -69.265701)
		(end 138.182604 -69.477636)
		(width 0.0889)
		(layer "In4.Cu")
		(net "RST_CPU1_G_N")
	)
	(arc
		(start 133.396228 -69.677534)
		(mid 133.586157 -69.619664)
		(end 133.724904 -69.477636)
		(width 0.0889)
		(layer "In4.Cu")
		(net "RST_CPU1_G_N")
	)
	(arc
		(start 126.856998 -69.477636)
		(mid 127.065606 -69.265704)
		(end 127.351028 -69.182234)
		(width 0.0889)
		(layer "In4.Cu")
		(net "RST_CPU1_G_N")
	)
	(arc
		(start 141.616684 -69.477636)
		(mid 141.645689 -69.521385)
		(end 141.680184 -69.560948)
		(width 0.0889)
		(layer "In4.Cu")
		(net "RST_CPU1_G_N")
	)
	(arc
		(start 130.820668 -69.182234)
		(mid 131.106092 -69.265701)
		(end 131.314698 -69.477636)
		(width 0.0889)
		(layer "In4.Cu")
		(net "RST_CPU1_G_N")
	)
	(arc
		(start 127.386588 -69.182234)
		(mid 127.672012 -69.265701)
		(end 127.880618 -69.477636)
		(width 0.0889)
		(layer "In4.Cu")
		(net "RST_CPU1_G_N")
	)
	(arc
		(start 128.574038 -69.477636)
		(mid 128.782646 -69.265704)
		(end 129.068068 -69.182234)
		(width 0.0889)
		(layer "In4.Cu")
		(net "RST_CPU1_G_N")
	)
	(arc
		(start 139.899644 -69.477636)
		(mid 140.038388 -69.619669)
		(end 140.22832 -69.677534)
		(width 0.0889)
		(layer "In4.Cu")
		(net "RST_CPU1_G_N")
	)
	(arc
		(start 131.6736 -69.677534)
		(mid 131.866703 -69.621015)
		(end 132.007864 -69.477636)
		(width 0.0889)
		(layer "In4.Cu")
		(net "RST_CPU1_G_N")
	)
	(arc
		(start 135.971534 -69.182234)
		(mid 136.256958 -69.265701)
		(end 136.465564 -69.477636)
		(width 0.0889)
		(layer "In4.Cu")
		(net "RST_CPU1_G_N")
	)
	(arc
		(start 139.405614 -69.182234)
		(mid 139.691038 -69.265701)
		(end 139.899644 -69.477636)
		(width 0.0889)
		(layer "In4.Cu")
		(net "RST_CPU1_G_N")
	)
	(arc
		(start 132.007864 -69.477636)
		(mid 132.216472 -69.265704)
		(end 132.501894 -69.182234)
		(width 0.0889)
		(layer "In4.Cu")
		(net "RST_CPU1_G_N")
	)
	(arc
		(start 133.724904 -69.477636)
		(mid 133.933512 -69.265704)
		(end 134.218934 -69.182234)
		(width 0.0889)
		(layer "In4.Cu")
		(net "RST_CPU1_G_N")
	)
	(arc
		(start 140.593064 -69.477636)
		(mid 140.801672 -69.265704)
		(end 141.087094 -69.182234)
		(width 0.0889)
		(layer "In4.Cu")
		(net "RST_CPU1_G_N")
	)
	(arc
		(start 129.103628 -69.182234)
		(mid 129.389052 -69.265701)
		(end 129.597658 -69.477636)
		(width 0.0889)
		(layer "In4.Cu")
		(net "RST_CPU1_G_N")
	)
	(arc
		(start 136.465564 -69.477636)
		(mid 136.604308 -69.619669)
		(end 136.79424 -69.677534)
		(width 0.0889)
		(layer "In4.Cu")
		(net "RST_CPU1_G_N")
	)
	(arc
		(start 133.031484 -69.477636)
		(mid 133.170228 -69.619669)
		(end 133.36016 -69.677534)
		(width 0.0889)
		(layer "In4.Cu")
		(net "RST_CPU1_G_N")
	)
	(arc
		(start 138.876024 -69.477636)
		(mid 139.084632 -69.265704)
		(end 139.370054 -69.182234)
		(width 0.0889)
		(layer "In4.Cu")
		(net "RST_CPU1_G_N")
	)
	(arc
		(start 129.597658 -69.477636)
		(mid 129.944368 -69.677947)
		(end 130.291078 -69.477636)
		(width 0.0889)
		(layer "In4.Cu")
		(net "RST_CPU1_G_N")
	)
	(via
		(at 360.162602 -52.39512)
		(size 0.6604)
		(drill 0.3302)
		(layers "F.Cu" "B.Cu")
		(net "RST_CPU0_LVC3_N")
	)
	(segment
		(start 354.047298 -70.060312)
		(end 359.757726 -64.349884)
		(width 0.10795)
		(layer "B.Cu")
		(net "RST_CPU0_LVC3_N")
	)
	(segment
		(start 359.791 -50.51806)
		(end 359.791 -51.466496)
		(width 0.10795)
		(layer "B.Cu")
		(net "RST_CPU0_LVC3_N")
	)
	(segment
		(start 360.998262 -50.876454)
		(end 360.474006 -50.352198)
		(width 0.10795)
		(layer "B.Cu")
		(net "RST_CPU0_LVC3_N")
	)
	(segment
		(start 365.44631 -52.392326)
		(end 365.44631 -51.141884)
		(width 0.10795)
		(layer "B.Cu")
		(net "RST_CPU0_LVC3_N")
	)
	(segment
		(start 365.44631 -51.141884)
		(end 365.18088 -50.876454)
		(width 0.10795)
		(layer "B.Cu")
		(net "RST_CPU0_LVC3_N")
	)
	(segment
		(start 354.047298 -72.320658)
		(end 354.047298 -70.060312)
		(width 0.10795)
		(layer "B.Cu")
		(net "RST_CPU0_LVC3_N")
	)
	(segment
		(start 359.791 -51.466496)
		(end 360.162602 -51.838098)
		(width 0.10795)
		(layer "B.Cu")
		(net "RST_CPU0_LVC3_N")
	)
	(segment
		(start 360.162602 -51.838098)
		(end 360.162602 -52.39512)
		(width 0.10795)
		(layer "B.Cu")
		(net "RST_CPU0_LVC3_N")
	)
	(segment
		(start 354.760784 -73.034144)
		(end 354.047298 -72.320658)
		(width 0.10795)
		(layer "B.Cu")
		(net "RST_CPU0_LVC3_N")
	)
	(segment
		(start 364.4138 -80.0354)
		(end 364.191804 -79.813404)
		(width 0.10795)
		(layer "B.Cu")
		(net "RST_CPU0_LVC3_N")
	)
	(segment
		(start 359.757726 -64.349884)
		(end 359.757726 -58.52668)
		(width 0.10795)
		(layer "B.Cu")
		(net "RST_CPU0_LVC3_N")
	)
	(segment
		(start 361.84586 -73.034144)
		(end 354.760784 -73.034144)
		(width 0.10795)
		(layer "B.Cu")
		(net "RST_CPU0_LVC3_N")
	)
	(segment
		(start 365.275876 -52.56276)
		(end 365.44631 -52.392326)
		(width 0.10795)
		(layer "B.Cu")
		(net "RST_CPU0_LVC3_N")
	)
	(segment
		(start 365.18088 -50.876454)
		(end 360.998262 -50.876454)
		(width 0.10795)
		(layer "B.Cu")
		(net "RST_CPU0_LVC3_N")
	)
	(segment
		(start 364.191804 -79.813404)
		(end 364.191804 -75.380088)
		(width 0.10795)
		(layer "B.Cu")
		(net "RST_CPU0_LVC3_N")
	)
	(segment
		(start 359.757726 -58.52668)
		(end 360.162602 -58.121804)
		(width 0.10795)
		(layer "B.Cu")
		(net "RST_CPU0_LVC3_N")
	)
	(segment
		(start 360.474006 -50.352198)
		(end 359.956862 -50.352198)
		(width 0.10795)
		(layer "B.Cu")
		(net "RST_CPU0_LVC3_N")
	)
	(segment
		(start 363.9185 -52.56276)
		(end 365.275876 -52.56276)
		(width 0.10795)
		(layer "B.Cu")
		(net "RST_CPU0_LVC3_N")
	)
	(segment
		(start 364.191804 -75.380088)
		(end 361.84586 -73.034144)
		(width 0.10795)
		(layer "B.Cu")
		(net "RST_CPU0_LVC3_N")
	)
	(segment
		(start 360.162602 -58.121804)
		(end 360.162602 -52.39512)
		(width 0.10795)
		(layer "B.Cu")
		(net "RST_CPU0_LVC3_N")
	)
	(segment
		(start 359.956862 -50.352198)
		(end 359.791 -50.51806)
		(width 0.10795)
		(layer "B.Cu")
		(net "RST_CPU0_LVC3_N")
	)
	(segment
		(start 280.71445 -70.438518)
		(end 281.332178 -70.438518)
		(width 0.10795)
		(layer "F.Cu")
		(net "RST_CPU0_G_N")
	)
	(segment
		(start 281.332178 -70.438518)
		(end 281.46375 -70.306946)
		(width 0.10795)
		(layer "F.Cu")
		(net "RST_CPU0_G_N")
	)
	(segment
		(start 290.0807 -67.791584)
		(end 290.6522 -67.791584)
		(width 0.1016)
		(layer "F.Cu")
		(net "RST_CPU0_G_N")
	)
	(via
		(at 357.4288 -68.4784)
		(size 0.6604)
		(drill 0.3302)
		(layers "F.Cu" "B.Cu")
		(net "RST_CPU0_G_N")
	)
	(via
		(at 281.46375 -70.306946)
		(size 0.508)
		(drill 0.254)
		(layers "F.Cu" "B.Cu")
		(net "RST_CPU0_G_N")
	)
	(via
		(at 290.6522 -67.791584)
		(size 0.508)
		(drill 0.254)
		(layers "F.Cu" "B.Cu")
		(net "RST_CPU0_G_N")
	)
	(via
		(at 355.180138 -72.141842)
		(size 0.508)
		(drill 0.254)
		(layers "F.Cu" "B.Cu")
		(net "RST_CPU0_G_N")
	)
	(segment
		(start 368.703606 -52.56276)
		(end 365.280194 -55.986172)
		(width 0.10795)
		(layer "B.Cu")
		(net "RST_CPU0_G_N")
	)
	(segment
		(start 355.808534 -70.378066)
		(end 357.4288 -68.7578)
		(width 0.10795)
		(layer "B.Cu")
		(net "RST_CPU0_G_N")
	)
	(segment
		(start 357.4288 -68.083938)
		(end 357.4288 -68.4784)
		(width 0.10795)
		(layer "B.Cu")
		(net "RST_CPU0_G_N")
	)
	(segment
		(start 360.717592 -64.795146)
		(end 357.4288 -68.083938)
		(width 0.10795)
		(layer "B.Cu")
		(net "RST_CPU0_G_N")
	)
	(segment
		(start 361.102402 -58.511948)
		(end 360.717592 -58.896758)
		(width 0.10795)
		(layer "B.Cu")
		(net "RST_CPU0_G_N")
	)
	(segment
		(start 355.304598 -72.141842)
		(end 355.808534 -71.637906)
		(width 0.10795)
		(layer "B.Cu")
		(net "RST_CPU0_G_N")
	)
	(segment
		(start 369.8875 -52.56276)
		(end 368.703606 -52.56276)
		(width 0.10795)
		(layer "B.Cu")
		(net "RST_CPU0_G_N")
	)
	(segment
		(start 365.280194 -55.986172)
		(end 362.776516 -55.986172)
		(width 0.10795)
		(layer "B.Cu")
		(net "RST_CPU0_G_N")
	)
	(segment
		(start 355.180138 -72.141842)
		(end 355.304598 -72.141842)
		(width 0.10795)
		(layer "B.Cu")
		(net "RST_CPU0_G_N")
	)
	(segment
		(start 355.808534 -71.637906)
		(end 355.808534 -70.378066)
		(width 0.10795)
		(layer "B.Cu")
		(net "RST_CPU0_G_N")
	)
	(segment
		(start 362.776516 -55.986172)
		(end 361.102402 -57.660286)
		(width 0.10795)
		(layer "B.Cu")
		(net "RST_CPU0_G_N")
	)
	(segment
		(start 361.102402 -57.660286)
		(end 361.102402 -58.511948)
		(width 0.10795)
		(layer "B.Cu")
		(net "RST_CPU0_G_N")
	)
	(segment
		(start 360.717592 -58.896758)
		(end 360.717592 -64.795146)
		(width 0.10795)
		(layer "B.Cu")
		(net "RST_CPU0_G_N")
	)
	(segment
		(start 357.4288 -68.7578)
		(end 357.4288 -68.4784)
		(width 0.10795)
		(layer "B.Cu")
		(net "RST_CPU0_G_N")
	)
	(segment
		(start 289.146742 -72.187308)
		(end 289.613594 -71.720456)
		(width 0.089408)
		(layer "In9.Cu")
		(net "RST_CPU0_G_N")
	)
	(segment
		(start 281.46375 -70.306946)
		(end 283.502608 -72.345804)
		(width 0.089408)
		(layer "In9.Cu")
		(net "RST_CPU0_G_N")
	)
	(segment
		(start 290.233354 -68.21043)
		(end 290.6522 -67.791584)
		(width 0.089408)
		(layer "In9.Cu")
		(net "RST_CPU0_G_N")
	)
	(segment
		(start 287.052766 -73.143364)
		(end 287.383474 -73.143364)
		(width 0.089408)
		(layer "In9.Cu")
		(net "RST_CPU0_G_N")
	)
	(segment
		(start 288.84118 -72.187308)
		(end 289.146742 -72.187308)
		(width 0.089408)
		(layer "In9.Cu")
		(net "RST_CPU0_G_N")
	)
	(segment
		(start 290.233354 -71.457058)
		(end 290.233354 -68.21043)
		(width 0.089408)
		(layer "In9.Cu")
		(net "RST_CPU0_G_N")
	)
	(segment
		(start 289.969956 -71.720456)
		(end 290.233354 -71.457058)
		(width 0.089408)
		(layer "In9.Cu")
		(net "RST_CPU0_G_N")
	)
	(segment
		(start 286.589216 -72.679814)
		(end 287.052766 -73.143364)
		(width 0.089408)
		(layer "In9.Cu")
		(net "RST_CPU0_G_N")
	)
	(segment
		(start 285.825184 -72.345804)
		(end 286.159194 -72.679814)
		(width 0.089408)
		(layer "In9.Cu")
		(net "RST_CPU0_G_N")
	)
	(segment
		(start 283.502608 -72.345804)
		(end 285.825184 -72.345804)
		(width 0.089408)
		(layer "In9.Cu")
		(net "RST_CPU0_G_N")
	)
	(segment
		(start 287.847024 -72.679814)
		(end 288.348674 -72.679814)
		(width 0.089408)
		(layer "In9.Cu")
		(net "RST_CPU0_G_N")
	)
	(segment
		(start 289.613594 -71.720456)
		(end 289.969956 -71.720456)
		(width 0.089408)
		(layer "In9.Cu")
		(net "RST_CPU0_G_N")
	)
	(segment
		(start 288.348674 -72.679814)
		(end 288.84118 -72.187308)
		(width 0.089408)
		(layer "In9.Cu")
		(net "RST_CPU0_G_N")
	)
	(segment
		(start 287.383474 -73.143364)
		(end 287.847024 -72.679814)
		(width 0.089408)
		(layer "In9.Cu")
		(net "RST_CPU0_G_N")
	)
	(segment
		(start 286.159194 -72.679814)
		(end 286.589216 -72.679814)
		(width 0.089408)
		(layer "In9.Cu")
		(net "RST_CPU0_G_N")
	)
	(segment
		(start 297.520106 -71.16318)
		(end 297.54068 -71.16318)
		(width 0.089408)
		(layer "In11.Cu")
		(net "RST_CPU0_G_N")
	)
	(segment
		(start 296.6974 -70.66788)
		(end 296.727118 -70.671182)
		(width 0.089408)
		(layer "In11.Cu")
		(net "RST_CPU0_G_N")
	)
	(segment
		(start 302.650652 -71.16318)
		(end 302.683418 -71.16318)
		(width 0.089408)
		(layer "In11.Cu")
		(net "RST_CPU0_G_N")
	)
	(segment
		(start 352.215196 -66.796158)
		(end 355.92893 -70.509892)
		(width 0.089408)
		(layer "In11.Cu")
		(net "RST_CPU0_G_N")
	)
	(segment
		(start 303.513236 -70.66788)
		(end 303.541938 -70.66788)
		(width 0.089408)
		(layer "In11.Cu")
		(net "RST_CPU0_G_N")
	)
	(segment
		(start 355.273356 -72.141842)
		(end 355.180138 -72.141842)
		(width 0.089408)
		(layer "In11.Cu")
		(net "RST_CPU0_G_N")
	)
	(segment
		(start 307.779928 -70.658228)
		(end 309.0291 -71.9074)
		(width 0.089408)
		(layer "In11.Cu")
		(net "RST_CPU0_G_N")
	)
	(segment
		(start 296.64533 -70.66788)
		(end 296.6974 -70.66788)
		(width 0.089408)
		(layer "In11.Cu")
		(net "RST_CPU0_G_N")
	)
	(segment
		(start 336.983324 -66.796158)
		(end 352.215196 -66.796158)
		(width 0.089408)
		(layer "In11.Cu")
		(net "RST_CPU0_G_N")
	)
	(segment
		(start 295.782746 -70.363588)
		(end 295.815512 -70.363588)
		(width 0.089408)
		(layer "In11.Cu")
		(net "RST_CPU0_G_N")
	)
	(segment
		(start 290.945062 -67.622928)
		(end 291.03447 -67.647058)
		(width 0.089408)
		(layer "In11.Cu")
		(net "RST_CPU0_G_N")
	)
	(segment
		(start 331.872082 -71.9074)
		(end 336.983324 -66.796158)
		(width 0.089408)
		(layer "In11.Cu")
		(net "RST_CPU0_G_N")
	)
	(segment
		(start 297.173904 -70.963282)
		(end 297.17619 -70.967092)
		(width 0.089408)
		(layer "In11.Cu")
		(net "RST_CPU0_G_N")
	)
	(segment
		(start 309.0291 -71.9074)
		(end 331.872082 -71.9074)
		(width 0.089408)
		(layer "In11.Cu")
		(net "RST_CPU0_G_N")
	)
	(segment
		(start 291.490146 -67.887342)
		(end 291.522912 -67.887342)
		(width 0.089408)
		(layer "In11.Cu")
		(net "RST_CPU0_G_N")
	)
	(segment
		(start 290.6522 -67.791584)
		(end 290.945062 -67.622928)
		(width 0.089408)
		(layer "In11.Cu")
		(net "RST_CPU0_G_N")
	)
	(segment
		(start 306.942744 -70.658228)
		(end 307.779928 -70.658228)
		(width 0.089408)
		(layer "In11.Cu")
		(net "RST_CPU0_G_N")
	)
	(segment
		(start 355.92893 -70.509892)
		(end 355.92893 -71.486268)
		(width 0.089408)
		(layer "In11.Cu")
		(net "RST_CPU0_G_N")
	)
	(segment
		(start 291.862002 -68.478146)
		(end 291.857176 -68.486782)
		(width 0.089408)
		(layer "In11.Cu")
		(net "RST_CPU0_G_N")
	)
	(segment
		(start 291.857176 -68.486782)
		(end 291.850826 -68.49745)
		(width 0.089408)
		(layer "In11.Cu")
		(net "RST_CPU0_G_N")
	)
	(segment
		(start 306.61737 -70.467982)
		(end 306.633118 -70.49516)
		(width 0.089408)
		(layer "In11.Cu")
		(net "RST_CPU0_G_N")
	)
	(segment
		(start 294.926004 -69.868542)
		(end 294.963596 -69.868542)
		(width 0.089408)
		(layer "In11.Cu")
		(net "RST_CPU0_G_N")
	)
	(segment
		(start 355.92893 -71.486268)
		(end 355.273356 -72.141842)
		(width 0.089408)
		(layer "In11.Cu")
		(net "RST_CPU0_G_N")
	)
	(segment
		(start 292.34511 -69.372988)
		(end 292.376352 -69.372988)
		(width 0.089408)
		(layer "In11.Cu")
		(net "RST_CPU0_G_N")
	)
	(arc
		(start 295.815512 -70.363588)
		(mid 295.967752 -70.398764)
		(end 296.094912 -70.489572)
		(width 0.089408)
		(layer "In11.Cu")
		(net "RST_CPU0_G_N")
	)
	(arc
		(start 293.969186 -70.352666)
		(mid 294.329563 -70.311711)
		(end 294.598344 -70.068186)
		(width 0.089408)
		(layer "In11.Cu")
		(net "RST_CPU0_G_N")
	)
	(arc
		(start 303.017682 -70.963282)
		(mid 303.226987 -70.751042)
		(end 303.513236 -70.66788)
		(width 0.089408)
		(layer "In11.Cu")
		(net "RST_CPU0_G_N")
	)
	(arc
		(start 291.850826 -68.49745)
		(mid 291.854163 -69.072911)
		(end 292.34511 -69.372988)
		(width 0.089408)
		(layer "In11.Cu")
		(net "RST_CPU0_G_N")
	)
	(arc
		(start 294.598344 -70.068186)
		(mid 294.736672 -69.926509)
		(end 294.926004 -69.868542)
		(width 0.089408)
		(layer "In11.Cu")
		(net "RST_CPU0_G_N")
	)
	(arc
		(start 292.376352 -69.372988)
		(mid 292.572384 -69.428372)
		(end 292.715696 -69.57314)
		(width 0.089408)
		(layer "In11.Cu")
		(net "RST_CPU0_G_N")
	)
	(arc
		(start 301.46625 -71.458582)
		(mid 301.812706 -71.6588)
		(end 302.159162 -71.458582)
		(width 0.089408)
		(layer "In11.Cu")
		(net "RST_CPU0_G_N")
	)
	(arc
		(start 303.541938 -70.66788)
		(mid 303.735041 -70.611361)
		(end 303.876202 -70.467982)
		(width 0.089408)
		(layer "In11.Cu")
		(net "RST_CPU0_G_N")
	)
	(arc
		(start 306.633118 -70.49516)
		(mid 306.767791 -70.614914)
		(end 306.942744 -70.658228)
		(width 0.089408)
		(layer "In11.Cu")
		(net "RST_CPU0_G_N")
	)
	(arc
		(start 302.683418 -71.16318)
		(mid 302.876521 -71.106661)
		(end 303.017682 -70.963282)
		(width 0.089408)
		(layer "In11.Cu")
		(net "RST_CPU0_G_N")
	)
	(arc
		(start 297.17619 -70.967092)
		(mid 297.322149 -71.110747)
		(end 297.520106 -71.16318)
		(width 0.089408)
		(layer "In11.Cu")
		(net "RST_CPU0_G_N")
	)
	(arc
		(start 297.54068 -71.16318)
		(mid 297.824641 -71.247298)
		(end 298.03217 -71.458582)
		(width 0.089408)
		(layer "In11.Cu")
		(net "RST_CPU0_G_N")
	)
	(arc
		(start 291.522912 -67.887342)
		(mid 291.857605 -68.087999)
		(end 291.862002 -68.478146)
		(width 0.089408)
		(layer "In11.Cu")
		(net "RST_CPU0_G_N")
	)
	(arc
		(start 303.876202 -70.467982)
		(mid 304.388266 -70.172223)
		(end 304.90033 -70.467982)
		(width 0.089408)
		(layer "In11.Cu")
		(net "RST_CPU0_G_N")
	)
	(arc
		(start 300.442122 -71.458582)
		(mid 300.954186 -71.162823)
		(end 301.46625 -71.458582)
		(width 0.089408)
		(layer "In11.Cu")
		(net "RST_CPU0_G_N")
	)
	(arc
		(start 295.291256 -70.068186)
		(mid 295.498785 -70.27947)
		(end 295.782746 -70.363588)
		(width 0.089408)
		(layer "In11.Cu")
		(net "RST_CPU0_G_N")
	)
	(arc
		(start 291.03447 -67.647058)
		(mid 291.23476 -67.819436)
		(end 291.490146 -67.887342)
		(width 0.089408)
		(layer "In11.Cu")
		(net "RST_CPU0_G_N")
	)
	(arc
		(start 296.094912 -70.489572)
		(mid 296.356043 -70.622179)
		(end 296.64533 -70.66788)
		(width 0.089408)
		(layer "In11.Cu")
		(net "RST_CPU0_G_N")
	)
	(arc
		(start 305.593242 -70.467982)
		(mid 306.105306 -70.172223)
		(end 306.61737 -70.467982)
		(width 0.089408)
		(layer "In11.Cu")
		(net "RST_CPU0_G_N")
	)
	(arc
		(start 293.574216 -70.068694)
		(mid 293.741121 -70.253227)
		(end 293.969186 -70.352666)
		(width 0.089408)
		(layer "In11.Cu")
		(net "RST_CPU0_G_N")
	)
	(arc
		(start 298.725082 -71.458582)
		(mid 299.237146 -71.162823)
		(end 299.74921 -71.458582)
		(width 0.089408)
		(layer "In11.Cu")
		(net "RST_CPU0_G_N")
	)
	(arc
		(start 298.03217 -71.458582)
		(mid 298.378626 -71.6588)
		(end 298.725082 -71.458582)
		(width 0.089408)
		(layer "In11.Cu")
		(net "RST_CPU0_G_N")
	)
	(arc
		(start 293.110666 -69.857112)
		(mid 293.172461 -69.866181)
		(end 293.234872 -69.868542)
		(width 0.089408)
		(layer "In11.Cu")
		(net "RST_CPU0_G_N")
	)
	(arc
		(start 292.715696 -69.57314)
		(mid 292.882601 -69.757673)
		(end 293.110666 -69.857112)
		(width 0.089408)
		(layer "In11.Cu")
		(net "RST_CPU0_G_N")
	)
	(arc
		(start 296.727118 -70.671182)
		(mid 296.985377 -70.76392)
		(end 297.173904 -70.963282)
		(width 0.089408)
		(layer "In11.Cu")
		(net "RST_CPU0_G_N")
	)
	(arc
		(start 302.159162 -71.458582)
		(mid 302.366691 -71.247298)
		(end 302.650652 -71.16318)
		(width 0.089408)
		(layer "In11.Cu")
		(net "RST_CPU0_G_N")
	)
	(arc
		(start 304.90033 -70.467982)
		(mid 305.246786 -70.668073)
		(end 305.593242 -70.467982)
		(width 0.089408)
		(layer "In11.Cu")
		(net "RST_CPU0_G_N")
	)
	(arc
		(start 294.963596 -69.868542)
		(mid 295.152925 -69.926513)
		(end 295.291256 -70.068186)
		(width 0.089408)
		(layer "In11.Cu")
		(net "RST_CPU0_G_N")
	)
	(arc
		(start 293.234872 -69.868542)
		(mid 293.430904 -69.923926)
		(end 293.574216 -70.068694)
		(width 0.089408)
		(layer "In11.Cu")
		(net "RST_CPU0_G_N")
	)
	(arc
		(start 299.74921 -71.458582)
		(mid 300.095666 -71.6588)
		(end 300.442122 -71.458582)
		(width 0.089408)
		(layer "In11.Cu")
		(net "RST_CPU0_G_N")
	)
	(segment
		(start 412.05531 -43.920156)
		(end 412.05531 -43.499786)
		(width 0.10795)
		(layer "F.Cu")
		(net "RST_BMC_LVC3_N")
	)
	(segment
		(start 411.973268 -44.002198)
		(end 412.05531 -43.920156)
		(width 0.10795)
		(layer "F.Cu")
		(net "RST_BMC_LVC3_N")
	)
	(segment
		(start 412.05531 -43.499786)
		(end 411.89021 -43.334686)
		(width 0.10795)
		(layer "F.Cu")
		(net "RST_BMC_LVC3_N")
	)
	(via
		(at 411.973268 -44.002198)
		(size 0.4572)
		(drill 0.2032)
		(layers "F.Cu" "B.Cu")
		(net "RST_BMC_LVC3_N")
	)
	(via
		(at 412.512256 -44.376086)
		(size 0.508)
		(drill 0.254)
		(layers "F.Cu" "B.Cu")
		(net "RST_BMC_LVC3_N")
	)
	(segment
		(start 412.138368 -44.002198)
		(end 412.512256 -44.376086)
		(width 0.1143)
		(layer "B.Cu")
		(net "RST_BMC_LVC3_N")
	)
	(segment
		(start 411.973268 -44.002198)
		(end 412.138368 -44.002198)
		(width 0.1143)
		(layer "B.Cu")
		(net "RST_BMC_LVC3_N")
	)
	(segment
		(start 412.75 -44.61383)
		(end 412.75 -45.163232)
		(width 0.10795)
		(layer "B.Cu")
		(net "RST_BMC_LVC3_N")
	)
	(segment
		(start 412.512256 -44.376086)
		(end 412.75 -44.61383)
		(width 0.10795)
		(layer "B.Cu")
		(net "RST_BMC_LVC3_N")
	)
	(segment
		(start 404.003002 -101.405182)
		(end 403.733508 -101.405182)
		(width 0.10795)
		(layer "F.Cu")
		(net "PWRGD_SYS_PWROK")
	)
	(segment
		(start 402.198332 -101.35489)
		(end 400.880072 -101.35489)
		(width 0.0889)
		(layer "F.Cu")
		(net "PWRGD_SYS_PWROK")
	)
	(segment
		(start 394.462 -40.4876)
		(end 394.462 -40.005)
		(width 0.10795)
		(layer "F.Cu")
		(net "PWRGD_SYS_PWROK")
	)
	(segment
		(start 402.868638 -101.346)
		(end 402.207222 -101.346)
		(width 0.0889)
		(layer "F.Cu")
		(net "PWRGD_SYS_PWROK")
	)
	(segment
		(start 403.271482 -100.943156)
		(end 402.868638 -101.346)
		(width 0.0889)
		(layer "F.Cu")
		(net "PWRGD_SYS_PWROK")
	)
	(segment
		(start 405.0665 -102.108)
		(end 404.70582 -102.108)
		(width 0.10795)
		(layer "F.Cu")
		(net "PWRGD_SYS_PWROK")
	)
	(segment
		(start 412.741364 -43.385994)
		(end 412.690056 -43.334686)
		(width 0.10795)
		(layer "F.Cu")
		(net "PWRGD_SYS_PWROK")
	)
	(segment
		(start 402.207222 -101.346)
		(end 402.198332 -101.35489)
		(width 0.0889)
		(layer "F.Cu")
		(net "PWRGD_SYS_PWROK")
	)
	(segment
		(start 394.462 -40.005)
		(end 394.589 -39.878)
		(width 0.10795)
		(layer "F.Cu")
		(net "PWRGD_SYS_PWROK")
	)
	(segment
		(start 367.945162 -70.295262)
		(end 368.344958 -70.695058)
		(width 0.10795)
		(layer "F.Cu")
		(net "PWRGD_SYS_PWROK")
	)
	(segment
		(start 412.741364 -43.925744)
		(end 412.741364 -43.385994)
		(width 0.10795)
		(layer "F.Cu")
		(net "PWRGD_SYS_PWROK")
	)
	(segment
		(start 403.733508 -101.405182)
		(end 403.271482 -100.943156)
		(width 0.10795)
		(layer "F.Cu")
		(net "PWRGD_SYS_PWROK")
	)
	(segment
		(start 404.70582 -102.108)
		(end 404.003002 -101.405182)
		(width 0.10795)
		(layer "F.Cu")
		(net "PWRGD_SYS_PWROK")
	)
	(via
		(at 424.75531 -120.2944)
		(size 0.508)
		(drill 0.254)
		(layers "F.Cu" "B.Cu")
		(net "PWRGD_SYS_PWROK")
	)
	(via
		(at 399.161254 -45.727874)
		(size 0.508)
		(drill 0.254)
		(layers "F.Cu" "B.Cu")
		(net "PWRGD_SYS_PWROK")
	)
	(via
		(at 396.5956 -66.802)
		(size 0.6604)
		(drill 0.3302)
		(layers "F.Cu" "B.Cu")
		(net "PWRGD_SYS_PWROK")
	)
	(via
		(at 367.945162 -70.295262)
		(size 0.4572)
		(drill 0.2032)
		(layers "F.Cu" "B.Cu")
		(net "PWRGD_SYS_PWROK")
	)
	(via
		(at 472.066112 -138.310112)
		(size 0.508)
		(drill 0.254)
		(layers "F.Cu" "B.Cu")
		(net "PWRGD_SYS_PWROK")
	)
	(via
		(at 412.741364 -43.925744)
		(size 0.4572)
		(drill 0.2032)
		(layers "F.Cu" "B.Cu")
		(net "PWRGD_SYS_PWROK")
	)
	(via
		(at 394.589 -39.878)
		(size 0.508)
		(drill 0.254)
		(layers "F.Cu" "B.Cu")
		(net "PWRGD_SYS_PWROK")
	)
	(via
		(at 403.271482 -100.943156)
		(size 0.508)
		(drill 0.254)
		(layers "F.Cu" "B.Cu")
		(net "PWRGD_SYS_PWROK")
	)
	(via
		(at 398.018 -65.92824)
		(size 0.508)
		(drill 0.254)
		(layers "F.Cu" "B.Cu")
		(net "PWRGD_SYS_PWROK")
	)
	(segment
		(start 397.22044 -66.802)
		(end 396.5956 -66.802)
		(width 0.10795)
		(layer "B.Cu")
		(net "PWRGD_SYS_PWROK")
	)
	(segment
		(start 399.161254 -45.727874)
		(end 399.161254 -45.068998)
		(width 0.10795)
		(layer "B.Cu")
		(net "PWRGD_SYS_PWROK")
	)
	(segment
		(start 395.920722 -41.971722)
		(end 394.589 -40.64)
		(width 0.10795)
		(layer "B.Cu")
		(net "PWRGD_SYS_PWROK")
	)
	(segment
		(start 397.21282 -42.24782)
		(end 396.936722 -41.971722)
		(width 0.10795)
		(layer "B.Cu")
		(net "PWRGD_SYS_PWROK")
	)
	(segment
		(start 396.936722 -41.971722)
		(end 395.920722 -41.971722)
		(width 0.10795)
		(layer "B.Cu")
		(net "PWRGD_SYS_PWROK")
	)
	(segment
		(start 472.193112 -138.437112)
		(end 472.066112 -138.310112)
		(width 0.10795)
		(layer "B.Cu")
		(net "PWRGD_SYS_PWROK")
	)
	(segment
		(start 473.660216 -138.437112)
		(end 472.193112 -138.437112)
		(width 0.10795)
		(layer "B.Cu")
		(net "PWRGD_SYS_PWROK")
	)
	(segment
		(start 398.018 -66.00444)
		(end 397.22044 -66.802)
		(width 0.10795)
		(layer "B.Cu")
		(net "PWRGD_SYS_PWROK")
	)
	(segment
		(start 394.589 -40.64)
		(end 394.589 -39.878)
		(width 0.10795)
		(layer "B.Cu")
		(net "PWRGD_SYS_PWROK")
	)
	(segment
		(start 399.161254 -45.068998)
		(end 397.21282 -43.120564)
		(width 0.10795)
		(layer "B.Cu")
		(net "PWRGD_SYS_PWROK")
	)
	(segment
		(start 398.018 -65.92824)
		(end 398.018 -66.00444)
		(width 0.10795)
		(layer "B.Cu")
		(net "PWRGD_SYS_PWROK")
	)
	(segment
		(start 397.21282 -43.120564)
		(end 397.21282 -42.24782)
		(width 0.10795)
		(layer "B.Cu")
		(net "PWRGD_SYS_PWROK")
	)
	(segment
		(start 407.460704 -112.683036)
		(end 406.12568 -111.348012)
		(width 0.089408)
		(layer "In2.Cu")
		(net "PWRGD_SYS_PWROK")
	)
	(segment
		(start 410.743908 -43.2816)
		(end 411.133544 -43.671236)
		(width 0.089408)
		(layer "In2.Cu")
		(net "PWRGD_SYS_PWROK")
	)
	(segment
		(start 404.683722 -43.169332)
		(end 406.924764 -43.169332)
		(width 0.089408)
		(layer "In2.Cu")
		(net "PWRGD_SYS_PWROK")
	)
	(segment
		(start 404.368 -104.6226)
		(end 404.6347 -104.3559)
		(width 0.089408)
		(layer "In2.Cu")
		(net "PWRGD_SYS_PWROK")
	)
	(segment
		(start 407.460704 -114.854228)
		(end 407.460704 -112.683036)
		(width 0.089408)
		(layer "In2.Cu")
		(net "PWRGD_SYS_PWROK")
	)
	(segment
		(start 406.924764 -43.169332)
		(end 407.037032 -43.2816)
		(width 0.089408)
		(layer "In2.Cu")
		(net "PWRGD_SYS_PWROK")
	)
	(segment
		(start 402.12518 -45.727874)
		(end 404.683722 -43.169332)
		(width 0.089408)
		(layer "In2.Cu")
		(net "PWRGD_SYS_PWROK")
	)
	(segment
		(start 408.731212 -118.603776)
		(end 409.757372 -117.577616)
		(width 0.089408)
		(layer "In2.Cu")
		(net "PWRGD_SYS_PWROK")
	)
	(segment
		(start 411.795214 -43.671744)
		(end 411.839664 -43.627294)
		(width 0.089408)
		(layer "In2.Cu")
		(net "PWRGD_SYS_PWROK")
	)
	(segment
		(start 406.12568 -111.348012)
		(end 406.12568 -107.82808)
		(width 0.089408)
		(layer "In2.Cu")
		(net "PWRGD_SYS_PWROK")
	)
	(segment
		(start 409.471368 -121.589292)
		(end 408.731212 -120.849136)
		(width 0.089408)
		(layer "In2.Cu")
		(net "PWRGD_SYS_PWROK")
	)
	(segment
		(start 404.6347 -103.8225)
		(end 404.1648 -103.3526)
		(width 0.089408)
		(layer "In2.Cu")
		(net "PWRGD_SYS_PWROK")
	)
	(segment
		(start 409.757372 -117.577616)
		(end 409.757372 -117.150896)
		(width 0.089408)
		(layer "In2.Cu")
		(net "PWRGD_SYS_PWROK")
	)
	(segment
		(start 403.268434 -103.3526)
		(end 402.678392 -102.762558)
		(width 0.089408)
		(layer "In2.Cu")
		(net "PWRGD_SYS_PWROK")
	)
	(segment
		(start 421.365172 -120.58396)
		(end 421.037004 -120.255792)
		(width 0.089408)
		(layer "In2.Cu")
		(net "PWRGD_SYS_PWROK")
	)
	(segment
		(start 424.75531 -120.2944)
		(end 424.46575 -120.58396)
		(width 0.089408)
		(layer "In2.Cu")
		(net "PWRGD_SYS_PWROK")
	)
	(segment
		(start 411.380686 -121.722896)
		(end 411.247082 -121.589292)
		(width 0.089408)
		(layer "In2.Cu")
		(net "PWRGD_SYS_PWROK")
	)
	(segment
		(start 416.72256 -121.722896)
		(end 411.380686 -121.722896)
		(width 0.089408)
		(layer "In2.Cu")
		(net "PWRGD_SYS_PWROK")
	)
	(segment
		(start 402.678392 -102.762558)
		(end 402.678392 -101.536246)
		(width 0.089408)
		(layer "In2.Cu")
		(net "PWRGD_SYS_PWROK")
	)
	(segment
		(start 402.678392 -101.536246)
		(end 403.271482 -100.943156)
		(width 0.089408)
		(layer "In2.Cu")
		(net "PWRGD_SYS_PWROK")
	)
	(segment
		(start 404.1648 -103.3526)
		(end 403.268434 -103.3526)
		(width 0.089408)
		(layer "In2.Cu")
		(net "PWRGD_SYS_PWROK")
	)
	(segment
		(start 418.189664 -120.255792)
		(end 416.72256 -121.722896)
		(width 0.089408)
		(layer "In2.Cu")
		(net "PWRGD_SYS_PWROK")
	)
	(segment
		(start 399.161254 -45.727874)
		(end 402.12518 -45.727874)
		(width 0.089408)
		(layer "In2.Cu")
		(net "PWRGD_SYS_PWROK")
	)
	(segment
		(start 411.247082 -121.589292)
		(end 409.471368 -121.589292)
		(width 0.089408)
		(layer "In2.Cu")
		(net "PWRGD_SYS_PWROK")
	)
	(segment
		(start 404.368 -106.0704)
		(end 404.368 -104.6226)
		(width 0.089408)
		(layer "In2.Cu")
		(net "PWRGD_SYS_PWROK")
	)
	(segment
		(start 407.037032 -43.2816)
		(end 410.743908 -43.2816)
		(width 0.089408)
		(layer "In2.Cu")
		(net "PWRGD_SYS_PWROK")
	)
	(segment
		(start 411.839664 -43.627294)
		(end 412.442914 -43.627294)
		(width 0.089408)
		(layer "In2.Cu")
		(net "PWRGD_SYS_PWROK")
	)
	(segment
		(start 411.133544 -43.671236)
		(end 411.478222 -43.671236)
		(width 0.089408)
		(layer "In2.Cu")
		(net "PWRGD_SYS_PWROK")
	)
	(segment
		(start 411.478222 -43.671236)
		(end 411.47873 -43.671744)
		(width 0.089408)
		(layer "In2.Cu")
		(net "PWRGD_SYS_PWROK")
	)
	(segment
		(start 404.6347 -104.3559)
		(end 404.6347 -103.8225)
		(width 0.089408)
		(layer "In2.Cu")
		(net "PWRGD_SYS_PWROK")
	)
	(segment
		(start 424.46575 -120.58396)
		(end 421.365172 -120.58396)
		(width 0.089408)
		(layer "In2.Cu")
		(net "PWRGD_SYS_PWROK")
	)
	(segment
		(start 421.037004 -120.255792)
		(end 418.189664 -120.255792)
		(width 0.089408)
		(layer "In2.Cu")
		(net "PWRGD_SYS_PWROK")
	)
	(segment
		(start 411.47873 -43.671744)
		(end 411.795214 -43.671744)
		(width 0.089408)
		(layer "In2.Cu")
		(net "PWRGD_SYS_PWROK")
	)
	(segment
		(start 409.757372 -117.150896)
		(end 407.460704 -114.854228)
		(width 0.089408)
		(layer "In2.Cu")
		(net "PWRGD_SYS_PWROK")
	)
	(segment
		(start 406.12568 -107.82808)
		(end 404.368 -106.0704)
		(width 0.089408)
		(layer "In2.Cu")
		(net "PWRGD_SYS_PWROK")
	)
	(segment
		(start 408.731212 -120.849136)
		(end 408.731212 -118.603776)
		(width 0.089408)
		(layer "In2.Cu")
		(net "PWRGD_SYS_PWROK")
	)
	(segment
		(start 412.442914 -43.627294)
		(end 412.741364 -43.925744)
		(width 0.089408)
		(layer "In2.Cu")
		(net "PWRGD_SYS_PWROK")
	)
	(segment
		(start 443.221364 -116.434616)
		(end 442.219588 -117.436392)
		(width 0.089408)
		(layer "In4.Cu")
		(net "PWRGD_SYS_PWROK")
	)
	(segment
		(start 471.4494 -137.5156)
		(end 470.64168 -136.70788)
		(width 0.089408)
		(layer "In4.Cu")
		(net "PWRGD_SYS_PWROK")
	)
	(segment
		(start 471.4494 -133.48462)
		(end 471.4494 -127.0508)
		(width 0.089408)
		(layer "In4.Cu")
		(net "PWRGD_SYS_PWROK")
	)
	(segment
		(start 397.69542 -66.25082)
		(end 395.593316 -66.25082)
		(width 0.089408)
		(layer "In4.Cu")
		(net "PWRGD_SYS_PWROK")
	)
	(segment
		(start 395.10716 -65.764664)
		(end 391.406634 -65.764664)
		(width 0.089408)
		(layer "In4.Cu")
		(net "PWRGD_SYS_PWROK")
	)
	(segment
		(start 471.4494 -127.0508)
		(end 472.012772 -126.487428)
		(width 0.089408)
		(layer "In4.Cu")
		(net "PWRGD_SYS_PWROK")
	)
	(segment
		(start 473.154248 -126.157228)
		(end 473.154248 -123.826524)
		(width 0.089408)
		(layer "In4.Cu")
		(net "PWRGD_SYS_PWROK")
	)
	(segment
		(start 470.64168 -136.70788)
		(end 470.64168 -134.29234)
		(width 0.089408)
		(layer "In4.Cu")
		(net "PWRGD_SYS_PWROK")
	)
	(segment
		(start 464.74634 -117.577616)
		(end 463.60334 -116.434616)
		(width 0.089408)
		(layer "In4.Cu")
		(net "PWRGD_SYS_PWROK")
	)
	(segment
		(start 472.066112 -138.310112)
		(end 471.4494 -137.6934)
		(width 0.089408)
		(layer "In4.Cu")
		(net "PWRGD_SYS_PWROK")
	)
	(segment
		(start 378.113544 -67.171824)
		(end 378.006356 -67.064636)
		(width 0.089408)
		(layer "In4.Cu")
		(net "PWRGD_SYS_PWROK")
	)
	(segment
		(start 391.406634 -65.764664)
		(end 391.40638 -65.76441)
		(width 0.089408)
		(layer "In4.Cu")
		(net "PWRGD_SYS_PWROK")
	)
	(segment
		(start 388.747508 -67.948302)
		(end 380.79299 -67.948302)
		(width 0.089408)
		(layer "In4.Cu")
		(net "PWRGD_SYS_PWROK")
	)
	(segment
		(start 374.75033 -68.920868)
		(end 374.57126 -69.099938)
		(width 0.089408)
		(layer "In4.Cu")
		(net "PWRGD_SYS_PWROK")
	)
	(segment
		(start 368.007138 -70.295262)
		(end 367.945162 -70.295262)
		(width 0.089408)
		(layer "In4.Cu")
		(net "PWRGD_SYS_PWROK")
	)
	(segment
		(start 436.885588 -117.436392)
		(end 433.786534 -120.535446)
		(width 0.089408)
		(layer "In4.Cu")
		(net "PWRGD_SYS_PWROK")
	)
	(segment
		(start 378.361194 -67.172078)
		(end 378.36094 -67.171824)
		(width 0.089408)
		(layer "In4.Cu")
		(net "PWRGD_SYS_PWROK")
	)
	(segment
		(start 391.40638 -65.76441)
		(end 390.9314 -65.76441)
		(width 0.089408)
		(layer "In4.Cu")
		(net "PWRGD_SYS_PWROK")
	)
	(segment
		(start 380.79299 -67.948302)
		(end 380.096776 -67.252088)
		(width 0.089408)
		(layer "In4.Cu")
		(net "PWRGD_SYS_PWROK")
	)
	(segment
		(start 374.75033 -68.227702)
		(end 374.75033 -68.920868)
		(width 0.089408)
		(layer "In4.Cu")
		(net "PWRGD_SYS_PWROK")
	)
	(segment
		(start 424.75531 -120.050052)
		(end 424.75531 -120.2944)
		(width 0.089408)
		(layer "In4.Cu")
		(net "PWRGD_SYS_PWROK")
	)
	(segment
		(start 471.4494 -137.6934)
		(end 471.4494 -137.5156)
		(width 0.089408)
		(layer "In4.Cu")
		(net "PWRGD_SYS_PWROK")
	)
	(segment
		(start 470.013284 -120.68556)
		(end 470.013284 -118.61292)
		(width 0.089408)
		(layer "In4.Cu")
		(net "PWRGD_SYS_PWROK")
	)
	(segment
		(start 463.60334 -116.434616)
		(end 443.221364 -116.434616)
		(width 0.089408)
		(layer "In4.Cu")
		(net "PWRGD_SYS_PWROK")
	)
	(segment
		(start 374.57126 -69.099938)
		(end 374.21185 -69.099938)
		(width 0.089408)
		(layer "In4.Cu")
		(net "PWRGD_SYS_PWROK")
	)
	(segment
		(start 378.006356 -67.064636)
		(end 376.507248 -67.064636)
		(width 0.089408)
		(layer "In4.Cu")
		(net "PWRGD_SYS_PWROK")
	)
	(segment
		(start 468.97798 -117.577616)
		(end 464.74634 -117.577616)
		(width 0.089408)
		(layer "In4.Cu")
		(net "PWRGD_SYS_PWROK")
	)
	(segment
		(start 470.013284 -118.61292)
		(end 468.97798 -117.577616)
		(width 0.089408)
		(layer "In4.Cu")
		(net "PWRGD_SYS_PWROK")
	)
	(segment
		(start 428.125382 -120.535446)
		(end 428.125128 -120.5357)
		(width 0.089408)
		(layer "In4.Cu")
		(net "PWRGD_SYS_PWROK")
	)
	(segment
		(start 473.154248 -123.826524)
		(end 470.013284 -120.68556)
		(width 0.089408)
		(layer "In4.Cu")
		(net "PWRGD_SYS_PWROK")
	)
	(segment
		(start 442.219588 -117.436392)
		(end 436.885588 -117.436392)
		(width 0.089408)
		(layer "In4.Cu")
		(net "PWRGD_SYS_PWROK")
	)
	(segment
		(start 374.21185 -69.099938)
		(end 373.971312 -69.340476)
		(width 0.089408)
		(layer "In4.Cu")
		(net "PWRGD_SYS_PWROK")
	)
	(segment
		(start 398.018 -65.92824)
		(end 397.69542 -66.25082)
		(width 0.089408)
		(layer "In4.Cu")
		(net "PWRGD_SYS_PWROK")
	)
	(segment
		(start 472.824048 -126.487428)
		(end 473.154248 -126.157228)
		(width 0.089408)
		(layer "In4.Cu")
		(net "PWRGD_SYS_PWROK")
	)
	(segment
		(start 380.096522 -67.252088)
		(end 380.016512 -67.172078)
		(width 0.089408)
		(layer "In4.Cu")
		(net "PWRGD_SYS_PWROK")
	)
	(segment
		(start 380.096776 -67.252088)
		(end 380.096522 -67.252088)
		(width 0.089408)
		(layer "In4.Cu")
		(net "PWRGD_SYS_PWROK")
	)
	(segment
		(start 376.385074 -67.18681)
		(end 375.791222 -67.18681)
		(width 0.089408)
		(layer "In4.Cu")
		(net "PWRGD_SYS_PWROK")
	)
	(segment
		(start 433.786534 -120.535446)
		(end 428.125382 -120.535446)
		(width 0.089408)
		(layer "In4.Cu")
		(net "PWRGD_SYS_PWROK")
	)
	(segment
		(start 472.012772 -126.487428)
		(end 472.824048 -126.487428)
		(width 0.089408)
		(layer "In4.Cu")
		(net "PWRGD_SYS_PWROK")
	)
	(segment
		(start 380.016512 -67.172078)
		(end 378.361194 -67.172078)
		(width 0.089408)
		(layer "In4.Cu")
		(net "PWRGD_SYS_PWROK")
	)
	(segment
		(start 426.376592 -119.187976)
		(end 425.617386 -119.187976)
		(width 0.089408)
		(layer "In4.Cu")
		(net "PWRGD_SYS_PWROK")
	)
	(segment
		(start 428.125128 -120.5357)
		(end 427.724316 -120.5357)
		(width 0.089408)
		(layer "In4.Cu")
		(net "PWRGD_SYS_PWROK")
	)
	(segment
		(start 427.724316 -120.5357)
		(end 426.376592 -119.187976)
		(width 0.089408)
		(layer "In4.Cu")
		(net "PWRGD_SYS_PWROK")
	)
	(segment
		(start 375.791222 -67.18681)
		(end 374.75033 -68.227702)
		(width 0.089408)
		(layer "In4.Cu")
		(net "PWRGD_SYS_PWROK")
	)
	(segment
		(start 395.593316 -66.25082)
		(end 395.10716 -65.764664)
		(width 0.089408)
		(layer "In4.Cu")
		(net "PWRGD_SYS_PWROK")
	)
	(segment
		(start 373.816118 -69.921882)
		(end 368.380518 -69.921882)
		(width 0.089408)
		(layer "In4.Cu")
		(net "PWRGD_SYS_PWROK")
	)
	(segment
		(start 373.971312 -69.766688)
		(end 373.816118 -69.921882)
		(width 0.089408)
		(layer "In4.Cu")
		(net "PWRGD_SYS_PWROK")
	)
	(segment
		(start 378.36094 -67.171824)
		(end 378.113544 -67.171824)
		(width 0.089408)
		(layer "In4.Cu")
		(net "PWRGD_SYS_PWROK")
	)
	(segment
		(start 425.617386 -119.187976)
		(end 424.75531 -120.050052)
		(width 0.089408)
		(layer "In4.Cu")
		(net "PWRGD_SYS_PWROK")
	)
	(segment
		(start 390.9314 -65.76441)
		(end 388.747508 -67.948302)
		(width 0.089408)
		(layer "In4.Cu")
		(net "PWRGD_SYS_PWROK")
	)
	(segment
		(start 368.380518 -69.921882)
		(end 368.007138 -70.295262)
		(width 0.089408)
		(layer "In4.Cu")
		(net "PWRGD_SYS_PWROK")
	)
	(segment
		(start 470.64168 -134.29234)
		(end 471.4494 -133.48462)
		(width 0.089408)
		(layer "In4.Cu")
		(net "PWRGD_SYS_PWROK")
	)
	(segment
		(start 373.971312 -69.340476)
		(end 373.971312 -69.766688)
		(width 0.089408)
		(layer "In4.Cu")
		(net "PWRGD_SYS_PWROK")
	)
	(segment
		(start 376.507248 -67.064636)
		(end 376.385074 -67.18681)
		(width 0.089408)
		(layer "In4.Cu")
		(net "PWRGD_SYS_PWROK")
	)
	(segment
		(start 398.424654 -46.916848)
		(end 398.135094 -47.206408)
		(width 0.089408)
		(layer "In9.Cu")
		(net "PWRGD_SYS_PWROK")
	)
	(segment
		(start 398.798034 -64.02324)
		(end 398.151096 -64.670178)
		(width 0.089408)
		(layer "In9.Cu")
		(net "PWRGD_SYS_PWROK")
	)
	(segment
		(start 398.424654 -46.464474)
		(end 398.424654 -46.916848)
		(width 0.089408)
		(layer "In9.Cu")
		(net "PWRGD_SYS_PWROK")
	)
	(segment
		(start 398.448784 -62.176152)
		(end 398.798034 -62.525402)
		(width 0.089408)
		(layer "In9.Cu")
		(net "PWRGD_SYS_PWROK")
	)
	(segment
		(start 398.151096 -65.795144)
		(end 398.018 -65.92824)
		(width 0.089408)
		(layer "In9.Cu")
		(net "PWRGD_SYS_PWROK")
	)
	(segment
		(start 399.161254 -45.727874)
		(end 398.424654 -46.464474)
		(width 0.089408)
		(layer "In9.Cu")
		(net "PWRGD_SYS_PWROK")
	)
	(segment
		(start 398.448784 -61.846714)
		(end 398.448784 -62.176152)
		(width 0.089408)
		(layer "In9.Cu")
		(net "PWRGD_SYS_PWROK")
	)
	(segment
		(start 398.449038 -61.84646)
		(end 398.448784 -61.846714)
		(width 0.089408)
		(layer "In9.Cu")
		(net "PWRGD_SYS_PWROK")
	)
	(segment
		(start 398.151096 -64.670178)
		(end 398.151096 -65.795144)
		(width 0.089408)
		(layer "In9.Cu")
		(net "PWRGD_SYS_PWROK")
	)
	(segment
		(start 398.798034 -62.525402)
		(end 398.798034 -64.02324)
		(width 0.089408)
		(layer "In9.Cu")
		(net "PWRGD_SYS_PWROK")
	)
	(segment
		(start 398.135094 -47.206408)
		(end 398.135094 -58.264552)
		(width 0.089408)
		(layer "In9.Cu")
		(net "PWRGD_SYS_PWROK")
	)
	(segment
		(start 398.449038 -60.579)
		(end 398.449038 -61.84646)
		(width 0.089408)
		(layer "In9.Cu")
		(net "PWRGD_SYS_PWROK")
	)
	(segment
		(start 398.135094 -58.264552)
		(end 398.448784 -58.578242)
		(width 0.089408)
		(layer "In9.Cu")
		(net "PWRGD_SYS_PWROK")
	)
	(segment
		(start 398.448784 -60.578746)
		(end 398.449038 -60.579)
		(width 0.089408)
		(layer "In9.Cu")
		(net "PWRGD_SYS_PWROK")
	)
	(segment
		(start 398.448784 -58.578242)
		(end 398.448784 -60.578746)
		(width 0.089408)
		(layer "In9.Cu")
		(net "PWRGD_SYS_PWROK")
	)
	(segment
		(start 400.170904 -75.27671)
		(end 400.170904 -72.112378)
		(width 0.089408)
		(layer "In11.Cu")
		(net "PWRGD_SYS_PWROK")
	)
	(segment
		(start 402.448776 -83.754976)
		(end 401.092924 -82.399124)
		(width 0.089408)
		(layer "In11.Cu")
		(net "PWRGD_SYS_PWROK")
	)
	(segment
		(start 400.787362 -76.45019)
		(end 400.787616 -76.449936)
		(width 0.089408)
		(layer "In11.Cu")
		(net "PWRGD_SYS_PWROK")
	)
	(segment
		(start 400.787616 -76.449936)
		(end 400.787616 -75.893422)
		(width 0.089408)
		(layer "In11.Cu")
		(net "PWRGD_SYS_PWROK")
	)
	(segment
		(start 404.315676 -86.713568)
		(end 402.448776 -84.846668)
		(width 0.089408)
		(layer "In11.Cu")
		(net "PWRGD_SYS_PWROK")
	)
	(segment
		(start 400.787362 -77.328776)
		(end 400.787362 -76.45019)
		(width 0.089408)
		(layer "In11.Cu")
		(net "PWRGD_SYS_PWROK")
	)
	(segment
		(start 402.4122 -99.9998)
		(end 402.4122 -99.7204)
		(width 0.089408)
		(layer "In11.Cu")
		(net "PWRGD_SYS_PWROK")
	)
	(segment
		(start 398.068292 -70.009766)
		(end 398.068292 -65.978532)
		(width 0.089408)
		(layer "In11.Cu")
		(net "PWRGD_SYS_PWROK")
	)
	(segment
		(start 401.09267 -79.131922)
		(end 401.09267 -78.889606)
		(width 0.089408)
		(layer "In11.Cu")
		(net "PWRGD_SYS_PWROK")
	)
	(segment
		(start 403.271482 -100.859082)
		(end 402.4122 -99.9998)
		(width 0.089408)
		(layer "In11.Cu")
		(net "PWRGD_SYS_PWROK")
	)
	(segment
		(start 398.068292 -65.978532)
		(end 398.018 -65.92824)
		(width 0.089408)
		(layer "In11.Cu")
		(net "PWRGD_SYS_PWROK")
	)
	(segment
		(start 400.170904 -72.112378)
		(end 398.068292 -70.009766)
		(width 0.089408)
		(layer "In11.Cu")
		(net "PWRGD_SYS_PWROK")
	)
	(segment
		(start 401.09267 -78.889606)
		(end 401.280376 -78.7019)
		(width 0.089408)
		(layer "In11.Cu")
		(net "PWRGD_SYS_PWROK")
	)
	(segment
		(start 401.092924 -82.399124)
		(end 401.092924 -79.132176)
		(width 0.089408)
		(layer "In11.Cu")
		(net "PWRGD_SYS_PWROK")
	)
	(segment
		(start 401.280376 -77.82179)
		(end 400.787362 -77.328776)
		(width 0.089408)
		(layer "In11.Cu")
		(net "PWRGD_SYS_PWROK")
	)
	(segment
		(start 402.988272 -99.144328)
		(end 402.988272 -93.141038)
		(width 0.089408)
		(layer "In11.Cu")
		(net "PWRGD_SYS_PWROK")
	)
	(segment
		(start 403.271482 -100.943156)
		(end 403.271482 -100.859082)
		(width 0.089408)
		(layer "In11.Cu")
		(net "PWRGD_SYS_PWROK")
	)
	(segment
		(start 404.315676 -91.813634)
		(end 404.315676 -86.713568)
		(width 0.089408)
		(layer "In11.Cu")
		(net "PWRGD_SYS_PWROK")
	)
	(segment
		(start 402.448776 -84.846668)
		(end 402.448776 -83.754976)
		(width 0.089408)
		(layer "In11.Cu")
		(net "PWRGD_SYS_PWROK")
	)
	(segment
		(start 402.4122 -99.7204)
		(end 402.988272 -99.144328)
		(width 0.089408)
		(layer "In11.Cu")
		(net "PWRGD_SYS_PWROK")
	)
	(segment
		(start 400.787616 -75.893422)
		(end 400.170904 -75.27671)
		(width 0.089408)
		(layer "In11.Cu")
		(net "PWRGD_SYS_PWROK")
	)
	(segment
		(start 401.092924 -79.132176)
		(end 401.09267 -79.131922)
		(width 0.089408)
		(layer "In11.Cu")
		(net "PWRGD_SYS_PWROK")
	)
	(segment
		(start 401.280376 -78.7019)
		(end 401.280376 -77.82179)
		(width 0.089408)
		(layer "In11.Cu")
		(net "PWRGD_SYS_PWROK")
	)
	(segment
		(start 402.988272 -93.141038)
		(end 404.315676 -91.813634)
		(width 0.089408)
		(layer "In11.Cu")
		(net "PWRGD_SYS_PWROK")
	)
	(segment
		(start 382.972564 -79.934816)
		(end 382.922526 -79.884778)
		(width 0.10795)
		(layer "F.Cu")
		(net "PWRGD_PVSA_CPU1")
	)
	(segment
		(start 16.002 -86.741)
		(end 16.002 -86.106)
		(width 0.10795)
		(layer "F.Cu")
		(net "PWRGD_PVSA_CPU1")
	)
	(segment
		(start 379.653038 -81.077562)
		(end 377.127516 -81.077562)
		(width 0.10795)
		(layer "F.Cu")
		(net "PWRGD_PVSA_CPU1")
	)
	(segment
		(start 380.845822 -79.884778)
		(end 379.653038 -81.077562)
		(width 0.10795)
		(layer "F.Cu")
		(net "PWRGD_PVSA_CPU1")
	)
	(segment
		(start 384.573018 -80.169004)
		(end 384.33883 -79.934816)
		(width 0.10795)
		(layer "F.Cu")
		(net "PWRGD_PVSA_CPU1")
	)
	(segment
		(start 16.002 -86.106)
		(end 15.9766 -86.106)
		(width 0.10795)
		(layer "F.Cu")
		(net "PWRGD_PVSA_CPU1")
	)
	(segment
		(start 377.127516 -81.077562)
		(end 376.344942 -80.294988)
		(width 0.10795)
		(layer "F.Cu")
		(net "PWRGD_PVSA_CPU1")
	)
	(segment
		(start 384.33883 -79.934816)
		(end 382.972564 -79.934816)
		(width 0.10795)
		(layer "F.Cu")
		(net "PWRGD_PVSA_CPU1")
	)
	(segment
		(start 382.922526 -79.884778)
		(end 380.845822 -79.884778)
		(width 0.10795)
		(layer "F.Cu")
		(net "PWRGD_PVSA_CPU1")
	)
	(via
		(at 384.573018 -80.169004)
		(size 0.508)
		(drill 0.254)
		(layers "F.Cu" "B.Cu")
		(net "PWRGD_PVSA_CPU1")
	)
	(via
		(at 15.9766 -86.106)
		(size 0.508)
		(drill 0.254)
		(layers "F.Cu" "B.Cu")
		(net "PWRGD_PVSA_CPU1")
	)
	(via
		(at 329.883516 -21.141182)
		(size 0.508)
		(drill 0.254)
		(layers "F.Cu" "B.Cu")
		(net "PWRGD_PVSA_CPU1")
	)
	(segment
		(start 172.441108 -4.046728)
		(end 173.777148 -4.046728)
		(width 0.089408)
		(layer "In4.Cu")
		(net "PWRGD_PVSA_CPU1")
	)
	(segment
		(start 168.069514 -3.52552)
		(end 171.87672 -3.52552)
		(width 0.089408)
		(layer "In4.Cu")
		(net "PWRGD_PVSA_CPU1")
	)
	(segment
		(start 15.9766 -81.7118)
		(end 15.5956 -81.3308)
		(width 0.089408)
		(layer "In4.Cu")
		(net "PWRGD_PVSA_CPU1")
	)
	(segment
		(start 22.4282 -50.66538)
		(end 20.753832 -48.991012)
		(width 0.089408)
		(layer "In4.Cu")
		(net "PWRGD_PVSA_CPU1")
	)
	(segment
		(start 187.142882 4.12496)
		(end 322.03644 4.12496)
		(width 0.089408)
		(layer "In4.Cu")
		(net "PWRGD_PVSA_CPU1")
	)
	(segment
		(start 27.876246 3.012186)
		(end 28.95346 4.0894)
		(width 0.089408)
		(layer "In4.Cu")
		(net "PWRGD_PVSA_CPU1")
	)
	(segment
		(start 322.03644 4.12496)
		(end 324.2564 1.905)
		(width 0.089408)
		(layer "In4.Cu")
		(net "PWRGD_PVSA_CPU1")
	)
	(segment
		(start 22.257512 -76.236322)
		(end 22.257512 -72.517254)
		(width 0.089408)
		(layer "In4.Cu")
		(net "PWRGD_PVSA_CPU1")
	)
	(segment
		(start 27.876246 -0.091694)
		(end 27.876246 3.012186)
		(width 0.089408)
		(layer "In4.Cu")
		(net "PWRGD_PVSA_CPU1")
	)
	(segment
		(start 24.446992 -31.545276)
		(end 26.12009 -31.545276)
		(width 0.089408)
		(layer "In4.Cu")
		(net "PWRGD_PVSA_CPU1")
	)
	(segment
		(start 20.746212 -38.526466)
		(end 20.197826 -37.97808)
		(width 0.089408)
		(layer "In4.Cu")
		(net "PWRGD_PVSA_CPU1")
	)
	(segment
		(start 28.890976 -22.13737)
		(end 26.87828 -20.124674)
		(width 0.089408)
		(layer "In4.Cu")
		(net "PWRGD_PVSA_CPU1")
	)
	(segment
		(start 184.087008 1.148588)
		(end 186.888628 3.950208)
		(width 0.089408)
		(layer "In4.Cu")
		(net "PWRGD_PVSA_CPU1")
	)
	(segment
		(start 26.87828 -16.047974)
		(end 27.432 -15.494254)
		(width 0.089408)
		(layer "In4.Cu")
		(net "PWRGD_PVSA_CPU1")
	)
	(segment
		(start 171.87672 -3.52552)
		(end 172.39234 -4.04114)
		(width 0.089408)
		(layer "In4.Cu")
		(net "PWRGD_PVSA_CPU1")
	)
	(segment
		(start 20.005548 -37.97808)
		(end 19.411696 -37.384228)
		(width 0.089408)
		(layer "In4.Cu")
		(net "PWRGD_PVSA_CPU1")
	)
	(segment
		(start 19.411696 -36.580572)
		(end 24.446992 -31.545276)
		(width 0.089408)
		(layer "In4.Cu")
		(net "PWRGD_PVSA_CPU1")
	)
	(segment
		(start 22.4282 -52.21478)
		(end 22.4282 -50.66538)
		(width 0.089408)
		(layer "In4.Cu")
		(net "PWRGD_PVSA_CPU1")
	)
	(segment
		(start 183.631078 -0.971042)
		(end 184.087008 -0.515112)
		(width 0.089408)
		(layer "In4.Cu")
		(net "PWRGD_PVSA_CPU1")
	)
	(segment
		(start 15.5956 -81.3308)
		(end 15.5956 -78.58252)
		(width 0.089408)
		(layer "In4.Cu")
		(net "PWRGD_PVSA_CPU1")
	)
	(segment
		(start 328.42073 -19.678396)
		(end 329.883516 -21.141182)
		(width 0.089408)
		(layer "In4.Cu")
		(net "PWRGD_PVSA_CPU1")
	)
	(segment
		(start 20.197826 -37.97808)
		(end 20.005548 -37.97808)
		(width 0.089408)
		(layer "In4.Cu")
		(net "PWRGD_PVSA_CPU1")
	)
	(segment
		(start 22.257512 -72.517254)
		(end 22.0218 -72.281542)
		(width 0.089408)
		(layer "In4.Cu")
		(net "PWRGD_PVSA_CPU1")
	)
	(segment
		(start 20.746212 -39.680388)
		(end 20.746212 -38.526466)
		(width 0.089408)
		(layer "In4.Cu")
		(net "PWRGD_PVSA_CPU1")
	)
	(segment
		(start 324.2564 1.905)
		(end 324.2564 0.432054)
		(width 0.089408)
		(layer "In4.Cu")
		(net "PWRGD_PVSA_CPU1")
	)
	(segment
		(start 326.041512 -19.678396)
		(end 328.42073 -19.678396)
		(width 0.089408)
		(layer "In4.Cu")
		(net "PWRGD_PVSA_CPU1")
	)
	(segment
		(start 324.967346 -18.60423)
		(end 326.041512 -19.678396)
		(width 0.089408)
		(layer "In4.Cu")
		(net "PWRGD_PVSA_CPU1")
	)
	(segment
		(start 22.0218 -72.281542)
		(end 22.0218 -70.5612)
		(width 0.089408)
		(layer "In4.Cu")
		(net "PWRGD_PVSA_CPU1")
	)
	(segment
		(start 165.186106 3.20548)
		(end 165.186106 0.428752)
		(width 0.089408)
		(layer "In4.Cu")
		(net "PWRGD_PVSA_CPU1")
	)
	(segment
		(start 20.603972 -77.889862)
		(end 22.257512 -76.236322)
		(width 0.089408)
		(layer "In4.Cu")
		(net "PWRGD_PVSA_CPU1")
	)
	(segment
		(start 117.110764 4.20116)
		(end 164.190426 4.20116)
		(width 0.089408)
		(layer "In4.Cu")
		(net "PWRGD_PVSA_CPU1")
	)
	(segment
		(start 186.888628 3.950208)
		(end 186.96813 3.950208)
		(width 0.089408)
		(layer "In4.Cu")
		(net "PWRGD_PVSA_CPU1")
	)
	(segment
		(start 172.43552 -4.04114)
		(end 172.441108 -4.046728)
		(width 0.089408)
		(layer "In4.Cu")
		(net "PWRGD_PVSA_CPU1")
	)
	(segment
		(start 173.777148 -4.046728)
		(end 174.016924 -4.286504)
		(width 0.089408)
		(layer "In4.Cu")
		(net "PWRGD_PVSA_CPU1")
	)
	(segment
		(start 176.649126 -3.69824)
		(end 181.760876 -3.69824)
		(width 0.089408)
		(layer "In4.Cu")
		(net "PWRGD_PVSA_CPU1")
	)
	(segment
		(start 166.950136 -2.406142)
		(end 168.069514 -3.52552)
		(width 0.089408)
		(layer "In4.Cu")
		(net "PWRGD_PVSA_CPU1")
	)
	(segment
		(start 27.432 -0.53594)
		(end 27.876246 -0.091694)
		(width 0.089408)
		(layer "In4.Cu")
		(net "PWRGD_PVSA_CPU1")
	)
	(segment
		(start 102.935278 3.532886)
		(end 116.44249 3.532886)
		(width 0.089408)
		(layer "In4.Cu")
		(net "PWRGD_PVSA_CPU1")
	)
	(segment
		(start 172.39234 -4.04114)
		(end 172.43552 -4.04114)
		(width 0.089408)
		(layer "In4.Cu")
		(net "PWRGD_PVSA_CPU1")
	)
	(segment
		(start 164.190426 4.20116)
		(end 165.186106 3.20548)
		(width 0.089408)
		(layer "In4.Cu")
		(net "PWRGD_PVSA_CPU1")
	)
	(segment
		(start 174.016924 -4.286504)
		(end 176.060862 -4.286504)
		(width 0.089408)
		(layer "In4.Cu")
		(net "PWRGD_PVSA_CPU1")
	)
	(segment
		(start 22.0218 -70.5612)
		(end 26.099008 -66.483992)
		(width 0.089408)
		(layer "In4.Cu")
		(net "PWRGD_PVSA_CPU1")
	)
	(segment
		(start 16.288258 -77.889862)
		(end 20.603972 -77.889862)
		(width 0.089408)
		(layer "In4.Cu")
		(net "PWRGD_PVSA_CPU1")
	)
	(segment
		(start 184.087008 -0.515112)
		(end 184.087008 1.148588)
		(width 0.089408)
		(layer "In4.Cu")
		(net "PWRGD_PVSA_CPU1")
	)
	(segment
		(start 20.753832 -39.688008)
		(end 20.746212 -39.680388)
		(width 0.089408)
		(layer "In4.Cu")
		(net "PWRGD_PVSA_CPU1")
	)
	(segment
		(start 19.411696 -37.384228)
		(end 19.411696 -36.580572)
		(width 0.089408)
		(layer "In4.Cu")
		(net "PWRGD_PVSA_CPU1")
	)
	(segment
		(start 176.060862 -4.286504)
		(end 176.649126 -3.69824)
		(width 0.089408)
		(layer "In4.Cu")
		(net "PWRGD_PVSA_CPU1")
	)
	(segment
		(start 116.44249 3.532886)
		(end 117.110764 4.20116)
		(width 0.089408)
		(layer "In4.Cu")
		(net "PWRGD_PVSA_CPU1")
	)
	(segment
		(start 26.099008 -55.885588)
		(end 22.4282 -52.21478)
		(width 0.089408)
		(layer "In4.Cu")
		(net "PWRGD_PVSA_CPU1")
	)
	(segment
		(start 102.378764 4.0894)
		(end 102.935278 3.532886)
		(width 0.089408)
		(layer "In4.Cu")
		(net "PWRGD_PVSA_CPU1")
	)
	(segment
		(start 26.099008 -66.483992)
		(end 26.099008 -55.885588)
		(width 0.089408)
		(layer "In4.Cu")
		(net "PWRGD_PVSA_CPU1")
	)
	(segment
		(start 186.96813 3.950208)
		(end 187.142882 4.12496)
		(width 0.089408)
		(layer "In4.Cu")
		(net "PWRGD_PVSA_CPU1")
	)
	(segment
		(start 26.12009 -31.545276)
		(end 28.890976 -28.77439)
		(width 0.089408)
		(layer "In4.Cu")
		(net "PWRGD_PVSA_CPU1")
	)
	(segment
		(start 15.5956 -78.58252)
		(end 16.288258 -77.889862)
		(width 0.089408)
		(layer "In4.Cu")
		(net "PWRGD_PVSA_CPU1")
	)
	(segment
		(start 28.95346 4.0894)
		(end 102.378764 4.0894)
		(width 0.089408)
		(layer "In4.Cu")
		(net "PWRGD_PVSA_CPU1")
	)
	(segment
		(start 27.432 -15.494254)
		(end 27.432 -0.53594)
		(width 0.089408)
		(layer "In4.Cu")
		(net "PWRGD_PVSA_CPU1")
	)
	(segment
		(start 15.9766 -86.106)
		(end 15.9766 -81.7118)
		(width 0.089408)
		(layer "In4.Cu")
		(net "PWRGD_PVSA_CPU1")
	)
	(segment
		(start 165.186106 0.428752)
		(end 166.950136 -1.335278)
		(width 0.089408)
		(layer "In4.Cu")
		(net "PWRGD_PVSA_CPU1")
	)
	(segment
		(start 20.753832 -48.991012)
		(end 20.753832 -39.688008)
		(width 0.089408)
		(layer "In4.Cu")
		(net "PWRGD_PVSA_CPU1")
	)
	(segment
		(start 183.631078 -1.828038)
		(end 183.631078 -0.971042)
		(width 0.089408)
		(layer "In4.Cu")
		(net "PWRGD_PVSA_CPU1")
	)
	(segment
		(start 324.2564 0.432054)
		(end 324.967346 -0.278892)
		(width 0.089408)
		(layer "In4.Cu")
		(net "PWRGD_PVSA_CPU1")
	)
	(segment
		(start 324.967346 -0.278892)
		(end 324.967346 -18.60423)
		(width 0.089408)
		(layer "In4.Cu")
		(net "PWRGD_PVSA_CPU1")
	)
	(segment
		(start 26.87828 -20.124674)
		(end 26.87828 -16.047974)
		(width 0.089408)
		(layer "In4.Cu")
		(net "PWRGD_PVSA_CPU1")
	)
	(segment
		(start 166.950136 -1.335278)
		(end 166.950136 -2.406142)
		(width 0.089408)
		(layer "In4.Cu")
		(net "PWRGD_PVSA_CPU1")
	)
	(segment
		(start 181.760876 -3.69824)
		(end 183.631078 -1.828038)
		(width 0.089408)
		(layer "In4.Cu")
		(net "PWRGD_PVSA_CPU1")
	)
	(segment
		(start 28.890976 -28.77439)
		(end 28.890976 -22.13737)
		(width 0.089408)
		(layer "In4.Cu")
		(net "PWRGD_PVSA_CPU1")
	)
	(segment
		(start 331.278992 -22.536658)
		(end 329.883516 -21.141182)
		(width 0.089408)
		(layer "In11.Cu")
		(net "PWRGD_PVSA_CPU1")
	)
	(segment
		(start 381.532384 -66.00698)
		(end 381.532384 -64.983868)
		(width 0.089408)
		(layer "In11.Cu")
		(net "PWRGD_PVSA_CPU1")
	)
	(segment
		(start 383.316734 -71.721218)
		(end 383.316734 -70.813422)
		(width 0.089408)
		(layer "In11.Cu")
		(net "PWRGD_PVSA_CPU1")
	)
	(segment
		(start 383.509012 -70.37832)
		(end 383.509012 -67.983608)
		(width 0.089408)
		(layer "In11.Cu")
		(net "PWRGD_PVSA_CPU1")
	)
	(segment
		(start 357.06812 -37.022278)
		(end 354.48621 -37.022278)
		(width 0.089408)
		(layer "In11.Cu")
		(net "PWRGD_PVSA_CPU1")
	)
	(segment
		(start 383.509266 -70.378574)
		(end 383.509012 -70.37832)
		(width 0.089408)
		(layer "In11.Cu")
		(net "PWRGD_PVSA_CPU1")
	)
	(segment
		(start 384.573018 -80.169004)
		(end 384.429 -80.024986)
		(width 0.089408)
		(layer "In11.Cu")
		(net "PWRGD_PVSA_CPU1")
	)
	(segment
		(start 380.235968 -63.871094)
		(end 380.235968 -63.214758)
		(width 0.089408)
		(layer "In11.Cu")
		(net "PWRGD_PVSA_CPU1")
	)
	(segment
		(start 332.667102 -33.321244)
		(end 332.217268 -32.87141)
		(width 0.089408)
		(layer "In11.Cu")
		(net "PWRGD_PVSA_CPU1")
	)
	(segment
		(start 380.623064 -58.02503)
		(end 379.573028 -56.974994)
		(width 0.089408)
		(layer "In11.Cu")
		(net "PWRGD_PVSA_CPU1")
	)
	(segment
		(start 384.429 -76.10602)
		(end 385.356862 -75.178158)
		(width 0.089408)
		(layer "In11.Cu")
		(net "PWRGD_PVSA_CPU1")
	)
	(segment
		(start 336.42808 -38.58768)
		(end 335.964784 -38.124384)
		(width 0.089408)
		(layer "In11.Cu")
		(net "PWRGD_PVSA_CPU1")
	)
	(segment
		(start 384.58013 -72.984614)
		(end 383.316734 -71.721218)
		(width 0.089408)
		(layer "In11.Cu")
		(net "PWRGD_PVSA_CPU1")
	)
	(segment
		(start 380.996952 -62.436756)
		(end 381.000508 -62.4332)
		(width 0.089408)
		(layer "In11.Cu")
		(net "PWRGD_PVSA_CPU1")
	)
	(segment
		(start 373.351552 -51.096926)
		(end 370.204238 -47.949612)
		(width 0.089408)
		(layer "In11.Cu")
		(net "PWRGD_PVSA_CPU1")
	)
	(segment
		(start 384.58013 -73.319386)
		(end 384.58013 -72.984614)
		(width 0.089408)
		(layer "In11.Cu")
		(net "PWRGD_PVSA_CPU1")
	)
	(segment
		(start 385.356608 -74.935588)
		(end 385.356608 -74.095864)
		(width 0.089408)
		(layer "In11.Cu")
		(net "PWRGD_PVSA_CPU1")
	)
	(segment
		(start 381.660654 -59.869832)
		(end 381.660654 -58.753248)
		(width 0.089408)
		(layer "In11.Cu")
		(net "PWRGD_PVSA_CPU1")
	)
	(segment
		(start 381.532638 -64.741298)
		(end 381.105664 -64.314324)
		(width 0.089408)
		(layer "In11.Cu")
		(net "PWRGD_PVSA_CPU1")
	)
	(segment
		(start 331.371956 -32.87141)
		(end 330.257912 -31.757366)
		(width 0.089408)
		(layer "In11.Cu")
		(net "PWRGD_PVSA_CPU1")
	)
	(segment
		(start 381.000508 -62.4332)
		(end 381.00381 -62.4332)
		(width 0.089408)
		(layer "In11.Cu")
		(net "PWRGD_PVSA_CPU1")
	)
	(segment
		(start 380.658878 -64.314324)
		(end 380.606554 -64.262)
		(width 0.089408)
		(layer "In11.Cu")
		(net "PWRGD_PVSA_CPU1")
	)
	(segment
		(start 354.48621 -37.022278)
		(end 352.920808 -38.58768)
		(width 0.089408)
		(layer "In11.Cu")
		(net "PWRGD_PVSA_CPU1")
	)
	(segment
		(start 331.278992 -26.51252)
		(end 331.278992 -22.536658)
		(width 0.089408)
		(layer "In11.Cu")
		(net "PWRGD_PVSA_CPU1")
	)
	(segment
		(start 373.351552 -52.540916)
		(end 373.351552 -51.096926)
		(width 0.089408)
		(layer "In11.Cu")
		(net "PWRGD_PVSA_CPU1")
	)
	(segment
		(start 381.660908 -58.752994)
		(end 381.660908 -58.510678)
		(width 0.089408)
		(layer "In11.Cu")
		(net "PWRGD_PVSA_CPU1")
	)
	(segment
		(start 378.586238 -53.950616)
		(end 374.761252 -53.950616)
		(width 0.089408)
		(layer "In11.Cu")
		(net "PWRGD_PVSA_CPU1")
	)
	(segment
		(start 366.606328 -45.301408)
		(end 365.34725 -45.301408)
		(width 0.089408)
		(layer "In11.Cu")
		(net "PWRGD_PVSA_CPU1")
	)
	(segment
		(start 380.996952 -62.44971)
		(end 380.996952 -62.436756)
		(width 0.089408)
		(layer "In11.Cu")
		(net "PWRGD_PVSA_CPU1")
	)
	(segment
		(start 381.105664 -64.314324)
		(end 380.658878 -64.314324)
		(width 0.089408)
		(layer "In11.Cu")
		(net "PWRGD_PVSA_CPU1")
	)
	(segment
		(start 384.429 -80.024986)
		(end 384.429 -76.10602)
		(width 0.089408)
		(layer "In11.Cu")
		(net "PWRGD_PVSA_CPU1")
	)
	(segment
		(start 385.356862 -75.178158)
		(end 385.356862 -74.935842)
		(width 0.089408)
		(layer "In11.Cu")
		(net "PWRGD_PVSA_CPU1")
	)
	(segment
		(start 330.257912 -31.757366)
		(end 330.257912 -27.5336)
		(width 0.089408)
		(layer "In11.Cu")
		(net "PWRGD_PVSA_CPU1")
	)
	(segment
		(start 379.573028 -56.974994)
		(end 379.573028 -54.937406)
		(width 0.089408)
		(layer "In11.Cu")
		(net "PWRGD_PVSA_CPU1")
	)
	(segment
		(start 369.254532 -47.949612)
		(end 366.606328 -45.301408)
		(width 0.089408)
		(layer "In11.Cu")
		(net "PWRGD_PVSA_CPU1")
	)
	(segment
		(start 330.257912 -27.5336)
		(end 331.278992 -26.51252)
		(width 0.089408)
		(layer "In11.Cu")
		(net "PWRGD_PVSA_CPU1")
	)
	(segment
		(start 381.660654 -58.753248)
		(end 381.660908 -58.752994)
		(width 0.089408)
		(layer "In11.Cu")
		(net "PWRGD_PVSA_CPU1")
	)
	(segment
		(start 365.34725 -45.301408)
		(end 357.06812 -37.022278)
		(width 0.089408)
		(layer "In11.Cu")
		(net "PWRGD_PVSA_CPU1")
	)
	(segment
		(start 381.00381 -60.526676)
		(end 381.660654 -59.869832)
		(width 0.089408)
		(layer "In11.Cu")
		(net "PWRGD_PVSA_CPU1")
	)
	(segment
		(start 385.356608 -74.095864)
		(end 384.58013 -73.319386)
		(width 0.089408)
		(layer "In11.Cu")
		(net "PWRGD_PVSA_CPU1")
	)
	(segment
		(start 334.70723 -38.124384)
		(end 333.54772 -36.964874)
		(width 0.089408)
		(layer "In11.Cu")
		(net "PWRGD_PVSA_CPU1")
	)
	(segment
		(start 381.17526 -58.02503)
		(end 380.623064 -58.02503)
		(width 0.089408)
		(layer "In11.Cu")
		(net "PWRGD_PVSA_CPU1")
	)
	(segment
		(start 370.204238 -47.949612)
		(end 369.254532 -47.949612)
		(width 0.089408)
		(layer "In11.Cu")
		(net "PWRGD_PVSA_CPU1")
	)
	(segment
		(start 381.532384 -64.983868)
		(end 381.532638 -64.983614)
		(width 0.089408)
		(layer "In11.Cu")
		(net "PWRGD_PVSA_CPU1")
	)
	(segment
		(start 381.532638 -64.983614)
		(end 381.532638 -64.741298)
		(width 0.089408)
		(layer "In11.Cu")
		(net "PWRGD_PVSA_CPU1")
	)
	(segment
		(start 335.964784 -38.124384)
		(end 334.70723 -38.124384)
		(width 0.089408)
		(layer "In11.Cu")
		(net "PWRGD_PVSA_CPU1")
	)
	(segment
		(start 381.660908 -58.510678)
		(end 381.17526 -58.02503)
		(width 0.089408)
		(layer "In11.Cu")
		(net "PWRGD_PVSA_CPU1")
	)
	(segment
		(start 332.667102 -35.625024)
		(end 332.667102 -33.321244)
		(width 0.089408)
		(layer "In11.Cu")
		(net "PWRGD_PVSA_CPU1")
	)
	(segment
		(start 333.54772 -36.505642)
		(end 332.667102 -35.625024)
		(width 0.089408)
		(layer "In11.Cu")
		(net "PWRGD_PVSA_CPU1")
	)
	(segment
		(start 333.54772 -36.964874)
		(end 333.54772 -36.505642)
		(width 0.089408)
		(layer "In11.Cu")
		(net "PWRGD_PVSA_CPU1")
	)
	(segment
		(start 380.235968 -63.214758)
		(end 380.233936 -63.212726)
		(width 0.089408)
		(layer "In11.Cu")
		(net "PWRGD_PVSA_CPU1")
	)
	(segment
		(start 383.509266 -70.62089)
		(end 383.509266 -70.378574)
		(width 0.089408)
		(layer "In11.Cu")
		(net "PWRGD_PVSA_CPU1")
	)
	(segment
		(start 380.606554 -64.262)
		(end 380.416054 -64.05118)
		(width 0.089408)
		(layer "In11.Cu")
		(net "PWRGD_PVSA_CPU1")
	)
	(segment
		(start 380.416054 -64.05118)
		(end 380.235968 -63.871094)
		(width 0.089408)
		(layer "In11.Cu")
		(net "PWRGD_PVSA_CPU1")
	)
	(segment
		(start 383.509012 -67.983608)
		(end 381.532384 -66.00698)
		(width 0.089408)
		(layer "In11.Cu")
		(net "PWRGD_PVSA_CPU1")
	)
	(segment
		(start 352.920808 -38.58768)
		(end 336.42808 -38.58768)
		(width 0.089408)
		(layer "In11.Cu")
		(net "PWRGD_PVSA_CPU1")
	)
	(segment
		(start 381.00381 -62.4332)
		(end 381.00381 -60.526676)
		(width 0.089408)
		(layer "In11.Cu")
		(net "PWRGD_PVSA_CPU1")
	)
	(segment
		(start 379.573028 -54.937406)
		(end 378.586238 -53.950616)
		(width 0.089408)
		(layer "In11.Cu")
		(net "PWRGD_PVSA_CPU1")
	)
	(segment
		(start 380.233936 -63.212726)
		(end 380.996952 -62.44971)
		(width 0.089408)
		(layer "In11.Cu")
		(net "PWRGD_PVSA_CPU1")
	)
	(segment
		(start 383.316734 -70.813422)
		(end 383.509266 -70.62089)
		(width 0.089408)
		(layer "In11.Cu")
		(net "PWRGD_PVSA_CPU1")
	)
	(segment
		(start 385.356862 -74.935842)
		(end 385.356608 -74.935588)
		(width 0.089408)
		(layer "In11.Cu")
		(net "PWRGD_PVSA_CPU1")
	)
	(segment
		(start 374.761252 -53.950616)
		(end 373.351552 -52.540916)
		(width 0.089408)
		(layer "In11.Cu")
		(net "PWRGD_PVSA_CPU1")
	)
	(segment
		(start 332.217268 -32.87141)
		(end 331.371956 -32.87141)
		(width 0.089408)
		(layer "In11.Cu")
		(net "PWRGD_PVSA_CPU1")
	)
	(segment
		(start 379.3236 -76.4032)
		(end 379.215396 -76.294996)
		(width 0.10795)
		(layer "F.Cu")
		(net "PWRGD_PVSA_CPU0")
	)
	(segment
		(start 379.215396 -76.294996)
		(end 378.744988 -76.294996)
		(width 0.10795)
		(layer "F.Cu")
		(net "PWRGD_PVSA_CPU0")
	)
	(segment
		(start 182.118 -63.67272)
		(end 182.118 -64.135)
		(width 0.10795)
		(layer "F.Cu")
		(net "PWRGD_PVSA_CPU0")
	)
	(segment
		(start 182.22468 -63.56604)
		(end 182.118 -63.67272)
		(width 0.10795)
		(layer "F.Cu")
		(net "PWRGD_PVSA_CPU0")
	)
	(segment
		(start 182.22468 -63.47968)
		(end 182.22468 -63.56604)
		(width 0.10795)
		(layer "F.Cu")
		(net "PWRGD_PVSA_CPU0")
	)
	(via
		(at 182.22468 -63.47968)
		(size 0.508)
		(drill 0.254)
		(layers "F.Cu" "B.Cu")
		(net "PWRGD_PVSA_CPU0")
	)
	(via
		(at 379.3236 -76.4032)
		(size 0.4572)
		(drill 0.2032)
		(layers "F.Cu" "B.Cu")
		(net "PWRGD_PVSA_CPU0")
	)
	(via
		(at 322.9356 -41.1226)
		(size 0.508)
		(drill 0.254)
		(layers "F.Cu" "B.Cu")
		(net "PWRGD_PVSA_CPU0")
	)
	(via
		(at 189.0268 -26.1112)
		(size 0.508)
		(drill 0.254)
		(layers "F.Cu" "B.Cu")
		(net "PWRGD_PVSA_CPU0")
	)
	(segment
		(start 242.345464 -28.344368)
		(end 241.558572 -29.13126)
		(width 0.089408)
		(layer "In9.Cu")
		(net "PWRGD_PVSA_CPU0")
	)
	(segment
		(start 264.786364 -31.493714)
		(end 262.832342 -29.539692)
		(width 0.089408)
		(layer "In9.Cu")
		(net "PWRGD_PVSA_CPU0")
	)
	(segment
		(start 322.535296 -41.522904)
		(end 313.9313 -41.522904)
		(width 0.089408)
		(layer "In9.Cu")
		(net "PWRGD_PVSA_CPU0")
	)
	(segment
		(start 322.9356 -41.1226)
		(end 322.535296 -41.522904)
		(width 0.089408)
		(layer "In9.Cu")
		(net "PWRGD_PVSA_CPU0")
	)
	(segment
		(start 241.558572 -29.13126)
		(end 224.347532 -29.13126)
		(width 0.089408)
		(layer "In9.Cu")
		(net "PWRGD_PVSA_CPU0")
	)
	(segment
		(start 260.149086 -28.344368)
		(end 242.345464 -28.344368)
		(width 0.089408)
		(layer "In9.Cu")
		(net "PWRGD_PVSA_CPU0")
	)
	(segment
		(start 224.347532 -29.13126)
		(end 222.5548 -27.338528)
		(width 0.089408)
		(layer "In9.Cu")
		(net "PWRGD_PVSA_CPU0")
	)
	(segment
		(start 313.9313 -41.522904)
		(end 303.90211 -31.493714)
		(width 0.089408)
		(layer "In9.Cu")
		(net "PWRGD_PVSA_CPU0")
	)
	(segment
		(start 189.853824 -27.338528)
		(end 189.0268 -26.511504)
		(width 0.089408)
		(layer "In9.Cu")
		(net "PWRGD_PVSA_CPU0")
	)
	(segment
		(start 222.5548 -27.338528)
		(end 189.853824 -27.338528)
		(width 0.089408)
		(layer "In9.Cu")
		(net "PWRGD_PVSA_CPU0")
	)
	(segment
		(start 261.34441 -29.539692)
		(end 260.149086 -28.344368)
		(width 0.089408)
		(layer "In9.Cu")
		(net "PWRGD_PVSA_CPU0")
	)
	(segment
		(start 189.0268 -26.511504)
		(end 189.0268 -26.1112)
		(width 0.089408)
		(layer "In9.Cu")
		(net "PWRGD_PVSA_CPU0")
	)
	(segment
		(start 262.832342 -29.539692)
		(end 261.34441 -29.539692)
		(width 0.089408)
		(layer "In9.Cu")
		(net "PWRGD_PVSA_CPU0")
	)
	(segment
		(start 303.90211 -31.493714)
		(end 264.786364 -31.493714)
		(width 0.089408)
		(layer "In9.Cu")
		(net "PWRGD_PVSA_CPU0")
	)
	(segment
		(start 370.586 -56.769)
		(end 370.90858 -56.769)
		(width 0.089408)
		(layer "In11.Cu")
		(net "PWRGD_PVSA_CPU0")
	)
	(segment
		(start 183.985154 -63.006986)
		(end 184.758076 -62.234064)
		(width 0.089408)
		(layer "In11.Cu")
		(net "PWRGD_PVSA_CPU0")
	)
	(segment
		(start 378.718064 -68.862956)
		(end 378.3584 -69.22262)
		(width 0.089408)
		(layer "In11.Cu")
		(net "PWRGD_PVSA_CPU0")
	)
	(segment
		(start 182.29072 -63.47968)
		(end 182.763414 -63.006986)
		(width 0.089408)
		(layer "In11.Cu")
		(net "PWRGD_PVSA_CPU0")
	)
	(segment
		(start 365.127032 -53.98897)
		(end 367.80597 -53.98897)
		(width 0.089408)
		(layer "In11.Cu")
		(net "PWRGD_PVSA_CPU0")
	)
	(segment
		(start 193.0908 -31.7246)
		(end 189.0268 -27.6606)
		(width 0.089408)
		(layer "In11.Cu")
		(net "PWRGD_PVSA_CPU0")
	)
	(segment
		(start 376.018806 -61.763148)
		(end 376.018552 -61.763402)
		(width 0.089408)
		(layer "In11.Cu")
		(net "PWRGD_PVSA_CPU0")
	)
	(segment
		(start 322.9356 -41.1226)
		(end 322.9356 -41.535096)
		(width 0.089408)
		(layer "In11.Cu")
		(net "PWRGD_PVSA_CPU0")
	)
	(segment
		(start 376.018552 -61.763402)
		(end 376.018552 -63.054992)
		(width 0.089408)
		(layer "In11.Cu")
		(net "PWRGD_PVSA_CPU0")
	)
	(segment
		(start 374.442736 -59.944762)
		(end 376.018806 -61.520832)
		(width 0.089408)
		(layer "In11.Cu")
		(net "PWRGD_PVSA_CPU0")
	)
	(segment
		(start 195.4784 -49.083976)
		(end 195.7832 -48.779176)
		(width 0.089408)
		(layer "In11.Cu")
		(net "PWRGD_PVSA_CPU0")
	)
	(segment
		(start 184.2008 -60.654946)
		(end 184.2008 -54.102)
		(width 0.089408)
		(layer "In11.Cu")
		(net "PWRGD_PVSA_CPU0")
	)
	(segment
		(start 189.0268 -27.6606)
		(end 189.0268 -26.1112)
		(width 0.089408)
		(layer "In11.Cu")
		(net "PWRGD_PVSA_CPU0")
	)
	(segment
		(start 372.676166 -58.641234)
		(end 373.977916 -59.942984)
		(width 0.089408)
		(layer "In11.Cu")
		(net "PWRGD_PVSA_CPU0")
	)
	(segment
		(start 377.971304 -74.288142)
		(end 379.3236 -75.640438)
		(width 0.089408)
		(layer "In11.Cu")
		(net "PWRGD_PVSA_CPU0")
	)
	(segment
		(start 374.057418 -59.942984)
		(end 374.059196 -59.944762)
		(width 0.089408)
		(layer "In11.Cu")
		(net "PWRGD_PVSA_CPU0")
	)
	(segment
		(start 182.22468 -63.47968)
		(end 182.29072 -63.47968)
		(width 0.089408)
		(layer "In11.Cu")
		(net "PWRGD_PVSA_CPU0")
	)
	(segment
		(start 367.80597 -53.98897)
		(end 370.586 -56.769)
		(width 0.089408)
		(layer "In11.Cu")
		(net "PWRGD_PVSA_CPU0")
	)
	(segment
		(start 373.977916 -59.942984)
		(end 374.057418 -59.942984)
		(width 0.089408)
		(layer "In11.Cu")
		(net "PWRGD_PVSA_CPU0")
	)
	(segment
		(start 378.3584 -69.22262)
		(end 378.3584 -70.553326)
		(width 0.089408)
		(layer "In11.Cu")
		(net "PWRGD_PVSA_CPU0")
	)
	(segment
		(start 379.3236 -75.640438)
		(end 379.3236 -76.4032)
		(width 0.089408)
		(layer "In11.Cu")
		(net "PWRGD_PVSA_CPU0")
	)
	(segment
		(start 376.65152 -63.68796)
		(end 376.65152 -65.051686)
		(width 0.089408)
		(layer "In11.Cu")
		(net "PWRGD_PVSA_CPU0")
	)
	(segment
		(start 195.7832 -48.779176)
		(end 195.7832 -46.8376)
		(width 0.089408)
		(layer "In11.Cu")
		(net "PWRGD_PVSA_CPU0")
	)
	(segment
		(start 322.9356 -41.535096)
		(end 328.962512 -47.562008)
		(width 0.089408)
		(layer "In11.Cu")
		(net "PWRGD_PVSA_CPU0")
	)
	(segment
		(start 378.44603 -68.268596)
		(end 378.718064 -68.54063)
		(width 0.089408)
		(layer "In11.Cu")
		(net "PWRGD_PVSA_CPU0")
	)
	(segment
		(start 378.718064 -68.54063)
		(end 378.718064 -68.862956)
		(width 0.089408)
		(layer "In11.Cu")
		(net "PWRGD_PVSA_CPU0")
	)
	(segment
		(start 376.018552 -63.054992)
		(end 376.65152 -63.68796)
		(width 0.089408)
		(layer "In11.Cu")
		(net "PWRGD_PVSA_CPU0")
	)
	(segment
		(start 376.65152 -65.051686)
		(end 376.535696 -65.16751)
		(width 0.089408)
		(layer "In11.Cu")
		(net "PWRGD_PVSA_CPU0")
	)
	(segment
		(start 372.676166 -58.536586)
		(end 372.676166 -58.641234)
		(width 0.089408)
		(layer "In11.Cu")
		(net "PWRGD_PVSA_CPU0")
	)
	(segment
		(start 370.90858 -56.769)
		(end 372.676166 -58.536586)
		(width 0.089408)
		(layer "In11.Cu")
		(net "PWRGD_PVSA_CPU0")
	)
	(segment
		(start 182.763414 -63.006986)
		(end 183.985154 -63.006986)
		(width 0.089408)
		(layer "In11.Cu")
		(net "PWRGD_PVSA_CPU0")
	)
	(segment
		(start 376.535696 -65.16751)
		(end 376.535696 -66.077592)
		(width 0.089408)
		(layer "In11.Cu")
		(net "PWRGD_PVSA_CPU0")
	)
	(segment
		(start 189.218824 -49.083976)
		(end 195.4784 -49.083976)
		(width 0.089408)
		(layer "In11.Cu")
		(net "PWRGD_PVSA_CPU0")
	)
	(segment
		(start 195.7832 -46.8376)
		(end 193.0908 -44.1452)
		(width 0.089408)
		(layer "In11.Cu")
		(net "PWRGD_PVSA_CPU0")
	)
	(segment
		(start 358.70007 -47.562008)
		(end 365.127032 -53.98897)
		(width 0.089408)
		(layer "In11.Cu")
		(net "PWRGD_PVSA_CPU0")
	)
	(segment
		(start 184.758076 -62.234064)
		(end 184.758076 -61.212222)
		(width 0.089408)
		(layer "In11.Cu")
		(net "PWRGD_PVSA_CPU0")
	)
	(segment
		(start 378.3584 -70.553326)
		(end 377.971304 -70.940422)
		(width 0.089408)
		(layer "In11.Cu")
		(net "PWRGD_PVSA_CPU0")
	)
	(segment
		(start 374.059196 -59.944762)
		(end 374.442736 -59.944762)
		(width 0.089408)
		(layer "In11.Cu")
		(net "PWRGD_PVSA_CPU0")
	)
	(segment
		(start 378.44603 -67.987926)
		(end 378.44603 -68.268596)
		(width 0.089408)
		(layer "In11.Cu")
		(net "PWRGD_PVSA_CPU0")
	)
	(segment
		(start 184.2008 -54.102)
		(end 189.218824 -49.083976)
		(width 0.089408)
		(layer "In11.Cu")
		(net "PWRGD_PVSA_CPU0")
	)
	(segment
		(start 376.018806 -61.520832)
		(end 376.018806 -61.763148)
		(width 0.089408)
		(layer "In11.Cu")
		(net "PWRGD_PVSA_CPU0")
	)
	(segment
		(start 376.535696 -66.077592)
		(end 378.44603 -67.987926)
		(width 0.089408)
		(layer "In11.Cu")
		(net "PWRGD_PVSA_CPU0")
	)
	(segment
		(start 328.962512 -47.562008)
		(end 358.70007 -47.562008)
		(width 0.089408)
		(layer "In11.Cu")
		(net "PWRGD_PVSA_CPU0")
	)
	(segment
		(start 193.0908 -44.1452)
		(end 193.0908 -31.7246)
		(width 0.089408)
		(layer "In11.Cu")
		(net "PWRGD_PVSA_CPU0")
	)
	(segment
		(start 184.758076 -61.212222)
		(end 184.2008 -60.654946)
		(width 0.089408)
		(layer "In11.Cu")
		(net "PWRGD_PVSA_CPU0")
	)
	(segment
		(start 377.971304 -70.940422)
		(end 377.971304 -74.288142)
		(width 0.089408)
		(layer "In11.Cu")
		(net "PWRGD_PVSA_CPU0")
	)
	(segment
		(start -3.81 -130.1242)
		(end -4.064 -130.3782)
		(width 0.10795)
		(layer "F.Cu")
		(net "PWRGD_PVDDQ_KLM")
	)
	(segment
		(start -4.5466 -124.333)
		(end -5.2324 -125.0188)
		(width 0.10795)
		(layer "F.Cu")
		(net "PWRGD_PVDDQ_KLM")
	)
	(segment
		(start -3.556 -130.1242)
		(end -3.81 -130.1242)
		(width 0.10795)
		(layer "F.Cu")
		(net "PWRGD_PVDDQ_KLM")
	)
	(segment
		(start -1.41986 -132.969762)
		(end -1.41986 -132.54736)
		(width 0.10795)
		(layer "F.Cu")
		(net "PWRGD_PVDDQ_KLM")
	)
	(segment
		(start -4.064 -130.3782)
		(end -4.3688 -130.3782)
		(width 0.10795)
		(layer "F.Cu")
		(net "PWRGD_PVDDQ_KLM")
	)
	(segment
		(start -1.397 -133.19506)
		(end -1.397 -132.992622)
		(width 0.10795)
		(layer "F.Cu")
		(net "PWRGD_PVDDQ_KLM")
	)
	(segment
		(start -3.556 -129.3622)
		(end -3.556 -130.1242)
		(width 0.10795)
		(layer "F.Cu")
		(net "PWRGD_PVDDQ_KLM")
	)
	(segment
		(start -5.2324 -125.0188)
		(end -5.2324 -128.8796)
		(width 0.10795)
		(layer "F.Cu")
		(net "PWRGD_PVDDQ_KLM")
	)
	(segment
		(start -4.191 -124.333)
		(end -4.5466 -124.333)
		(width 0.10795)
		(layer "F.Cu")
		(net "PWRGD_PVDDQ_KLM")
	)
	(segment
		(start -5.2324 -128.8796)
		(end -4.3688 -129.7432)
		(width 0.10795)
		(layer "F.Cu")
		(net "PWRGD_PVDDQ_KLM")
	)
	(segment
		(start -1.44272 -133.24078)
		(end -1.397 -133.19506)
		(width 0.10795)
		(layer "F.Cu")
		(net "PWRGD_PVDDQ_KLM")
	)
	(segment
		(start -4.3688 -130.3782)
		(end -4.3688 -129.7432)
		(width 0.10795)
		(layer "F.Cu")
		(net "PWRGD_PVDDQ_KLM")
	)
	(segment
		(start -1.397 -132.992622)
		(end -1.41986 -132.969762)
		(width 0.10795)
		(layer "F.Cu")
		(net "PWRGD_PVDDQ_KLM")
	)
	(via
		(at -1.44272 -133.24078)
		(size 0.508)
		(drill 0.254)
		(layers "F.Cu" "B.Cu")
		(net "PWRGD_PVDDQ_KLM")
	)
	(via
		(at -4.3688 -129.7432)
		(size 0.508)
		(drill 0.254)
		(layers "F.Cu" "B.Cu")
		(net "PWRGD_PVDDQ_KLM")
	)
	(via
		(at 12.1412 -123.8504)
		(size 0.508)
		(drill 0.254)
		(layers "F.Cu" "B.Cu")
		(net "PWRGD_PVDDQ_KLM")
	)
	(segment
		(start 12.070334 -123.921266)
		(end 12.1412 -123.8504)
		(width 0.10795)
		(layer "B.Cu")
		(net "PWRGD_PVDDQ_KLM")
	)
	(segment
		(start 11.161268 -123.921266)
		(end 12.070334 -123.921266)
		(width 0.10795)
		(layer "B.Cu")
		(net "PWRGD_PVDDQ_KLM")
	)
	(segment
		(start -4.580636 -129.955036)
		(end -4.3688 -129.7432)
		(width 0.089408)
		(layer "In2.Cu")
		(net "PWRGD_PVDDQ_KLM")
	)
	(segment
		(start -4.580636 -132.037328)
		(end -4.580636 -129.955036)
		(width 0.089408)
		(layer "In2.Cu")
		(net "PWRGD_PVDDQ_KLM")
	)
	(segment
		(start -2.1209 -132.6134)
		(end -4.004564 -132.6134)
		(width 0.089408)
		(layer "In2.Cu")
		(net "PWRGD_PVDDQ_KLM")
	)
	(segment
		(start -4.004564 -132.6134)
		(end -4.580636 -132.037328)
		(width 0.089408)
		(layer "In2.Cu")
		(net "PWRGD_PVDDQ_KLM")
	)
	(segment
		(start -1.44272 -133.24078)
		(end -1.49352 -133.24078)
		(width 0.089408)
		(layer "In2.Cu")
		(net "PWRGD_PVDDQ_KLM")
	)
	(segment
		(start -1.49352 -133.24078)
		(end -2.1209 -132.6134)
		(width 0.089408)
		(layer "In2.Cu")
		(net "PWRGD_PVDDQ_KLM")
	)
	(segment
		(start 0.05842 -125.079252)
		(end 3.41122 -125.079252)
		(width 0.089408)
		(layer "In4.Cu")
		(net "PWRGD_PVDDQ_KLM")
	)
	(segment
		(start -0.877824 -126.015496)
		(end 0.05842 -125.079252)
		(width 0.089408)
		(layer "In4.Cu")
		(net "PWRGD_PVDDQ_KLM")
	)
	(segment
		(start -1.90881 -126.015496)
		(end -0.877824 -126.015496)
		(width 0.089408)
		(layer "In4.Cu")
		(net "PWRGD_PVDDQ_KLM")
	)
	(segment
		(start -4.3688 -129.7432)
		(end -2.89941 -128.27381)
		(width 0.089408)
		(layer "In4.Cu")
		(net "PWRGD_PVDDQ_KLM")
	)
	(segment
		(start -2.89941 -128.27381)
		(end -2.89941 -127.006096)
		(width 0.089408)
		(layer "In4.Cu")
		(net "PWRGD_PVDDQ_KLM")
	)
	(segment
		(start 3.865626 -124.624846)
		(end 7.340092 -124.624846)
		(width 0.089408)
		(layer "In4.Cu")
		(net "PWRGD_PVDDQ_KLM")
	)
	(segment
		(start 3.41122 -125.079252)
		(end 3.865626 -124.624846)
		(width 0.089408)
		(layer "In4.Cu")
		(net "PWRGD_PVDDQ_KLM")
	)
	(segment
		(start 7.340092 -124.624846)
		(end 8.114538 -123.8504)
		(width 0.089408)
		(layer "In4.Cu")
		(net "PWRGD_PVDDQ_KLM")
	)
	(segment
		(start 8.114538 -123.8504)
		(end 12.1412 -123.8504)
		(width 0.089408)
		(layer "In4.Cu")
		(net "PWRGD_PVDDQ_KLM")
	)
	(segment
		(start -2.89941 -127.006096)
		(end -1.90881 -126.015496)
		(width 0.089408)
		(layer "In4.Cu")
		(net "PWRGD_PVDDQ_KLM")
	)
	(segment
		(start 30.615382 -27.82189)
		(end 30.20949 -28.227782)
		(width 0.10795)
		(layer "F.Cu")
		(net "PWRGD_PVDDQ_GHJ")
	)
	(segment
		(start 11.89863 -4.67487)
		(end 11.82878 -4.74472)
		(width 0.10795)
		(layer "F.Cu")
		(net "PWRGD_PVDDQ_GHJ")
	)
	(segment
		(start 11.82878 -4.74472)
		(end 11.82878 -4.770374)
		(width 0.10795)
		(layer "F.Cu")
		(net "PWRGD_PVDDQ_GHJ")
	)
	(segment
		(start 8.818626 -4.246118)
		(end 8.818626 -4.94157)
		(width 0.10795)
		(layer "F.Cu")
		(net "PWRGD_PVDDQ_GHJ")
	)
	(segment
		(start 9.572752 -5.695696)
		(end 11.679174 -5.695696)
		(width 0.10795)
		(layer "F.Cu")
		(net "PWRGD_PVDDQ_GHJ")
	)
	(segment
		(start 8.818626 -4.94157)
		(end 9.572752 -5.695696)
		(width 0.10795)
		(layer "F.Cu")
		(net "PWRGD_PVDDQ_GHJ")
	)
	(segment
		(start 11.905488 -4.42341)
		(end 12.66952 -4.42341)
		(width 0.10795)
		(layer "F.Cu")
		(net "PWRGD_PVDDQ_GHJ")
	)
	(segment
		(start 16.182848 -0.31115)
		(end 16.34617 -0.147828)
		(width 0.10795)
		(layer "F.Cu")
		(net "PWRGD_PVDDQ_GHJ")
	)
	(segment
		(start 16.34617 1.33096)
		(end 16.34617 1.80467)
		(width 0.10795)
		(layer "F.Cu")
		(net "PWRGD_PVDDQ_GHJ")
	)
	(segment
		(start 16.34617 1.80467)
		(end 18.249646 3.708146)
		(width 0.10795)
		(layer "F.Cu")
		(net "PWRGD_PVDDQ_GHJ")
	)
	(segment
		(start 11.8237 -5.55117)
		(end 11.8237 -5.197856)
		(width 0.10795)
		(layer "F.Cu")
		(net "PWRGD_PVDDQ_GHJ")
	)
	(segment
		(start 11.82878 -4.770374)
		(end 11.8237 -4.775454)
		(width 0.10795)
		(layer "F.Cu")
		(net "PWRGD_PVDDQ_GHJ")
	)
	(segment
		(start 20.395946 3.708146)
		(end 20.9042 4.2164)
		(width 0.10795)
		(layer "F.Cu")
		(net "PWRGD_PVDDQ_GHJ")
	)
	(segment
		(start 11.89863 -4.430268)
		(end 11.905488 -4.42341)
		(width 0.10795)
		(layer "F.Cu")
		(net "PWRGD_PVDDQ_GHJ")
	)
	(segment
		(start 11.8237 -4.775454)
		(end 11.8237 -5.197856)
		(width 0.10795)
		(layer "F.Cu")
		(net "PWRGD_PVDDQ_GHJ")
	)
	(segment
		(start 16.34617 -0.147828)
		(end 16.34617 1.33096)
		(width 0.10795)
		(layer "F.Cu")
		(net "PWRGD_PVDDQ_GHJ")
	)
	(segment
		(start 16.182848 -0.733552)
		(end 16.182848 -0.31115)
		(width 0.10795)
		(layer "F.Cu")
		(net "PWRGD_PVDDQ_GHJ")
	)
	(segment
		(start 18.249646 3.708146)
		(end 20.395946 3.708146)
		(width 0.10795)
		(layer "F.Cu")
		(net "PWRGD_PVDDQ_GHJ")
	)
	(segment
		(start 11.89863 -4.430268)
		(end 11.89863 -4.67487)
		(width 0.10795)
		(layer "F.Cu")
		(net "PWRGD_PVDDQ_GHJ")
	)
	(segment
		(start 30.20949 -28.227782)
		(end 30.20949 -30.190694)
		(width 0.10795)
		(layer "F.Cu")
		(net "PWRGD_PVDDQ_GHJ")
	)
	(segment
		(start 11.679174 -5.695696)
		(end 11.8237 -5.55117)
		(width 0.10795)
		(layer "F.Cu")
		(net "PWRGD_PVDDQ_GHJ")
	)
	(via
		(at 16.34617 1.33096)
		(size 0.762)
		(drill 0.381)
		(layers "F.Cu" "B.Cu")
		(net "PWRGD_PVDDQ_GHJ")
	)
	(via
		(at 30.615382 -27.82189)
		(size 0.508)
		(drill 0.254)
		(layers "F.Cu" "B.Cu")
		(net "PWRGD_PVDDQ_GHJ")
	)
	(via
		(at 8.818626 -4.94157)
		(size 0.508)
		(drill 0.254)
		(layers "F.Cu" "B.Cu")
		(net "PWRGD_PVDDQ_GHJ")
	)
	(via
		(at 20.9042 4.2164)
		(size 0.508)
		(drill 0.254)
		(layers "F.Cu" "B.Cu")
		(net "PWRGD_PVDDQ_GHJ")
	)
	(segment
		(start 30.0482 -8.763)
		(end 30.0482 -10.414)
		(width 0.089408)
		(layer "In2.Cu")
		(net "PWRGD_PVDDQ_GHJ")
	)
	(segment
		(start 21.090636 4.2164)
		(end 22.149054 3.157982)
		(width 0.089408)
		(layer "In2.Cu")
		(net "PWRGD_PVDDQ_GHJ")
	)
	(segment
		(start 30.0482 -27.254708)
		(end 30.615382 -27.82189)
		(width 0.089408)
		(layer "In2.Cu")
		(net "PWRGD_PVDDQ_GHJ")
	)
	(segment
		(start 30.988 -17.0688)
		(end 30.4292 -17.6276)
		(width 0.089408)
		(layer "In2.Cu")
		(net "PWRGD_PVDDQ_GHJ")
	)
	(segment
		(start 29.6418 -8.3566)
		(end 30.0482 -8.763)
		(width 0.089408)
		(layer "In2.Cu")
		(net "PWRGD_PVDDQ_GHJ")
	)
	(segment
		(start 25.153112 -0.20447)
		(end 26.599642 -1.651)
		(width 0.089408)
		(layer "In2.Cu")
		(net "PWRGD_PVDDQ_GHJ")
	)
	(segment
		(start 29.6418 -4.191)
		(end 29.6418 -8.3566)
		(width 0.089408)
		(layer "In2.Cu")
		(net "PWRGD_PVDDQ_GHJ")
	)
	(segment
		(start 22.149054 3.157982)
		(end 22.149054 0.930148)
		(width 0.089408)
		(layer "In2.Cu")
		(net "PWRGD_PVDDQ_GHJ")
	)
	(segment
		(start 30.0482 -10.414)
		(end 30.988 -11.3538)
		(width 0.089408)
		(layer "In2.Cu")
		(net "PWRGD_PVDDQ_GHJ")
	)
	(segment
		(start 30.0482 -21.0312)
		(end 30.0482 -27.254708)
		(width 0.089408)
		(layer "In2.Cu")
		(net "PWRGD_PVDDQ_GHJ")
	)
	(segment
		(start 27.1018 -1.651)
		(end 29.6418 -4.191)
		(width 0.089408)
		(layer "In2.Cu")
		(net "PWRGD_PVDDQ_GHJ")
	)
	(segment
		(start 30.4292 -20.6502)
		(end 30.0482 -21.0312)
		(width 0.089408)
		(layer "In2.Cu")
		(net "PWRGD_PVDDQ_GHJ")
	)
	(segment
		(start 30.988 -11.3538)
		(end 30.988 -17.0688)
		(width 0.089408)
		(layer "In2.Cu")
		(net "PWRGD_PVDDQ_GHJ")
	)
	(segment
		(start 23.283672 -0.20447)
		(end 25.153112 -0.20447)
		(width 0.089408)
		(layer "In2.Cu")
		(net "PWRGD_PVDDQ_GHJ")
	)
	(segment
		(start 20.9042 4.2164)
		(end 21.090636 4.2164)
		(width 0.089408)
		(layer "In2.Cu")
		(net "PWRGD_PVDDQ_GHJ")
	)
	(segment
		(start 30.4292 -17.6276)
		(end 30.4292 -20.6502)
		(width 0.089408)
		(layer "In2.Cu")
		(net "PWRGD_PVDDQ_GHJ")
	)
	(segment
		(start 22.149054 0.930148)
		(end 23.283672 -0.20447)
		(width 0.089408)
		(layer "In2.Cu")
		(net "PWRGD_PVDDQ_GHJ")
	)
	(segment
		(start 26.599642 -1.651)
		(end 27.1018 -1.651)
		(width 0.089408)
		(layer "In2.Cu")
		(net "PWRGD_PVDDQ_GHJ")
	)
	(segment
		(start 20.7772 4.1656)
		(end 20.8534 4.1656)
		(width 0.089408)
		(layer "In4.Cu")
		(net "PWRGD_PVDDQ_GHJ")
	)
	(segment
		(start 8.818626 -4.94157)
		(end 8.818626 -4.457954)
		(width 0.089408)
		(layer "In4.Cu")
		(net "PWRGD_PVDDQ_GHJ")
	)
	(segment
		(start 20.8534 4.1656)
		(end 20.9042 4.2164)
		(width 0.089408)
		(layer "In4.Cu")
		(net "PWRGD_PVDDQ_GHJ")
	)
	(segment
		(start 17.00149 2.821432)
		(end 19.433032 2.821432)
		(width 0.089408)
		(layer "In4.Cu")
		(net "PWRGD_PVDDQ_GHJ")
	)
	(segment
		(start 11.433048 -2.843022)
		(end 13.359384 -2.843022)
		(width 0.089408)
		(layer "In4.Cu")
		(net "PWRGD_PVDDQ_GHJ")
	)
	(segment
		(start 9.048496 -4.228084)
		(end 10.047986 -4.228084)
		(width 0.089408)
		(layer "In4.Cu")
		(net "PWRGD_PVDDQ_GHJ")
	)
	(segment
		(start 14.542008 0.36195)
		(end 17.00149 2.821432)
		(width 0.089408)
		(layer "In4.Cu")
		(net "PWRGD_PVDDQ_GHJ")
	)
	(segment
		(start 8.818626 -4.457954)
		(end 9.048496 -4.228084)
		(width 0.089408)
		(layer "In4.Cu")
		(net "PWRGD_PVDDQ_GHJ")
	)
	(segment
		(start 19.433032 2.821432)
		(end 20.7772 4.1656)
		(width 0.089408)
		(layer "In4.Cu")
		(net "PWRGD_PVDDQ_GHJ")
	)
	(segment
		(start 13.359384 -2.843022)
		(end 14.542008 -1.660398)
		(width 0.089408)
		(layer "In4.Cu")
		(net "PWRGD_PVDDQ_GHJ")
	)
	(segment
		(start 14.542008 -1.660398)
		(end 14.542008 0.36195)
		(width 0.089408)
		(layer "In4.Cu")
		(net "PWRGD_PVDDQ_GHJ")
	)
	(segment
		(start 10.047986 -4.228084)
		(end 11.433048 -2.843022)
		(width 0.089408)
		(layer "In4.Cu")
		(net "PWRGD_PVDDQ_GHJ")
	)
	(segment
		(start 363.485938 -131.523994)
		(end 356.983538 -131.523994)
		(width 0.10795)
		(layer "F.Cu")
		(net "PWRGD_PVDDQ_DEF")
	)
	(segment
		(start 356.983538 -131.523994)
		(end 356.368858 -132.138674)
		(width 0.10795)
		(layer "F.Cu")
		(net "PWRGD_PVDDQ_DEF")
	)
	(segment
		(start 364.7694 -134.22884)
		(end 364.323884 -133.783324)
		(width 0.10795)
		(layer "F.Cu")
		(net "PWRGD_PVDDQ_DEF")
	)
	(segment
		(start 187.362592 -126.022862)
		(end 186.882532 -126.022862)
		(width 0.10795)
		(layer "F.Cu")
		(net "PWRGD_PVDDQ_DEF")
	)
	(segment
		(start 365.3536 -135.9916)
		(end 365.5568 -135.7884)
		(width 0.10795)
		(layer "F.Cu")
		(net "PWRGD_PVDDQ_DEF")
	)
	(segment
		(start 365.887 -135.7884)
		(end 365.5568 -135.7884)
		(width 0.089408)
		(layer "F.Cu")
		(net "PWRGD_PVDDQ_DEF")
	)
	(segment
		(start 366.141508 -136.042908)
		(end 365.887 -135.7884)
		(width 0.089408)
		(layer "F.Cu")
		(net "PWRGD_PVDDQ_DEF")
	)
	(segment
		(start 366.141508 -138.683492)
		(end 366.141508 -136.042908)
		(width 0.089408)
		(layer "F.Cu")
		(net "PWRGD_PVDDQ_DEF")
	)
	(segment
		(start 364.744 -140.081)
		(end 366.141508 -138.683492)
		(width 0.089408)
		(layer "F.Cu")
		(net "PWRGD_PVDDQ_DEF")
	)
	(segment
		(start 187.616592 -124.9807)
		(end 187.616592 -125.768862)
		(width 0.10795)
		(layer "F.Cu")
		(net "PWRGD_PVDDQ_DEF")
	)
	(segment
		(start 364.7694 -135.9916)
		(end 364.7694 -134.22884)
		(width 0.10795)
		(layer "F.Cu")
		(net "PWRGD_PVDDQ_DEF")
	)
	(segment
		(start 364.323884 -133.783324)
		(end 364.323884 -132.36194)
		(width 0.10795)
		(layer "F.Cu")
		(net "PWRGD_PVDDQ_DEF")
	)
	(segment
		(start 364.323884 -132.36194)
		(end 363.485938 -131.523994)
		(width 0.10795)
		(layer "F.Cu")
		(net "PWRGD_PVDDQ_DEF")
	)
	(segment
		(start 364.7694 -135.9916)
		(end 364.7694 -136.7536)
		(width 0.10795)
		(layer "F.Cu")
		(net "PWRGD_PVDDQ_DEF")
	)
	(segment
		(start 364.7694 -135.9916)
		(end 365.3536 -135.9916)
		(width 0.10795)
		(layer "F.Cu")
		(net "PWRGD_PVDDQ_DEF")
	)
	(segment
		(start 187.616592 -125.768862)
		(end 187.362592 -126.022862)
		(width 0.10795)
		(layer "F.Cu")
		(net "PWRGD_PVDDQ_DEF")
	)
	(via
		(at 187.616592 -124.9807)
		(size 0.508)
		(drill 0.254)
		(layers "F.Cu" "B.Cu")
		(net "PWRGD_PVDDQ_DEF")
	)
	(via
		(at 187.783978 -152.1079)
		(size 0.508)
		(drill 0.254)
		(layers "F.Cu" "B.Cu")
		(net "PWRGD_PVDDQ_DEF")
	)
	(via
		(at 356.368858 -132.138674)
		(size 0.508)
		(drill 0.254)
		(layers "F.Cu" "B.Cu")
		(net "PWRGD_PVDDQ_DEF")
	)
	(via
		(at 357.4288 -132.461)
		(size 0.6604)
		(drill 0.3302)
		(layers "F.Cu" "B.Cu")
		(net "PWRGD_PVDDQ_DEF")
	)
	(segment
		(start 359.8164 -133.223)
		(end 358.839262 -133.223)
		(width 0.10795)
		(layer "B.Cu")
		(net "PWRGD_PVDDQ_DEF")
	)
	(segment
		(start 358.839262 -133.223)
		(end 358.077262 -132.461)
		(width 0.10795)
		(layer "B.Cu")
		(net "PWRGD_PVDDQ_DEF")
	)
	(segment
		(start 357.4288 -132.461)
		(end 356.691184 -132.461)
		(width 0.10795)
		(layer "B.Cu")
		(net "PWRGD_PVDDQ_DEF")
	)
	(segment
		(start 358.077262 -132.461)
		(end 357.4288 -132.461)
		(width 0.10795)
		(layer "B.Cu")
		(net "PWRGD_PVDDQ_DEF")
	)
	(segment
		(start 356.691184 -132.461)
		(end 356.368858 -132.138674)
		(width 0.10795)
		(layer "B.Cu")
		(net "PWRGD_PVDDQ_DEF")
	)
	(segment
		(start 191.59474 -134.236714)
		(end 191.59474 -136.8679)
		(width 0.089408)
		(layer "In2.Cu")
		(net "PWRGD_PVDDQ_DEF")
	)
	(segment
		(start 189.50178 -152.1079)
		(end 187.783978 -152.1079)
		(width 0.089408)
		(layer "In2.Cu")
		(net "PWRGD_PVDDQ_DEF")
	)
	(segment
		(start 187.616592 -124.9807)
		(end 187.091066 -125.506226)
		(width 0.089408)
		(layer "In2.Cu")
		(net "PWRGD_PVDDQ_DEF")
	)
	(segment
		(start 190.733426 -150.876254)
		(end 189.50178 -152.1079)
		(width 0.089408)
		(layer "In2.Cu")
		(net "PWRGD_PVDDQ_DEF")
	)
	(segment
		(start 187.091066 -131.500626)
		(end 188.42736 -132.83692)
		(width 0.089408)
		(layer "In2.Cu")
		(net "PWRGD_PVDDQ_DEF")
	)
	(segment
		(start 188.42736 -132.83692)
		(end 190.194946 -132.83692)
		(width 0.089408)
		(layer "In2.Cu")
		(net "PWRGD_PVDDQ_DEF")
	)
	(segment
		(start 190.733426 -137.729214)
		(end 190.733426 -150.876254)
		(width 0.089408)
		(layer "In2.Cu")
		(net "PWRGD_PVDDQ_DEF")
	)
	(segment
		(start 187.091066 -125.506226)
		(end 187.091066 -131.500626)
		(width 0.089408)
		(layer "In2.Cu")
		(net "PWRGD_PVDDQ_DEF")
	)
	(segment
		(start 190.194946 -132.83692)
		(end 191.59474 -134.236714)
		(width 0.089408)
		(layer "In2.Cu")
		(net "PWRGD_PVDDQ_DEF")
	)
	(segment
		(start 191.59474 -136.8679)
		(end 190.733426 -137.729214)
		(width 0.089408)
		(layer "In2.Cu")
		(net "PWRGD_PVDDQ_DEF")
	)
	(segment
		(start 339.38591 -134.398766)
		(end 354.108766 -134.398766)
		(width 0.089408)
		(layer "In9.Cu")
		(net "PWRGD_PVDDQ_DEF")
	)
	(segment
		(start 329.164696 -139.211304)
		(end 332.40472 -135.97128)
		(width 0.089408)
		(layer "In9.Cu")
		(net "PWRGD_PVDDQ_DEF")
	)
	(segment
		(start 329.317096 -149.694138)
		(end 329.591924 -149.41931)
		(width 0.089408)
		(layer "In9.Cu")
		(net "PWRGD_PVDDQ_DEF")
	)
	(segment
		(start 328.386948 -152.1079)
		(end 329.317096 -151.177752)
		(width 0.089408)
		(layer "In9.Cu")
		(net "PWRGD_PVDDQ_DEF")
	)
	(segment
		(start 332.40472 -135.97128)
		(end 332.40472 -135.24992)
		(width 0.089408)
		(layer "In9.Cu")
		(net "PWRGD_PVDDQ_DEF")
	)
	(segment
		(start 332.40472 -135.24992)
		(end 334.837532 -132.817108)
		(width 0.089408)
		(layer "In9.Cu")
		(net "PWRGD_PVDDQ_DEF")
	)
	(segment
		(start 329.591924 -143.223742)
		(end 329.164696 -142.796514)
		(width 0.089408)
		(layer "In9.Cu")
		(net "PWRGD_PVDDQ_DEF")
	)
	(segment
		(start 334.837532 -132.817108)
		(end 337.804252 -132.817108)
		(width 0.089408)
		(layer "In9.Cu")
		(net "PWRGD_PVDDQ_DEF")
	)
	(segment
		(start 187.783978 -152.1079)
		(end 328.386948 -152.1079)
		(width 0.089408)
		(layer "In9.Cu")
		(net "PWRGD_PVDDQ_DEF")
	)
	(segment
		(start 354.108766 -134.398766)
		(end 356.368858 -132.138674)
		(width 0.089408)
		(layer "In9.Cu")
		(net "PWRGD_PVDDQ_DEF")
	)
	(segment
		(start 329.591924 -149.41931)
		(end 329.591924 -143.223742)
		(width 0.089408)
		(layer "In9.Cu")
		(net "PWRGD_PVDDQ_DEF")
	)
	(segment
		(start 337.804252 -132.817108)
		(end 339.38591 -134.398766)
		(width 0.089408)
		(layer "In9.Cu")
		(net "PWRGD_PVDDQ_DEF")
	)
	(segment
		(start 329.164696 -142.796514)
		(end 329.164696 -139.211304)
		(width 0.089408)
		(layer "In9.Cu")
		(net "PWRGD_PVDDQ_DEF")
	)
	(segment
		(start 329.317096 -151.177752)
		(end 329.317096 -149.694138)
		(width 0.089408)
		(layer "In9.Cu")
		(net "PWRGD_PVDDQ_DEF")
	)
	(segment
		(start 337.947 -18.923)
		(end 337.947 -18.161)
		(width 0.10795)
		(layer "F.Cu")
		(net "PWRGD_PVDDQ_ABC")
	)
	(segment
		(start 182.604664 -23.481284)
		(end 182.200804 -23.077424)
		(width 0.10795)
		(layer "F.Cu")
		(net "PWRGD_PVDDQ_ABC")
	)
	(segment
		(start 177.128424 -23.077424)
		(end 177.0634 -23.0124)
		(width 0.10795)
		(layer "F.Cu")
		(net "PWRGD_PVDDQ_ABC")
	)
	(segment
		(start 178.8541 -4.9911)
		(end 178.8541 -4.1529)
		(width 0.10795)
		(layer "F.Cu")
		(net "PWRGD_PVDDQ_ABC")
	)
	(segment
		(start 337.947 -14.732)
		(end 337.312 -14.732)
		(width 0.10795)
		(layer "F.Cu")
		(net "PWRGD_PVDDQ_ABC")
	)
	(segment
		(start 179.7304 3.694176)
		(end 180.692806 4.656582)
		(width 0.10795)
		(layer "F.Cu")
		(net "PWRGD_PVDDQ_ABC")
	)
	(segment
		(start 336.9564 -18.7706)
		(end 336.9564 -19.6596)
		(width 0.10795)
		(layer "F.Cu")
		(net "PWRGD_PVDDQ_ABC")
	)
	(segment
		(start 182.200804 -23.077424)
		(end 177.128424 -23.077424)
		(width 0.10795)
		(layer "F.Cu")
		(net "PWRGD_PVDDQ_ABC")
	)
	(segment
		(start 337.947 -18.923)
		(end 337.693 -18.923)
		(width 0.10795)
		(layer "F.Cu")
		(net "PWRGD_PVDDQ_ABC")
	)
	(segment
		(start 337.693 -18.923)
		(end 336.9564 -19.6596)
		(width 0.10795)
		(layer "F.Cu")
		(net "PWRGD_PVDDQ_ABC")
	)
	(segment
		(start 336.7278 -15.989554)
		(end 336.7278 -18.542)
		(width 0.10795)
		(layer "F.Cu")
		(net "PWRGD_PVDDQ_ABC")
	)
	(segment
		(start 337.100672 -15.616682)
		(end 336.7278 -15.989554)
		(width 0.10795)
		(layer "F.Cu")
		(net "PWRGD_PVDDQ_ABC")
	)
	(segment
		(start 337.100672 -14.943328)
		(end 337.100672 -15.616682)
		(width 0.10795)
		(layer "F.Cu")
		(net "PWRGD_PVDDQ_ABC")
	)
	(segment
		(start 180.692806 4.656582)
		(end 181.311296 4.656582)
		(width 0.10795)
		(layer "F.Cu")
		(net "PWRGD_PVDDQ_ABC")
	)
	(segment
		(start 179.7304 -3.2766)
		(end 179.7304 3.694176)
		(width 0.10795)
		(layer "F.Cu")
		(net "PWRGD_PVDDQ_ABC")
	)
	(segment
		(start 178.8541 -4.1529)
		(end 179.7304 -3.2766)
		(width 0.10795)
		(layer "F.Cu")
		(net "PWRGD_PVDDQ_ABC")
	)
	(segment
		(start 336.7278 -18.542)
		(end 336.9564 -18.7706)
		(width 0.10795)
		(layer "F.Cu")
		(net "PWRGD_PVDDQ_ABC")
	)
	(segment
		(start 342.265 -20.447)
		(end 342.265 -21.082)
		(width 0.10795)
		(layer "F.Cu")
		(net "PWRGD_PVDDQ_ABC")
	)
	(segment
		(start 337.312 -14.732)
		(end 337.100672 -14.943328)
		(width 0.10795)
		(layer "F.Cu")
		(net "PWRGD_PVDDQ_ABC")
	)
	(via
		(at 337.100672 -15.616682)
		(size 0.508)
		(drill 0.254)
		(layers "F.Cu" "B.Cu")
		(net "PWRGD_PVDDQ_ABC")
	)
	(via
		(at 342.265 -21.082)
		(size 0.508)
		(drill 0.254)
		(layers "F.Cu" "B.Cu")
		(net "PWRGD_PVDDQ_ABC")
	)
	(via
		(at 181.311296 4.656582)
		(size 0.508)
		(drill 0.254)
		(layers "F.Cu" "B.Cu")
		(net "PWRGD_PVDDQ_ABC")
	)
	(via
		(at 190.9064 -10.414)
		(size 0.508)
		(drill 0.254)
		(layers "F.Cu" "B.Cu")
		(net "PWRGD_PVDDQ_ABC")
	)
	(via
		(at 177.0634 -23.0124)
		(size 0.508)
		(drill 0.254)
		(layers "F.Cu" "B.Cu")
		(net "PWRGD_PVDDQ_ABC")
	)
	(via
		(at 178.8541 -4.9911)
		(size 0.508)
		(drill 0.254)
		(layers "F.Cu" "B.Cu")
		(net "PWRGD_PVDDQ_ABC")
	)
	(via
		(at 331.38999 -20.022058)
		(size 0.508)
		(drill 0.254)
		(layers "F.Cu" "B.Cu")
		(net "PWRGD_PVDDQ_ABC")
	)
	(segment
		(start 333.50708 -20.7264)
		(end 332.086712 -20.7264)
		(width 0.10795)
		(layer "B.Cu")
		(net "PWRGD_PVDDQ_ABC")
	)
	(segment
		(start 341.46236 -20.066)
		(end 334.16748 -20.066)
		(width 0.10795)
		(layer "B.Cu")
		(net "PWRGD_PVDDQ_ABC")
	)
	(segment
		(start 331.38618 -20.025868)
		(end 331.38618 -20.022058)
		(width 0.10795)
		(layer "B.Cu")
		(net "PWRGD_PVDDQ_ABC")
	)
	(segment
		(start 342.265 -21.082)
		(end 342.265 -20.86864)
		(width 0.10795)
		(layer "B.Cu")
		(net "PWRGD_PVDDQ_ABC")
	)
	(segment
		(start 334.16748 -20.066)
		(end 333.50708 -20.7264)
		(width 0.10795)
		(layer "B.Cu")
		(net "PWRGD_PVDDQ_ABC")
	)
	(segment
		(start 331.38618 -20.022058)
		(end 331.38999 -20.022058)
		(width 0.10795)
		(layer "B.Cu")
		(net "PWRGD_PVDDQ_ABC")
	)
	(segment
		(start 342.265 -20.86864)
		(end 341.46236 -20.066)
		(width 0.10795)
		(layer "B.Cu")
		(net "PWRGD_PVDDQ_ABC")
	)
	(segment
		(start 332.086712 -20.7264)
		(end 331.38618 -20.025868)
		(width 0.10795)
		(layer "B.Cu")
		(net "PWRGD_PVDDQ_ABC")
	)
	(segment
		(start 183.8706 -22.6568)
		(end 183.8706 -19.39163)
		(width 0.089408)
		(layer "In2.Cu")
		(net "PWRGD_PVDDQ_ABC")
	)
	(segment
		(start 184.8358 -18.42643)
		(end 184.8358 -16.15948)
		(width 0.089408)
		(layer "In2.Cu")
		(net "PWRGD_PVDDQ_ABC")
	)
	(segment
		(start 330.5556 -18.3642)
		(end 330.5556 -19.187668)
		(width 0.089408)
		(layer "In2.Cu")
		(net "PWRGD_PVDDQ_ABC")
	)
	(segment
		(start 329.8698 3.077718)
		(end 329.8698 -4.987544)
		(width 0.089408)
		(layer "In2.Cu")
		(net "PWRGD_PVDDQ_ABC")
	)
	(segment
		(start 321.7672 4.034536)
		(end 323.028056 5.295392)
		(width 0.089408)
		(layer "In2.Cu")
		(net "PWRGD_PVDDQ_ABC")
	)
	(segment
		(start 329.8698 -4.987544)
		(end 330.0984 -5.216144)
		(width 0.089408)
		(layer "In2.Cu")
		(net "PWRGD_PVDDQ_ABC")
	)
	(segment
		(start 181.311296 4.656582)
		(end 181.925214 5.2705)
		(width 0.089408)
		(layer "In2.Cu")
		(net "PWRGD_PVDDQ_ABC")
	)
	(segment
		(start 186.312302 -14.682978)
		(end 189.710822 -14.682978)
		(width 0.089408)
		(layer "In2.Cu")
		(net "PWRGD_PVDDQ_ABC")
	)
	(segment
		(start 190.9064 -13.4874)
		(end 190.9064 -10.414)
		(width 0.089408)
		(layer "In2.Cu")
		(net "PWRGD_PVDDQ_ABC")
	)
	(segment
		(start 323.028056 5.295392)
		(end 330.182728 5.295392)
		(width 0.089408)
		(layer "In2.Cu")
		(net "PWRGD_PVDDQ_ABC")
	)
	(segment
		(start 267.075666 4.034536)
		(end 321.7672 4.034536)
		(width 0.089408)
		(layer "In2.Cu")
		(net "PWRGD_PVDDQ_ABC")
	)
	(segment
		(start 189.710822 -14.682978)
		(end 190.9064 -13.4874)
		(width 0.089408)
		(layer "In2.Cu")
		(net "PWRGD_PVDDQ_ABC")
	)
	(segment
		(start 330.5556 -19.187668)
		(end 331.38999 -20.022058)
		(width 0.089408)
		(layer "In2.Cu")
		(net "PWRGD_PVDDQ_ABC")
	)
	(segment
		(start 330.182728 5.295392)
		(end 330.546202 4.931918)
		(width 0.089408)
		(layer "In2.Cu")
		(net "PWRGD_PVDDQ_ABC")
	)
	(segment
		(start 183.3626 -23.1648)
		(end 183.8706 -22.6568)
		(width 0.089408)
		(layer "In2.Cu")
		(net "PWRGD_PVDDQ_ABC")
	)
	(segment
		(start 330.0984 -5.216144)
		(end 330.0984 -13.34262)
		(width 0.089408)
		(layer "In2.Cu")
		(net "PWRGD_PVDDQ_ABC")
	)
	(segment
		(start 329.256644 -17.065244)
		(end 330.5556 -18.3642)
		(width 0.089408)
		(layer "In2.Cu")
		(net "PWRGD_PVDDQ_ABC")
	)
	(segment
		(start 177.0634 -23.0124)
		(end 177.2158 -23.1648)
		(width 0.089408)
		(layer "In2.Cu")
		(net "PWRGD_PVDDQ_ABC")
	)
	(segment
		(start 184.8358 -16.15948)
		(end 186.312302 -14.682978)
		(width 0.089408)
		(layer "In2.Cu")
		(net "PWRGD_PVDDQ_ABC")
	)
	(segment
		(start 265.839702 5.2705)
		(end 267.075666 4.034536)
		(width 0.089408)
		(layer "In2.Cu")
		(net "PWRGD_PVDDQ_ABC")
	)
	(segment
		(start 183.8706 -19.39163)
		(end 184.8358 -18.42643)
		(width 0.089408)
		(layer "In2.Cu")
		(net "PWRGD_PVDDQ_ABC")
	)
	(segment
		(start 329.256644 -14.184376)
		(end 329.256644 -17.065244)
		(width 0.089408)
		(layer "In2.Cu")
		(net "PWRGD_PVDDQ_ABC")
	)
	(segment
		(start 330.546202 4.931918)
		(end 330.546202 3.75412)
		(width 0.089408)
		(layer "In2.Cu")
		(net "PWRGD_PVDDQ_ABC")
	)
	(segment
		(start 330.546202 3.75412)
		(end 329.8698 3.077718)
		(width 0.089408)
		(layer "In2.Cu")
		(net "PWRGD_PVDDQ_ABC")
	)
	(segment
		(start 181.925214 5.2705)
		(end 265.839702 5.2705)
		(width 0.089408)
		(layer "In2.Cu")
		(net "PWRGD_PVDDQ_ABC")
	)
	(segment
		(start 330.0984 -13.34262)
		(end 329.256644 -14.184376)
		(width 0.089408)
		(layer "In2.Cu")
		(net "PWRGD_PVDDQ_ABC")
	)
	(segment
		(start 177.2158 -23.1648)
		(end 183.3626 -23.1648)
		(width 0.089408)
		(layer "In2.Cu")
		(net "PWRGD_PVDDQ_ABC")
	)
	(segment
		(start 184.15 -4.191)
		(end 185.187082 -3.153918)
		(width 0.089408)
		(layer "In11.Cu")
		(net "PWRGD_PVDDQ_ABC")
	)
	(segment
		(start 190.9064 -7.5692)
		(end 190.9064 -10.414)
		(width 0.089408)
		(layer "In11.Cu")
		(net "PWRGD_PVDDQ_ABC")
	)
	(segment
		(start 337.649312 -16.165322)
		(end 337.649312 -19.719544)
		(width 0.089408)
		(layer "In11.Cu")
		(net "PWRGD_PVDDQ_ABC")
	)
	(segment
		(start 341.81542 -21.554948)
		(end 342.265 -21.105368)
		(width 0.089408)
		(layer "In11.Cu")
		(net "PWRGD_PVDDQ_ABC")
	)
	(segment
		(start 185.187082 -3.153918)
		(end 186.491118 -3.153918)
		(width 0.089408)
		(layer "In11.Cu")
		(net "PWRGD_PVDDQ_ABC")
	)
	(segment
		(start 186.491118 -3.153918)
		(end 190.9064 -7.5692)
		(width 0.089408)
		(layer "In11.Cu")
		(net "PWRGD_PVDDQ_ABC")
	)
	(segment
		(start 339.484716 -21.554948)
		(end 341.81542 -21.554948)
		(width 0.089408)
		(layer "In11.Cu")
		(net "PWRGD_PVDDQ_ABC")
	)
	(segment
		(start 342.265 -21.105368)
		(end 342.265 -21.082)
		(width 0.089408)
		(layer "In11.Cu")
		(net "PWRGD_PVDDQ_ABC")
	)
	(segment
		(start 337.100672 -15.616682)
		(end 337.649312 -16.165322)
		(width 0.089408)
		(layer "In11.Cu")
		(net "PWRGD_PVDDQ_ABC")
	)
	(segment
		(start 179.6542 -4.191)
		(end 184.15 -4.191)
		(width 0.089408)
		(layer "In11.Cu")
		(net "PWRGD_PVDDQ_ABC")
	)
	(segment
		(start 337.649312 -19.719544)
		(end 339.484716 -21.554948)
		(width 0.089408)
		(layer "In11.Cu")
		(net "PWRGD_PVDDQ_ABC")
	)
	(segment
		(start 178.8541 -4.9911)
		(end 179.6542 -4.191)
		(width 0.089408)
		(layer "In11.Cu")
		(net "PWRGD_PVDDQ_ABC")
	)
	(segment
		(start 379.895354 -79.0829)
		(end 378.744988 -77.932534)
		(width 0.10795)
		(layer "F.Cu")
		(net "PWRGD_PVCCIN_CPU1")
	)
	(segment
		(start 18.813526 -22.1742)
		(end 19.330924 -22.691598)
		(width 0.10795)
		(layer "F.Cu")
		(net "PWRGD_PVCCIN_CPU1")
	)
	(segment
		(start 13.843 -88.4936)
		(end 13.756386 -88.4936)
		(width 0.10795)
		(layer "F.Cu")
		(net "PWRGD_PVCCIN_CPU1")
	)
	(segment
		(start 9.688068 -24.634444)
		(end 12.148312 -22.1742)
		(width 0.10795)
		(layer "F.Cu")
		(net "PWRGD_PVCCIN_CPU1")
	)
	(segment
		(start 378.744988 -77.932534)
		(end 378.744988 -77.894942)
		(width 0.10795)
		(layer "F.Cu")
		(net "PWRGD_PVCCIN_CPU1")
	)
	(segment
		(start 9.688068 -34.491168)
		(end 9.688068 -24.634444)
		(width 0.10795)
		(layer "F.Cu")
		(net "PWRGD_PVCCIN_CPU1")
	)
	(segment
		(start 12.148312 -22.1742)
		(end 18.813526 -22.1742)
		(width 0.10795)
		(layer "F.Cu")
		(net "PWRGD_PVCCIN_CPU1")
	)
	(segment
		(start 9.407398 -35.15995)
		(end 9.407398 -34.771838)
		(width 0.10795)
		(layer "F.Cu")
		(net "PWRGD_PVCCIN_CPU1")
	)
	(segment
		(start 9.407398 -34.771838)
		(end 9.688068 -34.491168)
		(width 0.10795)
		(layer "F.Cu")
		(net "PWRGD_PVCCIN_CPU1")
	)
	(segment
		(start 13.756386 -88.4936)
		(end 13.188442 -87.925656)
		(width 0.10795)
		(layer "F.Cu")
		(net "PWRGD_PVCCIN_CPU1")
	)
	(via
		(at 13.188442 -87.925656)
		(size 0.508)
		(drill 0.254)
		(layers "F.Cu" "B.Cu")
		(net "PWRGD_PVCCIN_CPU1")
	)
	(via
		(at 168.3258 4.5466)
		(size 0.508)
		(drill 0.254)
		(layers "F.Cu" "B.Cu")
		(net "PWRGD_PVCCIN_CPU1")
	)
	(via
		(at 23.749 4.572)
		(size 0.508)
		(drill 0.254)
		(layers "F.Cu" "B.Cu")
		(net "PWRGD_PVCCIN_CPU1")
	)
	(via
		(at 9.407398 -35.15995)
		(size 0.508)
		(drill 0.254)
		(layers "F.Cu" "B.Cu")
		(net "PWRGD_PVCCIN_CPU1")
	)
	(via
		(at 19.330924 -22.691598)
		(size 0.508)
		(drill 0.254)
		(layers "F.Cu" "B.Cu")
		(net "PWRGD_PVCCIN_CPU1")
	)
	(via
		(at 379.895354 -79.0829)
		(size 0.4572)
		(drill 0.2032)
		(layers "F.Cu" "B.Cu")
		(net "PWRGD_PVCCIN_CPU1")
	)
	(segment
		(start 23.749 4.572)
		(end 22.021038 2.844038)
		(width 0.10795)
		(layer "B.Cu")
		(net "PWRGD_PVCCIN_CPU1")
	)
	(segment
		(start 22.021038 2.50825)
		(end 22.037548 2.49174)
		(width 0.10795)
		(layer "B.Cu")
		(net "PWRGD_PVCCIN_CPU1")
	)
	(segment
		(start 22.021038 2.844038)
		(end 22.021038 2.50825)
		(width 0.10795)
		(layer "B.Cu")
		(net "PWRGD_PVCCIN_CPU1")
	)
	(segment
		(start 20.264374 -22.691598)
		(end 19.330924 -22.691598)
		(width 0.10795)
		(layer "B.Cu")
		(net "PWRGD_PVCCIN_CPU1")
	)
	(segment
		(start 22.037548 -20.918424)
		(end 20.264374 -22.691598)
		(width 0.10795)
		(layer "B.Cu")
		(net "PWRGD_PVCCIN_CPU1")
	)
	(segment
		(start 22.037548 2.49174)
		(end 22.037548 -20.918424)
		(width 0.10795)
		(layer "B.Cu")
		(net "PWRGD_PVCCIN_CPU1")
	)
	(segment
		(start 13.0556 -78.443582)
		(end 13.0556 -68.419472)
		(width 0.089408)
		(layer "In4.Cu")
		(net "PWRGD_PVCCIN_CPU1")
	)
	(segment
		(start 10.37082 -37.57422)
		(end 9.241282 -36.444682)
		(width 0.089408)
		(layer "In4.Cu")
		(net "PWRGD_PVCCIN_CPU1")
	)
	(segment
		(start 12.096496 -86.690962)
		(end 12.096496 -84.413344)
		(width 0.089408)
		(layer "In4.Cu")
		(net "PWRGD_PVCCIN_CPU1")
	)
	(segment
		(start 12.036298 -49.892458)
		(end 14.166342 -47.762414)
		(width 0.089408)
		(layer "In4.Cu")
		(net "PWRGD_PVCCIN_CPU1")
	)
	(segment
		(start 9.241282 -35.326066)
		(end 9.407398 -35.15995)
		(width 0.089408)
		(layer "In4.Cu")
		(net "PWRGD_PVCCIN_CPU1")
	)
	(segment
		(start 12.036298 -67.40017)
		(end 12.036298 -49.892458)
		(width 0.089408)
		(layer "In4.Cu")
		(net "PWRGD_PVCCIN_CPU1")
	)
	(segment
		(start 10.37082 -38.749986)
		(end 10.37082 -37.57422)
		(width 0.089408)
		(layer "In4.Cu")
		(net "PWRGD_PVCCIN_CPU1")
	)
	(segment
		(start 12.102846 -79.396336)
		(end 13.0556 -78.443582)
		(width 0.089408)
		(layer "In4.Cu")
		(net "PWRGD_PVCCIN_CPU1")
	)
	(segment
		(start 11.945366 -40.324532)
		(end 10.37082 -38.749986)
		(width 0.089408)
		(layer "In4.Cu")
		(net "PWRGD_PVCCIN_CPU1")
	)
	(segment
		(start 14.259306 -41.802304)
		(end 14.259306 -41.28262)
		(width 0.089408)
		(layer "In4.Cu")
		(net "PWRGD_PVCCIN_CPU1")
	)
	(segment
		(start 12.096496 -84.413344)
		(end 12.9286 -83.58124)
		(width 0.089408)
		(layer "In4.Cu")
		(net "PWRGD_PVCCIN_CPU1")
	)
	(segment
		(start 14.166342 -41.895268)
		(end 14.259306 -41.802304)
		(width 0.089408)
		(layer "In4.Cu")
		(net "PWRGD_PVCCIN_CPU1")
	)
	(segment
		(start 12.9286 -83.58124)
		(end 12.9286 -81.95818)
		(width 0.089408)
		(layer "In4.Cu")
		(net "PWRGD_PVCCIN_CPU1")
	)
	(segment
		(start 12.330938 -86.925404)
		(end 12.096496 -86.690962)
		(width 0.089408)
		(layer "In4.Cu")
		(net "PWRGD_PVCCIN_CPU1")
	)
	(segment
		(start 13.301218 -40.324532)
		(end 11.945366 -40.324532)
		(width 0.089408)
		(layer "In4.Cu")
		(net "PWRGD_PVCCIN_CPU1")
	)
	(segment
		(start 13.0556 -68.419472)
		(end 12.036298 -67.40017)
		(width 0.089408)
		(layer "In4.Cu")
		(net "PWRGD_PVCCIN_CPU1")
	)
	(segment
		(start 13.188442 -87.925656)
		(end 13.188442 -87.44839)
		(width 0.089408)
		(layer "In4.Cu")
		(net "PWRGD_PVCCIN_CPU1")
	)
	(segment
		(start 14.259306 -41.28262)
		(end 13.301218 -40.324532)
		(width 0.089408)
		(layer "In4.Cu")
		(net "PWRGD_PVCCIN_CPU1")
	)
	(segment
		(start 14.166342 -47.762414)
		(end 14.166342 -41.895268)
		(width 0.089408)
		(layer "In4.Cu")
		(net "PWRGD_PVCCIN_CPU1")
	)
	(segment
		(start 9.241282 -36.444682)
		(end 9.241282 -35.326066)
		(width 0.089408)
		(layer "In4.Cu")
		(net "PWRGD_PVCCIN_CPU1")
	)
	(segment
		(start 12.102846 -81.132426)
		(end 12.102846 -79.396336)
		(width 0.089408)
		(layer "In4.Cu")
		(net "PWRGD_PVCCIN_CPU1")
	)
	(segment
		(start 12.665456 -86.925404)
		(end 12.330938 -86.925404)
		(width 0.089408)
		(layer "In4.Cu")
		(net "PWRGD_PVCCIN_CPU1")
	)
	(segment
		(start 13.188442 -87.44839)
		(end 12.665456 -86.925404)
		(width 0.089408)
		(layer "In4.Cu")
		(net "PWRGD_PVCCIN_CPU1")
	)
	(segment
		(start 12.9286 -81.95818)
		(end 12.102846 -81.132426)
		(width 0.089408)
		(layer "In4.Cu")
		(net "PWRGD_PVCCIN_CPU1")
	)
	(segment
		(start 168.148 4.953)
		(end 167.259 4.953)
		(width 0.089408)
		(layer "In9.Cu")
		(net "PWRGD_PVCCIN_CPU1")
	)
	(segment
		(start 165.227 5.08)
		(end 164.719 5.08)
		(width 0.089408)
		(layer "In9.Cu")
		(net "PWRGD_PVCCIN_CPU1")
	)
	(segment
		(start 167.005 4.699)
		(end 165.608 4.699)
		(width 0.089408)
		(layer "In9.Cu")
		(net "PWRGD_PVCCIN_CPU1")
	)
	(segment
		(start 24.921464 5.398008)
		(end 24.095456 4.572)
		(width 0.089408)
		(layer "In9.Cu")
		(net "PWRGD_PVCCIN_CPU1")
	)
	(segment
		(start 103.263446 5.398008)
		(end 24.921464 5.398008)
		(width 0.089408)
		(layer "In9.Cu")
		(net "PWRGD_PVCCIN_CPU1")
	)
	(segment
		(start 168.3258 4.5466)
		(end 168.3258 4.7752)
		(width 0.089408)
		(layer "In9.Cu")
		(net "PWRGD_PVCCIN_CPU1")
	)
	(segment
		(start 164.592 5.207)
		(end 116.106448 5.207)
		(width 0.089408)
		(layer "In9.Cu")
		(net "PWRGD_PVCCIN_CPU1")
	)
	(segment
		(start 167.259 4.953)
		(end 167.005 4.699)
		(width 0.089408)
		(layer "In9.Cu")
		(net "PWRGD_PVCCIN_CPU1")
	)
	(segment
		(start 116.106448 5.207)
		(end 115.566952 4.667504)
		(width 0.089408)
		(layer "In9.Cu")
		(net "PWRGD_PVCCIN_CPU1")
	)
	(segment
		(start 103.99395 4.667504)
		(end 103.263446 5.398008)
		(width 0.089408)
		(layer "In9.Cu")
		(net "PWRGD_PVCCIN_CPU1")
	)
	(segment
		(start 164.719 5.08)
		(end 164.592 5.207)
		(width 0.089408)
		(layer "In9.Cu")
		(net "PWRGD_PVCCIN_CPU1")
	)
	(segment
		(start 24.095456 4.572)
		(end 23.749 4.572)
		(width 0.089408)
		(layer "In9.Cu")
		(net "PWRGD_PVCCIN_CPU1")
	)
	(segment
		(start 115.566952 4.667504)
		(end 103.99395 4.667504)
		(width 0.089408)
		(layer "In9.Cu")
		(net "PWRGD_PVCCIN_CPU1")
	)
	(segment
		(start 165.608 4.699)
		(end 165.227 5.08)
		(width 0.089408)
		(layer "In9.Cu")
		(net "PWRGD_PVCCIN_CPU1")
	)
	(segment
		(start 168.3258 4.7752)
		(end 168.148 4.953)
		(width 0.089408)
		(layer "In9.Cu")
		(net "PWRGD_PVCCIN_CPU1")
	)
	(segment
		(start 380.596394 -71.985886)
		(end 381.319278 -71.263002)
		(width 0.089408)
		(layer "In11.Cu")
		(net "PWRGD_PVCCIN_CPU1")
	)
	(segment
		(start 179.761896 1.335786)
		(end 179.761896 -0.99187)
		(width 0.089408)
		(layer "In11.Cu")
		(net "PWRGD_PVCCIN_CPU1")
	)
	(segment
		(start 380.612904 -73.510648)
		(end 380.596394 -73.494138)
		(width 0.089408)
		(layer "In11.Cu")
		(net "PWRGD_PVCCIN_CPU1")
	)
	(segment
		(start 378.871734 -60.361068)
		(end 378.871734 -59.193176)
		(width 0.089408)
		(layer "In11.Cu")
		(net "PWRGD_PVCCIN_CPU1")
	)
	(segment
		(start 371.418358 -51.972972)
		(end 367.430812 -47.985426)
		(width 0.089408)
		(layer "In11.Cu")
		(net "PWRGD_PVCCIN_CPU1")
	)
	(segment
		(start 181.332886 2.906776)
		(end 179.761896 1.335786)
		(width 0.089408)
		(layer "In11.Cu")
		(net "PWRGD_PVCCIN_CPU1")
	)
	(segment
		(start 329.398884 -15.685262)
		(end 330.640436 -14.44371)
		(width 0.089408)
		(layer "In11.Cu")
		(net "PWRGD_PVCCIN_CPU1")
	)
	(segment
		(start 177.860452 -1.657096)
		(end 177.332386 -2.185162)
		(width 0.089408)
		(layer "In11.Cu")
		(net "PWRGD_PVCCIN_CPU1")
	)
	(segment
		(start 336.343752 -40.018208)
		(end 335.225136 -38.899592)
		(width 0.089408)
		(layer "In11.Cu")
		(net "PWRGD_PVCCIN_CPU1")
	)
	(segment
		(start 380.529338 -75.881484)
		(end 380.612904 -75.797918)
		(width 0.089408)
		(layer "In11.Cu")
		(net "PWRGD_PVCCIN_CPU1")
	)
	(segment
		(start 172.76191 -1.262126)
		(end 170.744134 -1.262126)
		(width 0.089408)
		(layer "In11.Cu")
		(net "PWRGD_PVCCIN_CPU1")
	)
	(segment
		(start 379.483112 -60.972446)
		(end 378.871734 -60.361068)
		(width 0.089408)
		(layer "In11.Cu")
		(net "PWRGD_PVCCIN_CPU1")
	)
	(segment
		(start 353.300792 -40.018208)
		(end 336.343752 -40.018208)
		(width 0.089408)
		(layer "In11.Cu")
		(net "PWRGD_PVCCIN_CPU1")
	)
	(segment
		(start 329.621896 -22.097492)
		(end 329.398884 -21.87448)
		(width 0.089408)
		(layer "In11.Cu")
		(net "PWRGD_PVCCIN_CPU1")
	)
	(segment
		(start 332.468474 -37.508688)
		(end 331.108558 -36.148772)
		(width 0.089408)
		(layer "In11.Cu")
		(net "PWRGD_PVCCIN_CPU1")
	)
	(segment
		(start 329.398884 -21.87448)
		(end 329.398884 -15.685262)
		(width 0.089408)
		(layer "In11.Cu")
		(net "PWRGD_PVCCIN_CPU1")
	)
	(segment
		(start 330.137008 -10.065766)
		(end 330.137008 -6.513068)
		(width 0.089408)
		(layer "In11.Cu")
		(net "PWRGD_PVCCIN_CPU1")
	)
	(segment
		(start 178.670204 -1.657604)
		(end 178.669696 -1.657096)
		(width 0.089408)
		(layer "In11.Cu")
		(net "PWRGD_PVCCIN_CPU1")
	)
	(segment
		(start 181.332886 3.48742)
		(end 181.332886 2.906776)
		(width 0.089408)
		(layer "In11.Cu")
		(net "PWRGD_PVCCIN_CPU1")
	)
	(segment
		(start 330.640436 -10.569194)
		(end 330.137008 -10.065766)
		(width 0.089408)
		(layer "In11.Cu")
		(net "PWRGD_PVCCIN_CPU1")
	)
	(segment
		(start 381.319278 -70.931278)
		(end 380.747016 -70.359016)
		(width 0.089408)
		(layer "In11.Cu")
		(net "PWRGD_PVCCIN_CPU1")
	)
	(segment
		(start 330.137008 -6.513068)
		(end 328.799952 -5.176012)
		(width 0.089408)
		(layer "In11.Cu")
		(net "PWRGD_PVCCIN_CPU1")
	)
	(segment
		(start 331.108558 -36.148772)
		(end 331.108558 -33.41878)
		(width 0.089408)
		(layer "In11.Cu")
		(net "PWRGD_PVCCIN_CPU1")
	)
	(segment
		(start 381.319278 -71.263002)
		(end 381.319278 -70.931278)
		(width 0.089408)
		(layer "In11.Cu")
		(net "PWRGD_PVCCIN_CPU1")
	)
	(segment
		(start 334.401414 -38.899592)
		(end 333.01051 -37.508688)
		(width 0.089408)
		(layer "In11.Cu")
		(net "PWRGD_PVCCIN_CPU1")
	)
	(segment
		(start 380.74219 -78.236064)
		(end 380.74219 -76.657708)
		(width 0.089408)
		(layer "In11.Cu")
		(net "PWRGD_PVCCIN_CPU1")
	)
	(segment
		(start 354.571808 -38.747192)
		(end 353.300792 -40.018208)
		(width 0.089408)
		(layer "In11.Cu")
		(net "PWRGD_PVCCIN_CPU1")
	)
	(segment
		(start 329.621896 -31.932118)
		(end 329.621896 -22.097492)
		(width 0.089408)
		(layer "In11.Cu")
		(net "PWRGD_PVCCIN_CPU1")
	)
	(segment
		(start 173.684946 -2.185162)
		(end 172.76191 -1.262126)
		(width 0.089408)
		(layer "In11.Cu")
		(net "PWRGD_PVCCIN_CPU1")
	)
	(segment
		(start 378.278136 -66.062606)
		(end 378.278136 -63.793624)
		(width 0.089408)
		(layer "In11.Cu")
		(net "PWRGD_PVCCIN_CPU1")
	)
	(segment
		(start 356.993444 -38.747192)
		(end 354.571808 -38.747192)
		(width 0.089408)
		(layer "In11.Cu")
		(net "PWRGD_PVCCIN_CPU1")
	)
	(segment
		(start 178.669696 -1.657096)
		(end 177.860452 -1.657096)
		(width 0.089408)
		(layer "In11.Cu")
		(net "PWRGD_PVCCIN_CPU1")
	)
	(segment
		(start 380.747016 -67.673728)
		(end 379.875288 -66.802)
		(width 0.089408)
		(layer "In11.Cu")
		(net "PWRGD_PVCCIN_CPU1")
	)
	(segment
		(start 380.596394 -73.494138)
		(end 380.596394 -71.985886)
		(width 0.089408)
		(layer "In11.Cu")
		(net "PWRGD_PVCCIN_CPU1")
	)
	(segment
		(start 182.579518 4.734052)
		(end 181.332886 3.48742)
		(width 0.089408)
		(layer "In11.Cu")
		(net "PWRGD_PVCCIN_CPU1")
	)
	(segment
		(start 177.332386 -2.185162)
		(end 173.684946 -2.185162)
		(width 0.089408)
		(layer "In11.Cu")
		(net "PWRGD_PVCCIN_CPU1")
	)
	(segment
		(start 379.875288 -66.802)
		(end 379.01753 -66.802)
		(width 0.089408)
		(layer "In11.Cu")
		(net "PWRGD_PVCCIN_CPU1")
	)
	(segment
		(start 366.231678 -47.985426)
		(end 356.993444 -38.747192)
		(width 0.089408)
		(layer "In11.Cu")
		(net "PWRGD_PVCCIN_CPU1")
	)
	(segment
		(start 378.116084 -58.437526)
		(end 378.116084 -56.701182)
		(width 0.089408)
		(layer "In11.Cu")
		(net "PWRGD_PVCCIN_CPU1")
	)
	(segment
		(start 378.116084 -56.701182)
		(end 376.855736 -55.440834)
		(width 0.089408)
		(layer "In11.Cu")
		(net "PWRGD_PVCCIN_CPU1")
	)
	(segment
		(start 380.747016 -70.359016)
		(end 380.747016 -67.673728)
		(width 0.089408)
		(layer "In11.Cu")
		(net "PWRGD_PVCCIN_CPU1")
	)
	(segment
		(start 379.483112 -62.588648)
		(end 379.483112 -60.972446)
		(width 0.089408)
		(layer "In11.Cu")
		(net "PWRGD_PVCCIN_CPU1")
	)
	(segment
		(start 327.349866 3.548634)
		(end 327.060814 3.548634)
		(width 0.089408)
		(layer "In11.Cu")
		(net "PWRGD_PVCCIN_CPU1")
	)
	(segment
		(start 380.612904 -75.797918)
		(end 380.612904 -73.510648)
		(width 0.089408)
		(layer "In11.Cu")
		(net "PWRGD_PVCCIN_CPU1")
	)
	(segment
		(start 179.096162 -1.657604)
		(end 178.670204 -1.657604)
		(width 0.089408)
		(layer "In11.Cu")
		(net "PWRGD_PVCCIN_CPU1")
	)
	(segment
		(start 327.060814 3.548634)
		(end 325.875396 4.734052)
		(width 0.089408)
		(layer "In11.Cu")
		(net "PWRGD_PVCCIN_CPU1")
	)
	(segment
		(start 170.744134 -1.262126)
		(end 168.3258 1.156208)
		(width 0.089408)
		(layer "In11.Cu")
		(net "PWRGD_PVCCIN_CPU1")
	)
	(segment
		(start 371.418358 -52.893722)
		(end 371.418358 -51.972972)
		(width 0.089408)
		(layer "In11.Cu")
		(net "PWRGD_PVCCIN_CPU1")
	)
	(segment
		(start 378.871734 -59.193176)
		(end 378.116084 -58.437526)
		(width 0.089408)
		(layer "In11.Cu")
		(net "PWRGD_PVCCIN_CPU1")
	)
	(segment
		(start 380.529338 -76.444856)
		(end 380.529338 -75.881484)
		(width 0.089408)
		(layer "In11.Cu")
		(net "PWRGD_PVCCIN_CPU1")
	)
	(segment
		(start 331.108558 -33.41878)
		(end 329.621896 -31.932118)
		(width 0.089408)
		(layer "In11.Cu")
		(net "PWRGD_PVCCIN_CPU1")
	)
	(segment
		(start 380.74219 -76.657708)
		(end 380.529338 -76.444856)
		(width 0.089408)
		(layer "In11.Cu")
		(net "PWRGD_PVCCIN_CPU1")
	)
	(segment
		(start 379.895354 -79.0829)
		(end 380.74219 -78.236064)
		(width 0.089408)
		(layer "In11.Cu")
		(net "PWRGD_PVCCIN_CPU1")
	)
	(segment
		(start 179.761896 -0.99187)
		(end 179.096162 -1.657604)
		(width 0.089408)
		(layer "In11.Cu")
		(net "PWRGD_PVCCIN_CPU1")
	)
	(segment
		(start 325.875396 4.734052)
		(end 182.579518 4.734052)
		(width 0.089408)
		(layer "In11.Cu")
		(net "PWRGD_PVCCIN_CPU1")
	)
	(segment
		(start 333.01051 -37.508688)
		(end 332.468474 -37.508688)
		(width 0.089408)
		(layer "In11.Cu")
		(net "PWRGD_PVCCIN_CPU1")
	)
	(segment
		(start 328.799952 -5.176012)
		(end 328.799952 2.098548)
		(width 0.089408)
		(layer "In11.Cu")
		(net "PWRGD_PVCCIN_CPU1")
	)
	(segment
		(start 335.225136 -38.899592)
		(end 334.401414 -38.899592)
		(width 0.089408)
		(layer "In11.Cu")
		(net "PWRGD_PVCCIN_CPU1")
	)
	(segment
		(start 376.855736 -55.440834)
		(end 373.96547 -55.440834)
		(width 0.089408)
		(layer "In11.Cu")
		(net "PWRGD_PVCCIN_CPU1")
	)
	(segment
		(start 168.3258 1.156208)
		(end 168.3258 4.5466)
		(width 0.089408)
		(layer "In11.Cu")
		(net "PWRGD_PVCCIN_CPU1")
	)
	(segment
		(start 379.01753 -66.802)
		(end 378.278136 -66.062606)
		(width 0.089408)
		(layer "In11.Cu")
		(net "PWRGD_PVCCIN_CPU1")
	)
	(segment
		(start 373.96547 -55.440834)
		(end 371.418358 -52.893722)
		(width 0.089408)
		(layer "In11.Cu")
		(net "PWRGD_PVCCIN_CPU1")
	)
	(segment
		(start 367.430812 -47.985426)
		(end 366.231678 -47.985426)
		(width 0.089408)
		(layer "In11.Cu")
		(net "PWRGD_PVCCIN_CPU1")
	)
	(segment
		(start 378.278136 -63.793624)
		(end 379.483112 -62.588648)
		(width 0.089408)
		(layer "In11.Cu")
		(net "PWRGD_PVCCIN_CPU1")
	)
	(segment
		(start 328.799952 2.098548)
		(end 327.349866 3.548634)
		(width 0.089408)
		(layer "In11.Cu")
		(net "PWRGD_PVCCIN_CPU1")
	)
	(segment
		(start 330.640436 -14.44371)
		(end 330.640436 -10.569194)
		(width 0.089408)
		(layer "In11.Cu")
		(net "PWRGD_PVCCIN_CPU1")
	)
	(segment
		(start 460.78521 -134.80161)
		(end 460.1464 -134.1628)
		(width 0.10795)
		(layer "F.Cu")
		(net "PWRGD_PVCCIN_CPU0")
	)
	(segment
		(start 462.138522 -150.825962)
		(end 461.88503 -151.079454)
		(width 0.10795)
		(layer "F.Cu")
		(net "PWRGD_PVCCIN_CPU0")
	)
	(segment
		(start 460.578454 -150.749254)
		(end 457.302616 -150.749254)
		(width 0.10795)
		(layer "F.Cu")
		(net "PWRGD_PVCCIN_CPU0")
	)
	(segment
		(start 461.88503 -151.079454)
		(end 460.908654 -151.079454)
		(width 0.10795)
		(layer "F.Cu")
		(net "PWRGD_PVCCIN_CPU0")
	)
	(segment
		(start 459.8289 -133.5151)
		(end 458.901546 -134.442454)
		(width 0.10795)
		(layer "F.Cu")
		(net "PWRGD_PVCCIN_CPU0")
	)
	(segment
		(start 462.192116 -150.825962)
		(end 462.138522 -150.825962)
		(width 0.10795)
		(layer "F.Cu")
		(net "PWRGD_PVCCIN_CPU0")
	)
	(segment
		(start 460.1464 -134.1628)
		(end 460.1464 -133.8326)
		(width 0.10795)
		(layer "F.Cu")
		(net "PWRGD_PVCCIN_CPU0")
	)
	(segment
		(start 460.1464 -133.8326)
		(end 459.8289 -133.5151)
		(width 0.10795)
		(layer "F.Cu")
		(net "PWRGD_PVCCIN_CPU0")
	)
	(segment
		(start 460.908654 -151.079454)
		(end 460.578454 -150.749254)
		(width 0.10795)
		(layer "F.Cu")
		(net "PWRGD_PVCCIN_CPU0")
	)
	(segment
		(start 375.944892 -75.894692)
		(end 375.545096 -75.494896)
		(width 0.1016)
		(layer "F.Cu")
		(net "PWRGD_PVCCIN_CPU0")
	)
	(segment
		(start 177.9016 -65.3288)
		(end 178.3334 -65.7606)
		(width 0.10795)
		(layer "F.Cu")
		(net "PWRGD_PVCCIN_CPU0")
	)
	(segment
		(start 457.302616 -150.749254)
		(end 457.296012 -150.755858)
		(width 0.10795)
		(layer "F.Cu")
		(net "PWRGD_PVCCIN_CPU0")
	)
	(segment
		(start 459.753208 -138.456162)
		(end 460.78521 -137.42416)
		(width 0.10795)
		(layer "F.Cu")
		(net "PWRGD_PVCCIN_CPU0")
	)
	(segment
		(start 458.901546 -134.442454)
		(end 458.153008 -134.442454)
		(width 0.10795)
		(layer "F.Cu")
		(net "PWRGD_PVCCIN_CPU0")
	)
	(segment
		(start 458.597 -152.056846)
		(end 457.296012 -150.755858)
		(width 0.10795)
		(layer "F.Cu")
		(net "PWRGD_PVCCIN_CPU0")
	)
	(segment
		(start 178.3334 -65.7606)
		(end 178.7398 -65.7606)
		(width 0.10795)
		(layer "F.Cu")
		(net "PWRGD_PVCCIN_CPU0")
	)
	(segment
		(start 458.597 -153.1874)
		(end 458.597 -152.056846)
		(width 0.10795)
		(layer "F.Cu")
		(net "PWRGD_PVCCIN_CPU0")
	)
	(segment
		(start 460.78521 -137.42416)
		(end 460.78521 -134.80161)
		(width 0.10795)
		(layer "F.Cu")
		(net "PWRGD_PVCCIN_CPU0")
	)
	(via
		(at 459.753208 -138.456162)
		(size 0.508)
		(drill 0.254)
		(layers "F.Cu" "B.Cu")
		(net "PWRGD_PVCCIN_CPU0")
	)
	(via
		(at 459.8289 -133.5151)
		(size 0.508)
		(drill 0.254)
		(layers "F.Cu" "B.Cu")
		(net "PWRGD_PVCCIN_CPU0")
	)
	(via
		(at 415.776156 -68.8086)
		(size 0.508)
		(drill 0.254)
		(layers "F.Cu" "B.Cu")
		(net "PWRGD_PVCCIN_CPU0")
	)
	(via
		(at 458.153008 -134.442454)
		(size 0.508)
		(drill 0.254)
		(layers "F.Cu" "B.Cu")
		(net "PWRGD_PVCCIN_CPU0")
	)
	(via
		(at 416.82797 -82.340704)
		(size 0.6604)
		(drill 0.3302)
		(layers "F.Cu" "B.Cu")
		(net "PWRGD_PVCCIN_CPU0")
	)
	(via
		(at 462.192116 -150.825962)
		(size 0.508)
		(drill 0.254)
		(layers "F.Cu" "B.Cu")
		(net "PWRGD_PVCCIN_CPU0")
	)
	(via
		(at 322.0212 -41.0972)
		(size 0.508)
		(drill 0.254)
		(layers "F.Cu" "B.Cu")
		(net "PWRGD_PVCCIN_CPU0")
	)
	(via
		(at 458.597 -153.1874)
		(size 0.508)
		(drill 0.254)
		(layers "F.Cu" "B.Cu")
		(net "PWRGD_PVCCIN_CPU0")
	)
	(via
		(at 191.2366 -25.654)
		(size 0.508)
		(drill 0.254)
		(layers "F.Cu" "B.Cu")
		(net "PWRGD_PVCCIN_CPU0")
	)
	(via
		(at 177.9016 -65.3288)
		(size 0.508)
		(drill 0.254)
		(layers "F.Cu" "B.Cu")
		(net "PWRGD_PVCCIN_CPU0")
	)
	(via
		(at 436.648606 -119.914416)
		(size 0.508)
		(drill 0.254)
		(layers "F.Cu" "B.Cu")
		(net "PWRGD_PVCCIN_CPU0")
	)
	(via
		(at 375.944892 -75.894692)
		(size 0.4572)
		(drill 0.2032)
		(layers "F.Cu" "B.Cu")
		(net "PWRGD_PVCCIN_CPU0")
	)
	(via
		(at 457.296012 -150.755858)
		(size 0.508)
		(drill 0.254)
		(layers "F.Cu" "B.Cu")
		(net "PWRGD_PVCCIN_CPU0")
	)
	(segment
		(start 421.347646 -113.29924)
		(end 424.325796 -116.27739)
		(width 0.10795)
		(layer "B.Cu")
		(net "PWRGD_PVCCIN_CPU0")
	)
	(segment
		(start 417.014914 -82.527648)
		(end 417.014914 -83.522058)
		(width 0.10795)
		(layer "B.Cu")
		(net "PWRGD_PVCCIN_CPU0")
	)
	(segment
		(start 456.6412 -133.8072)
		(end 457.517754 -133.8072)
		(width 0.10795)
		(layer "B.Cu")
		(net "PWRGD_PVCCIN_CPU0")
	)
	(segment
		(start 458.06995 -154.559)
		(end 460.6798 -154.559)
		(width 0.10795)
		(layer "B.Cu")
		(net "PWRGD_PVCCIN_CPU0")
	)
	(segment
		(start 414.600898 -79.954374)
		(end 415.241232 -80.594708)
		(width 0.10795)
		(layer "B.Cu")
		(net "PWRGD_PVCCIN_CPU0")
	)
	(segment
		(start 421.193214 -87.700358)
		(end 421.193214 -94.08922)
		(width 0.10795)
		(layer "B.Cu")
		(net "PWRGD_PVCCIN_CPU0")
	)
	(segment
		(start 459.8289 -133.5151)
		(end 460.253334 -133.939534)
		(width 0.10795)
		(layer "B.Cu")
		(net "PWRGD_PVCCIN_CPU0")
	)
	(segment
		(start 458.2033 -136.894316)
		(end 456.578716 -136.894316)
		(width 0.10795)
		(layer "B.Cu")
		(net "PWRGD_PVCCIN_CPU0")
	)
	(segment
		(start 457.517754 -133.8072)
		(end 458.153008 -134.442454)
		(width 0.10795)
		(layer "B.Cu")
		(net "PWRGD_PVCCIN_CPU0")
	)
	(segment
		(start 462.08823 -150.876254)
		(end 462.138522 -150.825962)
		(width 0.10795)
		(layer "B.Cu")
		(net "PWRGD_PVCCIN_CPU0")
	)
	(segment
		(start 458.3303 -151.876252)
		(end 458.3303 -152.489154)
		(width 0.10795)
		(layer "B.Cu")
		(net "PWRGD_PVCCIN_CPU0")
	)
	(segment
		(start 457.662534 -150.376128)
		(end 458.3303 -150.376128)
		(width 0.10795)
		(layer "B.Cu")
		(net "PWRGD_PVCCIN_CPU0")
	)
	(segment
		(start 421.347646 -100.308918)
		(end 421.347646 -113.29924)
		(width 0.10795)
		(layer "B.Cu")
		(net "PWRGD_PVCCIN_CPU0")
	)
	(segment
		(start 462.138522 -150.825962)
		(end 462.192116 -150.825962)
		(width 0.10795)
		(layer "B.Cu")
		(net "PWRGD_PVCCIN_CPU0")
	)
	(segment
		(start 456.2094 -136.525)
		(end 456.2094 -134.239)
		(width 0.10795)
		(layer "B.Cu")
		(net "PWRGD_PVCCIN_CPU0")
	)
	(segment
		(start 456.578716 -136.894316)
		(end 456.2094 -136.525)
		(width 0.10795)
		(layer "B.Cu")
		(net "PWRGD_PVCCIN_CPU0")
	)
	(segment
		(start 460.878682 -154.360118)
		(end 460.878682 -153.335482)
		(width 0.10795)
		(layer "B.Cu")
		(net "PWRGD_PVCCIN_CPU0")
	)
	(segment
		(start 414.772602 -69.812154)
		(end 414.772602 -71.54799)
		(width 0.10795)
		(layer "B.Cu")
		(net "PWRGD_PVCCIN_CPU0")
	)
	(segment
		(start 458.3303 -152.489154)
		(end 458.534008 -152.692862)
		(width 0.10795)
		(layer "B.Cu")
		(net "PWRGD_PVCCIN_CPU0")
	)
	(segment
		(start 426.134276 -120.767856)
		(end 435.795166 -120.767856)
		(width 0.10795)
		(layer "B.Cu")
		(net "PWRGD_PVCCIN_CPU0")
	)
	(segment
		(start 416.521138 -82.033872)
		(end 416.82797 -82.340704)
		(width 0.10795)
		(layer "B.Cu")
		(net "PWRGD_PVCCIN_CPU0")
	)
	(segment
		(start 415.776156 -68.8086)
		(end 414.772602 -69.812154)
		(width 0.10795)
		(layer "B.Cu")
		(net "PWRGD_PVCCIN_CPU0")
	)
	(segment
		(start 435.795166 -120.767856)
		(end 436.648606 -119.914416)
		(width 0.10795)
		(layer "B.Cu")
		(net "PWRGD_PVCCIN_CPU0")
	)
	(segment
		(start 420.828724 -99.789996)
		(end 421.347646 -100.308918)
		(width 0.10795)
		(layer "B.Cu")
		(net "PWRGD_PVCCIN_CPU0")
	)
	(segment
		(start 416.30346 -82.033872)
		(end 416.521138 -82.033872)
		(width 0.10795)
		(layer "B.Cu")
		(net "PWRGD_PVCCIN_CPU0")
	)
	(segment
		(start 457.962 -153.8224)
		(end 457.962 -154.45105)
		(width 0.10795)
		(layer "B.Cu")
		(net "PWRGD_PVCCIN_CPU0")
	)
	(segment
		(start 461.430116 -150.876254)
		(end 462.08823 -150.876254)
		(width 0.10795)
		(layer "B.Cu")
		(net "PWRGD_PVCCIN_CPU0")
	)
	(segment
		(start 417.014914 -83.522058)
		(end 421.193214 -87.700358)
		(width 0.10795)
		(layer "B.Cu")
		(net "PWRGD_PVCCIN_CPU0")
	)
	(segment
		(start 457.296012 -150.74265)
		(end 457.662534 -150.376128)
		(width 0.10795)
		(layer "B.Cu")
		(net "PWRGD_PVCCIN_CPU0")
	)
	(segment
		(start 458.534008 -152.692862)
		(end 458.534008 -153.124408)
		(width 0.10795)
		(layer "B.Cu")
		(net "PWRGD_PVCCIN_CPU0")
	)
	(segment
		(start 460.6798 -154.559)
		(end 460.878682 -154.360118)
		(width 0.10795)
		(layer "B.Cu")
		(net "PWRGD_PVCCIN_CPU0")
	)
	(segment
		(start 460.63027 -153.08707)
		(end 460.63027 -152.426162)
		(width 0.10795)
		(layer "B.Cu")
		(net "PWRGD_PVCCIN_CPU0")
	)
	(segment
		(start 456.2094 -134.239)
		(end 456.6412 -133.8072)
		(width 0.10795)
		(layer "B.Cu")
		(net "PWRGD_PVCCIN_CPU0")
	)
	(segment
		(start 457.296012 -150.755858)
		(end 457.296012 -150.74265)
		(width 0.10795)
		(layer "B.Cu")
		(net "PWRGD_PVCCIN_CPU0")
	)
	(segment
		(start 459.753208 -137.694162)
		(end 459.753208 -138.456162)
		(width 0.10795)
		(layer "B.Cu")
		(net "PWRGD_PVCCIN_CPU0")
	)
	(segment
		(start 425.781216 -118.11508)
		(end 425.781216 -120.414796)
		(width 0.10795)
		(layer "B.Cu")
		(net "PWRGD_PVCCIN_CPU0")
	)
	(segment
		(start 414.600898 -71.719694)
		(end 414.600898 -79.954374)
		(width 0.10795)
		(layer "B.Cu")
		(net "PWRGD_PVCCIN_CPU0")
	)
	(segment
		(start 458.3049 -134.594346)
		(end 458.75321 -134.594346)
		(width 0.10795)
		(layer "B.Cu")
		(net "PWRGD_PVCCIN_CPU0")
	)
	(segment
		(start 420.828724 -94.45371)
		(end 420.828724 -99.789996)
		(width 0.10795)
		(layer "B.Cu")
		(net "PWRGD_PVCCIN_CPU0")
	)
	(segment
		(start 424.325796 -116.65966)
		(end 425.781216 -118.11508)
		(width 0.10795)
		(layer "B.Cu")
		(net "PWRGD_PVCCIN_CPU0")
	)
	(segment
		(start 415.241232 -80.594708)
		(end 415.241232 -80.971644)
		(width 0.10795)
		(layer "B.Cu")
		(net "PWRGD_PVCCIN_CPU0")
	)
	(segment
		(start 421.193214 -94.08922)
		(end 420.828724 -94.45371)
		(width 0.10795)
		(layer "B.Cu")
		(net "PWRGD_PVCCIN_CPU0")
	)
	(segment
		(start 415.241232 -80.971644)
		(end 416.30346 -82.033872)
		(width 0.10795)
		(layer "B.Cu")
		(net "PWRGD_PVCCIN_CPU0")
	)
	(segment
		(start 458.153008 -134.442454)
		(end 458.3049 -134.594346)
		(width 0.10795)
		(layer "B.Cu")
		(net "PWRGD_PVCCIN_CPU0")
	)
	(segment
		(start 424.325796 -116.27739)
		(end 424.325796 -116.65966)
		(width 0.10795)
		(layer "B.Cu")
		(net "PWRGD_PVCCIN_CPU0")
	)
	(segment
		(start 460.878682 -153.335482)
		(end 460.63027 -153.08707)
		(width 0.10795)
		(layer "B.Cu")
		(net "PWRGD_PVCCIN_CPU0")
	)
	(segment
		(start 460.253334 -133.939534)
		(end 460.253334 -134.594346)
		(width 0.10795)
		(layer "B.Cu")
		(net "PWRGD_PVCCIN_CPU0")
	)
	(segment
		(start 457.962 -154.45105)
		(end 458.06995 -154.559)
		(width 0.10795)
		(layer "B.Cu")
		(net "PWRGD_PVCCIN_CPU0")
	)
	(segment
		(start 416.82797 -82.340704)
		(end 417.014914 -82.527648)
		(width 0.10795)
		(layer "B.Cu")
		(net "PWRGD_PVCCIN_CPU0")
	)
	(segment
		(start 425.781216 -120.414796)
		(end 426.134276 -120.767856)
		(width 0.10795)
		(layer "B.Cu")
		(net "PWRGD_PVCCIN_CPU0")
	)
	(segment
		(start 414.772602 -71.54799)
		(end 414.600898 -71.719694)
		(width 0.10795)
		(layer "B.Cu")
		(net "PWRGD_PVCCIN_CPU0")
	)
	(segment
		(start 458.534008 -153.124408)
		(end 458.597 -153.1874)
		(width 0.10795)
		(layer "B.Cu")
		(net "PWRGD_PVCCIN_CPU0")
	)
	(segment
		(start 458.597 -153.1874)
		(end 457.962 -153.8224)
		(width 0.10795)
		(layer "B.Cu")
		(net "PWRGD_PVCCIN_CPU0")
	)
	(segment
		(start 414.40735 -69.8246)
		(end 414.366456 -69.8246)
		(width 0.089408)
		(layer "In4.Cu")
		(net "PWRGD_PVCCIN_CPU0")
	)
	(segment
		(start 415.776156 -68.8086)
		(end 415.470848 -68.8086)
		(width 0.089408)
		(layer "In4.Cu")
		(net "PWRGD_PVCCIN_CPU0")
	)
	(segment
		(start 414.208214 -69.824854)
		(end 414.20796 -69.8246)
		(width 0.089408)
		(layer "In4.Cu")
		(net "PWRGD_PVCCIN_CPU0")
	)
	(segment
		(start 414.366456 -69.8246)
		(end 414.366202 -69.824854)
		(width 0.089408)
		(layer "In4.Cu")
		(net "PWRGD_PVCCIN_CPU0")
	)
	(segment
		(start 415.470848 -68.8086)
		(end 414.455102 -69.824346)
		(width 0.089408)
		(layer "In4.Cu")
		(net "PWRGD_PVCCIN_CPU0")
	)
	(segment
		(start 376.318272 -76.268072)
		(end 375.944892 -75.894692)
		(width 0.089408)
		(layer "In4.Cu")
		(net "PWRGD_PVCCIN_CPU0")
	)
	(segment
		(start 391.573258 -75.782678)
		(end 384.190748 -75.782678)
		(width 0.089408)
		(layer "In4.Cu")
		(net "PWRGD_PVCCIN_CPU0")
	)
	(segment
		(start 406.18283 -72.340978)
		(end 402.346922 -72.340978)
		(width 0.089408)
		(layer "In4.Cu")
		(net "PWRGD_PVCCIN_CPU0")
	)
	(segment
		(start 380.041404 -76.078334)
		(end 379.526546 -76.078334)
		(width 0.089408)
		(layer "In4.Cu")
		(net "PWRGD_PVCCIN_CPU0")
	)
	(segment
		(start 384.043682 -75.635612)
		(end 380.484126 -75.635612)
		(width 0.089408)
		(layer "In4.Cu")
		(net "PWRGD_PVCCIN_CPU0")
	)
	(segment
		(start 392.903456 -74.45248)
		(end 391.573258 -75.782678)
		(width 0.089408)
		(layer "In4.Cu")
		(net "PWRGD_PVCCIN_CPU0")
	)
	(segment
		(start 414.20796 -69.8246)
		(end 413.812482 -69.8246)
		(width 0.089408)
		(layer "In4.Cu")
		(net "PWRGD_PVCCIN_CPU0")
	)
	(segment
		(start 395.319758 -74.51852)
		(end 395.243558 -74.59472)
		(width 0.089408)
		(layer "In4.Cu")
		(net "PWRGD_PVCCIN_CPU0")
	)
	(segment
		(start 395.243558 -74.59472)
		(end 394.369798 -74.59472)
		(width 0.089408)
		(layer "In4.Cu")
		(net "PWRGD_PVCCIN_CPU0")
	)
	(segment
		(start 412.136082 -71.501)
		(end 409.34894 -71.501)
		(width 0.089408)
		(layer "In4.Cu")
		(net "PWRGD_PVCCIN_CPU0")
	)
	(segment
		(start 378.472446 -76.268072)
		(end 376.318272 -76.268072)
		(width 0.089408)
		(layer "In4.Cu")
		(net "PWRGD_PVCCIN_CPU0")
	)
	(segment
		(start 394.369798 -74.59472)
		(end 394.227558 -74.45248)
		(width 0.089408)
		(layer "In4.Cu")
		(net "PWRGD_PVCCIN_CPU0")
	)
	(segment
		(start 399.326862 -73.858374)
		(end 398.365726 -73.858374)
		(width 0.089408)
		(layer "In4.Cu")
		(net "PWRGD_PVCCIN_CPU0")
	)
	(segment
		(start 380.484126 -75.635612)
		(end 380.041404 -76.078334)
		(width 0.089408)
		(layer "In4.Cu")
		(net "PWRGD_PVCCIN_CPU0")
	)
	(segment
		(start 402.346922 -72.340978)
		(end 401.907756 -72.780144)
		(width 0.089408)
		(layer "In4.Cu")
		(net "PWRGD_PVCCIN_CPU0")
	)
	(segment
		(start 406.673304 -71.850504)
		(end 406.18283 -72.340978)
		(width 0.089408)
		(layer "In4.Cu")
		(net "PWRGD_PVCCIN_CPU0")
	)
	(segment
		(start 379.526546 -76.078334)
		(end 379.478032 -76.02982)
		(width 0.089408)
		(layer "In4.Cu")
		(net "PWRGD_PVCCIN_CPU0")
	)
	(segment
		(start 414.455102 -69.824346)
		(end 414.407604 -69.824346)
		(width 0.089408)
		(layer "In4.Cu")
		(net "PWRGD_PVCCIN_CPU0")
	)
	(segment
		(start 384.190748 -75.782678)
		(end 384.043682 -75.635612)
		(width 0.089408)
		(layer "In4.Cu")
		(net "PWRGD_PVCCIN_CPU0")
	)
	(segment
		(start 379.478032 -76.02982)
		(end 378.710698 -76.02982)
		(width 0.089408)
		(layer "In4.Cu")
		(net "PWRGD_PVCCIN_CPU0")
	)
	(segment
		(start 409.34894 -71.501)
		(end 408.999436 -71.850504)
		(width 0.089408)
		(layer "In4.Cu")
		(net "PWRGD_PVCCIN_CPU0")
	)
	(segment
		(start 400.405092 -72.780144)
		(end 399.326862 -73.858374)
		(width 0.089408)
		(layer "In4.Cu")
		(net "PWRGD_PVCCIN_CPU0")
	)
	(segment
		(start 378.710698 -76.02982)
		(end 378.472446 -76.268072)
		(width 0.089408)
		(layer "In4.Cu")
		(net "PWRGD_PVCCIN_CPU0")
	)
	(segment
		(start 401.907756 -72.780144)
		(end 400.405092 -72.780144)
		(width 0.089408)
		(layer "In4.Cu")
		(net "PWRGD_PVCCIN_CPU0")
	)
	(segment
		(start 414.407604 -69.824346)
		(end 414.40735 -69.8246)
		(width 0.089408)
		(layer "In4.Cu")
		(net "PWRGD_PVCCIN_CPU0")
	)
	(segment
		(start 394.227558 -74.45248)
		(end 392.903456 -74.45248)
		(width 0.089408)
		(layer "In4.Cu")
		(net "PWRGD_PVCCIN_CPU0")
	)
	(segment
		(start 398.365726 -73.858374)
		(end 397.70558 -74.51852)
		(width 0.089408)
		(layer "In4.Cu")
		(net "PWRGD_PVCCIN_CPU0")
	)
	(segment
		(start 397.70558 -74.51852)
		(end 395.319758 -74.51852)
		(width 0.089408)
		(layer "In4.Cu")
		(net "PWRGD_PVCCIN_CPU0")
	)
	(segment
		(start 414.366202 -69.824854)
		(end 414.208214 -69.824854)
		(width 0.089408)
		(layer "In4.Cu")
		(net "PWRGD_PVCCIN_CPU0")
	)
	(segment
		(start 408.999436 -71.850504)
		(end 406.673304 -71.850504)
		(width 0.089408)
		(layer "In4.Cu")
		(net "PWRGD_PVCCIN_CPU0")
	)
	(segment
		(start 413.812482 -69.8246)
		(end 412.136082 -71.501)
		(width 0.089408)
		(layer "In4.Cu")
		(net "PWRGD_PVCCIN_CPU0")
	)
	(segment
		(start 458.153008 -145.85188)
		(end 458.153008 -134.442454)
		(width 0.089408)
		(layer "In9.Cu")
		(net "PWRGD_PVCCIN_CPU0")
	)
	(segment
		(start 313.520836 -40.2844)
		(end 304.348134 -31.111698)
		(width 0.089408)
		(layer "In9.Cu")
		(net "PWRGD_PVCCIN_CPU0")
	)
	(segment
		(start 192.119504 -26.536904)
		(end 191.2366 -25.654)
		(width 0.089408)
		(layer "In9.Cu")
		(net "PWRGD_PVCCIN_CPU0")
	)
	(segment
		(start 197.235064 -25.795224)
		(end 196.493384 -26.536904)
		(width 0.089408)
		(layer "In9.Cu")
		(net "PWRGD_PVCCIN_CPU0")
	)
	(segment
		(start 446.071244 -122.770392)
		(end 447.675 -124.374148)
		(width 0.089408)
		(layer "In9.Cu")
		(net "PWRGD_PVCCIN_CPU0")
	)
	(segment
		(start 196.493384 -26.536904)
		(end 192.119504 -26.536904)
		(width 0.089408)
		(layer "In9.Cu")
		(net "PWRGD_PVCCIN_CPU0")
	)
	(segment
		(start 439.738008 -122.770392)
		(end 446.071244 -122.770392)
		(width 0.089408)
		(layer "In9.Cu")
		(net "PWRGD_PVCCIN_CPU0")
	)
	(segment
		(start 260.382766 -27.750008)
		(end 244.907308 -27.750008)
		(width 0.089408)
		(layer "In9.Cu")
		(net "PWRGD_PVCCIN_CPU0")
	)
	(segment
		(start 447.675 -124.8791)
		(end 449.032122 -126.236222)
		(width 0.089408)
		(layer "In9.Cu")
		(net "PWRGD_PVCCIN_CPU0")
	)
	(segment
		(start 450.465444 -130.651504)
		(end 455.611992 -130.651504)
		(width 0.089408)
		(layer "In9.Cu")
		(net "PWRGD_PVCCIN_CPU0")
	)
	(segment
		(start 321.2084 -40.2844)
		(end 313.520836 -40.2844)
		(width 0.089408)
		(layer "In9.Cu")
		(net "PWRGD_PVCCIN_CPU0")
	)
	(segment
		(start 460.0448 -147.743672)
		(end 458.153008 -145.85188)
		(width 0.089408)
		(layer "In9.Cu")
		(net "PWRGD_PVCCIN_CPU0")
	)
	(segment
		(start 462.71561 -135.49376)
		(end 459.753208 -138.456162)
		(width 0.089408)
		(layer "In9.Cu")
		(net "PWRGD_PVCCIN_CPU0")
	)
	(segment
		(start 455.611992 -130.651504)
		(end 456.057 -130.206496)
		(width 0.089408)
		(layer "In9.Cu")
		(net "PWRGD_PVCCIN_CPU0")
	)
	(segment
		(start 304.348134 -31.111698)
		(end 265.232388 -31.111698)
		(width 0.089408)
		(layer "In9.Cu")
		(net "PWRGD_PVCCIN_CPU0")
	)
	(segment
		(start 457.574396 -150.755858)
		(end 460.0448 -148.285454)
		(width 0.089408)
		(layer "In9.Cu")
		(net "PWRGD_PVCCIN_CPU0")
	)
	(segment
		(start 447.675 -124.374148)
		(end 447.675 -124.8791)
		(width 0.089408)
		(layer "In9.Cu")
		(net "PWRGD_PVCCIN_CPU0")
	)
	(segment
		(start 460.450438 -132.646166)
		(end 461.632808 -132.646166)
		(width 0.089408)
		(layer "In9.Cu")
		(net "PWRGD_PVCCIN_CPU0")
	)
	(segment
		(start 457.296012 -150.755858)
		(end 457.574396 -150.755858)
		(width 0.089408)
		(layer "In9.Cu")
		(net "PWRGD_PVCCIN_CPU0")
	)
	(segment
		(start 265.232388 -31.111698)
		(end 263.075166 -28.954476)
		(width 0.089408)
		(layer "In9.Cu")
		(net "PWRGD_PVCCIN_CPU0")
	)
	(segment
		(start 244.907308 -27.750008)
		(end 242.952524 -25.795224)
		(width 0.089408)
		(layer "In9.Cu")
		(net "PWRGD_PVCCIN_CPU0")
	)
	(segment
		(start 456.057 -130.206496)
		(end 458.010768 -130.206496)
		(width 0.089408)
		(layer "In9.Cu")
		(net "PWRGD_PVCCIN_CPU0")
	)
	(segment
		(start 460.0448 -148.285454)
		(end 460.0448 -147.743672)
		(width 0.089408)
		(layer "In9.Cu")
		(net "PWRGD_PVCCIN_CPU0")
	)
	(segment
		(start 242.952524 -25.795224)
		(end 197.235064 -25.795224)
		(width 0.089408)
		(layer "In9.Cu")
		(net "PWRGD_PVCCIN_CPU0")
	)
	(segment
		(start 436.882032 -119.914416)
		(end 439.738008 -122.770392)
		(width 0.089408)
		(layer "In9.Cu")
		(net "PWRGD_PVCCIN_CPU0")
	)
	(segment
		(start 458.010768 -130.206496)
		(end 460.450438 -132.646166)
		(width 0.089408)
		(layer "In9.Cu")
		(net "PWRGD_PVCCIN_CPU0")
	)
	(segment
		(start 322.0212 -41.0972)
		(end 321.2084 -40.2844)
		(width 0.089408)
		(layer "In9.Cu")
		(net "PWRGD_PVCCIN_CPU0")
	)
	(segment
		(start 449.032122 -129.218182)
		(end 450.465444 -130.651504)
		(width 0.089408)
		(layer "In9.Cu")
		(net "PWRGD_PVCCIN_CPU0")
	)
	(segment
		(start 436.648606 -119.914416)
		(end 436.882032 -119.914416)
		(width 0.089408)
		(layer "In9.Cu")
		(net "PWRGD_PVCCIN_CPU0")
	)
	(segment
		(start 261.587234 -28.954476)
		(end 260.382766 -27.750008)
		(width 0.089408)
		(layer "In9.Cu")
		(net "PWRGD_PVCCIN_CPU0")
	)
	(segment
		(start 461.632808 -132.646166)
		(end 462.71561 -133.728968)
		(width 0.089408)
		(layer "In9.Cu")
		(net "PWRGD_PVCCIN_CPU0")
	)
	(segment
		(start 449.032122 -126.236222)
		(end 449.032122 -129.218182)
		(width 0.089408)
		(layer "In9.Cu")
		(net "PWRGD_PVCCIN_CPU0")
	)
	(segment
		(start 263.075166 -28.954476)
		(end 261.587234 -28.954476)
		(width 0.089408)
		(layer "In9.Cu")
		(net "PWRGD_PVCCIN_CPU0")
	)
	(segment
		(start 462.71561 -133.728968)
		(end 462.71561 -135.49376)
		(width 0.089408)
		(layer "In9.Cu")
		(net "PWRGD_PVCCIN_CPU0")
	)
	(segment
		(start 376.066304 -64.808862)
		(end 375.881138 -64.994028)
		(width 0.089408)
		(layer "In11.Cu")
		(net "PWRGD_PVCCIN_CPU0")
	)
	(segment
		(start 375.433336 -61.763402)
		(end 375.433336 -63.33617)
		(width 0.089408)
		(layer "In11.Cu")
		(net "PWRGD_PVCCIN_CPU0")
	)
	(segment
		(start 191.2366 -27.7876)
		(end 193.676016 -30.227016)
		(width 0.089408)
		(layer "In11.Cu")
		(net "PWRGD_PVCCIN_CPU0")
	)
	(segment
		(start 376.046492 -73.068688)
		(end 376.318272 -73.340468)
		(width 0.089408)
		(layer "In11.Cu")
		(net "PWRGD_PVCCIN_CPU0")
	)
	(segment
		(start 180.32984 -64.81064)
		(end 179.648104 -65.492376)
		(width 0.089408)
		(layer "In11.Cu")
		(net "PWRGD_PVCCIN_CPU0")
	)
	(segment
		(start 372.105682 -59.175904)
		(end 373.459756 -60.529978)
		(width 0.089408)
		(layer "In11.Cu")
		(net "PWRGD_PVCCIN_CPU0")
	)
	(segment
		(start 189.17412 -49.669192)
		(end 185.153808 -53.689504)
		(width 0.089408)
		(layer "In11.Cu")
		(net "PWRGD_PVCCIN_CPU0")
	)
	(segment
		(start 196.3928 -46.5836)
		(end 196.3928 -49.130712)
		(width 0.089408)
		(layer "In11.Cu")
		(net "PWRGD_PVCCIN_CPU0")
	)
	(segment
		(start 365.862362 -54.59984)
		(end 366.02035 -54.59984)
		(width 0.089408)
		(layer "In11.Cu")
		(net "PWRGD_PVCCIN_CPU0")
	)
	(segment
		(start 366.02035 -54.59984)
		(end 366.020604 -54.600094)
		(width 0.089408)
		(layer "In11.Cu")
		(net "PWRGD_PVCCIN_CPU0")
	)
	(segment
		(start 323.22008 -42.747184)
		(end 323.238114 -42.747184)
		(width 0.089408)
		(layer "In11.Cu")
		(net "PWRGD_PVCCIN_CPU0")
	)
	(segment
		(start 376.899424 -70.668642)
		(end 376.643138 -70.668642)
		(width 0.089408)
		(layer "In11.Cu")
		(net "PWRGD_PVCCIN_CPU0")
	)
	(segment
		(start 185.654696 -62.188852)
		(end 185.180224 -62.663324)
		(width 0.089408)
		(layer "In11.Cu")
		(net "PWRGD_PVCCIN_CPU0")
	)
	(segment
		(start 196.3928 -49.130712)
		(end 195.85432 -49.669192)
		(width 0.089408)
		(layer "In11.Cu")
		(net "PWRGD_PVCCIN_CPU0")
	)
	(segment
		(start 191.2366 -25.654)
		(end 191.2366 -27.7876)
		(width 0.089408)
		(layer "In11.Cu")
		(net "PWRGD_PVCCIN_CPU0")
	)
	(segment
		(start 184.925208 -64.036956)
		(end 184.925208 -64.053212)
		(width 0.089408)
		(layer "In11.Cu")
		(net "PWRGD_PVCCIN_CPU0")
	)
	(segment
		(start 367.113566 -54.600094)
		(end 371.689884 -59.175904)
		(width 0.089408)
		(layer "In11.Cu")
		(net "PWRGD_PVCCIN_CPU0")
	)
	(segment
		(start 375.571512 -72.849994)
		(end 375.790206 -73.068688)
		(width 0.089408)
		(layer "In11.Cu")
		(net "PWRGD_PVCCIN_CPU0")
	)
	(segment
		(start 178.065176 -65.492376)
		(end 177.9016 -65.3288)
		(width 0.089408)
		(layer "In11.Cu")
		(net "PWRGD_PVCCIN_CPU0")
	)
	(segment
		(start 375.433336 -63.33617)
		(end 376.066304 -63.969138)
		(width 0.089408)
		(layer "In11.Cu")
		(net "PWRGD_PVCCIN_CPU0")
	)
	(segment
		(start 184.912 -64.1096)
		(end 184.21096 -64.81064)
		(width 0.089408)
		(layer "In11.Cu")
		(net "PWRGD_PVCCIN_CPU0")
	)
	(segment
		(start 375.790206 -73.068688)
		(end 376.046492 -73.068688)
		(width 0.089408)
		(layer "In11.Cu")
		(net "PWRGD_PVCCIN_CPU0")
	)
	(segment
		(start 371.689884 -59.175904)
		(end 372.105682 -59.175904)
		(width 0.089408)
		(layer "In11.Cu")
		(net "PWRGD_PVCCIN_CPU0")
	)
	(segment
		(start 374.199912 -60.529978)
		(end 375.433336 -61.763402)
		(width 0.089408)
		(layer "In11.Cu")
		(net "PWRGD_PVCCIN_CPU0")
	)
	(segment
		(start 322.0212 -41.548304)
		(end 323.22008 -42.747184)
		(width 0.089408)
		(layer "In11.Cu")
		(net "PWRGD_PVCCIN_CPU0")
	)
	(segment
		(start 376.066304 -63.969138)
		(end 376.066304 -64.808862)
		(width 0.089408)
		(layer "In11.Cu")
		(net "PWRGD_PVCCIN_CPU0")
	)
	(segment
		(start 185.153808 -59.116468)
		(end 185.654696 -59.617356)
		(width 0.089408)
		(layer "In11.Cu")
		(net "PWRGD_PVCCIN_CPU0")
	)
	(segment
		(start 377.118118 -70.449948)
		(end 376.899424 -70.668642)
		(width 0.089408)
		(layer "In11.Cu")
		(net "PWRGD_PVCCIN_CPU0")
	)
	(segment
		(start 193.676016 -43.866816)
		(end 196.3928 -46.5836)
		(width 0.089408)
		(layer "In11.Cu")
		(net "PWRGD_PVCCIN_CPU0")
	)
	(segment
		(start 376.318272 -67.74053)
		(end 376.318272 -67.996816)
		(width 0.089408)
		(layer "In11.Cu")
		(net "PWRGD_PVCCIN_CPU0")
	)
	(segment
		(start 185.180224 -62.663324)
		(end 185.180224 -63.78194)
		(width 0.089408)
		(layer "In11.Cu")
		(net "PWRGD_PVCCIN_CPU0")
	)
	(segment
		(start 364.910116 -54.600094)
		(end 365.862108 -54.600094)
		(width 0.089408)
		(layer "In11.Cu")
		(net "PWRGD_PVCCIN_CPU0")
	)
	(segment
		(start 376.318272 -73.340468)
		(end 376.318272 -75.521312)
		(width 0.089408)
		(layer "In11.Cu")
		(net "PWRGD_PVCCIN_CPU0")
	)
	(segment
		(start 373.459756 -60.529978)
		(end 374.199912 -60.529978)
		(width 0.089408)
		(layer "In11.Cu")
		(net "PWRGD_PVCCIN_CPU0")
	)
	(segment
		(start 184.912 -64.06642)
		(end 184.912 -64.1096)
		(width 0.089408)
		(layer "In11.Cu")
		(net "PWRGD_PVCCIN_CPU0")
	)
	(segment
		(start 365.862108 -54.600094)
		(end 365.862362 -54.59984)
		(width 0.089408)
		(layer "In11.Cu")
		(net "PWRGD_PVCCIN_CPU0")
	)
	(segment
		(start 328.77633 -48.2854)
		(end 358.595422 -48.2854)
		(width 0.089408)
		(layer "In11.Cu")
		(net "PWRGD_PVCCIN_CPU0")
	)
	(segment
		(start 375.571512 -71.740268)
		(end 375.571512 -72.849994)
		(width 0.089408)
		(layer "In11.Cu")
		(net "PWRGD_PVCCIN_CPU0")
	)
	(segment
		(start 193.676016 -30.227016)
		(end 193.676016 -43.866816)
		(width 0.089408)
		(layer "In11.Cu")
		(net "PWRGD_PVCCIN_CPU0")
	)
	(segment
		(start 184.925208 -64.053212)
		(end 184.912 -64.06642)
		(width 0.089408)
		(layer "In11.Cu")
		(net "PWRGD_PVCCIN_CPU0")
	)
	(segment
		(start 366.020604 -54.600094)
		(end 367.113566 -54.600094)
		(width 0.089408)
		(layer "In11.Cu")
		(net "PWRGD_PVCCIN_CPU0")
	)
	(segment
		(start 376.318272 -75.521312)
		(end 375.944892 -75.894692)
		(width 0.089408)
		(layer "In11.Cu")
		(net "PWRGD_PVCCIN_CPU0")
	)
	(segment
		(start 185.180224 -63.78194)
		(end 184.925208 -64.036956)
		(width 0.089408)
		(layer "In11.Cu")
		(net "PWRGD_PVCCIN_CPU0")
	)
	(segment
		(start 375.881138 -67.303396)
		(end 376.318272 -67.74053)
		(width 0.089408)
		(layer "In11.Cu")
		(net "PWRGD_PVCCIN_CPU0")
	)
	(segment
		(start 195.85432 -49.669192)
		(end 189.17412 -49.669192)
		(width 0.089408)
		(layer "In11.Cu")
		(net "PWRGD_PVCCIN_CPU0")
	)
	(segment
		(start 185.654696 -59.617356)
		(end 185.654696 -62.188852)
		(width 0.089408)
		(layer "In11.Cu")
		(net "PWRGD_PVCCIN_CPU0")
	)
	(segment
		(start 376.318272 -67.996816)
		(end 376.590052 -68.268596)
		(width 0.089408)
		(layer "In11.Cu")
		(net "PWRGD_PVCCIN_CPU0")
	)
	(segment
		(start 377.118118 -68.54063)
		(end 377.118118 -70.449948)
		(width 0.089408)
		(layer "In11.Cu")
		(net "PWRGD_PVCCIN_CPU0")
	)
	(segment
		(start 376.590052 -68.268596)
		(end 376.846084 -68.268596)
		(width 0.089408)
		(layer "In11.Cu")
		(net "PWRGD_PVCCIN_CPU0")
	)
	(segment
		(start 185.153808 -53.689504)
		(end 185.153808 -59.116468)
		(width 0.089408)
		(layer "In11.Cu")
		(net "PWRGD_PVCCIN_CPU0")
	)
	(segment
		(start 376.846084 -68.268596)
		(end 377.118118 -68.54063)
		(width 0.089408)
		(layer "In11.Cu")
		(net "PWRGD_PVCCIN_CPU0")
	)
	(segment
		(start 323.238114 -42.747184)
		(end 328.77633 -48.2854)
		(width 0.089408)
		(layer "In11.Cu")
		(net "PWRGD_PVCCIN_CPU0")
	)
	(segment
		(start 375.881138 -64.994028)
		(end 375.881138 -67.303396)
		(width 0.089408)
		(layer "In11.Cu")
		(net "PWRGD_PVCCIN_CPU0")
	)
	(segment
		(start 179.648104 -65.492376)
		(end 178.065176 -65.492376)
		(width 0.089408)
		(layer "In11.Cu")
		(net "PWRGD_PVCCIN_CPU0")
	)
	(segment
		(start 376.643138 -70.668642)
		(end 375.571512 -71.740268)
		(width 0.089408)
		(layer "In11.Cu")
		(net "PWRGD_PVCCIN_CPU0")
	)
	(segment
		(start 322.0212 -41.0972)
		(end 322.0212 -41.548304)
		(width 0.089408)
		(layer "In11.Cu")
		(net "PWRGD_PVCCIN_CPU0")
	)
	(segment
		(start 184.21096 -64.81064)
		(end 180.32984 -64.81064)
		(width 0.089408)
		(layer "In11.Cu")
		(net "PWRGD_PVCCIN_CPU0")
	)
	(segment
		(start 358.595422 -48.2854)
		(end 364.910116 -54.600094)
		(width 0.089408)
		(layer "In11.Cu")
		(net "PWRGD_PVCCIN_CPU0")
	)
	(segment
		(start 366.345216 -69.495162)
		(end 366.745012 -69.894958)
		(width 0.10795)
		(layer "F.Cu")
		(net "PWRGD_PCH_PWROK")
	)
	(segment
		(start 380.80315 -100.41128)
		(end 381.29845 -100.181156)
		(width 0.10795)
		(layer "F.Cu")
		(net "PWRGD_PCH_PWROK")
	)
	(segment
		(start 414.290256 -40.93464)
		(end 413.890206 -41.33469)
		(width 0.10795)
		(layer "F.Cu")
		(net "PWRGD_PCH_PWROK")
	)
	(via
		(at 407.7208 -67.013582)
		(size 0.6604)
		(drill 0.3302)
		(layers "F.Cu" "B.Cu")
		(net "PWRGD_PCH_PWROK")
	)
	(via
		(at 366.345216 -69.495162)
		(size 0.4572)
		(drill 0.2032)
		(layers "F.Cu" "B.Cu")
		(net "PWRGD_PCH_PWROK")
	)
	(via
		(at 406.60574 -67.565524)
		(size 0.508)
		(drill 0.254)
		(layers "F.Cu" "B.Cu")
		(net "PWRGD_PCH_PWROK")
	)
	(via
		(at 413.890206 -41.33469)
		(size 0.4572)
		(drill 0.2032)
		(layers "F.Cu" "B.Cu")
		(net "PWRGD_PCH_PWROK")
	)
	(via
		(at 381.29845 -100.181156)
		(size 0.508)
		(drill 0.254)
		(layers "F.Cu" "B.Cu")
		(net "PWRGD_PCH_PWROK")
	)
	(segment
		(start 407.7208 -67.013582)
		(end 407.7208 -67.457574)
		(width 0.10795)
		(layer "B.Cu")
		(net "PWRGD_PCH_PWROK")
	)
	(segment
		(start 407.7208 -67.457574)
		(end 407.61285 -67.565524)
		(width 0.10795)
		(layer "B.Cu")
		(net "PWRGD_PCH_PWROK")
	)
	(segment
		(start 380.468124 -101.390958)
		(end 380.136908 -101.390958)
		(width 0.10795)
		(layer "B.Cu")
		(net "PWRGD_PCH_PWROK")
	)
	(segment
		(start 378.533406 -101.412294)
		(end 378.09297 -101.412294)
		(width 0.10795)
		(layer "B.Cu")
		(net "PWRGD_PCH_PWROK")
	)
	(segment
		(start 379.992636 -101.53523)
		(end 379.611128 -101.53523)
		(width 0.10795)
		(layer "B.Cu")
		(net "PWRGD_PCH_PWROK")
	)
	(segment
		(start 379.120654 -101.418898)
		(end 379.014228 -101.525324)
		(width 0.10795)
		(layer "B.Cu")
		(net "PWRGD_PCH_PWROK")
	)
	(segment
		(start 380.996952 -101.4857)
		(end 380.562866 -101.4857)
		(width 0.10795)
		(layer "B.Cu")
		(net "PWRGD_PCH_PWROK")
	)
	(segment
		(start 377.947174 -101.55809)
		(end 376.802904 -101.55809)
		(width 0.10795)
		(layer "B.Cu")
		(net "PWRGD_PCH_PWROK")
	)
	(segment
		(start 381.29845 -100.181156)
		(end 381.29845 -101.184202)
		(width 0.10795)
		(layer "B.Cu")
		(net "PWRGD_PCH_PWROK")
	)
	(segment
		(start 378.09297 -101.412294)
		(end 377.947174 -101.55809)
		(width 0.10795)
		(layer "B.Cu")
		(net "PWRGD_PCH_PWROK")
	)
	(segment
		(start 380.136908 -101.390958)
		(end 379.992636 -101.53523)
		(width 0.10795)
		(layer "B.Cu")
		(net "PWRGD_PCH_PWROK")
	)
	(segment
		(start 376.278394 -102.0826)
		(end 375.7168 -102.0826)
		(width 0.10795)
		(layer "B.Cu")
		(net "PWRGD_PCH_PWROK")
	)
	(segment
		(start 379.611128 -101.53523)
		(end 379.494796 -101.418898)
		(width 0.10795)
		(layer "B.Cu")
		(net "PWRGD_PCH_PWROK")
	)
	(segment
		(start 407.61285 -67.565524)
		(end 406.60574 -67.565524)
		(width 0.10795)
		(layer "B.Cu")
		(net "PWRGD_PCH_PWROK")
	)
	(segment
		(start 379.014228 -101.525324)
		(end 378.646436 -101.525324)
		(width 0.10795)
		(layer "B.Cu")
		(net "PWRGD_PCH_PWROK")
	)
	(segment
		(start 378.646436 -101.525324)
		(end 378.533406 -101.412294)
		(width 0.10795)
		(layer "B.Cu")
		(net "PWRGD_PCH_PWROK")
	)
	(segment
		(start 376.802904 -101.55809)
		(end 376.278394 -102.0826)
		(width 0.10795)
		(layer "B.Cu")
		(net "PWRGD_PCH_PWROK")
	)
	(segment
		(start 380.562866 -101.4857)
		(end 380.468124 -101.390958)
		(width 0.10795)
		(layer "B.Cu")
		(net "PWRGD_PCH_PWROK")
	)
	(segment
		(start 381.29845 -101.184202)
		(end 380.996952 -101.4857)
		(width 0.10795)
		(layer "B.Cu")
		(net "PWRGD_PCH_PWROK")
	)
	(segment
		(start 379.494796 -101.418898)
		(end 379.120654 -101.418898)
		(width 0.10795)
		(layer "B.Cu")
		(net "PWRGD_PCH_PWROK")
	)
	(segment
		(start 374.8151 -66.23177)
		(end 374.11914 -66.92773)
		(width 0.089408)
		(layer "In4.Cu")
		(net "PWRGD_PCH_PWROK")
	)
	(segment
		(start 381.202184 -66.965576)
		(end 380.453392 -66.216784)
		(width 0.089408)
		(layer "In4.Cu")
		(net "PWRGD_PCH_PWROK")
	)
	(segment
		(start 376.125232 -66.04)
		(end 376.076718 -66.04)
		(width 0.089408)
		(layer "In4.Cu")
		(net "PWRGD_PCH_PWROK")
	)
	(segment
		(start 375.884948 -66.23177)
		(end 374.8151 -66.23177)
		(width 0.089408)
		(layer "In4.Cu")
		(net "PWRGD_PCH_PWROK")
	)
	(segment
		(start 373.638064 -66.92773)
		(end 372.162324 -66.92773)
		(width 0.089408)
		(layer "In4.Cu")
		(net "PWRGD_PCH_PWROK")
	)
	(segment
		(start 396.474696 -64.567816)
		(end 396.238984 -64.803528)
		(width 0.089408)
		(layer "In4.Cu")
		(net "PWRGD_PCH_PWROK")
	)
	(segment
		(start 370.7384 -68.829682)
		(end 370.480082 -69.088)
		(width 0.089408)
		(layer "In4.Cu")
		(net "PWRGD_PCH_PWROK")
	)
	(segment
		(start 393.261596 -64.803782)
		(end 393.261342 -64.803528)
		(width 0.089408)
		(layer "In4.Cu")
		(net "PWRGD_PCH_PWROK")
	)
	(segment
		(start 405.332184 -66.901568)
		(end 405.101552 -67.1322)
		(width 0.089408)
		(layer "In4.Cu")
		(net "PWRGD_PCH_PWROK")
	)
	(segment
		(start 367.824258 -69.088)
		(end 367.518696 -69.393562)
		(width 0.089408)
		(layer "In4.Cu")
		(net "PWRGD_PCH_PWROK")
	)
	(segment
		(start 378.331984 -66.038984)
		(end 376.126248 -66.038984)
		(width 0.089408)
		(layer "In4.Cu")
		(net "PWRGD_PCH_PWROK")
	)
	(segment
		(start 373.638318 -66.927984)
		(end 373.638064 -66.92773)
		(width 0.089408)
		(layer "In4.Cu")
		(net "PWRGD_PCH_PWROK")
	)
	(segment
		(start 405.101552 -67.1322)
		(end 401.653248 -67.1322)
		(width 0.089408)
		(layer "In4.Cu")
		(net "PWRGD_PCH_PWROK")
	)
	(segment
		(start 406.60574 -67.565524)
		(end 406.92959 -67.241674)
		(width 0.089408)
		(layer "In4.Cu")
		(net "PWRGD_PCH_PWROK")
	)
	(segment
		(start 398.6022 -64.93002)
		(end 397.886174 -64.93002)
		(width 0.089408)
		(layer "In4.Cu")
		(net "PWRGD_PCH_PWROK")
	)
	(segment
		(start 406.92959 -67.241674)
		(end 406.92959 -67.05219)
		(width 0.089408)
		(layer "In4.Cu")
		(net "PWRGD_PCH_PWROK")
	)
	(segment
		(start 366.99063 -69.868542)
		(end 366.61725 -69.495162)
		(width 0.089408)
		(layer "In4.Cu")
		(net "PWRGD_PCH_PWROK")
	)
	(segment
		(start 373.954802 -66.927984)
		(end 373.638318 -66.927984)
		(width 0.089408)
		(layer "In4.Cu")
		(net "PWRGD_PCH_PWROK")
	)
	(segment
		(start 393.419584 -64.803782)
		(end 393.261596 -64.803782)
		(width 0.089408)
		(layer "In4.Cu")
		(net "PWRGD_PCH_PWROK")
	)
	(segment
		(start 366.61725 -69.495162)
		(end 366.345216 -69.495162)
		(width 0.089408)
		(layer "In4.Cu")
		(net "PWRGD_PCH_PWROK")
	)
	(segment
		(start 401.653248 -67.1322)
		(end 400.23796 -65.716912)
		(width 0.089408)
		(layer "In4.Cu")
		(net "PWRGD_PCH_PWROK")
	)
	(segment
		(start 393.419838 -64.804036)
		(end 393.419584 -64.803782)
		(width 0.089408)
		(layer "In4.Cu")
		(net "PWRGD_PCH_PWROK")
	)
	(segment
		(start 378.509784 -66.216784)
		(end 378.331984 -66.038984)
		(width 0.089408)
		(layer "In4.Cu")
		(net "PWRGD_PCH_PWROK")
	)
	(segment
		(start 399.389092 -65.716912)
		(end 398.6022 -64.93002)
		(width 0.089408)
		(layer "In4.Cu")
		(net "PWRGD_PCH_PWROK")
	)
	(segment
		(start 367.300002 -69.868542)
		(end 366.99063 -69.868542)
		(width 0.089408)
		(layer "In4.Cu")
		(net "PWRGD_PCH_PWROK")
	)
	(segment
		(start 373.955056 -66.92773)
		(end 373.954802 -66.927984)
		(width 0.089408)
		(layer "In4.Cu")
		(net "PWRGD_PCH_PWROK")
	)
	(segment
		(start 397.52397 -64.567816)
		(end 396.474696 -64.567816)
		(width 0.089408)
		(layer "In4.Cu")
		(net "PWRGD_PCH_PWROK")
	)
	(segment
		(start 370.7384 -68.351654)
		(end 370.7384 -68.829682)
		(width 0.089408)
		(layer "In4.Cu")
		(net "PWRGD_PCH_PWROK")
	)
	(segment
		(start 406.92959 -67.05219)
		(end 406.778968 -66.901568)
		(width 0.089408)
		(layer "In4.Cu")
		(net "PWRGD_PCH_PWROK")
	)
	(segment
		(start 372.162324 -66.92773)
		(end 370.7384 -68.351654)
		(width 0.089408)
		(layer "In4.Cu")
		(net "PWRGD_PCH_PWROK")
	)
	(segment
		(start 376.076718 -66.04)
		(end 375.884948 -66.23177)
		(width 0.089408)
		(layer "In4.Cu")
		(net "PWRGD_PCH_PWROK")
	)
	(segment
		(start 393.261342 -64.803528)
		(end 390.518904 -64.803528)
		(width 0.089408)
		(layer "In4.Cu")
		(net "PWRGD_PCH_PWROK")
	)
	(segment
		(start 394.370814 -64.803528)
		(end 394.370306 -64.804036)
		(width 0.089408)
		(layer "In4.Cu")
		(net "PWRGD_PCH_PWROK")
	)
	(segment
		(start 394.370306 -64.804036)
		(end 393.419838 -64.804036)
		(width 0.089408)
		(layer "In4.Cu")
		(net "PWRGD_PCH_PWROK")
	)
	(segment
		(start 367.518696 -69.649848)
		(end 367.300002 -69.868542)
		(width 0.089408)
		(layer "In4.Cu")
		(net "PWRGD_PCH_PWROK")
	)
	(segment
		(start 400.23796 -65.716912)
		(end 399.389092 -65.716912)
		(width 0.089408)
		(layer "In4.Cu")
		(net "PWRGD_PCH_PWROK")
	)
	(segment
		(start 396.238984 -64.803528)
		(end 394.370814 -64.803528)
		(width 0.089408)
		(layer "In4.Cu")
		(net "PWRGD_PCH_PWROK")
	)
	(segment
		(start 380.453392 -66.216784)
		(end 378.509784 -66.216784)
		(width 0.089408)
		(layer "In4.Cu")
		(net "PWRGD_PCH_PWROK")
	)
	(segment
		(start 388.356856 -66.965576)
		(end 381.202184 -66.965576)
		(width 0.089408)
		(layer "In4.Cu")
		(net "PWRGD_PCH_PWROK")
	)
	(segment
		(start 374.11914 -66.92773)
		(end 373.955056 -66.92773)
		(width 0.089408)
		(layer "In4.Cu")
		(net "PWRGD_PCH_PWROK")
	)
	(segment
		(start 397.886174 -64.93002)
		(end 397.52397 -64.567816)
		(width 0.089408)
		(layer "In4.Cu")
		(net "PWRGD_PCH_PWROK")
	)
	(segment
		(start 367.518696 -69.393562)
		(end 367.518696 -69.649848)
		(width 0.089408)
		(layer "In4.Cu")
		(net "PWRGD_PCH_PWROK")
	)
	(segment
		(start 376.126248 -66.038984)
		(end 376.125232 -66.04)
		(width 0.089408)
		(layer "In4.Cu")
		(net "PWRGD_PCH_PWROK")
	)
	(segment
		(start 370.480082 -69.088)
		(end 367.824258 -69.088)
		(width 0.089408)
		(layer "In4.Cu")
		(net "PWRGD_PCH_PWROK")
	)
	(segment
		(start 390.518904 -64.803528)
		(end 388.356856 -66.965576)
		(width 0.089408)
		(layer "In4.Cu")
		(net "PWRGD_PCH_PWROK")
	)
	(segment
		(start 406.778968 -66.901568)
		(end 405.332184 -66.901568)
		(width 0.089408)
		(layer "In4.Cu")
		(net "PWRGD_PCH_PWROK")
	)
	(segment
		(start 418.893244 -41.717976)
		(end 419.090094 -41.914826)
		(width 0.089408)
		(layer "In9.Cu")
		(net "PWRGD_PCH_PWROK")
	)
	(segment
		(start 419.090094 -42.319448)
		(end 417.917122 -43.49242)
		(width 0.089408)
		(layer "In9.Cu")
		(net "PWRGD_PCH_PWROK")
	)
	(segment
		(start 418.2872 -41.580562)
		(end 418.424614 -41.717976)
		(width 0.089408)
		(layer "In9.Cu")
		(net "PWRGD_PCH_PWROK")
	)
	(segment
		(start 417.917122 -43.49242)
		(end 417.917122 -45.866558)
		(width 0.089408)
		(layer "In9.Cu")
		(net "PWRGD_PCH_PWROK")
	)
	(segment
		(start 412.053024 -48.53559)
		(end 411.037278 -49.551336)
		(width 0.089408)
		(layer "In9.Cu")
		(net "PWRGD_PCH_PWROK")
	)
	(segment
		(start 417.917122 -45.866558)
		(end 418.089842 -46.039278)
		(width 0.089408)
		(layer "In9.Cu")
		(net "PWRGD_PCH_PWROK")
	)
	(segment
		(start 418.424614 -41.717976)
		(end 418.893244 -41.717976)
		(width 0.089408)
		(layer "In9.Cu")
		(net "PWRGD_PCH_PWROK")
	)
	(segment
		(start 407.497534 -61.851032)
		(end 407.886408 -62.239906)
		(width 0.089408)
		(layer "In9.Cu")
		(net "PWRGD_PCH_PWROK")
	)
	(segment
		(start 418.2872 -40.40124)
		(end 418.2872 -41.580562)
		(width 0.089408)
		(layer "In9.Cu")
		(net "PWRGD_PCH_PWROK")
	)
	(segment
		(start 418.089842 -46.039278)
		(end 418.089842 -47.280322)
		(width 0.089408)
		(layer "In9.Cu")
		(net "PWRGD_PCH_PWROK")
	)
	(segment
		(start 408.312366 -54.642258)
		(end 408.294586 -54.660038)
		(width 0.089408)
		(layer "In9.Cu")
		(net "PWRGD_PCH_PWROK")
	)
	(segment
		(start 413.890206 -41.33469)
		(end 415.089594 -40.135302)
		(width 0.089408)
		(layer "In9.Cu")
		(net "PWRGD_PCH_PWROK")
	)
	(segment
		(start 411.037278 -50.545746)
		(end 408.312366 -53.270658)
		(width 0.089408)
		(layer "In9.Cu")
		(net "PWRGD_PCH_PWROK")
	)
	(segment
		(start 408.294586 -54.660038)
		(end 408.294586 -54.665118)
		(width 0.089408)
		(layer "In9.Cu")
		(net "PWRGD_PCH_PWROK")
	)
	(segment
		(start 407.688542 -55.271162)
		(end 407.688542 -60.81014)
		(width 0.089408)
		(layer "In9.Cu")
		(net "PWRGD_PCH_PWROK")
	)
	(segment
		(start 407.886408 -62.239906)
		(end 407.886408 -66.38036)
		(width 0.089408)
		(layer "In9.Cu")
		(net "PWRGD_PCH_PWROK")
	)
	(segment
		(start 412.73603 -48.53559)
		(end 412.053024 -48.53559)
		(width 0.089408)
		(layer "In9.Cu")
		(net "PWRGD_PCH_PWROK")
	)
	(segment
		(start 407.886408 -66.38036)
		(end 406.701244 -67.565524)
		(width 0.089408)
		(layer "In9.Cu")
		(net "PWRGD_PCH_PWROK")
	)
	(segment
		(start 419.090094 -41.914826)
		(end 419.090094 -42.319448)
		(width 0.089408)
		(layer "In9.Cu")
		(net "PWRGD_PCH_PWROK")
	)
	(segment
		(start 418.089842 -47.280322)
		(end 417.485068 -47.885096)
		(width 0.089408)
		(layer "In9.Cu")
		(net "PWRGD_PCH_PWROK")
	)
	(segment
		(start 418.021262 -40.135302)
		(end 418.2872 -40.40124)
		(width 0.089408)
		(layer "In9.Cu")
		(net "PWRGD_PCH_PWROK")
	)
	(segment
		(start 407.688542 -60.81014)
		(end 407.497534 -61.001148)
		(width 0.089408)
		(layer "In9.Cu")
		(net "PWRGD_PCH_PWROK")
	)
	(segment
		(start 415.619184 -48.088804)
		(end 413.182816 -48.088804)
		(width 0.089408)
		(layer "In9.Cu")
		(net "PWRGD_PCH_PWROK")
	)
	(segment
		(start 417.485068 -47.885096)
		(end 415.822892 -47.885096)
		(width 0.089408)
		(layer "In9.Cu")
		(net "PWRGD_PCH_PWROK")
	)
	(segment
		(start 406.701244 -67.565524)
		(end 406.60574 -67.565524)
		(width 0.089408)
		(layer "In9.Cu")
		(net "PWRGD_PCH_PWROK")
	)
	(segment
		(start 408.294586 -54.665118)
		(end 407.688542 -55.271162)
		(width 0.089408)
		(layer "In9.Cu")
		(net "PWRGD_PCH_PWROK")
	)
	(segment
		(start 408.312366 -53.270658)
		(end 408.312366 -54.642258)
		(width 0.089408)
		(layer "In9.Cu")
		(net "PWRGD_PCH_PWROK")
	)
	(segment
		(start 413.182816 -48.088804)
		(end 412.73603 -48.53559)
		(width 0.089408)
		(layer "In9.Cu")
		(net "PWRGD_PCH_PWROK")
	)
	(segment
		(start 411.037278 -49.551336)
		(end 411.037278 -50.545746)
		(width 0.089408)
		(layer "In9.Cu")
		(net "PWRGD_PCH_PWROK")
	)
	(segment
		(start 415.089594 -40.135302)
		(end 418.021262 -40.135302)
		(width 0.089408)
		(layer "In9.Cu")
		(net "PWRGD_PCH_PWROK")
	)
	(segment
		(start 407.497534 -61.001148)
		(end 407.497534 -61.851032)
		(width 0.089408)
		(layer "In9.Cu")
		(net "PWRGD_PCH_PWROK")
	)
	(segment
		(start 415.822892 -47.885096)
		(end 415.619184 -48.088804)
		(width 0.089408)
		(layer "In9.Cu")
		(net "PWRGD_PCH_PWROK")
	)
	(segment
		(start 379.647196 -99.721416)
		(end 379.977904 -99.721416)
		(width 0.089408)
		(layer "In11.Cu")
		(net "PWRGD_PCH_PWROK")
	)
	(segment
		(start 366.790732 -80.868774)
		(end 367.009426 -81.087468)
		(width 0.089408)
		(layer "In11.Cu")
		(net "PWRGD_PCH_PWROK")
	)
	(segment
		(start 367.358676 -83.665568)
		(end 367.00206 -84.022184)
		(width 0.089408)
		(layer "In11.Cu")
		(net "PWRGD_PCH_PWROK")
	)
	(segment
		(start 369.753896 -92.182696)
		(end 369.753896 -95.060262)
		(width 0.089408)
		(layer "In11.Cu")
		(net "PWRGD_PCH_PWROK")
	)
	(segment
		(start 366.78235 -80.10525)
		(end 366.78235 -80.855566)
		(width 0.089408)
		(layer "In11.Cu")
		(net "PWRGD_PCH_PWROK")
	)
	(segment
		(start 380.83871 -99.721416)
		(end 381.29845 -100.181156)
		(width 0.089408)
		(layer "In11.Cu")
		(net "PWRGD_PCH_PWROK")
	)
	(segment
		(start 370.320062 -95.294704)
		(end 371.749066 -93.8657)
		(width 0.089408)
		(layer "In11.Cu")
		(net "PWRGD_PCH_PWROK")
	)
	(segment
		(start 367.014252 -81.087468)
		(end 367.358676 -81.431892)
		(width 0.089408)
		(layer "In11.Cu")
		(net "PWRGD_PCH_PWROK")
	)
	(segment
		(start 368.7064 -91.1352)
		(end 369.753896 -92.182696)
		(width 0.089408)
		(layer "In11.Cu")
		(net "PWRGD_PCH_PWROK")
	)
	(segment
		(start 378.987304 -99.721416)
		(end 379.01372 -99.695)
		(width 0.089408)
		(layer "In11.Cu")
		(net "PWRGD_PCH_PWROK")
	)
	(segment
		(start 368.7064 -90.2843)
		(end 368.7064 -91.1352)
		(width 0.089408)
		(layer "In11.Cu")
		(net "PWRGD_PCH_PWROK")
	)
	(segment
		(start 366.345216 -69.495162)
		(end 366.771936 -69.921882)
		(width 0.089408)
		(layer "In11.Cu")
		(net "PWRGD_PCH_PWROK")
	)
	(segment
		(start 369.988338 -95.294704)
		(end 370.320062 -95.294704)
		(width 0.089408)
		(layer "In11.Cu")
		(net "PWRGD_PCH_PWROK")
	)
	(segment
		(start 379.62078 -99.695)
		(end 379.647196 -99.721416)
		(width 0.089408)
		(layer "In11.Cu")
		(net "PWRGD_PCH_PWROK")
	)
	(segment
		(start 378.656596 -99.721416)
		(end 378.987304 -99.721416)
		(width 0.089408)
		(layer "In11.Cu")
		(net "PWRGD_PCH_PWROK")
	)
	(segment
		(start 367.358676 -81.431892)
		(end 367.358676 -83.665568)
		(width 0.089408)
		(layer "In11.Cu")
		(net "PWRGD_PCH_PWROK")
	)
	(segment
		(start 368.3254 -78.457806)
		(end 368.11077 -78.672436)
		(width 0.089408)
		(layer "In11.Cu")
		(net "PWRGD_PCH_PWROK")
	)
	(segment
		(start 375.2088 -94.9452)
		(end 375.2088 -98.5012)
		(width 0.089408)
		(layer "In11.Cu")
		(net "PWRGD_PCH_PWROK")
	)
	(segment
		(start 368.11077 -78.672436)
		(end 367.812574 -78.672436)
		(width 0.089408)
		(layer "In11.Cu")
		(net "PWRGD_PCH_PWROK")
	)
	(segment
		(start 367.00206 -84.022184)
		(end 367.00206 -87.0585)
		(width 0.089408)
		(layer "In11.Cu")
		(net "PWRGD_PCH_PWROK")
	)
	(segment
		(start 378.50318 -99.568)
		(end 378.656596 -99.721416)
		(width 0.089408)
		(layer "In11.Cu")
		(net "PWRGD_PCH_PWROK")
	)
	(segment
		(start 380.61138 -99.695)
		(end 380.637796 -99.721416)
		(width 0.089408)
		(layer "In11.Cu")
		(net "PWRGD_PCH_PWROK")
	)
	(segment
		(start 367.538 -79.3496)
		(end 366.78235 -80.10525)
		(width 0.089408)
		(layer "In11.Cu")
		(net "PWRGD_PCH_PWROK")
	)
	(segment
		(start 379.01372 -99.695)
		(end 379.62078 -99.695)
		(width 0.089408)
		(layer "In11.Cu")
		(net "PWRGD_PCH_PWROK")
	)
	(segment
		(start 366.790732 -80.863948)
		(end 366.790732 -80.868774)
		(width 0.089408)
		(layer "In11.Cu")
		(net "PWRGD_PCH_PWROK")
	)
	(segment
		(start 367.538 -78.94701)
		(end 367.538 -79.3496)
		(width 0.089408)
		(layer "In11.Cu")
		(net "PWRGD_PCH_PWROK")
	)
	(segment
		(start 368.808 -88.86444)
		(end 368.808 -90.1827)
		(width 0.089408)
		(layer "In11.Cu")
		(net "PWRGD_PCH_PWROK")
	)
	(segment
		(start 368.117882 -69.921882)
		(end 368.3254 -70.1294)
		(width 0.089408)
		(layer "In11.Cu")
		(net "PWRGD_PCH_PWROK")
	)
	(segment
		(start 380.637796 -99.721416)
		(end 380.83871 -99.721416)
		(width 0.089408)
		(layer "In11.Cu")
		(net "PWRGD_PCH_PWROK")
	)
	(segment
		(start 374.1293 -93.8657)
		(end 375.2088 -94.9452)
		(width 0.089408)
		(layer "In11.Cu")
		(net "PWRGD_PCH_PWROK")
	)
	(segment
		(start 368.808 -90.1827)
		(end 368.7064 -90.2843)
		(width 0.089408)
		(layer "In11.Cu")
		(net "PWRGD_PCH_PWROK")
	)
	(segment
		(start 367.00206 -87.0585)
		(end 368.808 -88.86444)
		(width 0.089408)
		(layer "In11.Cu")
		(net "PWRGD_PCH_PWROK")
	)
	(segment
		(start 367.812574 -78.672436)
		(end 367.538 -78.94701)
		(width 0.089408)
		(layer "In11.Cu")
		(net "PWRGD_PCH_PWROK")
	)
	(segment
		(start 366.771936 -69.921882)
		(end 368.117882 -69.921882)
		(width 0.089408)
		(layer "In11.Cu")
		(net "PWRGD_PCH_PWROK")
	)
	(segment
		(start 376.2756 -99.568)
		(end 378.50318 -99.568)
		(width 0.089408)
		(layer "In11.Cu")
		(net "PWRGD_PCH_PWROK")
	)
	(segment
		(start 368.3254 -70.1294)
		(end 368.3254 -78.457806)
		(width 0.089408)
		(layer "In11.Cu")
		(net "PWRGD_PCH_PWROK")
	)
	(segment
		(start 366.78235 -80.855566)
		(end 366.790732 -80.863948)
		(width 0.089408)
		(layer "In11.Cu")
		(net "PWRGD_PCH_PWROK")
	)
	(segment
		(start 369.753896 -95.060262)
		(end 369.988338 -95.294704)
		(width 0.089408)
		(layer "In11.Cu")
		(net "PWRGD_PCH_PWROK")
	)
	(segment
		(start 379.977904 -99.721416)
		(end 380.00432 -99.695)
		(width 0.089408)
		(layer "In11.Cu")
		(net "PWRGD_PCH_PWROK")
	)
	(segment
		(start 380.00432 -99.695)
		(end 380.61138 -99.695)
		(width 0.089408)
		(layer "In11.Cu")
		(net "PWRGD_PCH_PWROK")
	)
	(segment
		(start 371.749066 -93.8657)
		(end 374.1293 -93.8657)
		(width 0.089408)
		(layer "In11.Cu")
		(net "PWRGD_PCH_PWROK")
	)
	(segment
		(start 367.009426 -81.087468)
		(end 367.014252 -81.087468)
		(width 0.089408)
		(layer "In11.Cu")
		(net "PWRGD_PCH_PWROK")
	)
	(segment
		(start 375.2088 -98.5012)
		(end 376.2756 -99.568)
		(width 0.089408)
		(layer "In11.Cu")
		(net "PWRGD_PCH_PWROK")
	)
	(segment
		(start 399.542 -77.089)
		(end 400.304 -77.089)
		(width 0.10795)
		(layer "F.Cu")
		(net "PWRGD_P12V_HSC")
	)
	(segment
		(start 401.01266 -73.89368)
		(end 400.789394 -73.89368)
		(width 0.10795)
		(layer "F.Cu")
		(net "PWRGD_P12V_HSC")
	)
	(segment
		(start 401.390358 -74.963274)
		(end 401.4724 -74.881232)
		(width 0.10795)
		(layer "F.Cu")
		(net "PWRGD_P12V_HSC")
	)
	(segment
		(start 12.3317 -76.6191)
		(end 12.3317 -75.4507)
		(width 0.10795)
		(layer "F.Cu")
		(net "PWRGD_P12V_HSC")
	)
	(segment
		(start 400.304 -77.089)
		(end 400.685 -76.708)
		(width 0.10795)
		(layer "F.Cu")
		(net "PWRGD_P12V_HSC")
	)
	(segment
		(start 12.7762 -75.0062)
		(end 12.9286 -75.0062)
		(width 0.10795)
		(layer "F.Cu")
		(net "PWRGD_P12V_HSC")
	)
	(segment
		(start 401.390358 -75.313286)
		(end 401.390358 -74.963274)
		(width 0.10795)
		(layer "F.Cu")
		(net "PWRGD_P12V_HSC")
	)
	(segment
		(start 401.4724 -74.35342)
		(end 401.01266 -73.89368)
		(width 0.10795)
		(layer "F.Cu")
		(net "PWRGD_P12V_HSC")
	)
	(segment
		(start 400.585178 -74.097896)
		(end 399.909538 -74.097896)
		(width 0.10795)
		(layer "F.Cu")
		(net "PWRGD_P12V_HSC")
	)
	(segment
		(start 401.4724 -74.881232)
		(end 401.4724 -74.35342)
		(width 0.10795)
		(layer "F.Cu")
		(net "PWRGD_P12V_HSC")
	)
	(segment
		(start 400.789394 -73.89368)
		(end 400.585178 -74.097896)
		(width 0.10795)
		(layer "F.Cu")
		(net "PWRGD_P12V_HSC")
	)
	(segment
		(start 12.3317 -75.4507)
		(end 12.7762 -75.0062)
		(width 0.10795)
		(layer "F.Cu")
		(net "PWRGD_P12V_HSC")
	)
	(segment
		(start 401.4724 -75.565)
		(end 401.4724 -75.395328)
		(width 0.10795)
		(layer "F.Cu")
		(net "PWRGD_P12V_HSC")
	)
	(segment
		(start 400.685 -76.073)
		(end 400.9644 -76.073)
		(width 0.10795)
		(layer "F.Cu")
		(net "PWRGD_P12V_HSC")
	)
	(segment
		(start 400.685 -76.708)
		(end 400.685 -76.073)
		(width 0.10795)
		(layer "F.Cu")
		(net "PWRGD_P12V_HSC")
	)
	(segment
		(start 401.4724 -75.395328)
		(end 401.390358 -75.313286)
		(width 0.10795)
		(layer "F.Cu")
		(net "PWRGD_P12V_HSC")
	)
	(segment
		(start 400.9644 -76.073)
		(end 401.4724 -75.565)
		(width 0.10795)
		(layer "F.Cu")
		(net "PWRGD_P12V_HSC")
	)
	(via
		(at 12.3317 -76.6191)
		(size 0.508)
		(drill 0.254)
		(layers "F.Cu" "B.Cu")
		(net "PWRGD_P12V_HSC")
	)
	(via
		(at 323.3928 -147.8788)
		(size 0.508)
		(drill 0.254)
		(layers "F.Cu" "B.Cu")
		(net "PWRGD_P12V_HSC")
	)
	(via
		(at 401.01266 -73.89368)
		(size 0.508)
		(drill 0.254)
		(layers "F.Cu" "B.Cu")
		(net "PWRGD_P12V_HSC")
	)
	(via
		(at 406.21458 -62.56274)
		(size 0.508)
		(drill 0.254)
		(layers "F.Cu" "B.Cu")
		(net "PWRGD_P12V_HSC")
	)
	(segment
		(start 388.396734 -62.47384)
		(end 386.650484 -62.47384)
		(width 0.089408)
		(layer "In4.Cu")
		(net "PWRGD_P12V_HSC")
	)
	(segment
		(start 362.434886 -70.227698)
		(end 359.001314 -70.227698)
		(width 0.089408)
		(layer "In4.Cu")
		(net "PWRGD_P12V_HSC")
	)
	(segment
		(start 338.568792 -70.930008)
		(end 337.019392 -72.479408)
		(width 0.089408)
		(layer "In4.Cu")
		(net "PWRGD_P12V_HSC")
	)
	(segment
		(start 390.71931 -62.89294)
		(end 390.03351 -62.20714)
		(width 0.089408)
		(layer "In4.Cu")
		(net "PWRGD_P12V_HSC")
	)
	(segment
		(start 383.742184 -61.7474)
		(end 383.027682 -61.7474)
		(width 0.089408)
		(layer "In4.Cu")
		(net "PWRGD_P12V_HSC")
	)
	(segment
		(start 378.8156 -62.686946)
		(end 378.087128 -63.415418)
		(width 0.089408)
		(layer "In4.Cu")
		(net "PWRGD_P12V_HSC")
	)
	(segment
		(start 325.177658 -118.830344)
		(end 325.177658 -123.254008)
		(width 0.089408)
		(layer "In4.Cu")
		(net "PWRGD_P12V_HSC")
	)
	(segment
		(start 390.03351 -62.20714)
		(end 388.663434 -62.20714)
		(width 0.089408)
		(layer "In4.Cu")
		(net "PWRGD_P12V_HSC")
	)
	(segment
		(start 385.305554 -63.817754)
		(end 384.199892 -63.817754)
		(width 0.089408)
		(layer "In4.Cu")
		(net "PWRGD_P12V_HSC")
	)
	(segment
		(start 372.28526 -61.918596)
		(end 370.58981 -63.614046)
		(width 0.089408)
		(layer "In4.Cu")
		(net "PWRGD_P12V_HSC")
	)
	(segment
		(start 340.015576 -69.921882)
		(end 339.00745 -70.930008)
		(width 0.089408)
		(layer "In4.Cu")
		(net "PWRGD_P12V_HSC")
	)
	(segment
		(start 333.39024 -79.665322)
		(end 330.569824 -82.485738)
		(width 0.089408)
		(layer "In4.Cu")
		(net "PWRGD_P12V_HSC")
	)
	(segment
		(start 394.09116 -61.849)
		(end 393.65428 -61.41212)
		(width 0.089408)
		(layer "In4.Cu")
		(net "PWRGD_P12V_HSC")
	)
	(segment
		(start 379.679454 -62.686946)
		(end 378.8156 -62.686946)
		(width 0.089408)
		(layer "In4.Cu")
		(net "PWRGD_P12V_HSC")
	)
	(segment
		(start 393.65428 -61.41212)
		(end 392.990578 -61.41212)
		(width 0.089408)
		(layer "In4.Cu")
		(net "PWRGD_P12V_HSC")
	)
	(segment
		(start 383.027682 -61.7474)
		(end 382.826006 -61.949076)
		(width 0.089408)
		(layer "In4.Cu")
		(net "PWRGD_P12V_HSC")
	)
	(segment
		(start 363.070902 -69.591682)
		(end 362.434886 -70.227698)
		(width 0.089408)
		(layer "In4.Cu")
		(net "PWRGD_P12V_HSC")
	)
	(segment
		(start 324.03796 -135.745728)
		(end 323.589396 -136.194292)
		(width 0.089408)
		(layer "In4.Cu")
		(net "PWRGD_P12V_HSC")
	)
	(segment
		(start 377.552204 -63.415418)
		(end 376.679206 -62.54242)
		(width 0.089408)
		(layer "In4.Cu")
		(net "PWRGD_P12V_HSC")
	)
	(segment
		(start 354.093018 -69.020436)
		(end 354.092002 -69.021452)
		(width 0.089408)
		(layer "In4.Cu")
		(net "PWRGD_P12V_HSC")
	)
	(segment
		(start 384.199892 -63.817754)
		(end 383.958338 -63.5762)
		(width 0.089408)
		(layer "In4.Cu")
		(net "PWRGD_P12V_HSC")
	)
	(segment
		(start 376.679206 -62.54242)
		(end 375.693432 -62.54242)
		(width 0.089408)
		(layer "In4.Cu")
		(net "PWRGD_P12V_HSC")
	)
	(segment
		(start 345.248992 -69.921882)
		(end 340.015576 -69.921882)
		(width 0.089408)
		(layer "In4.Cu")
		(net "PWRGD_P12V_HSC")
	)
	(segment
		(start 406.21458 -63.459614)
		(end 405.498554 -64.17564)
		(width 0.089408)
		(layer "In4.Cu")
		(net "PWRGD_P12V_HSC")
	)
	(segment
		(start 323.493638 -115.1509)
		(end 324.614286 -116.271548)
		(width 0.089408)
		(layer "In4.Cu")
		(net "PWRGD_P12V_HSC")
	)
	(segment
		(start 392.740896 -62.02553)
		(end 392.189462 -62.576964)
		(width 0.089408)
		(layer "In4.Cu")
		(net "PWRGD_P12V_HSC")
	)
	(segment
		(start 353.740974 -69.37121)
		(end 345.799664 -69.37121)
		(width 0.089408)
		(layer "In4.Cu")
		(net "PWRGD_P12V_HSC")
	)
	(segment
		(start 323.10959 -138.61161)
		(end 323.10959 -147.59559)
		(width 0.089408)
		(layer "In4.Cu")
		(net "PWRGD_P12V_HSC")
	)
	(segment
		(start 399.550382 -63.003176)
		(end 398.396206 -61.849)
		(width 0.089408)
		(layer "In4.Cu")
		(net "PWRGD_P12V_HSC")
	)
	(segment
		(start 323.10959 -147.59559)
		(end 323.3928 -147.8788)
		(width 0.089408)
		(layer "In4.Cu")
		(net "PWRGD_P12V_HSC")
	)
	(segment
		(start 404.537672 -64.17564)
		(end 403.365208 -63.003176)
		(width 0.089408)
		(layer "In4.Cu")
		(net "PWRGD_P12V_HSC")
	)
	(segment
		(start 339.00745 -70.930008)
		(end 338.568792 -70.930008)
		(width 0.089408)
		(layer "In4.Cu")
		(net "PWRGD_P12V_HSC")
	)
	(segment
		(start 392.189462 -62.577218)
		(end 391.87374 -62.89294)
		(width 0.089408)
		(layer "In4.Cu")
		(net "PWRGD_P12V_HSC")
	)
	(segment
		(start 386.360924 -62.7634)
		(end 386.359908 -62.7634)
		(width 0.089408)
		(layer "In4.Cu")
		(net "PWRGD_P12V_HSC")
	)
	(segment
		(start 388.663434 -62.20714)
		(end 388.396734 -62.47384)
		(width 0.089408)
		(layer "In4.Cu")
		(net "PWRGD_P12V_HSC")
	)
	(segment
		(start 323.8246 -137.8966)
		(end 323.10959 -138.61161)
		(width 0.089408)
		(layer "In4.Cu")
		(net "PWRGD_P12V_HSC")
	)
	(segment
		(start 381.082804 -62.41161)
		(end 379.95479 -62.41161)
		(width 0.089408)
		(layer "In4.Cu")
		(net "PWRGD_P12V_HSC")
	)
	(segment
		(start 378.087128 -63.415418)
		(end 377.552204 -63.415418)
		(width 0.089408)
		(layer "In4.Cu")
		(net "PWRGD_P12V_HSC")
	)
	(segment
		(start 345.799664 -69.37121)
		(end 345.248992 -69.921882)
		(width 0.089408)
		(layer "In4.Cu")
		(net "PWRGD_P12V_HSC")
	)
	(segment
		(start 324.935342 -128.723644)
		(end 324.935342 -131.432046)
		(width 0.089408)
		(layer "In4.Cu")
		(net "PWRGD_P12V_HSC")
	)
	(segment
		(start 324.614286 -118.266972)
		(end 325.177658 -118.830344)
		(width 0.089408)
		(layer "In4.Cu")
		(net "PWRGD_P12V_HSC")
	)
	(segment
		(start 335.10728 -72.479408)
		(end 333.39024 -74.196448)
		(width 0.089408)
		(layer "In4.Cu")
		(net "PWRGD_P12V_HSC")
	)
	(segment
		(start 383.958338 -63.5762)
		(end 383.958338 -61.963554)
		(width 0.089408)
		(layer "In4.Cu")
		(net "PWRGD_P12V_HSC")
	)
	(segment
		(start 325.453756 -128.20523)
		(end 324.935342 -128.723644)
		(width 0.089408)
		(layer "In4.Cu")
		(net "PWRGD_P12V_HSC")
	)
	(segment
		(start 325.208646 -131.70535)
		(end 325.208646 -132.964428)
		(width 0.089408)
		(layer "In4.Cu")
		(net "PWRGD_P12V_HSC")
	)
	(segment
		(start 373.015764 -62.122304)
		(end 372.812056 -61.918596)
		(width 0.089408)
		(layer "In4.Cu")
		(net "PWRGD_P12V_HSC")
	)
	(segment
		(start 370.58981 -63.614046)
		(end 368.696748 -63.614046)
		(width 0.089408)
		(layer "In4.Cu")
		(net "PWRGD_P12V_HSC")
	)
	(segment
		(start 375.693432 -62.54242)
		(end 375.273316 -62.122304)
		(width 0.089408)
		(layer "In4.Cu")
		(net "PWRGD_P12V_HSC")
	)
	(segment
		(start 386.359908 -62.7634)
		(end 385.305554 -63.817754)
		(width 0.089408)
		(layer "In4.Cu")
		(net "PWRGD_P12V_HSC")
	)
	(segment
		(start 323.589396 -137.389108)
		(end 323.8246 -137.624312)
		(width 0.089408)
		(layer "In4.Cu")
		(net "PWRGD_P12V_HSC")
	)
	(segment
		(start 323.8246 -137.624312)
		(end 323.8246 -137.8966)
		(width 0.089408)
		(layer "In4.Cu")
		(net "PWRGD_P12V_HSC")
	)
	(segment
		(start 392.990578 -61.41212)
		(end 392.740896 -61.661802)
		(width 0.089408)
		(layer "In4.Cu")
		(net "PWRGD_P12V_HSC")
	)
	(segment
		(start 405.498554 -64.17564)
		(end 404.537672 -64.17564)
		(width 0.089408)
		(layer "In4.Cu")
		(net "PWRGD_P12V_HSC")
	)
	(segment
		(start 406.21458 -62.56274)
		(end 406.21458 -63.459614)
		(width 0.089408)
		(layer "In4.Cu")
		(net "PWRGD_P12V_HSC")
	)
	(segment
		(start 363.070902 -69.239892)
		(end 363.070902 -69.591682)
		(width 0.089408)
		(layer "In4.Cu")
		(net "PWRGD_P12V_HSC")
	)
	(segment
		(start 330.569824 -82.485738)
		(end 330.569824 -84.555076)
		(width 0.089408)
		(layer "In4.Cu")
		(net "PWRGD_P12V_HSC")
	)
	(segment
		(start 392.189462 -62.576964)
		(end 392.189462 -62.577218)
		(width 0.089408)
		(layer "In4.Cu")
		(net "PWRGD_P12V_HSC")
	)
	(segment
		(start 324.614286 -116.271548)
		(end 324.614286 -118.266972)
		(width 0.089408)
		(layer "In4.Cu")
		(net "PWRGD_P12V_HSC")
	)
	(segment
		(start 325.177658 -123.254008)
		(end 326.527668 -124.604018)
		(width 0.089408)
		(layer "In4.Cu")
		(net "PWRGD_P12V_HSC")
	)
	(segment
		(start 368.696748 -63.614046)
		(end 363.070902 -69.239892)
		(width 0.089408)
		(layer "In4.Cu")
		(net "PWRGD_P12V_HSC")
	)
	(segment
		(start 354.090732 -69.021452)
		(end 353.740974 -69.37121)
		(width 0.089408)
		(layer "In4.Cu")
		(net "PWRGD_P12V_HSC")
	)
	(segment
		(start 323.589396 -136.194292)
		(end 323.589396 -137.389108)
		(width 0.089408)
		(layer "In4.Cu")
		(net "PWRGD_P12V_HSC")
	)
	(segment
		(start 386.650484 -62.47384)
		(end 386.360924 -62.7634)
		(width 0.089408)
		(layer "In4.Cu")
		(net "PWRGD_P12V_HSC")
	)
	(segment
		(start 372.812056 -61.918596)
		(end 372.28526 -61.918596)
		(width 0.089408)
		(layer "In4.Cu")
		(net "PWRGD_P12V_HSC")
	)
	(segment
		(start 379.95479 -62.41161)
		(end 379.679454 -62.686946)
		(width 0.089408)
		(layer "In4.Cu")
		(net "PWRGD_P12V_HSC")
	)
	(segment
		(start 326.527668 -126.562104)
		(end 325.453756 -127.636016)
		(width 0.089408)
		(layer "In4.Cu")
		(net "PWRGD_P12V_HSC")
	)
	(segment
		(start 337.019392 -72.479408)
		(end 335.10728 -72.479408)
		(width 0.089408)
		(layer "In4.Cu")
		(net "PWRGD_P12V_HSC")
	)
	(segment
		(start 324.935342 -131.432046)
		(end 325.208646 -131.70535)
		(width 0.089408)
		(layer "In4.Cu")
		(net "PWRGD_P12V_HSC")
	)
	(segment
		(start 324.03796 -134.135114)
		(end 324.03796 -135.745728)
		(width 0.089408)
		(layer "In4.Cu")
		(net "PWRGD_P12V_HSC")
	)
	(segment
		(start 325.208646 -132.964428)
		(end 324.03796 -134.135114)
		(width 0.089408)
		(layer "In4.Cu")
		(net "PWRGD_P12V_HSC")
	)
	(segment
		(start 323.493638 -91.631262)
		(end 323.493638 -115.1509)
		(width 0.089408)
		(layer "In4.Cu")
		(net "PWRGD_P12V_HSC")
	)
	(segment
		(start 333.39024 -74.196448)
		(end 333.39024 -79.665322)
		(width 0.089408)
		(layer "In4.Cu")
		(net "PWRGD_P12V_HSC")
	)
	(segment
		(start 325.453756 -127.636016)
		(end 325.453756 -128.20523)
		(width 0.089408)
		(layer "In4.Cu")
		(net "PWRGD_P12V_HSC")
	)
	(segment
		(start 391.87374 -62.89294)
		(end 390.71931 -62.89294)
		(width 0.089408)
		(layer "In4.Cu")
		(net "PWRGD_P12V_HSC")
	)
	(segment
		(start 381.545338 -61.949076)
		(end 381.082804 -62.41161)
		(width 0.089408)
		(layer "In4.Cu")
		(net "PWRGD_P12V_HSC")
	)
	(segment
		(start 354.092002 -69.021452)
		(end 354.090732 -69.021452)
		(width 0.089408)
		(layer "In4.Cu")
		(net "PWRGD_P12V_HSC")
	)
	(segment
		(start 326.527668 -124.604018)
		(end 326.527668 -126.562104)
		(width 0.089408)
		(layer "In4.Cu")
		(net "PWRGD_P12V_HSC")
	)
	(segment
		(start 383.958338 -61.963554)
		(end 383.742184 -61.7474)
		(width 0.089408)
		(layer "In4.Cu")
		(net "PWRGD_P12V_HSC")
	)
	(segment
		(start 359.001314 -70.227698)
		(end 357.794052 -69.020436)
		(width 0.089408)
		(layer "In4.Cu")
		(net "PWRGD_P12V_HSC")
	)
	(segment
		(start 392.740896 -61.661802)
		(end 392.740896 -62.02553)
		(width 0.089408)
		(layer "In4.Cu")
		(net "PWRGD_P12V_HSC")
	)
	(segment
		(start 357.794052 -69.020436)
		(end 354.093018 -69.020436)
		(width 0.089408)
		(layer "In4.Cu")
		(net "PWRGD_P12V_HSC")
	)
	(segment
		(start 398.396206 -61.849)
		(end 394.09116 -61.849)
		(width 0.089408)
		(layer "In4.Cu")
		(net "PWRGD_P12V_HSC")
	)
	(segment
		(start 375.273316 -62.122304)
		(end 373.015764 -62.122304)
		(width 0.089408)
		(layer "In4.Cu")
		(net "PWRGD_P12V_HSC")
	)
	(segment
		(start 382.826006 -61.949076)
		(end 381.545338 -61.949076)
		(width 0.089408)
		(layer "In4.Cu")
		(net "PWRGD_P12V_HSC")
	)
	(segment
		(start 403.365208 -63.003176)
		(end 399.550382 -63.003176)
		(width 0.089408)
		(layer "In4.Cu")
		(net "PWRGD_P12V_HSC")
	)
	(segment
		(start 330.569824 -84.555076)
		(end 323.493638 -91.631262)
		(width 0.089408)
		(layer "In4.Cu")
		(net "PWRGD_P12V_HSC")
	)
	(segment
		(start 401.01266 -73.89368)
		(end 401.731226 -73.89368)
		(width 0.089408)
		(layer "In9.Cu")
		(net "PWRGD_P12V_HSC")
	)
	(segment
		(start 406.496266 -64.15151)
		(end 406.496266 -63.636398)
		(width 0.089408)
		(layer "In9.Cu")
		(net "PWRGD_P12V_HSC")
	)
	(segment
		(start 406.732232 -64.387476)
		(end 406.496266 -64.15151)
		(width 0.089408)
		(layer "In9.Cu")
		(net "PWRGD_P12V_HSC")
	)
	(segment
		(start 405.727154 -69.897752)
		(end 405.727154 -67.148456)
		(width 0.089408)
		(layer "In9.Cu")
		(net "PWRGD_P12V_HSC")
	)
	(segment
		(start 161.204656 -142.09268)
		(end 166.473886 -142.09268)
		(width 0.089408)
		(layer "In9.Cu")
		(net "PWRGD_P12V_HSC")
	)
	(segment
		(start 11.176 -93.2942)
		(end 12.149836 -94.268036)
		(width 0.089408)
		(layer "In9.Cu")
		(net "PWRGD_P12V_HSC")
	)
	(segment
		(start 12.363958 -76.651358)
		(end 12.363958 -79.953358)
		(width 0.089408)
		(layer "In9.Cu")
		(net "PWRGD_P12V_HSC")
	)
	(segment
		(start 151.88692 -128.467104)
		(end 157.554168 -128.467104)
		(width 0.089408)
		(layer "In9.Cu")
		(net "PWRGD_P12V_HSC")
	)
	(segment
		(start 12.363958 -79.953358)
		(end 14.56182 -82.15122)
		(width 0.089408)
		(layer "In9.Cu")
		(net "PWRGD_P12V_HSC")
	)
	(segment
		(start 14.56182 -83.48218)
		(end 13.85824 -84.18576)
		(width 0.089408)
		(layer "In9.Cu")
		(net "PWRGD_P12V_HSC")
	)
	(segment
		(start 406.732232 -65.531492)
		(end 406.732232 -64.387476)
		(width 0.089408)
		(layer "In9.Cu")
		(net "PWRGD_P12V_HSC")
	)
	(segment
		(start 406.49652 -62.722252)
		(end 406.337008 -62.56274)
		(width 0.089408)
		(layer "In9.Cu")
		(net "PWRGD_P12V_HSC")
	)
	(segment
		(start 157.554168 -128.467104)
		(end 159.7406 -130.653536)
		(width 0.089408)
		(layer "In9.Cu")
		(net "PWRGD_P12V_HSC")
	)
	(segment
		(start 263.160764 -143.288766)
		(end 264.446512 -143.288766)
		(width 0.089408)
		(layer "In9.Cu")
		(net "PWRGD_P12V_HSC")
	)
	(segment
		(start 12.3317 -76.6191)
		(end 12.363958 -76.651358)
		(width 0.089408)
		(layer "In9.Cu")
		(net "PWRGD_P12V_HSC")
	)
	(segment
		(start 14.56182 -82.15122)
		(end 14.56182 -83.48218)
		(width 0.089408)
		(layer "In9.Cu")
		(net "PWRGD_P12V_HSC")
	)
	(segment
		(start 12.930632 -84.18576)
		(end 12.0904 -85.025992)
		(width 0.089408)
		(layer "In9.Cu")
		(net "PWRGD_P12V_HSC")
	)
	(segment
		(start 189.441836 -142.6972)
		(end 193.418206 -146.67357)
		(width 0.089408)
		(layer "In9.Cu")
		(net "PWRGD_P12V_HSC")
	)
	(segment
		(start 401.731226 -73.89368)
		(end 405.727154 -69.897752)
		(width 0.089408)
		(layer "In9.Cu")
		(net "PWRGD_P12V_HSC")
	)
	(segment
		(start 22.045422 -121.950734)
		(end 23.9903 -123.895612)
		(width 0.089408)
		(layer "In9.Cu")
		(net "PWRGD_P12V_HSC")
	)
	(segment
		(start 406.089104 -66.556128)
		(end 406.089104 -66.17462)
		(width 0.089408)
		(layer "In9.Cu")
		(net "PWRGD_P12V_HSC")
	)
	(segment
		(start 166.473886 -142.09268)
		(end 167.078406 -142.6972)
		(width 0.089408)
		(layer "In9.Cu")
		(net "PWRGD_P12V_HSC")
	)
	(segment
		(start 147.315428 -123.895612)
		(end 151.88692 -128.467104)
		(width 0.089408)
		(layer "In9.Cu")
		(net "PWRGD_P12V_HSC")
	)
	(segment
		(start 167.078406 -142.6972)
		(end 189.441836 -142.6972)
		(width 0.089408)
		(layer "In9.Cu")
		(net "PWRGD_P12V_HSC")
	)
	(segment
		(start 406.496266 -63.636398)
		(end 406.49652 -63.636144)
		(width 0.089408)
		(layer "In9.Cu")
		(net "PWRGD_P12V_HSC")
	)
	(segment
		(start 264.795 -146.063462)
		(end 265.265916 -146.534378)
		(width 0.089408)
		(layer "In9.Cu")
		(net "PWRGD_P12V_HSC")
	)
	(segment
		(start 262.178292 -143.294608)
		(end 263.154922 -143.294608)
		(width 0.089408)
		(layer "In9.Cu")
		(net "PWRGD_P12V_HSC")
	)
	(segment
		(start 406.089612 -66.556636)
		(end 406.089104 -66.556128)
		(width 0.089408)
		(layer "In9.Cu")
		(net "PWRGD_P12V_HSC")
	)
	(segment
		(start 406.089104 -66.17462)
		(end 406.732232 -65.531492)
		(width 0.089408)
		(layer "In9.Cu")
		(net "PWRGD_P12V_HSC")
	)
	(segment
		(start 159.7406 -140.628624)
		(end 161.204656 -142.09268)
		(width 0.089408)
		(layer "In9.Cu")
		(net "PWRGD_P12V_HSC")
	)
	(segment
		(start 17.85112 -105.953814)
		(end 17.85112 -109.52988)
		(width 0.089408)
		(layer "In9.Cu")
		(net "PWRGD_P12V_HSC")
	)
	(segment
		(start 12.149836 -94.268036)
		(end 12.149836 -100.25253)
		(width 0.089408)
		(layer "In9.Cu")
		(net "PWRGD_P12V_HSC")
	)
	(segment
		(start 22.045422 -113.724182)
		(end 22.045422 -121.950734)
		(width 0.089408)
		(layer "In9.Cu")
		(net "PWRGD_P12V_HSC")
	)
	(segment
		(start 13.85824 -84.18576)
		(end 12.930632 -84.18576)
		(width 0.089408)
		(layer "In9.Cu")
		(net "PWRGD_P12V_HSC")
	)
	(segment
		(start 406.337008 -62.56274)
		(end 406.21458 -62.56274)
		(width 0.089408)
		(layer "In9.Cu")
		(net "PWRGD_P12V_HSC")
	)
	(segment
		(start 258.79933 -146.67357)
		(end 262.178292 -143.294608)
		(width 0.089408)
		(layer "In9.Cu")
		(net "PWRGD_P12V_HSC")
	)
	(segment
		(start 264.795 -143.637254)
		(end 264.795 -146.063462)
		(width 0.089408)
		(layer "In9.Cu")
		(net "PWRGD_P12V_HSC")
	)
	(segment
		(start 11.823192 -89.497408)
		(end 11.176 -90.1446)
		(width 0.089408)
		(layer "In9.Cu")
		(net "PWRGD_P12V_HSC")
	)
	(segment
		(start 159.7406 -130.653536)
		(end 159.7406 -140.628624)
		(width 0.089408)
		(layer "In9.Cu")
		(net "PWRGD_P12V_HSC")
	)
	(segment
		(start 11.176 -90.1446)
		(end 11.176 -93.2942)
		(width 0.089408)
		(layer "In9.Cu")
		(net "PWRGD_P12V_HSC")
	)
	(segment
		(start 322.048378 -146.534378)
		(end 323.3928 -147.8788)
		(width 0.089408)
		(layer "In9.Cu")
		(net "PWRGD_P12V_HSC")
	)
	(segment
		(start 406.49652 -63.636144)
		(end 406.49652 -62.722252)
		(width 0.089408)
		(layer "In9.Cu")
		(net "PWRGD_P12V_HSC")
	)
	(segment
		(start 264.446512 -143.288766)
		(end 264.795 -143.637254)
		(width 0.089408)
		(layer "In9.Cu")
		(net "PWRGD_P12V_HSC")
	)
	(segment
		(start 265.265916 -146.534378)
		(end 322.048378 -146.534378)
		(width 0.089408)
		(layer "In9.Cu")
		(net "PWRGD_P12V_HSC")
	)
	(segment
		(start 406.089612 -66.785998)
		(end 406.089612 -66.556636)
		(width 0.089408)
		(layer "In9.Cu")
		(net "PWRGD_P12V_HSC")
	)
	(segment
		(start 17.85112 -109.52988)
		(end 22.045422 -113.724182)
		(width 0.089408)
		(layer "In9.Cu")
		(net "PWRGD_P12V_HSC")
	)
	(segment
		(start 193.418206 -146.67357)
		(end 258.79933 -146.67357)
		(width 0.089408)
		(layer "In9.Cu")
		(net "PWRGD_P12V_HSC")
	)
	(segment
		(start 11.823192 -87.119206)
		(end 11.823192 -89.497408)
		(width 0.089408)
		(layer "In9.Cu")
		(net "PWRGD_P12V_HSC")
	)
	(segment
		(start 12.149836 -100.25253)
		(end 17.85112 -105.953814)
		(width 0.089408)
		(layer "In9.Cu")
		(net "PWRGD_P12V_HSC")
	)
	(segment
		(start 405.727154 -67.148456)
		(end 406.089612 -66.785998)
		(width 0.089408)
		(layer "In9.Cu")
		(net "PWRGD_P12V_HSC")
	)
	(segment
		(start 23.9903 -123.895612)
		(end 147.315428 -123.895612)
		(width 0.089408)
		(layer "In9.Cu")
		(net "PWRGD_P12V_HSC")
	)
	(segment
		(start 12.0904 -85.025992)
		(end 12.0904 -86.851998)
		(width 0.089408)
		(layer "In9.Cu")
		(net "PWRGD_P12V_HSC")
	)
	(segment
		(start 12.0904 -86.851998)
		(end 11.823192 -87.119206)
		(width 0.089408)
		(layer "In9.Cu")
		(net "PWRGD_P12V_HSC")
	)
	(segment
		(start 263.154922 -143.294608)
		(end 263.160764 -143.288766)
		(width 0.089408)
		(layer "In9.Cu")
		(net "PWRGD_P12V_HSC")
	)
	(segment
		(start 173.981618 -102.279704)
		(end 173.981618 -100.982018)
		(width 0.10795)
		(layer "F.Cu")
		(net "PWRGD_DRAMPWRGD")
	)
	(segment
		(start 367.171224 -79.9211)
		(end 367.545112 -80.294988)
		(width 0.10795)
		(layer "F.Cu")
		(net "PWRGD_DRAMPWRGD")
	)
	(segment
		(start 365.99114 -80.42656)
		(end 366.4966 -79.9211)
		(width 0.10795)
		(layer "F.Cu")
		(net "PWRGD_DRAMPWRGD")
	)
	(segment
		(start 173.331378 -101.115622)
		(end 173.5328 -100.9142)
		(width 0.10795)
		(layer "F.Cu")
		(net "PWRGD_DRAMPWRGD")
	)
	(segment
		(start 173.331378 -102.279704)
		(end 173.331378 -101.115622)
		(width 0.10795)
		(layer "F.Cu")
		(net "PWRGD_DRAMPWRGD")
	)
	(segment
		(start 365.99114 -80.440022)
		(end 365.99114 -80.42656)
		(width 0.10795)
		(layer "F.Cu")
		(net "PWRGD_DRAMPWRGD")
	)
	(segment
		(start 173.981618 -100.982018)
		(end 173.9138 -100.9142)
		(width 0.10795)
		(layer "F.Cu")
		(net "PWRGD_DRAMPWRGD")
	)
	(segment
		(start 366.4966 -79.9211)
		(end 367.171224 -79.9211)
		(width 0.10795)
		(layer "F.Cu")
		(net "PWRGD_DRAMPWRGD")
	)
	(segment
		(start 173.9138 -100.9142)
		(end 173.5074 -100.5078)
		(width 0.10795)
		(layer "F.Cu")
		(net "PWRGD_DRAMPWRGD")
	)
	(segment
		(start 173.5074 -100.5078)
		(end 173.5074 -99.6188)
		(width 0.10795)
		(layer "F.Cu")
		(net "PWRGD_DRAMPWRGD")
	)
	(segment
		(start 173.5328 -100.9142)
		(end 173.9138 -100.9142)
		(width 0.10795)
		(layer "F.Cu")
		(net "PWRGD_DRAMPWRGD")
	)
	(via
		(at 173.5074 -99.6188)
		(size 0.508)
		(drill 0.254)
		(layers "F.Cu" "B.Cu")
		(net "PWRGD_DRAMPWRGD")
	)
	(via
		(at 359.590848 -54.1782)
		(size 0.6604)
		(drill 0.3302)
		(layers "F.Cu" "B.Cu")
		(net "PWRGD_DRAMPWRGD")
	)
	(via
		(at 180.0098 -126.8476)
		(size 0.508)
		(drill 0.254)
		(layers "F.Cu" "B.Cu")
		(net "PWRGD_DRAMPWRGD")
	)
	(via
		(at 365.99114 -80.440022)
		(size 0.4572)
		(drill 0.2032)
		(layers "F.Cu" "B.Cu")
		(net "PWRGD_DRAMPWRGD")
	)
	(segment
		(start 361.115356 -50.641504)
		(end 365.302546 -50.641504)
		(width 0.10795)
		(layer "B.Cu")
		(net "PWRGD_DRAMPWRGD")
	)
	(segment
		(start 363.9185 -54.51348)
		(end 362.756704 -54.51348)
		(width 0.10795)
		(layer "B.Cu")
		(net "PWRGD_DRAMPWRGD")
	)
	(segment
		(start 359.927652 -58.024268)
		(end 359.522776 -58.429144)
		(width 0.10795)
		(layer "B.Cu")
		(net "PWRGD_DRAMPWRGD")
	)
	(segment
		(start 365.302546 -50.641504)
		(end 365.928402 -51.26736)
		(width 0.10795)
		(layer "B.Cu")
		(net "PWRGD_DRAMPWRGD")
	)
	(segment
		(start 359.590848 -54.1782)
		(end 359.53192 -54.119272)
		(width 0.10795)
		(layer "B.Cu")
		(net "PWRGD_DRAMPWRGD")
	)
	(segment
		(start 359.53192 -54.119272)
		(end 359.53192 -50.437034)
		(width 0.10795)
		(layer "B.Cu")
		(net "PWRGD_DRAMPWRGD")
	)
	(segment
		(start 359.927652 -55.480458)
		(end 359.927652 -58.024268)
		(width 0.10795)
		(layer "B.Cu")
		(net "PWRGD_DRAMPWRGD")
	)
	(segment
		(start 353.812348 -72.205342)
		(end 353.812094 -72.205596)
		(width 0.10795)
		(layer "B.Cu")
		(net "PWRGD_DRAMPWRGD")
	)
	(segment
		(start 353.812094 -72.205596)
		(end 353.812094 -72.41794)
		(width 0.10795)
		(layer "B.Cu")
		(net "PWRGD_DRAMPWRGD")
	)
	(segment
		(start 365.928402 -51.26736)
		(end 365.928402 -53.463698)
		(width 0.10795)
		(layer "B.Cu")
		(net "PWRGD_DRAMPWRGD")
	)
	(segment
		(start 359.851706 -50.117248)
		(end 360.5911 -50.117248)
		(width 0.10795)
		(layer "B.Cu")
		(net "PWRGD_DRAMPWRGD")
	)
	(segment
		(start 362.756704 -54.51348)
		(end 362.585 -54.341776)
		(width 0.10795)
		(layer "B.Cu")
		(net "PWRGD_DRAMPWRGD")
	)
	(segment
		(start 364.05312 -80.490822)
		(end 365.94034 -80.490822)
		(width 0.10795)
		(layer "B.Cu")
		(net "PWRGD_DRAMPWRGD")
	)
	(segment
		(start 353.812348 -69.962776)
		(end 353.812348 -72.205342)
		(width 0.10795)
		(layer "B.Cu")
		(net "PWRGD_DRAMPWRGD")
	)
	(segment
		(start 360.5911 -50.117248)
		(end 361.115356 -50.641504)
		(width 0.10795)
		(layer "B.Cu")
		(net "PWRGD_DRAMPWRGD")
	)
	(segment
		(start 353.812094 -72.41794)
		(end 354.663248 -73.269094)
		(width 0.10795)
		(layer "B.Cu")
		(net "PWRGD_DRAMPWRGD")
	)
	(segment
		(start 362.585 -54.00294)
		(end 362.7247 -53.86324)
		(width 0.10795)
		(layer "B.Cu")
		(net "PWRGD_DRAMPWRGD")
	)
	(segment
		(start 354.663248 -73.269094)
		(end 361.722924 -73.269094)
		(width 0.10795)
		(layer "B.Cu")
		(net "PWRGD_DRAMPWRGD")
	)
	(segment
		(start 363.94517 -75.49134)
		(end 363.94517 -80.382872)
		(width 0.10795)
		(layer "B.Cu")
		(net "PWRGD_DRAMPWRGD")
	)
	(segment
		(start 359.590848 -54.1782)
		(end 359.590848 -55.143654)
		(width 0.10795)
		(layer "B.Cu")
		(net "PWRGD_DRAMPWRGD")
	)
	(segment
		(start 365.928402 -53.463698)
		(end 365.52886 -53.86324)
		(width 0.10795)
		(layer "B.Cu")
		(net "PWRGD_DRAMPWRGD")
	)
	(segment
		(start 365.52886 -53.86324)
		(end 363.9185 -53.86324)
		(width 0.10795)
		(layer "B.Cu")
		(net "PWRGD_DRAMPWRGD")
	)
	(segment
		(start 365.94034 -80.490822)
		(end 365.99114 -80.440022)
		(width 0.10795)
		(layer "B.Cu")
		(net "PWRGD_DRAMPWRGD")
	)
	(segment
		(start 363.94517 -80.382872)
		(end 364.05312 -80.490822)
		(width 0.10795)
		(layer "B.Cu")
		(net "PWRGD_DRAMPWRGD")
	)
	(segment
		(start 359.522776 -58.429144)
		(end 359.522776 -64.252348)
		(width 0.10795)
		(layer "B.Cu")
		(net "PWRGD_DRAMPWRGD")
	)
	(segment
		(start 359.522776 -64.252348)
		(end 353.812348 -69.962776)
		(width 0.10795)
		(layer "B.Cu")
		(net "PWRGD_DRAMPWRGD")
	)
	(segment
		(start 359.590848 -55.143654)
		(end 359.927652 -55.480458)
		(width 0.10795)
		(layer "B.Cu")
		(net "PWRGD_DRAMPWRGD")
	)
	(segment
		(start 362.7247 -53.86324)
		(end 363.9185 -53.86324)
		(width 0.10795)
		(layer "B.Cu")
		(net "PWRGD_DRAMPWRGD")
	)
	(segment
		(start 362.585 -54.341776)
		(end 362.585 -54.00294)
		(width 0.10795)
		(layer "B.Cu")
		(net "PWRGD_DRAMPWRGD")
	)
	(segment
		(start 359.53192 -50.437034)
		(end 359.851706 -50.117248)
		(width 0.10795)
		(layer "B.Cu")
		(net "PWRGD_DRAMPWRGD")
	)
	(segment
		(start 361.722924 -73.269094)
		(end 363.94517 -75.49134)
		(width 0.10795)
		(layer "B.Cu")
		(net "PWRGD_DRAMPWRGD")
	)
	(segment
		(start 344.639646 -125.803406)
		(end 344.639646 -127.049784)
		(width 0.089408)
		(layer "In9.Cu")
		(net "PWRGD_DRAMPWRGD")
	)
	(segment
		(start 334.360774 -124.243084)
		(end 343.079324 -124.243084)
		(width 0.089408)
		(layer "In9.Cu")
		(net "PWRGD_DRAMPWRGD")
	)
	(segment
		(start 182.5498 -126.3396)
		(end 186.434476 -126.3396)
		(width 0.089408)
		(layer "In9.Cu")
		(net "PWRGD_DRAMPWRGD")
	)
	(segment
		(start 373.548656 -115.94338)
		(end 374.928638 -114.563398)
		(width 0.089408)
		(layer "In9.Cu")
		(net "PWRGD_DRAMPWRGD")
	)
	(segment
		(start 367.621312 -125.068584)
		(end 367.621312 -123.80976)
		(width 0.089408)
		(layer "In9.Cu")
		(net "PWRGD_DRAMPWRGD")
	)
	(segment
		(start 191.403224 -126.303024)
		(end 191.940688 -125.76556)
		(width 0.089408)
		(layer "In9.Cu")
		(net "PWRGD_DRAMPWRGD")
	)
	(segment
		(start 365.5949 -88.984328)
		(end 365.5949 -81.1911)
		(width 0.089408)
		(layer "In9.Cu")
		(net "PWRGD_DRAMPWRGD")
	)
	(segment
		(start 369.04676 -93.319346)
		(end 366.998504 -91.27109)
		(width 0.089408)
		(layer "In9.Cu")
		(net "PWRGD_DRAMPWRGD")
	)
	(segment
		(start 354.931218 -126.631446)
		(end 366.05845 -126.631446)
		(width 0.089408)
		(layer "In9.Cu")
		(net "PWRGD_DRAMPWRGD")
	)
	(segment
		(start 306.04841 -123.6853)
		(end 309.7149 -127.35179)
		(width 0.089408)
		(layer "In9.Cu")
		(net "PWRGD_DRAMPWRGD")
	)
	(segment
		(start 328.940922 -124.857764)
		(end 329.110086 -124.6886)
		(width 0.089408)
		(layer "In9.Cu")
		(net "PWRGD_DRAMPWRGD")
	)
	(segment
		(start 322.50634 -126.39294)
		(end 322.761864 -126.137416)
		(width 0.089408)
		(layer "In9.Cu")
		(net "PWRGD_DRAMPWRGD")
	)
	(segment
		(start 186.434476 -126.3396)
		(end 186.471052 -126.303024)
		(width 0.089408)
		(layer "In9.Cu")
		(net "PWRGD_DRAMPWRGD")
	)
	(segment
		(start 323.465952 -126.137416)
		(end 324.134734 -126.806198)
		(width 0.089408)
		(layer "In9.Cu")
		(net "PWRGD_DRAMPWRGD")
	)
	(segment
		(start 366.998504 -90.387932)
		(end 365.5949 -88.984328)
		(width 0.089408)
		(layer "In9.Cu")
		(net "PWRGD_DRAMPWRGD")
	)
	(segment
		(start 329.110086 -124.6886)
		(end 333.915258 -124.6886)
		(width 0.089408)
		(layer "In9.Cu")
		(net "PWRGD_DRAMPWRGD")
	)
	(segment
		(start 243.97589 -124.57303)
		(end 264.28319 -124.57303)
		(width 0.089408)
		(layer "In9.Cu")
		(net "PWRGD_DRAMPWRGD")
	)
	(segment
		(start 366.014 -80.772)
		(end 366.014 -80.58912)
		(width 0.089408)
		(layer "In9.Cu")
		(net "PWRGD_DRAMPWRGD")
	)
	(segment
		(start 322.761864 -126.137416)
		(end 323.465952 -126.137416)
		(width 0.089408)
		(layer "In9.Cu")
		(net "PWRGD_DRAMPWRGD")
	)
	(segment
		(start 181.437534 -127.451866)
		(end 182.5498 -126.3396)
		(width 0.089408)
		(layer "In9.Cu")
		(net "PWRGD_DRAMPWRGD")
	)
	(segment
		(start 373.548656 -117.890544)
		(end 373.548656 -115.94338)
		(width 0.089408)
		(layer "In9.Cu")
		(net "PWRGD_DRAMPWRGD")
	)
	(segment
		(start 365.99114 -80.56626)
		(end 365.99114 -80.440022)
		(width 0.089408)
		(layer "In9.Cu")
		(net "PWRGD_DRAMPWRGD")
	)
	(segment
		(start 191.940688 -125.76556)
		(end 222.85198 -125.76556)
		(width 0.089408)
		(layer "In9.Cu")
		(net "PWRGD_DRAMPWRGD")
	)
	(segment
		(start 366.05845 -126.631446)
		(end 367.621312 -125.068584)
		(width 0.089408)
		(layer "In9.Cu")
		(net "PWRGD_DRAMPWRGD")
	)
	(segment
		(start 373.86514 -101.7524)
		(end 370.4717 -101.7524)
		(width 0.089408)
		(layer "In9.Cu")
		(net "PWRGD_DRAMPWRGD")
	)
	(segment
		(start 369.04676 -100.32746)
		(end 369.04676 -93.319346)
		(width 0.089408)
		(layer "In9.Cu")
		(net "PWRGD_DRAMPWRGD")
	)
	(segment
		(start 265.17092 -123.6853)
		(end 306.04841 -123.6853)
		(width 0.089408)
		(layer "In9.Cu")
		(net "PWRGD_DRAMPWRGD")
	)
	(segment
		(start 350.330008 -127.910336)
		(end 350.689418 -128.269746)
		(width 0.089408)
		(layer "In9.Cu")
		(net "PWRGD_DRAMPWRGD")
	)
	(segment
		(start 180.614066 -127.451866)
		(end 181.437534 -127.451866)
		(width 0.089408)
		(layer "In9.Cu")
		(net "PWRGD_DRAMPWRGD")
	)
	(segment
		(start 324.134734 -126.806198)
		(end 325.636128 -126.806198)
		(width 0.089408)
		(layer "In9.Cu")
		(net "PWRGD_DRAMPWRGD")
	)
	(segment
		(start 370.4717 -101.7524)
		(end 369.04676 -100.32746)
		(width 0.089408)
		(layer "In9.Cu")
		(net "PWRGD_DRAMPWRGD")
	)
	(segment
		(start 366.014 -80.58912)
		(end 365.99114 -80.56626)
		(width 0.089408)
		(layer "In9.Cu")
		(net "PWRGD_DRAMPWRGD")
	)
	(segment
		(start 374.928638 -114.563398)
		(end 374.928638 -102.815898)
		(width 0.089408)
		(layer "In9.Cu")
		(net "PWRGD_DRAMPWRGD")
	)
	(segment
		(start 350.689418 -128.269746)
		(end 353.292918 -128.269746)
		(width 0.089408)
		(layer "In9.Cu")
		(net "PWRGD_DRAMPWRGD")
	)
	(segment
		(start 327.584562 -124.857764)
		(end 328.940922 -124.857764)
		(width 0.089408)
		(layer "In9.Cu")
		(net "PWRGD_DRAMPWRGD")
	)
	(segment
		(start 325.636128 -126.806198)
		(end 327.584562 -124.857764)
		(width 0.089408)
		(layer "In9.Cu")
		(net "PWRGD_DRAMPWRGD")
	)
	(segment
		(start 186.471052 -126.303024)
		(end 191.403224 -126.303024)
		(width 0.089408)
		(layer "In9.Cu")
		(net "PWRGD_DRAMPWRGD")
	)
	(segment
		(start 344.639646 -127.049784)
		(end 345.500198 -127.910336)
		(width 0.089408)
		(layer "In9.Cu")
		(net "PWRGD_DRAMPWRGD")
	)
	(segment
		(start 321.87896 -126.39294)
		(end 322.50634 -126.39294)
		(width 0.089408)
		(layer "In9.Cu")
		(net "PWRGD_DRAMPWRGD")
	)
	(segment
		(start 370.586 -120.8532)
		(end 373.548656 -117.890544)
		(width 0.089408)
		(layer "In9.Cu")
		(net "PWRGD_DRAMPWRGD")
	)
	(segment
		(start 365.5949 -81.1911)
		(end 366.014 -80.772)
		(width 0.089408)
		(layer "In9.Cu")
		(net "PWRGD_DRAMPWRGD")
	)
	(segment
		(start 333.915258 -124.6886)
		(end 334.360774 -124.243084)
		(width 0.089408)
		(layer "In9.Cu")
		(net "PWRGD_DRAMPWRGD")
	)
	(segment
		(start 345.500198 -127.910336)
		(end 350.330008 -127.910336)
		(width 0.089408)
		(layer "In9.Cu")
		(net "PWRGD_DRAMPWRGD")
	)
	(segment
		(start 343.079324 -124.243084)
		(end 344.639646 -125.803406)
		(width 0.089408)
		(layer "In9.Cu")
		(net "PWRGD_DRAMPWRGD")
	)
	(segment
		(start 353.292918 -128.269746)
		(end 354.931218 -126.631446)
		(width 0.089408)
		(layer "In9.Cu")
		(net "PWRGD_DRAMPWRGD")
	)
	(segment
		(start 320.92011 -127.35179)
		(end 321.87896 -126.39294)
		(width 0.089408)
		(layer "In9.Cu")
		(net "PWRGD_DRAMPWRGD")
	)
	(segment
		(start 180.0098 -126.8476)
		(end 180.614066 -127.451866)
		(width 0.089408)
		(layer "In9.Cu")
		(net "PWRGD_DRAMPWRGD")
	)
	(segment
		(start 367.309654 -122.504454)
		(end 368.960908 -120.8532)
		(width 0.089408)
		(layer "In9.Cu")
		(net "PWRGD_DRAMPWRGD")
	)
	(segment
		(start 367.309654 -123.498102)
		(end 367.309654 -122.504454)
		(width 0.089408)
		(layer "In9.Cu")
		(net "PWRGD_DRAMPWRGD")
	)
	(segment
		(start 367.621312 -123.80976)
		(end 367.309654 -123.498102)
		(width 0.089408)
		(layer "In9.Cu")
		(net "PWRGD_DRAMPWRGD")
	)
	(segment
		(start 374.928638 -102.815898)
		(end 373.86514 -101.7524)
		(width 0.089408)
		(layer "In9.Cu")
		(net "PWRGD_DRAMPWRGD")
	)
	(segment
		(start 222.85198 -125.76556)
		(end 224.48774 -124.1298)
		(width 0.089408)
		(layer "In9.Cu")
		(net "PWRGD_DRAMPWRGD")
	)
	(segment
		(start 309.7149 -127.35179)
		(end 320.92011 -127.35179)
		(width 0.089408)
		(layer "In9.Cu")
		(net "PWRGD_DRAMPWRGD")
	)
	(segment
		(start 366.998504 -91.27109)
		(end 366.998504 -90.387932)
		(width 0.089408)
		(layer "In9.Cu")
		(net "PWRGD_DRAMPWRGD")
	)
	(segment
		(start 368.960908 -120.8532)
		(end 370.586 -120.8532)
		(width 0.089408)
		(layer "In9.Cu")
		(net "PWRGD_DRAMPWRGD")
	)
	(segment
		(start 243.53266 -124.1298)
		(end 243.97589 -124.57303)
		(width 0.089408)
		(layer "In9.Cu")
		(net "PWRGD_DRAMPWRGD")
	)
	(segment
		(start 224.48774 -124.1298)
		(end 243.53266 -124.1298)
		(width 0.089408)
		(layer "In9.Cu")
		(net "PWRGD_DRAMPWRGD")
	)
	(segment
		(start 264.28319 -124.57303)
		(end 265.17092 -123.6853)
		(width 0.089408)
		(layer "In9.Cu")
		(net "PWRGD_DRAMPWRGD")
	)
	(segment
		(start 177.709576 -104.972104)
		(end 177.709576 -106.483912)
		(width 0.089408)
		(layer "In11.Cu")
		(net "PWRGD_DRAMPWRGD")
	)
	(segment
		(start 178.841146 -126.8476)
		(end 180.0098 -126.8476)
		(width 0.089408)
		(layer "In11.Cu")
		(net "PWRGD_DRAMPWRGD")
	)
	(segment
		(start 173.5074 -100.769928)
		(end 177.709576 -104.972104)
		(width 0.089408)
		(layer "In11.Cu")
		(net "PWRGD_DRAMPWRGD")
	)
	(segment
		(start 173.5074 -99.6188)
		(end 173.5074 -100.769928)
		(width 0.089408)
		(layer "In11.Cu")
		(net "PWRGD_DRAMPWRGD")
	)
	(segment
		(start 177.709576 -106.483912)
		(end 178.067208 -106.841544)
		(width 0.089408)
		(layer "In11.Cu")
		(net "PWRGD_DRAMPWRGD")
	)
	(segment
		(start 178.067208 -106.841544)
		(end 178.067208 -126.073662)
		(width 0.089408)
		(layer "In11.Cu")
		(net "PWRGD_DRAMPWRGD")
	)
	(segment
		(start 178.067208 -126.073662)
		(end 178.841146 -126.8476)
		(width 0.089408)
		(layer "In11.Cu")
		(net "PWRGD_DRAMPWRGD")
	)
	(segment
		(start 368.745516 -71.895462)
		(end 369.145058 -72.295004)
		(width 0.10795)
		(layer "F.Cu")
		(net "PWRGD_CPUPWRGD")
	)
	(via
		(at 368.745516 -71.895462)
		(size 0.4572)
		(drill 0.2032)
		(layers "F.Cu" "B.Cu")
		(net "PWRGD_CPUPWRGD")
	)
	(via
		(at 365.232442 -68.485258)
		(size 0.6604)
		(drill 0.3302)
		(layers "F.Cu" "B.Cu")
		(net "PWRGD_CPUPWRGD")
	)
	(segment
		(start 365.232442 -68.485258)
		(end 365.232442 -71.989696)
		(width 0.10795)
		(layer "B.Cu")
		(net "PWRGD_CPUPWRGD")
	)
	(segment
		(start 369.12804 -72.277986)
		(end 368.745516 -71.895462)
		(width 0.10795)
		(layer "B.Cu")
		(net "PWRGD_CPUPWRGD")
	)
	(segment
		(start 366.354868 -73.112122)
		(end 366.503712 -73.112122)
		(width 0.10795)
		(layer "B.Cu")
		(net "PWRGD_CPUPWRGD")
	)
	(segment
		(start 365.232442 -64.42075)
		(end 364.778798 -64.874394)
		(width 0.10795)
		(layer "B.Cu")
		(net "PWRGD_CPUPWRGD")
	)
	(segment
		(start 366.995456 -73.913238)
		(end 368.068352 -73.913238)
		(width 0.10795)
		(layer "B.Cu")
		(net "PWRGD_CPUPWRGD")
	)
	(segment
		(start 368.903758 -73.078086)
		(end 369.12804 -72.853804)
		(width 0.10795)
		(layer "B.Cu")
		(net "PWRGD_CPUPWRGD")
	)
	(segment
		(start 369.12804 -72.853804)
		(end 369.12804 -72.277986)
		(width 0.10795)
		(layer "B.Cu")
		(net "PWRGD_CPUPWRGD")
	)
	(segment
		(start 365.76 -63.5127)
		(end 365.232442 -64.040258)
		(width 0.10795)
		(layer "B.Cu")
		(net "PWRGD_CPUPWRGD")
	)
	(segment
		(start 368.356896 -73.342246)
		(end 368.621056 -73.078086)
		(width 0.10795)
		(layer "B.Cu")
		(net "PWRGD_CPUPWRGD")
	)
	(segment
		(start 368.068352 -73.913238)
		(end 368.356896 -73.624694)
		(width 0.10795)
		(layer "B.Cu")
		(net "PWRGD_CPUPWRGD")
	)
	(segment
		(start 366.75314 -73.670922)
		(end 366.995456 -73.913238)
		(width 0.10795)
		(layer "B.Cu")
		(net "PWRGD_CPUPWRGD")
	)
	(segment
		(start 364.778798 -64.874394)
		(end 364.778798 -65.783206)
		(width 0.10795)
		(layer "B.Cu")
		(net "PWRGD_CPUPWRGD")
	)
	(segment
		(start 368.621056 -73.078086)
		(end 368.903758 -73.078086)
		(width 0.10795)
		(layer "B.Cu")
		(net "PWRGD_CPUPWRGD")
	)
	(segment
		(start 365.76 -63.1825)
		(end 365.76 -63.5127)
		(width 0.10795)
		(layer "B.Cu")
		(net "PWRGD_CPUPWRGD")
	)
	(segment
		(start 365.232442 -66.23685)
		(end 365.232442 -68.485258)
		(width 0.10795)
		(layer "B.Cu")
		(net "PWRGD_CPUPWRGD")
	)
	(segment
		(start 365.232442 -71.989696)
		(end 366.354868 -73.112122)
		(width 0.10795)
		(layer "B.Cu")
		(net "PWRGD_CPUPWRGD")
	)
	(segment
		(start 365.232442 -64.040258)
		(end 365.232442 -64.42075)
		(width 0.10795)
		(layer "B.Cu")
		(net "PWRGD_CPUPWRGD")
	)
	(segment
		(start 366.503712 -73.112122)
		(end 366.75314 -73.36155)
		(width 0.10795)
		(layer "B.Cu")
		(net "PWRGD_CPUPWRGD")
	)
	(segment
		(start 366.75314 -73.36155)
		(end 366.75314 -73.670922)
		(width 0.10795)
		(layer "B.Cu")
		(net "PWRGD_CPUPWRGD")
	)
	(segment
		(start 364.778798 -65.783206)
		(end 365.232442 -66.23685)
		(width 0.10795)
		(layer "B.Cu")
		(net "PWRGD_CPUPWRGD")
	)
	(segment
		(start 368.356896 -73.624694)
		(end 368.356896 -73.342246)
		(width 0.10795)
		(layer "B.Cu")
		(net "PWRGD_CPUPWRGD")
	)
	(segment
		(start 175.0187 -99.7204)
		(end 175.932338 -100.634038)
		(width 0.10795)
		(layer "F.Cu")
		(net "PWRGD_CPU1_LVC3")
	)
	(segment
		(start 174.401226 -99.7204)
		(end 175.0187 -99.7204)
		(width 0.10795)
		(layer "F.Cu")
		(net "PWRGD_CPU1_LVC3")
	)
	(segment
		(start 175.932338 -100.634038)
		(end 175.932338 -102.279704)
		(width 0.10795)
		(layer "F.Cu")
		(net "PWRGD_CPU1_LVC3")
	)
	(segment
		(start 371.145308 -77.494892)
		(end 371.545104 -77.095096)
		(width 0.10795)
		(layer "F.Cu")
		(net "PWRGD_CPU1_LVC3")
	)
	(via
		(at 174.401226 -99.7204)
		(size 0.508)
		(drill 0.254)
		(layers "F.Cu" "B.Cu")
		(net "PWRGD_CPU1_LVC3")
	)
	(via
		(at 371.145308 -77.494892)
		(size 0.4572)
		(drill 0.2032)
		(layers "F.Cu" "B.Cu")
		(net "PWRGD_CPU1_LVC3")
	)
	(via
		(at 372.9863 -64.2366)
		(size 0.508)
		(drill 0.254)
		(layers "F.Cu" "B.Cu")
		(net "PWRGD_CPU1_LVC3")
	)
	(segment
		(start 371.768624 -68.087494)
		(end 371.57025 -67.88912)
		(width 0.089408)
		(layer "In9.Cu")
		(net "PWRGD_CPU1_LVC3")
	)
	(segment
		(start 371.768624 -68.979288)
		(end 371.768624 -68.087494)
		(width 0.089408)
		(layer "In9.Cu")
		(net "PWRGD_CPU1_LVC3")
	)
	(segment
		(start 370.985542 -67.88912)
		(end 370.631212 -67.53479)
		(width 0.089408)
		(layer "In9.Cu")
		(net "PWRGD_CPU1_LVC3")
	)
	(segment
		(start 371.518688 -77.121512)
		(end 371.518688 -69.229224)
		(width 0.089408)
		(layer "In9.Cu")
		(net "PWRGD_CPU1_LVC3")
	)
	(segment
		(start 372.662704 -65.189862)
		(end 372.662704 -64.560196)
		(width 0.089408)
		(layer "In9.Cu")
		(net "PWRGD_CPU1_LVC3")
	)
	(segment
		(start 371.518688 -69.229224)
		(end 371.768624 -68.979288)
		(width 0.089408)
		(layer "In9.Cu")
		(net "PWRGD_CPU1_LVC3")
	)
	(segment
		(start 372.662704 -64.560196)
		(end 372.9863 -64.2366)
		(width 0.089408)
		(layer "In9.Cu")
		(net "PWRGD_CPU1_LVC3")
	)
	(segment
		(start 371.145308 -77.494892)
		(end 371.518688 -77.121512)
		(width 0.089408)
		(layer "In9.Cu")
		(net "PWRGD_CPU1_LVC3")
	)
	(segment
		(start 370.631212 -66.833242)
		(end 371.881654 -65.5828)
		(width 0.089408)
		(layer "In9.Cu")
		(net "PWRGD_CPU1_LVC3")
	)
	(segment
		(start 371.881654 -65.5828)
		(end 372.269766 -65.5828)
		(width 0.089408)
		(layer "In9.Cu")
		(net "PWRGD_CPU1_LVC3")
	)
	(segment
		(start 370.631212 -67.53479)
		(end 370.631212 -66.833242)
		(width 0.089408)
		(layer "In9.Cu")
		(net "PWRGD_CPU1_LVC3")
	)
	(segment
		(start 371.57025 -67.88912)
		(end 370.985542 -67.88912)
		(width 0.089408)
		(layer "In9.Cu")
		(net "PWRGD_CPU1_LVC3")
	)
	(segment
		(start 372.269766 -65.5828)
		(end 372.662704 -65.189862)
		(width 0.089408)
		(layer "In9.Cu")
		(net "PWRGD_CPU1_LVC3")
	)
	(segment
		(start 157.099 -66.843148)
		(end 157.099 -83.192874)
		(width 0.089408)
		(layer "In11.Cu")
		(net "PWRGD_CPU1_LVC3")
	)
	(segment
		(start 158.886652 -65.055496)
		(end 157.099 -66.843148)
		(width 0.089408)
		(layer "In11.Cu")
		(net "PWRGD_CPU1_LVC3")
	)
	(segment
		(start 159.772858 -61.693806)
		(end 158.886652 -62.580012)
		(width 0.089408)
		(layer "In11.Cu")
		(net "PWRGD_CPU1_LVC3")
	)
	(segment
		(start 371.582696 -61.755274)
		(end 366.15116 -56.324754)
		(width 0.089408)
		(layer "In11.Cu")
		(net "PWRGD_CPU1_LVC3")
	)
	(segment
		(start 323.361304 -25.61717)
		(end 323.276468 -25.532334)
		(width 0.089408)
		(layer "In11.Cu")
		(net "PWRGD_CPU1_LVC3")
	)
	(segment
		(start 173.722538 -93.835982)
		(end 173.722538 -99.041712)
		(width 0.089408)
		(layer "In11.Cu")
		(net "PWRGD_CPU1_LVC3")
	)
	(segment
		(start 366.15116 -56.324754)
		(end 364.3757 -56.324754)
		(width 0.089408)
		(layer "In11.Cu")
		(net "PWRGD_CPU1_LVC3")
	)
	(segment
		(start 189.5475 -19.606768)
		(end 185.290714 -19.606768)
		(width 0.089408)
		(layer "In11.Cu")
		(net "PWRGD_CPU1_LVC3")
	)
	(segment
		(start 193.0654 2.427224)
		(end 193.0654 -3.5306)
		(width 0.089408)
		(layer "In11.Cu")
		(net "PWRGD_CPU1_LVC3")
	)
	(segment
		(start 173.722538 -99.041712)
		(end 174.401226 -99.7204)
		(width 0.089408)
		(layer "In11.Cu")
		(net "PWRGD_CPU1_LVC3")
	)
	(segment
		(start 360.461814 -52.410868)
		(end 359.043478 -52.410868)
		(width 0.089408)
		(layer "In11.Cu")
		(net "PWRGD_CPU1_LVC3")
	)
	(segment
		(start 173.988222 -92.167202)
		(end 173.988222 -93.570298)
		(width 0.089408)
		(layer "In11.Cu")
		(net "PWRGD_CPU1_LVC3")
	)
	(segment
		(start 158.886652 -62.580012)
		(end 158.886652 -65.055496)
		(width 0.089408)
		(layer "In11.Cu")
		(net "PWRGD_CPU1_LVC3")
	)
	(segment
		(start 185.290714 -19.606768)
		(end 183.80964 -21.087842)
		(width 0.089408)
		(layer "In11.Cu")
		(net "PWRGD_CPU1_LVC3")
	)
	(segment
		(start 193.5734 -5.7912)
		(end 193.0654 -6.2992)
		(width 0.089408)
		(layer "In11.Cu")
		(net "PWRGD_CPU1_LVC3")
	)
	(segment
		(start 193.5734 -4.0386)
		(end 193.5734 -5.7912)
		(width 0.089408)
		(layer "In11.Cu")
		(net "PWRGD_CPU1_LVC3")
	)
	(segment
		(start 364.3757 -56.324754)
		(end 360.461814 -52.410868)
		(width 0.089408)
		(layer "In11.Cu")
		(net "PWRGD_CPU1_LVC3")
	)
	(segment
		(start 321.843146 3.97002)
		(end 194.608196 3.97002)
		(width 0.089408)
		(layer "In11.Cu")
		(net "PWRGD_CPU1_LVC3")
	)
	(segment
		(start 172.471334 -90.650314)
		(end 173.988222 -92.167202)
		(width 0.089408)
		(layer "In11.Cu")
		(net "PWRGD_CPU1_LVC3")
	)
	(segment
		(start 323.361304 -27.962606)
		(end 323.361304 -25.61717)
		(width 0.089408)
		(layer "In11.Cu")
		(net "PWRGD_CPU1_LVC3")
	)
	(segment
		(start 320.302128 -34.405062)
		(end 321.374262 -34.405062)
		(width 0.089408)
		(layer "In11.Cu")
		(net "PWRGD_CPU1_LVC3")
	)
	(segment
		(start 320.152522 -44.741084)
		(end 318.570356 -43.158918)
		(width 0.089408)
		(layer "In11.Cu")
		(net "PWRGD_CPU1_LVC3")
	)
	(segment
		(start 323.276468 -24.957786)
		(end 323.41312 -24.821134)
		(width 0.089408)
		(layer "In11.Cu")
		(net "PWRGD_CPU1_LVC3")
	)
	(segment
		(start 371.582696 -62.89802)
		(end 371.582696 -61.755274)
		(width 0.089408)
		(layer "In11.Cu")
		(net "PWRGD_CPU1_LVC3")
	)
	(segment
		(start 183.80964 -30.23616)
		(end 159.772858 -54.272942)
		(width 0.089408)
		(layer "In11.Cu")
		(net "PWRGD_CPU1_LVC3")
	)
	(segment
		(start 323.276468 -25.532334)
		(end 323.276468 -24.957786)
		(width 0.089408)
		(layer "In11.Cu")
		(net "PWRGD_CPU1_LVC3")
	)
	(segment
		(start 372.921276 -64.2366)
		(end 371.582696 -62.89802)
		(width 0.089408)
		(layer "In11.Cu")
		(net "PWRGD_CPU1_LVC3")
	)
	(segment
		(start 193.0654 -16.0274)
		(end 190.580264 -18.512536)
		(width 0.089408)
		(layer "In11.Cu")
		(net "PWRGD_CPU1_LVC3")
	)
	(segment
		(start 318.570356 -43.158918)
		(end 318.570356 -36.136834)
		(width 0.089408)
		(layer "In11.Cu")
		(net "PWRGD_CPU1_LVC3")
	)
	(segment
		(start 328.581766 -50.252884)
		(end 323.069966 -44.741084)
		(width 0.089408)
		(layer "In11.Cu")
		(net "PWRGD_CPU1_LVC3")
	)
	(segment
		(start 164.55644 -90.650314)
		(end 172.471334 -90.650314)
		(width 0.089408)
		(layer "In11.Cu")
		(net "PWRGD_CPU1_LVC3")
	)
	(segment
		(start 159.772858 -54.272942)
		(end 159.772858 -61.693806)
		(width 0.089408)
		(layer "In11.Cu")
		(net "PWRGD_CPU1_LVC3")
	)
	(segment
		(start 190.53683 -18.617438)
		(end 189.5475 -19.606768)
		(width 0.089408)
		(layer "In11.Cu")
		(net "PWRGD_CPU1_LVC3")
	)
	(segment
		(start 323.41312 -24.821134)
		(end 323.41312 2.400046)
		(width 0.089408)
		(layer "In11.Cu")
		(net "PWRGD_CPU1_LVC3")
	)
	(segment
		(start 157.099 -83.192874)
		(end 164.55644 -90.650314)
		(width 0.089408)
		(layer "In11.Cu")
		(net "PWRGD_CPU1_LVC3")
	)
	(segment
		(start 321.374262 -34.405062)
		(end 323.983096 -31.796228)
		(width 0.089408)
		(layer "In11.Cu")
		(net "PWRGD_CPU1_LVC3")
	)
	(segment
		(start 356.885494 -50.252884)
		(end 328.581766 -50.252884)
		(width 0.089408)
		(layer "In11.Cu")
		(net "PWRGD_CPU1_LVC3")
	)
	(segment
		(start 323.983096 -31.796228)
		(end 323.983096 -28.584398)
		(width 0.089408)
		(layer "In11.Cu")
		(net "PWRGD_CPU1_LVC3")
	)
	(segment
		(start 173.988222 -93.570298)
		(end 173.722538 -93.835982)
		(width 0.089408)
		(layer "In11.Cu")
		(net "PWRGD_CPU1_LVC3")
	)
	(segment
		(start 318.570356 -36.136834)
		(end 320.302128 -34.405062)
		(width 0.089408)
		(layer "In11.Cu")
		(net "PWRGD_CPU1_LVC3")
	)
	(segment
		(start 193.0654 -6.2992)
		(end 193.0654 -16.0274)
		(width 0.089408)
		(layer "In11.Cu")
		(net "PWRGD_CPU1_LVC3")
	)
	(segment
		(start 323.069966 -44.741084)
		(end 320.152522 -44.741084)
		(width 0.089408)
		(layer "In11.Cu")
		(net "PWRGD_CPU1_LVC3")
	)
	(segment
		(start 323.41312 2.400046)
		(end 321.843146 3.97002)
		(width 0.089408)
		(layer "In11.Cu")
		(net "PWRGD_CPU1_LVC3")
	)
	(segment
		(start 194.608196 3.97002)
		(end 193.0654 2.427224)
		(width 0.089408)
		(layer "In11.Cu")
		(net "PWRGD_CPU1_LVC3")
	)
	(segment
		(start 359.043478 -52.410868)
		(end 356.885494 -50.252884)
		(width 0.089408)
		(layer "In11.Cu")
		(net "PWRGD_CPU1_LVC3")
	)
	(segment
		(start 323.983096 -28.584398)
		(end 323.361304 -27.962606)
		(width 0.089408)
		(layer "In11.Cu")
		(net "PWRGD_CPU1_LVC3")
	)
	(segment
		(start 190.580264 -18.512536)
		(end 190.53683 -18.617438)
		(width 0.089408)
		(layer "In11.Cu")
		(net "PWRGD_CPU1_LVC3")
	)
	(segment
		(start 183.80964 -21.087842)
		(end 183.80964 -30.23616)
		(width 0.089408)
		(layer "In11.Cu")
		(net "PWRGD_CPU1_LVC3")
	)
	(segment
		(start 372.9863 -64.2366)
		(end 372.921276 -64.2366)
		(width 0.089408)
		(layer "In11.Cu")
		(net "PWRGD_CPU1_LVC3")
	)
	(segment
		(start 193.0654 -3.5306)
		(end 193.5734 -4.0386)
		(width 0.089408)
		(layer "In11.Cu")
		(net "PWRGD_CPU1_LVC3")
	)
	(segment
		(start 175.932338 -96.310704)
		(end 175.932338 -97.55505)
		(width 0.10795)
		(layer "F.Cu")
		(net "PWRGD_CPU1_G")
	)
	(segment
		(start 175.424338 -98.06305)
		(end 175.424084 -98.06305)
		(width 0.10795)
		(layer "F.Cu")
		(net "PWRGD_CPU1_G")
	)
	(segment
		(start 117.5512 -73.787)
		(end 117.1956 -73.787)
		(width 0.10795)
		(layer "F.Cu")
		(net "PWRGD_CPU1_G")
	)
	(segment
		(start 175.932338 -97.55505)
		(end 175.424338 -98.06305)
		(width 0.10795)
		(layer "F.Cu")
		(net "PWRGD_CPU1_G")
	)
	(segment
		(start 175.424084 -98.06305)
		(end 174.931578 -98.555556)
		(width 0.10795)
		(layer "F.Cu")
		(net "PWRGD_CPU1_G")
	)
	(segment
		(start 117.8052 -73.533)
		(end 117.5512 -73.787)
		(width 0.10795)
		(layer "F.Cu")
		(net "PWRGD_CPU1_G")
	)
	(segment
		(start 122.504708 -72.249538)
		(end 123.076208 -72.249538)
		(width 0.1016)
		(layer "F.Cu")
		(net "PWRGD_CPU1_G")
	)
	(segment
		(start 174.931578 -98.555556)
		(end 172.739304 -98.555556)
		(width 0.10795)
		(layer "F.Cu")
		(net "PWRGD_CPU1_G")
	)
	(segment
		(start 172.739304 -98.555556)
		(end 172.56379 -98.73107)
		(width 0.10795)
		(layer "F.Cu")
		(net "PWRGD_CPU1_G")
	)
	(via
		(at 172.56379 -98.73107)
		(size 0.508)
		(drill 0.254)
		(layers "F.Cu" "B.Cu")
		(net "PWRGD_CPU1_G")
	)
	(via
		(at 123.076208 -72.249538)
		(size 0.508)
		(drill 0.254)
		(layers "F.Cu" "B.Cu")
		(net "PWRGD_CPU1_G")
	)
	(via
		(at 117.8052 -73.533)
		(size 0.508)
		(drill 0.254)
		(layers "F.Cu" "B.Cu")
		(net "PWRGD_CPU1_G")
	)
	(segment
		(start 133.360414 -69.868288)
		(end 133.395974 -69.868288)
		(width 0.0889)
		(layer "In4.Cu")
		(net "PWRGD_CPU1_G")
	)
	(segment
		(start 161.00171 -74.204576)
		(end 161.498534 -74.7014)
		(width 0.089408)
		(layer "In4.Cu")
		(net "PWRGD_CPU1_G")
	)
	(segment
		(start 159.935418 -73.942702)
		(end 160.197292 -74.204576)
		(width 0.089408)
		(layer "In4.Cu")
		(net "PWRGD_CPU1_G")
	)
	(segment
		(start 172.198538 -98.365818)
		(end 172.56379 -98.73107)
		(width 0.089408)
		(layer "In4.Cu")
		(net "PWRGD_CPU1_G")
	)
	(segment
		(start 141.54531 -69.695568)
		(end 141.788896 -69.939154)
		(width 0.0889)
		(layer "In4.Cu")
		(net "PWRGD_CPU1_G")
	)
	(segment
		(start 123.913138 -69.372734)
		(end 123.956318 -69.372734)
		(width 0.0889)
		(layer "In4.Cu")
		(net "PWRGD_CPU1_G")
	)
	(segment
		(start 136.794494 -69.868288)
		(end 136.830054 -69.868288)
		(width 0.0889)
		(layer "In4.Cu")
		(net "PWRGD_CPU1_G")
	)
	(segment
		(start 172.332904 -95.276924)
		(end 172.332904 -97.143062)
		(width 0.089408)
		(layer "In4.Cu")
		(net "PWRGD_CPU1_G")
	)
	(segment
		(start 160.197292 -74.204576)
		(end 161.00171 -74.204576)
		(width 0.089408)
		(layer "In4.Cu")
		(net "PWRGD_CPU1_G")
	)
	(segment
		(start 131.643628 -69.868288)
		(end 131.679188 -69.868288)
		(width 0.0889)
		(layer "In4.Cu")
		(net "PWRGD_CPU1_G")
	)
	(segment
		(start 128.209548 -69.868288)
		(end 128.245108 -69.868288)
		(width 0.0889)
		(layer "In4.Cu")
		(net "PWRGD_CPU1_G")
	)
	(segment
		(start 122.637804 -69.142356)
		(end 122.901202 -68.878958)
		(width 0.089408)
		(layer "In4.Cu")
		(net "PWRGD_CPU1_G")
	)
	(segment
		(start 125.630178 -69.372734)
		(end 125.662944 -69.372734)
		(width 0.0889)
		(layer "In4.Cu")
		(net "PWRGD_CPU1_G")
	)
	(segment
		(start 126.492508 -69.868288)
		(end 126.528068 -69.868288)
		(width 0.0889)
		(layer "In4.Cu")
		(net "PWRGD_CPU1_G")
	)
	(segment
		(start 125.992128 -69.562218)
		(end 125.998478 -69.572886)
		(width 0.0889)
		(layer "In4.Cu")
		(net "PWRGD_CPU1_G")
	)
	(segment
		(start 171.192952 -92.579952)
		(end 171.192952 -94.136972)
		(width 0.089408)
		(layer "In4.Cu")
		(net "PWRGD_CPU1_G")
	)
	(segment
		(start 129.926588 -69.868288)
		(end 129.962148 -69.868288)
		(width 0.0889)
		(layer "In4.Cu")
		(net "PWRGD_CPU1_G")
	)
	(segment
		(start 163.644834 -75.662028)
		(end 163.644834 -83.667092)
		(width 0.089408)
		(layer "In4.Cu")
		(net "PWRGD_CPU1_G")
	)
	(segment
		(start 132.173218 -69.572886)
		(end 132.17652 -69.567044)
		(width 0.0889)
		(layer "In4.Cu")
		(net "PWRGD_CPU1_G")
	)
	(segment
		(start 142.548102 -69.939154)
		(end 142.938246 -69.54901)
		(width 0.089408)
		(layer "In4.Cu")
		(net "PWRGD_CPU1_G")
	)
	(segment
		(start 169.214038 -90.601038)
		(end 171.192952 -92.579952)
		(width 0.089408)
		(layer "In4.Cu")
		(net "PWRGD_CPU1_G")
	)
	(segment
		(start 124.778262 -68.877688)
		(end 124.808234 -68.877688)
		(width 0.0889)
		(layer "In4.Cu")
		(net "PWRGD_CPU1_G")
	)
	(segment
		(start 167.90543 -87.927688)
		(end 168.783254 -87.927688)
		(width 0.089408)
		(layer "In4.Cu")
		(net "PWRGD_CPU1_G")
	)
	(segment
		(start 122.901202 -68.878958)
		(end 123.063 -68.878958)
		(width 0.089408)
		(layer "In4.Cu")
		(net "PWRGD_CPU1_G")
	)
	(segment
		(start 140.228574 -69.868288)
		(end 140.264134 -69.868288)
		(width 0.0889)
		(layer "In4.Cu")
		(net "PWRGD_CPU1_G")
	)
	(segment
		(start 169.214038 -88.358472)
		(end 169.214038 -90.601038)
		(width 0.089408)
		(layer "In4.Cu")
		(net "PWRGD_CPU1_G")
	)
	(segment
		(start 141.788896 -69.939154)
		(end 142.548102 -69.939154)
		(width 0.0889)
		(layer "In4.Cu")
		(net "PWRGD_CPU1_G")
	)
	(segment
		(start 162.684206 -74.7014)
		(end 163.644834 -75.662028)
		(width 0.089408)
		(layer "In4.Cu")
		(net "PWRGD_CPU1_G")
	)
	(segment
		(start 122.637804 -71.811134)
		(end 122.637804 -69.142356)
		(width 0.089408)
		(layer "In4.Cu")
		(net "PWRGD_CPU1_G")
	)
	(segment
		(start 171.192952 -94.136972)
		(end 172.332904 -95.276924)
		(width 0.089408)
		(layer "In4.Cu")
		(net "PWRGD_CPU1_G")
	)
	(segment
		(start 142.938246 -69.54901)
		(end 154.783028 -69.54901)
		(width 0.089408)
		(layer "In4.Cu")
		(net "PWRGD_CPU1_G")
	)
	(segment
		(start 172.198538 -97.277428)
		(end 172.198538 -98.365818)
		(width 0.089408)
		(layer "In4.Cu")
		(net "PWRGD_CPU1_G")
	)
	(segment
		(start 172.332904 -97.143062)
		(end 172.198538 -97.277428)
		(width 0.089408)
		(layer "In4.Cu")
		(net "PWRGD_CPU1_G")
	)
	(segment
		(start 138.511534 -69.868288)
		(end 138.547094 -69.868288)
		(width 0.0889)
		(layer "In4.Cu")
		(net "PWRGD_CPU1_G")
	)
	(segment
		(start 159.17672 -73.942702)
		(end 159.935418 -73.942702)
		(width 0.089408)
		(layer "In4.Cu")
		(net "PWRGD_CPU1_G")
	)
	(segment
		(start 161.498534 -74.7014)
		(end 162.684206 -74.7014)
		(width 0.089408)
		(layer "In4.Cu")
		(net "PWRGD_CPU1_G")
	)
	(segment
		(start 168.783254 -87.927688)
		(end 169.214038 -88.358472)
		(width 0.089408)
		(layer "In4.Cu")
		(net "PWRGD_CPU1_G")
	)
	(segment
		(start 123.076208 -72.249538)
		(end 122.637804 -71.811134)
		(width 0.089408)
		(layer "In4.Cu")
		(net "PWRGD_CPU1_G")
	)
	(segment
		(start 154.783028 -69.54901)
		(end 159.17672 -73.942702)
		(width 0.089408)
		(layer "In4.Cu")
		(net "PWRGD_CPU1_G")
	)
	(segment
		(start 163.644834 -83.667092)
		(end 167.90543 -87.927688)
		(width 0.089408)
		(layer "In4.Cu")
		(net "PWRGD_CPU1_G")
	)
	(arc
		(start 136.830054 -69.868288)
		(mid 137.115478 -69.784821)
		(end 137.324084 -69.572886)
		(width 0.0889)
		(layer "In4.Cu")
		(net "PWRGD_CPU1_G")
	)
	(arc
		(start 124.808234 -68.877688)
		(mid 124.999876 -68.934854)
		(end 125.139958 -69.077586)
		(width 0.0889)
		(layer "In4.Cu")
		(net "PWRGD_CPU1_G")
	)
	(arc
		(start 125.139958 -69.077586)
		(mid 125.346962 -69.28845)
		(end 125.630178 -69.372734)
		(width 0.0889)
		(layer "In4.Cu")
		(net "PWRGD_CPU1_G")
	)
	(arc
		(start 132.17652 -69.567044)
		(mid 132.523093 -69.372694)
		(end 132.866384 -69.572886)
		(width 0.0889)
		(layer "In4.Cu")
		(net "PWRGD_CPU1_G")
	)
	(arc
		(start 125.662944 -69.372734)
		(mid 125.852864 -69.423483)
		(end 125.992128 -69.562218)
		(width 0.0889)
		(layer "In4.Cu")
		(net "PWRGD_CPU1_G")
	)
	(arc
		(start 141.451584 -69.572886)
		(mid 141.464355 -69.594116)
		(end 141.478 -69.614796)
		(width 0.0889)
		(layer "In4.Cu")
		(net "PWRGD_CPU1_G")
	)
	(arc
		(start 135.607044 -69.572886)
		(mid 135.953754 -69.372575)
		(end 136.300464 -69.572886)
		(width 0.0889)
		(layer "In4.Cu")
		(net "PWRGD_CPU1_G")
	)
	(arc
		(start 139.041124 -69.572886)
		(mid 139.387834 -69.372575)
		(end 139.734544 -69.572886)
		(width 0.0889)
		(layer "In4.Cu")
		(net "PWRGD_CPU1_G")
	)
	(arc
		(start 126.528068 -69.868288)
		(mid 126.813492 -69.784821)
		(end 127.022098 -69.572886)
		(width 0.0889)
		(layer "In4.Cu")
		(net "PWRGD_CPU1_G")
	)
	(arc
		(start 133.395974 -69.868288)
		(mid 133.681398 -69.784821)
		(end 133.890004 -69.572886)
		(width 0.0889)
		(layer "In4.Cu")
		(net "PWRGD_CPU1_G")
	)
	(arc
		(start 138.547094 -69.868288)
		(mid 138.832518 -69.784821)
		(end 139.041124 -69.572886)
		(width 0.0889)
		(layer "In4.Cu")
		(net "PWRGD_CPU1_G")
	)
	(arc
		(start 130.456178 -69.572886)
		(mid 130.802888 -69.372575)
		(end 131.149598 -69.572886)
		(width 0.0889)
		(layer "In4.Cu")
		(net "PWRGD_CPU1_G")
	)
	(arc
		(start 131.679188 -69.868288)
		(mid 131.964612 -69.784821)
		(end 132.173218 -69.572886)
		(width 0.0889)
		(layer "In4.Cu")
		(net "PWRGD_CPU1_G")
	)
	(arc
		(start 127.715518 -69.572886)
		(mid 127.924126 -69.784818)
		(end 128.209548 -69.868288)
		(width 0.0889)
		(layer "In4.Cu")
		(net "PWRGD_CPU1_G")
	)
	(arc
		(start 140.264134 -69.868288)
		(mid 140.549558 -69.784821)
		(end 140.758164 -69.572886)
		(width 0.0889)
		(layer "In4.Cu")
		(net "PWRGD_CPU1_G")
	)
	(arc
		(start 133.890004 -69.572886)
		(mid 134.236714 -69.372575)
		(end 134.583424 -69.572886)
		(width 0.0889)
		(layer "In4.Cu")
		(net "PWRGD_CPU1_G")
	)
	(arc
		(start 141.478 -69.614796)
		(mid 141.509855 -69.656682)
		(end 141.54531 -69.695568)
		(width 0.0889)
		(layer "In4.Cu")
		(net "PWRGD_CPU1_G")
	)
	(arc
		(start 123.956318 -69.372734)
		(mid 124.239535 -69.288453)
		(end 124.446538 -69.077586)
		(width 0.0889)
		(layer "In4.Cu")
		(net "PWRGD_CPU1_G")
	)
	(arc
		(start 134.583424 -69.572886)
		(mid 135.095234 -69.868553)
		(end 135.607044 -69.572886)
		(width 0.0889)
		(layer "In4.Cu")
		(net "PWRGD_CPU1_G")
	)
	(arc
		(start 123.422918 -69.077586)
		(mid 123.629922 -69.28845)
		(end 123.913138 -69.372734)
		(width 0.0889)
		(layer "In4.Cu")
		(net "PWRGD_CPU1_G")
	)
	(arc
		(start 124.446538 -69.077586)
		(mid 124.586617 -68.93485)
		(end 124.778262 -68.877688)
		(width 0.0889)
		(layer "In4.Cu")
		(net "PWRGD_CPU1_G")
	)
	(arc
		(start 129.432558 -69.572886)
		(mid 129.641166 -69.784818)
		(end 129.926588 -69.868288)
		(width 0.0889)
		(layer "In4.Cu")
		(net "PWRGD_CPU1_G")
	)
	(arc
		(start 140.758164 -69.572886)
		(mid 141.104874 -69.372575)
		(end 141.451584 -69.572886)
		(width 0.0889)
		(layer "In4.Cu")
		(net "PWRGD_CPU1_G")
	)
	(arc
		(start 131.149598 -69.572886)
		(mid 131.358206 -69.784818)
		(end 131.643628 -69.868288)
		(width 0.0889)
		(layer "In4.Cu")
		(net "PWRGD_CPU1_G")
	)
	(arc
		(start 132.866384 -69.572886)
		(mid 133.074992 -69.784818)
		(end 133.360414 -69.868288)
		(width 0.0889)
		(layer "In4.Cu")
		(net "PWRGD_CPU1_G")
	)
	(arc
		(start 137.324084 -69.572886)
		(mid 137.670794 -69.372575)
		(end 138.017504 -69.572886)
		(width 0.0889)
		(layer "In4.Cu")
		(net "PWRGD_CPU1_G")
	)
	(arc
		(start 139.734544 -69.572886)
		(mid 139.943152 -69.784818)
		(end 140.228574 -69.868288)
		(width 0.0889)
		(layer "In4.Cu")
		(net "PWRGD_CPU1_G")
	)
	(arc
		(start 136.300464 -69.572886)
		(mid 136.509072 -69.784818)
		(end 136.794494 -69.868288)
		(width 0.0889)
		(layer "In4.Cu")
		(net "PWRGD_CPU1_G")
	)
	(arc
		(start 128.739138 -69.572886)
		(mid 129.085848 -69.372575)
		(end 129.432558 -69.572886)
		(width 0.0889)
		(layer "In4.Cu")
		(net "PWRGD_CPU1_G")
	)
	(arc
		(start 123.063 -68.878958)
		(mid 123.270641 -68.928138)
		(end 123.422918 -69.077586)
		(width 0.0889)
		(layer "In4.Cu")
		(net "PWRGD_CPU1_G")
	)
	(arc
		(start 127.022098 -69.572886)
		(mid 127.368808 -69.372575)
		(end 127.715518 -69.572886)
		(width 0.0889)
		(layer "In4.Cu")
		(net "PWRGD_CPU1_G")
	)
	(arc
		(start 138.017504 -69.572886)
		(mid 138.226112 -69.784818)
		(end 138.511534 -69.868288)
		(width 0.0889)
		(layer "In4.Cu")
		(net "PWRGD_CPU1_G")
	)
	(arc
		(start 125.998478 -69.572886)
		(mid 126.207086 -69.784818)
		(end 126.492508 -69.868288)
		(width 0.0889)
		(layer "In4.Cu")
		(net "PWRGD_CPU1_G")
	)
	(arc
		(start 128.245108 -69.868288)
		(mid 128.530532 -69.784821)
		(end 128.739138 -69.572886)
		(width 0.0889)
		(layer "In4.Cu")
		(net "PWRGD_CPU1_G")
	)
	(arc
		(start 129.962148 -69.868288)
		(mid 130.247572 -69.784821)
		(end 130.456178 -69.572886)
		(width 0.0889)
		(layer "In4.Cu")
		(net "PWRGD_CPU1_G")
	)
	(segment
		(start 118.455186 -72.298814)
		(end 119.823992 -72.298814)
		(width 0.0889)
		(layer "In11.Cu")
		(net "PWRGD_CPU1_G")
	)
	(segment
		(start 120.174766 -72.649588)
		(end 121.370344 -72.649588)
		(width 0.0889)
		(layer "In11.Cu")
		(net "PWRGD_CPU1_G")
	)
	(segment
		(start 117.8306 -73.5076)
		(end 117.8306 -72.9234)
		(width 0.0889)
		(layer "In11.Cu")
		(net "PWRGD_CPU1_G")
	)
	(segment
		(start 117.8306 -72.9234)
		(end 118.455186 -72.298814)
		(width 0.0889)
		(layer "In11.Cu")
		(net "PWRGD_CPU1_G")
	)
	(segment
		(start 122.253756 -72.154034)
		(end 123.076208 -72.249538)
		(width 0.0889)
		(layer "In11.Cu")
		(net "PWRGD_CPU1_G")
	)
	(segment
		(start 119.823992 -72.298814)
		(end 120.174766 -72.649588)
		(width 0.0889)
		(layer "In11.Cu")
		(net "PWRGD_CPU1_G")
	)
	(segment
		(start 122.199908 -72.154034)
		(end 122.253756 -72.154034)
		(width 0.0889)
		(layer "In11.Cu")
		(net "PWRGD_CPU1_G")
	)
	(segment
		(start 117.8052 -73.533)
		(end 117.8306 -73.5076)
		(width 0.0889)
		(layer "In11.Cu")
		(net "PWRGD_CPU1_G")
	)
	(arc
		(start 121.705878 -72.449436)
		(mid 121.914486 -72.237504)
		(end 122.199908 -72.154034)
		(width 0.0889)
		(layer "In11.Cu")
		(net "PWRGD_CPU1_G")
	)
	(arc
		(start 121.370344 -72.649588)
		(mid 121.564194 -72.593238)
		(end 121.705878 -72.449436)
		(width 0.0889)
		(layer "In11.Cu")
		(net "PWRGD_CPU1_G")
	)
	(segment
		(start 375.944892 -76.694792)
		(end 375.545096 -76.294996)
		(width 0.10795)
		(layer "F.Cu")
		(net "PWRGD_CPU0_LVC3")
	)
	(via
		(at 363.815376 -73.516998)
		(size 0.6604)
		(drill 0.3302)
		(layers "F.Cu" "B.Cu")
		(net "PWRGD_CPU0_LVC3")
	)
	(via
		(at 375.944892 -76.694792)
		(size 0.4572)
		(drill 0.2032)
		(layers "F.Cu" "B.Cu")
		(net "PWRGD_CPU0_LVC3")
	)
	(segment
		(start 374.903238 -74.312018)
		(end 375.5517 -74.96048)
		(width 0.10795)
		(layer "B.Cu")
		(net "PWRGD_CPU0_LVC3")
	)
	(segment
		(start 366.72774 -76.01839)
		(end 366.98682 -76.27747)
		(width 0.10795)
		(layer "B.Cu")
		(net "PWRGD_CPU0_LVC3")
	)
	(segment
		(start 369.305078 -75.506326)
		(end 369.764564 -75.506326)
		(width 0.10795)
		(layer "B.Cu")
		(net "PWRGD_CPU0_LVC3")
	)
	(segment
		(start 363.9185 -51.91252)
		(end 362.530898 -51.91252)
		(width 0.10795)
		(layer "B.Cu")
		(net "PWRGD_CPU0_LVC3")
	)
	(segment
		(start 362.530898 -51.91252)
		(end 362.05414 -52.389278)
		(width 0.10795)
		(layer "B.Cu")
		(net "PWRGD_CPU0_LVC3")
	)
	(segment
		(start 369.141756 -75.669648)
		(end 369.305078 -75.506326)
		(width 0.10795)
		(layer "B.Cu")
		(net "PWRGD_CPU0_LVC3")
	)
	(segment
		(start 370.586762 -74.312018)
		(end 374.903238 -74.312018)
		(width 0.10795)
		(layer "B.Cu")
		(net "PWRGD_CPU0_LVC3")
	)
	(segment
		(start 369.141756 -76.062586)
		(end 369.141756 -75.669648)
		(width 0.10795)
		(layer "B.Cu")
		(net "PWRGD_CPU0_LVC3")
	)
	(segment
		(start 368.926872 -76.27747)
		(end 369.141756 -76.062586)
		(width 0.10795)
		(layer "B.Cu")
		(net "PWRGD_CPU0_LVC3")
	)
	(segment
		(start 354.517198 -70.255384)
		(end 354.517198 -72.125586)
		(width 0.10795)
		(layer "B.Cu")
		(net "PWRGD_CPU0_LVC3")
	)
	(segment
		(start 360.917744 -55.833264)
		(end 360.632502 -56.118506)
		(width 0.10795)
		(layer "B.Cu")
		(net "PWRGD_CPU0_LVC3")
	)
	(segment
		(start 375.5517 -74.96048)
		(end 375.5517 -76.3016)
		(width 0.10795)
		(layer "B.Cu")
		(net "PWRGD_CPU0_LVC3")
	)
	(segment
		(start 362.05414 -55.258462)
		(end 361.479338 -55.833264)
		(width 0.10795)
		(layer "B.Cu")
		(net "PWRGD_CPU0_LVC3")
	)
	(segment
		(start 360.632502 -58.316876)
		(end 360.227626 -58.721752)
		(width 0.10795)
		(layer "B.Cu")
		(net "PWRGD_CPU0_LVC3")
	)
	(segment
		(start 366.72774 -75.73645)
		(end 366.72774 -76.01839)
		(width 0.10795)
		(layer "B.Cu")
		(net "PWRGD_CPU0_LVC3")
	)
	(segment
		(start 375.5517 -76.3016)
		(end 375.944892 -76.694792)
		(width 0.10795)
		(layer "B.Cu")
		(net "PWRGD_CPU0_LVC3")
	)
	(segment
		(start 365.794036 -75.495658)
		(end 366.486948 -75.495658)
		(width 0.10795)
		(layer "B.Cu")
		(net "PWRGD_CPU0_LVC3")
	)
	(segment
		(start 369.96243 -74.93635)
		(end 370.586762 -74.312018)
		(width 0.10795)
		(layer "B.Cu")
		(net "PWRGD_CPU0_LVC3")
	)
	(segment
		(start 360.227626 -64.544956)
		(end 354.517198 -70.255384)
		(width 0.10795)
		(layer "B.Cu")
		(net "PWRGD_CPU0_LVC3")
	)
	(segment
		(start 369.962684 -75.253596)
		(end 369.96243 -75.253342)
		(width 0.10795)
		(layer "B.Cu")
		(net "PWRGD_CPU0_LVC3")
	)
	(segment
		(start 363.815376 -73.516998)
		(end 365.794036 -75.495658)
		(width 0.10795)
		(layer "B.Cu")
		(net "PWRGD_CPU0_LVC3")
	)
	(segment
		(start 369.96243 -75.253342)
		(end 369.96243 -74.93635)
		(width 0.10795)
		(layer "B.Cu")
		(net "PWRGD_CPU0_LVC3")
	)
	(segment
		(start 366.486948 -75.495658)
		(end 366.72774 -75.73645)
		(width 0.10795)
		(layer "B.Cu")
		(net "PWRGD_CPU0_LVC3")
	)
	(segment
		(start 362.862622 -72.564244)
		(end 363.815376 -73.516998)
		(width 0.10795)
		(layer "B.Cu")
		(net "PWRGD_CPU0_LVC3")
	)
	(segment
		(start 369.962684 -75.308206)
		(end 369.962684 -75.253596)
		(width 0.10795)
		(layer "B.Cu")
		(net "PWRGD_CPU0_LVC3")
	)
	(segment
		(start 369.764564 -75.506326)
		(end 369.962684 -75.308206)
		(width 0.10795)
		(layer "B.Cu")
		(net "PWRGD_CPU0_LVC3")
	)
	(segment
		(start 360.227626 -58.721752)
		(end 360.227626 -64.544956)
		(width 0.10795)
		(layer "B.Cu")
		(net "PWRGD_CPU0_LVC3")
	)
	(segment
		(start 354.955856 -72.564244)
		(end 362.862622 -72.564244)
		(width 0.10795)
		(layer "B.Cu")
		(net "PWRGD_CPU0_LVC3")
	)
	(segment
		(start 361.479338 -55.833264)
		(end 360.917744 -55.833264)
		(width 0.10795)
		(layer "B.Cu")
		(net "PWRGD_CPU0_LVC3")
	)
	(segment
		(start 354.517198 -72.125586)
		(end 354.955856 -72.564244)
		(width 0.10795)
		(layer "B.Cu")
		(net "PWRGD_CPU0_LVC3")
	)
	(segment
		(start 360.632502 -56.118506)
		(end 360.632502 -58.316876)
		(width 0.10795)
		(layer "B.Cu")
		(net "PWRGD_CPU0_LVC3")
	)
	(segment
		(start 366.98682 -76.27747)
		(end 368.926872 -76.27747)
		(width 0.10795)
		(layer "B.Cu")
		(net "PWRGD_CPU0_LVC3")
	)
	(segment
		(start 362.05414 -52.389278)
		(end 362.05414 -55.258462)
		(width 0.10795)
		(layer "B.Cu")
		(net "PWRGD_CPU0_LVC3")
	)
	(segment
		(start 385.30784 -84.859622)
		(end 385.440428 -84.727034)
		(width 0.10795)
		(layer "F.Cu")
		(net "PWRGD_CPU0_G")
	)
	(segment
		(start 427.252638 -116.686838)
		(end 427.252638 -119.252238)
		(width 0.10795)
		(layer "F.Cu")
		(net "PWRGD_CPU0_G")
	)
	(segment
		(start 426.448982 -113.219738)
		(end 426.448982 -115.883182)
		(width 0.10795)
		(layer "F.Cu")
		(net "PWRGD_CPU0_G")
	)
	(segment
		(start 417.010088 -80.085692)
		(end 417.010088 -80.258412)
		(width 0.10795)
		(layer "F.Cu")
		(net "PWRGD_CPU0_G")
	)
	(segment
		(start 391.85596 -81.4578)
		(end 392.0998 -81.4578)
		(width 0.10795)
		(layer "F.Cu")
		(net "PWRGD_CPU0_G")
	)
	(segment
		(start 287.50514 -72.249538)
		(end 288.07664 -72.249538)
		(width 0.1016)
		(layer "F.Cu")
		(net "PWRGD_CPU0_G")
	)
	(segment
		(start 377.417838 -82.316574)
		(end 378.963174 -83.86191)
		(width 0.10795)
		(layer "F.Cu")
		(net "PWRGD_CPU0_G")
	)
	(segment
		(start 419.697916 -78.470506)
		(end 419.38321 -78.785212)
		(width 0.10795)
		(layer "F.Cu")
		(net "PWRGD_CPU0_G")
	)
	(segment
		(start 357.811324 -72.847454)
		(end 357.153464 -72.847454)
		(width 0.10795)
		(layer "F.Cu")
		(net "PWRGD_CPU0_G")
	)
	(segment
		(start 371.759734 -82.503772)
		(end 372.816882 -83.56092)
		(width 0.10795)
		(layer "F.Cu")
		(net "PWRGD_CPU0_G")
	)
	(segment
		(start 382.917954 -84.55914)
		(end 383.218436 -84.859622)
		(width 0.10795)
		(layer "F.Cu")
		(net "PWRGD_CPU0_G")
	)
	(segment
		(start 282.637992 -73.470008)
		(end 282.067 -74.041)
		(width 0.10795)
		(layer "F.Cu")
		(net "PWRGD_CPU0_G")
	)
	(segment
		(start 419.38321 -78.785212)
		(end 418.310568 -78.785212)
		(width 0.10795)
		(layer "F.Cu")
		(net "PWRGD_CPU0_G")
	)
	(segment
		(start 357.153464 -72.847454)
		(end 357.029258 -72.723248)
		(width 0.10795)
		(layer "F.Cu")
		(net "PWRGD_CPU0_G")
	)
	(segment
		(start 427.252638 -119.252238)
		(end 429.880522 -121.880122)
		(width 0.10795)
		(layer "F.Cu")
		(net "PWRGD_CPU0_G")
	)
	(segment
		(start 283.26842 -73.470008)
		(end 282.637992 -73.470008)
		(width 0.10795)
		(layer "F.Cu")
		(net "PWRGD_CPU0_G")
	)
	(segment
		(start 426.149262 -111.154972)
		(end 426.149262 -111.993426)
		(width 0.10795)
		(layer "F.Cu")
		(net "PWRGD_CPU0_G")
	)
	(segment
		(start 370.16563 -81.703164)
		(end 370.17071 -81.708244)
		(width 0.10795)
		(layer "F.Cu")
		(net "PWRGD_CPU0_G")
	)
	(segment
		(start 421.8178 -89.6874)
		(end 425.027852 -92.897452)
		(width 0.10795)
		(layer "F.Cu")
		(net "PWRGD_CPU0_G")
	)
	(segment
		(start 425.86656 -112.287304)
		(end 425.86656 -112.637316)
		(width 0.10795)
		(layer "F.Cu")
		(net "PWRGD_CPU0_G")
	)
	(segment
		(start 421.471852 -78.470506)
		(end 419.697916 -78.470506)
		(width 0.10795)
		(layer "F.Cu")
		(net "PWRGD_CPU0_G")
	)
	(segment
		(start 429.880522 -121.880122)
		(end 429.880522 -123.763786)
		(width 0.10795)
		(layer "F.Cu")
		(net "PWRGD_CPU0_G")
	)
	(segment
		(start 375.56059 -82.546444)
		(end 375.79046 -82.316574)
		(width 0.10795)
		(layer "F.Cu")
		(net "PWRGD_CPU0_G")
	)
	(segment
		(start 393.1412 -80.4164)
		(end 393.446 -80.4164)
		(width 0.10795)
		(layer "F.Cu")
		(net "PWRGD_CPU0_G")
	)
	(segment
		(start 370.493544 -81.979262)
		(end 371.759734 -82.503772)
		(width 0.10795)
		(layer "F.Cu")
		(net "PWRGD_CPU0_G")
	)
	(segment
		(start 357.029258 -72.723248)
		(end 355.949504 -72.723248)
		(width 0.10795)
		(layer "F.Cu")
		(net "PWRGD_CPU0_G")
	)
	(segment
		(start 372.816882 -83.56092)
		(end 373.761 -83.56092)
		(width 0.10795)
		(layer "F.Cu")
		(net "PWRGD_CPU0_G")
	)
	(segment
		(start 355.708966 -71.90359)
		(end 355.327204 -71.521828)
		(width 0.10795)
		(layer "F.Cu")
		(net "PWRGD_CPU0_G")
	)
	(segment
		(start 373.761 -83.56092)
		(end 374.775476 -82.546444)
		(width 0.10795)
		(layer "F.Cu")
		(net "PWRGD_CPU0_G")
	)
	(segment
		(start 363.365288 -75.645518)
		(end 363.365288 -79.35468)
		(width 0.10795)
		(layer "F.Cu")
		(net "PWRGD_CPU0_G")
	)
	(segment
		(start 363.365288 -79.35468)
		(end 365.713772 -81.703164)
		(width 0.10795)
		(layer "F.Cu")
		(net "PWRGD_CPU0_G")
	)
	(segment
		(start 390.750044 -82.563716)
		(end 391.85596 -81.4578)
		(width 0.10795)
		(layer "F.Cu")
		(net "PWRGD_CPU0_G")
	)
	(segment
		(start 425.027852 -92.897452)
		(end 425.027852 -110.033562)
		(width 0.10795)
		(layer "F.Cu")
		(net "PWRGD_CPU0_G")
	)
	(segment
		(start 417.010088 -80.258412)
		(end 416.073844 -81.194656)
		(width 0.10795)
		(layer "F.Cu")
		(net "PWRGD_CPU0_G")
	)
	(segment
		(start 422.0718 -89.3064)
		(end 423.942002 -87.436198)
		(width 0.10795)
		(layer "F.Cu")
		(net "PWRGD_CPU0_G")
	)
	(segment
		(start 425.86656 -112.637316)
		(end 426.448982 -113.219738)
		(width 0.10795)
		(layer "F.Cu")
		(net "PWRGD_CPU0_G")
	)
	(segment
		(start 421.8178 -89.3064)
		(end 421.8178 -89.6874)
		(width 0.10795)
		(layer "F.Cu")
		(net "PWRGD_CPU0_G")
	)
	(segment
		(start 390.386824 -82.563716)
		(end 390.750044 -82.563716)
		(width 0.10795)
		(layer "F.Cu")
		(net "PWRGD_CPU0_G")
	)
	(segment
		(start 381.27432 -83.86191)
		(end 381.97155 -84.55914)
		(width 0.10795)
		(layer "F.Cu")
		(net "PWRGD_CPU0_G")
	)
	(segment
		(start 388.223506 -84.727034)
		(end 390.386824 -82.563716)
		(width 0.10795)
		(layer "F.Cu")
		(net "PWRGD_CPU0_G")
	)
	(segment
		(start 383.218436 -84.859622)
		(end 385.30784 -84.859622)
		(width 0.10795)
		(layer "F.Cu")
		(net "PWRGD_CPU0_G")
	)
	(segment
		(start 381.97155 -84.55914)
		(end 382.917954 -84.55914)
		(width 0.10795)
		(layer "F.Cu")
		(net "PWRGD_CPU0_G")
	)
	(segment
		(start 360.567224 -72.847454)
		(end 363.365288 -75.645518)
		(width 0.10795)
		(layer "F.Cu")
		(net "PWRGD_CPU0_G")
	)
	(segment
		(start 423.942002 -80.940656)
		(end 421.471852 -78.470506)
		(width 0.10795)
		(layer "F.Cu")
		(net "PWRGD_CPU0_G")
	)
	(segment
		(start 426.448982 -115.883182)
		(end 427.252638 -116.686838)
		(width 0.10795)
		(layer "F.Cu")
		(net "PWRGD_CPU0_G")
	)
	(segment
		(start 421.8178 -89.3064)
		(end 422.0718 -89.3064)
		(width 0.10795)
		(layer "F.Cu")
		(net "PWRGD_CPU0_G")
	)
	(segment
		(start 370.17071 -81.708244)
		(end 370.259356 -81.745074)
		(width 0.10795)
		(layer "F.Cu")
		(net "PWRGD_CPU0_G")
	)
	(segment
		(start 425.886372 -112.256316)
		(end 425.886372 -112.267492)
		(width 0.10795)
		(layer "F.Cu")
		(net "PWRGD_CPU0_G")
	)
	(segment
		(start 355.949504 -72.723248)
		(end 355.708966 -72.48271)
		(width 0.10795)
		(layer "F.Cu")
		(net "PWRGD_CPU0_G")
	)
	(segment
		(start 370.259356 -81.745074)
		(end 370.493544 -81.979262)
		(width 0.10795)
		(layer "F.Cu")
		(net "PWRGD_CPU0_G")
	)
	(segment
		(start 365.713772 -81.703164)
		(end 370.16563 -81.703164)
		(width 0.10795)
		(layer "F.Cu")
		(net "PWRGD_CPU0_G")
	)
	(segment
		(start 426.149262 -111.993426)
		(end 425.886372 -112.256316)
		(width 0.10795)
		(layer "F.Cu")
		(net "PWRGD_CPU0_G")
	)
	(segment
		(start 425.027852 -110.033562)
		(end 426.149262 -111.154972)
		(width 0.10795)
		(layer "F.Cu")
		(net "PWRGD_CPU0_G")
	)
	(segment
		(start 375.79046 -82.316574)
		(end 377.417838 -82.316574)
		(width 0.10795)
		(layer "F.Cu")
		(net "PWRGD_CPU0_G")
	)
	(segment
		(start 355.708966 -72.48271)
		(end 355.708966 -71.90359)
		(width 0.10795)
		(layer "F.Cu")
		(net "PWRGD_CPU0_G")
	)
	(segment
		(start 423.942002 -87.436198)
		(end 423.942002 -80.940656)
		(width 0.10795)
		(layer "F.Cu")
		(net "PWRGD_CPU0_G")
	)
	(segment
		(start 425.886372 -112.267492)
		(end 425.86656 -112.287304)
		(width 0.10795)
		(layer "F.Cu")
		(net "PWRGD_CPU0_G")
	)
	(segment
		(start 385.440428 -84.727034)
		(end 388.223506 -84.727034)
		(width 0.10795)
		(layer "F.Cu")
		(net "PWRGD_CPU0_G")
	)
	(segment
		(start 418.310568 -78.785212)
		(end 417.010088 -80.085692)
		(width 0.10795)
		(layer "F.Cu")
		(net "PWRGD_CPU0_G")
	)
	(segment
		(start 357.811324 -72.847454)
		(end 360.567224 -72.847454)
		(width 0.10795)
		(layer "F.Cu")
		(net "PWRGD_CPU0_G")
	)
	(segment
		(start 467.0806 -126.6952)
		(end 467.8426 -126.6952)
		(width 0.10795)
		(layer "F.Cu")
		(net "PWRGD_CPU0_G")
	)
	(segment
		(start 374.775476 -82.546444)
		(end 375.56059 -82.546444)
		(width 0.10795)
		(layer "F.Cu")
		(net "PWRGD_CPU0_G")
	)
	(segment
		(start 378.963174 -83.86191)
		(end 381.27432 -83.86191)
		(width 0.10795)
		(layer "F.Cu")
		(net "PWRGD_CPU0_G")
	)
	(segment
		(start 392.0998 -81.4578)
		(end 393.1412 -80.4164)
		(width 0.10795)
		(layer "F.Cu")
		(net "PWRGD_CPU0_G")
	)
	(via
		(at 467.8426 -126.6952)
		(size 0.508)
		(drill 0.254)
		(layers "F.Cu" "B.Cu")
		(net "PWRGD_CPU0_G")
	)
	(via
		(at 355.327204 -71.521828)
		(size 0.508)
		(drill 0.254)
		(layers "F.Cu" "B.Cu")
		(net "PWRGD_CPU0_G")
	)
	(via
		(at 288.07664 -72.249538)
		(size 0.508)
		(drill 0.254)
		(layers "F.Cu" "B.Cu")
		(net "PWRGD_CPU0_G")
	)
	(via
		(at 393.446 -80.4164)
		(size 0.508)
		(drill 0.254)
		(layers "F.Cu" "B.Cu")
		(net "PWRGD_CPU0_G")
	)
	(via
		(at 421.8178 -89.3064)
		(size 0.762)
		(drill 0.381)
		(layers "F.Cu" "B.Cu")
		(net "PWRGD_CPU0_G")
	)
	(via
		(at 416.073844 -81.194656)
		(size 0.508)
		(drill 0.254)
		(layers "F.Cu" "B.Cu")
		(net "PWRGD_CPU0_G")
	)
	(via
		(at 283.26842 -73.470008)
		(size 0.508)
		(drill 0.254)
		(layers "F.Cu" "B.Cu")
		(net "PWRGD_CPU0_G")
	)
	(via
		(at 357.811324 -72.847454)
		(size 0.762)
		(drill 0.381)
		(layers "F.Cu" "B.Cu")
		(net "PWRGD_CPU0_G")
	)
	(via
		(at 429.880522 -123.763786)
		(size 0.508)
		(drill 0.254)
		(layers "F.Cu" "B.Cu")
		(net "PWRGD_CPU0_G")
	)
	(segment
		(start 360.867452 -58.414412)
		(end 360.462576 -58.819288)
		(width 0.10795)
		(layer "B.Cu")
		(net "PWRGD_CPU0_G")
	)
	(segment
		(start 361.502706 -56.690768)
		(end 360.867452 -57.326022)
		(width 0.10795)
		(layer "B.Cu")
		(net "PWRGD_CPU0_G")
	)
	(segment
		(start 367.223802 -53.399944)
		(end 367.223802 -53.710078)
		(width 0.10795)
		(layer "B.Cu")
		(net "PWRGD_CPU0_G")
	)
	(segment
		(start 360.462576 -64.642492)
		(end 355.327204 -69.777864)
		(width 0.10795)
		(layer "B.Cu")
		(net "PWRGD_CPU0_G")
	)
	(segment
		(start 369.8875 -51.91252)
		(end 368.711226 -51.91252)
		(width 0.10795)
		(layer "B.Cu")
		(net "PWRGD_CPU0_G")
	)
	(segment
		(start 368.711226 -51.91252)
		(end 367.223802 -53.399944)
		(width 0.10795)
		(layer "B.Cu")
		(net "PWRGD_CPU0_G")
	)
	(segment
		(start 360.867452 -57.326022)
		(end 360.867452 -58.414412)
		(width 0.10795)
		(layer "B.Cu")
		(net "PWRGD_CPU0_G")
	)
	(segment
		(start 361.739434 -56.690768)
		(end 361.502706 -56.690768)
		(width 0.10795)
		(layer "B.Cu")
		(net "PWRGD_CPU0_G")
	)
	(segment
		(start 362.698538 -55.731664)
		(end 361.739434 -56.690768)
		(width 0.10795)
		(layer "B.Cu")
		(net "PWRGD_CPU0_G")
	)
	(segment
		(start 355.327204 -69.777864)
		(end 355.327204 -71.521828)
		(width 0.10795)
		(layer "B.Cu")
		(net "PWRGD_CPU0_G")
	)
	(segment
		(start 360.462576 -58.819288)
		(end 360.462576 -64.642492)
		(width 0.10795)
		(layer "B.Cu")
		(net "PWRGD_CPU0_G")
	)
	(segment
		(start 365.202216 -55.731664)
		(end 362.698538 -55.731664)
		(width 0.10795)
		(layer "B.Cu")
		(net "PWRGD_CPU0_G")
	)
	(segment
		(start 367.223802 -53.710078)
		(end 365.202216 -55.731664)
		(width 0.10795)
		(layer "B.Cu")
		(net "PWRGD_CPU0_G")
	)
	(segment
		(start 434.124608 -124.472954)
		(end 430.23917 -124.472954)
		(width 0.089408)
		(layer "In2.Cu")
		(net "PWRGD_CPU0_G")
	)
	(segment
		(start 449.601844 -122.423936)
		(end 440.205622 -122.423936)
		(width 0.089408)
		(layer "In2.Cu")
		(net "PWRGD_CPU0_G")
	)
	(segment
		(start 435.542944 -123.054618)
		(end 434.124608 -124.472954)
		(width 0.089408)
		(layer "In2.Cu")
		(net "PWRGD_CPU0_G")
	)
	(segment
		(start 467.8426 -126.6952)
		(end 467.061296 -125.913896)
		(width 0.089408)
		(layer "In2.Cu")
		(net "PWRGD_CPU0_G")
	)
	(segment
		(start 459.982316 -125.843792)
		(end 455.925936 -125.843792)
		(width 0.089408)
		(layer "In2.Cu")
		(net "PWRGD_CPU0_G")
	)
	(segment
		(start 439.089038 -123.054618)
		(end 439.088784 -123.054872)
		(width 0.089408)
		(layer "In2.Cu")
		(net "PWRGD_CPU0_G")
	)
	(segment
		(start 438.930796 -123.054872)
		(end 438.930542 -123.054618)
		(width 0.089408)
		(layer "In2.Cu")
		(net "PWRGD_CPU0_G")
	)
	(segment
		(start 429.880522 -124.114306)
		(end 429.880522 -123.763786)
		(width 0.089408)
		(layer "In2.Cu")
		(net "PWRGD_CPU0_G")
	)
	(segment
		(start 439.088784 -123.054872)
		(end 438.930796 -123.054872)
		(width 0.089408)
		(layer "In2.Cu")
		(net "PWRGD_CPU0_G")
	)
	(segment
		(start 467.061296 -125.913896)
		(end 464.712304 -125.913896)
		(width 0.089408)
		(layer "In2.Cu")
		(net "PWRGD_CPU0_G")
	)
	(segment
		(start 438.930542 -123.054618)
		(end 435.542944 -123.054618)
		(width 0.089408)
		(layer "In2.Cu")
		(net "PWRGD_CPU0_G")
	)
	(segment
		(start 455.925936 -125.843792)
		(end 455.418444 -125.3363)
		(width 0.089408)
		(layer "In2.Cu")
		(net "PWRGD_CPU0_G")
	)
	(segment
		(start 440.205622 -122.423936)
		(end 439.57494 -123.054618)
		(width 0.089408)
		(layer "In2.Cu")
		(net "PWRGD_CPU0_G")
	)
	(segment
		(start 460.503524 -126.365)
		(end 459.982316 -125.843792)
		(width 0.089408)
		(layer "In2.Cu")
		(net "PWRGD_CPU0_G")
	)
	(segment
		(start 464.712304 -125.913896)
		(end 464.2612 -126.365)
		(width 0.089408)
		(layer "In2.Cu")
		(net "PWRGD_CPU0_G")
	)
	(segment
		(start 430.23917 -124.472954)
		(end 429.880522 -124.114306)
		(width 0.089408)
		(layer "In2.Cu")
		(net "PWRGD_CPU0_G")
	)
	(segment
		(start 439.57494 -123.054618)
		(end 439.089038 -123.054618)
		(width 0.089408)
		(layer "In2.Cu")
		(net "PWRGD_CPU0_G")
	)
	(segment
		(start 464.2612 -126.365)
		(end 460.503524 -126.365)
		(width 0.089408)
		(layer "In2.Cu")
		(net "PWRGD_CPU0_G")
	)
	(segment
		(start 455.418444 -125.3363)
		(end 452.514208 -125.3363)
		(width 0.089408)
		(layer "In2.Cu")
		(net "PWRGD_CPU0_G")
	)
	(segment
		(start 452.514208 -125.3363)
		(end 449.601844 -122.423936)
		(width 0.089408)
		(layer "In2.Cu")
		(net "PWRGD_CPU0_G")
	)
	(segment
		(start 405.958294 -79.578454)
		(end 402.665946 -79.578454)
		(width 0.089408)
		(layer "In4.Cu")
		(net "PWRGD_CPU0_G")
	)
	(segment
		(start 416.073844 -81.194656)
		(end 407.574496 -81.194656)
		(width 0.089408)
		(layer "In4.Cu")
		(net "PWRGD_CPU0_G")
	)
	(segment
		(start 394.910056 -80.4164)
		(end 393.446 -80.4164)
		(width 0.089408)
		(layer "In4.Cu")
		(net "PWRGD_CPU0_G")
	)
	(segment
		(start 395.531086 -81.03743)
		(end 394.910056 -80.4164)
		(width 0.089408)
		(layer "In4.Cu")
		(net "PWRGD_CPU0_G")
	)
	(segment
		(start 399.97634 -79.931006)
		(end 398.869916 -81.03743)
		(width 0.089408)
		(layer "In4.Cu")
		(net "PWRGD_CPU0_G")
	)
	(segment
		(start 402.313394 -79.931006)
		(end 399.97634 -79.931006)
		(width 0.089408)
		(layer "In4.Cu")
		(net "PWRGD_CPU0_G")
	)
	(segment
		(start 402.665946 -79.578454)
		(end 402.313394 -79.931006)
		(width 0.089408)
		(layer "In4.Cu")
		(net "PWRGD_CPU0_G")
	)
	(segment
		(start 407.574496 -81.194656)
		(end 405.958294 -79.578454)
		(width 0.089408)
		(layer "In4.Cu")
		(net "PWRGD_CPU0_G")
	)
	(segment
		(start 398.869916 -81.03743)
		(end 395.531086 -81.03743)
		(width 0.089408)
		(layer "In4.Cu")
		(net "PWRGD_CPU0_G")
	)
	(segment
		(start 337.116674 -66.987166)
		(end 331.931264 -72.172576)
		(width 0.089408)
		(layer "In11.Cu")
		(net "PWRGD_CPU0_G")
	)
	(segment
		(start 288.07664 -72.249538)
		(end 288.369756 -72.418448)
		(width 0.0889)
		(layer "In11.Cu")
		(net "PWRGD_CPU0_G")
	)
	(segment
		(start 289.81019 -71.754238)
		(end 289.793426 -71.754238)
		(width 0.089408)
		(layer "In11.Cu")
		(net "PWRGD_CPU0_G")
	)
	(segment
		(start 355.327204 -71.521828)
		(end 355.327204 -70.178422)
		(width 0.089408)
		(layer "In11.Cu")
		(net "PWRGD_CPU0_G")
	)
	(segment
		(start 302.695356 -71.354188)
		(end 302.664114 -71.354188)
		(width 0.089408)
		(layer "In11.Cu")
		(net "PWRGD_CPU0_G")
	)
	(segment
		(start 303.540922 -70.859142)
		(end 303.517554 -70.859142)
		(width 0.089408)
		(layer "In11.Cu")
		(net "PWRGD_CPU0_G")
	)
	(segment
		(start 297.527218 -71.354188)
		(end 297.495976 -71.354188)
		(width 0.089408)
		(layer "In11.Cu")
		(net "PWRGD_CPU0_G")
	)
	(segment
		(start 288.087816 -72.649588)
		(end 288.05505 -72.649588)
		(width 0.0889)
		(layer "In11.Cu")
		(net "PWRGD_CPU0_G")
	)
	(segment
		(start 285.34741 -72.8218)
		(end 284.89021 -73.279)
		(width 0.089408)
		(layer "In11.Cu")
		(net "PWRGD_CPU0_G")
	)
	(segment
		(start 283.857192 -73.470008)
		(end 283.26842 -73.470008)
		(width 0.089408)
		(layer "In11.Cu")
		(net "PWRGD_CPU0_G")
	)
	(segment
		(start 288.955226 -72.249284)
		(end 288.93516 -72.249284)
		(width 0.089408)
		(layer "In11.Cu")
		(net "PWRGD_CPU0_G")
	)
	(segment
		(start 290.672266 -71.258684)
		(end 290.640008 -71.258684)
		(width 0.089408)
		(layer "In11.Cu")
		(net "PWRGD_CPU0_G")
	)
	(segment
		(start 355.327204 -70.178422)
		(end 352.135948 -66.987166)
		(width 0.089408)
		(layer "In11.Cu")
		(net "PWRGD_CPU0_G")
	)
	(segment
		(start 292.798754 -71.011288)
		(end 292.7985 -71.011288)
		(width 0.089408)
		(layer "In11.Cu")
		(net "PWRGD_CPU0_G")
	)
	(segment
		(start 287.219136 -73.14438)
		(end 286.91078 -73.14438)
		(width 0.0889)
		(layer "In11.Cu")
		(net "PWRGD_CPU0_G")
	)
	(segment
		(start 306.472082 -70.598792)
		(end 306.451762 -70.563486)
		(width 0.089408)
		(layer "In11.Cu")
		(net "PWRGD_CPU0_G")
	)
	(segment
		(start 288.369756 -72.418448)
		(end 288.390838 -72.497188)
		(width 0.0889)
		(layer "In11.Cu")
		(net "PWRGD_CPU0_G")
	)
	(segment
		(start 284.0482 -73.279)
		(end 283.857192 -73.470008)
		(width 0.089408)
		(layer "In11.Cu")
		(net "PWRGD_CPU0_G")
	)
	(segment
		(start 297.008042 -71.05904)
		(end 297.005756 -71.05523)
		(width 0.089408)
		(layer "In11.Cu")
		(net "PWRGD_CPU0_G")
	)
	(segment
		(start 284.89021 -73.279)
		(end 284.0482 -73.279)
		(width 0.089408)
		(layer "In11.Cu")
		(net "PWRGD_CPU0_G")
	)
	(segment
		(start 307.57114 -70.853554)
		(end 306.950364 -70.853554)
		(width 0.089408)
		(layer "In11.Cu")
		(net "PWRGD_CPU0_G")
	)
	(segment
		(start 286.5882 -72.8218)
		(end 285.34741 -72.8218)
		(width 0.0889)
		(layer "In11.Cu")
		(net "PWRGD_CPU0_G")
	)
	(segment
		(start 308.890162 -72.172576)
		(end 307.57114 -70.853554)
		(width 0.089408)
		(layer "In11.Cu")
		(net "PWRGD_CPU0_G")
	)
	(segment
		(start 331.931264 -72.172576)
		(end 308.890162 -72.172576)
		(width 0.089408)
		(layer "In11.Cu")
		(net "PWRGD_CPU0_G")
	)
	(segment
		(start 288.93516 -72.249284)
		(end 288.07664 -72.249538)
		(width 0.089408)
		(layer "In11.Cu")
		(net "PWRGD_CPU0_G")
	)
	(segment
		(start 352.135948 -66.987166)
		(end 337.116674 -66.987166)
		(width 0.089408)
		(layer "In11.Cu")
		(net "PWRGD_CPU0_G")
	)
	(segment
		(start 286.91078 -73.14438)
		(end 286.5882 -72.8218)
		(width 0.0889)
		(layer "In11.Cu")
		(net "PWRGD_CPU0_G")
	)
	(segment
		(start 292.389306 -71.258684)
		(end 292.349174 -71.258684)
		(width 0.089408)
		(layer "In11.Cu")
		(net "PWRGD_CPU0_G")
	)
	(arc
		(start 292.349174 -71.258684)
		(mid 292.112773 -71.187589)
		(end 291.93998 -71.011288)
		(width 0.089408)
		(layer "In11.Cu")
		(net "PWRGD_CPU0_G")
	)
	(arc
		(start 291.08146 -71.011288)
		(mid 290.908665 -71.187585)
		(end 290.672266 -71.258684)
		(width 0.089408)
		(layer "In11.Cu")
		(net "PWRGD_CPU0_G")
	)
	(arc
		(start 297.005756 -71.05523)
		(mid 296.88433 -70.926962)
		(end 296.719498 -70.86346)
		(width 0.089408)
		(layer "In11.Cu")
		(net "PWRGD_CPU0_G")
	)
	(arc
		(start 301.300642 -71.55434)
		(mid 300.954186 -71.354122)
		(end 300.60773 -71.55434)
		(width 0.089408)
		(layer "In11.Cu")
		(net "PWRGD_CPU0_G")
	)
	(arc
		(start 294.940228 -70.763384)
		(mid 294.667503 -70.815156)
		(end 294.432736 -70.963282)
		(width 0.089408)
		(layer "In11.Cu")
		(net "PWRGD_CPU0_G")
	)
	(arc
		(start 293.702486 -71.000112)
		(mid 293.486004 -70.839876)
		(end 293.22776 -70.763384)
		(width 0.089408)
		(layer "In11.Cu")
		(net "PWRGD_CPU0_G")
	)
	(arc
		(start 291.93998 -71.011288)
		(mid 291.51072 -70.763363)
		(end 291.08146 -71.011288)
		(width 0.089408)
		(layer "In11.Cu")
		(net "PWRGD_CPU0_G")
	)
	(arc
		(start 304.04181 -70.563486)
		(mid 303.830242 -70.777175)
		(end 303.540922 -70.859142)
		(width 0.089408)
		(layer "In11.Cu")
		(net "PWRGD_CPU0_G")
	)
	(arc
		(start 299.583602 -71.55434)
		(mid 299.237146 -71.354122)
		(end 298.89069 -71.55434)
		(width 0.089408)
		(layer "In11.Cu")
		(net "PWRGD_CPU0_G")
	)
	(arc
		(start 288.390838 -72.497188)
		(mid 288.256276 -72.6071)
		(end 288.087816 -72.649588)
		(width 0.0889)
		(layer "In11.Cu")
		(net "PWRGD_CPU0_G")
	)
	(arc
		(start 296.649648 -70.859142)
		(mid 296.456545 -70.915661)
		(end 296.315384 -71.05904)
		(width 0.089408)
		(layer "In11.Cu")
		(net "PWRGD_CPU0_G")
	)
	(arc
		(start 295.354248 -70.988936)
		(mid 295.188549 -70.800399)
		(end 294.940228 -70.763384)
		(width 0.089408)
		(layer "In11.Cu")
		(net "PWRGD_CPU0_G")
	)
	(arc
		(start 304.734722 -70.563486)
		(mid 304.388266 -70.363395)
		(end 304.04181 -70.563486)
		(width 0.089408)
		(layer "In11.Cu")
		(net "PWRGD_CPU0_G")
	)
	(arc
		(start 289.36442 -72.001888)
		(mid 289.191625 -72.178185)
		(end 288.955226 -72.249284)
		(width 0.089408)
		(layer "In11.Cu")
		(net "PWRGD_CPU0_G")
	)
	(arc
		(start 296.315384 -71.05904)
		(mid 296.168598 -71.184132)
		(end 295.975786 -71.18858)
		(width 0.089408)
		(layer "In11.Cu")
		(net "PWRGD_CPU0_G")
	)
	(arc
		(start 290.22294 -71.506588)
		(mid 290.048651 -71.68389)
		(end 289.81019 -71.754238)
		(width 0.089408)
		(layer "In11.Cu")
		(net "PWRGD_CPU0_G")
	)
	(arc
		(start 303.18329 -71.05904)
		(mid 302.977253 -71.269318)
		(end 302.695356 -71.354188)
		(width 0.089408)
		(layer "In11.Cu")
		(net "PWRGD_CPU0_G")
	)
	(arc
		(start 290.640008 -71.258684)
		(mid 290.399051 -71.328089)
		(end 290.22294 -71.506588)
		(width 0.089408)
		(layer "In11.Cu")
		(net "PWRGD_CPU0_G")
	)
	(arc
		(start 297.495976 -71.354188)
		(mid 297.214074 -71.269325)
		(end 297.008042 -71.05904)
		(width 0.089408)
		(layer "In11.Cu")
		(net "PWRGD_CPU0_G")
	)
	(arc
		(start 295.782746 -71.16318)
		(mid 295.736054 -71.166681)
		(end 295.689782 -71.173848)
		(width 0.089408)
		(layer "In11.Cu")
		(net "PWRGD_CPU0_G")
	)
	(arc
		(start 287.56483 -72.944736)
		(mid 287.418747 -73.090912)
		(end 287.219136 -73.14438)
		(width 0.0889)
		(layer "In11.Cu")
		(net "PWRGD_CPU0_G")
	)
	(arc
		(start 296.719498 -70.86346)
		(mid 296.684663 -70.859845)
		(end 296.649648 -70.859142)
		(width 0.089408)
		(layer "In11.Cu")
		(net "PWRGD_CPU0_G")
	)
	(arc
		(start 294.432736 -70.963282)
		(mid 294.315272 -71.091338)
		(end 294.154606 -71.157592)
		(width 0.089408)
		(layer "In11.Cu")
		(net "PWRGD_CPU0_G")
	)
	(arc
		(start 298.89069 -71.55434)
		(mid 298.378626 -71.850099)
		(end 297.866562 -71.55434)
		(width 0.089408)
		(layer "In11.Cu")
		(net "PWRGD_CPU0_G")
	)
	(arc
		(start 302.664114 -71.354188)
		(mid 302.468082 -71.409572)
		(end 302.32477 -71.55434)
		(width 0.089408)
		(layer "In11.Cu")
		(net "PWRGD_CPU0_G")
	)
	(arc
		(start 294.154606 -71.157592)
		(mid 293.909389 -71.133812)
		(end 293.702486 -71.000112)
		(width 0.089408)
		(layer "In11.Cu")
		(net "PWRGD_CPU0_G")
	)
	(arc
		(start 297.866562 -71.55434)
		(mid 297.723251 -71.409569)
		(end 297.527218 -71.354188)
		(width 0.089408)
		(layer "In11.Cu")
		(net "PWRGD_CPU0_G")
	)
	(arc
		(start 289.793426 -71.754238)
		(mid 289.545762 -71.820604)
		(end 289.36442 -72.001888)
		(width 0.089408)
		(layer "In11.Cu")
		(net "PWRGD_CPU0_G")
	)
	(arc
		(start 295.975786 -71.18858)
		(mid 295.880322 -71.167859)
		(end 295.782746 -71.16318)
		(width 0.089408)
		(layer "In11.Cu")
		(net "PWRGD_CPU0_G")
	)
	(arc
		(start 305.75885 -70.563486)
		(mid 305.246786 -70.859245)
		(end 304.734722 -70.563486)
		(width 0.089408)
		(layer "In11.Cu")
		(net "PWRGD_CPU0_G")
	)
	(arc
		(start 288.05505 -72.649588)
		(mid 287.771833 -72.733869)
		(end 287.56483 -72.944736)
		(width 0.0889)
		(layer "In11.Cu")
		(net "PWRGD_CPU0_G")
	)
	(arc
		(start 293.22776 -70.763384)
		(mid 292.980058 -70.829879)
		(end 292.798754 -71.011288)
		(width 0.089408)
		(layer "In11.Cu")
		(net "PWRGD_CPU0_G")
	)
	(arc
		(start 306.451762 -70.563486)
		(mid 306.105306 -70.363395)
		(end 305.75885 -70.563486)
		(width 0.089408)
		(layer "In11.Cu")
		(net "PWRGD_CPU0_G")
	)
	(arc
		(start 303.517554 -70.859142)
		(mid 303.324451 -70.915661)
		(end 303.18329 -71.05904)
		(width 0.089408)
		(layer "In11.Cu")
		(net "PWRGD_CPU0_G")
	)
	(arc
		(start 302.32477 -71.55434)
		(mid 301.812706 -71.850099)
		(end 301.300642 -71.55434)
		(width 0.089408)
		(layer "In11.Cu")
		(net "PWRGD_CPU0_G")
	)
	(arc
		(start 292.7985 -71.011288)
		(mid 292.625705 -71.187585)
		(end 292.389306 -71.258684)
		(width 0.089408)
		(layer "In11.Cu")
		(net "PWRGD_CPU0_G")
	)
	(arc
		(start 306.950364 -70.853554)
		(mid 306.679388 -70.785911)
		(end 306.472082 -70.598792)
		(width 0.089408)
		(layer "In11.Cu")
		(net "PWRGD_CPU0_G")
	)
	(arc
		(start 295.689782 -71.173848)
		(mid 295.488422 -71.142374)
		(end 295.354248 -70.988936)
		(width 0.089408)
		(layer "In11.Cu")
		(net "PWRGD_CPU0_G")
	)
	(arc
		(start 300.60773 -71.55434)
		(mid 300.095666 -71.850099)
		(end 299.583602 -71.55434)
		(width 0.089408)
		(layer "In11.Cu")
		(net "PWRGD_CPU0_G")
	)
	(segment
		(start 95.298768 -131.91617)
		(end 94.299532 -132.915406)
		(width 0.508)
		(layer "F.Cu")
		(net "PVTT_KLM")
	)
	(segment
		(start 95.298768 -131.154424)
		(end 95.298768 -131.789424)
		(width 0.508)
		(layer "F.Cu")
		(net "PVTT_KLM")
	)
	(segment
		(start 94.299532 -132.915406)
		(end 94.299532 -133.0706)
		(width 0.508)
		(layer "F.Cu")
		(net "PVTT_KLM")
	)
	(segment
		(start 95.298768 -131.789424)
		(end 95.298768 -131.91617)
		(width 0.508)
		(layer "F.Cu")
		(net "PVTT_KLM")
	)
	(segment
		(start 96.89592 -157.3276)
		(end 96.89592 -157.8356)
		(width 0.254)
		(layer "F.Cu")
		(net "PVTT_KLM")
	)
	(segment
		(start 96.89592 -157.8356)
		(end 97.18802 -158.1277)
		(width 0.254)
		(layer "F.Cu")
		(net "PVTT_KLM")
	)
	(via
		(at 165.64356 -145.925794)
		(size 0.508)
		(drill 0.254)
		(layers "F.Cu" "B.Cu")
		(net "PVTT_KLM")
	)
	(via
		(at 165.0238 -146.558)
		(size 0.508)
		(drill 0.254)
		(layers "F.Cu" "B.Cu")
		(net "PVTT_KLM")
	)
	(via
		(at 94.25178 -126.6571)
		(size 0.6604)
		(drill 0.3302)
		(layers "F.Cu" "B.Cu")
		(net "PVTT_KLM")
	)
	(via
		(at 95.298768 -131.789424)
		(size 0.508)
		(drill 0.254)
		(layers "F.Cu" "B.Cu")
		(net "PVTT_KLM")
	)
	(via
		(at 167.695118 -146.490436)
		(size 0.508)
		(drill 0.254)
		(layers "F.Cu" "B.Cu")
		(net "PVTT_KLM")
	)
	(via
		(at 94.131384 -148.745956)
		(size 0.508)
		(drill 0.254)
		(layers "F.Cu" "B.Cu")
		(net "PVTT_KLM")
	)
	(via
		(at 165.64356 -146.560794)
		(size 0.508)
		(drill 0.254)
		(layers "F.Cu" "B.Cu")
		(net "PVTT_KLM")
	)
	(via
		(at 95.705168 -138.0998)
		(size 0.508)
		(drill 0.254)
		(layers "F.Cu" "B.Cu")
		(net "PVTT_KLM")
	)
	(via
		(at 94.268036 -155.563062)
		(size 0.508)
		(drill 0.254)
		(layers "F.Cu" "B.Cu")
		(net "PVTT_KLM")
	)
	(via
		(at 95.298768 -131.154424)
		(size 0.508)
		(drill 0.254)
		(layers "F.Cu" "B.Cu")
		(net "PVTT_KLM")
	)
	(via
		(at 165.0238 -145.8976)
		(size 0.508)
		(drill 0.254)
		(layers "F.Cu" "B.Cu")
		(net "PVTT_KLM")
	)
	(via
		(at 95.730568 -147.606258)
		(size 0.508)
		(drill 0.254)
		(layers "F.Cu" "B.Cu")
		(net "PVTT_KLM")
	)
	(via
		(at 96.1644 -153.9748)
		(size 0.508)
		(drill 0.254)
		(layers "F.Cu" "B.Cu")
		(net "PVTT_KLM")
	)
	(via
		(at 94.313248 -153.596086)
		(size 0.508)
		(drill 0.254)
		(layers "F.Cu" "B.Cu")
		(net "PVTT_KLM")
	)
	(via
		(at 94.147386 -150.797514)
		(size 0.508)
		(drill 0.254)
		(layers "F.Cu" "B.Cu")
		(net "PVTT_KLM")
	)
	(segment
		(start 166.66718 -145.97126)
		(end 167.175942 -145.97126)
		(width 0.254)
		(layer "B.Cu")
		(net "PVTT_KLM")
	)
	(segment
		(start 167.175942 -145.97126)
		(end 167.695118 -146.490436)
		(width 0.254)
		(layer "B.Cu")
		(net "PVTT_KLM")
	)
	(segment
		(start 95.335598 -21.304758)
		(end 95.335598 -21.939758)
		(width 0.254)
		(layer "F.Cu")
		(net "PVTT_GHJ")
	)
	(segment
		(start 94.299532 -20.023582)
		(end 94.299532 -20.141946)
		(width 0.508)
		(layer "F.Cu")
		(net "PVTT_GHJ")
	)
	(segment
		(start 94.299532 0.471932)
		(end 94.299532 2.4892)
		(width 0.508)
		(layer "F.Cu")
		(net "PVTT_GHJ")
	)
	(segment
		(start 95.335598 -21.178012)
		(end 95.335598 -21.304758)
		(width 0.508)
		(layer "F.Cu")
		(net "PVTT_GHJ")
	)
	(segment
		(start 97.787968 -20.7264)
		(end 97.254568 -21.2598)
		(width 0.508)
		(layer "F.Cu")
		(net "PVTT_GHJ")
	)
	(segment
		(start 94.299532 -20.141946)
		(end 95.335598 -21.178012)
		(width 0.508)
		(layer "F.Cu")
		(net "PVTT_GHJ")
	)
	(segment
		(start 96.6216 -16.0528)
		(end 96.746568 -16.0528)
		(width 0.508)
		(layer "F.Cu")
		(net "PVTT_GHJ")
	)
	(segment
		(start 94.299532 2.4892)
		(end 94.299532 3.778758)
		(width 0.508)
		(layer "F.Cu")
		(net "PVTT_GHJ")
	)
	(segment
		(start 95.992442 -15.423642)
		(end 96.6216 -16.0528)
		(width 0.508)
		(layer "F.Cu")
		(net "PVTT_GHJ")
	)
	(segment
		(start 94.299532 -15.423642)
		(end 95.992442 -15.423642)
		(width 0.508)
		(layer "F.Cu")
		(net "PVTT_GHJ")
	)
	(segment
		(start 97.254568 -22.733)
		(end 96.746568 -23.241)
		(width 0.508)
		(layer "F.Cu")
		(net "PVTT_GHJ")
	)
	(segment
		(start 97.254568 -21.2598)
		(end 97.254568 -22.733)
		(width 0.508)
		(layer "F.Cu")
		(net "PVTT_GHJ")
	)
	(via
		(at 95.192342 -5.034026)
		(size 0.508)
		(drill 0.254)
		(layers "F.Cu" "B.Cu")
		(net "PVTT_GHJ")
	)
	(via
		(at 96.76892 -15.29334)
		(size 0.508)
		(drill 0.254)
		(layers "F.Cu" "B.Cu")
		(net "PVTT_GHJ")
	)
	(via
		(at 94.91218 -4.46532)
		(size 0.508)
		(drill 0.254)
		(layers "F.Cu" "B.Cu")
		(net "PVTT_GHJ")
	)
	(via
		(at 95.6818 0.3302)
		(size 0.508)
		(drill 0.254)
		(layers "F.Cu" "B.Cu")
		(net "PVTT_GHJ")
	)
	(via
		(at 96.6724 -9.4996)
		(size 0.508)
		(drill 0.254)
		(layers "F.Cu" "B.Cu")
		(net "PVTT_GHJ")
	)
	(via
		(at 95.335598 -21.304758)
		(size 0.508)
		(drill 0.254)
		(layers "F.Cu" "B.Cu")
		(net "PVTT_GHJ")
	)
	(via
		(at 164.7317 -2.1717)
		(size 0.508)
		(drill 0.254)
		(layers "F.Cu" "B.Cu")
		(net "PVTT_GHJ")
	)
	(via
		(at 96.746568 -16.0528)
		(size 0.508)
		(drill 0.254)
		(layers "F.Cu" "B.Cu")
		(net "PVTT_GHJ")
	)
	(via
		(at 165.3794 -2.9718)
		(size 0.508)
		(drill 0.254)
		(layers "F.Cu" "B.Cu")
		(net "PVTT_GHJ")
	)
	(via
		(at 164.719 -2.9464)
		(size 0.508)
		(drill 0.254)
		(layers "F.Cu" "B.Cu")
		(net "PVTT_GHJ")
	)
	(via
		(at 94.299532 2.4892)
		(size 0.508)
		(drill 0.254)
		(layers "F.Cu" "B.Cu")
		(net "PVTT_GHJ")
	)
	(via
		(at 94.4118 -28.5242)
		(size 0.6604)
		(drill 0.3302)
		(layers "F.Cu" "B.Cu")
		(net "PVTT_GHJ")
	)
	(via
		(at 94.299532 0.471932)
		(size 0.508)
		(drill 0.254)
		(layers "F.Cu" "B.Cu")
		(net "PVTT_GHJ")
	)
	(via
		(at 97.787968 -20.7264)
		(size 0.508)
		(drill 0.254)
		(layers "F.Cu" "B.Cu")
		(net "PVTT_GHJ")
	)
	(via
		(at 95.335598 -21.939758)
		(size 0.508)
		(drill 0.254)
		(layers "F.Cu" "B.Cu")
		(net "PVTT_GHJ")
	)
	(via
		(at 165.3794 -2.1971)
		(size 0.508)
		(drill 0.254)
		(layers "F.Cu" "B.Cu")
		(net "PVTT_GHJ")
	)
	(segment
		(start 165.67404 -1.90246)
		(end 165.3794 -2.1971)
		(width 0.254)
		(layer "B.Cu")
		(net "PVTT_GHJ")
	)
	(segment
		(start 166.5097 -1.90246)
		(end 165.67404 -1.90246)
		(width 0.254)
		(layer "B.Cu")
		(net "PVTT_GHJ")
	)
	(segment
		(start 259.300472 -147.27174)
		(end 259.300472 -142.6718)
		(width 0.381)
		(layer "F.Cu")
		(net "PVTT_DEF")
	)
	(segment
		(start 259.299964 -133.0706)
		(end 259.300472 -133.0706)
		(width 0.508)
		(layer "F.Cu")
		(net "PVTT_DEF")
	)
	(segment
		(start 260.2992 -131.789424)
		(end 259.808218 -131.789424)
		(width 0.508)
		(layer "F.Cu")
		(net "PVTT_DEF")
	)
	(segment
		(start 259.299964 -132.297678)
		(end 259.299964 -133.0706)
		(width 0.508)
		(layer "F.Cu")
		(net "PVTT_DEF")
	)
	(segment
		(start 259.300472 -141.444472)
		(end 259.0292 -141.1732)
		(width 0.381)
		(layer "F.Cu")
		(net "PVTT_DEF")
	)
	(segment
		(start 259.808218 -131.789424)
		(end 259.299964 -132.297678)
		(width 0.508)
		(layer "F.Cu")
		(net "PVTT_DEF")
	)
	(segment
		(start 260.2992 -131.154424)
		(end 260.2992 -131.789424)
		(width 0.508)
		(layer "F.Cu")
		(net "PVTT_DEF")
	)
	(segment
		(start 259.300472 -142.6718)
		(end 259.300472 -141.444472)
		(width 0.381)
		(layer "F.Cu")
		(net "PVTT_DEF")
	)
	(via
		(at 181.890924 -154.6987)
		(size 0.508)
		(drill 0.254)
		(layers "F.Cu" "B.Cu")
		(net "PVTT_DEF")
	)
	(via
		(at 261.563358 -155.849574)
		(size 0.508)
		(drill 0.254)
		(layers "F.Cu" "B.Cu")
		(net "PVTT_DEF")
	)
	(via
		(at 260.2992 -131.789424)
		(size 0.508)
		(drill 0.254)
		(layers "F.Cu" "B.Cu")
		(net "PVTT_DEF")
	)
	(via
		(at 260.7056 -138.0998)
		(size 0.508)
		(drill 0.254)
		(layers "F.Cu" "B.Cu")
		(net "PVTT_DEF")
	)
	(via
		(at 259.1562 -150.7998)
		(size 0.508)
		(drill 0.254)
		(layers "F.Cu" "B.Cu")
		(net "PVTT_DEF")
	)
	(via
		(at 260.2992 -131.154424)
		(size 0.508)
		(drill 0.254)
		(layers "F.Cu" "B.Cu")
		(net "PVTT_DEF")
	)
	(via
		(at 182.273448 -152.032716)
		(size 0.508)
		(drill 0.254)
		(layers "F.Cu" "B.Cu")
		(net "PVTT_DEF")
	)
	(via
		(at 260.731 -147.574)
		(size 0.508)
		(drill 0.254)
		(layers "F.Cu" "B.Cu")
		(net "PVTT_DEF")
	)
	(via
		(at 180.874924 -154.0891)
		(size 0.508)
		(drill 0.254)
		(layers "F.Cu" "B.Cu")
		(net "PVTT_DEF")
	)
	(via
		(at 181.135528 -154.763724)
		(size 0.508)
		(drill 0.254)
		(layers "F.Cu" "B.Cu")
		(net "PVTT_DEF")
	)
	(via
		(at 180.874924 -153.4287)
		(size 0.508)
		(drill 0.254)
		(layers "F.Cu" "B.Cu")
		(net "PVTT_DEF")
	)
	(via
		(at 259.0292 -141.1732)
		(size 0.508)
		(drill 0.254)
		(layers "F.Cu" "B.Cu")
		(net "PVTT_DEF")
	)
	(via
		(at 259.2832 -155.6004)
		(size 0.508)
		(drill 0.254)
		(layers "F.Cu" "B.Cu")
		(net "PVTT_DEF")
	)
	(via
		(at 259.2578 -153.5684)
		(size 0.508)
		(drill 0.254)
		(layers "F.Cu" "B.Cu")
		(net "PVTT_DEF")
	)
	(segment
		(start 259.300472 -141.444472)
		(end 259.300472 -142.477236)
		(width 0.254)
		(layer "B.Cu")
		(net "PVTT_DEF")
	)
	(segment
		(start 259.0292 -141.1732)
		(end 259.300472 -141.444472)
		(width 0.254)
		(layer "B.Cu")
		(net "PVTT_DEF")
	)
	(segment
		(start 259.300472 0.47244)
		(end 259.299964 0.471932)
		(width 0.508)
		(layer "F.Cu")
		(net "PVTT_ABC")
	)
	(segment
		(start 260.33603 -21.178012)
		(end 259.299964 -20.141946)
		(width 0.508)
		(layer "F.Cu")
		(net "PVTT_ABC")
	)
	(segment
		(start 259.300472 3.778758)
		(end 259.300472 0.47244)
		(width 0.508)
		(layer "F.Cu")
		(net "PVTT_ABC")
	)
	(segment
		(start 259.299964 -20.141946)
		(end 259.299964 -20.023582)
		(width 0.508)
		(layer "F.Cu")
		(net "PVTT_ABC")
	)
	(segment
		(start 259.299964 -20.023582)
		(end 259.300472 -20.023582)
		(width 0.508)
		(layer "F.Cu")
		(net "PVTT_ABC")
	)
	(segment
		(start 260.33603 -21.304758)
		(end 260.33603 -21.178012)
		(width 0.508)
		(layer "F.Cu")
		(net "PVTT_ABC")
	)
	(segment
		(start 259.300472 -10.422382)
		(end 259.300472 -11.857228)
		(width 0.254)
		(layer "F.Cu")
		(net "PVTT_ABC")
	)
	(segment
		(start 260.33603 -21.939758)
		(end 260.33603 -21.304758)
		(width 0.254)
		(layer "F.Cu")
		(net "PVTT_ABC")
	)
	(segment
		(start 259.300472 -11.857228)
		(end 259.2451 -11.9126)
		(width 0.254)
		(layer "F.Cu")
		(net "PVTT_ABC")
	)
	(via
		(at 184.487058 3.723132)
		(size 0.508)
		(drill 0.254)
		(layers "F.Cu" "B.Cu")
		(net "PVTT_ABC")
	)
	(via
		(at 259.299964 0.471932)
		(size 0.508)
		(drill 0.254)
		(layers "F.Cu" "B.Cu")
		(net "PVTT_ABC")
	)
	(via
		(at 260.423914 -5.266436)
		(size 0.508)
		(drill 0.254)
		(layers "F.Cu" "B.Cu")
		(net "PVTT_ABC")
	)
	(via
		(at 220.948758 1.45669)
		(size 0.6604)
		(drill 0.3302)
		(layers "F.Cu" "B.Cu")
		(net "PVTT_ABC")
	)
	(via
		(at 259.2451 -11.9126)
		(size 0.508)
		(drill 0.254)
		(layers "F.Cu" "B.Cu")
		(net "PVTT_ABC")
	)
	(via
		(at 260.02996 -4.6101)
		(size 0.508)
		(drill 0.254)
		(layers "F.Cu" "B.Cu")
		(net "PVTT_ABC")
	)
	(via
		(at 260.33603 -21.304758)
		(size 0.508)
		(drill 0.254)
		(layers "F.Cu" "B.Cu")
		(net "PVTT_ABC")
	)
	(via
		(at 261.6962 -16.0528)
		(size 0.508)
		(drill 0.254)
		(layers "F.Cu" "B.Cu")
		(net "PVTT_ABC")
	)
	(via
		(at 185.093864 3.92811)
		(size 0.508)
		(drill 0.254)
		(layers "F.Cu" "B.Cu")
		(net "PVTT_ABC")
	)
	(via
		(at 260.52018 -1.68656)
		(size 0.508)
		(drill 0.254)
		(layers "F.Cu" "B.Cu")
		(net "PVTT_ABC")
	)
	(via
		(at 183.852058 3.723132)
		(size 0.508)
		(drill 0.254)
		(layers "F.Cu" "B.Cu")
		(net "PVTT_ABC")
	)
	(via
		(at 230.24338 1.46685)
		(size 0.6604)
		(drill 0.3302)
		(layers "F.Cu" "B.Cu")
		(net "PVTT_ABC")
	)
	(via
		(at 185.124598 3.241802)
		(size 0.508)
		(drill 0.254)
		(layers "F.Cu" "B.Cu")
		(net "PVTT_ABC")
	)
	(via
		(at 260.33603 -21.939758)
		(size 0.508)
		(drill 0.254)
		(layers "F.Cu" "B.Cu")
		(net "PVTT_ABC")
	)
	(segment
		(start 259.300472 -11.857228)
		(end 259.300472 -10.623042)
		(width 0.254)
		(layer "B.Cu")
		(net "PVTT_ABC")
	)
	(segment
		(start 259.2451 -11.9126)
		(end 259.300472 -11.857228)
		(width 0.254)
		(layer "B.Cu")
		(net "PVTT_ABC")
	)
	(segment
		(start 260.866382 -15.222982)
		(end 259.300472 -15.222982)
		(width 0.4064)
		(layer "B.Cu")
		(net "PVTT_ABC")
	)
	(segment
		(start 261.6962 -16.0528)
		(end 260.866382 -15.222982)
		(width 0.4064)
		(layer "B.Cu")
		(net "PVTT_ABC")
	)
	(segment
		(start 78.909672 -81.841086)
		(end 78.338172 -81.841086)
		(width 0.254)
		(layer "F.Cu")
		(net "PVSA_CPU1")
	)
	(segment
		(start 80.626712 -80.850486)
		(end 80.055212 -80.850486)
		(width 0.254)
		(layer "F.Cu")
		(net "PVSA_CPU1")
	)
	(segment
		(start 83.202272 -80.35544)
		(end 82.630772 -80.35544)
		(width 0.254)
		(layer "F.Cu")
		(net "PVSA_CPU1")
	)
	(segment
		(start 84.060792 -79.859886)
		(end 83.489292 -79.859886)
		(width 0.254)
		(layer "F.Cu")
		(net "PVSA_CPU1")
	)
	(segment
		(start 85.777832 -80.850486)
		(end 85.206332 -80.850486)
		(width 0.254)
		(layer "F.Cu")
		(net "PVSA_CPU1")
	)
	(segment
		(start 77.192886 -82.83194)
		(end 76.621386 -82.83194)
		(width 0.254)
		(layer "F.Cu")
		(net "PVSA_CPU1")
	)
	(segment
		(start 79.768192 -81.34604)
		(end 79.196692 -81.34604)
		(width 0.254)
		(layer "F.Cu")
		(net "PVSA_CPU1")
	)
	(segment
		(start 85.777832 -82.83194)
		(end 85.206332 -82.83194)
		(width 0.254)
		(layer "F.Cu")
		(net "PVSA_CPU1")
	)
	(segment
		(start 31.409386 -95.284544)
		(end 31.302706 -95.177864)
		(width 0.254)
		(layer "F.Cu")
		(net "PVSA_CPU1")
	)
	(segment
		(start 85.777832 -81.841086)
		(end 85.206332 -81.841086)
		(width 0.254)
		(layer "F.Cu")
		(net "PVSA_CPU1")
	)
	(segment
		(start 31.645098 -95.284544)
		(end 31.409386 -95.284544)
		(width 0.254)
		(layer "F.Cu")
		(net "PVSA_CPU1")
	)
	(segment
		(start 31.302706 -95.177864)
		(end 31.108142 -95.177864)
		(width 0.254)
		(layer "F.Cu")
		(net "PVSA_CPU1")
	)
	(segment
		(start 82.343752 -80.850486)
		(end 81.772252 -80.850486)
		(width 0.254)
		(layer "F.Cu")
		(net "PVSA_CPU1")
	)
	(segment
		(start 82.343752 -79.859886)
		(end 81.772252 -79.859886)
		(width 0.254)
		(layer "F.Cu")
		(net "PVSA_CPU1")
	)
	(segment
		(start 77.192886 -81.841086)
		(end 76.621386 -81.841086)
		(width 0.254)
		(layer "F.Cu")
		(net "PVSA_CPU1")
	)
	(segment
		(start 86.636352 -81.34604)
		(end 86.064852 -81.34604)
		(width 0.254)
		(layer "F.Cu")
		(net "PVSA_CPU1")
	)
	(segment
		(start 84.919312 -82.33664)
		(end 84.347812 -82.33664)
		(width 0.254)
		(layer "F.Cu")
		(net "PVSA_CPU1")
	)
	(segment
		(start 86.636352 -83.32724)
		(end 86.064852 -83.32724)
		(width 0.254)
		(layer "F.Cu")
		(net "PVSA_CPU1")
	)
	(segment
		(start 85.777832 -79.859886)
		(end 85.206332 -79.859886)
		(width 0.254)
		(layer "F.Cu")
		(net "PVSA_CPU1")
	)
	(segment
		(start 84.919312 -80.35544)
		(end 84.347812 -80.35544)
		(width 0.254)
		(layer "F.Cu")
		(net "PVSA_CPU1")
	)
	(segment
		(start 84.919312 -81.34604)
		(end 84.347812 -81.34604)
		(width 0.254)
		(layer "F.Cu")
		(net "PVSA_CPU1")
	)
	(segment
		(start 84.060792 -80.850486)
		(end 83.489292 -80.850486)
		(width 0.254)
		(layer "F.Cu")
		(net "PVSA_CPU1")
	)
	(segment
		(start 84.060792 -81.841086)
		(end 83.489292 -81.841086)
		(width 0.254)
		(layer "F.Cu")
		(net "PVSA_CPU1")
	)
	(segment
		(start 78.051406 -81.34604)
		(end 77.479906 -81.34604)
		(width 0.254)
		(layer "F.Cu")
		(net "PVSA_CPU1")
	)
	(segment
		(start 86.636352 -82.33664)
		(end 86.064852 -82.33664)
		(width 0.254)
		(layer "F.Cu")
		(net "PVSA_CPU1")
	)
	(segment
		(start 81.485232 -80.35544)
		(end 80.913732 -80.35544)
		(width 0.254)
		(layer "F.Cu")
		(net "PVSA_CPU1")
	)
	(segment
		(start 83.202272 -81.34604)
		(end 82.630772 -81.34604)
		(width 0.254)
		(layer "F.Cu")
		(net "PVSA_CPU1")
	)
	(segment
		(start 78.051406 -82.33664)
		(end 77.479906 -82.33664)
		(width 0.254)
		(layer "F.Cu")
		(net "PVSA_CPU1")
	)
	(segment
		(start 84.919312 -83.32724)
		(end 84.347812 -83.32724)
		(width 0.254)
		(layer "F.Cu")
		(net "PVSA_CPU1")
	)
	(via
		(at 80.055212 -80.850486)
		(size 0.508)
		(drill 0.254)
		(layers "F.Cu" "B.Cu")
		(net "PVSA_CPU1")
	)
	(via
		(at 44.3865 -97.360232)
		(size 0.5588)
		(drill 0.3048)
		(layers "F.Cu" "B.Cu")
		(net "PVSA_CPU1")
	)
	(via
		(at 93.172788 -82.412586)
		(size 0.5588)
		(drill 0.3048)
		(layers "F.Cu" "B.Cu")
		(net "PVSA_CPU1")
	)
	(via
		(at 82.630772 -81.34604)
		(size 0.508)
		(drill 0.254)
		(layers "F.Cu" "B.Cu")
		(net "PVSA_CPU1")
	)
	(via
		(at 47.8536 -93.163898)
		(size 0.5588)
		(drill 0.3048)
		(layers "F.Cu" "B.Cu")
		(net "PVSA_CPU1")
	)
	(via
		(at 96.21139 -83.71332)
		(size 0.5588)
		(drill 0.3048)
		(layers "F.Cu" "B.Cu")
		(net "PVSA_CPU1")
	)
	(via
		(at 85.206332 -80.850486)
		(size 0.508)
		(drill 0.254)
		(layers "F.Cu" "B.Cu")
		(net "PVSA_CPU1")
	)
	(via
		(at 85.206332 -79.859886)
		(size 0.508)
		(drill 0.254)
		(layers "F.Cu" "B.Cu")
		(net "PVSA_CPU1")
	)
	(via
		(at 76.621386 -82.83194)
		(size 0.508)
		(drill 0.254)
		(layers "F.Cu" "B.Cu")
		(net "PVSA_CPU1")
	)
	(via
		(at 80.913732 -80.35544)
		(size 0.508)
		(drill 0.254)
		(layers "F.Cu" "B.Cu")
		(net "PVSA_CPU1")
	)
	(via
		(at 44.8056 -93.925898)
		(size 0.5588)
		(drill 0.3048)
		(layers "F.Cu" "B.Cu")
		(net "PVSA_CPU1")
	)
	(via
		(at 50.737516 -95.52686)
		(size 0.5588)
		(drill 0.3048)
		(layers "F.Cu" "B.Cu")
		(net "PVSA_CPU1")
	)
	(via
		(at 52.4764 -94.5896)
		(size 0.508)
		(drill 0.254)
		(layers "F.Cu" "B.Cu")
		(net "PVSA_CPU1")
	)
	(via
		(at 83.489292 -79.859886)
		(size 0.508)
		(drill 0.254)
		(layers "F.Cu" "B.Cu")
		(net "PVSA_CPU1")
	)
	(via
		(at 84.347812 -82.33664)
		(size 0.508)
		(drill 0.254)
		(layers "F.Cu" "B.Cu")
		(net "PVSA_CPU1")
	)
	(via
		(at 81.772252 -79.859886)
		(size 0.508)
		(drill 0.254)
		(layers "F.Cu" "B.Cu")
		(net "PVSA_CPU1")
	)
	(via
		(at 50.142394 -95.202248)
		(size 0.5588)
		(drill 0.3048)
		(layers "F.Cu" "B.Cu")
		(net "PVSA_CPU1")
	)
	(via
		(at 43.474132 -98.747072)
		(size 0.5588)
		(drill 0.3048)
		(layers "F.Cu" "B.Cu")
		(net "PVSA_CPU1")
	)
	(via
		(at 44.3865 -98.884232)
		(size 0.5588)
		(drill 0.3048)
		(layers "F.Cu" "B.Cu")
		(net "PVSA_CPU1")
	)
	(via
		(at 44.0436 -93.163898)
		(size 0.5588)
		(drill 0.3048)
		(layers "F.Cu" "B.Cu")
		(net "PVSA_CPU1")
	)
	(via
		(at 95.306642 -83.006692)
		(size 0.5588)
		(drill 0.3048)
		(layers "F.Cu" "B.Cu")
		(net "PVSA_CPU1")
	)
	(via
		(at 48.2854 -99.822)
		(size 0.5588)
		(drill 0.3048)
		(layers "F.Cu" "B.Cu")
		(net "PVSA_CPU1")
	)
	(via
		(at 86.064852 -81.34604)
		(size 0.508)
		(drill 0.254)
		(layers "F.Cu" "B.Cu")
		(net "PVSA_CPU1")
	)
	(via
		(at 84.347812 -83.32724)
		(size 0.508)
		(drill 0.254)
		(layers "F.Cu" "B.Cu")
		(net "PVSA_CPU1")
	)
	(via
		(at 43.474132 -97.985072)
		(size 0.5588)
		(drill 0.3048)
		(layers "F.Cu" "B.Cu")
		(net "PVSA_CPU1")
	)
	(via
		(at 45.5676 -93.925898)
		(size 0.5588)
		(drill 0.3048)
		(layers "F.Cu" "B.Cu")
		(net "PVSA_CPU1")
	)
	(via
		(at 85.206332 -81.841086)
		(size 0.508)
		(drill 0.254)
		(layers "F.Cu" "B.Cu")
		(net "PVSA_CPU1")
	)
	(via
		(at 46.3296 -93.163898)
		(size 0.5588)
		(drill 0.3048)
		(layers "F.Cu" "B.Cu")
		(net "PVSA_CPU1")
	)
	(via
		(at 94.587314 -82.993484)
		(size 0.5588)
		(drill 0.3048)
		(layers "F.Cu" "B.Cu")
		(net "PVSA_CPU1")
	)
	(via
		(at 46.3296 -93.925898)
		(size 0.5588)
		(drill 0.3048)
		(layers "F.Cu" "B.Cu")
		(net "PVSA_CPU1")
	)
	(via
		(at 81.772252 -80.850486)
		(size 0.508)
		(drill 0.254)
		(layers "F.Cu" "B.Cu")
		(net "PVSA_CPU1")
	)
	(via
		(at 45.5676 -93.163898)
		(size 0.5588)
		(drill 0.3048)
		(layers "F.Cu" "B.Cu")
		(net "PVSA_CPU1")
	)
	(via
		(at 50.7746 -94.8436)
		(size 0.5588)
		(drill 0.3048)
		(layers "F.Cu" "B.Cu")
		(net "PVSA_CPU1")
	)
	(via
		(at 84.347812 -81.34604)
		(size 0.508)
		(drill 0.254)
		(layers "F.Cu" "B.Cu")
		(net "PVSA_CPU1")
	)
	(via
		(at 44.8056 -93.163898)
		(size 0.5588)
		(drill 0.3048)
		(layers "F.Cu" "B.Cu")
		(net "PVSA_CPU1")
	)
	(via
		(at 83.489292 -81.841086)
		(size 0.508)
		(drill 0.254)
		(layers "F.Cu" "B.Cu")
		(net "PVSA_CPU1")
	)
	(via
		(at 47.0916 -93.163898)
		(size 0.5588)
		(drill 0.3048)
		(layers "F.Cu" "B.Cu")
		(net "PVSA_CPU1")
	)
	(via
		(at 79.196692 -81.34604)
		(size 0.508)
		(drill 0.254)
		(layers "F.Cu" "B.Cu")
		(net "PVSA_CPU1")
	)
	(via
		(at 77.479906 -81.34604)
		(size 0.508)
		(drill 0.254)
		(layers "F.Cu" "B.Cu")
		(net "PVSA_CPU1")
	)
	(via
		(at 86.064852 -82.33664)
		(size 0.508)
		(drill 0.254)
		(layers "F.Cu" "B.Cu")
		(net "PVSA_CPU1")
	)
	(via
		(at 95.985076 -83.001358)
		(size 0.5588)
		(drill 0.3048)
		(layers "F.Cu" "B.Cu")
		(net "PVSA_CPU1")
	)
	(via
		(at 47.0916 -93.925898)
		(size 0.5588)
		(drill 0.3048)
		(layers "F.Cu" "B.Cu")
		(net "PVSA_CPU1")
	)
	(via
		(at 43.474132 -97.223072)
		(size 0.5588)
		(drill 0.3048)
		(layers "F.Cu" "B.Cu")
		(net "PVSA_CPU1")
	)
	(via
		(at 47.5234 -100.076)
		(size 0.5588)
		(drill 0.3048)
		(layers "F.Cu" "B.Cu")
		(net "PVSA_CPU1")
	)
	(via
		(at 93.915992 -83.033108)
		(size 0.5588)
		(drill 0.3048)
		(layers "F.Cu" "B.Cu")
		(net "PVSA_CPU1")
	)
	(via
		(at 31.108142 -95.177864)
		(size 0.508)
		(drill 0.254)
		(layers "F.Cu" "B.Cu")
		(net "PVSA_CPU1")
	)
	(via
		(at 44.3865 -98.122232)
		(size 0.5588)
		(drill 0.3048)
		(layers "F.Cu" "B.Cu")
		(net "PVSA_CPU1")
	)
	(via
		(at 86.064852 -83.32724)
		(size 0.508)
		(drill 0.254)
		(layers "F.Cu" "B.Cu")
		(net "PVSA_CPU1")
	)
	(via
		(at 95.465392 -83.696048)
		(size 0.5588)
		(drill 0.3048)
		(layers "F.Cu" "B.Cu")
		(net "PVSA_CPU1")
	)
	(via
		(at 77.479906 -82.33664)
		(size 0.508)
		(drill 0.254)
		(layers "F.Cu" "B.Cu")
		(net "PVSA_CPU1")
	)
	(via
		(at 84.347812 -80.35544)
		(size 0.508)
		(drill 0.254)
		(layers "F.Cu" "B.Cu")
		(net "PVSA_CPU1")
	)
	(via
		(at 93.248734 -83.072478)
		(size 0.5588)
		(drill 0.3048)
		(layers "F.Cu" "B.Cu")
		(net "PVSA_CPU1")
	)
	(via
		(at 44.0436 -93.925898)
		(size 0.5588)
		(drill 0.3048)
		(layers "F.Cu" "B.Cu")
		(net "PVSA_CPU1")
	)
	(via
		(at 85.206332 -82.83194)
		(size 0.508)
		(drill 0.254)
		(layers "F.Cu" "B.Cu")
		(net "PVSA_CPU1")
	)
	(via
		(at 50.7746 -94.0816)
		(size 0.5588)
		(drill 0.3048)
		(layers "F.Cu" "B.Cu")
		(net "PVSA_CPU1")
	)
	(via
		(at 82.630772 -80.35544)
		(size 0.508)
		(drill 0.254)
		(layers "F.Cu" "B.Cu")
		(net "PVSA_CPU1")
	)
	(via
		(at 47.8536 -93.925898)
		(size 0.5588)
		(drill 0.3048)
		(layers "F.Cu" "B.Cu")
		(net "PVSA_CPU1")
	)
	(via
		(at 83.489292 -80.850486)
		(size 0.508)
		(drill 0.254)
		(layers "F.Cu" "B.Cu")
		(net "PVSA_CPU1")
	)
	(via
		(at 76.621386 -81.841086)
		(size 0.508)
		(drill 0.254)
		(layers "F.Cu" "B.Cu")
		(net "PVSA_CPU1")
	)
	(via
		(at 78.338172 -81.841086)
		(size 0.508)
		(drill 0.254)
		(layers "F.Cu" "B.Cu")
		(net "PVSA_CPU1")
	)
	(segment
		(start 44.549314 -101.738684)
		(end 42.886122 -101.738684)
		(width 0.254)
		(layer "B.Cu")
		(net "PVSA_CPU1")
	)
	(segment
		(start 42.886122 -101.738684)
		(end 41.825418 -102.799388)
		(width 0.254)
		(layer "B.Cu")
		(net "PVSA_CPU1")
	)
	(segment
		(start 84.347812 -83.32724)
		(end 84.347812 -82.33664)
		(width 0.508)
		(layer "B.Cu")
		(net "PVSA_CPU1")
	)
	(segment
		(start 41.825418 -102.799388)
		(end 41.825418 -103.482648)
		(width 0.254)
		(layer "B.Cu")
		(net "PVSA_CPU1")
	)
	(segment
		(start 45.611796 -100.676202)
		(end 44.549314 -101.738684)
		(width 0.254)
		(layer "B.Cu")
		(net "PVSA_CPU1")
	)
	(segment
		(start 44.3865 -99.172776)
		(end 41.730676 -101.8286)
		(width 0.508)
		(layer "In9.Cu")
		(net "PVSA_CPU1")
	)
	(segment
		(start 33.91662 -100.36302)
		(end 33.91662 -96.025208)
		(width 0.508)
		(layer "In9.Cu")
		(net "PVSA_CPU1")
	)
	(segment
		(start 37.1856 -103.3272)
		(end 33.782 -103.3272)
		(width 0.508)
		(layer "In9.Cu")
		(net "PVSA_CPU1")
	)
	(segment
		(start 31.447486 -95.517208)
		(end 31.108142 -95.177864)
		(width 0.508)
		(layer "In9.Cu")
		(net "PVSA_CPU1")
	)
	(segment
		(start 32.98952 -102.53472)
		(end 32.98952 -101.29012)
		(width 0.508)
		(layer "In9.Cu")
		(net "PVSA_CPU1")
	)
	(segment
		(start 44.3865 -98.884232)
		(end 44.3865 -99.172776)
		(width 0.508)
		(layer "In9.Cu")
		(net "PVSA_CPU1")
	)
	(segment
		(start 33.91662 -96.025208)
		(end 33.40862 -95.517208)
		(width 0.508)
		(layer "In9.Cu")
		(net "PVSA_CPU1")
	)
	(segment
		(start 33.782 -103.3272)
		(end 32.98952 -102.53472)
		(width 0.508)
		(layer "In9.Cu")
		(net "PVSA_CPU1")
	)
	(segment
		(start 41.730676 -101.8286)
		(end 38.6842 -101.8286)
		(width 0.508)
		(layer "In9.Cu")
		(net "PVSA_CPU1")
	)
	(segment
		(start 32.98952 -101.29012)
		(end 33.91662 -100.36302)
		(width 0.508)
		(layer "In9.Cu")
		(net "PVSA_CPU1")
	)
	(segment
		(start 38.6842 -101.8286)
		(end 37.1856 -103.3272)
		(width 0.508)
		(layer "In9.Cu")
		(net "PVSA_CPU1")
	)
	(segment
		(start 33.40862 -95.517208)
		(end 31.447486 -95.517208)
		(width 0.508)
		(layer "In9.Cu")
		(net "PVSA_CPU1")
	)
	(segment
		(start 249.061224 -81.841086)
		(end 248.489724 -81.841086)
		(width 0.254)
		(layer "F.Cu")
		(net "PVSA_CPU0")
	)
	(segment
		(start 196.210174 -95.0976)
		(end 195.9356 -95.0976)
		(width 0.254)
		(layer "F.Cu")
		(net "PVSA_CPU0")
	)
	(segment
		(start 242.193318 -81.841086)
		(end 241.621818 -81.841086)
		(width 0.254)
		(layer "F.Cu")
		(net "PVSA_CPU0")
	)
	(segment
		(start 250.778264 -80.850486)
		(end 250.206764 -80.850486)
		(width 0.254)
		(layer "F.Cu")
		(net "PVSA_CPU0")
	)
	(segment
		(start 249.061224 -79.859886)
		(end 248.489724 -79.859886)
		(width 0.254)
		(layer "F.Cu")
		(net "PVSA_CPU0")
	)
	(segment
		(start 249.919744 -82.33664)
		(end 249.348244 -82.33664)
		(width 0.254)
		(layer "F.Cu")
		(net "PVSA_CPU0")
	)
	(segment
		(start 243.051838 -81.34604)
		(end 242.480338 -81.34604)
		(width 0.254)
		(layer "F.Cu")
		(net "PVSA_CPU0")
	)
	(segment
		(start 248.202704 -81.34604)
		(end 247.631204 -81.34604)
		(width 0.254)
		(layer "F.Cu")
		(net "PVSA_CPU0")
	)
	(segment
		(start 249.919744 -81.34604)
		(end 249.348244 -81.34604)
		(width 0.254)
		(layer "F.Cu")
		(net "PVSA_CPU0")
	)
	(segment
		(start 249.919744 -80.35544)
		(end 249.348244 -80.35544)
		(width 0.254)
		(layer "F.Cu")
		(net "PVSA_CPU0")
	)
	(segment
		(start 251.636784 -81.34604)
		(end 251.065284 -81.34604)
		(width 0.254)
		(layer "F.Cu")
		(net "PVSA_CPU0")
	)
	(segment
		(start 243.910104 -81.841086)
		(end 243.338604 -81.841086)
		(width 0.254)
		(layer "F.Cu")
		(net "PVSA_CPU0")
	)
	(segment
		(start 243.051838 -82.33664)
		(end 242.480338 -82.33664)
		(width 0.254)
		(layer "F.Cu")
		(net "PVSA_CPU0")
	)
	(segment
		(start 196.63283 -95.284544)
		(end 196.397118 -95.284544)
		(width 0.254)
		(layer "F.Cu")
		(net "PVSA_CPU0")
	)
	(segment
		(start 250.778264 -79.859886)
		(end 250.206764 -79.859886)
		(width 0.254)
		(layer "F.Cu")
		(net "PVSA_CPU0")
	)
	(segment
		(start 247.344184 -80.850486)
		(end 246.772684 -80.850486)
		(width 0.254)
		(layer "F.Cu")
		(net "PVSA_CPU0")
	)
	(segment
		(start 250.778264 -81.841086)
		(end 250.206764 -81.841086)
		(width 0.254)
		(layer "F.Cu")
		(net "PVSA_CPU0")
	)
	(segment
		(start 244.768624 -81.34604)
		(end 244.197124 -81.34604)
		(width 0.254)
		(layer "F.Cu")
		(net "PVSA_CPU0")
	)
	(segment
		(start 249.919744 -83.32724)
		(end 249.348244 -83.32724)
		(width 0.254)
		(layer "F.Cu")
		(net "PVSA_CPU0")
	)
	(segment
		(start 251.636784 -82.33664)
		(end 251.065284 -82.33664)
		(width 0.254)
		(layer "F.Cu")
		(net "PVSA_CPU0")
	)
	(segment
		(start 245.627144 -80.850486)
		(end 245.055644 -80.850486)
		(width 0.254)
		(layer "F.Cu")
		(net "PVSA_CPU0")
	)
	(segment
		(start 250.778264 -82.83194)
		(end 250.206764 -82.83194)
		(width 0.254)
		(layer "F.Cu")
		(net "PVSA_CPU0")
	)
	(segment
		(start 246.485664 -80.35544)
		(end 245.914164 -80.35544)
		(width 0.254)
		(layer "F.Cu")
		(net "PVSA_CPU0")
	)
	(segment
		(start 247.344184 -79.859886)
		(end 246.772684 -79.859886)
		(width 0.254)
		(layer "F.Cu")
		(net "PVSA_CPU0")
	)
	(segment
		(start 249.061224 -80.850486)
		(end 248.489724 -80.850486)
		(width 0.254)
		(layer "F.Cu")
		(net "PVSA_CPU0")
	)
	(segment
		(start 242.193318 -82.83194)
		(end 241.621818 -82.83194)
		(width 0.254)
		(layer "F.Cu")
		(net "PVSA_CPU0")
	)
	(segment
		(start 196.397118 -95.284544)
		(end 196.210174 -95.0976)
		(width 0.254)
		(layer "F.Cu")
		(net "PVSA_CPU0")
	)
	(segment
		(start 251.636784 -83.32724)
		(end 251.065284 -83.32724)
		(width 0.254)
		(layer "F.Cu")
		(net "PVSA_CPU0")
	)
	(segment
		(start 248.202704 -80.35544)
		(end 247.631204 -80.35544)
		(width 0.254)
		(layer "F.Cu")
		(net "PVSA_CPU0")
	)
	(via
		(at 212.003132 -93.843602)
		(size 0.5588)
		(drill 0.3048)
		(layers "F.Cu" "B.Cu")
		(net "PVSA_CPU0")
	)
	(via
		(at 247.631204 -80.35544)
		(size 0.508)
		(drill 0.254)
		(layers "F.Cu" "B.Cu")
		(net "PVSA_CPU0")
	)
	(via
		(at 208.701132 -93.843602)
		(size 0.5588)
		(drill 0.3048)
		(layers "F.Cu" "B.Cu")
		(net "PVSA_CPU0")
	)
	(via
		(at 209.361532 -93.843602)
		(size 0.5588)
		(drill 0.3048)
		(layers "F.Cu" "B.Cu")
		(net "PVSA_CPU0")
	)
	(via
		(at 242.480338 -81.34604)
		(size 0.508)
		(drill 0.254)
		(layers "F.Cu" "B.Cu")
		(net "PVSA_CPU0")
	)
	(via
		(at 249.348244 -81.34604)
		(size 0.508)
		(drill 0.254)
		(layers "F.Cu" "B.Cu")
		(net "PVSA_CPU0")
	)
	(via
		(at 213.995 -100.6856)
		(size 0.6604)
		(drill 0.3302)
		(layers "F.Cu" "B.Cu")
		(net "PVSA_CPU0")
	)
	(via
		(at 209.858864 -97.309432)
		(size 0.5588)
		(drill 0.3048)
		(layers "F.Cu" "B.Cu")
		(net "PVSA_CPU0")
	)
	(via
		(at 248.489724 -80.850486)
		(size 0.508)
		(drill 0.254)
		(layers "F.Cu" "B.Cu")
		(net "PVSA_CPU0")
	)
	(via
		(at 249.348244 -83.32724)
		(size 0.508)
		(drill 0.254)
		(layers "F.Cu" "B.Cu")
		(net "PVSA_CPU0")
	)
	(via
		(at 243.338604 -81.841086)
		(size 0.508)
		(drill 0.254)
		(layers "F.Cu" "B.Cu")
		(net "PVSA_CPU0")
	)
	(via
		(at 215.546432 -95.521272)
		(size 0.5588)
		(drill 0.3048)
		(layers "F.Cu" "B.Cu")
		(net "PVSA_CPU0")
	)
	(via
		(at 258.417822 -82.95132)
		(size 0.508)
		(drill 0.254)
		(layers "F.Cu" "B.Cu")
		(net "PVSA_CPU0")
	)
	(via
		(at 250.206764 -79.859886)
		(size 0.508)
		(drill 0.254)
		(layers "F.Cu" "B.Cu")
		(net "PVSA_CPU0")
	)
	(via
		(at 251.065284 -83.32724)
		(size 0.508)
		(drill 0.254)
		(layers "F.Cu" "B.Cu")
		(net "PVSA_CPU0")
	)
	(via
		(at 216.206832 -96.181672)
		(size 0.5588)
		(drill 0.3048)
		(layers "F.Cu" "B.Cu")
		(net "PVSA_CPU0")
	)
	(via
		(at 246.772684 -79.859886)
		(size 0.508)
		(drill 0.254)
		(layers "F.Cu" "B.Cu")
		(net "PVSA_CPU0")
	)
	(via
		(at 211.342732 -93.843602)
		(size 0.5588)
		(drill 0.3048)
		(layers "F.Cu" "B.Cu")
		(net "PVSA_CPU0")
	)
	(via
		(at 212.003132 -93.183202)
		(size 0.5588)
		(drill 0.3048)
		(layers "F.Cu" "B.Cu")
		(net "PVSA_CPU0")
	)
	(via
		(at 241.621818 -82.83194)
		(size 0.508)
		(drill 0.254)
		(layers "F.Cu" "B.Cu")
		(net "PVSA_CPU0")
	)
	(via
		(at 216.338658 -94.792038)
		(size 0.5588)
		(drill 0.3048)
		(layers "F.Cu" "B.Cu")
		(net "PVSA_CPU0")
	)
	(via
		(at 209.097372 -97.2693)
		(size 0.5588)
		(drill 0.3048)
		(layers "F.Cu" "B.Cu")
		(net "PVSA_CPU0")
	)
	(via
		(at 248.489724 -81.841086)
		(size 0.508)
		(drill 0.254)
		(layers "F.Cu" "B.Cu")
		(net "PVSA_CPU0")
	)
	(via
		(at 246.772684 -80.850486)
		(size 0.508)
		(drill 0.254)
		(layers "F.Cu" "B.Cu")
		(net "PVSA_CPU0")
	)
	(via
		(at 249.348244 -80.35544)
		(size 0.508)
		(drill 0.254)
		(layers "F.Cu" "B.Cu")
		(net "PVSA_CPU0")
	)
	(via
		(at 214.886032 -95.521272)
		(size 0.5588)
		(drill 0.3048)
		(layers "F.Cu" "B.Cu")
		(net "PVSA_CPU0")
	)
	(via
		(at 210.682332 -93.183202)
		(size 0.5588)
		(drill 0.3048)
		(layers "F.Cu" "B.Cu")
		(net "PVSA_CPU0")
	)
	(via
		(at 248.489724 -79.859886)
		(size 0.508)
		(drill 0.254)
		(layers "F.Cu" "B.Cu")
		(net "PVSA_CPU0")
	)
	(via
		(at 216.206832 -95.521272)
		(size 0.5588)
		(drill 0.3048)
		(layers "F.Cu" "B.Cu")
		(net "PVSA_CPU0")
	)
	(via
		(at 215.546432 -96.181672)
		(size 0.5588)
		(drill 0.3048)
		(layers "F.Cu" "B.Cu")
		(net "PVSA_CPU0")
	)
	(via
		(at 195.9356 -95.0976)
		(size 0.508)
		(drill 0.254)
		(layers "F.Cu" "B.Cu")
		(net "PVSA_CPU0")
	)
	(via
		(at 212.690202 -93.174566)
		(size 0.5588)
		(drill 0.3048)
		(layers "F.Cu" "B.Cu")
		(net "PVSA_CPU0")
	)
	(via
		(at 249.348244 -82.33664)
		(size 0.508)
		(drill 0.254)
		(layers "F.Cu" "B.Cu")
		(net "PVSA_CPU0")
	)
	(via
		(at 259.052822 -82.95132)
		(size 0.508)
		(drill 0.254)
		(layers "F.Cu" "B.Cu")
		(net "PVSA_CPU0")
	)
	(via
		(at 250.206764 -82.83194)
		(size 0.508)
		(drill 0.254)
		(layers "F.Cu" "B.Cu")
		(net "PVSA_CPU0")
	)
	(via
		(at 216.26322 -93.336872)
		(size 0.508)
		(drill 0.254)
		(layers "F.Cu" "B.Cu")
		(net "PVSA_CPU0")
	)
	(via
		(at 261.211822 -83.71332)
		(size 0.508)
		(drill 0.254)
		(layers "F.Cu" "B.Cu")
		(net "PVSA_CPU0")
	)
	(via
		(at 214.886032 -96.181672)
		(size 0.5588)
		(drill 0.3048)
		(layers "F.Cu" "B.Cu")
		(net "PVSA_CPU0")
	)
	(via
		(at 260.322822 -82.95132)
		(size 0.508)
		(drill 0.254)
		(layers "F.Cu" "B.Cu")
		(net "PVSA_CPU0")
	)
	(via
		(at 260.54177 -83.553554)
		(size 0.508)
		(drill 0.254)
		(layers "F.Cu" "B.Cu")
		(net "PVSA_CPU0")
	)
	(via
		(at 209.828638 -98.024442)
		(size 0.5588)
		(drill 0.3048)
		(layers "F.Cu" "B.Cu")
		(net "PVSA_CPU0")
	)
	(via
		(at 259.687822 -82.95132)
		(size 0.508)
		(drill 0.254)
		(layers "F.Cu" "B.Cu")
		(net "PVSA_CPU0")
	)
	(via
		(at 241.621818 -81.841086)
		(size 0.508)
		(drill 0.254)
		(layers "F.Cu" "B.Cu")
		(net "PVSA_CPU0")
	)
	(via
		(at 209.361532 -93.183202)
		(size 0.5588)
		(drill 0.3048)
		(layers "F.Cu" "B.Cu")
		(net "PVSA_CPU0")
	)
	(via
		(at 245.914164 -80.35544)
		(size 0.508)
		(drill 0.254)
		(layers "F.Cu" "B.Cu")
		(net "PVSA_CPU0")
	)
	(via
		(at 260.957822 -82.95132)
		(size 0.508)
		(drill 0.254)
		(layers "F.Cu" "B.Cu")
		(net "PVSA_CPU0")
	)
	(via
		(at 251.065284 -82.33664)
		(size 0.508)
		(drill 0.254)
		(layers "F.Cu" "B.Cu")
		(net "PVSA_CPU0")
	)
	(via
		(at 210.682332 -93.843602)
		(size 0.5588)
		(drill 0.3048)
		(layers "F.Cu" "B.Cu")
		(net "PVSA_CPU0")
	)
	(via
		(at 215.628728 -94.807278)
		(size 0.5588)
		(drill 0.3048)
		(layers "F.Cu" "B.Cu")
		(net "PVSA_CPU0")
	)
	(via
		(at 247.631204 -81.34604)
		(size 0.508)
		(drill 0.254)
		(layers "F.Cu" "B.Cu")
		(net "PVSA_CPU0")
	)
	(via
		(at 210.021932 -93.183202)
		(size 0.5588)
		(drill 0.3048)
		(layers "F.Cu" "B.Cu")
		(net "PVSA_CPU0")
	)
	(via
		(at 208.701132 -93.183202)
		(size 0.5588)
		(drill 0.3048)
		(layers "F.Cu" "B.Cu")
		(net "PVSA_CPU0")
	)
	(via
		(at 211.342732 -93.183202)
		(size 0.5588)
		(drill 0.3048)
		(layers "F.Cu" "B.Cu")
		(net "PVSA_CPU0")
	)
	(via
		(at 242.480338 -82.33664)
		(size 0.508)
		(drill 0.254)
		(layers "F.Cu" "B.Cu")
		(net "PVSA_CPU0")
	)
	(via
		(at 244.197124 -81.34604)
		(size 0.508)
		(drill 0.254)
		(layers "F.Cu" "B.Cu")
		(net "PVSA_CPU0")
	)
	(via
		(at 251.065284 -81.34604)
		(size 0.508)
		(drill 0.254)
		(layers "F.Cu" "B.Cu")
		(net "PVSA_CPU0")
	)
	(via
		(at 210.021932 -93.843602)
		(size 0.5588)
		(drill 0.3048)
		(layers "F.Cu" "B.Cu")
		(net "PVSA_CPU0")
	)
	(via
		(at 250.206764 -80.850486)
		(size 0.508)
		(drill 0.254)
		(layers "F.Cu" "B.Cu")
		(net "PVSA_CPU0")
	)
	(via
		(at 208.335372 -97.2693)
		(size 0.5588)
		(drill 0.3048)
		(layers "F.Cu" "B.Cu")
		(net "PVSA_CPU0")
	)
	(via
		(at 250.206764 -81.841086)
		(size 0.508)
		(drill 0.254)
		(layers "F.Cu" "B.Cu")
		(net "PVSA_CPU0")
	)
	(via
		(at 245.055644 -80.850486)
		(size 0.508)
		(drill 0.254)
		(layers "F.Cu" "B.Cu")
		(net "PVSA_CPU0")
	)
	(via
		(at 208.335372 -98.0313)
		(size 0.5588)
		(drill 0.3048)
		(layers "F.Cu" "B.Cu")
		(net "PVSA_CPU0")
	)
	(via
		(at 258.165346 -82.373216)
		(size 0.508)
		(drill 0.254)
		(layers "F.Cu" "B.Cu")
		(net "PVSA_CPU0")
	)
	(via
		(at 209.097372 -98.0313)
		(size 0.5588)
		(drill 0.3048)
		(layers "F.Cu" "B.Cu")
		(net "PVSA_CPU0")
	)
	(segment
		(start 197.89394 -95.5548)
		(end 198.699628 -94.749112)
		(width 0.508)
		(layer "In11.Cu")
		(net "PVSA_CPU0")
	)
	(segment
		(start 195.9356 -95.0976)
		(end 196.3928 -95.5548)
		(width 0.508)
		(layer "In11.Cu")
		(net "PVSA_CPU0")
	)
	(segment
		(start 198.699628 -94.749112)
		(end 198.699628 -94.429072)
		(width 0.508)
		(layer "In11.Cu")
		(net "PVSA_CPU0")
	)
	(segment
		(start 199.737472 -93.391228)
		(end 201.855324 -93.391228)
		(width 0.508)
		(layer "In11.Cu")
		(net "PVSA_CPU0")
	)
	(segment
		(start 201.855324 -93.391228)
		(end 201.952352 -93.2942)
		(width 0.508)
		(layer "In11.Cu")
		(net "PVSA_CPU0")
	)
	(segment
		(start 196.3928 -95.5548)
		(end 197.89394 -95.5548)
		(width 0.508)
		(layer "In11.Cu")
		(net "PVSA_CPU0")
	)
	(segment
		(start 207.984852 -93.183202)
		(end 208.701132 -93.183202)
		(width 0.508)
		(layer "In11.Cu")
		(net "PVSA_CPU0")
	)
	(segment
		(start 198.699628 -94.429072)
		(end 199.737472 -93.391228)
		(width 0.508)
		(layer "In11.Cu")
		(net "PVSA_CPU0")
	)
	(segment
		(start 201.952352 -93.2942)
		(end 207.873854 -93.2942)
		(width 0.508)
		(layer "In11.Cu")
		(net "PVSA_CPU0")
	)
	(segment
		(start 207.873854 -93.2942)
		(end 207.984852 -93.183202)
		(width 0.508)
		(layer "In11.Cu")
		(net "PVSA_CPU0")
	)
	(segment
		(start 152.949402 -156.878782)
		(end 152.949402 -156.87294)
		(width 0.1651)
		(layer "F.Cu")
		(net "PVPP_KLM")
	)
	(segment
		(start 152.949402 -137.676382)
		(end 152.949402 -137.67054)
		(width 0.4064)
		(layer "F.Cu")
		(net "PVPP_KLM")
	)
	(segment
		(start 155.499562 -147.27174)
		(end 155.499562 -146.013678)
		(width 0.1651)
		(layer "F.Cu")
		(net "PVPP_KLM")
	)
	(segment
		(start 154.649424 -147.277582)
		(end 154.649424 -147.27174)
		(width 0.1651)
		(layer "F.Cu")
		(net "PVPP_KLM")
	)
	(segment
		(start 156.349446 -156.87294)
		(end 156.349446 -156.878782)
		(width 0.1651)
		(layer "F.Cu")
		(net "PVPP_KLM")
	)
	(segment
		(start 156.349446 -155.614878)
		(end 156.349446 -156.87294)
		(width 0.1651)
		(layer "F.Cu")
		(net "PVPP_KLM")
	)
	(segment
		(start 155.499562 -137.676382)
		(end 155.499562 -137.67054)
		(width 0.1651)
		(layer "F.Cu")
		(net "PVPP_KLM")
	)
	(segment
		(start 154.649424 -137.676382)
		(end 154.649424 -137.67054)
		(width 0.1651)
		(layer "F.Cu")
		(net "PVPP_KLM")
	)
	(segment
		(start 152.949402 -137.67054)
		(end 152.949402 -136.412478)
		(width 0.4064)
		(layer "F.Cu")
		(net "PVPP_KLM")
	)
	(segment
		(start 159.8422 -124.46)
		(end 159.87522 -124.49302)
		(width 0.4572)
		(layer "F.Cu")
		(net "PVPP_KLM")
	)
	(segment
		(start 159.87522 -124.49302)
		(end 159.87522 -125.1077)
		(width 0.4572)
		(layer "F.Cu")
		(net "PVPP_KLM")
	)
	(segment
		(start 160.5915 -123.7107)
		(end 159.8422 -124.46)
		(width 0.254)
		(layer "F.Cu")
		(net "PVPP_KLM")
	)
	(segment
		(start 156.349446 -137.676382)
		(end 156.349446 -137.67054)
		(width 0.1651)
		(layer "F.Cu")
		(net "PVPP_KLM")
	)
	(segment
		(start 155.499562 -156.878782)
		(end 155.499562 -156.87294)
		(width 0.1651)
		(layer "F.Cu")
		(net "PVPP_KLM")
	)
	(segment
		(start 156.349446 -147.277582)
		(end 156.349446 -147.27174)
		(width 0.1651)
		(layer "F.Cu")
		(net "PVPP_KLM")
	)
	(segment
		(start 154.649424 -156.87294)
		(end 154.649424 -155.614878)
		(width 0.1651)
		(layer "F.Cu")
		(net "PVPP_KLM")
	)
	(segment
		(start 154.649424 -134.340346)
		(end 154.649424 -133.076442)
		(width 0.1651)
		(layer "F.Cu")
		(net "PVPP_KLM")
	)
	(segment
		(start 155.499562 -133.0706)
		(end 155.499562 -134.340346)
		(width 0.1651)
		(layer "F.Cu")
		(net "PVPP_KLM")
	)
	(segment
		(start 154.649424 -137.67054)
		(end 154.649424 -136.412478)
		(width 0.1651)
		(layer "F.Cu")
		(net "PVPP_KLM")
	)
	(segment
		(start 152.949402 -147.27174)
		(end 152.949402 -146.013678)
		(width 0.1651)
		(layer "F.Cu")
		(net "PVPP_KLM")
	)
	(segment
		(start 154.649424 -147.27174)
		(end 154.649424 -146.013678)
		(width 0.1651)
		(layer "F.Cu")
		(net "PVPP_KLM")
	)
	(segment
		(start 113.849404 -156.87294)
		(end 113.849404 -155.732226)
		(width 0.4064)
		(layer "F.Cu")
		(net "PVPP_KLM")
	)
	(segment
		(start 155.499562 -137.67054)
		(end 155.499562 -136.412478)
		(width 0.1651)
		(layer "F.Cu")
		(net "PVPP_KLM")
	)
	(segment
		(start 155.499562 -147.277582)
		(end 155.499562 -147.27174)
		(width 0.1651)
		(layer "F.Cu")
		(net "PVPP_KLM")
	)
	(segment
		(start 161.27222 -123.7107)
		(end 160.5915 -123.7107)
		(width 0.4572)
		(layer "F.Cu")
		(net "PVPP_KLM")
	)
	(segment
		(start 152.949402 -147.277582)
		(end 152.949402 -147.27174)
		(width 0.1651)
		(layer "F.Cu")
		(net "PVPP_KLM")
	)
	(segment
		(start 156.349446 -147.27174)
		(end 156.349446 -146.013678)
		(width 0.1651)
		(layer "F.Cu")
		(net "PVPP_KLM")
	)
	(segment
		(start 152.949402 -156.87294)
		(end 152.949402 -155.614878)
		(width 0.1651)
		(layer "F.Cu")
		(net "PVPP_KLM")
	)
	(segment
		(start 113.849404 -155.732226)
		(end 113.732564 -155.615386)
		(width 0.4064)
		(layer "F.Cu")
		(net "PVPP_KLM")
	)
	(segment
		(start 154.649424 -156.878782)
		(end 154.649424 -156.87294)
		(width 0.1651)
		(layer "F.Cu")
		(net "PVPP_KLM")
	)
	(segment
		(start 155.499562 -156.87294)
		(end 155.499562 -155.614878)
		(width 0.1651)
		(layer "F.Cu")
		(net "PVPP_KLM")
	)
	(segment
		(start 156.349446 -137.67054)
		(end 156.349446 -136.412478)
		(width 0.1651)
		(layer "F.Cu")
		(net "PVPP_KLM")
	)
	(via
		(at 156.349446 -146.013678)
		(size 0.508)
		(drill 0.254)
		(layers "F.Cu" "B.Cu")
		(net "PVPP_KLM")
	)
	(via
		(at 155.499562 -129.579878)
		(size 0.508)
		(drill 0.254)
		(layers "F.Cu" "B.Cu")
		(net "PVPP_KLM")
	)
	(via
		(at 154.649424 -150.774146)
		(size 0.508)
		(drill 0.254)
		(layers "F.Cu" "B.Cu")
		(net "PVPP_KLM")
	)
	(via
		(at 154.649424 -139.181078)
		(size 0.508)
		(drill 0.254)
		(layers "F.Cu" "B.Cu")
		(net "PVPP_KLM")
	)
	(via
		(at 152.099518 -141.187678)
		(size 0.508)
		(drill 0.254)
		(layers "F.Cu" "B.Cu")
		(net "PVPP_KLM")
	)
	(via
		(at 167.6908 -140.335)
		(size 0.508)
		(drill 0.254)
		(layers "F.Cu" "B.Cu")
		(net "PVPP_KLM")
	)
	(via
		(at 154.649424 -146.013678)
		(size 0.508)
		(drill 0.254)
		(layers "F.Cu" "B.Cu")
		(net "PVPP_KLM")
	)
	(via
		(at 166.1668 -135.3312)
		(size 0.508)
		(drill 0.254)
		(layers "F.Cu" "B.Cu")
		(net "PVPP_KLM")
	)
	(via
		(at 113.72469 -149.452076)
		(size 0.508)
		(drill 0.254)
		(layers "F.Cu" "B.Cu")
		(net "PVPP_KLM")
	)
	(via
		(at 167.5765 -135.7122)
		(size 0.508)
		(drill 0.254)
		(layers "F.Cu" "B.Cu")
		(net "PVPP_KLM")
	)
	(via
		(at 152.949402 -143.941546)
		(size 0.508)
		(drill 0.254)
		(layers "F.Cu" "B.Cu")
		(net "PVPP_KLM")
	)
	(via
		(at 154.649424 -136.412478)
		(size 0.508)
		(drill 0.254)
		(layers "F.Cu" "B.Cu")
		(net "PVPP_KLM")
	)
	(via
		(at 156.349446 -155.614878)
		(size 0.508)
		(drill 0.254)
		(layers "F.Cu" "B.Cu")
		(net "PVPP_KLM")
	)
	(via
		(at 156.349446 -139.181078)
		(size 0.508)
		(drill 0.254)
		(layers "F.Cu" "B.Cu")
		(net "PVPP_KLM")
	)
	(via
		(at 152.949402 -139.181078)
		(size 0.508)
		(drill 0.254)
		(layers "F.Cu" "B.Cu")
		(net "PVPP_KLM")
	)
	(via
		(at 154.649424 -131.571746)
		(size 0.508)
		(drill 0.254)
		(layers "F.Cu" "B.Cu")
		(net "PVPP_KLM")
	)
	(via
		(at 155.499562 -153.542746)
		(size 0.508)
		(drill 0.254)
		(layers "F.Cu" "B.Cu")
		(net "PVPP_KLM")
	)
	(via
		(at 155.499562 -146.013678)
		(size 0.508)
		(drill 0.254)
		(layers "F.Cu" "B.Cu")
		(net "PVPP_KLM")
	)
	(via
		(at 152.099518 -150.788878)
		(size 0.508)
		(drill 0.254)
		(layers "F.Cu" "B.Cu")
		(net "PVPP_KLM")
	)
	(via
		(at 152.949402 -136.412478)
		(size 0.508)
		(drill 0.254)
		(layers "F.Cu" "B.Cu")
		(net "PVPP_KLM")
	)
	(via
		(at 166.9415 -134.9502)
		(size 0.508)
		(drill 0.254)
		(layers "F.Cu" "B.Cu")
		(net "PVPP_KLM")
	)
	(via
		(at 154.649424 -129.579878)
		(size 0.508)
		(drill 0.254)
		(layers "F.Cu" "B.Cu")
		(net "PVPP_KLM")
	)
	(via
		(at 113.732564 -155.615386)
		(size 0.508)
		(drill 0.254)
		(layers "F.Cu" "B.Cu")
		(net "PVPP_KLM")
	)
	(via
		(at 152.949402 -141.172946)
		(size 0.508)
		(drill 0.254)
		(layers "F.Cu" "B.Cu")
		(net "PVPP_KLM")
	)
	(via
		(at 164.719 -121.2596)
		(size 0.508)
		(drill 0.254)
		(layers "F.Cu" "B.Cu")
		(net "PVPP_KLM")
	)
	(via
		(at 166.9288 -132.6642)
		(size 0.6604)
		(drill 0.3302)
		(layers "F.Cu" "B.Cu")
		(net "PVPP_KLM")
	)
	(via
		(at 155.499562 -143.941546)
		(size 0.508)
		(drill 0.254)
		(layers "F.Cu" "B.Cu")
		(net "PVPP_KLM")
	)
	(via
		(at 152.949402 -148.782278)
		(size 0.508)
		(drill 0.254)
		(layers "F.Cu" "B.Cu")
		(net "PVPP_KLM")
	)
	(via
		(at 154.649424 -155.614878)
		(size 0.508)
		(drill 0.254)
		(layers "F.Cu" "B.Cu")
		(net "PVPP_KLM")
	)
	(via
		(at 155.499562 -131.571746)
		(size 0.508)
		(drill 0.254)
		(layers "F.Cu" "B.Cu")
		(net "PVPP_KLM")
	)
	(via
		(at 155.499562 -148.782278)
		(size 0.508)
		(drill 0.254)
		(layers "F.Cu" "B.Cu")
		(net "PVPP_KLM")
	)
	(via
		(at 164.1221 -137.2489)
		(size 0.508)
		(drill 0.254)
		(layers "F.Cu" "B.Cu")
		(net "PVPP_KLM")
	)
	(via
		(at 154.649424 -148.782278)
		(size 0.508)
		(drill 0.254)
		(layers "F.Cu" "B.Cu")
		(net "PVPP_KLM")
	)
	(via
		(at 156.349446 -136.412478)
		(size 0.508)
		(drill 0.254)
		(layers "F.Cu" "B.Cu")
		(net "PVPP_KLM")
	)
	(via
		(at 154.649424 -141.172946)
		(size 0.508)
		(drill 0.254)
		(layers "F.Cu" "B.Cu")
		(net "PVPP_KLM")
	)
	(via
		(at 166.1541 -134.6708)
		(size 0.508)
		(drill 0.254)
		(layers "F.Cu" "B.Cu")
		(net "PVPP_KLM")
	)
	(via
		(at 164.1221 -138.0109)
		(size 0.508)
		(drill 0.254)
		(layers "F.Cu" "B.Cu")
		(net "PVPP_KLM")
	)
	(via
		(at 156.349446 -129.579878)
		(size 0.508)
		(drill 0.254)
		(layers "F.Cu" "B.Cu")
		(net "PVPP_KLM")
	)
	(via
		(at 165.3794 -135.3058)
		(size 0.508)
		(drill 0.254)
		(layers "F.Cu" "B.Cu")
		(net "PVPP_KLM")
	)
	(via
		(at 155.499562 -150.774146)
		(size 0.508)
		(drill 0.254)
		(layers "F.Cu" "B.Cu")
		(net "PVPP_KLM")
	)
	(via
		(at 167.5765 -134.9502)
		(size 0.508)
		(drill 0.254)
		(layers "F.Cu" "B.Cu")
		(net "PVPP_KLM")
	)
	(via
		(at 168.31056 -134.19582)
		(size 0.508)
		(drill 0.254)
		(layers "F.Cu" "B.Cu")
		(net "PVPP_KLM")
	)
	(via
		(at 152.099518 -131.586478)
		(size 0.508)
		(drill 0.254)
		(layers "F.Cu" "B.Cu")
		(net "PVPP_KLM")
	)
	(via
		(at 165.3921 -134.6708)
		(size 0.508)
		(drill 0.254)
		(layers "F.Cu" "B.Cu")
		(net "PVPP_KLM")
	)
	(via
		(at 154.649424 -134.340346)
		(size 0.508)
		(drill 0.254)
		(layers "F.Cu" "B.Cu")
		(net "PVPP_KLM")
	)
	(via
		(at 164.1221 -138.7729)
		(size 0.508)
		(drill 0.254)
		(layers "F.Cu" "B.Cu")
		(net "PVPP_KLM")
	)
	(via
		(at 156.349446 -148.782278)
		(size 0.508)
		(drill 0.254)
		(layers "F.Cu" "B.Cu")
		(net "PVPP_KLM")
	)
	(via
		(at 159.8422 -124.46)
		(size 0.508)
		(drill 0.254)
		(layers "F.Cu" "B.Cu")
		(net "PVPP_KLM")
	)
	(via
		(at 152.949402 -129.579878)
		(size 0.508)
		(drill 0.254)
		(layers "F.Cu" "B.Cu")
		(net "PVPP_KLM")
	)
	(via
		(at 155.499562 -141.172946)
		(size 0.508)
		(drill 0.254)
		(layers "F.Cu" "B.Cu")
		(net "PVPP_KLM")
	)
	(via
		(at 155.499562 -136.412478)
		(size 0.508)
		(drill 0.254)
		(layers "F.Cu" "B.Cu")
		(net "PVPP_KLM")
	)
	(via
		(at 166.9034 -140.335)
		(size 0.508)
		(drill 0.254)
		(layers "F.Cu" "B.Cu")
		(net "PVPP_KLM")
	)
	(via
		(at 166.0398 -140.335)
		(size 0.508)
		(drill 0.254)
		(layers "F.Cu" "B.Cu")
		(net "PVPP_KLM")
	)
	(via
		(at 154.649424 -153.542746)
		(size 0.508)
		(drill 0.254)
		(layers "F.Cu" "B.Cu")
		(net "PVPP_KLM")
	)
	(via
		(at 152.949402 -146.013678)
		(size 0.508)
		(drill 0.254)
		(layers "F.Cu" "B.Cu")
		(net "PVPP_KLM")
	)
	(via
		(at 155.499562 -139.181078)
		(size 0.508)
		(drill 0.254)
		(layers "F.Cu" "B.Cu")
		(net "PVPP_KLM")
	)
	(via
		(at 152.949402 -155.614878)
		(size 0.508)
		(drill 0.254)
		(layers "F.Cu" "B.Cu")
		(net "PVPP_KLM")
	)
	(via
		(at 166.9415 -135.7122)
		(size 0.508)
		(drill 0.254)
		(layers "F.Cu" "B.Cu")
		(net "PVPP_KLM")
	)
	(via
		(at 163.7792 -143.0782)
		(size 0.508)
		(drill 0.254)
		(layers "F.Cu" "B.Cu")
		(net "PVPP_KLM")
	)
	(via
		(at 154.649424 -143.941546)
		(size 0.508)
		(drill 0.254)
		(layers "F.Cu" "B.Cu")
		(net "PVPP_KLM")
	)
	(via
		(at 155.57881 -126.683008)
		(size 0.508)
		(drill 0.254)
		(layers "F.Cu" "B.Cu")
		(net "PVPP_KLM")
	)
	(via
		(at 164.5412 -143.0782)
		(size 0.508)
		(drill 0.254)
		(layers "F.Cu" "B.Cu")
		(net "PVPP_KLM")
	)
	(via
		(at 155.499562 -155.614878)
		(size 0.508)
		(drill 0.254)
		(layers "F.Cu" "B.Cu")
		(net "PVPP_KLM")
	)
	(via
		(at 166.0652 -143.0782)
		(size 0.508)
		(drill 0.254)
		(layers "F.Cu" "B.Cu")
		(net "PVPP_KLM")
	)
	(via
		(at 155.499562 -134.340346)
		(size 0.508)
		(drill 0.254)
		(layers "F.Cu" "B.Cu")
		(net "PVPP_KLM")
	)
	(via
		(at 165.3286 -140.335)
		(size 0.508)
		(drill 0.254)
		(layers "F.Cu" "B.Cu")
		(net "PVPP_KLM")
	)
	(via
		(at 165.3032 -143.0782)
		(size 0.508)
		(drill 0.254)
		(layers "F.Cu" "B.Cu")
		(net "PVPP_KLM")
	)
	(segment
		(start 167.9956 -123.0376)
		(end 168.148 -123.19)
		(width 0.254)
		(layer "B.Cu")
		(net "PVPP_KLM")
	)
	(segment
		(start 164.719 -121.2596)
		(end 164.754814 -121.2596)
		(width 0.254)
		(layer "B.Cu")
		(net "PVPP_KLM")
	)
	(segment
		(start 113.849404 -149.327362)
		(end 113.72469 -149.452076)
		(width 0.4064)
		(layer "B.Cu")
		(net "PVPP_KLM")
	)
	(segment
		(start 113.849404 -147.478496)
		(end 113.849404 -149.327362)
		(width 0.4064)
		(layer "B.Cu")
		(net "PVPP_KLM")
	)
	(segment
		(start 166.532814 -123.0376)
		(end 167.9956 -123.0376)
		(width 0.254)
		(layer "B.Cu")
		(net "PVPP_KLM")
	)
	(segment
		(start 164.754814 -121.2596)
		(end 166.532814 -123.0376)
		(width 0.254)
		(layer "B.Cu")
		(net "PVPP_KLM")
	)
	(segment
		(start 148.079968 -153.1366)
		(end 148.079968 -154.2034)
		(width 0.254)
		(layer "In2.Cu")
		(net "PVPP_KLM")
	)
	(segment
		(start 113.732564 -155.615386)
		(end 113.732564 -155.226004)
		(width 0.254)
		(layer "In2.Cu")
		(net "PVPP_KLM")
	)
	(segment
		(start 148.511768 -154.6352)
		(end 151.969724 -154.6352)
		(width 0.254)
		(layer "In2.Cu")
		(net "PVPP_KLM")
	)
	(segment
		(start 114.485166 -150.292562)
		(end 114.069368 -150.70836)
		(width 0.254)
		(layer "In2.Cu")
		(net "PVPP_KLM")
	)
	(segment
		(start 113.72469 -149.452076)
		(end 114.06251 -149.452076)
		(width 0.254)
		(layer "In2.Cu")
		(net "PVPP_KLM")
	)
	(segment
		(start 114.069368 -150.70836)
		(end 114.069368 -151.88692)
		(width 0.254)
		(layer "In2.Cu")
		(net "PVPP_KLM")
	)
	(segment
		(start 114.06251 -149.452076)
		(end 114.485166 -149.874732)
		(width 0.254)
		(layer "In2.Cu")
		(net "PVPP_KLM")
	)
	(segment
		(start 114.069368 -151.88692)
		(end 114.785648 -152.6032)
		(width 0.254)
		(layer "In2.Cu")
		(net "PVPP_KLM")
	)
	(segment
		(start 113.732564 -155.226004)
		(end 114.221768 -154.7368)
		(width 0.254)
		(layer "In2.Cu")
		(net "PVPP_KLM")
	)
	(segment
		(start 114.485166 -149.874732)
		(end 114.485166 -150.292562)
		(width 0.254)
		(layer "In2.Cu")
		(net "PVPP_KLM")
	)
	(segment
		(start 114.785648 -152.6032)
		(end 147.546568 -152.6032)
		(width 0.254)
		(layer "In2.Cu")
		(net "PVPP_KLM")
	)
	(segment
		(start 114.221768 -153.8732)
		(end 114.041936 -153.693368)
		(width 0.254)
		(layer "In2.Cu")
		(net "PVPP_KLM")
	)
	(segment
		(start 114.399568 -152.6032)
		(end 114.785648 -152.6032)
		(width 0.254)
		(layer "In2.Cu")
		(net "PVPP_KLM")
	)
	(segment
		(start 114.041936 -152.960832)
		(end 114.399568 -152.6032)
		(width 0.254)
		(layer "In2.Cu")
		(net "PVPP_KLM")
	)
	(segment
		(start 147.546568 -152.6032)
		(end 148.079968 -153.1366)
		(width 0.254)
		(layer "In2.Cu")
		(net "PVPP_KLM")
	)
	(segment
		(start 114.041936 -153.693368)
		(end 114.041936 -152.960832)
		(width 0.254)
		(layer "In2.Cu")
		(net "PVPP_KLM")
	)
	(segment
		(start 151.969724 -154.6352)
		(end 152.949402 -155.614878)
		(width 0.254)
		(layer "In2.Cu")
		(net "PVPP_KLM")
	)
	(segment
		(start 148.079968 -154.2034)
		(end 148.511768 -154.6352)
		(width 0.254)
		(layer "In2.Cu")
		(net "PVPP_KLM")
	)
	(segment
		(start 114.221768 -154.7368)
		(end 114.221768 -153.8732)
		(width 0.254)
		(layer "In2.Cu")
		(net "PVPP_KLM")
	)
	(segment
		(start 164.719 -121.2596)
		(end 163.0426 -121.2596)
		(width 0.254)
		(layer "In4.Cu")
		(net "PVPP_KLM")
	)
	(segment
		(start 163.0426 -121.2596)
		(end 159.8422 -124.46)
		(width 0.254)
		(layer "In4.Cu")
		(net "PVPP_KLM")
	)
	(segment
		(start 166.9415 4.1275)
		(end 167.259 4.445)
		(width 0.4064)
		(layer "F.Cu")
		(net "PVPP_GHJ")
	)
	(segment
		(start 134.96798 -51.319684)
		(end 134.650988 -51.319684)
		(width 0.254)
		(layer "F.Cu")
		(net "PVPP_GHJ")
	)
	(segment
		(start 135.095234 -51.446938)
		(end 134.96798 -51.319684)
		(width 0.254)
		(layer "F.Cu")
		(net "PVPP_GHJ")
	)
	(segment
		(start 113.849404 -2.8194)
		(end 113.849404 -0.821182)
		(width 0.4064)
		(layer "F.Cu")
		(net "PVPP_GHJ")
	)
	(segment
		(start 133.251194 -51.319684)
		(end 132.933948 -51.319684)
		(width 0.254)
		(layer "F.Cu")
		(net "PVPP_GHJ")
	)
	(segment
		(start 133.665214 -51.941984)
		(end 134.236714 -51.941984)
		(width 0.254)
		(layer "F.Cu")
		(net "PVPP_GHJ")
	)
	(segment
		(start 166.9415 3.79222)
		(end 166.9415 4.1275)
		(width 0.4064)
		(layer "F.Cu")
		(net "PVPP_GHJ")
	)
	(segment
		(start 136.744456 -51.30292)
		(end 136.384792 -51.30292)
		(width 0.254)
		(layer "F.Cu")
		(net "PVPP_GHJ")
	)
	(segment
		(start 133.378194 -51.446938)
		(end 133.251194 -51.319684)
		(width 0.254)
		(layer "F.Cu")
		(net "PVPP_GHJ")
	)
	(segment
		(start 134.650988 -51.319684)
		(end 134.523734 -51.446938)
		(width 0.254)
		(layer "F.Cu")
		(net "PVPP_GHJ")
	)
	(segment
		(start 132.933948 -51.319684)
		(end 132.806694 -51.446938)
		(width 0.254)
		(layer "F.Cu")
		(net "PVPP_GHJ")
	)
	(segment
		(start 136.812274 -51.370738)
		(end 136.744456 -51.30292)
		(width 0.254)
		(layer "F.Cu")
		(net "PVPP_GHJ")
	)
	(segment
		(start 136.384792 -51.30292)
		(end 136.240774 -51.446938)
		(width 0.254)
		(layer "F.Cu")
		(net "PVPP_GHJ")
	)
	(segment
		(start 167.259 4.445)
		(end 167.64 4.445)
		(width 0.4064)
		(layer "F.Cu")
		(net "PVPP_GHJ")
	)
	(via
		(at 155.499562 -7.086346)
		(size 0.508)
		(drill 0.254)
		(layers "F.Cu" "B.Cu")
		(net "PVPP_GHJ")
	)
	(via
		(at 154.649424 -18.759678)
		(size 0.508)
		(drill 0.254)
		(layers "F.Cu" "B.Cu")
		(net "PVPP_GHJ")
	)
	(via
		(at 152.099518 -4.332478)
		(size 0.508)
		(drill 0.254)
		(layers "F.Cu" "B.Cu")
		(net "PVPP_GHJ")
	)
	(via
		(at 166.5224 -17.5514)
		(size 0.508)
		(drill 0.254)
		(layers "F.Cu" "B.Cu")
		(net "PVPP_GHJ")
	)
	(via
		(at 155.499562 -9.158478)
		(size 0.508)
		(drill 0.254)
		(layers "F.Cu" "B.Cu")
		(net "PVPP_GHJ")
	)
	(via
		(at 155.499562 -2.325878)
		(size 0.508)
		(drill 0.254)
		(layers "F.Cu" "B.Cu")
		(net "PVPP_GHJ")
	)
	(via
		(at 154.649424 2.514854)
		(size 0.508)
		(drill 0.254)
		(layers "F.Cu" "B.Cu")
		(net "PVPP_GHJ")
	)
	(via
		(at 154.649424 -9.158478)
		(size 0.508)
		(drill 0.254)
		(layers "F.Cu" "B.Cu")
		(net "PVPP_GHJ")
	)
	(via
		(at 133.378194 -51.446938)
		(size 0.4826)
		(drill 0.254)
		(layers "F.Cu" "B.Cu")
		(net "PVPP_GHJ")
	)
	(via
		(at 167.386 -18.3642)
		(size 0.508)
		(drill 0.254)
		(layers "F.Cu" "B.Cu")
		(net "PVPP_GHJ")
	)
	(via
		(at 163.805616 -23.465028)
		(size 0.508)
		(drill 0.254)
		(layers "F.Cu" "B.Cu")
		(net "PVPP_GHJ")
	)
	(via
		(at 166.5224 -16.7894)
		(size 0.508)
		(drill 0.254)
		(layers "F.Cu" "B.Cu")
		(net "PVPP_GHJ")
	)
	(via
		(at 156.349446 -21.528278)
		(size 0.508)
		(drill 0.254)
		(layers "F.Cu" "B.Cu")
		(net "PVPP_GHJ")
	)
	(via
		(at 155.499562 -21.528278)
		(size 0.508)
		(drill 0.254)
		(layers "F.Cu" "B.Cu")
		(net "PVPP_GHJ")
	)
	(via
		(at 155.499562 2.514854)
		(size 0.508)
		(drill 0.254)
		(layers "F.Cu" "B.Cu")
		(net "PVPP_GHJ")
	)
	(via
		(at 152.949402 -7.086346)
		(size 0.508)
		(drill 0.254)
		(layers "F.Cu" "B.Cu")
		(net "PVPP_GHJ")
	)
	(via
		(at 156.349446 -2.325878)
		(size 0.508)
		(drill 0.254)
		(layers "F.Cu" "B.Cu")
		(net "PVPP_GHJ")
	)
	(via
		(at 167.1574 -17.5514)
		(size 0.508)
		(drill 0.254)
		(layers "F.Cu" "B.Cu")
		(net "PVPP_GHJ")
	)
	(via
		(at 156.349446 0.442722)
		(size 0.508)
		(drill 0.254)
		(layers "F.Cu" "B.Cu")
		(net "PVPP_GHJ")
	)
	(via
		(at 164.8968 -21.9202)
		(size 0.508)
		(drill 0.254)
		(layers "F.Cu" "B.Cu")
		(net "PVPP_GHJ")
	)
	(via
		(at 152.949402 -13.918946)
		(size 0.508)
		(drill 0.254)
		(layers "F.Cu" "B.Cu")
		(net "PVPP_GHJ")
	)
	(via
		(at 165.1 -18.3642)
		(size 0.508)
		(drill 0.254)
		(layers "F.Cu" "B.Cu")
		(net "PVPP_GHJ")
	)
	(via
		(at 154.649424 -7.086346)
		(size 0.508)
		(drill 0.254)
		(layers "F.Cu" "B.Cu")
		(net "PVPP_GHJ")
	)
	(via
		(at 156.349446 -11.927078)
		(size 0.508)
		(drill 0.254)
		(layers "F.Cu" "B.Cu")
		(net "PVPP_GHJ")
	)
	(via
		(at 154.649424 -13.918946)
		(size 0.508)
		(drill 0.254)
		(layers "F.Cu" "B.Cu")
		(net "PVPP_GHJ")
	)
	(via
		(at 152.949402 -2.325878)
		(size 0.508)
		(drill 0.254)
		(layers "F.Cu" "B.Cu")
		(net "PVPP_GHJ")
	)
	(via
		(at 165.735 -19.1262)
		(size 0.508)
		(drill 0.254)
		(layers "F.Cu" "B.Cu")
		(net "PVPP_GHJ")
	)
	(via
		(at 155.499562 -18.759678)
		(size 0.508)
		(drill 0.254)
		(layers "F.Cu" "B.Cu")
		(net "PVPP_GHJ")
	)
	(via
		(at 155.499562 -16.687546)
		(size 0.508)
		(drill 0.254)
		(layers "F.Cu" "B.Cu")
		(net "PVPP_GHJ")
	)
	(via
		(at 152.099518 -13.933678)
		(size 0.508)
		(drill 0.254)
		(layers "F.Cu" "B.Cu")
		(net "PVPP_GHJ")
	)
	(via
		(at 166.751 -18.3642)
		(size 0.508)
		(drill 0.254)
		(layers "F.Cu" "B.Cu")
		(net "PVPP_GHJ")
	)
	(via
		(at 154.649424 -2.325878)
		(size 0.508)
		(drill 0.254)
		(layers "F.Cu" "B.Cu")
		(net "PVPP_GHJ")
	)
	(via
		(at 167.276018 -11.338306)
		(size 0.508)
		(drill 0.254)
		(layers "F.Cu" "B.Cu")
		(net "PVPP_GHJ")
	)
	(via
		(at 155.499562 0.442722)
		(size 0.508)
		(drill 0.254)
		(layers "F.Cu" "B.Cu")
		(net "PVPP_GHJ")
	)
	(via
		(at 165.1 -19.1262)
		(size 0.508)
		(drill 0.254)
		(layers "F.Cu" "B.Cu")
		(net "PVPP_GHJ")
	)
	(via
		(at 165.735 -18.3642)
		(size 0.508)
		(drill 0.254)
		(layers "F.Cu" "B.Cu")
		(net "PVPP_GHJ")
	)
	(via
		(at 167.386 -19.1262)
		(size 0.508)
		(drill 0.254)
		(layers "F.Cu" "B.Cu")
		(net "PVPP_GHJ")
	)
	(via
		(at 164.8968 -22.5552)
		(size 0.508)
		(drill 0.254)
		(layers "F.Cu" "B.Cu")
		(net "PVPP_GHJ")
	)
	(via
		(at 154.649424 -23.520146)
		(size 0.508)
		(drill 0.254)
		(layers "F.Cu" "B.Cu")
		(net "PVPP_GHJ")
	)
	(via
		(at 154.5844 -26.162)
		(size 0.508)
		(drill 0.254)
		(layers "F.Cu" "B.Cu")
		(net "PVPP_GHJ")
	)
	(via
		(at 136.812274 -51.370738)
		(size 0.508)
		(drill 0.254)
		(layers "F.Cu" "B.Cu")
		(net "PVPP_GHJ")
	)
	(via
		(at 154.649424 -4.317746)
		(size 0.508)
		(drill 0.254)
		(layers "F.Cu" "B.Cu")
		(net "PVPP_GHJ")
	)
	(via
		(at 154.649424 -11.927078)
		(size 0.508)
		(drill 0.254)
		(layers "F.Cu" "B.Cu")
		(net "PVPP_GHJ")
	)
	(via
		(at 167.64 4.445)
		(size 0.508)
		(drill 0.254)
		(layers "F.Cu" "B.Cu")
		(net "PVPP_GHJ")
	)
	(via
		(at 152.949402 0.442722)
		(size 0.508)
		(drill 0.254)
		(layers "F.Cu" "B.Cu")
		(net "PVPP_GHJ")
	)
	(via
		(at 156.349446 -9.158478)
		(size 0.508)
		(drill 0.254)
		(layers "F.Cu" "B.Cu")
		(net "PVPP_GHJ")
	)
	(via
		(at 134.236714 -51.941984)
		(size 0.508)
		(drill 0.254)
		(layers "F.Cu" "B.Cu")
		(net "PVPP_GHJ")
	)
	(via
		(at 155.499562 -23.520146)
		(size 0.508)
		(drill 0.254)
		(layers "F.Cu" "B.Cu")
		(net "PVPP_GHJ")
	)
	(via
		(at 164.1348 -22.5552)
		(size 0.508)
		(drill 0.254)
		(layers "F.Cu" "B.Cu")
		(net "PVPP_GHJ")
	)
	(via
		(at 152.949402 -11.927078)
		(size 0.508)
		(drill 0.254)
		(layers "F.Cu" "B.Cu")
		(net "PVPP_GHJ")
	)
	(via
		(at 156.349446 -18.759678)
		(size 0.508)
		(drill 0.254)
		(layers "F.Cu" "B.Cu")
		(net "PVPP_GHJ")
	)
	(via
		(at 155.499562 -13.918946)
		(size 0.508)
		(drill 0.254)
		(layers "F.Cu" "B.Cu")
		(net "PVPP_GHJ")
	)
	(via
		(at 167.276018 -12.100306)
		(size 0.508)
		(drill 0.254)
		(layers "F.Cu" "B.Cu")
		(net "PVPP_GHJ")
	)
	(via
		(at 154.649424 0.442722)
		(size 0.508)
		(drill 0.254)
		(layers "F.Cu" "B.Cu")
		(net "PVPP_GHJ")
	)
	(via
		(at 165.812216 -22.982428)
		(size 0.508)
		(drill 0.254)
		(layers "F.Cu" "B.Cu")
		(net "PVPP_GHJ")
	)
	(via
		(at 135.095234 -51.446938)
		(size 0.4826)
		(drill 0.254)
		(layers "F.Cu" "B.Cu")
		(net "PVPP_GHJ")
	)
	(via
		(at 166.641018 -11.338306)
		(size 0.508)
		(drill 0.254)
		(layers "F.Cu" "B.Cu")
		(net "PVPP_GHJ")
	)
	(via
		(at 165.151816 -23.185628)
		(size 0.508)
		(drill 0.254)
		(layers "F.Cu" "B.Cu")
		(net "PVPP_GHJ")
	)
	(via
		(at 164.415216 -23.338028)
		(size 0.508)
		(drill 0.254)
		(layers "F.Cu" "B.Cu")
		(net "PVPP_GHJ")
	)
	(via
		(at 155.499562 -11.927078)
		(size 0.508)
		(drill 0.254)
		(layers "F.Cu" "B.Cu")
		(net "PVPP_GHJ")
	)
	(via
		(at 152.949402 -9.158478)
		(size 0.508)
		(drill 0.254)
		(layers "F.Cu" "B.Cu")
		(net "PVPP_GHJ")
	)
	(via
		(at 166.641018 -12.100306)
		(size 0.508)
		(drill 0.254)
		(layers "F.Cu" "B.Cu")
		(net "PVPP_GHJ")
	)
	(via
		(at 154.649424 -16.687546)
		(size 0.508)
		(drill 0.254)
		(layers "F.Cu" "B.Cu")
		(net "PVPP_GHJ")
	)
	(via
		(at 152.099518 -23.534878)
		(size 0.508)
		(drill 0.254)
		(layers "F.Cu" "B.Cu")
		(net "PVPP_GHJ")
	)
	(via
		(at 152.949402 -21.528278)
		(size 0.508)
		(drill 0.254)
		(layers "F.Cu" "B.Cu")
		(net "PVPP_GHJ")
	)
	(via
		(at 164.1348 -21.9202)
		(size 0.508)
		(drill 0.254)
		(layers "F.Cu" "B.Cu")
		(net "PVPP_GHJ")
	)
	(via
		(at 167.1574 -16.7894)
		(size 0.508)
		(drill 0.254)
		(layers "F.Cu" "B.Cu")
		(net "PVPP_GHJ")
	)
	(via
		(at 152.949402 -18.759678)
		(size 0.508)
		(drill 0.254)
		(layers "F.Cu" "B.Cu")
		(net "PVPP_GHJ")
	)
	(via
		(at 113.849404 -2.8194)
		(size 0.508)
		(drill 0.254)
		(layers "F.Cu" "B.Cu")
		(net "PVPP_GHJ")
	)
	(via
		(at 166.751 -19.1262)
		(size 0.508)
		(drill 0.254)
		(layers "F.Cu" "B.Cu")
		(net "PVPP_GHJ")
	)
	(via
		(at 154.649424 -21.528278)
		(size 0.508)
		(drill 0.254)
		(layers "F.Cu" "B.Cu")
		(net "PVPP_GHJ")
	)
	(via
		(at 155.499562 -4.317746)
		(size 0.508)
		(drill 0.254)
		(layers "F.Cu" "B.Cu")
		(net "PVPP_GHJ")
	)
	(segment
		(start 166.751 4.445)
		(end 165.9001 4.445)
		(width 0.4064)
		(layer "B.Cu")
		(net "PVPP_GHJ")
	)
	(segment
		(start 165.46576 4.5212)
		(end 165.54196 4.445)
		(width 0.4064)
		(layer "B.Cu")
		(net "PVPP_GHJ")
	)
	(segment
		(start 165.1127 4.5212)
		(end 165.46576 4.5212)
		(width 0.4064)
		(layer "B.Cu")
		(net "PVPP_GHJ")
	)
	(segment
		(start 165.54196 4.445)
		(end 165.9001 4.445)
		(width 0.4064)
		(layer "B.Cu")
		(net "PVPP_GHJ")
	)
	(segment
		(start 167.64 4.445)
		(end 166.751 4.445)
		(width 0.4064)
		(layer "B.Cu")
		(net "PVPP_GHJ")
	)
	(segment
		(start 113.849404 -2.8194)
		(end 113.849404 -1.021842)
		(width 0.4064)
		(layer "B.Cu")
		(net "PVPP_GHJ")
	)
	(segment
		(start 155.499562 3.734562)
		(end 155.499562 2.514854)
		(width 0.4064)
		(layer "B.Cu")
		(net "PVPP_GHJ")
	)
	(segment
		(start 152.099518 -24.824182)
		(end 152.099518 -23.534878)
		(width 0.1651)
		(layer "B.Cu")
		(net "PVPP_GHJ")
	)
	(segment
		(start 165.1127 4.5212)
		(end 156.2862 4.5212)
		(width 0.4064)
		(layer "B.Cu")
		(net "PVPP_GHJ")
	)
	(segment
		(start 155.499562 -24.824182)
		(end 155.499562 -23.520146)
		(width 0.254)
		(layer "B.Cu")
		(net "PVPP_GHJ")
	)
	(segment
		(start 154.649424 -24.824182)
		(end 154.649424 -23.520146)
		(width 0.254)
		(layer "B.Cu")
		(net "PVPP_GHJ")
	)
	(segment
		(start 156.2862 4.5212)
		(end 155.499562 3.734562)
		(width 0.4064)
		(layer "B.Cu")
		(net "PVPP_GHJ")
	)
	(segment
		(start 152.099518 -5.621782)
		(end 152.099518 -4.332478)
		(width 0.1651)
		(layer "B.Cu")
		(net "PVPP_GHJ")
	)
	(segment
		(start 114.371628 -1.74244)
		(end 152.365964 -1.74244)
		(width 0.4064)
		(layer "In2.Cu")
		(net "PVPP_GHJ")
	)
	(segment
		(start 113.849404 -2.264664)
		(end 114.371628 -1.74244)
		(width 0.4064)
		(layer "In2.Cu")
		(net "PVPP_GHJ")
	)
	(segment
		(start 113.849404 -2.8194)
		(end 113.849404 -2.264664)
		(width 0.4064)
		(layer "In2.Cu")
		(net "PVPP_GHJ")
	)
	(segment
		(start 152.365964 -1.74244)
		(end 152.949402 -2.325878)
		(width 0.4064)
		(layer "In2.Cu")
		(net "PVPP_GHJ")
	)
	(segment
		(start 278.850344 -156.87294)
		(end 278.849836 -156.87294)
		(width 0.4064)
		(layer "F.Cu")
		(net "PVPP_DEF")
	)
	(segment
		(start 278.849836 -155.732226)
		(end 278.732996 -155.615386)
		(width 0.4064)
		(layer "F.Cu")
		(net "PVPP_DEF")
	)
	(segment
		(start 278.849836 -156.87294)
		(end 278.849836 -155.732226)
		(width 0.4064)
		(layer "F.Cu")
		(net "PVPP_DEF")
	)
	(via
		(at 321.349878 -146.013678)
		(size 0.508)
		(drill 0.254)
		(layers "F.Cu" "B.Cu")
		(net "PVPP_DEF")
	)
	(via
		(at 317.09995 -150.788878)
		(size 0.508)
		(drill 0.254)
		(layers "F.Cu" "B.Cu")
		(net "PVPP_DEF")
	)
	(via
		(at 329.17384 -130.4163)
		(size 0.508)
		(drill 0.254)
		(layers "F.Cu" "B.Cu")
		(net "PVPP_DEF")
	)
	(via
		(at 319.649856 -150.774146)
		(size 0.508)
		(drill 0.254)
		(layers "F.Cu" "B.Cu")
		(net "PVPP_DEF")
	)
	(via
		(at 329.80884 -131.1783)
		(size 0.508)
		(drill 0.254)
		(layers "F.Cu" "B.Cu")
		(net "PVPP_DEF")
	)
	(via
		(at 320.499994 -153.542746)
		(size 0.508)
		(drill 0.254)
		(layers "F.Cu" "B.Cu")
		(net "PVPP_DEF")
	)
	(via
		(at 317.949834 -148.782278)
		(size 0.508)
		(drill 0.254)
		(layers "F.Cu" "B.Cu")
		(net "PVPP_DEF")
	)
	(via
		(at 329.09764 -135.5598)
		(size 0.508)
		(drill 0.254)
		(layers "F.Cu" "B.Cu")
		(net "PVPP_DEF")
	)
	(via
		(at 319.649856 -148.782278)
		(size 0.508)
		(drill 0.254)
		(layers "F.Cu" "B.Cu")
		(net "PVPP_DEF")
	)
	(via
		(at 317.09995 -131.586478)
		(size 0.508)
		(drill 0.254)
		(layers "F.Cu" "B.Cu")
		(net "PVPP_DEF")
	)
	(via
		(at 329.17384 -131.1783)
		(size 0.508)
		(drill 0.254)
		(layers "F.Cu" "B.Cu")
		(net "PVPP_DEF")
	)
	(via
		(at 317.949834 -139.181078)
		(size 0.508)
		(drill 0.254)
		(layers "F.Cu" "B.Cu")
		(net "PVPP_DEF")
	)
	(via
		(at 321.349878 -155.614878)
		(size 0.508)
		(drill 0.254)
		(layers "F.Cu" "B.Cu")
		(net "PVPP_DEF")
	)
	(via
		(at 319.649856 -153.542746)
		(size 0.508)
		(drill 0.254)
		(layers "F.Cu" "B.Cu")
		(net "PVPP_DEF")
	)
	(via
		(at 317.949834 -136.412478)
		(size 0.508)
		(drill 0.254)
		(layers "F.Cu" "B.Cu")
		(net "PVPP_DEF")
	)
	(via
		(at 319.649856 -146.013678)
		(size 0.508)
		(drill 0.254)
		(layers "F.Cu" "B.Cu")
		(net "PVPP_DEF")
	)
	(via
		(at 321.349878 -148.782278)
		(size 0.508)
		(drill 0.254)
		(layers "F.Cu" "B.Cu")
		(net "PVPP_DEF")
	)
	(via
		(at 329.80884 -130.4163)
		(size 0.508)
		(drill 0.254)
		(layers "F.Cu" "B.Cu")
		(net "PVPP_DEF")
	)
	(via
		(at 329.80884 -131.9403)
		(size 0.508)
		(drill 0.254)
		(layers "F.Cu" "B.Cu")
		(net "PVPP_DEF")
	)
	(via
		(at 329.09764 -134.7978)
		(size 0.508)
		(drill 0.254)
		(layers "F.Cu" "B.Cu")
		(net "PVPP_DEF")
	)
	(via
		(at 333.6798 -130.8608)
		(size 0.508)
		(drill 0.254)
		(layers "F.Cu" "B.Cu")
		(net "PVPP_DEF")
	)
	(via
		(at 329.80884 -135.5598)
		(size 0.508)
		(drill 0.254)
		(layers "F.Cu" "B.Cu")
		(net "PVPP_DEF")
	)
	(via
		(at 278.725122 -149.452076)
		(size 0.508)
		(drill 0.254)
		(layers "F.Cu" "B.Cu")
		(net "PVPP_DEF")
	)
	(via
		(at 278.732996 -155.615386)
		(size 0.508)
		(drill 0.254)
		(layers "F.Cu" "B.Cu")
		(net "PVPP_DEF")
	)
	(via
		(at 317.949834 -155.614878)
		(size 0.508)
		(drill 0.254)
		(layers "F.Cu" "B.Cu")
		(net "PVPP_DEF")
	)
	(via
		(at 329.09764 -136.3218)
		(size 0.508)
		(drill 0.254)
		(layers "F.Cu" "B.Cu")
		(net "PVPP_DEF")
	)
	(via
		(at 320.499994 -139.181078)
		(size 0.508)
		(drill 0.254)
		(layers "F.Cu" "B.Cu")
		(net "PVPP_DEF")
	)
	(via
		(at 319.649856 -131.571746)
		(size 0.508)
		(drill 0.254)
		(layers "F.Cu" "B.Cu")
		(net "PVPP_DEF")
	)
	(via
		(at 329.17384 -131.9403)
		(size 0.508)
		(drill 0.254)
		(layers "F.Cu" "B.Cu")
		(net "PVPP_DEF")
	)
	(via
		(at 333.6798 -131.5212)
		(size 0.508)
		(drill 0.254)
		(layers "F.Cu" "B.Cu")
		(net "PVPP_DEF")
	)
	(via
		(at 320.499994 -148.782278)
		(size 0.508)
		(drill 0.254)
		(layers "F.Cu" "B.Cu")
		(net "PVPP_DEF")
	)
	(via
		(at 317.949834 -143.941546)
		(size 0.508)
		(drill 0.254)
		(layers "F.Cu" "B.Cu")
		(net "PVPP_DEF")
	)
	(via
		(at 329.09764 -134.0358)
		(size 0.508)
		(drill 0.254)
		(layers "F.Cu" "B.Cu")
		(net "PVPP_DEF")
	)
	(via
		(at 317.949834 -129.579878)
		(size 0.508)
		(drill 0.254)
		(layers "F.Cu" "B.Cu")
		(net "PVPP_DEF")
	)
	(via
		(at 319.649856 -136.412478)
		(size 0.508)
		(drill 0.254)
		(layers "F.Cu" "B.Cu")
		(net "PVPP_DEF")
	)
	(via
		(at 320.499994 -150.774146)
		(size 0.508)
		(drill 0.254)
		(layers "F.Cu" "B.Cu")
		(net "PVPP_DEF")
	)
	(via
		(at 315.12256 -125.84176)
		(size 0.6604)
		(drill 0.3302)
		(layers "F.Cu" "B.Cu")
		(net "PVPP_DEF")
	)
	(via
		(at 319.649856 -139.181078)
		(size 0.508)
		(drill 0.254)
		(layers "F.Cu" "B.Cu")
		(net "PVPP_DEF")
	)
	(via
		(at 320.499994 -136.412478)
		(size 0.508)
		(drill 0.254)
		(layers "F.Cu" "B.Cu")
		(net "PVPP_DEF")
	)
	(via
		(at 319.649856 -134.340346)
		(size 0.508)
		(drill 0.254)
		(layers "F.Cu" "B.Cu")
		(net "PVPP_DEF")
	)
	(via
		(at 319.649856 -129.579878)
		(size 0.508)
		(drill 0.254)
		(layers "F.Cu" "B.Cu")
		(net "PVPP_DEF")
	)
	(via
		(at 329.80884 -134.7978)
		(size 0.508)
		(drill 0.254)
		(layers "F.Cu" "B.Cu")
		(net "PVPP_DEF")
	)
	(via
		(at 320.499994 -155.614878)
		(size 0.508)
		(drill 0.254)
		(layers "F.Cu" "B.Cu")
		(net "PVPP_DEF")
	)
	(via
		(at 329.80884 -136.3218)
		(size 0.508)
		(drill 0.254)
		(layers "F.Cu" "B.Cu")
		(net "PVPP_DEF")
	)
	(via
		(at 317.09995 -141.187678)
		(size 0.508)
		(drill 0.254)
		(layers "F.Cu" "B.Cu")
		(net "PVPP_DEF")
	)
	(via
		(at 320.499994 -141.172946)
		(size 0.508)
		(drill 0.254)
		(layers "F.Cu" "B.Cu")
		(net "PVPP_DEF")
	)
	(via
		(at 321.349878 -136.412478)
		(size 0.508)
		(drill 0.254)
		(layers "F.Cu" "B.Cu")
		(net "PVPP_DEF")
	)
	(via
		(at 321.349878 -139.181078)
		(size 0.508)
		(drill 0.254)
		(layers "F.Cu" "B.Cu")
		(net "PVPP_DEF")
	)
	(via
		(at 320.499994 -129.579878)
		(size 0.508)
		(drill 0.254)
		(layers "F.Cu" "B.Cu")
		(net "PVPP_DEF")
	)
	(via
		(at 320.499994 -146.013678)
		(size 0.508)
		(drill 0.254)
		(layers "F.Cu" "B.Cu")
		(net "PVPP_DEF")
	)
	(via
		(at 320.499994 -131.571746)
		(size 0.508)
		(drill 0.254)
		(layers "F.Cu" "B.Cu")
		(net "PVPP_DEF")
	)
	(via
		(at 319.649856 -155.614878)
		(size 0.508)
		(drill 0.254)
		(layers "F.Cu" "B.Cu")
		(net "PVPP_DEF")
	)
	(via
		(at 329.15352 -129.74574)
		(size 0.508)
		(drill 0.254)
		(layers "F.Cu" "B.Cu")
		(net "PVPP_DEF")
	)
	(via
		(at 329.80884 -134.0358)
		(size 0.508)
		(drill 0.254)
		(layers "F.Cu" "B.Cu")
		(net "PVPP_DEF")
	)
	(via
		(at 319.649856 -143.941546)
		(size 0.508)
		(drill 0.254)
		(layers "F.Cu" "B.Cu")
		(net "PVPP_DEF")
	)
	(via
		(at 321.349878 -129.579878)
		(size 0.508)
		(drill 0.254)
		(layers "F.Cu" "B.Cu")
		(net "PVPP_DEF")
	)
	(via
		(at 317.949834 -146.013678)
		(size 0.508)
		(drill 0.254)
		(layers "F.Cu" "B.Cu")
		(net "PVPP_DEF")
	)
	(via
		(at 317.949834 -141.172946)
		(size 0.508)
		(drill 0.254)
		(layers "F.Cu" "B.Cu")
		(net "PVPP_DEF")
	)
	(via
		(at 320.499994 -134.340346)
		(size 0.508)
		(drill 0.254)
		(layers "F.Cu" "B.Cu")
		(net "PVPP_DEF")
	)
	(via
		(at 320.499994 -143.941546)
		(size 0.508)
		(drill 0.254)
		(layers "F.Cu" "B.Cu")
		(net "PVPP_DEF")
	)
	(via
		(at 329.78852 -129.74574)
		(size 0.508)
		(drill 0.254)
		(layers "F.Cu" "B.Cu")
		(net "PVPP_DEF")
	)
	(via
		(at 319.649856 -141.172946)
		(size 0.508)
		(drill 0.254)
		(layers "F.Cu" "B.Cu")
		(net "PVPP_DEF")
	)
	(segment
		(start 317.6016 -126.873)
		(end 316.1538 -126.873)
		(width 0.254)
		(layer "B.Cu")
		(net "PVPP_DEF")
	)
	(segment
		(start 315.7855 -120.3198)
		(end 316.2808 -120.3198)
		(width 0.254)
		(layer "B.Cu")
		(net "PVPP_DEF")
	)
	(segment
		(start 321.2338 -124.115322)
		(end 321.2338 -123.56846)
		(width 0.254)
		(layer "B.Cu")
		(net "PVPP_DEF")
	)
	(segment
		(start 278.850344 -149.326854)
		(end 278.725122 -149.452076)
		(width 0.4064)
		(layer "B.Cu")
		(net "PVPP_DEF")
	)
	(segment
		(start 316.1538 -126.873)
		(end 315.12256 -125.84176)
		(width 0.254)
		(layer "B.Cu")
		(net "PVPP_DEF")
	)
	(segment
		(start 314.5028 -125.222)
		(end 314.5028 -121.6025)
		(width 0.254)
		(layer "B.Cu")
		(net "PVPP_DEF")
	)
	(segment
		(start 315.12256 -125.84176)
		(end 314.5028 -125.222)
		(width 0.254)
		(layer "B.Cu")
		(net "PVPP_DEF")
	)
	(segment
		(start 321.2338 -123.56846)
		(end 320.9544 -123.28906)
		(width 0.254)
		(layer "B.Cu")
		(net "PVPP_DEF")
	)
	(segment
		(start 314.5028 -121.6025)
		(end 315.7855 -120.3198)
		(width 0.254)
		(layer "B.Cu")
		(net "PVPP_DEF")
	)
	(segment
		(start 278.850344 -147.478496)
		(end 278.850344 -149.326854)
		(width 0.4064)
		(layer "B.Cu")
		(net "PVPP_DEF")
	)
	(segment
		(start 320.9544 -123.28906)
		(end 320.9544 -122.81916)
		(width 0.254)
		(layer "B.Cu")
		(net "PVPP_DEF")
	)
	(segment
		(start 281.996642 -147.263358)
		(end 316.700154 -147.263358)
		(width 0.254)
		(layer "In2.Cu")
		(net "PVPP_DEF")
	)
	(segment
		(start 278.725122 -149.452076)
		(end 279.807924 -149.452076)
		(width 0.254)
		(layer "In2.Cu")
		(net "PVPP_DEF")
	)
	(segment
		(start 316.700154 -147.263358)
		(end 317.949834 -146.013678)
		(width 0.254)
		(layer "In2.Cu")
		(net "PVPP_DEF")
	)
	(segment
		(start 279.807924 -149.452076)
		(end 281.996642 -147.263358)
		(width 0.254)
		(layer "In2.Cu")
		(net "PVPP_DEF")
	)
	(segment
		(start 278.5618 -154.7622)
		(end 278.1046 -154.305)
		(width 0.254)
		(layer "In11.Cu")
		(net "PVPP_DEF")
	)
	(segment
		(start 278.1046 -154.305)
		(end 278.1046 -154.1526)
		(width 0.254)
		(layer "In11.Cu")
		(net "PVPP_DEF")
	)
	(segment
		(start 278.5618 -155.44419)
		(end 278.5618 -154.7622)
		(width 0.254)
		(layer "In11.Cu")
		(net "PVPP_DEF")
	)
	(segment
		(start 278.6888 -153.5684)
		(end 278.6888 -150.749)
		(width 0.254)
		(layer "In11.Cu")
		(net "PVPP_DEF")
	)
	(segment
		(start 278.6888 -150.749)
		(end 278.3586 -150.4188)
		(width 0.254)
		(layer "In11.Cu")
		(net "PVPP_DEF")
	)
	(segment
		(start 278.3586 -149.8346)
		(end 278.725122 -149.468078)
		(width 0.254)
		(layer "In11.Cu")
		(net "PVPP_DEF")
	)
	(segment
		(start 278.3586 -150.4188)
		(end 278.3586 -149.8346)
		(width 0.254)
		(layer "In11.Cu")
		(net "PVPP_DEF")
	)
	(segment
		(start 278.1046 -154.1526)
		(end 278.6888 -153.5684)
		(width 0.254)
		(layer "In11.Cu")
		(net "PVPP_DEF")
	)
	(segment
		(start 278.732996 -155.615386)
		(end 278.5618 -155.44419)
		(width 0.254)
		(layer "In11.Cu")
		(net "PVPP_DEF")
	)
	(segment
		(start 278.725122 -149.468078)
		(end 278.725122 -149.452076)
		(width 0.254)
		(layer "In11.Cu")
		(net "PVPP_DEF")
	)
	(segment
		(start 310.756554 -34.081466)
		(end 310.756554 -35.959796)
		(width 0.254)
		(layer "F.Cu")
		(net "PVPP_ABC")
	)
	(segment
		(start 324.612 -35.052)
		(end 324.866 -35.052)
		(width 0.254)
		(layer "F.Cu")
		(net "PVPP_ABC")
	)
	(segment
		(start 362.358686 -86.205314)
		(end 362.358686 -76.100686)
		(width 0.254)
		(layer "F.Cu")
		(net "PVPP_ABC")
	)
	(segment
		(start 413.901382 -130.649472)
		(end 413.613854 -130.937)
		(width 0.254)
		(layer "F.Cu")
		(net "PVPP_ABC")
	)
	(segment
		(start 417.414964 -124.348494)
		(end 417.29152 -124.471938)
		(width 0.254)
		(layer "F.Cu")
		(net "PVPP_ABC")
	)
	(segment
		(start 421.894 -117.4877)
		(end 422.293034 -117.4877)
		(width 0.254)
		(layer "F.Cu")
		(net "PVPP_ABC")
	)
	(segment
		(start 415.191194 -122.74042)
		(end 416.61588 -122.74042)
		(width 0.254)
		(layer "F.Cu")
		(net "PVPP_ABC")
	)
	(segment
		(start 310.502554 -33.827466)
		(end 310.756554 -34.081466)
		(width 0.254)
		(layer "F.Cu")
		(net "PVPP_ABC")
	)
	(segment
		(start 308.628288 -33.345628)
		(end 309.110126 -33.827466)
		(width 0.254)
		(layer "F.Cu")
		(net "PVPP_ABC")
	)
	(segment
		(start 423.417238 -118.514876)
		(end 423.589196 -118.686834)
		(width 0.254)
		(layer "F.Cu")
		(net "PVPP_ABC")
	)
	(segment
		(start 422.293034 -117.4877)
		(end 422.933622 -118.128288)
		(width 0.254)
		(layer "F.Cu")
		(net "PVPP_ABC")
	)
	(segment
		(start 308.628288 -27.202384)
		(end 308.628288 -33.345628)
		(width 0.254)
		(layer "F.Cu")
		(net "PVPP_ABC")
	)
	(segment
		(start 317.058802 -24.995632)
		(end 310.83504 -24.995632)
		(width 0.254)
		(layer "F.Cu")
		(net "PVPP_ABC")
	)
	(segment
		(start 423.417238 -118.441978)
		(end 423.417238 -118.514876)
		(width 0.254)
		(layer "F.Cu")
		(net "PVPP_ABC")
	)
	(segment
		(start 413.512 -125.767084)
		(end 413.40532 -125.873764)
		(width 0.254)
		(layer "F.Cu")
		(net "PVPP_ABC")
	)
	(segment
		(start 423.103548 -118.128288)
		(end 423.417238 -118.441978)
		(width 0.254)
		(layer "F.Cu")
		(net "PVPP_ABC")
	)
	(segment
		(start 417.414964 -123.539504)
		(end 417.414964 -124.348494)
		(width 0.254)
		(layer "F.Cu")
		(net "PVPP_ABC")
	)
	(segment
		(start 359.5243 -89.0397)
		(end 362.358686 -86.205314)
		(width 0.254)
		(layer "F.Cu")
		(net "PVPP_ABC")
	)
	(segment
		(start 412.5722 -123.0376)
		(end 412.5722 -124.234702)
		(width 0.254)
		(layer "F.Cu")
		(net "PVPP_ABC")
	)
	(segment
		(start 315.498734 -37.336984)
		(end 316.73038 -36.105338)
		(width 0.254)
		(layer "F.Cu")
		(net "PVPP_ABC")
	)
	(segment
		(start 278.850344 -0.821182)
		(end 278.849836 -0.821182)
		(width 0.4064)
		(layer "F.Cu")
		(net "PVPP_ABC")
	)
	(segment
		(start 421.894 -117.4877)
		(end 421.005 -117.4877)
		(width 0.254)
		(layer "F.Cu")
		(net "PVPP_ABC")
	)
	(segment
		(start 360.553 -74.295)
		(end 348.44101 -74.295)
		(width 0.254)
		(layer "F.Cu")
		(net "PVPP_ABC")
	)
	(segment
		(start 316.73038 -36.105338)
		(end 316.73038 -34.936938)
		(width 0.254)
		(layer "F.Cu")
		(net "PVPP_ABC")
	)
	(segment
		(start 413.613854 -130.937)
		(end 411.784546 -130.937)
		(width 0.254)
		(layer "F.Cu")
		(net "PVPP_ABC")
	)
	(segment
		(start 413.403034 -128.99263)
		(end 413.527494 -129.11709)
		(width 0.254)
		(layer "F.Cu")
		(net "PVPP_ABC")
	)
	(segment
		(start 413.40532 -125.873764)
		(end 413.40532 -125.979682)
		(width 0.254)
		(layer "F.Cu")
		(net "PVPP_ABC")
	)
	(segment
		(start 416.61588 -122.74042)
		(end 417.414964 -123.539504)
		(width 0.254)
		(layer "F.Cu")
		(net "PVPP_ABC")
	)
	(segment
		(start 326.5043 -36.6903)
		(end 329.1078 -36.6903)
		(width 0.254)
		(layer "F.Cu")
		(net "PVPP_ABC")
	)
	(segment
		(start 413.40532 -125.979682)
		(end 413.403034 -125.981968)
		(width 0.254)
		(layer "F.Cu")
		(net "PVPP_ABC")
	)
	(segment
		(start 362.358686 -76.100686)
		(end 360.553 -74.295)
		(width 0.254)
		(layer "F.Cu")
		(net "PVPP_ABC")
	)
	(segment
		(start 314.171076 -37.194744)
		(end 314.624212 -37.194744)
		(width 0.254)
		(layer "F.Cu")
		(net "PVPP_ABC")
	)
	(segment
		(start 278.849836 -0.821182)
		(end 278.849836 -2.8194)
		(width 0.4064)
		(layer "F.Cu")
		(net "PVPP_ABC")
	)
	(segment
		(start 413.512 -125.174502)
		(end 413.512 -125.767084)
		(width 0.254)
		(layer "F.Cu")
		(net "PVPP_ABC")
	)
	(segment
		(start 413.527494 -129.124964)
		(end 413.901382 -129.498852)
		(width 0.254)
		(layer "F.Cu")
		(net "PVPP_ABC")
	)
	(segment
		(start 309.110126 -33.827466)
		(end 310.502554 -33.827466)
		(width 0.254)
		(layer "F.Cu")
		(net "PVPP_ABC")
	)
	(segment
		(start 428.651924 -127.238252)
		(end 428.572676 -127.3175)
		(width 0.254)
		(layer "F.Cu")
		(net "PVPP_ABC")
	)
	(segment
		(start 312.628788 -37.83203)
		(end 313.53379 -37.83203)
		(width 0.254)
		(layer "F.Cu")
		(net "PVPP_ABC")
	)
	(segment
		(start 415.191194 -122.74042)
		(end 412.86938 -122.74042)
		(width 0.254)
		(layer "F.Cu")
		(net "PVPP_ABC")
	)
	(segment
		(start 314.624212 -37.194744)
		(end 314.766452 -37.336984)
		(width 0.254)
		(layer "F.Cu")
		(net "PVPP_ABC")
	)
	(segment
		(start 310.756554 -35.959796)
		(end 312.628788 -37.83203)
		(width 0.254)
		(layer "F.Cu")
		(net "PVPP_ABC")
	)
	(segment
		(start 411.444694 -132.567172)
		(end 411.444694 -131.805172)
		(width 0.254)
		(layer "F.Cu")
		(net "PVPP_ABC")
	)
	(segment
		(start 324.866 -35.052)
		(end 326.5043 -36.6903)
		(width 0.254)
		(layer "F.Cu")
		(net "PVPP_ABC")
	)
	(segment
		(start 313.53379 -37.83203)
		(end 314.171076 -37.194744)
		(width 0.254)
		(layer "F.Cu")
		(net "PVPP_ABC")
	)
	(segment
		(start 413.403034 -125.981968)
		(end 413.403034 -128.99263)
		(width 0.254)
		(layer "F.Cu")
		(net "PVPP_ABC")
	)
	(segment
		(start 427.056042 -129.794)
		(end 426.5295 -129.794)
		(width 0.254)
		(layer "F.Cu")
		(net "PVPP_ABC")
	)
	(segment
		(start 314.766452 -37.336984)
		(end 315.498734 -37.336984)
		(width 0.254)
		(layer "F.Cu")
		(net "PVPP_ABC")
	)
	(segment
		(start 428.572676 -127.3175)
		(end 426.5295 -127.3175)
		(width 0.254)
		(layer "F.Cu")
		(net "PVPP_ABC")
	)
	(segment
		(start 413.527494 -129.11709)
		(end 413.527494 -129.124964)
		(width 0.254)
		(layer "F.Cu")
		(net "PVPP_ABC")
	)
	(segment
		(start 310.83504 -24.995632)
		(end 308.628288 -27.202384)
		(width 0.254)
		(layer "F.Cu")
		(net "PVPP_ABC")
	)
	(segment
		(start 427.1391 -129.710942)
		(end 427.056042 -129.794)
		(width 0.254)
		(layer "F.Cu")
		(net "PVPP_ABC")
	)
	(segment
		(start 411.444694 -131.276852)
		(end 411.444694 -131.805172)
		(width 0.254)
		(layer "F.Cu")
		(net "PVPP_ABC")
	)
	(segment
		(start 422.933622 -118.128288)
		(end 423.103548 -118.128288)
		(width 0.254)
		(layer "F.Cu")
		(net "PVPP_ABC")
	)
	(segment
		(start 411.784546 -130.937)
		(end 411.444694 -131.276852)
		(width 0.254)
		(layer "F.Cu")
		(net "PVPP_ABC")
	)
	(segment
		(start 412.86938 -122.74042)
		(end 412.5722 -123.0376)
		(width 0.254)
		(layer "F.Cu")
		(net "PVPP_ABC")
	)
	(segment
		(start 348.44101 -74.295)
		(end 346.772484 -72.626474)
		(width 0.254)
		(layer "F.Cu")
		(net "PVPP_ABC")
	)
	(segment
		(start 412.5722 -124.234702)
		(end 413.512 -125.174502)
		(width 0.254)
		(layer "F.Cu")
		(net "PVPP_ABC")
	)
	(segment
		(start 413.901382 -129.498852)
		(end 413.901382 -130.649472)
		(width 0.254)
		(layer "F.Cu")
		(net "PVPP_ABC")
	)
	(via
		(at 319.649856 -9.158478)
		(size 0.508)
		(drill 0.254)
		(layers "F.Cu" "B.Cu")
		(net "PVPP_ABC")
	)
	(via
		(at 320.499994 -11.927078)
		(size 0.508)
		(drill 0.254)
		(layers "F.Cu" "B.Cu")
		(net "PVPP_ABC")
	)
	(via
		(at 320.499994 -16.687546)
		(size 0.508)
		(drill 0.254)
		(layers "F.Cu" "B.Cu")
		(net "PVPP_ABC")
	)
	(via
		(at 278.849836 -2.8194)
		(size 0.508)
		(drill 0.254)
		(layers "F.Cu" "B.Cu")
		(net "PVPP_ABC")
	)
	(via
		(at 301.812706 -51.370738)
		(size 0.508)
		(drill 0.254)
		(layers "F.Cu" "B.Cu")
		(net "PVPP_ABC")
	)
	(via
		(at 321.349878 0.442722)
		(size 0.508)
		(drill 0.254)
		(layers "F.Cu" "B.Cu")
		(net "PVPP_ABC")
	)
	(via
		(at 346.772484 -72.626474)
		(size 0.508)
		(drill 0.254)
		(layers "F.Cu" "B.Cu")
		(net "PVPP_ABC")
	)
	(via
		(at 321.349878 -18.759678)
		(size 0.508)
		(drill 0.254)
		(layers "F.Cu" "B.Cu")
		(net "PVPP_ABC")
	)
	(via
		(at 355.3714 -42.3926)
		(size 0.508)
		(drill 0.254)
		(layers "F.Cu" "B.Cu")
		(net "PVPP_ABC")
	)
	(via
		(at 359.5243 -89.0397)
		(size 0.508)
		(drill 0.254)
		(layers "F.Cu" "B.Cu")
		(net "PVPP_ABC")
	)
	(via
		(at 319.649856 -4.317746)
		(size 0.508)
		(drill 0.254)
		(layers "F.Cu" "B.Cu")
		(net "PVPP_ABC")
	)
	(via
		(at 326.673464 -29.446728)
		(size 0.508)
		(drill 0.254)
		(layers "F.Cu" "B.Cu")
		(net "PVPP_ABC")
	)
	(via
		(at 321.349878 -9.158478)
		(size 0.508)
		(drill 0.254)
		(layers "F.Cu" "B.Cu")
		(net "PVPP_ABC")
	)
	(via
		(at 330.841604 -30.251908)
		(size 0.508)
		(drill 0.254)
		(layers "F.Cu" "B.Cu")
		(net "PVPP_ABC")
	)
	(via
		(at 317.949834 -21.528278)
		(size 0.508)
		(drill 0.254)
		(layers "F.Cu" "B.Cu")
		(net "PVPP_ABC")
	)
	(via
		(at 329.077574 -24.71928)
		(size 0.508)
		(drill 0.254)
		(layers "F.Cu" "B.Cu")
		(net "PVPP_ABC")
	)
	(via
		(at 417.29152 -124.471938)
		(size 0.508)
		(drill 0.254)
		(layers "F.Cu" "B.Cu")
		(net "PVPP_ABC")
	)
	(via
		(at 321.349878 -21.528278)
		(size 0.508)
		(drill 0.254)
		(layers "F.Cu" "B.Cu")
		(net "PVPP_ABC")
	)
	(via
		(at 319.649856 -7.086346)
		(size 0.508)
		(drill 0.254)
		(layers "F.Cu" "B.Cu")
		(net "PVPP_ABC")
	)
	(via
		(at 319.649856 0.442722)
		(size 0.508)
		(drill 0.254)
		(layers "F.Cu" "B.Cu")
		(net "PVPP_ABC")
	)
	(via
		(at 328.010774 -24.71928)
		(size 0.508)
		(drill 0.254)
		(layers "F.Cu" "B.Cu")
		(net "PVPP_ABC")
	)
	(via
		(at 317.949834 -7.086346)
		(size 0.508)
		(drill 0.254)
		(layers "F.Cu" "B.Cu")
		(net "PVPP_ABC")
	)
	(via
		(at 320.30162 -26.7589)
		(size 0.508)
		(drill 0.254)
		(layers "F.Cu" "B.Cu")
		(net "PVPP_ABC")
	)
	(via
		(at 321.1957 -29.12618)
		(size 0.508)
		(drill 0.254)
		(layers "F.Cu" "B.Cu")
		(net "PVPP_ABC")
	)
	(via
		(at 319.649856 -23.520146)
		(size 0.508)
		(drill 0.254)
		(layers "F.Cu" "B.Cu")
		(net "PVPP_ABC")
	)
	(via
		(at 319.649856 -13.918946)
		(size 0.508)
		(drill 0.254)
		(layers "F.Cu" "B.Cu")
		(net "PVPP_ABC")
	)
	(via
		(at 320.499994 -21.528278)
		(size 0.508)
		(drill 0.254)
		(layers "F.Cu" "B.Cu")
		(net "PVPP_ABC")
	)
	(via
		(at 326.673464 -30.208728)
		(size 0.508)
		(drill 0.254)
		(layers "F.Cu" "B.Cu")
		(net "PVPP_ABC")
	)
	(via
		(at 320.499994 -18.759678)
		(size 0.508)
		(drill 0.254)
		(layers "F.Cu" "B.Cu")
		(net "PVPP_ABC")
	)
	(via
		(at 317.09995 -4.332478)
		(size 0.508)
		(drill 0.254)
		(layers "F.Cu" "B.Cu")
		(net "PVPP_ABC")
	)
	(via
		(at 320.499994 -13.918946)
		(size 0.508)
		(drill 0.254)
		(layers "F.Cu" "B.Cu")
		(net "PVPP_ABC")
	)
	(via
		(at 300.095666 -51.446938)
		(size 0.508)
		(drill 0.254)
		(layers "F.Cu" "B.Cu")
		(net "PVPP_ABC")
	)
	(via
		(at 428.651924 -127.238252)
		(size 0.508)
		(drill 0.254)
		(layers "F.Cu" "B.Cu")
		(net "PVPP_ABC")
	)
	(via
		(at 321.349878 -2.325878)
		(size 0.508)
		(drill 0.254)
		(layers "F.Cu" "B.Cu")
		(net "PVPP_ABC")
	)
	(via
		(at 330.836016 -28.3718)
		(size 0.508)
		(drill 0.254)
		(layers "F.Cu" "B.Cu")
		(net "PVPP_ABC")
	)
	(via
		(at 317.949834 -9.158478)
		(size 0.508)
		(drill 0.254)
		(layers "F.Cu" "B.Cu")
		(net "PVPP_ABC")
	)
	(via
		(at 317.09995 -23.534878)
		(size 0.508)
		(drill 0.254)
		(layers "F.Cu" "B.Cu")
		(net "PVPP_ABC")
	)
	(via
		(at 320.499994 2.514854)
		(size 0.508)
		(drill 0.254)
		(layers "F.Cu" "B.Cu")
		(net "PVPP_ABC")
	)
	(via
		(at 425.9072 -122.8852)
		(size 0.508)
		(drill 0.254)
		(layers "F.Cu" "B.Cu")
		(net "PVPP_ABC")
	)
	(via
		(at 324.3834 -29.1592)
		(size 0.508)
		(drill 0.254)
		(layers "F.Cu" "B.Cu")
		(net "PVPP_ABC")
	)
	(via
		(at 320.499994 -23.520146)
		(size 0.508)
		(drill 0.254)
		(layers "F.Cu" "B.Cu")
		(net "PVPP_ABC")
	)
	(via
		(at 319.649856 -2.325878)
		(size 0.508)
		(drill 0.254)
		(layers "F.Cu" "B.Cu")
		(net "PVPP_ABC")
	)
	(via
		(at 317.949834 -2.325878)
		(size 0.508)
		(drill 0.254)
		(layers "F.Cu" "B.Cu")
		(net "PVPP_ABC")
	)
	(via
		(at 317.09995 -13.933678)
		(size 0.508)
		(drill 0.254)
		(layers "F.Cu" "B.Cu")
		(net "PVPP_ABC")
	)
	(via
		(at 299.237146 -51.941984)
		(size 0.508)
		(drill 0.254)
		(layers "F.Cu" "B.Cu")
		(net "PVPP_ABC")
	)
	(via
		(at 317.949834 -13.918946)
		(size 0.508)
		(drill 0.254)
		(layers "F.Cu" "B.Cu")
		(net "PVPP_ABC")
	)
	(via
		(at 317.949834 0.442722)
		(size 0.508)
		(drill 0.254)
		(layers "F.Cu" "B.Cu")
		(net "PVPP_ABC")
	)
	(via
		(at 320.499994 -9.158478)
		(size 0.508)
		(drill 0.254)
		(layers "F.Cu" "B.Cu")
		(net "PVPP_ABC")
	)
	(via
		(at 320.294 -2.3114)
		(size 0.508)
		(drill 0.254)
		(layers "F.Cu" "B.Cu")
		(net "PVPP_ABC")
	)
	(via
		(at 319.649856 2.514854)
		(size 0.508)
		(drill 0.254)
		(layers "F.Cu" "B.Cu")
		(net "PVPP_ABC")
	)
	(via
		(at 320.499994 0.442722)
		(size 0.508)
		(drill 0.254)
		(layers "F.Cu" "B.Cu")
		(net "PVPP_ABC")
	)
	(via
		(at 321.349878 -11.927078)
		(size 0.508)
		(drill 0.254)
		(layers "F.Cu" "B.Cu")
		(net "PVPP_ABC")
	)
	(via
		(at 320.499994 -7.086346)
		(size 0.508)
		(drill 0.254)
		(layers "F.Cu" "B.Cu")
		(net "PVPP_ABC")
	)
	(via
		(at 423.589196 -118.686834)
		(size 0.508)
		(drill 0.254)
		(layers "F.Cu" "B.Cu")
		(net "PVPP_ABC")
	)
	(via
		(at 319.649856 -21.528278)
		(size 0.508)
		(drill 0.254)
		(layers "F.Cu" "B.Cu")
		(net "PVPP_ABC")
	)
	(via
		(at 298.378626 -51.446938)
		(size 0.508)
		(drill 0.254)
		(layers "F.Cu" "B.Cu")
		(net "PVPP_ABC")
	)
	(via
		(at 328.5998 -30.9372)
		(size 0.508)
		(drill 0.254)
		(layers "F.Cu" "B.Cu")
		(net "PVPP_ABC")
	)
	(via
		(at 330.836016 -29.0322)
		(size 0.508)
		(drill 0.254)
		(layers "F.Cu" "B.Cu")
		(net "PVPP_ABC")
	)
	(via
		(at 317.949834 -18.759678)
		(size 0.508)
		(drill 0.254)
		(layers "F.Cu" "B.Cu")
		(net "PVPP_ABC")
	)
	(via
		(at 319.649856 -18.759678)
		(size 0.508)
		(drill 0.254)
		(layers "F.Cu" "B.Cu")
		(net "PVPP_ABC")
	)
	(via
		(at 338.283296 -53.098954)
		(size 0.508)
		(drill 0.254)
		(layers "F.Cu" "B.Cu")
		(net "PVPP_ABC")
	)
	(via
		(at 329.1078 -36.6903)
		(size 0.508)
		(drill 0.254)
		(layers "F.Cu" "B.Cu")
		(net "PVPP_ABC")
	)
	(via
		(at 327.248774 -24.71928)
		(size 0.508)
		(drill 0.254)
		(layers "F.Cu" "B.Cu")
		(net "PVPP_ABC")
	)
	(via
		(at 330.836016 -29.6418)
		(size 0.508)
		(drill 0.254)
		(layers "F.Cu" "B.Cu")
		(net "PVPP_ABC")
	)
	(via
		(at 427.1391 -129.710942)
		(size 0.508)
		(drill 0.254)
		(layers "F.Cu" "B.Cu")
		(net "PVPP_ABC")
	)
	(via
		(at 317.949834 -11.927078)
		(size 0.508)
		(drill 0.254)
		(layers "F.Cu" "B.Cu")
		(net "PVPP_ABC")
	)
	(via
		(at 319.649856 -16.687546)
		(size 0.508)
		(drill 0.254)
		(layers "F.Cu" "B.Cu")
		(net "PVPP_ABC")
	)
	(via
		(at 320.499994 -4.317746)
		(size 0.508)
		(drill 0.254)
		(layers "F.Cu" "B.Cu")
		(net "PVPP_ABC")
	)
	(via
		(at 319.649856 -11.927078)
		(size 0.508)
		(drill 0.254)
		(layers "F.Cu" "B.Cu")
		(net "PVPP_ABC")
	)
	(segment
		(start 278.849836 -1.021842)
		(end 278.849836 -2.8194)
		(width 0.4064)
		(layer "B.Cu")
		(net "PVPP_ABC")
	)
	(segment
		(start 278.850344 -1.021842)
		(end 278.849836 -1.021842)
		(width 0.4064)
		(layer "B.Cu")
		(net "PVPP_ABC")
	)
	(segment
		(start 351.552764 -49.774348)
		(end 341.309706 -49.774348)
		(width 0.254)
		(layer "B.Cu")
		(net "PVPP_ABC")
	)
	(segment
		(start 338.283296 -52.800758)
		(end 338.283296 -53.098954)
		(width 0.254)
		(layer "B.Cu")
		(net "PVPP_ABC")
	)
	(segment
		(start 355.3714 -45.955712)
		(end 351.552764 -49.774348)
		(width 0.254)
		(layer "B.Cu")
		(net "PVPP_ABC")
	)
	(segment
		(start 341.309706 -49.774348)
		(end 338.283296 -52.800758)
		(width 0.254)
		(layer "B.Cu")
		(net "PVPP_ABC")
	)
	(segment
		(start 355.3714 -42.3926)
		(end 355.3714 -45.955712)
		(width 0.254)
		(layer "B.Cu")
		(net "PVPP_ABC")
	)
	(segment
		(start 427.1391 -127.9525)
		(end 427.1391 -129.710942)
		(width 0.508)
		(layer "In2.Cu")
		(net "PVPP_ABC")
	)
	(segment
		(start 278.849836 -2.264664)
		(end 279.37206 -1.74244)
		(width 0.4064)
		(layer "In2.Cu")
		(net "PVPP_ABC")
	)
	(segment
		(start 317.31458 -1.74244)
		(end 317.898018 -2.325878)
		(width 0.4064)
		(layer "In2.Cu")
		(net "PVPP_ABC")
	)
	(segment
		(start 428.651924 -127.238252)
		(end 427.853348 -127.238252)
		(width 0.508)
		(layer "In2.Cu")
		(net "PVPP_ABC")
	)
	(segment
		(start 278.849836 -2.8194)
		(end 278.849836 -2.264664)
		(width 0.4064)
		(layer "In2.Cu")
		(net "PVPP_ABC")
	)
	(segment
		(start 427.853348 -127.238252)
		(end 427.1391 -127.9525)
		(width 0.508)
		(layer "In2.Cu")
		(net "PVPP_ABC")
	)
	(segment
		(start 279.37206 -1.74244)
		(end 317.31458 -1.74244)
		(width 0.4064)
		(layer "In2.Cu")
		(net "PVPP_ABC")
	)
	(segment
		(start 317.898018 -2.325878)
		(end 317.949834 -2.325878)
		(width 0.4064)
		(layer "In2.Cu")
		(net "PVPP_ABC")
	)
	(segment
		(start 362.3437 -112.583468)
		(end 362.777532 -113.0173)
		(width 0.254)
		(layer "In4.Cu")
		(net "PVPP_ABC")
	)
	(segment
		(start 364.2614 -118.1862)
		(end 363.520482 -118.927118)
		(width 0.254)
		(layer "In4.Cu")
		(net "PVPP_ABC")
	)
	(segment
		(start 423.589958 -120.634506)
		(end 423.589958 -118.686834)
		(width 0.254)
		(layer "In4.Cu")
		(net "PVPP_ABC")
	)
	(segment
		(start 374.933464 -126.087632)
		(end 379.718062 -126.087632)
		(width 0.254)
		(layer "In4.Cu")
		(net "PVPP_ABC")
	)
	(segment
		(start 406.69845 -127.533654)
		(end 408.09926 -126.953518)
		(width 0.254)
		(layer "In4.Cu")
		(net "PVPP_ABC")
	)
	(segment
		(start 363.9185 -113.0173)
		(end 364.2614 -113.3602)
		(width 0.254)
		(layer "In4.Cu")
		(net "PVPP_ABC")
	)
	(segment
		(start 365.262414 -126.67615)
		(end 371.294914 -126.67615)
		(width 0.254)
		(layer "In4.Cu")
		(net "PVPP_ABC")
	)
	(segment
		(start 414.221168 -125.349)
		(end 416.751262 -125.349)
		(width 0.254)
		(layer "In4.Cu")
		(net "PVPP_ABC")
	)
	(segment
		(start 414.220152 -125.350016)
		(end 414.221168 -125.349)
		(width 0.254)
		(layer "In4.Cu")
		(net "PVPP_ABC")
	)
	(segment
		(start 359.5243 -89.0397)
		(end 358.276398 -90.287602)
		(width 0.254)
		(layer "In4.Cu")
		(net "PVPP_ABC")
	)
	(segment
		(start 417.252404 -124.847858)
		(end 417.252404 -124.511054)
		(width 0.254)
		(layer "In4.Cu")
		(net "PVPP_ABC")
	)
	(segment
		(start 358.276398 -97.009458)
		(end 360.074718 -98.807778)
		(width 0.254)
		(layer "In4.Cu")
		(net "PVPP_ABC")
	)
	(segment
		(start 422.715182 -124.1806)
		(end 424.869864 -124.1806)
		(width 0.254)
		(layer "In4.Cu")
		(net "PVPP_ABC")
	)
	(segment
		(start 361.922822 -105.095294)
		(end 361.922822 -109.735874)
		(width 0.254)
		(layer "In4.Cu")
		(net "PVPP_ABC")
	)
	(segment
		(start 374.567958 -126.453138)
		(end 374.933464 -126.087632)
		(width 0.254)
		(layer "In4.Cu")
		(net "PVPP_ABC")
	)
	(segment
		(start 417.29152 -124.471938)
		(end 417.682172 -124.86259)
		(width 0.254)
		(layer "In4.Cu")
		(net "PVPP_ABC")
	)
	(segment
		(start 371.632226 -126.338838)
		(end 373.182642 -126.338838)
		(width 0.254)
		(layer "In4.Cu")
		(net "PVPP_ABC")
	)
	(segment
		(start 361.922822 -109.735874)
		(end 362.3437 -110.156752)
		(width 0.254)
		(layer "In4.Cu")
		(net "PVPP_ABC")
	)
	(segment
		(start 401.795996 -127.533654)
		(end 406.69845 -127.533654)
		(width 0.254)
		(layer "In4.Cu")
		(net "PVPP_ABC")
	)
	(segment
		(start 358.276398 -90.287602)
		(end 358.276398 -97.009458)
		(width 0.254)
		(layer "In4.Cu")
		(net "PVPP_ABC")
	)
	(segment
		(start 425.9072 -123.143264)
		(end 425.9072 -122.8852)
		(width 0.254)
		(layer "In4.Cu")
		(net "PVPP_ABC")
	)
	(segment
		(start 360.074718 -103.24719)
		(end 361.922822 -105.095294)
		(width 0.254)
		(layer "In4.Cu")
		(net "PVPP_ABC")
	)
	(segment
		(start 328.5998 -30.9372)
		(end 328.5998 -36.1823)
		(width 0.508)
		(layer "In4.Cu")
		(net "PVPP_ABC")
	)
	(segment
		(start 411.164278 -125.171454)
		(end 411.850332 -124.4854)
		(width 0.254)
		(layer "In4.Cu")
		(net "PVPP_ABC")
	)
	(segment
		(start 363.520482 -118.927118)
		(end 363.520482 -125.22835)
		(width 0.254)
		(layer "In4.Cu")
		(net "PVPP_ABC")
	)
	(segment
		(start 388.291578 -129.976626)
		(end 389.07085 -130.755898)
		(width 0.254)
		(layer "In4.Cu")
		(net "PVPP_ABC")
	)
	(segment
		(start 362.777532 -113.0173)
		(end 363.9185 -113.0173)
		(width 0.254)
		(layer "In4.Cu")
		(net "PVPP_ABC")
	)
	(segment
		(start 373.296942 -126.453138)
		(end 374.567958 -126.453138)
		(width 0.254)
		(layer "In4.Cu")
		(net "PVPP_ABC")
	)
	(segment
		(start 425.9072 -122.8852)
		(end 425.840652 -122.8852)
		(width 0.254)
		(layer "In4.Cu")
		(net "PVPP_ABC")
	)
	(segment
		(start 387.641338 -125.388624)
		(end 388.291578 -126.038864)
		(width 0.254)
		(layer "In4.Cu")
		(net "PVPP_ABC")
	)
	(segment
		(start 425.840652 -122.8852)
		(end 423.589958 -120.634506)
		(width 0.254)
		(layer "In4.Cu")
		(net "PVPP_ABC")
	)
	(segment
		(start 408.09926 -126.953518)
		(end 409.881324 -125.171454)
		(width 0.254)
		(layer "In4.Cu")
		(net "PVPP_ABC")
	)
	(segment
		(start 363.520482 -125.22835)
		(end 364.893098 -126.600966)
		(width 0.254)
		(layer "In4.Cu")
		(net "PVPP_ABC")
	)
	(segment
		(start 328.5998 -36.1823)
		(end 329.1078 -36.6903)
		(width 0.508)
		(layer "In4.Cu")
		(net "PVPP_ABC")
	)
	(segment
		(start 371.294914 -126.67615)
		(end 371.632226 -126.338838)
		(width 0.254)
		(layer "In4.Cu")
		(net "PVPP_ABC")
	)
	(segment
		(start 362.3437 -110.156752)
		(end 362.3437 -112.583468)
		(width 0.254)
		(layer "In4.Cu")
		(net "PVPP_ABC")
	)
	(segment
		(start 380.41707 -125.388624)
		(end 387.641338 -125.388624)
		(width 0.254)
		(layer "In4.Cu")
		(net "PVPP_ABC")
	)
	(segment
		(start 424.869864 -124.1806)
		(end 425.9072 -123.143264)
		(width 0.254)
		(layer "In4.Cu")
		(net "PVPP_ABC")
	)
	(segment
		(start 416.751262 -125.349)
		(end 417.252404 -124.847858)
		(width 0.254)
		(layer "In4.Cu")
		(net "PVPP_ABC")
	)
	(segment
		(start 389.07085 -130.755898)
		(end 398.573752 -130.755898)
		(width 0.254)
		(layer "In4.Cu")
		(net "PVPP_ABC")
	)
	(segment
		(start 360.074718 -98.807778)
		(end 360.074718 -103.24719)
		(width 0.254)
		(layer "In4.Cu")
		(net "PVPP_ABC")
	)
	(segment
		(start 364.893098 -126.600966)
		(end 365.262414 -126.67615)
		(width 0.254)
		(layer "In4.Cu")
		(net "PVPP_ABC")
	)
	(segment
		(start 398.573752 -130.755898)
		(end 401.795996 -127.533654)
		(width 0.254)
		(layer "In4.Cu")
		(net "PVPP_ABC")
	)
	(segment
		(start 412.732982 -124.4854)
		(end 413.597598 -125.350016)
		(width 0.254)
		(layer "In4.Cu")
		(net "PVPP_ABC")
	)
	(segment
		(start 422.033192 -124.86259)
		(end 422.715182 -124.1806)
		(width 0.254)
		(layer "In4.Cu")
		(net "PVPP_ABC")
	)
	(segment
		(start 379.718062 -126.087632)
		(end 380.41707 -125.388624)
		(width 0.254)
		(layer "In4.Cu")
		(net "PVPP_ABC")
	)
	(segment
		(start 413.597598 -125.350016)
		(end 414.220152 -125.350016)
		(width 0.254)
		(layer "In4.Cu")
		(net "PVPP_ABC")
	)
	(segment
		(start 423.589958 -118.686834)
		(end 423.589196 -118.686834)
		(width 0.254)
		(layer "In4.Cu")
		(net "PVPP_ABC")
	)
	(segment
		(start 411.850332 -124.4854)
		(end 412.732982 -124.4854)
		(width 0.254)
		(layer "In4.Cu")
		(net "PVPP_ABC")
	)
	(segment
		(start 388.291578 -126.038864)
		(end 388.291578 -129.976626)
		(width 0.254)
		(layer "In4.Cu")
		(net "PVPP_ABC")
	)
	(segment
		(start 373.182642 -126.338838)
		(end 373.296942 -126.453138)
		(width 0.254)
		(layer "In4.Cu")
		(net "PVPP_ABC")
	)
	(segment
		(start 409.881324 -125.171454)
		(end 411.164278 -125.171454)
		(width 0.254)
		(layer "In4.Cu")
		(net "PVPP_ABC")
	)
	(segment
		(start 417.252404 -124.511054)
		(end 417.29152 -124.471938)
		(width 0.254)
		(layer "In4.Cu")
		(net "PVPP_ABC")
	)
	(segment
		(start 417.682172 -124.86259)
		(end 422.033192 -124.86259)
		(width 0.254)
		(layer "In4.Cu")
		(net "PVPP_ABC")
	)
	(segment
		(start 364.2614 -113.3602)
		(end 364.2614 -118.1862)
		(width 0.254)
		(layer "In4.Cu")
		(net "PVPP_ABC")
	)
	(segment
		(start 333.83728 -73.458832)
		(end 334.372458 -73.458832)
		(width 0.254)
		(layer "In9.Cu")
		(net "PVPP_ABC")
	)
	(segment
		(start 343.027 -72.377046)
		(end 343.027 -72.590152)
		(width 0.254)
		(layer "In9.Cu")
		(net "PVPP_ABC")
	)
	(segment
		(start 343.568528 -72.918574)
		(end 346.480384 -72.918574)
		(width 0.254)
		(layer "In9.Cu")
		(net "PVPP_ABC")
	)
	(segment
		(start 355.517704 -38.92677)
		(end 356.267004 -38.92677)
		(width 0.254)
		(layer "In9.Cu")
		(net "PVPP_ABC")
	)
	(segment
		(start 338.8614 -58.3438)
		(end 338.8614 -60.8076)
		(width 0.254)
		(layer "In9.Cu")
		(net "PVPP_ABC")
	)
	(segment
		(start 331.410564 -30.820868)
		(end 330.841604 -30.251908)
		(width 0.254)
		(layer "In9.Cu")
		(net "PVPP_ABC")
	)
	(segment
		(start 354.6348 -39.809674)
		(end 355.517704 -38.92677)
		(width 0.254)
		(layer "In9.Cu")
		(net "PVPP_ABC")
	)
	(segment
		(start 343.027 -72.590152)
		(end 343.309448 -72.8726)
		(width 0.254)
		(layer "In9.Cu")
		(net "PVPP_ABC")
	)
	(segment
		(start 354.6348 -41.656)
		(end 354.6348 -39.809674)
		(width 0.254)
		(layer "In9.Cu")
		(net "PVPP_ABC")
	)
	(segment
		(start 333.372968 -37.03955)
		(end 333.372968 -35.979608)
		(width 0.254)
		(layer "In9.Cu")
		(net "PVPP_ABC")
	)
	(segment
		(start 356.431342 -37.269166)
		(end 353.52482 -37.269166)
		(width 0.254)
		(layer "In9.Cu")
		(net "PVPP_ABC")
	)
	(segment
		(start 334.372458 -73.458832)
		(end 335.315052 -72.516238)
		(width 0.254)
		(layer "In9.Cu")
		(net "PVPP_ABC")
	)
	(segment
		(start 335.315052 -72.516238)
		(end 337.490562 -72.516238)
		(width 0.254)
		(layer "In9.Cu")
		(net "PVPP_ABC")
	)
	(segment
		(start 356.685342 -37.523166)
		(end 356.431342 -37.269166)
		(width 0.254)
		(layer "In9.Cu")
		(net "PVPP_ABC")
	)
	(segment
		(start 340.095586 -54.507384)
		(end 340.095586 -57.109614)
		(width 0.254)
		(layer "In9.Cu")
		(net "PVPP_ABC")
	)
	(segment
		(start 342.124538 -71.474584)
		(end 343.027 -72.377046)
		(width 0.254)
		(layer "In9.Cu")
		(net "PVPP_ABC")
	)
	(segment
		(start 338.283296 -53.780944)
		(end 338.537296 -54.034944)
		(width 0.254)
		(layer "In9.Cu")
		(net "PVPP_ABC")
	)
	(segment
		(start 338.283296 -53.098954)
		(end 338.283296 -53.780944)
		(width 0.254)
		(layer "In9.Cu")
		(net "PVPP_ABC")
	)
	(segment
		(start 333.803752 -37.470334)
		(end 333.372968 -37.03955)
		(width 0.254)
		(layer "In9.Cu")
		(net "PVPP_ABC")
	)
	(segment
		(start 338.537296 -54.034944)
		(end 339.623146 -54.034944)
		(width 0.254)
		(layer "In9.Cu")
		(net "PVPP_ABC")
	)
	(segment
		(start 343.309448 -72.8726)
		(end 343.522554 -72.8726)
		(width 0.254)
		(layer "In9.Cu")
		(net "PVPP_ABC")
	)
	(segment
		(start 353.52482 -37.269166)
		(end 353.323652 -37.470334)
		(width 0.254)
		(layer "In9.Cu")
		(net "PVPP_ABC")
	)
	(segment
		(start 338.532216 -71.474584)
		(end 342.124538 -71.474584)
		(width 0.254)
		(layer "In9.Cu")
		(net "PVPP_ABC")
	)
	(segment
		(start 333.372968 -35.979608)
		(end 331.410564 -34.017204)
		(width 0.254)
		(layer "In9.Cu")
		(net "PVPP_ABC")
	)
	(segment
		(start 356.267004 -38.92677)
		(end 356.685342 -38.508432)
		(width 0.254)
		(layer "In9.Cu")
		(net "PVPP_ABC")
	)
	(segment
		(start 343.522554 -72.8726)
		(end 343.568528 -72.918574)
		(width 0.254)
		(layer "In9.Cu")
		(net "PVPP_ABC")
	)
	(segment
		(start 340.095586 -57.109614)
		(end 338.8614 -58.3438)
		(width 0.254)
		(layer "In9.Cu")
		(net "PVPP_ABC")
	)
	(segment
		(start 337.490562 -72.516238)
		(end 338.532216 -71.474584)
		(width 0.254)
		(layer "In9.Cu")
		(net "PVPP_ABC")
	)
	(segment
		(start 334.912462 -66.063114)
		(end 333.244698 -67.730878)
		(width 0.254)
		(layer "In9.Cu")
		(net "PVPP_ABC")
	)
	(segment
		(start 334.912462 -64.756538)
		(end 334.912462 -66.063114)
		(width 0.254)
		(layer "In9.Cu")
		(net "PVPP_ABC")
	)
	(segment
		(start 333.244698 -67.730878)
		(end 333.244698 -72.86625)
		(width 0.254)
		(layer "In9.Cu")
		(net "PVPP_ABC")
	)
	(segment
		(start 338.8614 -60.8076)
		(end 334.912462 -64.756538)
		(width 0.254)
		(layer "In9.Cu")
		(net "PVPP_ABC")
	)
	(segment
		(start 331.410564 -34.017204)
		(end 331.410564 -30.820868)
		(width 0.254)
		(layer "In9.Cu")
		(net "PVPP_ABC")
	)
	(segment
		(start 346.480384 -72.918574)
		(end 346.772484 -72.626474)
		(width 0.254)
		(layer "In9.Cu")
		(net "PVPP_ABC")
	)
	(segment
		(start 355.3714 -42.3926)
		(end 354.6348 -41.656)
		(width 0.254)
		(layer "In9.Cu")
		(net "PVPP_ABC")
	)
	(segment
		(start 339.623146 -54.034944)
		(end 340.095586 -54.507384)
		(width 0.254)
		(layer "In9.Cu")
		(net "PVPP_ABC")
	)
	(segment
		(start 356.685342 -38.508432)
		(end 356.685342 -37.523166)
		(width 0.254)
		(layer "In9.Cu")
		(net "PVPP_ABC")
	)
	(segment
		(start 333.244698 -72.86625)
		(end 333.83728 -73.458832)
		(width 0.254)
		(layer "In9.Cu")
		(net "PVPP_ABC")
	)
	(segment
		(start 353.323652 -37.470334)
		(end 333.803752 -37.470334)
		(width 0.254)
		(layer "In9.Cu")
		(net "PVPP_ABC")
	)
	(segment
		(start 100.372164 -100.167186)
		(end 99.800664 -99.17684)
		(width 0.254)
		(layer "F.Cu")
		(net "PVDDQ_KLM")
	)
	(segment
		(start 112.149382 -148.769578)
		(end 112.149382 -147.27174)
		(width 0.508)
		(layer "F.Cu")
		(net "PVDDQ_KLM")
	)
	(segment
		(start 80.92948 -131.13258)
		(end 80.92948 -132.033518)
		(width 0.4064)
		(layer "F.Cu")
		(net "PVDDQ_KLM")
	)
	(segment
		(start 80.699356 -141.187678)
		(end 80.699356 -142.6718)
		(width 0.508)
		(layer "F.Cu")
		(net "PVDDQ_KLM")
	)
	(segment
		(start 110.44936 -133.0706)
		(end 110.44936 -131.611878)
		(width 0.4064)
		(layer "F.Cu")
		(net "PVDDQ_KLM")
	)
	(segment
		(start 88.349582 -141.187678)
		(end 88.349582 -142.6718)
		(width 0.508)
		(layer "F.Cu")
		(net "PVDDQ_KLM")
	)
	(segment
		(start 106.199432 -142.6718)
		(end 106.199432 -143.968978)
		(width 0.508)
		(layer "F.Cu")
		(net "PVDDQ_KLM")
	)
	(segment
		(start 106.199432 -142.6718)
		(end 106.199432 -141.183868)
		(width 0.508)
		(layer "F.Cu")
		(net "PVDDQ_KLM")
	)
	(segment
		(start 112.149382 -139.168378)
		(end 112.149382 -137.67054)
		(width 0.508)
		(layer "F.Cu")
		(net "PVDDQ_KLM")
	)
	(segment
		(start 95.221298 -100.167186)
		(end 95.508318 -99.67214)
		(width 0.254)
		(layer "F.Cu")
		(net "PVDDQ_KLM")
	)
	(segment
		(start 93.449394 -147.27174)
		(end 93.449394 -146.131026)
		(width 0.4064)
		(layer "F.Cu")
		(net "PVDDQ_KLM")
	)
	(segment
		(start 106.199432 -148.742146)
		(end 106.199432 -147.27174)
		(width 0.508)
		(layer "F.Cu")
		(net "PVDDQ_KLM")
	)
	(segment
		(start 93.504258 -100.167186)
		(end 93.698568 -99.83216)
		(width 0.254)
		(layer "F.Cu")
		(net "PVDDQ_KLM")
	)
	(segment
		(start 112.149382 -136.387078)
		(end 112.149382 -137.67054)
		(width 0.508)
		(layer "F.Cu")
		(net "PVDDQ_KLM")
	)
	(segment
		(start 98.655378 -94.223586)
		(end 98.083878 -94.223586)
		(width 0.254)
		(layer "F.Cu")
		(net "PVDDQ_KLM")
	)
	(segment
		(start 101.949504 -141.183868)
		(end 101.949504 -142.6718)
		(width 0.508)
		(layer "F.Cu")
		(net "PVDDQ_KLM")
	)
	(segment
		(start 90.070178 -100.167186)
		(end 90.357198 -99.67214)
		(width 0.254)
		(layer "F.Cu")
		(net "PVDDQ_KLM")
	)
	(segment
		(start 112.149382 -131.586478)
		(end 112.149382 -133.0706)
		(width 0.4064)
		(layer "F.Cu")
		(net "PVDDQ_KLM")
	)
	(segment
		(start 90.899488 -147.27174)
		(end 90.899488 -148.556218)
		(width 0.508)
		(layer "F.Cu")
		(net "PVDDQ_KLM")
	)
	(segment
		(start 97.254568 -130.367024)
		(end 96.746568 -129.859024)
		(width 0.508)
		(layer "F.Cu")
		(net "PVDDQ_KLM")
	)
	(segment
		(start 108.749338 -154.252168)
		(end 108.749338 -152.273)
		(width 0.508)
		(layer "F.Cu")
		(net "PVDDQ_KLM")
	)
	(segment
		(start 101.099366 -147.27174)
		(end 101.099366 -145.988278)
		(width 0.508)
		(layer "F.Cu")
		(net "PVDDQ_KLM")
	)
	(segment
		(start 108.749338 -150.789386)
		(end 108.749846 -150.788878)
		(width 0.381)
		(layer "F.Cu")
		(net "PVDDQ_KLM")
	)
	(segment
		(start 104.49941 -141.187932)
		(end 104.49941 -142.6718)
		(width 0.508)
		(layer "F.Cu")
		(net "PVDDQ_KLM")
	)
	(segment
		(start 101.949504 -152.273)
		(end 101.949504 -150.785068)
		(width 0.508)
		(layer "F.Cu")
		(net "PVDDQ_KLM")
	)
	(segment
		(start 88.353392 -94.223586)
		(end 87.781892 -94.223586)
		(width 0.254)
		(layer "F.Cu")
		(net "PVDDQ_KLM")
	)
	(segment
		(start 88.349582 -131.611878)
		(end 88.349582 -133.0706)
		(width 0.508)
		(layer "F.Cu")
		(net "PVDDQ_KLM")
	)
	(segment
		(start 109.599476 -147.27174)
		(end 109.599476 -148.769578)
		(width 0.508)
		(layer "F.Cu")
		(net "PVDDQ_KLM")
	)
	(segment
		(start 84.0994 -156.87294)
		(end 84.0994 -154.905456)
		(width 0.508)
		(layer "F.Cu")
		(net "PVDDQ_KLM")
	)
	(segment
		(start 101.949504 -143.972534)
		(end 101.949758 -143.972788)
		(width 0.508)
		(layer "F.Cu")
		(net "PVDDQ_KLM")
	)
	(segment
		(start 110.44936 -143.97228)
		(end 110.449868 -143.972788)
		(width 0.508)
		(layer "F.Cu")
		(net "PVDDQ_KLM")
	)
	(segment
		(start 112.149382 -155.589478)
		(end 112.149382 -154.252168)
		(width 0.4064)
		(layer "F.Cu")
		(net "PVDDQ_KLM")
	)
	(segment
		(start 110.44936 -142.6718)
		(end 110.44936 -143.97228)
		(width 0.508)
		(layer "F.Cu")
		(net "PVDDQ_KLM")
	)
	(segment
		(start 89.199466 -155.155392)
		(end 89.199466 -156.87294)
		(width 0.508)
		(layer "F.Cu")
		(net "PVDDQ_KLM")
	)
	(segment
		(start 86.64956 -156.87294)
		(end 86.64956 -155.564078)
		(width 0.508)
		(layer "F.Cu")
		(net "PVDDQ_KLM")
	)
	(segment
		(start 108.749338 -133.0706)
		(end 108.749338 -134.37108)
		(width 0.508)
		(layer "F.Cu")
		(net "PVDDQ_KLM")
	)
	(segment
		(start 96.938338 -97.19564)
		(end 96.366838 -97.19564)
		(width 0.254)
		(layer "F.Cu")
		(net "PVDDQ_KLM")
	)
	(segment
		(start 112.149382 -156.87294)
		(end 112.149382 -155.589478)
		(width 0.508)
		(layer "F.Cu")
		(net "PVDDQ_KLM")
	)
	(segment
		(start 112.149382 -152.273)
		(end 112.149382 -154.252168)
		(width 0.508)
		(layer "F.Cu")
		(net "PVDDQ_KLM")
	)
	(segment
		(start 91.787218 -97.19564)
		(end 91.215718 -97.19564)
		(width 0.254)
		(layer "F.Cu")
		(net "PVDDQ_KLM")
	)
	(segment
		(start 99.513898 -101.653086)
		(end 99.513898 -102.3112)
		(width 0.254)
		(layer "F.Cu")
		(net "PVDDQ_KLM")
	)
	(segment
		(start 101.94925 -131.611878)
		(end 101.949504 -131.612132)
		(width 0.4064)
		(layer "F.Cu")
		(net "PVDDQ_KLM")
	)
	(segment
		(start 90.928698 -101.653086)
		(end 90.928698 -102.3112)
		(width 0.254)
		(layer "F.Cu")
		(net "PVDDQ_KLM")
	)
	(segment
		(start 78.999334 -133.0706)
		(end 78.999334 -133.076442)
		(width 0.4064)
		(layer "F.Cu")
		(net "PVDDQ_KLM")
	)
	(segment
		(start 79.551022 -125.88113)
		(end 79.551022 -126.401576)
		(width 0.4064)
		(layer "F.Cu")
		(net "PVDDQ_KLM")
	)
	(segment
		(start 107.899454 -156.87294)
		(end 107.899454 -154.905456)
		(width 0.508)
		(layer "F.Cu")
		(net "PVDDQ_KLM")
	)
	(segment
		(start 101.099366 -136.383268)
		(end 101.099366 -137.67054)
		(width 0.508)
		(layer "F.Cu")
		(net "PVDDQ_KLM")
	)
	(segment
		(start 110.44936 -152.273)
		(end 110.44936 -150.766272)
		(width 0.508)
		(layer "F.Cu")
		(net "PVDDQ_KLM")
	)
	(segment
		(start 79.849472 -139.170156)
		(end 79.849472 -137.67054)
		(width 0.508)
		(layer "F.Cu")
		(net "PVDDQ_KLM")
	)
	(segment
		(start 79.849472 -137.67054)
		(end 79.849472 -136.387078)
		(width 0.508)
		(layer "F.Cu")
		(net "PVDDQ_KLM")
	)
	(segment
		(start 101.230684 -92.737686)
		(end 100.659184 -92.737686)
		(width 0.254)
		(layer "F.Cu")
		(net "PVDDQ_KLM")
	)
	(segment
		(start 93.449394 -136.250426)
		(end 93.449394 -137.67054)
		(width 0.4064)
		(layer "F.Cu")
		(net "PVDDQ_KLM")
	)
	(segment
		(start 98.655378 -100.167186)
		(end 99.226878 -100.167186)
		(width 0.254)
		(layer "F.Cu")
		(net "PVDDQ_KLM")
	)
	(segment
		(start 83.446112 -154.252168)
		(end 84.0994 -154.905456)
		(width 0.4064)
		(layer "F.Cu")
		(net "PVDDQ_KLM")
	)
	(segment
		(start 88.353392 -100.167186)
		(end 88.640412 -99.67214)
		(width 0.254)
		(layer "F.Cu")
		(net "PVDDQ_KLM")
	)
	(segment
		(start 88.349582 -142.6718)
		(end 88.349582 -143.972788)
		(width 0.508)
		(layer "F.Cu")
		(net "PVDDQ_KLM")
	)
	(segment
		(start 101.099366 -147.27174)
		(end 101.099366 -148.769578)
		(width 0.508)
		(layer "F.Cu")
		(net "PVDDQ_KLM")
	)
	(segment
		(start 87.781892 -97.19564)
		(end 88.353392 -97.19564)
		(width 0.254)
		(layer "F.Cu")
		(net "PVDDQ_KLM")
	)
	(segment
		(start 101.949504 -134.371334)
		(end 101.949758 -134.371588)
		(width 0.508)
		(layer "F.Cu")
		(net "PVDDQ_KLM")
	)
	(segment
		(start 104.49941 -150.789132)
		(end 104.49941 -152.273)
		(width 0.508)
		(layer "F.Cu")
		(net "PVDDQ_KLM")
	)
	(segment
		(start 86.636352 -93.23324)
		(end 86.064852 -93.23324)
		(width 0.254)
		(layer "F.Cu")
		(net "PVDDQ_KLM")
	)
	(segment
		(start 93.449394 -139.11453)
		(end 93.449394 -137.67054)
		(width 0.4064)
		(layer "F.Cu")
		(net "PVDDQ_KLM")
	)
	(segment
		(start 110.44936 -141.188186)
		(end 110.449868 -141.187678)
		(width 0.508)
		(layer "F.Cu")
		(net "PVDDQ_KLM")
	)
	(segment
		(start 86.64956 -147.27174)
		(end 86.64956 -145.988278)
		(width 0.508)
		(layer "F.Cu")
		(net "PVDDQ_KLM")
	)
	(segment
		(start 90.899488 -150.999952)
		(end 90.684604 -150.785068)
		(width 0.508)
		(layer "F.Cu")
		(net "PVDDQ_KLM")
	)
	(segment
		(start 93.449394 -152.273)
		(end 93.449394 -153.571956)
		(width 0.508)
		(layer "F.Cu")
		(net "PVDDQ_KLM")
	)
	(segment
		(start 104.49941 -142.6718)
		(end 104.49941 -143.972534)
		(width 0.508)
		(layer "F.Cu")
		(net "PVDDQ_KLM")
	)
	(segment
		(start 107.899454 -147.27174)
		(end 107.899454 -145.984468)
		(width 0.508)
		(layer "F.Cu")
		(net "PVDDQ_KLM")
	)
	(segment
		(start 108.749338 -154.252168)
		(end 108.09605 -154.905456)
		(width 0.4064)
		(layer "F.Cu")
		(net "PVDDQ_KLM")
	)
	(segment
		(start 108.09605 -154.905456)
		(end 107.899454 -154.905456)
		(width 0.4064)
		(layer "F.Cu")
		(net "PVDDQ_KLM")
	)
	(segment
		(start 85.799422 -150.788878)
		(end 85.799422 -152.273)
		(width 0.508)
		(layer "F.Cu")
		(net "PVDDQ_KLM")
	)
	(segment
		(start 93.449394 -150.785068)
		(end 93.449394 -152.273)
		(width 0.508)
		(layer "F.Cu")
		(net "PVDDQ_KLM")
	)
	(segment
		(start 86.064852 -97.19564)
		(end 86.636352 -97.19564)
		(width 0.254)
		(layer "F.Cu")
		(net "PVDDQ_KLM")
	)
	(segment
		(start 79.849472 -156.87294)
		(end 79.849472 -155.564078)
		(width 0.508)
		(layer "F.Cu")
		(net "PVDDQ_KLM")
	)
	(segment
		(start 81.549494 -136.387078)
		(end 81.549494 -137.67054)
		(width 0.508)
		(layer "F.Cu")
		(net "PVDDQ_KLM")
	)
	(segment
		(start 99.513898 -92.737686)
		(end 98.942398 -92.737686)
		(width 0.254)
		(layer "F.Cu")
		(net "PVDDQ_KLM")
	)
	(segment
		(start 90.928698 -92.737686)
		(end 90.357198 -92.737686)
		(width 0.254)
		(layer "F.Cu")
		(net "PVDDQ_KLM")
	)
	(segment
		(start 87.494872 -89.765886)
		(end 86.923372 -89.765886)
		(width 0.254)
		(layer "F.Cu")
		(net "PVDDQ_KLM")
	)
	(segment
		(start 102.947724 -92.737686)
		(end 102.376224 -92.737686)
		(width 0.254)
		(layer "F.Cu")
		(net "PVDDQ_KLM")
	)
	(segment
		(start 80.699356 -152.273)
		(end 80.699356 -153.571956)
		(width 0.508)
		(layer "F.Cu")
		(net "PVDDQ_KLM")
	)
	(segment
		(start 103.649526 -137.67054)
		(end 103.649526 -136.383268)
		(width 0.508)
		(layer "F.Cu")
		(net "PVDDQ_KLM")
	)
	(segment
		(start 101.94925 -152.279096)
		(end 101.949504 -152.278842)
		(width 0.508)
		(layer "F.Cu")
		(net "PVDDQ_KLM")
	)
	(segment
		(start -0.535686 -135.382)
		(end -0.7874 -135.633714)
		(width 0.254)
		(layer "F.Cu")
		(net "PVDDQ_KLM")
	)
	(segment
		(start 109.599476 -139.168378)
		(end 109.599476 -137.67054)
		(width 0.508)
		(layer "F.Cu")
		(net "PVDDQ_KLM")
	)
	(segment
		(start 0.117602 -135.789162)
		(end 0.117602 -135.636)
		(width 0.254)
		(layer "F.Cu")
		(net "PVDDQ_KLM")
	)
	(segment
		(start 101.099366 -156.87294)
		(end 101.099366 -154.905456)
		(width 0.508)
		(layer "F.Cu")
		(net "PVDDQ_KLM")
	)
	(segment
		(start 96.079818 -92.737686)
		(end 95.508318 -92.737686)
		(width 0.254)
		(layer "F.Cu")
		(net "PVDDQ_KLM")
	)
	(segment
		(start 106.199432 -137.67054)
		(end 106.199432 -139.168378)
		(width 0.508)
		(layer "F.Cu")
		(net "PVDDQ_KLM")
	)
	(segment
		(start 93.449394 -146.131026)
		(end 93.302836 -145.984468)
		(width 0.4064)
		(layer "F.Cu")
		(net "PVDDQ_KLM")
	)
	(segment
		(start 80.699356 -143.970756)
		(end 80.699356 -142.6718)
		(width 0.508)
		(layer "F.Cu")
		(net "PVDDQ_KLM")
	)
	(segment
		(start 109.599476 -136.383268)
		(end 109.599476 -137.67054)
		(width 0.508)
		(layer "F.Cu")
		(net "PVDDQ_KLM")
	)
	(segment
		(start 109.599476 -156.87294)
		(end 109.599476 -154.905456)
		(width 0.508)
		(layer "F.Cu")
		(net "PVDDQ_KLM")
	)
	(segment
		(start 98.655378 -97.19564)
		(end 98.083878 -97.19564)
		(width 0.254)
		(layer "F.Cu")
		(net "PVDDQ_KLM")
	)
	(segment
		(start 90.899488 -152.273)
		(end 90.899488 -150.999952)
		(width 0.508)
		(layer "F.Cu")
		(net "PVDDQ_KLM")
	)
	(segment
		(start 107.899454 -137.67054)
		(end 107.899454 -139.168378)
		(width 0.508)
		(layer "F.Cu")
		(net "PVDDQ_KLM")
	)
	(segment
		(start 91.787218 -94.223586)
		(end 91.215718 -94.223586)
		(width 0.254)
		(layer "F.Cu")
		(net "PVDDQ_KLM")
	)
	(segment
		(start 103.268272 -102.227634)
		(end 102.947724 -101.653086)
		(width 0.254)
		(layer "F.Cu")
		(net "PVDDQ_KLM")
	)
	(segment
		(start 112.149382 -133.0706)
		(end 112.149382 -133.076442)
		(width 0.4064)
		(layer "F.Cu")
		(net "PVDDQ_KLM")
	)
	(segment
		(start 81.549494 -137.67054)
		(end 81.549494 -139.170156)
		(width 0.508)
		(layer "F.Cu")
		(net "PVDDQ_KLM")
	)
	(segment
		(start 0.117602 -144.933162)
		(end -0.11811 -144.933162)
		(width 0.254)
		(layer "F.Cu")
		(net "PVDDQ_KLM")
	)
	(segment
		(start 104.49941 -143.972534)
		(end 104.499664 -143.972788)
		(width 0.508)
		(layer "F.Cu")
		(net "PVDDQ_KLM")
	)
	(segment
		(start 93.302836 -145.984468)
		(end 93.266768 -145.984468)
		(width 0.4064)
		(layer "F.Cu")
		(net "PVDDQ_KLM")
	)
	(segment
		(start 103.649526 -155.615132)
		(end 103.649526 -156.87294)
		(width 0.508)
		(layer "F.Cu")
		(net "PVDDQ_KLM")
	)
	(segment
		(start 88.349582 -152.273)
		(end 88.349582 -154.252168)
		(width 0.508)
		(layer "F.Cu")
		(net "PVDDQ_KLM")
	)
	(segment
		(start 91.787218 -100.167186)
		(end 92.074238 -99.67214)
		(width 0.254)
		(layer "F.Cu")
		(net "PVDDQ_KLM")
	)
	(segment
		(start 112.149382 -145.984468)
		(end 112.149382 -145.988786)
		(width 0.254)
		(layer "F.Cu")
		(net "PVDDQ_KLM")
	)
	(segment
		(start 89.199466 -139.172188)
		(end 89.199466 -137.67054)
		(width 0.508)
		(layer "F.Cu")
		(net "PVDDQ_KLM")
	)
	(segment
		(start 85.799422 -130.902456)
		(end 85.799422 -133.0706)
		(width 0.4064)
		(layer "F.Cu")
		(net "PVDDQ_KLM")
	)
	(segment
		(start 104.49941 -133.0706)
		(end 104.49941 -132.289042)
		(width 0.4064)
		(layer "F.Cu")
		(net "PVDDQ_KLM")
	)
	(segment
		(start 102.089204 -97.19564)
		(end 101.517704 -97.19564)
		(width 0.254)
		(layer "F.Cu")
		(net "PVDDQ_KLM")
	)
	(segment
		(start 89.211912 -89.765886)
		(end 88.640412 -89.765886)
		(width 0.254)
		(layer "F.Cu")
		(net "PVDDQ_KLM")
	)
	(segment
		(start 93.271594 -141.635226)
		(end 93.449394 -141.813026)
		(width 0.508)
		(layer "F.Cu")
		(net "PVDDQ_KLM")
	)
	(segment
		(start 93.449394 -133.0706)
		(end 93.449394 -134.380478)
		(width 0.4064)
		(layer "F.Cu")
		(net "PVDDQ_KLM")
	)
	(segment
		(start 97.796858 -92.737686)
		(end 97.225358 -92.737686)
		(width 0.254)
		(layer "F.Cu")
		(net "PVDDQ_KLM")
	)
	(segment
		(start 90.899488 -143.961104)
		(end 90.899488 -142.6718)
		(width 0.508)
		(layer "F.Cu")
		(net "PVDDQ_KLM")
	)
	(segment
		(start 79.849472 -147.27174)
		(end 79.849472 -145.988278)
		(width 0.508)
		(layer "F.Cu")
		(net "PVDDQ_KLM")
	)
	(segment
		(start 94.649798 -97.19564)
		(end 95.221298 -97.19564)
		(width 0.254)
		(layer "F.Cu")
		(net "PVDDQ_KLM")
	)
	(segment
		(start 89.199466 -137.67054)
		(end 89.199466 -136.387078)
		(width 0.508)
		(layer "F.Cu")
		(net "PVDDQ_KLM")
	)
	(segment
		(start 90.899488 -148.556218)
		(end 90.68435 -148.771356)
		(width 0.508)
		(layer "F.Cu")
		(net "PVDDQ_KLM")
	)
	(segment
		(start 96.938338 -100.167186)
		(end 96.366838 -99.17684)
		(width 0.254)
		(layer "F.Cu")
		(net "PVDDQ_KLM")
	)
	(segment
		(start 90.899488 -136.31291)
		(end 90.899488 -137.67054)
		(width 0.508)
		(layer "F.Cu")
		(net "PVDDQ_KLM")
	)
	(segment
		(start 93.393768 -136.1948)
		(end 93.449394 -136.250426)
		(width 0.4064)
		(layer "F.Cu")
		(net "PVDDQ_KLM")
	)
	(segment
		(start 89.211912 -92.737686)
		(end 88.640412 -92.737686)
		(width 0.254)
		(layer "F.Cu")
		(net "PVDDQ_KLM")
	)
	(segment
		(start 89.435686 -154.919172)
		(end 89.199466 -155.155392)
		(width 0.508)
		(layer "F.Cu")
		(net "PVDDQ_KLM")
	)
	(segment
		(start 103.649526 -148.769578)
		(end 103.649526 -147.27174)
		(width 0.508)
		(layer "F.Cu")
		(net "PVDDQ_KLM")
	)
	(segment
		(start 85.799422 -141.187678)
		(end 85.799422 -142.6718)
		(width 0.508)
		(layer "F.Cu")
		(net "PVDDQ_KLM")
	)
	(segment
		(start 93.19006 -148.498814)
		(end 93.449394 -148.23948)
		(width 0.508)
		(layer "F.Cu")
		(net "PVDDQ_KLM")
	)
	(segment
		(start 93.19006 -148.844)
		(end 93.19006 -148.498814)
		(width 0.508)
		(layer "F.Cu")
		(net "PVDDQ_KLM")
	)
	(segment
		(start 112.149382 -145.988786)
		(end 112.149382 -147.27174)
		(width 0.508)
		(layer "F.Cu")
		(net "PVDDQ_KLM")
	)
	(segment
		(start 83.249516 -154.252168)
		(end 83.249516 -152.273)
		(width 0.508)
		(layer "F.Cu")
		(net "PVDDQ_KLM")
	)
	(segment
		(start 103.649272 -155.614878)
		(end 103.649526 -155.615132)
		(width 0.508)
		(layer "F.Cu")
		(net "PVDDQ_KLM")
	)
	(segment
		(start 83.249516 -133.0706)
		(end 83.249516 -134.369556)
		(width 0.508)
		(layer "F.Cu")
		(net "PVDDQ_KLM")
	)
	(segment
		(start 106.199432 -153.542746)
		(end 106.199432 -152.273)
		(width 0.508)
		(layer "F.Cu")
		(net "PVDDQ_KLM")
	)
	(segment
		(start 89.199466 -147.27174)
		(end 89.199466 -145.988278)
		(width 0.508)
		(layer "F.Cu")
		(net "PVDDQ_KLM")
	)
	(segment
		(start 93.393768 -139.170156)
		(end 93.449394 -139.11453)
		(width 0.4064)
		(layer "F.Cu")
		(net "PVDDQ_KLM")
	)
	(segment
		(start 90.899488 -145.984468)
		(end 90.899488 -147.27174)
		(width 0.508)
		(layer "F.Cu")
		(net "PVDDQ_KLM")
	)
	(segment
		(start 79.551022 -126.401576)
		(end 79.172054 -126.780544)
		(width 0.4064)
		(layer "F.Cu")
		(net "PVDDQ_KLM")
	)
	(segment
		(start 90.070178 -94.223586)
		(end 89.498678 -94.223586)
		(width 0.254)
		(layer "F.Cu")
		(net "PVDDQ_KLM")
	)
	(segment
		(start 109.796072 -154.905456)
		(end 109.599476 -154.905456)
		(width 0.4064)
		(layer "F.Cu")
		(net "PVDDQ_KLM")
	)
	(segment
		(start 84.0994 -145.988278)
		(end 84.0994 -147.27174)
		(width 0.508)
		(layer "F.Cu")
		(net "PVDDQ_KLM")
	)
	(segment
		(start 92.645738 -92.737686)
		(end 92.074238 -92.737686)
		(width 0.254)
		(layer "F.Cu")
		(net "PVDDQ_KLM")
	)
	(segment
		(start 104.49941 -132.289042)
		(end 104.290368 -132.08)
		(width 0.4064)
		(layer "F.Cu")
		(net "PVDDQ_KLM")
	)
	(segment
		(start 83.249516 -154.252168)
		(end 83.446112 -154.252168)
		(width 0.4064)
		(layer "F.Cu")
		(net "PVDDQ_KLM")
	)
	(segment
		(start 80.92948 -132.033518)
		(end 80.699356 -132.263642)
		(width 0.4064)
		(layer "F.Cu")
		(net "PVDDQ_KLM")
	)
	(segment
		(start 96.079818 -101.653086)
		(end 96.079818 -102.3112)
		(width 0.254)
		(layer "F.Cu")
		(net "PVDDQ_KLM")
	)
	(segment
		(start 103.649526 -139.168378)
		(end 103.649526 -137.67054)
		(width 0.508)
		(layer "F.Cu")
		(net "PVDDQ_KLM")
	)
	(segment
		(start 101.949504 -152.278842)
		(end 101.949504 -152.273)
		(width 0.508)
		(layer "F.Cu")
		(net "PVDDQ_KLM")
	)
	(segment
		(start 108.749338 -131.611878)
		(end 108.749338 -133.0706)
		(width 0.4064)
		(layer "F.Cu")
		(net "PVDDQ_KLM")
	)
	(segment
		(start 90.899488 -133.0706)
		(end 90.899488 -134.351268)
		(width 0.508)
		(layer "F.Cu")
		(net "PVDDQ_KLM")
	)
	(segment
		(start 110.44936 -142.6718)
		(end 110.44936 -141.188186)
		(width 0.508)
		(layer "F.Cu")
		(net "PVDDQ_KLM")
	)
	(segment
		(start 106.199432 -154.905456)
		(end 106.199432 -153.542746)
		(width 0.4064)
		(layer "F.Cu")
		(net "PVDDQ_KLM")
	)
	(segment
		(start 86.64956 -139.172188)
		(end 86.64956 -137.67054)
		(width 0.508)
		(layer "F.Cu")
		(net "PVDDQ_KLM")
	)
	(segment
		(start 81.549494 -156.87294)
		(end 81.549494 -155.564078)
		(width 0.508)
		(layer "F.Cu")
		(net "PVDDQ_KLM")
	)
	(segment
		(start 89.199466 -148.773388)
		(end 89.199466 -147.27174)
		(width 0.508)
		(layer "F.Cu")
		(net "PVDDQ_KLM")
	)
	(segment
		(start 85.799422 -133.076442)
		(end 85.799422 -134.369556)
		(width 0.508)
		(layer "F.Cu")
		(net "PVDDQ_KLM")
	)
	(segment
		(start 102.089204 -94.223586)
		(end 101.517704 -94.223586)
		(width 0.254)
		(layer "F.Cu")
		(net "PVDDQ_KLM")
	)
	(segment
		(start 110.44936 -134.37108)
		(end 110.449868 -134.371588)
		(width 0.508)
		(layer "F.Cu")
		(net "PVDDQ_KLM")
	)
	(segment
		(start 112.149382 -142.6718)
		(end 112.149382 -143.968978)
		(width 0.508)
		(layer "F.Cu")
		(net "PVDDQ_KLM")
	)
	(segment
		(start 94.362778 -89.765886)
		(end 93.791278 -89.765886)
		(width 0.254)
		(layer "F.Cu")
		(net "PVDDQ_KLM")
	)
	(segment
		(start 81.549494 -148.771356)
		(end 81.549494 -147.27174)
		(width 0.508)
		(layer "F.Cu")
		(net "PVDDQ_KLM")
	)
	(segment
		(start 93.26118 -155.45308)
		(end 93.26118 -155.386786)
		(width 0.508)
		(layer "F.Cu")
		(net "PVDDQ_KLM")
	)
	(segment
		(start 84.0994 -137.67054)
		(end 84.0994 -139.170156)
		(width 0.508)
		(layer "F.Cu")
		(net "PVDDQ_KLM")
	)
	(segment
		(start 93.698568 -99.83216)
		(end 93.791278 -99.67214)
		(width 0.254)
		(layer "F.Cu")
		(net "PVDDQ_KLM")
	)
	(segment
		(start 100.372164 -97.19564)
		(end 99.800664 -97.19564)
		(width 0.254)
		(layer "F.Cu")
		(net "PVDDQ_KLM")
	)
	(segment
		(start 104.290368 -132.08)
		(end 104.290368 -131.111498)
		(width 0.4064)
		(layer "F.Cu")
		(net "PVDDQ_KLM")
	)
	(segment
		(start 106.199432 -136.383268)
		(end 106.199432 -137.67054)
		(width 0.508)
		(layer "F.Cu")
		(net "PVDDQ_KLM")
	)
	(segment
		(start 97.966784 -132.55244)
		(end 97.254568 -131.840224)
		(width 0.508)
		(layer "F.Cu")
		(net "PVDDQ_KLM")
	)
	(segment
		(start 93.449394 -155.641294)
		(end 93.26118 -155.45308)
		(width 0.508)
		(layer "F.Cu")
		(net "PVDDQ_KLM")
	)
	(segment
		(start 101.949504 -133.0706)
		(end 101.949504 -134.371334)
		(width 0.508)
		(layer "F.Cu")
		(net "PVDDQ_KLM")
	)
	(segment
		(start 86.64956 -137.67054)
		(end 86.64956 -136.387078)
		(width 0.508)
		(layer "F.Cu")
		(net "PVDDQ_KLM")
	)
	(segment
		(start 90.928698 -89.765886)
		(end 90.357198 -89.765886)
		(width 0.254)
		(layer "F.Cu")
		(net "PVDDQ_KLM")
	)
	(segment
		(start 88.349582 -133.0706)
		(end 88.349582 -134.371588)
		(width 0.508)
		(layer "F.Cu")
		(net "PVDDQ_KLM")
	)
	(segment
		(start 93.449394 -143.799052)
		(end 93.27769 -143.970756)
		(width 0.508)
		(layer "F.Cu")
		(net "PVDDQ_KLM")
	)
	(segment
		(start 101.94925 -154.252168)
		(end 101.295962 -154.905456)
		(width 0.4064)
		(layer "F.Cu")
		(net "PVDDQ_KLM")
	)
	(segment
		(start 83.249516 -141.187678)
		(end 83.249516 -142.6718)
		(width 0.508)
		(layer "F.Cu")
		(net "PVDDQ_KLM")
	)
	(segment
		(start 107.899454 -136.383268)
		(end 107.899454 -137.67054)
		(width 0.508)
		(layer "F.Cu")
		(net "PVDDQ_KLM")
	)
	(segment
		(start 93.504258 -94.223586)
		(end 92.932758 -94.223586)
		(width 0.254)
		(layer "F.Cu")
		(net "PVDDQ_KLM")
	)
	(segment
		(start 86.64956 -148.773388)
		(end 86.64956 -147.27174)
		(width 0.508)
		(layer "F.Cu")
		(net "PVDDQ_KLM")
	)
	(segment
		(start 78.999334 -141.187678)
		(end 78.999334 -142.6718)
		(width 0.508)
		(layer "F.Cu")
		(net "PVDDQ_KLM")
	)
	(segment
		(start 102.089204 -100.167186)
		(end 102.376224 -99.67214)
		(width 0.254)
		(layer "F.Cu")
		(net "PVDDQ_KLM")
	)
	(segment
		(start 104.49941 -133.0706)
		(end 104.49941 -134.371334)
		(width 0.508)
		(layer "F.Cu")
		(net "PVDDQ_KLM")
	)
	(segment
		(start 93.449394 -156.87294)
		(end 93.449394 -155.641294)
		(width 0.508)
		(layer "F.Cu")
		(net "PVDDQ_KLM")
	)
	(segment
		(start 109.599476 -147.27174)
		(end 109.599476 -145.984468)
		(width 0.508)
		(layer "F.Cu")
		(net "PVDDQ_KLM")
	)
	(segment
		(start 104.290368 -131.111498)
		(end 104.49941 -130.902456)
		(width 0.4064)
		(layer "F.Cu")
		(net "PVDDQ_KLM")
	)
	(segment
		(start 96.938338 -94.223586)
		(end 96.366838 -94.223586)
		(width 0.254)
		(layer "F.Cu")
		(net "PVDDQ_KLM")
	)
	(segment
		(start 90.848688 -139.170156)
		(end 90.899488 -139.119356)
		(width 0.4064)
		(layer "F.Cu")
		(net "PVDDQ_KLM")
	)
	(segment
		(start 87.494872 -92.737686)
		(end 86.923372 -92.737686)
		(width 0.254)
		(layer "F.Cu")
		(net "PVDDQ_KLM")
	)
	(segment
		(start 80.699356 -132.263642)
		(end 80.699356 -133.0706)
		(width 0.508)
		(layer "F.Cu")
		(net "PVDDQ_KLM")
	)
	(segment
		(start 85.799422 -152.273)
		(end 85.799422 -153.542746)
		(width 0.508)
		(layer "F.Cu")
		(net "PVDDQ_KLM")
	)
	(segment
		(start 80.699356 -133.0706)
		(end 80.699356 -134.369556)
		(width 0.508)
		(layer "F.Cu")
		(net "PVDDQ_KLM")
	)
	(segment
		(start 78.999334 -150.788878)
		(end 78.999334 -152.273)
		(width 0.508)
		(layer "F.Cu")
		(net "PVDDQ_KLM")
	)
	(segment
		(start 104.49941 -153.571956)
		(end 104.49941 -152.273)
		(width 0.508)
		(layer "F.Cu")
		(net "PVDDQ_KLM")
	)
	(segment
		(start 103.649526 -147.27174)
		(end 103.649526 -145.984468)
		(width 0.508)
		(layer "F.Cu")
		(net "PVDDQ_KLM")
	)
	(segment
		(start 78.999334 -130.902456)
		(end 78.999334 -133.0706)
		(width 0.4064)
		(layer "F.Cu")
		(net "PVDDQ_KLM")
	)
	(segment
		(start 80.699356 -130.902456)
		(end 80.92948 -131.13258)
		(width 0.4064)
		(layer "F.Cu")
		(net "PVDDQ_KLM")
	)
	(segment
		(start 90.90914 -136.322562)
		(end 90.899488 -136.31291)
		(width 0.508)
		(layer "F.Cu")
		(net "PVDDQ_KLM")
	)
	(segment
		(start 103.806244 -101.689662)
		(end 103.268272 -102.227634)
		(width 0.254)
		(layer "F.Cu")
		(net "PVDDQ_KLM")
	)
	(segment
		(start 106.199432 -156.87294)
		(end 106.199432 -154.905456)
		(width 0.508)
		(layer "F.Cu")
		(net "PVDDQ_KLM")
	)
	(segment
		(start 93.271594 -141.183868)
		(end 93.271594 -141.635226)
		(width 0.508)
		(layer "F.Cu")
		(net "PVDDQ_KLM")
	)
	(segment
		(start 108.749846 -141.187678)
		(end 108.749338 -141.188186)
		(width 0.508)
		(layer "F.Cu")
		(net "PVDDQ_KLM")
	)
	(segment
		(start 107.899454 -147.27174)
		(end 107.899454 -148.769578)
		(width 0.508)
		(layer "F.Cu")
		(net "PVDDQ_KLM")
	)
	(segment
		(start 81.549494 -147.27174)
		(end 81.549494 -145.988278)
		(width 0.508)
		(layer "F.Cu")
		(net "PVDDQ_KLM")
	)
	(segment
		(start 94.649798 -94.223586)
		(end 95.221298 -94.223586)
		(width 0.254)
		(layer "F.Cu")
		(net "PVDDQ_KLM")
	)
	(segment
		(start 86.636352 -97.19564)
		(end 87.781892 -97.19564)
		(width 0.254)
		(layer "F.Cu")
		(net "PVDDQ_KLM")
	)
	(segment
		(start 84.0994 -136.387078)
		(end 84.0994 -137.67054)
		(width 0.508)
		(layer "F.Cu")
		(net "PVDDQ_KLM")
	)
	(segment
		(start 83.249516 -143.970756)
		(end 83.249516 -142.6718)
		(width 0.508)
		(layer "F.Cu")
		(net "PVDDQ_KLM")
	)
	(segment
		(start 0.117602 -135.636)
		(end -0.136398 -135.382)
		(width 0.254)
		(layer "F.Cu")
		(net "PVDDQ_KLM")
	)
	(segment
		(start 93.449394 -141.813026)
		(end 93.449394 -142.6718)
		(width 0.508)
		(layer "F.Cu")
		(net "PVDDQ_KLM")
	)
	(segment
		(start 110.44936 -133.0706)
		(end 110.44936 -134.37108)
		(width 0.508)
		(layer "F.Cu")
		(net "PVDDQ_KLM")
	)
	(segment
		(start 80.699356 -150.788878)
		(end 80.699356 -152.273)
		(width 0.508)
		(layer "F.Cu")
		(net "PVDDQ_KLM")
	)
	(segment
		(start 101.099366 -137.67054)
		(end 101.099366 -139.168378)
		(width 0.508)
		(layer "F.Cu")
		(net "PVDDQ_KLM")
	)
	(segment
		(start 78.999334 -143.970756)
		(end 78.999334 -142.6718)
		(width 0.508)
		(layer "F.Cu")
		(net "PVDDQ_KLM")
	)
	(segment
		(start 90.899488 -139.119356)
		(end 90.899488 -137.67054)
		(width 0.508)
		(layer "F.Cu")
		(net "PVDDQ_KLM")
	)
	(segment
		(start 102.947724 -90.756486)
		(end 102.376224 -90.756486)
		(width 0.254)
		(layer "F.Cu")
		(net "PVDDQ_KLM")
	)
	(segment
		(start 93.449394 -148.23948)
		(end 93.449394 -147.27174)
		(width 0.508)
		(layer "F.Cu")
		(net "PVDDQ_KLM")
	)
	(segment
		(start 104.49941 -134.371334)
		(end 104.499664 -134.371588)
		(width 0.508)
		(layer "F.Cu")
		(net "PVDDQ_KLM")
	)
	(segment
		(start 108.749338 -134.37108)
		(end 108.749846 -134.371588)
		(width 0.508)
		(layer "F.Cu")
		(net "PVDDQ_KLM")
	)
	(segment
		(start 103.806244 -101.15804)
		(end 103.806244 -101.689662)
		(width 0.254)
		(layer "F.Cu")
		(net "PVDDQ_KLM")
	)
	(segment
		(start 112.149382 -141.183868)
		(end 112.149382 -142.6718)
		(width 0.508)
		(layer "F.Cu")
		(net "PVDDQ_KLM")
	)
	(segment
		(start 98.20402 -132.55244)
		(end 97.966784 -132.55244)
		(width 0.508)
		(layer "F.Cu")
		(net "PVDDQ_KLM")
	)
	(segment
		(start 79.849472 -148.771356)
		(end 79.849472 -147.27174)
		(width 0.508)
		(layer "F.Cu")
		(net "PVDDQ_KLM")
	)
	(segment
		(start 93.27769 -143.970756)
		(end 93.266768 -143.970756)
		(width 0.508)
		(layer "F.Cu")
		(net "PVDDQ_KLM")
	)
	(segment
		(start -0.398272 -144.653)
		(end -0.635 -144.653)
		(width 0.254)
		(layer "F.Cu")
		(net "PVDDQ_KLM")
	)
	(segment
		(start 78.999334 -152.273)
		(end 78.999334 -153.571956)
		(width 0.508)
		(layer "F.Cu")
		(net "PVDDQ_KLM")
	)
	(segment
		(start 106.199432 -152.273)
		(end 106.199432 -150.785068)
		(width 0.508)
		(layer "F.Cu")
		(net "PVDDQ_KLM")
	)
	(segment
		(start 108.749338 -152.273)
		(end 108.749338 -150.789386)
		(width 0.508)
		(layer "F.Cu")
		(net "PVDDQ_KLM")
	)
	(segment
		(start 92.645738 -89.765886)
		(end 92.074238 -89.765886)
		(width 0.254)
		(layer "F.Cu")
		(net "PVDDQ_KLM")
	)
	(segment
		(start 93.504258 -97.19564)
		(end 92.932758 -97.19564)
		(width 0.254)
		(layer "F.Cu")
		(net "PVDDQ_KLM")
	)
	(segment
		(start 90.899488 -153.571956)
		(end 90.899488 -152.273)
		(width 0.508)
		(layer "F.Cu")
		(net "PVDDQ_KLM")
	)
	(segment
		(start 100.372164 -94.223586)
		(end 99.800664 -94.223586)
		(width 0.254)
		(layer "F.Cu")
		(net "PVDDQ_KLM")
	)
	(segment
		(start 85.799422 -133.0706)
		(end 85.799422 -133.076442)
		(width 0.4064)
		(layer "F.Cu")
		(net "PVDDQ_KLM")
	)
	(segment
		(start 104.499664 -141.187678)
		(end 104.49941 -141.187932)
		(width 0.508)
		(layer "F.Cu")
		(net "PVDDQ_KLM")
	)
	(segment
		(start 101.295962 -154.905456)
		(end 101.099366 -154.905456)
		(width 0.4064)
		(layer "F.Cu")
		(net "PVDDQ_KLM")
	)
	(segment
		(start -0.11811 -144.933162)
		(end -0.398272 -144.653)
		(width 0.254)
		(layer "F.Cu")
		(net "PVDDQ_KLM")
	)
	(segment
		(start 110.44936 -154.252168)
		(end 109.796072 -154.905456)
		(width 0.4064)
		(layer "F.Cu")
		(net "PVDDQ_KLM")
	)
	(segment
		(start 84.0994 -147.27174)
		(end 84.0994 -148.771356)
		(width 0.508)
		(layer "F.Cu")
		(net "PVDDQ_KLM")
	)
	(segment
		(start 90.070178 -97.19564)
		(end 89.498678 -97.19564)
		(width 0.254)
		(layer "F.Cu")
		(net "PVDDQ_KLM")
	)
	(segment
		(start 93.449394 -142.6718)
		(end 93.449394 -143.799052)
		(width 0.508)
		(layer "F.Cu")
		(net "PVDDQ_KLM")
	)
	(segment
		(start 108.749338 -141.188186)
		(end 108.749338 -142.6718)
		(width 0.508)
		(layer "F.Cu")
		(net "PVDDQ_KLM")
	)
	(segment
		(start 85.799422 -143.970756)
		(end 85.799422 -142.6718)
		(width 0.508)
		(layer "F.Cu")
		(net "PVDDQ_KLM")
	)
	(segment
		(start 97.254568 -131.840224)
		(end 97.254568 -130.367024)
		(width 0.508)
		(layer "F.Cu")
		(net "PVDDQ_KLM")
	)
	(segment
		(start 106.199432 -133.0706)
		(end 106.199432 -134.367778)
		(width 0.381)
		(layer "F.Cu")
		(net "PVDDQ_KLM")
	)
	(segment
		(start 112.149382 -152.273)
		(end 112.149382 -150.785068)
		(width 0.508)
		(layer "F.Cu")
		(net "PVDDQ_KLM")
	)
	(segment
		(start 90.899488 -155.509468)
		(end 90.899488 -153.571956)
		(width 0.508)
		(layer "F.Cu")
		(net "PVDDQ_KLM")
	)
	(segment
		(start 112.149382 -133.076442)
		(end 112.149382 -134.367778)
		(width 0.508)
		(layer "F.Cu")
		(net "PVDDQ_KLM")
	)
	(segment
		(start 90.899488 -156.87294)
		(end 90.899488 -155.509468)
		(width 0.508)
		(layer "F.Cu")
		(net "PVDDQ_KLM")
	)
	(segment
		(start 110.44936 -154.252168)
		(end 110.44936 -152.273)
		(width 0.508)
		(layer "F.Cu")
		(net "PVDDQ_KLM")
	)
	(segment
		(start 94.362778 -92.737686)
		(end 93.791278 -92.737686)
		(width 0.254)
		(layer "F.Cu")
		(net "PVDDQ_KLM")
	)
	(segment
		(start 96.079818 -89.765886)
		(end 95.508318 -89.765886)
		(width 0.254)
		(layer "F.Cu")
		(net "PVDDQ_KLM")
	)
	(segment
		(start 101.949504 -131.612132)
		(end 101.949504 -133.0706)
		(width 0.4064)
		(layer "F.Cu")
		(net "PVDDQ_KLM")
	)
	(segment
		(start 88.349582 -150.788878)
		(end 88.349582 -152.273)
		(width 0.508)
		(layer "F.Cu")
		(net "PVDDQ_KLM")
	)
	(segment
		(start 78.999334 -133.076442)
		(end 78.999334 -134.369556)
		(width 0.508)
		(layer "F.Cu")
		(net "PVDDQ_KLM")
	)
	(segment
		(start 90.90914 -143.970756)
		(end 90.899488 -143.961104)
		(width 0.5588)
		(layer "F.Cu")
		(net "PVDDQ_KLM")
	)
	(segment
		(start 106.199432 -147.27174)
		(end 106.199432 -146.013932)
		(width 0.508)
		(layer "F.Cu")
		(net "PVDDQ_KLM")
	)
	(segment
		(start 83.249516 -152.273)
		(end 83.249516 -150.788878)
		(width 0.508)
		(layer "F.Cu")
		(net "PVDDQ_KLM")
	)
	(segment
		(start 104.499664 -150.788878)
		(end 104.49941 -150.789132)
		(width 0.381)
		(layer "F.Cu")
		(net "PVDDQ_KLM")
	)
	(segment
		(start 90.90914 -136.328658)
		(end 90.90914 -136.322562)
		(width 0.508)
		(layer "F.Cu")
		(net "PVDDQ_KLM")
	)
	(segment
		(start 83.249516 -131.611878)
		(end 83.249516 -133.0706)
		(width 0.508)
		(layer "F.Cu")
		(net "PVDDQ_KLM")
	)
	(segment
		(start 101.94925 -154.252168)
		(end 101.94925 -152.279096)
		(width 0.508)
		(layer "F.Cu")
		(net "PVDDQ_KLM")
	)
	(segment
		(start -0.136398 -135.382)
		(end -0.535686 -135.382)
		(width 0.254)
		(layer "F.Cu")
		(net "PVDDQ_KLM")
	)
	(segment
		(start 101.949504 -142.6718)
		(end 101.949504 -143.972534)
		(width 0.508)
		(layer "F.Cu")
		(net "PVDDQ_KLM")
	)
	(via
		(at 83.006438 -126.940818)
		(size 0.508)
		(drill 0.254)
		(layers "F.Cu" "B.Cu")
		(net "PVDDQ_KLM")
	)
	(via
		(at 15.875 -136.017)
		(size 0.508)
		(drill 0.254)
		(layers "F.Cu" "B.Cu")
		(net "PVDDQ_KLM")
	)
	(via
		(at 19.167094 -137.532872)
		(size 0.508)
		(drill 0.254)
		(layers "F.Cu" "B.Cu")
		(net "PVDDQ_KLM")
	)
	(via
		(at 17.653 -151.384)
		(size 0.508)
		(drill 0.254)
		(layers "F.Cu" "B.Cu")
		(net "PVDDQ_KLM")
	)
	(via
		(at 86.64956 -148.773388)
		(size 0.508)
		(drill 0.254)
		(layers "F.Cu" "B.Cu")
		(net "PVDDQ_KLM")
	)
	(via
		(at -0.635 -144.653)
		(size 0.508)
		(drill 0.254)
		(layers "F.Cu" "B.Cu")
		(net "PVDDQ_KLM")
	)
	(via
		(at 89.199466 -139.172188)
		(size 0.508)
		(drill 0.254)
		(layers "F.Cu" "B.Cu")
		(net "PVDDQ_KLM")
	)
	(via
		(at 90.899488 -134.351268)
		(size 0.508)
		(drill 0.254)
		(layers "F.Cu" "B.Cu")
		(net "PVDDQ_KLM")
	)
	(via
		(at 98.083878 -94.223586)
		(size 0.508)
		(drill 0.254)
		(layers "F.Cu" "B.Cu")
		(net "PVDDQ_KLM")
	)
	(via
		(at 107.899454 -136.383268)
		(size 0.508)
		(drill 0.254)
		(layers "F.Cu" "B.Cu")
		(net "PVDDQ_KLM")
	)
	(via
		(at 81.549494 -145.988278)
		(size 0.508)
		(drill 0.254)
		(layers "F.Cu" "B.Cu")
		(net "PVDDQ_KLM")
	)
	(via
		(at 112.149382 -143.968978)
		(size 0.508)
		(drill 0.254)
		(layers "F.Cu" "B.Cu")
		(net "PVDDQ_KLM")
	)
	(via
		(at 79.849472 -145.988278)
		(size 0.508)
		(drill 0.254)
		(layers "F.Cu" "B.Cu")
		(net "PVDDQ_KLM")
	)
	(via
		(at 16.129 -152.146)
		(size 0.508)
		(drill 0.254)
		(layers "F.Cu" "B.Cu")
		(net "PVDDQ_KLM")
	)
	(via
		(at 92.074238 -89.765886)
		(size 0.508)
		(drill 0.254)
		(layers "F.Cu" "B.Cu")
		(net "PVDDQ_KLM")
	)
	(via
		(at 112.149382 -139.168378)
		(size 0.508)
		(drill 0.254)
		(layers "F.Cu" "B.Cu")
		(net "PVDDQ_KLM")
	)
	(via
		(at 84.0994 -148.771356)
		(size 0.508)
		(drill 0.254)
		(layers "F.Cu" "B.Cu")
		(net "PVDDQ_KLM")
	)
	(via
		(at 99.800664 -97.19564)
		(size 0.508)
		(drill 0.254)
		(layers "F.Cu" "B.Cu")
		(net "PVDDQ_KLM")
	)
	(via
		(at 101.099366 -148.769578)
		(size 0.508)
		(drill 0.254)
		(layers "F.Cu" "B.Cu")
		(net "PVDDQ_KLM")
	)
	(via
		(at 168.021 -144.7292)
		(size 0.508)
		(drill 0.254)
		(layers "F.Cu" "B.Cu")
		(net "PVDDQ_KLM")
	)
	(via
		(at 109.599476 -148.769578)
		(size 0.508)
		(drill 0.254)
		(layers "F.Cu" "B.Cu")
		(net "PVDDQ_KLM")
	)
	(via
		(at 101.129592 -85.938614)
		(size 0.508)
		(drill 0.254)
		(layers "F.Cu" "B.Cu")
		(net "PVDDQ_KLM")
	)
	(via
		(at 80.699356 -150.788878)
		(size 0.508)
		(drill 0.254)
		(layers "F.Cu" "B.Cu")
		(net "PVDDQ_KLM")
	)
	(via
		(at 18.923 -146.812)
		(size 0.508)
		(drill 0.254)
		(layers "F.Cu" "B.Cu")
		(net "PVDDQ_KLM")
	)
	(via
		(at 88.349582 -150.788878)
		(size 0.508)
		(drill 0.254)
		(layers "F.Cu" "B.Cu")
		(net "PVDDQ_KLM")
	)
	(via
		(at 157.29204 -118.51894)
		(size 0.508)
		(drill 0.254)
		(layers "F.Cu" "B.Cu")
		(net "PVDDQ_KLM")
	)
	(via
		(at 107.899454 -145.984468)
		(size 0.508)
		(drill 0.254)
		(layers "F.Cu" "B.Cu")
		(net "PVDDQ_KLM")
	)
	(via
		(at 78.999334 -141.187678)
		(size 0.508)
		(drill 0.254)
		(layers "F.Cu" "B.Cu")
		(net "PVDDQ_KLM")
	)
	(via
		(at 28.877768 -143.764)
		(size 0.508)
		(drill 0.254)
		(layers "F.Cu" "B.Cu")
		(net "PVDDQ_KLM")
	)
	(via
		(at 106.199432 -150.785068)
		(size 0.508)
		(drill 0.254)
		(layers "F.Cu" "B.Cu")
		(net "PVDDQ_KLM")
	)
	(via
		(at 93.18371 -129.568956)
		(size 0.508)
		(drill 0.254)
		(layers "F.Cu" "B.Cu")
		(net "PVDDQ_KLM")
	)
	(via
		(at 20.418806 -136.770872)
		(size 0.508)
		(drill 0.254)
		(layers "F.Cu" "B.Cu")
		(net "PVDDQ_KLM")
	)
	(via
		(at 90.357198 -89.765886)
		(size 0.508)
		(drill 0.254)
		(layers "F.Cu" "B.Cu")
		(net "PVDDQ_KLM")
	)
	(via
		(at 80.699356 -141.187678)
		(size 0.508)
		(drill 0.254)
		(layers "F.Cu" "B.Cu")
		(net "PVDDQ_KLM")
	)
	(via
		(at 88.349582 -134.371588)
		(size 0.508)
		(drill 0.254)
		(layers "F.Cu" "B.Cu")
		(net "PVDDQ_KLM")
	)
	(via
		(at 106.199432 -154.905456)
		(size 0.508)
		(drill 0.254)
		(layers "F.Cu" "B.Cu")
		(net "PVDDQ_KLM")
	)
	(via
		(at 101.517704 -97.19564)
		(size 0.508)
		(drill 0.254)
		(layers "F.Cu" "B.Cu")
		(net "PVDDQ_KLM")
	)
	(via
		(at 106.199432 -136.383268)
		(size 0.508)
		(drill 0.254)
		(layers "F.Cu" "B.Cu")
		(net "PVDDQ_KLM")
	)
	(via
		(at 103.649526 -136.383268)
		(size 0.508)
		(drill 0.254)
		(layers "F.Cu" "B.Cu")
		(net "PVDDQ_KLM")
	)
	(via
		(at 108.749338 -131.611878)
		(size 0.508)
		(drill 0.254)
		(layers "F.Cu" "B.Cu")
		(net "PVDDQ_KLM")
	)
	(via
		(at 95.508318 -89.765886)
		(size 0.508)
		(drill 0.254)
		(layers "F.Cu" "B.Cu")
		(net "PVDDQ_KLM")
	)
	(via
		(at 83.249516 -150.788878)
		(size 0.508)
		(drill 0.254)
		(layers "F.Cu" "B.Cu")
		(net "PVDDQ_KLM")
	)
	(via
		(at 79.849472 -136.387078)
		(size 0.508)
		(drill 0.254)
		(layers "F.Cu" "B.Cu")
		(net "PVDDQ_KLM")
	)
	(via
		(at 16.891 -152.146)
		(size 0.508)
		(drill 0.254)
		(layers "F.Cu" "B.Cu")
		(net "PVDDQ_KLM")
	)
	(via
		(at 93.791278 -89.765886)
		(size 0.508)
		(drill 0.254)
		(layers "F.Cu" "B.Cu")
		(net "PVDDQ_KLM")
	)
	(via
		(at 103.649272 -130.249168)
		(size 0.508)
		(drill 0.254)
		(layers "F.Cu" "B.Cu")
		(net "PVDDQ_KLM")
	)
	(via
		(at 109.242606 -85.960712)
		(size 0.508)
		(drill 0.254)
		(layers "F.Cu" "B.Cu")
		(net "PVDDQ_KLM")
	)
	(via
		(at 86.64956 -155.564078)
		(size 0.508)
		(drill 0.254)
		(layers "F.Cu" "B.Cu")
		(net "PVDDQ_KLM")
	)
	(via
		(at 79.849472 -130.249168)
		(size 0.508)
		(drill 0.254)
		(layers "F.Cu" "B.Cu")
		(net "PVDDQ_KLM")
	)
	(via
		(at 104.499664 -141.187678)
		(size 0.508)
		(drill 0.254)
		(layers "F.Cu" "B.Cu")
		(net "PVDDQ_KLM")
	)
	(via
		(at 19.939 -142.621)
		(size 0.508)
		(drill 0.254)
		(layers "F.Cu" "B.Cu")
		(net "PVDDQ_KLM")
	)
	(via
		(at 101.099366 -145.984468)
		(size 0.508)
		(drill 0.254)
		(layers "F.Cu" "B.Cu")
		(net "PVDDQ_KLM")
	)
	(via
		(at 81.549494 -155.564078)
		(size 0.508)
		(drill 0.254)
		(layers "F.Cu" "B.Cu")
		(net "PVDDQ_KLM")
	)
	(via
		(at 20.701 -152.908)
		(size 0.508)
		(drill 0.254)
		(layers "F.Cu" "B.Cu")
		(net "PVDDQ_KLM")
	)
	(via
		(at 18.415 -141.605)
		(size 0.508)
		(drill 0.254)
		(layers "F.Cu" "B.Cu")
		(net "PVDDQ_KLM")
	)
	(via
		(at 103.649526 -139.168378)
		(size 0.508)
		(drill 0.254)
		(layers "F.Cu" "B.Cu")
		(net "PVDDQ_KLM")
	)
	(via
		(at 101.949758 -143.972788)
		(size 0.4572)
		(drill 0.2032)
		(layers "F.Cu" "B.Cu")
		(net "PVDDQ_KLM")
	)
	(via
		(at 106.199432 -143.968978)
		(size 0.508)
		(drill 0.254)
		(layers "F.Cu" "B.Cu")
		(net "PVDDQ_KLM")
	)
	(via
		(at 79.172054 -126.780544)
		(size 0.508)
		(drill 0.254)
		(layers "F.Cu" "B.Cu")
		(net "PVDDQ_KLM")
	)
	(via
		(at 102.376224 -90.756486)
		(size 0.508)
		(drill 0.254)
		(layers "F.Cu" "B.Cu")
		(net "PVDDQ_KLM")
	)
	(via
		(at 18.415 -140.843)
		(size 0.508)
		(drill 0.254)
		(layers "F.Cu" "B.Cu")
		(net "PVDDQ_KLM")
	)
	(via
		(at 104.49941 -153.571956)
		(size 0.508)
		(drill 0.254)
		(layers "F.Cu" "B.Cu")
		(net "PVDDQ_KLM")
	)
	(via
		(at 16.891 -141.605)
		(size 0.508)
		(drill 0.254)
		(layers "F.Cu" "B.Cu")
		(net "PVDDQ_KLM")
	)
	(via
		(at 104.380792 -86.014814)
		(size 0.508)
		(drill 0.254)
		(layers "F.Cu" "B.Cu")
		(net "PVDDQ_KLM")
	)
	(via
		(at 101.517704 -94.223586)
		(size 0.508)
		(drill 0.254)
		(layers "F.Cu" "B.Cu")
		(net "PVDDQ_KLM")
	)
	(via
		(at 90.848688 -139.170156)
		(size 0.508)
		(drill 0.254)
		(layers "F.Cu" "B.Cu")
		(net "PVDDQ_KLM")
	)
	(via
		(at 106.199432 -148.742146)
		(size 0.508)
		(drill 0.254)
		(layers "F.Cu" "B.Cu")
		(net "PVDDQ_KLM")
	)
	(via
		(at 81.549494 -136.387078)
		(size 0.508)
		(drill 0.254)
		(layers "F.Cu" "B.Cu")
		(net "PVDDQ_KLM")
	)
	(via
		(at 109.599476 -145.984468)
		(size 0.508)
		(drill 0.254)
		(layers "F.Cu" "B.Cu")
		(net "PVDDQ_KLM")
	)
	(via
		(at 167.3606 -144.7292)
		(size 0.508)
		(drill 0.254)
		(layers "F.Cu" "B.Cu")
		(net "PVDDQ_KLM")
	)
	(via
		(at 19.939 -152.146)
		(size 0.508)
		(drill 0.254)
		(layers "F.Cu" "B.Cu")
		(net "PVDDQ_KLM")
	)
	(via
		(at 98.20402 -132.55244)
		(size 0.508)
		(drill 0.254)
		(layers "F.Cu" "B.Cu")
		(net "PVDDQ_KLM")
	)
	(via
		(at 106.199432 -153.542746)
		(size 0.508)
		(drill 0.254)
		(layers "F.Cu" "B.Cu")
		(net "PVDDQ_KLM")
	)
	(via
		(at 101.099366 -136.383268)
		(size 0.508)
		(drill 0.254)
		(layers "F.Cu" "B.Cu")
		(net "PVDDQ_KLM")
	)
	(via
		(at 19.939 -155.448)
		(size 0.508)
		(drill 0.254)
		(layers "F.Cu" "B.Cu")
		(net "PVDDQ_KLM")
	)
	(via
		(at 91.215718 -97.19564)
		(size 0.508)
		(drill 0.254)
		(layers "F.Cu" "B.Cu")
		(net "PVDDQ_KLM")
	)
	(via
		(at 93.791278 -92.737686)
		(size 0.508)
		(drill 0.254)
		(layers "F.Cu" "B.Cu")
		(net "PVDDQ_KLM")
	)
	(via
		(at 107.899454 -139.168378)
		(size 0.508)
		(drill 0.254)
		(layers "F.Cu" "B.Cu")
		(net "PVDDQ_KLM")
	)
	(via
		(at 17.653 -140.843)
		(size 0.508)
		(drill 0.254)
		(layers "F.Cu" "B.Cu")
		(net "PVDDQ_KLM")
	)
	(via
		(at 97.225358 -92.737686)
		(size 0.508)
		(drill 0.254)
		(layers "F.Cu" "B.Cu")
		(net "PVDDQ_KLM")
	)
	(via
		(at 101.099366 -129.539746)
		(size 0.508)
		(drill 0.254)
		(layers "F.Cu" "B.Cu")
		(net "PVDDQ_KLM")
	)
	(via
		(at 165.1127 -144.430242)
		(size 0.508)
		(drill 0.254)
		(layers "F.Cu" "B.Cu")
		(net "PVDDQ_KLM")
	)
	(via
		(at 88.349582 -141.187678)
		(size 0.508)
		(drill 0.254)
		(layers "F.Cu" "B.Cu")
		(net "PVDDQ_KLM")
	)
	(via
		(at 92.932758 -97.19564)
		(size 0.508)
		(drill 0.254)
		(layers "F.Cu" "B.Cu")
		(net "PVDDQ_KLM")
	)
	(via
		(at 83.249516 -141.187678)
		(size 0.508)
		(drill 0.254)
		(layers "F.Cu" "B.Cu")
		(net "PVDDQ_KLM")
	)
	(via
		(at 85.799422 -134.369556)
		(size 0.508)
		(drill 0.254)
		(layers "F.Cu" "B.Cu")
		(net "PVDDQ_KLM")
	)
	(via
		(at 86.064852 -93.23324)
		(size 0.508)
		(drill 0.254)
		(layers "F.Cu" "B.Cu")
		(net "PVDDQ_KLM")
	)
	(via
		(at 101.949504 -150.785068)
		(size 0.508)
		(drill 0.254)
		(layers "F.Cu" "B.Cu")
		(net "PVDDQ_KLM")
	)
	(via
		(at 99.800664 -99.17684)
		(size 0.508)
		(drill 0.254)
		(layers "F.Cu" "B.Cu")
		(net "PVDDQ_KLM")
	)
	(via
		(at 94.649798 -94.223586)
		(size 0.508)
		(drill 0.254)
		(layers "F.Cu" "B.Cu")
		(net "PVDDQ_KLM")
	)
	(via
		(at 16.129 -140.843)
		(size 0.508)
		(drill 0.254)
		(layers "F.Cu" "B.Cu")
		(net "PVDDQ_KLM")
	)
	(via
		(at 79.849472 -139.170156)
		(size 0.508)
		(drill 0.254)
		(layers "F.Cu" "B.Cu")
		(net "PVDDQ_KLM")
	)
	(via
		(at 20.701 -146.812)
		(size 0.508)
		(drill 0.254)
		(layers "F.Cu" "B.Cu")
		(net "PVDDQ_KLM")
	)
	(via
		(at 108.749846 -141.187678)
		(size 0.508)
		(drill 0.254)
		(layers "F.Cu" "B.Cu")
		(net "PVDDQ_KLM")
	)
	(via
		(at 105.777792 -86.014814)
		(size 0.508)
		(drill 0.254)
		(layers "F.Cu" "B.Cu")
		(net "PVDDQ_KLM")
	)
	(via
		(at 106.199432 -141.183868)
		(size 0.508)
		(drill 0.254)
		(layers "F.Cu" "B.Cu")
		(net "PVDDQ_KLM")
	)
	(via
		(at 16.891 -140.843)
		(size 0.508)
		(drill 0.254)
		(layers "F.Cu" "B.Cu")
		(net "PVDDQ_KLM")
	)
	(via
		(at 101.949504 -141.183868)
		(size 0.508)
		(drill 0.254)
		(layers "F.Cu" "B.Cu")
		(net "PVDDQ_KLM")
	)
	(via
		(at 86.64956 -130.249168)
		(size 0.508)
		(drill 0.254)
		(layers "F.Cu" "B.Cu")
		(net "PVDDQ_KLM")
	)
	(via
		(at 112.149382 -130.249168)
		(size 0.508)
		(drill 0.254)
		(layers "F.Cu" "B.Cu")
		(net "PVDDQ_KLM")
	)
	(via
		(at 93.266768 -143.970756)
		(size 0.508)
		(drill 0.254)
		(layers "F.Cu" "B.Cu")
		(net "PVDDQ_KLM")
	)
	(via
		(at 104.49941 -130.902456)
		(size 0.508)
		(drill 0.254)
		(layers "F.Cu" "B.Cu")
		(net "PVDDQ_KLM")
	)
	(via
		(at 103.649526 -148.769578)
		(size 0.508)
		(drill 0.254)
		(layers "F.Cu" "B.Cu")
		(net "PVDDQ_KLM")
	)
	(via
		(at 29.157168 -134.2644)
		(size 0.508)
		(drill 0.254)
		(layers "F.Cu" "B.Cu")
		(net "PVDDQ_KLM")
	)
	(via
		(at 89.199466 -148.773388)
		(size 0.508)
		(drill 0.254)
		(layers "F.Cu" "B.Cu")
		(net "PVDDQ_KLM")
	)
	(via
		(at 87.781892 -97.19564)
		(size 0.508)
		(drill 0.254)
		(layers "F.Cu" "B.Cu")
		(net "PVDDQ_KLM")
	)
	(via
		(at 20.701 -155.448)
		(size 0.508)
		(drill 0.254)
		(layers "F.Cu" "B.Cu")
		(net "PVDDQ_KLM")
	)
	(via
		(at 109.599476 -139.168378)
		(size 0.508)
		(drill 0.254)
		(layers "F.Cu" "B.Cu")
		(net "PVDDQ_KLM")
	)
	(via
		(at 19.177 -141.605)
		(size 0.508)
		(drill 0.254)
		(layers "F.Cu" "B.Cu")
		(net "PVDDQ_KLM")
	)
	(via
		(at 19.80184 -137.532872)
		(size 0.508)
		(drill 0.254)
		(layers "F.Cu" "B.Cu")
		(net "PVDDQ_KLM")
	)
	(via
		(at 20.701 -152.146)
		(size 0.508)
		(drill 0.254)
		(layers "F.Cu" "B.Cu")
		(net "PVDDQ_KLM")
	)
	(via
		(at 80.699356 -134.369556)
		(size 0.508)
		(drill 0.254)
		(layers "F.Cu" "B.Cu")
		(net "PVDDQ_KLM")
	)
	(via
		(at 101.94925 -154.252168)
		(size 0.508)
		(drill 0.254)
		(layers "F.Cu" "B.Cu")
		(net "PVDDQ_KLM")
	)
	(via
		(at 80.699356 -130.902456)
		(size 0.508)
		(drill 0.254)
		(layers "F.Cu" "B.Cu")
		(net "PVDDQ_KLM")
	)
	(via
		(at 19.939 -140.843)
		(size 0.508)
		(drill 0.254)
		(layers "F.Cu" "B.Cu")
		(net "PVDDQ_KLM")
	)
	(via
		(at 98.083878 -97.19564)
		(size 0.508)
		(drill 0.254)
		(layers "F.Cu" "B.Cu")
		(net "PVDDQ_KLM")
	)
	(via
		(at 101.099366 -139.168378)
		(size 0.508)
		(drill 0.254)
		(layers "F.Cu" "B.Cu")
		(net "PVDDQ_KLM")
	)
	(via
		(at 16.129 -151.384)
		(size 0.508)
		(drill 0.254)
		(layers "F.Cu" "B.Cu")
		(net "PVDDQ_KLM")
	)
	(via
		(at 19.80184 -136.770872)
		(size 0.508)
		(drill 0.254)
		(layers "F.Cu" "B.Cu")
		(net "PVDDQ_KLM")
	)
	(via
		(at 112.149382 -131.586478)
		(size 0.508)
		(drill 0.254)
		(layers "F.Cu" "B.Cu")
		(net "PVDDQ_KLM")
	)
	(via
		(at 100.659184 -92.737686)
		(size 0.508)
		(drill 0.254)
		(layers "F.Cu" "B.Cu")
		(net "PVDDQ_KLM")
	)
	(via
		(at 93.791278 -99.67214)
		(size 0.508)
		(drill 0.254)
		(layers "F.Cu" "B.Cu")
		(net "PVDDQ_KLM")
	)
	(via
		(at 17.912334 -136.754362)
		(size 0.508)
		(drill 0.254)
		(layers "F.Cu" "B.Cu")
		(net "PVDDQ_KLM")
	)
	(via
		(at 20.701 -142.621)
		(size 0.508)
		(drill 0.254)
		(layers "F.Cu" "B.Cu")
		(net "PVDDQ_KLM")
	)
	(via
		(at 89.435686 -154.919172)
		(size 0.508)
		(drill 0.254)
		(layers "F.Cu" "B.Cu")
		(net "PVDDQ_KLM")
	)
	(via
		(at 81.549494 -148.771356)
		(size 0.508)
		(drill 0.254)
		(layers "F.Cu" "B.Cu")
		(net "PVDDQ_KLM")
	)
	(via
		(at 17.653 -141.605)
		(size 0.508)
		(drill 0.254)
		(layers "F.Cu" "B.Cu")
		(net "PVDDQ_KLM")
	)
	(via
		(at 79.849472 -155.564078)
		(size 0.508)
		(drill 0.254)
		(layers "F.Cu" "B.Cu")
		(net "PVDDQ_KLM")
	)
	(via
		(at 112.149382 -136.387078)
		(size 0.508)
		(drill 0.254)
		(layers "F.Cu" "B.Cu")
		(net "PVDDQ_KLM")
	)
	(via
		(at 109.599476 -136.383268)
		(size 0.508)
		(drill 0.254)
		(layers "F.Cu" "B.Cu")
		(net "PVDDQ_KLM")
	)
	(via
		(at 20.701 -141.605)
		(size 0.508)
		(drill 0.254)
		(layers "F.Cu" "B.Cu")
		(net "PVDDQ_KLM")
	)
	(via
		(at 16.129 -142.621)
		(size 0.508)
		(drill 0.254)
		(layers "F.Cu" "B.Cu")
		(net "PVDDQ_KLM")
	)
	(via
		(at 81.549494 -139.170156)
		(size 0.508)
		(drill 0.254)
		(layers "F.Cu" "B.Cu")
		(net "PVDDQ_KLM")
	)
	(via
		(at 18.161 -147.828)
		(size 0.508)
		(drill 0.254)
		(layers "F.Cu" "B.Cu")
		(net "PVDDQ_KLM")
	)
	(via
		(at 84.0994 -129.568956)
		(size 0.508)
		(drill 0.254)
		(layers "F.Cu" "B.Cu")
		(net "PVDDQ_KLM")
	)
	(via
		(at 87.781892 -94.223586)
		(size 0.508)
		(drill 0.254)
		(layers "F.Cu" "B.Cu")
		(net "PVDDQ_KLM")
	)
	(via
		(at 90.90914 -141.183868)
		(size 0.508)
		(drill 0.254)
		(layers "F.Cu" "B.Cu")
		(net "PVDDQ_KLM")
	)
	(via
		(at 18.544286 -137.526776)
		(size 0.508)
		(drill 0.254)
		(layers "F.Cu" "B.Cu")
		(net "PVDDQ_KLM")
	)
	(via
		(at 20.701 -151.384)
		(size 0.508)
		(drill 0.254)
		(layers "F.Cu" "B.Cu")
		(net "PVDDQ_KLM")
	)
	(via
		(at 108.749338 -154.252168)
		(size 0.508)
		(drill 0.254)
		(layers "F.Cu" "B.Cu")
		(net "PVDDQ_KLM")
	)
	(via
		(at 16.637 -136.017)
		(size 0.508)
		(drill 0.254)
		(layers "F.Cu" "B.Cu")
		(net "PVDDQ_KLM")
	)
	(via
		(at 88.640412 -92.737686)
		(size 0.508)
		(drill 0.254)
		(layers "F.Cu" "B.Cu")
		(net "PVDDQ_KLM")
	)
	(via
		(at 102.376224 -99.67214)
		(size 0.508)
		(drill 0.254)
		(layers "F.Cu" "B.Cu")
		(net "PVDDQ_KLM")
	)
	(via
		(at 85.799422 -150.788878)
		(size 0.508)
		(drill 0.254)
		(layers "F.Cu" "B.Cu")
		(net "PVDDQ_KLM")
	)
	(via
		(at 92.074238 -92.737686)
		(size 0.508)
		(drill 0.254)
		(layers "F.Cu" "B.Cu")
		(net "PVDDQ_KLM")
	)
	(via
		(at 96.366838 -94.223586)
		(size 0.508)
		(drill 0.254)
		(layers "F.Cu" "B.Cu")
		(net "PVDDQ_KLM")
	)
	(via
		(at -0.7874 -135.633714)
		(size 0.508)
		(drill 0.254)
		(layers "F.Cu" "B.Cu")
		(net "PVDDQ_KLM")
	)
	(via
		(at 108.329476 -85.943694)
		(size 0.508)
		(drill 0.254)
		(layers "F.Cu" "B.Cu")
		(net "PVDDQ_KLM")
	)
	(via
		(at 89.498678 -94.223586)
		(size 0.508)
		(drill 0.254)
		(layers "F.Cu" "B.Cu")
		(net "PVDDQ_KLM")
	)
	(via
		(at 85.799422 -130.902456)
		(size 0.508)
		(drill 0.254)
		(layers "F.Cu" "B.Cu")
		(net "PVDDQ_KLM")
	)
	(via
		(at 103.491792 -86.014814)
		(size 0.508)
		(drill 0.254)
		(layers "F.Cu" "B.Cu")
		(net "PVDDQ_KLM")
	)
	(via
		(at 90.899488 -145.984468)
		(size 0.508)
		(drill 0.254)
		(layers "F.Cu" "B.Cu")
		(net "PVDDQ_KLM")
	)
	(via
		(at 19.939 -146.05)
		(size 0.508)
		(drill 0.254)
		(layers "F.Cu" "B.Cu")
		(net "PVDDQ_KLM")
	)
	(via
		(at 19.167094 -136.770872)
		(size 0.508)
		(drill 0.254)
		(layers "F.Cu" "B.Cu")
		(net "PVDDQ_KLM")
	)
	(via
		(at 93.449394 -134.380478)
		(size 0.508)
		(drill 0.254)
		(layers "F.Cu" "B.Cu")
		(net "PVDDQ_KLM")
	)
	(via
		(at 19.177 -152.908)
		(size 0.508)
		(drill 0.254)
		(layers "F.Cu" "B.Cu")
		(net "PVDDQ_KLM")
	)
	(via
		(at 84.0994 -145.988278)
		(size 0.508)
		(drill 0.254)
		(layers "F.Cu" "B.Cu")
		(net "PVDDQ_KLM")
	)
	(via
		(at 108.749846 -150.788878)
		(size 0.508)
		(drill 0.254)
		(layers "F.Cu" "B.Cu")
		(net "PVDDQ_KLM")
	)
	(via
		(at 108.749846 -143.972788)
		(size 0.4572)
		(drill 0.2032)
		(layers "F.Cu" "B.Cu")
		(net "PVDDQ_KLM")
	)
	(via
		(at 93.18371 -130.848608)
		(size 0.508)
		(drill 0.254)
		(layers "F.Cu" "B.Cu")
		(net "PVDDQ_KLM")
	)
	(via
		(at 112.149382 -155.589478)
		(size 0.508)
		(drill 0.254)
		(layers "F.Cu" "B.Cu")
		(net "PVDDQ_KLM")
	)
	(via
		(at 17.653 -142.621)
		(size 0.508)
		(drill 0.254)
		(layers "F.Cu" "B.Cu")
		(net "PVDDQ_KLM")
	)
	(via
		(at 16.891 -152.908)
		(size 0.508)
		(drill 0.254)
		(layers "F.Cu" "B.Cu")
		(net "PVDDQ_KLM")
	)
	(via
		(at 17.653 -152.146)
		(size 0.508)
		(drill 0.254)
		(layers "F.Cu" "B.Cu")
		(net "PVDDQ_KLM")
	)
	(via
		(at 17.399 -136.017)
		(size 0.508)
		(drill 0.254)
		(layers "F.Cu" "B.Cu")
		(net "PVDDQ_KLM")
	)
	(via
		(at 93.26118 -155.386786)
		(size 0.508)
		(drill 0.254)
		(layers "F.Cu" "B.Cu")
		(net "PVDDQ_KLM")
	)
	(via
		(at 168.4274 -145.8468)
		(size 0.508)
		(drill 0.254)
		(layers "F.Cu" "B.Cu")
		(net "PVDDQ_KLM")
	)
	(via
		(at 106.199432 -130.902456)
		(size 0.508)
		(drill 0.254)
		(layers "F.Cu" "B.Cu")
		(net "PVDDQ_KLM")
	)
	(via
		(at 20.701 -147.828)
		(size 0.508)
		(drill 0.254)
		(layers "F.Cu" "B.Cu")
		(net "PVDDQ_KLM")
	)
	(via
		(at 109.599476 -129.539746)
		(size 0.508)
		(drill 0.254)
		(layers "F.Cu" "B.Cu")
		(net "PVDDQ_KLM")
	)
	(via
		(at 19.939 -141.605)
		(size 0.508)
		(drill 0.254)
		(layers "F.Cu" "B.Cu")
		(net "PVDDQ_KLM")
	)
	(via
		(at 17.906492 -137.514076)
		(size 0.508)
		(drill 0.254)
		(layers "F.Cu" "B.Cu")
		(net "PVDDQ_KLM")
	)
	(via
		(at 88.640412 -99.67214)
		(size 0.508)
		(drill 0.254)
		(layers "F.Cu" "B.Cu")
		(net "PVDDQ_KLM")
	)
	(via
		(at 88.349582 -131.611878)
		(size 0.508)
		(drill 0.254)
		(layers "F.Cu" "B.Cu")
		(net "PVDDQ_KLM")
	)
	(via
		(at 110.449868 -150.788878)
		(size 0.508)
		(drill 0.254)
		(layers "F.Cu" "B.Cu")
		(net "PVDDQ_KLM")
	)
	(via
		(at 20.418806 -137.532872)
		(size 0.508)
		(drill 0.254)
		(layers "F.Cu" "B.Cu")
		(net "PVDDQ_KLM")
	)
	(via
		(at 86.923372 -89.765886)
		(size 0.508)
		(drill 0.254)
		(layers "F.Cu" "B.Cu")
		(net "PVDDQ_KLM")
	)
	(via
		(at 89.199466 -145.988278)
		(size 0.508)
		(drill 0.254)
		(layers "F.Cu" "B.Cu")
		(net "PVDDQ_KLM")
	)
	(via
		(at 18.923 -146.05)
		(size 0.508)
		(drill 0.254)
		(layers "F.Cu" "B.Cu")
		(net "PVDDQ_KLM")
	)
	(via
		(at 112.149382 -154.252168)
		(size 0.508)
		(drill 0.254)
		(layers "F.Cu" "B.Cu")
		(net "PVDDQ_KLM")
	)
	(via
		(at 104.499664 -143.972788)
		(size 0.4572)
		(drill 0.2032)
		(layers "F.Cu" "B.Cu")
		(net "PVDDQ_KLM")
	)
	(via
		(at 90.684604 -150.785068)
		(size 0.508)
		(drill 0.254)
		(layers "F.Cu" "B.Cu")
		(net "PVDDQ_KLM")
	)
	(via
		(at 83.249516 -131.611878)
		(size 0.508)
		(drill 0.254)
		(layers "F.Cu" "B.Cu")
		(net "PVDDQ_KLM")
	)
	(via
		(at 94.00032 -141.1478)
		(size 0.508)
		(drill 0.254)
		(layers "F.Cu" "B.Cu")
		(net "PVDDQ_KLM")
	)
	(via
		(at 78.999334 -153.571956)
		(size 0.508)
		(drill 0.254)
		(layers "F.Cu" "B.Cu")
		(net "PVDDQ_KLM")
	)
	(via
		(at 108.749846 -134.371588)
		(size 0.4572)
		(drill 0.2032)
		(layers "F.Cu" "B.Cu")
		(net "PVDDQ_KLM")
	)
	(via
		(at 84.0994 -136.387078)
		(size 0.508)
		(drill 0.254)
		(layers "F.Cu" "B.Cu")
		(net "PVDDQ_KLM")
	)
	(via
		(at 103.268272 -102.227634)
		(size 0.508)
		(drill 0.254)
		(layers "F.Cu" "B.Cu")
		(net "PVDDQ_KLM")
	)
	(via
		(at 93.271594 -141.183868)
		(size 0.508)
		(drill 0.254)
		(layers "F.Cu" "B.Cu")
		(net "PVDDQ_KLM")
	)
	(via
		(at 83.249516 -143.970756)
		(size 0.508)
		(drill 0.254)
		(layers "F.Cu" "B.Cu")
		(net "PVDDQ_KLM")
	)
	(via
		(at 18.415 -142.621)
		(size 0.508)
		(drill 0.254)
		(layers "F.Cu" "B.Cu")
		(net "PVDDQ_KLM")
	)
	(via
		(at 16.891 -151.384)
		(size 0.508)
		(drill 0.254)
		(layers "F.Cu" "B.Cu")
		(net "PVDDQ_KLM")
	)
	(via
		(at 83.249516 -134.369556)
		(size 0.508)
		(drill 0.254)
		(layers "F.Cu" "B.Cu")
		(net "PVDDQ_KLM")
	)
	(via
		(at 104.499664 -150.788878)
		(size 0.508)
		(drill 0.254)
		(layers "F.Cu" "B.Cu")
		(net "PVDDQ_KLM")
	)
	(via
		(at 107.899454 -148.769578)
		(size 0.508)
		(drill 0.254)
		(layers "F.Cu" "B.Cu")
		(net "PVDDQ_KLM")
	)
	(via
		(at 109.599476 -154.905456)
		(size 0.508)
		(drill 0.254)
		(layers "F.Cu" "B.Cu")
		(net "PVDDQ_KLM")
	)
	(via
		(at 106.199432 -139.168378)
		(size 0.508)
		(drill 0.254)
		(layers "F.Cu" "B.Cu")
		(net "PVDDQ_KLM")
	)
	(via
		(at 84.0994 -154.905456)
		(size 0.508)
		(drill 0.254)
		(layers "F.Cu" "B.Cu")
		(net "PVDDQ_KLM")
	)
	(via
		(at 102.376224 -92.737686)
		(size 0.508)
		(drill 0.254)
		(layers "F.Cu" "B.Cu")
		(net "PVDDQ_KLM")
	)
	(via
		(at 86.64956 -136.387078)
		(size 0.508)
		(drill 0.254)
		(layers "F.Cu" "B.Cu")
		(net "PVDDQ_KLM")
	)
	(via
		(at 110.030768 -126.4031)
		(size 0.508)
		(drill 0.254)
		(layers "F.Cu" "B.Cu")
		(net "PVDDQ_KLM")
	)
	(via
		(at 18.161 -146.05)
		(size 0.508)
		(drill 0.254)
		(layers "F.Cu" "B.Cu")
		(net "PVDDQ_KLM")
	)
	(via
		(at 99.513898 -102.3112)
		(size 0.508)
		(drill 0.254)
		(layers "F.Cu" "B.Cu")
		(net "PVDDQ_KLM")
	)
	(via
		(at 18.415 -152.908)
		(size 0.508)
		(drill 0.254)
		(layers "F.Cu" "B.Cu")
		(net "PVDDQ_KLM")
	)
	(via
		(at 20.701 -146.05)
		(size 0.508)
		(drill 0.254)
		(layers "F.Cu" "B.Cu")
		(net "PVDDQ_KLM")
	)
	(via
		(at 92.932758 -94.223586)
		(size 0.508)
		(drill 0.254)
		(layers "F.Cu" "B.Cu")
		(net "PVDDQ_KLM")
	)
	(via
		(at 93.449394 -153.571956)
		(size 0.508)
		(drill 0.254)
		(layers "F.Cu" "B.Cu")
		(net "PVDDQ_KLM")
	)
	(via
		(at 110.449868 -143.972788)
		(size 0.4572)
		(drill 0.2032)
		(layers "F.Cu" "B.Cu")
		(net "PVDDQ_KLM")
	)
	(via
		(at 93.19006 -148.844)
		(size 0.508)
		(drill 0.254)
		(layers "F.Cu" "B.Cu")
		(net "PVDDQ_KLM")
	)
	(via
		(at 100.240592 -85.938614)
		(size 0.508)
		(drill 0.254)
		(layers "F.Cu" "B.Cu")
		(net "PVDDQ_KLM")
	)
	(via
		(at 18.923 -147.828)
		(size 0.508)
		(drill 0.254)
		(layers "F.Cu" "B.Cu")
		(net "PVDDQ_KLM")
	)
	(via
		(at 90.357198 -92.737686)
		(size 0.508)
		(drill 0.254)
		(layers "F.Cu" "B.Cu")
		(net "PVDDQ_KLM")
	)
	(via
		(at 110.44936 -131.611878)
		(size 0.508)
		(drill 0.254)
		(layers "F.Cu" "B.Cu")
		(net "PVDDQ_KLM")
	)
	(via
		(at 19.177 -142.621)
		(size 0.508)
		(drill 0.254)
		(layers "F.Cu" "B.Cu")
		(net "PVDDQ_KLM")
	)
	(via
		(at 18.544286 -136.764776)
		(size 0.508)
		(drill 0.254)
		(layers "F.Cu" "B.Cu")
		(net "PVDDQ_KLM")
	)
	(via
		(at 90.899488 -155.509468)
		(size 0.508)
		(drill 0.254)
		(layers "F.Cu" "B.Cu")
		(net "PVDDQ_KLM")
	)
	(via
		(at 17.4498 -135.2296)
		(size 0.6604)
		(drill 0.3302)
		(layers "F.Cu" "B.Cu")
		(net "PVDDQ_KLM")
	)
	(via
		(at 91.165172 -129.568956)
		(size 0.508)
		(drill 0.254)
		(layers "F.Cu" "B.Cu")
		(net "PVDDQ_KLM")
	)
	(via
		(at 18.415 -156.337)
		(size 0.508)
		(drill 0.254)
		(layers "F.Cu" "B.Cu")
		(net "PVDDQ_KLM")
	)
	(via
		(at 98.942398 -92.737686)
		(size 0.508)
		(drill 0.254)
		(layers "F.Cu" "B.Cu")
		(net "PVDDQ_KLM")
	)
	(via
		(at 110.44936 -154.252168)
		(size 0.508)
		(drill 0.254)
		(layers "F.Cu" "B.Cu")
		(net "PVDDQ_KLM")
	)
	(via
		(at 19.939 -156.337)
		(size 0.508)
		(drill 0.254)
		(layers "F.Cu" "B.Cu")
		(net "PVDDQ_KLM")
	)
	(via
		(at 90.68435 -148.771356)
		(size 0.508)
		(drill 0.254)
		(layers "F.Cu" "B.Cu")
		(net "PVDDQ_KLM")
	)
	(via
		(at 91.196668 -130.8608)
		(size 0.508)
		(drill 0.254)
		(layers "F.Cu" "B.Cu")
		(net "PVDDQ_KLM")
	)
	(via
		(at 102.526592 -85.938614)
		(size 0.508)
		(drill 0.254)
		(layers "F.Cu" "B.Cu")
		(net "PVDDQ_KLM")
	)
	(via
		(at 84.0994 -139.170156)
		(size 0.508)
		(drill 0.254)
		(layers "F.Cu" "B.Cu")
		(net "PVDDQ_KLM")
	)
	(via
		(at 90.90914 -136.328658)
		(size 0.508)
		(drill 0.254)
		(layers "F.Cu" "B.Cu")
		(net "PVDDQ_KLM")
	)
	(via
		(at 94.649798 -97.19564)
		(size 0.508)
		(drill 0.254)
		(layers "F.Cu" "B.Cu")
		(net "PVDDQ_KLM")
	)
	(via
		(at 101.949758 -134.371588)
		(size 0.4572)
		(drill 0.2032)
		(layers "F.Cu" "B.Cu")
		(net "PVDDQ_KLM")
	)
	(via
		(at 112.149382 -150.785068)
		(size 0.508)
		(drill 0.254)
		(layers "F.Cu" "B.Cu")
		(net "PVDDQ_KLM")
	)
	(via
		(at 99.800664 -94.223586)
		(size 0.508)
		(drill 0.254)
		(layers "F.Cu" "B.Cu")
		(net "PVDDQ_KLM")
	)
	(via
		(at 93.393768 -139.170156)
		(size 0.508)
		(drill 0.254)
		(layers "F.Cu" "B.Cu")
		(net "PVDDQ_KLM")
	)
	(via
		(at 78.999334 -143.970756)
		(size 0.508)
		(drill 0.254)
		(layers "F.Cu" "B.Cu")
		(net "PVDDQ_KLM")
	)
	(via
		(at 105.142792 -86.014814)
		(size 0.508)
		(drill 0.254)
		(layers "F.Cu" "B.Cu")
		(net "PVDDQ_KLM")
	)
	(via
		(at 112.149382 -141.183868)
		(size 0.508)
		(drill 0.254)
		(layers "F.Cu" "B.Cu")
		(net "PVDDQ_KLM")
	)
	(via
		(at 16.129 -152.908)
		(size 0.508)
		(drill 0.254)
		(layers "F.Cu" "B.Cu")
		(net "PVDDQ_KLM")
	)
	(via
		(at 106.199432 -145.984468)
		(size 0.508)
		(drill 0.254)
		(layers "F.Cu" "B.Cu")
		(net "PVDDQ_KLM")
	)
	(via
		(at 79.849472 -148.771356)
		(size 0.508)
		(drill 0.254)
		(layers "F.Cu" "B.Cu")
		(net "PVDDQ_KLM")
	)
	(via
		(at 19.177 -156.337)
		(size 0.508)
		(drill 0.254)
		(layers "F.Cu" "B.Cu")
		(net "PVDDQ_KLM")
	)
	(via
		(at 110.449868 -134.371588)
		(size 0.4572)
		(drill 0.2032)
		(layers "F.Cu" "B.Cu")
		(net "PVDDQ_KLM")
	)
	(via
		(at 19.939 -152.908)
		(size 0.508)
		(drill 0.254)
		(layers "F.Cu" "B.Cu")
		(net "PVDDQ_KLM")
	)
	(via
		(at 19.939 -147.828)
		(size 0.508)
		(drill 0.254)
		(layers "F.Cu" "B.Cu")
		(net "PVDDQ_KLM")
	)
	(via
		(at 101.099366 -154.905456)
		(size 0.508)
		(drill 0.254)
		(layers "F.Cu" "B.Cu")
		(net "PVDDQ_KLM")
	)
	(via
		(at 85.799422 -143.970756)
		(size 0.508)
		(drill 0.254)
		(layers "F.Cu" "B.Cu")
		(net "PVDDQ_KLM")
	)
	(via
		(at 112.149382 -145.984468)
		(size 0.508)
		(drill 0.254)
		(layers "F.Cu" "B.Cu")
		(net "PVDDQ_KLM")
	)
	(via
		(at 19.177 -151.384)
		(size 0.508)
		(drill 0.254)
		(layers "F.Cu" "B.Cu")
		(net "PVDDQ_KLM")
	)
	(via
		(at 96.366838 -99.17684)
		(size 0.508)
		(drill 0.254)
		(layers "F.Cu" "B.Cu")
		(net "PVDDQ_KLM")
	)
	(via
		(at 96.366838 -97.19564)
		(size 0.508)
		(drill 0.254)
		(layers "F.Cu" "B.Cu")
		(net "PVDDQ_KLM")
	)
	(via
		(at 18.415 -152.146)
		(size 0.508)
		(drill 0.254)
		(layers "F.Cu" "B.Cu")
		(net "PVDDQ_KLM")
	)
	(via
		(at 80.699356 -153.571956)
		(size 0.508)
		(drill 0.254)
		(layers "F.Cu" "B.Cu")
		(net "PVDDQ_KLM")
	)
	(via
		(at 17.653 -156.337)
		(size 0.508)
		(drill 0.254)
		(layers "F.Cu" "B.Cu")
		(net "PVDDQ_KLM")
	)
	(via
		(at 106.5276 -86.0044)
		(size 0.508)
		(drill 0.254)
		(layers "F.Cu" "B.Cu")
		(net "PVDDQ_KLM")
	)
	(via
		(at 18.161 -146.812)
		(size 0.508)
		(drill 0.254)
		(layers "F.Cu" "B.Cu")
		(net "PVDDQ_KLM")
	)
	(via
		(at 81.549494 -130.249168)
		(size 0.508)
		(drill 0.254)
		(layers "F.Cu" "B.Cu")
		(net "PVDDQ_KLM")
	)
	(via
		(at 93.266768 -145.984468)
		(size 0.508)
		(drill 0.254)
		(layers "F.Cu" "B.Cu")
		(net "PVDDQ_KLM")
	)
	(via
		(at 92.074238 -99.67214)
		(size 0.508)
		(drill 0.254)
		(layers "F.Cu" "B.Cu")
		(net "PVDDQ_KLM")
	)
	(via
		(at 78.999334 -134.369556)
		(size 0.508)
		(drill 0.254)
		(layers "F.Cu" "B.Cu")
		(net "PVDDQ_KLM")
	)
	(via
		(at 16.129 -141.605)
		(size 0.508)
		(drill 0.254)
		(layers "F.Cu" "B.Cu")
		(net "PVDDQ_KLM")
	)
	(via
		(at 88.349582 -143.972788)
		(size 0.508)
		(drill 0.254)
		(layers "F.Cu" "B.Cu")
		(net "PVDDQ_KLM")
	)
	(via
		(at 88.349582 -154.252168)
		(size 0.508)
		(drill 0.254)
		(layers "F.Cu" "B.Cu")
		(net "PVDDQ_KLM")
	)
	(via
		(at 93.393768 -136.1948)
		(size 0.508)
		(drill 0.254)
		(layers "F.Cu" "B.Cu")
		(net "PVDDQ_KLM")
	)
	(via
		(at 112.149382 -148.769578)
		(size 0.508)
		(drill 0.254)
		(layers "F.Cu" "B.Cu")
		(net "PVDDQ_KLM")
	)
	(via
		(at 20.701 -156.337)
		(size 0.508)
		(drill 0.254)
		(layers "F.Cu" "B.Cu")
		(net "PVDDQ_KLM")
	)
	(via
		(at 86.923372 -92.737686)
		(size 0.508)
		(drill 0.254)
		(layers "F.Cu" "B.Cu")
		(net "PVDDQ_KLM")
	)
	(via
		(at 99.226878 -100.167186)
		(size 0.508)
		(drill 0.254)
		(layers "F.Cu" "B.Cu")
		(net "PVDDQ_KLM")
	)
	(via
		(at 90.357198 -99.67214)
		(size 0.508)
		(drill 0.254)
		(layers "F.Cu" "B.Cu")
		(net "PVDDQ_KLM")
	)
	(via
		(at 85.799422 -141.187678)
		(size 0.508)
		(drill 0.254)
		(layers "F.Cu" "B.Cu")
		(net "PVDDQ_KLM")
	)
	(via
		(at 91.215718 -94.223586)
		(size 0.508)
		(drill 0.254)
		(layers "F.Cu" "B.Cu")
		(net "PVDDQ_KLM")
	)
	(via
		(at 106.199432 -134.367778)
		(size 0.508)
		(drill 0.254)
		(layers "F.Cu" "B.Cu")
		(net "PVDDQ_KLM")
	)
	(via
		(at 80.699356 -143.970756)
		(size 0.508)
		(drill 0.254)
		(layers "F.Cu" "B.Cu")
		(net "PVDDQ_KLM")
	)
	(via
		(at 103.649526 -145.984468)
		(size 0.508)
		(drill 0.254)
		(layers "F.Cu" "B.Cu")
		(net "PVDDQ_KLM")
	)
	(via
		(at 89.199466 -136.387078)
		(size 0.508)
		(drill 0.254)
		(layers "F.Cu" "B.Cu")
		(net "PVDDQ_KLM")
	)
	(via
		(at 88.640412 -89.765886)
		(size 0.508)
		(drill 0.254)
		(layers "F.Cu" "B.Cu")
		(net "PVDDQ_KLM")
	)
	(via
		(at 110.449868 -141.187678)
		(size 0.508)
		(drill 0.254)
		(layers "F.Cu" "B.Cu")
		(net "PVDDQ_KLM")
	)
	(via
		(at 17.653 -152.908)
		(size 0.508)
		(drill 0.254)
		(layers "F.Cu" "B.Cu")
		(net "PVDDQ_KLM")
	)
	(via
		(at 95.508318 -99.67214)
		(size 0.508)
		(drill 0.254)
		(layers "F.Cu" "B.Cu")
		(net "PVDDQ_KLM")
	)
	(via
		(at 86.064852 -97.19564)
		(size 0.508)
		(drill 0.254)
		(layers "F.Cu" "B.Cu")
		(net "PVDDQ_KLM")
	)
	(via
		(at 86.64956 -139.172188)
		(size 0.508)
		(drill 0.254)
		(layers "F.Cu" "B.Cu")
		(net "PVDDQ_KLM")
	)
	(via
		(at 101.94925 -131.611878)
		(size 0.508)
		(drill 0.254)
		(layers "F.Cu" "B.Cu")
		(net "PVDDQ_KLM")
	)
	(via
		(at 104.499664 -134.371588)
		(size 0.4572)
		(drill 0.2032)
		(layers "F.Cu" "B.Cu")
		(net "PVDDQ_KLM")
	)
	(via
		(at 169.0878 -145.8468)
		(size 0.508)
		(drill 0.254)
		(layers "F.Cu" "B.Cu")
		(net "PVDDQ_KLM")
	)
	(via
		(at 19.939 -151.384)
		(size 0.508)
		(drill 0.254)
		(layers "F.Cu" "B.Cu")
		(net "PVDDQ_KLM")
	)
	(via
		(at 106.199432 -129.539746)
		(size 0.508)
		(drill 0.254)
		(layers "F.Cu" "B.Cu")
		(net "PVDDQ_KLM")
	)
	(via
		(at 83.249516 -154.252168)
		(size 0.508)
		(drill 0.254)
		(layers "F.Cu" "B.Cu")
		(net "PVDDQ_KLM")
	)
	(via
		(at 95.508318 -92.737686)
		(size 0.508)
		(drill 0.254)
		(layers "F.Cu" "B.Cu")
		(net "PVDDQ_KLM")
	)
	(via
		(at 90.928698 -102.3112)
		(size 0.508)
		(drill 0.254)
		(layers "F.Cu" "B.Cu")
		(net "PVDDQ_KLM")
	)
	(via
		(at 78.999334 -130.902456)
		(size 0.508)
		(drill 0.254)
		(layers "F.Cu" "B.Cu")
		(net "PVDDQ_KLM")
	)
	(via
		(at 18.415 -151.384)
		(size 0.508)
		(drill 0.254)
		(layers "F.Cu" "B.Cu")
		(net "PVDDQ_KLM")
	)
	(via
		(at 19.939 -146.812)
		(size 0.508)
		(drill 0.254)
		(layers "F.Cu" "B.Cu")
		(net "PVDDQ_KLM")
	)
	(via
		(at 29.157168 -153.5684)
		(size 0.508)
		(drill 0.254)
		(layers "F.Cu" "B.Cu")
		(net "PVDDQ_KLM")
	)
	(via
		(at 89.498678 -97.19564)
		(size 0.508)
		(drill 0.254)
		(layers "F.Cu" "B.Cu")
		(net "PVDDQ_KLM")
	)
	(via
		(at 85.799422 -153.542746)
		(size 0.508)
		(drill 0.254)
		(layers "F.Cu" "B.Cu")
		(net "PVDDQ_KLM")
	)
	(via
		(at 101.891592 -85.938614)
		(size 0.508)
		(drill 0.254)
		(layers "F.Cu" "B.Cu")
		(net "PVDDQ_KLM")
	)
	(via
		(at 112.149382 -134.367778)
		(size 0.508)
		(drill 0.254)
		(layers "F.Cu" "B.Cu")
		(net "PVDDQ_KLM")
	)
	(via
		(at 90.899488 -153.571956)
		(size 0.508)
		(drill 0.254)
		(layers "F.Cu" "B.Cu")
		(net "PVDDQ_KLM")
	)
	(via
		(at 96.079818 -102.3112)
		(size 0.508)
		(drill 0.254)
		(layers "F.Cu" "B.Cu")
		(net "PVDDQ_KLM")
	)
	(via
		(at 89.124028 -129.539746)
		(size 0.508)
		(drill 0.254)
		(layers "F.Cu" "B.Cu")
		(net "PVDDQ_KLM")
	)
	(via
		(at 86.64956 -145.988278)
		(size 0.508)
		(drill 0.254)
		(layers "F.Cu" "B.Cu")
		(net "PVDDQ_KLM")
	)
	(via
		(at 20.701 -140.843)
		(size 0.508)
		(drill 0.254)
		(layers "F.Cu" "B.Cu")
		(net "PVDDQ_KLM")
	)
	(via
		(at 107.899454 -154.905456)
		(size 0.508)
		(drill 0.254)
		(layers "F.Cu" "B.Cu")
		(net "PVDDQ_KLM")
	)
	(via
		(at 93.449394 -150.785068)
		(size 0.508)
		(drill 0.254)
		(layers "F.Cu" "B.Cu")
		(net "PVDDQ_KLM")
	)
	(via
		(at 103.649272 -155.614878)
		(size 0.508)
		(drill 0.254)
		(layers "F.Cu" "B.Cu")
		(net "PVDDQ_KLM")
	)
	(via
		(at 19.177 -140.843)
		(size 0.508)
		(drill 0.254)
		(layers "F.Cu" "B.Cu")
		(net "PVDDQ_KLM")
	)
	(via
		(at 164.4269 -144.430242)
		(size 0.508)
		(drill 0.254)
		(layers "F.Cu" "B.Cu")
		(net "PVDDQ_KLM")
	)
	(via
		(at 16.891 -142.621)
		(size 0.508)
		(drill 0.254)
		(layers "F.Cu" "B.Cu")
		(net "PVDDQ_KLM")
	)
	(via
		(at 78.999334 -150.788878)
		(size 0.508)
		(drill 0.254)
		(layers "F.Cu" "B.Cu")
		(net "PVDDQ_KLM")
	)
	(via
		(at 19.177 -152.146)
		(size 0.508)
		(drill 0.254)
		(layers "F.Cu" "B.Cu")
		(net "PVDDQ_KLM")
	)
	(via
		(at 107.899454 -129.568956)
		(size 0.508)
		(drill 0.254)
		(layers "F.Cu" "B.Cu")
		(net "PVDDQ_KLM")
	)
	(via
		(at 90.90914 -143.970756)
		(size 0.508)
		(drill 0.254)
		(layers "F.Cu" "B.Cu")
		(net "PVDDQ_KLM")
	)
	(segment
		(start 85.799422 -142.477236)
		(end 85.799422 -141.187678)
		(width 0.4064)
		(layer "B.Cu")
		(net "PVDDQ_KLM")
	)
	(segment
		(start 79.849472 -136.387078)
		(end 79.849472 -137.877296)
		(width 0.4064)
		(layer "B.Cu")
		(net "PVDDQ_KLM")
	)
	(segment
		(start 106.199432 -155.829)
		(end 106.199432 -154.905456)
		(width 0.4064)
		(layer "B.Cu")
		(net "PVDDQ_KLM")
	)
	(segment
		(start 90.899488 -152.078436)
		(end 90.899488 -150.999952)
		(width 0.4064)
		(layer "B.Cu")
		(net "PVDDQ_KLM")
	)
	(segment
		(start 79.849472 -130.249168)
		(end 79.849472 -128.276096)
		(width 0.4064)
		(layer "B.Cu")
		(net "PVDDQ_KLM")
	)
	(segment
		(start 81.549494 -130.249168)
		(end 81.352644 -130.249168)
		(width 0.4064)
		(layer "B.Cu")
		(net "PVDDQ_KLM")
	)
	(segment
		(start 88.349582 -154.252168)
		(end 88.349582 -152.078436)
		(width 0.4064)
		(layer "B.Cu")
		(net "PVDDQ_KLM")
	)
	(segment
		(start 93.449394 -128.275842)
		(end 93.449902 -128.27635)
		(width 0.4064)
		(layer "B.Cu")
		(net "PVDDQ_KLM")
	)
	(segment
		(start 80.81518 -126.50724)
		(end 81.549494 -127.241554)
		(width 0.4064)
		(layer "B.Cu")
		(net "PVDDQ_KLM")
	)
	(segment
		(start 110.318296 -156.910024)
		(end 110.318296 -156.37002)
		(width 0.4064)
		(layer "B.Cu")
		(net "PVDDQ_KLM")
	)
	(segment
		(start 101.949504 -141.183868)
		(end 101.949504 -142.477236)
		(width 0.4064)
		(layer "B.Cu")
		(net "PVDDQ_KLM")
	)
	(segment
		(start 90.899488 -153.571956)
		(end 90.899488 -152.078436)
		(width 0.4064)
		(layer "B.Cu")
		(net "PVDDQ_KLM")
	)
	(segment
		(start 90.899488 -129.303272)
		(end 91.165172 -129.568956)
		(width 0.4064)
		(layer "B.Cu")
		(net "PVDDQ_KLM")
	)
	(segment
		(start 112.149382 -132.876036)
		(end 112.149382 -131.586478)
		(width 0.4064)
		(layer "B.Cu")
		(net "PVDDQ_KLM")
	)
	(segment
		(start 78.999334 -142.477236)
		(end 78.999334 -143.970756)
		(width 0.4064)
		(layer "B.Cu")
		(net "PVDDQ_KLM")
	)
	(segment
		(start 156.414978 -119.384826)
		(end 156.414978 -119.302022)
		(width 0.254)
		(layer "B.Cu")
		(net "PVDDQ_KLM")
	)
	(segment
		(start 89.199466 -145.988278)
		(end 89.199466 -147.478496)
		(width 0.4064)
		(layer "B.Cu")
		(net "PVDDQ_KLM")
	)
	(segment
		(start 106.199432 -152.078436)
		(end 106.199432 -153.542746)
		(width 0.4064)
		(layer "B.Cu")
		(net "PVDDQ_KLM")
	)
	(segment
		(start 90.899488 -147.478496)
		(end 90.899488 -145.984468)
		(width 0.4064)
		(layer "B.Cu")
		(net "PVDDQ_KLM")
	)
	(segment
		(start 85.799422 -153.542746)
		(end 85.799422 -152.078436)
		(width 0.4064)
		(layer "B.Cu")
		(net "PVDDQ_KLM")
	)
	(segment
		(start 108.749846 -150.788878)
		(end 108.749338 -150.789386)
		(width 0.4064)
		(layer "B.Cu")
		(net "PVDDQ_KLM")
	)
	(segment
		(start 104.49941 -153.573734)
		(end 104.49941 -153.571956)
		(width 0.4064)
		(layer "B.Cu")
		(net "PVDDQ_KLM")
	)
	(segment
		(start 93.449394 -147.478496)
		(end 93.449394 -148.584666)
		(width 0.381)
		(layer "B.Cu")
		(net "PVDDQ_KLM")
	)
	(segment
		(start 90.899488 -134.340346)
		(end 90.899488 -132.876036)
		(width 0.4064)
		(layer "B.Cu")
		(net "PVDDQ_KLM")
	)
	(segment
		(start 93.449394 -128.276096)
		(end 93.449394 -128.275842)
		(width 0.4064)
		(layer "B.Cu")
		(net "PVDDQ_KLM")
	)
	(segment
		(start 101.099366 -145.984468)
		(end 101.099366 -147.478496)
		(width 0.4064)
		(layer "B.Cu")
		(net "PVDDQ_KLM")
	)
	(segment
		(start 84.0994 -147.478496)
		(end 84.0994 -148.771356)
		(width 0.4064)
		(layer "B.Cu")
		(net "PVDDQ_KLM")
	)
	(segment
		(start 28.547568 -144.0942)
		(end 28.877768 -143.764)
		(width 0.4064)
		(layer "B.Cu")
		(net "PVDDQ_KLM")
	)
	(segment
		(start 110.44936 -141.188186)
		(end 110.449868 -141.187678)
		(width 0.4064)
		(layer "B.Cu")
		(net "PVDDQ_KLM")
	)
	(segment
		(start 108.749338 -141.188186)
		(end 108.749846 -141.187678)
		(width 0.4064)
		(layer "B.Cu")
		(net "PVDDQ_KLM")
	)
	(segment
		(start 107.899454 -145.984468)
		(end 107.899454 -147.478496)
		(width 0.4064)
		(layer "B.Cu")
		(net "PVDDQ_KLM")
	)
	(segment
		(start 78.999334 -152.078436)
		(end 78.999334 -153.571956)
		(width 0.4064)
		(layer "B.Cu")
		(net "PVDDQ_KLM")
	)
	(segment
		(start 88.349582 -142.477236)
		(end 88.349582 -143.972788)
		(width 0.4064)
		(layer "B.Cu")
		(net "PVDDQ_KLM")
	)
	(segment
		(start 103.649272 -155.614878)
		(end 103.649272 -156.594048)
		(width 0.4064)
		(layer "B.Cu")
		(net "PVDDQ_KLM")
	)
	(segment
		(start 112.149382 -139.168378)
		(end 112.149382 -137.877296)
		(width 0.4064)
		(layer "B.Cu")
		(net "PVDDQ_KLM")
	)
	(segment
		(start 93.449902 -132.875274)
		(end 93.449394 -132.875782)
		(width 0.4064)
		(layer "B.Cu")
		(net "PVDDQ_KLM")
	)
	(segment
		(start 81.1022 -124.87402)
		(end 80.81518 -125.16104)
		(width 0.254)
		(layer "B.Cu")
		(net "PVDDQ_KLM")
	)
	(segment
		(start 88.349582 -142.477236)
		(end 88.349582 -141.187678)
		(width 0.4064)
		(layer "B.Cu")
		(net "PVDDQ_KLM")
	)
	(segment
		(start 90.899488 -137.877296)
		(end 90.899488 -139.119356)
		(width 0.4064)
		(layer "B.Cu")
		(net "PVDDQ_KLM")
	)
	(segment
		(start 110.449868 -150.788878)
		(end 110.44936 -150.789386)
		(width 0.4064)
		(layer "B.Cu")
		(net "PVDDQ_KLM")
	)
	(segment
		(start 79.849472 -147.478496)
		(end 79.849472 -145.988278)
		(width 0.4064)
		(layer "B.Cu")
		(net "PVDDQ_KLM")
	)
	(segment
		(start 88.349582 -132.876036)
		(end 88.349582 -131.611878)
		(width 0.4064)
		(layer "B.Cu")
		(net "PVDDQ_KLM")
	)
	(segment
		(start 78.999334 -130.902456)
		(end 79.652622 -130.249168)
		(width 0.4064)
		(layer "B.Cu")
		(net "PVDDQ_KLM")
	)
	(segment
		(start 93.18371 -130.848608)
		(end 93.449902 -131.1148)
		(width 0.4064)
		(layer "B.Cu")
		(net "PVDDQ_KLM")
	)
	(segment
		(start 85.799422 -132.876036)
		(end 85.799422 -134.340346)
		(width 0.4064)
		(layer "B.Cu")
		(net "PVDDQ_KLM")
	)
	(segment
		(start 90.899488 -136.33831)
		(end 90.90914 -136.328658)
		(width 0.4064)
		(layer "B.Cu")
		(net "PVDDQ_KLM")
	)
	(segment
		(start 101.099366 -137.877296)
		(end 101.099366 -139.168378)
		(width 0.4064)
		(layer "B.Cu")
		(net "PVDDQ_KLM")
	)
	(segment
		(start 28.674568 -154.559)
		(end 28.674568 -154.051)
		(width 0.4064)
		(layer "B.Cu")
		(net "PVDDQ_KLM")
	)
	(segment
		(start 80.699356 -134.369556)
		(end 80.699356 -132.876036)
		(width 0.4064)
		(layer "B.Cu")
		(net "PVDDQ_KLM")
	)
	(segment
		(start 106.199432 -132.876036)
		(end 106.199432 -130.902456)
		(width 0.4064)
		(layer "B.Cu")
		(net "PVDDQ_KLM")
	)
	(segment
		(start 86.64956 -147.478496)
		(end 86.64956 -148.773388)
		(width 0.4064)
		(layer "B.Cu")
		(net "PVDDQ_KLM")
	)
	(segment
		(start 79.550768 -126.40183)
		(end 79.550768 -125.8824)
		(width 0.4064)
		(layer "B.Cu")
		(net "PVDDQ_KLM")
	)
	(segment
		(start 79.849472 -139.170156)
		(end 79.849472 -137.877296)
		(width 0.4064)
		(layer "B.Cu")
		(net "PVDDQ_KLM")
	)
	(segment
		(start 93.449394 -147.478496)
		(end 93.449394 -146.131026)
		(width 0.381)
		(layer "B.Cu")
		(net "PVDDQ_KLM")
	)
	(segment
		(start 86.64956 -139.172188)
		(end 86.64956 -137.877296)
		(width 0.4064)
		(layer "B.Cu")
		(net "PVDDQ_KLM")
	)
	(segment
		(start 79.172054 -126.780544)
		(end 79.550768 -126.40183)
		(width 0.4064)
		(layer "B.Cu")
		(net "PVDDQ_KLM")
	)
	(segment
		(start 93.449902 -131.1148)
		(end 93.449902 -132.875274)
		(width 0.4064)
		(layer "B.Cu")
		(net "PVDDQ_KLM")
	)
	(segment
		(start 86.64956 -147.478496)
		(end 86.64956 -145.988278)
		(width 0.4064)
		(layer "B.Cu")
		(net "PVDDQ_KLM")
	)
	(segment
		(start 104.49941 -153.571956)
		(end 104.49941 -152.078436)
		(width 0.4064)
		(layer "B.Cu")
		(net "PVDDQ_KLM")
	)
	(segment
		(start 108.749338 -132.876036)
		(end 108.749338 -134.35457)
		(width 0.4064)
		(layer "B.Cu")
		(net "PVDDQ_KLM")
	)
	(segment
		(start 85.799422 -142.477236)
		(end 85.799422 -143.970756)
		(width 0.4064)
		(layer "B.Cu")
		(net "PVDDQ_KLM")
	)
	(segment
		(start 104.49941 -142.477236)
		(end 104.49941 -143.972534)
		(width 0.4064)
		(layer "B.Cu")
		(net "PVDDQ_KLM")
	)
	(segment
		(start 110.44936 -131.611878)
		(end 110.44936 -132.876036)
		(width 0.4064)
		(layer "B.Cu")
		(net "PVDDQ_KLM")
	)
	(segment
		(start 93.449394 -142.477236)
		(end 93.449394 -143.78813)
		(width 0.4064)
		(layer "B.Cu")
		(net "PVDDQ_KLM")
	)
	(segment
		(start 110.44936 -134.37108)
		(end 110.44936 -132.876036)
		(width 0.4064)
		(layer "B.Cu")
		(net "PVDDQ_KLM")
	)
	(segment
		(start 28.547568 -144.4752)
		(end 28.547568 -144.0942)
		(width 0.4064)
		(layer "B.Cu")
		(net "PVDDQ_KLM")
	)
	(segment
		(start 81.549494 -127.241554)
		(end 81.549494 -128.276096)
		(width 0.4064)
		(layer "B.Cu")
		(net "PVDDQ_KLM")
	)
	(segment
		(start 112.149382 -142.477236)
		(end 112.149382 -143.968978)
		(width 0.4064)
		(layer "B.Cu")
		(net "PVDDQ_KLM")
	)
	(segment
		(start 81.549494 -145.988278)
		(end 81.549494 -147.478496)
		(width 0.4064)
		(layer "B.Cu")
		(net "PVDDQ_KLM")
	)
	(segment
		(start 80.699356 -130.902456)
		(end 80.699356 -132.876036)
		(width 0.4064)
		(layer "B.Cu")
		(net "PVDDQ_KLM")
	)
	(segment
		(start 83.249516 -154.252168)
		(end 83.249516 -152.078436)
		(width 0.4064)
		(layer "B.Cu")
		(net "PVDDQ_KLM")
	)
	(segment
		(start 90.905838 -141.18717)
		(end 90.90914 -141.183868)
		(width 0.4064)
		(layer "B.Cu")
		(net "PVDDQ_KLM")
	)
	(segment
		(start 90.899488 -128.276096)
		(end 90.899488 -129.303272)
		(width 0.4064)
		(layer "B.Cu")
		(net "PVDDQ_KLM")
	)
	(segment
		(start 90.899488 -150.999952)
		(end 90.684604 -150.785068)
		(width 0.4064)
		(layer "B.Cu")
		(net "PVDDQ_KLM")
	)
	(segment
		(start 93.449394 -141.361668)
		(end 93.271594 -141.183868)
		(width 0.4064)
		(layer "B.Cu")
		(net "PVDDQ_KLM")
	)
	(segment
		(start 90.899488 -148.556218)
		(end 90.899488 -147.478496)
		(width 0.4064)
		(layer "B.Cu")
		(net "PVDDQ_KLM")
	)
	(segment
		(start 112.149382 -145.984468)
		(end 112.149382 -147.478496)
		(width 0.4064)
		(layer "B.Cu")
		(net "PVDDQ_KLM")
	)
	(segment
		(start 89.199466 -148.773388)
		(end 89.199466 -147.478496)
		(width 0.4064)
		(layer "B.Cu")
		(net "PVDDQ_KLM")
	)
	(segment
		(start 106.199432 -150.785068)
		(end 106.199432 -152.078436)
		(width 0.4064)
		(layer "B.Cu")
		(net "PVDDQ_KLM")
	)
	(segment
		(start 86.64956 -130.249168)
		(end 86.64956 -128.276096)
		(width 0.4064)
		(layer "B.Cu")
		(net "PVDDQ_KLM")
	)
	(segment
		(start 93.449394 -139.11453)
		(end 93.449394 -137.877296)
		(width 0.4064)
		(layer "B.Cu")
		(net "PVDDQ_KLM")
	)
	(segment
		(start 79.849472 -148.771356)
		(end 79.849472 -147.478496)
		(width 0.4064)
		(layer "B.Cu")
		(net "PVDDQ_KLM")
	)
	(segment
		(start 93.302836 -145.984468)
		(end 93.266768 -145.984468)
		(width 0.381)
		(layer "B.Cu")
		(net "PVDDQ_KLM")
	)
	(segment
		(start 78.999334 -152.078436)
		(end 78.999334 -150.788878)
		(width 0.4064)
		(layer "B.Cu")
		(net "PVDDQ_KLM")
	)
	(segment
		(start 110.449868 -134.371588)
		(end 110.44936 -134.37108)
		(width 0.4064)
		(layer "B.Cu")
		(net "PVDDQ_KLM")
	)
	(segment
		(start 79.172054 -126.780544)
		(end 79.308452 -126.780544)
		(width 0.4064)
		(layer "B.Cu")
		(net "PVDDQ_KLM")
	)
	(segment
		(start 112.149382 -128.276096)
		(end 112.149382 -125.911102)
		(width 0.4064)
		(layer "B.Cu")
		(net "PVDDQ_KLM")
	)
	(segment
		(start 109.599476 -129.539746)
		(end 109.599476 -128.276096)
		(width 0.4064)
		(layer "B.Cu")
		(net "PVDDQ_KLM")
	)
	(segment
		(start 104.49941 -130.902456)
		(end 104.49941 -132.876036)
		(width 0.4064)
		(layer "B.Cu")
		(net "PVDDQ_KLM")
	)
	(segment
		(start 109.289088 -126.675388)
		(end 109.599476 -126.985776)
		(width 0.4064)
		(layer "B.Cu")
		(net "PVDDQ_KLM")
	)
	(segment
		(start 83.249516 -132.876036)
		(end 83.249516 -134.369556)
		(width 0.4064)
		(layer "B.Cu")
		(net "PVDDQ_KLM")
	)
	(segment
		(start 78.999334 -142.477236)
		(end 78.999334 -141.187678)
		(width 0.4064)
		(layer "B.Cu")
		(net "PVDDQ_KLM")
	)
	(segment
		(start 81.549494 -148.771356)
		(end 81.549494 -147.478496)
		(width 0.4064)
		(layer "B.Cu")
		(net "PVDDQ_KLM")
	)
	(segment
		(start 80.699356 -153.571956)
		(end 80.699356 -152.078436)
		(width 0.4064)
		(layer "B.Cu")
		(net "PVDDQ_KLM")
	)
	(segment
		(start 103.649526 -139.168378)
		(end 103.649526 -137.877296)
		(width 0.4064)
		(layer "B.Cu")
		(net "PVDDQ_KLM")
	)
	(segment
		(start 112.149382 -132.876036)
		(end 112.149382 -134.367778)
		(width 0.4064)
		(layer "B.Cu")
		(net "PVDDQ_KLM")
	)
	(segment
		(start 90.899488 -142.477236)
		(end 90.899488 -141.18717)
		(width 0.4064)
		(layer "B.Cu")
		(net "PVDDQ_KLM")
	)
	(segment
		(start 79.849472 -127.321564)
		(end 79.849472 -128.276096)
		(width 0.4064)
		(layer "B.Cu")
		(net "PVDDQ_KLM")
	)
	(segment
		(start 106.199432 -142.477236)
		(end 106.199432 -141.183868)
		(width 0.4064)
		(layer "B.Cu")
		(net "PVDDQ_KLM")
	)
	(segment
		(start 89.199466 -139.172188)
		(end 89.199466 -137.877296)
		(width 0.4064)
		(layer "B.Cu")
		(net "PVDDQ_KLM")
	)
	(segment
		(start 108.749338 -142.477236)
		(end 108.749338 -141.188186)
		(width 0.4064)
		(layer "B.Cu")
		(net "PVDDQ_KLM")
	)
	(segment
		(start 81.549494 -128.276096)
		(end 81.549494 -130.249168)
		(width 0.4064)
		(layer "B.Cu")
		(net "PVDDQ_KLM")
	)
	(segment
		(start 85.996272 -130.902456)
		(end 86.64956 -130.249168)
		(width 0.4064)
		(layer "B.Cu")
		(net "PVDDQ_KLM")
	)
	(segment
		(start 93.449902 -129.302764)
		(end 93.18371 -129.568956)
		(width 0.4064)
		(layer "B.Cu")
		(net "PVDDQ_KLM")
	)
	(segment
		(start 93.449902 -128.27635)
		(end 93.449902 -129.302764)
		(width 0.4064)
		(layer "B.Cu")
		(net "PVDDQ_KLM")
	)
	(segment
		(start 83.249516 -142.477236)
		(end 83.249516 -141.187678)
		(width 0.4064)
		(layer "B.Cu")
		(net "PVDDQ_KLM")
	)
	(segment
		(start 109.599476 -126.985776)
		(end 109.599476 -128.276096)
		(width 0.4064)
		(layer "B.Cu")
		(net "PVDDQ_KLM")
	)
	(segment
		(start 90.899488 -137.877296)
		(end 90.899488 -136.33831)
		(width 0.4064)
		(layer "B.Cu")
		(net "PVDDQ_KLM")
	)
	(segment
		(start 80.699356 -142.477236)
		(end 80.699356 -141.187678)
		(width 0.4064)
		(layer "B.Cu")
		(net "PVDDQ_KLM")
	)
	(segment
		(start 93.449394 -148.584666)
		(end 93.19006 -148.844)
		(width 0.381)
		(layer "B.Cu")
		(net "PVDDQ_KLM")
	)
	(segment
		(start 103.649272 -156.594048)
		(end 103.333296 -156.910024)
		(width 0.4064)
		(layer "B.Cu")
		(net "PVDDQ_KLM")
	)
	(segment
		(start 110.44936 -150.789386)
		(end 110.44936 -152.078436)
		(width 0.4064)
		(layer "B.Cu")
		(net "PVDDQ_KLM")
	)
	(segment
		(start 93.449394 -136.250426)
		(end 93.393768 -136.1948)
		(width 0.4064)
		(layer "B.Cu")
		(net "PVDDQ_KLM")
	)
	(segment
		(start 84.0994 -137.877296)
		(end 84.0994 -139.170156)
		(width 0.4064)
		(layer "B.Cu")
		(net "PVDDQ_KLM")
	)
	(segment
		(start 104.49941 -132.876036)
		(end 104.49941 -134.369556)
		(width 0.4064)
		(layer "B.Cu")
		(net "PVDDQ_KLM")
	)
	(segment
		(start 106.199432 -147.478496)
		(end 106.199432 -145.984468)
		(width 0.4064)
		(layer "B.Cu")
		(net "PVDDQ_KLM")
	)
	(segment
		(start 110.318296 -156.37002)
		(end 109.599476 -155.6512)
		(width 0.4064)
		(layer "B.Cu")
		(net "PVDDQ_KLM")
	)
	(segment
		(start 90.899488 -143.961104)
		(end 90.899488 -142.477236)
		(width 0.4064)
		(layer "B.Cu")
		(net "PVDDQ_KLM")
	)
	(segment
		(start 106.199432 -134.340346)
		(end 106.199432 -132.876036)
		(width 0.4064)
		(layer "B.Cu")
		(net "PVDDQ_KLM")
	)
	(segment
		(start 103.649526 -137.877296)
		(end 103.649526 -136.412732)
		(width 0.4064)
		(layer "B.Cu")
		(net "PVDDQ_KLM")
	)
	(segment
		(start 83.249516 -142.477236)
		(end 83.249516 -143.970756)
		(width 0.4064)
		(layer "B.Cu")
		(net "PVDDQ_KLM")
	)
	(segment
		(start 93.449394 -142.477236)
		(end 93.449394 -141.361668)
		(width 0.4064)
		(layer "B.Cu")
		(net "PVDDQ_KLM")
	)
	(segment
		(start 93.18371 -129.568956)
		(end 93.18371 -130.848608)
		(width 0.4064)
		(layer "B.Cu")
		(net "PVDDQ_KLM")
	)
	(segment
		(start 157.19806 -118.51894)
		(end 157.29204 -118.51894)
		(width 0.254)
		(layer "B.Cu")
		(net "PVDDQ_KLM")
	)
	(segment
		(start 106.199432 -142.477236)
		(end 106.199432 -143.968978)
		(width 0.4064)
		(layer "B.Cu")
		(net "PVDDQ_KLM")
	)
	(segment
		(start 101.949504 -152.078436)
		(end 101.949504 -150.785068)
		(width 0.4064)
		(layer "B.Cu")
		(net "PVDDQ_KLM")
	)
	(segment
		(start 109.599476 -137.877296)
		(end 109.599476 -136.449308)
		(width 0.4064)
		(layer "B.Cu")
		(net "PVDDQ_KLM")
	)
	(segment
		(start 88.349582 -132.876036)
		(end 88.349582 -134.371588)
		(width 0.4064)
		(layer "B.Cu")
		(net "PVDDQ_KLM")
	)
	(segment
		(start 107.899454 -147.478496)
		(end 107.899454 -148.769578)
		(width 0.4064)
		(layer "B.Cu")
		(net "PVDDQ_KLM")
	)
	(segment
		(start 85.799422 -130.902456)
		(end 85.996272 -130.902456)
		(width 0.4064)
		(layer "B.Cu")
		(net "PVDDQ_KLM")
	)
	(segment
		(start 85.799422 -152.078436)
		(end 85.799422 -150.788878)
		(width 0.4064)
		(layer "B.Cu")
		(net "PVDDQ_KLM")
	)
	(segment
		(start 109.599476 -145.984468)
		(end 109.599476 -147.478496)
		(width 0.4064)
		(layer "B.Cu")
		(net "PVDDQ_KLM")
	)
	(segment
		(start 93.449394 -132.875782)
		(end 93.449394 -132.876036)
		(width 0.4064)
		(layer "B.Cu")
		(net "PVDDQ_KLM")
	)
	(segment
		(start 83.249516 -152.078436)
		(end 83.249516 -150.788878)
		(width 0.4064)
		(layer "B.Cu")
		(net "PVDDQ_KLM")
	)
	(segment
		(start 101.94925 -131.611878)
		(end 101.949504 -131.612132)
		(width 0.254)
		(layer "B.Cu")
		(net "PVDDQ_KLM")
	)
	(segment
		(start 85.799422 -132.876036)
		(end 85.799422 -130.902456)
		(width 0.4064)
		(layer "B.Cu")
		(net "PVDDQ_KLM")
	)
	(segment
		(start 156.414978 -119.302022)
		(end 157.19806 -118.51894)
		(width 0.254)
		(layer "B.Cu")
		(net "PVDDQ_KLM")
	)
	(segment
		(start 28.674568 -154.051)
		(end 29.157168 -153.5684)
		(width 0.4064)
		(layer "B.Cu")
		(net "PVDDQ_KLM")
	)
	(segment
		(start 90.899488 -139.119356)
		(end 90.848688 -139.170156)
		(width 0.4064)
		(layer "B.Cu")
		(net "PVDDQ_KLM")
	)
	(segment
		(start 104.49941 -143.972534)
		(end 104.499664 -143.972788)
		(width 0.4064)
		(layer "B.Cu")
		(net "PVDDQ_KLM")
	)
	(segment
		(start 104.49941 -142.477236)
		(end 104.49941 -141.187932)
		(width 0.4064)
		(layer "B.Cu")
		(net "PVDDQ_KLM")
	)
	(segment
		(start 88.349582 -152.078436)
		(end 88.349582 -150.788878)
		(width 0.4064)
		(layer "B.Cu")
		(net "PVDDQ_KLM")
	)
	(segment
		(start 104.49941 -150.814532)
		(end 104.49941 -152.078436)
		(width 0.4064)
		(layer "B.Cu")
		(net "PVDDQ_KLM")
	)
	(segment
		(start 108.749338 -152.078436)
		(end 108.749338 -154.252168)
		(width 0.4064)
		(layer "B.Cu")
		(net "PVDDQ_KLM")
	)
	(segment
		(start 81.19872 -124.886212)
		(end 83.9089 -124.886212)
		(width 0.254)
		(layer "B.Cu")
		(net "PVDDQ_KLM")
	)
	(segment
		(start 110.44936 -152.078436)
		(end 110.44936 -154.252168)
		(width 0.4064)
		(layer "B.Cu")
		(net "PVDDQ_KLM")
	)
	(segment
		(start 101.949504 -142.477236)
		(end 101.949504 -143.972534)
		(width 0.4064)
		(layer "B.Cu")
		(net "PVDDQ_KLM")
	)
	(segment
		(start 89.199466 -137.877296)
		(end 89.199466 -136.401302)
		(width 0.4064)
		(layer "B.Cu")
		(net "PVDDQ_KLM")
	)
	(segment
		(start 106.199432 -147.478496)
		(end 106.199432 -148.742146)
		(width 0.4064)
		(layer "B.Cu")
		(net "PVDDQ_KLM")
	)
	(segment
		(start 106.199432 -137.877296)
		(end 106.199432 -136.383268)
		(width 0.4064)
		(layer "B.Cu")
		(net "PVDDQ_KLM")
	)
	(segment
		(start 101.949504 -143.972534)
		(end 101.949758 -143.972788)
		(width 0.4064)
		(layer "B.Cu")
		(net "PVDDQ_KLM")
	)
	(segment
		(start 108.749338 -143.97228)
		(end 108.749338 -142.477236)
		(width 0.4064)
		(layer "B.Cu")
		(net "PVDDQ_KLM")
	)
	(segment
		(start 28.801568 -134.62)
		(end 29.157168 -134.2644)
		(width 0.4064)
		(layer "B.Cu")
		(net "PVDDQ_KLM")
	)
	(segment
		(start 109.599476 -155.6512)
		(end 109.599476 -154.905456)
		(width 0.4064)
		(layer "B.Cu")
		(net "PVDDQ_KLM")
	)
	(segment
		(start 89.124028 -129.539746)
		(end 89.199466 -129.464308)
		(width 0.4064)
		(layer "B.Cu")
		(net "PVDDQ_KLM")
	)
	(segment
		(start 106.199432 -137.877296)
		(end 106.199432 -139.168378)
		(width 0.4064)
		(layer "B.Cu")
		(net "PVDDQ_KLM")
	)
	(segment
		(start 112.149382 -136.387078)
		(end 112.149382 -137.877296)
		(width 0.4064)
		(layer "B.Cu")
		(net "PVDDQ_KLM")
	)
	(segment
		(start 112.149382 -141.183868)
		(end 112.149382 -142.477236)
		(width 0.4064)
		(layer "B.Cu")
		(net "PVDDQ_KLM")
	)
	(segment
		(start 79.652622 -130.249168)
		(end 79.849472 -130.249168)
		(width 0.4064)
		(layer "B.Cu")
		(net "PVDDQ_KLM")
	)
	(segment
		(start 90.899488 -131.15798)
		(end 91.196668 -130.8608)
		(width 0.4064)
		(layer "B.Cu")
		(net "PVDDQ_KLM")
	)
	(segment
		(start 80.699356 -150.788878)
		(end 80.699356 -152.078436)
		(width 0.4064)
		(layer "B.Cu")
		(net "PVDDQ_KLM")
	)
	(segment
		(start 90.899488 -141.18717)
		(end 90.905838 -141.18717)
		(width 0.4064)
		(layer "B.Cu")
		(net "PVDDQ_KLM")
	)
	(segment
		(start 28.801568 -134.874)
		(end 28.801568 -134.62)
		(width 0.4064)
		(layer "B.Cu")
		(net "PVDDQ_KLM")
	)
	(segment
		(start 101.949504 -154.251914)
		(end 101.949504 -152.078436)
		(width 0.4064)
		(layer "B.Cu")
		(net "PVDDQ_KLM")
	)
	(segment
		(start 103.649526 -147.478496)
		(end 103.649526 -148.769578)
		(width 0.4064)
		(layer "B.Cu")
		(net "PVDDQ_KLM")
	)
	(segment
		(start 104.49941 -141.187932)
		(end 104.499664 -141.187678)
		(width 0.4064)
		(layer "B.Cu")
		(net "PVDDQ_KLM")
	)
	(segment
		(start 84.0994 -147.478496)
		(end 84.0994 -145.988278)
		(width 0.4064)
		(layer "B.Cu")
		(net "PVDDQ_KLM")
	)
	(segment
		(start 110.44936 -143.97228)
		(end 110.449868 -143.972788)
		(width 0.4064)
		(layer "B.Cu")
		(net "PVDDQ_KLM")
	)
	(segment
		(start 93.393768 -139.170156)
		(end 93.449394 -139.11453)
		(width 0.4064)
		(layer "B.Cu")
		(net "PVDDQ_KLM")
	)
	(segment
		(start 106.762296 -156.391864)
		(end 106.199432 -155.829)
		(width 0.4064)
		(layer "B.Cu")
		(net "PVDDQ_KLM")
	)
	(segment
		(start 104.499664 -150.788878)
		(end 104.499664 -150.814278)
		(width 0.4064)
		(layer "B.Cu")
		(net "PVDDQ_KLM")
	)
	(segment
		(start 79.308452 -126.780544)
		(end 79.849472 -127.321564)
		(width 0.4064)
		(layer "B.Cu")
		(net "PVDDQ_KLM")
	)
	(segment
		(start 90.899488 -132.876036)
		(end 90.899488 -131.15798)
		(width 0.4064)
		(layer "B.Cu")
		(net "PVDDQ_KLM")
	)
	(segment
		(start 90.90914 -143.970756)
		(end 90.899488 -143.961104)
		(width 0.4064)
		(layer "B.Cu")
		(net "PVDDQ_KLM")
	)
	(segment
		(start 93.449394 -150.785068)
		(end 93.449394 -152.078436)
		(width 0.4064)
		(layer "B.Cu")
		(net "PVDDQ_KLM")
	)
	(segment
		(start 78.999334 -132.876036)
		(end 78.999334 -130.902456)
		(width 0.4064)
		(layer "B.Cu")
		(net "PVDDQ_KLM")
	)
	(segment
		(start 81.352644 -130.249168)
		(end 80.699356 -130.902456)
		(width 0.4064)
		(layer "B.Cu")
		(net "PVDDQ_KLM")
	)
	(segment
		(start 80.81518 -125.16104)
		(end 80.81518 -125.64745)
		(width 0.254)
		(layer "B.Cu")
		(net "PVDDQ_KLM")
	)
	(segment
		(start 90.68435 -148.771356)
		(end 90.899488 -148.556218)
		(width 0.4064)
		(layer "B.Cu")
		(net "PVDDQ_KLM")
	)
	(segment
		(start 101.949504 -131.612132)
		(end 101.949504 -132.876036)
		(width 0.4064)
		(layer "B.Cu")
		(net "PVDDQ_KLM")
	)
	(segment
		(start 108.749338 -131.611878)
		(end 108.749338 -132.876036)
		(width 0.4064)
		(layer "B.Cu")
		(net "PVDDQ_KLM")
	)
	(segment
		(start 89.199466 -129.464308)
		(end 89.199466 -128.276096)
		(width 0.4064)
		(layer "B.Cu")
		(net "PVDDQ_KLM")
	)
	(segment
		(start 109.599476 -147.478496)
		(end 109.599476 -148.769578)
		(width 0.4064)
		(layer "B.Cu")
		(net "PVDDQ_KLM")
	)
	(segment
		(start 112.149382 -128.276096)
		(end 112.149382 -130.249168)
		(width 0.4064)
		(layer "B.Cu")
		(net "PVDDQ_KLM")
	)
	(segment
		(start 110.44936 -142.477236)
		(end 110.44936 -143.97228)
		(width 0.4064)
		(layer "B.Cu")
		(net "PVDDQ_KLM")
	)
	(segment
		(start 101.099366 -137.877296)
		(end 101.099366 -136.383268)
		(width 0.4064)
		(layer "B.Cu")
		(net "PVDDQ_KLM")
	)
	(segment
		(start 104.499664 -150.814278)
		(end 104.49941 -150.814532)
		(width 0.4064)
		(layer "B.Cu")
		(net "PVDDQ_KLM")
	)
	(segment
		(start 84.0994 -128.276096)
		(end 84.0994 -129.568956)
		(width 0.4064)
		(layer "B.Cu")
		(net "PVDDQ_KLM")
	)
	(segment
		(start 103.649526 -145.984468)
		(end 103.649526 -147.478496)
		(width 0.4064)
		(layer "B.Cu")
		(net "PVDDQ_KLM")
	)
	(segment
		(start 101.099366 -147.478496)
		(end 101.099366 -148.769578)
		(width 0.4064)
		(layer "B.Cu")
		(net "PVDDQ_KLM")
	)
	(segment
		(start 80.699356 -142.477236)
		(end 80.699356 -143.970756)
		(width 0.4064)
		(layer "B.Cu")
		(net "PVDDQ_KLM")
	)
	(segment
		(start 81.549494 -137.877296)
		(end 81.549494 -136.412478)
		(width 0.4064)
		(layer "B.Cu")
		(net "PVDDQ_KLM")
	)
	(segment
		(start 83.9089 -124.886212)
		(end 85.014308 -125.99162)
		(width 0.254)
		(layer "B.Cu")
		(net "PVDDQ_KLM")
	)
	(segment
		(start 112.149382 -147.478496)
		(end 112.149382 -148.769578)
		(width 0.4064)
		(layer "B.Cu")
		(net "PVDDQ_KLM")
	)
	(segment
		(start 108.749846 -143.972788)
		(end 108.749338 -143.97228)
		(width 0.4064)
		(layer "B.Cu")
		(net "PVDDQ_KLM")
	)
	(segment
		(start 93.449394 -152.078436)
		(end 93.449394 -153.571956)
		(width 0.4064)
		(layer "B.Cu")
		(net "PVDDQ_KLM")
	)
	(segment
		(start 93.449394 -146.131026)
		(end 93.302836 -145.984468)
		(width 0.381)
		(layer "B.Cu")
		(net "PVDDQ_KLM")
	)
	(segment
		(start 101.94925 -154.252168)
		(end 101.949504 -154.251914)
		(width 0.4064)
		(layer "B.Cu")
		(net "PVDDQ_KLM")
	)
	(segment
		(start 101.949504 -132.876036)
		(end 101.949504 -134.285736)
		(width 0.4064)
		(layer "B.Cu")
		(net "PVDDQ_KLM")
	)
	(segment
		(start 107.899454 -136.383268)
		(end 107.899454 -137.877296)
		(width 0.4064)
		(layer "B.Cu")
		(net "PVDDQ_KLM")
	)
	(segment
		(start 86.64956 -137.877296)
		(end 86.64956 -136.412478)
		(width 0.4064)
		(layer "B.Cu")
		(net "PVDDQ_KLM")
	)
	(segment
		(start 93.449394 -143.78813)
		(end 93.266768 -143.970756)
		(width 0.4064)
		(layer "B.Cu")
		(net "PVDDQ_KLM")
	)
	(segment
		(start 109.599476 -139.168378)
		(end 109.599476 -137.877296)
		(width 0.4064)
		(layer "B.Cu")
		(net "PVDDQ_KLM")
	)
	(segment
		(start 110.44936 -142.477236)
		(end 110.44936 -141.188186)
		(width 0.4064)
		(layer "B.Cu")
		(net "PVDDQ_KLM")
	)
	(segment
		(start 80.81518 -125.64745)
		(end 80.81518 -126.50724)
		(width 0.4064)
		(layer "B.Cu")
		(net "PVDDQ_KLM")
	)
	(segment
		(start 93.449394 -132.876036)
		(end 93.449394 -134.380478)
		(width 0.4064)
		(layer "B.Cu")
		(net "PVDDQ_KLM")
	)
	(segment
		(start 93.449394 -137.877296)
		(end 93.449394 -136.250426)
		(width 0.4064)
		(layer "B.Cu")
		(net "PVDDQ_KLM")
	)
	(segment
		(start 84.0994 -137.877296)
		(end 84.0994 -136.476232)
		(width 0.4064)
		(layer "B.Cu")
		(net "PVDDQ_KLM")
	)
	(segment
		(start 108.749338 -150.789386)
		(end 108.749338 -152.078436)
		(width 0.4064)
		(layer "B.Cu")
		(net "PVDDQ_KLM")
	)
	(segment
		(start 112.149382 -150.785068)
		(end 112.149382 -152.078436)
		(width 0.4064)
		(layer "B.Cu")
		(net "PVDDQ_KLM")
	)
	(segment
		(start 107.899454 -139.168378)
		(end 107.899454 -137.877296)
		(width 0.4064)
		(layer "B.Cu")
		(net "PVDDQ_KLM")
	)
	(segment
		(start 106.762296 -156.910024)
		(end 106.762296 -156.391864)
		(width 0.4064)
		(layer "B.Cu")
		(net "PVDDQ_KLM")
	)
	(segment
		(start 81.549494 -139.170156)
		(end 81.549494 -137.877296)
		(width 0.4064)
		(layer "B.Cu")
		(net "PVDDQ_KLM")
	)
	(segment
		(start 78.999334 -132.876036)
		(end 78.999334 -134.369556)
		(width 0.4064)
		(layer "B.Cu")
		(net "PVDDQ_KLM")
	)
	(segment
		(start 83.249516 -131.611878)
		(end 83.249516 -132.876036)
		(width 0.4064)
		(layer "B.Cu")
		(net "PVDDQ_KLM")
	)
	(segment
		(start 112.149382 -152.078436)
		(end 112.149382 -154.252168)
		(width 0.4064)
		(layer "B.Cu")
		(net "PVDDQ_KLM")
	)
	(segment
		(start 157.124654 -118.686326)
		(end 156.73705 -118.686326)
		(width 0.254)
		(layer "In4.Cu")
		(net "PVDDQ_KLM")
	)
	(segment
		(start 156.73705 -118.686326)
		(end 156.534104 -118.889272)
		(width 0.254)
		(layer "In4.Cu")
		(net "PVDDQ_KLM")
	)
	(segment
		(start 158.011114 -131.123944)
		(end 157.4546 -131.680458)
		(width 0.254)
		(layer "In4.Cu")
		(net "PVDDQ_KLM")
	)
	(segment
		(start 158.309818 -140.834618)
		(end 160.5788 -143.1036)
		(width 0.254)
		(layer "In4.Cu")
		(net "PVDDQ_KLM")
	)
	(segment
		(start 156.534104 -123.365768)
		(end 158.011114 -124.842778)
		(width 0.254)
		(layer "In4.Cu")
		(net "PVDDQ_KLM")
	)
	(segment
		(start 158.309818 -135.272018)
		(end 158.309818 -140.834618)
		(width 0.254)
		(layer "In4.Cu")
		(net "PVDDQ_KLM")
	)
	(segment
		(start 157.4546 -134.4168)
		(end 158.309818 -135.272018)
		(width 0.254)
		(layer "In4.Cu")
		(net "PVDDQ_KLM")
	)
	(segment
		(start 160.5788 -143.1036)
		(end 163.100258 -143.1036)
		(width 0.254)
		(layer "In4.Cu")
		(net "PVDDQ_KLM")
	)
	(segment
		(start 158.011114 -124.842778)
		(end 158.011114 -131.123944)
		(width 0.254)
		(layer "In4.Cu")
		(net "PVDDQ_KLM")
	)
	(segment
		(start 157.4546 -131.680458)
		(end 157.4546 -134.4168)
		(width 0.254)
		(layer "In4.Cu")
		(net "PVDDQ_KLM")
	)
	(segment
		(start 156.534104 -118.889272)
		(end 156.534104 -123.365768)
		(width 0.254)
		(layer "In4.Cu")
		(net "PVDDQ_KLM")
	)
	(segment
		(start 157.29204 -118.51894)
		(end 157.124654 -118.686326)
		(width 0.254)
		(layer "In4.Cu")
		(net "PVDDQ_KLM")
	)
	(segment
		(start 163.100258 -143.1036)
		(end 164.4269 -144.430242)
		(width 0.254)
		(layer "In4.Cu")
		(net "PVDDQ_KLM")
	)
	(segment
		(start 2.699512 -135.289544)
		(end 3.791204 -135.289544)
		(width 0.254)
		(layer "In9.Cu")
		(net "PVDDQ_KLM")
	)
	(segment
		(start 8.725154 -136.20369)
		(end 10.253218 -137.731754)
		(width 0.254)
		(layer "In9.Cu")
		(net "PVDDQ_KLM")
	)
	(segment
		(start -0.7874 -135.633714)
		(end -0.774192 -135.620506)
		(width 0.254)
		(layer "In9.Cu")
		(net "PVDDQ_KLM")
	)
	(segment
		(start 3.791204 -135.289544)
		(end 4.49834 -134.582408)
		(width 0.254)
		(layer "In9.Cu")
		(net "PVDDQ_KLM")
	)
	(segment
		(start 10.253218 -137.731754)
		(end 11.979402 -137.731754)
		(width 0.254)
		(layer "In9.Cu")
		(net "PVDDQ_KLM")
	)
	(segment
		(start -0.774192 -135.620506)
		(end 2.36855 -135.620506)
		(width 0.254)
		(layer "In9.Cu")
		(net "PVDDQ_KLM")
	)
	(segment
		(start 8.45693 -134.582408)
		(end 8.725154 -134.850632)
		(width 0.254)
		(layer "In9.Cu")
		(net "PVDDQ_KLM")
	)
	(segment
		(start 4.49834 -134.582408)
		(end 8.45693 -134.582408)
		(width 0.254)
		(layer "In9.Cu")
		(net "PVDDQ_KLM")
	)
	(segment
		(start 11.979402 -137.731754)
		(end 13.694156 -136.017)
		(width 0.254)
		(layer "In9.Cu")
		(net "PVDDQ_KLM")
	)
	(segment
		(start 2.36855 -135.620506)
		(end 2.699512 -135.289544)
		(width 0.254)
		(layer "In9.Cu")
		(net "PVDDQ_KLM")
	)
	(segment
		(start 8.725154 -134.850632)
		(end 8.725154 -136.20369)
		(width 0.254)
		(layer "In9.Cu")
		(net "PVDDQ_KLM")
	)
	(segment
		(start 13.694156 -136.017)
		(end 15.875 -136.017)
		(width 0.254)
		(layer "In9.Cu")
		(net "PVDDQ_KLM")
	)
	(segment
		(start -0.635 -146.784568)
		(end -2.3114 -148.460968)
		(width 0.254)
		(layer "In11.Cu")
		(net "PVDDQ_KLM")
	)
	(segment
		(start 0.174498 -151.407368)
		(end 0.748792 -150.833074)
		(width 0.254)
		(layer "In11.Cu")
		(net "PVDDQ_KLM")
	)
	(segment
		(start 5.356352 -151.252682)
		(end 5.837428 -151.252682)
		(width 0.254)
		(layer "In11.Cu")
		(net "PVDDQ_KLM")
	)
	(segment
		(start 4.560316 -150.955248)
		(end 5.058918 -150.955248)
		(width 0.254)
		(layer "In11.Cu")
		(net "PVDDQ_KLM")
	)
	(segment
		(start 5.837428 -151.252682)
		(end 8.153146 -153.5684)
		(width 0.254)
		(layer "In11.Cu")
		(net "PVDDQ_KLM")
	)
	(segment
		(start 0.748792 -150.833074)
		(end 4.438142 -150.833074)
		(width 0.254)
		(layer "In11.Cu")
		(net "PVDDQ_KLM")
	)
	(segment
		(start 4.438142 -150.833074)
		(end 4.560316 -150.955248)
		(width 0.254)
		(layer "In11.Cu")
		(net "PVDDQ_KLM")
	)
	(segment
		(start -1.737106 -151.407368)
		(end 0.174498 -151.407368)
		(width 0.254)
		(layer "In11.Cu")
		(net "PVDDQ_KLM")
	)
	(segment
		(start 8.153146 -153.5684)
		(end 15.4686 -153.5684)
		(width 0.254)
		(layer "In11.Cu")
		(net "PVDDQ_KLM")
	)
	(segment
		(start -2.3114 -150.833074)
		(end -1.737106 -151.407368)
		(width 0.254)
		(layer "In11.Cu")
		(net "PVDDQ_KLM")
	)
	(segment
		(start 15.4686 -153.5684)
		(end 16.129 -152.908)
		(width 0.254)
		(layer "In11.Cu")
		(net "PVDDQ_KLM")
	)
	(segment
		(start -2.3114 -148.460968)
		(end -2.3114 -150.833074)
		(width 0.254)
		(layer "In11.Cu")
		(net "PVDDQ_KLM")
	)
	(segment
		(start -0.635 -144.653)
		(end -0.635 -146.784568)
		(width 0.254)
		(layer "In11.Cu")
		(net "PVDDQ_KLM")
	)
	(segment
		(start 5.058918 -150.955248)
		(end 5.356352 -151.252682)
		(width 0.254)
		(layer "In11.Cu")
		(net "PVDDQ_KLM")
	)
	(segment
		(start 101.099366 -20.023582)
		(end 101.099366 -21.5392)
		(width 0.508)
		(layer "F.Cu")
		(net "PVDDQ_GHJ")
	)
	(segment
		(start 106.199432 -20.023582)
		(end 106.199432 -21.488146)
		(width 0.508)
		(layer "F.Cu")
		(net "PVDDQ_GHJ")
	)
	(segment
		(start 112.149382 -20.722336)
		(end 112.149382 -20.896072)
		(width 0.254)
		(layer "F.Cu")
		(net "PVDDQ_GHJ")
	)
	(segment
		(start 91.171522 -21.577554)
		(end 91.171522 -21.952966)
		(width 0.254)
		(layer "F.Cu")
		(net "PVDDQ_GHJ")
	)
	(segment
		(start 90.928698 -62.029086)
		(end 90.357198 -62.029086)
		(width 0.254)
		(layer "F.Cu")
		(net "PVDDQ_GHJ")
	)
	(segment
		(start 2.29235 -14.799818)
		(end 2.282952 -14.799818)
		(width 0.254)
		(layer "F.Cu")
		(net "PVDDQ_GHJ")
	)
	(segment
		(start 89.199466 -9.133078)
		(end 89.199466 -10.422382)
		(width 0.508)
		(layer "F.Cu")
		(net "PVDDQ_GHJ")
	)
	(segment
		(start 101.949504 -15.423642)
		(end 101.949504 -16.718534)
		(width 0.508)
		(layer "F.Cu")
		(net "PVDDQ_GHJ")
	)
	(segment
		(start 100.671884 -50.141886)
		(end 100.659184 -50.129186)
		(width 0.254)
		(layer "F.Cu")
		(net "PVDDQ_GHJ")
	)
	(segment
		(start 81.549494 -2.314956)
		(end 81.549494 -0.821182)
		(width 0.508)
		(layer "F.Cu")
		(net "PVDDQ_GHJ")
	)
	(segment
		(start 78.999334 -5.822442)
		(end 78.999334 -4.332478)
		(width 0.508)
		(layer "F.Cu")
		(net "PVDDQ_GHJ")
	)
	(segment
		(start 2.29235 -14.811756)
		(end 2.29235 -14.799818)
		(width 0.254)
		(layer "F.Cu")
		(net "PVDDQ_GHJ")
	)
	(segment
		(start 90.899488 -2.264156)
		(end 90.848688 -2.314956)
		(width 0.508)
		(layer "F.Cu")
		(net "PVDDQ_GHJ")
	)
	(segment
		(start 79.849472 -2.314956)
		(end 79.849472 -0.821182)
		(width 0.508)
		(layer "F.Cu")
		(net "PVDDQ_GHJ")
	)
	(segment
		(start 108.749846 -7.117588)
		(end 108.749338 -7.11708)
		(width 0.5588)
		(layer "F.Cu")
		(net "PVDDQ_GHJ")
	)
	(segment
		(start 85.799422 -16.716756)
		(end 85.799422 -15.423642)
		(width 0.508)
		(layer "F.Cu")
		(net "PVDDQ_GHJ")
	)
	(segment
		(start 79.893414 -22.197568)
		(end 79.849472 -22.197568)
		(width 0.254)
		(layer "F.Cu")
		(net "PVDDQ_GHJ")
	)
	(segment
		(start 88.349582 -7.117588)
		(end 88.349582 -5.822442)
		(width 0.508)
		(layer "F.Cu")
		(net "PVDDQ_GHJ")
	)
	(segment
		(start 90.899488 -9.341612)
		(end 90.899488 -10.422382)
		(width 0.508)
		(layer "F.Cu")
		(net "PVDDQ_GHJ")
	)
	(segment
		(start 106.199432 -15.423642)
		(end 106.199432 -13.929868)
		(width 0.508)
		(layer "F.Cu")
		(net "PVDDQ_GHJ")
	)
	(segment
		(start 86.64956 -9.133078)
		(end 86.64956 -10.422382)
		(width 0.508)
		(layer "F.Cu")
		(net "PVDDQ_GHJ")
	)
	(segment
		(start 102.089204 -57.57164)
		(end 101.517704 -57.57164)
		(width 0.254)
		(layer "F.Cu")
		(net "PVDDQ_GHJ")
	)
	(segment
		(start 90.928698 -59.057286)
		(end 90.357198 -59.057286)
		(width 0.254)
		(layer "F.Cu")
		(net "PVDDQ_GHJ")
	)
	(segment
		(start 110.449868 -13.933678)
		(end 110.44936 -13.934186)
		(width 0.5588)
		(layer "F.Cu")
		(net "PVDDQ_GHJ")
	)
	(segment
		(start 90.899488 -4.321556)
		(end 90.899488 -5.822442)
		(width 0.508)
		(layer "F.Cu")
		(net "PVDDQ_GHJ")
	)
	(segment
		(start 104.49941 -7.117334)
		(end 104.49941 -5.822442)
		(width 0.508)
		(layer "F.Cu")
		(net "PVDDQ_GHJ")
	)
	(segment
		(start 108.749338 -15.423642)
		(end 108.749338 -16.71828)
		(width 0.508)
		(layer "F.Cu")
		(net "PVDDQ_GHJ")
	)
	(segment
		(start 164.246814 -71.02856)
		(end 164.292026 -71.02856)
		(width 0.254)
		(layer "F.Cu")
		(net "PVDDQ_GHJ")
	)
	(segment
		(start 108.749338 -13.934186)
		(end 108.749338 -15.423642)
		(width 0.508)
		(layer "F.Cu")
		(net "PVDDQ_GHJ")
	)
	(segment
		(start 81.549494 -10.422382)
		(end 81.549494 -11.916156)
		(width 0.508)
		(layer "F.Cu")
		(net "PVDDQ_GHJ")
	)
	(segment
		(start 80.029304 -22.061678)
		(end 79.893414 -22.197568)
		(width 0.254)
		(layer "F.Cu")
		(net "PVDDQ_GHJ")
	)
	(segment
		(start 107.899454 -11.914378)
		(end 107.899454 -10.422382)
		(width 0.508)
		(layer "F.Cu")
		(net "PVDDQ_GHJ")
	)
	(segment
		(start 98.655378 -57.57164)
		(end 99.800664 -57.57164)
		(width 0.254)
		(layer "F.Cu")
		(net "PVDDQ_GHJ")
	)
	(segment
		(start 100.372164 -51.62804)
		(end 99.800664 -51.62804)
		(width 0.254)
		(layer "F.Cu")
		(net "PVDDQ_GHJ")
	)
	(segment
		(start 110.449868 -7.180072)
		(end 110.44936 -7.179564)
		(width 0.508)
		(layer "F.Cu")
		(net "PVDDQ_GHJ")
	)
	(segment
		(start 110.44936 -13.934186)
		(end 110.44936 -15.423642)
		(width 0.508)
		(layer "F.Cu")
		(net "PVDDQ_GHJ")
	)
	(segment
		(start 28.768548 -23.657306)
		(end 29.028136 -23.397718)
		(width 0.4064)
		(layer "F.Cu")
		(net "PVDDQ_GHJ")
	)
	(segment
		(start 106.199432 -2.313178)
		(end 106.199432 -0.821182)
		(width 0.508)
		(layer "F.Cu")
		(net "PVDDQ_GHJ")
	)
	(segment
		(start 88.349582 3.778758)
		(end 88.349582 1.805432)
		(width 0.508)
		(layer "F.Cu")
		(net "PVDDQ_GHJ")
	)
	(segment
		(start 90.899488 -21.30552)
		(end 90.959178 -21.36521)
		(width 0.508)
		(layer "F.Cu")
		(net "PVDDQ_GHJ")
	)
	(segment
		(start 83.249516 1.805432)
		(end 83.817968 1.368552)
		(width 0.508)
		(layer "F.Cu")
		(net "PVDDQ_GHJ")
	)
	(segment
		(start 112.149382 -13.929868)
		(end 112.149382 -15.423642)
		(width 0.508)
		(layer "F.Cu")
		(net "PVDDQ_GHJ")
	)
	(segment
		(start 112.149382 -15.423642)
		(end 112.149382 -16.714978)
		(width 0.508)
		(layer "F.Cu")
		(net "PVDDQ_GHJ")
	)
	(segment
		(start 104.499664 -7.117588)
		(end 104.49941 -7.117334)
		(width 0.508)
		(layer "F.Cu")
		(net "PVDDQ_GHJ")
	)
	(segment
		(start 106.199432 -5.822442)
		(end 106.199432 -7.113778)
		(width 0.508)
		(layer "F.Cu")
		(net "PVDDQ_GHJ")
	)
	(segment
		(start 108.749338 -7.11708)
		(end 108.749338 -5.822442)
		(width 0.508)
		(layer "F.Cu")
		(net "PVDDQ_GHJ")
	)
	(segment
		(start 101.230684 -50.141886)
		(end 100.671884 -50.141886)
		(width 0.254)
		(layer "F.Cu")
		(net "PVDDQ_GHJ")
	)
	(segment
		(start 80.699356 -4.332478)
		(end 80.699356 -5.822442)
		(width 0.508)
		(layer "F.Cu")
		(net "PVDDQ_GHJ")
	)
	(segment
		(start 29.028136 -23.397718)
		(end 29.028136 -22.994366)
		(width 0.4064)
		(layer "F.Cu")
		(net "PVDDQ_GHJ")
	)
	(segment
		(start 28.702 -3.97256)
		(end 29.12872 -4.39928)
		(width 0.4064)
		(layer "F.Cu")
		(net "PVDDQ_GHJ")
	)
	(segment
		(start 102.089204 -54.59984)
		(end 101.517704 -54.59984)
		(width 0.254)
		(layer "F.Cu")
		(net "PVDDQ_GHJ")
	)
	(segment
		(start 102.947724 -51.132486)
		(end 102.947724 -50.803556)
		(width 0.254)
		(layer "F.Cu")
		(net "PVDDQ_GHJ")
	)
	(segment
		(start 90.899488 3.778758)
		(end 90.899488 2.485644)
		(width 0.508)
		(layer "F.Cu")
		(net "PVDDQ_GHJ")
	)
	(segment
		(start 109.599476 -11.914378)
		(end 109.599476 -10.422382)
		(width 0.508)
		(layer "F.Cu")
		(net "PVDDQ_GHJ")
	)
	(segment
		(start 78.999334 -13.933678)
		(end 78.999334 -15.423642)
		(width 0.508)
		(layer "F.Cu")
		(net "PVDDQ_GHJ")
	)
	(segment
		(start 89.211912 -62.029086)
		(end 88.640412 -62.029086)
		(width 0.254)
		(layer "F.Cu")
		(net "PVDDQ_GHJ")
	)
	(segment
		(start 93.449394 -11.916156)
		(end 93.449394 -10.422382)
		(width 0.508)
		(layer "F.Cu")
		(net "PVDDQ_GHJ")
	)
	(segment
		(start 93.449394 -15.423642)
		(end 93.449394 -16.517874)
		(width 0.508)
		(layer "F.Cu")
		(net "PVDDQ_GHJ")
	)
	(segment
		(start 96.938338 -57.57164)
		(end 96.366838 -57.57164)
		(width 0.254)
		(layer "F.Cu")
		(net "PVDDQ_GHJ")
	)
	(segment
		(start 84.0994 -2.314956)
		(end 84.0994 -0.821182)
		(width 0.508)
		(layer "F.Cu")
		(net "PVDDQ_GHJ")
	)
	(segment
		(start 112.149382 -20.896072)
		(end 111.964978 -21.080476)
		(width 0.254)
		(layer "F.Cu")
		(net "PVDDQ_GHJ")
	)
	(segment
		(start 83.856068 -12.159488)
		(end 83.856068 -12.954)
		(width 0.508)
		(layer "F.Cu")
		(net "PVDDQ_GHJ")
	)
	(segment
		(start 104.49941 -15.423642)
		(end 104.49941 -16.718534)
		(width 0.508)
		(layer "F.Cu")
		(net "PVDDQ_GHJ")
	)
	(segment
		(start 84.0994 -20.023582)
		(end 84.0994 -18.734278)
		(width 0.508)
		(layer "F.Cu")
		(net "PVDDQ_GHJ")
	)
	(segment
		(start 85.799422 -15.423642)
		(end 85.799422 -13.933678)
		(width 0.508)
		(layer "F.Cu")
		(net "PVDDQ_GHJ")
	)
	(segment
		(start 91.089226 -9.151874)
		(end 90.899488 -9.341612)
		(width 0.508)
		(layer "F.Cu")
		(net "PVDDQ_GHJ")
	)
	(segment
		(start 84.0994 -11.916156)
		(end 83.856068 -12.159488)
		(width 0.508)
		(layer "F.Cu")
		(net "PVDDQ_GHJ")
	)
	(segment
		(start 28.449778 -23.657306)
		(end 28.768548 -23.657306)
		(width 0.4064)
		(layer "F.Cu")
		(net "PVDDQ_GHJ")
	)
	(segment
		(start 86.636352 -51.62804)
		(end 87.781892 -51.62804)
		(width 0.254)
		(layer "F.Cu")
		(net "PVDDQ_GHJ")
	)
	(segment
		(start 91.787218 -51.62804)
		(end 92.074238 -52.12334)
		(width 0.254)
		(layer "F.Cu")
		(net "PVDDQ_GHJ")
	)
	(segment
		(start 104.49941 -13.933932)
		(end 104.49941 -15.423642)
		(width 0.508)
		(layer "F.Cu")
		(net "PVDDQ_GHJ")
	)
	(segment
		(start 79.849472 -20.023582)
		(end 79.849472 -21.52269)
		(width 0.508)
		(layer "F.Cu")
		(net "PVDDQ_GHJ")
	)
	(segment
		(start 90.899488 -0.821182)
		(end 90.899488 -2.264156)
		(width 0.508)
		(layer "F.Cu")
		(net "PVDDQ_GHJ")
	)
	(segment
		(start 2.19964 -6.927596)
		(end 2.370582 -7.098538)
		(width 0.254)
		(layer "F.Cu")
		(net "PVDDQ_GHJ")
	)
	(segment
		(start 96.938338 -51.62804)
		(end 97.225358 -51.132486)
		(width 0.254)
		(layer "F.Cu")
		(net "PVDDQ_GHJ")
	)
	(segment
		(start 108.749846 -13.933678)
		(end 108.749338 -13.934186)
		(width 0.5588)
		(layer "F.Cu")
		(net "PVDDQ_GHJ")
	)
	(segment
		(start 86.64956 -0.821182)
		(end 86.64956 -2.316988)
		(width 0.508)
		(layer "F.Cu")
		(net "PVDDQ_GHJ")
	)
	(segment
		(start 103.649526 -21.45665)
		(end 103.469694 -21.636482)
		(width 0.254)
		(layer "F.Cu")
		(net "PVDDQ_GHJ")
	)
	(segment
		(start 95.221298 -54.59984)
		(end 94.649798 -54.59984)
		(width 0.254)
		(layer "F.Cu")
		(net "PVDDQ_GHJ")
	)
	(segment
		(start 112.149382 0.468122)
		(end 112.149382 3.778758)
		(width 0.508)
		(layer "F.Cu")
		(net "PVDDQ_GHJ")
	)
	(segment
		(start 84.0994 -9.133078)
		(end 84.0994 -10.422382)
		(width 0.508)
		(layer "F.Cu")
		(net "PVDDQ_GHJ")
	)
	(segment
		(start 112.149382 -11.914378)
		(end 112.149382 -10.422382)
		(width 0.508)
		(layer "F.Cu")
		(net "PVDDQ_GHJ")
	)
	(segment
		(start 85.799422 -5.822442)
		(end 85.799422 -7.115556)
		(width 0.508)
		(layer "F.Cu")
		(net "PVDDQ_GHJ")
	)
	(segment
		(start 80.699356 3.778758)
		(end 80.699356 2.485644)
		(width 0.508)
		(layer "F.Cu")
		(net "PVDDQ_GHJ")
	)
	(segment
		(start 78.999334 -7.115556)
		(end 78.999334 -5.822442)
		(width 0.508)
		(layer "F.Cu")
		(net "PVDDQ_GHJ")
	)
	(segment
		(start 83.249516 -15.423642)
		(end 83.249516 -16.716756)
		(width 0.508)
		(layer "F.Cu")
		(net "PVDDQ_GHJ")
	)
	(segment
		(start 101.099366 1.152144)
		(end 101.099366 -0.821182)
		(width 0.508)
		(layer "F.Cu")
		(net "PVDDQ_GHJ")
	)
	(segment
		(start 110.44936 3.778758)
		(end 110.44936 1.805432)
		(width 0.508)
		(layer "F.Cu")
		(net "PVDDQ_GHJ")
	)
	(segment
		(start 103.649526 0.442468)
		(end 103.649272 0.442722)
		(width 0.5588)
		(layer "F.Cu")
		(net "PVDDQ_GHJ")
	)
	(segment
		(start 99.798632 -49.54778)
		(end 99.796092 -49.540414)
		(width 0.254)
		(layer "F.Cu")
		(net "PVDDQ_GHJ")
	)
	(segment
		(start 102.089204 -51.62804)
		(end 101.517704 -51.62804)
		(width 0.254)
		(layer "F.Cu")
		(net "PVDDQ_GHJ")
	)
	(segment
		(start 86.636352 -58.770266)
		(end 86.923372 -59.057286)
		(width 0.254)
		(layer "F.Cu")
		(net "PVDDQ_GHJ")
	)
	(segment
		(start 80.029304 -21.702522)
		(end 80.029304 -22.061678)
		(width 0.254)
		(layer "F.Cu")
		(net "PVDDQ_GHJ")
	)
	(segment
		(start 83.249516 -15.423642)
		(end 83.249516 -13.933678)
		(width 0.508)
		(layer "F.Cu")
		(net "PVDDQ_GHJ")
	)
	(segment
		(start 112.149382 -20.023582)
		(end 112.149382 -20.722336)
		(width 0.508)
		(layer "F.Cu")
		(net "PVDDQ_GHJ")
	)
	(segment
		(start 93.449394 0.471932)
		(end 93.449394 -0.821182)
		(width 0.508)
		(layer "F.Cu")
		(net "PVDDQ_GHJ")
	)
	(segment
		(start 106.199432 -20.023582)
		(end 106.199432 -18.730468)
		(width 0.508)
		(layer "F.Cu")
		(net "PVDDQ_GHJ")
	)
	(segment
		(start 102.947724 -61.038486)
		(end 103.557324 -61.038486)
		(width 0.254)
		(layer "F.Cu")
		(net "PVDDQ_GHJ")
	)
	(segment
		(start 28.702 -3.766312)
		(end 28.702 -3.97256)
		(width 0.4064)
		(layer "F.Cu")
		(net "PVDDQ_GHJ")
	)
	(segment
		(start 107.899454 -2.313178)
		(end 107.899454 -0.821182)
		(width 0.508)
		(layer "F.Cu")
		(net "PVDDQ_GHJ")
	)
	(segment
		(start 98.655378 -51.62804)
		(end 98.083878 -52.618386)
		(width 0.254)
		(layer "F.Cu")
		(net "PVDDQ_GHJ")
	)
	(segment
		(start 102.947724 -59.057286)
		(end 103.557324 -59.057286)
		(width 0.254)
		(layer "F.Cu")
		(net "PVDDQ_GHJ")
	)
	(segment
		(start 88.349582 -13.933678)
		(end 88.349582 -15.423642)
		(width 0.508)
		(layer "F.Cu")
		(net "PVDDQ_GHJ")
	)
	(segment
		(start 85.799422 -4.332478)
		(end 85.799422 -5.822442)
		(width 0.508)
		(layer "F.Cu")
		(net "PVDDQ_GHJ")
	)
	(segment
		(start 93.449394 -4.328668)
		(end 93.449394 -5.822442)
		(width 0.508)
		(layer "F.Cu")
		(net "PVDDQ_GHJ")
	)
	(segment
		(start 88.353392 -54.59984)
		(end 87.781892 -54.59984)
		(width 0.254)
		(layer "F.Cu")
		(net "PVDDQ_GHJ")
	)
	(segment
		(start 81.549494 -20.023582)
		(end 81.549494 -22.197568)
		(width 0.508)
		(layer "F.Cu")
		(net "PVDDQ_GHJ")
	)
	(segment
		(start 78.998318 -26.85415)
		(end 79.663798 -26.85415)
		(width 0.4064)
		(layer "F.Cu")
		(net "PVDDQ_GHJ")
	)
	(segment
		(start 107.899454 -20.023582)
		(end 107.899454 -18.730468)
		(width 0.508)
		(layer "F.Cu")
		(net "PVDDQ_GHJ")
	)
	(segment
		(start 84.0994 1.152144)
		(end 84.0994 -0.821182)
		(width 0.508)
		(layer "F.Cu")
		(net "PVDDQ_GHJ")
	)
	(segment
		(start 95.221298 -57.57164)
		(end 94.649798 -57.57164)
		(width 0.254)
		(layer "F.Cu")
		(net "PVDDQ_GHJ")
	)
	(segment
		(start 93.449394 -16.517874)
		(end 93.215968 -16.7513)
		(width 0.508)
		(layer "F.Cu")
		(net "PVDDQ_GHJ")
	)
	(segment
		(start 100.372164 -54.59984)
		(end 99.800664 -54.59984)
		(width 0.254)
		(layer "F.Cu")
		(net "PVDDQ_GHJ")
	)
	(segment
		(start 112.149382 -7.113778)
		(end 112.149382 -5.822442)
		(width 0.508)
		(layer "F.Cu")
		(net "PVDDQ_GHJ")
	)
	(segment
		(start 103.649526 -20.023582)
		(end 103.649526 -21.45665)
		(width 0.508)
		(layer "F.Cu")
		(net "PVDDQ_GHJ")
	)
	(segment
		(start 106.199432 2.464054)
		(end 106.199432 3.778758)
		(width 0.508)
		(layer "F.Cu")
		(net "PVDDQ_GHJ")
	)
	(segment
		(start 103.469694 -22.01799)
		(end 103.649272 -22.197568)
		(width 0.254)
		(layer "F.Cu")
		(net "PVDDQ_GHJ")
	)
	(segment
		(start 94.362778 -59.057286)
		(end 93.791278 -59.057286)
		(width 0.254)
		(layer "F.Cu")
		(net "PVDDQ_GHJ")
	)
	(segment
		(start 107.899454 -0.821182)
		(end 107.899454 1.152144)
		(width 0.508)
		(layer "F.Cu")
		(net "PVDDQ_GHJ")
	)
	(segment
		(start 163.91255 -70.694296)
		(end 164.246814 -71.02856)
		(width 0.254)
		(layer "F.Cu")
		(net "PVDDQ_GHJ")
	)
	(segment
		(start 83.249516 3.778758)
		(end 83.249516 1.805432)
		(width 0.508)
		(layer "F.Cu")
		(net "PVDDQ_GHJ")
	)
	(segment
		(start 110.44936 -7.179564)
		(end 110.44936 -5.822442)
		(width 0.508)
		(layer "F.Cu")
		(net "PVDDQ_GHJ")
	)
	(segment
		(start 86.64956 -20.023582)
		(end 86.64956 -18.734278)
		(width 0.508)
		(layer "F.Cu")
		(net "PVDDQ_GHJ")
	)
	(segment
		(start 101.949758 -7.117588)
		(end 101.949504 -7.117334)
		(width 0.508)
		(layer "F.Cu")
		(net "PVDDQ_GHJ")
	)
	(segment
		(start 91.787218 -54.59984)
		(end 91.215718 -54.59984)
		(width 0.254)
		(layer "F.Cu")
		(net "PVDDQ_GHJ")
	)
	(segment
		(start 108.749338 3.778758)
		(end 108.749338 1.805432)
		(width 0.508)
		(layer "F.Cu")
		(net "PVDDQ_GHJ")
	)
	(segment
		(start 88.349582 -13.933678)
		(end 88.392 -13.89126)
		(width 0.508)
		(layer "F.Cu")
		(net "PVDDQ_GHJ")
	)
	(segment
		(start 80.699356 -15.423642)
		(end 80.699356 -16.716756)
		(width 0.508)
		(layer "F.Cu")
		(net "PVDDQ_GHJ")
	)
	(segment
		(start 92.645738 -62.029086)
		(end 92.074238 -62.029086)
		(width 0.254)
		(layer "F.Cu")
		(net "PVDDQ_GHJ")
	)
	(segment
		(start 91.171522 -21.952966)
		(end 90.899488 -22.225)
		(width 0.254)
		(layer "F.Cu")
		(net "PVDDQ_GHJ")
	)
	(segment
		(start 86.636352 -58.561986)
		(end 86.636352 -58.770266)
		(width 0.254)
		(layer "F.Cu")
		(net "PVDDQ_GHJ")
	)
	(segment
		(start 90.899488 -11.916156)
		(end 90.899488 -10.422382)
		(width 0.508)
		(layer "F.Cu")
		(net "PVDDQ_GHJ")
	)
	(segment
		(start 109.599476 -0.821182)
		(end 109.599476 1.152144)
		(width 0.508)
		(layer "F.Cu")
		(net "PVDDQ_GHJ")
	)
	(segment
		(start 80.757268 -3.107182)
		(end 80.757268 -3.3528)
		(width 0.508)
		(layer "F.Cu")
		(net "PVDDQ_GHJ")
	)
	(segment
		(start 111.964978 -21.080476)
		(end 111.964978 -22.013164)
		(width 0.254)
		(layer "F.Cu")
		(net "PVDDQ_GHJ")
	)
	(segment
		(start 95.221298 -51.62804)
		(end 95.508318 -52.123594)
		(width 0.254)
		(layer "F.Cu")
		(net "PVDDQ_GHJ")
	)
	(segment
		(start 83.249516 -5.822442)
		(end 83.249516 -7.115556)
		(width 0.508)
		(layer "F.Cu")
		(net "PVDDQ_GHJ")
	)
	(segment
		(start 78.999334 -15.423642)
		(end 78.999334 -16.716756)
		(width 0.508)
		(layer "F.Cu")
		(net "PVDDQ_GHJ")
	)
	(segment
		(start 81.549494 -0.821182)
		(end 81.549494 0.442722)
		(width 0.508)
		(layer "F.Cu")
		(net "PVDDQ_GHJ")
	)
	(segment
		(start 91.088972 -13.929868)
		(end 90.899488 -14.119352)
		(width 0.381)
		(layer "F.Cu")
		(net "PVDDQ_GHJ")
	)
	(segment
		(start 90.899488 2.485644)
		(end 90.899488 0.471932)
		(width 0.508)
		(layer "F.Cu")
		(net "PVDDQ_GHJ")
	)
	(segment
		(start 90.899488 0.471932)
		(end 90.899488 -0.821182)
		(width 0.508)
		(layer "F.Cu")
		(net "PVDDQ_GHJ")
	)
	(segment
		(start 108.749338 -16.71828)
		(end 108.749846 -16.718788)
		(width 0.508)
		(layer "F.Cu")
		(net "PVDDQ_GHJ")
	)
	(segment
		(start 111.964978 -22.013164)
		(end 112.149382 -22.197568)
		(width 0.254)
		(layer "F.Cu")
		(net "PVDDQ_GHJ")
	)
	(segment
		(start 96.079818 -50.141886)
		(end 96.079818 -49.150778)
		(width 0.2032)
		(layer "F.Cu")
		(net "PVDDQ_GHJ")
	)
	(segment
		(start 93.449394 2.485644)
		(end 93.449394 0.471932)
		(width 0.4064)
		(layer "F.Cu")
		(net "PVDDQ_GHJ")
	)
	(segment
		(start 101.099366 -10.422382)
		(end 101.099366 -11.914378)
		(width 0.508)
		(layer "F.Cu")
		(net "PVDDQ_GHJ")
	)
	(segment
		(start 101.099366 -20.023582)
		(end 101.099366 -18.730468)
		(width 0.508)
		(layer "F.Cu")
		(net "PVDDQ_GHJ")
	)
	(segment
		(start 78.999334 3.778758)
		(end 78.999334 2.485644)
		(width 0.508)
		(layer "F.Cu")
		(net "PVDDQ_GHJ")
	)
	(segment
		(start 109.599476 -20.023582)
		(end 109.599476 -18.730468)
		(width 0.508)
		(layer "F.Cu")
		(net "PVDDQ_GHJ")
	)
	(segment
		(start 99.800664 -57.57164)
		(end 100.372164 -57.57164)
		(width 0.254)
		(layer "F.Cu")
		(net "PVDDQ_GHJ")
	)
	(segment
		(start 92.645738 -59.057286)
		(end 92.074238 -59.057286)
		(width 0.254)
		(layer "F.Cu")
		(net "PVDDQ_GHJ")
	)
	(segment
		(start 93.449394 3.778758)
		(end 93.449394 2.485644)
		(width 0.508)
		(layer "F.Cu")
		(net "PVDDQ_GHJ")
	)
	(segment
		(start 103.649526 -20.023582)
		(end 103.649526 -18.730468)
		(width 0.508)
		(layer "F.Cu")
		(net "PVDDQ_GHJ")
	)
	(segment
		(start 89.199466 -20.023582)
		(end 89.199466 -18.734278)
		(width 0.508)
		(layer "F.Cu")
		(net "PVDDQ_GHJ")
	)
	(segment
		(start 93.449394 -20.023582)
		(end 93.449394 -18.699226)
		(width 0.508)
		(layer "F.Cu")
		(net "PVDDQ_GHJ")
	)
	(segment
		(start 106.199432 -15.423642)
		(end 106.199432 -16.714978)
		(width 0.508)
		(layer "F.Cu")
		(net "PVDDQ_GHJ")
	)
	(segment
		(start 81.549494 -2.314956)
		(end 80.757268 -3.107182)
		(width 0.508)
		(layer "F.Cu")
		(net "PVDDQ_GHJ")
	)
	(segment
		(start 85.799422 3.778758)
		(end 85.799422 2.514854)
		(width 0.508)
		(layer "F.Cu")
		(net "PVDDQ_GHJ")
	)
	(segment
		(start 112.149382 -0.821182)
		(end 112.149382 0.468122)
		(width 0.508)
		(layer "F.Cu")
		(net "PVDDQ_GHJ")
	)
	(segment
		(start 84.0994 -20.023582)
		(end 84.0994 -21.517356)
		(width 0.508)
		(layer "F.Cu")
		(net "PVDDQ_GHJ")
	)
	(segment
		(start 79.849472 -21.52269)
		(end 80.029304 -21.702522)
		(width 0.254)
		(layer "F.Cu")
		(net "PVDDQ_GHJ")
	)
	(segment
		(start 112.149382 -18.730468)
		(end 112.149382 -20.023582)
		(width 0.508)
		(layer "F.Cu")
		(net "PVDDQ_GHJ")
	)
	(segment
		(start 2.54635 -15.065756)
		(end 2.29235 -14.811756)
		(width 0.254)
		(layer "F.Cu")
		(net "PVDDQ_GHJ")
	)
	(segment
		(start 90.899488 -5.822442)
		(end 90.899488 -7.115556)
		(width 0.508)
		(layer "F.Cu")
		(net "PVDDQ_GHJ")
	)
	(segment
		(start 88.353392 -57.57164)
		(end 87.781892 -57.57164)
		(width 0.254)
		(layer "F.Cu")
		(net "PVDDQ_GHJ")
	)
	(segment
		(start 164.292026 -71.02856)
		(end 164.461698 -71.198232)
		(width 0.254)
		(layer "F.Cu")
		(net "PVDDQ_GHJ")
	)
	(segment
		(start 103.649526 -11.914378)
		(end 103.649526 -10.422382)
		(width 0.508)
		(layer "F.Cu")
		(net "PVDDQ_GHJ")
	)
	(segment
		(start 103.469694 -21.636482)
		(end 103.469694 -22.01799)
		(width 0.254)
		(layer "F.Cu")
		(net "PVDDQ_GHJ")
	)
	(segment
		(start 106.199432 1.152144)
		(end 106.199432 2.464054)
		(width 0.508)
		(layer "F.Cu")
		(net "PVDDQ_GHJ")
	)
	(segment
		(start 2.370582 -7.098538)
		(end 2.683002 -7.098538)
		(width 0.254)
		(layer "F.Cu")
		(net "PVDDQ_GHJ")
	)
	(segment
		(start 102.947724 -50.803556)
		(end 102.715568 -50.5714)
		(width 0.254)
		(layer "F.Cu")
		(net "PVDDQ_GHJ")
	)
	(segment
		(start 80.757268 -4.274566)
		(end 80.757268 -3.3528)
		(width 0.508)
		(layer "F.Cu")
		(net "PVDDQ_GHJ")
	)
	(segment
		(start 81.549494 -20.023582)
		(end 81.549494 -18.734278)
		(width 0.508)
		(layer "F.Cu")
		(net "PVDDQ_GHJ")
	)
	(segment
		(start 110.44936 -15.423642)
		(end 110.44936 -16.71828)
		(width 0.508)
		(layer "F.Cu")
		(net "PVDDQ_GHJ")
	)
	(segment
		(start 2.765552 -15.065756)
		(end 2.54635 -15.065756)
		(width 0.254)
		(layer "F.Cu")
		(net "PVDDQ_GHJ")
	)
	(segment
		(start 79.849472 -9.133078)
		(end 79.849472 -10.422382)
		(width 0.508)
		(layer "F.Cu")
		(net "PVDDQ_GHJ")
	)
	(segment
		(start 89.199466 -10.422382)
		(end 89.199466 -11.918188)
		(width 0.508)
		(layer "F.Cu")
		(net "PVDDQ_GHJ")
	)
	(segment
		(start 101.94925 3.778504)
		(end 101.94925 1.805432)
		(width 0.508)
		(layer "F.Cu")
		(net "PVDDQ_GHJ")
	)
	(segment
		(start 90.928698 -50.141886)
		(end 90.928698 -49.150778)
		(width 0.2032)
		(layer "F.Cu")
		(net "PVDDQ_GHJ")
	)
	(segment
		(start 101.949504 -7.117334)
		(end 101.949504 -5.822442)
		(width 0.508)
		(layer "F.Cu")
		(net "PVDDQ_GHJ")
	)
	(segment
		(start 83.817968 1.368552)
		(end 84.0994 1.152144)
		(width 0.508)
		(layer "F.Cu")
		(net "PVDDQ_GHJ")
	)
	(segment
		(start 109.599476 -20.023582)
		(end 109.599476 -21.515324)
		(width 0.508)
		(layer "F.Cu")
		(net "PVDDQ_GHJ")
	)
	(segment
		(start 101.099366 -0.821182)
		(end 101.099366 -2.313178)
		(width 0.508)
		(layer "F.Cu")
		(net "PVDDQ_GHJ")
	)
	(segment
		(start 93.504258 -54.59984)
		(end 92.932758 -54.59984)
		(width 0.254)
		(layer "F.Cu")
		(net "PVDDQ_GHJ")
	)
	(segment
		(start 28.575 -13.3731)
		(end 28.575 -13.593572)
		(width 0.4064)
		(layer "F.Cu")
		(net "PVDDQ_GHJ")
	)
	(segment
		(start 80.699356 -7.115556)
		(end 80.699356 -5.822442)
		(width 0.508)
		(layer "F.Cu")
		(net "PVDDQ_GHJ")
	)
	(segment
		(start 93.449394 -9.129268)
		(end 93.449394 -10.422382)
		(width 0.508)
		(layer "F.Cu")
		(net "PVDDQ_GHJ")
	)
	(segment
		(start 90.070178 -54.59984)
		(end 89.498678 -54.59984)
		(width 0.254)
		(layer "F.Cu")
		(net "PVDDQ_GHJ")
	)
	(segment
		(start 96.079818 -59.057286)
		(end 95.508318 -59.057286)
		(width 0.254)
		(layer "F.Cu")
		(net "PVDDQ_GHJ")
	)
	(segment
		(start 93.449394 -5.822442)
		(end 93.449394 -7.115556)
		(width 0.508)
		(layer "F.Cu")
		(net "PVDDQ_GHJ")
	)
	(segment
		(start 102.715568 -50.5714)
		(end 102.649528 -50.63744)
		(width 0.254)
		(layer "F.Cu")
		(net "PVDDQ_GHJ")
	)
	(segment
		(start 90.070178 -57.57164)
		(end 89.498678 -57.57164)
		(width 0.254)
		(layer "F.Cu")
		(net "PVDDQ_GHJ")
	)
	(segment
		(start 79.849472 -10.422382)
		(end 79.849472 -11.916156)
		(width 0.508)
		(layer "F.Cu")
		(net "PVDDQ_GHJ")
	)
	(segment
		(start 98.083878 -57.57164)
		(end 98.655378 -57.57164)
		(width 0.254)
		(layer "F.Cu")
		(net "PVDDQ_GHJ")
	)
	(segment
		(start 102.649528 -50.63744)
		(end 102.089204 -50.63744)
		(width 0.254)
		(layer "F.Cu")
		(net "PVDDQ_GHJ")
	)
	(segment
		(start 89.199466 1.152144)
		(end 89.199466 -0.821182)
		(width 0.508)
		(layer "F.Cu")
		(net "PVDDQ_GHJ")
	)
	(segment
		(start 101.230684 -59.057286)
		(end 100.659184 -59.057286)
		(width 0.254)
		(layer "F.Cu")
		(net "PVDDQ_GHJ")
	)
	(segment
		(start 80.699356 -13.933678)
		(end 80.699356 -15.423642)
		(width 0.508)
		(layer "F.Cu")
		(net "PVDDQ_GHJ")
	)
	(segment
		(start 109.599476 -21.515324)
		(end 109.5756 -21.5392)
		(width 0.508)
		(layer "F.Cu")
		(net "PVDDQ_GHJ")
	)
	(segment
		(start 78.735174 -26.591006)
		(end 78.998318 -26.85415)
		(width 0.4064)
		(layer "F.Cu")
		(net "PVDDQ_GHJ")
	)
	(segment
		(start 99.513898 -59.057286)
		(end 98.942398 -59.057286)
		(width 0.254)
		(layer "F.Cu")
		(net "PVDDQ_GHJ")
	)
	(segment
		(start 163.592764 -70.694296)
		(end 163.91255 -70.694296)
		(width 0.254)
		(layer "F.Cu")
		(net "PVDDQ_GHJ")
	)
	(segment
		(start 91.056714 -18.663666)
		(end 90.899488 -18.820892)
		(width 0.508)
		(layer "F.Cu")
		(net "PVDDQ_GHJ")
	)
	(segment
		(start 104.49941 -16.718534)
		(end 104.499664 -16.718788)
		(width 0.508)
		(layer "F.Cu")
		(net "PVDDQ_GHJ")
	)
	(segment
		(start 101.949504 3.778758)
		(end 101.94925 3.778504)
		(width 0.508)
		(layer "F.Cu")
		(net "PVDDQ_GHJ")
	)
	(segment
		(start 93.449394 -0.821182)
		(end 93.449394 -2.314956)
		(width 0.508)
		(layer "F.Cu")
		(net "PVDDQ_GHJ")
	)
	(segment
		(start 89.199466 -20.023582)
		(end 89.199466 -21.488146)
		(width 0.508)
		(layer "F.Cu")
		(net "PVDDQ_GHJ")
	)
	(segment
		(start 93.504258 -51.62804)
		(end 92.932758 -51.62804)
		(width 0.254)
		(layer "F.Cu")
		(net "PVDDQ_GHJ")
	)
	(segment
		(start 101.949504 -16.718534)
		(end 101.949758 -16.718788)
		(width 0.508)
		(layer "F.Cu")
		(net "PVDDQ_GHJ")
	)
	(segment
		(start 97.796858 -59.057286)
		(end 97.225358 -59.057286)
		(width 0.254)
		(layer "F.Cu")
		(net "PVDDQ_GHJ")
	)
	(segment
		(start 101.949504 -13.929868)
		(end 101.949504 -15.423642)
		(width 0.508)
		(layer "F.Cu")
		(net "PVDDQ_GHJ")
	)
	(segment
		(start 106.199432 -0.821182)
		(end 106.199432 1.152144)
		(width 0.508)
		(layer "F.Cu")
		(net "PVDDQ_GHJ")
	)
	(segment
		(start 86.64956 0.442722)
		(end 86.64956 -0.821182)
		(width 0.508)
		(layer "F.Cu")
		(net "PVDDQ_GHJ")
	)
	(segment
		(start 90.899488 -15.423642)
		(end 90.899488 -16.696944)
		(width 0.508)
		(layer "F.Cu")
		(net "PVDDQ_GHJ")
	)
	(segment
		(start 93.504258 -57.57164)
		(end 92.932758 -57.57164)
		(width 0.254)
		(layer "F.Cu")
		(net "PVDDQ_GHJ")
	)
	(segment
		(start 90.959178 -21.36521)
		(end 91.171522 -21.577554)
		(width 0.254)
		(layer "F.Cu")
		(net "PVDDQ_GHJ")
	)
	(segment
		(start 93.449394 -18.699226)
		(end 93.406468 -18.6563)
		(width 0.508)
		(layer "F.Cu")
		(net "PVDDQ_GHJ")
	)
	(segment
		(start 80.699356 -4.332478)
		(end 80.757268 -4.274566)
		(width 0.508)
		(layer "F.Cu")
		(net "PVDDQ_GHJ")
	)
	(segment
		(start 86.64956 -11.918188)
		(end 86.64956 -10.422382)
		(width 0.508)
		(layer "F.Cu")
		(net "PVDDQ_GHJ")
	)
	(segment
		(start 88.349582 -16.718788)
		(end 88.349582 -15.423642)
		(width 0.508)
		(layer "F.Cu")
		(net "PVDDQ_GHJ")
	)
	(segment
		(start 86.923372 -59.057286)
		(end 87.494872 -59.057286)
		(width 0.254)
		(layer "F.Cu")
		(net "PVDDQ_GHJ")
	)
	(segment
		(start 107.899454 -20.023582)
		(end 107.899454 -21.5392)
		(width 0.508)
		(layer "F.Cu")
		(net "PVDDQ_GHJ")
	)
	(segment
		(start 96.938338 -54.59984)
		(end 96.366838 -54.59984)
		(width 0.254)
		(layer "F.Cu")
		(net "PVDDQ_GHJ")
	)
	(segment
		(start 90.070178 -51.62804)
		(end 90.357198 -52.12334)
		(width 0.254)
		(layer "F.Cu")
		(net "PVDDQ_GHJ")
	)
	(segment
		(start 90.899488 -18.820892)
		(end 90.899488 -20.023582)
		(width 0.508)
		(layer "F.Cu")
		(net "PVDDQ_GHJ")
	)
	(segment
		(start 94.362778 -62.029086)
		(end 93.791278 -62.029086)
		(width 0.254)
		(layer "F.Cu")
		(net "PVDDQ_GHJ")
	)
	(segment
		(start 99.513898 -50.141886)
		(end 99.798632 -49.54778)
		(width 0.254)
		(layer "F.Cu")
		(net "PVDDQ_GHJ")
	)
	(segment
		(start 81.549494 -9.133078)
		(end 81.549494 -10.422382)
		(width 0.508)
		(layer "F.Cu")
		(net "PVDDQ_GHJ")
	)
	(segment
		(start 87.781892 -51.62804)
		(end 88.353392 -51.62804)
		(width 0.254)
		(layer "F.Cu")
		(net "PVDDQ_GHJ")
	)
	(segment
		(start 28.575 -13.593572)
		(end 28.976828 -13.9954)
		(width 0.4064)
		(layer "F.Cu")
		(net "PVDDQ_GHJ")
	)
	(segment
		(start 91.787218 -57.57164)
		(end 91.215718 -57.57164)
		(width 0.254)
		(layer "F.Cu")
		(net "PVDDQ_GHJ")
	)
	(segment
		(start 104.49941 3.778758)
		(end 104.49941 2.485644)
		(width 0.508)
		(layer "F.Cu")
		(net "PVDDQ_GHJ")
	)
	(segment
		(start 103.649526 -2.313178)
		(end 103.649526 -0.821182)
		(width 0.508)
		(layer "F.Cu")
		(net "PVDDQ_GHJ")
	)
	(segment
		(start 84.0994 -11.916156)
		(end 84.0994 -10.422382)
		(width 0.508)
		(layer "F.Cu")
		(net "PVDDQ_GHJ")
	)
	(segment
		(start 98.083878 -54.59984)
		(end 98.655378 -54.59984)
		(width 0.254)
		(layer "F.Cu")
		(net "PVDDQ_GHJ")
	)
	(segment
		(start 86.64956 -20.023582)
		(end 86.64956 -22.197568)
		(width 0.508)
		(layer "F.Cu")
		(net "PVDDQ_GHJ")
	)
	(segment
		(start 90.899488 -20.023582)
		(end 90.899488 -21.30552)
		(width 0.508)
		(layer "F.Cu")
		(net "PVDDQ_GHJ")
	)
	(segment
		(start 103.649526 -0.821182)
		(end 103.649526 0.442468)
		(width 0.508)
		(layer "F.Cu")
		(net "PVDDQ_GHJ")
	)
	(segment
		(start 79.849472 -20.023582)
		(end 79.849472 -18.734278)
		(width 0.508)
		(layer "F.Cu")
		(net "PVDDQ_GHJ")
	)
	(segment
		(start 90.899488 -14.119352)
		(end 90.899488 -15.423642)
		(width 0.508)
		(layer "F.Cu")
		(net "PVDDQ_GHJ")
	)
	(segment
		(start 106.199432 -10.422382)
		(end 106.199432 -11.914378)
		(width 0.508)
		(layer "F.Cu")
		(net "PVDDQ_GHJ")
	)
	(segment
		(start 87.494872 -62.029086)
		(end 86.923372 -62.029086)
		(width 0.254)
		(layer "F.Cu")
		(net "PVDDQ_GHJ")
	)
	(segment
		(start 112.149382 -0.821182)
		(end 112.149382 -2.313178)
		(width 0.508)
		(layer "F.Cu")
		(net "PVDDQ_GHJ")
	)
	(segment
		(start 88.392 -13.89126)
		(end 88.392 -12.954)
		(width 0.508)
		(layer "F.Cu")
		(net "PVDDQ_GHJ")
	)
	(segment
		(start 110.44936 -16.71828)
		(end 110.449868 -16.718788)
		(width 0.508)
		(layer "F.Cu")
		(net "PVDDQ_GHJ")
	)
	(segment
		(start 86.636352 -55.59044)
		(end 86.064852 -55.59044)
		(width 0.254)
		(layer "F.Cu")
		(net "PVDDQ_GHJ")
	)
	(segment
		(start 89.211912 -59.057286)
		(end 88.640412 -59.057286)
		(width 0.254)
		(layer "F.Cu")
		(net "PVDDQ_GHJ")
	)
	(segment
		(start 109.599476 -2.313178)
		(end 109.599476 -0.821182)
		(width 0.508)
		(layer "F.Cu")
		(net "PVDDQ_GHJ")
	)
	(segment
		(start 79.849472 -0.821182)
		(end 79.849472 0.468122)
		(width 0.508)
		(layer "F.Cu")
		(net "PVDDQ_GHJ")
	)
	(via
		(at 93.449394 0.471932)
		(size 0.508)
		(drill 0.254)
		(layers "F.Cu" "B.Cu")
		(net "PVDDQ_GHJ")
	)
	(via
		(at 81.549494 -22.197568)
		(size 0.508)
		(drill 0.254)
		(layers "F.Cu" "B.Cu")
		(net "PVDDQ_GHJ")
	)
	(via
		(at 88.349582 -13.933678)
		(size 0.508)
		(drill 0.254)
		(layers "F.Cu" "B.Cu")
		(net "PVDDQ_GHJ")
	)
	(via
		(at 91.089226 -9.151874)
		(size 0.508)
		(drill 0.254)
		(layers "F.Cu" "B.Cu")
		(net "PVDDQ_GHJ")
	)
	(via
		(at 103.664004 -26.8605)
		(size 0.508)
		(drill 0.254)
		(layers "F.Cu" "B.Cu")
		(net "PVDDQ_GHJ")
	)
	(via
		(at 107.899454 -9.129268)
		(size 0.508)
		(drill 0.254)
		(layers "F.Cu" "B.Cu")
		(net "PVDDQ_GHJ")
	)
	(via
		(at 93.449394 -22.225)
		(size 0.508)
		(drill 0.254)
		(layers "F.Cu" "B.Cu")
		(net "PVDDQ_GHJ")
	)
	(via
		(at 112.149382 -13.929868)
		(size 0.508)
		(drill 0.254)
		(layers "F.Cu" "B.Cu")
		(net "PVDDQ_GHJ")
	)
	(via
		(at 15.621 -11.049)
		(size 0.508)
		(drill 0.254)
		(layers "F.Cu" "B.Cu")
		(net "PVDDQ_GHJ")
	)
	(via
		(at 104.499664 -13.933678)
		(size 0.508)
		(drill 0.254)
		(layers "F.Cu" "B.Cu")
		(net "PVDDQ_GHJ")
	)
	(via
		(at 16.51 -6.604)
		(size 0.508)
		(drill 0.254)
		(layers "F.Cu" "B.Cu")
		(net "PVDDQ_GHJ")
	)
	(via
		(at 16.51 -7.239)
		(size 0.508)
		(drill 0.254)
		(layers "F.Cu" "B.Cu")
		(net "PVDDQ_GHJ")
	)
	(via
		(at 108.749846 -16.718788)
		(size 0.4572)
		(drill 0.2032)
		(layers "F.Cu" "B.Cu")
		(net "PVDDQ_GHJ")
	)
	(via
		(at 99.800664 -54.59984)
		(size 0.508)
		(drill 0.254)
		(layers "F.Cu" "B.Cu")
		(net "PVDDQ_GHJ")
	)
	(via
		(at 83.249516 -7.115556)
		(size 0.508)
		(drill 0.254)
		(layers "F.Cu" "B.Cu")
		(net "PVDDQ_GHJ")
	)
	(via
		(at 112.149382 -18.730468)
		(size 0.508)
		(drill 0.254)
		(layers "F.Cu" "B.Cu")
		(net "PVDDQ_GHJ")
	)
	(via
		(at 107.899454 -21.5392)
		(size 0.508)
		(drill 0.254)
		(layers "F.Cu" "B.Cu")
		(net "PVDDQ_GHJ")
	)
	(via
		(at 112.149382 -16.714978)
		(size 0.508)
		(drill 0.254)
		(layers "F.Cu" "B.Cu")
		(net "PVDDQ_GHJ")
	)
	(via
		(at 17.907 -11.811)
		(size 0.508)
		(drill 0.254)
		(layers "F.Cu" "B.Cu")
		(net "PVDDQ_GHJ")
	)
	(via
		(at 108.634784 -26.8732)
		(size 0.508)
		(drill 0.254)
		(layers "F.Cu" "B.Cu")
		(net "PVDDQ_GHJ")
	)
	(via
		(at 84.0994 -18.734278)
		(size 0.508)
		(drill 0.254)
		(layers "F.Cu" "B.Cu")
		(net "PVDDQ_GHJ")
	)
	(via
		(at 29.12872 -4.39928)
		(size 0.508)
		(drill 0.254)
		(layers "F.Cu" "B.Cu")
		(net "PVDDQ_GHJ")
	)
	(via
		(at 104.49941 -22.850856)
		(size 0.508)
		(drill 0.254)
		(layers "F.Cu" "B.Cu")
		(net "PVDDQ_GHJ")
	)
	(via
		(at 19.431 -11.811)
		(size 0.508)
		(drill 0.254)
		(layers "F.Cu" "B.Cu")
		(net "PVDDQ_GHJ")
	)
	(via
		(at 86.923372 -62.029086)
		(size 0.508)
		(drill 0.254)
		(layers "F.Cu" "B.Cu")
		(net "PVDDQ_GHJ")
	)
	(via
		(at 102.715568 -50.5714)
		(size 0.508)
		(drill 0.254)
		(layers "F.Cu" "B.Cu")
		(net "PVDDQ_GHJ")
	)
	(via
		(at 20.090384 -2.511044)
		(size 0.508)
		(drill 0.254)
		(layers "F.Cu" "B.Cu")
		(net "PVDDQ_GHJ")
	)
	(via
		(at 28.449778 -23.657306)
		(size 0.508)
		(drill 0.254)
		(layers "F.Cu" "B.Cu")
		(net "PVDDQ_GHJ")
	)
	(via
		(at 88.349582 -16.718788)
		(size 0.508)
		(drill 0.254)
		(layers "F.Cu" "B.Cu")
		(net "PVDDQ_GHJ")
	)
	(via
		(at 101.700076 -67.284346)
		(size 0.508)
		(drill 0.254)
		(layers "F.Cu" "B.Cu")
		(net "PVDDQ_GHJ")
	)
	(via
		(at 91.088972 -13.929868)
		(size 0.508)
		(drill 0.254)
		(layers "F.Cu" "B.Cu")
		(net "PVDDQ_GHJ")
	)
	(via
		(at 101.94925 -23.560278)
		(size 0.508)
		(drill 0.254)
		(layers "F.Cu" "B.Cu")
		(net "PVDDQ_GHJ")
	)
	(via
		(at 84.0994 -9.133078)
		(size 0.508)
		(drill 0.254)
		(layers "F.Cu" "B.Cu")
		(net "PVDDQ_GHJ")
	)
	(via
		(at 93.449394 -9.129268)
		(size 0.508)
		(drill 0.254)
		(layers "F.Cu" "B.Cu")
		(net "PVDDQ_GHJ")
	)
	(via
		(at 92.074238 -62.029086)
		(size 0.508)
		(drill 0.254)
		(layers "F.Cu" "B.Cu")
		(net "PVDDQ_GHJ")
	)
	(via
		(at 15.113 -6.604)
		(size 0.508)
		(drill 0.254)
		(layers "F.Cu" "B.Cu")
		(net "PVDDQ_GHJ")
	)
	(via
		(at 2.19964 -6.927596)
		(size 0.508)
		(drill 0.254)
		(layers "F.Cu" "B.Cu")
		(net "PVDDQ_GHJ")
	)
	(via
		(at 109.599476 -11.914378)
		(size 0.508)
		(drill 0.254)
		(layers "F.Cu" "B.Cu")
		(net "PVDDQ_GHJ")
	)
	(via
		(at 106.199432 -18.730468)
		(size 0.508)
		(drill 0.254)
		(layers "F.Cu" "B.Cu")
		(net "PVDDQ_GHJ")
	)
	(via
		(at 89.199466 -11.918188)
		(size 0.508)
		(drill 0.254)
		(layers "F.Cu" "B.Cu")
		(net "PVDDQ_GHJ")
	)
	(via
		(at 87.781892 -51.62804)
		(size 0.508)
		(drill 0.254)
		(layers "F.Cu" "B.Cu")
		(net "PVDDQ_GHJ")
	)
	(via
		(at 90.357198 -62.029086)
		(size 0.508)
		(drill 0.254)
		(layers "F.Cu" "B.Cu")
		(net "PVDDQ_GHJ")
	)
	(via
		(at 104.499664 -16.718788)
		(size 0.4572)
		(drill 0.2032)
		(layers "F.Cu" "B.Cu")
		(net "PVDDQ_GHJ")
	)
	(via
		(at 20.193 -11.811)
		(size 0.508)
		(drill 0.254)
		(layers "F.Cu" "B.Cu")
		(net "PVDDQ_GHJ")
	)
	(via
		(at 98.083878 -57.57164)
		(size 0.508)
		(drill 0.254)
		(layers "F.Cu" "B.Cu")
		(net "PVDDQ_GHJ")
	)
	(via
		(at 101.94925 1.805432)
		(size 0.508)
		(drill 0.254)
		(layers "F.Cu" "B.Cu")
		(net "PVDDQ_GHJ")
	)
	(via
		(at 88.349582 1.805432)
		(size 0.508)
		(drill 0.254)
		(layers "F.Cu" "B.Cu")
		(net "PVDDQ_GHJ")
	)
	(via
		(at 87.781892 -57.57164)
		(size 0.508)
		(drill 0.254)
		(layers "F.Cu" "B.Cu")
		(net "PVDDQ_GHJ")
	)
	(via
		(at 109.599476 -2.313178)
		(size 0.508)
		(drill 0.254)
		(layers "F.Cu" "B.Cu")
		(net "PVDDQ_GHJ")
	)
	(via
		(at 96.366838 -54.59984)
		(size 0.508)
		(drill 0.254)
		(layers "F.Cu" "B.Cu")
		(net "PVDDQ_GHJ")
	)
	(via
		(at 15.367 -20.066)
		(size 0.508)
		(drill 0.254)
		(layers "F.Cu" "B.Cu")
		(net "PVDDQ_GHJ")
	)
	(via
		(at 20.72894 -2.326386)
		(size 0.508)
		(drill 0.254)
		(layers "F.Cu" "B.Cu")
		(net "PVDDQ_GHJ")
	)
	(via
		(at 97.225358 -59.057286)
		(size 0.508)
		(drill 0.254)
		(layers "F.Cu" "B.Cu")
		(net "PVDDQ_GHJ")
	)
	(via
		(at 89.498678 -57.57164)
		(size 0.508)
		(drill 0.254)
		(layers "F.Cu" "B.Cu")
		(net "PVDDQ_GHJ")
	)
	(via
		(at 169.149268 -1.197864)
		(size 0.508)
		(drill 0.254)
		(layers "F.Cu" "B.Cu")
		(net "PVDDQ_GHJ")
	)
	(via
		(at 108.749338 1.805432)
		(size 0.508)
		(drill 0.254)
		(layers "F.Cu" "B.Cu")
		(net "PVDDQ_GHJ")
	)
	(via
		(at 83.249516 1.805432)
		(size 0.508)
		(drill 0.254)
		(layers "F.Cu" "B.Cu")
		(net "PVDDQ_GHJ")
	)
	(via
		(at 18.542 -17.907)
		(size 0.508)
		(drill 0.254)
		(layers "F.Cu" "B.Cu")
		(net "PVDDQ_GHJ")
	)
	(via
		(at 15.748 -6.604)
		(size 0.508)
		(drill 0.254)
		(layers "F.Cu" "B.Cu")
		(net "PVDDQ_GHJ")
	)
	(via
		(at 80.699356 -22.850856)
		(size 0.508)
		(drill 0.254)
		(layers "F.Cu" "B.Cu")
		(net "PVDDQ_GHJ")
	)
	(via
		(at 82.954368 -26.8224)
		(size 0.508)
		(drill 0.254)
		(layers "F.Cu" "B.Cu")
		(net "PVDDQ_GHJ")
	)
	(via
		(at 18.796 -7.239)
		(size 0.508)
		(drill 0.254)
		(layers "F.Cu" "B.Cu")
		(net "PVDDQ_GHJ")
	)
	(via
		(at 79.663798 -26.85415)
		(size 0.508)
		(drill 0.254)
		(layers "F.Cu" "B.Cu")
		(net "PVDDQ_GHJ")
	)
	(via
		(at 16.383 -12.573)
		(size 0.508)
		(drill 0.254)
		(layers "F.Cu" "B.Cu")
		(net "PVDDQ_GHJ")
	)
	(via
		(at 86.923372 -59.057286)
		(size 0.508)
		(drill 0.254)
		(layers "F.Cu" "B.Cu")
		(net "PVDDQ_GHJ")
	)
	(via
		(at 17.272 -7.239)
		(size 0.508)
		(drill 0.254)
		(layers "F.Cu" "B.Cu")
		(net "PVDDQ_GHJ")
	)
	(via
		(at 110.449868 -13.933678)
		(size 0.508)
		(drill 0.254)
		(layers "F.Cu" "B.Cu")
		(net "PVDDQ_GHJ")
	)
	(via
		(at 89.498678 -54.59984)
		(size 0.508)
		(drill 0.254)
		(layers "F.Cu" "B.Cu")
		(net "PVDDQ_GHJ")
	)
	(via
		(at 78.999334 -7.115556)
		(size 0.508)
		(drill 0.254)
		(layers "F.Cu" "B.Cu")
		(net "PVDDQ_GHJ")
	)
	(via
		(at 15.367 -17.907)
		(size 0.508)
		(drill 0.254)
		(layers "F.Cu" "B.Cu")
		(net "PVDDQ_GHJ")
	)
	(via
		(at 100.659184 -50.129186)
		(size 0.508)
		(drill 0.254)
		(layers "F.Cu" "B.Cu")
		(net "PVDDQ_GHJ")
	)
	(via
		(at 86.64956 -11.918188)
		(size 0.508)
		(drill 0.254)
		(layers "F.Cu" "B.Cu")
		(net "PVDDQ_GHJ")
	)
	(via
		(at 110.449868 -7.180072)
		(size 0.4572)
		(drill 0.2032)
		(layers "F.Cu" "B.Cu")
		(net "PVDDQ_GHJ")
	)
	(via
		(at 95.508318 -52.123594)
		(size 0.508)
		(drill 0.254)
		(layers "F.Cu" "B.Cu")
		(net "PVDDQ_GHJ")
	)
	(via
		(at 90.899488 -16.696944)
		(size 0.508)
		(drill 0.254)
		(layers "F.Cu" "B.Cu")
		(net "PVDDQ_GHJ")
	)
	(via
		(at 106.727752 -67.284346)
		(size 0.5588)
		(drill 0.3048)
		(layers "F.Cu" "B.Cu")
		(net "PVDDQ_GHJ")
	)
	(via
		(at 20.32 -7.366)
		(size 0.508)
		(drill 0.254)
		(layers "F.Cu" "B.Cu")
		(net "PVDDQ_GHJ")
	)
	(via
		(at 85.799422 -4.332478)
		(size 0.508)
		(drill 0.254)
		(layers "F.Cu" "B.Cu")
		(net "PVDDQ_GHJ")
	)
	(via
		(at 14.986 -11.049)
		(size 0.508)
		(drill 0.254)
		(layers "F.Cu" "B.Cu")
		(net "PVDDQ_GHJ")
	)
	(via
		(at 79.849472 -11.916156)
		(size 0.508)
		(drill 0.254)
		(layers "F.Cu" "B.Cu")
		(net "PVDDQ_GHJ")
	)
	(via
		(at 93.791278 -59.057286)
		(size 0.508)
		(drill 0.254)
		(layers "F.Cu" "B.Cu")
		(net "PVDDQ_GHJ")
	)
	(via
		(at 107.899454 -18.730468)
		(size 0.508)
		(drill 0.254)
		(layers "F.Cu" "B.Cu")
		(net "PVDDQ_GHJ")
	)
	(via
		(at 101.517704 -51.62804)
		(size 0.508)
		(drill 0.254)
		(layers "F.Cu" "B.Cu")
		(net "PVDDQ_GHJ")
	)
	(via
		(at 20.095464 -3.139694)
		(size 0.508)
		(drill 0.254)
		(layers "F.Cu" "B.Cu")
		(net "PVDDQ_GHJ")
	)
	(via
		(at 101.949504 -13.929868)
		(size 0.508)
		(drill 0.254)
		(layers "F.Cu" "B.Cu")
		(net "PVDDQ_GHJ")
	)
	(via
		(at 107.465368 -67.233038)
		(size 0.5588)
		(drill 0.3048)
		(layers "F.Cu" "B.Cu")
		(net "PVDDQ_GHJ")
	)
	(via
		(at 83.249516 -16.716756)
		(size 0.508)
		(drill 0.254)
		(layers "F.Cu" "B.Cu")
		(net "PVDDQ_GHJ")
	)
	(via
		(at 15.621 -11.811)
		(size 0.508)
		(drill 0.254)
		(layers "F.Cu" "B.Cu")
		(net "PVDDQ_GHJ")
	)
	(via
		(at 110.44936 1.805432)
		(size 0.508)
		(drill 0.254)
		(layers "F.Cu" "B.Cu")
		(net "PVDDQ_GHJ")
	)
	(via
		(at 95.508318 -59.057286)
		(size 0.508)
		(drill 0.254)
		(layers "F.Cu" "B.Cu")
		(net "PVDDQ_GHJ")
	)
	(via
		(at 16.002 -18.796)
		(size 0.508)
		(drill 0.254)
		(layers "F.Cu" "B.Cu")
		(net "PVDDQ_GHJ")
	)
	(via
		(at 166.7764 -8.001)
		(size 0.508)
		(drill 0.254)
		(layers "F.Cu" "B.Cu")
		(net "PVDDQ_GHJ")
	)
	(via
		(at 93.449394 -11.916156)
		(size 0.508)
		(drill 0.254)
		(layers "F.Cu" "B.Cu")
		(net "PVDDQ_GHJ")
	)
	(via
		(at 80.699356 -7.115556)
		(size 0.508)
		(drill 0.254)
		(layers "F.Cu" "B.Cu")
		(net "PVDDQ_GHJ")
	)
	(via
		(at 79.849472 -22.197568)
		(size 0.508)
		(drill 0.254)
		(layers "F.Cu" "B.Cu")
		(net "PVDDQ_GHJ")
	)
	(via
		(at 92.932758 -51.62804)
		(size 0.508)
		(drill 0.254)
		(layers "F.Cu" "B.Cu")
		(net "PVDDQ_GHJ")
	)
	(via
		(at 90.899488 -7.115556)
		(size 0.508)
		(drill 0.254)
		(layers "F.Cu" "B.Cu")
		(net "PVDDQ_GHJ")
	)
	(via
		(at 92.932758 -54.59984)
		(size 0.508)
		(drill 0.254)
		(layers "F.Cu" "B.Cu")
		(net "PVDDQ_GHJ")
	)
	(via
		(at 83.249516 -23.560278)
		(size 0.508)
		(drill 0.254)
		(layers "F.Cu" "B.Cu")
		(net "PVDDQ_GHJ")
	)
	(via
		(at 17.272 -6.601968)
		(size 0.508)
		(drill 0.254)
		(layers "F.Cu" "B.Cu")
		(net "PVDDQ_GHJ")
	)
	(via
		(at 19.558 -7.239)
		(size 0.508)
		(drill 0.254)
		(layers "F.Cu" "B.Cu")
		(net "PVDDQ_GHJ")
	)
	(via
		(at 92.932758 -57.57164)
		(size 0.508)
		(drill 0.254)
		(layers "F.Cu" "B.Cu")
		(net "PVDDQ_GHJ")
	)
	(via
		(at 96.079818 -49.150778)
		(size 0.508)
		(drill 0.254)
		(layers "F.Cu" "B.Cu")
		(net "PVDDQ_GHJ")
	)
	(via
		(at 103.649272 0.442722)
		(size 0.508)
		(drill 0.254)
		(layers "F.Cu" "B.Cu")
		(net "PVDDQ_GHJ")
	)
	(via
		(at 110.449868 -4.332478)
		(size 0.508)
		(drill 0.254)
		(layers "F.Cu" "B.Cu")
		(net "PVDDQ_GHJ")
	)
	(via
		(at 20.193 -20.066)
		(size 0.508)
		(drill 0.254)
		(layers "F.Cu" "B.Cu")
		(net "PVDDQ_GHJ")
	)
	(via
		(at 101.099366 -21.5392)
		(size 0.508)
		(drill 0.254)
		(layers "F.Cu" "B.Cu")
		(net "PVDDQ_GHJ")
	)
	(via
		(at 88.349582 -7.117588)
		(size 0.508)
		(drill 0.254)
		(layers "F.Cu" "B.Cu")
		(net "PVDDQ_GHJ")
	)
	(via
		(at 109.599476 1.152144)
		(size 0.508)
		(drill 0.254)
		(layers "F.Cu" "B.Cu")
		(net "PVDDQ_GHJ")
	)
	(via
		(at 106.199432 -13.929868)
		(size 0.508)
		(drill 0.254)
		(layers "F.Cu" "B.Cu")
		(net "PVDDQ_GHJ")
	)
	(via
		(at 78.999334 -22.850856)
		(size 0.508)
		(drill 0.254)
		(layers "F.Cu" "B.Cu")
		(net "PVDDQ_GHJ")
	)
	(via
		(at 85.799422 2.514854)
		(size 0.508)
		(drill 0.254)
		(layers "F.Cu" "B.Cu")
		(net "PVDDQ_GHJ")
	)
	(via
		(at 20.193 -20.828)
		(size 0.508)
		(drill 0.254)
		(layers "F.Cu" "B.Cu")
		(net "PVDDQ_GHJ")
	)
	(via
		(at 107.049824 -9.133078)
		(size 0.4572)
		(drill 0.2032)
		(layers "F.Cu" "B.Cu")
		(net "PVDDQ_GHJ")
	)
	(via
		(at 88.640412 -62.029086)
		(size 0.508)
		(drill 0.254)
		(layers "F.Cu" "B.Cu")
		(net "PVDDQ_GHJ")
	)
	(via
		(at 106.199432 -9.129268)
		(size 0.508)
		(drill 0.254)
		(layers "F.Cu" "B.Cu")
		(net "PVDDQ_GHJ")
	)
	(via
		(at 78.999334 -4.332478)
		(size 0.508)
		(drill 0.254)
		(layers "F.Cu" "B.Cu")
		(net "PVDDQ_GHJ")
	)
	(via
		(at 93.449394 -13.929868)
		(size 0.508)
		(drill 0.254)
		(layers "F.Cu" "B.Cu")
		(net "PVDDQ_GHJ")
	)
	(via
		(at 112.149382 -4.328668)
		(size 0.508)
		(drill 0.254)
		(layers "F.Cu" "B.Cu")
		(net "PVDDQ_GHJ")
	)
	(via
		(at 175.895 -3.8862)
		(size 0.508)
		(drill 0.254)
		(layers "F.Cu" "B.Cu")
		(net "PVDDQ_GHJ")
	)
	(via
		(at 100.938076 -67.284346)
		(size 0.508)
		(drill 0.254)
		(layers "F.Cu" "B.Cu")
		(net "PVDDQ_GHJ")
	)
	(via
		(at 79.849472 -18.734278)
		(size 0.508)
		(drill 0.254)
		(layers "F.Cu" "B.Cu")
		(net "PVDDQ_GHJ")
	)
	(via
		(at 92.074238 -59.057286)
		(size 0.508)
		(drill 0.254)
		(layers "F.Cu" "B.Cu")
		(net "PVDDQ_GHJ")
	)
	(via
		(at 80.699356 2.485644)
		(size 0.508)
		(drill 0.254)
		(layers "F.Cu" "B.Cu")
		(net "PVDDQ_GHJ")
	)
	(via
		(at 20.574 -14.859)
		(size 0.508)
		(drill 0.254)
		(layers "F.Cu" "B.Cu")
		(net "PVDDQ_GHJ")
	)
	(via
		(at 20.193 -18.415)
		(size 0.508)
		(drill 0.254)
		(layers "F.Cu" "B.Cu")
		(net "PVDDQ_GHJ")
	)
	(via
		(at 17.907 -11.049)
		(size 0.508)
		(drill 0.254)
		(layers "F.Cu" "B.Cu")
		(net "PVDDQ_GHJ")
	)
	(via
		(at 14.986 -14.224)
		(size 0.508)
		(drill 0.254)
		(layers "F.Cu" "B.Cu")
		(net "PVDDQ_GHJ")
	)
	(via
		(at 105.203752 -67.284346)
		(size 0.5588)
		(drill 0.3048)
		(layers "F.Cu" "B.Cu")
		(net "PVDDQ_GHJ")
	)
	(via
		(at 81.549494 -11.916156)
		(size 0.508)
		(drill 0.254)
		(layers "F.Cu" "B.Cu")
		(net "PVDDQ_GHJ")
	)
	(via
		(at 99.287076 -67.284346)
		(size 0.508)
		(drill 0.254)
		(layers "F.Cu" "B.Cu")
		(net "PVDDQ_GHJ")
	)
	(via
		(at 15.367 -20.701)
		(size 0.508)
		(drill 0.254)
		(layers "F.Cu" "B.Cu")
		(net "PVDDQ_GHJ")
	)
	(via
		(at 101.517704 -57.57164)
		(size 0.508)
		(drill 0.254)
		(layers "F.Cu" "B.Cu")
		(net "PVDDQ_GHJ")
	)
	(via
		(at 15.621 -14.859)
		(size 0.508)
		(drill 0.254)
		(layers "F.Cu" "B.Cu")
		(net "PVDDQ_GHJ")
	)
	(via
		(at 20.160488 -3.78333)
		(size 0.508)
		(drill 0.254)
		(layers "F.Cu" "B.Cu")
		(net "PVDDQ_GHJ")
	)
	(via
		(at 101.949758 -16.718788)
		(size 0.4572)
		(drill 0.2032)
		(layers "F.Cu" "B.Cu")
		(net "PVDDQ_GHJ")
	)
	(via
		(at 15.621 -15.494)
		(size 0.508)
		(drill 0.254)
		(layers "F.Cu" "B.Cu")
		(net "PVDDQ_GHJ")
	)
	(via
		(at 112.149382 -23.495)
		(size 0.508)
		(drill 0.254)
		(layers "F.Cu" "B.Cu")
		(net "PVDDQ_GHJ")
	)
	(via
		(at 81.549494 -2.314956)
		(size 0.508)
		(drill 0.254)
		(layers "F.Cu" "B.Cu")
		(net "PVDDQ_GHJ")
	)
	(via
		(at 93.791278 -62.029086)
		(size 0.508)
		(drill 0.254)
		(layers "F.Cu" "B.Cu")
		(net "PVDDQ_GHJ")
	)
	(via
		(at 104.49941 2.485644)
		(size 0.508)
		(drill 0.254)
		(layers "F.Cu" "B.Cu")
		(net "PVDDQ_GHJ")
	)
	(via
		(at 86.64956 -9.133078)
		(size 0.508)
		(drill 0.254)
		(layers "F.Cu" "B.Cu")
		(net "PVDDQ_GHJ")
	)
	(via
		(at 99.800664 -51.62804)
		(size 0.508)
		(drill 0.254)
		(layers "F.Cu" "B.Cu")
		(net "PVDDQ_GHJ")
	)
	(via
		(at 86.64956 -18.734278)
		(size 0.508)
		(drill 0.254)
		(layers "F.Cu" "B.Cu")
		(net "PVDDQ_GHJ")
	)
	(via
		(at 104.499664 -7.117588)
		(size 0.4572)
		(drill 0.2032)
		(layers "F.Cu" "B.Cu")
		(net "PVDDQ_GHJ")
	)
	(via
		(at 169.1894 -2.54)
		(size 0.508)
		(drill 0.254)
		(layers "F.Cu" "B.Cu")
		(net "PVDDQ_GHJ")
	)
	(via
		(at 108.749846 -13.933678)
		(size 0.508)
		(drill 0.254)
		(layers "F.Cu" "B.Cu")
		(net "PVDDQ_GHJ")
	)
	(via
		(at 17.145 -11.049)
		(size 0.508)
		(drill 0.254)
		(layers "F.Cu" "B.Cu")
		(net "PVDDQ_GHJ")
	)
	(via
		(at 16.637 -17.907)
		(size 0.508)
		(drill 0.254)
		(layers "F.Cu" "B.Cu")
		(net "PVDDQ_GHJ")
	)
	(via
		(at 93.550994 -23.495)
		(size 0.508)
		(drill 0.254)
		(layers "F.Cu" "B.Cu")
		(net "PVDDQ_GHJ")
	)
	(via
		(at 84.0994 -11.916156)
		(size 0.508)
		(drill 0.254)
		(layers "F.Cu" "B.Cu")
		(net "PVDDQ_GHJ")
	)
	(via
		(at 102.766876 -67.284346)
		(size 0.5588)
		(drill 0.3048)
		(layers "F.Cu" "B.Cu")
		(net "PVDDQ_GHJ")
	)
	(via
		(at 79.849472 0.468122)
		(size 0.508)
		(drill 0.254)
		(layers "F.Cu" "B.Cu")
		(net "PVDDQ_GHJ")
	)
	(via
		(at 101.94925 -26.8732)
		(size 0.508)
		(drill 0.254)
		(layers "F.Cu" "B.Cu")
		(net "PVDDQ_GHJ")
	)
	(via
		(at 86.64956 0.442722)
		(size 0.508)
		(drill 0.254)
		(layers "F.Cu" "B.Cu")
		(net "PVDDQ_GHJ")
	)
	(via
		(at 90.899488 -11.916156)
		(size 0.508)
		(drill 0.254)
		(layers "F.Cu" "B.Cu")
		(net "PVDDQ_GHJ")
	)
	(via
		(at 97.225358 -51.132486)
		(size 0.508)
		(drill 0.254)
		(layers "F.Cu" "B.Cu")
		(net "PVDDQ_GHJ")
	)
	(via
		(at 105.96626 -67.284346)
		(size 0.5588)
		(drill 0.3048)
		(layers "F.Cu" "B.Cu")
		(net "PVDDQ_GHJ")
	)
	(via
		(at 18.669 -11.049)
		(size 0.508)
		(drill 0.254)
		(layers "F.Cu" "B.Cu")
		(net "PVDDQ_GHJ")
	)
	(via
		(at 20.743926 -2.970022)
		(size 0.508)
		(drill 0.254)
		(layers "F.Cu" "B.Cu")
		(net "PVDDQ_GHJ")
	)
	(via
		(at 84.0994 1.152144)
		(size 0.508)
		(drill 0.254)
		(layers "F.Cu" "B.Cu")
		(net "PVDDQ_GHJ")
	)
	(via
		(at 19.431 -12.573)
		(size 0.508)
		(drill 0.254)
		(layers "F.Cu" "B.Cu")
		(net "PVDDQ_GHJ")
	)
	(via
		(at 108.749846 -7.117588)
		(size 0.4572)
		(drill 0.2032)
		(layers "F.Cu" "B.Cu")
		(net "PVDDQ_GHJ")
	)
	(via
		(at 109.599476 -18.730468)
		(size 0.508)
		(drill 0.254)
		(layers "F.Cu" "B.Cu")
		(net "PVDDQ_GHJ")
	)
	(via
		(at 98.942398 -59.057286)
		(size 0.508)
		(drill 0.254)
		(layers "F.Cu" "B.Cu")
		(net "PVDDQ_GHJ")
	)
	(via
		(at 96.366838 -57.57164)
		(size 0.508)
		(drill 0.254)
		(layers "F.Cu" "B.Cu")
		(net "PVDDQ_GHJ")
	)
	(via
		(at 89.199466 -9.133078)
		(size 0.508)
		(drill 0.254)
		(layers "F.Cu" "B.Cu")
		(net "PVDDQ_GHJ")
	)
	(via
		(at 84.0994 -2.314956)
		(size 0.508)
		(drill 0.254)
		(layers "F.Cu" "B.Cu")
		(net "PVDDQ_GHJ")
	)
	(via
		(at 94.649798 -54.59984)
		(size 0.508)
		(drill 0.254)
		(layers "F.Cu" "B.Cu")
		(net "PVDDQ_GHJ")
	)
	(via
		(at 18.034 -6.601968)
		(size 0.508)
		(drill 0.254)
		(layers "F.Cu" "B.Cu")
		(net "PVDDQ_GHJ")
	)
	(via
		(at 106.199432 -11.914378)
		(size 0.508)
		(drill 0.254)
		(layers "F.Cu" "B.Cu")
		(net "PVDDQ_GHJ")
	)
	(via
		(at 80.699356 -4.332478)
		(size 0.508)
		(drill 0.254)
		(layers "F.Cu" "B.Cu")
		(net "PVDDQ_GHJ")
	)
	(via
		(at 109.599476 -9.129268)
		(size 0.508)
		(drill 0.254)
		(layers "F.Cu" "B.Cu")
		(net "PVDDQ_GHJ")
	)
	(via
		(at 85.799422 -16.716756)
		(size 0.508)
		(drill 0.254)
		(layers "F.Cu" "B.Cu")
		(net "PVDDQ_GHJ")
	)
	(via
		(at 103.557324 -61.038486)
		(size 0.508)
		(drill 0.254)
		(layers "F.Cu" "B.Cu")
		(net "PVDDQ_GHJ")
	)
	(via
		(at 80.699356 -16.716756)
		(size 0.508)
		(drill 0.254)
		(layers "F.Cu" "B.Cu")
		(net "PVDDQ_GHJ")
	)
	(via
		(at 106.199432 -4.328668)
		(size 0.508)
		(drill 0.254)
		(layers "F.Cu" "B.Cu")
		(net "PVDDQ_GHJ")
	)
	(via
		(at 81.549494 -18.734278)
		(size 0.508)
		(drill 0.254)
		(layers "F.Cu" "B.Cu")
		(net "PVDDQ_GHJ")
	)
	(via
		(at 105.36428 -26.8732)
		(size 0.508)
		(drill 0.254)
		(layers "F.Cu" "B.Cu")
		(net "PVDDQ_GHJ")
	)
	(via
		(at 20.25015 -19.302222)
		(size 0.508)
		(drill 0.254)
		(layers "F.Cu" "B.Cu")
		(net "PVDDQ_GHJ")
	)
	(via
		(at 88.640412 -59.057286)
		(size 0.508)
		(drill 0.254)
		(layers "F.Cu" "B.Cu")
		(net "PVDDQ_GHJ")
	)
	(via
		(at 17.145 -12.573)
		(size 0.508)
		(drill 0.254)
		(layers "F.Cu" "B.Cu")
		(net "PVDDQ_GHJ")
	)
	(via
		(at 15.621 -14.224)
		(size 0.508)
		(drill 0.254)
		(layers "F.Cu" "B.Cu")
		(net "PVDDQ_GHJ")
	)
	(via
		(at 16.383 -11.811)
		(size 0.508)
		(drill 0.254)
		(layers "F.Cu" "B.Cu")
		(net "PVDDQ_GHJ")
	)
	(via
		(at 17.907 -17.907)
		(size 0.508)
		(drill 0.254)
		(layers "F.Cu" "B.Cu")
		(net "PVDDQ_GHJ")
	)
	(via
		(at 168.4782 -2.54)
		(size 0.508)
		(drill 0.254)
		(layers "F.Cu" "B.Cu")
		(net "PVDDQ_GHJ")
	)
	(via
		(at 106.199432 -22.850856)
		(size 0.508)
		(drill 0.254)
		(layers "F.Cu" "B.Cu")
		(net "PVDDQ_GHJ")
	)
	(via
		(at 18.034 -7.239)
		(size 0.508)
		(drill 0.254)
		(layers "F.Cu" "B.Cu")
		(net "PVDDQ_GHJ")
	)
	(via
		(at 112.149382 0.468122)
		(size 0.508)
		(drill 0.254)
		(layers "F.Cu" "B.Cu")
		(net "PVDDQ_GHJ")
	)
	(via
		(at 14.986 -14.859)
		(size 0.508)
		(drill 0.254)
		(layers "F.Cu" "B.Cu")
		(net "PVDDQ_GHJ")
	)
	(via
		(at 98.083878 -52.618386)
		(size 0.508)
		(drill 0.254)
		(layers "F.Cu" "B.Cu")
		(net "PVDDQ_GHJ")
	)
	(via
		(at 107.899454 -11.914378)
		(size 0.508)
		(drill 0.254)
		(layers "F.Cu" "B.Cu")
		(net "PVDDQ_GHJ")
	)
	(via
		(at 91.056714 -18.663666)
		(size 0.508)
		(drill 0.254)
		(layers "F.Cu" "B.Cu")
		(net "PVDDQ_GHJ")
	)
	(via
		(at 20.193 -12.573)
		(size 0.508)
		(drill 0.254)
		(layers "F.Cu" "B.Cu")
		(net "PVDDQ_GHJ")
	)
	(via
		(at 18.669 -12.573)
		(size 0.508)
		(drill 0.254)
		(layers "F.Cu" "B.Cu")
		(net "PVDDQ_GHJ")
	)
	(via
		(at 17.145 -11.811)
		(size 0.508)
		(drill 0.254)
		(layers "F.Cu" "B.Cu")
		(net "PVDDQ_GHJ")
	)
	(via
		(at 18.669 -11.811)
		(size 0.508)
		(drill 0.254)
		(layers "F.Cu" "B.Cu")
		(net "PVDDQ_GHJ")
	)
	(via
		(at 108.749338 -23.495)
		(size 0.508)
		(drill 0.254)
		(layers "F.Cu" "B.Cu")
		(net "PVDDQ_GHJ")
	)
	(via
		(at 108.749846 -4.332478)
		(size 0.508)
		(drill 0.254)
		(layers "F.Cu" "B.Cu")
		(net "PVDDQ_GHJ")
	)
	(via
		(at 107.899454 -2.313178)
		(size 0.508)
		(drill 0.254)
		(layers "F.Cu" "B.Cu")
		(net "PVDDQ_GHJ")
	)
	(via
		(at 101.099366 -9.129268)
		(size 0.508)
		(drill 0.254)
		(layers "F.Cu" "B.Cu")
		(net "PVDDQ_GHJ")
	)
	(via
		(at 93.449394 -7.115556)
		(size 0.508)
		(drill 0.254)
		(layers "F.Cu" "B.Cu")
		(net "PVDDQ_GHJ")
	)
	(via
		(at 20.32 -6.604)
		(size 0.508)
		(drill 0.254)
		(layers "F.Cu" "B.Cu")
		(net "PVDDQ_GHJ")
	)
	(via
		(at 81.549494 -9.133078)
		(size 0.508)
		(drill 0.254)
		(layers "F.Cu" "B.Cu")
		(net "PVDDQ_GHJ")
	)
	(via
		(at 101.099366 1.152144)
		(size 0.508)
		(drill 0.254)
		(layers "F.Cu" "B.Cu")
		(net "PVDDQ_GHJ")
	)
	(via
		(at 99.796092 -49.540414)
		(size 0.508)
		(drill 0.254)
		(layers "F.Cu" "B.Cu")
		(net "PVDDQ_GHJ")
	)
	(via
		(at 15.367 -19.431)
		(size 0.508)
		(drill 0.254)
		(layers "F.Cu" "B.Cu")
		(net "PVDDQ_GHJ")
	)
	(via
		(at 94.649798 -57.57164)
		(size 0.508)
		(drill 0.254)
		(layers "F.Cu" "B.Cu")
		(net "PVDDQ_GHJ")
	)
	(via
		(at 90.357198 -52.12334)
		(size 0.508)
		(drill 0.254)
		(layers "F.Cu" "B.Cu")
		(net "PVDDQ_GHJ")
	)
	(via
		(at 89.199466 1.152144)
		(size 0.508)
		(drill 0.254)
		(layers "F.Cu" "B.Cu")
		(net "PVDDQ_GHJ")
	)
	(via
		(at 19.177 -17.907)
		(size 0.508)
		(drill 0.254)
		(layers "F.Cu" "B.Cu")
		(net "PVDDQ_GHJ")
	)
	(via
		(at 101.949758 -7.117588)
		(size 0.4572)
		(drill 0.2032)
		(layers "F.Cu" "B.Cu")
		(net "PVDDQ_GHJ")
	)
	(via
		(at 92.074238 -52.12334)
		(size 0.508)
		(drill 0.254)
		(layers "F.Cu" "B.Cu")
		(net "PVDDQ_GHJ")
	)
	(via
		(at 78.999334 -16.716756)
		(size 0.508)
		(drill 0.254)
		(layers "F.Cu" "B.Cu")
		(net "PVDDQ_GHJ")
	)
	(via
		(at 84.0994 -21.517356)
		(size 0.508)
		(drill 0.254)
		(layers "F.Cu" "B.Cu")
		(net "PVDDQ_GHJ")
	)
	(via
		(at 28.976828 -13.9954)
		(size 0.508)
		(drill 0.254)
		(layers "F.Cu" "B.Cu")
		(net "PVDDQ_GHJ")
	)
	(via
		(at 20.831302 -3.588766)
		(size 0.508)
		(drill 0.254)
		(layers "F.Cu" "B.Cu")
		(net "PVDDQ_GHJ")
	)
	(via
		(at 106.199432 1.152144)
		(size 0.508)
		(drill 0.254)
		(layers "F.Cu" "B.Cu")
		(net "PVDDQ_GHJ")
	)
	(via
		(at 104.441752 -67.284346)
		(size 0.5588)
		(drill 0.3048)
		(layers "F.Cu" "B.Cu")
		(net "PVDDQ_GHJ")
	)
	(via
		(at 18.796 -6.601968)
		(size 0.508)
		(drill 0.254)
		(layers "F.Cu" "B.Cu")
		(net "PVDDQ_GHJ")
	)
	(via
		(at 107.899454 1.152144)
		(size 0.508)
		(drill 0.254)
		(layers "F.Cu" "B.Cu")
		(net "PVDDQ_GHJ")
	)
	(via
		(at 2.282952 -14.799818)
		(size 0.508)
		(drill 0.254)
		(layers "F.Cu" "B.Cu")
		(net "PVDDQ_GHJ")
	)
	(via
		(at 164.461698 -71.198232)
		(size 0.508)
		(drill 0.254)
		(layers "F.Cu" "B.Cu")
		(net "PVDDQ_GHJ")
	)
	(via
		(at 90.92311 -23.495)
		(size 0.508)
		(drill 0.254)
		(layers "F.Cu" "B.Cu")
		(net "PVDDQ_GHJ")
	)
	(via
		(at 83.249516 -4.332478)
		(size 0.508)
		(drill 0.254)
		(layers "F.Cu" "B.Cu")
		(net "PVDDQ_GHJ")
	)
	(via
		(at 110.44936 -23.495)
		(size 0.508)
		(drill 0.254)
		(layers "F.Cu" "B.Cu")
		(net "PVDDQ_GHJ")
	)
	(via
		(at 15.621 -12.573)
		(size 0.508)
		(drill 0.254)
		(layers "F.Cu" "B.Cu")
		(net "PVDDQ_GHJ")
	)
	(via
		(at 19.431 -11.049)
		(size 0.508)
		(drill 0.254)
		(layers "F.Cu" "B.Cu")
		(net "PVDDQ_GHJ")
	)
	(via
		(at 103.649526 -18.730468)
		(size 0.508)
		(drill 0.254)
		(layers "F.Cu" "B.Cu")
		(net "PVDDQ_GHJ")
	)
	(via
		(at 15.367 -18.796)
		(size 0.508)
		(drill 0.254)
		(layers "F.Cu" "B.Cu")
		(net "PVDDQ_GHJ")
	)
	(via
		(at 93.406468 -18.6563)
		(size 0.508)
		(drill 0.254)
		(layers "F.Cu" "B.Cu")
		(net "PVDDQ_GHJ")
	)
	(via
		(at 14.986 -12.573)
		(size 0.508)
		(drill 0.254)
		(layers "F.Cu" "B.Cu")
		(net "PVDDQ_GHJ")
	)
	(via
		(at 86.64956 -22.197568)
		(size 0.508)
		(drill 0.254)
		(layers "F.Cu" "B.Cu")
		(net "PVDDQ_GHJ")
	)
	(via
		(at 90.928698 -49.150778)
		(size 0.508)
		(drill 0.254)
		(layers "F.Cu" "B.Cu")
		(net "PVDDQ_GHJ")
	)
	(via
		(at 85.799422 -22.850856)
		(size 0.508)
		(drill 0.254)
		(layers "F.Cu" "B.Cu")
		(net "PVDDQ_GHJ")
	)
	(via
		(at 112.149382 -2.313178)
		(size 0.508)
		(drill 0.254)
		(layers "F.Cu" "B.Cu")
		(net "PVDDQ_GHJ")
	)
	(via
		(at 112.149382 -7.113778)
		(size 0.508)
		(drill 0.254)
		(layers "F.Cu" "B.Cu")
		(net "PVDDQ_GHJ")
	)
	(via
		(at 20.193 -11.049)
		(size 0.508)
		(drill 0.254)
		(layers "F.Cu" "B.Cu")
		(net "PVDDQ_GHJ")
	)
	(via
		(at 90.357198 -59.057286)
		(size 0.508)
		(drill 0.254)
		(layers "F.Cu" "B.Cu")
		(net "PVDDQ_GHJ")
	)
	(via
		(at 78.999334 2.485644)
		(size 0.508)
		(drill 0.254)
		(layers "F.Cu" "B.Cu")
		(net "PVDDQ_GHJ")
	)
	(via
		(at 88.349582 -4.332478)
		(size 0.508)
		(drill 0.254)
		(layers "F.Cu" "B.Cu")
		(net "PVDDQ_GHJ")
	)
	(via
		(at 90.899488 0.471932)
		(size 0.508)
		(drill 0.254)
		(layers "F.Cu" "B.Cu")
		(net "PVDDQ_GHJ")
	)
	(via
		(at 109.5756 -21.5392)
		(size 0.508)
		(drill 0.254)
		(layers "F.Cu" "B.Cu")
		(net "PVDDQ_GHJ")
	)
	(via
		(at 85.799422 -13.933678)
		(size 0.508)
		(drill 0.254)
		(layers "F.Cu" "B.Cu")
		(net "PVDDQ_GHJ")
	)
	(via
		(at 90.899488 2.485644)
		(size 0.508)
		(drill 0.254)
		(layers "F.Cu" "B.Cu")
		(net "PVDDQ_GHJ")
	)
	(via
		(at 16.002 -19.431)
		(size 0.508)
		(drill 0.254)
		(layers "F.Cu" "B.Cu")
		(net "PVDDQ_GHJ")
	)
	(via
		(at 19.812 -17.907)
		(size 0.508)
		(drill 0.254)
		(layers "F.Cu" "B.Cu")
		(net "PVDDQ_GHJ")
	)
	(via
		(at 166.0652 -5.7912)
		(size 0.508)
		(drill 0.254)
		(layers "F.Cu" "B.Cu")
		(net "PVDDQ_GHJ")
	)
	(via
		(at 106.199432 -16.714978)
		(size 0.508)
		(drill 0.254)
		(layers "F.Cu" "B.Cu")
		(net "PVDDQ_GHJ")
	)
	(via
		(at 90.848688 -2.314956)
		(size 0.508)
		(drill 0.254)
		(layers "F.Cu" "B.Cu")
		(net "PVDDQ_GHJ")
	)
	(via
		(at 17.272 -17.907)
		(size 0.508)
		(drill 0.254)
		(layers "F.Cu" "B.Cu")
		(net "PVDDQ_GHJ")
	)
	(via
		(at 93.449394 -2.314956)
		(size 0.508)
		(drill 0.254)
		(layers "F.Cu" "B.Cu")
		(net "PVDDQ_GHJ")
	)
	(via
		(at 112.149382 -9.129268)
		(size 0.508)
		(drill 0.254)
		(layers "F.Cu" "B.Cu")
		(net "PVDDQ_GHJ")
	)
	(via
		(at 80.699356 -13.933678)
		(size 0.508)
		(drill 0.254)
		(layers "F.Cu" "B.Cu")
		(net "PVDDQ_GHJ")
	)
	(via
		(at 89.199466 -2.316988)
		(size 0.508)
		(drill 0.254)
		(layers "F.Cu" "B.Cu")
		(net "PVDDQ_GHJ")
	)
	(via
		(at 108.181394 -67.23634)
		(size 0.5588)
		(drill 0.3048)
		(layers "F.Cu" "B.Cu")
		(net "PVDDQ_GHJ")
	)
	(via
		(at 112.149382 -22.197568)
		(size 0.508)
		(drill 0.254)
		(layers "F.Cu" "B.Cu")
		(net "PVDDQ_GHJ")
	)
	(via
		(at 101.099366 -11.914378)
		(size 0.508)
		(drill 0.254)
		(layers "F.Cu" "B.Cu")
		(net "PVDDQ_GHJ")
	)
	(via
		(at 89.199466 -18.734278)
		(size 0.508)
		(drill 0.254)
		(layers "F.Cu" "B.Cu")
		(net "PVDDQ_GHJ")
	)
	(via
		(at 107.061762 -26.8732)
		(size 0.508)
		(drill 0.254)
		(layers "F.Cu" "B.Cu")
		(net "PVDDQ_GHJ")
	)
	(via
		(at 79.849472 -9.133078)
		(size 0.508)
		(drill 0.254)
		(layers "F.Cu" "B.Cu")
		(net "PVDDQ_GHJ")
	)
	(via
		(at 112.149382 -11.914378)
		(size 0.508)
		(drill 0.254)
		(layers "F.Cu" "B.Cu")
		(net "PVDDQ_GHJ")
	)
	(via
		(at 106.199432 -21.488146)
		(size 0.508)
		(drill 0.254)
		(layers "F.Cu" "B.Cu")
		(net "PVDDQ_GHJ")
	)
	(via
		(at 83.249516 -13.933678)
		(size 0.508)
		(drill 0.254)
		(layers "F.Cu" "B.Cu")
		(net "PVDDQ_GHJ")
	)
	(via
		(at 86.64956 -2.316988)
		(size 0.508)
		(drill 0.254)
		(layers "F.Cu" "B.Cu")
		(net "PVDDQ_GHJ")
	)
	(via
		(at 89.199466 -21.488146)
		(size 0.508)
		(drill 0.254)
		(layers "F.Cu" "B.Cu")
		(net "PVDDQ_GHJ")
	)
	(via
		(at 100.659184 -59.057286)
		(size 0.508)
		(drill 0.254)
		(layers "F.Cu" "B.Cu")
		(net "PVDDQ_GHJ")
	)
	(via
		(at 16.002 -20.066)
		(size 0.508)
		(drill 0.254)
		(layers "F.Cu" "B.Cu")
		(net "PVDDQ_GHJ")
	)
	(via
		(at 87.781892 -54.59984)
		(size 0.508)
		(drill 0.254)
		(layers "F.Cu" "B.Cu")
		(net "PVDDQ_GHJ")
	)
	(via
		(at 15.113 -7.239)
		(size 0.508)
		(drill 0.254)
		(layers "F.Cu" "B.Cu")
		(net "PVDDQ_GHJ")
	)
	(via
		(at 91.215718 -57.57164)
		(size 0.508)
		(drill 0.254)
		(layers "F.Cu" "B.Cu")
		(net "PVDDQ_GHJ")
	)
	(via
		(at 93.215968 -16.7513)
		(size 0.508)
		(drill 0.254)
		(layers "F.Cu" "B.Cu")
		(net "PVDDQ_GHJ")
	)
	(via
		(at 166.7002 -5.7912)
		(size 0.508)
		(drill 0.254)
		(layers "F.Cu" "B.Cu")
		(net "PVDDQ_GHJ")
	)
	(via
		(at 90.899488 -4.321556)
		(size 0.508)
		(drill 0.254)
		(layers "F.Cu" "B.Cu")
		(net "PVDDQ_GHJ")
	)
	(via
		(at 79.849472 -2.314956)
		(size 0.508)
		(drill 0.254)
		(layers "F.Cu" "B.Cu")
		(net "PVDDQ_GHJ")
	)
	(via
		(at 19.558 -6.601968)
		(size 0.508)
		(drill 0.254)
		(layers "F.Cu" "B.Cu")
		(net "PVDDQ_GHJ")
	)
	(via
		(at 14.986 -15.494)
		(size 0.508)
		(drill 0.254)
		(layers "F.Cu" "B.Cu")
		(net "PVDDQ_GHJ")
	)
	(via
		(at 106.199432 -2.313178)
		(size 0.508)
		(drill 0.254)
		(layers "F.Cu" "B.Cu")
		(net "PVDDQ_GHJ")
	)
	(via
		(at 104.499664 -4.332478)
		(size 0.508)
		(drill 0.254)
		(layers "F.Cu" "B.Cu")
		(net "PVDDQ_GHJ")
	)
	(via
		(at 16.002 -20.701)
		(size 0.508)
		(drill 0.254)
		(layers "F.Cu" "B.Cu")
		(net "PVDDQ_GHJ")
	)
	(via
		(at 14.986 -11.811)
		(size 0.508)
		(drill 0.254)
		(layers "F.Cu" "B.Cu")
		(net "PVDDQ_GHJ")
	)
	(via
		(at 90.899488 -22.225)
		(size 0.508)
		(drill 0.254)
		(layers "F.Cu" "B.Cu")
		(net "PVDDQ_GHJ")
	)
	(via
		(at 101.517704 -54.59984)
		(size 0.508)
		(drill 0.254)
		(layers "F.Cu" "B.Cu")
		(net "PVDDQ_GHJ")
	)
	(via
		(at 93.449394 2.485644)
		(size 0.508)
		(drill 0.254)
		(layers "F.Cu" "B.Cu")
		(net "PVDDQ_GHJ")
	)
	(via
		(at 85.799422 -7.115556)
		(size 0.508)
		(drill 0.254)
		(layers "F.Cu" "B.Cu")
		(net "PVDDQ_GHJ")
	)
	(via
		(at 103.557324 -59.057286)
		(size 0.508)
		(drill 0.254)
		(layers "F.Cu" "B.Cu")
		(net "PVDDQ_GHJ")
	)
	(via
		(at 101.099366 -18.730468)
		(size 0.508)
		(drill 0.254)
		(layers "F.Cu" "B.Cu")
		(net "PVDDQ_GHJ")
	)
	(via
		(at 168.579546 -0.980694)
		(size 0.508)
		(drill 0.254)
		(layers "F.Cu" "B.Cu")
		(net "PVDDQ_GHJ")
	)
	(via
		(at 103.649526 -2.313178)
		(size 0.508)
		(drill 0.254)
		(layers "F.Cu" "B.Cu")
		(net "PVDDQ_GHJ")
	)
	(via
		(at 100.049076 -67.284346)
		(size 0.508)
		(drill 0.254)
		(layers "F.Cu" "B.Cu")
		(net "PVDDQ_GHJ")
	)
	(via
		(at 106.199432 -7.113778)
		(size 0.508)
		(drill 0.254)
		(layers "F.Cu" "B.Cu")
		(net "PVDDQ_GHJ")
	)
	(via
		(at 103.528876 -67.284346)
		(size 0.5588)
		(drill 0.3048)
		(layers "F.Cu" "B.Cu")
		(net "PVDDQ_GHJ")
	)
	(via
		(at 103.649272 -22.197568)
		(size 0.508)
		(drill 0.254)
		(layers "F.Cu" "B.Cu")
		(net "PVDDQ_GHJ")
	)
	(via
		(at 91.215718 -54.59984)
		(size 0.508)
		(drill 0.254)
		(layers "F.Cu" "B.Cu")
		(net "PVDDQ_GHJ")
	)
	(via
		(at 86.064852 -55.59044)
		(size 0.508)
		(drill 0.254)
		(layers "F.Cu" "B.Cu")
		(net "PVDDQ_GHJ")
	)
	(via
		(at 106.199432 2.464054)
		(size 0.508)
		(drill 0.254)
		(layers "F.Cu" "B.Cu")
		(net "PVDDQ_GHJ")
	)
	(via
		(at 101.949504 -4.328668)
		(size 0.508)
		(drill 0.254)
		(layers "F.Cu" "B.Cu")
		(net "PVDDQ_GHJ")
	)
	(via
		(at 16.383 -11.049)
		(size 0.508)
		(drill 0.254)
		(layers "F.Cu" "B.Cu")
		(net "PVDDQ_GHJ")
	)
	(via
		(at 16.002 -17.907)
		(size 0.508)
		(drill 0.254)
		(layers "F.Cu" "B.Cu")
		(net "PVDDQ_GHJ")
	)
	(via
		(at 99.800664 -57.57164)
		(size 0.508)
		(drill 0.254)
		(layers "F.Cu" "B.Cu")
		(net "PVDDQ_GHJ")
	)
	(via
		(at 81.549494 0.442722)
		(size 0.508)
		(drill 0.254)
		(layers "F.Cu" "B.Cu")
		(net "PVDDQ_GHJ")
	)
	(via
		(at 110.449868 -16.718788)
		(size 0.4572)
		(drill 0.2032)
		(layers "F.Cu" "B.Cu")
		(net "PVDDQ_GHJ")
	)
	(via
		(at 103.649526 -11.914378)
		(size 0.508)
		(drill 0.254)
		(layers "F.Cu" "B.Cu")
		(net "PVDDQ_GHJ")
	)
	(via
		(at 15.748 -7.239)
		(size 0.508)
		(drill 0.254)
		(layers "F.Cu" "B.Cu")
		(net "PVDDQ_GHJ")
	)
	(via
		(at 88.349582 -23.560278)
		(size 0.508)
		(drill 0.254)
		(layers "F.Cu" "B.Cu")
		(net "PVDDQ_GHJ")
	)
	(via
		(at 20.574 -15.621)
		(size 0.508)
		(drill 0.254)
		(layers "F.Cu" "B.Cu")
		(net "PVDDQ_GHJ")
	)
	(via
		(at 93.449394 -4.328668)
		(size 0.508)
		(drill 0.254)
		(layers "F.Cu" "B.Cu")
		(net "PVDDQ_GHJ")
	)
	(via
		(at 98.083878 -54.59984)
		(size 0.508)
		(drill 0.254)
		(layers "F.Cu" "B.Cu")
		(net "PVDDQ_GHJ")
	)
	(via
		(at 103.649526 -9.129268)
		(size 0.508)
		(drill 0.254)
		(layers "F.Cu" "B.Cu")
		(net "PVDDQ_GHJ")
	)
	(via
		(at 101.099366 -2.313178)
		(size 0.508)
		(drill 0.254)
		(layers "F.Cu" "B.Cu")
		(net "PVDDQ_GHJ")
	)
	(via
		(at 78.999334 -13.933678)
		(size 0.508)
		(drill 0.254)
		(layers "F.Cu" "B.Cu")
		(net "PVDDQ_GHJ")
	)
	(via
		(at 17.907 -12.573)
		(size 0.508)
		(drill 0.254)
		(layers "F.Cu" "B.Cu")
		(net "PVDDQ_GHJ")
	)
	(segment
		(start 93.449394 -5.621782)
		(end 93.449394 -4.328668)
		(width 0.4064)
		(layer "B.Cu")
		(net "PVDDQ_GHJ")
	)
	(segment
		(start 101.949504 -15.222982)
		(end 101.949504 -16.718534)
		(width 0.4064)
		(layer "B.Cu")
		(net "PVDDQ_GHJ")
	)
	(segment
		(start 108.749338 3.49377)
		(end 108.749338 1.805432)
		(width 0.508)
		(layer "B.Cu")
		(net "PVDDQ_GHJ")
	)
	(segment
		(start 90.899488 -20.224242)
		(end 90.899488 -22.225)
		(width 0.4064)
		(layer "B.Cu")
		(net "PVDDQ_GHJ")
	)
	(segment
		(start 90.899488 -15.222982)
		(end 90.899488 -14.119352)
		(width 0.4064)
		(layer "B.Cu")
		(net "PVDDQ_GHJ")
	)
	(segment
		(start 112.149382 -15.222982)
		(end 112.149382 -16.714978)
		(width 0.4064)
		(layer "B.Cu")
		(net "PVDDQ_GHJ")
	)
	(segment
		(start 175.895 -4.169156)
		(end 175.488346 -4.57581)
		(width 0.4064)
		(layer "B.Cu")
		(net "PVDDQ_GHJ")
	)
	(segment
		(start 85.799422 -7.115556)
		(end 85.799422 -5.621782)
		(width 0.4064)
		(layer "B.Cu")
		(net "PVDDQ_GHJ")
	)
	(segment
		(start 108.749338 -4.332986)
		(end 108.749338 -5.621782)
		(width 0.4064)
		(layer "B.Cu")
		(net "PVDDQ_GHJ")
	)
	(segment
		(start 102.080568 2.786888)
		(end 102.080568 3.81)
		(width 0.508)
		(layer "B.Cu")
		(net "PVDDQ_GHJ")
	)
	(segment
		(start 106.199432 -5.621782)
		(end 106.199432 -7.113778)
		(width 0.4064)
		(layer "B.Cu")
		(net "PVDDQ_GHJ")
	)
	(segment
		(start 104.499664 -13.959078)
		(end 104.49941 -13.959332)
		(width 0.4064)
		(layer "B.Cu")
		(net "PVDDQ_GHJ")
	)
	(segment
		(start 101.099366 -20.224242)
		(end 101.099366 -18.730468)
		(width 0.4064)
		(layer "B.Cu")
		(net "PVDDQ_GHJ")
	)
	(segment
		(start 101.949504 -13.929868)
		(end 101.949504 -15.222982)
		(width 0.4064)
		(layer "B.Cu")
		(net "PVDDQ_GHJ")
	)
	(segment
		(start 93.449394 0.471932)
		(end 93.449394 -1.021842)
		(width 0.4064)
		(layer "B.Cu")
		(net "PVDDQ_GHJ")
	)
	(segment
		(start 80.699356 -4.332478)
		(end 80.699356 -5.621782)
		(width 0.4064)
		(layer "B.Cu")
		(net "PVDDQ_GHJ")
	)
	(segment
		(start 89.199466 -20.224242)
		(end 89.199466 -18.734278)
		(width 0.4064)
		(layer "B.Cu")
		(net "PVDDQ_GHJ")
	)
	(segment
		(start 101.949504 -16.718534)
		(end 101.949758 -16.718788)
		(width 0.4064)
		(layer "B.Cu")
		(net "PVDDQ_GHJ")
	)
	(segment
		(start 79.849472 -22.197568)
		(end 79.849472 -20.224242)
		(width 0.4064)
		(layer "B.Cu")
		(net "PVDDQ_GHJ")
	)
	(segment
		(start 81.549494 -1.021842)
		(end 81.549494 -2.314956)
		(width 0.4064)
		(layer "B.Cu")
		(net "PVDDQ_GHJ")
	)
	(segment
		(start 107.899454 -10.623042)
		(end 107.899454 -9.129268)
		(width 0.4064)
		(layer "B.Cu")
		(net "PVDDQ_GHJ")
	)
	(segment
		(start 80.699356 -22.850856)
		(end 80.699356 -24.824182)
		(width 0.4064)
		(layer "B.Cu")
		(net "PVDDQ_GHJ")
	)
	(segment
		(start 90.899488 0.471932)
		(end 90.899488 -1.021842)
		(width 0.4064)
		(layer "B.Cu")
		(net "PVDDQ_GHJ")
	)
	(segment
		(start 107.899454 -11.914378)
		(end 107.899454 -10.623042)
		(width 0.4064)
		(layer "B.Cu")
		(net "PVDDQ_GHJ")
	)
	(segment
		(start 90.899488 -18.820892)
		(end 90.899488 -20.224242)
		(width 0.4064)
		(layer "B.Cu")
		(net "PVDDQ_GHJ")
	)
	(segment
		(start 110.449868 -16.718788)
		(end 110.44936 -16.71828)
		(width 0.4064)
		(layer "B.Cu")
		(net "PVDDQ_GHJ")
	)
	(segment
		(start 112.149382 -5.621782)
		(end 112.149382 -4.328668)
		(width 0.4064)
		(layer "B.Cu")
		(net "PVDDQ_GHJ")
	)
	(segment
		(start 81.549494 -10.623042)
		(end 81.549494 -11.916156)
		(width 0.4064)
		(layer "B.Cu")
		(net "PVDDQ_GHJ")
	)
	(segment
		(start 90.899488 -14.119352)
		(end 91.088972 -13.929868)
		(width 0.4064)
		(layer "B.Cu")
		(net "PVDDQ_GHJ")
	)
	(segment
		(start 81.549494 0.442722)
		(end 81.549494 -1.021842)
		(width 0.4064)
		(layer "B.Cu")
		(net "PVDDQ_GHJ")
	)
	(segment
		(start 106.199432 -15.222982)
		(end 106.199432 -13.929868)
		(width 0.4064)
		(layer "B.Cu")
		(net "PVDDQ_GHJ")
	)
	(segment
		(start 83.249516 -23.560278)
		(end 83.249516 -24.824182)
		(width 0.4064)
		(layer "B.Cu")
		(net "PVDDQ_GHJ")
	)
	(segment
		(start 86.64956 -1.021842)
		(end 86.64956 -2.316988)
		(width 0.4064)
		(layer "B.Cu")
		(net "PVDDQ_GHJ")
	)
	(segment
		(start 90.899488 -23.546816)
		(end 90.899488 -24.824182)
		(width 0.4064)
		(layer "B.Cu")
		(net "PVDDQ_GHJ")
	)
	(segment
		(start 108.749338 -13.934186)
		(end 108.749338 -15.222982)
		(width 0.4064)
		(layer "B.Cu")
		(net "PVDDQ_GHJ")
	)
	(segment
		(start 103.649526 -22.197314)
		(end 103.649526 -20.224242)
		(width 0.4064)
		(layer "B.Cu")
		(net "PVDDQ_GHJ")
	)
	(segment
		(start 104.49941 -13.959332)
		(end 104.49941 -15.222982)
		(width 0.4064)
		(layer "B.Cu")
		(net "PVDDQ_GHJ")
	)
	(segment
		(start 93.449394 -7.115556)
		(end 93.449394 -5.621782)
		(width 0.4064)
		(layer "B.Cu")
		(net "PVDDQ_GHJ")
	)
	(segment
		(start 84.0994 -10.623042)
		(end 84.0994 -9.133078)
		(width 0.4064)
		(layer "B.Cu")
		(net "PVDDQ_GHJ")
	)
	(segment
		(start 85.799422 -15.222982)
		(end 85.799422 -13.933678)
		(width 0.4064)
		(layer "B.Cu")
		(net "PVDDQ_GHJ")
	)
	(segment
		(start 78.999334 -15.222982)
		(end 78.999334 -16.716756)
		(width 0.4064)
		(layer "B.Cu")
		(net "PVDDQ_GHJ")
	)
	(segment
		(start 106.199432 -4.328668)
		(end 106.199432 -5.621782)
		(width 0.4064)
		(layer "B.Cu")
		(net "PVDDQ_GHJ")
	)
	(segment
		(start 86.64956 -11.918188)
		(end 86.64956 -10.623042)
		(width 0.4064)
		(layer "B.Cu")
		(net "PVDDQ_GHJ")
	)
	(segment
		(start 78.999334 -13.933678)
		(end 78.999334 -15.222982)
		(width 0.4064)
		(layer "B.Cu")
		(net "PVDDQ_GHJ")
	)
	(segment
		(start 104.49941 -4.332732)
		(end 104.49941 -5.621782)
		(width 0.4064)
		(layer "B.Cu")
		(net "PVDDQ_GHJ")
	)
	(segment
		(start 101.099366 -21.5392)
		(end 101.099366 -20.224242)
		(width 0.4064)
		(layer "B.Cu")
		(net "PVDDQ_GHJ")
	)
	(segment
		(start 110.449868 -4.332478)
		(end 110.44936 -4.332986)
		(width 0.4064)
		(layer "B.Cu")
		(net "PVDDQ_GHJ")
	)
	(segment
		(start 109.065568 3.81)
		(end 108.749338 3.49377)
		(width 0.508)
		(layer "B.Cu")
		(net "PVDDQ_GHJ")
	)
	(segment
		(start 84.0994 -20.224242)
		(end 84.0994 -21.517356)
		(width 0.4064)
		(layer "B.Cu")
		(net "PVDDQ_GHJ")
	)
	(segment
		(start 109.599476 -10.623042)
		(end 109.599476 -9.129268)
		(width 0.4064)
		(layer "B.Cu")
		(net "PVDDQ_GHJ")
	)
	(segment
		(start 112.149382 -15.222982)
		(end 112.149382 -13.929868)
		(width 0.4064)
		(layer "B.Cu")
		(net "PVDDQ_GHJ")
	)
	(segment
		(start 110.44936 -16.71828)
		(end 110.44936 -15.222982)
		(width 0.4064)
		(layer "B.Cu")
		(net "PVDDQ_GHJ")
	)
	(segment
		(start 106.199432 -10.623042)
		(end 106.199432 -9.129268)
		(width 0.4064)
		(layer "B.Cu")
		(net "PVDDQ_GHJ")
	)
	(segment
		(start 108.749846 -4.332478)
		(end 108.749338 -4.332986)
		(width 0.4064)
		(layer "B.Cu")
		(net "PVDDQ_GHJ")
	)
	(segment
		(start 79.849472 -10.623042)
		(end 79.849472 -9.133078)
		(width 0.4064)
		(layer "B.Cu")
		(net "PVDDQ_GHJ")
	)
	(segment
		(start 110.44936 -13.934186)
		(end 110.44936 -15.222982)
		(width 0.4064)
		(layer "B.Cu")
		(net "PVDDQ_GHJ")
	)
	(segment
		(start 107.899454 -2.313178)
		(end 107.899454 -1.021842)
		(width 0.4064)
		(layer "B.Cu")
		(net "PVDDQ_GHJ")
	)
	(segment
		(start 105.636568 3.026918)
		(end 106.199432 2.464054)
		(width 0.4064)
		(layer "B.Cu")
		(net "PVDDQ_GHJ")
	)
	(segment
		(start 101.099366 -10.623042)
		(end 101.099366 -9.129268)
		(width 0.4064)
		(layer "B.Cu")
		(net "PVDDQ_GHJ")
	)
	(segment
		(start 107.899454 -1.021842)
		(end 107.899454 1.152144)
		(width 0.4064)
		(layer "B.Cu")
		(net "PVDDQ_GHJ")
	)
	(segment
		(start 107.899454 -20.224242)
		(end 107.899454 -18.730468)
		(width 0.4064)
		(layer "B.Cu")
		(net "PVDDQ_GHJ")
	)
	(segment
		(start 83.249516 -7.115556)
		(end 83.249516 -5.621782)
		(width 0.4064)
		(layer "B.Cu")
		(net "PVDDQ_GHJ")
	)
	(segment
		(start 90.848688 -2.314956)
		(end 90.899488 -2.264156)
		(width 0.4064)
		(layer "B.Cu")
		(net "PVDDQ_GHJ")
	)
	(segment
		(start 81.549494 -18.734278)
		(end 81.549494 -20.224242)
		(width 0.4064)
		(layer "B.Cu")
		(net "PVDDQ_GHJ")
	)
	(segment
		(start 79.663798 -26.85415)
		(end 80.699356 -25.818592)
		(width 0.4064)
		(layer "B.Cu")
		(net "PVDDQ_GHJ")
	)
	(segment
		(start 112.149382 -20.224242)
		(end 112.149382 -22.197568)
		(width 0.4064)
		(layer "B.Cu")
		(net "PVDDQ_GHJ")
	)
	(segment
		(start 83.249516 -13.933678)
		(end 83.249516 -15.222982)
		(width 0.4064)
		(layer "B.Cu")
		(net "PVDDQ_GHJ")
	)
	(segment
		(start 104.49941 -24.824182)
		(end 104.49941 -22.850856)
		(width 0.4064)
		(layer "B.Cu")
		(net "PVDDQ_GHJ")
	)
	(segment
		(start 80.699356 -13.933678)
		(end 80.699356 -15.222982)
		(width 0.4064)
		(layer "B.Cu")
		(net "PVDDQ_GHJ")
	)
	(segment
		(start 78.999334 -24.824182)
		(end 78.999334 -22.850856)
		(width 0.4064)
		(layer "B.Cu")
		(net "PVDDQ_GHJ")
	)
	(segment
		(start 85.799422 -5.621782)
		(end 85.799422 -4.332478)
		(width 0.4064)
		(layer "B.Cu")
		(net "PVDDQ_GHJ")
	)
	(segment
		(start 109.599476 -11.914378)
		(end 109.599476 -10.623042)
		(width 0.4064)
		(layer "B.Cu")
		(net "PVDDQ_GHJ")
	)
	(segment
		(start 103.649526 -10.623042)
		(end 103.649526 -11.914378)
		(width 0.4064)
		(layer "B.Cu")
		(net "PVDDQ_GHJ")
	)
	(segment
		(start 103.649526 0.442468)
		(end 103.649272 0.442722)
		(width 0.4064)
		(layer "B.Cu")
		(net "PVDDQ_GHJ")
	)
	(segment
		(start 112.149382 -18.730468)
		(end 112.149382 -20.224242)
		(width 0.4064)
		(layer "B.Cu")
		(net "PVDDQ_GHJ")
	)
	(segment
		(start 104.499664 -13.933678)
		(end 104.499664 -13.959078)
		(width 0.4064)
		(layer "B.Cu")
		(net "PVDDQ_GHJ")
	)
	(segment
		(start 81.549494 -20.224242)
		(end 81.549494 -22.197568)
		(width 0.4064)
		(layer "B.Cu")
		(net "PVDDQ_GHJ")
	)
	(segment
		(start 102.080568 3.81)
		(end 101.4603 3.81)
		(width 0.508)
		(layer "B.Cu")
		(net "PVDDQ_GHJ")
	)
	(segment
		(start 86.64956 0.442722)
		(end 86.64956 -1.021842)
		(width 0.4064)
		(layer "B.Cu")
		(net "PVDDQ_GHJ")
	)
	(segment
		(start 175.488346 -4.57581)
		(end 174.809404 -4.57581)
		(width 0.4064)
		(layer "B.Cu")
		(net "PVDDQ_GHJ")
	)
	(segment
		(start 79.849472 0.468122)
		(end 79.849472 -1.021842)
		(width 0.4064)
		(layer "B.Cu")
		(net "PVDDQ_GHJ")
	)
	(segment
		(start 104.49941 -16.718534)
		(end 104.49941 -15.222982)
		(width 0.4064)
		(layer "B.Cu")
		(net "PVDDQ_GHJ")
	)
	(segment
		(start 110.560612 -29.337508)
		(end 110.560612 -29.94152)
		(width 0.254)
		(layer "B.Cu")
		(net "PVDDQ_GHJ")
	)
	(segment
		(start 79.849472 -1.021842)
		(end 79.849472 -2.314956)
		(width 0.4064)
		(layer "B.Cu")
		(net "PVDDQ_GHJ")
	)
	(segment
		(start 93.449394 -20.224242)
		(end 93.449394 -22.225)
		(width 0.4064)
		(layer "B.Cu")
		(net "PVDDQ_GHJ")
	)
	(segment
		(start 84.0994 1.152144)
		(end 84.0994 -1.021842)
		(width 0.4064)
		(layer "B.Cu")
		(net "PVDDQ_GHJ")
	)
	(segment
		(start 103.649526 -18.730468)
		(end 103.649526 -20.224242)
		(width 0.4064)
		(layer "B.Cu")
		(net "PVDDQ_GHJ")
	)
	(segment
		(start 89.199466 1.152144)
		(end 89.199466 -1.021842)
		(width 0.4064)
		(layer "B.Cu")
		(net "PVDDQ_GHJ")
	)
	(segment
		(start 88.349582 -5.621782)
		(end 88.349582 -4.332478)
		(width 0.4064)
		(layer "B.Cu")
		(net "PVDDQ_GHJ")
	)
	(segment
		(start 106.199432 -21.488146)
		(end 106.199432 -20.224242)
		(width 0.4064)
		(layer "B.Cu")
		(net "PVDDQ_GHJ")
	)
	(segment
		(start 101.94925 -23.560278)
		(end 101.949504 -23.560532)
		(width 0.4064)
		(layer "B.Cu")
		(net "PVDDQ_GHJ")
	)
	(segment
		(start 110.449868 -7.180072)
		(end 110.449868 -7.117588)
		(width 0.4064)
		(layer "B.Cu")
		(net "PVDDQ_GHJ")
	)
	(segment
		(start 110.449868 -13.933678)
		(end 110.44936 -13.934186)
		(width 0.4064)
		(layer "B.Cu")
		(net "PVDDQ_GHJ")
	)
	(segment
		(start 91.089226 -9.151874)
		(end 90.899488 -9.341612)
		(width 0.4064)
		(layer "B.Cu")
		(net "PVDDQ_GHJ")
	)
	(segment
		(start 110.44936 -23.495)
		(end 110.44936 -24.824182)
		(width 0.4064)
		(layer "B.Cu")
		(net "PVDDQ_GHJ")
	)
	(segment
		(start 89.199466 -11.918188)
		(end 89.199466 -10.623042)
		(width 0.4064)
		(layer "B.Cu")
		(net "PVDDQ_GHJ")
	)
	(segment
		(start 108.749846 -13.933678)
		(end 108.749338 -13.934186)
		(width 0.4064)
		(layer "B.Cu")
		(net "PVDDQ_GHJ")
	)
	(segment
		(start 78.999334 -5.621782)
		(end 78.999334 -7.115556)
		(width 0.4064)
		(layer "B.Cu")
		(net "PVDDQ_GHJ")
	)
	(segment
		(start 101.3841 3.8862)
		(end 100.6856 3.8862)
		(width 0.508)
		(layer "B.Cu")
		(net "PVDDQ_GHJ")
	)
	(segment
		(start 90.92311 -23.495)
		(end 90.903298 -23.514812)
		(width 0.4064)
		(layer "B.Cu")
		(net "PVDDQ_GHJ")
	)
	(segment
		(start 104.5591 -12.954)
		(end 104.5591 -13.874242)
		(width 0.4572)
		(layer "B.Cu")
		(net "PVDDQ_GHJ")
	)
	(segment
		(start 81.549494 -9.133078)
		(end 81.549494 -10.623042)
		(width 0.4064)
		(layer "B.Cu")
		(net "PVDDQ_GHJ")
	)
	(segment
		(start 109.599476 -21.515324)
		(end 109.5756 -21.5392)
		(width 0.4064)
		(layer "B.Cu")
		(net "PVDDQ_GHJ")
	)
	(segment
		(start 175.895 -3.8862)
		(end 175.895 -4.169156)
		(width 0.4064)
		(layer "B.Cu")
		(net "PVDDQ_GHJ")
	)
	(segment
		(start 84.0994 -11.916156)
		(end 84.0994 -10.623042)
		(width 0.4064)
		(layer "B.Cu")
		(net "PVDDQ_GHJ")
	)
	(segment
		(start 86.64956 -10.623042)
		(end 86.64956 -9.133078)
		(width 0.4064)
		(layer "B.Cu")
		(net "PVDDQ_GHJ")
	)
	(segment
		(start 86.64956 -18.734278)
		(end 86.64956 -20.224242)
		(width 0.4064)
		(layer "B.Cu")
		(net "PVDDQ_GHJ")
	)
	(segment
		(start 104.499664 -5.622036)
		(end 104.499664 -7.117588)
		(width 0.4064)
		(layer "B.Cu")
		(net "PVDDQ_GHJ")
	)
	(segment
		(start 103.649526 -1.021842)
		(end 103.649526 0.442468)
		(width 0.4064)
		(layer "B.Cu")
		(net "PVDDQ_GHJ")
	)
	(segment
		(start 91.056714 -18.663666)
		(end 90.899488 -18.820892)
		(width 0.4064)
		(layer "B.Cu")
		(net "PVDDQ_GHJ")
	)
	(segment
		(start 101.099366 1.152144)
		(end 101.099366 -1.021842)
		(width 0.4064)
		(layer "B.Cu")
		(net "PVDDQ_GHJ")
	)
	(segment
		(start 85.799422 -24.824182)
		(end 85.799422 -22.850856)
		(width 0.4064)
		(layer "B.Cu")
		(net "PVDDQ_GHJ")
	)
	(segment
		(start 89.199466 -21.488146)
		(end 89.199466 -20.224242)
		(width 0.4064)
		(layer "B.Cu")
		(net "PVDDQ_GHJ")
	)
	(segment
		(start 79.499968 -27.813)
		(end 79.499968 -27.01798)
		(width 0.4064)
		(layer "B.Cu")
		(net "PVDDQ_GHJ")
	)
	(segment
		(start 112.149382 -11.914378)
		(end 112.149382 -10.623042)
		(width 0.4064)
		(layer "B.Cu")
		(net "PVDDQ_GHJ")
	)
	(segment
		(start 85.799422 -16.716756)
		(end 85.799422 -15.222982)
		(width 0.4064)
		(layer "B.Cu")
		(net "PVDDQ_GHJ")
	)
	(segment
		(start 79.849472 -11.916156)
		(end 79.849472 -10.623042)
		(width 0.4064)
		(layer "B.Cu")
		(net "PVDDQ_GHJ")
	)
	(segment
		(start 88.349582 -7.117588)
		(end 88.349582 -5.621782)
		(width 0.4064)
		(layer "B.Cu")
		(net "PVDDQ_GHJ")
	)
	(segment
		(start 90.903298 -23.514812)
		(end 90.903298 -23.543006)
		(width 0.4064)
		(layer "B.Cu")
		(net "PVDDQ_GHJ")
	)
	(segment
		(start 79.849472 -18.734278)
		(end 79.849472 -20.224242)
		(width 0.4064)
		(layer "B.Cu")
		(net "PVDDQ_GHJ")
	)
	(segment
		(start 112.149382 -2.313178)
		(end 112.149382 -1.021842)
		(width 0.4064)
		(layer "B.Cu")
		(net "PVDDQ_GHJ")
	)
	(segment
		(start 93.449394 -24.824182)
		(end 93.449394 -23.5966)
		(width 0.4064)
		(layer "B.Cu")
		(net "PVDDQ_GHJ")
	)
	(segment
		(start 90.899488 -5.621782)
		(end 90.899488 -4.321556)
		(width 0.4064)
		(layer "B.Cu")
		(net "PVDDQ_GHJ")
	)
	(segment
		(start 166.7764 -5.8674)
		(end 166.7002 -5.7912)
		(width 0.254)
		(layer "B.Cu")
		(net "PVDDQ_GHJ")
	)
	(segment
		(start 86.64956 -22.197568)
		(end 86.64956 -20.224242)
		(width 0.4064)
		(layer "B.Cu")
		(net "PVDDQ_GHJ")
	)
	(segment
		(start 104.49941 -5.621782)
		(end 104.499664 -5.622036)
		(width 0.4064)
		(layer "B.Cu")
		(net "PVDDQ_GHJ")
	)
	(segment
		(start 101.94925 1.805432)
		(end 101.94925 2.65557)
		(width 0.508)
		(layer "B.Cu")
		(net "PVDDQ_GHJ")
	)
	(segment
		(start 109.599476 -1.021842)
		(end 109.599476 1.152144)
		(width 0.4064)
		(layer "B.Cu")
		(net "PVDDQ_GHJ")
	)
	(segment
		(start 84.0994 -1.021842)
		(end 84.0994 -2.314956)
		(width 0.4064)
		(layer "B.Cu")
		(net "PVDDQ_GHJ")
	)
	(segment
		(start 109.599476 -18.730468)
		(end 109.599476 -20.224242)
		(width 0.4064)
		(layer "B.Cu")
		(net "PVDDQ_GHJ")
	)
	(segment
		(start 112.149382 -23.495)
		(end 112.149382 -24.824182)
		(width 0.4064)
		(layer "B.Cu")
		(net "PVDDQ_GHJ")
	)
	(segment
		(start 80.699356 -15.222982)
		(end 80.699356 -16.716756)
		(width 0.4064)
		(layer "B.Cu")
		(net "PVDDQ_GHJ")
	)
	(segment
		(start 101.099366 -11.914378)
		(end 101.099366 -10.623042)
		(width 0.4064)
		(layer "B.Cu")
		(net "PVDDQ_GHJ")
	)
	(segment
		(start 107.899454 -21.5392)
		(end 107.899454 -20.224242)
		(width 0.4064)
		(layer "B.Cu")
		(net "PVDDQ_GHJ")
	)
	(segment
		(start 101.3968 -13.377164)
		(end 101.949504 -13.929868)
		(width 0.4572)
		(layer "B.Cu")
		(net "PVDDQ_GHJ")
	)
	(segment
		(start 83.249516 -5.621782)
		(end 83.249516 -4.332478)
		(width 0.4064)
		(layer "B.Cu")
		(net "PVDDQ_GHJ")
	)
	(segment
		(start 101.94925 2.65557)
		(end 102.080568 2.786888)
		(width 0.508)
		(layer "B.Cu")
		(net "PVDDQ_GHJ")
	)
	(segment
		(start 101.949504 -23.560532)
		(end 101.949504 -24.824182)
		(width 0.4064)
		(layer "B.Cu")
		(net "PVDDQ_GHJ")
	)
	(segment
		(start 106.199432 -18.730468)
		(end 106.199432 -20.224242)
		(width 0.4064)
		(layer "B.Cu")
		(net "PVDDQ_GHJ")
	)
	(segment
		(start 103.649272 -22.197568)
		(end 103.649526 -22.197314)
		(width 0.4064)
		(layer "B.Cu")
		(net "PVDDQ_GHJ")
	)
	(segment
		(start 112.149382 -7.113778)
		(end 112.149382 -5.621782)
		(width 0.4064)
		(layer "B.Cu")
		(net "PVDDQ_GHJ")
	)
	(segment
		(start 110.44936 -7.11708)
		(end 110.44936 -5.621782)
		(width 0.4064)
		(layer "B.Cu")
		(net "PVDDQ_GHJ")
	)
	(segment
		(start 104.499664 -4.332478)
		(end 104.49941 -4.332732)
		(width 0.4064)
		(layer "B.Cu")
		(net "PVDDQ_GHJ")
	)
	(segment
		(start 110.57128 -29.32684)
		(end 110.560612 -29.337508)
		(width 0.254)
		(layer "B.Cu")
		(net "PVDDQ_GHJ")
	)
	(segment
		(start 112.149382 -1.021842)
		(end 112.149382 0.468122)
		(width 0.4064)
		(layer "B.Cu")
		(net "PVDDQ_GHJ")
	)
	(segment
		(start 106.199432 -2.313178)
		(end 106.199432 -1.021842)
		(width 0.4064)
		(layer "B.Cu")
		(net "PVDDQ_GHJ")
	)
	(segment
		(start 109.599476 -2.313178)
		(end 109.599476 -1.021842)
		(width 0.4064)
		(layer "B.Cu")
		(net "PVDDQ_GHJ")
	)
	(segment
		(start 166.7764 -8.001)
		(end 166.7764 -5.8674)
		(width 0.254)
		(layer "B.Cu")
		(net "PVDDQ_GHJ")
	)
	(segment
		(start 103.649526 -2.313178)
		(end 103.649526 -1.021842)
		(width 0.4064)
		(layer "B.Cu")
		(net "PVDDQ_GHJ")
	)
	(segment
		(start 101.3968 -12.954)
		(end 101.3968 -13.377164)
		(width 0.4572)
		(layer "B.Cu")
		(net "PVDDQ_GHJ")
	)
	(segment
		(start 80.699356 -5.621782)
		(end 80.699356 -7.115556)
		(width 0.4064)
		(layer "B.Cu")
		(net "PVDDQ_GHJ")
	)
	(segment
		(start 78.999334 -4.332478)
		(end 78.999334 -5.621782)
		(width 0.4064)
		(layer "B.Cu")
		(net "PVDDQ_GHJ")
	)
	(segment
		(start 83.249516 -15.222982)
		(end 83.249516 -16.716756)
		(width 0.4064)
		(layer "B.Cu")
		(net "PVDDQ_GHJ")
	)
	(segment
		(start 108.749338 -23.495)
		(end 108.749338 -24.824182)
		(width 0.4064)
		(layer "B.Cu")
		(net "PVDDQ_GHJ")
	)
	(segment
		(start 110.449868 -7.117588)
		(end 110.44936 -7.11708)
		(width 0.4064)
		(layer "B.Cu")
		(net "PVDDQ_GHJ")
	)
	(segment
		(start 106.199432 -1.021842)
		(end 106.199432 1.152144)
		(width 0.4064)
		(layer "B.Cu")
		(net "PVDDQ_GHJ")
	)
	(segment
		(start 104.5591 -13.874242)
		(end 104.499664 -13.933678)
		(width 0.4572)
		(layer "B.Cu")
		(net "PVDDQ_GHJ")
	)
	(segment
		(start 90.899488 -7.115556)
		(end 90.899488 -5.621782)
		(width 0.4064)
		(layer "B.Cu")
		(net "PVDDQ_GHJ")
	)
	(segment
		(start 90.899488 -11.916156)
		(end 90.899488 -10.623042)
		(width 0.4064)
		(layer "B.Cu")
		(net "PVDDQ_GHJ")
	)
	(segment
		(start 110.44936 -4.332986)
		(end 110.44936 -5.621782)
		(width 0.4064)
		(layer "B.Cu")
		(net "PVDDQ_GHJ")
	)
	(segment
		(start 89.199466 -10.623042)
		(end 89.199466 -9.133078)
		(width 0.4064)
		(layer "B.Cu")
		(net "PVDDQ_GHJ")
	)
	(segment
		(start 104.499664 -16.718788)
		(end 104.49941 -16.718534)
		(width 0.4064)
		(layer "B.Cu")
		(net "PVDDQ_GHJ")
	)
	(segment
		(start 105.636568 3.81)
		(end 105.636568 3.026918)
		(width 0.4064)
		(layer "B.Cu")
		(net "PVDDQ_GHJ")
	)
	(segment
		(start 106.199432 -15.222982)
		(end 106.199432 -16.714978)
		(width 0.4064)
		(layer "B.Cu")
		(net "PVDDQ_GHJ")
	)
	(segment
		(start 84.0994 -18.734278)
		(end 84.0994 -20.224242)
		(width 0.4064)
		(layer "B.Cu")
		(net "PVDDQ_GHJ")
	)
	(segment
		(start 89.199466 -1.021842)
		(end 89.199466 -2.316988)
		(width 0.4064)
		(layer "B.Cu")
		(net "PVDDQ_GHJ")
	)
	(segment
		(start 90.899488 -9.341612)
		(end 90.899488 -10.623042)
		(width 0.4064)
		(layer "B.Cu")
		(net "PVDDQ_GHJ")
	)
	(segment
		(start 101.949758 -7.117588)
		(end 101.949504 -7.117334)
		(width 0.4064)
		(layer "B.Cu")
		(net "PVDDQ_GHJ")
	)
	(segment
		(start 88.349582 -23.560278)
		(end 88.349582 -24.824182)
		(width 0.4064)
		(layer "B.Cu")
		(net "PVDDQ_GHJ")
	)
	(segment
		(start 106.199432 -11.914378)
		(end 106.199432 -10.623042)
		(width 0.4064)
		(layer "B.Cu")
		(net "PVDDQ_GHJ")
	)
	(segment
		(start 106.199432 -24.824182)
		(end 106.199432 -22.850856)
		(width 0.4064)
		(layer "B.Cu")
		(net "PVDDQ_GHJ")
	)
	(segment
		(start 101.099366 -1.021842)
		(end 101.099366 -2.313178)
		(width 0.4064)
		(layer "B.Cu")
		(net "PVDDQ_GHJ")
	)
	(segment
		(start 101.949504 -7.117334)
		(end 101.949504 -5.621782)
		(width 0.4064)
		(layer "B.Cu")
		(net "PVDDQ_GHJ")
	)
	(segment
		(start 79.499968 -27.01798)
		(end 79.663798 -26.85415)
		(width 0.4064)
		(layer "B.Cu")
		(net "PVDDQ_GHJ")
	)
	(segment
		(start 93.449394 -23.5966)
		(end 93.550994 -23.495)
		(width 0.4064)
		(layer "B.Cu")
		(net "PVDDQ_GHJ")
	)
	(segment
		(start 90.899488 -2.264156)
		(end 90.899488 -1.021842)
		(width 0.4064)
		(layer "B.Cu")
		(net "PVDDQ_GHJ")
	)
	(segment
		(start 90.899488 -16.696944)
		(end 90.899488 -15.222982)
		(width 0.4064)
		(layer "B.Cu")
		(net "PVDDQ_GHJ")
	)
	(segment
		(start 88.349582 -16.718788)
		(end 88.349582 -15.222982)
		(width 0.4064)
		(layer "B.Cu")
		(net "PVDDQ_GHJ")
	)
	(segment
		(start 80.699356 -25.818592)
		(end 80.699356 -24.824182)
		(width 0.4064)
		(layer "B.Cu")
		(net "PVDDQ_GHJ")
	)
	(segment
		(start 88.349582 -15.222982)
		(end 88.349582 -13.933678)
		(width 0.4064)
		(layer "B.Cu")
		(net "PVDDQ_GHJ")
	)
	(segment
		(start 109.599476 -20.224242)
		(end 109.599476 -21.515324)
		(width 0.4064)
		(layer "B.Cu")
		(net "PVDDQ_GHJ")
	)
	(segment
		(start 101.4603 3.81)
		(end 101.3841 3.8862)
		(width 0.508)
		(layer "B.Cu")
		(net "PVDDQ_GHJ")
	)
	(segment
		(start 93.449394 -1.021842)
		(end 93.449394 -2.314956)
		(width 0.4064)
		(layer "B.Cu")
		(net "PVDDQ_GHJ")
	)
	(segment
		(start 90.903298 -23.543006)
		(end 90.899488 -23.546816)
		(width 0.4064)
		(layer "B.Cu")
		(net "PVDDQ_GHJ")
	)
	(segment
		(start 164.991034 -70.804024)
		(end 164.991034 -66.306954)
		(width 0.254)
		(layer "In2.Cu")
		(net "PVDDQ_GHJ")
	)
	(segment
		(start 165.06444 -16.95704)
		(end 165.06444 -10.5029)
		(width 0.254)
		(layer "In2.Cu")
		(net "PVDDQ_GHJ")
	)
	(segment
		(start 172.4152 -33.58134)
		(end 169.225722 -30.391862)
		(width 0.254)
		(layer "In2.Cu")
		(net "PVDDQ_GHJ")
	)
	(segment
		(start 160.241488 -58.594752)
		(end 160.241488 -51.480212)
		(width 0.254)
		(layer "In2.Cu")
		(net "PVDDQ_GHJ")
	)
	(segment
		(start 167.689276 -20.801076)
		(end 166.2684 -19.3802)
		(width 0.254)
		(layer "In2.Cu")
		(net "PVDDQ_GHJ")
	)
	(segment
		(start 166.2684 -18.161)
		(end 165.06444 -16.95704)
		(width 0.254)
		(layer "In2.Cu")
		(net "PVDDQ_GHJ")
	)
	(segment
		(start 169.611294 -21.439886)
		(end 168.972484 -20.801076)
		(width 0.254)
		(layer "In2.Cu")
		(net "PVDDQ_GHJ")
	)
	(segment
		(start 169.611294 -27.869896)
		(end 169.611294 -21.439886)
		(width 0.254)
		(layer "In2.Cu")
		(net "PVDDQ_GHJ")
	)
	(segment
		(start 169.225722 -28.255468)
		(end 169.611294 -27.869896)
		(width 0.254)
		(layer "In2.Cu")
		(net "PVDDQ_GHJ")
	)
	(segment
		(start 159.26562 -59.57062)
		(end 160.241488 -58.594752)
		(width 0.254)
		(layer "In2.Cu")
		(net "PVDDQ_GHJ")
	)
	(segment
		(start 169.858436 -44.248832)
		(end 169.858436 -41.494964)
		(width 0.254)
		(layer "In2.Cu")
		(net "PVDDQ_GHJ")
	)
	(segment
		(start 159.26562 -63.57874)
		(end 159.26562 -59.57062)
		(width 0.254)
		(layer "In2.Cu")
		(net "PVDDQ_GHJ")
	)
	(segment
		(start 166.7764 -8.79094)
		(end 166.7764 -8.001)
		(width 0.254)
		(layer "In2.Cu")
		(net "PVDDQ_GHJ")
	)
	(segment
		(start 168.524428 -45.58284)
		(end 169.858436 -44.248832)
		(width 0.254)
		(layer "In2.Cu")
		(net "PVDDQ_GHJ")
	)
	(segment
		(start 168.972484 -20.801076)
		(end 167.689276 -20.801076)
		(width 0.254)
		(layer "In2.Cu")
		(net "PVDDQ_GHJ")
	)
	(segment
		(start 164.461698 -71.198232)
		(end 164.596826 -71.198232)
		(width 0.254)
		(layer "In2.Cu")
		(net "PVDDQ_GHJ")
	)
	(segment
		(start 164.596826 -71.198232)
		(end 164.991034 -70.804024)
		(width 0.254)
		(layer "In2.Cu")
		(net "PVDDQ_GHJ")
	)
	(segment
		(start 169.858436 -41.494964)
		(end 172.4152 -38.9382)
		(width 0.254)
		(layer "In2.Cu")
		(net "PVDDQ_GHJ")
	)
	(segment
		(start 164.991034 -66.306954)
		(end 164.12464 -65.44056)
		(width 0.254)
		(layer "In2.Cu")
		(net "PVDDQ_GHJ")
	)
	(segment
		(start 160.241488 -51.480212)
		(end 166.13886 -45.58284)
		(width 0.254)
		(layer "In2.Cu")
		(net "PVDDQ_GHJ")
	)
	(segment
		(start 166.13886 -45.58284)
		(end 168.524428 -45.58284)
		(width 0.254)
		(layer "In2.Cu")
		(net "PVDDQ_GHJ")
	)
	(segment
		(start 169.225722 -30.391862)
		(end 169.225722 -28.255468)
		(width 0.254)
		(layer "In2.Cu")
		(net "PVDDQ_GHJ")
	)
	(segment
		(start 164.12464 -65.44056)
		(end 161.12744 -65.44056)
		(width 0.254)
		(layer "In2.Cu")
		(net "PVDDQ_GHJ")
	)
	(segment
		(start 172.4152 -38.9382)
		(end 172.4152 -33.58134)
		(width 0.254)
		(layer "In2.Cu")
		(net "PVDDQ_GHJ")
	)
	(segment
		(start 161.12744 -65.44056)
		(end 159.26562 -63.57874)
		(width 0.254)
		(layer "In2.Cu")
		(net "PVDDQ_GHJ")
	)
	(segment
		(start 166.2684 -19.3802)
		(end 166.2684 -18.161)
		(width 0.254)
		(layer "In2.Cu")
		(net "PVDDQ_GHJ")
	)
	(segment
		(start 165.06444 -10.5029)
		(end 166.7764 -8.79094)
		(width 0.254)
		(layer "In2.Cu")
		(net "PVDDQ_GHJ")
	)
	(segment
		(start 4.402582 -14.799818)
		(end 2.282952 -14.799818)
		(width 0.254)
		(layer "In7.Cu")
		(net "PVDDQ_GHJ")
	)
	(segment
		(start 5.7912 -13.4112)
		(end 4.402582 -14.799818)
		(width 0.254)
		(layer "In7.Cu")
		(net "PVDDQ_GHJ")
	)
	(segment
		(start 8.660384 -5.8928)
		(end 5.65912 -5.8928)
		(width 0.254)
		(layer "In7.Cu")
		(net "PVDDQ_GHJ")
	)
	(segment
		(start 12.565126 -6.36016)
		(end 9.127744 -6.36016)
		(width 0.254)
		(layer "In7.Cu")
		(net "PVDDQ_GHJ")
	)
	(segment
		(start 15.508224 -13.4112)
		(end 5.7912 -13.4112)
		(width 0.254)
		(layer "In7.Cu")
		(net "PVDDQ_GHJ")
	)
	(segment
		(start 4.54406 -7.00786)
		(end 2.279904 -7.00786)
		(width 0.254)
		(layer "In7.Cu")
		(net "PVDDQ_GHJ")
	)
	(segment
		(start 2.279904 -7.00786)
		(end 2.19964 -6.927596)
		(width 0.254)
		(layer "In7.Cu")
		(net "PVDDQ_GHJ")
	)
	(segment
		(start 5.65912 -5.8928)
		(end 4.54406 -7.00786)
		(width 0.254)
		(layer "In7.Cu")
		(net "PVDDQ_GHJ")
	)
	(segment
		(start 15.54353 -7.874508)
		(end 14.079474 -7.874508)
		(width 0.254)
		(layer "In7.Cu")
		(net "PVDDQ_GHJ")
	)
	(segment
		(start 9.127744 -6.36016)
		(end 8.660384 -5.8928)
		(width 0.254)
		(layer "In7.Cu")
		(net "PVDDQ_GHJ")
	)
	(segment
		(start 14.079474 -7.874508)
		(end 12.565126 -6.36016)
		(width 0.254)
		(layer "In7.Cu")
		(net "PVDDQ_GHJ")
	)
	(segment
		(start 15.862046 -8.193024)
		(end 15.54353 -7.874508)
		(width 0.254)
		(layer "In7.Cu")
		(net "PVDDQ_GHJ")
	)
	(segment
		(start 25.85212 -20.55876)
		(end 28.449778 -23.156418)
		(width 0.4064)
		(layer "In9.Cu")
		(net "PVDDQ_GHJ")
	)
	(segment
		(start 28.449778 -23.156418)
		(end 28.449778 -23.657306)
		(width 0.4064)
		(layer "In9.Cu")
		(net "PVDDQ_GHJ")
	)
	(segment
		(start 22.46376 -20.55876)
		(end 25.85212 -20.55876)
		(width 0.4064)
		(layer "In9.Cu")
		(net "PVDDQ_GHJ")
	)
	(segment
		(start 20.193 -18.415)
		(end 20.32 -18.415)
		(width 0.4064)
		(layer "In9.Cu")
		(net "PVDDQ_GHJ")
	)
	(segment
		(start 20.32 -18.415)
		(end 22.46376 -20.55876)
		(width 0.4064)
		(layer "In9.Cu")
		(net "PVDDQ_GHJ")
	)
	(segment
		(start 274.599908 -156.87294)
		(end 274.599908 -154.905456)
		(width 0.508)
		(layer "F.Cu")
		(net "PVDDQ_DEF")
	)
	(segment
		(start 258.450334 -148.214588)
		(end 258.896358 -148.660612)
		(width 0.4064)
		(layer "F.Cu")
		(net "PVDDQ_DEF")
	)
	(segment
		(start 255.89992 -148.556218)
		(end 255.89992 -147.27174)
		(width 0.508)
		(layer "F.Cu")
		(net "PVDDQ_DEF")
	)
	(segment
		(start 246.549926 -156.87294)
		(end 246.549926 -155.564078)
		(width 0.508)
		(layer "F.Cu")
		(net "PVDDQ_DEF")
	)
	(segment
		(start 248.250456 -142.6718)
		(end 248.250456 -141.188186)
		(width 0.508)
		(layer "F.Cu")
		(net "PVDDQ_DEF")
	)
	(segment
		(start 244.000274 -152.273)
		(end 243.999766 -152.273)
		(width 0.508)
		(layer "F.Cu")
		(net "PVDDQ_DEF")
	)
	(segment
		(start 268.649958 -139.168378)
		(end 268.649958 -137.67054)
		(width 0.508)
		(layer "F.Cu")
		(net "PVDDQ_DEF")
	)
	(segment
		(start 266.100306 -137.67054)
		(end 266.099798 -137.67054)
		(width 0.508)
		(layer "F.Cu")
		(net "PVDDQ_DEF")
	)
	(segment
		(start 252.495304 -92.737686)
		(end 251.923804 -92.737686)
		(width 0.254)
		(layer "F.Cu")
		(net "PVDDQ_DEF")
	)
	(segment
		(start 266.100306 -148.76907)
		(end 266.099798 -148.769578)
		(width 0.508)
		(layer "F.Cu")
		(net "PVDDQ_DEF")
	)
	(segment
		(start 255.900428 -143.961612)
		(end 255.909572 -143.970756)
		(width 0.508)
		(layer "F.Cu")
		(net "PVDDQ_DEF")
	)
	(segment
		(start 245.880636 -131.995164)
		(end 245.880636 -131.083304)
		(width 0.4064)
		(layer "F.Cu")
		(net "PVDDQ_DEF")
	)
	(segment
		(start 263.65581 -100.167186)
		(end 264.22731 -100.167186)
		(width 0.254)
		(layer "F.Cu")
		(net "PVDDQ_DEF")
	)
	(segment
		(start 273.750278 -142.6718)
		(end 273.750278 -143.972788)
		(width 0.508)
		(layer "F.Cu")
		(net "PVDDQ_DEF")
	)
	(segment
		(start 260.50875 -92.737686)
		(end 261.08025 -92.737686)
		(width 0.254)
		(layer "F.Cu")
		(net "PVDDQ_DEF")
	)
	(segment
		(start 253.353824 -100.167186)
		(end 253.640844 -99.67214)
		(width 0.254)
		(layer "F.Cu")
		(net "PVDDQ_DEF")
	)
	(segment
		(start 268.650466 -137.67054)
		(end 268.649958 -137.67054)
		(width 0.508)
		(layer "F.Cu")
		(net "PVDDQ_DEF")
	)
	(segment
		(start 246.549926 -137.67054)
		(end 246.549926 -136.387078)
		(width 0.508)
		(layer "F.Cu")
		(net "PVDDQ_DEF")
	)
	(segment
		(start 274.599908 -147.27174)
		(end 274.599908 -145.984468)
		(width 0.508)
		(layer "F.Cu")
		(net "PVDDQ_DEF")
	)
	(segment
		(start 265.372596 -97.19564)
		(end 264.801096 -97.19564)
		(width 0.254)
		(layer "F.Cu")
		(net "PVDDQ_DEF")
	)
	(segment
		(start 271.199864 -147.27174)
		(end 271.199864 -148.742146)
		(width 0.508)
		(layer "F.Cu")
		(net "PVDDQ_DEF")
	)
	(segment
		(start 275.4503 -131.612386)
		(end 275.449792 -131.611878)
		(width 0.4064)
		(layer "F.Cu")
		(net "PVDDQ_DEF")
	)
	(segment
		(start 259.36321 -92.737686)
		(end 258.79171 -92.737686)
		(width 0.254)
		(layer "F.Cu")
		(net "PVDDQ_DEF")
	)
	(segment
		(start 277.149814 -150.788878)
		(end 277.149814 -152.273)
		(width 0.508)
		(layer "F.Cu")
		(net "PVDDQ_DEF")
	)
	(segment
		(start 248.249948 -152.273)
		(end 248.250456 -152.273)
		(width 0.508)
		(layer "F.Cu")
		(net "PVDDQ_DEF")
	)
	(segment
		(start 251.649992 -147.27174)
		(end 251.649992 -145.988278)
		(width 0.508)
		(layer "F.Cu")
		(net "PVDDQ_DEF")
	)
	(segment
		(start 245.700296 -134.369048)
		(end 245.699788 -134.369556)
		(width 0.4064)
		(layer "F.Cu")
		(net "PVDDQ_DEF")
	)
	(segment
		(start 253.350014 -150.788878)
		(end 253.350014 -152.273)
		(width 0.508)
		(layer "F.Cu")
		(net "PVDDQ_DEF")
	)
	(segment
		(start 272.900394 -156.87294)
		(end 272.899886 -156.87294)
		(width 0.508)
		(layer "F.Cu")
		(net "PVDDQ_DEF")
	)
	(segment
		(start 249.099832 -145.988278)
		(end 249.099832 -147.27174)
		(width 0.508)
		(layer "F.Cu")
		(net "PVDDQ_DEF")
	)
	(segment
		(start 244.850412 -137.67054)
		(end 244.849904 -137.67054)
		(width 0.508)
		(layer "F.Cu")
		(net "PVDDQ_DEF")
	)
	(segment
		(start 277.149814 -143.968978)
		(end 277.150322 -143.96847)
		(width 0.508)
		(layer "F.Cu")
		(net "PVDDQ_DEF")
	)
	(segment
		(start 263.65581 -97.19564)
		(end 263.08431 -97.19564)
		(width 0.254)
		(layer "F.Cu")
		(net "PVDDQ_DEF")
	)
	(segment
		(start 248.250456 -141.188186)
		(end 248.249948 -141.187678)
		(width 0.508)
		(layer "F.Cu")
		(net "PVDDQ_DEF")
	)
	(segment
		(start 260.22173 -100.167186)
		(end 260.50875 -99.67214)
		(width 0.254)
		(layer "F.Cu")
		(net "PVDDQ_DEF")
	)
	(segment
		(start 258.261612 -155.386786)
		(end 258.450334 -155.575508)
		(width 0.4572)
		(layer "F.Cu")
		(net "PVDDQ_DEF")
	)
	(segment
		(start 273.750278 -133.0706)
		(end 273.750278 -131.612386)
		(width 0.4064)
		(layer "F.Cu")
		(net "PVDDQ_DEF")
	)
	(segment
		(start 244.849904 -137.67054)
		(end 244.849904 -136.387078)
		(width 0.508)
		(layer "F.Cu")
		(net "PVDDQ_DEF")
	)
	(segment
		(start 255.89992 -153.571956)
		(end 255.89992 -152.273)
		(width 0.508)
		(layer "F.Cu")
		(net "PVDDQ_DEF")
	)
	(segment
		(start 271.200372 -152.273)
		(end 271.199864 -152.273)
		(width 0.508)
		(layer "F.Cu")
		(net "PVDDQ_DEF")
	)
	(segment
		(start 277.150322 -143.96847)
		(end 277.150322 -142.6718)
		(width 0.508)
		(layer "F.Cu")
		(net "PVDDQ_DEF")
	)
	(segment
		(start 254.200406 -156.87294)
		(end 254.199898 -156.87294)
		(width 0.508)
		(layer "F.Cu")
		(net "PVDDQ_DEF")
	)
	(segment
		(start 275.449792 -152.273)
		(end 275.449792 -154.252168)
		(width 0.508)
		(layer "F.Cu")
		(net "PVDDQ_DEF")
	)
	(segment
		(start 271.199864 -146.013932)
		(end 271.199864 -147.27174)
		(width 0.508)
		(layer "F.Cu")
		(net "PVDDQ_DEF")
	)
	(segment
		(start 249.099832 -137.67054)
		(end 249.099832 -139.170156)
		(width 0.508)
		(layer "F.Cu")
		(net "PVDDQ_DEF")
	)
	(segment
		(start 255.89992 -137.67054)
		(end 255.900428 -137.67054)
		(width 0.508)
		(layer "F.Cu")
		(net "PVDDQ_DEF")
	)
	(segment
		(start 258.414774 -139.149582)
		(end 258.449826 -139.149582)
		(width 0.4064)
		(layer "F.Cu")
		(net "PVDDQ_DEF")
	)
	(segment
		(start 250.800362 -141.188186)
		(end 250.799854 -141.187678)
		(width 0.508)
		(layer "F.Cu")
		(net "PVDDQ_DEF")
	)
	(segment
		(start 253.350014 -152.273)
		(end 253.350522 -152.273)
		(width 0.508)
		(layer "F.Cu")
		(net "PVDDQ_DEF")
	)
	(segment
		(start 245.700296 -152.273)
		(end 245.699788 -152.273)
		(width 0.508)
		(layer "F.Cu")
		(net "PVDDQ_DEF")
	)
	(segment
		(start 248.249948 -150.788878)
		(end 248.249948 -152.273)
		(width 0.508)
		(layer "F.Cu")
		(net "PVDDQ_DEF")
	)
	(segment
		(start 350.404684 -156.076904)
		(end 350.74606 -156.41828)
		(width 0.254)
		(layer "F.Cu")
		(net "PVDDQ_DEF")
	)
	(segment
		(start 277.149814 -145.988786)
		(end 277.149814 -147.27174)
		(width 0.508)
		(layer "F.Cu")
		(net "PVDDQ_DEF")
	)
	(segment
		(start 272.899886 -147.27174)
		(end 272.899886 -145.984468)
		(width 0.508)
		(layer "F.Cu")
		(net "PVDDQ_DEF")
	)
	(segment
		(start 277.150322 -137.67054)
		(end 277.149814 -137.67054)
		(width 0.508)
		(layer "F.Cu")
		(net "PVDDQ_DEF")
	)
	(segment
		(start 253.54661 -154.252168)
		(end 254.199898 -154.905456)
		(width 0.4064)
		(layer "F.Cu")
		(net "PVDDQ_DEF")
	)
	(segment
		(start 266.949936 -152.278842)
		(end 266.949936 -152.273)
		(width 0.508)
		(layer "F.Cu")
		(net "PVDDQ_DEF")
	)
	(segment
		(start 266.100306 -156.87294)
		(end 266.099798 -156.87294)
		(width 0.508)
		(layer "F.Cu")
		(net "PVDDQ_DEF")
	)
	(segment
		(start 248.249948 -134.369556)
		(end 248.249948 -133.0706)
		(width 0.508)
		(layer "F.Cu")
		(net "PVDDQ_DEF")
	)
	(segment
		(start 250.800362 -142.6718)
		(end 250.800362 -141.188186)
		(width 0.508)
		(layer "F.Cu")
		(net "PVDDQ_DEF")
	)
	(segment
		(start 253.353824 -94.223586)
		(end 252.782324 -94.223586)
		(width 0.254)
		(layer "F.Cu")
		(net "PVDDQ_DEF")
	)
	(segment
		(start 246.549926 -139.170156)
		(end 246.549926 -137.67054)
		(width 0.508)
		(layer "F.Cu")
		(net "PVDDQ_DEF")
	)
	(segment
		(start 266.950444 -142.6718)
		(end 266.949936 -142.6718)
		(width 0.508)
		(layer "F.Cu")
		(net "PVDDQ_DEF")
	)
	(segment
		(start 249.10034 -137.67054)
		(end 249.099832 -137.67054)
		(width 0.508)
		(layer "F.Cu")
		(net "PVDDQ_DEF")
	)
	(segment
		(start 271.200372 -137.67054)
		(end 271.199864 -137.67054)
		(width 0.508)
		(layer "F.Cu")
		(net "PVDDQ_DEF")
	)
	(segment
		(start 267.089636 -100.167186)
		(end 267.376656 -99.67214)
		(width 0.254)
		(layer "F.Cu")
		(net "PVDDQ_DEF")
	)
	(segment
		(start 244.000274 -143.970248)
		(end 243.999766 -143.970756)
		(width 0.508)
		(layer "F.Cu")
		(net "PVDDQ_DEF")
	)
	(segment
		(start 266.949936 -142.6718)
		(end 266.949936 -141.183868)
		(width 0.508)
		(layer "F.Cu")
		(net "PVDDQ_DEF")
	)
	(segment
		(start 244.000274 -133.0706)
		(end 243.999766 -133.0706)
		(width 0.4064)
		(layer "F.Cu")
		(net "PVDDQ_DEF")
	)
	(segment
		(start 249.099832 -147.27174)
		(end 249.099832 -148.771356)
		(width 0.508)
		(layer "F.Cu")
		(net "PVDDQ_DEF")
	)
	(segment
		(start 275.4503 -133.0706)
		(end 275.4503 -134.371588)
		(width 0.4064)
		(layer "F.Cu")
		(net "PVDDQ_DEF")
	)
	(segment
		(start 268.649704 -155.614878)
		(end 268.649958 -155.615132)
		(width 0.4064)
		(layer "F.Cu")
		(net "PVDDQ_DEF")
	)
	(segment
		(start 266.950444 -133.0706)
		(end 266.950444 -131.61264)
		(width 0.4064)
		(layer "F.Cu")
		(net "PVDDQ_DEF")
	)
	(segment
		(start 255.92913 -89.765886)
		(end 255.35763 -89.765886)
		(width 0.254)
		(layer "F.Cu")
		(net "PVDDQ_DEF")
	)
	(segment
		(start 254.199898 -136.387078)
		(end 254.199898 -137.67054)
		(width 0.508)
		(layer "F.Cu")
		(net "PVDDQ_DEF")
	)
	(segment
		(start 258.450334 -147.27174)
		(end 258.450334 -148.214588)
		(width 0.4064)
		(layer "F.Cu")
		(net "PVDDQ_DEF")
	)
	(segment
		(start 267.089636 -97.19564)
		(end 266.518136 -97.19564)
		(width 0.254)
		(layer "F.Cu")
		(net "PVDDQ_DEF")
	)
	(segment
		(start 262.255 -130.367024)
		(end 262.255 -131.840224)
		(width 0.508)
		(layer "F.Cu")
		(net "PVDDQ_DEF")
	)
	(segment
		(start 254.212344 -92.737686)
		(end 253.640844 -92.737686)
		(width 0.254)
		(layer "F.Cu")
		(net "PVDDQ_DEF")
	)
	(segment
		(start 244.849904 -147.27174)
		(end 244.849904 -148.771356)
		(width 0.508)
		(layer "F.Cu")
		(net "PVDDQ_DEF")
	)
	(segment
		(start 273.750278 -133.0706)
		(end 273.750278 -134.371588)
		(width 0.4064)
		(layer "F.Cu")
		(net "PVDDQ_DEF")
	)
	(segment
		(start 272.899886 -137.67054)
		(end 272.899886 -136.383268)
		(width 0.508)
		(layer "F.Cu")
		(net "PVDDQ_DEF")
	)
	(segment
		(start 255.89992 -141.18717)
		(end 255.90627 -141.18717)
		(width 0.5588)
		(layer "F.Cu")
		(net "PVDDQ_DEF")
	)
	(segment
		(start 250.799854 -134.369556)
		(end 250.799854 -133.076442)
		(width 0.508)
		(layer "F.Cu")
		(net "PVDDQ_DEF")
	)
	(segment
		(start 274.796504 -154.905456)
		(end 274.599908 -154.905456)
		(width 0.4064)
		(layer "F.Cu")
		(net "PVDDQ_DEF")
	)
	(segment
		(start 245.700296 -133.0706)
		(end 245.700296 -132.175504)
		(width 0.4064)
		(layer "F.Cu")
		(net "PVDDQ_DEF")
	)
	(segment
		(start 266.099798 -136.383268)
		(end 266.099798 -137.67054)
		(width 0.508)
		(layer "F.Cu")
		(net "PVDDQ_DEF")
	)
	(segment
		(start 258.450334 -152.273)
		(end 258.449826 -152.273)
		(width 0.508)
		(layer "F.Cu")
		(net "PVDDQ_DEF")
	)
	(segment
		(start 246.549926 -147.27174)
		(end 246.549926 -148.771356)
		(width 0.508)
		(layer "F.Cu")
		(net "PVDDQ_DEF")
	)
	(segment
		(start 266.950444 -134.371334)
		(end 266.95019 -134.371588)
		(width 0.4064)
		(layer "F.Cu")
		(net "PVDDQ_DEF")
	)
	(segment
		(start 273.74977 -150.789386)
		(end 273.750278 -150.788878)
		(width 0.381)
		(layer "F.Cu")
		(net "PVDDQ_DEF")
	)
	(segment
		(start 269.500096 -143.972788)
		(end 269.50035 -143.972534)
		(width 0.508)
		(layer "F.Cu")
		(net "PVDDQ_DEF")
	)
	(segment
		(start 258.450334 -142.6718)
		(end 258.450334 -141.71168)
		(width 0.508)
		(layer "F.Cu")
		(net "PVDDQ_DEF")
	)
	(segment
		(start 258.896358 -148.660612)
		(end 258.896358 -148.771356)
		(width 0.4064)
		(layer "F.Cu")
		(net "PVDDQ_DEF")
	)
	(segment
		(start 277.149814 -142.6718)
		(end 277.149814 -141.183868)
		(width 0.508)
		(layer "F.Cu")
		(net "PVDDQ_DEF")
	)
	(segment
		(start 255.900428 -142.6718)
		(end 255.900428 -143.961612)
		(width 0.508)
		(layer "F.Cu")
		(net "PVDDQ_DEF")
	)
	(segment
		(start 266.099798 -147.27174)
		(end 266.100306 -147.27174)
		(width 0.508)
		(layer "F.Cu")
		(net "PVDDQ_DEF")
	)
	(segment
		(start 244.551454 -126.401576)
		(end 244.172486 -126.780544)
		(width 0.4064)
		(layer "F.Cu")
		(net "PVDDQ_DEF")
	)
	(segment
		(start 253.353824 -97.19564)
		(end 252.782324 -97.19564)
		(width 0.254)
		(layer "F.Cu")
		(net "PVDDQ_DEF")
	)
	(segment
		(start 255.89992 -155.509468)
		(end 255.89992 -153.571956)
		(width 0.508)
		(layer "F.Cu")
		(net "PVDDQ_DEF")
	)
	(segment
		(start 277.149814 -137.67054)
		(end 277.149814 -136.383268)
		(width 0.508)
		(layer "F.Cu")
		(net "PVDDQ_DEF")
	)
	(segment
		(start 253.350014 -154.252168)
		(end 253.350014 -152.273)
		(width 0.508)
		(layer "F.Cu")
		(net "PVDDQ_DEF")
	)
	(segment
		(start 251.649992 -148.773388)
		(end 251.649992 -147.27174)
		(width 0.508)
		(layer "F.Cu")
		(net "PVDDQ_DEF")
	)
	(segment
		(start 258.50469 -97.19564)
		(end 257.93319 -97.19564)
		(width 0.254)
		(layer "F.Cu")
		(net "PVDDQ_DEF")
	)
	(segment
		(start 267.948156 -92.737686)
		(end 267.376656 -92.737686)
		(width 0.254)
		(layer "F.Cu")
		(net "PVDDQ_DEF")
	)
	(segment
		(start 273.750278 -131.612386)
		(end 273.74977 -131.611878)
		(width 0.4064)
		(layer "F.Cu")
		(net "PVDDQ_DEF")
	)
	(segment
		(start 262.255 -131.840224)
		(end 262.89 -132.475224)
		(width 0.508)
		(layer "F.Cu")
		(net "PVDDQ_DEF")
	)
	(segment
		(start 251.6505 -147.27174)
		(end 251.649992 -147.27174)
		(width 0.508)
		(layer "F.Cu")
		(net "PVDDQ_DEF")
	)
	(segment
		(start 274.600416 -156.87294)
		(end 274.599908 -156.87294)
		(width 0.508)
		(layer "F.Cu")
		(net "PVDDQ_DEF")
	)
	(segment
		(start 269.2908 -132.08)
		(end 269.2908 -131.111498)
		(width 0.4064)
		(layer "F.Cu")
		(net "PVDDQ_DEF")
	)
	(segment
		(start 277.150322 -152.273)
		(end 277.149814 -152.273)
		(width 0.508)
		(layer "F.Cu")
		(net "PVDDQ_DEF")
	)
	(segment
		(start 258.272026 -141.533372)
		(end 258.272026 -141.183868)
		(width 0.508)
		(layer "F.Cu")
		(net "PVDDQ_DEF")
	)
	(segment
		(start 277.149814 -145.984468)
		(end 277.149814 -145.988786)
		(width 0.254)
		(layer "F.Cu")
		(net "PVDDQ_DEF")
	)
	(segment
		(start 256.78765 -94.223586)
		(end 256.21615 -94.223586)
		(width 0.254)
		(layer "F.Cu")
		(net "PVDDQ_DEF")
	)
	(segment
		(start 251.649992 -137.67054)
		(end 251.649992 -139.172188)
		(width 0.508)
		(layer "F.Cu")
		(net "PVDDQ_DEF")
	)
	(segment
		(start 269.499842 -150.789132)
		(end 269.500096 -150.788878)
		(width 0.381)
		(layer "F.Cu")
		(net "PVDDQ_DEF")
	)
	(segment
		(start 272.900394 -148.76907)
		(end 272.899886 -148.769578)
		(width 0.508)
		(layer "F.Cu")
		(net "PVDDQ_DEF")
	)
	(segment
		(start 246.550434 -137.67054)
		(end 246.549926 -137.67054)
		(width 0.508)
		(layer "F.Cu")
		(net "PVDDQ_DEF")
	)
	(segment
		(start 261.93877 -100.167186)
		(end 261.36727 -99.17684)
		(width 0.254)
		(layer "F.Cu")
		(net "PVDDQ_DEF")
	)
	(segment
		(start 255.900428 -152.273)
		(end 255.89992 -152.273)
		(width 0.508)
		(layer "F.Cu")
		(net "PVDDQ_DEF")
	)
	(segment
		(start 267.948156 -90.756486)
		(end 267.376656 -90.756486)
		(width 0.254)
		(layer "F.Cu")
		(net "PVDDQ_DEF")
	)
	(segment
		(start 262.79729 -92.737686)
		(end 262.22579 -92.737686)
		(width 0.254)
		(layer "F.Cu")
		(net "PVDDQ_DEF")
	)
	(segment
		(start 257.64617 -92.737686)
		(end 257.07467 -92.737686)
		(width 0.254)
		(layer "F.Cu")
		(net "PVDDQ_DEF")
	)
	(segment
		(start 243.999766 -133.0706)
		(end 243.999766 -130.902456)
		(width 0.4064)
		(layer "F.Cu")
		(net "PVDDQ_DEF")
	)
	(segment
		(start 268.649958 -137.67054)
		(end 268.649958 -136.383268)
		(width 0.508)
		(layer "F.Cu")
		(net "PVDDQ_DEF")
	)
	(segment
		(start 269.2908 -131.111498)
		(end 269.499842 -130.902456)
		(width 0.4064)
		(layer "F.Cu")
		(net "PVDDQ_DEF")
	)
	(segment
		(start 263.65581 -94.223586)
		(end 263.08431 -94.223586)
		(width 0.254)
		(layer "F.Cu")
		(net "PVDDQ_DEF")
	)
	(segment
		(start 277.149814 -155.589478)
		(end 277.149814 -154.252168)
		(width 0.4064)
		(layer "F.Cu")
		(net "PVDDQ_DEF")
	)
	(segment
		(start 255.90627 -141.18717)
		(end 255.909572 -141.183868)
		(width 0.5588)
		(layer "F.Cu")
		(net "PVDDQ_DEF")
	)
	(segment
		(start 253.350014 -134.371588)
		(end 253.350014 -133.0706)
		(width 0.508)
		(layer "F.Cu")
		(net "PVDDQ_DEF")
	)
	(segment
		(start 269.50035 -142.6718)
		(end 269.499842 -142.6718)
		(width 0.508)
		(layer "F.Cu")
		(net "PVDDQ_DEF")
	)
	(segment
		(start 258.449826 -133.076442)
		(end 258.449826 -134.380478)
		(width 0.4064)
		(layer "F.Cu")
		(net "PVDDQ_DEF")
	)
	(segment
		(start 250.800362 -142.6718)
		(end 250.800362 -143.970248)
		(width 0.508)
		(layer "F.Cu")
		(net "PVDDQ_DEF")
	)
	(segment
		(start 258.50469 -100.167186)
		(end 258.699 -99.83216)
		(width 0.254)
		(layer "F.Cu")
		(net "PVDDQ_DEF")
	)
	(segment
		(start 248.250456 -142.6718)
		(end 248.250456 -143.970248)
		(width 0.508)
		(layer "F.Cu")
		(net "PVDDQ_DEF")
	)
	(segment
		(start 266.949936 -152.273)
		(end 266.949936 -150.785068)
		(width 0.508)
		(layer "F.Cu")
		(net "PVDDQ_DEF")
	)
	(segment
		(start 255.84912 -139.170156)
		(end 255.89992 -139.119356)
		(width 0.4064)
		(layer "F.Cu")
		(net "PVDDQ_DEF")
	)
	(segment
		(start 269.499842 -142.6718)
		(end 269.499842 -141.187932)
		(width 0.508)
		(layer "F.Cu")
		(net "PVDDQ_DEF")
	)
	(segment
		(start 255.900428 -156.87294)
		(end 255.89992 -156.87294)
		(width 0.508)
		(layer "F.Cu")
		(net "PVDDQ_DEF")
	)
	(segment
		(start 248.249948 -154.252168)
		(end 248.446544 -154.252168)
		(width 0.4064)
		(layer "F.Cu")
		(net "PVDDQ_DEF")
	)
	(segment
		(start 257.64617 -89.765886)
		(end 257.07467 -89.765886)
		(width 0.254)
		(layer "F.Cu")
		(net "PVDDQ_DEF")
	)
	(segment
		(start 268.649958 -145.984468)
		(end 268.649958 -147.27174)
		(width 0.508)
		(layer "F.Cu")
		(net "PVDDQ_DEF")
	)
	(segment
		(start 268.649958 -156.87294)
		(end 268.650466 -156.87294)
		(width 0.508)
		(layer "F.Cu")
		(net "PVDDQ_DEF")
	)
	(segment
		(start 271.199864 -143.968978)
		(end 271.200372 -143.96847)
		(width 0.508)
		(layer "F.Cu")
		(net "PVDDQ_DEF")
	)
	(segment
		(start 256.78765 -97.19564)
		(end 256.21615 -97.19564)
		(width 0.254)
		(layer "F.Cu")
		(net "PVDDQ_DEF")
	)
	(segment
		(start 277.149814 -152.273)
		(end 277.149814 -154.252168)
		(width 0.508)
		(layer "F.Cu")
		(net "PVDDQ_DEF")
	)
	(segment
		(start 267.089636 -94.223586)
		(end 266.518136 -94.223586)
		(width 0.254)
		(layer "F.Cu")
		(net "PVDDQ_DEF")
	)
	(segment
		(start 249.10034 -156.87294)
		(end 249.099832 -156.87294)
		(width 0.508)
		(layer "F.Cu")
		(net "PVDDQ_DEF")
	)
	(segment
		(start 274.600416 -148.76907)
		(end 274.599908 -148.769578)
		(width 0.508)
		(layer "F.Cu")
		(net "PVDDQ_DEF")
	)
	(segment
		(start 253.350014 -133.0706)
		(end 253.350014 -131.611878)
		(width 0.508)
		(layer "F.Cu")
		(net "PVDDQ_DEF")
	)
	(segment
		(start 252.782324 -97.19564)
		(end 251.636784 -97.19564)
		(width 0.254)
		(layer "F.Cu")
		(net "PVDDQ_DEF")
	)
	(segment
		(start 243.999766 -152.273)
		(end 243.999766 -153.571956)
		(width 0.508)
		(layer "F.Cu")
		(net "PVDDQ_DEF")
	)
	(segment
		(start 256.78765 -100.167186)
		(end 257.07467 -99.67214)
		(width 0.254)
		(layer "F.Cu")
		(net "PVDDQ_DEF")
	)
	(segment
		(start 258.2672 -145.984468)
		(end 258.450334 -146.167602)
		(width 0.4064)
		(layer "F.Cu")
		(net "PVDDQ_DEF")
	)
	(segment
		(start 255.07061 -100.167186)
		(end 255.35763 -99.67214)
		(width 0.254)
		(layer "F.Cu")
		(net "PVDDQ_DEF")
	)
	(segment
		(start 277.149814 -139.168378)
		(end 277.149814 -137.67054)
		(width 0.508)
		(layer "F.Cu")
		(net "PVDDQ_DEF")
	)
	(segment
		(start 275.449792 -150.814278)
		(end 275.449792 -152.273)
		(width 0.508)
		(layer "F.Cu")
		(net "PVDDQ_DEF")
	)
	(segment
		(start 251.065284 -97.19564)
		(end 251.636784 -97.19564)
		(width 0.254)
		(layer "F.Cu")
		(net "PVDDQ_DEF")
	)
	(segment
		(start 261.93877 -94.223586)
		(end 261.36727 -94.223586)
		(width 0.254)
		(layer "F.Cu")
		(net "PVDDQ_DEF")
	)
	(segment
		(start 254.199898 -147.27174)
		(end 254.199898 -145.988278)
		(width 0.508)
		(layer "F.Cu")
		(net "PVDDQ_DEF")
	)
	(segment
		(start 255.89992 -133.076442)
		(end 255.89992 -134.351268)
		(width 0.508)
		(layer "F.Cu")
		(net "PVDDQ_DEF")
	)
	(segment
		(start 255.92913 -92.737686)
		(end 255.35763 -92.737686)
		(width 0.254)
		(layer "F.Cu")
		(net "PVDDQ_DEF")
	)
	(segment
		(start 255.909572 -136.328658)
		(end 255.909572 -136.322562)
		(width 0.508)
		(layer "F.Cu")
		(net "PVDDQ_DEF")
	)
	(segment
		(start 255.89992 -152.273)
		(end 255.89992 -150.999952)
		(width 0.508)
		(layer "F.Cu")
		(net "PVDDQ_DEF")
	)
	(segment
		(start 273.096482 -154.905456)
		(end 272.899886 -154.905456)
		(width 0.4064)
		(layer "F.Cu")
		(net "PVDDQ_DEF")
	)
	(segment
		(start 277.150322 -133.0706)
		(end 277.150322 -134.36727)
		(width 0.4064)
		(layer "F.Cu")
		(net "PVDDQ_DEF")
	)
	(segment
		(start 255.89992 -156.87294)
		(end 255.89992 -155.509468)
		(width 0.508)
		(layer "F.Cu")
		(net "PVDDQ_DEF")
	)
	(segment
		(start 350.110298 -155.613862)
		(end 350.404684 -155.908248)
		(width 0.254)
		(layer "F.Cu")
		(net "PVDDQ_DEF")
	)
	(segment
		(start 255.684782 -148.771356)
		(end 255.89992 -148.556218)
		(width 0.508)
		(layer "F.Cu")
		(net "PVDDQ_DEF")
	)
	(segment
		(start 275.4503 -133.0706)
		(end 275.4503 -131.612386)
		(width 0.4064)
		(layer "F.Cu")
		(net "PVDDQ_DEF")
	)
	(segment
		(start 254.200406 -147.27174)
		(end 254.199898 -147.27174)
		(width 0.508)
		(layer "F.Cu")
		(net "PVDDQ_DEF")
	)
	(segment
		(start 252.495304 -89.765886)
		(end 251.923804 -89.765886)
		(width 0.254)
		(layer "F.Cu")
		(net "PVDDQ_DEF")
	)
	(segment
		(start 246.550434 -156.87294)
		(end 246.549926 -156.87294)
		(width 0.508)
		(layer "F.Cu")
		(net "PVDDQ_DEF")
	)
	(segment
		(start 275.4503 -142.6718)
		(end 275.449792 -142.6718)
		(width 0.508)
		(layer "F.Cu")
		(net "PVDDQ_DEF")
	)
	(segment
		(start 258.449826 -139.149582)
		(end 258.449826 -137.67054)
		(width 0.4064)
		(layer "F.Cu")
		(net "PVDDQ_DEF")
	)
	(segment
		(start 251.649992 -156.87294)
		(end 251.649992 -155.564078)
		(width 0.508)
		(layer "F.Cu")
		(net "PVDDQ_DEF")
	)
	(segment
		(start 245.700296 -132.175504)
		(end 245.880636 -131.995164)
		(width 0.4064)
		(layer "F.Cu")
		(net "PVDDQ_DEF")
	)
	(segment
		(start 266.950444 -152.273)
		(end 266.949936 -152.273)
		(width 0.508)
		(layer "F.Cu")
		(net "PVDDQ_DEF")
	)
	(segment
		(start 275.449792 -141.188186)
		(end 275.4503 -141.187678)
		(width 0.508)
		(layer "F.Cu")
		(net "PVDDQ_DEF")
	)
	(segment
		(start 254.212344 -89.765886)
		(end 253.640844 -89.765886)
		(width 0.254)
		(layer "F.Cu")
		(net "PVDDQ_DEF")
	)
	(segment
		(start 274.600416 -137.67054)
		(end 274.599908 -137.67054)
		(width 0.508)
		(layer "F.Cu")
		(net "PVDDQ_DEF")
	)
	(segment
		(start 264.51433 -101.653086)
		(end 264.51433 -102.3112)
		(width 0.254)
		(layer "F.Cu")
		(net "PVDDQ_DEF")
	)
	(segment
		(start 260.50875 -89.765886)
		(end 261.08025 -89.765886)
		(width 0.254)
		(layer "F.Cu")
		(net "PVDDQ_DEF")
	)
	(segment
		(start 250.799854 -133.0706)
		(end 250.799854 -130.902456)
		(width 0.4064)
		(layer "F.Cu")
		(net "PVDDQ_DEF")
	)
	(segment
		(start 253.350014 -154.252168)
		(end 253.54661 -154.252168)
		(width 0.4064)
		(layer "F.Cu")
		(net "PVDDQ_DEF")
	)
	(segment
		(start 253.350014 -142.6718)
		(end 253.350014 -141.187678)
		(width 0.508)
		(layer "F.Cu")
		(net "PVDDQ_DEF")
	)
	(segment
		(start 277.150322 -133.0706)
		(end 277.150322 -131.586986)
		(width 0.4064)
		(layer "F.Cu")
		(net "PVDDQ_DEF")
	)
	(segment
		(start 266.95019 -143.972788)
		(end 266.950444 -143.972534)
		(width 0.508)
		(layer "F.Cu")
		(net "PVDDQ_DEF")
	)
	(segment
		(start 266.950444 -143.972534)
		(end 266.950444 -142.6718)
		(width 0.508)
		(layer "F.Cu")
		(net "PVDDQ_DEF")
	)
	(segment
		(start 277.149814 -147.27174)
		(end 277.149814 -148.769578)
		(width 0.508)
		(layer "F.Cu")
		(net "PVDDQ_DEF")
	)
	(segment
		(start 271.199864 -142.6718)
		(end 271.199864 -141.183868)
		(width 0.508)
		(layer "F.Cu")
		(net "PVDDQ_DEF")
	)
	(segment
		(start 245.700296 -141.188186)
		(end 245.699788 -141.187678)
		(width 0.508)
		(layer "F.Cu")
		(net "PVDDQ_DEF")
	)
	(segment
		(start 272.900394 -137.67054)
		(end 272.899886 -137.67054)
		(width 0.508)
		(layer "F.Cu")
		(net "PVDDQ_DEF")
	)
	(segment
		(start 244.000274 -142.6718)
		(end 244.000274 -143.970248)
		(width 0.508)
		(layer "F.Cu")
		(net "PVDDQ_DEF")
	)
	(segment
		(start 248.249948 -133.0706)
		(end 248.249948 -131.611878)
		(width 0.508)
		(layer "F.Cu")
		(net "PVDDQ_DEF")
	)
	(segment
		(start 266.949682 -152.279096)
		(end 266.949936 -152.278842)
		(width 0.508)
		(layer "F.Cu")
		(net "PVDDQ_DEF")
	)
	(segment
		(start 269.499842 -152.273)
		(end 269.499842 -153.571956)
		(width 0.508)
		(layer "F.Cu")
		(net "PVDDQ_DEF")
	)
	(segment
		(start 250.800362 -133.0706)
		(end 250.799854 -133.0706)
		(width 0.4064)
		(layer "F.Cu")
		(net "PVDDQ_DEF")
	)
	(segment
		(start 259.65023 -94.223586)
		(end 260.22173 -94.223586)
		(width 0.254)
		(layer "F.Cu")
		(net "PVDDQ_DEF")
	)
	(segment
		(start 248.250456 -143.970248)
		(end 248.249948 -143.970756)
		(width 0.508)
		(layer "F.Cu")
		(net "PVDDQ_DEF")
	)
	(segment
		(start 269.50035 -132.28955)
		(end 269.2908 -132.08)
		(width 0.4064)
		(layer "F.Cu")
		(net "PVDDQ_DEF")
	)
	(segment
		(start 251.649992 -136.387078)
		(end 251.649992 -137.67054)
		(width 0.508)
		(layer "F.Cu")
		(net "PVDDQ_DEF")
	)
	(segment
		(start 254.199898 -148.773388)
		(end 254.199898 -147.27174)
		(width 0.508)
		(layer "F.Cu")
		(net "PVDDQ_DEF")
	)
	(segment
		(start 277.150322 -142.6718)
		(end 277.149814 -142.6718)
		(width 0.508)
		(layer "F.Cu")
		(net "PVDDQ_DEF")
	)
	(segment
		(start 273.74977 -152.273)
		(end 273.74977 -154.252168)
		(width 0.508)
		(layer "F.Cu")
		(net "PVDDQ_DEF")
	)
	(segment
		(start 258.3942 -136.1948)
		(end 258.449826 -136.250426)
		(width 0.4064)
		(layer "F.Cu")
		(net "PVDDQ_DEF")
	)
	(segment
		(start 251.6505 -156.87294)
		(end 251.649992 -156.87294)
		(width 0.508)
		(layer "F.Cu")
		(net "PVDDQ_DEF")
	)
	(segment
		(start 271.199864 -153.542746)
		(end 271.199864 -152.273)
		(width 0.508)
		(layer "F.Cu")
		(net "PVDDQ_DEF")
	)
	(segment
		(start 349.741998 -155.613862)
		(end 350.110298 -155.613862)
		(width 0.254)
		(layer "F.Cu")
		(net "PVDDQ_DEF")
	)
	(segment
		(start 255.89992 -147.27174)
		(end 255.89992 -145.984468)
		(width 0.508)
		(layer "F.Cu")
		(net "PVDDQ_DEF")
	)
	(segment
		(start 266.099798 -137.67054)
		(end 266.099798 -139.168378)
		(width 0.508)
		(layer "F.Cu")
		(net "PVDDQ_DEF")
	)
	(segment
		(start 277.150322 -131.586986)
		(end 277.149814 -131.586478)
		(width 0.4064)
		(layer "F.Cu")
		(net "PVDDQ_DEF")
	)
	(segment
		(start 244.000274 -141.188186)
		(end 243.999766 -141.187678)
		(width 0.508)
		(layer "F.Cu")
		(net "PVDDQ_DEF")
	)
	(segment
		(start 249.099832 -136.387078)
		(end 249.099832 -137.67054)
		(width 0.508)
		(layer "F.Cu")
		(net "PVDDQ_DEF")
	)
	(segment
		(start 258.449826 -136.250426)
		(end 258.449826 -137.67054)
		(width 0.4064)
		(layer "F.Cu")
		(net "PVDDQ_DEF")
	)
	(segment
		(start 272.899886 -139.168378)
		(end 272.899886 -137.67054)
		(width 0.508)
		(layer "F.Cu")
		(net "PVDDQ_DEF")
	)
	(segment
		(start 274.600416 -147.27174)
		(end 274.600416 -148.76907)
		(width 0.508)
		(layer "F.Cu")
		(net "PVDDQ_DEF")
	)
	(segment
		(start 243.999766 -150.788878)
		(end 243.999766 -152.273)
		(width 0.508)
		(layer "F.Cu")
		(net "PVDDQ_DEF")
	)
	(segment
		(start 255.89992 -142.6718)
		(end 255.89992 -141.18717)
		(width 0.508)
		(layer "F.Cu")
		(net "PVDDQ_DEF")
	)
	(segment
		(start 274.599908 -139.168378)
		(end 274.599908 -137.67054)
		(width 0.508)
		(layer "F.Cu")
		(net "PVDDQ_DEF")
	)
	(segment
		(start 268.649958 -155.615132)
		(end 268.649958 -156.87294)
		(width 0.508)
		(layer "F.Cu")
		(net "PVDDQ_DEF")
	)
	(segment
		(start 255.07061 -97.19564)
		(end 254.49911 -97.19564)
		(width 0.254)
		(layer "F.Cu")
		(net "PVDDQ_DEF")
	)
	(segment
		(start 271.200372 -156.87294)
		(end 271.199864 -156.87294)
		(width 0.508)
		(layer "F.Cu")
		(net "PVDDQ_DEF")
	)
	(segment
		(start 244.850412 -156.87294)
		(end 244.849904 -156.87294)
		(width 0.508)
		(layer "F.Cu")
		(net "PVDDQ_DEF")
	)
	(segment
		(start 258.450334 -142.6718)
		(end 258.450334 -143.787622)
		(width 0.508)
		(layer "F.Cu")
		(net "PVDDQ_DEF")
	)
	(segment
		(start 273.750278 -152.273)
		(end 273.74977 -152.273)
		(width 0.508)
		(layer "F.Cu")
		(net "PVDDQ_DEF")
	)
	(segment
		(start 258.3942 -139.170156)
		(end 258.414774 -139.149582)
		(width 0.4064)
		(layer "F.Cu")
		(net "PVDDQ_DEF")
	)
	(segment
		(start 243.999766 -133.076442)
		(end 243.999766 -133.0706)
		(width 0.4064)
		(layer "F.Cu")
		(net "PVDDQ_DEF")
	)
	(segment
		(start 271.200372 -143.96847)
		(end 271.200372 -142.6718)
		(width 0.508)
		(layer "F.Cu")
		(net "PVDDQ_DEF")
	)
	(segment
		(start 269.50035 -133.0706)
		(end 269.50035 -132.28955)
		(width 0.4064)
		(layer "F.Cu")
		(net "PVDDQ_DEF")
	)
	(segment
		(start 245.699788 -152.273)
		(end 245.699788 -153.571956)
		(width 0.508)
		(layer "F.Cu")
		(net "PVDDQ_DEF")
	)
	(segment
		(start 261.08025 -101.653086)
		(end 261.08025 -102.3112)
		(width 0.254)
		(layer "F.Cu")
		(net "PVDDQ_DEF")
	)
	(segment
		(start 274.600416 -147.27174)
		(end 274.599908 -147.27174)
		(width 0.508)
		(layer "F.Cu")
		(net "PVDDQ_DEF")
	)
	(segment
		(start 250.800362 -152.273)
		(end 250.799854 -152.273)
		(width 0.508)
		(layer "F.Cu")
		(net "PVDDQ_DEF")
	)
	(segment
		(start 265.372596 -100.167186)
		(end 264.801096 -99.17684)
		(width 0.254)
		(layer "F.Cu")
		(net "PVDDQ_DEF")
	)
	(segment
		(start 255.89992 -136.31291)
		(end 255.89992 -137.67054)
		(width 0.508)
		(layer "F.Cu")
		(net "PVDDQ_DEF")
	)
	(segment
		(start 258.450334 -146.167602)
		(end 258.450334 -147.27174)
		(width 0.4064)
		(layer "F.Cu")
		(net "PVDDQ_DEF")
	)
	(segment
		(start 258.449826 -150.785068)
		(end 258.449826 -152.273)
		(width 0.508)
		(layer "F.Cu")
		(net "PVDDQ_DEF")
	)
	(segment
		(start 261.747 -129.859024)
		(end 262.255 -130.367024)
		(width 0.508)
		(layer "F.Cu")
		(net "PVDDQ_DEF")
	)
	(segment
		(start 251.6505 -137.67054)
		(end 251.649992 -137.67054)
		(width 0.508)
		(layer "F.Cu")
		(net "PVDDQ_DEF")
	)
	(segment
		(start 248.250456 -133.0706)
		(end 248.249948 -133.0706)
		(width 0.508)
		(layer "F.Cu")
		(net "PVDDQ_DEF")
	)
	(segment
		(start 277.150322 -134.36727)
		(end 277.149814 -134.367778)
		(width 0.4064)
		(layer "F.Cu")
		(net "PVDDQ_DEF")
	)
	(segment
		(start 266.100306 -147.27174)
		(end 266.100306 -148.76907)
		(width 0.508)
		(layer "F.Cu")
		(net "PVDDQ_DEF")
	)
	(segment
		(start 255.07061 -94.223586)
		(end 254.49911 -94.223586)
		(width 0.254)
		(layer "F.Cu")
		(net "PVDDQ_DEF")
	)
	(segment
		(start 255.89992 -139.119356)
		(end 255.89992 -137.67054)
		(width 0.508)
		(layer "F.Cu")
		(net "PVDDQ_DEF")
	)
	(segment
		(start 245.700296 -143.970248)
		(end 245.700296 -142.6718)
		(width 0.508)
		(layer "F.Cu")
		(net "PVDDQ_DEF")
	)
	(segment
		(start 245.699788 -150.788878)
		(end 245.699788 -152.273)
		(width 0.508)
		(layer "F.Cu")
		(net "PVDDQ_DEF")
	)
	(segment
		(start 261.93877 -97.19564)
		(end 261.36727 -97.19564)
		(width 0.254)
		(layer "F.Cu")
		(net "PVDDQ_DEF")
	)
	(segment
		(start 255.89992 -150.999952)
		(end 255.685036 -150.785068)
		(width 0.508)
		(layer "F.Cu")
		(net "PVDDQ_DEF")
	)
	(segment
		(start 244.849904 -139.170156)
		(end 244.849904 -137.67054)
		(width 0.508)
		(layer "F.Cu")
		(net "PVDDQ_DEF")
	)
	(segment
		(start 258.450334 -155.575508)
		(end 258.450334 -156.87294)
		(width 0.4572)
		(layer "F.Cu")
		(net "PVDDQ_DEF")
	)
	(segment
		(start 266.099798 -145.988278)
		(end 266.099798 -147.27174)
		(width 0.508)
		(layer "F.Cu")
		(net "PVDDQ_DEF")
	)
	(segment
		(start 250.799854 -150.788878)
		(end 250.799854 -152.273)
		(width 0.508)
		(layer "F.Cu")
		(net "PVDDQ_DEF")
	)
	(segment
		(start 249.099832 -156.87294)
		(end 249.099832 -154.905456)
		(width 0.508)
		(layer "F.Cu")
		(net "PVDDQ_DEF")
	)
	(segment
		(start 272.899886 -156.87294)
		(end 272.899886 -154.905456)
		(width 0.508)
		(layer "F.Cu")
		(net "PVDDQ_DEF")
	)
	(segment
		(start 271.199864 -137.67054)
		(end 271.199864 -136.383268)
		(width 0.508)
		(layer "F.Cu")
		(net "PVDDQ_DEF")
	)
	(segment
		(start 249.10034 -147.27174)
		(end 249.099832 -147.27174)
		(width 0.508)
		(layer "F.Cu")
		(net "PVDDQ_DEF")
	)
	(segment
		(start 275.4503 -142.6718)
		(end 275.4503 -143.972788)
		(width 0.508)
		(layer "F.Cu")
		(net "PVDDQ_DEF")
	)
	(segment
		(start 269.50035 -134.371334)
		(end 269.500096 -134.371588)
		(width 0.4064)
		(layer "F.Cu")
		(net "PVDDQ_DEF")
	)
	(segment
		(start 273.74977 -152.273)
		(end 273.74977 -150.789386)
		(width 0.508)
		(layer "F.Cu")
		(net "PVDDQ_DEF")
	)
	(segment
		(start 253.350014 -143.972788)
		(end 253.350014 -142.6718)
		(width 0.508)
		(layer "F.Cu")
		(net "PVDDQ_DEF")
	)
	(segment
		(start 258.449826 -137.67054)
		(end 258.450334 -137.67054)
		(width 0.4064)
		(layer "F.Cu")
		(net "PVDDQ_DEF")
	)
	(segment
		(start 271.200372 -147.27174)
		(end 271.199864 -147.27174)
		(width 0.508)
		(layer "F.Cu")
		(net "PVDDQ_DEF")
	)
	(segment
		(start 350.279462 -147.793456)
		(end 350.175068 -147.689062)
		(width 0.254)
		(layer "F.Cu")
		(net "PVDDQ_DEF")
	)
	(segment
		(start 277.149814 -156.87294)
		(end 277.149814 -155.589478)
		(width 0.508)
		(layer "F.Cu")
		(net "PVDDQ_DEF")
	)
	(segment
		(start 269.499842 -152.273)
		(end 269.499842 -150.789132)
		(width 0.508)
		(layer "F.Cu")
		(net "PVDDQ_DEF")
	)
	(segment
		(start 255.900428 -147.27174)
		(end 255.89992 -147.27174)
		(width 0.508)
		(layer "F.Cu")
		(net "PVDDQ_DEF")
	)
	(segment
		(start 259.36321 -89.765886)
		(end 258.79171 -89.765886)
		(width 0.254)
		(layer "F.Cu")
		(net "PVDDQ_DEF")
	)
	(segment
		(start 266.950444 -131.61264)
		(end 266.949682 -131.611878)
		(width 0.4064)
		(layer "F.Cu")
		(net "PVDDQ_DEF")
	)
	(segment
		(start 258.699 -99.83216)
		(end 258.79171 -99.67214)
		(width 0.254)
		(layer "F.Cu")
		(net "PVDDQ_DEF")
	)
	(segment
		(start 258.272026 -140.339826)
		(end 258.272026 -141.183868)
		(width 0.508)
		(layer "F.Cu")
		(net "PVDDQ_DEF")
	)
	(segment
		(start 246.549926 -145.988278)
		(end 246.549926 -147.27174)
		(width 0.508)
		(layer "F.Cu")
		(net "PVDDQ_DEF")
	)
	(segment
		(start 245.700296 -142.6718)
		(end 245.700296 -141.188186)
		(width 0.508)
		(layer "F.Cu")
		(net "PVDDQ_DEF")
	)
	(segment
		(start 271.199864 -133.076442)
		(end 271.199864 -134.367778)
		(width 0.508)
		(layer "F.Cu")
		(net "PVDDQ_DEF")
	)
	(segment
		(start 250.799854 -152.273)
		(end 250.799854 -153.542746)
		(width 0.508)
		(layer "F.Cu")
		(net "PVDDQ_DEF")
	)
	(segment
		(start 246.550434 -147.27174)
		(end 246.549926 -147.27174)
		(width 0.508)
		(layer "F.Cu")
		(net "PVDDQ_DEF")
	)
	(segment
		(start 258.450334 -141.71168)
		(end 258.272026 -141.533372)
		(width 0.508)
		(layer "F.Cu")
		(net "PVDDQ_DEF")
	)
	(segment
		(start 350.175068 -147.689062)
		(end 349.741998 -147.689062)
		(width 0.254)
		(layer "F.Cu")
		(net "PVDDQ_DEF")
	)
	(segment
		(start 266.099798 -156.87294)
		(end 266.099798 -154.905456)
		(width 0.508)
		(layer "F.Cu")
		(net "PVDDQ_DEF")
	)
	(segment
		(start 268.650466 -147.27174)
		(end 268.649958 -147.27174)
		(width 0.508)
		(layer "F.Cu")
		(net "PVDDQ_DEF")
	)
	(segment
		(start 268.649958 -147.27174)
		(end 268.649958 -148.769578)
		(width 0.508)
		(layer "F.Cu")
		(net "PVDDQ_DEF")
	)
	(segment
		(start 255.900428 -142.6718)
		(end 255.89992 -142.6718)
		(width 0.508)
		(layer "F.Cu")
		(net "PVDDQ_DEF")
	)
	(segment
		(start 265.372596 -94.223586)
		(end 264.801096 -94.223586)
		(width 0.254)
		(layer "F.Cu")
		(net "PVDDQ_DEF")
	)
	(segment
		(start 271.199864 -152.273)
		(end 271.199864 -150.785068)
		(width 0.508)
		(layer "F.Cu")
		(net "PVDDQ_DEF")
	)
	(segment
		(start 243.999766 -134.369556)
		(end 243.999766 -133.076442)
		(width 0.508)
		(layer "F.Cu")
		(net "PVDDQ_DEF")
	)
	(segment
		(start 244.849904 -145.988278)
		(end 244.849904 -147.27174)
		(width 0.508)
		(layer "F.Cu")
		(net "PVDDQ_DEF")
	)
	(segment
		(start 269.499842 -141.187932)
		(end 269.500096 -141.187678)
		(width 0.508)
		(layer "F.Cu")
		(net "PVDDQ_DEF")
	)
	(segment
		(start 254.199898 -137.67054)
		(end 254.199898 -139.172188)
		(width 0.508)
		(layer "F.Cu")
		(net "PVDDQ_DEF")
	)
	(segment
		(start 245.700296 -133.0706)
		(end 245.700296 -134.369048)
		(width 0.4064)
		(layer "F.Cu")
		(net "PVDDQ_DEF")
	)
	(segment
		(start 271.199864 -156.87294)
		(end 271.199864 -154.905456)
		(width 0.508)
		(layer "F.Cu")
		(net "PVDDQ_DEF")
	)
	(segment
		(start 269.50035 -152.273)
		(end 269.499842 -152.273)
		(width 0.508)
		(layer "F.Cu")
		(net "PVDDQ_DEF")
	)
	(segment
		(start 244.849904 -156.87294)
		(end 244.849904 -155.564078)
		(width 0.508)
		(layer "F.Cu")
		(net "PVDDQ_DEF")
	)
	(segment
		(start 272.900394 -147.27174)
		(end 272.900394 -148.76907)
		(width 0.508)
		(layer "F.Cu")
		(net "PVDDQ_DEF")
	)
	(segment
		(start 266.296394 -154.905456)
		(end 266.099798 -154.905456)
		(width 0.4064)
		(layer "F.Cu")
		(net "PVDDQ_DEF")
	)
	(segment
		(start 244.000274 -142.6718)
		(end 244.000274 -141.188186)
		(width 0.508)
		(layer "F.Cu")
		(net "PVDDQ_DEF")
	)
	(segment
		(start 255.900428 -133.0706)
		(end 255.89992 -133.076442)
		(width 0.508)
		(layer "F.Cu")
		(net "PVDDQ_DEF")
	)
	(segment
		(start 271.200372 -133.0706)
		(end 271.199864 -133.076442)
		(width 0.508)
		(layer "F.Cu")
		(net "PVDDQ_DEF")
	)
	(segment
		(start 269.50035 -143.972534)
		(end 269.50035 -142.6718)
		(width 0.508)
		(layer "F.Cu")
		(net "PVDDQ_DEF")
	)
	(segment
		(start 258.064 -140.1318)
		(end 258.272026 -140.339826)
		(width 0.508)
		(layer "F.Cu")
		(net "PVDDQ_DEF")
	)
	(segment
		(start 275.449792 -154.252168)
		(end 274.796504 -154.905456)
		(width 0.4064)
		(layer "F.Cu")
		(net "PVDDQ_DEF")
	)
	(segment
		(start 264.51433 -92.737686)
		(end 263.94283 -92.737686)
		(width 0.254)
		(layer "F.Cu")
		(net "PVDDQ_DEF")
	)
	(segment
		(start 250.800362 -143.970248)
		(end 250.799854 -143.970756)
		(width 0.508)
		(layer "F.Cu")
		(net "PVDDQ_DEF")
	)
	(segment
		(start 275.4503 -152.273)
		(end 275.449792 -152.273)
		(width 0.508)
		(layer "F.Cu")
		(net "PVDDQ_DEF")
	)
	(segment
		(start 258.450334 -133.0706)
		(end 258.449826 -133.076442)
		(width 0.4064)
		(layer "F.Cu")
		(net "PVDDQ_DEF")
	)
	(segment
		(start 253.350522 -142.6718)
		(end 253.350014 -142.6718)
		(width 0.508)
		(layer "F.Cu")
		(net "PVDDQ_DEF")
	)
	(segment
		(start 244.551454 -125.88113)
		(end 244.551454 -126.401576)
		(width 0.4064)
		(layer "F.Cu")
		(net "PVDDQ_DEF")
	)
	(segment
		(start 275.449792 -142.6718)
		(end 275.449792 -141.188186)
		(width 0.508)
		(layer "F.Cu")
		(net "PVDDQ_DEF")
	)
	(segment
		(start 272.900394 -147.27174)
		(end 272.899886 -147.27174)
		(width 0.508)
		(layer "F.Cu")
		(net "PVDDQ_DEF")
	)
	(segment
		(start 271.200372 -142.6718)
		(end 271.199864 -142.6718)
		(width 0.508)
		(layer "F.Cu")
		(net "PVDDQ_DEF")
	)
	(segment
		(start 267.948156 -101.653086)
		(end 268.268704 -102.227634)
		(width 0.254)
		(layer "F.Cu")
		(net "PVDDQ_DEF")
	)
	(segment
		(start 254.199898 -156.87294)
		(end 254.199898 -154.905456)
		(width 0.508)
		(layer "F.Cu")
		(net "PVDDQ_DEF")
	)
	(segment
		(start 255.92913 -101.653086)
		(end 255.92913 -102.3112)
		(width 0.254)
		(layer "F.Cu")
		(net "PVDDQ_DEF")
	)
	(segment
		(start 245.699788 -143.970756)
		(end 245.700296 -143.970248)
		(width 0.508)
		(layer "F.Cu")
		(net "PVDDQ_DEF")
	)
	(segment
		(start 273.750278 -142.6718)
		(end 273.74977 -142.6718)
		(width 0.508)
		(layer "F.Cu")
		(net "PVDDQ_DEF")
	)
	(segment
		(start 255.909572 -136.322562)
		(end 255.89992 -136.31291)
		(width 0.508)
		(layer "F.Cu")
		(net "PVDDQ_DEF")
	)
	(segment
		(start 253.350522 -133.0706)
		(end 253.350014 -133.0706)
		(width 0.508)
		(layer "F.Cu")
		(net "PVDDQ_DEF")
	)
	(segment
		(start 277.150322 -147.27174)
		(end 277.149814 -147.27174)
		(width 0.508)
		(layer "F.Cu")
		(net "PVDDQ_DEF")
	)
	(segment
		(start 254.200406 -137.67054)
		(end 254.199898 -137.67054)
		(width 0.508)
		(layer "F.Cu")
		(net "PVDDQ_DEF")
	)
	(segment
		(start 274.599908 -137.67054)
		(end 274.599908 -136.383268)
		(width 0.508)
		(layer "F.Cu")
		(net "PVDDQ_DEF")
	)
	(segment
		(start 273.74977 -142.6718)
		(end 273.74977 -141.188186)
		(width 0.508)
		(layer "F.Cu")
		(net "PVDDQ_DEF")
	)
	(segment
		(start 250.799854 -133.076442)
		(end 250.799854 -133.0706)
		(width 0.4064)
		(layer "F.Cu")
		(net "PVDDQ_DEF")
	)
	(segment
		(start 248.249948 -154.252168)
		(end 248.249948 -152.273)
		(width 0.508)
		(layer "F.Cu")
		(net "PVDDQ_DEF")
	)
	(segment
		(start 245.880636 -131.083304)
		(end 245.699788 -130.902456)
		(width 0.4064)
		(layer "F.Cu")
		(net "PVDDQ_DEF")
	)
	(segment
		(start 258.450334 -143.787622)
		(end 258.2672 -143.970756)
		(width 0.508)
		(layer "F.Cu")
		(net "PVDDQ_DEF")
	)
	(segment
		(start 269.50035 -133.0706)
		(end 269.50035 -134.371334)
		(width 0.4064)
		(layer "F.Cu")
		(net "PVDDQ_DEF")
	)
	(segment
		(start 266.950444 -133.0706)
		(end 266.950444 -134.371334)
		(width 0.4064)
		(layer "F.Cu")
		(net "PVDDQ_DEF")
	)
	(segment
		(start 268.806676 -101.689662)
		(end 268.806676 -101.15804)
		(width 0.254)
		(layer "F.Cu")
		(net "PVDDQ_DEF")
	)
	(segment
		(start 273.74977 -154.252168)
		(end 273.096482 -154.905456)
		(width 0.4064)
		(layer "F.Cu")
		(net "PVDDQ_DEF")
	)
	(segment
		(start 244.850412 -147.27174)
		(end 244.849904 -147.27174)
		(width 0.508)
		(layer "F.Cu")
		(net "PVDDQ_DEF")
	)
	(segment
		(start 277.150322 -156.87294)
		(end 277.149814 -156.87294)
		(width 0.508)
		(layer "F.Cu")
		(net "PVDDQ_DEF")
	)
	(segment
		(start 268.268704 -102.227634)
		(end 268.806676 -101.689662)
		(width 0.254)
		(layer "F.Cu")
		(net "PVDDQ_DEF")
	)
	(segment
		(start 271.199864 -154.905456)
		(end 271.199864 -153.542746)
		(width 0.4064)
		(layer "F.Cu")
		(net "PVDDQ_DEF")
	)
	(segment
		(start 259.65023 -97.19564)
		(end 260.22173 -97.19564)
		(width 0.254)
		(layer "F.Cu")
		(net "PVDDQ_DEF")
	)
	(segment
		(start 266.949682 -154.252168)
		(end 266.296394 -154.905456)
		(width 0.4064)
		(layer "F.Cu")
		(net "PVDDQ_DEF")
	)
	(segment
		(start 266.231116 -92.737686)
		(end 265.659616 -92.737686)
		(width 0.254)
		(layer "F.Cu")
		(net "PVDDQ_DEF")
	)
	(segment
		(start 258.50469 -94.223586)
		(end 257.93319 -94.223586)
		(width 0.254)
		(layer "F.Cu")
		(net "PVDDQ_DEF")
	)
	(segment
		(start 251.636784 -93.23324)
		(end 251.065284 -93.23324)
		(width 0.254)
		(layer "F.Cu")
		(net "PVDDQ_DEF")
	)
	(segment
		(start 350.404684 -155.908248)
		(end 350.404684 -156.076904)
		(width 0.254)
		(layer "F.Cu")
		(net "PVDDQ_DEF")
	)
	(segment
		(start 271.199864 -139.168378)
		(end 271.199864 -137.67054)
		(width 0.508)
		(layer "F.Cu")
		(net "PVDDQ_DEF")
	)
	(segment
		(start 248.446544 -154.252168)
		(end 249.099832 -154.905456)
		(width 0.4064)
		(layer "F.Cu")
		(net "PVDDQ_DEF")
	)
	(segment
		(start 266.949682 -154.252168)
		(end 266.949682 -152.279096)
		(width 0.508)
		(layer "F.Cu")
		(net "PVDDQ_DEF")
	)
	(segment
		(start 258.449826 -152.273)
		(end 258.449826 -153.571956)
		(width 0.508)
		(layer "F.Cu")
		(net "PVDDQ_DEF")
	)
	(segment
		(start 273.74977 -141.188186)
		(end 273.750278 -141.187678)
		(width 0.508)
		(layer "F.Cu")
		(net "PVDDQ_DEF")
	)
	(via
		(at 246.549926 -145.988278)
		(size 0.508)
		(drill 0.254)
		(layers "F.Cu" "B.Cu")
		(net "PVDDQ_DEF")
	)
	(via
		(at 269.500096 -134.371588)
		(size 0.4572)
		(drill 0.2032)
		(layers "F.Cu" "B.Cu")
		(net "PVDDQ_DEF")
	)
	(via
		(at 245.699788 -141.187678)
		(size 0.508)
		(drill 0.254)
		(layers "F.Cu" "B.Cu")
		(net "PVDDQ_DEF")
	)
	(via
		(at 277.149814 -141.183868)
		(size 0.508)
		(drill 0.254)
		(layers "F.Cu" "B.Cu")
		(net "PVDDQ_DEF")
	)
	(via
		(at 251.065284 -93.23324)
		(size 0.508)
		(drill 0.254)
		(layers "F.Cu" "B.Cu")
		(net "PVDDQ_DEF")
	)
	(via
		(at 275.4503 -134.371588)
		(size 0.4572)
		(drill 0.2032)
		(layers "F.Cu" "B.Cu")
		(net "PVDDQ_DEF")
	)
	(via
		(at 263.08431 -97.19564)
		(size 0.508)
		(drill 0.254)
		(layers "F.Cu" "B.Cu")
		(net "PVDDQ_DEF")
	)
	(via
		(at 249.099832 -139.170156)
		(size 0.508)
		(drill 0.254)
		(layers "F.Cu" "B.Cu")
		(net "PVDDQ_DEF")
	)
	(via
		(at 333.248 -145.1356)
		(size 0.508)
		(drill 0.254)
		(layers "F.Cu" "B.Cu")
		(net "PVDDQ_DEF")
	)
	(via
		(at 273.750278 -143.972788)
		(size 0.4572)
		(drill 0.2032)
		(layers "F.Cu" "B.Cu")
		(net "PVDDQ_DEF")
	)
	(via
		(at 271.199864 -153.542746)
		(size 0.508)
		(drill 0.254)
		(layers "F.Cu" "B.Cu")
		(net "PVDDQ_DEF")
	)
	(via
		(at 269.500096 -143.972788)
		(size 0.4572)
		(drill 0.2032)
		(layers "F.Cu" "B.Cu")
		(net "PVDDQ_DEF")
	)
	(via
		(at 255.84912 -139.170156)
		(size 0.508)
		(drill 0.254)
		(layers "F.Cu" "B.Cu")
		(net "PVDDQ_DEF")
	)
	(via
		(at 266.949682 -131.611878)
		(size 0.508)
		(drill 0.254)
		(layers "F.Cu" "B.Cu")
		(net "PVDDQ_DEF")
	)
	(via
		(at 330.962 -145.1356)
		(size 0.508)
		(drill 0.254)
		(layers "F.Cu" "B.Cu")
		(net "PVDDQ_DEF")
	)
	(via
		(at 249.099832 -136.387078)
		(size 0.508)
		(drill 0.254)
		(layers "F.Cu" "B.Cu")
		(net "PVDDQ_DEF")
	)
	(via
		(at 330.962 -143.1036)
		(size 0.508)
		(drill 0.254)
		(layers "F.Cu" "B.Cu")
		(net "PVDDQ_DEF")
	)
	(via
		(at 258.3942 -136.1948)
		(size 0.508)
		(drill 0.254)
		(layers "F.Cu" "B.Cu")
		(net "PVDDQ_DEF")
	)
	(via
		(at 257.93319 -97.19564)
		(size 0.508)
		(drill 0.254)
		(layers "F.Cu" "B.Cu")
		(net "PVDDQ_DEF")
	)
	(via
		(at 336.169 -141.8336)
		(size 0.508)
		(drill 0.254)
		(layers "F.Cu" "B.Cu")
		(net "PVDDQ_DEF")
	)
	(via
		(at 180.848 -152.273)
		(size 0.508)
		(drill 0.254)
		(layers "F.Cu" "B.Cu")
		(net "PVDDQ_DEF")
	)
	(via
		(at 266.892024 -85.938614)
		(size 0.508)
		(drill 0.254)
		(layers "F.Cu" "B.Cu")
		(net "PVDDQ_DEF")
	)
	(via
		(at 258.184142 -130.848608)
		(size 0.508)
		(drill 0.254)
		(layers "F.Cu" "B.Cu")
		(net "PVDDQ_DEF")
	)
	(via
		(at 335.407 -141.8336)
		(size 0.508)
		(drill 0.254)
		(layers "F.Cu" "B.Cu")
		(net "PVDDQ_DEF")
	)
	(via
		(at 271.199864 -145.984468)
		(size 0.508)
		(drill 0.254)
		(layers "F.Cu" "B.Cu")
		(net "PVDDQ_DEF")
	)
	(via
		(at 246.549926 -155.564078)
		(size 0.508)
		(drill 0.254)
		(layers "F.Cu" "B.Cu")
		(net "PVDDQ_DEF")
	)
	(via
		(at 350.74606 -156.41828)
		(size 0.508)
		(drill 0.254)
		(layers "F.Cu" "B.Cu")
		(net "PVDDQ_DEF")
	)
	(via
		(at 271.199864 -129.539746)
		(size 0.508)
		(drill 0.254)
		(layers "F.Cu" "B.Cu")
		(net "PVDDQ_DEF")
	)
	(via
		(at 273.629628 -85.987382)
		(size 0.5588)
		(drill 0.3048)
		(layers "F.Cu" "B.Cu")
		(net "PVDDQ_DEF")
	)
	(via
		(at 250.799854 -143.970756)
		(size 0.508)
		(drill 0.254)
		(layers "F.Cu" "B.Cu")
		(net "PVDDQ_DEF")
	)
	(via
		(at 254.199898 -145.988278)
		(size 0.508)
		(drill 0.254)
		(layers "F.Cu" "B.Cu")
		(net "PVDDQ_DEF")
	)
	(via
		(at 336.3468 -151.7904)
		(size 0.508)
		(drill 0.254)
		(layers "F.Cu" "B.Cu")
		(net "PVDDQ_DEF")
	)
	(via
		(at 332.486 -143.1036)
		(size 0.508)
		(drill 0.254)
		(layers "F.Cu" "B.Cu")
		(net "PVDDQ_DEF")
	)
	(via
		(at 331.724 -147.066)
		(size 0.508)
		(drill 0.254)
		(layers "F.Cu" "B.Cu")
		(net "PVDDQ_DEF")
	)
	(via
		(at 272.899886 -136.383268)
		(size 0.508)
		(drill 0.254)
		(layers "F.Cu" "B.Cu")
		(net "PVDDQ_DEF")
	)
	(via
		(at 245.699788 -130.902456)
		(size 0.508)
		(drill 0.254)
		(layers "F.Cu" "B.Cu")
		(net "PVDDQ_DEF")
	)
	(via
		(at 333.2734 -152.654)
		(size 0.508)
		(drill 0.254)
		(layers "F.Cu" "B.Cu")
		(net "PVDDQ_DEF")
	)
	(via
		(at 336.296 -145.1356)
		(size 0.508)
		(drill 0.254)
		(layers "F.Cu" "B.Cu")
		(net "PVDDQ_DEF")
	)
	(via
		(at 335.5594 -152.654)
		(size 0.508)
		(drill 0.254)
		(layers "F.Cu" "B.Cu")
		(net "PVDDQ_DEF")
	)
	(via
		(at 334.01 -145.1356)
		(size 0.508)
		(drill 0.254)
		(layers "F.Cu" "B.Cu")
		(net "PVDDQ_DEF")
	)
	(via
		(at 330.2 -141.8336)
		(size 0.508)
		(drill 0.254)
		(layers "F.Cu" "B.Cu")
		(net "PVDDQ_DEF")
	)
	(via
		(at 256.165604 -129.568956)
		(size 0.508)
		(drill 0.254)
		(layers "F.Cu" "B.Cu")
		(net "PVDDQ_DEF")
	)
	(via
		(at 265.659616 -92.737686)
		(size 0.508)
		(drill 0.254)
		(layers "F.Cu" "B.Cu")
		(net "PVDDQ_DEF")
	)
	(via
		(at 249.099832 -154.905456)
		(size 0.508)
		(drill 0.254)
		(layers "F.Cu" "B.Cu")
		(net "PVDDQ_DEF")
	)
	(via
		(at 253.640844 -89.765886)
		(size 0.508)
		(drill 0.254)
		(layers "F.Cu" "B.Cu")
		(net "PVDDQ_DEF")
	)
	(via
		(at 263.94283 -92.737686)
		(size 0.508)
		(drill 0.254)
		(layers "F.Cu" "B.Cu")
		(net "PVDDQ_DEF")
	)
	(via
		(at 271.199864 -154.905456)
		(size 0.508)
		(drill 0.254)
		(layers "F.Cu" "B.Cu")
		(net "PVDDQ_DEF")
	)
	(via
		(at 274.599908 -129.539746)
		(size 0.508)
		(drill 0.254)
		(layers "F.Cu" "B.Cu")
		(net "PVDDQ_DEF")
	)
	(via
		(at 255.92913 -102.3112)
		(size 0.508)
		(drill 0.254)
		(layers "F.Cu" "B.Cu")
		(net "PVDDQ_DEF")
	)
	(via
		(at 277.149814 -131.586478)
		(size 0.508)
		(drill 0.254)
		(layers "F.Cu" "B.Cu")
		(net "PVDDQ_DEF")
	)
	(via
		(at 273.750278 -141.187678)
		(size 0.508)
		(drill 0.254)
		(layers "F.Cu" "B.Cu")
		(net "PVDDQ_DEF")
	)
	(via
		(at 268.649958 -148.769578)
		(size 0.508)
		(drill 0.254)
		(layers "F.Cu" "B.Cu")
		(net "PVDDQ_DEF")
	)
	(via
		(at 248.249948 -141.187678)
		(size 0.508)
		(drill 0.254)
		(layers "F.Cu" "B.Cu")
		(net "PVDDQ_DEF")
	)
	(via
		(at 243.999766 -134.369556)
		(size 0.508)
		(drill 0.254)
		(layers "F.Cu" "B.Cu")
		(net "PVDDQ_DEF")
	)
	(via
		(at 272.050256 -145.988278)
		(size 0.4572)
		(drill 0.2032)
		(layers "F.Cu" "B.Cu")
		(net "PVDDQ_DEF")
	)
	(via
		(at 243.999766 -143.970756)
		(size 0.508)
		(drill 0.254)
		(layers "F.Cu" "B.Cu")
		(net "PVDDQ_DEF")
	)
	(via
		(at 269.491968 -86.022942)
		(size 0.5588)
		(drill 0.3048)
		(layers "F.Cu" "B.Cu")
		(net "PVDDQ_DEF")
	)
	(via
		(at 272.899886 -154.905456)
		(size 0.508)
		(drill 0.254)
		(layers "F.Cu" "B.Cu")
		(net "PVDDQ_DEF")
	)
	(via
		(at 273.74977 -154.252168)
		(size 0.508)
		(drill 0.254)
		(layers "F.Cu" "B.Cu")
		(net "PVDDQ_DEF")
	)
	(via
		(at 275.0312 -126.4031)
		(size 0.508)
		(drill 0.254)
		(layers "F.Cu" "B.Cu")
		(net "PVDDQ_DEF")
	)
	(via
		(at 266.099798 -139.168378)
		(size 0.508)
		(drill 0.254)
		(layers "F.Cu" "B.Cu")
		(net "PVDDQ_DEF")
	)
	(via
		(at 258.272026 -141.183868)
		(size 0.508)
		(drill 0.254)
		(layers "F.Cu" "B.Cu")
		(net "PVDDQ_DEF")
	)
	(via
		(at 248.249948 -154.252168)
		(size 0.508)
		(drill 0.254)
		(layers "F.Cu" "B.Cu")
		(net "PVDDQ_DEF")
	)
	(via
		(at 244.849904 -148.771356)
		(size 0.508)
		(drill 0.254)
		(layers "F.Cu" "B.Cu")
		(net "PVDDQ_DEF")
	)
	(via
		(at 245.699788 -153.571956)
		(size 0.508)
		(drill 0.254)
		(layers "F.Cu" "B.Cu")
		(net "PVDDQ_DEF")
	)
	(via
		(at 330.962 -144.5006)
		(size 0.508)
		(drill 0.254)
		(layers "F.Cu" "B.Cu")
		(net "PVDDQ_DEF")
	)
	(via
		(at 246.549926 -139.170156)
		(size 0.508)
		(drill 0.254)
		(layers "F.Cu" "B.Cu")
		(net "PVDDQ_DEF")
	)
	(via
		(at 249.099832 -148.771356)
		(size 0.508)
		(drill 0.254)
		(layers "F.Cu" "B.Cu")
		(net "PVDDQ_DEF")
	)
	(via
		(at 336.3468 -154.9654)
		(size 0.508)
		(drill 0.254)
		(layers "F.Cu" "B.Cu")
		(net "PVDDQ_DEF")
	)
	(via
		(at 270.253968 -86.022942)
		(size 0.5588)
		(drill 0.3048)
		(layers "F.Cu" "B.Cu")
		(net "PVDDQ_DEF")
	)
	(via
		(at 266.099798 -148.769578)
		(size 0.508)
		(drill 0.254)
		(layers "F.Cu" "B.Cu")
		(net "PVDDQ_DEF")
	)
	(via
		(at 259.65023 -94.223586)
		(size 0.508)
		(drill 0.254)
		(layers "F.Cu" "B.Cu")
		(net "PVDDQ_DEF")
	)
	(via
		(at 257.07467 -92.737686)
		(size 0.508)
		(drill 0.254)
		(layers "F.Cu" "B.Cu")
		(net "PVDDQ_DEF")
	)
	(via
		(at 246.549926 -148.771356)
		(size 0.508)
		(drill 0.254)
		(layers "F.Cu" "B.Cu")
		(net "PVDDQ_DEF")
	)
	(via
		(at 266.099798 -145.984468)
		(size 0.508)
		(drill 0.254)
		(layers "F.Cu" "B.Cu")
		(net "PVDDQ_DEF")
	)
	(via
		(at 269.500096 -141.187678)
		(size 0.508)
		(drill 0.254)
		(layers "F.Cu" "B.Cu")
		(net "PVDDQ_DEF")
	)
	(via
		(at 254.49911 -97.19564)
		(size 0.508)
		(drill 0.254)
		(layers "F.Cu" "B.Cu")
		(net "PVDDQ_DEF")
	)
	(via
		(at 251.649992 -148.773388)
		(size 0.508)
		(drill 0.254)
		(layers "F.Cu" "B.Cu")
		(net "PVDDQ_DEF")
	)
	(via
		(at 255.35763 -89.765886)
		(size 0.508)
		(drill 0.254)
		(layers "F.Cu" "B.Cu")
		(net "PVDDQ_DEF")
	)
	(via
		(at 271.320768 -86.022942)
		(size 0.5588)
		(drill 0.3048)
		(layers "F.Cu" "B.Cu")
		(net "PVDDQ_DEF")
	)
	(via
		(at 272.082768 -86.022942)
		(size 0.5588)
		(drill 0.3048)
		(layers "F.Cu" "B.Cu")
		(net "PVDDQ_DEF")
	)
	(via
		(at 330.962 -143.7386)
		(size 0.508)
		(drill 0.254)
		(layers "F.Cu" "B.Cu")
		(net "PVDDQ_DEF")
	)
	(via
		(at 261.36727 -99.17684)
		(size 0.508)
		(drill 0.254)
		(layers "F.Cu" "B.Cu")
		(net "PVDDQ_DEF")
	)
	(via
		(at 277.149814 -154.252168)
		(size 0.508)
		(drill 0.254)
		(layers "F.Cu" "B.Cu")
		(net "PVDDQ_DEF")
	)
	(via
		(at 251.649992 -145.988278)
		(size 0.508)
		(drill 0.254)
		(layers "F.Cu" "B.Cu")
		(net "PVDDQ_DEF")
	)
	(via
		(at 277.149814 -136.383268)
		(size 0.508)
		(drill 0.254)
		(layers "F.Cu" "B.Cu")
		(net "PVDDQ_DEF")
	)
	(via
		(at 275.4503 -143.972788)
		(size 0.4572)
		(drill 0.2032)
		(layers "F.Cu" "B.Cu")
		(net "PVDDQ_DEF")
	)
	(via
		(at 249.099832 -145.988278)
		(size 0.508)
		(drill 0.254)
		(layers "F.Cu" "B.Cu")
		(net "PVDDQ_DEF")
	)
	(via
		(at 277.149814 -134.367778)
		(size 0.508)
		(drill 0.254)
		(layers "F.Cu" "B.Cu")
		(net "PVDDQ_DEF")
	)
	(via
		(at 256.1971 -130.8608)
		(size 0.508)
		(drill 0.254)
		(layers "F.Cu" "B.Cu")
		(net "PVDDQ_DEF")
	)
	(via
		(at 273.750278 -150.788878)
		(size 0.508)
		(drill 0.254)
		(layers "F.Cu" "B.Cu")
		(net "PVDDQ_DEF")
	)
	(via
		(at 277.149814 -150.785068)
		(size 0.508)
		(drill 0.254)
		(layers "F.Cu" "B.Cu")
		(net "PVDDQ_DEF")
	)
	(via
		(at 334.01 -143.7386)
		(size 0.508)
		(drill 0.254)
		(layers "F.Cu" "B.Cu")
		(net "PVDDQ_DEF")
	)
	(via
		(at 193.8782 -143.764)
		(size 0.508)
		(drill 0.254)
		(layers "F.Cu" "B.Cu")
		(net "PVDDQ_DEF")
	)
	(via
		(at 334.01 -143.1036)
		(size 0.508)
		(drill 0.254)
		(layers "F.Cu" "B.Cu")
		(net "PVDDQ_DEF")
	)
	(via
		(at 246.549926 -136.387078)
		(size 0.508)
		(drill 0.254)
		(layers "F.Cu" "B.Cu")
		(net "PVDDQ_DEF")
	)
	(via
		(at 267.640308 -85.954616)
		(size 0.508)
		(drill 0.254)
		(layers "F.Cu" "B.Cu")
		(net "PVDDQ_DEF")
	)
	(via
		(at 254.199898 -139.172188)
		(size 0.508)
		(drill 0.254)
		(layers "F.Cu" "B.Cu")
		(net "PVDDQ_DEF")
	)
	(via
		(at 250.799854 -134.369556)
		(size 0.508)
		(drill 0.254)
		(layers "F.Cu" "B.Cu")
		(net "PVDDQ_DEF")
	)
	(via
		(at 245.699788 -143.970756)
		(size 0.508)
		(drill 0.254)
		(layers "F.Cu" "B.Cu")
		(net "PVDDQ_DEF")
	)
	(via
		(at 271.199864 -150.785068)
		(size 0.508)
		(drill 0.254)
		(layers "F.Cu" "B.Cu")
		(net "PVDDQ_DEF")
	)
	(via
		(at 266.518136 -94.223586)
		(size 0.508)
		(drill 0.254)
		(layers "F.Cu" "B.Cu")
		(net "PVDDQ_DEF")
	)
	(via
		(at 335.534 -144.5006)
		(size 0.508)
		(drill 0.254)
		(layers "F.Cu" "B.Cu")
		(net "PVDDQ_DEF")
	)
	(via
		(at 255.35763 -99.67214)
		(size 0.508)
		(drill 0.254)
		(layers "F.Cu" "B.Cu")
		(net "PVDDQ_DEF")
	)
	(via
		(at 264.22731 -100.167186)
		(size 0.508)
		(drill 0.254)
		(layers "F.Cu" "B.Cu")
		(net "PVDDQ_DEF")
	)
	(via
		(at 268.268704 -102.227634)
		(size 0.508)
		(drill 0.254)
		(layers "F.Cu" "B.Cu")
		(net "PVDDQ_DEF")
	)
	(via
		(at 267.376656 -99.67214)
		(size 0.508)
		(drill 0.254)
		(layers "F.Cu" "B.Cu")
		(net "PVDDQ_DEF")
	)
	(via
		(at 254.199898 -148.773388)
		(size 0.508)
		(drill 0.254)
		(layers "F.Cu" "B.Cu")
		(net "PVDDQ_DEF")
	)
	(via
		(at 250.799854 -141.187678)
		(size 0.508)
		(drill 0.254)
		(layers "F.Cu" "B.Cu")
		(net "PVDDQ_DEF")
	)
	(via
		(at 336.169 -141.0716)
		(size 0.508)
		(drill 0.254)
		(layers "F.Cu" "B.Cu")
		(net "PVDDQ_DEF")
	)
	(via
		(at 260.50875 -92.737686)
		(size 0.508)
		(drill 0.254)
		(layers "F.Cu" "B.Cu")
		(net "PVDDQ_DEF")
	)
	(via
		(at 254.12446 -129.539746)
		(size 0.508)
		(drill 0.254)
		(layers "F.Cu" "B.Cu")
		(net "PVDDQ_DEF")
	)
	(via
		(at 336.3468 -154.305)
		(size 0.508)
		(drill 0.254)
		(layers "F.Cu" "B.Cu")
		(net "PVDDQ_DEF")
	)
	(via
		(at 261.36727 -97.19564)
		(size 0.508)
		(drill 0.254)
		(layers "F.Cu" "B.Cu")
		(net "PVDDQ_DEF")
	)
	(via
		(at 334.772 -144.5006)
		(size 0.508)
		(drill 0.254)
		(layers "F.Cu" "B.Cu")
		(net "PVDDQ_DEF")
	)
	(via
		(at 271.199864 -136.383268)
		(size 0.508)
		(drill 0.254)
		(layers "F.Cu" "B.Cu")
		(net "PVDDQ_DEF")
	)
	(via
		(at 253.640844 -99.67214)
		(size 0.508)
		(drill 0.254)
		(layers "F.Cu" "B.Cu")
		(net "PVDDQ_DEF")
	)
	(via
		(at 253.350014 -141.187678)
		(size 0.508)
		(drill 0.254)
		(layers "F.Cu" "B.Cu")
		(net "PVDDQ_DEF")
	)
	(via
		(at 263.08431 -94.223586)
		(size 0.508)
		(drill 0.254)
		(layers "F.Cu" "B.Cu")
		(net "PVDDQ_DEF")
	)
	(via
		(at 258.896358 -148.771356)
		(size 0.508)
		(drill 0.254)
		(layers "F.Cu" "B.Cu")
		(net "PVDDQ_DEF")
	)
	(via
		(at 334.0354 -152.019)
		(size 0.508)
		(drill 0.254)
		(layers "F.Cu" "B.Cu")
		(net "PVDDQ_DEF")
	)
	(via
		(at 266.949936 -141.183868)
		(size 0.508)
		(drill 0.254)
		(layers "F.Cu" "B.Cu")
		(net "PVDDQ_DEF")
	)
	(via
		(at 258.449826 -153.571956)
		(size 0.508)
		(drill 0.254)
		(layers "F.Cu" "B.Cu")
		(net "PVDDQ_DEF")
	)
	(via
		(at 255.685036 -150.785068)
		(size 0.508)
		(drill 0.254)
		(layers "F.Cu" "B.Cu")
		(net "PVDDQ_DEF")
	)
	(via
		(at 334.7974 -152.654)
		(size 0.508)
		(drill 0.254)
		(layers "F.Cu" "B.Cu")
		(net "PVDDQ_DEF")
	)
	(via
		(at 180.0352 -151.5618)
		(size 0.508)
		(drill 0.254)
		(layers "F.Cu" "B.Cu")
		(net "PVDDQ_DEF")
	)
	(via
		(at 277.149814 -143.968978)
		(size 0.508)
		(drill 0.254)
		(layers "F.Cu" "B.Cu")
		(net "PVDDQ_DEF")
	)
	(via
		(at 275.4503 -141.187678)
		(size 0.508)
		(drill 0.254)
		(layers "F.Cu" "B.Cu")
		(net "PVDDQ_DEF")
	)
	(via
		(at 256.21615 -97.19564)
		(size 0.508)
		(drill 0.254)
		(layers "F.Cu" "B.Cu")
		(net "PVDDQ_DEF")
	)
	(via
		(at 335.534 -143.1036)
		(size 0.508)
		(drill 0.254)
		(layers "F.Cu" "B.Cu")
		(net "PVDDQ_DEF")
	)
	(via
		(at 258.2672 -143.970756)
		(size 0.508)
		(drill 0.254)
		(layers "F.Cu" "B.Cu")
		(net "PVDDQ_DEF")
	)
	(via
		(at 257.93319 -94.223586)
		(size 0.508)
		(drill 0.254)
		(layers "F.Cu" "B.Cu")
		(net "PVDDQ_DEF")
	)
	(via
		(at 180.848 -151.638)
		(size 0.508)
		(drill 0.254)
		(layers "F.Cu" "B.Cu")
		(net "PVDDQ_DEF")
	)
	(via
		(at 264.801096 -97.19564)
		(size 0.508)
		(drill 0.254)
		(layers "F.Cu" "B.Cu")
		(net "PVDDQ_DEF")
	)
	(via
		(at 258.79171 -89.765886)
		(size 0.508)
		(drill 0.254)
		(layers "F.Cu" "B.Cu")
		(net "PVDDQ_DEF")
	)
	(via
		(at 275.449792 -154.252168)
		(size 0.508)
		(drill 0.254)
		(layers "F.Cu" "B.Cu")
		(net "PVDDQ_DEF")
	)
	(via
		(at 253.350014 -154.252168)
		(size 0.508)
		(drill 0.254)
		(layers "F.Cu" "B.Cu")
		(net "PVDDQ_DEF")
	)
	(via
		(at 277.149814 -130.249168)
		(size 0.508)
		(drill 0.254)
		(layers "F.Cu" "B.Cu")
		(net "PVDDQ_DEF")
	)
	(via
		(at 335.407 -141.0716)
		(size 0.508)
		(drill 0.254)
		(layers "F.Cu" "B.Cu")
		(net "PVDDQ_DEF")
	)
	(via
		(at 268.649958 -145.984468)
		(size 0.508)
		(drill 0.254)
		(layers "F.Cu" "B.Cu")
		(net "PVDDQ_DEF")
	)
	(via
		(at 269.499842 -153.571956)
		(size 0.508)
		(drill 0.254)
		(layers "F.Cu" "B.Cu")
		(net "PVDDQ_DEF")
	)
	(via
		(at 261.08025 -102.3112)
		(size 0.508)
		(drill 0.254)
		(layers "F.Cu" "B.Cu")
		(net "PVDDQ_DEF")
	)
	(via
		(at 272.899886 -145.984468)
		(size 0.508)
		(drill 0.254)
		(layers "F.Cu" "B.Cu")
		(net "PVDDQ_DEF")
	)
	(via
		(at 244.849904 -130.249168)
		(size 0.508)
		(drill 0.254)
		(layers "F.Cu" "B.Cu")
		(net "PVDDQ_DEF")
	)
	(via
		(at 335.534 -145.1356)
		(size 0.508)
		(drill 0.254)
		(layers "F.Cu" "B.Cu")
		(net "PVDDQ_DEF")
	)
	(via
		(at 334.01 -144.5006)
		(size 0.508)
		(drill 0.254)
		(layers "F.Cu" "B.Cu")
		(net "PVDDQ_DEF")
	)
	(via
		(at 243.999766 -141.187678)
		(size 0.508)
		(drill 0.254)
		(layers "F.Cu" "B.Cu")
		(net "PVDDQ_DEF")
	)
	(via
		(at 244.172486 -126.780544)
		(size 0.508)
		(drill 0.254)
		(layers "F.Cu" "B.Cu")
		(net "PVDDQ_DEF")
	)
	(via
		(at 332.486 -143.7386)
		(size 0.508)
		(drill 0.254)
		(layers "F.Cu" "B.Cu")
		(net "PVDDQ_DEF")
	)
	(via
		(at 336.238596 -143.03883)
		(size 0.508)
		(drill 0.254)
		(layers "F.Cu" "B.Cu")
		(net "PVDDQ_DEF")
	)
	(via
		(at 258.3942 -139.170156)
		(size 0.508)
		(drill 0.254)
		(layers "F.Cu" "B.Cu")
		(net "PVDDQ_DEF")
	)
	(via
		(at 277.149814 -155.589478)
		(size 0.508)
		(drill 0.254)
		(layers "F.Cu" "B.Cu")
		(net "PVDDQ_DEF")
	)
	(via
		(at 333.248 -144.5006)
		(size 0.508)
		(drill 0.254)
		(layers "F.Cu" "B.Cu")
		(net "PVDDQ_DEF")
	)
	(via
		(at 333.2734 -152.019)
		(size 0.508)
		(drill 0.254)
		(layers "F.Cu" "B.Cu")
		(net "PVDDQ_DEF")
	)
	(via
		(at 331.8764 -154.94)
		(size 0.508)
		(drill 0.254)
		(layers "F.Cu" "B.Cu")
		(net "PVDDQ_DEF")
	)
	(via
		(at 248.249948 -150.788878)
		(size 0.508)
		(drill 0.254)
		(layers "F.Cu" "B.Cu")
		(net "PVDDQ_DEF")
	)
	(via
		(at 266.099798 -129.539746)
		(size 0.508)
		(drill 0.254)
		(layers "F.Cu" "B.Cu")
		(net "PVDDQ_DEF")
	)
	(via
		(at 266.130024 -85.938614)
		(size 0.508)
		(drill 0.254)
		(layers "F.Cu" "B.Cu")
		(net "PVDDQ_DEF")
	)
	(via
		(at 350.279462 -147.793456)
		(size 0.508)
		(drill 0.254)
		(layers "F.Cu" "B.Cu")
		(net "PVDDQ_DEF")
	)
	(via
		(at 268.649958 -139.168378)
		(size 0.508)
		(drill 0.254)
		(layers "F.Cu" "B.Cu")
		(net "PVDDQ_DEF")
	)
	(via
		(at 267.376656 -92.737686)
		(size 0.508)
		(drill 0.254)
		(layers "F.Cu" "B.Cu")
		(net "PVDDQ_DEF")
	)
	(via
		(at 268.425168 -86.022942)
		(size 0.5588)
		(drill 0.3048)
		(layers "F.Cu" "B.Cu")
		(net "PVDDQ_DEF")
	)
	(via
		(at 331.724 -146.304)
		(size 0.508)
		(drill 0.254)
		(layers "F.Cu" "B.Cu")
		(net "PVDDQ_DEF")
	)
	(via
		(at 335.407 -140.3096)
		(size 0.508)
		(drill 0.254)
		(layers "F.Cu" "B.Cu")
		(net "PVDDQ_DEF")
	)
	(via
		(at 253.350014 -134.371588)
		(size 0.508)
		(drill 0.254)
		(layers "F.Cu" "B.Cu")
		(net "PVDDQ_DEF")
	)
	(via
		(at 258.449826 -150.785068)
		(size 0.508)
		(drill 0.254)
		(layers "F.Cu" "B.Cu")
		(net "PVDDQ_DEF")
	)
	(via
		(at 336.3468 -152.4254)
		(size 0.508)
		(drill 0.254)
		(layers "F.Cu" "B.Cu")
		(net "PVDDQ_DEF")
	)
	(via
		(at 244.849904 -136.387078)
		(size 0.508)
		(drill 0.254)
		(layers "F.Cu" "B.Cu")
		(net "PVDDQ_DEF")
	)
	(via
		(at 331.724 -144.5006)
		(size 0.508)
		(drill 0.254)
		(layers "F.Cu" "B.Cu")
		(net "PVDDQ_DEF")
	)
	(via
		(at 253.350014 -150.788878)
		(size 0.508)
		(drill 0.254)
		(layers "F.Cu" "B.Cu")
		(net "PVDDQ_DEF")
	)
	(via
		(at 334.7974 -152.019)
		(size 0.508)
		(drill 0.254)
		(layers "F.Cu" "B.Cu")
		(net "PVDDQ_DEF")
	)
	(via
		(at 183.4388 -145.1102)
		(size 0.508)
		(drill 0.254)
		(layers "F.Cu" "B.Cu")
		(net "PVDDQ_DEF")
	)
	(via
		(at 266.099798 -154.905456)
		(size 0.508)
		(drill 0.254)
		(layers "F.Cu" "B.Cu")
		(net "PVDDQ_DEF")
	)
	(via
		(at 334.772 -143.1036)
		(size 0.508)
		(drill 0.254)
		(layers "F.Cu" "B.Cu")
		(net "PVDDQ_DEF")
	)
	(via
		(at 255.684782 -148.771356)
		(size 0.508)
		(drill 0.254)
		(layers "F.Cu" "B.Cu")
		(net "PVDDQ_DEF")
	)
	(via
		(at 255.89992 -145.984468)
		(size 0.508)
		(drill 0.254)
		(layers "F.Cu" "B.Cu")
		(net "PVDDQ_DEF")
	)
	(via
		(at 256.21615 -94.223586)
		(size 0.508)
		(drill 0.254)
		(layers "F.Cu" "B.Cu")
		(net "PVDDQ_DEF")
	)
	(via
		(at 336.3468 -153.6954)
		(size 0.508)
		(drill 0.254)
		(layers "F.Cu" "B.Cu")
		(net "PVDDQ_DEF")
	)
	(via
		(at 335.534 -143.7386)
		(size 0.508)
		(drill 0.254)
		(layers "F.Cu" "B.Cu")
		(net "PVDDQ_DEF")
	)
	(via
		(at 334.645 -141.8336)
		(size 0.508)
		(drill 0.254)
		(layers "F.Cu" "B.Cu")
		(net "PVDDQ_DEF")
	)
	(via
		(at 250.799854 -130.902456)
		(size 0.508)
		(drill 0.254)
		(layers "F.Cu" "B.Cu")
		(net "PVDDQ_DEF")
	)
	(via
		(at 274.599908 -145.984468)
		(size 0.508)
		(drill 0.254)
		(layers "F.Cu" "B.Cu")
		(net "PVDDQ_DEF")
	)
	(via
		(at 334.645 -140.3096)
		(size 0.508)
		(drill 0.254)
		(layers "F.Cu" "B.Cu")
		(net "PVDDQ_DEF")
	)
	(via
		(at 330.962 -147.066)
		(size 0.508)
		(drill 0.254)
		(layers "F.Cu" "B.Cu")
		(net "PVDDQ_DEF")
	)
	(via
		(at 251.649992 -130.249168)
		(size 0.508)
		(drill 0.254)
		(layers "F.Cu" "B.Cu")
		(net "PVDDQ_DEF")
	)
	(via
		(at 243.999766 -130.902456)
		(size 0.508)
		(drill 0.254)
		(layers "F.Cu" "B.Cu")
		(net "PVDDQ_DEF")
	)
	(via
		(at 272.899886 -129.568956)
		(size 0.508)
		(drill 0.254)
		(layers "F.Cu" "B.Cu")
		(net "PVDDQ_DEF")
	)
	(via
		(at 252.782324 -97.19564)
		(size 0.508)
		(drill 0.254)
		(layers "F.Cu" "B.Cu")
		(net "PVDDQ_DEF")
	)
	(via
		(at 255.89992 -134.351268)
		(size 0.508)
		(drill 0.254)
		(layers "F.Cu" "B.Cu")
		(net "PVDDQ_DEF")
	)
	(via
		(at 332.5114 -152.019)
		(size 0.508)
		(drill 0.254)
		(layers "F.Cu" "B.Cu")
		(net "PVDDQ_DEF")
	)
	(via
		(at 266.95019 -134.371588)
		(size 0.4572)
		(drill 0.2032)
		(layers "F.Cu" "B.Cu")
		(net "PVDDQ_DEF")
	)
	(via
		(at 250.799854 -153.542746)
		(size 0.508)
		(drill 0.254)
		(layers "F.Cu" "B.Cu")
		(net "PVDDQ_DEF")
	)
	(via
		(at 266.95019 -143.972788)
		(size 0.4572)
		(drill 0.2032)
		(layers "F.Cu" "B.Cu")
		(net "PVDDQ_DEF")
	)
	(via
		(at 268.649958 -136.383268)
		(size 0.508)
		(drill 0.254)
		(layers "F.Cu" "B.Cu")
		(net "PVDDQ_DEF")
	)
	(via
		(at 267.376656 -90.756486)
		(size 0.508)
		(drill 0.254)
		(layers "F.Cu" "B.Cu")
		(net "PVDDQ_DEF")
	)
	(via
		(at 266.949936 -150.785068)
		(size 0.508)
		(drill 0.254)
		(layers "F.Cu" "B.Cu")
		(net "PVDDQ_DEF")
	)
	(via
		(at 331.724 -143.1036)
		(size 0.508)
		(drill 0.254)
		(layers "F.Cu" "B.Cu")
		(net "PVDDQ_DEF")
	)
	(via
		(at 268.649704 -130.249168)
		(size 0.508)
		(drill 0.254)
		(layers "F.Cu" "B.Cu")
		(net "PVDDQ_DEF")
	)
	(via
		(at 271.199864 -139.168378)
		(size 0.4572)
		(drill 0.2032)
		(layers "F.Cu" "B.Cu")
		(net "PVDDQ_DEF")
	)
	(via
		(at 330.962 -146.304)
		(size 0.508)
		(drill 0.254)
		(layers "F.Cu" "B.Cu")
		(net "PVDDQ_DEF")
	)
	(via
		(at 274.391628 -85.987382)
		(size 0.5588)
		(drill 0.3048)
		(layers "F.Cu" "B.Cu")
		(net "PVDDQ_DEF")
	)
	(via
		(at 243.999766 -153.571956)
		(size 0.508)
		(drill 0.254)
		(layers "F.Cu" "B.Cu")
		(net "PVDDQ_DEF")
	)
	(via
		(at 255.909572 -141.183868)
		(size 0.508)
		(drill 0.254)
		(layers "F.Cu" "B.Cu")
		(net "PVDDQ_DEF")
	)
	(via
		(at 333.9338 -146.6596)
		(size 0.6604)
		(drill 0.3302)
		(layers "F.Cu" "B.Cu")
		(net "PVDDQ_DEF")
	)
	(via
		(at 180.0352 -152.2222)
		(size 0.508)
		(drill 0.254)
		(layers "F.Cu" "B.Cu")
		(net "PVDDQ_DEF")
	)
	(via
		(at 336.3468 -153.0858)
		(size 0.508)
		(drill 0.254)
		(layers "F.Cu" "B.Cu")
		(net "PVDDQ_DEF")
	)
	(via
		(at 261.36727 -94.223586)
		(size 0.508)
		(drill 0.254)
		(layers "F.Cu" "B.Cu")
		(net "PVDDQ_DEF")
	)
	(via
		(at 266.949682 -154.252168)
		(size 0.508)
		(drill 0.254)
		(layers "F.Cu" "B.Cu")
		(net "PVDDQ_DEF")
	)
	(via
		(at 258.79171 -92.737686)
		(size 0.508)
		(drill 0.254)
		(layers "F.Cu" "B.Cu")
		(net "PVDDQ_DEF")
	)
	(via
		(at 248.249948 -134.369556)
		(size 0.508)
		(drill 0.254)
		(layers "F.Cu" "B.Cu")
		(net "PVDDQ_DEF")
	)
	(via
		(at 258.184142 -129.568956)
		(size 0.508)
		(drill 0.254)
		(layers "F.Cu" "B.Cu")
		(net "PVDDQ_DEF")
	)
	(via
		(at 254.199898 -154.905456)
		(size 0.508)
		(drill 0.254)
		(layers "F.Cu" "B.Cu")
		(net "PVDDQ_DEF")
	)
	(via
		(at 257.07467 -89.765886)
		(size 0.508)
		(drill 0.254)
		(layers "F.Cu" "B.Cu")
		(net "PVDDQ_DEF")
	)
	(via
		(at 271.199864 -141.183868)
		(size 0.508)
		(drill 0.254)
		(layers "F.Cu" "B.Cu")
		(net "PVDDQ_DEF")
	)
	(via
		(at 251.649992 -139.172188)
		(size 0.508)
		(drill 0.254)
		(layers "F.Cu" "B.Cu")
		(net "PVDDQ_DEF")
	)
	(via
		(at 262.22579 -92.737686)
		(size 0.508)
		(drill 0.254)
		(layers "F.Cu" "B.Cu")
		(net "PVDDQ_DEF")
	)
	(via
		(at 244.849904 -155.564078)
		(size 0.508)
		(drill 0.254)
		(layers "F.Cu" "B.Cu")
		(net "PVDDQ_DEF")
	)
	(via
		(at 258.2672 -145.984468)
		(size 0.508)
		(drill 0.254)
		(layers "F.Cu" "B.Cu")
		(net "PVDDQ_DEF")
	)
	(via
		(at 330.7588 -153.7462)
		(size 0.6604)
		(drill 0.3302)
		(layers "F.Cu" "B.Cu")
		(net "PVDDQ_DEF")
	)
	(via
		(at 333.248 -143.1036)
		(size 0.508)
		(drill 0.254)
		(layers "F.Cu" "B.Cu")
		(net "PVDDQ_DEF")
	)
	(via
		(at 330.2 -140.3096)
		(size 0.508)
		(drill 0.254)
		(layers "F.Cu" "B.Cu")
		(net "PVDDQ_DEF")
	)
	(via
		(at 332.5114 -152.654)
		(size 0.508)
		(drill 0.254)
		(layers "F.Cu" "B.Cu")
		(net "PVDDQ_DEF")
	)
	(via
		(at 243.999766 -150.788878)
		(size 0.508)
		(drill 0.254)
		(layers "F.Cu" "B.Cu")
		(net "PVDDQ_DEF")
	)
	(via
		(at 331.724 -145.1356)
		(size 0.508)
		(drill 0.254)
		(layers "F.Cu" "B.Cu")
		(net "PVDDQ_DEF")
	)
	(via
		(at 264.51433 -102.3112)
		(size 0.508)
		(drill 0.254)
		(layers "F.Cu" "B.Cu")
		(net "PVDDQ_DEF")
	)
	(via
		(at 275.449792 -131.611878)
		(size 0.508)
		(drill 0.254)
		(layers "F.Cu" "B.Cu")
		(net "PVDDQ_DEF")
	)
	(via
		(at 253.350014 -143.972788)
		(size 0.508)
		(drill 0.254)
		(layers "F.Cu" "B.Cu")
		(net "PVDDQ_DEF")
	)
	(via
		(at 334.0354 -152.654)
		(size 0.508)
		(drill 0.254)
		(layers "F.Cu" "B.Cu")
		(net "PVDDQ_DEF")
	)
	(via
		(at 264.801096 -99.17684)
		(size 0.508)
		(drill 0.254)
		(layers "F.Cu" "B.Cu")
		(net "PVDDQ_DEF")
	)
	(via
		(at 249.099832 -129.568956)
		(size 0.508)
		(drill 0.254)
		(layers "F.Cu" "B.Cu")
		(net "PVDDQ_DEF")
	)
	(via
		(at 262.89 -132.475224)
		(size 0.508)
		(drill 0.254)
		(layers "F.Cu" "B.Cu")
		(net "PVDDQ_DEF")
	)
	(via
		(at 251.649992 -136.387078)
		(size 0.508)
		(drill 0.254)
		(layers "F.Cu" "B.Cu")
		(net "PVDDQ_DEF")
	)
	(via
		(at 274.599908 -154.905456)
		(size 0.508)
		(drill 0.254)
		(layers "F.Cu" "B.Cu")
		(net "PVDDQ_DEF")
	)
	(via
		(at 275.4503 -150.788878)
		(size 0.508)
		(drill 0.254)
		(layers "F.Cu" "B.Cu")
		(net "PVDDQ_DEF")
	)
	(via
		(at 254.199898 -136.387078)
		(size 0.508)
		(drill 0.254)
		(layers "F.Cu" "B.Cu")
		(net "PVDDQ_DEF")
	)
	(via
		(at 194.1576 -153.5684)
		(size 0.508)
		(drill 0.254)
		(layers "F.Cu" "B.Cu")
		(net "PVDDQ_DEF")
	)
	(via
		(at 251.649992 -155.564078)
		(size 0.508)
		(drill 0.254)
		(layers "F.Cu" "B.Cu")
		(net "PVDDQ_DEF")
	)
	(via
		(at 255.909572 -143.970756)
		(size 0.508)
		(drill 0.254)
		(layers "F.Cu" "B.Cu")
		(net "PVDDQ_DEF")
	)
	(via
		(at 269.499842 -130.902456)
		(size 0.508)
		(drill 0.254)
		(layers "F.Cu" "B.Cu")
		(net "PVDDQ_DEF")
	)
	(via
		(at 266.099798 -136.383268)
		(size 0.508)
		(drill 0.254)
		(layers "F.Cu" "B.Cu")
		(net "PVDDQ_DEF")
	)
	(via
		(at 273.74977 -131.611878)
		(size 0.508)
		(drill 0.254)
		(layers "F.Cu" "B.Cu")
		(net "PVDDQ_DEF")
	)
	(via
		(at 332.486 -144.5006)
		(size 0.508)
		(drill 0.254)
		(layers "F.Cu" "B.Cu")
		(net "PVDDQ_DEF")
	)
	(via
		(at 264.801096 -94.223586)
		(size 0.508)
		(drill 0.254)
		(layers "F.Cu" "B.Cu")
		(net "PVDDQ_DEF")
	)
	(via
		(at 250.799854 -150.788878)
		(size 0.508)
		(drill 0.254)
		(layers "F.Cu" "B.Cu")
		(net "PVDDQ_DEF")
	)
	(via
		(at 194.1576 -134.2644)
		(size 0.508)
		(drill 0.254)
		(layers "F.Cu" "B.Cu")
		(net "PVDDQ_DEF")
	)
	(via
		(at 274.599908 -148.769578)
		(size 0.508)
		(drill 0.254)
		(layers "F.Cu" "B.Cu")
		(net "PVDDQ_DEF")
	)
	(via
		(at 269.500096 -150.788878)
		(size 0.508)
		(drill 0.254)
		(layers "F.Cu" "B.Cu")
		(net "PVDDQ_DEF")
	)
	(via
		(at 245.699788 -134.369556)
		(size 0.508)
		(drill 0.254)
		(layers "F.Cu" "B.Cu")
		(net "PVDDQ_DEF")
	)
	(via
		(at 277.149814 -145.984468)
		(size 0.508)
		(drill 0.254)
		(layers "F.Cu" "B.Cu")
		(net "PVDDQ_DEF")
	)
	(via
		(at 271.199864 -143.968978)
		(size 0.508)
		(drill 0.254)
		(layers "F.Cu" "B.Cu")
		(net "PVDDQ_DEF")
	)
	(via
		(at 331.865224 -154.319732)
		(size 0.508)
		(drill 0.254)
		(layers "F.Cu" "B.Cu")
		(net "PVDDQ_DEF")
	)
	(via
		(at 255.89992 -153.571956)
		(size 0.508)
		(drill 0.254)
		(layers "F.Cu" "B.Cu")
		(net "PVDDQ_DEF")
	)
	(via
		(at 248.010934 -126.941072)
		(size 0.508)
		(drill 0.254)
		(layers "F.Cu" "B.Cu")
		(net "PVDDQ_DEF")
	)
	(via
		(at 277.149814 -148.769578)
		(size 0.508)
		(drill 0.254)
		(layers "F.Cu" "B.Cu")
		(net "PVDDQ_DEF")
	)
	(via
		(at 336.296 -144.5006)
		(size 0.508)
		(drill 0.254)
		(layers "F.Cu" "B.Cu")
		(net "PVDDQ_DEF")
	)
	(via
		(at 271.199864 -134.367778)
		(size 0.508)
		(drill 0.254)
		(layers "F.Cu" "B.Cu")
		(net "PVDDQ_DEF")
	)
	(via
		(at 254.49911 -94.223586)
		(size 0.508)
		(drill 0.254)
		(layers "F.Cu" "B.Cu")
		(net "PVDDQ_DEF")
	)
	(via
		(at 253.350014 -131.611878)
		(size 0.508)
		(drill 0.254)
		(layers "F.Cu" "B.Cu")
		(net "PVDDQ_DEF")
	)
	(via
		(at 255.89992 -155.509468)
		(size 0.508)
		(drill 0.254)
		(layers "F.Cu" "B.Cu")
		(net "PVDDQ_DEF")
	)
	(via
		(at 268.649704 -155.614878)
		(size 0.508)
		(drill 0.254)
		(layers "F.Cu" "B.Cu")
		(net "PVDDQ_DEF")
	)
	(via
		(at 272.899886 -148.769578)
		(size 0.508)
		(drill 0.254)
		(layers "F.Cu" "B.Cu")
		(net "PVDDQ_DEF")
	)
	(via
		(at 255.909572 -136.328658)
		(size 0.508)
		(drill 0.254)
		(layers "F.Cu" "B.Cu")
		(net "PVDDQ_DEF")
	)
	(via
		(at 334.772 -145.1356)
		(size 0.508)
		(drill 0.254)
		(layers "F.Cu" "B.Cu")
		(net "PVDDQ_DEF")
	)
	(via
		(at 273.750278 -134.371588)
		(size 0.4572)
		(drill 0.2032)
		(layers "F.Cu" "B.Cu")
		(net "PVDDQ_DEF")
	)
	(via
		(at 333.248 -143.7386)
		(size 0.508)
		(drill 0.254)
		(layers "F.Cu" "B.Cu")
		(net "PVDDQ_DEF")
	)
	(via
		(at 277.149814 -139.168378)
		(size 0.508)
		(drill 0.254)
		(layers "F.Cu" "B.Cu")
		(net "PVDDQ_DEF")
	)
	(via
		(at 274.599908 -136.383268)
		(size 0.508)
		(drill 0.254)
		(layers "F.Cu" "B.Cu")
		(net "PVDDQ_DEF")
	)
	(via
		(at 265.241024 -85.938614)
		(size 0.508)
		(drill 0.254)
		(layers "F.Cu" "B.Cu")
		(net "PVDDQ_DEF")
	)
	(via
		(at 255.35763 -92.737686)
		(size 0.508)
		(drill 0.254)
		(layers "F.Cu" "B.Cu")
		(net "PVDDQ_DEF")
	)
	(via
		(at 331.724 -143.7386)
		(size 0.508)
		(drill 0.254)
		(layers "F.Cu" "B.Cu")
		(net "PVDDQ_DEF")
	)
	(via
		(at 271.199864 -130.902456)
		(size 0.508)
		(drill 0.254)
		(layers "F.Cu" "B.Cu")
		(net "PVDDQ_DEF")
	)
	(via
		(at 332.486 -145.1356)
		(size 0.508)
		(drill 0.254)
		(layers "F.Cu" "B.Cu")
		(net "PVDDQ_DEF")
	)
	(via
		(at 271.199864 -148.742146)
		(size 0.508)
		(drill 0.254)
		(layers "F.Cu" "B.Cu")
		(net "PVDDQ_DEF")
	)
	(via
		(at 251.923804 -89.765886)
		(size 0.508)
		(drill 0.254)
		(layers "F.Cu" "B.Cu")
		(net "PVDDQ_DEF")
	)
	(via
		(at 335.5594 -152.019)
		(size 0.508)
		(drill 0.254)
		(layers "F.Cu" "B.Cu")
		(net "PVDDQ_DEF")
	)
	(via
		(at 330.2 -141.0716)
		(size 0.508)
		(drill 0.254)
		(layers "F.Cu" "B.Cu")
		(net "PVDDQ_DEF")
	)
	(via
		(at 244.849904 -139.170156)
		(size 0.508)
		(drill 0.254)
		(layers "F.Cu" "B.Cu")
		(net "PVDDQ_DEF")
	)
	(via
		(at 334.772 -143.7386)
		(size 0.508)
		(drill 0.254)
		(layers "F.Cu" "B.Cu")
		(net "PVDDQ_DEF")
	)
	(via
		(at 258.261612 -155.386786)
		(size 0.508)
		(drill 0.254)
		(layers "F.Cu" "B.Cu")
		(net "PVDDQ_DEF")
	)
	(via
		(at 248.249948 -131.611878)
		(size 0.508)
		(drill 0.254)
		(layers "F.Cu" "B.Cu")
		(net "PVDDQ_DEF")
	)
	(via
		(at 260.50875 -89.765886)
		(size 0.508)
		(drill 0.254)
		(layers "F.Cu" "B.Cu")
		(net "PVDDQ_DEF")
	)
	(via
		(at 253.640844 -92.737686)
		(size 0.508)
		(drill 0.254)
		(layers "F.Cu" "B.Cu")
		(net "PVDDQ_DEF")
	)
	(via
		(at 258.449826 -134.380478)
		(size 0.508)
		(drill 0.254)
		(layers "F.Cu" "B.Cu")
		(net "PVDDQ_DEF")
	)
	(via
		(at 252.782324 -94.223586)
		(size 0.508)
		(drill 0.254)
		(layers "F.Cu" "B.Cu")
		(net "PVDDQ_DEF")
	)
	(via
		(at 251.923804 -92.737686)
		(size 0.508)
		(drill 0.254)
		(layers "F.Cu" "B.Cu")
		(net "PVDDQ_DEF")
	)
	(via
		(at 245.699788 -150.788878)
		(size 0.508)
		(drill 0.254)
		(layers "F.Cu" "B.Cu")
		(net "PVDDQ_DEF")
	)
	(via
		(at 272.899886 -139.168378)
		(size 0.508)
		(drill 0.254)
		(layers "F.Cu" "B.Cu")
		(net "PVDDQ_DEF")
	)
	(via
		(at 246.549926 -130.249168)
		(size 0.508)
		(drill 0.254)
		(layers "F.Cu" "B.Cu")
		(net "PVDDQ_DEF")
	)
	(via
		(at 257.07467 -99.67214)
		(size 0.508)
		(drill 0.254)
		(layers "F.Cu" "B.Cu")
		(net "PVDDQ_DEF")
	)
	(via
		(at 258.79171 -99.67214)
		(size 0.508)
		(drill 0.254)
		(layers "F.Cu" "B.Cu")
		(net "PVDDQ_DEF")
	)
	(via
		(at 259.65023 -97.19564)
		(size 0.508)
		(drill 0.254)
		(layers "F.Cu" "B.Cu")
		(net "PVDDQ_DEF")
	)
	(via
		(at 260.50875 -99.67214)
		(size 0.508)
		(drill 0.254)
		(layers "F.Cu" "B.Cu")
		(net "PVDDQ_DEF")
	)
	(via
		(at 336.169 -140.3096)
		(size 0.508)
		(drill 0.254)
		(layers "F.Cu" "B.Cu")
		(net "PVDDQ_DEF")
	)
	(via
		(at 334.645 -141.0716)
		(size 0.508)
		(drill 0.254)
		(layers "F.Cu" "B.Cu")
		(net "PVDDQ_DEF")
	)
	(via
		(at 251.065284 -97.19564)
		(size 0.508)
		(drill 0.254)
		(layers "F.Cu" "B.Cu")
		(net "PVDDQ_DEF")
	)
	(via
		(at 244.849904 -145.988278)
		(size 0.508)
		(drill 0.254)
		(layers "F.Cu" "B.Cu")
		(net "PVDDQ_DEF")
	)
	(via
		(at 266.518136 -97.19564)
		(size 0.508)
		(drill 0.254)
		(layers "F.Cu" "B.Cu")
		(net "PVDDQ_DEF")
	)
	(via
		(at 248.249948 -143.970756)
		(size 0.508)
		(drill 0.254)
		(layers "F.Cu" "B.Cu")
		(net "PVDDQ_DEF")
	)
	(via
		(at 274.599908 -139.168378)
		(size 0.508)
		(drill 0.254)
		(layers "F.Cu" "B.Cu")
		(net "PVDDQ_DEF")
	)
	(via
		(at 336.238596 -143.80083)
		(size 0.508)
		(drill 0.254)
		(layers "F.Cu" "B.Cu")
		(net "PVDDQ_DEF")
	)
	(segment
		(start 244.653054 -130.249168)
		(end 244.849904 -130.249168)
		(width 0.4064)
		(layer "B.Cu")
		(net "PVDDQ_DEF")
	)
	(segment
		(start 266.099798 -148.769578)
		(end 266.099798 -147.478496)
		(width 0.4064)
		(layer "B.Cu")
		(net "PVDDQ_DEF")
	)
	(segment
		(start 271.199864 -139.168378)
		(end 271.199864 -137.877296)
		(width 0.4064)
		(layer "B.Cu")
		(net "PVDDQ_DEF")
	)
	(segment
		(start 255.89992 -142.477236)
		(end 255.89992 -141.18717)
		(width 0.4064)
		(layer "B.Cu")
		(net "PVDDQ_DEF")
	)
	(segment
		(start 246.550434 -136.387586)
		(end 246.550434 -137.877296)
		(width 0.4064)
		(layer "B.Cu")
		(net "PVDDQ_DEF")
	)
	(segment
		(start 258.318 -135.3312)
		(end 258.318 -134.512304)
		(width 0.4572)
		(layer "B.Cu")
		(net "PVDDQ_DEF")
	)
	(segment
		(start 251.649992 -139.172188)
		(end 251.649992 -137.877296)
		(width 0.4064)
		(layer "B.Cu")
		(net "PVDDQ_DEF")
	)
	(segment
		(start 249.10034 -128.276096)
		(end 249.099832 -128.276096)
		(width 0.4064)
		(layer "B.Cu")
		(net "PVDDQ_DEF")
	)
	(segment
		(start 244.5512 -126.227586)
		(end 244.172486 -126.6063)
		(width 0.4064)
		(layer "B.Cu")
		(net "PVDDQ_DEF")
	)
	(segment
		(start 266.100306 -137.877296)
		(end 266.099798 -137.877296)
		(width 0.4064)
		(layer "B.Cu")
		(net "PVDDQ_DEF")
	)
	(segment
		(start 272.899886 -147.478496)
		(end 272.900394 -147.478496)
		(width 0.4064)
		(layer "B.Cu")
		(net "PVDDQ_DEF")
	)
	(segment
		(start 246.549926 -148.771356)
		(end 246.549926 -147.478496)
		(width 0.4064)
		(layer "B.Cu")
		(net "PVDDQ_DEF")
	)
	(segment
		(start 243.999766 -130.902456)
		(end 243.999766 -132.876036)
		(width 0.4064)
		(layer "B.Cu")
		(net "PVDDQ_DEF")
	)
	(segment
		(start 248.249948 -150.788878)
		(end 248.249948 -152.078436)
		(width 0.4064)
		(layer "B.Cu")
		(net "PVDDQ_DEF")
	)
	(segment
		(start 254.199898 -148.773388)
		(end 254.199898 -147.478496)
		(width 0.4064)
		(layer "B.Cu")
		(net "PVDDQ_DEF")
	)
	(segment
		(start 248.249948 -142.477236)
		(end 248.249948 -143.970756)
		(width 0.4064)
		(layer "B.Cu")
		(net "PVDDQ_DEF")
	)
	(segment
		(start 246.549926 -130.249168)
		(end 246.549926 -128.276096)
		(width 0.4064)
		(layer "B.Cu")
		(net "PVDDQ_DEF")
	)
	(segment
		(start 258.449826 -148.23948)
		(end 258.896358 -148.686012)
		(width 0.381)
		(layer "B.Cu")
		(net "PVDDQ_DEF")
	)
	(segment
		(start 253.350522 -132.876036)
		(end 253.350014 -132.876036)
		(width 0.4064)
		(layer "B.Cu")
		(net "PVDDQ_DEF")
	)
	(segment
		(start 243.999766 -142.477236)
		(end 243.999766 -141.187678)
		(width 0.4064)
		(layer "B.Cu")
		(net "PVDDQ_DEF")
	)
	(segment
		(start 277.149814 -137.877296)
		(end 277.149814 -136.387078)
		(width 0.4064)
		(layer "B.Cu")
		(net "PVDDQ_DEF")
	)
	(segment
		(start 255.89992 -128.276096)
		(end 255.89992 -129.303272)
		(width 0.4064)
		(layer "B.Cu")
		(net "PVDDQ_DEF")
	)
	(segment
		(start 246.549926 -137.877296)
		(end 246.550434 -137.877296)
		(width 0.4064)
		(layer "B.Cu")
		(net "PVDDQ_DEF")
	)
	(segment
		(start 249.099832 -148.771356)
		(end 249.099832 -147.478496)
		(width 0.4064)
		(layer "B.Cu")
		(net "PVDDQ_DEF")
	)
	(segment
		(start 274.600416 -128.276096)
		(end 274.599908 -128.276096)
		(width 0.4064)
		(layer "B.Cu")
		(net "PVDDQ_DEF")
	)
	(segment
		(start 243.999766 -130.902456)
		(end 244.653054 -130.249168)
		(width 0.4064)
		(layer "B.Cu")
		(net "PVDDQ_DEF")
	)
	(segment
		(start 250.996704 -130.902456)
		(end 251.649992 -130.249168)
		(width 0.4064)
		(layer "B.Cu")
		(net "PVDDQ_DEF")
	)
	(segment
		(start 277.149814 -132.876036)
		(end 277.150322 -132.876036)
		(width 0.4064)
		(layer "B.Cu")
		(net "PVDDQ_DEF")
	)
	(segment
		(start 258.450334 -129.302764)
		(end 258.450334 -128.276096)
		(width 0.4064)
		(layer "B.Cu")
		(net "PVDDQ_DEF")
	)
	(segment
		(start 246.549926 -136.387078)
		(end 246.550434 -136.387586)
		(width 0.4064)
		(layer "B.Cu")
		(net "PVDDQ_DEF")
	)
	(segment
		(start 273.750278 -154.25166)
		(end 273.74977 -154.252168)
		(width 0.4064)
		(layer "B.Cu")
		(net "PVDDQ_DEF")
	)
	(segment
		(start 245.699788 -152.078436)
		(end 245.699788 -150.788878)
		(width 0.4064)
		(layer "B.Cu")
		(net "PVDDQ_DEF")
	)
	(segment
		(start 277.149814 -147.478496)
		(end 277.150322 -147.478496)
		(width 0.4064)
		(layer "B.Cu")
		(net "PVDDQ_DEF")
	)
	(segment
		(start 274.599908 -128.276096)
		(end 274.599908 -126.985776)
		(width 0.4064)
		(layer "B.Cu")
		(net "PVDDQ_DEF")
	)
	(segment
		(start 258.278122 -143.970756)
		(end 258.2672 -143.970756)
		(width 0.4064)
		(layer "B.Cu")
		(net "PVDDQ_DEF")
	)
	(segment
		(start 254.199898 -129.464308)
		(end 254.12446 -129.539746)
		(width 0.4064)
		(layer "B.Cu")
		(net "PVDDQ_DEF")
	)
	(segment
		(start 193.8782 -143.764)
		(end 193.548 -144.0942)
		(width 0.4064)
		(layer "B.Cu")
		(net "PVDDQ_DEF")
	)
	(segment
		(start 255.89992 -141.18717)
		(end 255.90627 -141.18717)
		(width 0.4064)
		(layer "B.Cu")
		(net "PVDDQ_DEF")
	)
	(segment
		(start 244.849904 -145.988278)
		(end 244.849904 -147.478496)
		(width 0.4064)
		(layer "B.Cu")
		(net "PVDDQ_DEF")
	)
	(segment
		(start 274.599908 -139.168378)
		(end 274.599908 -137.877296)
		(width 0.4064)
		(layer "B.Cu")
		(net "PVDDQ_DEF")
	)
	(segment
		(start 266.949936 -142.477236)
		(end 266.949936 -141.183868)
		(width 0.4064)
		(layer "B.Cu")
		(net "PVDDQ_DEF")
	)
	(segment
		(start 273.74977 -134.35457)
		(end 273.74977 -132.876036)
		(width 0.4064)
		(layer "B.Cu")
		(net "PVDDQ_DEF")
	)
	(segment
		(start 266.949936 -152.078436)
		(end 266.950444 -152.078436)
		(width 0.4064)
		(layer "B.Cu")
		(net "PVDDQ_DEF")
	)
	(segment
		(start 269.499842 -143.972534)
		(end 269.499842 -142.477236)
		(width 0.4064)
		(layer "B.Cu")
		(net "PVDDQ_DEF")
	)
	(segment
		(start 250.799854 -134.369556)
		(end 250.800362 -134.369048)
		(width 0.4064)
		(layer "B.Cu")
		(net "PVDDQ_DEF")
	)
	(segment
		(start 255.89992 -131.15798)
		(end 255.89992 -132.876036)
		(width 0.4064)
		(layer "B.Cu")
		(net "PVDDQ_DEF")
	)
	(segment
		(start 251.649992 -137.877296)
		(end 251.6505 -137.877296)
		(width 0.4064)
		(layer "B.Cu")
		(net "PVDDQ_DEF")
	)
	(segment
		(start 258.449826 -132.875782)
		(end 258.449826 -132.876036)
		(width 0.4064)
		(layer "B.Cu")
		(net "PVDDQ_DEF")
	)
	(segment
		(start 249.099832 -128.276096)
		(end 249.099832 -129.568956)
		(width 0.4064)
		(layer "B.Cu")
		(net "PVDDQ_DEF")
	)
	(segment
		(start 273.74977 -132.876036)
		(end 273.74977 -131.611878)
		(width 0.4064)
		(layer "B.Cu")
		(net "PVDDQ_DEF")
	)
	(segment
		(start 271.199864 -132.876036)
		(end 271.199864 -130.902456)
		(width 0.4064)
		(layer "B.Cu")
		(net "PVDDQ_DEF")
	)
	(segment
		(start 250.799854 -141.187678)
		(end 250.799854 -142.477236)
		(width 0.4064)
		(layer "B.Cu")
		(net "PVDDQ_DEF")
	)
	(segment
		(start 268.649958 -148.769578)
		(end 268.649958 -147.478496)
		(width 0.4064)
		(layer "B.Cu")
		(net "PVDDQ_DEF")
	)
	(segment
		(start 250.799854 -130.902456)
		(end 250.996704 -130.902456)
		(width 0.4064)
		(layer "B.Cu")
		(net "PVDDQ_DEF")
	)
	(segment
		(start 193.675 -154.559)
		(end 193.675 -154.051)
		(width 0.4064)
		(layer "B.Cu")
		(net "PVDDQ_DEF")
	)
	(segment
		(start 268.649958 -139.168378)
		(end 268.649958 -137.877296)
		(width 0.4064)
		(layer "B.Cu")
		(net "PVDDQ_DEF")
	)
	(segment
		(start 258.896358 -148.686012)
		(end 258.896358 -148.771356)
		(width 0.381)
		(layer "B.Cu")
		(net "PVDDQ_DEF")
	)
	(segment
		(start 266.950444 -132.876036)
		(end 266.949936 -132.876036)
		(width 0.4064)
		(layer "B.Cu")
		(net "PVDDQ_DEF")
	)
	(segment
		(start 249.099832 -136.387078)
		(end 249.10034 -136.387586)
		(width 0.4064)
		(layer "B.Cu")
		(net "PVDDQ_DEF")
	)
	(segment
		(start 193.802 -134.874)
		(end 193.802 -134.62)
		(width 0.4064)
		(layer "B.Cu")
		(net "PVDDQ_DEF")
	)
	(segment
		(start 269.499842 -141.187932)
		(end 269.499842 -142.477236)
		(width 0.4064)
		(layer "B.Cu")
		(net "PVDDQ_DEF")
	)
	(segment
		(start 266.099798 -137.877296)
		(end 266.099798 -139.168378)
		(width 0.4064)
		(layer "B.Cu")
		(net "PVDDQ_DEF")
	)
	(segment
		(start 271.199864 -141.183868)
		(end 271.199864 -142.477236)
		(width 0.4064)
		(layer "B.Cu")
		(net "PVDDQ_DEF")
	)
	(segment
		(start 268.649958 -147.478496)
		(end 268.650466 -147.478496)
		(width 0.4064)
		(layer "B.Cu")
		(net "PVDDQ_DEF")
	)
	(segment
		(start 271.199864 -134.340346)
		(end 271.199864 -132.876036)
		(width 0.4064)
		(layer "B.Cu")
		(net "PVDDQ_DEF")
	)
	(segment
		(start 277.149814 -128.276096)
		(end 277.149814 -125.911102)
		(width 0.4064)
		(layer "B.Cu")
		(net "PVDDQ_DEF")
	)
	(segment
		(start 274.599908 -146.025108)
		(end 274.599908 -147.478496)
		(width 0.4064)
		(layer "B.Cu")
		(net "PVDDQ_DEF")
	)
	(segment
		(start 253.350522 -134.37108)
		(end 253.350522 -132.876036)
		(width 0.4064)
		(layer "B.Cu")
		(net "PVDDQ_DEF")
	)
	(segment
		(start 244.849904 -136.387078)
		(end 244.849904 -137.877296)
		(width 0.4064)
		(layer "B.Cu")
		(net "PVDDQ_DEF")
	)
	(segment
		(start 266.949936 -132.876036)
		(end 266.949936 -134.285736)
		(width 0.4064)
		(layer "B.Cu")
		(net "PVDDQ_DEF")
	)
	(segment
		(start 275.449792 -131.611878)
		(end 275.4503 -131.612386)
		(width 0.381)
		(layer "B.Cu")
		(net "PVDDQ_DEF")
	)
	(segment
		(start 255.909572 -143.970756)
		(end 255.89992 -143.961104)
		(width 0.4064)
		(layer "B.Cu")
		(net "PVDDQ_DEF")
	)
	(segment
		(start 272.899886 -137.877296)
		(end 272.900394 -137.877296)
		(width 0.4064)
		(layer "B.Cu")
		(net "PVDDQ_DEF")
	)
	(segment
		(start 269.500096 -141.187678)
		(end 269.499842 -141.187932)
		(width 0.4064)
		(layer "B.Cu")
		(net "PVDDQ_DEF")
	)
	(segment
		(start 255.89992 -147.478496)
		(end 255.89992 -145.984468)
		(width 0.4064)
		(layer "B.Cu")
		(net "PVDDQ_DEF")
	)
	(segment
		(start 275.449792 -143.97228)
		(end 275.449792 -142.477236)
		(width 0.4064)
		(layer "B.Cu")
		(net "PVDDQ_DEF")
	)
	(segment
		(start 258.3942 -139.170156)
		(end 258.449826 -139.11453)
		(width 0.4064)
		(layer "B.Cu")
		(net "PVDDQ_DEF")
	)
	(segment
		(start 258.449826 -146.131026)
		(end 258.303268 -145.984468)
		(width 0.381)
		(layer "B.Cu")
		(net "PVDDQ_DEF")
	)
	(segment
		(start 277.150322 -128.276096)
		(end 277.149814 -128.276096)
		(width 0.4064)
		(layer "B.Cu")
		(net "PVDDQ_DEF")
	)
	(segment
		(start 250.799854 -132.876036)
		(end 250.799854 -130.902456)
		(width 0.4064)
		(layer "B.Cu")
		(net "PVDDQ_DEF")
	)
	(segment
		(start 245.815612 -126.50724)
		(end 245.815612 -125.55601)
		(width 0.4064)
		(layer "B.Cu")
		(net "PVDDQ_DEF")
	)
	(segment
		(start 244.849904 -128.276096)
		(end 244.849904 -130.249168)
		(width 0.4064)
		(layer "B.Cu")
		(net "PVDDQ_DEF")
	)
	(segment
		(start 193.802 -134.62)
		(end 194.1576 -134.2644)
		(width 0.4064)
		(layer "B.Cu")
		(net "PVDDQ_DEF")
	)
	(segment
		(start 277.149814 -142.477236)
		(end 277.149814 -143.968978)
		(width 0.4064)
		(layer "B.Cu")
		(net "PVDDQ_DEF")
	)
	(segment
		(start 255.89992 -137.877296)
		(end 255.89992 -139.119356)
		(width 0.4064)
		(layer "B.Cu")
		(net "PVDDQ_DEF")
	)
	(segment
		(start 245.699788 -141.187678)
		(end 245.699788 -142.477236)
		(width 0.4064)
		(layer "B.Cu")
		(net "PVDDQ_DEF")
	)
	(segment
		(start 269.50035 -132.876036)
		(end 269.499842 -132.876036)
		(width 0.4064)
		(layer "B.Cu")
		(net "PVDDQ_DEF")
	)
	(segment
		(start 244.849904 -137.877296)
		(end 244.850412 -137.877296)
		(width 0.4064)
		(layer "B.Cu")
		(net "PVDDQ_DEF")
	)
	(segment
		(start 250.800362 -142.477236)
		(end 250.799854 -142.477236)
		(width 0.4064)
		(layer "B.Cu")
		(net "PVDDQ_DEF")
	)
	(segment
		(start 272.899886 -148.769578)
		(end 272.899886 -147.478496)
		(width 0.4064)
		(layer "B.Cu")
		(net "PVDDQ_DEF")
	)
	(segment
		(start 275.449792 -150.789386)
		(end 275.4503 -150.788878)
		(width 0.4064)
		(layer "B.Cu")
		(net "PVDDQ_DEF")
	)
	(segment
		(start 266.949936 -131.612132)
		(end 266.949936 -132.876036)
		(width 0.4064)
		(layer "B.Cu")
		(net "PVDDQ_DEF")
	)
	(segment
		(start 258.450334 -137.877296)
		(end 258.449826 -137.877296)
		(width 0.4064)
		(layer "B.Cu")
		(net "PVDDQ_DEF")
	)
	(segment
		(start 245.700296 -132.876036)
		(end 245.699788 -132.876036)
		(width 0.4064)
		(layer "B.Cu")
		(net "PVDDQ_DEF")
	)
	(segment
		(start 266.949936 -142.477236)
		(end 266.950444 -142.477236)
		(width 0.4064)
		(layer "B.Cu")
		(net "PVDDQ_DEF")
	)
	(segment
		(start 258.449826 -153.571956)
		(end 258.449826 -152.078436)
		(width 0.4064)
		(layer "B.Cu")
		(net "PVDDQ_DEF")
	)
	(segment
		(start 273.74977 -141.188186)
		(end 273.74977 -142.477236)
		(width 0.4064)
		(layer "B.Cu")
		(net "PVDDQ_DEF")
	)
	(segment
		(start 269.499842 -132.876036)
		(end 269.499842 -130.902456)
		(width 0.4064)
		(layer "B.Cu")
		(net "PVDDQ_DEF")
	)
	(segment
		(start 258.272026 -141.183868)
		(end 258.449826 -141.361668)
		(width 0.4064)
		(layer "B.Cu")
		(net "PVDDQ_DEF")
	)
	(segment
		(start 272.899886 -146.001486)
		(end 272.899886 -147.478496)
		(width 0.4064)
		(layer "B.Cu")
		(net "PVDDQ_DEF")
	)
	(segment
		(start 266.099798 -136.383268)
		(end 266.099798 -137.877296)
		(width 0.4064)
		(layer "B.Cu")
		(net "PVDDQ_DEF")
	)
	(segment
		(start 255.900428 -134.35076)
		(end 255.900428 -132.876036)
		(width 0.4064)
		(layer "B.Cu")
		(net "PVDDQ_DEF")
	)
	(segment
		(start 244.850412 -147.478496)
		(end 244.849904 -147.478496)
		(width 0.4064)
		(layer "B.Cu")
		(net "PVDDQ_DEF")
	)
	(segment
		(start 258.184142 -129.568956)
		(end 258.450334 -129.302764)
		(width 0.4064)
		(layer "B.Cu")
		(net "PVDDQ_DEF")
	)
	(segment
		(start 258.450334 -131.1148)
		(end 258.450334 -132.875274)
		(width 0.4064)
		(layer "B.Cu")
		(net "PVDDQ_DEF")
	)
	(segment
		(start 275.449792 -152.078436)
		(end 275.449792 -154.252168)
		(width 0.4064)
		(layer "B.Cu")
		(net "PVDDQ_DEF")
	)
	(segment
		(start 273.74977 -142.477236)
		(end 273.74977 -143.97228)
		(width 0.4064)
		(layer "B.Cu")
		(net "PVDDQ_DEF")
	)
	(segment
		(start 253.350014 -142.477236)
		(end 253.350014 -143.972788)
		(width 0.4064)
		(layer "B.Cu")
		(net "PVDDQ_DEF")
	)
	(segment
		(start 249.099832 -145.988278)
		(end 249.099832 -147.478496)
		(width 0.4064)
		(layer "B.Cu")
		(net "PVDDQ_DEF")
	)
	(segment
		(start 258.184142 -130.848608)
		(end 258.450334 -131.1148)
		(width 0.4064)
		(layer "B.Cu")
		(net "PVDDQ_DEF")
	)
	(segment
		(start 258.303268 -145.984468)
		(end 258.2672 -145.984468)
		(width 0.381)
		(layer "B.Cu")
		(net "PVDDQ_DEF")
	)
	(segment
		(start 244.000274 -132.876036)
		(end 243.999766 -132.876036)
		(width 0.4064)
		(layer "B.Cu")
		(net "PVDDQ_DEF")
	)
	(segment
		(start 258.450334 -147.478496)
		(end 258.449826 -147.478496)
		(width 0.381)
		(layer "B.Cu")
		(net "PVDDQ_DEF")
	)
	(segment
		(start 250.799854 -150.788878)
		(end 250.799854 -152.078436)
		(width 0.4064)
		(layer "B.Cu")
		(net "PVDDQ_DEF")
	)
	(segment
		(start 275.449792 -142.477236)
		(end 275.4503 -142.477236)
		(width 0.4064)
		(layer "B.Cu")
		(net "PVDDQ_DEF")
	)
	(segment
		(start 255.89992 -134.351268)
		(end 255.900428 -134.35076)
		(width 0.4064)
		(layer "B.Cu")
		(net "PVDDQ_DEF")
	)
	(segment
		(start 250.800362 -134.369048)
		(end 250.800362 -132.876036)
		(width 0.4064)
		(layer "B.Cu")
		(net "PVDDQ_DEF")
	)
	(segment
		(start 250.800362 -132.876036)
		(end 250.799854 -132.876036)
		(width 0.4064)
		(layer "B.Cu")
		(net "PVDDQ_DEF")
	)
	(segment
		(start 246.549926 -128.276096)
		(end 246.550434 -128.276096)
		(width 0.4064)
		(layer "B.Cu")
		(net "PVDDQ_DEF")
	)
	(segment
		(start 249.10034 -136.387586)
		(end 249.10034 -137.877296)
		(width 0.4064)
		(layer "B.Cu")
		(net "PVDDQ_DEF")
	)
	(segment
		(start 275.4503 -143.972788)
		(end 275.449792 -143.97228)
		(width 0.4064)
		(layer "B.Cu")
		(net "PVDDQ_DEF")
	)
	(segment
		(start 193.675 -154.051)
		(end 194.1576 -153.5684)
		(width 0.4064)
		(layer "B.Cu")
		(net "PVDDQ_DEF")
	)
	(segment
		(start 277.149814 -131.586478)
		(end 277.149814 -130.249168)
		(width 0.4064)
		(layer "B.Cu")
		(net "PVDDQ_DEF")
	)
	(segment
		(start 258.449826 -132.876036)
		(end 258.449826 -134.380478)
		(width 0.4064)
		(layer "B.Cu")
		(net "PVDDQ_DEF")
	)
	(segment
		(start 271.199864 -142.477236)
		(end 271.200372 -142.477236)
		(width 0.4064)
		(layer "B.Cu")
		(net "PVDDQ_DEF")
	)
	(segment
		(start 251.6505 -136.387586)
		(end 251.6505 -137.877296)
		(width 0.4064)
		(layer "B.Cu")
		(net "PVDDQ_DEF")
	)
	(segment
		(start 277.149814 -148.769578)
		(end 277.149814 -147.478496)
		(width 0.4064)
		(layer "B.Cu")
		(net "PVDDQ_DEF")
	)
	(segment
		(start 258.3942 -136.1948)
		(end 258.449826 -136.250426)
		(width 0.4064)
		(layer "B.Cu")
		(net "PVDDQ_DEF")
	)
	(segment
		(start 266.099798 -147.478496)
		(end 266.100306 -147.478496)
		(width 0.4064)
		(layer "B.Cu")
		(net "PVDDQ_DEF")
	)
	(segment
		(start 272.899886 -136.383268)
		(end 272.899886 -137.877296)
		(width 0.4064)
		(layer "B.Cu")
		(net "PVDDQ_DEF")
	)
	(segment
		(start 250.799854 -142.477236)
		(end 250.799854 -143.970756)
		(width 0.4064)
		(layer "B.Cu")
		(net "PVDDQ_DEF")
	)
	(segment
		(start 275.4503 -141.187678)
		(end 275.449792 -141.188186)
		(width 0.4064)
		(layer "B.Cu")
		(net "PVDDQ_DEF")
	)
	(segment
		(start 258.449826 -139.11453)
		(end 258.449826 -137.877296)
		(width 0.4064)
		(layer "B.Cu")
		(net "PVDDQ_DEF")
	)
	(segment
		(start 248.249948 -132.876036)
		(end 248.249948 -131.611878)
		(width 0.4064)
		(layer "B.Cu")
		(net "PVDDQ_DEF")
	)
	(segment
		(start 273.74977 -150.814532)
		(end 273.74977 -152.078436)
		(width 0.4064)
		(layer "B.Cu")
		(net "PVDDQ_DEF")
	)
	(segment
		(start 248.249948 -134.369556)
		(end 248.249948 -132.876036)
		(width 0.4064)
		(layer "B.Cu")
		(net "PVDDQ_DEF")
	)
	(segment
		(start 277.149814 -141.183868)
		(end 277.149814 -142.477236)
		(width 0.4064)
		(layer "B.Cu")
		(net "PVDDQ_DEF")
	)
	(segment
		(start 268.649958 -146.013932)
		(end 268.649958 -147.478496)
		(width 0.4064)
		(layer "B.Cu")
		(net "PVDDQ_DEF")
	)
	(segment
		(start 277.149814 -137.877296)
		(end 277.150322 -137.877296)
		(width 0.4064)
		(layer "B.Cu")
		(net "PVDDQ_DEF")
	)
	(segment
		(start 244.172486 -126.6063)
		(end 244.172486 -126.780544)
		(width 0.4064)
		(layer "B.Cu")
		(net "PVDDQ_DEF")
	)
	(segment
		(start 244.850412 -128.276096)
		(end 244.849904 -128.276096)
		(width 0.4064)
		(layer "B.Cu")
		(net "PVDDQ_DEF")
	)
	(segment
		(start 243.999766 -152.078436)
		(end 243.999766 -150.788878)
		(width 0.4064)
		(layer "B.Cu")
		(net "PVDDQ_DEF")
	)
	(segment
		(start 183.515 -145.1864)
		(end 183.515 -145.796)
		(width 0.254)
		(layer "B.Cu")
		(net "PVDDQ_DEF")
	)
	(segment
		(start 258.449826 -142.477236)
		(end 258.449826 -143.799052)
		(width 0.4064)
		(layer "B.Cu")
		(net "PVDDQ_DEF")
	)
	(segment
		(start 271.200372 -148.741638)
		(end 271.199864 -148.742146)
		(width 0.4064)
		(layer "B.Cu")
		(net "PVDDQ_DEF")
	)
	(segment
		(start 248.250456 -142.477236)
		(end 248.249948 -142.477236)
		(width 0.4064)
		(layer "B.Cu")
		(net "PVDDQ_DEF")
	)
	(segment
		(start 251.649992 -136.387078)
		(end 251.6505 -136.387586)
		(width 0.4064)
		(layer "B.Cu")
		(net "PVDDQ_DEF")
	)
	(segment
		(start 253.350014 -132.876036)
		(end 253.350014 -131.611878)
		(width 0.4064)
		(layer "B.Cu")
		(net "PVDDQ_DEF")
	)
	(segment
		(start 269.499842 -142.477236)
		(end 269.50035 -142.477236)
		(width 0.4064)
		(layer "B.Cu")
		(net "PVDDQ_DEF")
	)
	(segment
		(start 277.149814 -134.367778)
		(end 277.150322 -134.36727)
		(width 0.381)
		(layer "B.Cu")
		(net "PVDDQ_DEF")
	)
	(segment
		(start 271.200372 -145.984976)
		(end 271.199864 -145.984468)
		(width 0.4064)
		(layer "B.Cu")
		(net "PVDDQ_DEF")
	)
	(segment
		(start 276.933152 -125.69444)
		(end 275.73986 -125.69444)
		(width 0.4064)
		(layer "B.Cu")
		(net "PVDDQ_DEF")
	)
	(segment
		(start 246.549926 -127.241554)
		(end 245.815612 -126.50724)
		(width 0.4064)
		(layer "B.Cu")
		(net "PVDDQ_DEF")
	)
	(segment
		(start 255.685036 -150.785068)
		(end 255.89992 -150.999952)
		(width 0.4064)
		(layer "B.Cu")
		(net "PVDDQ_DEF")
	)
	(segment
		(start 259.491988 -135.3312)
		(end 259.5372 -135.376412)
		(width 0.4572)
		(layer "B.Cu")
		(net "PVDDQ_DEF")
	)
	(segment
		(start 258.449826 -147.478496)
		(end 258.449826 -148.23948)
		(width 0.381)
		(layer "B.Cu")
		(net "PVDDQ_DEF")
	)
	(segment
		(start 266.949936 -152.078436)
		(end 266.949936 -150.785068)
		(width 0.4064)
		(layer "B.Cu")
		(net "PVDDQ_DEF")
	)
	(segment
		(start 255.89992 -137.877296)
		(end 255.89992 -136.33831)
		(width 0.4064)
		(layer "B.Cu")
		(net "PVDDQ_DEF")
	)
	(segment
		(start 255.89992 -136.33831)
		(end 255.909572 -136.328658)
		(width 0.4064)
		(layer "B.Cu")
		(net "PVDDQ_DEF")
	)
	(segment
		(start 255.89992 -150.999952)
		(end 255.89992 -152.078436)
		(width 0.4064)
		(layer "B.Cu")
		(net "PVDDQ_DEF")
	)
	(segment
		(start 254.200406 -128.276096)
		(end 254.199898 -128.276096)
		(width 0.4064)
		(layer "B.Cu")
		(net "PVDDQ_DEF")
	)
	(segment
		(start 276.933152 -125.69444)
		(end 277.149814 -125.911102)
		(width 0.4064)
		(layer "B.Cu")
		(net "PVDDQ_DEF")
	)
	(segment
		(start 275.4503 -131.612386)
		(end 275.4503 -132.876036)
		(width 0.381)
		(layer "B.Cu")
		(net "PVDDQ_DEF")
	)
	(segment
		(start 244.849904 -127.321564)
		(end 244.308884 -126.780544)
		(width 0.4064)
		(layer "B.Cu")
		(net "PVDDQ_DEF")
	)
	(segment
		(start 255.89992 -142.477236)
		(end 255.900428 -142.477236)
		(width 0.4064)
		(layer "B.Cu")
		(net "PVDDQ_DEF")
	)
	(segment
		(start 255.89992 -148.556218)
		(end 255.89992 -147.478496)
		(width 0.4064)
		(layer "B.Cu")
		(net "PVDDQ_DEF")
	)
	(segment
		(start 253.350522 -152.078436)
		(end 253.350014 -152.078436)
		(width 0.4064)
		(layer "B.Cu")
		(net "PVDDQ_DEF")
	)
	(segment
		(start 269.500096 -143.972788)
		(end 269.499842 -143.972534)
		(width 0.4064)
		(layer "B.Cu")
		(net "PVDDQ_DEF")
	)
	(segment
		(start 245.699788 -134.369556)
		(end 245.699788 -132.876036)
		(width 0.4064)
		(layer "B.Cu")
		(net "PVDDQ_DEF")
	)
	(segment
		(start 244.5512 -125.55601)
		(end 244.5512 -126.227586)
		(width 0.4064)
		(layer "B.Cu")
		(net "PVDDQ_DEF")
	)
	(segment
		(start 246.549926 -128.276096)
		(end 246.549926 -127.241554)
		(width 0.4064)
		(layer "B.Cu")
		(net "PVDDQ_DEF")
	)
	(segment
		(start 272.899886 -139.168378)
		(end 272.899886 -137.877296)
		(width 0.4064)
		(layer "B.Cu")
		(net "PVDDQ_DEF")
	)
	(segment
		(start 274.599908 -147.478496)
		(end 274.600416 -147.478496)
		(width 0.4064)
		(layer "B.Cu")
		(net "PVDDQ_DEF")
	)
	(segment
		(start 275.449792 -152.078436)
		(end 275.449792 -150.789386)
		(width 0.4064)
		(layer "B.Cu")
		(net "PVDDQ_DEF")
	)
	(segment
		(start 243.999766 -152.078436)
		(end 244.000274 -152.078436)
		(width 0.4064)
		(layer "B.Cu")
		(net "PVDDQ_DEF")
	)
	(segment
		(start 245.699788 -152.078436)
		(end 245.700296 -152.078436)
		(width 0.4064)
		(layer "B.Cu")
		(net "PVDDQ_DEF")
	)
	(segment
		(start 258.450334 -132.875274)
		(end 258.449826 -132.875782)
		(width 0.4064)
		(layer "B.Cu")
		(net "PVDDQ_DEF")
	)
	(segment
		(start 275.4503 -152.078436)
		(end 275.449792 -152.078436)
		(width 0.4064)
		(layer "B.Cu")
		(net "PVDDQ_DEF")
	)
	(segment
		(start 183.4388 -145.1102)
		(end 183.515 -145.1864)
		(width 0.254)
		(layer "B.Cu")
		(net "PVDDQ_DEF")
	)
	(segment
		(start 255.684782 -148.771356)
		(end 255.89992 -148.556218)
		(width 0.4064)
		(layer "B.Cu")
		(net "PVDDQ_DEF")
	)
	(segment
		(start 251.649992 -147.478496)
		(end 251.6505 -147.478496)
		(width 0.4064)
		(layer "B.Cu")
		(net "PVDDQ_DEF")
	)
	(segment
		(start 255.900428 -128.276096)
		(end 255.89992 -128.276096)
		(width 0.4064)
		(layer "B.Cu")
		(net "PVDDQ_DEF")
	)
	(segment
		(start 274.28952 -126.675388)
		(end 274.599908 -126.985776)
		(width 0.4064)
		(layer "B.Cu")
		(net "PVDDQ_DEF")
	)
	(segment
		(start 244.849904 -128.276096)
		(end 244.849904 -127.321564)
		(width 0.4064)
		(layer "B.Cu")
		(net "PVDDQ_DEF")
	)
	(segment
		(start 258.450334 -142.477236)
		(end 258.449826 -142.477236)
		(width 0.4064)
		(layer "B.Cu")
		(net "PVDDQ_DEF")
	)
	(segment
		(start 246.549926 -147.478496)
		(end 246.550434 -147.478496)
		(width 0.4064)
		(layer "B.Cu")
		(net "PVDDQ_DEF")
	)
	(segment
		(start 255.89992 -129.303272)
		(end 256.165604 -129.568956)
		(width 0.4064)
		(layer "B.Cu")
		(net "PVDDQ_DEF")
	)
	(segment
		(start 253.350522 -142.477236)
		(end 253.350014 -142.477236)
		(width 0.4064)
		(layer "B.Cu")
		(net "PVDDQ_DEF")
	)
	(segment
		(start 258.318 -134.512304)
		(end 258.449826 -134.380478)
		(width 0.4572)
		(layer "B.Cu")
		(net "PVDDQ_DEF")
	)
	(segment
		(start 271.200372 -147.478496)
		(end 271.200372 -145.984976)
		(width 0.4064)
		(layer "B.Cu")
		(net "PVDDQ_DEF")
	)
	(segment
		(start 244.308884 -126.780544)
		(end 244.172486 -126.780544)
		(width 0.4064)
		(layer "B.Cu")
		(net "PVDDQ_DEF")
	)
	(segment
		(start 274.599908 -137.877296)
		(end 274.600416 -137.877296)
		(width 0.4064)
		(layer "B.Cu")
		(net "PVDDQ_DEF")
	)
	(segment
		(start 253.350014 -134.371588)
		(end 253.350522 -134.37108)
		(width 0.4064)
		(layer "B.Cu")
		(net "PVDDQ_DEF")
	)
	(segment
		(start 266.099798 -145.984468)
		(end 266.099798 -147.478496)
		(width 0.4064)
		(layer "B.Cu")
		(net "PVDDQ_DEF")
	)
	(segment
		(start 255.900428 -152.078436)
		(end 255.89992 -152.078436)
		(width 0.4064)
		(layer "B.Cu")
		(net "PVDDQ_DEF")
	)
	(segment
		(start 246.549926 -139.170156)
		(end 246.549926 -137.877296)
		(width 0.4064)
		(layer "B.Cu")
		(net "PVDDQ_DEF")
	)
	(segment
		(start 258.449826 -152.078436)
		(end 258.449826 -150.785068)
		(width 0.4064)
		(layer "B.Cu")
		(net "PVDDQ_DEF")
	)
	(segment
		(start 244.000274 -142.477236)
		(end 243.999766 -142.477236)
		(width 0.4064)
		(layer "B.Cu")
		(net "PVDDQ_DEF")
	)
	(segment
		(start 277.149814 -131.586478)
		(end 277.149814 -132.876036)
		(width 0.4064)
		(layer "B.Cu")
		(net "PVDDQ_DEF")
	)
	(segment
		(start 277.150322 -152.078436)
		(end 277.149814 -152.078436)
		(width 0.4064)
		(layer "B.Cu")
		(net "PVDDQ_DEF")
	)
	(segment
		(start 258.450334 -132.876036)
		(end 258.449826 -132.876036)
		(width 0.4064)
		(layer "B.Cu")
		(net "PVDDQ_DEF")
	)
	(segment
		(start 258.449826 -136.250426)
		(end 258.449826 -137.877296)
		(width 0.4064)
		(layer "B.Cu")
		(net "PVDDQ_DEF")
	)
	(segment
		(start 269.500096 -150.814278)
		(end 269.499842 -150.814532)
		(width 0.4064)
		(layer "B.Cu")
		(net "PVDDQ_DEF")
	)
	(segment
		(start 255.89992 -132.876036)
		(end 255.900428 -132.876036)
		(width 0.4064)
		(layer "B.Cu")
		(net "PVDDQ_DEF")
	)
	(segment
		(start 266.949936 -143.972534)
		(end 266.949936 -142.477236)
		(width 0.4064)
		(layer "B.Cu")
		(net "PVDDQ_DEF")
	)
	(segment
		(start 273.750278 -141.187678)
		(end 273.74977 -141.188186)
		(width 0.4064)
		(layer "B.Cu")
		(net "PVDDQ_DEF")
	)
	(segment
		(start 271.199864 -137.877296)
		(end 271.199864 -136.383268)
		(width 0.4064)
		(layer "B.Cu")
		(net "PVDDQ_DEF")
	)
	(segment
		(start 269.499842 -152.078436)
		(end 269.50035 -152.078436)
		(width 0.4064)
		(layer "B.Cu")
		(net "PVDDQ_DEF")
	)
	(segment
		(start 277.150322 -134.36727)
		(end 277.150322 -132.876036)
		(width 0.381)
		(layer "B.Cu")
		(net "PVDDQ_DEF")
	)
	(segment
		(start 255.90627 -141.18717)
		(end 255.909572 -141.183868)
		(width 0.4064)
		(layer "B.Cu")
		(net "PVDDQ_DEF")
	)
	(segment
		(start 251.649992 -145.988278)
		(end 251.649992 -147.478496)
		(width 0.4064)
		(layer "B.Cu")
		(net "PVDDQ_DEF")
	)
	(segment
		(start 251.649992 -148.773388)
		(end 251.649992 -147.478496)
		(width 0.4064)
		(layer "B.Cu")
		(net "PVDDQ_DEF")
	)
	(segment
		(start 251.649992 -128.276096)
		(end 251.6505 -128.276096)
		(width 0.4064)
		(layer "B.Cu")
		(net "PVDDQ_DEF")
	)
	(segment
		(start 258.184142 -130.848608)
		(end 258.184142 -129.568956)
		(width 0.4064)
		(layer "B.Cu")
		(net "PVDDQ_DEF")
	)
	(segment
		(start 249.099832 -147.478496)
		(end 249.10034 -147.478496)
		(width 0.4064)
		(layer "B.Cu")
		(net "PVDDQ_DEF")
	)
	(segment
		(start 274.599908 -137.877296)
		(end 274.599908 -136.449308)
		(width 0.4064)
		(layer "B.Cu")
		(net "PVDDQ_DEF")
	)
	(segment
		(start 248.249948 -152.078436)
		(end 248.250456 -152.078436)
		(width 0.4064)
		(layer "B.Cu")
		(net "PVDDQ_DEF")
	)
	(segment
		(start 245.699788 -142.477236)
		(end 245.699788 -143.970756)
		(width 0.4064)
		(layer "B.Cu")
		(net "PVDDQ_DEF")
	)
	(segment
		(start 258.449826 -147.478496)
		(end 258.449826 -146.131026)
		(width 0.381)
		(layer "B.Cu")
		(net "PVDDQ_DEF")
	)
	(segment
		(start 254.199898 -145.988278)
		(end 254.199898 -147.478496)
		(width 0.4064)
		(layer "B.Cu")
		(net "PVDDQ_DEF")
	)
	(segment
		(start 273.750278 -132.876036)
		(end 273.74977 -132.876036)
		(width 0.4064)
		(layer "B.Cu")
		(net "PVDDQ_DEF")
	)
	(segment
		(start 254.200406 -136.387586)
		(end 254.200406 -137.877296)
		(width 0.4064)
		(layer "B.Cu")
		(net "PVDDQ_DEF")
	)
	(segment
		(start 193.548 -144.0942)
		(end 193.548 -144.4752)
		(width 0.4064)
		(layer "B.Cu")
		(net "PVDDQ_DEF")
	)
	(segment
		(start 255.89992 -152.078436)
		(end 255.89992 -153.571956)
		(width 0.4064)
		(layer "B.Cu")
		(net "PVDDQ_DEF")
	)
	(segment
		(start 253.350014 -154.252168)
		(end 253.350014 -152.078436)
		(width 0.4064)
		(layer "B.Cu")
		(net "PVDDQ_DEF")
	)
	(segment
		(start 254.199898 -137.877296)
		(end 254.200406 -137.877296)
		(width 0.4064)
		(layer "B.Cu")
		(net "PVDDQ_DEF")
	)
	(segment
		(start 271.200372 -147.478496)
		(end 271.200372 -148.741638)
		(width 0.4064)
		(layer "B.Cu")
		(net "PVDDQ_DEF")
	)
	(segment
		(start 254.199898 -147.478496)
		(end 254.200406 -147.478496)
		(width 0.4064)
		(layer "B.Cu")
		(net "PVDDQ_DEF")
	)
	(segment
		(start 245.699788 -130.902456)
		(end 246.353076 -130.249168)
		(width 0.4064)
		(layer "B.Cu")
		(net "PVDDQ_DEF")
	)
	(segment
		(start 258.449826 -141.361668)
		(end 258.449826 -142.477236)
		(width 0.4064)
		(layer "B.Cu")
		(net "PVDDQ_DEF")
	)
	(segment
		(start 269.500096 -150.788878)
		(end 269.500096 -150.814278)
		(width 0.4064)
		(layer "B.Cu")
		(net "PVDDQ_DEF")
	)
	(segment
		(start 245.699788 -132.876036)
		(end 245.699788 -130.902456)
		(width 0.4064)
		(layer "B.Cu")
		(net "PVDDQ_DEF")
	)
	(segment
		(start 256.165604 -129.568956)
		(end 256.1971 -129.600452)
		(width 0.4064)
		(layer "B.Cu")
		(net "PVDDQ_DEF")
	)
	(segment
		(start 256.1971 -130.8608)
		(end 255.89992 -131.15798)
		(width 0.4064)
		(layer "B.Cu")
		(net "PVDDQ_DEF")
	)
	(segment
		(start 271.199864 -152.078436)
		(end 271.199864 -153.542746)
		(width 0.4064)
		(layer "B.Cu")
		(net "PVDDQ_DEF")
	)
	(segment
		(start 255.89992 -147.478496)
		(end 255.900428 -147.478496)
		(width 0.4064)
		(layer "B.Cu")
		(net "PVDDQ_DEF")
	)
	(segment
		(start 269.499842 -152.078436)
		(end 269.499842 -153.571956)
		(width 0.4064)
		(layer "B.Cu")
		(net "PVDDQ_DEF")
	)
	(segment
		(start 253.350014 -152.078436)
		(end 253.350014 -150.788878)
		(width 0.4064)
		(layer "B.Cu")
		(net "PVDDQ_DEF")
	)
	(segment
		(start 243.999766 -142.477236)
		(end 243.999766 -143.970756)
		(width 0.4064)
		(layer "B.Cu")
		(net "PVDDQ_DEF")
	)
	(segment
		(start 248.249948 -152.078436)
		(end 248.249948 -154.252168)
		(width 0.4064)
		(layer "B.Cu")
		(net "PVDDQ_DEF")
	)
	(segment
		(start 273.74977 -142.477236)
		(end 273.750278 -142.477236)
		(width 0.4064)
		(layer "B.Cu")
		(net "PVDDQ_DEF")
	)
	(segment
		(start 273.74977 -152.078436)
		(end 273.750278 -152.078436)
		(width 0.4064)
		(layer "B.Cu")
		(net "PVDDQ_DEF")
	)
	(segment
		(start 275.449792 -141.188186)
		(end 275.449792 -142.477236)
		(width 0.4064)
		(layer "B.Cu")
		(net "PVDDQ_DEF")
	)
	(segment
		(start 269.499842 -153.571956)
		(end 269.499842 -153.573734)
		(width 0.4064)
		(layer "B.Cu")
		(net "PVDDQ_DEF")
	)
	(segment
		(start 249.099832 -137.877296)
		(end 249.10034 -137.877296)
		(width 0.4064)
		(layer "B.Cu")
		(net "PVDDQ_DEF")
	)
	(segment
		(start 255.89992 -143.961104)
		(end 255.89992 -142.477236)
		(width 0.4064)
		(layer "B.Cu")
		(net "PVDDQ_DEF")
	)
	(segment
		(start 250.799854 -152.078436)
		(end 250.799854 -153.542746)
		(width 0.4064)
		(layer "B.Cu")
		(net "PVDDQ_DEF")
	)
	(segment
		(start 266.949682 -131.611878)
		(end 266.949936 -131.612132)
		(width 0.254)
		(layer "B.Cu")
		(net "PVDDQ_DEF")
	)
	(segment
		(start 271.199864 -137.877296)
		(end 271.200372 -137.877296)
		(width 0.4064)
		(layer "B.Cu")
		(net "PVDDQ_DEF")
	)
	(segment
		(start 277.149814 -145.988278)
		(end 277.149814 -147.478496)
		(width 0.4064)
		(layer "B.Cu")
		(net "PVDDQ_DEF")
	)
	(segment
		(start 277.149814 -150.785068)
		(end 277.149814 -152.078436)
		(width 0.4064)
		(layer "B.Cu")
		(net "PVDDQ_DEF")
	)
	(segment
		(start 273.750278 -152.078436)
		(end 273.750278 -154.25166)
		(width 0.4064)
		(layer "B.Cu")
		(net "PVDDQ_DEF")
	)
	(segment
		(start 255.89992 -137.877296)
		(end 255.900428 -137.877296)
		(width 0.4064)
		(layer "B.Cu")
		(net "PVDDQ_DEF")
	)
	(segment
		(start 256.1971 -129.600452)
		(end 256.1971 -130.8608)
		(width 0.4064)
		(layer "B.Cu")
		(net "PVDDQ_DEF")
	)
	(segment
		(start 253.350014 -141.187678)
		(end 253.350014 -142.477236)
		(width 0.4064)
		(layer "B.Cu")
		(net "PVDDQ_DEF")
	)
	(segment
		(start 245.700296 -142.477236)
		(end 245.699788 -142.477236)
		(width 0.4064)
		(layer "B.Cu")
		(net "PVDDQ_DEF")
	)
	(segment
		(start 266.949936 -154.251914)
		(end 266.949682 -154.252168)
		(width 0.4064)
		(layer "B.Cu")
		(net "PVDDQ_DEF")
	)
	(segment
		(start 246.353076 -130.249168)
		(end 246.549926 -130.249168)
		(width 0.4064)
		(layer "B.Cu")
		(net "PVDDQ_DEF")
	)
	(segment
		(start 249.099832 -139.170156)
		(end 249.099832 -137.877296)
		(width 0.4064)
		(layer "B.Cu")
		(net "PVDDQ_DEF")
	)
	(segment
		(start 269.499842 -150.814532)
		(end 269.499842 -152.078436)
		(width 0.4064)
		(layer "B.Cu")
		(net "PVDDQ_DEF")
	)
	(segment
		(start 255.89992 -139.119356)
		(end 255.84912 -139.170156)
		(width 0.4064)
		(layer "B.Cu")
		(net "PVDDQ_DEF")
	)
	(segment
		(start 271.199864 -143.968978)
		(end 271.199864 -142.477236)
		(width 0.4064)
		(layer "B.Cu")
		(net "PVDDQ_DEF")
	)
	(segment
		(start 274.599908 -148.769578)
		(end 274.599908 -147.478496)
		(width 0.4064)
		(layer "B.Cu")
		(net "PVDDQ_DEF")
	)
	(segment
		(start 271.199864 -152.078436)
		(end 271.199864 -150.785068)
		(width 0.4064)
		(layer "B.Cu")
		(net "PVDDQ_DEF")
	)
	(segment
		(start 248.250456 -132.876036)
		(end 248.249948 -132.876036)
		(width 0.4064)
		(layer "B.Cu")
		(net "PVDDQ_DEF")
	)
	(segment
		(start 258.449826 -143.799052)
		(end 258.278122 -143.970756)
		(width 0.4064)
		(layer "B.Cu")
		(net "PVDDQ_DEF")
	)
	(segment
		(start 268.649958 -137.877296)
		(end 268.650466 -137.877296)
		(width 0.4064)
		(layer "B.Cu")
		(net "PVDDQ_DEF")
	)
	(segment
		(start 275.73986 -125.69444)
		(end 275.0312 -126.4031)
		(width 0.4064)
		(layer "B.Cu")
		(net "PVDDQ_DEF")
	)
	(segment
		(start 275.4503 -132.876036)
		(end 275.4503 -134.371588)
		(width 0.381)
		(layer "B.Cu")
		(net "PVDDQ_DEF")
	)
	(segment
		(start 251.649992 -130.249168)
		(end 251.649992 -128.276096)
		(width 0.4064)
		(layer "B.Cu")
		(net "PVDDQ_DEF")
	)
	(segment
		(start 258.450334 -152.078436)
		(end 258.449826 -152.078436)
		(width 0.4064)
		(layer "B.Cu")
		(net "PVDDQ_DEF")
	)
	(segment
		(start 254.199898 -139.172188)
		(end 254.199898 -137.877296)
		(width 0.4064)
		(layer "B.Cu")
		(net "PVDDQ_DEF")
	)
	(segment
		(start 258.318 -135.3312)
		(end 259.491988 -135.3312)
		(width 0.4572)
		(layer "B.Cu")
		(net "PVDDQ_DEF")
	)
	(segment
		(start 254.199898 -128.276096)
		(end 254.199898 -129.464308)
		(width 0.4064)
		(layer "B.Cu")
		(net "PVDDQ_DEF")
	)
	(segment
		(start 250.800362 -152.078436)
		(end 250.799854 -152.078436)
		(width 0.4064)
		(layer "B.Cu")
		(net "PVDDQ_DEF")
	)
	(segment
		(start 248.249948 -141.187678)
		(end 248.249948 -142.477236)
		(width 0.4064)
		(layer "B.Cu")
		(net "PVDDQ_DEF")
	)
	(segment
		(start 271.200372 -132.876036)
		(end 271.199864 -132.876036)
		(width 0.4064)
		(layer "B.Cu")
		(net "PVDDQ_DEF")
	)
	(segment
		(start 277.150322 -142.477236)
		(end 277.149814 -142.477236)
		(width 0.4064)
		(layer "B.Cu")
		(net "PVDDQ_DEF")
	)
	(segment
		(start 244.849904 -139.170156)
		(end 244.849904 -137.877296)
		(width 0.4064)
		(layer "B.Cu")
		(net "PVDDQ_DEF")
	)
	(segment
		(start 266.95019 -143.972788)
		(end 266.949936 -143.972534)
		(width 0.4064)
		(layer "B.Cu")
		(net "PVDDQ_DEF")
	)
	(segment
		(start 268.649958 -137.877296)
		(end 268.649958 -136.412732)
		(width 0.4064)
		(layer "B.Cu")
		(net "PVDDQ_DEF")
	)
	(segment
		(start 277.149814 -152.078436)
		(end 277.149814 -154.252168)
		(width 0.4064)
		(layer "B.Cu")
		(net "PVDDQ_DEF")
	)
	(segment
		(start 245.699788 -153.571956)
		(end 245.699788 -152.078436)
		(width 0.4064)
		(layer "B.Cu")
		(net "PVDDQ_DEF")
	)
	(segment
		(start 246.549926 -147.478496)
		(end 246.549926 -145.988278)
		(width 0.4064)
		(layer "B.Cu")
		(net "PVDDQ_DEF")
	)
	(segment
		(start 273.74977 -143.97228)
		(end 273.750278 -143.972788)
		(width 0.4064)
		(layer "B.Cu")
		(net "PVDDQ_DEF")
	)
	(segment
		(start 266.949936 -152.078436)
		(end 266.949936 -154.251914)
		(width 0.4064)
		(layer "B.Cu")
		(net "PVDDQ_DEF")
	)
	(segment
		(start 243.999766 -132.876036)
		(end 243.999766 -134.369556)
		(width 0.4064)
		(layer "B.Cu")
		(net "PVDDQ_DEF")
	)
	(segment
		(start 271.200372 -152.078436)
		(end 271.199864 -152.078436)
		(width 0.4064)
		(layer "B.Cu")
		(net "PVDDQ_DEF")
	)
	(segment
		(start 269.499842 -134.369556)
		(end 269.499842 -132.876036)
		(width 0.4064)
		(layer "B.Cu")
		(net "PVDDQ_DEF")
	)
	(segment
		(start 277.149814 -139.168378)
		(end 277.149814 -137.877296)
		(width 0.4064)
		(layer "B.Cu")
		(net "PVDDQ_DEF")
	)
	(segment
		(start 254.199898 -136.387078)
		(end 254.200406 -136.387586)
		(width 0.4064)
		(layer "B.Cu")
		(net "PVDDQ_DEF")
	)
	(segment
		(start 243.999766 -153.571956)
		(end 243.999766 -152.078436)
		(width 0.4064)
		(layer "B.Cu")
		(net "PVDDQ_DEF")
	)
	(segment
		(start 244.849904 -147.478496)
		(end 244.849904 -148.771356)
		(width 0.4064)
		(layer "B.Cu")
		(net "PVDDQ_DEF")
	)
	(segment
		(start 332.486 -154.94)
		(end 331.8764 -154.94)
		(width 0.4064)
		(layer "In4.Cu")
		(net "PVDDQ_DEF")
	)
	(segment
		(start 350.74606 -156.41828)
		(end 350.74606 -156.97708)
		(width 0.4064)
		(layer "In4.Cu")
		(net "PVDDQ_DEF")
	)
	(segment
		(start 335.8642 -158.3182)
		(end 332.486 -154.94)
		(width 0.4064)
		(layer "In4.Cu")
		(net "PVDDQ_DEF")
	)
	(segment
		(start 349.9866 -158.3182)
		(end 335.8642 -158.3182)
		(width 0.4064)
		(layer "In4.Cu")
		(net "PVDDQ_DEF")
	)
	(segment
		(start 350.7486 -157.5562)
		(end 349.9866 -158.3182)
		(width 0.4064)
		(layer "In4.Cu")
		(net "PVDDQ_DEF")
	)
	(segment
		(start 350.7486 -156.97962)
		(end 350.7486 -157.5562)
		(width 0.4064)
		(layer "In4.Cu")
		(net "PVDDQ_DEF")
	)
	(segment
		(start 350.74606 -156.97708)
		(end 350.7486 -156.97962)
		(width 0.4064)
		(layer "In4.Cu")
		(net "PVDDQ_DEF")
	)
	(segment
		(start 350.056958 -155.467558)
		(end 350.056958 -149.56917)
		(width 0.4064)
		(layer "In11.Cu")
		(net "PVDDQ_DEF")
	)
	(segment
		(start 350.0628 -149.563328)
		(end 350.0628 -149.33295)
		(width 0.4064)
		(layer "In11.Cu")
		(net "PVDDQ_DEF")
	)
	(segment
		(start 350.74606 -156.41828)
		(end 350.350836 -156.023056)
		(width 0.4064)
		(layer "In11.Cu")
		(net "PVDDQ_DEF")
	)
	(segment
		(start 350.0628 -149.33295)
		(end 350.466406 -148.929344)
		(width 0.4064)
		(layer "In11.Cu")
		(net "PVDDQ_DEF")
	)
	(segment
		(start 350.466406 -148.929344)
		(end 350.466406 -147.9804)
		(width 0.4064)
		(layer "In11.Cu")
		(net "PVDDQ_DEF")
	)
	(segment
		(start 350.056958 -149.56917)
		(end 350.0628 -149.563328)
		(width 0.4064)
		(layer "In11.Cu")
		(net "PVDDQ_DEF")
	)
	(segment
		(start 350.350836 -156.023056)
		(end 350.350836 -155.761436)
		(width 0.4064)
		(layer "In11.Cu")
		(net "PVDDQ_DEF")
	)
	(segment
		(start 350.466406 -147.9804)
		(end 350.279462 -147.793456)
		(width 0.4064)
		(layer "In11.Cu")
		(net "PVDDQ_DEF")
	)
	(segment
		(start 350.350836 -155.761436)
		(end 350.056958 -155.467558)
		(width 0.4064)
		(layer "In11.Cu")
		(net "PVDDQ_DEF")
	)
	(segment
		(start 246.549926 -11.916156)
		(end 246.549926 -10.422382)
		(width 0.508)
		(layer "F.Cu")
		(net "PVDDQ_ABC")
	)
	(segment
		(start 274.599908 1.152144)
		(end 274.599908 -0.821182)
		(width 0.508)
		(layer "F.Cu")
		(net "PVDDQ_ABC")
	)
	(segment
		(start 253.350522 -5.822442)
		(end 253.350014 -5.822442)
		(width 0.508)
		(layer "F.Cu")
		(net "PVDDQ_ABC")
	)
	(segment
		(start 263.65581 -57.57164)
		(end 264.801096 -57.57164)
		(width 0.254)
		(layer "F.Cu")
		(net "PVDDQ_ABC")
	)
	(segment
		(start 255.900428 -15.423642)
		(end 255.89992 -15.423642)
		(width 0.508)
		(layer "F.Cu")
		(net "PVDDQ_ABC")
	)
	(segment
		(start 269.50035 -16.718534)
		(end 269.500096 -16.718788)
		(width 0.508)
		(layer "F.Cu")
		(net "PVDDQ_ABC")
	)
	(segment
		(start 258.449826 -2.314956)
		(end 258.449826 -0.821182)
		(width 0.508)
		(layer "F.Cu")
		(net "PVDDQ_ABC")
	)
	(segment
		(start 193.675 -23.418546)
		(end 193.4591 -23.634446)
		(width 0.4064)
		(layer "F.Cu")
		(net "PVDDQ_ABC")
	)
	(segment
		(start 264.51433 -50.141886)
		(end 264.799064 -49.54778)
		(width 0.254)
		(layer "F.Cu")
		(net "PVDDQ_ABC")
	)
	(segment
		(start 258.449826 -0.821182)
		(end 258.450334 -0.821182)
		(width 0.508)
		(layer "F.Cu")
		(net "PVDDQ_ABC")
	)
	(segment
		(start 245.699788 -4.332478)
		(end 245.699788 -5.822442)
		(width 0.508)
		(layer "F.Cu")
		(net "PVDDQ_ABC")
	)
	(segment
		(start 265.372596 -54.59984)
		(end 264.801096 -54.59984)
		(width 0.254)
		(layer "F.Cu")
		(net "PVDDQ_ABC")
	)
	(segment
		(start 258.2164 -16.7513)
		(end 258.450334 -16.517366)
		(width 0.508)
		(layer "F.Cu")
		(net "PVDDQ_ABC")
	)
	(segment
		(start 249.099832 -10.422382)
		(end 249.10034 -10.422382)
		(width 0.508)
		(layer "F.Cu")
		(net "PVDDQ_ABC")
	)
	(segment
		(start 271.200372 -15.423642)
		(end 271.199864 -15.423134)
		(width 0.508)
		(layer "F.Cu")
		(net "PVDDQ_ABC")
	)
	(segment
		(start 272.900394 -20.023582)
		(end 272.900394 -18.730976)
		(width 0.508)
		(layer "F.Cu")
		(net "PVDDQ_ABC")
	)
	(segment
		(start 277.149814 -16.714978)
		(end 277.149814 -15.423642)
		(width 0.508)
		(layer "F.Cu")
		(net "PVDDQ_ABC")
	)
	(segment
		(start 245.699788 -16.716756)
		(end 245.699788 -15.423642)
		(width 0.508)
		(layer "F.Cu")
		(net "PVDDQ_ABC")
	)
	(segment
		(start 253.350522 -15.423642)
		(end 253.350522 -16.71828)
		(width 0.508)
		(layer "F.Cu")
		(net "PVDDQ_ABC")
	)
	(segment
		(start 269.50035 -15.423642)
		(end 269.50035 -16.718534)
		(width 0.508)
		(layer "F.Cu")
		(net "PVDDQ_ABC")
	)
	(segment
		(start 185.978292 -5.283708)
		(end 185.978292 -2.946908)
		(width 0.254)
		(layer "F.Cu")
		(net "PVDDQ_ABC")
	)
	(segment
		(start 255.07061 -57.57164)
		(end 254.49911 -57.57164)
		(width 0.254)
		(layer "F.Cu")
		(net "PVDDQ_ABC")
	)
	(segment
		(start 254.199898 -9.133078)
		(end 254.200406 -9.133586)
		(width 0.508)
		(layer "F.Cu")
		(net "PVDDQ_ABC")
	)
	(segment
		(start 253.350522 -16.71828)
		(end 253.350014 -16.718788)
		(width 0.508)
		(layer "F.Cu")
		(net "PVDDQ_ABC")
	)
	(segment
		(start 249.099832 1.152144)
		(end 249.099832 -0.821182)
		(width 0.508)
		(layer "F.Cu")
		(net "PVDDQ_ABC")
	)
	(segment
		(start 274.599908 -11.914378)
		(end 274.599908 -10.422382)
		(width 0.508)
		(layer "F.Cu")
		(net "PVDDQ_ABC")
	)
	(segment
		(start 254.212344 -59.057286)
		(end 253.640844 -59.057286)
		(width 0.254)
		(layer "F.Cu")
		(net "PVDDQ_ABC")
	)
	(segment
		(start 258.449826 -9.129268)
		(end 258.450334 -9.129776)
		(width 0.508)
		(layer "F.Cu")
		(net "PVDDQ_ABC")
	)
	(segment
		(start 249.10034 -20.023582)
		(end 249.10034 -18.734786)
		(width 0.508)
		(layer "F.Cu")
		(net "PVDDQ_ABC")
	)
	(segment
		(start 255.89992 -2.264156)
		(end 255.84912 -2.314956)
		(width 0.508)
		(layer "F.Cu")
		(net "PVDDQ_ABC")
	)
	(segment
		(start 262.255 -22.733)
		(end 262.255 -21.2598)
		(width 0.508)
		(layer "F.Cu")
		(net "PVDDQ_ABC")
	)
	(segment
		(start 258.450334 -18.699734)
		(end 258.4069 -18.6563)
		(width 0.508)
		(layer "F.Cu")
		(net "PVDDQ_ABC")
	)
	(segment
		(start 244.000274 3.778758)
		(end 243.999766 3.778758)
		(width 0.508)
		(layer "F.Cu")
		(net "PVDDQ_ABC")
	)
	(segment
		(start 254.200406 -20.023582)
		(end 254.200406 -21.487638)
		(width 0.508)
		(layer "F.Cu")
		(net "PVDDQ_ABC")
	)
	(segment
		(start 244.849904 0.468122)
		(end 244.849904 -0.821182)
		(width 0.508)
		(layer "F.Cu")
		(net "PVDDQ_ABC")
	)
	(segment
		(start 266.099798 -2.313178)
		(end 266.099798 -0.821182)
		(width 0.508)
		(layer "F.Cu")
		(net "PVDDQ_ABC")
	)
	(segment
		(start 266.950444 -7.117334)
		(end 266.95019 -7.117588)
		(width 0.508)
		(layer "F.Cu")
		(net "PVDDQ_ABC")
	)
	(segment
		(start 255.900428 -18.820384)
		(end 256.057146 -18.663666)
		(width 0.508)
		(layer "F.Cu")
		(net "PVDDQ_ABC")
	)
	(segment
		(start 249.10034 -20.023582)
		(end 249.10034 -21.516848)
		(width 0.508)
		(layer "F.Cu")
		(net "PVDDQ_ABC")
	)
	(segment
		(start 271.200372 -18.730976)
		(end 271.199864 -18.730468)
		(width 0.508)
		(layer "F.Cu")
		(net "PVDDQ_ABC")
	)
	(segment
		(start 262.79729 -59.057286)
		(end 262.22579 -59.057286)
		(width 0.254)
		(layer "F.Cu")
		(net "PVDDQ_ABC")
	)
	(segment
		(start 251.6505 -18.734786)
		(end 251.649992 -18.734278)
		(width 0.508)
		(layer "F.Cu")
		(net "PVDDQ_ABC")
	)
	(segment
		(start 267.948156 -61.038486)
		(end 268.557756 -61.038486)
		(width 0.254)
		(layer "F.Cu")
		(net "PVDDQ_ABC")
	)
	(segment
		(start 253.350522 -13.934186)
		(end 253.350014 -13.933678)
		(width 0.508)
		(layer "F.Cu")
		(net "PVDDQ_ABC")
	)
	(segment
		(start 277.149814 -13.929868)
		(end 277.149814 -15.423642)
		(width 0.508)
		(layer "F.Cu")
		(net "PVDDQ_ABC")
	)
	(segment
		(start 258.450334 3.778758)
		(end 258.449826 3.77825)
		(width 0.508)
		(layer "F.Cu")
		(net "PVDDQ_ABC")
	)
	(segment
		(start 275.4503 -5.822442)
		(end 275.4503 -7.136892)
		(width 0.508)
		(layer "F.Cu")
		(net "PVDDQ_ABC")
	)
	(segment
		(start 246.549926 -9.133078)
		(end 246.549926 -10.422382)
		(width 0.508)
		(layer "F.Cu")
		(net "PVDDQ_ABC")
	)
	(segment
		(start 246.549926 -2.314956)
		(end 246.549926 -0.821182)
		(width 0.508)
		(layer "F.Cu")
		(net "PVDDQ_ABC")
	)
	(segment
		(start 248.249948 -5.822442)
		(end 248.249948 -7.115556)
		(width 0.508)
		(layer "F.Cu")
		(net "PVDDQ_ABC")
	)
	(segment
		(start 265.672316 -50.141886)
		(end 265.659616 -50.129186)
		(width 0.254)
		(layer "F.Cu")
		(net "PVDDQ_ABC")
	)
	(segment
		(start 258.449826 0.471932)
		(end 258.449826 2.485644)
		(width 0.4064)
		(layer "F.Cu")
		(net "PVDDQ_ABC")
	)
	(segment
		(start 277.149814 -9.133586)
		(end 277.149814 -10.422382)
		(width 0.508)
		(layer "F.Cu")
		(net "PVDDQ_ABC")
	)
	(segment
		(start 276.839172 -21.886926)
		(end 277.149814 -22.197568)
		(width 0.254)
		(layer "F.Cu")
		(net "PVDDQ_ABC")
	)
	(segment
		(start 271.200372 -4.329176)
		(end 271.200372 -5.822442)
		(width 0.508)
		(layer "F.Cu")
		(net "PVDDQ_ABC")
	)
	(segment
		(start 265.372596 -51.62804)
		(end 264.801096 -51.62804)
		(width 0.254)
		(layer "F.Cu")
		(net "PVDDQ_ABC")
	)
	(segment
		(start 258.450334 -16.517366)
		(end 258.450334 -15.423642)
		(width 0.508)
		(layer "F.Cu")
		(net "PVDDQ_ABC")
	)
	(segment
		(start 246.550434 -18.734786)
		(end 246.549926 -18.734278)
		(width 0.508)
		(layer "F.Cu")
		(net "PVDDQ_ABC")
	)
	(segment
		(start 260.22173 -57.57164)
		(end 259.65023 -57.57164)
		(width 0.254)
		(layer "F.Cu")
		(net "PVDDQ_ABC")
	)
	(segment
		(start 277.149814 -7.113778)
		(end 277.150322 -7.11327)
		(width 0.508)
		(layer "F.Cu")
		(net "PVDDQ_ABC")
	)
	(segment
		(start 246.549926 -2.314956)
		(end 245.7577 -3.107182)
		(width 0.508)
		(layer "F.Cu")
		(net "PVDDQ_ABC")
	)
	(segment
		(start 271.200372 -15.423642)
		(end 271.199864 -15.423642)
		(width 0.508)
		(layer "F.Cu")
		(net "PVDDQ_ABC")
	)
	(segment
		(start 253.350014 3.778758)
		(end 253.350014 1.805432)
		(width 0.508)
		(layer "F.Cu")
		(net "PVDDQ_ABC")
	)
	(segment
		(start 274.599908 -9.129268)
		(end 274.599908 -10.422382)
		(width 0.508)
		(layer "F.Cu")
		(net "PVDDQ_ABC")
	)
	(segment
		(start 255.900428 -20.023582)
		(end 255.900428 -18.820384)
		(width 0.508)
		(layer "F.Cu")
		(net "PVDDQ_ABC")
	)
	(segment
		(start 271.200372 -20.023582)
		(end 271.200372 -21.487638)
		(width 0.508)
		(layer "F.Cu")
		(net "PVDDQ_ABC")
	)
	(segment
		(start 248.249948 1.805432)
		(end 248.249948 3.778758)
		(width 0.508)
		(layer "F.Cu")
		(net "PVDDQ_ABC")
	)
	(segment
		(start 268.649958 -11.914378)
		(end 268.649958 -10.422382)
		(width 0.508)
		(layer "F.Cu")
		(net "PVDDQ_ABC")
	)
	(segment
		(start 260.50875 -59.057286)
		(end 261.08025 -59.057286)
		(width 0.254)
		(layer "F.Cu")
		(net "PVDDQ_ABC")
	)
	(segment
		(start 277.150322 -20.725892)
		(end 277.150322 -20.940268)
		(width 0.254)
		(layer "F.Cu")
		(net "PVDDQ_ABC")
	)
	(segment
		(start 275.449792 -16.71828)
		(end 275.449792 -15.423642)
		(width 0.508)
		(layer "F.Cu")
		(net "PVDDQ_ABC")
	)
	(segment
		(start 255.89992 -4.321556)
		(end 255.89992 -5.822442)
		(width 0.508)
		(layer "F.Cu")
		(net "PVDDQ_ABC")
	)
	(segment
		(start 249.099832 -9.133078)
		(end 249.099832 -10.422382)
		(width 0.508)
		(layer "F.Cu")
		(net "PVDDQ_ABC")
	)
	(segment
		(start 251.6505 -20.023582)
		(end 251.6505 -22.19706)
		(width 0.508)
		(layer "F.Cu")
		(net "PVDDQ_ABC")
	)
	(segment
		(start 250.799854 -4.332478)
		(end 250.799854 -5.822442)
		(width 0.508)
		(layer "F.Cu")
		(net "PVDDQ_ABC")
	)
	(segment
		(start 269.499842 3.778758)
		(end 269.499842 2.485644)
		(width 0.508)
		(layer "F.Cu")
		(net "PVDDQ_ABC")
	)
	(segment
		(start 274.600416 -20.023582)
		(end 274.600416 -21.487638)
		(width 0.508)
		(layer "F.Cu")
		(net "PVDDQ_ABC")
	)
	(segment
		(start 245.699788 -15.423642)
		(end 245.700296 -15.423642)
		(width 0.508)
		(layer "F.Cu")
		(net "PVDDQ_ABC")
	)
	(segment
		(start 244.849904 -21.29409)
		(end 244.849904 -22.197568)
		(width 0.381)
		(layer "F.Cu")
		(net "PVDDQ_ABC")
	)
	(segment
		(start 271.199864 -2.313178)
		(end 271.199864 -0.821182)
		(width 0.508)
		(layer "F.Cu")
		(net "PVDDQ_ABC")
	)
	(segment
		(start 268.650466 -18.730976)
		(end 268.649958 -18.730468)
		(width 0.508)
		(layer "F.Cu")
		(net "PVDDQ_ABC")
	)
	(segment
		(start 186.008264 -0.03048)
		(end 186.008264 0.403098)
		(width 0.254)
		(layer "F.Cu")
		(net "PVDDQ_ABC")
	)
	(segment
		(start 258.50469 -51.62804)
		(end 257.93319 -51.62804)
		(width 0.254)
		(layer "F.Cu")
		(net "PVDDQ_ABC")
	)
	(segment
		(start 251.6505 -10.422382)
		(end 251.6505 -11.91768)
		(width 0.508)
		(layer "F.Cu")
		(net "PVDDQ_ABC")
	)
	(segment
		(start 277.150322 -4.329176)
		(end 277.149814 -4.328668)
		(width 0.508)
		(layer "F.Cu")
		(net "PVDDQ_ABC")
	)
	(segment
		(start 272.899886 -11.914378)
		(end 272.899886 -10.422382)
		(width 0.508)
		(layer "F.Cu")
		(net "PVDDQ_ABC")
	)
	(segment
		(start 258.449826 -5.822442)
		(end 258.450334 -5.822442)
		(width 0.508)
		(layer "F.Cu")
		(net "PVDDQ_ABC")
	)
	(segment
		(start 274.600416 -18.730976)
		(end 274.599908 -18.730468)
		(width 0.508)
		(layer "F.Cu")
		(net "PVDDQ_ABC")
	)
	(segment
		(start 256.78765 -54.59984)
		(end 256.21615 -54.59984)
		(width 0.254)
		(layer "F.Cu")
		(net "PVDDQ_ABC")
	)
	(segment
		(start 269.50035 -7.117334)
		(end 269.500096 -7.117588)
		(width 0.508)
		(layer "F.Cu")
		(net "PVDDQ_ABC")
	)
	(segment
		(start 255.900428 -0.821182)
		(end 255.89992 -0.820674)
		(width 0.508)
		(layer "F.Cu")
		(net "PVDDQ_ABC")
	)
	(segment
		(start 273.74977 -15.423642)
		(end 273.750278 -15.423642)
		(width 0.508)
		(layer "F.Cu")
		(net "PVDDQ_ABC")
	)
	(segment
		(start 254.199898 1.152144)
		(end 254.199898 -0.821182)
		(width 0.508)
		(layer "F.Cu")
		(net "PVDDQ_ABC")
	)
	(segment
		(start 264.801096 -57.57164)
		(end 265.372596 -57.57164)
		(width 0.254)
		(layer "F.Cu")
		(net "PVDDQ_ABC")
	)
	(segment
		(start 254.212344 -62.029086)
		(end 253.640844 -62.029086)
		(width 0.254)
		(layer "F.Cu")
		(net "PVDDQ_ABC")
	)
	(segment
		(start 248.250456 -5.822442)
		(end 248.249948 -5.822442)
		(width 0.508)
		(layer "F.Cu")
		(net "PVDDQ_ABC")
	)
	(segment
		(start 260.22173 -54.59984)
		(end 259.65023 -54.59984)
		(width 0.254)
		(layer "F.Cu")
		(net "PVDDQ_ABC")
	)
	(segment
		(start 245.699788 -5.822442)
		(end 245.699788 -7.115556)
		(width 0.508)
		(layer "F.Cu")
		(net "PVDDQ_ABC")
	)
	(segment
		(start 267.089636 -54.59984)
		(end 266.518136 -54.59984)
		(width 0.254)
		(layer "F.Cu")
		(net "PVDDQ_ABC")
	)
	(segment
		(start 246.550434 -22.19706)
		(end 246.549926 -22.197568)
		(width 0.508)
		(layer "F.Cu")
		(net "PVDDQ_ABC")
	)
	(segment
		(start 271.199864 2.514854)
		(end 271.200372 2.515362)
		(width 0.508)
		(layer "F.Cu")
		(net "PVDDQ_ABC")
	)
	(segment
		(start 254.200406 -9.133586)
		(end 254.200406 -10.422382)
		(width 0.508)
		(layer "F.Cu")
		(net "PVDDQ_ABC")
	)
	(segment
		(start 275.449792 -13.934186)
		(end 275.4503 -13.933678)
		(width 0.5588)
		(layer "F.Cu")
		(net "PVDDQ_ABC")
	)
	(segment
		(start 249.099832 -0.821182)
		(end 249.10034 -0.821182)
		(width 0.508)
		(layer "F.Cu")
		(net "PVDDQ_ABC")
	)
	(segment
		(start 258.449826 0.471932)
		(end 258.449826 -0.821182)
		(width 0.508)
		(layer "F.Cu")
		(net "PVDDQ_ABC")
	)
	(segment
		(start 255.900428 -14.118844)
		(end 256.089404 -13.929868)
		(width 0.508)
		(layer "F.Cu")
		(net "PVDDQ_ABC")
	)
	(segment
		(start 255.07061 -54.59984)
		(end 254.49911 -54.59984)
		(width 0.254)
		(layer "F.Cu")
		(net "PVDDQ_ABC")
	)
	(segment
		(start 244.849904 -20.023582)
		(end 244.849904 -18.734278)
		(width 0.508)
		(layer "F.Cu")
		(net "PVDDQ_ABC")
	)
	(segment
		(start 246.550434 -20.023582)
		(end 246.550434 -22.19706)
		(width 0.508)
		(layer "F.Cu")
		(net "PVDDQ_ABC")
	)
	(segment
		(start 266.950444 -4.329176)
		(end 266.949936 -4.328668)
		(width 0.508)
		(layer "F.Cu")
		(net "PVDDQ_ABC")
	)
	(segment
		(start 248.249948 1.805432)
		(end 248.8184 1.368552)
		(width 0.5588)
		(layer "F.Cu")
		(net "PVDDQ_ABC")
	)
	(segment
		(start 251.923804 -59.057286)
		(end 252.495304 -59.057286)
		(width 0.254)
		(layer "F.Cu")
		(net "PVDDQ_ABC")
	)
	(segment
		(start 266.949682 1.805432)
		(end 266.950444 1.806194)
		(width 0.508)
		(layer "F.Cu")
		(net "PVDDQ_ABC")
	)
	(segment
		(start 267.089636 -57.57164)
		(end 266.518136 -57.57164)
		(width 0.254)
		(layer "F.Cu")
		(net "PVDDQ_ABC")
	)
	(segment
		(start 193.4591 -23.634446)
		(end 193.4591 -24.0157)
		(width 0.4064)
		(layer "F.Cu")
		(net "PVDDQ_ABC")
	)
	(segment
		(start 268.650466 -2.31267)
		(end 268.649958 -2.313178)
		(width 0.508)
		(layer "F.Cu")
		(net "PVDDQ_ABC")
	)
	(segment
		(start 277.149814 -20.023582)
		(end 277.149814 -18.730468)
		(width 0.508)
		(layer "F.Cu")
		(net "PVDDQ_ABC")
	)
	(segment
		(start 272.899886 -0.821182)
		(end 272.900394 -0.821182)
		(width 0.508)
		(layer "F.Cu")
		(net "PVDDQ_ABC")
	)
	(segment
		(start 268.650466 0.44196)
		(end 268.649704 0.442722)
		(width 0.508)
		(layer "F.Cu")
		(net "PVDDQ_ABC")
	)
	(segment
		(start 244.401086 -26.591006)
		(end 244.66423 -26.85415)
		(width 0.4064)
		(layer "F.Cu")
		(net "PVDDQ_ABC")
	)
	(segment
		(start 254.200406 -20.023582)
		(end 254.200406 -18.734786)
		(width 0.508)
		(layer "F.Cu")
		(net "PVDDQ_ABC")
	)
	(segment
		(start 268.650466 -0.821182)
		(end 268.650466 -2.31267)
		(width 0.508)
		(layer "F.Cu")
		(net "PVDDQ_ABC")
	)
	(segment
		(start 255.92913 -50.141886)
		(end 255.92913 -49.150778)
		(width 0.2032)
		(layer "F.Cu")
		(net "PVDDQ_ABC")
	)
	(segment
		(start 277.149814 -9.129268)
		(end 277.149814 -9.133586)
		(width 0.254)
		(layer "F.Cu")
		(net "PVDDQ_ABC")
	)
	(segment
		(start 269.50035 -4.332732)
		(end 269.50035 -5.822442)
		(width 0.508)
		(layer "F.Cu")
		(net "PVDDQ_ABC")
	)
	(segment
		(start 268.649704 -21.443696)
		(end 268.649704 -22.197568)
		(width 0.254)
		(layer "F.Cu")
		(net "PVDDQ_ABC")
	)
	(segment
		(start 268.649958 -9.129268)
		(end 268.649958 -10.422382)
		(width 0.508)
		(layer "F.Cu")
		(net "PVDDQ_ABC")
	)
	(segment
		(start 193.675 -13.589)
		(end 194.0814 -13.9954)
		(width 0.4064)
		(layer "F.Cu")
		(net "PVDDQ_ABC")
	)
	(segment
		(start 258.449826 -4.328668)
		(end 258.449826 -5.822442)
		(width 0.508)
		(layer "F.Cu")
		(net "PVDDQ_ABC")
	)
	(segment
		(start 261.93877 -54.59984)
		(end 261.36727 -54.59984)
		(width 0.254)
		(layer "F.Cu")
		(net "PVDDQ_ABC")
	)
	(segment
		(start 266.099798 -11.914378)
		(end 266.100306 -11.91387)
		(width 0.508)
		(layer "F.Cu")
		(net "PVDDQ_ABC")
	)
	(segment
		(start 248.249948 -15.423642)
		(end 248.250456 -15.423642)
		(width 0.508)
		(layer "F.Cu")
		(net "PVDDQ_ABC")
	)
	(segment
		(start 277.150322 -0.821182)
		(end 277.149814 -0.821182)
		(width 0.508)
		(layer "F.Cu")
		(net "PVDDQ_ABC")
	)
	(segment
		(start 255.89992 -15.423642)
		(end 255.89992 -16.696944)
		(width 0.508)
		(layer "F.Cu")
		(net "PVDDQ_ABC")
	)
	(segment
		(start 272.899886 -10.422382)
		(end 272.900394 -10.422382)
		(width 0.508)
		(layer "F.Cu")
		(net "PVDDQ_ABC")
	)
	(segment
		(start 245.699788 -4.332478)
		(end 245.7577 -4.274566)
		(width 0.508)
		(layer "F.Cu")
		(net "PVDDQ_ABC")
	)
	(segment
		(start 252.495304 -62.029086)
		(end 251.923804 -62.029086)
		(width 0.254)
		(layer "F.Cu")
		(net "PVDDQ_ABC")
	)
	(segment
		(start 277.149814 -15.423642)
		(end 277.150322 -15.423642)
		(width 0.508)
		(layer "F.Cu")
		(net "PVDDQ_ABC")
	)
	(segment
		(start 185.293 -5.969)
		(end 185.978292 -5.283708)
		(width 0.254)
		(layer "F.Cu")
		(net "PVDDQ_ABC")
	)
	(segment
		(start 266.231116 -50.141886)
		(end 265.672316 -50.141886)
		(width 0.254)
		(layer "F.Cu")
		(net "PVDDQ_ABC")
	)
	(segment
		(start 251.649992 -9.133078)
		(end 251.6505 -9.133586)
		(width 0.508)
		(layer "F.Cu")
		(net "PVDDQ_ABC")
	)
	(segment
		(start 254.200406 -11.91768)
		(end 254.199898 -11.918188)
		(width 0.508)
		(layer "F.Cu")
		(net "PVDDQ_ABC")
	)
	(segment
		(start 275.449792 3.778758)
		(end 275.449792 1.805432)
		(width 0.508)
		(layer "F.Cu")
		(net "PVDDQ_ABC")
	)
	(segment
		(start 264.799064 -49.54778)
		(end 264.796524 -49.540414)
		(width 0.254)
		(layer "F.Cu")
		(net "PVDDQ_ABC")
	)
	(segment
		(start 261.93877 -57.57164)
		(end 261.36727 -57.57164)
		(width 0.254)
		(layer "F.Cu")
		(net "PVDDQ_ABC")
	)
	(segment
		(start 186.652408 -2.272792)
		(end 186.652408 -0.674624)
		(width 0.254)
		(layer "F.Cu")
		(net "PVDDQ_ABC")
	)
	(segment
		(start 271.200372 -21.487638)
		(end 271.199864 -21.488146)
		(width 0.508)
		(layer "F.Cu")
		(net "PVDDQ_ABC")
	)
	(segment
		(start 255.89992 3.778758)
		(end 255.900428 3.778758)
		(width 0.508)
		(layer "F.Cu")
		(net "PVDDQ_ABC")
	)
	(segment
		(start 249.10034 -21.516848)
		(end 249.099832 -21.517356)
		(width 0.508)
		(layer "F.Cu")
		(net "PVDDQ_ABC")
	)
	(segment
		(start 266.100306 -20.023582)
		(end 266.100306 -21.487638)
		(width 0.508)
		(layer "F.Cu")
		(net "PVDDQ_ABC")
	)
	(segment
		(start 277.150322 -20.940268)
		(end 276.839172 -21.251418)
		(width 0.254)
		(layer "F.Cu")
		(net "PVDDQ_ABC")
	)
	(segment
		(start 245.7577 -4.274566)
		(end 245.7577 -3.3528)
		(width 0.508)
		(layer "F.Cu")
		(net "PVDDQ_ABC")
	)
	(segment
		(start 255.89992 -21.541232)
		(end 255.89992 -22.225)
		(width 0.2032)
		(layer "F.Cu")
		(net "PVDDQ_ABC")
	)
	(segment
		(start 250.799854 -7.115556)
		(end 250.799854 -5.822442)
		(width 0.508)
		(layer "F.Cu")
		(net "PVDDQ_ABC")
	)
	(segment
		(start 248.249948 3.778758)
		(end 248.250456 3.778758)
		(width 0.508)
		(layer "F.Cu")
		(net "PVDDQ_ABC")
	)
	(segment
		(start 271.200372 -11.91387)
		(end 271.199864 -11.914378)
		(width 0.508)
		(layer "F.Cu")
		(net "PVDDQ_ABC")
	)
	(segment
		(start 193.675 -23.396194)
		(end 193.675 -23.418546)
		(width 0.4064)
		(layer "F.Cu")
		(net "PVDDQ_ABC")
	)
	(segment
		(start 274.600416 -20.023582)
		(end 274.600416 -18.730976)
		(width 0.508)
		(layer "F.Cu")
		(net "PVDDQ_ABC")
	)
	(segment
		(start 250.799854 -5.822442)
		(end 250.800362 -5.822442)
		(width 0.508)
		(layer "F.Cu")
		(net "PVDDQ_ABC")
	)
	(segment
		(start 258.449826 3.77825)
		(end 258.449826 2.485644)
		(width 0.508)
		(layer "F.Cu")
		(net "PVDDQ_ABC")
	)
	(segment
		(start 251.649992 -0.821182)
		(end 251.6505 -0.821182)
		(width 0.508)
		(layer "F.Cu")
		(net "PVDDQ_ABC")
	)
	(segment
		(start 246.549926 0.442722)
		(end 246.549926 -0.821182)
		(width 0.508)
		(layer "F.Cu")
		(net "PVDDQ_ABC")
	)
	(segment
		(start 273.750278 -5.822442)
		(end 273.750278 -7.117588)
		(width 0.508)
		(layer "F.Cu")
		(net "PVDDQ_ABC")
	)
	(segment
		(start 271.199864 -15.423134)
		(end 271.199864 -13.929868)
		(width 0.508)
		(layer "F.Cu")
		(net "PVDDQ_ABC")
	)
	(segment
		(start 256.78765 -51.62804)
		(end 257.07467 -52.12334)
		(width 0.254)
		(layer "F.Cu")
		(net "PVDDQ_ABC")
	)
	(segment
		(start 273.750278 -16.718788)
		(end 273.74977 -16.71828)
		(width 0.508)
		(layer "F.Cu")
		(net "PVDDQ_ABC")
	)
	(segment
		(start 193.675 -3.937)
		(end 193.675 -3.7465)
		(width 0.4064)
		(layer "F.Cu")
		(net "PVDDQ_ABC")
	)
	(segment
		(start 253.353824 -57.57164)
		(end 252.782324 -57.57164)
		(width 0.254)
		(layer "F.Cu")
		(net "PVDDQ_ABC")
	)
	(segment
		(start 244.850412 -20.023582)
		(end 244.850412 -21.293582)
		(width 0.508)
		(layer "F.Cu")
		(net "PVDDQ_ABC")
	)
	(segment
		(start 266.231116 -59.057286)
		(end 265.659616 -59.057286)
		(width 0.254)
		(layer "F.Cu")
		(net "PVDDQ_ABC")
	)
	(segment
		(start 273.74977 -16.71828)
		(end 273.74977 -15.423642)
		(width 0.508)
		(layer "F.Cu")
		(net "PVDDQ_ABC")
	)
	(segment
		(start 251.6505 -9.133586)
		(end 251.6505 -10.422382)
		(width 0.508)
		(layer "F.Cu")
		(net "PVDDQ_ABC")
	)
	(segment
		(start 349.760286 -9.586214)
		(end 348.96171 -8.787638)
		(width 0.254)
		(layer "F.Cu")
		(net "PVDDQ_ABC")
	)
	(segment
		(start 266.100306 -0.821182)
		(end 266.099798 -0.821182)
		(width 0.508)
		(layer "F.Cu")
		(net "PVDDQ_ABC")
	)
	(segment
		(start 254.199898 -0.821182)
		(end 254.200406 -0.821182)
		(width 0.508)
		(layer "F.Cu")
		(net "PVDDQ_ABC")
	)
	(segment
		(start 253.353824 -54.59984)
		(end 252.782324 -54.59984)
		(width 0.254)
		(layer "F.Cu")
		(net "PVDDQ_ABC")
	)
	(segment
		(start 258.449826 -9.129268)
		(end 258.449826 -7.115556)
		(width 0.4064)
		(layer "F.Cu")
		(net "PVDDQ_ABC")
	)
	(segment
		(start 275.4503 3.778758)
		(end 275.449792 3.778758)
		(width 0.508)
		(layer "F.Cu")
		(net "PVDDQ_ABC")
	)
	(segment
		(start 246.549926 -0.821182)
		(end 246.550434 -0.821182)
		(width 0.508)
		(layer "F.Cu")
		(net "PVDDQ_ABC")
	)
	(segment
		(start 266.950444 -5.822442)
		(end 266.950444 -4.329176)
		(width 0.508)
		(layer "F.Cu")
		(net "PVDDQ_ABC")
	)
	(segment
		(start 258.450334 -10.422382)
		(end 258.450334 -11.915648)
		(width 0.508)
		(layer "F.Cu")
		(net "PVDDQ_ABC")
	)
	(segment
		(start 258.450334 -9.129776)
		(end 258.450334 -10.422382)
		(width 0.508)
		(layer "F.Cu")
		(net "PVDDQ_ABC")
	)
	(segment
		(start 255.92913 -62.029086)
		(end 255.35763 -62.029086)
		(width 0.254)
		(layer "F.Cu")
		(net "PVDDQ_ABC")
	)
	(segment
		(start 246.549926 -10.422382)
		(end 246.550434 -10.422382)
		(width 0.508)
		(layer "F.Cu")
		(net "PVDDQ_ABC")
	)
	(segment
		(start 248.249948 -13.933678)
		(end 248.249948 -15.423642)
		(width 0.508)
		(layer "F.Cu")
		(net "PVDDQ_ABC")
	)
	(segment
		(start 277.150322 -7.11327)
		(end 277.150322 -5.822442)
		(width 0.508)
		(layer "F.Cu")
		(net "PVDDQ_ABC")
	)
	(segment
		(start 264.51433 -59.057286)
		(end 263.94283 -59.057286)
		(width 0.254)
		(layer "F.Cu")
		(net "PVDDQ_ABC")
	)
	(segment
		(start 271.199864 -15.423642)
		(end 271.199864 -16.714978)
		(width 0.508)
		(layer "F.Cu")
		(net "PVDDQ_ABC")
	)
	(segment
		(start 277.149814 -10.422382)
		(end 277.150322 -10.422382)
		(width 0.508)
		(layer "F.Cu")
		(net "PVDDQ_ABC")
	)
	(segment
		(start 271.200372 -10.422382)
		(end 271.200372 -11.91387)
		(width 0.508)
		(layer "F.Cu")
		(net "PVDDQ_ABC")
	)
	(segment
		(start 249.099832 -11.916156)
		(end 249.099832 -10.422382)
		(width 0.508)
		(layer "F.Cu")
		(net "PVDDQ_ABC")
	)
	(segment
		(start 253.350014 1.805432)
		(end 254.199898 1.152144)
		(width 0.5588)
		(layer "F.Cu")
		(net "PVDDQ_ABC")
	)
	(segment
		(start 244.850412 -20.023582)
		(end 244.849904 -20.023582)
		(width 0.508)
		(layer "F.Cu")
		(net "PVDDQ_ABC")
	)
	(segment
		(start 255.900428 -15.423642)
		(end 255.900428 -14.118844)
		(width 0.508)
		(layer "F.Cu")
		(net "PVDDQ_ABC")
	)
	(segment
		(start 267.089636 -51.62804)
		(end 266.518136 -51.62804)
		(width 0.254)
		(layer "F.Cu")
		(net "PVDDQ_ABC")
	)
	(segment
		(start 255.89992 -7.115556)
		(end 255.89992 -5.822442)
		(width 0.508)
		(layer "F.Cu")
		(net "PVDDQ_ABC")
	)
	(segment
		(start 272.899886 -2.313178)
		(end 272.899886 -0.821182)
		(width 0.508)
		(layer "F.Cu")
		(net "PVDDQ_ABC")
	)
	(segment
		(start 250.799854 3.778758)
		(end 250.799854 2.514854)
		(width 0.508)
		(layer "F.Cu")
		(net "PVDDQ_ABC")
	)
	(segment
		(start 254.200406 -10.422382)
		(end 254.200406 -11.91768)
		(width 0.508)
		(layer "F.Cu")
		(net "PVDDQ_ABC")
	)
	(segment
		(start 248.8184 1.368552)
		(end 249.099832 1.152144)
		(width 0.5588)
		(layer "F.Cu")
		(net "PVDDQ_ABC")
	)
	(segment
		(start 255.89992 0.471932)
		(end 255.89992 2.485644)
		(width 0.508)
		(layer "F.Cu")
		(net "PVDDQ_ABC")
	)
	(segment
		(start 253.350522 3.778758)
		(end 253.350014 3.778758)
		(width 0.508)
		(layer "F.Cu")
		(net "PVDDQ_ABC")
	)
	(segment
		(start 255.900428 -21.540724)
		(end 255.89992 -21.541232)
		(width 0.2032)
		(layer "F.Cu")
		(net "PVDDQ_ABC")
	)
	(segment
		(start 257.64617 -59.057286)
		(end 257.07467 -59.057286)
		(width 0.254)
		(layer "F.Cu")
		(net "PVDDQ_ABC")
	)
	(segment
		(start 185.978292 -2.946908)
		(end 186.652408 -2.272792)
		(width 0.254)
		(layer "F.Cu")
		(net "PVDDQ_ABC")
	)
	(segment
		(start 274.599908 -0.821182)
		(end 274.600416 -0.821182)
		(width 0.508)
		(layer "F.Cu")
		(net "PVDDQ_ABC")
	)
	(segment
		(start 349.062294 -0.653542)
		(end 349.527876 -1.119124)
		(width 0.254)
		(layer "F.Cu")
		(net "PVDDQ_ABC")
	)
	(segment
		(start 244.849904 -2.314956)
		(end 244.849904 -0.821182)
		(width 0.508)
		(layer "F.Cu")
		(net "PVDDQ_ABC")
	)
	(segment
		(start 255.89992 -0.821182)
		(end 255.89992 -2.264156)
		(width 0.508)
		(layer "F.Cu")
		(net "PVDDQ_ABC")
	)
	(segment
		(start 251.649992 0.442722)
		(end 251.649992 -0.821182)
		(width 0.508)
		(layer "F.Cu")
		(net "PVDDQ_ABC")
	)
	(segment
		(start 273.74977 -15.423642)
		(end 273.74977 -13.934186)
		(width 0.508)
		(layer "F.Cu")
		(net "PVDDQ_ABC")
	)
	(segment
		(start 277.149814 -11.914378)
		(end 277.149814 -10.422382)
		(width 0.508)
		(layer "F.Cu")
		(net "PVDDQ_ABC")
	)
	(segment
		(start 250.799854 -13.933678)
		(end 250.799854 -15.423642)
		(width 0.508)
		(layer "F.Cu")
		(net "PVDDQ_ABC")
	)
	(segment
		(start 251.636784 -51.62804)
		(end 252.782324 -51.62804)
		(width 0.254)
		(layer "F.Cu")
		(net "PVDDQ_ABC")
	)
	(segment
		(start 243.999766 -16.716756)
		(end 243.999766 -15.423642)
		(width 0.508)
		(layer "F.Cu")
		(net "PVDDQ_ABC")
	)
	(segment
		(start 254.200406 -21.487638)
		(end 254.199898 -21.488146)
		(width 0.508)
		(layer "F.Cu")
		(net "PVDDQ_ABC")
	)
	(segment
		(start 277.149814 -0.821182)
		(end 277.149814 -2.313178)
		(width 0.508)
		(layer "F.Cu")
		(net "PVDDQ_ABC")
	)
	(segment
		(start 271.200372 -20.023582)
		(end 271.200372 -18.730976)
		(width 0.508)
		(layer "F.Cu")
		(net "PVDDQ_ABC")
	)
	(segment
		(start 275.449792 -15.423642)
		(end 275.449792 -13.934186)
		(width 0.508)
		(layer "F.Cu")
		(net "PVDDQ_ABC")
	)
	(segment
		(start 271.200372 2.515362)
		(end 271.200372 3.778758)
		(width 0.508)
		(layer "F.Cu")
		(net "PVDDQ_ABC")
	)
	(segment
		(start 258.450334 -20.023582)
		(end 258.450334 -18.699734)
		(width 0.508)
		(layer "F.Cu")
		(net "PVDDQ_ABC")
	)
	(segment
		(start 267.948156 -59.057286)
		(end 268.557756 -59.057286)
		(width 0.254)
		(layer "F.Cu")
		(net "PVDDQ_ABC")
	)
	(segment
		(start 243.999766 3.778758)
		(end 243.999766 2.485644)
		(width 0.508)
		(layer "F.Cu")
		(net "PVDDQ_ABC")
	)
	(segment
		(start 277.150322 -0.821182)
		(end 277.150322 0.467614)
		(width 0.508)
		(layer "F.Cu")
		(net "PVDDQ_ABC")
	)
	(segment
		(start 274.599908 -10.422382)
		(end 274.600416 -10.422382)
		(width 0.508)
		(layer "F.Cu")
		(net "PVDDQ_ABC")
	)
	(segment
		(start 251.6505 -11.91768)
		(end 251.649992 -11.918188)
		(width 0.508)
		(layer "F.Cu")
		(net "PVDDQ_ABC")
	)
	(segment
		(start 193.675 -13.3985)
		(end 193.675 -13.589)
		(width 0.4064)
		(layer "F.Cu")
		(net "PVDDQ_ABC")
	)
	(segment
		(start 272.900394 -20.023582)
		(end 272.900394 -21.516848)
		(width 0.508)
		(layer "F.Cu")
		(net "PVDDQ_ABC")
	)
	(segment
		(start 245.700296 -5.822442)
		(end 245.699788 -5.822442)
		(width 0.508)
		(layer "F.Cu")
		(net "PVDDQ_ABC")
	)
	(segment
		(start 349.760286 -10.097262)
		(end 349.760286 -9.586214)
		(width 0.254)
		(layer "F.Cu")
		(net "PVDDQ_ABC")
	)
	(segment
		(start 246.550434 -20.023582)
		(end 246.550434 -18.734786)
		(width 0.508)
		(layer "F.Cu")
		(net "PVDDQ_ABC")
	)
	(segment
		(start 251.636784 -58.770266)
		(end 251.923804 -59.057286)
		(width 0.254)
		(layer "F.Cu")
		(net "PVDDQ_ABC")
	)
	(segment
		(start 266.949936 -13.929868)
		(end 266.949936 -15.423642)
		(width 0.508)
		(layer "F.Cu")
		(net "PVDDQ_ABC")
	)
	(segment
		(start 261.08025 -50.141886)
		(end 261.08025 -49.150778)
		(width 0.2032)
		(layer "F.Cu")
		(net "PVDDQ_ABC")
	)
	(segment
		(start 244.849904 -0.821182)
		(end 244.850412 -0.821182)
		(width 0.508)
		(layer "F.Cu")
		(net "PVDDQ_ABC")
	)
	(segment
		(start 266.100306 -11.91387)
		(end 266.100306 -10.422382)
		(width 0.508)
		(layer "F.Cu")
		(net "PVDDQ_ABC")
	)
	(segment
		(start 259.36321 -62.029086)
		(end 258.79171 -62.029086)
		(width 0.254)
		(layer "F.Cu")
		(net "PVDDQ_ABC")
	)
	(segment
		(start 275.4503 -16.718788)
		(end 275.449792 -16.71828)
		(width 0.508)
		(layer "F.Cu")
		(net "PVDDQ_ABC")
	)
	(segment
		(start 249.10034 -18.734786)
		(end 249.099832 -18.734278)
		(width 0.508)
		(layer "F.Cu")
		(net "PVDDQ_ABC")
	)
	(segment
		(start 253.350522 -15.423642)
		(end 253.350522 -13.934186)
		(width 0.508)
		(layer "F.Cu")
		(net "PVDDQ_ABC")
	)
	(segment
		(start 258.450334 -11.915648)
		(end 258.449826 -11.916156)
		(width 0.508)
		(layer "F.Cu")
		(net "PVDDQ_ABC")
	)
	(segment
		(start 271.200372 -7.11327)
		(end 271.200372 -5.822442)
		(width 0.508)
		(layer "F.Cu")
		(net "PVDDQ_ABC")
	)
	(segment
		(start 266.95019 -16.718788)
		(end 266.949936 -16.718534)
		(width 0.508)
		(layer "F.Cu")
		(net "PVDDQ_ABC")
	)
	(segment
		(start 275.449792 -15.423642)
		(end 275.4503 -15.423642)
		(width 0.508)
		(layer "F.Cu")
		(net "PVDDQ_ABC")
	)
	(segment
		(start 273.74977 -13.934186)
		(end 273.750278 -13.933678)
		(width 0.5588)
		(layer "F.Cu")
		(net "PVDDQ_ABC")
	)
	(segment
		(start 244.849904 -11.916156)
		(end 244.849904 -10.422382)
		(width 0.508)
		(layer "F.Cu")
		(net "PVDDQ_ABC")
	)
	(segment
		(start 272.900394 -18.730976)
		(end 272.899886 -18.730468)
		(width 0.508)
		(layer "F.Cu")
		(net "PVDDQ_ABC")
	)
	(segment
		(start 261.93877 -51.62804)
		(end 262.22579 -51.132486)
		(width 0.254)
		(layer "F.Cu")
		(net "PVDDQ_ABC")
	)
	(segment
		(start 249.099832 -2.314956)
		(end 249.099832 -0.821182)
		(width 0.508)
		(layer "F.Cu")
		(net "PVDDQ_ABC")
	)
	(segment
		(start 243.999766 -4.332478)
		(end 243.999766 -5.822442)
		(width 0.508)
		(layer "F.Cu")
		(net "PVDDQ_ABC")
	)
	(segment
		(start 244.849904 -9.133078)
		(end 244.849904 -10.422382)
		(width 0.508)
		(layer "F.Cu")
		(net "PVDDQ_ABC")
	)
	(segment
		(start 348.647004 -0.653542)
		(end 349.062294 -0.653542)
		(width 0.254)
		(layer "F.Cu")
		(net "PVDDQ_ABC")
	)
	(segment
		(start 251.6505 -22.19706)
		(end 251.649992 -22.197568)
		(width 0.508)
		(layer "F.Cu")
		(net "PVDDQ_ABC")
	)
	(segment
		(start 255.89992 -5.822442)
		(end 255.900428 -5.822442)
		(width 0.508)
		(layer "F.Cu")
		(net "PVDDQ_ABC")
	)
	(segment
		(start 263.08431 -54.59984)
		(end 263.65581 -54.59984)
		(width 0.254)
		(layer "F.Cu")
		(net "PVDDQ_ABC")
	)
	(segment
		(start 252.782324 -51.62804)
		(end 253.353824 -51.62804)
		(width 0.254)
		(layer "F.Cu")
		(net "PVDDQ_ABC")
	)
	(segment
		(start 266.100306 -20.023582)
		(end 266.100306 -18.730976)
		(width 0.508)
		(layer "F.Cu")
		(net "PVDDQ_ABC")
	)
	(segment
		(start 245.699788 3.778758)
		(end 245.699788 2.485644)
		(width 0.508)
		(layer "F.Cu")
		(net "PVDDQ_ABC")
	)
	(segment
		(start 269.500096 -4.332478)
		(end 269.50035 -4.332732)
		(width 0.508)
		(layer "F.Cu")
		(net "PVDDQ_ABC")
	)
	(segment
		(start 258.449826 -7.115556)
		(end 258.449826 -5.822442)
		(width 0.508)
		(layer "F.Cu")
		(net "PVDDQ_ABC")
	)
	(segment
		(start 272.899886 -9.129268)
		(end 272.899886 -10.422382)
		(width 0.508)
		(layer "F.Cu")
		(net "PVDDQ_ABC")
	)
	(segment
		(start 244.850412 -21.293582)
		(end 244.849904 -21.29409)
		(width 0.508)
		(layer "F.Cu")
		(net "PVDDQ_ABC")
	)
	(segment
		(start 254.200406 -18.734786)
		(end 254.199898 -18.734278)
		(width 0.508)
		(layer "F.Cu")
		(net "PVDDQ_ABC")
	)
	(segment
		(start 269.50035 -5.822442)
		(end 269.50035 -7.117334)
		(width 0.508)
		(layer "F.Cu")
		(net "PVDDQ_ABC")
	)
	(segment
		(start 243.999766 -13.933678)
		(end 243.999766 -15.423642)
		(width 0.508)
		(layer "F.Cu")
		(net "PVDDQ_ABC")
	)
	(segment
		(start 271.199864 1.152144)
		(end 271.199864 -0.821182)
		(width 0.508)
		(layer "F.Cu")
		(net "PVDDQ_ABC")
	)
	(segment
		(start 250.800362 3.778758)
		(end 250.799854 3.778758)
		(width 0.508)
		(layer "F.Cu")
		(net "PVDDQ_ABC")
	)
	(segment
		(start 266.099798 -0.821182)
		(end 266.099798 1.152144)
		(width 0.508)
		(layer "F.Cu")
		(net "PVDDQ_ABC")
	)
	(segment
		(start 243.999766 -15.423642)
		(end 244.000274 -15.423642)
		(width 0.508)
		(layer "F.Cu")
		(net "PVDDQ_ABC")
	)
	(segment
		(start 271.199864 -0.821182)
		(end 271.200372 -0.821182)
		(width 0.508)
		(layer "F.Cu")
		(net "PVDDQ_ABC")
	)
	(segment
		(start 255.900428 -11.915648)
		(end 255.89992 -11.916156)
		(width 0.508)
		(layer "F.Cu")
		(net "PVDDQ_ABC")
	)
	(segment
		(start 277.150322 -5.822442)
		(end 277.150322 -4.329176)
		(width 0.508)
		(layer "F.Cu")
		(net "PVDDQ_ABC")
	)
	(segment
		(start 253.350014 -5.822442)
		(end 253.350014 -7.117588)
		(width 0.508)
		(layer "F.Cu")
		(net "PVDDQ_ABC")
	)
	(segment
		(start 348.96171 -8.787638)
		(end 348.725998 -8.787638)
		(width 0.254)
		(layer "F.Cu")
		(net "PVDDQ_ABC")
	)
	(segment
		(start 255.07061 -51.62804)
		(end 255.35763 -52.12334)
		(width 0.254)
		(layer "F.Cu")
		(net "PVDDQ_ABC")
	)
	(segment
		(start 277.150322 0.467614)
		(end 277.149814 0.468122)
		(width 0.508)
		(layer "F.Cu")
		(net "PVDDQ_ABC")
	)
	(segment
		(start 258.1656 -13.645642)
		(end 258.449826 -13.929868)
		(width 0.508)
		(layer "F.Cu")
		(net "PVDDQ_ABC")
	)
	(segment
		(start 271.199864 -4.328668)
		(end 271.200372 -4.329176)
		(width 0.508)
		(layer "F.Cu")
		(net "PVDDQ_ABC")
	)
	(segment
		(start 268.649958 -10.422382)
		(end 268.650466 -10.422382)
		(width 0.508)
		(layer "F.Cu")
		(net "PVDDQ_ABC")
	)
	(segment
		(start 266.949936 -16.718534)
		(end 266.949936 -15.423642)
		(width 0.508)
		(layer "F.Cu")
		(net "PVDDQ_ABC")
	)
	(segment
		(start 245.7577 -3.107182)
		(end 245.7577 -3.3528)
		(width 0.508)
		(layer "F.Cu")
		(net "PVDDQ_ABC")
	)
	(segment
		(start 255.900428 -10.422382)
		(end 255.900428 -11.915648)
		(width 0.508)
		(layer "F.Cu")
		(net "PVDDQ_ABC")
	)
	(segment
		(start 244.849904 -10.422382)
		(end 244.850412 -10.422382)
		(width 0.508)
		(layer "F.Cu")
		(net "PVDDQ_ABC")
	)
	(segment
		(start 274.600416 -21.487638)
		(end 274.599908 -21.488146)
		(width 0.508)
		(layer "F.Cu")
		(net "PVDDQ_ABC")
	)
	(segment
		(start 268.650466 -20.023582)
		(end 268.650466 -21.442934)
		(width 0.508)
		(layer "F.Cu")
		(net "PVDDQ_ABC")
	)
	(segment
		(start 258.50469 -57.57164)
		(end 257.93319 -57.57164)
		(width 0.254)
		(layer "F.Cu")
		(net "PVDDQ_ABC")
	)
	(segment
		(start 250.799854 -15.423642)
		(end 250.800362 -15.423642)
		(width 0.508)
		(layer "F.Cu")
		(net "PVDDQ_ABC")
	)
	(segment
		(start 248.249948 -16.716756)
		(end 248.249948 -15.423642)
		(width 0.508)
		(layer "F.Cu")
		(net "PVDDQ_ABC")
	)
	(segment
		(start 245.700296 3.778758)
		(end 245.699788 3.778758)
		(width 0.508)
		(layer "F.Cu")
		(net "PVDDQ_ABC")
	)
	(segment
		(start 261.747 -23.241)
		(end 262.255 -22.733)
		(width 0.508)
		(layer "F.Cu")
		(net "PVDDQ_ABC")
	)
	(segment
		(start 267.948156 -51.132486)
		(end 267.948156 -50.803556)
		(width 0.254)
		(layer "F.Cu")
		(net "PVDDQ_ABC")
	)
	(segment
		(start 274.599908 -2.313178)
		(end 274.599908 -0.821182)
		(width 0.508)
		(layer "F.Cu")
		(net "PVDDQ_ABC")
	)
	(segment
		(start 255.900428 -20.023582)
		(end 255.900428 -21.540724)
		(width 0.508)
		(layer "F.Cu")
		(net "PVDDQ_ABC")
	)
	(segment
		(start 243.999766 -5.822442)
		(end 244.000274 -5.822442)
		(width 0.508)
		(layer "F.Cu")
		(net "PVDDQ_ABC")
	)
	(segment
		(start 276.839172 -21.251418)
		(end 276.839172 -21.886926)
		(width 0.254)
		(layer "F.Cu")
		(net "PVDDQ_ABC")
	)
	(segment
		(start 267.948156 -50.803556)
		(end 267.716 -50.5714)
		(width 0.254)
		(layer "F.Cu")
		(net "PVDDQ_ABC")
	)
	(segment
		(start 273.74977 3.778758)
		(end 273.74977 1.805432)
		(width 0.508)
		(layer "F.Cu")
		(net "PVDDQ_ABC")
	)
	(segment
		(start 263.65581 -51.62804)
		(end 263.08431 -52.618386)
		(width 0.254)
		(layer "F.Cu")
		(net "PVDDQ_ABC")
	)
	(segment
		(start 251.649992 -2.316988)
		(end 251.649992 -0.821182)
		(width 0.508)
		(layer "F.Cu")
		(net "PVDDQ_ABC")
	)
	(segment
		(start 262.255 -21.2598)
		(end 262.89 -20.6248)
		(width 0.508)
		(layer "F.Cu")
		(net "PVDDQ_ABC")
	)
	(segment
		(start 277.150322 -20.023582)
		(end 277.149814 -20.023582)
		(width 0.508)
		(layer "F.Cu")
		(net "PVDDQ_ABC")
	)
	(segment
		(start 277.150322 3.778758)
		(end 277.150322 0.46863)
		(width 0.508)
		(layer "F.Cu")
		(net "PVDDQ_ABC")
	)
	(segment
		(start 260.22173 -51.62804)
		(end 260.50875 -52.123594)
		(width 0.254)
		(layer "F.Cu")
		(net "PVDDQ_ABC")
	)
	(segment
		(start 271.199864 -7.113778)
		(end 271.200372 -7.11327)
		(width 0.508)
		(layer "F.Cu")
		(net "PVDDQ_ABC")
	)
	(segment
		(start 251.636784 -58.561986)
		(end 251.636784 -58.770266)
		(width 0.254)
		(layer "F.Cu")
		(net "PVDDQ_ABC")
	)
	(segment
		(start 255.89992 2.485644)
		(end 255.89992 3.778758)
		(width 0.508)
		(layer "F.Cu")
		(net "PVDDQ_ABC")
	)
	(segment
		(start 266.950444 -5.822442)
		(end 266.950444 -7.117334)
		(width 0.508)
		(layer "F.Cu")
		(net "PVDDQ_ABC")
	)
	(segment
		(start 266.949936 -15.423642)
		(end 266.950444 -15.423642)
		(width 0.508)
		(layer "F.Cu")
		(net "PVDDQ_ABC")
	)
	(segment
		(start 268.650466 -20.023582)
		(end 268.650466 -18.730976)
		(width 0.508)
		(layer "F.Cu")
		(net "PVDDQ_ABC")
	)
	(segment
		(start 256.78765 -57.57164)
		(end 256.21615 -57.57164)
		(width 0.254)
		(layer "F.Cu")
		(net "PVDDQ_ABC")
	)
	(segment
		(start 243.735606 -26.591006)
		(end 244.401086 -26.591006)
		(width 0.4064)
		(layer "F.Cu")
		(net "PVDDQ_ABC")
	)
	(segment
		(start 277.150322 0.46863)
		(end 277.149814 0.468122)
		(width 0.508)
		(layer "F.Cu")
		(net "PVDDQ_ABC")
	)
	(segment
		(start 255.89992 -0.820674)
		(end 255.89992 0.471932)
		(width 0.508)
		(layer "F.Cu")
		(net "PVDDQ_ABC")
	)
	(segment
		(start 243.999766 -7.115556)
		(end 243.999766 -5.822442)
		(width 0.508)
		(layer "F.Cu")
		(net "PVDDQ_ABC")
	)
	(segment
		(start 263.08431 -57.57164)
		(end 263.65581 -57.57164)
		(width 0.254)
		(layer "F.Cu")
		(net "PVDDQ_ABC")
	)
	(segment
		(start 273.750278 -5.822442)
		(end 273.750278 -4.332478)
		(width 0.508)
		(layer "F.Cu")
		(net "PVDDQ_ABC")
	)
	(segment
		(start 268.650466 -0.821182)
		(end 268.650466 0.44196)
		(width 0.508)
		(layer "F.Cu")
		(net "PVDDQ_ABC")
	)
	(segment
		(start 251.636784 -55.59044)
		(end 251.065284 -55.59044)
		(width 0.254)
		(layer "F.Cu")
		(net "PVDDQ_ABC")
	)
	(segment
		(start 266.100306 -21.487638)
		(end 266.099798 -21.488146)
		(width 0.508)
		(layer "F.Cu")
		(net "PVDDQ_ABC")
	)
	(segment
		(start 272.899886 1.152144)
		(end 272.899886 -0.821182)
		(width 0.508)
		(layer "F.Cu")
		(net "PVDDQ_ABC")
	)
	(segment
		(start 186.652408 -0.674624)
		(end 186.008264 -0.03048)
		(width 0.254)
		(layer "F.Cu")
		(net "PVDDQ_ABC")
	)
	(segment
		(start 268.650466 -21.442934)
		(end 268.649704 -21.443696)
		(width 0.508)
		(layer "F.Cu")
		(net "PVDDQ_ABC")
	)
	(segment
		(start 277.150322 -20.023582)
		(end 277.150322 -20.725892)
		(width 0.508)
		(layer "F.Cu")
		(net "PVDDQ_ABC")
	)
	(segment
		(start 259.36321 -59.057286)
		(end 258.79171 -59.057286)
		(width 0.254)
		(layer "F.Cu")
		(net "PVDDQ_ABC")
	)
	(segment
		(start 266.950444 1.806194)
		(end 266.950444 3.778758)
		(width 0.508)
		(layer "F.Cu")
		(net "PVDDQ_ABC")
	)
	(segment
		(start 267.64996 -50.63744)
		(end 267.089636 -50.63744)
		(width 0.254)
		(layer "F.Cu")
		(net "PVDDQ_ABC")
	)
	(segment
		(start 269.50035 3.778758)
		(end 269.499842 3.778758)
		(width 0.508)
		(layer "F.Cu")
		(net "PVDDQ_ABC")
	)
	(segment
		(start 257.64617 -62.029086)
		(end 257.07467 -62.029086)
		(width 0.254)
		(layer "F.Cu")
		(net "PVDDQ_ABC")
	)
	(segment
		(start 255.900428 -0.821182)
		(end 255.89992 -0.821182)
		(width 0.508)
		(layer "F.Cu")
		(net "PVDDQ_ABC")
	)
	(segment
		(start 258.50469 -54.59984)
		(end 257.93319 -54.59984)
		(width 0.254)
		(layer "F.Cu")
		(net "PVDDQ_ABC")
	)
	(segment
		(start 267.716 -50.5714)
		(end 267.64996 -50.63744)
		(width 0.254)
		(layer "F.Cu")
		(net "PVDDQ_ABC")
	)
	(segment
		(start 266.100306 -18.730976)
		(end 266.099798 -18.730468)
		(width 0.508)
		(layer "F.Cu")
		(net "PVDDQ_ABC")
	)
	(segment
		(start 272.900394 -21.516848)
		(end 272.899886 -21.517356)
		(width 0.508)
		(layer "F.Cu")
		(net "PVDDQ_ABC")
	)
	(segment
		(start 273.750278 3.778758)
		(end 273.74977 3.778758)
		(width 0.508)
		(layer "F.Cu")
		(net "PVDDQ_ABC")
	)
	(segment
		(start 275.4503 -5.822442)
		(end 275.4503 -4.332478)
		(width 0.508)
		(layer "F.Cu")
		(net "PVDDQ_ABC")
	)
	(segment
		(start 251.6505 -20.023582)
		(end 251.6505 -18.734786)
		(width 0.508)
		(layer "F.Cu")
		(net "PVDDQ_ABC")
	)
	(segment
		(start 258.1656 -12.9032)
		(end 258.1656 -13.645642)
		(width 0.508)
		(layer "F.Cu")
		(net "PVDDQ_ABC")
	)
	(segment
		(start 255.92913 -59.057286)
		(end 255.35763 -59.057286)
		(width 0.254)
		(layer "F.Cu")
		(net "PVDDQ_ABC")
	)
	(segment
		(start 194.0814 -4.3434)
		(end 193.675 -3.937)
		(width 0.4064)
		(layer "F.Cu")
		(net "PVDDQ_ABC")
	)
	(segment
		(start 245.699788 -13.933678)
		(end 245.699788 -15.423642)
		(width 0.508)
		(layer "F.Cu")
		(net "PVDDQ_ABC")
	)
	(segment
		(start 250.799854 -16.716756)
		(end 250.799854 -15.423642)
		(width 0.508)
		(layer "F.Cu")
		(net "PVDDQ_ABC")
	)
	(via
		(at 266.099798 -21.488146)
		(size 0.508)
		(drill 0.254)
		(layers "F.Cu" "B.Cu")
		(net "PVDDQ_ABC")
	)
	(via
		(at 269.499842 -22.850856)
		(size 0.508)
		(drill 0.254)
		(layers "F.Cu" "B.Cu")
		(net "PVDDQ_ABC")
	)
	(via
		(at 258.449826 2.485644)
		(size 0.508)
		(drill 0.254)
		(layers "F.Cu" "B.Cu")
		(net "PVDDQ_ABC")
	)
	(via
		(at 330.5048 -3.20294)
		(size 0.508)
		(drill 0.254)
		(layers "F.Cu" "B.Cu")
		(net "PVDDQ_ABC")
	)
	(via
		(at 246.549926 0.442722)
		(size 0.508)
		(drill 0.254)
		(layers "F.Cu" "B.Cu")
		(net "PVDDQ_ABC")
	)
	(via
		(at 256.21615 -54.59984)
		(size 0.508)
		(drill 0.254)
		(layers "F.Cu" "B.Cu")
		(net "PVDDQ_ABC")
	)
	(via
		(at 271.199864 -2.313178)
		(size 0.508)
		(drill 0.254)
		(layers "F.Cu" "B.Cu")
		(net "PVDDQ_ABC")
	)
	(via
		(at 249.099832 -18.734278)
		(size 0.508)
		(drill 0.254)
		(layers "F.Cu" "B.Cu")
		(net "PVDDQ_ABC")
	)
	(via
		(at 273.750278 -13.933678)
		(size 0.508)
		(drill 0.254)
		(layers "F.Cu" "B.Cu")
		(net "PVDDQ_ABC")
	)
	(via
		(at 329.077574 -23.95728)
		(size 0.508)
		(drill 0.254)
		(layers "F.Cu" "B.Cu")
		(net "PVDDQ_ABC")
	)
	(via
		(at 253.350014 -23.560278)
		(size 0.508)
		(drill 0.254)
		(layers "F.Cu" "B.Cu")
		(net "PVDDQ_ABC")
	)
	(via
		(at 258.79171 -62.029086)
		(size 0.508)
		(drill 0.254)
		(layers "F.Cu" "B.Cu")
		(net "PVDDQ_ABC")
	)
	(via
		(at 333.3242 -0.6858)
		(size 0.508)
		(drill 0.254)
		(layers "F.Cu" "B.Cu")
		(net "PVDDQ_ABC")
	)
	(via
		(at 248.249948 -13.933678)
		(size 0.508)
		(drill 0.254)
		(layers "F.Cu" "B.Cu")
		(net "PVDDQ_ABC")
	)
	(via
		(at 337.33359 -2.50571)
		(size 0.508)
		(drill 0.254)
		(layers "F.Cu" "B.Cu")
		(net "PVDDQ_ABC")
	)
	(via
		(at 269.342108 -67.258946)
		(size 0.5588)
		(drill 0.3048)
		(layers "F.Cu" "B.Cu")
		(net "PVDDQ_ABC")
	)
	(via
		(at 266.949682 -26.8732)
		(size 0.508)
		(drill 0.254)
		(layers "F.Cu" "B.Cu")
		(net "PVDDQ_ABC")
	)
	(via
		(at 254.199898 -18.734278)
		(size 0.508)
		(drill 0.254)
		(layers "F.Cu" "B.Cu")
		(net "PVDDQ_ABC")
	)
	(via
		(at 249.099832 -21.517356)
		(size 0.508)
		(drill 0.254)
		(layers "F.Cu" "B.Cu")
		(net "PVDDQ_ABC")
	)
	(via
		(at 277.149814 -4.328668)
		(size 0.508)
		(drill 0.254)
		(layers "F.Cu" "B.Cu")
		(net "PVDDQ_ABC")
	)
	(via
		(at 266.949682 -23.560278)
		(size 0.508)
		(drill 0.254)
		(layers "F.Cu" "B.Cu")
		(net "PVDDQ_ABC")
	)
	(via
		(at 254.199898 -9.133078)
		(size 0.508)
		(drill 0.254)
		(layers "F.Cu" "B.Cu")
		(net "PVDDQ_ABC")
	)
	(via
		(at 244.66423 -26.85415)
		(size 0.508)
		(drill 0.254)
		(layers "F.Cu" "B.Cu")
		(net "PVDDQ_ABC")
	)
	(via
		(at 245.699788 2.485644)
		(size 0.508)
		(drill 0.254)
		(layers "F.Cu" "B.Cu")
		(net "PVDDQ_ABC")
	)
	(via
		(at 262.89 -20.6248)
		(size 0.508)
		(drill 0.254)
		(layers "F.Cu" "B.Cu")
		(net "PVDDQ_ABC")
	)
	(via
		(at 277.149814 -2.313178)
		(size 0.508)
		(drill 0.254)
		(layers "F.Cu" "B.Cu")
		(net "PVDDQ_ABC")
	)
	(via
		(at 266.099798 -11.914378)
		(size 0.508)
		(drill 0.254)
		(layers "F.Cu" "B.Cu")
		(net "PVDDQ_ABC")
	)
	(via
		(at 265.659616 -50.129186)
		(size 0.508)
		(drill 0.254)
		(layers "F.Cu" "B.Cu")
		(net "PVDDQ_ABC")
	)
	(via
		(at 335.923128 -2.494788)
		(size 0.508)
		(drill 0.254)
		(layers "F.Cu" "B.Cu")
		(net "PVDDQ_ABC")
	)
	(via
		(at 255.89992 -22.225)
		(size 0.508)
		(drill 0.254)
		(layers "F.Cu" "B.Cu")
		(net "PVDDQ_ABC")
	)
	(via
		(at 255.35763 -62.029086)
		(size 0.508)
		(drill 0.254)
		(layers "F.Cu" "B.Cu")
		(net "PVDDQ_ABC")
	)
	(via
		(at 330.7842 -1.2192)
		(size 0.508)
		(drill 0.254)
		(layers "F.Cu" "B.Cu")
		(net "PVDDQ_ABC")
	)
	(via
		(at 272.899886 -11.914378)
		(size 0.508)
		(drill 0.254)
		(layers "F.Cu" "B.Cu")
		(net "PVDDQ_ABC")
	)
	(via
		(at 250.799854 -13.933678)
		(size 0.508)
		(drill 0.254)
		(layers "F.Cu" "B.Cu")
		(net "PVDDQ_ABC")
	)
	(via
		(at 271.199864 -13.929868)
		(size 0.508)
		(drill 0.254)
		(layers "F.Cu" "B.Cu")
		(net "PVDDQ_ABC")
	)
	(via
		(at 271.199864 -4.328668)
		(size 0.508)
		(drill 0.254)
		(layers "F.Cu" "B.Cu")
		(net "PVDDQ_ABC")
	)
	(via
		(at 245.699788 -16.716756)
		(size 0.508)
		(drill 0.254)
		(layers "F.Cu" "B.Cu")
		(net "PVDDQ_ABC")
	)
	(via
		(at 266.949936 -13.929868)
		(size 0.508)
		(drill 0.254)
		(layers "F.Cu" "B.Cu")
		(net "PVDDQ_ABC")
	)
	(via
		(at 258.2164 -16.7513)
		(size 0.508)
		(drill 0.254)
		(layers "F.Cu" "B.Cu")
		(net "PVDDQ_ABC")
	)
	(via
		(at 258.79171 -59.057286)
		(size 0.508)
		(drill 0.254)
		(layers "F.Cu" "B.Cu")
		(net "PVDDQ_ABC")
	)
	(via
		(at 258.4069 -18.6563)
		(size 0.508)
		(drill 0.254)
		(layers "F.Cu" "B.Cu")
		(net "PVDDQ_ABC")
	)
	(via
		(at 332.9178 -1.2192)
		(size 0.508)
		(drill 0.254)
		(layers "F.Cu" "B.Cu")
		(net "PVDDQ_ABC")
	)
	(via
		(at 275.449792 -23.560278)
		(size 0.508)
		(drill 0.254)
		(layers "F.Cu" "B.Cu")
		(net "PVDDQ_ABC")
	)
	(via
		(at 272.899886 -21.517356)
		(size 0.508)
		(drill 0.254)
		(layers "F.Cu" "B.Cu")
		(net "PVDDQ_ABC")
	)
	(via
		(at 333.741268 -7.801356)
		(size 0.508)
		(drill 0.254)
		(layers "F.Cu" "B.Cu")
		(net "PVDDQ_ABC")
	)
	(via
		(at 266.099798 1.152144)
		(size 0.508)
		(drill 0.254)
		(layers "F.Cu" "B.Cu")
		(net "PVDDQ_ABC")
	)
	(via
		(at 246.549926 -22.197568)
		(size 0.508)
		(drill 0.254)
		(layers "F.Cu" "B.Cu")
		(net "PVDDQ_ABC")
	)
	(via
		(at 274.599908 1.152144)
		(size 0.508)
		(drill 0.254)
		(layers "F.Cu" "B.Cu")
		(net "PVDDQ_ABC")
	)
	(via
		(at 268.649958 -9.129268)
		(size 0.508)
		(drill 0.254)
		(layers "F.Cu" "B.Cu")
		(net "PVDDQ_ABC")
	)
	(via
		(at 261.36727 -57.57164)
		(size 0.508)
		(drill 0.254)
		(layers "F.Cu" "B.Cu")
		(net "PVDDQ_ABC")
	)
	(via
		(at 251.649992 -11.918188)
		(size 0.508)
		(drill 0.254)
		(layers "F.Cu" "B.Cu")
		(net "PVDDQ_ABC")
	)
	(via
		(at 186.69508 2.249932)
		(size 0.508)
		(drill 0.254)
		(layers "F.Cu" "B.Cu")
		(net "PVDDQ_ABC")
	)
	(via
		(at 272.062194 -26.8732)
		(size 0.508)
		(drill 0.254)
		(layers "F.Cu" "B.Cu")
		(net "PVDDQ_ABC")
	)
	(via
		(at 251.649992 -18.734278)
		(size 0.508)
		(drill 0.254)
		(layers "F.Cu" "B.Cu")
		(net "PVDDQ_ABC")
	)
	(via
		(at 185.976514 1.038098)
		(size 0.508)
		(drill 0.254)
		(layers "F.Cu" "B.Cu")
		(net "PVDDQ_ABC")
	)
	(via
		(at 336.4992 -1.1938)
		(size 0.508)
		(drill 0.254)
		(layers "F.Cu" "B.Cu")
		(net "PVDDQ_ABC")
	)
	(via
		(at 254.49911 -57.57164)
		(size 0.508)
		(drill 0.254)
		(layers "F.Cu" "B.Cu")
		(net "PVDDQ_ABC")
	)
	(via
		(at 266.518136 -51.62804)
		(size 0.508)
		(drill 0.254)
		(layers "F.Cu" "B.Cu")
		(net "PVDDQ_ABC")
	)
	(via
		(at 246.549926 -11.916156)
		(size 0.508)
		(drill 0.254)
		(layers "F.Cu" "B.Cu")
		(net "PVDDQ_ABC")
	)
	(via
		(at 263.08431 -52.618386)
		(size 0.508)
		(drill 0.254)
		(layers "F.Cu" "B.Cu")
		(net "PVDDQ_ABC")
	)
	(via
		(at 251.649992 -2.316988)
		(size 0.508)
		(drill 0.254)
		(layers "F.Cu" "B.Cu")
		(net "PVDDQ_ABC")
	)
	(via
		(at 250.799854 -7.115556)
		(size 0.508)
		(drill 0.254)
		(layers "F.Cu" "B.Cu")
		(net "PVDDQ_ABC")
	)
	(via
		(at 333.199486 -8.152384)
		(size 0.508)
		(drill 0.254)
		(layers "F.Cu" "B.Cu")
		(net "PVDDQ_ABC")
	)
	(via
		(at 335.788 -1.1938)
		(size 0.508)
		(drill 0.254)
		(layers "F.Cu" "B.Cu")
		(net "PVDDQ_ABC")
	)
	(via
		(at 274.599908 -18.730468)
		(size 0.508)
		(drill 0.254)
		(layers "F.Cu" "B.Cu")
		(net "PVDDQ_ABC")
	)
	(via
		(at 277.149814 -11.914378)
		(size 0.508)
		(drill 0.254)
		(layers "F.Cu" "B.Cu")
		(net "PVDDQ_ABC")
	)
	(via
		(at 250.799854 -22.850856)
		(size 0.508)
		(drill 0.254)
		(layers "F.Cu" "B.Cu")
		(net "PVDDQ_ABC")
	)
	(via
		(at 335.788 3.7592)
		(size 0.508)
		(drill 0.254)
		(layers "F.Cu" "B.Cu")
		(net "PVDDQ_ABC")
	)
	(via
		(at 277.149814 -22.197568)
		(size 0.508)
		(drill 0.254)
		(layers "F.Cu" "B.Cu")
		(net "PVDDQ_ABC")
	)
	(via
		(at 268.557756 -59.057286)
		(size 0.508)
		(drill 0.254)
		(layers "F.Cu" "B.Cu")
		(net "PVDDQ_ABC")
	)
	(via
		(at 253.350014 -13.933678)
		(size 0.508)
		(drill 0.254)
		(layers "F.Cu" "B.Cu")
		(net "PVDDQ_ABC")
	)
	(via
		(at 265.938508 -67.284346)
		(size 0.508)
		(drill 0.254)
		(layers "F.Cu" "B.Cu")
		(net "PVDDQ_ABC")
	)
	(via
		(at 332.613 -0.6858)
		(size 0.508)
		(drill 0.254)
		(layers "F.Cu" "B.Cu")
		(net "PVDDQ_ABC")
	)
	(via
		(at 250.799854 -16.716756)
		(size 0.508)
		(drill 0.254)
		(layers "F.Cu" "B.Cu")
		(net "PVDDQ_ABC")
	)
	(via
		(at 265.659616 -59.057286)
		(size 0.508)
		(drill 0.254)
		(layers "F.Cu" "B.Cu")
		(net "PVDDQ_ABC")
	)
	(via
		(at 274.599908 -21.488146)
		(size 0.508)
		(drill 0.254)
		(layers "F.Cu" "B.Cu")
		(net "PVDDQ_ABC")
	)
	(via
		(at 336.4992 3.7592)
		(size 0.508)
		(drill 0.254)
		(layers "F.Cu" "B.Cu")
		(net "PVDDQ_ABC")
	)
	(via
		(at 268.557756 -61.038486)
		(size 0.508)
		(drill 0.254)
		(layers "F.Cu" "B.Cu")
		(net "PVDDQ_ABC")
	)
	(via
		(at 256.21615 -57.57164)
		(size 0.508)
		(drill 0.254)
		(layers "F.Cu" "B.Cu")
		(net "PVDDQ_ABC")
	)
	(via
		(at 334.011016 4.300982)
		(size 0.508)
		(drill 0.254)
		(layers "F.Cu" "B.Cu")
		(net "PVDDQ_ABC")
	)
	(via
		(at 271.8562 -67.2846)
		(size 0.5588)
		(drill 0.3048)
		(layers "F.Cu" "B.Cu")
		(net "PVDDQ_ABC")
	)
	(via
		(at 245.699788 -7.115556)
		(size 0.508)
		(drill 0.254)
		(layers "F.Cu" "B.Cu")
		(net "PVDDQ_ABC")
	)
	(via
		(at 265.049508 -67.284346)
		(size 0.508)
		(drill 0.254)
		(layers "F.Cu" "B.Cu")
		(net "PVDDQ_ABC")
	)
	(via
		(at 277.149814 -9.129268)
		(size 0.508)
		(drill 0.254)
		(layers "F.Cu" "B.Cu")
		(net "PVDDQ_ABC")
	)
	(via
		(at 247.9548 -26.8224)
		(size 0.508)
		(drill 0.254)
		(layers "F.Cu" "B.Cu")
		(net "PVDDQ_ABC")
	)
	(via
		(at 334.9498 -8.113522)
		(size 0.508)
		(drill 0.254)
		(layers "F.Cu" "B.Cu")
		(net "PVDDQ_ABC")
	)
	(via
		(at 337.343242 -3.23342)
		(size 0.508)
		(drill 0.254)
		(layers "F.Cu" "B.Cu")
		(net "PVDDQ_ABC")
	)
	(via
		(at 255.923542 -23.495)
		(size 0.508)
		(drill 0.254)
		(layers "F.Cu" "B.Cu")
		(net "PVDDQ_ABC")
	)
	(via
		(at 268.664436 -26.8605)
		(size 0.508)
		(drill 0.254)
		(layers "F.Cu" "B.Cu")
		(net "PVDDQ_ABC")
	)
	(via
		(at 335.648808 -8.077962)
		(size 0.508)
		(drill 0.254)
		(layers "F.Cu" "B.Cu")
		(net "PVDDQ_ABC")
	)
	(via
		(at 255.89992 -11.916156)
		(size 0.508)
		(drill 0.254)
		(layers "F.Cu" "B.Cu")
		(net "PVDDQ_ABC")
	)
	(via
		(at 332.2574 -10.541)
		(size 0.508)
		(drill 0.254)
		(layers "F.Cu" "B.Cu")
		(net "PVDDQ_ABC")
	)
	(via
		(at 336.804 -10.525506)
		(size 0.508)
		(drill 0.254)
		(layers "F.Cu" "B.Cu")
		(net "PVDDQ_ABC")
	)
	(via
		(at 264.801096 -51.62804)
		(size 0.508)
		(drill 0.254)
		(layers "F.Cu" "B.Cu")
		(net "PVDDQ_ABC")
	)
	(via
		(at 260.50875 -52.123594)
		(size 0.508)
		(drill 0.254)
		(layers "F.Cu" "B.Cu")
		(net "PVDDQ_ABC")
	)
	(via
		(at 258.449826 -7.115556)
		(size 0.508)
		(drill 0.254)
		(layers "F.Cu" "B.Cu")
		(net "PVDDQ_ABC")
	)
	(via
		(at 194.0814 -13.9954)
		(size 0.508)
		(drill 0.254)
		(layers "F.Cu" "B.Cu")
		(net "PVDDQ_ABC")
	)
	(via
		(at 251.649992 0.442722)
		(size 0.508)
		(drill 0.254)
		(layers "F.Cu" "B.Cu")
		(net "PVDDQ_ABC")
	)
	(via
		(at 253.350014 -4.332478)
		(size 0.508)
		(drill 0.254)
		(layers "F.Cu" "B.Cu")
		(net "PVDDQ_ABC")
	)
	(via
		(at 254.199898 -21.488146)
		(size 0.508)
		(drill 0.254)
		(layers "F.Cu" "B.Cu")
		(net "PVDDQ_ABC")
	)
	(via
		(at 337.562698 -0.64135)
		(size 0.508)
		(drill 0.254)
		(layers "F.Cu" "B.Cu")
		(net "PVDDQ_ABC")
	)
	(via
		(at 255.89992 -7.115556)
		(size 0.508)
		(drill 0.254)
		(layers "F.Cu" "B.Cu")
		(net "PVDDQ_ABC")
	)
	(via
		(at 266.518136 -54.59984)
		(size 0.508)
		(drill 0.254)
		(layers "F.Cu" "B.Cu")
		(net "PVDDQ_ABC")
	)
	(via
		(at 250.799854 -4.332478)
		(size 0.508)
		(drill 0.254)
		(layers "F.Cu" "B.Cu")
		(net "PVDDQ_ABC")
	)
	(via
		(at 277.149814 0.468122)
		(size 0.508)
		(drill 0.254)
		(layers "F.Cu" "B.Cu")
		(net "PVDDQ_ABC")
	)
	(via
		(at 258.449826 -13.929868)
		(size 0.508)
		(drill 0.254)
		(layers "F.Cu" "B.Cu")
		(net "PVDDQ_ABC")
	)
	(via
		(at 257.93319 -54.59984)
		(size 0.508)
		(drill 0.254)
		(layers "F.Cu" "B.Cu")
		(net "PVDDQ_ABC")
	)
	(via
		(at 271.199864 -21.488146)
		(size 0.508)
		(drill 0.254)
		(layers "F.Cu" "B.Cu")
		(net "PVDDQ_ABC")
	)
	(via
		(at 243.999766 -16.716756)
		(size 0.508)
		(drill 0.254)
		(layers "F.Cu" "B.Cu")
		(net "PVDDQ_ABC")
	)
	(via
		(at 253.350014 1.805432)
		(size 0.508)
		(drill 0.254)
		(layers "F.Cu" "B.Cu")
		(net "PVDDQ_ABC")
	)
	(via
		(at 277.149814 -13.929868)
		(size 0.508)
		(drill 0.254)
		(layers "F.Cu" "B.Cu")
		(net "PVDDQ_ABC")
	)
	(via
		(at 271.199864 -7.113778)
		(size 0.508)
		(drill 0.254)
		(layers "F.Cu" "B.Cu")
		(net "PVDDQ_ABC")
	)
	(via
		(at 263.08431 -54.59984)
		(size 0.508)
		(drill 0.254)
		(layers "F.Cu" "B.Cu")
		(net "PVDDQ_ABC")
	)
	(via
		(at 258.551426 -23.495)
		(size 0.508)
		(drill 0.254)
		(layers "F.Cu" "B.Cu")
		(net "PVDDQ_ABC")
	)
	(via
		(at 246.549926 -2.314956)
		(size 0.508)
		(drill 0.254)
		(layers "F.Cu" "B.Cu")
		(net "PVDDQ_ABC")
	)
	(via
		(at 274.599908 -2.313178)
		(size 0.508)
		(drill 0.254)
		(layers "F.Cu" "B.Cu")
		(net "PVDDQ_ABC")
	)
	(via
		(at 269.500096 -16.718788)
		(size 0.4572)
		(drill 0.2032)
		(layers "F.Cu" "B.Cu")
		(net "PVDDQ_ABC")
	)
	(via
		(at 271.199864 -11.914378)
		(size 0.508)
		(drill 0.254)
		(layers "F.Cu" "B.Cu")
		(net "PVDDQ_ABC")
	)
	(via
		(at 261.36727 -54.59984)
		(size 0.508)
		(drill 0.254)
		(layers "F.Cu" "B.Cu")
		(net "PVDDQ_ABC")
	)
	(via
		(at 252.782324 -51.62804)
		(size 0.508)
		(drill 0.254)
		(layers "F.Cu" "B.Cu")
		(net "PVDDQ_ABC")
	)
	(via
		(at 336.804 3.2258)
		(size 0.508)
		(drill 0.254)
		(layers "F.Cu" "B.Cu")
		(net "PVDDQ_ABC")
	)
	(via
		(at 331.1906 -0.6858)
		(size 0.508)
		(drill 0.254)
		(layers "F.Cu" "B.Cu")
		(net "PVDDQ_ABC")
	)
	(via
		(at 332.9178 3.7338)
		(size 0.508)
		(drill 0.254)
		(layers "F.Cu" "B.Cu")
		(net "PVDDQ_ABC")
	)
	(via
		(at 264.801096 -54.59984)
		(size 0.508)
		(drill 0.254)
		(layers "F.Cu" "B.Cu")
		(net "PVDDQ_ABC")
	)
	(via
		(at 251.065284 -55.59044)
		(size 0.508)
		(drill 0.254)
		(layers "F.Cu" "B.Cu")
		(net "PVDDQ_ABC")
	)
	(via
		(at 268.649958 -18.730468)
		(size 0.508)
		(drill 0.254)
		(layers "F.Cu" "B.Cu")
		(net "PVDDQ_ABC")
	)
	(via
		(at 269.500096 -7.117588)
		(size 0.4572)
		(drill 0.2032)
		(layers "F.Cu" "B.Cu")
		(net "PVDDQ_ABC")
	)
	(via
		(at 334.7466 4.2926)
		(size 0.508)
		(drill 0.254)
		(layers "F.Cu" "B.Cu")
		(net "PVDDQ_ABC")
	)
	(via
		(at 272.5928 -67.307714)
		(size 0.5588)
		(drill 0.3048)
		(layers "F.Cu" "B.Cu")
		(net "PVDDQ_ABC")
	)
	(via
		(at 273.74977 1.805432)
		(size 0.508)
		(drill 0.254)
		(layers "F.Cu" "B.Cu")
		(net "PVDDQ_ABC")
	)
	(via
		(at 271.199864 -16.714978)
		(size 0.508)
		(drill 0.254)
		(layers "F.Cu" "B.Cu")
		(net "PVDDQ_ABC")
	)
	(via
		(at 268.649958 -11.914378)
		(size 0.508)
		(drill 0.254)
		(layers "F.Cu" "B.Cu")
		(net "PVDDQ_ABC")
	)
	(via
		(at 337.2104 3.7592)
		(size 0.508)
		(drill 0.254)
		(layers "F.Cu" "B.Cu")
		(net "PVDDQ_ABC")
	)
	(via
		(at 273.750278 -16.718788)
		(size 0.4572)
		(drill 0.2032)
		(layers "F.Cu" "B.Cu")
		(net "PVDDQ_ABC")
	)
	(via
		(at 331.947266 -2.554732)
		(size 0.508)
		(drill 0.254)
		(layers "F.Cu" "B.Cu")
		(net "PVDDQ_ABC")
	)
	(via
		(at 336.1436 -10.525506)
		(size 0.508)
		(drill 0.254)
		(layers "F.Cu" "B.Cu")
		(net "PVDDQ_ABC")
	)
	(via
		(at 335.0768 -1.1938)
		(size 0.508)
		(drill 0.254)
		(layers "F.Cu" "B.Cu")
		(net "PVDDQ_ABC")
	)
	(via
		(at 256.089404 -13.929868)
		(size 0.508)
		(drill 0.254)
		(layers "F.Cu" "B.Cu")
		(net "PVDDQ_ABC")
	)
	(via
		(at 266.099798 -18.730468)
		(size 0.508)
		(drill 0.254)
		(layers "F.Cu" "B.Cu")
		(net "PVDDQ_ABC")
	)
	(via
		(at 264.801096 -57.57164)
		(size 0.508)
		(drill 0.254)
		(layers "F.Cu" "B.Cu")
		(net "PVDDQ_ABC")
	)
	(via
		(at 266.099798 -2.313178)
		(size 0.508)
		(drill 0.254)
		(layers "F.Cu" "B.Cu")
		(net "PVDDQ_ABC")
	)
	(via
		(at 186.008264 0.403098)
		(size 0.508)
		(drill 0.254)
		(layers "F.Cu" "B.Cu")
		(net "PVDDQ_ABC")
	)
	(via
		(at 274.599908 -9.129268)
		(size 0.508)
		(drill 0.254)
		(layers "F.Cu" "B.Cu")
		(net "PVDDQ_ABC")
	)
	(via
		(at 271.199864 -9.129268)
		(size 0.508)
		(drill 0.254)
		(layers "F.Cu" "B.Cu")
		(net "PVDDQ_ABC")
	)
	(via
		(at 252.782324 -57.57164)
		(size 0.508)
		(drill 0.254)
		(layers "F.Cu" "B.Cu")
		(net "PVDDQ_ABC")
	)
	(via
		(at 268.649704 -22.197568)
		(size 0.508)
		(drill 0.254)
		(layers "F.Cu" "B.Cu")
		(net "PVDDQ_ABC")
	)
	(via
		(at 277.149814 -16.714978)
		(size 0.508)
		(drill 0.254)
		(layers "F.Cu" "B.Cu")
		(net "PVDDQ_ABC")
	)
	(via
		(at 269.500096 -4.332478)
		(size 0.508)
		(drill 0.254)
		(layers "F.Cu" "B.Cu")
		(net "PVDDQ_ABC")
	)
	(via
		(at 248.249948 -23.560278)
		(size 0.508)
		(drill 0.254)
		(layers "F.Cu" "B.Cu")
		(net "PVDDQ_ABC")
	)
	(via
		(at 258.449826 -11.916156)
		(size 0.508)
		(drill 0.254)
		(layers "F.Cu" "B.Cu")
		(net "PVDDQ_ABC")
	)
	(via
		(at 263.08431 -57.57164)
		(size 0.508)
		(drill 0.254)
		(layers "F.Cu" "B.Cu")
		(net "PVDDQ_ABC")
	)
	(via
		(at 349.760286 -10.097262)
		(size 0.508)
		(drill 0.254)
		(layers "F.Cu" "B.Cu")
		(net "PVDDQ_ABC")
	)
	(via
		(at 186.668664 0.403098)
		(size 0.508)
		(drill 0.254)
		(layers "F.Cu" "B.Cu")
		(net "PVDDQ_ABC")
	)
	(via
		(at 257.07467 -62.029086)
		(size 0.508)
		(drill 0.254)
		(layers "F.Cu" "B.Cu")
		(net "PVDDQ_ABC")
	)
	(via
		(at 271.199864 -22.850856)
		(size 0.508)
		(drill 0.254)
		(layers "F.Cu" "B.Cu")
		(net "PVDDQ_ABC")
	)
	(via
		(at 259.65023 -54.59984)
		(size 0.508)
		(drill 0.254)
		(layers "F.Cu" "B.Cu")
		(net "PVDDQ_ABC")
	)
	(via
		(at 274.599908 -11.914378)
		(size 0.508)
		(drill 0.254)
		(layers "F.Cu" "B.Cu")
		(net "PVDDQ_ABC")
	)
	(via
		(at 268.529308 -67.284346)
		(size 0.5588)
		(drill 0.3048)
		(layers "F.Cu" "B.Cu")
		(net "PVDDQ_ABC")
	)
	(via
		(at 253.640844 -59.057286)
		(size 0.508)
		(drill 0.254)
		(layers "F.Cu" "B.Cu")
		(net "PVDDQ_ABC")
	)
	(via
		(at 270.364712 -26.8732)
		(size 0.508)
		(drill 0.254)
		(layers "F.Cu" "B.Cu")
		(net "PVDDQ_ABC")
	)
	(via
		(at 330.5048 -3.8608)
		(size 0.508)
		(drill 0.254)
		(layers "F.Cu" "B.Cu")
		(net "PVDDQ_ABC")
	)
	(via
		(at 272.899886 1.152144)
		(size 0.508)
		(drill 0.254)
		(layers "F.Cu" "B.Cu")
		(net "PVDDQ_ABC")
	)
	(via
		(at 334.7466 -0.6604)
		(size 0.508)
		(drill 0.254)
		(layers "F.Cu" "B.Cu")
		(net "PVDDQ_ABC")
	)
	(via
		(at 252.782324 -54.59984)
		(size 0.508)
		(drill 0.254)
		(layers "F.Cu" "B.Cu")
		(net "PVDDQ_ABC")
	)
	(via
		(at 243.999766 -4.332478)
		(size 0.508)
		(drill 0.254)
		(layers "F.Cu" "B.Cu")
		(net "PVDDQ_ABC")
	)
	(via
		(at 262.22579 -59.057286)
		(size 0.508)
		(drill 0.254)
		(layers "F.Cu" "B.Cu")
		(net "PVDDQ_ABC")
	)
	(via
		(at 243.999766 -13.933678)
		(size 0.508)
		(drill 0.254)
		(layers "F.Cu" "B.Cu")
		(net "PVDDQ_ABC")
	)
	(via
		(at 253.350014 -7.117588)
		(size 0.508)
		(drill 0.254)
		(layers "F.Cu" "B.Cu")
		(net "PVDDQ_ABC")
	)
	(via
		(at 273.74977 -23.560278)
		(size 0.508)
		(drill 0.254)
		(layers "F.Cu" "B.Cu")
		(net "PVDDQ_ABC")
	)
	(via
		(at 243.999766 2.485644)
		(size 0.508)
		(drill 0.254)
		(layers "F.Cu" "B.Cu")
		(net "PVDDQ_ABC")
	)
	(via
		(at 258.449826 -2.314956)
		(size 0.508)
		(drill 0.254)
		(layers "F.Cu" "B.Cu")
		(net "PVDDQ_ABC")
	)
	(via
		(at 272.899886 -2.313178)
		(size 0.508)
		(drill 0.254)
		(layers "F.Cu" "B.Cu")
		(net "PVDDQ_ABC")
	)
	(via
		(at 272.899886 -9.129268)
		(size 0.508)
		(drill 0.254)
		(layers "F.Cu" "B.Cu")
		(net "PVDDQ_ABC")
	)
	(via
		(at 335.4832 -0.6604)
		(size 0.508)
		(drill 0.254)
		(layers "F.Cu" "B.Cu")
		(net "PVDDQ_ABC")
	)
	(via
		(at 259.65023 -57.57164)
		(size 0.508)
		(drill 0.254)
		(layers "F.Cu" "B.Cu")
		(net "PVDDQ_ABC")
	)
	(via
		(at 193.4591 -24.0157)
		(size 0.508)
		(drill 0.254)
		(layers "F.Cu" "B.Cu")
		(net "PVDDQ_ABC")
	)
	(via
		(at 254.199898 -11.918188)
		(size 0.508)
		(drill 0.254)
		(layers "F.Cu" "B.Cu")
		(net "PVDDQ_ABC")
	)
	(via
		(at 244.849904 -11.916156)
		(size 0.508)
		(drill 0.254)
		(layers "F.Cu" "B.Cu")
		(net "PVDDQ_ABC")
	)
	(via
		(at 257.93319 -57.57164)
		(size 0.508)
		(drill 0.254)
		(layers "F.Cu" "B.Cu")
		(net "PVDDQ_ABC")
	)
	(via
		(at 244.849904 -2.314956)
		(size 0.508)
		(drill 0.254)
		(layers "F.Cu" "B.Cu")
		(net "PVDDQ_ABC")
	)
	(via
		(at 258.449826 -9.129268)
		(size 0.508)
		(drill 0.254)
		(layers "F.Cu" "B.Cu")
		(net "PVDDQ_ABC")
	)
	(via
		(at 258.449826 -22.225)
		(size 0.508)
		(drill 0.254)
		(layers "F.Cu" "B.Cu")
		(net "PVDDQ_ABC")
	)
	(via
		(at 194.0814 -4.3434)
		(size 0.508)
		(drill 0.254)
		(layers "F.Cu" "B.Cu")
		(net "PVDDQ_ABC")
	)
	(via
		(at 249.099832 -2.314956)
		(size 0.508)
		(drill 0.254)
		(layers "F.Cu" "B.Cu")
		(net "PVDDQ_ABC")
	)
	(via
		(at 248.249948 -7.115556)
		(size 0.508)
		(drill 0.254)
		(layers "F.Cu" "B.Cu")
		(net "PVDDQ_ABC")
	)
	(via
		(at 336.9056 -0.6604)
		(size 0.508)
		(drill 0.254)
		(layers "F.Cu" "B.Cu")
		(net "PVDDQ_ABC")
	)
	(via
		(at 272.050256 -9.133078)
		(size 0.4572)
		(drill 0.2032)
		(layers "F.Cu" "B.Cu")
		(net "PVDDQ_ABC")
	)
	(via
		(at 337.2358 -7.9248)
		(size 0.6604)
		(drill 0.3302)
		(layers "F.Cu" "B.Cu")
		(net "PVDDQ_ABC")
	)
	(via
		(at 333.629 -1.2192)
		(size 0.508)
		(drill 0.254)
		(layers "F.Cu" "B.Cu")
		(net "PVDDQ_ABC")
	)
	(via
		(at 254.199898 -2.316988)
		(size 0.508)
		(drill 0.254)
		(layers "F.Cu" "B.Cu")
		(net "PVDDQ_ABC")
	)
	(via
		(at 331.4954 -1.2192)
		(size 0.508)
		(drill 0.254)
		(layers "F.Cu" "B.Cu")
		(net "PVDDQ_ABC")
	)
	(via
		(at 268.649958 -2.313178)
		(size 0.508)
		(drill 0.254)
		(layers "F.Cu" "B.Cu")
		(net "PVDDQ_ABC")
	)
	(via
		(at 258.449826 -4.328668)
		(size 0.508)
		(drill 0.254)
		(layers "F.Cu" "B.Cu")
		(net "PVDDQ_ABC")
	)
	(via
		(at 336.1944 3.2004)
		(size 0.508)
		(drill 0.254)
		(layers "F.Cu" "B.Cu")
		(net "PVDDQ_ABC")
	)
	(via
		(at 268.649704 0.442722)
		(size 0.508)
		(drill 0.254)
		(layers "F.Cu" "B.Cu")
		(net "PVDDQ_ABC")
	)
	(via
		(at 367.368074 -50.11039)
		(size 0.508)
		(drill 0.254)
		(layers "F.Cu" "B.Cu")
		(net "PVDDQ_ABC")
	)
	(via
		(at 275.449792 1.805432)
		(size 0.508)
		(drill 0.254)
		(layers "F.Cu" "B.Cu")
		(net "PVDDQ_ABC")
	)
	(via
		(at 250.799854 2.514854)
		(size 0.508)
		(drill 0.254)
		(layers "F.Cu" "B.Cu")
		(net "PVDDQ_ABC")
	)
	(via
		(at 266.099798 -9.129268)
		(size 0.508)
		(drill 0.254)
		(layers "F.Cu" "B.Cu")
		(net "PVDDQ_ABC")
	)
	(via
		(at 246.549926 -18.734278)
		(size 0.508)
		(drill 0.254)
		(layers "F.Cu" "B.Cu")
		(net "PVDDQ_ABC")
	)
	(via
		(at 349.527876 -1.119124)
		(size 0.508)
		(drill 0.254)
		(layers "F.Cu" "B.Cu")
		(net "PVDDQ_ABC")
	)
	(via
		(at 258.449826 0.471932)
		(size 0.508)
		(drill 0.254)
		(layers "F.Cu" "B.Cu")
		(net "PVDDQ_ABC")
	)
	(via
		(at 332.8924 -10.541)
		(size 0.508)
		(drill 0.254)
		(layers "F.Cu" "B.Cu")
		(net "PVDDQ_ABC")
	)
	(via
		(at 253.350014 -16.718788)
		(size 0.508)
		(drill 0.254)
		(layers "F.Cu" "B.Cu")
		(net "PVDDQ_ABC")
	)
	(via
		(at 245.699788 -22.850856)
		(size 0.508)
		(drill 0.254)
		(layers "F.Cu" "B.Cu")
		(net "PVDDQ_ABC")
	)
	(via
		(at 267.716 -50.5714)
		(size 0.508)
		(drill 0.254)
		(layers "F.Cu" "B.Cu")
		(net "PVDDQ_ABC")
	)
	(via
		(at 261.08025 -49.150778)
		(size 0.508)
		(drill 0.254)
		(layers "F.Cu" "B.Cu")
		(net "PVDDQ_ABC")
	)
	(via
		(at 335.4832 4.2926)
		(size 0.508)
		(drill 0.254)
		(layers "F.Cu" "B.Cu")
		(net "PVDDQ_ABC")
	)
	(via
		(at 335.0768 3.7592)
		(size 0.508)
		(drill 0.254)
		(layers "F.Cu" "B.Cu")
		(net "PVDDQ_ABC")
	)
	(via
		(at 275.4503 -4.332478)
		(size 0.508)
		(drill 0.254)
		(layers "F.Cu" "B.Cu")
		(net "PVDDQ_ABC")
	)
	(via
		(at 263.94283 -59.057286)
		(size 0.508)
		(drill 0.254)
		(layers "F.Cu" "B.Cu")
		(net "PVDDQ_ABC")
	)
	(via
		(at 249.099832 -9.133078)
		(size 0.508)
		(drill 0.254)
		(layers "F.Cu" "B.Cu")
		(net "PVDDQ_ABC")
	)
	(via
		(at 332.613 4.2672)
		(size 0.508)
		(drill 0.254)
		(layers "F.Cu" "B.Cu")
		(net "PVDDQ_ABC")
	)
	(via
		(at 244.849904 -9.133078)
		(size 0.508)
		(drill 0.254)
		(layers "F.Cu" "B.Cu")
		(net "PVDDQ_ABC")
	)
	(via
		(at 332.2066 3.7338)
		(size 0.508)
		(drill 0.254)
		(layers "F.Cu" "B.Cu")
		(net "PVDDQ_ABC")
	)
	(via
		(at 271.199864 1.152144)
		(size 0.508)
		(drill 0.254)
		(layers "F.Cu" "B.Cu")
		(net "PVDDQ_ABC")
	)
	(via
		(at 333.629 3.7338)
		(size 0.508)
		(drill 0.254)
		(layers "F.Cu" "B.Cu")
		(net "PVDDQ_ABC")
	)
	(via
		(at 270.8402 -67.2338)
		(size 0.5588)
		(drill 0.3048)
		(layers "F.Cu" "B.Cu")
		(net "PVDDQ_ABC")
	)
	(via
		(at 334.3402 -8.105394)
		(size 0.508)
		(drill 0.254)
		(layers "F.Cu" "B.Cu")
		(net "PVDDQ_ABC")
	)
	(via
		(at 336.628232 -3.996436)
		(size 0.508)
		(drill 0.254)
		(layers "F.Cu" "B.Cu")
		(net "PVDDQ_ABC")
	)
	(via
		(at 336.1944 4.2926)
		(size 0.508)
		(drill 0.254)
		(layers "F.Cu" "B.Cu")
		(net "PVDDQ_ABC")
	)
	(via
		(at 243.999766 -22.850856)
		(size 0.508)
		(drill 0.254)
		(layers "F.Cu" "B.Cu")
		(net "PVDDQ_ABC")
	)
	(via
		(at 251.923804 -62.029086)
		(size 0.508)
		(drill 0.254)
		(layers "F.Cu" "B.Cu")
		(net "PVDDQ_ABC")
	)
	(via
		(at 257.93319 -51.62804)
		(size 0.508)
		(drill 0.254)
		(layers "F.Cu" "B.Cu")
		(net "PVDDQ_ABC")
	)
	(via
		(at 270.104108 -67.258946)
		(size 0.5588)
		(drill 0.3048)
		(layers "F.Cu" "B.Cu")
		(net "PVDDQ_ABC")
	)
	(via
		(at 334.3402 3.7592)
		(size 0.508)
		(drill 0.254)
		(layers "F.Cu" "B.Cu")
		(net "PVDDQ_ABC")
	)
	(via
		(at 334.3402 -1.1938)
		(size 0.508)
		(drill 0.254)
		(layers "F.Cu" "B.Cu")
		(net "PVDDQ_ABC")
	)
	(via
		(at 254.49911 -54.59984)
		(size 0.508)
		(drill 0.254)
		(layers "F.Cu" "B.Cu")
		(net "PVDDQ_ABC")
	)
	(via
		(at 275.4503 -16.718788)
		(size 0.4572)
		(drill 0.2032)
		(layers "F.Cu" "B.Cu")
		(net "PVDDQ_ABC")
	)
	(via
		(at 277.149814 -7.113778)
		(size 0.508)
		(drill 0.254)
		(layers "F.Cu" "B.Cu")
		(net "PVDDQ_ABC")
	)
	(via
		(at 332.67904 -7.795514)
		(size 0.508)
		(drill 0.254)
		(layers "F.Cu" "B.Cu")
		(net "PVDDQ_ABC")
	)
	(via
		(at 254.199898 1.152144)
		(size 0.508)
		(drill 0.254)
		(layers "F.Cu" "B.Cu")
		(net "PVDDQ_ABC")
	)
	(via
		(at 266.949936 -4.328668)
		(size 0.508)
		(drill 0.254)
		(layers "F.Cu" "B.Cu")
		(net "PVDDQ_ABC")
	)
	(via
		(at 273.635216 -26.8732)
		(size 0.508)
		(drill 0.254)
		(layers "F.Cu" "B.Cu")
		(net "PVDDQ_ABC")
	)
	(via
		(at 337.2104 -1.1938)
		(size 0.508)
		(drill 0.254)
		(layers "F.Cu" "B.Cu")
		(net "PVDDQ_ABC")
	)
	(via
		(at 336.9056 4.2926)
		(size 0.508)
		(drill 0.254)
		(layers "F.Cu" "B.Cu")
		(net "PVDDQ_ABC")
	)
	(via
		(at 244.849904 -18.734278)
		(size 0.508)
		(drill 0.254)
		(layers "F.Cu" "B.Cu")
		(net "PVDDQ_ABC")
	)
	(via
		(at 266.95019 -7.117588)
		(size 0.4572)
		(drill 0.2032)
		(layers "F.Cu" "B.Cu")
		(net "PVDDQ_ABC")
	)
	(via
		(at 273.750278 -7.117588)
		(size 0.4572)
		(drill 0.2032)
		(layers "F.Cu" "B.Cu")
		(net "PVDDQ_ABC")
	)
	(via
		(at 331.9018 4.2672)
		(size 0.508)
		(drill 0.254)
		(layers "F.Cu" "B.Cu")
		(net "PVDDQ_ABC")
	)
	(via
		(at 260.50875 -59.057286)
		(size 0.508)
		(drill 0.254)
		(layers "F.Cu" "B.Cu")
		(net "PVDDQ_ABC")
	)
	(via
		(at 331.236066 -2.554732)
		(size 0.508)
		(drill 0.254)
		(layers "F.Cu" "B.Cu")
		(net "PVDDQ_ABC")
	)
	(via
		(at 272.899886 -18.730468)
		(size 0.508)
		(drill 0.254)
		(layers "F.Cu" "B.Cu")
		(net "PVDDQ_ABC")
	)
	(via
		(at 256.057146 -18.663666)
		(size 0.508)
		(drill 0.254)
		(layers "F.Cu" "B.Cu")
		(net "PVDDQ_ABC")
	)
	(via
		(at 255.89992 -4.321556)
		(size 0.508)
		(drill 0.254)
		(layers "F.Cu" "B.Cu")
		(net "PVDDQ_ABC")
	)
	(via
		(at 271.199864 -18.730468)
		(size 0.508)
		(drill 0.254)
		(layers "F.Cu" "B.Cu")
		(net "PVDDQ_ABC")
	)
	(via
		(at 257.07467 -52.12334)
		(size 0.508)
		(drill 0.254)
		(layers "F.Cu" "B.Cu")
		(net "PVDDQ_ABC")
	)
	(via
		(at 255.92913 -49.150778)
		(size 0.508)
		(drill 0.254)
		(layers "F.Cu" "B.Cu")
		(net "PVDDQ_ABC")
	)
	(via
		(at 264.796524 -49.540414)
		(size 0.508)
		(drill 0.254)
		(layers "F.Cu" "B.Cu")
		(net "PVDDQ_ABC")
	)
	(via
		(at 273.26971 -67.250564)
		(size 0.5588)
		(drill 0.3048)
		(layers "F.Cu" "B.Cu")
		(net "PVDDQ_ABC")
	)
	(via
		(at 262.22579 -51.132486)
		(size 0.508)
		(drill 0.254)
		(layers "F.Cu" "B.Cu")
		(net "PVDDQ_ABC")
	)
	(via
		(at 255.89992 2.485644)
		(size 0.508)
		(drill 0.254)
		(layers "F.Cu" "B.Cu")
		(net "PVDDQ_ABC")
	)
	(via
		(at 244.849904 -22.197568)
		(size 0.508)
		(drill 0.254)
		(layers "F.Cu" "B.Cu")
		(net "PVDDQ_ABC")
	)
	(via
		(at 245.699788 -13.933678)
		(size 0.508)
		(drill 0.254)
		(layers "F.Cu" "B.Cu")
		(net "PVDDQ_ABC")
	)
	(via
		(at 243.999766 -7.115556)
		(size 0.508)
		(drill 0.254)
		(layers "F.Cu" "B.Cu")
		(net "PVDDQ_ABC")
	)
	(via
		(at 267.767308 -67.284346)
		(size 0.5588)
		(drill 0.3048)
		(layers "F.Cu" "B.Cu")
		(net "PVDDQ_ABC")
	)
	(via
		(at 185.293 -5.969)
		(size 0.508)
		(drill 0.254)
		(layers "F.Cu" "B.Cu")
		(net "PVDDQ_ABC")
	)
	(via
		(at 331.216 -3.8608)
		(size 0.508)
		(drill 0.254)
		(layers "F.Cu" "B.Cu")
		(net "PVDDQ_ABC")
	)
	(via
		(at 335.910682 -3.259836)
		(size 0.508)
		(drill 0.254)
		(layers "F.Cu" "B.Cu")
		(net "PVDDQ_ABC")
	)
	(via
		(at 337.5152 3.2258)
		(size 0.508)
		(drill 0.254)
		(layers "F.Cu" "B.Cu")
		(net "PVDDQ_ABC")
	)
	(via
		(at 331.9018 -0.6858)
		(size 0.508)
		(drill 0.254)
		(layers "F.Cu" "B.Cu")
		(net "PVDDQ_ABC")
	)
	(via
		(at 255.35763 -52.12334)
		(size 0.508)
		(drill 0.254)
		(layers "F.Cu" "B.Cu")
		(net "PVDDQ_ABC")
	)
	(via
		(at 244.849904 0.468122)
		(size 0.508)
		(drill 0.254)
		(layers "F.Cu" "B.Cu")
		(net "PVDDQ_ABC")
	)
	(via
		(at 248.249948 -16.716756)
		(size 0.508)
		(drill 0.254)
		(layers "F.Cu" "B.Cu")
		(net "PVDDQ_ABC")
	)
	(via
		(at 275.4503 -7.136892)
		(size 0.4572)
		(drill 0.2032)
		(layers "F.Cu" "B.Cu")
		(net "PVDDQ_ABC")
	)
	(via
		(at 330.524866 -2.554732)
		(size 0.508)
		(drill 0.254)
		(layers "F.Cu" "B.Cu")
		(net "PVDDQ_ABC")
	)
	(via
		(at 256.087118 -9.129268)
		(size 0.508)
		(drill 0.254)
		(layers "F.Cu" "B.Cu")
		(net "PVDDQ_ABC")
	)
	(via
		(at 269.500096 -13.933678)
		(size 0.508)
		(drill 0.254)
		(layers "F.Cu" "B.Cu")
		(net "PVDDQ_ABC")
	)
	(via
		(at 331.216 -3.20294)
		(size 0.508)
		(drill 0.254)
		(layers "F.Cu" "B.Cu")
		(net "PVDDQ_ABC")
	)
	(via
		(at 264.287508 -67.284346)
		(size 0.508)
		(drill 0.254)
		(layers "F.Cu" "B.Cu")
		(net "PVDDQ_ABC")
	)
	(via
		(at 248.249948 -4.332478)
		(size 0.508)
		(drill 0.254)
		(layers "F.Cu" "B.Cu")
		(net "PVDDQ_ABC")
	)
	(via
		(at 266.518136 -57.57164)
		(size 0.508)
		(drill 0.254)
		(layers "F.Cu" "B.Cu")
		(net "PVDDQ_ABC")
	)
	(via
		(at 246.549926 -9.133078)
		(size 0.508)
		(drill 0.254)
		(layers "F.Cu" "B.Cu")
		(net "PVDDQ_ABC")
	)
	(via
		(at 266.700508 -67.284346)
		(size 0.508)
		(drill 0.254)
		(layers "F.Cu" "B.Cu")
		(net "PVDDQ_ABC")
	)
	(via
		(at 335.917032 -3.996436)
		(size 0.508)
		(drill 0.254)
		(layers "F.Cu" "B.Cu")
		(net "PVDDQ_ABC")
	)
	(via
		(at 266.95019 -16.718788)
		(size 0.4572)
		(drill 0.2032)
		(layers "F.Cu" "B.Cu")
		(net "PVDDQ_ABC")
	)
	(via
		(at 334.011016 -0.652018)
		(size 0.508)
		(drill 0.254)
		(layers "F.Cu" "B.Cu")
		(net "PVDDQ_ABC")
	)
	(via
		(at 275.4503 -13.933678)
		(size 0.508)
		(drill 0.254)
		(layers "F.Cu" "B.Cu")
		(net "PVDDQ_ABC")
	)
	(via
		(at 245.699788 -4.332478)
		(size 0.508)
		(drill 0.254)
		(layers "F.Cu" "B.Cu")
		(net "PVDDQ_ABC")
	)
	(via
		(at 323.1134 -35.967162)
		(size 0.508)
		(drill 0.254)
		(layers "F.Cu" "B.Cu")
		(net "PVDDQ_ABC")
	)
	(via
		(at 332.2066 -1.2192)
		(size 0.508)
		(drill 0.254)
		(layers "F.Cu" "B.Cu")
		(net "PVDDQ_ABC")
	)
	(via
		(at 331.9272 -3.20294)
		(size 0.508)
		(drill 0.254)
		(layers "F.Cu" "B.Cu")
		(net "PVDDQ_ABC")
	)
	(via
		(at 336.818732 -11.164824)
		(size 0.508)
		(drill 0.254)
		(layers "F.Cu" "B.Cu")
		(net "PVDDQ_ABC")
	)
	(via
		(at 255.35763 -59.057286)
		(size 0.508)
		(drill 0.254)
		(layers "F.Cu" "B.Cu")
		(net "PVDDQ_ABC")
	)
	(via
		(at 249.099832 1.152144)
		(size 0.508)
		(drill 0.254)
		(layers "F.Cu" "B.Cu")
		(net "PVDDQ_ABC")
	)
	(via
		(at 255.84912 -2.314956)
		(size 0.508)
		(drill 0.254)
		(layers "F.Cu" "B.Cu")
		(net "PVDDQ_ABC")
	)
	(via
		(at 337.32343 -4.021074)
		(size 0.508)
		(drill 0.254)
		(layers "F.Cu" "B.Cu")
		(net "PVDDQ_ABC")
	)
	(via
		(at 257.07467 -59.057286)
		(size 0.508)
		(drill 0.254)
		(layers "F.Cu" "B.Cu")
		(net "PVDDQ_ABC")
	)
	(via
		(at 336.1944 -0.6604)
		(size 0.508)
		(drill 0.254)
		(layers "F.Cu" "B.Cu")
		(net "PVDDQ_ABC")
	)
	(via
		(at 277.149814 -23.534878)
		(size 0.508)
		(drill 0.254)
		(layers "F.Cu" "B.Cu")
		(net "PVDDQ_ABC")
	)
	(via
		(at 249.099832 -11.916156)
		(size 0.508)
		(drill 0.254)
		(layers "F.Cu" "B.Cu")
		(net "PVDDQ_ABC")
	)
	(via
		(at 186.563 1.4478)
		(size 0.508)
		(drill 0.254)
		(layers "F.Cu" "B.Cu")
		(net "PVDDQ_ABC")
	)
	(via
		(at 336.634328 -2.494788)
		(size 0.508)
		(drill 0.254)
		(layers "F.Cu" "B.Cu")
		(net "PVDDQ_ABC")
	)
	(via
		(at 251.649992 -22.197568)
		(size 0.508)
		(drill 0.254)
		(layers "F.Cu" "B.Cu")
		(net "PVDDQ_ABC")
	)
	(via
		(at 248.249948 1.805432)
		(size 0.508)
		(drill 0.254)
		(layers "F.Cu" "B.Cu")
		(net "PVDDQ_ABC")
	)
	(via
		(at 336.1436 -11.135106)
		(size 0.508)
		(drill 0.254)
		(layers "F.Cu" "B.Cu")
		(net "PVDDQ_ABC")
	)
	(via
		(at 255.89992 0.471932)
		(size 0.508)
		(drill 0.254)
		(layers "F.Cu" "B.Cu")
		(net "PVDDQ_ABC")
	)
	(via
		(at 266.949682 1.805432)
		(size 0.508)
		(drill 0.254)
		(layers "F.Cu" "B.Cu")
		(net "PVDDQ_ABC")
	)
	(via
		(at 331.9272 -3.8608)
		(size 0.508)
		(drill 0.254)
		(layers "F.Cu" "B.Cu")
		(net "PVDDQ_ABC")
	)
	(via
		(at 253.640844 -62.029086)
		(size 0.508)
		(drill 0.254)
		(layers "F.Cu" "B.Cu")
		(net "PVDDQ_ABC")
	)
	(via
		(at 255.89992 -16.696944)
		(size 0.508)
		(drill 0.254)
		(layers "F.Cu" "B.Cu")
		(net "PVDDQ_ABC")
	)
	(via
		(at 251.923804 -59.057286)
		(size 0.508)
		(drill 0.254)
		(layers "F.Cu" "B.Cu")
		(net "PVDDQ_ABC")
	)
	(via
		(at 273.750278 -4.332478)
		(size 0.508)
		(drill 0.254)
		(layers "F.Cu" "B.Cu")
		(net "PVDDQ_ABC")
	)
	(via
		(at 336.647282 -3.209036)
		(size 0.508)
		(drill 0.254)
		(layers "F.Cu" "B.Cu")
		(net "PVDDQ_ABC")
	)
	(via
		(at 330.4794 -0.6858)
		(size 0.508)
		(drill 0.254)
		(layers "F.Cu" "B.Cu")
		(net "PVDDQ_ABC")
	)
	(via
		(at 269.499842 2.485644)
		(size 0.508)
		(drill 0.254)
		(layers "F.Cu" "B.Cu")
		(net "PVDDQ_ABC")
	)
	(via
		(at 333.3242 4.2672)
		(size 0.508)
		(drill 0.254)
		(layers "F.Cu" "B.Cu")
		(net "PVDDQ_ABC")
	)
	(via
		(at 251.649992 -9.133078)
		(size 0.508)
		(drill 0.254)
		(layers "F.Cu" "B.Cu")
		(net "PVDDQ_ABC")
	)
	(via
		(at 271.199864 2.514854)
		(size 0.508)
		(drill 0.254)
		(layers "F.Cu" "B.Cu")
		(net "PVDDQ_ABC")
	)
	(via
		(at 277.149814 -18.730468)
		(size 0.508)
		(drill 0.254)
		(layers "F.Cu" "B.Cu")
		(net "PVDDQ_ABC")
	)
	(segment
		(start 271.199864 -7.113778)
		(end 271.199864 -5.621782)
		(width 0.4064)
		(layer "B.Cu")
		(net "PVDDQ_ABC")
	)
	(segment
		(start 274.600416 -20.224242)
		(end 274.600416 -18.730976)
		(width 0.508)
		(layer "B.Cu")
		(net "PVDDQ_ABC")
	)
	(segment
		(start 271.200372 -15.222982)
		(end 271.200372 -13.930376)
		(width 0.4064)
		(layer "B.Cu")
		(net "PVDDQ_ABC")
	)
	(segment
		(start 246.549926 -11.916156)
		(end 246.549926 -10.623042)
		(width 0.4064)
		(layer "B.Cu")
		(net "PVDDQ_ABC")
	)
	(segment
		(start 243.999766 -5.62229)
		(end 243.999766 -7.115556)
		(width 0.4064)
		(layer "B.Cu")
		(net "PVDDQ_ABC")
	)
	(segment
		(start 250.800362 -15.222982)
		(end 250.799854 -15.222982)
		(width 0.4064)
		(layer "B.Cu")
		(net "PVDDQ_ABC")
	)
	(segment
		(start 266.949936 -15.222982)
		(end 266.949936 -13.929868)
		(width 0.4064)
		(layer "B.Cu")
		(net "PVDDQ_ABC")
	)
	(segment
		(start 277.149814 -1.021842)
		(end 277.149814 0.468122)
		(width 0.4064)
		(layer "B.Cu")
		(net "PVDDQ_ABC")
	)
	(segment
		(start 277.149814 -1.021842)
		(end 277.150322 -1.021842)
		(width 0.4064)
		(layer "B.Cu")
		(net "PVDDQ_ABC")
	)
	(segment
		(start 267.365988 -13.513816)
		(end 269.080234 -13.513816)
		(width 0.127)
		(layer "B.Cu")
		(net "PVDDQ_ABC")
	)
	(segment
		(start 372.869968 -51.34229)
		(end 372.869968 -51.1302)
		(width 0.254)
		(layer "B.Cu")
		(net "PVDDQ_ABC")
	)
	(segment
		(start 268.649958 -2.313178)
		(end 268.649958 -1.021842)
		(width 0.4064)
		(layer "B.Cu")
		(net "PVDDQ_ABC")
	)
	(segment
		(start 255.89992 -16.696944)
		(end 255.89992 -15.222982)
		(width 0.4064)
		(layer "B.Cu")
		(net "PVDDQ_ABC")
	)
	(segment
		(start 255.900428 -24.824182)
		(end 255.89992 -24.824182)
		(width 0.4064)
		(layer "B.Cu")
		(net "PVDDQ_ABC")
	)
	(segment
		(start 271.200372 -16.71447)
		(end 271.200372 -15.222982)
		(width 0.4064)
		(layer "B.Cu")
		(net "PVDDQ_ABC")
	)
	(segment
		(start 267.081 3.048)
		(end 267.081 3.81)
		(width 0.508)
		(layer "B.Cu")
		(net "PVDDQ_ABC")
	)
	(segment
		(start 274.066 3.81)
		(end 274.066 2.8575)
		(width 0.508)
		(layer "B.Cu")
		(net "PVDDQ_ABC")
	)
	(segment
		(start 248.249948 -5.62229)
		(end 248.249948 -7.115556)
		(width 0.4064)
		(layer "B.Cu")
		(net "PVDDQ_ABC")
	)
	(segment
		(start 246.549926 -1.021842)
		(end 246.550434 -1.021842)
		(width 0.4064)
		(layer "B.Cu")
		(net "PVDDQ_ABC")
	)
	(segment
		(start 266.949682 2.916682)
		(end 267.081 3.048)
		(width 0.508)
		(layer "B.Cu")
		(net "PVDDQ_ABC")
	)
	(segment
		(start 275.449792 -5.621782)
		(end 275.4503 -5.621782)
		(width 0.4064)
		(layer "B.Cu")
		(net "PVDDQ_ABC")
	)
	(segment
		(start 273.74977 -5.621782)
		(end 273.74977 -4.332986)
		(width 0.4064)
		(layer "B.Cu")
		(net "PVDDQ_ABC")
	)
	(segment
		(start 244.000274 -22.851364)
		(end 244.000274 -24.824182)
		(width 0.4064)
		(layer "B.Cu")
		(net "PVDDQ_ABC")
	)
	(segment
		(start 271.199864 -10.623042)
		(end 271.200372 -10.623042)
		(width 0.4064)
		(layer "B.Cu")
		(net "PVDDQ_ABC")
	)
	(segment
		(start 277.149814 -9.133078)
		(end 277.18004 -9.163304)
		(width 0.5588)
		(layer "B.Cu")
		(net "PVDDQ_ABC")
	)
	(segment
		(start 266.099798 -10.623042)
		(end 266.100306 -10.623042)
		(width 0.4064)
		(layer "B.Cu")
		(net "PVDDQ_ABC")
	)
	(segment
		(start 253.350522 -24.824182)
		(end 253.350014 -24.824182)
		(width 0.4064)
		(layer "B.Cu")
		(net "PVDDQ_ABC")
	)
	(segment
		(start 277.149814 -2.313178)
		(end 277.149814 -1.021842)
		(width 0.4064)
		(layer "B.Cu")
		(net "PVDDQ_ABC")
	)
	(segment
		(start 275.449792 -15.222982)
		(end 275.4503 -15.222982)
		(width 0.4064)
		(layer "B.Cu")
		(net "PVDDQ_ABC")
	)
	(segment
		(start 246.549926 -10.623042)
		(end 246.550434 -10.623042)
		(width 0.4064)
		(layer "B.Cu")
		(net "PVDDQ_ABC")
	)
	(segment
		(start 254.199898 -10.623042)
		(end 254.199898 -11.918188)
		(width 0.4064)
		(layer "B.Cu")
		(net "PVDDQ_ABC")
	)
	(segment
		(start 245.700296 -5.621782)
		(end 245.699788 -5.62229)
		(width 0.4064)
		(layer "B.Cu")
		(net "PVDDQ_ABC")
	)
	(segment
		(start 253.350522 -5.621782)
		(end 253.350014 -5.621782)
		(width 0.4064)
		(layer "B.Cu")
		(net "PVDDQ_ABC")
	)
	(segment
		(start 255.84912 -2.314956)
		(end 255.900428 -2.263648)
		(width 0.4064)
		(layer "B.Cu")
		(net "PVDDQ_ABC")
	)
	(segment
		(start 244.849904 -2.314956)
		(end 244.849904 -1.021842)
		(width 0.4064)
		(layer "B.Cu")
		(net "PVDDQ_ABC")
	)
	(segment
		(start 249.099832 -10.623042)
		(end 249.10034 -10.623042)
		(width 0.4064)
		(layer "B.Cu")
		(net "PVDDQ_ABC")
	)
	(segment
		(start 266.099798 -1.021842)
		(end 266.099798 -2.313178)
		(width 0.4064)
		(layer "B.Cu")
		(net "PVDDQ_ABC")
	)
	(segment
		(start 251.649992 -1.021842)
		(end 251.6505 -1.021842)
		(width 0.4064)
		(layer "B.Cu")
		(net "PVDDQ_ABC")
	)
	(segment
		(start 266.950444 -15.222982)
		(end 266.949936 -15.222982)
		(width 0.4064)
		(layer "B.Cu")
		(net "PVDDQ_ABC")
	)
	(segment
		(start 251.649992 -10.623042)
		(end 251.649992 -11.918188)
		(width 0.4064)
		(layer "B.Cu")
		(net "PVDDQ_ABC")
	)
	(segment
		(start 272.899886 -10.623042)
		(end 272.900394 -10.623042)
		(width 0.4064)
		(layer "B.Cu")
		(net "PVDDQ_ABC")
	)
	(segment
		(start 255.89992 -9.316466)
		(end 256.087118 -9.129268)
		(width 0.4064)
		(layer "B.Cu")
		(net "PVDDQ_ABC")
	)
	(segment
		(start 248.250456 -15.222982)
		(end 248.249948 -15.222474)
		(width 0.4064)
		(layer "B.Cu")
		(net "PVDDQ_ABC")
	)
	(segment
		(start 255.900428 -5.621782)
		(end 255.89992 -5.621782)
		(width 0.4064)
		(layer "B.Cu")
		(net "PVDDQ_ABC")
	)
	(segment
		(start 269.50035 -15.222982)
		(end 269.50035 -13.933932)
		(width 0.4064)
		(layer "B.Cu")
		(net "PVDDQ_ABC")
	)
	(segment
		(start 249.099832 -20.224242)
		(end 249.10034 -20.224242)
		(width 0.4064)
		(layer "B.Cu")
		(net "PVDDQ_ABC")
	)
	(segment
		(start 268.649958 -9.158732)
		(end 268.649958 -10.623042)
		(width 0.4064)
		(layer "B.Cu")
		(net "PVDDQ_ABC")
	)
	(segment
		(start 258.450334 -5.621782)
		(end 258.449826 -5.621782)
		(width 0.4064)
		(layer "B.Cu")
		(net "PVDDQ_ABC")
	)
	(segment
		(start 249.099832 -18.734278)
		(end 249.099832 -20.224242)
		(width 0.4064)
		(layer "B.Cu")
		(net "PVDDQ_ABC")
	)
	(segment
		(start 273.74977 -4.332986)
		(end 273.750278 -4.332478)
		(width 0.4064)
		(layer "B.Cu")
		(net "PVDDQ_ABC")
	)
	(segment
		(start 269.919958 -13.513816)
		(end 270.783812 -13.513816)
		(width 0.127)
		(layer "B.Cu")
		(net "PVDDQ_ABC")
	)
	(segment
		(start 255.89992 -5.621782)
		(end 255.89992 -4.321556)
		(width 0.4064)
		(layer "B.Cu")
		(net "PVDDQ_ABC")
	)
	(segment
		(start 275.449792 -5.621782)
		(end 275.449792 -4.332986)
		(width 0.4064)
		(layer "B.Cu")
		(net "PVDDQ_ABC")
	)
	(segment
		(start 266.95019 -16.718788)
		(end 266.949936 -16.718534)
		(width 0.4064)
		(layer "B.Cu")
		(net "PVDDQ_ABC")
	)
	(segment
		(start 277.18004 -9.163304)
		(end 277.18004 -10.592816)
		(width 0.4064)
		(layer "B.Cu")
		(net "PVDDQ_ABC")
	)
	(segment
		(start 244.849904 -20.224242)
		(end 244.849904 -22.197568)
		(width 0.4064)
		(layer "B.Cu")
		(net "PVDDQ_ABC")
	)
	(segment
		(start 244.849904 -18.734278)
		(end 244.849904 -20.224242)
		(width 0.4064)
		(layer "B.Cu")
		(net "PVDDQ_ABC")
	)
	(segment
		(start 250.800362 -15.222982)
		(end 250.799854 -15.222474)
		(width 0.4064)
		(layer "B.Cu")
		(net "PVDDQ_ABC")
	)
	(segment
		(start 275.449792 -7.136384)
		(end 275.4503 -7.136892)
		(width 0.4064)
		(layer "B.Cu")
		(net "PVDDQ_ABC")
	)
	(segment
		(start 271.199864 -5.621782)
		(end 271.200372 -5.621782)
		(width 0.4064)
		(layer "B.Cu")
		(net "PVDDQ_ABC")
	)
	(segment
		(start 254.199898 -1.021842)
		(end 254.199898 1.152144)
		(width 0.4064)
		(layer "B.Cu")
		(net "PVDDQ_ABC")
	)
	(segment
		(start 250.799854 -15.222474)
		(end 250.799854 -13.933678)
		(width 0.4064)
		(layer "B.Cu")
		(net "PVDDQ_ABC")
	)
	(segment
		(start 249.099832 -1.021842)
		(end 249.099832 1.152144)
		(width 0.4064)
		(layer "B.Cu")
		(net "PVDDQ_ABC")
	)
	(segment
		(start 268.649958 -1.021842)
		(end 268.650466 -1.021842)
		(width 0.4064)
		(layer "B.Cu")
		(net "PVDDQ_ABC")
	)
	(segment
		(start 253.350014 -15.222474)
		(end 253.350014 -13.933678)
		(width 0.4064)
		(layer "B.Cu")
		(net "PVDDQ_ABC")
	)
	(segment
		(start 275.5138 -29.337)
		(end 275.5138 -28.6258)
		(width 0.254)
		(layer "B.Cu")
		(net "PVDDQ_ABC")
	)
	(segment
		(start 277.150322 -18.730976)
		(end 277.149814 -18.730468)
		(width 0.508)
		(layer "B.Cu")
		(net "PVDDQ_ABC")
	)
	(segment
		(start 277.149814 -15.222982)
		(end 277.149814 -16.714978)
		(width 0.4064)
		(layer "B.Cu")
		(net "PVDDQ_ABC")
	)
	(segment
		(start 258.450334 -1.021842)
		(end 258.449826 -1.021842)
		(width 0.4064)
		(layer "B.Cu")
		(net "PVDDQ_ABC")
	)
	(segment
		(start 253.350014 -5.621782)
		(end 253.350014 -4.332478)
		(width 0.4064)
		(layer "B.Cu")
		(net "PVDDQ_ABC")
	)
	(segment
		(start 271.199864 -10.623042)
		(end 271.199864 -11.914378)
		(width 0.4064)
		(layer "B.Cu")
		(net "PVDDQ_ABC")
	)
	(segment
		(start 271.199864 -2.313178)
		(end 271.199864 -1.021842)
		(width 0.4064)
		(layer "B.Cu")
		(net "PVDDQ_ABC")
	)
	(segment
		(start 245.699788 -15.222982)
		(end 245.699788 -13.933678)
		(width 0.4064)
		(layer "B.Cu")
		(net "PVDDQ_ABC")
	)
	(segment
		(start 273.74977 -15.222982)
		(end 273.750278 -15.222982)
		(width 0.4064)
		(layer "B.Cu")
		(net "PVDDQ_ABC")
	)
	(segment
		(start 255.90373 -23.514812)
		(end 255.923542 -23.495)
		(width 0.4064)
		(layer "B.Cu")
		(net "PVDDQ_ABC")
	)
	(segment
		(start 254.199898 -1.021842)
		(end 254.200406 -1.021842)
		(width 0.4064)
		(layer "B.Cu")
		(net "PVDDQ_ABC")
	)
	(segment
		(start 251.649992 -20.224242)
		(end 251.649992 -22.197568)
		(width 0.4064)
		(layer "B.Cu")
		(net "PVDDQ_ABC")
	)
	(segment
		(start 245.699788 -15.222982)
		(end 245.700296 -15.222982)
		(width 0.4064)
		(layer "B.Cu")
		(net "PVDDQ_ABC")
	)
	(segment
		(start 273.74977 -5.621782)
		(end 273.74977 -7.11708)
		(width 0.4064)
		(layer "B.Cu")
		(net "PVDDQ_ABC")
	)
	(segment
		(start 272.899886 -1.021842)
		(end 272.900394 -1.021842)
		(width 0.4064)
		(layer "B.Cu")
		(net "PVDDQ_ABC")
	)
	(segment
		(start 246.549926 -2.314956)
		(end 246.549926 -1.021842)
		(width 0.4064)
		(layer "B.Cu")
		(net "PVDDQ_ABC")
	)
	(segment
		(start 266.100306 -1.021842)
		(end 266.099798 -1.021842)
		(width 0.4064)
		(layer "B.Cu")
		(net "PVDDQ_ABC")
	)
	(segment
		(start 273.74977 -15.222982)
		(end 273.74977 -13.934186)
		(width 0.4064)
		(layer "B.Cu")
		(net "PVDDQ_ABC")
	)
	(segment
		(start 255.89992 -15.222982)
		(end 255.900428 -15.222982)
		(width 0.4064)
		(layer "B.Cu")
		(net "PVDDQ_ABC")
	)
	(segment
		(start 255.900428 -10.623042)
		(end 255.89992 -10.623042)
		(width 0.4064)
		(layer "B.Cu")
		(net "PVDDQ_ABC")
	)
	(segment
		(start 245.699788 -5.621782)
		(end 245.699788 -4.332478)
		(width 0.4064)
		(layer "B.Cu")
		(net "PVDDQ_ABC")
	)
	(segment
		(start 251.649992 -18.734278)
		(end 251.649992 -20.224242)
		(width 0.4064)
		(layer "B.Cu")
		(net "PVDDQ_ABC")
	)
	(segment
		(start 254.199898 -9.133078)
		(end 254.199898 -10.623042)
		(width 0.4064)
		(layer "B.Cu")
		(net "PVDDQ_ABC")
	)
	(segment
		(start 272.899886 -10.623042)
		(end 272.899886 -9.129268)
		(width 0.4064)
		(layer "B.Cu")
		(net "PVDDQ_ABC")
	)
	(segment
		(start 248.250456 -24.824182)
		(end 248.249948 -24.824182)
		(width 0.4064)
		(layer "B.Cu")
		(net "PVDDQ_ABC")
	)
	(segment
		(start 266.949936 -13.929868)
		(end 266.949936 -13.506704)
		(width 0.508)
		(layer "B.Cu")
		(net "PVDDQ_ABC")
	)
	(segment
		(start 251.649992 -20.224242)
		(end 251.6505 -20.224242)
		(width 0.4064)
		(layer "B.Cu")
		(net "PVDDQ_ABC")
	)
	(segment
		(start 266.100306 -20.224242)
		(end 266.100306 -18.730976)
		(width 0.508)
		(layer "B.Cu")
		(net "PVDDQ_ABC")
	)
	(segment
		(start 271.199864 -5.621782)
		(end 271.199864 -4.328668)
		(width 0.4064)
		(layer "B.Cu")
		(net "PVDDQ_ABC")
	)
	(segment
		(start 269.559532 -12.954)
		(end 269.500096 -13.013436)
		(width 0.508)
		(layer "B.Cu")
		(net "PVDDQ_ABC")
	)
	(segment
		(start 255.89992 -23.546816)
		(end 255.90373 -23.543006)
		(width 0.4064)
		(layer "B.Cu")
		(net "PVDDQ_ABC")
	)
	(segment
		(start 266.949936 -7.117334)
		(end 266.949936 -5.621782)
		(width 0.4064)
		(layer "B.Cu")
		(net "PVDDQ_ABC")
	)
	(segment
		(start 255.90373 -23.543006)
		(end 255.90373 -23.514812)
		(width 0.4064)
		(layer "B.Cu")
		(net "PVDDQ_ABC")
	)
	(segment
		(start 277.149814 -15.222982)
		(end 277.150322 -15.222982)
		(width 0.4064)
		(layer "B.Cu")
		(net "PVDDQ_ABC")
	)
	(segment
		(start 372.565168 -50.8254)
		(end 368.083084 -50.8254)
		(width 0.254)
		(layer "B.Cu")
		(net "PVDDQ_ABC")
	)
	(segment
		(start 243.999766 -5.621782)
		(end 243.999766 -4.332478)
		(width 0.4064)
		(layer "B.Cu")
		(net "PVDDQ_ABC")
	)
	(segment
		(start 277.149814 -7.113778)
		(end 277.149814 -5.621782)
		(width 0.4064)
		(layer "B.Cu")
		(net "PVDDQ_ABC")
	)
	(segment
		(start 270.637 3.077718)
		(end 271.199864 2.514854)
		(width 0.508)
		(layer "B.Cu")
		(net "PVDDQ_ABC")
	)
	(segment
		(start 245.700296 -5.621782)
		(end 245.699788 -5.621782)
		(width 0.4064)
		(layer "B.Cu")
		(net "PVDDQ_ABC")
	)
	(segment
		(start 269.50035 -4.332732)
		(end 269.500096 -4.332478)
		(width 0.4064)
		(layer "B.Cu")
		(net "PVDDQ_ABC")
	)
	(segment
		(start 243.999766 -16.716756)
		(end 243.999766 -15.222982)
		(width 0.4064)
		(layer "B.Cu")
		(net "PVDDQ_ABC")
	)
	(segment
		(start 250.799854 -24.824182)
		(end 250.800362 -24.824182)
		(width 0.4064)
		(layer "B.Cu")
		(net "PVDDQ_ABC")
	)
	(segment
		(start 255.900428 -20.224242)
		(end 255.89992 -20.224242)
		(width 0.4064)
		(layer "B.Cu")
		(net "PVDDQ_ABC")
	)
	(segment
		(start 269.50035 -5.621782)
		(end 269.50035 -4.332732)
		(width 0.4064)
		(layer "B.Cu")
		(net "PVDDQ_ABC")
	)
	(segment
		(start 256.089404 -13.929868)
		(end 255.89992 -14.119352)
		(width 0.4064)
		(layer "B.Cu")
		(net "PVDDQ_ABC")
	)
	(segment
		(start 271.199864 -1.021842)
		(end 271.200372 -1.021842)
		(width 0.4064)
		(layer "B.Cu")
		(net "PVDDQ_ABC")
	)
	(segment
		(start 271.199864 -1.021842)
		(end 271.199864 1.152144)
		(width 0.4064)
		(layer "B.Cu")
		(net "PVDDQ_ABC")
	)
	(segment
		(start 277.149814 -5.621782)
		(end 277.149814 -4.332986)
		(width 0.4064)
		(layer "B.Cu")
		(net "PVDDQ_ABC")
	)
	(segment
		(start 269.50035 -16.718534)
		(end 269.50035 -15.222982)
		(width 0.4064)
		(layer "B.Cu")
		(net "PVDDQ_ABC")
	)
	(segment
		(start 244.000274 -5.621782)
		(end 243.999766 -5.621782)
		(width 0.4064)
		(layer "B.Cu")
		(net "PVDDQ_ABC")
	)
	(segment
		(start 251.649992 -9.133078)
		(end 251.649992 -10.623042)
		(width 0.4064)
		(layer "B.Cu")
		(net "PVDDQ_ABC")
	)
	(segment
		(start 274.599908 -10.623042)
		(end 274.600416 -10.623042)
		(width 0.4064)
		(layer "B.Cu")
		(net "PVDDQ_ABC")
	)
	(segment
		(start 246.549926 -18.734278)
		(end 246.549926 -20.224242)
		(width 0.4064)
		(layer "B.Cu")
		(net "PVDDQ_ABC")
	)
	(segment
		(start 269.080234 -13.513816)
		(end 269.500096 -13.933678)
		(width 0.127)
		(layer "B.Cu")
		(net "PVDDQ_ABC")
	)
	(segment
		(start 266.949936 -16.718534)
		(end 266.949936 -15.222982)
		(width 0.4064)
		(layer "B.Cu")
		(net "PVDDQ_ABC")
	)
	(segment
		(start 258.449826 -2.314956)
		(end 258.449826 -1.021842)
		(width 0.4064)
		(layer "B.Cu")
		(net "PVDDQ_ABC")
	)
	(segment
		(start 272.899886 -2.313178)
		(end 272.899886 -1.021842)
		(width 0.4064)
		(layer "B.Cu")
		(net "PVDDQ_ABC")
	)
	(segment
		(start 269.50035 -7.117334)
		(end 269.50035 -5.621782)
		(width 0.4064)
		(layer "B.Cu")
		(net "PVDDQ_ABC")
	)
	(segment
		(start 246.549926 -10.623042)
		(end 246.549926 -9.133078)
		(width 0.4064)
		(layer "B.Cu")
		(net "PVDDQ_ABC")
	)
	(segment
		(start 271.200372 -13.930376)
		(end 271.199864 -13.929868)
		(width 0.3302)
		(layer "B.Cu")
		(net "PVDDQ_ABC")
	)
	(segment
		(start 255.89992 -14.119352)
		(end 255.89992 -15.222982)
		(width 0.4064)
		(layer "B.Cu")
		(net "PVDDQ_ABC")
	)
	(segment
		(start 277.149814 -13.934186)
		(end 277.149814 -15.222982)
		(width 0.4064)
		(layer "B.Cu")
		(net "PVDDQ_ABC")
	)
	(segment
		(start 250.799854 -22.850856)
		(end 250.799854 -24.824182)
		(width 0.4064)
		(layer "B.Cu")
		(net "PVDDQ_ABC")
	)
	(segment
		(start 253.350014 -24.824182)
		(end 253.350014 -23.560278)
		(width 0.4064)
		(layer "B.Cu")
		(net "PVDDQ_ABC")
	)
	(segment
		(start 253.350522 -15.222982)
		(end 253.350014 -15.222474)
		(width 0.4064)
		(layer "B.Cu")
		(net "PVDDQ_ABC")
	)
	(segment
		(start 255.89992 -24.824182)
		(end 255.89992 -23.546816)
		(width 0.4064)
		(layer "B.Cu")
		(net "PVDDQ_ABC")
	)
	(segment
		(start 249.099832 -2.314956)
		(end 249.099832 -1.021842)
		(width 0.4064)
		(layer "B.Cu")
		(net "PVDDQ_ABC")
	)
	(segment
		(start 270.783812 -13.513816)
		(end 271.199864 -13.929868)
		(width 0.127)
		(layer "B.Cu")
		(net "PVDDQ_ABC")
	)
	(segment
		(start 268.649958 -1.021842)
		(end 268.649958 0.442468)
		(width 0.4064)
		(layer "B.Cu")
		(net "PVDDQ_ABC")
	)
	(segment
		(start 266.949936 -13.929868)
		(end 267.365988 -13.513816)
		(width 0.127)
		(layer "B.Cu")
		(net "PVDDQ_ABC")
	)
	(segment
		(start 254.199898 -10.623042)
		(end 254.200406 -10.623042)
		(width 0.4064)
		(layer "B.Cu")
		(net "PVDDQ_ABC")
	)
	(segment
		(start 271.199864 -16.714978)
		(end 271.200372 -16.71447)
		(width 0.3302)
		(layer "B.Cu")
		(net "PVDDQ_ABC")
	)
	(segment
		(start 243.999766 -15.222982)
		(end 243.999766 -13.933678)
		(width 0.4064)
		(layer "B.Cu")
		(net "PVDDQ_ABC")
	)
	(segment
		(start 272.899886 -11.914378)
		(end 272.899886 -10.623042)
		(width 0.4064)
		(layer "B.Cu")
		(net "PVDDQ_ABC")
	)
	(segment
		(start 270.637 3.81)
		(end 270.637 3.077718)
		(width 0.508)
		(layer "B.Cu")
		(net "PVDDQ_ABC")
	)
	(segment
		(start 183.387746 -6.604)
		(end 184.658 -6.604)
		(width 0.254)
		(layer "B.Cu")
		(net "PVDDQ_ABC")
	)
	(segment
		(start 249.099832 -10.623042)
		(end 249.099832 -11.916156)
		(width 0.4064)
		(layer "B.Cu")
		(net "PVDDQ_ABC")
	)
	(segment
		(start 271.199864 -20.224242)
		(end 271.199864 -18.730468)
		(width 0.508)
		(layer "B.Cu")
		(net "PVDDQ_ABC")
	)
	(segment
		(start 248.249948 -5.621782)
		(end 248.249948 -4.332478)
		(width 0.4064)
		(layer "B.Cu")
		(net "PVDDQ_ABC")
	)
	(segment
		(start 183.007 -5.59181)
		(end 183.007 -6.223254)
		(width 0.254)
		(layer "B.Cu")
		(net "PVDDQ_ABC")
	)
	(segment
		(start 266.099798 -1.021842)
		(end 266.099798 1.152144)
		(width 0.4064)
		(layer "B.Cu")
		(net "PVDDQ_ABC")
	)
	(segment
		(start 274.599908 1.152144)
		(end 274.599908 -1.021842)
		(width 0.4064)
		(layer "B.Cu")
		(net "PVDDQ_ABC")
	)
	(segment
		(start 254.199898 -20.224242)
		(end 254.200406 -20.224242)
		(width 0.4064)
		(layer "B.Cu")
		(net "PVDDQ_ABC")
	)
	(segment
		(start 273.74977 -5.621782)
		(end 273.750278 -5.621782)
		(width 0.4064)
		(layer "B.Cu")
		(net "PVDDQ_ABC")
	)
	(segment
		(start 244.849904 -11.916156)
		(end 244.849904 -10.623042)
		(width 0.4064)
		(layer "B.Cu")
		(net "PVDDQ_ABC")
	)
	(segment
		(start 250.799854 -5.62229)
		(end 250.799854 -7.115556)
		(width 0.4064)
		(layer "B.Cu")
		(net "PVDDQ_ABC")
	)
	(segment
		(start 246.549926 -1.021842)
		(end 246.549926 0.442722)
		(width 0.4064)
		(layer "B.Cu")
		(net "PVDDQ_ABC")
	)
	(segment
		(start 251.649992 -1.021842)
		(end 251.649992 0.442722)
		(width 0.4064)
		(layer "B.Cu")
		(net "PVDDQ_ABC")
	)
	(segment
		(start 275.449792 -16.71828)
		(end 275.449792 -15.222982)
		(width 0.4064)
		(layer "B.Cu")
		(net "PVDDQ_ABC")
	)
	(segment
		(start 255.900428 -2.263648)
		(end 255.900428 -1.021842)
		(width 0.4064)
		(layer "B.Cu")
		(net "PVDDQ_ABC")
	)
	(segment
		(start 244.000274 -5.621782)
		(end 243.999766 -5.62229)
		(width 0.4064)
		(layer "B.Cu")
		(net "PVDDQ_ABC")
	)
	(segment
		(start 274.599908 -1.021842)
		(end 274.599908 -2.313178)
		(width 0.4064)
		(layer "B.Cu")
		(net "PVDDQ_ABC")
	)
	(segment
		(start 250.799854 -15.222982)
		(end 250.799854 -16.716756)
		(width 0.4064)
		(layer "B.Cu")
		(net "PVDDQ_ABC")
	)
	(segment
		(start 372.869968 -51.1302)
		(end 372.565168 -50.8254)
		(width 0.254)
		(layer "B.Cu")
		(net "PVDDQ_ABC")
	)
	(segment
		(start 244.849904 -1.021842)
		(end 244.850412 -1.021842)
		(width 0.4064)
		(layer "B.Cu")
		(net "PVDDQ_ABC")
	)
	(segment
		(start 266.949936 -13.506704)
		(end 266.397232 -12.954)
		(width 0.508)
		(layer "B.Cu")
		(net "PVDDQ_ABC")
	)
	(segment
		(start 277.150322 -20.224242)
		(end 277.150322 -18.730976)
		(width 0.508)
		(layer "B.Cu")
		(net "PVDDQ_ABC")
	)
	(segment
		(start 274.599908 -1.021842)
		(end 274.600416 -1.021842)
		(width 0.4064)
		(layer "B.Cu")
		(net "PVDDQ_ABC")
	)
	(segment
		(start 273.74977 -16.71828)
		(end 273.74977 -15.222982)
		(width 0.4064)
		(layer "B.Cu")
		(net "PVDDQ_ABC")
	)
	(segment
		(start 277.149814 -13.929868)
		(end 277.149814 -13.934186)
		(width 0.254)
		(layer "B.Cu")
		(net "PVDDQ_ABC")
	)
	(segment
		(start 245.700296 -22.851364)
		(end 245.700296 -24.824182)
		(width 0.4064)
		(layer "B.Cu")
		(net "PVDDQ_ABC")
	)
	(segment
		(start 275.449792 -4.332986)
		(end 275.4503 -4.332478)
		(width 0.4064)
		(layer "B.Cu")
		(net "PVDDQ_ABC")
	)
	(segment
		(start 266.95019 -7.117588)
		(end 266.949936 -7.117334)
		(width 0.4064)
		(layer "B.Cu")
		(net "PVDDQ_ABC")
	)
	(segment
		(start 268.650466 -20.224242)
		(end 268.650466 -18.730976)
		(width 0.508)
		(layer "B.Cu")
		(net "PVDDQ_ABC")
	)
	(segment
		(start 273.74977 2.54127)
		(end 273.74977 1.805432)
		(width 0.508)
		(layer "B.Cu")
		(net "PVDDQ_ABC")
	)
	(segment
		(start 245.699788 -22.850856)
		(end 245.700296 -22.851364)
		(width 0.4064)
		(layer "B.Cu")
		(net "PVDDQ_ABC")
	)
	(segment
		(start 255.89992 -1.021842)
		(end 255.900428 -1.021842)
		(width 0.4064)
		(layer "B.Cu")
		(net "PVDDQ_ABC")
	)
	(segment
		(start 255.89992 -10.623042)
		(end 255.89992 -9.316466)
		(width 0.4064)
		(layer "B.Cu")
		(net "PVDDQ_ABC")
	)
	(segment
		(start 266.100306 -18.730976)
		(end 266.099798 -18.730468)
		(width 0.508)
		(layer "B.Cu")
		(net "PVDDQ_ABC")
	)
	(segment
		(start 269.50035 -13.933932)
		(end 269.500096 -13.933678)
		(width 0.4064)
		(layer "B.Cu")
		(net "PVDDQ_ABC")
	)
	(segment
		(start 274.599908 -11.914378)
		(end 274.599908 -10.623042)
		(width 0.4064)
		(layer "B.Cu")
		(net "PVDDQ_ABC")
	)
	(segment
		(start 268.649958 -10.623042)
		(end 268.650466 -10.623042)
		(width 0.4064)
		(layer "B.Cu")
		(net "PVDDQ_ABC")
	)
	(segment
		(start 275.449792 -5.621782)
		(end 275.449792 -7.136384)
		(width 0.4064)
		(layer "B.Cu")
		(net "PVDDQ_ABC")
	)
	(segment
		(start 268.649958 -10.623042)
		(end 268.649958 -11.914378)
		(width 0.4064)
		(layer "B.Cu")
		(net "PVDDQ_ABC")
	)
	(segment
		(start 248.250456 -15.222982)
		(end 248.249948 -15.222982)
		(width 0.4064)
		(layer "B.Cu")
		(net "PVDDQ_ABC")
	)
	(segment
		(start 249.099832 -9.133078)
		(end 249.099832 -10.623042)
		(width 0.4064)
		(layer "B.Cu")
		(net "PVDDQ_ABC")
	)
	(segment
		(start 250.800362 -5.621782)
		(end 250.799854 -5.62229)
		(width 0.4064)
		(layer "B.Cu")
		(net "PVDDQ_ABC")
	)
	(segment
		(start 255.89992 -20.224242)
		(end 255.89992 -22.225)
		(width 0.4064)
		(layer "B.Cu")
		(net "PVDDQ_ABC")
	)
	(segment
		(start 254.199898 -2.316988)
		(end 254.199898 -1.021842)
		(width 0.4064)
		(layer "B.Cu")
		(net "PVDDQ_ABC")
	)
	(segment
		(start 368.083084 -50.8254)
		(end 367.368074 -50.11039)
		(width 0.254)
		(layer "B.Cu")
		(net "PVDDQ_ABC")
	)
	(segment
		(start 277.149814 -4.332986)
		(end 277.149814 -4.328668)
		(width 0.254)
		(layer "B.Cu")
		(net "PVDDQ_ABC")
	)
	(segment
		(start 274.599908 -10.623042)
		(end 274.599908 -9.129268)
		(width 0.4064)
		(layer "B.Cu")
		(net "PVDDQ_ABC")
	)
	(segment
		(start 183.007 -6.223254)
		(end 183.387746 -6.604)
		(width 0.254)
		(layer "B.Cu")
		(net "PVDDQ_ABC")
	)
	(segment
		(start 245.699788 -5.62229)
		(end 245.699788 -7.115556)
		(width 0.4064)
		(layer "B.Cu")
		(net "PVDDQ_ABC")
	)
	(segment
		(start 277.18004 -10.592816)
		(end 277.149814 -10.623042)
		(width 0.4064)
		(layer "B.Cu")
		(net "PVDDQ_ABC")
	)
	(segment
		(start 277.149814 -10.623042)
		(end 277.149814 -11.914378)
		(width 0.4064)
		(layer "B.Cu")
		(net "PVDDQ_ABC")
	)
	(segment
		(start 249.099832 -20.224242)
		(end 249.099832 -21.517356)
		(width 0.4064)
		(layer "B.Cu")
		(net "PVDDQ_ABC")
	)
	(segment
		(start 254.199898 -21.488146)
		(end 254.199898 -20.224242)
		(width 0.4064)
		(layer "B.Cu")
		(net "PVDDQ_ABC")
	)
	(segment
		(start 184.658 -6.604)
		(end 185.293 -5.969)
		(width 0.254)
		(layer "B.Cu")
		(net "PVDDQ_ABC")
	)
	(segment
		(start 253.350522 -5.621782)
		(end 253.350014 -5.62229)
		(width 0.4064)
		(layer "B.Cu")
		(net "PVDDQ_ABC")
	)
	(segment
		(start 248.249948 -15.222474)
		(end 248.249948 -13.933678)
		(width 0.4064)
		(layer "B.Cu")
		(net "PVDDQ_ABC")
	)
	(segment
		(start 255.89992 -18.820892)
		(end 255.89992 -20.224242)
		(width 0.4064)
		(layer "B.Cu")
		(net "PVDDQ_ABC")
	)
	(segment
		(start 255.900428 -5.621782)
		(end 255.89992 -5.62229)
		(width 0.4064)
		(layer "B.Cu")
		(net "PVDDQ_ABC")
	)
	(segment
		(start 258.449826 -5.621782)
		(end 258.449826 -4.328668)
		(width 0.4064)
		(layer "B.Cu")
		(net "PVDDQ_ABC")
	)
	(segment
		(start 266.099798 -10.623042)
		(end 266.099798 -11.914378)
		(width 0.4064)
		(layer "B.Cu")
		(net "PVDDQ_ABC")
	)
	(segment
		(start 274.066 2.8575)
		(end 273.74977 2.54127)
		(width 0.508)
		(layer "B.Cu")
		(net "PVDDQ_ABC")
	)
	(segment
		(start 272.899886 -1.021842)
		(end 272.899886 1.152144)
		(width 0.4064)
		(layer "B.Cu")
		(net "PVDDQ_ABC")
	)
	(segment
		(start 275.449792 -15.222982)
		(end 275.449792 -13.934186)
		(width 0.4064)
		(layer "B.Cu")
		(net "PVDDQ_ABC")
	)
	(segment
		(start 277.149814 -5.621782)
		(end 277.150322 -5.621782)
		(width 0.4064)
		(layer "B.Cu")
		(net "PVDDQ_ABC")
	)
	(segment
		(start 266.950444 -5.621782)
		(end 266.949936 -5.621782)
		(width 0.4064)
		(layer "B.Cu")
		(net "PVDDQ_ABC")
	)
	(segment
		(start 243.999766 -15.222982)
		(end 244.000274 -15.222982)
		(width 0.4064)
		(layer "B.Cu")
		(net "PVDDQ_ABC")
	)
	(segment
		(start 248.249948 -15.222982)
		(end 248.249948 -16.716756)
		(width 0.4064)
		(layer "B.Cu")
		(net "PVDDQ_ABC")
	)
	(segment
		(start 255.89992 -5.62229)
		(end 255.89992 -7.115556)
		(width 0.4064)
		(layer "B.Cu")
		(net "PVDDQ_ABC")
	)
	(segment
		(start 251.649992 -2.316988)
		(end 251.649992 -1.021842)
		(width 0.4064)
		(layer "B.Cu")
		(net "PVDDQ_ABC")
	)
	(segment
		(start 271.199864 -9.129268)
		(end 271.199864 -10.623042)
		(width 0.4064)
		(layer "B.Cu")
		(net "PVDDQ_ABC")
	)
	(segment
		(start 256.057146 -18.663666)
		(end 255.89992 -18.820892)
		(width 0.4064)
		(layer "B.Cu")
		(net "PVDDQ_ABC")
	)
	(segment
		(start 271.200372 -20.224242)
		(end 271.199864 -20.224242)
		(width 0.508)
		(layer "B.Cu")
		(net "PVDDQ_ABC")
	)
	(segment
		(start 246.549926 -20.224242)
		(end 246.549926 -22.197568)
		(width 0.4064)
		(layer "B.Cu")
		(net "PVDDQ_ABC")
	)
	(segment
		(start 248.250456 -5.621782)
		(end 248.249948 -5.62229)
		(width 0.4064)
		(layer "B.Cu")
		(net "PVDDQ_ABC")
	)
	(segment
		(start 248.250456 -5.621782)
		(end 248.249948 -5.621782)
		(width 0.4064)
		(layer "B.Cu")
		(net "PVDDQ_ABC")
	)
	(segment
		(start 248.249948 -24.824182)
		(end 248.249948 -23.560278)
		(width 0.4064)
		(layer "B.Cu")
		(net "PVDDQ_ABC")
	)
	(segment
		(start 268.649958 0.442468)
		(end 268.649704 0.442722)
		(width 0.4064)
		(layer "B.Cu")
		(net "PVDDQ_ABC")
	)
	(segment
		(start 253.350522 -15.222982)
		(end 253.350014 -15.222982)
		(width 0.4064)
		(layer "B.Cu")
		(net "PVDDQ_ABC")
	)
	(segment
		(start 274.600416 -18.730976)
		(end 274.599908 -18.730468)
		(width 0.508)
		(layer "B.Cu")
		(net "PVDDQ_ABC")
	)
	(segment
		(start 244.849904 -10.623042)
		(end 244.849904 -9.133078)
		(width 0.4064)
		(layer "B.Cu")
		(net "PVDDQ_ABC")
	)
	(segment
		(start 258.449826 -7.115556)
		(end 258.449826 -5.621782)
		(width 0.4064)
		(layer "B.Cu")
		(net "PVDDQ_ABC")
	)
	(segment
		(start 269.500096 -13.013436)
		(end 269.500096 -13.933678)
		(width 0.508)
		(layer "B.Cu")
		(net "PVDDQ_ABC")
	)
	(segment
		(start 246.549926 -20.224242)
		(end 246.550434 -20.224242)
		(width 0.4064)
		(layer "B.Cu")
		(net "PVDDQ_ABC")
	)
	(segment
		(start 253.350014 -15.222982)
		(end 253.350014 -16.718788)
		(width 0.4064)
		(layer "B.Cu")
		(net "PVDDQ_ABC")
	)
	(segment
		(start 253.350014 -5.62229)
		(end 253.350014 -7.117588)
		(width 0.4064)
		(layer "B.Cu")
		(net "PVDDQ_ABC")
	)
	(segment
		(start 266.099798 -9.129268)
		(end 266.099798 -10.623042)
		(width 0.4064)
		(layer "B.Cu")
		(net "PVDDQ_ABC")
	)
	(segment
		(start 250.799854 -5.621782)
		(end 250.799854 -4.332478)
		(width 0.4064)
		(layer "B.Cu")
		(net "PVDDQ_ABC")
	)
	(segment
		(start 268.650466 -18.730976)
		(end 268.649958 -18.730468)
		(width 0.508)
		(layer "B.Cu")
		(net "PVDDQ_ABC")
	)
	(segment
		(start 272.899886 -18.730468)
		(end 272.899886 -20.224242)
		(width 0.508)
		(layer "B.Cu")
		(net "PVDDQ_ABC")
	)
	(segment
		(start 269.500096 -7.117588)
		(end 269.50035 -7.117334)
		(width 0.4064)
		(layer "B.Cu")
		(net "PVDDQ_ABC")
	)
	(segment
		(start 275.449792 -13.934186)
		(end 275.4503 -13.933678)
		(width 0.4064)
		(layer "B.Cu")
		(net "PVDDQ_ABC")
	)
	(segment
		(start 245.699788 -16.716756)
		(end 245.699788 -15.222982)
		(width 0.4064)
		(layer "B.Cu")
		(net "PVDDQ_ABC")
	)
	(segment
		(start 277.149814 -10.623042)
		(end 277.150322 -10.623042)
		(width 0.4064)
		(layer "B.Cu")
		(net "PVDDQ_ABC")
	)
	(segment
		(start 254.199898 -20.224242)
		(end 254.199898 -18.734278)
		(width 0.4064)
		(layer "B.Cu")
		(net "PVDDQ_ABC")
	)
	(segment
		(start 250.800362 -5.621782)
		(end 250.799854 -5.621782)
		(width 0.4064)
		(layer "B.Cu")
		(net "PVDDQ_ABC")
	)
	(segment
		(start 258.449826 -1.021842)
		(end 258.449826 0.471932)
		(width 0.4064)
		(layer "B.Cu")
		(net "PVDDQ_ABC")
	)
	(segment
		(start 266.949682 1.805432)
		(end 266.949682 2.916682)
		(width 0.508)
		(layer "B.Cu")
		(net "PVDDQ_ABC")
	)
	(segment
		(start 272.899886 -20.224242)
		(end 272.900394 -20.224242)
		(width 0.508)
		(layer "B.Cu")
		(net "PVDDQ_ABC")
	)
	(segment
		(start 244.849904 -20.224242)
		(end 244.850412 -20.224242)
		(width 0.4064)
		(layer "B.Cu")
		(net "PVDDQ_ABC")
	)
	(segment
		(start 273.74977 -13.934186)
		(end 273.750278 -13.933678)
		(width 0.4064)
		(layer "B.Cu")
		(net "PVDDQ_ABC")
	)
	(segment
		(start 243.999766 -22.850856)
		(end 244.000274 -22.851364)
		(width 0.4064)
		(layer "B.Cu")
		(net "PVDDQ_ABC")
	)
	(segment
		(start 244.849904 -10.623042)
		(end 244.850412 -10.623042)
		(width 0.4064)
		(layer "B.Cu")
		(net "PVDDQ_ABC")
	)
	(segment
		(start 269.500096 -13.933678)
		(end 269.919958 -13.513816)
		(width 0.127)
		(layer "B.Cu")
		(net "PVDDQ_ABC")
	)
	(segment
		(start 249.099832 -1.021842)
		(end 249.10034 -1.021842)
		(width 0.4064)
		(layer "B.Cu")
		(net "PVDDQ_ABC")
	)
	(segment
		(start 255.89992 -10.623042)
		(end 255.89992 -11.916156)
		(width 0.4064)
		(layer "B.Cu")
		(net "PVDDQ_ABC")
	)
	(segment
		(start 269.500096 -16.718788)
		(end 269.50035 -16.718534)
		(width 0.3302)
		(layer "B.Cu")
		(net "PVDDQ_ABC")
	)
	(segment
		(start 275.4503 -16.718788)
		(end 275.449792 -16.71828)
		(width 0.4064)
		(layer "B.Cu")
		(net "PVDDQ_ABC")
	)
	(segment
		(start 251.649992 -10.623042)
		(end 251.6505 -10.623042)
		(width 0.4064)
		(layer "B.Cu")
		(net "PVDDQ_ABC")
	)
	(segment
		(start 182.736998 -5.321808)
		(end 183.007 -5.59181)
		(width 0.254)
		(layer "B.Cu")
		(net "PVDDQ_ABC")
	)
	(segment
		(start 255.89992 0.471932)
		(end 255.89992 -1.021842)
		(width 0.4064)
		(layer "B.Cu")
		(net "PVDDQ_ABC")
	)
	(segment
		(start 244.849904 -1.021842)
		(end 244.849904 0.468122)
		(width 0.4064)
		(layer "B.Cu")
		(net "PVDDQ_ABC")
	)
	(segment
		(start 323.1134 -35.967162)
		(end 323.773546 -35.307016)
		(width 0.254)
		(layer "In2.Cu")
		(net "PVDDQ_ABC")
	)
	(segment
		(start 325.5391 -28.1305)
		(end 328.562716 -25.106884)
		(width 0.254)
		(layer "In2.Cu")
		(net "PVDDQ_ABC")
	)
	(segment
		(start 323.773546 -30.905704)
		(end 324.130924 -30.548326)
		(width 0.254)
		(layer "In2.Cu")
		(net "PVDDQ_ABC")
	)
	(segment
		(start 325.077074 -30.548326)
		(end 325.5391 -30.0863)
		(width 0.254)
		(layer "In2.Cu")
		(net "PVDDQ_ABC")
	)
	(segment
		(start 325.5391 -30.0863)
		(end 325.5391 -28.1305)
		(width 0.254)
		(layer "In2.Cu")
		(net "PVDDQ_ABC")
	)
	(segment
		(start 324.130924 -30.548326)
		(end 325.077074 -30.548326)
		(width 0.254)
		(layer "In2.Cu")
		(net "PVDDQ_ABC")
	)
	(segment
		(start 328.562716 -25.106884)
		(end 328.562716 -24.472138)
		(width 0.254)
		(layer "In2.Cu")
		(net "PVDDQ_ABC")
	)
	(segment
		(start 328.562716 -24.472138)
		(end 329.077574 -23.95728)
		(width 0.254)
		(layer "In2.Cu")
		(net "PVDDQ_ABC")
	)
	(segment
		(start 323.773546 -35.307016)
		(end 323.773546 -30.905704)
		(width 0.254)
		(layer "In2.Cu")
		(net "PVDDQ_ABC")
	)
	(segment
		(start 350.00311 -1.594358)
		(end 350.00311 -2.431542)
		(width 0.4064)
		(layer "In4.Cu")
		(net "PVDDQ_ABC")
	)
	(segment
		(start 345.9988 -9.017)
		(end 346.2528 -8.763)
		(width 0.4064)
		(layer "In4.Cu")
		(net "PVDDQ_ABC")
	)
	(segment
		(start 335.648808 -8.077962)
		(end 337.756246 -10.1854)
		(width 0.508)
		(layer "In4.Cu")
		(net "PVDDQ_ABC")
	)
	(segment
		(start 348.689168 -8.763)
		(end 349.198946 -8.253222)
		(width 0.4064)
		(layer "In4.Cu")
		(net "PVDDQ_ABC")
	)
	(segment
		(start 349.760286 -8.814562)
		(end 349.760286 -10.097262)
		(width 0.4064)
		(layer "In4.Cu")
		(net "PVDDQ_ABC")
	)
	(segment
		(start 345.9988 -10.082276)
		(end 345.9988 -9.017)
		(width 0.4064)
		(layer "In4.Cu")
		(net "PVDDQ_ABC")
	)
	(segment
		(start 349.198946 -6.419596)
		(end 349.198946 -8.253222)
		(width 0.4064)
		(layer "In4.Cu")
		(net "PVDDQ_ABC")
	)
	(segment
		(start 349.527876 -1.119124)
		(end 350.00311 -1.594358)
		(width 0.4064)
		(layer "In4.Cu")
		(net "PVDDQ_ABC")
	)
	(segment
		(start 350.9518 -3.380232)
		(end 350.9518 -4.666742)
		(width 0.4064)
		(layer "In4.Cu")
		(net "PVDDQ_ABC")
	)
	(segment
		(start 349.198946 -8.253222)
		(end 349.760286 -8.814562)
		(width 0.4064)
		(layer "In4.Cu")
		(net "PVDDQ_ABC")
	)
	(segment
		(start 337.756246 -10.1854)
		(end 340.573614 -10.1854)
		(width 0.508)
		(layer "In4.Cu")
		(net "PVDDQ_ABC")
	)
	(segment
		(start 346.2528 -8.763)
		(end 348.689168 -8.763)
		(width 0.4064)
		(layer "In4.Cu")
		(net "PVDDQ_ABC")
	)
	(segment
		(start 350.9518 -4.666742)
		(end 349.198946 -6.419596)
		(width 0.4064)
		(layer "In4.Cu")
		(net "PVDDQ_ABC")
	)
	(segment
		(start 344.857324 -11.223752)
		(end 345.9988 -10.082276)
		(width 0.4064)
		(layer "In4.Cu")
		(net "PVDDQ_ABC")
	)
	(segment
		(start 341.611966 -11.223752)
		(end 344.857324 -11.223752)
		(width 0.4064)
		(layer "In4.Cu")
		(net "PVDDQ_ABC")
	)
	(segment
		(start 340.573614 -10.1854)
		(end 341.611966 -11.223752)
		(width 0.4064)
		(layer "In4.Cu")
		(net "PVDDQ_ABC")
	)
	(segment
		(start 350.00311 -2.431542)
		(end 350.9518 -3.380232)
		(width 0.4064)
		(layer "In4.Cu")
		(net "PVDDQ_ABC")
	)
	(segment
		(start 334.476344 -44.496736)
		(end 358.844596 -44.496736)
		(width 0.254)
		(layer "In11.Cu")
		(net "PVDDQ_ABC")
	)
	(segment
		(start 333.40802 -43.428412)
		(end 334.476344 -44.496736)
		(width 0.254)
		(layer "In11.Cu")
		(net "PVDDQ_ABC")
	)
	(segment
		(start 332.67015 -41.07561)
		(end 333.40802 -41.81348)
		(width 0.254)
		(layer "In11.Cu")
		(net "PVDDQ_ABC")
	)
	(segment
		(start 323.1134 -35.967162)
		(end 323.1134 -38.05682)
		(width 0.254)
		(layer "In11.Cu")
		(net "PVDDQ_ABC")
	)
	(segment
		(start 331.192124 -41.07561)
		(end 332.67015 -41.07561)
		(width 0.254)
		(layer "In11.Cu")
		(net "PVDDQ_ABC")
	)
	(segment
		(start 333.40802 -41.81348)
		(end 333.40802 -43.428412)
		(width 0.254)
		(layer "In11.Cu")
		(net "PVDDQ_ABC")
	)
	(segment
		(start 330.967334 -41.3004)
		(end 331.192124 -41.07561)
		(width 0.254)
		(layer "In11.Cu")
		(net "PVDDQ_ABC")
	)
	(segment
		(start 323.1134 -38.05682)
		(end 326.35698 -41.3004)
		(width 0.254)
		(layer "In11.Cu")
		(net "PVDDQ_ABC")
	)
	(segment
		(start 358.844596 -44.496736)
		(end 364.45825 -50.11039)
		(width 0.254)
		(layer "In11.Cu")
		(net "PVDDQ_ABC")
	)
	(segment
		(start 326.35698 -41.3004)
		(end 330.967334 -41.3004)
		(width 0.254)
		(layer "In11.Cu")
		(net "PVDDQ_ABC")
	)
	(segment
		(start 364.45825 -50.11039)
		(end 367.368074 -50.11039)
		(width 0.254)
		(layer "In11.Cu")
		(net "PVDDQ_ABC")
	)
	(segment
		(start -2.13106 -118.65102)
		(end -3.764788 -118.65102)
		(width 0.254)
		(layer "F.Cu")
		(net "PVCCIO_CPU1")
	)
	(segment
		(start 122.504708 -71.258938)
		(end 123.076208 -71.258938)
		(width 0.254)
		(layer "F.Cu")
		(net "PVCCIO_CPU1")
	)
	(segment
		(start 158.877 -120.080786)
		(end 158.877 -119.166386)
		(width 0.4572)
		(layer "F.Cu")
		(net "PVCCIO_CPU1")
	)
	(segment
		(start 137.670794 -89.584784)
		(end 137.099294 -89.584784)
		(width 0.254)
		(layer "F.Cu")
		(net "PVCCIO_CPU1")
	)
	(segment
		(start 158.877 -120.4468)
		(end 158.3436 -120.9802)
		(width 0.4572)
		(layer "F.Cu")
		(net "PVCCIO_CPU1")
	)
	(segment
		(start 436.0926 -15.0876)
		(end 436.372 -15.367)
		(width 0.254)
		(layer "F.Cu")
		(net "PVCCIO_CPU1")
	)
	(segment
		(start 112.202722 -63.334138)
		(end 111.631222 -63.334138)
		(width 0.254)
		(layer "F.Cu")
		(net "PVCCIO_CPU1")
	)
	(segment
		(start 39.330122 -106.036618)
		(end 38.584886 -105.291382)
		(width 0.4064)
		(layer "F.Cu")
		(net "PVCCIO_CPU1")
	)
	(segment
		(start -4.155948 -118.25986)
		(end -4.155948 -117.38864)
		(width 0.254)
		(layer "F.Cu")
		(net "PVCCIO_CPU1")
	)
	(segment
		(start 138.816334 -68.782184)
		(end 139.387834 -68.782184)
		(width 0.254)
		(layer "F.Cu")
		(net "PVCCIO_CPU1")
	)
	(segment
		(start 131.089908 -93.052138)
		(end 131.661408 -93.052138)
		(width 0.254)
		(layer "F.Cu")
		(net "PVCCIO_CPU1")
	)
	(segment
		(start 127.655828 -92.061538)
		(end 128.227328 -92.061538)
		(width 0.254)
		(layer "F.Cu")
		(net "PVCCIO_CPU1")
	)
	(segment
		(start 179.714398 -56.742838)
		(end 179.95011 -56.742838)
		(width 0.254)
		(layer "F.Cu")
		(net "PVCCIO_CPU1")
	)
	(segment
		(start 429.8442 -14.4526)
		(end 430.518824 -14.4526)
		(width 0.254)
		(layer "F.Cu")
		(net "PVCCIO_CPU1")
	)
	(segment
		(start 436.372 -15.367)
		(end 436.8165 -15.367)
		(width 0.254)
		(layer "F.Cu")
		(net "PVCCIO_CPU1")
	)
	(segment
		(start 138.816334 -63.829184)
		(end 139.387834 -63.829184)
		(width 0.254)
		(layer "F.Cu")
		(net "PVCCIO_CPU1")
	)
	(segment
		(start 120.787668 -71.258938)
		(end 121.359168 -71.258938)
		(width 0.254)
		(layer "F.Cu")
		(net "PVCCIO_CPU1")
	)
	(segment
		(start 134.523734 -60.362338)
		(end 135.095234 -60.362338)
		(width 0.254)
		(layer "F.Cu")
		(net "PVCCIO_CPU1")
	)
	(segment
		(start 134.523734 -63.334138)
		(end 135.095234 -63.334138)
		(width 0.254)
		(layer "F.Cu")
		(net "PVCCIO_CPU1")
	)
	(segment
		(start 130.231388 -101.471984)
		(end 130.802888 -101.471984)
		(width 0.254)
		(layer "F.Cu")
		(net "PVCCIO_CPU1")
	)
	(segment
		(start 173.595284 -92.702888)
		(end 173.587918 -92.702888)
		(width 0.254)
		(layer "F.Cu")
		(net "PVCCIO_CPU1")
	)
	(segment
		(start 127.655828 -89.089738)
		(end 128.227328 -89.089738)
		(width 0.254)
		(layer "F.Cu")
		(net "PVCCIO_CPU1")
	)
	(segment
		(start 135.382254 -56.894984)
		(end 135.953754 -56.894984)
		(width 0.254)
		(layer "F.Cu")
		(net "PVCCIO_CPU1")
	)
	(segment
		(start 120.787668 -76.211938)
		(end 121.359168 -76.211938)
		(width 0.254)
		(layer "F.Cu")
		(net "PVCCIO_CPU1")
	)
	(segment
		(start 125.080268 -89.584784)
		(end 125.651768 -89.584784)
		(width 0.254)
		(layer "F.Cu")
		(net "PVCCIO_CPU1")
	)
	(segment
		(start 137.099294 -52.932838)
		(end 137.67054 -52.932838)
		(width 0.254)
		(layer "F.Cu")
		(net "PVCCIO_CPU1")
	)
	(segment
		(start 129.372868 -56.399938)
		(end 129.944368 -56.399938)
		(width 0.254)
		(layer "F.Cu")
		(net "PVCCIO_CPU1")
	)
	(segment
		(start 113.919762 -64.324738)
		(end 113.348262 -64.324738)
		(width 0.254)
		(layer "F.Cu")
		(net "PVCCIO_CPU1")
	)
	(segment
		(start 125.938788 -98.995738)
		(end 126.510288 -98.995738)
		(width 0.254)
		(layer "F.Cu")
		(net "PVCCIO_CPU1")
	)
	(segment
		(start 133.665214 -99.490784)
		(end 134.236714 -99.490784)
		(width 0.254)
		(layer "F.Cu")
		(net "PVCCIO_CPU1")
	)
	(segment
		(start 130.231388 -55.904384)
		(end 130.802888 -55.904384)
		(width 0.254)
		(layer "F.Cu")
		(net "PVCCIO_CPU1")
	)
	(segment
		(start 117.640862 -66.800984)
		(end 118.212362 -66.800984)
		(width 0.254)
		(layer "F.Cu")
		(net "PVCCIO_CPU1")
	)
	(segment
		(start 39.330122 -106.415586)
		(end 39.330122 -106.036618)
		(width 0.4064)
		(layer "F.Cu")
		(net "PVCCIO_CPU1")
	)
	(segment
		(start 138.816334 -57.885584)
		(end 139.387834 -57.885584)
		(width 0.254)
		(layer "F.Cu")
		(net "PVCCIO_CPU1")
	)
	(segment
		(start 134.523734 -61.352938)
		(end 135.095234 -61.352938)
		(width 0.254)
		(layer "F.Cu")
		(net "PVCCIO_CPU1")
	)
	(segment
		(start 120.787668 -72.249538)
		(end 121.359168 -72.249538)
		(width 0.254)
		(layer "F.Cu")
		(net "PVCCIO_CPU1")
	)
	(segment
		(start 122.504708 -75.221338)
		(end 123.076208 -75.221338)
		(width 0.254)
		(layer "F.Cu")
		(net "PVCCIO_CPU1")
	)
	(segment
		(start 131.948174 -87.603584)
		(end 132.519674 -87.603584)
		(width 0.254)
		(layer "F.Cu")
		(net "PVCCIO_CPU1")
	)
	(segment
		(start 158.877 -120.080786)
		(end 158.877 -120.4468)
		(width 0.4572)
		(layer "F.Cu")
		(net "PVCCIO_CPU1")
	)
	(segment
		(start 120.787668 -75.221338)
		(end 121.359168 -75.221338)
		(width 0.254)
		(layer "F.Cu")
		(net "PVCCIO_CPU1")
	)
	(segment
		(start 131.948174 -81.659984)
		(end 132.519674 -81.659984)
		(width 0.254)
		(layer "F.Cu")
		(net "PVCCIO_CPU1")
	)
	(segment
		(start 166.9415 0.5207)
		(end 166.9415 -0.77978)
		(width 0.4064)
		(layer "F.Cu")
		(net "PVCCIO_CPU1")
	)
	(segment
		(start 133.665214 -68.782184)
		(end 134.236714 -68.782184)
		(width 0.254)
		(layer "F.Cu")
		(net "PVCCIO_CPU1")
	)
	(segment
		(start 132.806694 -100.976684)
		(end 133.378194 -100.976684)
		(width 0.254)
		(layer "F.Cu")
		(net "PVCCIO_CPU1")
	)
	(segment
		(start 120.500902 -69.772784)
		(end 119.929402 -69.772784)
		(width 0.254)
		(layer "F.Cu")
		(net "PVCCIO_CPU1")
	)
	(segment
		(start 155.253436 -111.421164)
		(end 157.4546 -109.22)
		(width 0.254)
		(layer "F.Cu")
		(net "PVCCIO_CPU1")
	)
	(segment
		(start 137.957814 -87.108538)
		(end 138.529314 -87.108538)
		(width 0.254)
		(layer "F.Cu")
		(net "PVCCIO_CPU1")
	)
	(segment
		(start 111.344202 -62.838584)
		(end 110.772702 -62.838584)
		(width 0.254)
		(layer "F.Cu")
		(net "PVCCIO_CPU1")
	)
	(segment
		(start 120.787668 -74.230738)
		(end 121.359168 -74.230738)
		(width 0.254)
		(layer "F.Cu")
		(net "PVCCIO_CPU1")
	)
	(segment
		(start 180.230272 -57.023)
		(end 180.467 -57.023)
		(width 0.254)
		(layer "F.Cu")
		(net "PVCCIO_CPU1")
	)
	(segment
		(start 119.070882 -66.305938)
		(end 118.499382 -66.305938)
		(width 0.254)
		(layer "F.Cu")
		(net "PVCCIO_CPU1")
	)
	(segment
		(start 132.806694 -86.117938)
		(end 133.378194 -86.117938)
		(width 0.254)
		(layer "F.Cu")
		(net "PVCCIO_CPU1")
	)
	(segment
		(start 112.202722 -62.343538)
		(end 111.631222 -62.343538)
		(width 0.254)
		(layer "F.Cu")
		(net "PVCCIO_CPU1")
	)
	(segment
		(start 119.070882 -85.127338)
		(end 119.070882 -84.555838)
		(width 0.381)
		(layer "F.Cu")
		(net "PVCCIO_CPU1")
	)
	(segment
		(start 134.523734 -67.296538)
		(end 135.095234 -67.296538)
		(width 0.254)
		(layer "F.Cu")
		(net "PVCCIO_CPU1")
	)
	(segment
		(start 139.674854 -60.362338)
		(end 140.246354 -60.362338)
		(width 0.254)
		(layer "F.Cu")
		(net "PVCCIO_CPU1")
	)
	(segment
		(start 134.523734 -102.958138)
		(end 135.095234 -102.958138)
		(width 0.254)
		(layer "F.Cu")
		(net "PVCCIO_CPU1")
	)
	(segment
		(start 128.514348 -81.659984)
		(end 129.085848 -81.659984)
		(width 0.254)
		(layer "F.Cu")
		(net "PVCCIO_CPU1")
	)
	(segment
		(start 164.615114 -109.22)
		(end 164.615114 -109.20095)
		(width 0.254)
		(layer "F.Cu")
		(net "PVCCIO_CPU1")
	)
	(segment
		(start 121.646188 -75.716384)
		(end 122.217688 -75.716384)
		(width 0.254)
		(layer "F.Cu")
		(net "PVCCIO_CPU1")
	)
	(segment
		(start 119.929402 -76.706984)
		(end 119.357902 -76.706984)
		(width 0.254)
		(layer "F.Cu")
		(net "PVCCIO_CPU1")
	)
	(segment
		(start 127.655828 -57.390538)
		(end 128.227328 -57.390538)
		(width 0.254)
		(layer "F.Cu")
		(net "PVCCIO_CPU1")
	)
	(segment
		(start 113.919762 -63.334138)
		(end 113.348262 -63.334138)
		(width 0.254)
		(layer "F.Cu")
		(net "PVCCIO_CPU1")
	)
	(segment
		(start 157.97022 -123.9647)
		(end 157.71622 -123.7107)
		(width 0.4572)
		(layer "F.Cu")
		(net "PVCCIO_CPU1")
	)
	(segment
		(start 140.533374 -58.876438)
		(end 141.104874 -58.876438)
		(width 0.254)
		(layer "F.Cu")
		(net "PVCCIO_CPU1")
	)
	(segment
		(start 434.95722 -13.22705)
		(end 436.0926 -14.36243)
		(width 0.254)
		(layer "F.Cu")
		(net "PVCCIO_CPU1")
	)
	(segment
		(start 128.514348 -96.518984)
		(end 129.085848 -96.518984)
		(width 0.254)
		(layer "F.Cu")
		(net "PVCCIO_CPU1")
	)
	(segment
		(start 135.382254 -82.650584)
		(end 135.953754 -82.650584)
		(width 0.254)
		(layer "F.Cu")
		(net "PVCCIO_CPU1")
	)
	(segment
		(start 136.240774 -97.014538)
		(end 136.812274 -97.014538)
		(width 0.254)
		(layer "F.Cu")
		(net "PVCCIO_CPU1")
	)
	(segment
		(start 137.957814 -60.362338)
		(end 138.529314 -60.362338)
		(width 0.254)
		(layer "F.Cu")
		(net "PVCCIO_CPU1")
	)
	(segment
		(start 125.080268 -95.528384)
		(end 125.651768 -95.528384)
		(width 0.254)
		(layer "F.Cu")
		(net "PVCCIO_CPU1")
	)
	(segment
		(start 138.816334 -71.753984)
		(end 139.387834 -71.753984)
		(width 0.254)
		(layer "F.Cu")
		(net "PVCCIO_CPU1")
	)
	(segment
		(start 119.070882 -68.287138)
		(end 118.499382 -68.287138)
		(width 0.254)
		(layer "F.Cu")
		(net "PVCCIO_CPU1")
	)
	(segment
		(start 126.797308 -97.509584)
		(end 127.368808 -97.509584)
		(width 0.254)
		(layer "F.Cu")
		(net "PVCCIO_CPU1")
	)
	(segment
		(start 131.089908 -56.399938)
		(end 131.661408 -56.399938)
		(width 0.254)
		(layer "F.Cu")
		(net "PVCCIO_CPU1")
	)
	(segment
		(start 138.816334 -66.800984)
		(end 139.387834 -66.800984)
		(width 0.254)
		(layer "F.Cu")
		(net "PVCCIO_CPU1")
	)
	(segment
		(start 133.665214 -70.763384)
		(end 134.236714 -70.763384)
		(width 0.254)
		(layer "F.Cu")
		(net "PVCCIO_CPU1")
	)
	(segment
		(start 137.670794 -94.538038)
		(end 137.099294 -94.538038)
		(width 0.254)
		(layer "F.Cu")
		(net "PVCCIO_CPU1")
	)
	(segment
		(start 113.061242 -63.829184)
		(end 112.489742 -63.829184)
		(width 0.254)
		(layer "F.Cu")
		(net "PVCCIO_CPU1")
	)
	(segment
		(start 131.089908 -59.371484)
		(end 131.661408 -59.371484)
		(width 0.254)
		(layer "F.Cu")
		(net "PVCCIO_CPU1")
	)
	(segment
		(start 120.500902 -82.650584)
		(end 119.929402 -82.650584)
		(width 0.254)
		(layer "F.Cu")
		(net "PVCCIO_CPU1")
	)
	(segment
		(start 135.382254 -84.631784)
		(end 135.953754 -84.631784)
		(width 0.254)
		(layer "F.Cu")
		(net "PVCCIO_CPU1")
	)
	(segment
		(start 121.646188 -77.697584)
		(end 122.217688 -77.697584)
		(width 0.254)
		(layer "F.Cu")
		(net "PVCCIO_CPU1")
	)
	(segment
		(start -1.5494 -118.06936)
		(end -2.13106 -118.65102)
		(width 0.254)
		(layer "F.Cu")
		(net "PVCCIO_CPU1")
	)
	(segment
		(start 130.231388 -86.612984)
		(end 130.802888 -86.612984)
		(width 0.254)
		(layer "F.Cu")
		(net "PVCCIO_CPU1")
	)
	(segment
		(start 132.806694 -89.089738)
		(end 133.378194 -89.089738)
		(width 0.254)
		(layer "F.Cu")
		(net "PVCCIO_CPU1")
	)
	(segment
		(start 131.948174 -54.913784)
		(end 132.519674 -54.913784)
		(width 0.254)
		(layer "F.Cu")
		(net "PVCCIO_CPU1")
	)
	(segment
		(start 139.674854 -62.343538)
		(end 140.246354 -62.343538)
		(width 0.254)
		(layer "F.Cu")
		(net "PVCCIO_CPU1")
	)
	(segment
		(start 119.929402 -73.735184)
		(end 119.357902 -73.735184)
		(width 0.254)
		(layer "F.Cu")
		(net "PVCCIO_CPU1")
	)
	(segment
		(start 157.08122 -124.8537)
		(end 157.33522 -125.1077)
		(width 0.254)
		(layer "F.Cu")
		(net "PVCCIO_CPU1")
	)
	(segment
		(start 125.938788 -62.343538)
		(end 126.510288 -62.343538)
		(width 0.254)
		(layer "F.Cu")
		(net "PVCCIO_CPU1")
	)
	(segment
		(start 127.655828 -83.146138)
		(end 128.227328 -83.146138)
		(width 0.254)
		(layer "F.Cu")
		(net "PVCCIO_CPU1")
	)
	(segment
		(start 131.089908 -91.070938)
		(end 131.661408 -91.070938)
		(width 0.254)
		(layer "F.Cu")
		(net "PVCCIO_CPU1")
	)
	(segment
		(start 120.500902 -83.641184)
		(end 119.929402 -83.641184)
		(width 0.381)
		(layer "F.Cu")
		(net "PVCCIO_CPU1")
	)
	(segment
		(start 157.4546 -109.22)
		(end 164.615114 -109.22)
		(width 0.254)
		(layer "F.Cu")
		(net "PVCCIO_CPU1")
	)
	(segment
		(start 131.948174 -93.547184)
		(end 132.519674 -93.547184)
		(width 0.254)
		(layer "F.Cu")
		(net "PVCCIO_CPU1")
	)
	(segment
		(start 137.67054 -52.932838)
		(end 137.670794 -52.932584)
		(width 0.254)
		(layer "F.Cu")
		(net "PVCCIO_CPU1")
	)
	(segment
		(start 162.38728 -68.072)
		(end 162.38728 -68.8467)
		(width 0.254)
		(layer "F.Cu")
		(net "PVCCIO_CPU1")
	)
	(segment
		(start 431.744374 -13.22705)
		(end 434.95722 -13.22705)
		(width 0.254)
		(layer "F.Cu")
		(net "PVCCIO_CPU1")
	)
	(segment
		(start 150.422864 -113.068608)
		(end 152.070308 -111.421164)
		(width 0.254)
		(layer "F.Cu")
		(net "PVCCIO_CPU1")
	)
	(segment
		(start 173.595284 -92.67825)
		(end 173.595284 -92.702888)
		(width 0.254)
		(layer "F.Cu")
		(net "PVCCIO_CPU1")
	)
	(segment
		(start 152.070308 -111.421164)
		(end 155.253436 -111.421164)
		(width 0.254)
		(layer "F.Cu")
		(net "PVCCIO_CPU1")
	)
	(segment
		(start 131.089908 -84.136738)
		(end 131.661408 -84.136738)
		(width 0.254)
		(layer "F.Cu")
		(net "PVCCIO_CPU1")
	)
	(segment
		(start 436.8165 -15.367)
		(end 436.8165 -16.129)
		(width 0.254)
		(layer "F.Cu")
		(net "PVCCIO_CPU1")
	)
	(segment
		(start 119.929402 -71.753984)
		(end 119.357902 -71.753984)
		(width 0.254)
		(layer "F.Cu")
		(net "PVCCIO_CPU1")
	)
	(segment
		(start 179.95011 -56.742838)
		(end 180.230272 -57.023)
		(width 0.254)
		(layer "F.Cu")
		(net "PVCCIO_CPU1")
	)
	(segment
		(start 125.080268 -93.547184)
		(end 125.651768 -93.547184)
		(width 0.254)
		(layer "F.Cu")
		(net "PVCCIO_CPU1")
	)
	(segment
		(start 123.363228 -73.735184)
		(end 123.934728 -73.735184)
		(width 0.254)
		(layer "F.Cu")
		(net "PVCCIO_CPU1")
	)
	(segment
		(start 39.322756 -107.355132)
		(end 39.322756 -106.422952)
		(width 0.4064)
		(layer "F.Cu")
		(net "PVCCIO_CPU1")
	)
	(segment
		(start 129.372868 -95.033084)
		(end 129.944368 -95.033084)
		(width 0.254)
		(layer "F.Cu")
		(net "PVCCIO_CPU1")
	)
	(segment
		(start 430.518824 -14.4526)
		(end 431.744374 -13.22705)
		(width 0.254)
		(layer "F.Cu")
		(net "PVCCIO_CPU1")
	)
	(segment
		(start 134.523734 -98.005138)
		(end 135.095234 -98.005138)
		(width 0.254)
		(layer "F.Cu")
		(net "PVCCIO_CPU1")
	)
	(segment
		(start 119.929402 -74.725784)
		(end 119.357902 -74.725784)
		(width 0.254)
		(layer "F.Cu")
		(net "PVCCIO_CPU1")
	)
	(segment
		(start 121.646188 -74.725784)
		(end 122.217688 -74.725784)
		(width 0.254)
		(layer "F.Cu")
		(net "PVCCIO_CPU1")
	)
	(segment
		(start 141.391894 -98.005138)
		(end 142.039848 -98.005138)
		(width 0.254)
		(layer "F.Cu")
		(net "PVCCIO_CPU1")
	)
	(segment
		(start 137.670794 -92.556584)
		(end 137.099294 -92.556584)
		(width 0.254)
		(layer "F.Cu")
		(net "PVCCIO_CPU1")
	)
	(segment
		(start 120.500902 -84.631784)
		(end 119.929402 -84.631784)
		(width 0.254)
		(layer "F.Cu")
		(net "PVCCIO_CPU1")
	)
	(segment
		(start 173.297088 -91.22156)
		(end 173.297088 -92.380054)
		(width 0.254)
		(layer "F.Cu")
		(net "PVCCIO_CPU1")
	)
	(segment
		(start 120.787668 -70.268084)
		(end 121.359168 -70.268084)
		(width 0.254)
		(layer "F.Cu")
		(net "PVCCIO_CPU1")
	)
	(segment
		(start 133.665214 -56.894984)
		(end 134.236714 -56.894984)
		(width 0.254)
		(layer "F.Cu")
		(net "PVCCIO_CPU1")
	)
	(segment
		(start 125.080268 -56.894984)
		(end 125.651768 -56.894984)
		(width 0.254)
		(layer "F.Cu")
		(net "PVCCIO_CPU1")
	)
	(segment
		(start 122.504708 -73.240138)
		(end 123.076208 -73.240138)
		(width 0.254)
		(layer "F.Cu")
		(net "PVCCIO_CPU1")
	)
	(segment
		(start 38.584886 -105.291382)
		(end 38.584886 -104.969818)
		(width 0.4064)
		(layer "F.Cu")
		(net "PVCCIO_CPU1")
	)
	(segment
		(start 137.099294 -56.894984)
		(end 137.670794 -56.894984)
		(width 0.254)
		(layer "F.Cu")
		(net "PVCCIO_CPU1")
	)
	(segment
		(start 138.816334 -83.641184)
		(end 139.387834 -83.641184)
		(width 0.254)
		(layer "F.Cu")
		(net "PVCCIO_CPU1")
	)
	(segment
		(start 113.061242 -62.838584)
		(end 112.489742 -62.838584)
		(width 0.254)
		(layer "F.Cu")
		(net "PVCCIO_CPU1")
	)
	(segment
		(start 141.391894 -55.409338)
		(end 141.963394 -55.409338)
		(width 0.254)
		(layer "F.Cu")
		(net "PVCCIO_CPU1")
	)
	(segment
		(start 138.816334 -85.622384)
		(end 139.387834 -85.622384)
		(width 0.254)
		(layer "F.Cu")
		(net "PVCCIO_CPU1")
	)
	(segment
		(start -3.764788 -118.65102)
		(end -4.155948 -118.25986)
		(width 0.254)
		(layer "F.Cu")
		(net "PVCCIO_CPU1")
	)
	(segment
		(start 119.929402 -75.716384)
		(end 119.357902 -75.716384)
		(width 0.254)
		(layer "F.Cu")
		(net "PVCCIO_CPU1")
	)
	(segment
		(start 157.33522 -125.1077)
		(end 157.97022 -125.1077)
		(width 0.254)
		(layer "F.Cu")
		(net "PVCCIO_CPU1")
	)
	(segment
		(start 134.523734 -55.409338)
		(end 135.095234 -55.409338)
		(width 0.254)
		(layer "F.Cu")
		(net "PVCCIO_CPU1")
	)
	(segment
		(start 157.97022 -125.1077)
		(end 157.97022 -123.9647)
		(width 0.4572)
		(layer "F.Cu")
		(net "PVCCIO_CPU1")
	)
	(segment
		(start 128.514348 -90.575384)
		(end 129.085848 -90.575384)
		(width 0.254)
		(layer "F.Cu")
		(net "PVCCIO_CPU1")
	)
	(segment
		(start 119.929402 -70.763384)
		(end 119.357902 -70.763384)
		(width 0.254)
		(layer "F.Cu")
		(net "PVCCIO_CPU1")
	)
	(segment
		(start 436.0926 -14.36243)
		(end 436.0926 -15.0876)
		(width 0.254)
		(layer "F.Cu")
		(net "PVCCIO_CPU1")
	)
	(segment
		(start 137.957814 -70.268084)
		(end 138.529314 -70.268084)
		(width 0.254)
		(layer "F.Cu")
		(net "PVCCIO_CPU1")
	)
	(segment
		(start 135.382254 -64.819784)
		(end 135.953754 -64.819784)
		(width 0.254)
		(layer "F.Cu")
		(net "PVCCIO_CPU1")
	)
	(segment
		(start 125.938788 -86.117938)
		(end 126.510288 -86.117938)
		(width 0.254)
		(layer "F.Cu")
		(net "PVCCIO_CPU1")
	)
	(segment
		(start 120.787668 -82.155284)
		(end 121.359168 -82.155284)
		(width 0.254)
		(layer "F.Cu")
		(net "PVCCIO_CPU1")
	)
	(segment
		(start 173.297088 -92.380054)
		(end 173.595284 -92.67825)
		(width 0.254)
		(layer "F.Cu")
		(net "PVCCIO_CPU1")
	)
	(segment
		(start 157.71622 -123.7107)
		(end 156.70022 -123.7107)
		(width 0.4572)
		(layer "F.Cu")
		(net "PVCCIO_CPU1")
	)
	(segment
		(start 137.099294 -68.782184)
		(end 137.670794 -68.782184)
		(width 0.254)
		(layer "F.Cu")
		(net "PVCCIO_CPU1")
	)
	(segment
		(start 39.322756 -106.422952)
		(end 39.330122 -106.415586)
		(width 0.4064)
		(layer "F.Cu")
		(net "PVCCIO_CPU1")
	)
	(segment
		(start 136.240774 -94.042738)
		(end 136.812274 -94.042738)
		(width 0.254)
		(layer "F.Cu")
		(net "PVCCIO_CPU1")
	)
	(via
		(at 133.378194 -86.117938)
		(size 0.508)
		(drill 0.254)
		(layers "F.Cu" "B.Cu")
		(net "PVCCIO_CPU1")
	)
	(via
		(at 137.670794 -89.584784)
		(size 0.508)
		(drill 0.254)
		(layers "F.Cu" "B.Cu")
		(net "PVCCIO_CPU1")
	)
	(via
		(at 161.798254 -57.083198)
		(size 0.5588)
		(drill 0.3048)
		(layers "F.Cu" "B.Cu")
		(net "PVCCIO_CPU1")
	)
	(via
		(at 163.703 -56.896)
		(size 0.5588)
		(drill 0.3048)
		(layers "F.Cu" "B.Cu")
		(net "PVCCIO_CPU1")
	)
	(via
		(at 134.236714 -68.782184)
		(size 0.508)
		(drill 0.254)
		(layers "F.Cu" "B.Cu")
		(net "PVCCIO_CPU1")
	)
	(via
		(at 114.261392 -70.825614)
		(size 0.508)
		(drill 0.254)
		(layers "F.Cu" "B.Cu")
		(net "PVCCIO_CPU1")
	)
	(via
		(at 165.2778 -58.2168)
		(size 0.5588)
		(drill 0.3048)
		(layers "F.Cu" "B.Cu")
		(net "PVCCIO_CPU1")
	)
	(via
		(at 129.085848 -88.594184)
		(size 0.508)
		(drill 0.254)
		(layers "F.Cu" "B.Cu")
		(net "PVCCIO_CPU1")
	)
	(via
		(at 129.944368 -56.399938)
		(size 0.508)
		(drill 0.254)
		(layers "F.Cu" "B.Cu")
		(net "PVCCIO_CPU1")
	)
	(via
		(at 131.661408 -59.371484)
		(size 0.508)
		(drill 0.254)
		(layers "F.Cu" "B.Cu")
		(net "PVCCIO_CPU1")
	)
	(via
		(at 163.703 -57.5564)
		(size 0.5588)
		(drill 0.3048)
		(layers "F.Cu" "B.Cu")
		(net "PVCCIO_CPU1")
	)
	(via
		(at 139.387834 -57.885584)
		(size 0.508)
		(drill 0.254)
		(layers "F.Cu" "B.Cu")
		(net "PVCCIO_CPU1")
	)
	(via
		(at 135.095234 -102.958138)
		(size 0.508)
		(drill 0.254)
		(layers "F.Cu" "B.Cu")
		(net "PVCCIO_CPU1")
	)
	(via
		(at 113.348262 -63.334138)
		(size 0.508)
		(drill 0.254)
		(layers "F.Cu" "B.Cu")
		(net "PVCCIO_CPU1")
	)
	(via
		(at 129.085848 -81.659984)
		(size 0.508)
		(drill 0.254)
		(layers "F.Cu" "B.Cu")
		(net "PVCCIO_CPU1")
	)
	(via
		(at 122.217688 -75.716384)
		(size 0.508)
		(drill 0.254)
		(layers "F.Cu" "B.Cu")
		(net "PVCCIO_CPU1")
	)
	(via
		(at 137.670794 -68.782184)
		(size 0.508)
		(drill 0.254)
		(layers "F.Cu" "B.Cu")
		(net "PVCCIO_CPU1")
	)
	(via
		(at 177.0888 -20.193)
		(size 0.508)
		(drill 0.254)
		(layers "F.Cu" "B.Cu")
		(net "PVCCIO_CPU1")
	)
	(via
		(at 130.802888 -55.904384)
		(size 0.508)
		(drill 0.254)
		(layers "F.Cu" "B.Cu")
		(net "PVCCIO_CPU1")
	)
	(via
		(at 373.477028 -47.846488)
		(size 0.508)
		(drill 0.254)
		(layers "F.Cu" "B.Cu")
		(net "PVCCIO_CPU1")
	)
	(via
		(at 121.359168 -82.155284)
		(size 0.508)
		(drill 0.254)
		(layers "F.Cu" "B.Cu")
		(net "PVCCIO_CPU1")
	)
	(via
		(at 123.934728 -73.735184)
		(size 0.508)
		(drill 0.254)
		(layers "F.Cu" "B.Cu")
		(net "PVCCIO_CPU1")
	)
	(via
		(at 128.227328 -57.390538)
		(size 0.508)
		(drill 0.254)
		(layers "F.Cu" "B.Cu")
		(net "PVCCIO_CPU1")
	)
	(via
		(at 135.095234 -60.362338)
		(size 0.508)
		(drill 0.254)
		(layers "F.Cu" "B.Cu")
		(net "PVCCIO_CPU1")
	)
	(via
		(at 135.095234 -67.296538)
		(size 0.508)
		(drill 0.254)
		(layers "F.Cu" "B.Cu")
		(net "PVCCIO_CPU1")
	)
	(via
		(at 114.718592 -78.318614)
		(size 0.508)
		(drill 0.254)
		(layers "F.Cu" "B.Cu")
		(net "PVCCIO_CPU1")
	)
	(via
		(at 111.631222 -63.334138)
		(size 0.508)
		(drill 0.254)
		(layers "F.Cu" "B.Cu")
		(net "PVCCIO_CPU1")
	)
	(via
		(at 140.246354 -60.362338)
		(size 0.508)
		(drill 0.254)
		(layers "F.Cu" "B.Cu")
		(net "PVCCIO_CPU1")
	)
	(via
		(at 164.4904 -57.5564)
		(size 0.5588)
		(drill 0.3048)
		(layers "F.Cu" "B.Cu")
		(net "PVCCIO_CPU1")
	)
	(via
		(at 120.500902 -82.650584)
		(size 0.508)
		(drill 0.254)
		(layers "F.Cu" "B.Cu")
		(net "PVCCIO_CPU1")
	)
	(via
		(at 165.2778 -57.5564)
		(size 0.5588)
		(drill 0.3048)
		(layers "F.Cu" "B.Cu")
		(net "PVCCIO_CPU1")
	)
	(via
		(at 128.227328 -83.146138)
		(size 0.508)
		(drill 0.254)
		(layers "F.Cu" "B.Cu")
		(net "PVCCIO_CPU1")
	)
	(via
		(at 139.387834 -71.753984)
		(size 0.508)
		(drill 0.254)
		(layers "F.Cu" "B.Cu")
		(net "PVCCIO_CPU1")
	)
	(via
		(at 119.357902 -74.725784)
		(size 0.508)
		(drill 0.254)
		(layers "F.Cu" "B.Cu")
		(net "PVCCIO_CPU1")
	)
	(via
		(at 130.802888 -101.471984)
		(size 0.508)
		(drill 0.254)
		(layers "F.Cu" "B.Cu")
		(net "PVCCIO_CPU1")
	)
	(via
		(at 135.095234 -55.409338)
		(size 0.508)
		(drill 0.254)
		(layers "F.Cu" "B.Cu")
		(net "PVCCIO_CPU1")
	)
	(via
		(at 119.357902 -75.716384)
		(size 0.508)
		(drill 0.254)
		(layers "F.Cu" "B.Cu")
		(net "PVCCIO_CPU1")
	)
	(via
		(at 119.357902 -71.753984)
		(size 0.508)
		(drill 0.254)
		(layers "F.Cu" "B.Cu")
		(net "PVCCIO_CPU1")
	)
	(via
		(at 135.953754 -84.631784)
		(size 0.508)
		(drill 0.254)
		(layers "F.Cu" "B.Cu")
		(net "PVCCIO_CPU1")
	)
	(via
		(at 136.812274 -94.042738)
		(size 0.508)
		(drill 0.254)
		(layers "F.Cu" "B.Cu")
		(net "PVCCIO_CPU1")
	)
	(via
		(at 135.953754 -82.650584)
		(size 0.508)
		(drill 0.254)
		(layers "F.Cu" "B.Cu")
		(net "PVCCIO_CPU1")
	)
	(via
		(at 142.039848 -98.005138)
		(size 0.508)
		(drill 0.254)
		(layers "F.Cu" "B.Cu")
		(net "PVCCIO_CPU1")
	)
	(via
		(at 127.368808 -97.509584)
		(size 0.508)
		(drill 0.254)
		(layers "F.Cu" "B.Cu")
		(net "PVCCIO_CPU1")
	)
	(via
		(at 129.085848 -96.518984)
		(size 0.508)
		(drill 0.254)
		(layers "F.Cu" "B.Cu")
		(net "PVCCIO_CPU1")
	)
	(via
		(at 123.076208 -71.258938)
		(size 0.508)
		(drill 0.254)
		(layers "F.Cu" "B.Cu")
		(net "PVCCIO_CPU1")
	)
	(via
		(at 129.944368 -88.099138)
		(size 0.508)
		(drill 0.254)
		(layers "F.Cu" "B.Cu")
		(net "PVCCIO_CPU1")
	)
	(via
		(at 141.963394 -55.409338)
		(size 0.508)
		(drill 0.254)
		(layers "F.Cu" "B.Cu")
		(net "PVCCIO_CPU1")
	)
	(via
		(at 125.651768 -56.894984)
		(size 0.508)
		(drill 0.254)
		(layers "F.Cu" "B.Cu")
		(net "PVCCIO_CPU1")
	)
	(via
		(at 128.227328 -89.089738)
		(size 0.508)
		(drill 0.254)
		(layers "F.Cu" "B.Cu")
		(net "PVCCIO_CPU1")
	)
	(via
		(at 144.8816 -61.849)
		(size 0.508)
		(drill 0.254)
		(layers "F.Cu" "B.Cu")
		(net "PVCCIO_CPU1")
	)
	(via
		(at 136.812274 -97.014538)
		(size 0.508)
		(drill 0.254)
		(layers "F.Cu" "B.Cu")
		(net "PVCCIO_CPU1")
	)
	(via
		(at 140.246354 -62.343538)
		(size 0.508)
		(drill 0.254)
		(layers "F.Cu" "B.Cu")
		(net "PVCCIO_CPU1")
	)
	(via
		(at 163.7665 -44.6151)
		(size 0.508)
		(drill 0.254)
		(layers "F.Cu" "B.Cu")
		(net "PVCCIO_CPU1")
	)
	(via
		(at 129.085848 -87.603584)
		(size 0.508)
		(drill 0.254)
		(layers "F.Cu" "B.Cu")
		(net "PVCCIO_CPU1")
	)
	(via
		(at 129.085848 -90.575384)
		(size 0.508)
		(drill 0.254)
		(layers "F.Cu" "B.Cu")
		(net "PVCCIO_CPU1")
	)
	(via
		(at 119.357902 -76.706984)
		(size 0.508)
		(drill 0.254)
		(layers "F.Cu" "B.Cu")
		(net "PVCCIO_CPU1")
	)
	(via
		(at 162.9664 -56.896)
		(size 0.5588)
		(drill 0.3048)
		(layers "F.Cu" "B.Cu")
		(net "PVCCIO_CPU1")
	)
	(via
		(at 133.378194 -100.976684)
		(size 0.508)
		(drill 0.254)
		(layers "F.Cu" "B.Cu")
		(net "PVCCIO_CPU1")
	)
	(via
		(at 131.661408 -56.399938)
		(size 0.508)
		(drill 0.254)
		(layers "F.Cu" "B.Cu")
		(net "PVCCIO_CPU1")
	)
	(via
		(at 121.359168 -71.258938)
		(size 0.508)
		(drill 0.254)
		(layers "F.Cu" "B.Cu")
		(net "PVCCIO_CPU1")
	)
	(via
		(at 150.422864 -113.068608)
		(size 0.508)
		(drill 0.254)
		(layers "F.Cu" "B.Cu")
		(net "PVCCIO_CPU1")
	)
	(via
		(at 132.519674 -54.913784)
		(size 0.508)
		(drill 0.254)
		(layers "F.Cu" "B.Cu")
		(net "PVCCIO_CPU1")
	)
	(via
		(at 111.631222 -62.343538)
		(size 0.508)
		(drill 0.254)
		(layers "F.Cu" "B.Cu")
		(net "PVCCIO_CPU1")
	)
	(via
		(at 120.500902 -83.641184)
		(size 0.508)
		(drill 0.254)
		(layers "F.Cu" "B.Cu")
		(net "PVCCIO_CPU1")
	)
	(via
		(at 115.1636 -70.0024)
		(size 0.508)
		(drill 0.254)
		(layers "F.Cu" "B.Cu")
		(net "PVCCIO_CPU1")
	)
	(via
		(at 130.802888 -87.603584)
		(size 0.508)
		(drill 0.254)
		(layers "F.Cu" "B.Cu")
		(net "PVCCIO_CPU1")
	)
	(via
		(at -1.5494 -118.06936)
		(size 0.508)
		(drill 0.254)
		(layers "F.Cu" "B.Cu")
		(net "PVCCIO_CPU1")
	)
	(via
		(at 134.236714 -99.490784)
		(size 0.508)
		(drill 0.254)
		(layers "F.Cu" "B.Cu")
		(net "PVCCIO_CPU1")
	)
	(via
		(at 421.2844 -11.3538)
		(size 0.508)
		(drill 0.254)
		(layers "F.Cu" "B.Cu")
		(net "PVCCIO_CPU1")
	)
	(via
		(at 162.951414 -61.271912)
		(size 0.5588)
		(drill 0.3048)
		(layers "F.Cu" "B.Cu")
		(net "PVCCIO_CPU1")
	)
	(via
		(at 162.951414 -59.951112)
		(size 0.5588)
		(drill 0.3048)
		(layers "F.Cu" "B.Cu")
		(net "PVCCIO_CPU1")
	)
	(via
		(at 133.378194 -89.089738)
		(size 0.508)
		(drill 0.254)
		(layers "F.Cu" "B.Cu")
		(net "PVCCIO_CPU1")
	)
	(via
		(at 115.353592 -78.826614)
		(size 0.508)
		(drill 0.254)
		(layers "F.Cu" "B.Cu")
		(net "PVCCIO_CPU1")
	)
	(via
		(at 121.359168 -74.230738)
		(size 0.508)
		(drill 0.254)
		(layers "F.Cu" "B.Cu")
		(net "PVCCIO_CPU1")
	)
	(via
		(at 126.510288 -62.343538)
		(size 0.508)
		(drill 0.254)
		(layers "F.Cu" "B.Cu")
		(net "PVCCIO_CPU1")
	)
	(via
		(at 16.3068 -4.416806)
		(size 0.508)
		(drill 0.254)
		(layers "F.Cu" "B.Cu")
		(net "PVCCIO_CPU1")
	)
	(via
		(at 137.670794 -92.556584)
		(size 0.508)
		(drill 0.254)
		(layers "F.Cu" "B.Cu")
		(net "PVCCIO_CPU1")
	)
	(via
		(at 126.510288 -86.117938)
		(size 0.508)
		(drill 0.254)
		(layers "F.Cu" "B.Cu")
		(net "PVCCIO_CPU1")
	)
	(via
		(at 157.08122 -124.8537)
		(size 0.508)
		(drill 0.254)
		(layers "F.Cu" "B.Cu")
		(net "PVCCIO_CPU1")
	)
	(via
		(at 135.095234 -98.005138)
		(size 0.508)
		(drill 0.254)
		(layers "F.Cu" "B.Cu")
		(net "PVCCIO_CPU1")
	)
	(via
		(at 139.387834 -68.782184)
		(size 0.508)
		(drill 0.254)
		(layers "F.Cu" "B.Cu")
		(net "PVCCIO_CPU1")
	)
	(via
		(at 139.387834 -83.641184)
		(size 0.508)
		(drill 0.254)
		(layers "F.Cu" "B.Cu")
		(net "PVCCIO_CPU1")
	)
	(via
		(at 132.519674 -87.603584)
		(size 0.508)
		(drill 0.254)
		(layers "F.Cu" "B.Cu")
		(net "PVCCIO_CPU1")
	)
	(via
		(at 161.798254 -57.743598)
		(size 0.5588)
		(drill 0.3048)
		(layers "F.Cu" "B.Cu")
		(net "PVCCIO_CPU1")
	)
	(via
		(at 126.510288 -98.995738)
		(size 0.508)
		(drill 0.254)
		(layers "F.Cu" "B.Cu")
		(net "PVCCIO_CPU1")
	)
	(via
		(at 129.085848 -86.612984)
		(size 0.508)
		(drill 0.254)
		(layers "F.Cu" "B.Cu")
		(net "PVCCIO_CPU1")
	)
	(via
		(at 162.9664 -57.5564)
		(size 0.5588)
		(drill 0.3048)
		(layers "F.Cu" "B.Cu")
		(net "PVCCIO_CPU1")
	)
	(via
		(at 162.9664 -58.8772)
		(size 0.5588)
		(drill 0.3048)
		(layers "F.Cu" "B.Cu")
		(net "PVCCIO_CPU1")
	)
	(via
		(at 164.4904 -56.896)
		(size 0.5588)
		(drill 0.3048)
		(layers "F.Cu" "B.Cu")
		(net "PVCCIO_CPU1")
	)
	(via
		(at 129.944368 -89.089738)
		(size 0.508)
		(drill 0.254)
		(layers "F.Cu" "B.Cu")
		(net "PVCCIO_CPU1")
	)
	(via
		(at 122.217688 -77.697584)
		(size 0.508)
		(drill 0.254)
		(layers "F.Cu" "B.Cu")
		(net "PVCCIO_CPU1")
	)
	(via
		(at 114.5032 -70.0024)
		(size 0.508)
		(drill 0.254)
		(layers "F.Cu" "B.Cu")
		(net "PVCCIO_CPU1")
	)
	(via
		(at 134.236714 -56.894984)
		(size 0.508)
		(drill 0.254)
		(layers "F.Cu" "B.Cu")
		(net "PVCCIO_CPU1")
	)
	(via
		(at 137.670794 -56.894984)
		(size 0.508)
		(drill 0.254)
		(layers "F.Cu" "B.Cu")
		(net "PVCCIO_CPU1")
	)
	(via
		(at 115.353592 -78.191614)
		(size 0.508)
		(drill 0.254)
		(layers "F.Cu" "B.Cu")
		(net "PVCCIO_CPU1")
	)
	(via
		(at 307.094382 -46.712378)
		(size 0.508)
		(drill 0.254)
		(layers "F.Cu" "B.Cu")
		(net "PVCCIO_CPU1")
	)
	(via
		(at 130.802888 -88.594184)
		(size 0.508)
		(drill 0.254)
		(layers "F.Cu" "B.Cu")
		(net "PVCCIO_CPU1")
	)
	(via
		(at 131.661408 -84.136738)
		(size 0.508)
		(drill 0.254)
		(layers "F.Cu" "B.Cu")
		(net "PVCCIO_CPU1")
	)
	(via
		(at 138.529314 -70.268084)
		(size 0.508)
		(drill 0.254)
		(layers "F.Cu" "B.Cu")
		(net "PVCCIO_CPU1")
	)
	(via
		(at 164.4904 -58.8772)
		(size 0.5588)
		(drill 0.3048)
		(layers "F.Cu" "B.Cu")
		(net "PVCCIO_CPU1")
	)
	(via
		(at 122.217688 -74.725784)
		(size 0.508)
		(drill 0.254)
		(layers "F.Cu" "B.Cu")
		(net "PVCCIO_CPU1")
	)
	(via
		(at 38.584886 -104.969818)
		(size 0.508)
		(drill 0.254)
		(layers "F.Cu" "B.Cu")
		(net "PVCCIO_CPU1")
	)
	(via
		(at 110.772702 -62.838584)
		(size 0.508)
		(drill 0.254)
		(layers "F.Cu" "B.Cu")
		(net "PVCCIO_CPU1")
	)
	(via
		(at 128.227328 -92.061538)
		(size 0.508)
		(drill 0.254)
		(layers "F.Cu" "B.Cu")
		(net "PVCCIO_CPU1")
	)
	(via
		(at 163.703 -58.8772)
		(size 0.5588)
		(drill 0.3048)
		(layers "F.Cu" "B.Cu")
		(net "PVCCIO_CPU1")
	)
	(via
		(at 165.2778 -58.8772)
		(size 0.5588)
		(drill 0.3048)
		(layers "F.Cu" "B.Cu")
		(net "PVCCIO_CPU1")
	)
	(via
		(at 120.500902 -84.631784)
		(size 0.508)
		(drill 0.254)
		(layers "F.Cu" "B.Cu")
		(net "PVCCIO_CPU1")
	)
	(via
		(at 118.499382 -66.305938)
		(size 0.508)
		(drill 0.254)
		(layers "F.Cu" "B.Cu")
		(net "PVCCIO_CPU1")
	)
	(via
		(at 130.802888 -89.584784)
		(size 0.508)
		(drill 0.254)
		(layers "F.Cu" "B.Cu")
		(net "PVCCIO_CPU1")
	)
	(via
		(at 138.529314 -87.108538)
		(size 0.508)
		(drill 0.254)
		(layers "F.Cu" "B.Cu")
		(net "PVCCIO_CPU1")
	)
	(via
		(at 119.357902 -73.735184)
		(size 0.508)
		(drill 0.254)
		(layers "F.Cu" "B.Cu")
		(net "PVCCIO_CPU1")
	)
	(via
		(at 135.095234 -63.334138)
		(size 0.508)
		(drill 0.254)
		(layers "F.Cu" "B.Cu")
		(net "PVCCIO_CPU1")
	)
	(via
		(at 123.076208 -73.240138)
		(size 0.508)
		(drill 0.254)
		(layers "F.Cu" "B.Cu")
		(net "PVCCIO_CPU1")
	)
	(via
		(at 130.802888 -86.612984)
		(size 0.508)
		(drill 0.254)
		(layers "F.Cu" "B.Cu")
		(net "PVCCIO_CPU1")
	)
	(via
		(at 162.951414 -61.932312)
		(size 0.5588)
		(drill 0.3048)
		(layers "F.Cu" "B.Cu")
		(net "PVCCIO_CPU1")
	)
	(via
		(at 135.953754 -56.894984)
		(size 0.508)
		(drill 0.254)
		(layers "F.Cu" "B.Cu")
		(net "PVCCIO_CPU1")
	)
	(via
		(at 158.3436 -120.9802)
		(size 0.508)
		(drill 0.254)
		(layers "F.Cu" "B.Cu")
		(net "PVCCIO_CPU1")
	)
	(via
		(at 164.4904 -58.2168)
		(size 0.5588)
		(drill 0.3048)
		(layers "F.Cu" "B.Cu")
		(net "PVCCIO_CPU1")
	)
	(via
		(at 113.575592 -70.825614)
		(size 0.508)
		(drill 0.254)
		(layers "F.Cu" "B.Cu")
		(net "PVCCIO_CPU1")
	)
	(via
		(at 132.519674 -93.547184)
		(size 0.508)
		(drill 0.254)
		(layers "F.Cu" "B.Cu")
		(net "PVCCIO_CPU1")
	)
	(via
		(at 166.9415 0.5207)
		(size 0.508)
		(drill 0.254)
		(layers "F.Cu" "B.Cu")
		(net "PVCCIO_CPU1")
	)
	(via
		(at 15.6972 -48.6664)
		(size 0.508)
		(drill 0.254)
		(layers "F.Cu" "B.Cu")
		(net "PVCCIO_CPU1")
	)
	(via
		(at 165.2778 -56.896)
		(size 0.5588)
		(drill 0.3048)
		(layers "F.Cu" "B.Cu")
		(net "PVCCIO_CPU1")
	)
	(via
		(at 132.519674 -81.659984)
		(size 0.508)
		(drill 0.254)
		(layers "F.Cu" "B.Cu")
		(net "PVCCIO_CPU1")
	)
	(via
		(at 139.387834 -85.622384)
		(size 0.508)
		(drill 0.254)
		(layers "F.Cu" "B.Cu")
		(net "PVCCIO_CPU1")
	)
	(via
		(at 180.467 -57.023)
		(size 0.508)
		(drill 0.254)
		(layers "F.Cu" "B.Cu")
		(net "PVCCIO_CPU1")
	)
	(via
		(at 117.640862 -66.800984)
		(size 0.508)
		(drill 0.254)
		(layers "F.Cu" "B.Cu")
		(net "PVCCIO_CPU1")
	)
	(via
		(at 135.953754 -64.819784)
		(size 0.508)
		(drill 0.254)
		(layers "F.Cu" "B.Cu")
		(net "PVCCIO_CPU1")
	)
	(via
		(at 112.489742 -63.829184)
		(size 0.508)
		(drill 0.254)
		(layers "F.Cu" "B.Cu")
		(net "PVCCIO_CPU1")
	)
	(via
		(at 139.387834 -63.829184)
		(size 0.508)
		(drill 0.254)
		(layers "F.Cu" "B.Cu")
		(net "PVCCIO_CPU1")
	)
	(via
		(at 141.104874 -58.876438)
		(size 0.508)
		(drill 0.254)
		(layers "F.Cu" "B.Cu")
		(net "PVCCIO_CPU1")
	)
	(via
		(at 162.9664 -56.2356)
		(size 0.5588)
		(drill 0.3048)
		(layers "F.Cu" "B.Cu")
		(net "PVCCIO_CPU1")
	)
	(via
		(at 355.9302 -37.9984)
		(size 0.508)
		(drill 0.254)
		(layers "F.Cu" "B.Cu")
		(net "PVCCIO_CPU1")
	)
	(via
		(at 162.951414 -60.611512)
		(size 0.5588)
		(drill 0.3048)
		(layers "F.Cu" "B.Cu")
		(net "PVCCIO_CPU1")
	)
	(via
		(at 429.8442 -14.4526)
		(size 0.508)
		(drill 0.254)
		(layers "F.Cu" "B.Cu")
		(net "PVCCIO_CPU1")
	)
	(via
		(at 138.529314 -60.362338)
		(size 0.508)
		(drill 0.254)
		(layers "F.Cu" "B.Cu")
		(net "PVCCIO_CPU1")
	)
	(via
		(at 137.670794 -52.932584)
		(size 0.508)
		(drill 0.254)
		(layers "F.Cu" "B.Cu")
		(net "PVCCIO_CPU1")
	)
	(via
		(at 24.129492 -122.329448)
		(size 0.508)
		(drill 0.254)
		(layers "F.Cu" "B.Cu")
		(net "PVCCIO_CPU1")
	)
	(via
		(at 135.095234 -61.352938)
		(size 0.508)
		(drill 0.254)
		(layers "F.Cu" "B.Cu")
		(net "PVCCIO_CPU1")
	)
	(via
		(at 162.9664 -58.2168)
		(size 0.5588)
		(drill 0.3048)
		(layers "F.Cu" "B.Cu")
		(net "PVCCIO_CPU1")
	)
	(via
		(at 118.499382 -68.287138)
		(size 0.508)
		(drill 0.254)
		(layers "F.Cu" "B.Cu")
		(net "PVCCIO_CPU1")
	)
	(via
		(at 114.173 -78.6892)
		(size 0.508)
		(drill 0.254)
		(layers "F.Cu" "B.Cu")
		(net "PVCCIO_CPU1")
	)
	(via
		(at 166.0525 -57.277)
		(size 0.5588)
		(drill 0.3048)
		(layers "F.Cu" "B.Cu")
		(net "PVCCIO_CPU1")
	)
	(via
		(at 374.080532 -54.98973)
		(size 0.508)
		(drill 0.254)
		(layers "F.Cu" "B.Cu")
		(net "PVCCIO_CPU1")
	)
	(via
		(at 163.93922 -7.891018)
		(size 0.508)
		(drill 0.254)
		(layers "F.Cu" "B.Cu")
		(net "PVCCIO_CPU1")
	)
	(via
		(at 120.500902 -69.772784)
		(size 0.508)
		(drill 0.254)
		(layers "F.Cu" "B.Cu")
		(net "PVCCIO_CPU1")
	)
	(via
		(at 164.4904 -21.3868)
		(size 0.508)
		(drill 0.254)
		(layers "F.Cu" "B.Cu")
		(net "PVCCIO_CPU1")
	)
	(via
		(at 163.703 -58.2168)
		(size 0.5588)
		(drill 0.3048)
		(layers "F.Cu" "B.Cu")
		(net "PVCCIO_CPU1")
	)
	(via
		(at 125.651768 -93.547184)
		(size 0.508)
		(drill 0.254)
		(layers "F.Cu" "B.Cu")
		(net "PVCCIO_CPU1")
	)
	(via
		(at 173.587918 -92.702888)
		(size 0.508)
		(drill 0.254)
		(layers "F.Cu" "B.Cu")
		(net "PVCCIO_CPU1")
	)
	(via
		(at 131.661408 -93.052138)
		(size 0.508)
		(drill 0.254)
		(layers "F.Cu" "B.Cu")
		(net "PVCCIO_CPU1")
	)
	(via
		(at 121.359168 -70.268084)
		(size 0.508)
		(drill 0.254)
		(layers "F.Cu" "B.Cu")
		(net "PVCCIO_CPU1")
	)
	(via
		(at 121.359168 -72.249538)
		(size 0.508)
		(drill 0.254)
		(layers "F.Cu" "B.Cu")
		(net "PVCCIO_CPU1")
	)
	(via
		(at 113.538 -78.6892)
		(size 0.508)
		(drill 0.254)
		(layers "F.Cu" "B.Cu")
		(net "PVCCIO_CPU1")
	)
	(via
		(at 125.651768 -95.528384)
		(size 0.508)
		(drill 0.254)
		(layers "F.Cu" "B.Cu")
		(net "PVCCIO_CPU1")
	)
	(via
		(at 139.387834 -66.800984)
		(size 0.508)
		(drill 0.254)
		(layers "F.Cu" "B.Cu")
		(net "PVCCIO_CPU1")
	)
	(via
		(at 161.798254 -56.422798)
		(size 0.5588)
		(drill 0.3048)
		(layers "F.Cu" "B.Cu")
		(net "PVCCIO_CPU1")
	)
	(via
		(at 123.076208 -75.221338)
		(size 0.508)
		(drill 0.254)
		(layers "F.Cu" "B.Cu")
		(net "PVCCIO_CPU1")
	)
	(via
		(at 121.359168 -76.211938)
		(size 0.508)
		(drill 0.254)
		(layers "F.Cu" "B.Cu")
		(net "PVCCIO_CPU1")
	)
	(via
		(at 125.651768 -89.584784)
		(size 0.508)
		(drill 0.254)
		(layers "F.Cu" "B.Cu")
		(net "PVCCIO_CPU1")
	)
	(via
		(at 332.764892 -38.11016)
		(size 0.508)
		(drill 0.254)
		(layers "F.Cu" "B.Cu")
		(net "PVCCIO_CPU1")
	)
	(via
		(at 121.359168 -75.221338)
		(size 0.508)
		(drill 0.254)
		(layers "F.Cu" "B.Cu")
		(net "PVCCIO_CPU1")
	)
	(via
		(at 16.8529 -88.3793)
		(size 0.508)
		(drill 0.254)
		(layers "F.Cu" "B.Cu")
		(net "PVCCIO_CPU1")
	)
	(via
		(at 137.670794 -94.538038)
		(size 0.508)
		(drill 0.254)
		(layers "F.Cu" "B.Cu")
		(net "PVCCIO_CPU1")
	)
	(via
		(at 112.489742 -62.838584)
		(size 0.508)
		(drill 0.254)
		(layers "F.Cu" "B.Cu")
		(net "PVCCIO_CPU1")
	)
	(via
		(at 119.357902 -70.763384)
		(size 0.508)
		(drill 0.254)
		(layers "F.Cu" "B.Cu")
		(net "PVCCIO_CPU1")
	)
	(via
		(at 131.661408 -91.070938)
		(size 0.508)
		(drill 0.254)
		(layers "F.Cu" "B.Cu")
		(net "PVCCIO_CPU1")
	)
	(via
		(at 165.735 -69.4944)
		(size 0.508)
		(drill 0.254)
		(layers "F.Cu" "B.Cu")
		(net "PVCCIO_CPU1")
	)
	(via
		(at 119.070882 -84.555838)
		(size 0.508)
		(drill 0.254)
		(layers "F.Cu" "B.Cu")
		(net "PVCCIO_CPU1")
	)
	(via
		(at -1.6891 -123.9012)
		(size 0.508)
		(drill 0.254)
		(layers "F.Cu" "B.Cu")
		(net "PVCCIO_CPU1")
	)
	(via
		(at 161.798254 -58.403998)
		(size 0.5588)
		(drill 0.3048)
		(layers "F.Cu" "B.Cu")
		(net "PVCCIO_CPU1")
	)
	(via
		(at 134.236714 -70.763384)
		(size 0.508)
		(drill 0.254)
		(layers "F.Cu" "B.Cu")
		(net "PVCCIO_CPU1")
	)
	(via
		(at 162.38728 -68.072)
		(size 0.508)
		(drill 0.254)
		(layers "F.Cu" "B.Cu")
		(net "PVCCIO_CPU1")
	)
	(via
		(at 129.944368 -95.033084)
		(size 0.508)
		(drill 0.254)
		(layers "F.Cu" "B.Cu")
		(net "PVCCIO_CPU1")
	)
	(via
		(at 113.348262 -64.324738)
		(size 0.508)
		(drill 0.254)
		(layers "F.Cu" "B.Cu")
		(net "PVCCIO_CPU1")
	)
	(via
		(at 129.944368 -87.108538)
		(size 0.508)
		(drill 0.254)
		(layers "F.Cu" "B.Cu")
		(net "PVCCIO_CPU1")
	)
	(segment
		(start 373.8372 -47.486316)
		(end 373.477028 -47.846488)
		(width 0.254)
		(layer "B.Cu")
		(net "PVCCIO_CPU1")
	)
	(segment
		(start 177.906426 -21.0439)
		(end 177.576226 -21.0439)
		(width 0.254)
		(layer "B.Cu")
		(net "PVCCIO_CPU1")
	)
	(segment
		(start 14.35608 -4.047744)
		(end 13.630148 -3.321812)
		(width 0.4064)
		(layer "B.Cu")
		(net "PVCCIO_CPU1")
	)
	(segment
		(start 166.7002 0.2794)
		(end 166.9415 0.5207)
		(width 0.4064)
		(layer "B.Cu")
		(net "PVCCIO_CPU1")
	)
	(segment
		(start 169.770552 -23.562564)
		(end 169.770552 -23.929848)
		(width 0.254)
		(layer "B.Cu")
		(net "PVCCIO_CPU1")
	)
	(segment
		(start 157.52572 -120.9802)
		(end 157.08122 -121.4247)
		(width 0.254)
		(layer "B.Cu")
		(net "PVCCIO_CPU1")
	)
	(segment
		(start 163.93922 -7.891018)
		(end 164.998908 -8.950706)
		(width 0.254)
		(layer "B.Cu")
		(net "PVCCIO_CPU1")
	)
	(segment
		(start 17.399 -88.9254)
		(end 17.399 -89.281)
		(width 0.254)
		(layer "B.Cu")
		(net "PVCCIO_CPU1")
	)
	(segment
		(start 157.4165 -124.0917)
		(end 158.0134 -123.4948)
		(width 0.254)
		(layer "B.Cu")
		(net "PVCCIO_CPU1")
	)
	(segment
		(start 158.3436 -120.9802)
		(end 157.52572 -120.9802)
		(width 0.254)
		(layer "B.Cu")
		(net "PVCCIO_CPU1")
	)
	(segment
		(start 373.8372 -46.8376)
		(end 373.8372 -47.486316)
		(width 0.254)
		(layer "B.Cu")
		(net "PVCCIO_CPU1")
	)
	(segment
		(start 169.8498 -10.1854)
		(end 169.8498 -16.129)
		(width 0.254)
		(layer "B.Cu")
		(net "PVCCIO_CPU1")
	)
	(segment
		(start -3.47726 -117.89156)
		(end -2.20726 -117.89156)
		(width 0.254)
		(layer "B.Cu")
		(net "PVCCIO_CPU1")
	)
	(segment
		(start 158.0134 -123.4948)
		(end 158.0134 -122.3518)
		(width 0.254)
		(layer "B.Cu")
		(net "PVCCIO_CPU1")
	)
	(segment
		(start 166.31666 -0.75184)
		(end 166.7002 -0.3683)
		(width 0.4064)
		(layer "B.Cu")
		(net "PVCCIO_CPU1")
	)
	(segment
		(start 164.973 -69.088)
		(end 164.973 -68.199)
		(width 0.254)
		(layer "B.Cu")
		(net "PVCCIO_CPU1")
	)
	(segment
		(start 165.4048 -69.4944)
		(end 165.735 -69.4944)
		(width 0.254)
		(layer "B.Cu")
		(net "PVCCIO_CPU1")
	)
	(segment
		(start 16.3068 -4.416806)
		(end 15.937738 -4.047744)
		(width 0.4064)
		(layer "B.Cu")
		(net "PVCCIO_CPU1")
	)
	(segment
		(start 157.08122 -124.0917)
		(end 157.08122 -124.8537)
		(width 0.4572)
		(layer "B.Cu")
		(net "PVCCIO_CPU1")
	)
	(segment
		(start 16.8529 -88.3793)
		(end 17.399 -88.9254)
		(width 0.254)
		(layer "B.Cu")
		(net "PVCCIO_CPU1")
	)
	(segment
		(start 18.288 -87.7062)
		(end 17.526 -87.7062)
		(width 0.254)
		(layer "B.Cu")
		(net "PVCCIO_CPU1")
	)
	(segment
		(start 166.7002 -0.3683)
		(end 166.7002 0.2794)
		(width 0.4064)
		(layer "B.Cu")
		(net "PVCCIO_CPU1")
	)
	(segment
		(start 168.013634 -23.562564)
		(end 167.616124 -23.562564)
		(width 0.254)
		(layer "B.Cu")
		(net "PVCCIO_CPU1")
	)
	(segment
		(start -3.47726 -117.89156)
		(end -3.47726 -118.39956)
		(width 0.254)
		(layer "B.Cu")
		(net "PVCCIO_CPU1")
	)
	(segment
		(start 373.6975 -55.372762)
		(end 373.6975 -55.88)
		(width 0.254)
		(layer "B.Cu")
		(net "PVCCIO_CPU1")
	)
	(segment
		(start 163.93922 -7.891018)
		(end 163.93922 -1.94818)
		(width 0.4064)
		(layer "B.Cu")
		(net "PVCCIO_CPU1")
	)
	(segment
		(start 163.93922 -1.94818)
		(end 165.13556 -0.75184)
		(width 0.4064)
		(layer "B.Cu")
		(net "PVCCIO_CPU1")
	)
	(segment
		(start 177.0888 -20.193)
		(end 177.1015 -20.2057)
		(width 0.254)
		(layer "B.Cu")
		(net "PVCCIO_CPU1")
	)
	(segment
		(start 169.8498 -16.129)
		(end 170.5356 -16.8148)
		(width 0.254)
		(layer "B.Cu")
		(net "PVCCIO_CPU1")
	)
	(segment
		(start -2.5146 -126.2634)
		(end -2.5146 -127.7112)
		(width 0.254)
		(layer "B.Cu")
		(net "PVCCIO_CPU1")
	)
	(segment
		(start 170.5356 -21.6408)
		(end 170.8912 -21.9964)
		(width 0.254)
		(layer "B.Cu")
		(net "PVCCIO_CPU1")
	)
	(segment
		(start 164.973 -69.088)
		(end 164.9984 -69.088)
		(width 0.254)
		(layer "B.Cu")
		(net "PVCCIO_CPU1")
	)
	(segment
		(start 169.6212 -24.0792)
		(end 168.53027 -24.0792)
		(width 0.254)
		(layer "B.Cu")
		(net "PVCCIO_CPU1")
	)
	(segment
		(start 374.080532 -54.98973)
		(end 373.6975 -55.372762)
		(width 0.254)
		(layer "B.Cu")
		(net "PVCCIO_CPU1")
	)
	(segment
		(start -1.6891 -125.4379)
		(end -2.5146 -126.2634)
		(width 0.254)
		(layer "B.Cu")
		(net "PVCCIO_CPU1")
	)
	(segment
		(start 168.615106 -8.950706)
		(end 169.8498 -10.1854)
		(width 0.254)
		(layer "B.Cu")
		(net "PVCCIO_CPU1")
	)
	(segment
		(start 168.53027 -24.0792)
		(end 168.013634 -23.562564)
		(width 0.254)
		(layer "B.Cu")
		(net "PVCCIO_CPU1")
	)
	(segment
		(start 166.7256 0.5207)
		(end 166.9415 0.5207)
		(width 0.4064)
		(layer "B.Cu")
		(net "PVCCIO_CPU1")
	)
	(segment
		(start 170.493436 -23.562564)
		(end 169.770552 -23.562564)
		(width 0.254)
		(layer "B.Cu")
		(net "PVCCIO_CPU1")
	)
	(segment
		(start 165.13556 -0.75184)
		(end 166.31666 -0.75184)
		(width 0.4064)
		(layer "B.Cu")
		(net "PVCCIO_CPU1")
	)
	(segment
		(start 11.313668 -3.321812)
		(end 10.551668 -3.321812)
		(width 0.4064)
		(layer "B.Cu")
		(net "PVCCIO_CPU1")
	)
	(segment
		(start 170.8912 -21.9964)
		(end 170.8912 -23.1648)
		(width 0.254)
		(layer "B.Cu")
		(net "PVCCIO_CPU1")
	)
	(segment
		(start 177.0888 -20.556474)
		(end 177.0888 -20.193)
		(width 0.254)
		(layer "B.Cu")
		(net "PVCCIO_CPU1")
	)
	(segment
		(start 164.9984 -69.088)
		(end 165.4048 -69.4944)
		(width 0.254)
		(layer "B.Cu")
		(net "PVCCIO_CPU1")
	)
	(segment
		(start 170.5356 -16.8148)
		(end 170.5356 -21.6408)
		(width 0.254)
		(layer "B.Cu")
		(net "PVCCIO_CPU1")
	)
	(segment
		(start 158.3436 -122.0216)
		(end 158.3436 -120.9802)
		(width 0.254)
		(layer "B.Cu")
		(net "PVCCIO_CPU1")
	)
	(segment
		(start 166.3192 0.9271)
		(end 166.7256 0.5207)
		(width 0.4064)
		(layer "B.Cu")
		(net "PVCCIO_CPU1")
	)
	(segment
		(start 17.526 -87.7062)
		(end 16.8529 -88.3793)
		(width 0.254)
		(layer "B.Cu")
		(net "PVCCIO_CPU1")
	)
	(segment
		(start 113.361724 -69.809614)
		(end 112.378236 -68.826126)
		(width 0.254)
		(layer "B.Cu")
		(net "PVCCIO_CPU1")
	)
	(segment
		(start 170.8912 -23.1648)
		(end 170.493436 -23.562564)
		(width 0.254)
		(layer "B.Cu")
		(net "PVCCIO_CPU1")
	)
	(segment
		(start 157.08122 -124.0917)
		(end 157.4165 -124.0917)
		(width 0.254)
		(layer "B.Cu")
		(net "PVCCIO_CPU1")
	)
	(segment
		(start 15.937738 -4.047744)
		(end 14.35608 -4.047744)
		(width 0.4064)
		(layer "B.Cu")
		(net "PVCCIO_CPU1")
	)
	(segment
		(start 13.630148 -3.321812)
		(end 11.313668 -3.321812)
		(width 0.4064)
		(layer "B.Cu")
		(net "PVCCIO_CPU1")
	)
	(segment
		(start 164.998908 -8.950706)
		(end 168.615106 -8.950706)
		(width 0.254)
		(layer "B.Cu")
		(net "PVCCIO_CPU1")
	)
	(segment
		(start 177.1015 -20.2057)
		(end 177.906426 -20.2057)
		(width 0.254)
		(layer "B.Cu")
		(net "PVCCIO_CPU1")
	)
	(segment
		(start 158.0134 -122.3518)
		(end 158.3436 -122.0216)
		(width 0.254)
		(layer "B.Cu")
		(net "PVCCIO_CPU1")
	)
	(segment
		(start -1.6891 -123.9012)
		(end -1.6891 -125.4379)
		(width 0.254)
		(layer "B.Cu")
		(net "PVCCIO_CPU1")
	)
	(segment
		(start 177.576226 -21.0439)
		(end 177.0888 -20.556474)
		(width 0.254)
		(layer "B.Cu")
		(net "PVCCIO_CPU1")
	)
	(segment
		(start -1.7272 -117.89156)
		(end -1.5494 -118.06936)
		(width 0.254)
		(layer "B.Cu")
		(net "PVCCIO_CPU1")
	)
	(segment
		(start 166.3192 1.2192)
		(end 166.3192 0.9271)
		(width 0.4064)
		(layer "B.Cu")
		(net "PVCCIO_CPU1")
	)
	(segment
		(start 169.770552 -23.929848)
		(end 169.6212 -24.0792)
		(width 0.254)
		(layer "B.Cu")
		(net "PVCCIO_CPU1")
	)
	(segment
		(start -2.5146 -128.6002)
		(end -2.5146 -127.7112)
		(width 0.254)
		(layer "B.Cu")
		(net "PVCCIO_CPU1")
	)
	(segment
		(start -2.20726 -117.89156)
		(end -1.7272 -117.89156)
		(width 0.254)
		(layer "B.Cu")
		(net "PVCCIO_CPU1")
	)
	(segment
		(start 113.575592 -69.809614)
		(end 113.361724 -69.809614)
		(width 0.254)
		(layer "B.Cu")
		(net "PVCCIO_CPU1")
	)
	(segment
		(start -3.47726 -118.39956)
		(end -3.09626 -118.78056)
		(width 0.254)
		(layer "B.Cu")
		(net "PVCCIO_CPU1")
	)
	(segment
		(start 112.378236 -68.826126)
		(end 112.378236 -68.603114)
		(width 0.254)
		(layer "B.Cu")
		(net "PVCCIO_CPU1")
	)
	(segment
		(start 7.51332 -123.08332)
		(end 8.226298 -123.796298)
		(width 0.254)
		(layer "In2.Cu")
		(net "PVCCIO_CPU1")
	)
	(segment
		(start 26.797 -17.8562)
		(end 26.2382 -17.2974)
		(width 0.381)
		(layer "In2.Cu")
		(net "PVCCIO_CPU1")
	)
	(segment
		(start 163.1696 -88.9762)
		(end 165.726872 -91.533472)
		(width 0.254)
		(layer "In2.Cu")
		(net "PVCCIO_CPU1")
	)
	(segment
		(start 163.0934 -113.8174)
		(end 164.5412 -112.3696)
		(width 0.254)
		(layer "In2.Cu")
		(net "PVCCIO_CPU1")
	)
	(segment
		(start 165.726872 -91.533472)
		(end 172.914056 -91.533472)
		(width 0.254)
		(layer "In2.Cu")
		(net "PVCCIO_CPU1")
	)
	(segment
		(start 10.4902 -123.19)
		(end 19.558 -123.19)
		(width 0.254)
		(layer "In2.Cu")
		(net "PVCCIO_CPU1")
	)
	(segment
		(start 159.014668 -116.346732)
		(end 161.544 -113.8174)
		(width 0.254)
		(layer "In2.Cu")
		(net "PVCCIO_CPU1")
	)
	(segment
		(start 16.6116 -87.6554)
		(end 15.2654 -87.6554)
		(width 0.4064)
		(layer "In2.Cu")
		(net "PVCCIO_CPU1")
	)
	(segment
		(start 21.410676 -23.605744)
		(end 21.840952 -23.175468)
		(width 0.381)
		(layer "In2.Cu")
		(net "PVCCIO_CPU1")
	)
	(segment
		(start 19.949922 -25.455372)
		(end 21.410676 -23.994618)
		(width 0.381)
		(layer "In2.Cu")
		(net "PVCCIO_CPU1")
	)
	(segment
		(start 164.5412 -112.3696)
		(end 164.5412 -103.3526)
		(width 0.254)
		(layer "In2.Cu")
		(net "PVCCIO_CPU1")
	)
	(segment
		(start 161.544 -113.8174)
		(end 163.0934 -113.8174)
		(width 0.254)
		(layer "In2.Cu")
		(net "PVCCIO_CPU1")
	)
	(segment
		(start 22.76094 -112.93094)
		(end 22.76094 -119.747538)
		(width 0.4064)
		(layer "In2.Cu")
		(net "PVCCIO_CPU1")
	)
	(segment
		(start 170.8404 -96.3676)
		(end 171.7548 -95.4532)
		(width 0.254)
		(layer "In2.Cu")
		(net "PVCCIO_CPU1")
	)
	(segment
		(start 17.695926 -27.369262)
		(end 17.695926 -26.042874)
		(width 0.381)
		(layer "In2.Cu")
		(net "PVCCIO_CPU1")
	)
	(segment
		(start 172.914056 -91.533472)
		(end 173.595284 -92.2147)
		(width 0.254)
		(layer "In2.Cu")
		(net "PVCCIO_CPU1")
	)
	(segment
		(start 18.5293 -38.3159)
		(end 18.9484 -37.8968)
		(width 0.381)
		(layer "In2.Cu")
		(net "PVCCIO_CPU1")
	)
	(segment
		(start 14.919198 -102.059486)
		(end 14.919198 -103.066596)
		(width 0.4064)
		(layer "In2.Cu")
		(net "PVCCIO_CPU1")
	)
	(segment
		(start -1.3462 -123.9012)
		(end -0.52832 -123.08332)
		(width 0.254)
		(layer "In2.Cu")
		(net "PVCCIO_CPU1")
	)
	(segment
		(start 311.868058 -43.033696)
		(end 309.803546 -43.033696)
		(width 0.254)
		(layer "In2.Cu")
		(net "PVCCIO_CPU1")
	)
	(segment
		(start 321.215512 -40.417242)
		(end 314.484512 -40.417242)
		(width 0.254)
		(layer "In2.Cu")
		(net "PVCCIO_CPU1")
	)
	(segment
		(start 26.043128 -21.177504)
		(end 26.797 -20.423632)
		(width 0.381)
		(layer "In2.Cu")
		(net "PVCCIO_CPU1")
	)
	(segment
		(start 166.011606 -21.3614)
		(end 164.5158 -21.3614)
		(width 0.4064)
		(layer "In2.Cu")
		(net "PVCCIO_CPU1")
	)
	(segment
		(start -1.6891 -123.9012)
		(end -1.3462 -123.9012)
		(width 0.254)
		(layer "In2.Cu")
		(net "PVCCIO_CPU1")
	)
	(segment
		(start 21.840952 -23.175468)
		(end 22.114256 -23.175468)
		(width 0.381)
		(layer "In2.Cu")
		(net "PVCCIO_CPU1")
	)
	(segment
		(start 23.34514 -123.1138)
		(end 24.129492 -122.329448)
		(width 0.254)
		(layer "In2.Cu")
		(net "PVCCIO_CPU1")
	)
	(segment
		(start 309.803546 -43.033696)
		(end 307.094382 -45.74286)
		(width 0.254)
		(layer "In2.Cu")
		(net "PVCCIO_CPU1")
	)
	(segment
		(start 15.6972 -48.6664)
		(end 16.93545 -47.42815)
		(width 0.381)
		(layer "In2.Cu")
		(net "PVCCIO_CPU1")
	)
	(segment
		(start 166.418006 -21.7678)
		(end 166.011606 -21.3614)
		(width 0.4064)
		(layer "In2.Cu")
		(net "PVCCIO_CPU1")
	)
	(segment
		(start 16.8402 -87.884)
		(end 16.6116 -87.6554)
		(width 0.4064)
		(layer "In2.Cu")
		(net "PVCCIO_CPU1")
	)
	(segment
		(start 24.022812 -121.00941)
		(end 24.022812 -122.222768)
		(width 0.4064)
		(layer "In2.Cu")
		(net "PVCCIO_CPU1")
	)
	(segment
		(start 161.202878 -31.095442)
		(end 161.822384 -30.475936)
		(width 0.4064)
		(layer "In2.Cu")
		(net "PVCCIO_CPU1")
	)
	(segment
		(start 165.735 -69.4944)
		(end 165.735 -70.94982)
		(width 0.254)
		(layer "In2.Cu")
		(net "PVCCIO_CPU1")
	)
	(segment
		(start -0.52832 -123.08332)
		(end 7.51332 -123.08332)
		(width 0.254)
		(layer "In2.Cu")
		(net "PVCCIO_CPU1")
	)
	(segment
		(start 22.76094 -119.747538)
		(end 24.022812 -121.00941)
		(width 0.4064)
		(layer "In2.Cu")
		(net "PVCCIO_CPU1")
	)
	(segment
		(start 171.7548 -95.4532)
		(end 171.7548 -94.543372)
		(width 0.254)
		(layer "In2.Cu")
		(net "PVCCIO_CPU1")
	)
	(segment
		(start 164.395912 -27.526488)
		(end 166.418006 -25.504394)
		(width 0.4064)
		(layer "In2.Cu")
		(net "PVCCIO_CPU1")
	)
	(segment
		(start 159.132778 -31.095442)
		(end 161.202878 -31.095442)
		(width 0.4064)
		(layer "In2.Cu")
		(net "PVCCIO_CPU1")
	)
	(segment
		(start 17.695926 -26.042874)
		(end 18.283428 -25.455372)
		(width 0.381)
		(layer "In2.Cu")
		(net "PVCCIO_CPU1")
	)
	(segment
		(start 17.9324 -27.605736)
		(end 17.695926 -27.369262)
		(width 0.381)
		(layer "In2.Cu")
		(net "PVCCIO_CPU1")
	)
	(segment
		(start 18.5293 -39.1287)
		(end 18.5293 -38.3159)
		(width 0.381)
		(layer "In2.Cu")
		(net "PVCCIO_CPU1")
	)
	(segment
		(start 15.2654 -87.6554)
		(end 14.3256 -88.5952)
		(width 0.4064)
		(layer "In2.Cu")
		(net "PVCCIO_CPU1")
	)
	(segment
		(start 332.764892 -38.11016)
		(end 329.820524 -38.11016)
		(width 0.254)
		(layer "In2.Cu")
		(net "PVCCIO_CPU1")
	)
	(segment
		(start 164.4904 -19.929094)
		(end 164.4904 -21.3868)
		(width 0.4064)
		(layer "In2.Cu")
		(net "PVCCIO_CPU1")
	)
	(segment
		(start 24.927814 -24.353012)
		(end 26.043128 -23.237698)
		(width 0.381)
		(layer "In2.Cu")
		(net "PVCCIO_CPU1")
	)
	(segment
		(start 26.043128 -23.237698)
		(end 26.043128 -21.177504)
		(width 0.381)
		(layer "In2.Cu")
		(net "PVCCIO_CPU1")
	)
	(segment
		(start 18.283428 -25.455372)
		(end 19.949922 -25.455372)
		(width 0.381)
		(layer "In2.Cu")
		(net "PVCCIO_CPU1")
	)
	(segment
		(start 328.09434 -37.108384)
		(end 324.713092 -40.489632)
		(width 0.254)
		(layer "In2.Cu")
		(net "PVCCIO_CPU1")
	)
	(segment
		(start 19.6342 -123.1138)
		(end 23.34514 -123.1138)
		(width 0.254)
		(layer "In2.Cu")
		(net "PVCCIO_CPU1")
	)
	(segment
		(start 21.734526 -4.416806)
		(end 16.3068 -4.416806)
		(width 0.381)
		(layer "In2.Cu")
		(net "PVCCIO_CPU1")
	)
	(segment
		(start 161.822384 -30.475936)
		(end 161.822384 -28.266644)
		(width 0.4064)
		(layer "In2.Cu")
		(net "PVCCIO_CPU1")
	)
	(segment
		(start 158.3436 -120.9802)
		(end 159.014668 -120.309132)
		(width 0.254)
		(layer "In2.Cu")
		(net "PVCCIO_CPU1")
	)
	(segment
		(start 164.5412 -103.3526)
		(end 170.8404 -97.0534)
		(width 0.254)
		(layer "In2.Cu")
		(net "PVCCIO_CPU1")
	)
	(segment
		(start 17.9324 -29.464)
		(end 17.9324 -27.605736)
		(width 0.381)
		(layer "In2.Cu")
		(net "PVCCIO_CPU1")
	)
	(segment
		(start 24.022812 -122.222768)
		(end 24.129492 -122.329448)
		(width 0.4064)
		(layer "In2.Cu")
		(net "PVCCIO_CPU1")
	)
	(segment
		(start 164.995098 -76.35875)
		(end 163.1696 -78.184248)
		(width 0.254)
		(layer "In2.Cu")
		(net "PVCCIO_CPU1")
	)
	(segment
		(start 329.820524 -38.11016)
		(end 328.818748 -37.108384)
		(width 0.254)
		(layer "In2.Cu")
		(net "PVCCIO_CPU1")
	)
	(segment
		(start 164.995098 -71.689722)
		(end 164.995098 -76.35875)
		(width 0.254)
		(layer "In2.Cu")
		(net "PVCCIO_CPU1")
	)
	(segment
		(start 15.577058 -103.724456)
		(end 15.577058 -105.747058)
		(width 0.4064)
		(layer "In2.Cu")
		(net "PVCCIO_CPU1")
	)
	(segment
		(start 14.919198 -103.066596)
		(end 15.577058 -103.724456)
		(width 0.4064)
		(layer "In2.Cu")
		(net "PVCCIO_CPU1")
	)
	(segment
		(start 26.797 -20.423632)
		(end 26.797 -17.8562)
		(width 0.381)
		(layer "In2.Cu")
		(net "PVCCIO_CPU1")
	)
	(segment
		(start 16.8529 -88.3793)
		(end 16.8402 -88.3666)
		(width 0.4064)
		(layer "In2.Cu")
		(net "PVCCIO_CPU1")
	)
	(segment
		(start 134.823962 -70.697852)
		(end 134.75843 -70.763384)
		(width 0.254)
		(layer "In2.Cu")
		(net "PVCCIO_CPU1")
	)
	(segment
		(start 16.93545 -47.42815)
		(end 16.93545 -40.72255)
		(width 0.381)
		(layer "In2.Cu")
		(net "PVCCIO_CPU1")
	)
	(segment
		(start 166.418006 -25.504394)
		(end 166.418006 -21.7678)
		(width 0.4064)
		(layer "In2.Cu")
		(net "PVCCIO_CPU1")
	)
	(segment
		(start 173.595284 -92.2147)
		(end 173.595284 -92.702888)
		(width 0.254)
		(layer "In2.Cu")
		(net "PVCCIO_CPU1")
	)
	(segment
		(start 21.410676 -23.994618)
		(end 21.410676 -23.605744)
		(width 0.381)
		(layer "In2.Cu")
		(net "PVCCIO_CPU1")
	)
	(segment
		(start 19.558 -123.19)
		(end 19.6342 -123.1138)
		(width 0.254)
		(layer "In2.Cu")
		(net "PVCCIO_CPU1")
	)
	(segment
		(start 134.866888 -68.794376)
		(end 134.854696 -68.782184)
		(width 0.254)
		(layer "In2.Cu")
		(net "PVCCIO_CPU1")
	)
	(segment
		(start 23.2918 -24.353012)
		(end 24.927814 -24.353012)
		(width 0.381)
		(layer "In2.Cu")
		(net "PVCCIO_CPU1")
	)
	(segment
		(start 164.5158 -21.3614)
		(end 164.4904 -21.3868)
		(width 0.4064)
		(layer "In2.Cu")
		(net "PVCCIO_CPU1")
	)
	(segment
		(start 163.93922 -19.377914)
		(end 164.4904 -19.929094)
		(width 0.4064)
		(layer "In2.Cu")
		(net "PVCCIO_CPU1")
	)
	(segment
		(start 171.7548 -94.543372)
		(end 173.595284 -92.702888)
		(width 0.254)
		(layer "In2.Cu")
		(net "PVCCIO_CPU1")
	)
	(segment
		(start 13.234162 -92.517976)
		(end 13.234162 -100.37445)
		(width 0.4064)
		(layer "In2.Cu")
		(net "PVCCIO_CPU1")
	)
	(segment
		(start 134.854696 -68.782184)
		(end 134.236714 -68.782184)
		(width 0.254)
		(layer "In2.Cu")
		(net "PVCCIO_CPU1")
	)
	(segment
		(start 24.046434 -5.377434)
		(end 22.695154 -5.377434)
		(width 0.381)
		(layer "In2.Cu")
		(net "PVCCIO_CPU1")
	)
	(segment
		(start 9.883902 -123.796298)
		(end 10.4902 -123.19)
		(width 0.254)
		(layer "In2.Cu")
		(net "PVCCIO_CPU1")
	)
	(segment
		(start 324.713092 -40.489632)
		(end 321.287902 -40.489632)
		(width 0.254)
		(layer "In2.Cu")
		(net "PVCCIO_CPU1")
	)
	(segment
		(start 13.234162 -100.37445)
		(end 14.919198 -102.059486)
		(width 0.4064)
		(layer "In2.Cu")
		(net "PVCCIO_CPU1")
	)
	(segment
		(start 328.818748 -37.108384)
		(end 328.09434 -37.108384)
		(width 0.254)
		(layer "In2.Cu")
		(net "PVCCIO_CPU1")
	)
	(segment
		(start 162.56254 -27.526488)
		(end 164.395912 -27.526488)
		(width 0.4064)
		(layer "In2.Cu")
		(net "PVCCIO_CPU1")
	)
	(segment
		(start 159.014668 -120.309132)
		(end 159.014668 -116.346732)
		(width 0.254)
		(layer "In2.Cu")
		(net "PVCCIO_CPU1")
	)
	(segment
		(start 307.094382 -45.74286)
		(end 307.094382 -46.712378)
		(width 0.254)
		(layer "In2.Cu")
		(net "PVCCIO_CPU1")
	)
	(segment
		(start 22.695154 -5.377434)
		(end 21.734526 -4.416806)
		(width 0.381)
		(layer "In2.Cu")
		(net "PVCCIO_CPU1")
	)
	(segment
		(start 170.8404 -97.0534)
		(end 170.8404 -96.3676)
		(width 0.254)
		(layer "In2.Cu")
		(net "PVCCIO_CPU1")
	)
	(segment
		(start 26.2382 -7.5692)
		(end 24.046434 -5.377434)
		(width 0.381)
		(layer "In2.Cu")
		(net "PVCCIO_CPU1")
	)
	(segment
		(start 16.93545 -40.72255)
		(end 18.5293 -39.1287)
		(width 0.381)
		(layer "In2.Cu")
		(net "PVCCIO_CPU1")
	)
	(segment
		(start 158.018988 -32.209232)
		(end 159.132778 -31.095442)
		(width 0.4064)
		(layer "In2.Cu")
		(net "PVCCIO_CPU1")
	)
	(segment
		(start 142.24 -54.102)
		(end 158.018988 -38.323012)
		(width 0.4064)
		(layer "In2.Cu")
		(net "PVCCIO_CPU1")
	)
	(segment
		(start 163.93922 -7.891018)
		(end 163.93922 -19.377914)
		(width 0.4064)
		(layer "In2.Cu")
		(net "PVCCIO_CPU1")
	)
	(segment
		(start 142.24 -55.132732)
		(end 142.24 -54.102)
		(width 0.4064)
		(layer "In2.Cu")
		(net "PVCCIO_CPU1")
	)
	(segment
		(start 161.822384 -28.266644)
		(end 162.56254 -27.526488)
		(width 0.4064)
		(layer "In2.Cu")
		(net "PVCCIO_CPU1")
	)
	(segment
		(start 8.226298 -123.796298)
		(end 9.883902 -123.796298)
		(width 0.254)
		(layer "In2.Cu")
		(net "PVCCIO_CPU1")
	)
	(segment
		(start 158.018988 -38.323012)
		(end 158.018988 -32.209232)
		(width 0.4064)
		(layer "In2.Cu")
		(net "PVCCIO_CPU1")
	)
	(segment
		(start 163.1696 -78.184248)
		(end 163.1696 -88.9762)
		(width 0.254)
		(layer "In2.Cu")
		(net "PVCCIO_CPU1")
	)
	(segment
		(start 14.3256 -88.5952)
		(end 14.3256 -91.426538)
		(width 0.4064)
		(layer "In2.Cu")
		(net "PVCCIO_CPU1")
	)
	(segment
		(start 321.287902 -40.489632)
		(end 321.215512 -40.417242)
		(width 0.254)
		(layer "In2.Cu")
		(net "PVCCIO_CPU1")
	)
	(segment
		(start 18.9484 -37.8968)
		(end 18.9484 -30.48)
		(width 0.381)
		(layer "In2.Cu")
		(net "PVCCIO_CPU1")
	)
	(segment
		(start 26.2382 -17.2974)
		(end 26.2382 -7.5692)
		(width 0.381)
		(layer "In2.Cu")
		(net "PVCCIO_CPU1")
	)
	(segment
		(start 134.75843 -70.763384)
		(end 134.236714 -70.763384)
		(width 0.254)
		(layer "In2.Cu")
		(net "PVCCIO_CPU1")
	)
	(segment
		(start 141.963394 -55.409338)
		(end 142.24 -55.132732)
		(width 0.4064)
		(layer "In2.Cu")
		(net "PVCCIO_CPU1")
	)
	(segment
		(start 16.8402 -88.3666)
		(end 16.8402 -87.884)
		(width 0.4064)
		(layer "In2.Cu")
		(net "PVCCIO_CPU1")
	)
	(segment
		(start 165.735 -70.94982)
		(end 164.995098 -71.689722)
		(width 0.254)
		(layer "In2.Cu")
		(net "PVCCIO_CPU1")
	)
	(segment
		(start 22.114256 -23.175468)
		(end 23.2918 -24.353012)
		(width 0.381)
		(layer "In2.Cu")
		(net "PVCCIO_CPU1")
	)
	(segment
		(start 15.577058 -105.747058)
		(end 22.76094 -112.93094)
		(width 0.4064)
		(layer "In2.Cu")
		(net "PVCCIO_CPU1")
	)
	(segment
		(start 18.9484 -30.48)
		(end 17.9324 -29.464)
		(width 0.381)
		(layer "In2.Cu")
		(net "PVCCIO_CPU1")
	)
	(segment
		(start 173.595284 -92.702888)
		(end 173.587918 -92.702888)
		(width 0.254)
		(layer "In2.Cu")
		(net "PVCCIO_CPU1")
	)
	(segment
		(start 314.484512 -40.417242)
		(end 311.868058 -43.033696)
		(width 0.254)
		(layer "In2.Cu")
		(net "PVCCIO_CPU1")
	)
	(segment
		(start 14.3256 -91.426538)
		(end 13.234162 -92.517976)
		(width 0.4064)
		(layer "In2.Cu")
		(net "PVCCIO_CPU1")
	)
	(segment
		(start 94.970092 -148.191474)
		(end 94.595188 -147.81657)
		(width 0.3556)
		(layer "In4.Cu")
		(net "PVCCIO_CPU1")
	)
	(segment
		(start 156.548836 -130.979672)
		(end 156.8958 -131.326636)
		(width 0.3556)
		(layer "In4.Cu")
		(net "PVCCIO_CPU1")
	)
	(segment
		(start 24.129492 -122.772424)
		(end 24.129492 -122.329448)
		(width 0.3556)
		(layer "In4.Cu")
		(net "PVCCIO_CPU1")
	)
	(segment
		(start 96.87433 -147.28444)
		(end 95.967296 -148.191474)
		(width 0.3556)
		(layer "In4.Cu")
		(net "PVCCIO_CPU1")
	)
	(segment
		(start 27.099768 -125.7427)
		(end 24.129492 -122.772424)
		(width 0.3556)
		(layer "In4.Cu")
		(net "PVCCIO_CPU1")
	)
	(segment
		(start 27.099768 -127.875792)
		(end 27.099768 -125.7427)
		(width 0.3556)
		(layer "In4.Cu")
		(net "PVCCIO_CPU1")
	)
	(segment
		(start 24.129492 -121.920508)
		(end 34.40684 -111.64316)
		(width 0.4064)
		(layer "In4.Cu")
		(net "PVCCIO_CPU1")
	)
	(segment
		(start 91.228672 -151.539702)
		(end 90.070686 -152.697688)
		(width 0.3556)
		(layer "In4.Cu")
		(net "PVCCIO_CPU1")
	)
	(segment
		(start 174.91583 -20.731988)
		(end 173.643798 -22.00402)
		(width 0.254)
		(layer "In4.Cu")
		(net "PVCCIO_CPU1")
	)
	(segment
		(start 157.08122 -129.7686)
		(end 156.548836 -130.300984)
		(width 0.3556)
		(layer "In4.Cu")
		(net "PVCCIO_CPU1")
	)
	(segment
		(start 425.854368 -11.55192)
		(end 425.656248 -11.3538)
		(width 0.254)
		(layer "In4.Cu")
		(net "PVCCIO_CPU1")
	)
	(segment
		(start 30.569154 -156.6164)
		(end 27.8892 -153.936446)
		(width 0.4064)
		(layer "In4.Cu")
		(net "PVCCIO_CPU1")
	)
	(segment
		(start 429.02632 -11.55192)
		(end 425.854368 -11.55192)
		(width 0.254)
		(layer "In4.Cu")
		(net "PVCCIO_CPU1")
	)
	(segment
		(start 94.595188 -147.81657)
		(end 91.782392 -147.81657)
		(width 0.3556)
		(layer "In4.Cu")
		(net "PVCCIO_CPU1")
	)
	(segment
		(start 156.8958 -135.77316)
		(end 157.738318 -136.615678)
		(width 0.3556)
		(layer "In4.Cu")
		(net "PVCCIO_CPU1")
	)
	(segment
		(start 122.665998 -150.364952)
		(end 122.665998 -149.312376)
		(width 0.3556)
		(layer "In4.Cu")
		(net "PVCCIO_CPU1")
	)
	(segment
		(start 159.045402 -117.262402)
		(end 154.851608 -113.068608)
		(width 0.254)
		(layer "In4.Cu")
		(net "PVCCIO_CPU1")
	)
	(segment
		(start 27.8892 -153.936446)
		(end 27.8892 -128.665224)
		(width 0.4064)
		(layer "In4.Cu")
		(net "PVCCIO_CPU1")
	)
	(segment
		(start 88.902286 -155.77058)
		(end 88.576658 -156.096208)
		(width 0.3556)
		(layer "In4.Cu")
		(net "PVCCIO_CPU1")
	)
	(segment
		(start 176.549812 -20.731988)
		(end 174.91583 -20.731988)
		(width 0.254)
		(layer "In4.Cu")
		(net "PVCCIO_CPU1")
	)
	(segment
		(start 91.782392 -147.81657)
		(end 91.228672 -148.37029)
		(width 0.3556)
		(layer "In4.Cu")
		(net "PVCCIO_CPU1")
	)
	(segment
		(start 86.50986 -156.6164)
		(end 30.569154 -156.6164)
		(width 0.4064)
		(layer "In4.Cu")
		(net "PVCCIO_CPU1")
	)
	(segment
		(start 24.129492 -122.329448)
		(end 24.129492 -121.920508)
		(width 0.4064)
		(layer "In4.Cu")
		(net "PVCCIO_CPU1")
	)
	(segment
		(start 177.0888 -20.193)
		(end 176.549812 -20.731988)
		(width 0.254)
		(layer "In4.Cu")
		(net "PVCCIO_CPU1")
	)
	(segment
		(start 156.548836 -130.300984)
		(end 156.548836 -130.979672)
		(width 0.3556)
		(layer "In4.Cu")
		(net "PVCCIO_CPU1")
	)
	(segment
		(start 38.885876 -107.905804)
		(end 38.885876 -105.270808)
		(width 0.4064)
		(layer "In4.Cu")
		(net "PVCCIO_CPU1")
	)
	(segment
		(start 173.643798 -22.00402)
		(end 171.029884 -22.00402)
		(width 0.254)
		(layer "In4.Cu")
		(net "PVCCIO_CPU1")
	)
	(segment
		(start 122.665998 -149.312376)
		(end 122.882914 -149.09546)
		(width 0.3556)
		(layer "In4.Cu")
		(net "PVCCIO_CPU1")
	)
	(segment
		(start 86.857332 -156.6164)
		(end 86.50986 -156.6164)
		(width 0.3556)
		(layer "In4.Cu")
		(net "PVCCIO_CPU1")
	)
	(segment
		(start 154.851608 -113.068608)
		(end 150.422864 -113.068608)
		(width 0.254)
		(layer "In4.Cu")
		(net "PVCCIO_CPU1")
	)
	(segment
		(start 95.967296 -148.191474)
		(end 94.970092 -148.191474)
		(width 0.3556)
		(layer "In4.Cu")
		(net "PVCCIO_CPU1")
	)
	(segment
		(start 157.738318 -151.0792)
		(end 157.331918 -151.4856)
		(width 0.3556)
		(layer "In4.Cu")
		(net "PVCCIO_CPU1")
	)
	(segment
		(start 122.882914 -148.398484)
		(end 121.76887 -147.28444)
		(width 0.3556)
		(layer "In4.Cu")
		(net "PVCCIO_CPU1")
	)
	(segment
		(start 34.40684 -111.64316)
		(end 35.14852 -111.64316)
		(width 0.4064)
		(layer "In4.Cu")
		(net "PVCCIO_CPU1")
	)
	(segment
		(start 429.8442 -14.4526)
		(end 429.8442 -12.3698)
		(width 0.254)
		(layer "In4.Cu")
		(net "PVCCIO_CPU1")
	)
	(segment
		(start 171.029884 -22.00402)
		(end 170.057064 -21.0312)
		(width 0.254)
		(layer "In4.Cu")
		(net "PVCCIO_CPU1")
	)
	(segment
		(start 156.8958 -131.326636)
		(end 156.8958 -135.77316)
		(width 0.3556)
		(layer "In4.Cu")
		(net "PVCCIO_CPU1")
	)
	(segment
		(start 157.331918 -151.4856)
		(end 123.786646 -151.4856)
		(width 0.3556)
		(layer "In4.Cu")
		(net "PVCCIO_CPU1")
	)
	(segment
		(start 35.14852 -111.64316)
		(end 38.885876 -107.905804)
		(width 0.4064)
		(layer "In4.Cu")
		(net "PVCCIO_CPU1")
	)
	(segment
		(start 90.070686 -152.697688)
		(end 90.070686 -153.476706)
		(width 0.3556)
		(layer "In4.Cu")
		(net "PVCCIO_CPU1")
	)
	(segment
		(start 121.76887 -147.28444)
		(end 96.87433 -147.28444)
		(width 0.3556)
		(layer "In4.Cu")
		(net "PVCCIO_CPU1")
	)
	(segment
		(start 91.228672 -148.37029)
		(end 91.228672 -151.539702)
		(width 0.3556)
		(layer "In4.Cu")
		(net "PVCCIO_CPU1")
	)
	(segment
		(start 38.885876 -105.270808)
		(end 38.584886 -104.969818)
		(width 0.4064)
		(layer "In4.Cu")
		(net "PVCCIO_CPU1")
	)
	(segment
		(start 157.08122 -124.8537)
		(end 157.08122 -129.7686)
		(width 0.3556)
		(layer "In4.Cu")
		(net "PVCCIO_CPU1")
	)
	(segment
		(start 27.8892 -128.665224)
		(end 27.099768 -127.875792)
		(width 0.3556)
		(layer "In4.Cu")
		(net "PVCCIO_CPU1")
	)
	(segment
		(start 170.057064 -21.0312)
		(end 164.846 -21.0312)
		(width 0.254)
		(layer "In4.Cu")
		(net "PVCCIO_CPU1")
	)
	(segment
		(start 87.377524 -156.096208)
		(end 86.857332 -156.6164)
		(width 0.3556)
		(layer "In4.Cu")
		(net "PVCCIO_CPU1")
	)
	(segment
		(start 159.045402 -120.278398)
		(end 159.045402 -117.262402)
		(width 0.254)
		(layer "In4.Cu")
		(net "PVCCIO_CPU1")
	)
	(segment
		(start 90.070686 -153.476706)
		(end 88.902286 -154.645106)
		(width 0.3556)
		(layer "In4.Cu")
		(net "PVCCIO_CPU1")
	)
	(segment
		(start 425.656248 -11.3538)
		(end 421.2844 -11.3538)
		(width 0.254)
		(layer "In4.Cu")
		(net "PVCCIO_CPU1")
	)
	(segment
		(start 158.3436 -120.9802)
		(end 159.045402 -120.278398)
		(width 0.254)
		(layer "In4.Cu")
		(net "PVCCIO_CPU1")
	)
	(segment
		(start 164.846 -21.0312)
		(end 164.4904 -21.3868)
		(width 0.254)
		(layer "In4.Cu")
		(net "PVCCIO_CPU1")
	)
	(segment
		(start 157.738318 -136.615678)
		(end 157.738318 -151.0792)
		(width 0.3556)
		(layer "In4.Cu")
		(net "PVCCIO_CPU1")
	)
	(segment
		(start 123.786646 -151.4856)
		(end 122.665998 -150.364952)
		(width 0.3556)
		(layer "In4.Cu")
		(net "PVCCIO_CPU1")
	)
	(segment
		(start 88.902286 -154.645106)
		(end 88.902286 -155.77058)
		(width 0.3556)
		(layer "In4.Cu")
		(net "PVCCIO_CPU1")
	)
	(segment
		(start 429.8442 -12.3698)
		(end 429.02632 -11.55192)
		(width 0.254)
		(layer "In4.Cu")
		(net "PVCCIO_CPU1")
	)
	(segment
		(start 122.882914 -149.09546)
		(end 122.882914 -148.398484)
		(width 0.3556)
		(layer "In4.Cu")
		(net "PVCCIO_CPU1")
	)
	(segment
		(start 88.576658 -156.096208)
		(end 87.377524 -156.096208)
		(width 0.3556)
		(layer "In4.Cu")
		(net "PVCCIO_CPU1")
	)
	(segment
		(start 169.25798 -42.46118)
		(end 165.92042 -42.46118)
		(width 0.508)
		(layer "In7.Cu")
		(net "PVCCIO_CPU1")
	)
	(segment
		(start 305.49596 -48.3108)
		(end 212.214968 -48.3108)
		(width 0.508)
		(layer "In7.Cu")
		(net "PVCCIO_CPU1")
	)
	(segment
		(start 212.214968 -48.3108)
		(end 208.624932 -44.720764)
		(width 0.508)
		(layer "In7.Cu")
		(net "PVCCIO_CPU1")
	)
	(segment
		(start 200.823576 -44.720764)
		(end 200.311512 -44.2087)
		(width 0.508)
		(layer "In7.Cu")
		(net "PVCCIO_CPU1")
	)
	(segment
		(start 307.094382 -46.712378)
		(end 305.49596 -48.3108)
		(width 0.508)
		(layer "In7.Cu")
		(net "PVCCIO_CPU1")
	)
	(segment
		(start 171.0055 -44.2087)
		(end 169.25798 -42.46118)
		(width 0.508)
		(layer "In7.Cu")
		(net "PVCCIO_CPU1")
	)
	(segment
		(start 165.92042 -42.46118)
		(end 163.7665 -44.6151)
		(width 0.508)
		(layer "In7.Cu")
		(net "PVCCIO_CPU1")
	)
	(segment
		(start 208.624932 -44.720764)
		(end 200.823576 -44.720764)
		(width 0.508)
		(layer "In7.Cu")
		(net "PVCCIO_CPU1")
	)
	(segment
		(start 200.311512 -44.2087)
		(end 171.0055 -44.2087)
		(width 0.508)
		(layer "In7.Cu")
		(net "PVCCIO_CPU1")
	)
	(segment
		(start 353.416362 -38.601396)
		(end 333.256128 -38.601396)
		(width 0.254)
		(layer "In9.Cu")
		(net "PVCCIO_CPU1")
	)
	(segment
		(start 165.391338 -61.932312)
		(end 166.212774 -62.753748)
		(width 0.3556)
		(layer "In9.Cu")
		(net "PVCCIO_CPU1")
	)
	(segment
		(start 355.9302 -37.9984)
		(end 354.019358 -37.9984)
		(width 0.254)
		(layer "In9.Cu")
		(net "PVCCIO_CPU1")
	)
	(segment
		(start 165.810184 -64.844422)
		(end 166.853362 -65.8876)
		(width 0.3556)
		(layer "In9.Cu")
		(net "PVCCIO_CPU1")
	)
	(segment
		(start 372.781322 -54.05501)
		(end 372.781322 -48.555148)
		(width 0.254)
		(layer "In9.Cu")
		(net "PVCCIO_CPU1")
	)
	(segment
		(start 166.853362 -65.8876)
		(end 171.9326 -65.8876)
		(width 0.3556)
		(layer "In9.Cu")
		(net "PVCCIO_CPU1")
	)
	(segment
		(start 373.481092 -47.846488)
		(end 373.477028 -47.846488)
		(width 0.254)
		(layer "In9.Cu")
		(net "PVCCIO_CPU1")
	)
	(segment
		(start 166.212774 -63.324232)
		(end 165.810184 -63.726822)
		(width 0.3556)
		(layer "In9.Cu")
		(net "PVCCIO_CPU1")
	)
	(segment
		(start 179.8574 -58.1914)
		(end 180.467 -57.5818)
		(width 0.3556)
		(layer "In9.Cu")
		(net "PVCCIO_CPU1")
	)
	(segment
		(start 374.080532 -54.98973)
		(end 373.716042 -54.98973)
		(width 0.254)
		(layer "In9.Cu")
		(net "PVCCIO_CPU1")
	)
	(segment
		(start 177.2666 -58.1914)
		(end 179.8574 -58.1914)
		(width 0.3556)
		(layer "In9.Cu")
		(net "PVCCIO_CPU1")
	)
	(segment
		(start 372.781322 -48.555148)
		(end 373.481092 -47.855378)
		(width 0.254)
		(layer "In9.Cu")
		(net "PVCCIO_CPU1")
	)
	(segment
		(start 180.467 -57.5818)
		(end 180.467 -57.023)
		(width 0.3556)
		(layer "In9.Cu")
		(net "PVCCIO_CPU1")
	)
	(segment
		(start 373.716042 -54.98973)
		(end 372.781322 -54.05501)
		(width 0.254)
		(layer "In9.Cu")
		(net "PVCCIO_CPU1")
	)
	(segment
		(start 373.481092 -47.855378)
		(end 373.481092 -47.846488)
		(width 0.254)
		(layer "In9.Cu")
		(net "PVCCIO_CPU1")
	)
	(segment
		(start 333.256128 -38.601396)
		(end 332.764892 -38.11016)
		(width 0.254)
		(layer "In9.Cu")
		(net "PVCCIO_CPU1")
	)
	(segment
		(start 166.212774 -62.753748)
		(end 166.212774 -63.324232)
		(width 0.3556)
		(layer "In9.Cu")
		(net "PVCCIO_CPU1")
	)
	(segment
		(start 171.9326 -65.8876)
		(end 173.8376 -63.9826)
		(width 0.3556)
		(layer "In9.Cu")
		(net "PVCCIO_CPU1")
	)
	(segment
		(start 173.8376 -63.9826)
		(end 173.8376 -61.6204)
		(width 0.3556)
		(layer "In9.Cu")
		(net "PVCCIO_CPU1")
	)
	(segment
		(start 162.951414 -61.932312)
		(end 165.391338 -61.932312)
		(width 0.3556)
		(layer "In9.Cu")
		(net "PVCCIO_CPU1")
	)
	(segment
		(start 173.8376 -61.6204)
		(end 177.2666 -58.1914)
		(width 0.3556)
		(layer "In9.Cu")
		(net "PVCCIO_CPU1")
	)
	(segment
		(start 165.810184 -63.726822)
		(end 165.810184 -64.844422)
		(width 0.3556)
		(layer "In9.Cu")
		(net "PVCCIO_CPU1")
	)
	(segment
		(start 354.019358 -37.9984)
		(end 353.416362 -38.601396)
		(width 0.254)
		(layer "In9.Cu")
		(net "PVCCIO_CPU1")
	)
	(segment
		(start 370.862352 -33.99028)
		(end 370.862352 -28.377134)
		(width 0.254)
		(layer "In11.Cu")
		(net "PVCCIO_CPU1")
	)
	(segment
		(start 13.208 -86.868)
		(end 13.7668 -87.4268)
		(width 0.4064)
		(layer "In11.Cu")
		(net "PVCCIO_CPU1")
	)
	(segment
		(start 13.6398 -53.6956)
		(end 14.7447 -54.8005)
		(width 0.4064)
		(layer "In11.Cu")
		(net "PVCCIO_CPU1")
	)
	(segment
		(start 15.392146 -69.427598)
		(end 14.223238 -70.596506)
		(width 0.4064)
		(layer "In11.Cu")
		(net "PVCCIO_CPU1")
	)
	(segment
		(start 373.477028 -47.846488)
		(end 372.798848 -47.168308)
		(width 0.254)
		(layer "In11.Cu")
		(net "PVCCIO_CPU1")
	)
	(segment
		(start 19.07286 -54.8005)
		(end 20.320508 -56.048148)
		(width 0.4064)
		(layer "In11.Cu")
		(net "PVCCIO_CPU1")
	)
	(segment
		(start 16.8402 -88.3666)
		(end 16.8529 -88.3793)
		(width 0.4064)
		(layer "In11.Cu")
		(net "PVCCIO_CPU1")
	)
	(segment
		(start -1.8542 -122.7074)
		(end -1.8542 -121.8438)
		(width 0.254)
		(layer "In11.Cu")
		(net "PVCCIO_CPU1")
	)
	(segment
		(start 371.152166 -34.280094)
		(end 370.862352 -33.99028)
		(width 0.254)
		(layer "In11.Cu")
		(net "PVCCIO_CPU1")
	)
	(segment
		(start 13.335 -83.9216)
		(end 12.7762 -84.4804)
		(width 0.4064)
		(layer "In11.Cu")
		(net "PVCCIO_CPU1")
	)
	(segment
		(start 14.223238 -73.190354)
		(end 12.9032 -74.510392)
		(width 0.4064)
		(layer "In11.Cu")
		(net "PVCCIO_CPU1")
	)
	(segment
		(start 20.320508 -56.048148)
		(end 20.320508 -67.974464)
		(width 0.4064)
		(layer "In11.Cu")
		(net "PVCCIO_CPU1")
	)
	(segment
		(start 13.208 -86.3346)
		(end 13.208 -86.868)
		(width 0.4064)
		(layer "In11.Cu")
		(net "PVCCIO_CPU1")
	)
	(segment
		(start 20.320508 -67.974464)
		(end 18.867374 -69.427598)
		(width 0.4064)
		(layer "In11.Cu")
		(net "PVCCIO_CPU1")
	)
	(segment
		(start -1.33604 -118.06936)
		(end -1.5494 -118.06936)
		(width 0.254)
		(layer "In11.Cu")
		(net "PVCCIO_CPU1")
	)
	(segment
		(start 374.080532 -54.98973)
		(end 371.691662 -52.60086)
		(width 0.254)
		(layer "In11.Cu")
		(net "PVCCIO_CPU1")
	)
	(segment
		(start 14.223238 -70.596506)
		(end 14.223238 -73.190354)
		(width 0.4064)
		(layer "In11.Cu")
		(net "PVCCIO_CPU1")
	)
	(segment
		(start 12.7762 -84.4804)
		(end 12.7762 -85.9028)
		(width 0.4064)
		(layer "In11.Cu")
		(net "PVCCIO_CPU1")
	)
	(segment
		(start 12.7762 -85.9028)
		(end 13.208 -86.3346)
		(width 0.4064)
		(layer "In11.Cu")
		(net "PVCCIO_CPU1")
	)
	(segment
		(start 371.691662 -52.60086)
		(end 371.691662 -51.859688)
		(width 0.254)
		(layer "In11.Cu")
		(net "PVCCIO_CPU1")
	)
	(segment
		(start 18.867374 -69.427598)
		(end 15.392146 -69.427598)
		(width 0.4064)
		(layer "In11.Cu")
		(net "PVCCIO_CPU1")
	)
	(segment
		(start 15.6972 -49.8348)
		(end 13.6398 -51.8922)
		(width 0.4064)
		(layer "In11.Cu")
		(net "PVCCIO_CPU1")
	)
	(segment
		(start 372.798848 -46.52518)
		(end 371.152166 -44.878498)
		(width 0.254)
		(layer "In11.Cu")
		(net "PVCCIO_CPU1")
	)
	(segment
		(start 13.6398 -51.8922)
		(end 13.6398 -53.6956)
		(width 0.4064)
		(layer "In11.Cu")
		(net "PVCCIO_CPU1")
	)
	(segment
		(start 371.152166 -44.878498)
		(end 371.152166 -34.280094)
		(width 0.254)
		(layer "In11.Cu")
		(net "PVCCIO_CPU1")
	)
	(segment
		(start -1.8542 -121.8438)
		(end -0.635 -120.6246)
		(width 0.254)
		(layer "In11.Cu")
		(net "PVCCIO_CPU1")
	)
	(segment
		(start 367.544604 -47.712122)
		(end 366.344962 -47.712122)
		(width 0.254)
		(layer "In11.Cu")
		(net "PVCCIO_CPU1")
	)
	(segment
		(start 421.022272 -11.091672)
		(end 421.2844 -11.3538)
		(width 0.254)
		(layer "In11.Cu")
		(net "PVCCIO_CPU1")
	)
	(segment
		(start 16.8402 -88.0364)
		(end 16.8402 -88.3666)
		(width 0.4064)
		(layer "In11.Cu")
		(net "PVCCIO_CPU1")
	)
	(segment
		(start -1.6891 -122.8725)
		(end -1.8542 -122.7074)
		(width 0.254)
		(layer "In11.Cu")
		(net "PVCCIO_CPU1")
	)
	(segment
		(start 14.7447 -54.8005)
		(end 19.07286 -54.8005)
		(width 0.4064)
		(layer "In11.Cu")
		(net "PVCCIO_CPU1")
	)
	(segment
		(start 12.9032 -80.398112)
		(end 14.097 -81.591912)
		(width 0.4064)
		(layer "In11.Cu")
		(net "PVCCIO_CPU1")
	)
	(segment
		(start 372.410736 -26.82875)
		(end 372.410736 -21.740622)
		(width 0.254)
		(layer "In11.Cu")
		(net "PVCCIO_CPU1")
	)
	(segment
		(start 13.462 -83.9216)
		(end 13.335 -83.9216)
		(width 0.4064)
		(layer "In11.Cu")
		(net "PVCCIO_CPU1")
	)
	(segment
		(start 356.63124 -37.9984)
		(end 355.9302 -37.9984)
		(width 0.254)
		(layer "In11.Cu")
		(net "PVCCIO_CPU1")
	)
	(segment
		(start 370.862352 -28.377134)
		(end 372.410736 -26.82875)
		(width 0.254)
		(layer "In11.Cu")
		(net "PVCCIO_CPU1")
	)
	(segment
		(start 399.819876 -12.796012)
		(end 401.524216 -11.091672)
		(width 0.254)
		(layer "In11.Cu")
		(net "PVCCIO_CPU1")
	)
	(segment
		(start 16.2306 -87.4268)
		(end 16.8402 -88.0364)
		(width 0.4064)
		(layer "In11.Cu")
		(net "PVCCIO_CPU1")
	)
	(segment
		(start 13.7668 -87.4268)
		(end 16.2306 -87.4268)
		(width 0.4064)
		(layer "In11.Cu")
		(net "PVCCIO_CPU1")
	)
	(segment
		(start 14.097 -83.2866)
		(end 13.462 -83.9216)
		(width 0.4064)
		(layer "In11.Cu")
		(net "PVCCIO_CPU1")
	)
	(segment
		(start 381.355346 -12.796012)
		(end 399.819876 -12.796012)
		(width 0.254)
		(layer "In11.Cu")
		(net "PVCCIO_CPU1")
	)
	(segment
		(start -0.635 -118.7704)
		(end -1.33604 -118.06936)
		(width 0.254)
		(layer "In11.Cu")
		(net "PVCCIO_CPU1")
	)
	(segment
		(start 372.798848 -47.168308)
		(end 372.798848 -46.52518)
		(width 0.254)
		(layer "In11.Cu")
		(net "PVCCIO_CPU1")
	)
	(segment
		(start 372.410736 -21.740622)
		(end 381.355346 -12.796012)
		(width 0.254)
		(layer "In11.Cu")
		(net "PVCCIO_CPU1")
	)
	(segment
		(start 14.097 -81.591912)
		(end 14.097 -83.2866)
		(width 0.4064)
		(layer "In11.Cu")
		(net "PVCCIO_CPU1")
	)
	(segment
		(start 371.691662 -51.859688)
		(end 367.544604 -47.712122)
		(width 0.254)
		(layer "In11.Cu")
		(net "PVCCIO_CPU1")
	)
	(segment
		(start -1.6891 -123.9012)
		(end -1.6891 -122.8725)
		(width 0.254)
		(layer "In11.Cu")
		(net "PVCCIO_CPU1")
	)
	(segment
		(start 366.344962 -47.712122)
		(end 356.63124 -37.9984)
		(width 0.254)
		(layer "In11.Cu")
		(net "PVCCIO_CPU1")
	)
	(segment
		(start 401.524216 -11.091672)
		(end 421.022272 -11.091672)
		(width 0.254)
		(layer "In11.Cu")
		(net "PVCCIO_CPU1")
	)
	(segment
		(start -0.635 -120.6246)
		(end -0.635 -118.7704)
		(width 0.254)
		(layer "In11.Cu")
		(net "PVCCIO_CPU1")
	)
	(segment
		(start 12.9032 -74.510392)
		(end 12.9032 -80.398112)
		(width 0.4064)
		(layer "In11.Cu")
		(net "PVCCIO_CPU1")
	)
	(segment
		(start 15.6972 -48.6664)
		(end 15.6972 -49.8348)
		(width 0.4064)
		(layer "In11.Cu")
		(net "PVCCIO_CPU1")
	)
	(segment
		(start 299.524166 -60.362338)
		(end 300.095666 -60.362338)
		(width 0.254)
		(layer "F.Cu")
		(net "PVCCIO_CPU0")
	)
	(segment
		(start 388.501128 -85.39734)
		(end 390.6647 -83.233768)
		(width 0.254)
		(layer "F.Cu")
		(net "PVCCIO_CPU0")
	)
	(segment
		(start 304.675286 -60.362338)
		(end 305.246786 -60.362338)
		(width 0.254)
		(layer "F.Cu")
		(net "PVCCIO_CPU0")
	)
	(segment
		(start 300.382686 -84.631784)
		(end 300.954186 -84.631784)
		(width 0.254)
		(layer "F.Cu")
		(net "PVCCIO_CPU0")
	)
	(segment
		(start 306.392326 -98.005138)
		(end 307.040026 -98.005138)
		(width 0.254)
		(layer "F.Cu")
		(net "PVCCIO_CPU0")
	)
	(segment
		(start 323.985382 -131.313682)
		(end 323.98716 -131.31546)
		(width 0.254)
		(layer "F.Cu")
		(net "PVCCIO_CPU0")
	)
	(segment
		(start 419.64864 -105.05694)
		(end 419.64864 -107.01528)
		(width 0.254)
		(layer "F.Cu")
		(net "PVCCIO_CPU0")
	)
	(segment
		(start 204.978 -105.537)
		(end 204.978 -105.918)
		(width 0.381)
		(layer "F.Cu")
		(net "PVCCIO_CPU0")
	)
	(segment
		(start 184.33415 -61.41085)
		(end 184.33415 -61.35624)
		(width 0.381)
		(layer "F.Cu")
		(net "PVCCIO_CPU0")
	)
	(segment
		(start 290.0807 -95.528384)
		(end 290.6522 -95.528384)
		(width 0.254)
		(layer "F.Cu")
		(net "PVCCIO_CPU0")
	)
	(segment
		(start 296.66184 -91.070938)
		(end 296.09034 -91.070938)
		(width 0.254)
		(layer "F.Cu")
		(net "PVCCIO_CPU0")
	)
	(segment
		(start 183.769 -61.976)
		(end 184.33415 -61.41085)
		(width 0.381)
		(layer "F.Cu")
		(net "PVCCIO_CPU0")
	)
	(segment
		(start 323.6087 -31.6357)
		(end 323.6087 -32.42818)
		(width 0.4572)
		(layer "F.Cu")
		(net "PVCCIO_CPU0")
	)
	(segment
		(start 287.50514 -73.240138)
		(end 288.07664 -73.240138)
		(width 0.254)
		(layer "F.Cu")
		(net "PVCCIO_CPU0")
	)
	(segment
		(start 324.3834 -31.15818)
		(end 324.08622 -31.15818)
		(width 0.4572)
		(layer "F.Cu")
		(net "PVCCIO_CPU0")
	)
	(segment
		(start 443.567312 -14.988794)
		(end 442.623194 -14.988794)
		(width 0.254)
		(layer "F.Cu")
		(net "PVCCIO_CPU0")
	)
	(segment
		(start 324.08622 -31.15818)
		(end 323.6087 -31.6357)
		(width 0.4572)
		(layer "F.Cu")
		(net "PVCCIO_CPU0")
	)
	(segment
		(start 422.2877 -105.029)
		(end 422.529 -105.029)
		(width 0.254)
		(layer "F.Cu")
		(net "PVCCIO_CPU0")
	)
	(segment
		(start 330.430378 -128.395222)
		(end 326.239378 -128.395222)
		(width 0.254)
		(layer "F.Cu")
		(net "PVCCIO_CPU0")
	)
	(segment
		(start 300.382686 -56.894984)
		(end 300.954186 -56.894984)
		(width 0.254)
		(layer "F.Cu")
		(net "PVCCIO_CPU0")
	)
	(segment
		(start 299.524166 -63.334138)
		(end 300.095666 -63.334138)
		(width 0.254)
		(layer "F.Cu")
		(net "PVCCIO_CPU0")
	)
	(segment
		(start 332.136496 -127.381)
		(end 331.4446 -127.381)
		(width 0.254)
		(layer "F.Cu")
		(net "PVCCIO_CPU0")
	)
	(segment
		(start 325.0057 -31.15818)
		(end 324.3834 -31.15818)
		(width 0.4572)
		(layer "F.Cu")
		(net "PVCCIO_CPU0")
	)
	(segment
		(start 323.10324 -131.34086)
		(end 323.10324 -131.7625)
		(width 0.254)
		(layer "F.Cu")
		(net "PVCCIO_CPU0")
	)
	(segment
		(start 326.239378 -128.395222)
		(end 325.1962 -129.4384)
		(width 0.254)
		(layer "F.Cu")
		(net "PVCCIO_CPU0")
	)
	(segment
		(start 302.099726 -94.538038)
		(end 302.671226 -94.538038)
		(width 0.254)
		(layer "F.Cu")
		(net "PVCCIO_CPU0")
	)
	(segment
		(start 203.073 -103.4288)
		(end 203.073 -104.263952)
		(width 0.381)
		(layer "F.Cu")
		(net "PVCCIO_CPU0")
	)
	(segment
		(start 290.0807 -89.584784)
		(end 290.6522 -89.584784)
		(width 0.254)
		(layer "F.Cu")
		(net "PVCCIO_CPU0")
	)
	(segment
		(start 287.21812 -74.725784)
		(end 286.64662 -74.725784)
		(width 0.254)
		(layer "F.Cu")
		(net "PVCCIO_CPU0")
	)
	(segment
		(start 285.7881 -75.221338)
		(end 286.3596 -75.221338)
		(width 0.254)
		(layer "F.Cu")
		(net "PVCCIO_CPU0")
	)
	(segment
		(start 442.364876 -14.123924)
		(end 441.783724 -14.123924)
		(width 0.254)
		(layer "F.Cu")
		(net "PVCCIO_CPU0")
	)
	(segment
		(start 418.9984 -105.029)
		(end 418.67963 -105.34777)
		(width 0.254)
		(layer "F.Cu")
		(net "PVCCIO_CPU0")
	)
	(segment
		(start 204.015848 -105.2068)
		(end 204.6478 -105.2068)
		(width 0.381)
		(layer "F.Cu")
		(net "PVCCIO_CPU0")
	)
	(segment
		(start 296.948606 -54.913784)
		(end 297.520106 -54.913784)
		(width 0.254)
		(layer "F.Cu")
		(net "PVCCIO_CPU0")
	)
	(segment
		(start 287.21812 -77.697584)
		(end 286.64662 -77.697584)
		(width 0.254)
		(layer "F.Cu")
		(net "PVCCIO_CPU0")
	)
	(segment
		(start 325.1962 -129.4384)
		(end 325.1962 -130.8354)
		(width 0.254)
		(layer "F.Cu")
		(net "PVCCIO_CPU0")
	)
	(segment
		(start 301.241206 -94.042738)
		(end 301.812706 -94.042738)
		(width 0.254)
		(layer "F.Cu")
		(net "PVCCIO_CPU0")
	)
	(segment
		(start 424.311572 -104.665272)
		(end 424.311572 -106.549952)
		(width 0.254)
		(layer "F.Cu")
		(net "PVCCIO_CPU0")
	)
	(segment
		(start 419.64864 -107.823)
		(end 419.90264 -108.077)
		(width 0.254)
		(layer "F.Cu")
		(net "PVCCIO_CPU0")
	)
	(segment
		(start 298.665646 -68.782184)
		(end 299.237146 -68.782184)
		(width 0.254)
		(layer "F.Cu")
		(net "PVCCIO_CPU0")
	)
	(segment
		(start 284.929834 -84.631784)
		(end 285.501334 -84.631784)
		(width 0.254)
		(layer "F.Cu")
		(net "PVCCIO_CPU0")
	)
	(segment
		(start 387.877558 -85.397086)
		(end 387.877812 -85.39734)
		(width 0.254)
		(layer "F.Cu")
		(net "PVCCIO_CPU0")
	)
	(segment
		(start 296.66184 -56.399938)
		(end 296.09034 -56.399938)
		(width 0.254)
		(layer "F.Cu")
		(net "PVCCIO_CPU0")
	)
	(segment
		(start 298.665646 -70.763384)
		(end 299.237146 -70.763384)
		(width 0.254)
		(layer "F.Cu")
		(net "PVCCIO_CPU0")
	)
	(segment
		(start 294.3733 -95.033084)
		(end 294.9448 -95.033084)
		(width 0.254)
		(layer "F.Cu")
		(net "PVCCIO_CPU0")
	)
	(segment
		(start 303.529746 -87.108538)
		(end 302.958246 -87.108538)
		(width 0.127)
		(layer "F.Cu")
		(net "PVCCIO_CPU0")
	)
	(segment
		(start 424.311572 -106.549952)
		(end 423.851324 -107.0102)
		(width 0.254)
		(layer "F.Cu")
		(net "PVCCIO_CPU0")
	)
	(segment
		(start 284.929834 -73.735184)
		(end 284.358334 -73.735184)
		(width 0.254)
		(layer "F.Cu")
		(net "PVCCIO_CPU0")
	)
	(segment
		(start 419.6207 -105.029)
		(end 419.64864 -105.05694)
		(width 0.254)
		(layer "F.Cu")
		(net "PVCCIO_CPU0")
	)
	(segment
		(start 304.675286 -62.343538)
		(end 305.246786 -62.343538)
		(width 0.254)
		(layer "F.Cu")
		(net "PVCCIO_CPU0")
	)
	(segment
		(start 291.79774 -97.509584)
		(end 292.36924 -97.509584)
		(width 0.254)
		(layer "F.Cu")
		(net "PVCCIO_CPU0")
	)
	(segment
		(start 419.64864 -107.01528)
		(end 419.64864 -107.823)
		(width 0.254)
		(layer "F.Cu")
		(net "PVCCIO_CPU0")
	)
	(segment
		(start 287.50514 -71.258938)
		(end 288.07664 -71.258938)
		(width 0.254)
		(layer "F.Cu")
		(net "PVCCIO_CPU0")
	)
	(segment
		(start 392.2268 -82.6516)
		(end 392.2268 -82.0674)
		(width 0.254)
		(layer "F.Cu")
		(net "PVCCIO_CPU0")
	)
	(segment
		(start 323.10324 -131.34086)
		(end 323.59854 -131.34086)
		(width 0.254)
		(layer "F.Cu")
		(net "PVCCIO_CPU0")
	)
	(segment
		(start 276.344634 -62.838584)
		(end 275.773134 -62.838584)
		(width 0.254)
		(layer "F.Cu")
		(net "PVCCIO_CPU0")
	)
	(segment
		(start 298.665646 -56.894984)
		(end 299.237146 -56.894984)
		(width 0.254)
		(layer "F.Cu")
		(net "PVCCIO_CPU0")
	)
	(segment
		(start 331.4446 -127.381)
		(end 330.430378 -128.395222)
		(width 0.254)
		(layer "F.Cu")
		(net "PVCCIO_CPU0")
	)
	(segment
		(start 295.23182 -55.904384)
		(end 295.80332 -55.904384)
		(width 0.254)
		(layer "F.Cu")
		(net "PVCCIO_CPU0")
	)
	(segment
		(start 387.877812 -85.39734)
		(end 388.501128 -85.39734)
		(width 0.254)
		(layer "F.Cu")
		(net "PVCCIO_CPU0")
	)
	(segment
		(start 296.66184 -59.371484)
		(end 296.09034 -59.371484)
		(width 0.1016)
		(layer "F.Cu")
		(net "PVCCIO_CPU0")
	)
	(segment
		(start 389.8138 -77.8764)
		(end 390.7663 -78.8289)
		(width 0.254)
		(layer "F.Cu")
		(net "PVCCIO_CPU0")
	)
	(segment
		(start 295.23182 -101.471984)
		(end 295.80332 -101.471984)
		(width 0.254)
		(layer "F.Cu")
		(net "PVCCIO_CPU0")
	)
	(segment
		(start 284.929834 -82.650584)
		(end 285.501334 -82.650584)
		(width 0.381)
		(layer "F.Cu")
		(net "PVCCIO_CPU0")
	)
	(segment
		(start 360.613452 -89.7128)
		(end 359.537 -89.7128)
		(width 0.254)
		(layer "F.Cu")
		(net "PVCCIO_CPU0")
	)
	(segment
		(start 367.15954 -88.983058)
		(end 361.343194 -88.983058)
		(width 0.254)
		(layer "F.Cu")
		(net "PVCCIO_CPU0")
	)
	(segment
		(start 300.382686 -64.819784)
		(end 300.954186 -64.819784)
		(width 0.254)
		(layer "F.Cu")
		(net "PVCCIO_CPU0")
	)
	(segment
		(start 323.10324 -131.7625)
		(end 323.35724 -132.0165)
		(width 0.254)
		(layer "F.Cu")
		(net "PVCCIO_CPU0")
	)
	(segment
		(start 296.948606 -93.547184)
		(end 297.520106 -93.547184)
		(width 0.254)
		(layer "F.Cu")
		(net "PVCCIO_CPU0")
	)
	(segment
		(start 203.073 -104.263952)
		(end 204.015848 -105.2068)
		(width 0.381)
		(layer "F.Cu")
		(net "PVCCIO_CPU0")
	)
	(segment
		(start 278.920194 -63.334138)
		(end 278.348694 -63.334138)
		(width 0.254)
		(layer "F.Cu")
		(net "PVCCIO_CPU0")
	)
	(segment
		(start 285.7881 -76.211938)
		(end 286.3596 -76.211938)
		(width 0.254)
		(layer "F.Cu")
		(net "PVCCIO_CPU0")
	)
	(segment
		(start 440.6138 -12.954)
		(end 439.293 -12.954)
		(width 0.254)
		(layer "F.Cu")
		(net "PVCCIO_CPU0")
	)
	(segment
		(start 287.21812 -75.716384)
		(end 286.64662 -75.716384)
		(width 0.254)
		(layer "F.Cu")
		(net "PVCCIO_CPU0")
	)
	(segment
		(start 418.67963 -105.34777)
		(end 417.398454 -105.34777)
		(width 0.254)
		(layer "F.Cu")
		(net "PVCCIO_CPU0")
	)
	(segment
		(start 284.929834 -69.772784)
		(end 284.929834 -70.763384)
		(width 0.381)
		(layer "F.Cu")
		(net "PVCCIO_CPU0")
	)
	(segment
		(start 284.929834 -83.641184)
		(end 285.501334 -83.641184)
		(width 0.381)
		(layer "F.Cu")
		(net "PVCCIO_CPU0")
	)
	(segment
		(start 296.948606 -81.659984)
		(end 297.520106 -81.659984)
		(width 0.254)
		(layer "F.Cu")
		(net "PVCCIO_CPU0")
	)
	(segment
		(start 384.63347 -73.892664)
		(end 388.06501 -73.892664)
		(width 0.254)
		(layer "F.Cu")
		(net "PVCCIO_CPU0")
	)
	(segment
		(start 303.816766 -63.829184)
		(end 304.388266 -63.829184)
		(width 0.254)
		(layer "F.Cu")
		(net "PVCCIO_CPU0")
	)
	(segment
		(start 278.920194 -64.324738)
		(end 278.348694 -64.324738)
		(width 0.254)
		(layer "F.Cu")
		(net "PVCCIO_CPU0")
	)
	(segment
		(start 296.66184 -84.136738)
		(end 296.09034 -84.136738)
		(width 0.254)
		(layer "F.Cu")
		(net "PVCCIO_CPU0")
	)
	(segment
		(start 442.623194 -14.988794)
		(end 442.364876 -14.730476)
		(width 0.254)
		(layer "F.Cu")
		(net "PVCCIO_CPU0")
	)
	(segment
		(start 323.35724 -132.0165)
		(end 324.718426 -132.0165)
		(width 0.254)
		(layer "F.Cu")
		(net "PVCCIO_CPU0")
	)
	(segment
		(start 390.7663 -79.8322)
		(end 389.9535 -79.8322)
		(width 0.254)
		(layer "F.Cu")
		(net "PVCCIO_CPU0")
	)
	(segment
		(start 455.041 -154.051)
		(end 455.041 -152.146)
		(width 0.254)
		(layer "F.Cu")
		(net "PVCCIO_CPU0")
	)
	(segment
		(start 303.816766 -66.800984)
		(end 304.388266 -66.800984)
		(width 0.254)
		(layer "F.Cu")
		(net "PVCCIO_CPU0")
	)
	(segment
		(start 391.888472 -82.989928)
		(end 392.2268 -82.6516)
		(width 0.254)
		(layer "F.Cu")
		(net "PVCCIO_CPU0")
	)
	(segment
		(start 361.343194 -88.983058)
		(end 360.613452 -89.7128)
		(width 0.254)
		(layer "F.Cu")
		(net "PVCCIO_CPU0")
	)
	(segment
		(start 391.575798 -82.989928)
		(end 391.888472 -82.989928)
		(width 0.254)
		(layer "F.Cu")
		(net "PVCCIO_CPU0")
	)
	(segment
		(start 391.331958 -83.233768)
		(end 391.575798 -82.989928)
		(width 0.254)
		(layer "F.Cu")
		(net "PVCCIO_CPU0")
	)
	(segment
		(start 278.061674 -62.838584)
		(end 277.490174 -62.838584)
		(width 0.254)
		(layer "F.Cu")
		(net "PVCCIO_CPU0")
	)
	(segment
		(start 455.041 -152.146)
		(end 454.025 -151.13)
		(width 0.254)
		(layer "F.Cu")
		(net "PVCCIO_CPU0")
	)
	(segment
		(start 324.71614 -131.31546)
		(end 323.98716 -131.31546)
		(width 0.254)
		(layer "F.Cu")
		(net "PVCCIO_CPU0")
	)
	(segment
		(start 292.65626 -57.390538)
		(end 293.22776 -57.390538)
		(width 0.254)
		(layer "F.Cu")
		(net "PVCCIO_CPU0")
	)
	(segment
		(start 299.524166 -98.005138)
		(end 300.095666 -98.005138)
		(width 0.254)
		(layer "F.Cu")
		(net "PVCCIO_CPU0")
	)
	(segment
		(start 277.203154 -62.343538)
		(end 276.631654 -62.343538)
		(width 0.254)
		(layer "F.Cu")
		(net "PVCCIO_CPU0")
	)
	(segment
		(start 349.311976 -99.94011)
		(end 349.547688 -99.94011)
		(width 0.254)
		(layer "F.Cu")
		(net "PVCCIO_CPU0")
	)
	(segment
		(start 423.4307 -107.0102)
		(end 423.851324 -107.0102)
		(width 0.254)
		(layer "F.Cu")
		(net "PVCCIO_CPU0")
	)
	(segment
		(start 204.978 -106.68)
		(end 204.978 -105.918)
		(width 0.381)
		(layer "F.Cu")
		(net "PVCCIO_CPU0")
	)
	(segment
		(start 296.66184 -93.052138)
		(end 296.09034 -93.052138)
		(width 0.254)
		(layer "F.Cu")
		(net "PVCCIO_CPU0")
	)
	(segment
		(start 441.783724 -14.123924)
		(end 440.6138 -12.954)
		(width 0.254)
		(layer "F.Cu")
		(net "PVCCIO_CPU0")
	)
	(segment
		(start 378.012452 -86.464648)
		(end 378.522738 -85.954362)
		(width 0.254)
		(layer "F.Cu")
		(net "PVCCIO_CPU0")
	)
	(segment
		(start 323.625718 -131.313682)
		(end 323.985382 -131.313682)
		(width 0.254)
		(layer "F.Cu")
		(net "PVCCIO_CPU0")
	)
	(segment
		(start 419.6207 -105.029)
		(end 418.9984 -105.029)
		(width 0.254)
		(layer "F.Cu")
		(net "PVCCIO_CPU0")
	)
	(segment
		(start 292.65626 -89.089738)
		(end 293.22776 -89.089738)
		(width 0.254)
		(layer "F.Cu")
		(net "PVCCIO_CPU0")
	)
	(segment
		(start 290.93922 -98.995738)
		(end 291.51072 -98.995738)
		(width 0.254)
		(layer "F.Cu")
		(net "PVCCIO_CPU0")
	)
	(segment
		(start 285.7881 -71.258938)
		(end 286.3596 -71.258938)
		(width 0.254)
		(layer "F.Cu")
		(net "PVCCIO_CPU0")
	)
	(segment
		(start 323.59854 -131.34086)
		(end 323.625718 -131.313682)
		(width 0.254)
		(layer "F.Cu")
		(net "PVCCIO_CPU0")
	)
	(segment
		(start 285.7881 -74.230738)
		(end 286.3596 -74.230738)
		(width 0.1016)
		(layer "F.Cu")
		(net "PVCCIO_CPU0")
	)
	(segment
		(start 303.816766 -71.753984)
		(end 304.388266 -71.753984)
		(width 0.254)
		(layer "F.Cu")
		(net "PVCCIO_CPU0")
	)
	(segment
		(start 382.582674 -86.14156)
		(end 383.2098 -86.14156)
		(width 0.254)
		(layer "F.Cu")
		(net "PVCCIO_CPU0")
	)
	(segment
		(start 292.65626 -92.061538)
		(end 293.22776 -92.061538)
		(width 0.254)
		(layer "F.Cu")
		(net "PVCCIO_CPU0")
	)
	(segment
		(start 284.929834 -70.763384)
		(end 284.358334 -70.763384)
		(width 0.254)
		(layer "F.Cu")
		(net "PVCCIO_CPU0")
	)
	(segment
		(start 300.382686 -82.650584)
		(end 300.954186 -82.650584)
		(width 0.254)
		(layer "F.Cu")
		(net "PVCCIO_CPU0")
	)
	(segment
		(start 383.660904 -75.776328)
		(end 383.660904 -76.026264)
		(width 0.254)
		(layer "F.Cu")
		(net "PVCCIO_CPU0")
	)
	(segment
		(start 298.665646 -99.490784)
		(end 299.237146 -99.490784)
		(width 0.254)
		(layer "F.Cu")
		(net "PVCCIO_CPU0")
	)
	(segment
		(start 302.099726 -92.556584)
		(end 302.671226 -92.556584)
		(width 0.254)
		(layer "F.Cu")
		(net "PVCCIO_CPU0")
	)
	(segment
		(start 303.529746 -60.362338)
		(end 302.958246 -60.362338)
		(width 0.254)
		(layer "F.Cu")
		(net "PVCCIO_CPU0")
	)
	(segment
		(start 290.93922 -62.343538)
		(end 291.51072 -62.343538)
		(width 0.254)
		(layer "F.Cu")
		(net "PVCCIO_CPU0")
	)
	(segment
		(start 422.529 -105.029)
		(end 423.3926 -104.1654)
		(width 0.254)
		(layer "F.Cu")
		(net "PVCCIO_CPU0")
	)
	(segment
		(start 392.2268 -82.0674)
		(end 392.0998 -81.9404)
		(width 0.254)
		(layer "F.Cu")
		(net "PVCCIO_CPU0")
	)
	(segment
		(start 330.28001 -108.687108)
		(end 330.11491 -108.81106)
		(width 0.254)
		(layer "F.Cu")
		(net "PVCCIO_CPU0")
	)
	(segment
		(start 284.929834 -71.753984)
		(end 284.358334 -71.753984)
		(width 0.254)
		(layer "F.Cu")
		(net "PVCCIO_CPU0")
	)
	(segment
		(start 423.8117 -104.1654)
		(end 424.311572 -104.665272)
		(width 0.254)
		(layer "F.Cu")
		(net "PVCCIO_CPU0")
	)
	(segment
		(start 284.929834 -74.725784)
		(end 284.358334 -74.725784)
		(width 0.254)
		(layer "F.Cu")
		(net "PVCCIO_CPU0")
	)
	(segment
		(start 290.0807 -93.547184)
		(end 290.6522 -93.547184)
		(width 0.254)
		(layer "F.Cu")
		(net "PVCCIO_CPU0")
	)
	(segment
		(start 293.51478 -81.659984)
		(end 294.08628 -81.659984)
		(width 0.254)
		(layer "F.Cu")
		(net "PVCCIO_CPU0")
	)
	(segment
		(start 424.2562 -107.415076)
		(end 424.2562 -110.467394)
		(width 0.254)
		(layer "F.Cu")
		(net "PVCCIO_CPU0")
	)
	(segment
		(start 202.438 -102.7938)
		(end 203.073 -103.4288)
		(width 0.381)
		(layer "F.Cu")
		(net "PVCCIO_CPU0")
	)
	(segment
		(start 349.547688 -99.94011)
		(end 349.82785 -100.220272)
		(width 0.254)
		(layer "F.Cu")
		(net "PVCCIO_CPU0")
	)
	(segment
		(start 294.3733 -56.399938)
		(end 294.9448 -56.399938)
		(width 0.254)
		(layer "F.Cu")
		(net "PVCCIO_CPU0")
	)
	(segment
		(start 292.65626 -83.146138)
		(end 293.22776 -83.146138)
		(width 0.254)
		(layer "F.Cu")
		(net "PVCCIO_CPU0")
	)
	(segment
		(start 423.3926 -104.1654)
		(end 423.8117 -104.1654)
		(width 0.254)
		(layer "F.Cu")
		(net "PVCCIO_CPU0")
	)
	(segment
		(start 389.2804 -77.8764)
		(end 389.8138 -77.8764)
		(width 0.254)
		(layer "F.Cu")
		(net "PVCCIO_CPU0")
	)
	(segment
		(start 293.51478 -90.575384)
		(end 294.08628 -90.575384)
		(width 0.254)
		(layer "F.Cu")
		(net "PVCCIO_CPU0")
	)
	(segment
		(start 296.948606 -87.603584)
		(end 297.520106 -87.603584)
		(width 0.254)
		(layer "F.Cu")
		(net "PVCCIO_CPU0")
	)
	(segment
		(start 293.51478 -96.518984)
		(end 294.08628 -96.518984)
		(width 0.254)
		(layer "F.Cu")
		(net "PVCCIO_CPU0")
	)
	(segment
		(start 282.641294 -66.800984)
		(end 283.212794 -66.800984)
		(width 0.254)
		(layer "F.Cu")
		(net "PVCCIO_CPU0")
	)
	(segment
		(start 388.62 -74.447654)
		(end 388.62 -77.216)
		(width 0.254)
		(layer "F.Cu")
		(net "PVCCIO_CPU0")
	)
	(segment
		(start 284.071314 -85.127338)
		(end 284.071314 -84.555838)
		(width 0.381)
		(layer "F.Cu")
		(net "PVCCIO_CPU0")
	)
	(segment
		(start 290.0807 -56.894984)
		(end 290.6522 -56.894984)
		(width 0.254)
		(layer "F.Cu")
		(net "PVCCIO_CPU0")
	)
	(segment
		(start 383.345182 -75.137518)
		(end 383.345182 -75.460606)
		(width 0.254)
		(layer "F.Cu")
		(net "PVCCIO_CPU0")
	)
	(segment
		(start 183.007 -61.976)
		(end 183.769 -61.976)
		(width 0.381)
		(layer "F.Cu")
		(net "PVCCIO_CPU0")
	)
	(segment
		(start 384.518916 -74.007218)
		(end 384.63347 -73.892664)
		(width 0.254)
		(layer "F.Cu")
		(net "PVCCIO_CPU0")
	)
	(segment
		(start 423.851324 -107.0102)
		(end 424.2562 -107.415076)
		(width 0.254)
		(layer "F.Cu")
		(net "PVCCIO_CPU0")
	)
	(segment
		(start 204.6478 -105.2068)
		(end 204.978 -105.537)
		(width 0.381)
		(layer "F.Cu")
		(net "PVCCIO_CPU0")
	)
	(segment
		(start 297.807126 -100.976684)
		(end 298.378626 -100.976684)
		(width 0.254)
		(layer "F.Cu")
		(net "PVCCIO_CPU0")
	)
	(segment
		(start 383.610104 -74.007218)
		(end 384.518916 -74.007218)
		(width 0.254)
		(layer "F.Cu")
		(net "PVCCIO_CPU0")
	)
	(segment
		(start 424.2562 -110.467394)
		(end 425.48048 -111.691674)
		(width 0.254)
		(layer "F.Cu")
		(net "PVCCIO_CPU0")
	)
	(segment
		(start 278.061674 -63.829184)
		(end 277.490174 -63.829184)
		(width 0.254)
		(layer "F.Cu")
		(net "PVCCIO_CPU0")
	)
	(segment
		(start 284.929834 -75.716384)
		(end 284.358334 -75.716384)
		(width 0.254)
		(layer "F.Cu")
		(net "PVCCIO_CPU0")
	)
	(segment
		(start 330.11491 -108.81106)
		(end 329.594972 -109.20095)
		(width 0.254)
		(layer "F.Cu")
		(net "PVCCIO_CPU0")
	)
	(segment
		(start 383.345182 -74.27214)
		(end 383.610104 -74.007218)
		(width 0.254)
		(layer "F.Cu")
		(net "PVCCIO_CPU0")
	)
	(segment
		(start 301.241206 -97.014538)
		(end 301.812706 -97.014538)
		(width 0.254)
		(layer "F.Cu")
		(net "PVCCIO_CPU0")
	)
	(segment
		(start 302.099726 -56.894984)
		(end 302.671226 -56.894984)
		(width 0.254)
		(layer "F.Cu")
		(net "PVCCIO_CPU0")
	)
	(segment
		(start 378.522738 -85.954362)
		(end 378.522738 -84.930742)
		(width 0.254)
		(layer "F.Cu")
		(net "PVCCIO_CPU0")
	)
	(segment
		(start 390.6647 -83.233768)
		(end 391.331958 -83.233768)
		(width 0.254)
		(layer "F.Cu")
		(net "PVCCIO_CPU0")
	)
	(segment
		(start 285.7881 -70.268084)
		(end 286.3596 -70.268084)
		(width 0.254)
		(layer "F.Cu")
		(net "PVCCIO_CPU0")
	)
	(segment
		(start 283.499814 -66.305938)
		(end 284.071314 -66.305938)
		(width 0.254)
		(layer "F.Cu")
		(net "PVCCIO_CPU0")
	)
	(segment
		(start 383.49936 -85.852)
		(end 385.269994 -85.852)
		(width 0.254)
		(layer "F.Cu")
		(net "PVCCIO_CPU0")
	)
	(segment
		(start 302.099726 -52.932838)
		(end 302.671226 -52.932838)
		(width 0.254)
		(layer "F.Cu")
		(net "PVCCIO_CPU0")
	)
	(segment
		(start 390.7663 -78.8289)
		(end 390.7663 -79.8322)
		(width 0.254)
		(layer "F.Cu")
		(net "PVCCIO_CPU0")
	)
	(segment
		(start 299.524166 -102.958138)
		(end 300.095666 -102.958138)
		(width 0.254)
		(layer "F.Cu")
		(net "PVCCIO_CPU0")
	)
	(segment
		(start 349.82785 -100.220272)
		(end 350.064578 -100.220272)
		(width 0.254)
		(layer "F.Cu")
		(net "PVCCIO_CPU0")
	)
	(segment
		(start 302.099726 -89.584784)
		(end 302.671226 -89.584784)
		(width 0.254)
		(layer "F.Cu")
		(net "PVCCIO_CPU0")
	)
	(segment
		(start 303.816766 -85.622384)
		(end 304.388266 -85.622384)
		(width 0.254)
		(layer "F.Cu")
		(net "PVCCIO_CPU0")
	)
	(segment
		(start 305.533806 -58.876438)
		(end 306.105306 -58.876438)
		(width 0.254)
		(layer "F.Cu")
		(net "PVCCIO_CPU0")
	)
	(segment
		(start 303.816766 -68.782184)
		(end 304.388266 -68.782184)
		(width 0.254)
		(layer "F.Cu")
		(net "PVCCIO_CPU0")
	)
	(segment
		(start 285.7881 -72.249538)
		(end 286.3596 -72.249538)
		(width 0.254)
		(layer "F.Cu")
		(net "PVCCIO_CPU0")
	)
	(segment
		(start 284.929834 -76.706984)
		(end 284.358334 -76.706984)
		(width 0.254)
		(layer "F.Cu")
		(net "PVCCIO_CPU0")
	)
	(segment
		(start 388.06501 -73.892664)
		(end 388.62 -74.447654)
		(width 0.254)
		(layer "F.Cu")
		(net "PVCCIO_CPU0")
	)
	(segment
		(start 299.524166 -67.296538)
		(end 300.095666 -67.296538)
		(width 0.254)
		(layer "F.Cu")
		(net "PVCCIO_CPU0")
	)
	(segment
		(start 299.524166 -61.352938)
		(end 300.095666 -61.352938)
		(width 0.254)
		(layer "F.Cu")
		(net "PVCCIO_CPU0")
	)
	(segment
		(start 295.23182 -86.612984)
		(end 295.80332 -86.612984)
		(width 0.254)
		(layer "F.Cu")
		(net "PVCCIO_CPU0")
	)
	(segment
		(start 287.50514 -75.221338)
		(end 288.07664 -75.221338)
		(width 0.254)
		(layer "F.Cu")
		(net "PVCCIO_CPU0")
	)
	(segment
		(start 383.345182 -75.137518)
		(end 383.345182 -74.27214)
		(width 0.254)
		(layer "F.Cu")
		(net "PVCCIO_CPU0")
	)
	(segment
		(start 324.718426 -132.0165)
		(end 324.757542 -131.977384)
		(width 0.254)
		(layer "F.Cu")
		(net "PVCCIO_CPU0")
	)
	(segment
		(start 277.203154 -63.334138)
		(end 276.631654 -63.334138)
		(width 0.254)
		(layer "F.Cu")
		(net "PVCCIO_CPU0")
	)
	(segment
		(start 303.816766 -83.641184)
		(end 304.388266 -83.641184)
		(width 0.254)
		(layer "F.Cu")
		(net "PVCCIO_CPU0")
	)
	(segment
		(start 285.7881 -82.155284)
		(end 286.3596 -82.155284)
		(width 0.254)
		(layer "F.Cu")
		(net "PVCCIO_CPU0")
	)
	(segment
		(start 385.269994 -85.852)
		(end 385.724908 -85.397086)
		(width 0.254)
		(layer "F.Cu")
		(net "PVCCIO_CPU0")
	)
	(segment
		(start 383.345182 -75.460606)
		(end 383.660904 -75.776328)
		(width 0.254)
		(layer "F.Cu")
		(net "PVCCIO_CPU0")
	)
	(segment
		(start 377.915932 -86.464648)
		(end 378.012452 -86.464648)
		(width 0.254)
		(layer "F.Cu")
		(net "PVCCIO_CPU0")
	)
	(segment
		(start 378.522738 -84.930742)
		(end 378.921518 -84.531962)
		(width 0.254)
		(layer "F.Cu")
		(net "PVCCIO_CPU0")
	)
	(segment
		(start 332.70698 -126.810516)
		(end 332.136496 -127.381)
		(width 0.254)
		(layer "F.Cu")
		(net "PVCCIO_CPU0")
	)
	(segment
		(start 419.90264 -108.077)
		(end 422.3639 -108.077)
		(width 0.254)
		(layer "F.Cu")
		(net "PVCCIO_CPU0")
	)
	(segment
		(start 442.364876 -14.730476)
		(end 442.364876 -14.123924)
		(width 0.254)
		(layer "F.Cu")
		(net "PVCCIO_CPU0")
	)
	(segment
		(start 302.099726 -68.782184)
		(end 302.671226 -68.782184)
		(width 0.254)
		(layer "F.Cu")
		(net "PVCCIO_CPU0")
	)
	(segment
		(start 380.973076 -84.531962)
		(end 382.582674 -86.14156)
		(width 0.254)
		(layer "F.Cu")
		(net "PVCCIO_CPU0")
	)
	(segment
		(start 288.36366 -73.735184)
		(end 288.93516 -73.735184)
		(width 0.254)
		(layer "F.Cu")
		(net "PVCCIO_CPU0")
	)
	(segment
		(start 325.1962 -130.8354)
		(end 324.71614 -131.31546)
		(width 0.254)
		(layer "F.Cu")
		(net "PVCCIO_CPU0")
	)
	(segment
		(start 303.816766 -57.885584)
		(end 304.388266 -57.885584)
		(width 0.254)
		(layer "F.Cu")
		(net "PVCCIO_CPU0")
	)
	(segment
		(start 383.2098 -86.14156)
		(end 383.49936 -85.852)
		(width 0.254)
		(layer "F.Cu")
		(net "PVCCIO_CPU0")
	)
	(segment
		(start 290.93922 -86.117938)
		(end 291.51072 -86.117938)
		(width 0.254)
		(layer "F.Cu")
		(net "PVCCIO_CPU0")
	)
	(segment
		(start 299.524166 -55.409338)
		(end 300.095666 -55.409338)
		(width 0.254)
		(layer "F.Cu")
		(net "PVCCIO_CPU0")
	)
	(segment
		(start 297.807126 -89.089738)
		(end 298.378626 -89.089738)
		(width 0.254)
		(layer "F.Cu")
		(net "PVCCIO_CPU0")
	)
	(segment
		(start 303.529746 -70.268084)
		(end 302.958246 -70.268084)
		(width 0.254)
		(layer "F.Cu")
		(net "PVCCIO_CPU0")
	)
	(segment
		(start 422.3639 -108.077)
		(end 423.4307 -107.0102)
		(width 0.254)
		(layer "F.Cu")
		(net "PVCCIO_CPU0")
	)
	(segment
		(start 385.724908 -85.397086)
		(end 387.877558 -85.397086)
		(width 0.254)
		(layer "F.Cu")
		(net "PVCCIO_CPU0")
	)
	(segment
		(start 297.807126 -86.117938)
		(end 298.378626 -86.117938)
		(width 0.254)
		(layer "F.Cu")
		(net "PVCCIO_CPU0")
	)
	(segment
		(start 284.071314 -68.287138)
		(end 283.499814 -68.287138)
		(width 0.1016)
		(layer "F.Cu")
		(net "PVCCIO_CPU0")
	)
	(segment
		(start 378.921518 -84.531962)
		(end 380.973076 -84.531962)
		(width 0.254)
		(layer "F.Cu")
		(net "PVCCIO_CPU0")
	)
	(segment
		(start 306.392326 -55.409338)
		(end 306.963826 -55.409338)
		(width 0.254)
		(layer "F.Cu")
		(net "PVCCIO_CPU0")
	)
	(segment
		(start 388.62 -77.216)
		(end 389.2804 -77.8764)
		(width 0.254)
		(layer "F.Cu")
		(net "PVCCIO_CPU0")
	)
	(via
		(at 359.537 -89.7128)
		(size 0.508)
		(drill 0.254)
		(layers "F.Cu" "B.Cu")
		(net "PVCCIO_CPU0")
	)
	(via
		(at 303.529746 -60.362338)
		(size 0.508)
		(drill 0.254)
		(layers "F.Cu" "B.Cu")
		(net "PVCCIO_CPU0")
	)
	(via
		(at 366.078008 -139.352274)
		(size 0.508)
		(drill 0.254)
		(layers "F.Cu" "B.Cu")
		(net "PVCCIO_CPU0")
	)
	(via
		(at 469.444832 -12.554458)
		(size 0.508)
		(drill 0.254)
		(layers "F.Cu" "B.Cu")
		(net "PVCCIO_CPU0")
	)
	(via
		(at 304.388266 -85.622384)
		(size 0.508)
		(drill 0.254)
		(layers "F.Cu" "B.Cu")
		(net "PVCCIO_CPU0")
	)
	(via
		(at 299.237146 -70.763384)
		(size 0.508)
		(drill 0.254)
		(layers "F.Cu" "B.Cu")
		(net "PVCCIO_CPU0")
	)
	(via
		(at 286.3596 -74.230738)
		(size 0.508)
		(drill 0.254)
		(layers "F.Cu" "B.Cu")
		(net "PVCCIO_CPU0")
	)
	(via
		(at 336.877152 -102.123748)
		(size 0.508)
		(drill 0.254)
		(layers "F.Cu" "B.Cu")
		(net "PVCCIO_CPU0")
	)
	(via
		(at 375.567194 -53.26253)
		(size 0.508)
		(drill 0.254)
		(layers "F.Cu" "B.Cu")
		(net "PVCCIO_CPU0")
	)
	(via
		(at 375.434606 -46.3931)
		(size 0.508)
		(drill 0.254)
		(layers "F.Cu" "B.Cu")
		(net "PVCCIO_CPU0")
	)
	(via
		(at 339.061806 -107.0356)
		(size 0.508)
		(drill 0.254)
		(layers "F.Cu" "B.Cu")
		(net "PVCCIO_CPU0")
	)
	(via
		(at 284.358334 -75.716384)
		(size 0.508)
		(drill 0.254)
		(layers "F.Cu" "B.Cu")
		(net "PVCCIO_CPU0")
	)
	(via
		(at 304.388266 -63.829184)
		(size 0.508)
		(drill 0.254)
		(layers "F.Cu" "B.Cu")
		(net "PVCCIO_CPU0")
	)
	(via
		(at 279.084024 -78.699614)
		(size 0.508)
		(drill 0.254)
		(layers "F.Cu" "B.Cu")
		(net "PVCCIO_CPU0")
	)
	(via
		(at 443.567312 -14.988794)
		(size 0.508)
		(drill 0.254)
		(layers "F.Cu" "B.Cu")
		(net "PVCCIO_CPU0")
	)
	(via
		(at 337.582256 -101.487224)
		(size 0.508)
		(drill 0.254)
		(layers "F.Cu" "B.Cu")
		(net "PVCCIO_CPU0")
	)
	(via
		(at 284.358334 -76.706984)
		(size 0.508)
		(drill 0.254)
		(layers "F.Cu" "B.Cu")
		(net "PVCCIO_CPU0")
	)
	(via
		(at 300.095666 -67.296538)
		(size 0.508)
		(drill 0.254)
		(layers "F.Cu" "B.Cu")
		(net "PVCCIO_CPU0")
	)
	(via
		(at 335.387442 -101.493066)
		(size 0.508)
		(drill 0.254)
		(layers "F.Cu" "B.Cu")
		(net "PVCCIO_CPU0")
	)
	(via
		(at 300.095666 -60.362338)
		(size 0.508)
		(drill 0.254)
		(layers "F.Cu" "B.Cu")
		(net "PVCCIO_CPU0")
	)
	(via
		(at 337.8708 -95.8342)
		(size 0.508)
		(drill 0.254)
		(layers "F.Cu" "B.Cu")
		(net "PVCCIO_CPU0")
	)
	(via
		(at 330.28001 -108.687108)
		(size 0.508)
		(drill 0.254)
		(layers "F.Cu" "B.Cu")
		(net "PVCCIO_CPU0")
	)
	(via
		(at 286.3596 -71.258938)
		(size 0.508)
		(drill 0.254)
		(layers "F.Cu" "B.Cu")
		(net "PVCCIO_CPU0")
	)
	(via
		(at 290.6522 -93.547184)
		(size 0.508)
		(drill 0.254)
		(layers "F.Cu" "B.Cu")
		(net "PVCCIO_CPU0")
	)
	(via
		(at 304.388266 -71.753984)
		(size 0.508)
		(drill 0.254)
		(layers "F.Cu" "B.Cu")
		(net "PVCCIO_CPU0")
	)
	(via
		(at 305.246786 -60.362338)
		(size 0.508)
		(drill 0.254)
		(layers "F.Cu" "B.Cu")
		(net "PVCCIO_CPU0")
	)
	(via
		(at 278.308308 -78.715616)
		(size 0.508)
		(drill 0.254)
		(layers "F.Cu" "B.Cu")
		(net "PVCCIO_CPU0")
	)
	(via
		(at 307.040026 -98.005138)
		(size 0.508)
		(drill 0.254)
		(layers "F.Cu" "B.Cu")
		(net "PVCCIO_CPU0")
	)
	(via
		(at 277.490174 -62.838584)
		(size 0.508)
		(drill 0.254)
		(layers "F.Cu" "B.Cu")
		(net "PVCCIO_CPU0")
	)
	(via
		(at 466.71865 -145.75409)
		(size 0.508)
		(drill 0.254)
		(layers "F.Cu" "B.Cu")
		(net "PVCCIO_CPU0")
	)
	(via
		(at 337.752944 -106.427016)
		(size 0.508)
		(drill 0.254)
		(layers "F.Cu" "B.Cu")
		(net "PVCCIO_CPU0")
	)
	(via
		(at 365.0996 -62.0141)
		(size 0.508)
		(drill 0.254)
		(layers "F.Cu" "B.Cu")
		(net "PVCCIO_CPU0")
	)
	(via
		(at 350.064578 -100.220272)
		(size 0.508)
		(drill 0.254)
		(layers "F.Cu" "B.Cu")
		(net "PVCCIO_CPU0")
	)
	(via
		(at 296.66184 -93.052138)
		(size 0.508)
		(drill 0.254)
		(layers "F.Cu" "B.Cu")
		(net "PVCCIO_CPU0")
	)
	(via
		(at 306.105306 -58.876438)
		(size 0.508)
		(drill 0.254)
		(layers "F.Cu" "B.Cu")
		(net "PVCCIO_CPU0")
	)
	(via
		(at 303.529746 -87.108538)
		(size 0.508)
		(drill 0.254)
		(layers "F.Cu" "B.Cu")
		(net "PVCCIO_CPU0")
	)
	(via
		(at 293.22776 -57.390538)
		(size 0.508)
		(drill 0.254)
		(layers "F.Cu" "B.Cu")
		(net "PVCCIO_CPU0")
	)
	(via
		(at 338.426806 -107.0356)
		(size 0.508)
		(drill 0.254)
		(layers "F.Cu" "B.Cu")
		(net "PVCCIO_CPU0")
	)
	(via
		(at 332.603348 -61.018166)
		(size 0.508)
		(drill 0.254)
		(layers "F.Cu" "B.Cu")
		(net "PVCCIO_CPU0")
	)
	(via
		(at 285.501334 -84.631784)
		(size 0.508)
		(drill 0.254)
		(layers "F.Cu" "B.Cu")
		(net "PVCCIO_CPU0")
	)
	(via
		(at 288.07664 -73.240138)
		(size 0.508)
		(drill 0.254)
		(layers "F.Cu" "B.Cu")
		(net "PVCCIO_CPU0")
	)
	(via
		(at 298.378626 -86.117938)
		(size 0.508)
		(drill 0.254)
		(layers "F.Cu" "B.Cu")
		(net "PVCCIO_CPU0")
	)
	(via
		(at 290.6522 -89.584784)
		(size 0.508)
		(drill 0.254)
		(layers "F.Cu" "B.Cu")
		(net "PVCCIO_CPU0")
	)
	(via
		(at 334.718152 -102.250748)
		(size 0.508)
		(drill 0.254)
		(layers "F.Cu" "B.Cu")
		(net "PVCCIO_CPU0")
	)
	(via
		(at 332.70698 -126.810516)
		(size 0.508)
		(drill 0.254)
		(layers "F.Cu" "B.Cu")
		(net "PVCCIO_CPU0")
	)
	(via
		(at 377.915932 -86.464648)
		(size 0.508)
		(drill 0.254)
		(layers "F.Cu" "B.Cu")
		(net "PVCCIO_CPU0")
	)
	(via
		(at 338.012532 -97.48139)
		(size 0.508)
		(drill 0.254)
		(layers "F.Cu" "B.Cu")
		(net "PVCCIO_CPU0")
	)
	(via
		(at 301.812706 -94.042738)
		(size 0.508)
		(drill 0.254)
		(layers "F.Cu" "B.Cu")
		(net "PVCCIO_CPU0")
	)
	(via
		(at 335.801716 -96.66224)
		(size 0.508)
		(drill 0.254)
		(layers "F.Cu" "B.Cu")
		(net "PVCCIO_CPU0")
	)
	(via
		(at 294.9448 -95.033084)
		(size 0.508)
		(drill 0.254)
		(layers "F.Cu" "B.Cu")
		(net "PVCCIO_CPU0")
	)
	(via
		(at 300.095666 -98.005138)
		(size 0.508)
		(drill 0.254)
		(layers "F.Cu" "B.Cu")
		(net "PVCCIO_CPU0")
	)
	(via
		(at 302.671226 -56.894984)
		(size 0.508)
		(drill 0.254)
		(layers "F.Cu" "B.Cu")
		(net "PVCCIO_CPU0")
	)
	(via
		(at 425.48048 -111.691674)
		(size 0.508)
		(drill 0.254)
		(layers "F.Cu" "B.Cu")
		(net "PVCCIO_CPU0")
	)
	(via
		(at 336.115152 -102.123748)
		(size 0.508)
		(drill 0.254)
		(layers "F.Cu" "B.Cu")
		(net "PVCCIO_CPU0")
	)
	(via
		(at 336.517488 -97.455228)
		(size 0.508)
		(drill 0.254)
		(layers "F.Cu" "B.Cu")
		(net "PVCCIO_CPU0")
	)
	(via
		(at 336.517488 -96.693228)
		(size 0.508)
		(drill 0.254)
		(layers "F.Cu" "B.Cu")
		(net "PVCCIO_CPU0")
	)
	(via
		(at 288.07664 -75.221338)
		(size 0.508)
		(drill 0.254)
		(layers "F.Cu" "B.Cu")
		(net "PVCCIO_CPU0")
	)
	(via
		(at 294.49014 -65.96888)
		(size 0.508)
		(drill 0.254)
		(layers "F.Cu" "B.Cu")
		(net "PVCCIO_CPU0")
	)
	(via
		(at 296.66184 -91.070938)
		(size 0.508)
		(drill 0.254)
		(layers "F.Cu" "B.Cu")
		(net "PVCCIO_CPU0")
	)
	(via
		(at 336.482944 -106.444796)
		(size 0.508)
		(drill 0.254)
		(layers "F.Cu" "B.Cu")
		(net "PVCCIO_CPU0")
	)
	(via
		(at 335.1022 -96.139)
		(size 0.508)
		(drill 0.254)
		(layers "F.Cu" "B.Cu")
		(net "PVCCIO_CPU0")
	)
	(via
		(at 287.21812 -77.697584)
		(size 0.508)
		(drill 0.254)
		(layers "F.Cu" "B.Cu")
		(net "PVCCIO_CPU0")
	)
	(via
		(at 181.64302 -20.211796)
		(size 0.508)
		(drill 0.254)
		(layers "F.Cu" "B.Cu")
		(net "PVCCIO_CPU0")
	)
	(via
		(at 297.520106 -87.603584)
		(size 0.508)
		(drill 0.254)
		(layers "F.Cu" "B.Cu")
		(net "PVCCIO_CPU0")
	)
	(via
		(at 300.954186 -84.631784)
		(size 0.508)
		(drill 0.254)
		(layers "F.Cu" "B.Cu")
		(net "PVCCIO_CPU0")
	)
	(via
		(at 338.387944 -106.427016)
		(size 0.508)
		(drill 0.254)
		(layers "F.Cu" "B.Cu")
		(net "PVCCIO_CPU0")
	)
	(via
		(at 401.0914 -17.526)
		(size 0.508)
		(drill 0.254)
		(layers "F.Cu" "B.Cu")
		(net "PVCCIO_CPU0")
	)
	(via
		(at 336.058256 -101.487224)
		(size 0.508)
		(drill 0.254)
		(layers "F.Cu" "B.Cu")
		(net "PVCCIO_CPU0")
	)
	(via
		(at 177.10277 -67.842892)
		(size 0.508)
		(drill 0.254)
		(layers "F.Cu" "B.Cu")
		(net "PVCCIO_CPU0")
	)
	(via
		(at 335.88198 -107.0356)
		(size 0.508)
		(drill 0.254)
		(layers "F.Cu" "B.Cu")
		(net "PVCCIO_CPU0")
	)
	(via
		(at 184.33415 -61.35624)
		(size 0.508)
		(drill 0.254)
		(layers "F.Cu" "B.Cu")
		(net "PVCCIO_CPU0")
	)
	(via
		(at 285.501334 -82.650584)
		(size 0.508)
		(drill 0.254)
		(layers "F.Cu" "B.Cu")
		(net "PVCCIO_CPU0")
	)
	(via
		(at 295.80332 -86.612984)
		(size 0.508)
		(drill 0.254)
		(layers "F.Cu" "B.Cu")
		(net "PVCCIO_CPU0")
	)
	(via
		(at 336.55 -95.885)
		(size 0.508)
		(drill 0.254)
		(layers "F.Cu" "B.Cu")
		(net "PVCCIO_CPU0")
	)
	(via
		(at 300.954186 -64.819784)
		(size 0.508)
		(drill 0.254)
		(layers "F.Cu" "B.Cu")
		(net "PVCCIO_CPU0")
	)
	(via
		(at 303.529746 -70.268084)
		(size 0.508)
		(drill 0.254)
		(layers "F.Cu" "B.Cu")
		(net "PVCCIO_CPU0")
	)
	(via
		(at 280.354024 -78.826614)
		(size 0.508)
		(drill 0.254)
		(layers "F.Cu" "B.Cu")
		(net "PVCCIO_CPU0")
	)
	(via
		(at 460.617824 -148.209)
		(size 0.508)
		(drill 0.254)
		(layers "F.Cu" "B.Cu")
		(net "PVCCIO_CPU0")
	)
	(via
		(at 302.671226 -68.782184)
		(size 0.508)
		(drill 0.254)
		(layers "F.Cu" "B.Cu")
		(net "PVCCIO_CPU0")
	)
	(via
		(at 335.353152 -102.123748)
		(size 0.508)
		(drill 0.254)
		(layers "F.Cu" "B.Cu")
		(net "PVCCIO_CPU0")
	)
	(via
		(at 278.348694 -64.324738)
		(size 0.508)
		(drill 0.254)
		(layers "F.Cu" "B.Cu")
		(net "PVCCIO_CPU0")
	)
	(via
		(at 338.517992 -96.647762)
		(size 0.508)
		(drill 0.254)
		(layers "F.Cu" "B.Cu")
		(net "PVCCIO_CPU0")
	)
	(via
		(at 300.095666 -102.958138)
		(size 0.508)
		(drill 0.254)
		(layers "F.Cu" "B.Cu")
		(net "PVCCIO_CPU0")
	)
	(via
		(at 459.7654 -29.1338)
		(size 0.508)
		(drill 0.254)
		(layers "F.Cu" "B.Cu")
		(net "PVCCIO_CPU0")
	)
	(via
		(at 278.348694 -63.334138)
		(size 0.508)
		(drill 0.254)
		(layers "F.Cu" "B.Cu")
		(net "PVCCIO_CPU0")
	)
	(via
		(at 284.358334 -73.735184)
		(size 0.508)
		(drill 0.254)
		(layers "F.Cu" "B.Cu")
		(net "PVCCIO_CPU0")
	)
	(via
		(at 336.521806 -107.05338)
		(size 0.508)
		(drill 0.254)
		(layers "F.Cu" "B.Cu")
		(net "PVCCIO_CPU0")
	)
	(via
		(at 487.200702 -23.768304)
		(size 0.508)
		(drill 0.254)
		(layers "F.Cu" "B.Cu")
		(net "PVCCIO_CPU0")
	)
	(via
		(at 202.438 -102.7938)
		(size 0.508)
		(drill 0.254)
		(layers "F.Cu" "B.Cu")
		(net "PVCCIO_CPU0")
	)
	(via
		(at 338.26958 -101.47046)
		(size 0.508)
		(drill 0.254)
		(layers "F.Cu" "B.Cu")
		(net "PVCCIO_CPU0")
	)
	(via
		(at 338.012532 -99.00539)
		(size 0.508)
		(drill 0.254)
		(layers "F.Cu" "B.Cu")
		(net "PVCCIO_CPU0")
	)
	(via
		(at 300.095666 -63.334138)
		(size 0.508)
		(drill 0.254)
		(layers "F.Cu" "B.Cu")
		(net "PVCCIO_CPU0")
	)
	(via
		(at 287.21812 -75.716384)
		(size 0.508)
		(drill 0.254)
		(layers "F.Cu" "B.Cu")
		(net "PVCCIO_CPU0")
	)
	(via
		(at 338.4804 -95.8088)
		(size 0.508)
		(drill 0.254)
		(layers "F.Cu" "B.Cu")
		(net "PVCCIO_CPU0")
	)
	(via
		(at 275.773134 -62.838584)
		(size 0.508)
		(drill 0.254)
		(layers "F.Cu" "B.Cu")
		(net "PVCCIO_CPU0")
	)
	(via
		(at 337.6676 -102.749096)
		(size 0.508)
		(drill 0.254)
		(layers "F.Cu" "B.Cu")
		(net "PVCCIO_CPU0")
	)
	(via
		(at 286.3596 -72.249538)
		(size 0.508)
		(drill 0.254)
		(layers "F.Cu" "B.Cu")
		(net "PVCCIO_CPU0")
	)
	(via
		(at 324.3834 -31.15818)
		(size 0.508)
		(drill 0.254)
		(layers "F.Cu" "B.Cu")
		(net "PVCCIO_CPU0")
	)
	(via
		(at 390.7663 -79.8322)
		(size 0.508)
		(drill 0.254)
		(layers "F.Cu" "B.Cu")
		(net "PVCCIO_CPU0")
	)
	(via
		(at 299.237146 -99.490784)
		(size 0.508)
		(drill 0.254)
		(layers "F.Cu" "B.Cu")
		(net "PVCCIO_CPU0")
	)
	(via
		(at 336.1436 -102.749096)
		(size 0.508)
		(drill 0.254)
		(layers "F.Cu" "B.Cu")
		(net "PVCCIO_CPU0")
	)
	(via
		(at 302.671226 -92.556584)
		(size 0.508)
		(drill 0.254)
		(layers "F.Cu" "B.Cu")
		(net "PVCCIO_CPU0")
	)
	(via
		(at 300.095666 -55.409338)
		(size 0.508)
		(drill 0.254)
		(layers "F.Cu" "B.Cu")
		(net "PVCCIO_CPU0")
	)
	(via
		(at 367.15954 -88.983058)
		(size 0.508)
		(drill 0.254)
		(layers "F.Cu" "B.Cu")
		(net "PVCCIO_CPU0")
	)
	(via
		(at 283.499814 -66.305938)
		(size 0.508)
		(drill 0.254)
		(layers "F.Cu" "B.Cu")
		(net "PVCCIO_CPU0")
	)
	(via
		(at 373.732552 -44.1198)
		(size 0.508)
		(drill 0.254)
		(layers "F.Cu" "B.Cu")
		(net "PVCCIO_CPU0")
	)
	(via
		(at 334.718152 -101.615748)
		(size 0.508)
		(drill 0.254)
		(layers "F.Cu" "B.Cu")
		(net "PVCCIO_CPU0")
	)
	(via
		(at 299.237146 -68.782184)
		(size 0.508)
		(drill 0.254)
		(layers "F.Cu" "B.Cu")
		(net "PVCCIO_CPU0")
	)
	(via
		(at 455.041 -154.051)
		(size 0.508)
		(drill 0.254)
		(layers "F.Cu" "B.Cu")
		(net "PVCCIO_CPU0")
	)
	(via
		(at 295.80332 -101.471984)
		(size 0.508)
		(drill 0.254)
		(layers "F.Cu" "B.Cu")
		(net "PVCCIO_CPU0")
	)
	(via
		(at 297.520106 -54.913784)
		(size 0.508)
		(drill 0.254)
		(layers "F.Cu" "B.Cu")
		(net "PVCCIO_CPU0")
	)
	(via
		(at 304.388266 -66.800984)
		(size 0.508)
		(drill 0.254)
		(layers "F.Cu" "B.Cu")
		(net "PVCCIO_CPU0")
	)
	(via
		(at 288.07664 -71.258938)
		(size 0.508)
		(drill 0.254)
		(layers "F.Cu" "B.Cu")
		(net "PVCCIO_CPU0")
	)
	(via
		(at 294.08628 -96.518984)
		(size 0.508)
		(drill 0.254)
		(layers "F.Cu" "B.Cu")
		(net "PVCCIO_CPU0")
	)
	(via
		(at 375.097294 -39.9796)
		(size 0.508)
		(drill 0.254)
		(layers "F.Cu" "B.Cu")
		(net "PVCCIO_CPU0")
	)
	(via
		(at 300.954186 -82.650584)
		(size 0.508)
		(drill 0.254)
		(layers "F.Cu" "B.Cu")
		(net "PVCCIO_CPU0")
	)
	(via
		(at 336.9056 -102.749096)
		(size 0.508)
		(drill 0.254)
		(layers "F.Cu" "B.Cu")
		(net "PVCCIO_CPU0")
	)
	(via
		(at 284.071314 -84.555838)
		(size 0.508)
		(drill 0.254)
		(layers "F.Cu" "B.Cu")
		(net "PVCCIO_CPU0")
	)
	(via
		(at 295.80332 -55.904384)
		(size 0.508)
		(drill 0.254)
		(layers "F.Cu" "B.Cu")
		(net "PVCCIO_CPU0")
	)
	(via
		(at 455.536808 -149.022054)
		(size 0.508)
		(drill 0.254)
		(layers "F.Cu" "B.Cu")
		(net "PVCCIO_CPU0")
	)
	(via
		(at 337.639152 -102.123748)
		(size 0.508)
		(drill 0.254)
		(layers "F.Cu" "B.Cu")
		(net "PVCCIO_CPU0")
	)
	(via
		(at 277.490174 -63.829184)
		(size 0.508)
		(drill 0.254)
		(layers "F.Cu" "B.Cu")
		(net "PVCCIO_CPU0")
	)
	(via
		(at 293.22776 -92.061538)
		(size 0.508)
		(drill 0.254)
		(layers "F.Cu" "B.Cu")
		(net "PVCCIO_CPU0")
	)
	(via
		(at 336.820256 -101.487224)
		(size 0.508)
		(drill 0.254)
		(layers "F.Cu" "B.Cu")
		(net "PVCCIO_CPU0")
	)
	(via
		(at 324.757542 -131.977384)
		(size 0.508)
		(drill 0.254)
		(layers "F.Cu" "B.Cu")
		(net "PVCCIO_CPU0")
	)
	(via
		(at 129.211578 -65.667128)
		(size 0.508)
		(drill 0.254)
		(layers "F.Cu" "B.Cu")
		(net "PVCCIO_CPU0")
	)
	(via
		(at 337.2612 -97.409)
		(size 0.508)
		(drill 0.254)
		(layers "F.Cu" "B.Cu")
		(net "PVCCIO_CPU0")
	)
	(via
		(at 296.66184 -56.399938)
		(size 0.508)
		(drill 0.254)
		(layers "F.Cu" "B.Cu")
		(net "PVCCIO_CPU0")
	)
	(via
		(at 337.2358 -96.6216)
		(size 0.508)
		(drill 0.254)
		(layers "F.Cu" "B.Cu")
		(net "PVCCIO_CPU0")
	)
	(via
		(at 436.6895 -45.5041)
		(size 0.508)
		(drill 0.254)
		(layers "F.Cu" "B.Cu")
		(net "PVCCIO_CPU0")
	)
	(via
		(at 283.499814 -68.287138)
		(size 0.508)
		(drill 0.254)
		(layers "F.Cu" "B.Cu")
		(net "PVCCIO_CPU0")
	)
	(via
		(at 302.671226 -52.932838)
		(size 0.508)
		(drill 0.254)
		(layers "F.Cu" "B.Cu")
		(net "PVCCIO_CPU0")
	)
	(via
		(at 335.843118 -106.427016)
		(size 0.508)
		(drill 0.254)
		(layers "F.Cu" "B.Cu")
		(net "PVCCIO_CPU0")
	)
	(via
		(at 286.3596 -82.155284)
		(size 0.508)
		(drill 0.254)
		(layers "F.Cu" "B.Cu")
		(net "PVCCIO_CPU0")
	)
	(via
		(at 287.21812 -74.725784)
		(size 0.508)
		(drill 0.254)
		(layers "F.Cu" "B.Cu")
		(net "PVCCIO_CPU0")
	)
	(via
		(at 294.08628 -81.659984)
		(size 0.508)
		(drill 0.254)
		(layers "F.Cu" "B.Cu")
		(net "PVCCIO_CPU0")
	)
	(via
		(at 339.5599 -19.4183)
		(size 0.508)
		(drill 0.254)
		(layers "F.Cu" "B.Cu")
		(net "PVCCIO_CPU0")
	)
	(via
		(at 305.246786 -62.343538)
		(size 0.508)
		(drill 0.254)
		(layers "F.Cu" "B.Cu")
		(net "PVCCIO_CPU0")
	)
	(via
		(at 390.78408 -3.025394)
		(size 0.508)
		(drill 0.254)
		(layers "F.Cu" "B.Cu")
		(net "PVCCIO_CPU0")
	)
	(via
		(at 337.117944 -106.43362)
		(size 0.508)
		(drill 0.254)
		(layers "F.Cu" "B.Cu")
		(net "PVCCIO_CPU0")
	)
	(via
		(at 371.8941 -59.8297)
		(size 0.508)
		(drill 0.254)
		(layers "F.Cu" "B.Cu")
		(net "PVCCIO_CPU0")
	)
	(via
		(at 304.388266 -57.885584)
		(size 0.508)
		(drill 0.254)
		(layers "F.Cu" "B.Cu")
		(net "PVCCIO_CPU0")
	)
	(via
		(at 292.36924 -97.509584)
		(size 0.508)
		(drill 0.254)
		(layers "F.Cu" "B.Cu")
		(net "PVCCIO_CPU0")
	)
	(via
		(at 291.51072 -98.995738)
		(size 0.508)
		(drill 0.254)
		(layers "F.Cu" "B.Cu")
		(net "PVCCIO_CPU0")
	)
	(via
		(at 337.791806 -107.0356)
		(size 0.508)
		(drill 0.254)
		(layers "F.Cu" "B.Cu")
		(net "PVCCIO_CPU0")
	)
	(via
		(at 338.321142 -102.76332)
		(size 0.508)
		(drill 0.254)
		(layers "F.Cu" "B.Cu")
		(net "PVCCIO_CPU0")
	)
	(via
		(at 284.358334 -71.753984)
		(size 0.508)
		(drill 0.254)
		(layers "F.Cu" "B.Cu")
		(net "PVCCIO_CPU0")
	)
	(via
		(at 286.3596 -76.211938)
		(size 0.508)
		(drill 0.254)
		(layers "F.Cu" "B.Cu")
		(net "PVCCIO_CPU0")
	)
	(via
		(at 296.66184 -59.371484)
		(size 0.508)
		(drill 0.254)
		(layers "F.Cu" "B.Cu")
		(net "PVCCIO_CPU0")
	)
	(via
		(at 297.520106 -81.659984)
		(size 0.508)
		(drill 0.254)
		(layers "F.Cu" "B.Cu")
		(net "PVCCIO_CPU0")
	)
	(via
		(at 279.193244 -70.850252)
		(size 0.508)
		(drill 0.254)
		(layers "F.Cu" "B.Cu")
		(net "PVCCIO_CPU0")
	)
	(via
		(at 288.93516 -73.735184)
		(size 0.508)
		(drill 0.254)
		(layers "F.Cu" "B.Cu")
		(net "PVCCIO_CPU0")
	)
	(via
		(at 337.2104 -95.8596)
		(size 0.508)
		(drill 0.254)
		(layers "F.Cu" "B.Cu")
		(net "PVCCIO_CPU0")
	)
	(via
		(at 181.34838 -78.95844)
		(size 0.508)
		(drill 0.254)
		(layers "F.Cu" "B.Cu")
		(net "PVCCIO_CPU0")
	)
	(via
		(at 278.576024 -70.851014)
		(size 0.508)
		(drill 0.254)
		(layers "F.Cu" "B.Cu")
		(net "PVCCIO_CPU0")
	)
	(via
		(at 335.8134 -95.9612)
		(size 0.508)
		(drill 0.254)
		(layers "F.Cu" "B.Cu")
		(net "PVCCIO_CPU0")
	)
	(via
		(at 392.0998 -81.9404)
		(size 0.508)
		(drill 0.254)
		(layers "F.Cu" "B.Cu")
		(net "PVCCIO_CPU0")
	)
	(via
		(at 338.4931 -95.1103)
		(size 0.508)
		(drill 0.254)
		(layers "F.Cu" "B.Cu")
		(net "PVCCIO_CPU0")
	)
	(via
		(at 337.86826 -96.623124)
		(size 0.508)
		(drill 0.254)
		(layers "F.Cu" "B.Cu")
		(net "PVCCIO_CPU0")
	)
	(via
		(at 304.388266 -83.641184)
		(size 0.508)
		(drill 0.254)
		(layers "F.Cu" "B.Cu")
		(net "PVCCIO_CPU0")
	)
	(via
		(at 293.22776 -83.146138)
		(size 0.508)
		(drill 0.254)
		(layers "F.Cu" "B.Cu")
		(net "PVCCIO_CPU0")
	)
	(via
		(at 460.972408 -132.054854)
		(size 0.508)
		(drill 0.254)
		(layers "F.Cu" "B.Cu")
		(net "PVCCIO_CPU0")
	)
	(via
		(at 284.358334 -70.763384)
		(size 0.508)
		(drill 0.254)
		(layers "F.Cu" "B.Cu")
		(net "PVCCIO_CPU0")
	)
	(via
		(at 337.156806 -107.042204)
		(size 0.508)
		(drill 0.254)
		(layers "F.Cu" "B.Cu")
		(net "PVCCIO_CPU0")
	)
	(via
		(at 296.66184 -84.136738)
		(size 0.508)
		(drill 0.254)
		(layers "F.Cu" "B.Cu")
		(net "PVCCIO_CPU0")
	)
	(via
		(at 171.245276 -91.050618)
		(size 0.508)
		(drill 0.254)
		(layers "F.Cu" "B.Cu")
		(net "PVCCIO_CPU0")
	)
	(via
		(at 282.641294 -66.800984)
		(size 0.508)
		(drill 0.254)
		(layers "F.Cu" "B.Cu")
		(net "PVCCIO_CPU0")
	)
	(via
		(at 302.671226 -89.584784)
		(size 0.508)
		(drill 0.254)
		(layers "F.Cu" "B.Cu")
		(net "PVCCIO_CPU0")
	)
	(via
		(at 291.51072 -86.117938)
		(size 0.508)
		(drill 0.254)
		(layers "F.Cu" "B.Cu")
		(net "PVCCIO_CPU0")
	)
	(via
		(at 375.1834 -0.6096)
		(size 0.508)
		(drill 0.254)
		(layers "F.Cu" "B.Cu")
		(net "PVCCIO_CPU0")
	)
	(via
		(at 276.631654 -63.334138)
		(size 0.508)
		(drill 0.254)
		(layers "F.Cu" "B.Cu")
		(net "PVCCIO_CPU0")
	)
	(via
		(at 298.378626 -89.089738)
		(size 0.508)
		(drill 0.254)
		(layers "F.Cu" "B.Cu")
		(net "PVCCIO_CPU0")
	)
	(via
		(at 301.812706 -97.014538)
		(size 0.508)
		(drill 0.254)
		(layers "F.Cu" "B.Cu")
		(net "PVCCIO_CPU0")
	)
	(via
		(at 299.237146 -56.894984)
		(size 0.508)
		(drill 0.254)
		(layers "F.Cu" "B.Cu")
		(net "PVCCIO_CPU0")
	)
	(via
		(at 297.520106 -93.547184)
		(size 0.508)
		(drill 0.254)
		(layers "F.Cu" "B.Cu")
		(net "PVCCIO_CPU0")
	)
	(via
		(at 285.501334 -83.641184)
		(size 0.508)
		(drill 0.254)
		(layers "F.Cu" "B.Cu")
		(net "PVCCIO_CPU0")
	)
	(via
		(at 284.358334 -74.725784)
		(size 0.508)
		(drill 0.254)
		(layers "F.Cu" "B.Cu")
		(net "PVCCIO_CPU0")
	)
	(via
		(at 290.6522 -95.528384)
		(size 0.508)
		(drill 0.254)
		(layers "F.Cu" "B.Cu")
		(net "PVCCIO_CPU0")
	)
	(via
		(at 302.671226 -94.538038)
		(size 0.508)
		(drill 0.254)
		(layers "F.Cu" "B.Cu")
		(net "PVCCIO_CPU0")
	)
	(via
		(at 276.631654 -62.343538)
		(size 0.508)
		(drill 0.254)
		(layers "F.Cu" "B.Cu")
		(net "PVCCIO_CPU0")
	)
	(via
		(at 336.475578 -138.555222)
		(size 0.508)
		(drill 0.254)
		(layers "F.Cu" "B.Cu")
		(net "PVCCIO_CPU0")
	)
	(via
		(at 330.312776 -68.051426)
		(size 0.508)
		(drill 0.254)
		(layers "F.Cu" "B.Cu")
		(net "PVCCIO_CPU0")
	)
	(via
		(at 338.012532 -98.24339)
		(size 0.508)
		(drill 0.254)
		(layers "F.Cu" "B.Cu")
		(net "PVCCIO_CPU0")
	)
	(via
		(at 300.954186 -56.894984)
		(size 0.508)
		(drill 0.254)
		(layers "F.Cu" "B.Cu")
		(net "PVCCIO_CPU0")
	)
	(via
		(at 291.51072 -62.343538)
		(size 0.508)
		(drill 0.254)
		(layers "F.Cu" "B.Cu")
		(net "PVCCIO_CPU0")
	)
	(via
		(at 339.081618 -106.426254)
		(size 0.508)
		(drill 0.254)
		(layers "F.Cu" "B.Cu")
		(net "PVCCIO_CPU0")
	)
	(via
		(at 279.719024 -78.445614)
		(size 0.508)
		(drill 0.254)
		(layers "F.Cu" "B.Cu")
		(net "PVCCIO_CPU0")
	)
	(via
		(at 304.388266 -68.782184)
		(size 0.508)
		(drill 0.254)
		(layers "F.Cu" "B.Cu")
		(net "PVCCIO_CPU0")
	)
	(via
		(at 290.6522 -56.894984)
		(size 0.508)
		(drill 0.254)
		(layers "F.Cu" "B.Cu")
		(net "PVCCIO_CPU0")
	)
	(via
		(at 286.3596 -70.268084)
		(size 0.508)
		(drill 0.254)
		(layers "F.Cu" "B.Cu")
		(net "PVCCIO_CPU0")
	)
	(via
		(at 335.3816 -102.749096)
		(size 0.508)
		(drill 0.254)
		(layers "F.Cu" "B.Cu")
		(net "PVCCIO_CPU0")
	)
	(via
		(at 294.08628 -90.575384)
		(size 0.508)
		(drill 0.254)
		(layers "F.Cu" "B.Cu")
		(net "PVCCIO_CPU0")
	)
	(via
		(at 293.22776 -89.089738)
		(size 0.508)
		(drill 0.254)
		(layers "F.Cu" "B.Cu")
		(net "PVCCIO_CPU0")
	)
	(via
		(at 300.095666 -61.352938)
		(size 0.508)
		(drill 0.254)
		(layers "F.Cu" "B.Cu")
		(net "PVCCIO_CPU0")
	)
	(via
		(at 306.963826 -55.409338)
		(size 0.508)
		(drill 0.254)
		(layers "F.Cu" "B.Cu")
		(net "PVCCIO_CPU0")
	)
	(via
		(at 338.291424 -102.10673)
		(size 0.508)
		(drill 0.254)
		(layers "F.Cu" "B.Cu")
		(net "PVCCIO_CPU0")
	)
	(via
		(at 279.993344 -69.804026)
		(size 0.508)
		(drill 0.254)
		(layers "F.Cu" "B.Cu")
		(net "PVCCIO_CPU0")
	)
	(via
		(at 294.9448 -56.399938)
		(size 0.508)
		(drill 0.254)
		(layers "F.Cu" "B.Cu")
		(net "PVCCIO_CPU0")
	)
	(via
		(at 286.3596 -75.221338)
		(size 0.508)
		(drill 0.254)
		(layers "F.Cu" "B.Cu")
		(net "PVCCIO_CPU0")
	)
	(via
		(at 298.378626 -100.976684)
		(size 0.508)
		(drill 0.254)
		(layers "F.Cu" "B.Cu")
		(net "PVCCIO_CPU0")
	)
	(via
		(at 280.354024 -78.191614)
		(size 0.508)
		(drill 0.254)
		(layers "F.Cu" "B.Cu")
		(net "PVCCIO_CPU0")
	)
	(segment
		(start 328.179176 -61.087)
		(end 327.914 -61.087)
		(width 0.254)
		(layer "B.Cu")
		(net "PVCCIO_CPU0")
	)
	(segment
		(start 176.586642 -68.35902)
		(end 177.10277 -67.842892)
		(width 0.254)
		(layer "B.Cu")
		(net "PVCCIO_CPU0")
	)
	(segment
		(start 357.694484 -89.7128)
		(end 356.546404 -90.86088)
		(width 0.254)
		(layer "B.Cu")
		(net "PVCCIO_CPU0")
	)
	(segment
		(start 321.0433 -31.5849)
		(end 321.1957 -31.7373)
		(width 0.4064)
		(layer "B.Cu")
		(net "PVCCIO_CPU0")
	)
	(segment
		(start 338.961476 -88.355424)
		(end 340.1187 -87.1982)
		(width 0.254)
		(layer "B.Cu")
		(net "PVCCIO_CPU0")
	)
	(segment
		(start 179.804822 -20.014692)
		(end 180.653182 -20.014692)
		(width 0.254)
		(layer "B.Cu")
		(net "PVCCIO_CPU0")
	)
	(segment
		(start 277.75154 -68.58)
		(end 278.576024 -69.404484)
		(width 0.4064)
		(layer "B.Cu")
		(net "PVCCIO_CPU0")
	)
	(segment
		(start 403.228302 -6.761734)
		(end 403.228302 -15.389098)
		(width 0.254)
		(layer "B.Cu")
		(net "PVCCIO_CPU0")
	)
	(segment
		(start 181.52618 -20.23364)
		(end 181.307232 -20.014692)
		(width 0.254)
		(layer "B.Cu")
		(net "PVCCIO_CPU0")
	)
	(segment
		(start 375.574306 -46.5328)
		(end 375.434606 -46.3931)
		(width 0.254)
		(layer "B.Cu")
		(net "PVCCIO_CPU0")
	)
	(segment
		(start 128.8796 -66.292984)
		(end 128.8796 -65.999106)
		(width 0.254)
		(layer "B.Cu")
		(net "PVCCIO_CPU0")
	)
	(segment
		(start 186.073542 -62.238636)
		(end 184.74055 -62.238636)
		(width 0.4064)
		(layer "B.Cu")
		(net "PVCCIO_CPU0")
	)
	(segment
		(start 338.7344 -17.272)
		(end 338.7344 -18.16354)
		(width 0.508)
		(layer "B.Cu")
		(net "PVCCIO_CPU0")
	)
	(segment
		(start 321.427856 -30.493716)
		(end 321.0433 -30.878272)
		(width 0.4064)
		(layer "B.Cu")
		(net "PVCCIO_CPU0")
	)
	(segment
		(start 187.451746 -63.61684)
		(end 186.073542 -62.238636)
		(width 0.4064)
		(layer "B.Cu")
		(net "PVCCIO_CPU0")
	)
	(segment
		(start 403.228302 -15.389098)
		(end 401.0914 -17.526)
		(width 0.254)
		(layer "B.Cu")
		(net "PVCCIO_CPU0")
	)
	(segment
		(start 337.439 -92.0242)
		(end 337.439 -90.596466)
		(width 0.254)
		(layer "B.Cu")
		(net "PVCCIO_CPU0")
	)
	(segment
		(start 338.961476 -89.07399)
		(end 338.961476 -88.355424)
		(width 0.254)
		(layer "B.Cu")
		(net "PVCCIO_CPU0")
	)
	(segment
		(start 164.6428 -71.9836)
		(end 165.427152 -71.199248)
		(width 0.254)
		(layer "B.Cu")
		(net "PVCCIO_CPU0")
	)
	(segment
		(start 328.38898 -111.839756)
		(end 328.83983 -112.290606)
		(width 0.4064)
		(layer "B.Cu")
		(net "PVCCIO_CPU0")
	)
	(segment
		(start 224.815146 -55.2196)
		(end 220.737684 -51.142138)
		(width 0.4064)
		(layer "B.Cu")
		(net "PVCCIO_CPU0")
	)
	(segment
		(start 181.307232 -20.014692)
		(end 180.653182 -20.014692)
		(width 0.254)
		(layer "B.Cu")
		(net "PVCCIO_CPU0")
	)
	(segment
		(start 171.245276 -91.050618)
		(end 173.845982 -91.050618)
		(width 0.254)
		(layer "B.Cu")
		(net "PVCCIO_CPU0")
	)
	(segment
		(start 330.095606 -65.303908)
		(end 330.095606 -64.179958)
		(width 0.254)
		(layer "B.Cu")
		(net "PVCCIO_CPU0")
	)
	(segment
		(start 460.617824 -148.209)
		(end 461.17637 -147.650454)
		(width 0.4064)
		(layer "B.Cu")
		(net "PVCCIO_CPU0")
	)
	(segment
		(start 377.063 -46.5328)
		(end 375.574306 -46.5328)
		(width 0.254)
		(layer "B.Cu")
		(net "PVCCIO_CPU0")
	)
	(segment
		(start 330.312776 -68.051426)
		(end 330.08316 -67.82181)
		(width 0.254)
		(layer "B.Cu")
		(net "PVCCIO_CPU0")
	)
	(segment
		(start 327.34504 -123.5075)
		(end 326.6567 -122.81916)
		(width 0.254)
		(layer "B.Cu")
		(net "PVCCIO_CPU0")
	)
	(segment
		(start 373.884952 -43.9674)
		(end 373.884952 -43.224958)
		(width 0.254)
		(layer "B.Cu")
		(net "PVCCIO_CPU0")
	)
	(segment
		(start 373.732552 -44.1198)
		(end 373.884952 -43.9674)
		(width 0.254)
		(layer "B.Cu")
		(net "PVCCIO_CPU0")
	)
	(segment
		(start 433.84089 -42.925746)
		(end 433.833524 -42.91838)
		(width 0.254)
		(layer "B.Cu")
		(net "PVCCIO_CPU0")
	)
	(segment
		(start 295.1226 -65.462404)
		(end 294.996616 -65.462404)
		(width 0.254)
		(layer "B.Cu")
		(net "PVCCIO_CPU0")
	)
	(segment
		(start 330.08316 -66.25336)
		(end 330.08316 -65.316354)
		(width 0.254)
		(layer "B.Cu")
		(net "PVCCIO_CPU0")
	)
	(segment
		(start 375.571004 -53.749956)
		(end 375.413524 -53.907436)
		(width 0.254)
		(layer "B.Cu")
		(net "PVCCIO_CPU0")
	)
	(segment
		(start 337.439 -90.596466)
		(end 338.961476 -89.07399)
		(width 0.254)
		(layer "B.Cu")
		(net "PVCCIO_CPU0")
	)
	(segment
		(start 390.779 -3.302)
		(end 391.364216 -3.887216)
		(width 0.254)
		(layer "B.Cu")
		(net "PVCCIO_CPU0")
	)
	(segment
		(start 340.966552 -92.636848)
		(end 352.645726 -92.636848)
		(width 0.254)
		(layer "B.Cu")
		(net "PVCCIO_CPU0")
	)
	(segment
		(start 374.777 -55.334916)
		(end 374.777 -57.4548)
		(width 0.254)
		(layer "B.Cu")
		(net "PVCCIO_CPU0")
	)
	(segment
		(start 323.718936 -30.493716)
		(end 321.427856 -30.493716)
		(width 0.4064)
		(layer "B.Cu")
		(net "PVCCIO_CPU0")
	)
	(segment
		(start 184.33415 -61.832236)
		(end 184.33415 -61.35624)
		(width 0.4064)
		(layer "B.Cu")
		(net "PVCCIO_CPU0")
	)
	(segment
		(start 433.84089 -43.70578)
		(end 433.24272 -43.70578)
		(width 0.254)
		(layer "B.Cu")
		(net "PVCCIO_CPU0")
	)
	(segment
		(start 330.08316 -67.26936)
		(end 330.08316 -66.25336)
		(width 0.254)
		(layer "B.Cu")
		(net "PVCCIO_CPU0")
	)
	(segment
		(start 328.38898 -110.578138)
		(end 328.38898 -111.839756)
		(width 0.4064)
		(layer "B.Cu")
		(net "PVCCIO_CPU0")
	)
	(segment
		(start 195.136516 -50.879756)
		(end 193.404236 -52.612036)
		(width 0.4064)
		(layer "B.Cu")
		(net "PVCCIO_CPU0")
	)
	(segment
		(start 230.89616 -55.2196)
		(end 224.815146 -55.2196)
		(width 0.4064)
		(layer "B.Cu")
		(net "PVCCIO_CPU0")
	)
	(segment
		(start 377.3932 -45.5676)
		(end 377.3932 -46.2026)
		(width 0.254)
		(layer "B.Cu")
		(net "PVCCIO_CPU0")
	)
	(segment
		(start 378.587 -86.233)
		(end 378.209048 -86.233)
		(width 0.254)
		(layer "B.Cu")
		(net "PVCCIO_CPU0")
	)
	(segment
		(start 321.0433 -30.878272)
		(end 321.0433 -31.5849)
		(width 0.4064)
		(layer "B.Cu")
		(net "PVCCIO_CPU0")
	)
	(segment
		(start 375.413524 -53.907436)
		(end 375.413524 -54.698392)
		(width 0.254)
		(layer "B.Cu")
		(net "PVCCIO_CPU0")
	)
	(segment
		(start 375.270268 -47.566326)
		(end 375.270268 -46.557438)
		(width 0.254)
		(layer "B.Cu")
		(net "PVCCIO_CPU0")
	)
	(segment
		(start 208.439766 -48.8696)
		(end 202.3872 -48.8696)
		(width 0.4064)
		(layer "B.Cu")
		(net "PVCCIO_CPU0")
	)
	(segment
		(start 339.5599 -19.4183)
		(end 338.7344 -18.5928)
		(width 0.508)
		(layer "B.Cu")
		(net "PVCCIO_CPU0")
	)
	(segment
		(start 163.531042 -71.982076)
		(end 162.463988 -71.982076)
		(width 0.254)
		(layer "B.Cu")
		(net "PVCCIO_CPU0")
	)
	(segment
		(start 333.423514 -107.24896)
		(end 331.718158 -107.24896)
		(width 0.4064)
		(layer "B.Cu")
		(net "PVCCIO_CPU0")
	)
	(segment
		(start 391.364216 -3.887216)
		(end 400.353784 -3.887216)
		(width 0.254)
		(layer "B.Cu")
		(net "PVCCIO_CPU0")
	)
	(segment
		(start 337.3501 -57.5564)
		(end 332.62062 -57.5564)
		(width 0.254)
		(layer "B.Cu")
		(net "PVCCIO_CPU0")
	)
	(segment
		(start 330.28001 -108.687108)
		(end 328.38898 -110.578138)
		(width 0.4064)
		(layer "B.Cu")
		(net "PVCCIO_CPU0")
	)
	(segment
		(start 327.914 -61.849)
		(end 327.914 -62.992)
		(width 0.254)
		(layer "B.Cu")
		(net "PVCCIO_CPU0")
	)
	(segment
		(start 165.427152 -71.199248)
		(end 166.417498 -71.199248)
		(width 0.254)
		(layer "B.Cu")
		(net "PVCCIO_CPU0")
	)
	(segment
		(start 376.9614 -45.1358)
		(end 377.3932 -45.5676)
		(width 0.254)
		(layer "B.Cu")
		(net "PVCCIO_CPU0")
	)
	(segment
		(start 460.972408 -132.054854)
		(end 461.658208 -132.740654)
		(width 0.4064)
		(layer "B.Cu")
		(net "PVCCIO_CPU0")
	)
	(segment
		(start 162.179 -69.596)
		(end 162.179 -70.358)
		(width 0.254)
		(layer "B.Cu")
		(net "PVCCIO_CPU0")
	)
	(segment
		(start 375.270268 -46.557438)
		(end 375.434606 -46.3931)
		(width 0.254)
		(layer "B.Cu")
		(net "PVCCIO_CPU0")
	)
	(segment
		(start 181.282848 -78.95844)
		(end 181.34838 -78.95844)
		(width 0.254)
		(layer "B.Cu")
		(net "PVCCIO_CPU0")
	)
	(segment
		(start 183.0324 -90.305382)
		(end 183.0324 -80.64246)
		(width 0.254)
		(layer "B.Cu")
		(net "PVCCIO_CPU0")
	)
	(segment
		(start 332.70698 -126.810516)
		(end 329.032616 -126.810516)
		(width 0.4064)
		(layer "B.Cu")
		(net "PVCCIO_CPU0")
	)
	(segment
		(start 433.07 -43.8785)
		(end 433.07 -44.577)
		(width 0.254)
		(layer "B.Cu")
		(net "PVCCIO_CPU0")
	)
	(segment
		(start 338.4931 -95.1103)
		(end 340.966552 -92.636848)
		(width 0.254)
		(layer "B.Cu")
		(net "PVCCIO_CPU0")
	)
	(segment
		(start 354.258372 -92.105988)
		(end 354.597208 -91.767152)
		(width 0.254)
		(layer "B.Cu")
		(net "PVCCIO_CPU0")
	)
	(segment
		(start 183.0324 -80.64246)
		(end 181.34838 -78.95844)
		(width 0.254)
		(layer "B.Cu")
		(net "PVCCIO_CPU0")
	)
	(segment
		(start 329.206606 -60.05957)
		(end 328.179176 -61.087)
		(width 0.254)
		(layer "B.Cu")
		(net "PVCCIO_CPU0")
	)
	(segment
		(start 167.278304 -69.996558)
		(end 169.393362 -67.8815)
		(width 0.254)
		(layer "B.Cu")
		(net "PVCCIO_CPU0")
	)
	(segment
		(start 433.9971 -45.5041)
		(end 436.6895 -45.5041)
		(width 0.254)
		(layer "B.Cu")
		(net "PVCCIO_CPU0")
	)
	(segment
		(start 325.7804 -123.2027)
		(end 326.3519 -123.7742)
		(width 0.254)
		(layer "B.Cu")
		(net "PVCCIO_CPU0")
	)
	(segment
		(start 461.658208 -132.740654)
		(end 461.658208 -132.842254)
		(width 0.4064)
		(layer "B.Cu")
		(net "PVCCIO_CPU0")
	)
	(segment
		(start 366.078008 -139.352274)
		(end 366.078008 -139.483592)
		(width 0.4064)
		(layer "B.Cu")
		(net "PVCCIO_CPU0")
	)
	(segment
		(start 366.078008 -139.483592)
		(end 365.55807 -140.00353)
		(width 0.4064)
		(layer "B.Cu")
		(net "PVCCIO_CPU0")
	)
	(segment
		(start 192.056004 -57.321196)
		(end 191.1858 -58.1914)
		(width 0.4064)
		(layer "B.Cu")
		(net "PVCCIO_CPU0")
	)
	(segment
		(start 338.7344 -18.5928)
		(end 338.7344 -18.16354)
		(width 0.508)
		(layer "B.Cu")
		(net "PVCCIO_CPU0")
	)
	(segment
		(start 332.62062 -57.5564)
		(end 330.11745 -60.05957)
		(width 0.254)
		(layer "B.Cu")
		(net "PVCCIO_CPU0")
	)
	(segment
		(start 193.404236 -52.612036)
		(end 193.404236 -54.294278)
		(width 0.4064)
		(layer "B.Cu")
		(net "PVCCIO_CPU0")
	)
	(segment
		(start 374.777 -57.4548)
		(end 375.1072 -57.785)
		(width 0.254)
		(layer "B.Cu")
		(net "PVCCIO_CPU0")
	)
	(segment
		(start 163.531042 -71.982076)
		(end 164.641276 -71.982076)
		(width 0.254)
		(layer "B.Cu")
		(net "PVCCIO_CPU0")
	)
	(segment
		(start 184.74055 -62.238636)
		(end 184.33415 -61.832236)
		(width 0.4064)
		(layer "B.Cu")
		(net "PVCCIO_CPU0")
	)
	(segment
		(start 331.0255 -61.341)
		(end 332.280514 -61.341)
		(width 0.254)
		(layer "B.Cu")
		(net "PVCCIO_CPU0")
	)
	(segment
		(start 327.914 -61.087)
		(end 327.914 -61.849)
		(width 0.254)
		(layer "B.Cu")
		(net "PVCCIO_CPU0")
	)
	(segment
		(start 359.537 -89.7128)
		(end 357.694484 -89.7128)
		(width 0.254)
		(layer "B.Cu")
		(net "PVCCIO_CPU0")
	)
	(segment
		(start 460.388208 -132.639054)
		(end 460.972408 -132.054854)
		(width 0.4064)
		(layer "B.Cu")
		(net "PVCCIO_CPU0")
	)
	(segment
		(start 180.7464 -78.421992)
		(end 181.282848 -78.95844)
		(width 0.254)
		(layer "B.Cu")
		(net "PVCCIO_CPU0")
	)
	(segment
		(start 174.568358 -91.772994)
		(end 176.911 -91.772994)
		(width 0.254)
		(layer "B.Cu")
		(net "PVCCIO_CPU0")
	)
	(segment
		(start 162.813746 -70.358)
		(end 162.179 -70.358)
		(width 0.254)
		(layer "B.Cu")
		(net "PVCCIO_CPU0")
	)
	(segment
		(start 374.325642 -39.874952)
		(end 374.992646 -39.874952)
		(width 0.254)
		(layer "B.Cu")
		(net "PVCCIO_CPU0")
	)
	(segment
		(start 176.911 -91.772994)
		(end 177.607976 -91.076018)
		(width 0.381)
		(layer "B.Cu")
		(net "PVCCIO_CPU0")
	)
	(segment
		(start 353.176586 -92.105988)
		(end 354.258372 -92.105988)
		(width 0.254)
		(layer "B.Cu")
		(net "PVCCIO_CPU0")
	)
	(segment
		(start 174.693834 -68.35902)
		(end 176.586642 -68.35902)
		(width 0.254)
		(layer "B.Cu")
		(net "PVCCIO_CPU0")
	)
	(segment
		(start 328.422 -123.317)
		(end 328.2315 -123.5075)
		(width 0.254)
		(layer "B.Cu")
		(net "PVCCIO_CPU0")
	)
	(segment
		(start 191.193166 -59.671966)
		(end 191.193166 -62.30493)
		(width 0.4064)
		(layer "B.Cu")
		(net "PVCCIO_CPU0")
	)
	(segment
		(start 330.08316 -65.316354)
		(end 330.095606 -65.303908)
		(width 0.254)
		(layer "B.Cu")
		(net "PVCCIO_CPU0")
	)
	(segment
		(start 400.353784 -3.887216)
		(end 403.228302 -6.761734)
		(width 0.254)
		(layer "B.Cu")
		(net "PVCCIO_CPU0")
	)
	(segment
		(start 443.567312 -14.988794)
		(end 443.5602 -14.988794)
		(width 0.254)
		(layer "B.Cu")
		(net "PVCCIO_CPU0")
	)
	(segment
		(start 325.5264 -122.81916)
		(end 325.7804 -123.07316)
		(width 0.254)
		(layer "B.Cu")
		(net "PVCCIO_CPU0")
	)
	(segment
		(start 390.78408 -3.025394)
		(end 390.779 -3.025394)
		(width 0.254)
		(layer "B.Cu")
		(net "PVCCIO_CPU0")
	)
	(segment
		(start 166.417498 -71.199248)
		(end 167.278304 -70.338442)
		(width 0.254)
		(layer "B.Cu")
		(net "PVCCIO_CPU0")
	)
	(segment
		(start 443.5602 -14.988794)
		(end 443.5602 -14.9606)
		(width 0.254)
		(layer "B.Cu")
		(net "PVCCIO_CPU0")
	)
	(segment
		(start 210.712304 -51.142138)
		(end 208.439766 -48.8696)
		(width 0.4064)
		(layer "B.Cu")
		(net "PVCCIO_CPU0")
	)
	(segment
		(start 128.8796 -65.999106)
		(end 129.211578 -65.667128)
		(width 0.254)
		(layer "B.Cu")
		(net "PVCCIO_CPU0")
	)
	(segment
		(start 181.0004 -77.1144)
		(end 181.0004 -77.724)
		(width 0.254)
		(layer "B.Cu")
		(net "PVCCIO_CPU0")
	)
	(segment
		(start 460.388208 -132.842254)
		(end 460.388208 -132.639054)
		(width 0.4064)
		(layer "B.Cu")
		(net "PVCCIO_CPU0")
	)
	(segment
		(start 294.49014 -65.96888)
		(end 294.851582 -66.330322)
		(width 0.254)
		(layer "B.Cu")
		(net "PVCCIO_CPU0")
	)
	(segment
		(start 330.095606 -64.179958)
		(end 330.091288 -64.17564)
		(width 0.254)
		(layer "B.Cu")
		(net "PVCCIO_CPU0")
	)
	(segment
		(start 329.09764 -64.17564)
		(end 330.091288 -64.17564)
		(width 0.254)
		(layer "B.Cu")
		(net "PVCCIO_CPU0")
	)
	(segment
		(start 193.404236 -54.294278)
		(end 192.056004 -55.64251)
		(width 0.4064)
		(layer "B.Cu")
		(net "PVCCIO_CPU0")
	)
	(segment
		(start 363.87024 -139.00404)
		(end 363.87024 -138.41857)
		(width 0.4064)
		(layer "B.Cu")
		(net "PVCCIO_CPU0")
	)
	(segment
		(start 163.531042 -71.075296)
		(end 162.813746 -70.358)
		(width 0.254)
		(layer "B.Cu")
		(net "PVCCIO_CPU0")
	)
	(segment
		(start 330.08316 -67.82181)
		(end 330.08316 -67.26936)
		(width 0.254)
		(layer "B.Cu")
		(net "PVCCIO_CPU0")
	)
	(segment
		(start 325.7804 -123.07316)
		(end 325.7804 -123.2027)
		(width 0.254)
		(layer "B.Cu")
		(net "PVCCIO_CPU0")
	)
	(segment
		(start 294.996616 -65.462404)
		(end 294.49014 -65.96888)
		(width 0.254)
		(layer "B.Cu")
		(net "PVCCIO_CPU0")
	)
	(segment
		(start 433.07 -44.577)
		(end 433.9971 -45.5041)
		(width 0.254)
		(layer "B.Cu")
		(net "PVCCIO_CPU0")
	)
	(segment
		(start 354.597208 -91.767152)
		(end 354.597208 -90.86088)
		(width 0.254)
		(layer "B.Cu")
		(net "PVCCIO_CPU0")
	)
	(segment
		(start 356.546404 -90.86088)
		(end 354.597208 -90.86088)
		(width 0.254)
		(layer "B.Cu")
		(net "PVCCIO_CPU0")
	)
	(segment
		(start 340.3092 -86.4362)
		(end 340.3092 -87.1982)
		(width 0.254)
		(layer "B.Cu")
		(net "PVCCIO_CPU0")
	)
	(segment
		(start 169.393362 -67.8815)
		(end 174.216314 -67.8815)
		(width 0.254)
		(layer "B.Cu")
		(net "PVCCIO_CPU0")
	)
	(segment
		(start 329.032616 -126.810516)
		(end 326.3519 -124.1298)
		(width 0.4064)
		(layer "B.Cu")
		(net "PVCCIO_CPU0")
	)
	(segment
		(start 293.938452 -65.417192)
		(end 293.881302 -65.417192)
		(width 0.254)
		(layer "B.Cu")
		(net "PVCCIO_CPU0")
	)
	(segment
		(start 174.216314 -67.8815)
		(end 174.693834 -68.35902)
		(width 0.254)
		(layer "B.Cu")
		(net "PVCCIO_CPU0")
	)
	(segment
		(start 378.209048 -86.233)
		(end 377.9774 -86.464648)
		(width 0.254)
		(layer "B.Cu")
		(net "PVCCIO_CPU0")
	)
	(segment
		(start 189.881256 -63.61684)
		(end 187.451746 -63.61684)
		(width 0.4064)
		(layer "B.Cu")
		(net "PVCCIO_CPU0")
	)
	(segment
		(start 294.851582 -66.330322)
		(end 295.153588 -66.330322)
		(width 0.254)
		(layer "B.Cu")
		(net "PVCCIO_CPU0")
	)
	(segment
		(start 461.17637 -147.650454)
		(end 461.277208 -147.650454)
		(width 0.4064)
		(layer "B.Cu")
		(net "PVCCIO_CPU0")
	)
	(segment
		(start 167.278304 -70.338442)
		(end 167.278304 -69.996558)
		(width 0.254)
		(layer "B.Cu")
		(net "PVCCIO_CPU0")
	)
	(segment
		(start 465.595208 -146.177254)
		(end 466.295486 -146.177254)
		(width 0.4064)
		(layer "B.Cu")
		(net "PVCCIO_CPU0")
	)
	(segment
		(start 443.5602 -14.9606)
		(end 443.2808 -14.6812)
		(width 0.254)
		(layer "B.Cu")
		(net "PVCCIO_CPU0")
	)
	(segment
		(start 177.607976 -91.076018)
		(end 182.261764 -91.076018)
		(width 0.381)
		(layer "B.Cu")
		(net "PVCCIO_CPU0")
	)
	(segment
		(start 202.3872 -48.8696)
		(end 200.377044 -50.879756)
		(width 0.4064)
		(layer "B.Cu")
		(net "PVCCIO_CPU0")
	)
	(segment
		(start 333.66456 -107.007914)
		(end 333.423514 -107.24896)
		(width 0.4064)
		(layer "B.Cu")
		(net "PVCCIO_CPU0")
	)
	(segment
		(start 375.413524 -54.698392)
		(end 374.777 -55.334916)
		(width 0.254)
		(layer "B.Cu")
		(net "PVCCIO_CPU0")
	)
	(segment
		(start 328.83983 -112.290606)
		(end 328.83983 -122.89917)
		(width 0.4064)
		(layer "B.Cu")
		(net "PVCCIO_CPU0")
	)
	(segment
		(start 331.718158 -107.24896)
		(end 330.28001 -108.687108)
		(width 0.4064)
		(layer "B.Cu")
		(net "PVCCIO_CPU0")
	)
	(segment
		(start 180.7464 -77.978)
		(end 180.7464 -78.421992)
		(width 0.254)
		(layer "B.Cu")
		(net "PVCCIO_CPU0")
	)
	(segment
		(start 323.8627 -31.67888)
		(end 324.3834 -31.15818)
		(width 0.4064)
		(layer "B.Cu")
		(net "PVCCIO_CPU0")
	)
	(segment
		(start 328.2315 -123.5075)
		(end 327.34504 -123.5075)
		(width 0.254)
		(layer "B.Cu")
		(net "PVCCIO_CPU0")
	)
	(segment
		(start 181.64302 -20.211796)
		(end 181.64302 -20.23364)
		(width 0.254)
		(layer "B.Cu")
		(net "PVCCIO_CPU0")
	)
	(segment
		(start 340.1187 -87.1982)
		(end 340.3092 -87.1982)
		(width 0.254)
		(layer "B.Cu")
		(net "PVCCIO_CPU0")
	)
	(segment
		(start 433.84089 -43.70578)
		(end 433.84089 -42.925746)
		(width 0.254)
		(layer "B.Cu")
		(net "PVCCIO_CPU0")
	)
	(segment
		(start 323.8627 -31.967678)
		(end 323.8627 -31.67888)
		(width 0.4064)
		(layer "B.Cu")
		(net "PVCCIO_CPU0")
	)
	(segment
		(start 164.641276 -71.982076)
		(end 164.6428 -71.9836)
		(width 0.254)
		(layer "B.Cu")
		(net "PVCCIO_CPU0")
	)
	(segment
		(start 220.737684 -51.142138)
		(end 210.712304 -51.142138)
		(width 0.4064)
		(layer "B.Cu")
		(net "PVCCIO_CPU0")
	)
	(segment
		(start 433.24272 -43.70578)
		(end 433.07 -43.8785)
		(width 0.254)
		(layer "B.Cu")
		(net "PVCCIO_CPU0")
	)
	(segment
		(start 375.571004 -53.26253)
		(end 375.571004 -53.749956)
		(width 0.254)
		(layer "B.Cu")
		(net "PVCCIO_CPU0")
	)
	(segment
		(start 326.3519 -123.7742)
		(end 326.3519 -124.1298)
		(width 0.254)
		(layer "B.Cu")
		(net "PVCCIO_CPU0")
	)
	(segment
		(start 278.576024 -69.404484)
		(end 278.576024 -69.809614)
		(width 0.4064)
		(layer "B.Cu")
		(net "PVCCIO_CPU0")
	)
	(segment
		(start 192.056004 -55.64251)
		(end 192.056004 -57.321196)
		(width 0.4064)
		(layer "B.Cu")
		(net "PVCCIO_CPU0")
	)
	(segment
		(start 374.992646 -39.874952)
		(end 375.097294 -39.9796)
		(width 0.254)
		(layer "B.Cu")
		(net "PVCCIO_CPU0")
	)
	(segment
		(start 200.377044 -50.879756)
		(end 195.136516 -50.879756)
		(width 0.4064)
		(layer "B.Cu")
		(net "PVCCIO_CPU0")
	)
	(segment
		(start 443.2808 -14.6812)
		(end 442.722 -14.6812)
		(width 0.254)
		(layer "B.Cu")
		(net "PVCCIO_CPU0")
	)
	(segment
		(start 390.779 -3.025394)
		(end 390.779 -3.302)
		(width 0.254)
		(layer "B.Cu")
		(net "PVCCIO_CPU0")
	)
	(segment
		(start 365.55807 -140.00353)
		(end 364.86973 -140.00353)
		(width 0.4064)
		(layer "B.Cu")
		(net "PVCCIO_CPU0")
	)
	(segment
		(start 191.1858 -59.6646)
		(end 191.193166 -59.671966)
		(width 0.4064)
		(layer "B.Cu")
		(net "PVCCIO_CPU0")
	)
	(segment
		(start 163.531042 -71.982076)
		(end 163.531042 -71.075296)
		(width 0.254)
		(layer "B.Cu")
		(net "PVCCIO_CPU0")
	)
	(segment
		(start 181.0004 -77.724)
		(end 180.7464 -77.978)
		(width 0.254)
		(layer "B.Cu")
		(net "PVCCIO_CPU0")
	)
	(segment
		(start 326.6567 -122.81916)
		(end 325.5264 -122.81916)
		(width 0.254)
		(layer "B.Cu")
		(net "PVCCIO_CPU0")
	)
	(segment
		(start 182.261764 -91.076018)
		(end 183.0324 -90.305382)
		(width 0.254)
		(layer "B.Cu")
		(net "PVCCIO_CPU0")
	)
	(segment
		(start 375.567194 -53.26253)
		(end 375.571004 -53.26253)
		(width 0.254)
		(layer "B.Cu")
		(net "PVCCIO_CPU0")
	)
	(segment
		(start 377.9774 -86.464648)
		(end 377.915932 -86.464648)
		(width 0.254)
		(layer "B.Cu")
		(net "PVCCIO_CPU0")
	)
	(segment
		(start 363.87024 -137.52957)
		(end 363.87024 -138.41857)
		(width 0.4064)
		(layer "B.Cu")
		(net "PVCCIO_CPU0")
	)
	(segment
		(start 294.49014 -65.96888)
		(end 293.938452 -65.417192)
		(width 0.254)
		(layer "B.Cu")
		(net "PVCCIO_CPU0")
	)
	(segment
		(start 173.845982 -91.050618)
		(end 174.568358 -91.772994)
		(width 0.254)
		(layer "B.Cu")
		(net "PVCCIO_CPU0")
	)
	(segment
		(start 364.86973 -140.00353)
		(end 363.87024 -139.00404)
		(width 0.4064)
		(layer "B.Cu")
		(net "PVCCIO_CPU0")
	)
	(segment
		(start 277.368 -68.58)
		(end 277.75154 -68.58)
		(width 0.4064)
		(layer "B.Cu")
		(net "PVCCIO_CPU0")
	)
	(segment
		(start 191.193166 -62.30493)
		(end 189.881256 -63.61684)
		(width 0.4064)
		(layer "B.Cu")
		(net "PVCCIO_CPU0")
	)
	(segment
		(start 327.914 -62.992)
		(end 329.09764 -64.17564)
		(width 0.254)
		(layer "B.Cu")
		(net "PVCCIO_CPU0")
	)
	(segment
		(start 352.645726 -92.636848)
		(end 353.176586 -92.105988)
		(width 0.254)
		(layer "B.Cu")
		(net "PVCCIO_CPU0")
	)
	(segment
		(start 338.0232 -56.8833)
		(end 337.3501 -57.5564)
		(width 0.254)
		(layer "B.Cu")
		(net "PVCCIO_CPU0")
	)
	(segment
		(start 324.3834 -31.15818)
		(end 323.718936 -30.493716)
		(width 0.4064)
		(layer "B.Cu")
		(net "PVCCIO_CPU0")
	)
	(segment
		(start 330.11745 -60.05957)
		(end 329.206606 -60.05957)
		(width 0.254)
		(layer "B.Cu")
		(net "PVCCIO_CPU0")
	)
	(segment
		(start 181.64302 -20.23364)
		(end 181.52618 -20.23364)
		(width 0.254)
		(layer "B.Cu")
		(net "PVCCIO_CPU0")
	)
	(segment
		(start 377.3932 -46.2026)
		(end 377.063 -46.5328)
		(width 0.254)
		(layer "B.Cu")
		(net "PVCCIO_CPU0")
	)
	(segment
		(start 332.280514 -61.341)
		(end 332.603348 -61.018166)
		(width 0.254)
		(layer "B.Cu")
		(net "PVCCIO_CPU0")
	)
	(segment
		(start 191.1858 -58.1914)
		(end 191.1858 -59.6646)
		(width 0.4064)
		(layer "B.Cu")
		(net "PVCCIO_CPU0")
	)
	(segment
		(start 328.83983 -122.89917)
		(end 328.422 -123.317)
		(width 0.4064)
		(layer "B.Cu")
		(net "PVCCIO_CPU0")
	)
	(segment
		(start 466.295486 -146.177254)
		(end 466.71865 -145.75409)
		(width 0.4064)
		(layer "B.Cu")
		(net "PVCCIO_CPU0")
	)
	(segment
		(start 321.1957 -31.7373)
		(end 321.1957 -31.92018)
		(width 0.4064)
		(layer "B.Cu")
		(net "PVCCIO_CPU0")
	)
	(segment
		(start 460.617824 -148.209)
		(end 460.74584 -148.209)
		(width 0.254)
		(layer "In2.Cu")
		(net "PVCCIO_CPU0")
	)
	(segment
		(start 493.66932 -140.869416)
		(end 494.663984 -140.869416)
		(width 0.254)
		(layer "In2.Cu")
		(net "PVCCIO_CPU0")
	)
	(segment
		(start 486.684574 -24.268176)
		(end 486.684574 -25.357836)
		(width 0.254)
		(layer "In2.Cu")
		(net "PVCCIO_CPU0")
	)
	(segment
		(start 469.785954 -29.629608)
		(end 468.052658 -27.896312)
		(width 0.254)
		(layer "In2.Cu")
		(net "PVCCIO_CPU0")
	)
	(segment
		(start 492.633 -141.905736)
		(end 493.66932 -140.869416)
		(width 0.254)
		(layer "In2.Cu")
		(net "PVCCIO_CPU0")
	)
	(segment
		(start 487.200702 -23.768304)
		(end 487.184446 -23.768304)
		(width 0.254)
		(layer "In2.Cu")
		(net "PVCCIO_CPU0")
	)
	(segment
		(start 487.184446 -23.768304)
		(end 486.684574 -24.268176)
		(width 0.254)
		(layer "In2.Cu")
		(net "PVCCIO_CPU0")
	)
	(segment
		(start 438.189878 -111.684054)
		(end 437.789574 -111.684054)
		(width 0.254)
		(layer "In2.Cu")
		(net "PVCCIO_CPU0")
	)
	(segment
		(start 183.060594 -97.826576)
		(end 183.51246 -97.37471)
		(width 0.4064)
		(layer "In2.Cu")
		(net "PVCCIO_CPU0")
	)
	(segment
		(start 459.806294 -147.39747)
		(end 460.617824 -148.209)
		(width 0.254)
		(layer "In2.Cu")
		(net "PVCCIO_CPU0")
	)
	(segment
		(start 488.237784 -112.853724)
		(end 484.15448 -112.853724)
		(width 0.254)
		(layer "In2.Cu")
		(net "PVCCIO_CPU0")
	)
	(segment
		(start 471.02522 -145.39722)
		(end 471.27668 -145.14576)
		(width 0.254)
		(layer "In2.Cu")
		(net "PVCCIO_CPU0")
	)
	(segment
		(start 491.718346 -149.01418)
		(end 492.633 -148.099526)
		(width 0.254)
		(layer "In2.Cu")
		(net "PVCCIO_CPU0")
	)
	(segment
		(start 371.8941 -59.8297)
		(end 373.05488 -59.8297)
		(width 0.254)
		(layer "In2.Cu")
		(net "PVCCIO_CPU0")
	)
	(segment
		(start 183.35752 -81.774792)
		(end 182.40629 -80.823562)
		(width 0.4064)
		(layer "In2.Cu")
		(net "PVCCIO_CPU0")
	)
	(segment
		(start 375.1834 -1.102614)
		(end 375.205752 -1.124966)
		(width 0.254)
		(layer "In2.Cu")
		(net "PVCCIO_CPU0")
	)
	(segment
		(start 202.438 -102.7938)
		(end 202.40752 -102.76332)
		(width 0.4064)
		(layer "In2.Cu")
		(net "PVCCIO_CPU0")
	)
	(segment
		(start 188.816488 -104.10571)
		(end 184.857136 -104.10571)
		(width 0.4064)
		(layer "In2.Cu")
		(net "PVCCIO_CPU0")
	)
	(segment
		(start 202.40752 -102.76332)
		(end 196.685408 -102.76332)
		(width 0.4064)
		(layer "In2.Cu")
		(net "PVCCIO_CPU0")
	)
	(segment
		(start 473.148406 -145.14576)
		(end 473.645738 -145.643092)
		(width 0.254)
		(layer "In2.Cu")
		(net "PVCCIO_CPU0")
	)
	(segment
		(start 368.878866 -6.647434)
		(end 358.924606 -6.647434)
		(width 0.254)
		(layer "In2.Cu")
		(net "PVCCIO_CPU0")
	)
	(segment
		(start 483.67696 -149.58314)
		(end 483.67696 -150.66391)
		(width 0.254)
		(layer "In2.Cu")
		(net "PVCCIO_CPU0")
	)
	(segment
		(start 358.924606 -6.647434)
		(end 352.0186 -13.55344)
		(width 0.254)
		(layer "In2.Cu")
		(net "PVCCIO_CPU0")
	)
	(segment
		(start 484.623364 -27.419046)
		(end 484.145082 -27.419046)
		(width 0.254)
		(layer "In2.Cu")
		(net "PVCCIO_CPU0")
	)
	(segment
		(start 479.736912 -145.643092)
		(end 483.67696 -149.58314)
		(width 0.254)
		(layer "In2.Cu")
		(net "PVCCIO_CPU0")
	)
	(segment
		(start 184.857136 -104.10571)
		(end 183.060594 -102.309168)
		(width 0.4064)
		(layer "In2.Cu")
		(net "PVCCIO_CPU0")
	)
	(segment
		(start 339.471 -100.62972)
		(end 338.63026 -101.47046)
		(width 0.508)
		(layer "In2.Cu")
		(net "PVCCIO_CPU0")
	)
	(segment
		(start 375.9708 -46.929294)
		(end 375.434606 -46.3931)
		(width 0.254)
		(layer "In2.Cu")
		(net "PVCCIO_CPU0")
	)
	(segment
		(start 375.567194 -54.581806)
		(end 375.567194 -53.26253)
		(width 0.254)
		(layer "In2.Cu")
		(net "PVCCIO_CPU0")
	)
	(segment
		(start 457.93533 -147.39747)
		(end 459.806294 -147.39747)
		(width 0.254)
		(layer "In2.Cu")
		(net "PVCCIO_CPU0")
	)
	(segment
		(start 480.499166 -23.77313)
		(end 476.32366 -23.77313)
		(width 0.254)
		(layer "In2.Cu")
		(net "PVCCIO_CPU0")
	)
	(segment
		(start 498.05336 -134.07136)
		(end 494.76914 -130.78714)
		(width 0.254)
		(layer "In2.Cu")
		(net "PVCCIO_CPU0")
	)
	(segment
		(start 490.245146 -150.48738)
		(end 490.245146 -149.342094)
		(width 0.254)
		(layer "In2.Cu")
		(net "PVCCIO_CPU0")
	)
	(segment
		(start 498.05336 -137.48004)
		(end 498.05336 -134.07136)
		(width 0.254)
		(layer "In2.Cu")
		(net "PVCCIO_CPU0")
	)
	(segment
		(start 336.423508 -138.607292)
		(end 330.982828 -138.607292)
		(width 0.4064)
		(layer "In2.Cu")
		(net "PVCCIO_CPU0")
	)
	(segment
		(start 493.5474 -120.94718)
		(end 488.94746 -116.34724)
		(width 0.254)
		(layer "In2.Cu")
		(net "PVCCIO_CPU0")
	)
	(segment
		(start 345.9988 -20.3708)
		(end 345.344496 -19.716496)
		(width 0.254)
		(layer "In2.Cu")
		(net "PVCCIO_CPU0")
	)
	(segment
		(start 472.744292 -29.23032)
		(end 472.345004 -29.629608)
		(width 0.254)
		(layer "In2.Cu")
		(net "PVCCIO_CPU0")
	)
	(segment
		(start 473.645738 -145.643092)
		(end 479.736912 -145.643092)
		(width 0.254)
		(layer "In2.Cu")
		(net "PVCCIO_CPU0")
	)
	(segment
		(start 484.15448 -112.853724)
		(end 482.99243 -111.691674)
		(width 0.254)
		(layer "In2.Cu")
		(net "PVCCIO_CPU0")
	)
	(segment
		(start 182.40629 -80.01635)
		(end 181.34838 -78.95844)
		(width 0.4064)
		(layer "In2.Cu")
		(net "PVCCIO_CPU0")
	)
	(segment
		(start 371.207538 -4.318762)
		(end 368.878866 -6.647434)
		(width 0.254)
		(layer "In2.Cu")
		(net "PVCCIO_CPU0")
	)
	(segment
		(start 438.197498 -111.691674)
		(end 438.189878 -111.684054)
		(width 0.254)
		(layer "In2.Cu")
		(net "PVCCIO_CPU0")
	)
	(segment
		(start 482.99243 -111.691674)
		(end 438.197498 -111.691674)
		(width 0.254)
		(layer "In2.Cu")
		(net "PVCCIO_CPU0")
	)
	(segment
		(start 347.2434 -101.4984)
		(end 346.37472 -100.62972)
		(width 0.508)
		(layer "In2.Cu")
		(net "PVCCIO_CPU0")
	)
	(segment
		(start 490.245146 -149.342094)
		(end 490.57306 -149.01418)
		(width 0.254)
		(layer "In2.Cu")
		(net "PVCCIO_CPU0")
	)
	(segment
		(start 183.51246 -81.930748)
		(end 183.35752 -81.775808)
		(width 0.4064)
		(layer "In2.Cu")
		(net "PVCCIO_CPU0")
	)
	(segment
		(start 338.63026 -101.47046)
		(end 338.26958 -101.47046)
		(width 0.508)
		(layer "In2.Cu")
		(net "PVCCIO_CPU0")
	)
	(segment
		(start 375.205752 -2.163318)
		(end 373.050308 -4.318762)
		(width 0.254)
		(layer "In2.Cu")
		(net "PVCCIO_CPU0")
	)
	(segment
		(start 330.982828 -138.607292)
		(end 330.36764 -137.992104)
		(width 0.4064)
		(layer "In2.Cu")
		(net "PVCCIO_CPU0")
	)
	(segment
		(start 350.064578 -100.220272)
		(end 350.064578 -100.760022)
		(width 0.508)
		(layer "In2.Cu")
		(net "PVCCIO_CPU0")
	)
	(segment
		(start 483.67696 -150.66391)
		(end 485.179878 -152.166828)
		(width 0.254)
		(layer "In2.Cu")
		(net "PVCCIO_CPU0")
	)
	(segment
		(start 183.35752 -81.775808)
		(end 183.35752 -81.774792)
		(width 0.4064)
		(layer "In2.Cu")
		(net "PVCCIO_CPU0")
	)
	(segment
		(start 461.45704 -147.4978)
		(end 464.97494 -147.4978)
		(width 0.254)
		(layer "In2.Cu")
		(net "PVCCIO_CPU0")
	)
	(segment
		(start 492.633 -148.099526)
		(end 492.633 -141.905736)
		(width 0.254)
		(layer "In2.Cu")
		(net "PVCCIO_CPU0")
	)
	(segment
		(start 494.76914 -130.78714)
		(end 494.76914 -128.37668)
		(width 0.254)
		(layer "In2.Cu")
		(net "PVCCIO_CPU0")
	)
	(segment
		(start 346.37472 -100.62972)
		(end 339.471 -100.62972)
		(width 0.508)
		(layer "In2.Cu")
		(net "PVCCIO_CPU0")
	)
	(segment
		(start 326.231758 -133.4516)
		(end 324.757542 -131.977384)
		(width 0.4064)
		(layer "In2.Cu")
		(net "PVCCIO_CPU0")
	)
	(segment
		(start 488.94746 -113.5634)
		(end 488.237784 -112.853724)
		(width 0.254)
		(layer "In2.Cu")
		(net "PVCCIO_CPU0")
	)
	(segment
		(start 375.9708 -51.35118)
		(end 375.9708 -46.929294)
		(width 0.254)
		(layer "In2.Cu")
		(net "PVCCIO_CPU0")
	)
	(segment
		(start 467.07552 -145.39722)
		(end 471.02522 -145.39722)
		(width 0.254)
		(layer "In2.Cu")
		(net "PVCCIO_CPU0")
	)
	(segment
		(start 352.0186 -13.55344)
		(end 352.0186 -17.6784)
		(width 0.254)
		(layer "In2.Cu")
		(net "PVCCIO_CPU0")
	)
	(segment
		(start 345.344496 -19.716496)
		(end 339.858096 -19.716496)
		(width 0.254)
		(layer "In2.Cu")
		(net "PVCCIO_CPU0")
	)
	(segment
		(start 349.3262 -101.4984)
		(end 347.2434 -101.4984)
		(width 0.508)
		(layer "In2.Cu")
		(net "PVCCIO_CPU0")
	)
	(segment
		(start 494.663984 -140.869416)
		(end 498.05336 -137.48004)
		(width 0.254)
		(layer "In2.Cu")
		(net "PVCCIO_CPU0")
	)
	(segment
		(start 461.002888 -27.896312)
		(end 459.7654 -29.1338)
		(width 0.254)
		(layer "In2.Cu")
		(net "PVCCIO_CPU0")
	)
	(segment
		(start 484.145082 -27.419046)
		(end 480.499166 -23.77313)
		(width 0.254)
		(layer "In2.Cu")
		(net "PVCCIO_CPU0")
	)
	(segment
		(start 493.5474 -127.15494)
		(end 493.5474 -120.94718)
		(width 0.254)
		(layer "In2.Cu")
		(net "PVCCIO_CPU0")
	)
	(segment
		(start 373.050308 -4.318762)
		(end 371.207538 -4.318762)
		(width 0.254)
		(layer "In2.Cu")
		(net "PVCCIO_CPU0")
	)
	(segment
		(start 350.064578 -100.760022)
		(end 349.3262 -101.4984)
		(width 0.508)
		(layer "In2.Cu")
		(net "PVCCIO_CPU0")
	)
	(segment
		(start 460.74584 -148.209)
		(end 461.45704 -147.4978)
		(width 0.254)
		(layer "In2.Cu")
		(net "PVCCIO_CPU0")
	)
	(segment
		(start 375.567194 -53.26253)
		(end 375.1834 -52.878736)
		(width 0.254)
		(layer "In2.Cu")
		(net "PVCCIO_CPU0")
	)
	(segment
		(start 196.685408 -102.76332)
		(end 196.395848 -103.05288)
		(width 0.4064)
		(layer "In2.Cu")
		(net "PVCCIO_CPU0")
	)
	(segment
		(start 437.781954 -111.691674)
		(end 425.48048 -111.691674)
		(width 0.254)
		(layer "In2.Cu")
		(net "PVCCIO_CPU0")
	)
	(segment
		(start 466.71865 -145.75409)
		(end 467.07552 -145.39722)
		(width 0.254)
		(layer "In2.Cu")
		(net "PVCCIO_CPU0")
	)
	(segment
		(start 182.40629 -80.823562)
		(end 182.40629 -80.01635)
		(width 0.4064)
		(layer "In2.Cu")
		(net "PVCCIO_CPU0")
	)
	(segment
		(start 375.205752 -1.124966)
		(end 375.205752 -2.163318)
		(width 0.254)
		(layer "In2.Cu")
		(net "PVCCIO_CPU0")
	)
	(segment
		(start 374.39854 -58.48604)
		(end 374.39854 -55.75046)
		(width 0.254)
		(layer "In2.Cu")
		(net "PVCCIO_CPU0")
	)
	(segment
		(start 486.684574 -25.357836)
		(end 484.623364 -27.419046)
		(width 0.254)
		(layer "In2.Cu")
		(net "PVCCIO_CPU0")
	)
	(segment
		(start 373.05488 -59.8297)
		(end 374.39854 -58.48604)
		(width 0.254)
		(layer "In2.Cu")
		(net "PVCCIO_CPU0")
	)
	(segment
		(start 468.052658 -27.896312)
		(end 461.002888 -27.896312)
		(width 0.254)
		(layer "In2.Cu")
		(net "PVCCIO_CPU0")
	)
	(segment
		(start 183.060594 -102.309168)
		(end 183.060594 -97.826576)
		(width 0.4064)
		(layer "In2.Cu")
		(net "PVCCIO_CPU0")
	)
	(segment
		(start 485.179878 -152.166828)
		(end 488.565698 -152.166828)
		(width 0.254)
		(layer "In2.Cu")
		(net "PVCCIO_CPU0")
	)
	(segment
		(start 490.57306 -149.01418)
		(end 491.718346 -149.01418)
		(width 0.254)
		(layer "In2.Cu")
		(net "PVCCIO_CPU0")
	)
	(segment
		(start 471.27668 -145.14576)
		(end 473.148406 -145.14576)
		(width 0.254)
		(layer "In2.Cu")
		(net "PVCCIO_CPU0")
	)
	(segment
		(start 349.3262 -20.3708)
		(end 345.9988 -20.3708)
		(width 0.254)
		(layer "In2.Cu")
		(net "PVCCIO_CPU0")
	)
	(segment
		(start 330.36764 -133.804152)
		(end 330.015088 -133.4516)
		(width 0.4064)
		(layer "In2.Cu")
		(net "PVCCIO_CPU0")
	)
	(segment
		(start 472.345004 -29.629608)
		(end 469.785954 -29.629608)
		(width 0.254)
		(layer "In2.Cu")
		(net "PVCCIO_CPU0")
	)
	(segment
		(start 476.32366 -23.77313)
		(end 472.744292 -27.352498)
		(width 0.254)
		(layer "In2.Cu")
		(net "PVCCIO_CPU0")
	)
	(segment
		(start 375.1834 -0.6096)
		(end 375.1834 -1.102614)
		(width 0.254)
		(layer "In2.Cu")
		(net "PVCCIO_CPU0")
	)
	(segment
		(start 472.744292 -27.352498)
		(end 472.744292 -29.23032)
		(width 0.254)
		(layer "In2.Cu")
		(net "PVCCIO_CPU0")
	)
	(segment
		(start 183.51246 -97.37471)
		(end 183.51246 -81.930748)
		(width 0.4064)
		(layer "In2.Cu")
		(net "PVCCIO_CPU0")
	)
	(segment
		(start 375.1834 -52.878736)
		(end 375.1834 -52.13858)
		(width 0.254)
		(layer "In2.Cu")
		(net "PVCCIO_CPU0")
	)
	(segment
		(start 437.789574 -111.684054)
		(end 437.781954 -111.691674)
		(width 0.254)
		(layer "In2.Cu")
		(net "PVCCIO_CPU0")
	)
	(segment
		(start 456.310746 -149.022054)
		(end 457.93533 -147.39747)
		(width 0.254)
		(layer "In2.Cu")
		(net "PVCCIO_CPU0")
	)
	(segment
		(start 330.015088 -133.4516)
		(end 326.231758 -133.4516)
		(width 0.4064)
		(layer "In2.Cu")
		(net "PVCCIO_CPU0")
	)
	(segment
		(start 488.94746 -116.34724)
		(end 488.94746 -113.5634)
		(width 0.254)
		(layer "In2.Cu")
		(net "PVCCIO_CPU0")
	)
	(segment
		(start 488.565698 -152.166828)
		(end 490.245146 -150.48738)
		(width 0.254)
		(layer "In2.Cu")
		(net "PVCCIO_CPU0")
	)
	(segment
		(start 339.858096 -19.716496)
		(end 339.5599 -19.4183)
		(width 0.254)
		(layer "In2.Cu")
		(net "PVCCIO_CPU0")
	)
	(segment
		(start 196.395848 -103.05288)
		(end 189.869318 -103.05288)
		(width 0.4064)
		(layer "In2.Cu")
		(net "PVCCIO_CPU0")
	)
	(segment
		(start 352.0186 -17.6784)
		(end 349.3262 -20.3708)
		(width 0.254)
		(layer "In2.Cu")
		(net "PVCCIO_CPU0")
	)
	(segment
		(start 374.39854 -55.75046)
		(end 375.567194 -54.581806)
		(width 0.254)
		(layer "In2.Cu")
		(net "PVCCIO_CPU0")
	)
	(segment
		(start 336.475578 -138.555222)
		(end 336.423508 -138.607292)
		(width 0.4064)
		(layer "In2.Cu")
		(net "PVCCIO_CPU0")
	)
	(segment
		(start 375.1834 -52.13858)
		(end 375.9708 -51.35118)
		(width 0.254)
		(layer "In2.Cu")
		(net "PVCCIO_CPU0")
	)
	(segment
		(start 455.536808 -149.022054)
		(end 456.310746 -149.022054)
		(width 0.254)
		(layer "In2.Cu")
		(net "PVCCIO_CPU0")
	)
	(segment
		(start 464.97494 -147.4978)
		(end 466.71865 -145.75409)
		(width 0.254)
		(layer "In2.Cu")
		(net "PVCCIO_CPU0")
	)
	(segment
		(start 330.36764 -137.992104)
		(end 330.36764 -133.804152)
		(width 0.4064)
		(layer "In2.Cu")
		(net "PVCCIO_CPU0")
	)
	(segment
		(start 189.869318 -103.05288)
		(end 188.816488 -104.10571)
		(width 0.4064)
		(layer "In2.Cu")
		(net "PVCCIO_CPU0")
	)
	(segment
		(start 494.76914 -128.37668)
		(end 493.5474 -127.15494)
		(width 0.254)
		(layer "In2.Cu")
		(net "PVCCIO_CPU0")
	)
	(segment
		(start 454.862184 -15.070836)
		(end 456.817222 -15.070836)
		(width 0.254)
		(layer "In4.Cu")
		(net "PVCCIO_CPU0")
	)
	(segment
		(start 331.089 -32.1564)
		(end 332.0542 -31.1912)
		(width 0.254)
		(layer "In4.Cu")
		(net "PVCCIO_CPU0")
	)
	(segment
		(start 459.537054 -132.054854)
		(end 460.972408 -132.054854)
		(width 0.254)
		(layer "In4.Cu")
		(net "PVCCIO_CPU0")
	)
	(segment
		(start 373.755158 -27.025854)
		(end 373.755412 -27.025854)
		(width 0.254)
		(layer "In4.Cu")
		(net "PVCCIO_CPU0")
	)
	(segment
		(start 317.355982 -39.907718)
		(end 314.009278 -39.907718)
		(width 0.254)
		(layer "In4.Cu")
		(net "PVCCIO_CPU0")
	)
	(segment
		(start 462.534 -14.570456)
		(end 462.534 -13.970254)
		(width 0.254)
		(layer "In4.Cu")
		(net "PVCCIO_CPU0")
	)
	(segment
		(start 328.170032 -30.274768)
		(end 329.080368 -30.274768)
		(width 0.254)
		(layer "In4.Cu")
		(net "PVCCIO_CPU0")
	)
	(segment
		(start 404.0378 -17.956784)
		(end 404.0378 -16.632682)
		(width 0.254)
		(layer "In4.Cu")
		(net "PVCCIO_CPU0")
	)
	(segment
		(start 308.0639 -51.0159)
		(end 306.963826 -52.115974)
		(width 0.254)
		(layer "In4.Cu")
		(net "PVCCIO_CPU0")
	)
	(segment
		(start 423.255186 -137.210546)
		(end 423.888662 -136.57707)
		(width 0.254)
		(layer "In4.Cu")
		(net "PVCCIO_CPU0")
	)
	(segment
		(start 368.138964 -34.712402)
		(end 368.480086 -34.484818)
		(width 0.254)
		(layer "In4.Cu")
		(net "PVCCIO_CPU0")
	)
	(segment
		(start 322.340732 -35.215322)
		(end 320.867278 -35.215322)
		(width 0.254)
		(layer "In4.Cu")
		(net "PVCCIO_CPU0")
	)
	(segment
		(start 408.815286 -140.182346)
		(end 408.86507 -140.182346)
		(width 0.254)
		(layer "In4.Cu")
		(net "PVCCIO_CPU0")
	)
	(segment
		(start 367.889028 -34.962084)
		(end 368.138964 -34.712402)
		(width 0.254)
		(layer "In4.Cu")
		(net "PVCCIO_CPU0")
	)
	(segment
		(start 371.8941 -59.8297)
		(end 367.284 -59.8297)
		(width 0.254)
		(layer "In4.Cu")
		(net "PVCCIO_CPU0")
	)
	(segment
		(start 403.484588 -18.509996)
		(end 404.0378 -17.956784)
		(width 0.254)
		(layer "In4.Cu")
		(net "PVCCIO_CPU0")
	)
	(segment
		(start 419.81755 -139.402566)
		(end 422.00957 -137.210546)
		(width 0.254)
		(layer "In4.Cu")
		(net "PVCCIO_CPU0")
	)
	(segment
		(start 376.178064 -22.110446)
		(end 380.61011 -17.6784)
		(width 0.254)
		(layer "In4.Cu")
		(net "PVCCIO_CPU0")
	)
	(segment
		(start 374.992646 -39.874952)
		(end 374.367806 -39.874952)
		(width 0.254)
		(layer "In4.Cu")
		(net "PVCCIO_CPU0")
	)
	(segment
		(start 402.27885 -18.509996)
		(end 403.484588 -18.509996)
		(width 0.254)
		(layer "In4.Cu")
		(net "PVCCIO_CPU0")
	)
	(segment
		(start 332.0542 -27.813)
		(end 332.8162 -27.051)
		(width 0.254)
		(layer "In4.Cu")
		(net "PVCCIO_CPU0")
	)
	(segment
		(start 454.006712 -15.518638)
		(end 454.414382 -15.518638)
		(width 0.254)
		(layer "In4.Cu")
		(net "PVCCIO_CPU0")
	)
	(segment
		(start 338.0994 -23.6982)
		(end 338.0994 -22.789642)
		(width 0.254)
		(layer "In4.Cu")
		(net "PVCCIO_CPU0")
	)
	(segment
		(start 426.1866 -10.762996)
		(end 449.25107 -10.762996)
		(width 0.254)
		(layer "In4.Cu")
		(net "PVCCIO_CPU0")
	)
	(segment
		(start 426.042328 -136.57707)
		(end 427.438058 -137.9728)
		(width 0.254)
		(layer "In4.Cu")
		(net "PVCCIO_CPU0")
	)
	(segment
		(start 375.412 -0.381)
		(end 379.716792 -0.381)
		(width 0.254)
		(layer "In4.Cu")
		(net "PVCCIO_CPU0")
	)
	(segment
		(start 382.96342 -1.824228)
		(end 384.257042 -3.11785)
		(width 0.254)
		(layer "In4.Cu")
		(net "PVCCIO_CPU0")
	)
	(segment
		(start 463.949796 -12.554458)
		(end 469.444832 -12.554458)
		(width 0.254)
		(layer "In4.Cu")
		(net "PVCCIO_CPU0")
	)
	(segment
		(start 373.965724 -26.910284)
		(end 373.965978 -26.910284)
		(width 0.254)
		(layer "In4.Cu")
		(net "PVCCIO_CPU0")
	)
	(segment
		(start 458.05344 -16.307054)
		(end 460.797402 -16.307054)
		(width 0.254)
		(layer "In4.Cu")
		(net "PVCCIO_CPU0")
	)
	(segment
		(start 373.424958 -27.207718)
		(end 373.755158 -27.025854)
		(width 0.254)
		(layer "In4.Cu")
		(net "PVCCIO_CPU0")
	)
	(segment
		(start 336.46237 -24.2062)
		(end 337.5914 -24.2062)
		(width 0.254)
		(layer "In4.Cu")
		(net "PVCCIO_CPU0")
	)
	(segment
		(start 374.189752 -26.787094)
		(end 374.726454 -26.491946)
		(width 0.254)
		(layer "In4.Cu")
		(net "PVCCIO_CPU0")
	)
	(segment
		(start 370.47678 -139.17422)
		(end 384.24993 -139.17422)
		(width 0.254)
		(layer "In4.Cu")
		(net "PVCCIO_CPU0")
	)
	(segment
		(start 367.889028 -38.52545)
		(end 367.889028 -34.962084)
		(width 0.254)
		(layer "In4.Cu")
		(net "PVCCIO_CPU0")
	)
	(segment
		(start 374.726454 -26.491946)
		(end 376.178064 -25.040336)
		(width 0.254)
		(layer "In4.Cu")
		(net "PVCCIO_CPU0")
	)
	(segment
		(start 368.480086 -34.484818)
		(end 368.546634 -34.440368)
		(width 0.254)
		(layer "In4.Cu")
		(net "PVCCIO_CPU0")
	)
	(segment
		(start 380.61011 -17.6784)
		(end 391.75182 -17.6784)
		(width 0.254)
		(layer "In4.Cu")
		(net "PVCCIO_CPU0")
	)
	(segment
		(start 398.774158 -140.698982)
		(end 402.178266 -140.698982)
		(width 0.254)
		(layer "In4.Cu")
		(net "PVCCIO_CPU0")
	)
	(segment
		(start 419.738556 -11.010392)
		(end 420.170356 -10.578592)
		(width 0.254)
		(layer "In4.Cu")
		(net "PVCCIO_CPU0")
	)
	(segment
		(start 381.16002 -1.824228)
		(end 382.96342 -1.824228)
		(width 0.254)
		(layer "In4.Cu")
		(net "PVCCIO_CPU0")
	)
	(segment
		(start 401.0914 -17.526)
		(end 401.294854 -17.526)
		(width 0.254)
		(layer "In4.Cu")
		(net "PVCCIO_CPU0")
	)
	(segment
		(start 410.747718 -139.402566)
		(end 419.81755 -139.402566)
		(width 0.254)
		(layer "In4.Cu")
		(net "PVCCIO_CPU0")
	)
	(segment
		(start 372.980458 -29.353002)
		(end 373.001286 -29.252672)
		(width 0.254)
		(layer "In4.Cu")
		(net "PVCCIO_CPU0")
	)
	(segment
		(start 329.2602 -30.4546)
		(end 329.2602 -31.0134)
		(width 0.254)
		(layer "In4.Cu")
		(net "PVCCIO_CPU0")
	)
	(segment
		(start 375.542556 -87.1982)
		(end 377.18238 -87.1982)
		(width 0.254)
		(layer "In4.Cu")
		(net "PVCCIO_CPU0")
	)
	(segment
		(start 388.868412 -3.11785)
		(end 388.960868 -3.025394)
		(width 0.254)
		(layer "In4.Cu")
		(net "PVCCIO_CPU0")
	)
	(segment
		(start 327.28662 -31.15818)
		(end 328.170032 -30.274768)
		(width 0.254)
		(layer "In4.Cu")
		(net "PVCCIO_CPU0")
	)
	(segment
		(start 384.615944 -138.808206)
		(end 392.800332 -138.808206)
		(width 0.254)
		(layer "In4.Cu")
		(net "PVCCIO_CPU0")
	)
	(segment
		(start 332.8162 -27.051)
		(end 333.61757 -27.051)
		(width 0.254)
		(layer "In4.Cu")
		(net "PVCCIO_CPU0")
	)
	(segment
		(start 319.532 -36.5506)
		(end 319.532 -37.7317)
		(width 0.254)
		(layer "In4.Cu")
		(net "PVCCIO_CPU0")
	)
	(segment
		(start 329.080368 -30.274768)
		(end 329.2602 -30.4546)
		(width 0.254)
		(layer "In4.Cu")
		(net "PVCCIO_CPU0")
	)
	(segment
		(start 392.800332 -138.808206)
		(end 393.760452 -139.768326)
		(width 0.254)
		(layer "In4.Cu")
		(net "PVCCIO_CPU0")
	)
	(segment
		(start 384.24993 -139.17422)
		(end 384.615944 -138.808206)
		(width 0.254)
		(layer "In4.Cu")
		(net "PVCCIO_CPU0")
	)
	(segment
		(start 441.9854 -134.3406)
		(end 443.5094 -134.3406)
		(width 0.254)
		(layer "In4.Cu")
		(net "PVCCIO_CPU0")
	)
	(segment
		(start 427.438058 -137.9728)
		(end 438.3532 -137.9728)
		(width 0.254)
		(layer "In4.Cu")
		(net "PVCCIO_CPU0")
	)
	(segment
		(start 366.337596 -139.611862)
		(end 370.039138 -139.611862)
		(width 0.254)
		(layer "In4.Cu")
		(net "PVCCIO_CPU0")
	)
	(segment
		(start 338.0994 -22.789642)
		(end 340.0298 -20.859242)
		(width 0.254)
		(layer "In4.Cu")
		(net "PVCCIO_CPU0")
	)
	(segment
		(start 420.170356 -10.578592)
		(end 426.002196 -10.578592)
		(width 0.254)
		(layer "In4.Cu")
		(net "PVCCIO_CPU0")
	)
	(segment
		(start 314.009278 -39.907718)
		(end 308.0639 -45.853096)
		(width 0.254)
		(layer "In4.Cu")
		(net "PVCCIO_CPU0")
	)
	(segment
		(start 375.1834 -0.6096)
		(end 375.412 -0.381)
		(width 0.254)
		(layer "In4.Cu")
		(net "PVCCIO_CPU0")
	)
	(segment
		(start 308.0639 -45.853096)
		(end 308.0639 -51.0159)
		(width 0.254)
		(layer "In4.Cu")
		(net "PVCCIO_CPU0")
	)
	(segment
		(start 306.963826 -52.115974)
		(end 306.963826 -55.409338)
		(width 0.254)
		(layer "In4.Cu")
		(net "PVCCIO_CPU0")
	)
	(segment
		(start 319.532 -37.7317)
		(end 317.355982 -39.907718)
		(width 0.254)
		(layer "In4.Cu")
		(net "PVCCIO_CPU0")
	)
	(segment
		(start 320.867278 -35.215322)
		(end 319.532 -36.5506)
		(width 0.254)
		(layer "In4.Cu")
		(net "PVCCIO_CPU0")
	)
	(segment
		(start 397.843502 -139.768326)
		(end 398.774158 -140.698982)
		(width 0.254)
		(layer "In4.Cu")
		(net "PVCCIO_CPU0")
	)
	(segment
		(start 438.3532 -137.9728)
		(end 441.9854 -134.3406)
		(width 0.254)
		(layer "In4.Cu")
		(net "PVCCIO_CPU0")
	)
	(segment
		(start 456.817222 -15.070836)
		(end 458.05344 -16.307054)
		(width 0.254)
		(layer "In4.Cu")
		(net "PVCCIO_CPU0")
	)
	(segment
		(start 409.66009 -11.010392)
		(end 419.738556 -11.010392)
		(width 0.254)
		(layer "In4.Cu")
		(net "PVCCIO_CPU0")
	)
	(segment
		(start 456.692 -129.2098)
		(end 459.537054 -132.054854)
		(width 0.254)
		(layer "In4.Cu")
		(net "PVCCIO_CPU0")
	)
	(segment
		(start 329.2602 -31.0134)
		(end 330.4032 -32.1564)
		(width 0.254)
		(layer "In4.Cu")
		(net "PVCCIO_CPU0")
	)
	(segment
		(start 373.079518 -28.875736)
		(end 373.424958 -27.207718)
		(width 0.254)
		(layer "In4.Cu")
		(net "PVCCIO_CPU0")
	)
	(segment
		(start 374.367806 -39.874952)
		(end 373.488458 -38.995604)
		(width 0.254)
		(layer "In4.Cu")
		(net "PVCCIO_CPU0")
	)
	(segment
		(start 377.18238 -87.1982)
		(end 377.915932 -86.464648)
		(width 0.254)
		(layer "In4.Cu")
		(net "PVCCIO_CPU0")
	)
	(segment
		(start 372.980458 -31.090108)
		(end 372.980458 -29.353002)
		(width 0.254)
		(layer "In4.Cu")
		(net "PVCCIO_CPU0")
	)
	(segment
		(start 368.359182 -38.995604)
		(end 367.889028 -38.52545)
		(width 0.254)
		(layer "In4.Cu")
		(net "PVCCIO_CPU0")
	)
	(segment
		(start 393.026646 -16.403574)
		(end 398.440656 -16.403574)
		(width 0.254)
		(layer "In4.Cu")
		(net "PVCCIO_CPU0")
	)
	(segment
		(start 379.716792 -0.381)
		(end 381.16002 -1.824228)
		(width 0.254)
		(layer "In4.Cu")
		(net "PVCCIO_CPU0")
	)
	(segment
		(start 454.414382 -15.518638)
		(end 454.862184 -15.070836)
		(width 0.254)
		(layer "In4.Cu")
		(net "PVCCIO_CPU0")
	)
	(segment
		(start 324.3834 -31.15818)
		(end 324.3834 -33.172654)
		(width 0.254)
		(layer "In4.Cu")
		(net "PVCCIO_CPU0")
	)
	(segment
		(start 404.0378 -16.632682)
		(end 409.66009 -11.010392)
		(width 0.254)
		(layer "In4.Cu")
		(net "PVCCIO_CPU0")
	)
	(segment
		(start 340.0298 -19.8882)
		(end 339.5599 -19.4183)
		(width 0.254)
		(layer "In4.Cu")
		(net "PVCCIO_CPU0")
	)
	(segment
		(start 449.25107 -10.762996)
		(end 454.006712 -15.518638)
		(width 0.254)
		(layer "In4.Cu")
		(net "PVCCIO_CPU0")
	)
	(segment
		(start 340.0298 -20.859242)
		(end 340.0298 -19.8882)
		(width 0.254)
		(layer "In4.Cu")
		(net "PVCCIO_CPU0")
	)
	(segment
		(start 367.284 -59.8297)
		(end 365.0996 -62.0141)
		(width 0.254)
		(layer "In4.Cu")
		(net "PVCCIO_CPU0")
	)
	(segment
		(start 333.61757 -27.051)
		(end 336.46237 -24.2062)
		(width 0.254)
		(layer "In4.Cu")
		(net "PVCCIO_CPU0")
	)
	(segment
		(start 367.15954 -88.983058)
		(end 367.54689 -88.595708)
		(width 0.254)
		(layer "In4.Cu")
		(net "PVCCIO_CPU0")
	)
	(segment
		(start 367.54689 -88.595708)
		(end 374.145048 -88.595708)
		(width 0.254)
		(layer "In4.Cu")
		(net "PVCCIO_CPU0")
	)
	(segment
		(start 373.755412 -27.025854)
		(end 373.965724 -26.910284)
		(width 0.254)
		(layer "In4.Cu")
		(net "PVCCIO_CPU0")
	)
	(segment
		(start 460.797402 -16.307054)
		(end 462.534 -14.570456)
		(width 0.254)
		(layer "In4.Cu")
		(net "PVCCIO_CPU0")
	)
	(segment
		(start 402.178266 -140.698982)
		(end 402.767546 -141.288262)
		(width 0.254)
		(layer "In4.Cu")
		(net "PVCCIO_CPU0")
	)
	(segment
		(start 401.294854 -17.526)
		(end 402.27885 -18.509996)
		(width 0.254)
		(layer "In4.Cu")
		(net "PVCCIO_CPU0")
	)
	(segment
		(start 374.145048 -88.595708)
		(end 375.542556 -87.1982)
		(width 0.254)
		(layer "In4.Cu")
		(net "PVCCIO_CPU0")
	)
	(segment
		(start 373.001286 -29.252672)
		(end 373.079518 -28.875736)
		(width 0.254)
		(layer "In4.Cu")
		(net "PVCCIO_CPU0")
	)
	(segment
		(start 324.3834 -33.172654)
		(end 322.340732 -35.215322)
		(width 0.254)
		(layer "In4.Cu")
		(net "PVCCIO_CPU0")
	)
	(segment
		(start 443.5094 -134.3406)
		(end 448.6402 -129.2098)
		(width 0.254)
		(layer "In4.Cu")
		(net "PVCCIO_CPU0")
	)
	(segment
		(start 388.960868 -3.025394)
		(end 390.78408 -3.025394)
		(width 0.254)
		(layer "In4.Cu")
		(net "PVCCIO_CPU0")
	)
	(segment
		(start 384.257042 -3.11785)
		(end 388.868412 -3.11785)
		(width 0.254)
		(layer "In4.Cu")
		(net "PVCCIO_CPU0")
	)
	(segment
		(start 402.767546 -141.288262)
		(end 406.144984 -141.288262)
		(width 0.254)
		(layer "In4.Cu")
		(net "PVCCIO_CPU0")
	)
	(segment
		(start 337.5914 -24.2062)
		(end 338.0994 -23.6982)
		(width 0.254)
		(layer "In4.Cu")
		(net "PVCCIO_CPU0")
	)
	(segment
		(start 370.039138 -139.611862)
		(end 370.47678 -139.17422)
		(width 0.254)
		(layer "In4.Cu")
		(net "PVCCIO_CPU0")
	)
	(segment
		(start 391.75182 -17.6784)
		(end 393.026646 -16.403574)
		(width 0.254)
		(layer "In4.Cu")
		(net "PVCCIO_CPU0")
	)
	(segment
		(start 373.965978 -26.910284)
		(end 374.189752 -26.787094)
		(width 0.254)
		(layer "In4.Cu")
		(net "PVCCIO_CPU0")
	)
	(segment
		(start 324.3834 -31.15818)
		(end 327.28662 -31.15818)
		(width 0.254)
		(layer "In4.Cu")
		(net "PVCCIO_CPU0")
	)
	(segment
		(start 399.563082 -17.526)
		(end 401.0914 -17.526)
		(width 0.254)
		(layer "In4.Cu")
		(net "PVCCIO_CPU0")
	)
	(segment
		(start 462.534 -13.970254)
		(end 463.949796 -12.554458)
		(width 0.254)
		(layer "In4.Cu")
		(net "PVCCIO_CPU0")
	)
	(segment
		(start 369.630198 -34.440368)
		(end 372.980458 -31.090108)
		(width 0.254)
		(layer "In4.Cu")
		(net "PVCCIO_CPU0")
	)
	(segment
		(start 406.144984 -141.288262)
		(end 408.815286 -140.182346)
		(width 0.254)
		(layer "In4.Cu")
		(net "PVCCIO_CPU0")
	)
	(segment
		(start 426.002196 -10.578592)
		(end 426.1866 -10.762996)
		(width 0.254)
		(layer "In4.Cu")
		(net "PVCCIO_CPU0")
	)
	(segment
		(start 376.178064 -25.040336)
		(end 376.178064 -22.110446)
		(width 0.254)
		(layer "In4.Cu")
		(net "PVCCIO_CPU0")
	)
	(segment
		(start 330.4032 -32.1564)
		(end 331.089 -32.1564)
		(width 0.254)
		(layer "In4.Cu")
		(net "PVCCIO_CPU0")
	)
	(segment
		(start 448.6402 -129.2098)
		(end 456.692 -129.2098)
		(width 0.254)
		(layer "In4.Cu")
		(net "PVCCIO_CPU0")
	)
	(segment
		(start 366.078008 -139.352274)
		(end 366.337596 -139.611862)
		(width 0.254)
		(layer "In4.Cu")
		(net "PVCCIO_CPU0")
	)
	(segment
		(start 375.097294 -39.9796)
		(end 374.992646 -39.874952)
		(width 0.254)
		(layer "In4.Cu")
		(net "PVCCIO_CPU0")
	)
	(segment
		(start 422.00957 -137.210546)
		(end 423.255186 -137.210546)
		(width 0.254)
		(layer "In4.Cu")
		(net "PVCCIO_CPU0")
	)
	(segment
		(start 332.0542 -31.1912)
		(end 332.0542 -27.813)
		(width 0.254)
		(layer "In4.Cu")
		(net "PVCCIO_CPU0")
	)
	(segment
		(start 368.546634 -34.440368)
		(end 369.630198 -34.440368)
		(width 0.254)
		(layer "In4.Cu")
		(net "PVCCIO_CPU0")
	)
	(segment
		(start 423.888662 -136.57707)
		(end 426.042328 -136.57707)
		(width 0.254)
		(layer "In4.Cu")
		(net "PVCCIO_CPU0")
	)
	(segment
		(start 393.760452 -139.768326)
		(end 397.843502 -139.768326)
		(width 0.254)
		(layer "In4.Cu")
		(net "PVCCIO_CPU0")
	)
	(segment
		(start 398.440656 -16.403574)
		(end 399.563082 -17.526)
		(width 0.254)
		(layer "In4.Cu")
		(net "PVCCIO_CPU0")
	)
	(segment
		(start 373.488458 -38.995604)
		(end 368.359182 -38.995604)
		(width 0.254)
		(layer "In4.Cu")
		(net "PVCCIO_CPU0")
	)
	(segment
		(start 408.86507 -140.182346)
		(end 410.747718 -139.402566)
		(width 0.254)
		(layer "In4.Cu")
		(net "PVCCIO_CPU0")
	)
	(segment
		(start 457.955904 -35.238182)
		(end 459.945232 -33.248854)
		(width 0.254)
		(layer "In9.Cu")
		(net "PVCCIO_CPU0")
	)
	(segment
		(start 482.0666 -17.907)
		(end 482.657404 -18.497804)
		(width 0.254)
		(layer "In9.Cu")
		(net "PVCCIO_CPU0")
	)
	(segment
		(start 436.6895 -45.5041)
		(end 436.118 -44.9326)
		(width 0.254)
		(layer "In9.Cu")
		(net "PVCCIO_CPU0")
	)
	(segment
		(start 460.972408 -132.054854)
		(end 461.842104 -132.054854)
		(width 0.254)
		(layer "In9.Cu")
		(net "PVCCIO_CPU0")
	)
	(segment
		(start 484.968804 -18.497804)
		(end 486.71226 -20.24126)
		(width 0.254)
		(layer "In9.Cu")
		(net "PVCCIO_CPU0")
	)
	(segment
		(start 461.842104 -132.054854)
		(end 463.281522 -133.494272)
		(width 0.254)
		(layer "In9.Cu")
		(net "PVCCIO_CPU0")
	)
	(segment
		(start 456.525884 -152.693116)
		(end 456.525884 -151.71166)
		(width 0.254)
		(layer "In9.Cu")
		(net "PVCCIO_CPU0")
	)
	(segment
		(start 460.7306 -148.209)
		(end 460.617824 -148.209)
		(width 0.254)
		(layer "In9.Cu")
		(net "PVCCIO_CPU0")
	)
	(segment
		(start 333.7052 -65.557146)
		(end 331.21092 -68.051426)
		(width 0.254)
		(layer "In9.Cu")
		(net "PVCCIO_CPU0")
	)
	(segment
		(start 478.253044 -13.128244)
		(end 478.253044 -16.277844)
		(width 0.254)
		(layer "In9.Cu")
		(net "PVCCIO_CPU0")
	)
	(segment
		(start 352.845624 -140.589508)
		(end 355.934772 -140.589508)
		(width 0.4064)
		(layer "In9.Cu")
		(net "PVCCIO_CPU0")
	)
	(segment
		(start 453.935592 -42.164)
		(end 455.291952 -40.80764)
		(width 0.254)
		(layer "In9.Cu")
		(net "PVCCIO_CPU0")
	)
	(segment
		(start 452.09714 -43.330114)
		(end 453.263254 -42.164)
		(width 0.254)
		(layer "In9.Cu")
		(net "PVCCIO_CPU0")
	)
	(segment
		(start 350.844612 -139.945364)
		(end 352.20148 -139.945364)
		(width 0.4064)
		(layer "In9.Cu")
		(net "PVCCIO_CPU0")
	)
	(segment
		(start 455.386948 -40.80764)
		(end 456.211432 -39.983156)
		(width 0.254)
		(layer "In9.Cu")
		(net "PVCCIO_CPU0")
	)
	(segment
		(start 355.934772 -140.589508)
		(end 358.176322 -138.347958)
		(width 0.4064)
		(layer "In9.Cu")
		(net "PVCCIO_CPU0")
	)
	(segment
		(start 486.71226 -20.24126)
		(end 486.71226 -23.279862)
		(width 0.254)
		(layer "In9.Cu")
		(net "PVCCIO_CPU0")
	)
	(segment
		(start 350.632014 -139.732766)
		(end 350.844612 -139.945364)
		(width 0.4064)
		(layer "In9.Cu")
		(net "PVCCIO_CPU0")
	)
	(segment
		(start 436.118 -44.4754)
		(end 437.263286 -43.330114)
		(width 0.254)
		(layer "In9.Cu")
		(net "PVCCIO_CPU0")
	)
	(segment
		(start 344.973656 -140.523722)
		(end 347.905832 -140.523722)
		(width 0.4064)
		(layer "In9.Cu")
		(net "PVCCIO_CPU0")
	)
	(segment
		(start 455.536808 -150.722584)
		(end 455.536808 -149.022054)
		(width 0.254)
		(layer "In9.Cu")
		(net "PVCCIO_CPU0")
	)
	(segment
		(start 365.905542 -139.52474)
		(end 366.078008 -139.352274)
		(width 0.4064)
		(layer "In9.Cu")
		(net "PVCCIO_CPU0")
	)
	(segment
		(start 479.8822 -17.907)
		(end 482.0666 -17.907)
		(width 0.254)
		(layer "In9.Cu")
		(net "PVCCIO_CPU0")
	)
	(segment
		(start 352.20148 -139.945364)
		(end 352.845624 -140.589508)
		(width 0.4064)
		(layer "In9.Cu")
		(net "PVCCIO_CPU0")
	)
	(segment
		(start 472.720416 -12.554458)
		(end 473.057474 -12.2174)
		(width 0.254)
		(layer "In9.Cu")
		(net "PVCCIO_CPU0")
	)
	(segment
		(start 459.945232 -32.017462)
		(end 459.668372 -31.740602)
		(width 0.254)
		(layer "In9.Cu")
		(net "PVCCIO_CPU0")
	)
	(segment
		(start 459.945232 -33.248854)
		(end 459.945232 -32.017462)
		(width 0.254)
		(layer "In9.Cu")
		(net "PVCCIO_CPU0")
	)
	(segment
		(start 455.168 -154.051)
		(end 456.525884 -152.693116)
		(width 0.254)
		(layer "In9.Cu")
		(net "PVCCIO_CPU0")
	)
	(segment
		(start 337.069176 -138.03757)
		(end 337.532472 -138.03757)
		(width 0.4064)
		(layer "In9.Cu")
		(net "PVCCIO_CPU0")
	)
	(segment
		(start 455.041 -154.051)
		(end 455.168 -154.051)
		(width 0.254)
		(layer "In9.Cu")
		(net "PVCCIO_CPU0")
	)
	(segment
		(start 336.475578 -138.555222)
		(end 336.551524 -138.555222)
		(width 0.4064)
		(layer "In9.Cu")
		(net "PVCCIO_CPU0")
	)
	(segment
		(start 365.33074 -139.52474)
		(end 365.905542 -139.52474)
		(width 0.4064)
		(layer "In9.Cu")
		(net "PVCCIO_CPU0")
	)
	(segment
		(start 463.281522 -133.494272)
		(end 463.281522 -145.658078)
		(width 0.254)
		(layer "In9.Cu")
		(net "PVCCIO_CPU0")
	)
	(segment
		(start 360.786172 -138.347958)
		(end 361.00893 -138.1252)
		(width 0.4064)
		(layer "In9.Cu")
		(net "PVCCIO_CPU0")
	)
	(segment
		(start 363.9312 -138.1252)
		(end 365.33074 -139.52474)
		(width 0.4064)
		(layer "In9.Cu")
		(net "PVCCIO_CPU0")
	)
	(segment
		(start 331.21092 -68.051426)
		(end 330.312776 -68.051426)
		(width 0.254)
		(layer "In9.Cu")
		(net "PVCCIO_CPU0")
	)
	(segment
		(start 459.668372 -29.230828)
		(end 459.7654 -29.1338)
		(width 0.254)
		(layer "In9.Cu")
		(net "PVCCIO_CPU0")
	)
	(segment
		(start 457.058014 -35.238182)
		(end 457.955904 -35.238182)
		(width 0.254)
		(layer "In9.Cu")
		(net "PVCCIO_CPU0")
	)
	(segment
		(start 456.211432 -39.983156)
		(end 456.211432 -36.084764)
		(width 0.254)
		(layer "In9.Cu")
		(net "PVCCIO_CPU0")
	)
	(segment
		(start 361.00893 -138.1252)
		(end 363.9312 -138.1252)
		(width 0.4064)
		(layer "In9.Cu")
		(net "PVCCIO_CPU0")
	)
	(segment
		(start 336.551524 -138.555222)
		(end 337.069176 -138.03757)
		(width 0.4064)
		(layer "In9.Cu")
		(net "PVCCIO_CPU0")
	)
	(segment
		(start 456.211432 -36.084764)
		(end 457.058014 -35.238182)
		(width 0.254)
		(layer "In9.Cu")
		(net "PVCCIO_CPU0")
	)
	(segment
		(start 469.444832 -12.554458)
		(end 472.720416 -12.554458)
		(width 0.254)
		(layer "In9.Cu")
		(net "PVCCIO_CPU0")
	)
	(segment
		(start 332.603348 -61.018166)
		(end 333.7052 -62.120018)
		(width 0.254)
		(layer "In9.Cu")
		(net "PVCCIO_CPU0")
	)
	(segment
		(start 337.752436 -138.257534)
		(end 342.707468 -138.257534)
		(width 0.4064)
		(layer "In9.Cu")
		(net "PVCCIO_CPU0")
	)
	(segment
		(start 486.71226 -23.279862)
		(end 487.200702 -23.768304)
		(width 0.254)
		(layer "In9.Cu")
		(net "PVCCIO_CPU0")
	)
	(segment
		(start 358.176322 -138.347958)
		(end 360.786172 -138.347958)
		(width 0.4064)
		(layer "In9.Cu")
		(net "PVCCIO_CPU0")
	)
	(segment
		(start 478.253044 -16.277844)
		(end 479.8822 -17.907)
		(width 0.254)
		(layer "In9.Cu")
		(net "PVCCIO_CPU0")
	)
	(segment
		(start 463.281522 -145.658078)
		(end 460.7306 -148.209)
		(width 0.254)
		(layer "In9.Cu")
		(net "PVCCIO_CPU0")
	)
	(segment
		(start 453.263254 -42.164)
		(end 453.935592 -42.164)
		(width 0.254)
		(layer "In9.Cu")
		(net "PVCCIO_CPU0")
	)
	(segment
		(start 333.7052 -62.120018)
		(end 333.7052 -65.557146)
		(width 0.254)
		(layer "In9.Cu")
		(net "PVCCIO_CPU0")
	)
	(segment
		(start 473.057474 -12.2174)
		(end 477.3422 -12.2174)
		(width 0.254)
		(layer "In9.Cu")
		(net "PVCCIO_CPU0")
	)
	(segment
		(start 436.118 -44.9326)
		(end 436.118 -44.4754)
		(width 0.254)
		(layer "In9.Cu")
		(net "PVCCIO_CPU0")
	)
	(segment
		(start 337.532472 -138.03757)
		(end 337.752436 -138.257534)
		(width 0.4064)
		(layer "In9.Cu")
		(net "PVCCIO_CPU0")
	)
	(segment
		(start 348.696788 -139.732766)
		(end 350.632014 -139.732766)
		(width 0.4064)
		(layer "In9.Cu")
		(net "PVCCIO_CPU0")
	)
	(segment
		(start 456.525884 -151.71166)
		(end 455.536808 -150.722584)
		(width 0.254)
		(layer "In9.Cu")
		(net "PVCCIO_CPU0")
	)
	(segment
		(start 455.291952 -40.80764)
		(end 455.386948 -40.80764)
		(width 0.254)
		(layer "In9.Cu")
		(net "PVCCIO_CPU0")
	)
	(segment
		(start 477.3422 -12.2174)
		(end 478.253044 -13.128244)
		(width 0.254)
		(layer "In9.Cu")
		(net "PVCCIO_CPU0")
	)
	(segment
		(start 482.657404 -18.497804)
		(end 484.968804 -18.497804)
		(width 0.254)
		(layer "In9.Cu")
		(net "PVCCIO_CPU0")
	)
	(segment
		(start 347.905832 -140.523722)
		(end 348.696788 -139.732766)
		(width 0.4064)
		(layer "In9.Cu")
		(net "PVCCIO_CPU0")
	)
	(segment
		(start 459.668372 -31.740602)
		(end 459.668372 -29.230828)
		(width 0.254)
		(layer "In9.Cu")
		(net "PVCCIO_CPU0")
	)
	(segment
		(start 437.263286 -43.330114)
		(end 452.09714 -43.330114)
		(width 0.254)
		(layer "In9.Cu")
		(net "PVCCIO_CPU0")
	)
	(segment
		(start 342.707468 -138.257534)
		(end 344.973656 -140.523722)
		(width 0.4064)
		(layer "In9.Cu")
		(net "PVCCIO_CPU0")
	)
	(segment
		(start 137.874248 -67.300094)
		(end 138.078972 -67.504818)
		(width 0.254)
		(layer "In11.Cu")
		(net "PVCCIO_CPU0")
	)
	(segment
		(start 158.511748 -65.033144)
		(end 153.831798 -69.713094)
		(width 0.254)
		(layer "In11.Cu")
		(net "PVCCIO_CPU0")
	)
	(segment
		(start 183.536336 -21.972016)
		(end 183.536336 -29.743908)
		(width 0.254)
		(layer "In11.Cu")
		(net "PVCCIO_CPU0")
	)
	(segment
		(start 158.511748 -62.268354)
		(end 158.511748 -65.033144)
		(width 0.254)
		(layer "In11.Cu")
		(net "PVCCIO_CPU0")
	)
	(segment
		(start 181.34838 -78.95844)
		(end 180.78704 -78.95844)
		(width 0.4064)
		(layer "In11.Cu")
		(net "PVCCIO_CPU0")
	)
	(segment
		(start 182.973472 -62.085728)
		(end 181.87543 -62.085728)
		(width 0.4064)
		(layer "In11.Cu")
		(net "PVCCIO_CPU0")
	)
	(segment
		(start 141.311122 -69.282564)
		(end 141.507972 -69.479414)
		(width 0.254)
		(layer "In11.Cu")
		(net "PVCCIO_CPU0")
	)
	(segment
		(start 129.503932 -65.667128)
		(end 129.718054 -65.453006)
		(width 0.254)
		(layer "In11.Cu")
		(net "PVCCIO_CPU0")
	)
	(segment
		(start 170.889422 -42.390822)
		(end 167.667178 -42.390822)
		(width 0.254)
		(layer "In11.Cu")
		(net "PVCCIO_CPU0")
	)
	(segment
		(start 180.78704 -78.95844)
		(end 179.379626 -77.551026)
		(width 0.4064)
		(layer "In11.Cu")
		(net "PVCCIO_CPU0")
	)
	(segment
		(start 401.0914 -17.526)
		(end 401.0914 -16.7132)
		(width 0.254)
		(layer "In11.Cu")
		(net "PVCCIO_CPU0")
	)
	(segment
		(start 170.965114 -91.177618)
		(end 171.092114 -91.050618)
		(width 0.254)
		(layer "In11.Cu")
		(net "PVCCIO_CPU0")
	)
	(segment
		(start 179.379626 -77.551026)
		(end 179.110386 -77.551026)
		(width 0.4064)
		(layer "In11.Cu")
		(net "PVCCIO_CPU0")
	)
	(segment
		(start 138.724132 -67.78117)
		(end 138.926824 -67.983862)
		(width 0.254)
		(layer "In11.Cu")
		(net "PVCCIO_CPU0")
	)
	(segment
		(start 171.092114 -91.050618)
		(end 171.245276 -91.050618)
		(width 0.254)
		(layer "In11.Cu")
		(net "PVCCIO_CPU0")
	)
	(segment
		(start 403.061424 -14.743176)
		(end 409.919424 -14.743176)
		(width 0.254)
		(layer "In11.Cu")
		(net "PVCCIO_CPU0")
	)
	(segment
		(start 141.507972 -69.479414)
		(end 141.507972 -69.507862)
		(width 0.254)
		(layer "In11.Cu")
		(net "PVCCIO_CPU0")
	)
	(segment
		(start 331.79258 -61.018166)
		(end 331.070966 -61.73978)
		(width 0.254)
		(layer "In11.Cu")
		(net "PVCCIO_CPU0")
	)
	(segment
		(start 375.434606 -45.902118)
		(end 375.434606 -46.3931)
		(width 0.254)
		(layer "In11.Cu")
		(net "PVCCIO_CPU0")
	)
	(segment
		(start 181.64302 -20.211796)
		(end 181.64302 -20.23364)
		(width 0.254)
		(layer "In11.Cu")
		(net "PVCCIO_CPU0")
	)
	(segment
		(start 134.859014 -65.809876)
		(end 135.2804 -65.809876)
		(width 0.254)
		(layer "In11.Cu")
		(net "PVCCIO_CPU0")
	)
	(segment
		(start 138.331448 -67.78117)
		(end 138.724132 -67.78117)
		(width 0.254)
		(layer "In11.Cu")
		(net "PVCCIO_CPU0")
	)
	(segment
		(start 183.536336 -29.743908)
		(end 170.889422 -42.390822)
		(width 0.254)
		(layer "In11.Cu")
		(net "PVCCIO_CPU0")
	)
	(segment
		(start 137.247884 -67.07886)
		(end 137.469118 -67.300094)
		(width 0.254)
		(layer "In11.Cu")
		(net "PVCCIO_CPU0")
	)
	(segment
		(start 146.587972 -69.713094)
		(end 146.076416 -70.22465)
		(width 0.254)
		(layer "In11.Cu")
		(net "PVCCIO_CPU0")
	)
	(segment
		(start 373.732552 -44.200064)
		(end 375.434606 -45.902118)
		(width 0.254)
		(layer "In11.Cu")
		(net "PVCCIO_CPU0")
	)
	(segment
		(start 134.010146 -65.324736)
		(end 134.431786 -65.324736)
		(width 0.254)
		(layer "In11.Cu")
		(net "PVCCIO_CPU0")
	)
	(segment
		(start 375.097294 -42.47896)
		(end 373.732552 -43.843702)
		(width 0.254)
		(layer "In11.Cu")
		(net "PVCCIO_CPU0")
	)
	(segment
		(start 138.926824 -67.983862)
		(end 138.926824 -68.011802)
		(width 0.254)
		(layer "In11.Cu")
		(net "PVCCIO_CPU0")
	)
	(segment
		(start 177.10277 -71.388224)
		(end 177.10277 -67.842892)
		(width 0.4064)
		(layer "In11.Cu")
		(net "PVCCIO_CPU0")
	)
	(segment
		(start 137.247884 -67.032124)
		(end 137.247884 -67.07886)
		(width 0.254)
		(layer "In11.Cu")
		(net "PVCCIO_CPU0")
	)
	(segment
		(start 160.33369 -50.890678)
		(end 160.33369 -52.884832)
		(width 0.254)
		(layer "In11.Cu")
		(net "PVCCIO_CPU0")
	)
	(segment
		(start 392.0998 -81.4578)
		(end 390.7663 -80.1243)
		(width 0.254)
		(layer "In11.Cu")
		(net "PVCCIO_CPU0")
	)
	(segment
		(start 319.534032 -64.331088)
		(end 313.38647 -64.331088)
		(width 0.254)
		(layer "In11.Cu")
		(net "PVCCIO_CPU0")
	)
	(segment
		(start 365.0996 -62.0141)
		(end 363.868716 -62.0141)
		(width 0.254)
		(layer "In11.Cu")
		(net "PVCCIO_CPU0")
	)
	(segment
		(start 313.38647 -64.331088)
		(end 311.39892 -62.343538)
		(width 0.254)
		(layer "In11.Cu")
		(net "PVCCIO_CPU0")
	)
	(segment
		(start 140.660628 -68.988432)
		(end 140.660628 -69.029072)
		(width 0.254)
		(layer "In11.Cu")
		(net "PVCCIO_CPU0")
	)
	(segment
		(start 311.39892 -62.343538)
		(end 305.246786 -62.343538)
		(width 0.254)
		(layer "In11.Cu")
		(net "PVCCIO_CPU0")
	)
	(segment
		(start 132.274056 -65.30975)
		(end 132.714238 -65.30975)
		(width 0.254)
		(layer "In11.Cu")
		(net "PVCCIO_CPU0")
	)
	(segment
		(start 167.667178 -42.390822)
		(end 166.2176 -43.8404)
		(width 0.254)
		(layer "In11.Cu")
		(net "PVCCIO_CPU0")
	)
	(segment
		(start 177.84826 -76.2889)
		(end 177.84826 -72.133714)
		(width 0.4064)
		(layer "In11.Cu")
		(net "PVCCIO_CPU0")
	)
	(segment
		(start 160.33369 -52.884832)
		(end 159.47263 -53.745892)
		(width 0.254)
		(layer "In11.Cu")
		(net "PVCCIO_CPU0")
	)
	(segment
		(start 131.267454 -65.81013)
		(end 131.850638 -65.81013)
		(width 0.254)
		(layer "In11.Cu")
		(net "PVCCIO_CPU0")
	)
	(segment
		(start 438.841388 -15.985998)
		(end 442.570108 -15.985998)
		(width 0.254)
		(layer "In11.Cu")
		(net "PVCCIO_CPU0")
	)
	(segment
		(start 375.097294 -39.9796)
		(end 375.097294 -42.47896)
		(width 0.254)
		(layer "In11.Cu")
		(net "PVCCIO_CPU0")
	)
	(segment
		(start 333.815182 -62.23)
		(end 332.603348 -61.018166)
		(width 0.254)
		(layer "In11.Cu")
		(net "PVCCIO_CPU0")
	)
	(segment
		(start 142.75943 -69.457316)
		(end 143.463264 -69.457316)
		(width 0.254)
		(layer "In11.Cu")
		(net "PVCCIO_CPU0")
	)
	(segment
		(start 139.80287 -68.486782)
		(end 139.80287 -68.534534)
		(width 0.254)
		(layer "In11.Cu")
		(net "PVCCIO_CPU0")
	)
	(segment
		(start 143.463264 -69.457316)
		(end 144.643094 -70.637146)
		(width 0.254)
		(layer "In11.Cu")
		(net "PVCCIO_CPU0")
	)
	(segment
		(start 331.070966 -61.73978)
		(end 323.322442 -61.73978)
		(width 0.254)
		(layer "In11.Cu")
		(net "PVCCIO_CPU0")
	)
	(segment
		(start 136.39165 -66.579242)
		(end 136.61771 -66.805302)
		(width 0.254)
		(layer "In11.Cu")
		(net "PVCCIO_CPU0")
	)
	(segment
		(start 137.469118 -67.300094)
		(end 137.874248 -67.300094)
		(width 0.254)
		(layer "In11.Cu")
		(net "PVCCIO_CPU0")
	)
	(segment
		(start 138.078972 -67.528694)
		(end 138.331448 -67.78117)
		(width 0.254)
		(layer "In11.Cu")
		(net "PVCCIO_CPU0")
	)
	(segment
		(start 129.211578 -65.667128)
		(end 129.503932 -65.667128)
		(width 0.254)
		(layer "In11.Cu")
		(net "PVCCIO_CPU0")
	)
	(segment
		(start 322.946522 -61.36386)
		(end 322.50126 -61.36386)
		(width 0.254)
		(layer "In11.Cu")
		(net "PVCCIO_CPU0")
	)
	(segment
		(start 144.643094 -70.637146)
		(end 146.076416 -70.637146)
		(width 0.254)
		(layer "In11.Cu")
		(net "PVCCIO_CPU0")
	)
	(segment
		(start 181.79796 -20.23364)
		(end 183.536336 -21.972016)
		(width 0.254)
		(layer "In11.Cu")
		(net "PVCCIO_CPU0")
	)
	(segment
		(start 180.741066 -63.220092)
		(end 178.308508 -63.220092)
		(width 0.4064)
		(layer "In11.Cu")
		(net "PVCCIO_CPU0")
	)
	(segment
		(start 156.425646 -83.31454)
		(end 164.288724 -91.177618)
		(width 0.254)
		(layer "In11.Cu")
		(net "PVCCIO_CPU0")
	)
	(segment
		(start 409.919424 -14.743176)
		(end 414.378648 -19.2024)
		(width 0.254)
		(layer "In11.Cu")
		(net "PVCCIO_CPU0")
	)
	(segment
		(start 432.35626 -16.208248)
		(end 438.619138 -16.208248)
		(width 0.254)
		(layer "In11.Cu")
		(net "PVCCIO_CPU0")
	)
	(segment
		(start 146.076416 -70.22465)
		(end 146.076416 -70.637146)
		(width 0.254)
		(layer "In11.Cu")
		(net "PVCCIO_CPU0")
	)
	(segment
		(start 133.826758 -65.078356)
		(end 133.826758 -65.141348)
		(width 0.254)
		(layer "In11.Cu")
		(net "PVCCIO_CPU0")
	)
	(segment
		(start 178.308508 -63.220092)
		(end 177.10277 -64.42583)
		(width 0.4064)
		(layer "In11.Cu")
		(net "PVCCIO_CPU0")
	)
	(segment
		(start 181.64302 -20.23364)
		(end 181.79796 -20.23364)
		(width 0.254)
		(layer "In11.Cu")
		(net "PVCCIO_CPU0")
	)
	(segment
		(start 136.61771 -66.805302)
		(end 137.021062 -66.805302)
		(width 0.254)
		(layer "In11.Cu")
		(net "PVCCIO_CPU0")
	)
	(segment
		(start 135.2804 -65.809876)
		(end 135.562086 -66.091562)
		(width 0.254)
		(layer "In11.Cu")
		(net "PVCCIO_CPU0")
	)
	(segment
		(start 177.10277 -64.42583)
		(end 177.10277 -67.842892)
		(width 0.4064)
		(layer "In11.Cu")
		(net "PVCCIO_CPU0")
	)
	(segment
		(start 184.33415 -61.35624)
		(end 183.70296 -61.35624)
		(width 0.4064)
		(layer "In11.Cu")
		(net "PVCCIO_CPU0")
	)
	(segment
		(start 137.021062 -66.805302)
		(end 137.247884 -67.032124)
		(width 0.254)
		(layer "In11.Cu")
		(net "PVCCIO_CPU0")
	)
	(segment
		(start 142.439136 -69.77761)
		(end 142.75943 -69.457316)
		(width 0.254)
		(layer "In11.Cu")
		(net "PVCCIO_CPU0")
	)
	(segment
		(start 166.2176 -43.8404)
		(end 166.2176 -45.006768)
		(width 0.254)
		(layer "In11.Cu")
		(net "PVCCIO_CPU0")
	)
	(segment
		(start 132.119116 -65.46469)
		(end 132.274056 -65.30975)
		(width 0.254)
		(layer "In11.Cu")
		(net "PVCCIO_CPU0")
	)
	(segment
		(start 141.77772 -69.77761)
		(end 142.439136 -69.77761)
		(width 0.254)
		(layer "In11.Cu")
		(net "PVCCIO_CPU0")
	)
	(segment
		(start 323.322442 -61.73978)
		(end 322.946522 -61.36386)
		(width 0.254)
		(layer "In11.Cu")
		(net "PVCCIO_CPU0")
	)
	(segment
		(start 392.0998 -81.9404)
		(end 392.0998 -81.4578)
		(width 0.254)
		(layer "In11.Cu")
		(net "PVCCIO_CPU0")
	)
	(segment
		(start 332.603348 -61.018166)
		(end 331.79258 -61.018166)
		(width 0.254)
		(layer "In11.Cu")
		(net "PVCCIO_CPU0")
	)
	(segment
		(start 138.078972 -67.504818)
		(end 138.078972 -67.528694)
		(width 0.254)
		(layer "In11.Cu")
		(net "PVCCIO_CPU0")
	)
	(segment
		(start 140.042138 -68.773802)
		(end 140.445998 -68.773802)
		(width 0.254)
		(layer "In11.Cu")
		(net "PVCCIO_CPU0")
	)
	(segment
		(start 138.926824 -68.011802)
		(end 139.202414 -68.287392)
		(width 0.254)
		(layer "In11.Cu")
		(net "PVCCIO_CPU0")
	)
	(segment
		(start 129.718054 -65.453006)
		(end 130.91033 -65.453006)
		(width 0.254)
		(layer "In11.Cu")
		(net "PVCCIO_CPU0")
	)
	(segment
		(start 133.578346 -64.829944)
		(end 133.826758 -65.078356)
		(width 0.254)
		(layer "In11.Cu")
		(net "PVCCIO_CPU0")
	)
	(segment
		(start 363.004608 -62.878208)
		(end 357.098346 -62.878208)
		(width 0.254)
		(layer "In11.Cu")
		(net "PVCCIO_CPU0")
	)
	(segment
		(start 181.87543 -62.085728)
		(end 180.741066 -63.220092)
		(width 0.4064)
		(layer "In11.Cu")
		(net "PVCCIO_CPU0")
	)
	(segment
		(start 132.714238 -65.30975)
		(end 132.963666 -65.060322)
		(width 0.254)
		(layer "In11.Cu")
		(net "PVCCIO_CPU0")
	)
	(segment
		(start 357.098346 -62.878208)
		(end 356.450138 -62.23)
		(width 0.254)
		(layer "In11.Cu")
		(net "PVCCIO_CPU0")
	)
	(segment
		(start 139.80287 -68.534534)
		(end 140.042138 -68.773802)
		(width 0.254)
		(layer "In11.Cu")
		(net "PVCCIO_CPU0")
	)
	(segment
		(start 132.119116 -65.541652)
		(end 132.119116 -65.46469)
		(width 0.254)
		(layer "In11.Cu")
		(net "PVCCIO_CPU0")
	)
	(segment
		(start 156.425646 -80.986376)
		(end 156.425646 -83.31454)
		(width 0.254)
		(layer "In11.Cu")
		(net "PVCCIO_CPU0")
	)
	(segment
		(start 438.619138 -16.208248)
		(end 438.841388 -15.985998)
		(width 0.254)
		(layer "In11.Cu")
		(net "PVCCIO_CPU0")
	)
	(segment
		(start 140.660628 -69.029072)
		(end 140.91412 -69.282564)
		(width 0.254)
		(layer "In11.Cu")
		(net "PVCCIO_CPU0")
	)
	(segment
		(start 135.562086 -66.147442)
		(end 135.71093 -66.296286)
		(width 0.254)
		(layer "In11.Cu")
		(net "PVCCIO_CPU0")
	)
	(segment
		(start 153.831798 -69.713094)
		(end 146.587972 -69.713094)
		(width 0.254)
		(layer "In11.Cu")
		(net "PVCCIO_CPU0")
	)
	(segment
		(start 373.732552 -44.1198)
		(end 373.732552 -44.200064)
		(width 0.254)
		(layer "In11.Cu")
		(net "PVCCIO_CPU0")
	)
	(segment
		(start 166.2176 -45.006768)
		(end 160.33369 -50.890678)
		(width 0.254)
		(layer "In11.Cu")
		(net "PVCCIO_CPU0")
	)
	(segment
		(start 141.507972 -69.507862)
		(end 141.77772 -69.77761)
		(width 0.254)
		(layer "In11.Cu")
		(net "PVCCIO_CPU0")
	)
	(segment
		(start 177.84826 -72.133714)
		(end 177.10277 -71.388224)
		(width 0.4064)
		(layer "In11.Cu")
		(net "PVCCIO_CPU0")
	)
	(segment
		(start 164.288724 -91.177618)
		(end 170.965114 -91.177618)
		(width 0.254)
		(layer "In11.Cu")
		(net "PVCCIO_CPU0")
	)
	(segment
		(start 135.562086 -66.091562)
		(end 135.562086 -66.147442)
		(width 0.254)
		(layer "In11.Cu")
		(net "PVCCIO_CPU0")
	)
	(segment
		(start 136.39165 -66.54419)
		(end 136.39165 -66.579242)
		(width 0.254)
		(layer "In11.Cu")
		(net "PVCCIO_CPU0")
	)
	(segment
		(start 373.732552 -43.843702)
		(end 373.732552 -44.1198)
		(width 0.254)
		(layer "In11.Cu")
		(net "PVCCIO_CPU0")
	)
	(segment
		(start 131.850638 -65.81013)
		(end 132.119116 -65.541652)
		(width 0.254)
		(layer "In11.Cu")
		(net "PVCCIO_CPU0")
	)
	(segment
		(start 140.91412 -69.282564)
		(end 141.311122 -69.282564)
		(width 0.254)
		(layer "In11.Cu")
		(net "PVCCIO_CPU0")
	)
	(segment
		(start 135.71093 -66.296286)
		(end 136.143746 -66.296286)
		(width 0.254)
		(layer "In11.Cu")
		(net "PVCCIO_CPU0")
	)
	(segment
		(start 130.91033 -65.453006)
		(end 131.267454 -65.81013)
		(width 0.254)
		(layer "In11.Cu")
		(net "PVCCIO_CPU0")
	)
	(segment
		(start 132.963666 -65.019428)
		(end 133.15315 -64.829944)
		(width 0.254)
		(layer "In11.Cu")
		(net "PVCCIO_CPU0")
	)
	(segment
		(start 159.47263 -61.307472)
		(end 158.511748 -62.268354)
		(width 0.254)
		(layer "In11.Cu")
		(net "PVCCIO_CPU0")
	)
	(segment
		(start 179.110386 -77.551026)
		(end 177.84826 -76.2889)
		(width 0.4064)
		(layer "In11.Cu")
		(net "PVCCIO_CPU0")
	)
	(segment
		(start 390.7663 -80.1243)
		(end 390.7663 -79.8322)
		(width 0.254)
		(layer "In11.Cu")
		(net "PVCCIO_CPU0")
	)
	(segment
		(start 133.826758 -65.141348)
		(end 134.010146 -65.324736)
		(width 0.254)
		(layer "In11.Cu")
		(net "PVCCIO_CPU0")
	)
	(segment
		(start 136.143746 -66.296286)
		(end 136.39165 -66.54419)
		(width 0.254)
		(layer "In11.Cu")
		(net "PVCCIO_CPU0")
	)
	(segment
		(start 134.689088 -65.582038)
		(end 134.689088 -65.63995)
		(width 0.254)
		(layer "In11.Cu")
		(net "PVCCIO_CPU0")
	)
	(segment
		(start 414.378648 -19.2024)
		(end 418.276024 -19.2024)
		(width 0.254)
		(layer "In11.Cu")
		(net "PVCCIO_CPU0")
	)
	(segment
		(start 356.450138 -62.23)
		(end 333.815182 -62.23)
		(width 0.254)
		(layer "In11.Cu")
		(net "PVCCIO_CPU0")
	)
	(segment
		(start 140.445998 -68.773802)
		(end 140.660628 -68.988432)
		(width 0.254)
		(layer "In11.Cu")
		(net "PVCCIO_CPU0")
	)
	(segment
		(start 134.689088 -65.63995)
		(end 134.859014 -65.809876)
		(width 0.254)
		(layer "In11.Cu")
		(net "PVCCIO_CPU0")
	)
	(segment
		(start 183.70296 -61.35624)
		(end 182.973472 -62.085728)
		(width 0.4064)
		(layer "In11.Cu")
		(net "PVCCIO_CPU0")
	)
	(segment
		(start 139.202414 -68.287392)
		(end 139.60348 -68.287392)
		(width 0.254)
		(layer "In11.Cu")
		(net "PVCCIO_CPU0")
	)
	(segment
		(start 418.276024 -19.2024)
		(end 421.081962 -16.396462)
		(width 0.254)
		(layer "In11.Cu")
		(net "PVCCIO_CPU0")
	)
	(segment
		(start 442.570108 -15.985998)
		(end 443.567312 -14.988794)
		(width 0.254)
		(layer "In11.Cu")
		(net "PVCCIO_CPU0")
	)
	(segment
		(start 421.081962 -16.396462)
		(end 432.168046 -16.396462)
		(width 0.254)
		(layer "In11.Cu")
		(net "PVCCIO_CPU0")
	)
	(segment
		(start 363.868716 -62.0141)
		(end 363.004608 -62.878208)
		(width 0.254)
		(layer "In11.Cu")
		(net "PVCCIO_CPU0")
	)
	(segment
		(start 133.15315 -64.829944)
		(end 133.578346 -64.829944)
		(width 0.254)
		(layer "In11.Cu")
		(net "PVCCIO_CPU0")
	)
	(segment
		(start 401.0914 -16.7132)
		(end 403.061424 -14.743176)
		(width 0.254)
		(layer "In11.Cu")
		(net "PVCCIO_CPU0")
	)
	(segment
		(start 132.963666 -65.060322)
		(end 132.963666 -65.019428)
		(width 0.254)
		(layer "In11.Cu")
		(net "PVCCIO_CPU0")
	)
	(segment
		(start 146.076416 -70.637146)
		(end 156.425646 -80.986376)
		(width 0.254)
		(layer "In11.Cu")
		(net "PVCCIO_CPU0")
	)
	(segment
		(start 134.431786 -65.324736)
		(end 134.689088 -65.582038)
		(width 0.254)
		(layer "In11.Cu")
		(net "PVCCIO_CPU0")
	)
	(segment
		(start 139.60348 -68.287392)
		(end 139.80287 -68.486782)
		(width 0.254)
		(layer "In11.Cu")
		(net "PVCCIO_CPU0")
	)
	(segment
		(start 159.47263 -53.745892)
		(end 159.47263 -61.307472)
		(width 0.254)
		(layer "In11.Cu")
		(net "PVCCIO_CPU0")
	)
	(segment
		(start 432.168046 -16.396462)
		(end 432.35626 -16.208248)
		(width 0.254)
		(layer "In11.Cu")
		(net "PVCCIO_CPU0")
	)
	(segment
		(start 322.50126 -61.36386)
		(end 319.534032 -64.331088)
		(width 0.254)
		(layer "In11.Cu")
		(net "PVCCIO_CPU0")
	)
	(segment
		(start 90.070178 -80.35544)
		(end 90.692478 -80.35544)
		(width 0.254)
		(layer "F.Cu")
		(net "PVCCIN_CPU1")
	)
	(segment
		(start 84.060792 -73.916286)
		(end 83.489292 -73.916286)
		(width 0.254)
		(layer "F.Cu")
		(net "PVCCIN_CPU1")
	)
	(segment
		(start 95.221298 -64.50584)
		(end 94.649798 -64.50584)
		(width 0.254)
		(layer "F.Cu")
		(net "PVCCIN_CPU1")
	)
	(segment
		(start 85.777832 -76.888086)
		(end 85.206332 -76.888086)
		(width 0.254)
		(layer "F.Cu")
		(net "PVCCIN_CPU1")
	)
	(segment
		(start 74.617326 -79.36484)
		(end 74.045826 -79.36484)
		(width 0.254)
		(layer "F.Cu")
		(net "PVCCIN_CPU1")
	)
	(segment
		(start 83.202272 -77.38364)
		(end 82.630772 -77.38364)
		(width 0.254)
		(layer "F.Cu")
		(net "PVCCIN_CPU1")
	)
	(segment
		(start 90.070178 -75.40244)
		(end 90.692478 -75.40244)
		(width 0.254)
		(layer "F.Cu")
		(net "PVCCIN_CPU1")
	)
	(segment
		(start 94.362778 -86.794086)
		(end 93.791278 -86.794086)
		(width 0.254)
		(layer "F.Cu")
		(net "PVCCIN_CPU1")
	)
	(segment
		(start 115.636802 -67.296538)
		(end 115.636802 -67.868038)
		(width 0.254)
		(layer "F.Cu")
		(net "PVCCIN_CPU1")
	)
	(segment
		(start 68.892928 -72.43064)
		(end 68.806568 -72.517)
		(width 0.254)
		(layer "F.Cu")
		(net "PVCCIN_CPU1")
	)
	(segment
		(start 72.041766 -70.94474)
		(end 71.470266 -70.94474)
		(width 0.254)
		(layer "F.Cu")
		(net "PVCCIN_CPU1")
	)
	(segment
		(start 83.202272 -78.37424)
		(end 82.630772 -78.37424)
		(width 0.254)
		(layer "F.Cu")
		(net "PVCCIN_CPU1")
	)
	(segment
		(start 72.041766 -75.897486)
		(end 71.470266 -75.897486)
		(width 0.254)
		(layer "F.Cu")
		(net "PVCCIN_CPU1")
	)
	(segment
		(start 97.796858 -87.784686)
		(end 97.796858 -87.175086)
		(width 0.254)
		(layer "F.Cu")
		(net "PVCCIN_CPU1")
	)
	(segment
		(start 96.079818 -64.010286)
		(end 95.508318 -64.010286)
		(width 0.254)
		(layer "F.Cu")
		(net "PVCCIN_CPU1")
	)
	(segment
		(start 31.291276 -70.782434)
		(end 31.0896 -70.782434)
		(width 0.254)
		(layer "F.Cu")
		(net "PVCCIN_CPU1")
	)
	(segment
		(start 102.089204 -88.28024)
		(end 102.089204 -87.67064)
		(width 0.254)
		(layer "F.Cu")
		(net "PVCCIN_CPU1")
	)
	(segment
		(start 100.372164 -88.28024)
		(end 100.372164 -87.67064)
		(width 0.254)
		(layer "F.Cu")
		(net "PVCCIN_CPU1")
	)
	(segment
		(start 75.475846 -74.906886)
		(end 74.904346 -74.906886)
		(width 0.254)
		(layer "F.Cu")
		(net "PVCCIN_CPU1")
	)
	(segment
		(start 90.070178 -67.47764)
		(end 89.498678 -67.47764)
		(width 0.254)
		(layer "F.Cu")
		(net "PVCCIN_CPU1")
	)
	(segment
		(start 31.409386 -62.772544)
		(end 31.292292 -62.65545)
		(width 0.254)
		(layer "F.Cu")
		(net "PVCCIN_CPU1")
	)
	(segment
		(start 70.324726 -75.897486)
		(end 69.753226 -75.897486)
		(width 0.254)
		(layer "F.Cu")
		(net "PVCCIN_CPU1")
	)
	(segment
		(start 84.060792 -72.925686)
		(end 83.489292 -72.925686)
		(width 0.254)
		(layer "F.Cu")
		(net "PVCCIN_CPU1")
	)
	(segment
		(start 72.041766 -76.888086)
		(end 71.470266 -76.888086)
		(width 0.254)
		(layer "F.Cu")
		(net "PVCCIN_CPU1")
	)
	(segment
		(start 90.070178 -82.33664)
		(end 90.692478 -82.33664)
		(width 0.254)
		(layer "F.Cu")
		(net "PVCCIN_CPU1")
	)
	(segment
		(start 108.768896 -89.089738)
		(end 108.768896 -88.518238)
		(width 0.381)
		(layer "F.Cu")
		(net "PVCCIN_CPU1")
	)
	(segment
		(start 73.758806 -75.897486)
		(end 73.187306 -75.897486)
		(width 0.254)
		(layer "F.Cu")
		(net "PVCCIN_CPU1")
	)
	(segment
		(start 78.051406 -73.42124)
		(end 77.479906 -73.42124)
		(width 0.254)
		(layer "F.Cu")
		(net "PVCCIN_CPU1")
	)
	(segment
		(start 96.938338 -64.50584)
		(end 96.938338 -65.1256)
		(width 0.254)
		(layer "F.Cu")
		(net "PVCCIN_CPU1")
	)
	(segment
		(start 79.768192 -79.36484)
		(end 79.196692 -79.36484)
		(width 0.254)
		(layer "F.Cu")
		(net "PVCCIN_CPU1")
	)
	(segment
		(start 31.409386 -70.900544)
		(end 31.291276 -70.782434)
		(width 0.254)
		(layer "F.Cu")
		(net "PVCCIN_CPU1")
	)
	(segment
		(start 109.627416 -88.594184)
		(end 109.627416 -88.022684)
		(width 0.381)
		(layer "F.Cu")
		(net "PVCCIN_CPU1")
	)
	(segment
		(start 88.353392 -79.36484)
		(end 87.781892 -79.36484)
		(width 0.254)
		(layer "F.Cu")
		(net "PVCCIN_CPU1")
	)
	(segment
		(start 94.362778 -85.803486)
		(end 94.362778 -85.193886)
		(width 0.254)
		(layer "F.Cu")
		(net "PVCCIN_CPU1")
	)
	(segment
		(start 90.070178 -79.36484)
		(end 90.692478 -79.36484)
		(width 0.254)
		(layer "F.Cu")
		(net "PVCCIN_CPU1")
	)
	(segment
		(start 72.900286 -79.36484)
		(end 72.328786 -79.36484)
		(width 0.254)
		(layer "F.Cu")
		(net "PVCCIN_CPU1")
	)
	(segment
		(start 101.230684 -88.775286)
		(end 101.230684 -88.165686)
		(width 0.254)
		(layer "F.Cu")
		(net "PVCCIN_CPU1")
	)
	(segment
		(start 89.211912 -82.83194)
		(end 88.640412 -82.83194)
		(width 0.254)
		(layer "F.Cu")
		(net "PVCCIN_CPU1")
	)
	(segment
		(start 69.466206 -71.44004)
		(end 68.894706 -71.44004)
		(width 0.254)
		(layer "F.Cu")
		(net "PVCCIN_CPU1")
	)
	(segment
		(start 71.183246 -75.40244)
		(end 70.611746 -75.40244)
		(width 0.254)
		(layer "F.Cu")
		(net "PVCCIN_CPU1")
	)
	(segment
		(start 76.334366 -71.44004)
		(end 75.762866 -71.44004)
		(width 0.254)
		(layer "F.Cu")
		(net "PVCCIN_CPU1")
	)
	(segment
		(start 79.768192 -73.42124)
		(end 79.196692 -73.42124)
		(width 0.254)
		(layer "F.Cu")
		(net "PVCCIN_CPU1")
	)
	(segment
		(start 84.060792 -74.906886)
		(end 83.489292 -74.906886)
		(width 0.254)
		(layer "F.Cu")
		(net "PVCCIN_CPU1")
	)
	(segment
		(start 72.041766 -79.859886)
		(end 71.470266 -79.859886)
		(width 0.254)
		(layer "F.Cu")
		(net "PVCCIN_CPU1")
	)
	(segment
		(start 82.343752 -77.878686)
		(end 81.772252 -77.878686)
		(width 0.254)
		(layer "F.Cu")
		(net "PVCCIN_CPU1")
	)
	(segment
		(start 80.626712 -72.925686)
		(end 80.055212 -72.925686)
		(width 0.254)
		(layer "F.Cu")
		(net "PVCCIN_CPU1")
	)
	(segment
		(start 75.475846 -70.94474)
		(end 74.904346 -70.94474)
		(width 0.254)
		(layer "F.Cu")
		(net "PVCCIN_CPU1")
	)
	(segment
		(start 31.292292 -62.65545)
		(end 31.039562 -62.65545)
		(width 0.254)
		(layer "F.Cu")
		(net "PVCCIN_CPU1")
	)
	(segment
		(start 82.343752 -75.897486)
		(end 81.772252 -75.897486)
		(width 0.254)
		(layer "F.Cu")
		(net "PVCCIN_CPU1")
	)
	(segment
		(start 31.095442 -87.048594)
		(end 31.079694 -87.032846)
		(width 0.254)
		(layer "F.Cu")
		(net "PVCCIN_CPU1")
	)
	(segment
		(start 74.617326 -75.40244)
		(end 74.045826 -75.40244)
		(width 0.254)
		(layer "F.Cu")
		(net "PVCCIN_CPU1")
	)
	(segment
		(start 84.919312 -78.37424)
		(end 84.347812 -78.37424)
		(width 0.254)
		(layer "F.Cu")
		(net "PVCCIN_CPU1")
	)
	(segment
		(start 96.079818 -86.794086)
		(end 96.079818 -86.184486)
		(width 0.254)
		(layer "F.Cu")
		(net "PVCCIN_CPU1")
	)
	(segment
		(start 90.928698 -67.972686)
		(end 91.350592 -68.523358)
		(width 0.254)
		(layer "F.Cu")
		(net "PVCCIN_CPU1")
	)
	(segment
		(start 92.645738 -85.803486)
		(end 92.074238 -85.803486)
		(width 0.254)
		(layer "F.Cu")
		(net "PVCCIN_CPU1")
	)
	(segment
		(start 88.353392 -74.411586)
		(end 87.781892 -74.411586)
		(width 0.254)
		(layer "F.Cu")
		(net "PVCCIN_CPU1")
	)
	(segment
		(start 89.211912 -75.897486)
		(end 88.640412 -75.897486)
		(width 0.254)
		(layer "F.Cu")
		(net "PVCCIN_CPU1")
	)
	(segment
		(start 68.869306 -80.35544)
		(end 68.818506 -80.30464)
		(width 0.254)
		(layer "F.Cu")
		(net "PVCCIN_CPU1")
	)
	(segment
		(start 69.466206 -79.36484)
		(end 69.339206 -79.23784)
		(width 0.254)
		(layer "F.Cu")
		(net "PVCCIN_CPU1")
	)
	(segment
		(start 93.504258 -65.49644)
		(end 92.932758 -65.49644)
		(width 0.254)
		(layer "F.Cu")
		(net "PVCCIN_CPU1")
	)
	(segment
		(start 100.372164 -64.50584)
		(end 100.372164 -65.1256)
		(width 0.254)
		(layer "F.Cu")
		(net "PVCCIN_CPU1")
	)
	(segment
		(start 81.485232 -75.40244)
		(end 80.913732 -75.40244)
		(width 0.254)
		(layer "F.Cu")
		(net "PVCCIN_CPU1")
	)
	(segment
		(start 78.051406 -79.36484)
		(end 77.479906 -79.36484)
		(width 0.254)
		(layer "F.Cu")
		(net "PVCCIN_CPU1")
	)
	(segment
		(start 79.768192 -77.38364)
		(end 79.196692 -77.38364)
		(width 0.254)
		(layer "F.Cu")
		(net "PVCCIN_CPU1")
	)
	(segment
		(start 69.466206 -82.33664)
		(end 68.894706 -82.33664)
		(width 0.254)
		(layer "F.Cu")
		(net "PVCCIN_CPU1")
	)
	(segment
		(start 88.353392 -73.42124)
		(end 87.781892 -73.42124)
		(width 0.254)
		(layer "F.Cu")
		(net "PVCCIN_CPU1")
	)
	(segment
		(start 90.56116 -76.261722)
		(end 90.692478 -76.39304)
		(width 0.254)
		(layer "F.Cu")
		(net "PVCCIN_CPU1")
	)
	(segment
		(start 70.324726 -74.906886)
		(end 69.753226 -74.906886)
		(width 0.254)
		(layer "F.Cu")
		(net "PVCCIN_CPU1")
	)
	(segment
		(start 90.070178 -83.32724)
		(end 90.928698 -83.212686)
		(width 0.254)
		(layer "F.Cu")
		(net "PVCCIN_CPU1")
	)
	(segment
		(start 88.353392 -77.38364)
		(end 87.781892 -77.38364)
		(width 0.254)
		(layer "F.Cu")
		(net "PVCCIN_CPU1")
	)
	(segment
		(start 90.070178 -68.46824)
		(end 90.411808 -68.46824)
		(width 0.254)
		(layer "F.Cu")
		(net "PVCCIN_CPU1")
	)
	(segment
		(start 90.070178 -74.411586)
		(end 90.692478 -74.411586)
		(width 0.254)
		(layer "F.Cu")
		(net "PVCCIN_CPU1")
	)
	(segment
		(start 90.070178 -71.44004)
		(end 90.692478 -71.44004)
		(width 0.254)
		(layer "F.Cu")
		(net "PVCCIN_CPU1")
	)
	(segment
		(start 44.1071 -52.78628)
		(end 44.1071 -51.3334)
		(width 0.254)
		(layer "F.Cu")
		(net "PVCCIN_CPU1")
	)
	(segment
		(start 113.919762 -66.305938)
		(end 113.919762 -66.877438)
		(width 0.254)
		(layer "F.Cu")
		(net "PVCCIN_CPU1")
	)
	(segment
		(start 80.626712 -73.916286)
		(end 80.055212 -73.916286)
		(width 0.254)
		(layer "F.Cu")
		(net "PVCCIN_CPU1")
	)
	(segment
		(start 76.621386 -78.869286)
		(end 77.192886 -78.869286)
		(width 0.254)
		(layer "F.Cu")
		(net "PVCCIN_CPU1")
	)
	(segment
		(start 89.211912 -78.869286)
		(end 88.640412 -78.869286)
		(width 0.254)
		(layer "F.Cu")
		(net "PVCCIN_CPU1")
	)
	(segment
		(start 76.621386 -71.935086)
		(end 77.192886 -71.935086)
		(width 0.254)
		(layer "F.Cu")
		(net "PVCCIN_CPU1")
	)
	(segment
		(start 31.645098 -79.028544)
		(end 31.409386 -79.028544)
		(width 0.254)
		(layer "F.Cu")
		(net "PVCCIN_CPU1")
	)
	(segment
		(start 87.494872 -77.878686)
		(end 86.923372 -77.878686)
		(width 0.254)
		(layer "F.Cu")
		(net "PVCCIN_CPU1")
	)
	(segment
		(start 78.909672 -79.859886)
		(end 78.338172 -79.859886)
		(width 0.254)
		(layer "F.Cu")
		(net "PVCCIN_CPU1")
	)
	(segment
		(start 85.777832 -75.897486)
		(end 85.206332 -75.897486)
		(width 0.254)
		(layer "F.Cu")
		(net "PVCCIN_CPU1")
	)
	(segment
		(start 98.655378 -88.28024)
		(end 98.655378 -87.67064)
		(width 0.254)
		(layer "F.Cu")
		(net "PVCCIN_CPU1")
	)
	(segment
		(start 88.353392 -72.43064)
		(end 87.781892 -72.43064)
		(width 0.254)
		(layer "F.Cu")
		(net "PVCCIN_CPU1")
	)
	(segment
		(start 86.636352 -77.38364)
		(end 86.064852 -77.38364)
		(width 0.254)
		(layer "F.Cu")
		(net "PVCCIN_CPU1")
	)
	(segment
		(start 76.621386 -73.916286)
		(end 77.192886 -73.916286)
		(width 0.254)
		(layer "F.Cu")
		(net "PVCCIN_CPU1")
	)
	(segment
		(start 90.070178 -81.34604)
		(end 90.692478 -81.34604)
		(width 0.254)
		(layer "F.Cu")
		(net "PVCCIN_CPU1")
	)
	(segment
		(start 93.504258 -66.48704)
		(end 93.504258 -67.1322)
		(width 0.254)
		(layer "F.Cu")
		(net "PVCCIN_CPU1")
	)
	(segment
		(start 75.475846 -78.869286)
		(end 74.904346 -78.869286)
		(width 0.254)
		(layer "F.Cu")
		(net "PVCCIN_CPU1")
	)
	(segment
		(start 84.919312 -77.38364)
		(end 84.347812 -77.38364)
		(width 0.254)
		(layer "F.Cu")
		(net "PVCCIN_CPU1")
	)
	(segment
		(start 71.183246 -79.36484)
		(end 70.611746 -79.36484)
		(width 0.254)
		(layer "F.Cu")
		(net "PVCCIN_CPU1")
	)
	(segment
		(start 89.211912 -71.935086)
		(end 88.640412 -71.935086)
		(width 0.254)
		(layer "F.Cu")
		(net "PVCCIN_CPU1")
	)
	(segment
		(start 76.621386 -70.94474)
		(end 77.192886 -70.94474)
		(width 0.254)
		(layer "F.Cu")
		(net "PVCCIN_CPU1")
	)
	(segment
		(start 89.211912 -72.925686)
		(end 88.640412 -72.925686)
		(width 0.254)
		(layer "F.Cu")
		(net "PVCCIN_CPU1")
	)
	(segment
		(start 75.475846 -76.888086)
		(end 74.904346 -76.888086)
		(width 0.254)
		(layer "F.Cu")
		(net "PVCCIN_CPU1")
	)
	(segment
		(start 68.607686 -70.94474)
		(end 67.909186 -70.94474)
		(width 0.254)
		(layer "F.Cu")
		(net "PVCCIN_CPU1")
	)
	(segment
		(start 70.324726 -72.925686)
		(end 69.753226 -72.925686)
		(width 0.254)
		(layer "F.Cu")
		(net "PVCCIN_CPU1")
	)
	(segment
		(start 76.334366 -77.38364)
		(end 75.762866 -77.38364)
		(width 0.254)
		(layer "F.Cu")
		(net "PVCCIN_CPU1")
	)
	(segment
		(start 87.494872 -76.888086)
		(end 86.923372 -76.888086)
		(width 0.254)
		(layer "F.Cu")
		(net "PVCCIN_CPU1")
	)
	(segment
		(start 85.777832 -74.906886)
		(end 85.206332 -74.906886)
		(width 0.254)
		(layer "F.Cu")
		(net "PVCCIN_CPU1")
	)
	(segment
		(start 88.353392 -80.35544)
		(end 87.781892 -80.35544)
		(width 0.254)
		(layer "F.Cu")
		(net "PVCCIN_CPU1")
	)
	(segment
		(start 93.504258 -85.30844)
		(end 93.504258 -84.69884)
		(width 0.254)
		(layer "F.Cu")
		(net "PVCCIN_CPU1")
	)
	(segment
		(start 31.645098 -70.900544)
		(end 31.409386 -70.900544)
		(width 0.254)
		(layer "F.Cu")
		(net "PVCCIN_CPU1")
	)
	(segment
		(start 89.211912 -70.94474)
		(end 88.640412 -70.94474)
		(width 0.254)
		(layer "F.Cu")
		(net "PVCCIN_CPU1")
	)
	(segment
		(start 107.910376 -88.594184)
		(end 107.910376 -88.022684)
		(width 0.381)
		(layer "F.Cu")
		(net "PVCCIN_CPU1")
	)
	(segment
		(start 72.041766 -78.869286)
		(end 71.470266 -78.869286)
		(width 0.254)
		(layer "F.Cu")
		(net "PVCCIN_CPU1")
	)
	(segment
		(start 93.504258 -86.29904)
		(end 92.932758 -86.29904)
		(width 0.254)
		(layer "F.Cu")
		(net "PVCCIN_CPU1")
	)
	(segment
		(start 110.485682 -64.324738)
		(end 110.485682 -64.896238)
		(width 0.254)
		(layer "F.Cu")
		(net "PVCCIN_CPU1")
	)
	(segment
		(start 82.343752 -76.888086)
		(end 81.772252 -76.888086)
		(width 0.254)
		(layer "F.Cu")
		(net "PVCCIN_CPU1")
	)
	(segment
		(start 76.621386 -74.906886)
		(end 77.192886 -74.906886)
		(width 0.254)
		(layer "F.Cu")
		(net "PVCCIN_CPU1")
	)
	(segment
		(start 89.211912 -80.850486)
		(end 88.640412 -80.850486)
		(width 0.254)
		(layer "F.Cu")
		(net "PVCCIN_CPU1")
	)
	(segment
		(start 102.089204 -64.50584)
		(end 102.089204 -65.151)
		(width 0.254)
		(layer "F.Cu")
		(net "PVCCIN_CPU1")
	)
	(segment
		(start 88.353392 -76.39304)
		(end 87.781892 -76.39304)
		(width 0.254)
		(layer "F.Cu")
		(net "PVCCIN_CPU1")
	)
	(segment
		(start 89.211912 -76.888086)
		(end 88.640412 -76.888086)
		(width 0.254)
		(layer "F.Cu")
		(net "PVCCIN_CPU1")
	)
	(segment
		(start 75.475846 -72.925686)
		(end 74.904346 -72.925686)
		(width 0.254)
		(layer "F.Cu")
		(net "PVCCIN_CPU1")
	)
	(segment
		(start 78.909672 -77.878686)
		(end 78.338172 -77.878686)
		(width 0.254)
		(layer "F.Cu")
		(net "PVCCIN_CPU1")
	)
	(segment
		(start 87.494872 -73.916286)
		(end 86.923372 -73.916286)
		(width 0.254)
		(layer "F.Cu")
		(net "PVCCIN_CPU1")
	)
	(segment
		(start 90.928698 -84.812886)
		(end 90.357198 -84.812886)
		(width 0.254)
		(layer "F.Cu")
		(net "PVCCIN_CPU1")
	)
	(segment
		(start 89.211912 -74.906886)
		(end 88.640412 -74.906886)
		(width 0.254)
		(layer "F.Cu")
		(net "PVCCIN_CPU1")
	)
	(segment
		(start 73.758806 -77.878686)
		(end 73.187306 -77.878686)
		(width 0.254)
		(layer "F.Cu")
		(net "PVCCIN_CPU1")
	)
	(segment
		(start 89.211912 -79.859886)
		(end 88.640412 -79.859886)
		(width 0.254)
		(layer "F.Cu")
		(net "PVCCIN_CPU1")
	)
	(segment
		(start 89.211912 -77.878686)
		(end 88.640412 -77.878686)
		(width 0.254)
		(layer "F.Cu")
		(net "PVCCIN_CPU1")
	)
	(segment
		(start 73.758806 -71.935086)
		(end 73.187306 -71.935086)
		(width 0.254)
		(layer "F.Cu")
		(net "PVCCIN_CPU1")
	)
	(segment
		(start 31.645098 -62.772544)
		(end 31.409386 -62.772544)
		(width 0.254)
		(layer "F.Cu")
		(net "PVCCIN_CPU1")
	)
	(segment
		(start 80.626712 -75.897486)
		(end 80.055212 -75.897486)
		(width 0.254)
		(layer "F.Cu")
		(net "PVCCIN_CPU1")
	)
	(segment
		(start 86.636352 -72.43064)
		(end 86.064852 -72.43064)
		(width 0.254)
		(layer "F.Cu")
		(net "PVCCIN_CPU1")
	)
	(segment
		(start 75.475846 -71.935086)
		(end 74.904346 -71.935086)
		(width 0.254)
		(layer "F.Cu")
		(net "PVCCIN_CPU1")
	)
	(segment
		(start 70.324726 -76.888086)
		(end 69.753226 -76.888086)
		(width 0.254)
		(layer "F.Cu")
		(net "PVCCIN_CPU1")
	)
	(segment
		(start 95.221298 -65.49644)
		(end 95.221298 -66.1162)
		(width 0.254)
		(layer "F.Cu")
		(net "PVCCIN_CPU1")
	)
	(segment
		(start 96.079818 -65.000886)
		(end 96.079818 -65.6336)
		(width 0.254)
		(layer "F.Cu")
		(net "PVCCIN_CPU1")
	)
	(segment
		(start 68.607686 -71.935086)
		(end 67.909186 -71.935086)
		(width 0.254)
		(layer "F.Cu")
		(net "PVCCIN_CPU1")
	)
	(segment
		(start 88.353392 -70.44944)
		(end 87.781892 -70.44944)
		(width 0.254)
		(layer "F.Cu")
		(net "PVCCIN_CPU1")
	)
	(segment
		(start 69.466206 -80.35544)
		(end 68.869306 -80.35544)
		(width 0.254)
		(layer "F.Cu")
		(net "PVCCIN_CPU1")
	)
	(segment
		(start 90.411808 -68.46824)
		(end 90.701368 -68.7578)
		(width 0.254)
		(layer "F.Cu")
		(net "PVCCIN_CPU1")
	)
	(segment
		(start 72.041766 -73.916286)
		(end 71.470266 -73.916286)
		(width 0.254)
		(layer "F.Cu")
		(net "PVCCIN_CPU1")
	)
	(segment
		(start 71.183246 -71.44004)
		(end 70.611746 -71.44004)
		(width 0.254)
		(layer "F.Cu")
		(net "PVCCIN_CPU1")
	)
	(segment
		(start 76.334366 -73.42124)
		(end 75.762866 -73.42124)
		(width 0.254)
		(layer "F.Cu")
		(net "PVCCIN_CPU1")
	)
	(segment
		(start 90.070178 -72.43064)
		(end 90.692478 -72.43064)
		(width 0.254)
		(layer "F.Cu")
		(net "PVCCIN_CPU1")
	)
	(segment
		(start 69.466206 -81.34604)
		(end 68.894706 -81.34604)
		(width 0.254)
		(layer "F.Cu")
		(net "PVCCIN_CPU1")
	)
	(segment
		(start 85.777832 -73.916286)
		(end 85.206332 -73.916286)
		(width 0.254)
		(layer "F.Cu")
		(net "PVCCIN_CPU1")
	)
	(segment
		(start 78.909672 -78.869286)
		(end 78.338172 -78.869286)
		(width 0.254)
		(layer "F.Cu")
		(net "PVCCIN_CPU1")
	)
	(segment
		(start 76.621386 -79.859886)
		(end 77.192886 -79.859886)
		(width 0.254)
		(layer "F.Cu")
		(net "PVCCIN_CPU1")
	)
	(segment
		(start 89.211912 -81.841086)
		(end 88.640412 -81.841086)
		(width 0.254)
		(layer "F.Cu")
		(net "PVCCIN_CPU1")
	)
	(segment
		(start 69.466206 -77.38364)
		(end 68.806568 -77.38364)
		(width 0.254)
		(layer "F.Cu")
		(net "PVCCIN_CPU1")
	)
	(segment
		(start 76.621386 -77.878686)
		(end 77.192886 -77.878686)
		(width 0.254)
		(layer "F.Cu")
		(net "PVCCIN_CPU1")
	)
	(segment
		(start 67.970654 -81.841086)
		(end 67.917568 -81.788)
		(width 0.254)
		(layer "F.Cu")
		(net "PVCCIN_CPU1")
	)
	(segment
		(start 89.211912 -68.963286)
		(end 88.640412 -68.963286)
		(width 0.254)
		(layer "F.Cu")
		(net "PVCCIN_CPU1")
	)
	(segment
		(start 78.909672 -73.916286)
		(end 78.338172 -73.916286)
		(width 0.254)
		(layer "F.Cu")
		(net "PVCCIN_CPU1")
	)
	(segment
		(start 106.193336 -63.829184)
		(end 106.193336 -64.400684)
		(width 0.1016)
		(layer "F.Cu")
		(net "PVCCIN_CPU1")
	)
	(segment
		(start 69.466206 -76.39304)
		(end 68.806568 -76.39304)
		(width 0.254)
		(layer "F.Cu")
		(net "PVCCIN_CPU1")
	)
	(segment
		(start 73.758806 -74.906886)
		(end 73.187306 -74.906886)
		(width 0.254)
		(layer "F.Cu")
		(net "PVCCIN_CPU1")
	)
	(segment
		(start 75.475846 -73.916286)
		(end 74.904346 -73.916286)
		(width 0.254)
		(layer "F.Cu")
		(net "PVCCIN_CPU1")
	)
	(segment
		(start 99.513898 -88.775286)
		(end 99.513898 -88.165686)
		(width 0.254)
		(layer "F.Cu")
		(net "PVCCIN_CPU1")
	)
	(segment
		(start 31.409386 -79.028544)
		(end 31.281624 -78.900782)
		(width 0.254)
		(layer "F.Cu")
		(net "PVCCIN_CPU1")
	)
	(segment
		(start 44.1198 -52.79898)
		(end 44.1071 -52.78628)
		(width 0.254)
		(layer "F.Cu")
		(net "PVCCIN_CPU1")
	)
	(segment
		(start 70.324726 -70.94474)
		(end 69.753226 -70.94474)
		(width 0.254)
		(layer "F.Cu")
		(net "PVCCIN_CPU1")
	)
	(segment
		(start 90.070178 -69.45884)
		(end 90.692478 -69.45884)
		(width 0.254)
		(layer "F.Cu")
		(net "PVCCIN_CPU1")
	)
	(segment
		(start 81.485232 -73.42124)
		(end 80.913732 -73.42124)
		(width 0.254)
		(layer "F.Cu")
		(net "PVCCIN_CPU1")
	)
	(segment
		(start 75.475846 -79.859886)
		(end 74.904346 -79.859886)
		(width 0.254)
		(layer "F.Cu")
		(net "PVCCIN_CPU1")
	)
	(segment
		(start 81.485232 -78.37424)
		(end 80.913732 -78.37424)
		(width 0.254)
		(layer "F.Cu")
		(net "PVCCIN_CPU1")
	)
	(segment
		(start 80.626712 -76.888086)
		(end 80.055212 -76.888086)
		(width 0.254)
		(layer "F.Cu")
		(net "PVCCIN_CPU1")
	)
	(segment
		(start 68.607686 -80.850486)
		(end 67.909186 -80.850486)
		(width 0.254)
		(layer "F.Cu")
		(net "PVCCIN_CPU1")
	)
	(segment
		(start 83.202272 -72.43064)
		(end 82.630772 -72.43064)
		(width 0.254)
		(layer "F.Cu")
		(net "PVCCIN_CPU1")
	)
	(segment
		(start 31.409386 -87.156544)
		(end 31.301436 -87.048594)
		(width 0.254)
		(layer "F.Cu")
		(net "PVCCIN_CPU1")
	)
	(segment
		(start 80.626712 -74.906886)
		(end 80.055212 -74.906886)
		(width 0.254)
		(layer "F.Cu")
		(net "PVCCIN_CPU1")
	)
	(segment
		(start 72.041766 -74.906886)
		(end 71.470266 -74.906886)
		(width 0.254)
		(layer "F.Cu")
		(net "PVCCIN_CPU1")
	)
	(segment
		(start 98.655378 -64.50584)
		(end 98.655378 -65.151)
		(width 0.254)
		(layer "F.Cu")
		(net "PVCCIN_CPU1")
	)
	(segment
		(start 75.475846 -77.878686)
		(end 74.904346 -77.878686)
		(width 0.254)
		(layer "F.Cu")
		(net "PVCCIN_CPU1")
	)
	(segment
		(start 78.909672 -72.925686)
		(end 78.338172 -72.925686)
		(width 0.254)
		(layer "F.Cu")
		(net "PVCCIN_CPU1")
	)
	(segment
		(start 89.211912 -69.953886)
		(end 88.640412 -69.953886)
		(width 0.254)
		(layer "F.Cu")
		(net "PVCCIN_CPU1")
	)
	(segment
		(start 84.919312 -72.43064)
		(end 84.347812 -72.43064)
		(width 0.254)
		(layer "F.Cu")
		(net "PVCCIN_CPU1")
	)
	(segment
		(start 72.041766 -72.925686)
		(end 71.470266 -72.925686)
		(width 0.254)
		(layer "F.Cu")
		(net "PVCCIN_CPU1")
	)
	(segment
		(start 112.202722 -65.315338)
		(end 112.202722 -65.886838)
		(width 0.254)
		(layer "F.Cu")
		(net "PVCCIN_CPU1")
	)
	(segment
		(start 85.777832 -72.925686)
		(end 85.206332 -72.925686)
		(width 0.254)
		(layer "F.Cu")
		(net "PVCCIN_CPU1")
	)
	(segment
		(start 72.900286 -71.44004)
		(end 72.328786 -71.44004)
		(width 0.254)
		(layer "F.Cu")
		(net "PVCCIN_CPU1")
	)
	(segment
		(start 78.909672 -74.906886)
		(end 78.338172 -74.906886)
		(width 0.254)
		(layer "F.Cu")
		(net "PVCCIN_CPU1")
	)
	(segment
		(start 72.041766 -77.878686)
		(end 71.470266 -77.878686)
		(width 0.254)
		(layer "F.Cu")
		(net "PVCCIN_CPU1")
	)
	(segment
		(start 90.070178 -77.38364)
		(end 90.692478 -77.38364)
		(width 0.254)
		(layer "F.Cu")
		(net "PVCCIN_CPU1")
	)
	(segment
		(start 86.636352 -78.37424)
		(end 86.064852 -78.37424)
		(width 0.254)
		(layer "F.Cu")
		(net "PVCCIN_CPU1")
	)
	(segment
		(start 91.787218 -84.31784)
		(end 91.787218 -83.70824)
		(width 0.254)
		(layer "F.Cu")
		(net "PVCCIN_CPU1")
	)
	(segment
		(start 108.768896 -64.324738)
		(end 108.768896 -64.896238)
		(width 0.254)
		(layer "F.Cu")
		(net "PVCCIN_CPU1")
	)
	(segment
		(start 73.758806 -73.916286)
		(end 73.187306 -73.916286)
		(width 0.254)
		(layer "F.Cu")
		(net "PVCCIN_CPU1")
	)
	(segment
		(start 90.928698 -83.212686)
		(end 90.928698 -83.822286)
		(width 0.254)
		(layer "F.Cu")
		(net "PVCCIN_CPU1")
	)
	(segment
		(start 72.041766 -71.935086)
		(end 71.470266 -71.935086)
		(width 0.254)
		(layer "F.Cu")
		(net "PVCCIN_CPU1")
	)
	(segment
		(start 71.183246 -73.42124)
		(end 70.611746 -73.42124)
		(width 0.254)
		(layer "F.Cu")
		(net "PVCCIN_CPU1")
	)
	(segment
		(start 86.636352 -75.40244)
		(end 86.064852 -75.40244)
		(width 0.254)
		(layer "F.Cu")
		(net "PVCCIN_CPU1")
	)
	(segment
		(start 78.051406 -71.44004)
		(end 77.479906 -71.44004)
		(width 0.254)
		(layer "F.Cu")
		(net "PVCCIN_CPU1")
	)
	(segment
		(start 95.221298 -86.29904)
		(end 95.221298 -85.68944)
		(width 0.254)
		(layer "F.Cu")
		(net "PVCCIN_CPU1")
	)
	(segment
		(start 91.787218 -85.30844)
		(end 91.215718 -85.30844)
		(width 0.254)
		(layer "F.Cu")
		(net "PVCCIN_CPU1")
	)
	(segment
		(start 76.621386 -76.888086)
		(end 77.192886 -76.888086)
		(width 0.254)
		(layer "F.Cu")
		(net "PVCCIN_CPU1")
	)
	(segment
		(start 90.070178 -76.39304)
		(end 90.201496 -76.261722)
		(width 0.254)
		(layer "F.Cu")
		(net "PVCCIN_CPU1")
	)
	(segment
		(start 78.909672 -76.888086)
		(end 78.338172 -76.888086)
		(width 0.254)
		(layer "F.Cu")
		(net "PVCCIN_CPU1")
	)
	(segment
		(start 69.466206 -70.44944)
		(end 68.894706 -70.44944)
		(width 0.254)
		(layer "F.Cu")
		(net "PVCCIN_CPU1")
	)
	(segment
		(start 107.910376 -64.819784)
		(end 107.910376 -65.391284)
		(width 0.254)
		(layer "F.Cu")
		(net "PVCCIN_CPU1")
	)
	(segment
		(start 102.947724 -64.010286)
		(end 102.947724 -64.643)
		(width 0.254)
		(layer "F.Cu")
		(net "PVCCIN_CPU1")
	)
	(segment
		(start 92.645738 -66.982086)
		(end 92.645738 -67.6402)
		(width 0.254)
		(layer "F.Cu")
		(net "PVCCIN_CPU1")
	)
	(segment
		(start 76.334366 -79.36484)
		(end 75.762866 -79.36484)
		(width 0.254)
		(layer "F.Cu")
		(net "PVCCIN_CPU1")
	)
	(segment
		(start 72.900286 -77.38364)
		(end 72.328786 -77.38364)
		(width 0.254)
		(layer "F.Cu")
		(net "PVCCIN_CPU1")
	)
	(segment
		(start 111.344202 -64.819784)
		(end 111.344202 -65.391284)
		(width 0.254)
		(layer "F.Cu")
		(net "PVCCIN_CPU1")
	)
	(segment
		(start 78.051406 -75.40244)
		(end 77.479906 -75.40244)
		(width 0.254)
		(layer "F.Cu")
		(net "PVCCIN_CPU1")
	)
	(segment
		(start 90.070178 -78.37424)
		(end 90.692478 -78.37424)
		(width 0.254)
		(layer "F.Cu")
		(net "PVCCIN_CPU1")
	)
	(segment
		(start 96.938338 -87.28964)
		(end 96.938338 -86.68004)
		(width 0.254)
		(layer "F.Cu")
		(net "PVCCIN_CPU1")
	)
	(segment
		(start 79.768192 -75.40244)
		(end 79.196692 -75.40244)
		(width 0.254)
		(layer "F.Cu")
		(net "PVCCIN_CPU1")
	)
	(segment
		(start 91.787218 -67.47764)
		(end 91.787218 -68.06565)
		(width 0.254)
		(layer "F.Cu")
		(net "PVCCIN_CPU1")
	)
	(segment
		(start 69.339206 -79.23784)
		(end 68.806568 -79.23784)
		(width 0.254)
		(layer "F.Cu")
		(net "PVCCIN_CPU1")
	)
	(segment
		(start 68.607686 -69.953886)
		(end 68.067682 -69.953886)
		(width 0.254)
		(layer "F.Cu")
		(net "PVCCIN_CPU1")
	)
	(segment
		(start 90.201496 -76.261722)
		(end 90.56116 -76.261722)
		(width 0.254)
		(layer "F.Cu")
		(net "PVCCIN_CPU1")
	)
	(segment
		(start 75.475846 -75.897486)
		(end 74.904346 -75.897486)
		(width 0.254)
		(layer "F.Cu")
		(net "PVCCIN_CPU1")
	)
	(segment
		(start 87.494872 -75.897486)
		(end 86.923372 -75.897486)
		(width 0.254)
		(layer "F.Cu")
		(net "PVCCIN_CPU1")
	)
	(segment
		(start 73.758806 -72.925686)
		(end 73.187306 -72.925686)
		(width 0.254)
		(layer "F.Cu")
		(net "PVCCIN_CPU1")
	)
	(segment
		(start 70.324726 -73.916286)
		(end 69.753226 -73.916286)
		(width 0.254)
		(layer "F.Cu")
		(net "PVCCIN_CPU1")
	)
	(segment
		(start 94.362778 -65.000886)
		(end 93.791278 -65.000886)
		(width 0.254)
		(layer "F.Cu")
		(net "PVCCIN_CPU1")
	)
	(segment
		(start 97.796858 -64.010286)
		(end 97.796858 -64.581786)
		(width 0.254)
		(layer "F.Cu")
		(net "PVCCIN_CPU1")
	)
	(segment
		(start 90.070178 -73.42124)
		(end 90.692478 -73.42124)
		(width 0.254)
		(layer "F.Cu")
		(net "PVCCIN_CPU1")
	)
	(segment
		(start 31.645098 -54.644544)
		(end 31.409386 -54.644544)
		(width 0.254)
		(layer "F.Cu")
		(net "PVCCIN_CPU1")
	)
	(segment
		(start 31.409386 -54.644544)
		(end 31.125668 -54.360826)
		(width 0.254)
		(layer "F.Cu")
		(net "PVCCIN_CPU1")
	)
	(segment
		(start 81.485232 -77.38364)
		(end 80.913732 -77.38364)
		(width 0.254)
		(layer "F.Cu")
		(net "PVCCIN_CPU1")
	)
	(segment
		(start 82.343752 -74.906886)
		(end 81.772252 -74.906886)
		(width 0.254)
		(layer "F.Cu")
		(net "PVCCIN_CPU1")
	)
	(segment
		(start 107.051856 -64.324738)
		(end 107.051856 -64.896238)
		(width 0.254)
		(layer "F.Cu")
		(net "PVCCIN_CPU1")
	)
	(segment
		(start 91.787218 -66.48704)
		(end 91.215718 -66.48704)
		(width 0.254)
		(layer "F.Cu")
		(net "PVCCIN_CPU1")
	)
	(segment
		(start 92.645738 -65.991486)
		(end 92.074238 -65.991486)
		(width 0.254)
		(layer "F.Cu")
		(net "PVCCIN_CPU1")
	)
	(segment
		(start 92.645738 -84.812886)
		(end 92.645738 -84.203286)
		(width 0.254)
		(layer "F.Cu")
		(net "PVCCIN_CPU1")
	)
	(segment
		(start 90.928698 -66.982086)
		(end 90.357198 -66.982086)
		(width 0.254)
		(layer "F.Cu")
		(net "PVCCIN_CPU1")
	)
	(segment
		(start 69.466206 -72.43064)
		(end 68.892928 -72.43064)
		(width 0.254)
		(layer "F.Cu")
		(net "PVCCIN_CPU1")
	)
	(segment
		(start 70.324726 -77.878686)
		(end 69.753226 -77.878686)
		(width 0.254)
		(layer "F.Cu")
		(net "PVCCIN_CPU1")
	)
	(segment
		(start 76.621386 -75.897486)
		(end 77.192886 -75.897486)
		(width 0.254)
		(layer "F.Cu")
		(net "PVCCIN_CPU1")
	)
	(segment
		(start 88.353392 -78.37424)
		(end 87.781892 -78.37424)
		(width 0.254)
		(layer "F.Cu")
		(net "PVCCIN_CPU1")
	)
	(segment
		(start 89.211912 -67.972686)
		(end 88.640412 -67.972686)
		(width 0.254)
		(layer "F.Cu")
		(net "PVCCIN_CPU1")
	)
	(segment
		(start 78.051406 -77.38364)
		(end 77.479906 -77.38364)
		(width 0.254)
		(layer "F.Cu")
		(net "PVCCIN_CPU1")
	)
	(segment
		(start 88.353392 -75.40244)
		(end 87.781892 -75.40244)
		(width 0.254)
		(layer "F.Cu")
		(net "PVCCIN_CPU1")
	)
	(segment
		(start 89.211912 -83.822286)
		(end 88.640412 -83.822286)
		(width 0.254)
		(layer "F.Cu")
		(net "PVCCIN_CPU1")
	)
	(segment
		(start 85.777832 -77.878686)
		(end 85.206332 -77.878686)
		(width 0.254)
		(layer "F.Cu")
		(net "PVCCIN_CPU1")
	)
	(segment
		(start 76.334366 -75.40244)
		(end 75.762866 -75.40244)
		(width 0.254)
		(layer "F.Cu")
		(net "PVCCIN_CPU1")
	)
	(segment
		(start 114.778282 -87.603584)
		(end 114.778282 -87.032084)
		(width 0.381)
		(layer "F.Cu")
		(net "PVCCIN_CPU1")
	)
	(segment
		(start 91.787218 -68.06565)
		(end 91.818968 -68.0974)
		(width 0.1016)
		(layer "F.Cu")
		(net "PVCCIN_CPU1")
	)
	(segment
		(start 113.919762 -88.099138)
		(end 113.919762 -87.527638)
		(width 0.381)
		(layer "F.Cu")
		(net "PVCCIN_CPU1")
	)
	(segment
		(start 74.617326 -71.44004)
		(end 74.045826 -71.44004)
		(width 0.254)
		(layer "F.Cu")
		(net "PVCCIN_CPU1")
	)
	(segment
		(start 73.758806 -70.94474)
		(end 73.187306 -70.94474)
		(width 0.254)
		(layer "F.Cu")
		(net "PVCCIN_CPU1")
	)
	(segment
		(start 78.909672 -70.94474)
		(end 78.338172 -70.94474)
		(width 0.254)
		(layer "F.Cu")
		(net "PVCCIN_CPU1")
	)
	(segment
		(start 69.466206 -74.411586)
		(end 68.806568 -74.411586)
		(width 0.254)
		(layer "F.Cu")
		(net "PVCCIN_CPU1")
	)
	(segment
		(start 78.909672 -75.897486)
		(end 78.338172 -75.897486)
		(width 0.254)
		(layer "F.Cu")
		(net "PVCCIN_CPU1")
	)
	(segment
		(start 113.061242 -65.810384)
		(end 113.061242 -66.381884)
		(width 0.254)
		(layer "F.Cu")
		(net "PVCCIN_CPU1")
	)
	(segment
		(start 82.343752 -73.916286)
		(end 81.772252 -73.916286)
		(width 0.254)
		(layer "F.Cu")
		(net "PVCCIN_CPU1")
	)
	(segment
		(start 84.060792 -75.897486)
		(end 83.489292 -75.897486)
		(width 0.254)
		(layer "F.Cu")
		(net "PVCCIN_CPU1")
	)
	(segment
		(start 114.778282 -66.800984)
		(end 114.778282 -67.372484)
		(width 0.254)
		(layer "F.Cu")
		(net "PVCCIN_CPU1")
	)
	(segment
		(start 82.343752 -72.925686)
		(end 81.772252 -72.925686)
		(width 0.254)
		(layer "F.Cu")
		(net "PVCCIN_CPU1")
	)
	(segment
		(start 88.353392 -71.44004)
		(end 87.781892 -71.44004)
		(width 0.254)
		(layer "F.Cu")
		(net "PVCCIN_CPU1")
	)
	(segment
		(start 73.758806 -76.888086)
		(end 73.187306 -76.888086)
		(width 0.254)
		(layer "F.Cu")
		(net "PVCCIN_CPU1")
	)
	(segment
		(start 74.617326 -77.38364)
		(end 74.045826 -77.38364)
		(width 0.254)
		(layer "F.Cu")
		(net "PVCCIN_CPU1")
	)
	(segment
		(start 73.758806 -79.859886)
		(end 73.187306 -79.859886)
		(width 0.254)
		(layer "F.Cu")
		(net "PVCCIN_CPU1")
	)
	(segment
		(start 78.909672 -71.935086)
		(end 78.338172 -71.935086)
		(width 0.254)
		(layer "F.Cu")
		(net "PVCCIN_CPU1")
	)
	(segment
		(start 80.626712 -77.878686)
		(end 80.055212 -77.878686)
		(width 0.254)
		(layer "F.Cu")
		(net "PVCCIN_CPU1")
	)
	(segment
		(start 69.466206 -73.42124)
		(end 68.806568 -73.42124)
		(width 0.254)
		(layer "F.Cu")
		(net "PVCCIN_CPU1")
	)
	(segment
		(start 70.324726 -79.859886)
		(end 69.753226 -79.859886)
		(width 0.254)
		(layer "F.Cu")
		(net "PVCCIN_CPU1")
	)
	(segment
		(start 79.768192 -71.44004)
		(end 79.196692 -71.44004)
		(width 0.254)
		(layer "F.Cu")
		(net "PVCCIN_CPU1")
	)
	(segment
		(start 69.466206 -75.40244)
		(end 68.806568 -75.40244)
		(width 0.254)
		(layer "F.Cu")
		(net "PVCCIN_CPU1")
	)
	(segment
		(start 72.900286 -75.40244)
		(end 72.328786 -75.40244)
		(width 0.254)
		(layer "F.Cu")
		(net "PVCCIN_CPU1")
	)
	(segment
		(start 87.494872 -72.925686)
		(end 86.923372 -72.925686)
		(width 0.254)
		(layer "F.Cu")
		(net "PVCCIN_CPU1")
	)
	(segment
		(start 70.324726 -80.850486)
		(end 69.753226 -80.850486)
		(width 0.254)
		(layer "F.Cu")
		(net "PVCCIN_CPU1")
	)
	(segment
		(start 84.919312 -75.40244)
		(end 84.347812 -75.40244)
		(width 0.254)
		(layer "F.Cu")
		(net "PVCCIN_CPU1")
	)
	(segment
		(start 99.513898 -64.010286)
		(end 99.513898 -64.581786)
		(width 0.254)
		(layer "F.Cu")
		(net "PVCCIN_CPU1")
	)
	(segment
		(start 84.919312 -73.42124)
		(end 84.347812 -73.42124)
		(width 0.254)
		(layer "F.Cu")
		(net "PVCCIN_CPU1")
	)
	(segment
		(start 68.067682 -69.953886)
		(end 67.917568 -70.104)
		(width 0.254)
		(layer "F.Cu")
		(net "PVCCIN_CPU1")
	)
	(segment
		(start 94.362778 -65.991486)
		(end 94.362778 -66.6242)
		(width 0.254)
		(layer "F.Cu")
		(net "PVCCIN_CPU1")
	)
	(segment
		(start 31.301436 -87.048594)
		(end 31.095442 -87.048594)
		(width 0.254)
		(layer "F.Cu")
		(net "PVCCIN_CPU1")
	)
	(segment
		(start 95.221298 -87.28964)
		(end 94.649798 -87.28964)
		(width 0.254)
		(layer "F.Cu")
		(net "PVCCIN_CPU1")
	)
	(segment
		(start 87.494872 -74.906886)
		(end 86.923372 -74.906886)
		(width 0.254)
		(layer "F.Cu")
		(net "PVCCIN_CPU1")
	)
	(segment
		(start 81.485232 -72.43064)
		(end 80.913732 -72.43064)
		(width 0.254)
		(layer "F.Cu")
		(net "PVCCIN_CPU1")
	)
	(segment
		(start 89.211912 -73.916286)
		(end 88.640412 -73.916286)
		(width 0.254)
		(layer "F.Cu")
		(net "PVCCIN_CPU1")
	)
	(segment
		(start 107.051856 -89.089738)
		(end 107.051856 -88.518238)
		(width 0.381)
		(layer "F.Cu")
		(net "PVCCIN_CPU1")
	)
	(segment
		(start 84.060792 -77.878686)
		(end 83.489292 -77.878686)
		(width 0.254)
		(layer "F.Cu")
		(net "PVCCIN_CPU1")
	)
	(segment
		(start 31.645098 -87.156544)
		(end 31.409386 -87.156544)
		(width 0.254)
		(layer "F.Cu")
		(net "PVCCIN_CPU1")
	)
	(segment
		(start 84.060792 -76.888086)
		(end 83.489292 -76.888086)
		(width 0.254)
		(layer "F.Cu")
		(net "PVCCIN_CPU1")
	)
	(segment
		(start 68.607686 -82.83194)
		(end 68.036186 -82.83194)
		(width 0.254)
		(layer "F.Cu")
		(net "PVCCIN_CPU1")
	)
	(segment
		(start 83.202272 -73.42124)
		(end 82.630772 -73.42124)
		(width 0.254)
		(layer "F.Cu")
		(net "PVCCIN_CPU1")
	)
	(segment
		(start 101.230684 -64.010286)
		(end 101.230684 -64.581786)
		(width 0.254)
		(layer "F.Cu")
		(net "PVCCIN_CPU1")
	)
	(segment
		(start 76.621386 -72.925686)
		(end 77.192886 -72.925686)
		(width 0.254)
		(layer "F.Cu")
		(net "PVCCIN_CPU1")
	)
	(segment
		(start 110.485682 -89.089738)
		(end 110.485682 -88.518238)
		(width 0.381)
		(layer "F.Cu")
		(net "PVCCIN_CPU1")
	)
	(segment
		(start 70.324726 -71.935086)
		(end 69.753226 -71.935086)
		(width 0.254)
		(layer "F.Cu")
		(net "PVCCIN_CPU1")
	)
	(segment
		(start 90.070178 -84.31784)
		(end 89.498678 -84.31784)
		(width 0.254)
		(layer "F.Cu")
		(net "PVCCIN_CPU1")
	)
	(segment
		(start 111.344202 -88.594184)
		(end 111.344202 -88.022684)
		(width 0.381)
		(layer "F.Cu")
		(net "PVCCIN_CPU1")
	)
	(segment
		(start 70.324726 -78.869286)
		(end 69.753226 -78.869286)
		(width 0.254)
		(layer "F.Cu")
		(net "PVCCIN_CPU1")
	)
	(segment
		(start 90.070178 -70.44944)
		(end 90.692478 -70.44944)
		(width 0.254)
		(layer "F.Cu")
		(net "PVCCIN_CPU1")
	)
	(segment
		(start 83.202272 -75.40244)
		(end 82.630772 -75.40244)
		(width 0.254)
		(layer "F.Cu")
		(net "PVCCIN_CPU1")
	)
	(segment
		(start 69.466206 -78.37424)
		(end 68.806568 -78.37424)
		(width 0.254)
		(layer "F.Cu")
		(net "PVCCIN_CPU1")
	)
	(segment
		(start 109.627416 -64.819784)
		(end 109.627416 -65.391284)
		(width 0.254)
		(layer "F.Cu")
		(net "PVCCIN_CPU1")
	)
	(segment
		(start 73.758806 -78.869286)
		(end 73.187306 -78.869286)
		(width 0.254)
		(layer "F.Cu")
		(net "PVCCIN_CPU1")
	)
	(segment
		(start 71.183246 -77.38364)
		(end 70.611746 -77.38364)
		(width 0.254)
		(layer "F.Cu")
		(net "PVCCIN_CPU1")
	)
	(segment
		(start 72.900286 -73.42124)
		(end 72.328786 -73.42124)
		(width 0.254)
		(layer "F.Cu")
		(net "PVCCIN_CPU1")
	)
	(segment
		(start 68.607686 -81.841086)
		(end 67.970654 -81.841086)
		(width 0.254)
		(layer "F.Cu")
		(net "PVCCIN_CPU1")
	)
	(segment
		(start 74.617326 -73.42124)
		(end 74.045826 -73.42124)
		(width 0.254)
		(layer "F.Cu")
		(net "PVCCIN_CPU1")
	)
	(segment
		(start 31.281624 -78.900782)
		(end 31.113222 -78.900782)
		(width 0.254)
		(layer "F.Cu")
		(net "PVCCIN_CPU1")
	)
	(segment
		(start 86.636352 -73.42124)
		(end 86.064852 -73.42124)
		(width 0.254)
		(layer "F.Cu")
		(net "PVCCIN_CPU1")
	)
	(via
		(at 46.9392 -76.4794)
		(size 0.5588)
		(drill 0.3048)
		(layers "F.Cu" "B.Cu")
		(net "PVCCIN_CPU1")
	)
	(via
		(at 44.6532 -77.216)
		(size 0.5588)
		(drill 0.3048)
		(layers "F.Cu" "B.Cu")
		(net "PVCCIN_CPU1")
	)
	(via
		(at 47.7012 -77.216)
		(size 0.5588)
		(drill 0.3048)
		(layers "F.Cu" "B.Cu")
		(net "PVCCIN_CPU1")
	)
	(via
		(at 72.328786 -75.40244)
		(size 0.508)
		(drill 0.254)
		(layers "F.Cu" "B.Cu")
		(net "PVCCIN_CPU1")
	)
	(via
		(at 51.015138 -69.832982)
		(size 0.5588)
		(drill 0.3048)
		(layers "F.Cu" "B.Cu")
		(net "PVCCIN_CPU1")
	)
	(via
		(at 96.938338 -86.68004)
		(size 0.508)
		(drill 0.254)
		(layers "F.Cu" "B.Cu")
		(net "PVCCIN_CPU1")
	)
	(via
		(at 89.498678 -84.31784)
		(size 0.508)
		(drill 0.254)
		(layers "F.Cu" "B.Cu")
		(net "PVCCIN_CPU1")
	)
	(via
		(at 45.4152 -75.7936)
		(size 0.5588)
		(drill 0.3048)
		(layers "F.Cu" "B.Cu")
		(net "PVCCIN_CPU1")
	)
	(via
		(at 67.909186 -70.94474)
		(size 0.508)
		(drill 0.254)
		(layers "F.Cu" "B.Cu")
		(net "PVCCIN_CPU1")
	)
	(via
		(at 80.055212 -77.878686)
		(size 0.508)
		(drill 0.254)
		(layers "F.Cu" "B.Cu")
		(net "PVCCIN_CPU1")
	)
	(via
		(at 74.045826 -71.44004)
		(size 0.508)
		(drill 0.254)
		(layers "F.Cu" "B.Cu")
		(net "PVCCIN_CPU1")
	)
	(via
		(at 47.8282 -59.436)
		(size 0.5588)
		(drill 0.3048)
		(layers "F.Cu" "B.Cu")
		(net "PVCCIN_CPU1")
	)
	(via
		(at 77.479906 -77.38364)
		(size 0.508)
		(drill 0.254)
		(layers "F.Cu" "B.Cu")
		(net "PVCCIN_CPU1")
	)
	(via
		(at 101.573076 -78.715616)
		(size 0.5588)
		(drill 0.3048)
		(layers "F.Cu" "B.Cu")
		(net "PVCCIN_CPU1")
	)
	(via
		(at 47.0535 -59.4995)
		(size 0.5588)
		(drill 0.3048)
		(layers "F.Cu" "B.Cu")
		(net "PVCCIN_CPU1")
	)
	(via
		(at 99.744276 -78.715616)
		(size 0.5588)
		(drill 0.3048)
		(layers "F.Cu" "B.Cu")
		(net "PVCCIN_CPU1")
	)
	(via
		(at 93.504258 -67.1322)
		(size 0.508)
		(drill 0.254)
		(layers "F.Cu" "B.Cu")
		(net "PVCCIN_CPU1")
	)
	(via
		(at 73.187306 -71.935086)
		(size 0.508)
		(drill 0.254)
		(layers "F.Cu" "B.Cu")
		(net "PVCCIN_CPU1")
	)
	(via
		(at 110.485682 -88.518238)
		(size 0.508)
		(drill 0.254)
		(layers "F.Cu" "B.Cu")
		(net "PVCCIN_CPU1")
	)
	(via
		(at 83.489292 -72.925686)
		(size 0.508)
		(drill 0.254)
		(layers "F.Cu" "B.Cu")
		(net "PVCCIN_CPU1")
	)
	(via
		(at 51.8668 -64.135)
		(size 0.5588)
		(drill 0.3048)
		(layers "F.Cu" "B.Cu")
		(net "PVCCIN_CPU1")
	)
	(via
		(at 70.611746 -73.42124)
		(size 0.508)
		(drill 0.254)
		(layers "F.Cu" "B.Cu")
		(net "PVCCIN_CPU1")
	)
	(via
		(at 92.645738 -84.203286)
		(size 0.508)
		(drill 0.254)
		(layers "F.Cu" "B.Cu")
		(net "PVCCIN_CPU1")
	)
	(via
		(at 44.0182 -85.598)
		(size 0.5588)
		(drill 0.3048)
		(layers "F.Cu" "B.Cu")
		(net "PVCCIN_CPU1")
	)
	(via
		(at 68.806568 -73.42124)
		(size 0.508)
		(drill 0.254)
		(layers "F.Cu" "B.Cu")
		(net "PVCCIN_CPU1")
	)
	(via
		(at 74.904346 -74.906886)
		(size 0.508)
		(drill 0.254)
		(layers "F.Cu" "B.Cu")
		(net "PVCCIN_CPU1")
	)
	(via
		(at 73.187306 -79.859886)
		(size 0.508)
		(drill 0.254)
		(layers "F.Cu" "B.Cu")
		(net "PVCCIN_CPU1")
	)
	(via
		(at 45.454824 -75.078082)
		(size 0.5588)
		(drill 0.3048)
		(layers "F.Cu" "B.Cu")
		(net "PVCCIN_CPU1")
	)
	(via
		(at 46.1772 -77.216)
		(size 0.5588)
		(drill 0.3048)
		(layers "F.Cu" "B.Cu")
		(net "PVCCIN_CPU1")
	)
	(via
		(at 85.206332 -72.925686)
		(size 0.508)
		(drill 0.254)
		(layers "F.Cu" "B.Cu")
		(net "PVCCIN_CPU1")
	)
	(via
		(at 68.806568 -74.411586)
		(size 0.508)
		(drill 0.254)
		(layers "F.Cu" "B.Cu")
		(net "PVCCIN_CPU1")
	)
	(via
		(at 44.0436 -58.7756)
		(size 0.5588)
		(drill 0.3048)
		(layers "F.Cu" "B.Cu")
		(net "PVCCIN_CPU1")
	)
	(via
		(at 95.221298 -85.68944)
		(size 0.508)
		(drill 0.254)
		(layers "F.Cu" "B.Cu")
		(net "PVCCIN_CPU1")
	)
	(via
		(at 46.9392 -77.216)
		(size 0.5588)
		(drill 0.3048)
		(layers "F.Cu" "B.Cu")
		(net "PVCCIN_CPU1")
	)
	(via
		(at 114.778282 -87.032084)
		(size 0.508)
		(drill 0.254)
		(layers "F.Cu" "B.Cu")
		(net "PVCCIN_CPU1")
	)
	(via
		(at 47.17669 -70.663816)
		(size 0.5588)
		(drill 0.3048)
		(layers "F.Cu" "B.Cu")
		(net "PVCCIN_CPU1")
	)
	(via
		(at 50.351182 -88.494108)
		(size 0.5588)
		(drill 0.3048)
		(layers "F.Cu" "B.Cu")
		(net "PVCCIN_CPU1")
	)
	(via
		(at 59.563254 -68.679568)
		(size 0.5588)
		(drill 0.3048)
		(layers "F.Cu" "B.Cu")
		(net "PVCCIN_CPU1")
	)
	(via
		(at 79.196692 -79.36484)
		(size 0.508)
		(drill 0.254)
		(layers "F.Cu" "B.Cu")
		(net "PVCCIN_CPU1")
	)
	(via
		(at 45.573696 -91.343734)
		(size 0.5588)
		(drill 0.3048)
		(layers "F.Cu" "B.Cu")
		(net "PVCCIN_CPU1")
	)
	(via
		(at 88.640412 -72.925686)
		(size 0.508)
		(drill 0.254)
		(layers "F.Cu" "B.Cu")
		(net "PVCCIN_CPU1")
	)
	(via
		(at 46.347634 -92.273374)
		(size 0.5588)
		(drill 0.3048)
		(layers "F.Cu" "B.Cu")
		(net "PVCCIN_CPU1")
	)
	(via
		(at 71.470266 -71.935086)
		(size 0.508)
		(drill 0.254)
		(layers "F.Cu" "B.Cu")
		(net "PVCCIN_CPU1")
	)
	(via
		(at 44.91609 -69.901816)
		(size 0.5588)
		(drill 0.3048)
		(layers "F.Cu" "B.Cu")
		(net "PVCCIN_CPU1")
	)
	(via
		(at 68.894706 -71.44004)
		(size 0.508)
		(drill 0.254)
		(layers "F.Cu" "B.Cu")
		(net "PVCCIN_CPU1")
	)
	(via
		(at 76.621386 -75.897486)
		(size 0.508)
		(drill 0.254)
		(layers "F.Cu" "B.Cu")
		(net "PVCCIN_CPU1")
	)
	(via
		(at 85.206332 -77.878686)
		(size 0.508)
		(drill 0.254)
		(layers "F.Cu" "B.Cu")
		(net "PVCCIN_CPU1")
	)
	(via
		(at 48.42891 -77.946758)
		(size 0.5588)
		(drill 0.3048)
		(layers "F.Cu" "B.Cu")
		(net "PVCCIN_CPU1")
	)
	(via
		(at 68.894706 -81.34604)
		(size 0.508)
		(drill 0.254)
		(layers "F.Cu" "B.Cu")
		(net "PVCCIN_CPU1")
	)
	(via
		(at 77.479906 -75.40244)
		(size 0.508)
		(drill 0.254)
		(layers "F.Cu" "B.Cu")
		(net "PVCCIN_CPU1")
	)
	(via
		(at 49.589182 -88.494108)
		(size 0.508)
		(drill 0.254)
		(layers "F.Cu" "B.Cu")
		(net "PVCCIN_CPU1")
	)
	(via
		(at 48.715168 -83.246722)
		(size 0.5588)
		(drill 0.3048)
		(layers "F.Cu" "B.Cu")
		(net "PVCCIN_CPU1")
	)
	(via
		(at 69.753226 -70.94474)
		(size 0.508)
		(drill 0.254)
		(layers "F.Cu" "B.Cu")
		(net "PVCCIN_CPU1")
	)
	(via
		(at 52.6288 -63.373)
		(size 0.5588)
		(drill 0.3048)
		(layers "F.Cu" "B.Cu")
		(net "PVCCIN_CPU1")
	)
	(via
		(at 47.185072 -68.59651)
		(size 0.5588)
		(drill 0.3048)
		(layers "F.Cu" "B.Cu")
		(net "PVCCIN_CPU1")
	)
	(via
		(at 76.621386 -70.94474)
		(size 0.508)
		(drill 0.254)
		(layers "F.Cu" "B.Cu")
		(net "PVCCIN_CPU1")
	)
	(via
		(at 79.196692 -71.44004)
		(size 0.508)
		(drill 0.254)
		(layers "F.Cu" "B.Cu")
		(net "PVCCIN_CPU1")
	)
	(via
		(at 99.513898 -64.581786)
		(size 0.508)
		(drill 0.254)
		(layers "F.Cu" "B.Cu")
		(net "PVCCIN_CPU1")
	)
	(via
		(at 51.1048 -64.135)
		(size 0.5588)
		(drill 0.3048)
		(layers "F.Cu" "B.Cu")
		(net "PVCCIN_CPU1")
	)
	(via
		(at 98.933508 -78.71714)
		(size 0.5588)
		(drill 0.3048)
		(layers "F.Cu" "B.Cu")
		(net "PVCCIN_CPU1")
	)
	(via
		(at 49.477168 -83.221322)
		(size 0.5588)
		(drill 0.3048)
		(layers "F.Cu" "B.Cu")
		(net "PVCCIN_CPU1")
	)
	(via
		(at 45.4152 -76.4794)
		(size 0.5588)
		(drill 0.3048)
		(layers "F.Cu" "B.Cu")
		(net "PVCCIN_CPU1")
	)
	(via
		(at 97.915476 -78.715616)
		(size 0.5588)
		(drill 0.3048)
		(layers "F.Cu" "B.Cu")
		(net "PVCCIN_CPU1")
	)
	(via
		(at 72.328786 -77.38364)
		(size 0.508)
		(drill 0.254)
		(layers "F.Cu" "B.Cu")
		(net "PVCCIN_CPU1")
	)
	(via
		(at 47.0662 -86.3346)
		(size 0.5588)
		(drill 0.3048)
		(layers "F.Cu" "B.Cu")
		(net "PVCCIN_CPU1")
	)
	(via
		(at 80.055212 -74.906886)
		(size 0.508)
		(drill 0.254)
		(layers "F.Cu" "B.Cu")
		(net "PVCCIN_CPU1")
	)
	(via
		(at 44.0182 -55.2958)
		(size 0.5588)
		(drill 0.3048)
		(layers "F.Cu" "B.Cu")
		(net "PVCCIN_CPU1")
	)
	(via
		(at 44.15409 -69.901816)
		(size 0.5588)
		(drill 0.3048)
		(layers "F.Cu" "B.Cu")
		(net "PVCCIN_CPU1")
	)
	(via
		(at 102.089204 -87.67064)
		(size 0.508)
		(drill 0.254)
		(layers "F.Cu" "B.Cu")
		(net "PVCCIN_CPU1")
	)
	(via
		(at 113.919762 -87.527638)
		(size 0.508)
		(drill 0.254)
		(layers "F.Cu" "B.Cu")
		(net "PVCCIN_CPU1")
	)
	(via
		(at 103.401876 -78.715616)
		(size 0.5588)
		(drill 0.3048)
		(layers "F.Cu" "B.Cu")
		(net "PVCCIN_CPU1")
	)
	(via
		(at 31.039562 -62.65545)
		(size 0.508)
		(drill 0.254)
		(layers "F.Cu" "B.Cu")
		(net "PVCCIN_CPU1")
	)
	(via
		(at 86.064852 -78.37424)
		(size 0.508)
		(drill 0.254)
		(layers "F.Cu" "B.Cu")
		(net "PVCCIN_CPU1")
	)
	(via
		(at 99.744276 -74.397616)
		(size 0.5588)
		(drill 0.3048)
		(layers "F.Cu" "B.Cu")
		(net "PVCCIN_CPU1")
	)
	(via
		(at 99.513898 -88.165686)
		(size 0.508)
		(drill 0.254)
		(layers "F.Cu" "B.Cu")
		(net "PVCCIN_CPU1")
	)
	(via
		(at 91.350592 -68.523358)
		(size 0.508)
		(drill 0.254)
		(layers "F.Cu" "B.Cu")
		(net "PVCCIN_CPU1")
	)
	(via
		(at 97.796858 -87.175086)
		(size 0.508)
		(drill 0.254)
		(layers "F.Cu" "B.Cu")
		(net "PVCCIN_CPU1")
	)
	(via
		(at 90.692478 -81.34604)
		(size 0.508)
		(drill 0.254)
		(layers "F.Cu" "B.Cu")
		(net "PVCCIN_CPU1")
	)
	(via
		(at 80.055212 -75.897486)
		(size 0.508)
		(drill 0.254)
		(layers "F.Cu" "B.Cu")
		(net "PVCCIN_CPU1")
	)
	(via
		(at 51.098958 -84.766912)
		(size 0.5588)
		(drill 0.3048)
		(layers "F.Cu" "B.Cu")
		(net "PVCCIN_CPU1")
	)
	(via
		(at 68.894706 -82.33664)
		(size 0.508)
		(drill 0.254)
		(layers "F.Cu" "B.Cu")
		(net "PVCCIN_CPU1")
	)
	(via
		(at 73.187306 -76.888086)
		(size 0.508)
		(drill 0.254)
		(layers "F.Cu" "B.Cu")
		(net "PVCCIN_CPU1")
	)
	(via
		(at 87.781892 -70.44944)
		(size 0.508)
		(drill 0.254)
		(layers "F.Cu" "B.Cu")
		(net "PVCCIN_CPU1")
	)
	(via
		(at 86.064852 -75.40244)
		(size 0.508)
		(drill 0.254)
		(layers "F.Cu" "B.Cu")
		(net "PVCCIN_CPU1")
	)
	(via
		(at 87.781892 -77.38364)
		(size 0.508)
		(drill 0.254)
		(layers "F.Cu" "B.Cu")
		(net "PVCCIN_CPU1")
	)
	(via
		(at 86.923372 -77.878686)
		(size 0.508)
		(drill 0.254)
		(layers "F.Cu" "B.Cu")
		(net "PVCCIN_CPU1")
	)
	(via
		(at 86.064852 -77.38364)
		(size 0.508)
		(drill 0.254)
		(layers "F.Cu" "B.Cu")
		(net "PVCCIN_CPU1")
	)
	(via
		(at 76.621386 -79.859886)
		(size 0.508)
		(drill 0.254)
		(layers "F.Cu" "B.Cu")
		(net "PVCCIN_CPU1")
	)
	(via
		(at 47.0662 -85.5726)
		(size 0.5588)
		(drill 0.3048)
		(layers "F.Cu" "B.Cu")
		(net "PVCCIN_CPU1")
	)
	(via
		(at 69.753226 -78.869286)
		(size 0.508)
		(drill 0.254)
		(layers "F.Cu" "B.Cu")
		(net "PVCCIN_CPU1")
	)
	(via
		(at 93.791278 -86.794086)
		(size 0.508)
		(drill 0.254)
		(layers "F.Cu" "B.Cu")
		(net "PVCCIN_CPU1")
	)
	(via
		(at 69.753226 -79.859886)
		(size 0.508)
		(drill 0.254)
		(layers "F.Cu" "B.Cu")
		(net "PVCCIN_CPU1")
	)
	(via
		(at 47.88154 -69.257164)
		(size 0.5588)
		(drill 0.3048)
		(layers "F.Cu" "B.Cu")
		(net "PVCCIN_CPU1")
	)
	(via
		(at 47.7012 -76.4794)
		(size 0.5588)
		(drill 0.3048)
		(layers "F.Cu" "B.Cu")
		(net "PVCCIN_CPU1")
	)
	(via
		(at 81.772252 -74.906886)
		(size 0.508)
		(drill 0.254)
		(layers "F.Cu" "B.Cu")
		(net "PVCCIN_CPU1")
	)
	(via
		(at 73.187306 -78.869286)
		(size 0.508)
		(drill 0.254)
		(layers "F.Cu" "B.Cu")
		(net "PVCCIN_CPU1")
	)
	(via
		(at 84.347812 -78.37424)
		(size 0.508)
		(drill 0.254)
		(layers "F.Cu" "B.Cu")
		(net "PVCCIN_CPU1")
	)
	(via
		(at 88.640412 -70.94474)
		(size 0.508)
		(drill 0.254)
		(layers "F.Cu" "B.Cu")
		(net "PVCCIN_CPU1")
	)
	(via
		(at 83.489292 -74.906886)
		(size 0.508)
		(drill 0.254)
		(layers "F.Cu" "B.Cu")
		(net "PVCCIN_CPU1")
	)
	(via
		(at 73.187306 -73.916286)
		(size 0.508)
		(drill 0.254)
		(layers "F.Cu" "B.Cu")
		(net "PVCCIN_CPU1")
	)
	(via
		(at 90.701368 -68.7578)
		(size 0.508)
		(drill 0.254)
		(layers "F.Cu" "B.Cu")
		(net "PVCCIN_CPU1")
	)
	(via
		(at 90.692478 -70.44944)
		(size 0.508)
		(drill 0.254)
		(layers "F.Cu" "B.Cu")
		(net "PVCCIN_CPU1")
	)
	(via
		(at 44.833032 -58.828686)
		(size 0.5588)
		(drill 0.3048)
		(layers "F.Cu" "B.Cu")
		(net "PVCCIN_CPU1")
	)
	(via
		(at 88.640412 -69.953886)
		(size 0.508)
		(drill 0.254)
		(layers "F.Cu" "B.Cu")
		(net "PVCCIN_CPU1")
	)
	(via
		(at 100.764086 -78.71714)
		(size 0.5588)
		(drill 0.3048)
		(layers "F.Cu" "B.Cu")
		(net "PVCCIN_CPU1")
	)
	(via
		(at 68.806568 -75.40244)
		(size 0.508)
		(drill 0.254)
		(layers "F.Cu" "B.Cu")
		(net "PVCCIN_CPU1")
	)
	(via
		(at 45.585634 -92.273374)
		(size 0.5588)
		(drill 0.3048)
		(layers "F.Cu" "B.Cu")
		(net "PVCCIN_CPU1")
	)
	(via
		(at 89.498678 -67.47764)
		(size 0.508)
		(drill 0.254)
		(layers "F.Cu" "B.Cu")
		(net "PVCCIN_CPU1")
	)
	(via
		(at 83.489292 -76.888086)
		(size 0.508)
		(drill 0.254)
		(layers "F.Cu" "B.Cu")
		(net "PVCCIN_CPU1")
	)
	(via
		(at 95.248476 -78.71714)
		(size 0.5588)
		(drill 0.3048)
		(layers "F.Cu" "B.Cu")
		(net "PVCCIN_CPU1")
	)
	(via
		(at 43.8912 -77.216)
		(size 0.5588)
		(drill 0.3048)
		(layers "F.Cu" "B.Cu")
		(net "PVCCIN_CPU1")
	)
	(via
		(at 112.202722 -65.886838)
		(size 0.508)
		(drill 0.254)
		(layers "F.Cu" "B.Cu")
		(net "PVCCIN_CPU1")
	)
	(via
		(at 81.772252 -72.925686)
		(size 0.508)
		(drill 0.254)
		(layers "F.Cu" "B.Cu")
		(net "PVCCIN_CPU1")
	)
	(via
		(at 88.640412 -67.972686)
		(size 0.508)
		(drill 0.254)
		(layers "F.Cu" "B.Cu")
		(net "PVCCIN_CPU1")
	)
	(via
		(at 50.239168 -83.221322)
		(size 0.5588)
		(drill 0.3048)
		(layers "F.Cu" "B.Cu")
		(net "PVCCIN_CPU1")
	)
	(via
		(at 95.508318 -64.010286)
		(size 0.508)
		(drill 0.254)
		(layers "F.Cu" "B.Cu")
		(net "PVCCIN_CPU1")
	)
	(via
		(at 90.692478 -82.33664)
		(size 0.508)
		(drill 0.254)
		(layers "F.Cu" "B.Cu")
		(net "PVCCIN_CPU1")
	)
	(via
		(at 87.781892 -71.44004)
		(size 0.508)
		(drill 0.254)
		(layers "F.Cu" "B.Cu")
		(net "PVCCIN_CPU1")
	)
	(via
		(at 74.904346 -76.888086)
		(size 0.508)
		(drill 0.254)
		(layers "F.Cu" "B.Cu")
		(net "PVCCIN_CPU1")
	)
	(via
		(at 71.470266 -75.897486)
		(size 0.508)
		(drill 0.254)
		(layers "F.Cu" "B.Cu")
		(net "PVCCIN_CPU1")
	)
	(via
		(at 59.436 -81.5086)
		(size 0.5588)
		(drill 0.3048)
		(layers "F.Cu" "B.Cu")
		(net "PVCCIN_CPU1")
	)
	(via
		(at 90.692478 -69.45884)
		(size 0.508)
		(drill 0.254)
		(layers "F.Cu" "B.Cu")
		(net "PVCCIN_CPU1")
	)
	(via
		(at 88.640412 -83.822286)
		(size 0.508)
		(drill 0.254)
		(layers "F.Cu" "B.Cu")
		(net "PVCCIN_CPU1")
	)
	(via
		(at 47.8282 -85.5726)
		(size 0.5588)
		(drill 0.3048)
		(layers "F.Cu" "B.Cu")
		(net "PVCCIN_CPU1")
	)
	(via
		(at 45.5422 -54.154832)
		(size 0.5588)
		(drill 0.3048)
		(layers "F.Cu" "B.Cu")
		(net "PVCCIN_CPU1")
	)
	(via
		(at 68.806568 -77.38364)
		(size 0.508)
		(drill 0.254)
		(layers "F.Cu" "B.Cu")
		(net "PVCCIN_CPU1")
	)
	(via
		(at 82.630772 -78.37424)
		(size 0.508)
		(drill 0.254)
		(layers "F.Cu" "B.Cu")
		(net "PVCCIN_CPU1")
	)
	(via
		(at 47.7266 -77.9526)
		(size 0.5588)
		(drill 0.3048)
		(layers "F.Cu" "B.Cu")
		(net "PVCCIN_CPU1")
	)
	(via
		(at 70.611746 -79.36484)
		(size 0.508)
		(drill 0.254)
		(layers "F.Cu" "B.Cu")
		(net "PVCCIN_CPU1")
	)
	(via
		(at 108.768896 -88.518238)
		(size 0.508)
		(drill 0.254)
		(layers "F.Cu" "B.Cu")
		(net "PVCCIN_CPU1")
	)
	(via
		(at 50.211736 -78.035658)
		(size 0.5588)
		(drill 0.3048)
		(layers "F.Cu" "B.Cu")
		(net "PVCCIN_CPU1")
	)
	(via
		(at 96.079818 -86.184486)
		(size 0.508)
		(drill 0.254)
		(layers "F.Cu" "B.Cu")
		(net "PVCCIN_CPU1")
	)
	(via
		(at 50.348642 -86.97722)
		(size 0.5588)
		(drill 0.3048)
		(layers "F.Cu" "B.Cu")
		(net "PVCCIN_CPU1")
	)
	(via
		(at 31.113222 -78.900782)
		(size 0.508)
		(drill 0.254)
		(layers "F.Cu" "B.Cu")
		(net "PVCCIN_CPU1")
	)
	(via
		(at 111.344202 -88.022684)
		(size 0.508)
		(drill 0.254)
		(layers "F.Cu" "B.Cu")
		(net "PVCCIN_CPU1")
	)
	(via
		(at 84.347812 -72.43064)
		(size 0.508)
		(drill 0.254)
		(layers "F.Cu" "B.Cu")
		(net "PVCCIN_CPU1")
	)
	(via
		(at 47.17669 -70.003416)
		(size 0.5588)
		(drill 0.3048)
		(layers "F.Cu" "B.Cu")
		(net "PVCCIN_CPU1")
	)
	(via
		(at 93.504258 -84.69884)
		(size 0.508)
		(drill 0.254)
		(layers "F.Cu" "B.Cu")
		(net "PVCCIN_CPU1")
	)
	(via
		(at 85.206332 -75.897486)
		(size 0.508)
		(drill 0.254)
		(layers "F.Cu" "B.Cu")
		(net "PVCCIN_CPU1")
	)
	(via
		(at 45.5676 -59.5122)
		(size 0.5588)
		(drill 0.3048)
		(layers "F.Cu" "B.Cu")
		(net "PVCCIN_CPU1")
	)
	(via
		(at 47.0535 -60.9219)
		(size 0.5588)
		(drill 0.3048)
		(layers "F.Cu" "B.Cu")
		(net "PVCCIN_CPU1")
	)
	(via
		(at 47.0535 -60.1853)
		(size 0.5588)
		(drill 0.3048)
		(layers "F.Cu" "B.Cu")
		(net "PVCCIN_CPU1")
	)
	(via
		(at 68.894706 -70.44944)
		(size 0.508)
		(drill 0.254)
		(layers "F.Cu" "B.Cu")
		(net "PVCCIN_CPU1")
	)
	(via
		(at 51.06543 -87.744046)
		(size 0.5588)
		(drill 0.3048)
		(layers "F.Cu" "B.Cu")
		(net "PVCCIN_CPU1")
	)
	(via
		(at 47.15002 -84.816442)
		(size 0.5588)
		(drill 0.3048)
		(layers "F.Cu" "B.Cu")
		(net "PVCCIN_CPU1")
	)
	(via
		(at 47.7012 -75.7936)
		(size 0.5588)
		(drill 0.3048)
		(layers "F.Cu" "B.Cu")
		(net "PVCCIN_CPU1")
	)
	(via
		(at 56.99506 -65.76568)
		(size 0.5588)
		(drill 0.3048)
		(layers "F.Cu" "B.Cu")
		(net "PVCCIN_CPU1")
	)
	(via
		(at 48.40478 -78.622906)
		(size 0.5588)
		(drill 0.3048)
		(layers "F.Cu" "B.Cu")
		(net "PVCCIN_CPU1")
	)
	(via
		(at 78.338172 -75.897486)
		(size 0.508)
		(drill 0.254)
		(layers "F.Cu" "B.Cu")
		(net "PVCCIN_CPU1")
	)
	(via
		(at 78.338172 -74.906886)
		(size 0.508)
		(drill 0.254)
		(layers "F.Cu" "B.Cu")
		(net "PVCCIN_CPU1")
	)
	(via
		(at 44.0182 -53.8226)
		(size 0.5588)
		(drill 0.3048)
		(layers "F.Cu" "B.Cu")
		(net "PVCCIN_CPU1")
	)
	(via
		(at 74.045826 -75.40244)
		(size 0.508)
		(drill 0.254)
		(layers "F.Cu" "B.Cu")
		(net "PVCCIN_CPU1")
	)
	(via
		(at 74.904346 -79.859886)
		(size 0.508)
		(drill 0.254)
		(layers "F.Cu" "B.Cu")
		(net "PVCCIN_CPU1")
	)
	(via
		(at 92.074238 -85.803486)
		(size 0.508)
		(drill 0.254)
		(layers "F.Cu" "B.Cu")
		(net "PVCCIN_CPU1")
	)
	(via
		(at 115.636802 -67.868038)
		(size 0.508)
		(drill 0.254)
		(layers "F.Cu" "B.Cu")
		(net "PVCCIN_CPU1")
	)
	(via
		(at 90.692478 -75.40244)
		(size 0.508)
		(drill 0.254)
		(layers "F.Cu" "B.Cu")
		(net "PVCCIN_CPU1")
	)
	(via
		(at 90.692478 -73.42124)
		(size 0.508)
		(drill 0.254)
		(layers "F.Cu" "B.Cu")
		(net "PVCCIN_CPU1")
	)
	(via
		(at 88.640412 -79.859886)
		(size 0.508)
		(drill 0.254)
		(layers "F.Cu" "B.Cu")
		(net "PVCCIN_CPU1")
	)
	(via
		(at 51.83124 -87.763858)
		(size 0.5588)
		(drill 0.3048)
		(layers "F.Cu" "B.Cu")
		(net "PVCCIN_CPU1")
	)
	(via
		(at 44.6532 -75.057)
		(size 0.5588)
		(drill 0.3048)
		(layers "F.Cu" "B.Cu")
		(net "PVCCIN_CPU1")
	)
	(via
		(at 49.589182 -87.732108)
		(size 0.5588)
		(drill 0.3048)
		(layers "F.Cu" "B.Cu")
		(net "PVCCIN_CPU1")
	)
	(via
		(at 74.904346 -75.897486)
		(size 0.508)
		(drill 0.254)
		(layers "F.Cu" "B.Cu")
		(net "PVCCIN_CPU1")
	)
	(via
		(at 50.322226 -86.28634)
		(size 0.5588)
		(drill 0.3048)
		(layers "F.Cu" "B.Cu")
		(net "PVCCIN_CPU1")
	)
	(via
		(at 94.362778 -85.193886)
		(size 0.508)
		(drill 0.254)
		(layers "F.Cu" "B.Cu")
		(net "PVCCIN_CPU1")
	)
	(via
		(at 44.0436 -60.9346)
		(size 0.5588)
		(drill 0.3048)
		(layers "F.Cu" "B.Cu")
		(net "PVCCIN_CPU1")
	)
	(via
		(at 51.83124 -87.001858)
		(size 0.5588)
		(drill 0.3048)
		(layers "F.Cu" "B.Cu")
		(net "PVCCIN_CPU1")
	)
	(via
		(at 44.0182 -54.5592)
		(size 0.5588)
		(drill 0.3048)
		(layers "F.Cu" "B.Cu")
		(net "PVCCIN_CPU1")
	)
	(via
		(at 46.335696 -91.343734)
		(size 0.5588)
		(drill 0.3048)
		(layers "F.Cu" "B.Cu")
		(net "PVCCIN_CPU1")
	)
	(via
		(at 87.781892 -74.411586)
		(size 0.508)
		(drill 0.254)
		(layers "F.Cu" "B.Cu")
		(net "PVCCIN_CPU1")
	)
	(via
		(at 88.640412 -74.906886)
		(size 0.508)
		(drill 0.254)
		(layers "F.Cu" "B.Cu")
		(net "PVCCIN_CPU1")
	)
	(via
		(at 72.328786 -73.42124)
		(size 0.508)
		(drill 0.254)
		(layers "F.Cu" "B.Cu")
		(net "PVCCIN_CPU1")
	)
	(via
		(at 76.621386 -74.906886)
		(size 0.508)
		(drill 0.254)
		(layers "F.Cu" "B.Cu")
		(net "PVCCIN_CPU1")
	)
	(via
		(at 73.187306 -72.925686)
		(size 0.508)
		(drill 0.254)
		(layers "F.Cu" "B.Cu")
		(net "PVCCIN_CPU1")
	)
	(via
		(at 51.802538 -71.356982)
		(size 0.508)
		(drill 0.254)
		(layers "F.Cu" "B.Cu")
		(net "PVCCIN_CPU1")
	)
	(via
		(at 52.6288 -64.135)
		(size 0.5588)
		(drill 0.3048)
		(layers "F.Cu" "B.Cu")
		(net "PVCCIN_CPU1")
	)
	(via
		(at 112.27308 -86.16188)
		(size 0.508)
		(drill 0.254)
		(layers "F.Cu" "B.Cu")
		(net "PVCCIN_CPU1")
	)
	(via
		(at 82.630772 -73.42124)
		(size 0.508)
		(drill 0.254)
		(layers "F.Cu" "B.Cu")
		(net "PVCCIN_CPU1")
	)
	(via
		(at 80.913732 -72.43064)
		(size 0.508)
		(drill 0.254)
		(layers "F.Cu" "B.Cu")
		(net "PVCCIN_CPU1")
	)
	(via
		(at 80.913732 -75.40244)
		(size 0.508)
		(drill 0.254)
		(layers "F.Cu" "B.Cu")
		(net "PVCCIN_CPU1")
	)
	(via
		(at 44.0182 -86.3346)
		(size 0.5588)
		(drill 0.3048)
		(layers "F.Cu" "B.Cu")
		(net "PVCCIN_CPU1")
	)
	(via
		(at 49.589182 -89.256108)
		(size 0.5588)
		(drill 0.3048)
		(layers "F.Cu" "B.Cu")
		(net "PVCCIN_CPU1")
	)
	(via
		(at 48.4632 -75.057)
		(size 0.5588)
		(drill 0.3048)
		(layers "F.Cu" "B.Cu")
		(net "PVCCIN_CPU1")
	)
	(via
		(at 87.781892 -75.40244)
		(size 0.508)
		(drill 0.254)
		(layers "F.Cu" "B.Cu")
		(net "PVCCIN_CPU1")
	)
	(via
		(at 83.489292 -75.897486)
		(size 0.508)
		(drill 0.254)
		(layers "F.Cu" "B.Cu")
		(net "PVCCIN_CPU1")
	)
	(via
		(at 97.796858 -64.581786)
		(size 0.508)
		(drill 0.254)
		(layers "F.Cu" "B.Cu")
		(net "PVCCIN_CPU1")
	)
	(via
		(at 51.777138 -69.832982)
		(size 0.5588)
		(drill 0.3048)
		(layers "F.Cu" "B.Cu")
		(net "PVCCIN_CPU1")
	)
	(via
		(at 47.181516 -69.263006)
		(size 0.5588)
		(drill 0.3048)
		(layers "F.Cu" "B.Cu")
		(net "PVCCIN_CPU1")
	)
	(via
		(at 46.1772 -75.7936)
		(size 0.5588)
		(drill 0.3048)
		(layers "F.Cu" "B.Cu")
		(net "PVCCIN_CPU1")
	)
	(via
		(at 85.206332 -74.906886)
		(size 0.508)
		(drill 0.254)
		(layers "F.Cu" "B.Cu")
		(net "PVCCIN_CPU1")
	)
	(via
		(at 74.045826 -73.42124)
		(size 0.508)
		(drill 0.254)
		(layers "F.Cu" "B.Cu")
		(net "PVCCIN_CPU1")
	)
	(via
		(at 49.6062 -58.2295)
		(size 0.5588)
		(drill 0.3048)
		(layers "F.Cu" "B.Cu")
		(net "PVCCIN_CPU1")
	)
	(via
		(at 88.640412 -77.878686)
		(size 0.508)
		(drill 0.254)
		(layers "F.Cu" "B.Cu")
		(net "PVCCIN_CPU1")
	)
	(via
		(at 81.772252 -76.888086)
		(size 0.508)
		(drill 0.254)
		(layers "F.Cu" "B.Cu")
		(net "PVCCIN_CPU1")
	)
	(via
		(at 83.489292 -73.916286)
		(size 0.508)
		(drill 0.254)
		(layers "F.Cu" "B.Cu")
		(net "PVCCIN_CPU1")
	)
	(via
		(at 88.640412 -80.850486)
		(size 0.508)
		(drill 0.254)
		(layers "F.Cu" "B.Cu")
		(net "PVCCIN_CPU1")
	)
	(via
		(at 47.097696 -91.343734)
		(size 0.5588)
		(drill 0.3048)
		(layers "F.Cu" "B.Cu")
		(net "PVCCIN_CPU1")
	)
	(via
		(at 47.871634 -92.273374)
		(size 0.5588)
		(drill 0.3048)
		(layers "F.Cu" "B.Cu")
		(net "PVCCIN_CPU1")
	)
	(via
		(at 72.328786 -71.44004)
		(size 0.508)
		(drill 0.254)
		(layers "F.Cu" "B.Cu")
		(net "PVCCIN_CPU1")
	)
	(via
		(at 79.196692 -77.38364)
		(size 0.508)
		(drill 0.254)
		(layers "F.Cu" "B.Cu")
		(net "PVCCIN_CPU1")
	)
	(via
		(at 92.074238 -65.991486)
		(size 0.508)
		(drill 0.254)
		(layers "F.Cu" "B.Cu")
		(net "PVCCIN_CPU1")
	)
	(via
		(at 97.18675 -74.474578)
		(size 0.5588)
		(drill 0.3048)
		(layers "F.Cu" "B.Cu")
		(net "PVCCIN_CPU1")
	)
	(via
		(at 76.621386 -73.916286)
		(size 0.508)
		(drill 0.254)
		(layers "F.Cu" "B.Cu")
		(net "PVCCIN_CPU1")
	)
	(via
		(at 90.692478 -76.39304)
		(size 0.508)
		(drill 0.254)
		(layers "F.Cu" "B.Cu")
		(net "PVCCIN_CPU1")
	)
	(via
		(at 60.903612 -69.717412)
		(size 0.508)
		(drill 0.254)
		(layers "F.Cu" "B.Cu")
		(net "PVCCIN_CPU1")
	)
	(via
		(at 90.692478 -72.43064)
		(size 0.508)
		(drill 0.254)
		(layers "F.Cu" "B.Cu")
		(net "PVCCIN_CPU1")
	)
	(via
		(at 90.692478 -80.35544)
		(size 0.508)
		(drill 0.254)
		(layers "F.Cu" "B.Cu")
		(net "PVCCIN_CPU1")
	)
	(via
		(at 80.913732 -77.38364)
		(size 0.508)
		(drill 0.254)
		(layers "F.Cu" "B.Cu")
		(net "PVCCIN_CPU1")
	)
	(via
		(at 102.089204 -65.151)
		(size 0.508)
		(drill 0.254)
		(layers "F.Cu" "B.Cu")
		(net "PVCCIN_CPU1")
	)
	(via
		(at 44.811696 -91.343734)
		(size 0.5588)
		(drill 0.3048)
		(layers "F.Cu" "B.Cu")
		(net "PVCCIN_CPU1")
	)
	(via
		(at 50.338228 -71.37273)
		(size 0.5588)
		(drill 0.3048)
		(layers "F.Cu" "B.Cu")
		(net "PVCCIN_CPU1")
	)
	(via
		(at 51.8668 -63.373)
		(size 0.5588)
		(drill 0.3048)
		(layers "F.Cu" "B.Cu")
		(net "PVCCIN_CPU1")
	)
	(via
		(at 75.762866 -75.40244)
		(size 0.508)
		(drill 0.254)
		(layers "F.Cu" "B.Cu")
		(net "PVCCIN_CPU1")
	)
	(via
		(at 71.470266 -76.888086)
		(size 0.508)
		(drill 0.254)
		(layers "F.Cu" "B.Cu")
		(net "PVCCIN_CPU1")
	)
	(via
		(at 97.154238 -78.71714)
		(size 0.5588)
		(drill 0.3048)
		(layers "F.Cu" "B.Cu")
		(net "PVCCIN_CPU1")
	)
	(via
		(at 107.051856 -64.896238)
		(size 0.508)
		(drill 0.254)
		(layers "F.Cu" "B.Cu")
		(net "PVCCIN_CPU1")
	)
	(via
		(at 68.806568 -76.39304)
		(size 0.508)
		(drill 0.254)
		(layers "F.Cu" "B.Cu")
		(net "PVCCIN_CPU1")
	)
	(via
		(at 78.338172 -79.859886)
		(size 0.508)
		(drill 0.254)
		(layers "F.Cu" "B.Cu")
		(net "PVCCIN_CPU1")
	)
	(via
		(at 44.823634 -92.273374)
		(size 0.5588)
		(drill 0.3048)
		(layers "F.Cu" "B.Cu")
		(net "PVCCIN_CPU1")
	)
	(via
		(at 47.8282 -87.210392)
		(size 0.5588)
		(drill 0.3048)
		(layers "F.Cu" "B.Cu")
		(net "PVCCIN_CPU1")
	)
	(via
		(at 102.947724 -64.643)
		(size 0.508)
		(drill 0.254)
		(layers "F.Cu" "B.Cu")
		(net "PVCCIN_CPU1")
	)
	(via
		(at 75.762866 -79.36484)
		(size 0.508)
		(drill 0.254)
		(layers "F.Cu" "B.Cu")
		(net "PVCCIN_CPU1")
	)
	(via
		(at 91.215718 -85.30844)
		(size 0.508)
		(drill 0.254)
		(layers "F.Cu" "B.Cu")
		(net "PVCCIN_CPU1")
	)
	(via
		(at 47.9044 -70.6882)
		(size 0.5588)
		(drill 0.3048)
		(layers "F.Cu" "B.Cu")
		(net "PVCCIN_CPU1")
	)
	(via
		(at 90.357198 -66.982086)
		(size 0.508)
		(drill 0.254)
		(layers "F.Cu" "B.Cu")
		(net "PVCCIN_CPU1")
	)
	(via
		(at 70.611746 -77.38364)
		(size 0.508)
		(drill 0.254)
		(layers "F.Cu" "B.Cu")
		(net "PVCCIN_CPU1")
	)
	(via
		(at 113.061242 -66.381884)
		(size 0.508)
		(drill 0.254)
		(layers "F.Cu" "B.Cu")
		(net "PVCCIN_CPU1")
	)
	(via
		(at 76.621386 -72.925686)
		(size 0.508)
		(drill 0.254)
		(layers "F.Cu" "B.Cu")
		(net "PVCCIN_CPU1")
	)
	(via
		(at 47.918116 -83.305142)
		(size 0.5588)
		(drill 0.3048)
		(layers "F.Cu" "B.Cu")
		(net "PVCCIN_CPU1")
	)
	(via
		(at 51.098958 -85.528912)
		(size 0.5588)
		(drill 0.3048)
		(layers "F.Cu" "B.Cu")
		(net "PVCCIN_CPU1")
	)
	(via
		(at 69.753226 -76.888086)
		(size 0.508)
		(drill 0.254)
		(layers "F.Cu" "B.Cu")
		(net "PVCCIN_CPU1")
	)
	(via
		(at 94.294198 -78.700884)
		(size 0.5588)
		(drill 0.3048)
		(layers "F.Cu" "B.Cu")
		(net "PVCCIN_CPU1")
	)
	(via
		(at 74.904346 -73.916286)
		(size 0.508)
		(drill 0.254)
		(layers "F.Cu" "B.Cu")
		(net "PVCCIN_CPU1")
	)
	(via
		(at 69.753226 -74.906886)
		(size 0.508)
		(drill 0.254)
		(layers "F.Cu" "B.Cu")
		(net "PVCCIN_CPU1")
	)
	(via
		(at 78.338172 -78.869286)
		(size 0.508)
		(drill 0.254)
		(layers "F.Cu" "B.Cu")
		(net "PVCCIN_CPU1")
	)
	(via
		(at 51.0794 -62.611)
		(size 0.5588)
		(drill 0.3048)
		(layers "F.Cu" "B.Cu")
		(net "PVCCIN_CPU1")
	)
	(via
		(at 46.3296 -59.5122)
		(size 0.5588)
		(drill 0.3048)
		(layers "F.Cu" "B.Cu")
		(net "PVCCIN_CPU1")
	)
	(via
		(at 48.5902 -86.3092)
		(size 0.5588)
		(drill 0.3048)
		(layers "F.Cu" "B.Cu")
		(net "PVCCIN_CPU1")
	)
	(via
		(at 44.6532 -75.7936)
		(size 0.5588)
		(drill 0.3048)
		(layers "F.Cu" "B.Cu")
		(net "PVCCIN_CPU1")
	)
	(via
		(at 50.351182 -89.256108)
		(size 0.5588)
		(drill 0.3048)
		(layers "F.Cu" "B.Cu")
		(net "PVCCIN_CPU1")
	)
	(via
		(at 68.806568 -79.23784)
		(size 0.508)
		(drill 0.254)
		(layers "F.Cu" "B.Cu")
		(net "PVCCIN_CPU1")
	)
	(via
		(at 47.91202 -84.816442)
		(size 0.5588)
		(drill 0.3048)
		(layers "F.Cu" "B.Cu")
		(net "PVCCIN_CPU1")
	)
	(via
		(at 50.3428 -64.135)
		(size 0.5588)
		(drill 0.3048)
		(layers "F.Cu" "B.Cu")
		(net "PVCCIN_CPU1")
	)
	(via
		(at 82.630772 -72.43064)
		(size 0.508)
		(drill 0.254)
		(layers "F.Cu" "B.Cu")
		(net "PVCCIN_CPU1")
	)
	(via
		(at 45.5676 -60.198)
		(size 0.5588)
		(drill 0.3048)
		(layers "F.Cu" "B.Cu")
		(net "PVCCIN_CPU1")
	)
	(via
		(at 88.640412 -75.897486)
		(size 0.508)
		(drill 0.254)
		(layers "F.Cu" "B.Cu")
		(net "PVCCIN_CPU1")
	)
	(via
		(at 68.036186 -82.83194)
		(size 0.508)
		(drill 0.254)
		(layers "F.Cu" "B.Cu")
		(net "PVCCIN_CPU1")
	)
	(via
		(at 85.206332 -73.916286)
		(size 0.508)
		(drill 0.254)
		(layers "F.Cu" "B.Cu")
		(net "PVCCIN_CPU1")
	)
	(via
		(at 98.655378 -65.151)
		(size 0.508)
		(drill 0.254)
		(layers "F.Cu" "B.Cu")
		(net "PVCCIN_CPU1")
	)
	(via
		(at 114.778282 -67.372484)
		(size 0.508)
		(drill 0.254)
		(layers "F.Cu" "B.Cu")
		(net "PVCCIN_CPU1")
	)
	(via
		(at 45.4152 -77.216)
		(size 0.5588)
		(drill 0.3048)
		(layers "F.Cu" "B.Cu")
		(net "PVCCIN_CPU1")
	)
	(via
		(at 98.655378 -87.67064)
		(size 0.508)
		(drill 0.254)
		(layers "F.Cu" "B.Cu")
		(net "PVCCIN_CPU1")
	)
	(via
		(at 88.640412 -82.83194)
		(size 0.508)
		(drill 0.254)
		(layers "F.Cu" "B.Cu")
		(net "PVCCIN_CPU1")
	)
	(via
		(at 102.683564 -74.42962)
		(size 0.5588)
		(drill 0.3048)
		(layers "F.Cu" "B.Cu")
		(net "PVCCIN_CPU1")
	)
	(via
		(at 96.086676 -74.397616)
		(size 0.5588)
		(drill 0.3048)
		(layers "F.Cu" "B.Cu")
		(net "PVCCIN_CPU1")
	)
	(via
		(at 110.827566 -67.265804)
		(size 0.5588)
		(drill 0.3048)
		(layers "F.Cu" "B.Cu")
		(net "PVCCIN_CPU1")
	)
	(via
		(at 71.470266 -72.925686)
		(size 0.508)
		(drill 0.254)
		(layers "F.Cu" "B.Cu")
		(net "PVCCIN_CPU1")
	)
	(via
		(at 81.772252 -73.916286)
		(size 0.508)
		(drill 0.254)
		(layers "F.Cu" "B.Cu")
		(net "PVCCIN_CPU1")
	)
	(via
		(at 47.88789 -70.003416)
		(size 0.5588)
		(drill 0.3048)
		(layers "F.Cu" "B.Cu")
		(net "PVCCIN_CPU1")
	)
	(via
		(at 46.46549 -70.663816)
		(size 0.5588)
		(drill 0.3048)
		(layers "F.Cu" "B.Cu")
		(net "PVCCIN_CPU1")
	)
	(via
		(at 74.045826 -77.38364)
		(size 0.508)
		(drill 0.254)
		(layers "F.Cu" "B.Cu")
		(net "PVCCIN_CPU1")
	)
	(via
		(at 43.8912 -75.7936)
		(size 0.5588)
		(drill 0.3048)
		(layers "F.Cu" "B.Cu")
		(net "PVCCIN_CPU1")
	)
	(via
		(at 78.338172 -70.94474)
		(size 0.508)
		(drill 0.254)
		(layers "F.Cu" "B.Cu")
		(net "PVCCIN_CPU1")
	)
	(via
		(at 44.7802 -85.598)
		(size 0.5588)
		(drill 0.3048)
		(layers "F.Cu" "B.Cu")
		(net "PVCCIN_CPU1")
	)
	(via
		(at 86.923372 -72.925686)
		(size 0.508)
		(drill 0.254)
		(layers "F.Cu" "B.Cu")
		(net "PVCCIN_CPU1")
	)
	(via
		(at 69.753226 -77.878686)
		(size 0.508)
		(drill 0.254)
		(layers "F.Cu" "B.Cu")
		(net "PVCCIN_CPU1")
	)
	(via
		(at 78.338172 -77.878686)
		(size 0.508)
		(drill 0.254)
		(layers "F.Cu" "B.Cu")
		(net "PVCCIN_CPU1")
	)
	(via
		(at 47.8282 -86.3346)
		(size 0.5588)
		(drill 0.3048)
		(layers "F.Cu" "B.Cu")
		(net "PVCCIN_CPU1")
	)
	(via
		(at 81.772252 -75.897486)
		(size 0.508)
		(drill 0.254)
		(layers "F.Cu" "B.Cu")
		(net "PVCCIN_CPU1")
	)
	(via
		(at 49.5554 -64.008)
		(size 0.5588)
		(drill 0.3048)
		(layers "F.Cu" "B.Cu")
		(net "PVCCIN_CPU1")
	)
	(via
		(at 101.573076 -74.397616)
		(size 0.5588)
		(drill 0.3048)
		(layers "F.Cu" "B.Cu")
		(net "PVCCIN_CPU1")
	)
	(via
		(at 84.347812 -73.42124)
		(size 0.508)
		(drill 0.254)
		(layers "F.Cu" "B.Cu")
		(net "PVCCIN_CPU1")
	)
	(via
		(at 52.5272 -62.611)
		(size 0.508)
		(drill 0.254)
		(layers "F.Cu" "B.Cu")
		(net "PVCCIN_CPU1")
	)
	(via
		(at 82.630772 -77.38364)
		(size 0.508)
		(drill 0.254)
		(layers "F.Cu" "B.Cu")
		(net "PVCCIN_CPU1")
	)
	(via
		(at 86.064852 -73.42124)
		(size 0.508)
		(drill 0.254)
		(layers "F.Cu" "B.Cu")
		(net "PVCCIN_CPU1")
	)
	(via
		(at 50.3428 -63.373)
		(size 0.5588)
		(drill 0.3048)
		(layers "F.Cu" "B.Cu")
		(net "PVCCIN_CPU1")
	)
	(via
		(at 71.470266 -70.94474)
		(size 0.508)
		(drill 0.254)
		(layers "F.Cu" "B.Cu")
		(net "PVCCIN_CPU1")
	)
	(via
		(at 49.2252 -75.057)
		(size 0.5588)
		(drill 0.3048)
		(layers "F.Cu" "B.Cu")
		(net "PVCCIN_CPU1")
	)
	(via
		(at 71.470266 -79.859886)
		(size 0.508)
		(drill 0.254)
		(layers "F.Cu" "B.Cu")
		(net "PVCCIN_CPU1")
	)
	(via
		(at 106.193336 -64.400684)
		(size 0.508)
		(drill 0.254)
		(layers "F.Cu" "B.Cu")
		(net "PVCCIN_CPU1")
	)
	(via
		(at 87.781892 -80.35544)
		(size 0.508)
		(drill 0.254)
		(layers "F.Cu" "B.Cu")
		(net "PVCCIN_CPU1")
	)
	(via
		(at 47.918116 -84.067142)
		(size 0.5588)
		(drill 0.3048)
		(layers "F.Cu" "B.Cu")
		(net "PVCCIN_CPU1")
	)
	(via
		(at 74.904346 -71.935086)
		(size 0.508)
		(drill 0.254)
		(layers "F.Cu" "B.Cu")
		(net "PVCCIN_CPU1")
	)
	(via
		(at 93.450156 -78.71714)
		(size 0.5588)
		(drill 0.3048)
		(layers "F.Cu" "B.Cu")
		(net "PVCCIN_CPU1")
	)
	(via
		(at 58.1914 -82.7786)
		(size 0.5588)
		(drill 0.3048)
		(layers "F.Cu" "B.Cu")
		(net "PVCCIN_CPU1")
	)
	(via
		(at 85.206332 -76.888086)
		(size 0.508)
		(drill 0.254)
		(layers "F.Cu" "B.Cu")
		(net "PVCCIN_CPU1")
	)
	(via
		(at 96.079818 -65.6336)
		(size 0.508)
		(drill 0.254)
		(layers "F.Cu" "B.Cu")
		(net "PVCCIN_CPU1")
	)
	(via
		(at 109.627416 -88.022684)
		(size 0.508)
		(drill 0.254)
		(layers "F.Cu" "B.Cu")
		(net "PVCCIN_CPU1")
	)
	(via
		(at 51.06543 -88.506046)
		(size 0.5588)
		(drill 0.3048)
		(layers "F.Cu" "B.Cu")
		(net "PVCCIN_CPU1")
	)
	(via
		(at 109.627416 -65.391284)
		(size 0.508)
		(drill 0.254)
		(layers "F.Cu" "B.Cu")
		(net "PVCCIN_CPU1")
	)
	(via
		(at 90.692478 -77.38364)
		(size 0.508)
		(drill 0.254)
		(layers "F.Cu" "B.Cu")
		(net "PVCCIN_CPU1")
	)
	(via
		(at 113.919762 -66.877438)
		(size 0.508)
		(drill 0.254)
		(layers "F.Cu" "B.Cu")
		(net "PVCCIN_CPU1")
	)
	(via
		(at 78.338172 -73.916286)
		(size 0.508)
		(drill 0.254)
		(layers "F.Cu" "B.Cu")
		(net "PVCCIN_CPU1")
	)
	(via
		(at 58.6232 -67.3608)
		(size 0.5588)
		(drill 0.3048)
		(layers "F.Cu" "B.Cu")
		(net "PVCCIN_CPU1")
	)
	(via
		(at 31.125668 -54.360826)
		(size 0.508)
		(drill 0.254)
		(layers "F.Cu" "B.Cu")
		(net "PVCCIN_CPU1")
	)
	(via
		(at 71.470266 -73.916286)
		(size 0.508)
		(drill 0.254)
		(layers "F.Cu" "B.Cu")
		(net "PVCCIN_CPU1")
	)
	(via
		(at 43.8912 -75.057)
		(size 0.5588)
		(drill 0.3048)
		(layers "F.Cu" "B.Cu")
		(net "PVCCIN_CPU1")
	)
	(via
		(at 50.863754 -77.863192)
		(size 0.5588)
		(drill 0.3048)
		(layers "F.Cu" "B.Cu")
		(net "PVCCIN_CPU1")
	)
	(via
		(at 71.470266 -77.878686)
		(size 0.508)
		(drill 0.254)
		(layers "F.Cu" "B.Cu")
		(net "PVCCIN_CPU1")
	)
	(via
		(at 90.692478 -71.44004)
		(size 0.508)
		(drill 0.254)
		(layers "F.Cu" "B.Cu")
		(net "PVCCIN_CPU1")
	)
	(via
		(at 51.095402 -86.988904)
		(size 0.5588)
		(drill 0.3048)
		(layers "F.Cu" "B.Cu")
		(net "PVCCIN_CPU1")
	)
	(via
		(at 91.818968 -68.0974)
		(size 0.508)
		(drill 0.254)
		(layers "F.Cu" "B.Cu")
		(net "PVCCIN_CPU1")
	)
	(via
		(at 101.230684 -88.165686)
		(size 0.508)
		(drill 0.254)
		(layers "F.Cu" "B.Cu")
		(net "PVCCIN_CPU1")
	)
	(via
		(at 90.928698 -83.212686)
		(size 0.508)
		(drill 0.254)
		(layers "F.Cu" "B.Cu")
		(net "PVCCIN_CPU1")
	)
	(via
		(at 44.6532 -76.4794)
		(size 0.5588)
		(drill 0.3048)
		(layers "F.Cu" "B.Cu")
		(net "PVCCIN_CPU1")
	)
	(via
		(at 47.87265 -68.59651)
		(size 0.5588)
		(drill 0.3048)
		(layers "F.Cu" "B.Cu")
		(net "PVCCIN_CPU1")
	)
	(via
		(at 69.753226 -80.850486)
		(size 0.508)
		(drill 0.254)
		(layers "F.Cu" "B.Cu")
		(net "PVCCIN_CPU1")
	)
	(via
		(at 76.621386 -77.878686)
		(size 0.508)
		(drill 0.254)
		(layers "F.Cu" "B.Cu")
		(net "PVCCIN_CPU1")
	)
	(via
		(at 76.621386 -76.888086)
		(size 0.508)
		(drill 0.254)
		(layers "F.Cu" "B.Cu")
		(net "PVCCIN_CPU1")
	)
	(via
		(at 45.67809 -69.901816)
		(size 0.5588)
		(drill 0.3048)
		(layers "F.Cu" "B.Cu")
		(net "PVCCIN_CPU1")
	)
	(via
		(at 74.904346 -77.878686)
		(size 0.508)
		(drill 0.254)
		(layers "F.Cu" "B.Cu")
		(net "PVCCIN_CPU1")
	)
	(via
		(at 107.051856 -88.518238)
		(size 0.508)
		(drill 0.254)
		(layers "F.Cu" "B.Cu")
		(net "PVCCIN_CPU1")
	)
	(via
		(at 100.372164 -65.1256)
		(size 0.508)
		(drill 0.254)
		(layers "F.Cu" "B.Cu")
		(net "PVCCIN_CPU1")
	)
	(via
		(at 88.640412 -76.888086)
		(size 0.508)
		(drill 0.254)
		(layers "F.Cu" "B.Cu")
		(net "PVCCIN_CPU1")
	)
	(via
		(at 46.9392 -75.057)
		(size 0.5588)
		(drill 0.3048)
		(layers "F.Cu" "B.Cu")
		(net "PVCCIN_CPU1")
	)
	(via
		(at 45.67809 -70.562216)
		(size 0.5588)
		(drill 0.3048)
		(layers "F.Cu" "B.Cu")
		(net "PVCCIN_CPU1")
	)
	(via
		(at 55.753 -64.643)
		(size 0.5588)
		(drill 0.3048)
		(layers "F.Cu" "B.Cu")
		(net "PVCCIN_CPU1")
	)
	(via
		(at 77.479906 -73.42124)
		(size 0.508)
		(drill 0.254)
		(layers "F.Cu" "B.Cu")
		(net "PVCCIN_CPU1")
	)
	(via
		(at 71.470266 -78.869286)
		(size 0.508)
		(drill 0.254)
		(layers "F.Cu" "B.Cu")
		(net "PVCCIN_CPU1")
	)
	(via
		(at 86.923372 -74.906886)
		(size 0.508)
		(drill 0.254)
		(layers "F.Cu" "B.Cu")
		(net "PVCCIN_CPU1")
	)
	(via
		(at 44.061634 -92.273374)
		(size 0.5588)
		(drill 0.3048)
		(layers "F.Cu" "B.Cu")
		(net "PVCCIN_CPU1")
	)
	(via
		(at 77.479906 -71.44004)
		(size 0.508)
		(drill 0.254)
		(layers "F.Cu" "B.Cu")
		(net "PVCCIN_CPU1")
	)
	(via
		(at 45.5676 -60.9346)
		(size 0.5588)
		(drill 0.3048)
		(layers "F.Cu" "B.Cu")
		(net "PVCCIN_CPU1")
	)
	(via
		(at 46.3042 -54.891432)
		(size 0.5588)
		(drill 0.3048)
		(layers "F.Cu" "B.Cu")
		(net "PVCCIN_CPU1")
	)
	(via
		(at 44.0182 -87.235792)
		(size 0.5588)
		(drill 0.3048)
		(layers "F.Cu" "B.Cu")
		(net "PVCCIN_CPU1")
	)
	(via
		(at 68.818506 -80.30464)
		(size 0.508)
		(drill 0.254)
		(layers "F.Cu" "B.Cu")
		(net "PVCCIN_CPU1")
	)
	(via
		(at 51.095402 -86.226904)
		(size 0.5588)
		(drill 0.3048)
		(layers "F.Cu" "B.Cu")
		(net "PVCCIN_CPU1")
	)
	(via
		(at 80.913732 -78.37424)
		(size 0.508)
		(drill 0.254)
		(layers "F.Cu" "B.Cu")
		(net "PVCCIN_CPU1")
	)
	(via
		(at 77.479906 -79.36484)
		(size 0.508)
		(drill 0.254)
		(layers "F.Cu" "B.Cu")
		(net "PVCCIN_CPU1")
	)
	(via
		(at 51.802538 -70.594982)
		(size 0.5588)
		(drill 0.3048)
		(layers "F.Cu" "B.Cu")
		(net "PVCCIN_CPU1")
	)
	(via
		(at 44.15409 -70.562216)
		(size 0.5588)
		(drill 0.3048)
		(layers "F.Cu" "B.Cu")
		(net "PVCCIN_CPU1")
	)
	(via
		(at 78.338172 -76.888086)
		(size 0.508)
		(drill 0.254)
		(layers "F.Cu" "B.Cu")
		(net "PVCCIN_CPU1")
	)
	(via
		(at 88.640412 -78.869286)
		(size 0.508)
		(drill 0.254)
		(layers "F.Cu" "B.Cu")
		(net "PVCCIN_CPU1")
	)
	(via
		(at 69.753226 -71.935086)
		(size 0.508)
		(drill 0.254)
		(layers "F.Cu" "B.Cu")
		(net "PVCCIN_CPU1")
	)
	(via
		(at 56.896 -84.0486)
		(size 0.5588)
		(drill 0.3048)
		(layers "F.Cu" "B.Cu")
		(net "PVCCIN_CPU1")
	)
	(via
		(at 48.5902 -87.184992)
		(size 0.5588)
		(drill 0.3048)
		(layers "F.Cu" "B.Cu")
		(net "PVCCIN_CPU1")
	)
	(via
		(at 78.338172 -72.925686)
		(size 0.508)
		(drill 0.254)
		(layers "F.Cu" "B.Cu")
		(net "PVCCIN_CPU1")
	)
	(via
		(at 87.781892 -78.37424)
		(size 0.508)
		(drill 0.254)
		(layers "F.Cu" "B.Cu")
		(net "PVCCIN_CPU1")
	)
	(via
		(at 91.215718 -66.48704)
		(size 0.508)
		(drill 0.254)
		(layers "F.Cu" "B.Cu")
		(net "PVCCIN_CPU1")
	)
	(via
		(at 90.357198 -84.812886)
		(size 0.508)
		(drill 0.254)
		(layers "F.Cu" "B.Cu")
		(net "PVCCIN_CPU1")
	)
	(via
		(at 46.3296 -60.198)
		(size 0.5588)
		(drill 0.3048)
		(layers "F.Cu" "B.Cu")
		(net "PVCCIN_CPU1")
	)
	(via
		(at 103.401876 -74.397616)
		(size 0.5588)
		(drill 0.3048)
		(layers "F.Cu" "B.Cu")
		(net "PVCCIN_CPU1")
	)
	(via
		(at 51.040538 -70.594982)
		(size 0.5588)
		(drill 0.3048)
		(layers "F.Cu" "B.Cu")
		(net "PVCCIN_CPU1")
	)
	(via
		(at 86.923372 -73.916286)
		(size 0.508)
		(drill 0.254)
		(layers "F.Cu" "B.Cu")
		(net "PVCCIN_CPU1")
	)
	(via
		(at 47.859696 -91.343734)
		(size 0.5588)
		(drill 0.3048)
		(layers "F.Cu" "B.Cu")
		(net "PVCCIN_CPU1")
	)
	(via
		(at 102.645718 -78.71714)
		(size 0.5588)
		(drill 0.3048)
		(layers "F.Cu" "B.Cu")
		(net "PVCCIN_CPU1")
	)
	(via
		(at 83.489292 -77.878686)
		(size 0.508)
		(drill 0.254)
		(layers "F.Cu" "B.Cu")
		(net "PVCCIN_CPU1")
	)
	(via
		(at 81.772252 -77.878686)
		(size 0.508)
		(drill 0.254)
		(layers "F.Cu" "B.Cu")
		(net "PVCCIN_CPU1")
	)
	(via
		(at 110.875826 -66.606928)
		(size 0.5588)
		(drill 0.3048)
		(layers "F.Cu" "B.Cu")
		(net "PVCCIN_CPU1")
	)
	(via
		(at 55.626 -85.3186)
		(size 0.5588)
		(drill 0.3048)
		(layers "F.Cu" "B.Cu")
		(net "PVCCIN_CPU1")
	)
	(via
		(at 46.1772 -75.057)
		(size 0.5588)
		(drill 0.3048)
		(layers "F.Cu" "B.Cu")
		(net "PVCCIN_CPU1")
	)
	(via
		(at 73.187306 -70.94474)
		(size 0.508)
		(drill 0.254)
		(layers "F.Cu" "B.Cu")
		(net "PVCCIN_CPU1")
	)
	(via
		(at 50.3428 -62.611)
		(size 0.5588)
		(drill 0.3048)
		(layers "F.Cu" "B.Cu")
		(net "PVCCIN_CPU1")
	)
	(via
		(at 44.7802 -86.3346)
		(size 0.5588)
		(drill 0.3048)
		(layers "F.Cu" "B.Cu")
		(net "PVCCIN_CPU1")
	)
	(via
		(at 76.621386 -71.935086)
		(size 0.508)
		(drill 0.254)
		(layers "F.Cu" "B.Cu")
		(net "PVCCIN_CPU1")
	)
	(via
		(at 80.055212 -76.888086)
		(size 0.508)
		(drill 0.254)
		(layers "F.Cu" "B.Cu")
		(net "PVCCIN_CPU1")
	)
	(via
		(at 90.692478 -78.37424)
		(size 0.508)
		(drill 0.254)
		(layers "F.Cu" "B.Cu")
		(net "PVCCIN_CPU1")
	)
	(via
		(at 96.938338 -65.1256)
		(size 0.508)
		(drill 0.254)
		(layers "F.Cu" "B.Cu")
		(net "PVCCIN_CPU1")
	)
	(via
		(at 47.0662 -87.210392)
		(size 0.5588)
		(drill 0.3048)
		(layers "F.Cu" "B.Cu")
		(net "PVCCIN_CPU1")
	)
	(via
		(at 75.762866 -77.38364)
		(size 0.508)
		(drill 0.254)
		(layers "F.Cu" "B.Cu")
		(net "PVCCIN_CPU1")
	)
	(via
		(at 98.940112 -74.39914)
		(size 0.5588)
		(drill 0.3048)
		(layers "F.Cu" "B.Cu")
		(net "PVCCIN_CPU1")
	)
	(via
		(at 69.753226 -72.925686)
		(size 0.508)
		(drill 0.254)
		(layers "F.Cu" "B.Cu")
		(net "PVCCIN_CPU1")
	)
	(via
		(at 44.8056 -60.9346)
		(size 0.5588)
		(drill 0.3048)
		(layers "F.Cu" "B.Cu")
		(net "PVCCIN_CPU1")
	)
	(via
		(at 79.196692 -73.42124)
		(size 0.508)
		(drill 0.254)
		(layers "F.Cu" "B.Cu")
		(net "PVCCIN_CPU1")
	)
	(via
		(at 76.621386 -78.869286)
		(size 0.508)
		(drill 0.254)
		(layers "F.Cu" "B.Cu")
		(net "PVCCIN_CPU1")
	)
	(via
		(at 45.5422 -87.235792)
		(size 0.5588)
		(drill 0.3048)
		(layers "F.Cu" "B.Cu")
		(net "PVCCIN_CPU1")
	)
	(via
		(at 44.7802 -87.235792)
		(size 0.5588)
		(drill 0.3048)
		(layers "F.Cu" "B.Cu")
		(net "PVCCIN_CPU1")
	)
	(via
		(at 100.372164 -87.67064)
		(size 0.508)
		(drill 0.254)
		(layers "F.Cu" "B.Cu")
		(net "PVCCIN_CPU1")
	)
	(via
		(at 87.781892 -79.36484)
		(size 0.508)
		(drill 0.254)
		(layers "F.Cu" "B.Cu")
		(net "PVCCIN_CPU1")
	)
	(via
		(at 67.917568 -70.104)
		(size 0.508)
		(drill 0.254)
		(layers "F.Cu" "B.Cu")
		(net "PVCCIN_CPU1")
	)
	(via
		(at 51.098958 -84.004912)
		(size 0.5588)
		(drill 0.3048)
		(layers "F.Cu" "B.Cu")
		(net "PVCCIN_CPU1")
	)
	(via
		(at 51.857402 -86.226904)
		(size 0.5588)
		(drill 0.3048)
		(layers "F.Cu" "B.Cu")
		(net "PVCCIN_CPU1")
	)
	(via
		(at 51.040538 -71.356982)
		(size 0.5588)
		(drill 0.3048)
		(layers "F.Cu" "B.Cu")
		(net "PVCCIN_CPU1")
	)
	(via
		(at 54.356 -86.5886)
		(size 0.5588)
		(drill 0.3048)
		(layers "F.Cu" "B.Cu")
		(net "PVCCIN_CPU1")
	)
	(via
		(at 73.187306 -75.897486)
		(size 0.508)
		(drill 0.254)
		(layers "F.Cu" "B.Cu")
		(net "PVCCIN_CPU1")
	)
	(via
		(at 73.187306 -74.906886)
		(size 0.508)
		(drill 0.254)
		(layers "F.Cu" "B.Cu")
		(net "PVCCIN_CPU1")
	)
	(via
		(at 101.230684 -64.581786)
		(size 0.508)
		(drill 0.254)
		(layers "F.Cu" "B.Cu")
		(net "PVCCIN_CPU1")
	)
	(via
		(at 111.344202 -65.391284)
		(size 0.508)
		(drill 0.254)
		(layers "F.Cu" "B.Cu")
		(net "PVCCIN_CPU1")
	)
	(via
		(at 44.0436 -59.5122)
		(size 0.5588)
		(drill 0.3048)
		(layers "F.Cu" "B.Cu")
		(net "PVCCIN_CPU1")
	)
	(via
		(at 46.3296 -60.9346)
		(size 0.5588)
		(drill 0.3048)
		(layers "F.Cu" "B.Cu")
		(net "PVCCIN_CPU1")
	)
	(via
		(at 96.158558 -78.68793)
		(size 0.5588)
		(drill 0.3048)
		(layers "F.Cu" "B.Cu")
		(net "PVCCIN_CPU1")
	)
	(via
		(at 86.923372 -75.897486)
		(size 0.508)
		(drill 0.254)
		(layers "F.Cu" "B.Cu")
		(net "PVCCIN_CPU1")
	)
	(via
		(at 51.7906 -62.611)
		(size 0.5588)
		(drill 0.3048)
		(layers "F.Cu" "B.Cu")
		(net "PVCCIN_CPU1")
	)
	(via
		(at 44.8056 -60.198)
		(size 0.5588)
		(drill 0.3048)
		(layers "F.Cu" "B.Cu")
		(net "PVCCIN_CPU1")
	)
	(via
		(at 74.904346 -70.94474)
		(size 0.508)
		(drill 0.254)
		(layers "F.Cu" "B.Cu")
		(net "PVCCIN_CPU1")
	)
	(via
		(at 87.781892 -72.43064)
		(size 0.508)
		(drill 0.254)
		(layers "F.Cu" "B.Cu")
		(net "PVCCIN_CPU1")
	)
	(via
		(at 97.915476 -74.397616)
		(size 0.5588)
		(drill 0.3048)
		(layers "F.Cu" "B.Cu")
		(net "PVCCIN_CPU1")
	)
	(via
		(at 94.649798 -87.28964)
		(size 0.508)
		(drill 0.254)
		(layers "F.Cu" "B.Cu")
		(net "PVCCIN_CPU1")
	)
	(via
		(at 50.026824 -75.078082)
		(size 0.5588)
		(drill 0.3048)
		(layers "F.Cu" "B.Cu")
		(net "PVCCIN_CPU1")
	)
	(via
		(at 94.362778 -66.6242)
		(size 0.508)
		(drill 0.254)
		(layers "F.Cu" "B.Cu")
		(net "PVCCIN_CPU1")
	)
	(via
		(at 75.762866 -73.42124)
		(size 0.508)
		(drill 0.254)
		(layers "F.Cu" "B.Cu")
		(net "PVCCIN_CPU1")
	)
	(via
		(at 44.0436 -60.198)
		(size 0.5588)
		(drill 0.3048)
		(layers "F.Cu" "B.Cu")
		(net "PVCCIN_CPU1")
	)
	(via
		(at 80.913732 -73.42124)
		(size 0.508)
		(drill 0.254)
		(layers "F.Cu" "B.Cu")
		(net "PVCCIN_CPU1")
	)
	(via
		(at 44.7802 -54.483)
		(size 0.5588)
		(drill 0.3048)
		(layers "F.Cu" "B.Cu")
		(net "PVCCIN_CPU1")
	)
	(via
		(at 84.347812 -75.40244)
		(size 0.508)
		(drill 0.254)
		(layers "F.Cu" "B.Cu")
		(net "PVCCIN_CPU1")
	)
	(via
		(at 45.5422 -86.3346)
		(size 0.5588)
		(drill 0.3048)
		(layers "F.Cu" "B.Cu")
		(net "PVCCIN_CPU1")
	)
	(via
		(at 51.860958 -85.528912)
		(size 0.5588)
		(drill 0.3048)
		(layers "F.Cu" "B.Cu")
		(net "PVCCIN_CPU1")
	)
	(via
		(at 70.611746 -71.44004)
		(size 0.508)
		(drill 0.254)
		(layers "F.Cu" "B.Cu")
		(net "PVCCIN_CPU1")
	)
	(via
		(at 86.923372 -76.888086)
		(size 0.508)
		(drill 0.254)
		(layers "F.Cu" "B.Cu")
		(net "PVCCIN_CPU1")
	)
	(via
		(at 67.917568 -81.788)
		(size 0.508)
		(drill 0.254)
		(layers "F.Cu" "B.Cu")
		(net "PVCCIN_CPU1")
	)
	(via
		(at 47.740824 -75.078082)
		(size 0.5588)
		(drill 0.3048)
		(layers "F.Cu" "B.Cu")
		(net "PVCCIN_CPU1")
	)
	(via
		(at 73.187306 -77.878686)
		(size 0.508)
		(drill 0.254)
		(layers "F.Cu" "B.Cu")
		(net "PVCCIN_CPU1")
	)
	(via
		(at 46.9392 -75.7936)
		(size 0.5588)
		(drill 0.3048)
		(layers "F.Cu" "B.Cu")
		(net "PVCCIN_CPU1")
	)
	(via
		(at 44.91609 -70.562216)
		(size 0.5588)
		(drill 0.3048)
		(layers "F.Cu" "B.Cu")
		(net "PVCCIN_CPU1")
	)
	(via
		(at 94.649798 -64.50584)
		(size 0.508)
		(drill 0.254)
		(layers "F.Cu" "B.Cu")
		(net "PVCCIN_CPU1")
	)
	(via
		(at 82.630772 -75.40244)
		(size 0.508)
		(drill 0.254)
		(layers "F.Cu" "B.Cu")
		(net "PVCCIN_CPU1")
	)
	(via
		(at 91.787218 -83.70824)
		(size 0.508)
		(drill 0.254)
		(layers "F.Cu" "B.Cu")
		(net "PVCCIN_CPU1")
	)
	(via
		(at 94.257876 -74.397616)
		(size 0.5588)
		(drill 0.3048)
		(layers "F.Cu" "B.Cu")
		(net "PVCCIN_CPU1")
	)
	(via
		(at 44.7802 -55.196232)
		(size 0.5588)
		(drill 0.3048)
		(layers "F.Cu" "B.Cu")
		(net "PVCCIN_CPU1")
	)
	(via
		(at 74.904346 -78.869286)
		(size 0.508)
		(drill 0.254)
		(layers "F.Cu" "B.Cu")
		(net "PVCCIN_CPU1")
	)
	(via
		(at 95.221298 -66.1162)
		(size 0.508)
		(drill 0.254)
		(layers "F.Cu" "B.Cu")
		(net "PVCCIN_CPU1")
	)
	(via
		(at 88.640412 -71.935086)
		(size 0.508)
		(drill 0.254)
		(layers "F.Cu" "B.Cu")
		(net "PVCCIN_CPU1")
	)
	(via
		(at 87.781892 -76.39304)
		(size 0.508)
		(drill 0.254)
		(layers "F.Cu" "B.Cu")
		(net "PVCCIN_CPU1")
	)
	(via
		(at 45.5422 -54.891432)
		(size 0.5588)
		(drill 0.3048)
		(layers "F.Cu" "B.Cu")
		(net "PVCCIN_CPU1")
	)
	(via
		(at 46.3042 -87.235792)
		(size 0.5588)
		(drill 0.3048)
		(layers "F.Cu" "B.Cu")
		(net "PVCCIN_CPU1")
	)
	(via
		(at 68.806568 -78.37424)
		(size 0.508)
		(drill 0.254)
		(layers "F.Cu" "B.Cu")
		(net "PVCCIN_CPU1")
	)
	(via
		(at 88.640412 -81.841086)
		(size 0.508)
		(drill 0.254)
		(layers "F.Cu" "B.Cu")
		(net "PVCCIN_CPU1")
	)
	(via
		(at 74.904346 -72.925686)
		(size 0.508)
		(drill 0.254)
		(layers "F.Cu" "B.Cu")
		(net "PVCCIN_CPU1")
	)
	(via
		(at 50.351182 -87.732108)
		(size 0.5588)
		(drill 0.3048)
		(layers "F.Cu" "B.Cu")
		(net "PVCCIN_CPU1")
	)
	(via
		(at 46.46549 -70.003416)
		(size 0.5588)
		(drill 0.3048)
		(layers "F.Cu" "B.Cu")
		(net "PVCCIN_CPU1")
	)
	(via
		(at 90.692478 -74.411586)
		(size 0.508)
		(drill 0.254)
		(layers "F.Cu" "B.Cu")
		(net "PVCCIN_CPU1")
	)
	(via
		(at 92.932758 -86.29904)
		(size 0.508)
		(drill 0.254)
		(layers "F.Cu" "B.Cu")
		(net "PVCCIN_CPU1")
	)
	(via
		(at 84.347812 -77.38364)
		(size 0.508)
		(drill 0.254)
		(layers "F.Cu" "B.Cu")
		(net "PVCCIN_CPU1")
	)
	(via
		(at 47.8028 -60.1472)
		(size 0.5588)
		(drill 0.3048)
		(layers "F.Cu" "B.Cu")
		(net "PVCCIN_CPU1")
	)
	(via
		(at 47.109634 -92.273374)
		(size 0.5588)
		(drill 0.3048)
		(layers "F.Cu" "B.Cu")
		(net "PVCCIN_CPU1")
	)
	(via
		(at 78.338172 -71.935086)
		(size 0.508)
		(drill 0.254)
		(layers "F.Cu" "B.Cu")
		(net "PVCCIN_CPU1")
	)
	(via
		(at 67.909186 -80.850486)
		(size 0.508)
		(drill 0.254)
		(layers "F.Cu" "B.Cu")
		(net "PVCCIN_CPU1")
	)
	(via
		(at 45.5422 -85.598)
		(size 0.5588)
		(drill 0.3048)
		(layers "F.Cu" "B.Cu")
		(net "PVCCIN_CPU1")
	)
	(via
		(at 79.196692 -75.40244)
		(size 0.508)
		(drill 0.254)
		(layers "F.Cu" "B.Cu")
		(net "PVCCIN_CPU1")
	)
	(via
		(at 68.806568 -72.517)
		(size 0.508)
		(drill 0.254)
		(layers "F.Cu" "B.Cu")
		(net "PVCCIN_CPU1")
	)
	(via
		(at 72.328786 -79.36484)
		(size 0.508)
		(drill 0.254)
		(layers "F.Cu" "B.Cu")
		(net "PVCCIN_CPU1")
	)
	(via
		(at 90.692478 -79.36484)
		(size 0.508)
		(drill 0.254)
		(layers "F.Cu" "B.Cu")
		(net "PVCCIN_CPU1")
	)
	(via
		(at 75.762866 -71.44004)
		(size 0.508)
		(drill 0.254)
		(layers "F.Cu" "B.Cu")
		(net "PVCCIN_CPU1")
	)
	(via
		(at 69.753226 -73.916286)
		(size 0.508)
		(drill 0.254)
		(layers "F.Cu" "B.Cu")
		(net "PVCCIN_CPU1")
	)
	(via
		(at 46.3042 -86.3346)
		(size 0.5588)
		(drill 0.3048)
		(layers "F.Cu" "B.Cu")
		(net "PVCCIN_CPU1")
	)
	(via
		(at 94.928944 -74.439272)
		(size 0.5588)
		(drill 0.3048)
		(layers "F.Cu" "B.Cu")
		(net "PVCCIN_CPU1")
	)
	(via
		(at 44.8056 -59.5122)
		(size 0.5588)
		(drill 0.3048)
		(layers "F.Cu" "B.Cu")
		(net "PVCCIN_CPU1")
	)
	(via
		(at 69.753226 -75.897486)
		(size 0.508)
		(drill 0.254)
		(layers "F.Cu" "B.Cu")
		(net "PVCCIN_CPU1")
	)
	(via
		(at 80.055212 -73.916286)
		(size 0.508)
		(drill 0.254)
		(layers "F.Cu" "B.Cu")
		(net "PVCCIN_CPU1")
	)
	(via
		(at 46.1772 -76.4794)
		(size 0.5588)
		(drill 0.3048)
		(layers "F.Cu" "B.Cu")
		(net "PVCCIN_CPU1")
	)
	(via
		(at 110.485682 -64.896238)
		(size 0.508)
		(drill 0.254)
		(layers "F.Cu" "B.Cu")
		(net "PVCCIN_CPU1")
	)
	(via
		(at 88.640412 -73.916286)
		(size 0.508)
		(drill 0.254)
		(layers "F.Cu" "B.Cu")
		(net "PVCCIN_CPU1")
	)
	(via
		(at 51.1048 -63.373)
		(size 0.5588)
		(drill 0.3048)
		(layers "F.Cu" "B.Cu")
		(net "PVCCIN_CPU1")
	)
	(via
		(at 67.909186 -71.935086)
		(size 0.508)
		(drill 0.254)
		(layers "F.Cu" "B.Cu")
		(net "PVCCIN_CPU1")
	)
	(via
		(at 92.645738 -67.6402)
		(size 0.508)
		(drill 0.254)
		(layers "F.Cu" "B.Cu")
		(net "PVCCIN_CPU1")
	)
	(via
		(at 80.055212 -72.925686)
		(size 0.508)
		(drill 0.254)
		(layers "F.Cu" "B.Cu")
		(net "PVCCIN_CPU1")
	)
	(via
		(at 70.611746 -75.40244)
		(size 0.508)
		(drill 0.254)
		(layers "F.Cu" "B.Cu")
		(net "PVCCIN_CPU1")
	)
	(via
		(at 86.064852 -72.43064)
		(size 0.508)
		(drill 0.254)
		(layers "F.Cu" "B.Cu")
		(net "PVCCIN_CPU1")
	)
	(via
		(at 100.811838 -74.436732)
		(size 0.5588)
		(drill 0.3048)
		(layers "F.Cu" "B.Cu")
		(net "PVCCIN_CPU1")
	)
	(via
		(at 47.7774 -60.9092)
		(size 0.5588)
		(drill 0.3048)
		(layers "F.Cu" "B.Cu")
		(net "PVCCIN_CPU1")
	)
	(via
		(at 43.8912 -76.4794)
		(size 0.5588)
		(drill 0.3048)
		(layers "F.Cu" "B.Cu")
		(net "PVCCIN_CPU1")
	)
	(via
		(at 71.470266 -74.906886)
		(size 0.508)
		(drill 0.254)
		(layers "F.Cu" "B.Cu")
		(net "PVCCIN_CPU1")
	)
	(via
		(at 31.079694 -87.032846)
		(size 0.508)
		(drill 0.254)
		(layers "F.Cu" "B.Cu")
		(net "PVCCIN_CPU1")
	)
	(via
		(at 50.22342 -78.729586)
		(size 0.5588)
		(drill 0.3048)
		(layers "F.Cu" "B.Cu")
		(net "PVCCIN_CPU1")
	)
	(via
		(at 31.0896 -70.782434)
		(size 0.508)
		(drill 0.254)
		(layers "F.Cu" "B.Cu")
		(net "PVCCIN_CPU1")
	)
	(via
		(at 44.7802 -53.8226)
		(size 0.5588)
		(drill 0.3048)
		(layers "F.Cu" "B.Cu")
		(net "PVCCIN_CPU1")
	)
	(via
		(at 92.932758 -65.49644)
		(size 0.508)
		(drill 0.254)
		(layers "F.Cu" "B.Cu")
		(net "PVCCIN_CPU1")
	)
	(via
		(at 87.781892 -73.42124)
		(size 0.508)
		(drill 0.254)
		(layers "F.Cu" "B.Cu")
		(net "PVCCIN_CPU1")
	)
	(via
		(at 93.501464 -74.444098)
		(size 0.5588)
		(drill 0.3048)
		(layers "F.Cu" "B.Cu")
		(net "PVCCIN_CPU1")
	)
	(via
		(at 107.910376 -88.022684)
		(size 0.508)
		(drill 0.254)
		(layers "F.Cu" "B.Cu")
		(net "PVCCIN_CPU1")
	)
	(via
		(at 93.791278 -65.000886)
		(size 0.508)
		(drill 0.254)
		(layers "F.Cu" "B.Cu")
		(net "PVCCIN_CPU1")
	)
	(via
		(at 48.6156 -70.7136)
		(size 0.5588)
		(drill 0.3048)
		(layers "F.Cu" "B.Cu")
		(net "PVCCIN_CPU1")
	)
	(via
		(at 46.3042 -85.598)
		(size 0.5588)
		(drill 0.3048)
		(layers "F.Cu" "B.Cu")
		(net "PVCCIN_CPU1")
	)
	(via
		(at 88.640412 -68.963286)
		(size 0.508)
		(drill 0.254)
		(layers "F.Cu" "B.Cu")
		(net "PVCCIN_CPU1")
	)
	(via
		(at 111.31296 -86.20252)
		(size 0.508)
		(drill 0.254)
		(layers "F.Cu" "B.Cu")
		(net "PVCCIN_CPU1")
	)
	(via
		(at 44.049696 -91.343734)
		(size 0.5588)
		(drill 0.3048)
		(layers "F.Cu" "B.Cu")
		(net "PVCCIN_CPU1")
	)
	(via
		(at 50.312828 -70.61073)
		(size 0.5588)
		(drill 0.3048)
		(layers "F.Cu" "B.Cu")
		(net "PVCCIN_CPU1")
	)
	(via
		(at 74.045826 -79.36484)
		(size 0.508)
		(drill 0.254)
		(layers "F.Cu" "B.Cu")
		(net "PVCCIN_CPU1")
	)
	(segment
		(start 29.36748 -58.91022)
		(end 29.36748 -61.04763)
		(width 0.508)
		(layer "In2.Cu")
		(net "PVCCIN_CPU1")
	)
	(segment
		(start 29.6164 -77.40396)
		(end 29.6164 -76.4794)
		(width 0.508)
		(layer "In2.Cu")
		(net "PVCCIN_CPU1")
	)
	(segment
		(start 31.079694 -86.45144)
		(end 29.941012 -85.312758)
		(width 0.508)
		(layer "In2.Cu")
		(net "PVCCIN_CPU1")
	)
	(segment
		(start 31.24962 -62.92977)
		(end 31.24962 -66.646806)
		(width 0.508)
		(layer "In2.Cu")
		(net "PVCCIN_CPU1")
	)
	(segment
		(start 29.948632 -67.947794)
		(end 29.948632 -69.641466)
		(width 0.508)
		(layer "In2.Cu")
		(net "PVCCIN_CPU1")
	)
	(segment
		(start 29.948632 -69.641466)
		(end 31.0896 -70.782434)
		(width 0.508)
		(layer "In2.Cu")
		(net "PVCCIN_CPU1")
	)
	(segment
		(start 30.71622 -54.770274)
		(end 30.71622 -57.56148)
		(width 0.508)
		(layer "In2.Cu")
		(net "PVCCIN_CPU1")
	)
	(segment
		(start 29.36748 -61.04763)
		(end 30.9753 -62.65545)
		(width 0.508)
		(layer "In2.Cu")
		(net "PVCCIN_CPU1")
	)
	(segment
		(start 29.988002 -74.422)
		(end 30.877002 -73.533)
		(width 0.508)
		(layer "In2.Cu")
		(net "PVCCIN_CPU1")
	)
	(segment
		(start 30.9753 -62.65545)
		(end 31.039562 -62.65545)
		(width 0.508)
		(layer "In2.Cu")
		(net "PVCCIN_CPU1")
	)
	(segment
		(start 29.941012 -85.312758)
		(end 29.941012 -83.190588)
		(width 0.508)
		(layer "In2.Cu")
		(net "PVCCIN_CPU1")
	)
	(segment
		(start 29.6164 -76.4794)
		(end 28.956 -75.819)
		(width 0.508)
		(layer "In2.Cu")
		(net "PVCCIN_CPU1")
	)
	(segment
		(start 30.9753 -62.65545)
		(end 31.24962 -62.92977)
		(width 0.508)
		(layer "In2.Cu")
		(net "PVCCIN_CPU1")
	)
	(segment
		(start 31.24962 -66.646806)
		(end 29.948632 -67.947794)
		(width 0.508)
		(layer "In2.Cu")
		(net "PVCCIN_CPU1")
	)
	(segment
		(start 30.877002 -73.533)
		(end 30.877002 -70.995032)
		(width 0.508)
		(layer "In2.Cu")
		(net "PVCCIN_CPU1")
	)
	(segment
		(start 28.956 -74.803)
		(end 29.337 -74.422)
		(width 0.508)
		(layer "In2.Cu")
		(net "PVCCIN_CPU1")
	)
	(segment
		(start 30.65272 -82.47888)
		(end 30.65272 -79.361284)
		(width 0.508)
		(layer "In2.Cu")
		(net "PVCCIN_CPU1")
	)
	(segment
		(start 31.079694 -87.032846)
		(end 31.079694 -86.45144)
		(width 0.508)
		(layer "In2.Cu")
		(net "PVCCIN_CPU1")
	)
	(segment
		(start 30.65272 -79.361284)
		(end 31.113222 -78.900782)
		(width 0.508)
		(layer "In2.Cu")
		(net "PVCCIN_CPU1")
	)
	(segment
		(start 28.956 -75.819)
		(end 28.956 -74.803)
		(width 0.508)
		(layer "In2.Cu")
		(net "PVCCIN_CPU1")
	)
	(segment
		(start 31.113222 -78.900782)
		(end 29.6164 -77.40396)
		(width 0.508)
		(layer "In2.Cu")
		(net "PVCCIN_CPU1")
	)
	(segment
		(start 30.877002 -70.995032)
		(end 31.0896 -70.782434)
		(width 0.508)
		(layer "In2.Cu")
		(net "PVCCIN_CPU1")
	)
	(segment
		(start 30.71622 -57.56148)
		(end 29.36748 -58.91022)
		(width 0.508)
		(layer "In2.Cu")
		(net "PVCCIN_CPU1")
	)
	(segment
		(start 31.125668 -54.360826)
		(end 30.71622 -54.770274)
		(width 0.508)
		(layer "In2.Cu")
		(net "PVCCIN_CPU1")
	)
	(segment
		(start 29.337 -74.422)
		(end 29.988002 -74.422)
		(width 0.508)
		(layer "In2.Cu")
		(net "PVCCIN_CPU1")
	)
	(segment
		(start 29.941012 -83.190588)
		(end 30.65272 -82.47888)
		(width 0.508)
		(layer "In2.Cu")
		(net "PVCCIN_CPU1")
	)
	(segment
		(start 258.50469 -86.29904)
		(end 257.93319 -86.29904)
		(width 0.254)
		(layer "F.Cu")
		(net "PVCCIN_CPU0")
	)
	(segment
		(start 242.193318 -73.916286)
		(end 241.621818 -73.916286)
		(width 0.254)
		(layer "F.Cu")
		(net "PVCCIN_CPU0")
	)
	(segment
		(start 250.778264 -72.925686)
		(end 250.206764 -72.925686)
		(width 0.254)
		(layer "F.Cu")
		(net "PVCCIN_CPU0")
	)
	(segment
		(start 255.07061 -75.40244)
		(end 255.69291 -75.40244)
		(width 0.254)
		(layer "F.Cu")
		(net "PVCCIN_CPU0")
	)
	(segment
		(start 241.334798 -77.38364)
		(end 240.763298 -77.38364)
		(width 0.254)
		(layer "F.Cu")
		(net "PVCCIN_CPU0")
	)
	(segment
		(start 255.07061 -67.47764)
		(end 254.49911 -67.47764)
		(width 0.254)
		(layer "F.Cu")
		(net "PVCCIN_CPU0")
	)
	(segment
		(start 240.476278 -79.859886)
		(end 239.904778 -79.859886)
		(width 0.254)
		(layer "F.Cu")
		(net "PVCCIN_CPU0")
	)
	(segment
		(start 196.409818 -87.156544)
		(end 196.248528 -86.995254)
		(width 0.254)
		(layer "F.Cu")
		(net "PVCCIN_CPU0")
	)
	(segment
		(start 238.187738 -78.869286)
		(end 238.759238 -78.869286)
		(width 0.254)
		(layer "F.Cu")
		(net "PVCCIN_CPU0")
	)
	(segment
		(start 247.344184 -77.878686)
		(end 246.772684 -77.878686)
		(width 0.254)
		(layer "F.Cu")
		(net "PVCCIN_CPU0")
	)
	(segment
		(start 254.212344 -68.963286)
		(end 253.640844 -68.963286)
		(width 0.254)
		(layer "F.Cu")
		(net "PVCCIN_CPU0")
	)
	(segment
		(start 255.07061 -80.35544)
		(end 255.69291 -80.35544)
		(width 0.254)
		(layer "F.Cu")
		(net "PVCCIN_CPU0")
	)
	(segment
		(start 239.617758 -79.36484)
		(end 239.046258 -79.36484)
		(width 0.254)
		(layer "F.Cu")
		(net "PVCCIN_CPU0")
	)
	(segment
		(start 254.212344 -78.869286)
		(end 253.640844 -78.869286)
		(width 0.254)
		(layer "F.Cu")
		(net "PVCCIN_CPU0")
	)
	(segment
		(start 234.466638 -77.38364)
		(end 233.807 -77.38364)
		(width 0.254)
		(layer "F.Cu")
		(net "PVCCIN_CPU0")
	)
	(segment
		(start 243.338604 -72.925686)
		(end 243.910104 -72.925686)
		(width 0.254)
		(layer "F.Cu")
		(net "PVCCIN_CPU0")
	)
	(segment
		(start 243.338604 -75.897486)
		(end 243.910104 -75.897486)
		(width 0.254)
		(layer "F.Cu")
		(net "PVCCIN_CPU0")
	)
	(segment
		(start 238.187738 -72.925686)
		(end 238.759238 -72.925686)
		(width 0.254)
		(layer "F.Cu")
		(net "PVCCIN_CPU0")
	)
	(segment
		(start 238.187738 -76.888086)
		(end 238.759238 -76.888086)
		(width 0.254)
		(layer "F.Cu")
		(net "PVCCIN_CPU0")
	)
	(segment
		(start 279.778714 -66.800984)
		(end 279.778714 -67.4116)
		(width 0.1016)
		(layer "F.Cu")
		(net "PVCCIN_CPU0")
	)
	(segment
		(start 249.919744 -78.37424)
		(end 249.348244 -78.37424)
		(width 0.254)
		(layer "F.Cu")
		(net "PVCCIN_CPU0")
	)
	(segment
		(start 260.22173 -65.49644)
		(end 260.22173 -66.1162)
		(width 0.254)
		(layer "F.Cu")
		(net "PVCCIN_CPU0")
	)
	(segment
		(start 261.08025 -86.794086)
		(end 261.08025 -86.184486)
		(width 0.254)
		(layer "F.Cu")
		(net "PVCCIN_CPU0")
	)
	(segment
		(start 266.231116 -88.775286)
		(end 266.231116 -88.165686)
		(width 0.254)
		(layer "F.Cu")
		(net "PVCCIN_CPU0")
	)
	(segment
		(start 235.325158 -71.935086)
		(end 234.753658 -71.935086)
		(width 0.254)
		(layer "F.Cu")
		(net "PVCCIN_CPU0")
	)
	(segment
		(start 238.187738 -77.878686)
		(end 238.759238 -77.878686)
		(width 0.254)
		(layer "F.Cu")
		(net "PVCCIN_CPU0")
	)
	(segment
		(start 245.627144 -72.925686)
		(end 245.055644 -72.925686)
		(width 0.254)
		(layer "F.Cu")
		(net "PVCCIN_CPU0")
	)
	(segment
		(start 249.061224 -72.925686)
		(end 248.489724 -72.925686)
		(width 0.254)
		(layer "F.Cu")
		(net "PVCCIN_CPU0")
	)
	(segment
		(start 263.65581 -88.28024)
		(end 263.65581 -87.67064)
		(width 0.254)
		(layer "F.Cu")
		(net "PVCCIN_CPU0")
	)
	(segment
		(start 254.212344 -79.859886)
		(end 253.640844 -79.859886)
		(width 0.254)
		(layer "F.Cu")
		(net "PVCCIN_CPU0")
	)
	(segment
		(start 234.466638 -81.34604)
		(end 233.895138 -81.34604)
		(width 0.254)
		(layer "F.Cu")
		(net "PVCCIN_CPU0")
	)
	(segment
		(start 237.042198 -78.869286)
		(end 236.470698 -78.869286)
		(width 0.254)
		(layer "F.Cu")
		(net "PVCCIN_CPU0")
	)
	(segment
		(start 253.353824 -78.37424)
		(end 252.782324 -78.37424)
		(width 0.254)
		(layer "F.Cu")
		(net "PVCCIN_CPU0")
	)
	(segment
		(start 209.296 -51.382168)
		(end 209.296 -52.1208)
		(width 0.254)
		(layer "F.Cu")
		(net "PVCCIN_CPU0")
	)
	(segment
		(start 234.466638 -71.44004)
		(end 233.895138 -71.44004)
		(width 0.254)
		(layer "F.Cu")
		(net "PVCCIN_CPU0")
	)
	(segment
		(start 254.212344 -83.822286)
		(end 253.640844 -83.822286)
		(width 0.254)
		(layer "F.Cu")
		(net "PVCCIN_CPU0")
	)
	(segment
		(start 250.778264 -73.916286)
		(end 250.206764 -73.916286)
		(width 0.254)
		(layer "F.Cu")
		(net "PVCCIN_CPU0")
	)
	(segment
		(start 237.900718 -73.42124)
		(end 237.329218 -73.42124)
		(width 0.254)
		(layer "F.Cu")
		(net "PVCCIN_CPU0")
	)
	(segment
		(start 238.187738 -74.906886)
		(end 238.759238 -74.906886)
		(width 0.254)
		(layer "F.Cu")
		(net "PVCCIN_CPU0")
	)
	(segment
		(start 255.07061 -76.39304)
		(end 255.69291 -76.39304)
		(width 0.254)
		(layer "F.Cu")
		(net "PVCCIN_CPU0")
	)
	(segment
		(start 258.50469 -66.48704)
		(end 258.50469 -67.1322)
		(width 0.254)
		(layer "F.Cu")
		(net "PVCCIN_CPU0")
	)
	(segment
		(start 243.338604 -73.916286)
		(end 243.910104 -73.916286)
		(width 0.254)
		(layer "F.Cu")
		(net "PVCCIN_CPU0")
	)
	(segment
		(start 256.78765 -85.30844)
		(end 256.21615 -85.30844)
		(width 0.254)
		(layer "F.Cu")
		(net "PVCCIN_CPU0")
	)
	(segment
		(start 248.202704 -73.42124)
		(end 247.631204 -73.42124)
		(width 0.254)
		(layer "F.Cu")
		(net "PVCCIN_CPU0")
	)
	(segment
		(start 245.627144 -76.888086)
		(end 245.055644 -76.888086)
		(width 0.254)
		(layer "F.Cu")
		(net "PVCCIN_CPU0")
	)
	(segment
		(start 241.334798 -73.42124)
		(end 240.763298 -73.42124)
		(width 0.254)
		(layer "F.Cu")
		(net "PVCCIN_CPU0")
	)
	(segment
		(start 237.042198 -70.94474)
		(end 236.470698 -70.94474)
		(width 0.254)
		(layer "F.Cu")
		(net "PVCCIN_CPU0")
	)
	(segment
		(start 273.769328 -64.871346)
		(end 273.769328 -64.324738)
		(width 0.254)
		(layer "F.Cu")
		(net "PVCCIN_CPU0")
	)
	(segment
		(start 196.235828 -62.598554)
		(end 195.9991 -62.598554)
		(width 0.254)
		(layer "F.Cu")
		(net "PVCCIN_CPU0")
	)
	(segment
		(start 237.042198 -74.906886)
		(end 236.470698 -74.906886)
		(width 0.254)
		(layer "F.Cu")
		(net "PVCCIN_CPU0")
	)
	(segment
		(start 243.338604 -79.859886)
		(end 243.910104 -79.859886)
		(width 0.254)
		(layer "F.Cu")
		(net "PVCCIN_CPU0")
	)
	(segment
		(start 243.338604 -70.94474)
		(end 243.910104 -70.94474)
		(width 0.254)
		(layer "F.Cu")
		(net "PVCCIN_CPU0")
	)
	(segment
		(start 240.476278 -70.94474)
		(end 239.904778 -70.94474)
		(width 0.254)
		(layer "F.Cu")
		(net "PVCCIN_CPU0")
	)
	(segment
		(start 236.183678 -71.44004)
		(end 235.612178 -71.44004)
		(width 0.254)
		(layer "F.Cu")
		(net "PVCCIN_CPU0")
	)
	(segment
		(start 253.353824 -70.44944)
		(end 252.782324 -70.44944)
		(width 0.254)
		(layer "F.Cu")
		(net "PVCCIN_CPU0")
	)
	(segment
		(start 249.061224 -76.888086)
		(end 248.489724 -76.888086)
		(width 0.254)
		(layer "F.Cu")
		(net "PVCCIN_CPU0")
	)
	(segment
		(start 249.061224 -75.897486)
		(end 248.489724 -75.897486)
		(width 0.254)
		(layer "F.Cu")
		(net "PVCCIN_CPU0")
	)
	(segment
		(start 252.495304 -72.925686)
		(end 251.923804 -72.925686)
		(width 0.254)
		(layer "F.Cu")
		(net "PVCCIN_CPU0")
	)
	(segment
		(start 275.486114 -64.324738)
		(end 275.486114 -64.896238)
		(width 0.1016)
		(layer "F.Cu")
		(net "PVCCIN_CPU0")
	)
	(segment
		(start 196.248528 -86.995254)
		(end 196.0118 -86.995254)
		(width 0.254)
		(layer "F.Cu")
		(net "PVCCIN_CPU0")
	)
	(segment
		(start 196.64553 -54.644544)
		(end 196.409818 -54.644544)
		(width 0.254)
		(layer "F.Cu")
		(net "PVCCIN_CPU0")
	)
	(segment
		(start 238.187738 -79.859886)
		(end 238.759238 -79.859886)
		(width 0.254)
		(layer "F.Cu")
		(net "PVCCIN_CPU0")
	)
	(segment
		(start 257.64617 -65.991486)
		(end 257.07467 -65.991486)
		(width 0.254)
		(layer "F.Cu")
		(net "PVCCIN_CPU0")
	)
	(segment
		(start 243.338604 -71.935086)
		(end 243.910104 -71.935086)
		(width 0.254)
		(layer "F.Cu")
		(net "PVCCIN_CPU0")
	)
	(segment
		(start 236.183678 -79.36484)
		(end 235.612178 -79.36484)
		(width 0.254)
		(layer "F.Cu")
		(net "PVCCIN_CPU0")
	)
	(segment
		(start 244.768624 -79.36484)
		(end 244.197124 -79.36484)
		(width 0.254)
		(layer "F.Cu")
		(net "PVCCIN_CPU0")
	)
	(segment
		(start 196.235828 -70.726554)
		(end 195.9991 -70.726554)
		(width 0.254)
		(layer "F.Cu")
		(net "PVCCIN_CPU0")
	)
	(segment
		(start 276.344634 -88.594184)
		(end 276.344634 -88.022684)
		(width 0.381)
		(layer "F.Cu")
		(net "PVCCIN_CPU0")
	)
	(segment
		(start 242.193318 -72.925686)
		(end 241.621818 -72.925686)
		(width 0.254)
		(layer "F.Cu")
		(net "PVCCIN_CPU0")
	)
	(segment
		(start 232.918 -70.104)
		(end 233.068114 -69.953886)
		(width 0.254)
		(layer "F.Cu")
		(net "PVCCIN_CPU0")
	)
	(segment
		(start 235.325158 -79.859886)
		(end 234.753658 -79.859886)
		(width 0.254)
		(layer "F.Cu")
		(net "PVCCIN_CPU0")
	)
	(segment
		(start 249.061224 -77.878686)
		(end 248.489724 -77.878686)
		(width 0.254)
		(layer "F.Cu")
		(net "PVCCIN_CPU0")
	)
	(segment
		(start 253.353824 -71.44004)
		(end 252.782324 -71.44004)
		(width 0.254)
		(layer "F.Cu")
		(net "PVCCIN_CPU0")
	)
	(segment
		(start 234.466638 -74.411586)
		(end 233.807 -74.411586)
		(width 0.254)
		(layer "F.Cu")
		(net "PVCCIN_CPU0")
	)
	(segment
		(start 267.089636 -88.28024)
		(end 267.089636 -87.67064)
		(width 0.254)
		(layer "F.Cu")
		(net "PVCCIN_CPU0")
	)
	(segment
		(start 279.778714 -87.603584)
		(end 279.778714 -87.032084)
		(width 0.381)
		(layer "F.Cu")
		(net "PVCCIN_CPU0")
	)
	(segment
		(start 246.485664 -75.40244)
		(end 245.914164 -75.40244)
		(width 0.254)
		(layer "F.Cu")
		(net "PVCCIN_CPU0")
	)
	(segment
		(start 255.07061 -73.42124)
		(end 255.69291 -73.42124)
		(width 0.254)
		(layer "F.Cu")
		(net "PVCCIN_CPU0")
	)
	(segment
		(start 241.334798 -71.44004)
		(end 240.763298 -71.44004)
		(width 0.254)
		(layer "F.Cu")
		(net "PVCCIN_CPU0")
	)
	(segment
		(start 255.92913 -66.982086)
		(end 255.35763 -66.982086)
		(width 0.254)
		(layer "F.Cu")
		(net "PVCCIN_CPU0")
	)
	(segment
		(start 278.920194 -88.099138)
		(end 278.920194 -87.527638)
		(width 0.381)
		(layer "F.Cu")
		(net "PVCCIN_CPU0")
	)
	(segment
		(start 240.476278 -75.897486)
		(end 239.904778 -75.897486)
		(width 0.254)
		(layer "F.Cu")
		(net "PVCCIN_CPU0")
	)
	(segment
		(start 233.807 -72.517)
		(end 233.89336 -72.43064)
		(width 0.254)
		(layer "F.Cu")
		(net "PVCCIN_CPU0")
	)
	(segment
		(start 254.212344 -77.878686)
		(end 253.640844 -77.878686)
		(width 0.254)
		(layer "F.Cu")
		(net "PVCCIN_CPU0")
	)
	(segment
		(start 252.495304 -76.888086)
		(end 251.923804 -76.888086)
		(width 0.254)
		(layer "F.Cu")
		(net "PVCCIN_CPU0")
	)
	(segment
		(start 261.93877 -64.50584)
		(end 261.93877 -65.1256)
		(width 0.254)
		(layer "F.Cu")
		(net "PVCCIN_CPU0")
	)
	(segment
		(start 241.334798 -75.40244)
		(end 240.763298 -75.40244)
		(width 0.254)
		(layer "F.Cu")
		(net "PVCCIN_CPU0")
	)
	(segment
		(start 255.07061 -69.45884)
		(end 255.69291 -69.45884)
		(width 0.254)
		(layer "F.Cu")
		(net "PVCCIN_CPU0")
	)
	(segment
		(start 273.769582 -64.8716)
		(end 273.769328 -64.871346)
		(width 0.254)
		(layer "F.Cu")
		(net "PVCCIN_CPU0")
	)
	(segment
		(start 259.36321 -86.794086)
		(end 258.79171 -86.794086)
		(width 0.254)
		(layer "F.Cu")
		(net "PVCCIN_CPU0")
	)
	(segment
		(start 248.202704 -77.38364)
		(end 247.631204 -77.38364)
		(width 0.254)
		(layer "F.Cu")
		(net "PVCCIN_CPU0")
	)
	(segment
		(start 259.36321 -85.803486)
		(end 259.36321 -85.193886)
		(width 0.254)
		(layer "F.Cu")
		(net "PVCCIN_CPU0")
	)
	(segment
		(start 237.042198 -71.935086)
		(end 236.470698 -71.935086)
		(width 0.254)
		(layer "F.Cu")
		(net "PVCCIN_CPU0")
	)
	(segment
		(start 253.353824 -77.38364)
		(end 252.782324 -77.38364)
		(width 0.254)
		(layer "F.Cu")
		(net "PVCCIN_CPU0")
	)
	(segment
		(start 266.231116 -64.010286)
		(end 266.231116 -64.581786)
		(width 0.254)
		(layer "F.Cu")
		(net "PVCCIN_CPU0")
	)
	(segment
		(start 272.913094 -65.31483)
		(end 272.910808 -65.312544)
		(width 0.254)
		(layer "F.Cu")
		(net "PVCCIN_CPU0")
	)
	(segment
		(start 242.193318 -75.897486)
		(end 241.621818 -75.897486)
		(width 0.254)
		(layer "F.Cu")
		(net "PVCCIN_CPU0")
	)
	(segment
		(start 237.900718 -71.44004)
		(end 237.329218 -71.44004)
		(width 0.254)
		(layer "F.Cu")
		(net "PVCCIN_CPU0")
	)
	(segment
		(start 257.64617 -66.982086)
		(end 257.64617 -67.6402)
		(width 0.254)
		(layer "F.Cu")
		(net "PVCCIN_CPU0")
	)
	(segment
		(start 242.193318 -74.906886)
		(end 241.621818 -74.906886)
		(width 0.254)
		(layer "F.Cu")
		(net "PVCCIN_CPU0")
	)
	(segment
		(start 245.627144 -73.916286)
		(end 245.055644 -73.916286)
		(width 0.254)
		(layer "F.Cu")
		(net "PVCCIN_CPU0")
	)
	(segment
		(start 258.50469 -85.30844)
		(end 258.50469 -84.69884)
		(width 0.254)
		(layer "F.Cu")
		(net "PVCCIN_CPU0")
	)
	(segment
		(start 243.051838 -79.36484)
		(end 242.480338 -79.36484)
		(width 0.254)
		(layer "F.Cu")
		(net "PVCCIN_CPU0")
	)
	(segment
		(start 244.768624 -73.42124)
		(end 244.197124 -73.42124)
		(width 0.254)
		(layer "F.Cu")
		(net "PVCCIN_CPU0")
	)
	(segment
		(start 236.183678 -77.38364)
		(end 235.612178 -77.38364)
		(width 0.254)
		(layer "F.Cu")
		(net "PVCCIN_CPU0")
	)
	(segment
		(start 254.212344 -70.94474)
		(end 253.640844 -70.94474)
		(width 0.254)
		(layer "F.Cu")
		(net "PVCCIN_CPU0")
	)
	(segment
		(start 234.466638 -70.44944)
		(end 233.895138 -70.44944)
		(width 0.254)
		(layer "F.Cu")
		(net "PVCCIN_CPU0")
	)
	(segment
		(start 278.061674 -65.810384)
		(end 278.061674 -66.421)
		(width 0.1016)
		(layer "F.Cu")
		(net "PVCCIN_CPU0")
	)
	(segment
		(start 254.212344 -73.916286)
		(end 253.640844 -73.916286)
		(width 0.254)
		(layer "F.Cu")
		(net "PVCCIN_CPU0")
	)
	(segment
		(start 260.22173 -86.29904)
		(end 260.22173 -85.68944)
		(width 0.254)
		(layer "F.Cu")
		(net "PVCCIN_CPU0")
	)
	(segment
		(start 264.51433 -88.775286)
		(end 264.51433 -88.165686)
		(width 0.254)
		(layer "F.Cu")
		(net "PVCCIN_CPU0")
	)
	(segment
		(start 249.919744 -73.42124)
		(end 249.348244 -73.42124)
		(width 0.254)
		(layer "F.Cu")
		(net "PVCCIN_CPU0")
	)
	(segment
		(start 263.65581 -64.50584)
		(end 263.65581 -65.151)
		(width 0.254)
		(layer "F.Cu")
		(net "PVCCIN_CPU0")
	)
	(segment
		(start 240.476278 -78.869286)
		(end 239.904778 -78.869286)
		(width 0.254)
		(layer "F.Cu")
		(net "PVCCIN_CPU0")
	)
	(segment
		(start 248.202704 -72.43064)
		(end 247.631204 -72.43064)
		(width 0.254)
		(layer "F.Cu")
		(net "PVCCIN_CPU0")
	)
	(segment
		(start 196.409818 -79.028544)
		(end 196.273674 -78.8924)
		(width 0.254)
		(layer "F.Cu")
		(net "PVCCIN_CPU0")
	)
	(segment
		(start 234.339638 -79.23784)
		(end 234.466638 -79.36484)
		(width 0.254)
		(layer "F.Cu")
		(net "PVCCIN_CPU0")
	)
	(segment
		(start 254.212344 -74.906886)
		(end 253.640844 -74.906886)
		(width 0.254)
		(layer "F.Cu")
		(net "PVCCIN_CPU0")
	)
	(segment
		(start 250.778264 -74.906886)
		(end 250.206764 -74.906886)
		(width 0.254)
		(layer "F.Cu")
		(net "PVCCIN_CPU0")
	)
	(segment
		(start 245.627144 -74.906886)
		(end 245.055644 -74.906886)
		(width 0.254)
		(layer "F.Cu")
		(net "PVCCIN_CPU0")
	)
	(segment
		(start 259.65023 -87.28964)
		(end 260.22173 -87.28964)
		(width 0.254)
		(layer "F.Cu")
		(net "PVCCIN_CPU0")
	)
	(segment
		(start 253.353824 -75.40244)
		(end 252.782324 -75.40244)
		(width 0.254)
		(layer "F.Cu")
		(net "PVCCIN_CPU0")
	)
	(segment
		(start 233.869738 -80.35544)
		(end 234.466638 -80.35544)
		(width 0.254)
		(layer "F.Cu")
		(net "PVCCIN_CPU0")
	)
	(segment
		(start 233.608118 -70.94474)
		(end 232.909618 -70.94474)
		(width 0.254)
		(layer "F.Cu")
		(net "PVCCIN_CPU0")
	)
	(segment
		(start 237.042198 -72.925686)
		(end 236.470698 -72.925686)
		(width 0.254)
		(layer "F.Cu")
		(net "PVCCIN_CPU0")
	)
	(segment
		(start 250.778264 -76.888086)
		(end 250.206764 -76.888086)
		(width 0.254)
		(layer "F.Cu")
		(net "PVCCIN_CPU0")
	)
	(segment
		(start 246.485664 -73.42124)
		(end 245.914164 -73.42124)
		(width 0.254)
		(layer "F.Cu")
		(net "PVCCIN_CPU0")
	)
	(segment
		(start 251.636784 -78.37424)
		(end 251.065284 -78.37424)
		(width 0.254)
		(layer "F.Cu")
		(net "PVCCIN_CPU0")
	)
	(segment
		(start 267.089636 -64.50584)
		(end 267.089636 -65.151)
		(width 0.254)
		(layer "F.Cu")
		(net "PVCCIN_CPU0")
	)
	(segment
		(start 238.187738 -73.916286)
		(end 238.759238 -73.916286)
		(width 0.254)
		(layer "F.Cu")
		(net "PVCCIN_CPU0")
	)
	(segment
		(start 255.07061 -74.411586)
		(end 255.69291 -74.411586)
		(width 0.254)
		(layer "F.Cu")
		(net "PVCCIN_CPU0")
	)
	(segment
		(start 253.353824 -73.42124)
		(end 252.782324 -73.42124)
		(width 0.254)
		(layer "F.Cu")
		(net "PVCCIN_CPU0")
	)
	(segment
		(start 242.193318 -76.888086)
		(end 241.621818 -76.888086)
		(width 0.254)
		(layer "F.Cu")
		(net "PVCCIN_CPU0")
	)
	(segment
		(start 240.476278 -74.906886)
		(end 239.904778 -74.906886)
		(width 0.254)
		(layer "F.Cu")
		(net "PVCCIN_CPU0")
	)
	(segment
		(start 237.042198 -77.878686)
		(end 236.470698 -77.878686)
		(width 0.254)
		(layer "F.Cu")
		(net "PVCCIN_CPU0")
	)
	(segment
		(start 249.919744 -75.40244)
		(end 249.348244 -75.40244)
		(width 0.254)
		(layer "F.Cu")
		(net "PVCCIN_CPU0")
	)
	(segment
		(start 264.51433 -64.010286)
		(end 264.51433 -64.581786)
		(width 0.254)
		(layer "F.Cu")
		(net "PVCCIN_CPU0")
	)
	(segment
		(start 239.617758 -73.42124)
		(end 239.046258 -73.42124)
		(width 0.254)
		(layer "F.Cu")
		(net "PVCCIN_CPU0")
	)
	(segment
		(start 247.344184 -74.906886)
		(end 246.772684 -74.906886)
		(width 0.254)
		(layer "F.Cu")
		(net "PVCCIN_CPU0")
	)
	(segment
		(start 196.64553 -62.772544)
		(end 196.409818 -62.772544)
		(width 0.254)
		(layer "F.Cu")
		(net "PVCCIN_CPU0")
	)
	(segment
		(start 280.637234 -67.296538)
		(end 280.637234 -67.8942)
		(width 0.1016)
		(layer "F.Cu")
		(net "PVCCIN_CPU0")
	)
	(segment
		(start 277.203154 -65.315338)
		(end 277.203154 -65.9384)
		(width 0.1016)
		(layer "F.Cu")
		(net "PVCCIN_CPU0")
	)
	(segment
		(start 271.193768 -63.829184)
		(end 271.193768 -64.516)
		(width 0.1016)
		(layer "F.Cu")
		(net "PVCCIN_CPU0")
	)
	(segment
		(start 196.409818 -62.772544)
		(end 196.235828 -62.598554)
		(width 0.254)
		(layer "F.Cu")
		(net "PVCCIN_CPU0")
	)
	(segment
		(start 233.608118 -81.841086)
		(end 232.960418 -81.841086)
		(width 0.254)
		(layer "F.Cu")
		(net "PVCCIN_CPU0")
	)
	(segment
		(start 247.344184 -73.916286)
		(end 246.772684 -73.916286)
		(width 0.254)
		(layer "F.Cu")
		(net "PVCCIN_CPU0")
	)
	(segment
		(start 278.920194 -66.305938)
		(end 278.920194 -66.9036)
		(width 0.1016)
		(layer "F.Cu")
		(net "PVCCIN_CPU0")
	)
	(segment
		(start 259.36321 -65.000886)
		(end 258.79171 -65.000886)
		(width 0.254)
		(layer "F.Cu")
		(net "PVCCIN_CPU0")
	)
	(segment
		(start 255.92913 -67.972686)
		(end 256.351024 -68.523358)
		(width 0.254)
		(layer "F.Cu")
		(net "PVCCIN_CPU0")
	)
	(segment
		(start 240.476278 -76.888086)
		(end 239.904778 -76.888086)
		(width 0.254)
		(layer "F.Cu")
		(net "PVCCIN_CPU0")
	)
	(segment
		(start 274.627848 -64.819784)
		(end 274.627848 -65.4304)
		(width 0.1016)
		(layer "F.Cu")
		(net "PVCCIN_CPU0")
	)
	(segment
		(start 253.353824 -80.35544)
		(end 252.782324 -80.35544)
		(width 0.1016)
		(layer "F.Cu")
		(net "PVCCIN_CPU0")
	)
	(segment
		(start 244.768624 -75.40244)
		(end 244.197124 -75.40244)
		(width 0.254)
		(layer "F.Cu")
		(net "PVCCIN_CPU0")
	)
	(segment
		(start 248.202704 -78.37424)
		(end 247.631204 -78.37424)
		(width 0.254)
		(layer "F.Cu")
		(net "PVCCIN_CPU0")
	)
	(segment
		(start 276.344634 -64.819784)
		(end 276.344634 -65.4812)
		(width 0.1016)
		(layer "F.Cu")
		(net "PVCCIN_CPU0")
	)
	(segment
		(start 261.08025 -65.000886)
		(end 261.08025 -65.6336)
		(width 0.254)
		(layer "F.Cu")
		(net "PVCCIN_CPU0")
	)
	(segment
		(start 233.608118 -82.83194)
		(end 233.036618 -82.83194)
		(width 0.254)
		(layer "F.Cu")
		(net "PVCCIN_CPU0")
	)
	(segment
		(start 243.051838 -75.40244)
		(end 242.480338 -75.40244)
		(width 0.254)
		(layer "F.Cu")
		(net "PVCCIN_CPU0")
	)
	(segment
		(start 253.353824 -76.39304)
		(end 252.782324 -76.39304)
		(width 0.254)
		(layer "F.Cu")
		(net "PVCCIN_CPU0")
	)
	(segment
		(start 239.617758 -75.40244)
		(end 239.046258 -75.40244)
		(width 0.254)
		(layer "F.Cu")
		(net "PVCCIN_CPU0")
	)
	(segment
		(start 247.344184 -75.897486)
		(end 246.772684 -75.897486)
		(width 0.254)
		(layer "F.Cu")
		(net "PVCCIN_CPU0")
	)
	(segment
		(start 246.485664 -77.38364)
		(end 245.914164 -77.38364)
		(width 0.254)
		(layer "F.Cu")
		(net "PVCCIN_CPU0")
	)
	(segment
		(start 255.07061 -72.43064)
		(end 255.69291 -72.43064)
		(width 0.254)
		(layer "F.Cu")
		(net "PVCCIN_CPU0")
	)
	(segment
		(start 196.273674 -78.8924)
		(end 195.9864 -78.8924)
		(width 0.254)
		(layer "F.Cu")
		(net "PVCCIN_CPU0")
	)
	(segment
		(start 252.495304 -73.916286)
		(end 251.923804 -73.916286)
		(width 0.254)
		(layer "F.Cu")
		(net "PVCCIN_CPU0")
	)
	(segment
		(start 256.78765 -66.48704)
		(end 256.21615 -66.48704)
		(width 0.1016)
		(layer "F.Cu")
		(net "PVCCIN_CPU0")
	)
	(segment
		(start 257.64617 -84.812886)
		(end 257.64617 -84.203286)
		(width 0.254)
		(layer "F.Cu")
		(net "PVCCIN_CPU0")
	)
	(segment
		(start 255.07061 -71.44004)
		(end 255.69291 -71.44004)
		(width 0.254)
		(layer "F.Cu")
		(net "PVCCIN_CPU0")
	)
	(segment
		(start 240.476278 -71.935086)
		(end 239.904778 -71.935086)
		(width 0.254)
		(layer "F.Cu")
		(net "PVCCIN_CPU0")
	)
	(segment
		(start 255.07061 -82.33664)
		(end 255.69291 -82.33664)
		(width 0.254)
		(layer "F.Cu")
		(net "PVCCIN_CPU0")
	)
	(segment
		(start 243.051838 -71.44004)
		(end 242.480338 -71.44004)
		(width 0.254)
		(layer "F.Cu")
		(net "PVCCIN_CPU0")
	)
	(segment
		(start 272.910808 -88.594184)
		(end 272.910808 -88.022684)
		(width 0.381)
		(layer "F.Cu")
		(net "PVCCIN_CPU0")
	)
	(segment
		(start 239.617758 -77.38364)
		(end 239.046258 -77.38364)
		(width 0.254)
		(layer "F.Cu")
		(net "PVCCIN_CPU0")
	)
	(segment
		(start 251.636784 -77.38364)
		(end 251.065284 -77.38364)
		(width 0.254)
		(layer "F.Cu")
		(net "PVCCIN_CPU0")
	)
	(segment
		(start 234.466638 -82.33664)
		(end 233.895138 -82.33664)
		(width 0.254)
		(layer "F.Cu")
		(net "PVCCIN_CPU0")
	)
	(segment
		(start 253.353824 -79.36484)
		(end 252.782324 -79.36484)
		(width 0.1016)
		(layer "F.Cu")
		(net "PVCCIN_CPU0")
	)
	(segment
		(start 251.636784 -72.43064)
		(end 251.065284 -72.43064)
		(width 0.254)
		(layer "F.Cu")
		(net "PVCCIN_CPU0")
	)
	(segment
		(start 275.486114 -89.089738)
		(end 275.486114 -88.518238)
		(width 0.381)
		(layer "F.Cu")
		(net "PVCCIN_CPU0")
	)
	(segment
		(start 196.64553 -87.156544)
		(end 196.409818 -87.156544)
		(width 0.254)
		(layer "F.Cu")
		(net "PVCCIN_CPU0")
	)
	(segment
		(start 255.07061 -70.44944)
		(end 255.69291 -70.44944)
		(width 0.254)
		(layer "F.Cu")
		(net "PVCCIN_CPU0")
	)
	(segment
		(start 258.50469 -65.49644)
		(end 257.93319 -65.49644)
		(width 0.254)
		(layer "F.Cu")
		(net "PVCCIN_CPU0")
	)
	(segment
		(start 243.051838 -77.38364)
		(end 242.480338 -77.38364)
		(width 0.254)
		(layer "F.Cu")
		(net "PVCCIN_CPU0")
	)
	(segment
		(start 233.807 -79.23784)
		(end 234.339638 -79.23784)
		(width 0.254)
		(layer "F.Cu")
		(net "PVCCIN_CPU0")
	)
	(segment
		(start 246.485664 -78.37424)
		(end 245.914164 -78.37424)
		(width 0.254)
		(layer "F.Cu")
		(net "PVCCIN_CPU0")
	)
	(segment
		(start 254.212344 -82.83194)
		(end 253.640844 -82.83194)
		(width 0.254)
		(layer "F.Cu")
		(net "PVCCIN_CPU0")
	)
	(segment
		(start 256.8194 -68.0974)
		(end 256.78765 -68.06565)
		(width 0.254)
		(layer "F.Cu")
		(net "PVCCIN_CPU0")
	)
	(segment
		(start 237.042198 -73.916286)
		(end 236.470698 -73.916286)
		(width 0.254)
		(layer "F.Cu")
		(net "PVCCIN_CPU0")
	)
	(segment
		(start 265.372596 -64.50584)
		(end 265.372596 -65.1256)
		(width 0.254)
		(layer "F.Cu")
		(net "PVCCIN_CPU0")
	)
	(segment
		(start 249.061224 -73.916286)
		(end 248.489724 -73.916286)
		(width 0.254)
		(layer "F.Cu")
		(net "PVCCIN_CPU0")
	)
	(segment
		(start 239.617758 -71.44004)
		(end 239.046258 -71.44004)
		(width 0.254)
		(layer "F.Cu")
		(net "PVCCIN_CPU0")
	)
	(segment
		(start 254.212344 -69.953886)
		(end 253.640844 -69.953886)
		(width 0.254)
		(layer "F.Cu")
		(net "PVCCIN_CPU0")
	)
	(segment
		(start 255.92913 -84.812886)
		(end 255.35763 -84.812886)
		(width 0.254)
		(layer "F.Cu")
		(net "PVCCIN_CPU0")
	)
	(segment
		(start 251.636784 -75.40244)
		(end 251.065284 -75.40244)
		(width 0.254)
		(layer "F.Cu")
		(net "PVCCIN_CPU0")
	)
	(segment
		(start 257.64617 -85.803486)
		(end 257.07467 -85.803486)
		(width 0.254)
		(layer "F.Cu")
		(net "PVCCIN_CPU0")
	)
	(segment
		(start 247.344184 -76.888086)
		(end 246.772684 -76.888086)
		(width 0.254)
		(layer "F.Cu")
		(net "PVCCIN_CPU0")
	)
	(segment
		(start 236.183678 -75.40244)
		(end 235.612178 -75.40244)
		(width 0.254)
		(layer "F.Cu")
		(net "PVCCIN_CPU0")
	)
	(segment
		(start 247.344184 -72.925686)
		(end 246.772684 -72.925686)
		(width 0.254)
		(layer "F.Cu")
		(net "PVCCIN_CPU0")
	)
	(segment
		(start 252.495304 -74.906886)
		(end 251.923804 -74.906886)
		(width 0.254)
		(layer "F.Cu")
		(net "PVCCIN_CPU0")
	)
	(segment
		(start 236.183678 -73.42124)
		(end 235.612178 -73.42124)
		(width 0.254)
		(layer "F.Cu")
		(net "PVCCIN_CPU0")
	)
	(segment
		(start 237.900718 -79.36484)
		(end 237.329218 -79.36484)
		(width 0.254)
		(layer "F.Cu")
		(net "PVCCIN_CPU0")
	)
	(segment
		(start 233.068114 -69.953886)
		(end 233.608118 -69.953886)
		(width 0.254)
		(layer "F.Cu")
		(net "PVCCIN_CPU0")
	)
	(segment
		(start 255.07061 -78.37424)
		(end 255.69291 -78.37424)
		(width 0.254)
		(layer "F.Cu")
		(net "PVCCIN_CPU0")
	)
	(segment
		(start 255.07061 -84.31784)
		(end 254.49911 -84.31784)
		(width 0.254)
		(layer "F.Cu")
		(net "PVCCIN_CPU0")
	)
	(segment
		(start 262.79729 -87.784686)
		(end 262.79729 -87.175086)
		(width 0.254)
		(layer "F.Cu")
		(net "PVCCIN_CPU0")
	)
	(segment
		(start 252.495304 -77.878686)
		(end 251.923804 -77.878686)
		(width 0.254)
		(layer "F.Cu")
		(net "PVCCIN_CPU0")
	)
	(segment
		(start 237.042198 -79.859886)
		(end 236.470698 -79.859886)
		(width 0.254)
		(layer "F.Cu")
		(net "PVCCIN_CPU0")
	)
	(segment
		(start 249.061224 -74.906886)
		(end 248.489724 -74.906886)
		(width 0.254)
		(layer "F.Cu")
		(net "PVCCIN_CPU0")
	)
	(segment
		(start 243.338604 -74.906886)
		(end 243.910104 -74.906886)
		(width 0.254)
		(layer "F.Cu")
		(net "PVCCIN_CPU0")
	)
	(segment
		(start 253.353824 -72.43064)
		(end 252.782324 -72.43064)
		(width 0.254)
		(layer "F.Cu")
		(net "PVCCIN_CPU0")
	)
	(segment
		(start 233.818938 -80.30464)
		(end 233.869738 -80.35544)
		(width 0.254)
		(layer "F.Cu")
		(net "PVCCIN_CPU0")
	)
	(segment
		(start 235.325158 -75.897486)
		(end 234.753658 -75.897486)
		(width 0.254)
		(layer "F.Cu")
		(net "PVCCIN_CPU0")
	)
	(segment
		(start 243.338604 -77.878686)
		(end 243.910104 -77.878686)
		(width 0.254)
		(layer "F.Cu")
		(net "PVCCIN_CPU0")
	)
	(segment
		(start 254.212344 -67.972686)
		(end 253.640844 -67.972686)
		(width 0.254)
		(layer "F.Cu")
		(net "PVCCIN_CPU0")
	)
	(segment
		(start 233.89336 -72.43064)
		(end 234.466638 -72.43064)
		(width 0.254)
		(layer "F.Cu")
		(net "PVCCIN_CPU0")
	)
	(segment
		(start 244.768624 -77.38364)
		(end 244.197124 -77.38364)
		(width 0.254)
		(layer "F.Cu")
		(net "PVCCIN_CPU0")
	)
	(segment
		(start 243.051838 -73.42124)
		(end 242.480338 -73.42124)
		(width 0.254)
		(layer "F.Cu")
		(net "PVCCIN_CPU0")
	)
	(segment
		(start 235.325158 -73.916286)
		(end 234.753658 -73.916286)
		(width 0.254)
		(layer "F.Cu")
		(net "PVCCIN_CPU0")
	)
	(segment
		(start 246.485664 -72.43064)
		(end 245.914164 -72.43064)
		(width 0.1016)
		(layer "F.Cu")
		(net "PVCCIN_CPU0")
	)
	(segment
		(start 250.778264 -77.878686)
		(end 250.206764 -77.878686)
		(width 0.254)
		(layer "F.Cu")
		(net "PVCCIN_CPU0")
	)
	(segment
		(start 234.466638 -76.39304)
		(end 233.807 -76.39304)
		(width 0.254)
		(layer "F.Cu")
		(net "PVCCIN_CPU0")
	)
	(segment
		(start 255.07061 -81.34604)
		(end 255.69291 -81.34604)
		(width 0.254)
		(layer "F.Cu")
		(net "PVCCIN_CPU0")
	)
	(segment
		(start 196.64553 -79.028544)
		(end 196.409818 -79.028544)
		(width 0.254)
		(layer "F.Cu")
		(net "PVCCIN_CPU0")
	)
	(segment
		(start 242.193318 -79.859886)
		(end 241.621818 -79.859886)
		(width 0.254)
		(layer "F.Cu")
		(net "PVCCIN_CPU0")
	)
	(segment
		(start 272.910808 -65.312544)
		(end 272.910808 -64.819784)
		(width 0.254)
		(layer "F.Cu")
		(net "PVCCIN_CPU0")
	)
	(segment
		(start 242.193318 -71.935086)
		(end 241.621818 -71.935086)
		(width 0.254)
		(layer "F.Cu")
		(net "PVCCIN_CPU0")
	)
	(segment
		(start 245.627144 -75.897486)
		(end 245.055644 -75.897486)
		(width 0.254)
		(layer "F.Cu")
		(net "PVCCIN_CPU0")
	)
	(segment
		(start 252.495304 -75.897486)
		(end 251.923804 -75.897486)
		(width 0.254)
		(layer "F.Cu")
		(net "PVCCIN_CPU0")
	)
	(segment
		(start 234.466638 -75.40244)
		(end 233.807 -75.40244)
		(width 0.254)
		(layer "F.Cu")
		(net "PVCCIN_CPU0")
	)
	(segment
		(start 241.334798 -79.36484)
		(end 240.763298 -79.36484)
		(width 0.254)
		(layer "F.Cu")
		(net "PVCCIN_CPU0")
	)
	(segment
		(start 240.476278 -77.878686)
		(end 239.904778 -77.878686)
		(width 0.254)
		(layer "F.Cu")
		(net "PVCCIN_CPU0")
	)
	(segment
		(start 262.79729 -64.010286)
		(end 262.79729 -64.581786)
		(width 0.254)
		(layer "F.Cu")
		(net "PVCCIN_CPU0")
	)
	(segment
		(start 274.627848 -88.594184)
		(end 274.627848 -88.022684)
		(width 0.381)
		(layer "F.Cu")
		(net "PVCCIN_CPU0")
	)
	(segment
		(start 237.900718 -77.38364)
		(end 237.329218 -77.38364)
		(width 0.254)
		(layer "F.Cu")
		(net "PVCCIN_CPU0")
	)
	(segment
		(start 235.325158 -70.94474)
		(end 234.753658 -70.94474)
		(width 0.254)
		(layer "F.Cu")
		(net "PVCCIN_CPU0")
	)
	(segment
		(start 254.212344 -72.925686)
		(end 253.640844 -72.925686)
		(width 0.254)
		(layer "F.Cu")
		(net "PVCCIN_CPU0")
	)
	(segment
		(start 245.627144 -77.878686)
		(end 245.055644 -77.878686)
		(width 0.254)
		(layer "F.Cu")
		(net "PVCCIN_CPU0")
	)
	(segment
		(start 244.768624 -71.44004)
		(end 244.197124 -71.44004)
		(width 0.254)
		(layer "F.Cu")
		(net "PVCCIN_CPU0")
	)
	(segment
		(start 235.325158 -77.878686)
		(end 234.753658 -77.878686)
		(width 0.254)
		(layer "F.Cu")
		(net "PVCCIN_CPU0")
	)
	(segment
		(start 237.042198 -75.897486)
		(end 236.470698 -75.897486)
		(width 0.254)
		(layer "F.Cu")
		(net "PVCCIN_CPU0")
	)
	(segment
		(start 254.212344 -75.897486)
		(end 253.640844 -75.897486)
		(width 0.254)
		(layer "F.Cu")
		(net "PVCCIN_CPU0")
	)
	(segment
		(start 255.7018 -68.7578)
		(end 255.41224 -68.46824)
		(width 0.254)
		(layer "F.Cu")
		(net "PVCCIN_CPU0")
	)
	(segment
		(start 196.409818 -54.644544)
		(end 196.129656 -54.364382)
		(width 0.254)
		(layer "F.Cu")
		(net "PVCCIN_CPU0")
	)
	(segment
		(start 255.92913 -83.822286)
		(end 255.92913 -83.212686)
		(width 0.254)
		(layer "F.Cu")
		(net "PVCCIN_CPU0")
	)
	(segment
		(start 260.22173 -64.50584)
		(end 259.65023 -64.50584)
		(width 0.254)
		(layer "F.Cu")
		(net "PVCCIN_CPU0")
	)
	(segment
		(start 249.919744 -77.38364)
		(end 249.348244 -77.38364)
		(width 0.254)
		(layer "F.Cu")
		(net "PVCCIN_CPU0")
	)
	(segment
		(start 243.338604 -76.888086)
		(end 243.910104 -76.888086)
		(width 0.254)
		(layer "F.Cu")
		(net "PVCCIN_CPU0")
	)
	(segment
		(start 255.92913 -83.212686)
		(end 255.07061 -83.32724)
		(width 0.254)
		(layer "F.Cu")
		(net "PVCCIN_CPU0")
	)
	(segment
		(start 238.187738 -75.897486)
		(end 238.759238 -75.897486)
		(width 0.254)
		(layer "F.Cu")
		(net "PVCCIN_CPU0")
	)
	(segment
		(start 265.372596 -88.28024)
		(end 265.372596 -87.67064)
		(width 0.254)
		(layer "F.Cu")
		(net "PVCCIN_CPU0")
	)
	(segment
		(start 260.50875 -64.010286)
		(end 261.08025 -64.010286)
		(width 0.254)
		(layer "F.Cu")
		(net "PVCCIN_CPU0")
	)
	(segment
		(start 196.64553 -70.900544)
		(end 196.409818 -70.900544)
		(width 0.254)
		(layer "F.Cu")
		(net "PVCCIN_CPU0")
	)
	(segment
		(start 272.052288 -89.089738)
		(end 272.052288 -88.518238)
		(width 0.381)
		(layer "F.Cu")
		(net "PVCCIN_CPU0")
	)
	(segment
		(start 240.476278 -73.916286)
		(end 239.904778 -73.916286)
		(width 0.254)
		(layer "F.Cu")
		(net "PVCCIN_CPU0")
	)
	(segment
		(start 250.778264 -75.897486)
		(end 250.206764 -75.897486)
		(width 0.254)
		(layer "F.Cu")
		(net "PVCCIN_CPU0")
	)
	(segment
		(start 253.353824 -74.411586)
		(end 252.782324 -74.411586)
		(width 0.254)
		(layer "F.Cu")
		(net "PVCCIN_CPU0")
	)
	(segment
		(start 259.36321 -65.991486)
		(end 259.36321 -66.6242)
		(width 0.254)
		(layer "F.Cu")
		(net "PVCCIN_CPU0")
	)
	(segment
		(start 196.409818 -70.900544)
		(end 196.235828 -70.726554)
		(width 0.254)
		(layer "F.Cu")
		(net "PVCCIN_CPU0")
	)
	(segment
		(start 273.769328 -89.089738)
		(end 273.769328 -88.518238)
		(width 0.381)
		(layer "F.Cu")
		(net "PVCCIN_CPU0")
	)
	(segment
		(start 234.466638 -73.42124)
		(end 233.807 -73.42124)
		(width 0.254)
		(layer "F.Cu")
		(net "PVCCIN_CPU0")
	)
	(segment
		(start 234.466638 -78.37424)
		(end 233.807 -78.37424)
		(width 0.254)
		(layer "F.Cu")
		(net "PVCCIN_CPU0")
	)
	(segment
		(start 267.948156 -64.010286)
		(end 267.948156 -64.643)
		(width 0.254)
		(layer "F.Cu")
		(net "PVCCIN_CPU0")
	)
	(segment
		(start 233.608118 -80.850486)
		(end 232.960418 -80.850486)
		(width 0.254)
		(layer "F.Cu")
		(net "PVCCIN_CPU0")
	)
	(segment
		(start 254.212344 -76.888086)
		(end 253.640844 -76.888086)
		(width 0.254)
		(layer "F.Cu")
		(net "PVCCIN_CPU0")
	)
	(segment
		(start 240.476278 -72.925686)
		(end 239.904778 -72.925686)
		(width 0.254)
		(layer "F.Cu")
		(net "PVCCIN_CPU0")
	)
	(segment
		(start 255.07061 -79.36484)
		(end 255.69291 -79.36484)
		(width 0.254)
		(layer "F.Cu")
		(net "PVCCIN_CPU0")
	)
	(segment
		(start 235.325158 -78.869286)
		(end 234.753658 -78.869286)
		(width 0.254)
		(layer "F.Cu")
		(net "PVCCIN_CPU0")
	)
	(segment
		(start 235.325158 -80.850486)
		(end 234.753658 -80.850486)
		(width 0.254)
		(layer "F.Cu")
		(net "PVCCIN_CPU0")
	)
	(segment
		(start 235.325158 -76.888086)
		(end 234.753658 -76.888086)
		(width 0.254)
		(layer "F.Cu")
		(net "PVCCIN_CPU0")
	)
	(segment
		(start 196.129656 -54.364382)
		(end 195.892928 -54.364382)
		(width 0.254)
		(layer "F.Cu")
		(net "PVCCIN_CPU0")
	)
	(segment
		(start 237.900718 -75.40244)
		(end 237.329218 -75.40244)
		(width 0.254)
		(layer "F.Cu")
		(net "PVCCIN_CPU0")
	)
	(segment
		(start 242.193318 -70.94474)
		(end 241.621818 -70.94474)
		(width 0.254)
		(layer "F.Cu")
		(net "PVCCIN_CPU0")
	)
	(segment
		(start 261.93877 -87.28964)
		(end 261.93877 -86.68004)
		(width 0.254)
		(layer "F.Cu")
		(net "PVCCIN_CPU0")
	)
	(segment
		(start 238.187738 -70.94474)
		(end 238.759238 -70.94474)
		(width 0.254)
		(layer "F.Cu")
		(net "PVCCIN_CPU0")
	)
	(segment
		(start 238.187738 -71.935086)
		(end 238.759238 -71.935086)
		(width 0.254)
		(layer "F.Cu")
		(net "PVCCIN_CPU0")
	)
	(segment
		(start 242.193318 -77.878686)
		(end 241.621818 -77.878686)
		(width 0.254)
		(layer "F.Cu")
		(net "PVCCIN_CPU0")
	)
	(segment
		(start 255.41224 -68.46824)
		(end 255.07061 -68.46824)
		(width 0.254)
		(layer "F.Cu")
		(net "PVCCIN_CPU0")
	)
	(segment
		(start 249.919744 -72.43064)
		(end 249.348244 -72.43064)
		(width 0.1016)
		(layer "F.Cu")
		(net "PVCCIN_CPU0")
	)
	(segment
		(start 237.042198 -76.888086)
		(end 236.470698 -76.888086)
		(width 0.254)
		(layer "F.Cu")
		(net "PVCCIN_CPU0")
	)
	(segment
		(start 254.212344 -80.850486)
		(end 253.640844 -80.850486)
		(width 0.254)
		(layer "F.Cu")
		(net "PVCCIN_CPU0")
	)
	(segment
		(start 254.212344 -71.935086)
		(end 253.640844 -71.935086)
		(width 0.254)
		(layer "F.Cu")
		(net "PVCCIN_CPU0")
	)
	(segment
		(start 254.212344 -81.841086)
		(end 253.640844 -81.841086)
		(width 0.254)
		(layer "F.Cu")
		(net "PVCCIN_CPU0")
	)
	(segment
		(start 256.78765 -84.31784)
		(end 256.78765 -83.70824)
		(width 0.254)
		(layer "F.Cu")
		(net "PVCCIN_CPU0")
	)
	(segment
		(start 255.07061 -77.38364)
		(end 255.69291 -77.38364)
		(width 0.254)
		(layer "F.Cu")
		(net "PVCCIN_CPU0")
	)
	(segment
		(start 251.636784 -73.42124)
		(end 251.065284 -73.42124)
		(width 0.254)
		(layer "F.Cu")
		(net "PVCCIN_CPU0")
	)
	(segment
		(start 272.052288 -64.324738)
		(end 272.052288 -64.954912)
		(width 0.1016)
		(layer "F.Cu")
		(net "PVCCIN_CPU0")
	)
	(segment
		(start 243.338604 -78.869286)
		(end 243.910104 -78.869286)
		(width 0.254)
		(layer "F.Cu")
		(net "PVCCIN_CPU0")
	)
	(segment
		(start 235.325158 -72.925686)
		(end 234.753658 -72.925686)
		(width 0.254)
		(layer "F.Cu")
		(net "PVCCIN_CPU0")
	)
	(segment
		(start 248.202704 -75.40244)
		(end 247.631204 -75.40244)
		(width 0.254)
		(layer "F.Cu")
		(net "PVCCIN_CPU0")
	)
	(segment
		(start 256.78765 -68.06565)
		(end 256.78765 -67.47764)
		(width 0.254)
		(layer "F.Cu")
		(net "PVCCIN_CPU0")
	)
	(segment
		(start 242.193318 -78.869286)
		(end 241.621818 -78.869286)
		(width 0.254)
		(layer "F.Cu")
		(net "PVCCIN_CPU0")
	)
	(via
		(at 262.79729 -64.581786)
		(size 0.508)
		(drill 0.254)
		(layers "F.Cu" "B.Cu")
		(net "PVCCIN_CPU0")
	)
	(via
		(at 212.725 -60.1091)
		(size 0.5588)
		(drill 0.3048)
		(layers "F.Cu" "B.Cu")
		(net "PVCCIN_CPU0")
	)
	(via
		(at 239.904778 -71.935086)
		(size 0.508)
		(drill 0.254)
		(layers "F.Cu" "B.Cu")
		(net "PVCCIN_CPU0")
	)
	(via
		(at 257.93319 -86.29904)
		(size 0.508)
		(drill 0.254)
		(layers "F.Cu" "B.Cu")
		(net "PVCCIN_CPU0")
	)
	(via
		(at 245.914164 -73.42124)
		(size 0.508)
		(drill 0.254)
		(layers "F.Cu" "B.Cu")
		(net "PVCCIN_CPU0")
	)
	(via
		(at 265.372596 -65.1256)
		(size 0.508)
		(drill 0.254)
		(layers "F.Cu" "B.Cu")
		(net "PVCCIN_CPU0")
	)
	(via
		(at 249.348244 -78.37424)
		(size 0.508)
		(drill 0.254)
		(layers "F.Cu" "B.Cu")
		(net "PVCCIN_CPU0")
	)
	(via
		(at 233.807 -75.40244)
		(size 0.508)
		(drill 0.254)
		(layers "F.Cu" "B.Cu")
		(net "PVCCIN_CPU0")
	)
	(via
		(at 209.672428 -86.316058)
		(size 0.5588)
		(drill 0.3048)
		(layers "F.Cu" "B.Cu")
		(net "PVCCIN_CPU0")
	)
	(via
		(at 253.640844 -68.963286)
		(size 0.508)
		(drill 0.254)
		(layers "F.Cu" "B.Cu")
		(net "PVCCIN_CPU0")
	)
	(via
		(at 265.372596 -87.67064)
		(size 0.508)
		(drill 0.254)
		(layers "F.Cu" "B.Cu")
		(net "PVCCIN_CPU0")
	)
	(via
		(at 249.348244 -72.43064)
		(size 0.508)
		(drill 0.254)
		(layers "F.Cu" "B.Cu")
		(net "PVCCIN_CPU0")
	)
	(via
		(at 216.251028 -71.050658)
		(size 0.5588)
		(drill 0.3048)
		(layers "F.Cu" "B.Cu")
		(net "PVCCIN_CPU0")
	)
	(via
		(at 241.621818 -77.878686)
		(size 0.508)
		(drill 0.254)
		(layers "F.Cu" "B.Cu")
		(net "PVCCIN_CPU0")
	)
	(via
		(at 210.429856 -70.48754)
		(size 0.5588)
		(drill 0.3048)
		(layers "F.Cu" "B.Cu")
		(net "PVCCIN_CPU0")
	)
	(via
		(at 260.348476 -74.401172)
		(size 0.5588)
		(drill 0.3048)
		(layers "F.Cu" "B.Cu")
		(net "PVCCIN_CPU0")
	)
	(via
		(at 256.21615 -66.48704)
		(size 0.508)
		(drill 0.254)
		(layers "F.Cu" "B.Cu")
		(net "PVCCIN_CPU0")
	)
	(via
		(at 239.904778 -70.94474)
		(size 0.508)
		(drill 0.254)
		(layers "F.Cu" "B.Cu")
		(net "PVCCIN_CPU0")
	)
	(via
		(at 210.434428 -86.316058)
		(size 0.5588)
		(drill 0.3048)
		(layers "F.Cu" "B.Cu")
		(net "PVCCIN_CPU0")
	)
	(via
		(at 278.061674 -66.421)
		(size 0.508)
		(drill 0.254)
		(layers "F.Cu" "B.Cu")
		(net "PVCCIN_CPU0")
	)
	(via
		(at 255.92913 -83.212686)
		(size 0.508)
		(drill 0.254)
		(layers "F.Cu" "B.Cu")
		(net "PVCCIN_CPU0")
	)
	(via
		(at 253.640844 -77.878686)
		(size 0.508)
		(drill 0.254)
		(layers "F.Cu" "B.Cu")
		(net "PVCCIN_CPU0")
	)
	(via
		(at 262.927338 -78.715616)
		(size 0.5588)
		(drill 0.3048)
		(layers "F.Cu" "B.Cu")
		(net "PVCCIN_CPU0")
	)
	(via
		(at 255.69291 -79.36484)
		(size 0.508)
		(drill 0.254)
		(layers "F.Cu" "B.Cu")
		(net "PVCCIN_CPU0")
	)
	(via
		(at 259.65023 -87.28964)
		(size 0.508)
		(drill 0.254)
		(layers "F.Cu" "B.Cu")
		(net "PVCCIN_CPU0")
	)
	(via
		(at 245.914164 -78.37424)
		(size 0.508)
		(drill 0.254)
		(layers "F.Cu" "B.Cu")
		(net "PVCCIN_CPU0")
	)
	(via
		(at 275.486114 -88.518238)
		(size 0.508)
		(drill 0.254)
		(layers "F.Cu" "B.Cu")
		(net "PVCCIN_CPU0")
	)
	(via
		(at 268.402308 -74.397616)
		(size 0.5588)
		(drill 0.3048)
		(layers "F.Cu" "B.Cu")
		(net "PVCCIN_CPU0")
	)
	(via
		(at 216.987628 -62.592458)
		(size 0.5588)
		(drill 0.3048)
		(layers "F.Cu" "B.Cu")
		(net "PVCCIN_CPU0")
	)
	(via
		(at 211.096606 -92.146628)
		(size 0.5588)
		(drill 0.3048)
		(layers "F.Cu" "B.Cu")
		(net "PVCCIN_CPU0")
	)
	(via
		(at 238.187738 -74.906886)
		(size 0.508)
		(drill 0.254)
		(layers "F.Cu" "B.Cu")
		(net "PVCCIN_CPU0")
	)
	(via
		(at 216.251028 -70.364858)
		(size 0.5588)
		(drill 0.3048)
		(layers "F.Cu" "B.Cu")
		(net "PVCCIN_CPU0")
	)
	(via
		(at 216.987628 -63.252858)
		(size 0.5588)
		(drill 0.3048)
		(layers "F.Cu" "B.Cu")
		(net "PVCCIN_CPU0")
	)
	(via
		(at 217.673428 -85.935058)
		(size 0.5588)
		(drill 0.3048)
		(layers "F.Cu" "B.Cu")
		(net "PVCCIN_CPU0")
	)
	(via
		(at 280.637234 -67.8942)
		(size 0.508)
		(drill 0.254)
		(layers "F.Cu" "B.Cu")
		(net "PVCCIN_CPU0")
	)
	(via
		(at 246.772684 -75.897486)
		(size 0.508)
		(drill 0.254)
		(layers "F.Cu" "B.Cu")
		(net "PVCCIN_CPU0")
	)
	(via
		(at 238.187738 -76.888086)
		(size 0.508)
		(drill 0.254)
		(layers "F.Cu" "B.Cu")
		(net "PVCCIN_CPU0")
	)
	(via
		(at 248.489724 -75.897486)
		(size 0.508)
		(drill 0.254)
		(layers "F.Cu" "B.Cu")
		(net "PVCCIN_CPU0")
	)
	(via
		(at 264.744708 -74.397616)
		(size 0.5588)
		(drill 0.3048)
		(layers "F.Cu" "B.Cu")
		(net "PVCCIN_CPU0")
	)
	(via
		(at 215.463628 -62.592458)
		(size 0.5588)
		(drill 0.3048)
		(layers "F.Cu" "B.Cu")
		(net "PVCCIN_CPU0")
	)
	(via
		(at 217.749628 -62.592458)
		(size 0.5588)
		(drill 0.3048)
		(layers "F.Cu" "B.Cu")
		(net "PVCCIN_CPU0")
	)
	(via
		(at 216.225628 -64.599058)
		(size 0.5588)
		(drill 0.3048)
		(layers "F.Cu" "B.Cu")
		(net "PVCCIN_CPU0")
	)
	(via
		(at 239.904778 -78.869286)
		(size 0.508)
		(drill 0.254)
		(layers "F.Cu" "B.Cu")
		(net "PVCCIN_CPU0")
	)
	(via
		(at 250.206764 -74.906886)
		(size 0.508)
		(drill 0.254)
		(layers "F.Cu" "B.Cu")
		(net "PVCCIN_CPU0")
	)
	(via
		(at 233.807 -73.42124)
		(size 0.508)
		(drill 0.254)
		(layers "F.Cu" "B.Cu")
		(net "PVCCIN_CPU0")
	)
	(via
		(at 213.39937 -59.49823)
		(size 0.5588)
		(drill 0.3048)
		(layers "F.Cu" "B.Cu")
		(net "PVCCIN_CPU0")
	)
	(via
		(at 249.348244 -73.42124)
		(size 0.508)
		(drill 0.254)
		(layers "F.Cu" "B.Cu")
		(net "PVCCIN_CPU0")
	)
	(via
		(at 257.07467 -65.991486)
		(size 0.508)
		(drill 0.254)
		(layers "F.Cu" "B.Cu")
		(net "PVCCIN_CPU0")
	)
	(via
		(at 222.144844 -65.856612)
		(size 0.5588)
		(drill 0.3048)
		(layers "F.Cu" "B.Cu")
		(net "PVCCIN_CPU0")
	)
	(via
		(at 248.489724 -72.925686)
		(size 0.508)
		(drill 0.254)
		(layers "F.Cu" "B.Cu")
		(net "PVCCIN_CPU0")
	)
	(via
		(at 233.895138 -82.33664)
		(size 0.508)
		(drill 0.254)
		(layers "F.Cu" "B.Cu")
		(net "PVCCIN_CPU0")
	)
	(via
		(at 211.196428 -87.078058)
		(size 0.5588)
		(drill 0.3048)
		(layers "F.Cu" "B.Cu")
		(net "PVCCIN_CPU0")
	)
	(via
		(at 208.73085 -55.274718)
		(size 0.5588)
		(drill 0.3048)
		(layers "F.Cu" "B.Cu")
		(net "PVCCIN_CPU0")
	)
	(via
		(at 210.485228 -75.825858)
		(size 0.5588)
		(drill 0.3048)
		(layers "F.Cu" "B.Cu")
		(net "PVCCIN_CPU0")
	)
	(via
		(at 211.953856 -71.14794)
		(size 0.5588)
		(drill 0.3048)
		(layers "F.Cu" "B.Cu")
		(net "PVCCIN_CPU0")
	)
	(via
		(at 216.911428 -86.697058)
		(size 0.5588)
		(drill 0.3048)
		(layers "F.Cu" "B.Cu")
		(net "PVCCIN_CPU0")
	)
	(via
		(at 251.065284 -77.38364)
		(size 0.508)
		(drill 0.254)
		(layers "F.Cu" "B.Cu")
		(net "PVCCIN_CPU0")
	)
	(via
		(at 233.807 -77.38364)
		(size 0.508)
		(drill 0.254)
		(layers "F.Cu" "B.Cu")
		(net "PVCCIN_CPU0")
	)
	(via
		(at 210.485228 -60.204858)
		(size 0.5588)
		(drill 0.3048)
		(layers "F.Cu" "B.Cu")
		(net "PVCCIN_CPU0")
	)
	(via
		(at 217.013028 -71.050658)
		(size 0.5588)
		(drill 0.3048)
		(layers "F.Cu" "B.Cu")
		(net "PVCCIN_CPU0")
	)
	(via
		(at 216.17305 -85.19287)
		(size 0.5588)
		(drill 0.3048)
		(layers "F.Cu" "B.Cu")
		(net "PVCCIN_CPU0")
	)
	(via
		(at 195.9864 -78.8924)
		(size 0.508)
		(drill 0.254)
		(layers "F.Cu" "B.Cu")
		(net "PVCCIN_CPU0")
	)
	(via
		(at 244.197124 -71.44004)
		(size 0.508)
		(drill 0.254)
		(layers "F.Cu" "B.Cu")
		(net "PVCCIN_CPU0")
	)
	(via
		(at 239.046258 -75.40244)
		(size 0.508)
		(drill 0.254)
		(layers "F.Cu" "B.Cu")
		(net "PVCCIN_CPU0")
	)
	(via
		(at 236.470698 -74.906886)
		(size 0.508)
		(drill 0.254)
		(layers "F.Cu" "B.Cu")
		(net "PVCCIN_CPU0")
	)
	(via
		(at 246.772684 -73.916286)
		(size 0.508)
		(drill 0.254)
		(layers "F.Cu" "B.Cu")
		(net "PVCCIN_CPU0")
	)
	(via
		(at 244.197124 -79.36484)
		(size 0.508)
		(drill 0.254)
		(layers "F.Cu" "B.Cu")
		(net "PVCCIN_CPU0")
	)
	(via
		(at 210.429856 -71.14794)
		(size 0.5588)
		(drill 0.3048)
		(layers "F.Cu" "B.Cu")
		(net "PVCCIN_CPU0")
	)
	(via
		(at 209.314288 -54.57571)
		(size 0.5588)
		(drill 0.3048)
		(layers "F.Cu" "B.Cu")
		(net "PVCCIN_CPU0")
	)
	(via
		(at 233.895138 -81.34604)
		(size 0.508)
		(drill 0.254)
		(layers "F.Cu" "B.Cu")
		(net "PVCCIN_CPU0")
	)
	(via
		(at 250.206764 -73.916286)
		(size 0.508)
		(drill 0.254)
		(layers "F.Cu" "B.Cu")
		(net "PVCCIN_CPU0")
	)
	(via
		(at 208.8896 -53.9496)
		(size 0.508)
		(drill 0.254)
		(layers "F.Cu" "B.Cu")
		(net "PVCCIN_CPU0")
	)
	(via
		(at 215.463628 -64.599058)
		(size 0.5588)
		(drill 0.3048)
		(layers "F.Cu" "B.Cu")
		(net "PVCCIN_CPU0")
	)
	(via
		(at 237.329218 -71.44004)
		(size 0.508)
		(drill 0.254)
		(layers "F.Cu" "B.Cu")
		(net "PVCCIN_CPU0")
	)
	(via
		(at 215.311228 -78.569058)
		(size 0.5588)
		(drill 0.3048)
		(layers "F.Cu" "B.Cu")
		(net "PVCCIN_CPU0")
	)
	(via
		(at 220.874844 -64.586612)
		(size 0.5588)
		(drill 0.3048)
		(layers "F.Cu" "B.Cu")
		(net "PVCCIN_CPU0")
	)
	(via
		(at 218.950032 -86.6394)
		(size 0.5588)
		(drill 0.3048)
		(layers "F.Cu" "B.Cu")
		(net "PVCCIN_CPU0")
	)
	(via
		(at 214.4649 -87.376)
		(size 0.5588)
		(drill 0.3048)
		(layers "F.Cu" "B.Cu")
		(net "PVCCIN_CPU0")
	)
	(via
		(at 248.489724 -77.878686)
		(size 0.508)
		(drill 0.254)
		(layers "F.Cu" "B.Cu")
		(net "PVCCIN_CPU0")
	)
	(via
		(at 209.723228 -60.865258)
		(size 0.5588)
		(drill 0.3048)
		(layers "F.Cu" "B.Cu")
		(net "PVCCIN_CPU0")
	)
	(via
		(at 215.489028 -71.050658)
		(size 0.5588)
		(drill 0.3048)
		(layers "F.Cu" "B.Cu")
		(net "PVCCIN_CPU0")
	)
	(via
		(at 258.79171 -65.000886)
		(size 0.508)
		(drill 0.254)
		(layers "F.Cu" "B.Cu")
		(net "PVCCIN_CPU0")
	)
	(via
		(at 253.640844 -81.841086)
		(size 0.508)
		(drill 0.254)
		(layers "F.Cu" "B.Cu")
		(net "PVCCIN_CPU0")
	)
	(via
		(at 210.485228 -76.511658)
		(size 0.5588)
		(drill 0.3048)
		(layers "F.Cu" "B.Cu")
		(net "PVCCIN_CPU0")
	)
	(via
		(at 215.311228 -77.908658)
		(size 0.5588)
		(drill 0.3048)
		(layers "F.Cu" "B.Cu")
		(net "PVCCIN_CPU0")
	)
	(via
		(at 253.640844 -72.925686)
		(size 0.508)
		(drill 0.254)
		(layers "F.Cu" "B.Cu")
		(net "PVCCIN_CPU0")
	)
	(via
		(at 241.621818 -72.925686)
		(size 0.508)
		(drill 0.254)
		(layers "F.Cu" "B.Cu")
		(net "PVCCIN_CPU0")
	)
	(via
		(at 272.910808 -88.022684)
		(size 0.508)
		(drill 0.254)
		(layers "F.Cu" "B.Cu")
		(net "PVCCIN_CPU0")
	)
	(via
		(at 211.953856 -69.82714)
		(size 0.5588)
		(drill 0.3048)
		(layers "F.Cu" "B.Cu")
		(net "PVCCIN_CPU0")
	)
	(via
		(at 250.206764 -75.897486)
		(size 0.508)
		(drill 0.254)
		(layers "F.Cu" "B.Cu")
		(net "PVCCIN_CPU0")
	)
	(via
		(at 212.009228 -77.197458)
		(size 0.5588)
		(drill 0.3048)
		(layers "F.Cu" "B.Cu")
		(net "PVCCIN_CPU0")
	)
	(via
		(at 238.187738 -77.878686)
		(size 0.508)
		(drill 0.254)
		(layers "F.Cu" "B.Cu")
		(net "PVCCIN_CPU0")
	)
	(via
		(at 235.612178 -75.40244)
		(size 0.508)
		(drill 0.254)
		(layers "F.Cu" "B.Cu")
		(net "PVCCIN_CPU0")
	)
	(via
		(at 234.753658 -76.888086)
		(size 0.508)
		(drill 0.254)
		(layers "F.Cu" "B.Cu")
		(net "PVCCIN_CPU0")
	)
	(via
		(at 215.387428 -87.459058)
		(size 0.5588)
		(drill 0.3048)
		(layers "F.Cu" "B.Cu")
		(net "PVCCIN_CPU0")
	)
	(via
		(at 255.69291 -82.33664)
		(size 0.508)
		(drill 0.254)
		(layers "F.Cu" "B.Cu")
		(net "PVCCIN_CPU0")
	)
	(via
		(at 241.621818 -74.906886)
		(size 0.508)
		(drill 0.254)
		(layers "F.Cu" "B.Cu")
		(net "PVCCIN_CPU0")
	)
	(via
		(at 209.672428 -87.078058)
		(size 0.5588)
		(drill 0.3048)
		(layers "F.Cu" "B.Cu")
		(net "PVCCIN_CPU0")
	)
	(via
		(at 216.149428 -87.459058)
		(size 0.5588)
		(drill 0.3048)
		(layers "F.Cu" "B.Cu")
		(net "PVCCIN_CPU0")
	)
	(via
		(at 215.463628 -63.938658)
		(size 0.5588)
		(drill 0.3048)
		(layers "F.Cu" "B.Cu")
		(net "PVCCIN_CPU0")
	)
	(via
		(at 253.640844 -83.822286)
		(size 0.508)
		(drill 0.254)
		(layers "F.Cu" "B.Cu")
		(net "PVCCIN_CPU0")
	)
	(via
		(at 265.839448 -78.71714)
		(size 0.5588)
		(drill 0.3048)
		(layers "F.Cu" "B.Cu")
		(net "PVCCIN_CPU0")
	)
	(via
		(at 255.69291 -69.45884)
		(size 0.508)
		(drill 0.254)
		(layers "F.Cu" "B.Cu")
		(net "PVCCIN_CPU0")
	)
	(via
		(at 251.923804 -76.888086)
		(size 0.508)
		(drill 0.254)
		(layers "F.Cu" "B.Cu")
		(net "PVCCIN_CPU0")
	)
	(via
		(at 266.231116 -64.581786)
		(size 0.508)
		(drill 0.254)
		(layers "F.Cu" "B.Cu")
		(net "PVCCIN_CPU0")
	)
	(via
		(at 271.193768 -64.516)
		(size 0.508)
		(drill 0.254)
		(layers "F.Cu" "B.Cu")
		(net "PVCCIN_CPU0")
	)
	(via
		(at 211.247228 -60.204858)
		(size 0.5588)
		(drill 0.3048)
		(layers "F.Cu" "B.Cu")
		(net "PVCCIN_CPU0")
	)
	(via
		(at 208.652364 -54.59095)
		(size 0.5588)
		(drill 0.3048)
		(layers "F.Cu" "B.Cu")
		(net "PVCCIN_CPU0")
	)
	(via
		(at 238.187738 -73.916286)
		(size 0.508)
		(drill 0.254)
		(layers "F.Cu" "B.Cu")
		(net "PVCCIN_CPU0")
	)
	(via
		(at 211.247228 -76.511658)
		(size 0.5588)
		(drill 0.3048)
		(layers "F.Cu" "B.Cu")
		(net "PVCCIN_CPU0")
	)
	(via
		(at 234.753658 -75.897486)
		(size 0.508)
		(drill 0.254)
		(layers "F.Cu" "B.Cu")
		(net "PVCCIN_CPU0")
	)
	(via
		(at 212.796628 -76.460858)
		(size 0.5588)
		(drill 0.3048)
		(layers "F.Cu" "B.Cu")
		(net "PVCCIN_CPU0")
	)
	(via
		(at 249.348244 -77.38364)
		(size 0.508)
		(drill 0.254)
		(layers "F.Cu" "B.Cu")
		(net "PVCCIN_CPU0")
	)
	(via
		(at 196.0118 -86.995254)
		(size 0.508)
		(drill 0.254)
		(layers "F.Cu" "B.Cu")
		(net "PVCCIN_CPU0")
	)
	(via
		(at 234.753658 -70.94474)
		(size 0.508)
		(drill 0.254)
		(layers "F.Cu" "B.Cu")
		(net "PVCCIN_CPU0")
	)
	(via
		(at 262.138668 -78.71714)
		(size 0.5588)
		(drill 0.3048)
		(layers "F.Cu" "B.Cu")
		(net "PVCCIN_CPU0")
	)
	(via
		(at 240.763298 -73.42124)
		(size 0.508)
		(drill 0.254)
		(layers "F.Cu" "B.Cu")
		(net "PVCCIN_CPU0")
	)
	(via
		(at 211.858606 -91.399614)
		(size 0.5588)
		(drill 0.3048)
		(layers "F.Cu" "B.Cu")
		(net "PVCCIN_CPU0")
	)
	(via
		(at 209.723228 -75.825858)
		(size 0.5588)
		(drill 0.3048)
		(layers "F.Cu" "B.Cu")
		(net "PVCCIN_CPU0")
	)
	(via
		(at 234.753658 -79.859886)
		(size 0.508)
		(drill 0.254)
		(layers "F.Cu" "B.Cu")
		(net "PVCCIN_CPU0")
	)
	(via
		(at 252.782324 -75.40244)
		(size 0.508)
		(drill 0.254)
		(layers "F.Cu" "B.Cu")
		(net "PVCCIN_CPU0")
	)
	(via
		(at 243.338604 -78.869286)
		(size 0.508)
		(drill 0.254)
		(layers "F.Cu" "B.Cu")
		(net "PVCCIN_CPU0")
	)
	(via
		(at 256.21615 -85.30844)
		(size 0.508)
		(drill 0.254)
		(layers "F.Cu" "B.Cu")
		(net "PVCCIN_CPU0")
	)
	(via
		(at 244.197124 -77.38364)
		(size 0.508)
		(drill 0.254)
		(layers "F.Cu" "B.Cu")
		(net "PVCCIN_CPU0")
	)
	(via
		(at 244.197124 -75.40244)
		(size 0.508)
		(drill 0.254)
		(layers "F.Cu" "B.Cu")
		(net "PVCCIN_CPU0")
	)
	(via
		(at 256.351024 -68.523358)
		(size 0.508)
		(drill 0.254)
		(layers "F.Cu" "B.Cu")
		(net "PVCCIN_CPU0")
	)
	(via
		(at 233.807 -79.23784)
		(size 0.508)
		(drill 0.254)
		(layers "F.Cu" "B.Cu")
		(net "PVCCIN_CPU0")
	)
	(via
		(at 255.69291 -81.34604)
		(size 0.508)
		(drill 0.254)
		(layers "F.Cu" "B.Cu")
		(net "PVCCIN_CPU0")
	)
	(via
		(at 263.65581 -87.67064)
		(size 0.508)
		(drill 0.254)
		(layers "F.Cu" "B.Cu")
		(net "PVCCIN_CPU0")
	)
	(via
		(at 216.251028 -69.704458)
		(size 0.5588)
		(drill 0.3048)
		(layers "F.Cu" "B.Cu")
		(net "PVCCIN_CPU0")
	)
	(via
		(at 267.635736 -74.39914)
		(size 0.5588)
		(drill 0.3048)
		(layers "F.Cu" "B.Cu")
		(net "PVCCIN_CPU0")
	)
	(via
		(at 255.69291 -71.44004)
		(size 0.508)
		(drill 0.254)
		(layers "F.Cu" "B.Cu")
		(net "PVCCIN_CPU0")
	)
	(via
		(at 272.052288 -64.954912)
		(size 0.508)
		(drill 0.254)
		(layers "F.Cu" "B.Cu")
		(net "PVCCIN_CPU0")
	)
	(via
		(at 278.920194 -87.527638)
		(size 0.508)
		(drill 0.254)
		(layers "F.Cu" "B.Cu")
		(net "PVCCIN_CPU0")
	)
	(via
		(at 245.055644 -74.906886)
		(size 0.508)
		(drill 0.254)
		(layers "F.Cu" "B.Cu")
		(net "PVCCIN_CPU0")
	)
	(via
		(at 224.030032 -81.5594)
		(size 0.508)
		(drill 0.254)
		(layers "F.Cu" "B.Cu")
		(net "PVCCIN_CPU0")
	)
	(via
		(at 215.489028 -70.364858)
		(size 0.5588)
		(drill 0.3048)
		(layers "F.Cu" "B.Cu")
		(net "PVCCIN_CPU0")
	)
	(via
		(at 261.08025 -65.6336)
		(size 0.508)
		(drill 0.254)
		(layers "F.Cu" "B.Cu")
		(net "PVCCIN_CPU0")
	)
	(via
		(at 215.311228 -79.915258)
		(size 0.5588)
		(drill 0.3048)
		(layers "F.Cu" "B.Cu")
		(net "PVCCIN_CPU0")
	)
	(via
		(at 211.958428 -85.604858)
		(size 0.5588)
		(drill 0.3048)
		(layers "F.Cu" "B.Cu")
		(net "PVCCIN_CPU0")
	)
	(via
		(at 233.895138 -70.44944)
		(size 0.508)
		(drill 0.254)
		(layers "F.Cu" "B.Cu")
		(net "PVCCIN_CPU0")
	)
	(via
		(at 255.69291 -77.38364)
		(size 0.508)
		(drill 0.254)
		(layers "F.Cu" "B.Cu")
		(net "PVCCIN_CPU0")
	)
	(via
		(at 244.197124 -73.42124)
		(size 0.508)
		(drill 0.254)
		(layers "F.Cu" "B.Cu")
		(net "PVCCIN_CPU0")
	)
	(via
		(at 217.673428 -86.697058)
		(size 0.5588)
		(drill 0.3048)
		(layers "F.Cu" "B.Cu")
		(net "PVCCIN_CPU0")
	)
	(via
		(at 253.640844 -74.906886)
		(size 0.508)
		(drill 0.254)
		(layers "F.Cu" "B.Cu")
		(net "PVCCIN_CPU0")
	)
	(via
		(at 237.329218 -73.42124)
		(size 0.508)
		(drill 0.254)
		(layers "F.Cu" "B.Cu")
		(net "PVCCIN_CPU0")
	)
	(via
		(at 245.055644 -77.878686)
		(size 0.508)
		(drill 0.254)
		(layers "F.Cu" "B.Cu")
		(net "PVCCIN_CPU0")
	)
	(via
		(at 238.187738 -75.897486)
		(size 0.508)
		(drill 0.254)
		(layers "F.Cu" "B.Cu")
		(net "PVCCIN_CPU0")
	)
	(via
		(at 216.911428 -87.459058)
		(size 0.5588)
		(drill 0.3048)
		(layers "F.Cu" "B.Cu")
		(net "PVCCIN_CPU0")
	)
	(via
		(at 254.49911 -84.31784)
		(size 0.508)
		(drill 0.254)
		(layers "F.Cu" "B.Cu")
		(net "PVCCIN_CPU0")
	)
	(via
		(at 239.904778 -74.906886)
		(size 0.508)
		(drill 0.254)
		(layers "F.Cu" "B.Cu")
		(net "PVCCIN_CPU0")
	)
	(via
		(at 252.782324 -73.42124)
		(size 0.508)
		(drill 0.254)
		(layers "F.Cu" "B.Cu")
		(net "PVCCIN_CPU0")
	)
	(via
		(at 277.203154 -65.9384)
		(size 0.508)
		(drill 0.254)
		(layers "F.Cu" "B.Cu")
		(net "PVCCIN_CPU0")
	)
	(via
		(at 211.096606 -91.399614)
		(size 0.5588)
		(drill 0.3048)
		(layers "F.Cu" "B.Cu")
		(net "PVCCIN_CPU0")
	)
	(via
		(at 215.387428 -86.697058)
		(size 0.5588)
		(drill 0.3048)
		(layers "F.Cu" "B.Cu")
		(net "PVCCIN_CPU0")
	)
	(via
		(at 221.490032 -84.0994)
		(size 0.5588)
		(drill 0.3048)
		(layers "F.Cu" "B.Cu")
		(net "PVCCIN_CPU0")
	)
	(via
		(at 232.918 -70.104)
		(size 0.508)
		(drill 0.254)
		(layers "F.Cu" "B.Cu")
		(net "PVCCIN_CPU0")
	)
	(via
		(at 216.93505 -85.19287)
		(size 0.5588)
		(drill 0.3048)
		(layers "F.Cu" "B.Cu")
		(net "PVCCIN_CPU0")
	)
	(via
		(at 264.003282 -78.71714)
		(size 0.5588)
		(drill 0.3048)
		(layers "F.Cu" "B.Cu")
		(net "PVCCIN_CPU0")
	)
	(via
		(at 209.629502 -58.865262)
		(size 0.5588)
		(drill 0.3048)
		(layers "F.Cu" "B.Cu")
		(net "PVCCIN_CPU0")
	)
	(via
		(at 217.013028 -70.364858)
		(size 0.5588)
		(drill 0.3048)
		(layers "F.Cu" "B.Cu")
		(net "PVCCIN_CPU0")
	)
	(via
		(at 235.612178 -73.42124)
		(size 0.508)
		(drill 0.254)
		(layers "F.Cu" "B.Cu")
		(net "PVCCIN_CPU0")
	)
	(via
		(at 210.139788 -55.22722)
		(size 0.5588)
		(drill 0.3048)
		(layers "F.Cu" "B.Cu")
		(net "PVCCIN_CPU0")
	)
	(via
		(at 261.08025 -86.184486)
		(size 0.508)
		(drill 0.254)
		(layers "F.Cu" "B.Cu")
		(net "PVCCIN_CPU0")
	)
	(via
		(at 246.772684 -72.925686)
		(size 0.508)
		(drill 0.254)
		(layers "F.Cu" "B.Cu")
		(net "PVCCIN_CPU0")
	)
	(via
		(at 256.78765 -83.70824)
		(size 0.508)
		(drill 0.254)
		(layers "F.Cu" "B.Cu")
		(net "PVCCIN_CPU0")
	)
	(via
		(at 209.723228 -77.197458)
		(size 0.5588)
		(drill 0.3048)
		(layers "F.Cu" "B.Cu")
		(net "PVCCIN_CPU0")
	)
	(via
		(at 278.920194 -66.9036)
		(size 0.508)
		(drill 0.254)
		(layers "F.Cu" "B.Cu")
		(net "PVCCIN_CPU0")
	)
	(via
		(at 209.723228 -75.063858)
		(size 0.5588)
		(drill 0.3048)
		(layers "F.Cu" "B.Cu")
		(net "PVCCIN_CPU0")
	)
	(via
		(at 233.895138 -71.44004)
		(size 0.508)
		(drill 0.254)
		(layers "F.Cu" "B.Cu")
		(net "PVCCIN_CPU0")
	)
	(via
		(at 247.631204 -72.43064)
		(size 0.508)
		(drill 0.254)
		(layers "F.Cu" "B.Cu")
		(net "PVCCIN_CPU0")
	)
	(via
		(at 245.914164 -77.38364)
		(size 0.508)
		(drill 0.254)
		(layers "F.Cu" "B.Cu")
		(net "PVCCIN_CPU0")
	)
	(via
		(at 209.723228 -76.511658)
		(size 0.5588)
		(drill 0.3048)
		(layers "F.Cu" "B.Cu")
		(net "PVCCIN_CPU0")
	)
	(via
		(at 211.953856 -70.48754)
		(size 0.5588)
		(drill 0.3048)
		(layers "F.Cu" "B.Cu")
		(net "PVCCIN_CPU0")
	)
	(via
		(at 243.338604 -72.925686)
		(size 0.508)
		(drill 0.254)
		(layers "F.Cu" "B.Cu")
		(net "PVCCIN_CPU0")
	)
	(via
		(at 243.338604 -77.878686)
		(size 0.508)
		(drill 0.254)
		(layers "F.Cu" "B.Cu")
		(net "PVCCIN_CPU0")
	)
	(via
		(at 208.905856 -70.48754)
		(size 0.5588)
		(drill 0.3048)
		(layers "F.Cu" "B.Cu")
		(net "PVCCIN_CPU0")
	)
	(via
		(at 267.612876 -78.71714)
		(size 0.5588)
		(drill 0.3048)
		(layers "F.Cu" "B.Cu")
		(net "PVCCIN_CPU0")
	)
	(via
		(at 252.782324 -70.44944)
		(size 0.508)
		(drill 0.254)
		(layers "F.Cu" "B.Cu")
		(net "PVCCIN_CPU0")
	)
	(via
		(at 236.470698 -72.925686)
		(size 0.508)
		(drill 0.254)
		(layers "F.Cu" "B.Cu")
		(net "PVCCIN_CPU0")
	)
	(via
		(at 246.772684 -74.906886)
		(size 0.508)
		(drill 0.254)
		(layers "F.Cu" "B.Cu")
		(net "PVCCIN_CPU0")
	)
	(via
		(at 237.329218 -75.40244)
		(size 0.508)
		(drill 0.254)
		(layers "F.Cu" "B.Cu")
		(net "PVCCIN_CPU0")
	)
	(via
		(at 267.089636 -65.151)
		(size 0.508)
		(drill 0.254)
		(layers "F.Cu" "B.Cu")
		(net "PVCCIN_CPU0")
	)
	(via
		(at 210.649058 -54.54396)
		(size 0.5588)
		(drill 0.3048)
		(layers "F.Cu" "B.Cu")
		(net "PVCCIN_CPU0")
	)
	(via
		(at 212.009228 -60.166758)
		(size 0.5588)
		(drill 0.3048)
		(layers "F.Cu" "B.Cu")
		(net "PVCCIN_CPU0")
	)
	(via
		(at 275.844 -67.2846)
		(size 0.5588)
		(drill 0.3048)
		(layers "F.Cu" "B.Cu")
		(net "PVCCIN_CPU0")
	)
	(via
		(at 252.782324 -72.43064)
		(size 0.508)
		(drill 0.254)
		(layers "F.Cu" "B.Cu")
		(net "PVCCIN_CPU0")
	)
	(via
		(at 212.725 -59.4487)
		(size 0.5588)
		(drill 0.3048)
		(layers "F.Cu" "B.Cu")
		(net "PVCCIN_CPU0")
	)
	(via
		(at 272.052288 -88.518238)
		(size 0.508)
		(drill 0.254)
		(layers "F.Cu" "B.Cu")
		(net "PVCCIN_CPU0")
	)
	(via
		(at 210.434428 -87.078058)
		(size 0.5588)
		(drill 0.3048)
		(layers "F.Cu" "B.Cu")
		(net "PVCCIN_CPU0")
	)
	(via
		(at 247.631204 -73.42124)
		(size 0.508)
		(drill 0.254)
		(layers "F.Cu" "B.Cu")
		(net "PVCCIN_CPU0")
	)
	(via
		(at 216.073228 -79.915258)
		(size 0.5588)
		(drill 0.3048)
		(layers "F.Cu" "B.Cu")
		(net "PVCCIN_CPU0")
	)
	(via
		(at 216.225628 -63.938658)
		(size 0.5588)
		(drill 0.3048)
		(layers "F.Cu" "B.Cu")
		(net "PVCCIN_CPU0")
	)
	(via
		(at 217.749628 -63.938658)
		(size 0.5588)
		(drill 0.3048)
		(layers "F.Cu" "B.Cu")
		(net "PVCCIN_CPU0")
	)
	(via
		(at 212.665056 -70.48754)
		(size 0.5588)
		(drill 0.3048)
		(layers "F.Cu" "B.Cu")
		(net "PVCCIN_CPU0")
	)
	(via
		(at 240.763298 -75.40244)
		(size 0.508)
		(drill 0.254)
		(layers "F.Cu" "B.Cu")
		(net "PVCCIN_CPU0")
	)
	(via
		(at 211.247228 -60.865258)
		(size 0.5588)
		(drill 0.3048)
		(layers "F.Cu" "B.Cu")
		(net "PVCCIN_CPU0")
	)
	(via
		(at 239.904778 -73.916286)
		(size 0.508)
		(drill 0.254)
		(layers "F.Cu" "B.Cu")
		(net "PVCCIN_CPU0")
	)
	(via
		(at 236.470698 -75.897486)
		(size 0.508)
		(drill 0.254)
		(layers "F.Cu" "B.Cu")
		(net "PVCCIN_CPU0")
	)
	(via
		(at 233.807 -74.411586)
		(size 0.508)
		(drill 0.254)
		(layers "F.Cu" "B.Cu")
		(net "PVCCIN_CPU0")
	)
	(via
		(at 212.796628 -77.197458)
		(size 0.5588)
		(drill 0.3048)
		(layers "F.Cu" "B.Cu")
		(net "PVCCIN_CPU0")
	)
	(via
		(at 217.013028 -69.704458)
		(size 0.5588)
		(drill 0.3048)
		(layers "F.Cu" "B.Cu")
		(net "PVCCIN_CPU0")
	)
	(via
		(at 263.952228 -74.401426)
		(size 0.5588)
		(drill 0.3048)
		(layers "F.Cu" "B.Cu")
		(net "PVCCIN_CPU0")
	)
	(via
		(at 211.191856 -71.14794)
		(size 0.5588)
		(drill 0.3048)
		(layers "F.Cu" "B.Cu")
		(net "PVCCIN_CPU0")
	)
	(via
		(at 217.775028 -70.364858)
		(size 0.5588)
		(drill 0.3048)
		(layers "F.Cu" "B.Cu")
		(net "PVCCIN_CPU0")
	)
	(via
		(at 245.055644 -76.888086)
		(size 0.508)
		(drill 0.254)
		(layers "F.Cu" "B.Cu")
		(net "PVCCIN_CPU0")
	)
	(via
		(at 209.667856 -71.14794)
		(size 0.5588)
		(drill 0.3048)
		(layers "F.Cu" "B.Cu")
		(net "PVCCIN_CPU0")
	)
	(via
		(at 208.905856 -69.82714)
		(size 0.5588)
		(drill 0.3048)
		(layers "F.Cu" "B.Cu")
		(net "PVCCIN_CPU0")
	)
	(via
		(at 195.9991 -62.598554)
		(size 0.508)
		(drill 0.254)
		(layers "F.Cu" "B.Cu")
		(net "PVCCIN_CPU0")
	)
	(via
		(at 211.958428 -86.316058)
		(size 0.5588)
		(drill 0.3048)
		(layers "F.Cu" "B.Cu")
		(net "PVCCIN_CPU0")
	)
	(via
		(at 215.6206 -55.118)
		(size 0.6604)
		(drill 0.3302)
		(layers "F.Cu" "B.Cu")
		(net "PVCCIN_CPU0")
	)
	(via
		(at 261.93877 -65.1256)
		(size 0.508)
		(drill 0.254)
		(layers "F.Cu" "B.Cu")
		(net "PVCCIN_CPU0")
	)
	(via
		(at 236.470698 -77.878686)
		(size 0.508)
		(drill 0.254)
		(layers "F.Cu" "B.Cu")
		(net "PVCCIN_CPU0")
	)
	(via
		(at 238.187738 -71.935086)
		(size 0.508)
		(drill 0.254)
		(layers "F.Cu" "B.Cu")
		(net "PVCCIN_CPU0")
	)
	(via
		(at 217.749628 -64.599058)
		(size 0.5588)
		(drill 0.3048)
		(layers "F.Cu" "B.Cu")
		(net "PVCCIN_CPU0")
	)
	(via
		(at 241.621818 -71.935086)
		(size 0.508)
		(drill 0.254)
		(layers "F.Cu" "B.Cu")
		(net "PVCCIN_CPU0")
	)
	(via
		(at 217.69705 -85.19287)
		(size 0.5588)
		(drill 0.3048)
		(layers "F.Cu" "B.Cu")
		(net "PVCCIN_CPU0")
	)
	(via
		(at 213.376256 -70.48754)
		(size 0.5588)
		(drill 0.3048)
		(layers "F.Cu" "B.Cu")
		(net "PVCCIN_CPU0")
	)
	(via
		(at 216.835228 -79.915258)
		(size 0.5588)
		(drill 0.3048)
		(layers "F.Cu" "B.Cu")
		(net "PVCCIN_CPU0")
	)
	(via
		(at 236.470698 -79.859886)
		(size 0.508)
		(drill 0.254)
		(layers "F.Cu" "B.Cu")
		(net "PVCCIN_CPU0")
	)
	(via
		(at 242.480338 -77.38364)
		(size 0.508)
		(drill 0.254)
		(layers "F.Cu" "B.Cu")
		(net "PVCCIN_CPU0")
	)
	(via
		(at 217.775028 -71.711058)
		(size 0.5588)
		(drill 0.3048)
		(layers "F.Cu" "B.Cu")
		(net "PVCCIN_CPU0")
	)
	(via
		(at 211.191856 -69.82714)
		(size 0.5588)
		(drill 0.3048)
		(layers "F.Cu" "B.Cu")
		(net "PVCCIN_CPU0")
	)
	(via
		(at 233.807 -72.517)
		(size 0.508)
		(drill 0.254)
		(layers "F.Cu" "B.Cu")
		(net "PVCCIN_CPU0")
	)
	(via
		(at 237.329218 -77.38364)
		(size 0.508)
		(drill 0.254)
		(layers "F.Cu" "B.Cu")
		(net "PVCCIN_CPU0")
	)
	(via
		(at 253.640844 -79.859886)
		(size 0.508)
		(drill 0.254)
		(layers "F.Cu" "B.Cu")
		(net "PVCCIN_CPU0")
	)
	(via
		(at 261.087108 -74.397616)
		(size 0.5588)
		(drill 0.3048)
		(layers "F.Cu" "B.Cu")
		(net "PVCCIN_CPU0")
	)
	(via
		(at 211.398104 -54.547516)
		(size 0.5588)
		(drill 0.3048)
		(layers "F.Cu" "B.Cu")
		(net "PVCCIN_CPU0")
	)
	(via
		(at 258.47802 -74.39914)
		(size 0.5588)
		(drill 0.3048)
		(layers "F.Cu" "B.Cu")
		(net "PVCCIN_CPU0")
	)
	(via
		(at 208.810606 -92.146628)
		(size 0.5588)
		(drill 0.3048)
		(layers "F.Cu" "B.Cu")
		(net "PVCCIN_CPU0")
	)
	(via
		(at 274.627848 -65.4304)
		(size 0.508)
		(drill 0.254)
		(layers "F.Cu" "B.Cu")
		(net "PVCCIN_CPU0")
	)
	(via
		(at 224.684844 -68.396612)
		(size 0.5588)
		(drill 0.3048)
		(layers "F.Cu" "B.Cu")
		(net "PVCCIN_CPU0")
	)
	(via
		(at 239.904778 -77.878686)
		(size 0.508)
		(drill 0.254)
		(layers "F.Cu" "B.Cu")
		(net "PVCCIN_CPU0")
	)
	(via
		(at 251.923804 -72.925686)
		(size 0.508)
		(drill 0.254)
		(layers "F.Cu" "B.Cu")
		(net "PVCCIN_CPU0")
	)
	(via
		(at 225.954844 -69.666612)
		(size 0.5588)
		(drill 0.3048)
		(layers "F.Cu" "B.Cu")
		(net "PVCCIN_CPU0")
	)
	(via
		(at 267.089636 -87.67064)
		(size 0.508)
		(drill 0.254)
		(layers "F.Cu" "B.Cu")
		(net "PVCCIN_CPU0")
	)
	(via
		(at 213.431628 -86.417658)
		(size 0.5588)
		(drill 0.3048)
		(layers "F.Cu" "B.Cu")
		(net "PVCCIN_CPU0")
	)
	(via
		(at 245.914164 -72.43064)
		(size 0.508)
		(drill 0.254)
		(layers "F.Cu" "B.Cu")
		(net "PVCCIN_CPU0")
	)
	(via
		(at 255.69291 -70.44944)
		(size 0.508)
		(drill 0.254)
		(layers "F.Cu" "B.Cu")
		(net "PVCCIN_CPU0")
	)
	(via
		(at 212.0138 -59.4868)
		(size 0.5588)
		(drill 0.3048)
		(layers "F.Cu" "B.Cu")
		(net "PVCCIN_CPU0")
	)
	(via
		(at 255.69291 -72.43064)
		(size 0.508)
		(drill 0.254)
		(layers "F.Cu" "B.Cu")
		(net "PVCCIN_CPU0")
	)
	(via
		(at 255.69291 -80.35544)
		(size 0.508)
		(drill 0.254)
		(layers "F.Cu" "B.Cu")
		(net "PVCCIN_CPU0")
	)
	(via
		(at 214.6427 -58.2676)
		(size 0.5588)
		(drill 0.3048)
		(layers "F.Cu" "B.Cu")
		(net "PVCCIN_CPU0")
	)
	(via
		(at 212.665056 -69.82714)
		(size 0.5588)
		(drill 0.3048)
		(layers "F.Cu" "B.Cu")
		(net "PVCCIN_CPU0")
	)
	(via
		(at 255.69291 -73.42124)
		(size 0.508)
		(drill 0.254)
		(layers "F.Cu" "B.Cu")
		(net "PVCCIN_CPU0")
	)
	(via
		(at 256.8194 -68.0974)
		(size 0.508)
		(drill 0.254)
		(layers "F.Cu" "B.Cu")
		(net "PVCCIN_CPU0")
	)
	(via
		(at 210.334606 -91.399614)
		(size 0.5588)
		(drill 0.3048)
		(layers "F.Cu" "B.Cu")
		(net "PVCCIN_CPU0")
	)
	(via
		(at 265.754104 -74.39914)
		(size 0.5588)
		(drill 0.3048)
		(layers "F.Cu" "B.Cu")
		(net "PVCCIN_CPU0")
	)
	(via
		(at 251.065284 -72.43064)
		(size 0.508)
		(drill 0.254)
		(layers "F.Cu" "B.Cu")
		(net "PVCCIN_CPU0")
	)
	(via
		(at 252.782324 -80.35544)
		(size 0.508)
		(drill 0.254)
		(layers "F.Cu" "B.Cu")
		(net "PVCCIN_CPU0")
	)
	(via
		(at 242.480338 -71.44004)
		(size 0.508)
		(drill 0.254)
		(layers "F.Cu" "B.Cu")
		(net "PVCCIN_CPU0")
	)
	(via
		(at 273.769328 -88.518238)
		(size 0.508)
		(drill 0.254)
		(layers "F.Cu" "B.Cu")
		(net "PVCCIN_CPU0")
	)
	(via
		(at 213.457028 -85.706458)
		(size 0.5588)
		(drill 0.3048)
		(layers "F.Cu" "B.Cu")
		(net "PVCCIN_CPU0")
	)
	(via
		(at 217.673428 -87.459058)
		(size 0.5588)
		(drill 0.3048)
		(layers "F.Cu" "B.Cu")
		(net "PVCCIN_CPU0")
	)
	(via
		(at 252.782324 -71.44004)
		(size 0.508)
		(drill 0.254)
		(layers "F.Cu" "B.Cu")
		(net "PVCCIN_CPU0")
	)
	(via
		(at 235.612178 -79.36484)
		(size 0.508)
		(drill 0.254)
		(layers "F.Cu" "B.Cu")
		(net "PVCCIN_CPU0")
	)
	(via
		(at 215.311228 -79.254858)
		(size 0.5588)
		(drill 0.3048)
		(layers "F.Cu" "B.Cu")
		(net "PVCCIN_CPU0")
	)
	(via
		(at 241.621818 -76.888086)
		(size 0.508)
		(drill 0.254)
		(layers "F.Cu" "B.Cu")
		(net "PVCCIN_CPU0")
	)
	(via
		(at 232.960418 -81.841086)
		(size 0.508)
		(drill 0.254)
		(layers "F.Cu" "B.Cu")
		(net "PVCCIN_CPU0")
	)
	(via
		(at 250.206764 -72.925686)
		(size 0.508)
		(drill 0.254)
		(layers "F.Cu" "B.Cu")
		(net "PVCCIN_CPU0")
	)
	(via
		(at 251.923804 -74.906886)
		(size 0.508)
		(drill 0.254)
		(layers "F.Cu" "B.Cu")
		(net "PVCCIN_CPU0")
	)
	(via
		(at 209.667856 -70.48754)
		(size 0.5588)
		(drill 0.3048)
		(layers "F.Cu" "B.Cu")
		(net "PVCCIN_CPU0")
	)
	(via
		(at 212.695028 -87.090758)
		(size 0.5588)
		(drill 0.3048)
		(layers "F.Cu" "B.Cu")
		(net "PVCCIN_CPU0")
	)
	(via
		(at 213.376256 -71.14794)
		(size 0.5588)
		(drill 0.3048)
		(layers "F.Cu" "B.Cu")
		(net "PVCCIN_CPU0")
	)
	(via
		(at 239.904778 -72.925686)
		(size 0.508)
		(drill 0.254)
		(layers "F.Cu" "B.Cu")
		(net "PVCCIN_CPU0")
	)
	(via
		(at 252.782324 -78.37424)
		(size 0.508)
		(drill 0.254)
		(layers "F.Cu" "B.Cu")
		(net "PVCCIN_CPU0")
	)
	(via
		(at 236.470698 -70.94474)
		(size 0.508)
		(drill 0.254)
		(layers "F.Cu" "B.Cu")
		(net "PVCCIN_CPU0")
	)
	(via
		(at 236.470698 -76.888086)
		(size 0.508)
		(drill 0.254)
		(layers "F.Cu" "B.Cu")
		(net "PVCCIN_CPU0")
	)
	(via
		(at 235.612178 -77.38364)
		(size 0.508)
		(drill 0.254)
		(layers "F.Cu" "B.Cu")
		(net "PVCCIN_CPU0")
	)
	(via
		(at 259.36321 -66.6242)
		(size 0.508)
		(drill 0.254)
		(layers "F.Cu" "B.Cu")
		(net "PVCCIN_CPU0")
	)
	(via
		(at 262.79729 -87.175086)
		(size 0.508)
		(drill 0.254)
		(layers "F.Cu" "B.Cu")
		(net "PVCCIN_CPU0")
	)
	(via
		(at 208.961228 -59.519058)
		(size 0.5588)
		(drill 0.3048)
		(layers "F.Cu" "B.Cu")
		(net "PVCCIN_CPU0")
	)
	(via
		(at 251.065284 -78.37424)
		(size 0.508)
		(drill 0.254)
		(layers "F.Cu" "B.Cu")
		(net "PVCCIN_CPU0")
	)
	(via
		(at 255.35763 -84.812886)
		(size 0.508)
		(drill 0.254)
		(layers "F.Cu" "B.Cu")
		(net "PVCCIN_CPU0")
	)
	(via
		(at 214.4522 -79.3623)
		(size 0.5588)
		(drill 0.3048)
		(layers "F.Cu" "B.Cu")
		(net "PVCCIN_CPU0")
	)
	(via
		(at 215.463628 -63.252858)
		(size 0.5588)
		(drill 0.3048)
		(layers "F.Cu" "B.Cu")
		(net "PVCCIN_CPU0")
	)
	(via
		(at 260.13156 -78.71714)
		(size 0.5588)
		(drill 0.3048)
		(layers "F.Cu" "B.Cu")
		(net "PVCCIN_CPU0")
	)
	(via
		(at 253.640844 -71.935086)
		(size 0.508)
		(drill 0.254)
		(layers "F.Cu" "B.Cu")
		(net "PVCCIN_CPU0")
	)
	(via
		(at 208.961228 -75.825858)
		(size 0.5588)
		(drill 0.3048)
		(layers "F.Cu" "B.Cu")
		(net "PVCCIN_CPU0")
	)
	(via
		(at 253.640844 -69.953886)
		(size 0.508)
		(drill 0.254)
		(layers "F.Cu" "B.Cu")
		(net "PVCCIN_CPU0")
	)
	(via
		(at 264.756138 -78.715616)
		(size 0.5588)
		(drill 0.3048)
		(layers "F.Cu" "B.Cu")
		(net "PVCCIN_CPU0")
	)
	(via
		(at 195.9991 -70.726554)
		(size 0.508)
		(drill 0.254)
		(layers "F.Cu" "B.Cu")
		(net "PVCCIN_CPU0")
	)
	(via
		(at 238.187738 -79.859886)
		(size 0.508)
		(drill 0.254)
		(layers "F.Cu" "B.Cu")
		(net "PVCCIN_CPU0")
	)
	(via
		(at 208.810606 -91.384628)
		(size 0.5588)
		(drill 0.3048)
		(layers "F.Cu" "B.Cu")
		(net "PVCCIN_CPU0")
	)
	(via
		(at 233.807 -76.39304)
		(size 0.508)
		(drill 0.254)
		(layers "F.Cu" "B.Cu")
		(net "PVCCIN_CPU0")
	)
	(via
		(at 212.009228 -76.511658)
		(size 0.5588)
		(drill 0.3048)
		(layers "F.Cu" "B.Cu")
		(net "PVCCIN_CPU0")
	)
	(via
		(at 211.196428 -85.604858)
		(size 0.5588)
		(drill 0.3048)
		(layers "F.Cu" "B.Cu")
		(net "PVCCIN_CPU0")
	)
	(via
		(at 210.485228 -60.865258)
		(size 0.5588)
		(drill 0.3048)
		(layers "F.Cu" "B.Cu")
		(net "PVCCIN_CPU0")
	)
	(via
		(at 240.763298 -71.44004)
		(size 0.508)
		(drill 0.254)
		(layers "F.Cu" "B.Cu")
		(net "PVCCIN_CPU0")
	)
	(via
		(at 258.50469 -67.1322)
		(size 0.508)
		(drill 0.254)
		(layers "F.Cu" "B.Cu")
		(net "PVCCIN_CPU0")
	)
	(via
		(at 246.772684 -77.878686)
		(size 0.508)
		(drill 0.254)
		(layers "F.Cu" "B.Cu")
		(net "PVCCIN_CPU0")
	)
	(via
		(at 235.612178 -71.44004)
		(size 0.508)
		(drill 0.254)
		(layers "F.Cu" "B.Cu")
		(net "PVCCIN_CPU0")
	)
	(via
		(at 216.149428 -86.697058)
		(size 0.5588)
		(drill 0.3048)
		(layers "F.Cu" "B.Cu")
		(net "PVCCIN_CPU0")
	)
	(via
		(at 214.4776 -71.247)
		(size 0.5588)
		(drill 0.3048)
		(layers "F.Cu" "B.Cu")
		(net "PVCCIN_CPU0")
	)
	(via
		(at 279.778714 -67.4116)
		(size 0.508)
		(drill 0.254)
		(layers "F.Cu" "B.Cu")
		(net "PVCCIN_CPU0")
	)
	(via
		(at 217.597228 -78.569058)
		(size 0.5588)
		(drill 0.3048)
		(layers "F.Cu" "B.Cu")
		(net "PVCCIN_CPU0")
	)
	(via
		(at 211.858606 -92.146628)
		(size 0.5588)
		(drill 0.3048)
		(layers "F.Cu" "B.Cu")
		(net "PVCCIN_CPU0")
	)
	(via
		(at 253.640844 -73.916286)
		(size 0.508)
		(drill 0.254)
		(layers "F.Cu" "B.Cu")
		(net "PVCCIN_CPU0")
	)
	(via
		(at 245.914164 -75.40244)
		(size 0.508)
		(drill 0.254)
		(layers "F.Cu" "B.Cu")
		(net "PVCCIN_CPU0")
	)
	(via
		(at 239.046258 -77.38364)
		(size 0.508)
		(drill 0.254)
		(layers "F.Cu" "B.Cu")
		(net "PVCCIN_CPU0")
	)
	(via
		(at 247.631204 -77.38364)
		(size 0.508)
		(drill 0.254)
		(layers "F.Cu" "B.Cu")
		(net "PVCCIN_CPU0")
	)
	(via
		(at 267.948156 -64.643)
		(size 0.508)
		(drill 0.254)
		(layers "F.Cu" "B.Cu")
		(net "PVCCIN_CPU0")
	)
	(via
		(at 253.640844 -75.897486)
		(size 0.508)
		(drill 0.254)
		(layers "F.Cu" "B.Cu")
		(net "PVCCIN_CPU0")
	)
	(via
		(at 248.489724 -73.916286)
		(size 0.508)
		(drill 0.254)
		(layers "F.Cu" "B.Cu")
		(net "PVCCIN_CPU0")
	)
	(via
		(at 209.572606 -91.399614)
		(size 0.5588)
		(drill 0.3048)
		(layers "F.Cu" "B.Cu")
		(net "PVCCIN_CPU0")
	)
	(via
		(at 275.876004 -86.044532)
		(size 0.5588)
		(drill 0.3048)
		(layers "F.Cu" "B.Cu")
		(net "PVCCIN_CPU0")
	)
	(via
		(at 234.753658 -77.878686)
		(size 0.508)
		(drill 0.254)
		(layers "F.Cu" "B.Cu")
		(net "PVCCIN_CPU0")
	)
	(via
		(at 241.621818 -70.94474)
		(size 0.508)
		(drill 0.254)
		(layers "F.Cu" "B.Cu")
		(net "PVCCIN_CPU0")
	)
	(via
		(at 243.338604 -75.897486)
		(size 0.508)
		(drill 0.254)
		(layers "F.Cu" "B.Cu")
		(net "PVCCIN_CPU0")
	)
	(via
		(at 216.073228 -78.569058)
		(size 0.5588)
		(drill 0.3048)
		(layers "F.Cu" "B.Cu")
		(net "PVCCIN_CPU0")
	)
	(via
		(at 210.434428 -85.604858)
		(size 0.5588)
		(drill 0.3048)
		(layers "F.Cu" "B.Cu")
		(net "PVCCIN_CPU0")
	)
	(via
		(at 239.046258 -71.44004)
		(size 0.508)
		(drill 0.254)
		(layers "F.Cu" "B.Cu")
		(net "PVCCIN_CPU0")
	)
	(via
		(at 266.573508 -74.397616)
		(size 0.5588)
		(drill 0.3048)
		(layers "F.Cu" "B.Cu")
		(net "PVCCIN_CPU0")
	)
	(via
		(at 255.69291 -74.411586)
		(size 0.508)
		(drill 0.254)
		(layers "F.Cu" "B.Cu")
		(net "PVCCIN_CPU0")
	)
	(via
		(at 255.35763 -66.982086)
		(size 0.508)
		(drill 0.254)
		(layers "F.Cu" "B.Cu")
		(net "PVCCIN_CPU0")
	)
	(via
		(at 257.64617 -84.203286)
		(size 0.508)
		(drill 0.254)
		(layers "F.Cu" "B.Cu")
		(net "PVCCIN_CPU0")
	)
	(via
		(at 216.987628 -63.938658)
		(size 0.5588)
		(drill 0.3048)
		(layers "F.Cu" "B.Cu")
		(net "PVCCIN_CPU0")
	)
	(via
		(at 233.807 -78.37424)
		(size 0.508)
		(drill 0.254)
		(layers "F.Cu" "B.Cu")
		(net "PVCCIN_CPU0")
	)
	(via
		(at 208.961228 -75.063858)
		(size 0.5588)
		(drill 0.3048)
		(layers "F.Cu" "B.Cu")
		(net "PVCCIN_CPU0")
	)
	(via
		(at 258.79171 -86.794086)
		(size 0.508)
		(drill 0.254)
		(layers "F.Cu" "B.Cu")
		(net "PVCCIN_CPU0")
	)
	(via
		(at 261.146544 -78.69301)
		(size 0.5588)
		(drill 0.3048)
		(layers "F.Cu" "B.Cu")
		(net "PVCCIN_CPU0")
	)
	(via
		(at 266.231116 -88.165686)
		(size 0.508)
		(drill 0.254)
		(layers "F.Cu" "B.Cu")
		(net "PVCCIN_CPU0")
	)
	(via
		(at 242.480338 -73.42124)
		(size 0.508)
		(drill 0.254)
		(layers "F.Cu" "B.Cu")
		(net "PVCCIN_CPU0")
	)
	(via
		(at 210.485228 -59.519058)
		(size 0.5588)
		(drill 0.3048)
		(layers "F.Cu" "B.Cu")
		(net "PVCCIN_CPU0")
	)
	(via
		(at 211.247228 -59.519058)
		(size 0.5588)
		(drill 0.3048)
		(layers "F.Cu" "B.Cu")
		(net "PVCCIN_CPU0")
	)
	(via
		(at 253.640844 -78.869286)
		(size 0.508)
		(drill 0.254)
		(layers "F.Cu" "B.Cu")
		(net "PVCCIN_CPU0")
	)
	(via
		(at 211.196428 -86.316058)
		(size 0.5588)
		(drill 0.3048)
		(layers "F.Cu" "B.Cu")
		(net "PVCCIN_CPU0")
	)
	(via
		(at 279.778714 -87.032084)
		(size 0.508)
		(drill 0.254)
		(layers "F.Cu" "B.Cu")
		(net "PVCCIN_CPU0")
	)
	(via
		(at 216.251028 -71.711058)
		(size 0.5588)
		(drill 0.3048)
		(layers "F.Cu" "B.Cu")
		(net "PVCCIN_CPU0")
	)
	(via
		(at 240.763298 -79.36484)
		(size 0.508)
		(drill 0.254)
		(layers "F.Cu" "B.Cu")
		(net "PVCCIN_CPU0")
	)
	(via
		(at 246.772684 -76.888086)
		(size 0.508)
		(drill 0.254)
		(layers "F.Cu" "B.Cu")
		(net "PVCCIN_CPU0")
	)
	(via
		(at 255.69291 -76.39304)
		(size 0.508)
		(drill 0.254)
		(layers "F.Cu" "B.Cu")
		(net "PVCCIN_CPU0")
	)
	(via
		(at 251.923804 -77.878686)
		(size 0.508)
		(drill 0.254)
		(layers "F.Cu" "B.Cu")
		(net "PVCCIN_CPU0")
	)
	(via
		(at 243.338604 -76.888086)
		(size 0.508)
		(drill 0.254)
		(layers "F.Cu" "B.Cu")
		(net "PVCCIN_CPU0")
	)
	(via
		(at 209.672428 -85.604858)
		(size 0.5588)
		(drill 0.3048)
		(layers "F.Cu" "B.Cu")
		(net "PVCCIN_CPU0")
	)
	(via
		(at 236.470698 -73.916286)
		(size 0.508)
		(drill 0.254)
		(layers "F.Cu" "B.Cu")
		(net "PVCCIN_CPU0")
	)
	(via
		(at 239.904778 -79.859886)
		(size 0.508)
		(drill 0.254)
		(layers "F.Cu" "B.Cu")
		(net "PVCCIN_CPU0")
	)
	(via
		(at 259.35051 -78.678786)
		(size 0.5588)
		(drill 0.3048)
		(layers "F.Cu" "B.Cu")
		(net "PVCCIN_CPU0")
	)
	(via
		(at 257.93319 -65.49644)
		(size 0.508)
		(drill 0.254)
		(layers "F.Cu" "B.Cu")
		(net "PVCCIN_CPU0")
	)
	(via
		(at 245.055644 -75.897486)
		(size 0.508)
		(drill 0.254)
		(layers "F.Cu" "B.Cu")
		(net "PVCCIN_CPU0")
	)
	(via
		(at 217.775028 -71.050658)
		(size 0.5588)
		(drill 0.3048)
		(layers "F.Cu" "B.Cu")
		(net "PVCCIN_CPU0")
	)
	(via
		(at 211.247228 -77.197458)
		(size 0.5588)
		(drill 0.3048)
		(layers "F.Cu" "B.Cu")
		(net "PVCCIN_CPU0")
	)
	(via
		(at 233.818938 -80.30464)
		(size 0.508)
		(drill 0.254)
		(layers "F.Cu" "B.Cu")
		(net "PVCCIN_CPU0")
	)
	(via
		(at 239.046258 -79.36484)
		(size 0.508)
		(drill 0.254)
		(layers "F.Cu" "B.Cu")
		(net "PVCCIN_CPU0")
	)
	(via
		(at 208.910428 -87.078058)
		(size 0.5588)
		(drill 0.3048)
		(layers "F.Cu" "B.Cu")
		(net "PVCCIN_CPU0")
	)
	(via
		(at 250.206764 -76.888086)
		(size 0.508)
		(drill 0.254)
		(layers "F.Cu" "B.Cu")
		(net "PVCCIN_CPU0")
	)
	(via
		(at 259.258308 -74.397616)
		(size 0.5588)
		(drill 0.3048)
		(layers "F.Cu" "B.Cu")
		(net "PVCCIN_CPU0")
	)
	(via
		(at 208.961228 -60.204858)
		(size 0.5588)
		(drill 0.3048)
		(layers "F.Cu" "B.Cu")
		(net "PVCCIN_CPU0")
	)
	(via
		(at 243.338604 -79.859886)
		(size 0.508)
		(drill 0.254)
		(layers "F.Cu" "B.Cu")
		(net "PVCCIN_CPU0")
	)
	(via
		(at 216.225628 -62.592458)
		(size 0.5588)
		(drill 0.3048)
		(layers "F.Cu" "B.Cu")
		(net "PVCCIN_CPU0")
	)
	(via
		(at 252.782324 -76.39304)
		(size 0.508)
		(drill 0.254)
		(layers "F.Cu" "B.Cu")
		(net "PVCCIN_CPU0")
	)
	(via
		(at 247.631204 -75.40244)
		(size 0.508)
		(drill 0.254)
		(layers "F.Cu" "B.Cu")
		(net "PVCCIN_CPU0")
	)
	(via
		(at 217.013028 -71.711058)
		(size 0.5588)
		(drill 0.3048)
		(layers "F.Cu" "B.Cu")
		(net "PVCCIN_CPU0")
	)
	(via
		(at 276.344634 -88.022684)
		(size 0.508)
		(drill 0.254)
		(layers "F.Cu" "B.Cu")
		(net "PVCCIN_CPU0")
	)
	(via
		(at 208.910428 -85.604858)
		(size 0.5588)
		(drill 0.3048)
		(layers "F.Cu" "B.Cu")
		(net "PVCCIN_CPU0")
	)
	(via
		(at 260.22173 -85.68944)
		(size 0.508)
		(drill 0.254)
		(layers "F.Cu" "B.Cu")
		(net "PVCCIN_CPU0")
	)
	(via
		(at 238.187738 -72.925686)
		(size 0.508)
		(drill 0.254)
		(layers "F.Cu" "B.Cu")
		(net "PVCCIN_CPU0")
	)
	(via
		(at 212.009228 -75.825858)
		(size 0.5588)
		(drill 0.3048)
		(layers "F.Cu" "B.Cu")
		(net "PVCCIN_CPU0")
	)
	(via
		(at 243.338604 -71.935086)
		(size 0.508)
		(drill 0.254)
		(layers "F.Cu" "B.Cu")
		(net "PVCCIN_CPU0")
	)
	(via
		(at 209.409284 -55.238904)
		(size 0.5588)
		(drill 0.3048)
		(layers "F.Cu" "B.Cu")
		(net "PVCCIN_CPU0")
	)
	(via
		(at 264.51433 -64.581786)
		(size 0.508)
		(drill 0.254)
		(layers "F.Cu" "B.Cu")
		(net "PVCCIN_CPU0")
	)
	(via
		(at 208.910428 -86.316058)
		(size 0.5588)
		(drill 0.3048)
		(layers "F.Cu" "B.Cu")
		(net "PVCCIN_CPU0")
	)
	(via
		(at 237.329218 -79.36484)
		(size 0.508)
		(drill 0.254)
		(layers "F.Cu" "B.Cu")
		(net "PVCCIN_CPU0")
	)
	(via
		(at 243.338604 -73.916286)
		(size 0.508)
		(drill 0.254)
		(layers "F.Cu" "B.Cu")
		(net "PVCCIN_CPU0")
	)
	(via
		(at 217.749628 -63.252858)
		(size 0.5588)
		(drill 0.3048)
		(layers "F.Cu" "B.Cu")
		(net "PVCCIN_CPU0")
	)
	(via
		(at 212.665056 -71.14794)
		(size 0.5588)
		(drill 0.3048)
		(layers "F.Cu" "B.Cu")
		(net "PVCCIN_CPU0")
	)
	(via
		(at 215.489028 -69.704458)
		(size 0.5588)
		(drill 0.3048)
		(layers "F.Cu" "B.Cu")
		(net "PVCCIN_CPU0")
	)
	(via
		(at 212.695028 -86.328758)
		(size 0.5588)
		(drill 0.3048)
		(layers "F.Cu" "B.Cu")
		(net "PVCCIN_CPU0")
	)
	(via
		(at 242.480338 -75.40244)
		(size 0.508)
		(drill 0.254)
		(layers "F.Cu" "B.Cu")
		(net "PVCCIN_CPU0")
	)
	(via
		(at 212.796628 -75.724258)
		(size 0.5588)
		(drill 0.3048)
		(layers "F.Cu" "B.Cu")
		(net "PVCCIN_CPU0")
	)
	(via
		(at 255.69291 -75.40244)
		(size 0.508)
		(drill 0.254)
		(layers "F.Cu" "B.Cu")
		(net "PVCCIN_CPU0")
	)
	(via
		(at 212.725 -60.833)
		(size 0.5588)
		(drill 0.3048)
		(layers "F.Cu" "B.Cu")
		(net "PVCCIN_CPU0")
	)
	(via
		(at 223.414844 -67.126612)
		(size 0.5588)
		(drill 0.3048)
		(layers "F.Cu" "B.Cu")
		(net "PVCCIN_CPU0")
	)
	(via
		(at 257.64617 -67.6402)
		(size 0.508)
		(drill 0.254)
		(layers "F.Cu" "B.Cu")
		(net "PVCCIN_CPU0")
	)
	(via
		(at 209.9818 -54.559708)
		(size 0.5588)
		(drill 0.3048)
		(layers "F.Cu" "B.Cu")
		(net "PVCCIN_CPU0")
	)
	(via
		(at 262.116062 -74.39914)
		(size 0.5588)
		(drill 0.3048)
		(layers "F.Cu" "B.Cu")
		(net "PVCCIN_CPU0")
	)
	(via
		(at 245.055644 -72.925686)
		(size 0.508)
		(drill 0.254)
		(layers "F.Cu" "B.Cu")
		(net "PVCCIN_CPU0")
	)
	(via
		(at 208.961228 -77.197458)
		(size 0.5588)
		(drill 0.3048)
		(layers "F.Cu" "B.Cu")
		(net "PVCCIN_CPU0")
	)
	(via
		(at 259.36321 -85.193886)
		(size 0.508)
		(drill 0.254)
		(layers "F.Cu" "B.Cu")
		(net "PVCCIN_CPU0")
	)
	(via
		(at 251.065284 -73.42124)
		(size 0.508)
		(drill 0.254)
		(layers "F.Cu" "B.Cu")
		(net "PVCCIN_CPU0")
	)
	(via
		(at 215.387428 -85.935058)
		(size 0.5588)
		(drill 0.3048)
		(layers "F.Cu" "B.Cu")
		(net "PVCCIN_CPU0")
	)
	(via
		(at 216.835228 -78.569058)
		(size 0.5588)
		(drill 0.3048)
		(layers "F.Cu" "B.Cu")
		(net "PVCCIN_CPU0")
	)
	(via
		(at 210.485228 -77.197458)
		(size 0.5588)
		(drill 0.3048)
		(layers "F.Cu" "B.Cu")
		(net "PVCCIN_CPU0")
	)
	(via
		(at 212.695028 -85.617558)
		(size 0.5588)
		(drill 0.3048)
		(layers "F.Cu" "B.Cu")
		(net "PVCCIN_CPU0")
	)
	(via
		(at 248.489724 -74.906886)
		(size 0.508)
		(drill 0.254)
		(layers "F.Cu" "B.Cu")
		(net "PVCCIN_CPU0")
	)
	(via
		(at 275.158454 -86.065614)
		(size 0.5588)
		(drill 0.3048)
		(layers "F.Cu" "B.Cu")
		(net "PVCCIN_CPU0")
	)
	(via
		(at 210.429856 -69.82714)
		(size 0.5588)
		(drill 0.3048)
		(layers "F.Cu" "B.Cu")
		(net "PVCCIN_CPU0")
	)
	(via
		(at 254.49911 -67.47764)
		(size 0.508)
		(drill 0.254)
		(layers "F.Cu" "B.Cu")
		(net "PVCCIN_CPU0")
	)
	(via
		(at 255.69291 -78.37424)
		(size 0.508)
		(drill 0.254)
		(layers "F.Cu" "B.Cu")
		(net "PVCCIN_CPU0")
	)
	(via
		(at 276.344634 -65.4812)
		(size 0.508)
		(drill 0.254)
		(layers "F.Cu" "B.Cu")
		(net "PVCCIN_CPU0")
	)
	(via
		(at 239.046258 -73.42124)
		(size 0.508)
		(drill 0.254)
		(layers "F.Cu" "B.Cu")
		(net "PVCCIN_CPU0")
	)
	(via
		(at 209.723228 -59.519058)
		(size 0.5588)
		(drill 0.3048)
		(layers "F.Cu" "B.Cu")
		(net "PVCCIN_CPU0")
	)
	(via
		(at 232.909618 -70.94474)
		(size 0.508)
		(drill 0.254)
		(layers "F.Cu" "B.Cu")
		(net "PVCCIN_CPU0")
	)
	(via
		(at 216.835228 -77.908658)
		(size 0.5588)
		(drill 0.3048)
		(layers "F.Cu" "B.Cu")
		(net "PVCCIN_CPU0")
	)
	(via
		(at 212.009228 -60.865258)
		(size 0.5588)
		(drill 0.3048)
		(layers "F.Cu" "B.Cu")
		(net "PVCCIN_CPU0")
	)
	(via
		(at 211.247228 -75.825858)
		(size 0.5588)
		(drill 0.3048)
		(layers "F.Cu" "B.Cu")
		(net "PVCCIN_CPU0")
	)
	(via
		(at 241.621818 -75.897486)
		(size 0.508)
		(drill 0.254)
		(layers "F.Cu" "B.Cu")
		(net "PVCCIN_CPU0")
	)
	(via
		(at 260.50875 -64.010286)
		(size 0.508)
		(drill 0.254)
		(layers "F.Cu" "B.Cu")
		(net "PVCCIN_CPU0")
	)
	(via
		(at 257.07467 -85.803486)
		(size 0.508)
		(drill 0.254)
		(layers "F.Cu" "B.Cu")
		(net "PVCCIN_CPU0")
	)
	(via
		(at 274.627848 -88.022684)
		(size 0.508)
		(drill 0.254)
		(layers "F.Cu" "B.Cu")
		(net "PVCCIN_CPU0")
	)
	(via
		(at 215.489028 -71.711058)
		(size 0.5588)
		(drill 0.3048)
		(layers "F.Cu" "B.Cu")
		(net "PVCCIN_CPU0")
	)
	(via
		(at 213.426548 -87.124794)
		(size 0.5588)
		(drill 0.3048)
		(layers "F.Cu" "B.Cu")
		(net "PVCCIN_CPU0")
	)
	(via
		(at 210.334606 -92.146628)
		(size 0.5588)
		(drill 0.3048)
		(layers "F.Cu" "B.Cu")
		(net "PVCCIN_CPU0")
	)
	(via
		(at 217.597228 -79.254858)
		(size 0.5588)
		(drill 0.3048)
		(layers "F.Cu" "B.Cu")
		(net "PVCCIN_CPU0")
	)
	(via
		(at 242.480338 -79.36484)
		(size 0.508)
		(drill 0.254)
		(layers "F.Cu" "B.Cu")
		(net "PVCCIN_CPU0")
	)
	(via
		(at 216.911428 -85.935058)
		(size 0.5588)
		(drill 0.3048)
		(layers "F.Cu" "B.Cu")
		(net "PVCCIN_CPU0")
	)
	(via
		(at 209.667856 -69.82714)
		(size 0.5588)
		(drill 0.3048)
		(layers "F.Cu" "B.Cu")
		(net "PVCCIN_CPU0")
	)
	(via
		(at 253.640844 -70.94474)
		(size 0.508)
		(drill 0.254)
		(layers "F.Cu" "B.Cu")
		(net "PVCCIN_CPU0")
	)
	(via
		(at 217.597228 -77.908658)
		(size 0.5588)
		(drill 0.3048)
		(layers "F.Cu" "B.Cu")
		(net "PVCCIN_CPU0")
	)
	(via
		(at 214.6427 -64.0715)
		(size 0.5588)
		(drill 0.3048)
		(layers "F.Cu" "B.Cu")
		(net "PVCCIN_CPU0")
	)
	(via
		(at 234.753658 -80.850486)
		(size 0.508)
		(drill 0.254)
		(layers "F.Cu" "B.Cu")
		(net "PVCCIN_CPU0")
	)
	(via
		(at 247.631204 -78.37424)
		(size 0.508)
		(drill 0.254)
		(layers "F.Cu" "B.Cu")
		(net "PVCCIN_CPU0")
	)
	(via
		(at 245.055644 -73.916286)
		(size 0.508)
		(drill 0.254)
		(layers "F.Cu" "B.Cu")
		(net "PVCCIN_CPU0")
	)
	(via
		(at 275.486114 -64.896238)
		(size 0.508)
		(drill 0.254)
		(layers "F.Cu" "B.Cu")
		(net "PVCCIN_CPU0")
	)
	(via
		(at 252.782324 -79.36484)
		(size 0.508)
		(drill 0.254)
		(layers "F.Cu" "B.Cu")
		(net "PVCCIN_CPU0")
	)
	(via
		(at 255.7018 -68.7578)
		(size 0.508)
		(drill 0.254)
		(layers "F.Cu" "B.Cu")
		(net "PVCCIN_CPU0")
	)
	(via
		(at 243.338604 -70.94474)
		(size 0.508)
		(drill 0.254)
		(layers "F.Cu" "B.Cu")
		(net "PVCCIN_CPU0")
	)
	(via
		(at 222.760032 -82.8294)
		(size 0.5588)
		(drill 0.3048)
		(layers "F.Cu" "B.Cu")
		(net "PVCCIN_CPU0")
	)
	(via
		(at 262.915908 -74.397616)
		(size 0.5588)
		(drill 0.3048)
		(layers "F.Cu" "B.Cu")
		(net "PVCCIN_CPU0")
	)
	(via
		(at 234.753658 -78.869286)
		(size 0.508)
		(drill 0.254)
		(layers "F.Cu" "B.Cu")
		(net "PVCCIN_CPU0")
	)
	(via
		(at 216.149428 -85.935058)
		(size 0.5588)
		(drill 0.3048)
		(layers "F.Cu" "B.Cu")
		(net "PVCCIN_CPU0")
	)
	(via
		(at 275.859494 -66.6242)
		(size 0.5588)
		(drill 0.3048)
		(layers "F.Cu" "B.Cu")
		(net "PVCCIN_CPU0")
	)
	(via
		(at 211.958428 -87.078058)
		(size 0.5588)
		(drill 0.3048)
		(layers "F.Cu" "B.Cu")
		(net "PVCCIN_CPU0")
	)
	(via
		(at 195.892928 -54.364382)
		(size 0.508)
		(drill 0.254)
		(layers "F.Cu" "B.Cu")
		(net "PVCCIN_CPU0")
	)
	(via
		(at 249.348244 -75.40244)
		(size 0.508)
		(drill 0.254)
		(layers "F.Cu" "B.Cu")
		(net "PVCCIN_CPU0")
	)
	(via
		(at 251.065284 -75.40244)
		(size 0.508)
		(drill 0.254)
		(layers "F.Cu" "B.Cu")
		(net "PVCCIN_CPU0")
	)
	(via
		(at 241.621818 -73.916286)
		(size 0.508)
		(drill 0.254)
		(layers "F.Cu" "B.Cu")
		(net "PVCCIN_CPU0")
	)
	(via
		(at 239.904778 -75.897486)
		(size 0.508)
		(drill 0.254)
		(layers "F.Cu" "B.Cu")
		(net "PVCCIN_CPU0")
	)
	(via
		(at 264.51433 -88.165686)
		(size 0.508)
		(drill 0.254)
		(layers "F.Cu" "B.Cu")
		(net "PVCCIN_CPU0")
	)
	(via
		(at 216.225628 -63.252858)
		(size 0.5588)
		(drill 0.3048)
		(layers "F.Cu" "B.Cu")
		(net "PVCCIN_CPU0")
	)
	(via
		(at 234.753658 -72.925686)
		(size 0.508)
		(drill 0.254)
		(layers "F.Cu" "B.Cu")
		(net "PVCCIN_CPU0")
	)
	(via
		(at 253.640844 -67.972686)
		(size 0.508)
		(drill 0.254)
		(layers "F.Cu" "B.Cu")
		(net "PVCCIN_CPU0")
	)
	(via
		(at 216.835228 -79.254858)
		(size 0.5588)
		(drill 0.3048)
		(layers "F.Cu" "B.Cu")
		(net "PVCCIN_CPU0")
	)
	(via
		(at 208.961228 -76.511658)
		(size 0.5588)
		(drill 0.3048)
		(layers "F.Cu" "B.Cu")
		(net "PVCCIN_CPU0")
	)
	(via
		(at 258.339082 -78.71714)
		(size 0.5588)
		(drill 0.3048)
		(layers "F.Cu" "B.Cu")
		(net "PVCCIN_CPU0")
	)
	(via
		(at 217.775028 -69.704458)
		(size 0.5588)
		(drill 0.3048)
		(layers "F.Cu" "B.Cu")
		(net "PVCCIN_CPU0")
	)
	(via
		(at 233.036618 -82.83194)
		(size 0.508)
		(drill 0.254)
		(layers "F.Cu" "B.Cu")
		(net "PVCCIN_CPU0")
	)
	(via
		(at 216.987628 -64.599058)
		(size 0.5588)
		(drill 0.3048)
		(layers "F.Cu" "B.Cu")
		(net "PVCCIN_CPU0")
	)
	(via
		(at 211.191856 -70.48754)
		(size 0.5588)
		(drill 0.3048)
		(layers "F.Cu" "B.Cu")
		(net "PVCCIN_CPU0")
	)
	(via
		(at 208.961228 -58.858658)
		(size 0.5588)
		(drill 0.3048)
		(layers "F.Cu" "B.Cu")
		(net "PVCCIN_CPU0")
	)
	(via
		(at 259.65023 -64.50584)
		(size 0.508)
		(drill 0.254)
		(layers "F.Cu" "B.Cu")
		(net "PVCCIN_CPU0")
	)
	(via
		(at 253.640844 -82.83194)
		(size 0.508)
		(drill 0.254)
		(layers "F.Cu" "B.Cu")
		(net "PVCCIN_CPU0")
	)
	(via
		(at 234.753658 -73.916286)
		(size 0.508)
		(drill 0.254)
		(layers "F.Cu" "B.Cu")
		(net "PVCCIN_CPU0")
	)
	(via
		(at 241.621818 -79.859886)
		(size 0.508)
		(drill 0.254)
		(layers "F.Cu" "B.Cu")
		(net "PVCCIN_CPU0")
	)
	(via
		(at 210.35772 -58.863992)
		(size 0.5588)
		(drill 0.3048)
		(layers "F.Cu" "B.Cu")
		(net "PVCCIN_CPU0")
	)
	(via
		(at 248.489724 -76.888086)
		(size 0.508)
		(drill 0.254)
		(layers "F.Cu" "B.Cu")
		(net "PVCCIN_CPU0")
	)
	(via
		(at 251.923804 -73.916286)
		(size 0.508)
		(drill 0.254)
		(layers "F.Cu" "B.Cu")
		(net "PVCCIN_CPU0")
	)
	(via
		(at 209.723228 -60.204858)
		(size 0.5588)
		(drill 0.3048)
		(layers "F.Cu" "B.Cu")
		(net "PVCCIN_CPU0")
	)
	(via
		(at 238.187738 -78.869286)
		(size 0.508)
		(drill 0.254)
		(layers "F.Cu" "B.Cu")
		(net "PVCCIN_CPU0")
	)
	(via
		(at 251.923804 -75.897486)
		(size 0.508)
		(drill 0.254)
		(layers "F.Cu" "B.Cu")
		(net "PVCCIN_CPU0")
	)
	(via
		(at 252.782324 -77.38364)
		(size 0.508)
		(drill 0.254)
		(layers "F.Cu" "B.Cu")
		(net "PVCCIN_CPU0")
	)
	(via
		(at 236.470698 -78.869286)
		(size 0.508)
		(drill 0.254)
		(layers "F.Cu" "B.Cu")
		(net "PVCCIN_CPU0")
	)
	(via
		(at 258.50469 -84.69884)
		(size 0.508)
		(drill 0.254)
		(layers "F.Cu" "B.Cu")
		(net "PVCCIN_CPU0")
	)
	(via
		(at 234.753658 -71.935086)
		(size 0.508)
		(drill 0.254)
		(layers "F.Cu" "B.Cu")
		(net "PVCCIN_CPU0")
	)
	(via
		(at 208.961228 -60.865258)
		(size 0.5588)
		(drill 0.3048)
		(layers "F.Cu" "B.Cu")
		(net "PVCCIN_CPU0")
	)
	(via
		(at 250.206764 -77.878686)
		(size 0.508)
		(drill 0.254)
		(layers "F.Cu" "B.Cu")
		(net "PVCCIN_CPU0")
	)
	(via
		(at 243.338604 -74.906886)
		(size 0.508)
		(drill 0.254)
		(layers "F.Cu" "B.Cu")
		(net "PVCCIN_CPU0")
	)
	(via
		(at 209.572606 -92.146628)
		(size 0.5588)
		(drill 0.3048)
		(layers "F.Cu" "B.Cu")
		(net "PVCCIN_CPU0")
	)
	(via
		(at 266.584938 -78.715616)
		(size 0.5588)
		(drill 0.3048)
		(layers "F.Cu" "B.Cu")
		(net "PVCCIN_CPU0")
	)
	(via
		(at 217.597228 -79.915258)
		(size 0.5588)
		(drill 0.3048)
		(layers "F.Cu" "B.Cu")
		(net "PVCCIN_CPU0")
	)
	(via
		(at 240.763298 -77.38364)
		(size 0.508)
		(drill 0.254)
		(layers "F.Cu" "B.Cu")
		(net "PVCCIN_CPU0")
	)
	(via
		(at 263.65581 -65.151)
		(size 0.508)
		(drill 0.254)
		(layers "F.Cu" "B.Cu")
		(net "PVCCIN_CPU0")
	)
	(via
		(at 253.640844 -76.888086)
		(size 0.508)
		(drill 0.254)
		(layers "F.Cu" "B.Cu")
		(net "PVCCIN_CPU0")
	)
	(via
		(at 268.413738 -78.715616)
		(size 0.5588)
		(drill 0.3048)
		(layers "F.Cu" "B.Cu")
		(net "PVCCIN_CPU0")
	)
	(via
		(at 238.187738 -70.94474)
		(size 0.508)
		(drill 0.254)
		(layers "F.Cu" "B.Cu")
		(net "PVCCIN_CPU0")
	)
	(via
		(at 253.640844 -80.850486)
		(size 0.508)
		(drill 0.254)
		(layers "F.Cu" "B.Cu")
		(net "PVCCIN_CPU0")
	)
	(via
		(at 260.22173 -66.1162)
		(size 0.508)
		(drill 0.254)
		(layers "F.Cu" "B.Cu")
		(net "PVCCIN_CPU0")
	)
	(via
		(at 216.073228 -77.908658)
		(size 0.5588)
		(drill 0.3048)
		(layers "F.Cu" "B.Cu")
		(net "PVCCIN_CPU0")
	)
	(via
		(at 252.782324 -74.411586)
		(size 0.508)
		(drill 0.254)
		(layers "F.Cu" "B.Cu")
		(net "PVCCIN_CPU0")
	)
	(via
		(at 220.220032 -85.3694)
		(size 0.5588)
		(drill 0.3048)
		(layers "F.Cu" "B.Cu")
		(net "PVCCIN_CPU0")
	)
	(via
		(at 216.073228 -79.254858)
		(size 0.5588)
		(drill 0.3048)
		(layers "F.Cu" "B.Cu")
		(net "PVCCIN_CPU0")
	)
	(via
		(at 232.960418 -80.850486)
		(size 0.508)
		(drill 0.254)
		(layers "F.Cu" "B.Cu")
		(net "PVCCIN_CPU0")
	)
	(via
		(at 208.905856 -71.14794)
		(size 0.5588)
		(drill 0.3048)
		(layers "F.Cu" "B.Cu")
		(net "PVCCIN_CPU0")
	)
	(via
		(at 236.470698 -71.935086)
		(size 0.508)
		(drill 0.254)
		(layers "F.Cu" "B.Cu")
		(net "PVCCIN_CPU0")
	)
	(via
		(at 239.904778 -76.888086)
		(size 0.508)
		(drill 0.254)
		(layers "F.Cu" "B.Cu")
		(net "PVCCIN_CPU0")
	)
	(via
		(at 241.621818 -78.869286)
		(size 0.508)
		(drill 0.254)
		(layers "F.Cu" "B.Cu")
		(net "PVCCIN_CPU0")
	)
	(via
		(at 261.93877 -86.68004)
		(size 0.508)
		(drill 0.254)
		(layers "F.Cu" "B.Cu")
		(net "PVCCIN_CPU0")
	)
	(segment
		(start 228.4603 -66.5861)
		(end 228.4603 -65.5447)
		(width 0.254)
		(layer "B.Cu")
		(net "PVCCIN_CPU0")
	)
	(segment
		(start 228.473 -66.5988)
		(end 228.4603 -66.5861)
		(width 0.254)
		(layer "B.Cu")
		(net "PVCCIN_CPU0")
	)
	(segment
		(start 200.972166 -48.768)
		(end 195.892928 -53.847238)
		(width 0.508)
		(layer "In4.Cu")
		(net "PVCCIN_CPU0")
	)
	(segment
		(start 206.987648 -48.768)
		(end 200.972166 -48.768)
		(width 0.508)
		(layer "In4.Cu")
		(net "PVCCIN_CPU0")
	)
	(segment
		(start 195.892928 -53.847238)
		(end 195.892928 -54.364382)
		(width 0.508)
		(layer "In4.Cu")
		(net "PVCCIN_CPU0")
	)
	(segment
		(start 208.8896 -50.669952)
		(end 206.987648 -48.768)
		(width 0.508)
		(layer "In4.Cu")
		(net "PVCCIN_CPU0")
	)
	(segment
		(start 208.8896 -53.9496)
		(end 208.8896 -50.669952)
		(width 0.508)
		(layer "In4.Cu")
		(net "PVCCIN_CPU0")
	)
	(segment
		(start 195.651882 -78.820772)
		(end 195.914772 -78.820772)
		(width 0.508)
		(layer "In11.Cu")
		(net "PVCCIN_CPU0")
	)
	(segment
		(start 194.765422 -77.934312)
		(end 195.651882 -78.820772)
		(width 0.508)
		(layer "In11.Cu")
		(net "PVCCIN_CPU0")
	)
	(segment
		(start 195.9991 -70.726554)
		(end 195.9991 -69.9897)
		(width 0.508)
		(layer "In11.Cu")
		(net "PVCCIN_CPU0")
	)
	(segment
		(start 197.750938 -54.872382)
		(end 198.258938 -55.380382)
		(width 0.508)
		(layer "In11.Cu")
		(net "PVCCIN_CPU0")
	)
	(segment
		(start 194.8434 -68.834)
		(end 194.8434 -66.675)
		(width 0.508)
		(layer "In11.Cu")
		(net "PVCCIN_CPU0")
	)
	(segment
		(start 195.454778 -81.795366)
		(end 193.840862 -83.409282)
		(width 0.508)
		(layer "In11.Cu")
		(net "PVCCIN_CPU0")
	)
	(segment
		(start 198.732394 -62.21476)
		(end 198.354696 -62.592458)
		(width 0.508)
		(layer "In11.Cu")
		(net "PVCCIN_CPU0")
	)
	(segment
		(start 195.9991 -69.9897)
		(end 194.8434 -68.834)
		(width 0.508)
		(layer "In11.Cu")
		(net "PVCCIN_CPU0")
	)
	(segment
		(start 198.354696 -62.592458)
		(end 198.23049 -62.592458)
		(width 0.508)
		(layer "In11.Cu")
		(net "PVCCIN_CPU0")
	)
	(segment
		(start 195.892928 -54.364382)
		(end 196.400928 -54.872382)
		(width 0.508)
		(layer "In11.Cu")
		(net "PVCCIN_CPU0")
	)
	(segment
		(start 195.9991 -70.726554)
		(end 195.616576 -71.109078)
		(width 0.508)
		(layer "In11.Cu")
		(net "PVCCIN_CPU0")
	)
	(segment
		(start 198.258938 -55.380382)
		(end 198.258938 -59.943746)
		(width 0.508)
		(layer "In11.Cu")
		(net "PVCCIN_CPU0")
	)
	(segment
		(start 193.840862 -85.373464)
		(end 195.462652 -86.995254)
		(width 0.508)
		(layer "In11.Cu")
		(net "PVCCIN_CPU0")
	)
	(segment
		(start 195.462652 -86.995254)
		(end 196.0118 -86.995254)
		(width 0.508)
		(layer "In11.Cu")
		(net "PVCCIN_CPU0")
	)
	(segment
		(start 195.454778 -79.424022)
		(end 195.454778 -81.795366)
		(width 0.508)
		(layer "In11.Cu")
		(net "PVCCIN_CPU0")
	)
	(segment
		(start 194.0179 -77.934312)
		(end 194.765422 -77.934312)
		(width 0.508)
		(layer "In11.Cu")
		(net "PVCCIN_CPU0")
	)
	(segment
		(start 195.9864 -78.8924)
		(end 195.454778 -79.424022)
		(width 0.508)
		(layer "In11.Cu")
		(net "PVCCIN_CPU0")
	)
	(segment
		(start 198.23049 -62.592458)
		(end 198.224394 -62.598554)
		(width 0.508)
		(layer "In11.Cu")
		(net "PVCCIN_CPU0")
	)
	(segment
		(start 195.616576 -73.628758)
		(end 193.153792 -76.091542)
		(width 0.508)
		(layer "In11.Cu")
		(net "PVCCIN_CPU0")
	)
	(segment
		(start 196.400928 -54.872382)
		(end 197.750938 -54.872382)
		(width 0.508)
		(layer "In11.Cu")
		(net "PVCCIN_CPU0")
	)
	(segment
		(start 193.840862 -83.409282)
		(end 193.840862 -85.373464)
		(width 0.508)
		(layer "In11.Cu")
		(net "PVCCIN_CPU0")
	)
	(segment
		(start 195.6308 -62.966854)
		(end 195.9991 -62.598554)
		(width 0.508)
		(layer "In11.Cu")
		(net "PVCCIN_CPU0")
	)
	(segment
		(start 198.224394 -62.598554)
		(end 195.9991 -62.598554)
		(width 0.508)
		(layer "In11.Cu")
		(net "PVCCIN_CPU0")
	)
	(segment
		(start 193.153792 -76.091542)
		(end 193.153792 -77.070204)
		(width 0.508)
		(layer "In11.Cu")
		(net "PVCCIN_CPU0")
	)
	(segment
		(start 194.8434 -66.675)
		(end 195.6308 -65.8876)
		(width 0.508)
		(layer "In11.Cu")
		(net "PVCCIN_CPU0")
	)
	(segment
		(start 193.153792 -77.070204)
		(end 194.0179 -77.934312)
		(width 0.508)
		(layer "In11.Cu")
		(net "PVCCIN_CPU0")
	)
	(segment
		(start 195.914772 -78.820772)
		(end 195.9864 -78.8924)
		(width 0.508)
		(layer "In11.Cu")
		(net "PVCCIN_CPU0")
	)
	(segment
		(start 195.616576 -71.109078)
		(end 195.616576 -73.628758)
		(width 0.508)
		(layer "In11.Cu")
		(net "PVCCIN_CPU0")
	)
	(segment
		(start 198.732394 -60.417202)
		(end 198.732394 -62.21476)
		(width 0.508)
		(layer "In11.Cu")
		(net "PVCCIN_CPU0")
	)
	(segment
		(start 198.258938 -59.943746)
		(end 198.732394 -60.417202)
		(width 0.508)
		(layer "In11.Cu")
		(net "PVCCIN_CPU0")
	)
	(segment
		(start 195.6308 -65.8876)
		(end 195.6308 -62.966854)
		(width 0.508)
		(layer "In11.Cu")
		(net "PVCCIN_CPU0")
	)
	(segment
		(start 393.677648 -118.6688)
		(end 393.68095 -118.670324)
		(width 0.254)
		(layer "F.Cu")
		(net "A_PCIE_RCOMP_P")
	)
	(segment
		(start 393.18565 -118.4402)
		(end 393.677648 -118.6688)
		(width 0.254)
		(layer "F.Cu")
		(net "A_PCIE_RCOMP_P")
	)
	(via
		(at 393.68095 -118.670324)
		(size 0.508)
		(drill 0.254)
		(layers "F.Cu" "B.Cu")
		(net "A_PCIE_RCOMP_P")
	)
	(segment
		(start 391.888726 -118.214648)
		(end 391.982452 -118.308374)
		(width 0.2032)
		(layer "B.Cu")
		(net "A_PCIE_RCOMP_P")
	)
	(segment
		(start 388.22376 -122.28576)
		(end 388.22376 -121.92)
		(width 0.2032)
		(layer "B.Cu")
		(net "A_PCIE_RCOMP_P")
	)
	(segment
		(start 388.2644 -120.5738)
		(end 388.2644 -120.1928)
		(width 0.2032)
		(layer "B.Cu")
		(net "A_PCIE_RCOMP_P")
	)
	(segment
		(start 390.520174 -118.214648)
		(end 390.898126 -118.214648)
		(width 0.2032)
		(layer "B.Cu")
		(net "A_PCIE_RCOMP_P")
	)
	(segment
		(start 389.907526 -118.214648)
		(end 390.01954 -118.326662)
		(width 0.2032)
		(layer "B.Cu")
		(net "A_PCIE_RCOMP_P")
	)
	(segment
		(start 388.6962 -121.44756)
		(end 388.6962 -121.0056)
		(width 0.2032)
		(layer "B.Cu")
		(net "A_PCIE_RCOMP_P")
	)
	(segment
		(start 389.0518 -125.507242)
		(end 389.0518 -125.012704)
		(width 0.2032)
		(layer "B.Cu")
		(net "A_PCIE_RCOMP_P")
	)
	(segment
		(start 390.898126 -118.214648)
		(end 391.020046 -118.336568)
		(width 0.2032)
		(layer "B.Cu")
		(net "A_PCIE_RCOMP_P")
	)
	(segment
		(start 392.501374 -118.214648)
		(end 392.879326 -118.214648)
		(width 0.2032)
		(layer "B.Cu")
		(net "A_PCIE_RCOMP_P")
	)
	(segment
		(start 389.195818 -118.548404)
		(end 389.529574 -118.214648)
		(width 0.2032)
		(layer "B.Cu")
		(net "A_PCIE_RCOMP_P")
	)
	(segment
		(start 388.22376 -121.92)
		(end 388.6962 -121.44756)
		(width 0.2032)
		(layer "B.Cu")
		(net "A_PCIE_RCOMP_P")
	)
	(segment
		(start 388.228586 -123.632214)
		(end 388.6962 -123.1646)
		(width 0.2032)
		(layer "B.Cu")
		(net "A_PCIE_RCOMP_P")
	)
	(segment
		(start 391.020046 -118.336568)
		(end 391.388854 -118.336568)
		(width 0.2032)
		(layer "B.Cu")
		(net "A_PCIE_RCOMP_P")
	)
	(segment
		(start 388.7597 -119.6975)
		(end 388.7597 -119.3292)
		(width 0.2032)
		(layer "B.Cu")
		(net "A_PCIE_RCOMP_P")
	)
	(segment
		(start 389.529574 -118.214648)
		(end 389.907526 -118.214648)
		(width 0.2032)
		(layer "B.Cu")
		(net "A_PCIE_RCOMP_P")
	)
	(segment
		(start 389.0518 -125.012704)
		(end 388.228586 -124.18949)
		(width 0.2032)
		(layer "B.Cu")
		(net "A_PCIE_RCOMP_P")
	)
	(segment
		(start 392.879326 -118.214648)
		(end 392.932158 -118.26748)
		(width 0.2032)
		(layer "B.Cu")
		(net "A_PCIE_RCOMP_P")
	)
	(segment
		(start 391.388854 -118.336568)
		(end 391.510774 -118.214648)
		(width 0.2032)
		(layer "B.Cu")
		(net "A_PCIE_RCOMP_P")
	)
	(segment
		(start 388.6962 -121.0056)
		(end 388.2644 -120.5738)
		(width 0.2032)
		(layer "B.Cu")
		(net "A_PCIE_RCOMP_P")
	)
	(segment
		(start 388.2644 -120.1928)
		(end 388.7597 -119.6975)
		(width 0.2032)
		(layer "B.Cu")
		(net "A_PCIE_RCOMP_P")
	)
	(segment
		(start 388.6962 -122.7582)
		(end 388.22376 -122.28576)
		(width 0.2032)
		(layer "B.Cu")
		(net "A_PCIE_RCOMP_P")
	)
	(segment
		(start 392.407648 -118.308374)
		(end 392.501374 -118.214648)
		(width 0.2032)
		(layer "B.Cu")
		(net "A_PCIE_RCOMP_P")
	)
	(segment
		(start 391.510774 -118.214648)
		(end 391.888726 -118.214648)
		(width 0.2032)
		(layer "B.Cu")
		(net "A_PCIE_RCOMP_P")
	)
	(segment
		(start 390.01954 -118.326662)
		(end 390.40816 -118.326662)
		(width 0.2032)
		(layer "B.Cu")
		(net "A_PCIE_RCOMP_P")
	)
	(segment
		(start 389.195818 -118.893082)
		(end 389.195818 -118.548404)
		(width 0.2032)
		(layer "B.Cu")
		(net "A_PCIE_RCOMP_P")
	)
	(segment
		(start 391.982452 -118.308374)
		(end 392.407648 -118.308374)
		(width 0.2032)
		(layer "B.Cu")
		(net "A_PCIE_RCOMP_P")
	)
	(segment
		(start 393.278106 -118.26748)
		(end 393.68095 -118.670324)
		(width 0.2032)
		(layer "B.Cu")
		(net "A_PCIE_RCOMP_P")
	)
	(segment
		(start 388.228586 -124.18949)
		(end 388.228586 -123.632214)
		(width 0.2032)
		(layer "B.Cu")
		(net "A_PCIE_RCOMP_P")
	)
	(segment
		(start 392.932158 -118.26748)
		(end 393.278106 -118.26748)
		(width 0.2032)
		(layer "B.Cu")
		(net "A_PCIE_RCOMP_P")
	)
	(segment
		(start 390.40816 -118.326662)
		(end 390.520174 -118.214648)
		(width 0.2032)
		(layer "B.Cu")
		(net "A_PCIE_RCOMP_P")
	)
	(segment
		(start 388.6962 -123.1646)
		(end 388.6962 -122.7582)
		(width 0.2032)
		(layer "B.Cu")
		(net "A_PCIE_RCOMP_P")
	)
	(segment
		(start 388.7597 -119.3292)
		(end 389.195818 -118.893082)
		(width 0.2032)
		(layer "B.Cu")
		(net "A_PCIE_RCOMP_P")
	)
	(segment
		(start 393.68095 -119.29872)
		(end 394.17625 -119.528844)
		(width 0.254)
		(layer "F.Cu")
		(net "A_PCIE_RCOMP_N")
	)
	(via
		(at 394.17625 -119.528844)
		(size 0.508)
		(drill 0.254)
		(layers "F.Cu" "B.Cu")
		(net "A_PCIE_RCOMP_N")
	)
	(segment
		(start 389.255 -121.92)
		(end 389.6868 -121.4882)
		(width 0.2032)
		(layer "B.Cu")
		(net "A_PCIE_RCOMP_N")
	)
	(segment
		(start 393.41044 -119.073168)
		(end 393.502642 -119.16537)
		(width 0.2032)
		(layer "B.Cu")
		(net "A_PCIE_RCOMP_N")
	)
	(segment
		(start 389.255 -122.3264)
		(end 389.255 -121.92)
		(width 0.2032)
		(layer "B.Cu")
		(net "A_PCIE_RCOMP_N")
	)
	(segment
		(start 389.7122 -119.385842)
		(end 390.024874 -119.073168)
		(width 0.2032)
		(layer "B.Cu")
		(net "A_PCIE_RCOMP_N")
	)
	(segment
		(start 389.215884 -120.211596)
		(end 389.7122 -119.71528)
		(width 0.2032)
		(layer "B.Cu")
		(net "A_PCIE_RCOMP_N")
	)
	(segment
		(start 392.996674 -119.073168)
		(end 393.41044 -119.073168)
		(width 0.2032)
		(layer "B.Cu")
		(net "A_PCIE_RCOMP_N")
	)
	(segment
		(start 389.9408 -124.9934)
		(end 389.2296 -124.2822)
		(width 0.2032)
		(layer "B.Cu")
		(net "A_PCIE_RCOMP_N")
	)
	(segment
		(start 389.2296 -124.2822)
		(end 389.2296 -123.6472)
		(width 0.2032)
		(layer "B.Cu")
		(net "A_PCIE_RCOMP_N")
	)
	(segment
		(start 389.6868 -121.4882)
		(end 389.6868 -121.0564)
		(width 0.2032)
		(layer "B.Cu")
		(net "A_PCIE_RCOMP_N")
	)
	(segment
		(start 389.6868 -123.19)
		(end 389.6868 -122.7582)
		(width 0.2032)
		(layer "B.Cu")
		(net "A_PCIE_RCOMP_N")
	)
	(segment
		(start 392.919204 -119.150638)
		(end 392.996674 -119.073168)
		(width 0.2032)
		(layer "B.Cu")
		(net "A_PCIE_RCOMP_N")
	)
	(segment
		(start 393.502642 -119.16537)
		(end 393.812776 -119.16537)
		(width 0.2032)
		(layer "B.Cu")
		(net "A_PCIE_RCOMP_N")
	)
	(segment
		(start 389.9408 -125.507242)
		(end 389.9408 -124.9934)
		(width 0.2032)
		(layer "B.Cu")
		(net "A_PCIE_RCOMP_N")
	)
	(segment
		(start 389.7122 -119.71528)
		(end 389.7122 -119.385842)
		(width 0.2032)
		(layer "B.Cu")
		(net "A_PCIE_RCOMP_N")
	)
	(segment
		(start 389.215884 -120.585484)
		(end 389.215884 -120.211596)
		(width 0.2032)
		(layer "B.Cu")
		(net "A_PCIE_RCOMP_N")
	)
	(segment
		(start 391.015474 -119.073168)
		(end 391.457942 -119.073168)
		(width 0.2032)
		(layer "B.Cu")
		(net "A_PCIE_RCOMP_N")
	)
	(segment
		(start 390.481566 -119.073168)
		(end 390.575292 -119.166894)
		(width 0.2032)
		(layer "B.Cu")
		(net "A_PCIE_RCOMP_N")
	)
	(segment
		(start 393.812776 -119.16537)
		(end 394.17625 -119.528844)
		(width 0.2032)
		(layer "B.Cu")
		(net "A_PCIE_RCOMP_N")
	)
	(segment
		(start 390.024874 -119.073168)
		(end 390.481566 -119.073168)
		(width 0.2032)
		(layer "B.Cu")
		(net "A_PCIE_RCOMP_N")
	)
	(segment
		(start 389.6868 -122.7582)
		(end 389.255 -122.3264)
		(width 0.2032)
		(layer "B.Cu")
		(net "A_PCIE_RCOMP_N")
	)
	(segment
		(start 389.2296 -123.6472)
		(end 389.6868 -123.19)
		(width 0.2032)
		(layer "B.Cu")
		(net "A_PCIE_RCOMP_N")
	)
	(segment
		(start 389.6868 -121.0564)
		(end 389.215884 -120.585484)
		(width 0.2032)
		(layer "B.Cu")
		(net "A_PCIE_RCOMP_N")
	)
	(segment
		(start 391.457942 -119.073168)
		(end 391.5537 -119.168926)
		(width 0.2032)
		(layer "B.Cu")
		(net "A_PCIE_RCOMP_N")
	)
	(segment
		(start 392.526012 -119.150638)
		(end 392.919204 -119.150638)
		(width 0.2032)
		(layer "B.Cu")
		(net "A_PCIE_RCOMP_N")
	)
	(segment
		(start 390.575292 -119.166894)
		(end 390.921748 -119.166894)
		(width 0.2032)
		(layer "B.Cu")
		(net "A_PCIE_RCOMP_N")
	)
	(segment
		(start 390.921748 -119.166894)
		(end 391.015474 -119.073168)
		(width 0.2032)
		(layer "B.Cu")
		(net "A_PCIE_RCOMP_N")
	)
	(segment
		(start 392.006074 -119.073168)
		(end 392.448542 -119.073168)
		(width 0.2032)
		(layer "B.Cu")
		(net "A_PCIE_RCOMP_N")
	)
	(segment
		(start 391.910316 -119.168926)
		(end 392.006074 -119.073168)
		(width 0.2032)
		(layer "B.Cu")
		(net "A_PCIE_RCOMP_N")
	)
	(segment
		(start 392.448542 -119.073168)
		(end 392.526012 -119.150638)
		(width 0.2032)
		(layer "B.Cu")
		(net "A_PCIE_RCOMP_N")
	)
	(segment
		(start 391.5537 -119.168926)
		(end 391.910316 -119.168926)
		(width 0.2032)
		(layer "B.Cu")
		(net "A_PCIE_RCOMP_N")
	)
	(segment
		(start 385.75615 -119.29872)
		(end 386.25145 -119.528844)
		(width 0.254)
		(layer "F.Cu")
		(net "A_PCIEUP_RCOMP_N")
	)
	(via
		(at 386.25145 -119.528844)
		(size 0.508)
		(drill 0.254)
		(layers "F.Cu" "B.Cu")
		(net "A_PCIEUP_RCOMP_N")
	)
	(segment
		(start 387.1214 -125.507242)
		(end 387.1214 -125.352048)
		(width 0.2032)
		(layer "B.Cu")
		(net "A_PCIEUP_RCOMP_N")
	)
	(segment
		(start 386.7404 -123.1646)
		(end 386.7404 -122.76582)
		(width 0.2032)
		(layer "B.Cu")
		(net "A_PCIEUP_RCOMP_N")
	)
	(segment
		(start 386.25145 -120.56745)
		(end 386.25145 -119.528844)
		(width 0.2032)
		(layer "B.Cu")
		(net "A_PCIEUP_RCOMP_N")
	)
	(segment
		(start 386.289804 -124.520452)
		(end 386.289804 -123.615196)
		(width 0.2032)
		(layer "B.Cu")
		(net "A_PCIEUP_RCOMP_N")
	)
	(segment
		(start 386.289804 -123.615196)
		(end 386.7404 -123.1646)
		(width 0.2032)
		(layer "B.Cu")
		(net "A_PCIEUP_RCOMP_N")
	)
	(segment
		(start 386.7404 -121.0564)
		(end 386.25145 -120.56745)
		(width 0.2032)
		(layer "B.Cu")
		(net "A_PCIEUP_RCOMP_N")
	)
	(segment
		(start 386.24764 -121.93016)
		(end 386.7404 -121.4374)
		(width 0.2032)
		(layer "B.Cu")
		(net "A_PCIEUP_RCOMP_N")
	)
	(segment
		(start 386.24764 -122.27306)
		(end 386.24764 -121.93016)
		(width 0.2032)
		(layer "B.Cu")
		(net "A_PCIEUP_RCOMP_N")
	)
	(segment
		(start 386.7404 -121.4374)
		(end 386.7404 -121.0564)
		(width 0.2032)
		(layer "B.Cu")
		(net "A_PCIEUP_RCOMP_N")
	)
	(segment
		(start 387.1214 -125.352048)
		(end 386.289804 -124.520452)
		(width 0.2032)
		(layer "B.Cu")
		(net "A_PCIEUP_RCOMP_N")
	)
	(segment
		(start 386.7404 -122.76582)
		(end 386.24764 -122.27306)
		(width 0.2032)
		(layer "B.Cu")
		(net "A_PCIEUP_RCOMP_N")
	)
	(segment
		(start 470.440004 -144.7165)
		(end 470.2175 -144.493996)
		(width 0.10795)
		(layer "F.Cu")
		(net "PU_KEY_CONN_PIN2_R")
	)
	(segment
		(start 472.948 -144.7165)
		(end 470.440004 -144.7165)
		(width 0.10795)
		(layer "F.Cu")
		(net "PU_KEY_CONN_PIN2_R")
	)
	(via
		(at 467.066122 -144.493996)
		(size 0.6604)
		(drill 0.3302)
		(layers "F.Cu" "B.Cu")
		(net "PU_KEY_CONN_PIN2_R")
	)
	(segment
		(start 470.2175 -144.493996)
		(end 467.066122 -144.493996)
		(width 0.10795)
		(layer "B.Cu")
		(net "PU_KEY_CONN_PIN2_R")
	)
	(segment
		(start 110.744 -68.834)
		(end 110.744 -68.961)
		(width 0.10795)
		(layer "F.Cu")
		(net "PU_CPU1_TXT_AGENT")
	)
	(segment
		(start 111.887 -67.691)
		(end 110.744 -68.834)
		(width 0.10795)
		(layer "F.Cu")
		(net "PU_CPU1_TXT_AGENT")
	)
	(segment
		(start 127.655828 -70.268084)
		(end 128.227074 -70.268084)
		(width 0.10795)
		(layer "F.Cu")
		(net "PU_CPU1_TXT_AGENT")
	)
	(segment
		(start 128.227074 -70.268084)
		(end 128.227328 -70.268338)
		(width 0.10795)
		(layer "F.Cu")
		(net "PU_CPU1_TXT_AGENT")
	)
	(via
		(at 128.227328 -70.268338)
		(size 0.508)
		(drill 0.254)
		(layers "F.Cu" "B.Cu")
		(net "PU_CPU1_TXT_AGENT")
	)
	(via
		(at 111.887 -67.691)
		(size 0.508)
		(drill 0.254)
		(layers "F.Cu" "B.Cu")
		(net "PU_CPU1_TXT_AGENT")
	)
	(segment
		(start 118.833646 -70.2691)
		(end 118.327424 -69.762878)
		(width 0.0889)
		(layer "In2.Cu")
		(net "PU_CPU1_TXT_AGENT")
	)
	(segment
		(start 113.748312 -69.595746)
		(end 113.735866 -69.5833)
		(width 0.0889)
		(layer "In2.Cu")
		(net "PU_CPU1_TXT_AGENT")
	)
	(segment
		(start 111.887 -67.756278)
		(end 111.887 -67.691)
		(width 0.0889)
		(layer "In2.Cu")
		(net "PU_CPU1_TXT_AGENT")
	)
	(segment
		(start 115.688618 -69.762878)
		(end 115.521486 -69.595746)
		(width 0.0889)
		(layer "In2.Cu")
		(net "PU_CPU1_TXT_AGENT")
	)
	(segment
		(start 124.618242 -69.869558)
		(end 124.31649 -70.17131)
		(width 0.0889)
		(layer "In2.Cu")
		(net "PU_CPU1_TXT_AGENT")
	)
	(segment
		(start 122.415808 -70.17131)
		(end 121.974356 -70.17131)
		(width 0.0889)
		(layer "In2.Cu")
		(net "PU_CPU1_TXT_AGENT")
	)
	(segment
		(start 124.31649 -70.17131)
		(end 123.54306 -70.17131)
		(width 0.0889)
		(layer "In2.Cu")
		(net "PU_CPU1_TXT_AGENT")
	)
	(segment
		(start 126.11862 -69.869558)
		(end 125.816868 -70.17131)
		(width 0.0889)
		(layer "In2.Cu")
		(net "PU_CPU1_TXT_AGENT")
	)
	(segment
		(start 127.01016 -70.17131)
		(end 126.708408 -69.869558)
		(width 0.0889)
		(layer "In2.Cu")
		(net "PU_CPU1_TXT_AGENT")
	)
	(segment
		(start 120.8278 -69.3674)
		(end 120.154954 -69.3674)
		(width 0.0889)
		(layer "In2.Cu")
		(net "PU_CPU1_TXT_AGENT")
	)
	(segment
		(start 115.521486 -69.595746)
		(end 113.748312 -69.595746)
		(width 0.0889)
		(layer "In2.Cu")
		(net "PU_CPU1_TXT_AGENT")
	)
	(segment
		(start 120.154954 -69.3674)
		(end 119.253254 -70.2691)
		(width 0.0889)
		(layer "In2.Cu")
		(net "PU_CPU1_TXT_AGENT")
	)
	(segment
		(start 122.71756 -69.869558)
		(end 122.415808 -70.17131)
		(width 0.0889)
		(layer "In2.Cu")
		(net "PU_CPU1_TXT_AGENT")
	)
	(segment
		(start 121.1453 -69.6849)
		(end 120.8278 -69.3674)
		(width 0.0889)
		(layer "In2.Cu")
		(net "PU_CPU1_TXT_AGENT")
	)
	(segment
		(start 121.974356 -70.17131)
		(end 121.487946 -69.6849)
		(width 0.0889)
		(layer "In2.Cu")
		(net "PU_CPU1_TXT_AGENT")
	)
	(segment
		(start 126.708408 -69.869558)
		(end 126.11862 -69.869558)
		(width 0.0889)
		(layer "In2.Cu")
		(net "PU_CPU1_TXT_AGENT")
	)
	(segment
		(start 123.241308 -69.869558)
		(end 122.71756 -69.869558)
		(width 0.0889)
		(layer "In2.Cu")
		(net "PU_CPU1_TXT_AGENT")
	)
	(segment
		(start 112.242854 -68.112386)
		(end 112.242854 -68.112132)
		(width 0.0889)
		(layer "In2.Cu")
		(net "PU_CPU1_TXT_AGENT")
	)
	(segment
		(start 124.958348 -69.869558)
		(end 124.618242 -69.869558)
		(width 0.0889)
		(layer "In2.Cu")
		(net "PU_CPU1_TXT_AGENT")
	)
	(segment
		(start 113.735866 -69.5833)
		(end 113.713768 -69.5833)
		(width 0.0889)
		(layer "In2.Cu")
		(net "PU_CPU1_TXT_AGENT")
	)
	(segment
		(start 125.2601 -70.17131)
		(end 124.958348 -69.869558)
		(width 0.0889)
		(layer "In2.Cu")
		(net "PU_CPU1_TXT_AGENT")
	)
	(segment
		(start 112.242854 -68.112132)
		(end 111.887 -67.756278)
		(width 0.0889)
		(layer "In2.Cu")
		(net "PU_CPU1_TXT_AGENT")
	)
	(segment
		(start 118.327424 -69.762878)
		(end 115.688618 -69.762878)
		(width 0.0889)
		(layer "In2.Cu")
		(net "PU_CPU1_TXT_AGENT")
	)
	(segment
		(start 128.227328 -70.268338)
		(end 128.1303 -70.17131)
		(width 0.0889)
		(layer "In2.Cu")
		(net "PU_CPU1_TXT_AGENT")
	)
	(segment
		(start 119.253254 -70.2691)
		(end 118.833646 -70.2691)
		(width 0.0889)
		(layer "In2.Cu")
		(net "PU_CPU1_TXT_AGENT")
	)
	(segment
		(start 123.54306 -70.17131)
		(end 123.241308 -69.869558)
		(width 0.0889)
		(layer "In2.Cu")
		(net "PU_CPU1_TXT_AGENT")
	)
	(segment
		(start 113.713768 -69.5833)
		(end 112.242854 -68.112386)
		(width 0.0889)
		(layer "In2.Cu")
		(net "PU_CPU1_TXT_AGENT")
	)
	(segment
		(start 128.1303 -70.17131)
		(end 127.01016 -70.17131)
		(width 0.0889)
		(layer "In2.Cu")
		(net "PU_CPU1_TXT_AGENT")
	)
	(segment
		(start 125.816868 -70.17131)
		(end 125.2601 -70.17131)
		(width 0.0889)
		(layer "In2.Cu")
		(net "PU_CPU1_TXT_AGENT")
	)
	(segment
		(start 121.487946 -69.6849)
		(end 121.1453 -69.6849)
		(width 0.0889)
		(layer "In2.Cu")
		(net "PU_CPU1_TXT_AGENT")
	)
	(segment
		(start 117.6782 -71.6534)
		(end 117.6782 -71.7804)
		(width 0.10795)
		(layer "F.Cu")
		(net "PU_CPU1_SOCKET_ID_1")
	)
	(segment
		(start 117.6782 -71.7804)
		(end 117.1956 -72.263)
		(width 0.10795)
		(layer "F.Cu")
		(net "PU_CPU1_SOCKET_ID_1")
	)
	(segment
		(start 129.372868 -69.277738)
		(end 129.944368 -69.277738)
		(width 0.10795)
		(layer "F.Cu")
		(net "PU_CPU1_SOCKET_ID_1")
	)
	(segment
		(start 118.1354 -71.1962)
		(end 117.6782 -71.6534)
		(width 0.10795)
		(layer "F.Cu")
		(net "PU_CPU1_SOCKET_ID_1")
	)
	(via
		(at 118.1354 -71.1962)
		(size 0.508)
		(drill 0.254)
		(layers "F.Cu" "B.Cu")
		(net "PU_CPU1_SOCKET_ID_1")
	)
	(via
		(at 129.944368 -69.277738)
		(size 0.508)
		(drill 0.254)
		(layers "F.Cu" "B.Cu")
		(net "PU_CPU1_SOCKET_ID_1")
	)
	(segment
		(start 124.982986 -67.701414)
		(end 125.47854 -67.20586)
		(width 0.089408)
		(layer "In11.Cu")
		(net "PU_CPU1_SOCKET_ID_1")
	)
	(segment
		(start 128.890268 -68.377308)
		(end 129.253742 -68.377308)
		(width 0.089408)
		(layer "In11.Cu")
		(net "PU_CPU1_SOCKET_ID_1")
	)
	(segment
		(start 124.417328 -67.701414)
		(end 124.982986 -67.701414)
		(width 0.089408)
		(layer "In11.Cu")
		(net "PU_CPU1_SOCKET_ID_1")
	)
	(segment
		(start 126.13386 -66.891662)
		(end 126.835662 -66.891662)
		(width 0.089408)
		(layer "In11.Cu")
		(net "PU_CPU1_SOCKET_ID_1")
	)
	(segment
		(start 127.536702 -67.386708)
		(end 128.032256 -67.882262)
		(width 0.089408)
		(layer "In11.Cu")
		(net "PU_CPU1_SOCKET_ID_1")
	)
	(segment
		(start 121.8438 -68.072)
		(end 122.682 -68.072)
		(width 0.089408)
		(layer "In11.Cu")
		(net "PU_CPU1_SOCKET_ID_1")
	)
	(segment
		(start 126.835662 -66.891662)
		(end 127.330708 -67.386708)
		(width 0.089408)
		(layer "In11.Cu")
		(net "PU_CPU1_SOCKET_ID_1")
	)
	(segment
		(start 120.8532 -68.5292)
		(end 121.3866 -68.5292)
		(width 0.089408)
		(layer "In11.Cu")
		(net "PU_CPU1_SOCKET_ID_1")
	)
	(segment
		(start 120.4976 -68.8848)
		(end 120.8532 -68.5292)
		(width 0.089408)
		(layer "In11.Cu")
		(net "PU_CPU1_SOCKET_ID_1")
	)
	(segment
		(start 119.7864 -69.1896)
		(end 120.0912 -68.8848)
		(width 0.089408)
		(layer "In11.Cu")
		(net "PU_CPU1_SOCKET_ID_1")
	)
	(segment
		(start 129.253742 -68.377308)
		(end 129.490724 -68.61429)
		(width 0.089408)
		(layer "In11.Cu")
		(net "PU_CPU1_SOCKET_ID_1")
	)
	(segment
		(start 129.490724 -68.824094)
		(end 129.944368 -69.277738)
		(width 0.089408)
		(layer "In11.Cu")
		(net "PU_CPU1_SOCKET_ID_1")
	)
	(segment
		(start 125.47854 -67.20586)
		(end 125.819662 -67.20586)
		(width 0.089408)
		(layer "In11.Cu")
		(net "PU_CPU1_SOCKET_ID_1")
	)
	(segment
		(start 129.490724 -68.61429)
		(end 129.490724 -68.824094)
		(width 0.089408)
		(layer "In11.Cu")
		(net "PU_CPU1_SOCKET_ID_1")
	)
	(segment
		(start 127.330708 -67.386708)
		(end 127.536702 -67.386708)
		(width 0.089408)
		(layer "In11.Cu")
		(net "PU_CPU1_SOCKET_ID_1")
	)
	(segment
		(start 125.819662 -67.20586)
		(end 126.13386 -66.891662)
		(width 0.089408)
		(layer "In11.Cu")
		(net "PU_CPU1_SOCKET_ID_1")
	)
	(segment
		(start 123.513342 -67.6402)
		(end 123.766834 -67.386708)
		(width 0.089408)
		(layer "In11.Cu")
		(net "PU_CPU1_SOCKET_ID_1")
	)
	(segment
		(start 118.1354 -69.85)
		(end 118.7958 -69.1896)
		(width 0.089408)
		(layer "In11.Cu")
		(net "PU_CPU1_SOCKET_ID_1")
	)
	(segment
		(start 123.1138 -67.6402)
		(end 123.513342 -67.6402)
		(width 0.089408)
		(layer "In11.Cu")
		(net "PU_CPU1_SOCKET_ID_1")
	)
	(segment
		(start 123.766834 -67.386708)
		(end 124.102622 -67.386708)
		(width 0.089408)
		(layer "In11.Cu")
		(net "PU_CPU1_SOCKET_ID_1")
	)
	(segment
		(start 124.102622 -67.386708)
		(end 124.417328 -67.701414)
		(width 0.089408)
		(layer "In11.Cu")
		(net "PU_CPU1_SOCKET_ID_1")
	)
	(segment
		(start 122.682 -68.072)
		(end 123.1138 -67.6402)
		(width 0.089408)
		(layer "In11.Cu")
		(net "PU_CPU1_SOCKET_ID_1")
	)
	(segment
		(start 120.0912 -68.8848)
		(end 120.4976 -68.8848)
		(width 0.089408)
		(layer "In11.Cu")
		(net "PU_CPU1_SOCKET_ID_1")
	)
	(segment
		(start 128.395222 -67.882262)
		(end 128.890268 -68.377308)
		(width 0.089408)
		(layer "In11.Cu")
		(net "PU_CPU1_SOCKET_ID_1")
	)
	(segment
		(start 128.032256 -67.882262)
		(end 128.395222 -67.882262)
		(width 0.089408)
		(layer "In11.Cu")
		(net "PU_CPU1_SOCKET_ID_1")
	)
	(segment
		(start 118.1354 -71.1962)
		(end 118.1354 -69.85)
		(width 0.089408)
		(layer "In11.Cu")
		(net "PU_CPU1_SOCKET_ID_1")
	)
	(segment
		(start 121.3866 -68.5292)
		(end 121.8438 -68.072)
		(width 0.089408)
		(layer "In11.Cu")
		(net "PU_CPU1_SOCKET_ID_1")
	)
	(segment
		(start 118.7958 -69.1896)
		(end 119.7864 -69.1896)
		(width 0.089408)
		(layer "In11.Cu")
		(net "PU_CPU1_SOCKET_ID_1")
	)
	(segment
		(start 124.221748 -69.277738)
		(end 124.793248 -69.277738)
		(width 0.10795)
		(layer "F.Cu")
		(net "PU_CPU1_SOCKET_ID_0")
	)
	(segment
		(start 112.57153 -67.89547)
		(end 111.633 -68.834)
		(width 0.10795)
		(layer "F.Cu")
		(net "PU_CPU1_SOCKET_ID_0")
	)
	(segment
		(start 112.879632 -67.89547)
		(end 112.57153 -67.89547)
		(width 0.10795)
		(layer "F.Cu")
		(net "PU_CPU1_SOCKET_ID_0")
	)
	(segment
		(start 111.633 -68.834)
		(end 111.633 -68.961)
		(width 0.10795)
		(layer "F.Cu")
		(net "PU_CPU1_SOCKET_ID_0")
	)
	(via
		(at 124.793248 -69.277738)
		(size 0.508)
		(drill 0.254)
		(layers "F.Cu" "B.Cu")
		(net "PU_CPU1_SOCKET_ID_0")
	)
	(via
		(at 112.879632 -67.89547)
		(size 0.508)
		(drill 0.254)
		(layers "F.Cu" "B.Cu")
		(net "PU_CPU1_SOCKET_ID_0")
	)
	(segment
		(start 122.878342 -68.879212)
		(end 122.382788 -68.383658)
		(width 0.0889)
		(layer "In2.Cu")
		(net "PU_CPU1_SOCKET_ID_0")
	)
	(segment
		(start 124.793248 -69.277738)
		(end 124.69622 -69.18071)
		(width 0.0889)
		(layer "In2.Cu")
		(net "PU_CPU1_SOCKET_ID_0")
	)
	(segment
		(start 120.904 -68.4784)
		(end 120.4849 -68.8975)
		(width 0.0889)
		(layer "In2.Cu")
		(net "PU_CPU1_SOCKET_ID_0")
	)
	(segment
		(start 119.567706 -69.215)
		(end 117.561106 -69.215)
		(width 0.0889)
		(layer "In2.Cu")
		(net "PU_CPU1_SOCKET_ID_0")
	)
	(segment
		(start 117.134132 -69.202554)
		(end 113.893854 -69.202554)
		(width 0.0889)
		(layer "In2.Cu")
		(net "PU_CPU1_SOCKET_ID_0")
	)
	(segment
		(start 120.4849 -68.8975)
		(end 119.885206 -68.8975)
		(width 0.0889)
		(layer "In2.Cu")
		(net "PU_CPU1_SOCKET_ID_0")
	)
	(segment
		(start 121.386854 -68.4784)
		(end 120.904 -68.4784)
		(width 0.0889)
		(layer "In2.Cu")
		(net "PU_CPU1_SOCKET_ID_0")
	)
	(segment
		(start 119.885206 -68.8975)
		(end 119.567706 -69.215)
		(width 0.0889)
		(layer "In2.Cu")
		(net "PU_CPU1_SOCKET_ID_0")
	)
	(segment
		(start 123.542806 -69.18071)
		(end 123.241308 -68.879212)
		(width 0.0889)
		(layer "In2.Cu")
		(net "PU_CPU1_SOCKET_ID_0")
	)
	(segment
		(start 122.382788 -68.383658)
		(end 121.481596 -68.383658)
		(width 0.0889)
		(layer "In2.Cu")
		(net "PU_CPU1_SOCKET_ID_0")
	)
	(segment
		(start 124.69622 -69.18071)
		(end 123.542806 -69.18071)
		(width 0.0889)
		(layer "In2.Cu")
		(net "PU_CPU1_SOCKET_ID_0")
	)
	(segment
		(start 117.188742 -69.257164)
		(end 117.134132 -69.202554)
		(width 0.0889)
		(layer "In2.Cu")
		(net "PU_CPU1_SOCKET_ID_0")
	)
	(segment
		(start 113.893854 -69.202554)
		(end 112.879632 -68.188332)
		(width 0.0889)
		(layer "In2.Cu")
		(net "PU_CPU1_SOCKET_ID_0")
	)
	(segment
		(start 117.561106 -69.215)
		(end 117.518942 -69.257164)
		(width 0.0889)
		(layer "In2.Cu")
		(net "PU_CPU1_SOCKET_ID_0")
	)
	(segment
		(start 112.879632 -68.188332)
		(end 112.879632 -67.89547)
		(width 0.0889)
		(layer "In2.Cu")
		(net "PU_CPU1_SOCKET_ID_0")
	)
	(segment
		(start 123.241308 -68.879212)
		(end 122.878342 -68.879212)
		(width 0.0889)
		(layer "In2.Cu")
		(net "PU_CPU1_SOCKET_ID_0")
	)
	(segment
		(start 117.518942 -69.257164)
		(end 117.188742 -69.257164)
		(width 0.0889)
		(layer "In2.Cu")
		(net "PU_CPU1_SOCKET_ID_0")
	)
	(segment
		(start 121.481596 -68.383658)
		(end 121.386854 -68.4784)
		(width 0.0889)
		(layer "In2.Cu")
		(net "PU_CPU1_SOCKET_ID_0")
	)
	(segment
		(start 113.506758 -67.859148)
		(end 113.1316 -68.234306)
		(width 0.10795)
		(layer "F.Cu")
		(net "PU_CPU1_SAFE_MODE_BOOT")
	)
	(segment
		(start 114.119152 -67.67449)
		(end 113.934494 -67.859148)
		(width 0.10795)
		(layer "F.Cu")
		(net "PU_CPU1_SAFE_MODE_BOOT")
	)
	(segment
		(start 127.655828 -68.287138)
		(end 128.227328 -68.287138)
		(width 0.10795)
		(layer "F.Cu")
		(net "PU_CPU1_SAFE_MODE_BOOT")
	)
	(segment
		(start 113.934494 -67.859148)
		(end 113.506758 -67.859148)
		(width 0.10795)
		(layer "F.Cu")
		(net "PU_CPU1_SAFE_MODE_BOOT")
	)
	(segment
		(start 113.1316 -68.2752)
		(end 112.4458 -68.961)
		(width 0.10795)
		(layer "F.Cu")
		(net "PU_CPU1_SAFE_MODE_BOOT")
	)
	(segment
		(start 113.1316 -68.234306)
		(end 113.1316 -68.2752)
		(width 0.10795)
		(layer "F.Cu")
		(net "PU_CPU1_SAFE_MODE_BOOT")
	)
	(via
		(at 114.119152 -67.67449)
		(size 0.508)
		(drill 0.254)
		(layers "F.Cu" "B.Cu")
		(net "PU_CPU1_SAFE_MODE_BOOT")
	)
	(via
		(at 128.227328 -68.287138)
		(size 0.508)
		(drill 0.254)
		(layers "F.Cu" "B.Cu")
		(net "PU_CPU1_SAFE_MODE_BOOT")
	)
	(segment
		(start 123.271788 -67.882262)
		(end 123.585986 -68.19646)
		(width 0.0889)
		(layer "In2.Cu")
		(net "PU_CPU1_SAFE_MODE_BOOT")
	)
	(segment
		(start 119.068596 -68.383658)
		(end 119.739918 -68.383658)
		(width 0.0889)
		(layer "In2.Cu")
		(net "PU_CPU1_SAFE_MODE_BOOT")
	)
	(segment
		(start 116.68379 -68.76161)
		(end 116.985288 -68.460112)
		(width 0.0889)
		(layer "In2.Cu")
		(net "PU_CPU1_SAFE_MODE_BOOT")
	)
	(segment
		(start 120.041924 -68.685664)
		(end 120.427242 -68.685664)
		(width 0.0889)
		(layer "In2.Cu")
		(net "PU_CPU1_SAFE_MODE_BOOT")
	)
	(segment
		(start 121.2215 -68.2879)
		(end 121.627138 -67.882262)
		(width 0.0889)
		(layer "In2.Cu")
		(net "PU_CPU1_SAFE_MODE_BOOT")
	)
	(segment
		(start 126.886716 -67.882262)
		(end 127.194564 -68.19011)
		(width 0.0889)
		(layer "In2.Cu")
		(net "PU_CPU1_SAFE_MODE_BOOT")
	)
	(segment
		(start 117.619018 -68.460112)
		(end 117.84457 -68.685664)
		(width 0.0889)
		(layer "In2.Cu")
		(net "PU_CPU1_SAFE_MODE_BOOT")
	)
	(segment
		(start 114.6937 -68.9991)
		(end 115.3287 -68.9991)
		(width 0.0889)
		(layer "In2.Cu")
		(net "PU_CPU1_SAFE_MODE_BOOT")
	)
	(segment
		(start 125.346714 -68.19646)
		(end 125.973078 -68.19646)
		(width 0.0889)
		(layer "In2.Cu")
		(net "PU_CPU1_SAFE_MODE_BOOT")
	)
	(segment
		(start 120.427242 -68.685664)
		(end 120.825006 -68.2879)
		(width 0.0889)
		(layer "In2.Cu")
		(net "PU_CPU1_SAFE_MODE_BOOT")
	)
	(segment
		(start 125.032516 -67.882262)
		(end 125.346714 -68.19646)
		(width 0.0889)
		(layer "In2.Cu")
		(net "PU_CPU1_SAFE_MODE_BOOT")
	)
	(segment
		(start 127.194564 -68.19011)
		(end 127.543052 -68.19011)
		(width 0.0889)
		(layer "In2.Cu")
		(net "PU_CPU1_SAFE_MODE_BOOT")
	)
	(segment
		(start 119.739918 -68.383658)
		(end 120.041924 -68.685664)
		(width 0.0889)
		(layer "In2.Cu")
		(net "PU_CPU1_SAFE_MODE_BOOT")
	)
	(segment
		(start 120.825006 -68.2879)
		(end 121.2215 -68.2879)
		(width 0.0889)
		(layer "In2.Cu")
		(net "PU_CPU1_SAFE_MODE_BOOT")
	)
	(segment
		(start 123.585986 -68.19646)
		(end 124.309886 -68.19646)
		(width 0.0889)
		(layer "In2.Cu")
		(net "PU_CPU1_SAFE_MODE_BOOT")
	)
	(segment
		(start 114.5032 -68.8086)
		(end 114.6937 -68.9991)
		(width 0.0889)
		(layer "In2.Cu")
		(net "PU_CPU1_SAFE_MODE_BOOT")
	)
	(segment
		(start 127.543052 -68.19011)
		(end 127.584962 -68.1482)
		(width 0.0889)
		(layer "In2.Cu")
		(net "PU_CPU1_SAFE_MODE_BOOT")
	)
	(segment
		(start 127.584962 -68.1482)
		(end 128.08839 -68.1482)
		(width 0.0889)
		(layer "In2.Cu")
		(net "PU_CPU1_SAFE_MODE_BOOT")
	)
	(segment
		(start 115.56619 -68.76161)
		(end 116.68379 -68.76161)
		(width 0.0889)
		(layer "In2.Cu")
		(net "PU_CPU1_SAFE_MODE_BOOT")
	)
	(segment
		(start 116.985288 -68.460112)
		(end 117.619018 -68.460112)
		(width 0.0889)
		(layer "In2.Cu")
		(net "PU_CPU1_SAFE_MODE_BOOT")
	)
	(segment
		(start 118.76659 -68.685664)
		(end 119.068596 -68.383658)
		(width 0.0889)
		(layer "In2.Cu")
		(net "PU_CPU1_SAFE_MODE_BOOT")
	)
	(segment
		(start 115.3287 -68.9991)
		(end 115.56619 -68.76161)
		(width 0.0889)
		(layer "In2.Cu")
		(net "PU_CPU1_SAFE_MODE_BOOT")
	)
	(segment
		(start 121.627138 -67.882262)
		(end 123.271788 -67.882262)
		(width 0.0889)
		(layer "In2.Cu")
		(net "PU_CPU1_SAFE_MODE_BOOT")
	)
	(segment
		(start 114.119152 -67.67449)
		(end 114.5032 -68.058538)
		(width 0.0889)
		(layer "In2.Cu")
		(net "PU_CPU1_SAFE_MODE_BOOT")
	)
	(segment
		(start 128.08839 -68.1482)
		(end 128.227328 -68.287138)
		(width 0.0889)
		(layer "In2.Cu")
		(net "PU_CPU1_SAFE_MODE_BOOT")
	)
	(segment
		(start 124.309886 -68.19646)
		(end 124.624084 -67.882262)
		(width 0.0889)
		(layer "In2.Cu")
		(net "PU_CPU1_SAFE_MODE_BOOT")
	)
	(segment
		(start 125.973078 -68.19646)
		(end 126.287276 -67.882262)
		(width 0.0889)
		(layer "In2.Cu")
		(net "PU_CPU1_SAFE_MODE_BOOT")
	)
	(segment
		(start 114.5032 -68.058538)
		(end 114.5032 -68.8086)
		(width 0.0889)
		(layer "In2.Cu")
		(net "PU_CPU1_SAFE_MODE_BOOT")
	)
	(segment
		(start 126.287276 -67.882262)
		(end 126.886716 -67.882262)
		(width 0.0889)
		(layer "In2.Cu")
		(net "PU_CPU1_SAFE_MODE_BOOT")
	)
	(segment
		(start 124.624084 -67.882262)
		(end 125.032516 -67.882262)
		(width 0.0889)
		(layer "In2.Cu")
		(net "PU_CPU1_SAFE_MODE_BOOT")
	)
	(segment
		(start 117.84457 -68.685664)
		(end 118.76659 -68.685664)
		(width 0.0889)
		(layer "In2.Cu")
		(net "PU_CPU1_SAFE_MODE_BOOT")
	)
	(segment
		(start 111.700056 -66.979546)
		(end 111.674656 -66.979546)
		(width 0.10795)
		(layer "F.Cu")
		(net "PU_CPU1_FRMAGENT")
	)
	(segment
		(start 111.506 -67.5386)
		(end 110.5154 -68.5292)
		(width 0.10795)
		(layer "F.Cu")
		(net "PU_CPU1_FRMAGENT")
	)
	(segment
		(start 111.506 -67.148202)
		(end 111.506 -67.5386)
		(width 0.10795)
		(layer "F.Cu")
		(net "PU_CPU1_FRMAGENT")
	)
	(segment
		(start 110.1598 -68.5292)
		(end 109.728 -68.961)
		(width 0.10795)
		(layer "F.Cu")
		(net "PU_CPU1_FRMAGENT")
	)
	(segment
		(start 110.5154 -68.5292)
		(end 110.1598 -68.5292)
		(width 0.10795)
		(layer "F.Cu")
		(net "PU_CPU1_FRMAGENT")
	)
	(segment
		(start 128.514348 -69.772784)
		(end 129.085848 -69.772784)
		(width 0.10795)
		(layer "F.Cu")
		(net "PU_CPU1_FRMAGENT")
	)
	(segment
		(start 111.674656 -66.979546)
		(end 111.506 -67.148202)
		(width 0.10795)
		(layer "F.Cu")
		(net "PU_CPU1_FRMAGENT")
	)
	(via
		(at 129.085848 -69.772784)
		(size 0.508)
		(drill 0.254)
		(layers "F.Cu" "B.Cu")
		(net "PU_CPU1_FRMAGENT")
	)
	(via
		(at 111.700056 -66.979546)
		(size 0.508)
		(drill 0.254)
		(layers "F.Cu" "B.Cu")
		(net "PU_CPU1_FRMAGENT")
	)
	(segment
		(start 125.47854 -69.18706)
		(end 124.989336 -69.676264)
		(width 0.0889)
		(layer "In2.Cu")
		(net "PU_CPU1_FRMAGENT")
	)
	(segment
		(start 119.6467 -69.4055)
		(end 117.6401 -69.4055)
		(width 0.0889)
		(layer "In2.Cu")
		(net "PU_CPU1_FRMAGENT")
	)
	(segment
		(start 120.858788 -68.879212)
		(end 120.65 -69.088)
		(width 0.0889)
		(layer "In2.Cu")
		(net "PU_CPU1_FRMAGENT")
	)
	(segment
		(start 122.4788 -69.342)
		(end 122.1994 -69.342)
		(width 0.0889)
		(layer "In2.Cu")
		(net "PU_CPU1_FRMAGENT")
	)
	(segment
		(start 127.202438 -69.188584)
		(end 126.886716 -68.872862)
		(width 0.0889)
		(layer "In2.Cu")
		(net "PU_CPU1_FRMAGENT")
	)
	(segment
		(start 112.115346 -66.979546)
		(end 111.700056 -66.979546)
		(width 0.0889)
		(layer "In2.Cu")
		(net "PU_CPU1_FRMAGENT")
	)
	(segment
		(start 121.736612 -68.879212)
		(end 120.858788 -68.879212)
		(width 0.0889)
		(layer "In2.Cu")
		(net "PU_CPU1_FRMAGENT")
	)
	(segment
		(start 122.1994 -69.342)
		(end 121.736612 -68.879212)
		(width 0.0889)
		(layer "In2.Cu")
		(net "PU_CPU1_FRMAGENT")
	)
	(segment
		(start 117.6401 -69.4055)
		(end 117.597936 -69.447664)
		(width 0.0889)
		(layer "In2.Cu")
		(net "PU_CPU1_FRMAGENT")
	)
	(segment
		(start 117.109748 -69.447664)
		(end 117.055138 -69.393054)
		(width 0.0889)
		(layer "In2.Cu")
		(net "PU_CPU1_FRMAGENT")
	)
	(segment
		(start 112.433354 -67.297554)
		(end 112.115346 -66.979546)
		(width 0.0889)
		(layer "In2.Cu")
		(net "PU_CPU1_FRMAGENT")
	)
	(segment
		(start 127.562864 -69.188584)
		(end 127.202438 -69.188584)
		(width 0.0889)
		(layer "In2.Cu")
		(net "PU_CPU1_FRMAGENT")
	)
	(segment
		(start 126.13386 -68.872862)
		(end 125.819662 -69.18706)
		(width 0.0889)
		(layer "In2.Cu")
		(net "PU_CPU1_FRMAGENT")
	)
	(segment
		(start 117.055138 -69.393054)
		(end 113.81486 -69.393054)
		(width 0.0889)
		(layer "In2.Cu")
		(net "PU_CPU1_FRMAGENT")
	)
	(segment
		(start 113.81486 -69.393054)
		(end 113.814606 -69.3928)
		(width 0.0889)
		(layer "In2.Cu")
		(net "PU_CPU1_FRMAGENT")
	)
	(segment
		(start 128.147064 -69.772784)
		(end 127.562864 -69.188584)
		(width 0.0889)
		(layer "In2.Cu")
		(net "PU_CPU1_FRMAGENT")
	)
	(segment
		(start 124.263912 -69.374258)
		(end 123.716542 -69.374258)
		(width 0.0889)
		(layer "In2.Cu")
		(net "PU_CPU1_FRMAGENT")
	)
	(segment
		(start 129.085848 -69.772784)
		(end 128.147064 -69.772784)
		(width 0.0889)
		(layer "In2.Cu")
		(net "PU_CPU1_FRMAGENT")
	)
	(segment
		(start 112.433354 -68.033392)
		(end 112.433354 -67.297554)
		(width 0.0889)
		(layer "In2.Cu")
		(net "PU_CPU1_FRMAGENT")
	)
	(segment
		(start 120.65 -69.088)
		(end 119.9642 -69.088)
		(width 0.0889)
		(layer "In2.Cu")
		(net "PU_CPU1_FRMAGENT")
	)
	(segment
		(start 113.814606 -69.3928)
		(end 113.792762 -69.3928)
		(width 0.0889)
		(layer "In2.Cu")
		(net "PU_CPU1_FRMAGENT")
	)
	(segment
		(start 125.819662 -69.18706)
		(end 125.47854 -69.18706)
		(width 0.0889)
		(layer "In2.Cu")
		(net "PU_CPU1_FRMAGENT")
	)
	(segment
		(start 123.414536 -69.676264)
		(end 122.813064 -69.676264)
		(width 0.0889)
		(layer "In2.Cu")
		(net "PU_CPU1_FRMAGENT")
	)
	(segment
		(start 117.597936 -69.447664)
		(end 117.109748 -69.447664)
		(width 0.0889)
		(layer "In2.Cu")
		(net "PU_CPU1_FRMAGENT")
	)
	(segment
		(start 123.716542 -69.374258)
		(end 123.414536 -69.676264)
		(width 0.0889)
		(layer "In2.Cu")
		(net "PU_CPU1_FRMAGENT")
	)
	(segment
		(start 119.9642 -69.088)
		(end 119.6467 -69.4055)
		(width 0.0889)
		(layer "In2.Cu")
		(net "PU_CPU1_FRMAGENT")
	)
	(segment
		(start 122.813064 -69.676264)
		(end 122.4788 -69.342)
		(width 0.0889)
		(layer "In2.Cu")
		(net "PU_CPU1_FRMAGENT")
	)
	(segment
		(start 113.792762 -69.3928)
		(end 112.433354 -68.033392)
		(width 0.0889)
		(layer "In2.Cu")
		(net "PU_CPU1_FRMAGENT")
	)
	(segment
		(start 124.565918 -69.676264)
		(end 124.263912 -69.374258)
		(width 0.0889)
		(layer "In2.Cu")
		(net "PU_CPU1_FRMAGENT")
	)
	(segment
		(start 124.989336 -69.676264)
		(end 124.565918 -69.676264)
		(width 0.0889)
		(layer "In2.Cu")
		(net "PU_CPU1_FRMAGENT")
	)
	(segment
		(start 126.886716 -68.872862)
		(end 126.13386 -68.872862)
		(width 0.0889)
		(layer "In2.Cu")
		(net "PU_CPU1_FRMAGENT")
	)
	(segment
		(start 115.02771 -68.600574)
		(end 114.210084 -69.4182)
		(width 0.10795)
		(layer "F.Cu")
		(net "PD_CPU1_EAR_N")
	)
	(segment
		(start 131.089908 -65.315338)
		(end 131.661408 -65.315338)
		(width 0.10795)
		(layer "F.Cu")
		(net "PD_CPU1_EAR_N")
	)
	(segment
		(start 114.210084 -69.4182)
		(end 114.0714 -69.4182)
		(width 0.10795)
		(layer "F.Cu")
		(net "PD_CPU1_EAR_N")
	)
	(via
		(at 115.02771 -68.600574)
		(size 0.508)
		(drill 0.254)
		(layers "F.Cu" "B.Cu")
		(net "PD_CPU1_EAR_N")
	)
	(via
		(at 131.661408 -65.315338)
		(size 0.508)
		(drill 0.254)
		(layers "F.Cu" "B.Cu")
		(net "PD_CPU1_EAR_N")
	)
	(segment
		(start 116.26215 -67.887596)
		(end 116.900706 -67.887596)
		(width 0.089408)
		(layer "In2.Cu")
		(net "PD_CPU1_EAR_N")
	)
	(segment
		(start 127.71755 -65.22466)
		(end 128.081024 -64.861186)
		(width 0.089408)
		(layer "In2.Cu")
		(net "PD_CPU1_EAR_N")
	)
	(segment
		(start 115.869466 -68.28028)
		(end 116.26215 -67.887596)
		(width 0.089408)
		(layer "In2.Cu")
		(net "PD_CPU1_EAR_N")
	)
	(segment
		(start 124.656088 -65.906142)
		(end 125.156722 -65.405508)
		(width 0.0889)
		(layer "In2.Cu")
		(net "PD_CPU1_EAR_N")
	)
	(segment
		(start 118.268496 -67.887596)
		(end 118.269004 -67.887088)
		(width 0.0889)
		(layer "In2.Cu")
		(net "PD_CPU1_EAR_N")
	)
	(segment
		(start 126.99238 -65.22466)
		(end 127.71755 -65.22466)
		(width 0.089408)
		(layer "In2.Cu")
		(net "PD_CPU1_EAR_N")
	)
	(segment
		(start 118.269004 -67.887088)
		(end 118.517162 -67.887088)
		(width 0.0889)
		(layer "In2.Cu")
		(net "PD_CPU1_EAR_N")
	)
	(segment
		(start 126.678182 -64.910462)
		(end 126.99238 -65.22466)
		(width 0.089408)
		(layer "In2.Cu")
		(net "PD_CPU1_EAR_N")
	)
	(segment
		(start 125.84684 -65.405508)
		(end 126.341886 -64.910462)
		(width 0.089408)
		(layer "In2.Cu")
		(net "PD_CPU1_EAR_N")
	)
	(segment
		(start 121.063512 -67.391534)
		(end 121.096278 -67.391534)
		(width 0.0889)
		(layer "In2.Cu")
		(net "PD_CPU1_EAR_N")
	)
	(segment
		(start 130.365754 -65.315338)
		(end 131.661408 -65.315338)
		(width 0.089408)
		(layer "In2.Cu")
		(net "PD_CPU1_EAR_N")
	)
	(segment
		(start 119.701056 -67.585844)
		(end 119.704358 -67.591686)
		(width 0.0889)
		(layer "In2.Cu")
		(net "PD_CPU1_EAR_N")
	)
	(segment
		(start 126.341886 -64.910462)
		(end 126.678182 -64.910462)
		(width 0.089408)
		(layer "In2.Cu")
		(net "PD_CPU1_EAR_N")
	)
	(segment
		(start 129.911602 -64.861186)
		(end 130.365754 -65.315338)
		(width 0.089408)
		(layer "In2.Cu")
		(net "PD_CPU1_EAR_N")
	)
	(segment
		(start 116.900706 -67.887596)
		(end 118.268496 -67.887596)
		(width 0.0889)
		(layer "In2.Cu")
		(net "PD_CPU1_EAR_N")
	)
	(segment
		(start 115.348004 -68.28028)
		(end 115.869466 -68.28028)
		(width 0.089408)
		(layer "In2.Cu")
		(net "PD_CPU1_EAR_N")
	)
	(segment
		(start 123.649486 -65.906142)
		(end 124.656088 -65.906142)
		(width 0.0889)
		(layer "In2.Cu")
		(net "PD_CPU1_EAR_N")
	)
	(segment
		(start 125.156722 -65.405508)
		(end 125.84684 -65.405508)
		(width 0.089408)
		(layer "In2.Cu")
		(net "PD_CPU1_EAR_N")
	)
	(segment
		(start 128.081024 -64.861186)
		(end 129.911602 -64.861186)
		(width 0.089408)
		(layer "In2.Cu")
		(net "PD_CPU1_EAR_N")
	)
	(segment
		(start 121.918222 -66.896488)
		(end 121.950988 -66.896488)
		(width 0.0889)
		(layer "In2.Cu")
		(net "PD_CPU1_EAR_N")
	)
	(segment
		(start 115.02771 -68.600574)
		(end 115.348004 -68.28028)
		(width 0.089408)
		(layer "In2.Cu")
		(net "PD_CPU1_EAR_N")
	)
	(segment
		(start 122.780552 -66.400934)
		(end 122.813318 -66.400934)
		(width 0.0889)
		(layer "In2.Cu")
		(net "PD_CPU1_EAR_N")
	)
	(arc
		(start 118.517162 -67.887088)
		(mid 118.802586 -67.803621)
		(end 119.011192 -67.591686)
		(width 0.0889)
		(layer "In2.Cu")
		(net "PD_CPU1_EAR_N")
	)
	(arc
		(start 123.303538 -66.105786)
		(mid 123.449773 -65.959629)
		(end 123.649486 -65.906142)
		(width 0.0889)
		(layer "In2.Cu")
		(net "PD_CPU1_EAR_N")
	)
	(arc
		(start 121.586498 -67.096386)
		(mid 121.726577 -66.95365)
		(end 121.918222 -66.896488)
		(width 0.0889)
		(layer "In2.Cu")
		(net "PD_CPU1_EAR_N")
	)
	(arc
		(start 121.096278 -67.391534)
		(mid 121.379495 -67.307253)
		(end 121.586498 -67.096386)
		(width 0.0889)
		(layer "In2.Cu")
		(net "PD_CPU1_EAR_N")
	)
	(arc
		(start 121.950988 -66.896488)
		(mid 122.236412 -66.813021)
		(end 122.445018 -66.601086)
		(width 0.0889)
		(layer "In2.Cu")
		(net "PD_CPU1_EAR_N")
	)
	(arc
		(start 122.445018 -66.601086)
		(mid 122.586701 -66.457282)
		(end 122.780552 -66.400934)
		(width 0.0889)
		(layer "In2.Cu")
		(net "PD_CPU1_EAR_N")
	)
	(arc
		(start 120.727978 -67.591686)
		(mid 120.869661 -67.447882)
		(end 121.063512 -67.391534)
		(width 0.0889)
		(layer "In2.Cu")
		(net "PD_CPU1_EAR_N")
	)
	(arc
		(start 122.813318 -66.400934)
		(mid 123.096535 -66.316653)
		(end 123.303538 -66.105786)
		(width 0.0889)
		(layer "In2.Cu")
		(net "PD_CPU1_EAR_N")
	)
	(arc
		(start 119.704358 -67.591686)
		(mid 120.216168 -67.887353)
		(end 120.727978 -67.591686)
		(width 0.0889)
		(layer "In2.Cu")
		(net "PD_CPU1_EAR_N")
	)
	(arc
		(start 119.011192 -67.591686)
		(mid 119.354482 -67.39139)
		(end 119.701056 -67.585844)
		(width 0.0889)
		(layer "In2.Cu")
		(net "PD_CPU1_EAR_N")
	)
	(segment
		(start 118.550436 -73.448164)
		(end 117.9322 -74.0664)
		(width 0.10795)
		(layer "F.Cu")
		(net "H_CPU1_BMCINIT")
	)
	(segment
		(start 117.9322 -74.0664)
		(end 117.7036 -74.0664)
		(width 0.10795)
		(layer "F.Cu")
		(net "H_CPU1_BMCINIT")
	)
	(segment
		(start 117.7036 -74.0664)
		(end 117.1702 -74.5998)
		(width 0.10795)
		(layer "F.Cu")
		(net "H_CPU1_BMCINIT")
	)
	(segment
		(start 117.303804 -72.916796)
		(end 118.550436 -72.916796)
		(width 0.10795)
		(layer "F.Cu")
		(net "H_CPU1_BMCINIT")
	)
	(segment
		(start 118.550436 -72.916796)
		(end 118.550436 -73.448164)
		(width 0.10795)
		(layer "F.Cu")
		(net "H_CPU1_BMCINIT")
	)
	(segment
		(start 117.1956 -73.025)
		(end 117.303804 -72.916796)
		(width 0.10795)
		(layer "F.Cu")
		(net "H_CPU1_BMCINIT")
	)
	(segment
		(start 123.363228 -72.744584)
		(end 123.934728 -72.744584)
		(width 0.10795)
		(layer "F.Cu")
		(net "H_CPU1_BMCINIT")
	)
	(via
		(at 123.934728 -72.744584)
		(size 0.508)
		(drill 0.254)
		(layers "F.Cu" "B.Cu")
		(net "H_CPU1_BMCINIT")
	)
	(via
		(at 118.550436 -72.916796)
		(size 0.508)
		(drill 0.254)
		(layers "F.Cu" "B.Cu")
		(net "H_CPU1_BMCINIT")
	)
	(segment
		(start 118.550436 -72.916796)
		(end 118.78564 -73.152)
		(width 0.089408)
		(layer "In11.Cu")
		(net "H_CPU1_BMCINIT")
	)
	(segment
		(start 123.112276 -72.840088)
		(end 123.934728 -72.744584)
		(width 0.089408)
		(layer "In11.Cu")
		(net "H_CPU1_BMCINIT")
	)
	(segment
		(start 119.9388 -73.152)
		(end 120.617488 -73.830688)
		(width 0.089408)
		(layer "In11.Cu")
		(net "H_CPU1_BMCINIT")
	)
	(segment
		(start 120.617488 -73.830688)
		(end 121.376948 -73.830688)
		(width 0.089408)
		(layer "In11.Cu")
		(net "H_CPU1_BMCINIT")
	)
	(segment
		(start 122.206512 -73.335134)
		(end 122.239278 -73.335134)
		(width 0.089408)
		(layer "In11.Cu")
		(net "H_CPU1_BMCINIT")
	)
	(segment
		(start 123.061222 -72.840088)
		(end 123.112276 -72.840088)
		(width 0.089408)
		(layer "In11.Cu")
		(net "H_CPU1_BMCINIT")
	)
	(segment
		(start 118.78564 -73.152)
		(end 119.9388 -73.152)
		(width 0.089408)
		(layer "In11.Cu")
		(net "H_CPU1_BMCINIT")
	)
	(arc
		(start 121.376948 -73.830688)
		(mid 121.662372 -73.747221)
		(end 121.870978 -73.535286)
		(width 0.089408)
		(layer "In11.Cu")
		(net "H_CPU1_BMCINIT")
	)
	(arc
		(start 122.239278 -73.335134)
		(mid 122.522495 -73.250853)
		(end 122.729498 -73.039986)
		(width 0.089408)
		(layer "In11.Cu")
		(net "H_CPU1_BMCINIT")
	)
	(arc
		(start 121.870978 -73.535286)
		(mid 122.012661 -73.391482)
		(end 122.206512 -73.335134)
		(width 0.089408)
		(layer "In11.Cu")
		(net "H_CPU1_BMCINIT")
	)
	(arc
		(start 122.729498 -73.039986)
		(mid 122.869577 -72.89725)
		(end 123.061222 -72.840088)
		(width 0.089408)
		(layer "In11.Cu")
		(net "H_CPU1_BMCINIT")
	)
	(segment
		(start 293.227506 -70.268084)
		(end 293.22776 -70.268338)
		(width 0.10795)
		(layer "F.Cu")
		(net "PU_CPU0_TXT_AGENT")
	)
	(segment
		(start 292.65626 -70.268084)
		(end 293.227506 -70.268084)
		(width 0.10795)
		(layer "F.Cu")
		(net "PU_CPU0_TXT_AGENT")
	)
	(segment
		(start 276.606 -67.818)
		(end 275.463 -68.961)
		(width 0.10795)
		(layer "F.Cu")
		(net "PU_CPU0_TXT_AGENT")
	)
	(segment
		(start 275.463 -68.961)
		(end 275.463 -69.088)
		(width 0.10795)
		(layer "F.Cu")
		(net "PU_CPU0_TXT_AGENT")
	)
	(via
		(at 276.606 -67.818)
		(size 0.508)
		(drill 0.254)
		(layers "F.Cu" "B.Cu")
		(net "PU_CPU0_TXT_AGENT")
	)
	(via
		(at 293.22776 -70.268338)
		(size 0.508)
		(drill 0.254)
		(layers "F.Cu" "B.Cu")
		(net "PU_CPU0_TXT_AGENT")
	)
	(segment
		(start 293.130732 -70.17131)
		(end 293.22776 -70.268338)
		(width 0.0889)
		(layer "In2.Cu")
		(net "PU_CPU0_TXT_AGENT")
	)
	(segment
		(start 284.757114 -71.919338)
		(end 284.757114 -71.676768)
		(width 0.089408)
		(layer "In2.Cu")
		(net "PU_CPU0_TXT_AGENT")
	)
	(segment
		(start 284.110176 -72.06996)
		(end 284.19298 -72.152764)
		(width 0.089408)
		(layer "In2.Cu")
		(net "PU_CPU0_TXT_AGENT")
	)
	(segment
		(start 276.606 -67.818)
		(end 276.606 -68.199)
		(width 0.089408)
		(layer "In2.Cu")
		(net "PU_CPU0_TXT_AGENT")
	)
	(segment
		(start 282.73502 -72.06996)
		(end 284.110176 -72.06996)
		(width 0.089408)
		(layer "In2.Cu")
		(net "PU_CPU0_TXT_AGENT")
	)
	(segment
		(start 287.206944 -70.363334)
		(end 287.229296 -70.363334)
		(width 0.0889)
		(layer "In2.Cu")
		(net "PU_CPU0_TXT_AGENT")
	)
	(segment
		(start 278.384 -71.374)
		(end 282.03906 -71.374)
		(width 0.089408)
		(layer "In2.Cu")
		(net "PU_CPU0_TXT_AGENT")
	)
	(segment
		(start 288.063686 -70.858888)
		(end 288.089594 -70.858888)
		(width 0.0889)
		(layer "In2.Cu")
		(net "PU_CPU0_TXT_AGENT")
	)
	(segment
		(start 284.523688 -72.152764)
		(end 284.757114 -71.919338)
		(width 0.089408)
		(layer "In2.Cu")
		(net "PU_CPU0_TXT_AGENT")
	)
	(segment
		(start 288.923984 -70.363334)
		(end 288.946336 -70.363334)
		(width 0.0889)
		(layer "In2.Cu")
		(net "PU_CPU0_TXT_AGENT")
	)
	(segment
		(start 291.901118 -69.868288)
		(end 292.20414 -70.17131)
		(width 0.0889)
		(layer "In2.Cu")
		(net "PU_CPU0_TXT_AGENT")
	)
	(segment
		(start 290.641024 -70.363334)
		(end 290.67379 -70.363334)
		(width 0.0889)
		(layer "In2.Cu")
		(net "PU_CPU0_TXT_AGENT")
	)
	(segment
		(start 278.13 -71.12)
		(end 278.384 -71.374)
		(width 0.089408)
		(layer "In2.Cu")
		(net "PU_CPU0_TXT_AGENT")
	)
	(segment
		(start 278.13 -69.723)
		(end 278.13 -71.12)
		(width 0.089408)
		(layer "In2.Cu")
		(net "PU_CPU0_TXT_AGENT")
	)
	(segment
		(start 276.606 -68.199)
		(end 278.13 -69.723)
		(width 0.089408)
		(layer "In2.Cu")
		(net "PU_CPU0_TXT_AGENT")
	)
	(segment
		(start 284.757114 -71.676768)
		(end 285.574994 -70.858888)
		(width 0.089408)
		(layer "In2.Cu")
		(net "PU_CPU0_TXT_AGENT")
	)
	(segment
		(start 289.780726 -70.858888)
		(end 289.806634 -70.858888)
		(width 0.0889)
		(layer "In2.Cu")
		(net "PU_CPU0_TXT_AGENT")
	)
	(segment
		(start 282.03906 -71.374)
		(end 282.73502 -72.06996)
		(width 0.089408)
		(layer "In2.Cu")
		(net "PU_CPU0_TXT_AGENT")
	)
	(segment
		(start 284.19298 -72.152764)
		(end 284.523688 -72.152764)
		(width 0.089408)
		(layer "In2.Cu")
		(net "PU_CPU0_TXT_AGENT")
	)
	(segment
		(start 292.20414 -70.17131)
		(end 293.130732 -70.17131)
		(width 0.0889)
		(layer "In2.Cu")
		(net "PU_CPU0_TXT_AGENT")
	)
	(segment
		(start 285.574994 -70.858888)
		(end 286.372554 -70.858888)
		(width 0.0889)
		(layer "In2.Cu")
		(net "PU_CPU0_TXT_AGENT")
	)
	(segment
		(start 291.492686 -69.868288)
		(end 291.901118 -69.868288)
		(width 0.0889)
		(layer "In2.Cu")
		(net "PU_CPU0_TXT_AGENT")
	)
	(arc
		(start 287.56483 -70.563486)
		(mid 287.775543 -70.776565)
		(end 288.063686 -70.858888)
		(width 0.0889)
		(layer "In2.Cu")
		(net "PU_CPU0_TXT_AGENT")
	)
	(arc
		(start 290.67379 -70.363334)
		(mid 290.957007 -70.279053)
		(end 291.16401 -70.068186)
		(width 0.0889)
		(layer "In2.Cu")
		(net "PU_CPU0_TXT_AGENT")
	)
	(arc
		(start 286.87141 -70.563486)
		(mid 287.013093 -70.419682)
		(end 287.206944 -70.363334)
		(width 0.0889)
		(layer "In2.Cu")
		(net "PU_CPU0_TXT_AGENT")
	)
	(arc
		(start 289.28187 -70.563486)
		(mid 289.492583 -70.776565)
		(end 289.780726 -70.858888)
		(width 0.0889)
		(layer "In2.Cu")
		(net "PU_CPU0_TXT_AGENT")
	)
	(arc
		(start 286.372554 -70.858888)
		(mid 286.660699 -70.776569)
		(end 286.87141 -70.563486)
		(width 0.0889)
		(layer "In2.Cu")
		(net "PU_CPU0_TXT_AGENT")
	)
	(arc
		(start 288.946336 -70.363334)
		(mid 289.140186 -70.419684)
		(end 289.28187 -70.563486)
		(width 0.0889)
		(layer "In2.Cu")
		(net "PU_CPU0_TXT_AGENT")
	)
	(arc
		(start 291.16401 -70.068186)
		(mid 291.302754 -69.926153)
		(end 291.492686 -69.868288)
		(width 0.0889)
		(layer "In2.Cu")
		(net "PU_CPU0_TXT_AGENT")
	)
	(arc
		(start 289.806634 -70.858888)
		(mid 290.094779 -70.776569)
		(end 290.30549 -70.563486)
		(width 0.0889)
		(layer "In2.Cu")
		(net "PU_CPU0_TXT_AGENT")
	)
	(arc
		(start 288.089594 -70.858888)
		(mid 288.377739 -70.776569)
		(end 288.58845 -70.563486)
		(width 0.0889)
		(layer "In2.Cu")
		(net "PU_CPU0_TXT_AGENT")
	)
	(arc
		(start 290.30549 -70.563486)
		(mid 290.447173 -70.419682)
		(end 290.641024 -70.363334)
		(width 0.0889)
		(layer "In2.Cu")
		(net "PU_CPU0_TXT_AGENT")
	)
	(arc
		(start 288.58845 -70.563486)
		(mid 288.730133 -70.419682)
		(end 288.923984 -70.363334)
		(width 0.0889)
		(layer "In2.Cu")
		(net "PU_CPU0_TXT_AGENT")
	)
	(arc
		(start 287.229296 -70.363334)
		(mid 287.423146 -70.419684)
		(end 287.56483 -70.563486)
		(width 0.0889)
		(layer "In2.Cu")
		(net "PU_CPU0_TXT_AGENT")
	)
	(segment
		(start 282.669742 -71.660258)
		(end 282.067 -72.263)
		(width 0.10795)
		(layer "F.Cu")
		(net "PU_CPU0_SOCKET_ID_1")
	)
	(segment
		(start 294.3733 -69.277738)
		(end 294.9448 -69.277738)
		(width 0.10795)
		(layer "F.Cu")
		(net "PU_CPU0_SOCKET_ID_1")
	)
	(segment
		(start 283.04236 -71.26224)
		(end 283.04236 -71.552308)
		(width 0.10795)
		(layer "F.Cu")
		(net "PU_CPU0_SOCKET_ID_1")
	)
	(segment
		(start 283.04236 -71.552308)
		(end 282.93441 -71.660258)
		(width 0.10795)
		(layer "F.Cu")
		(net "PU_CPU0_SOCKET_ID_1")
	)
	(segment
		(start 282.93441 -71.660258)
		(end 282.669742 -71.660258)
		(width 0.10795)
		(layer "F.Cu")
		(net "PU_CPU0_SOCKET_ID_1")
	)
	(via
		(at 283.04236 -71.26224)
		(size 0.508)
		(drill 0.254)
		(layers "F.Cu" "B.Cu")
		(net "PU_CPU0_SOCKET_ID_1")
	)
	(via
		(at 294.9448 -69.277738)
		(size 0.508)
		(drill 0.254)
		(layers "F.Cu" "B.Cu")
		(net "PU_CPU0_SOCKET_ID_1")
	)
	(segment
		(start 292.775386 -68.650866)
		(end 292.95344 -68.82892)
		(width 0.089408)
		(layer "In11.Cu")
		(net "PU_CPU0_SOCKET_ID_1")
	)
	(segment
		(start 283.50337 -71.168514)
		(end 284.672786 -71.168514)
		(width 0.089408)
		(layer "In11.Cu")
		(net "PU_CPU0_SOCKET_ID_1")
	)
	(segment
		(start 288.46272 -67.61988)
		(end 289.2552 -66.8274)
		(width 0.089408)
		(layer "In11.Cu")
		(net "PU_CPU0_SOCKET_ID_1")
	)
	(segment
		(start 289.2552 -66.8274)
		(end 290.104068 -66.8274)
		(width 0.089408)
		(layer "In11.Cu")
		(net "PU_CPU0_SOCKET_ID_1")
	)
	(segment
		(start 292.95344 -68.82892)
		(end 293.52494 -68.82892)
		(width 0.089408)
		(layer "In11.Cu")
		(net "PU_CPU0_SOCKET_ID_1")
	)
	(segment
		(start 291.200332 -66.8274)
		(end 291.674296 -66.8274)
		(width 0.089408)
		(layer "In11.Cu")
		(net "PU_CPU0_SOCKET_ID_1")
	)
	(segment
		(start 285.212536 -70.133464)
		(end 287.72612 -67.61988)
		(width 0.089408)
		(layer "In11.Cu")
		(net "PU_CPU0_SOCKET_ID_1")
	)
	(segment
		(start 292.537642 -67.385438)
		(end 292.775386 -67.623182)
		(width 0.089408)
		(layer "In11.Cu")
		(net "PU_CPU0_SOCKET_ID_1")
	)
	(segment
		(start 293.52494 -68.82892)
		(end 293.973758 -69.277738)
		(width 0.089408)
		(layer "In11.Cu")
		(net "PU_CPU0_SOCKET_ID_1")
	)
	(segment
		(start 292.232334 -67.385438)
		(end 292.537642 -67.385438)
		(width 0.089408)
		(layer "In11.Cu")
		(net "PU_CPU0_SOCKET_ID_1")
	)
	(segment
		(start 285.212536 -70.628764)
		(end 285.212536 -70.133464)
		(width 0.089408)
		(layer "In11.Cu")
		(net "PU_CPU0_SOCKET_ID_1")
	)
	(segment
		(start 290.477956 -67.201288)
		(end 290.826444 -67.201288)
		(width 0.089408)
		(layer "In11.Cu")
		(net "PU_CPU0_SOCKET_ID_1")
	)
	(segment
		(start 287.72612 -67.61988)
		(end 288.46272 -67.61988)
		(width 0.089408)
		(layer "In11.Cu")
		(net "PU_CPU0_SOCKET_ID_1")
	)
	(segment
		(start 290.826444 -67.201288)
		(end 291.200332 -66.8274)
		(width 0.089408)
		(layer "In11.Cu")
		(net "PU_CPU0_SOCKET_ID_1")
	)
	(segment
		(start 283.04236 -71.26224)
		(end 283.409644 -71.26224)
		(width 0.089408)
		(layer "In11.Cu")
		(net "PU_CPU0_SOCKET_ID_1")
	)
	(segment
		(start 290.104068 -66.8274)
		(end 290.477956 -67.201288)
		(width 0.089408)
		(layer "In11.Cu")
		(net "PU_CPU0_SOCKET_ID_1")
	)
	(segment
		(start 293.973758 -69.277738)
		(end 294.9448 -69.277738)
		(width 0.089408)
		(layer "In11.Cu")
		(net "PU_CPU0_SOCKET_ID_1")
	)
	(segment
		(start 291.674296 -66.8274)
		(end 292.232334 -67.385438)
		(width 0.089408)
		(layer "In11.Cu")
		(net "PU_CPU0_SOCKET_ID_1")
	)
	(segment
		(start 283.409644 -71.26224)
		(end 283.50337 -71.168514)
		(width 0.089408)
		(layer "In11.Cu")
		(net "PU_CPU0_SOCKET_ID_1")
	)
	(segment
		(start 284.672786 -71.168514)
		(end 285.212536 -70.628764)
		(width 0.089408)
		(layer "In11.Cu")
		(net "PU_CPU0_SOCKET_ID_1")
	)
	(segment
		(start 292.775386 -67.623182)
		(end 292.775386 -68.650866)
		(width 0.089408)
		(layer "In11.Cu")
		(net "PU_CPU0_SOCKET_ID_1")
	)
	(segment
		(start 277.622 -68.326)
		(end 277.241 -68.707)
		(width 0.10795)
		(layer "F.Cu")
		(net "PU_CPU0_SOCKET_ID_0")
	)
	(segment
		(start 289.22218 -69.277738)
		(end 289.79368 -69.277738)
		(width 0.10795)
		(layer "F.Cu")
		(net "PU_CPU0_SOCKET_ID_0")
	)
	(segment
		(start 278.25446 -68.326)
		(end 277.622 -68.326)
		(width 0.10795)
		(layer "F.Cu")
		(net "PU_CPU0_SOCKET_ID_0")
	)
	(segment
		(start 277.241 -68.707)
		(end 277.241 -69.088)
		(width 0.10795)
		(layer "F.Cu")
		(net "PU_CPU0_SOCKET_ID_0")
	)
	(segment
		(start 278.3078 -68.27266)
		(end 278.25446 -68.326)
		(width 0.10795)
		(layer "F.Cu")
		(net "PU_CPU0_SOCKET_ID_0")
	)
	(via
		(at 289.79368 -69.277738)
		(size 0.508)
		(drill 0.254)
		(layers "F.Cu" "B.Cu")
		(net "PU_CPU0_SOCKET_ID_0")
	)
	(via
		(at 278.3078 -68.27266)
		(size 0.508)
		(drill 0.254)
		(layers "F.Cu" "B.Cu")
		(net "PU_CPU0_SOCKET_ID_0")
	)
	(segment
		(start 279.654 -68.707)
		(end 280.855166 -69.908166)
		(width 0.089408)
		(layer "In2.Cu")
		(net "PU_CPU0_SOCKET_ID_0")
	)
	(segment
		(start 284.84322 -69.6468)
		(end 286.380174 -69.6468)
		(width 0.089408)
		(layer "In2.Cu")
		(net "PU_CPU0_SOCKET_ID_0")
	)
	(segment
		(start 286.883602 -69.143372)
		(end 287.646872 -69.143372)
		(width 0.089408)
		(layer "In2.Cu")
		(net "PU_CPU0_SOCKET_ID_0")
	)
	(segment
		(start 278.74214 -68.707)
		(end 279.654 -68.707)
		(width 0.089408)
		(layer "In2.Cu")
		(net "PU_CPU0_SOCKET_ID_0")
	)
	(segment
		(start 286.380174 -69.6468)
		(end 286.883602 -69.143372)
		(width 0.089408)
		(layer "In2.Cu")
		(net "PU_CPU0_SOCKET_ID_0")
	)
	(segment
		(start 278.3078 -68.27266)
		(end 278.74214 -68.707)
		(width 0.089408)
		(layer "In2.Cu")
		(net "PU_CPU0_SOCKET_ID_0")
	)
	(segment
		(start 284.23362 -70.2564)
		(end 284.84322 -69.6468)
		(width 0.089408)
		(layer "In2.Cu")
		(net "PU_CPU0_SOCKET_ID_0")
	)
	(segment
		(start 288.426398 -68.878958)
		(end 288.730182 -69.182742)
		(width 0.089408)
		(layer "In2.Cu")
		(net "PU_CPU0_SOCKET_ID_0")
	)
	(segment
		(start 280.855166 -69.908166)
		(end 283.420566 -69.908166)
		(width 0.089408)
		(layer "In2.Cu")
		(net "PU_CPU0_SOCKET_ID_0")
	)
	(segment
		(start 288.730182 -69.182742)
		(end 289.698684 -69.182742)
		(width 0.089408)
		(layer "In2.Cu")
		(net "PU_CPU0_SOCKET_ID_0")
	)
	(segment
		(start 283.420566 -69.908166)
		(end 283.7688 -70.2564)
		(width 0.089408)
		(layer "In2.Cu")
		(net "PU_CPU0_SOCKET_ID_0")
	)
	(segment
		(start 283.7688 -70.2564)
		(end 284.23362 -70.2564)
		(width 0.089408)
		(layer "In2.Cu")
		(net "PU_CPU0_SOCKET_ID_0")
	)
	(segment
		(start 287.646872 -69.143372)
		(end 287.911286 -68.878958)
		(width 0.089408)
		(layer "In2.Cu")
		(net "PU_CPU0_SOCKET_ID_0")
	)
	(segment
		(start 289.698684 -69.182742)
		(end 289.79368 -69.277738)
		(width 0.089408)
		(layer "In2.Cu")
		(net "PU_CPU0_SOCKET_ID_0")
	)
	(segment
		(start 287.911286 -68.878958)
		(end 288.426398 -68.878958)
		(width 0.089408)
		(layer "In2.Cu")
		(net "PU_CPU0_SOCKET_ID_0")
	)
	(segment
		(start 277.4442 -67.8688)
		(end 276.352 -68.961)
		(width 0.10795)
		(layer "F.Cu")
		(net "PU_CPU0_SAFE_MODE_BOOT")
	)
	(segment
		(start 276.352 -68.961)
		(end 276.352 -69.088)
		(width 0.10795)
		(layer "F.Cu")
		(net "PU_CPU0_SAFE_MODE_BOOT")
	)
	(segment
		(start 292.65626 -68.287138)
		(end 293.22776 -68.287138)
		(width 0.10795)
		(layer "F.Cu")
		(net "PU_CPU0_SAFE_MODE_BOOT")
	)
	(via
		(at 277.4442 -67.8688)
		(size 0.508)
		(drill 0.254)
		(layers "F.Cu" "B.Cu")
		(net "PU_CPU0_SAFE_MODE_BOOT")
	)
	(via
		(at 293.22776 -68.287138)
		(size 0.508)
		(drill 0.254)
		(layers "F.Cu" "B.Cu")
		(net "PU_CPU0_SAFE_MODE_BOOT")
	)
	(segment
		(start 284.53969 -71.16191)
		(end 285.8516 -69.85)
		(width 0.089408)
		(layer "In2.Cu")
		(net "PU_CPU0_SAFE_MODE_BOOT")
	)
	(segment
		(start 281.279346 -70.739)
		(end 282.27782 -70.739)
		(width 0.089408)
		(layer "In2.Cu")
		(net "PU_CPU0_SAFE_MODE_BOOT")
	)
	(segment
		(start 284.16631 -71.16191)
		(end 284.53969 -71.16191)
		(width 0.0889)
		(layer "In2.Cu")
		(net "PU_CPU0_SAFE_MODE_BOOT")
	)
	(segment
		(start 282.54452 -70.4723)
		(end 283.4767 -70.4723)
		(width 0.089408)
		(layer "In2.Cu")
		(net "PU_CPU0_SAFE_MODE_BOOT")
	)
	(segment
		(start 280.745946 -70.2056)
		(end 281.279346 -70.739)
		(width 0.089408)
		(layer "In2.Cu")
		(net "PU_CPU0_SAFE_MODE_BOOT")
	)
	(segment
		(start 287.354518 -69.334634)
		(end 287.743138 -69.723254)
		(width 0.089408)
		(layer "In2.Cu")
		(net "PU_CPU0_SAFE_MODE_BOOT")
	)
	(segment
		(start 290.123372 -69.726048)
		(end 290.667186 -69.182234)
		(width 0.089408)
		(layer "In2.Cu")
		(net "PU_CPU0_SAFE_MODE_BOOT")
	)
	(segment
		(start 286.52978 -69.85)
		(end 287.045146 -69.334634)
		(width 0.089408)
		(layer "In2.Cu")
		(net "PU_CPU0_SAFE_MODE_BOOT")
	)
	(segment
		(start 282.27782 -70.739)
		(end 282.54452 -70.4723)
		(width 0.089408)
		(layer "In2.Cu")
		(net "PU_CPU0_SAFE_MODE_BOOT")
	)
	(segment
		(start 292.35146 -68.191634)
		(end 292.405308 -68.191634)
		(width 0.089408)
		(layer "In2.Cu")
		(net "PU_CPU0_SAFE_MODE_BOOT")
	)
	(segment
		(start 287.743138 -69.723254)
		(end 288.334958 -69.723254)
		(width 0.089408)
		(layer "In2.Cu")
		(net "PU_CPU0_SAFE_MODE_BOOT")
	)
	(segment
		(start 288.684208 -69.374004)
		(end 289.183064 -69.374004)
		(width 0.089408)
		(layer "In2.Cu")
		(net "PU_CPU0_SAFE_MODE_BOOT")
	)
	(segment
		(start 277.4442 -67.8688)
		(end 277.4442 -68.0212)
		(width 0.089408)
		(layer "In2.Cu")
		(net "PU_CPU0_SAFE_MODE_BOOT")
	)
	(segment
		(start 289.535108 -69.726048)
		(end 290.123372 -69.726048)
		(width 0.089408)
		(layer "In2.Cu")
		(net "PU_CPU0_SAFE_MODE_BOOT")
	)
	(segment
		(start 287.045146 -69.334634)
		(end 287.354518 -69.334634)
		(width 0.089408)
		(layer "In2.Cu")
		(net "PU_CPU0_SAFE_MODE_BOOT")
	)
	(segment
		(start 288.334958 -69.723254)
		(end 288.684208 -69.374004)
		(width 0.089408)
		(layer "In2.Cu")
		(net "PU_CPU0_SAFE_MODE_BOOT")
	)
	(segment
		(start 285.8516 -69.85)
		(end 286.52978 -69.85)
		(width 0.089408)
		(layer "In2.Cu")
		(net "PU_CPU0_SAFE_MODE_BOOT")
	)
	(segment
		(start 279.6286 -70.2056)
		(end 280.745946 -70.2056)
		(width 0.089408)
		(layer "In2.Cu")
		(net "PU_CPU0_SAFE_MODE_BOOT")
	)
	(segment
		(start 292.405308 -68.191634)
		(end 293.22776 -68.287138)
		(width 0.089408)
		(layer "In2.Cu")
		(net "PU_CPU0_SAFE_MODE_BOOT")
	)
	(segment
		(start 277.4442 -68.0212)
		(end 279.6286 -70.2056)
		(width 0.089408)
		(layer "In2.Cu")
		(net "PU_CPU0_SAFE_MODE_BOOT")
	)
	(segment
		(start 283.4767 -70.4723)
		(end 284.16631 -71.16191)
		(width 0.089408)
		(layer "In2.Cu")
		(net "PU_CPU0_SAFE_MODE_BOOT")
	)
	(segment
		(start 291.48913 -68.687188)
		(end 291.521896 -68.687188)
		(width 0.089408)
		(layer "In2.Cu")
		(net "PU_CPU0_SAFE_MODE_BOOT")
	)
	(segment
		(start 289.183064 -69.374004)
		(end 289.535108 -69.726048)
		(width 0.089408)
		(layer "In2.Cu")
		(net "PU_CPU0_SAFE_MODE_BOOT")
	)
	(arc
		(start 290.99891 -68.982336)
		(mid 291.205914 -68.771472)
		(end 291.48913 -68.687188)
		(width 0.089408)
		(layer "In2.Cu")
		(net "PU_CPU0_SAFE_MODE_BOOT")
	)
	(arc
		(start 291.85743 -68.487036)
		(mid 292.066038 -68.275104)
		(end 292.35146 -68.191634)
		(width 0.089408)
		(layer "In2.Cu")
		(net "PU_CPU0_SAFE_MODE_BOOT")
	)
	(arc
		(start 290.667186 -69.182234)
		(mid 290.858828 -69.125068)
		(end 290.99891 -68.982336)
		(width 0.089408)
		(layer "In2.Cu")
		(net "PU_CPU0_SAFE_MODE_BOOT")
	)
	(arc
		(start 291.521896 -68.687188)
		(mid 291.715746 -68.630838)
		(end 291.85743 -68.487036)
		(width 0.089408)
		(layer "In2.Cu")
		(net "PU_CPU0_SAFE_MODE_BOOT")
	)
	(segment
		(start 275.2344 -68.6562)
		(end 276.225 -67.6656)
		(width 0.10795)
		(layer "F.Cu")
		(net "PU_CPU0_FRMAGENT")
	)
	(segment
		(start 276.606 -67.183)
		(end 276.6314 -67.183)
		(width 0.10795)
		(layer "F.Cu")
		(net "PU_CPU0_FRMAGENT")
	)
	(segment
		(start 293.51478 -69.772784)
		(end 294.08628 -69.772784)
		(width 0.10795)
		(layer "F.Cu")
		(net "PU_CPU0_FRMAGENT")
	)
	(segment
		(start 276.225 -67.564)
		(end 276.606 -67.183)
		(width 0.10795)
		(layer "F.Cu")
		(net "PU_CPU0_FRMAGENT")
	)
	(segment
		(start 274.8788 -68.6562)
		(end 275.2344 -68.6562)
		(width 0.10795)
		(layer "F.Cu")
		(net "PU_CPU0_FRMAGENT")
	)
	(segment
		(start 276.225 -67.6656)
		(end 276.225 -67.564)
		(width 0.10795)
		(layer "F.Cu")
		(net "PU_CPU0_FRMAGENT")
	)
	(segment
		(start 274.447 -69.088)
		(end 274.8788 -68.6562)
		(width 0.10795)
		(layer "F.Cu")
		(net "PU_CPU0_FRMAGENT")
	)
	(via
		(at 294.08628 -69.772784)
		(size 0.508)
		(drill 0.254)
		(layers "F.Cu" "B.Cu")
		(net "PU_CPU0_FRMAGENT")
	)
	(via
		(at 276.6314 -67.183)
		(size 0.508)
		(drill 0.254)
		(layers "F.Cu" "B.Cu")
		(net "PU_CPU0_FRMAGENT")
	)
	(segment
		(start 286.106616 -70.668134)
		(end 286.3596 -70.668134)
		(width 0.089408)
		(layer "In2.Cu")
		(net "PU_CPU0_FRMAGENT")
	)
	(segment
		(start 292.35146 -69.182234)
		(end 292.38702 -69.182234)
		(width 0.089408)
		(layer "In2.Cu")
		(net "PU_CPU0_FRMAGENT")
	)
	(segment
		(start 280.543 -70.4342)
		(end 281.0764 -70.9676)
		(width 0.089408)
		(layer "In2.Cu")
		(net "PU_CPU0_FRMAGENT")
	)
	(segment
		(start 283.882338 -71.355204)
		(end 284.671262 -71.355204)
		(width 0.089408)
		(layer "In2.Cu")
		(net "PU_CPU0_FRMAGENT")
	)
	(segment
		(start 287.19653 -70.172834)
		(end 287.23971 -70.172834)
		(width 0.0889)
		(layer "In2.Cu")
		(net "PU_CPU0_FRMAGENT")
	)
	(segment
		(start 291.48913 -69.677534)
		(end 291.528754 -69.677534)
		(width 0.0889)
		(layer "In2.Cu")
		(net "PU_CPU0_FRMAGENT")
	)
	(segment
		(start 293.264336 -69.677534)
		(end 294.08628 -69.772784)
		(width 0.0889)
		(layer "In2.Cu")
		(net "PU_CPU0_FRMAGENT")
	)
	(segment
		(start 288.065464 -70.668134)
		(end 288.087816 -70.668134)
		(width 0.0889)
		(layer "In2.Cu")
		(net "PU_CPU0_FRMAGENT")
	)
	(segment
		(start 277.621746 -68.707)
		(end 277.749 -68.707)
		(width 0.089408)
		(layer "In2.Cu")
		(net "PU_CPU0_FRMAGENT")
	)
	(segment
		(start 277.0124 -67.564)
		(end 277.0124 -68.097654)
		(width 0.089408)
		(layer "In2.Cu")
		(net "PU_CPU0_FRMAGENT")
	)
	(segment
		(start 286.3596 -70.668134)
		(end 286.370776 -70.668134)
		(width 0.0889)
		(layer "In2.Cu")
		(net "PU_CPU0_FRMAGENT")
	)
	(segment
		(start 283.225494 -70.69836)
		(end 283.882338 -71.355204)
		(width 0.089408)
		(layer "In2.Cu")
		(net "PU_CPU0_FRMAGENT")
	)
	(segment
		(start 282.38704 -70.9676)
		(end 282.65628 -70.69836)
		(width 0.089408)
		(layer "In2.Cu")
		(net "PU_CPU0_FRMAGENT")
	)
	(segment
		(start 285.951168 -70.512686)
		(end 286.106616 -70.668134)
		(width 0.089408)
		(layer "In2.Cu")
		(net "PU_CPU0_FRMAGENT")
	)
	(segment
		(start 290.63061 -70.172834)
		(end 290.663376 -70.172834)
		(width 0.0889)
		(layer "In2.Cu")
		(net "PU_CPU0_FRMAGENT")
	)
	(segment
		(start 285.51378 -70.512686)
		(end 285.951168 -70.512686)
		(width 0.089408)
		(layer "In2.Cu")
		(net "PU_CPU0_FRMAGENT")
	)
	(segment
		(start 282.65628 -70.69836)
		(end 283.225494 -70.69836)
		(width 0.089408)
		(layer "In2.Cu")
		(net "PU_CPU0_FRMAGENT")
	)
	(segment
		(start 289.782504 -70.668134)
		(end 289.804856 -70.668134)
		(width 0.0889)
		(layer "In2.Cu")
		(net "PU_CPU0_FRMAGENT")
	)
	(segment
		(start 293.209726 -69.677534)
		(end 293.264336 -69.677534)
		(width 0.0889)
		(layer "In2.Cu")
		(net "PU_CPU0_FRMAGENT")
	)
	(segment
		(start 276.6314 -67.183)
		(end 277.0124 -67.564)
		(width 0.089408)
		(layer "In2.Cu")
		(net "PU_CPU0_FRMAGENT")
	)
	(segment
		(start 284.671262 -71.355204)
		(end 285.51378 -70.512686)
		(width 0.089408)
		(layer "In2.Cu")
		(net "PU_CPU0_FRMAGENT")
	)
	(segment
		(start 277.0124 -68.097654)
		(end 277.621746 -68.707)
		(width 0.089408)
		(layer "In2.Cu")
		(net "PU_CPU0_FRMAGENT")
	)
	(segment
		(start 281.0764 -70.9676)
		(end 282.38704 -70.9676)
		(width 0.089408)
		(layer "In2.Cu")
		(net "PU_CPU0_FRMAGENT")
	)
	(segment
		(start 279.4762 -70.4342)
		(end 280.543 -70.4342)
		(width 0.089408)
		(layer "In2.Cu")
		(net "PU_CPU0_FRMAGENT")
	)
	(segment
		(start 288.91357 -70.172834)
		(end 288.95675 -70.172834)
		(width 0.0889)
		(layer "In2.Cu")
		(net "PU_CPU0_FRMAGENT")
	)
	(segment
		(start 277.749 -68.707)
		(end 279.4762 -70.4342)
		(width 0.089408)
		(layer "In2.Cu")
		(net "PU_CPU0_FRMAGENT")
	)
	(arc
		(start 287.72993 -70.467982)
		(mid 287.871613 -70.611786)
		(end 288.065464 -70.668134)
		(width 0.0889)
		(layer "In2.Cu")
		(net "PU_CPU0_FRMAGENT")
	)
	(arc
		(start 287.23971 -70.172834)
		(mid 287.522927 -70.257115)
		(end 287.72993 -70.467982)
		(width 0.0889)
		(layer "In2.Cu")
		(net "PU_CPU0_FRMAGENT")
	)
	(arc
		(start 289.804856 -70.668134)
		(mid 289.998706 -70.611784)
		(end 290.14039 -70.467982)
		(width 0.0889)
		(layer "In2.Cu")
		(net "PU_CPU0_FRMAGENT")
	)
	(arc
		(start 291.85743 -69.477636)
		(mid 292.066038 -69.265704)
		(end 292.35146 -69.182234)
		(width 0.0889)
		(layer "In2.Cu")
		(net "PU_CPU0_FRMAGENT")
	)
	(arc
		(start 292.88105 -69.477636)
		(mid 293.019794 -69.619669)
		(end 293.209726 -69.677534)
		(width 0.0889)
		(layer "In2.Cu")
		(net "PU_CPU0_FRMAGENT")
	)
	(arc
		(start 291.528754 -69.677534)
		(mid 291.718683 -69.619664)
		(end 291.85743 -69.477636)
		(width 0.0889)
		(layer "In2.Cu")
		(net "PU_CPU0_FRMAGENT")
	)
	(arc
		(start 286.370776 -70.668134)
		(mid 286.564626 -70.611784)
		(end 286.70631 -70.467982)
		(width 0.0889)
		(layer "In2.Cu")
		(net "PU_CPU0_FRMAGENT")
	)
	(arc
		(start 288.95675 -70.172834)
		(mid 289.239967 -70.257115)
		(end 289.44697 -70.467982)
		(width 0.0889)
		(layer "In2.Cu")
		(net "PU_CPU0_FRMAGENT")
	)
	(arc
		(start 292.38702 -69.182234)
		(mid 292.672444 -69.265701)
		(end 292.88105 -69.477636)
		(width 0.0889)
		(layer "In2.Cu")
		(net "PU_CPU0_FRMAGENT")
	)
	(arc
		(start 288.42335 -70.467982)
		(mid 288.630354 -70.257118)
		(end 288.91357 -70.172834)
		(width 0.0889)
		(layer "In2.Cu")
		(net "PU_CPU0_FRMAGENT")
	)
	(arc
		(start 289.44697 -70.467982)
		(mid 289.588653 -70.611786)
		(end 289.782504 -70.668134)
		(width 0.0889)
		(layer "In2.Cu")
		(net "PU_CPU0_FRMAGENT")
	)
	(arc
		(start 290.99891 -69.972682)
		(mid 291.205914 -69.761818)
		(end 291.48913 -69.677534)
		(width 0.0889)
		(layer "In2.Cu")
		(net "PU_CPU0_FRMAGENT")
	)
	(arc
		(start 286.70631 -70.467982)
		(mid 286.913314 -70.257118)
		(end 287.19653 -70.172834)
		(width 0.0889)
		(layer "In2.Cu")
		(net "PU_CPU0_FRMAGENT")
	)
	(arc
		(start 290.14039 -70.467982)
		(mid 290.347394 -70.257118)
		(end 290.63061 -70.172834)
		(width 0.0889)
		(layer "In2.Cu")
		(net "PU_CPU0_FRMAGENT")
	)
	(arc
		(start 288.087816 -70.668134)
		(mid 288.281666 -70.611784)
		(end 288.42335 -70.467982)
		(width 0.0889)
		(layer "In2.Cu")
		(net "PU_CPU0_FRMAGENT")
	)
	(arc
		(start 290.663376 -70.172834)
		(mid 290.857226 -70.116484)
		(end 290.99891 -69.972682)
		(width 0.0889)
		(layer "In2.Cu")
		(net "PU_CPU0_FRMAGENT")
	)
	(segment
		(start 296.66184 -65.315338)
		(end 296.09034 -65.315338)
		(width 0.10795)
		(layer "F.Cu")
		(net "PD_CPU0_EAR_N")
	)
	(segment
		(start 278.070056 -69.080888)
		(end 278.45766 -69.080888)
		(width 0.10795)
		(layer "F.Cu")
		(net "PD_CPU0_EAR_N")
	)
	(segment
		(start 278.742394 -68.796154)
		(end 278.742394 -67.973194)
		(width 0.10795)
		(layer "F.Cu")
		(net "PD_CPU0_EAR_N")
	)
	(segment
		(start 278.45766 -69.080888)
		(end 278.742394 -68.796154)
		(width 0.10795)
		(layer "F.Cu")
		(net "PD_CPU0_EAR_N")
	)
	(segment
		(start 278.742394 -67.973194)
		(end 278.3078 -67.5386)
		(width 0.10795)
		(layer "F.Cu")
		(net "PD_CPU0_EAR_N")
	)
	(via
		(at 278.3078 -67.5386)
		(size 0.508)
		(drill 0.254)
		(layers "F.Cu" "B.Cu")
		(net "PD_CPU0_EAR_N")
	)
	(via
		(at 296.66184 -65.315338)
		(size 0.508)
		(drill 0.254)
		(layers "F.Cu" "B.Cu")
		(net "PD_CPU0_EAR_N")
	)
	(segment
		(start 296.975784 -65.067688)
		(end 296.954702 -65.146428)
		(width 0.0889)
		(layer "In2.Cu")
		(net "PD_CPU0_EAR_N")
	)
	(segment
		(start 295.45661 -64.619886)
		(end 295.456864 -64.619886)
		(width 0.0889)
		(layer "In2.Cu")
		(net "PD_CPU0_EAR_N")
	)
	(segment
		(start 280.9748 -69.6722)
		(end 283.0068 -69.6722)
		(width 0.089408)
		(layer "In2.Cu")
		(net "PD_CPU0_EAR_N")
	)
	(segment
		(start 283.0068 -69.6722)
		(end 283.2608 -69.4182)
		(width 0.089408)
		(layer "In2.Cu")
		(net "PD_CPU0_EAR_N")
	)
	(segment
		(start 289.164014 -68.197222)
		(end 289.656266 -67.70497)
		(width 0.089408)
		(layer "In2.Cu")
		(net "PD_CPU0_EAR_N")
	)
	(segment
		(start 286.596328 -68.685918)
		(end 288.353754 -68.685918)
		(width 0.089408)
		(layer "In2.Cu")
		(net "PD_CPU0_EAR_N")
	)
	(segment
		(start 290.348924 -67.339464)
		(end 290.829746 -67.339464)
		(width 0.089408)
		(layer "In2.Cu")
		(net "PD_CPU0_EAR_N")
	)
	(segment
		(start 278.3078 -67.5386)
		(end 279.1968 -68.4276)
		(width 0.089408)
		(layer "In2.Cu")
		(net "PD_CPU0_EAR_N")
	)
	(segment
		(start 279.7302 -68.4276)
		(end 280.9748 -69.6722)
		(width 0.089408)
		(layer "In2.Cu")
		(net "PD_CPU0_EAR_N")
	)
	(segment
		(start 288.84245 -68.197222)
		(end 289.164014 -68.197222)
		(width 0.089408)
		(layer "In2.Cu")
		(net "PD_CPU0_EAR_N")
	)
	(segment
		(start 288.353754 -68.685918)
		(end 288.84245 -68.197222)
		(width 0.089408)
		(layer "In2.Cu")
		(net "PD_CPU0_EAR_N")
	)
	(segment
		(start 289.656266 -67.70497)
		(end 289.983418 -67.70497)
		(width 0.089408)
		(layer "In2.Cu")
		(net "PD_CPU0_EAR_N")
	)
	(segment
		(start 289.983418 -67.70497)
		(end 290.348924 -67.339464)
		(width 0.089408)
		(layer "In2.Cu")
		(net "PD_CPU0_EAR_N")
	)
	(segment
		(start 296.64406 -64.915288)
		(end 296.66184 -64.915288)
		(width 0.0889)
		(layer "In2.Cu")
		(net "PD_CPU0_EAR_N")
	)
	(segment
		(start 279.1968 -68.4276)
		(end 279.7302 -68.4276)
		(width 0.089408)
		(layer "In2.Cu")
		(net "PD_CPU0_EAR_N")
	)
	(segment
		(start 296.954702 -65.146428)
		(end 296.66184 -65.315338)
		(width 0.0889)
		(layer "In2.Cu")
		(net "PD_CPU0_EAR_N")
	)
	(segment
		(start 292.358064 -66.400934)
		(end 292.39083 -66.400934)
		(width 0.0889)
		(layer "In2.Cu")
		(net "PD_CPU0_EAR_N")
	)
	(segment
		(start 294.08882 -65.641474)
		(end 294.208962 -65.521332)
		(width 0.0889)
		(layer "In2.Cu")
		(net "PD_CPU0_EAR_N")
	)
	(segment
		(start 294.916352 -65.26022)
		(end 295.048178 -65.128394)
		(width 0.0889)
		(layer "In2.Cu")
		(net "PD_CPU0_EAR_N")
	)
	(segment
		(start 295.788842 -64.419734)
		(end 295.817798 -64.419734)
		(width 0.0889)
		(layer "In2.Cu")
		(net "PD_CPU0_EAR_N")
	)
	(segment
		(start 285.864046 -69.4182)
		(end 286.596328 -68.685918)
		(width 0.089408)
		(layer "In2.Cu")
		(net "PD_CPU0_EAR_N")
	)
	(segment
		(start 290.829746 -67.339464)
		(end 291.232082 -67.7418)
		(width 0.089408)
		(layer "In2.Cu")
		(net "PD_CPU0_EAR_N")
	)
	(segment
		(start 293.212774 -65.905888)
		(end 293.450518 -65.905888)
		(width 0.0889)
		(layer "In2.Cu")
		(net "PD_CPU0_EAR_N")
	)
	(segment
		(start 294.323008 -65.474088)
		(end 294.39997 -65.474088)
		(width 0.0889)
		(layer "In2.Cu")
		(net "PD_CPU0_EAR_N")
	)
	(segment
		(start 283.2608 -69.4182)
		(end 285.864046 -69.4182)
		(width 0.089408)
		(layer "In2.Cu")
		(net "PD_CPU0_EAR_N")
	)
	(segment
		(start 291.232082 -67.7418)
		(end 291.757608 -67.7418)
		(width 0.089408)
		(layer "In2.Cu")
		(net "PD_CPU0_EAR_N")
	)
	(arc
		(start 295.048178 -65.128394)
		(mid 295.248556 -64.902767)
		(end 295.430194 -64.661796)
		(width 0.0889)
		(layer "In2.Cu")
		(net "PD_CPU0_EAR_N")
	)
	(arc
		(start 295.817798 -64.419734)
		(mid 296.009815 -64.476842)
		(end 296.15003 -64.619886)
		(width 0.0889)
		(layer "In2.Cu")
		(net "PD_CPU0_EAR_N")
	)
	(arc
		(start 294.39997 -65.474088)
		(mid 294.679425 -65.418501)
		(end 294.916352 -65.26022)
		(width 0.0889)
		(layer "In2.Cu")
		(net "PD_CPU0_EAR_N")
	)
	(arc
		(start 296.15003 -64.619886)
		(mid 296.358638 -64.831818)
		(end 296.64406 -64.915288)
		(width 0.0889)
		(layer "In2.Cu")
		(net "PD_CPU0_EAR_N")
	)
	(arc
		(start 296.66184 -64.915288)
		(mid 296.836301 -64.955457)
		(end 296.975784 -65.067688)
		(width 0.0889)
		(layer "In2.Cu")
		(net "PD_CPU0_EAR_N")
	)
	(arc
		(start 295.456864 -64.619886)
		(mid 295.597023 -64.476996)
		(end 295.788842 -64.419734)
		(width 0.0889)
		(layer "In2.Cu")
		(net "PD_CPU0_EAR_N")
	)
	(arc
		(start 293.450518 -65.905888)
		(mid 293.795947 -65.83712)
		(end 294.08882 -65.641474)
		(width 0.0889)
		(layer "In2.Cu")
		(net "PD_CPU0_EAR_N")
	)
	(arc
		(start 291.972238 -67.226942)
		(mid 291.926971 -66.908362)
		(end 292.02253 -66.601086)
		(width 0.0889)
		(layer "In2.Cu")
		(net "PD_CPU0_EAR_N")
	)
	(arc
		(start 292.02253 -66.601086)
		(mid 292.164213 -66.457282)
		(end 292.358064 -66.400934)
		(width 0.0889)
		(layer "In2.Cu")
		(net "PD_CPU0_EAR_N")
	)
	(arc
		(start 294.208962 -65.521332)
		(mid 294.261287 -65.48637)
		(end 294.323008 -65.474088)
		(width 0.0889)
		(layer "In2.Cu")
		(net "PD_CPU0_EAR_N")
	)
	(arc
		(start 292.88105 -66.105786)
		(mid 293.021129 -65.96305)
		(end 293.212774 -65.905888)
		(width 0.0889)
		(layer "In2.Cu")
		(net "PD_CPU0_EAR_N")
	)
	(arc
		(start 292.39083 -66.400934)
		(mid 292.674047 -66.316653)
		(end 292.88105 -66.105786)
		(width 0.0889)
		(layer "In2.Cu")
		(net "PD_CPU0_EAR_N")
	)
	(arc
		(start 295.430194 -64.661796)
		(mid 295.443844 -64.641119)
		(end 295.45661 -64.619886)
		(width 0.0889)
		(layer "In2.Cu")
		(net "PD_CPU0_EAR_N")
	)
	(arc
		(start 291.757608 -67.7418)
		(mid 291.967357 -67.527085)
		(end 291.972238 -67.226942)
		(width 0.0889)
		(layer "In2.Cu")
		(net "PD_CPU0_EAR_N")
	)
	(segment
		(start 288.36366 -72.744584)
		(end 288.93516 -72.744584)
		(width 0.10795)
		(layer "F.Cu")
		(net "H_CPU0_BMCINIT")
	)
	(segment
		(start 282.735528 -74.261472)
		(end 282.735528 -74.092308)
		(width 0.10795)
		(layer "F.Cu")
		(net "H_CPU0_BMCINIT")
	)
	(segment
		(start 282.067 -74.93)
		(end 282.735528 -74.261472)
		(width 0.10795)
		(layer "F.Cu")
		(net "H_CPU0_BMCINIT")
	)
	(segment
		(start 281.89936 -81.96072)
		(end 282.6512 -81.9658)
		(width 0.10795)
		(layer "F.Cu")
		(net "H_CPU0_BMCINIT")
	)
	(segment
		(start 282.6512 -81.9658)
		(end 282.829 -82.1436)
		(width 0.10795)
		(layer "F.Cu")
		(net "H_CPU0_BMCINIT")
	)
	(via
		(at 282.829 -82.1436)
		(size 0.508)
		(drill 0.254)
		(layers "F.Cu" "B.Cu")
		(net "H_CPU0_BMCINIT")
	)
	(via
		(at 288.93516 -72.744584)
		(size 0.508)
		(drill 0.254)
		(layers "F.Cu" "B.Cu")
		(net "H_CPU0_BMCINIT")
	)
	(via
		(at 282.735528 -74.092308)
		(size 0.508)
		(drill 0.254)
		(layers "F.Cu" "B.Cu")
		(net "H_CPU0_BMCINIT")
	)
	(segment
		(start 283.946854 -74.201782)
		(end 285.023814 -74.201782)
		(width 0.089408)
		(layer "In11.Cu")
		(net "H_CPU0_BMCINIT")
	)
	(segment
		(start 288.552636 -72.599804)
		(end 288.642044 -72.575674)
		(width 0.0889)
		(layer "In11.Cu")
		(net "H_CPU0_BMCINIT")
	)
	(segment
		(start 285.394908 -73.830688)
		(end 286.37738 -73.830688)
		(width 0.089408)
		(layer "In11.Cu")
		(net "H_CPU0_BMCINIT")
	)
	(segment
		(start 283.83738 -74.092308)
		(end 283.946854 -74.201782)
		(width 0.089408)
		(layer "In11.Cu")
		(net "H_CPU0_BMCINIT")
	)
	(segment
		(start 282.0162 -81.3308)
		(end 282.0162 -74.811636)
		(width 0.089408)
		(layer "In11.Cu")
		(net "H_CPU0_BMCINIT")
	)
	(segment
		(start 285.023814 -74.201782)
		(end 285.394908 -73.830688)
		(width 0.089408)
		(layer "In11.Cu")
		(net "H_CPU0_BMCINIT")
	)
	(segment
		(start 288.061654 -72.840088)
		(end 288.09442 -72.840088)
		(width 0.0889)
		(layer "In11.Cu")
		(net "H_CPU0_BMCINIT")
	)
	(segment
		(start 286.606996 -73.77684)
		(end 287.048702 -73.335134)
		(width 0.089408)
		(layer "In11.Cu")
		(net "H_CPU0_BMCINIT")
	)
	(segment
		(start 282.735528 -74.092308)
		(end 283.83738 -74.092308)
		(width 0.089408)
		(layer "In11.Cu")
		(net "H_CPU0_BMCINIT")
	)
	(segment
		(start 287.048702 -73.335134)
		(end 287.23971 -73.335134)
		(width 0.089408)
		(layer "In11.Cu")
		(net "H_CPU0_BMCINIT")
	)
	(segment
		(start 288.642044 -72.575674)
		(end 288.93516 -72.744584)
		(width 0.0889)
		(layer "In11.Cu")
		(net "H_CPU0_BMCINIT")
	)
	(segment
		(start 282.829 -82.1436)
		(end 282.0162 -81.3308)
		(width 0.089408)
		(layer "In11.Cu")
		(net "H_CPU0_BMCINIT")
	)
	(segment
		(start 282.0162 -74.811636)
		(end 282.735528 -74.092308)
		(width 0.089408)
		(layer "In11.Cu")
		(net "H_CPU0_BMCINIT")
	)
	(arc
		(start 288.09442 -72.840088)
		(mid 288.351242 -72.772787)
		(end 288.552636 -72.599804)
		(width 0.0889)
		(layer "In11.Cu")
		(net "H_CPU0_BMCINIT")
	)
	(arc
		(start 287.72993 -73.039986)
		(mid 287.870009 -72.89725)
		(end 288.061654 -72.840088)
		(width 0.0889)
		(layer "In11.Cu")
		(net "H_CPU0_BMCINIT")
	)
	(arc
		(start 287.23971 -73.335134)
		(mid 287.522927 -73.250853)
		(end 287.72993 -73.039986)
		(width 0.0889)
		(layer "In11.Cu")
		(net "H_CPU0_BMCINIT")
	)
	(arc
		(start 286.37738 -73.830688)
		(mid 286.494909 -73.815357)
		(end 286.606996 -73.77684)
		(width 0.089408)
		(layer "In11.Cu")
		(net "H_CPU0_BMCINIT")
	)
	(segment
		(start 381.79375 -96.9772)
		(end 382.1684 -96.80321)
		(width 0.1016)
		(layer "F.Cu")
		(net "PECI_PCH")
	)
	(segment
		(start 382.1684 -96.80321)
		(end 382.28905 -96.747076)
		(width 0.1016)
		(layer "F.Cu")
		(net "PECI_PCH")
	)
	(via
		(at 382.28905 -96.747076)
		(size 0.508)
		(drill 0.254)
		(layers "F.Cu" "B.Cu")
		(net "PECI_PCH")
	)
	(via
		(at 380.8349 -94.1959)
		(size 0.6604)
		(drill 0.3302)
		(layers "F.Cu" "B.Cu")
		(net "PECI_PCH")
	)
	(segment
		(start 381.498094 -81.77276)
		(end 382.0668 -81.77276)
		(width 0.10795)
		(layer "B.Cu")
		(net "PECI_PCH")
	)
	(segment
		(start 377.49353 -86.639654)
		(end 377.49353 -86.289642)
		(width 0.10795)
		(layer "B.Cu")
		(net "PECI_PCH")
	)
	(segment
		(start 377.4821 -85.93582)
		(end 377.4821 -85.534246)
		(width 0.10795)
		(layer "B.Cu")
		(net "PECI_PCH")
	)
	(segment
		(start 378.966222 -84.775802)
		(end 380.252224 -83.4898)
		(width 0.10795)
		(layer "B.Cu")
		(net "PECI_PCH")
	)
	(segment
		(start 383.07518 -81.06918)
		(end 382.3716 -81.77276)
		(width 0.10795)
		(layer "B.Cu")
		(net "PECI_PCH")
	)
	(segment
		(start 378.886974 -90.673682)
		(end 377.904502 -89.69121)
		(width 0.10795)
		(layer "B.Cu")
		(net "PECI_PCH")
	)
	(segment
		(start 377.904502 -87.050626)
		(end 377.49353 -86.639654)
		(width 0.10795)
		(layer "B.Cu")
		(net "PECI_PCH")
	)
	(segment
		(start 381.381 -82.85734)
		(end 381.381 -81.889854)
		(width 0.10795)
		(layer "B.Cu")
		(net "PECI_PCH")
	)
	(segment
		(start 381.381 -81.889854)
		(end 381.498094 -81.77276)
		(width 0.10795)
		(layer "B.Cu")
		(net "PECI_PCH")
	)
	(segment
		(start 377.53036 -85.98408)
		(end 377.4821 -85.93582)
		(width 0.10795)
		(layer "B.Cu")
		(net "PECI_PCH")
	)
	(segment
		(start 377.49353 -86.289642)
		(end 377.53036 -86.252812)
		(width 0.10795)
		(layer "B.Cu")
		(net "PECI_PCH")
	)
	(segment
		(start 383.42824 -81.06918)
		(end 383.07518 -81.06918)
		(width 0.10795)
		(layer "B.Cu")
		(net "PECI_PCH")
	)
	(segment
		(start 380.252224 -83.4898)
		(end 380.74854 -83.4898)
		(width 0.10795)
		(layer "B.Cu")
		(net "PECI_PCH")
	)
	(segment
		(start 382.3716 -81.77276)
		(end 382.0668 -81.77276)
		(width 0.10795)
		(layer "B.Cu")
		(net "PECI_PCH")
	)
	(segment
		(start 377.53036 -86.252812)
		(end 377.53036 -85.98408)
		(width 0.10795)
		(layer "B.Cu")
		(net "PECI_PCH")
	)
	(segment
		(start 378.240544 -84.775802)
		(end 378.966222 -84.775802)
		(width 0.10795)
		(layer "B.Cu")
		(net "PECI_PCH")
	)
	(segment
		(start 382.28905 -96.747076)
		(end 382.28905 -95.65005)
		(width 0.10795)
		(layer "B.Cu")
		(net "PECI_PCH")
	)
	(segment
		(start 380.8349 -94.1959)
		(end 378.886974 -92.247974)
		(width 0.10795)
		(layer "B.Cu")
		(net "PECI_PCH")
	)
	(segment
		(start 382.28905 -95.65005)
		(end 380.8349 -94.1959)
		(width 0.10795)
		(layer "B.Cu")
		(net "PECI_PCH")
	)
	(segment
		(start 380.74854 -83.4898)
		(end 381.381 -82.85734)
		(width 0.10795)
		(layer "B.Cu")
		(net "PECI_PCH")
	)
	(segment
		(start 378.886974 -92.247974)
		(end 378.886974 -90.673682)
		(width 0.10795)
		(layer "B.Cu")
		(net "PECI_PCH")
	)
	(segment
		(start 377.904502 -89.69121)
		(end 377.904502 -87.050626)
		(width 0.10795)
		(layer "B.Cu")
		(net "PECI_PCH")
	)
	(segment
		(start 377.4821 -85.534246)
		(end 378.240544 -84.775802)
		(width 0.10795)
		(layer "B.Cu")
		(net "PECI_PCH")
	)
	(segment
		(start 132.806694 -69.277738)
		(end 133.378194 -69.277738)
		(width 0.1016)
		(layer "F.Cu")
		(net "PECI_CPU_G")
	)
	(segment
		(start 297.807126 -69.277738)
		(end 298.378626 -69.277738)
		(width 0.1016)
		(layer "F.Cu")
		(net "PECI_CPU_G")
	)
	(via
		(at 362.43387 -67.82943)
		(size 0.508)
		(drill 0.254)
		(layers "F.Cu" "B.Cu")
		(net "PECI_CPU_G")
	)
	(via
		(at 133.378194 -69.277738)
		(size 0.508)
		(drill 0.254)
		(layers "F.Cu" "B.Cu")
		(net "PECI_CPU_G")
	)
	(via
		(at 367.138458 -74.301604)
		(size 0.4572)
		(drill 0.2032)
		(layers "F.Cu" "B.Cu")
		(net "PECI_CPU_G")
	)
	(via
		(at 330.2762 -43.1546)
		(size 0.508)
		(drill 0.254)
		(layers "F.Cu" "B.Cu")
		(net "PECI_CPU_G")
	)
	(via
		(at 298.378626 -69.277738)
		(size 0.508)
		(drill 0.254)
		(layers "F.Cu" "B.Cu")
		(net "PECI_CPU_G")
	)
	(via
		(at 364.950248 -72.641206)
		(size 0.6604)
		(drill 0.3302)
		(layers "F.Cu" "B.Cu")
		(net "PECI_CPU_G")
	)
	(via
		(at 374.015 -85.0392)
		(size 0.508)
		(drill 0.254)
		(layers "F.Cu" "B.Cu")
		(net "PECI_CPU_G")
	)
	(segment
		(start 374.555004 -85.156802)
		(end 374.437402 -85.0392)
		(width 0.10795)
		(layer "B.Cu")
		(net "PECI_CPU_G")
	)
	(segment
		(start 378.450602 -81.3308)
		(end 377.42495 -81.3308)
		(width 0.10795)
		(layer "B.Cu")
		(net "PECI_CPU_G")
	)
	(segment
		(start 364.6932 -70.08876)
		(end 364.6932 -72.384158)
		(width 0.10795)
		(layer "B.Cu")
		(net "PECI_CPU_G")
	)
	(segment
		(start 379.211586 -81.77276)
		(end 379.094746 -81.8896)
		(width 0.10795)
		(layer "B.Cu")
		(net "PECI_CPU_G")
	)
	(segment
		(start 377.383802 -84.337398)
		(end 377.1138 -84.6074)
		(width 0.10795)
		(layer "B.Cu")
		(net "PECI_CPU_G")
	)
	(segment
		(start 377.275598 -81.480152)
		(end 377.275598 -83.566)
		(width 0.10795)
		(layer "B.Cu")
		(net "PECI_CPU_G")
	)
	(segment
		(start 376.767344 -85.156802)
		(end 374.555004 -85.156802)
		(width 0.10795)
		(layer "B.Cu")
		(net "PECI_CPU_G")
	)
	(segment
		(start 377.1138 -84.6074)
		(end 377.1138 -84.810346)
		(width 0.10795)
		(layer "B.Cu")
		(net "PECI_CPU_G")
	)
	(segment
		(start 377.1138 -84.810346)
		(end 376.767344 -85.156802)
		(width 0.10795)
		(layer "B.Cu")
		(net "PECI_CPU_G")
	)
	(segment
		(start 366.197642 -73.8886)
		(end 366.63122 -73.8886)
		(width 0.10795)
		(layer "B.Cu")
		(net "PECI_CPU_G")
	)
	(segment
		(start 364.950248 -72.641206)
		(end 366.197642 -73.8886)
		(width 0.10795)
		(layer "B.Cu")
		(net "PECI_CPU_G")
	)
	(segment
		(start 377.275598 -83.566)
		(end 377.383802 -83.674204)
		(width 0.10795)
		(layer "B.Cu")
		(net "PECI_CPU_G")
	)
	(segment
		(start 366.63122 -73.8886)
		(end 367.044224 -74.301604)
		(width 0.10795)
		(layer "B.Cu")
		(net "PECI_CPU_G")
	)
	(segment
		(start 378.587 -81.467198)
		(end 378.450602 -81.3308)
		(width 0.10795)
		(layer "B.Cu")
		(net "PECI_CPU_G")
	)
	(segment
		(start 362.43387 -67.82943)
		(end 364.6932 -70.08876)
		(width 0.10795)
		(layer "B.Cu")
		(net "PECI_CPU_G")
	)
	(segment
		(start 377.383802 -83.674204)
		(end 377.383802 -84.337398)
		(width 0.10795)
		(layer "B.Cu")
		(net "PECI_CPU_G")
	)
	(segment
		(start 379.094746 -81.8896)
		(end 378.587 -81.8896)
		(width 0.10795)
		(layer "B.Cu")
		(net "PECI_CPU_G")
	)
	(segment
		(start 377.42495 -81.3308)
		(end 377.275598 -81.480152)
		(width 0.10795)
		(layer "B.Cu")
		(net "PECI_CPU_G")
	)
	(segment
		(start 367.044224 -74.301604)
		(end 367.138458 -74.301604)
		(width 0.10795)
		(layer "B.Cu")
		(net "PECI_CPU_G")
	)
	(segment
		(start 380.1872 -81.77276)
		(end 379.211586 -81.77276)
		(width 0.10795)
		(layer "B.Cu")
		(net "PECI_CPU_G")
	)
	(segment
		(start 378.587 -81.8896)
		(end 378.587 -81.467198)
		(width 0.10795)
		(layer "B.Cu")
		(net "PECI_CPU_G")
	)
	(segment
		(start 374.437402 -85.0392)
		(end 374.015 -85.0392)
		(width 0.10795)
		(layer "B.Cu")
		(net "PECI_CPU_G")
	)
	(segment
		(start 364.6932 -72.384158)
		(end 364.950248 -72.641206)
		(width 0.10795)
		(layer "B.Cu")
		(net "PECI_CPU_G")
	)
	(segment
		(start 367.537492 -80.987392)
		(end 367.875566 -81.325466)
		(width 0.089408)
		(layer "In2.Cu")
		(net "PECI_CPU_G")
	)
	(segment
		(start 311.070752 -45.303948)
		(end 311.070752 -56.258206)
		(width 0.089408)
		(layer "In2.Cu")
		(net "PECI_CPU_G")
	)
	(segment
		(start 311.749948 -56.937402)
		(end 311.749948 -63.179452)
		(width 0.089408)
		(layer "In2.Cu")
		(net "PECI_CPU_G")
	)
	(segment
		(start 318.233552 -43.278552)
		(end 314.814966 -43.278552)
		(width 0.089408)
		(layer "In2.Cu")
		(net "PECI_CPU_G")
	)
	(segment
		(start 314.814966 -43.278552)
		(end 313.173618 -44.9199)
		(width 0.089408)
		(layer "In2.Cu")
		(net "PECI_CPU_G")
	)
	(segment
		(start 319.74282 -44.78782)
		(end 318.233552 -43.278552)
		(width 0.089408)
		(layer "In2.Cu")
		(net "PECI_CPU_G")
	)
	(segment
		(start 367.219484 -80.208628)
		(end 367.537492 -80.526636)
		(width 0.089408)
		(layer "In2.Cu")
		(net "PECI_CPU_G")
	)
	(segment
		(start 330.2762 -43.1546)
		(end 328.64298 -44.78782)
		(width 0.089408)
		(layer "In2.Cu")
		(net "PECI_CPU_G")
	)
	(segment
		(start 367.537492 -80.526636)
		(end 367.537492 -80.987392)
		(width 0.089408)
		(layer "In2.Cu")
		(net "PECI_CPU_G")
	)
	(segment
		(start 301.147226 -69.2912)
		(end 300.82871 -69.2912)
		(width 0.0889)
		(layer "In2.Cu")
		(net "PECI_CPU_G")
	)
	(segment
		(start 302.008286 -69.698362)
		(end 301.554388 -69.698362)
		(width 0.0889)
		(layer "In2.Cu")
		(net "PECI_CPU_G")
	)
	(segment
		(start 303.532794 -68.879212)
		(end 303.205388 -68.879212)
		(width 0.0889)
		(layer "In2.Cu")
		(net "PECI_CPU_G")
	)
	(segment
		(start 299.86986 -69.693536)
		(end 299.454062 -69.277738)
		(width 0.0889)
		(layer "In2.Cu")
		(net "PECI_CPU_G")
	)
	(segment
		(start 300.426374 -69.693536)
		(end 299.86986 -69.693536)
		(width 0.0889)
		(layer "In2.Cu")
		(net "PECI_CPU_G")
	)
	(segment
		(start 303.205388 -68.879212)
		(end 302.815752 -69.268848)
		(width 0.0889)
		(layer "In2.Cu")
		(net "PECI_CPU_G")
	)
	(segment
		(start 299.454062 -69.277738)
		(end 298.378626 -69.277738)
		(width 0.0889)
		(layer "In2.Cu")
		(net "PECI_CPU_G")
	)
	(segment
		(start 304.409856 -69.372734)
		(end 304.366676 -69.372734)
		(width 0.0889)
		(layer "In2.Cu")
		(net "PECI_CPU_G")
	)
	(segment
		(start 328.64298 -44.78782)
		(end 319.74282 -44.78782)
		(width 0.089408)
		(layer "In2.Cu")
		(net "PECI_CPU_G")
	)
	(segment
		(start 306.126896 -68.382134)
		(end 306.09413 -68.382134)
		(width 0.0889)
		(layer "In2.Cu")
		(net "PECI_CPU_G")
	)
	(segment
		(start 302.815752 -69.268848)
		(end 302.4378 -69.268848)
		(width 0.0889)
		(layer "In2.Cu")
		(net "PECI_CPU_G")
	)
	(segment
		(start 367.875566 -81.325466)
		(end 369.577112 -81.325466)
		(width 0.089408)
		(layer "In2.Cu")
		(net "PECI_CPU_G")
	)
	(segment
		(start 366.7506 -74.689462)
		(end 366.7506 -79.412338)
		(width 0.089408)
		(layer "In2.Cu")
		(net "PECI_CPU_G")
	)
	(segment
		(start 311.070752 -56.258206)
		(end 311.749948 -56.937402)
		(width 0.089408)
		(layer "In2.Cu")
		(net "PECI_CPU_G")
	)
	(segment
		(start 307.862986 -67.066414)
		(end 307.862986 -67.362324)
		(width 0.089408)
		(layer "In2.Cu")
		(net "PECI_CPU_G")
	)
	(segment
		(start 369.577112 -81.325466)
		(end 373.290846 -85.0392)
		(width 0.089408)
		(layer "In2.Cu")
		(net "PECI_CPU_G")
	)
	(segment
		(start 300.82871 -69.2912)
		(end 300.426374 -69.693536)
		(width 0.0889)
		(layer "In2.Cu")
		(net "PECI_CPU_G")
	)
	(segment
		(start 311.4548 -44.9199)
		(end 311.070752 -45.303948)
		(width 0.089408)
		(layer "In2.Cu")
		(net "PECI_CPU_G")
	)
	(segment
		(start 301.554388 -69.698362)
		(end 301.147226 -69.2912)
		(width 0.0889)
		(layer "In2.Cu")
		(net "PECI_CPU_G")
	)
	(segment
		(start 302.4378 -69.268848)
		(end 302.008286 -69.698362)
		(width 0.0889)
		(layer "In2.Cu")
		(net "PECI_CPU_G")
	)
	(segment
		(start 313.173618 -44.9199)
		(end 311.4548 -44.9199)
		(width 0.089408)
		(layer "In2.Cu")
		(net "PECI_CPU_G")
	)
	(segment
		(start 307.338222 -67.887088)
		(end 306.94884 -67.887088)
		(width 0.0889)
		(layer "In2.Cu")
		(net "PECI_CPU_G")
	)
	(segment
		(start 305.264566 -68.877688)
		(end 305.2318 -68.877688)
		(width 0.0889)
		(layer "In2.Cu")
		(net "PECI_CPU_G")
	)
	(segment
		(start 367.219484 -79.881222)
		(end 367.219484 -80.208628)
		(width 0.089408)
		(layer "In2.Cu")
		(net "PECI_CPU_G")
	)
	(segment
		(start 366.7506 -79.412338)
		(end 367.219484 -79.881222)
		(width 0.089408)
		(layer "In2.Cu")
		(net "PECI_CPU_G")
	)
	(segment
		(start 367.138458 -74.301604)
		(end 366.7506 -74.689462)
		(width 0.089408)
		(layer "In2.Cu")
		(net "PECI_CPU_G")
	)
	(segment
		(start 307.862986 -67.362324)
		(end 307.338222 -67.887088)
		(width 0.089408)
		(layer "In2.Cu")
		(net "PECI_CPU_G")
	)
	(segment
		(start 373.290846 -85.0392)
		(end 374.015 -85.0392)
		(width 0.089408)
		(layer "In2.Cu")
		(net "PECI_CPU_G")
	)
	(segment
		(start 311.749948 -63.179452)
		(end 307.862986 -67.066414)
		(width 0.089408)
		(layer "In2.Cu")
		(net "PECI_CPU_G")
	)
	(arc
		(start 304.900076 -69.077586)
		(mid 304.693072 -69.28845)
		(end 304.409856 -69.372734)
		(width 0.0889)
		(layer "In2.Cu")
		(net "PECI_CPU_G")
	)
	(arc
		(start 306.94884 -67.887088)
		(mid 306.757198 -67.944254)
		(end 306.617116 -68.086986)
		(width 0.0889)
		(layer "In2.Cu")
		(net "PECI_CPU_G")
	)
	(arc
		(start 305.2318 -68.877688)
		(mid 305.040158 -68.934854)
		(end 304.900076 -69.077586)
		(width 0.0889)
		(layer "In2.Cu")
		(net "PECI_CPU_G")
	)
	(arc
		(start 305.758596 -68.582286)
		(mid 305.549988 -68.794218)
		(end 305.264566 -68.877688)
		(width 0.0889)
		(layer "In2.Cu")
		(net "PECI_CPU_G")
	)
	(arc
		(start 306.09413 -68.382134)
		(mid 305.90028 -68.438484)
		(end 305.758596 -68.582286)
		(width 0.0889)
		(layer "In2.Cu")
		(net "PECI_CPU_G")
	)
	(arc
		(start 304.366676 -69.372734)
		(mid 304.083459 -69.288453)
		(end 303.876456 -69.077586)
		(width 0.0889)
		(layer "In2.Cu")
		(net "PECI_CPU_G")
	)
	(arc
		(start 303.876456 -69.077586)
		(mid 303.731181 -68.932413)
		(end 303.532794 -68.879212)
		(width 0.0889)
		(layer "In2.Cu")
		(net "PECI_CPU_G")
	)
	(arc
		(start 306.617116 -68.086986)
		(mid 306.410112 -68.29785)
		(end 306.126896 -68.382134)
		(width 0.0889)
		(layer "In2.Cu")
		(net "PECI_CPU_G")
	)
	(segment
		(start 328.0918 -26.621994)
		(end 324.620382 -23.150576)
		(width 0.089408)
		(layer "In9.Cu")
		(net "PECI_CPU_G")
	)
	(segment
		(start 323.972682 -12.635738)
		(end 323.972682 -11.825986)
		(width 0.089408)
		(layer "In9.Cu")
		(net "PECI_CPU_G")
	)
	(segment
		(start 173.35246 -22.325584)
		(end 170.619674 -22.325584)
		(width 0.089408)
		(layer "In9.Cu")
		(net "PECI_CPU_G")
	)
	(segment
		(start 125.54077 -60.37199)
		(end 125.80747 -60.37199)
		(width 0.089408)
		(layer "In9.Cu")
		(net "PECI_CPU_G")
	)
	(segment
		(start 323.972428 -12.635992)
		(end 323.972682 -12.635738)
		(width 0.089408)
		(layer "In9.Cu")
		(net "PECI_CPU_G")
	)
	(segment
		(start 155.411424 -28.966922)
		(end 154.558746 -29.8196)
		(width 0.089408)
		(layer "In9.Cu")
		(net "PECI_CPU_G")
	)
	(segment
		(start 328.4474 -32.4866)
		(end 328.0918 -32.131)
		(width 0.089408)
		(layer "In9.Cu")
		(net "PECI_CPU_G")
	)
	(segment
		(start 124.049028 -58.880248)
		(end 125.54077 -60.37199)
		(width 0.089408)
		(layer "In9.Cu")
		(net "PECI_CPU_G")
	)
	(segment
		(start 328.0918 -32.131)
		(end 328.0918 -26.621994)
		(width 0.089408)
		(layer "In9.Cu")
		(net "PECI_CPU_G")
	)
	(segment
		(start 125.80747 -60.37199)
		(end 126.196598 -60.761118)
		(width 0.089408)
		(layer "In9.Cu")
		(net "PECI_CPU_G")
	)
	(segment
		(start 156.713174 -28.966922)
		(end 155.411424 -28.966922)
		(width 0.089408)
		(layer "In9.Cu")
		(net "PECI_CPU_G")
	)
	(segment
		(start 170.547792 -22.253702)
		(end 170.348656 -22.253702)
		(width 0.089408)
		(layer "In9.Cu")
		(net "PECI_CPU_G")
	)
	(segment
		(start 170.348656 -22.253702)
		(end 168.738804 -20.64385)
		(width 0.089408)
		(layer "In9.Cu")
		(net "PECI_CPU_G")
	)
	(segment
		(start 186.63666 -13.411454)
		(end 184.861454 -15.18666)
		(width 0.089408)
		(layer "In9.Cu")
		(net "PECI_CPU_G")
	)
	(segment
		(start 160.856676 -20.64385)
		(end 160.292542 -21.207984)
		(width 0.089408)
		(layer "In9.Cu")
		(net "PECI_CPU_G")
	)
	(segment
		(start 186.63666 -12.420092)
		(end 186.63666 -13.411454)
		(width 0.089408)
		(layer "In9.Cu")
		(net "PECI_CPU_G")
	)
	(segment
		(start 184.257696 -15.18666)
		(end 182.95366 -16.490696)
		(width 0.089408)
		(layer "In9.Cu")
		(net "PECI_CPU_G")
	)
	(segment
		(start 192.702688 -10.878312)
		(end 188.17844 -10.878312)
		(width 0.089408)
		(layer "In9.Cu")
		(net "PECI_CPU_G")
	)
	(segment
		(start 132.963158 -65.602358)
		(end 132.963158 -68.611242)
		(width 0.089408)
		(layer "In9.Cu")
		(net "PECI_CPU_G")
	)
	(segment
		(start 133.13664 -68.784724)
		(end 133.13664 -69.036184)
		(width 0.089408)
		(layer "In9.Cu")
		(net "PECI_CPU_G")
	)
	(segment
		(start 123.990354 -53.203856)
		(end 124.049028 -53.26253)
		(width 0.089408)
		(layer "In9.Cu")
		(net "PECI_CPU_G")
	)
	(segment
		(start 160.292542 -25.387554)
		(end 156.713174 -28.966922)
		(width 0.089408)
		(layer "In9.Cu")
		(net "PECI_CPU_G")
	)
	(segment
		(start 148.319744 -34.86531)
		(end 129.32537 -34.86531)
		(width 0.089408)
		(layer "In9.Cu")
		(net "PECI_CPU_G")
	)
	(segment
		(start 128.423924 -60.83554)
		(end 128.95453 -61.366146)
		(width 0.089408)
		(layer "In9.Cu")
		(net "PECI_CPU_G")
	)
	(segment
		(start 130.837178 -62.30874)
		(end 131.236212 -62.707774)
		(width 0.089408)
		(layer "In9.Cu")
		(net "PECI_CPU_G")
	)
	(segment
		(start 130.659378 -62.30874)
		(end 130.837178 -62.30874)
		(width 0.089408)
		(layer "In9.Cu")
		(net "PECI_CPU_G")
	)
	(segment
		(start 264.67181 -10.679684)
		(end 262.650732 -10.679684)
		(width 0.089408)
		(layer "In9.Cu")
		(net "PECI_CPU_G")
	)
	(segment
		(start 154.558746 -29.8196)
		(end 153.365454 -29.8196)
		(width 0.089408)
		(layer "In9.Cu")
		(net "PECI_CPU_G")
	)
	(segment
		(start 132.188204 -65.278)
		(end 132.6388 -65.278)
		(width 0.089408)
		(layer "In9.Cu")
		(net "PECI_CPU_G")
	)
	(segment
		(start 329.609704 -42.488104)
		(end 329.609704 -38.017704)
		(width 0.089408)
		(layer "In9.Cu")
		(net "PECI_CPU_G")
	)
	(segment
		(start 133.13664 -69.036184)
		(end 133.378194 -69.277738)
		(width 0.089408)
		(layer "In9.Cu")
		(net "PECI_CPU_G")
	)
	(segment
		(start 153.365454 -29.8196)
		(end 148.319744 -34.86531)
		(width 0.089408)
		(layer "In9.Cu")
		(net "PECI_CPU_G")
	)
	(segment
		(start 128.95453 -61.366146)
		(end 129.253234 -61.366146)
		(width 0.089408)
		(layer "In9.Cu")
		(net "PECI_CPU_G")
	)
	(segment
		(start 178.347116 -20.638008)
		(end 175.040036 -20.638008)
		(width 0.089408)
		(layer "In9.Cu")
		(net "PECI_CPU_G")
	)
	(segment
		(start 324.620382 -15.21714)
		(end 323.972428 -14.569186)
		(width 0.089408)
		(layer "In9.Cu")
		(net "PECI_CPU_G")
	)
	(segment
		(start 182.95366 -17.007078)
		(end 181.698138 -18.2626)
		(width 0.089408)
		(layer "In9.Cu")
		(net "PECI_CPU_G")
	)
	(segment
		(start 130.25755 -61.906912)
		(end 130.659378 -62.30874)
		(width 0.089408)
		(layer "In9.Cu")
		(net "PECI_CPU_G")
	)
	(segment
		(start 126.808738 -60.761118)
		(end 127.111252 -60.458604)
		(width 0.089408)
		(layer "In9.Cu")
		(net "PECI_CPU_G")
	)
	(segment
		(start 261.567422 -9.596374)
		(end 193.984626 -9.596374)
		(width 0.089408)
		(layer "In9.Cu")
		(net "PECI_CPU_G")
	)
	(segment
		(start 131.236212 -62.707774)
		(end 131.236212 -64.463676)
		(width 0.089408)
		(layer "In9.Cu")
		(net "PECI_CPU_G")
	)
	(segment
		(start 129.794 -61.906912)
		(end 130.25755 -61.906912)
		(width 0.089408)
		(layer "In9.Cu")
		(net "PECI_CPU_G")
	)
	(segment
		(start 322.646294 -10.499598)
		(end 264.851896 -10.499598)
		(width 0.089408)
		(layer "In9.Cu")
		(net "PECI_CPU_G")
	)
	(segment
		(start 264.851896 -10.499598)
		(end 264.67181 -10.679684)
		(width 0.089408)
		(layer "In9.Cu")
		(net "PECI_CPU_G")
	)
	(segment
		(start 132.963158 -68.611242)
		(end 133.13664 -68.784724)
		(width 0.089408)
		(layer "In9.Cu")
		(net "PECI_CPU_G")
	)
	(segment
		(start 175.040036 -20.638008)
		(end 173.35246 -22.325584)
		(width 0.089408)
		(layer "In9.Cu")
		(net "PECI_CPU_G")
	)
	(segment
		(start 182.95366 -16.490696)
		(end 182.95366 -17.007078)
		(width 0.089408)
		(layer "In9.Cu")
		(net "PECI_CPU_G")
	)
	(segment
		(start 132.6388 -65.278)
		(end 132.963158 -65.602358)
		(width 0.089408)
		(layer "In9.Cu")
		(net "PECI_CPU_G")
	)
	(segment
		(start 128.048004 -60.83554)
		(end 128.423924 -60.83554)
		(width 0.089408)
		(layer "In9.Cu")
		(net "PECI_CPU_G")
	)
	(segment
		(start 127.111252 -60.458604)
		(end 127.671068 -60.458604)
		(width 0.089408)
		(layer "In9.Cu")
		(net "PECI_CPU_G")
	)
	(segment
		(start 160.292542 -21.207984)
		(end 160.292542 -25.387554)
		(width 0.089408)
		(layer "In9.Cu")
		(net "PECI_CPU_G")
	)
	(segment
		(start 262.650732 -10.679684)
		(end 261.567422 -9.596374)
		(width 0.089408)
		(layer "In9.Cu")
		(net "PECI_CPU_G")
	)
	(segment
		(start 324.620382 -23.150576)
		(end 324.620382 -15.21714)
		(width 0.089408)
		(layer "In9.Cu")
		(net "PECI_CPU_G")
	)
	(segment
		(start 123.990354 -40.200326)
		(end 123.990354 -53.203856)
		(width 0.089408)
		(layer "In9.Cu")
		(net "PECI_CPU_G")
	)
	(segment
		(start 193.984626 -9.596374)
		(end 192.702688 -10.878312)
		(width 0.089408)
		(layer "In9.Cu")
		(net "PECI_CPU_G")
	)
	(segment
		(start 323.972428 -14.569186)
		(end 323.972428 -12.635992)
		(width 0.089408)
		(layer "In9.Cu")
		(net "PECI_CPU_G")
	)
	(segment
		(start 131.732274 -64.82207)
		(end 132.188204 -65.278)
		(width 0.089408)
		(layer "In9.Cu")
		(net "PECI_CPU_G")
	)
	(segment
		(start 323.972682 -11.825986)
		(end 322.646294 -10.499598)
		(width 0.089408)
		(layer "In9.Cu")
		(net "PECI_CPU_G")
	)
	(segment
		(start 184.861454 -15.18666)
		(end 184.257696 -15.18666)
		(width 0.089408)
		(layer "In9.Cu")
		(net "PECI_CPU_G")
	)
	(segment
		(start 129.32537 -34.86531)
		(end 123.990354 -40.200326)
		(width 0.089408)
		(layer "In9.Cu")
		(net "PECI_CPU_G")
	)
	(segment
		(start 329.609704 -38.017704)
		(end 328.4474 -36.8554)
		(width 0.089408)
		(layer "In9.Cu")
		(net "PECI_CPU_G")
	)
	(segment
		(start 188.17844 -10.878312)
		(end 186.63666 -12.420092)
		(width 0.089408)
		(layer "In9.Cu")
		(net "PECI_CPU_G")
	)
	(segment
		(start 131.594606 -64.82207)
		(end 131.732274 -64.82207)
		(width 0.089408)
		(layer "In9.Cu")
		(net "PECI_CPU_G")
	)
	(segment
		(start 127.671068 -60.458604)
		(end 128.048004 -60.83554)
		(width 0.089408)
		(layer "In9.Cu")
		(net "PECI_CPU_G")
	)
	(segment
		(start 129.253234 -61.366146)
		(end 129.794 -61.906912)
		(width 0.089408)
		(layer "In9.Cu")
		(net "PECI_CPU_G")
	)
	(segment
		(start 328.4474 -36.8554)
		(end 328.4474 -32.4866)
		(width 0.089408)
		(layer "In9.Cu")
		(net "PECI_CPU_G")
	)
	(segment
		(start 170.619674 -22.325584)
		(end 170.547792 -22.253702)
		(width 0.089408)
		(layer "In9.Cu")
		(net "PECI_CPU_G")
	)
	(segment
		(start 131.236212 -64.463676)
		(end 131.594606 -64.82207)
		(width 0.089408)
		(layer "In9.Cu")
		(net "PECI_CPU_G")
	)
	(segment
		(start 124.049028 -53.26253)
		(end 124.049028 -58.880248)
		(width 0.089408)
		(layer "In9.Cu")
		(net "PECI_CPU_G")
	)
	(segment
		(start 181.698138 -18.2626)
		(end 180.722524 -18.2626)
		(width 0.089408)
		(layer "In9.Cu")
		(net "PECI_CPU_G")
	)
	(segment
		(start 126.196598 -60.761118)
		(end 126.808738 -60.761118)
		(width 0.089408)
		(layer "In9.Cu")
		(net "PECI_CPU_G")
	)
	(segment
		(start 180.722524 -18.2626)
		(end 178.347116 -20.638008)
		(width 0.089408)
		(layer "In9.Cu")
		(net "PECI_CPU_G")
	)
	(segment
		(start 168.738804 -20.64385)
		(end 160.856676 -20.64385)
		(width 0.089408)
		(layer "In9.Cu")
		(net "PECI_CPU_G")
	)
	(segment
		(start 330.2762 -43.1546)
		(end 329.609704 -42.488104)
		(width 0.089408)
		(layer "In9.Cu")
		(net "PECI_CPU_G")
	)
	(segment
		(start 302.664114 -68.382388)
		(end 302.695356 -68.382388)
		(width 0.089408)
		(layer "In11.Cu")
		(net "PECI_CPU_G")
	)
	(segment
		(start 353.290378 -65.062354)
		(end 355.558344 -67.33032)
		(width 0.089408)
		(layer "In11.Cu")
		(net "PECI_CPU_G")
	)
	(segment
		(start 306.098194 -67.391788)
		(end 306.112418 -67.391788)
		(width 0.089408)
		(layer "In11.Cu")
		(net "PECI_CPU_G")
	)
	(segment
		(start 355.558344 -67.33032)
		(end 358.832404 -67.33032)
		(width 0.089408)
		(layer "In11.Cu")
		(net "PECI_CPU_G")
	)
	(segment
		(start 308.379876 -68.910962)
		(end 308.955948 -69.487034)
		(width 0.0889)
		(layer "In11.Cu")
		(net "PECI_CPU_G")
	)
	(segment
		(start 331.767688 -69.487034)
		(end 336.192368 -65.062354)
		(width 0.089408)
		(layer "In11.Cu")
		(net "PECI_CPU_G")
	)
	(segment
		(start 358.832404 -67.33032)
		(end 359.331514 -67.82943)
		(width 0.089408)
		(layer "In11.Cu")
		(net "PECI_CPU_G")
	)
	(segment
		(start 359.331514 -67.82943)
		(end 362.43387 -67.82943)
		(width 0.089408)
		(layer "In11.Cu")
		(net "PECI_CPU_G")
	)
	(segment
		(start 298.378626 -68.939918)
		(end 298.44365 -68.874894)
		(width 0.089408)
		(layer "In11.Cu")
		(net "PECI_CPU_G")
	)
	(segment
		(start 298.378626 -69.277738)
		(end 298.378626 -68.939918)
		(width 0.089408)
		(layer "In11.Cu")
		(net "PECI_CPU_G")
	)
	(segment
		(start 307.356256 -67.887342)
		(end 308.379876 -68.910962)
		(width 0.089408)
		(layer "In11.Cu")
		(net "PECI_CPU_G")
	)
	(segment
		(start 308.955948 -69.487034)
		(end 331.767688 -69.487034)
		(width 0.089408)
		(layer "In11.Cu")
		(net "PECI_CPU_G")
	)
	(segment
		(start 300.938438 -68.382642)
		(end 300.969934 -68.382642)
		(width 0.089408)
		(layer "In11.Cu")
		(net "PECI_CPU_G")
	)
	(segment
		(start 306.943252 -67.887342)
		(end 307.356256 -67.887342)
		(width 0.089408)
		(layer "In11.Cu")
		(net "PECI_CPU_G")
	)
	(segment
		(start 336.192368 -65.062354)
		(end 353.290378 -65.062354)
		(width 0.089408)
		(layer "In11.Cu")
		(net "PECI_CPU_G")
	)
	(segment
		(start 303.517554 -67.887342)
		(end 305.481482 -67.887342)
		(width 0.089408)
		(layer "In11.Cu")
		(net "PECI_CPU_G")
	)
	(arc
		(start 302.32477 -68.58254)
		(mid 302.468081 -68.437769)
		(end 302.664114 -68.382388)
		(width 0.089408)
		(layer "In11.Cu")
		(net "PECI_CPU_G")
	)
	(arc
		(start 299.583602 -68.58254)
		(mid 300.095666 -68.878299)
		(end 300.60773 -68.58254)
		(width 0.089408)
		(layer "In11.Cu")
		(net "PECI_CPU_G")
	)
	(arc
		(start 298.44365 -68.874894)
		(mid 298.702099 -68.782116)
		(end 298.89069 -68.58254)
		(width 0.089408)
		(layer "In11.Cu")
		(net "PECI_CPU_G")
	)
	(arc
		(start 303.18329 -68.08724)
		(mid 303.324447 -67.943855)
		(end 303.517554 -67.887342)
		(width 0.089408)
		(layer "In11.Cu")
		(net "PECI_CPU_G")
	)
	(arc
		(start 305.75885 -67.59194)
		(mid 305.902161 -67.447169)
		(end 306.098194 -67.391788)
		(width 0.089408)
		(layer "In11.Cu")
		(net "PECI_CPU_G")
	)
	(arc
		(start 300.60773 -68.58254)
		(mid 300.747332 -68.439984)
		(end 300.938438 -68.382642)
		(width 0.089408)
		(layer "In11.Cu")
		(net "PECI_CPU_G")
	)
	(arc
		(start 302.695356 -68.382388)
		(mid 302.977258 -68.297525)
		(end 303.18329 -68.08724)
		(width 0.089408)
		(layer "In11.Cu")
		(net "PECI_CPU_G")
	)
	(arc
		(start 305.481482 -67.887342)
		(mid 305.637291 -67.755725)
		(end 305.75885 -67.59194)
		(width 0.089408)
		(layer "In11.Cu")
		(net "PECI_CPU_G")
	)
	(arc
		(start 298.89069 -68.58254)
		(mid 299.237146 -68.382322)
		(end 299.583602 -68.58254)
		(width 0.089408)
		(layer "In11.Cu")
		(net "PECI_CPU_G")
	)
	(arc
		(start 300.969934 -68.382642)
		(mid 301.161035 -68.439992)
		(end 301.300642 -68.58254)
		(width 0.089408)
		(layer "In11.Cu")
		(net "PECI_CPU_G")
	)
	(arc
		(start 306.112418 -67.391788)
		(mid 306.30845 -67.447172)
		(end 306.451762 -67.59194)
		(width 0.089408)
		(layer "In11.Cu")
		(net "PECI_CPU_G")
	)
	(arc
		(start 306.451762 -67.59194)
		(mid 306.659291 -67.803224)
		(end 306.943252 -67.887342)
		(width 0.089408)
		(layer "In11.Cu")
		(net "PECI_CPU_G")
	)
	(arc
		(start 301.300642 -68.58254)
		(mid 301.812706 -68.878299)
		(end 302.32477 -68.58254)
		(width 0.089408)
		(layer "In11.Cu")
		(net "PECI_CPU_G")
	)
	(segment
		(start 434.37048 -43.844464)
		(end 434.37048 -44.01312)
		(width 0.10795)
		(layer "F.Cu")
		(net "PECI_BMC")
	)
	(segment
		(start 434.5051 -43.1038)
		(end 434.5051 -43.3959)
		(width 0.10795)
		(layer "F.Cu")
		(net "PECI_BMC")
	)
	(segment
		(start 434.37048 -43.53052)
		(end 434.37048 -43.844464)
		(width 0.10795)
		(layer "F.Cu")
		(net "PECI_BMC")
	)
	(segment
		(start 434.37048 -44.01312)
		(end 433.9209 -44.4627)
		(width 0.10795)
		(layer "F.Cu")
		(net "PECI_BMC")
	)
	(segment
		(start 434.5051 -43.3959)
		(end 434.37048 -43.53052)
		(width 0.10795)
		(layer "F.Cu")
		(net "PECI_BMC")
	)
	(via
		(at 433.9209 -44.4627)
		(size 0.508)
		(drill 0.254)
		(layers "F.Cu" "B.Cu")
		(net "PECI_BMC")
	)
	(via
		(at 386.4229 -81.893918)
		(size 0.6604)
		(drill 0.3302)
		(layers "F.Cu" "B.Cu")
		(net "PECI_BMC")
	)
	(via
		(at 387.07949 -81.000854)
		(size 0.508)
		(drill 0.254)
		(layers "F.Cu" "B.Cu")
		(net "PECI_BMC")
	)
	(segment
		(start 378.755656 -85.344)
		(end 380.374652 -83.725004)
		(width 0.10795)
		(layer "B.Cu")
		(net "PECI_BMC")
	)
	(segment
		(start 386.19303 -82.15757)
		(end 386.4229 -81.9277)
		(width 0.10795)
		(layer "B.Cu")
		(net "PECI_BMC")
	)
	(segment
		(start 378.587 -85.344)
		(end 378.755656 -85.344)
		(width 0.10795)
		(layer "B.Cu")
		(net "PECI_BMC")
	)
	(segment
		(start 383.34569 -82.15757)
		(end 386.19303 -82.15757)
		(width 0.10795)
		(layer "B.Cu")
		(net "PECI_BMC")
	)
	(segment
		(start 381.50292 -83.07324)
		(end 382.0668 -83.07324)
		(width 0.10795)
		(layer "B.Cu")
		(net "PECI_BMC")
	)
	(segment
		(start 387.07949 -81.237328)
		(end 386.4229 -81.893918)
		(width 0.10795)
		(layer "B.Cu")
		(net "PECI_BMC")
	)
	(segment
		(start 386.4229 -81.9277)
		(end 386.4229 -81.893918)
		(width 0.10795)
		(layer "B.Cu")
		(net "PECI_BMC")
	)
	(segment
		(start 380.851156 -83.725004)
		(end 381.50292 -83.07324)
		(width 0.10795)
		(layer "B.Cu")
		(net "PECI_BMC")
	)
	(segment
		(start 382.43002 -83.07324)
		(end 383.34569 -82.15757)
		(width 0.10795)
		(layer "B.Cu")
		(net "PECI_BMC")
	)
	(segment
		(start 380.374652 -83.725004)
		(end 380.851156 -83.725004)
		(width 0.10795)
		(layer "B.Cu")
		(net "PECI_BMC")
	)
	(segment
		(start 382.0668 -83.07324)
		(end 382.43002 -83.07324)
		(width 0.10795)
		(layer "B.Cu")
		(net "PECI_BMC")
	)
	(segment
		(start 387.07949 -81.000854)
		(end 387.07949 -81.237328)
		(width 0.10795)
		(layer "B.Cu")
		(net "PECI_BMC")
	)
	(segment
		(start 391.67562 -44.010326)
		(end 389.5598 -46.126146)
		(width 0.089408)
		(layer "In2.Cu")
		(net "PECI_BMC")
	)
	(segment
		(start 421.378888 -40.147748)
		(end 420.17315 -40.147748)
		(width 0.089408)
		(layer "In2.Cu")
		(net "PECI_BMC")
	)
	(segment
		(start 410.53639 -38.538912)
		(end 409.764484 -38.538912)
		(width 0.089408)
		(layer "In2.Cu")
		(net "PECI_BMC")
	)
	(segment
		(start 418.240972 -38.53434)
		(end 416.687 -40.088312)
		(width 0.089408)
		(layer "In2.Cu")
		(net "PECI_BMC")
	)
	(segment
		(start 400.79803 -40.0685)
		(end 396.511018 -40.0685)
		(width 0.089408)
		(layer "In2.Cu")
		(net "PECI_BMC")
	)
	(segment
		(start 388.425182 -70.395592)
		(end 388.425182 -71.543926)
		(width 0.089408)
		(layer "In2.Cu")
		(net "PECI_BMC")
	)
	(segment
		(start 409.764484 -38.538912)
		(end 409.487878 -38.262306)
		(width 0.089408)
		(layer "In2.Cu")
		(net "PECI_BMC")
	)
	(segment
		(start 390.71423 -61.22035)
		(end 390.71423 -64.269874)
		(width 0.089408)
		(layer "In2.Cu")
		(net "PECI_BMC")
	)
	(segment
		(start 386.802884 -78.322678)
		(end 386.802884 -79.888588)
		(width 0.089408)
		(layer "In2.Cu")
		(net "PECI_BMC")
	)
	(segment
		(start 411.658308 -38.538912)
		(end 410.84881 -38.538912)
		(width 0.089408)
		(layer "In2.Cu")
		(net "PECI_BMC")
	)
	(segment
		(start 406.639776 -38.14953)
		(end 402.717 -38.14953)
		(width 0.089408)
		(layer "In2.Cu")
		(net "PECI_BMC")
	)
	(segment
		(start 389.5598 -51.732434)
		(end 390.290304 -52.462938)
		(width 0.089408)
		(layer "In2.Cu")
		(net "PECI_BMC")
	)
	(segment
		(start 394.76299 -43.121072)
		(end 394.126212 -43.121072)
		(width 0.089408)
		(layer "In2.Cu")
		(net "PECI_BMC")
	)
	(segment
		(start 407.047954 -37.741352)
		(end 406.639776 -38.14953)
		(width 0.089408)
		(layer "In2.Cu")
		(net "PECI_BMC")
	)
	(segment
		(start 388.425182 -71.543926)
		(end 387.69036 -72.278748)
		(width 0.089408)
		(layer "In2.Cu")
		(net "PECI_BMC")
	)
	(segment
		(start 421.513762 -40.282622)
		(end 421.378888 -40.147748)
		(width 0.089408)
		(layer "In2.Cu")
		(net "PECI_BMC")
	)
	(segment
		(start 420.17315 -40.147748)
		(end 419.915594 -39.890192)
		(width 0.089408)
		(layer "In2.Cu")
		(net "PECI_BMC")
	)
	(segment
		(start 389.814816 -57.481724)
		(end 389.814816 -60.320936)
		(width 0.089408)
		(layer "In2.Cu")
		(net "PECI_BMC")
	)
	(segment
		(start 390.290304 -52.462938)
		(end 390.290304 -57.006236)
		(width 0.089408)
		(layer "In2.Cu")
		(net "PECI_BMC")
	)
	(segment
		(start 410.537152 -38.53815)
		(end 410.53639 -38.538912)
		(width 0.089408)
		(layer "In2.Cu")
		(net "PECI_BMC")
	)
	(segment
		(start 409.389072 -37.741352)
		(end 407.047954 -37.741352)
		(width 0.089408)
		(layer "In2.Cu")
		(net "PECI_BMC")
	)
	(segment
		(start 410.84881 -38.538912)
		(end 410.848048 -38.53815)
		(width 0.089408)
		(layer "In2.Cu")
		(net "PECI_BMC")
	)
	(segment
		(start 387.69036 -73.371456)
		(end 388.232904 -73.914)
		(width 0.089408)
		(layer "In2.Cu")
		(net "PECI_BMC")
	)
	(segment
		(start 423.919142 -42.692066)
		(end 422.138602 -40.911526)
		(width 0.089408)
		(layer "In2.Cu")
		(net "PECI_BMC")
	)
	(segment
		(start 409.487878 -37.840158)
		(end 409.389072 -37.741352)
		(width 0.089408)
		(layer "In2.Cu")
		(net "PECI_BMC")
	)
	(segment
		(start 395.990064 -40.589454)
		(end 395.990064 -41.893998)
		(width 0.089408)
		(layer "In2.Cu")
		(net "PECI_BMC")
	)
	(segment
		(start 390.71423 -64.269874)
		(end 388.129272 -66.854832)
		(width 0.089408)
		(layer "In2.Cu")
		(net "PECI_BMC")
	)
	(segment
		(start 421.513762 -40.729154)
		(end 421.513762 -40.282622)
		(width 0.089408)
		(layer "In2.Cu")
		(net "PECI_BMC")
	)
	(segment
		(start 393.236958 -44.010326)
		(end 391.67562 -44.010326)
		(width 0.089408)
		(layer "In2.Cu")
		(net "PECI_BMC")
	)
	(segment
		(start 387.585966 -77.539596)
		(end 386.802884 -78.322678)
		(width 0.089408)
		(layer "In2.Cu")
		(net "PECI_BMC")
	)
	(segment
		(start 390.290304 -57.006236)
		(end 389.814816 -57.481724)
		(width 0.089408)
		(layer "In2.Cu")
		(net "PECI_BMC")
	)
	(segment
		(start 388.232904 -73.914)
		(end 388.232904 -75.617578)
		(width 0.089408)
		(layer "In2.Cu")
		(net "PECI_BMC")
	)
	(segment
		(start 395.990064 -41.893998)
		(end 394.76299 -43.121072)
		(width 0.089408)
		(layer "In2.Cu")
		(net "PECI_BMC")
	)
	(segment
		(start 433.491894 -44.891706)
		(end 428.685706 -44.891706)
		(width 0.089408)
		(layer "In2.Cu")
		(net "PECI_BMC")
	)
	(segment
		(start 433.9209 -44.4627)
		(end 433.491894 -44.891706)
		(width 0.089408)
		(layer "In2.Cu")
		(net "PECI_BMC")
	)
	(segment
		(start 396.511018 -40.0685)
		(end 395.990064 -40.589454)
		(width 0.089408)
		(layer "In2.Cu")
		(net "PECI_BMC")
	)
	(segment
		(start 419.915594 -38.819074)
		(end 419.63086 -38.53434)
		(width 0.089408)
		(layer "In2.Cu")
		(net "PECI_BMC")
	)
	(segment
		(start 389.814816 -60.320936)
		(end 390.71423 -61.22035)
		(width 0.089408)
		(layer "In2.Cu")
		(net "PECI_BMC")
	)
	(segment
		(start 388.232904 -75.617578)
		(end 387.585966 -76.264516)
		(width 0.089408)
		(layer "In2.Cu")
		(net "PECI_BMC")
	)
	(segment
		(start 422.138602 -40.911526)
		(end 421.696134 -40.911526)
		(width 0.089408)
		(layer "In2.Cu")
		(net "PECI_BMC")
	)
	(segment
		(start 421.696134 -40.911526)
		(end 421.513762 -40.729154)
		(width 0.089408)
		(layer "In2.Cu")
		(net "PECI_BMC")
	)
	(segment
		(start 409.487878 -38.262306)
		(end 409.487878 -37.840158)
		(width 0.089408)
		(layer "In2.Cu")
		(net "PECI_BMC")
	)
	(segment
		(start 416.687 -40.088312)
		(end 412.29915 -40.088312)
		(width 0.089408)
		(layer "In2.Cu")
		(net "PECI_BMC")
	)
	(segment
		(start 402.717 -38.14953)
		(end 400.79803 -40.0685)
		(width 0.089408)
		(layer "In2.Cu")
		(net "PECI_BMC")
	)
	(segment
		(start 419.63086 -38.53434)
		(end 418.240972 -38.53434)
		(width 0.089408)
		(layer "In2.Cu")
		(net "PECI_BMC")
	)
	(segment
		(start 394.126212 -43.121072)
		(end 393.236958 -44.010326)
		(width 0.089408)
		(layer "In2.Cu")
		(net "PECI_BMC")
	)
	(segment
		(start 410.848048 -38.53815)
		(end 410.537152 -38.53815)
		(width 0.089408)
		(layer "In2.Cu")
		(net "PECI_BMC")
	)
	(segment
		(start 428.685706 -44.891706)
		(end 426.486066 -42.692066)
		(width 0.089408)
		(layer "In2.Cu")
		(net "PECI_BMC")
	)
	(segment
		(start 426.486066 -42.692066)
		(end 423.919142 -42.692066)
		(width 0.089408)
		(layer "In2.Cu")
		(net "PECI_BMC")
	)
	(segment
		(start 388.129272 -70.099682)
		(end 388.425182 -70.395592)
		(width 0.089408)
		(layer "In2.Cu")
		(net "PECI_BMC")
	)
	(segment
		(start 412.29915 -40.088312)
		(end 411.899354 -39.688516)
		(width 0.089408)
		(layer "In2.Cu")
		(net "PECI_BMC")
	)
	(segment
		(start 411.899354 -39.688516)
		(end 411.899354 -38.779958)
		(width 0.089408)
		(layer "In2.Cu")
		(net "PECI_BMC")
	)
	(segment
		(start 389.5598 -46.126146)
		(end 389.5598 -51.732434)
		(width 0.089408)
		(layer "In2.Cu")
		(net "PECI_BMC")
	)
	(segment
		(start 419.915594 -39.890192)
		(end 419.915594 -38.819074)
		(width 0.089408)
		(layer "In2.Cu")
		(net "PECI_BMC")
	)
	(segment
		(start 388.129272 -66.854832)
		(end 388.129272 -70.099682)
		(width 0.089408)
		(layer "In2.Cu")
		(net "PECI_BMC")
	)
	(segment
		(start 386.802884 -79.888588)
		(end 387.07949 -80.165194)
		(width 0.089408)
		(layer "In2.Cu")
		(net "PECI_BMC")
	)
	(segment
		(start 387.69036 -72.278748)
		(end 387.69036 -73.371456)
		(width 0.089408)
		(layer "In2.Cu")
		(net "PECI_BMC")
	)
	(segment
		(start 387.585966 -76.264516)
		(end 387.585966 -77.539596)
		(width 0.089408)
		(layer "In2.Cu")
		(net "PECI_BMC")
	)
	(segment
		(start 387.07949 -80.165194)
		(end 387.07949 -81.000854)
		(width 0.089408)
		(layer "In2.Cu")
		(net "PECI_BMC")
	)
	(segment
		(start 411.899354 -38.779958)
		(end 411.658308 -38.538912)
		(width 0.089408)
		(layer "In2.Cu")
		(net "PECI_BMC")
	)
	(via
		(at 452.8566 -2.413)
		(size 0.6604)
		(drill 0.3302)
		(layers "F.Cu" "B.Cu")
		(net "PD_RST_RTCRST_N")
	)
	(segment
		(start 452.35241 -2.9591)
		(end 452.8566 -2.45491)
		(width 0.10795)
		(layer "B.Cu")
		(net "PD_RST_RTCRST_N")
	)
	(segment
		(start 454.534016 -0.252984)
		(end 454.534016 1.27)
		(width 0.10795)
		(layer "B.Cu")
		(net "PD_RST_RTCRST_N")
	)
	(segment
		(start 452.35241 -3.852672)
		(end 452.35241 -2.9591)
		(width 0.10795)
		(layer "B.Cu")
		(net "PD_RST_RTCRST_N")
	)
	(segment
		(start 452.8566 -1.9304)
		(end 454.534016 -0.252984)
		(width 0.10795)
		(layer "B.Cu")
		(net "PD_RST_RTCRST_N")
	)
	(segment
		(start 452.8566 -2.413)
		(end 452.8566 -1.9304)
		(width 0.10795)
		(layer "B.Cu")
		(net "PD_RST_RTCRST_N")
	)
	(segment
		(start 452.8566 -2.45491)
		(end 452.8566 -2.413)
		(width 0.10795)
		(layer "B.Cu")
		(net "PD_RST_RTCRST_N")
	)
	(via
		(at 368.812318 -4.2672)
		(size 0.6604)
		(drill 0.3302)
		(layers "F.Cu" "B.Cu")
		(net "PD_PASSWORD_CLEAR")
	)
	(segment
		(start 378.968 3.81)
		(end 377.872752 4.905248)
		(width 0.10795)
		(layer "B.Cu")
		(net "PD_PASSWORD_CLEAR")
	)
	(segment
		(start 367.9444 -5.135118)
		(end 367.9444 -5.3467)
		(width 0.10795)
		(layer "B.Cu")
		(net "PD_PASSWORD_CLEAR")
	)
	(segment
		(start 368.2492 2.3622)
		(end 367.637314 1.750314)
		(width 0.10795)
		(layer "B.Cu")
		(net "PD_PASSWORD_CLEAR")
	)
	(segment
		(start 368.812318 -4.2672)
		(end 367.9444 -5.135118)
		(width 0.10795)
		(layer "B.Cu")
		(net "PD_PASSWORD_CLEAR")
	)
	(segment
		(start 377.872752 4.905248)
		(end 370.7638 4.905248)
		(width 0.10795)
		(layer "B.Cu")
		(net "PD_PASSWORD_CLEAR")
	)
	(segment
		(start 370.078 4.219448)
		(end 370.078 3.0988)
		(width 0.10795)
		(layer "B.Cu")
		(net "PD_PASSWORD_CLEAR")
	)
	(segment
		(start 369.3414 2.3622)
		(end 368.2492 2.3622)
		(width 0.10795)
		(layer "B.Cu")
		(net "PD_PASSWORD_CLEAR")
	)
	(segment
		(start 367.637314 1.750314)
		(end 367.637314 0.36195)
		(width 0.10795)
		(layer "B.Cu")
		(net "PD_PASSWORD_CLEAR")
	)
	(segment
		(start 368.812318 -3.10515)
		(end 368.812318 -4.2672)
		(width 0.10795)
		(layer "B.Cu")
		(net "PD_PASSWORD_CLEAR")
	)
	(segment
		(start 367.637314 0.36195)
		(end 367.276634 0.00127)
		(width 0.10795)
		(layer "B.Cu")
		(net "PD_PASSWORD_CLEAR")
	)
	(segment
		(start 367.276634 0.00127)
		(end 367.276634 -1.569466)
		(width 0.10795)
		(layer "B.Cu")
		(net "PD_PASSWORD_CLEAR")
	)
	(segment
		(start 370.7638 4.905248)
		(end 370.078 4.219448)
		(width 0.10795)
		(layer "B.Cu")
		(net "PD_PASSWORD_CLEAR")
	)
	(segment
		(start 370.078 3.0988)
		(end 369.3414 2.3622)
		(width 0.10795)
		(layer "B.Cu")
		(net "PD_PASSWORD_CLEAR")
	)
	(segment
		(start 367.276634 -1.569466)
		(end 368.812318 -3.10515)
		(width 0.10795)
		(layer "B.Cu")
		(net "PD_PASSWORD_CLEAR")
	)
	(via
		(at 371.94236 -62.84214)
		(size 0.6604)
		(drill 0.3302)
		(layers "F.Cu" "B.Cu")
		(net "PD_GTL2104_DIR_1")
	)
	(segment
		(start 372.676166 -61.427614)
		(end 372.676166 -61.098938)
		(width 0.10795)
		(layer "B.Cu")
		(net "PD_GTL2104_DIR_1")
	)
	(segment
		(start 372.676166 -61.098938)
		(end 372.071138 -61.098938)
		(width 0.10795)
		(layer "B.Cu")
		(net "PD_GTL2104_DIR_1")
	)
	(segment
		(start 371.85092 -60.87872)
		(end 370.3955 -60.87872)
		(width 0.10795)
		(layer "B.Cu")
		(net "PD_GTL2104_DIR_1")
	)
	(segment
		(start 371.94236 -62.16142)
		(end 372.676166 -61.427614)
		(width 0.10795)
		(layer "B.Cu")
		(net "PD_GTL2104_DIR_1")
	)
	(segment
		(start 372.071138 -61.098938)
		(end 371.85092 -60.87872)
		(width 0.10795)
		(layer "B.Cu")
		(net "PD_GTL2104_DIR_1")
	)
	(segment
		(start 371.94236 -62.84214)
		(end 371.94236 -62.16142)
		(width 0.10795)
		(layer "B.Cu")
		(net "PD_GTL2104_DIR_1")
	)
	(segment
		(start 386.2705 -79.1972)
		(end 386.2705 -79.8322)
		(width 0.10795)
		(layer "F.Cu")
		(net "PD_GTL2104_DIR_0")
	)
	(segment
		(start 386.326888 -79.140812)
		(end 386.2705 -79.1972)
		(width 0.10795)
		(layer "F.Cu")
		(net "PD_GTL2104_DIR_0")
	)
	(segment
		(start 386.326888 -78.388718)
		(end 386.326888 -79.140812)
		(width 0.10795)
		(layer "F.Cu")
		(net "PD_GTL2104_DIR_0")
	)
	(segment
		(start 118.380764 -74.282808)
		(end 118.380764 -75.167236)
		(width 0.10795)
		(layer "F.Cu")
		(net "PD_CPU1_TXT_PLTEN")
	)
	(segment
		(start 118.380764 -75.167236)
		(end 117.221 -76.327)
		(width 0.10795)
		(layer "F.Cu")
		(net "PD_CPU1_TXT_PLTEN")
	)
	(segment
		(start 130.231388 -69.772784)
		(end 130.802888 -69.772784)
		(width 0.10795)
		(layer "F.Cu")
		(net "PD_CPU1_TXT_PLTEN")
	)
	(via
		(at 118.380764 -74.282808)
		(size 0.508)
		(drill 0.254)
		(layers "F.Cu" "B.Cu")
		(net "PD_CPU1_TXT_PLTEN")
	)
	(via
		(at 130.802888 -69.772784)
		(size 0.508)
		(drill 0.254)
		(layers "F.Cu" "B.Cu")
		(net "PD_CPU1_TXT_PLTEN")
	)
	(segment
		(start 128.888236 -70.17131)
		(end 128.371346 -70.6882)
		(width 0.0889)
		(layer "In2.Cu")
		(net "PD_CPU1_TXT_PLTEN")
	)
	(segment
		(start 122.382788 -70.364858)
		(end 121.831862 -70.364858)
		(width 0.0889)
		(layer "In2.Cu")
		(net "PD_CPU1_TXT_PLTEN")
	)
	(segment
		(start 124.099828 -70.364858)
		(end 123.769628 -70.364858)
		(width 0.0889)
		(layer "In2.Cu")
		(net "PD_CPU1_TXT_PLTEN")
	)
	(segment
		(start 119.523002 -73.14311)
		(end 119.38635 -73.14311)
		(width 0.0889)
		(layer "In2.Cu")
		(net "PD_CPU1_TXT_PLTEN")
	)
	(segment
		(start 127.043942 -70.364858)
		(end 126.6952 -70.7136)
		(width 0.0889)
		(layer "In2.Cu")
		(net "PD_CPU1_TXT_PLTEN")
	)
	(segment
		(start 124.545344 -70.673722)
		(end 124.408692 -70.673722)
		(width 0.0889)
		(layer "In2.Cu")
		(net "PD_CPU1_TXT_PLTEN")
	)
	(segment
		(start 122.68454 -70.66661)
		(end 122.382788 -70.364858)
		(width 0.0889)
		(layer "In2.Cu")
		(net "PD_CPU1_TXT_PLTEN")
	)
	(segment
		(start 127.9398 -70.6882)
		(end 127.616458 -70.364858)
		(width 0.0889)
		(layer "In2.Cu")
		(net "PD_CPU1_TXT_PLTEN")
	)
	(segment
		(start 127.616458 -70.364858)
		(end 127.043942 -70.364858)
		(width 0.0889)
		(layer "In2.Cu")
		(net "PD_CPU1_TXT_PLTEN")
	)
	(segment
		(start 123.467876 -70.66661)
		(end 122.68454 -70.66661)
		(width 0.0889)
		(layer "In2.Cu")
		(net "PD_CPU1_TXT_PLTEN")
	)
	(segment
		(start 125.486668 -70.364858)
		(end 125.181614 -70.669912)
		(width 0.0889)
		(layer "In2.Cu")
		(net "PD_CPU1_TXT_PLTEN")
	)
	(segment
		(start 126.016004 -70.364858)
		(end 125.486668 -70.364858)
		(width 0.0889)
		(layer "In2.Cu")
		(net "PD_CPU1_TXT_PLTEN")
	)
	(segment
		(start 121.336308 -70.860412)
		(end 121.194068 -70.860412)
		(width 0.0889)
		(layer "In2.Cu")
		(net "PD_CPU1_TXT_PLTEN")
	)
	(segment
		(start 124.549154 -70.669912)
		(end 124.545344 -70.673722)
		(width 0.0889)
		(layer "In2.Cu")
		(net "PD_CPU1_TXT_PLTEN")
	)
	(segment
		(start 124.408692 -70.673722)
		(end 124.099828 -70.364858)
		(width 0.0889)
		(layer "In2.Cu")
		(net "PD_CPU1_TXT_PLTEN")
	)
	(segment
		(start 126.364746 -70.7136)
		(end 126.016004 -70.364858)
		(width 0.0889)
		(layer "In2.Cu")
		(net "PD_CPU1_TXT_PLTEN")
	)
	(segment
		(start 121.194068 -70.860412)
		(end 119.888 -72.16648)
		(width 0.0889)
		(layer "In2.Cu")
		(net "PD_CPU1_TXT_PLTEN")
	)
	(segment
		(start 129.649474 -69.772784)
		(end 129.250948 -70.17131)
		(width 0.0889)
		(layer "In2.Cu")
		(net "PD_CPU1_TXT_PLTEN")
	)
	(segment
		(start 119.888 -72.778112)
		(end 119.523002 -73.14311)
		(width 0.0889)
		(layer "In2.Cu")
		(net "PD_CPU1_TXT_PLTEN")
	)
	(segment
		(start 119.38635 -73.14311)
		(end 118.959376 -73.570084)
		(width 0.0889)
		(layer "In2.Cu")
		(net "PD_CPU1_TXT_PLTEN")
	)
	(segment
		(start 126.6952 -70.7136)
		(end 126.364746 -70.7136)
		(width 0.0889)
		(layer "In2.Cu")
		(net "PD_CPU1_TXT_PLTEN")
	)
	(segment
		(start 121.831862 -70.364858)
		(end 121.336308 -70.860412)
		(width 0.0889)
		(layer "In2.Cu")
		(net "PD_CPU1_TXT_PLTEN")
	)
	(segment
		(start 130.802888 -69.772784)
		(end 129.649474 -69.772784)
		(width 0.0889)
		(layer "In2.Cu")
		(net "PD_CPU1_TXT_PLTEN")
	)
	(segment
		(start 125.181614 -70.669912)
		(end 124.549154 -70.669912)
		(width 0.0889)
		(layer "In2.Cu")
		(net "PD_CPU1_TXT_PLTEN")
	)
	(segment
		(start 129.250948 -70.17131)
		(end 128.888236 -70.17131)
		(width 0.0889)
		(layer "In2.Cu")
		(net "PD_CPU1_TXT_PLTEN")
	)
	(segment
		(start 119.888 -72.16648)
		(end 119.888 -72.778112)
		(width 0.0889)
		(layer "In2.Cu")
		(net "PD_CPU1_TXT_PLTEN")
	)
	(segment
		(start 118.959376 -73.704196)
		(end 118.380764 -74.282808)
		(width 0.0889)
		(layer "In2.Cu")
		(net "PD_CPU1_TXT_PLTEN")
	)
	(segment
		(start 118.959376 -73.570084)
		(end 118.959376 -73.704196)
		(width 0.0889)
		(layer "In2.Cu")
		(net "PD_CPU1_TXT_PLTEN")
	)
	(segment
		(start 123.769628 -70.364858)
		(end 123.467876 -70.66661)
		(width 0.0889)
		(layer "In2.Cu")
		(net "PD_CPU1_TXT_PLTEN")
	)
	(segment
		(start 128.371346 -70.6882)
		(end 127.9398 -70.6882)
		(width 0.0889)
		(layer "In2.Cu")
		(net "PD_CPU1_TXT_PLTEN")
	)
	(segment
		(start 117.2972 -75.565)
		(end 117.221 -75.565)
		(width 0.10795)
		(layer "F.Cu")
		(net "PD_CPU1_BIST_ENABLE")
	)
	(segment
		(start 125.938788 -71.258938)
		(end 126.510288 -71.258938)
		(width 0.10795)
		(layer "F.Cu")
		(net "PD_CPU1_BIST_ENABLE")
	)
	(segment
		(start 117.856 -74.803)
		(end 117.856 -75.0062)
		(width 0.10795)
		(layer "F.Cu")
		(net "PD_CPU1_BIST_ENABLE")
	)
	(segment
		(start 117.856 -75.0062)
		(end 117.2972 -75.565)
		(width 0.10795)
		(layer "F.Cu")
		(net "PD_CPU1_BIST_ENABLE")
	)
	(via
		(at 117.856 -74.803)
		(size 0.508)
		(drill 0.254)
		(layers "F.Cu" "B.Cu")
		(net "PD_CPU1_BIST_ENABLE")
	)
	(via
		(at 126.510288 -71.258938)
		(size 0.508)
		(drill 0.254)
		(layers "F.Cu" "B.Cu")
		(net "PD_CPU1_BIST_ENABLE")
	)
	(segment
		(start 126.41326 -71.16191)
		(end 125.486668 -71.16191)
		(width 0.0889)
		(layer "In2.Cu")
		(net "PD_CPU1_BIST_ENABLE")
	)
	(segment
		(start 124.32665 -71.16191)
		(end 123.542806 -71.16191)
		(width 0.0889)
		(layer "In2.Cu")
		(net "PD_CPU1_BIST_ENABLE")
	)
	(segment
		(start 119.329454 -74.327258)
		(end 119.144542 -74.327258)
		(width 0.0889)
		(layer "In2.Cu")
		(net "PD_CPU1_BIST_ENABLE")
	)
	(segment
		(start 126.510288 -71.258938)
		(end 126.41326 -71.16191)
		(width 0.0889)
		(layer "In2.Cu")
		(net "PD_CPU1_BIST_ENABLE")
	)
	(segment
		(start 120.269 -72.506586)
		(end 120.269 -73.387712)
		(width 0.0889)
		(layer "In2.Cu")
		(net "PD_CPU1_BIST_ENABLE")
	)
	(segment
		(start 122.911108 -70.860412)
		(end 122.416062 -71.355458)
		(width 0.0889)
		(layer "In2.Cu")
		(net "PD_CPU1_BIST_ENABLE")
	)
	(segment
		(start 121.750582 -71.657464)
		(end 121.118122 -71.657464)
		(width 0.0889)
		(layer "In2.Cu")
		(net "PD_CPU1_BIST_ENABLE")
	)
	(segment
		(start 122.052588 -71.355458)
		(end 121.750582 -71.657464)
		(width 0.0889)
		(layer "In2.Cu")
		(net "PD_CPU1_BIST_ENABLE")
	)
	(segment
		(start 124.628148 -70.860412)
		(end 124.32665 -71.16191)
		(width 0.0889)
		(layer "In2.Cu")
		(net "PD_CPU1_BIST_ENABLE")
	)
	(segment
		(start 122.416062 -71.355458)
		(end 122.052588 -71.355458)
		(width 0.0889)
		(layer "In2.Cu")
		(net "PD_CPU1_BIST_ENABLE")
	)
	(segment
		(start 125.18517 -70.860412)
		(end 124.628148 -70.860412)
		(width 0.0889)
		(layer "In2.Cu")
		(net "PD_CPU1_BIST_ENABLE")
	)
	(segment
		(start 119.144542 -74.327258)
		(end 118.6688 -74.803)
		(width 0.0889)
		(layer "In2.Cu")
		(net "PD_CPU1_BIST_ENABLE")
	)
	(segment
		(start 125.486668 -71.16191)
		(end 125.18517 -70.860412)
		(width 0.0889)
		(layer "In2.Cu")
		(net "PD_CPU1_BIST_ENABLE")
	)
	(segment
		(start 118.6688 -74.803)
		(end 117.856 -74.803)
		(width 0.0889)
		(layer "In2.Cu")
		(net "PD_CPU1_BIST_ENABLE")
	)
	(segment
		(start 120.269 -73.387712)
		(end 119.329454 -74.327258)
		(width 0.0889)
		(layer "In2.Cu")
		(net "PD_CPU1_BIST_ENABLE")
	)
	(segment
		(start 123.241308 -70.860412)
		(end 122.911108 -70.860412)
		(width 0.0889)
		(layer "In2.Cu")
		(net "PD_CPU1_BIST_ENABLE")
	)
	(segment
		(start 123.542806 -71.16191)
		(end 123.241308 -70.860412)
		(width 0.0889)
		(layer "In2.Cu")
		(net "PD_CPU1_BIST_ENABLE")
	)
	(segment
		(start 121.118122 -71.657464)
		(end 120.269 -72.506586)
		(width 0.0889)
		(layer "In2.Cu")
		(net "PD_CPU1_BIST_ENABLE")
	)
	(segment
		(start 295.23182 -69.772784)
		(end 295.80332 -69.772784)
		(width 0.10795)
		(layer "F.Cu")
		(net "PD_CPU0_TXT_PLTEN")
	)
	(segment
		(start 282.067 -75.946)
		(end 282.6258 -75.946)
		(width 0.10795)
		(layer "F.Cu")
		(net "PD_CPU0_TXT_PLTEN")
	)
	(segment
		(start 282.6258 -75.946)
		(end 282.9306 -75.6412)
		(width 0.10795)
		(layer "F.Cu")
		(net "PD_CPU0_TXT_PLTEN")
	)
	(via
		(at 295.80332 -69.772784)
		(size 0.508)
		(drill 0.254)
		(layers "F.Cu" "B.Cu")
		(net "PD_CPU0_TXT_PLTEN")
	)
	(via
		(at 282.9306 -75.6412)
		(size 0.508)
		(drill 0.254)
		(layers "F.Cu" "B.Cu")
		(net "PD_CPU0_TXT_PLTEN")
	)
	(segment
		(start 283.11602 -73.909174)
		(end 283.134054 -73.927208)
		(width 0.0889)
		(layer "In2.Cu")
		(net "PD_CPU0_TXT_PLTEN")
	)
	(segment
		(start 282.869894 -73.617074)
		(end 282.869894 -73.635108)
		(width 0.0889)
		(layer "In2.Cu")
		(net "PD_CPU0_TXT_PLTEN")
	)
	(segment
		(start 285.875222 -71.860664)
		(end 285.762446 -71.97344)
		(width 0.0889)
		(layer "In2.Cu")
		(net "PD_CPU0_TXT_PLTEN")
	)
	(segment
		(start 293.890954 -70.17766)
		(end 293.380414 -70.6882)
		(width 0.0889)
		(layer "In2.Cu")
		(net "PD_CPU0_TXT_PLTEN")
	)
	(segment
		(start 290.667186 -71.163434)
		(end 290.63442 -71.163434)
		(width 0.0889)
		(layer "In2.Cu")
		(net "PD_CPU0_TXT_PLTEN")
	)
	(segment
		(start 283.40304 -72.34428)
		(end 282.76296 -72.98436)
		(width 0.0889)
		(layer "In2.Cu")
		(net "PD_CPU0_TXT_PLTEN")
	)
	(segment
		(start 283.134054 -73.927208)
		(end 283.134054 -74.136758)
		(width 0.0889)
		(layer "In2.Cu")
		(net "PD_CPU0_TXT_PLTEN")
	)
	(segment
		(start 292.751764 -70.364858)
		(end 291.960554 -70.364858)
		(width 0.0889)
		(layer "In2.Cu")
		(net "PD_CPU0_TXT_PLTEN")
	)
	(segment
		(start 284.94228 -72.34428)
		(end 283.40304 -72.34428)
		(width 0.0889)
		(layer "In2.Cu")
		(net "PD_CPU0_TXT_PLTEN")
	)
	(segment
		(start 289.804856 -71.658988)
		(end 289.782504 -71.658988)
		(width 0.0889)
		(layer "In2.Cu")
		(net "PD_CPU0_TXT_PLTEN")
	)
	(segment
		(start 291.521896 -70.668134)
		(end 291.497766 -70.668134)
		(width 0.0889)
		(layer "In2.Cu")
		(net "PD_CPU0_TXT_PLTEN")
	)
	(segment
		(start 294.65905 -69.772784)
		(end 294.254174 -70.17766)
		(width 0.0889)
		(layer "In2.Cu")
		(net "PD_CPU0_TXT_PLTEN")
	)
	(segment
		(start 285.762446 -71.97344)
		(end 285.31312 -71.97344)
		(width 0.0889)
		(layer "In2.Cu")
		(net "PD_CPU0_TXT_PLTEN")
	)
	(segment
		(start 283.11602 -73.881234)
		(end 283.11602 -73.909174)
		(width 0.0889)
		(layer "In2.Cu")
		(net "PD_CPU0_TXT_PLTEN")
	)
	(segment
		(start 283.134308 -74.137012)
		(end 283.134308 -74.257662)
		(width 0.089408)
		(layer "In2.Cu")
		(net "PD_CPU0_TXT_PLTEN")
	)
	(segment
		(start 282.869894 -73.635108)
		(end 283.11602 -73.881234)
		(width 0.0889)
		(layer "In2.Cu")
		(net "PD_CPU0_TXT_PLTEN")
	)
	(segment
		(start 283.134054 -74.136758)
		(end 283.134308 -74.137012)
		(width 0.0889)
		(layer "In2.Cu")
		(net "PD_CPU0_TXT_PLTEN")
	)
	(segment
		(start 295.80332 -69.772784)
		(end 294.65905 -69.772784)
		(width 0.089408)
		(layer "In2.Cu")
		(net "PD_CPU0_TXT_PLTEN")
	)
	(segment
		(start 282.76296 -72.98436)
		(end 282.76296 -73.51014)
		(width 0.0889)
		(layer "In2.Cu")
		(net "PD_CPU0_TXT_PLTEN")
	)
	(segment
		(start 288.95294 -71.163434)
		(end 288.91738 -71.163434)
		(width 0.0889)
		(layer "In2.Cu")
		(net "PD_CPU0_TXT_PLTEN")
	)
	(segment
		(start 287.2359 -71.163434)
		(end 287.20034 -71.163434)
		(width 0.0889)
		(layer "In2.Cu")
		(net "PD_CPU0_TXT_PLTEN")
	)
	(segment
		(start 294.254174 -70.17766)
		(end 293.890954 -70.17766)
		(width 0.0889)
		(layer "In2.Cu")
		(net "PD_CPU0_TXT_PLTEN")
	)
	(segment
		(start 283.134308 -74.257662)
		(end 283.0322 -74.35977)
		(width 0.089408)
		(layer "In2.Cu")
		(net "PD_CPU0_TXT_PLTEN")
	)
	(segment
		(start 283.0322 -74.35977)
		(end 283.0322 -75.5396)
		(width 0.089408)
		(layer "In2.Cu")
		(net "PD_CPU0_TXT_PLTEN")
	)
	(segment
		(start 283.0322 -75.5396)
		(end 282.9306 -75.6412)
		(width 0.089408)
		(layer "In2.Cu")
		(net "PD_CPU0_TXT_PLTEN")
	)
	(segment
		(start 293.075106 -70.6882)
		(end 292.751764 -70.364858)
		(width 0.0889)
		(layer "In2.Cu")
		(net "PD_CPU0_TXT_PLTEN")
	)
	(segment
		(start 282.76296 -73.51014)
		(end 282.869894 -73.617074)
		(width 0.0889)
		(layer "In2.Cu")
		(net "PD_CPU0_TXT_PLTEN")
	)
	(segment
		(start 286.370776 -71.658988)
		(end 286.33801 -71.658988)
		(width 0.0889)
		(layer "In2.Cu")
		(net "PD_CPU0_TXT_PLTEN")
	)
	(segment
		(start 288.087816 -71.658988)
		(end 288.065464 -71.658988)
		(width 0.0889)
		(layer "In2.Cu")
		(net "PD_CPU0_TXT_PLTEN")
	)
	(segment
		(start 293.380414 -70.6882)
		(end 293.075106 -70.6882)
		(width 0.0889)
		(layer "In2.Cu")
		(net "PD_CPU0_TXT_PLTEN")
	)
	(segment
		(start 291.960554 -70.364858)
		(end 291.85743 -70.467982)
		(width 0.0889)
		(layer "In2.Cu")
		(net "PD_CPU0_TXT_PLTEN")
	)
	(segment
		(start 285.31312 -71.97344)
		(end 284.94228 -72.34428)
		(width 0.0889)
		(layer "In2.Cu")
		(net "PD_CPU0_TXT_PLTEN")
	)
	(arc
		(start 286.33801 -71.658988)
		(mid 286.087504 -71.715976)
		(end 285.875222 -71.860664)
		(width 0.0889)
		(layer "In2.Cu")
		(net "PD_CPU0_TXT_PLTEN")
	)
	(arc
		(start 290.14039 -71.458836)
		(mid 289.998707 -71.60264)
		(end 289.804856 -71.658988)
		(width 0.0889)
		(layer "In2.Cu")
		(net "PD_CPU0_TXT_PLTEN")
	)
	(arc
		(start 288.065464 -71.658988)
		(mid 287.871614 -71.602638)
		(end 287.72993 -71.458836)
		(width 0.0889)
		(layer "In2.Cu")
		(net "PD_CPU0_TXT_PLTEN")
	)
	(arc
		(start 287.72993 -71.458836)
		(mid 287.521322 -71.246904)
		(end 287.2359 -71.163434)
		(width 0.0889)
		(layer "In2.Cu")
		(net "PD_CPU0_TXT_PLTEN")
	)
	(arc
		(start 290.63442 -71.163434)
		(mid 290.348996 -71.246901)
		(end 290.14039 -71.458836)
		(width 0.0889)
		(layer "In2.Cu")
		(net "PD_CPU0_TXT_PLTEN")
	)
	(arc
		(start 289.44697 -71.458836)
		(mid 289.238362 -71.246904)
		(end 288.95294 -71.163434)
		(width 0.0889)
		(layer "In2.Cu")
		(net "PD_CPU0_TXT_PLTEN")
	)
	(arc
		(start 286.70631 -71.458836)
		(mid 286.564627 -71.60264)
		(end 286.370776 -71.658988)
		(width 0.0889)
		(layer "In2.Cu")
		(net "PD_CPU0_TXT_PLTEN")
	)
	(arc
		(start 288.42335 -71.458836)
		(mid 288.281667 -71.60264)
		(end 288.087816 -71.658988)
		(width 0.0889)
		(layer "In2.Cu")
		(net "PD_CPU0_TXT_PLTEN")
	)
	(arc
		(start 291.85743 -70.467982)
		(mid 291.715747 -70.611786)
		(end 291.521896 -70.668134)
		(width 0.0889)
		(layer "In2.Cu")
		(net "PD_CPU0_TXT_PLTEN")
	)
	(arc
		(start 287.20034 -71.163434)
		(mid 286.914916 -71.246901)
		(end 286.70631 -71.458836)
		(width 0.0889)
		(layer "In2.Cu")
		(net "PD_CPU0_TXT_PLTEN")
	)
	(arc
		(start 291.497766 -70.668134)
		(mid 291.209621 -70.750453)
		(end 290.99891 -70.963536)
		(width 0.0889)
		(layer "In2.Cu")
		(net "PD_CPU0_TXT_PLTEN")
	)
	(arc
		(start 288.91738 -71.163434)
		(mid 288.631956 -71.246901)
		(end 288.42335 -71.458836)
		(width 0.0889)
		(layer "In2.Cu")
		(net "PD_CPU0_TXT_PLTEN")
	)
	(arc
		(start 290.99891 -70.963536)
		(mid 290.858831 -71.106272)
		(end 290.667186 -71.163434)
		(width 0.0889)
		(layer "In2.Cu")
		(net "PD_CPU0_TXT_PLTEN")
	)
	(arc
		(start 289.782504 -71.658988)
		(mid 289.588654 -71.602638)
		(end 289.44697 -71.458836)
		(width 0.0889)
		(layer "In2.Cu")
		(net "PD_CPU0_TXT_PLTEN")
	)
	(segment
		(start 291.51072 -71.258938)
		(end 290.93922 -71.258938)
		(width 0.10795)
		(layer "F.Cu")
		(net "PD_CPU0_BIST_ENABLE")
	)
	(via
		(at 291.51072 -71.258938)
		(size 0.508)
		(drill 0.254)
		(layers "F.Cu" "B.Cu")
		(net "PD_CPU0_BIST_ENABLE")
	)
	(via
		(at 283.169106 -81.29905)
		(size 0.508)
		(drill 0.254)
		(layers "F.Cu" "B.Cu")
		(net "PD_CPU0_BIST_ENABLE")
	)
	(segment
		(start 282.591256 -80.7212)
		(end 282.0162 -80.7212)
		(width 0.10795)
		(layer "B.Cu")
		(net "PD_CPU0_BIST_ENABLE")
	)
	(segment
		(start 283.169106 -81.29905)
		(end 282.591256 -80.7212)
		(width 0.10795)
		(layer "B.Cu")
		(net "PD_CPU0_BIST_ENABLE")
	)
	(segment
		(start 291.51072 -71.459598)
		(end 291.51072 -71.258938)
		(width 0.089408)
		(layer "In9.Cu")
		(net "PD_CPU0_BIST_ENABLE")
	)
	(segment
		(start 290.817554 -72.152764)
		(end 291.51072 -71.459598)
		(width 0.089408)
		(layer "In9.Cu")
		(net "PD_CPU0_BIST_ENABLE")
	)
	(segment
		(start 285.908242 -74.822558)
		(end 286.557212 -74.822558)
		(width 0.089408)
		(layer "In9.Cu")
		(net "PD_CPU0_BIST_ENABLE")
	)
	(segment
		(start 287.911286 -73.831958)
		(end 288.048954 -73.831958)
		(width 0.089408)
		(layer "In9.Cu")
		(net "PD_CPU0_BIST_ENABLE")
	)
	(segment
		(start 286.557212 -74.822558)
		(end 287.052766 -74.327004)
		(width 0.089408)
		(layer "In9.Cu")
		(net "PD_CPU0_BIST_ENABLE")
	)
	(segment
		(start 289.100514 -73.143364)
		(end 289.574478 -72.6694)
		(width 0.089408)
		(layer "In9.Cu")
		(net "PD_CPU0_BIST_ENABLE")
	)
	(segment
		(start 283.169106 -81.29905)
		(end 283.399992 -81.068164)
		(width 0.089408)
		(layer "In9.Cu")
		(net "PD_CPU0_BIST_ENABLE")
	)
	(segment
		(start 287.052766 -74.327004)
		(end 287.41624 -74.327004)
		(width 0.089408)
		(layer "In9.Cu")
		(net "PD_CPU0_BIST_ENABLE")
	)
	(segment
		(start 285.0134 -80.578452)
		(end 285.0134 -75.7174)
		(width 0.089408)
		(layer "In9.Cu")
		(net "PD_CPU0_BIST_ENABLE")
	)
	(segment
		(start 288.048954 -73.831958)
		(end 288.737548 -73.143364)
		(width 0.089408)
		(layer "In9.Cu")
		(net "PD_CPU0_BIST_ENABLE")
	)
	(segment
		(start 284.523688 -81.068164)
		(end 285.0134 -80.578452)
		(width 0.089408)
		(layer "In9.Cu")
		(net "PD_CPU0_BIST_ENABLE")
	)
	(segment
		(start 289.574478 -72.6694)
		(end 290.1442 -72.6694)
		(width 0.089408)
		(layer "In9.Cu")
		(net "PD_CPU0_BIST_ENABLE")
	)
	(segment
		(start 285.0134 -75.7174)
		(end 285.908242 -74.822558)
		(width 0.089408)
		(layer "In9.Cu")
		(net "PD_CPU0_BIST_ENABLE")
	)
	(segment
		(start 288.737548 -73.143364)
		(end 289.100514 -73.143364)
		(width 0.089408)
		(layer "In9.Cu")
		(net "PD_CPU0_BIST_ENABLE")
	)
	(segment
		(start 283.399992 -81.068164)
		(end 284.523688 -81.068164)
		(width 0.089408)
		(layer "In9.Cu")
		(net "PD_CPU0_BIST_ENABLE")
	)
	(segment
		(start 287.41624 -74.327004)
		(end 287.911286 -73.831958)
		(width 0.089408)
		(layer "In9.Cu")
		(net "PD_CPU0_BIST_ENABLE")
	)
	(segment
		(start 290.1442 -72.6694)
		(end 290.660836 -72.152764)
		(width 0.089408)
		(layer "In9.Cu")
		(net "PD_CPU0_BIST_ENABLE")
	)
	(segment
		(start 290.660836 -72.152764)
		(end 290.817554 -72.152764)
		(width 0.089408)
		(layer "In9.Cu")
		(net "PD_CPU0_BIST_ENABLE")
	)
	(via
		(at 463.7278 -130.7846)
		(size 0.508)
		(drill 0.254)
		(layers "F.Cu" "B.Cu")
		(net "P5V_USB")
	)
	(via
		(at 463.5119 -129.8067)
		(size 0.6604)
		(drill 0.3302)
		(layers "F.Cu" "B.Cu")
		(net "P5V_USB")
	)
	(via
		(at 464.312 -130.3528)
		(size 0.508)
		(drill 0.254)
		(layers "F.Cu" "B.Cu")
		(net "P5V_USB")
	)
	(via
		(at 464.3374 -131.1402)
		(size 0.508)
		(drill 0.254)
		(layers "F.Cu" "B.Cu")
		(net "P5V_USB")
	)
	(segment
		(start 480.669854 -132.236464)
		(end 481.251006 -131.655312)
		(width 0.254)
		(layer "In9.Cu")
		(net "P5V_USB")
	)
	(segment
		(start 480.669854 -131.07416)
		(end 481.251006 -131.655312)
		(width 0.254)
		(layer "In9.Cu")
		(net "P5V_USB")
	)
	(segment
		(start 481.251006 -131.655312)
		(end 481.832158 -132.236464)
		(width 0.254)
		(layer "In9.Cu")
		(net "P5V_USB")
	)
	(segment
		(start 481.251006 -131.655312)
		(end 481.832158 -131.07416)
		(width 0.254)
		(layer "In9.Cu")
		(net "P5V_USB")
	)
	(segment
		(start 487.39679 -59.929014)
		(end 486.165398 -61.160406)
		(width 0.508)
		(layer "F.Cu")
		(net "P5V_STBY")
	)
	(segment
		(start 391.0838 -72.4535)
		(end 391.0838 -72.427592)
		(width 0.508)
		(layer "F.Cu")
		(net "P5V_STBY")
	)
	(segment
		(start 350.0628 -6.592316)
		(end 350.3168 -6.846316)
		(width 0.254)
		(layer "F.Cu")
		(net "P5V_STBY")
	)
	(segment
		(start 347.113606 -1.517904)
		(end 347.164406 -1.467104)
		(width 0.254)
		(layer "F.Cu")
		(net "P5V_STBY")
	)
	(segment
		(start 31.02991 -81.223866)
		(end 30.10027 -81.223866)
		(width 0.254)
		(layer "F.Cu")
		(net "P5V_STBY")
	)
	(segment
		(start 4.115562 -14.384782)
		(end 4.22275 -14.277594)
		(width 0.254)
		(layer "F.Cu")
		(net "P5V_STBY")
	)
	(segment
		(start 373.303292 -154.277822)
		(end 373.202454 -154.37866)
		(width 0.254)
		(layer "F.Cu")
		(net "P5V_STBY")
	)
	(segment
		(start 399.492978 -64.509142)
		(end 399.461736 -64.4779)
		(width 0.254)
		(layer "F.Cu")
		(net "P5V_STBY")
	)
	(segment
		(start 195.193158 -89.351866)
		(end 194.939158 -89.097866)
		(width 0.254)
		(layer "F.Cu")
		(net "P5V_STBY")
	)
	(segment
		(start 347.961966 -100.621084)
		(end 347.829378 -100.753672)
		(width 0.254)
		(layer "F.Cu")
		(net "P5V_STBY")
	)
	(segment
		(start 4.033012 -6.417564)
		(end 4.1656 -6.284976)
		(width 0.254)
		(layer "F.Cu")
		(net "P5V_STBY")
	)
	(segment
		(start 383.8448 -3.5814)
		(end 389.5598 -3.5814)
		(width 0.254)
		(layer "F.Cu")
		(net "P5V_STBY")
	)
	(segment
		(start 393.485624 -6.059424)
		(end 393.530836 -6.059424)
		(width 0.254)
		(layer "F.Cu")
		(net "P5V_STBY")
	)
	(segment
		(start 29.585666 -72.928988)
		(end 29.464 -72.807322)
		(width 0.254)
		(layer "F.Cu")
		(net "P5V_STBY")
	)
	(segment
		(start 347.375988 -9.468612)
		(end 347.2434 -9.6012)
		(width 0.254)
		(layer "F.Cu")
		(net "P5V_STBY")
	)
	(segment
		(start 194.818 -80.969612)
		(end 194.818 -80.899)
		(width 0.254)
		(layer "F.Cu")
		(net "P5V_STBY")
	)
	(segment
		(start 178.364388 -56.742838)
		(end 178.364388 -57.423812)
		(width 0.254)
		(layer "F.Cu")
		(net "P5V_STBY")
	)
	(segment
		(start 33.178496 -77.605382)
		(end 33.178496 -78.164182)
		(width 0.508)
		(layer "F.Cu")
		(net "P5V_STBY")
	)
	(segment
		(start 427.355 -21.971)
		(end 427.609 -21.717)
		(width 0.254)
		(layer "F.Cu")
		(net "P5V_STBY")
	)
	(segment
		(start 33.178496 -53.780182)
		(end 33.178496 -53.221382)
		(width 0.508)
		(layer "F.Cu")
		(net "P5V_STBY")
	)
	(segment
		(start 1.01346 -9.29386)
		(end 0.9144 -9.1948)
		(width 0.254)
		(layer "F.Cu")
		(net "P5V_STBY")
	)
	(segment
		(start 347.296994 -1.334516)
		(end 347.164406 -1.467104)
		(width 0.254)
		(layer "F.Cu")
		(net "P5V_STBY")
	)
	(segment
		(start 351.23374 -153.41854)
		(end 351.660206 -153.845006)
		(width 0.254)
		(layer "F.Cu")
		(net "P5V_STBY")
	)
	(segment
		(start 1.467612 -135.057388)
		(end 1.5748 -134.9502)
		(width 0.254)
		(layer "F.Cu")
		(net "P5V_STBY")
	)
	(segment
		(start 1.136142 -16.7386)
		(end 0.7874 -16.7386)
		(width 0.254)
		(layer "F.Cu")
		(net "P5V_STBY")
	)
	(segment
		(start 427.609 -21.717)
		(end 427.609 -20.955)
		(width 0.254)
		(layer "F.Cu")
		(net "P5V_STBY")
	)
	(segment
		(start 32.995108 -54.644544)
		(end 32.995108 -53.96357)
		(width 0.254)
		(layer "F.Cu")
		(net "P5V_STBY")
	)
	(segment
		(start 348.391988 -155.613862)
		(end 348.391988 -156.269436)
		(width 0.254)
		(layer "F.Cu")
		(net "P5V_STBY")
	)
	(segment
		(start 32.9438 -86.398608)
		(end 32.9438 -86.072726)
		(width 0.508)
		(layer "F.Cu")
		(net "P5V_STBY")
	)
	(segment
		(start 1.660652 -17.261078)
		(end 1.569974 -17.1704)
		(width 0.254)
		(layer "F.Cu")
		(net "P5V_STBY")
	)
	(segment
		(start 445.592454 -20.5486)
		(end 446.459356 -20.5486)
		(width 0.254)
		(layer "F.Cu")
		(net "P5V_STBY")
	)
	(segment
		(start 12.498832 -123.092464)
		(end 13.409168 -124.0028)
		(width 0.508)
		(layer "F.Cu")
		(net "P5V_STBY")
	)
	(segment
		(start 30.061408 -56.672988)
		(end 29.588968 -56.672988)
		(width 0.254)
		(layer "F.Cu")
		(net "P5V_STBY")
	)
	(segment
		(start 445.3382 -20.294346)
		(end 445.592454 -20.5486)
		(width 0.254)
		(layer "F.Cu")
		(net "P5V_STBY")
	)
	(segment
		(start 195.062094 -97.211896)
		(end 194.727322 -97.211896)
		(width 0.254)
		(layer "F.Cu")
		(net "P5V_STBY")
	)
	(segment
		(start 32.995108 -86.500716)
		(end 32.9438 -86.449408)
		(width 0.254)
		(layer "F.Cu")
		(net "P5V_STBY")
	)
	(segment
		(start 180.329586 -54.547516)
		(end 181.187344 -54.547516)
		(width 0.254)
		(layer "F.Cu")
		(net "P5V_STBY")
	)
	(segment
		(start 1.651 -144.018)
		(end 1.5748 -144.0942)
		(width 0.508)
		(layer "F.Cu")
		(net "P5V_STBY")
	)
	(segment
		(start 4.29895 -13.642594)
		(end 4.29895 -14.201394)
		(width 0.508)
		(layer "F.Cu")
		(net "P5V_STBY")
	)
	(segment
		(start 33.240726 -93.787214)
		(end 33.240726 -94.086934)
		(width 0.508)
		(layer "F.Cu")
		(net "P5V_STBY")
	)
	(segment
		(start 2.150364 -17.261078)
		(end 1.660652 -17.261078)
		(width 0.254)
		(layer "F.Cu")
		(net "P5V_STBY")
	)
	(segment
		(start 389.594852 -73.331324)
		(end 390.205976 -73.331324)
		(width 0.508)
		(layer "F.Cu")
		(net "P5V_STBY")
	)
	(segment
		(start 389.5598 -3.5814)
		(end 391.4902 -5.5118)
		(width 0.254)
		(layer "F.Cu")
		(net "P5V_STBY")
	)
	(segment
		(start 349.927164 -97.744788)
		(end 350.376744 -97.744788)
		(width 0.2032)
		(layer "F.Cu")
		(net "P5V_STBY")
	)
	(segment
		(start 30.228286 -56.839866)
		(end 30.061408 -56.672988)
		(width 0.254)
		(layer "F.Cu")
		(net "P5V_STBY")
	)
	(segment
		(start 198.00443 -70.005448)
		(end 197.9676 -70.042278)
		(width 0.508)
		(layer "F.Cu")
		(net "P5V_STBY")
	)
	(segment
		(start 434.490876 -131.3053)
		(end 434.490876 -132.0546)
		(width 0.254)
		(layer "F.Cu")
		(net "P5V_STBY")
	)
	(segment
		(start 350.218502 1.27)
		(end 350.104456 1.27)
		(width 0.254)
		(layer "F.Cu")
		(net "P5V_STBY")
	)
	(segment
		(start 30.061408 -72.928988)
		(end 29.585666 -72.928988)
		(width 0.254)
		(layer "F.Cu")
		(net "P5V_STBY")
	)
	(segment
		(start 32.995108 -62.09157)
		(end 33.102296 -61.984382)
		(width 0.254)
		(layer "F.Cu")
		(net "P5V_STBY")
	)
	(segment
		(start 373.972328 -154.277822)
		(end 373.303292 -154.277822)
		(width 0.254)
		(layer "F.Cu")
		(net "P5V_STBY")
	)
	(segment
		(start 31.02991 -56.839866)
		(end 30.228286 -56.839866)
		(width 0.254)
		(layer "F.Cu")
		(net "P5V_STBY")
	)
	(segment
		(start 24.7904 -42.6212)
		(end 24.1554 -41.9862)
		(width 0.4064)
		(layer "F.Cu")
		(net "P5V_STBY")
	)
	(segment
		(start 380.6952 -0.4318)
		(end 383.8448 -3.5814)
		(width 0.254)
		(layer "F.Cu")
		(net "P5V_STBY")
	)
	(segment
		(start 24.71928 -41.2242)
		(end 25.2095 -40.73398)
		(width 0.508)
		(layer "F.Cu")
		(net "P5V_STBY")
	)
	(segment
		(start 196.030342 -56.839866)
		(end 195.072254 -56.839866)
		(width 0.254)
		(layer "F.Cu")
		(net "P5V_STBY")
	)
	(segment
		(start -1.918716 -147.128484)
		(end -2.0828 -146.9644)
		(width 0.254)
		(layer "F.Cu")
		(net "P5V_STBY")
	)
	(segment
		(start 33.229296 -61.298582)
		(end 33.229296 -61.857382)
		(width 0.508)
		(layer "F.Cu")
		(net "P5V_STBY")
	)
	(segment
		(start 347.778578 -100.804472)
		(end 347.778578 -101.363272)
		(width 0.508)
		(layer "F.Cu")
		(net "P5V_STBY")
	)
	(segment
		(start 385.194302 -156.565092)
		(end 385.194302 -157.4292)
		(width 0.254)
		(layer "F.Cu")
		(net "P5V_STBY")
	)
	(segment
		(start 1.567942 -17.1704)
		(end 1.136142 -16.7386)
		(width 0.254)
		(layer "F.Cu")
		(net "P5V_STBY")
	)
	(segment
		(start 8.919972 -122.898154)
		(end 9.30529 -123.283472)
		(width 0.508)
		(layer "F.Cu")
		(net "P5V_STBY")
	)
	(segment
		(start 398.808956 -64.720216)
		(end 395.910562 -64.720216)
		(width 0.254)
		(layer "F.Cu")
		(net "P5V_STBY")
	)
	(segment
		(start 487.995976 -137.2616)
		(end 487.995976 -135.5725)
		(width 0.254)
		(layer "F.Cu")
		(net "P5V_STBY")
	)
	(segment
		(start 32.995108 -62.772544)
		(end 32.995108 -62.09157)
		(width 0.254)
		(layer "F.Cu")
		(net "P5V_STBY")
	)
	(segment
		(start 428.0408 -20.955)
		(end 427.609 -20.955)
		(width 0.254)
		(layer "F.Cu")
		(net "P5V_STBY")
	)
	(segment
		(start 195.219066 -73.095866)
		(end 194.95262 -72.82942)
		(width 0.254)
		(layer "F.Cu")
		(net "P5V_STBY")
	)
	(segment
		(start 197.99554 -54.644544)
		(end 197.99554 -53.96357)
		(width 0.254)
		(layer "F.Cu")
		(net "P5V_STBY")
	)
	(segment
		(start 195.072254 -56.839866)
		(end 194.769994 -56.537606)
		(width 0.254)
		(layer "F.Cu")
		(net "P5V_STBY")
	)
	(segment
		(start 194.699128 -64.681608)
		(end 194.724528 -64.707008)
		(width 0.254)
		(layer "F.Cu")
		(net "P5V_STBY")
	)
	(segment
		(start 30.228286 -97.479866)
		(end 30.061408 -97.312988)
		(width 0.254)
		(layer "F.Cu")
		(net "P5V_STBY")
	)
	(segment
		(start 198.178928 -53.780182)
		(end 198.102728 -53.856382)
		(width 0.508)
		(layer "F.Cu")
		(net "P5V_STBY")
	)
	(segment
		(start 195.30949 -64.967866)
		(end 196.030342 -64.967866)
		(width 0.254)
		(layer "F.Cu")
		(net "P5V_STBY")
	)
	(segment
		(start 31.02991 -64.967866)
		(end 30.228286 -64.967866)
		(width 0.254)
		(layer "F.Cu")
		(net "P5V_STBY")
	)
	(segment
		(start 195.330064 -97.479866)
		(end 195.062094 -97.211896)
		(width 0.254)
		(layer "F.Cu")
		(net "P5V_STBY")
	)
	(segment
		(start 446.459356 -20.5486)
		(end 447.132456 -21.2217)
		(width 0.254)
		(layer "F.Cu")
		(net "P5V_STBY")
	)
	(segment
		(start 350.376744 -97.744788)
		(end 350.547432 -97.915476)
		(width 0.2032)
		(layer "F.Cu")
		(net "P5V_STBY")
	)
	(segment
		(start 488.67314 -154.1907)
		(end 488.4166 -153.93416)
		(width 0.254)
		(layer "F.Cu")
		(net "P5V_STBY")
	)
	(segment
		(start 30.061408 -89.184988)
		(end 29.585666 -89.184988)
		(width 0.254)
		(layer "F.Cu")
		(net "P5V_STBY")
	)
	(segment
		(start 395.910562 -64.720216)
		(end 393.916408 -62.726062)
		(width 0.254)
		(layer "F.Cu")
		(net "P5V_STBY")
	)
	(segment
		(start 33.102296 -53.856382)
		(end 33.178496 -53.780182)
		(width 0.508)
		(layer "F.Cu")
		(net "P5V_STBY")
	)
	(segment
		(start -1.184148 -137.90549)
		(end -1.930146 -137.90549)
		(width 0.254)
		(layer "F.Cu")
		(net "P5V_STBY")
	)
	(segment
		(start 382.234694 -154.599894)
		(end 382.1938 -154.559)
		(width 0.254)
		(layer "F.Cu")
		(net "P5V_STBY")
	)
	(segment
		(start 1.7018 -134.8232)
		(end 1.5748 -134.9502)
		(width 0.254)
		(layer "F.Cu")
		(net "P5V_STBY")
	)
	(segment
		(start 348.2086 -149.112224)
		(end 348.2086 -148.553424)
		(width 0.508)
		(layer "F.Cu")
		(net "P5V_STBY")
	)
	(segment
		(start 351.388934 -145.49374)
		(end 351.870264 -145.97507)
		(width 0.254)
		(layer "F.Cu")
		(net "P5V_STBY")
	)
	(segment
		(start 33.16859 -94.15907)
		(end 33.16859 -94.50959)
		(width 0.508)
		(layer "F.Cu")
		(net "P5V_STBY")
	)
	(segment
		(start 198.039228 -93.861382)
		(end 198.039228 -94.445582)
		(width 0.508)
		(layer "F.Cu")
		(net "P5V_STBY")
	)
	(segment
		(start 4.2164 -5.675376)
		(end 4.2164 -6.234176)
		(width 0.508)
		(layer "F.Cu")
		(net "P5V_STBY")
	)
	(segment
		(start 399.461736 -64.4779)
		(end 399.051272 -64.4779)
		(width 0.254)
		(layer "F.Cu")
		(net "P5V_STBY")
	)
	(segment
		(start 194.724528 -64.707008)
		(end 195.048632 -64.707008)
		(width 0.254)
		(layer "F.Cu")
		(net "P5V_STBY")
	)
	(segment
		(start 195.048632 -64.707008)
		(end 195.30949 -64.967866)
		(width 0.254)
		(layer "F.Cu")
		(net "P5V_STBY")
	)
	(segment
		(start 197.9676 -70.042278)
		(end 197.9676 -70.1548)
		(width 0.508)
		(layer "F.Cu")
		(net "P5V_STBY")
	)
	(segment
		(start 32.995108 -87.156544)
		(end 32.995108 -86.500716)
		(width 0.254)
		(layer "F.Cu")
		(net "P5V_STBY")
	)
	(segment
		(start 351.660206 -153.845006)
		(end 351.724976 -153.845006)
		(width 0.254)
		(layer "F.Cu")
		(net "P5V_STBY")
	)
	(segment
		(start 29.585666 -97.312988)
		(end 29.464 -97.191322)
		(width 0.254)
		(layer "F.Cu")
		(net "P5V_STBY")
	)
	(segment
		(start 348.4118 -156.8958)
		(end 348.4118 -157.2768)
		(width 0.254)
		(layer "F.Cu")
		(net "P5V_STBY")
	)
	(segment
		(start 32.995108 -70.21957)
		(end 33.102296 -70.112382)
		(width 0.254)
		(layer "F.Cu")
		(net "P5V_STBY")
	)
	(segment
		(start 197.99554 -70.261226)
		(end 197.9676 -70.233286)
		(width 0.254)
		(layer "F.Cu")
		(net "P5V_STBY")
	)
	(segment
		(start 488.4166 -153.93416)
		(end 488.4166 -153.5303)
		(width 0.254)
		(layer "F.Cu")
		(net "P5V_STBY")
	)
	(segment
		(start 334.5942 -22.7584)
		(end 333.9084 -22.7584)
		(width 0.508)
		(layer "F.Cu")
		(net "P5V_STBY")
	)
	(segment
		(start 490.524546 -153.68016)
		(end 490.014006 -154.1907)
		(width 0.254)
		(layer "F.Cu")
		(net "P5V_STBY")
	)
	(segment
		(start 197.99554 -53.96357)
		(end 198.102728 -53.856382)
		(width 0.254)
		(layer "F.Cu")
		(net "P5V_STBY")
	)
	(segment
		(start 391.4902 -5.5118)
		(end 392.938 -5.5118)
		(width 0.254)
		(layer "F.Cu")
		(net "P5V_STBY")
	)
	(segment
		(start 30.228286 -64.967866)
		(end 30.03042 -64.77)
		(width 0.254)
		(layer "F.Cu")
		(net "P5V_STBY")
	)
	(segment
		(start 4.033012 -7.098538)
		(end 4.033012 -6.417564)
		(width 0.254)
		(layer "F.Cu")
		(net "P5V_STBY")
	)
	(segment
		(start 24.1554 -41.9862)
		(end 24.1554 -41.2242)
		(width 0.508)
		(layer "F.Cu")
		(net "P5V_STBY")
	)
	(segment
		(start 197.8914 -78.2066)
		(end 198.065644 -78.032356)
		(width 0.508)
		(layer "F.Cu")
		(net "P5V_STBY")
	)
	(segment
		(start 348.391988 -147.689062)
		(end 348.391988 -148.370036)
		(width 0.254)
		(layer "F.Cu")
		(net "P5V_STBY")
	)
	(segment
		(start 348.2594 -156.402024)
		(end 348.2594 -156.7434)
		(width 0.254)
		(layer "F.Cu")
		(net "P5V_STBY")
	)
	(segment
		(start 197.99554 -87.156544)
		(end 197.99554 -86.47557)
		(width 0.254)
		(layer "F.Cu")
		(net "P5V_STBY")
	)
	(segment
		(start 194.769994 -56.537606)
		(end 194.724528 -56.537606)
		(width 0.254)
		(layer "F.Cu")
		(net "P5V_STBY")
	)
	(segment
		(start 347.961966 -99.94011)
		(end 347.961966 -100.621084)
		(width 0.254)
		(layer "F.Cu")
		(net "P5V_STBY")
	)
	(segment
		(start 392.938 -5.5118)
		(end 393.485624 -6.059424)
		(width 0.254)
		(layer "F.Cu")
		(net "P5V_STBY")
	)
	(segment
		(start 385.194302 -157.4292)
		(end 385.1656 -157.4292)
		(width 0.254)
		(layer "F.Cu")
		(net "P5V_STBY")
	)
	(segment
		(start 349.341186 -6.592316)
		(end 350.0628 -6.592316)
		(width 0.254)
		(layer "F.Cu")
		(net "P5V_STBY")
	)
	(segment
		(start 31.02991 -89.351866)
		(end 30.228286 -89.351866)
		(width 0.254)
		(layer "F.Cu")
		(net "P5V_STBY")
	)
	(segment
		(start 467.9315 -24.0284)
		(end 467.9315 -24.671274)
		(width 0.2032)
		(layer "F.Cu")
		(net "P5V_STBY")
	)
	(segment
		(start 1.569974 -17.1704)
		(end 1.567942 -17.1704)
		(width 0.254)
		(layer "F.Cu")
		(net "P5V_STBY")
	)
	(segment
		(start 429.04537 -19.809714)
		(end 429.04537 -19.95043)
		(width 0.254)
		(layer "F.Cu")
		(net "P5V_STBY")
	)
	(segment
		(start 198.00443 -69.318124)
		(end 198.00443 -70.005448)
		(width 0.508)
		(layer "F.Cu")
		(net "P5V_STBY")
	)
	(segment
		(start 348.391988 -148.370036)
		(end 348.2594 -148.502624)
		(width 0.254)
		(layer "F.Cu")
		(net "P5V_STBY")
	)
	(segment
		(start 348.2086 -148.553424)
		(end 348.2594 -148.502624)
		(width 0.508)
		(layer "F.Cu")
		(net "P5V_STBY")
	)
	(segment
		(start 347.113606 -2.127504)
		(end 347.113606 -1.517904)
		(width 0.254)
		(layer "F.Cu")
		(net "P5V_STBY")
	)
	(segment
		(start 32.995108 -53.96357)
		(end 33.102296 -53.856382)
		(width 0.254)
		(layer "F.Cu")
		(net "P5V_STBY")
	)
	(segment
		(start 32.9438 -86.072726)
		(end 33.278826 -85.7377)
		(width 0.508)
		(layer "F.Cu")
		(net "P5V_STBY")
	)
	(segment
		(start 354.03536 -97.4598)
		(end 354.16998 -97.59442)
		(width 0.508)
		(layer "F.Cu")
		(net "P5V_STBY")
	)
	(segment
		(start 4.2164 -6.234176)
		(end 4.1656 -6.284976)
		(width 0.508)
		(layer "F.Cu")
		(net "P5V_STBY")
	)
	(segment
		(start 448.323462 -18.208498)
		(end 446.32626 -18.208498)
		(width 0.254)
		(layer "F.Cu")
		(net "P5V_STBY")
	)
	(segment
		(start 9.30529 -123.283472)
		(end 10.4648 -123.283472)
		(width 0.508)
		(layer "F.Cu")
		(net "P5V_STBY")
	)
	(segment
		(start 376.16765 -156.24302)
		(end 376.16765 -157.5054)
		(width 0.254)
		(layer "F.Cu")
		(net "P5V_STBY")
	)
	(segment
		(start 196.017642 -97.479866)
		(end 195.330064 -97.479866)
		(width 0.254)
		(layer "F.Cu")
		(net "P5V_STBY")
	)
	(segment
		(start 350.104456 1.27)
		(end 349.832676 1.54178)
		(width 0.254)
		(layer "F.Cu")
		(net "P5V_STBY")
	)
	(segment
		(start 347.1926 -10.2108)
		(end 347.1926 -9.652)
		(width 0.508)
		(layer "F.Cu")
		(net "P5V_STBY")
	)
	(segment
		(start 198.11619 -61.118242)
		(end 198.11619 -61.97092)
		(width 0.254)
		(layer "F.Cu")
		(net "P5V_STBY")
	)
	(segment
		(start 194.94754 -72.82942)
		(end 194.89674 -72.77862)
		(width 0.254)
		(layer "F.Cu")
		(net "P5V_STBY")
	)
	(segment
		(start 393.916408 -62.726062)
		(end 393.916408 -62.662308)
		(width 0.254)
		(layer "F.Cu")
		(net "P5V_STBY")
	)
	(segment
		(start 198.090028 -94.745556)
		(end 198.090028 -94.496382)
		(width 0.254)
		(layer "F.Cu")
		(net "P5V_STBY")
	)
	(segment
		(start 194.95262 -72.82942)
		(end 194.94754 -72.82942)
		(width 0.254)
		(layer "F.Cu")
		(net "P5V_STBY")
	)
	(segment
		(start 29.933392 -81.056988)
		(end 29.585666 -81.056988)
		(width 0.254)
		(layer "F.Cu")
		(net "P5V_STBY")
	)
	(segment
		(start 448.62496 -17.907)
		(end 448.323462 -18.208498)
		(width 0.254)
		(layer "F.Cu")
		(net "P5V_STBY")
	)
	(segment
		(start 197.99554 -78.31074)
		(end 197.8914 -78.2066)
		(width 0.254)
		(layer "F.Cu")
		(net "P5V_STBY")
	)
	(segment
		(start 446.32626 -18.208498)
		(end 445.3382 -19.196558)
		(width 0.254)
		(layer "F.Cu")
		(net "P5V_STBY")
	)
	(segment
		(start 30.228286 -73.095866)
		(end 30.061408 -72.928988)
		(width 0.254)
		(layer "F.Cu")
		(net "P5V_STBY")
	)
	(segment
		(start 435.49062 -131.3053)
		(end 435.49062 -132.0546)
		(width 0.254)
		(layer "F.Cu")
		(net "P5V_STBY")
	)
	(segment
		(start 29.585666 -89.184988)
		(end 29.464 -89.063322)
		(width 0.254)
		(layer "F.Cu")
		(net "P5V_STBY")
	)
	(segment
		(start -0.497586 -147.128484)
		(end -1.918716 -147.128484)
		(width 0.254)
		(layer "F.Cu")
		(net "P5V_STBY")
	)
	(segment
		(start 10.655808 -123.092464)
		(end 12.498832 -123.092464)
		(width 0.508)
		(layer "F.Cu")
		(net "P5V_STBY")
	)
	(segment
		(start 32.995108 -78.34757)
		(end 33.102296 -78.240382)
		(width 0.254)
		(layer "F.Cu")
		(net "P5V_STBY")
	)
	(segment
		(start 29.554678 -64.77)
		(end 29.464 -64.679322)
		(width 0.254)
		(layer "F.Cu")
		(net "P5V_STBY")
	)
	(segment
		(start 373.085614 -154.4955)
		(end 372.491 -154.4955)
		(width 0.254)
		(layer "F.Cu")
		(net "P5V_STBY")
	)
	(segment
		(start 31.02991 -97.479866)
		(end 30.228286 -97.479866)
		(width 0.254)
		(layer "F.Cu")
		(net "P5V_STBY")
	)
	(segment
		(start 198.178928 -86.292182)
		(end 198.102728 -86.368382)
		(width 0.508)
		(layer "F.Cu")
		(net "P5V_STBY")
	)
	(segment
		(start 4.29895 -14.201394)
		(end 4.22275 -14.277594)
		(width 0.508)
		(layer "F.Cu")
		(net "P5V_STBY")
	)
	(segment
		(start 32.995108 -94.683072)
		(end 33.16859 -94.50959)
		(width 0.254)
		(layer "F.Cu")
		(net "P5V_STBY")
	)
	(segment
		(start 33.127696 -69.4182)
		(end 33.127696 -70.086982)
		(width 0.254)
		(layer "F.Cu")
		(net "P5V_STBY")
	)
	(segment
		(start 197.98284 -94.852744)
		(end 198.090028 -94.745556)
		(width 0.254)
		(layer "F.Cu")
		(net "P5V_STBY")
	)
	(segment
		(start 350.357186 -145.49374)
		(end 351.388934 -145.49374)
		(width 0.254)
		(layer "F.Cu")
		(net "P5V_STBY")
	)
	(segment
		(start 1.7018 -134.3152)
		(end 1.7018 -134.8232)
		(width 0.254)
		(layer "F.Cu")
		(net "P5V_STBY")
	)
	(segment
		(start 351.203768 -97.915476)
		(end 352.607626 -97.915476)
		(width 0.508)
		(layer "F.Cu")
		(net "P5V_STBY")
	)
	(segment
		(start 33.240726 -94.086934)
		(end 33.16859 -94.15907)
		(width 0.508)
		(layer "F.Cu")
		(net "P5V_STBY")
	)
	(segment
		(start 24.1554 -41.2242)
		(end 24.71928 -41.2242)
		(width 0.508)
		(layer "F.Cu")
		(net "P5V_STBY")
	)
	(segment
		(start 347.375988 -8.787638)
		(end 347.375988 -9.468612)
		(width 0.254)
		(layer "F.Cu")
		(net "P5V_STBY")
	)
	(segment
		(start -0.497586 -137.984484)
		(end -1.105154 -137.984484)
		(width 0.254)
		(layer "F.Cu")
		(net "P5V_STBY")
	)
	(segment
		(start 2.067814 -9.29386)
		(end 1.01346 -9.29386)
		(width 0.254)
		(layer "F.Cu")
		(net "P5V_STBY")
	)
	(segment
		(start 400.543522 -64.509142)
		(end 399.492978 -64.509142)
		(width 0.254)
		(layer "F.Cu")
		(net "P5V_STBY")
	)
	(segment
		(start 197.99554 -79.028544)
		(end 197.99554 -78.31074)
		(width 0.254)
		(layer "F.Cu")
		(net "P5V_STBY")
	)
	(segment
		(start 10.4648 -123.283472)
		(end 10.655808 -123.092464)
		(width 0.508)
		(layer "F.Cu")
		(net "P5V_STBY")
	)
	(segment
		(start 197.9676 -70.233286)
		(end 197.9676 -70.1548)
		(width 0.254)
		(layer "F.Cu")
		(net "P5V_STBY")
	)
	(segment
		(start 21.29028 -122.29084)
		(end 21.29028 -121.43232)
		(width 0.4064)
		(layer "F.Cu")
		(net "P5V_STBY")
	)
	(segment
		(start 32.995108 -95.284544)
		(end 32.995108 -94.683072)
		(width 0.254)
		(layer "F.Cu")
		(net "P5V_STBY")
	)
	(segment
		(start 29.585666 -81.056988)
		(end 29.464 -80.935322)
		(width 0.254)
		(layer "F.Cu")
		(net "P5V_STBY")
	)
	(segment
		(start 30.03042 -64.77)
		(end 29.554678 -64.77)
		(width 0.254)
		(layer "F.Cu")
		(net "P5V_STBY")
	)
	(segment
		(start 4.115562 -15.065756)
		(end 4.115562 -14.384782)
		(width 0.254)
		(layer "F.Cu")
		(net "P5V_STBY")
	)
	(segment
		(start 347.296994 -0.653542)
		(end 347.296994 -1.334516)
		(width 0.254)
		(layer "F.Cu")
		(net "P5V_STBY")
	)
	(segment
		(start 13.409168 -124.0028)
		(end 19.57832 -124.0028)
		(width 0.508)
		(layer "F.Cu")
		(net "P5V_STBY")
	)
	(segment
		(start 31.02991 -73.095866)
		(end 30.228286 -73.095866)
		(width 0.254)
		(layer "F.Cu")
		(net "P5V_STBY")
	)
	(segment
		(start 347.1926 -9.652)
		(end 347.2434 -9.6012)
		(width 0.508)
		(layer "F.Cu")
		(net "P5V_STBY")
	)
	(segment
		(start 198.11619 -61.97092)
		(end 198.102728 -61.984382)
		(width 0.254)
		(layer "F.Cu")
		(net "P5V_STBY")
	)
	(segment
		(start 194.939158 -89.097866)
		(end 194.939158 -89.079832)
		(width 0.254)
		(layer "F.Cu")
		(net "P5V_STBY")
	)
	(segment
		(start 373.202454 -154.37866)
		(end 373.085614 -154.4955)
		(width 0.254)
		(layer "F.Cu")
		(net "P5V_STBY")
	)
	(segment
		(start 490.014006 -154.1907)
		(end 488.67314 -154.1907)
		(width 0.254)
		(layer "F.Cu")
		(net "P5V_STBY")
	)
	(segment
		(start 198.039228 -94.445582)
		(end 198.090028 -94.496382)
		(width 0.508)
		(layer "F.Cu")
		(net "P5V_STBY")
	)
	(segment
		(start 181.187344 -54.547516)
		(end 181.455314 -54.815486)
		(width 0.254)
		(layer "F.Cu")
		(net "P5V_STBY")
	)
	(segment
		(start 33.127696 -70.086982)
		(end 33.102296 -70.112382)
		(width 0.254)
		(layer "F.Cu")
		(net "P5V_STBY")
	)
	(segment
		(start -1.105154 -137.984484)
		(end -1.184148 -137.90549)
		(width 0.254)
		(layer "F.Cu")
		(net "P5V_STBY")
	)
	(segment
		(start 390.205976 -73.331324)
		(end 391.0838 -72.4535)
		(width 0.508)
		(layer "F.Cu")
		(net "P5V_STBY")
	)
	(segment
		(start 447.132456 -21.2217)
		(end 447.132456 -21.624544)
		(width 0.254)
		(layer "F.Cu")
		(net "P5V_STBY")
	)
	(segment
		(start 178.181 -57.6072)
		(end 178.181 -58.166)
		(width 0.508)
		(layer "F.Cu")
		(net "P5V_STBY")
	)
	(segment
		(start 391.0838 -72.427592)
		(end 391.414 -72.097392)
		(width 0.508)
		(layer "F.Cu")
		(net "P5V_STBY")
	)
	(segment
		(start 30.061408 -97.312988)
		(end 29.585666 -97.312988)
		(width 0.254)
		(layer "F.Cu")
		(net "P5V_STBY")
	)
	(segment
		(start 347.829378 -100.753672)
		(end 347.778578 -100.804472)
		(width 0.508)
		(layer "F.Cu")
		(net "P5V_STBY")
	)
	(segment
		(start 382.99898 -154.599894)
		(end 382.234694 -154.599894)
		(width 0.254)
		(layer "F.Cu")
		(net "P5V_STBY")
	)
	(segment
		(start 33.178496 -78.164182)
		(end 33.102296 -78.240382)
		(width 0.508)
		(layer "F.Cu")
		(net "P5V_STBY")
	)
	(segment
		(start 8.7122 -122.65406)
		(end 8.919972 -122.861832)
		(width 0.508)
		(layer "F.Cu")
		(net "P5V_STBY")
	)
	(segment
		(start 197.99554 -62.09157)
		(end 198.102728 -61.984382)
		(width 0.254)
		(layer "F.Cu")
		(net "P5V_STBY")
	)
	(segment
		(start 178.364388 -57.423812)
		(end 178.2318 -57.5564)
		(width 0.254)
		(layer "F.Cu")
		(net "P5V_STBY")
	)
	(segment
		(start 198.065644 -78.032356)
		(end 198.065644 -77.513942)
		(width 0.508)
		(layer "F.Cu")
		(net "P5V_STBY")
	)
	(segment
		(start 32.995108 -70.900544)
		(end 32.995108 -70.21957)
		(width 0.254)
		(layer "F.Cu")
		(net "P5V_STBY")
	)
	(segment
		(start 445.3382 -19.196558)
		(end 445.3382 -20.294346)
		(width 0.254)
		(layer "F.Cu")
		(net "P5V_STBY")
	)
	(segment
		(start 29.588968 -56.672988)
		(end 29.54274 -56.62676)
		(width 0.254)
		(layer "F.Cu")
		(net "P5V_STBY")
	)
	(segment
		(start 197.99554 -70.900544)
		(end 197.99554 -70.261226)
		(width 0.254)
		(layer "F.Cu")
		(net "P5V_STBY")
	)
	(segment
		(start 30.228286 -89.351866)
		(end 30.061408 -89.184988)
		(width 0.254)
		(layer "F.Cu")
		(net "P5V_STBY")
	)
	(segment
		(start 178.2318 -57.5564)
		(end 178.181 -57.6072)
		(width 0.508)
		(layer "F.Cu")
		(net "P5V_STBY")
	)
	(segment
		(start 197.98284 -95.284544)
		(end 197.98284 -94.852744)
		(width 0.254)
		(layer "F.Cu")
		(net "P5V_STBY")
	)
	(segment
		(start 427.355 -22.86)
		(end 427.355 -21.971)
		(width 0.254)
		(layer "F.Cu")
		(net "P5V_STBY")
	)
	(segment
		(start 399.051272 -64.4779)
		(end 398.808956 -64.720216)
		(width 0.254)
		(layer "F.Cu")
		(net "P5V_STBY")
	)
	(segment
		(start 32.995108 -79.028544)
		(end 32.995108 -78.34757)
		(width 0.254)
		(layer "F.Cu")
		(net "P5V_STBY")
	)
	(segment
		(start 381.718566 -154.559)
		(end 381.576072 -154.416506)
		(width 0.508)
		(layer "F.Cu")
		(net "P5V_STBY")
	)
	(segment
		(start 348.391988 -156.269436)
		(end 348.2594 -156.402024)
		(width 0.254)
		(layer "F.Cu")
		(net "P5V_STBY")
	)
	(segment
		(start 467.9315 -24.671274)
		(end 468.149178 -24.888952)
		(width 0.2032)
		(layer "F.Cu")
		(net "P5V_STBY")
	)
	(segment
		(start 429.04537 -19.95043)
		(end 428.0408 -20.955)
		(width 0.254)
		(layer "F.Cu")
		(net "P5V_STBY")
	)
	(segment
		(start 400.547332 -64.512952)
		(end 400.543522 -64.509142)
		(width 0.254)
		(layer "F.Cu")
		(net "P5V_STBY")
	)
	(segment
		(start 197.99554 -62.772544)
		(end 197.99554 -62.09157)
		(width 0.254)
		(layer "F.Cu")
		(net "P5V_STBY")
	)
	(segment
		(start 198.178928 -53.221382)
		(end 198.178928 -53.780182)
		(width 0.508)
		(layer "F.Cu")
		(net "P5V_STBY")
	)
	(segment
		(start 32.9438 -86.449408)
		(end 32.9438 -86.398608)
		(width 0.254)
		(layer "F.Cu")
		(net "P5V_STBY")
	)
	(segment
		(start 198.178928 -85.733382)
		(end 198.178928 -86.292182)
		(width 0.508)
		(layer "F.Cu")
		(net "P5V_STBY")
	)
	(segment
		(start 19.57832 -124.0028)
		(end 21.29028 -122.29084)
		(width 0.508)
		(layer "F.Cu")
		(net "P5V_STBY")
	)
	(segment
		(start 486.165398 -61.160406)
		(end 486.165398 -61.886084)
		(width 0.508)
		(layer "F.Cu")
		(net "P5V_STBY")
	)
	(segment
		(start 382.1938 -154.559)
		(end 381.718566 -154.559)
		(width 0.508)
		(layer "F.Cu")
		(net "P5V_STBY")
	)
	(segment
		(start 1.467612 -135.789162)
		(end 1.467612 -135.057388)
		(width 0.254)
		(layer "F.Cu")
		(net "P5V_STBY")
	)
	(segment
		(start 1.467612 -144.201388)
		(end 1.5748 -144.0942)
		(width 0.254)
		(layer "F.Cu")
		(net "P5V_STBY")
	)
	(segment
		(start 350.547432 -97.915476)
		(end 351.203768 -97.915476)
		(width 0.2032)
		(layer "F.Cu")
		(net "P5V_STBY")
	)
	(segment
		(start 350.522032 0.96647)
		(end 350.218502 1.27)
		(width 0.254)
		(layer "F.Cu")
		(net "P5V_STBY")
	)
	(segment
		(start 8.919972 -122.861832)
		(end 8.919972 -122.898154)
		(width 0.508)
		(layer "F.Cu")
		(net "P5V_STBY")
	)
	(segment
		(start 196.030342 -81.223866)
		(end 195.072254 -81.223866)
		(width 0.254)
		(layer "F.Cu")
		(net "P5V_STBY")
	)
	(segment
		(start 1.467612 -144.933162)
		(end 1.467612 -144.201388)
		(width 0.254)
		(layer "F.Cu")
		(net "P5V_STBY")
	)
	(segment
		(start 333.9084 -22.7584)
		(end 333.726536 -22.576536)
		(width 0.508)
		(layer "F.Cu")
		(net "P5V_STBY")
	)
	(segment
		(start 333.726536 -22.576536)
		(end 333.726536 -20.801584)
		(width 0.508)
		(layer "F.Cu")
		(net "P5V_STBY")
	)
	(segment
		(start 195.072254 -81.223866)
		(end 194.818 -80.969612)
		(width 0.254)
		(layer "F.Cu")
		(net "P5V_STBY")
	)
	(segment
		(start 196.030342 -89.351866)
		(end 195.193158 -89.351866)
		(width 0.254)
		(layer "F.Cu")
		(net "P5V_STBY")
	)
	(segment
		(start 197.99554 -86.47557)
		(end 198.102728 -86.368382)
		(width 0.254)
		(layer "F.Cu")
		(net "P5V_STBY")
	)
	(segment
		(start 391.414 -72.097392)
		(end 391.414 -71.9455)
		(width 0.508)
		(layer "F.Cu")
		(net "P5V_STBY")
	)
	(segment
		(start 350.357186 -153.41854)
		(end 351.23374 -153.41854)
		(width 0.254)
		(layer "F.Cu")
		(net "P5V_STBY")
	)
	(segment
		(start 1.651 -143.256)
		(end 1.651 -144.018)
		(width 0.508)
		(layer "F.Cu")
		(net "P5V_STBY")
	)
	(segment
		(start 348.2594 -156.7434)
		(end 348.4118 -156.8958)
		(width 0.254)
		(layer "F.Cu")
		(net "P5V_STBY")
	)
	(segment
		(start 30.10027 -81.223866)
		(end 29.933392 -81.056988)
		(width 0.254)
		(layer "F.Cu")
		(net "P5V_STBY")
	)
	(segment
		(start -1.930146 -137.90549)
		(end -2.112772 -137.722864)
		(width 0.254)
		(layer "F.Cu")
		(net "P5V_STBY")
	)
	(segment
		(start 352.607626 -97.915476)
		(end 353.063302 -97.4598)
		(width 0.508)
		(layer "F.Cu")
		(net "P5V_STBY")
	)
	(segment
		(start 196.030342 -73.095866)
		(end 195.219066 -73.095866)
		(width 0.254)
		(layer "F.Cu")
		(net "P5V_STBY")
	)
	(segment
		(start 350.3168 -6.846316)
		(end 350.3168 -6.858)
		(width 0.254)
		(layer "F.Cu")
		(net "P5V_STBY")
	)
	(segment
		(start 380.6952 3.219704)
		(end 380.6952 -0.4318)
		(width 0.254)
		(layer "F.Cu")
		(net "P5V_STBY")
	)
	(segment
		(start 33.229296 -61.857382)
		(end 33.102296 -61.984382)
		(width 0.508)
		(layer "F.Cu")
		(net "P5V_STBY")
	)
	(segment
		(start 349.832676 1.54178)
		(end 349.262192 1.54178)
		(width 0.254)
		(layer "F.Cu")
		(net "P5V_STBY")
	)
	(segment
		(start 353.063302 -97.4598)
		(end 354.03536 -97.4598)
		(width 0.508)
		(layer "F.Cu")
		(net "P5V_STBY")
	)
	(via
		(at 393.5984 2.7432)
		(size 0.508)
		(drill 0.254)
		(layers "F.Cu" "B.Cu")
		(net "P5V_STBY")
	)
	(via
		(at 0.7874 -16.7386)
		(size 0.508)
		(drill 0.254)
		(layers "F.Cu" "B.Cu")
		(net "P5V_STBY")
	)
	(via
		(at 29.464 -80.935322)
		(size 0.508)
		(drill 0.254)
		(layers "F.Cu" "B.Cu")
		(net "P5V_STBY")
	)
	(via
		(at 435.49062 -132.0546)
		(size 0.508)
		(drill 0.254)
		(layers "F.Cu" "B.Cu")
		(net "P5V_STBY")
	)
	(via
		(at 432.275996 -127.45593)
		(size 0.5588)
		(drill 0.3048)
		(layers "F.Cu" "B.Cu")
		(net "P5V_STBY")
	)
	(via
		(at 467.487 -123.7615)
		(size 0.508)
		(drill 0.254)
		(layers "F.Cu" "B.Cu")
		(net "P5V_STBY")
	)
	(via
		(at 348.2594 -148.502624)
		(size 0.508)
		(drill 0.254)
		(layers "F.Cu" "B.Cu")
		(net "P5V_STBY")
	)
	(via
		(at 198.102728 -61.984382)
		(size 0.508)
		(drill 0.254)
		(layers "F.Cu" "B.Cu")
		(net "P5V_STBY")
	)
	(via
		(at 488.4166 -153.5303)
		(size 0.508)
		(drill 0.254)
		(layers "F.Cu" "B.Cu")
		(net "P5V_STBY")
	)
	(via
		(at 347.164406 -1.467104)
		(size 0.508)
		(drill 0.254)
		(layers "F.Cu" "B.Cu")
		(net "P5V_STBY")
	)
	(via
		(at 382.1938 -154.559)
		(size 0.508)
		(drill 0.254)
		(layers "F.Cu" "B.Cu")
		(net "P5V_STBY")
	)
	(via
		(at 29.8704 -49.22647)
		(size 0.508)
		(drill 0.254)
		(layers "F.Cu" "B.Cu")
		(net "P5V_STBY")
	)
	(via
		(at 476.784162 -15.440914)
		(size 0.508)
		(drill 0.254)
		(layers "F.Cu" "B.Cu")
		(net "P5V_STBY")
	)
	(via
		(at 432.30927 -126.787402)
		(size 0.5588)
		(drill 0.3048)
		(layers "F.Cu" "B.Cu")
		(net "P5V_STBY")
	)
	(via
		(at 195.6562 -52.05222)
		(size 0.508)
		(drill 0.254)
		(layers "F.Cu" "B.Cu")
		(net "P5V_STBY")
	)
	(via
		(at 4.1656 -6.284976)
		(size 0.508)
		(drill 0.254)
		(layers "F.Cu" "B.Cu")
		(net "P5V_STBY")
	)
	(via
		(at 347.2434 -9.6012)
		(size 0.508)
		(drill 0.254)
		(layers "F.Cu" "B.Cu")
		(net "P5V_STBY")
	)
	(via
		(at 485.171242 -55.206646)
		(size 0.508)
		(drill 0.254)
		(layers "F.Cu" "B.Cu")
		(net "P5V_STBY")
	)
	(via
		(at 33.102296 -78.240382)
		(size 0.508)
		(drill 0.254)
		(layers "F.Cu" "B.Cu")
		(net "P5V_STBY")
	)
	(via
		(at 198.102728 -86.368382)
		(size 0.508)
		(drill 0.254)
		(layers "F.Cu" "B.Cu")
		(net "P5V_STBY")
	)
	(via
		(at 348.2594 -156.402024)
		(size 0.508)
		(drill 0.254)
		(layers "F.Cu" "B.Cu")
		(net "P5V_STBY")
	)
	(via
		(at 487.995976 -135.5725)
		(size 0.508)
		(drill 0.254)
		(layers "F.Cu" "B.Cu")
		(net "P5V_STBY")
	)
	(via
		(at 402.101812 -66.070988)
		(size 0.5588)
		(drill 0.3048)
		(layers "F.Cu" "B.Cu")
		(net "P5V_STBY")
	)
	(via
		(at 351.870264 -145.97507)
		(size 0.508)
		(drill 0.254)
		(layers "F.Cu" "B.Cu")
		(net "P5V_STBY")
	)
	(via
		(at 369.33378 -41.49344)
		(size 0.508)
		(drill 0.254)
		(layers "F.Cu" "B.Cu")
		(net "P5V_STBY")
	)
	(via
		(at 355.756464 -3.50393)
		(size 0.508)
		(drill 0.254)
		(layers "F.Cu" "B.Cu")
		(net "P5V_STBY")
	)
	(via
		(at 33.16859 -94.50959)
		(size 0.508)
		(drill 0.254)
		(layers "F.Cu" "B.Cu")
		(net "P5V_STBY")
	)
	(via
		(at 29.54274 -56.62676)
		(size 0.508)
		(drill 0.254)
		(layers "F.Cu" "B.Cu")
		(net "P5V_STBY")
	)
	(via
		(at 485.393746 -118.618)
		(size 0.5588)
		(drill 0.3048)
		(layers "F.Cu" "B.Cu")
		(net "P5V_STBY")
	)
	(via
		(at 485.267 -120.65)
		(size 0.508)
		(drill 0.254)
		(layers "F.Cu" "B.Cu")
		(net "P5V_STBY")
	)
	(via
		(at 194.939158 -89.079832)
		(size 0.508)
		(drill 0.254)
		(layers "F.Cu" "B.Cu")
		(net "P5V_STBY")
	)
	(via
		(at 486.199942 -118.618)
		(size 0.5588)
		(drill 0.3048)
		(layers "F.Cu" "B.Cu")
		(net "P5V_STBY")
	)
	(via
		(at 354.16998 -97.59442)
		(size 0.508)
		(drill 0.254)
		(layers "F.Cu" "B.Cu")
		(net "P5V_STBY")
	)
	(via
		(at 485.267 -119.888)
		(size 0.508)
		(drill 0.254)
		(layers "F.Cu" "B.Cu")
		(net "P5V_STBY")
	)
	(via
		(at 369.48364 -42.2148)
		(size 0.508)
		(drill 0.254)
		(layers "F.Cu" "B.Cu")
		(net "P5V_STBY")
	)
	(via
		(at 336.58175 -25.400254)
		(size 0.508)
		(drill 0.254)
		(layers "F.Cu" "B.Cu")
		(net "P5V_STBY")
	)
	(via
		(at 373.202454 -154.37866)
		(size 0.508)
		(drill 0.254)
		(layers "F.Cu" "B.Cu")
		(net "P5V_STBY")
	)
	(via
		(at 194.699128 -64.681608)
		(size 0.508)
		(drill 0.254)
		(layers "F.Cu" "B.Cu")
		(net "P5V_STBY")
	)
	(via
		(at 448.62496 -17.907)
		(size 0.508)
		(drill 0.254)
		(layers "F.Cu" "B.Cu")
		(net "P5V_STBY")
	)
	(via
		(at 29.464 -97.191322)
		(size 0.508)
		(drill 0.254)
		(layers "F.Cu" "B.Cu")
		(net "P5V_STBY")
	)
	(via
		(at 497.162836 -51.122326)
		(size 0.508)
		(drill 0.254)
		(layers "F.Cu" "B.Cu")
		(net "P5V_STBY")
	)
	(via
		(at 432.967384 -126.714504)
		(size 0.5588)
		(drill 0.3048)
		(layers "F.Cu" "B.Cu")
		(net "P5V_STBY")
	)
	(via
		(at 402.945346 -65.303146)
		(size 0.5588)
		(drill 0.3048)
		(layers "F.Cu" "B.Cu")
		(net "P5V_STBY")
	)
	(via
		(at 345.4654 -116.205)
		(size 0.508)
		(drill 0.254)
		(layers "F.Cu" "B.Cu")
		(net "P5V_STBY")
	)
	(via
		(at 29.464 -64.679322)
		(size 0.508)
		(drill 0.254)
		(layers "F.Cu" "B.Cu")
		(net "P5V_STBY")
	)
	(via
		(at 486.165398 -61.886084)
		(size 0.5588)
		(drill 0.3048)
		(layers "F.Cu" "B.Cu")
		(net "P5V_STBY")
	)
	(via
		(at 32.9438 -86.398608)
		(size 0.508)
		(drill 0.254)
		(layers "F.Cu" "B.Cu")
		(net "P5V_STBY")
	)
	(via
		(at 345.4654 -114.935)
		(size 0.508)
		(drill 0.254)
		(layers "F.Cu" "B.Cu")
		(net "P5V_STBY")
	)
	(via
		(at 179.707794 -122.793506)
		(size 0.508)
		(drill 0.254)
		(layers "F.Cu" "B.Cu")
		(net "P5V_STBY")
	)
	(via
		(at 389.188198 -62.941454)
		(size 0.508)
		(drill 0.254)
		(layers "F.Cu" "B.Cu")
		(net "P5V_STBY")
	)
	(via
		(at 197.9676 -70.1548)
		(size 0.508)
		(drill 0.254)
		(layers "F.Cu" "B.Cu")
		(net "P5V_STBY")
	)
	(via
		(at 385.1656 -157.4292)
		(size 0.508)
		(drill 0.254)
		(layers "F.Cu" "B.Cu")
		(net "P5V_STBY")
	)
	(via
		(at 389.594852 -73.331324)
		(size 0.508)
		(drill 0.254)
		(layers "F.Cu" "B.Cu")
		(net "P5V_STBY")
	)
	(via
		(at 178.2318 -57.5564)
		(size 0.508)
		(drill 0.254)
		(layers "F.Cu" "B.Cu")
		(net "P5V_STBY")
	)
	(via
		(at 446.614296 -59.094878)
		(size 0.5588)
		(drill 0.3048)
		(layers "F.Cu" "B.Cu")
		(net "P5V_STBY")
	)
	(via
		(at 334.5942 -22.7584)
		(size 0.508)
		(drill 0.254)
		(layers "F.Cu" "B.Cu")
		(net "P5V_STBY")
	)
	(via
		(at 194.727322 -97.211896)
		(size 0.508)
		(drill 0.254)
		(layers "F.Cu" "B.Cu")
		(net "P5V_STBY")
	)
	(via
		(at 345.4654 -113.665)
		(size 0.508)
		(drill 0.254)
		(layers "F.Cu" "B.Cu")
		(net "P5V_STBY")
	)
	(via
		(at 8.7122 -122.65406)
		(size 0.508)
		(drill 0.254)
		(layers "F.Cu" "B.Cu")
		(net "P5V_STBY")
	)
	(via
		(at 4.22275 -14.277594)
		(size 0.508)
		(drill 0.254)
		(layers "F.Cu" "B.Cu")
		(net "P5V_STBY")
	)
	(via
		(at 195.337176 -48.602392)
		(size 0.508)
		(drill 0.254)
		(layers "F.Cu" "B.Cu")
		(net "P5V_STBY")
	)
	(via
		(at 380.6952 3.219704)
		(size 0.508)
		(drill 0.254)
		(layers "F.Cu" "B.Cu")
		(net "P5V_STBY")
	)
	(via
		(at 25.2095 -40.73398)
		(size 0.508)
		(drill 0.254)
		(layers "F.Cu" "B.Cu")
		(net "P5V_STBY")
	)
	(via
		(at 474.5228 -150.098506)
		(size 0.508)
		(drill 0.254)
		(layers "F.Cu" "B.Cu")
		(net "P5V_STBY")
	)
	(via
		(at 492.5822 -51.8922)
		(size 0.508)
		(drill 0.254)
		(layers "F.Cu" "B.Cu")
		(net "P5V_STBY")
	)
	(via
		(at 29.464 -89.063322)
		(size 0.508)
		(drill 0.254)
		(layers "F.Cu" "B.Cu")
		(net "P5V_STBY")
	)
	(via
		(at 468.149178 -24.888952)
		(size 0.508)
		(drill 0.254)
		(layers "F.Cu" "B.Cu")
		(net "P5V_STBY")
	)
	(via
		(at 403.605746 -65.304416)
		(size 0.5588)
		(drill 0.3048)
		(layers "F.Cu" "B.Cu")
		(net "P5V_STBY")
	)
	(via
		(at 194.818 -80.899)
		(size 0.508)
		(drill 0.254)
		(layers "F.Cu" "B.Cu")
		(net "P5V_STBY")
	)
	(via
		(at 467.487 -123.1011)
		(size 0.508)
		(drill 0.254)
		(layers "F.Cu" "B.Cu")
		(net "P5V_STBY")
	)
	(via
		(at 376.16765 -157.5054)
		(size 0.508)
		(drill 0.254)
		(layers "F.Cu" "B.Cu")
		(net "P5V_STBY")
	)
	(via
		(at 194.724528 -56.537606)
		(size 0.508)
		(drill 0.254)
		(layers "F.Cu" "B.Cu")
		(net "P5V_STBY")
	)
	(via
		(at 181.455314 -54.815486)
		(size 0.508)
		(drill 0.254)
		(layers "F.Cu" "B.Cu")
		(net "P5V_STBY")
	)
	(via
		(at 447.132456 -21.624544)
		(size 0.508)
		(drill 0.254)
		(layers "F.Cu" "B.Cu")
		(net "P5V_STBY")
	)
	(via
		(at 404.265892 -65.285112)
		(size 0.5588)
		(drill 0.3048)
		(layers "F.Cu" "B.Cu")
		(net "P5V_STBY")
	)
	(via
		(at 197.8914 -78.2066)
		(size 0.508)
		(drill 0.254)
		(layers "F.Cu" "B.Cu")
		(net "P5V_STBY")
	)
	(via
		(at 350.522032 0.96647)
		(size 0.508)
		(drill 0.254)
		(layers "F.Cu" "B.Cu")
		(net "P5V_STBY")
	)
	(via
		(at 497.6876 -152.6794)
		(size 0.508)
		(drill 0.254)
		(layers "F.Cu" "B.Cu")
		(net "P5V_STBY")
	)
	(via
		(at 198.102728 -53.856382)
		(size 0.508)
		(drill 0.254)
		(layers "F.Cu" "B.Cu")
		(net "P5V_STBY")
	)
	(via
		(at 198.090028 -94.496382)
		(size 0.508)
		(drill 0.254)
		(layers "F.Cu" "B.Cu")
		(net "P5V_STBY")
	)
	(via
		(at 351.724976 -153.845006)
		(size 0.508)
		(drill 0.254)
		(layers "F.Cu" "B.Cu")
		(net "P5V_STBY")
	)
	(via
		(at 404.273512 -66.020696)
		(size 0.5588)
		(drill 0.3048)
		(layers "F.Cu" "B.Cu")
		(net "P5V_STBY")
	)
	(via
		(at 318.8208 -44.704)
		(size 0.508)
		(drill 0.254)
		(layers "F.Cu" "B.Cu")
		(net "P5V_STBY")
	)
	(via
		(at 393.530836 -6.059424)
		(size 0.508)
		(drill 0.254)
		(layers "F.Cu" "B.Cu")
		(net "P5V_STBY")
	)
	(via
		(at 487.6546 -153.5557)
		(size 0.508)
		(drill 0.254)
		(layers "F.Cu" "B.Cu")
		(net "P5V_STBY")
	)
	(via
		(at 318.2112 -44.704)
		(size 0.508)
		(drill 0.254)
		(layers "F.Cu" "B.Cu")
		(net "P5V_STBY")
	)
	(via
		(at 486.993692 -118.617746)
		(size 0.5588)
		(drill 0.3048)
		(layers "F.Cu" "B.Cu")
		(net "P5V_STBY")
	)
	(via
		(at 33.102296 -70.112382)
		(size 0.508)
		(drill 0.254)
		(layers "F.Cu" "B.Cu")
		(net "P5V_STBY")
	)
	(via
		(at 194.89674 -72.77862)
		(size 0.508)
		(drill 0.254)
		(layers "F.Cu" "B.Cu")
		(net "P5V_STBY")
	)
	(via
		(at 180.374798 -122.830082)
		(size 0.508)
		(drill 0.254)
		(layers "F.Cu" "B.Cu")
		(net "P5V_STBY")
	)
	(via
		(at 33.102296 -53.856382)
		(size 0.508)
		(drill 0.254)
		(layers "F.Cu" "B.Cu")
		(net "P5V_STBY")
	)
	(via
		(at 33.102296 -61.984382)
		(size 0.508)
		(drill 0.254)
		(layers "F.Cu" "B.Cu")
		(net "P5V_STBY")
	)
	(via
		(at 434.490876 -132.0546)
		(size 0.508)
		(drill 0.254)
		(layers "F.Cu" "B.Cu")
		(net "P5V_STBY")
	)
	(via
		(at 347.829378 -100.753672)
		(size 0.508)
		(drill 0.254)
		(layers "F.Cu" "B.Cu")
		(net "P5V_STBY")
	)
	(via
		(at 432.954176 -127.413258)
		(size 0.5588)
		(drill 0.3048)
		(layers "F.Cu" "B.Cu")
		(net "P5V_STBY")
	)
	(via
		(at 403.61362 -65.990978)
		(size 0.5588)
		(drill 0.3048)
		(layers "F.Cu" "B.Cu")
		(net "P5V_STBY")
	)
	(via
		(at 429.04537 -19.809714)
		(size 0.508)
		(drill 0.254)
		(layers "F.Cu" "B.Cu")
		(net "P5V_STBY")
	)
	(via
		(at 494.411 -26.663396)
		(size 0.508)
		(drill 0.254)
		(layers "F.Cu" "B.Cu")
		(net "P5V_STBY")
	)
	(via
		(at 0.9144 -9.1948)
		(size 0.508)
		(drill 0.254)
		(layers "F.Cu" "B.Cu")
		(net "P5V_STBY")
	)
	(via
		(at -2.0828 -146.9644)
		(size 0.508)
		(drill 0.254)
		(layers "F.Cu" "B.Cu")
		(net "P5V_STBY")
	)
	(via
		(at 1.5748 -144.0942)
		(size 0.508)
		(drill 0.254)
		(layers "F.Cu" "B.Cu")
		(net "P5V_STBY")
	)
	(via
		(at 350.3168 -6.858)
		(size 0.508)
		(drill 0.254)
		(layers "F.Cu" "B.Cu")
		(net "P5V_STBY")
	)
	(via
		(at 1.5748 -134.9502)
		(size 0.508)
		(drill 0.254)
		(layers "F.Cu" "B.Cu")
		(net "P5V_STBY")
	)
	(via
		(at 402.093938 -65.321434)
		(size 0.5588)
		(drill 0.3048)
		(layers "F.Cu" "B.Cu")
		(net "P5V_STBY")
	)
	(via
		(at 402.95322 -65.995296)
		(size 0.5588)
		(drill 0.3048)
		(layers "F.Cu" "B.Cu")
		(net "P5V_STBY")
	)
	(via
		(at 29.464 -72.807322)
		(size 0.508)
		(drill 0.254)
		(layers "F.Cu" "B.Cu")
		(net "P5V_STBY")
	)
	(via
		(at -2.112772 -137.722864)
		(size 0.508)
		(drill 0.254)
		(layers "F.Cu" "B.Cu")
		(net "P5V_STBY")
	)
	(segment
		(start 4.388104 -14.442948)
		(end 4.22275 -14.277594)
		(width 0.254)
		(layer "B.Cu")
		(net "P5V_STBY")
	)
	(segment
		(start 347.829378 -100.042472)
		(end 347.829378 -100.753672)
		(width 0.4064)
		(layer "B.Cu")
		(net "P5V_STBY")
	)
	(segment
		(start 4.1656 -5.7531)
		(end 4.1656 -6.284976)
		(width 0.4064)
		(layer "B.Cu")
		(net "P5V_STBY")
	)
	(segment
		(start 3.93192 -5.51942)
		(end 4.1656 -5.7531)
		(width 0.4064)
		(layer "B.Cu")
		(net "P5V_STBY")
	)
	(segment
		(start 476.484696 -14.66215)
		(end 476.484696 -14.0589)
		(width 0.254)
		(layer "B.Cu")
		(net "P5V_STBY")
	)
	(segment
		(start 33.178496 -77.552042)
		(end 33.178496 -78.164182)
		(width 0.4064)
		(layer "B.Cu")
		(net "P5V_STBY")
	)
	(segment
		(start 399.4912 -18.362676)
		(end 399.4912 -16.2814)
		(width 0.254)
		(layer "B.Cu")
		(net "P5V_STBY")
	)
	(segment
		(start 3.93192 -5.41782)
		(end 3.93192 -5.51942)
		(width 0.4064)
		(layer "B.Cu")
		(net "P5V_STBY")
	)
	(segment
		(start 400.056604 -18.92808)
		(end 399.4912 -18.362676)
		(width 0.254)
		(layer "B.Cu")
		(net "P5V_STBY")
	)
	(segment
		(start 348.23654 -148.525484)
		(end 348.2594 -148.502624)
		(width 0.4064)
		(layer "B.Cu")
		(net "P5V_STBY")
	)
	(segment
		(start 382.1938 -153.79065)
		(end 382.1938 -154.559)
		(width 0.4064)
		(layer "B.Cu")
		(net "P5V_STBY")
	)
	(segment
		(start 33.178496 -86.292182)
		(end 33.07207 -86.398608)
		(width 0.4064)
		(layer "B.Cu")
		(net "P5V_STBY")
	)
	(segment
		(start 33.2232 -54.5084)
		(end 33.257998 -54.473602)
		(width 0.4064)
		(layer "B.Cu")
		(net "P5V_STBY")
	)
	(segment
		(start 198.102728 -86.368382)
		(end 198.316088 -86.155022)
		(width 0.4064)
		(layer "B.Cu")
		(net "P5V_STBY")
	)
	(segment
		(start 373.202454 -154.37866)
		(end 373.2911 -154.467306)
		(width 0.4064)
		(layer "B.Cu")
		(net "P5V_STBY")
	)
	(segment
		(start 197.8914 -78.08087)
		(end 197.8914 -78.2066)
		(width 0.4064)
		(layer "B.Cu")
		(net "P5V_STBY")
	)
	(segment
		(start 468.08263 -24.9555)
		(end 467.2203 -24.9555)
		(width 0.254)
		(layer "B.Cu")
		(net "P5V_STBY")
	)
	(segment
		(start 497.6876 -152.6794)
		(end 498.4496 -151.9174)
		(width 0.254)
		(layer "B.Cu")
		(net "P5V_STBY")
	)
	(segment
		(start 4.25958 -14.240764)
		(end 4.25958 -13.52296)
		(width 0.254)
		(layer "B.Cu")
		(net "P5V_STBY")
	)
	(segment
		(start 401.049744 -14.722856)
		(end 401.049744 -6.972554)
		(width 0.254)
		(layer "B.Cu")
		(net "P5V_STBY")
	)
	(segment
		(start 373.2911 -154.467306)
		(end 373.888 -154.467306)
		(width 0.4064)
		(layer "B.Cu")
		(net "P5V_STBY")
	)
	(segment
		(start 372.51894 -154.401266)
		(end 373.1514 -154.401266)
		(width 0.4064)
		(layer "B.Cu")
		(net "P5V_STBY")
	)
	(segment
		(start 33.147 -94.53118)
		(end 33.16859 -94.50959)
		(width 0.4064)
		(layer "B.Cu")
		(net "P5V_STBY")
	)
	(segment
		(start 400.056604 -20.104608)
		(end 400.056604 -18.92808)
		(width 0.254)
		(layer "B.Cu")
		(net "P5V_STBY")
	)
	(segment
		(start 8.7122 -122.65406)
		(end 8.67664 -122.6185)
		(width 0.254)
		(layer "B.Cu")
		(net "P5V_STBY")
	)
	(segment
		(start 382.176274 -153.773124)
		(end 382.1938 -153.79065)
		(width 0.4064)
		(layer "B.Cu")
		(net "P5V_STBY")
	)
	(segment
		(start 475.484952 -14.0589)
		(end 475.484952 -14.607794)
		(width 0.254)
		(layer "B.Cu")
		(net "P5V_STBY")
	)
	(segment
		(start 1.651 -144.1704)
		(end 1.5748 -144.0942)
		(width 0.4064)
		(layer "B.Cu")
		(net "P5V_STBY")
	)
	(segment
		(start 197.9676 -70.233286)
		(end 197.9676 -70.1548)
		(width 0.4064)
		(layer "B.Cu")
		(net "P5V_STBY")
	)
	(segment
		(start 445.25692 -20.58924)
		(end 446.2145 -20.58924)
		(width 0.254)
		(layer "B.Cu")
		(net "P5V_STBY")
	)
	(segment
		(start 348.2594 -147.791424)
		(end 348.2594 -148.502624)
		(width 0.4064)
		(layer "B.Cu")
		(net "P5V_STBY")
	)
	(segment
		(start 444.98768 -20.85848)
		(end 445.25692 -20.58924)
		(width 0.254)
		(layer "B.Cu")
		(net "P5V_STBY")
	)
	(segment
		(start 33.147 -62.029086)
		(end 33.147 -62.6364)
		(width 0.4064)
		(layer "B.Cu")
		(net "P5V_STBY")
	)
	(segment
		(start 399.4912 -16.2814)
		(end 401.049744 -14.722856)
		(width 0.254)
		(layer "B.Cu")
		(net "P5V_STBY")
	)
	(segment
		(start 8.344916 -123.135644)
		(end 8.7122 -122.76836)
		(width 0.254)
		(layer "B.Cu")
		(net "P5V_STBY")
	)
	(segment
		(start 8.645398 -121.936256)
		(end 8.653272 -121.94413)
		(width 0.254)
		(layer "B.Cu")
		(net "P5V_STBY")
	)
	(segment
		(start 33.178496 -85.733382)
		(end 33.178496 -86.292182)
		(width 0.4064)
		(layer "B.Cu")
		(net "P5V_STBY")
	)
	(segment
		(start 33.257998 -54.473602)
		(end 33.257998 -54.012084)
		(width 0.4064)
		(layer "B.Cu")
		(net "P5V_STBY")
	)
	(segment
		(start 198.128128 -78.542388)
		(end 198.128128 -78.915006)
		(width 0.4064)
		(layer "B.Cu")
		(net "P5V_STBY")
	)
	(segment
		(start 198.316088 -86.155022)
		(end 198.316088 -85.687662)
		(width 0.4064)
		(layer "B.Cu")
		(net "P5V_STBY")
	)
	(segment
		(start 382.973072 -154.543506)
		(end 383.019808 -154.543506)
		(width 0.4064)
		(layer "B.Cu")
		(net "P5V_STBY")
	)
	(segment
		(start 1.778 -135.763)
		(end 1.778 -135.1534)
		(width 0.4064)
		(layer "B.Cu")
		(net "P5V_STBY")
	)
	(segment
		(start 476.342456 -15.882366)
		(end 476.783908 -15.440914)
		(width 0.254)
		(layer "B.Cu")
		(net "P5V_STBY")
	)
	(segment
		(start 198.359268 -77.613002)
		(end 197.8914 -78.08087)
		(width 0.4064)
		(layer "B.Cu")
		(net "P5V_STBY")
	)
	(segment
		(start 198.115428 -95.171006)
		(end 198.115428 -94.521782)
		(width 0.4064)
		(layer "B.Cu")
		(net "P5V_STBY")
	)
	(segment
		(start 198.178928 -53.780182)
		(end 198.102728 -53.856382)
		(width 0.4064)
		(layer "B.Cu")
		(net "P5V_STBY")
	)
	(segment
		(start 33.132522 -86.398608)
		(end 33.1724 -86.438486)
		(width 0.4064)
		(layer "B.Cu")
		(net "P5V_STBY")
	)
	(segment
		(start 400.020282 -24.175212)
		(end 399.034 -23.18893)
		(width 0.254)
		(layer "B.Cu")
		(net "P5V_STBY")
	)
	(segment
		(start 347.483176 -156.402024)
		(end 348.2594 -156.402024)
		(width 0.4064)
		(layer "B.Cu")
		(net "P5V_STBY")
	)
	(segment
		(start 177.546 -57.531)
		(end 177.5714 -57.5564)
		(width 0.381)
		(layer "B.Cu")
		(net "P5V_STBY")
	)
	(segment
		(start 373.888 -154.467306)
		(end 373.9642 -154.543506)
		(width 0.4064)
		(layer "B.Cu")
		(net "P5V_STBY")
	)
	(segment
		(start 7.764272 -123.135644)
		(end 8.344916 -123.135644)
		(width 0.254)
		(layer "B.Cu")
		(net "P5V_STBY")
	)
	(segment
		(start 33.0962 -69.4182)
		(end 33.0962 -70.106286)
		(width 0.4064)
		(layer "B.Cu")
		(net "P5V_STBY")
	)
	(segment
		(start 401.049744 -6.972554)
		(end 399.63979 -5.5626)
		(width 0.254)
		(layer "B.Cu")
		(net "P5V_STBY")
	)
	(segment
		(start 1.778 -135.1534)
		(end 1.5748 -134.9502)
		(width 0.4064)
		(layer "B.Cu")
		(net "P5V_STBY")
	)
	(segment
		(start 198.171308 -53.127402)
		(end 198.178928 -53.135022)
		(width 0.4064)
		(layer "B.Cu")
		(net "P5V_STBY")
	)
	(segment
		(start 33.178496 -53.780182)
		(end 33.178496 -53.160422)
		(width 0.4064)
		(layer "B.Cu")
		(net "P5V_STBY")
	)
	(segment
		(start 197.9676 -70.042278)
		(end 198.178928 -69.83095)
		(width 0.4064)
		(layer "B.Cu")
		(net "P5V_STBY")
	)
	(segment
		(start 393.530836 -5.859018)
		(end 393.530836 -6.059424)
		(width 0.254)
		(layer "B.Cu")
		(net "P5V_STBY")
	)
	(segment
		(start 198.178928 -53.135022)
		(end 198.178928 -53.780182)
		(width 0.4064)
		(layer "B.Cu")
		(net "P5V_STBY")
	)
	(segment
		(start 475.484952 -14.607794)
		(end 475.187518 -14.905228)
		(width 0.254)
		(layer "B.Cu")
		(net "P5V_STBY")
	)
	(segment
		(start 2.17932 -134.38632)
		(end 1.74244 -134.8232)
		(width 0.4064)
		(layer "B.Cu")
		(net "P5V_STBY")
	)
	(segment
		(start 399.034 -21.127212)
		(end 400.056604 -20.104608)
		(width 0.254)
		(layer "B.Cu")
		(net "P5V_STBY")
	)
	(segment
		(start 4.22275 -14.277594)
		(end 4.25958 -14.240764)
		(width 0.254)
		(layer "B.Cu")
		(net "P5V_STBY")
	)
	(segment
		(start 33.244536 -94.433644)
		(end 33.244536 -93.818202)
		(width 0.4064)
		(layer "B.Cu")
		(net "P5V_STBY")
	)
	(segment
		(start 33.1724 -78.9432)
		(end 33.1724 -78.310486)
		(width 0.4064)
		(layer "B.Cu")
		(net "P5V_STBY")
	)
	(segment
		(start 347.240606 -0.679704)
		(end 347.164406 -0.755904)
		(width 0.4064)
		(layer "B.Cu")
		(net "P5V_STBY")
	)
	(segment
		(start 198.178928 -61.285882)
		(end 198.178928 -61.908182)
		(width 0.4064)
		(layer "B.Cu")
		(net "P5V_STBY")
	)
	(segment
		(start 393.827254 -5.5626)
		(end 393.530836 -5.859018)
		(width 0.254)
		(layer "B.Cu")
		(net "P5V_STBY")
	)
	(segment
		(start 347.905578 -99.966272)
		(end 347.829378 -100.042472)
		(width 0.4064)
		(layer "B.Cu")
		(net "P5V_STBY")
	)
	(segment
		(start 347.164406 -2.051304)
		(end 347.164406 -1.467104)
		(width 0.254)
		(layer "B.Cu")
		(net "P5V_STBY")
	)
	(segment
		(start 400.020282 -25.166066)
		(end 400.020282 -24.175212)
		(width 0.254)
		(layer "B.Cu")
		(net "P5V_STBY")
	)
	(segment
		(start 347.829378 -100.753672)
		(end 347.829378 -101.411532)
		(width 0.4064)
		(layer "B.Cu")
		(net "P5V_STBY")
	)
	(segment
		(start 198.166228 -93.841062)
		(end 198.166228 -94.420182)
		(width 0.4064)
		(layer "B.Cu")
		(net "P5V_STBY")
	)
	(segment
		(start 7.2898 -121.936256)
		(end 8.645398 -121.936256)
		(width 0.254)
		(layer "B.Cu")
		(net "P5V_STBY")
	)
	(segment
		(start 33.178496 -53.160422)
		(end 33.175956 -53.157882)
		(width 0.4064)
		(layer "B.Cu")
		(net "P5V_STBY")
	)
	(segment
		(start 198.128128 -70.787006)
		(end 198.128128 -70.393814)
		(width 0.4064)
		(layer "B.Cu")
		(net "P5V_STBY")
	)
	(segment
		(start 198.128128 -53.881782)
		(end 198.102728 -53.856382)
		(width 0.4064)
		(layer "B.Cu")
		(net "P5V_STBY")
	)
	(segment
		(start 476.783908 -15.44066)
		(end 476.783908 -14.961362)
		(width 0.254)
		(layer "B.Cu")
		(net "P5V_STBY")
	)
	(segment
		(start 475.187518 -15.517876)
		(end 475.399354 -15.517876)
		(width 0.254)
		(layer "B.Cu")
		(net "P5V_STBY")
	)
	(segment
		(start 382.957578 -154.559)
		(end 382.973072 -154.543506)
		(width 0.4064)
		(layer "B.Cu")
		(net "P5V_STBY")
	)
	(segment
		(start 198.128128 -86.393782)
		(end 198.128128 -87.043006)
		(width 0.4064)
		(layer "B.Cu")
		(net "P5V_STBY")
	)
	(segment
		(start 198.166228 -94.420182)
		(end 198.090028 -94.496382)
		(width 0.4064)
		(layer "B.Cu")
		(net "P5V_STBY")
	)
	(segment
		(start 198.178928 -69.83095)
		(end 198.178928 -69.477382)
		(width 0.4064)
		(layer "B.Cu")
		(net "P5V_STBY")
	)
	(segment
		(start 32.9438 -86.398608)
		(end 33.07207 -86.398608)
		(width 0.4064)
		(layer "B.Cu")
		(net "P5V_STBY")
	)
	(segment
		(start 1.74244 -134.8232)
		(end 1.7018 -134.8232)
		(width 0.4064)
		(layer "B.Cu")
		(net "P5V_STBY")
	)
	(segment
		(start 1.5748 -144.0942)
		(end 1.75006 -143.91894)
		(width 0.4064)
		(layer "B.Cu")
		(net "P5V_STBY")
	)
	(segment
		(start 7.2898 -122.936)
		(end 7.564628 -122.936)
		(width 0.254)
		(layer "B.Cu")
		(net "P5V_STBY")
	)
	(segment
		(start 348.3356 -147.715224)
		(end 348.2594 -147.791424)
		(width 0.4064)
		(layer "B.Cu")
		(net "P5V_STBY")
	)
	(segment
		(start 8.67664 -122.6185)
		(end 8.67664 -121.967498)
		(width 0.254)
		(layer "B.Cu")
		(net "P5V_STBY")
	)
	(segment
		(start 33.1724 -78.310486)
		(end 33.102296 -78.240382)
		(width 0.4064)
		(layer "B.Cu")
		(net "P5V_STBY")
	)
	(segment
		(start 347.16974 -9.67486)
		(end 347.2434 -9.6012)
		(width 0.508)
		(layer "B.Cu")
		(net "P5V_STBY")
	)
	(segment
		(start 178.308 -56.769)
		(end 178.308 -57.4802)
		(width 0.381)
		(layer "B.Cu")
		(net "P5V_STBY")
	)
	(segment
		(start 33.1978 -70.207886)
		(end 33.102296 -70.112382)
		(width 0.4064)
		(layer "B.Cu")
		(net "P5V_STBY")
	)
	(segment
		(start 33.0962 -70.106286)
		(end 33.102296 -70.112382)
		(width 0.4064)
		(layer "B.Cu")
		(net "P5V_STBY")
	)
	(segment
		(start 348.1324 -156.083)
		(end 348.1324 -155.7274)
		(width 0.4064)
		(layer "B.Cu")
		(net "P5V_STBY")
	)
	(segment
		(start 348.2594 -156.21)
		(end 348.1324 -156.083)
		(width 0.4064)
		(layer "B.Cu")
		(net "P5V_STBY")
	)
	(segment
		(start 399.737834 -25.448514)
		(end 400.020282 -25.166066)
		(width 0.254)
		(layer "B.Cu")
		(net "P5V_STBY")
	)
	(segment
		(start 487.9975 -153.2128)
		(end 487.6546 -153.5557)
		(width 0.254)
		(layer "B.Cu")
		(net "P5V_STBY")
	)
	(segment
		(start 475.763844 -15.882366)
		(end 476.342456 -15.882366)
		(width 0.254)
		(layer "B.Cu")
		(net "P5V_STBY")
	)
	(segment
		(start 198.128128 -62.659006)
		(end 198.128128 -62.009782)
		(width 0.4064)
		(layer "B.Cu")
		(net "P5V_STBY")
	)
	(segment
		(start 1.75006 -143.91894)
		(end 1.75006 -143.256)
		(width 0.4064)
		(layer "B.Cu")
		(net "P5V_STBY")
	)
	(segment
		(start 33.1978 -70.7898)
		(end 33.1978 -70.207886)
		(width 0.4064)
		(layer "B.Cu")
		(net "P5V_STBY")
	)
	(segment
		(start 33.178496 -78.164182)
		(end 33.102296 -78.240382)
		(width 0.4064)
		(layer "B.Cu")
		(net "P5V_STBY")
	)
	(segment
		(start 399.034 -23.18893)
		(end 399.034 -21.127212)
		(width 0.254)
		(layer "B.Cu")
		(net "P5V_STBY")
	)
	(segment
		(start 198.178928 -61.908182)
		(end 198.102728 -61.984382)
		(width 0.4064)
		(layer "B.Cu")
		(net "P5V_STBY")
	)
	(segment
		(start 347.3196 -156.5656)
		(end 347.483176 -156.402024)
		(width 0.4064)
		(layer "B.Cu")
		(net "P5V_STBY")
	)
	(segment
		(start 347.3196 -9.525)
		(end 347.2434 -9.6012)
		(width 0.254)
		(layer "B.Cu")
		(net "P5V_STBY")
	)
	(segment
		(start 476.783908 -14.961362)
		(end 476.484696 -14.66215)
		(width 0.254)
		(layer "B.Cu")
		(net "P5V_STBY")
	)
	(segment
		(start 33.16859 -94.50959)
		(end 33.244536 -94.433644)
		(width 0.4064)
		(layer "B.Cu")
		(net "P5V_STBY")
	)
	(segment
		(start 198.128128 -62.009782)
		(end 198.102728 -61.984382)
		(width 0.4064)
		(layer "B.Cu")
		(net "P5V_STBY")
	)
	(segment
		(start 8.7122 -122.76836)
		(end 8.7122 -122.65406)
		(width 0.254)
		(layer "B.Cu")
		(net "P5V_STBY")
	)
	(segment
		(start 498.4496 -151.9174)
		(end 498.6528 -151.9174)
		(width 0.254)
		(layer "B.Cu")
		(net "P5V_STBY")
	)
	(segment
		(start 447.132456 -21.149056)
		(end 446.57264 -20.58924)
		(width 0.254)
		(layer "B.Cu")
		(net "P5V_STBY")
	)
	(segment
		(start 197.8914 -78.30566)
		(end 198.128128 -78.542388)
		(width 0.4064)
		(layer "B.Cu")
		(net "P5V_STBY")
	)
	(segment
		(start 447.132456 -21.624544)
		(end 447.132456 -21.149056)
		(width 0.254)
		(layer "B.Cu")
		(net "P5V_STBY")
	)
	(segment
		(start 178.308 -57.4802)
		(end 178.2318 -57.5564)
		(width 0.381)
		(layer "B.Cu")
		(net "P5V_STBY")
	)
	(segment
		(start 197.9676 -70.1548)
		(end 197.9676 -70.042278)
		(width 0.4064)
		(layer "B.Cu")
		(net "P5V_STBY")
	)
	(segment
		(start 33.229296 -61.857382)
		(end 33.102296 -61.984382)
		(width 0.381)
		(layer "B.Cu")
		(net "P5V_STBY")
	)
	(segment
		(start 382.1938 -154.559)
		(end 382.957578 -154.559)
		(width 0.4064)
		(layer "B.Cu")
		(net "P5V_STBY")
	)
	(segment
		(start 198.102728 -86.368382)
		(end 198.128128 -86.393782)
		(width 0.4064)
		(layer "B.Cu")
		(net "P5V_STBY")
	)
	(segment
		(start 33.07207 -86.398608)
		(end 33.132522 -86.398608)
		(width 0.4064)
		(layer "B.Cu")
		(net "P5V_STBY")
	)
	(segment
		(start 198.128128 -54.531006)
		(end 198.128128 -53.881782)
		(width 0.4064)
		(layer "B.Cu")
		(net "P5V_STBY")
	)
	(segment
		(start 348.23654 -149.168104)
		(end 348.23654 -148.525484)
		(width 0.4064)
		(layer "B.Cu")
		(net "P5V_STBY")
	)
	(segment
		(start 347.266006 -2.152904)
		(end 347.164406 -2.051304)
		(width 0.254)
		(layer "B.Cu")
		(net "P5V_STBY")
	)
	(segment
		(start 4.21259 -6.237986)
		(end 4.1656 -6.284976)
		(width 0.508)
		(layer "B.Cu")
		(net "P5V_STBY")
	)
	(segment
		(start 4.388104 -15.15237)
		(end 4.388104 -14.442948)
		(width 0.254)
		(layer "B.Cu")
		(net "P5V_STBY")
	)
	(segment
		(start 348.2594 -156.402024)
		(end 348.2594 -156.21)
		(width 0.4064)
		(layer "B.Cu")
		(net "P5V_STBY")
	)
	(segment
		(start 5.17906 -6.237986)
		(end 4.21259 -6.237986)
		(width 0.508)
		(layer "B.Cu")
		(net "P5V_STBY")
	)
	(segment
		(start 177.5714 -57.5564)
		(end 178.2318 -57.5564)
		(width 0.381)
		(layer "B.Cu")
		(net "P5V_STBY")
	)
	(segment
		(start 33.1724 -86.438486)
		(end 33.1724 -87.0204)
		(width 0.4064)
		(layer "B.Cu")
		(net "P5V_STBY")
	)
	(segment
		(start 475.399354 -15.517876)
		(end 475.763844 -15.882366)
		(width 0.254)
		(layer "B.Cu")
		(net "P5V_STBY")
	)
	(segment
		(start 33.102296 -53.856382)
		(end 33.178496 -53.780182)
		(width 0.4064)
		(layer "B.Cu")
		(net "P5V_STBY")
	)
	(segment
		(start 446.57264 -20.58924)
		(end 446.2145 -20.58924)
		(width 0.254)
		(layer "B.Cu")
		(net "P5V_STBY")
	)
	(segment
		(start 347.164406 -0.755904)
		(end 347.164406 -1.467104)
		(width 0.4064)
		(layer "B.Cu")
		(net "P5V_STBY")
	)
	(segment
		(start 7.564628 -122.936)
		(end 7.764272 -123.135644)
		(width 0.254)
		(layer "B.Cu")
		(net "P5V_STBY")
	)
	(segment
		(start 475.187518 -14.905228)
		(end 475.187518 -15.517876)
		(width 0.254)
		(layer "B.Cu")
		(net "P5V_STBY")
	)
	(segment
		(start 33.229296 -61.298582)
		(end 33.229296 -61.857382)
		(width 0.381)
		(layer "B.Cu")
		(net "P5V_STBY")
	)
	(segment
		(start 476.783908 -15.440914)
		(end 476.784162 -15.440914)
		(width 0.254)
		(layer "B.Cu")
		(net "P5V_STBY")
	)
	(segment
		(start 476.784162 -15.440914)
		(end 476.783908 -15.44066)
		(width 0.254)
		(layer "B.Cu")
		(net "P5V_STBY")
	)
	(segment
		(start 347.3196 -8.8138)
		(end 347.3196 -9.525)
		(width 0.254)
		(layer "B.Cu")
		(net "P5V_STBY")
	)
	(segment
		(start 198.161148 -93.835982)
		(end 198.166228 -93.841062)
		(width 0.4064)
		(layer "B.Cu")
		(net "P5V_STBY")
	)
	(segment
		(start 373.1514 -154.401266)
		(end 373.153686 -154.39898)
		(width 0.4064)
		(layer "B.Cu")
		(net "P5V_STBY")
	)
	(segment
		(start 373.153686 -154.39898)
		(end 373.182134 -154.39898)
		(width 0.4064)
		(layer "B.Cu")
		(net "P5V_STBY")
	)
	(segment
		(start 487.9975 -152.5016)
		(end 487.9975 -153.2128)
		(width 0.254)
		(layer "B.Cu")
		(net "P5V_STBY")
	)
	(segment
		(start 489.189014 -152.757886)
		(end 488.4166 -153.5303)
		(width 0.254)
		(layer "B.Cu")
		(net "P5V_STBY")
	)
	(segment
		(start 347.829378 -101.411532)
		(end 347.791278 -101.449632)
		(width 0.4064)
		(layer "B.Cu")
		(net "P5V_STBY")
	)
	(segment
		(start 33.102296 -61.984382)
		(end 33.147 -62.029086)
		(width 0.4064)
		(layer "B.Cu")
		(net "P5V_STBY")
	)
	(segment
		(start 444.45174 -20.85848)
		(end 444.98768 -20.85848)
		(width 0.254)
		(layer "B.Cu")
		(net "P5V_STBY")
	)
	(segment
		(start 198.128128 -70.393814)
		(end 197.9676 -70.233286)
		(width 0.4064)
		(layer "B.Cu")
		(net "P5V_STBY")
	)
	(segment
		(start 489.189014 -152.146)
		(end 489.189014 -152.757886)
		(width 0.254)
		(layer "B.Cu")
		(net "P5V_STBY")
	)
	(segment
		(start 468.149178 -24.888952)
		(end 468.08263 -24.9555)
		(width 0.254)
		(layer "B.Cu")
		(net "P5V_STBY")
	)
	(segment
		(start 373.182134 -154.39898)
		(end 373.202454 -154.37866)
		(width 0.4064)
		(layer "B.Cu")
		(net "P5V_STBY")
	)
	(segment
		(start 475.44101 -150.098506)
		(end 474.5228 -150.098506)
		(width 0.254)
		(layer "B.Cu")
		(net "P5V_STBY")
	)
	(segment
		(start 475.51721 -150.174706)
		(end 475.44101 -150.098506)
		(width 0.254)
		(layer "B.Cu")
		(net "P5V_STBY")
	)
	(segment
		(start 198.115428 -94.521782)
		(end 198.090028 -94.496382)
		(width 0.4064)
		(layer "B.Cu")
		(net "P5V_STBY")
	)
	(segment
		(start 399.737834 -25.690068)
		(end 399.737834 -25.448514)
		(width 0.254)
		(layer "B.Cu")
		(net "P5V_STBY")
	)
	(segment
		(start 1.651 -144.8562)
		(end 1.651 -144.1704)
		(width 0.4064)
		(layer "B.Cu")
		(net "P5V_STBY")
	)
	(segment
		(start 33.147 -95.1484)
		(end 33.147 -94.53118)
		(width 0.4064)
		(layer "B.Cu")
		(net "P5V_STBY")
	)
	(segment
		(start 197.8914 -78.2066)
		(end 197.8914 -78.30566)
		(width 0.4064)
		(layer "B.Cu")
		(net "P5V_STBY")
	)
	(segment
		(start 1.7018 -134.8232)
		(end 1.5748 -134.9502)
		(width 0.4064)
		(layer "B.Cu")
		(net "P5V_STBY")
	)
	(segment
		(start 347.16974 -10.28446)
		(end 347.16974 -9.67486)
		(width 0.508)
		(layer "B.Cu")
		(net "P5V_STBY")
	)
	(segment
		(start 399.63979 -5.5626)
		(end 393.827254 -5.5626)
		(width 0.254)
		(layer "B.Cu")
		(net "P5V_STBY")
	)
	(segment
		(start 33.257998 -54.012084)
		(end 33.102296 -53.856382)
		(width 0.4064)
		(layer "B.Cu")
		(net "P5V_STBY")
	)
	(segment
		(start 8.67664 -121.967498)
		(end 8.653272 -121.94413)
		(width 0.254)
		(layer "B.Cu")
		(net "P5V_STBY")
	)
	(segment
		(start 476.784162 -15.440914)
		(end 476.783908 -15.440914)
		(width 0.254)
		(layer "In2.Cu")
		(net "P5V_STBY")
	)
	(segment
		(start 1.143 -9.6774)
		(end 0.9144 -9.4488)
		(width 0.4064)
		(layer "In2.Cu")
		(net "P5V_STBY")
	)
	(segment
		(start 0.7874 -16.7386)
		(end 1.2446 -16.7386)
		(width 0.4064)
		(layer "In2.Cu")
		(net "P5V_STBY")
	)
	(segment
		(start 466.188806 -22.92858)
		(end 463.86496 -22.92858)
		(width 0.254)
		(layer "In2.Cu")
		(net "P5V_STBY")
	)
	(segment
		(start 473.045028 -25.273762)
		(end 468.533988 -25.273762)
		(width 0.254)
		(layer "In2.Cu")
		(net "P5V_STBY")
	)
	(segment
		(start 0.9144 -9.0932)
		(end 2.6162 -7.3914)
		(width 0.4064)
		(layer "In2.Cu")
		(net "P5V_STBY")
	)
	(segment
		(start 433.103528 -18.519648)
		(end 432.432714 -19.190462)
		(width 0.254)
		(layer "In2.Cu")
		(net "P5V_STBY")
	)
	(segment
		(start 33.07207 -85.469984)
		(end 34.036 -84.506054)
		(width 0.508)
		(layer "In2.Cu")
		(net "P5V_STBY")
	)
	(segment
		(start 198.102728 -79.248)
		(end 196.5706 -79.248)
		(width 0.4064)
		(layer "In2.Cu")
		(net "P5V_STBY")
	)
	(segment
		(start 195.078604 -52.746148)
		(end 195.072 -52.752752)
		(width 0.4064)
		(layer "In2.Cu")
		(net "P5V_STBY")
	)
	(segment
		(start 468.533988 -25.273762)
		(end 468.149178 -24.888952)
		(width 0.254)
		(layer "In2.Cu")
		(net "P5V_STBY")
	)
	(segment
		(start 429.531018 -19.276314)
		(end 429.465486 -19.341846)
		(width 0.254)
		(layer "In2.Cu")
		(net "P5V_STBY")
	)
	(segment
		(start 33.9344 -69.280278)
		(end 33.9344 -62.816486)
		(width 0.508)
		(layer "In2.Cu")
		(net "P5V_STBY")
	)
	(segment
		(start 198.247 -85.522054)
		(end 198.247 -79.392272)
		(width 0.635)
		(layer "In2.Cu")
		(net "P5V_STBY")
	)
	(segment
		(start 349.9612 -99.179126)
		(end 349.9612 -98.52279)
		(width 0.508)
		(layer "In2.Cu")
		(net "P5V_STBY")
	)
	(segment
		(start 197.9676 -70.042278)
		(end 198.2724 -69.737478)
		(width 0.635)
		(layer "In2.Cu")
		(net "P5V_STBY")
	)
	(segment
		(start 476.783908 -15.440914)
		(end 476.1484 -16.076422)
		(width 0.254)
		(layer "In2.Cu")
		(net "P5V_STBY")
	)
	(segment
		(start 198.090028 -94.060518)
		(end 198.1962 -93.954346)
		(width 0.635)
		(layer "In2.Cu")
		(net "P5V_STBY")
	)
	(segment
		(start 476.1484 -16.076422)
		(end 476.1484 -22.17039)
		(width 0.254)
		(layer "In2.Cu")
		(net "P5V_STBY")
	)
	(segment
		(start 197.9676 -70.233286)
		(end 197.9676 -70.1548)
		(width 0.635)
		(layer "In2.Cu")
		(net "P5V_STBY")
	)
	(segment
		(start 196.6468 -62.992)
		(end 197.950328 -62.992)
		(width 0.4064)
		(layer "In2.Cu")
		(net "P5V_STBY")
	)
	(segment
		(start 33.102296 -70.112382)
		(end 33.9344 -69.280278)
		(width 0.508)
		(layer "In2.Cu")
		(net "P5V_STBY")
	)
	(segment
		(start 352.6282 -97.4344)
		(end 353.876102 -97.4344)
		(width 0.508)
		(layer "In2.Cu")
		(net "P5V_STBY")
	)
	(segment
		(start 198.1962 -93.954346)
		(end 198.1962 -87.520272)
		(width 0.635)
		(layer "In2.Cu")
		(net "P5V_STBY")
	)
	(segment
		(start 33.909 -70.919086)
		(end 33.102296 -70.112382)
		(width 0.508)
		(layer "In2.Cu")
		(net "P5V_STBY")
	)
	(segment
		(start 194.89674 -72.77862)
		(end 194.935856 -72.739504)
		(width 0.4064)
		(layer "In2.Cu")
		(net "P5V_STBY")
	)
	(segment
		(start 198.2216 -54.228746)
		(end 198.128128 -54.135274)
		(width 0.635)
		(layer "In2.Cu")
		(net "P5V_STBY")
	)
	(segment
		(start 194.9196 -80.899)
		(end 194.818 -80.899)
		(width 0.4064)
		(layer "In2.Cu")
		(net "P5V_STBY")
	)
	(segment
		(start 4.22275 -14.706346)
		(end 4.22275 -14.277594)
		(width 0.4064)
		(layer "In2.Cu")
		(net "P5V_STBY")
	)
	(segment
		(start 196.5706 -79.248)
		(end 194.9196 -80.899)
		(width 0.4064)
		(layer "In2.Cu")
		(net "P5V_STBY")
	)
	(segment
		(start 198.1962 -87.520272)
		(end 198.102728 -87.4268)
		(width 0.635)
		(layer "In2.Cu")
		(net "P5V_STBY")
	)
	(segment
		(start 349.4532 -99.687126)
		(end 349.9612 -99.179126)
		(width 0.508)
		(layer "In2.Cu")
		(net "P5V_STBY")
	)
	(segment
		(start 0.9144 -9.1948)
		(end 0.9144 -9.0932)
		(width 0.4064)
		(layer "In2.Cu")
		(net "P5V_STBY")
	)
	(segment
		(start 197.8914 -78.30566)
		(end 198.102728 -78.516988)
		(width 0.635)
		(layer "In2.Cu")
		(net "P5V_STBY")
	)
	(segment
		(start 195.078604 -52.629816)
		(end 195.078604 -52.746148)
		(width 0.4064)
		(layer "In2.Cu")
		(net "P5V_STBY")
	)
	(segment
		(start 0.889 -13.616432)
		(end 0.4826 -13.210032)
		(width 0.4064)
		(layer "In2.Cu")
		(net "P5V_STBY")
	)
	(segment
		(start 198.2724 -69.737478)
		(end 198.2724 -63.009272)
		(width 0.635)
		(layer "In2.Cu")
		(net "P5V_STBY")
	)
	(segment
		(start 194.727322 -97.211896)
		(end 196.638418 -95.3008)
		(width 0.4064)
		(layer "In2.Cu")
		(net "P5V_STBY")
	)
	(segment
		(start 198.2724 -77.68844)
		(end 198.2724 -70.538086)
		(width 0.635)
		(layer "In2.Cu")
		(net "P5V_STBY")
	)
	(segment
		(start 33.9344 -87.200486)
		(end 33.132522 -86.398608)
		(width 0.508)
		(layer "In2.Cu")
		(net "P5V_STBY")
	)
	(segment
		(start 0.4826 -11.332464)
		(end 1.143 -10.672064)
		(width 0.4064)
		(layer "In2.Cu")
		(net "P5V_STBY")
	)
	(segment
		(start 429.29937 -19.341846)
		(end 429.04537 -19.595846)
		(width 0.254)
		(layer "In2.Cu")
		(net "P5V_STBY")
	)
	(segment
		(start 448.62496 -17.907)
		(end 444.43142 -17.907)
		(width 0.254)
		(layer "In2.Cu")
		(net "P5V_STBY")
	)
	(segment
		(start 198.077328 -87.4014)
		(end 198.102728 -87.4268)
		(width 0.4064)
		(layer "In2.Cu")
		(net "P5V_STBY")
	)
	(segment
		(start 444.130938 -18.207482)
		(end 439.923682 -18.207482)
		(width 0.254)
		(layer "In2.Cu")
		(net "P5V_STBY")
	)
	(segment
		(start 197.611746 -95.3008)
		(end 198.090028 -94.822518)
		(width 0.4064)
		(layer "In2.Cu")
		(net "P5V_STBY")
	)
	(segment
		(start 33.782 -61.304678)
		(end 33.782 -54.536086)
		(width 0.508)
		(layer "In2.Cu")
		(net "P5V_STBY")
	)
	(segment
		(start 194.939158 -89.079832)
		(end 196.61759 -87.4014)
		(width 0.4064)
		(layer "In2.Cu")
		(net "P5V_STBY")
	)
	(segment
		(start 2.8702 -15.113)
		(end 3.816096 -15.113)
		(width 0.4064)
		(layer "In2.Cu")
		(net "P5V_STBY")
	)
	(segment
		(start 3.7338 -7.3914)
		(end 4.1656 -6.9596)
		(width 0.4064)
		(layer "In2.Cu")
		(net "P5V_STBY")
	)
	(segment
		(start 33.9344 -93.664278)
		(end 33.9344 -87.200486)
		(width 0.508)
		(layer "In2.Cu")
		(net "P5V_STBY")
	)
	(segment
		(start 195.078604 -56.18353)
		(end 194.724528 -56.537606)
		(width 0.4064)
		(layer "In2.Cu")
		(net "P5V_STBY")
	)
	(segment
		(start 431.865786 -19.276314)
		(end 429.531018 -19.276314)
		(width 0.254)
		(layer "In2.Cu")
		(net "P5V_STBY")
	)
	(segment
		(start 196.638418 -95.3008)
		(end 197.611746 -95.3008)
		(width 0.4064)
		(layer "In2.Cu")
		(net "P5V_STBY")
	)
	(segment
		(start 198.2724 -70.538086)
		(end 197.9676 -70.233286)
		(width 0.635)
		(layer "In2.Cu")
		(net "P5V_STBY")
	)
	(segment
		(start 196.9262 -71.1962)
		(end 197.9676 -70.1548)
		(width 0.4064)
		(layer "In2.Cu")
		(net "P5V_STBY")
	)
	(segment
		(start 350.45269 -98.0313)
		(end 352.0313 -98.0313)
		(width 0.508)
		(layer "In2.Cu")
		(net "P5V_STBY")
	)
	(segment
		(start 198.128128 -53.881782)
		(end 198.102728 -53.856382)
		(width 0.635)
		(layer "In2.Cu")
		(net "P5V_STBY")
	)
	(segment
		(start 33.16859 -94.430088)
		(end 33.9344 -93.664278)
		(width 0.508)
		(layer "In2.Cu")
		(net "P5V_STBY")
	)
	(segment
		(start 196.321934 -71.1962)
		(end 196.9262 -71.1962)
		(width 0.4064)
		(layer "In2.Cu")
		(net "P5V_STBY")
	)
	(segment
		(start 353.876102 -97.4344)
		(end 354.036122 -97.59442)
		(width 0.508)
		(layer "In2.Cu")
		(net "P5V_STBY")
	)
	(segment
		(start 0.4826 -13.210032)
		(end 0.4826 -11.332464)
		(width 0.4064)
		(layer "In2.Cu")
		(net "P5V_STBY")
	)
	(segment
		(start 347.829378 -100.753672)
		(end 347.658182 -100.582476)
		(width 0.508)
		(layer "In2.Cu")
		(net "P5V_STBY")
	)
	(segment
		(start 198.102728 -87.4268)
		(end 198.102728 -86.368382)
		(width 0.635)
		(layer "In2.Cu")
		(net "P5V_STBY")
	)
	(segment
		(start 33.132522 -86.398608)
		(end 33.07207 -86.398608)
		(width 0.508)
		(layer "In2.Cu")
		(net "P5V_STBY")
	)
	(segment
		(start 198.2216 -61.586618)
		(end 198.2216 -54.228746)
		(width 0.635)
		(layer "In2.Cu")
		(net "P5V_STBY")
	)
	(segment
		(start 0.9144 -9.4488)
		(end 0.9144 -9.1948)
		(width 0.4064)
		(layer "In2.Cu")
		(net "P5V_STBY")
	)
	(segment
		(start 1.143 -10.672064)
		(end 1.143 -9.6774)
		(width 0.4064)
		(layer "In2.Cu")
		(net "P5V_STBY")
	)
	(segment
		(start 196.61759 -87.4014)
		(end 198.077328 -87.4014)
		(width 0.4064)
		(layer "In2.Cu")
		(net "P5V_STBY")
	)
	(segment
		(start 444.43142 -17.907)
		(end 444.130938 -18.207482)
		(width 0.254)
		(layer "In2.Cu")
		(net "P5V_STBY")
	)
	(segment
		(start 198.102728 -61.70549)
		(end 198.2216 -61.586618)
		(width 0.635)
		(layer "In2.Cu")
		(net "P5V_STBY")
	)
	(segment
		(start 438.070244 -17.1069)
		(end 437.787796 -17.389348)
		(width 0.254)
		(layer "In2.Cu")
		(net "P5V_STBY")
	)
	(segment
		(start 194.699128 -64.681608)
		(end 194.957192 -64.681608)
		(width 0.4064)
		(layer "In2.Cu")
		(net "P5V_STBY")
	)
	(segment
		(start 198.090028 -94.496382)
		(end 198.090028 -94.060518)
		(width 0.635)
		(layer "In2.Cu")
		(net "P5V_STBY")
	)
	(segment
		(start 4.22275 -14.003782)
		(end 3.8354 -13.616432)
		(width 0.4064)
		(layer "In2.Cu")
		(net "P5V_STBY")
	)
	(segment
		(start 468.149178 -24.888952)
		(end 466.188806 -22.92858)
		(width 0.254)
		(layer "In2.Cu")
		(net "P5V_STBY")
	)
	(segment
		(start 195.6562 -52.05222)
		(end 195.078604 -52.629816)
		(width 0.4064)
		(layer "In2.Cu")
		(net "P5V_STBY")
	)
	(segment
		(start 476.1484 -22.17039)
		(end 473.045028 -25.273762)
		(width 0.254)
		(layer "In2.Cu")
		(net "P5V_STBY")
	)
	(segment
		(start 463.86496 -22.92858)
		(end 461.36052 -20.42414)
		(width 0.254)
		(layer "In2.Cu")
		(net "P5V_STBY")
	)
	(segment
		(start 347.843094 -99.687126)
		(end 349.4532 -99.687126)
		(width 0.508)
		(layer "In2.Cu")
		(net "P5V_STBY")
	)
	(segment
		(start 439.923682 -18.207482)
		(end 438.8231 -17.1069)
		(width 0.254)
		(layer "In2.Cu")
		(net "P5V_STBY")
	)
	(segment
		(start 198.102728 -61.984382)
		(end 198.102728 -61.70549)
		(width 0.635)
		(layer "In2.Cu")
		(net "P5V_STBY")
	)
	(segment
		(start 2.6162 -7.3914)
		(end 3.7338 -7.3914)
		(width 0.4064)
		(layer "In2.Cu")
		(net "P5V_STBY")
	)
	(segment
		(start 33.782 -54.536086)
		(end 33.102296 -53.856382)
		(width 0.508)
		(layer "In2.Cu")
		(net "P5V_STBY")
	)
	(segment
		(start 197.8914 -78.06944)
		(end 198.2724 -77.68844)
		(width 0.635)
		(layer "In2.Cu")
		(net "P5V_STBY")
	)
	(segment
		(start 33.9344 -62.816486)
		(end 33.102296 -61.984382)
		(width 0.508)
		(layer "In2.Cu")
		(net "P5V_STBY")
	)
	(segment
		(start 457.4667 -21.37664)
		(end 456.511152 -21.37664)
		(width 0.254)
		(layer "In2.Cu")
		(net "P5V_STBY")
	)
	(segment
		(start 198.102728 -61.984382)
		(end 198.102728 -62.8396)
		(width 0.635)
		(layer "In2.Cu")
		(net "P5V_STBY")
	)
	(segment
		(start 347.658182 -99.872038)
		(end 347.843094 -99.687126)
		(width 0.508)
		(layer "In2.Cu")
		(net "P5V_STBY")
	)
	(segment
		(start 458.4192 -20.42414)
		(end 457.4667 -21.37664)
		(width 0.254)
		(layer "In2.Cu")
		(net "P5V_STBY")
	)
	(segment
		(start 197.950328 -62.992)
		(end 198.102728 -62.8396)
		(width 0.4064)
		(layer "In2.Cu")
		(net "P5V_STBY")
	)
	(segment
		(start 34.036 -84.506054)
		(end 34.036 -79.8576)
		(width 0.508)
		(layer "In2.Cu")
		(net "P5V_STBY")
	)
	(segment
		(start 34.036 -79.8576)
		(end 33.102296 -78.923896)
		(width 0.508)
		(layer "In2.Cu")
		(net "P5V_STBY")
	)
	(segment
		(start 33.909 -77.433678)
		(end 33.909 -70.919086)
		(width 0.508)
		(layer "In2.Cu")
		(net "P5V_STBY")
	)
	(segment
		(start 437.787796 -18.066004)
		(end 437.334152 -18.519648)
		(width 0.254)
		(layer "In2.Cu")
		(net "P5V_STBY")
	)
	(segment
		(start 195.078604 -53.222652)
		(end 195.078604 -56.18353)
		(width 0.4064)
		(layer "In2.Cu")
		(net "P5V_STBY")
	)
	(segment
		(start 456.511152 -21.37664)
		(end 453.581008 -18.446496)
		(width 0.254)
		(layer "In2.Cu")
		(net "P5V_STBY")
	)
	(segment
		(start 4.22275 -14.277594)
		(end 4.22275 -14.003782)
		(width 0.4064)
		(layer "In2.Cu")
		(net "P5V_STBY")
	)
	(segment
		(start 198.102728 -78.516988)
		(end 198.102728 -79.248)
		(width 0.635)
		(layer "In2.Cu")
		(net "P5V_STBY")
	)
	(segment
		(start 453.581008 -18.446496)
		(end 449.164456 -18.446496)
		(width 0.254)
		(layer "In2.Cu")
		(net "P5V_STBY")
	)
	(segment
		(start 432.432714 -19.190462)
		(end 431.951638 -19.190462)
		(width 0.254)
		(layer "In2.Cu")
		(net "P5V_STBY")
	)
	(segment
		(start 198.102728 -85.666326)
		(end 198.247 -85.522054)
		(width 0.635)
		(layer "In2.Cu")
		(net "P5V_STBY")
	)
	(segment
		(start 32.9438 -86.398608)
		(end 33.07207 -86.398608)
		(width 0.508)
		(layer "In2.Cu")
		(net "P5V_STBY")
	)
	(segment
		(start 438.8231 -17.1069)
		(end 438.070244 -17.1069)
		(width 0.254)
		(layer "In2.Cu")
		(net "P5V_STBY")
	)
	(segment
		(start 3.8354 -13.616432)
		(end 0.889 -13.616432)
		(width 0.4064)
		(layer "In2.Cu")
		(net "P5V_STBY")
	)
	(segment
		(start 33.07207 -86.398608)
		(end 33.07207 -85.469984)
		(width 0.508)
		(layer "In2.Cu")
		(net "P5V_STBY")
	)
	(segment
		(start 431.951638 -19.190462)
		(end 431.865786 -19.276314)
		(width 0.254)
		(layer "In2.Cu")
		(net "P5V_STBY")
	)
	(segment
		(start 4.1656 -6.9596)
		(end 4.1656 -6.284976)
		(width 0.4064)
		(layer "In2.Cu")
		(net "P5V_STBY")
	)
	(segment
		(start 198.102728 -86.368382)
		(end 198.102728 -85.666326)
		(width 0.635)
		(layer "In2.Cu")
		(net "P5V_STBY")
	)
	(segment
		(start 198.128128 -54.135274)
		(end 198.128128 -53.881782)
		(width 0.635)
		(layer "In2.Cu")
		(net "P5V_STBY")
	)
	(segment
		(start 429.04537 -19.595846)
		(end 429.04537 -19.809714)
		(width 0.254)
		(layer "In2.Cu")
		(net "P5V_STBY")
	)
	(segment
		(start 195.072 -53.216048)
		(end 195.078604 -53.222652)
		(width 0.4064)
		(layer "In2.Cu")
		(net "P5V_STBY")
	)
	(segment
		(start 449.164456 -18.446496)
		(end 448.62496 -17.907)
		(width 0.254)
		(layer "In2.Cu")
		(net "P5V_STBY")
	)
	(segment
		(start 354.036122 -97.59442)
		(end 354.16998 -97.59442)
		(width 0.508)
		(layer "In2.Cu")
		(net "P5V_STBY")
	)
	(segment
		(start 197.8914 -78.2066)
		(end 197.8914 -78.30566)
		(width 0.635)
		(layer "In2.Cu")
		(net "P5V_STBY")
	)
	(segment
		(start 198.090028 -94.822518)
		(end 198.090028 -94.496382)
		(width 0.4064)
		(layer "In2.Cu")
		(net "P5V_STBY")
	)
	(segment
		(start 1.2446 -16.7386)
		(end 2.8702 -15.113)
		(width 0.4064)
		(layer "In2.Cu")
		(net "P5V_STBY")
	)
	(segment
		(start 33.102296 -78.923896)
		(end 33.102296 -78.240382)
		(width 0.508)
		(layer "In2.Cu")
		(net "P5V_STBY")
	)
	(segment
		(start 437.334152 -18.519648)
		(end 433.103528 -18.519648)
		(width 0.254)
		(layer "In2.Cu")
		(net "P5V_STBY")
	)
	(segment
		(start 194.957192 -64.681608)
		(end 196.6468 -62.992)
		(width 0.4064)
		(layer "In2.Cu")
		(net "P5V_STBY")
	)
	(segment
		(start 33.16859 -94.50959)
		(end 33.16859 -94.430088)
		(width 0.508)
		(layer "In2.Cu")
		(net "P5V_STBY")
	)
	(segment
		(start 3.816096 -15.113)
		(end 4.22275 -14.706346)
		(width 0.4064)
		(layer "In2.Cu")
		(net "P5V_STBY")
	)
	(segment
		(start 194.935856 -72.739504)
		(end 194.935856 -72.582278)
		(width 0.4064)
		(layer "In2.Cu")
		(net "P5V_STBY")
	)
	(segment
		(start 194.935856 -72.582278)
		(end 196.321934 -71.1962)
		(width 0.4064)
		(layer "In2.Cu")
		(net "P5V_STBY")
	)
	(segment
		(start 437.787796 -17.389348)
		(end 437.787796 -18.066004)
		(width 0.254)
		(layer "In2.Cu")
		(net "P5V_STBY")
	)
	(segment
		(start 197.8914 -78.2066)
		(end 197.8914 -78.06944)
		(width 0.635)
		(layer "In2.Cu")
		(net "P5V_STBY")
	)
	(segment
		(start 33.102296 -61.984382)
		(end 33.782 -61.304678)
		(width 0.508)
		(layer "In2.Cu")
		(net "P5V_STBY")
	)
	(segment
		(start 461.36052 -20.42414)
		(end 458.4192 -20.42414)
		(width 0.254)
		(layer "In2.Cu")
		(net "P5V_STBY")
	)
	(segment
		(start 33.102296 -78.240382)
		(end 33.909 -77.433678)
		(width 0.508)
		(layer "In2.Cu")
		(net "P5V_STBY")
	)
	(segment
		(start 198.247 -79.392272)
		(end 198.102728 -79.248)
		(width 0.635)
		(layer "In2.Cu")
		(net "P5V_STBY")
	)
	(segment
		(start 349.9612 -98.52279)
		(end 350.45269 -98.0313)
		(width 0.508)
		(layer "In2.Cu")
		(net "P5V_STBY")
	)
	(segment
		(start 197.9676 -70.1548)
		(end 197.9676 -70.042278)
		(width 0.635)
		(layer "In2.Cu")
		(net "P5V_STBY")
	)
	(segment
		(start 352.0313 -98.0313)
		(end 352.6282 -97.4344)
		(width 0.508)
		(layer "In2.Cu")
		(net "P5V_STBY")
	)
	(segment
		(start 429.465486 -19.341846)
		(end 429.29937 -19.341846)
		(width 0.254)
		(layer "In2.Cu")
		(net "P5V_STBY")
	)
	(segment
		(start 195.072 -52.752752)
		(end 195.072 -53.216048)
		(width 0.4064)
		(layer "In2.Cu")
		(net "P5V_STBY")
	)
	(segment
		(start 198.2724 -63.009272)
		(end 198.102728 -62.8396)
		(width 0.635)
		(layer "In2.Cu")
		(net "P5V_STBY")
	)
	(segment
		(start 347.658182 -100.582476)
		(end 347.658182 -99.872038)
		(width 0.508)
		(layer "In2.Cu")
		(net "P5V_STBY")
	)
	(segment
		(start 349.823024 -8.01497)
		(end 349.823024 -7.2644)
		(width 0.4064)
		(layer "In4.Cu")
		(net "P5V_STBY")
	)
	(segment
		(start 490.9566 -54.0004)
		(end 490.9566 -52.73167)
		(width 0.508)
		(layer "In4.Cu")
		(net "P5V_STBY")
	)
	(segment
		(start 347.164406 -1.298448)
		(end 347.675454 -0.7874)
		(width 0.381)
		(layer "In4.Cu")
		(net "P5V_STBY")
	)
	(segment
		(start 354.7872 -2.534666)
		(end 354.7872 -2.260346)
		(width 0.381)
		(layer "In4.Cu")
		(net "P5V_STBY")
	)
	(segment
		(start 351.80778 0.719074)
		(end 350.769428 0.719074)
		(width 0.381)
		(layer "In4.Cu")
		(net "P5V_STBY")
	)
	(segment
		(start 348.9579 0.3175)
		(end 349.79483 1.15443)
		(width 0.381)
		(layer "In4.Cu")
		(net "P5V_STBY")
	)
	(segment
		(start 335.7626 -22.0726)
		(end 335.7626 -21.516848)
		(width 0.254)
		(layer "In4.Cu")
		(net "P5V_STBY")
	)
	(segment
		(start 350.627696 -8.819642)
		(end 349.823024 -8.01497)
		(width 0.4064)
		(layer "In4.Cu")
		(net "P5V_STBY")
	)
	(segment
		(start 492.5822 -51.8922)
		(end 493.420146 -51.8922)
		(width 0.508)
		(layer "In4.Cu")
		(net "P5V_STBY")
	)
	(segment
		(start 336.69478 -14.9098)
		(end 341.8332 -14.9098)
		(width 0.254)
		(layer "In4.Cu")
		(net "P5V_STBY")
	)
	(segment
		(start 490.9566 -52.73167)
		(end 491.79607 -51.8922)
		(width 0.508)
		(layer "In4.Cu")
		(net "P5V_STBY")
	)
	(segment
		(start 487.497628 -61.895482)
		(end 490.101128 -59.291982)
		(width 0.508)
		(layer "In4.Cu")
		(net "P5V_STBY")
	)
	(segment
		(start 336.35188 -16.30172)
		(end 336.35188 -15.2527)
		(width 0.254)
		(layer "In4.Cu")
		(net "P5V_STBY")
	)
	(segment
		(start 350.769428 0.719074)
		(end 350.522032 0.96647)
		(width 0.381)
		(layer "In4.Cu")
		(net "P5V_STBY")
	)
	(segment
		(start 324.590664 -44.047664)
		(end 327.315576 -41.322752)
		(width 1.016)
		(layer "In4.Cu")
		(net "P5V_STBY")
	)
	(segment
		(start 349.1992 -13.974572)
		(end 349.1992 -12.2428)
		(width 0.254)
		(layer "In4.Cu")
		(net "P5V_STBY")
	)
	(segment
		(start 327.315576 -41.322752)
		(end 327.494646 -41.322752)
		(width 1.016)
		(layer "In4.Cu")
		(net "P5V_STBY")
	)
	(segment
		(start 354.7872 -2.260346)
		(end 351.80778 0.719074)
		(width 0.381)
		(layer "In4.Cu")
		(net "P5V_STBY")
	)
	(segment
		(start 347.993462 -11.697462)
		(end 346.750132 -10.454132)
		(width 0.254)
		(layer "In4.Cu")
		(net "P5V_STBY")
	)
	(segment
		(start 347.675454 -0.7874)
		(end 348.17177 -0.7874)
		(width 0.381)
		(layer "In4.Cu")
		(net "P5V_STBY")
	)
	(segment
		(start 349.1992 -12.2428)
		(end 348.653862 -11.697462)
		(width 0.254)
		(layer "In4.Cu")
		(net "P5V_STBY")
	)
	(segment
		(start 348.9579 -0.00127)
		(end 348.9579 0.3175)
		(width 0.381)
		(layer "In4.Cu")
		(net "P5V_STBY")
	)
	(segment
		(start 346.750132 -10.454132)
		(end 346.750132 -9.8552)
		(width 0.254)
		(layer "In4.Cu")
		(net "P5V_STBY")
	)
	(segment
		(start 494.19002 -51.122326)
		(end 497.162836 -51.122326)
		(width 0.508)
		(layer "In4.Cu")
		(net "P5V_STBY")
	)
	(segment
		(start 350.627696 -10.182352)
		(end 350.627696 -8.819642)
		(width 0.4064)
		(layer "In4.Cu")
		(net "P5V_STBY")
	)
	(segment
		(start 490.101128 -54.855872)
		(end 490.9566 -54.0004)
		(width 0.508)
		(layer "In4.Cu")
		(net "P5V_STBY")
	)
	(segment
		(start 335.0768 -22.7584)
		(end 335.7626 -22.0726)
		(width 0.254)
		(layer "In4.Cu")
		(net "P5V_STBY")
	)
	(segment
		(start 349.79483 1.15443)
		(end 350.334072 1.15443)
		(width 0.381)
		(layer "In4.Cu")
		(net "P5V_STBY")
	)
	(segment
		(start 491.79607 -51.8922)
		(end 492.5822 -51.8922)
		(width 0.508)
		(layer "In4.Cu")
		(net "P5V_STBY")
	)
	(segment
		(start 348.110048 -14.477492)
		(end 348.69628 -14.477492)
		(width 0.254)
		(layer "In4.Cu")
		(net "P5V_STBY")
	)
	(segment
		(start 348.653862 -11.697462)
		(end 347.993462 -11.697462)
		(width 0.254)
		(layer "In4.Cu")
		(net "P5V_STBY")
	)
	(segment
		(start 336.35188 -15.2527)
		(end 336.69478 -14.9098)
		(width 0.254)
		(layer "In4.Cu")
		(net "P5V_STBY")
	)
	(segment
		(start 486.165398 -61.886084)
		(end 486.174796 -61.895482)
		(width 0.508)
		(layer "In4.Cu")
		(net "P5V_STBY")
	)
	(segment
		(start 342.2904 -15.748)
		(end 342.737186 -16.194786)
		(width 0.254)
		(layer "In4.Cu")
		(net "P5V_STBY")
	)
	(segment
		(start 349.940118 -10.86993)
		(end 350.627696 -10.182352)
		(width 0.4064)
		(layer "In4.Cu")
		(net "P5V_STBY")
	)
	(segment
		(start 486.174796 -61.895482)
		(end 487.497628 -61.895482)
		(width 0.508)
		(layer "In4.Cu")
		(net "P5V_STBY")
	)
	(segment
		(start 347.2434 -9.6012)
		(end 347.2434 -9.8044)
		(width 0.4064)
		(layer "In4.Cu")
		(net "P5V_STBY")
	)
	(segment
		(start 348.30893 -10.86993)
		(end 349.940118 -10.86993)
		(width 0.4064)
		(layer "In4.Cu")
		(net "P5V_STBY")
	)
	(segment
		(start 493.420146 -51.8922)
		(end 494.19002 -51.122326)
		(width 0.508)
		(layer "In4.Cu")
		(net "P5V_STBY")
	)
	(segment
		(start 319.573148 -44.047664)
		(end 324.590664 -44.047664)
		(width 1.016)
		(layer "In4.Cu")
		(net "P5V_STBY")
	)
	(segment
		(start 342.737186 -16.194786)
		(end 346.392754 -16.194786)
		(width 0.254)
		(layer "In4.Cu")
		(net "P5V_STBY")
	)
	(segment
		(start 29.8704 -49.22647)
		(end 29.8704 -48.514)
		(width 0.6096)
		(layer "In4.Cu")
		(net "P5V_STBY")
	)
	(segment
		(start 335.5594 -21.313648)
		(end 335.5594 -17.0942)
		(width 0.254)
		(layer "In4.Cu")
		(net "P5V_STBY")
	)
	(segment
		(start 347.2434 -9.8044)
		(end 348.30893 -10.86993)
		(width 0.4064)
		(layer "In4.Cu")
		(net "P5V_STBY")
	)
	(segment
		(start 29.8704 -48.514)
		(end 27.3812 -46.0248)
		(width 0.6096)
		(layer "In4.Cu")
		(net "P5V_STBY")
	)
	(segment
		(start 347.004132 -9.6012)
		(end 347.2434 -9.6012)
		(width 0.254)
		(layer "In4.Cu")
		(net "P5V_STBY")
	)
	(segment
		(start 350.334072 1.15443)
		(end 350.522032 0.96647)
		(width 0.381)
		(layer "In4.Cu")
		(net "P5V_STBY")
	)
	(segment
		(start 334.5942 -22.7584)
		(end 335.0768 -22.7584)
		(width 0.254)
		(layer "In4.Cu")
		(net "P5V_STBY")
	)
	(segment
		(start 342.2904 -15.367)
		(end 342.2904 -15.748)
		(width 0.254)
		(layer "In4.Cu")
		(net "P5V_STBY")
	)
	(segment
		(start 346.750132 -9.8552)
		(end 347.004132 -9.6012)
		(width 0.254)
		(layer "In4.Cu")
		(net "P5V_STBY")
	)
	(segment
		(start 348.17177 -0.7874)
		(end 348.9579 -0.00127)
		(width 0.381)
		(layer "In4.Cu")
		(net "P5V_STBY")
	)
	(segment
		(start 355.756464 -3.50393)
		(end 354.7872 -2.534666)
		(width 0.381)
		(layer "In4.Cu")
		(net "P5V_STBY")
	)
	(segment
		(start 335.5594 -17.0942)
		(end 336.35188 -16.30172)
		(width 0.254)
		(layer "In4.Cu")
		(net "P5V_STBY")
	)
	(segment
		(start 341.8332 -14.9098)
		(end 342.2904 -15.367)
		(width 0.254)
		(layer "In4.Cu")
		(net "P5V_STBY")
	)
	(segment
		(start 27.3812 -42.90568)
		(end 25.2095 -40.73398)
		(width 0.6096)
		(layer "In4.Cu")
		(net "P5V_STBY")
	)
	(segment
		(start 346.392754 -16.194786)
		(end 348.110048 -14.477492)
		(width 0.254)
		(layer "In4.Cu")
		(net "P5V_STBY")
	)
	(segment
		(start 27.3812 -46.0248)
		(end 27.3812 -42.90568)
		(width 0.6096)
		(layer "In4.Cu")
		(net "P5V_STBY")
	)
	(segment
		(start 335.7626 -21.516848)
		(end 335.5594 -21.313648)
		(width 0.254)
		(layer "In4.Cu")
		(net "P5V_STBY")
	)
	(segment
		(start 350.229424 -6.858)
		(end 350.3168 -6.858)
		(width 0.4064)
		(layer "In4.Cu")
		(net "P5V_STBY")
	)
	(segment
		(start 349.823024 -7.2644)
		(end 350.229424 -6.858)
		(width 0.4064)
		(layer "In4.Cu")
		(net "P5V_STBY")
	)
	(segment
		(start 348.69628 -14.477492)
		(end 349.1992 -13.974572)
		(width 0.254)
		(layer "In4.Cu")
		(net "P5V_STBY")
	)
	(segment
		(start 490.101128 -59.291982)
		(end 490.101128 -54.855872)
		(width 0.508)
		(layer "In4.Cu")
		(net "P5V_STBY")
	)
	(segment
		(start 347.164406 -1.467104)
		(end 347.164406 -1.298448)
		(width 0.381)
		(layer "In4.Cu")
		(net "P5V_STBY")
	)
	(segment
		(start 373.202454 -154.37866)
		(end 373.202454 -153.771346)
		(width 0.254)
		(layer "In6.Cu")
		(net "P5V_STBY")
	)
	(segment
		(start 425.495466 -51.770534)
		(end 425.58335 -51.68265)
		(width 0.635)
		(layer "In6.Cu")
		(net "P5V_STBY")
	)
	(segment
		(start 382.1938 -154.559)
		(end 382.1938 -153.9748)
		(width 0.254)
		(layer "In6.Cu")
		(net "P5V_STBY")
	)
	(segment
		(start 413.6771 -70.55612)
		(end 414.6042 -69.62902)
		(width 0.635)
		(layer "In6.Cu")
		(net "P5V_STBY")
	)
	(segment
		(start 423.252646 -53.217572)
		(end 424.699684 -51.770534)
		(width 0.635)
		(layer "In6.Cu")
		(net "P5V_STBY")
	)
	(segment
		(start 420.839646 -53.883306)
		(end 421.50538 -53.217572)
		(width 0.635)
		(layer "In6.Cu")
		(net "P5V_STBY")
	)
	(segment
		(start 415.053526 -79.86014)
		(end 415.053526 -73.499726)
		(width 0.635)
		(layer "In6.Cu")
		(net "P5V_STBY")
	)
	(segment
		(start 439.71718 -54.541674)
		(end 443.361826 -58.18632)
		(width 0.635)
		(layer "In6.Cu")
		(net "P5V_STBY")
	)
	(segment
		(start 419.455092 -53.43398)
		(end 419.904418 -53.883306)
		(width 0.635)
		(layer "In6.Cu")
		(net "P5V_STBY")
	)
	(segment
		(start 415.258504 -55.611014)
		(end 417.435538 -53.43398)
		(width 0.635)
		(layer "In6.Cu")
		(net "P5V_STBY")
	)
	(segment
		(start 443.361826 -58.18632)
		(end 445.705738 -58.18632)
		(width 0.635)
		(layer "In6.Cu")
		(net "P5V_STBY")
	)
	(segment
		(start 414.6042 -69.62902)
		(end 414.6042 -58.316622)
		(width 0.635)
		(layer "In6.Cu")
		(net "P5V_STBY")
	)
	(segment
		(start 425.58335 -51.68265)
		(end 425.596558 -51.68265)
		(width 0.635)
		(layer "In6.Cu")
		(net "P5V_STBY")
	)
	(segment
		(start 421.50538 -53.217572)
		(end 423.252646 -53.217572)
		(width 0.635)
		(layer "In6.Cu")
		(net "P5V_STBY")
	)
	(segment
		(start 415.258504 -57.662318)
		(end 415.258504 -55.611014)
		(width 0.635)
		(layer "In6.Cu")
		(net "P5V_STBY")
	)
	(segment
		(start 414.6042 -58.316622)
		(end 415.258504 -57.662318)
		(width 0.635)
		(layer "In6.Cu")
		(net "P5V_STBY")
	)
	(segment
		(start 417.435538 -53.43398)
		(end 419.455092 -53.43398)
		(width 0.635)
		(layer "In6.Cu")
		(net "P5V_STBY")
	)
	(segment
		(start 424.699684 -51.770534)
		(end 425.495466 -51.770534)
		(width 0.635)
		(layer "In6.Cu")
		(net "P5V_STBY")
	)
	(segment
		(start 425.615608 -51.6636)
		(end 434.575458 -51.6636)
		(width 0.635)
		(layer "In6.Cu")
		(net "P5V_STBY")
	)
	(segment
		(start 419.904418 -53.883306)
		(end 420.839646 -53.883306)
		(width 0.635)
		(layer "In6.Cu")
		(net "P5V_STBY")
	)
	(segment
		(start 434.575458 -51.6636)
		(end 437.453532 -54.541674)
		(width 0.635)
		(layer "In6.Cu")
		(net "P5V_STBY")
	)
	(segment
		(start 415.053526 -73.499726)
		(end 413.6771 -72.1233)
		(width 0.635)
		(layer "In6.Cu")
		(net "P5V_STBY")
	)
	(segment
		(start 413.6771 -72.1233)
		(end 413.6771 -70.55612)
		(width 0.635)
		(layer "In6.Cu")
		(net "P5V_STBY")
	)
	(segment
		(start 413.365442 -81.548224)
		(end 415.053526 -79.86014)
		(width 0.635)
		(layer "In6.Cu")
		(net "P5V_STBY")
	)
	(segment
		(start 445.705738 -58.18632)
		(end 446.614296 -59.094878)
		(width 0.635)
		(layer "In6.Cu")
		(net "P5V_STBY")
	)
	(segment
		(start 437.453532 -54.541674)
		(end 439.71718 -54.541674)
		(width 0.635)
		(layer "In6.Cu")
		(net "P5V_STBY")
	)
	(segment
		(start 425.596558 -51.68265)
		(end 425.615608 -51.6636)
		(width 0.635)
		(layer "In6.Cu")
		(net "P5V_STBY")
	)
	(segment
		(start 475.315788 -56.58231)
		(end 477.177608 -58.44413)
		(width 0.635)
		(layer "In7.Cu")
		(net "P5V_STBY")
	)
	(segment
		(start 447.589148 -58.120026)
		(end 471.69578 -58.120026)
		(width 0.635)
		(layer "In7.Cu")
		(net "P5V_STBY")
	)
	(segment
		(start 478.073212 -61.895482)
		(end 486.156 -61.895482)
		(width 0.635)
		(layer "In7.Cu")
		(net "P5V_STBY")
	)
	(segment
		(start 473.233496 -56.58231)
		(end 475.315788 -56.58231)
		(width 0.635)
		(layer "In7.Cu")
		(net "P5V_STBY")
	)
	(segment
		(start 486.156 -61.895482)
		(end 486.165398 -61.886084)
		(width 0.635)
		(layer "In7.Cu")
		(net "P5V_STBY")
	)
	(segment
		(start 477.177608 -58.44413)
		(end 477.177608 -60.999878)
		(width 0.635)
		(layer "In7.Cu")
		(net "P5V_STBY")
	)
	(segment
		(start 477.177608 -60.999878)
		(end 478.073212 -61.895482)
		(width 0.635)
		(layer "In7.Cu")
		(net "P5V_STBY")
	)
	(segment
		(start 471.69578 -58.120026)
		(end 473.233496 -56.58231)
		(width 0.635)
		(layer "In7.Cu")
		(net "P5V_STBY")
	)
	(segment
		(start 446.614296 -59.094878)
		(end 447.589148 -58.120026)
		(width 0.635)
		(layer "In7.Cu")
		(net "P5V_STBY")
	)
	(segment
		(start 29.464 -64.679322)
		(end 29.364432 -64.579754)
		(width 0.508)
		(layer "In9.Cu")
		(net "P5V_STBY")
	)
	(segment
		(start 31.014162 -79.906114)
		(end 29.721302 -79.906114)
		(width 0.508)
		(layer "In9.Cu")
		(net "P5V_STBY")
	)
	(segment
		(start 476.784162 -15.440914)
		(end 477.007682 -15.440914)
		(width 0.508)
		(layer "In9.Cu")
		(net "P5V_STBY")
	)
	(segment
		(start 484.249984 -19.65706)
		(end 485.42321 -20.830286)
		(width 0.508)
		(layer "In9.Cu")
		(net "P5V_STBY")
	)
	(segment
		(start 32.594296 -79.299816)
		(end 31.62046 -79.299816)
		(width 0.508)
		(layer "In9.Cu")
		(net "P5V_STBY")
	)
	(segment
		(start 31.6992 -54.6608)
		(end 32.7152 -54.6608)
		(width 0.508)
		(layer "In9.Cu")
		(net "P5V_STBY")
	)
	(segment
		(start 31.571946 -93.8784)
		(end 31.683706 -93.76664)
		(width 0.508)
		(layer "In9.Cu")
		(net "P5V_STBY")
	)
	(segment
		(start 30.984444 -88.034114)
		(end 29.721302 -88.034114)
		(width 0.508)
		(layer "In9.Cu")
		(net "P5V_STBY")
	)
	(segment
		(start 484.287068 -51.769518)
		(end 484.287068 -54.322472)
		(width 0.508)
		(layer "In9.Cu")
		(net "P5V_STBY")
	)
	(segment
		(start 32.270192 -87.072216)
		(end 31.946342 -87.072216)
		(width 0.508)
		(layer "In9.Cu")
		(net "P5V_STBY")
	)
	(segment
		(start 33.102296 -50.211736)
		(end 33.102296 -53.856382)
		(width 0.508)
		(layer "In9.Cu")
		(net "P5V_STBY")
	)
	(segment
		(start 29.54274 -56.62676)
		(end 29.364432 -56.448452)
		(width 0.508)
		(layer "In9.Cu")
		(net "P5V_STBY")
	)
	(segment
		(start 31.946342 -87.072216)
		(end 30.984444 -88.034114)
		(width 0.508)
		(layer "In9.Cu")
		(net "P5V_STBY")
	)
	(segment
		(start 482.842824 -19.65706)
		(end 484.249984 -19.65706)
		(width 0.508)
		(layer "In9.Cu")
		(net "P5V_STBY")
	)
	(segment
		(start 29.364432 -55.878984)
		(end 29.721302 -55.522114)
		(width 0.508)
		(layer "In9.Cu")
		(net "P5V_STBY")
	)
	(segment
		(start 482.80066 -38.142926)
		(end 482.80066 -40.773096)
		(width 0.508)
		(layer "In9.Cu")
		(net "P5V_STBY")
	)
	(segment
		(start 29.364432 -64.006984)
		(end 29.833062 -63.538354)
		(width 0.508)
		(layer "In9.Cu")
		(net "P5V_STBY")
	)
	(segment
		(start 31.521908 -63.046864)
		(end 32.462216 -63.046864)
		(width 0.508)
		(layer "In9.Cu")
		(net "P5V_STBY")
	)
	(segment
		(start 29.721302 -79.906114)
		(end 29.364432 -80.262984)
		(width 0.508)
		(layer "In9.Cu")
		(net "P5V_STBY")
	)
	(segment
		(start 29.364432 -88.390984)
		(end 29.364432 -88.963754)
		(width 0.508)
		(layer "In9.Cu")
		(net "P5V_STBY")
	)
	(segment
		(start 31.030418 -63.538354)
		(end 31.521908 -63.046864)
		(width 0.508)
		(layer "In9.Cu")
		(net "P5V_STBY")
	)
	(segment
		(start 485.42321 -29.69641)
		(end 486.4862 -30.7594)
		(width 0.508)
		(layer "In9.Cu")
		(net "P5V_STBY")
	)
	(segment
		(start 485.42321 -20.830286)
		(end 485.42321 -29.69641)
		(width 0.508)
		(layer "In9.Cu")
		(net "P5V_STBY")
	)
	(segment
		(start 30.423358 -95.281496)
		(end 30.423358 -94.24416)
		(width 0.508)
		(layer "In9.Cu")
		(net "P5V_STBY")
	)
	(segment
		(start 32.66059 -93.76664)
		(end 33.16859 -94.27464)
		(width 0.508)
		(layer "In9.Cu")
		(net "P5V_STBY")
	)
	(segment
		(start 484.287068 -54.322472)
		(end 485.171242 -55.206646)
		(width 0.508)
		(layer "In9.Cu")
		(net "P5V_STBY")
	)
	(segment
		(start 29.364432 -56.448452)
		(end 29.364432 -55.878984)
		(width 0.508)
		(layer "In9.Cu")
		(net "P5V_STBY")
	)
	(segment
		(start 33.16859 -94.27464)
		(end 33.16859 -94.50959)
		(width 0.508)
		(layer "In9.Cu")
		(net "P5V_STBY")
	)
	(segment
		(start 482.1682 -41.405556)
		(end 482.1682 -45.667676)
		(width 0.508)
		(layer "In9.Cu")
		(net "P5V_STBY")
	)
	(segment
		(start 477.007682 -15.440914)
		(end 477.496632 -15.929864)
		(width 0.508)
		(layer "In9.Cu")
		(net "P5V_STBY")
	)
	(segment
		(start 29.364432 -72.134984)
		(end 29.87167 -71.627746)
		(width 0.508)
		(layer "In9.Cu")
		(net "P5V_STBY")
	)
	(segment
		(start 484.498396 -47.997872)
		(end 484.498396 -50.705258)
		(width 0.508)
		(layer "In9.Cu")
		(net "P5V_STBY")
	)
	(segment
		(start 31.692088 -71.123048)
		(end 32.489648 -71.123048)
		(width 0.508)
		(layer "In9.Cu")
		(net "P5V_STBY")
	)
	(segment
		(start 30.423358 -94.24416)
		(end 30.789118 -93.8784)
		(width 0.508)
		(layer "In9.Cu")
		(net "P5V_STBY")
	)
	(segment
		(start 32.9438 -86.398608)
		(end 32.270192 -87.072216)
		(width 0.508)
		(layer "In9.Cu")
		(net "P5V_STBY")
	)
	(segment
		(start 29.464 -96.240854)
		(end 30.423358 -95.281496)
		(width 0.508)
		(layer "In9.Cu")
		(net "P5V_STBY")
	)
	(segment
		(start 484.255318 -51.737768)
		(end 484.287068 -51.769518)
		(width 0.508)
		(layer "In9.Cu")
		(net "P5V_STBY")
	)
	(segment
		(start 32.11703 -49.22647)
		(end 33.102296 -50.211736)
		(width 0.635)
		(layer "In9.Cu")
		(net "P5V_STBY")
	)
	(segment
		(start 30.837886 -55.522114)
		(end 31.6992 -54.6608)
		(width 0.508)
		(layer "In9.Cu")
		(net "P5V_STBY")
	)
	(segment
		(start 32.462216 -63.046864)
		(end 33.102296 -62.406784)
		(width 0.508)
		(layer "In9.Cu")
		(net "P5V_STBY")
	)
	(segment
		(start 31.683706 -93.76664)
		(end 32.66059 -93.76664)
		(width 0.508)
		(layer "In9.Cu")
		(net "P5V_STBY")
	)
	(segment
		(start 29.364432 -80.835754)
		(end 29.464 -80.935322)
		(width 0.508)
		(layer "In9.Cu")
		(net "P5V_STBY")
	)
	(segment
		(start 29.464 -97.191322)
		(end 29.464 -96.240854)
		(width 0.508)
		(layer "In9.Cu")
		(net "P5V_STBY")
	)
	(segment
		(start 32.489648 -71.123048)
		(end 33.102296 -70.5104)
		(width 0.508)
		(layer "In9.Cu")
		(net "P5V_STBY")
	)
	(segment
		(start 29.364432 -64.579754)
		(end 29.364432 -64.006984)
		(width 0.508)
		(layer "In9.Cu")
		(net "P5V_STBY")
	)
	(segment
		(start 480.973638 -19.8247)
		(end 482.675184 -19.8247)
		(width 0.508)
		(layer "In9.Cu")
		(net "P5V_STBY")
	)
	(segment
		(start 477.496632 -16.347694)
		(end 480.973638 -19.8247)
		(width 0.508)
		(layer "In9.Cu")
		(net "P5V_STBY")
	)
	(segment
		(start 29.8704 -49.22647)
		(end 32.11703 -49.22647)
		(width 0.635)
		(layer "In9.Cu")
		(net "P5V_STBY")
	)
	(segment
		(start 482.1682 -45.667676)
		(end 484.498396 -47.997872)
		(width 0.508)
		(layer "In9.Cu")
		(net "P5V_STBY")
	)
	(segment
		(start 29.364432 -88.963754)
		(end 29.464 -89.063322)
		(width 0.508)
		(layer "In9.Cu")
		(net "P5V_STBY")
	)
	(segment
		(start 30.789118 -93.8784)
		(end 31.571946 -93.8784)
		(width 0.508)
		(layer "In9.Cu")
		(net "P5V_STBY")
	)
	(segment
		(start 485.59339 -37.16274)
		(end 483.780846 -37.16274)
		(width 0.508)
		(layer "In9.Cu")
		(net "P5V_STBY")
	)
	(segment
		(start 31.18739 -71.627746)
		(end 31.692088 -71.123048)
		(width 0.508)
		(layer "In9.Cu")
		(net "P5V_STBY")
	)
	(segment
		(start 483.780846 -37.16274)
		(end 482.80066 -38.142926)
		(width 0.508)
		(layer "In9.Cu")
		(net "P5V_STBY")
	)
	(segment
		(start 29.833062 -63.538354)
		(end 31.030418 -63.538354)
		(width 0.508)
		(layer "In9.Cu")
		(net "P5V_STBY")
	)
	(segment
		(start 29.87167 -71.627746)
		(end 31.18739 -71.627746)
		(width 0.508)
		(layer "In9.Cu")
		(net "P5V_STBY")
	)
	(segment
		(start 31.62046 -79.299816)
		(end 31.014162 -79.906114)
		(width 0.508)
		(layer "In9.Cu")
		(net "P5V_STBY")
	)
	(segment
		(start 484.498396 -50.705258)
		(end 484.255318 -50.948336)
		(width 0.508)
		(layer "In9.Cu")
		(net "P5V_STBY")
	)
	(segment
		(start 29.364432 -80.262984)
		(end 29.364432 -80.835754)
		(width 0.508)
		(layer "In9.Cu")
		(net "P5V_STBY")
	)
	(segment
		(start 33.102296 -78.240382)
		(end 33.102296 -78.791816)
		(width 0.508)
		(layer "In9.Cu")
		(net "P5V_STBY")
	)
	(segment
		(start 486.4862 -36.26993)
		(end 485.59339 -37.16274)
		(width 0.508)
		(layer "In9.Cu")
		(net "P5V_STBY")
	)
	(segment
		(start 482.675184 -19.8247)
		(end 482.842824 -19.65706)
		(width 0.508)
		(layer "In9.Cu")
		(net "P5V_STBY")
	)
	(segment
		(start 477.496632 -15.929864)
		(end 477.496632 -16.347694)
		(width 0.508)
		(layer "In9.Cu")
		(net "P5V_STBY")
	)
	(segment
		(start 482.80066 -40.773096)
		(end 482.1682 -41.405556)
		(width 0.508)
		(layer "In9.Cu")
		(net "P5V_STBY")
	)
	(segment
		(start 33.102296 -78.791816)
		(end 32.594296 -79.299816)
		(width 0.508)
		(layer "In9.Cu")
		(net "P5V_STBY")
	)
	(segment
		(start 33.102296 -70.5104)
		(end 33.102296 -70.112382)
		(width 0.508)
		(layer "In9.Cu")
		(net "P5V_STBY")
	)
	(segment
		(start 33.102296 -62.406784)
		(end 33.102296 -61.984382)
		(width 0.508)
		(layer "In9.Cu")
		(net "P5V_STBY")
	)
	(segment
		(start 29.721302 -88.034114)
		(end 29.364432 -88.390984)
		(width 0.508)
		(layer "In9.Cu")
		(net "P5V_STBY")
	)
	(segment
		(start 33.102296 -54.273704)
		(end 33.102296 -53.856382)
		(width 0.508)
		(layer "In9.Cu")
		(net "P5V_STBY")
	)
	(segment
		(start 484.255318 -50.948336)
		(end 484.255318 -51.737768)
		(width 0.508)
		(layer "In9.Cu")
		(net "P5V_STBY")
	)
	(segment
		(start 32.7152 -54.6608)
		(end 33.102296 -54.273704)
		(width 0.508)
		(layer "In9.Cu")
		(net "P5V_STBY")
	)
	(segment
		(start 29.721302 -55.522114)
		(end 30.837886 -55.522114)
		(width 0.508)
		(layer "In9.Cu")
		(net "P5V_STBY")
	)
	(segment
		(start 29.464 -72.807322)
		(end 29.364432 -72.707754)
		(width 0.508)
		(layer "In9.Cu")
		(net "P5V_STBY")
	)
	(segment
		(start 29.364432 -72.707754)
		(end 29.364432 -72.134984)
		(width 0.508)
		(layer "In9.Cu")
		(net "P5V_STBY")
	)
	(segment
		(start 486.4862 -30.7594)
		(end 486.4862 -36.26993)
		(width 0.508)
		(layer "In9.Cu")
		(net "P5V_STBY")
	)
	(segment
		(start -2.838196 -134.100824)
		(end -3.47218 -134.734808)
		(width 0.4064)
		(layer "In11.Cu")
		(net "P5V_STBY")
	)
	(segment
		(start 389.255 -63.582804)
		(end 389.255 -63.020702)
		(width 0.254)
		(layer "In11.Cu")
		(net "P5V_STBY")
	)
	(segment
		(start -3.3274 -139.56792)
		(end -3.3274 -141.9606)
		(width 0.4064)
		(layer "In11.Cu")
		(net "P5V_STBY")
	)
	(segment
		(start 492.5822 -51.8922)
		(end 487.243628 -51.8922)
		(width 0.508)
		(layer "In11.Cu")
		(net "P5V_STBY")
	)
	(segment
		(start 180.0352 -56.4896)
		(end 178.4858 -56.4896)
		(width 0.254)
		(layer "In11.Cu")
		(net "P5V_STBY")
	)
	(segment
		(start 0.8382 -143.129)
		(end -2.159 -143.129)
		(width 0.4064)
		(layer "In11.Cu")
		(net "P5V_STBY")
	)
	(segment
		(start 8.251952 -123.190508)
		(end 7.47141 -123.190508)
		(width 0.4064)
		(layer "In11.Cu")
		(net "P5V_STBY")
	)
	(segment
		(start 334.6069 -22.7584)
		(end 334.5942 -22.7584)
		(width 0.508)
		(layer "In11.Cu")
		(net "P5V_STBY")
	)
	(segment
		(start -1.174496 -134.388352)
		(end -0.053848 -135.509)
		(width 0.4064)
		(layer "In11.Cu")
		(net "P5V_STBY")
	)
	(segment
		(start -3.3274 -141.9606)
		(end -2.159 -143.129)
		(width 0.4064)
		(layer "In11.Cu")
		(net "P5V_STBY")
	)
	(segment
		(start 0.613664 -123.56084)
		(end -2.667 -126.841504)
		(width 0.4064)
		(layer "In11.Cu")
		(net "P5V_STBY")
	)
	(segment
		(start 389.175752 -62.941454)
		(end 389.188198 -62.941454)
		(width 0.254)
		(layer "In11.Cu")
		(net "P5V_STBY")
	)
	(segment
		(start 182.8038 -54.8132)
		(end 189.014608 -48.602392)
		(width 0.254)
		(layer "In11.Cu")
		(net "P5V_STBY")
	)
	(segment
		(start 487.243628 -51.8922)
		(end 486.134156 -53.001672)
		(width 0.508)
		(layer "In11.Cu")
		(net "P5V_STBY")
	)
	(segment
		(start 492.2012 -34.2392)
		(end 492.2012 -35.0774)
		(width 0.508)
		(layer "In11.Cu")
		(net "P5V_STBY")
	)
	(segment
		(start -3.0988 -133.84022)
		(end -2.838196 -134.100824)
		(width 0.4064)
		(layer "In11.Cu")
		(net "P5V_STBY")
	)
	(segment
		(start -3.078226 -144.048226)
		(end -3.078226 -145.968974)
		(width 0.4064)
		(layer "In11.Cu")
		(net "P5V_STBY")
	)
	(segment
		(start 189.014608 -48.602392)
		(end 195.337176 -48.602392)
		(width 0.254)
		(layer "In11.Cu")
		(net "P5V_STBY")
	)
	(segment
		(start 497.459 -50.826162)
		(end 497.162836 -51.122326)
		(width 0.508)
		(layer "In11.Cu")
		(net "P5V_STBY")
	)
	(segment
		(start 178.0794 -56.896)
		(end 178.0794 -57.404)
		(width 0.254)
		(layer "In11.Cu")
		(net "P5V_STBY")
	)
	(segment
		(start 7.47141 -123.190508)
		(end 6.773418 -122.492516)
		(width 0.4064)
		(layer "In11.Cu")
		(net "P5V_STBY")
	)
	(segment
		(start -2.550668 -134.388352)
		(end -1.174496 -134.388352)
		(width 0.4064)
		(layer "In11.Cu")
		(net "P5V_STBY")
	)
	(segment
		(start 493.3188 -36.195)
		(end 493.3188 -38.78453)
		(width 0.508)
		(layer "In11.Cu")
		(net "P5V_STBY")
	)
	(segment
		(start 389.594852 -73.331324)
		(end 389.939276 -73.331324)
		(width 0.254)
		(layer "In11.Cu")
		(net "P5V_STBY")
	)
	(segment
		(start 180.34 -55.499)
		(end 180.34 -56.1848)
		(width 0.254)
		(layer "In11.Cu")
		(net "P5V_STBY")
	)
	(segment
		(start 1.5748 -144.0942)
		(end 1.5748 -143.8656)
		(width 0.4064)
		(layer "In11.Cu")
		(net "P5V_STBY")
	)
	(segment
		(start 493.010444 -33.429956)
		(end 492.2012 -34.2392)
		(width 0.508)
		(layer "In11.Cu")
		(net "P5V_STBY")
	)
	(segment
		(start -0.053848 -135.509)
		(end 1.146048 -135.509)
		(width 0.4064)
		(layer "In11.Cu")
		(net "P5V_STBY")
	)
	(segment
		(start 181.023514 -54.815486)
		(end 180.34 -55.499)
		(width 0.254)
		(layer "In11.Cu")
		(net "P5V_STBY")
	)
	(segment
		(start 180.34 -56.1848)
		(end 180.0352 -56.4896)
		(width 0.254)
		(layer "In11.Cu")
		(net "P5V_STBY")
	)
	(segment
		(start 387.90245 -69.779134)
		(end 387.90245 -64.935354)
		(width 0.254)
		(layer "In11.Cu")
		(net "P5V_STBY")
	)
	(segment
		(start 1.28651 -123.56084)
		(end 0.613664 -123.56084)
		(width 0.4064)
		(layer "In11.Cu")
		(net "P5V_STBY")
	)
	(segment
		(start 486.134156 -53.001672)
		(end 486.134156 -54.243732)
		(width 0.508)
		(layer "In11.Cu")
		(net "P5V_STBY")
	)
	(segment
		(start -2.667 -126.841504)
		(end -2.667 -130.14198)
		(width 0.4064)
		(layer "In11.Cu")
		(net "P5V_STBY")
	)
	(segment
		(start 181.455314 -54.815486)
		(end 181.023514 -54.815486)
		(width 0.254)
		(layer "In11.Cu")
		(net "P5V_STBY")
	)
	(segment
		(start 1.5748 -143.8656)
		(end 0.8382 -143.129)
		(width 0.4064)
		(layer "In11.Cu")
		(net "P5V_STBY")
	)
	(segment
		(start 493.010444 -28.063952)
		(end 493.010444 -33.429956)
		(width 0.508)
		(layer "In11.Cu")
		(net "P5V_STBY")
	)
	(segment
		(start 6.773418 -122.492516)
		(end 2.354834 -122.492516)
		(width 0.4064)
		(layer "In11.Cu")
		(net "P5V_STBY")
	)
	(segment
		(start 2.354834 -122.492516)
		(end 1.28651 -123.56084)
		(width 0.4064)
		(layer "In11.Cu")
		(net "P5V_STBY")
	)
	(segment
		(start 1.146048 -135.509)
		(end 1.5748 -135.080248)
		(width 0.4064)
		(layer "In11.Cu")
		(net "P5V_STBY")
	)
	(segment
		(start 389.255 -63.020702)
		(end 389.175752 -62.941454)
		(width 0.254)
		(layer "In11.Cu")
		(net "P5V_STBY")
	)
	(segment
		(start 181.455314 -54.815486)
		(end 181.4576 -54.8132)
		(width 0.254)
		(layer "In11.Cu")
		(net "P5V_STBY")
	)
	(segment
		(start 178.4858 -56.4896)
		(end 178.0794 -56.896)
		(width 0.254)
		(layer "In11.Cu")
		(net "P5V_STBY")
	)
	(segment
		(start 336.58175 -25.400254)
		(end 336.58175 -24.73325)
		(width 0.508)
		(layer "In11.Cu")
		(net "P5V_STBY")
	)
	(segment
		(start 494.411 -26.663396)
		(end 493.010444 -28.063952)
		(width 0.508)
		(layer "In11.Cu")
		(net "P5V_STBY")
	)
	(segment
		(start 387.90245 -64.935354)
		(end 389.255 -63.582804)
		(width 0.254)
		(layer "In11.Cu")
		(net "P5V_STBY")
	)
	(segment
		(start 390.2202 -72.096884)
		(end 387.90245 -69.779134)
		(width 0.254)
		(layer "In11.Cu")
		(net "P5V_STBY")
	)
	(segment
		(start 486.134156 -54.243732)
		(end 485.171242 -55.206646)
		(width 0.508)
		(layer "In11.Cu")
		(net "P5V_STBY")
	)
	(segment
		(start -2.667 -130.14198)
		(end -3.0988 -130.57378)
		(width 0.4064)
		(layer "In11.Cu")
		(net "P5V_STBY")
	)
	(segment
		(start 389.939276 -73.331324)
		(end 390.2202 -73.0504)
		(width 0.254)
		(layer "In11.Cu")
		(net "P5V_STBY")
	)
	(segment
		(start -2.838196 -134.100824)
		(end -2.550668 -134.388352)
		(width 0.4064)
		(layer "In11.Cu")
		(net "P5V_STBY")
	)
	(segment
		(start 1.5748 -135.080248)
		(end 1.5748 -134.9502)
		(width 0.4064)
		(layer "In11.Cu")
		(net "P5V_STBY")
	)
	(segment
		(start 181.4576 -54.8132)
		(end 182.8038 -54.8132)
		(width 0.254)
		(layer "In11.Cu")
		(net "P5V_STBY")
	)
	(segment
		(start 390.2202 -73.0504)
		(end 390.2202 -72.096884)
		(width 0.254)
		(layer "In11.Cu")
		(net "P5V_STBY")
	)
	(segment
		(start 8.7122 -122.73026)
		(end 8.251952 -123.190508)
		(width 0.4064)
		(layer "In11.Cu")
		(net "P5V_STBY")
	)
	(segment
		(start 497.459 -42.92473)
		(end 497.459 -50.826162)
		(width 0.508)
		(layer "In11.Cu")
		(net "P5V_STBY")
	)
	(segment
		(start 8.7122 -122.65406)
		(end 8.7122 -122.73026)
		(width 0.4064)
		(layer "In11.Cu")
		(net "P5V_STBY")
	)
	(segment
		(start -3.47218 -134.734808)
		(end -3.47218 -136.363456)
		(width 0.4064)
		(layer "In11.Cu")
		(net "P5V_STBY")
	)
	(segment
		(start 493.3188 -38.78453)
		(end 497.459 -42.92473)
		(width 0.508)
		(layer "In11.Cu")
		(net "P5V_STBY")
	)
	(segment
		(start -3.0988 -130.57378)
		(end -3.0988 -133.84022)
		(width 0.4064)
		(layer "In11.Cu")
		(net "P5V_STBY")
	)
	(segment
		(start 336.58175 -24.73325)
		(end 334.6069 -22.7584)
		(width 0.508)
		(layer "In11.Cu")
		(net "P5V_STBY")
	)
	(segment
		(start -2.112772 -138.353292)
		(end -3.3274 -139.56792)
		(width 0.4064)
		(layer "In11.Cu")
		(net "P5V_STBY")
	)
	(segment
		(start -2.159 -143.129)
		(end -3.078226 -144.048226)
		(width 0.4064)
		(layer "In11.Cu")
		(net "P5V_STBY")
	)
	(segment
		(start -3.078226 -145.968974)
		(end -2.0828 -146.9644)
		(width 0.4064)
		(layer "In11.Cu")
		(net "P5V_STBY")
	)
	(segment
		(start -2.112772 -137.722864)
		(end -2.112772 -138.353292)
		(width 0.4064)
		(layer "In11.Cu")
		(net "P5V_STBY")
	)
	(segment
		(start 492.2012 -35.0774)
		(end 493.3188 -36.195)
		(width 0.508)
		(layer "In11.Cu")
		(net "P5V_STBY")
	)
	(segment
		(start -3.47218 -136.363456)
		(end -2.112772 -137.722864)
		(width 0.4064)
		(layer "In11.Cu")
		(net "P5V_STBY")
	)
	(segment
		(start 178.0794 -57.404)
		(end 178.2318 -57.5564)
		(width 0.254)
		(layer "In11.Cu")
		(net "P5V_STBY")
	)
	(segment
		(start 438.336182 -124.992638)
		(end 438.336182 -117.058694)
		(width 0.508)
		(layer "F.Cu")
		(net "P5V")
	)
	(segment
		(start 479.509836 -61.48959)
		(end 475.570042 -65.429384)
		(width 0.508)
		(layer "F.Cu")
		(net "P5V")
	)
	(segment
		(start 439.724546 -113.781586)
		(end 438.81548 -112.87252)
		(width 0.508)
		(layer "F.Cu")
		(net "P5V")
	)
	(segment
		(start 483.4001 -55.1815)
		(end 484.124 -55.9054)
		(width 0.508)
		(layer "F.Cu")
		(net "P5V")
	)
	(segment
		(start 482.05517 -61.48959)
		(end 479.509836 -61.48959)
		(width 0.508)
		(layer "F.Cu")
		(net "P5V")
	)
	(segment
		(start 475.570042 -65.429384)
		(end 475.570042 -67.098418)
		(width 0.508)
		(layer "F.Cu")
		(net "P5V")
	)
	(segment
		(start 484.124 -59.42076)
		(end 482.05517 -61.48959)
		(width 0.508)
		(layer "F.Cu")
		(net "P5V")
	)
	(segment
		(start 434.490876 -128.726184)
		(end 434.490876 -129.2479)
		(width 0.254)
		(layer "F.Cu")
		(net "P5V")
	)
	(segment
		(start 435.09946 -128.1176)
		(end 434.490876 -128.726184)
		(width 0.254)
		(layer "F.Cu")
		(net "P5V")
	)
	(segment
		(start 438.336182 -117.058694)
		(end 439.724546 -115.67033)
		(width 0.508)
		(layer "F.Cu")
		(net "P5V")
	)
	(segment
		(start 439.724546 -115.67033)
		(end 439.724546 -113.781586)
		(width 0.508)
		(layer "F.Cu")
		(net "P5V")
	)
	(segment
		(start 484.124 -55.9054)
		(end 484.124 -59.42076)
		(width 0.508)
		(layer "F.Cu")
		(net "P5V")
	)
	(segment
		(start 437.9468 -128.6764)
		(end 437.388 -128.1176)
		(width 0.254)
		(layer "F.Cu")
		(net "P5V")
	)
	(segment
		(start 437.388 -128.1176)
		(end 435.09946 -128.1176)
		(width 0.254)
		(layer "F.Cu")
		(net "P5V")
	)
	(via
		(at 468.1474 -124.841)
		(size 0.508)
		(drill 0.254)
		(layers "F.Cu" "B.Cu")
		(net "P5V")
	)
	(via
		(at 480.882452 -52.842668)
		(size 0.508)
		(drill 0.254)
		(layers "F.Cu" "B.Cu")
		(net "P5V")
	)
	(via
		(at 438.293764 -126.285244)
		(size 0.5588)
		(drill 0.3048)
		(layers "F.Cu" "B.Cu")
		(net "P5V")
	)
	(via
		(at 467.487 -125.5014)
		(size 0.508)
		(drill 0.254)
		(layers "F.Cu" "B.Cu")
		(net "P5V")
	)
	(via
		(at 483.4001 -55.1815)
		(size 0.508)
		(drill 0.254)
		(layers "F.Cu" "B.Cu")
		(net "P5V")
	)
	(via
		(at 410.845 3.683)
		(size 0.508)
		(drill 0.254)
		(layers "F.Cu" "B.Cu")
		(net "P5V")
	)
	(via
		(at 438.3024 -127.254)
		(size 0.5588)
		(drill 0.3048)
		(layers "F.Cu" "B.Cu")
		(net "P5V")
	)
	(via
		(at 405.084534 -7.9502)
		(size 0.6604)
		(drill 0.3302)
		(layers "F.Cu" "B.Cu")
		(net "P5V")
	)
	(via
		(at 438.81548 -112.87252)
		(size 0.508)
		(drill 0.254)
		(layers "F.Cu" "B.Cu")
		(net "P5V")
	)
	(via
		(at 467.487 -124.841)
		(size 0.508)
		(drill 0.254)
		(layers "F.Cu" "B.Cu")
		(net "P5V")
	)
	(via
		(at 437.792114 -126.78029)
		(size 0.5588)
		(drill 0.3048)
		(layers "F.Cu" "B.Cu")
		(net "P5V")
	)
	(via
		(at 438.947306 -126.188978)
		(size 0.5588)
		(drill 0.3048)
		(layers "F.Cu" "B.Cu")
		(net "P5V")
	)
	(via
		(at 441.2742 -127.2286)
		(size 0.508)
		(drill 0.254)
		(layers "F.Cu" "B.Cu")
		(net "P5V")
	)
	(via
		(at 468.1474 -125.5014)
		(size 0.508)
		(drill 0.254)
		(layers "F.Cu" "B.Cu")
		(net "P5V")
	)
	(via
		(at 441.49772 -127.885698)
		(size 0.508)
		(drill 0.254)
		(layers "F.Cu" "B.Cu")
		(net "P5V")
	)
	(via
		(at 477.012 -18.7833)
		(size 0.508)
		(drill 0.254)
		(layers "F.Cu" "B.Cu")
		(net "P5V")
	)
	(via
		(at 475.570042 -67.098418)
		(size 0.508)
		(drill 0.254)
		(layers "F.Cu" "B.Cu")
		(net "P5V")
	)
	(segment
		(start 404.7617 -19.286728)
		(end 404.7617 -19.022568)
		(width 0.254)
		(layer "B.Cu")
		(net "P5V")
	)
	(segment
		(start 404.497032 -12.548108)
		(end 405.084534 -11.960606)
		(width 0.254)
		(layer "B.Cu")
		(net "P5V")
	)
	(segment
		(start 404.7617 -19.022568)
		(end 404.457154 -18.718022)
		(width 0.254)
		(layer "B.Cu")
		(net "P5V")
	)
	(segment
		(start 405.084534 -5.507736)
		(end 406.21077 -4.3815)
		(width 0.254)
		(layer "B.Cu")
		(net "P5V")
	)
	(segment
		(start 403.793706 -17.260062)
		(end 404.497032 -16.556736)
		(width 0.254)
		(layer "B.Cu")
		(net "P5V")
	)
	(segment
		(start 406.115012 -19.6469)
		(end 405.121872 -19.6469)
		(width 0.254)
		(layer "B.Cu")
		(net "P5V")
	)
	(segment
		(start 408.958542 -3.30962)
		(end 408.958542 -3.58394)
		(width 0.254)
		(layer "B.Cu")
		(net "P5V")
	)
	(segment
		(start 405.084534 -11.960606)
		(end 405.084534 -10.804144)
		(width 0.254)
		(layer "B.Cu")
		(net "P5V")
	)
	(segment
		(start 409.1305 -19.812)
		(end 406.280112 -19.812)
		(width 0.254)
		(layer "B.Cu")
		(net "P5V")
	)
	(segment
		(start 406.21077 -4.3815)
		(end 408.051 -4.3815)
		(width 0.254)
		(layer "B.Cu")
		(net "P5V")
	)
	(segment
		(start 408.305 -3.937)
		(end 408.051 -4.191)
		(width 0.254)
		(layer "B.Cu")
		(net "P5V")
	)
	(segment
		(start 404.457154 -18.718022)
		(end 404.246842 -18.718022)
		(width 0.254)
		(layer "B.Cu")
		(net "P5V")
	)
	(segment
		(start 484.251 -56.0324)
		(end 484.251 -56.8071)
		(width 0.508)
		(layer "B.Cu")
		(net "P5V")
	)
	(segment
		(start 410.67863 3.51663)
		(end 410.67863 -1.589532)
		(width 0.254)
		(layer "B.Cu")
		(net "P5V")
	)
	(segment
		(start 404.246842 -18.718022)
		(end 403.793706 -18.264886)
		(width 0.254)
		(layer "B.Cu")
		(net "P5V")
	)
	(segment
		(start 410.67863 -1.589532)
		(end 408.958542 -3.30962)
		(width 0.254)
		(layer "B.Cu")
		(net "P5V")
	)
	(segment
		(start 404.497032 -16.556736)
		(end 404.497032 -12.548108)
		(width 0.254)
		(layer "B.Cu")
		(net "P5V")
	)
	(segment
		(start 410.845 3.683)
		(end 410.67863 3.51663)
		(width 0.254)
		(layer "B.Cu")
		(net "P5V")
	)
	(segment
		(start 406.280112 -19.812)
		(end 406.115012 -19.6469)
		(width 0.254)
		(layer "B.Cu")
		(net "P5V")
	)
	(segment
		(start 483.4001 -55.1815)
		(end 484.251 -56.0324)
		(width 0.508)
		(layer "B.Cu")
		(net "P5V")
	)
	(segment
		(start 408.605482 -3.937)
		(end 408.305 -3.937)
		(width 0.254)
		(layer "B.Cu")
		(net "P5V")
	)
	(segment
		(start 403.793706 -18.264886)
		(end 403.793706 -17.260062)
		(width 0.254)
		(layer "B.Cu")
		(net "P5V")
	)
	(segment
		(start 408.051 -4.191)
		(end 408.051 -4.3815)
		(width 0.254)
		(layer "B.Cu")
		(net "P5V")
	)
	(segment
		(start 405.722074 -10.166604)
		(end 405.722074 -8.58774)
		(width 0.254)
		(layer "B.Cu")
		(net "P5V")
	)
	(segment
		(start 405.722074 -8.58774)
		(end 405.084534 -7.9502)
		(width 0.254)
		(layer "B.Cu")
		(net "P5V")
	)
	(segment
		(start 405.121872 -19.6469)
		(end 404.7617 -19.286728)
		(width 0.254)
		(layer "B.Cu")
		(net "P5V")
	)
	(segment
		(start 408.958542 -3.58394)
		(end 408.605482 -3.937)
		(width 0.254)
		(layer "B.Cu")
		(net "P5V")
	)
	(segment
		(start 405.084534 -10.804144)
		(end 405.722074 -10.166604)
		(width 0.254)
		(layer "B.Cu")
		(net "P5V")
	)
	(segment
		(start 405.084534 -7.9502)
		(end 405.084534 -5.507736)
		(width 0.254)
		(layer "B.Cu")
		(net "P5V")
	)
	(segment
		(start 426.3898 -109.601)
		(end 427.609 -110.8202)
		(width 0.635)
		(layer "In7.Cu")
		(net "P5V")
	)
	(segment
		(start 426.3898 -78.358746)
		(end 426.3898 -109.601)
		(width 0.635)
		(layer "In7.Cu")
		(net "P5V")
	)
	(segment
		(start 438.81548 -111.975138)
		(end 438.81548 -112.87252)
		(width 0.635)
		(layer "In7.Cu")
		(net "P5V")
	)
	(segment
		(start 425.8056 -77.774546)
		(end 426.3898 -78.358746)
		(width 0.635)
		(layer "In7.Cu")
		(net "P5V")
	)
	(segment
		(start 475.570042 -67.098418)
		(end 427.261782 -67.098418)
		(width 0.635)
		(layer "In7.Cu")
		(net "P5V")
	)
	(segment
		(start 427.261782 -67.098418)
		(end 425.8056 -68.5546)
		(width 0.635)
		(layer "In7.Cu")
		(net "P5V")
	)
	(segment
		(start 425.8056 -68.5546)
		(end 425.8056 -77.774546)
		(width 0.635)
		(layer "In7.Cu")
		(net "P5V")
	)
	(segment
		(start 427.609 -110.8202)
		(end 437.660542 -110.8202)
		(width 0.635)
		(layer "In7.Cu")
		(net "P5V")
	)
	(segment
		(start 437.660542 -110.8202)
		(end 438.81548 -111.975138)
		(width 0.635)
		(layer "In7.Cu")
		(net "P5V")
	)
	(segment
		(start 478.69729 -40.4114)
		(end 479.1837 -40.4114)
		(width 0.254)
		(layer "In9.Cu")
		(net "P5V")
	)
	(segment
		(start 479.1837 -40.4114)
		(end 480.2124 -39.3827)
		(width 0.254)
		(layer "In9.Cu")
		(net "P5V")
	)
	(segment
		(start 481.145596 -29.102304)
		(end 481.705158 -28.542742)
		(width 0.254)
		(layer "In9.Cu")
		(net "P5V")
	)
	(segment
		(start 483.133654 -27.913076)
		(end 483.133654 -26.712672)
		(width 0.254)
		(layer "In9.Cu")
		(net "P5V")
	)
	(segment
		(start 477.901 -44.596304)
		(end 478.301304 -44.196)
		(width 0.254)
		(layer "In9.Cu")
		(net "P5V")
	)
	(segment
		(start 477.901 -48.4505)
		(end 477.901 -44.596304)
		(width 0.254)
		(layer "In9.Cu")
		(net "P5V")
	)
	(segment
		(start 480.882452 -52.842668)
		(end 480.187508 -52.842668)
		(width 0.254)
		(layer "In9.Cu")
		(net "P5V")
	)
	(segment
		(start 481.145596 -33.63087)
		(end 481.145596 -29.102304)
		(width 0.254)
		(layer "In9.Cu")
		(net "P5V")
	)
	(segment
		(start 479.552 -52.20716)
		(end 479.552 -50.1015)
		(width 0.254)
		(layer "In9.Cu")
		(net "P5V")
	)
	(segment
		(start 476.8596 -18.9357)
		(end 477.012 -18.7833)
		(width 0.254)
		(layer "In9.Cu")
		(net "P5V")
	)
	(segment
		(start 478.15627 -21.735288)
		(end 477.8248 -21.735288)
		(width 0.254)
		(layer "In9.Cu")
		(net "P5V")
	)
	(segment
		(start 479.552 -50.1015)
		(end 477.901 -48.4505)
		(width 0.254)
		(layer "In9.Cu")
		(net "P5V")
	)
	(segment
		(start 476.8596 -20.770088)
		(end 476.8596 -18.9357)
		(width 0.254)
		(layer "In9.Cu")
		(net "P5V")
	)
	(segment
		(start 478.301304 -44.196)
		(end 478.301304 -40.807386)
		(width 0.254)
		(layer "In9.Cu")
		(net "P5V")
	)
	(segment
		(start 480.2124 -34.564066)
		(end 481.145596 -33.63087)
		(width 0.254)
		(layer "In9.Cu")
		(net "P5V")
	)
	(segment
		(start 483.133654 -26.712672)
		(end 478.15627 -21.735288)
		(width 0.254)
		(layer "In9.Cu")
		(net "P5V")
	)
	(segment
		(start 478.301304 -40.807386)
		(end 478.69729 -40.4114)
		(width 0.254)
		(layer "In9.Cu")
		(net "P5V")
	)
	(segment
		(start 480.187508 -52.842668)
		(end 479.552 -52.20716)
		(width 0.254)
		(layer "In9.Cu")
		(net "P5V")
	)
	(segment
		(start 480.2124 -39.3827)
		(end 480.2124 -34.564066)
		(width 0.254)
		(layer "In9.Cu")
		(net "P5V")
	)
	(segment
		(start 477.8248 -21.735288)
		(end 476.8596 -20.770088)
		(width 0.254)
		(layer "In9.Cu")
		(net "P5V")
	)
	(segment
		(start 482.503988 -28.542742)
		(end 483.133654 -27.913076)
		(width 0.254)
		(layer "In9.Cu")
		(net "P5V")
	)
	(segment
		(start 481.705158 -28.542742)
		(end 482.503988 -28.542742)
		(width 0.254)
		(layer "In9.Cu")
		(net "P5V")
	)
	(segment
		(start 476.677482 -10.350246)
		(end 476.677482 -11.706098)
		(width 0.254)
		(layer "In11.Cu")
		(net "P5V")
	)
	(segment
		(start 445.897 2.667)
		(end 448.645788 5.415788)
		(width 0.254)
		(layer "In11.Cu")
		(net "P5V")
	)
	(segment
		(start 481.29317 -52.842668)
		(end 480.882452 -52.842668)
		(width 0.254)
		(layer "In11.Cu")
		(net "P5V")
	)
	(segment
		(start 474.344492 -3.745992)
		(end 474.705426 -3.745992)
		(width 0.254)
		(layer "In11.Cu")
		(net "P5V")
	)
	(segment
		(start 467.633304 4.371848)
		(end 467.633304 0.732536)
		(width 0.254)
		(layer "In11.Cu")
		(net "P5V")
	)
	(segment
		(start 474.705426 -3.745992)
		(end 476.16999 -5.210556)
		(width 0.254)
		(layer "In11.Cu")
		(net "P5V")
	)
	(segment
		(start 477.153986 -8.22071)
		(end 476.677228 -8.697468)
		(width 0.254)
		(layer "In11.Cu")
		(net "P5V")
	)
	(segment
		(start 477.153986 -6.804152)
		(end 477.153986 -8.22071)
		(width 0.254)
		(layer "In11.Cu")
		(net "P5V")
	)
	(segment
		(start 470.378028 -1.461516)
		(end 470.607644 -1.691132)
		(width 0.254)
		(layer "In11.Cu")
		(net "P5V")
	)
	(segment
		(start 466.589364 5.415788)
		(end 467.633304 4.371848)
		(width 0.254)
		(layer "In11.Cu")
		(net "P5V")
	)
	(segment
		(start 475.446344 -17.217644)
		(end 477.012 -18.7833)
		(width 0.254)
		(layer "In11.Cu")
		(net "P5V")
	)
	(segment
		(start 410.845 3.683)
		(end 411.861 2.667)
		(width 0.254)
		(layer "In11.Cu")
		(net "P5V")
	)
	(segment
		(start 475.446344 -12.937236)
		(end 475.446344 -17.217644)
		(width 0.254)
		(layer "In11.Cu")
		(net "P5V")
	)
	(segment
		(start 483.4001 -55.1815)
		(end 483.4001 -54.949598)
		(width 0.254)
		(layer "In11.Cu")
		(net "P5V")
	)
	(segment
		(start 476.677228 -8.697468)
		(end 476.677228 -10.349992)
		(width 0.254)
		(layer "In11.Cu")
		(net "P5V")
	)
	(segment
		(start 472.289632 -1.691132)
		(end 474.344492 -3.745992)
		(width 0.254)
		(layer "In11.Cu")
		(net "P5V")
	)
	(segment
		(start 467.633304 0.732536)
		(end 469.827356 -1.461516)
		(width 0.254)
		(layer "In11.Cu")
		(net "P5V")
	)
	(segment
		(start 476.16999 -5.820156)
		(end 477.153986 -6.804152)
		(width 0.254)
		(layer "In11.Cu")
		(net "P5V")
	)
	(segment
		(start 483.4001 -54.949598)
		(end 481.29317 -52.842668)
		(width 0.254)
		(layer "In11.Cu")
		(net "P5V")
	)
	(segment
		(start 469.827356 -1.461516)
		(end 470.378028 -1.461516)
		(width 0.254)
		(layer "In11.Cu")
		(net "P5V")
	)
	(segment
		(start 476.677228 -10.349992)
		(end 476.677482 -10.350246)
		(width 0.254)
		(layer "In11.Cu")
		(net "P5V")
	)
	(segment
		(start 476.16999 -5.210556)
		(end 476.16999 -5.820156)
		(width 0.254)
		(layer "In11.Cu")
		(net "P5V")
	)
	(segment
		(start 470.607644 -1.691132)
		(end 472.289632 -1.691132)
		(width 0.254)
		(layer "In11.Cu")
		(net "P5V")
	)
	(segment
		(start 448.645788 5.415788)
		(end 466.589364 5.415788)
		(width 0.254)
		(layer "In11.Cu")
		(net "P5V")
	)
	(segment
		(start 411.861 2.667)
		(end 445.897 2.667)
		(width 0.254)
		(layer "In11.Cu")
		(net "P5V")
	)
	(segment
		(start 476.677482 -11.706098)
		(end 475.446344 -12.937236)
		(width 0.254)
		(layer "In11.Cu")
		(net "P5V")
	)
	(via
		(at 447.7004 -3.937)
		(size 0.6604)
		(drill 0.3302)
		(layers "F.Cu" "B.Cu")
		(net "P3V_BAT_SOURCE")
	)
	(segment
		(start 442.1124 -2.9464)
		(end 441.7822 -2.6162)
		(width 0.254)
		(layer "B.Cu")
		(net "P3V_BAT_SOURCE")
	)
	(segment
		(start 413.421068 3.679952)
		(end 413.424116 3.683)
		(width 0.508)
		(layer "B.Cu")
		(net "P3V_BAT_SOURCE")
	)
	(segment
		(start 450.2912 -5.715)
		(end 450.2912 -6.5532)
		(width 0.254)
		(layer "B.Cu")
		(net "P3V_BAT_SOURCE")
	)
	(segment
		(start 448.5132 -3.937)
		(end 450.2912 -5.715)
		(width 0.254)
		(layer "B.Cu")
		(net "P3V_BAT_SOURCE")
	)
	(segment
		(start 440.9948 -0.762)
		(end 432.6382 -0.762)
		(width 0.254)
		(layer "B.Cu")
		(net "P3V_BAT_SOURCE")
	)
	(segment
		(start 423.418 3.683)
		(end 423.421048 3.679952)
		(width 0.508)
		(layer "B.Cu")
		(net "P3V_BAT_SOURCE")
	)
	(segment
		(start 426.691552 1.397)
		(end 424.4086 3.679952)
		(width 0.254)
		(layer "B.Cu")
		(net "P3V_BAT_SOURCE")
	)
	(segment
		(start 444.5254 -2.9464)
		(end 442.1124 -2.9464)
		(width 0.254)
		(layer "B.Cu")
		(net "P3V_BAT_SOURCE")
	)
	(segment
		(start 447.7004 -3.937)
		(end 445.516 -3.937)
		(width 0.254)
		(layer "B.Cu")
		(net "P3V_BAT_SOURCE")
	)
	(segment
		(start 447.7004 -3.937)
		(end 448.5132 -3.937)
		(width 0.254)
		(layer "B.Cu")
		(net "P3V_BAT_SOURCE")
	)
	(segment
		(start 432.6382 -0.762)
		(end 430.4792 1.397)
		(width 0.254)
		(layer "B.Cu")
		(net "P3V_BAT_SOURCE")
	)
	(segment
		(start 445.516 -3.937)
		(end 444.5254 -2.9464)
		(width 0.254)
		(layer "B.Cu")
		(net "P3V_BAT_SOURCE")
	)
	(segment
		(start 424.4086 3.679952)
		(end 423.421048 3.679952)
		(width 0.254)
		(layer "B.Cu")
		(net "P3V_BAT_SOURCE")
	)
	(segment
		(start 441.7822 -2.6162)
		(end 441.7822 -1.5494)
		(width 0.254)
		(layer "B.Cu")
		(net "P3V_BAT_SOURCE")
	)
	(segment
		(start 449.9864 -6.858)
		(end 449.9864 -8.0518)
		(width 0.254)
		(layer "B.Cu")
		(net "P3V_BAT_SOURCE")
	)
	(segment
		(start 450.2912 -6.5532)
		(end 449.9864 -6.858)
		(width 0.254)
		(layer "B.Cu")
		(net "P3V_BAT_SOURCE")
	)
	(segment
		(start 430.4792 1.397)
		(end 426.691552 1.397)
		(width 0.254)
		(layer "B.Cu")
		(net "P3V_BAT_SOURCE")
	)
	(segment
		(start 413.424116 3.683)
		(end 423.418 3.683)
		(width 0.508)
		(layer "B.Cu")
		(net "P3V_BAT_SOURCE")
	)
	(segment
		(start 441.7822 -1.5494)
		(end 440.9948 -0.762)
		(width 0.254)
		(layer "B.Cu")
		(net "P3V_BAT_SOURCE")
	)
	(segment
		(start 14.097 -83.058)
		(end 13.4874 -83.058)
		(width 0.254)
		(layer "F.Cu")
		(net "P12V_PSU")
	)
	(via
		(at 9.1948 -53.7464)
		(size 0.5588)
		(drill 0.3048)
		(layers "F.Cu" "B.Cu")
		(net "P12V_PSU")
	)
	(via
		(at 4.445 -56.896)
		(size 0.5588)
		(drill 0.3048)
		(layers "F.Cu" "B.Cu")
		(net "P12V_PSU")
	)
	(via
		(at 5.207 -56.134)
		(size 0.5588)
		(drill 0.3048)
		(layers "F.Cu" "B.Cu")
		(net "P12V_PSU")
	)
	(via
		(at 5.83438 -62.0776)
		(size 1.1684)
		(drill 0.762)
		(layers "F.Cu" "B.Cu")
		(net "P12V_PSU")
	)
	(via
		(at 5.2578 -52.9844)
		(size 0.5588)
		(drill 0.3048)
		(layers "F.Cu" "B.Cu")
		(net "P12V_PSU")
	)
	(via
		(at 7.6708 -53.7464)
		(size 0.5588)
		(drill 0.3048)
		(layers "F.Cu" "B.Cu")
		(net "P12V_PSU")
	)
	(via
		(at 5.2578 -53.7464)
		(size 0.5588)
		(drill 0.3048)
		(layers "F.Cu" "B.Cu")
		(net "P12V_PSU")
	)
	(via
		(at 5.969 -56.134)
		(size 0.5588)
		(drill 0.3048)
		(layers "F.Cu" "B.Cu")
		(net "P12V_PSU")
	)
	(via
		(at 5.969 -56.896)
		(size 0.5588)
		(drill 0.3048)
		(layers "F.Cu" "B.Cu")
		(net "P12V_PSU")
	)
	(via
		(at 7.29488 -62.0903)
		(size 1.1684)
		(drill 0.762)
		(layers "F.Cu" "B.Cu")
		(net "P12V_PSU")
	)
	(via
		(at 17.8816 -68.6308)
		(size 0.6604)
		(drill 0.3302)
		(layers "F.Cu" "B.Cu")
		(net "P12V_PSU")
	)
	(via
		(at 6.0198 -53.7464)
		(size 0.5588)
		(drill 0.3048)
		(layers "F.Cu" "B.Cu")
		(net "P12V_PSU")
	)
	(via
		(at 7.6708 -52.9844)
		(size 0.5588)
		(drill 0.3048)
		(layers "F.Cu" "B.Cu")
		(net "P12V_PSU")
	)
	(via
		(at 7.6962 -56.896)
		(size 0.5588)
		(drill 0.3048)
		(layers "F.Cu" "B.Cu")
		(net "P12V_PSU")
	)
	(via
		(at 8.4582 -56.896)
		(size 0.5588)
		(drill 0.3048)
		(layers "F.Cu" "B.Cu")
		(net "P12V_PSU")
	)
	(via
		(at 9.2202 -56.896)
		(size 0.5588)
		(drill 0.3048)
		(layers "F.Cu" "B.Cu")
		(net "P12V_PSU")
	)
	(via
		(at 4.445 -56.134)
		(size 0.5588)
		(drill 0.3048)
		(layers "F.Cu" "B.Cu")
		(net "P12V_PSU")
	)
	(via
		(at 4.4958 -52.9844)
		(size 0.5588)
		(drill 0.3048)
		(layers "F.Cu" "B.Cu")
		(net "P12V_PSU")
	)
	(via
		(at 7.6962 -56.134)
		(size 0.5588)
		(drill 0.3048)
		(layers "F.Cu" "B.Cu")
		(net "P12V_PSU")
	)
	(via
		(at 6.1468 -67.83324)
		(size 1.1684)
		(drill 0.762)
		(layers "F.Cu" "B.Cu")
		(net "P12V_PSU")
	)
	(via
		(at 9.1948 -52.9844)
		(size 0.5588)
		(drill 0.3048)
		(layers "F.Cu" "B.Cu")
		(net "P12V_PSU")
	)
	(via
		(at 5.207 -56.896)
		(size 0.5588)
		(drill 0.3048)
		(layers "F.Cu" "B.Cu")
		(net "P12V_PSU")
	)
	(via
		(at 24.99868 -28.498292)
		(size 0.508)
		(drill 0.254)
		(layers "F.Cu" "B.Cu")
		(net "P12V_PSU")
	)
	(via
		(at 9.2202 -56.134)
		(size 0.5588)
		(drill 0.3048)
		(layers "F.Cu" "B.Cu")
		(net "P12V_PSU")
	)
	(via
		(at 12.827 -52.246784)
		(size 0.5588)
		(drill 0.3048)
		(layers "F.Cu" "B.Cu")
		(net "P12V_PSU")
	)
	(via
		(at 13.4874 -83.058)
		(size 0.508)
		(drill 0.254)
		(layers "F.Cu" "B.Cu")
		(net "P12V_PSU")
	)
	(via
		(at 6.0198 -52.9844)
		(size 0.5588)
		(drill 0.3048)
		(layers "F.Cu" "B.Cu")
		(net "P12V_PSU")
	)
	(via
		(at 4.6863 -67.82054)
		(size 1.1684)
		(drill 0.762)
		(layers "F.Cu" "B.Cu")
		(net "P12V_PSU")
	)
	(via
		(at 4.4958 -53.7464)
		(size 0.5588)
		(drill 0.3048)
		(layers "F.Cu" "B.Cu")
		(net "P12V_PSU")
	)
	(via
		(at 8.4328 -52.9844)
		(size 0.5588)
		(drill 0.3048)
		(layers "F.Cu" "B.Cu")
		(net "P12V_PSU")
	)
	(via
		(at 8.4328 -53.7464)
		(size 0.5588)
		(drill 0.3048)
		(layers "F.Cu" "B.Cu")
		(net "P12V_PSU")
	)
	(via
		(at 8.4582 -56.134)
		(size 0.5588)
		(drill 0.3048)
		(layers "F.Cu" "B.Cu")
		(net "P12V_PSU")
	)
	(via
		(at 4.34848 -62.03188)
		(size 1.1684)
		(drill 0.762)
		(layers "F.Cu" "B.Cu")
		(net "P12V_PSU")
	)
	(via
		(at 3.12166 -67.21856)
		(size 1.1684)
		(drill 0.762)
		(layers "F.Cu" "B.Cu")
		(net "P12V_PSU")
	)
	(segment
		(start 11.7729 -72.0725)
		(end 11.7729 -70.99554)
		(width 0.508)
		(layer "B.Cu")
		(net "P12V_PSU")
	)
	(segment
		(start 11.8364 -70.93204)
		(end 11.8364 -70.0786)
		(width 0.508)
		(layer "B.Cu")
		(net "P12V_PSU")
	)
	(segment
		(start 24.892 -30.099)
		(end 25.781 -30.988)
		(width 0.254)
		(layer "B.Cu")
		(net "P12V_PSU")
	)
	(segment
		(start 11.7729 -70.99554)
		(end 11.8364 -70.93204)
		(width 0.508)
		(layer "B.Cu")
		(net "P12V_PSU")
	)
	(segment
		(start 19.431 -69.85)
		(end 19.177 -69.596)
		(width 0.4064)
		(layer "B.Cu")
		(net "P12V_PSU")
	)
	(segment
		(start 25.781 -30.988)
		(end 26.0096 -30.988)
		(width 0.254)
		(layer "B.Cu")
		(net "P12V_PSU")
	)
	(segment
		(start 24.765 -30.099)
		(end 24.892 -30.099)
		(width 0.254)
		(layer "B.Cu")
		(net "P12V_PSU")
	)
	(segment
		(start 24.765 -30.099)
		(end 24.765 -28.9814)
		(width 0.4064)
		(layer "B.Cu")
		(net "P12V_PSU")
	)
	(segment
		(start 13.2842 -68.6308)
		(end 17.8816 -68.6308)
		(width 0.508)
		(layer "B.Cu")
		(net "P12V_PSU")
	)
	(segment
		(start 18.669 -68.6308)
		(end 19.177 -69.1388)
		(width 0.508)
		(layer "B.Cu")
		(net "P12V_PSU")
	)
	(segment
		(start 19.177 -69.1388)
		(end 19.177 -69.596)
		(width 0.508)
		(layer "B.Cu")
		(net "P12V_PSU")
	)
	(segment
		(start 20.447 -69.85)
		(end 19.431 -69.85)
		(width 0.4064)
		(layer "B.Cu")
		(net "P12V_PSU")
	)
	(segment
		(start 24.99868 -28.74772)
		(end 24.99868 -28.498292)
		(width 0.4064)
		(layer "B.Cu")
		(net "P12V_PSU")
	)
	(segment
		(start 20.447 -69.85)
		(end 21.717 -69.85)
		(width 0.4064)
		(layer "B.Cu")
		(net "P12V_PSU")
	)
	(segment
		(start 11.8364 -70.0786)
		(end 13.2842 -68.6308)
		(width 0.508)
		(layer "B.Cu")
		(net "P12V_PSU")
	)
	(segment
		(start 7.62 -72.517)
		(end 11.3284 -72.517)
		(width 0.508)
		(layer "B.Cu")
		(net "P12V_PSU")
	)
	(segment
		(start 17.8816 -68.6308)
		(end 18.669 -68.6308)
		(width 0.508)
		(layer "B.Cu")
		(net "P12V_PSU")
	)
	(segment
		(start 24.765 -28.9814)
		(end 24.99868 -28.74772)
		(width 0.4064)
		(layer "B.Cu")
		(net "P12V_PSU")
	)
	(segment
		(start 11.3284 -72.517)
		(end 11.7729 -72.0725)
		(width 0.508)
		(layer "B.Cu")
		(net "P12V_PSU")
	)
	(segment
		(start 20.79752 -33.14192)
		(end 21.6535 -33.9979)
		(width 0.254)
		(layer "In2.Cu")
		(net "P12V_PSU")
	)
	(segment
		(start 21.6535 -41.4401)
		(end 17.78 -45.3136)
		(width 0.254)
		(layer "In2.Cu")
		(net "P12V_PSU")
	)
	(segment
		(start 24.99868 -28.498292)
		(end 24.353012 -29.14396)
		(width 0.254)
		(layer "In2.Cu")
		(net "P12V_PSU")
	)
	(segment
		(start 21.24456 -29.14396)
		(end 20.79752 -29.591)
		(width 0.254)
		(layer "In2.Cu")
		(net "P12V_PSU")
	)
	(segment
		(start 17.78 -48.1076)
		(end 16.681704 -49.205896)
		(width 0.254)
		(layer "In2.Cu")
		(net "P12V_PSU")
	)
	(segment
		(start 17.78 -45.3136)
		(end 17.78 -48.1076)
		(width 0.254)
		(layer "In2.Cu")
		(net "P12V_PSU")
	)
	(segment
		(start 20.79752 -29.591)
		(end 20.79752 -33.14192)
		(width 0.254)
		(layer "In2.Cu")
		(net "P12V_PSU")
	)
	(segment
		(start 16.681704 -49.205896)
		(end 14.319504 -49.205896)
		(width 0.254)
		(layer "In2.Cu")
		(net "P12V_PSU")
	)
	(segment
		(start 14.319504 -49.205896)
		(end 12.827 -50.6984)
		(width 0.254)
		(layer "In2.Cu")
		(net "P12V_PSU")
	)
	(segment
		(start 12.827 -50.6984)
		(end 12.827 -52.246784)
		(width 0.254)
		(layer "In2.Cu")
		(net "P12V_PSU")
	)
	(segment
		(start 24.353012 -29.14396)
		(end 21.24456 -29.14396)
		(width 0.254)
		(layer "In2.Cu")
		(net "P12V_PSU")
	)
	(segment
		(start 21.6535 -33.9979)
		(end 21.6535 -41.4401)
		(width 0.254)
		(layer "In2.Cu")
		(net "P12V_PSU")
	)
	(via
		(at 14.6304 -66.7512)
		(size 0.5588)
		(drill 0.3048)
		(layers "F.Cu" "B.Cu")
		(net "P12V_MB0_SW")
	)
	(via
		(at 13.462 -57.7342)
		(size 0.5588)
		(drill 0.3048)
		(layers "F.Cu" "B.Cu")
		(net "P12V_MB0_SW")
	)
	(via
		(at 14.7828 -58.5216)
		(size 0.5588)
		(drill 0.3048)
		(layers "F.Cu" "B.Cu")
		(net "P12V_MB0_SW")
	)
	(via
		(at 14.03985 -62.4586)
		(size 0.5588)
		(drill 0.3048)
		(layers "F.Cu" "B.Cu")
		(net "P12V_MB0_SW")
	)
	(via
		(at 14.70025 -62.4586)
		(size 0.5588)
		(drill 0.3048)
		(layers "F.Cu" "B.Cu")
		(net "P12V_MB0_SW")
	)
	(via
		(at 13.462 -60.0202)
		(size 0.5588)
		(drill 0.3048)
		(layers "F.Cu" "B.Cu")
		(net "P12V_MB0_SW")
	)
	(via
		(at 13.462 -60.7822)
		(size 0.5588)
		(drill 0.3048)
		(layers "F.Cu" "B.Cu")
		(net "P12V_MB0_SW")
	)
	(via
		(at 14.7828 -60.8076)
		(size 0.5588)
		(drill 0.3048)
		(layers "F.Cu" "B.Cu")
		(net "P12V_MB0_SW")
	)
	(via
		(at 17.1958 -64.7954)
		(size 0.6604)
		(drill 0.3302)
		(layers "F.Cu" "B.Cu")
		(net "P12V_MB0_SW")
	)
	(via
		(at 18.306796 -61.793628)
		(size 0.7112)
		(drill 0.4064)
		(layers "F.Cu" "B.Cu")
		(net "P12V_MB0_SW")
	)
	(via
		(at 18.161 -67.564)
		(size 0.5588)
		(drill 0.3048)
		(layers "F.Cu" "B.Cu")
		(net "P12V_MB0_SW")
	)
	(via
		(at 14.605 -66.0908)
		(size 0.5588)
		(drill 0.3048)
		(layers "F.Cu" "B.Cu")
		(net "P12V_MB0_SW")
	)
	(via
		(at 17.398492 -61.815472)
		(size 0.7112)
		(drill 0.4064)
		(layers "F.Cu" "B.Cu")
		(net "P12V_MB0_SW")
	)
	(via
		(at 16.637 -67.437)
		(size 0.5588)
		(drill 0.3048)
		(layers "F.Cu" "B.Cu")
		(net "P12V_MB0_SW")
	)
	(via
		(at 14.1224 -59.2836)
		(size 0.5588)
		(drill 0.3048)
		(layers "F.Cu" "B.Cu")
		(net "P12V_MB0_SW")
	)
	(via
		(at 14.1224 -58.5216)
		(size 0.5588)
		(drill 0.3048)
		(layers "F.Cu" "B.Cu")
		(net "P12V_MB0_SW")
	)
	(via
		(at 15.9512 -67.437)
		(size 0.5588)
		(drill 0.3048)
		(layers "F.Cu" "B.Cu")
		(net "P12V_MB0_SW")
	)
	(via
		(at 16.55572 -61.815472)
		(size 0.7112)
		(drill 0.4064)
		(layers "F.Cu" "B.Cu")
		(net "P12V_MB0_SW")
	)
	(via
		(at 14.1224 -60.0456)
		(size 0.5588)
		(drill 0.3048)
		(layers "F.Cu" "B.Cu")
		(net "P12V_MB0_SW")
	)
	(via
		(at 14.7828 -59.2836)
		(size 0.5588)
		(drill 0.3048)
		(layers "F.Cu" "B.Cu")
		(net "P12V_MB0_SW")
	)
	(via
		(at 13.463016 -62.136528)
		(size 0.5588)
		(drill 0.3048)
		(layers "F.Cu" "B.Cu")
		(net "P12V_MB0_SW")
	)
	(via
		(at 14.594078 -63.814198)
		(size 0.5588)
		(drill 0.3048)
		(layers "F.Cu" "B.Cu")
		(net "P12V_MB0_SW")
	)
	(via
		(at 14.7828 -60.0456)
		(size 0.5588)
		(drill 0.3048)
		(layers "F.Cu" "B.Cu")
		(net "P12V_MB0_SW")
	)
	(via
		(at 18.161 -66.8782)
		(size 0.5588)
		(drill 0.3048)
		(layers "F.Cu" "B.Cu")
		(net "P12V_MB0_SW")
	)
	(via
		(at 14.1224 -60.8076)
		(size 0.5588)
		(drill 0.3048)
		(layers "F.Cu" "B.Cu")
		(net "P12V_MB0_SW")
	)
	(via
		(at 17.4752 -66.8782)
		(size 0.5588)
		(drill 0.3048)
		(layers "F.Cu" "B.Cu")
		(net "P12V_MB0_SW")
	)
	(via
		(at 13.462 -58.4962)
		(size 0.5588)
		(drill 0.3048)
		(layers "F.Cu" "B.Cu")
		(net "P12V_MB0_SW")
	)
	(via
		(at 14.594078 -63.128398)
		(size 0.5588)
		(drill 0.3048)
		(layers "F.Cu" "B.Cu")
		(net "P12V_MB0_SW")
	)
	(via
		(at 14.7828 -57.7596)
		(size 0.5588)
		(drill 0.3048)
		(layers "F.Cu" "B.Cu")
		(net "P12V_MB0_SW")
	)
	(via
		(at 15.6972 -61.8236)
		(size 0.7112)
		(drill 0.4064)
		(layers "F.Cu" "B.Cu")
		(net "P12V_MB0_SW")
	)
	(via
		(at 13.462 -59.2582)
		(size 0.5588)
		(drill 0.3048)
		(layers "F.Cu" "B.Cu")
		(net "P12V_MB0_SW")
	)
	(via
		(at 15.24 -67.437)
		(size 0.5588)
		(drill 0.3048)
		(layers "F.Cu" "B.Cu")
		(net "P12V_MB0_SW")
	)
	(via
		(at 14.1224 -57.7596)
		(size 0.5588)
		(drill 0.3048)
		(layers "F.Cu" "B.Cu")
		(net "P12V_MB0_SW")
	)
	(via
		(at 17.4752 -67.564)
		(size 0.5588)
		(drill 0.3048)
		(layers "F.Cu" "B.Cu")
		(net "P12V_MB0_SW")
	)
	(via
		(at 5.0292 -65.5066)
		(size 0.5588)
		(drill 0.3048)
		(layers "F.Cu" "B.Cu")
		(net "P12V_HSC_SENP1")
	)
	(via
		(at 8.50646 -68.0466)
		(size 0.508)
		(drill 0.254)
		(layers "F.Cu" "B.Cu")
		(net "P12V_HSC_SENP1")
	)
	(segment
		(start 5.0292 -65.5066)
		(end 5.56768 -64.96812)
		(width 0.381)
		(layer "B.Cu")
		(net "P12V_HSC_SENP1")
	)
	(segment
		(start 9.398 -68.0466)
		(end 8.50646 -68.0466)
		(width 0.254)
		(layer "B.Cu")
		(net "P12V_HSC_SENP1")
	)
	(segment
		(start 5.56768 -64.96812)
		(end 7.366 -64.96812)
		(width 0.381)
		(layer "B.Cu")
		(net "P12V_HSC_SENP1")
	)
	(segment
		(start 8.67918 -66.858134)
		(end 7.193534 -65.372488)
		(width 0.381)
		(layer "In9.Cu")
		(net "P12V_HSC_SENP1")
	)
	(segment
		(start 8.67918 -67.87388)
		(end 8.67918 -66.858134)
		(width 0.381)
		(layer "In9.Cu")
		(net "P12V_HSC_SENP1")
	)
	(segment
		(start 8.50646 -68.0466)
		(end 8.67918 -67.87388)
		(width 0.381)
		(layer "In9.Cu")
		(net "P12V_HSC_SENP1")
	)
	(segment
		(start 7.193534 -65.372488)
		(end 5.163312 -65.372488)
		(width 0.381)
		(layer "In9.Cu")
		(net "P12V_HSC_SENP1")
	)
	(segment
		(start 5.163312 -65.372488)
		(end 5.0292 -65.5066)
		(width 0.381)
		(layer "In9.Cu")
		(net "P12V_HSC_SENP1")
	)
	(segment
		(start 7.366 -64.96812)
		(end 5.466588 -64.96812)
		(width 0.381)
		(layer "F.Cu")
		(net "P12V_HSC_SENP0")
	)
	(segment
		(start 5.466588 -64.96812)
		(end 5.055616 -64.557148)
		(width 0.381)
		(layer "F.Cu")
		(net "P12V_HSC_SENP0")
	)
	(segment
		(start 9.398 -67.3989)
		(end 9.398 -68.0593)
		(width 0.381)
		(layer "F.Cu")
		(net "P12V_HSC_SENP0")
	)
	(via
		(at 9.398 -67.3989)
		(size 0.508)
		(drill 0.254)
		(layers "F.Cu" "B.Cu")
		(net "P12V_HSC_SENP0")
	)
	(via
		(at 5.055616 -64.557148)
		(size 0.508)
		(drill 0.254)
		(layers "F.Cu" "B.Cu")
		(net "P12V_HSC_SENP0")
	)
	(segment
		(start 7.456678 -64.737488)
		(end 5.235956 -64.737488)
		(width 0.381)
		(layer "In9.Cu")
		(net "P12V_HSC_SENP0")
	)
	(segment
		(start 9.398 -67.3989)
		(end 9.398 -66.67881)
		(width 0.381)
		(layer "In9.Cu")
		(net "P12V_HSC_SENP0")
	)
	(segment
		(start 9.398 -66.67881)
		(end 7.456678 -64.737488)
		(width 0.381)
		(layer "In9.Cu")
		(net "P12V_HSC_SENP0")
	)
	(segment
		(start 5.235956 -64.737488)
		(end 5.055616 -64.557148)
		(width 0.381)
		(layer "In9.Cu")
		(net "P12V_HSC_SENP0")
	)
	(via
		(at 11.25474 -68.11264)
		(size 0.508)
		(drill 0.254)
		(layers "F.Cu" "B.Cu")
		(net "P12V_HSC_SENN1")
	)
	(via
		(at 14.590776 -65.393824)
		(size 0.5588)
		(drill 0.3048)
		(layers "F.Cu" "B.Cu")
		(net "P12V_HSC_SENN1")
	)
	(segment
		(start 14.590776 -65.393824)
		(end 14.165072 -64.96812)
		(width 0.381)
		(layer "B.Cu")
		(net "P12V_HSC_SENN1")
	)
	(segment
		(start 11.01344 -68.0466)
		(end 10.414 -68.0466)
		(width 0.254)
		(layer "B.Cu")
		(net "P12V_HSC_SENN1")
	)
	(segment
		(start 11.07948 -68.11264)
		(end 11.01344 -68.0466)
		(width 0.254)
		(layer "B.Cu")
		(net "P12V_HSC_SENN1")
	)
	(segment
		(start 11.25474 -68.11264)
		(end 11.07948 -68.11264)
		(width 0.254)
		(layer "B.Cu")
		(net "P12V_HSC_SENN1")
	)
	(segment
		(start 14.165072 -64.96812)
		(end 12.3698 -64.96812)
		(width 0.381)
		(layer "B.Cu")
		(net "P12V_HSC_SENN1")
	)
	(segment
		(start 12.772644 -65.268094)
		(end 14.465046 -65.268094)
		(width 0.381)
		(layer "In9.Cu")
		(net "P12V_HSC_SENN1")
	)
	(segment
		(start 11.25474 -68.11264)
		(end 11.09726 -67.95516)
		(width 0.381)
		(layer "In9.Cu")
		(net "P12V_HSC_SENN1")
	)
	(segment
		(start 14.465046 -65.268094)
		(end 14.590776 -65.393824)
		(width 0.381)
		(layer "In9.Cu")
		(net "P12V_HSC_SENN1")
	)
	(segment
		(start 11.09726 -67.95516)
		(end 11.09726 -66.943478)
		(width 0.381)
		(layer "In9.Cu")
		(net "P12V_HSC_SENN1")
	)
	(segment
		(start 11.09726 -66.943478)
		(end 12.772644 -65.268094)
		(width 0.381)
		(layer "In9.Cu")
		(net "P12V_HSC_SENN1")
	)
	(segment
		(start 10.414 -67.3989)
		(end 10.414 -68.0593)
		(width 0.381)
		(layer "F.Cu")
		(net "P12V_HSC_SENN0")
	)
	(segment
		(start 14.17828 -64.96812)
		(end 14.605 -64.5414)
		(width 0.381)
		(layer "F.Cu")
		(net "P12V_HSC_SENN0")
	)
	(segment
		(start 12.3698 -64.96812)
		(end 14.17828 -64.96812)
		(width 0.381)
		(layer "F.Cu")
		(net "P12V_HSC_SENN0")
	)
	(via
		(at 10.414 -67.3989)
		(size 0.508)
		(drill 0.254)
		(layers "F.Cu" "B.Cu")
		(net "P12V_HSC_SENN0")
	)
	(via
		(at 14.605 -64.5414)
		(size 0.508)
		(drill 0.254)
		(layers "F.Cu" "B.Cu")
		(net "P12V_HSC_SENN0")
	)
	(segment
		(start 14.513306 -64.633094)
		(end 14.605 -64.5414)
		(width 0.381)
		(layer "In9.Cu")
		(net "P12V_HSC_SENN0")
	)
	(segment
		(start 10.414 -66.728594)
		(end 12.5095 -64.633094)
		(width 0.381)
		(layer "In9.Cu")
		(net "P12V_HSC_SENN0")
	)
	(segment
		(start 12.5095 -64.633094)
		(end 14.513306 -64.633094)
		(width 0.381)
		(layer "In9.Cu")
		(net "P12V_HSC_SENN0")
	)
	(segment
		(start 10.414 -67.3989)
		(end 10.414 -66.728594)
		(width 0.381)
		(layer "In9.Cu")
		(net "P12V_HSC_SENN0")
	)
	(segment
		(start 349.735648 -23.033228)
		(end 349.354648 -23.414228)
		(width 0.254)
		(layer "F.Cu")
		(net "P12V_STBY")
	)
	(segment
		(start 192.685162 -126.636526)
		(end 192.685162 -125.774958)
		(width 0.254)
		(layer "F.Cu")
		(net "P12V_STBY")
	)
	(segment
		(start 187.821824 -124.4854)
		(end 188.298582 -124.962158)
		(width 0.254)
		(layer "F.Cu")
		(net "P12V_STBY")
	)
	(segment
		(start 21.336 -81.79308)
		(end 21.336 -82.433668)
		(width 0.254)
		(layer "F.Cu")
		(net "P12V_STBY")
	)
	(segment
		(start 186.035188 -125.1712)
		(end 186.720988 -124.4854)
		(width 0.254)
		(layer "F.Cu")
		(net "P12V_STBY")
	)
	(segment
		(start 177.91811 -24.961088)
		(end 178.881532 -25.92451)
		(width 0.254)
		(layer "F.Cu")
		(net "P12V_STBY")
	)
	(segment
		(start 30.98927 -32.588962)
		(end 28.741624 -32.588962)
		(width 0.254)
		(layer "F.Cu")
		(net "P12V_STBY")
	)
	(segment
		(start 188.298582 -124.962158)
		(end 188.298582 -127.903732)
		(width 0.254)
		(layer "F.Cu")
		(net "P12V_STBY")
	)
	(segment
		(start 191.632586 -126.920498)
		(end 191.662304 -126.89078)
		(width 0.254)
		(layer "F.Cu")
		(net "P12V_STBY")
	)
	(segment
		(start 182.510684 -127.071882)
		(end 182.594758 -126.987808)
		(width 0.254)
		(layer "F.Cu")
		(net "P12V_STBY")
	)
	(segment
		(start 498.735604 -25.055576)
		(end 498.735604 -24.647906)
		(width 0.3048)
		(layer "F.Cu")
		(net "P12V_STBY")
	)
	(segment
		(start 11.146028 -126.827026)
		(end 11.146028 -128.07061)
		(width 0.254)
		(layer "F.Cu")
		(net "P12V_STBY")
	)
	(segment
		(start 188.660024 -128.265174)
		(end 190.287148 -128.265174)
		(width 0.254)
		(layer "F.Cu")
		(net "P12V_STBY")
	)
	(segment
		(start 191.662304 -126.89078)
		(end 192.430908 -126.89078)
		(width 0.254)
		(layer "F.Cu")
		(net "P12V_STBY")
	)
	(segment
		(start 349.735648 -22.244812)
		(end 349.735648 -23.033228)
		(width 0.254)
		(layer "F.Cu")
		(net "P12V_STBY")
	)
	(segment
		(start 497.388642 -24.39035)
		(end 497.169694 -24.171402)
		(width 0.3048)
		(layer "F.Cu")
		(net "P12V_STBY")
	)
	(segment
		(start 183.638698 -25.92451)
		(end 184.12841 -25.434798)
		(width 0.254)
		(layer "F.Cu")
		(net "P12V_STBY")
	)
	(segment
		(start 176.573688 -24.961088)
		(end 177.91811 -24.961088)
		(width 0.254)
		(layer "F.Cu")
		(net "P12V_STBY")
	)
	(segment
		(start 31.769558 -31.808674)
		(end 30.98927 -32.588962)
		(width 0.254)
		(layer "F.Cu")
		(net "P12V_STBY")
	)
	(segment
		(start 21.336 -82.433668)
		(end 21.442426 -82.540094)
		(width 0.254)
		(layer "F.Cu")
		(net "P12V_STBY")
	)
	(segment
		(start 32.31388 -31.808674)
		(end 31.769558 -31.808674)
		(width 0.254)
		(layer "F.Cu")
		(net "P12V_STBY")
	)
	(segment
		(start 498.735604 -24.647906)
		(end 498.478048 -24.39035)
		(width 0.3048)
		(layer "F.Cu")
		(net "P12V_STBY")
	)
	(segment
		(start 183.215026 -125.1712)
		(end 186.035188 -125.1712)
		(width 0.254)
		(layer "F.Cu")
		(net "P12V_STBY")
	)
	(segment
		(start 186.720988 -124.4854)
		(end 187.821824 -124.4854)
		(width 0.254)
		(layer "F.Cu")
		(net "P12V_STBY")
	)
	(segment
		(start 184.499504 -25.434798)
		(end 184.785 -25.720294)
		(width 0.254)
		(layer "F.Cu")
		(net "P12V_STBY")
	)
	(segment
		(start 182.594758 -126.987808)
		(end 182.594758 -125.804168)
		(width 0.254)
		(layer "F.Cu")
		(net "P12V_STBY")
	)
	(segment
		(start 188.298582 -127.903732)
		(end 188.660024 -128.265174)
		(width 0.254)
		(layer "F.Cu")
		(net "P12V_STBY")
	)
	(segment
		(start 14.0208 -75.311)
		(end 14.224 -75.311)
		(width 0.254)
		(layer "F.Cu")
		(net "P12V_STBY")
	)
	(segment
		(start 175.2854 -23.6728)
		(end 176.573688 -24.961088)
		(width 0.254)
		(layer "F.Cu")
		(net "P12V_STBY")
	)
	(segment
		(start 28.741624 -32.588962)
		(end 28.616656 -32.71393)
		(width 0.254)
		(layer "F.Cu")
		(net "P12V_STBY")
	)
	(segment
		(start 184.12841 -25.434798)
		(end 184.499504 -25.434798)
		(width 0.254)
		(layer "F.Cu")
		(net "P12V_STBY")
	)
	(segment
		(start 191.631824 -126.920498)
		(end 191.632586 -126.920498)
		(width 0.254)
		(layer "F.Cu")
		(net "P12V_STBY")
	)
	(segment
		(start 178.881532 -25.92451)
		(end 183.638698 -25.92451)
		(width 0.254)
		(layer "F.Cu")
		(net "P12V_STBY")
	)
	(segment
		(start 183.215026 -125.1839)
		(end 183.215026 -125.1712)
		(width 0.254)
		(layer "F.Cu")
		(net "P12V_STBY")
	)
	(segment
		(start 11.146028 -128.07061)
		(end 11.1887 -128.113282)
		(width 0.254)
		(layer "F.Cu")
		(net "P12V_STBY")
	)
	(segment
		(start 13.6144 -75.7174)
		(end 14.0208 -75.311)
		(width 0.254)
		(layer "F.Cu")
		(net "P12V_STBY")
	)
	(segment
		(start 190.287148 -128.265174)
		(end 191.631824 -126.920498)
		(width 0.254)
		(layer "F.Cu")
		(net "P12V_STBY")
	)
	(segment
		(start 192.430908 -126.89078)
		(end 192.685162 -126.636526)
		(width 0.254)
		(layer "F.Cu")
		(net "P12V_STBY")
	)
	(segment
		(start 13.5636 -75.7174)
		(end 13.6144 -75.7174)
		(width 0.254)
		(layer "F.Cu")
		(net "P12V_STBY")
	)
	(segment
		(start 182.594758 -125.804168)
		(end 183.215026 -125.1839)
		(width 0.254)
		(layer "F.Cu")
		(net "P12V_STBY")
	)
	(segment
		(start 498.478048 -24.39035)
		(end 497.388642 -24.39035)
		(width 0.3048)
		(layer "F.Cu")
		(net "P12V_STBY")
	)
	(segment
		(start 184.785 -25.720294)
		(end 184.785 -26.416)
		(width 0.254)
		(layer "F.Cu")
		(net "P12V_STBY")
	)
	(segment
		(start 32.6263 -32.121094)
		(end 32.31388 -31.808674)
		(width 0.254)
		(layer "F.Cu")
		(net "P12V_STBY")
	)
	(segment
		(start 21.442426 -82.540094)
		(end 21.442426 -83.2866)
		(width 0.254)
		(layer "F.Cu")
		(net "P12V_STBY")
	)
	(segment
		(start 32.6263 -32.9438)
		(end 32.6263 -32.121094)
		(width 0.254)
		(layer "F.Cu")
		(net "P12V_STBY")
	)
	(via
		(at -2.908808 -20.779232)
		(size 0.508)
		(drill 0.254)
		(layers "F.Cu" "B.Cu")
		(net "P12V_STBY")
	)
	(via
		(at 24.19985 -55.25643)
		(size 0.7112)
		(drill 0.4064)
		(layers "F.Cu" "B.Cu")
		(net "P12V_STBY")
	)
	(via
		(at 22.203664 -54.738016)
		(size 0.7112)
		(drill 0.4064)
		(layers "F.Cu" "B.Cu")
		(net "P12V_STBY")
	)
	(via
		(at 0.594106 -114.521742)
		(size 0.5588)
		(drill 0.3048)
		(layers "F.Cu" "B.Cu")
		(net "P12V_STBY")
	)
	(via
		(at 23.7236 -64.3636)
		(size 0.5588)
		(drill 0.3048)
		(layers "F.Cu" "B.Cu")
		(net "P12V_STBY")
	)
	(via
		(at 356.551484 -23.28672)
		(size 0.508)
		(drill 0.254)
		(layers "F.Cu" "B.Cu")
		(net "P12V_STBY")
	)
	(via
		(at 8.7122 -129.794)
		(size 0.508)
		(drill 0.254)
		(layers "F.Cu" "B.Cu")
		(net "P12V_STBY")
	)
	(via
		(at 178.60264 -99.806506)
		(size 0.5588)
		(drill 0.3048)
		(layers "F.Cu" "B.Cu")
		(net "P12V_STBY")
	)
	(via
		(at 494.42878 -22.952202)
		(size 0.508)
		(drill 0.254)
		(layers "F.Cu" "B.Cu")
		(net "P12V_STBY")
	)
	(via
		(at 179.365656 -99.858322)
		(size 0.5588)
		(drill 0.3048)
		(layers "F.Cu" "B.Cu")
		(net "P12V_STBY")
	)
	(via
		(at 486.999788 -113.77422)
		(size 0.508)
		(drill 0.254)
		(layers "F.Cu" "B.Cu")
		(net "P12V_STBY")
	)
	(via
		(at 354.8126 -105.41)
		(size 0.508)
		(drill 0.254)
		(layers "F.Cu" "B.Cu")
		(net "P12V_STBY")
	)
	(via
		(at 185.952892 -139.7)
		(size 0.508)
		(drill 0.254)
		(layers "F.Cu" "B.Cu")
		(net "P12V_STBY")
	)
	(via
		(at 486.3338 -110.6424)
		(size 0.508)
		(drill 0.254)
		(layers "F.Cu" "B.Cu")
		(net "P12V_STBY")
	)
	(via
		(at 23.7236 -65.1002)
		(size 0.5588)
		(drill 0.3048)
		(layers "F.Cu" "B.Cu")
		(net "P12V_STBY")
	)
	(via
		(at 494.45418 -21.682202)
		(size 0.508)
		(drill 0.254)
		(layers "F.Cu" "B.Cu")
		(net "P12V_STBY")
	)
	(via
		(at 178.604926 -100.580444)
		(size 0.5588)
		(drill 0.3048)
		(layers "F.Cu" "B.Cu")
		(net "P12V_STBY")
	)
	(via
		(at 355.529134 -136.527286)
		(size 0.508)
		(drill 0.254)
		(layers "F.Cu" "B.Cu")
		(net "P12V_STBY")
	)
	(via
		(at 357.62184 -23.8252)
		(size 0.508)
		(drill 0.254)
		(layers "F.Cu" "B.Cu")
		(net "P12V_STBY")
	)
	(via
		(at 24.4856 -57.7723)
		(size 0.5588)
		(drill 0.3048)
		(layers "F.Cu" "B.Cu")
		(net "P12V_STBY")
	)
	(via
		(at 24.384 -62.8396)
		(size 0.5588)
		(drill 0.3048)
		(layers "F.Cu" "B.Cu")
		(net "P12V_STBY")
	)
	(via
		(at 23.7236 -65.7606)
		(size 0.5588)
		(drill 0.3048)
		(layers "F.Cu" "B.Cu")
		(net "P12V_STBY")
	)
	(via
		(at 496.358926 -21.364194)
		(size 0.508)
		(drill 0.254)
		(layers "F.Cu" "B.Cu")
		(net "P12V_STBY")
	)
	(via
		(at 354.51415 -105.967022)
		(size 0.508)
		(drill 0.254)
		(layers "F.Cu" "B.Cu")
		(net "P12V_STBY")
	)
	(via
		(at 357.313484 -23.28672)
		(size 0.508)
		(drill 0.254)
		(layers "F.Cu" "B.Cu")
		(net "P12V_STBY")
	)
	(via
		(at 361.317286 -146.513042)
		(size 0.508)
		(drill 0.254)
		(layers "F.Cu" "B.Cu")
		(net "P12V_STBY")
	)
	(via
		(at 495.20094 -24.260302)
		(size 0.508)
		(drill 0.254)
		(layers "F.Cu" "B.Cu")
		(net "P12V_STBY")
	)
	(via
		(at 360.631486 -145.725642)
		(size 0.508)
		(drill 0.254)
		(layers "F.Cu" "B.Cu")
		(net "P12V_STBY")
	)
	(via
		(at 178.296062 -26.645108)
		(size 0.508)
		(drill 0.254)
		(layers "F.Cu" "B.Cu")
		(net "P12V_STBY")
	)
	(via
		(at 9.750806 -133.031992)
		(size 0.508)
		(drill 0.254)
		(layers "F.Cu" "B.Cu")
		(net "P12V_STBY")
	)
	(via
		(at 359.372154 -146.462496)
		(size 0.508)
		(drill 0.254)
		(layers "F.Cu" "B.Cu")
		(net "P12V_STBY")
	)
	(via
		(at 180.74005 -99.8601)
		(size 0.5588)
		(drill 0.3048)
		(layers "F.Cu" "B.Cu")
		(net "P12V_STBY")
	)
	(via
		(at 179.926742 -98.301048)
		(size 0.5588)
		(drill 0.3048)
		(layers "F.Cu" "B.Cu")
		(net "P12V_STBY")
	)
	(via
		(at 179.240942 -98.301048)
		(size 0.5588)
		(drill 0.3048)
		(layers "F.Cu" "B.Cu")
		(net "P12V_STBY")
	)
	(via
		(at 0.594106 -113.200942)
		(size 0.5588)
		(drill 0.3048)
		(layers "F.Cu" "B.Cu")
		(net "P12V_STBY")
	)
	(via
		(at 175.2854 -23.6728)
		(size 0.508)
		(drill 0.254)
		(layers "F.Cu" "B.Cu")
		(net "P12V_STBY")
	)
	(via
		(at 332.7654 -114.935)
		(size 0.508)
		(drill 0.254)
		(layers "F.Cu" "B.Cu")
		(net "P12V_STBY")
	)
	(via
		(at 22.4028 -62.8396)
		(size 0.5588)
		(drill 0.3048)
		(layers "F.Cu" "B.Cu")
		(net "P12V_STBY")
	)
	(via
		(at 384.650488 -63.148464)
		(size 0.5588)
		(drill 0.3048)
		(layers "F.Cu" "B.Cu")
		(net "P12V_STBY")
	)
	(via
		(at 336.5754 -114.935)
		(size 0.508)
		(drill 0.254)
		(layers "F.Cu" "B.Cu")
		(net "P12V_STBY")
	)
	(via
		(at 495.11458 -22.317202)
		(size 0.508)
		(drill 0.254)
		(layers "F.Cu" "B.Cu")
		(net "P12V_STBY")
	)
	(via
		(at 483.788212 -23.83663)
		(size 0.5588)
		(drill 0.3048)
		(layers "F.Cu" "B.Cu")
		(net "P12V_STBY")
	)
	(via
		(at 0.281432 -115.793266)
		(size 0.5588)
		(drill 0.3048)
		(layers "F.Cu" "B.Cu")
		(net "P12V_STBY")
	)
	(via
		(at 22.97176 -126.18974)
		(size 0.5588)
		(drill 0.3048)
		(layers "F.Cu" "B.Cu")
		(net "P12V_STBY")
	)
	(via
		(at 161.281618 -119.58066)
		(size 0.508)
		(drill 0.254)
		(layers "F.Cu" "B.Cu")
		(net "P12V_STBY")
	)
	(via
		(at 24.384 -63.6016)
		(size 0.5588)
		(drill 0.3048)
		(layers "F.Cu" "B.Cu")
		(net "P12V_STBY")
	)
	(via
		(at 356.429056 -20.828)
		(size 0.508)
		(drill 0.254)
		(layers "F.Cu" "B.Cu")
		(net "P12V_STBY")
	)
	(via
		(at 190.125096 -126.917196)
		(size 0.508)
		(drill 0.254)
		(layers "F.Cu" "B.Cu")
		(net "P12V_STBY")
	)
	(via
		(at 22.4028 -65.7606)
		(size 0.5588)
		(drill 0.3048)
		(layers "F.Cu" "B.Cu")
		(net "P12V_STBY")
	)
	(via
		(at 22.4028 -64.3636)
		(size 0.5588)
		(drill 0.3048)
		(layers "F.Cu" "B.Cu")
		(net "P12V_STBY")
	)
	(via
		(at 353.4918 -32.7533)
		(size 0.508)
		(drill 0.254)
		(layers "F.Cu" "B.Cu")
		(net "P12V_STBY")
	)
	(via
		(at 357.191056 -20.828)
		(size 0.508)
		(drill 0.254)
		(layers "F.Cu" "B.Cu")
		(net "P12V_STBY")
	)
	(via
		(at 1.458722 -112.84585)
		(size 0.5588)
		(drill 0.3048)
		(layers "F.Cu" "B.Cu")
		(net "P12V_STBY")
	)
	(via
		(at 331.4954 -116.205)
		(size 0.508)
		(drill 0.254)
		(layers "F.Cu" "B.Cu")
		(net "P12V_STBY")
	)
	(via
		(at 422.033446 -114.617754)
		(size 0.508)
		(drill 0.254)
		(layers "F.Cu" "B.Cu")
		(net "P12V_STBY")
	)
	(via
		(at 11.1887 -128.113282)
		(size 0.508)
		(drill 0.254)
		(layers "F.Cu" "B.Cu")
		(net "P12V_STBY")
	)
	(via
		(at 176.8094 -26.0858)
		(size 0.508)
		(drill 0.254)
		(layers "F.Cu" "B.Cu")
		(net "P12V_STBY")
	)
	(via
		(at 176.392586 -26.767028)
		(size 0.508)
		(drill 0.254)
		(layers "F.Cu" "B.Cu")
		(net "P12V_STBY")
	)
	(via
		(at -1.50622 -20.156932)
		(size 0.508)
		(drill 0.254)
		(layers "F.Cu" "B.Cu")
		(net "P12V_STBY")
	)
	(via
		(at 25.146 -59.2963)
		(size 0.5588)
		(drill 0.3048)
		(layers "F.Cu" "B.Cu")
		(net "P12V_STBY")
	)
	(via
		(at -2.174748 -20.156932)
		(size 0.508)
		(drill 0.254)
		(layers "F.Cu" "B.Cu")
		(net "P12V_STBY")
	)
	(via
		(at 359.344722 -145.634202)
		(size 0.508)
		(drill 0.254)
		(layers "F.Cu" "B.Cu")
		(net "P12V_STBY")
	)
	(via
		(at -2.238248 -21.414232)
		(size 0.508)
		(drill 0.254)
		(layers "F.Cu" "B.Cu")
		(net "P12V_STBY")
	)
	(via
		(at 336.5754 -116.205)
		(size 0.508)
		(drill 0.254)
		(layers "F.Cu" "B.Cu")
		(net "P12V_STBY")
	)
	(via
		(at 188.855096 -127.552196)
		(size 0.508)
		(drill 0.254)
		(layers "F.Cu" "B.Cu")
		(net "P12V_STBY")
	)
	(via
		(at 29.891228 -33.118298)
		(size 0.508)
		(drill 0.254)
		(layers "F.Cu" "B.Cu")
		(net "P12V_STBY")
	)
	(via
		(at -1.501648 -21.401532)
		(size 0.508)
		(drill 0.254)
		(layers "F.Cu" "B.Cu")
		(net "P12V_STBY")
	)
	(via
		(at 30.509718 -33.74771)
		(size 0.508)
		(drill 0.254)
		(layers "F.Cu" "B.Cu")
		(net "P12V_STBY")
	)
	(via
		(at 25.0444 -65.1002)
		(size 0.5588)
		(drill 0.3048)
		(layers "F.Cu" "B.Cu")
		(net "P12V_STBY")
	)
	(via
		(at 177.873914 -99.729798)
		(size 0.5588)
		(drill 0.3048)
		(layers "F.Cu" "B.Cu")
		(net "P12V_STBY")
	)
	(via
		(at -3.581908 -20.156932)
		(size 0.508)
		(drill 0.254)
		(layers "F.Cu" "B.Cu")
		(net "P12V_STBY")
	)
	(via
		(at 352.2472 -137.541)
		(size 0.508)
		(drill 0.254)
		(layers "F.Cu" "B.Cu")
		(net "P12V_STBY")
	)
	(via
		(at 22.465538 -56.168544)
		(size 0.7112)
		(drill 0.4064)
		(layers "F.Cu" "B.Cu")
		(net "P12V_STBY")
	)
	(via
		(at -2.174748 -20.791932)
		(size 0.508)
		(drill 0.254)
		(layers "F.Cu" "B.Cu")
		(net "P12V_STBY")
	)
	(via
		(at 177.899314 -98.993198)
		(size 0.5588)
		(drill 0.3048)
		(layers "F.Cu" "B.Cu")
		(net "P12V_STBY")
	)
	(via
		(at 494.42878 -23.587202)
		(size 0.508)
		(drill 0.254)
		(layers "F.Cu" "B.Cu")
		(net "P12V_STBY")
	)
	(via
		(at -0.066294 -113.200942)
		(size 0.5588)
		(drill 0.3048)
		(layers "F.Cu" "B.Cu")
		(net "P12V_STBY")
	)
	(via
		(at 23.0632 -62.8396)
		(size 0.5588)
		(drill 0.3048)
		(layers "F.Cu" "B.Cu")
		(net "P12V_STBY")
	)
	(via
		(at 180.637942 -98.301048)
		(size 0.5588)
		(drill 0.3048)
		(layers "F.Cu" "B.Cu")
		(net "P12V_STBY")
	)
	(via
		(at 481.674932 -151.19477)
		(size 0.508)
		(drill 0.254)
		(layers "F.Cu" "B.Cu")
		(net "P12V_STBY")
	)
	(via
		(at 495.08918 -23.587202)
		(size 0.508)
		(drill 0.254)
		(layers "F.Cu" "B.Cu")
		(net "P12V_STBY")
	)
	(via
		(at 20.17014 -84.235544)
		(size 0.508)
		(drill 0.254)
		(layers "F.Cu" "B.Cu")
		(net "P12V_STBY")
	)
	(via
		(at 10.188194 -132.238242)
		(size 0.508)
		(drill 0.254)
		(layers "F.Cu" "B.Cu")
		(net "P12V_STBY")
	)
	(via
		(at 22.95906 -124.86894)
		(size 0.5588)
		(drill 0.3048)
		(layers "F.Cu" "B.Cu")
		(net "P12V_STBY")
	)
	(via
		(at 331.4954 -114.935)
		(size 0.508)
		(drill 0.254)
		(layers "F.Cu" "B.Cu")
		(net "P12V_STBY")
	)
	(via
		(at 185.952892 -141.224)
		(size 0.508)
		(drill 0.254)
		(layers "F.Cu" "B.Cu")
		(net "P12V_STBY")
	)
	(via
		(at 25.0444 -62.8396)
		(size 0.5588)
		(drill 0.3048)
		(layers "F.Cu" "B.Cu")
		(net "P12V_STBY")
	)
	(via
		(at 153.879804 -120.242076)
		(size 0.508)
		(drill 0.254)
		(layers "F.Cu" "B.Cu")
		(net "P12V_STBY")
	)
	(via
		(at 25.146 -57.7723)
		(size 0.5588)
		(drill 0.3048)
		(layers "F.Cu" "B.Cu")
		(net "P12V_STBY")
	)
	(via
		(at 495.74958 -21.682202)
		(size 0.508)
		(drill 0.254)
		(layers "F.Cu" "B.Cu")
		(net "P12V_STBY")
	)
	(via
		(at -0.066294 -113.861342)
		(size 0.5588)
		(drill 0.3048)
		(layers "F.Cu" "B.Cu")
		(net "P12V_STBY")
	)
	(via
		(at 25.0444 -64.3636)
		(size 0.5588)
		(drill 0.3048)
		(layers "F.Cu" "B.Cu")
		(net "P12V_STBY")
	)
	(via
		(at 24.4856 -60.0583)
		(size 0.5588)
		(drill 0.3048)
		(layers "F.Cu" "B.Cu")
		(net "P12V_STBY")
	)
	(via
		(at 168.193974 -121.703846)
		(size 0.508)
		(drill 0.254)
		(layers "F.Cu" "B.Cu")
		(net "P12V_STBY")
	)
	(via
		(at 23.1648 -58.5343)
		(size 0.5588)
		(drill 0.3048)
		(layers "F.Cu" "B.Cu")
		(net "P12V_STBY")
	)
	(via
		(at 353.4918 -31.2293)
		(size 0.508)
		(drill 0.254)
		(layers "F.Cu" "B.Cu")
		(net "P12V_STBY")
	)
	(via
		(at 334.0354 -114.935)
		(size 0.508)
		(drill 0.254)
		(layers "F.Cu" "B.Cu")
		(net "P12V_STBY")
	)
	(via
		(at 23.1648 -60.0583)
		(size 0.5588)
		(drill 0.3048)
		(layers "F.Cu" "B.Cu")
		(net "P12V_STBY")
	)
	(via
		(at 495.74958 -22.317202)
		(size 0.508)
		(drill 0.254)
		(layers "F.Cu" "B.Cu")
		(net "P12V_STBY")
	)
	(via
		(at 185.758328 -16.205454)
		(size 0.508)
		(drill 0.254)
		(layers "F.Cu" "B.Cu")
		(net "P12V_STBY")
	)
	(via
		(at 24.327358 -125.530102)
		(size 0.5588)
		(drill 0.3048)
		(layers "F.Cu" "B.Cu")
		(net "P12V_STBY")
	)
	(via
		(at 175.71974 -26.80716)
		(size 0.508)
		(drill 0.254)
		(layers "F.Cu" "B.Cu")
		(net "P12V_STBY")
	)
	(via
		(at 180.74005 -99.0981)
		(size 0.5588)
		(drill 0.3048)
		(layers "F.Cu" "B.Cu")
		(net "P12V_STBY")
	)
	(via
		(at 354.2538 -32.7533)
		(size 0.508)
		(drill 0.254)
		(layers "F.Cu" "B.Cu")
		(net "P12V_STBY")
	)
	(via
		(at -0.066294 -114.521742)
		(size 0.5588)
		(drill 0.3048)
		(layers "F.Cu" "B.Cu")
		(net "P12V_STBY")
	)
	(via
		(at 356.907846 -23.794466)
		(size 0.508)
		(drill 0.254)
		(layers "F.Cu" "B.Cu")
		(net "P12V_STBY")
	)
	(via
		(at 332.7654 -116.205)
		(size 0.508)
		(drill 0.254)
		(layers "F.Cu" "B.Cu")
		(net "P12V_STBY")
	)
	(via
		(at 25.0444 -62.0776)
		(size 0.5588)
		(drill 0.3048)
		(layers "F.Cu" "B.Cu")
		(net "P12V_STBY")
	)
	(via
		(at 22.5044 -58.5343)
		(size 0.5588)
		(drill 0.3048)
		(layers "F.Cu" "B.Cu")
		(net "P12V_STBY")
	)
	(via
		(at 384.64998 -62.488064)
		(size 0.5588)
		(drill 0.3048)
		(layers "F.Cu" "B.Cu")
		(net "P12V_STBY")
	)
	(via
		(at 178.555142 -98.301048)
		(size 0.5588)
		(drill 0.3048)
		(layers "F.Cu" "B.Cu")
		(net "P12V_STBY")
	)
	(via
		(at 487.799888 -113.77422)
		(size 0.508)
		(drill 0.254)
		(layers "F.Cu" "B.Cu")
		(net "P12V_STBY")
	)
	(via
		(at 23.7236 -63.6016)
		(size 0.5588)
		(drill 0.3048)
		(layers "F.Cu" "B.Cu")
		(net "P12V_STBY")
	)
	(via
		(at 487.8578 -110.6424)
		(size 0.508)
		(drill 0.254)
		(layers "F.Cu" "B.Cu")
		(net "P12V_STBY")
	)
	(via
		(at 179.365656 -100.620322)
		(size 0.5588)
		(drill 0.3048)
		(layers "F.Cu" "B.Cu")
		(net "P12V_STBY")
	)
	(via
		(at 22.5044 -59.2963)
		(size 0.5588)
		(drill 0.3048)
		(layers "F.Cu" "B.Cu")
		(net "P12V_STBY")
	)
	(via
		(at 167.58158 -121.703846)
		(size 0.508)
		(drill 0.254)
		(layers "F.Cu" "B.Cu")
		(net "P12V_STBY")
	)
	(via
		(at 495.72418 -23.587202)
		(size 0.508)
		(drill 0.254)
		(layers "F.Cu" "B.Cu")
		(net "P12V_STBY")
	)
	(via
		(at 441.452 -63.5)
		(size 0.5588)
		(drill 0.3048)
		(layers "F.Cu" "B.Cu")
		(net "P12V_STBY")
	)
	(via
		(at 23.63216 -126.18974)
		(size 0.5588)
		(drill 0.3048)
		(layers "F.Cu" "B.Cu")
		(net "P12V_STBY")
	)
	(via
		(at 335.3054 -114.935)
		(size 0.508)
		(drill 0.254)
		(layers "F.Cu" "B.Cu")
		(net "P12V_STBY")
	)
	(via
		(at 182.510684 -127.071882)
		(size 0.508)
		(drill 0.254)
		(layers "F.Cu" "B.Cu")
		(net "P12V_STBY")
	)
	(via
		(at 23.273004 -54.702456)
		(size 0.7112)
		(drill 0.4064)
		(layers "F.Cu" "B.Cu")
		(net "P12V_STBY")
	)
	(via
		(at 487.0958 -110.6424)
		(size 0.508)
		(drill 0.254)
		(layers "F.Cu" "B.Cu")
		(net "P12V_STBY")
	)
	(via
		(at 22.29866 -125.52934)
		(size 0.5588)
		(drill 0.3048)
		(layers "F.Cu" "B.Cu")
		(net "P12V_STBY")
	)
	(via
		(at 23.7236 -62.8396)
		(size 0.5588)
		(drill 0.3048)
		(layers "F.Cu" "B.Cu")
		(net "P12V_STBY")
	)
	(via
		(at 401.38985 -25.664414)
		(size 0.508)
		(drill 0.254)
		(layers "F.Cu" "B.Cu")
		(net "P12V_STBY")
	)
	(via
		(at 24.384 -65.1002)
		(size 0.5588)
		(drill 0.3048)
		(layers "F.Cu" "B.Cu")
		(net "P12V_STBY")
	)
	(via
		(at 177.916332 -100.457762)
		(size 0.5588)
		(drill 0.3048)
		(layers "F.Cu" "B.Cu")
		(net "P12V_STBY")
	)
	(via
		(at 22.235668 -53.350922)
		(size 0.7112)
		(drill 0.4064)
		(layers "F.Cu" "B.Cu")
		(net "P12V_STBY")
	)
	(via
		(at 178.922426 -26.529792)
		(size 0.508)
		(drill 0.254)
		(layers "F.Cu" "B.Cu")
		(net "P12V_STBY")
	)
	(via
		(at 442.214 -63.5)
		(size 0.5588)
		(drill 0.3048)
		(layers "F.Cu" "B.Cu")
		(net "P12V_STBY")
	)
	(via
		(at 438.0992 -53.6702)
		(size 0.5588)
		(drill 0.3048)
		(layers "F.Cu" "B.Cu")
		(net "P12V_STBY")
	)
	(via
		(at 24.384 -65.7606)
		(size 0.5588)
		(drill 0.3048)
		(layers "F.Cu" "B.Cu")
		(net "P12V_STBY")
	)
	(via
		(at 361.317286 -145.751042)
		(size 0.508)
		(drill 0.254)
		(layers "F.Cu" "B.Cu")
		(net "P12V_STBY")
	)
	(via
		(at 21.629624 -54.044596)
		(size 0.7112)
		(drill 0.4064)
		(layers "F.Cu" "B.Cu")
		(net "P12V_STBY")
	)
	(via
		(at 400.293586 -21.386292)
		(size 0.508)
		(drill 0.254)
		(layers "F.Cu" "B.Cu")
		(net "P12V_STBY")
	)
	(via
		(at 438.8104 -53.6702)
		(size 0.5588)
		(drill 0.3048)
		(layers "F.Cu" "B.Cu")
		(net "P12V_STBY")
	)
	(via
		(at 10.585958 3.65506)
		(size 0.508)
		(drill 0.254)
		(layers "F.Cu" "B.Cu")
		(net "P12V_STBY")
	)
	(via
		(at 25.146 -60.0583)
		(size 0.5588)
		(drill 0.3048)
		(layers "F.Cu" "B.Cu")
		(net "P12V_STBY")
	)
	(via
		(at 21.637752 -56.220614)
		(size 0.7112)
		(drill 0.4064)
		(layers "F.Cu" "B.Cu")
		(net "P12V_STBY")
	)
	(via
		(at 177.4444 -26.0604)
		(size 0.508)
		(drill 0.254)
		(layers "F.Cu" "B.Cu")
		(net "P12V_STBY")
	)
	(via
		(at 359.982008 -145.66138)
		(size 0.508)
		(drill 0.254)
		(layers "F.Cu" "B.Cu")
		(net "P12V_STBY")
	)
	(via
		(at 23.319486 -56.136286)
		(size 0.7112)
		(drill 0.4064)
		(layers "F.Cu" "B.Cu")
		(net "P12V_STBY")
	)
	(via
		(at 25.0444 -63.6016)
		(size 0.5588)
		(drill 0.3048)
		(layers "F.Cu" "B.Cu")
		(net "P12V_STBY")
	)
	(via
		(at 10.666222 -132.94995)
		(size 0.508)
		(drill 0.254)
		(layers "F.Cu" "B.Cu")
		(net "P12V_STBY")
	)
	(via
		(at 22.31136 -126.18974)
		(size 0.5588)
		(drill 0.3048)
		(layers "F.Cu" "B.Cu")
		(net "P12V_STBY")
	)
	(via
		(at 179.926742 -97.640648)
		(size 0.5588)
		(drill 0.3048)
		(layers "F.Cu" "B.Cu")
		(net "P12V_STBY")
	)
	(via
		(at 4.318 -120.777)
		(size 0.508)
		(drill 0.254)
		(layers "F.Cu" "B.Cu")
		(net "P12V_STBY")
	)
	(via
		(at 23.63216 -126.85014)
		(size 0.5588)
		(drill 0.3048)
		(layers "F.Cu" "B.Cu")
		(net "P12V_STBY")
	)
	(via
		(at 23.0632 -65.7606)
		(size 0.5588)
		(drill 0.3048)
		(layers "F.Cu" "B.Cu")
		(net "P12V_STBY")
	)
	(via
		(at 354.2538 -31.9913)
		(size 0.508)
		(drill 0.254)
		(layers "F.Cu" "B.Cu")
		(net "P12V_STBY")
	)
	(via
		(at 23.8252 -57.7723)
		(size 0.5588)
		(drill 0.3048)
		(layers "F.Cu" "B.Cu")
		(net "P12V_STBY")
	)
	(via
		(at 13.5636 -75.7174)
		(size 0.508)
		(drill 0.254)
		(layers "F.Cu" "B.Cu")
		(net "P12V_STBY")
	)
	(via
		(at -2.908808 -20.144232)
		(size 0.508)
		(drill 0.254)
		(layers "F.Cu" "B.Cu")
		(net "P12V_STBY")
	)
	(via
		(at 30.515052 -33.123632)
		(size 0.508)
		(drill 0.254)
		(layers "F.Cu" "B.Cu")
		(net "P12V_STBY")
	)
	(via
		(at 153.879804 -120.877076)
		(size 0.508)
		(drill 0.254)
		(layers "F.Cu" "B.Cu")
		(net "P12V_STBY")
	)
	(via
		(at 1.458722 -113.50625)
		(size 0.5588)
		(drill 0.3048)
		(layers "F.Cu" "B.Cu")
		(net "P12V_STBY")
	)
	(via
		(at 22.29866 -124.86894)
		(size 0.5588)
		(drill 0.3048)
		(layers "F.Cu" "B.Cu")
		(net "P12V_STBY")
	)
	(via
		(at 23.8252 -58.5343)
		(size 0.5588)
		(drill 0.3048)
		(layers "F.Cu" "B.Cu")
		(net "P12V_STBY")
	)
	(via
		(at 166.935658 -121.695464)
		(size 0.508)
		(drill 0.254)
		(layers "F.Cu" "B.Cu")
		(net "P12V_STBY")
	)
	(via
		(at 349.354648 -23.414228)
		(size 0.508)
		(drill 0.254)
		(layers "F.Cu" "B.Cu")
		(net "P12V_STBY")
	)
	(via
		(at 188.855096 -126.917196)
		(size 0.508)
		(drill 0.254)
		(layers "F.Cu" "B.Cu")
		(net "P12V_STBY")
	)
	(via
		(at 9.5504 -128.8796)
		(size 0.508)
		(drill 0.254)
		(layers "F.Cu" "B.Cu")
		(net "P12V_STBY")
	)
	(via
		(at 153.722324 -122.755914)
		(size 0.508)
		(drill 0.254)
		(layers "F.Cu" "B.Cu")
		(net "P12V_STBY")
	)
	(via
		(at 352.2472 -136.0424)
		(size 0.508)
		(drill 0.254)
		(layers "F.Cu" "B.Cu")
		(net "P12V_STBY")
	)
	(via
		(at 185.952892 -140.462)
		(size 0.508)
		(drill 0.254)
		(layers "F.Cu" "B.Cu")
		(net "P12V_STBY")
	)
	(via
		(at 177.851816 -97.53854)
		(size 0.5588)
		(drill 0.3048)
		(layers "F.Cu" "B.Cu")
		(net "P12V_STBY")
	)
	(via
		(at 359.344976 -144.983454)
		(size 0.508)
		(drill 0.254)
		(layers "F.Cu" "B.Cu")
		(net "P12V_STBY")
	)
	(via
		(at 180.637942 -97.615248)
		(size 0.5588)
		(drill 0.3048)
		(layers "F.Cu" "B.Cu")
		(net "P12V_STBY")
	)
	(via
		(at 24.95296 -126.85014)
		(size 0.5588)
		(drill 0.3048)
		(layers "F.Cu" "B.Cu")
		(net "P12V_STBY")
	)
	(via
		(at 185.3057 -140.462)
		(size 0.508)
		(drill 0.254)
		(layers "F.Cu" "B.Cu")
		(net "P12V_STBY")
	)
	(via
		(at 22.704044 -54.036976)
		(size 0.7112)
		(drill 0.4064)
		(layers "F.Cu" "B.Cu")
		(net "P12V_STBY")
	)
	(via
		(at 24.4856 -58.5343)
		(size 0.5588)
		(drill 0.3048)
		(layers "F.Cu" "B.Cu")
		(net "P12V_STBY")
	)
	(via
		(at 188.844682 -125.205998)
		(size 0.508)
		(drill 0.254)
		(layers "F.Cu" "B.Cu")
		(net "P12V_STBY")
	)
	(via
		(at 161.835592 -120.093486)
		(size 0.508)
		(drill 0.254)
		(layers "F.Cu" "B.Cu")
		(net "P12V_STBY")
	)
	(via
		(at 153.733246 -122.146314)
		(size 0.508)
		(drill 0.254)
		(layers "F.Cu" "B.Cu")
		(net "P12V_STBY")
	)
	(via
		(at 360.631486 -144.963642)
		(size 0.508)
		(drill 0.254)
		(layers "F.Cu" "B.Cu")
		(net "P12V_STBY")
	)
	(via
		(at 357.953056 -20.828)
		(size 0.508)
		(drill 0.254)
		(layers "F.Cu" "B.Cu")
		(net "P12V_STBY")
	)
	(via
		(at 356.860856 -20.2438)
		(size 0.508)
		(drill 0.254)
		(layers "F.Cu" "B.Cu")
		(net "P12V_STBY")
	)
	(via
		(at 22.5044 -57.7723)
		(size 0.5588)
		(drill 0.3048)
		(layers "F.Cu" "B.Cu")
		(net "P12V_STBY")
	)
	(via
		(at 177.6476 -26.68524)
		(size 0.508)
		(drill 0.254)
		(layers "F.Cu" "B.Cu")
		(net "P12V_STBY")
	)
	(via
		(at 359.964228 -144.960594)
		(size 0.508)
		(drill 0.254)
		(layers "F.Cu" "B.Cu")
		(net "P12V_STBY")
	)
	(via
		(at 190.125096 -127.552196)
		(size 0.508)
		(drill 0.254)
		(layers "F.Cu" "B.Cu")
		(net "P12V_STBY")
	)
	(via
		(at 497.050314 -23.498302)
		(size 0.508)
		(drill 0.254)
		(layers "F.Cu" "B.Cu")
		(net "P12V_STBY")
	)
	(via
		(at 22.31136 -126.85014)
		(size 0.5588)
		(drill 0.3048)
		(layers "F.Cu" "B.Cu")
		(net "P12V_STBY")
	)
	(via
		(at 22.97176 -126.85014)
		(size 0.5588)
		(drill 0.3048)
		(layers "F.Cu" "B.Cu")
		(net "P12V_STBY")
	)
	(via
		(at 24.29256 -126.18974)
		(size 0.5588)
		(drill 0.3048)
		(layers "F.Cu" "B.Cu")
		(net "P12V_STBY")
	)
	(via
		(at 334.0354 -116.205)
		(size 0.508)
		(drill 0.254)
		(layers "F.Cu" "B.Cu")
		(net "P12V_STBY")
	)
	(via
		(at 484.7336 -25.65654)
		(size 0.5588)
		(drill 0.3048)
		(layers "F.Cu" "B.Cu")
		(net "P12V_STBY")
	)
	(via
		(at 180.74005 -100.6221)
		(size 0.5588)
		(drill 0.3048)
		(layers "F.Cu" "B.Cu")
		(net "P12V_STBY")
	)
	(via
		(at 23.0632 -64.3636)
		(size 0.5588)
		(drill 0.3048)
		(layers "F.Cu" "B.Cu")
		(net "P12V_STBY")
	)
	(via
		(at 185.735468 -16.8148)
		(size 0.508)
		(drill 0.254)
		(layers "F.Cu" "B.Cu")
		(net "P12V_STBY")
	)
	(via
		(at 177.851816 -98.19894)
		(size 0.5588)
		(drill 0.3048)
		(layers "F.Cu" "B.Cu")
		(net "P12V_STBY")
	)
	(via
		(at 495.08918 -22.952202)
		(size 0.508)
		(drill 0.254)
		(layers "F.Cu" "B.Cu")
		(net "P12V_STBY")
	)
	(via
		(at 361.317286 -144.989042)
		(size 0.508)
		(drill 0.254)
		(layers "F.Cu" "B.Cu")
		(net "P12V_STBY")
	)
	(via
		(at -1.48844 -20.791932)
		(size 0.508)
		(drill 0.254)
		(layers "F.Cu" "B.Cu")
		(net "P12V_STBY")
	)
	(via
		(at 354.2538 -31.2293)
		(size 0.508)
		(drill 0.254)
		(layers "F.Cu" "B.Cu")
		(net "P12V_STBY")
	)
	(via
		(at 354.8126 -104.775)
		(size 0.508)
		(drill 0.254)
		(layers "F.Cu" "B.Cu")
		(net "P12V_STBY")
	)
	(via
		(at 24.384 -62.0776)
		(size 0.5588)
		(drill 0.3048)
		(layers "F.Cu" "B.Cu")
		(net "P12V_STBY")
	)
	(via
		(at 22.4028 -62.0776)
		(size 0.5588)
		(drill 0.3048)
		(layers "F.Cu" "B.Cu")
		(net "P12V_STBY")
	)
	(via
		(at 185.3057 -139.7)
		(size 0.508)
		(drill 0.254)
		(layers "F.Cu" "B.Cu")
		(net "P12V_STBY")
	)
	(via
		(at 23.61946 -125.52934)
		(size 0.5588)
		(drill 0.3048)
		(layers "F.Cu" "B.Cu")
		(net "P12V_STBY")
	)
	(via
		(at 9.9568 -129.413)
		(size 0.508)
		(drill 0.254)
		(layers "F.Cu" "B.Cu")
		(net "P12V_STBY")
	)
	(via
		(at 329.661012 -125.2601)
		(size 0.508)
		(drill 0.254)
		(layers "F.Cu" "B.Cu")
		(net "P12V_STBY")
	)
	(via
		(at 180.07965 -99.866196)
		(size 0.5588)
		(drill 0.3048)
		(layers "F.Cu" "B.Cu")
		(net "P12V_STBY")
	)
	(via
		(at 21.174964 -54.768496)
		(size 0.7112)
		(drill 0.4064)
		(layers "F.Cu" "B.Cu")
		(net "P12V_STBY")
	)
	(via
		(at -0.066294 -115.182142)
		(size 0.5588)
		(drill 0.3048)
		(layers "F.Cu" "B.Cu")
		(net "P12V_STBY")
	)
	(via
		(at 351.61474 -136.02716)
		(size 0.508)
		(drill 0.254)
		(layers "F.Cu" "B.Cu")
		(net "P12V_STBY")
	)
	(via
		(at 484.486712 -23.147782)
		(size 0.5588)
		(drill 0.3048)
		(layers "F.Cu" "B.Cu")
		(net "P12V_STBY")
	)
	(via
		(at 495.83594 -24.260302)
		(size 0.508)
		(drill 0.254)
		(layers "F.Cu" "B.Cu")
		(net "P12V_STBY")
	)
	(via
		(at 403.284436 -18.027396)
		(size 0.508)
		(drill 0.254)
		(layers "F.Cu" "B.Cu")
		(net "P12V_STBY")
	)
	(via
		(at 21.336 -82.433668)
		(size 0.508)
		(drill 0.254)
		(layers "F.Cu" "B.Cu")
		(net "P12V_STBY")
	)
	(via
		(at 357.4542 -19.6342)
		(size 0.508)
		(drill 0.254)
		(layers "F.Cu" "B.Cu")
		(net "P12V_STBY")
	)
	(via
		(at 359.991152 -146.462496)
		(size 0.508)
		(drill 0.254)
		(layers "F.Cu" "B.Cu")
		(net "P12V_STBY")
	)
	(via
		(at 176.995328 -26.666444)
		(size 0.508)
		(drill 0.254)
		(layers "F.Cu" "B.Cu")
		(net "P12V_STBY")
	)
	(via
		(at 23.0632 -63.6016)
		(size 0.5588)
		(drill 0.3048)
		(layers "F.Cu" "B.Cu")
		(net "P12V_STBY")
	)
	(via
		(at 22.4028 -63.6016)
		(size 0.5588)
		(drill 0.3048)
		(layers "F.Cu" "B.Cu")
		(net "P12V_STBY")
	)
	(via
		(at 440.69 -63.5)
		(size 0.5588)
		(drill 0.3048)
		(layers "F.Cu" "B.Cu")
		(net "P12V_STBY")
	)
	(via
		(at 496.534694 -24.171402)
		(size 0.508)
		(drill 0.254)
		(layers "F.Cu" "B.Cu")
		(net "P12V_STBY")
	)
	(via
		(at 179.365656 -99.096322)
		(size 0.5588)
		(drill 0.3048)
		(layers "F.Cu" "B.Cu")
		(net "P12V_STBY")
	)
	(via
		(at 8.0772 -129.6924)
		(size 0.508)
		(drill 0.254)
		(layers "F.Cu" "B.Cu")
		(net "P12V_STBY")
	)
	(via
		(at 23.1648 -59.2963)
		(size 0.5588)
		(drill 0.3048)
		(layers "F.Cu" "B.Cu")
		(net "P12V_STBY")
	)
	(via
		(at 29.883608 -33.729168)
		(size 0.508)
		(drill 0.254)
		(layers "F.Cu" "B.Cu")
		(net "P12V_STBY")
	)
	(via
		(at 483.804468 -24.524208)
		(size 0.5588)
		(drill 0.3048)
		(layers "F.Cu" "B.Cu")
		(net "P12V_STBY")
	)
	(via
		(at 352.2472 -136.779)
		(size 0.508)
		(drill 0.254)
		(layers "F.Cu" "B.Cu")
		(net "P12V_STBY")
	)
	(via
		(at 24.29256 -126.85014)
		(size 0.5588)
		(drill 0.3048)
		(layers "F.Cu" "B.Cu")
		(net "P12V_STBY")
	)
	(via
		(at -4.216908 -20.791932)
		(size 0.508)
		(drill 0.254)
		(layers "F.Cu" "B.Cu")
		(net "P12V_STBY")
	)
	(via
		(at 486.199942 -113.8428)
		(size 0.508)
		(drill 0.254)
		(layers "F.Cu" "B.Cu")
		(net "P12V_STBY")
	)
	(via
		(at 28.616656 -32.71393)
		(size 0.508)
		(drill 0.254)
		(layers "F.Cu" "B.Cu")
		(net "P12V_STBY")
	)
	(via
		(at -3.581908 -20.791932)
		(size 0.508)
		(drill 0.254)
		(layers "F.Cu" "B.Cu")
		(net "P12V_STBY")
	)
	(via
		(at 186.345068 -16.801084)
		(size 0.508)
		(drill 0.254)
		(layers "F.Cu" "B.Cu")
		(net "P12V_STBY")
	)
	(via
		(at 180.07965 -99.104196)
		(size 0.5588)
		(drill 0.3048)
		(layers "F.Cu" "B.Cu")
		(net "P12V_STBY")
	)
	(via
		(at 337.8454 -116.205)
		(size 0.508)
		(drill 0.254)
		(layers "F.Cu" "B.Cu")
		(net "P12V_STBY")
	)
	(via
		(at 25.0444 -65.7606)
		(size 0.5588)
		(drill 0.3048)
		(layers "F.Cu" "B.Cu")
		(net "P12V_STBY")
	)
	(via
		(at 178.555142 -97.640648)
		(size 0.5588)
		(drill 0.3048)
		(layers "F.Cu" "B.Cu")
		(net "P12V_STBY")
	)
	(via
		(at 24.16556 -56.120284)
		(size 0.7112)
		(drill 0.4064)
		(layers "F.Cu" "B.Cu")
		(net "P12V_STBY")
	)
	(via
		(at 186.367928 -16.191738)
		(size 0.508)
		(drill 0.254)
		(layers "F.Cu" "B.Cu")
		(net "P12V_STBY")
	)
	(via
		(at 176.1744 -26.1874)
		(size 0.508)
		(drill 0.254)
		(layers "F.Cu" "B.Cu")
		(net "P12V_STBY")
	)
	(via
		(at 22.5044 -60.0583)
		(size 0.5588)
		(drill 0.3048)
		(layers "F.Cu" "B.Cu")
		(net "P12V_STBY")
	)
	(via
		(at 484.47579 -23.857204)
		(size 0.5588)
		(drill 0.3048)
		(layers "F.Cu" "B.Cu")
		(net "P12V_STBY")
	)
	(via
		(at 354.0506 -104.775)
		(size 0.508)
		(drill 0.254)
		(layers "F.Cu" "B.Cu")
		(net "P12V_STBY")
	)
	(via
		(at 23.8252 -60.0583)
		(size 0.5588)
		(drill 0.3048)
		(layers "F.Cu" "B.Cu")
		(net "P12V_STBY")
	)
	(via
		(at 179.240942 -97.640648)
		(size 0.5588)
		(drill 0.3048)
		(layers "F.Cu" "B.Cu")
		(net "P12V_STBY")
	)
	(via
		(at 384.650488 -61.813694)
		(size 0.5588)
		(drill 0.3048)
		(layers "F.Cu" "B.Cu")
		(net "P12V_STBY")
	)
	(via
		(at 23.0632 -65.1002)
		(size 0.5588)
		(drill 0.3048)
		(layers "F.Cu" "B.Cu")
		(net "P12V_STBY")
	)
	(via
		(at 25.146 -58.5343)
		(size 0.5588)
		(drill 0.3048)
		(layers "F.Cu" "B.Cu")
		(net "P12V_STBY")
	)
	(via
		(at 24.4856 -59.2963)
		(size 0.5588)
		(drill 0.3048)
		(layers "F.Cu" "B.Cu")
		(net "P12V_STBY")
	)
	(via
		(at 497.169694 -24.171402)
		(size 0.508)
		(drill 0.254)
		(layers "F.Cu" "B.Cu")
		(net "P12V_STBY")
	)
	(via
		(at 23.1648 -57.7723)
		(size 0.5588)
		(drill 0.3048)
		(layers "F.Cu" "B.Cu")
		(net "P12V_STBY")
	)
	(via
		(at 9.069578 -129.29997)
		(size 0.508)
		(drill 0.254)
		(layers "F.Cu" "B.Cu")
		(net "P12V_STBY")
	)
	(via
		(at 23.7236 -62.0776)
		(size 0.5588)
		(drill 0.3048)
		(layers "F.Cu" "B.Cu")
		(net "P12V_STBY")
	)
	(via
		(at 351.61474 -136.78916)
		(size 0.508)
		(drill 0.254)
		(layers "F.Cu" "B.Cu")
		(net "P12V_STBY")
	)
	(via
		(at 22.95906 -125.52934)
		(size 0.5588)
		(drill 0.3048)
		(layers "F.Cu" "B.Cu")
		(net "P12V_STBY")
	)
	(via
		(at 357.622856 -20.2438)
		(size 0.508)
		(drill 0.254)
		(layers "F.Cu" "B.Cu")
		(net "P12V_STBY")
	)
	(via
		(at 23.0632 -62.0776)
		(size 0.5588)
		(drill 0.3048)
		(layers "F.Cu" "B.Cu")
		(net "P12V_STBY")
	)
	(via
		(at 178.60264 -99.095306)
		(size 0.5588)
		(drill 0.3048)
		(layers "F.Cu" "B.Cu")
		(net "P12V_STBY")
	)
	(via
		(at 495.72418 -22.952202)
		(size 0.508)
		(drill 0.254)
		(layers "F.Cu" "B.Cu")
		(net "P12V_STBY")
	)
	(via
		(at 337.8454 -114.935)
		(size 0.508)
		(drill 0.254)
		(layers "F.Cu" "B.Cu")
		(net "P12V_STBY")
	)
	(via
		(at 354.0506 -105.41)
		(size 0.508)
		(drill 0.254)
		(layers "F.Cu" "B.Cu")
		(net "P12V_STBY")
	)
	(via
		(at 180.07965 -100.628196)
		(size 0.5588)
		(drill 0.3048)
		(layers "F.Cu" "B.Cu")
		(net "P12V_STBY")
	)
	(via
		(at 351.61474 -137.55116)
		(size 0.508)
		(drill 0.254)
		(layers "F.Cu" "B.Cu")
		(net "P12V_STBY")
	)
	(via
		(at 24.384 -64.3636)
		(size 0.5588)
		(drill 0.3048)
		(layers "F.Cu" "B.Cu")
		(net "P12V_STBY")
	)
	(via
		(at 332.359 -137.359136)
		(size 0.508)
		(drill 0.254)
		(layers "F.Cu" "B.Cu")
		(net "P12V_STBY")
	)
	(via
		(at 23.8252 -59.2963)
		(size 0.5588)
		(drill 0.3048)
		(layers "F.Cu" "B.Cu")
		(net "P12V_STBY")
	)
	(via
		(at 0.594106 -113.861342)
		(size 0.5588)
		(drill 0.3048)
		(layers "F.Cu" "B.Cu")
		(net "P12V_STBY")
	)
	(via
		(at 484.491792 -24.54021)
		(size 0.5588)
		(drill 0.3048)
		(layers "F.Cu" "B.Cu")
		(net "P12V_STBY")
	)
	(via
		(at 419.4175 -9.3345)
		(size 0.508)
		(drill 0.254)
		(layers "F.Cu" "B.Cu")
		(net "P12V_STBY")
	)
	(via
		(at 185.3057 -141.224)
		(size 0.508)
		(drill 0.254)
		(layers "F.Cu" "B.Cu")
		(net "P12V_STBY")
	)
	(via
		(at 353.4918 -31.9913)
		(size 0.508)
		(drill 0.254)
		(layers "F.Cu" "B.Cu")
		(net "P12V_STBY")
	)
	(via
		(at 9.398 -129.8448)
		(size 0.508)
		(drill 0.254)
		(layers "F.Cu" "B.Cu")
		(net "P12V_STBY")
	)
	(via
		(at 190.736474 -126.978664)
		(size 0.508)
		(drill 0.254)
		(layers "F.Cu" "B.Cu")
		(net "P12V_STBY")
	)
	(via
		(at -4.216908 -20.156932)
		(size 0.508)
		(drill 0.254)
		(layers "F.Cu" "B.Cu")
		(net "P12V_STBY")
	)
	(via
		(at 186.3344 -17.410684)
		(size 0.508)
		(drill 0.254)
		(layers "F.Cu" "B.Cu")
		(net "P12V_STBY")
	)
	(via
		(at 2.119122 -113.50625)
		(size 0.5588)
		(drill 0.3048)
		(layers "F.Cu" "B.Cu")
		(net "P12V_STBY")
	)
	(via
		(at 189.490096 -126.917196)
		(size 0.508)
		(drill 0.254)
		(layers "F.Cu" "B.Cu")
		(net "P12V_STBY")
	)
	(via
		(at 189.490096 -127.552196)
		(size 0.508)
		(drill 0.254)
		(layers "F.Cu" "B.Cu")
		(net "P12V_STBY")
	)
	(via
		(at 22.4028 -65.1002)
		(size 0.5588)
		(drill 0.3048)
		(layers "F.Cu" "B.Cu")
		(net "P12V_STBY")
	)
	(via
		(at 495.11458 -21.682202)
		(size 0.508)
		(drill 0.254)
		(layers "F.Cu" "B.Cu")
		(net "P12V_STBY")
	)
	(via
		(at 494.45418 -22.317202)
		(size 0.508)
		(drill 0.254)
		(layers "F.Cu" "B.Cu")
		(net "P12V_STBY")
	)
	(via
		(at 0.594106 -115.182142)
		(size 0.5588)
		(drill 0.3048)
		(layers "F.Cu" "B.Cu")
		(net "P12V_STBY")
	)
	(via
		(at 496.415314 -23.498302)
		(size 0.508)
		(drill 0.254)
		(layers "F.Cu" "B.Cu")
		(net "P12V_STBY")
	)
	(via
		(at 185.7248 -17.4244)
		(size 0.508)
		(drill 0.254)
		(layers "F.Cu" "B.Cu")
		(net "P12V_STBY")
	)
	(via
		(at 358.1908 -19.6596)
		(size 0.508)
		(drill 0.254)
		(layers "F.Cu" "B.Cu")
		(net "P12V_STBY")
	)
	(via
		(at 24.95296 -126.18974)
		(size 0.5588)
		(drill 0.3048)
		(layers "F.Cu" "B.Cu")
		(net "P12V_STBY")
	)
	(via
		(at 335.3054 -116.205)
		(size 0.508)
		(drill 0.254)
		(layers "F.Cu" "B.Cu")
		(net "P12V_STBY")
	)
	(via
		(at 360.631486 -146.487642)
		(size 0.508)
		(drill 0.254)
		(layers "F.Cu" "B.Cu")
		(net "P12V_STBY")
	)
	(segment
		(start 20.17014 -84.438236)
		(end 19.636994 -84.971382)
		(width 0.254)
		(layer "B.Cu")
		(net "P12V_STBY")
	)
	(segment
		(start 10.199624 -130.9624)
		(end 10.770616 -130.391408)
		(width 0.254)
		(layer "B.Cu")
		(net "P12V_STBY")
	)
	(segment
		(start 356.38486 -136.18972)
		(end 356.047294 -136.527286)
		(width 0.254)
		(layer "B.Cu")
		(net "P12V_STBY")
	)
	(segment
		(start 10.770616 -129.221484)
		(end 11.1887 -128.8034)
		(width 0.254)
		(layer "B.Cu")
		(net "P12V_STBY")
	)
	(segment
		(start 11.9126 -74.8284)
		(end 12.192 -74.8284)
		(width 0.254)
		(layer "B.Cu")
		(net "P12V_STBY")
	)
	(segment
		(start 4.977384 -121.436384)
		(end 5.2324 -121.436384)
		(width 0.254)
		(layer "B.Cu")
		(net "P12V_STBY")
	)
	(segment
		(start 20.17014 -84.235544)
		(end 20.17014 -84.438236)
		(width 0.254)
		(layer "B.Cu")
		(net "P12V_STBY")
	)
	(segment
		(start 356.047294 -136.527286)
		(end 355.529134 -136.527286)
		(width 0.254)
		(layer "B.Cu")
		(net "P12V_STBY")
	)
	(segment
		(start 18.5674 -84.6328)
		(end 18.5674 -84.3026)
		(width 0.254)
		(layer "B.Cu")
		(net "P12V_STBY")
	)
	(segment
		(start 13.5636 -75.7174)
		(end 13.5636 -75.7428)
		(width 0.254)
		(layer "B.Cu")
		(net "P12V_STBY")
	)
	(segment
		(start 28.616656 -32.71393)
		(end 29.008832 -32.321754)
		(width 0.254)
		(layer "B.Cu")
		(net "P12V_STBY")
	)
	(segment
		(start 12.4968 -75.1332)
		(end 12.4968 -75.2856)
		(width 0.254)
		(layer "B.Cu")
		(net "P12V_STBY")
	)
	(segment
		(start 12.4968 -75.2856)
		(end 12.9286 -75.7174)
		(width 0.254)
		(layer "B.Cu")
		(net "P12V_STBY")
	)
	(segment
		(start 21.683726 -81.520792)
		(end 21.696934 -81.534)
		(width 0.254)
		(layer "B.Cu")
		(net "P12V_STBY")
	)
	(segment
		(start 12.9286 -75.7174)
		(end 13.5636 -75.7174)
		(width 0.254)
		(layer "B.Cu")
		(net "P12V_STBY")
	)
	(segment
		(start 10.941558 2.24282)
		(end 11.881358 2.24282)
		(width 0.254)
		(layer "B.Cu")
		(net "P12V_STBY")
	)
	(segment
		(start 419.1 -9.017)
		(end 418.719 -9.017)
		(width 0.254)
		(layer "B.Cu")
		(net "P12V_STBY")
	)
	(segment
		(start 401.38985 -25.664414)
		(end 401.39239 -25.664414)
		(width 0.254)
		(layer "B.Cu")
		(net "P12V_STBY")
	)
	(segment
		(start 13.9446 -76.1238)
		(end 14.224 -76.1238)
		(width 0.254)
		(layer "B.Cu")
		(net "P12V_STBY")
	)
	(segment
		(start 18.905982 -84.971382)
		(end 18.5674 -84.6328)
		(width 0.254)
		(layer "B.Cu")
		(net "P12V_STBY")
	)
	(segment
		(start 401.39239 -25.664414)
		(end 401.415504 -25.687528)
		(width 0.254)
		(layer "B.Cu")
		(net "P12V_STBY")
	)
	(segment
		(start 21.333206 -81.520792)
		(end 21.333206 -82.430874)
		(width 0.254)
		(layer "B.Cu")
		(net "P12V_STBY")
	)
	(segment
		(start 10.615422 2.568956)
		(end 10.941558 2.24282)
		(width 0.254)
		(layer "B.Cu")
		(net "P12V_STBY")
	)
	(segment
		(start 10.770616 -130.391408)
		(end 10.770616 -129.221484)
		(width 0.254)
		(layer "B.Cu")
		(net "P12V_STBY")
	)
	(segment
		(start 482.5238 -151.0284)
		(end 481.841302 -151.0284)
		(width 0.254)
		(layer "B.Cu")
		(net "P12V_STBY")
	)
	(segment
		(start 9.398 -130.9624)
		(end 10.199624 -130.9624)
		(width 0.254)
		(layer "B.Cu")
		(net "P12V_STBY")
	)
	(segment
		(start 19.636994 -84.971382)
		(end 18.905982 -84.971382)
		(width 0.254)
		(layer "B.Cu")
		(net "P12V_STBY")
	)
	(segment
		(start 21.336 -82.433668)
		(end 21.534374 -82.632042)
		(width 0.254)
		(layer "B.Cu")
		(net "P12V_STBY")
	)
	(segment
		(start 21.534374 -82.632042)
		(end 21.534374 -83.2866)
		(width 0.254)
		(layer "B.Cu")
		(net "P12V_STBY")
	)
	(segment
		(start 356.38486 -135.1915)
		(end 356.38486 -136.18972)
		(width 0.254)
		(layer "B.Cu")
		(net "P12V_STBY")
	)
	(segment
		(start 21.333206 -82.430874)
		(end 21.336 -82.433668)
		(width 0.254)
		(layer "B.Cu")
		(net "P12V_STBY")
	)
	(segment
		(start 11.1887 -128.8034)
		(end 11.1887 -128.113282)
		(width 0.254)
		(layer "B.Cu")
		(net "P12V_STBY")
	)
	(segment
		(start 10.585958 3.65506)
		(end 10.615422 3.625596)
		(width 0.254)
		(layer "B.Cu")
		(net "P12V_STBY")
	)
	(segment
		(start 401.415504 -25.72131)
		(end 401.108418 -26.028396)
		(width 0.254)
		(layer "B.Cu")
		(net "P12V_STBY")
	)
	(segment
		(start 12.192 -74.8284)
		(end 12.4968 -75.1332)
		(width 0.254)
		(layer "B.Cu")
		(net "P12V_STBY")
	)
	(segment
		(start 481.841302 -151.0284)
		(end 481.674932 -151.19477)
		(width 0.254)
		(layer "B.Cu")
		(net "P12V_STBY")
	)
	(segment
		(start 23.114 -81.534)
		(end 22.225 -81.534)
		(width 0.254)
		(layer "B.Cu")
		(net "P12V_STBY")
	)
	(segment
		(start 401.108418 -26.028396)
		(end 401.108418 -26.471372)
		(width 0.254)
		(layer "B.Cu")
		(net "P12V_STBY")
	)
	(segment
		(start 401.415504 -25.687528)
		(end 401.415504 -25.72131)
		(width 0.254)
		(layer "B.Cu")
		(net "P12V_STBY")
	)
	(segment
		(start 13.5636 -75.7428)
		(end 13.9446 -76.1238)
		(width 0.254)
		(layer "B.Cu")
		(net "P12V_STBY")
	)
	(segment
		(start 419.4175 -9.3345)
		(end 419.1 -9.017)
		(width 0.254)
		(layer "B.Cu")
		(net "P12V_STBY")
	)
	(segment
		(start 21.333206 -81.520792)
		(end 21.683726 -81.520792)
		(width 0.254)
		(layer "B.Cu")
		(net "P12V_STBY")
	)
	(segment
		(start 29.008832 -32.321754)
		(end 29.008832 -31.06674)
		(width 0.254)
		(layer "B.Cu")
		(net "P12V_STBY")
	)
	(segment
		(start 10.615422 3.625596)
		(end 10.615422 2.568956)
		(width 0.254)
		(layer "B.Cu")
		(net "P12V_STBY")
	)
	(segment
		(start 21.696934 -81.534)
		(end 22.225 -81.534)
		(width 0.254)
		(layer "B.Cu")
		(net "P12V_STBY")
	)
	(segment
		(start 4.318 -120.777)
		(end 4.977384 -121.436384)
		(width 0.254)
		(layer "B.Cu")
		(net "P12V_STBY")
	)
	(segment
		(start 22.889718 -1.341374)
		(end 24.681942 -1.341374)
		(width 0.254)
		(layer "In2.Cu")
		(net "P12V_STBY")
	)
	(segment
		(start 25.8572 -2.516632)
		(end 25.8572 -4.8514)
		(width 0.254)
		(layer "In2.Cu")
		(net "P12V_STBY")
	)
	(segment
		(start 10.585958 3.65506)
		(end 10.70102 3.539998)
		(width 0.254)
		(layer "In2.Cu")
		(net "P12V_STBY")
	)
	(segment
		(start 11.595862 2.664968)
		(end 14.484858 2.664968)
		(width 0.254)
		(layer "In2.Cu")
		(net "P12V_STBY")
	)
	(segment
		(start 14.484858 2.664968)
		(end 15.032228 2.117598)
		(width 0.254)
		(layer "In2.Cu")
		(net "P12V_STBY")
	)
	(segment
		(start 24.681942 -1.341374)
		(end 25.8572 -2.516632)
		(width 0.254)
		(layer "In2.Cu")
		(net "P12V_STBY")
	)
	(segment
		(start 15.032228 2.117598)
		(end 19.430746 2.117598)
		(width 0.254)
		(layer "In2.Cu")
		(net "P12V_STBY")
	)
	(segment
		(start 28.932378 -23.857458)
		(end 28.616656 -24.17318)
		(width 0.254)
		(layer "In2.Cu")
		(net "P12V_STBY")
	)
	(segment
		(start 10.720832 3.539998)
		(end 11.595862 2.664968)
		(width 0.254)
		(layer "In2.Cu")
		(net "P12V_STBY")
	)
	(segment
		(start 25.8572 -4.8514)
		(end 27.5336 -6.5278)
		(width 0.254)
		(layer "In2.Cu")
		(net "P12V_STBY")
	)
	(segment
		(start 27.5336 -6.5278)
		(end 27.5336 -19.290284)
		(width 0.254)
		(layer "In2.Cu")
		(net "P12V_STBY")
	)
	(segment
		(start 28.932378 -23.457154)
		(end 28.932378 -23.857458)
		(width 0.254)
		(layer "In2.Cu")
		(net "P12V_STBY")
	)
	(segment
		(start 28.616656 -20.37334)
		(end 28.616656 -23.141432)
		(width 0.254)
		(layer "In2.Cu")
		(net "P12V_STBY")
	)
	(segment
		(start 10.70102 3.539998)
		(end 10.720832 3.539998)
		(width 0.254)
		(layer "In2.Cu")
		(net "P12V_STBY")
	)
	(segment
		(start 28.616656 -23.141432)
		(end 28.932378 -23.457154)
		(width 0.254)
		(layer "In2.Cu")
		(net "P12V_STBY")
	)
	(segment
		(start 27.5336 -19.290284)
		(end 28.616656 -20.37334)
		(width 0.254)
		(layer "In2.Cu")
		(net "P12V_STBY")
	)
	(segment
		(start 28.616656 -24.17318)
		(end 28.616656 -32.71393)
		(width 0.254)
		(layer "In2.Cu")
		(net "P12V_STBY")
	)
	(segment
		(start 19.430746 2.117598)
		(end 22.889718 -1.341374)
		(width 0.254)
		(layer "In2.Cu")
		(net "P12V_STBY")
	)
	(segment
		(start 332.359 -137.359136)
		(end 332.359 -136.394698)
		(width 0.254)
		(layer "In4.Cu")
		(net "P12V_STBY")
	)
	(segment
		(start 194.82943 -0.85217)
		(end 192.8368 -2.8448)
		(width 0.254)
		(layer "In4.Cu")
		(net "P12V_STBY")
	)
	(segment
		(start 350.554798 -23.900638)
		(end 351.232216 -23.22322)
		(width 0.254)
		(layer "In4.Cu")
		(net "P12V_STBY")
	)
	(segment
		(start 183.602376 -20.423886)
		(end 183.602376 -20.802346)
		(width 0.254)
		(layer "In4.Cu")
		(net "P12V_STBY")
	)
	(segment
		(start 183.60263 -22.862286)
		(end 182.690516 -23.7744)
		(width 0.254)
		(layer "In4.Cu")
		(net "P12V_STBY")
	)
	(segment
		(start 326.342248 -26.2128)
		(end 323.039994 -22.910546)
		(width 0.254)
		(layer "In4.Cu")
		(net "P12V_STBY")
	)
	(segment
		(start 337.7692 -19.304)
		(end 336.6516 -20.4216)
		(width 0.254)
		(layer "In4.Cu")
		(net "P12V_STBY")
	)
	(segment
		(start 322.0212 -3.521964)
		(end 322.0212 -3.0988)
		(width 0.254)
		(layer "In4.Cu")
		(net "P12V_STBY")
	)
	(segment
		(start 190.716662 -6.705854)
		(end 190.716916 -6.705854)
		(width 0.254)
		(layer "In4.Cu")
		(net "P12V_STBY")
	)
	(segment
		(start 183.60263 -20.8026)
		(end 183.60263 -22.862286)
		(width 0.254)
		(layer "In4.Cu")
		(net "P12V_STBY")
	)
	(segment
		(start 183.602376 -20.802346)
		(end 183.60263 -20.8026)
		(width 0.254)
		(layer "In4.Cu")
		(net "P12V_STBY")
	)
	(segment
		(start 342.8746 -17.5514)
		(end 342.583516 -17.260316)
		(width 0.254)
		(layer "In4.Cu")
		(net "P12V_STBY")
	)
	(segment
		(start 264.354056 -0.961136)
		(end 262.648446 -0.961136)
		(width 0.254)
		(layer "In4.Cu")
		(net "P12V_STBY")
	)
	(segment
		(start 197.544182 -0.85217)
		(end 194.82943 -0.85217)
		(width 0.254)
		(layer "In4.Cu")
		(net "P12V_STBY")
	)
	(segment
		(start 191.4906 -9.965436)
		(end 191.4906 -10.938764)
		(width 0.254)
		(layer "In4.Cu")
		(net "P12V_STBY")
	)
	(segment
		(start 323.039994 -22.910546)
		(end 323.039994 -4.540504)
		(width 0.254)
		(layer "In4.Cu")
		(net "P12V_STBY")
	)
	(segment
		(start 342.583516 -17.260062)
		(end 342.316054 -16.9926)
		(width 0.254)
		(layer "In4.Cu")
		(net "P12V_STBY")
	)
	(segment
		(start 403.2504 -15.58798)
		(end 408.42565 -10.41273)
		(width 0.254)
		(layer "In4.Cu")
		(net "P12V_STBY")
	)
	(segment
		(start 197.559168 -0.867156)
		(end 197.544182 -0.85217)
		(width 0.254)
		(layer "In4.Cu")
		(net "P12V_STBY")
	)
	(segment
		(start 190.8556 -11.573764)
		(end 190.8556 -17.359884)
		(width 0.254)
		(layer "In4.Cu")
		(net "P12V_STBY")
	)
	(segment
		(start 323.039994 -4.540504)
		(end 322.772532 -4.273042)
		(width 0.254)
		(layer "In4.Cu")
		(net "P12V_STBY")
	)
	(segment
		(start 322.0212 -3.0988)
		(end 322.3895 -2.7305)
		(width 0.254)
		(layer "In4.Cu")
		(net "P12V_STBY")
	)
	(segment
		(start 322.772532 -4.273042)
		(end 322.772278 -4.273042)
		(width 0.254)
		(layer "In4.Cu")
		(net "P12V_STBY")
	)
	(segment
		(start 262.648446 -0.961136)
		(end 261.16534 0.52197)
		(width 0.254)
		(layer "In4.Cu")
		(net "P12V_STBY")
	)
	(segment
		(start 332.92415 -129.003044)
		(end 329.661012 -125.739906)
		(width 0.254)
		(layer "In4.Cu")
		(net "P12V_STBY")
	)
	(segment
		(start 190.872872 -19.685)
		(end 184.341262 -19.685)
		(width 0.254)
		(layer "In4.Cu")
		(net "P12V_STBY")
	)
	(segment
		(start 351.232216 -19.616674)
		(end 349.752666 -18.137124)
		(width 0.254)
		(layer "In4.Cu")
		(net "P12V_STBY")
	)
	(segment
		(start 349.841058 -23.900638)
		(end 350.554798 -23.900638)
		(width 0.254)
		(layer "In4.Cu")
		(net "P12V_STBY")
	)
	(segment
		(start 329.661012 -125.739906)
		(end 329.661012 -125.2601)
		(width 0.254)
		(layer "In4.Cu")
		(net "P12V_STBY")
	)
	(segment
		(start 176.276 -22.987)
		(end 175.514 -22.987)
		(width 0.254)
		(layer "In4.Cu")
		(net "P12V_STBY")
	)
	(segment
		(start 351.232216 -23.22322)
		(end 351.232216 -19.616674)
		(width 0.254)
		(layer "In4.Cu")
		(net "P12V_STBY")
	)
	(segment
		(start 191.505078 -18.009362)
		(end 191.505078 -19.052794)
		(width 0.254)
		(layer "In4.Cu")
		(net "P12V_STBY")
	)
	(segment
		(start 336.6516 -20.4216)
		(end 336.6516 -21.9456)
		(width 0.254)
		(layer "In4.Cu")
		(net "P12V_STBY")
	)
	(segment
		(start 329.5396 -27.4066)
		(end 328.3458 -26.2128)
		(width 0.254)
		(layer "In4.Cu")
		(net "P12V_STBY")
	)
	(segment
		(start 258.643628 -0.867156)
		(end 197.559168 -0.867156)
		(width 0.254)
		(layer "In4.Cu")
		(net "P12V_STBY")
	)
	(segment
		(start 190.4492 -5.271262)
		(end 190.4492 -6.438392)
		(width 0.254)
		(layer "In4.Cu")
		(net "P12V_STBY")
	)
	(segment
		(start 409.298648 -8.5471)
		(end 418.6301 -8.5471)
		(width 0.254)
		(layer "In4.Cu")
		(net "P12V_STBY")
	)
	(segment
		(start 177.0634 -23.7744)
		(end 176.276 -22.987)
		(width 0.254)
		(layer "In4.Cu")
		(net "P12V_STBY")
	)
	(segment
		(start 259.765038 0.254508)
		(end 259.765038 0.254254)
		(width 0.254)
		(layer "In4.Cu")
		(net "P12V_STBY")
	)
	(segment
		(start 330.2 -27.4066)
		(end 329.5396 -27.4066)
		(width 0.254)
		(layer "In4.Cu")
		(net "P12V_STBY")
	)
	(segment
		(start 348.1324 -17.5514)
		(end 342.8746 -17.5514)
		(width 0.254)
		(layer "In4.Cu")
		(net "P12V_STBY")
	)
	(segment
		(start 322.3895 -1.663446)
		(end 321.457574 -0.73152)
		(width 0.254)
		(layer "In4.Cu")
		(net "P12V_STBY")
	)
	(segment
		(start 190.4492 -6.438392)
		(end 190.716662 -6.705854)
		(width 0.254)
		(layer "In4.Cu")
		(net "P12V_STBY")
	)
	(segment
		(start 192.8368 -2.8448)
		(end 191.6938 -2.8448)
		(width 0.254)
		(layer "In4.Cu")
		(net "P12V_STBY")
	)
	(segment
		(start 418.6301 -8.5471)
		(end 419.4175 -9.3345)
		(width 0.254)
		(layer "In4.Cu")
		(net "P12V_STBY")
	)
	(segment
		(start 331.9018 -25.7048)
		(end 330.2 -27.4066)
		(width 0.254)
		(layer "In4.Cu")
		(net "P12V_STBY")
	)
	(segment
		(start 322.3895 -2.7305)
		(end 322.3895 -1.663446)
		(width 0.254)
		(layer "In4.Cu")
		(net "P12V_STBY")
	)
	(segment
		(start 191.4906 -10.938764)
		(end 190.8556 -11.573764)
		(width 0.254)
		(layer "In4.Cu")
		(net "P12V_STBY")
	)
	(segment
		(start 190.815722 -4.90474)
		(end 190.4492 -5.271262)
		(width 0.254)
		(layer "In4.Cu")
		(net "P12V_STBY")
	)
	(segment
		(start 190.716916 -6.705854)
		(end 191.1096 -7.098538)
		(width 0.254)
		(layer "In4.Cu")
		(net "P12V_STBY")
	)
	(segment
		(start 175.514 -22.987)
		(end 175.387 -23.114)
		(width 0.254)
		(layer "In4.Cu")
		(net "P12V_STBY")
	)
	(segment
		(start 175.387 -23.114)
		(end 175.387 -23.5712)
		(width 0.254)
		(layer "In4.Cu")
		(net "P12V_STBY")
	)
	(segment
		(start 337.7692 -18.034)
		(end 337.7692 -19.304)
		(width 0.254)
		(layer "In4.Cu")
		(net "P12V_STBY")
	)
	(segment
		(start 349.752666 -18.137124)
		(end 348.718124 -18.137124)
		(width 0.254)
		(layer "In4.Cu")
		(net "P12V_STBY")
	)
	(segment
		(start 175.387 -23.5712)
		(end 175.2854 -23.6728)
		(width 0.254)
		(layer "In4.Cu")
		(net "P12V_STBY")
	)
	(segment
		(start 184.341262 -19.685)
		(end 183.602376 -20.423886)
		(width 0.254)
		(layer "In4.Cu")
		(net "P12V_STBY")
	)
	(segment
		(start 191.1096 -9.584436)
		(end 191.4906 -9.965436)
		(width 0.254)
		(layer "In4.Cu")
		(net "P12V_STBY")
	)
	(segment
		(start 338.8106 -16.9926)
		(end 337.7692 -18.034)
		(width 0.254)
		(layer "In4.Cu")
		(net "P12V_STBY")
	)
	(segment
		(start 408.42565 -10.41273)
		(end 408.42565 -9.420098)
		(width 0.254)
		(layer "In4.Cu")
		(net "P12V_STBY")
	)
	(segment
		(start 342.583516 -17.260316)
		(end 342.583516 -17.260062)
		(width 0.254)
		(layer "In4.Cu")
		(net "P12V_STBY")
	)
	(segment
		(start 260.0325 0.52197)
		(end 259.765038 0.254508)
		(width 0.254)
		(layer "In4.Cu")
		(net "P12V_STBY")
	)
	(segment
		(start 322.772278 -4.273042)
		(end 322.0212 -3.521964)
		(width 0.254)
		(layer "In4.Cu")
		(net "P12V_STBY")
	)
	(segment
		(start 191.1096 -7.098538)
		(end 191.1096 -9.584436)
		(width 0.254)
		(layer "In4.Cu")
		(net "P12V_STBY")
	)
	(segment
		(start 342.316054 -16.9926)
		(end 338.8106 -16.9926)
		(width 0.254)
		(layer "In4.Cu")
		(net "P12V_STBY")
	)
	(segment
		(start 190.815722 -3.722878)
		(end 190.815722 -4.90474)
		(width 0.254)
		(layer "In4.Cu")
		(net "P12V_STBY")
	)
	(segment
		(start 328.3458 -26.2128)
		(end 326.342248 -26.2128)
		(width 0.254)
		(layer "In4.Cu")
		(net "P12V_STBY")
	)
	(segment
		(start 403.2504 -17.99336)
		(end 403.2504 -15.58798)
		(width 0.254)
		(layer "In4.Cu")
		(net "P12V_STBY")
	)
	(segment
		(start 321.457574 -0.73152)
		(end 264.583672 -0.73152)
		(width 0.254)
		(layer "In4.Cu")
		(net "P12V_STBY")
	)
	(segment
		(start 408.42565 -9.420098)
		(end 409.298648 -8.5471)
		(width 0.254)
		(layer "In4.Cu")
		(net "P12V_STBY")
	)
	(segment
		(start 182.690516 -23.7744)
		(end 177.0634 -23.7744)
		(width 0.254)
		(layer "In4.Cu")
		(net "P12V_STBY")
	)
	(segment
		(start 191.6938 -2.8448)
		(end 190.815722 -3.722878)
		(width 0.254)
		(layer "In4.Cu")
		(net "P12V_STBY")
	)
	(segment
		(start 403.284436 -18.027396)
		(end 403.2504 -17.99336)
		(width 0.254)
		(layer "In4.Cu")
		(net "P12V_STBY")
	)
	(segment
		(start 336.6516 -21.9456)
		(end 332.8924 -25.7048)
		(width 0.254)
		(layer "In4.Cu")
		(net "P12V_STBY")
	)
	(segment
		(start 190.8556 -17.359884)
		(end 191.505078 -18.009362)
		(width 0.254)
		(layer "In4.Cu")
		(net "P12V_STBY")
	)
	(segment
		(start 259.765038 0.254254)
		(end 258.643628 -0.867156)
		(width 0.254)
		(layer "In4.Cu")
		(net "P12V_STBY")
	)
	(segment
		(start 332.8924 -25.7048)
		(end 331.9018 -25.7048)
		(width 0.254)
		(layer "In4.Cu")
		(net "P12V_STBY")
	)
	(segment
		(start 191.505078 -19.052794)
		(end 190.872872 -19.685)
		(width 0.254)
		(layer "In4.Cu")
		(net "P12V_STBY")
	)
	(segment
		(start 349.354648 -23.414228)
		(end 349.841058 -23.900638)
		(width 0.254)
		(layer "In4.Cu")
		(net "P12V_STBY")
	)
	(segment
		(start 348.718124 -18.137124)
		(end 348.1324 -17.5514)
		(width 0.254)
		(layer "In4.Cu")
		(net "P12V_STBY")
	)
	(segment
		(start 261.16534 0.52197)
		(end 260.0325 0.52197)
		(width 0.254)
		(layer "In4.Cu")
		(net "P12V_STBY")
	)
	(segment
		(start 332.92415 -135.829548)
		(end 332.92415 -129.003044)
		(width 0.254)
		(layer "In4.Cu")
		(net "P12V_STBY")
	)
	(segment
		(start 264.583672 -0.73152)
		(end 264.354056 -0.961136)
		(width 0.254)
		(layer "In4.Cu")
		(net "P12V_STBY")
	)
	(segment
		(start 332.359 -136.394698)
		(end 332.92415 -135.829548)
		(width 0.254)
		(layer "In4.Cu")
		(net "P12V_STBY")
	)
	(segment
		(start 191.106298 -128.736598)
		(end 193.245232 -126.597664)
		(width 0.254)
		(layer "In9.Cu")
		(net "P12V_STBY")
	)
	(segment
		(start 329.028298 -125.9586)
		(end 329.661012 -125.325886)
		(width 0.254)
		(layer "In9.Cu")
		(net "P12V_STBY")
	)
	(segment
		(start 325.98614 -127.672846)
		(end 327.700386 -125.9586)
		(width 0.254)
		(layer "In9.Cu")
		(net "P12V_STBY")
	)
	(segment
		(start 264.859262 -125.667008)
		(end 265.6459 -124.88037)
		(width 0.254)
		(layer "In9.Cu")
		(net "P12V_STBY")
	)
	(segment
		(start 182.510684 -127.359918)
		(end 183.06923 -127.918464)
		(width 0.254)
		(layer "In9.Cu")
		(net "P12V_STBY")
	)
	(segment
		(start 285.019496 -124.88037)
		(end 288.605976 -128.46685)
		(width 0.254)
		(layer "In9.Cu")
		(net "P12V_STBY")
	)
	(segment
		(start 334.212692 -136.06145)
		(end 335.693512 -136.06145)
		(width 0.254)
		(layer "In9.Cu")
		(net "P12V_STBY")
	)
	(segment
		(start 332.359 -137.359136)
		(end 332.915006 -137.359136)
		(width 0.254)
		(layer "In9.Cu")
		(net "P12V_STBY")
	)
	(segment
		(start 183.06923 -127.918464)
		(end 185.947304 -127.918464)
		(width 0.254)
		(layer "In9.Cu")
		(net "P12V_STBY")
	)
	(segment
		(start 221.537784 -127.893572)
		(end 244.63248 -127.893572)
		(width 0.254)
		(layer "In9.Cu")
		(net "P12V_STBY")
	)
	(segment
		(start 335.693512 -136.06145)
		(end 336.934302 -134.82066)
		(width 0.254)
		(layer "In9.Cu")
		(net "P12V_STBY")
	)
	(segment
		(start 182.510684 -127.071882)
		(end 182.510684 -127.359918)
		(width 0.254)
		(layer "In9.Cu")
		(net "P12V_STBY")
	)
	(segment
		(start 327.700386 -125.9586)
		(end 329.028298 -125.9586)
		(width 0.254)
		(layer "In9.Cu")
		(net "P12V_STBY")
	)
	(segment
		(start 193.245232 -126.597664)
		(end 220.241876 -126.597664)
		(width 0.254)
		(layer "In9.Cu")
		(net "P12V_STBY")
	)
	(segment
		(start 322.986908 -128.46685)
		(end 323.780912 -127.672846)
		(width 0.254)
		(layer "In9.Cu")
		(net "P12V_STBY")
	)
	(segment
		(start 265.6459 -124.88037)
		(end 285.019496 -124.88037)
		(width 0.254)
		(layer "In9.Cu")
		(net "P12V_STBY")
	)
	(segment
		(start 220.241876 -126.597664)
		(end 221.537784 -127.893572)
		(width 0.254)
		(layer "In9.Cu")
		(net "P12V_STBY")
	)
	(segment
		(start 244.63248 -127.893572)
		(end 246.859044 -125.667008)
		(width 0.254)
		(layer "In9.Cu")
		(net "P12V_STBY")
	)
	(segment
		(start 323.780912 -127.672846)
		(end 325.98614 -127.672846)
		(width 0.254)
		(layer "In9.Cu")
		(net "P12V_STBY")
	)
	(segment
		(start 288.605976 -128.46685)
		(end 322.986908 -128.46685)
		(width 0.254)
		(layer "In9.Cu")
		(net "P12V_STBY")
	)
	(segment
		(start 336.934302 -134.82066)
		(end 353.92868 -134.82066)
		(width 0.254)
		(layer "In9.Cu")
		(net "P12V_STBY")
	)
	(segment
		(start 329.661012 -125.325886)
		(end 329.661012 -125.2601)
		(width 0.254)
		(layer "In9.Cu")
		(net "P12V_STBY")
	)
	(segment
		(start 332.915006 -137.359136)
		(end 334.212692 -136.06145)
		(width 0.254)
		(layer "In9.Cu")
		(net "P12V_STBY")
	)
	(segment
		(start 185.947304 -127.918464)
		(end 186.765438 -128.736598)
		(width 0.254)
		(layer "In9.Cu")
		(net "P12V_STBY")
	)
	(segment
		(start 246.859044 -125.667008)
		(end 264.859262 -125.667008)
		(width 0.254)
		(layer "In9.Cu")
		(net "P12V_STBY")
	)
	(segment
		(start 186.765438 -128.736598)
		(end 191.106298 -128.736598)
		(width 0.254)
		(layer "In9.Cu")
		(net "P12V_STBY")
	)
	(segment
		(start 355.529134 -136.421114)
		(end 355.529134 -136.527286)
		(width 0.254)
		(layer "In9.Cu")
		(net "P12V_STBY")
	)
	(segment
		(start 353.92868 -134.82066)
		(end 355.529134 -136.421114)
		(width 0.254)
		(layer "In9.Cu")
		(net "P12V_STBY")
	)
	(segment
		(start 492.8362 -148.441664)
		(end 491.43666 -149.841204)
		(width 0.508)
		(layer "In11.Cu")
		(net "P12V_STBY")
	)
	(segment
		(start 495.6937 -123.64466)
		(end 494.36274 -124.97562)
		(width 0.508)
		(layer "In11.Cu")
		(net "P12V_STBY")
	)
	(segment
		(start 495.173 -130.20548)
		(end 495.173 -136.167622)
		(width 0.508)
		(layer "In11.Cu")
		(net "P12V_STBY")
	)
	(segment
		(start 489.335064 -151.9428)
		(end 482.7143 -151.9428)
		(width 0.508)
		(layer "In11.Cu")
		(net "P12V_STBY")
	)
	(segment
		(start 487.799888 -113.77422)
		(end 490.192568 -116.1669)
		(width 0.508)
		(layer "In11.Cu")
		(net "P12V_STBY")
	)
	(segment
		(start 492.1504 -145.54073)
		(end 492.8362 -146.22653)
		(width 0.508)
		(layer "In11.Cu")
		(net "P12V_STBY")
	)
	(segment
		(start 491.43666 -149.841204)
		(end 491.43666 -150.13813)
		(width 0.508)
		(layer "In11.Cu")
		(net "P12V_STBY")
	)
	(segment
		(start 495.173 -136.167622)
		(end 495.52987 -136.524492)
		(width 0.508)
		(layer "In11.Cu")
		(net "P12V_STBY")
	)
	(segment
		(start 482.7143 -151.9428)
		(end 481.96627 -151.19477)
		(width 0.508)
		(layer "In11.Cu")
		(net "P12V_STBY")
	)
	(segment
		(start 491.43666 -150.13813)
		(end 491.07979 -150.495)
		(width 0.508)
		(layer "In11.Cu")
		(net "P12V_STBY")
	)
	(segment
		(start 494.36274 -124.97562)
		(end 494.36274 -129.39522)
		(width 0.508)
		(layer "In11.Cu")
		(net "P12V_STBY")
	)
	(segment
		(start 495.52987 -139.49553)
		(end 494.5126 -140.5128)
		(width 0.508)
		(layer "In11.Cu")
		(net "P12V_STBY")
	)
	(segment
		(start 491.8202 -116.1669)
		(end 495.6937 -120.0404)
		(width 0.508)
		(layer "In11.Cu")
		(net "P12V_STBY")
	)
	(segment
		(start 490.192568 -116.1669)
		(end 491.8202 -116.1669)
		(width 0.508)
		(layer "In11.Cu")
		(net "P12V_STBY")
	)
	(segment
		(start 492.1504 -145.03527)
		(end 492.1504 -145.54073)
		(width 0.508)
		(layer "In11.Cu")
		(net "P12V_STBY")
	)
	(segment
		(start 481.96627 -151.19477)
		(end 481.674932 -151.19477)
		(width 0.508)
		(layer "In11.Cu")
		(net "P12V_STBY")
	)
	(segment
		(start 495.6937 -120.0404)
		(end 495.6937 -123.64466)
		(width 0.508)
		(layer "In11.Cu")
		(net "P12V_STBY")
	)
	(segment
		(start 491.07979 -150.495)
		(end 490.782864 -150.495)
		(width 0.508)
		(layer "In11.Cu")
		(net "P12V_STBY")
	)
	(segment
		(start 494.5126 -140.5128)
		(end 493.6236 -140.5128)
		(width 0.508)
		(layer "In11.Cu")
		(net "P12V_STBY")
	)
	(segment
		(start 494.36274 -129.39522)
		(end 495.173 -130.20548)
		(width 0.508)
		(layer "In11.Cu")
		(net "P12V_STBY")
	)
	(segment
		(start 492.8362 -144.34947)
		(end 492.1504 -145.03527)
		(width 0.508)
		(layer "In11.Cu")
		(net "P12V_STBY")
	)
	(segment
		(start 493.6236 -140.5128)
		(end 492.8362 -141.3002)
		(width 0.508)
		(layer "In11.Cu")
		(net "P12V_STBY")
	)
	(segment
		(start 490.782864 -150.495)
		(end 489.335064 -151.9428)
		(width 0.508)
		(layer "In11.Cu")
		(net "P12V_STBY")
	)
	(segment
		(start 492.8362 -146.22653)
		(end 492.8362 -148.441664)
		(width 0.508)
		(layer "In11.Cu")
		(net "P12V_STBY")
	)
	(segment
		(start 495.52987 -136.524492)
		(end 495.52987 -139.49553)
		(width 0.508)
		(layer "In11.Cu")
		(net "P12V_STBY")
	)
	(segment
		(start 492.8362 -141.3002)
		(end 492.8362 -144.34947)
		(width 0.508)
		(layer "In11.Cu")
		(net "P12V_STBY")
	)
	(segment
		(start 498.72773 -17.918938)
		(end 499.067582 -17.579086)
		(width 0.508)
		(layer "F.Cu")
		(net "P12V")
	)
	(segment
		(start 501.287288 -20.6629)
		(end 500.779288 -21.1709)
		(width 0.508)
		(layer "F.Cu")
		(net "P12V")
	)
	(segment
		(start 500.779288 -21.1709)
		(end 500.20728 -21.1709)
		(width 0.508)
		(layer "F.Cu")
		(net "P12V")
	)
	(segment
		(start 499.3894 -21.98878)
		(end 499.3894 -24.075644)
		(width 0.508)
		(layer "F.Cu")
		(net "P12V")
	)
	(segment
		(start 499.095522 -25.555448)
		(end 498.735604 -25.555448)
		(width 0.3048)
		(layer "F.Cu")
		(net "P12V")
	)
	(segment
		(start 501.287288 -18.399506)
		(end 501.287288 -20.6629)
		(width 0.508)
		(layer "F.Cu")
		(net "P12V")
	)
	(segment
		(start 499.3894 -24.075644)
		(end 499.36654 -24.098504)
		(width 0.3048)
		(layer "F.Cu")
		(net "P12V")
	)
	(segment
		(start 500.466868 -17.579086)
		(end 501.287288 -18.399506)
		(width 0.508)
		(layer "F.Cu")
		(net "P12V")
	)
	(segment
		(start 499.067582 -17.579086)
		(end 500.466868 -17.579086)
		(width 0.508)
		(layer "F.Cu")
		(net "P12V")
	)
	(segment
		(start 500.20728 -21.1709)
		(end 499.3894 -21.98878)
		(width 0.508)
		(layer "F.Cu")
		(net "P12V")
	)
	(segment
		(start 493.7125 -17.918938)
		(end 498.72773 -17.918938)
		(width 0.508)
		(layer "F.Cu")
		(net "P12V")
	)
	(segment
		(start 499.36654 -25.28443)
		(end 499.095522 -25.555448)
		(width 0.3048)
		(layer "F.Cu")
		(net "P12V")
	)
	(segment
		(start 499.36654 -24.098504)
		(end 499.36654 -25.28443)
		(width 0.3048)
		(layer "F.Cu")
		(net "P12V")
	)
	(via
		(at 493.0013 -17.918938)
		(size 0.5588)
		(drill 0.3048)
		(layers "F.Cu" "B.Cu")
		(net "P12V")
	)
	(via
		(at 470.467944 -5.363972)
		(size 0.5588)
		(drill 0.3048)
		(layers "F.Cu" "B.Cu")
		(net "P12V")
	)
	(via
		(at 494.03508 -19.31924)
		(size 0.5588)
		(drill 0.3048)
		(layers "F.Cu" "B.Cu")
		(net "P12V")
	)
	(via
		(at 472.195144 -6.80212)
		(size 0.5588)
		(drill 0.3048)
		(layers "F.Cu" "B.Cu")
		(net "P12V")
	)
	(via
		(at 495.033554 -18.655792)
		(size 0.5588)
		(drill 0.3048)
		(layers "F.Cu" "B.Cu")
		(net "P12V")
	)
	(via
		(at 454.942702 -126.15418)
		(size 0.508)
		(drill 0.254)
		(layers "F.Cu" "B.Cu")
		(net "P12V")
	)
	(via
		(at 471.382344 -5.363972)
		(size 0.5588)
		(drill 0.3048)
		(layers "F.Cu" "B.Cu")
		(net "P12V")
	)
	(via
		(at 492.9505 -18.630138)
		(size 0.5588)
		(drill 0.3048)
		(layers "F.Cu" "B.Cu")
		(net "P12V")
	)
	(via
		(at 478.465642 -66.809366)
		(size 0.5588)
		(drill 0.3048)
		(layers "F.Cu" "B.Cu")
		(net "P12V")
	)
	(via
		(at 478.465642 -66.047366)
		(size 0.5588)
		(drill 0.3048)
		(layers "F.Cu" "B.Cu")
		(net "P12V")
	)
	(via
		(at 473.46108 -6.21538)
		(size 0.5588)
		(drill 0.3048)
		(layers "F.Cu" "B.Cu")
		(net "P12V")
	)
	(via
		(at 470.391744 -6.80212)
		(size 0.5588)
		(drill 0.3048)
		(layers "F.Cu" "B.Cu")
		(net "P12V")
	)
	(via
		(at 443.054232 -60.27293)
		(size 0.5588)
		(drill 0.3048)
		(layers "F.Cu" "B.Cu")
		(net "P12V")
	)
	(via
		(at 496.384834 -20.434046)
		(size 0.5588)
		(drill 0.3048)
		(layers "F.Cu" "B.Cu")
		(net "P12V")
	)
	(via
		(at 491.6297 -17.893538)
		(size 0.5588)
		(drill 0.3048)
		(layers "F.Cu" "B.Cu")
		(net "P12V")
	)
	(via
		(at 490.210094 -18.604738)
		(size 0.5588)
		(drill 0.3048)
		(layers "F.Cu" "B.Cu")
		(net "P12V")
	)
	(via
		(at 471.280744 -6.80212)
		(size 0.5588)
		(drill 0.3048)
		(layers "F.Cu" "B.Cu")
		(net "P12V")
	)
	(via
		(at 473.8243 -5.588)
		(size 0.5588)
		(drill 0.3048)
		(layers "F.Cu" "B.Cu")
		(net "P12V")
	)
	(via
		(at 454.16343 -126.150116)
		(size 0.508)
		(drill 0.254)
		(layers "F.Cu" "B.Cu")
		(net "P12V")
	)
	(via
		(at 472.296744 -5.363972)
		(size 0.5588)
		(drill 0.3048)
		(layers "F.Cu" "B.Cu")
		(net "P12V")
	)
	(via
		(at 477.680782 -66.829686)
		(size 0.5588)
		(drill 0.3048)
		(layers "F.Cu" "B.Cu")
		(net "P12V")
	)
	(via
		(at 494.3729 -18.655538)
		(size 0.5588)
		(drill 0.3048)
		(layers "F.Cu" "B.Cu")
		(net "P12V")
	)
	(via
		(at 492.2393 -18.604738)
		(size 0.5588)
		(drill 0.3048)
		(layers "F.Cu" "B.Cu")
		(net "P12V")
	)
	(via
		(at 493.36706 -19.31416)
		(size 0.5588)
		(drill 0.3048)
		(layers "F.Cu" "B.Cu")
		(net "P12V")
	)
	(via
		(at 490.2581 -17.893538)
		(size 0.5588)
		(drill 0.3048)
		(layers "F.Cu" "B.Cu")
		(net "P12V")
	)
	(via
		(at 477.680782 -66.067686)
		(size 0.5588)
		(drill 0.3048)
		(layers "F.Cu" "B.Cu")
		(net "P12V")
	)
	(via
		(at 441.717176 -60.270136)
		(size 0.5588)
		(drill 0.3048)
		(layers "F.Cu" "B.Cu")
		(net "P12V")
	)
	(via
		(at 406.8191 -6.13664)
		(size 0.508)
		(drill 0.254)
		(layers "F.Cu" "B.Cu")
		(net "P12V")
	)
	(via
		(at 493.6617 -18.630138)
		(size 0.5588)
		(drill 0.3048)
		(layers "F.Cu" "B.Cu")
		(net "P12V")
	)
	(via
		(at 491.923324 -19.300698)
		(size 0.5588)
		(drill 0.3048)
		(layers "F.Cu" "B.Cu")
		(net "P12V")
	)
	(via
		(at 473.109544 -6.80212)
		(size 0.5588)
		(drill 0.3048)
		(layers "F.Cu" "B.Cu")
		(net "P12V")
	)
	(via
		(at 470.860374 -6.069076)
		(size 0.5588)
		(drill 0.3048)
		(layers "F.Cu" "B.Cu")
		(net "P12V")
	)
	(via
		(at 490.9693 -17.893538)
		(size 0.5588)
		(drill 0.3048)
		(layers "F.Cu" "B.Cu")
		(net "P12V")
	)
	(via
		(at 493.7125 -17.918938)
		(size 0.5588)
		(drill 0.3048)
		(layers "F.Cu" "B.Cu")
		(net "P12V")
	)
	(via
		(at 443.795658 -60.277756)
		(size 0.5588)
		(drill 0.3048)
		(layers "F.Cu" "B.Cu")
		(net "P12V")
	)
	(via
		(at 492.62538 -19.304)
		(size 0.5588)
		(drill 0.3048)
		(layers "F.Cu" "B.Cu")
		(net "P12V")
	)
	(via
		(at 442.383672 -60.277756)
		(size 0.5588)
		(drill 0.3048)
		(layers "F.Cu" "B.Cu")
		(net "P12V")
	)
	(via
		(at 490.91342 -18.62074)
		(size 0.5588)
		(drill 0.3048)
		(layers "F.Cu" "B.Cu")
		(net "P12V")
	)
	(via
		(at 453.359012 -126.162054)
		(size 0.508)
		(drill 0.254)
		(layers "F.Cu" "B.Cu")
		(net "P12V")
	)
	(via
		(at 471.774774 -6.069076)
		(size 0.5588)
		(drill 0.3048)
		(layers "F.Cu" "B.Cu")
		(net "P12V")
	)
	(via
		(at 470.16416 -6.12902)
		(size 0.5588)
		(drill 0.3048)
		(layers "F.Cu" "B.Cu")
		(net "P12V")
	)
	(via
		(at 472.689174 -6.069076)
		(size 0.5588)
		(drill 0.3048)
		(layers "F.Cu" "B.Cu")
		(net "P12V")
	)
	(via
		(at 491.5789 -18.604738)
		(size 0.5588)
		(drill 0.3048)
		(layers "F.Cu" "B.Cu")
		(net "P12V")
	)
	(via
		(at 473.185744 -5.363972)
		(size 0.5588)
		(drill 0.3048)
		(layers "F.Cu" "B.Cu")
		(net "P12V")
	)
	(via
		(at 492.2901 -17.893538)
		(size 0.5588)
		(drill 0.3048)
		(layers "F.Cu" "B.Cu")
		(net "P12V")
	)
	(segment
		(start 406.8191 -6.13664)
		(end 407.60396 -6.9215)
		(width 0.254)
		(layer "B.Cu")
		(net "P12V")
	)
	(segment
		(start 407.60396 -6.9215)
		(end 408.051 -6.9215)
		(width 0.254)
		(layer "B.Cu")
		(net "P12V")
	)
	(via
		(at 375.1072 -59.440318)
		(size 0.508)
		(drill 0.254)
		(layers "F.Cu" "B.Cu")
		(net "P0V7_GTL2104_VREF_1")
	)
	(segment
		(start 373.520716 -59.289442)
		(end 374.185942 -59.289442)
		(width 0.254)
		(layer "B.Cu")
		(net "P0V7_GTL2104_VREF_1")
	)
	(segment
		(start 375.1072 -59.617864)
		(end 375.1072 -59.440318)
		(width 0.254)
		(layer "B.Cu")
		(net "P0V7_GTL2104_VREF_1")
	)
	(segment
		(start 374.4214 -59.650884)
		(end 374.568212 -59.797696)
		(width 0.254)
		(layer "B.Cu")
		(net "P0V7_GTL2104_VREF_1")
	)
	(segment
		(start 371.718078 -59.289442)
		(end 372.631716 -59.289442)
		(width 0.254)
		(layer "B.Cu")
		(net "P0V7_GTL2104_VREF_1")
	)
	(segment
		(start 371.356636 -58.928)
		(end 371.718078 -59.289442)
		(width 0.254)
		(layer "B.Cu")
		(net "P0V7_GTL2104_VREF_1")
	)
	(segment
		(start 374.568212 -59.797696)
		(end 374.927368 -59.797696)
		(width 0.254)
		(layer "B.Cu")
		(net "P0V7_GTL2104_VREF_1")
	)
	(segment
		(start 374.4214 -59.5249)
		(end 374.4214 -59.650884)
		(width 0.254)
		(layer "B.Cu")
		(net "P0V7_GTL2104_VREF_1")
	)
	(segment
		(start 372.631716 -59.289442)
		(end 373.520716 -59.289442)
		(width 0.254)
		(layer "B.Cu")
		(net "P0V7_GTL2104_VREF_1")
	)
	(segment
		(start 374.927368 -59.797696)
		(end 375.1072 -59.617864)
		(width 0.254)
		(layer "B.Cu")
		(net "P0V7_GTL2104_VREF_1")
	)
	(segment
		(start 375.1072 -59.440318)
		(end 375.1072 -58.674)
		(width 0.254)
		(layer "B.Cu")
		(net "P0V7_GTL2104_VREF_1")
	)
	(segment
		(start 370.3955 -58.928)
		(end 371.356636 -58.928)
		(width 0.254)
		(layer "B.Cu")
		(net "P0V7_GTL2104_VREF_1")
	)
	(segment
		(start 374.185942 -59.289442)
		(end 374.4214 -59.5249)
		(width 0.254)
		(layer "B.Cu")
		(net "P0V7_GTL2104_VREF_1")
	)
	(segment
		(start 388.112 -77.426566)
		(end 388.112 -76.9112)
		(width 0.254)
		(layer "F.Cu")
		(net "P0V7_GTL2104_VREF_0")
	)
	(segment
		(start 391.4902 -80.4799)
		(end 390.7663 -80.4799)
		(width 0.254)
		(layer "F.Cu")
		(net "P0V7_GTL2104_VREF_0")
	)
	(segment
		(start 389.0645 -79.8322)
		(end 389.0645 -78.379066)
		(width 0.254)
		(layer "F.Cu")
		(net "P0V7_GTL2104_VREF_0")
	)
	(segment
		(start 389.48868 -80.6196)
		(end 389.0645 -80.6196)
		(width 0.254)
		(layer "F.Cu")
		(net "P0V7_GTL2104_VREF_0")
	)
	(segment
		(start 388.112 -76.9112)
		(end 387.638798 -76.437998)
		(width 0.254)
		(layer "F.Cu")
		(net "P0V7_GTL2104_VREF_0")
	)
	(segment
		(start 389.0645 -79.8322)
		(end 389.0645 -80.6196)
		(width 0.254)
		(layer "F.Cu")
		(net "P0V7_GTL2104_VREF_0")
	)
	(segment
		(start 389.0645 -78.379066)
		(end 388.112 -77.426566)
		(width 0.254)
		(layer "F.Cu")
		(net "P0V7_GTL2104_VREF_0")
	)
	(segment
		(start 390.7663 -80.4799)
		(end 390.525 -80.7212)
		(width 0.254)
		(layer "F.Cu")
		(net "P0V7_GTL2104_VREF_0")
	)
	(segment
		(start 389.9535 -80.7212)
		(end 389.59028 -80.7212)
		(width 0.254)
		(layer "F.Cu")
		(net "P0V7_GTL2104_VREF_0")
	)
	(segment
		(start 387.638798 -76.437998)
		(end 386.326888 -76.437998)
		(width 0.254)
		(layer "F.Cu")
		(net "P0V7_GTL2104_VREF_0")
	)
	(segment
		(start 389.59028 -80.7212)
		(end 389.48868 -80.6196)
		(width 0.254)
		(layer "F.Cu")
		(net "P0V7_GTL2104_VREF_0")
	)
	(segment
		(start 390.525 -80.7212)
		(end 389.9535 -80.7212)
		(width 0.254)
		(layer "F.Cu")
		(net "P0V7_GTL2104_VREF_0")
	)
	(segment
		(start 96.079818 -93.72854)
		(end 95.508318 -93.72854)
		(width 0.1651)
		(layer "F.Cu")
		(net "M_M_PAR")
	)
	(segment
		(start 100.249482 -156.87294)
		(end 100.249228 -156.87294)
		(width 0.1651)
		(layer "F.Cu")
		(net "M_M_PAR")
	)
	(segment
		(start 100.249228 -156.87294)
		(end 100.249228 -155.614878)
		(width 0.1651)
		(layer "F.Cu")
		(net "M_M_PAR")
	)
	(via
		(at 100.249228 -155.614878)
		(size 0.508)
		(drill 0.254)
		(layers "F.Cu" "B.Cu")
		(net "M_M_PAR")
	)
	(via
		(at 100.249228 -149.451568)
		(size 0.508)
		(drill 0.254)
		(layers "F.Cu" "B.Cu")
		(net "M_M_PAR")
	)
	(via
		(at 95.508318 -93.72854)
		(size 0.508)
		(drill 0.254)
		(layers "F.Cu" "B.Cu")
		(net "M_M_PAR")
	)
	(segment
		(start 100.249228 -147.478496)
		(end 100.249228 -149.451568)
		(width 0.1651)
		(layer "B.Cu")
		(net "M_M_PAR")
	)
	(segment
		(start 100.249482 -147.478496)
		(end 100.249228 -147.478496)
		(width 0.1651)
		(layer "B.Cu")
		(net "M_M_PAR")
	)
	(segment
		(start 99.769168 -148.971508)
		(end 100.249228 -149.451568)
		(width 0.14224)
		(layer "In2.Cu")
		(net "M_M_PAR")
	)
	(segment
		(start 95.508318 -93.72854)
		(end 95.838518 -94.49054)
		(width 0.0889)
		(layer "In2.Cu")
		(net "M_M_PAR")
	)
	(segment
		(start 96.314768 -102.6922)
		(end 96.314768 -102.938834)
		(width 0.0889)
		(layer "In2.Cu")
		(net "M_M_PAR")
	)
	(segment
		(start 95.908368 -99.671378)
		(end 95.908368 -101.471476)
		(width 0.0889)
		(layer "In2.Cu")
		(net "M_M_PAR")
	)
	(segment
		(start 100.598478 -151.662638)
		(end 100.598478 -153.94051)
		(width 0.14224)
		(layer "In2.Cu")
		(net "M_M_PAR")
	)
	(segment
		(start 95.855028 -96.500188)
		(end 95.859854 -96.508824)
		(width 0.0889)
		(layer "In2.Cu")
		(net "M_M_PAR")
	)
	(segment
		(start 96.314768 -102.938834)
		(end 96.314768 -125.36678)
		(width 0.14224)
		(layer "In2.Cu")
		(net "M_M_PAR")
	)
	(segment
		(start 95.855028 -98.481388)
		(end 95.859854 -98.490024)
		(width 0.0889)
		(layer "In2.Cu")
		(net "M_M_PAR")
	)
	(segment
		(start 100.249228 -154.94254)
		(end 100.249228 -155.614878)
		(width 0.14224)
		(layer "In2.Cu")
		(net "M_M_PAR")
	)
	(segment
		(start 96.486472 -102.520496)
		(end 96.314768 -102.6922)
		(width 0.0889)
		(layer "In2.Cu")
		(net "M_M_PAR")
	)
	(segment
		(start 99.769168 -128.82118)
		(end 99.769168 -148.971508)
		(width 0.14224)
		(layer "In2.Cu")
		(net "M_M_PAR")
	)
	(segment
		(start 96.314768 -125.36678)
		(end 99.769168 -128.82118)
		(width 0.14224)
		(layer "In2.Cu")
		(net "M_M_PAR")
	)
	(segment
		(start 95.848678 -97.48012)
		(end 95.855028 -97.490788)
		(width 0.0889)
		(layer "In2.Cu")
		(net "M_M_PAR")
	)
	(segment
		(start 95.848678 -98.47072)
		(end 95.855028 -98.481388)
		(width 0.0889)
		(layer "In2.Cu")
		(net "M_M_PAR")
	)
	(segment
		(start 95.855028 -97.490788)
		(end 95.859854 -97.499424)
		(width 0.0889)
		(layer "In2.Cu")
		(net "M_M_PAR")
	)
	(segment
		(start 95.848678 -95.49892)
		(end 95.855028 -95.509588)
		(width 0.0889)
		(layer "In2.Cu")
		(net "M_M_PAR")
	)
	(segment
		(start 95.838518 -94.49054)
		(end 95.859854 -94.527624)
		(width 0.0889)
		(layer "In2.Cu")
		(net "M_M_PAR")
	)
	(segment
		(start 100.687886 -154.029918)
		(end 100.687886 -154.503882)
		(width 0.14224)
		(layer "In2.Cu")
		(net "M_M_PAR")
	)
	(segment
		(start 95.908368 -101.471476)
		(end 96.486472 -102.04958)
		(width 0.0889)
		(layer "In2.Cu")
		(net "M_M_PAR")
	)
	(segment
		(start 96.486472 -102.04958)
		(end 96.486472 -102.520496)
		(width 0.0889)
		(layer "In2.Cu")
		(net "M_M_PAR")
	)
	(segment
		(start 100.249228 -149.451568)
		(end 100.249228 -151.313388)
		(width 0.14224)
		(layer "In2.Cu")
		(net "M_M_PAR")
	)
	(segment
		(start 100.598478 -153.94051)
		(end 100.687886 -154.029918)
		(width 0.14224)
		(layer "In2.Cu")
		(net "M_M_PAR")
	)
	(segment
		(start 100.249228 -151.313388)
		(end 100.598478 -151.662638)
		(width 0.14224)
		(layer "In2.Cu")
		(net "M_M_PAR")
	)
	(segment
		(start 95.848678 -96.48952)
		(end 95.855028 -96.500188)
		(width 0.0889)
		(layer "In2.Cu")
		(net "M_M_PAR")
	)
	(segment
		(start 100.687886 -154.503882)
		(end 100.249228 -154.94254)
		(width 0.14224)
		(layer "In2.Cu")
		(net "M_M_PAR")
	)
	(segment
		(start 95.855028 -95.509588)
		(end 95.859854 -95.518224)
		(width 0.0889)
		(layer "In2.Cu")
		(net "M_M_PAR")
	)
	(arc
		(start 95.859854 -94.527624)
		(mid 95.908609 -94.723976)
		(end 95.855028 -94.919038)
		(width 0.0889)
		(layer "In2.Cu")
		(net "M_M_PAR")
	)
	(arc
		(start 95.855028 -99.472242)
		(mid 95.894814 -99.568298)
		(end 95.908368 -99.671378)
		(width 0.0889)
		(layer "In2.Cu")
		(net "M_M_PAR")
	)
	(arc
		(start 95.859854 -95.518224)
		(mid 95.908609 -95.714576)
		(end 95.855028 -95.909638)
		(width 0.0889)
		(layer "In2.Cu")
		(net "M_M_PAR")
	)
	(arc
		(start 95.855028 -98.881438)
		(mid 95.775897 -99.17684)
		(end 95.855028 -99.472242)
		(width 0.0889)
		(layer "In2.Cu")
		(net "M_M_PAR")
	)
	(arc
		(start 95.859854 -98.490024)
		(mid 95.908609 -98.686376)
		(end 95.855028 -98.881438)
		(width 0.0889)
		(layer "In2.Cu")
		(net "M_M_PAR")
	)
	(arc
		(start 95.855028 -94.919038)
		(mid 95.775806 -95.208156)
		(end 95.848678 -95.49892)
		(width 0.0889)
		(layer "In2.Cu")
		(net "M_M_PAR")
	)
	(arc
		(start 95.859854 -96.508824)
		(mid 95.908609 -96.705176)
		(end 95.855028 -96.900238)
		(width 0.0889)
		(layer "In2.Cu")
		(net "M_M_PAR")
	)
	(arc
		(start 95.859854 -97.499424)
		(mid 95.908609 -97.695776)
		(end 95.855028 -97.890838)
		(width 0.0889)
		(layer "In2.Cu")
		(net "M_M_PAR")
	)
	(arc
		(start 95.855028 -97.890838)
		(mid 95.775806 -98.179956)
		(end 95.848678 -98.47072)
		(width 0.0889)
		(layer "In2.Cu")
		(net "M_M_PAR")
	)
	(arc
		(start 95.855028 -96.900238)
		(mid 95.775806 -97.189356)
		(end 95.848678 -97.48012)
		(width 0.0889)
		(layer "In2.Cu")
		(net "M_M_PAR")
	)
	(arc
		(start 95.855028 -95.909638)
		(mid 95.775806 -96.198756)
		(end 95.848678 -96.48952)
		(width 0.0889)
		(layer "In2.Cu")
		(net "M_M_PAR")
	)
	(segment
		(start 101.230684 -91.747086)
		(end 100.659184 -91.747086)
		(width 0.1016)
		(layer "F.Cu")
		(net "M_M_ODT<3>")
	)
	(via
		(at 100.659184 -91.747086)
		(size 0.508)
		(drill 0.254)
		(layers "F.Cu" "B.Cu")
		(net "M_M_ODT<3>")
	)
	(via
		(at 111.299498 -150.789386)
		(size 0.4572)
		(drill 0.2032)
		(layers "F.Cu" "B.Cu")
		(net "M_M_ODT<3>")
	)
	(segment
		(start 111.299498 -152.078436)
		(end 111.299498 -150.789386)
		(width 0.1651)
		(layer "B.Cu")
		(net "M_M_ODT<3>")
	)
	(segment
		(start 110.875826 -147.377658)
		(end 110.036356 -146.538188)
		(width 0.14224)
		(layer "In2.Cu")
		(net "M_M_ODT<3>")
	)
	(segment
		(start 101.140768 -92.964)
		(end 101.140768 -92.5576)
		(width 0.14224)
		(layer "In2.Cu")
		(net "M_M_ODT<3>")
	)
	(segment
		(start 102.004368 -97.9932)
		(end 101.674168 -97.663)
		(width 0.14224)
		(layer "In2.Cu")
		(net "M_M_ODT<3>")
	)
	(segment
		(start 102.029768 -98.9838)
		(end 101.860604 -98.814636)
		(width 0.14224)
		(layer "In2.Cu")
		(net "M_M_ODT<3>")
	)
	(segment
		(start 101.140768 -94.9198)
		(end 101.140768 -94.5134)
		(width 0.14224)
		(layer "In2.Cu")
		(net "M_M_ODT<3>")
	)
	(segment
		(start 101.877368 -101.9048)
		(end 101.877368 -99.5172)
		(width 0.14224)
		(layer "In2.Cu")
		(net "M_M_ODT<3>")
	)
	(segment
		(start 102.436168 -120.603264)
		(end 102.436168 -102.9462)
		(width 0.14224)
		(layer "In2.Cu")
		(net "M_M_ODT<3>")
	)
	(segment
		(start 101.013768 -96.393)
		(end 101.013768 -96.0374)
		(width 0.14224)
		(layer "In2.Cu")
		(net "M_M_ODT<3>")
	)
	(segment
		(start 110.036356 -145.67662)
		(end 109.662468 -145.302732)
		(width 0.14224)
		(layer "In2.Cu")
		(net "M_M_ODT<3>")
	)
	(segment
		(start 101.013768 -97.3582)
		(end 101.013768 -97.0026)
		(width 0.14224)
		(layer "In2.Cu")
		(net "M_M_ODT<3>")
	)
	(segment
		(start 110.03661 -142.830042)
		(end 110.01375 -142.807182)
		(width 0.14224)
		(layer "In2.Cu")
		(net "M_M_ODT<3>")
	)
	(segment
		(start 109.979968 -132.1816)
		(end 109.979968 -131.318)
		(width 0.14224)
		(layer "In2.Cu")
		(net "M_M_ODT<3>")
	)
	(segment
		(start 109.954568 -130.6068)
		(end 109.954568 -129.9718)
		(width 0.14224)
		(layer "In2.Cu")
		(net "M_M_ODT<3>")
	)
	(segment
		(start 101.140768 -94.5134)
		(end 101.039168 -94.4118)
		(width 0.14224)
		(layer "In2.Cu")
		(net "M_M_ODT<3>")
	)
	(segment
		(start 109.64418 -135.152892)
		(end 110.036102 -134.76097)
		(width 0.14224)
		(layer "In2.Cu")
		(net "M_M_ODT<3>")
	)
	(segment
		(start 101.860604 -98.814636)
		(end 101.860604 -98.543364)
		(width 0.14224)
		(layer "In2.Cu")
		(net "M_M_ODT<3>")
	)
	(segment
		(start 110.081568 -130.7338)
		(end 109.954568 -130.6068)
		(width 0.14224)
		(layer "In2.Cu")
		(net "M_M_ODT<3>")
	)
	(segment
		(start 101.140768 -93.9292)
		(end 101.140768 -93.5228)
		(width 0.14224)
		(layer "In2.Cu")
		(net "M_M_ODT<3>")
	)
	(segment
		(start 101.318568 -97.663)
		(end 101.013768 -97.3582)
		(width 0.14224)
		(layer "In2.Cu")
		(net "M_M_ODT<3>")
	)
	(segment
		(start 102.029768 -99.3648)
		(end 102.029768 -98.9838)
		(width 0.14224)
		(layer "In2.Cu")
		(net "M_M_ODT<3>")
	)
	(segment
		(start 101.039168 -95.4278)
		(end 101.039168 -95.0214)
		(width 0.14224)
		(layer "In2.Cu")
		(net "M_M_ODT<3>")
	)
	(segment
		(start 101.039168 -94.4118)
		(end 101.039168 -94.0308)
		(width 0.14224)
		(layer "In2.Cu")
		(net "M_M_ODT<3>")
	)
	(segment
		(start 109.662468 -145.302732)
		(end 109.662468 -144.531588)
		(width 0.14224)
		(layer "In2.Cu")
		(net "M_M_ODT<3>")
	)
	(segment
		(start 106.116374 -125.320806)
		(end 106.116374 -124.28347)
		(width 0.14224)
		(layer "In2.Cu")
		(net "M_M_ODT<3>")
	)
	(segment
		(start 110.036356 -136.062212)
		(end 109.64418 -135.670036)
		(width 0.14224)
		(layer "In2.Cu")
		(net "M_M_ODT<3>")
	)
	(segment
		(start 102.004368 -98.3996)
		(end 102.004368 -97.9932)
		(width 0.14224)
		(layer "In2.Cu")
		(net "M_M_ODT<3>")
	)
	(segment
		(start 101.140768 -93.5228)
		(end 101.005132 -93.387164)
		(width 0.14224)
		(layer "In2.Cu")
		(net "M_M_ODT<3>")
	)
	(segment
		(start 101.140768 -95.9104)
		(end 101.140768 -95.5294)
		(width 0.14224)
		(layer "In2.Cu")
		(net "M_M_ODT<3>")
	)
	(segment
		(start 101.674168 -97.663)
		(end 101.318568 -97.663)
		(width 0.14224)
		(layer "In2.Cu")
		(net "M_M_ODT<3>")
	)
	(segment
		(start 110.081568 -131.2164)
		(end 110.081568 -130.7338)
		(width 0.14224)
		(layer "In2.Cu")
		(net "M_M_ODT<3>")
	)
	(segment
		(start 110.875826 -149.054058)
		(end 110.875826 -147.377658)
		(width 0.14224)
		(layer "In2.Cu")
		(net "M_M_ODT<3>")
	)
	(segment
		(start 101.013768 -97.0026)
		(end 101.140768 -96.8756)
		(width 0.14224)
		(layer "In2.Cu")
		(net "M_M_ODT<3>")
	)
	(segment
		(start 110.036356 -146.538188)
		(end 110.036356 -145.67662)
		(width 0.14224)
		(layer "In2.Cu")
		(net "M_M_ODT<3>")
	)
	(segment
		(start 100.659184 -92.076016)
		(end 100.659184 -91.747086)
		(width 0.14224)
		(layer "In2.Cu")
		(net "M_M_ODT<3>")
	)
	(segment
		(start 111.299498 -149.47773)
		(end 110.875826 -149.054058)
		(width 0.14224)
		(layer "In2.Cu")
		(net "M_M_ODT<3>")
	)
	(segment
		(start 110.056168 -129.8702)
		(end 110.056168 -129.2606)
		(width 0.14224)
		(layer "In2.Cu")
		(net "M_M_ODT<3>")
	)
	(segment
		(start 106.116374 -124.28347)
		(end 102.436168 -120.603264)
		(width 0.14224)
		(layer "In2.Cu")
		(net "M_M_ODT<3>")
	)
	(segment
		(start 101.039168 -95.0214)
		(end 101.140768 -94.9198)
		(width 0.14224)
		(layer "In2.Cu")
		(net "M_M_ODT<3>")
	)
	(segment
		(start 110.01375 -142.807182)
		(end 110.01375 -140.834618)
		(width 0.14224)
		(layer "In2.Cu")
		(net "M_M_ODT<3>")
	)
	(segment
		(start 110.036102 -132.237734)
		(end 109.979968 -132.1816)
		(width 0.14224)
		(layer "In2.Cu")
		(net "M_M_ODT<3>")
	)
	(segment
		(start 102.436168 -102.9462)
		(end 102.156768 -102.6668)
		(width 0.14224)
		(layer "In2.Cu")
		(net "M_M_ODT<3>")
	)
	(segment
		(start 109.64418 -135.670036)
		(end 109.64418 -135.152892)
		(width 0.14224)
		(layer "In2.Cu")
		(net "M_M_ODT<3>")
	)
	(segment
		(start 101.140768 -92.5576)
		(end 100.659184 -92.076016)
		(width 0.14224)
		(layer "In2.Cu")
		(net "M_M_ODT<3>")
	)
	(segment
		(start 109.670342 -140.49121)
		(end 109.670342 -139.806426)
		(width 0.14224)
		(layer "In2.Cu")
		(net "M_M_ODT<3>")
	)
	(segment
		(start 110.056168 -129.2606)
		(end 106.116374 -125.320806)
		(width 0.14224)
		(layer "In2.Cu")
		(net "M_M_ODT<3>")
	)
	(segment
		(start 109.670342 -139.806426)
		(end 110.036356 -139.440412)
		(width 0.14224)
		(layer "In2.Cu")
		(net "M_M_ODT<3>")
	)
	(segment
		(start 110.03661 -144.157446)
		(end 110.03661 -142.830042)
		(width 0.14224)
		(layer "In2.Cu")
		(net "M_M_ODT<3>")
	)
	(segment
		(start 101.877368 -99.5172)
		(end 102.029768 -99.3648)
		(width 0.14224)
		(layer "In2.Cu")
		(net "M_M_ODT<3>")
	)
	(segment
		(start 101.005132 -93.099636)
		(end 101.140768 -92.964)
		(width 0.14224)
		(layer "In2.Cu")
		(net "M_M_ODT<3>")
	)
	(segment
		(start 101.013768 -96.0374)
		(end 101.140768 -95.9104)
		(width 0.14224)
		(layer "In2.Cu")
		(net "M_M_ODT<3>")
	)
	(segment
		(start 110.036356 -139.440412)
		(end 110.036356 -136.062212)
		(width 0.14224)
		(layer "In2.Cu")
		(net "M_M_ODT<3>")
	)
	(segment
		(start 101.039168 -94.0308)
		(end 101.140768 -93.9292)
		(width 0.14224)
		(layer "In2.Cu")
		(net "M_M_ODT<3>")
	)
	(segment
		(start 101.140768 -96.52)
		(end 101.013768 -96.393)
		(width 0.14224)
		(layer "In2.Cu")
		(net "M_M_ODT<3>")
	)
	(segment
		(start 109.979968 -131.318)
		(end 110.081568 -131.2164)
		(width 0.14224)
		(layer "In2.Cu")
		(net "M_M_ODT<3>")
	)
	(segment
		(start 101.140768 -96.8756)
		(end 101.140768 -96.52)
		(width 0.14224)
		(layer "In2.Cu")
		(net "M_M_ODT<3>")
	)
	(segment
		(start 102.156768 -102.1842)
		(end 101.877368 -101.9048)
		(width 0.14224)
		(layer "In2.Cu")
		(net "M_M_ODT<3>")
	)
	(segment
		(start 101.005132 -93.387164)
		(end 101.005132 -93.099636)
		(width 0.14224)
		(layer "In2.Cu")
		(net "M_M_ODT<3>")
	)
	(segment
		(start 101.860604 -98.543364)
		(end 102.004368 -98.3996)
		(width 0.14224)
		(layer "In2.Cu")
		(net "M_M_ODT<3>")
	)
	(segment
		(start 102.156768 -102.6668)
		(end 102.156768 -102.1842)
		(width 0.14224)
		(layer "In2.Cu")
		(net "M_M_ODT<3>")
	)
	(segment
		(start 111.299498 -150.789386)
		(end 111.299498 -149.47773)
		(width 0.14224)
		(layer "In2.Cu")
		(net "M_M_ODT<3>")
	)
	(segment
		(start 109.954568 -129.9718)
		(end 110.056168 -129.8702)
		(width 0.14224)
		(layer "In2.Cu")
		(net "M_M_ODT<3>")
	)
	(segment
		(start 109.662468 -144.531588)
		(end 110.03661 -144.157446)
		(width 0.14224)
		(layer "In2.Cu")
		(net "M_M_ODT<3>")
	)
	(segment
		(start 110.01375 -140.834618)
		(end 109.670342 -140.49121)
		(width 0.14224)
		(layer "In2.Cu")
		(net "M_M_ODT<3>")
	)
	(segment
		(start 110.036102 -134.76097)
		(end 110.036102 -132.237734)
		(width 0.14224)
		(layer "In2.Cu")
		(net "M_M_ODT<3>")
	)
	(segment
		(start 101.140768 -95.5294)
		(end 101.039168 -95.4278)
		(width 0.14224)
		(layer "In2.Cu")
		(net "M_M_ODT<3>")
	)
	(segment
		(start 99.513898 -93.72854)
		(end 98.942398 -93.72854)
		(width 0.1016)
		(layer "F.Cu")
		(net "M_M_ODT<2>")
	)
	(via
		(at 98.942398 -93.72854)
		(size 0.508)
		(drill 0.254)
		(layers "F.Cu" "B.Cu")
		(net "M_M_ODT<2>")
	)
	(via
		(at 107.899454 -150.785068)
		(size 0.4572)
		(drill 0.2032)
		(layers "F.Cu" "B.Cu")
		(net "M_M_ODT<2>")
	)
	(segment
		(start 107.899454 -152.078436)
		(end 107.899454 -150.785068)
		(width 0.1651)
		(layer "B.Cu")
		(net "M_M_ODT<2>")
	)
	(segment
		(start 100.404168 -103.19131)
		(end 100.404168 -122.483372)
		(width 0.14224)
		(layer "In2.Cu")
		(net "M_M_ODT<2>")
	)
	(segment
		(start 99.279964 -98.466148)
		(end 99.288854 -98.481388)
		(width 0.0889)
		(layer "In2.Cu")
		(net "M_M_ODT<2>")
	)
	(segment
		(start 99.279964 -97.475548)
		(end 99.288854 -97.490788)
		(width 0.0889)
		(layer "In2.Cu")
		(net "M_M_ODT<2>")
	)
	(segment
		(start 104.514396 -127.401828)
		(end 104.80167 -127.689102)
		(width 0.14224)
		(layer "In2.Cu")
		(net "M_M_ODT<2>")
	)
	(segment
		(start 106.5022 -135.931656)
		(end 106.632756 -136.062212)
		(width 0.14224)
		(layer "In2.Cu")
		(net "M_M_ODT<2>")
	)
	(segment
		(start 106.550968 -131.2926)
		(end 106.550968 -132.1308)
		(width 0.14224)
		(layer "In2.Cu")
		(net "M_M_ODT<2>")
	)
	(segment
		(start 106.525568 -130.386328)
		(end 106.776774 -130.637534)
		(width 0.14224)
		(layer "In2.Cu")
		(net "M_M_ODT<2>")
	)
	(segment
		(start 105.493312 -127.572516)
		(end 105.780586 -127.85979)
		(width 0.14224)
		(layer "In2.Cu")
		(net "M_M_ODT<2>")
	)
	(segment
		(start 105.780586 -128.147318)
		(end 105.664 -128.263904)
		(width 0.14224)
		(layer "In2.Cu")
		(net "M_M_ODT<2>")
	)
	(segment
		(start 106.642916 -128.72212)
		(end 106.926634 -129.005838)
		(width 0.14224)
		(layer "In2.Cu")
		(net "M_M_ODT<2>")
	)
	(segment
		(start 98.942398 -93.72854)
		(end 99.272852 -94.491556)
		(width 0.0889)
		(layer "In2.Cu")
		(net "M_M_ODT<2>")
	)
	(segment
		(start 100.404168 -122.483372)
		(end 104.630982 -126.710186)
		(width 0.14224)
		(layer "In2.Cu")
		(net "M_M_ODT<2>")
	)
	(segment
		(start 100.404168 -102.8954)
		(end 100.404168 -103.19131)
		(width 0.0889)
		(layer "In2.Cu")
		(net "M_M_ODT<2>")
	)
	(segment
		(start 99.279964 -95.494348)
		(end 99.288854 -95.509588)
		(width 0.0889)
		(layer "In2.Cu")
		(net "M_M_ODT<2>")
	)
	(segment
		(start 106.640122 -144.259046)
		(end 106.500168 -144.399)
		(width 0.14224)
		(layer "In2.Cu")
		(net "M_M_ODT<2>")
	)
	(segment
		(start 105.780586 -127.85979)
		(end 105.780586 -128.147318)
		(width 0.14224)
		(layer "In2.Cu")
		(net "M_M_ODT<2>")
	)
	(segment
		(start 107.899454 -149.506686)
		(end 107.899454 -150.785068)
		(width 0.14224)
		(layer "In2.Cu")
		(net "M_M_ODT<2>")
	)
	(segment
		(start 106.636566 -145.685002)
		(end 106.636566 -146.719798)
		(width 0.14224)
		(layer "In2.Cu")
		(net "M_M_ODT<2>")
	)
	(segment
		(start 104.630982 -126.997714)
		(end 104.514396 -127.1143)
		(width 0.14224)
		(layer "In2.Cu")
		(net "M_M_ODT<2>")
	)
	(segment
		(start 106.636566 -146.719798)
		(end 107.46105 -147.544282)
		(width 0.14224)
		(layer "In2.Cu")
		(net "M_M_ODT<2>")
	)
	(segment
		(start 106.632756 -136.062212)
		(end 106.632756 -139.567412)
		(width 0.14224)
		(layer "In2.Cu")
		(net "M_M_ODT<2>")
	)
	(segment
		(start 100.124768 -102.616)
		(end 100.404168 -102.8954)
		(width 0.0889)
		(layer "In2.Cu")
		(net "M_M_ODT<2>")
	)
	(segment
		(start 106.776774 -130.637534)
		(end 106.776774 -131.066794)
		(width 0.14224)
		(layer "In2.Cu")
		(net "M_M_ODT<2>")
	)
	(segment
		(start 106.500168 -145.548604)
		(end 106.636566 -145.685002)
		(width 0.14224)
		(layer "In2.Cu")
		(net "M_M_ODT<2>")
	)
	(segment
		(start 105.089198 -127.689102)
		(end 105.205784 -127.572516)
		(width 0.14224)
		(layer "In2.Cu")
		(net "M_M_ODT<2>")
	)
	(segment
		(start 99.279964 -96.484948)
		(end 99.288854 -96.500188)
		(width 0.0889)
		(layer "In2.Cu")
		(net "M_M_ODT<2>")
	)
	(segment
		(start 105.664 -128.551432)
		(end 105.951274 -128.838706)
		(width 0.14224)
		(layer "In2.Cu")
		(net "M_M_ODT<2>")
	)
	(segment
		(start 104.514396 -127.1143)
		(end 104.514396 -127.401828)
		(width 0.14224)
		(layer "In2.Cu")
		(net "M_M_ODT<2>")
	)
	(segment
		(start 106.238802 -128.838706)
		(end 106.355388 -128.72212)
		(width 0.14224)
		(layer "In2.Cu")
		(net "M_M_ODT<2>")
	)
	(segment
		(start 106.500168 -144.399)
		(end 106.500168 -145.548604)
		(width 0.14224)
		(layer "In2.Cu")
		(net "M_M_ODT<2>")
	)
	(segment
		(start 106.550968 -132.1308)
		(end 106.636312 -132.216144)
		(width 0.14224)
		(layer "In2.Cu")
		(net "M_M_ODT<2>")
	)
	(segment
		(start 106.776774 -131.066794)
		(end 106.550968 -131.2926)
		(width 0.14224)
		(layer "In2.Cu")
		(net "M_M_ODT<2>")
	)
	(segment
		(start 105.951274 -128.838706)
		(end 106.238802 -128.838706)
		(width 0.14224)
		(layer "In2.Cu")
		(net "M_M_ODT<2>")
	)
	(segment
		(start 106.632756 -139.567412)
		(end 106.5022 -139.697968)
		(width 0.14224)
		(layer "In2.Cu")
		(net "M_M_ODT<2>")
	)
	(segment
		(start 106.636312 -134.636256)
		(end 106.5022 -134.770368)
		(width 0.14224)
		(layer "In2.Cu")
		(net "M_M_ODT<2>")
	)
	(segment
		(start 100.124768 -100.4316)
		(end 100.124768 -102.616)
		(width 0.0889)
		(layer "In2.Cu")
		(net "M_M_ODT<2>")
	)
	(segment
		(start 105.205784 -127.572516)
		(end 105.493312 -127.572516)
		(width 0.14224)
		(layer "In2.Cu")
		(net "M_M_ODT<2>")
	)
	(segment
		(start 106.640122 -140.924026)
		(end 106.640122 -144.259046)
		(width 0.14224)
		(layer "In2.Cu")
		(net "M_M_ODT<2>")
	)
	(segment
		(start 99.743768 -100.0506)
		(end 100.124768 -100.4316)
		(width 0.0889)
		(layer "In2.Cu")
		(net "M_M_ODT<2>")
	)
	(segment
		(start 106.926634 -129.570734)
		(end 106.525568 -129.9718)
		(width 0.14224)
		(layer "In2.Cu")
		(net "M_M_ODT<2>")
	)
	(segment
		(start 99.272852 -94.491556)
		(end 99.288854 -94.518988)
		(width 0.0889)
		(layer "In2.Cu")
		(net "M_M_ODT<2>")
	)
	(segment
		(start 107.46105 -149.068282)
		(end 107.899454 -149.506686)
		(width 0.14224)
		(layer "In2.Cu")
		(net "M_M_ODT<2>")
	)
	(segment
		(start 106.5022 -140.786104)
		(end 106.640122 -140.924026)
		(width 0.14224)
		(layer "In2.Cu")
		(net "M_M_ODT<2>")
	)
	(segment
		(start 106.5022 -134.770368)
		(end 106.5022 -135.931656)
		(width 0.14224)
		(layer "In2.Cu")
		(net "M_M_ODT<2>")
	)
	(segment
		(start 106.355388 -128.72212)
		(end 106.642916 -128.72212)
		(width 0.14224)
		(layer "In2.Cu")
		(net "M_M_ODT<2>")
	)
	(segment
		(start 105.664 -128.263904)
		(end 105.664 -128.551432)
		(width 0.14224)
		(layer "In2.Cu")
		(net "M_M_ODT<2>")
	)
	(segment
		(start 104.80167 -127.689102)
		(end 105.089198 -127.689102)
		(width 0.14224)
		(layer "In2.Cu")
		(net "M_M_ODT<2>")
	)
	(segment
		(start 106.926634 -129.005838)
		(end 106.926634 -129.570734)
		(width 0.14224)
		(layer "In2.Cu")
		(net "M_M_ODT<2>")
	)
	(segment
		(start 104.630982 -126.710186)
		(end 104.630982 -126.997714)
		(width 0.14224)
		(layer "In2.Cu")
		(net "M_M_ODT<2>")
	)
	(segment
		(start 106.5022 -139.697968)
		(end 106.5022 -140.786104)
		(width 0.14224)
		(layer "In2.Cu")
		(net "M_M_ODT<2>")
	)
	(segment
		(start 106.525568 -129.9718)
		(end 106.525568 -130.386328)
		(width 0.14224)
		(layer "In2.Cu")
		(net "M_M_ODT<2>")
	)
	(segment
		(start 106.636312 -132.216144)
		(end 106.636312 -134.636256)
		(width 0.14224)
		(layer "In2.Cu")
		(net "M_M_ODT<2>")
	)
	(segment
		(start 107.46105 -147.544282)
		(end 107.46105 -149.068282)
		(width 0.14224)
		(layer "In2.Cu")
		(net "M_M_ODT<2>")
	)
	(arc
		(start 99.288854 -96.899984)
		(mid 99.209665 -97.186599)
		(end 99.279964 -97.475548)
		(width 0.0889)
		(layer "In2.Cu")
		(net "M_M_ODT<2>")
	)
	(arc
		(start 99.288854 -98.481388)
		(mid 99.342387 -98.681286)
		(end 99.288854 -98.881184)
		(width 0.0889)
		(layer "In2.Cu")
		(net "M_M_ODT<2>")
	)
	(arc
		(start 99.288854 -96.500188)
		(mid 99.342387 -96.700086)
		(end 99.288854 -96.899984)
		(width 0.0889)
		(layer "In2.Cu")
		(net "M_M_ODT<2>")
	)
	(arc
		(start 99.288854 -94.518988)
		(mid 99.342387 -94.718886)
		(end 99.288854 -94.918784)
		(width 0.0889)
		(layer "In2.Cu")
		(net "M_M_ODT<2>")
	)
	(arc
		(start 99.288854 -94.918784)
		(mid 99.209665 -95.205399)
		(end 99.279964 -95.494348)
		(width 0.0889)
		(layer "In2.Cu")
		(net "M_M_ODT<2>")
	)
	(arc
		(start 99.288854 -97.890584)
		(mid 99.209665 -98.177199)
		(end 99.279964 -98.466148)
		(width 0.0889)
		(layer "In2.Cu")
		(net "M_M_ODT<2>")
	)
	(arc
		(start 99.288854 -97.490788)
		(mid 99.342387 -97.690686)
		(end 99.288854 -97.890584)
		(width 0.0889)
		(layer "In2.Cu")
		(net "M_M_ODT<2>")
	)
	(arc
		(start 99.277932 -99.452684)
		(mid 99.484415 -99.772239)
		(end 99.743768 -100.0506)
		(width 0.0889)
		(layer "In2.Cu")
		(net "M_M_ODT<2>")
	)
	(arc
		(start 99.288854 -95.509588)
		(mid 99.342387 -95.709486)
		(end 99.288854 -95.909384)
		(width 0.0889)
		(layer "In2.Cu")
		(net "M_M_ODT<2>")
	)
	(arc
		(start 99.288854 -95.909384)
		(mid 99.209665 -96.195999)
		(end 99.279964 -96.484948)
		(width 0.0889)
		(layer "In2.Cu")
		(net "M_M_ODT<2>")
	)
	(arc
		(start 99.288854 -98.881184)
		(mid 99.209704 -99.165528)
		(end 99.277932 -99.452684)
		(width 0.0889)
		(layer "In2.Cu")
		(net "M_M_ODT<2>")
	)
	(segment
		(start 100.372164 -92.24264)
		(end 99.800664 -92.24264)
		(width 0.1016)
		(layer "F.Cu")
		(net "M_M_ODT<1>")
	)
	(segment
		(start 111.299498 -152.273)
		(end 111.299498 -153.571956)
		(width 0.1651)
		(layer "F.Cu")
		(net "M_M_ODT<1>")
	)
	(via
		(at 111.299498 -153.571956)
		(size 0.508)
		(drill 0.254)
		(layers "F.Cu" "B.Cu")
		(net "M_M_ODT<1>")
	)
	(via
		(at 99.800664 -92.24264)
		(size 0.508)
		(drill 0.254)
		(layers "F.Cu" "B.Cu")
		(net "M_M_ODT<1>")
	)
	(segment
		(start 110.039912 -149.0726)
		(end 110.039912 -147.354544)
		(width 0.14224)
		(layer "In2.Cu")
		(net "M_M_ODT<1>")
	)
	(segment
		(start 109.159294 -140.835126)
		(end 109.159294 -134.043674)
		(width 0.14224)
		(layer "In2.Cu")
		(net "M_M_ODT<1>")
	)
	(segment
		(start 110.039912 -147.354544)
		(end 109.161326 -146.475958)
		(width 0.14224)
		(layer "In2.Cu")
		(net "M_M_ODT<1>")
	)
	(segment
		(start 109.044486 -130.678682)
		(end 109.290612 -130.432556)
		(width 0.14224)
		(layer "In2.Cu")
		(net "M_M_ODT<1>")
	)
	(segment
		(start 110.890558 -153.163016)
		(end 110.890558 -149.923246)
		(width 0.14224)
		(layer "In2.Cu")
		(net "M_M_ODT<1>")
	)
	(segment
		(start 111.299498 -153.571956)
		(end 110.890558 -153.163016)
		(width 0.14224)
		(layer "In2.Cu")
		(net "M_M_ODT<1>")
	)
	(segment
		(start 100.312474 -95.509588)
		(end 100.318824 -95.49892)
		(width 0.0889)
		(layer "In2.Cu")
		(net "M_M_ODT<1>")
	)
	(segment
		(start 109.159294 -134.043674)
		(end 109.268768 -133.9342)
		(width 0.14224)
		(layer "In2.Cu")
		(net "M_M_ODT<1>")
	)
	(segment
		(start 110.890558 -149.923246)
		(end 110.039912 -149.0726)
		(width 0.14224)
		(layer "In2.Cu")
		(net "M_M_ODT<1>")
	)
	(segment
		(start 100.307648 -95.518224)
		(end 100.312474 -95.509588)
		(width 0.0889)
		(layer "In2.Cu")
		(net "M_M_ODT<1>")
	)
	(segment
		(start 109.065568 -128.98882)
		(end 105.608374 -125.531626)
		(width 0.14224)
		(layer "In2.Cu")
		(net "M_M_ODT<1>")
	)
	(segment
		(start 109.161326 -146.475958)
		(end 109.161326 -142.094966)
		(width 0.14224)
		(layer "In2.Cu")
		(net "M_M_ODT<1>")
	)
	(segment
		(start 100.28682 -92.897198)
		(end 99.800664 -92.24264)
		(width 0.0889)
		(layer "In2.Cu")
		(net "M_M_ODT<1>")
	)
	(segment
		(start 100.312474 -97.490788)
		(end 100.318824 -97.48012)
		(width 0.0889)
		(layer "In2.Cu")
		(net "M_M_ODT<1>")
	)
	(segment
		(start 109.268768 -133.9342)
		(end 109.268768 -131.3434)
		(width 0.14224)
		(layer "In2.Cu")
		(net "M_M_ODT<1>")
	)
	(segment
		(start 109.185202 -142.07109)
		(end 109.185202 -140.861034)
		(width 0.14224)
		(layer "In2.Cu")
		(net "M_M_ODT<1>")
	)
	(segment
		(start 105.608374 -124.494036)
		(end 101.928168 -120.81383)
		(width 0.14224)
		(layer "In2.Cu")
		(net "M_M_ODT<1>")
	)
	(segment
		(start 101.674168 -102.902512)
		(end 101.674168 -102.2096)
		(width 0.0889)
		(layer "In2.Cu")
		(net "M_M_ODT<1>")
	)
	(segment
		(start 100.624386 -98.24466)
		(end 100.351336 -97.97161)
		(width 0.0889)
		(layer "In2.Cu")
		(net "M_M_ODT<1>")
	)
	(segment
		(start 101.928168 -103.406194)
		(end 101.928168 -103.156512)
		(width 0.0889)
		(layer "In2.Cu")
		(net "M_M_ODT<1>")
	)
	(segment
		(start 109.290612 -130.019044)
		(end 109.065568 -129.794)
		(width 0.14224)
		(layer "In2.Cu")
		(net "M_M_ODT<1>")
	)
	(segment
		(start 109.268768 -131.3434)
		(end 109.044486 -131.119118)
		(width 0.14224)
		(layer "In2.Cu")
		(net "M_M_ODT<1>")
	)
	(segment
		(start 101.115368 -98.514916)
		(end 100.845112 -98.24466)
		(width 0.0889)
		(layer "In2.Cu")
		(net "M_M_ODT<1>")
	)
	(segment
		(start 100.845112 -98.24466)
		(end 100.624386 -98.24466)
		(width 0.0889)
		(layer "In2.Cu")
		(net "M_M_ODT<1>")
	)
	(segment
		(start 109.044486 -131.119118)
		(end 109.044486 -130.678682)
		(width 0.14224)
		(layer "In2.Cu")
		(net "M_M_ODT<1>")
	)
	(segment
		(start 100.307648 -96.508824)
		(end 100.312474 -96.500188)
		(width 0.0889)
		(layer "In2.Cu")
		(net "M_M_ODT<1>")
	)
	(segment
		(start 101.115368 -101.6508)
		(end 101.115368 -98.514916)
		(width 0.0889)
		(layer "In2.Cu")
		(net "M_M_ODT<1>")
	)
	(segment
		(start 100.312474 -96.500188)
		(end 100.318824 -96.48952)
		(width 0.0889)
		(layer "In2.Cu")
		(net "M_M_ODT<1>")
	)
	(segment
		(start 100.307648 -94.527624)
		(end 100.312474 -94.518988)
		(width 0.0889)
		(layer "In2.Cu")
		(net "M_M_ODT<1>")
	)
	(segment
		(start 101.674168 -102.2096)
		(end 101.115368 -101.6508)
		(width 0.0889)
		(layer "In2.Cu")
		(net "M_M_ODT<1>")
	)
	(segment
		(start 109.185202 -140.861034)
		(end 109.159294 -140.835126)
		(width 0.14224)
		(layer "In2.Cu")
		(net "M_M_ODT<1>")
	)
	(segment
		(start 109.290612 -130.432556)
		(end 109.290612 -130.019044)
		(width 0.14224)
		(layer "In2.Cu")
		(net "M_M_ODT<1>")
	)
	(segment
		(start 100.307648 -97.499424)
		(end 100.312474 -97.490788)
		(width 0.0889)
		(layer "In2.Cu")
		(net "M_M_ODT<1>")
	)
	(segment
		(start 105.608374 -125.531626)
		(end 105.608374 -124.494036)
		(width 0.14224)
		(layer "In2.Cu")
		(net "M_M_ODT<1>")
	)
	(segment
		(start 109.065568 -129.794)
		(end 109.065568 -128.98882)
		(width 0.14224)
		(layer "In2.Cu")
		(net "M_M_ODT<1>")
	)
	(segment
		(start 109.161326 -142.094966)
		(end 109.185202 -142.07109)
		(width 0.14224)
		(layer "In2.Cu")
		(net "M_M_ODT<1>")
	)
	(segment
		(start 101.928168 -120.81383)
		(end 101.928168 -103.406194)
		(width 0.14224)
		(layer "In2.Cu")
		(net "M_M_ODT<1>")
	)
	(segment
		(start 100.318824 -93.939106)
		(end 100.312474 -93.928438)
		(width 0.0889)
		(layer "In2.Cu")
		(net "M_M_ODT<1>")
	)
	(segment
		(start 101.928168 -103.156512)
		(end 101.674168 -102.902512)
		(width 0.0889)
		(layer "In2.Cu")
		(net "M_M_ODT<1>")
	)
	(arc
		(start 100.312474 -93.928438)
		(mid 100.258975 -93.72854)
		(end 100.312474 -93.528642)
		(width 0.0889)
		(layer "In2.Cu")
		(net "M_M_ODT<1>")
	)
	(arc
		(start 100.312474 -93.528642)
		(mid 100.391117 -93.209211)
		(end 100.28682 -92.897198)
		(width 0.0889)
		(layer "In2.Cu")
		(net "M_M_ODT<1>")
	)
	(arc
		(start 100.318824 -97.48012)
		(mid 100.391622 -97.189357)
		(end 100.312474 -96.900238)
		(width 0.0889)
		(layer "In2.Cu")
		(net "M_M_ODT<1>")
	)
	(arc
		(start 100.351336 -97.97161)
		(mid 100.333436 -97.930488)
		(end 100.312474 -97.890838)
		(width 0.0889)
		(layer "In2.Cu")
		(net "M_M_ODT<1>")
	)
	(arc
		(start 100.312474 -94.919038)
		(mid 100.259004 -94.723975)
		(end 100.307648 -94.527624)
		(width 0.0889)
		(layer "In2.Cu")
		(net "M_M_ODT<1>")
	)
	(arc
		(start 100.312474 -95.909638)
		(mid 100.259004 -95.714575)
		(end 100.307648 -95.518224)
		(width 0.0889)
		(layer "In2.Cu")
		(net "M_M_ODT<1>")
	)
	(arc
		(start 100.318824 -95.49892)
		(mid 100.391622 -95.208157)
		(end 100.312474 -94.919038)
		(width 0.0889)
		(layer "In2.Cu")
		(net "M_M_ODT<1>")
	)
	(arc
		(start 100.312474 -96.900238)
		(mid 100.259004 -96.705175)
		(end 100.307648 -96.508824)
		(width 0.0889)
		(layer "In2.Cu")
		(net "M_M_ODT<1>")
	)
	(arc
		(start 100.312474 -97.890838)
		(mid 100.259004 -97.695775)
		(end 100.307648 -97.499424)
		(width 0.0889)
		(layer "In2.Cu")
		(net "M_M_ODT<1>")
	)
	(arc
		(start 100.312474 -94.518988)
		(mid 100.391696 -94.22987)
		(end 100.318824 -93.939106)
		(width 0.0889)
		(layer "In2.Cu")
		(net "M_M_ODT<1>")
	)
	(arc
		(start 100.318824 -96.48952)
		(mid 100.391622 -96.198757)
		(end 100.312474 -95.909638)
		(width 0.0889)
		(layer "In2.Cu")
		(net "M_M_ODT<1>")
	)
	(segment
		(start 98.655378 -92.24264)
		(end 98.083878 -92.24264)
		(width 0.1016)
		(layer "F.Cu")
		(net "M_M_ODT<0>")
	)
	(segment
		(start 107.899454 -152.273)
		(end 107.899454 -153.571956)
		(width 0.1651)
		(layer "F.Cu")
		(net "M_M_ODT<0>")
	)
	(via
		(at 107.899454 -153.571956)
		(size 0.508)
		(drill 0.254)
		(layers "F.Cu" "B.Cu")
		(net "M_M_ODT<0>")
	)
	(via
		(at 98.083878 -92.24264)
		(size 0.508)
		(drill 0.254)
		(layers "F.Cu" "B.Cu")
		(net "M_M_ODT<0>")
	)
	(segment
		(start 105.759504 -139.500356)
		(end 105.759504 -141.375892)
		(width 0.14224)
		(layer "In2.Cu")
		(net "M_M_ODT<0>")
	)
	(segment
		(start 98.595688 -97.490788)
		(end 98.590862 -97.499424)
		(width 0.0889)
		(layer "In2.Cu")
		(net "M_M_ODT<0>")
	)
	(segment
		(start 98.083878 -92.24264)
		(end 98.083878 -92.57411)
		(width 0.0889)
		(layer "In2.Cu")
		(net "M_M_ODT<0>")
	)
	(segment
		(start 99.896168 -102.6922)
		(end 99.896168 -103.058214)
		(width 0.0889)
		(layer "In2.Cu")
		(net "M_M_ODT<0>")
	)
	(segment
		(start 105.687368 -131.1402)
		(end 106.017568 -131.4704)
		(width 0.14224)
		(layer "In2.Cu")
		(net "M_M_ODT<0>")
	)
	(segment
		(start 98.602038 -96.48952)
		(end 98.595688 -96.500188)
		(width 0.0889)
		(layer "In2.Cu")
		(net "M_M_ODT<0>")
	)
	(segment
		(start 107.479846 -149.78507)
		(end 107.479846 -151.34844)
		(width 0.14224)
		(layer "In2.Cu")
		(net "M_M_ODT<0>")
	)
	(segment
		(start 105.763314 -139.496546)
		(end 105.759504 -139.500356)
		(width 0.14224)
		(layer "In2.Cu")
		(net "M_M_ODT<0>")
	)
	(segment
		(start 99.896168 -122.693938)
		(end 103.909368 -126.707138)
		(width 0.14224)
		(layer "In2.Cu")
		(net "M_M_ODT<0>")
	)
	(segment
		(start 98.602038 -97.48012)
		(end 98.595688 -97.490788)
		(width 0.0889)
		(layer "In2.Cu")
		(net "M_M_ODT<0>")
	)
	(segment
		(start 99.896168 -103.058214)
		(end 99.896168 -122.693938)
		(width 0.14224)
		(layer "In2.Cu")
		(net "M_M_ODT<0>")
	)
	(segment
		(start 98.676968 -100.249736)
		(end 99.921568 -101.494336)
		(width 0.0889)
		(layer "In2.Cu")
		(net "M_M_ODT<0>")
	)
	(segment
		(start 98.557334 -93.047566)
		(end 98.557334 -93.61932)
		(width 0.0889)
		(layer "In2.Cu")
		(net "M_M_ODT<0>")
	)
	(segment
		(start 98.702368 -99.6442)
		(end 98.676968 -99.6696)
		(width 0.0889)
		(layer "In2.Cu")
		(net "M_M_ODT<0>")
	)
	(segment
		(start 98.602038 -95.49892)
		(end 98.595688 -95.509588)
		(width 0.0889)
		(layer "In2.Cu")
		(net "M_M_ODT<0>")
	)
	(segment
		(start 105.763314 -133.909054)
		(end 105.763314 -139.496546)
		(width 0.14224)
		(layer "In2.Cu")
		(net "M_M_ODT<0>")
	)
	(segment
		(start 105.687368 -130.6576)
		(end 105.687368 -131.1402)
		(width 0.14224)
		(layer "In2.Cu")
		(net "M_M_ODT<0>")
	)
	(segment
		(start 103.909368 -127.61341)
		(end 105.496868 -129.20091)
		(width 0.14224)
		(layer "In2.Cu")
		(net "M_M_ODT<0>")
	)
	(segment
		(start 106.042968 -143.1798)
		(end 105.763314 -143.459454)
		(width 0.14224)
		(layer "In2.Cu")
		(net "M_M_ODT<0>")
	)
	(segment
		(start 106.017568 -131.4704)
		(end 106.017568 -133.6548)
		(width 0.14224)
		(layer "In2.Cu")
		(net "M_M_ODT<0>")
	)
	(segment
		(start 98.595688 -96.500188)
		(end 98.590862 -96.508824)
		(width 0.0889)
		(layer "In2.Cu")
		(net "M_M_ODT<0>")
	)
	(segment
		(start 105.759504 -141.375892)
		(end 106.042968 -141.659356)
		(width 0.14224)
		(layer "In2.Cu")
		(net "M_M_ODT<0>")
	)
	(segment
		(start 98.083878 -92.57411)
		(end 98.557334 -93.047566)
		(width 0.0889)
		(layer "In2.Cu")
		(net "M_M_ODT<0>")
	)
	(segment
		(start 105.763314 -143.459454)
		(end 105.763314 -146.811746)
		(width 0.14224)
		(layer "In2.Cu")
		(net "M_M_ODT<0>")
	)
	(segment
		(start 105.829354 -130.04673)
		(end 105.829354 -130.515614)
		(width 0.14224)
		(layer "In2.Cu")
		(net "M_M_ODT<0>")
	)
	(segment
		(start 98.595688 -94.518988)
		(end 98.590862 -94.527624)
		(width 0.0889)
		(layer "In2.Cu")
		(net "M_M_ODT<0>")
	)
	(segment
		(start 106.017568 -133.6548)
		(end 105.763314 -133.909054)
		(width 0.14224)
		(layer "In2.Cu")
		(net "M_M_ODT<0>")
	)
	(segment
		(start 99.921568 -102.6668)
		(end 99.896168 -102.6922)
		(width 0.0889)
		(layer "In2.Cu")
		(net "M_M_ODT<0>")
	)
	(segment
		(start 105.496868 -129.20091)
		(end 105.496868 -129.714244)
		(width 0.14224)
		(layer "In2.Cu")
		(net "M_M_ODT<0>")
	)
	(segment
		(start 107.479846 -151.34844)
		(end 107.899454 -151.768048)
		(width 0.14224)
		(layer "In2.Cu")
		(net "M_M_ODT<0>")
	)
	(segment
		(start 99.921568 -101.494336)
		(end 99.921568 -102.6668)
		(width 0.0889)
		(layer "In2.Cu")
		(net "M_M_ODT<0>")
	)
	(segment
		(start 98.595688 -98.481388)
		(end 98.590862 -98.490024)
		(width 0.0889)
		(layer "In2.Cu")
		(net "M_M_ODT<0>")
	)
	(segment
		(start 106.042968 -141.659356)
		(end 106.042968 -143.1798)
		(width 0.14224)
		(layer "In2.Cu")
		(net "M_M_ODT<0>")
	)
	(segment
		(start 103.909368 -126.707138)
		(end 103.909368 -127.61341)
		(width 0.14224)
		(layer "In2.Cu")
		(net "M_M_ODT<0>")
	)
	(segment
		(start 106.627168 -147.6756)
		(end 106.627168 -148.932392)
		(width 0.14224)
		(layer "In2.Cu")
		(net "M_M_ODT<0>")
	)
	(segment
		(start 105.763314 -146.811746)
		(end 106.627168 -147.6756)
		(width 0.14224)
		(layer "In2.Cu")
		(net "M_M_ODT<0>")
	)
	(segment
		(start 106.627168 -148.932392)
		(end 107.479846 -149.78507)
		(width 0.14224)
		(layer "In2.Cu")
		(net "M_M_ODT<0>")
	)
	(segment
		(start 105.496868 -129.714244)
		(end 105.829354 -130.04673)
		(width 0.14224)
		(layer "In2.Cu")
		(net "M_M_ODT<0>")
	)
	(segment
		(start 107.899454 -151.768048)
		(end 107.899454 -153.571956)
		(width 0.14224)
		(layer "In2.Cu")
		(net "M_M_ODT<0>")
	)
	(segment
		(start 98.602038 -98.47072)
		(end 98.595688 -98.481388)
		(width 0.0889)
		(layer "In2.Cu")
		(net "M_M_ODT<0>")
	)
	(segment
		(start 98.595688 -95.509588)
		(end 98.590862 -95.518224)
		(width 0.0889)
		(layer "In2.Cu")
		(net "M_M_ODT<0>")
	)
	(segment
		(start 98.676968 -99.6696)
		(end 98.676968 -100.249736)
		(width 0.0889)
		(layer "In2.Cu")
		(net "M_M_ODT<0>")
	)
	(segment
		(start 105.829354 -130.515614)
		(end 105.687368 -130.6576)
		(width 0.14224)
		(layer "In2.Cu")
		(net "M_M_ODT<0>")
	)
	(segment
		(start 98.595688 -93.928438)
		(end 98.602038 -93.939106)
		(width 0.0889)
		(layer "In2.Cu")
		(net "M_M_ODT<0>")
	)
	(arc
		(start 98.595688 -97.890838)
		(mid 98.67491 -98.179956)
		(end 98.602038 -98.47072)
		(width 0.0889)
		(layer "In2.Cu")
		(net "M_M_ODT<0>")
	)
	(arc
		(start 98.590862 -96.508824)
		(mid 98.542107 -96.705176)
		(end 98.595688 -96.900238)
		(width 0.0889)
		(layer "In2.Cu")
		(net "M_M_ODT<0>")
	)
	(arc
		(start 98.595688 -95.909638)
		(mid 98.67491 -96.198756)
		(end 98.602038 -96.48952)
		(width 0.0889)
		(layer "In2.Cu")
		(net "M_M_ODT<0>")
	)
	(arc
		(start 98.590862 -98.490024)
		(mid 98.542107 -98.686376)
		(end 98.595688 -98.881438)
		(width 0.0889)
		(layer "In2.Cu")
		(net "M_M_ODT<0>")
	)
	(arc
		(start 98.590862 -97.499424)
		(mid 98.542107 -97.695776)
		(end 98.595688 -97.890838)
		(width 0.0889)
		(layer "In2.Cu")
		(net "M_M_ODT<0>")
	)
	(arc
		(start 98.602038 -93.939106)
		(mid 98.674836 -94.229869)
		(end 98.595688 -94.518988)
		(width 0.0889)
		(layer "In2.Cu")
		(net "M_M_ODT<0>")
	)
	(arc
		(start 98.595688 -94.919038)
		(mid 98.67491 -95.208156)
		(end 98.602038 -95.49892)
		(width 0.0889)
		(layer "In2.Cu")
		(net "M_M_ODT<0>")
	)
	(arc
		(start 98.557334 -93.61932)
		(mid 98.545183 -93.777771)
		(end 98.595688 -93.928438)
		(width 0.0889)
		(layer "In2.Cu")
		(net "M_M_ODT<0>")
	)
	(arc
		(start 98.595688 -98.881438)
		(mid 98.723147 -99.252449)
		(end 98.702368 -99.6442)
		(width 0.0889)
		(layer "In2.Cu")
		(net "M_M_ODT<0>")
	)
	(arc
		(start 98.595688 -96.900238)
		(mid 98.67491 -97.189356)
		(end 98.602038 -97.48012)
		(width 0.0889)
		(layer "In2.Cu")
		(net "M_M_ODT<0>")
	)
	(arc
		(start 98.590862 -94.527624)
		(mid 98.542107 -94.723976)
		(end 98.595688 -94.919038)
		(width 0.0889)
		(layer "In2.Cu")
		(net "M_M_ODT<0>")
	)
	(arc
		(start 98.590862 -95.518224)
		(mid 98.542107 -95.714576)
		(end 98.595688 -95.909638)
		(width 0.0889)
		(layer "In2.Cu")
		(net "M_M_ODT<0>")
	)
	(segment
		(start 91.787218 -89.27084)
		(end 91.215718 -89.27084)
		(width 0.1016)
		(layer "F.Cu")
		(net "M_M_MA<9>")
	)
	(segment
		(start 84.949538 -152.273)
		(end 84.949538 -154.252168)
		(width 0.1651)
		(layer "F.Cu")
		(net "M_M_MA<9>")
	)
	(via
		(at 84.949538 -150.788878)
		(size 0.4572)
		(drill 0.2032)
		(layers "F.Cu" "B.Cu")
		(net "M_M_MA<9>")
	)
	(via
		(at 84.949538 -154.252168)
		(size 0.508)
		(drill 0.254)
		(layers "F.Cu" "B.Cu")
		(net "M_M_MA<9>")
	)
	(via
		(at 91.215718 -89.27084)
		(size 0.508)
		(drill 0.254)
		(layers "F.Cu" "B.Cu")
		(net "M_M_MA<9>")
	)
	(segment
		(start 84.949538 -152.078436)
		(end 84.949538 -150.788878)
		(width 0.1651)
		(layer "B.Cu")
		(net "M_M_MA<9>")
	)
	(segment
		(start 85.415882 -150.322534)
		(end 84.949538 -150.788878)
		(width 0.14224)
		(layer "In11.Cu")
		(net "M_M_MA<9>")
	)
	(segment
		(start 86.454234 -150.322534)
		(end 85.415882 -150.322534)
		(width 0.14224)
		(layer "In11.Cu")
		(net "M_M_MA<9>")
	)
	(segment
		(start 91.733878 -95.49892)
		(end 91.727528 -95.509588)
		(width 0.0889)
		(layer "In11.Cu")
		(net "M_M_MA<9>")
	)
	(segment
		(start 91.733878 -97.48012)
		(end 91.727528 -97.490788)
		(width 0.0889)
		(layer "In11.Cu")
		(net "M_M_MA<9>")
	)
	(segment
		(start 94.485968 -140.1826)
		(end 94.485968 -141.351)
		(width 0.14224)
		(layer "In11.Cu")
		(net "M_M_MA<9>")
	)
	(segment
		(start 93.155516 -102.403148)
		(end 93.155516 -128.675892)
		(width 0.14224)
		(layer "In11.Cu")
		(net "M_M_MA<9>")
	)
	(segment
		(start 89.230708 -146.501104)
		(end 87.921846 -147.809966)
		(width 0.14224)
		(layer "In11.Cu")
		(net "M_M_MA<9>")
	)
	(segment
		(start 91.197684 -93.633036)
		(end 91.233498 -93.633036)
		(width 0.0889)
		(layer "In11.Cu")
		(net "M_M_MA<9>")
	)
	(segment
		(start 93.927168 -146.117818)
		(end 93.543882 -146.501104)
		(width 0.14224)
		(layer "In11.Cu")
		(net "M_M_MA<9>")
	)
	(segment
		(start 93.690694 -133.900672)
		(end 93.927168 -134.137146)
		(width 0.14224)
		(layer "In11.Cu")
		(net "M_M_MA<9>")
	)
	(segment
		(start 93.155516 -128.675892)
		(end 93.690694 -129.21107)
		(width 0.14224)
		(layer "In11.Cu")
		(net "M_M_MA<9>")
	)
	(segment
		(start 87.526368 -149.5044)
		(end 87.272368 -149.5044)
		(width 0.14224)
		(layer "In11.Cu")
		(net "M_M_MA<9>")
	)
	(segment
		(start 91.727528 -94.518988)
		(end 91.722702 -94.527624)
		(width 0.0889)
		(layer "In11.Cu")
		(net "M_M_MA<9>")
	)
	(segment
		(start 91.62923 -99.0346)
		(end 91.62923 -100.876862)
		(width 0.0889)
		(layer "In11.Cu")
		(net "M_M_MA<9>")
	)
	(segment
		(start 91.627452 -98.660204)
		(end 91.627452 -99.032822)
		(width 0.0889)
		(layer "In11.Cu")
		(net "M_M_MA<9>")
	)
	(segment
		(start 87.921846 -147.809966)
		(end 87.921846 -149.108922)
		(width 0.14224)
		(layer "In11.Cu")
		(net "M_M_MA<9>")
	)
	(segment
		(start 90.815922 -89.66835)
		(end 90.815922 -93.235018)
		(width 0.0889)
		(layer "In11.Cu")
		(net "M_M_MA<9>")
	)
	(segment
		(start 91.213432 -89.27084)
		(end 90.815922 -89.66835)
		(width 0.0889)
		(layer "In11.Cu")
		(net "M_M_MA<9>")
	)
	(segment
		(start 91.215718 -89.27084)
		(end 91.213432 -89.27084)
		(width 0.0889)
		(layer "In11.Cu")
		(net "M_M_MA<9>")
	)
	(segment
		(start 91.727528 -95.509588)
		(end 91.722702 -95.518224)
		(width 0.0889)
		(layer "In11.Cu")
		(net "M_M_MA<9>")
	)
	(segment
		(start 92.022168 -101.2698)
		(end 93.155516 -102.403148)
		(width 0.14224)
		(layer "In11.Cu")
		(net "M_M_MA<9>")
	)
	(segment
		(start 91.62923 -100.876862)
		(end 92.022168 -101.2698)
		(width 0.0889)
		(layer "In11.Cu")
		(net "M_M_MA<9>")
	)
	(segment
		(start 87.921846 -149.108922)
		(end 87.526368 -149.5044)
		(width 0.14224)
		(layer "In11.Cu")
		(net "M_M_MA<9>")
	)
	(segment
		(start 87.272368 -149.5044)
		(end 86.454234 -150.322534)
		(width 0.14224)
		(layer "In11.Cu")
		(net "M_M_MA<9>")
	)
	(segment
		(start 91.733878 -96.48952)
		(end 91.727528 -96.500188)
		(width 0.0889)
		(layer "In11.Cu")
		(net "M_M_MA<9>")
	)
	(segment
		(start 84.949538 -150.788878)
		(end 84.949538 -154.252168)
		(width 0.14224)
		(layer "In11.Cu")
		(net "M_M_MA<9>")
	)
	(segment
		(start 91.627452 -99.032822)
		(end 91.62923 -99.0346)
		(width 0.0889)
		(layer "In11.Cu")
		(net "M_M_MA<9>")
	)
	(segment
		(start 93.543882 -146.501104)
		(end 89.230708 -146.501104)
		(width 0.14224)
		(layer "In11.Cu")
		(net "M_M_MA<9>")
	)
	(segment
		(start 93.927168 -141.9098)
		(end 93.927168 -146.117818)
		(width 0.14224)
		(layer "In11.Cu")
		(net "M_M_MA<9>")
	)
	(segment
		(start 90.864182 -93.424502)
		(end 90.869008 -93.433138)
		(width 0.0889)
		(layer "In11.Cu")
		(net "M_M_MA<9>")
	)
	(segment
		(start 91.727528 -96.500188)
		(end 91.722702 -96.508824)
		(width 0.0889)
		(layer "In11.Cu")
		(net "M_M_MA<9>")
	)
	(segment
		(start 93.690694 -129.21107)
		(end 93.690694 -133.900672)
		(width 0.14224)
		(layer "In11.Cu")
		(net "M_M_MA<9>")
	)
	(segment
		(start 91.727528 -97.490788)
		(end 91.722702 -97.499424)
		(width 0.0889)
		(layer "In11.Cu")
		(net "M_M_MA<9>")
	)
	(segment
		(start 91.734132 -98.469704)
		(end 91.627452 -98.660204)
		(width 0.0889)
		(layer "In11.Cu")
		(net "M_M_MA<9>")
	)
	(segment
		(start 93.927168 -134.137146)
		(end 93.927168 -139.6238)
		(width 0.14224)
		(layer "In11.Cu")
		(net "M_M_MA<9>")
	)
	(segment
		(start 93.927168 -139.6238)
		(end 94.485968 -140.1826)
		(width 0.14224)
		(layer "In11.Cu")
		(net "M_M_MA<9>")
	)
	(segment
		(start 94.485968 -141.351)
		(end 93.927168 -141.9098)
		(width 0.14224)
		(layer "In11.Cu")
		(net "M_M_MA<9>")
	)
	(arc
		(start 91.722702 -95.518224)
		(mid 91.673947 -95.714576)
		(end 91.727528 -95.909638)
		(width 0.0889)
		(layer "In11.Cu")
		(net "M_M_MA<9>")
	)
	(arc
		(start 91.722702 -96.508824)
		(mid 91.673947 -96.705176)
		(end 91.727528 -96.900238)
		(width 0.0889)
		(layer "In11.Cu")
		(net "M_M_MA<9>")
	)
	(arc
		(start 90.815922 -93.235018)
		(mid 90.828166 -93.33279)
		(end 90.864182 -93.424502)
		(width 0.0889)
		(layer "In11.Cu")
		(net "M_M_MA<9>")
	)
	(arc
		(start 91.727528 -96.900238)
		(mid 91.80675 -97.189356)
		(end 91.733878 -97.48012)
		(width 0.0889)
		(layer "In11.Cu")
		(net "M_M_MA<9>")
	)
	(arc
		(start 91.727528 -94.919038)
		(mid 91.80675 -95.208156)
		(end 91.733878 -95.49892)
		(width 0.0889)
		(layer "In11.Cu")
		(net "M_M_MA<9>")
	)
	(arc
		(start 91.233498 -93.633036)
		(mid 91.731749 -93.935876)
		(end 91.727528 -94.518988)
		(width 0.0889)
		(layer "In11.Cu")
		(net "M_M_MA<9>")
	)
	(arc
		(start 91.722702 -97.499424)
		(mid 91.673947 -97.695776)
		(end 91.727528 -97.890838)
		(width 0.0889)
		(layer "In11.Cu")
		(net "M_M_MA<9>")
	)
	(arc
		(start 90.869008 -93.433138)
		(mid 91.007752 -93.575171)
		(end 91.197684 -93.633036)
		(width 0.0889)
		(layer "In11.Cu")
		(net "M_M_MA<9>")
	)
	(arc
		(start 91.727528 -97.890838)
		(mid 91.80662 -98.179418)
		(end 91.734132 -98.469704)
		(width 0.0889)
		(layer "In11.Cu")
		(net "M_M_MA<9>")
	)
	(arc
		(start 91.727528 -95.909638)
		(mid 91.80675 -96.198756)
		(end 91.733878 -96.48952)
		(width 0.0889)
		(layer "In11.Cu")
		(net "M_M_MA<9>")
	)
	(arc
		(start 91.722702 -94.527624)
		(mid 91.673947 -94.723976)
		(end 91.727528 -94.919038)
		(width 0.0889)
		(layer "In11.Cu")
		(net "M_M_MA<9>")
	)
	(segment
		(start 86.64956 -152.273)
		(end 86.64956 -154.252168)
		(width 0.1651)
		(layer "F.Cu")
		(net "M_M_MA<8>")
	)
	(segment
		(start 90.928698 -90.756486)
		(end 90.357198 -90.756486)
		(width 0.1016)
		(layer "F.Cu")
		(net "M_M_MA<8>")
	)
	(via
		(at 86.64956 -154.252168)
		(size 0.508)
		(drill 0.254)
		(layers "F.Cu" "B.Cu")
		(net "M_M_MA<8>")
	)
	(via
		(at 86.64956 -150.788878)
		(size 0.4572)
		(drill 0.2032)
		(layers "F.Cu" "B.Cu")
		(net "M_M_MA<8>")
	)
	(via
		(at 90.357198 -90.756486)
		(size 0.508)
		(drill 0.254)
		(layers "F.Cu" "B.Cu")
		(net "M_M_MA<8>")
	)
	(segment
		(start 86.64956 -152.078436)
		(end 86.64956 -150.788878)
		(width 0.1651)
		(layer "B.Cu")
		(net "M_M_MA<8>")
	)
	(segment
		(start 90.016838 -95.49892)
		(end 90.010488 -95.509588)
		(width 0.0889)
		(layer "In2.Cu")
		(net "M_M_MA<8>")
	)
	(segment
		(start 90.016838 -96.48952)
		(end 90.010488 -96.500188)
		(width 0.0889)
		(layer "In2.Cu")
		(net "M_M_MA<8>")
	)
	(segment
		(start 86.865968 -154.955748)
		(end 86.865968 -154.468576)
		(width 0.14224)
		(layer "In2.Cu")
		(net "M_M_MA<8>")
	)
	(segment
		(start 87.063072 -136.061704)
		(end 87.089234 -136.087866)
		(width 0.14224)
		(layer "In2.Cu")
		(net "M_M_MA<8>")
	)
	(segment
		(start 86.992968 -130.6576)
		(end 86.992968 -131.191)
		(width 0.14224)
		(layer "In2.Cu")
		(net "M_M_MA<8>")
	)
	(segment
		(start 90.016838 -97.48012)
		(end 90.010488 -97.490788)
		(width 0.0889)
		(layer "In2.Cu")
		(net "M_M_MA<8>")
	)
	(segment
		(start 86.408768 -155.082748)
		(end 86.738968 -155.082748)
		(width 0.14224)
		(layer "In2.Cu")
		(net "M_M_MA<8>")
	)
	(segment
		(start 90.010488 -94.518988)
		(end 90.005662 -94.527624)
		(width 0.0889)
		(layer "In2.Cu")
		(net "M_M_MA<8>")
	)
	(segment
		(start 86.44382 -150.788878)
		(end 85.850222 -151.382476)
		(width 0.14224)
		(layer "In2.Cu")
		(net "M_M_MA<8>")
	)
	(segment
		(start 89.945972 -98.728276)
		(end 89.945972 -99.90582)
		(width 0.0889)
		(layer "In2.Cu")
		(net "M_M_MA<8>")
	)
	(segment
		(start 86.992968 -131.191)
		(end 87.119968 -131.318)
		(width 0.14224)
		(layer "In2.Cu")
		(net "M_M_MA<8>")
	)
	(segment
		(start 90.371168 -105.0544)
		(end 90.371168 -125.042168)
		(width 0.14224)
		(layer "In2.Cu")
		(net "M_M_MA<8>")
	)
	(segment
		(start 87.145368 -130.5052)
		(end 86.992968 -130.6576)
		(width 0.14224)
		(layer "In2.Cu")
		(net "M_M_MA<8>")
	)
	(segment
		(start 89.945972 -99.90582)
		(end 90.142568 -100.102416)
		(width 0.0889)
		(layer "In2.Cu")
		(net "M_M_MA<8>")
	)
	(segment
		(start 90.142568 -102.546912)
		(end 90.371168 -102.775512)
		(width 0.0889)
		(layer "In2.Cu")
		(net "M_M_MA<8>")
	)
	(segment
		(start 87.119968 -131.318)
		(end 87.119968 -132.5372)
		(width 0.14224)
		(layer "In2.Cu")
		(net "M_M_MA<8>")
	)
	(segment
		(start 90.010488 -93.928438)
		(end 90.016838 -93.939106)
		(width 0.0889)
		(layer "In2.Cu")
		(net "M_M_MA<8>")
	)
	(segment
		(start 90.02776 -91.51747)
		(end 90.005662 -91.555824)
		(width 0.0889)
		(layer "In2.Cu")
		(net "M_M_MA<8>")
	)
	(segment
		(start 90.371168 -102.775512)
		(end 90.371168 -105.0544)
		(width 0.0889)
		(layer "In2.Cu")
		(net "M_M_MA<8>")
	)
	(segment
		(start 90.010488 -92.537788)
		(end 90.005662 -92.546424)
		(width 0.0889)
		(layer "In2.Cu")
		(net "M_M_MA<8>")
	)
	(segment
		(start 86.256622 -153.353262)
		(end 86.256622 -153.73223)
		(width 0.14224)
		(layer "In2.Cu")
		(net "M_M_MA<8>")
	)
	(segment
		(start 86.281768 -154.74696)
		(end 86.281768 -154.955748)
		(width 0.14224)
		(layer "In2.Cu")
		(net "M_M_MA<8>")
	)
	(segment
		(start 87.119968 -132.5372)
		(end 87.063072 -132.594096)
		(width 0.14224)
		(layer "In2.Cu")
		(net "M_M_MA<8>")
	)
	(segment
		(start 87.145368 -129.9718)
		(end 87.145368 -130.5052)
		(width 0.14224)
		(layer "In2.Cu")
		(net "M_M_MA<8>")
	)
	(segment
		(start 90.010488 -95.509588)
		(end 90.005662 -95.518224)
		(width 0.0889)
		(layer "In2.Cu")
		(net "M_M_MA<8>")
	)
	(segment
		(start 85.850222 -152.946862)
		(end 86.256622 -153.353262)
		(width 0.14224)
		(layer "In2.Cu")
		(net "M_M_MA<8>")
	)
	(segment
		(start 86.865968 -154.468576)
		(end 86.64956 -154.252168)
		(width 0.14224)
		(layer "In2.Cu")
		(net "M_M_MA<8>")
	)
	(segment
		(start 86.738968 -155.082748)
		(end 86.865968 -154.955748)
		(width 0.14224)
		(layer "In2.Cu")
		(net "M_M_MA<8>")
	)
	(segment
		(start 86.64956 -150.176992)
		(end 86.64956 -150.788878)
		(width 0.14224)
		(layer "In2.Cu")
		(net "M_M_MA<8>")
	)
	(segment
		(start 90.142568 -100.102416)
		(end 90.142568 -102.546912)
		(width 0.0889)
		(layer "In2.Cu")
		(net "M_M_MA<8>")
	)
	(segment
		(start 87.089234 -146.563334)
		(end 86.212426 -147.440142)
		(width 0.14224)
		(layer "In2.Cu")
		(net "M_M_MA<8>")
	)
	(segment
		(start 90.010488 -97.490788)
		(end 90.005662 -97.499424)
		(width 0.0889)
		(layer "In2.Cu")
		(net "M_M_MA<8>")
	)
	(segment
		(start 86.64956 -150.788878)
		(end 86.44382 -150.788878)
		(width 0.14224)
		(layer "In2.Cu")
		(net "M_M_MA<8>")
	)
	(segment
		(start 86.212426 -149.739858)
		(end 86.64956 -150.176992)
		(width 0.14224)
		(layer "In2.Cu")
		(net "M_M_MA<8>")
	)
	(segment
		(start 85.850222 -151.382476)
		(end 85.850222 -152.946862)
		(width 0.14224)
		(layer "In2.Cu")
		(net "M_M_MA<8>")
	)
	(segment
		(start 87.063072 -132.594096)
		(end 87.063072 -136.061704)
		(width 0.14224)
		(layer "In2.Cu")
		(net "M_M_MA<8>")
	)
	(segment
		(start 90.016838 -92.52712)
		(end 90.010488 -92.537788)
		(width 0.0889)
		(layer "In2.Cu")
		(net "M_M_MA<8>")
	)
	(segment
		(start 86.942168 -129.7686)
		(end 87.145368 -129.9718)
		(width 0.14224)
		(layer "In2.Cu")
		(net "M_M_MA<8>")
	)
	(segment
		(start 86.281768 -154.955748)
		(end 86.408768 -155.082748)
		(width 0.14224)
		(layer "In2.Cu")
		(net "M_M_MA<8>")
	)
	(segment
		(start 90.010488 -96.500188)
		(end 90.005662 -96.508824)
		(width 0.0889)
		(layer "In2.Cu")
		(net "M_M_MA<8>")
	)
	(segment
		(start 86.212426 -147.440142)
		(end 86.212426 -149.739858)
		(width 0.14224)
		(layer "In2.Cu")
		(net "M_M_MA<8>")
	)
	(segment
		(start 90.371168 -125.042168)
		(end 86.942168 -128.471168)
		(width 0.14224)
		(layer "In2.Cu")
		(net "M_M_MA<8>")
	)
	(segment
		(start 86.942168 -128.471168)
		(end 86.942168 -129.7686)
		(width 0.14224)
		(layer "In2.Cu")
		(net "M_M_MA<8>")
	)
	(segment
		(start 90.357198 -90.756486)
		(end 90.02776 -91.51747)
		(width 0.0889)
		(layer "In2.Cu")
		(net "M_M_MA<8>")
	)
	(segment
		(start 85.959442 -154.424634)
		(end 86.281768 -154.74696)
		(width 0.14224)
		(layer "In2.Cu")
		(net "M_M_MA<8>")
	)
	(segment
		(start 87.089234 -136.087866)
		(end 87.089234 -146.563334)
		(width 0.14224)
		(layer "In2.Cu")
		(net "M_M_MA<8>")
	)
	(segment
		(start 86.256622 -153.73223)
		(end 85.959442 -154.02941)
		(width 0.14224)
		(layer "In2.Cu")
		(net "M_M_MA<8>")
	)
	(segment
		(start 85.959442 -154.02941)
		(end 85.959442 -154.424634)
		(width 0.14224)
		(layer "In2.Cu")
		(net "M_M_MA<8>")
	)
	(arc
		(start 90.005662 -95.518224)
		(mid 89.956907 -95.714576)
		(end 90.010488 -95.909638)
		(width 0.0889)
		(layer "In2.Cu")
		(net "M_M_MA<8>")
	)
	(arc
		(start 90.005662 -97.499424)
		(mid 89.956907 -97.695776)
		(end 90.010488 -97.890838)
		(width 0.0889)
		(layer "In2.Cu")
		(net "M_M_MA<8>")
	)
	(arc
		(start 90.005662 -96.508824)
		(mid 89.956907 -96.705176)
		(end 90.010488 -96.900238)
		(width 0.0889)
		(layer "In2.Cu")
		(net "M_M_MA<8>")
	)
	(arc
		(start 90.010488 -94.919038)
		(mid 90.08971 -95.208156)
		(end 90.016838 -95.49892)
		(width 0.0889)
		(layer "In2.Cu")
		(net "M_M_MA<8>")
	)
	(arc
		(start 90.005662 -94.527624)
		(mid 89.956907 -94.723976)
		(end 90.010488 -94.919038)
		(width 0.0889)
		(layer "In2.Cu")
		(net "M_M_MA<8>")
	)
	(arc
		(start 90.005662 -92.546424)
		(mid 89.956907 -92.742776)
		(end 90.010488 -92.937838)
		(width 0.0889)
		(layer "In2.Cu")
		(net "M_M_MA<8>")
	)
	(arc
		(start 90.016838 -93.939106)
		(mid 90.089636 -94.229869)
		(end 90.010488 -94.518988)
		(width 0.0889)
		(layer "In2.Cu")
		(net "M_M_MA<8>")
	)
	(arc
		(start 90.010488 -91.947238)
		(mid 90.08971 -92.236356)
		(end 90.016838 -92.52712)
		(width 0.0889)
		(layer "In2.Cu")
		(net "M_M_MA<8>")
	)
	(arc
		(start 90.016838 -98.47072)
		(mid 89.964008 -98.594712)
		(end 89.945972 -98.728276)
		(width 0.0889)
		(layer "In2.Cu")
		(net "M_M_MA<8>")
	)
	(arc
		(start 90.010488 -92.937838)
		(mid 90.089619 -93.23324)
		(end 90.010488 -93.528642)
		(width 0.0889)
		(layer "In2.Cu")
		(net "M_M_MA<8>")
	)
	(arc
		(start 90.010488 -93.528642)
		(mid 89.956989 -93.72854)
		(end 90.010488 -93.928438)
		(width 0.0889)
		(layer "In2.Cu")
		(net "M_M_MA<8>")
	)
	(arc
		(start 90.005662 -91.555824)
		(mid 89.956907 -91.752176)
		(end 90.010488 -91.947238)
		(width 0.0889)
		(layer "In2.Cu")
		(net "M_M_MA<8>")
	)
	(arc
		(start 90.010488 -95.909638)
		(mid 90.08971 -96.198756)
		(end 90.016838 -96.48952)
		(width 0.0889)
		(layer "In2.Cu")
		(net "M_M_MA<8>")
	)
	(arc
		(start 90.010488 -96.900238)
		(mid 90.08971 -97.189356)
		(end 90.016838 -97.48012)
		(width 0.0889)
		(layer "In2.Cu")
		(net "M_M_MA<8>")
	)
	(arc
		(start 90.010488 -97.890838)
		(mid 90.08971 -98.179956)
		(end 90.016838 -98.47072)
		(width 0.0889)
		(layer "In2.Cu")
		(net "M_M_MA<8>")
	)
	(segment
		(start 85.799422 -156.87294)
		(end 85.799422 -154.905456)
		(width 0.1651)
		(layer "F.Cu")
		(net "M_M_MA<7>")
	)
	(segment
		(start 90.070178 -90.26144)
		(end 89.498678 -90.26144)
		(width 0.1016)
		(layer "F.Cu")
		(net "M_M_MA<7>")
	)
	(via
		(at 89.498678 -90.26144)
		(size 0.508)
		(drill 0.254)
		(layers "F.Cu" "B.Cu")
		(net "M_M_MA<7>")
	)
	(via
		(at 85.799422 -148.771356)
		(size 0.4572)
		(drill 0.2032)
		(layers "F.Cu" "B.Cu")
		(net "M_M_MA<7>")
	)
	(via
		(at 85.799422 -154.905456)
		(size 0.508)
		(drill 0.254)
		(layers "F.Cu" "B.Cu")
		(net "M_M_MA<7>")
	)
	(segment
		(start 85.799422 -148.771356)
		(end 85.799422 -147.478496)
		(width 0.1651)
		(layer "B.Cu")
		(net "M_M_MA<7>")
	)
	(segment
		(start 89.685368 -99.962716)
		(end 89.863168 -100.140516)
		(width 0.0889)
		(layer "In2.Cu")
		(net "M_M_MA<7>")
	)
	(segment
		(start 85.342222 -153.822146)
		(end 85.406738 -153.886662)
		(width 0.14224)
		(layer "In2.Cu")
		(net "M_M_MA<7>")
	)
	(segment
		(start 88.541098 -125.232922)
		(end 88.541098 -125.46965)
		(width 0.14224)
		(layer "In2.Cu")
		(net "M_M_MA<7>")
	)
	(segment
		(start 86.154768 -130.4798)
		(end 86.307168 -130.6322)
		(width 0.14224)
		(layer "In2.Cu")
		(net "M_M_MA<7>")
	)
	(segment
		(start 86.002368 -132.2832)
		(end 86.234524 -132.515356)
		(width 0.14224)
		(layer "In2.Cu")
		(net "M_M_MA<7>")
	)
	(segment
		(start 89.863168 -124.873512)
		(end 89.620598 -125.116082)
		(width 0.14224)
		(layer "In2.Cu")
		(net "M_M_MA<7>")
	)
	(segment
		(start 85.406738 -153.886662)
		(end 85.406738 -154.512772)
		(width 0.14224)
		(layer "In2.Cu")
		(net "M_M_MA<7>")
	)
	(segment
		(start 89.850214 -97.386902)
		(end 89.845388 -97.395538)
		(width 0.0889)
		(layer "In2.Cu")
		(net "M_M_MA<7>")
	)
	(segment
		(start 86.154768 -129.9718)
		(end 86.154768 -130.4798)
		(width 0.14224)
		(layer "In2.Cu")
		(net "M_M_MA<7>")
	)
	(segment
		(start 85.342222 -151.048466)
		(end 85.342222 -153.822146)
		(width 0.14224)
		(layer "In2.Cu")
		(net "M_M_MA<7>")
	)
	(segment
		(start 87.681308 -126.046992)
		(end 87.475568 -126.252732)
		(width 0.14224)
		(layer "In2.Cu")
		(net "M_M_MA<7>")
	)
	(segment
		(start 86.307168 -131.191)
		(end 86.002368 -131.4958)
		(width 0.14224)
		(layer "In2.Cu")
		(net "M_M_MA<7>")
	)
	(segment
		(start 85.361272 -150.493984)
		(end 85.361272 -151.029416)
		(width 0.14224)
		(layer "In2.Cu")
		(net "M_M_MA<7>")
	)
	(segment
		(start 89.498678 -90.26144)
		(end 89.828624 -91.023186)
		(width 0.0889)
		(layer "In2.Cu")
		(net "M_M_MA<7>")
	)
	(segment
		(start 86.240112 -139.99464)
		(end 86.240112 -144.288256)
		(width 0.14224)
		(layer "In2.Cu")
		(net "M_M_MA<7>")
	)
	(segment
		(start 85.595968 -150.259288)
		(end 85.361272 -150.493984)
		(width 0.14224)
		(layer "In2.Cu")
		(net "M_M_MA<7>")
	)
	(segment
		(start 86.208616 -146.377152)
		(end 85.799422 -146.786346)
		(width 0.14224)
		(layer "In2.Cu")
		(net "M_M_MA<7>")
	)
	(segment
		(start 85.361272 -151.029416)
		(end 85.342222 -151.048466)
		(width 0.14224)
		(layer "In2.Cu")
		(net "M_M_MA<7>")
	)
	(segment
		(start 86.210394 -139.964922)
		(end 86.240112 -139.99464)
		(width 0.14224)
		(layer "In2.Cu")
		(net "M_M_MA<7>")
	)
	(segment
		(start 87.475568 -126.740412)
		(end 87.019384 -127.196596)
		(width 0.14224)
		(layer "In2.Cu")
		(net "M_M_MA<7>")
	)
	(segment
		(start 85.406738 -154.512772)
		(end 85.799422 -154.905456)
		(width 0.14224)
		(layer "In2.Cu")
		(net "M_M_MA<7>")
	)
	(segment
		(start 86.240112 -144.288256)
		(end 86.208616 -144.319752)
		(width 0.14224)
		(layer "In2.Cu")
		(net "M_M_MA<7>")
	)
	(segment
		(start 88.541098 -125.46965)
		(end 88.71331 -125.641862)
		(width 0.14224)
		(layer "In2.Cu")
		(net "M_M_MA<7>")
	)
	(segment
		(start 89.839038 -94.01302)
		(end 89.845388 -94.023688)
		(width 0.0889)
		(layer "In2.Cu")
		(net "M_M_MA<7>")
	)
	(segment
		(start 89.850214 -95.405702)
		(end 89.845388 -95.414338)
		(width 0.0889)
		(layer "In2.Cu")
		(net "M_M_MA<7>")
	)
	(segment
		(start 89.121234 -124.900182)
		(end 88.873838 -124.900182)
		(width 0.14224)
		(layer "In2.Cu")
		(net "M_M_MA<7>")
	)
	(segment
		(start 88.873838 -124.900182)
		(end 88.541098 -125.232922)
		(width 0.14224)
		(layer "In2.Cu")
		(net "M_M_MA<7>")
	)
	(segment
		(start 89.845388 -96.404938)
		(end 89.839038 -96.415606)
		(width 0.0889)
		(layer "In2.Cu")
		(net "M_M_MA<7>")
	)
	(segment
		(start 86.66988 -127.196596)
		(end 86.281768 -127.584708)
		(width 0.14224)
		(layer "In2.Cu")
		(net "M_M_MA<7>")
	)
	(segment
		(start 86.234524 -136.064244)
		(end 86.210394 -136.088374)
		(width 0.14224)
		(layer "In2.Cu")
		(net "M_M_MA<7>")
	)
	(segment
		(start 86.281768 -127.584708)
		(end 86.281768 -129.8448)
		(width 0.14224)
		(layer "In2.Cu")
		(net "M_M_MA<7>")
	)
	(segment
		(start 86.002368 -131.4958)
		(end 86.002368 -132.2832)
		(width 0.14224)
		(layer "In2.Cu")
		(net "M_M_MA<7>")
	)
	(segment
		(start 89.845388 -97.395538)
		(end 89.839038 -97.406206)
		(width 0.0889)
		(layer "In2.Cu")
		(net "M_M_MA<7>")
	)
	(segment
		(start 88.134952 -126.213108)
		(end 87.968836 -126.046992)
		(width 0.14224)
		(layer "In2.Cu")
		(net "M_M_MA<7>")
	)
	(segment
		(start 86.307168 -130.6322)
		(end 86.307168 -131.191)
		(width 0.14224)
		(layer "In2.Cu")
		(net "M_M_MA<7>")
	)
	(segment
		(start 86.208616 -144.319752)
		(end 86.208616 -146.377152)
		(width 0.14224)
		(layer "In2.Cu")
		(net "M_M_MA<7>")
	)
	(segment
		(start 89.863168 -103.051356)
		(end 89.863168 -124.873512)
		(width 0.14224)
		(layer "In2.Cu")
		(net "M_M_MA<7>")
	)
	(segment
		(start 85.799422 -148.771356)
		(end 85.595968 -148.97481)
		(width 0.14224)
		(layer "In2.Cu")
		(net "M_M_MA<7>")
	)
	(segment
		(start 89.845388 -91.451938)
		(end 89.839038 -91.462606)
		(width 0.0889)
		(layer "In2.Cu")
		(net "M_M_MA<7>")
	)
	(segment
		(start 86.210394 -136.088374)
		(end 86.210394 -139.964922)
		(width 0.14224)
		(layer "In2.Cu")
		(net "M_M_MA<7>")
	)
	(segment
		(start 89.620598 -125.116082)
		(end 89.337134 -125.116082)
		(width 0.14224)
		(layer "In2.Cu")
		(net "M_M_MA<7>")
	)
	(segment
		(start 89.850214 -92.433902)
		(end 89.845388 -92.442538)
		(width 0.0889)
		(layer "In2.Cu")
		(net "M_M_MA<7>")
	)
	(segment
		(start 87.968836 -126.046992)
		(end 87.681308 -126.046992)
		(width 0.14224)
		(layer "In2.Cu")
		(net "M_M_MA<7>")
	)
	(segment
		(start 89.845388 -95.414338)
		(end 89.839038 -95.425006)
		(width 0.0889)
		(layer "In2.Cu")
		(net "M_M_MA<7>")
	)
	(segment
		(start 86.234524 -132.515356)
		(end 86.234524 -136.064244)
		(width 0.14224)
		(layer "In2.Cu")
		(net "M_M_MA<7>")
	)
	(segment
		(start 89.685368 -99.000564)
		(end 89.685368 -99.962716)
		(width 0.0889)
		(layer "In2.Cu")
		(net "M_M_MA<7>")
	)
	(segment
		(start 89.828624 -91.023186)
		(end 89.845388 -91.051888)
		(width 0.0889)
		(layer "In2.Cu")
		(net "M_M_MA<7>")
	)
	(segment
		(start 88.426036 -126.213108)
		(end 88.134952 -126.213108)
		(width 0.14224)
		(layer "In2.Cu")
		(net "M_M_MA<7>")
	)
	(segment
		(start 85.595968 -148.97481)
		(end 85.595968 -150.259288)
		(width 0.14224)
		(layer "In2.Cu")
		(net "M_M_MA<7>")
	)
	(segment
		(start 89.863168 -100.140516)
		(end 89.863168 -103.051356)
		(width 0.0889)
		(layer "In2.Cu")
		(net "M_M_MA<7>")
	)
	(segment
		(start 88.71331 -125.641862)
		(end 88.71331 -125.925834)
		(width 0.14224)
		(layer "In2.Cu")
		(net "M_M_MA<7>")
	)
	(segment
		(start 87.475568 -126.252732)
		(end 87.475568 -126.740412)
		(width 0.14224)
		(layer "In2.Cu")
		(net "M_M_MA<7>")
	)
	(segment
		(start 89.845388 -92.442538)
		(end 89.839038 -92.453206)
		(width 0.0889)
		(layer "In2.Cu")
		(net "M_M_MA<7>")
	)
	(segment
		(start 89.850214 -96.396302)
		(end 89.845388 -96.404938)
		(width 0.0889)
		(layer "In2.Cu")
		(net "M_M_MA<7>")
	)
	(segment
		(start 88.71331 -125.925834)
		(end 88.426036 -126.213108)
		(width 0.14224)
		(layer "In2.Cu")
		(net "M_M_MA<7>")
	)
	(segment
		(start 87.019384 -127.196596)
		(end 86.66988 -127.196596)
		(width 0.14224)
		(layer "In2.Cu")
		(net "M_M_MA<7>")
	)
	(segment
		(start 89.850214 -98.377502)
		(end 89.845388 -98.386138)
		(width 0.0889)
		(layer "In2.Cu")
		(net "M_M_MA<7>")
	)
	(segment
		(start 86.281768 -129.8448)
		(end 86.154768 -129.9718)
		(width 0.14224)
		(layer "In2.Cu")
		(net "M_M_MA<7>")
	)
	(segment
		(start 89.850214 -91.443302)
		(end 89.845388 -91.451938)
		(width 0.0889)
		(layer "In2.Cu")
		(net "M_M_MA<7>")
	)
	(segment
		(start 89.337134 -125.116082)
		(end 89.121234 -124.900182)
		(width 0.14224)
		(layer "In2.Cu")
		(net "M_M_MA<7>")
	)
	(segment
		(start 85.799422 -146.786346)
		(end 85.799422 -148.771356)
		(width 0.14224)
		(layer "In2.Cu")
		(net "M_M_MA<7>")
	)
	(segment
		(start 89.850214 -93.424502)
		(end 89.845388 -93.433138)
		(width 0.0889)
		(layer "In2.Cu")
		(net "M_M_MA<7>")
	)
	(arc
		(start 89.845388 -96.004888)
		(mid 89.898858 -96.199951)
		(end 89.850214 -96.396302)
		(width 0.0889)
		(layer "In2.Cu")
		(net "M_M_MA<7>")
	)
	(arc
		(start 89.845388 -97.986088)
		(mid 89.898858 -98.181151)
		(end 89.850214 -98.377502)
		(width 0.0889)
		(layer "In2.Cu")
		(net "M_M_MA<7>")
	)
	(arc
		(start 89.845388 -93.033088)
		(mid 89.898858 -93.228151)
		(end 89.850214 -93.424502)
		(width 0.0889)
		(layer "In2.Cu")
		(net "M_M_MA<7>")
	)
	(arc
		(start 89.845388 -96.995488)
		(mid 89.898858 -97.190551)
		(end 89.850214 -97.386902)
		(width 0.0889)
		(layer "In2.Cu")
		(net "M_M_MA<7>")
	)
	(arc
		(start 89.845388 -93.433138)
		(mid 89.766166 -93.722256)
		(end 89.839038 -94.01302)
		(width 0.0889)
		(layer "In2.Cu")
		(net "M_M_MA<7>")
	)
	(arc
		(start 89.839038 -96.415606)
		(mid 89.76624 -96.706369)
		(end 89.845388 -96.995488)
		(width 0.0889)
		(layer "In2.Cu")
		(net "M_M_MA<7>")
	)
	(arc
		(start 89.839038 -97.406206)
		(mid 89.76624 -97.696969)
		(end 89.845388 -97.986088)
		(width 0.0889)
		(layer "In2.Cu")
		(net "M_M_MA<7>")
	)
	(arc
		(start 89.845388 -94.423484)
		(mid 89.766257 -94.718886)
		(end 89.845388 -95.014288)
		(width 0.0889)
		(layer "In2.Cu")
		(net "M_M_MA<7>")
	)
	(arc
		(start 89.845388 -98.386138)
		(mid 89.726003 -98.683099)
		(end 89.685368 -99.000564)
		(width 0.0889)
		(layer "In2.Cu")
		(net "M_M_MA<7>")
	)
	(arc
		(start 89.839038 -95.425006)
		(mid 89.76624 -95.715769)
		(end 89.845388 -96.004888)
		(width 0.0889)
		(layer "In2.Cu")
		(net "M_M_MA<7>")
	)
	(arc
		(start 89.839038 -91.462606)
		(mid 89.76624 -91.753369)
		(end 89.845388 -92.042488)
		(width 0.0889)
		(layer "In2.Cu")
		(net "M_M_MA<7>")
	)
	(arc
		(start 89.845388 -95.014288)
		(mid 89.898858 -95.209351)
		(end 89.850214 -95.405702)
		(width 0.0889)
		(layer "In2.Cu")
		(net "M_M_MA<7>")
	)
	(arc
		(start 89.839038 -92.453206)
		(mid 89.76624 -92.743969)
		(end 89.845388 -93.033088)
		(width 0.0889)
		(layer "In2.Cu")
		(net "M_M_MA<7>")
	)
	(arc
		(start 89.845388 -92.042488)
		(mid 89.898858 -92.237551)
		(end 89.850214 -92.433902)
		(width 0.0889)
		(layer "In2.Cu")
		(net "M_M_MA<7>")
	)
	(arc
		(start 89.845388 -91.051888)
		(mid 89.898858 -91.246951)
		(end 89.850214 -91.443302)
		(width 0.0889)
		(layer "In2.Cu")
		(net "M_M_MA<7>")
	)
	(arc
		(start 89.845388 -94.023688)
		(mid 89.898887 -94.223586)
		(end 89.845388 -94.423484)
		(width 0.0889)
		(layer "In2.Cu")
		(net "M_M_MA<7>")
	)
	(segment
		(start 90.928698 -93.72854)
		(end 90.357198 -93.72854)
		(width 0.1016)
		(layer "F.Cu")
		(net "M_M_MA<6>")
	)
	(segment
		(start 87.499444 -152.273)
		(end 87.499444 -153.571956)
		(width 0.1651)
		(layer "F.Cu")
		(net "M_M_MA<6>")
	)
	(via
		(at 87.499444 -150.788878)
		(size 0.4572)
		(drill 0.2032)
		(layers "F.Cu" "B.Cu")
		(net "M_M_MA<6>")
	)
	(via
		(at 90.357198 -93.72854)
		(size 0.508)
		(drill 0.254)
		(layers "F.Cu" "B.Cu")
		(net "M_M_MA<6>")
	)
	(via
		(at 87.499444 -153.571956)
		(size 0.508)
		(drill 0.254)
		(layers "F.Cu" "B.Cu")
		(net "M_M_MA<6>")
	)
	(segment
		(start 87.499444 -152.078436)
		(end 87.499444 -150.788878)
		(width 0.1651)
		(layer "B.Cu")
		(net "M_M_MA<6>")
	)
	(segment
		(start 87.499444 -150.788878)
		(end 87.499444 -151.28621)
		(width 0.14224)
		(layer "In2.Cu")
		(net "M_M_MA<6>")
	)
	(segment
		(start 86.417912 -152.171146)
		(end 87.855044 -152.171146)
		(width 0.14224)
		(layer "In2.Cu")
		(net "M_M_MA<6>")
	)
	(segment
		(start 87.932514 -145.033746)
		(end 87.932514 -146.532854)
		(width 0.14224)
		(layer "In2.Cu")
		(net "M_M_MA<6>")
	)
	(segment
		(start 89.35593 -126.909322)
		(end 89.140538 -126.909322)
		(width 0.14224)
		(layer "In2.Cu")
		(net "M_M_MA<6>")
	)
	(segment
		(start 87.089234 -150.378668)
		(end 87.499444 -150.788878)
		(width 0.14224)
		(layer "In2.Cu")
		(net "M_M_MA<6>")
	)
	(segment
		(start 86.266274 -152.019508)
		(end 86.417912 -152.171146)
		(width 0.14224)
		(layer "In2.Cu")
		(net "M_M_MA<6>")
	)
	(segment
		(start 90.697558 -97.48012)
		(end 90.703908 -97.490788)
		(width 0.0889)
		(layer "In2.Cu")
		(net "M_M_MA<6>")
	)
	(segment
		(start 86.397846 -151.472138)
		(end 86.266274 -151.60371)
		(width 0.14224)
		(layer "In2.Cu")
		(net "M_M_MA<6>")
	)
	(segment
		(start 87.913718 -140.18895)
		(end 87.913718 -145.01495)
		(width 0.14224)
		(layer "In2.Cu")
		(net "M_M_MA<6>")
	)
	(segment
		(start 90.757502 -98.679254)
		(end 90.757502 -99.43973)
		(width 0.0889)
		(layer "In2.Cu")
		(net "M_M_MA<6>")
	)
	(segment
		(start 87.499444 -151.28621)
		(end 87.313516 -151.472138)
		(width 0.14224)
		(layer "In2.Cu")
		(net "M_M_MA<6>")
	)
	(segment
		(start 87.89924 -130.522472)
		(end 87.958168 -130.5814)
		(width 0.14224)
		(layer "In2.Cu")
		(net "M_M_MA<6>")
	)
	(segment
		(start 87.9856 -152.69337)
		(end 87.844884 -152.834086)
		(width 0.14224)
		(layer "In2.Cu")
		(net "M_M_MA<6>")
	)
	(segment
		(start 88.662256 -127.387604)
		(end 88.662256 -127.717804)
		(width 0.14224)
		(layer "In2.Cu")
		(net "M_M_MA<6>")
	)
	(segment
		(start 90.357198 -93.72854)
		(end 90.687398 -94.49054)
		(width 0.0889)
		(layer "In2.Cu")
		(net "M_M_MA<6>")
	)
	(segment
		(start 90.703908 -96.500188)
		(end 90.708734 -96.508824)
		(width 0.0889)
		(layer "In2.Cu")
		(net "M_M_MA<6>")
	)
	(segment
		(start 87.936578 -136.06399)
		(end 87.936578 -140.16609)
		(width 0.14224)
		(layer "In2.Cu")
		(net "M_M_MA<6>")
	)
	(segment
		(start 86.709758 -153.618438)
		(end 86.96452 -153.8732)
		(width 0.14224)
		(layer "In2.Cu")
		(net "M_M_MA<6>")
	)
	(segment
		(start 87.313516 -151.472138)
		(end 86.397846 -151.472138)
		(width 0.14224)
		(layer "In2.Cu")
		(net "M_M_MA<6>")
	)
	(segment
		(start 87.983568 -129.3876)
		(end 87.983568 -129.8956)
		(width 0.14224)
		(layer "In2.Cu")
		(net "M_M_MA<6>")
	)
	(segment
		(start 87.089234 -147.376134)
		(end 87.089234 -150.378668)
		(width 0.14224)
		(layer "In2.Cu")
		(net "M_M_MA<6>")
	)
	(segment
		(start 87.855044 -152.171146)
		(end 87.9856 -152.301702)
		(width 0.14224)
		(layer "In2.Cu")
		(net "M_M_MA<6>")
	)
	(segment
		(start 89.140538 -126.909322)
		(end 88.662256 -127.387604)
		(width 0.14224)
		(layer "In2.Cu")
		(net "M_M_MA<6>")
	)
	(segment
		(start 87.936578 -140.16609)
		(end 87.913718 -140.18895)
		(width 0.14224)
		(layer "In2.Cu")
		(net "M_M_MA<6>")
	)
	(segment
		(start 87.983568 -129.8956)
		(end 87.89924 -129.979928)
		(width 0.14224)
		(layer "In2.Cu")
		(net "M_M_MA<6>")
	)
	(segment
		(start 86.863936 -152.834086)
		(end 86.709758 -152.988264)
		(width 0.14224)
		(layer "In2.Cu")
		(net "M_M_MA<6>")
	)
	(segment
		(start 90.687398 -94.49054)
		(end 90.708734 -94.527624)
		(width 0.0889)
		(layer "In2.Cu")
		(net "M_M_MA<6>")
	)
	(segment
		(start 88.008968 -135.9916)
		(end 87.936578 -136.06399)
		(width 0.14224)
		(layer "In2.Cu")
		(net "M_M_MA<6>")
	)
	(segment
		(start 90.604848 -104.566466)
		(end 90.879168 -104.840786)
		(width 0.0889)
		(layer "In2.Cu")
		(net "M_M_MA<6>")
	)
	(segment
		(start 87.844884 -152.834086)
		(end 86.863936 -152.834086)
		(width 0.14224)
		(layer "In2.Cu")
		(net "M_M_MA<6>")
	)
	(segment
		(start 90.697558 -96.48952)
		(end 90.703908 -96.500188)
		(width 0.0889)
		(layer "In2.Cu")
		(net "M_M_MA<6>")
	)
	(segment
		(start 86.266274 -151.60371)
		(end 86.266274 -152.019508)
		(width 0.14224)
		(layer "In2.Cu")
		(net "M_M_MA<6>")
	)
	(segment
		(start 90.604848 -102.57028)
		(end 90.604848 -104.566466)
		(width 0.0889)
		(layer "In2.Cu")
		(net "M_M_MA<6>")
	)
	(segment
		(start 90.472768 -102.4382)
		(end 90.604848 -102.57028)
		(width 0.0889)
		(layer "In2.Cu")
		(net "M_M_MA<6>")
	)
	(segment
		(start 87.805768 -132.2832)
		(end 87.914226 -132.391658)
		(width 0.14224)
		(layer "In2.Cu")
		(net "M_M_MA<6>")
	)
	(segment
		(start 87.89924 -129.979928)
		(end 87.89924 -130.522472)
		(width 0.14224)
		(layer "In2.Cu")
		(net "M_M_MA<6>")
	)
	(segment
		(start 87.914226 -135.388858)
		(end 88.008968 -135.4836)
		(width 0.14224)
		(layer "In2.Cu")
		(net "M_M_MA<6>")
	)
	(segment
		(start 90.697558 -98.47072)
		(end 90.703908 -98.481388)
		(width 0.0889)
		(layer "In2.Cu")
		(net "M_M_MA<6>")
	)
	(segment
		(start 90.703908 -97.490788)
		(end 90.708734 -97.499424)
		(width 0.0889)
		(layer "In2.Cu")
		(net "M_M_MA<6>")
	)
	(segment
		(start 89.81186 -126.20752)
		(end 89.81186 -126.453392)
		(width 0.14224)
		(layer "In2.Cu")
		(net "M_M_MA<6>")
	)
	(segment
		(start 90.758772 -100.19284)
		(end 90.472768 -100.478844)
		(width 0.0889)
		(layer "In2.Cu")
		(net "M_M_MA<6>")
	)
	(segment
		(start 86.96452 -153.8732)
		(end 87.1982 -153.8732)
		(width 0.14224)
		(layer "In2.Cu")
		(net "M_M_MA<6>")
	)
	(segment
		(start 86.709758 -152.988264)
		(end 86.709758 -153.618438)
		(width 0.14224)
		(layer "In2.Cu")
		(net "M_M_MA<6>")
	)
	(segment
		(start 87.914226 -132.391658)
		(end 87.914226 -135.388858)
		(width 0.14224)
		(layer "In2.Cu")
		(net "M_M_MA<6>")
	)
	(segment
		(start 88.008968 -135.4836)
		(end 88.008968 -135.9916)
		(width 0.14224)
		(layer "In2.Cu")
		(net "M_M_MA<6>")
	)
	(segment
		(start 90.879168 -105.109264)
		(end 90.879168 -125.140212)
		(width 0.14224)
		(layer "In2.Cu")
		(net "M_M_MA<6>")
	)
	(segment
		(start 90.472768 -100.478844)
		(end 90.472768 -102.4382)
		(width 0.0889)
		(layer "In2.Cu")
		(net "M_M_MA<6>")
	)
	(segment
		(start 87.913718 -145.01495)
		(end 87.932514 -145.033746)
		(width 0.14224)
		(layer "In2.Cu")
		(net "M_M_MA<6>")
	)
	(segment
		(start 89.81186 -126.453392)
		(end 89.35593 -126.909322)
		(width 0.14224)
		(layer "In2.Cu")
		(net "M_M_MA<6>")
	)
	(segment
		(start 87.1982 -153.8732)
		(end 87.499444 -153.571956)
		(width 0.14224)
		(layer "In2.Cu")
		(net "M_M_MA<6>")
	)
	(segment
		(start 87.817706 -129.221738)
		(end 87.983568 -129.3876)
		(width 0.14224)
		(layer "In2.Cu")
		(net "M_M_MA<6>")
	)
	(segment
		(start 90.879168 -125.140212)
		(end 89.81186 -126.20752)
		(width 0.14224)
		(layer "In2.Cu")
		(net "M_M_MA<6>")
	)
	(segment
		(start 90.757502 -99.43973)
		(end 90.758772 -99.441)
		(width 0.0889)
		(layer "In2.Cu")
		(net "M_M_MA<6>")
	)
	(segment
		(start 87.9856 -152.301702)
		(end 87.9856 -152.69337)
		(width 0.14224)
		(layer "In2.Cu")
		(net "M_M_MA<6>")
	)
	(segment
		(start 87.958168 -130.5814)
		(end 87.958168 -131.2164)
		(width 0.14224)
		(layer "In2.Cu")
		(net "M_M_MA<6>")
	)
	(segment
		(start 87.817706 -128.562354)
		(end 87.817706 -129.221738)
		(width 0.14224)
		(layer "In2.Cu")
		(net "M_M_MA<6>")
	)
	(segment
		(start 87.805768 -131.3688)
		(end 87.805768 -132.2832)
		(width 0.14224)
		(layer "In2.Cu")
		(net "M_M_MA<6>")
	)
	(segment
		(start 88.662256 -127.717804)
		(end 87.817706 -128.562354)
		(width 0.14224)
		(layer "In2.Cu")
		(net "M_M_MA<6>")
	)
	(segment
		(start 90.879168 -104.840786)
		(end 90.879168 -105.109264)
		(width 0.0889)
		(layer "In2.Cu")
		(net "M_M_MA<6>")
	)
	(segment
		(start 90.697558 -95.49892)
		(end 90.703908 -95.509588)
		(width 0.0889)
		(layer "In2.Cu")
		(net "M_M_MA<6>")
	)
	(segment
		(start 87.958168 -131.2164)
		(end 87.805768 -131.3688)
		(width 0.14224)
		(layer "In2.Cu")
		(net "M_M_MA<6>")
	)
	(segment
		(start 87.932514 -146.532854)
		(end 87.089234 -147.376134)
		(width 0.14224)
		(layer "In2.Cu")
		(net "M_M_MA<6>")
	)
	(segment
		(start 90.703908 -95.509588)
		(end 90.708734 -95.518224)
		(width 0.0889)
		(layer "In2.Cu")
		(net "M_M_MA<6>")
	)
	(segment
		(start 90.758772 -99.441)
		(end 90.758772 -100.19284)
		(width 0.0889)
		(layer "In2.Cu")
		(net "M_M_MA<6>")
	)
	(arc
		(start 90.703908 -98.481388)
		(mid 90.743598 -98.576831)
		(end 90.757502 -98.679254)
		(width 0.0889)
		(layer "In2.Cu")
		(net "M_M_MA<6>")
	)
	(arc
		(start 90.703908 -95.909638)
		(mid 90.624686 -96.198756)
		(end 90.697558 -96.48952)
		(width 0.0889)
		(layer "In2.Cu")
		(net "M_M_MA<6>")
	)
	(arc
		(start 90.708734 -94.527624)
		(mid 90.757489 -94.723976)
		(end 90.703908 -94.919038)
		(width 0.0889)
		(layer "In2.Cu")
		(net "M_M_MA<6>")
	)
	(arc
		(start 90.703908 -94.919038)
		(mid 90.624686 -95.208156)
		(end 90.697558 -95.49892)
		(width 0.0889)
		(layer "In2.Cu")
		(net "M_M_MA<6>")
	)
	(arc
		(start 90.708734 -95.518224)
		(mid 90.757489 -95.714576)
		(end 90.703908 -95.909638)
		(width 0.0889)
		(layer "In2.Cu")
		(net "M_M_MA<6>")
	)
	(arc
		(start 90.703908 -96.900238)
		(mid 90.624686 -97.189356)
		(end 90.697558 -97.48012)
		(width 0.0889)
		(layer "In2.Cu")
		(net "M_M_MA<6>")
	)
	(arc
		(start 90.703908 -97.890838)
		(mid 90.624686 -98.179956)
		(end 90.697558 -98.47072)
		(width 0.0889)
		(layer "In2.Cu")
		(net "M_M_MA<6>")
	)
	(arc
		(start 90.708734 -96.508824)
		(mid 90.757489 -96.705176)
		(end 90.703908 -96.900238)
		(width 0.0889)
		(layer "In2.Cu")
		(net "M_M_MA<6>")
	)
	(arc
		(start 90.708734 -97.499424)
		(mid 90.757489 -97.695776)
		(end 90.703908 -97.890838)
		(width 0.0889)
		(layer "In2.Cu")
		(net "M_M_MA<6>")
	)
	(segment
		(start 87.499444 -156.87294)
		(end 87.499444 -154.905456)
		(width 0.1651)
		(layer "F.Cu")
		(net "M_M_MA<5>")
	)
	(segment
		(start 90.928698 -91.747086)
		(end 90.357198 -91.747086)
		(width 0.1016)
		(layer "F.Cu")
		(net "M_M_MA<5>")
	)
	(via
		(at 90.357198 -91.747086)
		(size 0.508)
		(drill 0.254)
		(layers "F.Cu" "B.Cu")
		(net "M_M_MA<5>")
	)
	(via
		(at 87.499444 -148.773388)
		(size 0.4572)
		(drill 0.2032)
		(layers "F.Cu" "B.Cu")
		(net "M_M_MA<5>")
	)
	(via
		(at 87.499444 -154.905456)
		(size 0.508)
		(drill 0.254)
		(layers "F.Cu" "B.Cu")
		(net "M_M_MA<5>")
	)
	(segment
		(start 87.499444 -148.773388)
		(end 87.499444 -147.478496)
		(width 0.1651)
		(layer "B.Cu")
		(net "M_M_MA<5>")
	)
	(segment
		(start 90.852244 -92.413074)
		(end 90.869008 -92.442538)
		(width 0.0889)
		(layer "In2.Cu")
		(net "M_M_MA<5>")
	)
	(segment
		(start 87.913718 -150.53945)
		(end 87.913718 -151.017986)
		(width 0.14224)
		(layer "In2.Cu")
		(net "M_M_MA<5>")
	)
	(segment
		(start 88.78697 -135.340598)
		(end 88.764872 -135.362696)
		(width 0.14224)
		(layer "In2.Cu")
		(net "M_M_MA<5>")
	)
	(segment
		(start 90.864182 -95.405702)
		(end 90.869008 -95.414338)
		(width 0.0889)
		(layer "In2.Cu")
		(net "M_M_MA<5>")
	)
	(segment
		(start 91.059254 -102.94747)
		(end 91.059254 -104.27589)
		(width 0.14224)
		(layer "In2.Cu")
		(net "M_M_MA<5>")
	)
	(segment
		(start 88.43137 -151.535638)
		(end 88.43137 -153.461974)
		(width 0.14224)
		(layer "In2.Cu")
		(net "M_M_MA<5>")
	)
	(segment
		(start 88.764872 -140.862304)
		(end 88.783668 -140.8811)
		(width 0.14224)
		(layer "In2.Cu")
		(net "M_M_MA<5>")
	)
	(segment
		(start 88.757506 -145.655538)
		(end 88.757506 -146.596862)
		(width 0.14224)
		(layer "In2.Cu")
		(net "M_M_MA<5>")
	)
	(segment
		(start 91.063572 -101.809804)
		(end 91.361768 -102.108)
		(width 0.0889)
		(layer "In2.Cu")
		(net "M_M_MA<5>")
	)
	(segment
		(start 87.499444 -148.773388)
		(end 87.499444 -149.325076)
		(width 0.14224)
		(layer "In2.Cu")
		(net "M_M_MA<5>")
	)
	(segment
		(start 91.387168 -104.603804)
		(end 91.387168 -125.711712)
		(width 0.14224)
		(layer "In2.Cu")
		(net "M_M_MA<5>")
	)
	(segment
		(start 91.361768 -102.450392)
		(end 91.059254 -102.752906)
		(width 0.0889)
		(layer "In2.Cu")
		(net "M_M_MA<5>")
	)
	(segment
		(start 88.720168 -131.1402)
		(end 88.974168 -131.3942)
		(width 0.14224)
		(layer "In2.Cu")
		(net "M_M_MA<5>")
	)
	(segment
		(start 88.783668 -145.629376)
		(end 88.757506 -145.655538)
		(width 0.14224)
		(layer "In2.Cu")
		(net "M_M_MA<5>")
	)
	(segment
		(start 91.059254 -102.752906)
		(end 91.059254 -102.94747)
		(width 0.0889)
		(layer "In2.Cu")
		(net "M_M_MA<5>")
	)
	(segment
		(start 87.861394 -154.03195)
		(end 87.499444 -154.905456)
		(width 0.14224)
		(layer "In2.Cu")
		(net "M_M_MA<5>")
	)
	(segment
		(start 88.823292 -129.973324)
		(end 88.823292 -130.605276)
		(width 0.14224)
		(layer "In2.Cu")
		(net "M_M_MA<5>")
	)
	(segment
		(start 88.543892 -128.554988)
		(end 88.543892 -129.693924)
		(width 0.14224)
		(layer "In2.Cu")
		(net "M_M_MA<5>")
	)
	(segment
		(start 90.864182 -98.377502)
		(end 90.869008 -98.386138)
		(width 0.0889)
		(layer "In2.Cu")
		(net "M_M_MA<5>")
	)
	(segment
		(start 90.357198 -91.747086)
		(end 90.852244 -92.413074)
		(width 0.0889)
		(layer "In2.Cu")
		(net "M_M_MA<5>")
	)
	(segment
		(start 88.974168 -133.1468)
		(end 88.78697 -133.333998)
		(width 0.14224)
		(layer "In2.Cu")
		(net "M_M_MA<5>")
	)
	(segment
		(start 88.008968 -149.8346)
		(end 88.008968 -150.4442)
		(width 0.14224)
		(layer "In2.Cu")
		(net "M_M_MA<5>")
	)
	(segment
		(start 90.869008 -95.414338)
		(end 90.875358 -95.425006)
		(width 0.0889)
		(layer "In2.Cu")
		(net "M_M_MA<5>")
	)
	(segment
		(start 88.974168 -131.3942)
		(end 88.974168 -133.1468)
		(width 0.14224)
		(layer "In2.Cu")
		(net "M_M_MA<5>")
	)
	(segment
		(start 91.387168 -125.711712)
		(end 88.543892 -128.554988)
		(width 0.14224)
		(layer "In2.Cu")
		(net "M_M_MA<5>")
	)
	(segment
		(start 90.875358 -94.01302)
		(end 90.869008 -94.023688)
		(width 0.0889)
		(layer "In2.Cu")
		(net "M_M_MA<5>")
	)
	(segment
		(start 90.869008 -97.395538)
		(end 90.875358 -97.406206)
		(width 0.0889)
		(layer "In2.Cu")
		(net "M_M_MA<5>")
	)
	(segment
		(start 88.720168 -130.7084)
		(end 88.720168 -131.1402)
		(width 0.14224)
		(layer "In2.Cu")
		(net "M_M_MA<5>")
	)
	(segment
		(start 88.823292 -130.605276)
		(end 88.720168 -130.7084)
		(width 0.14224)
		(layer "In2.Cu")
		(net "M_M_MA<5>")
	)
	(segment
		(start 90.864182 -97.386902)
		(end 90.869008 -97.395538)
		(width 0.0889)
		(layer "In2.Cu")
		(net "M_M_MA<5>")
	)
	(segment
		(start 88.008968 -150.4442)
		(end 87.913718 -150.53945)
		(width 0.14224)
		(layer "In2.Cu")
		(net "M_M_MA<5>")
	)
	(segment
		(start 90.869008 -92.442538)
		(end 90.875358 -92.453206)
		(width 0.0889)
		(layer "In2.Cu")
		(net "M_M_MA<5>")
	)
	(segment
		(start 90.864182 -93.424502)
		(end 90.869008 -93.433138)
		(width 0.0889)
		(layer "In2.Cu")
		(net "M_M_MA<5>")
	)
	(segment
		(start 90.869008 -96.404938)
		(end 90.875358 -96.415606)
		(width 0.0889)
		(layer "In2.Cu")
		(net "M_M_MA<5>")
	)
	(segment
		(start 88.783668 -140.8811)
		(end 88.783668 -145.629376)
		(width 0.14224)
		(layer "In2.Cu")
		(net "M_M_MA<5>")
	)
	(segment
		(start 91.063572 -99.113086)
		(end 91.063572 -101.809804)
		(width 0.0889)
		(layer "In2.Cu")
		(net "M_M_MA<5>")
	)
	(segment
		(start 88.43137 -153.461974)
		(end 87.861394 -154.03195)
		(width 0.14224)
		(layer "In2.Cu")
		(net "M_M_MA<5>")
	)
	(segment
		(start 88.543892 -129.693924)
		(end 88.823292 -129.973324)
		(width 0.14224)
		(layer "In2.Cu")
		(net "M_M_MA<5>")
	)
	(segment
		(start 87.499444 -147.854924)
		(end 87.499444 -148.773388)
		(width 0.14224)
		(layer "In2.Cu")
		(net "M_M_MA<5>")
	)
	(segment
		(start 91.361768 -102.108)
		(end 91.361768 -102.450392)
		(width 0.0889)
		(layer "In2.Cu")
		(net "M_M_MA<5>")
	)
	(segment
		(start 87.499444 -149.325076)
		(end 88.008968 -149.8346)
		(width 0.14224)
		(layer "In2.Cu")
		(net "M_M_MA<5>")
	)
	(segment
		(start 88.78697 -133.333998)
		(end 88.78697 -135.340598)
		(width 0.14224)
		(layer "In2.Cu")
		(net "M_M_MA<5>")
	)
	(segment
		(start 90.864182 -96.396302)
		(end 90.869008 -96.404938)
		(width 0.0889)
		(layer "In2.Cu")
		(net "M_M_MA<5>")
	)
	(segment
		(start 87.913718 -151.017986)
		(end 88.43137 -151.535638)
		(width 0.14224)
		(layer "In2.Cu")
		(net "M_M_MA<5>")
	)
	(segment
		(start 91.059254 -104.27589)
		(end 91.387168 -104.603804)
		(width 0.14224)
		(layer "In2.Cu")
		(net "M_M_MA<5>")
	)
	(segment
		(start 88.764872 -135.362696)
		(end 88.764872 -140.862304)
		(width 0.14224)
		(layer "In2.Cu")
		(net "M_M_MA<5>")
	)
	(segment
		(start 88.757506 -146.596862)
		(end 87.499444 -147.854924)
		(width 0.14224)
		(layer "In2.Cu")
		(net "M_M_MA<5>")
	)
	(arc
		(start 90.869008 -97.986088)
		(mid 90.815538 -98.181151)
		(end 90.864182 -98.377502)
		(width 0.0889)
		(layer "In2.Cu")
		(net "M_M_MA<5>")
	)
	(arc
		(start 90.869008 -96.004888)
		(mid 90.815538 -96.199951)
		(end 90.864182 -96.396302)
		(width 0.0889)
		(layer "In2.Cu")
		(net "M_M_MA<5>")
	)
	(arc
		(start 90.875358 -96.415606)
		(mid 90.948156 -96.706369)
		(end 90.869008 -96.995488)
		(width 0.0889)
		(layer "In2.Cu")
		(net "M_M_MA<5>")
	)
	(arc
		(start 90.869008 -93.033088)
		(mid 90.815538 -93.228151)
		(end 90.864182 -93.424502)
		(width 0.0889)
		(layer "In2.Cu")
		(net "M_M_MA<5>")
	)
	(arc
		(start 90.875358 -95.425006)
		(mid 90.948156 -95.715769)
		(end 90.869008 -96.004888)
		(width 0.0889)
		(layer "In2.Cu")
		(net "M_M_MA<5>")
	)
	(arc
		(start 90.869008 -95.014288)
		(mid 90.815538 -95.209351)
		(end 90.864182 -95.405702)
		(width 0.0889)
		(layer "In2.Cu")
		(net "M_M_MA<5>")
	)
	(arc
		(start 90.869008 -94.023688)
		(mid 90.815509 -94.223586)
		(end 90.869008 -94.423484)
		(width 0.0889)
		(layer "In2.Cu")
		(net "M_M_MA<5>")
	)
	(arc
		(start 90.875358 -92.453206)
		(mid 90.948156 -92.743969)
		(end 90.869008 -93.033088)
		(width 0.0889)
		(layer "In2.Cu")
		(net "M_M_MA<5>")
	)
	(arc
		(start 90.869008 -98.386138)
		(mid 91.014106 -98.736816)
		(end 91.063572 -99.113086)
		(width 0.0889)
		(layer "In2.Cu")
		(net "M_M_MA<5>")
	)
	(arc
		(start 90.869008 -96.995488)
		(mid 90.815538 -97.190551)
		(end 90.864182 -97.386902)
		(width 0.0889)
		(layer "In2.Cu")
		(net "M_M_MA<5>")
	)
	(arc
		(start 90.869008 -93.433138)
		(mid 90.94823 -93.722256)
		(end 90.875358 -94.01302)
		(width 0.0889)
		(layer "In2.Cu")
		(net "M_M_MA<5>")
	)
	(arc
		(start 90.875358 -97.406206)
		(mid 90.948156 -97.696969)
		(end 90.869008 -97.986088)
		(width 0.0889)
		(layer "In2.Cu")
		(net "M_M_MA<5>")
	)
	(arc
		(start 90.869008 -94.423484)
		(mid 90.948139 -94.718886)
		(end 90.869008 -95.014288)
		(width 0.0889)
		(layer "In2.Cu")
		(net "M_M_MA<5>")
	)
	(segment
		(start 91.787218 -93.23324)
		(end 91.215718 -93.23324)
		(width 0.1016)
		(layer "F.Cu")
		(net "M_M_MA<4>")
	)
	(segment
		(start 88.349582 -156.87294)
		(end 88.349582 -155.538678)
		(width 0.1651)
		(layer "F.Cu")
		(net "M_M_MA<4>")
	)
	(via
		(at 88.349582 -155.538678)
		(size 0.508)
		(drill 0.254)
		(layers "F.Cu" "B.Cu")
		(net "M_M_MA<4>")
	)
	(via
		(at 91.215718 -93.23324)
		(size 0.508)
		(drill 0.254)
		(layers "F.Cu" "B.Cu")
		(net "M_M_MA<4>")
	)
	(via
		(at 88.349582 -148.773388)
		(size 0.4572)
		(drill 0.2032)
		(layers "F.Cu" "B.Cu")
		(net "M_M_MA<4>")
	)
	(segment
		(start 88.349582 -148.773388)
		(end 88.349582 -147.478496)
		(width 0.1651)
		(layer "B.Cu")
		(net "M_M_MA<4>")
	)
	(segment
		(start 91.215718 -93.23324)
		(end 92.03944 -93.32849)
		(width 0.0889)
		(layer "In11.Cu")
		(net "M_M_MA<4>")
	)
	(segment
		(start 94.435168 -139.5222)
		(end 94.917768 -140.0048)
		(width 0.14224)
		(layer "In11.Cu")
		(net "M_M_MA<4>")
	)
	(segment
		(start 94.917768 -141.5288)
		(end 94.435168 -142.0114)
		(width 0.14224)
		(layer "In11.Cu")
		(net "M_M_MA<4>")
	)
	(segment
		(start 93.663516 -102.174548)
		(end 93.663516 -126.982982)
		(width 0.14224)
		(layer "In11.Cu")
		(net "M_M_MA<4>")
	)
	(segment
		(start 88.542368 -151.999696)
		(end 88.542368 -153.67)
		(width 0.14224)
		(layer "In11.Cu")
		(net "M_M_MA<4>")
	)
	(segment
		(start 88.349582 -148.619464)
		(end 88.349582 -148.773388)
		(width 0.14224)
		(layer "In11.Cu")
		(net "M_M_MA<4>")
	)
	(segment
		(start 88.851486 -154.503882)
		(end 88.349582 -155.005786)
		(width 0.14224)
		(layer "In11.Cu")
		(net "M_M_MA<4>")
	)
	(segment
		(start 94.435168 -133.8326)
		(end 94.435168 -139.5222)
		(width 0.14224)
		(layer "In11.Cu")
		(net "M_M_MA<4>")
	)
	(segment
		(start 87.910416 -151.367744)
		(end 88.542368 -151.999696)
		(width 0.14224)
		(layer "In11.Cu")
		(net "M_M_MA<4>")
	)
	(segment
		(start 92.480384 -97.596706)
		(end 92.480384 -99.998784)
		(width 0.0889)
		(layer "In11.Cu")
		(net "M_M_MA<4>")
	)
	(segment
		(start 92.03944 -93.32849)
		(end 92.085414 -93.32849)
		(width 0.0889)
		(layer "In11.Cu")
		(net "M_M_MA<4>")
	)
	(segment
		(start 92.352368 -100.1268)
		(end 92.352368 -100.8634)
		(width 0.0889)
		(layer "In11.Cu")
		(net "M_M_MA<4>")
	)
	(segment
		(start 93.116908 -147.577048)
		(end 89.391998 -147.577048)
		(width 0.14224)
		(layer "In11.Cu")
		(net "M_M_MA<4>")
	)
	(segment
		(start 94.435168 -142.0114)
		(end 94.435168 -146.258788)
		(width 0.14224)
		(layer "In11.Cu")
		(net "M_M_MA<4>")
	)
	(segment
		(start 92.420948 -97.490788)
		(end 92.480384 -97.596706)
		(width 0.0889)
		(layer "In11.Cu")
		(net "M_M_MA<4>")
	)
	(segment
		(start 92.420948 -93.928438)
		(end 92.414598 -93.939106)
		(width 0.0889)
		(layer "In11.Cu")
		(net "M_M_MA<4>")
	)
	(segment
		(start 88.349582 -155.005786)
		(end 88.349582 -155.538678)
		(width 0.14224)
		(layer "In11.Cu")
		(net "M_M_MA<4>")
	)
	(segment
		(start 92.420948 -95.509588)
		(end 92.425774 -95.518224)
		(width 0.0889)
		(layer "In11.Cu")
		(net "M_M_MA<4>")
	)
	(segment
		(start 92.414598 -97.48012)
		(end 92.420948 -97.490788)
		(width 0.0889)
		(layer "In11.Cu")
		(net "M_M_MA<4>")
	)
	(segment
		(start 92.493084 -101.004116)
		(end 93.663516 -102.174548)
		(width 0.14224)
		(layer "In11.Cu")
		(net "M_M_MA<4>")
	)
	(segment
		(start 92.352368 -100.8634)
		(end 92.493084 -101.004116)
		(width 0.0889)
		(layer "In11.Cu")
		(net "M_M_MA<4>")
	)
	(segment
		(start 94.206822 -127.526288)
		(end 94.206822 -133.604254)
		(width 0.14224)
		(layer "In11.Cu")
		(net "M_M_MA<4>")
	)
	(segment
		(start 88.851486 -153.979118)
		(end 88.851486 -154.503882)
		(width 0.14224)
		(layer "In11.Cu")
		(net "M_M_MA<4>")
	)
	(segment
		(start 92.420948 -94.518988)
		(end 92.425774 -94.527624)
		(width 0.0889)
		(layer "In11.Cu")
		(net "M_M_MA<4>")
	)
	(segment
		(start 87.910416 -150.51278)
		(end 87.910416 -151.367744)
		(width 0.14224)
		(layer "In11.Cu")
		(net "M_M_MA<4>")
	)
	(segment
		(start 94.435168 -146.258788)
		(end 93.116908 -147.577048)
		(width 0.14224)
		(layer "In11.Cu")
		(net "M_M_MA<4>")
	)
	(segment
		(start 88.349582 -148.773388)
		(end 88.349582 -150.073614)
		(width 0.14224)
		(layer "In11.Cu")
		(net "M_M_MA<4>")
	)
	(segment
		(start 88.349582 -150.073614)
		(end 87.910416 -150.51278)
		(width 0.14224)
		(layer "In11.Cu")
		(net "M_M_MA<4>")
	)
	(segment
		(start 89.391998 -147.577048)
		(end 88.349582 -148.619464)
		(width 0.14224)
		(layer "In11.Cu")
		(net "M_M_MA<4>")
	)
	(segment
		(start 88.542368 -153.67)
		(end 88.851486 -153.979118)
		(width 0.14224)
		(layer "In11.Cu")
		(net "M_M_MA<4>")
	)
	(segment
		(start 92.420948 -96.500188)
		(end 92.425774 -96.508824)
		(width 0.0889)
		(layer "In11.Cu")
		(net "M_M_MA<4>")
	)
	(segment
		(start 94.917768 -140.0048)
		(end 94.917768 -141.5288)
		(width 0.14224)
		(layer "In11.Cu")
		(net "M_M_MA<4>")
	)
	(segment
		(start 92.414598 -95.49892)
		(end 92.420948 -95.509588)
		(width 0.0889)
		(layer "In11.Cu")
		(net "M_M_MA<4>")
	)
	(segment
		(start 93.663516 -126.982982)
		(end 94.206822 -127.526288)
		(width 0.14224)
		(layer "In11.Cu")
		(net "M_M_MA<4>")
	)
	(segment
		(start 92.414598 -96.48952)
		(end 92.420948 -96.500188)
		(width 0.0889)
		(layer "In11.Cu")
		(net "M_M_MA<4>")
	)
	(segment
		(start 94.206822 -133.604254)
		(end 94.435168 -133.8326)
		(width 0.14224)
		(layer "In11.Cu")
		(net "M_M_MA<4>")
	)
	(segment
		(start 92.480384 -99.998784)
		(end 92.352368 -100.1268)
		(width 0.0889)
		(layer "In11.Cu")
		(net "M_M_MA<4>")
	)
	(arc
		(start 92.420948 -96.900238)
		(mid 92.341726 -97.189356)
		(end 92.414598 -97.48012)
		(width 0.0889)
		(layer "In11.Cu")
		(net "M_M_MA<4>")
	)
	(arc
		(start 92.414598 -93.939106)
		(mid 92.3418 -94.229869)
		(end 92.420948 -94.518988)
		(width 0.0889)
		(layer "In11.Cu")
		(net "M_M_MA<4>")
	)
	(arc
		(start 92.085414 -93.32849)
		(mid 92.423529 -93.533192)
		(end 92.420948 -93.928438)
		(width 0.0889)
		(layer "In11.Cu")
		(net "M_M_MA<4>")
	)
	(arc
		(start 92.425774 -95.518224)
		(mid 92.474529 -95.714576)
		(end 92.420948 -95.909638)
		(width 0.0889)
		(layer "In11.Cu")
		(net "M_M_MA<4>")
	)
	(arc
		(start 92.420948 -94.919038)
		(mid 92.341726 -95.208156)
		(end 92.414598 -95.49892)
		(width 0.0889)
		(layer "In11.Cu")
		(net "M_M_MA<4>")
	)
	(arc
		(start 92.425774 -96.508824)
		(mid 92.474529 -96.705176)
		(end 92.420948 -96.900238)
		(width 0.0889)
		(layer "In11.Cu")
		(net "M_M_MA<4>")
	)
	(arc
		(start 92.425774 -94.527624)
		(mid 92.474529 -94.723976)
		(end 92.420948 -94.919038)
		(width 0.0889)
		(layer "In11.Cu")
		(net "M_M_MA<4>")
	)
	(arc
		(start 92.420948 -95.909638)
		(mid 92.341726 -96.198756)
		(end 92.414598 -96.48952)
		(width 0.0889)
		(layer "In11.Cu")
		(net "M_M_MA<4>")
	)
	(segment
		(start 91.787218 -92.24264)
		(end 91.215718 -92.24264)
		(width 0.1016)
		(layer "F.Cu")
		(net "M_M_MA<3>")
	)
	(segment
		(start 89.199466 -152.273)
		(end 89.199466 -153.542746)
		(width 0.1651)
		(layer "F.Cu")
		(net "M_M_MA<3>")
	)
	(via
		(at 89.199466 -153.542746)
		(size 0.508)
		(drill 0.254)
		(layers "F.Cu" "B.Cu")
		(net "M_M_MA<3>")
	)
	(via
		(at 89.199466 -150.788878)
		(size 0.4572)
		(drill 0.2032)
		(layers "F.Cu" "B.Cu")
		(net "M_M_MA<3>")
	)
	(via
		(at 91.215718 -92.24264)
		(size 0.508)
		(drill 0.254)
		(layers "F.Cu" "B.Cu")
		(net "M_M_MA<3>")
	)
	(segment
		(start 89.199466 -152.078436)
		(end 89.199466 -150.788878)
		(width 0.1651)
		(layer "B.Cu")
		(net "M_M_MA<3>")
	)
	(segment
		(start 89.710768 -131.2164)
		(end 89.507568 -131.4196)
		(width 0.14224)
		(layer "In2.Cu")
		(net "M_M_MA<3>")
	)
	(segment
		(start 91.567254 -98.377502)
		(end 91.371928 -98.727006)
		(width 0.0889)
		(layer "In2.Cu")
		(net "M_M_MA<3>")
	)
	(segment
		(start 91.215718 -92.24264)
		(end 91.545664 -93.004386)
		(width 0.0889)
		(layer "In2.Cu")
		(net "M_M_MA<3>")
	)
	(segment
		(start 89.710768 -130.683)
		(end 89.710768 -131.2164)
		(width 0.14224)
		(layer "In2.Cu")
		(net "M_M_MA<3>")
	)
	(segment
		(start 89.444322 -151.750268)
		(end 89.031572 -151.750268)
		(width 0.14224)
		(layer "In2.Cu")
		(net "M_M_MA<3>")
	)
	(segment
		(start 89.676224 -129.36982)
		(end 89.676224 -129.803144)
		(width 0.14224)
		(layer "In2.Cu")
		(net "M_M_MA<3>")
	)
	(segment
		(start 89.507568 -132.0546)
		(end 89.634568 -132.1816)
		(width 0.14224)
		(layer "In2.Cu")
		(net "M_M_MA<3>")
	)
	(segment
		(start 89.507568 -131.4196)
		(end 89.507568 -132.0546)
		(width 0.14224)
		(layer "In2.Cu")
		(net "M_M_MA<3>")
	)
	(segment
		(start 91.863672 -126.884176)
		(end 91.863672 -127.16129)
		(width 0.14224)
		(layer "In2.Cu")
		(net "M_M_MA<3>")
	)
	(segment
		(start 91.895168 -125.922532)
		(end 91.542362 -126.275338)
		(width 0.14224)
		(layer "In2.Cu")
		(net "M_M_MA<3>")
	)
	(segment
		(start 91.567254 -97.386902)
		(end 91.562428 -97.395538)
		(width 0.0889)
		(layer "In2.Cu")
		(net "M_M_MA<3>")
	)
	(segment
		(start 91.368372 -101.606604)
		(end 91.575128 -101.81336)
		(width 0.0889)
		(layer "In2.Cu")
		(net "M_M_MA<3>")
	)
	(segment
		(start 89.957656 -128.426972)
		(end 89.69121 -128.426972)
		(width 0.14224)
		(layer "In2.Cu")
		(net "M_M_MA<3>")
	)
	(segment
		(start 90.856054 -128.418336)
		(end 90.533982 -128.740408)
		(width 0.14224)
		(layer "In2.Cu")
		(net "M_M_MA<3>")
	)
	(segment
		(start 91.567254 -95.405702)
		(end 91.562428 -95.414338)
		(width 0.0889)
		(layer "In2.Cu")
		(net "M_M_MA<3>")
	)
	(segment
		(start 90.271092 -128.740408)
		(end 89.957656 -128.426972)
		(width 0.14224)
		(layer "In2.Cu")
		(net "M_M_MA<3>")
	)
	(segment
		(start 91.575128 -104.073198)
		(end 91.895168 -104.393238)
		(width 0.14224)
		(layer "In2.Cu")
		(net "M_M_MA<3>")
	)
	(segment
		(start 90.476578 -127.466852)
		(end 90.476578 -127.79629)
		(width 0.14224)
		(layer "In2.Cu")
		(net "M_M_MA<3>")
	)
	(segment
		(start 89.444322 -152.413208)
		(end 89.599262 -152.568148)
		(width 0.14224)
		(layer "In2.Cu")
		(net "M_M_MA<3>")
	)
	(segment
		(start 88.876632 -152.258268)
		(end 89.031572 -152.413208)
		(width 0.14224)
		(layer "In2.Cu")
		(net "M_M_MA<3>")
	)
	(segment
		(start 89.634568 -146.558)
		(end 88.761062 -147.431506)
		(width 0.14224)
		(layer "In2.Cu")
		(net "M_M_MA<3>")
	)
	(segment
		(start 91.556078 -94.01302)
		(end 91.562428 -94.023688)
		(width 0.0889)
		(layer "In2.Cu")
		(net "M_M_MA<3>")
	)
	(segment
		(start 89.36355 -129.057146)
		(end 89.676224 -129.36982)
		(width 0.14224)
		(layer "In2.Cu")
		(net "M_M_MA<3>")
	)
	(segment
		(start 89.676224 -129.803144)
		(end 89.532968 -129.9464)
		(width 0.14224)
		(layer "In2.Cu")
		(net "M_M_MA<3>")
	)
	(segment
		(start 88.761062 -147.431506)
		(end 88.761062 -150.350474)
		(width 0.14224)
		(layer "In2.Cu")
		(net "M_M_MA<3>")
	)
	(segment
		(start 89.031572 -151.750268)
		(end 88.876632 -151.905208)
		(width 0.14224)
		(layer "In2.Cu")
		(net "M_M_MA<3>")
	)
	(segment
		(start 91.545664 -93.004386)
		(end 91.562428 -93.033088)
		(width 0.0889)
		(layer "In2.Cu")
		(net "M_M_MA<3>")
	)
	(segment
		(start 91.368372 -98.730562)
		(end 91.368372 -101.606604)
		(width 0.0889)
		(layer "In2.Cu")
		(net "M_M_MA<3>")
	)
	(segment
		(start 91.576398 -127.448564)
		(end 91.278456 -127.448564)
		(width 0.14224)
		(layer "In2.Cu")
		(net "M_M_MA<3>")
	)
	(segment
		(start 89.36355 -128.754632)
		(end 89.36355 -129.057146)
		(width 0.14224)
		(layer "In2.Cu")
		(net "M_M_MA<3>")
	)
	(segment
		(start 89.599262 -152.568148)
		(end 89.599262 -153.14295)
		(width 0.14224)
		(layer "In2.Cu")
		(net "M_M_MA<3>")
	)
	(segment
		(start 89.532968 -130.5052)
		(end 89.710768 -130.683)
		(width 0.14224)
		(layer "In2.Cu")
		(net "M_M_MA<3>")
	)
	(segment
		(start 89.599262 -151.595328)
		(end 89.444322 -151.750268)
		(width 0.14224)
		(layer "In2.Cu")
		(net "M_M_MA<3>")
	)
	(segment
		(start 91.278456 -127.448564)
		(end 91.00947 -127.179578)
		(width 0.14224)
		(layer "In2.Cu")
		(net "M_M_MA<3>")
	)
	(segment
		(start 91.567254 -96.396302)
		(end 91.562428 -96.404938)
		(width 0.0889)
		(layer "In2.Cu")
		(net "M_M_MA<3>")
	)
	(segment
		(start 91.542362 -126.562866)
		(end 91.863672 -126.884176)
		(width 0.14224)
		(layer "In2.Cu")
		(net "M_M_MA<3>")
	)
	(segment
		(start 89.031572 -152.413208)
		(end 89.444322 -152.413208)
		(width 0.14224)
		(layer "In2.Cu")
		(net "M_M_MA<3>")
	)
	(segment
		(start 91.00947 -127.179578)
		(end 90.763852 -127.179578)
		(width 0.14224)
		(layer "In2.Cu")
		(net "M_M_MA<3>")
	)
	(segment
		(start 91.562428 -97.395538)
		(end 91.556078 -97.406206)
		(width 0.0889)
		(layer "In2.Cu")
		(net "M_M_MA<3>")
	)
	(segment
		(start 91.562428 -95.414338)
		(end 91.556078 -95.425006)
		(width 0.0889)
		(layer "In2.Cu")
		(net "M_M_MA<3>")
	)
	(segment
		(start 90.476578 -127.79629)
		(end 90.856054 -128.175766)
		(width 0.14224)
		(layer "In2.Cu")
		(net "M_M_MA<3>")
	)
	(segment
		(start 89.532968 -129.9464)
		(end 89.532968 -130.5052)
		(width 0.14224)
		(layer "In2.Cu")
		(net "M_M_MA<3>")
	)
	(segment
		(start 90.856054 -128.175766)
		(end 90.856054 -128.418336)
		(width 0.14224)
		(layer "In2.Cu")
		(net "M_M_MA<3>")
	)
	(segment
		(start 88.876632 -151.905208)
		(end 88.876632 -152.258268)
		(width 0.14224)
		(layer "In2.Cu")
		(net "M_M_MA<3>")
	)
	(segment
		(start 89.199466 -150.788878)
		(end 89.599262 -151.188674)
		(width 0.14224)
		(layer "In2.Cu")
		(net "M_M_MA<3>")
	)
	(segment
		(start 91.863672 -127.16129)
		(end 91.576398 -127.448564)
		(width 0.14224)
		(layer "In2.Cu")
		(net "M_M_MA<3>")
	)
	(segment
		(start 91.542362 -126.275338)
		(end 91.542362 -126.562866)
		(width 0.14224)
		(layer "In2.Cu")
		(net "M_M_MA<3>")
	)
	(segment
		(start 89.599262 -153.14295)
		(end 89.199466 -153.542746)
		(width 0.14224)
		(layer "In2.Cu")
		(net "M_M_MA<3>")
	)
	(segment
		(start 89.634568 -132.1816)
		(end 89.634568 -146.558)
		(width 0.14224)
		(layer "In2.Cu")
		(net "M_M_MA<3>")
	)
	(segment
		(start 90.763852 -127.179578)
		(end 90.476578 -127.466852)
		(width 0.14224)
		(layer "In2.Cu")
		(net "M_M_MA<3>")
	)
	(segment
		(start 88.761062 -150.350474)
		(end 89.199466 -150.788878)
		(width 0.14224)
		(layer "In2.Cu")
		(net "M_M_MA<3>")
	)
	(segment
		(start 91.575128 -102.80904)
		(end 91.575128 -104.073198)
		(width 0.14224)
		(layer "In2.Cu")
		(net "M_M_MA<3>")
	)
	(segment
		(start 91.567254 -93.424502)
		(end 91.562428 -93.433138)
		(width 0.0889)
		(layer "In2.Cu")
		(net "M_M_MA<3>")
	)
	(segment
		(start 89.599262 -151.188674)
		(end 89.599262 -151.595328)
		(width 0.14224)
		(layer "In2.Cu")
		(net "M_M_MA<3>")
	)
	(segment
		(start 90.533982 -128.740408)
		(end 90.271092 -128.740408)
		(width 0.14224)
		(layer "In2.Cu")
		(net "M_M_MA<3>")
	)
	(segment
		(start 91.562428 -96.404938)
		(end 91.556078 -96.415606)
		(width 0.0889)
		(layer "In2.Cu")
		(net "M_M_MA<3>")
	)
	(segment
		(start 91.371928 -98.727006)
		(end 91.368372 -98.730562)
		(width 0.0889)
		(layer "In2.Cu")
		(net "M_M_MA<3>")
	)
	(segment
		(start 91.575128 -101.81336)
		(end 91.575128 -102.80904)
		(width 0.0889)
		(layer "In2.Cu")
		(net "M_M_MA<3>")
	)
	(segment
		(start 91.895168 -104.393238)
		(end 91.895168 -125.922532)
		(width 0.14224)
		(layer "In2.Cu")
		(net "M_M_MA<3>")
	)
	(segment
		(start 89.69121 -128.426972)
		(end 89.36355 -128.754632)
		(width 0.14224)
		(layer "In2.Cu")
		(net "M_M_MA<3>")
	)
	(arc
		(start 91.562428 -93.033088)
		(mid 91.615898 -93.228151)
		(end 91.567254 -93.424502)
		(width 0.0889)
		(layer "In2.Cu")
		(net "M_M_MA<3>")
	)
	(arc
		(start 91.562428 -95.014288)
		(mid 91.615898 -95.209351)
		(end 91.567254 -95.405702)
		(width 0.0889)
		(layer "In2.Cu")
		(net "M_M_MA<3>")
	)
	(arc
		(start 91.556078 -96.415606)
		(mid 91.48328 -96.706369)
		(end 91.562428 -96.995488)
		(width 0.0889)
		(layer "In2.Cu")
		(net "M_M_MA<3>")
	)
	(arc
		(start 91.562428 -93.433138)
		(mid 91.483206 -93.722256)
		(end 91.556078 -94.01302)
		(width 0.0889)
		(layer "In2.Cu")
		(net "M_M_MA<3>")
	)
	(arc
		(start 91.562428 -97.986088)
		(mid 91.615898 -98.181151)
		(end 91.567254 -98.377502)
		(width 0.0889)
		(layer "In2.Cu")
		(net "M_M_MA<3>")
	)
	(arc
		(start 91.556078 -95.425006)
		(mid 91.48328 -95.715769)
		(end 91.562428 -96.004888)
		(width 0.0889)
		(layer "In2.Cu")
		(net "M_M_MA<3>")
	)
	(arc
		(start 91.562428 -96.995488)
		(mid 91.615898 -97.190551)
		(end 91.567254 -97.386902)
		(width 0.0889)
		(layer "In2.Cu")
		(net "M_M_MA<3>")
	)
	(arc
		(start 91.556078 -97.406206)
		(mid 91.48328 -97.696969)
		(end 91.562428 -97.986088)
		(width 0.0889)
		(layer "In2.Cu")
		(net "M_M_MA<3>")
	)
	(arc
		(start 91.562428 -96.004888)
		(mid 91.615898 -96.199951)
		(end 91.567254 -96.396302)
		(width 0.0889)
		(layer "In2.Cu")
		(net "M_M_MA<3>")
	)
	(arc
		(start 91.562428 -94.423484)
		(mid 91.483297 -94.718886)
		(end 91.562428 -95.014288)
		(width 0.0889)
		(layer "In2.Cu")
		(net "M_M_MA<3>")
	)
	(arc
		(start 91.562428 -94.023688)
		(mid 91.615927 -94.223586)
		(end 91.562428 -94.423484)
		(width 0.0889)
		(layer "In2.Cu")
		(net "M_M_MA<3>")
	)
	(segment
		(start 90.04935 -156.87294)
		(end 90.04935 -155.538932)
		(width 0.1651)
		(layer "F.Cu")
		(net "M_M_MA<2>")
	)
	(segment
		(start 92.645738 -90.756486)
		(end 92.074238 -90.756486)
		(width 0.1016)
		(layer "F.Cu")
		(net "M_M_MA<2>")
	)
	(via
		(at 92.074238 -90.756486)
		(size 0.508)
		(drill 0.254)
		(layers "F.Cu" "B.Cu")
		(net "M_M_MA<2>")
	)
	(via
		(at 90.04935 -148.773388)
		(size 0.4572)
		(drill 0.2032)
		(layers "F.Cu" "B.Cu")
		(net "M_M_MA<2>")
	)
	(via
		(at 90.04935 -155.538932)
		(size 0.508)
		(drill 0.254)
		(layers "F.Cu" "B.Cu")
		(net "M_M_MA<2>")
	)
	(segment
		(start 90.04935 -147.478496)
		(end 90.04935 -148.773388)
		(width 0.1651)
		(layer "B.Cu")
		(net "M_M_MA<2>")
	)
	(segment
		(start 94.171516 -101.958648)
		(end 94.171516 -126.772416)
		(width 0.14224)
		(layer "In11.Cu")
		(net "M_M_MA<2>")
	)
	(segment
		(start 92.581222 -97.386902)
		(end 92.790772 -97.752662)
		(width 0.0889)
		(layer "In11.Cu")
		(net "M_M_MA<2>")
	)
	(segment
		(start 92.592398 -94.01302)
		(end 92.586048 -94.023688)
		(width 0.0889)
		(layer "In11.Cu")
		(net "M_M_MA<2>")
	)
	(segment
		(start 94.714822 -127.315722)
		(end 94.714822 -133.375908)
		(width 0.14224)
		(layer "In11.Cu")
		(net "M_M_MA<2>")
	)
	(segment
		(start 94.943168 -139.4206)
		(end 95.400368 -139.8778)
		(width 0.14224)
		(layer "In11.Cu")
		(net "M_M_MA<2>")
	)
	(segment
		(start 95.400368 -145.8722)
		(end 93.28658 -147.985988)
		(width 0.14224)
		(layer "In11.Cu")
		(net "M_M_MA<2>")
	)
	(segment
		(start 92.581222 -96.396302)
		(end 92.586048 -96.404938)
		(width 0.0889)
		(layer "In11.Cu")
		(net "M_M_MA<2>")
	)
	(segment
		(start 90.04935 -149.401276)
		(end 89.611962 -149.838664)
		(width 0.14224)
		(layer "In11.Cu")
		(net "M_M_MA<2>")
	)
	(segment
		(start 92.074238 -90.756486)
		(end 92.532454 -91.52636)
		(width 0.0889)
		(layer "In11.Cu")
		(net "M_M_MA<2>")
	)
	(segment
		(start 94.171516 -126.772416)
		(end 94.714822 -127.315722)
		(width 0.14224)
		(layer "In11.Cu")
		(net "M_M_MA<2>")
	)
	(segment
		(start 92.586048 -95.414338)
		(end 92.592398 -95.425006)
		(width 0.0889)
		(layer "In11.Cu")
		(net "M_M_MA<2>")
	)
	(segment
		(start 89.611962 -149.838664)
		(end 89.611962 -153.088594)
		(width 0.14224)
		(layer "In11.Cu")
		(net "M_M_MA<2>")
	)
	(segment
		(start 92.586048 -96.404938)
		(end 92.592398 -96.415606)
		(width 0.0889)
		(layer "In11.Cu")
		(net "M_M_MA<2>")
	)
	(segment
		(start 92.581222 -95.405702)
		(end 92.586048 -95.414338)
		(width 0.0889)
		(layer "In11.Cu")
		(net "M_M_MA<2>")
	)
	(segment
		(start 94.714822 -133.375908)
		(end 94.943168 -133.604254)
		(width 0.14224)
		(layer "In11.Cu")
		(net "M_M_MA<2>")
	)
	(segment
		(start 93.28658 -147.985988)
		(end 90.83675 -147.985988)
		(width 0.14224)
		(layer "In11.Cu")
		(net "M_M_MA<2>")
	)
	(segment
		(start 90.04935 -148.773388)
		(end 90.04935 -149.401276)
		(width 0.14224)
		(layer "In11.Cu")
		(net "M_M_MA<2>")
	)
	(segment
		(start 92.879418 -100.66655)
		(end 94.171516 -101.958648)
		(width 0.14224)
		(layer "In11.Cu")
		(net "M_M_MA<2>")
	)
	(segment
		(start 90.507566 -153.984198)
		(end 90.507566 -154.498802)
		(width 0.14224)
		(layer "In11.Cu")
		(net "M_M_MA<2>")
	)
	(segment
		(start 90.507566 -154.498802)
		(end 90.04935 -154.957018)
		(width 0.14224)
		(layer "In11.Cu")
		(net "M_M_MA<2>")
	)
	(segment
		(start 90.83675 -147.985988)
		(end 90.04935 -148.773388)
		(width 0.14224)
		(layer "In11.Cu")
		(net "M_M_MA<2>")
	)
	(segment
		(start 92.790772 -97.752662)
		(end 92.790772 -100.577904)
		(width 0.0889)
		(layer "In11.Cu")
		(net "M_M_MA<2>")
	)
	(segment
		(start 92.790772 -100.577904)
		(end 92.879418 -100.66655)
		(width 0.0889)
		(layer "In11.Cu")
		(net "M_M_MA<2>")
	)
	(segment
		(start 92.581222 -93.424502)
		(end 92.586048 -93.433138)
		(width 0.0889)
		(layer "In11.Cu")
		(net "M_M_MA<2>")
	)
	(segment
		(start 92.532454 -91.52636)
		(end 92.532454 -93.2307)
		(width 0.0889)
		(layer "In11.Cu")
		(net "M_M_MA<2>")
	)
	(segment
		(start 89.611962 -153.088594)
		(end 90.507566 -153.984198)
		(width 0.14224)
		(layer "In11.Cu")
		(net "M_M_MA<2>")
	)
	(segment
		(start 95.400368 -139.8778)
		(end 95.400368 -145.8722)
		(width 0.14224)
		(layer "In11.Cu")
		(net "M_M_MA<2>")
	)
	(segment
		(start 90.04935 -154.957018)
		(end 90.04935 -155.538932)
		(width 0.14224)
		(layer "In11.Cu")
		(net "M_M_MA<2>")
	)
	(segment
		(start 94.943168 -133.604254)
		(end 94.943168 -139.4206)
		(width 0.14224)
		(layer "In11.Cu")
		(net "M_M_MA<2>")
	)
	(arc
		(start 92.586048 -95.014288)
		(mid 92.532578 -95.209351)
		(end 92.581222 -95.405702)
		(width 0.0889)
		(layer "In11.Cu")
		(net "M_M_MA<2>")
	)
	(arc
		(start 92.586048 -96.995488)
		(mid 92.532578 -97.190551)
		(end 92.581222 -97.386902)
		(width 0.0889)
		(layer "In11.Cu")
		(net "M_M_MA<2>")
	)
	(arc
		(start 92.592398 -96.415606)
		(mid 92.665196 -96.706369)
		(end 92.586048 -96.995488)
		(width 0.0889)
		(layer "In11.Cu")
		(net "M_M_MA<2>")
	)
	(arc
		(start 92.586048 -93.433138)
		(mid 92.66527 -93.722256)
		(end 92.592398 -94.01302)
		(width 0.0889)
		(layer "In11.Cu")
		(net "M_M_MA<2>")
	)
	(arc
		(start 92.586048 -94.023688)
		(mid 92.532549 -94.223586)
		(end 92.586048 -94.423484)
		(width 0.0889)
		(layer "In11.Cu")
		(net "M_M_MA<2>")
	)
	(arc
		(start 92.592398 -95.425006)
		(mid 92.665196 -95.715769)
		(end 92.586048 -96.004888)
		(width 0.0889)
		(layer "In11.Cu")
		(net "M_M_MA<2>")
	)
	(arc
		(start 92.586048 -94.423484)
		(mid 92.665179 -94.718886)
		(end 92.586048 -95.014288)
		(width 0.0889)
		(layer "In11.Cu")
		(net "M_M_MA<2>")
	)
	(arc
		(start 92.586048 -96.004888)
		(mid 92.532578 -96.199951)
		(end 92.581222 -96.396302)
		(width 0.0889)
		(layer "In11.Cu")
		(net "M_M_MA<2>")
	)
	(arc
		(start 92.532454 -93.2307)
		(mid 92.544554 -93.330691)
		(end 92.581222 -93.424502)
		(width 0.0889)
		(layer "In11.Cu")
		(net "M_M_MA<2>")
	)
	(segment
		(start 91.787218 -90.26144)
		(end 91.215718 -90.26144)
		(width 0.1016)
		(layer "F.Cu")
		(net "M_M_MA<1>")
	)
	(segment
		(start 90.04935 -152.273)
		(end 90.04935 -152.278842)
		(width 0.1651)
		(layer "F.Cu")
		(net "M_M_MA<1>")
	)
	(segment
		(start 90.04935 -152.278842)
		(end 90.049604 -152.279096)
		(width 0.1651)
		(layer "F.Cu")
		(net "M_M_MA<1>")
	)
	(segment
		(start 90.049604 -152.279096)
		(end 90.049604 -154.252168)
		(width 0.1651)
		(layer "F.Cu")
		(net "M_M_MA<1>")
	)
	(via
		(at 90.049604 -150.788878)
		(size 0.4572)
		(drill 0.2032)
		(layers "F.Cu" "B.Cu")
		(net "M_M_MA<1>")
	)
	(via
		(at 91.215718 -90.26144)
		(size 0.508)
		(drill 0.254)
		(layers "F.Cu" "B.Cu")
		(net "M_M_MA<1>")
	)
	(via
		(at 90.049604 -154.252168)
		(size 0.508)
		(drill 0.254)
		(layers "F.Cu" "B.Cu")
		(net "M_M_MA<1>")
	)
	(segment
		(start 90.04935 -150.814532)
		(end 90.049604 -150.814278)
		(width 0.1651)
		(layer "B.Cu")
		(net "M_M_MA<1>")
	)
	(segment
		(start 90.04935 -152.078436)
		(end 90.04935 -150.814532)
		(width 0.1651)
		(layer "B.Cu")
		(net "M_M_MA<1>")
	)
	(segment
		(start 90.049604 -150.814278)
		(end 90.049604 -150.788878)
		(width 0.1651)
		(layer "B.Cu")
		(net "M_M_MA<1>")
	)
	(segment
		(start 91.670632 -91.173554)
		(end 91.670632 -92.72524)
		(width 0.0889)
		(layer "In2.Cu")
		(net "M_M_MA<1>")
	)
	(segment
		(start 91.727528 -97.490788)
		(end 91.722702 -97.499424)
		(width 0.0889)
		(layer "In2.Cu")
		(net "M_M_MA<1>")
	)
	(segment
		(start 92.083128 -101.787706)
		(end 92.083128 -102.035102)
		(width 0.0889)
		(layer "In2.Cu")
		(net "M_M_MA<1>")
	)
	(segment
		(start 90.362278 -144.362678)
		(end 90.362278 -145.698718)
		(width 0.14224)
		(layer "In2.Cu")
		(net "M_M_MA<1>")
	)
	(segment
		(start 92.083128 -102.035102)
		(end 92.083128 -103.862632)
		(width 0.14224)
		(layer "In2.Cu")
		(net "M_M_MA<1>")
	)
	(segment
		(start 91.673172 -98.58121)
		(end 91.673172 -101.37775)
		(width 0.0889)
		(layer "In2.Cu")
		(net "M_M_MA<1>")
	)
	(segment
		(start 90.462862 -144.262094)
		(end 90.362278 -144.362678)
		(width 0.14224)
		(layer "In2.Cu")
		(net "M_M_MA<1>")
	)
	(segment
		(start 91.34221 -134.022338)
		(end 91.34221 -141.453362)
		(width 0.14224)
		(layer "In2.Cu")
		(net "M_M_MA<1>")
	)
	(segment
		(start 90.625168 -133.305296)
		(end 91.34221 -134.022338)
		(width 0.14224)
		(layer "In2.Cu")
		(net "M_M_MA<1>")
	)
	(segment
		(start 91.673172 -101.37775)
		(end 92.083128 -101.787706)
		(width 0.0889)
		(layer "In2.Cu")
		(net "M_M_MA<1>")
	)
	(segment
		(start 91.34221 -141.453362)
		(end 90.462862 -142.33271)
		(width 0.14224)
		(layer "In2.Cu")
		(net "M_M_MA<1>")
	)
	(segment
		(start 89.634314 -149.149054)
		(end 89.558368 -149.225)
		(width 0.14224)
		(layer "In2.Cu")
		(net "M_M_MA<1>")
	)
	(segment
		(start 91.733878 -97.48012)
		(end 91.727528 -97.490788)
		(width 0.0889)
		(layer "In2.Cu")
		(net "M_M_MA<1>")
	)
	(segment
		(start 90.625168 -129.397252)
		(end 90.625168 -133.305296)
		(width 0.14224)
		(layer "In2.Cu")
		(net "M_M_MA<1>")
	)
	(segment
		(start 91.727528 -96.500188)
		(end 91.722702 -96.508824)
		(width 0.0889)
		(layer "In2.Cu")
		(net "M_M_MA<1>")
	)
	(segment
		(start 89.558368 -150.297642)
		(end 90.049604 -150.788878)
		(width 0.14224)
		(layer "In2.Cu")
		(net "M_M_MA<1>")
	)
	(segment
		(start 91.727528 -95.509588)
		(end 91.722702 -95.518224)
		(width 0.0889)
		(layer "In2.Cu")
		(net "M_M_MA<1>")
	)
	(segment
		(start 92.403168 -127.619252)
		(end 90.625168 -129.397252)
		(width 0.14224)
		(layer "In2.Cu")
		(net "M_M_MA<1>")
	)
	(segment
		(start 91.733878 -96.48952)
		(end 91.727528 -96.500188)
		(width 0.0889)
		(layer "In2.Cu")
		(net "M_M_MA<1>")
	)
	(segment
		(start 90.362278 -145.698718)
		(end 90.463624 -145.800064)
		(width 0.14224)
		(layer "In2.Cu")
		(net "M_M_MA<1>")
	)
	(segment
		(start 90.463624 -145.800064)
		(end 90.463624 -146.643344)
		(width 0.14224)
		(layer "In2.Cu")
		(net "M_M_MA<1>")
	)
	(segment
		(start 90.462862 -142.33271)
		(end 90.462862 -144.262094)
		(width 0.14224)
		(layer "In2.Cu")
		(net "M_M_MA<1>")
	)
	(segment
		(start 92.403168 -104.182672)
		(end 92.403168 -127.619252)
		(width 0.14224)
		(layer "In2.Cu")
		(net "M_M_MA<1>")
	)
	(segment
		(start 91.733878 -95.49892)
		(end 91.727528 -95.509588)
		(width 0.0889)
		(layer "In2.Cu")
		(net "M_M_MA<1>")
	)
	(segment
		(start 89.558368 -149.225)
		(end 89.558368 -150.297642)
		(width 0.14224)
		(layer "In2.Cu")
		(net "M_M_MA<1>")
	)
	(segment
		(start 90.049604 -150.788878)
		(end 90.049604 -154.252168)
		(width 0.14224)
		(layer "In2.Cu")
		(net "M_M_MA<1>")
	)
	(segment
		(start 90.463624 -146.643344)
		(end 89.634314 -147.472654)
		(width 0.14224)
		(layer "In2.Cu")
		(net "M_M_MA<1>")
	)
	(segment
		(start 92.083128 -103.862632)
		(end 92.403168 -104.182672)
		(width 0.14224)
		(layer "In2.Cu")
		(net "M_M_MA<1>")
	)
	(segment
		(start 89.634314 -147.472654)
		(end 89.634314 -149.149054)
		(width 0.14224)
		(layer "In2.Cu")
		(net "M_M_MA<1>")
	)
	(segment
		(start 91.727528 -93.928438)
		(end 91.733878 -93.939106)
		(width 0.0889)
		(layer "In2.Cu")
		(net "M_M_MA<1>")
	)
	(segment
		(start 91.733878 -98.47072)
		(end 91.727528 -98.481388)
		(width 0.0889)
		(layer "In2.Cu")
		(net "M_M_MA<1>")
	)
	(segment
		(start 91.727528 -94.518988)
		(end 91.722702 -94.527624)
		(width 0.0889)
		(layer "In2.Cu")
		(net "M_M_MA<1>")
	)
	(segment
		(start 91.727528 -98.481388)
		(end 91.673172 -98.58121)
		(width 0.0889)
		(layer "In2.Cu")
		(net "M_M_MA<1>")
	)
	(segment
		(start 91.215718 -90.26144)
		(end 91.670632 -91.173554)
		(width 0.0889)
		(layer "In2.Cu")
		(net "M_M_MA<1>")
	)
	(arc
		(start 91.733878 -93.939106)
		(mid 91.806676 -94.229869)
		(end 91.727528 -94.518988)
		(width 0.0889)
		(layer "In2.Cu")
		(net "M_M_MA<1>")
	)
	(arc
		(start 91.727528 -95.909638)
		(mid 91.80675 -96.198756)
		(end 91.733878 -96.48952)
		(width 0.0889)
		(layer "In2.Cu")
		(net "M_M_MA<1>")
	)
	(arc
		(start 91.722702 -96.508824)
		(mid 91.673947 -96.705176)
		(end 91.727528 -96.900238)
		(width 0.0889)
		(layer "In2.Cu")
		(net "M_M_MA<1>")
	)
	(arc
		(start 91.722702 -95.518224)
		(mid 91.673947 -95.714576)
		(end 91.727528 -95.909638)
		(width 0.0889)
		(layer "In2.Cu")
		(net "M_M_MA<1>")
	)
	(arc
		(start 91.722702 -94.527624)
		(mid 91.673947 -94.723976)
		(end 91.727528 -94.919038)
		(width 0.0889)
		(layer "In2.Cu")
		(net "M_M_MA<1>")
	)
	(arc
		(start 91.727528 -94.919038)
		(mid 91.80675 -95.208156)
		(end 91.733878 -95.49892)
		(width 0.0889)
		(layer "In2.Cu")
		(net "M_M_MA<1>")
	)
	(arc
		(start 91.727528 -92.937838)
		(mid 91.806659 -93.23324)
		(end 91.727528 -93.528642)
		(width 0.0889)
		(layer "In2.Cu")
		(net "M_M_MA<1>")
	)
	(arc
		(start 91.670632 -92.72524)
		(mid 91.685092 -92.835285)
		(end 91.727528 -92.937838)
		(width 0.0889)
		(layer "In2.Cu")
		(net "M_M_MA<1>")
	)
	(arc
		(start 91.727528 -93.528642)
		(mid 91.674029 -93.72854)
		(end 91.727528 -93.928438)
		(width 0.0889)
		(layer "In2.Cu")
		(net "M_M_MA<1>")
	)
	(arc
		(start 91.727528 -96.900238)
		(mid 91.80675 -97.189356)
		(end 91.733878 -97.48012)
		(width 0.0889)
		(layer "In2.Cu")
		(net "M_M_MA<1>")
	)
	(arc
		(start 91.727528 -97.890838)
		(mid 91.80675 -98.179956)
		(end 91.733878 -98.47072)
		(width 0.0889)
		(layer "In2.Cu")
		(net "M_M_MA<1>")
	)
	(arc
		(start 91.722702 -97.499424)
		(mid 91.673947 -97.695776)
		(end 91.727528 -97.890838)
		(width 0.0889)
		(layer "In2.Cu")
		(net "M_M_MA<1>")
	)
	(segment
		(start 110.44936 -156.87294)
		(end 110.44936 -155.614878)
		(width 0.1651)
		(layer "F.Cu")
		(net "M_M_MA<17>")
	)
	(segment
		(start 102.089204 -91.25204)
		(end 101.517704 -91.25204)
		(width 0.10795)
		(layer "F.Cu")
		(net "M_M_MA<17>")
	)
	(via
		(at 110.449868 -148.773388)
		(size 0.4572)
		(drill 0.2032)
		(layers "F.Cu" "B.Cu")
		(net "M_M_MA<17>")
	)
	(via
		(at 110.44936 -155.614878)
		(size 0.508)
		(drill 0.254)
		(layers "F.Cu" "B.Cu")
		(net "M_M_MA<17>")
	)
	(via
		(at 101.517704 -91.25204)
		(size 0.508)
		(drill 0.254)
		(layers "F.Cu" "B.Cu")
		(net "M_M_MA<17>")
	)
	(segment
		(start 110.44936 -148.77288)
		(end 110.449868 -148.773388)
		(width 0.1651)
		(layer "B.Cu")
		(net "M_M_MA<17>")
	)
	(segment
		(start 110.44936 -147.478496)
		(end 110.44936 -148.77288)
		(width 0.1651)
		(layer "B.Cu")
		(net "M_M_MA<17>")
	)
	(segment
		(start 112.575594 -129.255266)
		(end 112.494568 -129.336292)
		(width 0.14224)
		(layer "In11.Cu")
		(net "M_M_MA<17>")
	)
	(segment
		(start 112.584738 -144.86763)
		(end 111.71174 -145.740628)
		(width 0.14224)
		(layer "In11.Cu")
		(net "M_M_MA<17>")
	)
	(segment
		(start 112.697768 -130.0988)
		(end 112.697768 -130.4544)
		(width 0.14224)
		(layer "In11.Cu")
		(net "M_M_MA<17>")
	)
	(segment
		(start 101.724968 -91.459304)
		(end 101.724968 -91.7702)
		(width 0.0889)
		(layer "In11.Cu")
		(net "M_M_MA<17>")
	)
	(segment
		(start 112.588802 -131.909566)
		(end 112.588802 -134.714234)
		(width 0.14224)
		(layer "In11.Cu")
		(net "M_M_MA<17>")
	)
	(segment
		(start 112.697768 -131.3434)
		(end 112.697768 -131.8006)
		(width 0.14224)
		(layer "In11.Cu")
		(net "M_M_MA<17>")
	)
	(segment
		(start 112.494568 -129.336292)
		(end 112.494568 -129.8956)
		(width 0.14224)
		(layer "In11.Cu")
		(net "M_M_MA<17>")
	)
	(segment
		(start 105.306622 -119.024908)
		(end 112.575594 -126.29388)
		(width 0.14224)
		(layer "In11.Cu")
		(net "M_M_MA<17>")
	)
	(segment
		(start 112.588802 -134.714234)
		(end 112.697768 -134.8232)
		(width 0.14224)
		(layer "In11.Cu")
		(net "M_M_MA<17>")
	)
	(segment
		(start 110.014004 -150.563072)
		(end 110.014004 -151.113236)
		(width 0.14224)
		(layer "In11.Cu")
		(net "M_M_MA<17>")
	)
	(segment
		(start 110.014004 -151.113236)
		(end 110.087156 -151.186388)
		(width 0.14224)
		(layer "In11.Cu")
		(net "M_M_MA<17>")
	)
	(segment
		(start 105.306622 -101.981254)
		(end 105.306622 -102.27056)
		(width 0.0889)
		(layer "In11.Cu")
		(net "M_M_MA<17>")
	)
	(segment
		(start 103.248968 -99.9236)
		(end 105.306622 -101.981254)
		(width 0.0889)
		(layer "In11.Cu")
		(net "M_M_MA<17>")
	)
	(segment
		(start 112.697768 -135.255)
		(end 112.519968 -135.4328)
		(width 0.14224)
		(layer "In11.Cu")
		(net "M_M_MA<17>")
	)
	(segment
		(start 112.575594 -126.29388)
		(end 112.575594 -129.255266)
		(width 0.14224)
		(layer "In11.Cu")
		(net "M_M_MA<17>")
	)
	(segment
		(start 110.087156 -153.842212)
		(end 109.991652 -153.937716)
		(width 0.14224)
		(layer "In11.Cu")
		(net "M_M_MA<17>")
	)
	(segment
		(start 112.697768 -130.4544)
		(end 112.519968 -130.6322)
		(width 0.14224)
		(layer "In11.Cu")
		(net "M_M_MA<17>")
	)
	(segment
		(start 110.087156 -151.186388)
		(end 110.087156 -153.842212)
		(width 0.14224)
		(layer "In11.Cu")
		(net "M_M_MA<17>")
	)
	(segment
		(start 105.306622 -102.27056)
		(end 105.306622 -119.024908)
		(width 0.14224)
		(layer "In11.Cu")
		(net "M_M_MA<17>")
	)
	(segment
		(start 112.697768 -131.8006)
		(end 112.588802 -131.909566)
		(width 0.14224)
		(layer "In11.Cu")
		(net "M_M_MA<17>")
	)
	(segment
		(start 110.55858 -149.437852)
		(end 110.55858 -150.018496)
		(width 0.14224)
		(layer "In11.Cu")
		(net "M_M_MA<17>")
	)
	(segment
		(start 111.71174 -147.511516)
		(end 110.449868 -148.773388)
		(width 0.14224)
		(layer "In11.Cu")
		(net "M_M_MA<17>")
	)
	(segment
		(start 112.519968 -131.1656)
		(end 112.697768 -131.3434)
		(width 0.14224)
		(layer "In11.Cu")
		(net "M_M_MA<17>")
	)
	(segment
		(start 112.519968 -130.6322)
		(end 112.519968 -131.1656)
		(width 0.14224)
		(layer "In11.Cu")
		(net "M_M_MA<17>")
	)
	(segment
		(start 112.697768 -134.8232)
		(end 112.697768 -135.255)
		(width 0.14224)
		(layer "In11.Cu")
		(net "M_M_MA<17>")
	)
	(segment
		(start 111.71174 -145.740628)
		(end 111.71174 -147.511516)
		(width 0.14224)
		(layer "In11.Cu")
		(net "M_M_MA<17>")
	)
	(segment
		(start 103.248968 -92.803472)
		(end 103.248968 -99.9236)
		(width 0.0889)
		(layer "In11.Cu")
		(net "M_M_MA<17>")
	)
	(segment
		(start 110.55858 -150.018496)
		(end 110.014004 -150.563072)
		(width 0.14224)
		(layer "In11.Cu")
		(net "M_M_MA<17>")
	)
	(segment
		(start 109.991652 -154.545284)
		(end 110.44936 -155.002992)
		(width 0.14224)
		(layer "In11.Cu")
		(net "M_M_MA<17>")
	)
	(segment
		(start 110.44936 -155.002992)
		(end 110.44936 -155.614878)
		(width 0.14224)
		(layer "In11.Cu")
		(net "M_M_MA<17>")
	)
	(segment
		(start 112.519968 -135.4328)
		(end 112.519968 -136.0424)
		(width 0.14224)
		(layer "In11.Cu")
		(net "M_M_MA<17>")
	)
	(segment
		(start 112.519968 -136.0424)
		(end 112.584738 -136.10717)
		(width 0.14224)
		(layer "In11.Cu")
		(net "M_M_MA<17>")
	)
	(segment
		(start 112.494568 -129.8956)
		(end 112.697768 -130.0988)
		(width 0.14224)
		(layer "In11.Cu")
		(net "M_M_MA<17>")
	)
	(segment
		(start 101.517704 -91.25204)
		(end 101.724968 -91.459304)
		(width 0.0889)
		(layer "In11.Cu")
		(net "M_M_MA<17>")
	)
	(segment
		(start 102.19944 -92.244672)
		(end 102.690168 -92.244672)
		(width 0.0889)
		(layer "In11.Cu")
		(net "M_M_MA<17>")
	)
	(segment
		(start 112.584738 -136.10717)
		(end 112.584738 -144.86763)
		(width 0.14224)
		(layer "In11.Cu")
		(net "M_M_MA<17>")
	)
	(segment
		(start 101.724968 -91.7702)
		(end 102.19944 -92.244672)
		(width 0.0889)
		(layer "In11.Cu")
		(net "M_M_MA<17>")
	)
	(segment
		(start 109.991652 -153.937716)
		(end 109.991652 -154.545284)
		(width 0.14224)
		(layer "In11.Cu")
		(net "M_M_MA<17>")
	)
	(segment
		(start 102.690168 -92.244672)
		(end 103.248968 -92.803472)
		(width 0.0889)
		(layer "In11.Cu")
		(net "M_M_MA<17>")
	)
	(segment
		(start 110.449868 -148.773388)
		(end 110.449868 -149.32914)
		(width 0.14224)
		(layer "In11.Cu")
		(net "M_M_MA<17>")
	)
	(segment
		(start 110.449868 -149.32914)
		(end 110.55858 -149.437852)
		(width 0.14224)
		(layer "In11.Cu")
		(net "M_M_MA<17>")
	)
	(segment
		(start 103.649526 -152.273)
		(end 103.649526 -154.251914)
		(width 0.1651)
		(layer "F.Cu")
		(net "M_M_MA<16>")
	)
	(segment
		(start 103.649526 -154.251914)
		(end 103.649272 -154.252168)
		(width 0.1651)
		(layer "F.Cu")
		(net "M_M_MA<16>")
	)
	(segment
		(start 96.938338 -92.24264)
		(end 96.366838 -92.24264)
		(width 0.1016)
		(layer "F.Cu")
		(net "M_M_MA<16>")
	)
	(via
		(at 103.649526 -150.785068)
		(size 0.4572)
		(drill 0.2032)
		(layers "F.Cu" "B.Cu")
		(net "M_M_MA<16>")
	)
	(via
		(at 96.366838 -92.24264)
		(size 0.508)
		(drill 0.254)
		(layers "F.Cu" "B.Cu")
		(net "M_M_MA<16>")
	)
	(via
		(at 103.649272 -154.252168)
		(size 0.508)
		(drill 0.254)
		(layers "F.Cu" "B.Cu")
		(net "M_M_MA<16>")
	)
	(segment
		(start 103.649526 -152.078436)
		(end 103.649526 -150.785068)
		(width 0.1651)
		(layer "B.Cu")
		(net "M_M_MA<16>")
	)
	(segment
		(start 102.410768 -131.318)
		(end 102.410768 -132.1816)
		(width 0.14224)
		(layer "In2.Cu")
		(net "M_M_MA<16>")
	)
	(segment
		(start 103.649526 -151.345392)
		(end 103.522526 -151.472392)
		(width 0.14224)
		(layer "In2.Cu")
		(net "M_M_MA<16>")
	)
	(segment
		(start 96.884998 -96.48952)
		(end 96.878648 -96.500188)
		(width 0.0889)
		(layer "In2.Cu")
		(net "M_M_MA<16>")
	)
	(segment
		(start 103.522526 -151.472392)
		(end 103.25989 -151.472392)
		(width 0.14224)
		(layer "In2.Cu")
		(net "M_M_MA<16>")
	)
	(segment
		(start 102.389686 -141.67231)
		(end 102.461568 -141.744192)
		(width 0.14224)
		(layer "In2.Cu")
		(net "M_M_MA<16>")
	)
	(segment
		(start 102.461568 -141.744192)
		(end 102.461568 -143.129)
		(width 0.14224)
		(layer "In2.Cu")
		(net "M_M_MA<16>")
	)
	(segment
		(start 104.485694 -152.325578)
		(end 104.677464 -152.517348)
		(width 0.14224)
		(layer "In2.Cu")
		(net "M_M_MA<16>")
	)
	(segment
		(start 96.878648 -98.481388)
		(end 96.873822 -98.490024)
		(width 0.0889)
		(layer "In2.Cu")
		(net "M_M_MA<16>")
	)
	(segment
		(start 102.389686 -139.526518)
		(end 102.389686 -141.67231)
		(width 0.14224)
		(layer "In2.Cu")
		(net "M_M_MA<16>")
	)
	(segment
		(start 96.878648 -96.500188)
		(end 96.873822 -96.508824)
		(width 0.0889)
		(layer "In2.Cu")
		(net "M_M_MA<16>")
	)
	(segment
		(start 102.309168 -129.205482)
		(end 102.309168 -129.8194)
		(width 0.14224)
		(layer "In2.Cu")
		(net "M_M_MA<16>")
	)
	(segment
		(start 102.382066 -143.208502)
		(end 102.382066 -144.935702)
		(width 0.14224)
		(layer "In2.Cu")
		(net "M_M_MA<16>")
	)
	(segment
		(start 102.512368 -130.0226)
		(end 102.512368 -130.4798)
		(width 0.14224)
		(layer "In2.Cu")
		(net "M_M_MA<16>")
	)
	(segment
		(start 97.051368 -99.526852)
		(end 97.051368 -100.882196)
		(width 0.0889)
		(layer "In2.Cu")
		(net "M_M_MA<16>")
	)
	(segment
		(start 103.320596 -153.285698)
		(end 103.320596 -153.923492)
		(width 0.14224)
		(layer "In2.Cu")
		(net "M_M_MA<16>")
	)
	(segment
		(start 102.309168 -131.2164)
		(end 102.410768 -131.318)
		(width 0.14224)
		(layer "In2.Cu")
		(net "M_M_MA<16>")
	)
	(segment
		(start 96.884998 -98.47072)
		(end 96.878648 -98.481388)
		(width 0.0889)
		(layer "In2.Cu")
		(net "M_M_MA<16>")
	)
	(segment
		(start 104.513634 -153.05913)
		(end 103.547164 -153.05913)
		(width 0.14224)
		(layer "In2.Cu")
		(net "M_M_MA<16>")
	)
	(segment
		(start 103.264716 -152.325578)
		(end 104.485694 -152.325578)
		(width 0.14224)
		(layer "In2.Cu")
		(net "M_M_MA<16>")
	)
	(segment
		(start 102.37089 -147.21205)
		(end 103.210614 -148.051774)
		(width 0.14224)
		(layer "In2.Cu")
		(net "M_M_MA<16>")
	)
	(segment
		(start 102.410768 -134.6962)
		(end 102.410768 -135.3058)
		(width 0.14224)
		(layer "In2.Cu")
		(net "M_M_MA<16>")
	)
	(segment
		(start 103.25989 -151.472392)
		(end 103.077772 -151.65451)
		(width 0.14224)
		(layer "In2.Cu")
		(net "M_M_MA<16>")
	)
	(segment
		(start 102.512368 -130.4798)
		(end 102.309168 -130.683)
		(width 0.14224)
		(layer "In2.Cu")
		(net "M_M_MA<16>")
	)
	(segment
		(start 96.878648 -94.518988)
		(end 96.873822 -94.527624)
		(width 0.0889)
		(layer "In2.Cu")
		(net "M_M_MA<16>")
	)
	(segment
		(start 102.367334 -135.349234)
		(end 102.367334 -139.504166)
		(width 0.14224)
		(layer "In2.Cu")
		(net "M_M_MA<16>")
	)
	(segment
		(start 102.309168 -130.683)
		(end 102.309168 -131.2164)
		(width 0.14224)
		(layer "In2.Cu")
		(net "M_M_MA<16>")
	)
	(segment
		(start 99.25304 -126.149354)
		(end 102.309168 -129.205482)
		(width 0.14224)
		(layer "In2.Cu")
		(net "M_M_MA<16>")
	)
	(segment
		(start 97.838768 -123.510802)
		(end 99.25304 -124.925074)
		(width 0.14224)
		(layer "In2.Cu")
		(net "M_M_MA<16>")
	)
	(segment
		(start 96.878648 -97.490788)
		(end 96.873822 -97.499424)
		(width 0.0889)
		(layer "In2.Cu")
		(net "M_M_MA<16>")
	)
	(segment
		(start 102.3747 -134.660132)
		(end 102.410768 -134.6962)
		(width 0.14224)
		(layer "In2.Cu")
		(net "M_M_MA<16>")
	)
	(segment
		(start 102.367334 -139.504166)
		(end 102.389686 -139.526518)
		(width 0.14224)
		(layer "In2.Cu")
		(net "M_M_MA<16>")
	)
	(segment
		(start 104.677464 -152.517348)
		(end 104.677464 -152.8953)
		(width 0.14224)
		(layer "In2.Cu")
		(net "M_M_MA<16>")
	)
	(segment
		(start 103.210614 -150.346156)
		(end 103.649526 -150.785068)
		(width 0.14224)
		(layer "In2.Cu")
		(net "M_M_MA<16>")
	)
	(segment
		(start 97.838768 -102.8954)
		(end 97.838768 -123.510802)
		(width 0.14224)
		(layer "In2.Cu")
		(net "M_M_MA<16>")
	)
	(segment
		(start 103.547164 -153.05913)
		(end 103.320596 -153.285698)
		(width 0.14224)
		(layer "In2.Cu")
		(net "M_M_MA<16>")
	)
	(segment
		(start 96.878648 -95.509588)
		(end 96.873822 -95.518224)
		(width 0.0889)
		(layer "In2.Cu")
		(net "M_M_MA<16>")
	)
	(segment
		(start 102.3747 -132.217668)
		(end 102.3747 -134.660132)
		(width 0.14224)
		(layer "In2.Cu")
		(net "M_M_MA<16>")
	)
	(segment
		(start 104.677464 -152.8953)
		(end 104.513634 -153.05913)
		(width 0.14224)
		(layer "In2.Cu")
		(net "M_M_MA<16>")
	)
	(segment
		(start 102.410768 -132.1816)
		(end 102.3747 -132.217668)
		(width 0.14224)
		(layer "In2.Cu")
		(net "M_M_MA<16>")
	)
	(segment
		(start 102.309168 -129.8194)
		(end 102.512368 -130.0226)
		(width 0.14224)
		(layer "In2.Cu")
		(net "M_M_MA<16>")
	)
	(segment
		(start 97.838768 -101.669596)
		(end 97.838768 -102.8954)
		(width 0.0889)
		(layer "In2.Cu")
		(net "M_M_MA<16>")
	)
	(segment
		(start 103.077772 -151.65451)
		(end 103.077772 -152.138634)
		(width 0.14224)
		(layer "In2.Cu")
		(net "M_M_MA<16>")
	)
	(segment
		(start 99.25304 -124.925074)
		(end 99.25304 -126.149354)
		(width 0.14224)
		(layer "In2.Cu")
		(net "M_M_MA<16>")
	)
	(segment
		(start 102.37089 -144.946878)
		(end 102.37089 -147.21205)
		(width 0.14224)
		(layer "In2.Cu")
		(net "M_M_MA<16>")
	)
	(segment
		(start 96.366838 -92.24264)
		(end 96.87179 -92.9259)
		(width 0.0889)
		(layer "In2.Cu")
		(net "M_M_MA<16>")
	)
	(segment
		(start 103.210614 -148.051774)
		(end 103.210614 -150.346156)
		(width 0.14224)
		(layer "In2.Cu")
		(net "M_M_MA<16>")
	)
	(segment
		(start 96.884998 -95.49892)
		(end 96.878648 -95.509588)
		(width 0.0889)
		(layer "In2.Cu")
		(net "M_M_MA<16>")
	)
	(segment
		(start 103.649526 -150.785068)
		(end 103.649526 -151.345392)
		(width 0.14224)
		(layer "In2.Cu")
		(net "M_M_MA<16>")
	)
	(segment
		(start 97.051368 -100.882196)
		(end 97.838768 -101.669596)
		(width 0.0889)
		(layer "In2.Cu")
		(net "M_M_MA<16>")
	)
	(segment
		(start 103.320596 -153.923492)
		(end 103.649272 -154.252168)
		(width 0.14224)
		(layer "In2.Cu")
		(net "M_M_MA<16>")
	)
	(segment
		(start 103.077772 -152.138634)
		(end 103.264716 -152.325578)
		(width 0.14224)
		(layer "In2.Cu")
		(net "M_M_MA<16>")
	)
	(segment
		(start 102.382066 -144.935702)
		(end 102.37089 -144.946878)
		(width 0.14224)
		(layer "In2.Cu")
		(net "M_M_MA<16>")
	)
	(segment
		(start 96.884998 -97.48012)
		(end 96.878648 -97.490788)
		(width 0.0889)
		(layer "In2.Cu")
		(net "M_M_MA<16>")
	)
	(segment
		(start 96.878648 -93.928438)
		(end 96.884998 -93.939106)
		(width 0.0889)
		(layer "In2.Cu")
		(net "M_M_MA<16>")
	)
	(segment
		(start 102.410768 -135.3058)
		(end 102.367334 -135.349234)
		(width 0.14224)
		(layer "In2.Cu")
		(net "M_M_MA<16>")
	)
	(segment
		(start 102.461568 -143.129)
		(end 102.382066 -143.208502)
		(width 0.14224)
		(layer "In2.Cu")
		(net "M_M_MA<16>")
	)
	(arc
		(start 96.878648 -98.881438)
		(mid 97.007455 -99.192787)
		(end 97.051368 -99.526852)
		(width 0.0889)
		(layer "In2.Cu")
		(net "M_M_MA<16>")
	)
	(arc
		(start 96.873822 -96.508824)
		(mid 96.825067 -96.705176)
		(end 96.878648 -96.900238)
		(width 0.0889)
		(layer "In2.Cu")
		(net "M_M_MA<16>")
	)
	(arc
		(start 96.878648 -96.900238)
		(mid 96.95787 -97.189356)
		(end 96.884998 -97.48012)
		(width 0.0889)
		(layer "In2.Cu")
		(net "M_M_MA<16>")
	)
	(arc
		(start 96.873822 -95.518224)
		(mid 96.825067 -95.714576)
		(end 96.878648 -95.909638)
		(width 0.0889)
		(layer "In2.Cu")
		(net "M_M_MA<16>")
	)
	(arc
		(start 96.884998 -93.939106)
		(mid 96.957796 -94.229869)
		(end 96.878648 -94.518988)
		(width 0.0889)
		(layer "In2.Cu")
		(net "M_M_MA<16>")
	)
	(arc
		(start 96.878648 -97.890838)
		(mid 96.95787 -98.179956)
		(end 96.884998 -98.47072)
		(width 0.0889)
		(layer "In2.Cu")
		(net "M_M_MA<16>")
	)
	(arc
		(start 96.878648 -95.909638)
		(mid 96.95787 -96.198756)
		(end 96.884998 -96.48952)
		(width 0.0889)
		(layer "In2.Cu")
		(net "M_M_MA<16>")
	)
	(arc
		(start 96.873822 -98.490024)
		(mid 96.825067 -98.686376)
		(end 96.878648 -98.881438)
		(width 0.0889)
		(layer "In2.Cu")
		(net "M_M_MA<16>")
	)
	(arc
		(start 96.878648 -93.528642)
		(mid 96.825149 -93.72854)
		(end 96.878648 -93.928438)
		(width 0.0889)
		(layer "In2.Cu")
		(net "M_M_MA<16>")
	)
	(arc
		(start 96.873822 -97.499424)
		(mid 96.825067 -97.695776)
		(end 96.878648 -97.890838)
		(width 0.0889)
		(layer "In2.Cu")
		(net "M_M_MA<16>")
	)
	(arc
		(start 96.878648 -94.919038)
		(mid 96.95787 -95.208156)
		(end 96.884998 -95.49892)
		(width 0.0889)
		(layer "In2.Cu")
		(net "M_M_MA<16>")
	)
	(arc
		(start 96.873822 -94.527624)
		(mid 96.825067 -94.723976)
		(end 96.878648 -94.919038)
		(width 0.0889)
		(layer "In2.Cu")
		(net "M_M_MA<16>")
	)
	(arc
		(start 96.87179 -92.9259)
		(mid 96.957798 -93.226322)
		(end 96.878648 -93.528642)
		(width 0.0889)
		(layer "In2.Cu")
		(net "M_M_MA<16>")
	)
	(segment
		(start 107.04957 -152.273)
		(end 107.04957 -154.251914)
		(width 0.1651)
		(layer "F.Cu")
		(net "M_M_MA<15>")
	)
	(segment
		(start 94.649798 -90.26144)
		(end 95.221298 -90.26144)
		(width 0.1016)
		(layer "F.Cu")
		(net "M_M_MA<15>")
	)
	(segment
		(start 107.04957 -154.251914)
		(end 107.049316 -154.252168)
		(width 0.1651)
		(layer "F.Cu")
		(net "M_M_MA<15>")
	)
	(via
		(at 94.649798 -90.26144)
		(size 0.508)
		(drill 0.254)
		(layers "F.Cu" "B.Cu")
		(net "M_M_MA<15>")
	)
	(via
		(at 107.049316 -154.252168)
		(size 0.508)
		(drill 0.254)
		(layers "F.Cu" "B.Cu")
		(net "M_M_MA<15>")
	)
	(via
		(at 107.049824 -150.788878)
		(size 0.4572)
		(drill 0.2032)
		(layers "F.Cu" "B.Cu")
		(net "M_M_MA<15>")
	)
	(segment
		(start 107.04957 -150.789132)
		(end 107.049824 -150.788878)
		(width 0.10795)
		(layer "B.Cu")
		(net "M_M_MA<15>")
	)
	(segment
		(start 107.04957 -152.078436)
		(end 107.04957 -150.789132)
		(width 0.10795)
		(layer "B.Cu")
		(net "M_M_MA<15>")
	)
	(segment
		(start 95.001334 -91.443302)
		(end 94.996508 -91.451938)
		(width 0.0889)
		(layer "In11.Cu")
		(net "M_M_MA<15>")
	)
	(segment
		(start 104.849168 -144.8054)
		(end 105.763314 -145.719546)
		(width 0.14224)
		(layer "In11.Cu")
		(net "M_M_MA<15>")
	)
	(segment
		(start 103.147368 -129.9972)
		(end 103.147368 -130.5306)
		(width 0.14224)
		(layer "In11.Cu")
		(net "M_M_MA<15>")
	)
	(segment
		(start 103.350568 -127.044196)
		(end 103.350568 -129.794)
		(width 0.14224)
		(layer "In11.Cu")
		(net "M_M_MA<15>")
	)
	(segment
		(start 107.049824 -150.788878)
		(end 107.049316 -150.789386)
		(width 0.14224)
		(layer "In11.Cu")
		(net "M_M_MA<15>")
	)
	(segment
		(start 107.118912 -152.59431)
		(end 107.387644 -152.863042)
		(width 0.14224)
		(layer "In11.Cu")
		(net "M_M_MA<15>")
	)
	(segment
		(start 95.855028 -99.471988)
		(end 96.200214 -100.068888)
		(width 0.0889)
		(layer "In11.Cu")
		(net "M_M_MA<15>")
	)
	(segment
		(start 107.049316 -150.789386)
		(end 107.049316 -151.518874)
		(width 0.14224)
		(layer "In11.Cu")
		(net "M_M_MA<15>")
	)
	(segment
		(start 104.849168 -144.3736)
		(end 104.849168 -144.8054)
		(width 0.14224)
		(layer "In11.Cu")
		(net "M_M_MA<15>")
	)
	(segment
		(start 105.589578 -152.59431)
		(end 107.118912 -152.59431)
		(width 0.14224)
		(layer "In11.Cu")
		(net "M_M_MA<15>")
	)
	(segment
		(start 103.210614 -136.842246)
		(end 103.401368 -137.033)
		(width 0.14224)
		(layer "In11.Cu")
		(net "M_M_MA<15>")
	)
	(segment
		(start 103.350568 -129.794)
		(end 103.147368 -129.9972)
		(width 0.14224)
		(layer "In11.Cu")
		(net "M_M_MA<15>")
	)
	(segment
		(start 104.091486 -139.450318)
		(end 104.137968 -139.4968)
		(width 0.14224)
		(layer "In11.Cu")
		(net "M_M_MA<15>")
	)
	(segment
		(start 103.147368 -131.2926)
		(end 103.147368 -131.8006)
		(width 0.14224)
		(layer "In11.Cu")
		(net "M_M_MA<15>")
	)
	(segment
		(start 104.137968 -140.1064)
		(end 104.942132 -140.910564)
		(width 0.14224)
		(layer "In11.Cu")
		(net "M_M_MA<15>")
	)
	(segment
		(start 105.367836 -152.372568)
		(end 105.589578 -152.59431)
		(width 0.14224)
		(layer "In11.Cu")
		(net "M_M_MA<15>")
	)
	(segment
		(start 103.147368 -131.8006)
		(end 103.210614 -131.863846)
		(width 0.14224)
		(layer "In11.Cu")
		(net "M_M_MA<15>")
	)
	(segment
		(start 94.649798 -90.26144)
		(end 94.957138 -90.969846)
		(width 0.0889)
		(layer "In11.Cu")
		(net "M_M_MA<15>")
	)
	(segment
		(start 95.486728 -96.300036)
		(end 95.519494 -96.300036)
		(width 0.0889)
		(layer "In11.Cu")
		(net "M_M_MA<15>")
	)
	(segment
		(start 98.641916 -122.335544)
		(end 103.350568 -127.044196)
		(width 0.14224)
		(layer "In11.Cu")
		(net "M_M_MA<15>")
	)
	(segment
		(start 105.367836 -151.995632)
		(end 105.367836 -152.372568)
		(width 0.14224)
		(layer "In11.Cu")
		(net "M_M_MA<15>")
	)
	(segment
		(start 105.763314 -149.502368)
		(end 107.049824 -150.788878)
		(width 0.14224)
		(layer "In11.Cu")
		(net "M_M_MA<15>")
	)
	(segment
		(start 104.091486 -138.723878)
		(end 104.091486 -139.450318)
		(width 0.14224)
		(layer "In11.Cu")
		(net "M_M_MA<15>")
	)
	(segment
		(start 103.210614 -131.863846)
		(end 103.210614 -136.842246)
		(width 0.14224)
		(layer "In11.Cu")
		(net "M_M_MA<15>")
	)
	(segment
		(start 103.299768 -131.1402)
		(end 103.147368 -131.2926)
		(width 0.14224)
		(layer "In11.Cu")
		(net "M_M_MA<15>")
	)
	(segment
		(start 107.387644 -153.91384)
		(end 107.049316 -154.252168)
		(width 0.14224)
		(layer "In11.Cu")
		(net "M_M_MA<15>")
	)
	(segment
		(start 96.40062 -100.269294)
		(end 97.699068 -101.567742)
		(width 0.14224)
		(layer "In11.Cu")
		(net "M_M_MA<15>")
	)
	(segment
		(start 98.641916 -104.104948)
		(end 98.641916 -122.335544)
		(width 0.14224)
		(layer "In11.Cu")
		(net "M_M_MA<15>")
	)
	(segment
		(start 107.387644 -152.863042)
		(end 107.387644 -153.91384)
		(width 0.14224)
		(layer "In11.Cu")
		(net "M_M_MA<15>")
	)
	(segment
		(start 103.299768 -130.683)
		(end 103.299768 -131.1402)
		(width 0.14224)
		(layer "In11.Cu")
		(net "M_M_MA<15>")
	)
	(segment
		(start 103.401368 -138.03376)
		(end 104.091486 -138.723878)
		(width 0.14224)
		(layer "In11.Cu")
		(net "M_M_MA<15>")
	)
	(segment
		(start 94.996508 -91.451938)
		(end 94.990158 -91.462606)
		(width 0.0889)
		(layer "In11.Cu")
		(net "M_M_MA<15>")
	)
	(segment
		(start 97.699068 -101.567742)
		(end 97.699068 -103.1621)
		(width 0.14224)
		(layer "In11.Cu")
		(net "M_M_MA<15>")
	)
	(segment
		(start 105.763314 -145.719546)
		(end 105.763314 -149.502368)
		(width 0.14224)
		(layer "In11.Cu")
		(net "M_M_MA<15>")
	)
	(segment
		(start 97.699068 -103.1621)
		(end 98.641916 -104.104948)
		(width 0.14224)
		(layer "In11.Cu")
		(net "M_M_MA<15>")
	)
	(segment
		(start 104.942132 -140.910564)
		(end 104.942132 -144.280636)
		(width 0.14224)
		(layer "In11.Cu")
		(net "M_M_MA<15>")
	)
	(segment
		(start 96.200214 -100.068888)
		(end 96.40062 -100.269294)
		(width 0.0889)
		(layer "In11.Cu")
		(net "M_M_MA<15>")
	)
	(segment
		(start 106.78668 -151.78151)
		(end 105.581958 -151.78151)
		(width 0.14224)
		(layer "In11.Cu")
		(net "M_M_MA<15>")
	)
	(segment
		(start 103.401368 -137.033)
		(end 103.401368 -138.03376)
		(width 0.14224)
		(layer "In11.Cu")
		(net "M_M_MA<15>")
	)
	(segment
		(start 103.147368 -130.5306)
		(end 103.299768 -130.683)
		(width 0.14224)
		(layer "In11.Cu")
		(net "M_M_MA<15>")
	)
	(segment
		(start 104.942132 -144.280636)
		(end 104.849168 -144.3736)
		(width 0.14224)
		(layer "In11.Cu")
		(net "M_M_MA<15>")
	)
	(segment
		(start 105.581958 -151.78151)
		(end 105.367836 -151.995632)
		(width 0.14224)
		(layer "In11.Cu")
		(net "M_M_MA<15>")
	)
	(segment
		(start 104.137968 -139.4968)
		(end 104.137968 -140.1064)
		(width 0.14224)
		(layer "In11.Cu")
		(net "M_M_MA<15>")
	)
	(segment
		(start 107.049316 -151.518874)
		(end 106.78668 -151.78151)
		(width 0.14224)
		(layer "In11.Cu")
		(net "M_M_MA<15>")
	)
	(arc
		(start 95.855028 -97.490788)
		(mid 95.908527 -97.690686)
		(end 95.855028 -97.890584)
		(width 0.0889)
		(layer "In11.Cu")
		(net "M_M_MA<15>")
	)
	(arc
		(start 95.855028 -97.890584)
		(mid 95.775897 -98.185986)
		(end 95.855028 -98.481388)
		(width 0.0889)
		(layer "In11.Cu")
		(net "M_M_MA<15>")
	)
	(arc
		(start 95.855028 -96.899984)
		(mid 95.775897 -97.195386)
		(end 95.855028 -97.490788)
		(width 0.0889)
		(layer "In11.Cu")
		(net "M_M_MA<15>")
	)
	(arc
		(start 95.855028 -98.881184)
		(mid 95.775897 -99.176586)
		(end 95.855028 -99.471988)
		(width 0.0889)
		(layer "In11.Cu")
		(net "M_M_MA<15>")
	)
	(arc
		(start 95.855028 -98.481388)
		(mid 95.908527 -98.681286)
		(end 95.855028 -98.881184)
		(width 0.0889)
		(layer "In11.Cu")
		(net "M_M_MA<15>")
	)
	(arc
		(start 94.996508 -92.042488)
		(mid 95.050007 -92.242386)
		(end 94.996508 -92.442284)
		(width 0.0889)
		(layer "In11.Cu")
		(net "M_M_MA<15>")
	)
	(arc
		(start 94.996508 -93.033088)
		(mid 95.050007 -93.232986)
		(end 94.996508 -93.432884)
		(width 0.0889)
		(layer "In11.Cu")
		(net "M_M_MA<15>")
	)
	(arc
		(start 94.996508 -91.051888)
		(mid 95.049978 -91.246951)
		(end 95.001334 -91.443302)
		(width 0.0889)
		(layer "In11.Cu")
		(net "M_M_MA<15>")
	)
	(arc
		(start 94.996508 -95.414084)
		(mid 94.991254 -95.995592)
		(end 95.486728 -96.300036)
		(width 0.0889)
		(layer "In11.Cu")
		(net "M_M_MA<15>")
	)
	(arc
		(start 94.996508 -92.442284)
		(mid 94.917377 -92.737686)
		(end 94.996508 -93.033088)
		(width 0.0889)
		(layer "In11.Cu")
		(net "M_M_MA<15>")
	)
	(arc
		(start 94.996508 -95.014288)
		(mid 95.050007 -95.214186)
		(end 94.996508 -95.414084)
		(width 0.0889)
		(layer "In11.Cu")
		(net "M_M_MA<15>")
	)
	(arc
		(start 94.990158 -91.462606)
		(mid 94.91736 -91.753369)
		(end 94.996508 -92.042488)
		(width 0.0889)
		(layer "In11.Cu")
		(net "M_M_MA<15>")
	)
	(arc
		(start 95.519494 -96.300036)
		(mid 95.857609 -96.504738)
		(end 95.855028 -96.899984)
		(width 0.0889)
		(layer "In11.Cu")
		(net "M_M_MA<15>")
	)
	(arc
		(start 94.996508 -93.432884)
		(mid 94.917377 -93.728286)
		(end 94.996508 -94.023688)
		(width 0.0889)
		(layer "In11.Cu")
		(net "M_M_MA<15>")
	)
	(arc
		(start 94.996508 -94.423484)
		(mid 94.917377 -94.718886)
		(end 94.996508 -95.014288)
		(width 0.0889)
		(layer "In11.Cu")
		(net "M_M_MA<15>")
	)
	(arc
		(start 94.957138 -90.969846)
		(mid 94.975239 -91.011627)
		(end 94.996508 -91.051888)
		(width 0.0889)
		(layer "In11.Cu")
		(net "M_M_MA<15>")
	)
	(arc
		(start 94.996508 -94.023688)
		(mid 95.050007 -94.223586)
		(end 94.996508 -94.423484)
		(width 0.0889)
		(layer "In11.Cu")
		(net "M_M_MA<15>")
	)
	(segment
		(start 105.349548 -155.615132)
		(end 105.349294 -155.614878)
		(width 0.1651)
		(layer "F.Cu")
		(net "M_M_MA<14>")
	)
	(segment
		(start 98.655378 -93.23324)
		(end 98.083878 -93.23324)
		(width 0.1016)
		(layer "F.Cu")
		(net "M_M_MA<14>")
	)
	(segment
		(start 105.349548 -156.87294)
		(end 105.349548 -155.615132)
		(width 0.1651)
		(layer "F.Cu")
		(net "M_M_MA<14>")
	)
	(via
		(at 105.349802 -148.773388)
		(size 0.4572)
		(drill 0.2032)
		(layers "F.Cu" "B.Cu")
		(net "M_M_MA<14>")
	)
	(via
		(at 98.083878 -93.23324)
		(size 0.508)
		(drill 0.254)
		(layers "F.Cu" "B.Cu")
		(net "M_M_MA<14>")
	)
	(via
		(at 105.349294 -155.614878)
		(size 0.508)
		(drill 0.254)
		(layers "F.Cu" "B.Cu")
		(net "M_M_MA<14>")
	)
	(segment
		(start 105.349548 -148.773134)
		(end 105.349802 -148.773388)
		(width 0.1651)
		(layer "B.Cu")
		(net "M_M_MA<14>")
	)
	(segment
		(start 105.349548 -147.478496)
		(end 105.349548 -148.773134)
		(width 0.1651)
		(layer "B.Cu")
		(net "M_M_MA<14>")
	)
	(segment
		(start 102.12959 -126.366778)
		(end 102.12959 -126.66091)
		(width 0.14224)
		(layer "In2.Cu")
		(net "M_M_MA<14>")
	)
	(segment
		(start 104.880156 -129.940812)
		(end 104.880156 -130.536188)
		(width 0.14224)
		(layer "In2.Cu")
		(net "M_M_MA<14>")
	)
	(segment
		(start 105.541318 -142.508732)
		(end 105.37571 -142.67434)
		(width 0.14224)
		(layer "In2.Cu")
		(net "M_M_MA<14>")
	)
	(segment
		(start 105.82783 -148.210524)
		(end 105.504742 -148.210524)
		(width 0.14224)
		(layer "In2.Cu")
		(net "M_M_MA<14>")
	)
	(segment
		(start 105.349802 -148.773388)
		(end 105.765092 -149.188678)
		(width 0.14224)
		(layer "In2.Cu")
		(net "M_M_MA<14>")
	)
	(segment
		(start 99.379532 -102.84079)
		(end 99.379532 -103.023924)
		(width 0.0889)
		(layer "In2.Cu")
		(net "M_M_MA<14>")
	)
	(segment
		(start 104.912414 -133.947154)
		(end 104.912414 -137.020046)
		(width 0.14224)
		(layer "In2.Cu")
		(net "M_M_MA<14>")
	)
	(segment
		(start 98.430588 -98.386138)
		(end 98.424238 -98.396806)
		(width 0.0889)
		(layer "In2.Cu")
		(net "M_M_MA<14>")
	)
	(segment
		(start 105.283 -147.547584)
		(end 105.841038 -147.547584)
		(width 0.14224)
		(layer "In2.Cu")
		(net "M_M_MA<14>")
	)
	(segment
		(start 98.41357 -93.994478)
		(end 98.430588 -94.023688)
		(width 0.0889)
		(layer "In2.Cu")
		(net "M_M_MA<14>")
	)
	(segment
		(start 99.083368 -102.544626)
		(end 99.379532 -102.84079)
		(width 0.0889)
		(layer "In2.Cu")
		(net "M_M_MA<14>")
	)
	(segment
		(start 98.435414 -98.377502)
		(end 98.430588 -98.386138)
		(width 0.0889)
		(layer "In2.Cu")
		(net "M_M_MA<14>")
	)
	(segment
		(start 98.430588 -95.414338)
		(end 98.424238 -95.425006)
		(width 0.0889)
		(layer "In2.Cu")
		(net "M_M_MA<14>")
	)
	(segment
		(start 104.91978 -147.184364)
		(end 105.283 -147.547584)
		(width 0.14224)
		(layer "In2.Cu")
		(net "M_M_MA<14>")
	)
	(segment
		(start 98.083878 -93.23324)
		(end 98.41357 -93.994478)
		(width 0.0889)
		(layer "In2.Cu")
		(net "M_M_MA<14>")
	)
	(segment
		(start 104.9274 -144.893792)
		(end 104.91978 -144.901412)
		(width 0.14224)
		(layer "In2.Cu")
		(net "M_M_MA<14>")
	)
	(segment
		(start 98.435414 -95.405702)
		(end 98.430588 -95.414338)
		(width 0.0889)
		(layer "In2.Cu")
		(net "M_M_MA<14>")
	)
	(segment
		(start 98.430588 -96.404938)
		(end 98.424238 -96.415606)
		(width 0.0889)
		(layer "In2.Cu")
		(net "M_M_MA<14>")
	)
	(segment
		(start 103.205026 -126.731776)
		(end 103.401368 -126.928118)
		(width 0.14224)
		(layer "In2.Cu")
		(net "M_M_MA<14>")
	)
	(segment
		(start 104.896158 -131.22021)
		(end 104.896158 -131.92379)
		(width 0.14224)
		(layer "In2.Cu")
		(net "M_M_MA<14>")
	)
	(segment
		(start 105.742232 -151.684736)
		(end 105.742232 -153.801064)
		(width 0.14224)
		(layer "In2.Cu")
		(net "M_M_MA<14>")
	)
	(segment
		(start 105.504742 -148.210524)
		(end 105.349802 -148.365464)
		(width 0.14224)
		(layer "In2.Cu")
		(net "M_M_MA<14>")
	)
	(segment
		(start 105.989374 -147.69592)
		(end 105.989374 -148.04898)
		(width 0.14224)
		(layer "In2.Cu")
		(net "M_M_MA<14>")
	)
	(segment
		(start 104.940862 -129.36347)
		(end 104.940862 -129.880106)
		(width 0.14224)
		(layer "In2.Cu")
		(net "M_M_MA<14>")
	)
	(segment
		(start 104.9274 -142.867634)
		(end 104.9274 -144.893792)
		(width 0.14224)
		(layer "In2.Cu")
		(net "M_M_MA<14>")
	)
	(segment
		(start 98.216212 -99.673156)
		(end 98.216212 -100.351844)
		(width 0.0889)
		(layer "In2.Cu")
		(net "M_M_MA<14>")
	)
	(segment
		(start 105.380282 -141.86154)
		(end 105.541318 -142.022576)
		(width 0.14224)
		(layer "In2.Cu")
		(net "M_M_MA<14>")
	)
	(segment
		(start 103.401368 -127.823976)
		(end 104.940862 -129.36347)
		(width 0.14224)
		(layer "In2.Cu")
		(net "M_M_MA<14>")
	)
	(segment
		(start 104.934766 -140.115798)
		(end 104.938322 -140.119354)
		(width 0.14224)
		(layer "In2.Cu")
		(net "M_M_MA<14>")
	)
	(segment
		(start 104.971342 -131.145026)
		(end 104.896158 -131.22021)
		(width 0.14224)
		(layer "In2.Cu")
		(net "M_M_MA<14>")
	)
	(segment
		(start 102.346252 -125.862588)
		(end 102.346252 -126.150116)
		(width 0.14224)
		(layer "In2.Cu")
		(net "M_M_MA<14>")
	)
	(segment
		(start 104.940862 -129.880106)
		(end 104.880156 -129.940812)
		(width 0.14224)
		(layer "In2.Cu")
		(net "M_M_MA<14>")
	)
	(segment
		(start 98.216212 -100.351844)
		(end 99.083368 -101.219)
		(width 0.0889)
		(layer "In2.Cu")
		(net "M_M_MA<14>")
	)
	(segment
		(start 104.934766 -137.042398)
		(end 104.934766 -140.115798)
		(width 0.14224)
		(layer "In2.Cu")
		(net "M_M_MA<14>")
	)
	(segment
		(start 102.697788 -126.948184)
		(end 102.914196 -126.731776)
		(width 0.14224)
		(layer "In2.Cu")
		(net "M_M_MA<14>")
	)
	(segment
		(start 102.416864 -126.948184)
		(end 102.697788 -126.948184)
		(width 0.14224)
		(layer "In2.Cu")
		(net "M_M_MA<14>")
	)
	(segment
		(start 99.379532 -103.023924)
		(end 99.379532 -122.895868)
		(width 0.14224)
		(layer "In2.Cu")
		(net "M_M_MA<14>")
	)
	(segment
		(start 105.765092 -151.661876)
		(end 105.742232 -151.684736)
		(width 0.14224)
		(layer "In2.Cu")
		(net "M_M_MA<14>")
	)
	(segment
		(start 104.896158 -131.92379)
		(end 105.188004 -132.215636)
		(width 0.14224)
		(layer "In2.Cu")
		(net "M_M_MA<14>")
	)
	(segment
		(start 105.349294 -154.955494)
		(end 105.349294 -155.614878)
		(width 0.14224)
		(layer "In2.Cu")
		(net "M_M_MA<14>")
	)
	(segment
		(start 98.435414 -96.396302)
		(end 98.430588 -96.404938)
		(width 0.0889)
		(layer "In2.Cu")
		(net "M_M_MA<14>")
	)
	(segment
		(start 104.91978 -144.901412)
		(end 104.91978 -147.184364)
		(width 0.14224)
		(layer "In2.Cu")
		(net "M_M_MA<14>")
	)
	(segment
		(start 105.989374 -148.04898)
		(end 105.82783 -148.210524)
		(width 0.14224)
		(layer "In2.Cu")
		(net "M_M_MA<14>")
	)
	(segment
		(start 98.372168 -99.5172)
		(end 98.216212 -99.673156)
		(width 0.0889)
		(layer "In2.Cu")
		(net "M_M_MA<14>")
	)
	(segment
		(start 102.346252 -126.150116)
		(end 102.12959 -126.366778)
		(width 0.14224)
		(layer "In2.Cu")
		(net "M_M_MA<14>")
	)
	(segment
		(start 105.541318 -142.022576)
		(end 105.541318 -142.508732)
		(width 0.14224)
		(layer "In2.Cu")
		(net "M_M_MA<14>")
	)
	(segment
		(start 98.430588 -97.395538)
		(end 98.424238 -97.406206)
		(width 0.0889)
		(layer "In2.Cu")
		(net "M_M_MA<14>")
	)
	(segment
		(start 105.742232 -153.801064)
		(end 105.806494 -153.865326)
		(width 0.14224)
		(layer "In2.Cu")
		(net "M_M_MA<14>")
	)
	(segment
		(start 105.188004 -132.215636)
		(end 105.188004 -133.671564)
		(width 0.14224)
		(layer "In2.Cu")
		(net "M_M_MA<14>")
	)
	(segment
		(start 105.143046 -141.86154)
		(end 105.380282 -141.86154)
		(width 0.14224)
		(layer "In2.Cu")
		(net "M_M_MA<14>")
	)
	(segment
		(start 104.912414 -137.020046)
		(end 104.934766 -137.042398)
		(width 0.14224)
		(layer "In2.Cu")
		(net "M_M_MA<14>")
	)
	(segment
		(start 105.37571 -142.67434)
		(end 105.120694 -142.67434)
		(width 0.14224)
		(layer "In2.Cu")
		(net "M_M_MA<14>")
	)
	(segment
		(start 104.880156 -130.536188)
		(end 104.971342 -130.627374)
		(width 0.14224)
		(layer "In2.Cu")
		(net "M_M_MA<14>")
	)
	(segment
		(start 98.435414 -97.386902)
		(end 98.430588 -97.395538)
		(width 0.0889)
		(layer "In2.Cu")
		(net "M_M_MA<14>")
	)
	(segment
		(start 105.806494 -153.865326)
		(end 105.806494 -154.498294)
		(width 0.14224)
		(layer "In2.Cu")
		(net "M_M_MA<14>")
	)
	(segment
		(start 104.938322 -140.119354)
		(end 104.938322 -141.656816)
		(width 0.14224)
		(layer "In2.Cu")
		(net "M_M_MA<14>")
	)
	(segment
		(start 99.379532 -122.895868)
		(end 102.346252 -125.862588)
		(width 0.14224)
		(layer "In2.Cu")
		(net "M_M_MA<14>")
	)
	(segment
		(start 105.120694 -142.67434)
		(end 104.9274 -142.867634)
		(width 0.14224)
		(layer "In2.Cu")
		(net "M_M_MA<14>")
	)
	(segment
		(start 99.083368 -101.219)
		(end 99.083368 -102.544626)
		(width 0.0889)
		(layer "In2.Cu")
		(net "M_M_MA<14>")
	)
	(segment
		(start 104.938322 -141.656816)
		(end 105.143046 -141.86154)
		(width 0.14224)
		(layer "In2.Cu")
		(net "M_M_MA<14>")
	)
	(segment
		(start 102.914196 -126.731776)
		(end 103.205026 -126.731776)
		(width 0.14224)
		(layer "In2.Cu")
		(net "M_M_MA<14>")
	)
	(segment
		(start 102.12959 -126.66091)
		(end 102.416864 -126.948184)
		(width 0.14224)
		(layer "In2.Cu")
		(net "M_M_MA<14>")
	)
	(segment
		(start 105.841038 -147.547584)
		(end 105.989374 -147.69592)
		(width 0.14224)
		(layer "In2.Cu")
		(net "M_M_MA<14>")
	)
	(segment
		(start 105.806494 -154.498294)
		(end 105.349294 -154.955494)
		(width 0.14224)
		(layer "In2.Cu")
		(net "M_M_MA<14>")
	)
	(segment
		(start 105.349802 -148.365464)
		(end 105.349802 -148.773388)
		(width 0.14224)
		(layer "In2.Cu")
		(net "M_M_MA<14>")
	)
	(segment
		(start 105.188004 -133.671564)
		(end 104.912414 -133.947154)
		(width 0.14224)
		(layer "In2.Cu")
		(net "M_M_MA<14>")
	)
	(segment
		(start 103.401368 -126.928118)
		(end 103.401368 -127.823976)
		(width 0.14224)
		(layer "In2.Cu")
		(net "M_M_MA<14>")
	)
	(segment
		(start 105.765092 -149.188678)
		(end 105.765092 -151.661876)
		(width 0.14224)
		(layer "In2.Cu")
		(net "M_M_MA<14>")
	)
	(segment
		(start 104.971342 -130.627374)
		(end 104.971342 -131.145026)
		(width 0.14224)
		(layer "In2.Cu")
		(net "M_M_MA<14>")
	)
	(arc
		(start 98.430588 -94.423484)
		(mid 98.351457 -94.718886)
		(end 98.430588 -95.014288)
		(width 0.0889)
		(layer "In2.Cu")
		(net "M_M_MA<14>")
	)
	(arc
		(start 98.424238 -97.406206)
		(mid 98.35144 -97.696969)
		(end 98.430588 -97.986088)
		(width 0.0889)
		(layer "In2.Cu")
		(net "M_M_MA<14>")
	)
	(arc
		(start 98.430588 -95.014288)
		(mid 98.484058 -95.209351)
		(end 98.435414 -95.405702)
		(width 0.0889)
		(layer "In2.Cu")
		(net "M_M_MA<14>")
	)
	(arc
		(start 98.424238 -98.396806)
		(mid 98.35144 -98.687569)
		(end 98.430588 -98.976688)
		(width 0.0889)
		(layer "In2.Cu")
		(net "M_M_MA<14>")
	)
	(arc
		(start 98.430588 -94.023688)
		(mid 98.484087 -94.223586)
		(end 98.430588 -94.423484)
		(width 0.0889)
		(layer "In2.Cu")
		(net "M_M_MA<14>")
	)
	(arc
		(start 98.430588 -97.986088)
		(mid 98.484058 -98.181151)
		(end 98.435414 -98.377502)
		(width 0.0889)
		(layer "In2.Cu")
		(net "M_M_MA<14>")
	)
	(arc
		(start 98.424238 -95.425006)
		(mid 98.35144 -95.715769)
		(end 98.430588 -96.004888)
		(width 0.0889)
		(layer "In2.Cu")
		(net "M_M_MA<14>")
	)
	(arc
		(start 98.424238 -96.415606)
		(mid 98.35144 -96.706369)
		(end 98.430588 -96.995488)
		(width 0.0889)
		(layer "In2.Cu")
		(net "M_M_MA<14>")
	)
	(arc
		(start 98.430588 -96.995488)
		(mid 98.484058 -97.190551)
		(end 98.435414 -97.386902)
		(width 0.0889)
		(layer "In2.Cu")
		(net "M_M_MA<14>")
	)
	(arc
		(start 98.430588 -96.004888)
		(mid 98.484058 -96.199951)
		(end 98.435414 -96.396302)
		(width 0.0889)
		(layer "In2.Cu")
		(net "M_M_MA<14>")
	)
	(arc
		(start 98.430588 -98.976688)
		(mid 98.48969 -99.256502)
		(end 98.372168 -99.5172)
		(width 0.0889)
		(layer "In2.Cu")
		(net "M_M_MA<14>")
	)
	(segment
		(start 108.749338 -156.87294)
		(end 108.749338 -155.614878)
		(width 0.1651)
		(layer "F.Cu")
		(net "M_M_MA<13>")
	)
	(segment
		(start 96.079818 -90.756486)
		(end 95.508318 -90.756486)
		(width 0.1016)
		(layer "F.Cu")
		(net "M_M_MA<13>")
	)
	(via
		(at 108.749846 -148.773388)
		(size 0.4572)
		(drill 0.2032)
		(layers "F.Cu" "B.Cu")
		(net "M_M_MA<13>")
	)
	(via
		(at 95.508318 -90.756486)
		(size 0.508)
		(drill 0.254)
		(layers "F.Cu" "B.Cu")
		(net "M_M_MA<13>")
	)
	(via
		(at 108.749338 -155.614878)
		(size 0.508)
		(drill 0.254)
		(layers "F.Cu" "B.Cu")
		(net "M_M_MA<13>")
	)
	(segment
		(start 108.749338 -148.77288)
		(end 108.749846 -148.773388)
		(width 0.1651)
		(layer "B.Cu")
		(net "M_M_MA<13>")
	)
	(segment
		(start 108.749338 -147.478496)
		(end 108.749338 -148.77288)
		(width 0.1651)
		(layer "B.Cu")
		(net "M_M_MA<13>")
	)
	(segment
		(start 108.903008 -147.397978)
		(end 108.903008 -147.696174)
		(width 0.14224)
		(layer "In11.Cu")
		(net "M_M_MA<13>")
	)
	(segment
		(start 107.46486 -146.315938)
		(end 106.988102 -146.792696)
		(width 0.14224)
		(layer "In11.Cu")
		(net "M_M_MA<13>")
	)
	(segment
		(start 107.396026 -147.51558)
		(end 107.740704 -147.51558)
		(width 0.14224)
		(layer "In11.Cu")
		(net "M_M_MA<13>")
	)
	(segment
		(start 108.23194 -147.024344)
		(end 108.529374 -147.024344)
		(width 0.14224)
		(layer "In11.Cu")
		(net "M_M_MA<13>")
	)
	(segment
		(start 104.9274 -138.863832)
		(end 104.9274 -140.108432)
		(width 0.14224)
		(layer "In11.Cu")
		(net "M_M_MA<13>")
	)
	(segment
		(start 99.149916 -103.927148)
		(end 99.149916 -122.124978)
		(width 0.14224)
		(layer "In11.Cu")
		(net "M_M_MA<13>")
	)
	(segment
		(start 104.137968 -134.7978)
		(end 104.137968 -136.010396)
		(width 0.14224)
		(layer "In11.Cu")
		(net "M_M_MA<13>")
	)
	(segment
		(start 108.887768 -151.4348)
		(end 108.887768 -153.6192)
		(width 0.14224)
		(layer "In11.Cu")
		(net "M_M_MA<13>")
	)
	(segment
		(start 108.529374 -147.024344)
		(end 108.903008 -147.397978)
		(width 0.14224)
		(layer "In11.Cu")
		(net "M_M_MA<13>")
	)
	(segment
		(start 109.222794 -153.954226)
		(end 109.222794 -154.528774)
		(width 0.14224)
		(layer "In11.Cu")
		(net "M_M_MA<13>")
	)
	(segment
		(start 104.08412 -131.213352)
		(end 104.08412 -134.743952)
		(width 0.14224)
		(layer "In11.Cu")
		(net "M_M_MA<13>")
	)
	(segment
		(start 107.15498 -145.4785)
		(end 107.46486 -145.78838)
		(width 0.14224)
		(layer "In11.Cu")
		(net "M_M_MA<13>")
	)
	(segment
		(start 105.75925 -140.940282)
		(end 105.75925 -144.68348)
		(width 0.14224)
		(layer "In11.Cu")
		(net "M_M_MA<13>")
	)
	(segment
		(start 109.185456 -151.137112)
		(end 108.887768 -151.4348)
		(width 0.14224)
		(layer "In11.Cu")
		(net "M_M_MA<13>")
	)
	(segment
		(start 108.749338 -155.00223)
		(end 108.749338 -155.614878)
		(width 0.14224)
		(layer "In11.Cu")
		(net "M_M_MA<13>")
	)
	(segment
		(start 104.010968 -130.683)
		(end 104.010968 -131.1402)
		(width 0.14224)
		(layer "In11.Cu")
		(net "M_M_MA<13>")
	)
	(segment
		(start 106.988102 -147.107656)
		(end 107.396026 -147.51558)
		(width 0.14224)
		(layer "In11.Cu")
		(net "M_M_MA<13>")
	)
	(segment
		(start 95.968058 -92.075762)
		(end 95.967042 -92.076778)
		(width 0.0889)
		(layer "In11.Cu")
		(net "M_M_MA<13>")
	)
	(segment
		(start 104.083866 -138.020298)
		(end 104.9274 -138.863832)
		(width 0.14224)
		(layer "In11.Cu")
		(net "M_M_MA<13>")
	)
	(segment
		(start 108.903008 -147.696174)
		(end 108.447332 -148.15185)
		(width 0.14224)
		(layer "In11.Cu")
		(net "M_M_MA<13>")
	)
	(segment
		(start 107.46486 -145.78838)
		(end 107.46486 -146.315938)
		(width 0.14224)
		(layer "In11.Cu")
		(net "M_M_MA<13>")
	)
	(segment
		(start 96.020128 -99.376738)
		(end 96.15297 -99.599242)
		(width 0.0889)
		(layer "In11.Cu")
		(net "M_M_MA<13>")
	)
	(segment
		(start 96.015302 -96.396302)
		(end 96.020128 -96.404938)
		(width 0.0889)
		(layer "In11.Cu")
		(net "M_M_MA<13>")
	)
	(segment
		(start 108.749846 -148.773388)
		(end 108.749846 -150.026878)
		(width 0.14224)
		(layer "In11.Cu")
		(net "M_M_MA<13>")
	)
	(segment
		(start 106.55427 -145.4785)
		(end 107.15498 -145.4785)
		(width 0.14224)
		(layer "In11.Cu")
		(net "M_M_MA<13>")
	)
	(segment
		(start 108.887768 -153.6192)
		(end 109.222794 -153.954226)
		(width 0.14224)
		(layer "In11.Cu")
		(net "M_M_MA<13>")
	)
	(segment
		(start 96.015302 -99.368102)
		(end 96.020128 -99.376738)
		(width 0.0889)
		(layer "In11.Cu")
		(net "M_M_MA<13>")
	)
	(segment
		(start 104.08412 -134.743952)
		(end 104.137968 -134.7978)
		(width 0.14224)
		(layer "In11.Cu")
		(net "M_M_MA<13>")
	)
	(segment
		(start 95.967042 -92.076778)
		(end 95.967042 -96.206564)
		(width 0.0889)
		(layer "In11.Cu")
		(net "M_M_MA<13>")
	)
	(segment
		(start 106.988102 -146.792696)
		(end 106.988102 -147.107656)
		(width 0.14224)
		(layer "In11.Cu")
		(net "M_M_MA<13>")
	)
	(segment
		(start 96.015302 -97.386902)
		(end 96.020128 -97.395538)
		(width 0.0889)
		(layer "In11.Cu")
		(net "M_M_MA<13>")
	)
	(segment
		(start 99.149916 -122.124978)
		(end 104.010968 -126.98603)
		(width 0.14224)
		(layer "In11.Cu")
		(net "M_M_MA<13>")
	)
	(segment
		(start 104.010968 -126.98603)
		(end 104.010968 -129.921)
		(width 0.14224)
		(layer "In11.Cu")
		(net "M_M_MA<13>")
	)
	(segment
		(start 95.968058 -91.538806)
		(end 95.968058 -92.075762)
		(width 0.0889)
		(layer "In11.Cu")
		(net "M_M_MA<13>")
	)
	(segment
		(start 107.740704 -147.51558)
		(end 108.23194 -147.024344)
		(width 0.14224)
		(layer "In11.Cu")
		(net "M_M_MA<13>")
	)
	(segment
		(start 95.508318 -90.756486)
		(end 95.968058 -91.538806)
		(width 0.0889)
		(layer "In11.Cu")
		(net "M_M_MA<13>")
	)
	(segment
		(start 108.447332 -148.470874)
		(end 108.749846 -148.773388)
		(width 0.14224)
		(layer "In11.Cu")
		(net "M_M_MA<13>")
	)
	(segment
		(start 109.222794 -154.528774)
		(end 108.749338 -155.00223)
		(width 0.14224)
		(layer "In11.Cu")
		(net "M_M_MA<13>")
	)
	(segment
		(start 98.092768 -102.87)
		(end 99.149916 -103.927148)
		(width 0.14224)
		(layer "In11.Cu")
		(net "M_M_MA<13>")
	)
	(segment
		(start 105.75925 -144.68348)
		(end 106.55427 -145.4785)
		(width 0.14224)
		(layer "In11.Cu")
		(net "M_M_MA<13>")
	)
	(segment
		(start 104.163368 -130.5306)
		(end 104.010968 -130.683)
		(width 0.14224)
		(layer "In11.Cu")
		(net "M_M_MA<13>")
	)
	(segment
		(start 109.185456 -150.462488)
		(end 109.185456 -151.137112)
		(width 0.14224)
		(layer "In11.Cu")
		(net "M_M_MA<13>")
	)
	(segment
		(start 96.020128 -96.404938)
		(end 96.026478 -96.415606)
		(width 0.0889)
		(layer "In11.Cu")
		(net "M_M_MA<13>")
	)
	(segment
		(start 104.163368 -130.0734)
		(end 104.163368 -130.5306)
		(width 0.14224)
		(layer "In11.Cu")
		(net "M_M_MA<13>")
	)
	(segment
		(start 104.010968 -129.921)
		(end 104.163368 -130.0734)
		(width 0.14224)
		(layer "In11.Cu")
		(net "M_M_MA<13>")
	)
	(segment
		(start 108.749846 -150.026878)
		(end 109.185456 -150.462488)
		(width 0.14224)
		(layer "In11.Cu")
		(net "M_M_MA<13>")
	)
	(segment
		(start 96.015302 -98.377502)
		(end 96.020128 -98.386138)
		(width 0.0889)
		(layer "In11.Cu")
		(net "M_M_MA<13>")
	)
	(segment
		(start 96.020128 -97.395538)
		(end 96.026478 -97.406206)
		(width 0.0889)
		(layer "In11.Cu")
		(net "M_M_MA<13>")
	)
	(segment
		(start 98.092768 -101.092)
		(end 98.092768 -102.87)
		(width 0.14224)
		(layer "In11.Cu")
		(net "M_M_MA<13>")
	)
	(segment
		(start 104.010968 -131.1402)
		(end 104.08412 -131.213352)
		(width 0.14224)
		(layer "In11.Cu")
		(net "M_M_MA<13>")
	)
	(segment
		(start 96.822768 -99.822)
		(end 97.148904 -100.148136)
		(width 0.0889)
		(layer "In11.Cu")
		(net "M_M_MA<13>")
	)
	(segment
		(start 104.137968 -136.010396)
		(end 104.083866 -136.064498)
		(width 0.14224)
		(layer "In11.Cu")
		(net "M_M_MA<13>")
	)
	(segment
		(start 96.020128 -98.386138)
		(end 96.026478 -98.396806)
		(width 0.0889)
		(layer "In11.Cu")
		(net "M_M_MA<13>")
	)
	(segment
		(start 97.148904 -100.148136)
		(end 98.092768 -101.092)
		(width 0.14224)
		(layer "In11.Cu")
		(net "M_M_MA<13>")
	)
	(segment
		(start 104.083866 -136.064498)
		(end 104.083866 -138.020298)
		(width 0.14224)
		(layer "In11.Cu")
		(net "M_M_MA<13>")
	)
	(segment
		(start 96.416368 -99.822)
		(end 96.822768 -99.822)
		(width 0.0889)
		(layer "In11.Cu")
		(net "M_M_MA<13>")
	)
	(segment
		(start 104.9274 -140.108432)
		(end 105.75925 -140.940282)
		(width 0.14224)
		(layer "In11.Cu")
		(net "M_M_MA<13>")
	)
	(segment
		(start 108.447332 -148.15185)
		(end 108.447332 -148.470874)
		(width 0.14224)
		(layer "In11.Cu")
		(net "M_M_MA<13>")
	)
	(segment
		(start 96.15297 -99.599242)
		(end 96.285812 -99.691444)
		(width 0.0889)
		(layer "In11.Cu")
		(net "M_M_MA<13>")
	)
	(segment
		(start 96.285812 -99.691444)
		(end 96.416368 -99.822)
		(width 0.0889)
		(layer "In11.Cu")
		(net "M_M_MA<13>")
	)
	(arc
		(start 96.026478 -96.415606)
		(mid 96.099276 -96.706369)
		(end 96.020128 -96.995488)
		(width 0.0889)
		(layer "In11.Cu")
		(net "M_M_MA<13>")
	)
	(arc
		(start 95.967042 -96.206564)
		(mid 95.979306 -96.304448)
		(end 96.015302 -96.396302)
		(width 0.0889)
		(layer "In11.Cu")
		(net "M_M_MA<13>")
	)
	(arc
		(start 96.020128 -96.995488)
		(mid 95.966658 -97.190551)
		(end 96.015302 -97.386902)
		(width 0.0889)
		(layer "In11.Cu")
		(net "M_M_MA<13>")
	)
	(arc
		(start 96.020128 -98.976688)
		(mid 95.966658 -99.171751)
		(end 96.015302 -99.368102)
		(width 0.0889)
		(layer "In11.Cu")
		(net "M_M_MA<13>")
	)
	(arc
		(start 96.026478 -98.396806)
		(mid 96.099276 -98.687569)
		(end 96.020128 -98.976688)
		(width 0.0889)
		(layer "In11.Cu")
		(net "M_M_MA<13>")
	)
	(arc
		(start 96.026478 -97.406206)
		(mid 96.099276 -97.696969)
		(end 96.020128 -97.986088)
		(width 0.0889)
		(layer "In11.Cu")
		(net "M_M_MA<13>")
	)
	(arc
		(start 96.020128 -97.986088)
		(mid 95.966658 -98.181151)
		(end 96.015302 -98.377502)
		(width 0.0889)
		(layer "In11.Cu")
		(net "M_M_MA<13>")
	)
	(segment
		(start 84.0994 -152.273)
		(end 84.0994 -153.571956)
		(width 0.1651)
		(layer "F.Cu")
		(net "M_M_MA<12>")
	)
	(segment
		(start 90.070178 -92.24264)
		(end 89.498678 -92.24264)
		(width 0.1016)
		(layer "F.Cu")
		(net "M_M_MA<12>")
	)
	(via
		(at 84.0994 -153.571956)
		(size 0.508)
		(drill 0.254)
		(layers "F.Cu" "B.Cu")
		(net "M_M_MA<12>")
	)
	(via
		(at 89.498678 -92.24264)
		(size 0.508)
		(drill 0.254)
		(layers "F.Cu" "B.Cu")
		(net "M_M_MA<12>")
	)
	(via
		(at 84.0994 -150.788878)
		(size 0.4572)
		(drill 0.2032)
		(layers "F.Cu" "B.Cu")
		(net "M_M_MA<12>")
	)
	(segment
		(start 84.0994 -152.078436)
		(end 84.0994 -150.788878)
		(width 0.1651)
		(layer "B.Cu")
		(net "M_M_MA<12>")
	)
	(segment
		(start 92.331032 -135.562086)
		(end 92.124784 -135.768334)
		(width 0.14224)
		(layer "In11.Cu")
		(net "M_M_MA<12>")
	)
	(segment
		(start 89.498678 -92.24264)
		(end 89.828624 -93.004386)
		(width 0.0889)
		(layer "In11.Cu")
		(net "M_M_MA<12>")
	)
	(segment
		(start 84.0994 -153.053288)
		(end 84.0994 -153.571956)
		(width 0.14224)
		(layer "In11.Cu")
		(net "M_M_MA<12>")
	)
	(segment
		(start 89.787476 -143.362934)
		(end 89.787476 -143.581882)
		(width 0.14224)
		(layer "In11.Cu")
		(net "M_M_MA<12>")
	)
	(segment
		(start 83.425538 -152.843484)
		(end 83.889596 -152.843484)
		(width 0.14224)
		(layer "In11.Cu")
		(net "M_M_MA<12>")
	)
	(segment
		(start 83.960208 -151.953214)
		(end 83.393788 -151.953214)
		(width 0.14224)
		(layer "In11.Cu")
		(net "M_M_MA<12>")
	)
	(segment
		(start 89.828624 -93.004386)
		(end 89.845388 -93.033088)
		(width 0.0889)
		(layer "In11.Cu")
		(net "M_M_MA<12>")
	)
	(segment
		(start 91.794584 -135.768334)
		(end 91.34221 -136.220708)
		(width 0.14224)
		(layer "In11.Cu")
		(net "M_M_MA<12>")
	)
	(segment
		(start 91.370912 -101.342444)
		(end 91.685618 -101.65715)
		(width 0.0889)
		(layer "In11.Cu")
		(net "M_M_MA<12>")
	)
	(segment
		(start 91.107768 -132.833872)
		(end 91.107768 -133.8072)
		(width 0.14224)
		(layer "In11.Cu")
		(net "M_M_MA<12>")
	)
	(segment
		(start 92.072968 -134.902702)
		(end 92.331032 -135.160766)
		(width 0.14224)
		(layer "In11.Cu")
		(net "M_M_MA<12>")
	)
	(segment
		(start 89.787476 -143.581882)
		(end 89.615772 -143.753586)
		(width 0.14224)
		(layer "In11.Cu")
		(net "M_M_MA<12>")
	)
	(segment
		(start 91.34221 -136.220708)
		(end 91.34221 -142.027148)
		(width 0.14224)
		(layer "In11.Cu")
		(net "M_M_MA<12>")
	)
	(segment
		(start 83.889596 -152.843484)
		(end 84.0994 -153.053288)
		(width 0.14224)
		(layer "In11.Cu")
		(net "M_M_MA<12>")
	)
	(segment
		(start 91.685618 -101.65715)
		(end 92.647516 -102.619048)
		(width 0.14224)
		(layer "In11.Cu")
		(net "M_M_MA<12>")
	)
	(segment
		(start 91.567254 -98.377502)
		(end 91.440508 -98.60407)
		(width 0.0889)
		(layer "In11.Cu")
		(net "M_M_MA<12>")
	)
	(segment
		(start 91.107768 -133.8072)
		(end 91.412568 -134.112)
		(width 0.14224)
		(layer "In11.Cu")
		(net "M_M_MA<12>")
	)
	(segment
		(start 91.562428 -95.414338)
		(end 91.556078 -95.425006)
		(width 0.0889)
		(layer "In11.Cu")
		(net "M_M_MA<12>")
	)
	(segment
		(start 87.027004 -147.253706)
		(end 85.919564 -147.253706)
		(width 0.14224)
		(layer "In11.Cu")
		(net "M_M_MA<12>")
	)
	(segment
		(start 91.368372 -98.80727)
		(end 91.370912 -98.80981)
		(width 0.0889)
		(layer "In11.Cu")
		(net "M_M_MA<12>")
	)
	(segment
		(start 91.567254 -95.405702)
		(end 91.562428 -95.414338)
		(width 0.0889)
		(layer "In11.Cu")
		(net "M_M_MA<12>")
	)
	(segment
		(start 84.0994 -150.788878)
		(end 84.0994 -151.814022)
		(width 0.14224)
		(layer "In11.Cu")
		(net "M_M_MA<12>")
	)
	(segment
		(start 83.393788 -151.953214)
		(end 83.226148 -152.120854)
		(width 0.14224)
		(layer "In11.Cu")
		(net "M_M_MA<12>")
	)
	(segment
		(start 91.370912 -98.80981)
		(end 91.370912 -101.342444)
		(width 0.0889)
		(layer "In11.Cu")
		(net "M_M_MA<12>")
	)
	(segment
		(start 91.562428 -97.395538)
		(end 91.556078 -97.406206)
		(width 0.0889)
		(layer "In11.Cu")
		(net "M_M_MA<12>")
	)
	(segment
		(start 84.529168 -149.284944)
		(end 84.0994 -149.714712)
		(width 0.14224)
		(layer "In11.Cu")
		(net "M_M_MA<12>")
	)
	(segment
		(start 85.66277 -147.856956)
		(end 85.87232 -148.066506)
		(width 0.14224)
		(layer "In11.Cu")
		(net "M_M_MA<12>")
	)
	(segment
		(start 87.089234 -148.375624)
		(end 87.089234 -148.967698)
		(width 0.14224)
		(layer "In11.Cu")
		(net "M_M_MA<12>")
	)
	(segment
		(start 84.0994 -151.814022)
		(end 83.960208 -151.953214)
		(width 0.14224)
		(layer "In11.Cu")
		(net "M_M_MA<12>")
	)
	(segment
		(start 91.615768 -134.902702)
		(end 92.072968 -134.902702)
		(width 0.14224)
		(layer "In11.Cu")
		(net "M_M_MA<12>")
	)
	(segment
		(start 89.980262 -142.617952)
		(end 89.761314 -142.617952)
		(width 0.14224)
		(layer "In11.Cu")
		(net "M_M_MA<12>")
	)
	(segment
		(start 90.344244 -93.32849)
		(end 90.368374 -93.32849)
		(width 0.0889)
		(layer "In11.Cu")
		(net "M_M_MA<12>")
	)
	(segment
		(start 90.545412 -132.271516)
		(end 91.107768 -132.833872)
		(width 0.14224)
		(layer "In11.Cu")
		(net "M_M_MA<12>")
	)
	(segment
		(start 92.647516 -102.619048)
		(end 92.647516 -127.290576)
		(width 0.14224)
		(layer "In11.Cu")
		(net "M_M_MA<12>")
	)
	(segment
		(start 83.226148 -152.120854)
		(end 83.226148 -152.644094)
		(width 0.14224)
		(layer "In11.Cu")
		(net "M_M_MA<12>")
	)
	(segment
		(start 90.25636 -142.89405)
		(end 89.980262 -142.617952)
		(width 0.14224)
		(layer "In11.Cu")
		(net "M_M_MA<12>")
	)
	(segment
		(start 88.37168 -145.2372)
		(end 87.917782 -145.691098)
		(width 0.14224)
		(layer "In11.Cu")
		(net "M_M_MA<12>")
	)
	(segment
		(start 89.615772 -144.343882)
		(end 88.722454 -145.2372)
		(width 0.14224)
		(layer "In11.Cu")
		(net "M_M_MA<12>")
	)
	(segment
		(start 86.771988 -149.284944)
		(end 84.529168 -149.284944)
		(width 0.14224)
		(layer "In11.Cu")
		(net "M_M_MA<12>")
	)
	(segment
		(start 83.226148 -152.644094)
		(end 83.425538 -152.843484)
		(width 0.14224)
		(layer "In11.Cu")
		(net "M_M_MA<12>")
	)
	(segment
		(start 92.124784 -135.768334)
		(end 91.794584 -135.768334)
		(width 0.14224)
		(layer "In11.Cu")
		(net "M_M_MA<12>")
	)
	(segment
		(start 89.511378 -142.867888)
		(end 89.511378 -143.086836)
		(width 0.14224)
		(layer "In11.Cu")
		(net "M_M_MA<12>")
	)
	(segment
		(start 86.780116 -148.066506)
		(end 87.089234 -148.375624)
		(width 0.14224)
		(layer "In11.Cu")
		(net "M_M_MA<12>")
	)
	(segment
		(start 87.917782 -146.362928)
		(end 87.027004 -147.253706)
		(width 0.14224)
		(layer "In11.Cu")
		(net "M_M_MA<12>")
	)
	(segment
		(start 91.412568 -134.699502)
		(end 91.615768 -134.902702)
		(width 0.14224)
		(layer "In11.Cu")
		(net "M_M_MA<12>")
	)
	(segment
		(start 90.545412 -129.39268)
		(end 90.545412 -132.271516)
		(width 0.14224)
		(layer "In11.Cu")
		(net "M_M_MA<12>")
	)
	(segment
		(start 87.089234 -148.967698)
		(end 86.771988 -149.284944)
		(width 0.14224)
		(layer "In11.Cu")
		(net "M_M_MA<12>")
	)
	(segment
		(start 89.615772 -143.753586)
		(end 89.615772 -144.343882)
		(width 0.14224)
		(layer "In11.Cu")
		(net "M_M_MA<12>")
	)
	(segment
		(start 84.0994 -149.714712)
		(end 84.0994 -150.788878)
		(width 0.14224)
		(layer "In11.Cu")
		(net "M_M_MA<12>")
	)
	(segment
		(start 91.562428 -96.404938)
		(end 91.556078 -96.415606)
		(width 0.0889)
		(layer "In11.Cu")
		(net "M_M_MA<12>")
	)
	(segment
		(start 90.475308 -142.89405)
		(end 90.25636 -142.89405)
		(width 0.14224)
		(layer "In11.Cu")
		(net "M_M_MA<12>")
	)
	(segment
		(start 91.194128 -93.82379)
		(end 91.233752 -93.82379)
		(width 0.0889)
		(layer "In11.Cu")
		(net "M_M_MA<12>")
	)
	(segment
		(start 89.761314 -142.617952)
		(end 89.511378 -142.867888)
		(width 0.14224)
		(layer "In11.Cu")
		(net "M_M_MA<12>")
	)
	(segment
		(start 89.511378 -143.086836)
		(end 89.787476 -143.362934)
		(width 0.14224)
		(layer "In11.Cu")
		(net "M_M_MA<12>")
	)
	(segment
		(start 85.87232 -148.066506)
		(end 86.780116 -148.066506)
		(width 0.14224)
		(layer "In11.Cu")
		(net "M_M_MA<12>")
	)
	(segment
		(start 85.919564 -147.253706)
		(end 85.66277 -147.5105)
		(width 0.14224)
		(layer "In11.Cu")
		(net "M_M_MA<12>")
	)
	(segment
		(start 91.567254 -96.396302)
		(end 91.562428 -96.404938)
		(width 0.0889)
		(layer "In11.Cu")
		(net "M_M_MA<12>")
	)
	(segment
		(start 87.917782 -145.691098)
		(end 87.917782 -146.362928)
		(width 0.14224)
		(layer "In11.Cu")
		(net "M_M_MA<12>")
	)
	(segment
		(start 92.331032 -135.160766)
		(end 92.331032 -135.562086)
		(width 0.14224)
		(layer "In11.Cu")
		(net "M_M_MA<12>")
	)
	(segment
		(start 91.34221 -142.027148)
		(end 90.475308 -142.89405)
		(width 0.14224)
		(layer "In11.Cu")
		(net "M_M_MA<12>")
	)
	(segment
		(start 85.66277 -147.5105)
		(end 85.66277 -147.856956)
		(width 0.14224)
		(layer "In11.Cu")
		(net "M_M_MA<12>")
	)
	(segment
		(start 91.567254 -97.386902)
		(end 91.562428 -97.395538)
		(width 0.0889)
		(layer "In11.Cu")
		(net "M_M_MA<12>")
	)
	(segment
		(start 88.722454 -145.2372)
		(end 88.37168 -145.2372)
		(width 0.14224)
		(layer "In11.Cu")
		(net "M_M_MA<12>")
	)
	(segment
		(start 92.647516 -127.290576)
		(end 90.545412 -129.39268)
		(width 0.14224)
		(layer "In11.Cu")
		(net "M_M_MA<12>")
	)
	(segment
		(start 91.412568 -134.112)
		(end 91.412568 -134.699502)
		(width 0.14224)
		(layer "In11.Cu")
		(net "M_M_MA<12>")
	)
	(arc
		(start 90.703908 -93.528642)
		(mid 90.910912 -93.739506)
		(end 91.194128 -93.82379)
		(width 0.0889)
		(layer "In11.Cu")
		(net "M_M_MA<12>")
	)
	(arc
		(start 89.845388 -93.033088)
		(mid 90.056101 -93.246167)
		(end 90.344244 -93.32849)
		(width 0.0889)
		(layer "In11.Cu")
		(net "M_M_MA<12>")
	)
	(arc
		(start 91.562428 -95.014288)
		(mid 91.615898 -95.209351)
		(end 91.567254 -95.405702)
		(width 0.0889)
		(layer "In11.Cu")
		(net "M_M_MA<12>")
	)
	(arc
		(start 91.562428 -96.995488)
		(mid 91.615898 -97.190551)
		(end 91.567254 -97.386902)
		(width 0.0889)
		(layer "In11.Cu")
		(net "M_M_MA<12>")
	)
	(arc
		(start 91.562428 -96.004888)
		(mid 91.615898 -96.199951)
		(end 91.567254 -96.396302)
		(width 0.0889)
		(layer "In11.Cu")
		(net "M_M_MA<12>")
	)
	(arc
		(start 91.562428 -97.986088)
		(mid 91.615898 -98.181151)
		(end 91.567254 -98.377502)
		(width 0.0889)
		(layer "In11.Cu")
		(net "M_M_MA<12>")
	)
	(arc
		(start 90.368374 -93.32849)
		(mid 90.562224 -93.38484)
		(end 90.703908 -93.528642)
		(width 0.0889)
		(layer "In11.Cu")
		(net "M_M_MA<12>")
	)
	(arc
		(start 91.440508 -98.60407)
		(mid 91.395838 -98.702616)
		(end 91.368372 -98.80727)
		(width 0.0889)
		(layer "In11.Cu")
		(net "M_M_MA<12>")
	)
	(arc
		(start 91.556078 -97.406206)
		(mid 91.48328 -97.696969)
		(end 91.562428 -97.986088)
		(width 0.0889)
		(layer "In11.Cu")
		(net "M_M_MA<12>")
	)
	(arc
		(start 91.556078 -95.425006)
		(mid 91.48328 -95.715769)
		(end 91.562428 -96.004888)
		(width 0.0889)
		(layer "In11.Cu")
		(net "M_M_MA<12>")
	)
	(arc
		(start 91.233752 -93.82379)
		(mid 91.566668 -94.031242)
		(end 91.562428 -94.423484)
		(width 0.0889)
		(layer "In11.Cu")
		(net "M_M_MA<12>")
	)
	(arc
		(start 91.556078 -96.415606)
		(mid 91.48328 -96.706369)
		(end 91.562428 -96.995488)
		(width 0.0889)
		(layer "In11.Cu")
		(net "M_M_MA<12>")
	)
	(arc
		(start 91.562428 -94.423484)
		(mid 91.483297 -94.718886)
		(end 91.562428 -95.014288)
		(width 0.0889)
		(layer "In11.Cu")
		(net "M_M_MA<12>")
	)
	(segment
		(start 90.070178 -89.27084)
		(end 89.498678 -89.27084)
		(width 0.1016)
		(layer "F.Cu")
		(net "M_M_MA<11>")
	)
	(segment
		(start 84.949538 -156.87294)
		(end 84.949538 -155.564078)
		(width 0.1651)
		(layer "F.Cu")
		(net "M_M_MA<11>")
	)
	(via
		(at 89.498678 -89.27084)
		(size 0.508)
		(drill 0.254)
		(layers "F.Cu" "B.Cu")
		(net "M_M_MA<11>")
	)
	(via
		(at 84.949284 -148.771356)
		(size 0.4572)
		(drill 0.2032)
		(layers "F.Cu" "B.Cu")
		(net "M_M_MA<11>")
	)
	(via
		(at 84.949538 -155.564078)
		(size 0.508)
		(drill 0.254)
		(layers "F.Cu" "B.Cu")
		(net "M_M_MA<11>")
	)
	(segment
		(start 84.949538 -147.478496)
		(end 84.949538 -148.771102)
		(width 0.1651)
		(layer "B.Cu")
		(net "M_M_MA<11>")
	)
	(segment
		(start 84.949538 -148.771102)
		(end 84.949284 -148.771356)
		(width 0.1651)
		(layer "B.Cu")
		(net "M_M_MA<11>")
	)
	(segment
		(start 89.609168 -101.346254)
		(end 89.609168 -102.5144)
		(width 0.0889)
		(layer "In2.Cu")
		(net "M_M_MA<11>")
	)
	(segment
		(start 85.468968 -139.6238)
		(end 85.468968 -140.303504)
		(width 0.14224)
		(layer "In2.Cu")
		(net "M_M_MA<11>")
	)
	(segment
		(start 89.355168 -103.1494)
		(end 89.355168 -123.654312)
		(width 0.14224)
		(layer "In2.Cu")
		(net "M_M_MA<11>")
	)
	(segment
		(start 85.468968 -140.303504)
		(end 85.361272 -140.4112)
		(width 0.14224)
		(layer "In2.Cu")
		(net "M_M_MA<11>")
	)
	(segment
		(start 85.291168 -130.6576)
		(end 85.291168 -131.1402)
		(width 0.14224)
		(layer "In2.Cu")
		(net "M_M_MA<11>")
	)
	(segment
		(start 89.277444 -98.528632)
		(end 89.349072 -98.60026)
		(width 0.0889)
		(layer "In2.Cu")
		(net "M_M_MA<11>")
	)
	(segment
		(start 89.152222 -96.404938)
		(end 89.161112 -96.420178)
		(width 0.0889)
		(layer "In2.Cu")
		(net "M_M_MA<11>")
	)
	(segment
		(start 89.349072 -98.60026)
		(end 89.349072 -101.086158)
		(width 0.0889)
		(layer "In2.Cu")
		(net "M_M_MA<11>")
	)
	(segment
		(start 85.519768 -133.2992)
		(end 85.365336 -133.453632)
		(width 0.14224)
		(layer "In2.Cu")
		(net "M_M_MA<11>")
	)
	(segment
		(start 89.498678 -89.27084)
		(end 89.098628 -89.97823)
		(width 0.0889)
		(layer "In2.Cu")
		(net "M_M_MA<11>")
	)
	(segment
		(start 89.098628 -89.97823)
		(end 89.098628 -92.247466)
		(width 0.0889)
		(layer "In2.Cu")
		(net "M_M_MA<11>")
	)
	(segment
		(start 85.361272 -144.316704)
		(end 85.468968 -144.4244)
		(width 0.14224)
		(layer "In2.Cu")
		(net "M_M_MA<11>")
	)
	(segment
		(start 89.349072 -101.086158)
		(end 89.609168 -101.346254)
		(width 0.0889)
		(layer "In2.Cu")
		(net "M_M_MA<11>")
	)
	(segment
		(start 85.316568 -129.375916)
		(end 85.316568 -129.8194)
		(width 0.14224)
		(layer "In2.Cu")
		(net "M_M_MA<11>")
	)
	(segment
		(start 84.478368 -154.559)
		(end 84.949538 -155.03017)
		(width 0.14224)
		(layer "In2.Cu")
		(net "M_M_MA<11>")
	)
	(segment
		(start 84.605368 -152.3238)
		(end 84.605368 -153.8224)
		(width 0.14224)
		(layer "In2.Cu")
		(net "M_M_MA<11>")
	)
	(segment
		(start 84.949538 -155.03017)
		(end 84.949538 -155.564078)
		(width 0.14224)
		(layer "In2.Cu")
		(net "M_M_MA<11>")
	)
	(segment
		(start 89.152222 -95.414338)
		(end 89.161112 -95.429578)
		(width 0.0889)
		(layer "In2.Cu")
		(net "M_M_MA<11>")
	)
	(segment
		(start 85.621368 -127.388112)
		(end 85.621368 -129.071116)
		(width 0.14224)
		(layer "In2.Cu")
		(net "M_M_MA<11>")
	)
	(segment
		(start 85.468968 -145.300192)
		(end 85.383878 -145.385282)
		(width 0.14224)
		(layer "In2.Cu")
		(net "M_M_MA<11>")
	)
	(segment
		(start 89.609168 -102.5144)
		(end 89.355168 -102.7684)
		(width 0.0889)
		(layer "In2.Cu")
		(net "M_M_MA<11>")
	)
	(segment
		(start 84.949284 -146.696684)
		(end 84.949284 -148.771356)
		(width 0.14224)
		(layer "In2.Cu")
		(net "M_M_MA<11>")
	)
	(segment
		(start 85.621368 -129.071116)
		(end 85.316568 -129.375916)
		(width 0.14224)
		(layer "In2.Cu")
		(net "M_M_MA<11>")
	)
	(segment
		(start 84.510372 -152.228804)
		(end 84.605368 -152.3238)
		(width 0.14224)
		(layer "In2.Cu")
		(net "M_M_MA<11>")
	)
	(segment
		(start 89.152222 -92.442538)
		(end 89.161112 -92.457778)
		(width 0.0889)
		(layer "In2.Cu")
		(net "M_M_MA<11>")
	)
	(segment
		(start 84.510372 -150.411688)
		(end 84.510372 -152.228804)
		(width 0.14224)
		(layer "In2.Cu")
		(net "M_M_MA<11>")
	)
	(segment
		(start 85.365336 -139.520168)
		(end 85.468968 -139.6238)
		(width 0.14224)
		(layer "In2.Cu")
		(net "M_M_MA<11>")
	)
	(segment
		(start 85.365336 -133.453632)
		(end 85.365336 -139.520168)
		(width 0.14224)
		(layer "In2.Cu")
		(net "M_M_MA<11>")
	)
	(segment
		(start 85.418168 -129.921)
		(end 85.418168 -130.5306)
		(width 0.14224)
		(layer "In2.Cu")
		(net "M_M_MA<11>")
	)
	(segment
		(start 89.152222 -94.423484)
		(end 89.158572 -94.434152)
		(width 0.0889)
		(layer "In2.Cu")
		(net "M_M_MA<11>")
	)
	(segment
		(start 85.383878 -146.26209)
		(end 84.949284 -146.696684)
		(width 0.14224)
		(layer "In2.Cu")
		(net "M_M_MA<11>")
	)
	(segment
		(start 89.355168 -123.654312)
		(end 85.621368 -127.388112)
		(width 0.14224)
		(layer "In2.Cu")
		(net "M_M_MA<11>")
	)
	(segment
		(start 89.158572 -94.01302)
		(end 89.152222 -94.023688)
		(width 0.0889)
		(layer "In2.Cu")
		(net "M_M_MA<11>")
	)
	(segment
		(start 85.383878 -145.385282)
		(end 85.383878 -146.26209)
		(width 0.14224)
		(layer "In2.Cu")
		(net "M_M_MA<11>")
	)
	(segment
		(start 84.478368 -153.9494)
		(end 84.478368 -154.559)
		(width 0.14224)
		(layer "In2.Cu")
		(net "M_M_MA<11>")
	)
	(segment
		(start 84.605368 -153.8224)
		(end 84.478368 -153.9494)
		(width 0.14224)
		(layer "In2.Cu")
		(net "M_M_MA<11>")
	)
	(segment
		(start 85.291168 -131.1402)
		(end 85.519768 -131.3688)
		(width 0.14224)
		(layer "In2.Cu")
		(net "M_M_MA<11>")
	)
	(segment
		(start 84.405978 -150.307294)
		(end 84.510372 -150.411688)
		(width 0.14224)
		(layer "In2.Cu")
		(net "M_M_MA<11>")
	)
	(segment
		(start 85.316568 -129.8194)
		(end 85.418168 -129.921)
		(width 0.14224)
		(layer "In2.Cu")
		(net "M_M_MA<11>")
	)
	(segment
		(start 84.949284 -148.771356)
		(end 84.405978 -149.314662)
		(width 0.14224)
		(layer "In2.Cu")
		(net "M_M_MA<11>")
	)
	(segment
		(start 85.418168 -130.5306)
		(end 85.291168 -130.6576)
		(width 0.14224)
		(layer "In2.Cu")
		(net "M_M_MA<11>")
	)
	(segment
		(start 89.152222 -97.395538)
		(end 89.161112 -97.410778)
		(width 0.0889)
		(layer "In2.Cu")
		(net "M_M_MA<11>")
	)
	(segment
		(start 85.361272 -140.4112)
		(end 85.361272 -144.316704)
		(width 0.14224)
		(layer "In2.Cu")
		(net "M_M_MA<11>")
	)
	(segment
		(start 85.468968 -144.4244)
		(end 85.468968 -145.300192)
		(width 0.14224)
		(layer "In2.Cu")
		(net "M_M_MA<11>")
	)
	(segment
		(start 84.405978 -149.314662)
		(end 84.405978 -150.307294)
		(width 0.14224)
		(layer "In2.Cu")
		(net "M_M_MA<11>")
	)
	(segment
		(start 85.519768 -131.3688)
		(end 85.519768 -133.2992)
		(width 0.14224)
		(layer "In2.Cu")
		(net "M_M_MA<11>")
	)
	(segment
		(start 89.355168 -102.7684)
		(end 89.355168 -103.1494)
		(width 0.0889)
		(layer "In2.Cu")
		(net "M_M_MA<11>")
	)
	(arc
		(start 89.152222 -96.995742)
		(mid 89.098689 -97.19564)
		(end 89.152222 -97.395538)
		(width 0.0889)
		(layer "In2.Cu")
		(net "M_M_MA<11>")
	)
	(arc
		(start 89.152222 -98.386138)
		(mid 89.207803 -98.463561)
		(end 89.277444 -98.528632)
		(width 0.0889)
		(layer "In2.Cu")
		(net "M_M_MA<11>")
	)
	(arc
		(start 89.161112 -95.429578)
		(mid 89.231509 -95.718529)
		(end 89.152222 -96.005142)
		(width 0.0889)
		(layer "In2.Cu")
		(net "M_M_MA<11>")
	)
	(arc
		(start 89.152222 -93.033342)
		(mid 89.098689 -93.23324)
		(end 89.152222 -93.433138)
		(width 0.0889)
		(layer "In2.Cu")
		(net "M_M_MA<11>")
	)
	(arc
		(start 89.152222 -96.005142)
		(mid 89.098689 -96.20504)
		(end 89.152222 -96.404938)
		(width 0.0889)
		(layer "In2.Cu")
		(net "M_M_MA<11>")
	)
	(arc
		(start 89.098628 -92.247466)
		(mid 89.112908 -92.348439)
		(end 89.152222 -92.442538)
		(width 0.0889)
		(layer "In2.Cu")
		(net "M_M_MA<11>")
	)
	(arc
		(start 89.152222 -97.986342)
		(mid 89.098689 -98.18624)
		(end 89.152222 -98.386138)
		(width 0.0889)
		(layer "In2.Cu")
		(net "M_M_MA<11>")
	)
	(arc
		(start 89.161112 -97.410778)
		(mid 89.231509 -97.699729)
		(end 89.152222 -97.986342)
		(width 0.0889)
		(layer "In2.Cu")
		(net "M_M_MA<11>")
	)
	(arc
		(start 89.161112 -96.420178)
		(mid 89.231509 -96.709129)
		(end 89.152222 -96.995742)
		(width 0.0889)
		(layer "In2.Cu")
		(net "M_M_MA<11>")
	)
	(arc
		(start 89.158572 -94.434152)
		(mid 89.231492 -94.725169)
		(end 89.152222 -95.014542)
		(width 0.0889)
		(layer "In2.Cu")
		(net "M_M_MA<11>")
	)
	(arc
		(start 89.161112 -92.457778)
		(mid 89.231509 -92.746729)
		(end 89.152222 -93.033342)
		(width 0.0889)
		(layer "In2.Cu")
		(net "M_M_MA<11>")
	)
	(arc
		(start 89.152222 -93.433138)
		(mid 89.231444 -93.722256)
		(end 89.158572 -94.01302)
		(width 0.0889)
		(layer "In2.Cu")
		(net "M_M_MA<11>")
	)
	(arc
		(start 89.152222 -95.014542)
		(mid 89.098689 -95.21444)
		(end 89.152222 -95.414338)
		(width 0.0889)
		(layer "In2.Cu")
		(net "M_M_MA<11>")
	)
	(arc
		(start 89.152222 -94.023688)
		(mid 89.098689 -94.223586)
		(end 89.152222 -94.423484)
		(width 0.0889)
		(layer "In2.Cu")
		(net "M_M_MA<11>")
	)
	(segment
		(start 94.362778 -90.756486)
		(end 93.791278 -90.756486)
		(width 0.1016)
		(layer "F.Cu")
		(net "M_M_MA<10>")
	)
	(segment
		(start 102.799388 -156.87294)
		(end 102.799388 -154.905456)
		(width 0.1651)
		(layer "F.Cu")
		(net "M_M_MA<10>")
	)
	(via
		(at 102.799642 -148.773388)
		(size 0.4572)
		(drill 0.2032)
		(layers "F.Cu" "B.Cu")
		(net "M_M_MA<10>")
	)
	(via
		(at 102.799388 -154.905456)
		(size 0.508)
		(drill 0.254)
		(layers "F.Cu" "B.Cu")
		(net "M_M_MA<10>")
	)
	(via
		(at 93.791278 -90.756486)
		(size 0.508)
		(drill 0.254)
		(layers "F.Cu" "B.Cu")
		(net "M_M_MA<10>")
	)
	(segment
		(start 102.799388 -148.773134)
		(end 102.799642 -148.773388)
		(width 0.1651)
		(layer "B.Cu")
		(net "M_M_MA<10>")
	)
	(segment
		(start 102.799388 -147.478496)
		(end 102.799388 -148.773134)
		(width 0.1651)
		(layer "B.Cu")
		(net "M_M_MA<10>")
	)
	(segment
		(start 102.799642 -148.773388)
		(end 103.223568 -149.197314)
		(width 0.14224)
		(layer "In11.Cu")
		(net "M_M_MA<10>")
	)
	(segment
		(start 96.416368 -135.9916)
		(end 96.975168 -136.5504)
		(width 0.14224)
		(layer "In11.Cu")
		(net "M_M_MA<10>")
	)
	(segment
		(start 95.187516 -101.513894)
		(end 95.187516 -126.202948)
		(width 0.14224)
		(layer "In11.Cu")
		(net "M_M_MA<10>")
	)
	(segment
		(start 103.321358 -152.55875)
		(end 103.321358 -153.808938)
		(width 0.14224)
		(layer "In11.Cu")
		(net "M_M_MA<10>")
	)
	(segment
		(start 93.774768 -100.101146)
		(end 93.902022 -100.2284)
		(width 0.0889)
		(layer "In11.Cu")
		(net "M_M_MA<10>")
	)
	(segment
		(start 102.799642 -148.529548)
		(end 102.799642 -148.773388)
		(width 0.14224)
		(layer "In11.Cu")
		(net "M_M_MA<10>")
	)
	(segment
		(start 103.223568 -149.197314)
		(end 103.223568 -152.46096)
		(width 0.14224)
		(layer "In11.Cu")
		(net "M_M_MA<10>")
	)
	(segment
		(start 103.223568 -152.46096)
		(end 103.321358 -152.55875)
		(width 0.14224)
		(layer "In11.Cu")
		(net "M_M_MA<10>")
	)
	(segment
		(start 98.041968 -146.7612)
		(end 101.031294 -146.7612)
		(width 0.14224)
		(layer "In11.Cu")
		(net "M_M_MA<10>")
	)
	(segment
		(start 93.902022 -100.2284)
		(end 95.187516 -101.513894)
		(width 0.14224)
		(layer "In11.Cu")
		(net "M_M_MA<10>")
	)
	(segment
		(start 103.321358 -153.808938)
		(end 102.799388 -154.330908)
		(width 0.14224)
		(layer "In11.Cu")
		(net "M_M_MA<10>")
	)
	(segment
		(start 93.368368 -97.775268)
		(end 93.368368 -98.1202)
		(width 0.0889)
		(layer "In11.Cu")
		(net "M_M_MA<10>")
	)
	(segment
		(start 93.647768 -100.101146)
		(end 93.774768 -100.101146)
		(width 0.0889)
		(layer "In11.Cu")
		(net "M_M_MA<10>")
	)
	(segment
		(start 102.799388 -154.330908)
		(end 102.799388 -154.905456)
		(width 0.14224)
		(layer "In11.Cu")
		(net "M_M_MA<10>")
	)
	(segment
		(start 96.416368 -127.4318)
		(end 96.416368 -135.9916)
		(width 0.14224)
		(layer "In11.Cu")
		(net "M_M_MA<10>")
	)
	(segment
		(start 93.373956 -99.827334)
		(end 93.647768 -100.101146)
		(width 0.0889)
		(layer "In11.Cu")
		(net "M_M_MA<10>")
	)
	(segment
		(start 101.031294 -146.7612)
		(end 102.799642 -148.529548)
		(width 0.14224)
		(layer "In11.Cu")
		(net "M_M_MA<10>")
	)
	(segment
		(start 93.373956 -98.125788)
		(end 93.373956 -99.827334)
		(width 0.0889)
		(layer "In11.Cu")
		(net "M_M_MA<10>")
	)
	(segment
		(start 93.698568 -90.96629)
		(end 93.501718 -91.411552)
		(width 0.0889)
		(layer "In11.Cu")
		(net "M_M_MA<10>")
	)
	(segment
		(start 93.791278 -90.756486)
		(end 93.698568 -90.96629)
		(width 0.0889)
		(layer "In11.Cu")
		(net "M_M_MA<10>")
	)
	(segment
		(start 96.975168 -145.6944)
		(end 98.041968 -146.7612)
		(width 0.14224)
		(layer "In11.Cu")
		(net "M_M_MA<10>")
	)
	(segment
		(start 95.187516 -126.202948)
		(end 96.416368 -127.4318)
		(width 0.14224)
		(layer "In11.Cu")
		(net "M_M_MA<10>")
	)
	(segment
		(start 96.975168 -136.5504)
		(end 96.975168 -145.6944)
		(width 0.14224)
		(layer "In11.Cu")
		(net "M_M_MA<10>")
	)
	(segment
		(start 93.368368 -98.1202)
		(end 93.373956 -98.125788)
		(width 0.0889)
		(layer "In11.Cu")
		(net "M_M_MA<10>")
	)
	(arc
		(start 93.444568 -93.528388)
		(mid 93.391069 -93.728286)
		(end 93.444568 -93.928184)
		(width 0.0889)
		(layer "In11.Cu")
		(net "M_M_MA<10>")
	)
	(arc
		(start 93.501718 -91.411552)
		(mid 93.477393 -91.481162)
		(end 93.444568 -91.547188)
		(width 0.0889)
		(layer "In11.Cu")
		(net "M_M_MA<10>")
	)
	(arc
		(start 93.444568 -94.518988)
		(mid 93.391069 -94.718886)
		(end 93.444568 -94.918784)
		(width 0.0889)
		(layer "In11.Cu")
		(net "M_M_MA<10>")
	)
	(arc
		(start 93.444568 -91.547188)
		(mid 93.391069 -91.747086)
		(end 93.444568 -91.946984)
		(width 0.0889)
		(layer "In11.Cu")
		(net "M_M_MA<10>")
	)
	(arc
		(start 93.444568 -91.946984)
		(mid 93.523699 -92.242386)
		(end 93.444568 -92.537788)
		(width 0.0889)
		(layer "In11.Cu")
		(net "M_M_MA<10>")
	)
	(arc
		(start 93.444568 -96.899984)
		(mid 93.523699 -97.195386)
		(end 93.444568 -97.490788)
		(width 0.0889)
		(layer "In11.Cu")
		(net "M_M_MA<10>")
	)
	(arc
		(start 93.444568 -95.909384)
		(mid 93.523699 -96.204786)
		(end 93.444568 -96.500188)
		(width 0.0889)
		(layer "In11.Cu")
		(net "M_M_MA<10>")
	)
	(arc
		(start 93.444568 -94.918784)
		(mid 93.523699 -95.214186)
		(end 93.444568 -95.509588)
		(width 0.0889)
		(layer "In11.Cu")
		(net "M_M_MA<10>")
	)
	(arc
		(start 93.444568 -95.509588)
		(mid 93.391069 -95.709486)
		(end 93.444568 -95.909384)
		(width 0.0889)
		(layer "In11.Cu")
		(net "M_M_MA<10>")
	)
	(arc
		(start 93.444568 -92.937584)
		(mid 93.523699 -93.232986)
		(end 93.444568 -93.528388)
		(width 0.0889)
		(layer "In11.Cu")
		(net "M_M_MA<10>")
	)
	(arc
		(start 93.444568 -92.537788)
		(mid 93.391069 -92.737686)
		(end 93.444568 -92.937584)
		(width 0.0889)
		(layer "In11.Cu")
		(net "M_M_MA<10>")
	)
	(arc
		(start 93.444568 -96.500188)
		(mid 93.391069 -96.700086)
		(end 93.444568 -96.899984)
		(width 0.0889)
		(layer "In11.Cu")
		(net "M_M_MA<10>")
	)
	(arc
		(start 93.444568 -93.928184)
		(mid 93.523699 -94.223586)
		(end 93.444568 -94.518988)
		(width 0.0889)
		(layer "In11.Cu")
		(net "M_M_MA<10>")
	)
	(arc
		(start 93.444568 -97.490788)
		(mid 93.387731 -97.628011)
		(end 93.368368 -97.775268)
		(width 0.0889)
		(layer "In11.Cu")
		(net "M_M_MA<10>")
	)
	(segment
		(start 101.099366 -152.273)
		(end 101.099366 -153.542746)
		(width 0.1651)
		(layer "F.Cu")
		(net "M_M_MA<0>")
	)
	(segment
		(start 96.079818 -91.747086)
		(end 95.508318 -91.747086)
		(width 0.1016)
		(layer "F.Cu")
		(net "M_M_MA<0>")
	)
	(via
		(at 101.099366 -150.785068)
		(size 0.4572)
		(drill 0.2032)
		(layers "F.Cu" "B.Cu")
		(net "M_M_MA<0>")
	)
	(via
		(at 95.508318 -91.747086)
		(size 0.508)
		(drill 0.254)
		(layers "F.Cu" "B.Cu")
		(net "M_M_MA<0>")
	)
	(via
		(at 101.099366 -153.542746)
		(size 0.508)
		(drill 0.254)
		(layers "F.Cu" "B.Cu")
		(net "M_M_MA<0>")
	)
	(segment
		(start 101.099366 -152.078436)
		(end 101.099366 -150.785068)
		(width 0.1651)
		(layer "B.Cu")
		(net "M_M_MA<0>")
	)
	(segment
		(start 100.61956 -131.152392)
		(end 100.661978 -131.19481)
		(width 0.14224)
		(layer "In2.Cu")
		(net "M_M_MA<0>")
	)
	(segment
		(start 96.020128 -96.404938)
		(end 96.026478 -96.415606)
		(width 0.0889)
		(layer "In2.Cu")
		(net "M_M_MA<0>")
	)
	(segment
		(start 100.687886 -139.577318)
		(end 100.687886 -143.195802)
		(width 0.14224)
		(layer "In2.Cu")
		(net "M_M_MA<0>")
	)
	(segment
		(start 96.822768 -101.829616)
		(end 96.822768 -102.921816)
		(width 0.0889)
		(layer "In2.Cu")
		(net "M_M_MA<0>")
	)
	(segment
		(start 96.822768 -125.156214)
		(end 100.607368 -128.940814)
		(width 0.14224)
		(layer "In2.Cu")
		(net "M_M_MA<0>")
	)
	(segment
		(start 96.226376 -99.610164)
		(end 96.226376 -101.233224)
		(width 0.0889)
		(layer "In2.Cu")
		(net "M_M_MA<0>")
	)
	(segment
		(start 101.099366 -149.539198)
		(end 101.099366 -150.785068)
		(width 0.14224)
		(layer "In2.Cu")
		(net "M_M_MA<0>")
	)
	(segment
		(start 95.508318 -91.747086)
		(end 95.508318 -92.13215)
		(width 0.0889)
		(layer "In2.Cu")
		(net "M_M_MA<0>")
	)
	(segment
		(start 96.020128 -98.386138)
		(end 96.026478 -98.396806)
		(width 0.0889)
		(layer "In2.Cu")
		(net "M_M_MA<0>")
	)
	(segment
		(start 96.015302 -97.386902)
		(end 96.020128 -97.395538)
		(width 0.0889)
		(layer "In2.Cu")
		(net "M_M_MA<0>")
	)
	(segment
		(start 100.687886 -143.195802)
		(end 100.633276 -143.250412)
		(width 0.14224)
		(layer "In2.Cu")
		(net "M_M_MA<0>")
	)
	(segment
		(start 96.015302 -99.368102)
		(end 96.020128 -99.376738)
		(width 0.0889)
		(layer "In2.Cu")
		(net "M_M_MA<0>")
	)
	(segment
		(start 101.226874 -150.912576)
		(end 101.226874 -153.415238)
		(width 0.14224)
		(layer "In2.Cu")
		(net "M_M_MA<0>")
	)
	(segment
		(start 100.661724 -145.055844)
		(end 100.661724 -149.101556)
		(width 0.14224)
		(layer "In2.Cu")
		(net "M_M_MA<0>")
	)
	(segment
		(start 96.026478 -94.01302)
		(end 96.020128 -94.023688)
		(width 0.0889)
		(layer "In2.Cu")
		(net "M_M_MA<0>")
	)
	(segment
		(start 100.721922 -130.543046)
		(end 100.61956 -130.645408)
		(width 0.14224)
		(layer "In2.Cu")
		(net "M_M_MA<0>")
	)
	(segment
		(start 100.661724 -149.101556)
		(end 101.099366 -149.539198)
		(width 0.14224)
		(layer "In2.Cu")
		(net "M_M_MA<0>")
	)
	(segment
		(start 100.665534 -138.702034)
		(end 100.632768 -138.7348)
		(width 0.14224)
		(layer "In2.Cu")
		(net "M_M_MA<0>")
	)
	(segment
		(start 96.226376 -101.233224)
		(end 96.822768 -101.829616)
		(width 0.0889)
		(layer "In2.Cu")
		(net "M_M_MA<0>")
	)
	(segment
		(start 96.822768 -102.921816)
		(end 96.822768 -125.156214)
		(width 0.14224)
		(layer "In2.Cu")
		(net "M_M_MA<0>")
	)
	(segment
		(start 96.032066 -92.655898)
		(end 96.032066 -92.988638)
		(width 0.0889)
		(layer "In2.Cu")
		(net "M_M_MA<0>")
	)
	(segment
		(start 100.665534 -134.57047)
		(end 100.665534 -138.702034)
		(width 0.14224)
		(layer "In2.Cu")
		(net "M_M_MA<0>")
	)
	(segment
		(start 100.632768 -138.7348)
		(end 100.632768 -139.5222)
		(width 0.14224)
		(layer "In2.Cu")
		(net "M_M_MA<0>")
	)
	(segment
		(start 100.710238 -145.00733)
		(end 100.661724 -145.055844)
		(width 0.14224)
		(layer "In2.Cu")
		(net "M_M_MA<0>")
	)
	(segment
		(start 100.61956 -130.645408)
		(end 100.61956 -131.152392)
		(width 0.14224)
		(layer "In2.Cu")
		(net "M_M_MA<0>")
	)
	(segment
		(start 96.020128 -95.414338)
		(end 96.026478 -95.425006)
		(width 0.0889)
		(layer "In2.Cu")
		(net "M_M_MA<0>")
	)
	(segment
		(start 100.607368 -129.771648)
		(end 100.721922 -129.886202)
		(width 0.14224)
		(layer "In2.Cu")
		(net "M_M_MA<0>")
	)
	(segment
		(start 100.661978 -134.566914)
		(end 100.665534 -134.57047)
		(width 0.14224)
		(layer "In2.Cu")
		(net "M_M_MA<0>")
	)
	(segment
		(start 96.015302 -98.377502)
		(end 96.020128 -98.386138)
		(width 0.0889)
		(layer "In2.Cu")
		(net "M_M_MA<0>")
	)
	(segment
		(start 96.015302 -96.396302)
		(end 96.020128 -96.404938)
		(width 0.0889)
		(layer "In2.Cu")
		(net "M_M_MA<0>")
	)
	(segment
		(start 100.661978 -131.19481)
		(end 100.661978 -134.566914)
		(width 0.14224)
		(layer "In2.Cu")
		(net "M_M_MA<0>")
	)
	(segment
		(start 100.632768 -139.5222)
		(end 100.687886 -139.577318)
		(width 0.14224)
		(layer "In2.Cu")
		(net "M_M_MA<0>")
	)
	(segment
		(start 100.710238 -144.34947)
		(end 100.710238 -145.00733)
		(width 0.14224)
		(layer "In2.Cu")
		(net "M_M_MA<0>")
	)
	(segment
		(start 100.633276 -143.250412)
		(end 100.633276 -144.272508)
		(width 0.14224)
		(layer "In2.Cu")
		(net "M_M_MA<0>")
	)
	(segment
		(start 101.099366 -150.785068)
		(end 101.226874 -150.912576)
		(width 0.14224)
		(layer "In2.Cu")
		(net "M_M_MA<0>")
	)
	(segment
		(start 100.633276 -144.272508)
		(end 100.710238 -144.34947)
		(width 0.14224)
		(layer "In2.Cu")
		(net "M_M_MA<0>")
	)
	(segment
		(start 100.607368 -128.940814)
		(end 100.607368 -129.771648)
		(width 0.14224)
		(layer "In2.Cu")
		(net "M_M_MA<0>")
	)
	(segment
		(start 96.015302 -93.424502)
		(end 96.020128 -93.433138)
		(width 0.0889)
		(layer "In2.Cu")
		(net "M_M_MA<0>")
	)
	(segment
		(start 96.015302 -95.405702)
		(end 96.020128 -95.414338)
		(width 0.0889)
		(layer "In2.Cu")
		(net "M_M_MA<0>")
	)
	(segment
		(start 101.226874 -153.415238)
		(end 101.099366 -153.542746)
		(width 0.14224)
		(layer "In2.Cu")
		(net "M_M_MA<0>")
	)
	(segment
		(start 100.721922 -129.886202)
		(end 100.721922 -130.543046)
		(width 0.14224)
		(layer "In2.Cu")
		(net "M_M_MA<0>")
	)
	(segment
		(start 95.508318 -92.13215)
		(end 96.032066 -92.655898)
		(width 0.0889)
		(layer "In2.Cu")
		(net "M_M_MA<0>")
	)
	(segment
		(start 96.020128 -97.395538)
		(end 96.026478 -97.406206)
		(width 0.0889)
		(layer "In2.Cu")
		(net "M_M_MA<0>")
	)
	(arc
		(start 96.026478 -98.396806)
		(mid 96.099276 -98.687569)
		(end 96.020128 -98.976688)
		(width 0.0889)
		(layer "In2.Cu")
		(net "M_M_MA<0>")
	)
	(arc
		(start 96.020128 -94.023688)
		(mid 95.966629 -94.223586)
		(end 96.020128 -94.423484)
		(width 0.0889)
		(layer "In2.Cu")
		(net "M_M_MA<0>")
	)
	(arc
		(start 96.026478 -97.406206)
		(mid 96.099276 -97.696969)
		(end 96.020128 -97.986088)
		(width 0.0889)
		(layer "In2.Cu")
		(net "M_M_MA<0>")
	)
	(arc
		(start 96.020128 -96.004888)
		(mid 95.966658 -96.199951)
		(end 96.015302 -96.396302)
		(width 0.0889)
		(layer "In2.Cu")
		(net "M_M_MA<0>")
	)
	(arc
		(start 96.032066 -92.988638)
		(mid 96.029043 -93.011658)
		(end 96.020128 -93.033088)
		(width 0.0889)
		(layer "In2.Cu")
		(net "M_M_MA<0>")
	)
	(arc
		(start 96.020128 -96.995488)
		(mid 95.966658 -97.190551)
		(end 96.015302 -97.386902)
		(width 0.0889)
		(layer "In2.Cu")
		(net "M_M_MA<0>")
	)
	(arc
		(start 96.020128 -94.423484)
		(mid 96.099259 -94.718886)
		(end 96.020128 -95.014288)
		(width 0.0889)
		(layer "In2.Cu")
		(net "M_M_MA<0>")
	)
	(arc
		(start 96.020128 -97.986088)
		(mid 95.966658 -98.181151)
		(end 96.015302 -98.377502)
		(width 0.0889)
		(layer "In2.Cu")
		(net "M_M_MA<0>")
	)
	(arc
		(start 96.026478 -95.425006)
		(mid 96.099276 -95.715769)
		(end 96.020128 -96.004888)
		(width 0.0889)
		(layer "In2.Cu")
		(net "M_M_MA<0>")
	)
	(arc
		(start 96.020128 -95.014288)
		(mid 95.966658 -95.209351)
		(end 96.015302 -95.405702)
		(width 0.0889)
		(layer "In2.Cu")
		(net "M_M_MA<0>")
	)
	(arc
		(start 96.020128 -93.033088)
		(mid 95.966658 -93.228151)
		(end 96.015302 -93.424502)
		(width 0.0889)
		(layer "In2.Cu")
		(net "M_M_MA<0>")
	)
	(arc
		(start 96.020128 -98.976688)
		(mid 95.966658 -99.171751)
		(end 96.015302 -99.368102)
		(width 0.0889)
		(layer "In2.Cu")
		(net "M_M_MA<0>")
	)
	(arc
		(start 96.020128 -93.433138)
		(mid 96.09935 -93.722256)
		(end 96.026478 -94.01302)
		(width 0.0889)
		(layer "In2.Cu")
		(net "M_M_MA<0>")
	)
	(arc
		(start 96.026478 -96.415606)
		(mid 96.099276 -96.706369)
		(end 96.020128 -96.995488)
		(width 0.0889)
		(layer "In2.Cu")
		(net "M_M_MA<0>")
	)
	(arc
		(start 96.020128 -99.376738)
		(mid 96.110675 -99.504568)
		(end 96.226376 -99.610164)
		(width 0.0889)
		(layer "In2.Cu")
		(net "M_M_MA<0>")
	)
	(segment
		(start 82.343752 -84.812886)
		(end 81.772252 -84.812886)
		(width 0.1651)
		(layer "F.Cu")
		(net "M_M_ECC<7>")
	)
	(segment
		(start 74.749406 -152.273)
		(end 74.749406 -153.542746)
		(width 0.1651)
		(layer "F.Cu")
		(net "M_M_ECC<7>")
	)
	(via
		(at 81.772252 -84.812886)
		(size 0.508)
		(drill 0.254)
		(layers "F.Cu" "B.Cu")
		(net "M_M_ECC<7>")
	)
	(via
		(at 75.59929 -149.533356)
		(size 0.508)
		(drill 0.254)
		(layers "F.Cu" "B.Cu")
		(net "M_M_ECC<7>")
	)
	(via
		(at 74.749406 -153.542746)
		(size 0.508)
		(drill 0.254)
		(layers "F.Cu" "B.Cu")
		(net "M_M_ECC<7>")
	)
	(segment
		(start 75.599544 -147.478496)
		(end 75.59929 -147.478496)
		(width 0.1651)
		(layer "B.Cu")
		(net "M_M_ECC<7>")
	)
	(segment
		(start 75.59929 -147.478496)
		(end 75.59929 -149.533356)
		(width 0.1651)
		(layer "B.Cu")
		(net "M_M_ECC<7>")
	)
	(segment
		(start 75.952096 -136.609328)
		(end 75.952096 -136.212072)
		(width 0.14224)
		(layer "In4.Cu")
		(net "M_M_ECC<7>")
	)
	(segment
		(start 75.952096 -145.813018)
		(end 76.12126 -145.643854)
		(width 0.14224)
		(layer "In4.Cu")
		(net "M_M_ECC<7>")
	)
	(segment
		(start 75.952096 -129.859278)
		(end 75.952096 -126.839472)
		(width 0.14224)
		(layer "In4.Cu")
		(net "M_M_ECC<7>")
	)
	(segment
		(start 75.901296 -141.086078)
		(end 76.180696 -140.806678)
		(width 0.14224)
		(layer "In4.Cu")
		(net "M_M_ECC<7>")
	)
	(segment
		(start 76.155296 -134.757668)
		(end 75.977496 -134.579868)
		(width 0.14224)
		(layer "In4.Cu")
		(net "M_M_ECC<7>")
	)
	(segment
		(start 75.952096 -126.839472)
		(end 76.274168 -126.5174)
		(width 0.14224)
		(layer "In4.Cu")
		(net "M_M_ECC<7>")
	)
	(segment
		(start 82.284062 -88.480138)
		(end 82.279236 -88.471502)
		(width 0.0889)
		(layer "In4.Cu")
		(net "M_M_ECC<7>")
	)
	(segment
		(start 76.12126 -144.313402)
		(end 75.977496 -144.169638)
		(width 0.14224)
		(layer "In4.Cu")
		(net "M_M_ECC<7>")
	)
	(segment
		(start 76.90485 -118.424706)
		(end 76.74991 -118.269766)
		(width 0.14224)
		(layer "In4.Cu")
		(net "M_M_ECC<7>")
	)
	(segment
		(start 75.977496 -134.579868)
		(end 75.977496 -131.408678)
		(width 0.14224)
		(layer "In4.Cu")
		(net "M_M_ECC<7>")
	)
	(segment
		(start 76.247752 -115.986306)
		(end 76.402692 -115.831366)
		(width 0.14224)
		(layer "In4.Cu")
		(net "M_M_ECC<7>")
	)
	(segment
		(start 76.180696 -140.806678)
		(end 76.180696 -139.689078)
		(width 0.14224)
		(layer "In4.Cu")
		(net "M_M_ECC<7>")
	)
	(segment
		(start 76.74991 -114.205766)
		(end 76.90485 -114.050826)
		(width 0.14224)
		(layer "In4.Cu")
		(net "M_M_ECC<7>")
	)
	(segment
		(start 75.952096 -139.460478)
		(end 75.952096 -138.802872)
		(width 0.14224)
		(layer "In4.Cu")
		(net "M_M_ECC<7>")
	)
	(segment
		(start 74.724768 -120.015)
		(end 75.657202 -119.082566)
		(width 0.14224)
		(layer "In4.Cu")
		(net "M_M_ECC<7>")
	)
	(segment
		(start 76.74991 -118.269766)
		(end 76.443078 -118.269766)
		(width 0.14224)
		(layer "In4.Cu")
		(net "M_M_ECC<7>")
	)
	(segment
		(start 82.46872 -102.346252)
		(end 82.46872 -102.23881)
		(width 0.0889)
		(layer "In4.Cu")
		(net "M_M_ECC<7>")
	)
	(segment
		(start 76.90485 -118.927626)
		(end 76.90485 -118.424706)
		(width 0.14224)
		(layer "In4.Cu")
		(net "M_M_ECC<7>")
	)
	(segment
		(start 82.290412 -89.481406)
		(end 82.284062 -89.470738)
		(width 0.0889)
		(layer "In4.Cu")
		(net "M_M_ECC<7>")
	)
	(segment
		(start 76.274676 -118.101364)
		(end 76.274676 -117.598444)
		(width 0.14224)
		(layer "In4.Cu")
		(net "M_M_ECC<7>")
	)
	(segment
		(start 76.864464 -117.302026)
		(end 76.864464 -116.799106)
		(width 0.14224)
		(layer "In4.Cu")
		(net "M_M_ECC<7>")
	)
	(segment
		(start 76.020168 -146.2786)
		(end 75.952096 -146.210528)
		(width 0.14224)
		(layer "In4.Cu")
		(net "M_M_ECC<7>")
	)
	(segment
		(start 76.297536 -112.358424)
		(end 82.703416 -105.952544)
		(width 0.14224)
		(layer "In4.Cu")
		(net "M_M_ECC<7>")
	)
	(segment
		(start 81.964784 -100.927154)
		(end 82.218784 -100.673154)
		(width 0.0889)
		(layer "In4.Cu")
		(net "M_M_ECC<7>")
	)
	(segment
		(start 82.284062 -85.508338)
		(end 82.196432 -85.354414)
		(width 0.0889)
		(layer "In4.Cu")
		(net "M_M_ECC<7>")
	)
	(segment
		(start 82.290412 -85.519006)
		(end 82.284062 -85.508338)
		(width 0.0889)
		(layer "In4.Cu")
		(net "M_M_ECC<7>")
	)
	(segment
		(start 82.290412 -95.425006)
		(end 82.284062 -95.414338)
		(width 0.0889)
		(layer "In4.Cu")
		(net "M_M_ECC<7>")
	)
	(segment
		(start 76.155296 -136.008872)
		(end 76.155296 -134.757668)
		(width 0.14224)
		(layer "In4.Cu")
		(net "M_M_ECC<7>")
	)
	(segment
		(start 75.977496 -144.169638)
		(end 75.977496 -143.806672)
		(width 0.14224)
		(layer "In4.Cu")
		(net "M_M_ECC<7>")
	)
	(segment
		(start 76.709524 -116.644166)
		(end 76.402692 -116.644166)
		(width 0.14224)
		(layer "In4.Cu")
		(net "M_M_ECC<7>")
	)
	(segment
		(start 82.408014 -97.791524)
		(end 82.408014 -96.62668)
		(width 0.0889)
		(layer "In4.Cu")
		(net "M_M_ECC<7>")
	)
	(segment
		(start 76.443078 -118.269766)
		(end 76.274676 -118.101364)
		(width 0.14224)
		(layer "In4.Cu")
		(net "M_M_ECC<7>")
	)
	(segment
		(start 75.977496 -143.806672)
		(end 76.020168 -143.764)
		(width 0.14224)
		(layer "In4.Cu")
		(net "M_M_ECC<7>")
	)
	(segment
		(start 82.290412 -88.490806)
		(end 82.284062 -88.480138)
		(width 0.0889)
		(layer "In4.Cu")
		(net "M_M_ECC<7>")
	)
	(segment
		(start 76.74991 -113.392966)
		(end 76.530708 -113.392966)
		(width 0.14224)
		(layer "In4.Cu")
		(net "M_M_ECC<7>")
	)
	(segment
		(start 76.537058 -114.205766)
		(end 76.74991 -114.205766)
		(width 0.14224)
		(layer "In4.Cu")
		(net "M_M_ECC<7>")
	)
	(segment
		(start 82.284062 -87.489538)
		(end 82.279236 -87.480902)
		(width 0.0889)
		(layer "In4.Cu")
		(net "M_M_ECC<7>")
	)
	(segment
		(start 76.530708 -113.392966)
		(end 76.297536 -113.159794)
		(width 0.14224)
		(layer "In4.Cu")
		(net "M_M_ECC<7>")
	)
	(segment
		(start 82.408014 -96.62668)
		(end 82.279236 -96.396302)
		(width 0.0889)
		(layer "In4.Cu")
		(net "M_M_ECC<7>")
	)
	(segment
		(start 75.952096 -148.531072)
		(end 76.020168 -148.463)
		(width 0.14224)
		(layer "In4.Cu")
		(net "M_M_ECC<7>")
	)
	(segment
		(start 76.180696 -131.205478)
		(end 76.180696 -130.087878)
		(width 0.14224)
		(layer "In4.Cu")
		(net "M_M_ECC<7>")
	)
	(segment
		(start 82.218784 -97.980754)
		(end 82.408014 -97.791524)
		(width 0.0889)
		(layer "In4.Cu")
		(net "M_M_ECC<7>")
	)
	(segment
		(start 82.284062 -95.414338)
		(end 82.279236 -95.405702)
		(width 0.0889)
		(layer "In4.Cu")
		(net "M_M_ECC<7>")
	)
	(segment
		(start 76.382118 -114.360706)
		(end 76.537058 -114.205766)
		(width 0.14224)
		(layer "In4.Cu")
		(net "M_M_ECC<7>")
	)
	(segment
		(start 82.284062 -92.442538)
		(end 82.279236 -92.433902)
		(width 0.0889)
		(layer "In4.Cu")
		(net "M_M_ECC<7>")
	)
	(segment
		(start 76.274676 -117.598444)
		(end 76.416154 -117.456966)
		(width 0.14224)
		(layer "In4.Cu")
		(net "M_M_ECC<7>")
	)
	(segment
		(start 82.284062 -93.433138)
		(end 82.279236 -93.424502)
		(width 0.0889)
		(layer "In4.Cu")
		(net "M_M_ECC<7>")
	)
	(segment
		(start 76.90485 -115.173506)
		(end 76.74991 -115.018566)
		(width 0.14224)
		(layer "In4.Cu")
		(net "M_M_ECC<7>")
	)
	(segment
		(start 76.90485 -113.547906)
		(end 76.74991 -113.392966)
		(width 0.14224)
		(layer "In4.Cu")
		(net "M_M_ECC<7>")
	)
	(segment
		(start 75.952096 -136.212072)
		(end 76.155296 -136.008872)
		(width 0.14224)
		(layer "In4.Cu")
		(net "M_M_ECC<7>")
	)
	(segment
		(start 76.274168 -126.5174)
		(end 76.274168 -125.73)
		(width 0.14224)
		(layer "In4.Cu")
		(net "M_M_ECC<7>")
	)
	(segment
		(start 75.901296 -141.485874)
		(end 75.901296 -141.086078)
		(width 0.14224)
		(layer "In4.Cu")
		(net "M_M_ECC<7>")
	)
	(segment
		(start 76.402692 -116.644166)
		(end 76.247752 -116.489226)
		(width 0.14224)
		(layer "In4.Cu")
		(net "M_M_ECC<7>")
	)
	(segment
		(start 76.74991 -115.018566)
		(end 76.537058 -115.018566)
		(width 0.14224)
		(layer "In4.Cu")
		(net "M_M_ECC<7>")
	)
	(segment
		(start 75.59929 -149.533356)
		(end 75.941174 -149.191472)
		(width 0.14224)
		(layer "In4.Cu")
		(net "M_M_ECC<7>")
	)
	(segment
		(start 82.290412 -91.462606)
		(end 82.284062 -91.451938)
		(width 0.0889)
		(layer "In4.Cu")
		(net "M_M_ECC<7>")
	)
	(segment
		(start 76.416154 -117.456966)
		(end 76.709524 -117.456966)
		(width 0.14224)
		(layer "In4.Cu")
		(net "M_M_ECC<7>")
	)
	(segment
		(start 75.952096 -149.191472)
		(end 75.952096 -148.531072)
		(width 0.14224)
		(layer "In4.Cu")
		(net "M_M_ECC<7>")
	)
	(segment
		(start 76.709524 -117.456966)
		(end 76.864464 -117.302026)
		(width 0.14224)
		(layer "In4.Cu")
		(net "M_M_ECC<7>")
	)
	(segment
		(start 82.703416 -102.580948)
		(end 82.46872 -102.346252)
		(width 0.0889)
		(layer "In4.Cu")
		(net "M_M_ECC<7>")
	)
	(segment
		(start 75.952096 -123.594368)
		(end 74.724768 -122.36704)
		(width 0.14224)
		(layer "In4.Cu")
		(net "M_M_ECC<7>")
	)
	(segment
		(start 76.90485 -114.050826)
		(end 76.90485 -113.547906)
		(width 0.14224)
		(layer "In4.Cu")
		(net "M_M_ECC<7>")
	)
	(segment
		(start 82.46872 -102.23881)
		(end 81.964784 -101.734874)
		(width 0.0889)
		(layer "In4.Cu")
		(net "M_M_ECC<7>")
	)
	(segment
		(start 76.247752 -116.489226)
		(end 76.247752 -115.986306)
		(width 0.14224)
		(layer "In4.Cu")
		(net "M_M_ECC<7>")
	)
	(segment
		(start 74.724768 -122.36704)
		(end 74.724768 -120.015)
		(width 0.14224)
		(layer "In4.Cu")
		(net "M_M_ECC<7>")
	)
	(segment
		(start 76.180696 -139.689078)
		(end 75.952096 -139.460478)
		(width 0.14224)
		(layer "In4.Cu")
		(net "M_M_ECC<7>")
	)
	(segment
		(start 75.952096 -146.210528)
		(end 75.952096 -145.813018)
		(width 0.14224)
		(layer "In4.Cu")
		(net "M_M_ECC<7>")
	)
	(segment
		(start 82.284062 -94.023688)
		(end 82.290412 -94.01302)
		(width 0.0889)
		(layer "In4.Cu")
		(net "M_M_ECC<7>")
	)
	(segment
		(start 82.290412 -92.453206)
		(end 82.284062 -92.442538)
		(width 0.0889)
		(layer "In4.Cu")
		(net "M_M_ECC<7>")
	)
	(segment
		(start 75.657202 -119.082566)
		(end 76.74991 -119.082566)
		(width 0.14224)
		(layer "In4.Cu")
		(net "M_M_ECC<7>")
	)
	(segment
		(start 82.703416 -105.952544)
		(end 82.703416 -102.580948)
		(width 0.14224)
		(layer "In4.Cu")
		(net "M_M_ECC<7>")
	)
	(segment
		(start 76.402692 -115.831366)
		(end 76.74991 -115.831366)
		(width 0.14224)
		(layer "In4.Cu")
		(net "M_M_ECC<7>")
	)
	(segment
		(start 76.020168 -148.463)
		(end 76.020168 -146.2786)
		(width 0.14224)
		(layer "In4.Cu")
		(net "M_M_ECC<7>")
	)
	(segment
		(start 76.12126 -145.643854)
		(end 76.12126 -144.313402)
		(width 0.14224)
		(layer "In4.Cu")
		(net "M_M_ECC<7>")
	)
	(segment
		(start 81.964784 -101.734874)
		(end 81.964784 -100.927154)
		(width 0.0889)
		(layer "In4.Cu")
		(net "M_M_ECC<7>")
	)
	(segment
		(start 75.952096 -125.407928)
		(end 75.952096 -123.594368)
		(width 0.14224)
		(layer "In4.Cu")
		(net "M_M_ECC<7>")
	)
	(segment
		(start 82.290412 -87.500206)
		(end 82.284062 -87.489538)
		(width 0.0889)
		(layer "In4.Cu")
		(net "M_M_ECC<7>")
	)
	(segment
		(start 76.020168 -138.7348)
		(end 76.020168 -136.6774)
		(width 0.14224)
		(layer "In4.Cu")
		(net "M_M_ECC<7>")
	)
	(segment
		(start 76.297536 -113.159794)
		(end 76.297536 -112.358424)
		(width 0.14224)
		(layer "In4.Cu")
		(net "M_M_ECC<7>")
	)
	(segment
		(start 76.74991 -119.082566)
		(end 76.90485 -118.927626)
		(width 0.14224)
		(layer "In4.Cu")
		(net "M_M_ECC<7>")
	)
	(segment
		(start 76.020168 -141.604746)
		(end 75.901296 -141.485874)
		(width 0.14224)
		(layer "In4.Cu")
		(net "M_M_ECC<7>")
	)
	(segment
		(start 82.284062 -89.470738)
		(end 82.279236 -89.462102)
		(width 0.0889)
		(layer "In4.Cu")
		(net "M_M_ECC<7>")
	)
	(segment
		(start 76.180696 -130.087878)
		(end 75.952096 -129.859278)
		(width 0.14224)
		(layer "In4.Cu")
		(net "M_M_ECC<7>")
	)
	(segment
		(start 76.020168 -136.6774)
		(end 75.952096 -136.609328)
		(width 0.14224)
		(layer "In4.Cu")
		(net "M_M_ECC<7>")
	)
	(segment
		(start 75.941174 -149.191472)
		(end 75.952096 -149.191472)
		(width 0.14224)
		(layer "In4.Cu")
		(net "M_M_ECC<7>")
	)
	(segment
		(start 75.977496 -131.408678)
		(end 76.180696 -131.205478)
		(width 0.14224)
		(layer "In4.Cu")
		(net "M_M_ECC<7>")
	)
	(segment
		(start 76.537058 -115.018566)
		(end 76.382118 -114.863626)
		(width 0.14224)
		(layer "In4.Cu")
		(net "M_M_ECC<7>")
	)
	(segment
		(start 76.90485 -115.676426)
		(end 76.90485 -115.173506)
		(width 0.14224)
		(layer "In4.Cu")
		(net "M_M_ECC<7>")
	)
	(segment
		(start 76.864464 -116.799106)
		(end 76.709524 -116.644166)
		(width 0.14224)
		(layer "In4.Cu")
		(net "M_M_ECC<7>")
	)
	(segment
		(start 82.290412 -90.472006)
		(end 82.284062 -90.461338)
		(width 0.0889)
		(layer "In4.Cu")
		(net "M_M_ECC<7>")
	)
	(segment
		(start 76.020168 -143.764)
		(end 76.020168 -141.604746)
		(width 0.14224)
		(layer "In4.Cu")
		(net "M_M_ECC<7>")
	)
	(segment
		(start 82.284062 -86.498938)
		(end 82.279236 -86.490302)
		(width 0.0889)
		(layer "In4.Cu")
		(net "M_M_ECC<7>")
	)
	(segment
		(start 76.74991 -115.831366)
		(end 76.90485 -115.676426)
		(width 0.14224)
		(layer "In4.Cu")
		(net "M_M_ECC<7>")
	)
	(segment
		(start 76.274168 -125.73)
		(end 75.952096 -125.407928)
		(width 0.14224)
		(layer "In4.Cu")
		(net "M_M_ECC<7>")
	)
	(segment
		(start 75.952096 -138.802872)
		(end 76.020168 -138.7348)
		(width 0.14224)
		(layer "In4.Cu")
		(net "M_M_ECC<7>")
	)
	(segment
		(start 82.284062 -91.451938)
		(end 82.279236 -91.443302)
		(width 0.0889)
		(layer "In4.Cu")
		(net "M_M_ECC<7>")
	)
	(segment
		(start 76.382118 -114.863626)
		(end 76.382118 -114.360706)
		(width 0.14224)
		(layer "In4.Cu")
		(net "M_M_ECC<7>")
	)
	(segment
		(start 82.290412 -86.509606)
		(end 82.284062 -86.498938)
		(width 0.0889)
		(layer "In4.Cu")
		(net "M_M_ECC<7>")
	)
	(segment
		(start 82.284062 -90.461338)
		(end 82.279236 -90.452702)
		(width 0.0889)
		(layer "In4.Cu")
		(net "M_M_ECC<7>")
	)
	(segment
		(start 82.218784 -100.673154)
		(end 82.218784 -97.980754)
		(width 0.0889)
		(layer "In4.Cu")
		(net "M_M_ECC<7>")
	)
	(arc
		(start 82.279236 -96.396302)
		(mid 82.230481 -96.19995)
		(end 82.284062 -96.004888)
		(width 0.0889)
		(layer "In4.Cu")
		(net "M_M_ECC<7>")
	)
	(arc
		(start 82.284062 -92.042488)
		(mid 82.363284 -91.75337)
		(end 82.290412 -91.462606)
		(width 0.0889)
		(layer "In4.Cu")
		(net "M_M_ECC<7>")
	)
	(arc
		(start 82.284062 -87.089488)
		(mid 82.363284 -86.80037)
		(end 82.290412 -86.509606)
		(width 0.0889)
		(layer "In4.Cu")
		(net "M_M_ECC<7>")
	)
	(arc
		(start 82.279236 -89.462102)
		(mid 82.230481 -89.26575)
		(end 82.284062 -89.070688)
		(width 0.0889)
		(layer "In4.Cu")
		(net "M_M_ECC<7>")
	)
	(arc
		(start 82.290412 -94.01302)
		(mid 82.36321 -93.722257)
		(end 82.284062 -93.433138)
		(width 0.0889)
		(layer "In4.Cu")
		(net "M_M_ECC<7>")
	)
	(arc
		(start 82.284062 -90.061288)
		(mid 82.363284 -89.77217)
		(end 82.290412 -89.481406)
		(width 0.0889)
		(layer "In4.Cu")
		(net "M_M_ECC<7>")
	)
	(arc
		(start 82.279236 -86.490302)
		(mid 82.230481 -86.29395)
		(end 82.284062 -86.098888)
		(width 0.0889)
		(layer "In4.Cu")
		(net "M_M_ECC<7>")
	)
	(arc
		(start 82.284062 -89.070688)
		(mid 82.363284 -88.78157)
		(end 82.290412 -88.490806)
		(width 0.0889)
		(layer "In4.Cu")
		(net "M_M_ECC<7>")
	)
	(arc
		(start 82.279236 -90.452702)
		(mid 82.230481 -90.25635)
		(end 82.284062 -90.061288)
		(width 0.0889)
		(layer "In4.Cu")
		(net "M_M_ECC<7>")
	)
	(arc
		(start 82.284062 -94.423484)
		(mid 82.230563 -94.223586)
		(end 82.284062 -94.023688)
		(width 0.0889)
		(layer "In4.Cu")
		(net "M_M_ECC<7>")
	)
	(arc
		(start 82.279236 -87.480902)
		(mid 82.230481 -87.28455)
		(end 82.284062 -87.089488)
		(width 0.0889)
		(layer "In4.Cu")
		(net "M_M_ECC<7>")
	)
	(arc
		(start 82.284062 -86.098888)
		(mid 82.363284 -85.80977)
		(end 82.290412 -85.519006)
		(width 0.0889)
		(layer "In4.Cu")
		(net "M_M_ECC<7>")
	)
	(arc
		(start 82.284062 -96.004888)
		(mid 82.363284 -95.71577)
		(end 82.290412 -95.425006)
		(width 0.0889)
		(layer "In4.Cu")
		(net "M_M_ECC<7>")
	)
	(arc
		(start 82.279236 -92.433902)
		(mid 82.230481 -92.23755)
		(end 82.284062 -92.042488)
		(width 0.0889)
		(layer "In4.Cu")
		(net "M_M_ECC<7>")
	)
	(arc
		(start 82.196432 -85.354414)
		(mid 82.004272 -85.068038)
		(end 81.772252 -84.812886)
		(width 0.0889)
		(layer "In4.Cu")
		(net "M_M_ECC<7>")
	)
	(arc
		(start 82.284062 -88.080088)
		(mid 82.363284 -87.79097)
		(end 82.290412 -87.500206)
		(width 0.0889)
		(layer "In4.Cu")
		(net "M_M_ECC<7>")
	)
	(arc
		(start 82.284062 -93.033088)
		(mid 82.363284 -92.74397)
		(end 82.290412 -92.453206)
		(width 0.0889)
		(layer "In4.Cu")
		(net "M_M_ECC<7>")
	)
	(arc
		(start 82.279236 -95.405702)
		(mid 82.230481 -95.20935)
		(end 82.284062 -95.014288)
		(width 0.0889)
		(layer "In4.Cu")
		(net "M_M_ECC<7>")
	)
	(arc
		(start 82.284062 -95.014288)
		(mid 82.363193 -94.718886)
		(end 82.284062 -94.423484)
		(width 0.0889)
		(layer "In4.Cu")
		(net "M_M_ECC<7>")
	)
	(arc
		(start 82.279236 -93.424502)
		(mid 82.230481 -93.22815)
		(end 82.284062 -93.033088)
		(width 0.0889)
		(layer "In4.Cu")
		(net "M_M_ECC<7>")
	)
	(arc
		(start 82.284062 -91.051888)
		(mid 82.363284 -90.76277)
		(end 82.290412 -90.472006)
		(width 0.0889)
		(layer "In4.Cu")
		(net "M_M_ECC<7>")
	)
	(arc
		(start 82.279236 -88.471502)
		(mid 82.230481 -88.27515)
		(end 82.284062 -88.080088)
		(width 0.0889)
		(layer "In4.Cu")
		(net "M_M_ECC<7>")
	)
	(arc
		(start 82.279236 -91.443302)
		(mid 82.230481 -91.24695)
		(end 82.284062 -91.051888)
		(width 0.0889)
		(layer "In4.Cu")
		(net "M_M_ECC<7>")
	)
	(segment
		(start 75.148694 -149.9616)
		(end 75.576938 -149.533356)
		(width 0.14224)
		(layer "In11.Cu")
		(net "M_M_ECC<7>")
	)
	(segment
		(start 75.167744 -151.9174)
		(end 74.910696 -151.660352)
		(width 0.14224)
		(layer "In11.Cu")
		(net "M_M_ECC<7>")
	)
	(segment
		(start 75.576938 -149.533356)
		(end 75.59929 -149.533356)
		(width 0.14224)
		(layer "In11.Cu")
		(net "M_M_ECC<7>")
	)
	(segment
		(start 75.193144 -150.435818)
		(end 75.148694 -150.391368)
		(width 0.14224)
		(layer "In11.Cu")
		(net "M_M_ECC<7>")
	)
	(segment
		(start 75.199494 -153.04135)
		(end 74.910696 -152.752552)
		(width 0.14224)
		(layer "In11.Cu")
		(net "M_M_ECC<7>")
	)
	(segment
		(start 75.021694 -153.542746)
		(end 75.199494 -153.364946)
		(width 0.14224)
		(layer "In11.Cu")
		(net "M_M_ECC<7>")
	)
	(segment
		(start 75.199494 -153.364946)
		(end 75.199494 -153.04135)
		(width 0.14224)
		(layer "In11.Cu")
		(net "M_M_ECC<7>")
	)
	(segment
		(start 75.167744 -152.2222)
		(end 75.167744 -151.9174)
		(width 0.14224)
		(layer "In11.Cu")
		(net "M_M_ECC<7>")
	)
	(segment
		(start 74.749406 -153.542746)
		(end 75.021694 -153.542746)
		(width 0.14224)
		(layer "In11.Cu")
		(net "M_M_ECC<7>")
	)
	(segment
		(start 74.910696 -151.660352)
		(end 74.910696 -151.387048)
		(width 0.14224)
		(layer "In11.Cu")
		(net "M_M_ECC<7>")
	)
	(segment
		(start 74.910696 -151.387048)
		(end 75.193144 -151.1046)
		(width 0.14224)
		(layer "In11.Cu")
		(net "M_M_ECC<7>")
	)
	(segment
		(start 75.148694 -150.391368)
		(end 75.148694 -149.9616)
		(width 0.14224)
		(layer "In11.Cu")
		(net "M_M_ECC<7>")
	)
	(segment
		(start 75.193144 -151.1046)
		(end 75.193144 -150.435818)
		(width 0.14224)
		(layer "In11.Cu")
		(net "M_M_ECC<7>")
	)
	(segment
		(start 74.910696 -152.752552)
		(end 74.910696 -152.479248)
		(width 0.14224)
		(layer "In11.Cu")
		(net "M_M_ECC<7>")
	)
	(segment
		(start 74.910696 -152.479248)
		(end 75.167744 -152.2222)
		(width 0.14224)
		(layer "In11.Cu")
		(net "M_M_ECC<7>")
	)
	(segment
		(start 75.731624 -155.45308)
		(end 75.599544 -155.321)
		(width 0.1651)
		(layer "F.Cu")
		(net "M_M_ECC<6>")
	)
	(segment
		(start 75.731624 -155.67152)
		(end 75.731624 -155.45308)
		(width 0.1651)
		(layer "F.Cu")
		(net "M_M_ECC<6>")
	)
	(segment
		(start 75.599544 -156.87294)
		(end 75.599544 -155.8036)
		(width 0.1651)
		(layer "F.Cu")
		(net "M_M_ECC<6>")
	)
	(segment
		(start 82.343752 -82.83194)
		(end 81.772252 -82.83194)
		(width 0.1651)
		(layer "F.Cu")
		(net "M_M_ECC<6>")
	)
	(segment
		(start 75.599544 -155.321)
		(end 75.599544 -155.118054)
		(width 0.1651)
		(layer "F.Cu")
		(net "M_M_ECC<6>")
	)
	(segment
		(start 75.599544 -155.118054)
		(end 75.59929 -155.1178)
		(width 0.1651)
		(layer "F.Cu")
		(net "M_M_ECC<6>")
	)
	(segment
		(start 75.599544 -155.8036)
		(end 75.731624 -155.67152)
		(width 0.1651)
		(layer "F.Cu")
		(net "M_M_ECC<6>")
	)
	(via
		(at 75.59929 -155.1178)
		(size 0.508)
		(drill 0.254)
		(layers "F.Cu" "B.Cu")
		(net "M_M_ECC<6>")
	)
	(via
		(at 74.749406 -150.814278)
		(size 0.508)
		(drill 0.254)
		(layers "F.Cu" "B.Cu")
		(net "M_M_ECC<6>")
	)
	(via
		(at 81.772252 -82.83194)
		(size 0.508)
		(drill 0.254)
		(layers "F.Cu" "B.Cu")
		(net "M_M_ECC<6>")
	)
	(segment
		(start 74.749406 -152.078436)
		(end 74.749406 -150.814278)
		(width 0.1651)
		(layer "B.Cu")
		(net "M_M_ECC<6>")
	)
	(segment
		(start 82.067654 -85.514688)
		(end 82.123788 -85.612224)
		(width 0.0889)
		(layer "In4.Cu")
		(net "M_M_ECC<6>")
	)
	(segment
		(start 75.181968 -148.4376)
		(end 75.317096 -148.572728)
		(width 0.14224)
		(layer "In4.Cu")
		(net "M_M_ECC<6>")
	)
	(segment
		(start 82.112612 -88.56472)
		(end 82.118962 -88.575388)
		(width 0.0889)
		(layer "In4.Cu")
		(net "M_M_ECC<6>")
	)
	(segment
		(start 82.068416 -105.6894)
		(end 75.677776 -112.08004)
		(width 0.14224)
		(layer "In4.Cu")
		(net "M_M_ECC<6>")
	)
	(segment
		(start 82.118962 -87.584788)
		(end 82.123788 -87.593424)
		(width 0.0889)
		(layer "In4.Cu")
		(net "M_M_ECC<6>")
	)
	(segment
		(start 75.677776 -118.167404)
		(end 74.038968 -119.806212)
		(width 0.14224)
		(layer "In4.Cu")
		(net "M_M_ECC<6>")
	)
	(segment
		(start 81.431892 -84.60232)
		(end 81.425542 -84.612988)
		(width 0.0889)
		(layer "In4.Cu")
		(net "M_M_ECC<6>")
	)
	(segment
		(start 81.425542 -84.612988)
		(end 81.420716 -84.621624)
		(width 0.0889)
		(layer "In4.Cu")
		(net "M_M_ECC<6>")
	)
	(segment
		(start 82.118962 -94.518988)
		(end 82.123788 -94.527624)
		(width 0.0889)
		(layer "In4.Cu")
		(net "M_M_ECC<6>")
	)
	(segment
		(start 81.609184 -85.178392)
		(end 81.769712 -85.266022)
		(width 0.0889)
		(layer "In4.Cu")
		(net "M_M_ECC<6>")
	)
	(segment
		(start 82.118962 -89.565988)
		(end 82.123788 -89.574624)
		(width 0.0889)
		(layer "In4.Cu")
		(net "M_M_ECC<6>")
	)
	(segment
		(start 82.118962 -91.547188)
		(end 82.123788 -91.555824)
		(width 0.0889)
		(layer "In4.Cu")
		(net "M_M_ECC<6>")
	)
	(segment
		(start 75.181968 -127.3048)
		(end 75.226672 -127.349504)
		(width 0.14224)
		(layer "In4.Cu")
		(net "M_M_ECC<6>")
	)
	(segment
		(start 75.317096 -148.934678)
		(end 74.623168 -149.628606)
		(width 0.14224)
		(layer "In4.Cu")
		(net "M_M_ECC<6>")
	)
	(segment
		(start 82.112612 -87.57412)
		(end 82.118962 -87.584788)
		(width 0.0889)
		(layer "In4.Cu")
		(net "M_M_ECC<6>")
	)
	(segment
		(start 82.218022 -96.676718)
		(end 82.218022 -97.712784)
		(width 0.0889)
		(layer "In4.Cu")
		(net "M_M_ECC<6>")
	)
	(segment
		(start 74.993754 -144.39138)
		(end 74.993754 -145.534126)
		(width 0.14224)
		(layer "In4.Cu")
		(net "M_M_ECC<6>")
	)
	(segment
		(start 75.317096 -125.442472)
		(end 75.181968 -125.5776)
		(width 0.14224)
		(layer "In4.Cu")
		(net "M_M_ECC<6>")
	)
	(segment
		(start 82.118962 -88.575388)
		(end 82.123788 -88.584024)
		(width 0.0889)
		(layer "In4.Cu")
		(net "M_M_ECC<6>")
	)
	(segment
		(start 82.112612 -90.54592)
		(end 82.118962 -90.556588)
		(width 0.0889)
		(layer "In4.Cu")
		(net "M_M_ECC<6>")
	)
	(segment
		(start 82.112612 -91.53652)
		(end 82.118962 -91.547188)
		(width 0.0889)
		(layer "In4.Cu")
		(net "M_M_ECC<6>")
	)
	(segment
		(start 82.278728 -102.386384)
		(end 82.068416 -102.596696)
		(width 0.0889)
		(layer "In4.Cu")
		(net "M_M_ECC<6>")
	)
	(segment
		(start 82.218022 -97.712784)
		(end 82.028792 -97.902014)
		(width 0.0889)
		(layer "In4.Cu")
		(net "M_M_ECC<6>")
	)
	(segment
		(start 74.623168 -149.628606)
		(end 74.623168 -150.68804)
		(width 0.14224)
		(layer "In4.Cu")
		(net "M_M_ECC<6>")
	)
	(segment
		(start 75.290934 -146.118834)
		(end 75.181968 -146.2278)
		(width 0.14224)
		(layer "In4.Cu")
		(net "M_M_ECC<6>")
	)
	(segment
		(start 75.181968 -143.6624)
		(end 75.266296 -143.746728)
		(width 0.14224)
		(layer "In4.Cu")
		(net "M_M_ECC<6>")
	)
	(segment
		(start 75.226672 -129.949702)
		(end 75.113896 -130.062478)
		(width 0.14224)
		(layer "In4.Cu")
		(net "M_M_ECC<6>")
	)
	(segment
		(start 75.113896 -130.062478)
		(end 75.113896 -131.307078)
		(width 0.14224)
		(layer "In4.Cu")
		(net "M_M_ECC<6>")
	)
	(segment
		(start 74.038968 -122.5296)
		(end 75.317096 -123.807728)
		(width 0.14224)
		(layer "In4.Cu")
		(net "M_M_ECC<6>")
	)
	(segment
		(start 82.118962 -90.556588)
		(end 82.123788 -90.565224)
		(width 0.0889)
		(layer "In4.Cu")
		(net "M_M_ECC<6>")
	)
	(segment
		(start 82.118962 -92.537788)
		(end 82.123788 -92.546424)
		(width 0.0889)
		(layer "In4.Cu")
		(net "M_M_ECC<6>")
	)
	(segment
		(start 75.215496 -131.408678)
		(end 75.215496 -134.579868)
		(width 0.14224)
		(layer "In4.Cu")
		(net "M_M_ECC<6>")
	)
	(segment
		(start 82.112612 -95.49892)
		(end 82.118962 -95.509588)
		(width 0.0889)
		(layer "In4.Cu")
		(net "M_M_ECC<6>")
	)
	(segment
		(start 82.118962 -93.928438)
		(end 82.112612 -93.939106)
		(width 0.0889)
		(layer "In4.Cu")
		(net "M_M_ECC<6>")
	)
	(segment
		(start 75.226672 -127.349504)
		(end 75.226672 -129.949702)
		(width 0.14224)
		(layer "In4.Cu")
		(net "M_M_ECC<6>")
	)
	(segment
		(start 75.113896 -139.663678)
		(end 75.113896 -140.908278)
		(width 0.14224)
		(layer "In4.Cu")
		(net "M_M_ECC<6>")
	)
	(segment
		(start 81.774792 -100.848414)
		(end 81.774792 -101.813614)
		(width 0.0889)
		(layer "In4.Cu")
		(net "M_M_ECC<6>")
	)
	(segment
		(start 75.113896 -134.681468)
		(end 75.113896 -136.101328)
		(width 0.14224)
		(layer "In4.Cu")
		(net "M_M_ECC<6>")
	)
	(segment
		(start 75.181968 -125.5776)
		(end 75.181968 -127.3048)
		(width 0.14224)
		(layer "In4.Cu")
		(net "M_M_ECC<6>")
	)
	(segment
		(start 81.769712 -85.266022)
		(end 82.067654 -85.514688)
		(width 0.0889)
		(layer "In4.Cu")
		(net "M_M_ECC<6>")
	)
	(segment
		(start 82.278728 -102.31755)
		(end 82.278728 -102.386384)
		(width 0.0889)
		(layer "In4.Cu")
		(net "M_M_ECC<6>")
	)
	(segment
		(start 75.181968 -141.613128)
		(end 75.181968 -143.6624)
		(width 0.14224)
		(layer "In4.Cu")
		(net "M_M_ECC<6>")
	)
	(segment
		(start 74.993754 -145.534126)
		(end 75.290934 -145.831306)
		(width 0.14224)
		(layer "In4.Cu")
		(net "M_M_ECC<6>")
	)
	(segment
		(start 75.266296 -141.5288)
		(end 75.181968 -141.613128)
		(width 0.14224)
		(layer "In4.Cu")
		(net "M_M_ECC<6>")
	)
	(segment
		(start 82.112612 -96.48952)
		(end 82.218022 -96.676718)
		(width 0.0889)
		(layer "In4.Cu")
		(net "M_M_ECC<6>")
	)
	(segment
		(start 75.677776 -112.08004)
		(end 75.677776 -118.167404)
		(width 0.14224)
		(layer "In4.Cu")
		(net "M_M_ECC<6>")
	)
	(segment
		(start 82.118962 -95.509588)
		(end 82.123788 -95.518224)
		(width 0.0889)
		(layer "In4.Cu")
		(net "M_M_ECC<6>")
	)
	(segment
		(start 81.425542 -83.622388)
		(end 81.420716 -83.631024)
		(width 0.0889)
		(layer "In4.Cu")
		(net "M_M_ECC<6>")
	)
	(segment
		(start 82.028792 -97.902014)
		(end 82.028792 -100.594414)
		(width 0.0889)
		(layer "In4.Cu")
		(net "M_M_ECC<6>")
	)
	(segment
		(start 75.181968 -146.2278)
		(end 75.181968 -148.4376)
		(width 0.14224)
		(layer "In4.Cu")
		(net "M_M_ECC<6>")
	)
	(segment
		(start 75.226418 -136.21385)
		(end 75.226418 -139.551156)
		(width 0.14224)
		(layer "In4.Cu")
		(net "M_M_ECC<6>")
	)
	(segment
		(start 81.772252 -82.83194)
		(end 81.44256 -83.593178)
		(width 0.0889)
		(layer "In4.Cu")
		(net "M_M_ECC<6>")
	)
	(segment
		(start 74.038968 -119.806212)
		(end 74.038968 -122.5296)
		(width 0.14224)
		(layer "In4.Cu")
		(net "M_M_ECC<6>")
	)
	(segment
		(start 75.290934 -145.831306)
		(end 75.290934 -146.118834)
		(width 0.14224)
		(layer "In4.Cu")
		(net "M_M_ECC<6>")
	)
	(segment
		(start 75.317096 -123.807728)
		(end 75.317096 -125.442472)
		(width 0.14224)
		(layer "In4.Cu")
		(net "M_M_ECC<6>")
	)
	(segment
		(start 75.266296 -143.746728)
		(end 75.266296 -144.118838)
		(width 0.14224)
		(layer "In4.Cu")
		(net "M_M_ECC<6>")
	)
	(segment
		(start 75.266296 -141.060678)
		(end 75.266296 -141.5288)
		(width 0.14224)
		(layer "In4.Cu")
		(net "M_M_ECC<6>")
	)
	(segment
		(start 82.118962 -86.594188)
		(end 82.123788 -86.602824)
		(width 0.0889)
		(layer "In4.Cu")
		(net "M_M_ECC<6>")
	)
	(segment
		(start 74.623168 -150.68804)
		(end 74.749406 -150.814278)
		(width 0.14224)
		(layer "In4.Cu")
		(net "M_M_ECC<6>")
	)
	(segment
		(start 82.112612 -89.55532)
		(end 82.118962 -89.565988)
		(width 0.0889)
		(layer "In4.Cu")
		(net "M_M_ECC<6>")
	)
	(segment
		(start 75.226418 -139.551156)
		(end 75.113896 -139.663678)
		(width 0.14224)
		(layer "In4.Cu")
		(net "M_M_ECC<6>")
	)
	(segment
		(start 75.113896 -136.101328)
		(end 75.226418 -136.21385)
		(width 0.14224)
		(layer "In4.Cu")
		(net "M_M_ECC<6>")
	)
	(segment
		(start 81.44256 -83.593178)
		(end 81.425542 -83.622388)
		(width 0.0889)
		(layer "In4.Cu")
		(net "M_M_ECC<6>")
	)
	(segment
		(start 75.113896 -131.307078)
		(end 75.215496 -131.408678)
		(width 0.14224)
		(layer "In4.Cu")
		(net "M_M_ECC<6>")
	)
	(segment
		(start 82.028792 -100.594414)
		(end 81.774792 -100.848414)
		(width 0.0889)
		(layer "In4.Cu")
		(net "M_M_ECC<6>")
	)
	(segment
		(start 81.774792 -101.813614)
		(end 82.278728 -102.31755)
		(width 0.0889)
		(layer "In4.Cu")
		(net "M_M_ECC<6>")
	)
	(segment
		(start 75.215496 -134.579868)
		(end 75.113896 -134.681468)
		(width 0.14224)
		(layer "In4.Cu")
		(net "M_M_ECC<6>")
	)
	(segment
		(start 82.112612 -92.52712)
		(end 82.118962 -92.537788)
		(width 0.0889)
		(layer "In4.Cu")
		(net "M_M_ECC<6>")
	)
	(segment
		(start 82.068416 -102.596696)
		(end 82.068416 -105.6894)
		(width 0.14224)
		(layer "In4.Cu")
		(net "M_M_ECC<6>")
	)
	(segment
		(start 75.266296 -144.118838)
		(end 74.993754 -144.39138)
		(width 0.14224)
		(layer "In4.Cu")
		(net "M_M_ECC<6>")
	)
	(segment
		(start 75.113896 -140.908278)
		(end 75.266296 -141.060678)
		(width 0.14224)
		(layer "In4.Cu")
		(net "M_M_ECC<6>")
	)
	(segment
		(start 82.112612 -86.58352)
		(end 82.118962 -86.594188)
		(width 0.0889)
		(layer "In4.Cu")
		(net "M_M_ECC<6>")
	)
	(segment
		(start 75.317096 -148.572728)
		(end 75.317096 -148.934678)
		(width 0.14224)
		(layer "In4.Cu")
		(net "M_M_ECC<6>")
	)
	(arc
		(start 82.118962 -92.937838)
		(mid 82.039831 -93.23324)
		(end 82.118962 -93.528642)
		(width 0.0889)
		(layer "In4.Cu")
		(net "M_M_ECC<6>")
	)
	(arc
		(start 82.123788 -90.565224)
		(mid 82.172543 -90.761576)
		(end 82.118962 -90.956638)
		(width 0.0889)
		(layer "In4.Cu")
		(net "M_M_ECC<6>")
	)
	(arc
		(start 81.420716 -84.621624)
		(mid 81.393188 -84.941217)
		(end 81.609184 -85.178392)
		(width 0.0889)
		(layer "In4.Cu")
		(net "M_M_ECC<6>")
	)
	(arc
		(start 82.118962 -86.994238)
		(mid 82.03974 -87.283356)
		(end 82.112612 -87.57412)
		(width 0.0889)
		(layer "In4.Cu")
		(net "M_M_ECC<6>")
	)
	(arc
		(start 82.118962 -91.947238)
		(mid 82.03974 -92.236356)
		(end 82.112612 -92.52712)
		(width 0.0889)
		(layer "In4.Cu")
		(net "M_M_ECC<6>")
	)
	(arc
		(start 81.420716 -83.631024)
		(mid 81.371961 -83.827376)
		(end 81.425542 -84.022438)
		(width 0.0889)
		(layer "In4.Cu")
		(net "M_M_ECC<6>")
	)
	(arc
		(start 82.118962 -88.975438)
		(mid 82.03974 -89.264556)
		(end 82.112612 -89.55532)
		(width 0.0889)
		(layer "In4.Cu")
		(net "M_M_ECC<6>")
	)
	(arc
		(start 82.118962 -90.956638)
		(mid 82.03974 -91.245756)
		(end 82.112612 -91.53652)
		(width 0.0889)
		(layer "In4.Cu")
		(net "M_M_ECC<6>")
	)
	(arc
		(start 82.123788 -88.584024)
		(mid 82.172543 -88.780376)
		(end 82.118962 -88.975438)
		(width 0.0889)
		(layer "In4.Cu")
		(net "M_M_ECC<6>")
	)
	(arc
		(start 82.123788 -85.612224)
		(mid 82.172543 -85.808576)
		(end 82.118962 -86.003638)
		(width 0.0889)
		(layer "In4.Cu")
		(net "M_M_ECC<6>")
	)
	(arc
		(start 82.118962 -94.919038)
		(mid 82.03974 -95.208156)
		(end 82.112612 -95.49892)
		(width 0.0889)
		(layer "In4.Cu")
		(net "M_M_ECC<6>")
	)
	(arc
		(start 82.112612 -93.939106)
		(mid 82.039814 -94.229869)
		(end 82.118962 -94.518988)
		(width 0.0889)
		(layer "In4.Cu")
		(net "M_M_ECC<6>")
	)
	(arc
		(start 82.118962 -87.984838)
		(mid 82.03974 -88.273956)
		(end 82.112612 -88.56472)
		(width 0.0889)
		(layer "In4.Cu")
		(net "M_M_ECC<6>")
	)
	(arc
		(start 82.123788 -87.593424)
		(mid 82.172543 -87.789776)
		(end 82.118962 -87.984838)
		(width 0.0889)
		(layer "In4.Cu")
		(net "M_M_ECC<6>")
	)
	(arc
		(start 82.123788 -95.518224)
		(mid 82.172543 -95.714576)
		(end 82.118962 -95.909638)
		(width 0.0889)
		(layer "In4.Cu")
		(net "M_M_ECC<6>")
	)
	(arc
		(start 82.123788 -86.602824)
		(mid 82.172543 -86.799176)
		(end 82.118962 -86.994238)
		(width 0.0889)
		(layer "In4.Cu")
		(net "M_M_ECC<6>")
	)
	(arc
		(start 82.118962 -93.528642)
		(mid 82.172461 -93.72854)
		(end 82.118962 -93.928438)
		(width 0.0889)
		(layer "In4.Cu")
		(net "M_M_ECC<6>")
	)
	(arc
		(start 82.123788 -92.546424)
		(mid 82.172543 -92.742776)
		(end 82.118962 -92.937838)
		(width 0.0889)
		(layer "In4.Cu")
		(net "M_M_ECC<6>")
	)
	(arc
		(start 81.425542 -84.022438)
		(mid 81.504764 -84.311556)
		(end 81.431892 -84.60232)
		(width 0.0889)
		(layer "In4.Cu")
		(net "M_M_ECC<6>")
	)
	(arc
		(start 82.123788 -89.574624)
		(mid 82.172543 -89.770976)
		(end 82.118962 -89.966038)
		(width 0.0889)
		(layer "In4.Cu")
		(net "M_M_ECC<6>")
	)
	(arc
		(start 82.118962 -86.003638)
		(mid 82.03974 -86.292756)
		(end 82.112612 -86.58352)
		(width 0.0889)
		(layer "In4.Cu")
		(net "M_M_ECC<6>")
	)
	(arc
		(start 82.118962 -95.909638)
		(mid 82.03974 -96.198756)
		(end 82.112612 -96.48952)
		(width 0.0889)
		(layer "In4.Cu")
		(net "M_M_ECC<6>")
	)
	(arc
		(start 82.123788 -94.527624)
		(mid 82.172543 -94.723976)
		(end 82.118962 -94.919038)
		(width 0.0889)
		(layer "In4.Cu")
		(net "M_M_ECC<6>")
	)
	(arc
		(start 82.123788 -91.555824)
		(mid 82.172543 -91.752176)
		(end 82.118962 -91.947238)
		(width 0.0889)
		(layer "In4.Cu")
		(net "M_M_ECC<6>")
	)
	(arc
		(start 82.118962 -89.966038)
		(mid 82.03974 -90.255156)
		(end 82.112612 -90.54592)
		(width 0.0889)
		(layer "In4.Cu")
		(net "M_M_ECC<6>")
	)
	(segment
		(start 74.316336 -153.834846)
		(end 74.316336 -151.247348)
		(width 0.14224)
		(layer "In11.Cu")
		(net "M_M_ECC<6>")
	)
	(segment
		(start 74.316336 -151.247348)
		(end 74.749406 -150.814278)
		(width 0.14224)
		(layer "In11.Cu")
		(net "M_M_ECC<6>")
	)
	(segment
		(start 75.59929 -155.1178)
		(end 74.316336 -153.834846)
		(width 0.14224)
		(layer "In11.Cu")
		(net "M_M_ECC<6>")
	)
	(segment
		(start 68.799456 -152.273)
		(end 68.799456 -153.542746)
		(width 0.1651)
		(layer "F.Cu")
		(net "M_M_ECC<5>")
	)
	(segment
		(start 79.768192 -84.31784)
		(end 79.196692 -84.31784)
		(width 0.1651)
		(layer "F.Cu")
		(net "M_M_ECC<5>")
	)
	(via
		(at 69.57314 -149.533356)
		(size 0.508)
		(drill 0.254)
		(layers "F.Cu" "B.Cu")
		(net "M_M_ECC<5>")
	)
	(via
		(at 68.799456 -153.542746)
		(size 0.508)
		(drill 0.254)
		(layers "F.Cu" "B.Cu")
		(net "M_M_ECC<5>")
	)
	(via
		(at 79.196692 -84.31784)
		(size 0.508)
		(drill 0.254)
		(layers "F.Cu" "B.Cu")
		(net "M_M_ECC<5>")
	)
	(segment
		(start 69.64934 -147.478496)
		(end 69.64934 -149.457156)
		(width 0.1651)
		(layer "B.Cu")
		(net "M_M_ECC<5>")
	)
	(segment
		(start 69.64934 -149.457156)
		(end 69.57314 -149.533356)
		(width 0.1651)
		(layer "B.Cu")
		(net "M_M_ECC<5>")
	)
	(segment
		(start 69.983096 -141.035278)
		(end 69.983096 -141.4526)
		(width 0.14224)
		(layer "In4.Cu")
		(net "M_M_ECC<5>")
	)
	(segment
		(start 77.748384 -101.443282)
		(end 77.98435 -101.679248)
		(width 0.0889)
		(layer "In4.Cu")
		(net "M_M_ECC<5>")
	)
	(segment
		(start 78.845156 -88.471502)
		(end 78.849982 -88.480138)
		(width 0.0889)
		(layer "In4.Cu")
		(net "M_M_ECC<5>")
	)
	(segment
		(start 68.931028 -122.752866)
		(end 69.14769 -122.969528)
		(width 0.14224)
		(layer "In4.Cu")
		(net "M_M_ECC<5>")
	)
	(segment
		(start 78.928214 -98.518472)
		(end 78.928214 -98.992436)
		(width 0.0889)
		(layer "In4.Cu")
		(net "M_M_ECC<5>")
	)
	(segment
		(start 69.120766 -122.156728)
		(end 68.931028 -122.346466)
		(width 0.14224)
		(layer "In4.Cu")
		(net "M_M_ECC<5>")
	)
	(segment
		(start 78.849982 -96.404938)
		(end 78.856332 -96.415606)
		(width 0.0889)
		(layer "In4.Cu")
		(net "M_M_ECC<5>")
	)
	(segment
		(start 69.983096 -131.434078)
		(end 69.983096 -131.8514)
		(width 0.14224)
		(layer "In4.Cu")
		(net "M_M_ECC<5>")
	)
	(segment
		(start 78.866746 -85.079586)
		(end 78.849982 -85.108288)
		(width 0.0889)
		(layer "In4.Cu")
		(net "M_M_ECC<5>")
	)
	(segment
		(start 78.845156 -96.396302)
		(end 78.849982 -96.404938)
		(width 0.0889)
		(layer "In4.Cu")
		(net "M_M_ECC<5>")
	)
	(segment
		(start 78.10373 -100.470208)
		(end 77.748384 -100.825554)
		(width 0.0889)
		(layer "In4.Cu")
		(net "M_M_ECC<5>")
	)
	(segment
		(start 69.957696 -136.525)
		(end 70.076568 -136.643872)
		(width 0.14224)
		(layer "In4.Cu")
		(net "M_M_ECC<5>")
	)
	(segment
		(start 77.98435 -104.233218)
		(end 70.152768 -112.0648)
		(width 0.14224)
		(layer "In4.Cu")
		(net "M_M_ECC<5>")
	)
	(segment
		(start 77.98435 -101.679248)
		(end 77.98435 -104.233218)
		(width 0.14224)
		(layer "In4.Cu")
		(net "M_M_ECC<5>")
	)
	(segment
		(start 78.849982 -85.508338)
		(end 78.856332 -85.519006)
		(width 0.0889)
		(layer "In4.Cu")
		(net "M_M_ECC<5>")
	)
	(segment
		(start 69.983096 -134.103872)
		(end 69.983096 -134.617968)
		(width 0.14224)
		(layer "In4.Cu")
		(net "M_M_ECC<5>")
	)
	(segment
		(start 69.957696 -145.607024)
		(end 69.957696 -146.235928)
		(width 0.14224)
		(layer "In4.Cu")
		(net "M_M_ECC<5>")
	)
	(segment
		(start 70.076568 -143.6878)
		(end 69.983096 -143.781272)
		(width 0.14224)
		(layer "In4.Cu")
		(net "M_M_ECC<5>")
	)
	(segment
		(start 70.076568 -141.546072)
		(end 70.076568 -143.6878)
		(width 0.14224)
		(layer "In4.Cu")
		(net "M_M_ECC<5>")
	)
	(segment
		(start 70.228968 -125.603)
		(end 70.051168 -125.7808)
		(width 0.14224)
		(layer "In4.Cu")
		(net "M_M_ECC<5>")
	)
	(segment
		(start 70.228968 -123.124976)
		(end 70.228968 -125.603)
		(width 0.14224)
		(layer "In4.Cu")
		(net "M_M_ECC<5>")
	)
	(segment
		(start 70.051168 -128.5748)
		(end 69.993764 -128.632204)
		(width 0.14224)
		(layer "In4.Cu")
		(net "M_M_ECC<5>")
	)
	(segment
		(start 70.046596 -140.971778)
		(end 69.983096 -141.035278)
		(width 0.14224)
		(layer "In4.Cu")
		(net "M_M_ECC<5>")
	)
	(segment
		(start 70.076568 -148.4376)
		(end 69.957696 -148.556472)
		(width 0.14224)
		(layer "In4.Cu")
		(net "M_M_ECC<5>")
	)
	(segment
		(start 78.845156 -87.480902)
		(end 78.849982 -87.489538)
		(width 0.0889)
		(layer "In4.Cu")
		(net "M_M_ECC<5>")
	)
	(segment
		(start 70.152768 -121.953528)
		(end 69.949568 -122.156728)
		(width 0.14224)
		(layer "In4.Cu")
		(net "M_M_ECC<5>")
	)
	(segment
		(start 70.076568 -134.0104)
		(end 69.983096 -134.103872)
		(width 0.14224)
		(layer "In4.Cu")
		(net "M_M_ECC<5>")
	)
	(segment
		(start 69.983096 -134.617968)
		(end 70.046596 -134.681468)
		(width 0.14224)
		(layer "In4.Cu")
		(net "M_M_ECC<5>")
	)
	(segment
		(start 69.983096 -144.271238)
		(end 70.110096 -144.398238)
		(width 0.14224)
		(layer "In4.Cu")
		(net "M_M_ECC<5>")
	)
	(segment
		(start 78.849982 -89.470738)
		(end 78.856332 -89.481406)
		(width 0.0889)
		(layer "In4.Cu")
		(net "M_M_ECC<5>")
	)
	(segment
		(start 78.849982 -88.480138)
		(end 78.856332 -88.490806)
		(width 0.0889)
		(layer "In4.Cu")
		(net "M_M_ECC<5>")
	)
	(segment
		(start 69.164962 -119.496586)
		(end 69.164962 -119.999506)
		(width 0.14224)
		(layer "In4.Cu")
		(net "M_M_ECC<5>")
	)
	(segment
		(start 70.046596 -135.938768)
		(end 69.957696 -136.027668)
		(width 0.14224)
		(layer "In4.Cu")
		(net "M_M_ECC<5>")
	)
	(segment
		(start 69.306948 -119.3546)
		(end 69.164962 -119.496586)
		(width 0.14224)
		(layer "In4.Cu")
		(net "M_M_ECC<5>")
	)
	(segment
		(start 70.046596 -129.983738)
		(end 70.046596 -131.370578)
		(width 0.14224)
		(layer "In4.Cu")
		(net "M_M_ECC<5>")
	)
	(segment
		(start 78.845156 -92.433902)
		(end 78.849982 -92.442538)
		(width 0.0889)
		(layer "In4.Cu")
		(net "M_M_ECC<5>")
	)
	(segment
		(start 69.14769 -122.969528)
		(end 70.07352 -122.969528)
		(width 0.14224)
		(layer "In4.Cu")
		(net "M_M_ECC<5>")
	)
	(segment
		(start 69.164962 -119.999506)
		(end 69.319902 -120.154446)
		(width 0.14224)
		(layer "In4.Cu")
		(net "M_M_ECC<5>")
	)
	(segment
		(start 69.957696 -138.955272)
		(end 69.957696 -139.41679)
		(width 0.14224)
		(layer "In4.Cu")
		(net "M_M_ECC<5>")
	)
	(segment
		(start 70.110096 -144.398238)
		(end 70.110096 -145.454624)
		(width 0.14224)
		(layer "In4.Cu")
		(net "M_M_ECC<5>")
	)
	(segment
		(start 68.931028 -122.346466)
		(end 68.931028 -122.752866)
		(width 0.14224)
		(layer "In4.Cu")
		(net "M_M_ECC<5>")
	)
	(segment
		(start 69.957696 -136.027668)
		(end 69.957696 -136.525)
		(width 0.14224)
		(layer "In4.Cu")
		(net "M_M_ECC<5>")
	)
	(segment
		(start 78.845156 -98.377502)
		(end 78.856332 -98.397568)
		(width 0.0889)
		(layer "In4.Cu")
		(net "M_M_ECC<5>")
	)
	(segment
		(start 70.046596 -139.50569)
		(end 70.046596 -140.971778)
		(width 0.14224)
		(layer "In4.Cu")
		(net "M_M_ECC<5>")
	)
	(segment
		(start 78.845156 -85.499702)
		(end 78.849982 -85.508338)
		(width 0.0889)
		(layer "In4.Cu")
		(net "M_M_ECC<5>")
	)
	(segment
		(start 69.983096 -141.4526)
		(end 70.076568 -141.546072)
		(width 0.14224)
		(layer "In4.Cu")
		(net "M_M_ECC<5>")
	)
	(segment
		(start 70.076568 -136.643872)
		(end 70.076568 -138.8364)
		(width 0.14224)
		(layer "In4.Cu")
		(net "M_M_ECC<5>")
	)
	(segment
		(start 78.856332 -94.01302)
		(end 78.849982 -94.023688)
		(width 0.0889)
		(layer "In4.Cu")
		(net "M_M_ECC<5>")
	)
	(segment
		(start 70.076568 -131.944872)
		(end 70.076568 -134.0104)
		(width 0.14224)
		(layer "In4.Cu")
		(net "M_M_ECC<5>")
	)
	(segment
		(start 69.319902 -120.154446)
		(end 69.997828 -120.154446)
		(width 0.14224)
		(layer "In4.Cu")
		(net "M_M_ECC<5>")
	)
	(segment
		(start 69.993764 -128.632204)
		(end 69.993764 -129.930906)
		(width 0.14224)
		(layer "In4.Cu")
		(net "M_M_ECC<5>")
	)
	(segment
		(start 69.984874 -119.3546)
		(end 69.306948 -119.3546)
		(width 0.14224)
		(layer "In4.Cu")
		(net "M_M_ECC<5>")
	)
	(segment
		(start 70.051168 -125.7808)
		(end 70.051168 -128.5748)
		(width 0.14224)
		(layer "In4.Cu")
		(net "M_M_ECC<5>")
	)
	(segment
		(start 69.983096 -131.8514)
		(end 70.076568 -131.944872)
		(width 0.14224)
		(layer "In4.Cu")
		(net "M_M_ECC<5>")
	)
	(segment
		(start 78.849982 -92.442538)
		(end 78.856332 -92.453206)
		(width 0.0889)
		(layer "In4.Cu")
		(net "M_M_ECC<5>")
	)
	(segment
		(start 78.849982 -90.461338)
		(end 78.856332 -90.472006)
		(width 0.0889)
		(layer "In4.Cu")
		(net "M_M_ECC<5>")
	)
	(segment
		(start 70.110096 -145.454624)
		(end 69.957696 -145.607024)
		(width 0.14224)
		(layer "In4.Cu")
		(net "M_M_ECC<5>")
	)
	(segment
		(start 78.849982 -87.489538)
		(end 78.856332 -87.500206)
		(width 0.0889)
		(layer "In4.Cu")
		(net "M_M_ECC<5>")
	)
	(segment
		(start 69.957696 -139.41679)
		(end 70.046596 -139.50569)
		(width 0.14224)
		(layer "In4.Cu")
		(net "M_M_ECC<5>")
	)
	(segment
		(start 78.849982 -97.395538)
		(end 78.856332 -97.406206)
		(width 0.0889)
		(layer "In4.Cu")
		(net "M_M_ECC<5>")
	)
	(segment
		(start 70.076568 -138.8364)
		(end 69.957696 -138.955272)
		(width 0.14224)
		(layer "In4.Cu")
		(net "M_M_ECC<5>")
	)
	(segment
		(start 78.845156 -86.490302)
		(end 78.849982 -86.498938)
		(width 0.0889)
		(layer "In4.Cu")
		(net "M_M_ECC<5>")
	)
	(segment
		(start 78.856332 -98.397568)
		(end 78.928214 -98.518472)
		(width 0.0889)
		(layer "In4.Cu")
		(net "M_M_ECC<5>")
	)
	(segment
		(start 69.983096 -143.781272)
		(end 69.983096 -144.271238)
		(width 0.14224)
		(layer "In4.Cu")
		(net "M_M_ECC<5>")
	)
	(segment
		(start 70.076568 -146.3548)
		(end 70.076568 -148.4376)
		(width 0.14224)
		(layer "In4.Cu")
		(net "M_M_ECC<5>")
	)
	(segment
		(start 78.928214 -98.992436)
		(end 78.10373 -99.81692)
		(width 0.0889)
		(layer "In4.Cu")
		(net "M_M_ECC<5>")
	)
	(segment
		(start 79.196692 -84.31784)
		(end 78.866746 -85.079586)
		(width 0.0889)
		(layer "In4.Cu")
		(net "M_M_ECC<5>")
	)
	(segment
		(start 78.849982 -86.498938)
		(end 78.856332 -86.509606)
		(width 0.0889)
		(layer "In4.Cu")
		(net "M_M_ECC<5>")
	)
	(segment
		(start 70.152768 -120.309386)
		(end 70.152768 -121.953528)
		(width 0.14224)
		(layer "In4.Cu")
		(net "M_M_ECC<5>")
	)
	(segment
		(start 78.845156 -95.405702)
		(end 78.849982 -95.414338)
		(width 0.0889)
		(layer "In4.Cu")
		(net "M_M_ECC<5>")
	)
	(segment
		(start 70.046596 -131.370578)
		(end 69.983096 -131.434078)
		(width 0.14224)
		(layer "In4.Cu")
		(net "M_M_ECC<5>")
	)
	(segment
		(start 77.748384 -100.825554)
		(end 77.748384 -101.443282)
		(width 0.0889)
		(layer "In4.Cu")
		(net "M_M_ECC<5>")
	)
	(segment
		(start 69.957696 -149.1488)
		(end 69.57314 -149.533356)
		(width 0.14224)
		(layer "In4.Cu")
		(net "M_M_ECC<5>")
	)
	(segment
		(start 78.849982 -91.451938)
		(end 78.856332 -91.462606)
		(width 0.0889)
		(layer "In4.Cu")
		(net "M_M_ECC<5>")
	)
	(segment
		(start 70.046596 -134.681468)
		(end 70.046596 -135.938768)
		(width 0.14224)
		(layer "In4.Cu")
		(net "M_M_ECC<5>")
	)
	(segment
		(start 69.993764 -129.930906)
		(end 70.046596 -129.983738)
		(width 0.14224)
		(layer "In4.Cu")
		(net "M_M_ECC<5>")
	)
	(segment
		(start 70.152768 -119.186706)
		(end 69.984874 -119.3546)
		(width 0.14224)
		(layer "In4.Cu")
		(net "M_M_ECC<5>")
	)
	(segment
		(start 69.957696 -146.235928)
		(end 70.076568 -146.3548)
		(width 0.14224)
		(layer "In4.Cu")
		(net "M_M_ECC<5>")
	)
	(segment
		(start 78.845156 -93.424502)
		(end 78.849982 -93.433138)
		(width 0.0889)
		(layer "In4.Cu")
		(net "M_M_ECC<5>")
	)
	(segment
		(start 78.845156 -97.386902)
		(end 78.849982 -97.395538)
		(width 0.0889)
		(layer "In4.Cu")
		(net "M_M_ECC<5>")
	)
	(segment
		(start 69.957696 -148.556472)
		(end 69.957696 -149.1488)
		(width 0.14224)
		(layer "In4.Cu")
		(net "M_M_ECC<5>")
	)
	(segment
		(start 78.849982 -95.414338)
		(end 78.856332 -95.425006)
		(width 0.0889)
		(layer "In4.Cu")
		(net "M_M_ECC<5>")
	)
	(segment
		(start 69.949568 -122.156728)
		(end 69.120766 -122.156728)
		(width 0.14224)
		(layer "In4.Cu")
		(net "M_M_ECC<5>")
	)
	(segment
		(start 78.845156 -90.452702)
		(end 78.849982 -90.461338)
		(width 0.0889)
		(layer "In4.Cu")
		(net "M_M_ECC<5>")
	)
	(segment
		(start 78.10373 -99.81692)
		(end 78.10373 -100.470208)
		(width 0.0889)
		(layer "In4.Cu")
		(net "M_M_ECC<5>")
	)
	(segment
		(start 78.845156 -91.443302)
		(end 78.849982 -91.451938)
		(width 0.0889)
		(layer "In4.Cu")
		(net "M_M_ECC<5>")
	)
	(segment
		(start 69.997828 -120.154446)
		(end 70.152768 -120.309386)
		(width 0.14224)
		(layer "In4.Cu")
		(net "M_M_ECC<5>")
	)
	(segment
		(start 70.152768 -112.0648)
		(end 70.152768 -119.186706)
		(width 0.14224)
		(layer "In4.Cu")
		(net "M_M_ECC<5>")
	)
	(segment
		(start 78.845156 -89.462102)
		(end 78.849982 -89.470738)
		(width 0.0889)
		(layer "In4.Cu")
		(net "M_M_ECC<5>")
	)
	(segment
		(start 70.07352 -122.969528)
		(end 70.228968 -123.124976)
		(width 0.14224)
		(layer "In4.Cu")
		(net "M_M_ECC<5>")
	)
	(arc
		(start 78.849982 -85.108288)
		(mid 78.796512 -85.303351)
		(end 78.845156 -85.499702)
		(width 0.0889)
		(layer "In4.Cu")
		(net "M_M_ECC<5>")
	)
	(arc
		(start 78.856332 -92.453206)
		(mid 78.92913 -92.743969)
		(end 78.849982 -93.033088)
		(width 0.0889)
		(layer "In4.Cu")
		(net "M_M_ECC<5>")
	)
	(arc
		(start 78.849982 -94.423484)
		(mid 78.929113 -94.718886)
		(end 78.849982 -95.014288)
		(width 0.0889)
		(layer "In4.Cu")
		(net "M_M_ECC<5>")
	)
	(arc
		(start 78.856332 -96.415606)
		(mid 78.92913 -96.706369)
		(end 78.849982 -96.995488)
		(width 0.0889)
		(layer "In4.Cu")
		(net "M_M_ECC<5>")
	)
	(arc
		(start 78.856332 -87.500206)
		(mid 78.92913 -87.790969)
		(end 78.849982 -88.080088)
		(width 0.0889)
		(layer "In4.Cu")
		(net "M_M_ECC<5>")
	)
	(arc
		(start 78.849982 -91.051888)
		(mid 78.796512 -91.246951)
		(end 78.845156 -91.443302)
		(width 0.0889)
		(layer "In4.Cu")
		(net "M_M_ECC<5>")
	)
	(arc
		(start 78.849982 -96.004888)
		(mid 78.796512 -96.199951)
		(end 78.845156 -96.396302)
		(width 0.0889)
		(layer "In4.Cu")
		(net "M_M_ECC<5>")
	)
	(arc
		(start 78.849982 -89.070688)
		(mid 78.796512 -89.265751)
		(end 78.845156 -89.462102)
		(width 0.0889)
		(layer "In4.Cu")
		(net "M_M_ECC<5>")
	)
	(arc
		(start 78.856332 -90.472006)
		(mid 78.92913 -90.762769)
		(end 78.849982 -91.051888)
		(width 0.0889)
		(layer "In4.Cu")
		(net "M_M_ECC<5>")
	)
	(arc
		(start 78.856332 -89.481406)
		(mid 78.92913 -89.772169)
		(end 78.849982 -90.061288)
		(width 0.0889)
		(layer "In4.Cu")
		(net "M_M_ECC<5>")
	)
	(arc
		(start 78.849982 -93.433138)
		(mid 78.929204 -93.722256)
		(end 78.856332 -94.01302)
		(width 0.0889)
		(layer "In4.Cu")
		(net "M_M_ECC<5>")
	)
	(arc
		(start 78.849982 -90.061288)
		(mid 78.796512 -90.256351)
		(end 78.845156 -90.452702)
		(width 0.0889)
		(layer "In4.Cu")
		(net "M_M_ECC<5>")
	)
	(arc
		(start 78.849982 -86.098888)
		(mid 78.796512 -86.293951)
		(end 78.845156 -86.490302)
		(width 0.0889)
		(layer "In4.Cu")
		(net "M_M_ECC<5>")
	)
	(arc
		(start 78.849982 -95.014288)
		(mid 78.796512 -95.209351)
		(end 78.845156 -95.405702)
		(width 0.0889)
		(layer "In4.Cu")
		(net "M_M_ECC<5>")
	)
	(arc
		(start 78.856332 -97.406206)
		(mid 78.92913 -97.696969)
		(end 78.849982 -97.986088)
		(width 0.0889)
		(layer "In4.Cu")
		(net "M_M_ECC<5>")
	)
	(arc
		(start 78.849982 -94.023688)
		(mid 78.796483 -94.223586)
		(end 78.849982 -94.423484)
		(width 0.0889)
		(layer "In4.Cu")
		(net "M_M_ECC<5>")
	)
	(arc
		(start 78.849982 -97.986088)
		(mid 78.796512 -98.181151)
		(end 78.845156 -98.377502)
		(width 0.0889)
		(layer "In4.Cu")
		(net "M_M_ECC<5>")
	)
	(arc
		(start 78.849982 -93.033088)
		(mid 78.796512 -93.228151)
		(end 78.845156 -93.424502)
		(width 0.0889)
		(layer "In4.Cu")
		(net "M_M_ECC<5>")
	)
	(arc
		(start 78.849982 -92.042488)
		(mid 78.796512 -92.237551)
		(end 78.845156 -92.433902)
		(width 0.0889)
		(layer "In4.Cu")
		(net "M_M_ECC<5>")
	)
	(arc
		(start 78.856332 -88.490806)
		(mid 78.92913 -88.781569)
		(end 78.849982 -89.070688)
		(width 0.0889)
		(layer "In4.Cu")
		(net "M_M_ECC<5>")
	)
	(arc
		(start 78.856332 -86.509606)
		(mid 78.92913 -86.800369)
		(end 78.849982 -87.089488)
		(width 0.0889)
		(layer "In4.Cu")
		(net "M_M_ECC<5>")
	)
	(arc
		(start 78.856332 -91.462606)
		(mid 78.92913 -91.753369)
		(end 78.849982 -92.042488)
		(width 0.0889)
		(layer "In4.Cu")
		(net "M_M_ECC<5>")
	)
	(arc
		(start 78.849982 -96.995488)
		(mid 78.796512 -97.190551)
		(end 78.845156 -97.386902)
		(width 0.0889)
		(layer "In4.Cu")
		(net "M_M_ECC<5>")
	)
	(arc
		(start 78.856332 -85.519006)
		(mid 78.92913 -85.809769)
		(end 78.849982 -86.098888)
		(width 0.0889)
		(layer "In4.Cu")
		(net "M_M_ECC<5>")
	)
	(arc
		(start 78.856332 -95.425006)
		(mid 78.92913 -95.715769)
		(end 78.849982 -96.004888)
		(width 0.0889)
		(layer "In4.Cu")
		(net "M_M_ECC<5>")
	)
	(arc
		(start 78.849982 -87.089488)
		(mid 78.796512 -87.284551)
		(end 78.845156 -87.480902)
		(width 0.0889)
		(layer "In4.Cu")
		(net "M_M_ECC<5>")
	)
	(arc
		(start 78.849982 -88.080088)
		(mid 78.796512 -88.275151)
		(end 78.845156 -88.471502)
		(width 0.0889)
		(layer "In4.Cu")
		(net "M_M_ECC<5>")
	)
	(segment
		(start 69.249544 -151.129746)
		(end 69.249544 -150.6474)
		(width 0.14224)
		(layer "In11.Cu")
		(net "M_M_ECC<5>")
	)
	(segment
		(start 69.071744 -153.542746)
		(end 69.224144 -153.390346)
		(width 0.14224)
		(layer "In11.Cu")
		(net "M_M_ECC<5>")
	)
	(segment
		(start 68.960746 -151.418544)
		(end 69.249544 -151.129746)
		(width 0.14224)
		(layer "In11.Cu")
		(net "M_M_ECC<5>")
	)
	(segment
		(start 69.122544 -150.5204)
		(end 69.122544 -149.9616)
		(width 0.14224)
		(layer "In11.Cu")
		(net "M_M_ECC<5>")
	)
	(segment
		(start 68.960746 -152.898856)
		(end 68.960746 -152.586944)
		(width 0.14224)
		(layer "In11.Cu")
		(net "M_M_ECC<5>")
	)
	(segment
		(start 69.550788 -149.533356)
		(end 69.57314 -149.533356)
		(width 0.14224)
		(layer "In11.Cu")
		(net "M_M_ECC<5>")
	)
	(segment
		(start 68.799456 -153.542746)
		(end 69.071744 -153.542746)
		(width 0.14224)
		(layer "In11.Cu")
		(net "M_M_ECC<5>")
	)
	(segment
		(start 69.224144 -153.162254)
		(end 68.960746 -152.898856)
		(width 0.14224)
		(layer "In11.Cu")
		(net "M_M_ECC<5>")
	)
	(segment
		(start 68.960746 -151.755856)
		(end 68.960746 -151.418544)
		(width 0.14224)
		(layer "In11.Cu")
		(net "M_M_ECC<5>")
	)
	(segment
		(start 68.960746 -152.586944)
		(end 69.198744 -152.348946)
		(width 0.14224)
		(layer "In11.Cu")
		(net "M_M_ECC<5>")
	)
	(segment
		(start 69.198744 -152.348946)
		(end 69.198744 -151.993854)
		(width 0.14224)
		(layer "In11.Cu")
		(net "M_M_ECC<5>")
	)
	(segment
		(start 69.249544 -150.6474)
		(end 69.122544 -150.5204)
		(width 0.14224)
		(layer "In11.Cu")
		(net "M_M_ECC<5>")
	)
	(segment
		(start 69.224144 -153.390346)
		(end 69.224144 -153.162254)
		(width 0.14224)
		(layer "In11.Cu")
		(net "M_M_ECC<5>")
	)
	(segment
		(start 69.198744 -151.993854)
		(end 68.960746 -151.755856)
		(width 0.14224)
		(layer "In11.Cu")
		(net "M_M_ECC<5>")
	)
	(segment
		(start 69.122544 -149.9616)
		(end 69.550788 -149.533356)
		(width 0.14224)
		(layer "In11.Cu")
		(net "M_M_ECC<5>")
	)
	(segment
		(start 79.768192 -83.32724)
		(end 79.196692 -83.32724)
		(width 0.1651)
		(layer "F.Cu")
		(net "M_M_ECC<4>")
	)
	(segment
		(start 69.64934 -156.87294)
		(end 69.64934 -155.547568)
		(width 0.1651)
		(layer "F.Cu")
		(net "M_M_ECC<4>")
	)
	(segment
		(start 69.64934 -155.547568)
		(end 69.551296 -155.0162)
		(width 0.1651)
		(layer "F.Cu")
		(net "M_M_ECC<4>")
	)
	(via
		(at 79.196692 -83.32724)
		(size 0.508)
		(drill 0.254)
		(layers "F.Cu" "B.Cu")
		(net "M_M_ECC<4>")
	)
	(via
		(at 68.799456 -150.814278)
		(size 0.508)
		(drill 0.254)
		(layers "F.Cu" "B.Cu")
		(net "M_M_ECC<4>")
	)
	(via
		(at 69.551296 -155.0162)
		(size 0.508)
		(drill 0.254)
		(layers "F.Cu" "B.Cu")
		(net "M_M_ECC<4>")
	)
	(segment
		(start 68.799456 -152.078436)
		(end 68.799456 -150.814278)
		(width 0.1651)
		(layer "B.Cu")
		(net "M_M_ECC<4>")
	)
	(segment
		(start 69.289168 -127.6604)
		(end 69.257164 -127.692404)
		(width 0.14224)
		(layer "In4.Cu")
		(net "M_M_ECC<4>")
	)
	(segment
		(start 68.654168 -120.604788)
		(end 68.851272 -120.604788)
		(width 0.14224)
		(layer "In4.Cu")
		(net "M_M_ECC<4>")
	)
	(segment
		(start 69.492368 -118.317264)
		(end 68.450968 -119.358664)
		(width 0.14224)
		(layer "In4.Cu")
		(net "M_M_ECC<4>")
	)
	(segment
		(start 78.738222 -98.57105)
		(end 78.738222 -98.913696)
		(width 0.0889)
		(layer "In4.Cu")
		(net "M_M_ECC<4>")
	)
	(segment
		(start 68.450968 -120.401588)
		(end 68.654168 -120.604788)
		(width 0.14224)
		(layer "In4.Cu")
		(net "M_M_ECC<4>")
	)
	(segment
		(start 69.068696 -129.996438)
		(end 69.068696 -131.19227)
		(width 0.14224)
		(layer "In4.Cu")
		(net "M_M_ECC<4>")
	)
	(segment
		(start 77.558392 -101.432106)
		(end 77.34935 -101.641148)
		(width 0.0889)
		(layer "In4.Cu")
		(net "M_M_ECC<4>")
	)
	(segment
		(start 77.34935 -103.928418)
		(end 69.492368 -111.7854)
		(width 0.14224)
		(layer "In4.Cu")
		(net "M_M_ECC<4>")
	)
	(segment
		(start 78.684882 -97.490788)
		(end 78.689708 -97.499424)
		(width 0.0889)
		(layer "In4.Cu")
		(net "M_M_ECC<4>")
	)
	(segment
		(start 68.450968 -123.418346)
		(end 69.097144 -124.064522)
		(width 0.14224)
		(layer "In4.Cu")
		(net "M_M_ECC<4>")
	)
	(segment
		(start 69.322696 -139.333478)
		(end 69.068696 -139.587478)
		(width 0.14224)
		(layer "In4.Cu")
		(net "M_M_ECC<4>")
	)
	(segment
		(start 78.678532 -98.47072)
		(end 78.738222 -98.57105)
		(width 0.0889)
		(layer "In4.Cu")
		(net "M_M_ECC<4>")
	)
	(segment
		(start 68.450968 -121.620788)
		(end 68.450968 -123.418346)
		(width 0.14224)
		(layer "In4.Cu")
		(net "M_M_ECC<4>")
	)
	(segment
		(start 69.031104 -144.327118)
		(end 69.031104 -145.527776)
		(width 0.14224)
		(layer "In4.Cu")
		(net "M_M_ECC<4>")
	)
	(segment
		(start 69.297296 -144.060926)
		(end 69.031104 -144.327118)
		(width 0.14224)
		(layer "In4.Cu")
		(net "M_M_ECC<4>")
	)
	(segment
		(start 78.678532 -88.56472)
		(end 78.684882 -88.575388)
		(width 0.0889)
		(layer "In4.Cu")
		(net "M_M_ECC<4>")
	)
	(segment
		(start 78.684882 -84.612988)
		(end 78.689708 -84.621624)
		(width 0.0889)
		(layer "In4.Cu")
		(net "M_M_ECC<4>")
	)
	(segment
		(start 69.054472 -121.214388)
		(end 68.851272 -121.417588)
		(width 0.14224)
		(layer "In4.Cu")
		(net "M_M_ECC<4>")
	)
	(segment
		(start 69.097144 -124.064522)
		(end 69.097144 -125.588776)
		(width 0.14224)
		(layer "In4.Cu")
		(net "M_M_ECC<4>")
	)
	(segment
		(start 78.678532 -89.55532)
		(end 78.684882 -89.565988)
		(width 0.0889)
		(layer "In4.Cu")
		(net "M_M_ECC<4>")
	)
	(segment
		(start 77.913738 -100.391468)
		(end 77.558392 -100.746814)
		(width 0.0889)
		(layer "In4.Cu")
		(net "M_M_ECC<4>")
	)
	(segment
		(start 78.684882 -85.603588)
		(end 78.689708 -85.612224)
		(width 0.0889)
		(layer "In4.Cu")
		(net "M_M_ECC<4>")
	)
	(segment
		(start 78.684882 -90.556588)
		(end 78.689708 -90.565224)
		(width 0.0889)
		(layer "In4.Cu")
		(net "M_M_ECC<4>")
	)
	(segment
		(start 69.054472 -120.807988)
		(end 69.054472 -121.214388)
		(width 0.14224)
		(layer "In4.Cu")
		(net "M_M_ECC<4>")
	)
	(segment
		(start 78.678532 -90.54592)
		(end 78.684882 -90.556588)
		(width 0.0889)
		(layer "In4.Cu")
		(net "M_M_ECC<4>")
	)
	(segment
		(start 69.297296 -131.42087)
		(end 69.297296 -134.484872)
		(width 0.14224)
		(layer "In4.Cu")
		(net "M_M_ECC<4>")
	)
	(segment
		(start 78.684882 -89.565988)
		(end 78.689708 -89.574624)
		(width 0.0889)
		(layer "In4.Cu")
		(net "M_M_ECC<4>")
	)
	(segment
		(start 68.654168 -121.417588)
		(end 68.450968 -121.620788)
		(width 0.14224)
		(layer "In4.Cu")
		(net "M_M_ECC<4>")
	)
	(segment
		(start 68.851272 -121.417588)
		(end 68.654168 -121.417588)
		(width 0.14224)
		(layer "In4.Cu")
		(net "M_M_ECC<4>")
	)
	(segment
		(start 78.678532 -91.53652)
		(end 78.684882 -91.547188)
		(width 0.0889)
		(layer "In4.Cu")
		(net "M_M_ECC<4>")
	)
	(segment
		(start 69.297296 -134.484872)
		(end 69.068696 -134.713472)
		(width 0.14224)
		(layer "In4.Cu")
		(net "M_M_ECC<4>")
	)
	(segment
		(start 78.678532 -85.59292)
		(end 78.684882 -85.603588)
		(width 0.0889)
		(layer "In4.Cu")
		(net "M_M_ECC<4>")
	)
	(segment
		(start 77.34935 -101.641148)
		(end 77.34935 -103.928418)
		(width 0.14224)
		(layer "In4.Cu")
		(net "M_M_ECC<4>")
	)
	(segment
		(start 78.684882 -93.928438)
		(end 78.678532 -93.939106)
		(width 0.0889)
		(layer "In4.Cu")
		(net "M_M_ECC<4>")
	)
	(segment
		(start 78.684882 -96.500188)
		(end 78.689708 -96.508824)
		(width 0.0889)
		(layer "In4.Cu")
		(net "M_M_ECC<4>")
	)
	(segment
		(start 78.678532 -84.60232)
		(end 78.684882 -84.612988)
		(width 0.0889)
		(layer "In4.Cu")
		(net "M_M_ECC<4>")
	)
	(segment
		(start 69.289168 -125.7808)
		(end 69.289168 -127.6604)
		(width 0.14224)
		(layer "In4.Cu")
		(net "M_M_ECC<4>")
	)
	(segment
		(start 78.678532 -86.58352)
		(end 78.684882 -86.594188)
		(width 0.0889)
		(layer "In4.Cu")
		(net "M_M_ECC<4>")
	)
	(segment
		(start 78.678532 -97.48012)
		(end 78.684882 -97.490788)
		(width 0.0889)
		(layer "In4.Cu")
		(net "M_M_ECC<4>")
	)
	(segment
		(start 69.068696 -140.794486)
		(end 69.297296 -141.023086)
		(width 0.14224)
		(layer "In4.Cu")
		(net "M_M_ECC<4>")
	)
	(segment
		(start 69.097144 -125.588776)
		(end 69.289168 -125.7808)
		(width 0.14224)
		(layer "In4.Cu")
		(net "M_M_ECC<4>")
	)
	(segment
		(start 68.450968 -119.358664)
		(end 68.450968 -120.401588)
		(width 0.14224)
		(layer "In4.Cu")
		(net "M_M_ECC<4>")
	)
	(segment
		(start 77.913738 -99.73818)
		(end 77.913738 -100.391468)
		(width 0.0889)
		(layer "In4.Cu")
		(net "M_M_ECC<4>")
	)
	(segment
		(start 78.684882 -92.537788)
		(end 78.689708 -92.546424)
		(width 0.0889)
		(layer "In4.Cu")
		(net "M_M_ECC<4>")
	)
	(segment
		(start 69.257164 -127.692404)
		(end 69.257164 -129.80797)
		(width 0.14224)
		(layer "In4.Cu")
		(net "M_M_ECC<4>")
	)
	(segment
		(start 79.196692 -83.32724)
		(end 78.701646 -83.992974)
		(width 0.0889)
		(layer "In4.Cu")
		(net "M_M_ECC<4>")
	)
	(segment
		(start 78.684882 -94.518988)
		(end 78.689708 -94.527624)
		(width 0.0889)
		(layer "In4.Cu")
		(net "M_M_ECC<4>")
	)
	(segment
		(start 68.851272 -120.604788)
		(end 69.054472 -120.807988)
		(width 0.14224)
		(layer "In4.Cu")
		(net "M_M_ECC<4>")
	)
	(segment
		(start 68.799456 -149.445218)
		(end 68.799456 -150.814278)
		(width 0.14224)
		(layer "In4.Cu")
		(net "M_M_ECC<4>")
	)
	(segment
		(start 78.738222 -98.913696)
		(end 77.913738 -99.73818)
		(width 0.0889)
		(layer "In4.Cu")
		(net "M_M_ECC<4>")
	)
	(segment
		(start 78.701646 -83.992974)
		(end 78.684882 -84.022438)
		(width 0.0889)
		(layer "In4.Cu")
		(net "M_M_ECC<4>")
	)
	(segment
		(start 69.031104 -145.527776)
		(end 69.284596 -145.781268)
		(width 0.14224)
		(layer "In4.Cu")
		(net "M_M_ECC<4>")
	)
	(segment
		(start 69.068696 -139.587478)
		(end 69.068696 -140.794486)
		(width 0.14224)
		(layer "In4.Cu")
		(net "M_M_ECC<4>")
	)
	(segment
		(start 69.297296 -141.023086)
		(end 69.297296 -144.060926)
		(width 0.14224)
		(layer "In4.Cu")
		(net "M_M_ECC<4>")
	)
	(segment
		(start 78.684882 -91.547188)
		(end 78.689708 -91.555824)
		(width 0.0889)
		(layer "In4.Cu")
		(net "M_M_ECC<4>")
	)
	(segment
		(start 69.068696 -131.19227)
		(end 69.297296 -131.42087)
		(width 0.14224)
		(layer "In4.Cu")
		(net "M_M_ECC<4>")
	)
	(segment
		(start 78.684882 -95.509588)
		(end 78.689708 -95.518224)
		(width 0.0889)
		(layer "In4.Cu")
		(net "M_M_ECC<4>")
	)
	(segment
		(start 69.068696 -135.951468)
		(end 69.322696 -136.205468)
		(width 0.14224)
		(layer "In4.Cu")
		(net "M_M_ECC<4>")
	)
	(segment
		(start 69.068696 -134.713472)
		(end 69.068696 -135.951468)
		(width 0.14224)
		(layer "In4.Cu")
		(net "M_M_ECC<4>")
	)
	(segment
		(start 78.678532 -95.49892)
		(end 78.684882 -95.509588)
		(width 0.0889)
		(layer "In4.Cu")
		(net "M_M_ECC<4>")
	)
	(segment
		(start 69.284596 -148.960078)
		(end 68.799456 -149.445218)
		(width 0.14224)
		(layer "In4.Cu")
		(net "M_M_ECC<4>")
	)
	(segment
		(start 78.684882 -86.594188)
		(end 78.689708 -86.602824)
		(width 0.0889)
		(layer "In4.Cu")
		(net "M_M_ECC<4>")
	)
	(segment
		(start 78.678532 -96.48952)
		(end 78.684882 -96.500188)
		(width 0.0889)
		(layer "In4.Cu")
		(net "M_M_ECC<4>")
	)
	(segment
		(start 69.322696 -136.205468)
		(end 69.322696 -139.333478)
		(width 0.14224)
		(layer "In4.Cu")
		(net "M_M_ECC<4>")
	)
	(segment
		(start 69.284596 -145.781268)
		(end 69.284596 -148.960078)
		(width 0.14224)
		(layer "In4.Cu")
		(net "M_M_ECC<4>")
	)
	(segment
		(start 78.684882 -88.575388)
		(end 78.689708 -88.584024)
		(width 0.0889)
		(layer "In4.Cu")
		(net "M_M_ECC<4>")
	)
	(segment
		(start 69.492368 -111.7854)
		(end 69.492368 -118.317264)
		(width 0.14224)
		(layer "In4.Cu")
		(net "M_M_ECC<4>")
	)
	(segment
		(start 78.678532 -87.57412)
		(end 78.684882 -87.584788)
		(width 0.0889)
		(layer "In4.Cu")
		(net "M_M_ECC<4>")
	)
	(segment
		(start 78.678532 -92.52712)
		(end 78.684882 -92.537788)
		(width 0.0889)
		(layer "In4.Cu")
		(net "M_M_ECC<4>")
	)
	(segment
		(start 78.684882 -87.584788)
		(end 78.689708 -87.593424)
		(width 0.0889)
		(layer "In4.Cu")
		(net "M_M_ECC<4>")
	)
	(segment
		(start 69.257164 -129.80797)
		(end 69.068696 -129.996438)
		(width 0.14224)
		(layer "In4.Cu")
		(net "M_M_ECC<4>")
	)
	(segment
		(start 77.558392 -100.746814)
		(end 77.558392 -101.432106)
		(width 0.0889)
		(layer "In4.Cu")
		(net "M_M_ECC<4>")
	)
	(arc
		(start 78.684882 -88.975438)
		(mid 78.60566 -89.264556)
		(end 78.678532 -89.55532)
		(width 0.0889)
		(layer "In4.Cu")
		(net "M_M_ECC<4>")
	)
	(arc
		(start 78.684882 -90.956638)
		(mid 78.60566 -91.245756)
		(end 78.678532 -91.53652)
		(width 0.0889)
		(layer "In4.Cu")
		(net "M_M_ECC<4>")
	)
	(arc
		(start 78.689708 -85.612224)
		(mid 78.738463 -85.808576)
		(end 78.684882 -86.003638)
		(width 0.0889)
		(layer "In4.Cu")
		(net "M_M_ECC<4>")
	)
	(arc
		(start 78.689708 -97.499424)
		(mid 78.738463 -97.695776)
		(end 78.684882 -97.890838)
		(width 0.0889)
		(layer "In4.Cu")
		(net "M_M_ECC<4>")
	)
	(arc
		(start 78.689708 -86.602824)
		(mid 78.738463 -86.799176)
		(end 78.684882 -86.994238)
		(width 0.0889)
		(layer "In4.Cu")
		(net "M_M_ECC<4>")
	)
	(arc
		(start 78.684882 -87.984838)
		(mid 78.60566 -88.273956)
		(end 78.678532 -88.56472)
		(width 0.0889)
		(layer "In4.Cu")
		(net "M_M_ECC<4>")
	)
	(arc
		(start 78.689708 -92.546424)
		(mid 78.738463 -92.742776)
		(end 78.684882 -92.937838)
		(width 0.0889)
		(layer "In4.Cu")
		(net "M_M_ECC<4>")
	)
	(arc
		(start 78.684882 -84.022438)
		(mid 78.60566 -84.311556)
		(end 78.678532 -84.60232)
		(width 0.0889)
		(layer "In4.Cu")
		(net "M_M_ECC<4>")
	)
	(arc
		(start 78.684882 -91.947238)
		(mid 78.60566 -92.236356)
		(end 78.678532 -92.52712)
		(width 0.0889)
		(layer "In4.Cu")
		(net "M_M_ECC<4>")
	)
	(arc
		(start 78.689708 -84.621624)
		(mid 78.738463 -84.817976)
		(end 78.684882 -85.013038)
		(width 0.0889)
		(layer "In4.Cu")
		(net "M_M_ECC<4>")
	)
	(arc
		(start 78.689708 -88.584024)
		(mid 78.738463 -88.780376)
		(end 78.684882 -88.975438)
		(width 0.0889)
		(layer "In4.Cu")
		(net "M_M_ECC<4>")
	)
	(arc
		(start 78.684882 -93.528642)
		(mid 78.738381 -93.72854)
		(end 78.684882 -93.928438)
		(width 0.0889)
		(layer "In4.Cu")
		(net "M_M_ECC<4>")
	)
	(arc
		(start 78.684882 -96.900238)
		(mid 78.60566 -97.189356)
		(end 78.678532 -97.48012)
		(width 0.0889)
		(layer "In4.Cu")
		(net "M_M_ECC<4>")
	)
	(arc
		(start 78.689708 -96.508824)
		(mid 78.738463 -96.705176)
		(end 78.684882 -96.900238)
		(width 0.0889)
		(layer "In4.Cu")
		(net "M_M_ECC<4>")
	)
	(arc
		(start 78.684882 -85.013038)
		(mid 78.60566 -85.302156)
		(end 78.678532 -85.59292)
		(width 0.0889)
		(layer "In4.Cu")
		(net "M_M_ECC<4>")
	)
	(arc
		(start 78.684882 -92.937838)
		(mid 78.605751 -93.23324)
		(end 78.684882 -93.528642)
		(width 0.0889)
		(layer "In4.Cu")
		(net "M_M_ECC<4>")
	)
	(arc
		(start 78.689708 -94.527624)
		(mid 78.738463 -94.723976)
		(end 78.684882 -94.919038)
		(width 0.0889)
		(layer "In4.Cu")
		(net "M_M_ECC<4>")
	)
	(arc
		(start 78.678532 -93.939106)
		(mid 78.605734 -94.229869)
		(end 78.684882 -94.518988)
		(width 0.0889)
		(layer "In4.Cu")
		(net "M_M_ECC<4>")
	)
	(arc
		(start 78.689708 -90.565224)
		(mid 78.738463 -90.761576)
		(end 78.684882 -90.956638)
		(width 0.0889)
		(layer "In4.Cu")
		(net "M_M_ECC<4>")
	)
	(arc
		(start 78.689708 -89.574624)
		(mid 78.738463 -89.770976)
		(end 78.684882 -89.966038)
		(width 0.0889)
		(layer "In4.Cu")
		(net "M_M_ECC<4>")
	)
	(arc
		(start 78.684882 -95.909638)
		(mid 78.60566 -96.198756)
		(end 78.678532 -96.48952)
		(width 0.0889)
		(layer "In4.Cu")
		(net "M_M_ECC<4>")
	)
	(arc
		(start 78.689708 -91.555824)
		(mid 78.738463 -91.752176)
		(end 78.684882 -91.947238)
		(width 0.0889)
		(layer "In4.Cu")
		(net "M_M_ECC<4>")
	)
	(arc
		(start 78.684882 -86.994238)
		(mid 78.60566 -87.283356)
		(end 78.678532 -87.57412)
		(width 0.0889)
		(layer "In4.Cu")
		(net "M_M_ECC<4>")
	)
	(arc
		(start 78.684882 -94.919038)
		(mid 78.60566 -95.208156)
		(end 78.678532 -95.49892)
		(width 0.0889)
		(layer "In4.Cu")
		(net "M_M_ECC<4>")
	)
	(arc
		(start 78.689708 -95.518224)
		(mid 78.738463 -95.714576)
		(end 78.684882 -95.909638)
		(width 0.0889)
		(layer "In4.Cu")
		(net "M_M_ECC<4>")
	)
	(arc
		(start 78.684882 -86.003638)
		(mid 78.60566 -86.292756)
		(end 78.678532 -86.58352)
		(width 0.0889)
		(layer "In4.Cu")
		(net "M_M_ECC<4>")
	)
	(arc
		(start 78.689708 -87.593424)
		(mid 78.738463 -87.789776)
		(end 78.684882 -87.984838)
		(width 0.0889)
		(layer "In4.Cu")
		(net "M_M_ECC<4>")
	)
	(arc
		(start 78.684882 -89.966038)
		(mid 78.60566 -90.255156)
		(end 78.678532 -90.54592)
		(width 0.0889)
		(layer "In4.Cu")
		(net "M_M_ECC<4>")
	)
	(arc
		(start 78.684882 -97.890838)
		(mid 78.60566 -98.179956)
		(end 78.678532 -98.47072)
		(width 0.0889)
		(layer "In4.Cu")
		(net "M_M_ECC<4>")
	)
	(segment
		(start 68.366386 -151.247348)
		(end 68.799456 -150.814278)
		(width 0.14224)
		(layer "In11.Cu")
		(net "M_M_ECC<4>")
	)
	(segment
		(start 68.366386 -153.83129)
		(end 68.366386 -151.247348)
		(width 0.14224)
		(layer "In11.Cu")
		(net "M_M_ECC<4>")
	)
	(segment
		(start 69.551296 -155.0162)
		(end 68.366386 -153.83129)
		(width 0.14224)
		(layer "In11.Cu")
		(net "M_M_ECC<4>")
	)
	(segment
		(start 76.449428 -152.273)
		(end 76.449428 -153.542746)
		(width 0.1651)
		(layer "F.Cu")
		(net "M_M_ECC<3>")
	)
	(segment
		(start 83.202272 -84.31784)
		(end 82.630772 -84.31784)
		(width 0.1651)
		(layer "F.Cu")
		(net "M_M_ECC<3>")
	)
	(via
		(at 82.630772 -84.31784)
		(size 0.508)
		(drill 0.254)
		(layers "F.Cu" "B.Cu")
		(net "M_M_ECC<3>")
	)
	(via
		(at 76.449428 -153.542746)
		(size 0.508)
		(drill 0.254)
		(layers "F.Cu" "B.Cu")
		(net "M_M_ECC<3>")
	)
	(via
		(at 77.299312 -149.533356)
		(size 0.508)
		(drill 0.254)
		(layers "F.Cu" "B.Cu")
		(net "M_M_ECC<3>")
	)
	(segment
		(start 77.299312 -148.227796)
		(end 77.299312 -149.533356)
		(width 0.1651)
		(layer "B.Cu")
		(net "M_M_ECC<3>")
	)
	(segment
		(start 77.299566 -148.227542)
		(end 77.299312 -148.227796)
		(width 0.1651)
		(layer "B.Cu")
		(net "M_M_ECC<3>")
	)
	(segment
		(start 77.299566 -147.478496)
		(end 77.299566 -148.227542)
		(width 0.1651)
		(layer "B.Cu")
		(net "M_M_ECC<3>")
	)
	(segment
		(start 83.148932 -87.57412)
		(end 83.142582 -87.584788)
		(width 0.0889)
		(layer "In4.Cu")
		(net "M_M_ECC<3>")
	)
	(segment
		(start 77.653896 -127.220472)
		(end 77.653896 -127.789178)
		(width 0.14224)
		(layer "In4.Cu")
		(net "M_M_ECC<3>")
	)
	(segment
		(start 83.142582 -91.547188)
		(end 83.137756 -91.555824)
		(width 0.0889)
		(layer "In4.Cu")
		(net "M_M_ECC<3>")
	)
	(segment
		(start 83.148932 -90.54592)
		(end 83.142582 -90.556588)
		(width 0.0889)
		(layer "In4.Cu")
		(net "M_M_ECC<3>")
	)
	(segment
		(start 77.798168 -136.745472)
		(end 77.798168 -138.811)
		(width 0.14224)
		(layer "In4.Cu")
		(net "M_M_ECC<3>")
	)
	(segment
		(start 83.047586 -84.84616)
		(end 83.142582 -85.013038)
		(width 0.0889)
		(layer "In4.Cu")
		(net "M_M_ECC<3>")
	)
	(segment
		(start 77.653896 -136.6012)
		(end 77.798168 -136.745472)
		(width 0.14224)
		(layer "In4.Cu")
		(net "M_M_ECC<3>")
	)
	(segment
		(start 83.142328 -95.910146)
		(end 83.818984 -97.081086)
		(width 0.0889)
		(layer "In4.Cu")
		(net "M_M_ECC<3>")
	)
	(segment
		(start 77.653896 -123.48464)
		(end 77.808836 -123.63958)
		(width 0.14224)
		(layer "In4.Cu")
		(net "M_M_ECC<3>")
	)
	(segment
		(start 77.806296 -139.714478)
		(end 77.806296 -140.870178)
		(width 0.14224)
		(layer "In4.Cu")
		(net "M_M_ECC<3>")
	)
	(segment
		(start 78.026768 -126.8476)
		(end 77.653896 -127.220472)
		(width 0.14224)
		(layer "In4.Cu")
		(net "M_M_ECC<3>")
	)
	(segment
		(start 77.808836 -124.45238)
		(end 77.653896 -124.60732)
		(width 0.14224)
		(layer "In4.Cu")
		(net "M_M_ECC<3>")
	)
	(segment
		(start 83.148932 -86.58352)
		(end 83.142582 -86.594188)
		(width 0.0889)
		(layer "In4.Cu")
		(net "M_M_ECC<3>")
	)
	(segment
		(start 78.053184 -112.399064)
		(end 78.053184 -121.182384)
		(width 0.14224)
		(layer "In4.Cu")
		(net "M_M_ECC<3>")
	)
	(segment
		(start 84.049616 -103.103934)
		(end 84.049616 -106.402632)
		(width 0.14224)
		(layer "In4.Cu")
		(net "M_M_ECC<3>")
	)
	(segment
		(start 77.653896 -138.955272)
		(end 77.653896 -139.562078)
		(width 0.14224)
		(layer "In4.Cu")
		(net "M_M_ECC<3>")
	)
	(segment
		(start 76.788518 -121.3739)
		(end 76.557886 -121.604532)
		(width 0.14224)
		(layer "In4.Cu")
		(net "M_M_ECC<3>")
	)
	(segment
		(start 78.596236 -123.63958)
		(end 78.751176 -123.79452)
		(width 0.14224)
		(layer "In4.Cu")
		(net "M_M_ECC<3>")
	)
	(segment
		(start 77.798168 -138.811)
		(end 77.653896 -138.955272)
		(width 0.14224)
		(layer "In4.Cu")
		(net "M_M_ECC<3>")
	)
	(segment
		(start 83.148932 -92.52712)
		(end 83.142582 -92.537788)
		(width 0.0889)
		(layer "In4.Cu")
		(net "M_M_ECC<3>")
	)
	(segment
		(start 77.666596 -132.024628)
		(end 77.798168 -132.1562)
		(width 0.14224)
		(layer "In4.Cu")
		(net "M_M_ECC<3>")
	)
	(segment
		(start 78.026768 -125.25248)
		(end 78.026768 -126.8476)
		(width 0.14224)
		(layer "In4.Cu")
		(net "M_M_ECC<3>")
	)
	(segment
		(start 77.791564 -145.675604)
		(end 77.450696 -146.016472)
		(width 0.14224)
		(layer "In4.Cu")
		(net "M_M_ECC<3>")
	)
	(segment
		(start 77.666596 -141.009878)
		(end 77.666596 -141.574774)
		(width 0.14224)
		(layer "In4.Cu")
		(net "M_M_ECC<3>")
	)
	(segment
		(start 77.653896 -129.960878)
		(end 77.78496 -130.091942)
		(width 0.14224)
		(layer "In4.Cu")
		(net "M_M_ECC<3>")
	)
	(segment
		(start 83.142582 -90.556588)
		(end 83.137756 -90.565224)
		(width 0.0889)
		(layer "In4.Cu")
		(net "M_M_ECC<3>")
	)
	(segment
		(start 83.148932 -95.49892)
		(end 83.142582 -95.509588)
		(width 0.0889)
		(layer "In4.Cu")
		(net "M_M_ECC<3>")
	)
	(segment
		(start 77.653896 -129.008378)
		(end 77.653896 -129.960878)
		(width 0.14224)
		(layer "In4.Cu")
		(net "M_M_ECC<3>")
	)
	(segment
		(start 77.653896 -122.615198)
		(end 77.653896 -123.48464)
		(width 0.14224)
		(layer "In4.Cu")
		(net "M_M_ECC<3>")
	)
	(segment
		(start 76.934568 -128.601978)
		(end 77.137768 -128.805178)
		(width 0.14224)
		(layer "In4.Cu")
		(net "M_M_ECC<3>")
	)
	(segment
		(start 83.142582 -93.928438)
		(end 83.148932 -93.939106)
		(width 0.0889)
		(layer "In4.Cu")
		(net "M_M_ECC<3>")
	)
	(segment
		(start 83.142582 -88.575388)
		(end 83.137756 -88.584024)
		(width 0.0889)
		(layer "In4.Cu")
		(net "M_M_ECC<3>")
	)
	(segment
		(start 77.653896 -124.879608)
		(end 78.026768 -125.25248)
		(width 0.14224)
		(layer "In4.Cu")
		(net "M_M_ECC<3>")
	)
	(segment
		(start 77.450696 -146.016472)
		(end 77.450696 -149.381972)
		(width 0.14224)
		(layer "In4.Cu")
		(net "M_M_ECC<3>")
	)
	(segment
		(start 77.653896 -139.562078)
		(end 77.806296 -139.714478)
		(width 0.14224)
		(layer "In4.Cu")
		(net "M_M_ECC<3>")
	)
	(segment
		(start 77.666596 -141.574774)
		(end 77.791564 -141.699742)
		(width 0.14224)
		(layer "In4.Cu")
		(net "M_M_ECC<3>")
	)
	(segment
		(start 83.142582 -95.509588)
		(end 83.137756 -95.518224)
		(width 0.0889)
		(layer "In4.Cu")
		(net "M_M_ECC<3>")
	)
	(segment
		(start 77.806296 -140.870178)
		(end 77.666596 -141.009878)
		(width 0.14224)
		(layer "In4.Cu")
		(net "M_M_ECC<3>")
	)
	(segment
		(start 83.148932 -91.53652)
		(end 83.142582 -91.547188)
		(width 0.0889)
		(layer "In4.Cu")
		(net "M_M_ECC<3>")
	)
	(segment
		(start 77.798168 -132.1562)
		(end 77.798168 -136.0932)
		(width 0.14224)
		(layer "In4.Cu")
		(net "M_M_ECC<3>")
	)
	(segment
		(start 84.049616 -106.402632)
		(end 78.053184 -112.399064)
		(width 0.14224)
		(layer "In4.Cu")
		(net "M_M_ECC<3>")
	)
	(segment
		(start 77.450696 -127.992378)
		(end 77.137768 -127.992378)
		(width 0.14224)
		(layer "In4.Cu")
		(net "M_M_ECC<3>")
	)
	(segment
		(start 77.137768 -127.992378)
		(end 76.934568 -128.195578)
		(width 0.14224)
		(layer "In4.Cu")
		(net "M_M_ECC<3>")
	)
	(segment
		(start 77.808836 -123.63958)
		(end 78.596236 -123.63958)
		(width 0.14224)
		(layer "In4.Cu")
		(net "M_M_ECC<3>")
	)
	(segment
		(start 83.818984 -102.873302)
		(end 84.049616 -103.103934)
		(width 0.0889)
		(layer "In4.Cu")
		(net "M_M_ECC<3>")
	)
	(segment
		(start 77.450696 -149.381972)
		(end 77.299312 -149.533356)
		(width 0.14224)
		(layer "In4.Cu")
		(net "M_M_ECC<3>")
	)
	(segment
		(start 83.142582 -86.594188)
		(end 83.137756 -86.602824)
		(width 0.0889)
		(layer "In4.Cu")
		(net "M_M_ECC<3>")
	)
	(segment
		(start 76.801218 -122.391424)
		(end 77.430122 -122.391424)
		(width 0.14224)
		(layer "In4.Cu")
		(net "M_M_ECC<3>")
	)
	(segment
		(start 76.934568 -128.195578)
		(end 76.934568 -128.601978)
		(width 0.14224)
		(layer "In4.Cu")
		(net "M_M_ECC<3>")
	)
	(segment
		(start 83.148932 -89.55532)
		(end 83.142582 -89.565988)
		(width 0.0889)
		(layer "In4.Cu")
		(net "M_M_ECC<3>")
	)
	(segment
		(start 77.137768 -128.805178)
		(end 77.450696 -128.805178)
		(width 0.14224)
		(layer "In4.Cu")
		(net "M_M_ECC<3>")
	)
	(segment
		(start 78.751176 -124.29744)
		(end 78.596236 -124.45238)
		(width 0.14224)
		(layer "In4.Cu")
		(net "M_M_ECC<3>")
	)
	(segment
		(start 76.557886 -122.148092)
		(end 76.801218 -122.391424)
		(width 0.14224)
		(layer "In4.Cu")
		(net "M_M_ECC<3>")
	)
	(segment
		(start 77.653896 -136.237472)
		(end 77.653896 -136.6012)
		(width 0.14224)
		(layer "In4.Cu")
		(net "M_M_ECC<3>")
	)
	(segment
		(start 83.142582 -92.537788)
		(end 83.137756 -92.546424)
		(width 0.0889)
		(layer "In4.Cu")
		(net "M_M_ECC<3>")
	)
	(segment
		(start 78.053184 -121.182384)
		(end 77.861668 -121.3739)
		(width 0.14224)
		(layer "In4.Cu")
		(net "M_M_ECC<3>")
	)
	(segment
		(start 83.142582 -85.603588)
		(end 83.137756 -85.612224)
		(width 0.0889)
		(layer "In4.Cu")
		(net "M_M_ECC<3>")
	)
	(segment
		(start 77.666596 -131.408678)
		(end 77.666596 -132.024628)
		(width 0.14224)
		(layer "In4.Cu")
		(net "M_M_ECC<3>")
	)
	(segment
		(start 77.450696 -128.805178)
		(end 77.653896 -129.008378)
		(width 0.14224)
		(layer "In4.Cu")
		(net "M_M_ECC<3>")
	)
	(segment
		(start 83.142582 -87.584788)
		(end 83.137756 -87.593424)
		(width 0.0889)
		(layer "In4.Cu")
		(net "M_M_ECC<3>")
	)
	(segment
		(start 76.557886 -121.604532)
		(end 76.557886 -122.148092)
		(width 0.14224)
		(layer "In4.Cu")
		(net "M_M_ECC<3>")
	)
	(segment
		(start 78.596236 -124.45238)
		(end 77.808836 -124.45238)
		(width 0.14224)
		(layer "In4.Cu")
		(net "M_M_ECC<3>")
	)
	(segment
		(start 83.818984 -97.081086)
		(end 83.818984 -102.873302)
		(width 0.0889)
		(layer "In4.Cu")
		(net "M_M_ECC<3>")
	)
	(segment
		(start 77.653896 -124.60732)
		(end 77.653896 -124.879608)
		(width 0.14224)
		(layer "In4.Cu")
		(net "M_M_ECC<3>")
	)
	(segment
		(start 83.148932 -88.56472)
		(end 83.142582 -88.575388)
		(width 0.0889)
		(layer "In4.Cu")
		(net "M_M_ECC<3>")
	)
	(segment
		(start 83.142582 -89.565988)
		(end 83.137756 -89.574624)
		(width 0.0889)
		(layer "In4.Cu")
		(net "M_M_ECC<3>")
	)
	(segment
		(start 83.142582 -94.518988)
		(end 83.137756 -94.527624)
		(width 0.0889)
		(layer "In4.Cu")
		(net "M_M_ECC<3>")
	)
	(segment
		(start 78.751176 -123.79452)
		(end 78.751176 -124.29744)
		(width 0.14224)
		(layer "In4.Cu")
		(net "M_M_ECC<3>")
	)
	(segment
		(start 82.630772 -84.31784)
		(end 82.657696 -84.321904)
		(width 0.0889)
		(layer "In4.Cu")
		(net "M_M_ECC<3>")
	)
	(segment
		(start 77.798168 -136.0932)
		(end 77.653896 -136.237472)
		(width 0.14224)
		(layer "In4.Cu")
		(net "M_M_ECC<3>")
	)
	(segment
		(start 77.78496 -130.091942)
		(end 77.78496 -131.290314)
		(width 0.14224)
		(layer "In4.Cu")
		(net "M_M_ECC<3>")
	)
	(segment
		(start 82.657696 -84.321904)
		(end 83.047586 -84.84616)
		(width 0.0889)
		(layer "In4.Cu")
		(net "M_M_ECC<3>")
	)
	(segment
		(start 77.78496 -131.290314)
		(end 77.666596 -131.408678)
		(width 0.14224)
		(layer "In4.Cu")
		(net "M_M_ECC<3>")
	)
	(segment
		(start 77.653896 -127.789178)
		(end 77.450696 -127.992378)
		(width 0.14224)
		(layer "In4.Cu")
		(net "M_M_ECC<3>")
	)
	(segment
		(start 83.148932 -85.59292)
		(end 83.142582 -85.603588)
		(width 0.0889)
		(layer "In4.Cu")
		(net "M_M_ECC<3>")
	)
	(segment
		(start 77.861668 -121.3739)
		(end 76.788518 -121.3739)
		(width 0.14224)
		(layer "In4.Cu")
		(net "M_M_ECC<3>")
	)
	(segment
		(start 77.791564 -141.699742)
		(end 77.791564 -145.675604)
		(width 0.14224)
		(layer "In4.Cu")
		(net "M_M_ECC<3>")
	)
	(segment
		(start 77.430122 -122.391424)
		(end 77.653896 -122.615198)
		(width 0.14224)
		(layer "In4.Cu")
		(net "M_M_ECC<3>")
	)
	(segment
		(start 83.142582 -95.909638)
		(end 83.142328 -95.910146)
		(width 0.0889)
		(layer "In4.Cu")
		(net "M_M_ECC<3>")
	)
	(arc
		(start 83.142582 -86.994238)
		(mid 83.221804 -87.283356)
		(end 83.148932 -87.57412)
		(width 0.0889)
		(layer "In4.Cu")
		(net "M_M_ECC<3>")
	)
	(arc
		(start 83.137756 -90.565224)
		(mid 83.089001 -90.761576)
		(end 83.142582 -90.956638)
		(width 0.0889)
		(layer "In4.Cu")
		(net "M_M_ECC<3>")
	)
	(arc
		(start 83.137756 -94.527624)
		(mid 83.089001 -94.723976)
		(end 83.142582 -94.919038)
		(width 0.0889)
		(layer "In4.Cu")
		(net "M_M_ECC<3>")
	)
	(arc
		(start 83.142582 -92.937838)
		(mid 83.221713 -93.23324)
		(end 83.142582 -93.528642)
		(width 0.0889)
		(layer "In4.Cu")
		(net "M_M_ECC<3>")
	)
	(arc
		(start 83.137756 -89.574624)
		(mid 83.089001 -89.770976)
		(end 83.142582 -89.966038)
		(width 0.0889)
		(layer "In4.Cu")
		(net "M_M_ECC<3>")
	)
	(arc
		(start 83.137756 -88.584024)
		(mid 83.089001 -88.780376)
		(end 83.142582 -88.975438)
		(width 0.0889)
		(layer "In4.Cu")
		(net "M_M_ECC<3>")
	)
	(arc
		(start 83.137756 -92.546424)
		(mid 83.089001 -92.742776)
		(end 83.142582 -92.937838)
		(width 0.0889)
		(layer "In4.Cu")
		(net "M_M_ECC<3>")
	)
	(arc
		(start 83.137756 -91.555824)
		(mid 83.089001 -91.752176)
		(end 83.142582 -91.947238)
		(width 0.0889)
		(layer "In4.Cu")
		(net "M_M_ECC<3>")
	)
	(arc
		(start 83.142582 -88.975438)
		(mid 83.221804 -89.264556)
		(end 83.148932 -89.55532)
		(width 0.0889)
		(layer "In4.Cu")
		(net "M_M_ECC<3>")
	)
	(arc
		(start 83.148932 -93.939106)
		(mid 83.22173 -94.229869)
		(end 83.142582 -94.518988)
		(width 0.0889)
		(layer "In4.Cu")
		(net "M_M_ECC<3>")
	)
	(arc
		(start 83.137756 -87.593424)
		(mid 83.089001 -87.789776)
		(end 83.142582 -87.984838)
		(width 0.0889)
		(layer "In4.Cu")
		(net "M_M_ECC<3>")
	)
	(arc
		(start 83.142582 -94.919038)
		(mid 83.221804 -95.208156)
		(end 83.148932 -95.49892)
		(width 0.0889)
		(layer "In4.Cu")
		(net "M_M_ECC<3>")
	)
	(arc
		(start 83.137756 -85.612224)
		(mid 83.089001 -85.808576)
		(end 83.142582 -86.003638)
		(width 0.0889)
		(layer "In4.Cu")
		(net "M_M_ECC<3>")
	)
	(arc
		(start 83.142582 -85.013038)
		(mid 83.221804 -85.302156)
		(end 83.148932 -85.59292)
		(width 0.0889)
		(layer "In4.Cu")
		(net "M_M_ECC<3>")
	)
	(arc
		(start 83.142582 -93.528642)
		(mid 83.089083 -93.72854)
		(end 83.142582 -93.928438)
		(width 0.0889)
		(layer "In4.Cu")
		(net "M_M_ECC<3>")
	)
	(arc
		(start 83.142582 -90.956638)
		(mid 83.221804 -91.245756)
		(end 83.148932 -91.53652)
		(width 0.0889)
		(layer "In4.Cu")
		(net "M_M_ECC<3>")
	)
	(arc
		(start 83.142582 -86.003638)
		(mid 83.221804 -86.292756)
		(end 83.148932 -86.58352)
		(width 0.0889)
		(layer "In4.Cu")
		(net "M_M_ECC<3>")
	)
	(arc
		(start 83.142582 -87.984838)
		(mid 83.221804 -88.273956)
		(end 83.148932 -88.56472)
		(width 0.0889)
		(layer "In4.Cu")
		(net "M_M_ECC<3>")
	)
	(arc
		(start 83.137756 -86.602824)
		(mid 83.089001 -86.799176)
		(end 83.142582 -86.994238)
		(width 0.0889)
		(layer "In4.Cu")
		(net "M_M_ECC<3>")
	)
	(arc
		(start 83.137756 -95.518224)
		(mid 83.089001 -95.714576)
		(end 83.142582 -95.909638)
		(width 0.0889)
		(layer "In4.Cu")
		(net "M_M_ECC<3>")
	)
	(arc
		(start 83.142582 -89.966038)
		(mid 83.221804 -90.255156)
		(end 83.148932 -90.54592)
		(width 0.0889)
		(layer "In4.Cu")
		(net "M_M_ECC<3>")
	)
	(arc
		(start 83.142582 -91.947238)
		(mid 83.221804 -92.236356)
		(end 83.148932 -92.52712)
		(width 0.0889)
		(layer "In4.Cu")
		(net "M_M_ECC<3>")
	)
	(segment
		(start 76.899516 -153.364946)
		(end 76.899516 -153.04135)
		(width 0.14224)
		(layer "In11.Cu")
		(net "M_M_ECC<3>")
	)
	(segment
		(start 76.721716 -153.542746)
		(end 76.899516 -153.364946)
		(width 0.14224)
		(layer "In11.Cu")
		(net "M_M_ECC<3>")
	)
	(segment
		(start 76.893166 -151.1046)
		(end 76.893166 -150.435818)
		(width 0.14224)
		(layer "In11.Cu")
		(net "M_M_ECC<3>")
	)
	(segment
		(start 76.867766 -151.9174)
		(end 76.610718 -151.660352)
		(width 0.14224)
		(layer "In11.Cu")
		(net "M_M_ECC<3>")
	)
	(segment
		(start 76.610718 -152.752552)
		(end 76.610718 -152.479248)
		(width 0.14224)
		(layer "In11.Cu")
		(net "M_M_ECC<3>")
	)
	(segment
		(start 76.848716 -150.391368)
		(end 76.848716 -149.9616)
		(width 0.14224)
		(layer "In11.Cu")
		(net "M_M_ECC<3>")
	)
	(segment
		(start 76.848716 -149.9616)
		(end 77.27696 -149.533356)
		(width 0.14224)
		(layer "In11.Cu")
		(net "M_M_ECC<3>")
	)
	(segment
		(start 76.899516 -153.04135)
		(end 76.610718 -152.752552)
		(width 0.14224)
		(layer "In11.Cu")
		(net "M_M_ECC<3>")
	)
	(segment
		(start 76.610718 -151.660352)
		(end 76.610718 -151.387048)
		(width 0.14224)
		(layer "In11.Cu")
		(net "M_M_ECC<3>")
	)
	(segment
		(start 76.867766 -152.2222)
		(end 76.867766 -151.9174)
		(width 0.14224)
		(layer "In11.Cu")
		(net "M_M_ECC<3>")
	)
	(segment
		(start 76.610718 -151.387048)
		(end 76.893166 -151.1046)
		(width 0.14224)
		(layer "In11.Cu")
		(net "M_M_ECC<3>")
	)
	(segment
		(start 76.610718 -152.479248)
		(end 76.867766 -152.2222)
		(width 0.14224)
		(layer "In11.Cu")
		(net "M_M_ECC<3>")
	)
	(segment
		(start 76.449428 -153.542746)
		(end 76.721716 -153.542746)
		(width 0.14224)
		(layer "In11.Cu")
		(net "M_M_ECC<3>")
	)
	(segment
		(start 76.893166 -150.435818)
		(end 76.848716 -150.391368)
		(width 0.14224)
		(layer "In11.Cu")
		(net "M_M_ECC<3>")
	)
	(segment
		(start 77.27696 -149.533356)
		(end 77.299312 -149.533356)
		(width 0.14224)
		(layer "In11.Cu")
		(net "M_M_ECC<3>")
	)
	(segment
		(start 83.202272 -83.32724)
		(end 82.630772 -83.32724)
		(width 0.1651)
		(layer "F.Cu")
		(net "M_M_ECC<2>")
	)
	(segment
		(start 77.299312 -155.395168)
		(end 77.299312 -155.1178)
		(width 0.1651)
		(layer "F.Cu")
		(net "M_M_ECC<2>")
	)
	(segment
		(start 77.299312 -155.881832)
		(end 77.430884 -155.75026)
		(width 0.1651)
		(layer "F.Cu")
		(net "M_M_ECC<2>")
	)
	(segment
		(start 77.430884 -155.52674)
		(end 77.299312 -155.395168)
		(width 0.1651)
		(layer "F.Cu")
		(net "M_M_ECC<2>")
	)
	(segment
		(start 77.299312 -156.87294)
		(end 77.299312 -155.881832)
		(width 0.1651)
		(layer "F.Cu")
		(net "M_M_ECC<2>")
	)
	(segment
		(start 77.430884 -155.75026)
		(end 77.430884 -155.52674)
		(width 0.1651)
		(layer "F.Cu")
		(net "M_M_ECC<2>")
	)
	(segment
		(start 77.299566 -156.87294)
		(end 77.299312 -156.87294)
		(width 0.1651)
		(layer "F.Cu")
		(net "M_M_ECC<2>")
	)
	(via
		(at 76.449428 -150.814278)
		(size 0.508)
		(drill 0.254)
		(layers "F.Cu" "B.Cu")
		(net "M_M_ECC<2>")
	)
	(via
		(at 82.630772 -83.32724)
		(size 0.508)
		(drill 0.254)
		(layers "F.Cu" "B.Cu")
		(net "M_M_ECC<2>")
	)
	(via
		(at 77.299312 -155.1178)
		(size 0.508)
		(drill 0.254)
		(layers "F.Cu" "B.Cu")
		(net "M_M_ECC<2>")
	)
	(segment
		(start 76.449428 -152.078436)
		(end 76.449428 -150.814278)
		(width 0.1651)
		(layer "B.Cu")
		(net "M_M_ECC<2>")
	)
	(segment
		(start 82.977482 -87.489538)
		(end 82.982308 -87.480902)
		(width 0.0889)
		(layer "In4.Cu")
		(net "M_M_ECC<2>")
	)
	(segment
		(start 76.815696 -139.562078)
		(end 76.942696 -139.435078)
		(width 0.14224)
		(layer "In4.Cu")
		(net "M_M_ECC<2>")
	)
	(segment
		(start 76.942696 -139.435078)
		(end 76.942696 -138.819128)
		(width 0.14224)
		(layer "In4.Cu")
		(net "M_M_ECC<2>")
	)
	(segment
		(start 82.977482 -86.498938)
		(end 82.982308 -86.490302)
		(width 0.0889)
		(layer "In4.Cu")
		(net "M_M_ECC<2>")
	)
	(segment
		(start 77.031596 -134.259828)
		(end 76.883768 -134.112)
		(width 0.14224)
		(layer "In4.Cu")
		(net "M_M_ECC<2>")
	)
	(segment
		(start 82.971132 -91.462606)
		(end 82.977482 -91.451938)
		(width 0.0889)
		(layer "In4.Cu")
		(net "M_M_ECC<2>")
	)
	(segment
		(start 76.739496 -144.372838)
		(end 77.018896 -144.093438)
		(width 0.14224)
		(layer "In4.Cu")
		(net "M_M_ECC<2>")
	)
	(segment
		(start 76.968096 -146.2278)
		(end 76.968096 -145.806668)
		(width 0.14224)
		(layer "In4.Cu")
		(net "M_M_ECC<2>")
	)
	(segment
		(start 82.971132 -85.519006)
		(end 82.977482 -85.508338)
		(width 0.0889)
		(layer "In4.Cu")
		(net "M_M_ECC<2>")
	)
	(segment
		(start 82.977482 -90.461338)
		(end 82.982308 -90.452702)
		(width 0.0889)
		(layer "In4.Cu")
		(net "M_M_ECC<2>")
	)
	(segment
		(start 76.449428 -150.814278)
		(end 76.324968 -150.689818)
		(width 0.14224)
		(layer "In4.Cu")
		(net "M_M_ECC<2>")
	)
	(segment
		(start 77.031596 -134.471664)
		(end 77.031596 -134.259828)
		(width 0.14224)
		(layer "In4.Cu")
		(net "M_M_ECC<2>")
	)
	(segment
		(start 75.853036 -122.57913)
		(end 75.853036 -120.841008)
		(width 0.14224)
		(layer "In4.Cu")
		(net "M_M_ECC<2>")
	)
	(segment
		(start 76.739496 -145.578068)
		(end 76.739496 -144.372838)
		(width 0.14224)
		(layer "In4.Cu")
		(net "M_M_ECC<2>")
	)
	(segment
		(start 82.977482 -88.480138)
		(end 82.982308 -88.471502)
		(width 0.0889)
		(layer "In4.Cu")
		(net "M_M_ECC<2>")
	)
	(segment
		(start 76.883768 -127.0254)
		(end 76.883768 -125.476)
		(width 0.14224)
		(layer "In4.Cu")
		(net "M_M_ECC<2>")
	)
	(segment
		(start 83.466432 -106.087672)
		(end 83.466432 -103.052118)
		(width 0.14224)
		(layer "In4.Cu")
		(net "M_M_ECC<2>")
	)
	(segment
		(start 76.883768 -146.312128)
		(end 76.968096 -146.2278)
		(width 0.14224)
		(layer "In4.Cu")
		(net "M_M_ECC<2>")
	)
	(segment
		(start 77.410056 -119.283988)
		(end 77.410056 -112.144048)
		(width 0.14224)
		(layer "In4.Cu")
		(net "M_M_ECC<2>")
	)
	(segment
		(start 82.300826 -84.088986)
		(end 82.630772 -83.32724)
		(width 0.0889)
		(layer "In4.Cu")
		(net "M_M_ECC<2>")
	)
	(segment
		(start 77.031596 -131.8768)
		(end 77.031596 -131.527042)
		(width 0.14224)
		(layer "In4.Cu")
		(net "M_M_ECC<2>")
	)
	(segment
		(start 76.875132 -143.679164)
		(end 76.875132 -141.647164)
		(width 0.14224)
		(layer "In4.Cu")
		(net "M_M_ECC<2>")
	)
	(segment
		(start 76.883768 -136.685528)
		(end 76.942696 -136.6266)
		(width 0.14224)
		(layer "In4.Cu")
		(net "M_M_ECC<2>")
	)
	(segment
		(start 82.977482 -93.433138)
		(end 82.982308 -93.424502)
		(width 0.0889)
		(layer "In4.Cu")
		(net "M_M_ECC<2>")
	)
	(segment
		(start 77.018896 -144.093438)
		(end 77.018896 -143.822928)
		(width 0.14224)
		(layer "In4.Cu")
		(net "M_M_ECC<2>")
	)
	(segment
		(start 76.942696 -129.395728)
		(end 76.451968 -128.905)
		(width 0.14224)
		(layer "In4.Cu")
		(net "M_M_ECC<2>")
	)
	(segment
		(start 76.968096 -148.547328)
		(end 76.883768 -148.463)
		(width 0.14224)
		(layer "In4.Cu")
		(net "M_M_ECC<2>")
	)
	(segment
		(start 76.324968 -149.615906)
		(end 76.968096 -148.972778)
		(width 0.14224)
		(layer "In4.Cu")
		(net "M_M_ECC<2>")
	)
	(segment
		(start 82.935572 -85.035898)
		(end 82.850482 -84.931758)
		(width 0.0889)
		(layer "In4.Cu")
		(net "M_M_ECC<2>")
	)
	(segment
		(start 76.815696 -140.933678)
		(end 76.815696 -139.562078)
		(width 0.14224)
		(layer "In4.Cu")
		(net "M_M_ECC<2>")
	)
	(segment
		(start 76.779882 -129.996692)
		(end 76.942696 -129.833878)
		(width 0.14224)
		(layer "In4.Cu")
		(net "M_M_ECC<2>")
	)
	(segment
		(start 76.451968 -128.905)
		(end 76.451968 -127.4572)
		(width 0.14224)
		(layer "In4.Cu")
		(net "M_M_ECC<2>")
	)
	(segment
		(start 83.628992 -102.889558)
		(end 83.628992 -97.132648)
		(width 0.0889)
		(layer "In4.Cu")
		(net "M_M_ECC<2>")
	)
	(segment
		(start 82.971132 -92.453206)
		(end 82.977482 -92.442538)
		(width 0.0889)
		(layer "In4.Cu")
		(net "M_M_ECC<2>")
	)
	(segment
		(start 76.968096 -145.806668)
		(end 76.739496 -145.578068)
		(width 0.14224)
		(layer "In4.Cu")
		(net "M_M_ECC<2>")
	)
	(segment
		(start 76.779882 -131.275328)
		(end 76.779882 -129.996692)
		(width 0.14224)
		(layer "In4.Cu")
		(net "M_M_ECC<2>")
	)
	(segment
		(start 82.971132 -89.481406)
		(end 82.977482 -89.470738)
		(width 0.0889)
		(layer "In4.Cu")
		(net "M_M_ECC<2>")
	)
	(segment
		(start 76.942696 -138.819128)
		(end 76.883768 -138.7602)
		(width 0.14224)
		(layer "In4.Cu")
		(net "M_M_ECC<2>")
	)
	(segment
		(start 77.018896 -141.5034)
		(end 77.018896 -141.136878)
		(width 0.14224)
		(layer "In4.Cu")
		(net "M_M_ECC<2>")
	)
	(segment
		(start 82.977482 -94.023688)
		(end 82.971132 -94.01302)
		(width 0.0889)
		(layer "In4.Cu")
		(net "M_M_ECC<2>")
	)
	(segment
		(start 82.850482 -84.931758)
		(end 82.792824 -84.879942)
		(width 0.0889)
		(layer "In4.Cu")
		(net "M_M_ECC<2>")
	)
	(segment
		(start 76.883768 -132.024628)
		(end 77.031596 -131.8768)
		(width 0.14224)
		(layer "In4.Cu")
		(net "M_M_ECC<2>")
	)
	(segment
		(start 77.010768 -123.736862)
		(end 75.853036 -122.57913)
		(width 0.14224)
		(layer "In4.Cu")
		(net "M_M_ECC<2>")
	)
	(segment
		(start 82.977482 -91.451938)
		(end 82.982308 -91.443302)
		(width 0.0889)
		(layer "In4.Cu")
		(net "M_M_ECC<2>")
	)
	(segment
		(start 76.942696 -136.6266)
		(end 76.942696 -136.279128)
		(width 0.14224)
		(layer "In4.Cu")
		(net "M_M_ECC<2>")
	)
	(segment
		(start 82.284062 -84.117688)
		(end 82.300826 -84.088986)
		(width 0.0889)
		(layer "In4.Cu")
		(net "M_M_ECC<2>")
	)
	(segment
		(start 77.410056 -112.144048)
		(end 83.466432 -106.087672)
		(width 0.14224)
		(layer "In4.Cu")
		(net "M_M_ECC<2>")
	)
	(segment
		(start 82.977482 -85.108288)
		(end 82.935572 -85.035898)
		(width 0.0889)
		(layer "In4.Cu")
		(net "M_M_ECC<2>")
	)
	(segment
		(start 83.628992 -97.132648)
		(end 82.977482 -96.004888)
		(width 0.0889)
		(layer "In4.Cu")
		(net "M_M_ECC<2>")
	)
	(segment
		(start 76.790296 -134.712964)
		(end 77.031596 -134.471664)
		(width 0.14224)
		(layer "In4.Cu")
		(net "M_M_ECC<2>")
	)
	(segment
		(start 76.942696 -129.833878)
		(end 76.942696 -129.395728)
		(width 0.14224)
		(layer "In4.Cu")
		(net "M_M_ECC<2>")
	)
	(segment
		(start 76.790296 -136.126728)
		(end 76.790296 -134.712964)
		(width 0.14224)
		(layer "In4.Cu")
		(net "M_M_ECC<2>")
	)
	(segment
		(start 77.018896 -141.136878)
		(end 76.815696 -140.933678)
		(width 0.14224)
		(layer "In4.Cu")
		(net "M_M_ECC<2>")
	)
	(segment
		(start 83.466432 -103.052118)
		(end 83.628992 -102.889558)
		(width 0.0889)
		(layer "In4.Cu")
		(net "M_M_ECC<2>")
	)
	(segment
		(start 82.977482 -89.470738)
		(end 82.982308 -89.462102)
		(width 0.0889)
		(layer "In4.Cu")
		(net "M_M_ECC<2>")
	)
	(segment
		(start 82.971132 -90.472006)
		(end 82.977482 -90.461338)
		(width 0.0889)
		(layer "In4.Cu")
		(net "M_M_ECC<2>")
	)
	(segment
		(start 76.451968 -127.4572)
		(end 76.883768 -127.0254)
		(width 0.14224)
		(layer "In4.Cu")
		(net "M_M_ECC<2>")
	)
	(segment
		(start 82.971132 -88.490806)
		(end 82.977482 -88.480138)
		(width 0.0889)
		(layer "In4.Cu")
		(net "M_M_ECC<2>")
	)
	(segment
		(start 82.792824 -84.879942)
		(end 82.533744 -84.706206)
		(width 0.0889)
		(layer "In4.Cu")
		(net "M_M_ECC<2>")
	)
	(segment
		(start 82.971132 -95.425006)
		(end 82.977482 -95.414338)
		(width 0.0889)
		(layer "In4.Cu")
		(net "M_M_ECC<2>")
	)
	(segment
		(start 82.977482 -95.414338)
		(end 82.982308 -95.405702)
		(width 0.0889)
		(layer "In4.Cu")
		(net "M_M_ECC<2>")
	)
	(segment
		(start 82.977482 -85.508338)
		(end 82.982308 -85.499702)
		(width 0.0889)
		(layer "In4.Cu")
		(net "M_M_ECC<2>")
	)
	(segment
		(start 77.018896 -143.822928)
		(end 76.875132 -143.679164)
		(width 0.14224)
		(layer "In4.Cu")
		(net "M_M_ECC<2>")
	)
	(segment
		(start 76.324968 -150.689818)
		(end 76.324968 -149.615906)
		(width 0.14224)
		(layer "In4.Cu")
		(net "M_M_ECC<2>")
	)
	(segment
		(start 76.968096 -148.972778)
		(end 76.968096 -148.547328)
		(width 0.14224)
		(layer "In4.Cu")
		(net "M_M_ECC<2>")
	)
	(segment
		(start 82.971132 -87.500206)
		(end 82.977482 -87.489538)
		(width 0.0889)
		(layer "In4.Cu")
		(net "M_M_ECC<2>")
	)
	(segment
		(start 76.883768 -125.476)
		(end 77.010768 -125.349)
		(width 0.14224)
		(layer "In4.Cu")
		(net "M_M_ECC<2>")
	)
	(segment
		(start 76.883768 -134.112)
		(end 76.883768 -132.024628)
		(width 0.14224)
		(layer "In4.Cu")
		(net "M_M_ECC<2>")
	)
	(segment
		(start 76.883768 -148.463)
		(end 76.883768 -146.312128)
		(width 0.14224)
		(layer "In4.Cu")
		(net "M_M_ECC<2>")
	)
	(segment
		(start 77.010768 -125.349)
		(end 77.010768 -123.736862)
		(width 0.14224)
		(layer "In4.Cu")
		(net "M_M_ECC<2>")
	)
	(segment
		(start 82.977482 -92.442538)
		(end 82.982308 -92.433902)
		(width 0.0889)
		(layer "In4.Cu")
		(net "M_M_ECC<2>")
	)
	(segment
		(start 77.031596 -131.527042)
		(end 76.779882 -131.275328)
		(width 0.14224)
		(layer "In4.Cu")
		(net "M_M_ECC<2>")
	)
	(segment
		(start 76.942696 -136.279128)
		(end 76.790296 -136.126728)
		(width 0.14224)
		(layer "In4.Cu")
		(net "M_M_ECC<2>")
	)
	(segment
		(start 76.883768 -138.7602)
		(end 76.883768 -136.685528)
		(width 0.14224)
		(layer "In4.Cu")
		(net "M_M_ECC<2>")
	)
	(segment
		(start 82.971132 -86.509606)
		(end 82.977482 -86.498938)
		(width 0.0889)
		(layer "In4.Cu")
		(net "M_M_ECC<2>")
	)
	(segment
		(start 75.853036 -120.841008)
		(end 77.410056 -119.283988)
		(width 0.14224)
		(layer "In4.Cu")
		(net "M_M_ECC<2>")
	)
	(segment
		(start 76.875132 -141.647164)
		(end 77.018896 -141.5034)
		(width 0.14224)
		(layer "In4.Cu")
		(net "M_M_ECC<2>")
	)
	(arc
		(start 82.977482 -87.089488)
		(mid 82.89826 -86.80037)
		(end 82.971132 -86.509606)
		(width 0.0889)
		(layer "In4.Cu")
		(net "M_M_ECC<2>")
	)
	(arc
		(start 82.977482 -89.070688)
		(mid 82.89826 -88.78157)
		(end 82.971132 -88.490806)
		(width 0.0889)
		(layer "In4.Cu")
		(net "M_M_ECC<2>")
	)
	(arc
		(start 82.977482 -93.033088)
		(mid 82.89826 -92.74397)
		(end 82.971132 -92.453206)
		(width 0.0889)
		(layer "In4.Cu")
		(net "M_M_ECC<2>")
	)
	(arc
		(start 82.982308 -86.490302)
		(mid 83.031063 -86.29395)
		(end 82.977482 -86.098888)
		(width 0.0889)
		(layer "In4.Cu")
		(net "M_M_ECC<2>")
	)
	(arc
		(start 82.977482 -94.423484)
		(mid 83.030981 -94.223586)
		(end 82.977482 -94.023688)
		(width 0.0889)
		(layer "In4.Cu")
		(net "M_M_ECC<2>")
	)
	(arc
		(start 82.977482 -96.004888)
		(mid 82.89826 -95.71577)
		(end 82.971132 -95.425006)
		(width 0.0889)
		(layer "In4.Cu")
		(net "M_M_ECC<2>")
	)
	(arc
		(start 82.977482 -92.042488)
		(mid 82.89826 -91.75337)
		(end 82.971132 -91.462606)
		(width 0.0889)
		(layer "In4.Cu")
		(net "M_M_ECC<2>")
	)
	(arc
		(start 82.982308 -89.462102)
		(mid 83.031063 -89.26575)
		(end 82.977482 -89.070688)
		(width 0.0889)
		(layer "In4.Cu")
		(net "M_M_ECC<2>")
	)
	(arc
		(start 82.977482 -95.014288)
		(mid 82.898351 -94.718886)
		(end 82.977482 -94.423484)
		(width 0.0889)
		(layer "In4.Cu")
		(net "M_M_ECC<2>")
	)
	(arc
		(start 82.982308 -87.480902)
		(mid 83.031063 -87.28455)
		(end 82.977482 -87.089488)
		(width 0.0889)
		(layer "In4.Cu")
		(net "M_M_ECC<2>")
	)
	(arc
		(start 82.977482 -91.051888)
		(mid 82.89826 -90.76277)
		(end 82.971132 -90.472006)
		(width 0.0889)
		(layer "In4.Cu")
		(net "M_M_ECC<2>")
	)
	(arc
		(start 82.982308 -91.443302)
		(mid 83.031063 -91.24695)
		(end 82.977482 -91.051888)
		(width 0.0889)
		(layer "In4.Cu")
		(net "M_M_ECC<2>")
	)
	(arc
		(start 82.982308 -85.499702)
		(mid 83.031063 -85.30335)
		(end 82.977482 -85.108288)
		(width 0.0889)
		(layer "In4.Cu")
		(net "M_M_ECC<2>")
	)
	(arc
		(start 82.982308 -95.405702)
		(mid 83.031063 -95.20935)
		(end 82.977482 -95.014288)
		(width 0.0889)
		(layer "In4.Cu")
		(net "M_M_ECC<2>")
	)
	(arc
		(start 82.977482 -90.061288)
		(mid 82.89826 -89.77217)
		(end 82.971132 -89.481406)
		(width 0.0889)
		(layer "In4.Cu")
		(net "M_M_ECC<2>")
	)
	(arc
		(start 82.977482 -88.080088)
		(mid 82.89826 -87.79097)
		(end 82.971132 -87.500206)
		(width 0.0889)
		(layer "In4.Cu")
		(net "M_M_ECC<2>")
	)
	(arc
		(start 82.971132 -94.01302)
		(mid 82.898334 -93.722257)
		(end 82.977482 -93.433138)
		(width 0.0889)
		(layer "In4.Cu")
		(net "M_M_ECC<2>")
	)
	(arc
		(start 82.982308 -90.452702)
		(mid 83.031063 -90.25635)
		(end 82.977482 -90.061288)
		(width 0.0889)
		(layer "In4.Cu")
		(net "M_M_ECC<2>")
	)
	(arc
		(start 82.977482 -86.098888)
		(mid 82.89826 -85.80977)
		(end 82.971132 -85.519006)
		(width 0.0889)
		(layer "In4.Cu")
		(net "M_M_ECC<2>")
	)
	(arc
		(start 82.982308 -92.433902)
		(mid 83.031063 -92.23755)
		(end 82.977482 -92.042488)
		(width 0.0889)
		(layer "In4.Cu")
		(net "M_M_ECC<2>")
	)
	(arc
		(start 82.533744 -84.706206)
		(mid 82.262257 -84.474171)
		(end 82.284062 -84.117688)
		(width 0.0889)
		(layer "In4.Cu")
		(net "M_M_ECC<2>")
	)
	(arc
		(start 82.982308 -88.471502)
		(mid 83.031063 -88.27515)
		(end 82.977482 -88.080088)
		(width 0.0889)
		(layer "In4.Cu")
		(net "M_M_ECC<2>")
	)
	(arc
		(start 82.982308 -93.424502)
		(mid 83.031063 -93.22815)
		(end 82.977482 -93.033088)
		(width 0.0889)
		(layer "In4.Cu")
		(net "M_M_ECC<2>")
	)
	(segment
		(start 76.016358 -151.247348)
		(end 76.449428 -150.814278)
		(width 0.14224)
		(layer "In11.Cu")
		(net "M_M_ECC<2>")
	)
	(segment
		(start 76.016358 -153.834846)
		(end 76.016358 -151.247348)
		(width 0.14224)
		(layer "In11.Cu")
		(net "M_M_ECC<2>")
	)
	(segment
		(start 77.299312 -155.1178)
		(end 76.016358 -153.834846)
		(width 0.14224)
		(layer "In11.Cu")
		(net "M_M_ECC<2>")
	)
	(segment
		(start 80.626712 -84.812886)
		(end 80.055212 -84.812886)
		(width 0.1651)
		(layer "F.Cu")
		(net "M_M_ECC<1>")
	)
	(segment
		(start 70.499478 -152.273)
		(end 70.499478 -153.542746)
		(width 0.1651)
		(layer "F.Cu")
		(net "M_M_ECC<1>")
	)
	(via
		(at 80.055212 -84.812886)
		(size 0.508)
		(drill 0.254)
		(layers "F.Cu" "B.Cu")
		(net "M_M_ECC<1>")
	)
	(via
		(at 71.171562 -149.533356)
		(size 0.508)
		(drill 0.254)
		(layers "F.Cu" "B.Cu")
		(net "M_M_ECC<1>")
	)
	(via
		(at 70.499478 -153.542746)
		(size 0.508)
		(drill 0.254)
		(layers "F.Cu" "B.Cu")
		(net "M_M_ECC<1>")
	)
	(segment
		(start 71.349362 -147.478496)
		(end 71.349362 -148.852382)
		(width 0.1651)
		(layer "B.Cu")
		(net "M_M_ECC<1>")
	)
	(segment
		(start 71.171562 -149.030182)
		(end 71.171562 -149.533356)
		(width 0.1651)
		(layer "B.Cu")
		(net "M_M_ECC<1>")
	)
	(segment
		(start 71.349362 -148.852382)
		(end 71.171562 -149.030182)
		(width 0.1651)
		(layer "B.Cu")
		(net "M_M_ECC<1>")
	)
	(segment
		(start 79.708502 -91.547188)
		(end 79.703676 -91.555824)
		(width 0.0889)
		(layer "In4.Cu")
		(net "M_M_ECC<1>")
	)
	(segment
		(start 79.119984 -101.468682)
		(end 79.33055 -101.679248)
		(width 0.0889)
		(layer "In4.Cu")
		(net "M_M_ECC<1>")
	)
	(segment
		(start 73.048368 -111.023654)
		(end 73.048368 -114.203988)
		(width 0.14224)
		(layer "In4.Cu")
		(net "M_M_ECC<1>")
	)
	(segment
		(start 79.543656 -100.147882)
		(end 79.119984 -100.571554)
		(width 0.0889)
		(layer "In4.Cu")
		(net "M_M_ECC<1>")
	)
	(segment
		(start 72.815196 -114.43716)
		(end 72.408796 -114.43716)
		(width 0.14224)
		(layer "In4.Cu")
		(net "M_M_ECC<1>")
	)
	(segment
		(start 79.33055 -101.679248)
		(end 79.33055 -104.741472)
		(width 0.14224)
		(layer "In4.Cu")
		(net "M_M_ECC<1>")
	)
	(segment
		(start 71.171562 -149.444456)
		(end 71.171562 -149.533356)
		(width 0.14224)
		(layer "In4.Cu")
		(net "M_M_ECC<1>")
	)
	(segment
		(start 71.778368 -142.9004)
		(end 71.659496 -143.019272)
		(width 0.14224)
		(layer "In4.Cu")
		(net "M_M_ECC<1>")
	)
	(segment
		(start 71.778368 -132.0546)
		(end 71.778368 -134.0866)
		(width 0.14224)
		(layer "In4.Cu")
		(net "M_M_ECC<1>")
	)
	(segment
		(start 79.714852 -88.56472)
		(end 79.708502 -88.575388)
		(width 0.0889)
		(layer "In4.Cu")
		(net "M_M_ECC<1>")
	)
	(segment
		(start 79.708502 -88.575388)
		(end 79.703676 -88.584024)
		(width 0.0889)
		(layer "In4.Cu")
		(net "M_M_ECC<1>")
	)
	(segment
		(start 71.659496 -146.2024)
		(end 71.778368 -146.321272)
		(width 0.14224)
		(layer "In4.Cu")
		(net "M_M_ECC<1>")
	)
	(segment
		(start 71.659496 -134.205472)
		(end 71.659496 -136.5758)
		(width 0.14224)
		(layer "In4.Cu")
		(net "M_M_ECC<1>")
	)
	(segment
		(start 79.714852 -97.48012)
		(end 79.708502 -97.490788)
		(width 0.0889)
		(layer "In4.Cu")
		(net "M_M_ECC<1>")
	)
	(segment
		(start 71.778368 -136.694672)
		(end 71.778368 -138.7602)
		(width 0.14224)
		(layer "In4.Cu")
		(net "M_M_ECC<1>")
	)
	(segment
		(start 79.725774 -85.57387)
		(end 79.703676 -85.612224)
		(width 0.0889)
		(layer "In4.Cu")
		(net "M_M_ECC<1>")
	)
	(segment
		(start 79.714852 -87.57412)
		(end 79.708502 -87.584788)
		(width 0.0889)
		(layer "In4.Cu")
		(net "M_M_ECC<1>")
	)
	(segment
		(start 71.778368 -138.7602)
		(end 71.659496 -138.879072)
		(width 0.14224)
		(layer "In4.Cu")
		(net "M_M_ECC<1>")
	)
	(segment
		(start 79.708502 -94.518988)
		(end 79.703676 -94.527624)
		(width 0.0889)
		(layer "In4.Cu")
		(net "M_M_ECC<1>")
	)
	(segment
		(start 79.714852 -90.54592)
		(end 79.708502 -90.556588)
		(width 0.0889)
		(layer "In4.Cu")
		(net "M_M_ECC<1>")
	)
	(segment
		(start 79.714852 -96.48952)
		(end 79.708502 -96.500188)
		(width 0.0889)
		(layer "In4.Cu")
		(net "M_M_ECC<1>")
	)
	(segment
		(start 79.708502 -90.556588)
		(end 79.703676 -90.565224)
		(width 0.0889)
		(layer "In4.Cu")
		(net "M_M_ECC<1>")
	)
	(segment
		(start 79.714852 -92.52712)
		(end 79.708502 -92.537788)
		(width 0.0889)
		(layer "In4.Cu")
		(net "M_M_ECC<1>")
	)
	(segment
		(start 71.778368 -134.0866)
		(end 71.659496 -134.205472)
		(width 0.14224)
		(layer "In4.Cu")
		(net "M_M_ECC<1>")
	)
	(segment
		(start 71.659496 -136.5758)
		(end 71.778368 -136.694672)
		(width 0.14224)
		(layer "In4.Cu")
		(net "M_M_ECC<1>")
	)
	(segment
		(start 71.659496 -131.935728)
		(end 71.778368 -132.0546)
		(width 0.14224)
		(layer "In4.Cu")
		(net "M_M_ECC<1>")
	)
	(segment
		(start 72.062086 -112.68964)
		(end 71.655686 -112.68964)
		(width 0.14224)
		(layer "In4.Cu")
		(net "M_M_ECC<1>")
	)
	(segment
		(start 79.708502 -92.537788)
		(end 79.703676 -92.546424)
		(width 0.0889)
		(layer "In4.Cu")
		(net "M_M_ECC<1>")
	)
	(segment
		(start 79.714852 -89.55532)
		(end 79.708502 -89.565988)
		(width 0.0889)
		(layer "In4.Cu")
		(net "M_M_ECC<1>")
	)
	(segment
		(start 79.714852 -91.53652)
		(end 79.708502 -91.547188)
		(width 0.0889)
		(layer "In4.Cu")
		(net "M_M_ECC<1>")
	)
	(segment
		(start 79.708502 -89.565988)
		(end 79.703676 -89.574624)
		(width 0.0889)
		(layer "In4.Cu")
		(net "M_M_ECC<1>")
	)
	(segment
		(start 71.655686 -112.68964)
		(end 71.422768 -112.922558)
		(width 0.14224)
		(layer "In4.Cu")
		(net "M_M_ECC<1>")
	)
	(segment
		(start 79.708502 -97.490788)
		(end 79.703676 -97.499424)
		(width 0.0889)
		(layer "In4.Cu")
		(net "M_M_ECC<1>")
	)
	(segment
		(start 79.708502 -86.594188)
		(end 79.703676 -86.602824)
		(width 0.0889)
		(layer "In4.Cu")
		(net "M_M_ECC<1>")
	)
	(segment
		(start 79.714852 -98.47072)
		(end 79.543656 -98.775266)
		(width 0.0889)
		(layer "In4.Cu")
		(net "M_M_ECC<1>")
	)
	(segment
		(start 71.659496 -143.019272)
		(end 71.659496 -146.2024)
		(width 0.14224)
		(layer "In4.Cu")
		(net "M_M_ECC<1>")
	)
	(segment
		(start 79.708502 -93.928438)
		(end 79.714852 -93.939106)
		(width 0.0889)
		(layer "In4.Cu")
		(net "M_M_ECC<1>")
	)
	(segment
		(start 80.055212 -84.812886)
		(end 79.725774 -85.57387)
		(width 0.0889)
		(layer "In4.Cu")
		(net "M_M_ECC<1>")
	)
	(segment
		(start 71.778368 -141.469872)
		(end 71.778368 -142.9004)
		(width 0.14224)
		(layer "In4.Cu")
		(net "M_M_ECC<1>")
	)
	(segment
		(start 73.048368 -114.203988)
		(end 72.815196 -114.43716)
		(width 0.14224)
		(layer "In4.Cu")
		(net "M_M_ECC<1>")
	)
	(segment
		(start 79.708502 -87.584788)
		(end 79.703676 -87.593424)
		(width 0.0889)
		(layer "In4.Cu")
		(net "M_M_ECC<1>")
	)
	(segment
		(start 72.408796 -114.43716)
		(end 72.235568 -114.263932)
		(width 0.14224)
		(layer "In4.Cu")
		(net "M_M_ECC<1>")
	)
	(segment
		(start 71.422768 -123.6472)
		(end 71.659496 -123.883928)
		(width 0.14224)
		(layer "In4.Cu")
		(net "M_M_ECC<1>")
	)
	(segment
		(start 71.659496 -123.883928)
		(end 71.659496 -131.935728)
		(width 0.14224)
		(layer "In4.Cu")
		(net "M_M_ECC<1>")
	)
	(segment
		(start 79.708502 -96.500188)
		(end 79.703676 -96.508824)
		(width 0.0889)
		(layer "In4.Cu")
		(net "M_M_ECC<1>")
	)
	(segment
		(start 71.659496 -148.404072)
		(end 71.659496 -148.956522)
		(width 0.14224)
		(layer "In4.Cu")
		(net "M_M_ECC<1>")
	)
	(segment
		(start 79.714852 -86.58352)
		(end 79.708502 -86.594188)
		(width 0.0889)
		(layer "In4.Cu")
		(net "M_M_ECC<1>")
	)
	(segment
		(start 72.235568 -114.263932)
		(end 72.235568 -112.863122)
		(width 0.14224)
		(layer "In4.Cu")
		(net "M_M_ECC<1>")
	)
	(segment
		(start 71.422768 -112.922558)
		(end 71.422768 -123.6472)
		(width 0.14224)
		(layer "In4.Cu")
		(net "M_M_ECC<1>")
	)
	(segment
		(start 71.659496 -138.879072)
		(end 71.659496 -141.351)
		(width 0.14224)
		(layer "In4.Cu")
		(net "M_M_ECC<1>")
	)
	(segment
		(start 79.33055 -104.741472)
		(end 73.048368 -111.023654)
		(width 0.14224)
		(layer "In4.Cu")
		(net "M_M_ECC<1>")
	)
	(segment
		(start 79.543656 -98.775266)
		(end 79.543656 -100.147882)
		(width 0.0889)
		(layer "In4.Cu")
		(net "M_M_ECC<1>")
	)
	(segment
		(start 72.235568 -112.863122)
		(end 72.062086 -112.68964)
		(width 0.14224)
		(layer "In4.Cu")
		(net "M_M_ECC<1>")
	)
	(segment
		(start 79.119984 -100.571554)
		(end 79.119984 -101.468682)
		(width 0.0889)
		(layer "In4.Cu")
		(net "M_M_ECC<1>")
	)
	(segment
		(start 79.714852 -95.49892)
		(end 79.708502 -95.509588)
		(width 0.0889)
		(layer "In4.Cu")
		(net "M_M_ECC<1>")
	)
	(segment
		(start 71.778368 -148.2852)
		(end 71.659496 -148.404072)
		(width 0.14224)
		(layer "In4.Cu")
		(net "M_M_ECC<1>")
	)
	(segment
		(start 79.708502 -95.509588)
		(end 79.703676 -95.518224)
		(width 0.0889)
		(layer "In4.Cu")
		(net "M_M_ECC<1>")
	)
	(segment
		(start 71.659496 -141.351)
		(end 71.778368 -141.469872)
		(width 0.14224)
		(layer "In4.Cu")
		(net "M_M_ECC<1>")
	)
	(segment
		(start 71.778368 -146.321272)
		(end 71.778368 -148.2852)
		(width 0.14224)
		(layer "In4.Cu")
		(net "M_M_ECC<1>")
	)
	(segment
		(start 71.659496 -148.956522)
		(end 71.171562 -149.444456)
		(width 0.14224)
		(layer "In4.Cu")
		(net "M_M_ECC<1>")
	)
	(arc
		(start 79.703676 -95.518224)
		(mid 79.654921 -95.714576)
		(end 79.708502 -95.909638)
		(width 0.0889)
		(layer "In4.Cu")
		(net "M_M_ECC<1>")
	)
	(arc
		(start 79.708502 -90.956638)
		(mid 79.787724 -91.245756)
		(end 79.714852 -91.53652)
		(width 0.0889)
		(layer "In4.Cu")
		(net "M_M_ECC<1>")
	)
	(arc
		(start 79.708502 -87.984838)
		(mid 79.787724 -88.273956)
		(end 79.714852 -88.56472)
		(width 0.0889)
		(layer "In4.Cu")
		(net "M_M_ECC<1>")
	)
	(arc
		(start 79.708502 -93.528642)
		(mid 79.655003 -93.72854)
		(end 79.708502 -93.928438)
		(width 0.0889)
		(layer "In4.Cu")
		(net "M_M_ECC<1>")
	)
	(arc
		(start 79.703676 -92.546424)
		(mid 79.654921 -92.742776)
		(end 79.708502 -92.937838)
		(width 0.0889)
		(layer "In4.Cu")
		(net "M_M_ECC<1>")
	)
	(arc
		(start 79.714852 -93.939106)
		(mid 79.78765 -94.229869)
		(end 79.708502 -94.518988)
		(width 0.0889)
		(layer "In4.Cu")
		(net "M_M_ECC<1>")
	)
	(arc
		(start 79.708502 -86.994238)
		(mid 79.787724 -87.283356)
		(end 79.714852 -87.57412)
		(width 0.0889)
		(layer "In4.Cu")
		(net "M_M_ECC<1>")
	)
	(arc
		(start 79.703676 -90.565224)
		(mid 79.654921 -90.761576)
		(end 79.708502 -90.956638)
		(width 0.0889)
		(layer "In4.Cu")
		(net "M_M_ECC<1>")
	)
	(arc
		(start 79.708502 -94.919038)
		(mid 79.787724 -95.208156)
		(end 79.714852 -95.49892)
		(width 0.0889)
		(layer "In4.Cu")
		(net "M_M_ECC<1>")
	)
	(arc
		(start 79.708502 -89.966038)
		(mid 79.787724 -90.255156)
		(end 79.714852 -90.54592)
		(width 0.0889)
		(layer "In4.Cu")
		(net "M_M_ECC<1>")
	)
	(arc
		(start 79.703676 -85.612224)
		(mid 79.654921 -85.808576)
		(end 79.708502 -86.003638)
		(width 0.0889)
		(layer "In4.Cu")
		(net "M_M_ECC<1>")
	)
	(arc
		(start 79.703676 -91.555824)
		(mid 79.654921 -91.752176)
		(end 79.708502 -91.947238)
		(width 0.0889)
		(layer "In4.Cu")
		(net "M_M_ECC<1>")
	)
	(arc
		(start 79.703676 -88.584024)
		(mid 79.654921 -88.780376)
		(end 79.708502 -88.975438)
		(width 0.0889)
		(layer "In4.Cu")
		(net "M_M_ECC<1>")
	)
	(arc
		(start 79.708502 -92.937838)
		(mid 79.787633 -93.23324)
		(end 79.708502 -93.528642)
		(width 0.0889)
		(layer "In4.Cu")
		(net "M_M_ECC<1>")
	)
	(arc
		(start 79.708502 -96.900238)
		(mid 79.787724 -97.189356)
		(end 79.714852 -97.48012)
		(width 0.0889)
		(layer "In4.Cu")
		(net "M_M_ECC<1>")
	)
	(arc
		(start 79.708502 -86.003638)
		(mid 79.787724 -86.292756)
		(end 79.714852 -86.58352)
		(width 0.0889)
		(layer "In4.Cu")
		(net "M_M_ECC<1>")
	)
	(arc
		(start 79.708502 -91.947238)
		(mid 79.787724 -92.236356)
		(end 79.714852 -92.52712)
		(width 0.0889)
		(layer "In4.Cu")
		(net "M_M_ECC<1>")
	)
	(arc
		(start 79.703676 -96.508824)
		(mid 79.654921 -96.705176)
		(end 79.708502 -96.900238)
		(width 0.0889)
		(layer "In4.Cu")
		(net "M_M_ECC<1>")
	)
	(arc
		(start 79.708502 -97.890838)
		(mid 79.787724 -98.179956)
		(end 79.714852 -98.47072)
		(width 0.0889)
		(layer "In4.Cu")
		(net "M_M_ECC<1>")
	)
	(arc
		(start 79.703676 -97.499424)
		(mid 79.654921 -97.695776)
		(end 79.708502 -97.890838)
		(width 0.0889)
		(layer "In4.Cu")
		(net "M_M_ECC<1>")
	)
	(arc
		(start 79.703676 -89.574624)
		(mid 79.654921 -89.770976)
		(end 79.708502 -89.966038)
		(width 0.0889)
		(layer "In4.Cu")
		(net "M_M_ECC<1>")
	)
	(arc
		(start 79.703676 -86.602824)
		(mid 79.654921 -86.799176)
		(end 79.708502 -86.994238)
		(width 0.0889)
		(layer "In4.Cu")
		(net "M_M_ECC<1>")
	)
	(arc
		(start 79.708502 -95.909638)
		(mid 79.787724 -96.198756)
		(end 79.714852 -96.48952)
		(width 0.0889)
		(layer "In4.Cu")
		(net "M_M_ECC<1>")
	)
	(arc
		(start 79.703676 -87.593424)
		(mid 79.654921 -87.789776)
		(end 79.708502 -87.984838)
		(width 0.0889)
		(layer "In4.Cu")
		(net "M_M_ECC<1>")
	)
	(arc
		(start 79.703676 -94.527624)
		(mid 79.654921 -94.723976)
		(end 79.708502 -94.919038)
		(width 0.0889)
		(layer "In4.Cu")
		(net "M_M_ECC<1>")
	)
	(arc
		(start 79.708502 -88.975438)
		(mid 79.787724 -89.264556)
		(end 79.714852 -89.55532)
		(width 0.0889)
		(layer "In4.Cu")
		(net "M_M_ECC<1>")
	)
	(segment
		(start 70.900544 -153.0858)
		(end 70.660768 -152.846024)
		(width 0.14224)
		(layer "In11.Cu")
		(net "M_M_ECC<1>")
	)
	(segment
		(start 70.748398 -153.542746)
		(end 70.900544 -153.3906)
		(width 0.14224)
		(layer "In11.Cu")
		(net "M_M_ECC<1>")
	)
	(segment
		(start 70.720966 -149.983952)
		(end 71.171562 -149.533356)
		(width 0.14224)
		(layer "In11.Cu")
		(net "M_M_ECC<1>")
	)
	(segment
		(start 70.900544 -153.3906)
		(end 70.900544 -153.0858)
		(width 0.14224)
		(layer "In11.Cu")
		(net "M_M_ECC<1>")
	)
	(segment
		(start 70.951344 -151.026368)
		(end 70.951344 -150.621746)
		(width 0.14224)
		(layer "In11.Cu")
		(net "M_M_ECC<1>")
	)
	(segment
		(start 70.875144 -151.892)
		(end 70.660768 -151.677624)
		(width 0.14224)
		(layer "In11.Cu")
		(net "M_M_ECC<1>")
	)
	(segment
		(start 70.951344 -150.621746)
		(end 70.720966 -150.391368)
		(width 0.14224)
		(layer "In11.Cu")
		(net "M_M_ECC<1>")
	)
	(segment
		(start 70.660768 -151.316944)
		(end 70.951344 -151.026368)
		(width 0.14224)
		(layer "In11.Cu")
		(net "M_M_ECC<1>")
	)
	(segment
		(start 70.720966 -150.391368)
		(end 70.720966 -149.983952)
		(width 0.14224)
		(layer "In11.Cu")
		(net "M_M_ECC<1>")
	)
	(segment
		(start 70.499478 -153.542746)
		(end 70.748398 -153.542746)
		(width 0.14224)
		(layer "In11.Cu")
		(net "M_M_ECC<1>")
	)
	(segment
		(start 70.660768 -151.677624)
		(end 70.660768 -151.316944)
		(width 0.14224)
		(layer "In11.Cu")
		(net "M_M_ECC<1>")
	)
	(segment
		(start 70.660768 -152.846024)
		(end 70.660768 -152.538176)
		(width 0.14224)
		(layer "In11.Cu")
		(net "M_M_ECC<1>")
	)
	(segment
		(start 70.660768 -152.538176)
		(end 70.875144 -152.3238)
		(width 0.14224)
		(layer "In11.Cu")
		(net "M_M_ECC<1>")
	)
	(segment
		(start 70.875144 -152.3238)
		(end 70.875144 -151.892)
		(width 0.14224)
		(layer "In11.Cu")
		(net "M_M_ECC<1>")
	)
	(segment
		(start 71.349362 -156.878782)
		(end 71.171562 -155.0162)
		(width 0.1651)
		(layer "F.Cu")
		(net "M_M_ECC<0>")
	)
	(segment
		(start 71.349362 -156.87294)
		(end 71.349362 -156.878782)
		(width 0.1651)
		(layer "F.Cu")
		(net "M_M_ECC<0>")
	)
	(segment
		(start 80.626712 -82.83194)
		(end 80.055212 -82.83194)
		(width 0.1651)
		(layer "F.Cu")
		(net "M_M_ECC<0>")
	)
	(via
		(at 71.171562 -155.0162)
		(size 0.508)
		(drill 0.254)
		(layers "F.Cu" "B.Cu")
		(net "M_M_ECC<0>")
	)
	(via
		(at 70.499478 -150.814278)
		(size 0.508)
		(drill 0.254)
		(layers "F.Cu" "B.Cu")
		(net "M_M_ECC<0>")
	)
	(via
		(at 80.055212 -82.83194)
		(size 0.508)
		(drill 0.254)
		(layers "F.Cu" "B.Cu")
		(net "M_M_ECC<0>")
	)
	(segment
		(start 70.499478 -152.078436)
		(end 70.499478 -150.814278)
		(width 0.1651)
		(layer "B.Cu")
		(net "M_M_ECC<0>")
	)
	(segment
		(start 79.353664 -98.725736)
		(end 79.353664 -100.069142)
		(width 0.0889)
		(layer "In4.Cu")
		(net "M_M_ECC<0>")
	)
	(segment
		(start 79.537052 -94.01302)
		(end 79.543402 -94.023688)
		(width 0.0889)
		(layer "In4.Cu")
		(net "M_M_ECC<0>")
	)
	(segment
		(start 79.543402 -91.451938)
		(end 79.537052 -91.462606)
		(width 0.0889)
		(layer "In4.Cu")
		(net "M_M_ECC<0>")
	)
	(segment
		(start 79.543402 -95.414338)
		(end 79.537052 -95.425006)
		(width 0.0889)
		(layer "In4.Cu")
		(net "M_M_ECC<0>")
	)
	(segment
		(start 79.543402 -90.461338)
		(end 79.537052 -90.472006)
		(width 0.0889)
		(layer "In4.Cu")
		(net "M_M_ECC<0>")
	)
	(segment
		(start 80.055212 -82.83194)
		(end 79.560166 -83.497674)
		(width 0.0889)
		(layer "In4.Cu")
		(net "M_M_ECC<0>")
	)
	(segment
		(start 79.548228 -93.424502)
		(end 79.543402 -93.433138)
		(width 0.0889)
		(layer "In4.Cu")
		(net "M_M_ECC<0>")
	)
	(segment
		(start 78.929992 -100.492814)
		(end 78.929992 -101.483414)
		(width 0.0889)
		(layer "In4.Cu")
		(net "M_M_ECC<0>")
	)
	(segment
		(start 71.024496 -139.320778)
		(end 70.681596 -139.663678)
		(width 0.14224)
		(layer "In4.Cu")
		(net "M_M_ECC<0>")
	)
	(segment
		(start 79.548228 -98.377502)
		(end 79.353664 -98.725736)
		(width 0.0889)
		(layer "In4.Cu")
		(net "M_M_ECC<0>")
	)
	(segment
		(start 70.95617 -131.416552)
		(end 70.95617 -134.496302)
		(width 0.14224)
		(layer "In4.Cu")
		(net "M_M_ECC<0>")
	)
	(segment
		(start 70.704964 -125.443996)
		(end 70.969632 -125.708664)
		(width 0.14224)
		(layer "In4.Cu")
		(net "M_M_ECC<0>")
	)
	(segment
		(start 72.057768 -111.36884)
		(end 72.233282 -111.544354)
		(width 0.14224)
		(layer "In4.Cu")
		(net "M_M_ECC<0>")
	)
	(segment
		(start 79.543402 -92.442538)
		(end 79.537052 -92.453206)
		(width 0.0889)
		(layer "In4.Cu")
		(net "M_M_ECC<0>")
	)
	(segment
		(start 70.973696 -144.085818)
		(end 70.694296 -144.365218)
		(width 0.14224)
		(layer "In4.Cu")
		(net "M_M_ECC<0>")
	)
	(segment
		(start 79.548228 -92.433902)
		(end 79.543402 -92.442538)
		(width 0.0889)
		(layer "In4.Cu")
		(net "M_M_ECC<0>")
	)
	(segment
		(start 70.681596 -139.663678)
		(end 70.681596 -140.743178)
		(width 0.14224)
		(layer "In4.Cu")
		(net "M_M_ECC<0>")
	)
	(segment
		(start 70.969632 -125.708664)
		(end 70.969632 -129.774442)
		(width 0.14224)
		(layer "In4.Cu")
		(net "M_M_ECC<0>")
	)
	(segment
		(start 72.233282 -111.858806)
		(end 71.946008 -112.14608)
		(width 0.14224)
		(layer "In4.Cu")
		(net "M_M_ECC<0>")
	)
	(segment
		(start 79.548228 -91.443302)
		(end 79.543402 -91.451938)
		(width 0.0889)
		(layer "In4.Cu")
		(net "M_M_ECC<0>")
	)
	(segment
		(start 70.95617 -134.496302)
		(end 70.681596 -134.770876)
		(width 0.14224)
		(layer "In4.Cu")
		(net "M_M_ECC<0>")
	)
	(segment
		(start 71.024496 -136.304528)
		(end 71.024496 -139.320778)
		(width 0.14224)
		(layer "In4.Cu")
		(net "M_M_ECC<0>")
	)
	(segment
		(start 71.685404 -112.14608)
		(end 71.482966 -111.943642)
		(width 0.14224)
		(layer "In4.Cu")
		(net "M_M_ECC<0>")
	)
	(segment
		(start 70.681596 -140.743178)
		(end 70.973696 -141.035278)
		(width 0.14224)
		(layer "In4.Cu")
		(net "M_M_ECC<0>")
	)
	(segment
		(start 79.543402 -97.395538)
		(end 79.537052 -97.406206)
		(width 0.0889)
		(layer "In4.Cu")
		(net "M_M_ECC<0>")
	)
	(segment
		(start 70.681596 -135.961628)
		(end 71.024496 -136.304528)
		(width 0.14224)
		(layer "In4.Cu")
		(net "M_M_ECC<0>")
	)
	(segment
		(start 78.69555 -104.44353)
		(end 72.057768 -111.081312)
		(width 0.14224)
		(layer "In4.Cu")
		(net "M_M_ECC<0>")
	)
	(segment
		(start 71.946008 -112.14608)
		(end 71.685404 -112.14608)
		(width 0.14224)
		(layer "In4.Cu")
		(net "M_M_ECC<0>")
	)
	(segment
		(start 79.543402 -85.508338)
		(end 79.537052 -85.519006)
		(width 0.0889)
		(layer "In4.Cu")
		(net "M_M_ECC<0>")
	)
	(segment
		(start 79.548228 -90.452702)
		(end 79.543402 -90.461338)
		(width 0.0889)
		(layer "In4.Cu")
		(net "M_M_ECC<0>")
	)
	(segment
		(start 79.548228 -88.471502)
		(end 79.543402 -88.480138)
		(width 0.0889)
		(layer "In4.Cu")
		(net "M_M_ECC<0>")
	)
	(segment
		(start 70.694296 -145.550382)
		(end 70.986396 -145.842482)
		(width 0.14224)
		(layer "In4.Cu")
		(net "M_M_ECC<0>")
	)
	(segment
		(start 70.704964 -124.009404)
		(end 70.704964 -125.443996)
		(width 0.14224)
		(layer "In4.Cu")
		(net "M_M_ECC<0>")
	)
	(segment
		(start 70.986396 -148.960078)
		(end 70.499478 -149.446996)
		(width 0.14224)
		(layer "In4.Cu")
		(net "M_M_ECC<0>")
	)
	(segment
		(start 70.499478 -149.446996)
		(end 70.499478 -150.814278)
		(width 0.14224)
		(layer "In4.Cu")
		(net "M_M_ECC<0>")
	)
	(segment
		(start 79.548228 -95.405702)
		(end 79.543402 -95.414338)
		(width 0.0889)
		(layer "In4.Cu")
		(net "M_M_ECC<0>")
	)
	(segment
		(start 79.548228 -84.509102)
		(end 79.543402 -84.517738)
		(width 0.0889)
		(layer "In4.Cu")
		(net "M_M_ECC<0>")
	)
	(segment
		(start 70.986396 -145.842482)
		(end 70.986396 -148.960078)
		(width 0.14224)
		(layer "In4.Cu")
		(net "M_M_ECC<0>")
	)
	(segment
		(start 79.543402 -84.517738)
		(end 79.537052 -84.528406)
		(width 0.0889)
		(layer "In4.Cu")
		(net "M_M_ECC<0>")
	)
	(segment
		(start 70.681596 -130.062478)
		(end 70.681596 -131.141978)
		(width 0.14224)
		(layer "In4.Cu")
		(net "M_M_ECC<0>")
	)
	(segment
		(start 70.787768 -112.351312)
		(end 70.787768 -123.9266)
		(width 0.14224)
		(layer "In4.Cu")
		(net "M_M_ECC<0>")
	)
	(segment
		(start 79.548228 -87.480902)
		(end 79.543402 -87.489538)
		(width 0.0889)
		(layer "In4.Cu")
		(net "M_M_ECC<0>")
	)
	(segment
		(start 72.057768 -111.081312)
		(end 72.057768 -111.36884)
		(width 0.14224)
		(layer "In4.Cu")
		(net "M_M_ECC<0>")
	)
	(segment
		(start 79.543402 -96.404938)
		(end 79.537052 -96.415606)
		(width 0.0889)
		(layer "In4.Cu")
		(net "M_M_ECC<0>")
	)
	(segment
		(start 79.543402 -86.498938)
		(end 79.537052 -86.509606)
		(width 0.0889)
		(layer "In4.Cu")
		(net "M_M_ECC<0>")
	)
	(segment
		(start 70.694296 -144.365218)
		(end 70.694296 -145.550382)
		(width 0.14224)
		(layer "In4.Cu")
		(net "M_M_ECC<0>")
	)
	(segment
		(start 79.548228 -89.462102)
		(end 79.543402 -89.470738)
		(width 0.0889)
		(layer "In4.Cu")
		(net "M_M_ECC<0>")
	)
	(segment
		(start 71.482966 -111.943642)
		(end 71.195438 -111.943642)
		(width 0.14224)
		(layer "In4.Cu")
		(net "M_M_ECC<0>")
	)
	(segment
		(start 79.560166 -83.497674)
		(end 79.543402 -83.527138)
		(width 0.0889)
		(layer "In4.Cu")
		(net "M_M_ECC<0>")
	)
	(segment
		(start 70.787768 -123.9266)
		(end 70.704964 -124.009404)
		(width 0.14224)
		(layer "In4.Cu")
		(net "M_M_ECC<0>")
	)
	(segment
		(start 78.929992 -101.483414)
		(end 78.69555 -101.717856)
		(width 0.0889)
		(layer "In4.Cu")
		(net "M_M_ECC<0>")
	)
	(segment
		(start 79.548228 -97.386902)
		(end 79.543402 -97.395538)
		(width 0.0889)
		(layer "In4.Cu")
		(net "M_M_ECC<0>")
	)
	(segment
		(start 79.543402 -89.470738)
		(end 79.537052 -89.481406)
		(width 0.0889)
		(layer "In4.Cu")
		(net "M_M_ECC<0>")
	)
	(segment
		(start 71.195438 -111.943642)
		(end 70.787768 -112.351312)
		(width 0.14224)
		(layer "In4.Cu")
		(net "M_M_ECC<0>")
	)
	(segment
		(start 78.69555 -101.717856)
		(end 78.69555 -104.44353)
		(width 0.14224)
		(layer "In4.Cu")
		(net "M_M_ECC<0>")
	)
	(segment
		(start 72.233282 -111.544354)
		(end 72.233282 -111.858806)
		(width 0.14224)
		(layer "In4.Cu")
		(net "M_M_ECC<0>")
	)
	(segment
		(start 79.543402 -88.480138)
		(end 79.537052 -88.490806)
		(width 0.0889)
		(layer "In4.Cu")
		(net "M_M_ECC<0>")
	)
	(segment
		(start 79.548228 -86.490302)
		(end 79.543402 -86.498938)
		(width 0.0889)
		(layer "In4.Cu")
		(net "M_M_ECC<0>")
	)
	(segment
		(start 70.973696 -141.035278)
		(end 70.973696 -144.085818)
		(width 0.14224)
		(layer "In4.Cu")
		(net "M_M_ECC<0>")
	)
	(segment
		(start 79.543402 -83.527138)
		(end 79.537052 -83.537806)
		(width 0.0889)
		(layer "In4.Cu")
		(net "M_M_ECC<0>")
	)
	(segment
		(start 70.681596 -131.141978)
		(end 70.95617 -131.416552)
		(width 0.14224)
		(layer "In4.Cu")
		(net "M_M_ECC<0>")
	)
	(segment
		(start 70.681596 -134.770876)
		(end 70.681596 -135.961628)
		(width 0.14224)
		(layer "In4.Cu")
		(net "M_M_ECC<0>")
	)
	(segment
		(start 79.543402 -87.489538)
		(end 79.537052 -87.500206)
		(width 0.0889)
		(layer "In4.Cu")
		(net "M_M_ECC<0>")
	)
	(segment
		(start 79.353664 -100.069142)
		(end 78.929992 -100.492814)
		(width 0.0889)
		(layer "In4.Cu")
		(net "M_M_ECC<0>")
	)
	(segment
		(start 70.969632 -129.774442)
		(end 70.681596 -130.062478)
		(width 0.14224)
		(layer "In4.Cu")
		(net "M_M_ECC<0>")
	)
	(segment
		(start 79.548228 -96.396302)
		(end 79.543402 -96.404938)
		(width 0.0889)
		(layer "In4.Cu")
		(net "M_M_ECC<0>")
	)
	(segment
		(start 79.548228 -85.499702)
		(end 79.543402 -85.508338)
		(width 0.0889)
		(layer "In4.Cu")
		(net "M_M_ECC<0>")
	)
	(arc
		(start 79.537052 -84.528406)
		(mid 79.464254 -84.819169)
		(end 79.543402 -85.108288)
		(width 0.0889)
		(layer "In4.Cu")
		(net "M_M_ECC<0>")
	)
	(arc
		(start 79.543402 -95.014288)
		(mid 79.596872 -95.209351)
		(end 79.548228 -95.405702)
		(width 0.0889)
		(layer "In4.Cu")
		(net "M_M_ECC<0>")
	)
	(arc
		(start 79.537052 -86.509606)
		(mid 79.464254 -86.800369)
		(end 79.543402 -87.089488)
		(width 0.0889)
		(layer "In4.Cu")
		(net "M_M_ECC<0>")
	)
	(arc
		(start 79.537052 -88.490806)
		(mid 79.464254 -88.781569)
		(end 79.543402 -89.070688)
		(width 0.0889)
		(layer "In4.Cu")
		(net "M_M_ECC<0>")
	)
	(arc
		(start 79.543402 -86.098888)
		(mid 79.596872 -86.293951)
		(end 79.548228 -86.490302)
		(width 0.0889)
		(layer "In4.Cu")
		(net "M_M_ECC<0>")
	)
	(arc
		(start 79.543402 -91.051888)
		(mid 79.596872 -91.246951)
		(end 79.548228 -91.443302)
		(width 0.0889)
		(layer "In4.Cu")
		(net "M_M_ECC<0>")
	)
	(arc
		(start 79.543402 -87.089488)
		(mid 79.596872 -87.284551)
		(end 79.548228 -87.480902)
		(width 0.0889)
		(layer "In4.Cu")
		(net "M_M_ECC<0>")
	)
	(arc
		(start 79.543402 -96.995488)
		(mid 79.596872 -97.190551)
		(end 79.548228 -97.386902)
		(width 0.0889)
		(layer "In4.Cu")
		(net "M_M_ECC<0>")
	)
	(arc
		(start 79.537052 -83.537806)
		(mid 79.464254 -83.828569)
		(end 79.543402 -84.117688)
		(width 0.0889)
		(layer "In4.Cu")
		(net "M_M_ECC<0>")
	)
	(arc
		(start 79.543402 -93.433138)
		(mid 79.46418 -93.722256)
		(end 79.537052 -94.01302)
		(width 0.0889)
		(layer "In4.Cu")
		(net "M_M_ECC<0>")
	)
	(arc
		(start 79.543402 -89.070688)
		(mid 79.596872 -89.265751)
		(end 79.548228 -89.462102)
		(width 0.0889)
		(layer "In4.Cu")
		(net "M_M_ECC<0>")
	)
	(arc
		(start 79.543402 -94.423484)
		(mid 79.464271 -94.718886)
		(end 79.543402 -95.014288)
		(width 0.0889)
		(layer "In4.Cu")
		(net "M_M_ECC<0>")
	)
	(arc
		(start 79.543402 -85.108288)
		(mid 79.596872 -85.303351)
		(end 79.548228 -85.499702)
		(width 0.0889)
		(layer "In4.Cu")
		(net "M_M_ECC<0>")
	)
	(arc
		(start 79.537052 -89.481406)
		(mid 79.464254 -89.772169)
		(end 79.543402 -90.061288)
		(width 0.0889)
		(layer "In4.Cu")
		(net "M_M_ECC<0>")
	)
	(arc
		(start 79.537052 -96.415606)
		(mid 79.464254 -96.706369)
		(end 79.543402 -96.995488)
		(width 0.0889)
		(layer "In4.Cu")
		(net "M_M_ECC<0>")
	)
	(arc
		(start 79.537052 -95.425006)
		(mid 79.464254 -95.715769)
		(end 79.543402 -96.004888)
		(width 0.0889)
		(layer "In4.Cu")
		(net "M_M_ECC<0>")
	)
	(arc
		(start 79.537052 -85.519006)
		(mid 79.464254 -85.809769)
		(end 79.543402 -86.098888)
		(width 0.0889)
		(layer "In4.Cu")
		(net "M_M_ECC<0>")
	)
	(arc
		(start 79.543402 -90.061288)
		(mid 79.596872 -90.256351)
		(end 79.548228 -90.452702)
		(width 0.0889)
		(layer "In4.Cu")
		(net "M_M_ECC<0>")
	)
	(arc
		(start 79.543402 -97.986088)
		(mid 79.596872 -98.181151)
		(end 79.548228 -98.377502)
		(width 0.0889)
		(layer "In4.Cu")
		(net "M_M_ECC<0>")
	)
	(arc
		(start 79.537052 -91.462606)
		(mid 79.464254 -91.753369)
		(end 79.543402 -92.042488)
		(width 0.0889)
		(layer "In4.Cu")
		(net "M_M_ECC<0>")
	)
	(arc
		(start 79.543402 -92.042488)
		(mid 79.596872 -92.237551)
		(end 79.548228 -92.433902)
		(width 0.0889)
		(layer "In4.Cu")
		(net "M_M_ECC<0>")
	)
	(arc
		(start 79.537052 -87.500206)
		(mid 79.464254 -87.790969)
		(end 79.543402 -88.080088)
		(width 0.0889)
		(layer "In4.Cu")
		(net "M_M_ECC<0>")
	)
	(arc
		(start 79.537052 -97.406206)
		(mid 79.464254 -97.696969)
		(end 79.543402 -97.986088)
		(width 0.0889)
		(layer "In4.Cu")
		(net "M_M_ECC<0>")
	)
	(arc
		(start 79.543402 -96.004888)
		(mid 79.596872 -96.199951)
		(end 79.548228 -96.396302)
		(width 0.0889)
		(layer "In4.Cu")
		(net "M_M_ECC<0>")
	)
	(arc
		(start 79.543402 -93.033088)
		(mid 79.596872 -93.228151)
		(end 79.548228 -93.424502)
		(width 0.0889)
		(layer "In4.Cu")
		(net "M_M_ECC<0>")
	)
	(arc
		(start 79.543402 -94.023688)
		(mid 79.596901 -94.223586)
		(end 79.543402 -94.423484)
		(width 0.0889)
		(layer "In4.Cu")
		(net "M_M_ECC<0>")
	)
	(arc
		(start 79.537052 -92.453206)
		(mid 79.464254 -92.743969)
		(end 79.543402 -93.033088)
		(width 0.0889)
		(layer "In4.Cu")
		(net "M_M_ECC<0>")
	)
	(arc
		(start 79.543402 -88.080088)
		(mid 79.596872 -88.275151)
		(end 79.548228 -88.471502)
		(width 0.0889)
		(layer "In4.Cu")
		(net "M_M_ECC<0>")
	)
	(arc
		(start 79.537052 -90.472006)
		(mid 79.464254 -90.762769)
		(end 79.543402 -91.051888)
		(width 0.0889)
		(layer "In4.Cu")
		(net "M_M_ECC<0>")
	)
	(arc
		(start 79.543402 -84.117688)
		(mid 79.596872 -84.312751)
		(end 79.548228 -84.509102)
		(width 0.0889)
		(layer "In4.Cu")
		(net "M_M_ECC<0>")
	)
	(segment
		(start 70.066408 -153.911046)
		(end 70.066408 -151.247348)
		(width 0.14224)
		(layer "In11.Cu")
		(net "M_M_ECC<0>")
	)
	(segment
		(start 70.066408 -151.247348)
		(end 70.499478 -150.814278)
		(width 0.14224)
		(layer "In11.Cu")
		(net "M_M_ECC<0>")
	)
	(segment
		(start 71.171562 -155.0162)
		(end 70.066408 -153.911046)
		(width 0.14224)
		(layer "In11.Cu")
		(net "M_M_ECC<0>")
	)
	(segment
		(start 78.051406 -87.28964)
		(end 77.479906 -87.28964)
		(width 0.1651)
		(layer "F.Cu")
		(net "M_M_DQS_DP<9>")
	)
	(segment
		(start 34.360358 -154.557984)
		(end 34.74212 -154.939746)
		(width 0.1651)
		(layer "F.Cu")
		(net "M_M_DQS_DP<9>")
	)
	(segment
		(start 34.278824 -154.333702)
		(end 34.360358 -154.557984)
		(width 0.1651)
		(layer "F.Cu")
		(net "M_M_DQS_DP<9>")
	)
	(segment
		(start 34.799524 -152.273)
		(end 34.799524 -152.895554)
		(width 0.1651)
		(layer "F.Cu")
		(net "M_M_DQS_DP<9>")
	)
	(segment
		(start 34.363406 -153.331672)
		(end 34.278824 -153.515568)
		(width 0.1651)
		(layer "F.Cu")
		(net "M_M_DQS_DP<9>")
	)
	(segment
		(start 34.799524 -152.895554)
		(end 34.363406 -153.331672)
		(width 0.1651)
		(layer "F.Cu")
		(net "M_M_DQS_DP<9>")
	)
	(segment
		(start 34.278824 -153.515568)
		(end 34.278824 -154.333702)
		(width 0.1651)
		(layer "F.Cu")
		(net "M_M_DQS_DP<9>")
	)
	(via
		(at 77.479906 -87.28964)
		(size 0.508)
		(drill 0.254)
		(layers "F.Cu" "B.Cu")
		(net "M_M_DQS_DP<9>")
	)
	(via
		(at 34.74212 -154.939746)
		(size 0.508)
		(drill 0.254)
		(layers "F.Cu" "B.Cu")
		(net "M_M_DQS_DP<9>")
	)
	(via
		(at 34.74212 -149.4282)
		(size 0.508)
		(drill 0.254)
		(layers "F.Cu" "B.Cu")
		(net "M_M_DQS_DP<9>")
	)
	(segment
		(start 34.34334 -151.00427)
		(end 34.266124 -150.871936)
		(width 0.1651)
		(layer "B.Cu")
		(net "M_M_DQS_DP<9>")
	)
	(segment
		(start 34.799524 -151.460454)
		(end 34.34334 -151.00427)
		(width 0.1651)
		(layer "B.Cu")
		(net "M_M_DQS_DP<9>")
	)
	(segment
		(start 34.266124 -150.871936)
		(end 34.266124 -149.976332)
		(width 0.1651)
		(layer "B.Cu")
		(net "M_M_DQS_DP<9>")
	)
	(segment
		(start 34.799524 -152.078436)
		(end 34.799524 -151.460454)
		(width 0.1651)
		(layer "B.Cu")
		(net "M_M_DQS_DP<9>")
	)
	(segment
		(start 34.3535 -149.81682)
		(end 34.74212 -149.4282)
		(width 0.1651)
		(layer "B.Cu")
		(net "M_M_DQS_DP<9>")
	)
	(segment
		(start 34.266124 -149.976332)
		(end 34.3535 -149.81682)
		(width 0.1651)
		(layer "B.Cu")
		(net "M_M_DQS_DP<9>")
	)
	(segment
		(start 36.502848 -117.969792)
		(end 36.502848 -117.175534)
		(width 0.14224)
		(layer "In11.Cu")
		(net "M_M_DQS_DP<9>")
	)
	(segment
		(start 52.636928 -98.28022)
		(end 62.581282 -88.335866)
		(width 0.14224)
		(layer "In11.Cu")
		(net "M_M_DQS_DP<9>")
	)
	(segment
		(start 68.018406 -88.184736)
		(end 68.051172 -88.184736)
		(width 0.0889)
		(layer "In11.Cu")
		(net "M_M_DQS_DP<9>")
	)
	(segment
		(start 36.502848 -117.175534)
		(end 36.282122 -116.954808)
		(width 0.14224)
		(layer "In11.Cu")
		(net "M_M_DQS_DP<9>")
	)
	(segment
		(start 35.527488 -116.954808)
		(end 35.243008 -116.670328)
		(width 0.14224)
		(layer "In11.Cu")
		(net "M_M_DQS_DP<9>")
	)
	(segment
		(start 68.873116 -87.68969)
		(end 68.905882 -87.68969)
		(width 0.0889)
		(layer "In11.Cu")
		(net "M_M_DQS_DP<9>")
	)
	(segment
		(start 34.877248 -118.544086)
		(end 35.283394 -118.13794)
		(width 0.14224)
		(layer "In11.Cu")
		(net "M_M_DQS_DP<9>")
	)
	(segment
		(start 35.243008 -115.827048)
		(end 35.527488 -115.542568)
		(width 0.14224)
		(layer "In11.Cu")
		(net "M_M_DQS_DP<9>")
	)
	(segment
		(start 71.452486 -86.203536)
		(end 71.485252 -86.203536)
		(width 0.0889)
		(layer "In11.Cu")
		(net "M_M_DQS_DP<9>")
	)
	(segment
		(start 65.55867 -88.335866)
		(end 65.580768 -88.335866)
		(width 0.0889)
		(layer "In11.Cu")
		(net "M_M_DQS_DP<9>")
	)
	(segment
		(start 35.2552 -149.164294)
		(end 35.2552 -126.76632)
		(width 0.14224)
		(layer "In11.Cu")
		(net "M_M_DQS_DP<9>")
	)
	(segment
		(start 40.343328 -108.24464)
		(end 40.343328 -107.73664)
		(width 0.14224)
		(layer "In11.Cu")
		(net "M_M_DQS_DP<9>")
	)
	(segment
		(start 48.724566 -103.18496)
		(end 52.636928 -99.272598)
		(width 0.14224)
		(layer "In11.Cu")
		(net "M_M_DQS_DP<9>")
	)
	(segment
		(start 73.169526 -85.212936)
		(end 73.202292 -85.212936)
		(width 0.0889)
		(layer "In11.Cu")
		(net "M_M_DQS_DP<9>")
	)
	(segment
		(start 34.991294 -149.4282)
		(end 35.2552 -149.164294)
		(width 0.14224)
		(layer "In11.Cu")
		(net "M_M_DQS_DP<9>")
	)
	(segment
		(start 52.636928 -99.272598)
		(end 52.636928 -98.28022)
		(width 0.14224)
		(layer "In11.Cu")
		(net "M_M_DQS_DP<9>")
	)
	(segment
		(start 36.3347 -118.13794)
		(end 36.502848 -117.969792)
		(width 0.14224)
		(layer "In11.Cu")
		(net "M_M_DQS_DP<9>")
	)
	(segment
		(start 66.917062 -88.68029)
		(end 67.188842 -88.68029)
		(width 0.0889)
		(layer "In11.Cu")
		(net "M_M_DQS_DP<9>")
	)
	(segment
		(start 65.580768 -88.335866)
		(end 65.620138 -88.375236)
		(width 0.0889)
		(layer "In11.Cu")
		(net "M_M_DQS_DP<9>")
	)
	(segment
		(start 34.668968 -149.4282)
		(end 34.237168 -149.86)
		(width 0.14224)
		(layer "In11.Cu")
		(net "M_M_DQS_DP<9>")
	)
	(segment
		(start 36.282122 -115.542568)
		(end 36.502848 -115.321842)
		(width 0.14224)
		(layer "In11.Cu")
		(net "M_M_DQS_DP<9>")
	)
	(segment
		(start 44.895008 -103.18496)
		(end 48.724566 -103.18496)
		(width 0.14224)
		(layer "In11.Cu")
		(net "M_M_DQS_DP<9>")
	)
	(segment
		(start 36.502848 -112.08512)
		(end 40.343328 -108.24464)
		(width 0.14224)
		(layer "In11.Cu")
		(net "M_M_DQS_DP<9>")
	)
	(segment
		(start 65.620138 -88.375236)
		(end 66.612008 -88.375236)
		(width 0.0889)
		(layer "In11.Cu")
		(net "M_M_DQS_DP<9>")
	)
	(segment
		(start 34.74212 -149.4282)
		(end 34.668968 -149.4282)
		(width 0.14224)
		(layer "In11.Cu")
		(net "M_M_DQS_DP<9>")
	)
	(segment
		(start 72.307196 -85.70849)
		(end 72.339962 -85.70849)
		(width 0.0889)
		(layer "In11.Cu")
		(net "M_M_DQS_DP<9>")
	)
	(segment
		(start 34.237168 -149.86)
		(end 34.237168 -154.434794)
		(width 0.14224)
		(layer "In11.Cu")
		(net "M_M_DQS_DP<9>")
	)
	(segment
		(start 77.162914 -87.031068)
		(end 77.18679 -87.120476)
		(width 0.0889)
		(layer "In11.Cu")
		(net "M_M_DQS_DP<9>")
	)
	(segment
		(start 77.18679 -87.120476)
		(end 77.479906 -87.28964)
		(width 0.0889)
		(layer "In11.Cu")
		(net "M_M_DQS_DP<9>")
	)
	(segment
		(start 36.502848 -115.321842)
		(end 36.502848 -112.08512)
		(width 0.14224)
		(layer "In11.Cu")
		(net "M_M_DQS_DP<9>")
	)
	(segment
		(start 76.6064 -86.203536)
		(end 76.639166 -86.203536)
		(width 0.0889)
		(layer "In11.Cu")
		(net "M_M_DQS_DP<9>")
	)
	(segment
		(start 36.282122 -116.954808)
		(end 35.527488 -116.954808)
		(width 0.14224)
		(layer "In11.Cu")
		(net "M_M_DQS_DP<9>")
	)
	(segment
		(start 62.581282 -88.335866)
		(end 65.55867 -88.335866)
		(width 0.14224)
		(layer "In11.Cu")
		(net "M_M_DQS_DP<9>")
	)
	(segment
		(start 35.527488 -115.542568)
		(end 36.282122 -115.542568)
		(width 0.14224)
		(layer "In11.Cu")
		(net "M_M_DQS_DP<9>")
	)
	(segment
		(start 74.024236 -84.71789)
		(end 74.067416 -84.71789)
		(width 0.0889)
		(layer "In11.Cu")
		(net "M_M_DQS_DP<9>")
	)
	(segment
		(start 35.243008 -116.670328)
		(end 35.243008 -115.827048)
		(width 0.14224)
		(layer "In11.Cu")
		(net "M_M_DQS_DP<9>")
	)
	(segment
		(start 69.735446 -87.194136)
		(end 69.768212 -87.194136)
		(width 0.0889)
		(layer "In11.Cu")
		(net "M_M_DQS_DP<9>")
	)
	(segment
		(start 70.590156 -86.69909)
		(end 70.622922 -86.69909)
		(width 0.0889)
		(layer "In11.Cu")
		(net "M_M_DQS_DP<9>")
	)
	(segment
		(start 35.2552 -126.76632)
		(end 34.877248 -126.388368)
		(width 0.14224)
		(layer "In11.Cu")
		(net "M_M_DQS_DP<9>")
	)
	(segment
		(start 34.74212 -149.4282)
		(end 34.991294 -149.4282)
		(width 0.14224)
		(layer "In11.Cu")
		(net "M_M_DQS_DP<9>")
	)
	(segment
		(start 66.612008 -88.375236)
		(end 66.917062 -88.68029)
		(width 0.0889)
		(layer "In11.Cu")
		(net "M_M_DQS_DP<9>")
	)
	(segment
		(start 34.237168 -154.434794)
		(end 34.74212 -154.939746)
		(width 0.14224)
		(layer "In11.Cu")
		(net "M_M_DQS_DP<9>")
	)
	(segment
		(start 74.88936 -85.212936)
		(end 74.922126 -85.212936)
		(width 0.0889)
		(layer "In11.Cu")
		(net "M_M_DQS_DP<9>")
	)
	(segment
		(start 40.343328 -107.73664)
		(end 44.895008 -103.18496)
		(width 0.14224)
		(layer "In11.Cu")
		(net "M_M_DQS_DP<9>")
	)
	(segment
		(start 75.75169 -85.70849)
		(end 75.784456 -85.70849)
		(width 0.0889)
		(layer "In11.Cu")
		(net "M_M_DQS_DP<9>")
	)
	(segment
		(start 34.877248 -126.388368)
		(end 34.877248 -118.544086)
		(width 0.14224)
		(layer "In11.Cu")
		(net "M_M_DQS_DP<9>")
	)
	(segment
		(start 35.283394 -118.13794)
		(end 36.3347 -118.13794)
		(width 0.14224)
		(layer "In11.Cu")
		(net "M_M_DQS_DP<9>")
	)
	(arc
		(start 68.382896 -87.984838)
		(mid 68.5899 -87.773974)
		(end 68.873116 -87.68969)
		(width 0.0889)
		(layer "In11.Cu")
		(net "M_M_DQS_DP<9>")
	)
	(arc
		(start 73.534016 -85.013038)
		(mid 73.74102 -84.802174)
		(end 74.024236 -84.71789)
		(width 0.0889)
		(layer "In11.Cu")
		(net "M_M_DQS_DP<9>")
	)
	(arc
		(start 72.675496 -85.508338)
		(mid 72.884104 -85.296406)
		(end 73.169526 -85.212936)
		(width 0.0889)
		(layer "In11.Cu")
		(net "M_M_DQS_DP<9>")
	)
	(arc
		(start 67.188842 -88.68029)
		(mid 67.382692 -88.62394)
		(end 67.524376 -88.480138)
		(width 0.0889)
		(layer "In11.Cu")
		(net "M_M_DQS_DP<9>")
	)
	(arc
		(start 71.816976 -86.003638)
		(mid 72.02398 -85.792774)
		(end 72.307196 -85.70849)
		(width 0.0889)
		(layer "In11.Cu")
		(net "M_M_DQS_DP<9>")
	)
	(arc
		(start 72.339962 -85.70849)
		(mid 72.533812 -85.65214)
		(end 72.675496 -85.508338)
		(width 0.0889)
		(layer "In11.Cu")
		(net "M_M_DQS_DP<9>")
	)
	(arc
		(start 74.067416 -84.71789)
		(mid 74.350633 -84.802171)
		(end 74.557636 -85.013038)
		(width 0.0889)
		(layer "In11.Cu")
		(net "M_M_DQS_DP<9>")
	)
	(arc
		(start 69.241416 -87.489538)
		(mid 69.450024 -87.277606)
		(end 69.735446 -87.194136)
		(width 0.0889)
		(layer "In11.Cu")
		(net "M_M_DQS_DP<9>")
	)
	(arc
		(start 76.639166 -86.203536)
		(mid 77.120877 -86.478145)
		(end 77.162914 -87.031068)
		(width 0.0889)
		(layer "In11.Cu")
		(net "M_M_DQS_DP<9>")
	)
	(arc
		(start 70.622922 -86.69909)
		(mid 70.816772 -86.64274)
		(end 70.958456 -86.498938)
		(width 0.0889)
		(layer "In11.Cu")
		(net "M_M_DQS_DP<9>")
	)
	(arc
		(start 74.922126 -85.212936)
		(mid 75.20755 -85.296403)
		(end 75.416156 -85.508338)
		(width 0.0889)
		(layer "In11.Cu")
		(net "M_M_DQS_DP<9>")
	)
	(arc
		(start 70.958456 -86.498938)
		(mid 71.167064 -86.287006)
		(end 71.452486 -86.203536)
		(width 0.0889)
		(layer "In11.Cu")
		(net "M_M_DQS_DP<9>")
	)
	(arc
		(start 73.202292 -85.212936)
		(mid 73.393934 -85.15577)
		(end 73.534016 -85.013038)
		(width 0.0889)
		(layer "In11.Cu")
		(net "M_M_DQS_DP<9>")
	)
	(arc
		(start 74.557636 -85.013038)
		(mid 74.697715 -85.155774)
		(end 74.88936 -85.212936)
		(width 0.0889)
		(layer "In11.Cu")
		(net "M_M_DQS_DP<9>")
	)
	(arc
		(start 71.485252 -86.203536)
		(mid 71.676894 -86.14637)
		(end 71.816976 -86.003638)
		(width 0.0889)
		(layer "In11.Cu")
		(net "M_M_DQS_DP<9>")
	)
	(arc
		(start 68.905882 -87.68969)
		(mid 69.099732 -87.63334)
		(end 69.241416 -87.489538)
		(width 0.0889)
		(layer "In11.Cu")
		(net "M_M_DQS_DP<9>")
	)
	(arc
		(start 70.099936 -86.994238)
		(mid 70.30694 -86.783374)
		(end 70.590156 -86.69909)
		(width 0.0889)
		(layer "In11.Cu")
		(net "M_M_DQS_DP<9>")
	)
	(arc
		(start 75.784456 -85.70849)
		(mid 76.067673 -85.792771)
		(end 76.274676 -86.003638)
		(width 0.0889)
		(layer "In11.Cu")
		(net "M_M_DQS_DP<9>")
	)
	(arc
		(start 76.274676 -86.003638)
		(mid 76.414755 -86.146374)
		(end 76.6064 -86.203536)
		(width 0.0889)
		(layer "In11.Cu")
		(net "M_M_DQS_DP<9>")
	)
	(arc
		(start 75.416156 -85.508338)
		(mid 75.557839 -85.652142)
		(end 75.75169 -85.70849)
		(width 0.0889)
		(layer "In11.Cu")
		(net "M_M_DQS_DP<9>")
	)
	(arc
		(start 68.051172 -88.184736)
		(mid 68.242814 -88.12757)
		(end 68.382896 -87.984838)
		(width 0.0889)
		(layer "In11.Cu")
		(net "M_M_DQS_DP<9>")
	)
	(arc
		(start 67.524376 -88.480138)
		(mid 67.732984 -88.268206)
		(end 68.018406 -88.184736)
		(width 0.0889)
		(layer "In11.Cu")
		(net "M_M_DQS_DP<9>")
	)
	(arc
		(start 69.768212 -87.194136)
		(mid 69.959854 -87.13697)
		(end 70.099936 -86.994238)
		(width 0.0889)
		(layer "In11.Cu")
		(net "M_M_DQS_DP<9>")
	)
	(segment
		(start 73.693528 -154.21356)
		(end 73.437496 -154.21356)
		(width 0.1651)
		(layer "F.Cu")
		(net "M_M_DQS_DP<8>")
	)
	(segment
		(start 81.485232 -84.31784)
		(end 80.913732 -84.31784)
		(width 0.1651)
		(layer "F.Cu")
		(net "M_M_DQS_DP<8>")
	)
	(segment
		(start 73.937368 -155.829)
		(end 73.937368 -154.4574)
		(width 0.1651)
		(layer "F.Cu")
		(net "M_M_DQS_DP<8>")
	)
	(segment
		(start 73.937368 -154.4574)
		(end 73.693528 -154.21356)
		(width 0.1651)
		(layer "F.Cu")
		(net "M_M_DQS_DP<8>")
	)
	(segment
		(start 73.899522 -155.866846)
		(end 73.937368 -155.829)
		(width 0.1651)
		(layer "F.Cu")
		(net "M_M_DQS_DP<8>")
	)
	(segment
		(start 73.899522 -156.87294)
		(end 73.899522 -155.866846)
		(width 0.1651)
		(layer "F.Cu")
		(net "M_M_DQS_DP<8>")
	)
	(via
		(at 73.437496 -154.21356)
		(size 0.508)
		(drill 0.254)
		(layers "F.Cu" "B.Cu")
		(net "M_M_DQS_DP<8>")
	)
	(via
		(at 80.913732 -84.31784)
		(size 0.508)
		(drill 0.254)
		(layers "F.Cu" "B.Cu")
		(net "M_M_DQS_DP<8>")
	)
	(via
		(at 73.437496 -150.142956)
		(size 0.508)
		(drill 0.254)
		(layers "F.Cu" "B.Cu")
		(net "M_M_DQS_DP<8>")
	)
	(segment
		(start 73.899522 -148.628354)
		(end 73.937368 -148.6662)
		(width 0.1651)
		(layer "B.Cu")
		(net "M_M_DQS_DP<8>")
	)
	(segment
		(start 73.899522 -147.478496)
		(end 73.899522 -148.628354)
		(width 0.1651)
		(layer "B.Cu")
		(net "M_M_DQS_DP<8>")
	)
	(segment
		(start 73.679812 -150.142956)
		(end 73.437496 -150.142956)
		(width 0.1651)
		(layer "B.Cu")
		(net "M_M_DQS_DP<8>")
	)
	(segment
		(start 73.937368 -148.6662)
		(end 73.937368 -149.8854)
		(width 0.1651)
		(layer "B.Cu")
		(net "M_M_DQS_DP<8>")
	)
	(segment
		(start 73.937368 -149.8854)
		(end 73.679812 -150.142956)
		(width 0.1651)
		(layer "B.Cu")
		(net "M_M_DQS_DP<8>")
	)
	(segment
		(start 81.425542 -91.547188)
		(end 81.420716 -91.555824)
		(width 0.0889)
		(layer "In4.Cu")
		(net "M_M_DQS_DP<8>")
	)
	(segment
		(start 81.425542 -96.900238)
		(end 81.508092 -97.04324)
		(width 0.0889)
		(layer "In4.Cu")
		(net "M_M_DQS_DP<8>")
	)
	(segment
		(start 74.219816 -123.632214)
		(end 74.219816 -149.360636)
		(width 0.14224)
		(layer "In4.Cu")
		(net "M_M_DQS_DP<8>")
	)
	(segment
		(start 81.425542 -90.556588)
		(end 81.420716 -90.565224)
		(width 0.0889)
		(layer "In4.Cu")
		(net "M_M_DQS_DP<8>")
	)
	(segment
		(start 73.779888 -116.617496)
		(end 74.001376 -116.838984)
		(width 0.14224)
		(layer "In4.Cu")
		(net "M_M_DQS_DP<8>")
	)
	(segment
		(start 81.425542 -92.537788)
		(end 81.420716 -92.546424)
		(width 0.0889)
		(layer "In4.Cu")
		(net "M_M_DQS_DP<8>")
	)
	(segment
		(start 81.431892 -95.49892)
		(end 81.425542 -95.509588)
		(width 0.0889)
		(layer "In4.Cu")
		(net "M_M_DQS_DP<8>")
	)
	(segment
		(start 73.373488 -118.580408)
		(end 73.373488 -122.785886)
		(width 0.14224)
		(layer "In4.Cu")
		(net "M_M_DQS_DP<8>")
	)
	(segment
		(start 81.085182 -100.877624)
		(end 81.085182 -102.261924)
		(width 0.0889)
		(layer "In4.Cu")
		(net "M_M_DQS_DP<8>")
	)
	(segment
		(start 81.431892 -92.52712)
		(end 81.425542 -92.537788)
		(width 0.0889)
		(layer "In4.Cu")
		(net "M_M_DQS_DP<8>")
	)
	(segment
		(start 81.425542 -93.928438)
		(end 81.431892 -93.939106)
		(width 0.0889)
		(layer "In4.Cu")
		(net "M_M_DQS_DP<8>")
	)
	(segment
		(start 81.340452 -103.933498)
		(end 81.340452 -105.476548)
		(width 0.14224)
		(layer "In4.Cu")
		(net "M_M_DQS_DP<8>")
	)
	(segment
		(start 81.431892 -86.58352)
		(end 81.425542 -86.594188)
		(width 0.0889)
		(layer "In4.Cu")
		(net "M_M_DQS_DP<8>")
	)
	(segment
		(start 75.057254 -111.759492)
		(end 75.057254 -115.57381)
		(width 0.14224)
		(layer "In4.Cu")
		(net "M_M_DQS_DP<8>")
	)
	(segment
		(start 81.508092 -100.454714)
		(end 81.085182 -100.877624)
		(width 0.0889)
		(layer "In4.Cu")
		(net "M_M_DQS_DP<8>")
	)
	(segment
		(start 81.425542 -89.565988)
		(end 81.420716 -89.574624)
		(width 0.0889)
		(layer "In4.Cu")
		(net "M_M_DQS_DP<8>")
	)
	(segment
		(start 81.431892 -89.55532)
		(end 81.425542 -89.565988)
		(width 0.0889)
		(layer "In4.Cu")
		(net "M_M_DQS_DP<8>")
	)
	(segment
		(start 74.001376 -116.838984)
		(end 74.551286 -116.838984)
		(width 0.14224)
		(layer "In4.Cu")
		(net "M_M_DQS_DP<8>")
	)
	(segment
		(start 74.551286 -118.30812)
		(end 73.645776 -118.30812)
		(width 0.14224)
		(layer "In4.Cu")
		(net "M_M_DQS_DP<8>")
	)
	(segment
		(start 74.001376 -115.965224)
		(end 73.779888 -116.186712)
		(width 0.14224)
		(layer "In4.Cu")
		(net "M_M_DQS_DP<8>")
	)
	(segment
		(start 81.340452 -105.476548)
		(end 75.057254 -111.759492)
		(width 0.14224)
		(layer "In4.Cu")
		(net "M_M_DQS_DP<8>")
	)
	(segment
		(start 81.301082 -102.635304)
		(end 81.301082 -103.87203)
		(width 0.0889)
		(layer "In4.Cu")
		(net "M_M_DQS_DP<8>")
	)
	(segment
		(start 81.431892 -87.57412)
		(end 81.425542 -87.584788)
		(width 0.0889)
		(layer "In4.Cu")
		(net "M_M_DQS_DP<8>")
	)
	(segment
		(start 81.431892 -91.53652)
		(end 81.425542 -91.547188)
		(width 0.0889)
		(layer "In4.Cu")
		(net "M_M_DQS_DP<8>")
	)
	(segment
		(start 73.373488 -122.785886)
		(end 74.219816 -123.632214)
		(width 0.14224)
		(layer "In4.Cu")
		(net "M_M_DQS_DP<8>")
	)
	(segment
		(start 81.301082 -103.87203)
		(end 81.340452 -103.9114)
		(width 0.0889)
		(layer "In4.Cu")
		(net "M_M_DQS_DP<8>")
	)
	(segment
		(start 74.551286 -116.838984)
		(end 74.835766 -117.123464)
		(width 0.14224)
		(layer "In4.Cu")
		(net "M_M_DQS_DP<8>")
	)
	(segment
		(start 81.431892 -90.54592)
		(end 81.425542 -90.556588)
		(width 0.0889)
		(layer "In4.Cu")
		(net "M_M_DQS_DP<8>")
	)
	(segment
		(start 81.340452 -103.9114)
		(end 81.340452 -103.933498)
		(width 0.0889)
		(layer "In4.Cu")
		(net "M_M_DQS_DP<8>")
	)
	(segment
		(start 74.835766 -117.123464)
		(end 74.835766 -118.02364)
		(width 0.14224)
		(layer "In4.Cu")
		(net "M_M_DQS_DP<8>")
	)
	(segment
		(start 81.508092 -97.04324)
		(end 81.508092 -100.454714)
		(width 0.0889)
		(layer "In4.Cu")
		(net "M_M_DQS_DP<8>")
	)
	(segment
		(start 81.425542 -86.594188)
		(end 81.420716 -86.602824)
		(width 0.0889)
		(layer "In4.Cu")
		(net "M_M_DQS_DP<8>")
	)
	(segment
		(start 74.219816 -149.360636)
		(end 73.437496 -150.142956)
		(width 0.14224)
		(layer "In4.Cu")
		(net "M_M_DQS_DP<8>")
	)
	(segment
		(start 73.779888 -116.186712)
		(end 73.779888 -116.617496)
		(width 0.14224)
		(layer "In4.Cu")
		(net "M_M_DQS_DP<8>")
	)
	(segment
		(start 81.425542 -95.509588)
		(end 81.420716 -95.518224)
		(width 0.0889)
		(layer "In4.Cu")
		(net "M_M_DQS_DP<8>")
	)
	(segment
		(start 81.425542 -88.575388)
		(end 81.420716 -88.584024)
		(width 0.0889)
		(layer "In4.Cu")
		(net "M_M_DQS_DP<8>")
	)
	(segment
		(start 81.425542 -87.584788)
		(end 81.420716 -87.593424)
		(width 0.0889)
		(layer "In4.Cu")
		(net "M_M_DQS_DP<8>")
	)
	(segment
		(start 81.085182 -102.261924)
		(end 81.301082 -102.635304)
		(width 0.0889)
		(layer "In4.Cu")
		(net "M_M_DQS_DP<8>")
	)
	(segment
		(start 81.42097 -96.507808)
		(end 81.420462 -96.50857)
		(width 0.0889)
		(layer "In4.Cu")
		(net "M_M_DQS_DP<8>")
	)
	(segment
		(start 73.645776 -118.30812)
		(end 73.373488 -118.580408)
		(width 0.14224)
		(layer "In4.Cu")
		(net "M_M_DQS_DP<8>")
	)
	(segment
		(start 81.431892 -96.48952)
		(end 81.42097 -96.507808)
		(width 0.0889)
		(layer "In4.Cu")
		(net "M_M_DQS_DP<8>")
	)
	(segment
		(start 74.835766 -118.02364)
		(end 74.551286 -118.30812)
		(width 0.14224)
		(layer "In4.Cu")
		(net "M_M_DQS_DP<8>")
	)
	(segment
		(start 81.425542 -94.518988)
		(end 81.420716 -94.527624)
		(width 0.0889)
		(layer "In4.Cu")
		(net "M_M_DQS_DP<8>")
	)
	(segment
		(start 81.431892 -88.56472)
		(end 81.425542 -88.575388)
		(width 0.0889)
		(layer "In4.Cu")
		(net "M_M_DQS_DP<8>")
	)
	(segment
		(start 81.31048 -85.361018)
		(end 81.31048 -85.7758)
		(width 0.0889)
		(layer "In4.Cu")
		(net "M_M_DQS_DP<8>")
	)
	(segment
		(start 81.420462 -96.50857)
		(end 81.420716 -96.508824)
		(width 0.0889)
		(layer "In4.Cu")
		(net "M_M_DQS_DP<8>")
	)
	(segment
		(start 75.057254 -115.57381)
		(end 74.66584 -115.965224)
		(width 0.14224)
		(layer "In4.Cu")
		(net "M_M_DQS_DP<8>")
	)
	(segment
		(start 74.66584 -115.965224)
		(end 74.001376 -115.965224)
		(width 0.14224)
		(layer "In4.Cu")
		(net "M_M_DQS_DP<8>")
	)
	(arc
		(start 81.425542 -95.909638)
		(mid 81.504764 -96.198756)
		(end 81.431892 -96.48952)
		(width 0.0889)
		(layer "In4.Cu")
		(net "M_M_DQS_DP<8>")
	)
	(arc
		(start 81.31048 -85.7758)
		(mid 81.364813 -85.891334)
		(end 81.425542 -86.003638)
		(width 0.0889)
		(layer "In4.Cu")
		(net "M_M_DQS_DP<8>")
	)
	(arc
		(start 81.420716 -87.593424)
		(mid 81.371961 -87.789776)
		(end 81.425542 -87.984838)
		(width 0.0889)
		(layer "In4.Cu")
		(net "M_M_DQS_DP<8>")
	)
	(arc
		(start 81.420716 -86.602824)
		(mid 81.371961 -86.799176)
		(end 81.425542 -86.994238)
		(width 0.0889)
		(layer "In4.Cu")
		(net "M_M_DQS_DP<8>")
	)
	(arc
		(start 81.425542 -93.528642)
		(mid 81.372043 -93.72854)
		(end 81.425542 -93.928438)
		(width 0.0889)
		(layer "In4.Cu")
		(net "M_M_DQS_DP<8>")
	)
	(arc
		(start 81.425542 -86.003638)
		(mid 81.504764 -86.292756)
		(end 81.431892 -86.58352)
		(width 0.0889)
		(layer "In4.Cu")
		(net "M_M_DQS_DP<8>")
	)
	(arc
		(start 81.420716 -91.555824)
		(mid 81.371961 -91.752176)
		(end 81.425542 -91.947238)
		(width 0.0889)
		(layer "In4.Cu")
		(net "M_M_DQS_DP<8>")
	)
	(arc
		(start 81.425542 -86.994238)
		(mid 81.504764 -87.283356)
		(end 81.431892 -87.57412)
		(width 0.0889)
		(layer "In4.Cu")
		(net "M_M_DQS_DP<8>")
	)
	(arc
		(start 81.420716 -88.584024)
		(mid 81.371961 -88.780376)
		(end 81.425542 -88.975438)
		(width 0.0889)
		(layer "In4.Cu")
		(net "M_M_DQS_DP<8>")
	)
	(arc
		(start 81.420716 -92.546424)
		(mid 81.371961 -92.742776)
		(end 81.425542 -92.937838)
		(width 0.0889)
		(layer "In4.Cu")
		(net "M_M_DQS_DP<8>")
	)
	(arc
		(start 81.425542 -91.947238)
		(mid 81.504764 -92.236356)
		(end 81.431892 -92.52712)
		(width 0.0889)
		(layer "In4.Cu")
		(net "M_M_DQS_DP<8>")
	)
	(arc
		(start 81.420716 -90.565224)
		(mid 81.371961 -90.761576)
		(end 81.425542 -90.956638)
		(width 0.0889)
		(layer "In4.Cu")
		(net "M_M_DQS_DP<8>")
	)
	(arc
		(start 80.913732 -84.31784)
		(mid 81.065384 -84.723079)
		(end 81.260442 -85.109304)
		(width 0.0889)
		(layer "In4.Cu")
		(net "M_M_DQS_DP<8>")
	)
	(arc
		(start 81.420716 -95.518224)
		(mid 81.371961 -95.714576)
		(end 81.425542 -95.909638)
		(width 0.0889)
		(layer "In4.Cu")
		(net "M_M_DQS_DP<8>")
	)
	(arc
		(start 81.420716 -94.527624)
		(mid 81.371961 -94.723976)
		(end 81.425542 -94.919038)
		(width 0.0889)
		(layer "In4.Cu")
		(net "M_M_DQS_DP<8>")
	)
	(arc
		(start 81.431892 -93.939106)
		(mid 81.50469 -94.229869)
		(end 81.425542 -94.518988)
		(width 0.0889)
		(layer "In4.Cu")
		(net "M_M_DQS_DP<8>")
	)
	(arc
		(start 81.425542 -87.984838)
		(mid 81.504764 -88.273956)
		(end 81.431892 -88.56472)
		(width 0.0889)
		(layer "In4.Cu")
		(net "M_M_DQS_DP<8>")
	)
	(arc
		(start 81.425542 -88.975438)
		(mid 81.504764 -89.264556)
		(end 81.431892 -89.55532)
		(width 0.0889)
		(layer "In4.Cu")
		(net "M_M_DQS_DP<8>")
	)
	(arc
		(start 81.425542 -90.956638)
		(mid 81.504764 -91.245756)
		(end 81.431892 -91.53652)
		(width 0.0889)
		(layer "In4.Cu")
		(net "M_M_DQS_DP<8>")
	)
	(arc
		(start 81.425542 -89.966038)
		(mid 81.504764 -90.255156)
		(end 81.431892 -90.54592)
		(width 0.0889)
		(layer "In4.Cu")
		(net "M_M_DQS_DP<8>")
	)
	(arc
		(start 81.260442 -85.109304)
		(mid 81.306155 -85.231041)
		(end 81.31048 -85.361018)
		(width 0.0889)
		(layer "In4.Cu")
		(net "M_M_DQS_DP<8>")
	)
	(arc
		(start 81.420716 -89.574624)
		(mid 81.371961 -89.770976)
		(end 81.425542 -89.966038)
		(width 0.0889)
		(layer "In4.Cu")
		(net "M_M_DQS_DP<8>")
	)
	(arc
		(start 81.425542 -92.937838)
		(mid 81.504673 -93.23324)
		(end 81.425542 -93.528642)
		(width 0.0889)
		(layer "In4.Cu")
		(net "M_M_DQS_DP<8>")
	)
	(arc
		(start 81.420716 -96.508824)
		(mid 81.371961 -96.705176)
		(end 81.425542 -96.900238)
		(width 0.0889)
		(layer "In4.Cu")
		(net "M_M_DQS_DP<8>")
	)
	(arc
		(start 81.425542 -94.919038)
		(mid 81.504764 -95.208156)
		(end 81.431892 -95.49892)
		(width 0.0889)
		(layer "In4.Cu")
		(net "M_M_DQS_DP<8>")
	)
	(segment
		(start 73.23328 -151.257)
		(end 73.618344 -151.257)
		(width 0.14224)
		(layer "In11.Cu")
		(net "M_M_DQS_DP<8>")
	)
	(segment
		(start 73.897744 -153.753312)
		(end 73.897744 -153.378916)
		(width 0.14224)
		(layer "In11.Cu")
		(net "M_M_DQS_DP<8>")
	)
	(segment
		(start 73.207372 -152.501092)
		(end 73.260204 -152.501092)
		(width 0.14224)
		(layer "In11.Cu")
		(net "M_M_DQS_DP<8>")
	)
	(segment
		(start 73.080372 -152.807924)
		(end 73.080372 -152.628092)
		(width 0.14224)
		(layer "In11.Cu")
		(net "M_M_DQS_DP<8>")
	)
	(segment
		(start 73.579228 -153.0604)
		(end 73.332848 -153.0604)
		(width 0.14224)
		(layer "In11.Cu")
		(net "M_M_DQS_DP<8>")
	)
	(segment
		(start 73.062846 -151.427434)
		(end 73.23328 -151.257)
		(width 0.14224)
		(layer "In11.Cu")
		(net "M_M_DQS_DP<8>")
	)
	(segment
		(start 73.897744 -153.378916)
		(end 73.579228 -153.0604)
		(width 0.14224)
		(layer "In11.Cu")
		(net "M_M_DQS_DP<8>")
	)
	(segment
		(start 73.062846 -151.751792)
		(end 73.062846 -151.427434)
		(width 0.14224)
		(layer "In11.Cu")
		(net "M_M_DQS_DP<8>")
	)
	(segment
		(start 73.618344 -151.257)
		(end 73.872344 -151.003)
		(width 0.14224)
		(layer "In11.Cu")
		(net "M_M_DQS_DP<8>")
	)
	(segment
		(start 73.260204 -152.501092)
		(end 73.448418 -152.312878)
		(width 0.14224)
		(layer "In11.Cu")
		(net "M_M_DQS_DP<8>")
	)
	(segment
		(start 73.262744 -151.8666)
		(end 73.177654 -151.8666)
		(width 0.14224)
		(layer "In11.Cu")
		(net "M_M_DQS_DP<8>")
	)
	(segment
		(start 73.080372 -152.628092)
		(end 73.207372 -152.501092)
		(width 0.14224)
		(layer "In11.Cu")
		(net "M_M_DQS_DP<8>")
	)
	(segment
		(start 73.448418 -152.312878)
		(end 73.448418 -152.052274)
		(width 0.14224)
		(layer "In11.Cu")
		(net "M_M_DQS_DP<8>")
	)
	(segment
		(start 73.872344 -150.577804)
		(end 73.437496 -150.142956)
		(width 0.14224)
		(layer "In11.Cu")
		(net "M_M_DQS_DP<8>")
	)
	(segment
		(start 73.332848 -153.0604)
		(end 73.080372 -152.807924)
		(width 0.14224)
		(layer "In11.Cu")
		(net "M_M_DQS_DP<8>")
	)
	(segment
		(start 73.448418 -152.052274)
		(end 73.262744 -151.8666)
		(width 0.14224)
		(layer "In11.Cu")
		(net "M_M_DQS_DP<8>")
	)
	(segment
		(start 73.872344 -151.003)
		(end 73.872344 -150.577804)
		(width 0.14224)
		(layer "In11.Cu")
		(net "M_M_DQS_DP<8>")
	)
	(segment
		(start 73.177654 -151.8666)
		(end 73.062846 -151.751792)
		(width 0.14224)
		(layer "In11.Cu")
		(net "M_M_DQS_DP<8>")
	)
	(segment
		(start 73.437496 -154.21356)
		(end 73.897744 -153.753312)
		(width 0.14224)
		(layer "In11.Cu")
		(net "M_M_DQS_DP<8>")
	)
	(segment
		(start 147.84959 -155.866846)
		(end 147.887436 -155.829)
		(width 0.1651)
		(layer "F.Cu")
		(net "M_M_DQS_DP<7>")
	)
	(segment
		(start 147.849336 -156.87294)
		(end 147.84959 -156.87294)
		(width 0.1651)
		(layer "F.Cu")
		(net "M_M_DQS_DP<7>")
	)
	(segment
		(start 118.212362 -91.565984)
		(end 118.783862 -91.565984)
		(width 0.1651)
		(layer "F.Cu")
		(net "M_M_DQS_DP<7>")
	)
	(segment
		(start 147.887436 -155.829)
		(end 147.887436 -154.4574)
		(width 0.1651)
		(layer "F.Cu")
		(net "M_M_DQS_DP<7>")
	)
	(segment
		(start 147.887436 -154.4574)
		(end 147.643596 -154.21356)
		(width 0.1651)
		(layer "F.Cu")
		(net "M_M_DQS_DP<7>")
	)
	(segment
		(start 147.643596 -154.21356)
		(end 147.387564 -154.21356)
		(width 0.1651)
		(layer "F.Cu")
		(net "M_M_DQS_DP<7>")
	)
	(segment
		(start 147.84959 -156.87294)
		(end 147.84959 -155.866846)
		(width 0.1651)
		(layer "F.Cu")
		(net "M_M_DQS_DP<7>")
	)
	(via
		(at 147.387564 -150.142956)
		(size 0.508)
		(drill 0.254)
		(layers "F.Cu" "B.Cu")
		(net "M_M_DQS_DP<7>")
	)
	(via
		(at 147.387564 -154.21356)
		(size 0.508)
		(drill 0.254)
		(layers "F.Cu" "B.Cu")
		(net "M_M_DQS_DP<7>")
	)
	(via
		(at 118.783862 -91.565984)
		(size 0.508)
		(drill 0.254)
		(layers "F.Cu" "B.Cu")
		(net "M_M_DQS_DP<7>")
	)
	(segment
		(start 147.62988 -150.142956)
		(end 147.387564 -150.142956)
		(width 0.1651)
		(layer "B.Cu")
		(net "M_M_DQS_DP<7>")
	)
	(segment
		(start 147.84959 -147.478496)
		(end 147.84959 -148.628354)
		(width 0.1651)
		(layer "B.Cu")
		(net "M_M_DQS_DP<7>")
	)
	(segment
		(start 147.849336 -147.478496)
		(end 147.84959 -147.478496)
		(width 0.1651)
		(layer "B.Cu")
		(net "M_M_DQS_DP<7>")
	)
	(segment
		(start 147.887436 -148.6662)
		(end 147.887436 -149.8854)
		(width 0.1651)
		(layer "B.Cu")
		(net "M_M_DQS_DP<7>")
	)
	(segment
		(start 147.84959 -148.628354)
		(end 147.887436 -148.6662)
		(width 0.1651)
		(layer "B.Cu")
		(net "M_M_DQS_DP<7>")
	)
	(segment
		(start 147.887436 -149.8854)
		(end 147.62988 -150.142956)
		(width 0.1651)
		(layer "B.Cu")
		(net "M_M_DQS_DP<7>")
	)
	(segment
		(start 125.993652 -104.456484)
		(end 126.962408 -105.42524)
		(width 0.14224)
		(layer "In11.Cu")
		(net "M_M_DQS_DP<7>")
	)
	(segment
		(start 147.847812 -153.3144)
		(end 147.847812 -153.753312)
		(width 0.14224)
		(layer "In11.Cu")
		(net "M_M_DQS_DP<7>")
	)
	(segment
		(start 122.199654 -94.937834)
		(end 122.239278 -94.937834)
		(width 0.0889)
		(layer "In11.Cu")
		(net "M_M_DQS_DP<7>")
	)
	(segment
		(start 134.914386 -111.167164)
		(end 136.153398 -111.167164)
		(width 0.14224)
		(layer "In11.Cu")
		(net "M_M_DQS_DP<7>")
	)
	(segment
		(start 147.568412 -151.257)
		(end 147.183348 -151.257)
		(width 0.14224)
		(layer "In11.Cu")
		(net "M_M_DQS_DP<7>")
	)
	(segment
		(start 126.962408 -105.42524)
		(end 127.240792 -105.42524)
		(width 0.14224)
		(layer "In11.Cu")
		(net "M_M_DQS_DP<7>")
	)
	(segment
		(start 125.636782 -102.862634)
		(end 125.741176 -102.862634)
		(width 0.0889)
		(layer "In11.Cu")
		(net "M_M_DQS_DP<7>")
	)
	(segment
		(start 148.169884 -149.360636)
		(end 147.387564 -150.142956)
		(width 0.14224)
		(layer "In11.Cu")
		(net "M_M_DQS_DP<7>")
	)
	(segment
		(start 147.208748 -153.0604)
		(end 147.593812 -153.0604)
		(width 0.14224)
		(layer "In11.Cu")
		(net "M_M_DQS_DP<7>")
	)
	(segment
		(start 124.452888 -100.766118)
		(end 124.446538 -100.776786)
		(width 0.0889)
		(layer "In11.Cu")
		(net "M_M_DQS_DP<7>")
	)
	(segment
		(start 125.954282 -104.175814)
		(end 125.993652 -104.215184)
		(width 0.0889)
		(layer "In11.Cu")
		(net "M_M_DQS_DP<7>")
	)
	(segment
		(start 136.153398 -111.167164)
		(end 148.169884 -123.18365)
		(width 0.14224)
		(layer "In11.Cu")
		(net "M_M_DQS_DP<7>")
	)
	(segment
		(start 127.444754 -105.221278)
		(end 128.01854 -105.221278)
		(width 0.14224)
		(layer "In11.Cu")
		(net "M_M_DQS_DP<7>")
	)
	(segment
		(start 127.240792 -105.42524)
		(end 127.444754 -105.221278)
		(width 0.14224)
		(layer "In11.Cu")
		(net "M_M_DQS_DP<7>")
	)
	(segment
		(start 133.916674 -110.791498)
		(end 133.916674 -112.055656)
		(width 0.14224)
		(layer "In11.Cu")
		(net "M_M_DQS_DP<7>")
	)
	(segment
		(start 147.012914 -152.638252)
		(end 147.012914 -152.864566)
		(width 0.14224)
		(layer "In11.Cu")
		(net "M_M_DQS_DP<7>")
	)
	(segment
		(start 125.954282 -103.07574)
		(end 125.954282 -104.175814)
		(width 0.0889)
		(layer "In11.Cu")
		(net "M_M_DQS_DP<7>")
	)
	(segment
		(start 147.127722 -151.8666)
		(end 147.212812 -151.8666)
		(width 0.14224)
		(layer "In11.Cu")
		(net "M_M_DQS_DP<7>")
	)
	(segment
		(start 147.593812 -153.0604)
		(end 147.847812 -153.3144)
		(width 0.14224)
		(layer "In11.Cu")
		(net "M_M_DQS_DP<7>")
	)
	(segment
		(start 134.064502 -112.203484)
		(end 134.417562 -112.203484)
		(width 0.14224)
		(layer "In11.Cu")
		(net "M_M_DQS_DP<7>")
	)
	(segment
		(start 124.782072 -102.367588)
		(end 124.814838 -102.367588)
		(width 0.0889)
		(layer "In11.Cu")
		(net "M_M_DQS_DP<7>")
	)
	(segment
		(start 124.446538 -99.195636)
		(end 124.452888 -99.206304)
		(width 0.0889)
		(layer "In11.Cu")
		(net "M_M_DQS_DP<7>")
	)
	(segment
		(start 134.579614 -111.501936)
		(end 134.914386 -111.167164)
		(width 0.14224)
		(layer "In11.Cu")
		(net "M_M_DQS_DP<7>")
	)
	(segment
		(start 133.916674 -112.055656)
		(end 134.064502 -112.203484)
		(width 0.14224)
		(layer "In11.Cu")
		(net "M_M_DQS_DP<7>")
	)
	(segment
		(start 147.150074 -152.501092)
		(end 147.012914 -152.638252)
		(width 0.14224)
		(layer "In11.Cu")
		(net "M_M_DQS_DP<7>")
	)
	(segment
		(start 147.183348 -151.257)
		(end 147.012914 -151.427434)
		(width 0.14224)
		(layer "In11.Cu")
		(net "M_M_DQS_DP<7>")
	)
	(segment
		(start 147.210272 -152.501092)
		(end 147.150074 -152.501092)
		(width 0.14224)
		(layer "In11.Cu")
		(net "M_M_DQS_DP<7>")
	)
	(segment
		(start 125.993652 -104.215184)
		(end 125.993652 -104.237282)
		(width 0.0889)
		(layer "In11.Cu")
		(net "M_M_DQS_DP<7>")
	)
	(segment
		(start 134.417562 -112.203484)
		(end 134.579614 -112.041432)
		(width 0.14224)
		(layer "In11.Cu")
		(net "M_M_DQS_DP<7>")
	)
	(segment
		(start 147.390612 -152.320752)
		(end 147.210272 -152.501092)
		(width 0.14224)
		(layer "In11.Cu")
		(net "M_M_DQS_DP<7>")
	)
	(segment
		(start 147.847812 -153.753312)
		(end 147.387564 -154.21356)
		(width 0.14224)
		(layer "In11.Cu")
		(net "M_M_DQS_DP<7>")
	)
	(segment
		(start 123.919742 -95.928434)
		(end 123.952508 -95.928434)
		(width 0.0889)
		(layer "In11.Cu")
		(net "M_M_DQS_DP<7>")
	)
	(segment
		(start 129.815336 -106.69016)
		(end 133.916674 -110.791498)
		(width 0.14224)
		(layer "In11.Cu")
		(net "M_M_DQS_DP<7>")
	)
	(segment
		(start 128.01854 -105.221278)
		(end 128.425448 -105.628186)
		(width 0.14224)
		(layer "In11.Cu")
		(net "M_M_DQS_DP<7>")
	)
	(segment
		(start 147.822412 -151.003)
		(end 147.568412 -151.257)
		(width 0.14224)
		(layer "In11.Cu")
		(net "M_M_DQS_DP<7>")
	)
	(segment
		(start 123.065032 -95.433134)
		(end 123.089162 -95.433134)
		(width 0.0889)
		(layer "In11.Cu")
		(net "M_M_DQS_DP<7>")
	)
	(segment
		(start 119.631206 -93.452188)
		(end 119.663972 -93.452188)
		(width 0.0889)
		(layer "In11.Cu")
		(net "M_M_DQS_DP<7>")
	)
	(segment
		(start 128.597914 -106.69016)
		(end 129.815336 -106.69016)
		(width 0.14224)
		(layer "In11.Cu")
		(net "M_M_DQS_DP<7>")
	)
	(segment
		(start 121.346976 -94.442534)
		(end 121.376948 -94.442534)
		(width 0.0889)
		(layer "In11.Cu")
		(net "M_M_DQS_DP<7>")
	)
	(segment
		(start 124.441712 -99.187)
		(end 124.446538 -99.195636)
		(width 0.0889)
		(layer "In11.Cu")
		(net "M_M_DQS_DP<7>")
	)
	(segment
		(start 147.390612 -152.0444)
		(end 147.390612 -152.320752)
		(width 0.14224)
		(layer "In11.Cu")
		(net "M_M_DQS_DP<7>")
	)
	(segment
		(start 147.387564 -150.142956)
		(end 147.822412 -150.577804)
		(width 0.14224)
		(layer "In11.Cu")
		(net "M_M_DQS_DP<7>")
	)
	(segment
		(start 147.012914 -151.751792)
		(end 147.127722 -151.8666)
		(width 0.14224)
		(layer "In11.Cu")
		(net "M_M_DQS_DP<7>")
	)
	(segment
		(start 125.993652 -104.237282)
		(end 125.993652 -104.456484)
		(width 0.14224)
		(layer "In11.Cu")
		(net "M_M_DQS_DP<7>")
	)
	(segment
		(start 124.441712 -97.2058)
		(end 124.446538 -97.214436)
		(width 0.0889)
		(layer "In11.Cu")
		(net "M_M_DQS_DP<7>")
	)
	(segment
		(start 125.741176 -102.862634)
		(end 125.954282 -103.07574)
		(width 0.0889)
		(layer "In11.Cu")
		(net "M_M_DQS_DP<7>")
	)
	(segment
		(start 128.425448 -105.628186)
		(end 128.425448 -106.517694)
		(width 0.14224)
		(layer "In11.Cu")
		(net "M_M_DQS_DP<7>")
	)
	(segment
		(start 124.441712 -100.1776)
		(end 124.446538 -100.186236)
		(width 0.0889)
		(layer "In11.Cu")
		(net "M_M_DQS_DP<7>")
	)
	(segment
		(start 147.012914 -152.864566)
		(end 147.208748 -153.0604)
		(width 0.14224)
		(layer "In11.Cu")
		(net "M_M_DQS_DP<7>")
	)
	(segment
		(start 147.012914 -151.427434)
		(end 147.012914 -151.751792)
		(width 0.14224)
		(layer "In11.Cu")
		(net "M_M_DQS_DP<7>")
	)
	(segment
		(start 147.212812 -151.8666)
		(end 147.390612 -152.0444)
		(width 0.14224)
		(layer "In11.Cu")
		(net "M_M_DQS_DP<7>")
	)
	(segment
		(start 120.485916 -93.947234)
		(end 120.513856 -93.947234)
		(width 0.0889)
		(layer "In11.Cu")
		(net "M_M_DQS_DP<7>")
	)
	(segment
		(start 134.579614 -112.041432)
		(end 134.579614 -111.501936)
		(width 0.14224)
		(layer "In11.Cu")
		(net "M_M_DQS_DP<7>")
	)
	(segment
		(start 148.169884 -123.18365)
		(end 148.169884 -149.360636)
		(width 0.14224)
		(layer "In11.Cu")
		(net "M_M_DQS_DP<7>")
	)
	(segment
		(start 128.425448 -106.517694)
		(end 128.597914 -106.69016)
		(width 0.14224)
		(layer "In11.Cu")
		(net "M_M_DQS_DP<7>")
	)
	(segment
		(start 147.822412 -150.577804)
		(end 147.822412 -151.003)
		(width 0.14224)
		(layer "In11.Cu")
		(net "M_M_DQS_DP<7>")
	)
	(arc
		(start 122.239278 -94.937834)
		(mid 122.522495 -95.022115)
		(end 122.729498 -95.232982)
		(width 0.0889)
		(layer "In11.Cu")
		(net "M_M_DQS_DP<7>")
	)
	(arc
		(start 123.089162 -95.433134)
		(mid 123.377307 -95.515453)
		(end 123.588018 -95.728536)
		(width 0.0889)
		(layer "In11.Cu")
		(net "M_M_DQS_DP<7>")
	)
	(arc
		(start 122.729498 -95.232982)
		(mid 122.871181 -95.376786)
		(end 123.065032 -95.433134)
		(width 0.0889)
		(layer "In11.Cu")
		(net "M_M_DQS_DP<7>")
	)
	(arc
		(start 124.446538 -98.795586)
		(mid 124.393068 -98.990649)
		(end 124.441712 -99.187)
		(width 0.0889)
		(layer "In11.Cu")
		(net "M_M_DQS_DP<7>")
	)
	(arc
		(start 119.295672 -92.851986)
		(mid 119.293121 -93.247288)
		(end 119.631206 -93.452188)
		(width 0.0889)
		(layer "In11.Cu")
		(net "M_M_DQS_DP<7>")
	)
	(arc
		(start 119.130572 -92.356686)
		(mid 119.172441 -92.419687)
		(end 119.222012 -92.476828)
		(width 0.0889)
		(layer "In11.Cu")
		(net "M_M_DQS_DP<7>")
	)
	(arc
		(start 123.952508 -95.928434)
		(mid 124.450759 -96.231274)
		(end 124.446538 -96.814386)
		(width 0.0889)
		(layer "In11.Cu")
		(net "M_M_DQS_DP<7>")
	)
	(arc
		(start 119.222012 -92.476828)
		(mid 119.315973 -92.653177)
		(end 119.295672 -92.851986)
		(width 0.0889)
		(layer "In11.Cu")
		(net "M_M_DQS_DP<7>")
	)
	(arc
		(start 124.814838 -102.367588)
		(mid 125.098055 -102.451869)
		(end 125.305058 -102.662736)
		(width 0.0889)
		(layer "In11.Cu")
		(net "M_M_DQS_DP<7>")
	)
	(arc
		(start 124.446538 -96.814386)
		(mid 124.393068 -97.009449)
		(end 124.441712 -97.2058)
		(width 0.0889)
		(layer "In11.Cu")
		(net "M_M_DQS_DP<7>")
	)
	(arc
		(start 124.446538 -101.176582)
		(mid 124.525669 -101.471984)
		(end 124.446538 -101.767386)
		(width 0.0889)
		(layer "In11.Cu")
		(net "M_M_DQS_DP<7>")
	)
	(arc
		(start 124.446538 -97.805748)
		(mid 124.393073 -98.005646)
		(end 124.446538 -98.205544)
		(width 0.0889)
		(layer "In11.Cu")
		(net "M_M_DQS_DP<7>")
	)
	(arc
		(start 119.052086 -92.089986)
		(mid 119.075399 -92.228027)
		(end 119.130572 -92.356686)
		(width 0.0889)
		(layer "In11.Cu")
		(net "M_M_DQS_DP<7>")
	)
	(arc
		(start 125.305058 -102.662736)
		(mid 125.445137 -102.805472)
		(end 125.636782 -102.862634)
		(width 0.0889)
		(layer "In11.Cu")
		(net "M_M_DQS_DP<7>")
	)
	(arc
		(start 121.870978 -94.737936)
		(mid 122.009722 -94.879969)
		(end 122.199654 -94.937834)
		(width 0.0889)
		(layer "In11.Cu")
		(net "M_M_DQS_DP<7>")
	)
	(arc
		(start 120.513856 -93.947234)
		(mid 120.802001 -94.029553)
		(end 121.012712 -94.242636)
		(width 0.0889)
		(layer "In11.Cu")
		(net "M_M_DQS_DP<7>")
	)
	(arc
		(start 123.588018 -95.728536)
		(mid 123.728097 -95.871272)
		(end 123.919742 -95.928434)
		(width 0.0889)
		(layer "In11.Cu")
		(net "M_M_DQS_DP<7>")
	)
	(arc
		(start 124.446538 -101.767386)
		(mid 124.44379 -102.162853)
		(end 124.782072 -102.367588)
		(width 0.0889)
		(layer "In11.Cu")
		(net "M_M_DQS_DP<7>")
	)
	(arc
		(start 120.154192 -93.747336)
		(mid 120.294271 -93.890072)
		(end 120.485916 -93.947234)
		(width 0.0889)
		(layer "In11.Cu")
		(net "M_M_DQS_DP<7>")
	)
	(arc
		(start 118.783862 -91.565984)
		(mid 118.974471 -91.799074)
		(end 119.052086 -92.089986)
		(width 0.0889)
		(layer "In11.Cu")
		(net "M_M_DQS_DP<7>")
	)
	(arc
		(start 124.446538 -99.786186)
		(mid 124.393068 -99.981249)
		(end 124.441712 -100.1776)
		(width 0.0889)
		(layer "In11.Cu")
		(net "M_M_DQS_DP<7>")
	)
	(arc
		(start 124.446538 -97.214436)
		(mid 124.525627 -97.510092)
		(end 124.446538 -97.805748)
		(width 0.0889)
		(layer "In11.Cu")
		(net "M_M_DQS_DP<7>")
	)
	(arc
		(start 119.663972 -93.452188)
		(mid 119.947189 -93.536469)
		(end 120.154192 -93.747336)
		(width 0.0889)
		(layer "In11.Cu")
		(net "M_M_DQS_DP<7>")
	)
	(arc
		(start 124.446538 -98.205544)
		(mid 124.525543 -98.500582)
		(end 124.446538 -98.795586)
		(width 0.0889)
		(layer "In11.Cu")
		(net "M_M_DQS_DP<7>")
	)
	(arc
		(start 121.376948 -94.442534)
		(mid 121.662372 -94.526001)
		(end 121.870978 -94.737936)
		(width 0.0889)
		(layer "In11.Cu")
		(net "M_M_DQS_DP<7>")
	)
	(arc
		(start 124.446538 -100.186236)
		(mid 124.52576 -100.475354)
		(end 124.452888 -100.766118)
		(width 0.0889)
		(layer "In11.Cu")
		(net "M_M_DQS_DP<7>")
	)
	(arc
		(start 124.446538 -100.776786)
		(mid 124.393039 -100.976684)
		(end 124.446538 -101.176582)
		(width 0.0889)
		(layer "In11.Cu")
		(net "M_M_DQS_DP<7>")
	)
	(arc
		(start 124.452888 -99.206304)
		(mid 124.525686 -99.497067)
		(end 124.446538 -99.786186)
		(width 0.0889)
		(layer "In11.Cu")
		(net "M_M_DQS_DP<7>")
	)
	(arc
		(start 121.012712 -94.242636)
		(mid 121.153869 -94.386021)
		(end 121.346976 -94.442534)
		(width 0.0889)
		(layer "In11.Cu")
		(net "M_M_DQS_DP<7>")
	)
	(segment
		(start 138.293602 -154.21356)
		(end 138.03757 -154.21356)
		(width 0.1651)
		(layer "F.Cu")
		(net "M_M_DQS_DP<6>")
	)
	(segment
		(start 113.061242 -91.565984)
		(end 113.632742 -91.565984)
		(width 0.1651)
		(layer "F.Cu")
		(net "M_M_DQS_DP<6>")
	)
	(segment
		(start 138.499342 -156.87294)
		(end 138.499596 -156.87294)
		(width 0.1651)
		(layer "F.Cu")
		(net "M_M_DQS_DP<6>")
	)
	(segment
		(start 138.537442 -155.829)
		(end 138.537442 -154.4574)
		(width 0.1651)
		(layer "F.Cu")
		(net "M_M_DQS_DP<6>")
	)
	(segment
		(start 138.537442 -154.4574)
		(end 138.293602 -154.21356)
		(width 0.1651)
		(layer "F.Cu")
		(net "M_M_DQS_DP<6>")
	)
	(segment
		(start 138.499596 -155.866846)
		(end 138.537442 -155.829)
		(width 0.1651)
		(layer "F.Cu")
		(net "M_M_DQS_DP<6>")
	)
	(segment
		(start 138.499596 -156.87294)
		(end 138.499596 -155.866846)
		(width 0.1651)
		(layer "F.Cu")
		(net "M_M_DQS_DP<6>")
	)
	(via
		(at 138.03757 -154.21356)
		(size 0.508)
		(drill 0.254)
		(layers "F.Cu" "B.Cu")
		(net "M_M_DQS_DP<6>")
	)
	(via
		(at 138.03757 -150.142956)
		(size 0.508)
		(drill 0.254)
		(layers "F.Cu" "B.Cu")
		(net "M_M_DQS_DP<6>")
	)
	(via
		(at 113.632742 -91.565984)
		(size 0.508)
		(drill 0.254)
		(layers "F.Cu" "B.Cu")
		(net "M_M_DQS_DP<6>")
	)
	(segment
		(start 138.499596 -147.478496)
		(end 138.499596 -148.628354)
		(width 0.1651)
		(layer "B.Cu")
		(net "M_M_DQS_DP<6>")
	)
	(segment
		(start 138.279886 -150.142956)
		(end 138.03757 -150.142956)
		(width 0.1651)
		(layer "B.Cu")
		(net "M_M_DQS_DP<6>")
	)
	(segment
		(start 138.499596 -148.628354)
		(end 138.537442 -148.6662)
		(width 0.1651)
		(layer "B.Cu")
		(net "M_M_DQS_DP<6>")
	)
	(segment
		(start 138.537442 -149.8854)
		(end 138.279886 -150.142956)
		(width 0.1651)
		(layer "B.Cu")
		(net "M_M_DQS_DP<6>")
	)
	(segment
		(start 138.499342 -147.478496)
		(end 138.499596 -147.478496)
		(width 0.1651)
		(layer "B.Cu")
		(net "M_M_DQS_DP<6>")
	)
	(segment
		(start 138.537442 -148.6662)
		(end 138.537442 -149.8854)
		(width 0.1651)
		(layer "B.Cu")
		(net "M_M_DQS_DP<6>")
	)
	(segment
		(start 134.05866 -119.682768)
		(end 138.81989 -124.443998)
		(width 0.14224)
		(layer "In11.Cu")
		(net "M_M_DQS_DP<6>")
	)
	(segment
		(start 118.443502 -103.242618)
		(end 118.437152 -103.253286)
		(width 0.0889)
		(layer "In11.Cu")
		(net "M_M_DQS_DP<6>")
	)
	(segment
		(start 118.479062 -107.188)
		(end 118.479062 -112.94999)
		(width 0.14224)
		(layer "In11.Cu")
		(net "M_M_DQS_DP<6>")
	)
	(segment
		(start 118.437152 -105.634536)
		(end 118.515892 -105.771188)
		(width 0.0889)
		(layer "In11.Cu")
		(net "M_M_DQS_DP<6>")
	)
	(segment
		(start 114.144806 -93.25229)
		(end 114.144552 -93.252036)
		(width 0.0889)
		(layer "In11.Cu")
		(net "M_M_DQS_DP<6>")
	)
	(segment
		(start 118.479062 -107.165902)
		(end 118.479062 -107.188)
		(width 0.0889)
		(layer "In11.Cu")
		(net "M_M_DQS_DP<6>")
	)
	(segment
		(start 117.914166 -98.405188)
		(end 117.946932 -98.405188)
		(width 0.0889)
		(layer "In11.Cu")
		(net "M_M_DQS_DP<6>")
	)
	(segment
		(start 132.171694 -119.143272)
		(end 132.484114 -118.830852)
		(width 0.14224)
		(layer "In11.Cu")
		(net "M_M_DQS_DP<6>")
	)
	(segment
		(start 131.546346 -119.682768)
		(end 132.016754 -119.682768)
		(width 0.14224)
		(layer "In11.Cu")
		(net "M_M_DQS_DP<6>")
	)
	(segment
		(start 118.437152 -105.234486)
		(end 118.432326 -105.243122)
		(width 0.0889)
		(layer "In11.Cu")
		(net "M_M_DQS_DP<6>")
	)
	(segment
		(start 138.218418 -151.257)
		(end 137.833354 -151.257)
		(width 0.14224)
		(layer "In11.Cu")
		(net "M_M_DQS_DP<6>")
	)
	(segment
		(start 138.81989 -149.308566)
		(end 138.427968 -149.700488)
		(width 0.14224)
		(layer "In11.Cu")
		(net "M_M_DQS_DP<6>")
	)
	(segment
		(start 137.833354 -151.257)
		(end 137.66292 -151.427434)
		(width 0.14224)
		(layer "In11.Cu")
		(net "M_M_DQS_DP<6>")
	)
	(segment
		(start 118.515892 -106.209592)
		(end 118.439692 -106.285792)
		(width 0.0889)
		(layer "In11.Cu")
		(net "M_M_DQS_DP<6>")
	)
	(segment
		(start 133.373114 -119.527828)
		(end 133.528054 -119.682768)
		(width 0.14224)
		(layer "In11.Cu")
		(net "M_M_DQS_DP<6>")
	)
	(segment
		(start 133.528054 -119.682768)
		(end 134.05866 -119.682768)
		(width 0.14224)
		(layer "In11.Cu")
		(net "M_M_DQS_DP<6>")
	)
	(segment
		(start 138.427968 -149.752558)
		(end 138.03757 -150.142956)
		(width 0.14224)
		(layer "In11.Cu")
		(net "M_M_DQS_DP<6>")
	)
	(segment
		(start 137.862818 -151.8666)
		(end 138.040618 -152.0444)
		(width 0.14224)
		(layer "In11.Cu")
		(net "M_M_DQS_DP<6>")
	)
	(segment
		(start 118.443502 -104.233218)
		(end 118.437152 -104.243886)
		(width 0.0889)
		(layer "In11.Cu")
		(net "M_M_DQS_DP<6>")
	)
	(segment
		(start 137.66292 -151.751792)
		(end 137.777728 -151.8666)
		(width 0.14224)
		(layer "In11.Cu")
		(net "M_M_DQS_DP<6>")
	)
	(segment
		(start 114.150902 -94.822518)
		(end 114.144552 -94.833186)
		(width 0.0889)
		(layer "In11.Cu")
		(net "M_M_DQS_DP<6>")
	)
	(segment
		(start 133.060694 -118.830852)
		(end 133.373114 -119.143272)
		(width 0.14224)
		(layer "In11.Cu")
		(net "M_M_DQS_DP<6>")
	)
	(segment
		(start 133.373114 -119.143272)
		(end 133.373114 -119.527828)
		(width 0.14224)
		(layer "In11.Cu")
		(net "M_M_DQS_DP<6>")
	)
	(segment
		(start 116.197126 -97.414588)
		(end 116.229892 -97.414588)
		(width 0.0889)
		(layer "In11.Cu")
		(net "M_M_DQS_DP<6>")
	)
	(segment
		(start 118.439692 -107.126532)
		(end 118.479062 -107.165902)
		(width 0.0889)
		(layer "In11.Cu")
		(net "M_M_DQS_DP<6>")
	)
	(segment
		(start 137.66292 -151.427434)
		(end 137.66292 -151.751792)
		(width 0.14224)
		(layer "In11.Cu")
		(net "M_M_DQS_DP<6>")
	)
	(segment
		(start 138.472418 -151.003)
		(end 138.218418 -151.257)
		(width 0.14224)
		(layer "In11.Cu")
		(net "M_M_DQS_DP<6>")
	)
	(segment
		(start 130.272536 -119.08663)
		(end 130.950208 -119.08663)
		(width 0.14224)
		(layer "In11.Cu")
		(net "M_M_DQS_DP<6>")
	)
	(segment
		(start 114.150902 -93.831918)
		(end 114.144552 -93.842586)
		(width 0.0889)
		(layer "In11.Cu")
		(net "M_M_DQS_DP<6>")
	)
	(segment
		(start 129.541778 -119.817388)
		(end 130.272536 -119.08663)
		(width 0.14224)
		(layer "In11.Cu")
		(net "M_M_DQS_DP<6>")
	)
	(segment
		(start 137.860278 -152.501092)
		(end 137.80008 -152.501092)
		(width 0.14224)
		(layer "In11.Cu")
		(net "M_M_DQS_DP<6>")
	)
	(segment
		(start 125.34646 -119.817388)
		(end 129.541778 -119.817388)
		(width 0.14224)
		(layer "In11.Cu")
		(net "M_M_DQS_DP<6>")
	)
	(segment
		(start 114.480086 -96.423988)
		(end 114.512852 -96.423988)
		(width 0.0889)
		(layer "In11.Cu")
		(net "M_M_DQS_DP<6>")
	)
	(segment
		(start 118.479062 -112.94999)
		(end 125.34646 -119.817388)
		(width 0.14224)
		(layer "In11.Cu")
		(net "M_M_DQS_DP<6>")
	)
	(segment
		(start 118.443502 -105.223818)
		(end 118.437152 -105.234486)
		(width 0.0889)
		(layer "In11.Cu")
		(net "M_M_DQS_DP<6>")
	)
	(segment
		(start 138.81989 -124.443998)
		(end 138.81989 -149.308566)
		(width 0.14224)
		(layer "In11.Cu")
		(net "M_M_DQS_DP<6>")
	)
	(segment
		(start 137.66292 -152.864566)
		(end 137.858754 -153.0604)
		(width 0.14224)
		(layer "In11.Cu")
		(net "M_M_DQS_DP<6>")
	)
	(segment
		(start 138.497818 -153.753312)
		(end 138.03757 -154.21356)
		(width 0.14224)
		(layer "In11.Cu")
		(net "M_M_DQS_DP<6>")
	)
	(segment
		(start 137.858754 -153.0604)
		(end 138.243818 -153.0604)
		(width 0.14224)
		(layer "In11.Cu")
		(net "M_M_DQS_DP<6>")
	)
	(segment
		(start 115.334796 -96.919034)
		(end 115.367562 -96.919034)
		(width 0.0889)
		(layer "In11.Cu")
		(net "M_M_DQS_DP<6>")
	)
	(segment
		(start 137.777728 -151.8666)
		(end 137.862818 -151.8666)
		(width 0.14224)
		(layer "In11.Cu")
		(net "M_M_DQS_DP<6>")
	)
	(segment
		(start 118.437152 -104.243886)
		(end 118.432326 -104.252522)
		(width 0.0889)
		(layer "In11.Cu")
		(net "M_M_DQS_DP<6>")
	)
	(segment
		(start 118.439692 -106.285792)
		(end 118.439692 -107.126532)
		(width 0.0889)
		(layer "In11.Cu")
		(net "M_M_DQS_DP<6>")
	)
	(segment
		(start 117.051836 -97.909634)
		(end 117.084602 -97.909634)
		(width 0.0889)
		(layer "In11.Cu")
		(net "M_M_DQS_DP<6>")
	)
	(segment
		(start 132.016754 -119.682768)
		(end 132.171694 -119.527828)
		(width 0.14224)
		(layer "In11.Cu")
		(net "M_M_DQS_DP<6>")
	)
	(segment
		(start 132.171694 -119.527828)
		(end 132.171694 -119.143272)
		(width 0.14224)
		(layer "In11.Cu")
		(net "M_M_DQS_DP<6>")
	)
	(segment
		(start 138.040618 -152.320752)
		(end 137.860278 -152.501092)
		(width 0.14224)
		(layer "In11.Cu")
		(net "M_M_DQS_DP<6>")
	)
	(segment
		(start 137.80008 -152.501092)
		(end 137.66292 -152.638252)
		(width 0.14224)
		(layer "In11.Cu")
		(net "M_M_DQS_DP<6>")
	)
	(segment
		(start 137.66292 -152.638252)
		(end 137.66292 -152.864566)
		(width 0.14224)
		(layer "In11.Cu")
		(net "M_M_DQS_DP<6>")
	)
	(segment
		(start 138.472418 -150.577804)
		(end 138.472418 -151.003)
		(width 0.14224)
		(layer "In11.Cu")
		(net "M_M_DQS_DP<6>")
	)
	(segment
		(start 132.484114 -118.830852)
		(end 133.060694 -118.830852)
		(width 0.14224)
		(layer "In11.Cu")
		(net "M_M_DQS_DP<6>")
	)
	(segment
		(start 118.437152 -103.253286)
		(end 118.432326 -103.261922)
		(width 0.0889)
		(layer "In11.Cu")
		(net "M_M_DQS_DP<6>")
	)
	(segment
		(start 113.97615 -92.351352)
		(end 113.986056 -92.368624)
		(width 0.0889)
		(layer "In11.Cu")
		(net "M_M_DQS_DP<6>")
	)
	(segment
		(start 118.437152 -99.690682)
		(end 118.443502 -99.70135)
		(width 0.0889)
		(layer "In11.Cu")
		(net "M_M_DQS_DP<6>")
	)
	(segment
		(start 118.443502 -99.280218)
		(end 118.437152 -99.290886)
		(width 0.0889)
		(layer "In11.Cu")
		(net "M_M_DQS_DP<6>")
	)
	(segment
		(start 138.040618 -152.0444)
		(end 138.040618 -152.320752)
		(width 0.14224)
		(layer "In11.Cu")
		(net "M_M_DQS_DP<6>")
	)
	(segment
		(start 130.950208 -119.08663)
		(end 131.546346 -119.682768)
		(width 0.14224)
		(layer "In11.Cu")
		(net "M_M_DQS_DP<6>")
	)
	(segment
		(start 138.03757 -150.142956)
		(end 138.472418 -150.577804)
		(width 0.14224)
		(layer "In11.Cu")
		(net "M_M_DQS_DP<6>")
	)
	(segment
		(start 138.497818 -153.3144)
		(end 138.497818 -153.753312)
		(width 0.14224)
		(layer "In11.Cu")
		(net "M_M_DQS_DP<6>")
	)
	(segment
		(start 138.243818 -153.0604)
		(end 138.497818 -153.3144)
		(width 0.14224)
		(layer "In11.Cu")
		(net "M_M_DQS_DP<6>")
	)
	(segment
		(start 138.427968 -149.700488)
		(end 138.427968 -149.752558)
		(width 0.14224)
		(layer "In11.Cu")
		(net "M_M_DQS_DP<6>")
	)
	(segment
		(start 118.515892 -105.771188)
		(end 118.515892 -106.209592)
		(width 0.0889)
		(layer "In11.Cu")
		(net "M_M_DQS_DP<6>")
	)
	(arc
		(start 115.003072 -96.719136)
		(mid 115.143151 -96.861872)
		(end 115.334796 -96.919034)
		(width 0.0889)
		(layer "In11.Cu")
		(net "M_M_DQS_DP<6>")
	)
	(arc
		(start 115.861592 -97.214436)
		(mid 116.003275 -97.35824)
		(end 116.197126 -97.414588)
		(width 0.0889)
		(layer "In11.Cu")
		(net "M_M_DQS_DP<6>")
	)
	(arc
		(start 118.443502 -99.70135)
		(mid 118.5163 -99.992113)
		(end 118.437152 -100.281232)
		(width 0.0889)
		(layer "In11.Cu")
		(net "M_M_DQS_DP<6>")
	)
	(arc
		(start 118.443502 -101.68255)
		(mid 118.5163 -101.973313)
		(end 118.437152 -102.262432)
		(width 0.0889)
		(layer "In11.Cu")
		(net "M_M_DQS_DP<6>")
	)
	(arc
		(start 116.229892 -97.414588)
		(mid 116.513109 -97.498869)
		(end 116.720112 -97.709736)
		(width 0.0889)
		(layer "In11.Cu")
		(net "M_M_DQS_DP<6>")
	)
	(arc
		(start 118.437152 -103.653336)
		(mid 118.516374 -103.942454)
		(end 118.443502 -104.233218)
		(width 0.0889)
		(layer "In11.Cu")
		(net "M_M_DQS_DP<6>")
	)
	(arc
		(start 118.437152 -101.671628)
		(mid 118.440395 -101.677049)
		(end 118.443502 -101.68255)
		(width 0.0889)
		(layer "In11.Cu")
		(net "M_M_DQS_DP<6>")
	)
	(arc
		(start 114.144552 -94.833186)
		(mid 114.091053 -95.033084)
		(end 114.144552 -95.232982)
		(width 0.0889)
		(layer "In11.Cu")
		(net "M_M_DQS_DP<6>")
	)
	(arc
		(start 114.144552 -95.823786)
		(mid 114.141804 -96.219253)
		(end 114.480086 -96.423988)
		(width 0.0889)
		(layer "In11.Cu")
		(net "M_M_DQS_DP<6>")
	)
	(arc
		(start 118.437152 -99.290886)
		(mid 118.383653 -99.490784)
		(end 118.437152 -99.690682)
		(width 0.0889)
		(layer "In11.Cu")
		(net "M_M_DQS_DP<6>")
	)
	(arc
		(start 118.432326 -105.243122)
		(mid 118.383571 -105.439474)
		(end 118.437152 -105.634536)
		(width 0.0889)
		(layer "In11.Cu")
		(net "M_M_DQS_DP<6>")
	)
	(arc
		(start 118.437152 -104.643936)
		(mid 118.516374 -104.933054)
		(end 118.443502 -105.223818)
		(width 0.0889)
		(layer "In11.Cu")
		(net "M_M_DQS_DP<6>")
	)
	(arc
		(start 117.084602 -97.909634)
		(mid 117.370026 -97.993101)
		(end 117.578632 -98.205036)
		(width 0.0889)
		(layer "In11.Cu")
		(net "M_M_DQS_DP<6>")
	)
	(arc
		(start 118.47195 -100.751386)
		(mid 118.515365 -101.015677)
		(end 118.437152 -101.271832)
		(width 0.0889)
		(layer "In11.Cu")
		(net "M_M_DQS_DP<6>")
	)
	(arc
		(start 113.632742 -91.565984)
		(mid 113.783125 -91.96799)
		(end 113.97615 -92.351352)
		(width 0.0889)
		(layer "In11.Cu")
		(net "M_M_DQS_DP<6>")
	)
	(arc
		(start 118.437152 -102.662736)
		(mid 118.516374 -102.951854)
		(end 118.443502 -103.242618)
		(width 0.0889)
		(layer "In11.Cu")
		(net "M_M_DQS_DP<6>")
	)
	(arc
		(start 116.720112 -97.709736)
		(mid 116.860191 -97.852472)
		(end 117.051836 -97.909634)
		(width 0.0889)
		(layer "In11.Cu")
		(net "M_M_DQS_DP<6>")
	)
	(arc
		(start 118.437152 -101.271832)
		(mid 118.383653 -101.47173)
		(end 118.437152 -101.671628)
		(width 0.0889)
		(layer "In11.Cu")
		(net "M_M_DQS_DP<6>")
	)
	(arc
		(start 114.144552 -93.842586)
		(mid 114.090858 -94.042628)
		(end 114.144552 -94.242636)
		(width 0.0889)
		(layer "In11.Cu")
		(net "M_M_DQS_DP<6>")
	)
	(arc
		(start 115.367562 -96.919034)
		(mid 115.652986 -97.002501)
		(end 115.861592 -97.214436)
		(width 0.0889)
		(layer "In11.Cu")
		(net "M_M_DQS_DP<6>")
	)
	(arc
		(start 118.432326 -104.252522)
		(mid 118.383571 -104.448874)
		(end 118.437152 -104.643936)
		(width 0.0889)
		(layer "In11.Cu")
		(net "M_M_DQS_DP<6>")
	)
	(arc
		(start 117.946932 -98.405188)
		(mid 118.439322 -98.704121)
		(end 118.443502 -99.280218)
		(width 0.0889)
		(layer "In11.Cu")
		(net "M_M_DQS_DP<6>")
	)
	(arc
		(start 118.437152 -100.281232)
		(mid 118.383653 -100.48113)
		(end 118.437152 -100.681028)
		(width 0.0889)
		(layer "In11.Cu")
		(net "M_M_DQS_DP<6>")
	)
	(arc
		(start 117.578632 -98.205036)
		(mid 117.720315 -98.34884)
		(end 117.914166 -98.405188)
		(width 0.0889)
		(layer "In11.Cu")
		(net "M_M_DQS_DP<6>")
	)
	(arc
		(start 114.144552 -93.252036)
		(mid 114.223774 -93.541154)
		(end 114.150902 -93.831918)
		(width 0.0889)
		(layer "In11.Cu")
		(net "M_M_DQS_DP<6>")
	)
	(arc
		(start 113.986056 -92.368624)
		(mid 114.028618 -92.496638)
		(end 114.026188 -92.631514)
		(width 0.0889)
		(layer "In11.Cu")
		(net "M_M_DQS_DP<6>")
	)
	(arc
		(start 118.437152 -102.262432)
		(mid 118.383526 -102.462584)
		(end 118.437152 -102.662736)
		(width 0.0889)
		(layer "In11.Cu")
		(net "M_M_DQS_DP<6>")
	)
	(arc
		(start 114.026188 -92.631514)
		(mid 114.033031 -92.951935)
		(end 114.144806 -93.25229)
		(width 0.0889)
		(layer "In11.Cu")
		(net "M_M_DQS_DP<6>")
	)
	(arc
		(start 114.144552 -94.242636)
		(mid 114.223774 -94.531754)
		(end 114.150902 -94.822518)
		(width 0.0889)
		(layer "In11.Cu")
		(net "M_M_DQS_DP<6>")
	)
	(arc
		(start 114.512852 -96.423988)
		(mid 114.796069 -96.508269)
		(end 115.003072 -96.719136)
		(width 0.0889)
		(layer "In11.Cu")
		(net "M_M_DQS_DP<6>")
	)
	(arc
		(start 118.432326 -103.261922)
		(mid 118.383571 -103.458274)
		(end 118.437152 -103.653336)
		(width 0.0889)
		(layer "In11.Cu")
		(net "M_M_DQS_DP<6>")
	)
	(arc
		(start 114.144552 -95.232982)
		(mid 114.223683 -95.528384)
		(end 114.144552 -95.823786)
		(width 0.0889)
		(layer "In11.Cu")
		(net "M_M_DQS_DP<6>")
	)
	(arc
		(start 118.437152 -100.681028)
		(mid 118.455728 -100.715625)
		(end 118.47195 -100.751386)
		(width 0.0889)
		(layer "In11.Cu")
		(net "M_M_DQS_DP<6>")
	)
	(segment
		(start 129.149348 -156.87294)
		(end 129.149602 -156.87294)
		(width 0.1651)
		(layer "F.Cu")
		(net "M_M_DQS_DP<5>")
	)
	(segment
		(start 129.187448 -154.4574)
		(end 128.943608 -154.21356)
		(width 0.1651)
		(layer "F.Cu")
		(net "M_M_DQS_DP<5>")
	)
	(segment
		(start 129.149602 -156.87294)
		(end 129.149602 -155.866846)
		(width 0.1651)
		(layer "F.Cu")
		(net "M_M_DQS_DP<5>")
	)
	(segment
		(start 129.149602 -155.866846)
		(end 129.187448 -155.829)
		(width 0.1651)
		(layer "F.Cu")
		(net "M_M_DQS_DP<5>")
	)
	(segment
		(start 128.943608 -154.21356)
		(end 128.687576 -154.21356)
		(width 0.1651)
		(layer "F.Cu")
		(net "M_M_DQS_DP<5>")
	)
	(segment
		(start 129.187448 -155.829)
		(end 129.187448 -154.4574)
		(width 0.1651)
		(layer "F.Cu")
		(net "M_M_DQS_DP<5>")
	)
	(segment
		(start 115.636802 -95.033084)
		(end 116.208302 -95.033084)
		(width 0.1651)
		(layer "F.Cu")
		(net "M_M_DQS_DP<5>")
	)
	(via
		(at 128.687576 -154.21356)
		(size 0.508)
		(drill 0.254)
		(layers "F.Cu" "B.Cu")
		(net "M_M_DQS_DP<5>")
	)
	(via
		(at 128.687576 -150.142956)
		(size 0.508)
		(drill 0.254)
		(layers "F.Cu" "B.Cu")
		(net "M_M_DQS_DP<5>")
	)
	(via
		(at 116.208302 -95.033084)
		(size 0.508)
		(drill 0.254)
		(layers "F.Cu" "B.Cu")
		(net "M_M_DQS_DP<5>")
	)
	(segment
		(start 129.149348 -147.478496)
		(end 129.149602 -147.478496)
		(width 0.1651)
		(layer "B.Cu")
		(net "M_M_DQS_DP<5>")
	)
	(segment
		(start 128.929892 -150.142956)
		(end 128.687576 -150.142956)
		(width 0.1651)
		(layer "B.Cu")
		(net "M_M_DQS_DP<5>")
	)
	(segment
		(start 129.149602 -147.478496)
		(end 129.149602 -148.628354)
		(width 0.1651)
		(layer "B.Cu")
		(net "M_M_DQS_DP<5>")
	)
	(segment
		(start 129.187448 -148.6662)
		(end 129.187448 -149.8854)
		(width 0.1651)
		(layer "B.Cu")
		(net "M_M_DQS_DP<5>")
	)
	(segment
		(start 129.187448 -149.8854)
		(end 128.929892 -150.142956)
		(width 0.1651)
		(layer "B.Cu")
		(net "M_M_DQS_DP<5>")
	)
	(segment
		(start 129.149602 -148.628354)
		(end 129.187448 -148.6662)
		(width 0.1651)
		(layer "B.Cu")
		(net "M_M_DQS_DP<5>")
	)
	(segment
		(start 128.84785 -121.988834)
		(end 129.32537 -122.466354)
		(width 0.14224)
		(layer "In4.Cu")
		(net "M_M_DQS_DP<5>")
	)
	(segment
		(start 117.571774 -106.11739)
		(end 117.606826 -106.178858)
		(width 0.0889)
		(layer "In4.Cu")
		(net "M_M_DQS_DP<5>")
	)
	(segment
		(start 116.720112 -100.281486)
		(end 116.713254 -100.293678)
		(width 0.0889)
		(layer "In4.Cu")
		(net "M_M_DQS_DP<5>")
	)
	(segment
		(start 117.869462 -107.4547)
		(end 117.869462 -107.476798)
		(width 0.0889)
		(layer "In4.Cu")
		(net "M_M_DQS_DP<5>")
	)
	(segment
		(start 128.357376 -121.988834)
		(end 128.84785 -121.988834)
		(width 0.14224)
		(layer "In4.Cu")
		(net "M_M_DQS_DP<5>")
	)
	(segment
		(start 129.32537 -122.868944)
		(end 128.776476 -123.417838)
		(width 0.14224)
		(layer "In4.Cu")
		(net "M_M_DQS_DP<5>")
	)
	(segment
		(start 127.594868 -122.349768)
		(end 127.996442 -122.349768)
		(width 0.14224)
		(layer "In4.Cu")
		(net "M_M_DQS_DP<5>")
	)
	(segment
		(start 128.776476 -123.417838)
		(end 128.776476 -123.647708)
		(width 0.14224)
		(layer "In4.Cu")
		(net "M_M_DQS_DP<5>")
	)
	(segment
		(start 117.606826 -106.178858)
		(end 117.830092 -106.402124)
		(width 0.0889)
		(layer "In4.Cu")
		(net "M_M_DQS_DP<5>")
	)
	(segment
		(start 116.729002 -101.256846)
		(end 116.713254 -101.284278)
		(width 0.0889)
		(layer "In4.Cu")
		(net "M_M_DQS_DP<5>")
	)
	(segment
		(start 116.729002 -102.247446)
		(end 116.713254 -102.274878)
		(width 0.0889)
		(layer "In4.Cu")
		(net "M_M_DQS_DP<5>")
	)
	(segment
		(start 127.996442 -122.349768)
		(end 128.357376 -121.988834)
		(width 0.14224)
		(layer "In4.Cu")
		(net "M_M_DQS_DP<5>")
	)
	(segment
		(start 117.830092 -106.402124)
		(end 117.830092 -107.41533)
		(width 0.0889)
		(layer "In4.Cu")
		(net "M_M_DQS_DP<5>")
	)
	(segment
		(start 117.051836 -104.84358)
		(end 117.084602 -104.84358)
		(width 0.0889)
		(layer "In4.Cu")
		(net "M_M_DQS_DP<5>")
	)
	(segment
		(start 128.776476 -123.647708)
		(end 129.469896 -124.341128)
		(width 0.14224)
		(layer "In4.Cu")
		(net "M_M_DQS_DP<5>")
	)
	(segment
		(start 117.869462 -107.476798)
		(end 117.869462 -112.624362)
		(width 0.14224)
		(layer "In4.Cu")
		(net "M_M_DQS_DP<5>")
	)
	(segment
		(start 117.830092 -107.41533)
		(end 117.869462 -107.4547)
		(width 0.0889)
		(layer "In4.Cu")
		(net "M_M_DQS_DP<5>")
	)
	(segment
		(start 129.469896 -149.360636)
		(end 128.687576 -150.142956)
		(width 0.14224)
		(layer "In4.Cu")
		(net "M_M_DQS_DP<5>")
	)
	(segment
		(start 116.729002 -104.228646)
		(end 116.713254 -104.256078)
		(width 0.0889)
		(layer "In4.Cu")
		(net "M_M_DQS_DP<5>")
	)
	(segment
		(start 116.726462 -100.270818)
		(end 116.720112 -100.281486)
		(width 0.0889)
		(layer "In4.Cu")
		(net "M_M_DQS_DP<5>")
	)
	(segment
		(start 117.869462 -112.624362)
		(end 127.594868 -122.349768)
		(width 0.14224)
		(layer "In4.Cu")
		(net "M_M_DQS_DP<5>")
	)
	(segment
		(start 129.469896 -124.341128)
		(end 129.469896 -149.360636)
		(width 0.14224)
		(layer "In4.Cu")
		(net "M_M_DQS_DP<5>")
	)
	(segment
		(start 129.32537 -122.466354)
		(end 129.32537 -122.868944)
		(width 0.14224)
		(layer "In4.Cu")
		(net "M_M_DQS_DP<5>")
	)
	(arc
		(start 116.720112 -97.70999)
		(mid 116.799243 -98.005392)
		(end 116.720112 -98.300794)
		(width 0.0889)
		(layer "In4.Cu")
		(net "M_M_DQS_DP<5>")
	)
	(arc
		(start 116.720112 -96.71939)
		(mid 116.799243 -97.014792)
		(end 116.720112 -97.310194)
		(width 0.0889)
		(layer "In4.Cu")
		(net "M_M_DQS_DP<5>")
	)
	(arc
		(start 116.555012 -95.824294)
		(mid 116.600725 -95.946031)
		(end 116.60505 -96.076008)
		(width 0.0889)
		(layer "In4.Cu")
		(net "M_M_DQS_DP<5>")
	)
	(arc
		(start 116.720112 -101.671882)
		(mid 116.799301 -101.958497)
		(end 116.729002 -102.247446)
		(width 0.0889)
		(layer "In4.Cu")
		(net "M_M_DQS_DP<5>")
	)
	(arc
		(start 116.713254 -102.274878)
		(mid 116.666578 -102.469579)
		(end 116.720112 -102.662482)
		(width 0.0889)
		(layer "In4.Cu")
		(net "M_M_DQS_DP<5>")
	)
	(arc
		(start 116.60505 -96.076008)
		(mid 116.612748 -96.406609)
		(end 116.720112 -96.71939)
		(width 0.0889)
		(layer "In4.Cu")
		(net "M_M_DQS_DP<5>")
	)
	(arc
		(start 116.713254 -100.293678)
		(mid 116.666578 -100.488379)
		(end 116.720112 -100.681282)
		(width 0.0889)
		(layer "In4.Cu")
		(net "M_M_DQS_DP<5>")
	)
	(arc
		(start 116.720112 -97.310194)
		(mid 116.666613 -97.510092)
		(end 116.720112 -97.70999)
		(width 0.0889)
		(layer "In4.Cu")
		(net "M_M_DQS_DP<5>")
	)
	(arc
		(start 116.713254 -101.284278)
		(mid 116.666578 -101.478979)
		(end 116.720112 -101.671882)
		(width 0.0889)
		(layer "In4.Cu")
		(net "M_M_DQS_DP<5>")
	)
	(arc
		(start 116.689378 -99.62388)
		(mid 116.703174 -99.658128)
		(end 116.720112 -99.690936)
		(width 0.0889)
		(layer "In4.Cu")
		(net "M_M_DQS_DP<5>")
	)
	(arc
		(start 116.720112 -100.681282)
		(mid 116.799301 -100.967897)
		(end 116.729002 -101.256846)
		(width 0.0889)
		(layer "In4.Cu")
		(net "M_M_DQS_DP<5>")
	)
	(arc
		(start 116.720112 -98.70059)
		(mid 116.799243 -98.995992)
		(end 116.720112 -99.291394)
		(width 0.0889)
		(layer "In4.Cu")
		(net "M_M_DQS_DP<5>")
	)
	(arc
		(start 116.720112 -99.690936)
		(mid 116.799334 -99.980054)
		(end 116.726462 -100.270818)
		(width 0.0889)
		(layer "In4.Cu")
		(net "M_M_DQS_DP<5>")
	)
	(arc
		(start 117.084602 -104.84358)
		(mid 117.583123 -105.146464)
		(end 117.578632 -105.729786)
		(width 0.0889)
		(layer "In4.Cu")
		(net "M_M_DQS_DP<5>")
	)
	(arc
		(start 116.720112 -99.291394)
		(mid 116.668525 -99.454293)
		(end 116.689378 -99.62388)
		(width 0.0889)
		(layer "In4.Cu")
		(net "M_M_DQS_DP<5>")
	)
	(arc
		(start 116.729002 -103.238046)
		(mid 116.721318 -103.251871)
		(end 116.713254 -103.265478)
		(width 0.0889)
		(layer "In4.Cu")
		(net "M_M_DQS_DP<5>")
	)
	(arc
		(start 116.720112 -98.300794)
		(mid 116.666613 -98.500692)
		(end 116.720112 -98.70059)
		(width 0.0889)
		(layer "In4.Cu")
		(net "M_M_DQS_DP<5>")
	)
	(arc
		(start 116.713254 -103.265478)
		(mid 116.666578 -103.460179)
		(end 116.720112 -103.653082)
		(width 0.0889)
		(layer "In4.Cu")
		(net "M_M_DQS_DP<5>")
	)
	(arc
		(start 116.713254 -104.256078)
		(mid 116.720117 -104.643391)
		(end 117.051836 -104.84358)
		(width 0.0889)
		(layer "In4.Cu")
		(net "M_M_DQS_DP<5>")
	)
	(arc
		(start 116.720112 -103.653082)
		(mid 116.799301 -103.939697)
		(end 116.729002 -104.228646)
		(width 0.0889)
		(layer "In4.Cu")
		(net "M_M_DQS_DP<5>")
	)
	(arc
		(start 116.720112 -102.662482)
		(mid 116.799301 -102.949097)
		(end 116.729002 -103.238046)
		(width 0.0889)
		(layer "In4.Cu")
		(net "M_M_DQS_DP<5>")
	)
	(arc
		(start 116.208302 -95.033084)
		(mid 116.359986 -95.438185)
		(end 116.555012 -95.824294)
		(width 0.0889)
		(layer "In4.Cu")
		(net "M_M_DQS_DP<5>")
	)
	(arc
		(start 117.578632 -105.729786)
		(mid 117.525194 -105.922691)
		(end 117.571774 -106.11739)
		(width 0.0889)
		(layer "In4.Cu")
		(net "M_M_DQS_DP<5>")
	)
	(segment
		(start 129.147824 -153.3144)
		(end 129.147824 -153.753312)
		(width 0.14224)
		(layer "In11.Cu")
		(net "M_M_DQS_DP<5>")
	)
	(segment
		(start 129.147824 -153.753312)
		(end 128.687576 -154.21356)
		(width 0.14224)
		(layer "In11.Cu")
		(net "M_M_DQS_DP<5>")
	)
	(segment
		(start 128.48336 -151.257)
		(end 128.312926 -151.427434)
		(width 0.14224)
		(layer "In11.Cu")
		(net "M_M_DQS_DP<5>")
	)
	(segment
		(start 128.868424 -151.257)
		(end 128.48336 -151.257)
		(width 0.14224)
		(layer "In11.Cu")
		(net "M_M_DQS_DP<5>")
	)
	(segment
		(start 128.687576 -150.142956)
		(end 129.122424 -150.577804)
		(width 0.14224)
		(layer "In11.Cu")
		(net "M_M_DQS_DP<5>")
	)
	(segment
		(start 128.50876 -153.0604)
		(end 128.893824 -153.0604)
		(width 0.14224)
		(layer "In11.Cu")
		(net "M_M_DQS_DP<5>")
	)
	(segment
		(start 128.893824 -153.0604)
		(end 129.147824 -153.3144)
		(width 0.14224)
		(layer "In11.Cu")
		(net "M_M_DQS_DP<5>")
	)
	(segment
		(start 128.312926 -152.864566)
		(end 128.50876 -153.0604)
		(width 0.14224)
		(layer "In11.Cu")
		(net "M_M_DQS_DP<5>")
	)
	(segment
		(start 128.312926 -151.751792)
		(end 128.427734 -151.8666)
		(width 0.14224)
		(layer "In11.Cu")
		(net "M_M_DQS_DP<5>")
	)
	(segment
		(start 128.512824 -151.8666)
		(end 128.690624 -152.0444)
		(width 0.14224)
		(layer "In11.Cu")
		(net "M_M_DQS_DP<5>")
	)
	(segment
		(start 128.510284 -152.501092)
		(end 128.450086 -152.501092)
		(width 0.14224)
		(layer "In11.Cu")
		(net "M_M_DQS_DP<5>")
	)
	(segment
		(start 128.690624 -152.320752)
		(end 128.510284 -152.501092)
		(width 0.14224)
		(layer "In11.Cu")
		(net "M_M_DQS_DP<5>")
	)
	(segment
		(start 128.312926 -151.427434)
		(end 128.312926 -151.751792)
		(width 0.14224)
		(layer "In11.Cu")
		(net "M_M_DQS_DP<5>")
	)
	(segment
		(start 128.690624 -152.0444)
		(end 128.690624 -152.320752)
		(width 0.14224)
		(layer "In11.Cu")
		(net "M_M_DQS_DP<5>")
	)
	(segment
		(start 128.427734 -151.8666)
		(end 128.512824 -151.8666)
		(width 0.14224)
		(layer "In11.Cu")
		(net "M_M_DQS_DP<5>")
	)
	(segment
		(start 129.122424 -151.003)
		(end 128.868424 -151.257)
		(width 0.14224)
		(layer "In11.Cu")
		(net "M_M_DQS_DP<5>")
	)
	(segment
		(start 128.312926 -152.638252)
		(end 128.312926 -152.864566)
		(width 0.14224)
		(layer "In11.Cu")
		(net "M_M_DQS_DP<5>")
	)
	(segment
		(start 128.450086 -152.501092)
		(end 128.312926 -152.638252)
		(width 0.14224)
		(layer "In11.Cu")
		(net "M_M_DQS_DP<5>")
	)
	(segment
		(start 129.122424 -150.577804)
		(end 129.122424 -151.003)
		(width 0.14224)
		(layer "In11.Cu")
		(net "M_M_DQS_DP<5>")
	)
	(segment
		(start 119.799354 -155.866846)
		(end 119.8372 -155.829)
		(width 0.1651)
		(layer "F.Cu")
		(net "M_M_DQS_DP<4>")
	)
	(segment
		(start 119.8372 -155.829)
		(end 119.8372 -154.4574)
		(width 0.1651)
		(layer "F.Cu")
		(net "M_M_DQS_DP<4>")
	)
	(segment
		(start 108.768896 -95.033084)
		(end 109.340396 -95.033084)
		(width 0.1651)
		(layer "F.Cu")
		(net "M_M_DQS_DP<4>")
	)
	(segment
		(start 119.8372 -154.4574)
		(end 119.59336 -154.21356)
		(width 0.1651)
		(layer "F.Cu")
		(net "M_M_DQS_DP<4>")
	)
	(segment
		(start 119.799354 -156.87294)
		(end 119.799354 -155.866846)
		(width 0.1651)
		(layer "F.Cu")
		(net "M_M_DQS_DP<4>")
	)
	(segment
		(start 119.59336 -154.21356)
		(end 119.337582 -154.21356)
		(width 0.1651)
		(layer "F.Cu")
		(net "M_M_DQS_DP<4>")
	)
	(via
		(at 119.337328 -150.142956)
		(size 0.508)
		(drill 0.254)
		(layers "F.Cu" "B.Cu")
		(net "M_M_DQS_DP<4>")
	)
	(via
		(at 109.340396 -95.033084)
		(size 0.508)
		(drill 0.254)
		(layers "F.Cu" "B.Cu")
		(net "M_M_DQS_DP<4>")
	)
	(via
		(at 119.337582 -154.21356)
		(size 0.508)
		(drill 0.254)
		(layers "F.Cu" "B.Cu")
		(net "M_M_DQS_DP<4>")
	)
	(segment
		(start 119.799354 -147.478496)
		(end 119.799354 -148.628354)
		(width 0.1651)
		(layer "B.Cu")
		(net "M_M_DQS_DP<4>")
	)
	(segment
		(start 119.8372 -149.8854)
		(end 119.579644 -150.142956)
		(width 0.1651)
		(layer "B.Cu")
		(net "M_M_DQS_DP<4>")
	)
	(segment
		(start 119.799354 -148.628354)
		(end 119.8372 -148.6662)
		(width 0.1651)
		(layer "B.Cu")
		(net "M_M_DQS_DP<4>")
	)
	(segment
		(start 119.8372 -148.6662)
		(end 119.8372 -149.8854)
		(width 0.1651)
		(layer "B.Cu")
		(net "M_M_DQS_DP<4>")
	)
	(segment
		(start 119.579644 -150.142956)
		(end 119.337328 -150.142956)
		(width 0.1651)
		(layer "B.Cu")
		(net "M_M_DQS_DP<4>")
	)
	(segment
		(start 118.962932 -151.751792)
		(end 119.07774 -151.8666)
		(width 0.14224)
		(layer "In11.Cu")
		(net "M_M_DQS_DP<4>")
	)
	(segment
		(start 108.993686 -97.214436)
		(end 109.000036 -97.225104)
		(width 0.0889)
		(layer "In11.Cu")
		(net "M_M_DQS_DP<4>")
	)
	(segment
		(start 110.827058 -104.771698)
		(end 110.827058 -104.793796)
		(width 0.0889)
		(layer "In11.Cu")
		(net "M_M_DQS_DP<4>")
	)
	(segment
		(start 109.32922 -99.395788)
		(end 109.361986 -99.395788)
		(width 0.0889)
		(layer "In11.Cu")
		(net "M_M_DQS_DP<4>")
	)
	(segment
		(start 117.741954 -122.595386)
		(end 118.14937 -123.002802)
		(width 0.14224)
		(layer "In11.Cu")
		(net "M_M_DQS_DP<4>")
	)
	(segment
		(start 120.119902 -149.360636)
		(end 119.337582 -150.142956)
		(width 0.14224)
		(layer "In11.Cu")
		(net "M_M_DQS_DP<4>")
	)
	(segment
		(start 119.54383 -153.0604)
		(end 119.79783 -153.3144)
		(width 0.14224)
		(layer "In11.Cu")
		(net "M_M_DQS_DP<4>")
	)
	(segment
		(start 117.299486 -122.595386)
		(end 117.741954 -122.595386)
		(width 0.14224)
		(layer "In11.Cu")
		(net "M_M_DQS_DP<4>")
	)
	(segment
		(start 118.962932 -152.638252)
		(end 118.962932 -152.864566)
		(width 0.14224)
		(layer "In11.Cu")
		(net "M_M_DQS_DP<4>")
	)
	(segment
		(start 119.16283 -151.8666)
		(end 119.34063 -152.0444)
		(width 0.14224)
		(layer "In11.Cu")
		(net "M_M_DQS_DP<4>")
	)
	(segment
		(start 118.962932 -152.864566)
		(end 119.158766 -153.0604)
		(width 0.14224)
		(layer "In11.Cu")
		(net "M_M_DQS_DP<4>")
	)
	(segment
		(start 118.14937 -123.44527)
		(end 117.865652 -123.728988)
		(width 0.14224)
		(layer "In11.Cu")
		(net "M_M_DQS_DP<4>")
	)
	(segment
		(start 119.747538 -124.60097)
		(end 119.747538 -129.12217)
		(width 0.14224)
		(layer "In11.Cu")
		(net "M_M_DQS_DP<4>")
	)
	(segment
		(start 116.830094 -121.683526)
		(end 116.830094 -122.125994)
		(width 0.14224)
		(layer "In11.Cu")
		(net "M_M_DQS_DP<4>")
	)
	(segment
		(start 117.043962 -122.85091)
		(end 117.299486 -122.595386)
		(width 0.14224)
		(layer "In11.Cu")
		(net "M_M_DQS_DP<4>")
	)
	(segment
		(start 119.337328 -150.142956)
		(end 119.77243 -150.578058)
		(width 0.14224)
		(layer "In11.Cu")
		(net "M_M_DQS_DP<4>")
	)
	(segment
		(start 120.119902 -129.494534)
		(end 120.119902 -149.360636)
		(width 0.14224)
		(layer "In11.Cu")
		(net "M_M_DQS_DP<4>")
	)
	(segment
		(start 119.747538 -129.12217)
		(end 120.119902 -129.494534)
		(width 0.14224)
		(layer "In11.Cu")
		(net "M_M_DQS_DP<4>")
	)
	(segment
		(start 119.51843 -151.257)
		(end 119.133366 -151.257)
		(width 0.14224)
		(layer "In11.Cu")
		(net "M_M_DQS_DP<4>")
	)
	(segment
		(start 119.79783 -153.3144)
		(end 119.79783 -153.753312)
		(width 0.14224)
		(layer "In11.Cu")
		(net "M_M_DQS_DP<4>")
	)
	(segment
		(start 119.34063 -152.0444)
		(end 119.34063 -152.320752)
		(width 0.14224)
		(layer "In11.Cu")
		(net "M_M_DQS_DP<4>")
	)
	(segment
		(start 109.340396 -95.033084)
		(end 109.340396 -94.69501)
		(width 0.0889)
		(layer "In11.Cu")
		(net "M_M_DQS_DP<4>")
	)
	(segment
		(start 118.962932 -151.427434)
		(end 118.962932 -151.751792)
		(width 0.14224)
		(layer "In11.Cu")
		(net "M_M_DQS_DP<4>")
	)
	(segment
		(start 119.77243 -151.003)
		(end 119.600472 -151.174704)
		(width 0.14224)
		(layer "In11.Cu")
		(net "M_M_DQS_DP<4>")
	)
	(segment
		(start 110.787688 -100.745798)
		(end 110.787688 -104.732328)
		(width 0.0889)
		(layer "In11.Cu")
		(net "M_M_DQS_DP<4>")
	)
	(segment
		(start 108.993686 -98.205036)
		(end 109.000036 -98.215704)
		(width 0.0889)
		(layer "In11.Cu")
		(net "M_M_DQS_DP<4>")
	)
	(segment
		(start 119.34063 -152.320752)
		(end 119.16029 -152.501092)
		(width 0.14224)
		(layer "In11.Cu")
		(net "M_M_DQS_DP<4>")
	)
	(segment
		(start 109.852206 -99.690936)
		(end 110.015274 -99.973384)
		(width 0.0889)
		(layer "In11.Cu")
		(net "M_M_DQS_DP<4>")
	)
	(segment
		(start 110.827058 -104.793796)
		(end 110.827058 -115.68049)
		(width 0.14224)
		(layer "In11.Cu")
		(net "M_M_DQS_DP<4>")
	)
	(segment
		(start 118.116604 -124.187966)
		(end 118.345458 -124.187966)
		(width 0.14224)
		(layer "In11.Cu")
		(net "M_M_DQS_DP<4>")
	)
	(segment
		(start 110.787688 -104.732328)
		(end 110.827058 -104.771698)
		(width 0.0889)
		(layer "In11.Cu")
		(net "M_M_DQS_DP<4>")
	)
	(segment
		(start 119.600472 -151.174704)
		(end 119.51843 -151.257)
		(width 0.14224)
		(layer "In11.Cu")
		(net "M_M_DQS_DP<4>")
	)
	(segment
		(start 119.337582 -150.142956)
		(end 119.337328 -150.142956)
		(width 0.14224)
		(layer "In11.Cu")
		(net "M_M_DQS_DP<4>")
	)
	(segment
		(start 110.827058 -115.68049)
		(end 116.830094 -121.683526)
		(width 0.14224)
		(layer "In11.Cu")
		(net "M_M_DQS_DP<4>")
	)
	(segment
		(start 118.345458 -124.187966)
		(end 118.618762 -123.914662)
		(width 0.14224)
		(layer "In11.Cu")
		(net "M_M_DQS_DP<4>")
	)
	(segment
		(start 108.98886 -98.1964)
		(end 108.993686 -98.205036)
		(width 0.0889)
		(layer "In11.Cu")
		(net "M_M_DQS_DP<4>")
	)
	(segment
		(start 119.79783 -153.753312)
		(end 119.337582 -154.21356)
		(width 0.14224)
		(layer "In11.Cu")
		(net "M_M_DQS_DP<4>")
	)
	(segment
		(start 117.865652 -123.728988)
		(end 117.865652 -123.937014)
		(width 0.14224)
		(layer "In11.Cu")
		(net "M_M_DQS_DP<4>")
	)
	(segment
		(start 109.340396 -94.69501)
		(end 109.282484 -94.637098)
		(width 0.0889)
		(layer "In11.Cu")
		(net "M_M_DQS_DP<4>")
	)
	(segment
		(start 119.133366 -151.257)
		(end 118.962932 -151.427434)
		(width 0.14224)
		(layer "In11.Cu")
		(net "M_M_DQS_DP<4>")
	)
	(segment
		(start 119.100092 -152.501092)
		(end 118.962932 -152.638252)
		(width 0.14224)
		(layer "In11.Cu")
		(net "M_M_DQS_DP<4>")
	)
	(segment
		(start 110.015274 -99.973384)
		(end 110.787688 -100.745798)
		(width 0.0889)
		(layer "In11.Cu")
		(net "M_M_DQS_DP<4>")
	)
	(segment
		(start 118.14937 -123.002802)
		(end 118.14937 -123.44527)
		(width 0.14224)
		(layer "In11.Cu")
		(net "M_M_DQS_DP<4>")
	)
	(segment
		(start 119.06123 -123.914662)
		(end 119.747538 -124.60097)
		(width 0.14224)
		(layer "In11.Cu")
		(net "M_M_DQS_DP<4>")
	)
	(segment
		(start 118.618762 -123.914662)
		(end 119.06123 -123.914662)
		(width 0.14224)
		(layer "In11.Cu")
		(net "M_M_DQS_DP<4>")
	)
	(segment
		(start 119.158766 -153.0604)
		(end 119.54383 -153.0604)
		(width 0.14224)
		(layer "In11.Cu")
		(net "M_M_DQS_DP<4>")
	)
	(segment
		(start 119.16029 -152.501092)
		(end 119.100092 -152.501092)
		(width 0.14224)
		(layer "In11.Cu")
		(net "M_M_DQS_DP<4>")
	)
	(segment
		(start 116.825522 -122.85091)
		(end 117.043962 -122.85091)
		(width 0.14224)
		(layer "In11.Cu")
		(net "M_M_DQS_DP<4>")
	)
	(segment
		(start 116.57457 -122.381518)
		(end 116.57457 -122.599958)
		(width 0.14224)
		(layer "In11.Cu")
		(net "M_M_DQS_DP<4>")
	)
	(segment
		(start 119.07774 -151.8666)
		(end 119.16283 -151.8666)
		(width 0.14224)
		(layer "In11.Cu")
		(net "M_M_DQS_DP<4>")
	)
	(segment
		(start 108.98886 -97.2058)
		(end 108.993686 -97.214436)
		(width 0.0889)
		(layer "In11.Cu")
		(net "M_M_DQS_DP<4>")
	)
	(segment
		(start 116.57457 -122.599958)
		(end 116.825522 -122.85091)
		(width 0.14224)
		(layer "In11.Cu")
		(net "M_M_DQS_DP<4>")
	)
	(segment
		(start 108.98886 -96.2152)
		(end 108.993686 -96.223836)
		(width 0.0889)
		(layer "In11.Cu")
		(net "M_M_DQS_DP<4>")
	)
	(segment
		(start 116.830094 -122.125994)
		(end 116.57457 -122.381518)
		(width 0.14224)
		(layer "In11.Cu")
		(net "M_M_DQS_DP<4>")
	)
	(segment
		(start 117.865652 -123.937014)
		(end 118.116604 -124.187966)
		(width 0.14224)
		(layer "In11.Cu")
		(net "M_M_DQS_DP<4>")
	)
	(segment
		(start 108.993686 -96.223836)
		(end 109.000036 -96.234504)
		(width 0.0889)
		(layer "In11.Cu")
		(net "M_M_DQS_DP<4>")
	)
	(segment
		(start 119.77243 -150.578058)
		(end 119.77243 -151.003)
		(width 0.14224)
		(layer "In11.Cu")
		(net "M_M_DQS_DP<4>")
	)
	(arc
		(start 109.282484 -94.637098)
		(mid 109.184618 -94.664449)
		(end 109.09681 -94.715584)
		(width 0.0889)
		(layer "In11.Cu")
		(net "M_M_DQS_DP<4>")
	)
	(arc
		(start 108.993686 -95.232982)
		(mid 109.072817 -95.528384)
		(end 108.993686 -95.823786)
		(width 0.0889)
		(layer "In11.Cu")
		(net "M_M_DQS_DP<4>")
	)
	(arc
		(start 109.09681 -94.715584)
		(mid 108.947936 -94.954881)
		(end 108.993686 -95.232982)
		(width 0.0889)
		(layer "In11.Cu")
		(net "M_M_DQS_DP<4>")
	)
	(arc
		(start 109.000036 -98.215704)
		(mid 109.072834 -98.506467)
		(end 108.993686 -98.795586)
		(width 0.0889)
		(layer "In11.Cu")
		(net "M_M_DQS_DP<4>")
	)
	(arc
		(start 109.000036 -96.234504)
		(mid 109.072834 -96.525267)
		(end 108.993686 -96.814386)
		(width 0.0889)
		(layer "In11.Cu")
		(net "M_M_DQS_DP<4>")
	)
	(arc
		(start 108.993686 -97.804986)
		(mid 108.940216 -98.000049)
		(end 108.98886 -98.1964)
		(width 0.0889)
		(layer "In11.Cu")
		(net "M_M_DQS_DP<4>")
	)
	(arc
		(start 109.361986 -99.395788)
		(mid 109.645203 -99.480069)
		(end 109.852206 -99.690936)
		(width 0.0889)
		(layer "In11.Cu")
		(net "M_M_DQS_DP<4>")
	)
	(arc
		(start 108.993686 -95.823786)
		(mid 108.940216 -96.018849)
		(end 108.98886 -96.2152)
		(width 0.0889)
		(layer "In11.Cu")
		(net "M_M_DQS_DP<4>")
	)
	(arc
		(start 108.993686 -98.795586)
		(mid 108.990938 -99.191053)
		(end 109.32922 -99.395788)
		(width 0.0889)
		(layer "In11.Cu")
		(net "M_M_DQS_DP<4>")
	)
	(arc
		(start 108.993686 -96.814386)
		(mid 108.940216 -97.009449)
		(end 108.98886 -97.2058)
		(width 0.0889)
		(layer "In11.Cu")
		(net "M_M_DQS_DP<4>")
	)
	(arc
		(start 109.000036 -97.225104)
		(mid 109.072834 -97.515867)
		(end 108.993686 -97.804986)
		(width 0.0889)
		(layer "In11.Cu")
		(net "M_M_DQS_DP<4>")
	)
	(segment
		(start 64.549528 -156.87294)
		(end 64.549528 -155.866846)
		(width 0.1651)
		(layer "F.Cu")
		(net "M_M_DQS_DP<3>")
	)
	(segment
		(start 64.587374 -155.829)
		(end 64.587374 -154.4574)
		(width 0.1651)
		(layer "F.Cu")
		(net "M_M_DQS_DP<3>")
	)
	(segment
		(start 64.549528 -155.866846)
		(end 64.587374 -155.829)
		(width 0.1651)
		(layer "F.Cu")
		(net "M_M_DQS_DP<3>")
	)
	(segment
		(start 85.777832 -86.794086)
		(end 85.206332 -86.794086)
		(width 0.1651)
		(layer "F.Cu")
		(net "M_M_DQS_DP<3>")
	)
	(segment
		(start 64.587374 -154.4574)
		(end 64.343534 -154.21356)
		(width 0.1651)
		(layer "F.Cu")
		(net "M_M_DQS_DP<3>")
	)
	(segment
		(start 64.343534 -154.21356)
		(end 64.087502 -154.21356)
		(width 0.1651)
		(layer "F.Cu")
		(net "M_M_DQS_DP<3>")
	)
	(via
		(at 64.087502 -150.142956)
		(size 0.508)
		(drill 0.254)
		(layers "F.Cu" "B.Cu")
		(net "M_M_DQS_DP<3>")
	)
	(via
		(at 64.087502 -154.21356)
		(size 0.508)
		(drill 0.254)
		(layers "F.Cu" "B.Cu")
		(net "M_M_DQS_DP<3>")
	)
	(via
		(at 85.206332 -86.794086)
		(size 0.508)
		(drill 0.254)
		(layers "F.Cu" "B.Cu")
		(net "M_M_DQS_DP<3>")
	)
	(segment
		(start 64.587374 -148.6662)
		(end 64.587374 -149.8854)
		(width 0.1651)
		(layer "B.Cu")
		(net "M_M_DQS_DP<3>")
	)
	(segment
		(start 64.587374 -149.8854)
		(end 64.329818 -150.142956)
		(width 0.1651)
		(layer "B.Cu")
		(net "M_M_DQS_DP<3>")
	)
	(segment
		(start 64.329818 -150.142956)
		(end 64.087502 -150.142956)
		(width 0.1651)
		(layer "B.Cu")
		(net "M_M_DQS_DP<3>")
	)
	(segment
		(start 64.549528 -147.478496)
		(end 64.549528 -148.628354)
		(width 0.1651)
		(layer "B.Cu")
		(net "M_M_DQS_DP<3>")
	)
	(segment
		(start 64.549528 -148.628354)
		(end 64.587374 -148.6662)
		(width 0.1651)
		(layer "B.Cu")
		(net "M_M_DQS_DP<3>")
	)
	(segment
		(start 63.908686 -153.0604)
		(end 64.29375 -153.0604)
		(width 0.14224)
		(layer "In11.Cu")
		(net "M_M_DQS_DP<3>")
	)
	(segment
		(start 64.09055 -152.320752)
		(end 63.91021 -152.501092)
		(width 0.14224)
		(layer "In11.Cu")
		(net "M_M_DQS_DP<3>")
	)
	(segment
		(start 77.539088 -114.729514)
		(end 75.611736 -116.656866)
		(width 0.14224)
		(layer "In11.Cu")
		(net "M_M_DQS_DP<3>")
	)
	(segment
		(start 64.869822 -124.136912)
		(end 64.869822 -149.36089)
		(width 0.14224)
		(layer "In11.Cu")
		(net "M_M_DQS_DP<3>")
	)
	(segment
		(start 85.713316 -90.452702)
		(end 85.718142 -90.461338)
		(width 0.0889)
		(layer "In11.Cu")
		(net "M_M_DQS_DP<3>")
	)
	(segment
		(start 85.219286 -93.32849)
		(end 85.195156 -93.32849)
		(width 0.0889)
		(layer "In11.Cu")
		(net "M_M_DQS_DP<3>")
	)
	(segment
		(start 64.54775 -153.3144)
		(end 64.54775 -153.753312)
		(width 0.14224)
		(layer "In11.Cu")
		(net "M_M_DQS_DP<3>")
	)
	(segment
		(start 63.850012 -152.501092)
		(end 63.712852 -152.638252)
		(width 0.14224)
		(layer "In11.Cu")
		(net "M_M_DQS_DP<3>")
	)
	(segment
		(start 74.136758 -119.264684)
		(end 73.673462 -119.72798)
		(width 0.14224)
		(layer "In11.Cu")
		(net "M_M_DQS_DP<3>")
	)
	(segment
		(start 63.712852 -151.427434)
		(end 63.712852 -151.751792)
		(width 0.14224)
		(layer "In11.Cu")
		(net "M_M_DQS_DP<3>")
	)
	(segment
		(start 75.611736 -116.968778)
		(end 75.753976 -117.111018)
		(width 0.14224)
		(layer "In11.Cu")
		(net "M_M_DQS_DP<3>")
	)
	(segment
		(start 75.611736 -116.656866)
		(end 75.611736 -116.968778)
		(width 0.14224)
		(layer "In11.Cu")
		(net "M_M_DQS_DP<3>")
	)
	(segment
		(start 67.498214 -121.50852)
		(end 64.869822 -124.136912)
		(width 0.14224)
		(layer "In11.Cu")
		(net "M_M_DQS_DP<3>")
	)
	(segment
		(start 63.91021 -152.501092)
		(end 63.850012 -152.501092)
		(width 0.14224)
		(layer "In11.Cu")
		(net "M_M_DQS_DP<3>")
	)
	(segment
		(start 81.39049 -103.650542)
		(end 81.39049 -103.67264)
		(width 0.0889)
		(layer "In11.Cu")
		(net "M_M_DQS_DP<3>")
	)
	(segment
		(start 64.087756 -150.142956)
		(end 64.087502 -150.142956)
		(width 0.14224)
		(layer "In11.Cu")
		(net "M_M_DQS_DP<3>")
	)
	(segment
		(start 73.673462 -119.72798)
		(end 73.053194 -119.72798)
		(width 0.14224)
		(layer "In11.Cu")
		(net "M_M_DQS_DP<3>")
	)
	(segment
		(start 85.713316 -91.443302)
		(end 85.718142 -91.451938)
		(width 0.0889)
		(layer "In11.Cu")
		(net "M_M_DQS_DP<3>")
	)
	(segment
		(start 63.91275 -151.8666)
		(end 64.09055 -152.0444)
		(width 0.14224)
		(layer "In11.Cu")
		(net "M_M_DQS_DP<3>")
	)
	(segment
		(start 84.78393 -96.631506)
		(end 83.806792 -97.608644)
		(width 0.0889)
		(layer "In11.Cu")
		(net "M_M_DQS_DP<3>")
	)
	(segment
		(start 64.52235 -151.003)
		(end 64.26835 -151.257)
		(width 0.14224)
		(layer "In11.Cu")
		(net "M_M_DQS_DP<3>")
	)
	(segment
		(start 74.754232 -118.110762)
		(end 74.611992 -117.968522)
		(width 0.14224)
		(layer "In11.Cu")
		(net "M_M_DQS_DP<3>")
	)
	(segment
		(start 64.087502 -150.142956)
		(end 64.52235 -150.577804)
		(width 0.14224)
		(layer "In11.Cu")
		(net "M_M_DQS_DP<3>")
	)
	(segment
		(start 81.39049 -105.417366)
		(end 77.539088 -109.268768)
		(width 0.14224)
		(layer "In11.Cu")
		(net "M_M_DQS_DP<3>")
	)
	(segment
		(start 71.750936 -121.50852)
		(end 67.498214 -121.50852)
		(width 0.14224)
		(layer "In11.Cu")
		(net "M_M_DQS_DP<3>")
	)
	(segment
		(start 72.3773 -120.403874)
		(end 72.3773 -120.882156)
		(width 0.14224)
		(layer "In11.Cu")
		(net "M_M_DQS_DP<3>")
	)
	(segment
		(start 81.35112 -102.659942)
		(end 81.35112 -103.611172)
		(width 0.0889)
		(layer "In11.Cu")
		(net "M_M_DQS_DP<3>")
	)
	(segment
		(start 81.35112 -103.611172)
		(end 81.39049 -103.650542)
		(width 0.0889)
		(layer "In11.Cu")
		(net "M_M_DQS_DP<3>")
	)
	(segment
		(start 74.136758 -118.728236)
		(end 74.136758 -119.264684)
		(width 0.14224)
		(layer "In11.Cu")
		(net "M_M_DQS_DP<3>")
	)
	(segment
		(start 85.718142 -89.470738)
		(end 85.724492 -89.481406)
		(width 0.0889)
		(layer "In11.Cu")
		(net "M_M_DQS_DP<3>")
	)
	(segment
		(start 84.859622 -94.518988)
		(end 84.854796 -94.527624)
		(width 0.0889)
		(layer "In11.Cu")
		(net "M_M_DQS_DP<3>")
	)
	(segment
		(start 74.30008 -117.968522)
		(end 73.994518 -118.274084)
		(width 0.14224)
		(layer "In11.Cu")
		(net "M_M_DQS_DP<3>")
	)
	(segment
		(start 64.54775 -153.753312)
		(end 64.087502 -154.21356)
		(width 0.14224)
		(layer "In11.Cu")
		(net "M_M_DQS_DP<3>")
	)
	(segment
		(start 74.611992 -117.968522)
		(end 74.30008 -117.968522)
		(width 0.14224)
		(layer "In11.Cu")
		(net "M_M_DQS_DP<3>")
	)
	(segment
		(start 75.753976 -117.111018)
		(end 75.753976 -117.647466)
		(width 0.14224)
		(layer "In11.Cu")
		(net "M_M_DQS_DP<3>")
	)
	(segment
		(start 63.712852 -151.751792)
		(end 63.82766 -151.8666)
		(width 0.14224)
		(layer "In11.Cu")
		(net "M_M_DQS_DP<3>")
	)
	(segment
		(start 84.864702 -96.491044)
		(end 84.78393 -96.631506)
		(width 0.0889)
		(layer "In11.Cu")
		(net "M_M_DQS_DP<3>")
	)
	(segment
		(start 83.806792 -97.608644)
		(end 83.806792 -98.257614)
		(width 0.0889)
		(layer "In11.Cu")
		(net "M_M_DQS_DP<3>")
	)
	(segment
		(start 63.712852 -152.864566)
		(end 63.908686 -153.0604)
		(width 0.14224)
		(layer "In11.Cu")
		(net "M_M_DQS_DP<3>")
	)
	(segment
		(start 75.753976 -117.647466)
		(end 75.29068 -118.110762)
		(width 0.14224)
		(layer "In11.Cu")
		(net "M_M_DQS_DP<3>")
	)
	(segment
		(start 63.883286 -151.257)
		(end 63.712852 -151.427434)
		(width 0.14224)
		(layer "In11.Cu")
		(net "M_M_DQS_DP<3>")
	)
	(segment
		(start 64.26835 -151.257)
		(end 63.883286 -151.257)
		(width 0.14224)
		(layer "In11.Cu")
		(net "M_M_DQS_DP<3>")
	)
	(segment
		(start 81.063592 -101.000814)
		(end 81.063592 -102.372414)
		(width 0.0889)
		(layer "In11.Cu")
		(net "M_M_DQS_DP<3>")
	)
	(segment
		(start 83.806792 -98.257614)
		(end 81.063592 -101.000814)
		(width 0.0889)
		(layer "In11.Cu")
		(net "M_M_DQS_DP<3>")
	)
	(segment
		(start 64.52235 -150.577804)
		(end 64.52235 -151.003)
		(width 0.14224)
		(layer "In11.Cu")
		(net "M_M_DQS_DP<3>")
	)
	(segment
		(start 75.29068 -118.110762)
		(end 74.754232 -118.110762)
		(width 0.14224)
		(layer "In11.Cu")
		(net "M_M_DQS_DP<3>")
	)
	(segment
		(start 73.994518 -118.274084)
		(end 73.994518 -118.585996)
		(width 0.14224)
		(layer "In11.Cu")
		(net "M_M_DQS_DP<3>")
	)
	(segment
		(start 64.869822 -149.36089)
		(end 64.087756 -150.142956)
		(width 0.14224)
		(layer "In11.Cu")
		(net "M_M_DQS_DP<3>")
	)
	(segment
		(start 84.859622 -95.509588)
		(end 84.854796 -95.518224)
		(width 0.0889)
		(layer "In11.Cu")
		(net "M_M_DQS_DP<3>")
	)
	(segment
		(start 81.39049 -103.67264)
		(end 81.39049 -105.417366)
		(width 0.14224)
		(layer "In11.Cu")
		(net "M_M_DQS_DP<3>")
	)
	(segment
		(start 85.713316 -89.462102)
		(end 85.718142 -89.470738)
		(width 0.0889)
		(layer "In11.Cu")
		(net "M_M_DQS_DP<3>")
	)
	(segment
		(start 73.053194 -119.72798)
		(end 72.3773 -120.403874)
		(width 0.14224)
		(layer "In11.Cu")
		(net "M_M_DQS_DP<3>")
	)
	(segment
		(start 64.29375 -153.0604)
		(end 64.54775 -153.3144)
		(width 0.14224)
		(layer "In11.Cu")
		(net "M_M_DQS_DP<3>")
	)
	(segment
		(start 85.718142 -92.442538)
		(end 85.724492 -92.453206)
		(width 0.0889)
		(layer "In11.Cu")
		(net "M_M_DQS_DP<3>")
	)
	(segment
		(start 85.718142 -91.451938)
		(end 85.724492 -91.462606)
		(width 0.0889)
		(layer "In11.Cu")
		(net "M_M_DQS_DP<3>")
	)
	(segment
		(start 84.859622 -93.928438)
		(end 84.865972 -93.939106)
		(width 0.0889)
		(layer "In11.Cu")
		(net "M_M_DQS_DP<3>")
	)
	(segment
		(start 84.865972 -95.49892)
		(end 84.859622 -95.509588)
		(width 0.0889)
		(layer "In11.Cu")
		(net "M_M_DQS_DP<3>")
	)
	(segment
		(start 77.539088 -109.268768)
		(end 77.539088 -114.729514)
		(width 0.14224)
		(layer "In11.Cu")
		(net "M_M_DQS_DP<3>")
	)
	(segment
		(start 85.718142 -88.480392)
		(end 85.724492 -88.490806)
		(width 0.0889)
		(layer "In11.Cu")
		(net "M_M_DQS_DP<3>")
	)
	(segment
		(start 73.994518 -118.585996)
		(end 74.136758 -118.728236)
		(width 0.14224)
		(layer "In11.Cu")
		(net "M_M_DQS_DP<3>")
	)
	(segment
		(start 64.09055 -152.0444)
		(end 64.09055 -152.320752)
		(width 0.14224)
		(layer "In11.Cu")
		(net "M_M_DQS_DP<3>")
	)
	(segment
		(start 84.865718 -96.48952)
		(end 84.864702 -96.491044)
		(width 0.0889)
		(layer "In11.Cu")
		(net "M_M_DQS_DP<3>")
	)
	(segment
		(start 81.063592 -102.372414)
		(end 81.35112 -102.659942)
		(width 0.0889)
		(layer "In11.Cu")
		(net "M_M_DQS_DP<3>")
	)
	(segment
		(start 85.713316 -92.433902)
		(end 85.718142 -92.442538)
		(width 0.0889)
		(layer "In11.Cu")
		(net "M_M_DQS_DP<3>")
	)
	(segment
		(start 72.3773 -120.882156)
		(end 71.750936 -121.50852)
		(width 0.14224)
		(layer "In11.Cu")
		(net "M_M_DQS_DP<3>")
	)
	(segment
		(start 85.718142 -90.461338)
		(end 85.724492 -90.472006)
		(width 0.0889)
		(layer "In11.Cu")
		(net "M_M_DQS_DP<3>")
	)
	(segment
		(start 63.712852 -152.638252)
		(end 63.712852 -152.864566)
		(width 0.14224)
		(layer "In11.Cu")
		(net "M_M_DQS_DP<3>")
	)
	(segment
		(start 63.82766 -151.8666)
		(end 63.91275 -151.8666)
		(width 0.14224)
		(layer "In11.Cu")
		(net "M_M_DQS_DP<3>")
	)
	(arc
		(start 85.718142 -92.042488)
		(mid 85.664672 -92.237551)
		(end 85.713316 -92.433902)
		(width 0.0889)
		(layer "In11.Cu")
		(net "M_M_DQS_DP<3>")
	)
	(arc
		(start 85.718142 -89.070688)
		(mid 85.664672 -89.265751)
		(end 85.713316 -89.462102)
		(width 0.0889)
		(layer "In11.Cu")
		(net "M_M_DQS_DP<3>")
	)
	(arc
		(start 85.724492 -88.490806)
		(mid 85.79729 -88.781569)
		(end 85.718142 -89.070688)
		(width 0.0889)
		(layer "In11.Cu")
		(net "M_M_DQS_DP<3>")
	)
	(arc
		(start 84.859622 -94.919038)
		(mid 84.938844 -95.208156)
		(end 84.865972 -95.49892)
		(width 0.0889)
		(layer "In11.Cu")
		(net "M_M_DQS_DP<3>")
	)
	(arc
		(start 85.724492 -89.481406)
		(mid 85.79729 -89.772169)
		(end 85.718142 -90.061288)
		(width 0.0889)
		(layer "In11.Cu")
		(net "M_M_DQS_DP<3>")
	)
	(arc
		(start 85.724492 -90.472006)
		(mid 85.79729 -90.762769)
		(end 85.718142 -91.051888)
		(width 0.0889)
		(layer "In11.Cu")
		(net "M_M_DQS_DP<3>")
	)
	(arc
		(start 85.718142 -91.051888)
		(mid 85.664672 -91.246951)
		(end 85.713316 -91.443302)
		(width 0.0889)
		(layer "In11.Cu")
		(net "M_M_DQS_DP<3>")
	)
	(arc
		(start 84.865972 -93.939106)
		(mid 84.93877 -94.229869)
		(end 84.859622 -94.518988)
		(width 0.0889)
		(layer "In11.Cu")
		(net "M_M_DQS_DP<3>")
	)
	(arc
		(start 85.60308 -87.83701)
		(mid 85.610778 -88.167611)
		(end 85.718142 -88.480392)
		(width 0.0889)
		(layer "In11.Cu")
		(net "M_M_DQS_DP<3>")
	)
	(arc
		(start 85.206332 -86.794086)
		(mid 85.358016 -87.199187)
		(end 85.553042 -87.585296)
		(width 0.0889)
		(layer "In11.Cu")
		(net "M_M_DQS_DP<3>")
	)
	(arc
		(start 84.854796 -95.518224)
		(mid 84.806041 -95.714576)
		(end 84.859622 -95.909638)
		(width 0.0889)
		(layer "In11.Cu")
		(net "M_M_DQS_DP<3>")
	)
	(arc
		(start 84.854796 -94.527624)
		(mid 84.806041 -94.723976)
		(end 84.859622 -94.919038)
		(width 0.0889)
		(layer "In11.Cu")
		(net "M_M_DQS_DP<3>")
	)
	(arc
		(start 85.724492 -92.453206)
		(mid 85.718315 -93.033138)
		(end 85.219286 -93.32849)
		(width 0.0889)
		(layer "In11.Cu")
		(net "M_M_DQS_DP<3>")
	)
	(arc
		(start 85.553042 -87.585296)
		(mid 85.598755 -87.707033)
		(end 85.60308 -87.83701)
		(width 0.0889)
		(layer "In11.Cu")
		(net "M_M_DQS_DP<3>")
	)
	(arc
		(start 85.724492 -91.462606)
		(mid 85.79729 -91.753369)
		(end 85.718142 -92.042488)
		(width 0.0889)
		(layer "In11.Cu")
		(net "M_M_DQS_DP<3>")
	)
	(arc
		(start 85.195156 -93.32849)
		(mid 84.857041 -93.533192)
		(end 84.859622 -93.928438)
		(width 0.0889)
		(layer "In11.Cu")
		(net "M_M_DQS_DP<3>")
	)
	(arc
		(start 84.859622 -95.909638)
		(mid 84.93872 -96.198786)
		(end 84.865718 -96.48952)
		(width 0.0889)
		(layer "In11.Cu")
		(net "M_M_DQS_DP<3>")
	)
	(arc
		(start 85.718142 -90.061288)
		(mid 85.664672 -90.256351)
		(end 85.713316 -90.452702)
		(width 0.0889)
		(layer "In11.Cu")
		(net "M_M_DQS_DP<3>")
	)
	(segment
		(start 55.199534 -155.866846)
		(end 55.23738 -155.829)
		(width 0.1651)
		(layer "F.Cu")
		(net "M_M_DQS_DP<2>")
	)
	(segment
		(start 80.626712 -93.72854)
		(end 80.055212 -93.72854)
		(width 0.1651)
		(layer "F.Cu")
		(net "M_M_DQS_DP<2>")
	)
	(segment
		(start 55.23738 -155.829)
		(end 55.23738 -154.4574)
		(width 0.1651)
		(layer "F.Cu")
		(net "M_M_DQS_DP<2>")
	)
	(segment
		(start 55.199534 -156.87294)
		(end 55.199534 -155.866846)
		(width 0.1651)
		(layer "F.Cu")
		(net "M_M_DQS_DP<2>")
	)
	(segment
		(start 55.23738 -154.4574)
		(end 54.99354 -154.21356)
		(width 0.1651)
		(layer "F.Cu")
		(net "M_M_DQS_DP<2>")
	)
	(segment
		(start 54.99354 -154.21356)
		(end 54.737508 -154.21356)
		(width 0.1651)
		(layer "F.Cu")
		(net "M_M_DQS_DP<2>")
	)
	(via
		(at 54.737508 -150.142956)
		(size 0.508)
		(drill 0.254)
		(layers "F.Cu" "B.Cu")
		(net "M_M_DQS_DP<2>")
	)
	(via
		(at 54.737508 -154.21356)
		(size 0.508)
		(drill 0.254)
		(layers "F.Cu" "B.Cu")
		(net "M_M_DQS_DP<2>")
	)
	(via
		(at 80.055212 -93.72854)
		(size 0.508)
		(drill 0.254)
		(layers "F.Cu" "B.Cu")
		(net "M_M_DQS_DP<2>")
	)
	(segment
		(start 55.199534 -148.628354)
		(end 55.23738 -148.6662)
		(width 0.1651)
		(layer "B.Cu")
		(net "M_M_DQS_DP<2>")
	)
	(segment
		(start 55.23738 -148.6662)
		(end 55.23738 -149.8854)
		(width 0.1651)
		(layer "B.Cu")
		(net "M_M_DQS_DP<2>")
	)
	(segment
		(start 55.199534 -147.478496)
		(end 55.199534 -148.628354)
		(width 0.1651)
		(layer "B.Cu")
		(net "M_M_DQS_DP<2>")
	)
	(segment
		(start 54.979824 -150.142956)
		(end 54.737508 -150.142956)
		(width 0.1651)
		(layer "B.Cu")
		(net "M_M_DQS_DP<2>")
	)
	(segment
		(start 55.23738 -149.8854)
		(end 54.979824 -150.142956)
		(width 0.1651)
		(layer "B.Cu")
		(net "M_M_DQS_DP<2>")
	)
	(segment
		(start 55.197756 -153.3144)
		(end 55.197756 -153.753312)
		(width 0.14224)
		(layer "In11.Cu")
		(net "M_M_DQS_DP<2>")
	)
	(segment
		(start 54.943756 -153.0604)
		(end 55.197756 -153.3144)
		(width 0.14224)
		(layer "In11.Cu")
		(net "M_M_DQS_DP<2>")
	)
	(segment
		(start 55.172356 -151.003)
		(end 54.918356 -151.257)
		(width 0.14224)
		(layer "In11.Cu")
		(net "M_M_DQS_DP<2>")
	)
	(segment
		(start 66.38798 -110.818676)
		(end 66.38798 -111.595916)
		(width 0.14224)
		(layer "In11.Cu")
		(net "M_M_DQS_DP<2>")
	)
	(segment
		(start 58.30189 -119.520716)
		(end 57.641744 -120.180862)
		(width 0.14224)
		(layer "In11.Cu")
		(net "M_M_DQS_DP<2>")
	)
	(segment
		(start 66.729102 -110.477554)
		(end 66.38798 -110.818676)
		(width 0.14224)
		(layer "In11.Cu")
		(net "M_M_DQS_DP<2>")
	)
	(segment
		(start 71.988426 -99.95662)
		(end 71.982076 -99.967288)
		(width 0.0889)
		(layer "In11.Cu")
		(net "M_M_DQS_DP<2>")
	)
	(segment
		(start 65.111884 -112.094772)
		(end 64.770762 -112.435894)
		(width 0.14224)
		(layer "In11.Cu")
		(net "M_M_DQS_DP<2>")
	)
	(segment
		(start 68.53936 -108.860336)
		(end 68.005198 -109.394498)
		(width 0.14224)
		(layer "In11.Cu")
		(net "M_M_DQS_DP<2>")
	)
	(segment
		(start 69.314568 -105.625138)
		(end 69.314568 -108.247688)
		(width 0.14224)
		(layer "In11.Cu")
		(net "M_M_DQS_DP<2>")
	)
	(segment
		(start 71.976996 -101.349048)
		(end 72.064372 -101.500178)
		(width 0.0889)
		(layer "In11.Cu")
		(net "M_M_DQS_DP<2>")
	)
	(segment
		(start 55.172356 -150.577804)
		(end 55.172356 -151.003)
		(width 0.14224)
		(layer "In11.Cu")
		(net "M_M_DQS_DP<2>")
	)
	(segment
		(start 54.737762 -150.142956)
		(end 54.737508 -150.142956)
		(width 0.14224)
		(layer "In11.Cu")
		(net "M_M_DQS_DP<2>")
	)
	(segment
		(start 54.477666 -151.8666)
		(end 54.562756 -151.8666)
		(width 0.14224)
		(layer "In11.Cu")
		(net "M_M_DQS_DP<2>")
	)
	(segment
		(start 57.279032 -120.180862)
		(end 56.684672 -120.775222)
		(width 0.14224)
		(layer "In11.Cu")
		(net "M_M_DQS_DP<2>")
	)
	(segment
		(start 64.271906 -113.71199)
		(end 63.494666 -113.71199)
		(width 0.14224)
		(layer "In11.Cu")
		(net "M_M_DQS_DP<2>")
	)
	(segment
		(start 58.643012 -118.563644)
		(end 58.30189 -118.904766)
		(width 0.14224)
		(layer "In11.Cu")
		(net "M_M_DQS_DP<2>")
	)
	(segment
		(start 54.740556 -152.320752)
		(end 54.560216 -152.501092)
		(width 0.14224)
		(layer "In11.Cu")
		(net "M_M_DQS_DP<2>")
	)
	(segment
		(start 55.536084 -149.348444)
		(end 55.132732 -149.751796)
		(width 0.14224)
		(layer "In11.Cu")
		(net "M_M_DQS_DP<2>")
	)
	(segment
		(start 56.684672 -120.775222)
		(end 56.684672 -121.298462)
		(width 0.14224)
		(layer "In11.Cu")
		(net "M_M_DQS_DP<2>")
	)
	(segment
		(start 69.99351 -104.890824)
		(end 69.99351 -104.94645)
		(width 0.0889)
		(layer "In11.Cu")
		(net "M_M_DQS_DP<2>")
	)
	(segment
		(start 69.314568 -108.247688)
		(end 68.70192 -108.860336)
		(width 0.14224)
		(layer "In11.Cu")
		(net "M_M_DQS_DP<2>")
	)
	(segment
		(start 59.919108 -117.287548)
		(end 59.919108 -118.064788)
		(width 0.14224)
		(layer "In11.Cu")
		(net "M_M_DQS_DP<2>")
	)
	(segment
		(start 54.362858 -152.864566)
		(end 54.558692 -153.0604)
		(width 0.14224)
		(layer "In11.Cu")
		(net "M_M_DQS_DP<2>")
	)
	(segment
		(start 77.497686 -95.80499)
		(end 77.46492 -95.80499)
		(width 0.0889)
		(layer "In11.Cu")
		(net "M_M_DQS_DP<2>")
	)
	(segment
		(start 58.30189 -118.904766)
		(end 58.30189 -119.520716)
		(width 0.14224)
		(layer "In11.Cu")
		(net "M_M_DQS_DP<2>")
	)
	(segment
		(start 68.005198 -109.978698)
		(end 67.506342 -110.477554)
		(width 0.14224)
		(layer "In11.Cu")
		(net "M_M_DQS_DP<2>")
	)
	(segment
		(start 54.740556 -152.0444)
		(end 54.740556 -152.320752)
		(width 0.14224)
		(layer "In11.Cu")
		(net "M_M_DQS_DP<2>")
	)
	(segment
		(start 64.770762 -112.435894)
		(end 64.770762 -113.213134)
		(width 0.14224)
		(layer "In11.Cu")
		(net "M_M_DQS_DP<2>")
	)
	(segment
		(start 59.420252 -118.563644)
		(end 58.643012 -118.563644)
		(width 0.14224)
		(layer "In11.Cu")
		(net "M_M_DQS_DP<2>")
	)
	(segment
		(start 67.506342 -110.477554)
		(end 66.729102 -110.477554)
		(width 0.14224)
		(layer "In11.Cu")
		(net "M_M_DQS_DP<2>")
	)
	(segment
		(start 61.03747 -116.946426)
		(end 60.26023 -116.946426)
		(width 0.14224)
		(layer "In11.Cu")
		(net "M_M_DQS_DP<2>")
	)
	(segment
		(start 64.770762 -113.213134)
		(end 64.271906 -113.71199)
		(width 0.14224)
		(layer "In11.Cu")
		(net "M_M_DQS_DP<2>")
	)
	(segment
		(start 59.919108 -118.064788)
		(end 59.420252 -118.563644)
		(width 0.14224)
		(layer "In11.Cu")
		(net "M_M_DQS_DP<2>")
	)
	(segment
		(start 54.560216 -152.501092)
		(end 54.500018 -152.501092)
		(width 0.14224)
		(layer "In11.Cu")
		(net "M_M_DQS_DP<2>")
	)
	(segment
		(start 54.918356 -151.257)
		(end 54.533292 -151.257)
		(width 0.14224)
		(layer "In11.Cu")
		(net "M_M_DQS_DP<2>")
	)
	(segment
		(start 56.253888 -121.729246)
		(end 56.253888 -126.403608)
		(width 0.14224)
		(layer "In11.Cu")
		(net "M_M_DQS_DP<2>")
	)
	(segment
		(start 74.925936 -97.290636)
		(end 74.89317 -97.290636)
		(width 0.0889)
		(layer "In11.Cu")
		(net "M_M_DQS_DP<2>")
	)
	(segment
		(start 54.562756 -151.8666)
		(end 54.740556 -152.0444)
		(width 0.14224)
		(layer "In11.Cu")
		(net "M_M_DQS_DP<2>")
	)
	(segment
		(start 61.877448 -115.329208)
		(end 61.536326 -115.67033)
		(width 0.14224)
		(layer "In11.Cu")
		(net "M_M_DQS_DP<2>")
	)
	(segment
		(start 63.153544 -114.830352)
		(end 62.654688 -115.329208)
		(width 0.14224)
		(layer "In11.Cu")
		(net "M_M_DQS_DP<2>")
	)
	(segment
		(start 71.97725 -99.368102)
		(end 71.982076 -99.376738)
		(width 0.0889)
		(layer "In11.Cu")
		(net "M_M_DQS_DP<2>")
	)
	(segment
		(start 68.70192 -108.860336)
		(end 68.53936 -108.860336)
		(width 0.14224)
		(layer "In11.Cu")
		(net "M_M_DQS_DP<2>")
	)
	(segment
		(start 57.641744 -120.180862)
		(end 57.279032 -120.180862)
		(width 0.14224)
		(layer "In11.Cu")
		(net "M_M_DQS_DP<2>")
	)
	(segment
		(start 71.982076 -100.957888)
		(end 71.981822 -100.958142)
		(width 0.0889)
		(layer "In11.Cu")
		(net "M_M_DQS_DP<2>")
	)
	(segment
		(start 56.253888 -126.403608)
		(end 55.536084 -127.121412)
		(width 0.14224)
		(layer "In11.Cu")
		(net "M_M_DQS_DP<2>")
	)
	(segment
		(start 61.536326 -116.44757)
		(end 61.03747 -116.946426)
		(width 0.14224)
		(layer "In11.Cu")
		(net "M_M_DQS_DP<2>")
	)
	(segment
		(start 72.064372 -101.500178)
		(end 72.064372 -102.819962)
		(width 0.0889)
		(layer "In11.Cu")
		(net "M_M_DQS_DP<2>")
	)
	(segment
		(start 75.780646 -96.79559)
		(end 75.74788 -96.79559)
		(width 0.0889)
		(layer "In11.Cu")
		(net "M_M_DQS_DP<2>")
	)
	(segment
		(start 69.99351 -104.94645)
		(end 69.977762 -104.962198)
		(width 0.0889)
		(layer "In11.Cu")
		(net "M_M_DQS_DP<2>")
	)
	(segment
		(start 54.558692 -153.0604)
		(end 54.943756 -153.0604)
		(width 0.14224)
		(layer "In11.Cu")
		(net "M_M_DQS_DP<2>")
	)
	(segment
		(start 66.38798 -111.595916)
		(end 65.889124 -112.094772)
		(width 0.14224)
		(layer "In11.Cu")
		(net "M_M_DQS_DP<2>")
	)
	(segment
		(start 54.362858 -151.427434)
		(end 54.362858 -151.751792)
		(width 0.14224)
		(layer "In11.Cu")
		(net "M_M_DQS_DP<2>")
	)
	(segment
		(start 74.063606 -97.78619)
		(end 74.03084 -97.78619)
		(width 0.0889)
		(layer "In11.Cu")
		(net "M_M_DQS_DP<2>")
	)
	(segment
		(start 54.533292 -151.257)
		(end 54.362858 -151.427434)
		(width 0.14224)
		(layer "In11.Cu")
		(net "M_M_DQS_DP<2>")
	)
	(segment
		(start 55.132732 -149.751796)
		(end 55.128922 -149.751796)
		(width 0.14224)
		(layer "In11.Cu")
		(net "M_M_DQS_DP<2>")
	)
	(segment
		(start 68.005198 -109.394498)
		(end 68.005198 -109.978698)
		(width 0.14224)
		(layer "In11.Cu")
		(net "M_M_DQS_DP<2>")
	)
	(segment
		(start 72.346566 -98.77679)
		(end 72.3138 -98.77679)
		(width 0.0889)
		(layer "In11.Cu")
		(net "M_M_DQS_DP<2>")
	)
	(segment
		(start 79.042514 -94.680532)
		(end 78.849982 -95.014288)
		(width 0.0889)
		(layer "In11.Cu")
		(net "M_M_DQS_DP<2>")
	)
	(segment
		(start 78.359762 -95.309436)
		(end 78.338172 -95.309436)
		(width 0.0889)
		(layer "In11.Cu")
		(net "M_M_DQS_DP<2>")
	)
	(segment
		(start 65.889124 -112.094772)
		(end 65.111884 -112.094772)
		(width 0.14224)
		(layer "In11.Cu")
		(net "M_M_DQS_DP<2>")
	)
	(segment
		(start 79.34198 -94.59722)
		(end 79.252572 -94.63532)
		(width 0.0889)
		(layer "In11.Cu")
		(net "M_M_DQS_DP<2>")
	)
	(segment
		(start 63.153544 -114.053112)
		(end 63.153544 -114.830352)
		(width 0.14224)
		(layer "In11.Cu")
		(net "M_M_DQS_DP<2>")
	)
	(segment
		(start 76.642976 -96.300036)
		(end 76.61021 -96.300036)
		(width 0.0889)
		(layer "In11.Cu")
		(net "M_M_DQS_DP<2>")
	)
	(segment
		(start 54.500018 -152.501092)
		(end 54.362858 -152.638252)
		(width 0.14224)
		(layer "In11.Cu")
		(net "M_M_DQS_DP<2>")
	)
	(segment
		(start 61.536326 -115.67033)
		(end 61.536326 -116.44757)
		(width 0.14224)
		(layer "In11.Cu")
		(net "M_M_DQS_DP<2>")
	)
	(segment
		(start 77.995018 -95.503746)
		(end 77.991716 -95.509588)
		(width 0.0889)
		(layer "In11.Cu")
		(net "M_M_DQS_DP<2>")
	)
	(segment
		(start 60.26023 -116.946426)
		(end 59.919108 -117.287548)
		(width 0.14224)
		(layer "In11.Cu")
		(net "M_M_DQS_DP<2>")
	)
	(segment
		(start 55.536084 -127.121412)
		(end 55.536084 -149.348444)
		(width 0.14224)
		(layer "In11.Cu")
		(net "M_M_DQS_DP<2>")
	)
	(segment
		(start 63.494666 -113.71199)
		(end 63.153544 -114.053112)
		(width 0.14224)
		(layer "In11.Cu")
		(net "M_M_DQS_DP<2>")
	)
	(segment
		(start 72.064372 -102.819962)
		(end 69.99351 -104.890824)
		(width 0.0889)
		(layer "In11.Cu")
		(net "M_M_DQS_DP<2>")
	)
	(segment
		(start 73.208896 -98.281236)
		(end 73.17613 -98.281236)
		(width 0.0889)
		(layer "In11.Cu")
		(net "M_M_DQS_DP<2>")
	)
	(segment
		(start 55.128922 -149.751796)
		(end 54.737762 -150.142956)
		(width 0.14224)
		(layer "In11.Cu")
		(net "M_M_DQS_DP<2>")
	)
	(segment
		(start 56.684672 -121.298462)
		(end 56.253888 -121.729246)
		(width 0.14224)
		(layer "In11.Cu")
		(net "M_M_DQS_DP<2>")
	)
	(segment
		(start 62.654688 -115.329208)
		(end 61.877448 -115.329208)
		(width 0.14224)
		(layer "In11.Cu")
		(net "M_M_DQS_DP<2>")
	)
	(segment
		(start 54.737508 -150.142956)
		(end 55.172356 -150.577804)
		(width 0.14224)
		(layer "In11.Cu")
		(net "M_M_DQS_DP<2>")
	)
	(segment
		(start 54.362858 -152.638252)
		(end 54.362858 -152.864566)
		(width 0.14224)
		(layer "In11.Cu")
		(net "M_M_DQS_DP<2>")
	)
	(segment
		(start 54.362858 -151.751792)
		(end 54.477666 -151.8666)
		(width 0.14224)
		(layer "In11.Cu")
		(net "M_M_DQS_DP<2>")
	)
	(segment
		(start 55.197756 -153.753312)
		(end 54.737508 -154.21356)
		(width 0.14224)
		(layer "In11.Cu")
		(net "M_M_DQS_DP<2>")
	)
	(segment
		(start 79.252572 -94.63532)
		(end 79.042514 -94.680532)
		(width 0.0889)
		(layer "In11.Cu")
		(net "M_M_DQS_DP<2>")
	)
	(segment
		(start 69.977762 -104.962198)
		(end 69.314568 -105.625138)
		(width 0.14224)
		(layer "In11.Cu")
		(net "M_M_DQS_DP<2>")
	)
	(arc
		(start 74.89317 -97.290636)
		(mid 74.69932 -97.346986)
		(end 74.557636 -97.490788)
		(width 0.0889)
		(layer "In11.Cu")
		(net "M_M_DQS_DP<2>")
	)
	(arc
		(start 77.133196 -96.004888)
		(mid 76.926192 -96.215752)
		(end 76.642976 -96.300036)
		(width 0.0889)
		(layer "In11.Cu")
		(net "M_M_DQS_DP<2>")
	)
	(arc
		(start 71.981822 -100.958142)
		(mid 71.928513 -101.152951)
		(end 71.976996 -101.349048)
		(width 0.0889)
		(layer "In11.Cu")
		(net "M_M_DQS_DP<2>")
	)
	(arc
		(start 75.416156 -96.995488)
		(mid 75.209152 -97.206352)
		(end 74.925936 -97.290636)
		(width 0.0889)
		(layer "In11.Cu")
		(net "M_M_DQS_DP<2>")
	)
	(arc
		(start 78.338172 -95.309436)
		(mid 78.141011 -95.361395)
		(end 77.995018 -95.503746)
		(width 0.0889)
		(layer "In11.Cu")
		(net "M_M_DQS_DP<2>")
	)
	(arc
		(start 79.543402 -94.424246)
		(mid 79.457462 -94.527937)
		(end 79.34198 -94.59722)
		(width 0.0889)
		(layer "In11.Cu")
		(net "M_M_DQS_DP<2>")
	)
	(arc
		(start 75.74788 -96.79559)
		(mid 75.556238 -96.852756)
		(end 75.416156 -96.995488)
		(width 0.0889)
		(layer "In11.Cu")
		(net "M_M_DQS_DP<2>")
	)
	(arc
		(start 72.840596 -98.481388)
		(mid 72.631988 -98.69332)
		(end 72.346566 -98.77679)
		(width 0.0889)
		(layer "In11.Cu")
		(net "M_M_DQS_DP<2>")
	)
	(arc
		(start 71.982076 -100.367084)
		(mid 72.061207 -100.662486)
		(end 71.982076 -100.957888)
		(width 0.0889)
		(layer "In11.Cu")
		(net "M_M_DQS_DP<2>")
	)
	(arc
		(start 71.982076 -99.967288)
		(mid 71.928577 -100.167186)
		(end 71.982076 -100.367084)
		(width 0.0889)
		(layer "In11.Cu")
		(net "M_M_DQS_DP<2>")
	)
	(arc
		(start 72.3138 -98.77679)
		(mid 71.980882 -98.978781)
		(end 71.97725 -99.368102)
		(width 0.0889)
		(layer "In11.Cu")
		(net "M_M_DQS_DP<2>")
	)
	(arc
		(start 73.699116 -97.986088)
		(mid 73.492112 -98.196952)
		(end 73.208896 -98.281236)
		(width 0.0889)
		(layer "In11.Cu")
		(net "M_M_DQS_DP<2>")
	)
	(arc
		(start 74.03084 -97.78619)
		(mid 73.839198 -97.843356)
		(end 73.699116 -97.986088)
		(width 0.0889)
		(layer "In11.Cu")
		(net "M_M_DQS_DP<2>")
	)
	(arc
		(start 73.17613 -98.281236)
		(mid 72.98228 -98.337586)
		(end 72.840596 -98.481388)
		(width 0.0889)
		(layer "In11.Cu")
		(net "M_M_DQS_DP<2>")
	)
	(arc
		(start 74.557636 -97.490788)
		(mid 74.349028 -97.70272)
		(end 74.063606 -97.78619)
		(width 0.0889)
		(layer "In11.Cu")
		(net "M_M_DQS_DP<2>")
	)
	(arc
		(start 76.274676 -96.500188)
		(mid 76.066068 -96.71212)
		(end 75.780646 -96.79559)
		(width 0.0889)
		(layer "In11.Cu")
		(net "M_M_DQS_DP<2>")
	)
	(arc
		(start 80.055212 -93.72854)
		(mid 79.779934 -94.062141)
		(end 79.543402 -94.424246)
		(width 0.0889)
		(layer "In11.Cu")
		(net "M_M_DQS_DP<2>")
	)
	(arc
		(start 76.61021 -96.300036)
		(mid 76.41636 -96.356386)
		(end 76.274676 -96.500188)
		(width 0.0889)
		(layer "In11.Cu")
		(net "M_M_DQS_DP<2>")
	)
	(arc
		(start 77.991716 -95.509588)
		(mid 77.783108 -95.72152)
		(end 77.497686 -95.80499)
		(width 0.0889)
		(layer "In11.Cu")
		(net "M_M_DQS_DP<2>")
	)
	(arc
		(start 78.849982 -95.014288)
		(mid 78.642978 -95.225152)
		(end 78.359762 -95.309436)
		(width 0.0889)
		(layer "In11.Cu")
		(net "M_M_DQS_DP<2>")
	)
	(arc
		(start 71.982076 -99.376738)
		(mid 72.061298 -99.665856)
		(end 71.988426 -99.95662)
		(width 0.0889)
		(layer "In11.Cu")
		(net "M_M_DQS_DP<2>")
	)
	(arc
		(start 77.46492 -95.80499)
		(mid 77.273278 -95.862156)
		(end 77.133196 -96.004888)
		(width 0.0889)
		(layer "In11.Cu")
		(net "M_M_DQS_DP<2>")
	)
	(segment
		(start 76.334366 -91.25204)
		(end 75.762866 -91.25204)
		(width 0.1651)
		(layer "F.Cu")
		(net "M_M_DQS_DP<1>")
	)
	(segment
		(start 45.643546 -154.21356)
		(end 45.387514 -154.21356)
		(width 0.1651)
		(layer "F.Cu")
		(net "M_M_DQS_DP<1>")
	)
	(segment
		(start 45.84954 -155.866846)
		(end 45.887386 -155.829)
		(width 0.1651)
		(layer "F.Cu")
		(net "M_M_DQS_DP<1>")
	)
	(segment
		(start 45.84954 -156.87294)
		(end 45.84954 -155.866846)
		(width 0.1651)
		(layer "F.Cu")
		(net "M_M_DQS_DP<1>")
	)
	(segment
		(start 45.887386 -154.4574)
		(end 45.643546 -154.21356)
		(width 0.1651)
		(layer "F.Cu")
		(net "M_M_DQS_DP<1>")
	)
	(segment
		(start 45.887386 -155.829)
		(end 45.887386 -154.4574)
		(width 0.1651)
		(layer "F.Cu")
		(net "M_M_DQS_DP<1>")
	)
	(via
		(at 75.762866 -91.25204)
		(size 0.508)
		(drill 0.254)
		(layers "F.Cu" "B.Cu")
		(net "M_M_DQS_DP<1>")
	)
	(via
		(at 45.387514 -150.142956)
		(size 0.508)
		(drill 0.254)
		(layers "F.Cu" "B.Cu")
		(net "M_M_DQS_DP<1>")
	)
	(via
		(at 45.387514 -154.21356)
		(size 0.508)
		(drill 0.254)
		(layers "F.Cu" "B.Cu")
		(net "M_M_DQS_DP<1>")
	)
	(segment
		(start 45.84954 -148.628354)
		(end 45.887386 -148.6662)
		(width 0.1651)
		(layer "B.Cu")
		(net "M_M_DQS_DP<1>")
	)
	(segment
		(start 45.887386 -149.8854)
		(end 45.62983 -150.142956)
		(width 0.1651)
		(layer "B.Cu")
		(net "M_M_DQS_DP<1>")
	)
	(segment
		(start 45.62983 -150.142956)
		(end 45.387514 -150.142956)
		(width 0.1651)
		(layer "B.Cu")
		(net "M_M_DQS_DP<1>")
	)
	(segment
		(start 45.887386 -148.6662)
		(end 45.887386 -149.8854)
		(width 0.1651)
		(layer "B.Cu")
		(net "M_M_DQS_DP<1>")
	)
	(segment
		(start 45.84954 -147.478496)
		(end 45.84954 -148.628354)
		(width 0.1651)
		(layer "B.Cu")
		(net "M_M_DQS_DP<1>")
	)
	(segment
		(start 62.685168 -101.668834)
		(end 62.685168 -98.2472)
		(width 0.14224)
		(layer "In11.Cu")
		(net "M_M_DQS_DP<1>")
	)
	(segment
		(start 75.047094 -91.347036)
		(end 75.762866 -91.25204)
		(width 0.0889)
		(layer "In11.Cu")
		(net "M_M_DQS_DP<1>")
	)
	(segment
		(start 68.452492 -95.222314)
		(end 69.35597 -94.318836)
		(width 0.0889)
		(layer "In11.Cu")
		(net "M_M_DQS_DP<1>")
	)
	(segment
		(start 46.805088 -117.683788)
		(end 47.095918 -117.392958)
		(width 0.14224)
		(layer "In11.Cu")
		(net "M_M_DQS_DP<1>")
	)
	(segment
		(start 45.387514 -150.142956)
		(end 45.387768 -150.142956)
		(width 0.14224)
		(layer "In11.Cu")
		(net "M_M_DQS_DP<1>")
	)
	(segment
		(start 49.13376 -116.985796)
		(end 48.407066 -116.258848)
		(width 0.14224)
		(layer "In11.Cu")
		(net "M_M_DQS_DP<1>")
	)
	(segment
		(start 50.287174 -116.367814)
		(end 50.750978 -115.90401)
		(width 0.14224)
		(layer "In11.Cu")
		(net "M_M_DQS_DP<1>")
	)
	(segment
		(start 48.407066 -115.946936)
		(end 48.713136 -115.640866)
		(width 0.14224)
		(layer "In11.Cu")
		(net "M_M_DQS_DP<1>")
	)
	(segment
		(start 45.012864 -152.638252)
		(end 45.012864 -152.864566)
		(width 0.14224)
		(layer "In11.Cu")
		(net "M_M_DQS_DP<1>")
	)
	(segment
		(start 45.212762 -151.8666)
		(end 45.390562 -152.0444)
		(width 0.14224)
		(layer "In11.Cu")
		(net "M_M_DQS_DP<1>")
	)
	(segment
		(start 73.17613 -92.337636)
		(end 73.208896 -92.337636)
		(width 0.0889)
		(layer "In11.Cu")
		(net "M_M_DQS_DP<1>")
	)
	(segment
		(start 69.35597 -94.318836)
		(end 69.771006 -94.318836)
		(width 0.0889)
		(layer "In11.Cu")
		(net "M_M_DQS_DP<1>")
	)
	(segment
		(start 48.407066 -116.258848)
		(end 48.407066 -115.946936)
		(width 0.14224)
		(layer "In11.Cu")
		(net "M_M_DQS_DP<1>")
	)
	(segment
		(start 66.616072 -96.21393)
		(end 67.599052 -95.222314)
		(width 0.0889)
		(layer "In11.Cu")
		(net "M_M_DQS_DP<1>")
	)
	(segment
		(start 69.771006 -94.318836)
		(end 69.77126 -94.31909)
		(width 0.0889)
		(layer "In11.Cu")
		(net "M_M_DQS_DP<1>")
	)
	(segment
		(start 72.3138 -92.83319)
		(end 72.346566 -92.83319)
		(width 0.0889)
		(layer "In11.Cu")
		(net "M_M_DQS_DP<1>")
	)
	(segment
		(start 47.542196 -117.392958)
		(end 48.13427 -117.985032)
		(width 0.14224)
		(layer "In11.Cu")
		(net "M_M_DQS_DP<1>")
	)
	(segment
		(start 46.805088 -120.819418)
		(end 46.426882 -120.441212)
		(width 0.14224)
		(layer "In11.Cu")
		(net "M_M_DQS_DP<1>")
	)
	(segment
		(start 63.46444 -97.467928)
		(end 64.002158 -97.467928)
		(width 0.14224)
		(layer "In11.Cu")
		(net "M_M_DQS_DP<1>")
	)
	(segment
		(start 47.095918 -117.392958)
		(end 47.542196 -117.392958)
		(width 0.14224)
		(layer "In11.Cu")
		(net "M_M_DQS_DP<1>")
	)
	(segment
		(start 67.599052 -95.222314)
		(end 68.452492 -95.222314)
		(width 0.0889)
		(layer "In11.Cu")
		(net "M_M_DQS_DP<1>")
	)
	(segment
		(start 66.350388 -97.4217)
		(end 66.616072 -97.156016)
		(width 0.0889)
		(layer "In11.Cu")
		(net "M_M_DQS_DP<1>")
	)
	(segment
		(start 46.426882 -119.567452)
		(end 46.805088 -119.189246)
		(width 0.14224)
		(layer "In11.Cu")
		(net "M_M_DQS_DP<1>")
	)
	(segment
		(start 46.169834 -129.045208)
		(end 46.805088 -128.409954)
		(width 0.14224)
		(layer "In11.Cu")
		(net "M_M_DQS_DP<1>")
	)
	(segment
		(start 45.012864 -151.751792)
		(end 45.127672 -151.8666)
		(width 0.14224)
		(layer "In11.Cu")
		(net "M_M_DQS_DP<1>")
	)
	(segment
		(start 45.387768 -150.142956)
		(end 46.169834 -149.36089)
		(width 0.14224)
		(layer "In11.Cu")
		(net "M_M_DQS_DP<1>")
	)
	(segment
		(start 49.13376 -117.521228)
		(end 49.13376 -116.985796)
		(width 0.14224)
		(layer "In11.Cu")
		(net "M_M_DQS_DP<1>")
	)
	(segment
		(start 46.426882 -122.727212)
		(end 46.264576 -122.727212)
		(width 0.14224)
		(layer "In11.Cu")
		(net "M_M_DQS_DP<1>")
	)
	(segment
		(start 49.751234 -116.367814)
		(end 50.287174 -116.367814)
		(width 0.14224)
		(layer "In11.Cu")
		(net "M_M_DQS_DP<1>")
	)
	(segment
		(start 64.002158 -97.467928)
		(end 64.159638 -97.46488)
		(width 0.14224)
		(layer "In11.Cu")
		(net "M_M_DQS_DP<1>")
	)
	(segment
		(start 48.669956 -117.985032)
		(end 49.13376 -117.521228)
		(width 0.14224)
		(layer "In11.Cu")
		(net "M_M_DQS_DP<1>")
	)
	(segment
		(start 48.13427 -117.985032)
		(end 48.669956 -117.985032)
		(width 0.14224)
		(layer "In11.Cu")
		(net "M_M_DQS_DP<1>")
	)
	(segment
		(start 45.208698 -153.0604)
		(end 45.593762 -153.0604)
		(width 0.14224)
		(layer "In11.Cu")
		(net "M_M_DQS_DP<1>")
	)
	(segment
		(start 64.159638 -97.46488)
		(end 64.181736 -97.464626)
		(width 0.0889)
		(layer "In11.Cu")
		(net "M_M_DQS_DP<1>")
	)
	(segment
		(start 45.210222 -152.501092)
		(end 45.150024 -152.501092)
		(width 0.14224)
		(layer "In11.Cu")
		(net "M_M_DQS_DP<1>")
	)
	(segment
		(start 46.068488 -119.76354)
		(end 46.264576 -119.567452)
		(width 0.14224)
		(layer "In11.Cu")
		(net "M_M_DQS_DP<1>")
	)
	(segment
		(start 46.169834 -149.36089)
		(end 46.169834 -129.045208)
		(width 0.14224)
		(layer "In11.Cu")
		(net "M_M_DQS_DP<1>")
	)
	(segment
		(start 45.822362 -151.011128)
		(end 45.57649 -151.257)
		(width 0.14224)
		(layer "In11.Cu")
		(net "M_M_DQS_DP<1>")
	)
	(segment
		(start 70.593712 -93.82379)
		(end 70.633336 -93.82379)
		(width 0.0889)
		(layer "In11.Cu")
		(net "M_M_DQS_DP<1>")
	)
	(segment
		(start 46.426882 -121.853452)
		(end 46.805088 -121.475246)
		(width 0.14224)
		(layer "In11.Cu")
		(net "M_M_DQS_DP<1>")
	)
	(segment
		(start 48.713136 -115.640866)
		(end 49.02454 -115.640866)
		(width 0.14224)
		(layer "In11.Cu")
		(net "M_M_DQS_DP<1>")
	)
	(segment
		(start 46.043088 -122.505724)
		(end 46.043088 -122.07494)
		(width 0.14224)
		(layer "In11.Cu")
		(net "M_M_DQS_DP<1>")
	)
	(segment
		(start 49.02454 -115.640866)
		(end 49.751234 -116.367814)
		(width 0.14224)
		(layer "In11.Cu")
		(net "M_M_DQS_DP<1>")
	)
	(segment
		(start 46.805088 -123.105418)
		(end 46.426882 -122.727212)
		(width 0.14224)
		(layer "In11.Cu")
		(net "M_M_DQS_DP<1>")
	)
	(segment
		(start 46.264576 -120.441212)
		(end 46.068488 -120.245124)
		(width 0.14224)
		(layer "In11.Cu")
		(net "M_M_DQS_DP<1>")
	)
	(segment
		(start 64.22009 -97.424494)
		(end 64.358774 -97.4217)
		(width 0.0889)
		(layer "In11.Cu")
		(net "M_M_DQS_DP<1>")
	)
	(segment
		(start 45.183298 -151.257)
		(end 45.012864 -151.427434)
		(width 0.14224)
		(layer "In11.Cu")
		(net "M_M_DQS_DP<1>")
	)
	(segment
		(start 46.068488 -120.245124)
		(end 46.068488 -119.76354)
		(width 0.14224)
		(layer "In11.Cu")
		(net "M_M_DQS_DP<1>")
	)
	(segment
		(start 74.89317 -91.347036)
		(end 75.047094 -91.347036)
		(width 0.0889)
		(layer "In11.Cu")
		(net "M_M_DQS_DP<1>")
	)
	(segment
		(start 45.593762 -153.0604)
		(end 45.847762 -153.3144)
		(width 0.14224)
		(layer "In11.Cu")
		(net "M_M_DQS_DP<1>")
	)
	(segment
		(start 46.805088 -121.475246)
		(end 46.805088 -120.819418)
		(width 0.14224)
		(layer "In11.Cu")
		(net "M_M_DQS_DP<1>")
	)
	(segment
		(start 71.45909 -93.32849)
		(end 71.48322 -93.32849)
		(width 0.0889)
		(layer "In11.Cu")
		(net "M_M_DQS_DP<1>")
	)
	(segment
		(start 46.264576 -119.567452)
		(end 46.426882 -119.567452)
		(width 0.14224)
		(layer "In11.Cu")
		(net "M_M_DQS_DP<1>")
	)
	(segment
		(start 46.426882 -120.441212)
		(end 46.264576 -120.441212)
		(width 0.14224)
		(layer "In11.Cu")
		(net "M_M_DQS_DP<1>")
	)
	(segment
		(start 46.805088 -128.409954)
		(end 46.805088 -123.105418)
		(width 0.14224)
		(layer "In11.Cu")
		(net "M_M_DQS_DP<1>")
	)
	(segment
		(start 45.822362 -150.577804)
		(end 45.822362 -151.011128)
		(width 0.14224)
		(layer "In11.Cu")
		(net "M_M_DQS_DP<1>")
	)
	(segment
		(start 50.750978 -115.368578)
		(end 50.024284 -114.64163)
		(width 0.14224)
		(layer "In11.Cu")
		(net "M_M_DQS_DP<1>")
	)
	(segment
		(start 64.181736 -97.464626)
		(end 64.22009 -97.424494)
		(width 0.0889)
		(layer "In11.Cu")
		(net "M_M_DQS_DP<1>")
	)
	(segment
		(start 64.358774 -97.4217)
		(end 66.350388 -97.4217)
		(width 0.0889)
		(layer "In11.Cu")
		(net "M_M_DQS_DP<1>")
	)
	(segment
		(start 46.264576 -121.853452)
		(end 46.426882 -121.853452)
		(width 0.14224)
		(layer "In11.Cu")
		(net "M_M_DQS_DP<1>")
	)
	(segment
		(start 50.750978 -115.90401)
		(end 50.750978 -115.368578)
		(width 0.14224)
		(layer "In11.Cu")
		(net "M_M_DQS_DP<1>")
	)
	(segment
		(start 45.150024 -152.501092)
		(end 45.012864 -152.638252)
		(width 0.14224)
		(layer "In11.Cu")
		(net "M_M_DQS_DP<1>")
	)
	(segment
		(start 46.805088 -119.189246)
		(end 46.805088 -117.683788)
		(width 0.14224)
		(layer "In11.Cu")
		(net "M_M_DQS_DP<1>")
	)
	(segment
		(start 50.024284 -114.64163)
		(end 50.024284 -114.329718)
		(width 0.14224)
		(layer "In11.Cu")
		(net "M_M_DQS_DP<1>")
	)
	(segment
		(start 45.57649 -151.257)
		(end 45.183298 -151.257)
		(width 0.14224)
		(layer "In11.Cu")
		(net "M_M_DQS_DP<1>")
	)
	(segment
		(start 46.264576 -122.727212)
		(end 46.043088 -122.505724)
		(width 0.14224)
		(layer "In11.Cu")
		(net "M_M_DQS_DP<1>")
	)
	(segment
		(start 45.847762 -153.3144)
		(end 45.847762 -153.753312)
		(width 0.14224)
		(layer "In11.Cu")
		(net "M_M_DQS_DP<1>")
	)
	(segment
		(start 45.012864 -151.427434)
		(end 45.012864 -151.751792)
		(width 0.14224)
		(layer "In11.Cu")
		(net "M_M_DQS_DP<1>")
	)
	(segment
		(start 45.012864 -152.864566)
		(end 45.208698 -153.0604)
		(width 0.14224)
		(layer "In11.Cu")
		(net "M_M_DQS_DP<1>")
	)
	(segment
		(start 50.024284 -114.329718)
		(end 62.685168 -101.668834)
		(width 0.14224)
		(layer "In11.Cu")
		(net "M_M_DQS_DP<1>")
	)
	(segment
		(start 45.127672 -151.8666)
		(end 45.212762 -151.8666)
		(width 0.14224)
		(layer "In11.Cu")
		(net "M_M_DQS_DP<1>")
	)
	(segment
		(start 46.043088 -122.07494)
		(end 46.264576 -121.853452)
		(width 0.14224)
		(layer "In11.Cu")
		(net "M_M_DQS_DP<1>")
	)
	(segment
		(start 74.03084 -91.84259)
		(end 74.063606 -91.84259)
		(width 0.0889)
		(layer "In11.Cu")
		(net "M_M_DQS_DP<1>")
	)
	(segment
		(start 66.616072 -97.156016)
		(end 66.616072 -96.21393)
		(width 0.0889)
		(layer "In11.Cu")
		(net "M_M_DQS_DP<1>")
	)
	(segment
		(start 45.387514 -150.142956)
		(end 45.822362 -150.577804)
		(width 0.14224)
		(layer "In11.Cu")
		(net "M_M_DQS_DP<1>")
	)
	(segment
		(start 45.390562 -152.320752)
		(end 45.210222 -152.501092)
		(width 0.14224)
		(layer "In11.Cu")
		(net "M_M_DQS_DP<1>")
	)
	(segment
		(start 62.685168 -98.2472)
		(end 63.46444 -97.467928)
		(width 0.14224)
		(layer "In11.Cu")
		(net "M_M_DQS_DP<1>")
	)
	(segment
		(start 45.847762 -153.753312)
		(end 45.387514 -154.21356)
		(width 0.14224)
		(layer "In11.Cu")
		(net "M_M_DQS_DP<1>")
	)
	(segment
		(start 45.390562 -152.0444)
		(end 45.390562 -152.320752)
		(width 0.14224)
		(layer "In11.Cu")
		(net "M_M_DQS_DP<1>")
	)
	(arc
		(start 71.982076 -93.033088)
		(mid 72.122155 -92.890352)
		(end 72.3138 -92.83319)
		(width 0.0889)
		(layer "In11.Cu")
		(net "M_M_DQS_DP<1>")
	)
	(arc
		(start 72.346566 -92.83319)
		(mid 72.63199 -92.749723)
		(end 72.840596 -92.537788)
		(width 0.0889)
		(layer "In11.Cu")
		(net "M_M_DQS_DP<1>")
	)
	(arc
		(start 74.557636 -91.547188)
		(mid 74.699319 -91.403384)
		(end 74.89317 -91.347036)
		(width 0.0889)
		(layer "In11.Cu")
		(net "M_M_DQS_DP<1>")
	)
	(arc
		(start 69.77126 -94.31909)
		(mid 70.056543 -94.235564)
		(end 70.265036 -94.023688)
		(width 0.0889)
		(layer "In11.Cu")
		(net "M_M_DQS_DP<1>")
	)
	(arc
		(start 71.123556 -93.528642)
		(mid 71.265239 -93.384838)
		(end 71.45909 -93.32849)
		(width 0.0889)
		(layer "In11.Cu")
		(net "M_M_DQS_DP<1>")
	)
	(arc
		(start 73.208896 -92.337636)
		(mid 73.492113 -92.253355)
		(end 73.699116 -92.042488)
		(width 0.0889)
		(layer "In11.Cu")
		(net "M_M_DQS_DP<1>")
	)
	(arc
		(start 70.633336 -93.82379)
		(mid 70.916553 -93.739509)
		(end 71.123556 -93.528642)
		(width 0.0889)
		(layer "In11.Cu")
		(net "M_M_DQS_DP<1>")
	)
	(arc
		(start 71.48322 -93.32849)
		(mid 71.771365 -93.246171)
		(end 71.982076 -93.033088)
		(width 0.0889)
		(layer "In11.Cu")
		(net "M_M_DQS_DP<1>")
	)
	(arc
		(start 70.265036 -94.023688)
		(mid 70.40378 -93.881655)
		(end 70.593712 -93.82379)
		(width 0.0889)
		(layer "In11.Cu")
		(net "M_M_DQS_DP<1>")
	)
	(arc
		(start 72.840596 -92.537788)
		(mid 72.982279 -92.393984)
		(end 73.17613 -92.337636)
		(width 0.0889)
		(layer "In11.Cu")
		(net "M_M_DQS_DP<1>")
	)
	(arc
		(start 73.699116 -92.042488)
		(mid 73.839195 -91.899752)
		(end 74.03084 -91.84259)
		(width 0.0889)
		(layer "In11.Cu")
		(net "M_M_DQS_DP<1>")
	)
	(arc
		(start 74.063606 -91.84259)
		(mid 74.34903 -91.759123)
		(end 74.557636 -91.547188)
		(width 0.0889)
		(layer "In11.Cu")
		(net "M_M_DQS_DP<1>")
	)
	(segment
		(start 72.1995 -152.895554)
		(end 71.763382 -153.331672)
		(width 0.1651)
		(layer "F.Cu")
		(net "M_M_DQS_DP<17>")
	)
	(segment
		(start 71.6788 -154.333702)
		(end 71.760334 -154.557984)
		(width 0.1651)
		(layer "F.Cu")
		(net "M_M_DQS_DP<17>")
	)
	(segment
		(start 71.6788 -153.515568)
		(end 71.6788 -154.333702)
		(width 0.1651)
		(layer "F.Cu")
		(net "M_M_DQS_DP<17>")
	)
	(segment
		(start 71.760334 -154.557984)
		(end 72.142096 -154.939746)
		(width 0.1651)
		(layer "F.Cu")
		(net "M_M_DQS_DP<17>")
	)
	(segment
		(start 81.485232 -82.33664)
		(end 80.913732 -82.33664)
		(width 0.1651)
		(layer "F.Cu")
		(net "M_M_DQS_DP<17>")
	)
	(segment
		(start 71.763382 -153.331672)
		(end 71.6788 -153.515568)
		(width 0.1651)
		(layer "F.Cu")
		(net "M_M_DQS_DP<17>")
	)
	(segment
		(start 72.1995 -152.273)
		(end 72.1995 -152.895554)
		(width 0.1651)
		(layer "F.Cu")
		(net "M_M_DQS_DP<17>")
	)
	(via
		(at 72.142096 -154.939746)
		(size 0.508)
		(drill 0.254)
		(layers "F.Cu" "B.Cu")
		(net "M_M_DQS_DP<17>")
	)
	(via
		(at 80.913732 -82.33664)
		(size 0.508)
		(drill 0.254)
		(layers "F.Cu" "B.Cu")
		(net "M_M_DQS_DP<17>")
	)
	(via
		(at 72.142096 -149.4282)
		(size 0.508)
		(drill 0.254)
		(layers "F.Cu" "B.Cu")
		(net "M_M_DQS_DP<17>")
	)
	(segment
		(start 71.6661 -149.976332)
		(end 71.753476 -149.81682)
		(width 0.1651)
		(layer "B.Cu")
		(net "M_M_DQS_DP<17>")
	)
	(segment
		(start 71.753476 -149.81682)
		(end 72.142096 -149.4282)
		(width 0.1651)
		(layer "B.Cu")
		(net "M_M_DQS_DP<17>")
	)
	(segment
		(start 72.1995 -151.460454)
		(end 71.743316 -151.00427)
		(width 0.1651)
		(layer "B.Cu")
		(net "M_M_DQS_DP<17>")
	)
	(segment
		(start 72.1995 -152.078436)
		(end 72.1995 -151.460454)
		(width 0.1651)
		(layer "B.Cu")
		(net "M_M_DQS_DP<17>")
	)
	(segment
		(start 71.743316 -151.00427)
		(end 71.6661 -150.871936)
		(width 0.1651)
		(layer "B.Cu")
		(net "M_M_DQS_DP<17>")
	)
	(segment
		(start 71.6661 -150.871936)
		(end 71.6661 -149.976332)
		(width 0.1651)
		(layer "B.Cu")
		(net "M_M_DQS_DP<17>")
	)
	(segment
		(start 80.401922 -97.490788)
		(end 80.406748 -97.499424)
		(width 0.0889)
		(layer "In4.Cu")
		(net "M_M_DQS_DP<17>")
	)
	(segment
		(start 73.739248 -114.200686)
		(end 72.113648 -115.826286)
		(width 0.14224)
		(layer "In4.Cu")
		(net "M_M_DQS_DP<17>")
	)
	(segment
		(start 80.40497 -99.866196)
		(end 80.315562 -100.02139)
		(width 0.0889)
		(layer "In4.Cu")
		(net "M_M_DQS_DP<17>")
	)
	(segment
		(start 80.401922 -87.584788)
		(end 80.406748 -87.593424)
		(width 0.0889)
		(layer "In4.Cu")
		(net "M_M_DQS_DP<17>")
	)
	(segment
		(start 80.395572 -97.48012)
		(end 80.401922 -97.490788)
		(width 0.0889)
		(layer "In4.Cu")
		(net "M_M_DQS_DP<17>")
	)
	(segment
		(start 80.395572 -89.55532)
		(end 80.401922 -89.565988)
		(width 0.0889)
		(layer "In4.Cu")
		(net "M_M_DQS_DP<17>")
	)
	(segment
		(start 72.655176 -143.45031)
		(end 72.655176 -146.27733)
		(width 0.14224)
		(layer "In4.Cu")
		(net "M_M_DQS_DP<17>")
	)
	(segment
		(start 80.395572 -95.49892)
		(end 80.401922 -95.509588)
		(width 0.0889)
		(layer "In4.Cu")
		(net "M_M_DQS_DP<17>")
	)
	(segment
		(start 73.739248 -111.308388)
		(end 73.739248 -114.200686)
		(width 0.14224)
		(layer "In4.Cu")
		(net "M_M_DQS_DP<17>")
	)
	(segment
		(start 80.401922 -94.518988)
		(end 80.406748 -94.527624)
		(width 0.0889)
		(layer "In4.Cu")
		(net "M_M_DQS_DP<17>")
	)
	(segment
		(start 72.551544 -146.634962)
		(end 72.655176 -146.738594)
		(width 0.14224)
		(layer "In4.Cu")
		(net "M_M_DQS_DP<17>")
	)
	(segment
		(start 80.401922 -88.575388)
		(end 80.406748 -88.584024)
		(width 0.0889)
		(layer "In4.Cu")
		(net "M_M_DQS_DP<17>")
	)
	(segment
		(start 80.401922 -86.594188)
		(end 80.406748 -86.602824)
		(width 0.0889)
		(layer "In4.Cu")
		(net "M_M_DQS_DP<17>")
	)
	(segment
		(start 80.401922 -98.481388)
		(end 80.406748 -98.490024)
		(width 0.0889)
		(layer "In4.Cu")
		(net "M_M_DQS_DP<17>")
	)
	(segment
		(start 72.497696 -148.280882)
		(end 72.655176 -148.438362)
		(width 0.14224)
		(layer "In4.Cu")
		(net "M_M_DQS_DP<17>")
	)
	(segment
		(start 80.395572 -96.48952)
		(end 80.401922 -96.500188)
		(width 0.0889)
		(layer "In4.Cu")
		(net "M_M_DQS_DP<17>")
	)
	(segment
		(start 80.395572 -91.53652)
		(end 80.401922 -91.547188)
		(width 0.0889)
		(layer "In4.Cu")
		(net "M_M_DQS_DP<17>")
	)
	(segment
		(start 80.401922 -84.612988)
		(end 80.406748 -84.621624)
		(width 0.0889)
		(layer "In4.Cu")
		(net "M_M_DQS_DP<17>")
	)
	(segment
		(start 80.401922 -95.509588)
		(end 80.406748 -95.518224)
		(width 0.0889)
		(layer "In4.Cu")
		(net "M_M_DQS_DP<17>")
	)
	(segment
		(start 72.655176 -142.105888)
		(end 72.52462 -142.236444)
		(width 0.14224)
		(layer "In4.Cu")
		(net "M_M_DQS_DP<17>")
	)
	(segment
		(start 72.655176 -123.845574)
		(end 72.655176 -142.105888)
		(width 0.14224)
		(layer "In4.Cu")
		(net "M_M_DQS_DP<17>")
	)
	(segment
		(start 80.395572 -83.61172)
		(end 80.401922 -83.622388)
		(width 0.0889)
		(layer "In4.Cu")
		(net "M_M_DQS_DP<17>")
	)
	(segment
		(start 72.655176 -149.19452)
		(end 72.421496 -149.4282)
		(width 0.14224)
		(layer "In4.Cu")
		(net "M_M_DQS_DP<17>")
	)
	(segment
		(start 80.395572 -88.56472)
		(end 80.401922 -88.575388)
		(width 0.0889)
		(layer "In4.Cu")
		(net "M_M_DQS_DP<17>")
	)
	(segment
		(start 72.113648 -123.304046)
		(end 72.655176 -123.845574)
		(width 0.14224)
		(layer "In4.Cu")
		(net "M_M_DQS_DP<17>")
	)
	(segment
		(start 72.514714 -143.055848)
		(end 72.514714 -143.309848)
		(width 0.14224)
		(layer "In4.Cu")
		(net "M_M_DQS_DP<17>")
	)
	(segment
		(start 72.497696 -147.457922)
		(end 72.655176 -147.615402)
		(width 0.14224)
		(layer "In4.Cu")
		(net "M_M_DQS_DP<17>")
	)
	(segment
		(start 80.395572 -98.47072)
		(end 80.401922 -98.481388)
		(width 0.0889)
		(layer "In4.Cu")
		(net "M_M_DQS_DP<17>")
	)
	(segment
		(start 72.655176 -146.27733)
		(end 72.551544 -146.380962)
		(width 0.14224)
		(layer "In4.Cu")
		(net "M_M_DQS_DP<17>")
	)
	(segment
		(start 80.395572 -85.59292)
		(end 80.401922 -85.603588)
		(width 0.0889)
		(layer "In4.Cu")
		(net "M_M_DQS_DP<17>")
	)
	(segment
		(start 80.315562 -100.02139)
		(end 80.09382 -100.243132)
		(width 0.0889)
		(layer "In4.Cu")
		(net "M_M_DQS_DP<17>")
	)
	(segment
		(start 73.739756 -111.308388)
		(end 73.739248 -111.308388)
		(width 0.14224)
		(layer "In4.Cu")
		(net "M_M_DQS_DP<17>")
	)
	(segment
		(start 80.913732 -82.674714)
		(end 80.848708 -82.739738)
		(width 0.0889)
		(layer "In4.Cu")
		(net "M_M_DQS_DP<17>")
	)
	(segment
		(start 72.421496 -149.4282)
		(end 72.142096 -149.4282)
		(width 0.14224)
		(layer "In4.Cu")
		(net "M_M_DQS_DP<17>")
	)
	(segment
		(start 80.401922 -92.537788)
		(end 80.406748 -92.546424)
		(width 0.0889)
		(layer "In4.Cu")
		(net "M_M_DQS_DP<17>")
	)
	(segment
		(start 80.395572 -84.60232)
		(end 80.401922 -84.612988)
		(width 0.0889)
		(layer "In4.Cu")
		(net "M_M_DQS_DP<17>")
	)
	(segment
		(start 80.401922 -83.622388)
		(end 80.406748 -83.631024)
		(width 0.0889)
		(layer "In4.Cu")
		(net "M_M_DQS_DP<17>")
	)
	(segment
		(start 72.655176 -147.869402)
		(end 72.497696 -148.026882)
		(width 0.14224)
		(layer "In4.Cu")
		(net "M_M_DQS_DP<17>")
	)
	(segment
		(start 80.395572 -86.58352)
		(end 80.401922 -86.594188)
		(width 0.0889)
		(layer "In4.Cu")
		(net "M_M_DQS_DP<17>")
	)
	(segment
		(start 72.52462 -142.236444)
		(end 72.52462 -142.490444)
		(width 0.14224)
		(layer "In4.Cu")
		(net "M_M_DQS_DP<17>")
	)
	(segment
		(start 80.05445 -104.993694)
		(end 73.739756 -111.308388)
		(width 0.14224)
		(layer "In4.Cu")
		(net "M_M_DQS_DP<17>")
	)
	(segment
		(start 80.401922 -89.565988)
		(end 80.406748 -89.574624)
		(width 0.0889)
		(layer "In4.Cu")
		(net "M_M_DQS_DP<17>")
	)
	(segment
		(start 80.09382 -102.960678)
		(end 80.05445 -103.000048)
		(width 0.0889)
		(layer "In4.Cu")
		(net "M_M_DQS_DP<17>")
	)
	(segment
		(start 80.395572 -92.52712)
		(end 80.401922 -92.537788)
		(width 0.0889)
		(layer "In4.Cu")
		(net "M_M_DQS_DP<17>")
	)
	(segment
		(start 72.497696 -148.026882)
		(end 72.497696 -148.280882)
		(width 0.14224)
		(layer "In4.Cu")
		(net "M_M_DQS_DP<17>")
	)
	(segment
		(start 72.514714 -143.309848)
		(end 72.655176 -143.45031)
		(width 0.14224)
		(layer "In4.Cu")
		(net "M_M_DQS_DP<17>")
	)
	(segment
		(start 80.05445 -103.000048)
		(end 80.05445 -104.993694)
		(width 0.14224)
		(layer "In4.Cu")
		(net "M_M_DQS_DP<17>")
	)
	(segment
		(start 72.497696 -147.203922)
		(end 72.497696 -147.457922)
		(width 0.14224)
		(layer "In4.Cu")
		(net "M_M_DQS_DP<17>")
	)
	(segment
		(start 80.913732 -82.33664)
		(end 80.913732 -82.674714)
		(width 0.0889)
		(layer "In4.Cu")
		(net "M_M_DQS_DP<17>")
	)
	(segment
		(start 72.655176 -146.738594)
		(end 72.655176 -147.046442)
		(width 0.14224)
		(layer "In4.Cu")
		(net "M_M_DQS_DP<17>")
	)
	(segment
		(start 72.113648 -115.826286)
		(end 72.113648 -123.304046)
		(width 0.14224)
		(layer "In4.Cu")
		(net "M_M_DQS_DP<17>")
	)
	(segment
		(start 72.655176 -148.438362)
		(end 72.655176 -149.19452)
		(width 0.14224)
		(layer "In4.Cu")
		(net "M_M_DQS_DP<17>")
	)
	(segment
		(start 80.395572 -90.54592)
		(end 80.401922 -90.556588)
		(width 0.0889)
		(layer "In4.Cu")
		(net "M_M_DQS_DP<17>")
	)
	(segment
		(start 80.401922 -93.928438)
		(end 80.395572 -93.939106)
		(width 0.0889)
		(layer "In4.Cu")
		(net "M_M_DQS_DP<17>")
	)
	(segment
		(start 72.655176 -147.615402)
		(end 72.655176 -147.869402)
		(width 0.14224)
		(layer "In4.Cu")
		(net "M_M_DQS_DP<17>")
	)
	(segment
		(start 80.401922 -91.547188)
		(end 80.406748 -91.555824)
		(width 0.0889)
		(layer "In4.Cu")
		(net "M_M_DQS_DP<17>")
	)
	(segment
		(start 72.655176 -142.621)
		(end 72.655176 -142.915386)
		(width 0.14224)
		(layer "In4.Cu")
		(net "M_M_DQS_DP<17>")
	)
	(segment
		(start 80.09382 -100.243132)
		(end 80.09382 -102.960678)
		(width 0.0889)
		(layer "In4.Cu")
		(net "M_M_DQS_DP<17>")
	)
	(segment
		(start 80.401922 -85.603588)
		(end 80.406748 -85.612224)
		(width 0.0889)
		(layer "In4.Cu")
		(net "M_M_DQS_DP<17>")
	)
	(segment
		(start 80.395572 -87.57412)
		(end 80.401922 -87.584788)
		(width 0.0889)
		(layer "In4.Cu")
		(net "M_M_DQS_DP<17>")
	)
	(segment
		(start 72.551544 -146.380962)
		(end 72.551544 -146.634962)
		(width 0.14224)
		(layer "In4.Cu")
		(net "M_M_DQS_DP<17>")
	)
	(segment
		(start 72.655176 -142.915386)
		(end 72.514714 -143.055848)
		(width 0.14224)
		(layer "In4.Cu")
		(net "M_M_DQS_DP<17>")
	)
	(segment
		(start 72.655176 -147.046442)
		(end 72.497696 -147.203922)
		(width 0.14224)
		(layer "In4.Cu")
		(net "M_M_DQS_DP<17>")
	)
	(segment
		(start 80.401922 -96.500188)
		(end 80.406748 -96.508824)
		(width 0.0889)
		(layer "In4.Cu")
		(net "M_M_DQS_DP<17>")
	)
	(segment
		(start 80.401922 -90.556588)
		(end 80.406748 -90.565224)
		(width 0.0889)
		(layer "In4.Cu")
		(net "M_M_DQS_DP<17>")
	)
	(segment
		(start 72.52462 -142.490444)
		(end 72.655176 -142.621)
		(width 0.14224)
		(layer "In4.Cu")
		(net "M_M_DQS_DP<17>")
	)
	(arc
		(start 80.406748 -87.593424)
		(mid 80.455503 -87.789776)
		(end 80.401922 -87.984838)
		(width 0.0889)
		(layer "In4.Cu")
		(net "M_M_DQS_DP<17>")
	)
	(arc
		(start 80.401922 -87.984838)
		(mid 80.3227 -88.273956)
		(end 80.395572 -88.56472)
		(width 0.0889)
		(layer "In4.Cu")
		(net "M_M_DQS_DP<17>")
	)
	(arc
		(start 80.406748 -89.574624)
		(mid 80.455503 -89.770976)
		(end 80.401922 -89.966038)
		(width 0.0889)
		(layer "In4.Cu")
		(net "M_M_DQS_DP<17>")
	)
	(arc
		(start 80.401922 -92.937838)
		(mid 80.322791 -93.23324)
		(end 80.401922 -93.528642)
		(width 0.0889)
		(layer "In4.Cu")
		(net "M_M_DQS_DP<17>")
	)
	(arc
		(start 80.406748 -86.602824)
		(mid 80.455503 -86.799176)
		(end 80.401922 -86.994238)
		(width 0.0889)
		(layer "In4.Cu")
		(net "M_M_DQS_DP<17>")
	)
	(arc
		(start 80.401922 -93.528642)
		(mid 80.455421 -93.72854)
		(end 80.401922 -93.928438)
		(width 0.0889)
		(layer "In4.Cu")
		(net "M_M_DQS_DP<17>")
	)
	(arc
		(start 80.401922 -89.966038)
		(mid 80.3227 -90.255156)
		(end 80.395572 -90.54592)
		(width 0.0889)
		(layer "In4.Cu")
		(net "M_M_DQS_DP<17>")
	)
	(arc
		(start 80.406748 -85.612224)
		(mid 80.455503 -85.808576)
		(end 80.401922 -86.003638)
		(width 0.0889)
		(layer "In4.Cu")
		(net "M_M_DQS_DP<17>")
	)
	(arc
		(start 80.401922 -94.919038)
		(mid 80.3227 -95.208156)
		(end 80.395572 -95.49892)
		(width 0.0889)
		(layer "In4.Cu")
		(net "M_M_DQS_DP<17>")
	)
	(arc
		(start 80.406748 -83.631024)
		(mid 80.455503 -83.827376)
		(end 80.401922 -84.022438)
		(width 0.0889)
		(layer "In4.Cu")
		(net "M_M_DQS_DP<17>")
	)
	(arc
		(start 80.401922 -91.947238)
		(mid 80.3227 -92.236356)
		(end 80.395572 -92.52712)
		(width 0.0889)
		(layer "In4.Cu")
		(net "M_M_DQS_DP<17>")
	)
	(arc
		(start 80.406748 -97.499424)
		(mid 80.455503 -97.695776)
		(end 80.401922 -97.890838)
		(width 0.0889)
		(layer "In4.Cu")
		(net "M_M_DQS_DP<17>")
	)
	(arc
		(start 80.401922 -88.975438)
		(mid 80.3227 -89.264556)
		(end 80.395572 -89.55532)
		(width 0.0889)
		(layer "In4.Cu")
		(net "M_M_DQS_DP<17>")
	)
	(arc
		(start 80.395572 -93.939106)
		(mid 80.322774 -94.229869)
		(end 80.401922 -94.518988)
		(width 0.0889)
		(layer "In4.Cu")
		(net "M_M_DQS_DP<17>")
	)
	(arc
		(start 80.401922 -85.013038)
		(mid 80.3227 -85.302156)
		(end 80.395572 -85.59292)
		(width 0.0889)
		(layer "In4.Cu")
		(net "M_M_DQS_DP<17>")
	)
	(arc
		(start 80.401922 -99.472242)
		(mid 80.455282 -99.668814)
		(end 80.40497 -99.866196)
		(width 0.0889)
		(layer "In4.Cu")
		(net "M_M_DQS_DP<17>")
	)
	(arc
		(start 80.401922 -95.909638)
		(mid 80.3227 -96.198756)
		(end 80.395572 -96.48952)
		(width 0.0889)
		(layer "In4.Cu")
		(net "M_M_DQS_DP<17>")
	)
	(arc
		(start 80.406748 -95.518224)
		(mid 80.455503 -95.714576)
		(end 80.401922 -95.909638)
		(width 0.0889)
		(layer "In4.Cu")
		(net "M_M_DQS_DP<17>")
	)
	(arc
		(start 80.406748 -91.555824)
		(mid 80.455503 -91.752176)
		(end 80.401922 -91.947238)
		(width 0.0889)
		(layer "In4.Cu")
		(net "M_M_DQS_DP<17>")
	)
	(arc
		(start 80.401922 -90.956638)
		(mid 80.3227 -91.245756)
		(end 80.395572 -91.53652)
		(width 0.0889)
		(layer "In4.Cu")
		(net "M_M_DQS_DP<17>")
	)
	(arc
		(start 80.406748 -96.508824)
		(mid 80.455503 -96.705176)
		(end 80.401922 -96.900238)
		(width 0.0889)
		(layer "In4.Cu")
		(net "M_M_DQS_DP<17>")
	)
	(arc
		(start 80.401922 -98.881438)
		(mid 80.322791 -99.17684)
		(end 80.401922 -99.472242)
		(width 0.0889)
		(layer "In4.Cu")
		(net "M_M_DQS_DP<17>")
	)
	(arc
		(start 80.401922 -86.994238)
		(mid 80.3227 -87.283356)
		(end 80.395572 -87.57412)
		(width 0.0889)
		(layer "In4.Cu")
		(net "M_M_DQS_DP<17>")
	)
	(arc
		(start 80.406748 -84.621624)
		(mid 80.455503 -84.817976)
		(end 80.401922 -85.013038)
		(width 0.0889)
		(layer "In4.Cu")
		(net "M_M_DQS_DP<17>")
	)
	(arc
		(start 80.401922 -84.022438)
		(mid 80.3227 -84.311556)
		(end 80.395572 -84.60232)
		(width 0.0889)
		(layer "In4.Cu")
		(net "M_M_DQS_DP<17>")
	)
	(arc
		(start 80.848708 -82.739738)
		(mid 80.389231 -83.054687)
		(end 80.395572 -83.61172)
		(width 0.0889)
		(layer "In4.Cu")
		(net "M_M_DQS_DP<17>")
	)
	(arc
		(start 80.406748 -88.584024)
		(mid 80.455503 -88.780376)
		(end 80.401922 -88.975438)
		(width 0.0889)
		(layer "In4.Cu")
		(net "M_M_DQS_DP<17>")
	)
	(arc
		(start 80.406748 -94.527624)
		(mid 80.455503 -94.723976)
		(end 80.401922 -94.919038)
		(width 0.0889)
		(layer "In4.Cu")
		(net "M_M_DQS_DP<17>")
	)
	(arc
		(start 80.401922 -86.003638)
		(mid 80.3227 -86.292756)
		(end 80.395572 -86.58352)
		(width 0.0889)
		(layer "In4.Cu")
		(net "M_M_DQS_DP<17>")
	)
	(arc
		(start 80.406748 -92.546424)
		(mid 80.455503 -92.742776)
		(end 80.401922 -92.937838)
		(width 0.0889)
		(layer "In4.Cu")
		(net "M_M_DQS_DP<17>")
	)
	(arc
		(start 80.401922 -97.890838)
		(mid 80.3227 -98.179956)
		(end 80.395572 -98.47072)
		(width 0.0889)
		(layer "In4.Cu")
		(net "M_M_DQS_DP<17>")
	)
	(arc
		(start 80.406748 -98.490024)
		(mid 80.455503 -98.686376)
		(end 80.401922 -98.881438)
		(width 0.0889)
		(layer "In4.Cu")
		(net "M_M_DQS_DP<17>")
	)
	(arc
		(start 80.406748 -90.565224)
		(mid 80.455503 -90.761576)
		(end 80.401922 -90.956638)
		(width 0.0889)
		(layer "In4.Cu")
		(net "M_M_DQS_DP<17>")
	)
	(arc
		(start 80.401922 -96.900238)
		(mid 80.3227 -97.189356)
		(end 80.395572 -97.48012)
		(width 0.0889)
		(layer "In4.Cu")
		(net "M_M_DQS_DP<17>")
	)
	(segment
		(start 72.142096 -154.939746)
		(end 71.637144 -154.434794)
		(width 0.14224)
		(layer "In11.Cu")
		(net "M_M_DQS_DP<17>")
	)
	(segment
		(start 71.637144 -149.933152)
		(end 72.142096 -149.4282)
		(width 0.14224)
		(layer "In11.Cu")
		(net "M_M_DQS_DP<17>")
	)
	(segment
		(start 71.637144 -154.434794)
		(end 71.637144 -149.933152)
		(width 0.14224)
		(layer "In11.Cu")
		(net "M_M_DQS_DP<17>")
	)
	(segment
		(start 145.628868 -153.515568)
		(end 145.628868 -154.333702)
		(width 0.1651)
		(layer "F.Cu")
		(net "M_M_DQS_DP<16>")
	)
	(segment
		(start 146.149568 -152.273)
		(end 146.149568 -152.895554)
		(width 0.1651)
		(layer "F.Cu")
		(net "M_M_DQS_DP<16>")
	)
	(segment
		(start 145.628868 -154.333702)
		(end 145.710402 -154.557984)
		(width 0.1651)
		(layer "F.Cu")
		(net "M_M_DQS_DP<16>")
	)
	(segment
		(start 146.149568 -152.895554)
		(end 145.71345 -153.331672)
		(width 0.1651)
		(layer "F.Cu")
		(net "M_M_DQS_DP<16>")
	)
	(segment
		(start 145.710402 -154.557984)
		(end 146.092164 -154.939746)
		(width 0.1651)
		(layer "F.Cu")
		(net "M_M_DQS_DP<16>")
	)
	(segment
		(start 145.71345 -153.331672)
		(end 145.628868 -153.515568)
		(width 0.1651)
		(layer "F.Cu")
		(net "M_M_DQS_DP<16>")
	)
	(segment
		(start 118.212362 -89.584784)
		(end 118.783862 -89.584784)
		(width 0.1651)
		(layer "F.Cu")
		(net "M_M_DQS_DP<16>")
	)
	(via
		(at 146.092164 -149.4282)
		(size 0.508)
		(drill 0.254)
		(layers "F.Cu" "B.Cu")
		(net "M_M_DQS_DP<16>")
	)
	(via
		(at 146.092164 -154.939746)
		(size 0.508)
		(drill 0.254)
		(layers "F.Cu" "B.Cu")
		(net "M_M_DQS_DP<16>")
	)
	(via
		(at 118.783862 -89.584784)
		(size 0.508)
		(drill 0.254)
		(layers "F.Cu" "B.Cu")
		(net "M_M_DQS_DP<16>")
	)
	(segment
		(start 145.703544 -149.81682)
		(end 146.092164 -149.4282)
		(width 0.1651)
		(layer "B.Cu")
		(net "M_M_DQS_DP<16>")
	)
	(segment
		(start 146.149568 -151.460454)
		(end 145.693384 -151.00427)
		(width 0.1651)
		(layer "B.Cu")
		(net "M_M_DQS_DP<16>")
	)
	(segment
		(start 145.693384 -151.00427)
		(end 145.616168 -150.871936)
		(width 0.1651)
		(layer "B.Cu")
		(net "M_M_DQS_DP<16>")
	)
	(segment
		(start 145.616168 -150.871936)
		(end 145.616168 -149.976332)
		(width 0.1651)
		(layer "B.Cu")
		(net "M_M_DQS_DP<16>")
	)
	(segment
		(start 145.616168 -149.976332)
		(end 145.703544 -149.81682)
		(width 0.1651)
		(layer "B.Cu")
		(net "M_M_DQS_DP<16>")
	)
	(segment
		(start 146.149568 -152.078436)
		(end 146.149568 -151.460454)
		(width 0.1651)
		(layer "B.Cu")
		(net "M_M_DQS_DP<16>")
	)
	(segment
		(start 146.371564 -149.4282)
		(end 146.092164 -149.4282)
		(width 0.14224)
		(layer "In11.Cu")
		(net "M_M_DQS_DP<16>")
	)
	(segment
		(start 146.605244 -147.70735)
		(end 146.605244 -147.989798)
		(width 0.14224)
		(layer "In11.Cu")
		(net "M_M_DQS_DP<16>")
	)
	(segment
		(start 127.615188 -107.72902)
		(end 129.224024 -107.72902)
		(width 0.14224)
		(layer "In11.Cu")
		(net "M_M_DQS_DP<16>")
	)
	(segment
		(start 146.605244 -149.19452)
		(end 146.371564 -149.4282)
		(width 0.14224)
		(layer "In11.Cu")
		(net "M_M_DQS_DP<16>")
	)
	(segment
		(start 123.427744 -102.1588)
		(end 123.422918 -102.167436)
		(width 0.0889)
		(layer "In11.Cu")
		(net "M_M_DQS_DP<16>")
	)
	(segment
		(start 123.422918 -99.195636)
		(end 123.416568 -99.206304)
		(width 0.0889)
		(layer "In11.Cu")
		(net "M_M_DQS_DP<16>")
	)
	(segment
		(start 124.787152 -104.52481)
		(end 124.787152 -104.900984)
		(width 0.14224)
		(layer "In11.Cu")
		(net "M_M_DQS_DP<16>")
	)
	(segment
		(start 132.704586 -112.80394)
		(end 133.154166 -113.25352)
		(width 0.14224)
		(layer "In11.Cu")
		(net "M_M_DQS_DP<16>")
	)
	(segment
		(start 123.422918 -97.214436)
		(end 123.416568 -97.225104)
		(width 0.0889)
		(layer "In11.Cu")
		(net "M_M_DQS_DP<16>")
	)
	(segment
		(start 146.092164 -149.4282)
		(end 146.019012 -149.4282)
		(width 0.14224)
		(layer "In11.Cu")
		(net "M_M_DQS_DP<16>")
	)
	(segment
		(start 123.427744 -99.187)
		(end 123.422918 -99.195636)
		(width 0.0889)
		(layer "In11.Cu")
		(net "M_M_DQS_DP<16>")
	)
	(segment
		(start 118.276878 -93.2434)
		(end 118.272052 -93.252036)
		(width 0.0889)
		(layer "In11.Cu")
		(net "M_M_DQS_DP<16>")
	)
	(segment
		(start 118.272052 -91.270836)
		(end 118.265702 -91.281504)
		(width 0.0889)
		(layer "In11.Cu")
		(net "M_M_DQS_DP<16>")
	)
	(segment
		(start 136.525 -113.25352)
		(end 146.605244 -123.333764)
		(width 0.14224)
		(layer "In11.Cu")
		(net "M_M_DQS_DP<16>")
	)
	(segment
		(start 123.422918 -102.167436)
		(end 123.416568 -102.178104)
		(width 0.0889)
		(layer "In11.Cu")
		(net "M_M_DQS_DP<16>")
	)
	(segment
		(start 122.196098 -96.118934)
		(end 122.228864 -96.118934)
		(width 0.0889)
		(layer "In11.Cu")
		(net "M_M_DQS_DP<16>")
	)
	(segment
		(start 123.427744 -100.1776)
		(end 123.422918 -100.186236)
		(width 0.0889)
		(layer "In11.Cu")
		(net "M_M_DQS_DP<16>")
	)
	(segment
		(start 145.587212 -149.86)
		(end 145.587212 -154.434794)
		(width 0.14224)
		(layer "In11.Cu")
		(net "M_M_DQS_DP<16>")
	)
	(segment
		(start 124.787152 -104.900984)
		(end 127.615188 -107.72902)
		(width 0.14224)
		(layer "In11.Cu")
		(net "M_M_DQS_DP<16>")
	)
	(segment
		(start 146.605244 -147.13839)
		(end 146.447764 -147.29587)
		(width 0.14224)
		(layer "In11.Cu")
		(net "M_M_DQS_DP<16>")
	)
	(segment
		(start 124.775468 -103.548688)
		(end 124.826522 -103.599742)
		(width 0.0889)
		(layer "In11.Cu")
		(net "M_M_DQS_DP<16>")
	)
	(segment
		(start 123.422918 -101.176836)
		(end 123.416568 -101.187504)
		(width 0.0889)
		(layer "In11.Cu")
		(net "M_M_DQS_DP<16>")
	)
	(segment
		(start 123.427744 -97.2058)
		(end 123.422918 -97.214436)
		(width 0.0889)
		(layer "In11.Cu")
		(net "M_M_DQS_DP<16>")
	)
	(segment
		(start 123.913138 -103.053134)
		(end 123.945904 -103.053134)
		(width 0.0889)
		(layer "In11.Cu")
		(net "M_M_DQS_DP<16>")
	)
	(segment
		(start 146.476212 -148.11883)
		(end 146.476212 -148.37283)
		(width 0.14224)
		(layer "In11.Cu")
		(net "M_M_DQS_DP<16>")
	)
	(segment
		(start 124.787152 -104.502712)
		(end 124.787152 -104.52481)
		(width 0.0889)
		(layer "In11.Cu")
		(net "M_M_DQS_DP<16>")
	)
	(segment
		(start 120.483122 -95.128588)
		(end 120.513094 -95.128588)
		(width 0.0889)
		(layer "In11.Cu")
		(net "M_M_DQS_DP<16>")
	)
	(segment
		(start 118.272052 -92.261436)
		(end 118.265702 -92.272104)
		(width 0.0889)
		(layer "In11.Cu")
		(net "M_M_DQS_DP<16>")
	)
	(segment
		(start 118.272052 -93.252036)
		(end 118.265702 -93.262704)
		(width 0.0889)
		(layer "In11.Cu")
		(net "M_M_DQS_DP<16>")
	)
	(segment
		(start 123.058428 -96.614488)
		(end 123.091194 -96.614488)
		(width 0.0889)
		(layer "In11.Cu")
		(net "M_M_DQS_DP<16>")
	)
	(segment
		(start 124.826522 -103.599742)
		(end 124.826522 -104.463342)
		(width 0.0889)
		(layer "In11.Cu")
		(net "M_M_DQS_DP<16>")
	)
	(segment
		(start 132.704586 -111.209582)
		(end 132.704586 -112.80394)
		(width 0.14224)
		(layer "In11.Cu")
		(net "M_M_DQS_DP<16>")
	)
	(segment
		(start 118.276878 -91.2622)
		(end 118.272052 -91.270836)
		(width 0.0889)
		(layer "In11.Cu")
		(net "M_M_DQS_DP<16>")
	)
	(segment
		(start 146.447764 -147.54987)
		(end 146.605244 -147.70735)
		(width 0.14224)
		(layer "In11.Cu")
		(net "M_M_DQS_DP<16>")
	)
	(segment
		(start 123.427744 -98.1964)
		(end 123.422918 -98.205036)
		(width 0.0889)
		(layer "In11.Cu")
		(net "M_M_DQS_DP<16>")
	)
	(segment
		(start 146.476212 -148.37283)
		(end 146.605244 -148.501862)
		(width 0.14224)
		(layer "In11.Cu")
		(net "M_M_DQS_DP<16>")
	)
	(segment
		(start 118.783862 -89.922858)
		(end 118.718584 -89.988136)
		(width 0.0889)
		(layer "In11.Cu")
		(net "M_M_DQS_DP<16>")
	)
	(segment
		(start 146.605244 -146.834606)
		(end 146.605244 -147.13839)
		(width 0.14224)
		(layer "In11.Cu")
		(net "M_M_DQS_DP<16>")
	)
	(segment
		(start 146.019012 -149.4282)
		(end 145.587212 -149.86)
		(width 0.14224)
		(layer "In11.Cu")
		(net "M_M_DQS_DP<16>")
	)
	(segment
		(start 146.508216 -146.483578)
		(end 146.508216 -146.737578)
		(width 0.14224)
		(layer "In11.Cu")
		(net "M_M_DQS_DP<16>")
	)
	(segment
		(start 119.620792 -94.633288)
		(end 119.660416 -94.633288)
		(width 0.0889)
		(layer "In11.Cu")
		(net "M_M_DQS_DP<16>")
	)
	(segment
		(start 146.605244 -123.333764)
		(end 146.605244 -146.38655)
		(width 0.14224)
		(layer "In11.Cu")
		(net "M_M_DQS_DP<16>")
	)
	(segment
		(start 146.605244 -147.989798)
		(end 146.476212 -148.11883)
		(width 0.14224)
		(layer "In11.Cu")
		(net "M_M_DQS_DP<16>")
	)
	(segment
		(start 118.770908 -94.137988)
		(end 118.795038 -94.137988)
		(width 0.0889)
		(layer "In11.Cu")
		(net "M_M_DQS_DP<16>")
	)
	(segment
		(start 133.154166 -113.25352)
		(end 136.525 -113.25352)
		(width 0.14224)
		(layer "In11.Cu")
		(net "M_M_DQS_DP<16>")
	)
	(segment
		(start 146.508216 -146.737578)
		(end 146.605244 -146.834606)
		(width 0.14224)
		(layer "In11.Cu")
		(net "M_M_DQS_DP<16>")
	)
	(segment
		(start 129.224024 -107.72902)
		(end 132.704586 -111.209582)
		(width 0.14224)
		(layer "In11.Cu")
		(net "M_M_DQS_DP<16>")
	)
	(segment
		(start 145.587212 -154.434794)
		(end 146.092164 -154.939746)
		(width 0.14224)
		(layer "In11.Cu")
		(net "M_M_DQS_DP<16>")
	)
	(segment
		(start 121.346214 -95.623888)
		(end 121.374154 -95.623888)
		(width 0.0889)
		(layer "In11.Cu")
		(net "M_M_DQS_DP<16>")
	)
	(segment
		(start 124.826522 -104.463342)
		(end 124.787152 -104.502712)
		(width 0.0889)
		(layer "In11.Cu")
		(net "M_M_DQS_DP<16>")
	)
	(segment
		(start 118.276878 -92.2528)
		(end 118.272052 -92.261436)
		(width 0.0889)
		(layer "In11.Cu")
		(net "M_M_DQS_DP<16>")
	)
	(segment
		(start 118.783862 -89.584784)
		(end 118.783862 -89.922858)
		(width 0.0889)
		(layer "In11.Cu")
		(net "M_M_DQS_DP<16>")
	)
	(segment
		(start 146.605244 -146.38655)
		(end 146.508216 -146.483578)
		(width 0.14224)
		(layer "In11.Cu")
		(net "M_M_DQS_DP<16>")
	)
	(segment
		(start 146.605244 -148.501862)
		(end 146.605244 -149.19452)
		(width 0.14224)
		(layer "In11.Cu")
		(net "M_M_DQS_DP<16>")
	)
	(segment
		(start 123.422918 -98.205036)
		(end 123.416568 -98.215704)
		(width 0.0889)
		(layer "In11.Cu")
		(net "M_M_DQS_DP<16>")
	)
	(segment
		(start 146.447764 -147.29587)
		(end 146.447764 -147.54987)
		(width 0.14224)
		(layer "In11.Cu")
		(net "M_M_DQS_DP<16>")
	)
	(arc
		(start 119.660416 -94.633288)
		(mid 119.850345 -94.691158)
		(end 119.989092 -94.833186)
		(width 0.0889)
		(layer "In11.Cu")
		(net "M_M_DQS_DP<16>")
	)
	(arc
		(start 118.272052 -90.870786)
		(mid 118.325522 -91.065849)
		(end 118.276878 -91.2622)
		(width 0.0889)
		(layer "In11.Cu")
		(net "M_M_DQS_DP<16>")
	)
	(arc
		(start 123.422918 -99.786186)
		(mid 123.476388 -99.981249)
		(end 123.427744 -100.1776)
		(width 0.0889)
		(layer "In11.Cu")
		(net "M_M_DQS_DP<16>")
	)
	(arc
		(start 123.416568 -99.206304)
		(mid 123.34377 -99.497067)
		(end 123.422918 -99.786186)
		(width 0.0889)
		(layer "In11.Cu")
		(net "M_M_DQS_DP<16>")
	)
	(arc
		(start 119.130572 -94.33814)
		(mid 119.337576 -94.549004)
		(end 119.620792 -94.633288)
		(width 0.0889)
		(layer "In11.Cu")
		(net "M_M_DQS_DP<16>")
	)
	(arc
		(start 123.945904 -103.053134)
		(mid 124.139754 -103.109484)
		(end 124.281438 -103.253286)
		(width 0.0889)
		(layer "In11.Cu")
		(net "M_M_DQS_DP<16>")
	)
	(arc
		(start 123.416568 -101.187504)
		(mid 123.34377 -101.478267)
		(end 123.422918 -101.767386)
		(width 0.0889)
		(layer "In11.Cu")
		(net "M_M_DQS_DP<16>")
	)
	(arc
		(start 123.416568 -97.225104)
		(mid 123.34377 -97.515867)
		(end 123.422918 -97.804986)
		(width 0.0889)
		(layer "In11.Cu")
		(net "M_M_DQS_DP<16>")
	)
	(arc
		(start 118.265702 -93.262704)
		(mid 118.271879 -93.842636)
		(end 118.770908 -94.137988)
		(width 0.0889)
		(layer "In11.Cu")
		(net "M_M_DQS_DP<16>")
	)
	(arc
		(start 120.847358 -95.328486)
		(mid 121.058071 -95.541565)
		(end 121.346214 -95.623888)
		(width 0.0889)
		(layer "In11.Cu")
		(net "M_M_DQS_DP<16>")
	)
	(arc
		(start 123.422918 -100.186236)
		(mid 123.343787 -100.481638)
		(end 123.422918 -100.77704)
		(width 0.0889)
		(layer "In11.Cu")
		(net "M_M_DQS_DP<16>")
	)
	(arc
		(start 123.422918 -100.77704)
		(mid 123.476417 -100.976938)
		(end 123.422918 -101.176836)
		(width 0.0889)
		(layer "In11.Cu")
		(net "M_M_DQS_DP<16>")
	)
	(arc
		(start 118.265702 -91.281504)
		(mid 118.192904 -91.572267)
		(end 118.272052 -91.861386)
		(width 0.0889)
		(layer "In11.Cu")
		(net "M_M_DQS_DP<16>")
	)
	(arc
		(start 118.272052 -92.851986)
		(mid 118.325522 -93.047049)
		(end 118.276878 -93.2434)
		(width 0.0889)
		(layer "In11.Cu")
		(net "M_M_DQS_DP<16>")
	)
	(arc
		(start 123.422918 -101.767386)
		(mid 123.476388 -101.962449)
		(end 123.427744 -102.1588)
		(width 0.0889)
		(layer "In11.Cu")
		(net "M_M_DQS_DP<16>")
	)
	(arc
		(start 123.091194 -96.614488)
		(mid 123.424112 -96.816479)
		(end 123.427744 -97.2058)
		(width 0.0889)
		(layer "In11.Cu")
		(net "M_M_DQS_DP<16>")
	)
	(arc
		(start 121.374154 -95.623888)
		(mid 121.565796 -95.681054)
		(end 121.705878 -95.823786)
		(width 0.0889)
		(layer "In11.Cu")
		(net "M_M_DQS_DP<16>")
	)
	(arc
		(start 120.513094 -95.128588)
		(mid 120.706197 -95.185107)
		(end 120.847358 -95.328486)
		(width 0.0889)
		(layer "In11.Cu")
		(net "M_M_DQS_DP<16>")
	)
	(arc
		(start 118.718584 -89.988136)
		(mid 118.256615 -90.308678)
		(end 118.272052 -90.870786)
		(width 0.0889)
		(layer "In11.Cu")
		(net "M_M_DQS_DP<16>")
	)
	(arc
		(start 122.228864 -96.118934)
		(mid 122.422714 -96.175284)
		(end 122.564398 -96.319086)
		(width 0.0889)
		(layer "In11.Cu")
		(net "M_M_DQS_DP<16>")
	)
	(arc
		(start 124.281438 -103.253286)
		(mid 124.490046 -103.465218)
		(end 124.775468 -103.548688)
		(width 0.0889)
		(layer "In11.Cu")
		(net "M_M_DQS_DP<16>")
	)
	(arc
		(start 123.422918 -97.804986)
		(mid 123.476388 -98.000049)
		(end 123.427744 -98.1964)
		(width 0.0889)
		(layer "In11.Cu")
		(net "M_M_DQS_DP<16>")
	)
	(arc
		(start 123.422918 -98.795586)
		(mid 123.476388 -98.990649)
		(end 123.427744 -99.187)
		(width 0.0889)
		(layer "In11.Cu")
		(net "M_M_DQS_DP<16>")
	)
	(arc
		(start 118.795038 -94.137988)
		(mid 118.988888 -94.194338)
		(end 119.130572 -94.33814)
		(width 0.0889)
		(layer "In11.Cu")
		(net "M_M_DQS_DP<16>")
	)
	(arc
		(start 122.564398 -96.319086)
		(mid 122.773006 -96.531018)
		(end 123.058428 -96.614488)
		(width 0.0889)
		(layer "In11.Cu")
		(net "M_M_DQS_DP<16>")
	)
	(arc
		(start 118.272052 -91.861386)
		(mid 118.325522 -92.056449)
		(end 118.276878 -92.2528)
		(width 0.0889)
		(layer "In11.Cu")
		(net "M_M_DQS_DP<16>")
	)
	(arc
		(start 123.416568 -98.215704)
		(mid 123.34377 -98.506467)
		(end 123.422918 -98.795586)
		(width 0.0889)
		(layer "In11.Cu")
		(net "M_M_DQS_DP<16>")
	)
	(arc
		(start 119.989092 -94.833186)
		(mid 120.1977 -95.045118)
		(end 120.483122 -95.128588)
		(width 0.0889)
		(layer "In11.Cu")
		(net "M_M_DQS_DP<16>")
	)
	(arc
		(start 123.416568 -102.178104)
		(mid 123.420599 -102.754286)
		(end 123.913138 -103.053134)
		(width 0.0889)
		(layer "In11.Cu")
		(net "M_M_DQS_DP<16>")
	)
	(arc
		(start 121.705878 -95.823786)
		(mid 121.912882 -96.03465)
		(end 122.196098 -96.118934)
		(width 0.0889)
		(layer "In11.Cu")
		(net "M_M_DQS_DP<16>")
	)
	(arc
		(start 118.265702 -92.272104)
		(mid 118.192904 -92.562867)
		(end 118.272052 -92.851986)
		(width 0.0889)
		(layer "In11.Cu")
		(net "M_M_DQS_DP<16>")
	)
	(segment
		(start 136.799574 -152.895554)
		(end 136.363456 -153.331672)
		(width 0.1651)
		(layer "F.Cu")
		(net "M_M_DQS_DP<15>")
	)
	(segment
		(start 113.061242 -89.584784)
		(end 113.632742 -89.584784)
		(width 0.1651)
		(layer "F.Cu")
		(net "M_M_DQS_DP<15>")
	)
	(segment
		(start 136.799574 -152.273)
		(end 136.799574 -152.895554)
		(width 0.1651)
		(layer "F.Cu")
		(net "M_M_DQS_DP<15>")
	)
	(segment
		(start 136.360408 -154.557984)
		(end 136.74217 -154.939746)
		(width 0.1651)
		(layer "F.Cu")
		(net "M_M_DQS_DP<15>")
	)
	(segment
		(start 136.278874 -153.515568)
		(end 136.278874 -154.333702)
		(width 0.1651)
		(layer "F.Cu")
		(net "M_M_DQS_DP<15>")
	)
	(segment
		(start 136.278874 -154.333702)
		(end 136.360408 -154.557984)
		(width 0.1651)
		(layer "F.Cu")
		(net "M_M_DQS_DP<15>")
	)
	(segment
		(start 136.363456 -153.331672)
		(end 136.278874 -153.515568)
		(width 0.1651)
		(layer "F.Cu")
		(net "M_M_DQS_DP<15>")
	)
	(via
		(at 113.632742 -89.584784)
		(size 0.508)
		(drill 0.254)
		(layers "F.Cu" "B.Cu")
		(net "M_M_DQS_DP<15>")
	)
	(via
		(at 136.74217 -154.939746)
		(size 0.508)
		(drill 0.254)
		(layers "F.Cu" "B.Cu")
		(net "M_M_DQS_DP<15>")
	)
	(via
		(at 136.74217 -149.4282)
		(size 0.508)
		(drill 0.254)
		(layers "F.Cu" "B.Cu")
		(net "M_M_DQS_DP<15>")
	)
	(segment
		(start 136.266174 -149.976332)
		(end 136.35355 -149.81682)
		(width 0.1651)
		(layer "B.Cu")
		(net "M_M_DQS_DP<15>")
	)
	(segment
		(start 136.266174 -150.871936)
		(end 136.266174 -149.976332)
		(width 0.1651)
		(layer "B.Cu")
		(net "M_M_DQS_DP<15>")
	)
	(segment
		(start 136.34339 -151.00427)
		(end 136.266174 -150.871936)
		(width 0.1651)
		(layer "B.Cu")
		(net "M_M_DQS_DP<15>")
	)
	(segment
		(start 136.799574 -151.460454)
		(end 136.34339 -151.00427)
		(width 0.1651)
		(layer "B.Cu")
		(net "M_M_DQS_DP<15>")
	)
	(segment
		(start 136.35355 -149.81682)
		(end 136.74217 -149.4282)
		(width 0.1651)
		(layer "B.Cu")
		(net "M_M_DQS_DP<15>")
	)
	(segment
		(start 136.799574 -152.078436)
		(end 136.799574 -151.460454)
		(width 0.1651)
		(layer "B.Cu")
		(net "M_M_DQS_DP<15>")
	)
	(segment
		(start 137.25525 -149.094444)
		(end 136.921494 -149.4282)
		(width 0.14224)
		(layer "In11.Cu")
		(net "M_M_DQS_DP<15>")
	)
	(segment
		(start 117.404642 -103.238046)
		(end 117.42039 -103.265478)
		(width 0.0889)
		(layer "In11.Cu")
		(net "M_M_DQS_DP<15>")
	)
	(segment
		(start 113.120932 -93.252036)
		(end 113.114582 -93.262704)
		(width 0.0889)
		(layer "In11.Cu")
		(net "M_M_DQS_DP<15>")
	)
	(segment
		(start 117.25402 -107.165902)
		(end 117.25402 -107.188)
		(width 0.0889)
		(layer "In11.Cu")
		(net "M_M_DQS_DP<15>")
	)
	(segment
		(start 136.669018 -149.4282)
		(end 136.237218 -149.86)
		(width 0.14224)
		(layer "In11.Cu")
		(net "M_M_DQS_DP<15>")
	)
	(segment
		(start 113.611152 -97.109534)
		(end 113.643918 -97.109534)
		(width 0.0889)
		(layer "In11.Cu")
		(net "M_M_DQS_DP<15>")
	)
	(segment
		(start 117.29339 -107.126532)
		(end 117.25402 -107.165902)
		(width 0.0889)
		(layer "In11.Cu")
		(net "M_M_DQS_DP<15>")
	)
	(segment
		(start 113.125758 -96.2152)
		(end 113.120932 -96.223836)
		(width 0.0889)
		(layer "In11.Cu")
		(net "M_M_DQS_DP<15>")
	)
	(segment
		(start 117.25402 -107.188)
		(end 117.25402 -113.242852)
		(width 0.14224)
		(layer "In11.Cu")
		(net "M_M_DQS_DP<15>")
	)
	(segment
		(start 137.25525 -147.159472)
		(end 137.09777 -147.316952)
		(width 0.14224)
		(layer "In11.Cu")
		(net "M_M_DQS_DP<15>")
	)
	(segment
		(start 113.120932 -96.223836)
		(end 113.114582 -96.234504)
		(width 0.0889)
		(layer "In11.Cu")
		(net "M_M_DQS_DP<15>")
	)
	(segment
		(start 117.418358 -101.662992)
		(end 117.413532 -101.671628)
		(width 0.0889)
		(layer "In11.Cu")
		(net "M_M_DQS_DP<15>")
	)
	(segment
		(start 117.40642 -105.221532)
		(end 117.420644 -105.246678)
		(width 0.0889)
		(layer "In11.Cu")
		(net "M_M_DQS_DP<15>")
	)
	(segment
		(start 117.045232 -99.090734)
		(end 117.077998 -99.090734)
		(width 0.0889)
		(layer "In11.Cu")
		(net "M_M_DQS_DP<15>")
	)
	(segment
		(start 137.25525 -146.38274)
		(end 137.140442 -146.497548)
		(width 0.14224)
		(layer "In11.Cu")
		(net "M_M_DQS_DP<15>")
	)
	(segment
		(start 137.09777 -147.316952)
		(end 137.09777 -147.570952)
		(width 0.14224)
		(layer "In11.Cu")
		(net "M_M_DQS_DP<15>")
	)
	(segment
		(start 117.25402 -113.242852)
		(end 124.87148 -120.860312)
		(width 0.14224)
		(layer "In11.Cu")
		(net "M_M_DQS_DP<15>")
	)
	(segment
		(start 117.413532 -102.262432)
		(end 117.418358 -102.271068)
		(width 0.0889)
		(layer "In11.Cu")
		(net "M_M_DQS_DP<15>")
	)
	(segment
		(start 137.140442 -146.497548)
		(end 137.140442 -146.751548)
		(width 0.14224)
		(layer "In11.Cu")
		(net "M_M_DQS_DP<15>")
	)
	(segment
		(start 113.632742 -89.922858)
		(end 113.567464 -89.988136)
		(width 0.0889)
		(layer "In11.Cu")
		(net "M_M_DQS_DP<15>")
	)
	(segment
		(start 114.473482 -97.605088)
		(end 114.506248 -97.605088)
		(width 0.0889)
		(layer "In11.Cu")
		(net "M_M_DQS_DP<15>")
	)
	(segment
		(start 113.120932 -91.270836)
		(end 113.114582 -91.281504)
		(width 0.0889)
		(layer "In11.Cu")
		(net "M_M_DQS_DP<15>")
	)
	(segment
		(start 116.190522 -98.595688)
		(end 116.223288 -98.595688)
		(width 0.0889)
		(layer "In11.Cu")
		(net "M_M_DQS_DP<15>")
	)
	(segment
		(start 137.25525 -148.551392)
		(end 137.25525 -149.094444)
		(width 0.14224)
		(layer "In11.Cu")
		(net "M_M_DQS_DP<15>")
	)
	(segment
		(start 117.419374 -105.624122)
		(end 117.29339 -105.842308)
		(width 0.0889)
		(layer "In11.Cu")
		(net "M_M_DQS_DP<15>")
	)
	(segment
		(start 113.125758 -92.2528)
		(end 113.120932 -92.261436)
		(width 0.0889)
		(layer "In11.Cu")
		(net "M_M_DQS_DP<15>")
	)
	(segment
		(start 117.413532 -100.681028)
		(end 117.407182 -100.691696)
		(width 0.0889)
		(layer "In11.Cu")
		(net "M_M_DQS_DP<15>")
	)
	(segment
		(start 137.09777 -147.570952)
		(end 137.25525 -147.728432)
		(width 0.14224)
		(layer "In11.Cu")
		(net "M_M_DQS_DP<15>")
	)
	(segment
		(start 136.237218 -154.434794)
		(end 136.74217 -154.939746)
		(width 0.14224)
		(layer "In11.Cu")
		(net "M_M_DQS_DP<15>")
	)
	(segment
		(start 117.29339 -105.842308)
		(end 117.29339 -107.126532)
		(width 0.0889)
		(layer "In11.Cu")
		(net "M_M_DQS_DP<15>")
	)
	(segment
		(start 113.120932 -92.261436)
		(end 113.114582 -92.272104)
		(width 0.0889)
		(layer "In11.Cu")
		(net "M_M_DQS_DP<15>")
	)
	(segment
		(start 137.25525 -146.866356)
		(end 137.25525 -147.159472)
		(width 0.14224)
		(layer "In11.Cu")
		(net "M_M_DQS_DP<15>")
	)
	(segment
		(start 137.140442 -146.751548)
		(end 137.25525 -146.866356)
		(width 0.14224)
		(layer "In11.Cu")
		(net "M_M_DQS_DP<15>")
	)
	(segment
		(start 137.09777 -148.393912)
		(end 137.25525 -148.551392)
		(width 0.14224)
		(layer "In11.Cu")
		(net "M_M_DQS_DP<15>")
	)
	(segment
		(start 117.413532 -99.690682)
		(end 117.407182 -99.70135)
		(width 0.0889)
		(layer "In11.Cu")
		(net "M_M_DQS_DP<15>")
	)
	(segment
		(start 137.25525 -147.728432)
		(end 137.25525 -147.982432)
		(width 0.14224)
		(layer "In11.Cu")
		(net "M_M_DQS_DP<15>")
	)
	(segment
		(start 137.25525 -147.982432)
		(end 137.09777 -148.139912)
		(width 0.14224)
		(layer "In11.Cu")
		(net "M_M_DQS_DP<15>")
	)
	(segment
		(start 115.328192 -98.100134)
		(end 115.360958 -98.100134)
		(width 0.0889)
		(layer "In11.Cu")
		(net "M_M_DQS_DP<15>")
	)
	(segment
		(start 133.691122 -120.860312)
		(end 137.25525 -124.42444)
		(width 0.14224)
		(layer "In11.Cu")
		(net "M_M_DQS_DP<15>")
	)
	(segment
		(start 137.09777 -148.139912)
		(end 137.09777 -148.393912)
		(width 0.14224)
		(layer "In11.Cu")
		(net "M_M_DQS_DP<15>")
	)
	(segment
		(start 136.74217 -149.4282)
		(end 136.669018 -149.4282)
		(width 0.14224)
		(layer "In11.Cu")
		(net "M_M_DQS_DP<15>")
	)
	(segment
		(start 117.404642 -104.228646)
		(end 117.42039 -104.256078)
		(width 0.0889)
		(layer "In11.Cu")
		(net "M_M_DQS_DP<15>")
	)
	(segment
		(start 117.404642 -105.219246)
		(end 117.40642 -105.221532)
		(width 0.0889)
		(layer "In11.Cu")
		(net "M_M_DQS_DP<15>")
	)
	(segment
		(start 113.114582 -94.822518)
		(end 113.120932 -94.833186)
		(width 0.0889)
		(layer "In11.Cu")
		(net "M_M_DQS_DP<15>")
	)
	(segment
		(start 113.125758 -93.2434)
		(end 113.120932 -93.252036)
		(width 0.0889)
		(layer "In11.Cu")
		(net "M_M_DQS_DP<15>")
	)
	(segment
		(start 136.921494 -149.4282)
		(end 136.74217 -149.4282)
		(width 0.14224)
		(layer "In11.Cu")
		(net "M_M_DQS_DP<15>")
	)
	(segment
		(start 136.237218 -149.86)
		(end 136.237218 -154.434794)
		(width 0.14224)
		(layer "In11.Cu")
		(net "M_M_DQS_DP<15>")
	)
	(segment
		(start 113.125758 -91.2622)
		(end 113.120932 -91.270836)
		(width 0.0889)
		(layer "In11.Cu")
		(net "M_M_DQS_DP<15>")
	)
	(segment
		(start 137.25525 -124.42444)
		(end 137.25525 -146.38274)
		(width 0.14224)
		(layer "In11.Cu")
		(net "M_M_DQS_DP<15>")
	)
	(segment
		(start 124.87148 -120.860312)
		(end 133.691122 -120.860312)
		(width 0.14224)
		(layer "In11.Cu")
		(net "M_M_DQS_DP<15>")
	)
	(segment
		(start 113.632742 -89.584784)
		(end 113.632742 -89.922858)
		(width 0.0889)
		(layer "In11.Cu")
		(net "M_M_DQS_DP<15>")
	)
	(segment
		(start 113.125758 -94.234)
		(end 113.120932 -94.242636)
		(width 0.0889)
		(layer "In11.Cu")
		(net "M_M_DQS_DP<15>")
	)
	(arc
		(start 117.42039 -103.265478)
		(mid 117.467066 -103.460179)
		(end 117.413532 -103.653082)
		(width 0.0889)
		(layer "In11.Cu")
		(net "M_M_DQS_DP<15>")
	)
	(arc
		(start 113.114582 -93.262704)
		(mid 113.041784 -93.553467)
		(end 113.120932 -93.842586)
		(width 0.0889)
		(layer "In11.Cu")
		(net "M_M_DQS_DP<15>")
	)
	(arc
		(start 113.567464 -89.988136)
		(mid 113.105495 -90.308678)
		(end 113.120932 -90.870786)
		(width 0.0889)
		(layer "In11.Cu")
		(net "M_M_DQS_DP<15>")
	)
	(arc
		(start 113.120932 -91.861386)
		(mid 113.174402 -92.056449)
		(end 113.125758 -92.2528)
		(width 0.0889)
		(layer "In11.Cu")
		(net "M_M_DQS_DP<15>")
	)
	(arc
		(start 117.407182 -100.691696)
		(mid 117.334384 -100.982459)
		(end 117.413532 -101.271578)
		(width 0.0889)
		(layer "In11.Cu")
		(net "M_M_DQS_DP<15>")
	)
	(arc
		(start 113.114582 -91.281504)
		(mid 113.041784 -91.572267)
		(end 113.120932 -91.861386)
		(width 0.0889)
		(layer "In11.Cu")
		(net "M_M_DQS_DP<15>")
	)
	(arc
		(start 117.413532 -101.271578)
		(mid 117.467002 -101.466641)
		(end 117.418358 -101.662992)
		(width 0.0889)
		(layer "In11.Cu")
		(net "M_M_DQS_DP<15>")
	)
	(arc
		(start 117.413532 -101.671628)
		(mid 117.334401 -101.96703)
		(end 117.413532 -102.262432)
		(width 0.0889)
		(layer "In11.Cu")
		(net "M_M_DQS_DP<15>")
	)
	(arc
		(start 116.555012 -98.795586)
		(mid 116.762016 -99.00645)
		(end 117.045232 -99.090734)
		(width 0.0889)
		(layer "In11.Cu")
		(net "M_M_DQS_DP<15>")
	)
	(arc
		(start 113.979452 -97.309686)
		(mid 114.18806 -97.521618)
		(end 114.473482 -97.605088)
		(width 0.0889)
		(layer "In11.Cu")
		(net "M_M_DQS_DP<15>")
	)
	(arc
		(start 113.114582 -96.234504)
		(mid 113.118613 -96.810686)
		(end 113.611152 -97.109534)
		(width 0.0889)
		(layer "In11.Cu")
		(net "M_M_DQS_DP<15>")
	)
	(arc
		(start 115.696492 -98.300286)
		(mid 115.9051 -98.512218)
		(end 116.190522 -98.595688)
		(width 0.0889)
		(layer "In11.Cu")
		(net "M_M_DQS_DP<15>")
	)
	(arc
		(start 113.120932 -93.842586)
		(mid 113.174402 -94.037649)
		(end 113.125758 -94.234)
		(width 0.0889)
		(layer "In11.Cu")
		(net "M_M_DQS_DP<15>")
	)
	(arc
		(start 114.506248 -97.605088)
		(mid 114.69789 -97.662254)
		(end 114.837972 -97.804986)
		(width 0.0889)
		(layer "In11.Cu")
		(net "M_M_DQS_DP<15>")
	)
	(arc
		(start 113.120932 -95.823786)
		(mid 113.174402 -96.018849)
		(end 113.125758 -96.2152)
		(width 0.0889)
		(layer "In11.Cu")
		(net "M_M_DQS_DP<15>")
	)
	(arc
		(start 113.120932 -95.232982)
		(mid 113.041801 -95.528384)
		(end 113.120932 -95.823786)
		(width 0.0889)
		(layer "In11.Cu")
		(net "M_M_DQS_DP<15>")
	)
	(arc
		(start 113.120932 -92.851986)
		(mid 113.174402 -93.047049)
		(end 113.125758 -93.2434)
		(width 0.0889)
		(layer "In11.Cu")
		(net "M_M_DQS_DP<15>")
	)
	(arc
		(start 113.120932 -90.870786)
		(mid 113.174402 -91.065849)
		(end 113.125758 -91.2622)
		(width 0.0889)
		(layer "In11.Cu")
		(net "M_M_DQS_DP<15>")
	)
	(arc
		(start 113.120932 -94.242636)
		(mid 113.04171 -94.531754)
		(end 113.114582 -94.822518)
		(width 0.0889)
		(layer "In11.Cu")
		(net "M_M_DQS_DP<15>")
	)
	(arc
		(start 114.837972 -97.804986)
		(mid 115.044976 -98.01585)
		(end 115.328192 -98.100134)
		(width 0.0889)
		(layer "In11.Cu")
		(net "M_M_DQS_DP<15>")
	)
	(arc
		(start 117.413532 -104.643682)
		(mid 117.334343 -104.930297)
		(end 117.404642 -105.219246)
		(width 0.0889)
		(layer "In11.Cu")
		(net "M_M_DQS_DP<15>")
	)
	(arc
		(start 113.120932 -94.833186)
		(mid 113.174431 -95.033084)
		(end 113.120932 -95.232982)
		(width 0.0889)
		(layer "In11.Cu")
		(net "M_M_DQS_DP<15>")
	)
	(arc
		(start 116.223288 -98.595688)
		(mid 116.41493 -98.652854)
		(end 116.555012 -98.795586)
		(width 0.0889)
		(layer "In11.Cu")
		(net "M_M_DQS_DP<15>")
	)
	(arc
		(start 117.413532 -100.281232)
		(mid 117.467031 -100.48113)
		(end 117.413532 -100.681028)
		(width 0.0889)
		(layer "In11.Cu")
		(net "M_M_DQS_DP<15>")
	)
	(arc
		(start 113.643918 -97.109534)
		(mid 113.837768 -97.165884)
		(end 113.979452 -97.309686)
		(width 0.0889)
		(layer "In11.Cu")
		(net "M_M_DQS_DP<15>")
	)
	(arc
		(start 113.114582 -92.272104)
		(mid 113.041784 -92.562867)
		(end 113.120932 -92.851986)
		(width 0.0889)
		(layer "In11.Cu")
		(net "M_M_DQS_DP<15>")
	)
	(arc
		(start 117.420644 -105.246678)
		(mid 117.46723 -105.435549)
		(end 117.419374 -105.624122)
		(width 0.0889)
		(layer "In11.Cu")
		(net "M_M_DQS_DP<15>")
	)
	(arc
		(start 117.413532 -103.653082)
		(mid 117.334343 -103.939697)
		(end 117.404642 -104.228646)
		(width 0.0889)
		(layer "In11.Cu")
		(net "M_M_DQS_DP<15>")
	)
	(arc
		(start 117.407182 -99.70135)
		(mid 117.334384 -99.992113)
		(end 117.413532 -100.281232)
		(width 0.0889)
		(layer "In11.Cu")
		(net "M_M_DQS_DP<15>")
	)
	(arc
		(start 115.360958 -98.100134)
		(mid 115.554808 -98.156484)
		(end 115.696492 -98.300286)
		(width 0.0889)
		(layer "In11.Cu")
		(net "M_M_DQS_DP<15>")
	)
	(arc
		(start 117.077998 -99.090734)
		(mid 117.416113 -99.295436)
		(end 117.413532 -99.690682)
		(width 0.0889)
		(layer "In11.Cu")
		(net "M_M_DQS_DP<15>")
	)
	(arc
		(start 117.42039 -104.256078)
		(mid 117.467066 -104.450779)
		(end 117.413532 -104.643682)
		(width 0.0889)
		(layer "In11.Cu")
		(net "M_M_DQS_DP<15>")
	)
	(arc
		(start 117.413532 -102.662482)
		(mid 117.334343 -102.949097)
		(end 117.404642 -103.238046)
		(width 0.0889)
		(layer "In11.Cu")
		(net "M_M_DQS_DP<15>")
	)
	(arc
		(start 117.418358 -102.271068)
		(mid 117.467113 -102.46742)
		(end 117.413532 -102.662482)
		(width 0.0889)
		(layer "In11.Cu")
		(net "M_M_DQS_DP<15>")
	)
	(segment
		(start 127.013462 -153.331672)
		(end 126.92888 -153.515568)
		(width 0.1651)
		(layer "F.Cu")
		(net "M_M_DQS_DP<14>")
	)
	(segment
		(start 127.44958 -152.895554)
		(end 127.013462 -153.331672)
		(width 0.1651)
		(layer "F.Cu")
		(net "M_M_DQS_DP<14>")
	)
	(segment
		(start 127.010414 -154.557984)
		(end 127.392176 -154.939746)
		(width 0.1651)
		(layer "F.Cu")
		(net "M_M_DQS_DP<14>")
	)
	(segment
		(start 127.44958 -152.273)
		(end 127.44958 -152.895554)
		(width 0.1651)
		(layer "F.Cu")
		(net "M_M_DQS_DP<14>")
	)
	(segment
		(start 126.92888 -154.333702)
		(end 127.010414 -154.557984)
		(width 0.1651)
		(layer "F.Cu")
		(net "M_M_DQS_DP<14>")
	)
	(segment
		(start 115.636802 -93.052138)
		(end 116.208302 -93.052138)
		(width 0.1651)
		(layer "F.Cu")
		(net "M_M_DQS_DP<14>")
	)
	(segment
		(start 126.92888 -153.515568)
		(end 126.92888 -154.333702)
		(width 0.1651)
		(layer "F.Cu")
		(net "M_M_DQS_DP<14>")
	)
	(via
		(at 127.392176 -154.939746)
		(size 0.508)
		(drill 0.254)
		(layers "F.Cu" "B.Cu")
		(net "M_M_DQS_DP<14>")
	)
	(via
		(at 127.392176 -149.4282)
		(size 0.508)
		(drill 0.254)
		(layers "F.Cu" "B.Cu")
		(net "M_M_DQS_DP<14>")
	)
	(via
		(at 116.208302 -93.052138)
		(size 0.508)
		(drill 0.254)
		(layers "F.Cu" "B.Cu")
		(net "M_M_DQS_DP<14>")
	)
	(segment
		(start 127.44958 -151.460454)
		(end 126.993396 -151.00427)
		(width 0.1651)
		(layer "B.Cu")
		(net "M_M_DQS_DP<14>")
	)
	(segment
		(start 127.44958 -152.078436)
		(end 127.44958 -151.460454)
		(width 0.1651)
		(layer "B.Cu")
		(net "M_M_DQS_DP<14>")
	)
	(segment
		(start 126.91618 -150.871936)
		(end 126.91618 -149.976332)
		(width 0.1651)
		(layer "B.Cu")
		(net "M_M_DQS_DP<14>")
	)
	(segment
		(start 126.91618 -149.976332)
		(end 127.003556 -149.81682)
		(width 0.1651)
		(layer "B.Cu")
		(net "M_M_DQS_DP<14>")
	)
	(segment
		(start 127.003556 -149.81682)
		(end 127.392176 -149.4282)
		(width 0.1651)
		(layer "B.Cu")
		(net "M_M_DQS_DP<14>")
	)
	(segment
		(start 126.993396 -151.00427)
		(end 126.91618 -150.871936)
		(width 0.1651)
		(layer "B.Cu")
		(net "M_M_DQS_DP<14>")
	)
	(segment
		(start 115.696492 -94.737936)
		(end 115.690142 -94.748604)
		(width 0.0889)
		(layer "In4.Cu")
		(net "M_M_DQS_DP<14>")
	)
	(segment
		(start 115.690142 -99.280218)
		(end 115.696492 -99.290886)
		(width 0.0889)
		(layer "In4.Cu")
		(net "M_M_DQS_DP<14>")
	)
	(segment
		(start 115.690142 -96.308418)
		(end 115.696492 -96.319086)
		(width 0.0889)
		(layer "In4.Cu")
		(net "M_M_DQS_DP<14>")
	)
	(segment
		(start 127.905256 -146.725386)
		(end 127.905256 -147.08378)
		(width 0.14224)
		(layer "In4.Cu")
		(net "M_M_DQS_DP<14>")
	)
	(segment
		(start 115.696492 -97.309686)
		(end 115.701318 -97.318322)
		(width 0.0889)
		(layer "In4.Cu")
		(net "M_M_DQS_DP<14>")
	)
	(segment
		(start 116.660422 -107.286298)
		(end 116.660422 -112.968024)
		(width 0.14224)
		(layer "In4.Cu")
		(net "M_M_DQS_DP<14>")
	)
	(segment
		(start 127.791718 -147.197318)
		(end 127.791718 -147.451318)
		(width 0.14224)
		(layer "In4.Cu")
		(net "M_M_DQS_DP<14>")
	)
	(segment
		(start 115.696492 -100.281486)
		(end 115.701318 -100.290122)
		(width 0.0889)
		(layer "In4.Cu")
		(net "M_M_DQS_DP<14>")
	)
	(segment
		(start 116.660422 -107.2642)
		(end 116.660422 -107.286298)
		(width 0.0889)
		(layer "In4.Cu")
		(net "M_M_DQS_DP<14>")
	)
	(segment
		(start 127.905256 -149.19452)
		(end 127.671576 -149.4282)
		(width 0.14224)
		(layer "In4.Cu")
		(net "M_M_DQS_DP<14>")
	)
	(segment
		(start 115.690142 -101.261418)
		(end 115.696492 -101.272086)
		(width 0.0889)
		(layer "In4.Cu")
		(net "M_M_DQS_DP<14>")
	)
	(segment
		(start 115.690142 -103.242618)
		(end 115.696492 -103.253286)
		(width 0.0889)
		(layer "In4.Cu")
		(net "M_M_DQS_DP<14>")
	)
	(segment
		(start 115.696492 -95.328486)
		(end 115.701318 -95.337122)
		(width 0.0889)
		(layer "In4.Cu")
		(net "M_M_DQS_DP<14>")
	)
	(segment
		(start 116.660422 -112.968024)
		(end 127.905256 -124.212858)
		(width 0.14224)
		(layer "In4.Cu")
		(net "M_M_DQS_DP<14>")
	)
	(segment
		(start 127.815086 -146.635216)
		(end 127.905256 -146.725386)
		(width 0.14224)
		(layer "In4.Cu")
		(net "M_M_DQS_DP<14>")
	)
	(segment
		(start 127.905256 -147.564856)
		(end 127.905256 -147.862798)
		(width 0.14224)
		(layer "In4.Cu")
		(net "M_M_DQS_DP<14>")
	)
	(segment
		(start 115.696492 -96.319086)
		(end 115.701318 -96.327722)
		(width 0.0889)
		(layer "In4.Cu")
		(net "M_M_DQS_DP<14>")
	)
	(segment
		(start 116.699792 -107.22483)
		(end 116.660422 -107.2642)
		(width 0.0889)
		(layer "In4.Cu")
		(net "M_M_DQS_DP<14>")
	)
	(segment
		(start 115.696492 -101.272086)
		(end 115.701318 -101.280722)
		(width 0.0889)
		(layer "In4.Cu")
		(net "M_M_DQS_DP<14>")
	)
	(segment
		(start 127.747776 -148.020278)
		(end 127.747776 -148.274278)
		(width 0.14224)
		(layer "In4.Cu")
		(net "M_M_DQS_DP<14>")
	)
	(segment
		(start 115.690142 -98.289618)
		(end 115.696492 -98.300286)
		(width 0.0889)
		(layer "In4.Cu")
		(net "M_M_DQS_DP<14>")
	)
	(segment
		(start 115.690142 -97.299018)
		(end 115.696492 -97.309686)
		(width 0.0889)
		(layer "In4.Cu")
		(net "M_M_DQS_DP<14>")
	)
	(segment
		(start 127.747776 -148.274278)
		(end 127.905256 -148.431758)
		(width 0.14224)
		(layer "In4.Cu")
		(net "M_M_DQS_DP<14>")
	)
	(segment
		(start 115.690142 -104.233218)
		(end 115.696492 -104.243886)
		(width 0.0889)
		(layer "In4.Cu")
		(net "M_M_DQS_DP<14>")
	)
	(segment
		(start 115.690142 -102.252018)
		(end 115.696492 -102.262686)
		(width 0.0889)
		(layer "In4.Cu")
		(net "M_M_DQS_DP<14>")
	)
	(segment
		(start 116.190522 -105.529888)
		(end 116.228622 -105.529888)
		(width 0.0889)
		(layer "In4.Cu")
		(net "M_M_DQS_DP<14>")
	)
	(segment
		(start 127.791718 -147.451318)
		(end 127.905256 -147.564856)
		(width 0.14224)
		(layer "In4.Cu")
		(net "M_M_DQS_DP<14>")
	)
	(segment
		(start 115.696492 -104.243886)
		(end 115.701318 -104.252522)
		(width 0.0889)
		(layer "In4.Cu")
		(net "M_M_DQS_DP<14>")
	)
	(segment
		(start 127.815086 -146.381216)
		(end 127.815086 -146.635216)
		(width 0.14224)
		(layer "In4.Cu")
		(net "M_M_DQS_DP<14>")
	)
	(segment
		(start 115.696492 -99.290886)
		(end 115.701318 -99.299522)
		(width 0.0889)
		(layer "In4.Cu")
		(net "M_M_DQS_DP<14>")
	)
	(segment
		(start 116.60886 -106.556302)
		(end 116.699792 -106.647234)
		(width 0.0889)
		(layer "In4.Cu")
		(net "M_M_DQS_DP<14>")
	)
	(segment
		(start 127.905256 -147.862798)
		(end 127.747776 -148.020278)
		(width 0.14224)
		(layer "In4.Cu")
		(net "M_M_DQS_DP<14>")
	)
	(segment
		(start 127.671576 -149.4282)
		(end 127.392176 -149.4282)
		(width 0.14224)
		(layer "In4.Cu")
		(net "M_M_DQS_DP<14>")
	)
	(segment
		(start 127.905256 -147.08378)
		(end 127.791718 -147.197318)
		(width 0.14224)
		(layer "In4.Cu")
		(net "M_M_DQS_DP<14>")
	)
	(segment
		(start 115.696492 -98.300286)
		(end 115.701318 -98.308922)
		(width 0.0889)
		(layer "In4.Cu")
		(net "M_M_DQS_DP<14>")
	)
	(segment
		(start 116.699792 -106.647234)
		(end 116.699792 -107.22483)
		(width 0.0889)
		(layer "In4.Cu")
		(net "M_M_DQS_DP<14>")
	)
	(segment
		(start 127.905256 -146.291046)
		(end 127.815086 -146.381216)
		(width 0.14224)
		(layer "In4.Cu")
		(net "M_M_DQS_DP<14>")
	)
	(segment
		(start 115.690142 -100.270818)
		(end 115.696492 -100.281486)
		(width 0.0889)
		(layer "In4.Cu")
		(net "M_M_DQS_DP<14>")
	)
	(segment
		(start 116.208302 -93.052138)
		(end 116.208302 -93.390212)
		(width 0.0889)
		(layer "In4.Cu")
		(net "M_M_DQS_DP<14>")
	)
	(segment
		(start 116.208302 -93.390212)
		(end 116.143278 -93.455236)
		(width 0.0889)
		(layer "In4.Cu")
		(net "M_M_DQS_DP<14>")
	)
	(segment
		(start 127.905256 -148.431758)
		(end 127.905256 -149.19452)
		(width 0.14224)
		(layer "In4.Cu")
		(net "M_M_DQS_DP<14>")
	)
	(segment
		(start 115.696492 -103.253286)
		(end 115.701318 -103.261922)
		(width 0.0889)
		(layer "In4.Cu")
		(net "M_M_DQS_DP<14>")
	)
	(segment
		(start 116.60886 -105.929684)
		(end 116.60886 -106.556302)
		(width 0.0889)
		(layer "In4.Cu")
		(net "M_M_DQS_DP<14>")
	)
	(segment
		(start 127.905256 -124.212858)
		(end 127.905256 -146.291046)
		(width 0.14224)
		(layer "In4.Cu")
		(net "M_M_DQS_DP<14>")
	)
	(segment
		(start 115.696492 -102.262686)
		(end 115.701318 -102.271322)
		(width 0.0889)
		(layer "In4.Cu")
		(net "M_M_DQS_DP<14>")
	)
	(arc
		(start 115.701318 -95.337122)
		(mid 115.750073 -95.533474)
		(end 115.696492 -95.728536)
		(width 0.0889)
		(layer "In4.Cu")
		(net "M_M_DQS_DP<14>")
	)
	(arc
		(start 115.701318 -103.261922)
		(mid 115.750073 -103.458274)
		(end 115.696492 -103.653336)
		(width 0.0889)
		(layer "In4.Cu")
		(net "M_M_DQS_DP<14>")
	)
	(arc
		(start 115.701318 -100.290122)
		(mid 115.750073 -100.486474)
		(end 115.696492 -100.681536)
		(width 0.0889)
		(layer "In4.Cu")
		(net "M_M_DQS_DP<14>")
	)
	(arc
		(start 115.696492 -103.653336)
		(mid 115.61727 -103.942454)
		(end 115.690142 -104.233218)
		(width 0.0889)
		(layer "In4.Cu")
		(net "M_M_DQS_DP<14>")
	)
	(arc
		(start 115.696492 -97.709736)
		(mid 115.61727 -97.998854)
		(end 115.690142 -98.289618)
		(width 0.0889)
		(layer "In4.Cu")
		(net "M_M_DQS_DP<14>")
	)
	(arc
		(start 115.701318 -104.252522)
		(mid 115.750073 -104.448874)
		(end 115.696492 -104.643936)
		(width 0.0889)
		(layer "In4.Cu")
		(net "M_M_DQS_DP<14>")
	)
	(arc
		(start 115.701318 -101.280722)
		(mid 115.750073 -101.477074)
		(end 115.696492 -101.672136)
		(width 0.0889)
		(layer "In4.Cu")
		(net "M_M_DQS_DP<14>")
	)
	(arc
		(start 115.696492 -101.672136)
		(mid 115.61727 -101.961254)
		(end 115.690142 -102.252018)
		(width 0.0889)
		(layer "In4.Cu")
		(net "M_M_DQS_DP<14>")
	)
	(arc
		(start 115.701318 -102.271322)
		(mid 115.750073 -102.467674)
		(end 115.696492 -102.662736)
		(width 0.0889)
		(layer "In4.Cu")
		(net "M_M_DQS_DP<14>")
	)
	(arc
		(start 115.701318 -96.327722)
		(mid 115.750073 -96.524074)
		(end 115.696492 -96.719136)
		(width 0.0889)
		(layer "In4.Cu")
		(net "M_M_DQS_DP<14>")
	)
	(arc
		(start 115.696492 -100.681536)
		(mid 115.61727 -100.970654)
		(end 115.690142 -101.261418)
		(width 0.0889)
		(layer "In4.Cu")
		(net "M_M_DQS_DP<14>")
	)
	(arc
		(start 115.696492 -104.643936)
		(mid 115.692163 -105.227108)
		(end 116.190522 -105.529888)
		(width 0.0889)
		(layer "In4.Cu")
		(net "M_M_DQS_DP<14>")
	)
	(arc
		(start 115.696492 -95.728536)
		(mid 115.61727 -96.017654)
		(end 115.690142 -96.308418)
		(width 0.0889)
		(layer "In4.Cu")
		(net "M_M_DQS_DP<14>")
	)
	(arc
		(start 115.696492 -96.719136)
		(mid 115.61727 -97.008254)
		(end 115.690142 -97.299018)
		(width 0.0889)
		(layer "In4.Cu")
		(net "M_M_DQS_DP<14>")
	)
	(arc
		(start 115.696492 -99.690936)
		(mid 115.61727 -99.980054)
		(end 115.690142 -100.270818)
		(width 0.0889)
		(layer "In4.Cu")
		(net "M_M_DQS_DP<14>")
	)
	(arc
		(start 116.143278 -93.455236)
		(mid 115.680918 -93.775806)
		(end 115.696492 -94.33814)
		(width 0.0889)
		(layer "In4.Cu")
		(net "M_M_DQS_DP<14>")
	)
	(arc
		(start 115.701318 -98.308922)
		(mid 115.750073 -98.505274)
		(end 115.696492 -98.700336)
		(width 0.0889)
		(layer "In4.Cu")
		(net "M_M_DQS_DP<14>")
	)
	(arc
		(start 115.696492 -94.33814)
		(mid 115.749991 -94.538038)
		(end 115.696492 -94.737936)
		(width 0.0889)
		(layer "In4.Cu")
		(net "M_M_DQS_DP<14>")
	)
	(arc
		(start 116.228622 -105.529888)
		(mid 116.498553 -105.653881)
		(end 116.60886 -105.929684)
		(width 0.0889)
		(layer "In4.Cu")
		(net "M_M_DQS_DP<14>")
	)
	(arc
		(start 115.701318 -97.318322)
		(mid 115.750073 -97.514674)
		(end 115.696492 -97.709736)
		(width 0.0889)
		(layer "In4.Cu")
		(net "M_M_DQS_DP<14>")
	)
	(arc
		(start 115.696492 -98.700336)
		(mid 115.61727 -98.989454)
		(end 115.690142 -99.280218)
		(width 0.0889)
		(layer "In4.Cu")
		(net "M_M_DQS_DP<14>")
	)
	(arc
		(start 115.690142 -94.748604)
		(mid 115.617344 -95.039367)
		(end 115.696492 -95.328486)
		(width 0.0889)
		(layer "In4.Cu")
		(net "M_M_DQS_DP<14>")
	)
	(arc
		(start 115.696492 -102.662736)
		(mid 115.61727 -102.951854)
		(end 115.690142 -103.242618)
		(width 0.0889)
		(layer "In4.Cu")
		(net "M_M_DQS_DP<14>")
	)
	(arc
		(start 115.701318 -99.299522)
		(mid 115.750073 -99.495874)
		(end 115.696492 -99.690936)
		(width 0.0889)
		(layer "In4.Cu")
		(net "M_M_DQS_DP<14>")
	)
	(segment
		(start 127.319024 -149.4282)
		(end 126.887224 -149.86)
		(width 0.14224)
		(layer "In11.Cu")
		(net "M_M_DQS_DP<14>")
	)
	(segment
		(start 126.887224 -149.86)
		(end 126.887224 -154.434794)
		(width 0.14224)
		(layer "In11.Cu")
		(net "M_M_DQS_DP<14>")
	)
	(segment
		(start 126.887224 -154.434794)
		(end 127.392176 -154.939746)
		(width 0.14224)
		(layer "In11.Cu")
		(net "M_M_DQS_DP<14>")
	)
	(segment
		(start 127.392176 -149.4282)
		(end 127.319024 -149.4282)
		(width 0.14224)
		(layer "In11.Cu")
		(net "M_M_DQS_DP<14>")
	)
	(segment
		(start 117.578632 -154.333702)
		(end 117.660166 -154.557984)
		(width 0.1651)
		(layer "F.Cu")
		(net "M_M_DQS_DP<13>")
	)
	(segment
		(start 117.663214 -153.331926)
		(end 117.578632 -153.515568)
		(width 0.1651)
		(layer "F.Cu")
		(net "M_M_DQS_DP<13>")
	)
	(segment
		(start 118.099332 -152.895808)
		(end 117.663214 -153.331926)
		(width 0.1651)
		(layer "F.Cu")
		(net "M_M_DQS_DP<13>")
	)
	(segment
		(start 118.099332 -152.273)
		(end 118.099332 -152.895808)
		(width 0.1651)
		(layer "F.Cu")
		(net "M_M_DQS_DP<13>")
	)
	(segment
		(start 117.578632 -153.515568)
		(end 117.578632 -154.333702)
		(width 0.1651)
		(layer "F.Cu")
		(net "M_M_DQS_DP<13>")
	)
	(segment
		(start 117.660166 -154.557984)
		(end 118.041928 -154.939746)
		(width 0.1651)
		(layer "F.Cu")
		(net "M_M_DQS_DP<13>")
	)
	(segment
		(start 108.768896 -92.061538)
		(end 109.340396 -92.061538)
		(width 0.1651)
		(layer "F.Cu")
		(net "M_M_DQS_DP<13>")
	)
	(via
		(at 109.340396 -92.061538)
		(size 0.508)
		(drill 0.254)
		(layers "F.Cu" "B.Cu")
		(net "M_M_DQS_DP<13>")
	)
	(via
		(at 118.041928 -154.939746)
		(size 0.508)
		(drill 0.254)
		(layers "F.Cu" "B.Cu")
		(net "M_M_DQS_DP<13>")
	)
	(via
		(at 118.041928 -149.4282)
		(size 0.508)
		(drill 0.254)
		(layers "F.Cu" "B.Cu")
		(net "M_M_DQS_DP<13>")
	)
	(segment
		(start 118.099332 -151.460454)
		(end 117.643148 -151.00427)
		(width 0.1651)
		(layer "B.Cu")
		(net "M_M_DQS_DP<13>")
	)
	(segment
		(start 117.653308 -149.81682)
		(end 118.041928 -149.4282)
		(width 0.1651)
		(layer "B.Cu")
		(net "M_M_DQS_DP<13>")
	)
	(segment
		(start 117.565932 -150.871936)
		(end 117.565932 -149.976332)
		(width 0.1651)
		(layer "B.Cu")
		(net "M_M_DQS_DP<13>")
	)
	(segment
		(start 117.565932 -149.976332)
		(end 117.653308 -149.81682)
		(width 0.1651)
		(layer "B.Cu")
		(net "M_M_DQS_DP<13>")
	)
	(segment
		(start 118.099332 -152.078436)
		(end 118.099332 -151.460454)
		(width 0.1651)
		(layer "B.Cu")
		(net "M_M_DQS_DP<13>")
	)
	(segment
		(start 117.643148 -151.00427)
		(end 117.565932 -150.871936)
		(width 0.1651)
		(layer "B.Cu")
		(net "M_M_DQS_DP<13>")
	)
	(segment
		(start 118.041928 -149.4282)
		(end 117.96903 -149.4282)
		(width 0.14224)
		(layer "In11.Cu")
		(net "M_M_DQS_DP<13>")
	)
	(segment
		(start 118.440454 -143.587724)
		(end 118.555262 -143.702532)
		(width 0.14224)
		(layer "In11.Cu")
		(net "M_M_DQS_DP<13>")
	)
	(segment
		(start 108.828586 -100.28174)
		(end 109.004354 -100.586286)
		(width 0.0889)
		(layer "In11.Cu")
		(net "M_M_DQS_DP<13>")
	)
	(segment
		(start 118.555262 -148.499576)
		(end 118.555262 -148.964396)
		(width 0.14224)
		(layer "In11.Cu")
		(net "M_M_DQS_DP<13>")
	)
	(segment
		(start 118.555262 -126.925832)
		(end 118.555262 -143.218916)
		(width 0.14224)
		(layer "In11.Cu")
		(net "M_M_DQS_DP<13>")
	)
	(segment
		(start 118.1481 -125.94336)
		(end 118.351554 -126.434596)
		(width 0.14224)
		(layer "In11.Cu")
		(net "M_M_DQS_DP<13>")
	)
	(segment
		(start 109.605318 -116.194078)
		(end 115.148614 -121.737374)
		(width 0.14224)
		(layer "In11.Cu")
		(net "M_M_DQS_DP<13>")
	)
	(segment
		(start 107.963716 -94.822518)
		(end 107.970066 -94.833186)
		(width 0.0889)
		(layer "In11.Cu")
		(net "M_M_DQS_DP<13>")
	)
	(segment
		(start 118.555262 -147.107656)
		(end 118.397782 -147.265136)
		(width 0.14224)
		(layer "In11.Cu")
		(net "M_M_DQS_DP<13>")
	)
	(segment
		(start 107.970066 -96.223836)
		(end 107.963716 -96.234504)
		(width 0.0889)
		(layer "In11.Cu")
		(net "M_M_DQS_DP<13>")
	)
	(segment
		(start 118.397782 -147.265136)
		(end 118.397782 -147.519136)
		(width 0.14224)
		(layer "In11.Cu")
		(net "M_M_DQS_DP<13>")
	)
	(segment
		(start 117.96903 -149.4282)
		(end 117.911372 -149.485604)
		(width 0.14224)
		(layer "In11.Cu")
		(net "M_M_DQS_DP<13>")
	)
	(segment
		(start 109.340396 -92.399612)
		(end 109.275372 -92.464636)
		(width 0.0889)
		(layer "In11.Cu")
		(net "M_M_DQS_DP<13>")
	)
	(segment
		(start 118.555262 -143.702532)
		(end 118.555262 -146.3167)
		(width 0.14224)
		(layer "In11.Cu")
		(net "M_M_DQS_DP<13>")
	)
	(segment
		(start 118.091458 -149.4282)
		(end 118.041928 -149.4282)
		(width 0.14224)
		(layer "In11.Cu")
		(net "M_M_DQS_DP<13>")
	)
	(segment
		(start 109.605318 -104.771698)
		(end 109.605318 -104.793796)
		(width 0.0889)
		(layer "In11.Cu")
		(net "M_M_DQS_DP<13>")
	)
	(segment
		(start 118.429786 -146.696176)
		(end 118.555262 -146.821652)
		(width 0.14224)
		(layer "In11.Cu")
		(net "M_M_DQS_DP<13>")
	)
	(segment
		(start 108.496862 -93.947234)
		(end 108.468922 -93.947234)
		(width 0.0889)
		(layer "In11.Cu")
		(net "M_M_DQS_DP<13>")
	)
	(segment
		(start 118.429786 -146.442176)
		(end 118.429786 -146.696176)
		(width 0.14224)
		(layer "In11.Cu")
		(net "M_M_DQS_DP<13>")
	)
	(segment
		(start 107.970066 -99.195636)
		(end 107.963716 -99.206304)
		(width 0.0889)
		(layer "In11.Cu")
		(net "M_M_DQS_DP<13>")
	)
	(segment
		(start 118.397782 -147.519136)
		(end 118.555262 -147.676616)
		(width 0.14224)
		(layer "In11.Cu")
		(net "M_M_DQS_DP<13>")
	)
	(segment
		(start 109.605318 -104.793796)
		(end 109.605318 -116.194078)
		(width 0.14224)
		(layer "In11.Cu")
		(net "M_M_DQS_DP<13>")
	)
	(segment
		(start 109.340396 -92.061538)
		(end 109.340396 -92.399612)
		(width 0.0889)
		(layer "In11.Cu")
		(net "M_M_DQS_DP<13>")
	)
	(segment
		(start 118.555262 -146.821652)
		(end 118.555262 -147.107656)
		(width 0.14224)
		(layer "In11.Cu")
		(net "M_M_DQS_DP<13>")
	)
	(segment
		(start 115.148614 -122.94362)
		(end 118.1481 -125.94336)
		(width 0.14224)
		(layer "In11.Cu")
		(net "M_M_DQS_DP<13>")
	)
	(segment
		(start 108.828586 -93.347286)
		(end 108.833412 -93.355922)
		(width 0.0889)
		(layer "In11.Cu")
		(net "M_M_DQS_DP<13>")
	)
	(segment
		(start 109.644688 -101.22662)
		(end 109.644688 -104.732328)
		(width 0.0889)
		(layer "In11.Cu")
		(net "M_M_DQS_DP<13>")
	)
	(segment
		(start 109.644688 -104.732328)
		(end 109.605318 -104.771698)
		(width 0.0889)
		(layer "In11.Cu")
		(net "M_M_DQS_DP<13>")
	)
	(segment
		(start 107.974892 -99.187)
		(end 107.970066 -99.195636)
		(width 0.0889)
		(layer "In11.Cu")
		(net "M_M_DQS_DP<13>")
	)
	(segment
		(start 107.974892 -97.2058)
		(end 107.970066 -97.214436)
		(width 0.0889)
		(layer "In11.Cu")
		(net "M_M_DQS_DP<13>")
	)
	(segment
		(start 118.555262 -143.218916)
		(end 118.440454 -143.333724)
		(width 0.14224)
		(layer "In11.Cu")
		(net "M_M_DQS_DP<13>")
	)
	(segment
		(start 107.970066 -97.214436)
		(end 107.963716 -97.225104)
		(width 0.0889)
		(layer "In11.Cu")
		(net "M_M_DQS_DP<13>")
	)
	(segment
		(start 118.351554 -126.434596)
		(end 118.450868 -126.674118)
		(width 0.14224)
		(layer "In11.Cu")
		(net "M_M_DQS_DP<13>")
	)
	(segment
		(start 107.970066 -98.205036)
		(end 107.963716 -98.215704)
		(width 0.0889)
		(layer "In11.Cu")
		(net "M_M_DQS_DP<13>")
	)
	(segment
		(start 118.555262 -147.930616)
		(end 118.397782 -148.088096)
		(width 0.14224)
		(layer "In11.Cu")
		(net "M_M_DQS_DP<13>")
	)
	(segment
		(start 107.974892 -96.2152)
		(end 107.970066 -96.223836)
		(width 0.0889)
		(layer "In11.Cu")
		(net "M_M_DQS_DP<13>")
	)
	(segment
		(start 108.822236 -93.336618)
		(end 108.828586 -93.347286)
		(width 0.0889)
		(layer "In11.Cu")
		(net "M_M_DQS_DP<13>")
	)
	(segment
		(start 118.397782 -148.342096)
		(end 118.555262 -148.499576)
		(width 0.14224)
		(layer "In11.Cu")
		(net "M_M_DQS_DP<13>")
	)
	(segment
		(start 108.468922 -100.081588)
		(end 108.486702 -100.081588)
		(width 0.0889)
		(layer "In11.Cu")
		(net "M_M_DQS_DP<13>")
	)
	(segment
		(start 118.440454 -143.333724)
		(end 118.440454 -143.587724)
		(width 0.14224)
		(layer "In11.Cu")
		(net "M_M_DQS_DP<13>")
	)
	(segment
		(start 115.148614 -121.737374)
		(end 115.148614 -122.94362)
		(width 0.14224)
		(layer "In11.Cu")
		(net "M_M_DQS_DP<13>")
	)
	(segment
		(start 118.555262 -146.3167)
		(end 118.429786 -146.442176)
		(width 0.14224)
		(layer "In11.Cu")
		(net "M_M_DQS_DP<13>")
	)
	(segment
		(start 109.004354 -100.586286)
		(end 109.644688 -101.22662)
		(width 0.0889)
		(layer "In11.Cu")
		(net "M_M_DQS_DP<13>")
	)
	(segment
		(start 118.555262 -147.676616)
		(end 118.555262 -147.930616)
		(width 0.14224)
		(layer "In11.Cu")
		(net "M_M_DQS_DP<13>")
	)
	(segment
		(start 117.53723 -149.86)
		(end 117.53723 -154.435048)
		(width 0.14224)
		(layer "In11.Cu")
		(net "M_M_DQS_DP<13>")
	)
	(segment
		(start 117.53723 -154.435048)
		(end 118.041928 -154.939746)
		(width 0.14224)
		(layer "In11.Cu")
		(net "M_M_DQS_DP<13>")
	)
	(segment
		(start 117.911372 -149.485604)
		(end 117.53723 -149.86)
		(width 0.14224)
		(layer "In11.Cu")
		(net "M_M_DQS_DP<13>")
	)
	(segment
		(start 118.555262 -148.964396)
		(end 118.091458 -149.4282)
		(width 0.14224)
		(layer "In11.Cu")
		(net "M_M_DQS_DP<13>")
	)
	(segment
		(start 118.397782 -148.088096)
		(end 118.397782 -148.342096)
		(width 0.14224)
		(layer "In11.Cu")
		(net "M_M_DQS_DP<13>")
	)
	(segment
		(start 107.974892 -98.1964)
		(end 107.970066 -98.205036)
		(width 0.0889)
		(layer "In11.Cu")
		(net "M_M_DQS_DP<13>")
	)
	(segment
		(start 118.450868 -126.674118)
		(end 118.555262 -126.925832)
		(width 0.14224)
		(layer "In11.Cu")
		(net "M_M_DQS_DP<13>")
	)
	(arc
		(start 107.970066 -94.833186)
		(mid 108.023565 -95.033084)
		(end 107.970066 -95.232982)
		(width 0.0889)
		(layer "In11.Cu")
		(net "M_M_DQS_DP<13>")
	)
	(arc
		(start 107.963716 -97.225104)
		(mid 107.890918 -97.515867)
		(end 107.970066 -97.804986)
		(width 0.0889)
		(layer "In11.Cu")
		(net "M_M_DQS_DP<13>")
	)
	(arc
		(start 109.275372 -92.464636)
		(mid 108.815895 -92.779585)
		(end 108.822236 -93.336618)
		(width 0.0889)
		(layer "In11.Cu")
		(net "M_M_DQS_DP<13>")
	)
	(arc
		(start 107.963716 -96.234504)
		(mid 107.890918 -96.525267)
		(end 107.970066 -96.814386)
		(width 0.0889)
		(layer "In11.Cu")
		(net "M_M_DQS_DP<13>")
	)
	(arc
		(start 107.963716 -98.215704)
		(mid 107.890918 -98.506467)
		(end 107.970066 -98.795586)
		(width 0.0889)
		(layer "In11.Cu")
		(net "M_M_DQS_DP<13>")
	)
	(arc
		(start 108.468922 -93.947234)
		(mid 107.970041 -94.242671)
		(end 107.963716 -94.822518)
		(width 0.0889)
		(layer "In11.Cu")
		(net "M_M_DQS_DP<13>")
	)
	(arc
		(start 107.970066 -98.795586)
		(mid 108.023536 -98.990649)
		(end 107.974892 -99.187)
		(width 0.0889)
		(layer "In11.Cu")
		(net "M_M_DQS_DP<13>")
	)
	(arc
		(start 107.970066 -95.232982)
		(mid 107.890935 -95.528384)
		(end 107.970066 -95.823786)
		(width 0.0889)
		(layer "In11.Cu")
		(net "M_M_DQS_DP<13>")
	)
	(arc
		(start 107.970066 -97.804986)
		(mid 108.023536 -98.000049)
		(end 107.974892 -98.1964)
		(width 0.0889)
		(layer "In11.Cu")
		(net "M_M_DQS_DP<13>")
	)
	(arc
		(start 108.486702 -100.081588)
		(mid 108.684137 -100.136411)
		(end 108.828586 -100.28174)
		(width 0.0889)
		(layer "In11.Cu")
		(net "M_M_DQS_DP<13>")
	)
	(arc
		(start 107.963716 -99.206304)
		(mid 107.969893 -99.786236)
		(end 108.468922 -100.081588)
		(width 0.0889)
		(layer "In11.Cu")
		(net "M_M_DQS_DP<13>")
	)
	(arc
		(start 107.970066 -95.823786)
		(mid 108.023536 -96.018849)
		(end 107.974892 -96.2152)
		(width 0.0889)
		(layer "In11.Cu")
		(net "M_M_DQS_DP<13>")
	)
	(arc
		(start 107.970066 -96.814386)
		(mid 108.023536 -97.009449)
		(end 107.974892 -97.2058)
		(width 0.0889)
		(layer "In11.Cu")
		(net "M_M_DQS_DP<13>")
	)
	(arc
		(start 108.833412 -93.355922)
		(mid 108.829665 -93.745178)
		(end 108.496862 -93.947234)
		(width 0.0889)
		(layer "In11.Cu")
		(net "M_M_DQS_DP<13>")
	)
	(segment
		(start 62.413388 -153.331672)
		(end 62.328806 -153.515568)
		(width 0.1651)
		(layer "F.Cu")
		(net "M_M_DQS_DP<12>")
	)
	(segment
		(start 62.41034 -154.557984)
		(end 62.792102 -154.939746)
		(width 0.1651)
		(layer "F.Cu")
		(net "M_M_DQS_DP<12>")
	)
	(segment
		(start 62.849506 -152.895554)
		(end 62.413388 -153.331672)
		(width 0.1651)
		(layer "F.Cu")
		(net "M_M_DQS_DP<12>")
	)
	(segment
		(start 85.777832 -84.812886)
		(end 85.206332 -84.812886)
		(width 0.1651)
		(layer "F.Cu")
		(net "M_M_DQS_DP<12>")
	)
	(segment
		(start 62.328806 -153.515568)
		(end 62.328806 -154.333702)
		(width 0.1651)
		(layer "F.Cu")
		(net "M_M_DQS_DP<12>")
	)
	(segment
		(start 62.328806 -154.333702)
		(end 62.41034 -154.557984)
		(width 0.1651)
		(layer "F.Cu")
		(net "M_M_DQS_DP<12>")
	)
	(segment
		(start 62.849506 -152.273)
		(end 62.849506 -152.895554)
		(width 0.1651)
		(layer "F.Cu")
		(net "M_M_DQS_DP<12>")
	)
	(via
		(at 85.206332 -84.812886)
		(size 0.508)
		(drill 0.254)
		(layers "F.Cu" "B.Cu")
		(net "M_M_DQS_DP<12>")
	)
	(via
		(at 62.792102 -154.939746)
		(size 0.508)
		(drill 0.254)
		(layers "F.Cu" "B.Cu")
		(net "M_M_DQS_DP<12>")
	)
	(via
		(at 62.792102 -149.4282)
		(size 0.508)
		(drill 0.254)
		(layers "F.Cu" "B.Cu")
		(net "M_M_DQS_DP<12>")
	)
	(segment
		(start 62.849506 -152.078436)
		(end 62.849506 -151.460454)
		(width 0.1651)
		(layer "B.Cu")
		(net "M_M_DQS_DP<12>")
	)
	(segment
		(start 62.316106 -149.976332)
		(end 62.403482 -149.81682)
		(width 0.1651)
		(layer "B.Cu")
		(net "M_M_DQS_DP<12>")
	)
	(segment
		(start 62.849506 -151.460454)
		(end 62.393322 -151.00427)
		(width 0.1651)
		(layer "B.Cu")
		(net "M_M_DQS_DP<12>")
	)
	(segment
		(start 62.393322 -151.00427)
		(end 62.316106 -150.871936)
		(width 0.1651)
		(layer "B.Cu")
		(net "M_M_DQS_DP<12>")
	)
	(segment
		(start 62.316106 -150.871936)
		(end 62.316106 -149.976332)
		(width 0.1651)
		(layer "B.Cu")
		(net "M_M_DQS_DP<12>")
	)
	(segment
		(start 62.403482 -149.81682)
		(end 62.792102 -149.4282)
		(width 0.1651)
		(layer "B.Cu")
		(net "M_M_DQS_DP<12>")
	)
	(segment
		(start 63.305182 -147.818856)
		(end 63.305182 -148.072856)
		(width 0.14224)
		(layer "In11.Cu")
		(net "M_M_DQS_DP<12>")
	)
	(segment
		(start 63.183262 -148.448776)
		(end 63.305182 -148.570696)
		(width 0.14224)
		(layer "In11.Cu")
		(net "M_M_DQS_DP<12>")
	)
	(segment
		(start 84.694522 -87.489538)
		(end 84.688172 -87.500206)
		(width 0.0889)
		(layer "In11.Cu")
		(net "M_M_DQS_DP<12>")
	)
	(segment
		(start 63.81877 -123.384564)
		(end 63.305182 -124.624846)
		(width 0.14224)
		(layer "In11.Cu")
		(net "M_M_DQS_DP<12>")
	)
	(segment
		(start 76.304648 -114.200686)
		(end 70.231254 -120.27408)
		(width 0.14224)
		(layer "In11.Cu")
		(net "M_M_DQS_DP<12>")
	)
	(segment
		(start 80.34401 -99.97186)
		(end 80.0862 -100.439728)
		(width 0.0889)
		(layer "In11.Cu")
		(net "M_M_DQS_DP<12>")
	)
	(segment
		(start 63.183262 -148.194776)
		(end 63.183262 -148.448776)
		(width 0.14224)
		(layer "In11.Cu")
		(net "M_M_DQS_DP<12>")
	)
	(segment
		(start 80.04683 -103.1748)
		(end 80.04683 -103.196898)
		(width 0.0889)
		(layer "In11.Cu")
		(net "M_M_DQS_DP<12>")
	)
	(segment
		(start 83.836002 -95.509588)
		(end 83.840828 -95.518224)
		(width 0.0889)
		(layer "In11.Cu")
		(net "M_M_DQS_DP<12>")
	)
	(segment
		(start 80.47228 -99.749864)
		(end 80.34401 -99.97186)
		(width 0.0889)
		(layer "In11.Cu")
		(net "M_M_DQS_DP<12>")
	)
	(segment
		(start 81.581752 -98.343974)
		(end 81.581752 -99.085908)
		(width 0.0889)
		(layer "In11.Cu")
		(net "M_M_DQS_DP<12>")
	)
	(segment
		(start 76.304648 -108.7501)
		(end 76.304648 -114.200686)
		(width 0.14224)
		(layer "In11.Cu")
		(net "M_M_DQS_DP<12>")
	)
	(segment
		(start 83.836002 -93.928438)
		(end 83.829652 -93.939106)
		(width 0.0889)
		(layer "In11.Cu")
		(net "M_M_DQS_DP<12>")
	)
	(segment
		(start 62.28715 -149.86)
		(end 62.28715 -154.434794)
		(width 0.14224)
		(layer "In11.Cu")
		(net "M_M_DQS_DP<12>")
	)
	(segment
		(start 63.305182 -147.321016)
		(end 63.183262 -147.442936)
		(width 0.14224)
		(layer "In11.Cu")
		(net "M_M_DQS_DP<12>")
	)
	(segment
		(start 80.473296 -99.748086)
		(end 80.47228 -99.749864)
		(width 0.0889)
		(layer "In11.Cu")
		(net "M_M_DQS_DP<12>")
	)
	(segment
		(start 66.929254 -120.27408)
		(end 63.81877 -123.384564)
		(width 0.14224)
		(layer "In11.Cu")
		(net "M_M_DQS_DP<12>")
	)
	(segment
		(start 63.183262 -147.442936)
		(end 63.183262 -147.696936)
		(width 0.14224)
		(layer "In11.Cu")
		(net "M_M_DQS_DP<12>")
	)
	(segment
		(start 63.183262 -146.945096)
		(end 63.305182 -147.067016)
		(width 0.14224)
		(layer "In11.Cu")
		(net "M_M_DQS_DP<12>")
	)
	(segment
		(start 62.28715 -154.434794)
		(end 62.792102 -154.939746)
		(width 0.14224)
		(layer "In11.Cu")
		(net "M_M_DQS_DP<12>")
	)
	(segment
		(start 63.305182 -146.569176)
		(end 63.183262 -146.691096)
		(width 0.14224)
		(layer "In11.Cu")
		(net "M_M_DQS_DP<12>")
	)
	(segment
		(start 63.183262 -146.691096)
		(end 63.183262 -146.945096)
		(width 0.14224)
		(layer "In11.Cu")
		(net "M_M_DQS_DP<12>")
	)
	(segment
		(start 80.04683 -103.196898)
		(end 80.04683 -105.008426)
		(width 0.14224)
		(layer "In11.Cu")
		(net "M_M_DQS_DP<12>")
	)
	(segment
		(start 80.0862 -100.439728)
		(end 80.0862 -103.13543)
		(width 0.0889)
		(layer "In11.Cu")
		(net "M_M_DQS_DP<12>")
	)
	(segment
		(start 83.829652 -95.49892)
		(end 83.836002 -95.509588)
		(width 0.0889)
		(layer "In11.Cu")
		(net "M_M_DQS_DP<12>")
	)
	(segment
		(start 81.09077 -99.57689)
		(end 80.644492 -99.57689)
		(width 0.0889)
		(layer "In11.Cu")
		(net "M_M_DQS_DP<12>")
	)
	(segment
		(start 63.305182 -148.072856)
		(end 63.183262 -148.194776)
		(width 0.14224)
		(layer "In11.Cu")
		(net "M_M_DQS_DP<12>")
	)
	(segment
		(start 84.694522 -89.470738)
		(end 84.688172 -89.481406)
		(width 0.0889)
		(layer "In11.Cu")
		(net "M_M_DQS_DP<12>")
	)
	(segment
		(start 63.305182 -148.570696)
		(end 63.305182 -149.201886)
		(width 0.14224)
		(layer "In11.Cu")
		(net "M_M_DQS_DP<12>")
	)
	(segment
		(start 84.694522 -91.451938)
		(end 84.688172 -91.462606)
		(width 0.0889)
		(layer "In11.Cu")
		(net "M_M_DQS_DP<12>")
	)
	(segment
		(start 85.206332 -84.812886)
		(end 85.206332 -85.15096)
		(width 0.0889)
		(layer "In11.Cu")
		(net "M_M_DQS_DP<12>")
	)
	(segment
		(start 80.04683 -105.008426)
		(end 76.305156 -108.7501)
		(width 0.14224)
		(layer "In11.Cu")
		(net "M_M_DQS_DP<12>")
	)
	(segment
		(start 81.581752 -99.085908)
		(end 81.09077 -99.57689)
		(width 0.0889)
		(layer "In11.Cu")
		(net "M_M_DQS_DP<12>")
	)
	(segment
		(start 84.694522 -88.480138)
		(end 84.688172 -88.490806)
		(width 0.0889)
		(layer "In11.Cu")
		(net "M_M_DQS_DP<12>")
	)
	(segment
		(start 80.644492 -99.57689)
		(end 80.473296 -99.748086)
		(width 0.0889)
		(layer "In11.Cu")
		(net "M_M_DQS_DP<12>")
	)
	(segment
		(start 62.71895 -149.4282)
		(end 62.28715 -149.86)
		(width 0.14224)
		(layer "In11.Cu")
		(net "M_M_DQS_DP<12>")
	)
	(segment
		(start 63.305182 -147.067016)
		(end 63.305182 -147.321016)
		(width 0.14224)
		(layer "In11.Cu")
		(net "M_M_DQS_DP<12>")
	)
	(segment
		(start 84.358988 -92.64269)
		(end 84.326222 -92.64269)
		(width 0.0889)
		(layer "In11.Cu")
		(net "M_M_DQS_DP<12>")
	)
	(segment
		(start 84.699348 -88.471502)
		(end 84.694522 -88.480138)
		(width 0.0889)
		(layer "In11.Cu")
		(net "M_M_DQS_DP<12>")
	)
	(segment
		(start 63.305182 -149.201886)
		(end 63.078868 -149.4282)
		(width 0.14224)
		(layer "In11.Cu")
		(net "M_M_DQS_DP<12>")
	)
	(segment
		(start 84.694522 -86.498938)
		(end 84.688172 -86.509606)
		(width 0.0889)
		(layer "In11.Cu")
		(net "M_M_DQS_DP<12>")
	)
	(segment
		(start 83.836002 -94.518988)
		(end 83.840828 -94.527624)
		(width 0.0889)
		(layer "In11.Cu")
		(net "M_M_DQS_DP<12>")
	)
	(segment
		(start 63.305182 -124.624846)
		(end 63.305182 -146.569176)
		(width 0.14224)
		(layer "In11.Cu")
		(net "M_M_DQS_DP<12>")
	)
	(segment
		(start 63.183262 -147.696936)
		(end 63.305182 -147.818856)
		(width 0.14224)
		(layer "In11.Cu")
		(net "M_M_DQS_DP<12>")
	)
	(segment
		(start 85.206332 -85.15096)
		(end 85.141054 -85.216238)
		(width 0.0889)
		(layer "In11.Cu")
		(net "M_M_DQS_DP<12>")
	)
	(segment
		(start 84.694522 -90.461338)
		(end 84.688172 -90.472006)
		(width 0.0889)
		(layer "In11.Cu")
		(net "M_M_DQS_DP<12>")
	)
	(segment
		(start 84.699348 -87.480902)
		(end 84.694522 -87.489538)
		(width 0.0889)
		(layer "In11.Cu")
		(net "M_M_DQS_DP<12>")
	)
	(segment
		(start 84.699348 -90.452702)
		(end 84.694522 -90.461338)
		(width 0.0889)
		(layer "In11.Cu")
		(net "M_M_DQS_DP<12>")
	)
	(segment
		(start 84.699348 -86.490302)
		(end 84.694522 -86.498938)
		(width 0.0889)
		(layer "In11.Cu")
		(net "M_M_DQS_DP<12>")
	)
	(segment
		(start 83.836002 -95.909638)
		(end 83.589368 -96.336358)
		(width 0.0889)
		(layer "In11.Cu")
		(net "M_M_DQS_DP<12>")
	)
	(segment
		(start 62.792102 -149.4282)
		(end 62.71895 -149.4282)
		(width 0.14224)
		(layer "In11.Cu")
		(net "M_M_DQS_DP<12>")
	)
	(segment
		(start 80.0862 -103.13543)
		(end 80.04683 -103.1748)
		(width 0.0889)
		(layer "In11.Cu")
		(net "M_M_DQS_DP<12>")
	)
	(segment
		(start 70.231254 -120.27408)
		(end 66.929254 -120.27408)
		(width 0.14224)
		(layer "In11.Cu")
		(net "M_M_DQS_DP<12>")
	)
	(segment
		(start 63.078868 -149.4282)
		(end 62.792102 -149.4282)
		(width 0.14224)
		(layer "In11.Cu")
		(net "M_M_DQS_DP<12>")
	)
	(segment
		(start 83.589368 -96.336358)
		(end 81.581752 -98.343974)
		(width 0.0889)
		(layer "In11.Cu")
		(net "M_M_DQS_DP<12>")
	)
	(segment
		(start 76.305156 -108.7501)
		(end 76.304648 -108.7501)
		(width 0.14224)
		(layer "In11.Cu")
		(net "M_M_DQS_DP<12>")
	)
	(segment
		(start 84.699348 -89.462102)
		(end 84.694522 -89.470738)
		(width 0.0889)
		(layer "In11.Cu")
		(net "M_M_DQS_DP<12>")
	)
	(segment
		(start 84.699348 -91.443302)
		(end 84.694522 -91.451938)
		(width 0.0889)
		(layer "In11.Cu")
		(net "M_M_DQS_DP<12>")
	)
	(arc
		(start 84.694522 -87.089488)
		(mid 84.747992 -87.284551)
		(end 84.699348 -87.480902)
		(width 0.0889)
		(layer "In11.Cu")
		(net "M_M_DQS_DP<12>")
	)
	(arc
		(start 84.694522 -88.080088)
		(mid 84.747992 -88.275151)
		(end 84.699348 -88.471502)
		(width 0.0889)
		(layer "In11.Cu")
		(net "M_M_DQS_DP<12>")
	)
	(arc
		(start 84.688172 -88.490806)
		(mid 84.615374 -88.781569)
		(end 84.694522 -89.070688)
		(width 0.0889)
		(layer "In11.Cu")
		(net "M_M_DQS_DP<12>")
	)
	(arc
		(start 84.694522 -90.061288)
		(mid 84.747992 -90.256351)
		(end 84.699348 -90.452702)
		(width 0.0889)
		(layer "In11.Cu")
		(net "M_M_DQS_DP<12>")
	)
	(arc
		(start 84.694522 -86.098888)
		(mid 84.747992 -86.293951)
		(end 84.699348 -86.490302)
		(width 0.0889)
		(layer "In11.Cu")
		(net "M_M_DQS_DP<12>")
	)
	(arc
		(start 84.694522 -89.070688)
		(mid 84.747992 -89.265751)
		(end 84.699348 -89.462102)
		(width 0.0889)
		(layer "In11.Cu")
		(net "M_M_DQS_DP<12>")
	)
	(arc
		(start 84.688172 -90.472006)
		(mid 84.615374 -90.762769)
		(end 84.694522 -91.051888)
		(width 0.0889)
		(layer "In11.Cu")
		(net "M_M_DQS_DP<12>")
	)
	(arc
		(start 84.694522 -92.042488)
		(mid 84.69727 -92.437955)
		(end 84.358988 -92.64269)
		(width 0.0889)
		(layer "In11.Cu")
		(net "M_M_DQS_DP<12>")
	)
	(arc
		(start 84.688172 -86.509606)
		(mid 84.615374 -86.800369)
		(end 84.694522 -87.089488)
		(width 0.0889)
		(layer "In11.Cu")
		(net "M_M_DQS_DP<12>")
	)
	(arc
		(start 84.694522 -91.051888)
		(mid 84.747992 -91.246951)
		(end 84.699348 -91.443302)
		(width 0.0889)
		(layer "In11.Cu")
		(net "M_M_DQS_DP<12>")
	)
	(arc
		(start 83.840828 -94.527624)
		(mid 83.889583 -94.723976)
		(end 83.836002 -94.919038)
		(width 0.0889)
		(layer "In11.Cu")
		(net "M_M_DQS_DP<12>")
	)
	(arc
		(start 84.326222 -92.64269)
		(mid 83.830745 -92.947133)
		(end 83.836002 -93.528642)
		(width 0.0889)
		(layer "In11.Cu")
		(net "M_M_DQS_DP<12>")
	)
	(arc
		(start 83.840828 -95.518224)
		(mid 83.889583 -95.714576)
		(end 83.836002 -95.909638)
		(width 0.0889)
		(layer "In11.Cu")
		(net "M_M_DQS_DP<12>")
	)
	(arc
		(start 85.141054 -85.216238)
		(mid 84.679085 -85.53678)
		(end 84.694522 -86.098888)
		(width 0.0889)
		(layer "In11.Cu")
		(net "M_M_DQS_DP<12>")
	)
	(arc
		(start 83.836002 -94.919038)
		(mid 83.75678 -95.208156)
		(end 83.829652 -95.49892)
		(width 0.0889)
		(layer "In11.Cu")
		(net "M_M_DQS_DP<12>")
	)
	(arc
		(start 84.688172 -87.500206)
		(mid 84.615374 -87.790969)
		(end 84.694522 -88.080088)
		(width 0.0889)
		(layer "In11.Cu")
		(net "M_M_DQS_DP<12>")
	)
	(arc
		(start 83.829652 -93.939106)
		(mid 83.756854 -94.229869)
		(end 83.836002 -94.518988)
		(width 0.0889)
		(layer "In11.Cu")
		(net "M_M_DQS_DP<12>")
	)
	(arc
		(start 83.836002 -93.528642)
		(mid 83.889501 -93.72854)
		(end 83.836002 -93.928438)
		(width 0.0889)
		(layer "In11.Cu")
		(net "M_M_DQS_DP<12>")
	)
	(arc
		(start 84.688172 -91.462606)
		(mid 84.615374 -91.753369)
		(end 84.694522 -92.042488)
		(width 0.0889)
		(layer "In11.Cu")
		(net "M_M_DQS_DP<12>")
	)
	(arc
		(start 84.688172 -89.481406)
		(mid 84.615374 -89.772169)
		(end 84.694522 -90.061288)
		(width 0.0889)
		(layer "In11.Cu")
		(net "M_M_DQS_DP<12>")
	)
	(segment
		(start 52.978812 -154.333702)
		(end 53.060346 -154.557984)
		(width 0.1651)
		(layer "F.Cu")
		(net "M_M_DQS_DP<11>")
	)
	(segment
		(start 52.978812 -153.515568)
		(end 52.978812 -154.333702)
		(width 0.1651)
		(layer "F.Cu")
		(net "M_M_DQS_DP<11>")
	)
	(segment
		(start 53.499512 -152.273)
		(end 53.499512 -152.895554)
		(width 0.1651)
		(layer "F.Cu")
		(net "M_M_DQS_DP<11>")
	)
	(segment
		(start 53.063394 -153.331672)
		(end 52.978812 -153.515568)
		(width 0.1651)
		(layer "F.Cu")
		(net "M_M_DQS_DP<11>")
	)
	(segment
		(start 82.343752 -92.737686)
		(end 81.772252 -92.737686)
		(width 0.1651)
		(layer "F.Cu")
		(net "M_M_DQS_DP<11>")
	)
	(segment
		(start 53.060346 -154.557984)
		(end 53.442108 -154.939746)
		(width 0.1651)
		(layer "F.Cu")
		(net "M_M_DQS_DP<11>")
	)
	(segment
		(start 53.499512 -152.895554)
		(end 53.063394 -153.331672)
		(width 0.1651)
		(layer "F.Cu")
		(net "M_M_DQS_DP<11>")
	)
	(via
		(at 81.772252 -92.737686)
		(size 0.508)
		(drill 0.254)
		(layers "F.Cu" "B.Cu")
		(net "M_M_DQS_DP<11>")
	)
	(via
		(at 53.442108 -154.939746)
		(size 0.508)
		(drill 0.254)
		(layers "F.Cu" "B.Cu")
		(net "M_M_DQS_DP<11>")
	)
	(via
		(at 53.442108 -149.4282)
		(size 0.508)
		(drill 0.254)
		(layers "F.Cu" "B.Cu")
		(net "M_M_DQS_DP<11>")
	)
	(segment
		(start 52.966112 -149.976332)
		(end 53.053488 -149.81682)
		(width 0.1651)
		(layer "B.Cu")
		(net "M_M_DQS_DP<11>")
	)
	(segment
		(start 53.043328 -151.00427)
		(end 52.966112 -150.871936)
		(width 0.1651)
		(layer "B.Cu")
		(net "M_M_DQS_DP<11>")
	)
	(segment
		(start 53.053488 -149.81682)
		(end 53.442108 -149.4282)
		(width 0.1651)
		(layer "B.Cu")
		(net "M_M_DQS_DP<11>")
	)
	(segment
		(start 52.966112 -150.871936)
		(end 52.966112 -149.976332)
		(width 0.1651)
		(layer "B.Cu")
		(net "M_M_DQS_DP<11>")
	)
	(segment
		(start 53.499512 -151.460454)
		(end 53.043328 -151.00427)
		(width 0.1651)
		(layer "B.Cu")
		(net "M_M_DQS_DP<11>")
	)
	(segment
		(start 53.499512 -152.078436)
		(end 53.499512 -151.460454)
		(width 0.1651)
		(layer "B.Cu")
		(net "M_M_DQS_DP<11>")
	)
	(segment
		(start 70.870572 -101.510338)
		(end 70.870572 -102.324916)
		(width 0.0889)
		(layer "In11.Cu")
		(net "M_M_DQS_DP<11>")
	)
	(segment
		(start 76.636372 -95.118936)
		(end 76.603606 -95.118936)
		(width 0.0889)
		(layer "In11.Cu")
		(net "M_M_DQS_DP<11>")
	)
	(segment
		(start 69.379592 -103.815896)
		(end 69.323712 -103.815896)
		(width 0.0889)
		(layer "In11.Cu")
		(net "M_M_DQS_DP<11>")
	)
	(segment
		(start 55.019448 -125.859286)
		(end 53.955188 -126.923546)
		(width 0.14224)
		(layer "In11.Cu")
		(net "M_M_DQS_DP<11>")
	)
	(segment
		(start 69.323712 -103.815896)
		(end 69.307964 -103.831644)
		(width 0.0889)
		(layer "In11.Cu")
		(net "M_M_DQS_DP<11>")
	)
	(segment
		(start 80.070198 -93.137736)
		(end 80.042258 -93.137736)
		(width 0.0889)
		(layer "In11.Cu")
		(net "M_M_DQS_DP<11>")
	)
	(segment
		(start 72.339962 -97.59569)
		(end 72.307196 -97.59569)
		(width 0.0889)
		(layer "In11.Cu")
		(net "M_M_DQS_DP<11>")
	)
	(segment
		(start 53.368956 -149.4282)
		(end 52.937156 -149.86)
		(width 0.14224)
		(layer "In11.Cu")
		(net "M_M_DQS_DP<11>")
	)
	(segment
		(start 81.772252 -92.737686)
		(end 81.479136 -92.90685)
		(width 0.0889)
		(layer "In11.Cu")
		(net "M_M_DQS_DP<11>")
	)
	(segment
		(start 70.963282 -99.368102)
		(end 70.958456 -99.376738)
		(width 0.0889)
		(layer "In11.Cu")
		(net "M_M_DQS_DP<11>")
	)
	(segment
		(start 74.919332 -96.109536)
		(end 74.886566 -96.109536)
		(width 0.0889)
		(layer "In11.Cu")
		(net "M_M_DQS_DP<11>")
	)
	(segment
		(start 52.937156 -149.86)
		(end 52.937156 -154.434794)
		(width 0.14224)
		(layer "In11.Cu")
		(net "M_M_DQS_DP<11>")
	)
	(segment
		(start 53.955188 -149.201886)
		(end 53.728874 -149.4282)
		(width 0.14224)
		(layer "In11.Cu")
		(net "M_M_DQS_DP<11>")
	)
	(segment
		(start 80.935322 -92.64269)
		(end 80.892142 -92.64269)
		(width 0.0889)
		(layer "In11.Cu")
		(net "M_M_DQS_DP<11>")
	)
	(segment
		(start 70.870572 -102.324916)
		(end 69.379592 -103.815896)
		(width 0.0889)
		(layer "In11.Cu")
		(net "M_M_DQS_DP<11>")
	)
	(segment
		(start 53.728874 -149.4282)
		(end 53.442108 -149.4282)
		(width 0.14224)
		(layer "In11.Cu")
		(net "M_M_DQS_DP<11>")
	)
	(segment
		(start 55.019448 -120.37314)
		(end 55.019448 -125.859286)
		(width 0.14224)
		(layer "In11.Cu")
		(net "M_M_DQS_DP<11>")
	)
	(segment
		(start 53.442108 -149.4282)
		(end 53.368956 -149.4282)
		(width 0.14224)
		(layer "In11.Cu")
		(net "M_M_DQS_DP<11>")
	)
	(segment
		(start 52.937156 -154.434794)
		(end 53.442108 -154.939746)
		(width 0.14224)
		(layer "In11.Cu")
		(net "M_M_DQS_DP<11>")
	)
	(segment
		(start 79.214726 -93.633036)
		(end 79.178912 -93.633036)
		(width 0.0889)
		(layer "In11.Cu")
		(net "M_M_DQS_DP<11>")
	)
	(segment
		(start 81.479136 -92.90685)
		(end 81.389728 -92.88272)
		(width 0.0889)
		(layer "In11.Cu")
		(net "M_M_DQS_DP<11>")
	)
	(segment
		(start 78.356206 -94.128336)
		(end 78.316582 -94.128336)
		(width 0.0889)
		(layer "In11.Cu")
		(net "M_M_DQS_DP<11>")
	)
	(segment
		(start 74.057002 -96.60509)
		(end 74.024236 -96.60509)
		(width 0.0889)
		(layer "In11.Cu")
		(net "M_M_DQS_DP<11>")
	)
	(segment
		(start 70.963536 -101.349048)
		(end 70.870572 -101.510338)
		(width 0.0889)
		(layer "In11.Cu")
		(net "M_M_DQS_DP<11>")
	)
	(segment
		(start 73.202292 -97.100136)
		(end 73.169526 -97.100136)
		(width 0.0889)
		(layer "In11.Cu")
		(net "M_M_DQS_DP<11>")
	)
	(segment
		(start 70.952106 -99.95662)
		(end 70.958456 -99.967288)
		(width 0.0889)
		(layer "In11.Cu")
		(net "M_M_DQS_DP<11>")
	)
	(segment
		(start 70.958456 -100.957888)
		(end 70.95871 -100.958142)
		(width 0.0889)
		(layer "In11.Cu")
		(net "M_M_DQS_DP<11>")
	)
	(segment
		(start 77.826362 -94.423484)
		(end 77.82306 -94.429326)
		(width 0.0889)
		(layer "In11.Cu")
		(net "M_M_DQS_DP<11>")
	)
	(segment
		(start 77.479906 -94.623636)
		(end 77.466952 -94.623636)
		(width 0.0889)
		(layer "In11.Cu")
		(net "M_M_DQS_DP<11>")
	)
	(segment
		(start 55.019956 -120.37314)
		(end 55.019448 -120.37314)
		(width 0.14224)
		(layer "In11.Cu")
		(net "M_M_DQS_DP<11>")
	)
	(segment
		(start 53.955188 -126.923546)
		(end 53.955188 -149.201886)
		(width 0.14224)
		(layer "In11.Cu")
		(net "M_M_DQS_DP<11>")
	)
	(segment
		(start 71.485252 -98.090736)
		(end 71.452486 -98.090736)
		(width 0.0889)
		(layer "In11.Cu")
		(net "M_M_DQS_DP<11>")
	)
	(segment
		(start 68.044568 -105.09504)
		(end 68.044568 -107.348528)
		(width 0.14224)
		(layer "In11.Cu")
		(net "M_M_DQS_DP<11>")
	)
	(segment
		(start 69.307964 -103.831644)
		(end 68.044568 -105.09504)
		(width 0.14224)
		(layer "In11.Cu")
		(net "M_M_DQS_DP<11>")
	)
	(segment
		(start 68.044568 -107.348528)
		(end 55.019956 -120.37314)
		(width 0.14224)
		(layer "In11.Cu")
		(net "M_M_DQS_DP<11>")
	)
	(segment
		(start 75.774042 -95.61449)
		(end 75.741276 -95.61449)
		(width 0.0889)
		(layer "In11.Cu")
		(net "M_M_DQS_DP<11>")
	)
	(arc
		(start 72.307196 -97.59569)
		(mid 72.023979 -97.679971)
		(end 71.816976 -97.890838)
		(width 0.0889)
		(layer "In11.Cu")
		(net "M_M_DQS_DP<11>")
	)
	(arc
		(start 73.534016 -96.900238)
		(mid 73.393937 -97.042974)
		(end 73.202292 -97.100136)
		(width 0.0889)
		(layer "In11.Cu")
		(net "M_M_DQS_DP<11>")
	)
	(arc
		(start 72.675496 -97.395538)
		(mid 72.533813 -97.539342)
		(end 72.339962 -97.59569)
		(width 0.0889)
		(layer "In11.Cu")
		(net "M_M_DQS_DP<11>")
	)
	(arc
		(start 81.389728 -92.88272)
		(mid 81.189983 -92.710726)
		(end 80.935322 -92.64269)
		(width 0.0889)
		(layer "In11.Cu")
		(net "M_M_DQS_DP<11>")
	)
	(arc
		(start 71.816976 -97.890838)
		(mid 71.676897 -98.033574)
		(end 71.485252 -98.090736)
		(width 0.0889)
		(layer "In11.Cu")
		(net "M_M_DQS_DP<11>")
	)
	(arc
		(start 74.392536 -96.404938)
		(mid 74.250853 -96.548742)
		(end 74.057002 -96.60509)
		(width 0.0889)
		(layer "In11.Cu")
		(net "M_M_DQS_DP<11>")
	)
	(arc
		(start 70.95871 -100.958142)
		(mid 71.012019 -101.152951)
		(end 70.963536 -101.349048)
		(width 0.0889)
		(layer "In11.Cu")
		(net "M_M_DQS_DP<11>")
	)
	(arc
		(start 70.958456 -99.376738)
		(mid 70.879234 -99.665856)
		(end 70.952106 -99.95662)
		(width 0.0889)
		(layer "In11.Cu")
		(net "M_M_DQS_DP<11>")
	)
	(arc
		(start 76.603606 -95.118936)
		(mid 76.318182 -95.202403)
		(end 76.109576 -95.414338)
		(width 0.0889)
		(layer "In11.Cu")
		(net "M_M_DQS_DP<11>")
	)
	(arc
		(start 78.316582 -94.128336)
		(mid 78.033365 -94.212617)
		(end 77.826362 -94.423484)
		(width 0.0889)
		(layer "In11.Cu")
		(net "M_M_DQS_DP<11>")
	)
	(arc
		(start 75.251056 -95.909638)
		(mid 75.110977 -96.052374)
		(end 74.919332 -96.109536)
		(width 0.0889)
		(layer "In11.Cu")
		(net "M_M_DQS_DP<11>")
	)
	(arc
		(start 75.741276 -95.61449)
		(mid 75.458059 -95.698771)
		(end 75.251056 -95.909638)
		(width 0.0889)
		(layer "In11.Cu")
		(net "M_M_DQS_DP<11>")
	)
	(arc
		(start 80.042258 -93.137736)
		(mid 79.754113 -93.220055)
		(end 79.543402 -93.433138)
		(width 0.0889)
		(layer "In11.Cu")
		(net "M_M_DQS_DP<11>")
	)
	(arc
		(start 79.543402 -93.433138)
		(mid 79.404658 -93.575171)
		(end 79.214726 -93.633036)
		(width 0.0889)
		(layer "In11.Cu")
		(net "M_M_DQS_DP<11>")
	)
	(arc
		(start 78.684882 -93.928438)
		(mid 78.546138 -94.070471)
		(end 78.356206 -94.128336)
		(width 0.0889)
		(layer "In11.Cu")
		(net "M_M_DQS_DP<11>")
	)
	(arc
		(start 73.169526 -97.100136)
		(mid 72.884102 -97.183603)
		(end 72.675496 -97.395538)
		(width 0.0889)
		(layer "In11.Cu")
		(net "M_M_DQS_DP<11>")
	)
	(arc
		(start 70.958456 -98.976688)
		(mid 71.011926 -99.171751)
		(end 70.963282 -99.368102)
		(width 0.0889)
		(layer "In11.Cu")
		(net "M_M_DQS_DP<11>")
	)
	(arc
		(start 74.024236 -96.60509)
		(mid 73.741019 -96.689371)
		(end 73.534016 -96.900238)
		(width 0.0889)
		(layer "In11.Cu")
		(net "M_M_DQS_DP<11>")
	)
	(arc
		(start 76.109576 -95.414338)
		(mid 75.967893 -95.558142)
		(end 75.774042 -95.61449)
		(width 0.0889)
		(layer "In11.Cu")
		(net "M_M_DQS_DP<11>")
	)
	(arc
		(start 79.178912 -93.633036)
		(mid 78.893488 -93.716503)
		(end 78.684882 -93.928438)
		(width 0.0889)
		(layer "In11.Cu")
		(net "M_M_DQS_DP<11>")
	)
	(arc
		(start 70.958456 -99.967288)
		(mid 71.011955 -100.167186)
		(end 70.958456 -100.367084)
		(width 0.0889)
		(layer "In11.Cu")
		(net "M_M_DQS_DP<11>")
	)
	(arc
		(start 76.968096 -94.919038)
		(mid 76.828017 -95.061774)
		(end 76.636372 -95.118936)
		(width 0.0889)
		(layer "In11.Cu")
		(net "M_M_DQS_DP<11>")
	)
	(arc
		(start 74.886566 -96.109536)
		(mid 74.601142 -96.193003)
		(end 74.392536 -96.404938)
		(width 0.0889)
		(layer "In11.Cu")
		(net "M_M_DQS_DP<11>")
	)
	(arc
		(start 80.892142 -92.64269)
		(mid 80.608925 -92.726971)
		(end 80.401922 -92.937838)
		(width 0.0889)
		(layer "In11.Cu")
		(net "M_M_DQS_DP<11>")
	)
	(arc
		(start 77.466952 -94.623636)
		(mid 77.178807 -94.705955)
		(end 76.968096 -94.919038)
		(width 0.0889)
		(layer "In11.Cu")
		(net "M_M_DQS_DP<11>")
	)
	(arc
		(start 77.82306 -94.429326)
		(mid 77.677094 -94.571725)
		(end 77.479906 -94.623636)
		(width 0.0889)
		(layer "In11.Cu")
		(net "M_M_DQS_DP<11>")
	)
	(arc
		(start 70.958456 -100.367084)
		(mid 70.879325 -100.662486)
		(end 70.958456 -100.957888)
		(width 0.0889)
		(layer "In11.Cu")
		(net "M_M_DQS_DP<11>")
	)
	(arc
		(start 71.452486 -98.090736)
		(mid 70.954235 -98.393576)
		(end 70.958456 -98.976688)
		(width 0.0889)
		(layer "In11.Cu")
		(net "M_M_DQS_DP<11>")
	)
	(arc
		(start 80.401922 -92.937838)
		(mid 80.261843 -93.080574)
		(end 80.070198 -93.137736)
		(width 0.0889)
		(layer "In11.Cu")
		(net "M_M_DQS_DP<11>")
	)
	(segment
		(start 43.628818 -153.515568)
		(end 43.628818 -154.333702)
		(width 0.1651)
		(layer "F.Cu")
		(net "M_M_DQS_DP<10>")
	)
	(segment
		(start 44.149518 -152.273)
		(end 44.149518 -152.895554)
		(width 0.1651)
		(layer "F.Cu")
		(net "M_M_DQS_DP<10>")
	)
	(segment
		(start 44.149518 -152.895554)
		(end 43.7134 -153.331672)
		(width 0.1651)
		(layer "F.Cu")
		(net "M_M_DQS_DP<10>")
	)
	(segment
		(start 43.710352 -154.557984)
		(end 44.092114 -154.939746)
		(width 0.1651)
		(layer "F.Cu")
		(net "M_M_DQS_DP<10>")
	)
	(segment
		(start 43.628818 -154.333702)
		(end 43.710352 -154.557984)
		(width 0.1651)
		(layer "F.Cu")
		(net "M_M_DQS_DP<10>")
	)
	(segment
		(start 78.051406 -92.24264)
		(end 77.479906 -92.24264)
		(width 0.1651)
		(layer "F.Cu")
		(net "M_M_DQS_DP<10>")
	)
	(segment
		(start 43.7134 -153.331672)
		(end 43.628818 -153.515568)
		(width 0.1651)
		(layer "F.Cu")
		(net "M_M_DQS_DP<10>")
	)
	(via
		(at 44.092114 -154.939746)
		(size 0.508)
		(drill 0.254)
		(layers "F.Cu" "B.Cu")
		(net "M_M_DQS_DP<10>")
	)
	(via
		(at 44.092114 -149.4282)
		(size 0.508)
		(drill 0.254)
		(layers "F.Cu" "B.Cu")
		(net "M_M_DQS_DP<10>")
	)
	(via
		(at 77.479906 -92.24264)
		(size 0.508)
		(drill 0.254)
		(layers "F.Cu" "B.Cu")
		(net "M_M_DQS_DP<10>")
	)
	(segment
		(start 43.703494 -149.81682)
		(end 44.092114 -149.4282)
		(width 0.1651)
		(layer "B.Cu")
		(net "M_M_DQS_DP<10>")
	)
	(segment
		(start 43.693334 -151.00427)
		(end 43.616118 -150.871936)
		(width 0.1651)
		(layer "B.Cu")
		(net "M_M_DQS_DP<10>")
	)
	(segment
		(start 44.149518 -152.078436)
		(end 44.149518 -151.460454)
		(width 0.1651)
		(layer "B.Cu")
		(net "M_M_DQS_DP<10>")
	)
	(segment
		(start 43.616118 -149.976332)
		(end 43.703494 -149.81682)
		(width 0.1651)
		(layer "B.Cu")
		(net "M_M_DQS_DP<10>")
	)
	(segment
		(start 43.616118 -150.871936)
		(end 43.616118 -149.976332)
		(width 0.1651)
		(layer "B.Cu")
		(net "M_M_DQS_DP<10>")
	)
	(segment
		(start 44.149518 -151.460454)
		(end 43.693334 -151.00427)
		(width 0.1651)
		(layer "B.Cu")
		(net "M_M_DQS_DP<10>")
	)
	(segment
		(start 77.479906 -92.24264)
		(end 77.18679 -92.073476)
		(width 0.0889)
		(layer "In11.Cu")
		(net "M_M_DQS_DP<10>")
	)
	(segment
		(start 44.605194 -127.808482)
		(end 44.605194 -149.201886)
		(width 0.14224)
		(layer "In11.Cu")
		(net "M_M_DQS_DP<10>")
	)
	(segment
		(start 64.534288 -96.11741)
		(end 63.240158 -96.11741)
		(width 0.14224)
		(layer "In11.Cu")
		(net "M_M_DQS_DP<10>")
	)
	(segment
		(start 44.605194 -117.9957)
		(end 44.605194 -123.890786)
		(width 0.14224)
		(layer "In11.Cu")
		(net "M_M_DQS_DP<10>")
	)
	(segment
		(start 44.605194 -123.890786)
		(end 44.984162 -124.269754)
		(width 0.14224)
		(layer "In11.Cu")
		(net "M_M_DQS_DP<10>")
	)
	(segment
		(start 43.587162 -154.434794)
		(end 44.092114 -154.939746)
		(width 0.14224)
		(layer "In11.Cu")
		(net "M_M_DQS_DP<10>")
	)
	(segment
		(start 64.595756 -96.15678)
		(end 64.556386 -96.11741)
		(width 0.0889)
		(layer "In11.Cu")
		(net "M_M_DQS_DP<10>")
	)
	(segment
		(start 44.37888 -149.4282)
		(end 44.092114 -149.4282)
		(width 0.14224)
		(layer "In11.Cu")
		(net "M_M_DQS_DP<10>")
	)
	(segment
		(start 45.445934 -126.555754)
		(end 45.678852 -126.788672)
		(width 0.14224)
		(layer "In11.Cu")
		(net "M_M_DQS_DP<10>")
	)
	(segment
		(start 76.639166 -91.156536)
		(end 76.6064 -91.156536)
		(width 0.0889)
		(layer "In11.Cu")
		(net "M_M_DQS_DP<10>")
	)
	(segment
		(start 74.905362 -90.16619)
		(end 74.90333 -90.16619)
		(width 0.0889)
		(layer "In11.Cu")
		(net "M_M_DQS_DP<10>")
	)
	(segment
		(start 44.984162 -126.555754)
		(end 45.445934 -126.555754)
		(width 0.14224)
		(layer "In11.Cu")
		(net "M_M_DQS_DP<10>")
	)
	(segment
		(start 67.144392 -94.269814)
		(end 65.257426 -96.15678)
		(width 0.0889)
		(layer "In11.Cu")
		(net "M_M_DQS_DP<10>")
	)
	(segment
		(start 45.657516 -124.491242)
		(end 45.657516 -124.922788)
		(width 0.14224)
		(layer "In11.Cu")
		(net "M_M_DQS_DP<10>")
	)
	(segment
		(start 74.057002 -90.66149)
		(end 74.024236 -90.66149)
		(width 0.0889)
		(layer "In11.Cu")
		(net "M_M_DQS_DP<10>")
	)
	(segment
		(start 63.240158 -96.11741)
		(end 61.399928 -97.95764)
		(width 0.14224)
		(layer "In11.Cu")
		(net "M_M_DQS_DP<10>")
	)
	(segment
		(start 44.984162 -124.269754)
		(end 45.436028 -124.269754)
		(width 0.14224)
		(layer "In11.Cu")
		(net "M_M_DQS_DP<10>")
	)
	(segment
		(start 77.18679 -92.073476)
		(end 77.162914 -91.984068)
		(width 0.0889)
		(layer "In11.Cu")
		(net "M_M_DQS_DP<10>")
	)
	(segment
		(start 68.109592 -94.269814)
		(end 67.144392 -94.269814)
		(width 0.0889)
		(layer "In11.Cu")
		(net "M_M_DQS_DP<10>")
	)
	(segment
		(start 75.784456 -90.66149)
		(end 75.75169 -90.66149)
		(width 0.0889)
		(layer "In11.Cu")
		(net "M_M_DQS_DP<10>")
	)
	(segment
		(start 61.399928 -101.201474)
		(end 44.605702 -117.9957)
		(width 0.14224)
		(layer "In11.Cu")
		(net "M_M_DQS_DP<10>")
	)
	(segment
		(start 45.43679 -125.143514)
		(end 44.984162 -125.143514)
		(width 0.14224)
		(layer "In11.Cu")
		(net "M_M_DQS_DP<10>")
	)
	(segment
		(start 45.678852 -127.22098)
		(end 45.470318 -127.429514)
		(width 0.14224)
		(layer "In11.Cu")
		(net "M_M_DQS_DP<10>")
	)
	(segment
		(start 44.092114 -149.4282)
		(end 44.018962 -149.4282)
		(width 0.14224)
		(layer "In11.Cu")
		(net "M_M_DQS_DP<10>")
	)
	(segment
		(start 44.018962 -149.4282)
		(end 43.587162 -149.86)
		(width 0.14224)
		(layer "In11.Cu")
		(net "M_M_DQS_DP<10>")
	)
	(segment
		(start 44.984162 -127.429514)
		(end 44.605194 -127.808482)
		(width 0.14224)
		(layer "In11.Cu")
		(net "M_M_DQS_DP<10>")
	)
	(segment
		(start 73.202292 -91.156536)
		(end 73.169526 -91.156536)
		(width 0.0889)
		(layer "In11.Cu")
		(net "M_M_DQS_DP<10>")
	)
	(segment
		(start 61.399928 -97.95764)
		(end 61.399928 -101.201474)
		(width 0.14224)
		(layer "In11.Cu")
		(net "M_M_DQS_DP<10>")
	)
	(segment
		(start 71.485252 -92.147136)
		(end 71.452486 -92.147136)
		(width 0.0889)
		(layer "In11.Cu")
		(net "M_M_DQS_DP<10>")
	)
	(segment
		(start 45.657516 -124.922788)
		(end 45.43679 -125.143514)
		(width 0.14224)
		(layer "In11.Cu")
		(net "M_M_DQS_DP<10>")
	)
	(segment
		(start 69.768212 -93.137736)
		(end 69.24167 -93.137736)
		(width 0.0889)
		(layer "In11.Cu")
		(net "M_M_DQS_DP<10>")
	)
	(segment
		(start 43.587162 -149.86)
		(end 43.587162 -154.434794)
		(width 0.14224)
		(layer "In11.Cu")
		(net "M_M_DQS_DP<10>")
	)
	(segment
		(start 72.339962 -91.65209)
		(end 72.307196 -91.65209)
		(width 0.0889)
		(layer "In11.Cu")
		(net "M_M_DQS_DP<10>")
	)
	(segment
		(start 44.605702 -117.9957)
		(end 44.605194 -117.9957)
		(width 0.14224)
		(layer "In11.Cu")
		(net "M_M_DQS_DP<10>")
	)
	(segment
		(start 44.605194 -149.201886)
		(end 44.37888 -149.4282)
		(width 0.14224)
		(layer "In11.Cu")
		(net "M_M_DQS_DP<10>")
	)
	(segment
		(start 70.622922 -92.64269)
		(end 70.590156 -92.64269)
		(width 0.0889)
		(layer "In11.Cu")
		(net "M_M_DQS_DP<10>")
	)
	(segment
		(start 44.605194 -125.522482)
		(end 44.605194 -126.176786)
		(width 0.14224)
		(layer "In11.Cu")
		(net "M_M_DQS_DP<10>")
	)
	(segment
		(start 64.556386 -96.11741)
		(end 64.534288 -96.11741)
		(width 0.0889)
		(layer "In11.Cu")
		(net "M_M_DQS_DP<10>")
	)
	(segment
		(start 45.436028 -124.269754)
		(end 45.657516 -124.491242)
		(width 0.14224)
		(layer "In11.Cu")
		(net "M_M_DQS_DP<10>")
	)
	(segment
		(start 44.984162 -125.143514)
		(end 44.605194 -125.522482)
		(width 0.14224)
		(layer "In11.Cu")
		(net "M_M_DQS_DP<10>")
	)
	(segment
		(start 45.470318 -127.429514)
		(end 44.984162 -127.429514)
		(width 0.14224)
		(layer "In11.Cu")
		(net "M_M_DQS_DP<10>")
	)
	(segment
		(start 44.605194 -126.176786)
		(end 44.984162 -126.555754)
		(width 0.14224)
		(layer "In11.Cu")
		(net "M_M_DQS_DP<10>")
	)
	(segment
		(start 65.257426 -96.15678)
		(end 64.595756 -96.15678)
		(width 0.0889)
		(layer "In11.Cu")
		(net "M_M_DQS_DP<10>")
	)
	(segment
		(start 69.24167 -93.137736)
		(end 68.109592 -94.269814)
		(width 0.0889)
		(layer "In11.Cu")
		(net "M_M_DQS_DP<10>")
	)
	(segment
		(start 45.678852 -126.788672)
		(end 45.678852 -127.22098)
		(width 0.14224)
		(layer "In11.Cu")
		(net "M_M_DQS_DP<10>")
	)
	(arc
		(start 72.307196 -91.65209)
		(mid 72.023979 -91.736371)
		(end 71.816976 -91.947238)
		(width 0.0889)
		(layer "In11.Cu")
		(net "M_M_DQS_DP<10>")
	)
	(arc
		(start 77.162914 -91.984068)
		(mid 77.120935 -91.431108)
		(end 76.639166 -91.156536)
		(width 0.0889)
		(layer "In11.Cu")
		(net "M_M_DQS_DP<10>")
	)
	(arc
		(start 73.169526 -91.156536)
		(mid 72.884102 -91.240003)
		(end 72.675496 -91.451938)
		(width 0.0889)
		(layer "In11.Cu")
		(net "M_M_DQS_DP<10>")
	)
	(arc
		(start 71.816976 -91.947238)
		(mid 71.676897 -92.089974)
		(end 71.485252 -92.147136)
		(width 0.0889)
		(layer "In11.Cu")
		(net "M_M_DQS_DP<10>")
	)
	(arc
		(start 74.392536 -90.461338)
		(mid 74.250853 -90.605142)
		(end 74.057002 -90.66149)
		(width 0.0889)
		(layer "In11.Cu")
		(net "M_M_DQS_DP<10>")
	)
	(arc
		(start 75.416156 -90.461338)
		(mid 75.200302 -90.245357)
		(end 74.905362 -90.16619)
		(width 0.0889)
		(layer "In11.Cu")
		(net "M_M_DQS_DP<10>")
	)
	(arc
		(start 75.75169 -90.66149)
		(mid 75.55784 -90.60514)
		(end 75.416156 -90.461338)
		(width 0.0889)
		(layer "In11.Cu")
		(net "M_M_DQS_DP<10>")
	)
	(arc
		(start 70.590156 -92.64269)
		(mid 70.306939 -92.726971)
		(end 70.099936 -92.937838)
		(width 0.0889)
		(layer "In11.Cu")
		(net "M_M_DQS_DP<10>")
	)
	(arc
		(start 70.099936 -92.937838)
		(mid 69.959857 -93.080574)
		(end 69.768212 -93.137736)
		(width 0.0889)
		(layer "In11.Cu")
		(net "M_M_DQS_DP<10>")
	)
	(arc
		(start 70.958456 -92.442538)
		(mid 70.816773 -92.586342)
		(end 70.622922 -92.64269)
		(width 0.0889)
		(layer "In11.Cu")
		(net "M_M_DQS_DP<10>")
	)
	(arc
		(start 72.675496 -91.451938)
		(mid 72.533813 -91.595742)
		(end 72.339962 -91.65209)
		(width 0.0889)
		(layer "In11.Cu")
		(net "M_M_DQS_DP<10>")
	)
	(arc
		(start 73.534016 -90.956638)
		(mid 73.393937 -91.099374)
		(end 73.202292 -91.156536)
		(width 0.0889)
		(layer "In11.Cu")
		(net "M_M_DQS_DP<10>")
	)
	(arc
		(start 71.452486 -92.147136)
		(mid 71.167062 -92.230603)
		(end 70.958456 -92.442538)
		(width 0.0889)
		(layer "In11.Cu")
		(net "M_M_DQS_DP<10>")
	)
	(arc
		(start 76.6064 -91.156536)
		(mid 76.414758 -91.09937)
		(end 76.274676 -90.956638)
		(width 0.0889)
		(layer "In11.Cu")
		(net "M_M_DQS_DP<10>")
	)
	(arc
		(start 74.024236 -90.66149)
		(mid 73.741019 -90.745771)
		(end 73.534016 -90.956638)
		(width 0.0889)
		(layer "In11.Cu")
		(net "M_M_DQS_DP<10>")
	)
	(arc
		(start 74.90333 -90.16619)
		(mid 74.608336 -90.245264)
		(end 74.392536 -90.461338)
		(width 0.0889)
		(layer "In11.Cu")
		(net "M_M_DQS_DP<10>")
	)
	(arc
		(start 76.274676 -90.956638)
		(mid 76.067672 -90.745774)
		(end 75.784456 -90.66149)
		(width 0.0889)
		(layer "In11.Cu")
		(net "M_M_DQS_DP<10>")
	)
	(segment
		(start 76.334366 -86.29904)
		(end 75.762866 -86.29904)
		(width 0.1651)
		(layer "F.Cu")
		(net "M_M_DQS_DP<0>")
	)
	(segment
		(start 36.537392 -155.829)
		(end 36.537392 -154.4574)
		(width 0.1651)
		(layer "F.Cu")
		(net "M_M_DQS_DP<0>")
	)
	(segment
		(start 36.499546 -155.866846)
		(end 36.537392 -155.829)
		(width 0.1651)
		(layer "F.Cu")
		(net "M_M_DQS_DP<0>")
	)
	(segment
		(start 36.293552 -154.21356)
		(end 36.03752 -154.21356)
		(width 0.1651)
		(layer "F.Cu")
		(net "M_M_DQS_DP<0>")
	)
	(segment
		(start 36.499546 -156.87294)
		(end 36.499546 -155.866846)
		(width 0.1651)
		(layer "F.Cu")
		(net "M_M_DQS_DP<0>")
	)
	(segment
		(start 36.537392 -154.4574)
		(end 36.293552 -154.21356)
		(width 0.1651)
		(layer "F.Cu")
		(net "M_M_DQS_DP<0>")
	)
	(via
		(at 36.03752 -150.142956)
		(size 0.508)
		(drill 0.254)
		(layers "F.Cu" "B.Cu")
		(net "M_M_DQS_DP<0>")
	)
	(via
		(at 36.03752 -154.21356)
		(size 0.508)
		(drill 0.254)
		(layers "F.Cu" "B.Cu")
		(net "M_M_DQS_DP<0>")
	)
	(via
		(at 75.762866 -86.29904)
		(size 0.508)
		(drill 0.254)
		(layers "F.Cu" "B.Cu")
		(net "M_M_DQS_DP<0>")
	)
	(segment
		(start 36.499546 -148.628354)
		(end 36.537392 -148.6662)
		(width 0.1651)
		(layer "B.Cu")
		(net "M_M_DQS_DP<0>")
	)
	(segment
		(start 36.279836 -150.142956)
		(end 36.03752 -150.142956)
		(width 0.1651)
		(layer "B.Cu")
		(net "M_M_DQS_DP<0>")
	)
	(segment
		(start 36.537392 -148.6662)
		(end 36.537392 -149.8854)
		(width 0.1651)
		(layer "B.Cu")
		(net "M_M_DQS_DP<0>")
	)
	(segment
		(start 36.499546 -147.478496)
		(end 36.499546 -148.628354)
		(width 0.1651)
		(layer "B.Cu")
		(net "M_M_DQS_DP<0>")
	)
	(segment
		(start 36.537392 -149.8854)
		(end 36.279836 -150.142956)
		(width 0.1651)
		(layer "B.Cu")
		(net "M_M_DQS_DP<0>")
	)
	(segment
		(start 36.202874 -122.32132)
		(end 36.4236 -122.542046)
		(width 0.14224)
		(layer "In11.Cu")
		(net "M_M_DQS_DP<0>")
	)
	(segment
		(start 36.4236 -121.668286)
		(end 36.202874 -121.889012)
		(width 0.14224)
		(layer "In11.Cu")
		(net "M_M_DQS_DP<0>")
	)
	(segment
		(start 36.81984 -149.36978)
		(end 36.046664 -150.142956)
		(width 0.14224)
		(layer "In11.Cu")
		(net "M_M_DQS_DP<0>")
	)
	(segment
		(start 74.67473 -86.203282)
		(end 74.397616 -86.033356)
		(width 0.0889)
		(layer "In11.Cu")
		(net "M_M_DQS_DP<0>")
	)
	(segment
		(start 36.332414 -124.828046)
		(end 37.338 -124.828046)
		(width 0.14224)
		(layer "In11.Cu")
		(net "M_M_DQS_DP<0>")
	)
	(segment
		(start 36.218368 -151.257)
		(end 35.833304 -151.257)
		(width 0.14224)
		(layer "In11.Cu")
		(net "M_M_DQS_DP<0>")
	)
	(segment
		(start 45.159168 -104.3686)
		(end 41.374568 -108.1532)
		(width 0.14224)
		(layer "In11.Cu")
		(net "M_M_DQS_DP<0>")
	)
	(segment
		(start 63.48984 -89.555574)
		(end 63.45047 -89.594944)
		(width 0.0889)
		(layer "In11.Cu")
		(net "M_M_DQS_DP<0>")
	)
	(segment
		(start 36.497768 -153.32964)
		(end 36.497768 -153.753312)
		(width 0.14224)
		(layer "In11.Cu")
		(net "M_M_DQS_DP<0>")
	)
	(segment
		(start 37.762688 -112.27308)
		(end 37.762688 -119.00408)
		(width 0.14224)
		(layer "In11.Cu")
		(net "M_M_DQS_DP<0>")
	)
	(segment
		(start 63.428372 -89.594944)
		(end 62.828424 -89.594944)
		(width 0.14224)
		(layer "In11.Cu")
		(net "M_M_DQS_DP<0>")
	)
	(segment
		(start 37.338 -124.828046)
		(end 37.716968 -125.207014)
		(width 0.14224)
		(layer "In11.Cu")
		(net "M_M_DQS_DP<0>")
	)
	(segment
		(start 35.66287 -151.427434)
		(end 35.66287 -151.751792)
		(width 0.14224)
		(layer "In11.Cu")
		(net "M_M_DQS_DP<0>")
	)
	(segment
		(start 37.762688 -121.289318)
		(end 37.38372 -121.668286)
		(width 0.14224)
		(layer "In11.Cu")
		(net "M_M_DQS_DP<0>")
	)
	(segment
		(start 36.472368 -150.577804)
		(end 36.472368 -151.003)
		(width 0.14224)
		(layer "In11.Cu")
		(net "M_M_DQS_DP<0>")
	)
	(segment
		(start 66.363088 -89.555574)
		(end 63.48984 -89.555574)
		(width 0.0889)
		(layer "In11.Cu")
		(net "M_M_DQS_DP<0>")
	)
	(segment
		(start 37.762688 -123.57608)
		(end 37.384482 -123.954286)
		(width 0.14224)
		(layer "In11.Cu")
		(net "M_M_DQS_DP<0>")
	)
	(segment
		(start 37.762688 -122.921014)
		(end 37.762688 -123.57608)
		(width 0.14224)
		(layer "In11.Cu")
		(net "M_M_DQS_DP<0>")
	)
	(segment
		(start 62.828424 -89.594944)
		(end 53.785008 -98.63836)
		(width 0.14224)
		(layer "In11.Cu")
		(net "M_M_DQS_DP<0>")
	)
	(segment
		(start 36.333176 -123.954286)
		(end 36.111688 -124.175774)
		(width 0.14224)
		(layer "In11.Cu")
		(net "M_M_DQS_DP<0>")
	)
	(segment
		(start 35.858704 -153.0604)
		(end 36.228528 -153.0604)
		(width 0.14224)
		(layer "In11.Cu")
		(net "M_M_DQS_DP<0>")
	)
	(segment
		(start 71.491856 -87.384636)
		(end 71.45909 -87.384636)
		(width 0.0889)
		(layer "In11.Cu")
		(net "M_M_DQS_DP<0>")
	)
	(segment
		(start 35.777678 -151.8666)
		(end 35.862768 -151.8666)
		(width 0.14224)
		(layer "In11.Cu")
		(net "M_M_DQS_DP<0>")
	)
	(segment
		(start 35.833304 -151.257)
		(end 35.66287 -151.427434)
		(width 0.14224)
		(layer "In11.Cu")
		(net "M_M_DQS_DP<0>")
	)
	(segment
		(start 36.402264 -119.611394)
		(end 36.402264 -120.043702)
		(width 0.14224)
		(layer "In11.Cu")
		(net "M_M_DQS_DP<0>")
	)
	(segment
		(start 37.762688 -119.00408)
		(end 37.384482 -119.382286)
		(width 0.14224)
		(layer "In11.Cu")
		(net "M_M_DQS_DP<0>")
	)
	(segment
		(start 37.716968 -125.889512)
		(end 36.81984 -126.78664)
		(width 0.14224)
		(layer "In11.Cu")
		(net "M_M_DQS_DP<0>")
	)
	(segment
		(start 36.040568 -152.0444)
		(end 36.040568 -152.320752)
		(width 0.14224)
		(layer "In11.Cu")
		(net "M_M_DQS_DP<0>")
	)
	(segment
		(start 36.631372 -119.382286)
		(end 36.402264 -119.611394)
		(width 0.14224)
		(layer "In11.Cu")
		(net "M_M_DQS_DP<0>")
	)
	(segment
		(start 36.497768 -153.753312)
		(end 36.03752 -154.21356)
		(width 0.14224)
		(layer "In11.Cu")
		(net "M_M_DQS_DP<0>")
	)
	(segment
		(start 36.046664 -150.142956)
		(end 36.03752 -150.142956)
		(width 0.14224)
		(layer "In11.Cu")
		(net "M_M_DQS_DP<0>")
	)
	(segment
		(start 66.668904 -89.86139)
		(end 66.363088 -89.555574)
		(width 0.0889)
		(layer "In11.Cu")
		(net "M_M_DQS_DP<0>")
	)
	(segment
		(start 37.38372 -122.542046)
		(end 37.762688 -122.921014)
		(width 0.14224)
		(layer "In11.Cu")
		(net "M_M_DQS_DP<0>")
	)
	(segment
		(start 36.472368 -151.003)
		(end 36.218368 -151.257)
		(width 0.14224)
		(layer "In11.Cu")
		(net "M_M_DQS_DP<0>")
	)
	(segment
		(start 53.785008 -99.880674)
		(end 49.297082 -104.3686)
		(width 0.14224)
		(layer "In11.Cu")
		(net "M_M_DQS_DP<0>")
	)
	(segment
		(start 68.057776 -89.365836)
		(end 68.02501 -89.365836)
		(width 0.0889)
		(layer "In11.Cu")
		(net "M_M_DQS_DP<0>")
	)
	(segment
		(start 63.45047 -89.594944)
		(end 63.428372 -89.594944)
		(width 0.0889)
		(layer "In11.Cu")
		(net "M_M_DQS_DP<0>")
	)
	(segment
		(start 35.862768 -151.8666)
		(end 36.040568 -152.0444)
		(width 0.14224)
		(layer "In11.Cu")
		(net "M_M_DQS_DP<0>")
	)
	(segment
		(start 36.111688 -124.175774)
		(end 36.111688 -124.60732)
		(width 0.14224)
		(layer "In11.Cu")
		(net "M_M_DQS_DP<0>")
	)
	(segment
		(start 68.912486 -88.87079)
		(end 68.87972 -88.87079)
		(width 0.0889)
		(layer "In11.Cu")
		(net "M_M_DQS_DP<0>")
	)
	(segment
		(start 53.785008 -98.63836)
		(end 53.785008 -99.880674)
		(width 0.14224)
		(layer "In11.Cu")
		(net "M_M_DQS_DP<0>")
	)
	(segment
		(start 70.629526 -87.88019)
		(end 70.59676 -87.88019)
		(width 0.0889)
		(layer "In11.Cu")
		(net "M_M_DQS_DP<0>")
	)
	(segment
		(start 36.040568 -152.320752)
		(end 35.860228 -152.501092)
		(width 0.14224)
		(layer "In11.Cu")
		(net "M_M_DQS_DP<0>")
	)
	(segment
		(start 49.297082 -104.3686)
		(end 45.159168 -104.3686)
		(width 0.14224)
		(layer "In11.Cu")
		(net "M_M_DQS_DP<0>")
	)
	(segment
		(start 69.774816 -88.375236)
		(end 69.74205 -88.375236)
		(width 0.0889)
		(layer "In11.Cu")
		(net "M_M_DQS_DP<0>")
	)
	(segment
		(start 73.208896 -86.394036)
		(end 73.17613 -86.394036)
		(width 0.0889)
		(layer "In11.Cu")
		(net "M_M_DQS_DP<0>")
	)
	(segment
		(start 37.38372 -120.256046)
		(end 37.762688 -120.635014)
		(width 0.14224)
		(layer "In11.Cu")
		(net "M_M_DQS_DP<0>")
	)
	(segment
		(start 35.860228 -152.501092)
		(end 35.80003 -152.501092)
		(width 0.14224)
		(layer "In11.Cu")
		(net "M_M_DQS_DP<0>")
	)
	(segment
		(start 37.384482 -123.954286)
		(end 36.333176 -123.954286)
		(width 0.14224)
		(layer "In11.Cu")
		(net "M_M_DQS_DP<0>")
	)
	(segment
		(start 37.716968 -125.207014)
		(end 37.716968 -125.889512)
		(width 0.14224)
		(layer "In11.Cu")
		(net "M_M_DQS_DP<0>")
	)
	(segment
		(start 36.202874 -121.889012)
		(end 36.202874 -122.32132)
		(width 0.14224)
		(layer "In11.Cu")
		(net "M_M_DQS_DP<0>")
	)
	(segment
		(start 35.66287 -152.864566)
		(end 35.858704 -153.0604)
		(width 0.14224)
		(layer "In11.Cu")
		(net "M_M_DQS_DP<0>")
	)
	(segment
		(start 41.374568 -108.1532)
		(end 41.374568 -108.6612)
		(width 0.14224)
		(layer "In11.Cu")
		(net "M_M_DQS_DP<0>")
	)
	(segment
		(start 75.762866 -86.29904)
		(end 75.248262 -86.203282)
		(width 0.0889)
		(layer "In11.Cu")
		(net "M_M_DQS_DP<0>")
	)
	(segment
		(start 36.03752 -150.142956)
		(end 36.472368 -150.577804)
		(width 0.14224)
		(layer "In11.Cu")
		(net "M_M_DQS_DP<0>")
	)
	(segment
		(start 36.81984 -126.78664)
		(end 36.81984 -149.36978)
		(width 0.14224)
		(layer "In11.Cu")
		(net "M_M_DQS_DP<0>")
	)
	(segment
		(start 35.80003 -152.501092)
		(end 35.66287 -152.638252)
		(width 0.14224)
		(layer "In11.Cu")
		(net "M_M_DQS_DP<0>")
	)
	(segment
		(start 67.191382 -89.86139)
		(end 66.668904 -89.86139)
		(width 0.0889)
		(layer "In11.Cu")
		(net "M_M_DQS_DP<0>")
	)
	(segment
		(start 35.66287 -151.751792)
		(end 35.777678 -151.8666)
		(width 0.14224)
		(layer "In11.Cu")
		(net "M_M_DQS_DP<0>")
	)
	(segment
		(start 36.402264 -120.043702)
		(end 36.614608 -120.256046)
		(width 0.14224)
		(layer "In11.Cu")
		(net "M_M_DQS_DP<0>")
	)
	(segment
		(start 35.66287 -152.638252)
		(end 35.66287 -152.864566)
		(width 0.14224)
		(layer "In11.Cu")
		(net "M_M_DQS_DP<0>")
	)
	(segment
		(start 36.614608 -120.256046)
		(end 37.38372 -120.256046)
		(width 0.14224)
		(layer "In11.Cu")
		(net "M_M_DQS_DP<0>")
	)
	(segment
		(start 36.111688 -124.60732)
		(end 36.332414 -124.828046)
		(width 0.14224)
		(layer "In11.Cu")
		(net "M_M_DQS_DP<0>")
	)
	(segment
		(start 37.384482 -119.382286)
		(end 36.631372 -119.382286)
		(width 0.14224)
		(layer "In11.Cu")
		(net "M_M_DQS_DP<0>")
	)
	(segment
		(start 41.374568 -108.6612)
		(end 37.762688 -112.27308)
		(width 0.14224)
		(layer "In11.Cu")
		(net "M_M_DQS_DP<0>")
	)
	(segment
		(start 72.346566 -86.88959)
		(end 72.3138 -86.88959)
		(width 0.0889)
		(layer "In11.Cu")
		(net "M_M_DQS_DP<0>")
	)
	(segment
		(start 36.4236 -122.542046)
		(end 37.38372 -122.542046)
		(width 0.14224)
		(layer "In11.Cu")
		(net "M_M_DQS_DP<0>")
	)
	(segment
		(start 75.248262 -86.203282)
		(end 74.67473 -86.203282)
		(width 0.0889)
		(layer "In11.Cu")
		(net "M_M_DQS_DP<0>")
	)
	(segment
		(start 37.762688 -120.635014)
		(end 37.762688 -121.289318)
		(width 0.14224)
		(layer "In11.Cu")
		(net "M_M_DQS_DP<0>")
	)
	(segment
		(start 74.060812 -85.89899)
		(end 74.03084 -85.89899)
		(width 0.0889)
		(layer "In11.Cu")
		(net "M_M_DQS_DP<0>")
	)
	(segment
		(start 36.228528 -153.0604)
		(end 36.497768 -153.32964)
		(width 0.14224)
		(layer "In11.Cu")
		(net "M_M_DQS_DP<0>")
	)
	(segment
		(start 37.38372 -121.668286)
		(end 36.4236 -121.668286)
		(width 0.14224)
		(layer "In11.Cu")
		(net "M_M_DQS_DP<0>")
	)
	(arc
		(start 70.59676 -87.88019)
		(mid 70.405118 -87.937356)
		(end 70.265036 -88.080088)
		(width 0.0889)
		(layer "In11.Cu")
		(net "M_M_DQS_DP<0>")
	)
	(arc
		(start 72.3138 -86.88959)
		(mid 72.122158 -86.946756)
		(end 71.982076 -87.089488)
		(width 0.0889)
		(layer "In11.Cu")
		(net "M_M_DQS_DP<0>")
	)
	(arc
		(start 72.840596 -86.594188)
		(mid 72.631988 -86.80612)
		(end 72.346566 -86.88959)
		(width 0.0889)
		(layer "In11.Cu")
		(net "M_M_DQS_DP<0>")
	)
	(arc
		(start 71.982076 -87.089488)
		(mid 71.775072 -87.300352)
		(end 71.491856 -87.384636)
		(width 0.0889)
		(layer "In11.Cu")
		(net "M_M_DQS_DP<0>")
	)
	(arc
		(start 74.397616 -86.033356)
		(mid 74.305706 -85.980879)
		(end 74.210672 -85.934296)
		(width 0.0889)
		(layer "In11.Cu")
		(net "M_M_DQS_DP<0>")
	)
	(arc
		(start 70.265036 -88.080088)
		(mid 70.058032 -88.290952)
		(end 69.774816 -88.375236)
		(width 0.0889)
		(layer "In11.Cu")
		(net "M_M_DQS_DP<0>")
	)
	(arc
		(start 69.74205 -88.375236)
		(mid 69.5482 -88.431586)
		(end 69.406516 -88.575388)
		(width 0.0889)
		(layer "In11.Cu")
		(net "M_M_DQS_DP<0>")
	)
	(arc
		(start 74.210672 -85.934296)
		(mid 74.164462 -85.91676)
		(end 74.116438 -85.905086)
		(width 0.0889)
		(layer "In11.Cu")
		(net "M_M_DQS_DP<0>")
	)
	(arc
		(start 67.689476 -89.565988)
		(mid 67.479123 -89.77896)
		(end 67.191382 -89.86139)
		(width 0.0889)
		(layer "In11.Cu")
		(net "M_M_DQS_DP<0>")
	)
	(arc
		(start 71.45909 -87.384636)
		(mid 71.26524 -87.440986)
		(end 71.123556 -87.584788)
		(width 0.0889)
		(layer "In11.Cu")
		(net "M_M_DQS_DP<0>")
	)
	(arc
		(start 68.547996 -89.070688)
		(mid 68.340992 -89.281552)
		(end 68.057776 -89.365836)
		(width 0.0889)
		(layer "In11.Cu")
		(net "M_M_DQS_DP<0>")
	)
	(arc
		(start 68.02501 -89.365836)
		(mid 67.83116 -89.422186)
		(end 67.689476 -89.565988)
		(width 0.0889)
		(layer "In11.Cu")
		(net "M_M_DQS_DP<0>")
	)
	(arc
		(start 73.699116 -86.098888)
		(mid 73.492112 -86.309752)
		(end 73.208896 -86.394036)
		(width 0.0889)
		(layer "In11.Cu")
		(net "M_M_DQS_DP<0>")
	)
	(arc
		(start 74.03084 -85.89899)
		(mid 73.839198 -85.956156)
		(end 73.699116 -86.098888)
		(width 0.0889)
		(layer "In11.Cu")
		(net "M_M_DQS_DP<0>")
	)
	(arc
		(start 68.87972 -88.87079)
		(mid 68.688078 -88.927956)
		(end 68.547996 -89.070688)
		(width 0.0889)
		(layer "In11.Cu")
		(net "M_M_DQS_DP<0>")
	)
	(arc
		(start 74.116438 -85.905086)
		(mid 74.088732 -85.901061)
		(end 74.060812 -85.89899)
		(width 0.0889)
		(layer "In11.Cu")
		(net "M_M_DQS_DP<0>")
	)
	(arc
		(start 73.17613 -86.394036)
		(mid 72.98228 -86.450386)
		(end 72.840596 -86.594188)
		(width 0.0889)
		(layer "In11.Cu")
		(net "M_M_DQS_DP<0>")
	)
	(arc
		(start 69.406516 -88.575388)
		(mid 69.197908 -88.78732)
		(end 68.912486 -88.87079)
		(width 0.0889)
		(layer "In11.Cu")
		(net "M_M_DQS_DP<0>")
	)
	(arc
		(start 71.123556 -87.584788)
		(mid 70.914948 -87.79672)
		(end 70.629526 -87.88019)
		(width 0.0889)
		(layer "In11.Cu")
		(net "M_M_DQS_DP<0>")
	)
	(segment
		(start 35.649408 -152.932384)
		(end 35.231324 -153.350468)
		(width 0.1651)
		(layer "F.Cu")
		(net "M_M_DQS_DN<9>")
	)
	(segment
		(start 35.165284 -154.45613)
		(end 34.957004 -154.45613)
		(width 0.1651)
		(layer "F.Cu")
		(net "M_M_DQS_DN<9>")
	)
	(segment
		(start 35.649408 -152.273)
		(end 35.649408 -152.932384)
		(width 0.1651)
		(layer "F.Cu")
		(net "M_M_DQS_DN<9>")
	)
	(segment
		(start 35.417252 -154.204162)
		(end 35.165284 -154.45613)
		(width 0.1651)
		(layer "F.Cu")
		(net "M_M_DQS_DN<9>")
	)
	(segment
		(start 35.231324 -153.7716)
		(end 35.417252 -153.957528)
		(width 0.1651)
		(layer "F.Cu")
		(net "M_M_DQS_DN<9>")
	)
	(segment
		(start 77.192886 -86.794086)
		(end 76.621386 -86.794086)
		(width 0.1651)
		(layer "F.Cu")
		(net "M_M_DQS_DN<9>")
	)
	(segment
		(start 34.957004 -154.45613)
		(end 34.767774 -154.2669)
		(width 0.1651)
		(layer "F.Cu")
		(net "M_M_DQS_DN<9>")
	)
	(segment
		(start 34.767774 -154.2669)
		(end 34.748724 -154.2669)
		(width 0.1651)
		(layer "F.Cu")
		(net "M_M_DQS_DN<9>")
	)
	(segment
		(start 35.231324 -153.350468)
		(end 35.231324 -153.7716)
		(width 0.1651)
		(layer "F.Cu")
		(net "M_M_DQS_DN<9>")
	)
	(segment
		(start 35.417252 -153.957528)
		(end 35.417252 -154.204162)
		(width 0.1651)
		(layer "F.Cu")
		(net "M_M_DQS_DN<9>")
	)
	(via
		(at 34.748724 -154.2669)
		(size 0.508)
		(drill 0.254)
		(layers "F.Cu" "B.Cu")
		(net "M_M_DQS_DN<9>")
	)
	(via
		(at 34.74212 -150.0886)
		(size 0.508)
		(drill 0.254)
		(layers "F.Cu" "B.Cu")
		(net "M_M_DQS_DN<9>")
	)
	(via
		(at 76.621386 -86.794086)
		(size 0.508)
		(drill 0.254)
		(layers "F.Cu" "B.Cu")
		(net "M_M_DQS_DN<9>")
	)
	(segment
		(start 34.936684 -149.894036)
		(end 34.74212 -150.0886)
		(width 0.1651)
		(layer "B.Cu")
		(net "M_M_DQS_DN<9>")
	)
	(segment
		(start 35.16376 -149.894036)
		(end 34.936684 -149.894036)
		(width 0.1651)
		(layer "B.Cu")
		(net "M_M_DQS_DN<9>")
	)
	(segment
		(start 35.383724 -150.114)
		(end 35.16376 -149.894036)
		(width 0.1651)
		(layer "B.Cu")
		(net "M_M_DQS_DN<9>")
	)
	(segment
		(start 35.649408 -152.078436)
		(end 35.649662 -152.077928)
		(width 0.1651)
		(layer "B.Cu")
		(net "M_M_DQS_DN<9>")
	)
	(segment
		(start 35.205924 -150.622)
		(end 35.383724 -150.4442)
		(width 0.1651)
		(layer "B.Cu")
		(net "M_M_DQS_DN<9>")
	)
	(segment
		(start 35.649662 -151.421592)
		(end 35.205924 -150.977854)
		(width 0.1651)
		(layer "B.Cu")
		(net "M_M_DQS_DN<9>")
	)
	(segment
		(start 35.649662 -152.077928)
		(end 35.649662 -151.421592)
		(width 0.1651)
		(layer "B.Cu")
		(net "M_M_DQS_DN<9>")
	)
	(segment
		(start 35.383724 -150.4442)
		(end 35.383724 -150.114)
		(width 0.1651)
		(layer "B.Cu")
		(net "M_M_DQS_DN<9>")
	)
	(segment
		(start 35.205924 -150.977854)
		(end 35.205924 -150.622)
		(width 0.1651)
		(layer "B.Cu")
		(net "M_M_DQS_DN<9>")
	)
	(segment
		(start 66.533014 -88.565736)
		(end 66.838068 -88.87079)
		(width 0.0889)
		(layer "In11.Cu")
		(net "M_M_DQS_DN<9>")
	)
	(segment
		(start 36.772088 -112.19688)
		(end 40.612568 -108.3564)
		(width 0.14224)
		(layer "In11.Cu")
		(net "M_M_DQS_DN<9>")
	)
	(segment
		(start 34.793428 -151.83612)
		(end 34.948368 -151.99106)
		(width 0.14224)
		(layer "In11.Cu")
		(net "M_M_DQS_DN<9>")
	)
	(segment
		(start 76.599796 -86.394036)
		(end 76.632562 -86.394036)
		(width 0.0889)
		(layer "In11.Cu")
		(net "M_M_DQS_DN<9>")
	)
	(segment
		(start 66.838068 -88.87079)
		(end 67.191382 -88.87079)
		(width 0.0889)
		(layer "In11.Cu")
		(net "M_M_DQS_DN<9>")
	)
	(segment
		(start 34.646108 -152.49906)
		(end 34.506408 -152.63876)
		(width 0.14224)
		(layer "In11.Cu")
		(net "M_M_DQS_DN<9>")
	)
	(segment
		(start 35.181794 -153.83383)
		(end 34.748724 -154.2669)
		(width 0.14224)
		(layer "In11.Cu")
		(net "M_M_DQS_DN<9>")
	)
	(segment
		(start 34.74212 -150.0886)
		(end 35.176968 -150.523448)
		(width 0.14224)
		(layer "In11.Cu")
		(net "M_M_DQS_DN<9>")
	)
	(segment
		(start 34.755328 -150.0886)
		(end 35.52444 -149.319488)
		(width 0.14224)
		(layer "In11.Cu")
		(net "M_M_DQS_DN<9>")
	)
	(segment
		(start 35.512248 -115.938808)
		(end 35.639248 -115.811808)
		(width 0.14224)
		(layer "In11.Cu")
		(net "M_M_DQS_DN<9>")
	)
	(segment
		(start 34.638488 -151.83612)
		(end 34.793428 -151.83612)
		(width 0.14224)
		(layer "In11.Cu")
		(net "M_M_DQS_DN<9>")
	)
	(segment
		(start 35.512248 -116.558568)
		(end 35.512248 -115.938808)
		(width 0.14224)
		(layer "In11.Cu")
		(net "M_M_DQS_DN<9>")
	)
	(segment
		(start 35.395916 -118.40718)
		(end 36.447222 -118.40718)
		(width 0.14224)
		(layer "In11.Cu")
		(net "M_M_DQS_DN<9>")
	)
	(segment
		(start 72.3138 -85.89899)
		(end 72.346566 -85.89899)
		(width 0.0889)
		(layer "In11.Cu")
		(net "M_M_DQS_DN<9>")
	)
	(segment
		(start 35.68192 -148.08962)
		(end 35.52444 -147.93214)
		(width 0.14224)
		(layer "In11.Cu")
		(net "M_M_DQS_DN<9>")
	)
	(segment
		(start 35.176968 -150.523448)
		(end 35.176968 -150.9268)
		(width 0.14224)
		(layer "In11.Cu")
		(net "M_M_DQS_DN<9>")
	)
	(segment
		(start 40.612568 -107.8484)
		(end 45.006768 -103.4542)
		(width 0.14224)
		(layer "In11.Cu")
		(net "M_M_DQS_DN<9>")
	)
	(segment
		(start 70.59676 -86.88959)
		(end 70.629526 -86.88959)
		(width 0.0889)
		(layer "In11.Cu")
		(net "M_M_DQS_DN<9>")
	)
	(segment
		(start 52.906168 -98.39198)
		(end 62.693042 -88.605106)
		(width 0.14224)
		(layer "In11.Cu")
		(net "M_M_DQS_DN<9>")
	)
	(segment
		(start 34.656268 -151.2062)
		(end 34.506408 -151.35606)
		(width 0.14224)
		(layer "In11.Cu")
		(net "M_M_DQS_DN<9>")
	)
	(segment
		(start 69.74205 -87.384636)
		(end 69.774816 -87.384636)
		(width 0.0889)
		(layer "In11.Cu")
		(net "M_M_DQS_DN<9>")
	)
	(segment
		(start 76.830174 -86.914482)
		(end 76.621386 -86.794086)
		(width 0.0889)
		(layer "In11.Cu")
		(net "M_M_DQS_DN<9>")
	)
	(segment
		(start 35.68192 -147.26666)
		(end 35.52444 -147.10918)
		(width 0.14224)
		(layer "In11.Cu")
		(net "M_M_DQS_DN<9>")
	)
	(segment
		(start 62.693042 -88.605106)
		(end 65.55867 -88.605106)
		(width 0.14224)
		(layer "In11.Cu")
		(net "M_M_DQS_DN<9>")
	)
	(segment
		(start 40.612568 -108.3564)
		(end 40.612568 -107.8484)
		(width 0.14224)
		(layer "In11.Cu")
		(net "M_M_DQS_DN<9>")
	)
	(segment
		(start 35.639248 -116.685568)
		(end 35.512248 -116.558568)
		(width 0.14224)
		(layer "In11.Cu")
		(net "M_M_DQS_DN<9>")
	)
	(segment
		(start 75.745086 -85.89899)
		(end 75.777852 -85.89899)
		(width 0.0889)
		(layer "In11.Cu")
		(net "M_M_DQS_DN<9>")
	)
	(segment
		(start 34.793428 -152.49906)
		(end 34.646108 -152.49906)
		(width 0.14224)
		(layer "In11.Cu")
		(net "M_M_DQS_DN<9>")
	)
	(segment
		(start 34.948368 -151.99106)
		(end 34.948368 -152.34412)
		(width 0.14224)
		(layer "In11.Cu")
		(net "M_M_DQS_DN<9>")
	)
	(segment
		(start 36.772088 -117.063774)
		(end 36.393882 -116.685568)
		(width 0.14224)
		(layer "In11.Cu")
		(net "M_M_DQS_DN<9>")
	)
	(segment
		(start 34.506408 -151.35606)
		(end 34.506408 -151.70404)
		(width 0.14224)
		(layer "In11.Cu")
		(net "M_M_DQS_DN<9>")
	)
	(segment
		(start 34.668968 -153.162)
		(end 34.92754 -153.162)
		(width 0.14224)
		(layer "In11.Cu")
		(net "M_M_DQS_DN<9>")
	)
	(segment
		(start 36.393882 -115.811808)
		(end 36.772088 -115.433602)
		(width 0.14224)
		(layer "In11.Cu")
		(net "M_M_DQS_DN<9>")
	)
	(segment
		(start 35.52444 -147.67814)
		(end 35.68192 -147.52066)
		(width 0.14224)
		(layer "In11.Cu")
		(net "M_M_DQS_DN<9>")
	)
	(segment
		(start 76.993242 -86.941914)
		(end 76.914502 -86.96325)
		(width 0.0889)
		(layer "In11.Cu")
		(net "M_M_DQS_DN<9>")
	)
	(segment
		(start 52.906168 -99.384358)
		(end 52.906168 -98.39198)
		(width 0.14224)
		(layer "In11.Cu")
		(net "M_M_DQS_DN<9>")
	)
	(segment
		(start 35.146488 -118.656608)
		(end 35.395916 -118.40718)
		(width 0.14224)
		(layer "In11.Cu")
		(net "M_M_DQS_DN<9>")
	)
	(segment
		(start 34.506408 -152.63876)
		(end 34.506408 -152.99944)
		(width 0.14224)
		(layer "In11.Cu")
		(net "M_M_DQS_DN<9>")
	)
	(segment
		(start 34.74212 -150.0886)
		(end 34.755328 -150.0886)
		(width 0.14224)
		(layer "In11.Cu")
		(net "M_M_DQS_DN<9>")
	)
	(segment
		(start 34.506408 -152.99944)
		(end 34.668968 -153.162)
		(width 0.14224)
		(layer "In11.Cu")
		(net "M_M_DQS_DN<9>")
	)
	(segment
		(start 36.772088 -115.433602)
		(end 36.772088 -112.19688)
		(width 0.14224)
		(layer "In11.Cu")
		(net "M_M_DQS_DN<9>")
	)
	(segment
		(start 35.181794 -153.416254)
		(end 35.181794 -153.83383)
		(width 0.14224)
		(layer "In11.Cu")
		(net "M_M_DQS_DN<9>")
	)
	(segment
		(start 65.55867 -88.605106)
		(end 65.580768 -88.605106)
		(width 0.0889)
		(layer "In11.Cu")
		(net "M_M_DQS_DN<9>")
	)
	(segment
		(start 76.914502 -86.96325)
		(end 76.830174 -86.914482)
		(width 0.0889)
		(layer "In11.Cu")
		(net "M_M_DQS_DN<9>")
	)
	(segment
		(start 68.02501 -88.375236)
		(end 68.057776 -88.375236)
		(width 0.0889)
		(layer "In11.Cu")
		(net "M_M_DQS_DN<9>")
	)
	(segment
		(start 74.882756 -85.403436)
		(end 74.915522 -85.403436)
		(width 0.0889)
		(layer "In11.Cu")
		(net "M_M_DQS_DN<9>")
	)
	(segment
		(start 36.772088 -118.082314)
		(end 36.772088 -117.063774)
		(width 0.14224)
		(layer "In11.Cu")
		(net "M_M_DQS_DN<9>")
	)
	(segment
		(start 35.52444 -126.653798)
		(end 35.146488 -126.275846)
		(width 0.14224)
		(layer "In11.Cu")
		(net "M_M_DQS_DN<9>")
	)
	(segment
		(start 34.92754 -153.162)
		(end 35.181794 -153.416254)
		(width 0.14224)
		(layer "In11.Cu")
		(net "M_M_DQS_DN<9>")
	)
	(segment
		(start 35.146488 -126.275846)
		(end 35.146488 -118.656608)
		(width 0.14224)
		(layer "In11.Cu")
		(net "M_M_DQS_DN<9>")
	)
	(segment
		(start 36.447222 -118.40718)
		(end 36.772088 -118.082314)
		(width 0.14224)
		(layer "In11.Cu")
		(net "M_M_DQS_DN<9>")
	)
	(segment
		(start 35.52444 -149.319488)
		(end 35.52444 -148.5011)
		(width 0.14224)
		(layer "In11.Cu")
		(net "M_M_DQS_DN<9>")
	)
	(segment
		(start 34.948368 -152.34412)
		(end 34.793428 -152.49906)
		(width 0.14224)
		(layer "In11.Cu")
		(net "M_M_DQS_DN<9>")
	)
	(segment
		(start 35.639248 -115.811808)
		(end 36.393882 -115.811808)
		(width 0.14224)
		(layer "In11.Cu")
		(net "M_M_DQS_DN<9>")
	)
	(segment
		(start 45.006768 -103.4542)
		(end 48.836326 -103.4542)
		(width 0.14224)
		(layer "In11.Cu")
		(net "M_M_DQS_DN<9>")
	)
	(segment
		(start 74.03084 -84.90839)
		(end 74.060812 -84.90839)
		(width 0.0889)
		(layer "In11.Cu")
		(net "M_M_DQS_DN<9>")
	)
	(segment
		(start 68.87972 -87.88019)
		(end 68.912486 -87.88019)
		(width 0.0889)
		(layer "In11.Cu")
		(net "M_M_DQS_DN<9>")
	)
	(segment
		(start 36.393882 -116.685568)
		(end 35.639248 -116.685568)
		(width 0.14224)
		(layer "In11.Cu")
		(net "M_M_DQS_DN<9>")
	)
	(segment
		(start 71.45909 -86.394036)
		(end 71.491856 -86.394036)
		(width 0.0889)
		(layer "In11.Cu")
		(net "M_M_DQS_DN<9>")
	)
	(segment
		(start 73.17613 -85.403436)
		(end 73.208896 -85.403436)
		(width 0.0889)
		(layer "In11.Cu")
		(net "M_M_DQS_DN<9>")
	)
	(segment
		(start 65.620138 -88.565736)
		(end 66.533014 -88.565736)
		(width 0.0889)
		(layer "In11.Cu")
		(net "M_M_DQS_DN<9>")
	)
	(segment
		(start 35.176968 -150.9268)
		(end 34.897568 -151.2062)
		(width 0.14224)
		(layer "In11.Cu")
		(net "M_M_DQS_DN<9>")
	)
	(segment
		(start 65.580768 -88.605106)
		(end 65.620138 -88.565736)
		(width 0.0889)
		(layer "In11.Cu")
		(net "M_M_DQS_DN<9>")
	)
	(segment
		(start 35.52444 -147.10918)
		(end 35.52444 -126.653798)
		(width 0.14224)
		(layer "In11.Cu")
		(net "M_M_DQS_DN<9>")
	)
	(segment
		(start 35.68192 -148.34362)
		(end 35.68192 -148.08962)
		(width 0.14224)
		(layer "In11.Cu")
		(net "M_M_DQS_DN<9>")
	)
	(segment
		(start 34.506408 -151.70404)
		(end 34.638488 -151.83612)
		(width 0.14224)
		(layer "In11.Cu")
		(net "M_M_DQS_DN<9>")
	)
	(segment
		(start 35.52444 -147.93214)
		(end 35.52444 -147.67814)
		(width 0.14224)
		(layer "In11.Cu")
		(net "M_M_DQS_DN<9>")
	)
	(segment
		(start 48.836326 -103.4542)
		(end 52.906168 -99.384358)
		(width 0.14224)
		(layer "In11.Cu")
		(net "M_M_DQS_DN<9>")
	)
	(segment
		(start 35.68192 -147.52066)
		(end 35.68192 -147.26666)
		(width 0.14224)
		(layer "In11.Cu")
		(net "M_M_DQS_DN<9>")
	)
	(segment
		(start 34.897568 -151.2062)
		(end 34.656268 -151.2062)
		(width 0.14224)
		(layer "In11.Cu")
		(net "M_M_DQS_DN<9>")
	)
	(segment
		(start 35.52444 -148.5011)
		(end 35.68192 -148.34362)
		(width 0.14224)
		(layer "In11.Cu")
		(net "M_M_DQS_DN<9>")
	)
	(arc
		(start 69.406516 -87.584788)
		(mid 69.548199 -87.440984)
		(end 69.74205 -87.384636)
		(width 0.0889)
		(layer "In11.Cu")
		(net "M_M_DQS_DN<9>")
	)
	(arc
		(start 69.774816 -87.384636)
		(mid 70.058033 -87.300355)
		(end 70.265036 -87.089488)
		(width 0.0889)
		(layer "In11.Cu")
		(net "M_M_DQS_DN<9>")
	)
	(arc
		(start 75.777852 -85.89899)
		(mid 75.969494 -85.956156)
		(end 76.109576 -86.098888)
		(width 0.0889)
		(layer "In11.Cu")
		(net "M_M_DQS_DN<9>")
	)
	(arc
		(start 74.060812 -84.90839)
		(mid 74.252454 -84.965556)
		(end 74.392536 -85.108288)
		(width 0.0889)
		(layer "In11.Cu")
		(net "M_M_DQS_DN<9>")
	)
	(arc
		(start 70.265036 -87.089488)
		(mid 70.405115 -86.946752)
		(end 70.59676 -86.88959)
		(width 0.0889)
		(layer "In11.Cu")
		(net "M_M_DQS_DN<9>")
	)
	(arc
		(start 72.346566 -85.89899)
		(mid 72.63199 -85.815523)
		(end 72.840596 -85.603588)
		(width 0.0889)
		(layer "In11.Cu")
		(net "M_M_DQS_DN<9>")
	)
	(arc
		(start 67.191382 -88.87079)
		(mid 67.479069 -88.788269)
		(end 67.689476 -88.575388)
		(width 0.0889)
		(layer "In11.Cu")
		(net "M_M_DQS_DN<9>")
	)
	(arc
		(start 71.123556 -86.594188)
		(mid 71.265239 -86.450384)
		(end 71.45909 -86.394036)
		(width 0.0889)
		(layer "In11.Cu")
		(net "M_M_DQS_DN<9>")
	)
	(arc
		(start 74.392536 -85.108288)
		(mid 74.59954 -85.319152)
		(end 74.882756 -85.403436)
		(width 0.0889)
		(layer "In11.Cu")
		(net "M_M_DQS_DN<9>")
	)
	(arc
		(start 72.840596 -85.603588)
		(mid 72.982279 -85.459784)
		(end 73.17613 -85.403436)
		(width 0.0889)
		(layer "In11.Cu")
		(net "M_M_DQS_DN<9>")
	)
	(arc
		(start 73.699116 -85.108288)
		(mid 73.839195 -84.965552)
		(end 74.03084 -84.90839)
		(width 0.0889)
		(layer "In11.Cu")
		(net "M_M_DQS_DN<9>")
	)
	(arc
		(start 73.208896 -85.403436)
		(mid 73.492113 -85.319155)
		(end 73.699116 -85.108288)
		(width 0.0889)
		(layer "In11.Cu")
		(net "M_M_DQS_DN<9>")
	)
	(arc
		(start 68.912486 -87.88019)
		(mid 69.19791 -87.796723)
		(end 69.406516 -87.584788)
		(width 0.0889)
		(layer "In11.Cu")
		(net "M_M_DQS_DN<9>")
	)
	(arc
		(start 76.632562 -86.394036)
		(mid 76.955447 -86.574077)
		(end 76.993242 -86.941914)
		(width 0.0889)
		(layer "In11.Cu")
		(net "M_M_DQS_DN<9>")
	)
	(arc
		(start 71.491856 -86.394036)
		(mid 71.775073 -86.309755)
		(end 71.982076 -86.098888)
		(width 0.0889)
		(layer "In11.Cu")
		(net "M_M_DQS_DN<9>")
	)
	(arc
		(start 67.689476 -88.575388)
		(mid 67.831159 -88.431584)
		(end 68.02501 -88.375236)
		(width 0.0889)
		(layer "In11.Cu")
		(net "M_M_DQS_DN<9>")
	)
	(arc
		(start 76.109576 -86.098888)
		(mid 76.31658 -86.309752)
		(end 76.599796 -86.394036)
		(width 0.0889)
		(layer "In11.Cu")
		(net "M_M_DQS_DN<9>")
	)
	(arc
		(start 70.629526 -86.88959)
		(mid 70.91495 -86.806123)
		(end 71.123556 -86.594188)
		(width 0.0889)
		(layer "In11.Cu")
		(net "M_M_DQS_DN<9>")
	)
	(arc
		(start 75.251056 -85.603588)
		(mid 75.459664 -85.81552)
		(end 75.745086 -85.89899)
		(width 0.0889)
		(layer "In11.Cu")
		(net "M_M_DQS_DN<9>")
	)
	(arc
		(start 68.547996 -88.080088)
		(mid 68.688075 -87.937352)
		(end 68.87972 -87.88019)
		(width 0.0889)
		(layer "In11.Cu")
		(net "M_M_DQS_DN<9>")
	)
	(arc
		(start 68.057776 -88.375236)
		(mid 68.340993 -88.290955)
		(end 68.547996 -88.080088)
		(width 0.0889)
		(layer "In11.Cu")
		(net "M_M_DQS_DN<9>")
	)
	(arc
		(start 71.982076 -86.098888)
		(mid 72.122155 -85.956152)
		(end 72.3138 -85.89899)
		(width 0.0889)
		(layer "In11.Cu")
		(net "M_M_DQS_DN<9>")
	)
	(arc
		(start 74.915522 -85.403436)
		(mid 75.109372 -85.459786)
		(end 75.251056 -85.603588)
		(width 0.0889)
		(layer "In11.Cu")
		(net "M_M_DQS_DN<9>")
	)
	(segment
		(start 72.667368 -154.991054)
		(end 72.997822 -154.6606)
		(width 0.1651)
		(layer "F.Cu")
		(net "M_M_DQS_DN<8>")
	)
	(segment
		(start 73.049384 -155.80487)
		(end 72.667368 -155.422854)
		(width 0.1651)
		(layer "F.Cu")
		(net "M_M_DQS_DN<8>")
	)
	(segment
		(start 72.997822 -154.6606)
		(end 73.22185 -154.6606)
		(width 0.1651)
		(layer "F.Cu")
		(net "M_M_DQS_DN<8>")
	)
	(segment
		(start 81.485232 -85.30844)
		(end 80.913732 -85.30844)
		(width 0.1651)
		(layer "F.Cu")
		(net "M_M_DQS_DN<8>")
	)
	(segment
		(start 73.22185 -154.6606)
		(end 73.437496 -154.876246)
		(width 0.1651)
		(layer "F.Cu")
		(net "M_M_DQS_DN<8>")
	)
	(segment
		(start 73.049384 -156.87294)
		(end 73.049384 -155.80487)
		(width 0.1651)
		(layer "F.Cu")
		(net "M_M_DQS_DN<8>")
	)
	(segment
		(start 72.667368 -155.422854)
		(end 72.667368 -154.991054)
		(width 0.1651)
		(layer "F.Cu")
		(net "M_M_DQS_DN<8>")
	)
	(via
		(at 73.437496 -149.482556)
		(size 0.508)
		(drill 0.254)
		(layers "F.Cu" "B.Cu")
		(net "M_M_DQS_DN<8>")
	)
	(via
		(at 73.437496 -154.876246)
		(size 0.508)
		(drill 0.254)
		(layers "F.Cu" "B.Cu")
		(net "M_M_DQS_DN<8>")
	)
	(via
		(at 80.913732 -85.30844)
		(size 0.508)
		(drill 0.254)
		(layers "F.Cu" "B.Cu")
		(net "M_M_DQS_DN<8>")
	)
	(segment
		(start 72.921368 -148.513546)
		(end 72.921368 -148.767546)
		(width 0.1651)
		(layer "B.Cu")
		(net "M_M_DQS_DN<8>")
	)
	(segment
		(start 73.049384 -147.478496)
		(end 73.049384 -148.38553)
		(width 0.1651)
		(layer "B.Cu")
		(net "M_M_DQS_DN<8>")
	)
	(segment
		(start 72.667368 -149.021546)
		(end 72.667368 -149.352)
		(width 0.1651)
		(layer "B.Cu")
		(net "M_M_DQS_DN<8>")
	)
	(segment
		(start 72.667368 -149.352)
		(end 73.022968 -149.7076)
		(width 0.1651)
		(layer "B.Cu")
		(net "M_M_DQS_DN<8>")
	)
	(segment
		(start 73.049384 -148.38553)
		(end 72.921368 -148.513546)
		(width 0.1651)
		(layer "B.Cu")
		(net "M_M_DQS_DN<8>")
	)
	(segment
		(start 72.921368 -148.767546)
		(end 72.667368 -149.021546)
		(width 0.1651)
		(layer "B.Cu")
		(net "M_M_DQS_DN<8>")
	)
	(segment
		(start 73.022968 -149.7076)
		(end 73.212452 -149.7076)
		(width 0.1651)
		(layer "B.Cu")
		(net "M_M_DQS_DN<8>")
	)
	(segment
		(start 73.212452 -149.7076)
		(end 73.437496 -149.482556)
		(width 0.1651)
		(layer "B.Cu")
		(net "M_M_DQS_DN<8>")
	)
	(segment
		(start 81.258156 -96.408494)
		(end 81.256886 -96.411034)
		(width 0.0889)
		(layer "In4.Cu")
		(net "M_M_DQS_DN<8>")
	)
	(segment
		(start 81.265268 -86.490302)
		(end 81.260442 -86.498938)
		(width 0.0889)
		(layer "In4.Cu")
		(net "M_M_DQS_DN<8>")
	)
	(segment
		(start 73.950576 -142.866618)
		(end 73.950576 -143.161004)
		(width 0.14224)
		(layer "In4.Cu")
		(net "M_M_DQS_DN<8>")
	)
	(segment
		(start 73.853802 -146.474942)
		(end 73.853802 -146.728942)
		(width 0.14224)
		(layer "In4.Cu")
		(net "M_M_DQS_DN<8>")
	)
	(segment
		(start 81.265268 -87.480902)
		(end 81.260442 -87.489538)
		(width 0.0889)
		(layer "In4.Cu")
		(net "M_M_DQS_DN<8>")
	)
	(segment
		(start 81.265268 -90.452702)
		(end 81.260442 -90.461338)
		(width 0.0889)
		(layer "In4.Cu")
		(net "M_M_DQS_DN<8>")
	)
	(segment
		(start 73.950576 -145.835116)
		(end 73.950576 -146.378168)
		(width 0.14224)
		(layer "In4.Cu")
		(net "M_M_DQS_DN<8>")
	)
	(segment
		(start 81.110582 -102.686612)
		(end 81.110582 -103.87203)
		(width 0.0889)
		(layer "In4.Cu")
		(net "M_M_DQS_DN<8>")
	)
	(segment
		(start 73.950576 -148.532342)
		(end 73.950576 -149.248876)
		(width 0.14224)
		(layer "In4.Cu")
		(net "M_M_DQS_DN<8>")
	)
	(segment
		(start 81.260442 -95.414338)
		(end 81.254092 -95.425006)
		(width 0.0889)
		(layer "In4.Cu")
		(net "M_M_DQS_DN<8>")
	)
	(segment
		(start 74.566526 -117.235224)
		(end 74.566526 -117.91188)
		(width 0.14224)
		(layer "In4.Cu")
		(net "M_M_DQS_DN<8>")
	)
	(segment
		(start 74.788014 -111.647732)
		(end 74.788014 -115.46205)
		(width 0.14224)
		(layer "In4.Cu")
		(net "M_M_DQS_DN<8>")
	)
	(segment
		(start 73.793096 -132.020564)
		(end 73.793096 -132.274564)
		(width 0.14224)
		(layer "In4.Cu")
		(net "M_M_DQS_DN<8>")
	)
	(segment
		(start 73.950576 -147.709382)
		(end 73.950576 -147.963382)
		(width 0.14224)
		(layer "In4.Cu")
		(net "M_M_DQS_DN<8>")
	)
	(segment
		(start 73.793096 -147.297902)
		(end 73.793096 -147.551902)
		(width 0.14224)
		(layer "In4.Cu")
		(net "M_M_DQS_DN<8>")
	)
	(segment
		(start 74.55408 -115.695984)
		(end 73.889616 -115.695984)
		(width 0.14224)
		(layer "In4.Cu")
		(net "M_M_DQS_DN<8>")
	)
	(segment
		(start 81.071212 -103.9114)
		(end 81.071212 -103.933498)
		(width 0.0889)
		(layer "In4.Cu")
		(net "M_M_DQS_DN<8>")
	)
	(segment
		(start 81.260442 -87.489538)
		(end 81.254092 -87.500206)
		(width 0.0889)
		(layer "In4.Cu")
		(net "M_M_DQS_DN<8>")
	)
	(segment
		(start 73.840086 -145.470626)
		(end 73.840086 -145.724626)
		(width 0.14224)
		(layer "In4.Cu")
		(net "M_M_DQS_DN<8>")
	)
	(segment
		(start 74.566526 -117.91188)
		(end 74.439526 -118.03888)
		(width 0.14224)
		(layer "In4.Cu")
		(net "M_M_DQS_DN<8>")
	)
	(segment
		(start 73.104248 -122.898408)
		(end 73.950576 -123.744736)
		(width 0.14224)
		(layer "In4.Cu")
		(net "M_M_DQS_DN<8>")
	)
	(segment
		(start 73.853802 -146.728942)
		(end 73.950576 -146.825716)
		(width 0.14224)
		(layer "In4.Cu")
		(net "M_M_DQS_DN<8>")
	)
	(segment
		(start 81.265268 -95.405702)
		(end 81.260442 -95.414338)
		(width 0.0889)
		(layer "In4.Cu")
		(net "M_M_DQS_DN<8>")
	)
	(segment
		(start 80.913732 -85.30844)
		(end 81.182972 -85.96884)
		(width 0.0889)
		(layer "In4.Cu")
		(net "M_M_DQS_DN<8>")
	)
	(segment
		(start 81.182972 -85.96884)
		(end 81.260442 -86.098888)
		(width 0.0889)
		(layer "In4.Cu")
		(net "M_M_DQS_DN<8>")
	)
	(segment
		(start 73.793096 -133.920484)
		(end 73.950576 -134.077964)
		(width 0.14224)
		(layer "In4.Cu")
		(net "M_M_DQS_DN<8>")
	)
	(segment
		(start 73.950576 -134.077964)
		(end 73.950576 -136.726422)
		(width 0.14224)
		(layer "In4.Cu")
		(net "M_M_DQS_DN<8>")
	)
	(segment
		(start 73.889616 -115.695984)
		(end 73.510648 -116.074952)
		(width 0.14224)
		(layer "In4.Cu")
		(net "M_M_DQS_DN<8>")
	)
	(segment
		(start 73.950576 -123.744736)
		(end 73.950576 -131.863084)
		(width 0.14224)
		(layer "In4.Cu")
		(net "M_M_DQS_DN<8>")
	)
	(segment
		(start 73.950576 -142.297658)
		(end 73.793096 -142.455138)
		(width 0.14224)
		(layer "In4.Cu")
		(net "M_M_DQS_DN<8>")
	)
	(segment
		(start 73.950576 -136.726422)
		(end 73.793096 -136.883902)
		(width 0.14224)
		(layer "In4.Cu")
		(net "M_M_DQS_DN<8>")
	)
	(segment
		(start 73.840086 -145.724626)
		(end 73.950576 -145.835116)
		(width 0.14224)
		(layer "In4.Cu")
		(net "M_M_DQS_DN<8>")
	)
	(segment
		(start 73.793096 -141.886178)
		(end 73.950576 -142.043658)
		(width 0.14224)
		(layer "In4.Cu")
		(net "M_M_DQS_DN<8>")
	)
	(segment
		(start 73.793096 -147.551902)
		(end 73.950576 -147.709382)
		(width 0.14224)
		(layer "In4.Cu")
		(net "M_M_DQS_DN<8>")
	)
	(segment
		(start 81.110582 -103.87203)
		(end 81.071212 -103.9114)
		(width 0.0889)
		(layer "In4.Cu")
		(net "M_M_DQS_DN<8>")
	)
	(segment
		(start 81.260442 -96.404938)
		(end 81.259172 -96.40697)
		(width 0.0889)
		(layer "In4.Cu")
		(net "M_M_DQS_DN<8>")
	)
	(segment
		(start 80.894682 -100.79863)
		(end 80.894682 -102.313232)
		(width 0.0889)
		(layer "In4.Cu")
		(net "M_M_DQS_DN<8>")
	)
	(segment
		(start 73.793096 -133.666484)
		(end 73.793096 -133.920484)
		(width 0.14224)
		(layer "In4.Cu")
		(net "M_M_DQS_DN<8>")
	)
	(segment
		(start 81.259172 -96.40697)
		(end 81.258156 -96.408494)
		(width 0.0889)
		(layer "In4.Cu")
		(net "M_M_DQS_DN<8>")
	)
	(segment
		(start 73.950576 -137.549382)
		(end 73.793096 -137.706862)
		(width 0.14224)
		(layer "In4.Cu")
		(net "M_M_DQS_DN<8>")
	)
	(segment
		(start 73.950576 -131.863084)
		(end 73.793096 -132.020564)
		(width 0.14224)
		(layer "In4.Cu")
		(net "M_M_DQS_DN<8>")
	)
	(segment
		(start 81.256886 -96.411034)
		(end 81.254092 -96.415606)
		(width 0.0889)
		(layer "In4.Cu")
		(net "M_M_DQS_DN<8>")
	)
	(segment
		(start 73.83018 -143.5354)
		(end 73.950576 -143.655796)
		(width 0.14224)
		(layer "In4.Cu")
		(net "M_M_DQS_DN<8>")
	)
	(segment
		(start 73.83018 -143.2814)
		(end 73.83018 -143.5354)
		(width 0.14224)
		(layer "In4.Cu")
		(net "M_M_DQS_DN<8>")
	)
	(segment
		(start 73.950576 -146.825716)
		(end 73.950576 -147.140422)
		(width 0.14224)
		(layer "In4.Cu")
		(net "M_M_DQS_DN<8>")
	)
	(segment
		(start 81.260442 -89.470738)
		(end 81.254092 -89.481406)
		(width 0.0889)
		(layer "In4.Cu")
		(net "M_M_DQS_DN<8>")
	)
	(segment
		(start 81.260442 -92.442538)
		(end 81.254092 -92.453206)
		(width 0.0889)
		(layer "In4.Cu")
		(net "M_M_DQS_DN<8>")
	)
	(segment
		(start 73.950576 -133.509004)
		(end 73.793096 -133.666484)
		(width 0.14224)
		(layer "In4.Cu")
		(net "M_M_DQS_DN<8>")
	)
	(segment
		(start 73.510648 -116.729256)
		(end 73.889616 -117.108224)
		(width 0.14224)
		(layer "In4.Cu")
		(net "M_M_DQS_DN<8>")
	)
	(segment
		(start 81.317592 -97.09531)
		(end 81.317592 -100.37572)
		(width 0.0889)
		(layer "In4.Cu")
		(net "M_M_DQS_DN<8>")
	)
	(segment
		(start 81.317592 -100.37572)
		(end 80.894682 -100.79863)
		(width 0.0889)
		(layer "In4.Cu")
		(net "M_M_DQS_DN<8>")
	)
	(segment
		(start 81.071212 -105.364788)
		(end 74.788014 -111.647732)
		(width 0.14224)
		(layer "In4.Cu")
		(net "M_M_DQS_DN<8>")
	)
	(segment
		(start 73.793096 -137.137902)
		(end 73.950576 -137.295382)
		(width 0.14224)
		(layer "In4.Cu")
		(net "M_M_DQS_DN<8>")
	)
	(segment
		(start 81.260442 -90.461338)
		(end 81.254092 -90.472006)
		(width 0.0889)
		(layer "In4.Cu")
		(net "M_M_DQS_DN<8>")
	)
	(segment
		(start 81.265268 -88.471502)
		(end 81.260442 -88.480138)
		(width 0.0889)
		(layer "In4.Cu")
		(net "M_M_DQS_DN<8>")
	)
	(segment
		(start 73.950576 -133.255004)
		(end 73.950576 -133.509004)
		(width 0.14224)
		(layer "In4.Cu")
		(net "M_M_DQS_DN<8>")
	)
	(segment
		(start 73.793096 -132.843524)
		(end 73.793096 -133.097524)
		(width 0.14224)
		(layer "In4.Cu")
		(net "M_M_DQS_DN<8>")
	)
	(segment
		(start 81.265268 -91.443302)
		(end 81.260442 -91.451938)
		(width 0.0889)
		(layer "In4.Cu")
		(net "M_M_DQS_DN<8>")
	)
	(segment
		(start 81.260442 -88.480138)
		(end 81.254092 -88.490806)
		(width 0.0889)
		(layer "In4.Cu")
		(net "M_M_DQS_DN<8>")
	)
	(segment
		(start 73.950576 -143.161004)
		(end 73.83018 -143.2814)
		(width 0.14224)
		(layer "In4.Cu")
		(net "M_M_DQS_DN<8>")
	)
	(segment
		(start 73.793096 -136.883902)
		(end 73.793096 -137.137902)
		(width 0.14224)
		(layer "In4.Cu")
		(net "M_M_DQS_DN<8>")
	)
	(segment
		(start 73.950576 -141.474698)
		(end 73.793096 -141.632178)
		(width 0.14224)
		(layer "In4.Cu")
		(net "M_M_DQS_DN<8>")
	)
	(segment
		(start 81.260442 -96.995488)
		(end 81.317592 -97.09531)
		(width 0.0889)
		(layer "In4.Cu")
		(net "M_M_DQS_DN<8>")
	)
	(segment
		(start 73.793096 -138.783822)
		(end 73.950576 -138.941302)
		(width 0.14224)
		(layer "In4.Cu")
		(net "M_M_DQS_DN<8>")
	)
	(segment
		(start 73.534016 -118.03888)
		(end 73.104248 -118.468648)
		(width 0.14224)
		(layer "In4.Cu")
		(net "M_M_DQS_DN<8>")
	)
	(segment
		(start 73.950576 -147.140422)
		(end 73.793096 -147.297902)
		(width 0.14224)
		(layer "In4.Cu")
		(net "M_M_DQS_DN<8>")
	)
	(segment
		(start 73.716896 -149.482556)
		(end 73.437496 -149.482556)
		(width 0.14224)
		(layer "In4.Cu")
		(net "M_M_DQS_DN<8>")
	)
	(segment
		(start 73.793096 -137.960862)
		(end 73.950576 -138.118342)
		(width 0.14224)
		(layer "In4.Cu")
		(net "M_M_DQS_DN<8>")
	)
	(segment
		(start 73.950576 -138.372342)
		(end 73.793096 -138.529822)
		(width 0.14224)
		(layer "In4.Cu")
		(net "M_M_DQS_DN<8>")
	)
	(segment
		(start 73.793096 -133.097524)
		(end 73.950576 -133.255004)
		(width 0.14224)
		(layer "In4.Cu")
		(net "M_M_DQS_DN<8>")
	)
	(segment
		(start 73.950576 -132.686044)
		(end 73.793096 -132.843524)
		(width 0.14224)
		(layer "In4.Cu")
		(net "M_M_DQS_DN<8>")
	)
	(segment
		(start 73.950576 -137.295382)
		(end 73.950576 -137.549382)
		(width 0.14224)
		(layer "In4.Cu")
		(net "M_M_DQS_DN<8>")
	)
	(segment
		(start 73.889616 -117.108224)
		(end 74.439526 -117.108224)
		(width 0.14224)
		(layer "In4.Cu")
		(net "M_M_DQS_DN<8>")
	)
	(segment
		(start 73.510648 -116.074952)
		(end 73.510648 -116.729256)
		(width 0.14224)
		(layer "In4.Cu")
		(net "M_M_DQS_DN<8>")
	)
	(segment
		(start 73.104248 -118.468648)
		(end 73.104248 -122.898408)
		(width 0.14224)
		(layer "In4.Cu")
		(net "M_M_DQS_DN<8>")
	)
	(segment
		(start 81.254092 -94.01302)
		(end 81.260442 -94.023688)
		(width 0.0889)
		(layer "In4.Cu")
		(net "M_M_DQS_DN<8>")
	)
	(segment
		(start 73.793096 -141.632178)
		(end 73.793096 -141.886178)
		(width 0.14224)
		(layer "In4.Cu")
		(net "M_M_DQS_DN<8>")
	)
	(segment
		(start 74.439526 -117.108224)
		(end 74.566526 -117.235224)
		(width 0.14224)
		(layer "In4.Cu")
		(net "M_M_DQS_DN<8>")
	)
	(segment
		(start 81.071212 -103.933498)
		(end 81.071212 -105.364788)
		(width 0.14224)
		(layer "In4.Cu")
		(net "M_M_DQS_DN<8>")
	)
	(segment
		(start 81.260442 -86.498938)
		(end 81.254092 -86.509606)
		(width 0.0889)
		(layer "In4.Cu")
		(net "M_M_DQS_DN<8>")
	)
	(segment
		(start 81.265268 -89.462102)
		(end 81.260442 -89.470738)
		(width 0.0889)
		(layer "In4.Cu")
		(net "M_M_DQS_DN<8>")
	)
	(segment
		(start 73.950576 -147.963382)
		(end 73.793096 -148.120862)
		(width 0.14224)
		(layer "In4.Cu")
		(net "M_M_DQS_DN<8>")
	)
	(segment
		(start 73.793096 -148.374862)
		(end 73.950576 -148.532342)
		(width 0.14224)
		(layer "In4.Cu")
		(net "M_M_DQS_DN<8>")
	)
	(segment
		(start 81.265268 -93.424502)
		(end 81.260442 -93.433138)
		(width 0.0889)
		(layer "In4.Cu")
		(net "M_M_DQS_DN<8>")
	)
	(segment
		(start 74.439526 -118.03888)
		(end 73.534016 -118.03888)
		(width 0.14224)
		(layer "In4.Cu")
		(net "M_M_DQS_DN<8>")
	)
	(segment
		(start 73.950576 -138.941302)
		(end 73.950576 -141.474698)
		(width 0.14224)
		(layer "In4.Cu")
		(net "M_M_DQS_DN<8>")
	)
	(segment
		(start 73.793096 -138.529822)
		(end 73.793096 -138.783822)
		(width 0.14224)
		(layer "In4.Cu")
		(net "M_M_DQS_DN<8>")
	)
	(segment
		(start 73.793096 -132.274564)
		(end 73.950576 -132.432044)
		(width 0.14224)
		(layer "In4.Cu")
		(net "M_M_DQS_DN<8>")
	)
	(segment
		(start 81.265268 -92.433902)
		(end 81.260442 -92.442538)
		(width 0.0889)
		(layer "In4.Cu")
		(net "M_M_DQS_DN<8>")
	)
	(segment
		(start 81.260442 -91.451938)
		(end 81.254092 -91.462606)
		(width 0.0889)
		(layer "In4.Cu")
		(net "M_M_DQS_DN<8>")
	)
	(segment
		(start 73.950576 -142.043658)
		(end 73.950576 -142.297658)
		(width 0.14224)
		(layer "In4.Cu")
		(net "M_M_DQS_DN<8>")
	)
	(segment
		(start 74.788014 -115.46205)
		(end 74.55408 -115.695984)
		(width 0.14224)
		(layer "In4.Cu")
		(net "M_M_DQS_DN<8>")
	)
	(segment
		(start 73.950576 -149.248876)
		(end 73.716896 -149.482556)
		(width 0.14224)
		(layer "In4.Cu")
		(net "M_M_DQS_DN<8>")
	)
	(segment
		(start 73.793096 -142.455138)
		(end 73.793096 -142.709138)
		(width 0.14224)
		(layer "In4.Cu")
		(net "M_M_DQS_DN<8>")
	)
	(segment
		(start 73.950576 -145.360136)
		(end 73.840086 -145.470626)
		(width 0.14224)
		(layer "In4.Cu")
		(net "M_M_DQS_DN<8>")
	)
	(segment
		(start 73.950576 -146.378168)
		(end 73.853802 -146.474942)
		(width 0.14224)
		(layer "In4.Cu")
		(net "M_M_DQS_DN<8>")
	)
	(segment
		(start 73.793096 -148.120862)
		(end 73.793096 -148.374862)
		(width 0.14224)
		(layer "In4.Cu")
		(net "M_M_DQS_DN<8>")
	)
	(segment
		(start 81.265268 -96.396302)
		(end 81.260442 -96.404938)
		(width 0.0889)
		(layer "In4.Cu")
		(net "M_M_DQS_DN<8>")
	)
	(segment
		(start 73.793096 -137.706862)
		(end 73.793096 -137.960862)
		(width 0.14224)
		(layer "In4.Cu")
		(net "M_M_DQS_DN<8>")
	)
	(segment
		(start 73.950576 -132.432044)
		(end 73.950576 -132.686044)
		(width 0.14224)
		(layer "In4.Cu")
		(net "M_M_DQS_DN<8>")
	)
	(segment
		(start 80.894682 -102.313232)
		(end 81.110582 -102.686612)
		(width 0.0889)
		(layer "In4.Cu")
		(net "M_M_DQS_DN<8>")
	)
	(segment
		(start 73.950576 -143.655796)
		(end 73.950576 -145.360136)
		(width 0.14224)
		(layer "In4.Cu")
		(net "M_M_DQS_DN<8>")
	)
	(segment
		(start 73.950576 -138.118342)
		(end 73.950576 -138.372342)
		(width 0.14224)
		(layer "In4.Cu")
		(net "M_M_DQS_DN<8>")
	)
	(segment
		(start 73.793096 -142.709138)
		(end 73.950576 -142.866618)
		(width 0.14224)
		(layer "In4.Cu")
		(net "M_M_DQS_DN<8>")
	)
	(arc
		(start 81.254092 -95.425006)
		(mid 81.181294 -95.715769)
		(end 81.260442 -96.004888)
		(width 0.0889)
		(layer "In4.Cu")
		(net "M_M_DQS_DN<8>")
	)
	(arc
		(start 81.260442 -92.042488)
		(mid 81.313912 -92.237551)
		(end 81.265268 -92.433902)
		(width 0.0889)
		(layer "In4.Cu")
		(net "M_M_DQS_DN<8>")
	)
	(arc
		(start 81.254092 -92.453206)
		(mid 81.181294 -92.743969)
		(end 81.260442 -93.033088)
		(width 0.0889)
		(layer "In4.Cu")
		(net "M_M_DQS_DN<8>")
	)
	(arc
		(start 81.260442 -86.098888)
		(mid 81.313912 -86.293951)
		(end 81.265268 -86.490302)
		(width 0.0889)
		(layer "In4.Cu")
		(net "M_M_DQS_DN<8>")
	)
	(arc
		(start 81.260442 -88.080088)
		(mid 81.313912 -88.275151)
		(end 81.265268 -88.471502)
		(width 0.0889)
		(layer "In4.Cu")
		(net "M_M_DQS_DN<8>")
	)
	(arc
		(start 81.260442 -87.089488)
		(mid 81.313912 -87.284551)
		(end 81.265268 -87.480902)
		(width 0.0889)
		(layer "In4.Cu")
		(net "M_M_DQS_DN<8>")
	)
	(arc
		(start 81.254092 -87.500206)
		(mid 81.181294 -87.790969)
		(end 81.260442 -88.080088)
		(width 0.0889)
		(layer "In4.Cu")
		(net "M_M_DQS_DN<8>")
	)
	(arc
		(start 81.254092 -96.415606)
		(mid 81.181294 -96.706369)
		(end 81.260442 -96.995488)
		(width 0.0889)
		(layer "In4.Cu")
		(net "M_M_DQS_DN<8>")
	)
	(arc
		(start 81.260442 -91.051888)
		(mid 81.313912 -91.246951)
		(end 81.265268 -91.443302)
		(width 0.0889)
		(layer "In4.Cu")
		(net "M_M_DQS_DN<8>")
	)
	(arc
		(start 81.254092 -86.509606)
		(mid 81.181294 -86.800369)
		(end 81.260442 -87.089488)
		(width 0.0889)
		(layer "In4.Cu")
		(net "M_M_DQS_DN<8>")
	)
	(arc
		(start 81.254092 -90.472006)
		(mid 81.181294 -90.762769)
		(end 81.260442 -91.051888)
		(width 0.0889)
		(layer "In4.Cu")
		(net "M_M_DQS_DN<8>")
	)
	(arc
		(start 81.254092 -88.490806)
		(mid 81.181294 -88.781569)
		(end 81.260442 -89.070688)
		(width 0.0889)
		(layer "In4.Cu")
		(net "M_M_DQS_DN<8>")
	)
	(arc
		(start 81.260442 -93.033088)
		(mid 81.313912 -93.228151)
		(end 81.265268 -93.424502)
		(width 0.0889)
		(layer "In4.Cu")
		(net "M_M_DQS_DN<8>")
	)
	(arc
		(start 81.260442 -94.423484)
		(mid 81.181311 -94.718886)
		(end 81.260442 -95.014288)
		(width 0.0889)
		(layer "In4.Cu")
		(net "M_M_DQS_DN<8>")
	)
	(arc
		(start 81.260442 -95.014288)
		(mid 81.313912 -95.209351)
		(end 81.265268 -95.405702)
		(width 0.0889)
		(layer "In4.Cu")
		(net "M_M_DQS_DN<8>")
	)
	(arc
		(start 81.254092 -91.462606)
		(mid 81.181294 -91.753369)
		(end 81.260442 -92.042488)
		(width 0.0889)
		(layer "In4.Cu")
		(net "M_M_DQS_DN<8>")
	)
	(arc
		(start 81.260442 -96.004888)
		(mid 81.313912 -96.199951)
		(end 81.265268 -96.396302)
		(width 0.0889)
		(layer "In4.Cu")
		(net "M_M_DQS_DN<8>")
	)
	(arc
		(start 81.260442 -94.023688)
		(mid 81.313941 -94.223586)
		(end 81.260442 -94.423484)
		(width 0.0889)
		(layer "In4.Cu")
		(net "M_M_DQS_DN<8>")
	)
	(arc
		(start 81.260442 -90.061288)
		(mid 81.313912 -90.256351)
		(end 81.265268 -90.452702)
		(width 0.0889)
		(layer "In4.Cu")
		(net "M_M_DQS_DN<8>")
	)
	(arc
		(start 81.260442 -89.070688)
		(mid 81.313912 -89.265751)
		(end 81.265268 -89.462102)
		(width 0.0889)
		(layer "In4.Cu")
		(net "M_M_DQS_DN<8>")
	)
	(arc
		(start 81.260442 -93.433138)
		(mid 81.18122 -93.722256)
		(end 81.254092 -94.01302)
		(width 0.0889)
		(layer "In4.Cu")
		(net "M_M_DQS_DN<8>")
	)
	(arc
		(start 81.254092 -89.481406)
		(mid 81.181294 -89.772169)
		(end 81.260442 -90.061288)
		(width 0.0889)
		(layer "In4.Cu")
		(net "M_M_DQS_DN<8>")
	)
	(segment
		(start 73.437496 -154.876246)
		(end 73.004426 -154.443176)
		(width 0.14224)
		(layer "In11.Cu")
		(net "M_M_DQS_DN<8>")
	)
	(segment
		(start 72.793606 -152.906476)
		(end 72.793606 -151.31542)
		(width 0.14224)
		(layer "In11.Cu")
		(net "M_M_DQS_DN<8>")
	)
	(segment
		(start 73.004426 -151.1046)
		(end 73.004426 -149.842474)
		(width 0.14224)
		(layer "In11.Cu")
		(net "M_M_DQS_DN<8>")
	)
	(segment
		(start 73.004426 -149.842474)
		(end 73.364344 -149.482556)
		(width 0.14224)
		(layer "In11.Cu")
		(net "M_M_DQS_DN<8>")
	)
	(segment
		(start 72.793606 -151.31542)
		(end 73.004426 -151.1046)
		(width 0.14224)
		(layer "In11.Cu")
		(net "M_M_DQS_DN<8>")
	)
	(segment
		(start 73.004426 -154.443176)
		(end 73.004426 -153.117296)
		(width 0.14224)
		(layer "In11.Cu")
		(net "M_M_DQS_DN<8>")
	)
	(segment
		(start 73.364344 -149.482556)
		(end 73.437496 -149.482556)
		(width 0.14224)
		(layer "In11.Cu")
		(net "M_M_DQS_DN<8>")
	)
	(segment
		(start 73.004426 -153.117296)
		(end 72.793606 -152.906476)
		(width 0.14224)
		(layer "In11.Cu")
		(net "M_M_DQS_DN<8>")
	)
	(segment
		(start 146.617436 -154.991054)
		(end 146.94789 -154.6606)
		(width 0.1651)
		(layer "F.Cu")
		(net "M_M_DQS_DN<7>")
	)
	(segment
		(start 146.999452 -156.87294)
		(end 146.999452 -155.80487)
		(width 0.1651)
		(layer "F.Cu")
		(net "M_M_DQS_DN<7>")
	)
	(segment
		(start 146.999452 -155.80487)
		(end 146.617436 -155.422854)
		(width 0.1651)
		(layer "F.Cu")
		(net "M_M_DQS_DN<7>")
	)
	(segment
		(start 146.617436 -155.422854)
		(end 146.617436 -154.991054)
		(width 0.1651)
		(layer "F.Cu")
		(net "M_M_DQS_DN<7>")
	)
	(segment
		(start 118.212362 -92.556584)
		(end 118.783862 -92.556584)
		(width 0.1651)
		(layer "F.Cu")
		(net "M_M_DQS_DN<7>")
	)
	(segment
		(start 147.171918 -154.6606)
		(end 147.387564 -154.876246)
		(width 0.1651)
		(layer "F.Cu")
		(net "M_M_DQS_DN<7>")
	)
	(segment
		(start 146.94789 -154.6606)
		(end 147.171918 -154.6606)
		(width 0.1651)
		(layer "F.Cu")
		(net "M_M_DQS_DN<7>")
	)
	(via
		(at 147.387564 -154.876246)
		(size 0.508)
		(drill 0.254)
		(layers "F.Cu" "B.Cu")
		(net "M_M_DQS_DN<7>")
	)
	(via
		(at 147.387564 -149.482556)
		(size 0.508)
		(drill 0.254)
		(layers "F.Cu" "B.Cu")
		(net "M_M_DQS_DN<7>")
	)
	(via
		(at 118.783862 -92.556584)
		(size 0.508)
		(drill 0.254)
		(layers "F.Cu" "B.Cu")
		(net "M_M_DQS_DN<7>")
	)
	(segment
		(start 146.999452 -147.478496)
		(end 146.999452 -148.38553)
		(width 0.1651)
		(layer "B.Cu")
		(net "M_M_DQS_DN<7>")
	)
	(segment
		(start 146.617436 -149.352)
		(end 146.973036 -149.7076)
		(width 0.1651)
		(layer "B.Cu")
		(net "M_M_DQS_DN<7>")
	)
	(segment
		(start 146.871436 -148.513546)
		(end 146.871436 -148.767546)
		(width 0.1651)
		(layer "B.Cu")
		(net "M_M_DQS_DN<7>")
	)
	(segment
		(start 147.16252 -149.7076)
		(end 147.387564 -149.482556)
		(width 0.1651)
		(layer "B.Cu")
		(net "M_M_DQS_DN<7>")
	)
	(segment
		(start 146.973036 -149.7076)
		(end 147.16252 -149.7076)
		(width 0.1651)
		(layer "B.Cu")
		(net "M_M_DQS_DN<7>")
	)
	(segment
		(start 146.871436 -148.767546)
		(end 146.617436 -149.021546)
		(width 0.1651)
		(layer "B.Cu")
		(net "M_M_DQS_DN<7>")
	)
	(segment
		(start 146.617436 -149.021546)
		(end 146.617436 -149.352)
		(width 0.1651)
		(layer "B.Cu")
		(net "M_M_DQS_DN<7>")
	)
	(segment
		(start 146.999452 -148.38553)
		(end 146.871436 -148.513546)
		(width 0.1651)
		(layer "B.Cu")
		(net "M_M_DQS_DN<7>")
	)
	(segment
		(start 147.314412 -149.482556)
		(end 146.954494 -149.842474)
		(width 0.14224)
		(layer "In11.Cu")
		(net "M_M_DQS_DN<7>")
	)
	(segment
		(start 147.743164 -137.16635)
		(end 147.900644 -137.32383)
		(width 0.14224)
		(layer "In11.Cu")
		(net "M_M_DQS_DN<7>")
	)
	(segment
		(start 127.352552 -105.69448)
		(end 127.556514 -105.490518)
		(width 0.14224)
		(layer "In11.Cu")
		(net "M_M_DQS_DN<7>")
	)
	(segment
		(start 125.763782 -104.175814)
		(end 125.724412 -104.215184)
		(width 0.0889)
		(layer "In11.Cu")
		(net "M_M_DQS_DN<7>")
	)
	(segment
		(start 128.156208 -105.739946)
		(end 128.156208 -106.629454)
		(width 0.14224)
		(layer "In11.Cu")
		(net "M_M_DQS_DN<7>")
	)
	(segment
		(start 147.743164 -148.427186)
		(end 147.900644 -148.584666)
		(width 0.14224)
		(layer "In11.Cu")
		(net "M_M_DQS_DN<7>")
	)
	(segment
		(start 147.743164 -137.73531)
		(end 147.743164 -137.98931)
		(width 0.14224)
		(layer "In11.Cu")
		(net "M_M_DQS_DN<7>")
	)
	(segment
		(start 120.844056 -94.332298)
		(end 120.847358 -94.33814)
		(width 0.0889)
		(layer "In11.Cu")
		(net "M_M_DQS_DN<7>")
	)
	(segment
		(start 147.900644 -138.96975)
		(end 147.900644 -141.50213)
		(width 0.14224)
		(layer "In11.Cu")
		(net "M_M_DQS_DN<7>")
	)
	(segment
		(start 126.850648 -105.69448)
		(end 127.352552 -105.69448)
		(width 0.14224)
		(layer "In11.Cu")
		(net "M_M_DQS_DN<7>")
	)
	(segment
		(start 125.724412 -104.215184)
		(end 125.724412 -104.237282)
		(width 0.0889)
		(layer "In11.Cu")
		(net "M_M_DQS_DN<7>")
	)
	(segment
		(start 147.900644 -132.631942)
		(end 147.743164 -132.789422)
		(width 0.14224)
		(layer "In11.Cu")
		(net "M_M_DQS_DN<7>")
	)
	(segment
		(start 119.624602 -93.642688)
		(end 119.657368 -93.642688)
		(width 0.0889)
		(layer "In11.Cu")
		(net "M_M_DQS_DN<7>")
	)
	(segment
		(start 147.900644 -137.32383)
		(end 147.900644 -137.57783)
		(width 0.14224)
		(layer "In11.Cu")
		(net "M_M_DQS_DN<7>")
	)
	(segment
		(start 147.900644 -146.938746)
		(end 147.900644 -147.192746)
		(width 0.14224)
		(layer "In11.Cu")
		(net "M_M_DQS_DN<7>")
	)
	(segment
		(start 136.041638 -111.436404)
		(end 147.900644 -123.29541)
		(width 0.14224)
		(layer "In11.Cu")
		(net "M_M_DQS_DN<7>")
	)
	(segment
		(start 147.743164 -138.81227)
		(end 147.900644 -138.96975)
		(width 0.14224)
		(layer "In11.Cu")
		(net "M_M_DQS_DN<7>")
	)
	(segment
		(start 147.900644 -132.377942)
		(end 147.900644 -132.631942)
		(width 0.14224)
		(layer "In11.Cu")
		(net "M_M_DQS_DN<7>")
	)
	(segment
		(start 122.199908 -95.128588)
		(end 122.235722 -95.128588)
		(width 0.0889)
		(layer "In11.Cu")
		(net "M_M_DQS_DN<7>")
	)
	(segment
		(start 147.900644 -148.015706)
		(end 147.743164 -148.173186)
		(width 0.14224)
		(layer "In11.Cu")
		(net "M_M_DQS_DN<7>")
	)
	(segment
		(start 147.900644 -141.50213)
		(end 147.743164 -141.65961)
		(width 0.14224)
		(layer "In11.Cu")
		(net "M_M_DQS_DN<7>")
	)
	(segment
		(start 147.743164 -129.161794)
		(end 147.900644 -129.319274)
		(width 0.14224)
		(layer "In11.Cu")
		(net "M_M_DQS_DN<7>")
	)
	(segment
		(start 124.281438 -100.681536)
		(end 124.275088 -100.692204)
		(width 0.0889)
		(layer "In11.Cu")
		(net "M_M_DQS_DN<7>")
	)
	(segment
		(start 123.913138 -96.118934)
		(end 123.945904 -96.118934)
		(width 0.0889)
		(layer "In11.Cu")
		(net "M_M_DQS_DN<7>")
	)
	(segment
		(start 120.487948 -94.137988)
		(end 120.500902 -94.137988)
		(width 0.0889)
		(layer "In11.Cu")
		(net "M_M_DQS_DN<7>")
	)
	(segment
		(start 147.743164 -132.789422)
		(end 147.743164 -133.043422)
		(width 0.14224)
		(layer "In11.Cu")
		(net "M_M_DQS_DN<7>")
	)
	(segment
		(start 129.703576 -106.9594)
		(end 133.647434 -110.903258)
		(width 0.14224)
		(layer "In11.Cu")
		(net "M_M_DQS_DN<7>")
	)
	(segment
		(start 124.281438 -101.272086)
		(end 124.286264 -101.280722)
		(width 0.0889)
		(layer "In11.Cu")
		(net "M_M_DQS_DN<7>")
	)
	(segment
		(start 147.743164 -137.98931)
		(end 147.900644 -138.14679)
		(width 0.14224)
		(layer "In11.Cu")
		(net "M_M_DQS_DN<7>")
	)
	(segment
		(start 147.743164 -133.612382)
		(end 147.743164 -133.866382)
		(width 0.14224)
		(layer "In11.Cu")
		(net "M_M_DQS_DN<7>")
	)
	(segment
		(start 147.900644 -134.023862)
		(end 147.900644 -136.75487)
		(width 0.14224)
		(layer "In11.Cu")
		(net "M_M_DQS_DN<7>")
	)
	(segment
		(start 146.954494 -154.443176)
		(end 147.387564 -154.876246)
		(width 0.14224)
		(layer "In11.Cu")
		(net "M_M_DQS_DN<7>")
	)
	(segment
		(start 147.743164 -141.91361)
		(end 147.900644 -142.07109)
		(width 0.14224)
		(layer "In11.Cu")
		(net "M_M_DQS_DN<7>")
	)
	(segment
		(start 147.387564 -149.482556)
		(end 147.314412 -149.482556)
		(width 0.14224)
		(layer "In11.Cu")
		(net "M_M_DQS_DN<7>")
	)
	(segment
		(start 147.900644 -136.75487)
		(end 147.743164 -136.91235)
		(width 0.14224)
		(layer "In11.Cu")
		(net "M_M_DQS_DN<7>")
	)
	(segment
		(start 125.724412 -104.237282)
		(end 125.724412 -104.568244)
		(width 0.14224)
		(layer "In11.Cu")
		(net "M_M_DQS_DN<7>")
	)
	(segment
		(start 124.281438 -99.290886)
		(end 124.286264 -99.299522)
		(width 0.0889)
		(layer "In11.Cu")
		(net "M_M_DQS_DN<7>")
	)
	(segment
		(start 134.848854 -111.613696)
		(end 135.026146 -111.436404)
		(width 0.14224)
		(layer "In11.Cu")
		(net "M_M_DQS_DN<7>")
	)
	(segment
		(start 147.743164 -146.781266)
		(end 147.900644 -146.938746)
		(width 0.14224)
		(layer "In11.Cu")
		(net "M_M_DQS_DN<7>")
	)
	(segment
		(start 147.743164 -143.30553)
		(end 147.743164 -143.55953)
		(width 0.14224)
		(layer "In11.Cu")
		(net "M_M_DQS_DN<7>")
	)
	(segment
		(start 147.900644 -138.40079)
		(end 147.743164 -138.55827)
		(width 0.14224)
		(layer "In11.Cu")
		(net "M_M_DQS_DN<7>")
	)
	(segment
		(start 146.954494 -151.1046)
		(end 146.743674 -151.31542)
		(width 0.14224)
		(layer "In11.Cu")
		(net "M_M_DQS_DN<7>")
	)
	(segment
		(start 123.063254 -95.623888)
		(end 123.091194 -95.623888)
		(width 0.0889)
		(layer "In11.Cu")
		(net "M_M_DQS_DN<7>")
	)
	(segment
		(start 128.156208 -106.629454)
		(end 128.486154 -106.9594)
		(width 0.14224)
		(layer "In11.Cu")
		(net "M_M_DQS_DN<7>")
	)
	(segment
		(start 125.763782 -103.154734)
		(end 125.763782 -104.175814)
		(width 0.0889)
		(layer "In11.Cu")
		(net "M_M_DQS_DN<7>")
	)
	(segment
		(start 125.62967 -103.053134)
		(end 125.662182 -103.053134)
		(width 0.0889)
		(layer "In11.Cu")
		(net "M_M_DQS_DN<7>")
	)
	(segment
		(start 147.900644 -143.14805)
		(end 147.743164 -143.30553)
		(width 0.14224)
		(layer "In11.Cu")
		(net "M_M_DQS_DN<7>")
	)
	(segment
		(start 146.743674 -152.97658)
		(end 146.954494 -153.1874)
		(width 0.14224)
		(layer "In11.Cu")
		(net "M_M_DQS_DN<7>")
	)
	(segment
		(start 124.275088 -99.280218)
		(end 124.281438 -99.290886)
		(width 0.0889)
		(layer "In11.Cu")
		(net "M_M_DQS_DN<7>")
	)
	(segment
		(start 125.662182 -103.053134)
		(end 125.763782 -103.154734)
		(width 0.0889)
		(layer "In11.Cu")
		(net "M_M_DQS_DN<7>")
	)
	(segment
		(start 147.900644 -146.369786)
		(end 147.743164 -146.527266)
		(width 0.14224)
		(layer "In11.Cu")
		(net "M_M_DQS_DN<7>")
	)
	(segment
		(start 146.743674 -151.31542)
		(end 146.743674 -152.97658)
		(width 0.14224)
		(layer "In11.Cu")
		(net "M_M_DQS_DN<7>")
	)
	(segment
		(start 147.66671 -149.482556)
		(end 147.387564 -149.482556)
		(width 0.14224)
		(layer "In11.Cu")
		(net "M_M_DQS_DN<7>")
	)
	(segment
		(start 135.026146 -111.436404)
		(end 136.041638 -111.436404)
		(width 0.14224)
		(layer "In11.Cu")
		(net "M_M_DQS_DN<7>")
	)
	(segment
		(start 147.743164 -133.043422)
		(end 147.900644 -133.200902)
		(width 0.14224)
		(layer "In11.Cu")
		(net "M_M_DQS_DN<7>")
	)
	(segment
		(start 147.900644 -142.89405)
		(end 147.900644 -143.14805)
		(width 0.14224)
		(layer "In11.Cu")
		(net "M_M_DQS_DN<7>")
	)
	(segment
		(start 147.743164 -132.220462)
		(end 147.900644 -132.377942)
		(width 0.14224)
		(layer "In11.Cu")
		(net "M_M_DQS_DN<7>")
	)
	(segment
		(start 127.90678 -105.490518)
		(end 128.156208 -105.739946)
		(width 0.14224)
		(layer "In11.Cu")
		(net "M_M_DQS_DN<7>")
	)
	(segment
		(start 147.900644 -133.200902)
		(end 147.900644 -133.454902)
		(width 0.14224)
		(layer "In11.Cu")
		(net "M_M_DQS_DN<7>")
	)
	(segment
		(start 124.775468 -102.558088)
		(end 124.808234 -102.558088)
		(width 0.0889)
		(layer "In11.Cu")
		(net "M_M_DQS_DN<7>")
	)
	(segment
		(start 147.900644 -149.248622)
		(end 147.66671 -149.482556)
		(width 0.14224)
		(layer "In11.Cu")
		(net "M_M_DQS_DN<7>")
	)
	(segment
		(start 121.337578 -94.633288)
		(end 121.377202 -94.633288)
		(width 0.0889)
		(layer "In11.Cu")
		(net "M_M_DQS_DN<7>")
	)
	(segment
		(start 146.954494 -153.1874)
		(end 146.954494 -154.443176)
		(width 0.14224)
		(layer "In11.Cu")
		(net "M_M_DQS_DN<7>")
	)
	(segment
		(start 127.556514 -105.490518)
		(end 127.90678 -105.490518)
		(width 0.14224)
		(layer "In11.Cu")
		(net "M_M_DQS_DN<7>")
	)
	(segment
		(start 147.900644 -129.319274)
		(end 147.900644 -131.808982)
		(width 0.14224)
		(layer "In11.Cu")
		(net "M_M_DQS_DN<7>")
	)
	(segment
		(start 147.900644 -131.808982)
		(end 147.743164 -131.966462)
		(width 0.14224)
		(layer "In11.Cu")
		(net "M_M_DQS_DN<7>")
	)
	(segment
		(start 133.952742 -112.472724)
		(end 134.529322 -112.472724)
		(width 0.14224)
		(layer "In11.Cu")
		(net "M_M_DQS_DN<7>")
	)
	(segment
		(start 147.900644 -142.32509)
		(end 147.743164 -142.48257)
		(width 0.14224)
		(layer "In11.Cu")
		(net "M_M_DQS_DN<7>")
	)
	(segment
		(start 147.900644 -143.71701)
		(end 147.900644 -146.369786)
		(width 0.14224)
		(layer "In11.Cu")
		(net "M_M_DQS_DN<7>")
	)
	(segment
		(start 147.900644 -137.57783)
		(end 147.743164 -137.73531)
		(width 0.14224)
		(layer "In11.Cu")
		(net "M_M_DQS_DN<7>")
	)
	(segment
		(start 147.900644 -147.761706)
		(end 147.900644 -148.015706)
		(width 0.14224)
		(layer "In11.Cu")
		(net "M_M_DQS_DN<7>")
	)
	(segment
		(start 134.848854 -112.153192)
		(end 134.848854 -111.613696)
		(width 0.14224)
		(layer "In11.Cu")
		(net "M_M_DQS_DN<7>")
	)
	(segment
		(start 147.743164 -142.73657)
		(end 147.900644 -142.89405)
		(width 0.14224)
		(layer "In11.Cu")
		(net "M_M_DQS_DN<7>")
	)
	(segment
		(start 147.743164 -138.55827)
		(end 147.743164 -138.81227)
		(width 0.14224)
		(layer "In11.Cu")
		(net "M_M_DQS_DN<7>")
	)
	(segment
		(start 128.486154 -106.9594)
		(end 129.703576 -106.9594)
		(width 0.14224)
		(layer "In11.Cu")
		(net "M_M_DQS_DN<7>")
	)
	(segment
		(start 133.647434 -110.903258)
		(end 133.647434 -112.167416)
		(width 0.14224)
		(layer "In11.Cu")
		(net "M_M_DQS_DN<7>")
	)
	(segment
		(start 147.900644 -128.750314)
		(end 147.743164 -128.907794)
		(width 0.14224)
		(layer "In11.Cu")
		(net "M_M_DQS_DN<7>")
	)
	(segment
		(start 147.900644 -147.192746)
		(end 147.743164 -147.350226)
		(width 0.14224)
		(layer "In11.Cu")
		(net "M_M_DQS_DN<7>")
	)
	(segment
		(start 147.743164 -146.527266)
		(end 147.743164 -146.781266)
		(width 0.14224)
		(layer "In11.Cu")
		(net "M_M_DQS_DN<7>")
	)
	(segment
		(start 147.743164 -142.48257)
		(end 147.743164 -142.73657)
		(width 0.14224)
		(layer "In11.Cu")
		(net "M_M_DQS_DN<7>")
	)
	(segment
		(start 147.743164 -136.91235)
		(end 147.743164 -137.16635)
		(width 0.14224)
		(layer "In11.Cu")
		(net "M_M_DQS_DN<7>")
	)
	(segment
		(start 147.900644 -138.14679)
		(end 147.900644 -138.40079)
		(width 0.14224)
		(layer "In11.Cu")
		(net "M_M_DQS_DN<7>")
	)
	(segment
		(start 147.900644 -133.454902)
		(end 147.743164 -133.612382)
		(width 0.14224)
		(layer "In11.Cu")
		(net "M_M_DQS_DN<7>")
	)
	(segment
		(start 147.900644 -142.07109)
		(end 147.900644 -142.32509)
		(width 0.14224)
		(layer "In11.Cu")
		(net "M_M_DQS_DN<7>")
	)
	(segment
		(start 124.275088 -97.299018)
		(end 124.281438 -97.309686)
		(width 0.0889)
		(layer "In11.Cu")
		(net "M_M_DQS_DN<7>")
	)
	(segment
		(start 147.900644 -148.584666)
		(end 147.900644 -149.248622)
		(width 0.14224)
		(layer "In11.Cu")
		(net "M_M_DQS_DN<7>")
	)
	(segment
		(start 147.743164 -147.604226)
		(end 147.900644 -147.761706)
		(width 0.14224)
		(layer "In11.Cu")
		(net "M_M_DQS_DN<7>")
	)
	(segment
		(start 147.900644 -123.29541)
		(end 147.900644 -128.750314)
		(width 0.14224)
		(layer "In11.Cu")
		(net "M_M_DQS_DN<7>")
	)
	(segment
		(start 146.954494 -149.842474)
		(end 146.954494 -151.1046)
		(width 0.14224)
		(layer "In11.Cu")
		(net "M_M_DQS_DN<7>")
	)
	(segment
		(start 147.743164 -147.350226)
		(end 147.743164 -147.604226)
		(width 0.14224)
		(layer "In11.Cu")
		(net "M_M_DQS_DN<7>")
	)
	(segment
		(start 147.743164 -143.55953)
		(end 147.900644 -143.71701)
		(width 0.14224)
		(layer "In11.Cu")
		(net "M_M_DQS_DN<7>")
	)
	(segment
		(start 147.743164 -133.866382)
		(end 147.900644 -134.023862)
		(width 0.14224)
		(layer "In11.Cu")
		(net "M_M_DQS_DN<7>")
	)
	(segment
		(start 133.647434 -112.167416)
		(end 133.952742 -112.472724)
		(width 0.14224)
		(layer "In11.Cu")
		(net "M_M_DQS_DN<7>")
	)
	(segment
		(start 147.743164 -148.173186)
		(end 147.743164 -148.427186)
		(width 0.14224)
		(layer "In11.Cu")
		(net "M_M_DQS_DN<7>")
	)
	(segment
		(start 147.743164 -131.966462)
		(end 147.743164 -132.220462)
		(width 0.14224)
		(layer "In11.Cu")
		(net "M_M_DQS_DN<7>")
	)
	(segment
		(start 125.724412 -104.568244)
		(end 126.850648 -105.69448)
		(width 0.14224)
		(layer "In11.Cu")
		(net "M_M_DQS_DN<7>")
	)
	(segment
		(start 147.743164 -141.65961)
		(end 147.743164 -141.91361)
		(width 0.14224)
		(layer "In11.Cu")
		(net "M_M_DQS_DN<7>")
	)
	(segment
		(start 134.529322 -112.472724)
		(end 134.848854 -112.153192)
		(width 0.14224)
		(layer "In11.Cu")
		(net "M_M_DQS_DN<7>")
	)
	(segment
		(start 147.743164 -128.907794)
		(end 147.743164 -129.161794)
		(width 0.14224)
		(layer "In11.Cu")
		(net "M_M_DQS_DN<7>")
	)
	(arc
		(start 124.281438 -101.672136)
		(mid 124.277109 -102.255308)
		(end 124.775468 -102.558088)
		(width 0.0889)
		(layer "In11.Cu")
		(net "M_M_DQS_DN<7>")
	)
	(arc
		(start 124.286264 -99.299522)
		(mid 124.335019 -99.495874)
		(end 124.281438 -99.690936)
		(width 0.0889)
		(layer "In11.Cu")
		(net "M_M_DQS_DN<7>")
	)
	(arc
		(start 121.377202 -94.633288)
		(mid 121.567131 -94.691158)
		(end 121.705878 -94.833186)
		(width 0.0889)
		(layer "In11.Cu")
		(net "M_M_DQS_DN<7>")
	)
	(arc
		(start 122.564398 -95.328486)
		(mid 122.775111 -95.541565)
		(end 123.063254 -95.623888)
		(width 0.0889)
		(layer "In11.Cu")
		(net "M_M_DQS_DN<7>")
	)
	(arc
		(start 120.500902 -94.137988)
		(mid 120.698063 -94.189947)
		(end 120.844056 -94.332298)
		(width 0.0889)
		(layer "In11.Cu")
		(net "M_M_DQS_DN<7>")
	)
	(arc
		(start 123.422918 -95.823786)
		(mid 123.629922 -96.03465)
		(end 123.913138 -96.118934)
		(width 0.0889)
		(layer "In11.Cu")
		(net "M_M_DQS_DN<7>")
	)
	(arc
		(start 124.275088 -100.692204)
		(mid 124.20229 -100.982967)
		(end 124.281438 -101.272086)
		(width 0.0889)
		(layer "In11.Cu")
		(net "M_M_DQS_DN<7>")
	)
	(arc
		(start 124.281438 -98.700336)
		(mid 124.202216 -98.989454)
		(end 124.275088 -99.280218)
		(width 0.0889)
		(layer "In11.Cu")
		(net "M_M_DQS_DN<7>")
	)
	(arc
		(start 119.055388 -93.120972)
		(mid 119.24298 -93.487664)
		(end 119.624602 -93.642688)
		(width 0.0889)
		(layer "In11.Cu")
		(net "M_M_DQS_DN<7>")
	)
	(arc
		(start 121.705878 -94.833186)
		(mid 121.914486 -95.045118)
		(end 122.199908 -95.128588)
		(width 0.0889)
		(layer "In11.Cu")
		(net "M_M_DQS_DN<7>")
	)
	(arc
		(start 123.945904 -96.118934)
		(mid 124.284073 -96.323732)
		(end 124.281438 -96.719136)
		(width 0.0889)
		(layer "In11.Cu")
		(net "M_M_DQS_DN<7>")
	)
	(arc
		(start 123.091194 -95.623888)
		(mid 123.282836 -95.681054)
		(end 123.422918 -95.823786)
		(width 0.0889)
		(layer "In11.Cu")
		(net "M_M_DQS_DN<7>")
	)
	(arc
		(start 124.281438 -97.309686)
		(mid 124.335157 -97.509982)
		(end 124.281438 -97.710244)
		(width 0.0889)
		(layer "In11.Cu")
		(net "M_M_DQS_DN<7>")
	)
	(arc
		(start 124.281438 -96.719136)
		(mid 124.202216 -97.008254)
		(end 124.275088 -97.299018)
		(width 0.0889)
		(layer "In11.Cu")
		(net "M_M_DQS_DN<7>")
	)
	(arc
		(start 124.281438 -99.690936)
		(mid 124.202307 -99.986338)
		(end 124.281438 -100.28174)
		(width 0.0889)
		(layer "In11.Cu")
		(net "M_M_DQS_DN<7>")
	)
	(arc
		(start 124.286264 -101.280722)
		(mid 124.335019 -101.477074)
		(end 124.281438 -101.672136)
		(width 0.0889)
		(layer "In11.Cu")
		(net "M_M_DQS_DN<7>")
	)
	(arc
		(start 120.847358 -94.33814)
		(mid 121.054362 -94.549004)
		(end 121.337578 -94.633288)
		(width 0.0889)
		(layer "In11.Cu")
		(net "M_M_DQS_DN<7>")
	)
	(arc
		(start 119.657368 -93.642688)
		(mid 119.84901 -93.699854)
		(end 119.989092 -93.842586)
		(width 0.0889)
		(layer "In11.Cu")
		(net "M_M_DQS_DN<7>")
	)
	(arc
		(start 124.281438 -98.301048)
		(mid 124.334912 -98.500692)
		(end 124.281438 -98.700336)
		(width 0.0889)
		(layer "In11.Cu")
		(net "M_M_DQS_DN<7>")
	)
	(arc
		(start 118.783862 -92.556584)
		(mid 118.966831 -92.816063)
		(end 119.055388 -93.120972)
		(width 0.0889)
		(layer "In11.Cu")
		(net "M_M_DQS_DN<7>")
	)
	(arc
		(start 125.139958 -102.757986)
		(mid 125.346745 -102.968719)
		(end 125.62967 -103.053134)
		(width 0.0889)
		(layer "In11.Cu")
		(net "M_M_DQS_DN<7>")
	)
	(arc
		(start 122.235722 -95.128588)
		(mid 122.425651 -95.186458)
		(end 122.564398 -95.328486)
		(width 0.0889)
		(layer "In11.Cu")
		(net "M_M_DQS_DN<7>")
	)
	(arc
		(start 119.989092 -93.842586)
		(mid 120.199805 -94.055665)
		(end 120.487948 -94.137988)
		(width 0.0889)
		(layer "In11.Cu")
		(net "M_M_DQS_DN<7>")
	)
	(arc
		(start 124.281438 -97.710244)
		(mid 124.202307 -98.005646)
		(end 124.281438 -98.301048)
		(width 0.0889)
		(layer "In11.Cu")
		(net "M_M_DQS_DN<7>")
	)
	(arc
		(start 124.808234 -102.558088)
		(mid 124.999876 -102.615254)
		(end 125.139958 -102.757986)
		(width 0.0889)
		(layer "In11.Cu")
		(net "M_M_DQS_DN<7>")
	)
	(arc
		(start 124.281438 -100.28174)
		(mid 124.334937 -100.481638)
		(end 124.281438 -100.681536)
		(width 0.0889)
		(layer "In11.Cu")
		(net "M_M_DQS_DN<7>")
	)
	(segment
		(start 113.061242 -92.556584)
		(end 113.632742 -92.556584)
		(width 0.1651)
		(layer "F.Cu")
		(net "M_M_DQS_DN<6>")
	)
	(segment
		(start 137.267442 -155.422854)
		(end 137.267442 -154.991054)
		(width 0.1651)
		(layer "F.Cu")
		(net "M_M_DQS_DN<6>")
	)
	(segment
		(start 137.267442 -154.991054)
		(end 137.597896 -154.6606)
		(width 0.1651)
		(layer "F.Cu")
		(net "M_M_DQS_DN<6>")
	)
	(segment
		(start 137.649458 -155.80487)
		(end 137.267442 -155.422854)
		(width 0.1651)
		(layer "F.Cu")
		(net "M_M_DQS_DN<6>")
	)
	(segment
		(start 137.649458 -156.87294)
		(end 137.649458 -155.80487)
		(width 0.1651)
		(layer "F.Cu")
		(net "M_M_DQS_DN<6>")
	)
	(segment
		(start 137.597896 -154.6606)
		(end 137.821924 -154.6606)
		(width 0.1651)
		(layer "F.Cu")
		(net "M_M_DQS_DN<6>")
	)
	(segment
		(start 137.821924 -154.6606)
		(end 138.03757 -154.876246)
		(width 0.1651)
		(layer "F.Cu")
		(net "M_M_DQS_DN<6>")
	)
	(via
		(at 138.03757 -149.482556)
		(size 0.508)
		(drill 0.254)
		(layers "F.Cu" "B.Cu")
		(net "M_M_DQS_DN<6>")
	)
	(via
		(at 113.632742 -92.556584)
		(size 0.508)
		(drill 0.254)
		(layers "F.Cu" "B.Cu")
		(net "M_M_DQS_DN<6>")
	)
	(via
		(at 138.03757 -154.876246)
		(size 0.508)
		(drill 0.254)
		(layers "F.Cu" "B.Cu")
		(net "M_M_DQS_DN<6>")
	)
	(segment
		(start 137.267442 -149.021546)
		(end 137.267442 -149.352)
		(width 0.1651)
		(layer "B.Cu")
		(net "M_M_DQS_DN<6>")
	)
	(segment
		(start 137.521442 -148.767546)
		(end 137.267442 -149.021546)
		(width 0.1651)
		(layer "B.Cu")
		(net "M_M_DQS_DN<6>")
	)
	(segment
		(start 137.623042 -149.7076)
		(end 137.812526 -149.7076)
		(width 0.1651)
		(layer "B.Cu")
		(net "M_M_DQS_DN<6>")
	)
	(segment
		(start 137.812526 -149.7076)
		(end 138.03757 -149.482556)
		(width 0.1651)
		(layer "B.Cu")
		(net "M_M_DQS_DN<6>")
	)
	(segment
		(start 137.649458 -147.478496)
		(end 137.649458 -148.38553)
		(width 0.1651)
		(layer "B.Cu")
		(net "M_M_DQS_DN<6>")
	)
	(segment
		(start 137.267442 -149.352)
		(end 137.623042 -149.7076)
		(width 0.1651)
		(layer "B.Cu")
		(net "M_M_DQS_DN<6>")
	)
	(segment
		(start 137.649458 -148.38553)
		(end 137.521442 -148.513546)
		(width 0.1651)
		(layer "B.Cu")
		(net "M_M_DQS_DN<6>")
	)
	(segment
		(start 137.521442 -148.513546)
		(end 137.521442 -148.767546)
		(width 0.1651)
		(layer "B.Cu")
		(net "M_M_DQS_DN<6>")
	)
	(segment
		(start 117.907562 -98.595688)
		(end 117.940328 -98.595688)
		(width 0.0889)
		(layer "In11.Cu")
		(net "M_M_DQS_DN<6>")
	)
	(segment
		(start 138.55065 -143.11249)
		(end 138.39317 -143.26997)
		(width 0.14224)
		(layer "In11.Cu")
		(net "M_M_DQS_DN<6>")
	)
	(segment
		(start 132.440934 -119.639588)
		(end 132.440934 -119.255032)
		(width 0.14224)
		(layer "In11.Cu")
		(net "M_M_DQS_DN<6>")
	)
	(segment
		(start 113.979452 -95.328486)
		(end 113.984278 -95.337122)
		(width 0.0889)
		(layer "In11.Cu")
		(net "M_M_DQS_DN<6>")
	)
	(segment
		(start 137.39368 -151.31542)
		(end 137.39368 -152.97658)
		(width 0.14224)
		(layer "In11.Cu")
		(net "M_M_DQS_DN<6>")
	)
	(segment
		(start 138.55065 -147.086574)
		(end 138.39317 -147.244054)
		(width 0.14224)
		(layer "In11.Cu")
		(net "M_M_DQS_DN<6>")
	)
	(segment
		(start 114.473482 -96.614488)
		(end 114.506248 -96.614488)
		(width 0.0889)
		(layer "In11.Cu")
		(net "M_M_DQS_DN<6>")
	)
	(segment
		(start 138.39317 -137.889996)
		(end 138.55065 -138.047476)
		(width 0.14224)
		(layer "In11.Cu")
		(net "M_M_DQS_DN<6>")
	)
	(segment
		(start 138.55065 -136.655556)
		(end 138.39317 -136.813036)
		(width 0.14224)
		(layer "In11.Cu")
		(net "M_M_DQS_DN<6>")
	)
	(segment
		(start 138.55065 -133.554216)
		(end 138.39317 -133.711696)
		(width 0.14224)
		(layer "In11.Cu")
		(net "M_M_DQS_DN<6>")
	)
	(segment
		(start 138.55065 -134.123176)
		(end 138.55065 -136.655556)
		(width 0.14224)
		(layer "In11.Cu")
		(net "M_M_DQS_DN<6>")
	)
	(segment
		(start 138.39317 -148.321014)
		(end 138.55065 -148.478494)
		(width 0.14224)
		(layer "In11.Cu")
		(net "M_M_DQS_DN<6>")
	)
	(segment
		(start 138.55065 -142.28953)
		(end 138.39317 -142.44701)
		(width 0.14224)
		(layer "In11.Cu")
		(net "M_M_DQS_DN<6>")
	)
	(segment
		(start 118.276878 -105.1306)
		(end 118.272052 -105.139236)
		(width 0.0889)
		(layer "In11.Cu")
		(net "M_M_DQS_DN<6>")
	)
	(segment
		(start 138.55065 -146.263614)
		(end 138.39317 -146.421094)
		(width 0.14224)
		(layer "In11.Cu")
		(net "M_M_DQS_DN<6>")
	)
	(segment
		(start 138.39317 -147.498054)
		(end 138.55065 -147.655534)
		(width 0.14224)
		(layer "In11.Cu")
		(net "M_M_DQS_DN<6>")
	)
	(segment
		(start 118.249192 -106.206798)
		(end 118.249192 -107.126532)
		(width 0.0889)
		(layer "In11.Cu")
		(net "M_M_DQS_DN<6>")
	)
	(segment
		(start 138.39317 -141.62405)
		(end 138.39317 -141.87805)
		(width 0.14224)
		(layer "In11.Cu")
		(net "M_M_DQS_DN<6>")
	)
	(segment
		(start 118.276878 -99.187)
		(end 118.272052 -99.195636)
		(width 0.0889)
		(layer "In11.Cu")
		(net "M_M_DQS_DN<6>")
	)
	(segment
		(start 118.209822 -107.188)
		(end 118.209822 -113.06175)
		(width 0.14224)
		(layer "In11.Cu")
		(net "M_M_DQS_DN<6>")
	)
	(segment
		(start 116.190522 -97.605088)
		(end 116.223288 -97.605088)
		(width 0.0889)
		(layer "In11.Cu")
		(net "M_M_DQS_DN<6>")
	)
	(segment
		(start 138.39317 -143.52397)
		(end 138.55065 -143.68145)
		(width 0.14224)
		(layer "In11.Cu")
		(net "M_M_DQS_DN<6>")
	)
	(segment
		(start 138.55065 -138.870436)
		(end 138.55065 -141.46657)
		(width 0.14224)
		(layer "In11.Cu")
		(net "M_M_DQS_DN<6>")
	)
	(segment
		(start 130.838448 -119.35587)
		(end 131.434586 -119.952008)
		(width 0.14224)
		(layer "In11.Cu")
		(net "M_M_DQS_DN<6>")
	)
	(segment
		(start 138.39317 -133.711696)
		(end 138.39317 -133.965696)
		(width 0.14224)
		(layer "In11.Cu")
		(net "M_M_DQS_DN<6>")
	)
	(segment
		(start 138.55065 -142.85849)
		(end 138.55065 -143.11249)
		(width 0.14224)
		(layer "In11.Cu")
		(net "M_M_DQS_DN<6>")
	)
	(segment
		(start 138.39317 -132.319776)
		(end 138.55065 -132.477256)
		(width 0.14224)
		(layer "In11.Cu")
		(net "M_M_DQS_DN<6>")
	)
	(segment
		(start 138.264138 -149.482556)
		(end 138.03757 -149.482556)
		(width 0.14224)
		(layer "In11.Cu")
		(net "M_M_DQS_DN<6>")
	)
	(segment
		(start 133.103874 -119.255032)
		(end 133.103874 -119.639588)
		(width 0.14224)
		(layer "In11.Cu")
		(net "M_M_DQS_DN<6>")
	)
	(segment
		(start 118.272052 -105.729786)
		(end 118.325392 -105.822242)
		(width 0.0889)
		(layer "In11.Cu")
		(net "M_M_DQS_DN<6>")
	)
	(segment
		(start 138.55065 -148.478494)
		(end 138.55065 -149.196044)
		(width 0.14224)
		(layer "In11.Cu")
		(net "M_M_DQS_DN<6>")
	)
	(segment
		(start 115.328192 -97.109534)
		(end 115.360958 -97.109534)
		(width 0.0889)
		(layer "In11.Cu")
		(net "M_M_DQS_DN<6>")
	)
	(segment
		(start 131.434586 -119.952008)
		(end 132.128514 -119.952008)
		(width 0.14224)
		(layer "In11.Cu")
		(net "M_M_DQS_DN<6>")
	)
	(segment
		(start 137.39368 -152.97658)
		(end 137.6045 -153.1874)
		(width 0.14224)
		(layer "In11.Cu")
		(net "M_M_DQS_DN<6>")
	)
	(segment
		(start 138.39317 -137.635996)
		(end 138.39317 -137.889996)
		(width 0.14224)
		(layer "In11.Cu")
		(net "M_M_DQS_DN<6>")
	)
	(segment
		(start 138.55065 -133.300216)
		(end 138.55065 -133.554216)
		(width 0.14224)
		(layer "In11.Cu")
		(net "M_M_DQS_DN<6>")
	)
	(segment
		(start 118.272052 -104.148636)
		(end 118.265702 -104.159304)
		(width 0.0889)
		(layer "In11.Cu")
		(net "M_M_DQS_DN<6>")
	)
	(segment
		(start 129.653538 -120.086628)
		(end 130.384296 -119.35587)
		(width 0.14224)
		(layer "In11.Cu")
		(net "M_M_DQS_DN<6>")
	)
	(segment
		(start 138.55065 -147.655534)
		(end 138.55065 -147.909534)
		(width 0.14224)
		(layer "In11.Cu")
		(net "M_M_DQS_DN<6>")
	)
	(segment
		(start 138.55065 -132.477256)
		(end 138.55065 -132.731256)
		(width 0.14224)
		(layer "In11.Cu")
		(net "M_M_DQS_DN<6>")
	)
	(segment
		(start 138.55065 -138.301476)
		(end 138.39317 -138.458956)
		(width 0.14224)
		(layer "In11.Cu")
		(net "M_M_DQS_DN<6>")
	)
	(segment
		(start 137.964418 -149.482556)
		(end 137.6045 -149.842474)
		(width 0.14224)
		(layer "In11.Cu")
		(net "M_M_DQS_DN<6>")
	)
	(segment
		(start 133.416294 -119.952008)
		(end 133.9469 -119.952008)
		(width 0.14224)
		(layer "In11.Cu")
		(net "M_M_DQS_DN<6>")
	)
	(segment
		(start 118.272052 -99.785932)
		(end 118.276878 -99.794568)
		(width 0.0889)
		(layer "In11.Cu")
		(net "M_M_DQS_DN<6>")
	)
	(segment
		(start 138.39317 -133.142736)
		(end 138.55065 -133.300216)
		(width 0.14224)
		(layer "In11.Cu")
		(net "M_M_DQS_DN<6>")
	)
	(segment
		(start 118.209822 -107.165902)
		(end 118.209822 -107.188)
		(width 0.0889)
		(layer "In11.Cu")
		(net "M_M_DQS_DN<6>")
	)
	(segment
		(start 132.948934 -119.100092)
		(end 133.103874 -119.255032)
		(width 0.14224)
		(layer "In11.Cu")
		(net "M_M_DQS_DN<6>")
	)
	(segment
		(start 133.9469 -119.952008)
		(end 138.55065 -124.555758)
		(width 0.14224)
		(layer "In11.Cu")
		(net "M_M_DQS_DN<6>")
	)
	(segment
		(start 118.276878 -104.14)
		(end 118.272052 -104.148636)
		(width 0.0889)
		(layer "In11.Cu")
		(net "M_M_DQS_DN<6>")
	)
	(segment
		(start 138.03757 -149.482556)
		(end 137.964418 -149.482556)
		(width 0.14224)
		(layer "In11.Cu")
		(net "M_M_DQS_DN<6>")
	)
	(segment
		(start 118.272052 -103.158036)
		(end 118.265702 -103.168704)
		(width 0.0889)
		(layer "In11.Cu")
		(net "M_M_DQS_DN<6>")
	)
	(segment
		(start 138.55065 -132.731256)
		(end 138.39317 -132.888736)
		(width 0.14224)
		(layer "In11.Cu")
		(net "M_M_DQS_DN<6>")
	)
	(segment
		(start 137.6045 -151.1046)
		(end 137.39368 -151.31542)
		(width 0.14224)
		(layer "In11.Cu")
		(net "M_M_DQS_DN<6>")
	)
	(segment
		(start 138.39317 -146.675094)
		(end 138.55065 -146.832574)
		(width 0.14224)
		(layer "In11.Cu")
		(net "M_M_DQS_DN<6>")
	)
	(segment
		(start 138.39317 -141.87805)
		(end 138.55065 -142.03553)
		(width 0.14224)
		(layer "In11.Cu")
		(net "M_M_DQS_DN<6>")
	)
	(segment
		(start 138.55065 -141.46657)
		(end 138.39317 -141.62405)
		(width 0.14224)
		(layer "In11.Cu")
		(net "M_M_DQS_DN<6>")
	)
	(segment
		(start 132.440934 -119.255032)
		(end 132.595874 -119.100092)
		(width 0.14224)
		(layer "In11.Cu")
		(net "M_M_DQS_DN<6>")
	)
	(segment
		(start 138.55065 -128.835404)
		(end 138.4427 -128.943354)
		(width 0.14224)
		(layer "In11.Cu")
		(net "M_M_DQS_DN<6>")
	)
	(segment
		(start 132.595874 -119.100092)
		(end 132.948934 -119.100092)
		(width 0.14224)
		(layer "In11.Cu")
		(net "M_M_DQS_DN<6>")
	)
	(segment
		(start 118.272052 -105.139236)
		(end 118.265702 -105.149904)
		(width 0.0889)
		(layer "In11.Cu")
		(net "M_M_DQS_DN<6>")
	)
	(segment
		(start 138.55065 -137.478516)
		(end 138.39317 -137.635996)
		(width 0.14224)
		(layer "In11.Cu")
		(net "M_M_DQS_DN<6>")
	)
	(segment
		(start 130.384296 -119.35587)
		(end 130.838448 -119.35587)
		(width 0.14224)
		(layer "In11.Cu")
		(net "M_M_DQS_DN<6>")
	)
	(segment
		(start 138.4427 -129.197354)
		(end 138.55065 -129.305304)
		(width 0.14224)
		(layer "In11.Cu")
		(net "M_M_DQS_DN<6>")
	)
	(segment
		(start 138.39317 -133.965696)
		(end 138.55065 -134.123176)
		(width 0.14224)
		(layer "In11.Cu")
		(net "M_M_DQS_DN<6>")
	)
	(segment
		(start 138.55065 -129.305304)
		(end 138.55065 -131.908296)
		(width 0.14224)
		(layer "In11.Cu")
		(net "M_M_DQS_DN<6>")
	)
	(segment
		(start 138.55065 -137.224516)
		(end 138.55065 -137.478516)
		(width 0.14224)
		(layer "In11.Cu")
		(net "M_M_DQS_DN<6>")
	)
	(segment
		(start 138.55065 -142.03553)
		(end 138.55065 -142.28953)
		(width 0.14224)
		(layer "In11.Cu")
		(net "M_M_DQS_DN<6>")
	)
	(segment
		(start 125.2347 -120.086628)
		(end 129.653538 -120.086628)
		(width 0.14224)
		(layer "In11.Cu")
		(net "M_M_DQS_DN<6>")
	)
	(segment
		(start 113.979706 -93.347794)
		(end 113.979452 -93.34754)
		(width 0.0889)
		(layer "In11.Cu")
		(net "M_M_DQS_DN<6>")
	)
	(segment
		(start 138.39317 -136.813036)
		(end 138.39317 -137.067036)
		(width 0.14224)
		(layer "In11.Cu")
		(net "M_M_DQS_DN<6>")
	)
	(segment
		(start 118.325392 -106.130598)
		(end 118.249192 -106.206798)
		(width 0.0889)
		(layer "In11.Cu")
		(net "M_M_DQS_DN<6>")
	)
	(segment
		(start 138.55065 -124.555758)
		(end 138.55065 -128.835404)
		(width 0.14224)
		(layer "In11.Cu")
		(net "M_M_DQS_DN<6>")
	)
	(segment
		(start 133.103874 -119.639588)
		(end 133.416294 -119.952008)
		(width 0.14224)
		(layer "In11.Cu")
		(net "M_M_DQS_DN<6>")
	)
	(segment
		(start 138.4427 -128.943354)
		(end 138.4427 -129.197354)
		(width 0.14224)
		(layer "In11.Cu")
		(net "M_M_DQS_DN<6>")
	)
	(segment
		(start 138.55065 -146.832574)
		(end 138.55065 -147.086574)
		(width 0.14224)
		(layer "In11.Cu")
		(net "M_M_DQS_DN<6>")
	)
	(segment
		(start 137.6045 -153.1874)
		(end 137.6045 -154.443176)
		(width 0.14224)
		(layer "In11.Cu")
		(net "M_M_DQS_DN<6>")
	)
	(segment
		(start 138.55065 -131.908296)
		(end 138.39317 -132.065776)
		(width 0.14224)
		(layer "In11.Cu")
		(net "M_M_DQS_DN<6>")
	)
	(segment
		(start 138.55065 -138.047476)
		(end 138.55065 -138.301476)
		(width 0.14224)
		(layer "In11.Cu")
		(net "M_M_DQS_DN<6>")
	)
	(segment
		(start 113.979452 -94.737936)
		(end 113.973102 -94.748604)
		(width 0.0889)
		(layer "In11.Cu")
		(net "M_M_DQS_DN<6>")
	)
	(segment
		(start 138.39317 -148.067014)
		(end 138.39317 -148.321014)
		(width 0.14224)
		(layer "In11.Cu")
		(net "M_M_DQS_DN<6>")
	)
	(segment
		(start 138.39317 -147.244054)
		(end 138.39317 -147.498054)
		(width 0.14224)
		(layer "In11.Cu")
		(net "M_M_DQS_DN<6>")
	)
	(segment
		(start 138.55065 -147.909534)
		(end 138.39317 -148.067014)
		(width 0.14224)
		(layer "In11.Cu")
		(net "M_M_DQS_DN<6>")
	)
	(segment
		(start 118.276878 -103.1494)
		(end 118.272052 -103.158036)
		(width 0.0889)
		(layer "In11.Cu")
		(net "M_M_DQS_DN<6>")
	)
	(segment
		(start 138.39317 -138.712956)
		(end 138.55065 -138.870436)
		(width 0.14224)
		(layer "In11.Cu")
		(net "M_M_DQS_DN<6>")
	)
	(segment
		(start 118.209822 -113.06175)
		(end 125.2347 -120.086628)
		(width 0.14224)
		(layer "In11.Cu")
		(net "M_M_DQS_DN<6>")
	)
	(segment
		(start 137.6045 -154.443176)
		(end 138.03757 -154.876246)
		(width 0.14224)
		(layer "In11.Cu")
		(net "M_M_DQS_DN<6>")
	)
	(segment
		(start 138.55065 -149.196044)
		(end 138.264138 -149.482556)
		(width 0.14224)
		(layer "In11.Cu")
		(net "M_M_DQS_DN<6>")
	)
	(segment
		(start 137.6045 -149.842474)
		(end 137.6045 -151.1046)
		(width 0.14224)
		(layer "In11.Cu")
		(net "M_M_DQS_DN<6>")
	)
	(segment
		(start 138.39317 -138.458956)
		(end 138.39317 -138.712956)
		(width 0.14224)
		(layer "In11.Cu")
		(net "M_M_DQS_DN<6>")
	)
	(segment
		(start 138.55065 -143.68145)
		(end 138.55065 -146.263614)
		(width 0.14224)
		(layer "In11.Cu")
		(net "M_M_DQS_DN<6>")
	)
	(segment
		(start 117.045232 -98.100134)
		(end 117.077998 -98.100134)
		(width 0.0889)
		(layer "In11.Cu")
		(net "M_M_DQS_DN<6>")
	)
	(segment
		(start 118.325392 -105.822242)
		(end 118.325392 -106.130598)
		(width 0.0889)
		(layer "In11.Cu")
		(net "M_M_DQS_DN<6>")
	)
	(segment
		(start 132.128514 -119.952008)
		(end 132.440934 -119.639588)
		(width 0.14224)
		(layer "In11.Cu")
		(net "M_M_DQS_DN<6>")
	)
	(segment
		(start 118.249192 -107.126532)
		(end 118.209822 -107.165902)
		(width 0.0889)
		(layer "In11.Cu")
		(net "M_M_DQS_DN<6>")
	)
	(segment
		(start 138.39317 -142.70101)
		(end 138.55065 -142.85849)
		(width 0.14224)
		(layer "In11.Cu")
		(net "M_M_DQS_DN<6>")
	)
	(segment
		(start 138.39317 -137.067036)
		(end 138.55065 -137.224516)
		(width 0.14224)
		(layer "In11.Cu")
		(net "M_M_DQS_DN<6>")
	)
	(segment
		(start 138.39317 -143.26997)
		(end 138.39317 -143.52397)
		(width 0.14224)
		(layer "In11.Cu")
		(net "M_M_DQS_DN<6>")
	)
	(segment
		(start 138.39317 -132.888736)
		(end 138.39317 -133.142736)
		(width 0.14224)
		(layer "In11.Cu")
		(net "M_M_DQS_DN<6>")
	)
	(segment
		(start 138.39317 -146.421094)
		(end 138.39317 -146.675094)
		(width 0.14224)
		(layer "In11.Cu")
		(net "M_M_DQS_DN<6>")
	)
	(segment
		(start 138.39317 -132.065776)
		(end 138.39317 -132.319776)
		(width 0.14224)
		(layer "In11.Cu")
		(net "M_M_DQS_DN<6>")
	)
	(segment
		(start 138.39317 -142.44701)
		(end 138.39317 -142.70101)
		(width 0.14224)
		(layer "In11.Cu")
		(net "M_M_DQS_DN<6>")
	)
	(arc
		(start 113.979452 -94.33814)
		(mid 114.032951 -94.538038)
		(end 113.979452 -94.737936)
		(width 0.0889)
		(layer "In11.Cu")
		(net "M_M_DQS_DN<6>")
	)
	(arc
		(start 118.276878 -101.775768)
		(mid 118.325633 -101.97212)
		(end 118.272052 -102.167182)
		(width 0.0889)
		(layer "In11.Cu")
		(net "M_M_DQS_DN<6>")
	)
	(arc
		(start 118.265702 -101.75621)
		(mid 118.27139 -101.765932)
		(end 118.276878 -101.775768)
		(width 0.0889)
		(layer "In11.Cu")
		(net "M_M_DQS_DN<6>")
	)
	(arc
		(start 118.272052 -101.176582)
		(mid 118.193057 -101.465557)
		(end 118.265702 -101.75621)
		(width 0.0889)
		(layer "In11.Cu")
		(net "M_M_DQS_DN<6>")
	)
	(arc
		(start 118.272052 -100.185982)
		(mid 118.193057 -100.474957)
		(end 118.265702 -100.76561)
		(width 0.0889)
		(layer "In11.Cu")
		(net "M_M_DQS_DN<6>")
	)
	(arc
		(start 118.276878 -99.794568)
		(mid 118.325633 -99.99092)
		(end 118.272052 -100.185982)
		(width 0.0889)
		(layer "In11.Cu")
		(net "M_M_DQS_DN<6>")
	)
	(arc
		(start 118.272052 -103.748586)
		(mid 118.325522 -103.943649)
		(end 118.276878 -104.14)
		(width 0.0889)
		(layer "In11.Cu")
		(net "M_M_DQS_DN<6>")
	)
	(arc
		(start 114.506248 -96.614488)
		(mid 114.69789 -96.671654)
		(end 114.837972 -96.814386)
		(width 0.0889)
		(layer "In11.Cu")
		(net "M_M_DQS_DN<6>")
	)
	(arc
		(start 118.265702 -103.168704)
		(mid 118.192904 -103.459467)
		(end 118.272052 -103.748586)
		(width 0.0889)
		(layer "In11.Cu")
		(net "M_M_DQS_DN<6>")
	)
	(arc
		(start 115.696492 -97.309686)
		(mid 115.9051 -97.521618)
		(end 116.190522 -97.605088)
		(width 0.0889)
		(layer "In11.Cu")
		(net "M_M_DQS_DN<6>")
	)
	(arc
		(start 116.555012 -97.804986)
		(mid 116.762016 -98.01585)
		(end 117.045232 -98.100134)
		(width 0.0889)
		(layer "In11.Cu")
		(net "M_M_DQS_DN<6>")
	)
	(arc
		(start 118.272052 -104.739186)
		(mid 118.325522 -104.934249)
		(end 118.276878 -105.1306)
		(width 0.0889)
		(layer "In11.Cu")
		(net "M_M_DQS_DN<6>")
	)
	(arc
		(start 118.265702 -100.76561)
		(mid 118.286311 -100.803355)
		(end 118.302786 -100.84308)
		(width 0.0889)
		(layer "In11.Cu")
		(net "M_M_DQS_DN<6>")
	)
	(arc
		(start 117.940328 -98.595688)
		(mid 118.273246 -98.797679)
		(end 118.276878 -99.187)
		(width 0.0889)
		(layer "In11.Cu")
		(net "M_M_DQS_DN<6>")
	)
	(arc
		(start 113.979452 -93.747336)
		(mid 113.900389 -94.042738)
		(end 113.979452 -94.33814)
		(width 0.0889)
		(layer "In11.Cu")
		(net "M_M_DQS_DN<6>")
	)
	(arc
		(start 118.272052 -102.167182)
		(mid 118.192921 -102.462584)
		(end 118.272052 -102.757986)
		(width 0.0889)
		(layer "In11.Cu")
		(net "M_M_DQS_DN<6>")
	)
	(arc
		(start 115.360958 -97.109534)
		(mid 115.554808 -97.165884)
		(end 115.696492 -97.309686)
		(width 0.0889)
		(layer "In11.Cu")
		(net "M_M_DQS_DN<6>")
	)
	(arc
		(start 113.984278 -95.337122)
		(mid 114.033033 -95.533474)
		(end 113.979452 -95.728536)
		(width 0.0889)
		(layer "In11.Cu")
		(net "M_M_DQS_DN<6>")
	)
	(arc
		(start 118.265702 -104.159304)
		(mid 118.192904 -104.450067)
		(end 118.272052 -104.739186)
		(width 0.0889)
		(layer "In11.Cu")
		(net "M_M_DQS_DN<6>")
	)
	(arc
		(start 113.979452 -93.34754)
		(mid 114.032951 -93.547438)
		(end 113.979452 -93.747336)
		(width 0.0889)
		(layer "In11.Cu")
		(net "M_M_DQS_DN<6>")
	)
	(arc
		(start 118.272052 -99.195636)
		(mid 118.193047 -99.490784)
		(end 118.272052 -99.785932)
		(width 0.0889)
		(layer "In11.Cu")
		(net "M_M_DQS_DN<6>")
	)
	(arc
		(start 116.223288 -97.605088)
		(mid 116.41493 -97.662254)
		(end 116.555012 -97.804986)
		(width 0.0889)
		(layer "In11.Cu")
		(net "M_M_DQS_DN<6>")
	)
	(arc
		(start 118.265702 -105.149904)
		(mid 118.192904 -105.440667)
		(end 118.272052 -105.729786)
		(width 0.0889)
		(layer "In11.Cu")
		(net "M_M_DQS_DN<6>")
	)
	(arc
		(start 114.837972 -96.814386)
		(mid 115.044976 -97.02525)
		(end 115.328192 -97.109534)
		(width 0.0889)
		(layer "In11.Cu")
		(net "M_M_DQS_DN<6>")
	)
	(arc
		(start 113.632742 -92.556584)
		(mid 113.784508 -92.961711)
		(end 113.979706 -93.347794)
		(width 0.0889)
		(layer "In11.Cu")
		(net "M_M_DQS_DN<6>")
	)
	(arc
		(start 118.272052 -102.757986)
		(mid 118.325522 -102.953049)
		(end 118.276878 -103.1494)
		(width 0.0889)
		(layer "In11.Cu")
		(net "M_M_DQS_DN<6>")
	)
	(arc
		(start 117.413532 -98.300286)
		(mid 117.62214 -98.512218)
		(end 117.907562 -98.595688)
		(width 0.0889)
		(layer "In11.Cu")
		(net "M_M_DQS_DN<6>")
	)
	(arc
		(start 118.302786 -100.84308)
		(mid 118.323958 -101.013195)
		(end 118.272052 -101.176582)
		(width 0.0889)
		(layer "In11.Cu")
		(net "M_M_DQS_DN<6>")
	)
	(arc
		(start 117.077998 -98.100134)
		(mid 117.271848 -98.156484)
		(end 117.413532 -98.300286)
		(width 0.0889)
		(layer "In11.Cu")
		(net "M_M_DQS_DN<6>")
	)
	(arc
		(start 113.973102 -94.748604)
		(mid 113.900304 -95.039367)
		(end 113.979452 -95.328486)
		(width 0.0889)
		(layer "In11.Cu")
		(net "M_M_DQS_DN<6>")
	)
	(arc
		(start 113.979452 -95.728536)
		(mid 113.975123 -96.311708)
		(end 114.473482 -96.614488)
		(width 0.0889)
		(layer "In11.Cu")
		(net "M_M_DQS_DN<6>")
	)
	(segment
		(start 115.636802 -96.023938)
		(end 116.208302 -96.023938)
		(width 0.1651)
		(layer "F.Cu")
		(net "M_M_DQS_DN<5>")
	)
	(segment
		(start 128.47193 -154.6606)
		(end 128.687576 -154.876246)
		(width 0.1651)
		(layer "F.Cu")
		(net "M_M_DQS_DN<5>")
	)
	(segment
		(start 127.917448 -155.422854)
		(end 127.917448 -154.991054)
		(width 0.1651)
		(layer "F.Cu")
		(net "M_M_DQS_DN<5>")
	)
	(segment
		(start 128.299464 -155.80487)
		(end 127.917448 -155.422854)
		(width 0.1651)
		(layer "F.Cu")
		(net "M_M_DQS_DN<5>")
	)
	(segment
		(start 128.247902 -154.6606)
		(end 128.47193 -154.6606)
		(width 0.1651)
		(layer "F.Cu")
		(net "M_M_DQS_DN<5>")
	)
	(segment
		(start 128.299464 -156.87294)
		(end 128.299464 -155.80487)
		(width 0.1651)
		(layer "F.Cu")
		(net "M_M_DQS_DN<5>")
	)
	(segment
		(start 127.917448 -154.991054)
		(end 128.247902 -154.6606)
		(width 0.1651)
		(layer "F.Cu")
		(net "M_M_DQS_DN<5>")
	)
	(via
		(at 128.687576 -149.482556)
		(size 0.508)
		(drill 0.254)
		(layers "F.Cu" "B.Cu")
		(net "M_M_DQS_DN<5>")
	)
	(via
		(at 116.208302 -96.023938)
		(size 0.508)
		(drill 0.254)
		(layers "F.Cu" "B.Cu")
		(net "M_M_DQS_DN<5>")
	)
	(via
		(at 128.687576 -154.876246)
		(size 0.508)
		(drill 0.254)
		(layers "F.Cu" "B.Cu")
		(net "M_M_DQS_DN<5>")
	)
	(segment
		(start 128.273048 -149.7076)
		(end 128.462532 -149.7076)
		(width 0.1651)
		(layer "B.Cu")
		(net "M_M_DQS_DN<5>")
	)
	(segment
		(start 128.171448 -148.767546)
		(end 127.917448 -149.021546)
		(width 0.1651)
		(layer "B.Cu")
		(net "M_M_DQS_DN<5>")
	)
	(segment
		(start 128.299464 -148.38553)
		(end 128.171448 -148.513546)
		(width 0.1651)
		(layer "B.Cu")
		(net "M_M_DQS_DN<5>")
	)
	(segment
		(start 128.462532 -149.7076)
		(end 128.687576 -149.482556)
		(width 0.1651)
		(layer "B.Cu")
		(net "M_M_DQS_DN<5>")
	)
	(segment
		(start 127.917448 -149.021546)
		(end 127.917448 -149.352)
		(width 0.1651)
		(layer "B.Cu")
		(net "M_M_DQS_DN<5>")
	)
	(segment
		(start 128.299464 -147.478496)
		(end 128.299464 -148.38553)
		(width 0.1651)
		(layer "B.Cu")
		(net "M_M_DQS_DN<5>")
	)
	(segment
		(start 128.171448 -148.513546)
		(end 128.171448 -148.767546)
		(width 0.1651)
		(layer "B.Cu")
		(net "M_M_DQS_DN<5>")
	)
	(segment
		(start 127.917448 -149.352)
		(end 128.273048 -149.7076)
		(width 0.1651)
		(layer "B.Cu")
		(net "M_M_DQS_DN<5>")
	)
	(segment
		(start 129.200656 -147.929854)
		(end 129.043176 -148.087334)
		(width 0.14224)
		(layer "In4.Cu")
		(net "M_M_DQS_DN<5>")
	)
	(segment
		(start 129.043176 -143.505174)
		(end 129.200656 -143.662654)
		(width 0.14224)
		(layer "In4.Cu")
		(net "M_M_DQS_DN<5>")
	)
	(segment
		(start 117.600222 -112.736122)
		(end 127.483108 -122.619008)
		(width 0.14224)
		(layer "In4.Cu")
		(net "M_M_DQS_DN<5>")
	)
	(segment
		(start 129.043176 -143.251174)
		(end 129.043176 -143.505174)
		(width 0.14224)
		(layer "In4.Cu")
		(net "M_M_DQS_DN<5>")
	)
	(segment
		(start 129.043176 -133.606032)
		(end 129.043176 -133.860032)
		(width 0.14224)
		(layer "In4.Cu")
		(net "M_M_DQS_DN<5>")
	)
	(segment
		(start 129.200656 -137.434828)
		(end 129.043176 -137.592308)
		(width 0.14224)
		(layer "In4.Cu")
		(net "M_M_DQS_DN<5>")
	)
	(segment
		(start 129.043176 -148.087334)
		(end 129.043176 -148.341334)
		(width 0.14224)
		(layer "In4.Cu")
		(net "M_M_DQS_DN<5>")
	)
	(segment
		(start 129.043176 -137.592308)
		(end 129.043176 -137.846308)
		(width 0.14224)
		(layer "In4.Cu")
		(net "M_M_DQS_DN<5>")
	)
	(segment
		(start 129.200656 -143.662654)
		(end 129.200656 -146.283934)
		(width 0.14224)
		(layer "In4.Cu")
		(net "M_M_DQS_DN<5>")
	)
	(segment
		(start 128.469136 -122.258074)
		(end 128.73609 -122.258074)
		(width 0.14224)
		(layer "In4.Cu")
		(net "M_M_DQS_DN<5>")
	)
	(segment
		(start 129.043176 -132.214112)
		(end 129.200656 -132.371592)
		(width 0.14224)
		(layer "In4.Cu")
		(net "M_M_DQS_DN<5>")
	)
	(segment
		(start 129.200656 -142.016734)
		(end 129.200656 -142.270734)
		(width 0.14224)
		(layer "In4.Cu")
		(net "M_M_DQS_DN<5>")
	)
	(segment
		(start 129.043176 -133.037072)
		(end 129.200656 -133.194552)
		(width 0.14224)
		(layer "In4.Cu")
		(net "M_M_DQS_DN<5>")
	)
	(segment
		(start 129.043176 -141.859254)
		(end 129.200656 -142.016734)
		(width 0.14224)
		(layer "In4.Cu")
		(net "M_M_DQS_DN<5>")
	)
	(segment
		(start 116.56187 -101.16439)
		(end 116.546122 -101.191822)
		(width 0.0889)
		(layer "In4.Cu")
		(net "M_M_DQS_DN<5>")
	)
	(segment
		(start 117.45341 -106.294428)
		(end 117.453918 -106.295444)
		(width 0.0889)
		(layer "In4.Cu")
		(net "M_M_DQS_DN<5>")
	)
	(segment
		(start 129.200656 -124.452888)
		(end 129.200656 -131.802632)
		(width 0.14224)
		(layer "In4.Cu")
		(net "M_M_DQS_DN<5>")
	)
	(segment
		(start 129.200656 -142.839694)
		(end 129.200656 -143.093694)
		(width 0.14224)
		(layer "In4.Cu")
		(net "M_M_DQS_DN<5>")
	)
	(segment
		(start 129.200656 -141.447774)
		(end 129.043176 -141.605254)
		(width 0.14224)
		(layer "In4.Cu")
		(net "M_M_DQS_DN<5>")
	)
	(segment
		(start 129.200656 -149.248876)
		(end 128.966976 -149.482556)
		(width 0.14224)
		(layer "In4.Cu")
		(net "M_M_DQS_DN<5>")
	)
	(segment
		(start 117.453918 -106.295444)
		(end 117.639592 -106.481118)
		(width 0.0889)
		(layer "In4.Cu")
		(net "M_M_DQS_DN<5>")
	)
	(segment
		(start 129.043176 -132.783072)
		(end 129.043176 -133.037072)
		(width 0.14224)
		(layer "In4.Cu")
		(net "M_M_DQS_DN<5>")
	)
	(segment
		(start 129.200656 -134.017512)
		(end 129.200656 -136.611868)
		(width 0.14224)
		(layer "In4.Cu")
		(net "M_M_DQS_DN<5>")
	)
	(segment
		(start 129.043176 -148.341334)
		(end 129.200656 -148.498814)
		(width 0.14224)
		(layer "In4.Cu")
		(net "M_M_DQS_DN<5>")
	)
	(segment
		(start 129.043176 -142.428214)
		(end 129.043176 -142.682214)
		(width 0.14224)
		(layer "In4.Cu")
		(net "M_M_DQS_DN<5>")
	)
	(segment
		(start 129.043176 -137.023348)
		(end 129.200656 -137.180828)
		(width 0.14224)
		(layer "In4.Cu")
		(net "M_M_DQS_DN<5>")
	)
	(segment
		(start 128.507236 -123.306078)
		(end 128.507236 -123.759468)
		(width 0.14224)
		(layer "In4.Cu")
		(net "M_M_DQS_DN<5>")
	)
	(segment
		(start 129.200656 -132.625592)
		(end 129.043176 -132.783072)
		(width 0.14224)
		(layer "In4.Cu")
		(net "M_M_DQS_DN<5>")
	)
	(segment
		(start 129.200656 -140.42644)
		(end 129.200656 -141.447774)
		(width 0.14224)
		(layer "In4.Cu")
		(net "M_M_DQS_DN<5>")
	)
	(segment
		(start 129.043176 -147.264374)
		(end 129.043176 -147.518374)
		(width 0.14224)
		(layer "In4.Cu")
		(net "M_M_DQS_DN<5>")
	)
	(segment
		(start 127.483108 -122.619008)
		(end 128.108202 -122.619008)
		(width 0.14224)
		(layer "In4.Cu")
		(net "M_M_DQS_DN<5>")
	)
	(segment
		(start 129.107184 -140.078968)
		(end 129.107184 -140.332968)
		(width 0.14224)
		(layer "In4.Cu")
		(net "M_M_DQS_DN<5>")
	)
	(segment
		(start 129.043176 -138.669268)
		(end 129.200656 -138.826748)
		(width 0.14224)
		(layer "In4.Cu")
		(net "M_M_DQS_DN<5>")
	)
	(segment
		(start 129.200656 -147.106894)
		(end 129.043176 -147.264374)
		(width 0.14224)
		(layer "In4.Cu")
		(net "M_M_DQS_DN<5>")
	)
	(segment
		(start 117.600222 -107.476798)
		(end 117.600222 -112.736122)
		(width 0.14224)
		(layer "In4.Cu")
		(net "M_M_DQS_DN<5>")
	)
	(segment
		(start 117.404896 -106.209592)
		(end 117.45341 -106.294428)
		(width 0.0889)
		(layer "In4.Cu")
		(net "M_M_DQS_DN<5>")
	)
	(segment
		(start 129.200656 -133.448552)
		(end 129.043176 -133.606032)
		(width 0.14224)
		(layer "In4.Cu")
		(net "M_M_DQS_DN<5>")
	)
	(segment
		(start 129.200656 -138.826748)
		(end 129.200656 -139.985496)
		(width 0.14224)
		(layer "In4.Cu")
		(net "M_M_DQS_DN<5>")
	)
	(segment
		(start 129.200656 -138.257788)
		(end 129.043176 -138.415268)
		(width 0.14224)
		(layer "In4.Cu")
		(net "M_M_DQS_DN<5>")
	)
	(segment
		(start 129.043176 -133.860032)
		(end 129.200656 -134.017512)
		(width 0.14224)
		(layer "In4.Cu")
		(net "M_M_DQS_DN<5>")
	)
	(segment
		(start 129.043176 -146.441414)
		(end 129.043176 -146.695414)
		(width 0.14224)
		(layer "In4.Cu")
		(net "M_M_DQS_DN<5>")
	)
	(segment
		(start 129.200656 -147.675854)
		(end 129.200656 -147.929854)
		(width 0.14224)
		(layer "In4.Cu")
		(net "M_M_DQS_DN<5>")
	)
	(segment
		(start 128.507236 -123.759468)
		(end 129.200656 -124.452888)
		(width 0.14224)
		(layer "In4.Cu")
		(net "M_M_DQS_DN<5>")
	)
	(segment
		(start 129.200656 -131.802632)
		(end 129.043176 -131.960112)
		(width 0.14224)
		(layer "In4.Cu")
		(net "M_M_DQS_DN<5>")
	)
	(segment
		(start 117.04193 -105.03408)
		(end 117.071648 -105.03408)
		(width 0.0889)
		(layer "In4.Cu")
		(net "M_M_DQS_DN<5>")
	)
	(segment
		(start 129.043176 -138.415268)
		(end 129.043176 -138.669268)
		(width 0.14224)
		(layer "In4.Cu")
		(net "M_M_DQS_DN<5>")
	)
	(segment
		(start 129.200656 -132.371592)
		(end 129.200656 -132.625592)
		(width 0.14224)
		(layer "In4.Cu")
		(net "M_M_DQS_DN<5>")
	)
	(segment
		(start 129.200656 -139.985496)
		(end 129.107184 -140.078968)
		(width 0.14224)
		(layer "In4.Cu")
		(net "M_M_DQS_DN<5>")
	)
	(segment
		(start 116.56187 -102.15499)
		(end 116.546122 -102.182422)
		(width 0.0889)
		(layer "In4.Cu")
		(net "M_M_DQS_DN<5>")
	)
	(segment
		(start 129.05613 -122.578114)
		(end 129.05613 -122.757184)
		(width 0.14224)
		(layer "In4.Cu")
		(net "M_M_DQS_DN<5>")
	)
	(segment
		(start 129.043176 -146.695414)
		(end 129.200656 -146.852894)
		(width 0.14224)
		(layer "In4.Cu")
		(net "M_M_DQS_DN<5>")
	)
	(segment
		(start 129.200656 -138.003788)
		(end 129.200656 -138.257788)
		(width 0.14224)
		(layer "In4.Cu")
		(net "M_M_DQS_DN<5>")
	)
	(segment
		(start 129.200656 -133.194552)
		(end 129.200656 -133.448552)
		(width 0.14224)
		(layer "In4.Cu")
		(net "M_M_DQS_DN<5>")
	)
	(segment
		(start 128.966976 -149.482556)
		(end 128.687576 -149.482556)
		(width 0.14224)
		(layer "In4.Cu")
		(net "M_M_DQS_DN<5>")
	)
	(segment
		(start 129.043176 -137.846308)
		(end 129.200656 -138.003788)
		(width 0.14224)
		(layer "In4.Cu")
		(net "M_M_DQS_DN<5>")
	)
	(segment
		(start 129.05613 -122.757184)
		(end 128.507236 -123.306078)
		(width 0.14224)
		(layer "In4.Cu")
		(net "M_M_DQS_DN<5>")
	)
	(segment
		(start 129.200656 -143.093694)
		(end 129.043176 -143.251174)
		(width 0.14224)
		(layer "In4.Cu")
		(net "M_M_DQS_DN<5>")
	)
	(segment
		(start 129.107184 -140.332968)
		(end 129.200656 -140.42644)
		(width 0.14224)
		(layer "In4.Cu")
		(net "M_M_DQS_DN<5>")
	)
	(segment
		(start 116.56187 -104.13619)
		(end 116.546122 -104.163622)
		(width 0.0889)
		(layer "In4.Cu")
		(net "M_M_DQS_DN<5>")
	)
	(segment
		(start 129.043176 -142.682214)
		(end 129.200656 -142.839694)
		(width 0.14224)
		(layer "In4.Cu")
		(net "M_M_DQS_DN<5>")
	)
	(segment
		(start 129.200656 -142.270734)
		(end 129.043176 -142.428214)
		(width 0.14224)
		(layer "In4.Cu")
		(net "M_M_DQS_DN<5>")
	)
	(segment
		(start 117.600222 -107.4547)
		(end 117.600222 -107.476798)
		(width 0.0889)
		(layer "In4.Cu")
		(net "M_M_DQS_DN<5>")
	)
	(segment
		(start 129.043176 -136.769348)
		(end 129.043176 -137.023348)
		(width 0.14224)
		(layer "In4.Cu")
		(net "M_M_DQS_DN<5>")
	)
	(segment
		(start 129.200656 -146.283934)
		(end 129.043176 -146.441414)
		(width 0.14224)
		(layer "In4.Cu")
		(net "M_M_DQS_DN<5>")
	)
	(segment
		(start 117.639592 -107.41533)
		(end 117.600222 -107.4547)
		(width 0.0889)
		(layer "In4.Cu")
		(net "M_M_DQS_DN<5>")
	)
	(segment
		(start 129.200656 -137.180828)
		(end 129.200656 -137.434828)
		(width 0.14224)
		(layer "In4.Cu")
		(net "M_M_DQS_DN<5>")
	)
	(segment
		(start 116.56187 -100.17379)
		(end 116.546122 -100.201222)
		(width 0.0889)
		(layer "In4.Cu")
		(net "M_M_DQS_DN<5>")
	)
	(segment
		(start 129.200656 -148.498814)
		(end 129.200656 -149.248876)
		(width 0.14224)
		(layer "In4.Cu")
		(net "M_M_DQS_DN<5>")
	)
	(segment
		(start 129.043176 -141.605254)
		(end 129.043176 -141.859254)
		(width 0.14224)
		(layer "In4.Cu")
		(net "M_M_DQS_DN<5>")
	)
	(segment
		(start 129.200656 -146.852894)
		(end 129.200656 -147.106894)
		(width 0.14224)
		(layer "In4.Cu")
		(net "M_M_DQS_DN<5>")
	)
	(segment
		(start 128.108202 -122.619008)
		(end 128.469136 -122.258074)
		(width 0.14224)
		(layer "In4.Cu")
		(net "M_M_DQS_DN<5>")
	)
	(segment
		(start 129.200656 -136.611868)
		(end 129.043176 -136.769348)
		(width 0.14224)
		(layer "In4.Cu")
		(net "M_M_DQS_DN<5>")
	)
	(segment
		(start 128.73609 -122.258074)
		(end 129.05613 -122.578114)
		(width 0.14224)
		(layer "In4.Cu")
		(net "M_M_DQS_DN<5>")
	)
	(segment
		(start 129.043176 -147.518374)
		(end 129.200656 -147.675854)
		(width 0.14224)
		(layer "In4.Cu")
		(net "M_M_DQS_DN<5>")
	)
	(segment
		(start 117.639592 -106.481118)
		(end 117.639592 -107.41533)
		(width 0.0889)
		(layer "In4.Cu")
		(net "M_M_DQS_DN<5>")
	)
	(segment
		(start 129.043176 -131.960112)
		(end 129.043176 -132.214112)
		(width 0.14224)
		(layer "In4.Cu")
		(net "M_M_DQS_DN<5>")
	)
	(arc
		(start 116.555012 -100.776786)
		(mid 116.60845 -100.969691)
		(end 116.56187 -101.16439)
		(width 0.0889)
		(layer "In4.Cu")
		(net "M_M_DQS_DN<5>")
	)
	(arc
		(start 117.413532 -105.634536)
		(mid 117.334469 -105.920957)
		(end 117.404896 -106.209592)
		(width 0.0889)
		(layer "In4.Cu")
		(net "M_M_DQS_DN<5>")
	)
	(arc
		(start 116.546122 -104.163622)
		(mid 116.553127 -104.736095)
		(end 117.04193 -105.03408)
		(width 0.0889)
		(layer "In4.Cu")
		(net "M_M_DQS_DN<5>")
	)
	(arc
		(start 116.555012 -97.805494)
		(mid 116.608511 -98.005392)
		(end 116.555012 -98.20529)
		(width 0.0889)
		(layer "In4.Cu")
		(net "M_M_DQS_DN<5>")
	)
	(arc
		(start 116.546122 -103.173022)
		(mid 116.475725 -103.461973)
		(end 116.555012 -103.748586)
		(width 0.0889)
		(layer "In4.Cu")
		(net "M_M_DQS_DN<5>")
	)
	(arc
		(start 116.555012 -103.748586)
		(mid 116.60845 -103.941491)
		(end 116.56187 -104.13619)
		(width 0.0889)
		(layer "In4.Cu")
		(net "M_M_DQS_DN<5>")
	)
	(arc
		(start 116.555012 -99.19589)
		(mid 116.477073 -99.452216)
		(end 116.520468 -99.71659)
		(width 0.0889)
		(layer "In4.Cu")
		(net "M_M_DQS_DN<5>")
	)
	(arc
		(start 117.071648 -105.03408)
		(mid 117.414716 -105.236303)
		(end 117.413532 -105.634536)
		(width 0.0889)
		(layer "In4.Cu")
		(net "M_M_DQS_DN<5>")
	)
	(arc
		(start 116.555012 -96.814894)
		(mid 116.608511 -97.014792)
		(end 116.555012 -97.21469)
		(width 0.0889)
		(layer "In4.Cu")
		(net "M_M_DQS_DN<5>")
	)
	(arc
		(start 116.208302 -96.023938)
		(mid 116.359904 -96.428951)
		(end 116.555012 -96.814894)
		(width 0.0889)
		(layer "In4.Cu")
		(net "M_M_DQS_DN<5>")
	)
	(arc
		(start 116.520468 -99.71659)
		(mid 116.536533 -99.751987)
		(end 116.555012 -99.786186)
		(width 0.0889)
		(layer "In4.Cu")
		(net "M_M_DQS_DN<5>")
	)
	(arc
		(start 116.546122 -101.191822)
		(mid 116.475725 -101.480773)
		(end 116.555012 -101.767386)
		(width 0.0889)
		(layer "In4.Cu")
		(net "M_M_DQS_DN<5>")
	)
	(arc
		(start 116.555012 -98.796094)
		(mid 116.608511 -98.995992)
		(end 116.555012 -99.19589)
		(width 0.0889)
		(layer "In4.Cu")
		(net "M_M_DQS_DN<5>")
	)
	(arc
		(start 116.555012 -101.767386)
		(mid 116.60845 -101.960291)
		(end 116.56187 -102.15499)
		(width 0.0889)
		(layer "In4.Cu")
		(net "M_M_DQS_DN<5>")
	)
	(arc
		(start 116.56187 -103.14559)
		(mid 116.554222 -103.159436)
		(end 116.546122 -103.173022)
		(width 0.0889)
		(layer "In4.Cu")
		(net "M_M_DQS_DN<5>")
	)
	(arc
		(start 116.555012 -102.757986)
		(mid 116.60845 -102.950891)
		(end 116.56187 -103.14559)
		(width 0.0889)
		(layer "In4.Cu")
		(net "M_M_DQS_DN<5>")
	)
	(arc
		(start 116.546122 -100.201222)
		(mid 116.475725 -100.490173)
		(end 116.555012 -100.776786)
		(width 0.0889)
		(layer "In4.Cu")
		(net "M_M_DQS_DN<5>")
	)
	(arc
		(start 116.546122 -102.182422)
		(mid 116.475725 -102.471373)
		(end 116.555012 -102.757986)
		(width 0.0889)
		(layer "In4.Cu")
		(net "M_M_DQS_DN<5>")
	)
	(arc
		(start 116.555012 -97.21469)
		(mid 116.475881 -97.510092)
		(end 116.555012 -97.805494)
		(width 0.0889)
		(layer "In4.Cu")
		(net "M_M_DQS_DN<5>")
	)
	(arc
		(start 116.555012 -99.786186)
		(mid 116.60845 -99.979091)
		(end 116.56187 -100.17379)
		(width 0.0889)
		(layer "In4.Cu")
		(net "M_M_DQS_DN<5>")
	)
	(arc
		(start 116.555012 -98.20529)
		(mid 116.475881 -98.500692)
		(end 116.555012 -98.796094)
		(width 0.0889)
		(layer "In4.Cu")
		(net "M_M_DQS_DN<5>")
	)
	(segment
		(start 128.614424 -149.482556)
		(end 128.254252 -149.842728)
		(width 0.14224)
		(layer "In11.Cu")
		(net "M_M_DQS_DN<5>")
	)
	(segment
		(start 128.687576 -149.482556)
		(end 128.614424 -149.482556)
		(width 0.14224)
		(layer "In11.Cu")
		(net "M_M_DQS_DN<5>")
	)
	(segment
		(start 128.043686 -151.31542)
		(end 128.043686 -152.97658)
		(width 0.14224)
		(layer "In11.Cu")
		(net "M_M_DQS_DN<5>")
	)
	(segment
		(start 128.043686 -152.97658)
		(end 128.254252 -153.187146)
		(width 0.14224)
		(layer "In11.Cu")
		(net "M_M_DQS_DN<5>")
	)
	(segment
		(start 128.254252 -151.104854)
		(end 128.043686 -151.31542)
		(width 0.14224)
		(layer "In11.Cu")
		(net "M_M_DQS_DN<5>")
	)
	(segment
		(start 128.254252 -149.842728)
		(end 128.254252 -151.104854)
		(width 0.14224)
		(layer "In11.Cu")
		(net "M_M_DQS_DN<5>")
	)
	(segment
		(start 128.254252 -153.187146)
		(end 128.254252 -154.442922)
		(width 0.14224)
		(layer "In11.Cu")
		(net "M_M_DQS_DN<5>")
	)
	(segment
		(start 128.254252 -154.442922)
		(end 128.687576 -154.876246)
		(width 0.14224)
		(layer "In11.Cu")
		(net "M_M_DQS_DN<5>")
	)
	(segment
		(start 118.897654 -154.6606)
		(end 119.121682 -154.6606)
		(width 0.1651)
		(layer "F.Cu")
		(net "M_M_DQS_DN<4>")
	)
	(segment
		(start 118.5672 -155.422854)
		(end 118.5672 -154.991054)
		(width 0.1651)
		(layer "F.Cu")
		(net "M_M_DQS_DN<4>")
	)
	(segment
		(start 118.949216 -155.80487)
		(end 118.5672 -155.422854)
		(width 0.1651)
		(layer "F.Cu")
		(net "M_M_DQS_DN<4>")
	)
	(segment
		(start 118.5672 -154.991054)
		(end 118.897654 -154.6606)
		(width 0.1651)
		(layer "F.Cu")
		(net "M_M_DQS_DN<4>")
	)
	(segment
		(start 118.94947 -156.87294)
		(end 118.949216 -156.87294)
		(width 0.1651)
		(layer "F.Cu")
		(net "M_M_DQS_DN<4>")
	)
	(segment
		(start 108.768896 -94.042738)
		(end 109.340396 -94.042738)
		(width 0.1651)
		(layer "F.Cu")
		(net "M_M_DQS_DN<4>")
	)
	(segment
		(start 119.121682 -154.6606)
		(end 119.337328 -154.876246)
		(width 0.1651)
		(layer "F.Cu")
		(net "M_M_DQS_DN<4>")
	)
	(segment
		(start 118.949216 -156.87294)
		(end 118.949216 -155.80487)
		(width 0.1651)
		(layer "F.Cu")
		(net "M_M_DQS_DN<4>")
	)
	(via
		(at 109.340396 -94.042738)
		(size 0.508)
		(drill 0.254)
		(layers "F.Cu" "B.Cu")
		(net "M_M_DQS_DN<4>")
	)
	(via
		(at 119.337328 -154.876246)
		(size 0.508)
		(drill 0.254)
		(layers "F.Cu" "B.Cu")
		(net "M_M_DQS_DN<4>")
	)
	(via
		(at 119.337328 -149.482556)
		(size 0.508)
		(drill 0.254)
		(layers "F.Cu" "B.Cu")
		(net "M_M_DQS_DN<4>")
	)
	(segment
		(start 118.5672 -149.021546)
		(end 118.5672 -149.352)
		(width 0.1651)
		(layer "B.Cu")
		(net "M_M_DQS_DN<4>")
	)
	(segment
		(start 118.8212 -148.767546)
		(end 118.5672 -149.021546)
		(width 0.1651)
		(layer "B.Cu")
		(net "M_M_DQS_DN<4>")
	)
	(segment
		(start 118.94947 -148.385276)
		(end 118.8212 -148.513546)
		(width 0.1651)
		(layer "B.Cu")
		(net "M_M_DQS_DN<4>")
	)
	(segment
		(start 119.112284 -149.7076)
		(end 119.337328 -149.482556)
		(width 0.1651)
		(layer "B.Cu")
		(net "M_M_DQS_DN<4>")
	)
	(segment
		(start 118.5672 -149.352)
		(end 118.9228 -149.7076)
		(width 0.1651)
		(layer "B.Cu")
		(net "M_M_DQS_DN<4>")
	)
	(segment
		(start 118.94947 -147.478496)
		(end 118.94947 -148.385276)
		(width 0.1651)
		(layer "B.Cu")
		(net "M_M_DQS_DN<4>")
	)
	(segment
		(start 118.8212 -148.513546)
		(end 118.8212 -148.767546)
		(width 0.1651)
		(layer "B.Cu")
		(net "M_M_DQS_DN<4>")
	)
	(segment
		(start 118.9228 -149.7076)
		(end 119.112284 -149.7076)
		(width 0.1651)
		(layer "B.Cu")
		(net "M_M_DQS_DN<4>")
	)
	(segment
		(start 116.560854 -122.014234)
		(end 116.30533 -122.269758)
		(width 0.14224)
		(layer "In11.Cu")
		(net "M_M_DQS_DN<4>")
	)
	(segment
		(start 108.828586 -98.300286)
		(end 108.833412 -98.308922)
		(width 0.0889)
		(layer "In11.Cu")
		(net "M_M_DQS_DN<4>")
	)
	(segment
		(start 116.713762 -123.12015)
		(end 117.155722 -123.12015)
		(width 0.14224)
		(layer "In11.Cu")
		(net "M_M_DQS_DN<4>")
	)
	(segment
		(start 109.687106 -99.786186)
		(end 109.862874 -100.090732)
		(width 0.0889)
		(layer "In11.Cu")
		(net "M_M_DQS_DN<4>")
	)
	(segment
		(start 108.828586 -95.328486)
		(end 108.833412 -95.337122)
		(width 0.0889)
		(layer "In11.Cu")
		(net "M_M_DQS_DN<4>")
	)
	(segment
		(start 119.337328 -149.482556)
		(end 119.298212 -149.482556)
		(width 0.14224)
		(layer "In11.Cu")
		(net "M_M_DQS_DN<4>")
	)
	(segment
		(start 110.597188 -100.825046)
		(end 110.597188 -104.732328)
		(width 0.0889)
		(layer "In11.Cu")
		(net "M_M_DQS_DN<4>")
	)
	(segment
		(start 119.693182 -146.774154)
		(end 119.850662 -146.931634)
		(width 0.14224)
		(layer "In11.Cu")
		(net "M_M_DQS_DN<4>")
	)
	(segment
		(start 117.155722 -123.12015)
		(end 117.411246 -122.864626)
		(width 0.14224)
		(layer "In11.Cu")
		(net "M_M_DQS_DN<4>")
	)
	(segment
		(start 118.457218 -124.457206)
		(end 118.730522 -124.183902)
		(width 0.14224)
		(layer "In11.Cu")
		(net "M_M_DQS_DN<4>")
	)
	(segment
		(start 119.850662 -149.248876)
		(end 119.616982 -149.482556)
		(width 0.14224)
		(layer "In11.Cu")
		(net "M_M_DQS_DN<4>")
	)
	(segment
		(start 110.557818 -115.79225)
		(end 116.560854 -121.795286)
		(width 0.14224)
		(layer "In11.Cu")
		(net "M_M_DQS_DN<4>")
	)
	(segment
		(start 119.850662 -147.185634)
		(end 119.693182 -147.343114)
		(width 0.14224)
		(layer "In11.Cu")
		(net "M_M_DQS_DN<4>")
	)
	(segment
		(start 109.322616 -99.586288)
		(end 109.355382 -99.586288)
		(width 0.0889)
		(layer "In11.Cu")
		(net "M_M_DQS_DN<4>")
	)
	(segment
		(start 118.904258 -154.491944)
		(end 119.28856 -154.876246)
		(width 0.14224)
		(layer "In11.Cu")
		(net "M_M_DQS_DN<4>")
	)
	(segment
		(start 118.693692 -152.97658)
		(end 118.904258 -153.187146)
		(width 0.14224)
		(layer "In11.Cu")
		(net "M_M_DQS_DN<4>")
	)
	(segment
		(start 119.478298 -129.23393)
		(end 119.850662 -129.606294)
		(width 0.14224)
		(layer "In11.Cu")
		(net "M_M_DQS_DN<4>")
	)
	(segment
		(start 119.850662 -146.362674)
		(end 119.693182 -146.520154)
		(width 0.14224)
		(layer "In11.Cu")
		(net "M_M_DQS_DN<4>")
	)
	(segment
		(start 118.904258 -149.87651)
		(end 118.904258 -151.104854)
		(width 0.14224)
		(layer "In11.Cu")
		(net "M_M_DQS_DN<4>")
	)
	(segment
		(start 110.597188 -104.732328)
		(end 110.557818 -104.771698)
		(width 0.0889)
		(layer "In11.Cu")
		(net "M_M_DQS_DN<4>")
	)
	(segment
		(start 108.828586 -96.319086)
		(end 108.833412 -96.327722)
		(width 0.0889)
		(layer "In11.Cu")
		(net "M_M_DQS_DN<4>")
	)
	(segment
		(start 117.596412 -123.617228)
		(end 117.596412 -124.048774)
		(width 0.14224)
		(layer "In11.Cu")
		(net "M_M_DQS_DN<4>")
	)
	(segment
		(start 118.004844 -124.457206)
		(end 118.457218 -124.457206)
		(width 0.14224)
		(layer "In11.Cu")
		(net "M_M_DQS_DN<4>")
	)
	(segment
		(start 110.557818 -104.771698)
		(end 110.557818 -104.793796)
		(width 0.0889)
		(layer "In11.Cu")
		(net "M_M_DQS_DN<4>")
	)
	(segment
		(start 109.155738 -94.430088)
		(end 108.980732 -94.5642)
		(width 0.0889)
		(layer "In11.Cu")
		(net "M_M_DQS_DN<4>")
	)
	(segment
		(start 119.850662 -147.754594)
		(end 119.850662 -148.008594)
		(width 0.14224)
		(layer "In11.Cu")
		(net "M_M_DQS_DN<4>")
	)
	(segment
		(start 108.828586 -97.309686)
		(end 108.833412 -97.318322)
		(width 0.0889)
		(layer "In11.Cu")
		(net "M_M_DQS_DN<4>")
	)
	(segment
		(start 108.822236 -97.299018)
		(end 108.828586 -97.309686)
		(width 0.0889)
		(layer "In11.Cu")
		(net "M_M_DQS_DN<4>")
	)
	(segment
		(start 119.693182 -147.597114)
		(end 119.850662 -147.754594)
		(width 0.14224)
		(layer "In11.Cu")
		(net "M_M_DQS_DN<4>")
	)
	(segment
		(start 119.850662 -148.577554)
		(end 119.850662 -149.248876)
		(width 0.14224)
		(layer "In11.Cu")
		(net "M_M_DQS_DN<4>")
	)
	(segment
		(start 116.30533 -122.269758)
		(end 116.30533 -122.711718)
		(width 0.14224)
		(layer "In11.Cu")
		(net "M_M_DQS_DN<4>")
	)
	(segment
		(start 117.88013 -123.114562)
		(end 117.88013 -123.33351)
		(width 0.14224)
		(layer "In11.Cu")
		(net "M_M_DQS_DN<4>")
	)
	(segment
		(start 119.478298 -124.71273)
		(end 119.478298 -129.23393)
		(width 0.14224)
		(layer "In11.Cu")
		(net "M_M_DQS_DN<4>")
	)
	(segment
		(start 117.596412 -124.048774)
		(end 118.004844 -124.457206)
		(width 0.14224)
		(layer "In11.Cu")
		(net "M_M_DQS_DN<4>")
	)
	(segment
		(start 119.850662 -129.606294)
		(end 119.850662 -146.362674)
		(width 0.14224)
		(layer "In11.Cu")
		(net "M_M_DQS_DN<4>")
	)
	(segment
		(start 119.850662 -148.008594)
		(end 119.693182 -148.166074)
		(width 0.14224)
		(layer "In11.Cu")
		(net "M_M_DQS_DN<4>")
	)
	(segment
		(start 117.88013 -123.33351)
		(end 117.596412 -123.617228)
		(width 0.14224)
		(layer "In11.Cu")
		(net "M_M_DQS_DN<4>")
	)
	(segment
		(start 117.630194 -122.864626)
		(end 117.88013 -123.114562)
		(width 0.14224)
		(layer "In11.Cu")
		(net "M_M_DQS_DN<4>")
	)
	(segment
		(start 116.30533 -122.711718)
		(end 116.713762 -123.12015)
		(width 0.14224)
		(layer "In11.Cu")
		(net "M_M_DQS_DN<4>")
	)
	(segment
		(start 118.904258 -151.104854)
		(end 118.693692 -151.31542)
		(width 0.14224)
		(layer "In11.Cu")
		(net "M_M_DQS_DN<4>")
	)
	(segment
		(start 119.693182 -148.166074)
		(end 119.693182 -148.420074)
		(width 0.14224)
		(layer "In11.Cu")
		(net "M_M_DQS_DN<4>")
	)
	(segment
		(start 118.730522 -124.183902)
		(end 118.94947 -124.183902)
		(width 0.14224)
		(layer "In11.Cu")
		(net "M_M_DQS_DN<4>")
	)
	(segment
		(start 118.94947 -124.183902)
		(end 119.478298 -124.71273)
		(width 0.14224)
		(layer "In11.Cu")
		(net "M_M_DQS_DN<4>")
	)
	(segment
		(start 117.411246 -122.864626)
		(end 117.630194 -122.864626)
		(width 0.14224)
		(layer "In11.Cu")
		(net "M_M_DQS_DN<4>")
	)
	(segment
		(start 119.298212 -149.482556)
		(end 118.904258 -149.87651)
		(width 0.14224)
		(layer "In11.Cu")
		(net "M_M_DQS_DN<4>")
	)
	(segment
		(start 119.693182 -147.343114)
		(end 119.693182 -147.597114)
		(width 0.14224)
		(layer "In11.Cu")
		(net "M_M_DQS_DN<4>")
	)
	(segment
		(start 116.560854 -121.795286)
		(end 116.560854 -122.014234)
		(width 0.14224)
		(layer "In11.Cu")
		(net "M_M_DQS_DN<4>")
	)
	(segment
		(start 119.850662 -146.931634)
		(end 119.850662 -147.185634)
		(width 0.14224)
		(layer "In11.Cu")
		(net "M_M_DQS_DN<4>")
	)
	(segment
		(start 118.904258 -153.187146)
		(end 118.904258 -154.491944)
		(width 0.14224)
		(layer "In11.Cu")
		(net "M_M_DQS_DN<4>")
	)
	(segment
		(start 119.693182 -148.420074)
		(end 119.850662 -148.577554)
		(width 0.14224)
		(layer "In11.Cu")
		(net "M_M_DQS_DN<4>")
	)
	(segment
		(start 119.28856 -154.876246)
		(end 119.337328 -154.876246)
		(width 0.14224)
		(layer "In11.Cu")
		(net "M_M_DQS_DN<4>")
	)
	(segment
		(start 110.557818 -104.793796)
		(end 110.557818 -115.79225)
		(width 0.14224)
		(layer "In11.Cu")
		(net "M_M_DQS_DN<4>")
	)
	(segment
		(start 119.693182 -146.520154)
		(end 119.693182 -146.774154)
		(width 0.14224)
		(layer "In11.Cu")
		(net "M_M_DQS_DN<4>")
	)
	(segment
		(start 108.822236 -96.308418)
		(end 108.828586 -96.319086)
		(width 0.0889)
		(layer "In11.Cu")
		(net "M_M_DQS_DN<4>")
	)
	(segment
		(start 108.822236 -98.289618)
		(end 108.828586 -98.300286)
		(width 0.0889)
		(layer "In11.Cu")
		(net "M_M_DQS_DN<4>")
	)
	(segment
		(start 119.616982 -149.482556)
		(end 119.337328 -149.482556)
		(width 0.14224)
		(layer "In11.Cu")
		(net "M_M_DQS_DN<4>")
	)
	(segment
		(start 118.693692 -151.31542)
		(end 118.693692 -152.97658)
		(width 0.14224)
		(layer "In11.Cu")
		(net "M_M_DQS_DN<4>")
	)
	(segment
		(start 109.862874 -100.090732)
		(end 110.597188 -100.825046)
		(width 0.0889)
		(layer "In11.Cu")
		(net "M_M_DQS_DN<4>")
	)
	(arc
		(start 108.833412 -96.327722)
		(mid 108.882167 -96.524074)
		(end 108.828586 -96.719136)
		(width 0.0889)
		(layer "In11.Cu")
		(net "M_M_DQS_DN<4>")
	)
	(arc
		(start 108.828586 -98.700336)
		(mid 108.824257 -99.283508)
		(end 109.322616 -99.586288)
		(width 0.0889)
		(layer "In11.Cu")
		(net "M_M_DQS_DN<4>")
	)
	(arc
		(start 109.355382 -99.586288)
		(mid 109.547024 -99.643454)
		(end 109.687106 -99.786186)
		(width 0.0889)
		(layer "In11.Cu")
		(net "M_M_DQS_DN<4>")
	)
	(arc
		(start 108.828586 -97.709736)
		(mid 108.749364 -97.998854)
		(end 108.822236 -98.289618)
		(width 0.0889)
		(layer "In11.Cu")
		(net "M_M_DQS_DN<4>")
	)
	(arc
		(start 108.828586 -95.728536)
		(mid 108.749364 -96.017654)
		(end 108.822236 -96.308418)
		(width 0.0889)
		(layer "In11.Cu")
		(net "M_M_DQS_DN<4>")
	)
	(arc
		(start 108.833412 -95.337122)
		(mid 108.882167 -95.533474)
		(end 108.828586 -95.728536)
		(width 0.0889)
		(layer "In11.Cu")
		(net "M_M_DQS_DN<4>")
	)
	(arc
		(start 108.833412 -98.308922)
		(mid 108.882167 -98.505274)
		(end 108.828586 -98.700336)
		(width 0.0889)
		(layer "In11.Cu")
		(net "M_M_DQS_DN<4>")
	)
	(arc
		(start 108.833412 -97.318322)
		(mid 108.882167 -97.514674)
		(end 108.828586 -97.709736)
		(width 0.0889)
		(layer "In11.Cu")
		(net "M_M_DQS_DN<4>")
	)
	(arc
		(start 108.980732 -94.5642)
		(mid 108.760828 -94.91771)
		(end 108.828586 -95.328486)
		(width 0.0889)
		(layer "In11.Cu")
		(net "M_M_DQS_DN<4>")
	)
	(arc
		(start 108.828586 -96.719136)
		(mid 108.749364 -97.008254)
		(end 108.822236 -97.299018)
		(width 0.0889)
		(layer "In11.Cu")
		(net "M_M_DQS_DN<4>")
	)
	(arc
		(start 109.340396 -94.042738)
		(mid 109.291871 -94.257296)
		(end 109.155738 -94.430088)
		(width 0.0889)
		(layer "In11.Cu")
		(net "M_M_DQS_DN<4>")
	)
	(segment
		(start 85.777832 -87.784686)
		(end 85.206332 -87.784686)
		(width 0.1651)
		(layer "F.Cu")
		(net "M_M_DQS_DN<3>")
	)
	(segment
		(start 63.871856 -154.6606)
		(end 64.087502 -154.876246)
		(width 0.1651)
		(layer "F.Cu")
		(net "M_M_DQS_DN<3>")
	)
	(segment
		(start 63.317374 -154.991054)
		(end 63.647828 -154.6606)
		(width 0.1651)
		(layer "F.Cu")
		(net "M_M_DQS_DN<3>")
	)
	(segment
		(start 63.69939 -155.80487)
		(end 63.317374 -155.422854)
		(width 0.1651)
		(layer "F.Cu")
		(net "M_M_DQS_DN<3>")
	)
	(segment
		(start 63.647828 -154.6606)
		(end 63.871856 -154.6606)
		(width 0.1651)
		(layer "F.Cu")
		(net "M_M_DQS_DN<3>")
	)
	(segment
		(start 63.69939 -156.87294)
		(end 63.69939 -155.80487)
		(width 0.1651)
		(layer "F.Cu")
		(net "M_M_DQS_DN<3>")
	)
	(segment
		(start 63.317374 -155.422854)
		(end 63.317374 -154.991054)
		(width 0.1651)
		(layer "F.Cu")
		(net "M_M_DQS_DN<3>")
	)
	(via
		(at 64.087502 -149.482556)
		(size 0.508)
		(drill 0.254)
		(layers "F.Cu" "B.Cu")
		(net "M_M_DQS_DN<3>")
	)
	(via
		(at 85.206332 -87.784686)
		(size 0.508)
		(drill 0.254)
		(layers "F.Cu" "B.Cu")
		(net "M_M_DQS_DN<3>")
	)
	(via
		(at 64.087502 -154.876246)
		(size 0.508)
		(drill 0.254)
		(layers "F.Cu" "B.Cu")
		(net "M_M_DQS_DN<3>")
	)
	(segment
		(start 63.672974 -149.7076)
		(end 63.862458 -149.7076)
		(width 0.1651)
		(layer "B.Cu")
		(net "M_M_DQS_DN<3>")
	)
	(segment
		(start 63.69939 -147.478496)
		(end 63.69939 -148.38553)
		(width 0.1651)
		(layer "B.Cu")
		(net "M_M_DQS_DN<3>")
	)
	(segment
		(start 63.317374 -149.021546)
		(end 63.317374 -149.352)
		(width 0.1651)
		(layer "B.Cu")
		(net "M_M_DQS_DN<3>")
	)
	(segment
		(start 63.317374 -149.352)
		(end 63.672974 -149.7076)
		(width 0.1651)
		(layer "B.Cu")
		(net "M_M_DQS_DN<3>")
	)
	(segment
		(start 63.862458 -149.7076)
		(end 64.087502 -149.482556)
		(width 0.1651)
		(layer "B.Cu")
		(net "M_M_DQS_DN<3>")
	)
	(segment
		(start 63.571374 -148.767546)
		(end 63.317374 -149.021546)
		(width 0.1651)
		(layer "B.Cu")
		(net "M_M_DQS_DN<3>")
	)
	(segment
		(start 63.69939 -148.38553)
		(end 63.571374 -148.513546)
		(width 0.1651)
		(layer "B.Cu")
		(net "M_M_DQS_DN<3>")
	)
	(segment
		(start 63.571374 -148.513546)
		(end 63.571374 -148.767546)
		(width 0.1651)
		(layer "B.Cu")
		(net "M_M_DQS_DN<3>")
	)
	(segment
		(start 64.600582 -142.296642)
		(end 64.443102 -142.454122)
		(width 0.14224)
		(layer "In11.Cu")
		(net "M_M_DQS_DN<3>")
	)
	(segment
		(start 73.561702 -119.45874)
		(end 72.941434 -119.45874)
		(width 0.14224)
		(layer "In11.Cu")
		(net "M_M_DQS_DN<3>")
	)
	(segment
		(start 81.16062 -103.611172)
		(end 81.12125 -103.650542)
		(width 0.0889)
		(layer "In11.Cu")
		(net "M_M_DQS_DN<3>")
	)
	(segment
		(start 85.553042 -90.556588)
		(end 85.557868 -90.565224)
		(width 0.0889)
		(layer "In11.Cu")
		(net "M_M_DQS_DN<3>")
	)
	(segment
		(start 64.443102 -148.370544)
		(end 64.600582 -148.528024)
		(width 0.14224)
		(layer "In11.Cu")
		(net "M_M_DQS_DN<3>")
	)
	(segment
		(start 83.616292 -98.17862)
		(end 80.873092 -100.92182)
		(width 0.0889)
		(layer "In11.Cu")
		(net "M_M_DQS_DN<3>")
	)
	(segment
		(start 64.443102 -147.547584)
		(end 64.600582 -147.705064)
		(width 0.14224)
		(layer "In11.Cu")
		(net "M_M_DQS_DN<3>")
	)
	(segment
		(start 80.873092 -102.451408)
		(end 81.16062 -102.738936)
		(width 0.0889)
		(layer "In11.Cu")
		(net "M_M_DQS_DN<3>")
	)
	(segment
		(start 71.639176 -121.23928)
		(end 67.386454 -121.23928)
		(width 0.14224)
		(layer "In11.Cu")
		(net "M_M_DQS_DN<3>")
	)
	(segment
		(start 64.600582 -147.959064)
		(end 64.443102 -148.116544)
		(width 0.14224)
		(layer "In11.Cu")
		(net "M_M_DQS_DN<3>")
	)
	(segment
		(start 84.688172 -94.01302)
		(end 84.694522 -94.023688)
		(width 0.0889)
		(layer "In11.Cu")
		(net "M_M_DQS_DN<3>")
	)
	(segment
		(start 64.443102 -137.897108)
		(end 64.600582 -138.054588)
		(width 0.14224)
		(layer "In11.Cu")
		(net "M_M_DQS_DN<3>")
	)
	(segment
		(start 64.600582 -134.109206)
		(end 64.600582 -136.662668)
		(width 0.14224)
		(layer "In11.Cu")
		(net "M_M_DQS_DN<3>")
	)
	(segment
		(start 74.724514 -117.699282)
		(end 74.187558 -117.699282)
		(width 0.14224)
		(layer "In11.Cu")
		(net "M_M_DQS_DN<3>")
	)
	(segment
		(start 85.554566 -88.578436)
		(end 85.557868 -88.584024)
		(width 0.0889)
		(layer "In11.Cu")
		(net "M_M_DQS_DN<3>")
	)
	(segment
		(start 85.546692 -92.52712)
		(end 85.553042 -92.537788)
		(width 0.0889)
		(layer "In11.Cu")
		(net "M_M_DQS_DN<3>")
	)
	(segment
		(start 64.600582 -136.662668)
		(end 64.443102 -136.820148)
		(width 0.14224)
		(layer "In11.Cu")
		(net "M_M_DQS_DN<3>")
	)
	(segment
		(start 64.600582 -146.313144)
		(end 64.443102 -146.470624)
		(width 0.14224)
		(layer "In11.Cu")
		(net "M_M_DQS_DN<3>")
	)
	(segment
		(start 74.866754 -117.841522)
		(end 74.724514 -117.699282)
		(width 0.14224)
		(layer "In11.Cu")
		(net "M_M_DQS_DN<3>")
	)
	(segment
		(start 64.367156 -149.482556)
		(end 64.087502 -149.482556)
		(width 0.14224)
		(layer "In11.Cu")
		(net "M_M_DQS_DN<3>")
	)
	(segment
		(start 85.221318 -93.137736)
		(end 85.193378 -93.137736)
		(width 0.0889)
		(layer "In11.Cu")
		(net "M_M_DQS_DN<3>")
	)
	(segment
		(start 73.725278 -118.698518)
		(end 73.867518 -118.840758)
		(width 0.14224)
		(layer "In11.Cu")
		(net "M_M_DQS_DN<3>")
	)
	(segment
		(start 64.443102 -143.531082)
		(end 64.600582 -143.688562)
		(width 0.14224)
		(layer "In11.Cu")
		(net "M_M_DQS_DN<3>")
	)
	(segment
		(start 64.600582 -137.485628)
		(end 64.443102 -137.643108)
		(width 0.14224)
		(layer "In11.Cu")
		(net "M_M_DQS_DN<3>")
	)
	(segment
		(start 63.654432 -151.1046)
		(end 63.443612 -151.31542)
		(width 0.14224)
		(layer "In11.Cu")
		(net "M_M_DQS_DN<3>")
	)
	(segment
		(start 64.600582 -143.119602)
		(end 64.443102 -143.277082)
		(width 0.14224)
		(layer "In11.Cu")
		(net "M_M_DQS_DN<3>")
	)
	(segment
		(start 64.600582 -142.865602)
		(end 64.600582 -143.119602)
		(width 0.14224)
		(layer "In11.Cu")
		(net "M_M_DQS_DN<3>")
	)
	(segment
		(start 64.443102 -136.820148)
		(end 64.443102 -137.074148)
		(width 0.14224)
		(layer "In11.Cu")
		(net "M_M_DQS_DN<3>")
	)
	(segment
		(start 63.654432 -153.1874)
		(end 63.654432 -154.443176)
		(width 0.14224)
		(layer "In11.Cu")
		(net "M_M_DQS_DN<3>")
	)
	(segment
		(start 77.269848 -114.616992)
		(end 75.342496 -116.544344)
		(width 0.14224)
		(layer "In11.Cu")
		(net "M_M_DQS_DN<3>")
	)
	(segment
		(start 64.443102 -146.470624)
		(end 64.443102 -146.724624)
		(width 0.14224)
		(layer "In11.Cu")
		(net "M_M_DQS_DN<3>")
	)
	(segment
		(start 64.600582 -138.054588)
		(end 64.600582 -138.308588)
		(width 0.14224)
		(layer "In11.Cu")
		(net "M_M_DQS_DN<3>")
	)
	(segment
		(start 74.187558 -117.699282)
		(end 73.725278 -118.161562)
		(width 0.14224)
		(layer "In11.Cu")
		(net "M_M_DQS_DN<3>")
	)
	(segment
		(start 75.178158 -117.841522)
		(end 74.866754 -117.841522)
		(width 0.14224)
		(layer "In11.Cu")
		(net "M_M_DQS_DN<3>")
	)
	(segment
		(start 64.600582 -132.717286)
		(end 64.443102 -132.874766)
		(width 0.14224)
		(layer "In11.Cu")
		(net "M_M_DQS_DN<3>")
	)
	(segment
		(start 64.600582 -133.286246)
		(end 64.600582 -133.540246)
		(width 0.14224)
		(layer "In11.Cu")
		(net "M_M_DQS_DN<3>")
	)
	(segment
		(start 64.600582 -129.294636)
		(end 64.600582 -131.951222)
		(width 0.14224)
		(layer "In11.Cu")
		(net "M_M_DQS_DN<3>")
	)
	(segment
		(start 64.443102 -138.720068)
		(end 64.600582 -138.877548)
		(width 0.14224)
		(layer "In11.Cu")
		(net "M_M_DQS_DN<3>")
	)
	(segment
		(start 64.443102 -133.951726)
		(end 64.600582 -134.109206)
		(width 0.14224)
		(layer "In11.Cu")
		(net "M_M_DQS_DN<3>")
	)
	(segment
		(start 64.600582 -146.882104)
		(end 64.600582 -147.136104)
		(width 0.14224)
		(layer "In11.Cu")
		(net "M_M_DQS_DN<3>")
	)
	(segment
		(start 75.484736 -117.22354)
		(end 75.484736 -117.534944)
		(width 0.14224)
		(layer "In11.Cu")
		(net "M_M_DQS_DN<3>")
	)
	(segment
		(start 64.600582 -147.705064)
		(end 64.600582 -147.959064)
		(width 0.14224)
		(layer "In11.Cu")
		(net "M_M_DQS_DN<3>")
	)
	(segment
		(start 64.600582 -141.473682)
		(end 64.443102 -141.631162)
		(width 0.14224)
		(layer "In11.Cu")
		(net "M_M_DQS_DN<3>")
	)
	(segment
		(start 64.443102 -138.466068)
		(end 64.443102 -138.720068)
		(width 0.14224)
		(layer "In11.Cu")
		(net "M_M_DQS_DN<3>")
	)
	(segment
		(start 64.443102 -148.116544)
		(end 64.443102 -148.370544)
		(width 0.14224)
		(layer "In11.Cu")
		(net "M_M_DQS_DN<3>")
	)
	(segment
		(start 72.10806 -120.770396)
		(end 71.639176 -121.23928)
		(width 0.14224)
		(layer "In11.Cu")
		(net "M_M_DQS_DN<3>")
	)
	(segment
		(start 64.443102 -143.277082)
		(end 64.443102 -143.531082)
		(width 0.14224)
		(layer "In11.Cu")
		(net "M_M_DQS_DN<3>")
	)
	(segment
		(start 64.087502 -149.482556)
		(end 64.01435 -149.482556)
		(width 0.14224)
		(layer "In11.Cu")
		(net "M_M_DQS_DN<3>")
	)
	(segment
		(start 64.443102 -146.724624)
		(end 64.600582 -146.882104)
		(width 0.14224)
		(layer "In11.Cu")
		(net "M_M_DQS_DN<3>")
	)
	(segment
		(start 64.600582 -149.24913)
		(end 64.367156 -149.482556)
		(width 0.14224)
		(layer "In11.Cu")
		(net "M_M_DQS_DN<3>")
	)
	(segment
		(start 64.443102 -142.708122)
		(end 64.600582 -142.865602)
		(width 0.14224)
		(layer "In11.Cu")
		(net "M_M_DQS_DN<3>")
	)
	(segment
		(start 64.443102 -137.643108)
		(end 64.443102 -137.897108)
		(width 0.14224)
		(layer "In11.Cu")
		(net "M_M_DQS_DN<3>")
	)
	(segment
		(start 64.600582 -132.456174)
		(end 64.600582 -132.717286)
		(width 0.14224)
		(layer "In11.Cu")
		(net "M_M_DQS_DN<3>")
	)
	(segment
		(start 64.443102 -137.074148)
		(end 64.600582 -137.231628)
		(width 0.14224)
		(layer "In11.Cu")
		(net "M_M_DQS_DN<3>")
	)
	(segment
		(start 85.553042 -89.565988)
		(end 85.557868 -89.574624)
		(width 0.0889)
		(layer "In11.Cu")
		(net "M_M_DQS_DN<3>")
	)
	(segment
		(start 63.654432 -149.842474)
		(end 63.654432 -151.1046)
		(width 0.14224)
		(layer "In11.Cu")
		(net "M_M_DQS_DN<3>")
	)
	(segment
		(start 84.699348 -95.405702)
		(end 84.694522 -95.414338)
		(width 0.0889)
		(layer "In11.Cu")
		(net "M_M_DQS_DN<3>")
	)
	(segment
		(start 64.443102 -133.128766)
		(end 64.600582 -133.286246)
		(width 0.14224)
		(layer "In11.Cu")
		(net "M_M_DQS_DN<3>")
	)
	(segment
		(start 64.600582 -142.042642)
		(end 64.600582 -142.296642)
		(width 0.14224)
		(layer "In11.Cu")
		(net "M_M_DQS_DN<3>")
	)
	(segment
		(start 85.554058 -88.577674)
		(end 85.554566 -88.578436)
		(width 0.0889)
		(layer "In11.Cu")
		(net "M_M_DQS_DN<3>")
	)
	(segment
		(start 81.16062 -102.738936)
		(end 81.16062 -103.611172)
		(width 0.0889)
		(layer "In11.Cu")
		(net "M_M_DQS_DN<3>")
	)
	(segment
		(start 64.443102 -132.874766)
		(end 64.443102 -133.128766)
		(width 0.14224)
		(layer "In11.Cu")
		(net "M_M_DQS_DN<3>")
	)
	(segment
		(start 84.631276 -96.514666)
		(end 83.616292 -97.52965)
		(width 0.0889)
		(layer "In11.Cu")
		(net "M_M_DQS_DN<3>")
	)
	(segment
		(start 63.443612 -151.31542)
		(end 63.443612 -152.97658)
		(width 0.14224)
		(layer "In11.Cu")
		(net "M_M_DQS_DN<3>")
	)
	(segment
		(start 77.270356 -109.1565)
		(end 77.269848 -109.1565)
		(width 0.14224)
		(layer "In11.Cu")
		(net "M_M_DQS_DN<3>")
	)
	(segment
		(start 81.12125 -103.67264)
		(end 81.12125 -105.305606)
		(width 0.14224)
		(layer "In11.Cu")
		(net "M_M_DQS_DN<3>")
	)
	(segment
		(start 64.443102 -147.293584)
		(end 64.443102 -147.547584)
		(width 0.14224)
		(layer "In11.Cu")
		(net "M_M_DQS_DN<3>")
	)
	(segment
		(start 64.600582 -133.540246)
		(end 64.443102 -133.697726)
		(width 0.14224)
		(layer "In11.Cu")
		(net "M_M_DQS_DN<3>")
	)
	(segment
		(start 73.867518 -119.152924)
		(end 73.561702 -119.45874)
		(width 0.14224)
		(layer "In11.Cu")
		(net "M_M_DQS_DN<3>")
	)
	(segment
		(start 64.600582 -138.877548)
		(end 64.600582 -141.473682)
		(width 0.14224)
		(layer "In11.Cu")
		(net "M_M_DQS_DN<3>")
	)
	(segment
		(start 85.553042 -88.575896)
		(end 85.554058 -88.577674)
		(width 0.0889)
		(layer "In11.Cu")
		(net "M_M_DQS_DN<3>")
	)
	(segment
		(start 64.443102 -133.697726)
		(end 64.443102 -133.951726)
		(width 0.14224)
		(layer "In11.Cu")
		(net "M_M_DQS_DN<3>")
	)
	(segment
		(start 63.443612 -152.97658)
		(end 63.654432 -153.1874)
		(width 0.14224)
		(layer "In11.Cu")
		(net "M_M_DQS_DN<3>")
	)
	(segment
		(start 84.694522 -95.414338)
		(end 84.688172 -95.425006)
		(width 0.0889)
		(layer "In11.Cu")
		(net "M_M_DQS_DN<3>")
	)
	(segment
		(start 85.553042 -91.547188)
		(end 85.557868 -91.555824)
		(width 0.0889)
		(layer "In11.Cu")
		(net "M_M_DQS_DN<3>")
	)
	(segment
		(start 64.475106 -132.076698)
		(end 64.475106 -132.330698)
		(width 0.14224)
		(layer "In11.Cu")
		(net "M_M_DQS_DN<3>")
	)
	(segment
		(start 85.546692 -91.53652)
		(end 85.553042 -91.547188)
		(width 0.0889)
		(layer "In11.Cu")
		(net "M_M_DQS_DN<3>")
	)
	(segment
		(start 77.269848 -109.1565)
		(end 77.269848 -114.616992)
		(width 0.14224)
		(layer "In11.Cu")
		(net "M_M_DQS_DN<3>")
	)
	(segment
		(start 85.546692 -90.54592)
		(end 85.553042 -90.556588)
		(width 0.0889)
		(layer "In11.Cu")
		(net "M_M_DQS_DN<3>")
	)
	(segment
		(start 83.616292 -97.52965)
		(end 83.616292 -98.17862)
		(width 0.0889)
		(layer "In11.Cu")
		(net "M_M_DQS_DN<3>")
	)
	(segment
		(start 64.496188 -129.190242)
		(end 64.600582 -129.294636)
		(width 0.14224)
		(layer "In11.Cu")
		(net "M_M_DQS_DN<3>")
	)
	(segment
		(start 64.496188 -128.936242)
		(end 64.496188 -129.190242)
		(width 0.14224)
		(layer "In11.Cu")
		(net "M_M_DQS_DN<3>")
	)
	(segment
		(start 75.342496 -116.544344)
		(end 75.342496 -117.0813)
		(width 0.14224)
		(layer "In11.Cu")
		(net "M_M_DQS_DN<3>")
	)
	(segment
		(start 80.873092 -100.92182)
		(end 80.873092 -102.451408)
		(width 0.0889)
		(layer "In11.Cu")
		(net "M_M_DQS_DN<3>")
	)
	(segment
		(start 64.600582 -128.831848)
		(end 64.496188 -128.936242)
		(width 0.14224)
		(layer "In11.Cu")
		(net "M_M_DQS_DN<3>")
	)
	(segment
		(start 63.654432 -154.443176)
		(end 64.087502 -154.876246)
		(width 0.14224)
		(layer "In11.Cu")
		(net "M_M_DQS_DN<3>")
	)
	(segment
		(start 72.941434 -119.45874)
		(end 72.10806 -120.292114)
		(width 0.14224)
		(layer "In11.Cu")
		(net "M_M_DQS_DN<3>")
	)
	(segment
		(start 64.600582 -147.136104)
		(end 64.443102 -147.293584)
		(width 0.14224)
		(layer "In11.Cu")
		(net "M_M_DQS_DN<3>")
	)
	(segment
		(start 64.600582 -124.025152)
		(end 64.600582 -128.831848)
		(width 0.14224)
		(layer "In11.Cu")
		(net "M_M_DQS_DN<3>")
	)
	(segment
		(start 64.600582 -137.231628)
		(end 64.600582 -137.485628)
		(width 0.14224)
		(layer "In11.Cu")
		(net "M_M_DQS_DN<3>")
	)
	(segment
		(start 81.12125 -103.650542)
		(end 81.12125 -103.67264)
		(width 0.0889)
		(layer "In11.Cu")
		(net "M_M_DQS_DN<3>")
	)
	(segment
		(start 84.699348 -96.396302)
		(end 84.631276 -96.514666)
		(width 0.0889)
		(layer "In11.Cu")
		(net "M_M_DQS_DN<3>")
	)
	(segment
		(start 81.12125 -105.305606)
		(end 77.270356 -109.1565)
		(width 0.14224)
		(layer "In11.Cu")
		(net "M_M_DQS_DN<3>")
	)
	(segment
		(start 75.484736 -117.534944)
		(end 75.178158 -117.841522)
		(width 0.14224)
		(layer "In11.Cu")
		(net "M_M_DQS_DN<3>")
	)
	(segment
		(start 64.600582 -148.528024)
		(end 64.600582 -149.24913)
		(width 0.14224)
		(layer "In11.Cu")
		(net "M_M_DQS_DN<3>")
	)
	(segment
		(start 72.10806 -120.292114)
		(end 72.10806 -120.770396)
		(width 0.14224)
		(layer "In11.Cu")
		(net "M_M_DQS_DN<3>")
	)
	(segment
		(start 64.600582 -131.951222)
		(end 64.475106 -132.076698)
		(width 0.14224)
		(layer "In11.Cu")
		(net "M_M_DQS_DN<3>")
	)
	(segment
		(start 64.600582 -138.308588)
		(end 64.443102 -138.466068)
		(width 0.14224)
		(layer "In11.Cu")
		(net "M_M_DQS_DN<3>")
	)
	(segment
		(start 85.546692 -89.55532)
		(end 85.553042 -89.565988)
		(width 0.0889)
		(layer "In11.Cu")
		(net "M_M_DQS_DN<3>")
	)
	(segment
		(start 75.342496 -117.0813)
		(end 75.484736 -117.22354)
		(width 0.14224)
		(layer "In11.Cu")
		(net "M_M_DQS_DN<3>")
	)
	(segment
		(start 73.867518 -118.840758)
		(end 73.867518 -119.152924)
		(width 0.14224)
		(layer "In11.Cu")
		(net "M_M_DQS_DN<3>")
	)
	(segment
		(start 64.443102 -141.885162)
		(end 64.600582 -142.042642)
		(width 0.14224)
		(layer "In11.Cu")
		(net "M_M_DQS_DN<3>")
	)
	(segment
		(start 64.443102 -141.631162)
		(end 64.443102 -141.885162)
		(width 0.14224)
		(layer "In11.Cu")
		(net "M_M_DQS_DN<3>")
	)
	(segment
		(start 73.725278 -118.161562)
		(end 73.725278 -118.698518)
		(width 0.14224)
		(layer "In11.Cu")
		(net "M_M_DQS_DN<3>")
	)
	(segment
		(start 64.600582 -143.688562)
		(end 64.600582 -146.313144)
		(width 0.14224)
		(layer "In11.Cu")
		(net "M_M_DQS_DN<3>")
	)
	(segment
		(start 64.475106 -132.330698)
		(end 64.600582 -132.456174)
		(width 0.14224)
		(layer "In11.Cu")
		(net "M_M_DQS_DN<3>")
	)
	(segment
		(start 64.01435 -149.482556)
		(end 63.654432 -149.842474)
		(width 0.14224)
		(layer "In11.Cu")
		(net "M_M_DQS_DN<3>")
	)
	(segment
		(start 67.386454 -121.23928)
		(end 64.600582 -124.025152)
		(width 0.14224)
		(layer "In11.Cu")
		(net "M_M_DQS_DN<3>")
	)
	(segment
		(start 85.553042 -92.537788)
		(end 85.557868 -92.546424)
		(width 0.0889)
		(layer "In11.Cu")
		(net "M_M_DQS_DN<3>")
	)
	(segment
		(start 64.443102 -142.454122)
		(end 64.443102 -142.708122)
		(width 0.14224)
		(layer "In11.Cu")
		(net "M_M_DQS_DN<3>")
	)
	(arc
		(start 84.688172 -95.425006)
		(mid 84.615374 -95.715769)
		(end 84.694522 -96.004888)
		(width 0.0889)
		(layer "In11.Cu")
		(net "M_M_DQS_DN<3>")
	)
	(arc
		(start 85.193378 -93.137736)
		(mid 84.694497 -93.433173)
		(end 84.688172 -94.01302)
		(width 0.0889)
		(layer "In11.Cu")
		(net "M_M_DQS_DN<3>")
	)
	(arc
		(start 85.557868 -92.546424)
		(mid 85.554121 -92.93568)
		(end 85.221318 -93.137736)
		(width 0.0889)
		(layer "In11.Cu")
		(net "M_M_DQS_DN<3>")
	)
	(arc
		(start 85.553042 -90.956638)
		(mid 85.47382 -91.245756)
		(end 85.546692 -91.53652)
		(width 0.0889)
		(layer "In11.Cu")
		(net "M_M_DQS_DN<3>")
	)
	(arc
		(start 85.206332 -87.784686)
		(mid 85.357911 -88.189833)
		(end 85.553042 -88.575896)
		(width 0.0889)
		(layer "In11.Cu")
		(net "M_M_DQS_DN<3>")
	)
	(arc
		(start 84.694522 -94.423484)
		(mid 84.615391 -94.718886)
		(end 84.694522 -95.014288)
		(width 0.0889)
		(layer "In11.Cu")
		(net "M_M_DQS_DN<3>")
	)
	(arc
		(start 84.694522 -95.014288)
		(mid 84.747992 -95.209351)
		(end 84.699348 -95.405702)
		(width 0.0889)
		(layer "In11.Cu")
		(net "M_M_DQS_DN<3>")
	)
	(arc
		(start 85.557868 -91.555824)
		(mid 85.606623 -91.752176)
		(end 85.553042 -91.947238)
		(width 0.0889)
		(layer "In11.Cu")
		(net "M_M_DQS_DN<3>")
	)
	(arc
		(start 85.557868 -88.584024)
		(mid 85.606623 -88.780376)
		(end 85.553042 -88.975438)
		(width 0.0889)
		(layer "In11.Cu")
		(net "M_M_DQS_DN<3>")
	)
	(arc
		(start 84.694522 -96.004888)
		(mid 84.747992 -96.199951)
		(end 84.699348 -96.396302)
		(width 0.0889)
		(layer "In11.Cu")
		(net "M_M_DQS_DN<3>")
	)
	(arc
		(start 84.694522 -94.023688)
		(mid 84.748021 -94.223586)
		(end 84.694522 -94.423484)
		(width 0.0889)
		(layer "In11.Cu")
		(net "M_M_DQS_DN<3>")
	)
	(arc
		(start 85.557868 -89.574624)
		(mid 85.606623 -89.770976)
		(end 85.553042 -89.966038)
		(width 0.0889)
		(layer "In11.Cu")
		(net "M_M_DQS_DN<3>")
	)
	(arc
		(start 85.553042 -89.966038)
		(mid 85.47382 -90.255156)
		(end 85.546692 -90.54592)
		(width 0.0889)
		(layer "In11.Cu")
		(net "M_M_DQS_DN<3>")
	)
	(arc
		(start 85.553042 -88.975438)
		(mid 85.47382 -89.264556)
		(end 85.546692 -89.55532)
		(width 0.0889)
		(layer "In11.Cu")
		(net "M_M_DQS_DN<3>")
	)
	(arc
		(start 85.557868 -90.565224)
		(mid 85.606623 -90.761576)
		(end 85.553042 -90.956638)
		(width 0.0889)
		(layer "In11.Cu")
		(net "M_M_DQS_DN<3>")
	)
	(arc
		(start 85.553042 -91.947238)
		(mid 85.47382 -92.236356)
		(end 85.546692 -92.52712)
		(width 0.0889)
		(layer "In11.Cu")
		(net "M_M_DQS_DN<3>")
	)
	(segment
		(start 54.521862 -154.6606)
		(end 54.737508 -154.876246)
		(width 0.1651)
		(layer "F.Cu")
		(net "M_M_DQS_DN<2>")
	)
	(segment
		(start 54.297834 -154.6606)
		(end 54.521862 -154.6606)
		(width 0.1651)
		(layer "F.Cu")
		(net "M_M_DQS_DN<2>")
	)
	(segment
		(start 54.349396 -156.87294)
		(end 54.349396 -155.80487)
		(width 0.1651)
		(layer "F.Cu")
		(net "M_M_DQS_DN<2>")
	)
	(segment
		(start 54.349396 -155.80487)
		(end 53.96738 -155.422854)
		(width 0.1651)
		(layer "F.Cu")
		(net "M_M_DQS_DN<2>")
	)
	(segment
		(start 53.96738 -154.991054)
		(end 54.297834 -154.6606)
		(width 0.1651)
		(layer "F.Cu")
		(net "M_M_DQS_DN<2>")
	)
	(segment
		(start 53.96738 -155.422854)
		(end 53.96738 -154.991054)
		(width 0.1651)
		(layer "F.Cu")
		(net "M_M_DQS_DN<2>")
	)
	(segment
		(start 79.768192 -94.223586)
		(end 79.196692 -94.223586)
		(width 0.1651)
		(layer "F.Cu")
		(net "M_M_DQS_DN<2>")
	)
	(via
		(at 79.196692 -94.223586)
		(size 0.508)
		(drill 0.254)
		(layers "F.Cu" "B.Cu")
		(net "M_M_DQS_DN<2>")
	)
	(via
		(at 54.737508 -149.482556)
		(size 0.508)
		(drill 0.254)
		(layers "F.Cu" "B.Cu")
		(net "M_M_DQS_DN<2>")
	)
	(via
		(at 54.737508 -154.876246)
		(size 0.508)
		(drill 0.254)
		(layers "F.Cu" "B.Cu")
		(net "M_M_DQS_DN<2>")
	)
	(segment
		(start 54.349396 -147.478496)
		(end 54.349396 -148.38553)
		(width 0.1651)
		(layer "B.Cu")
		(net "M_M_DQS_DN<2>")
	)
	(segment
		(start 54.349396 -148.38553)
		(end 54.22138 -148.513546)
		(width 0.1651)
		(layer "B.Cu")
		(net "M_M_DQS_DN<2>")
	)
	(segment
		(start 54.22138 -148.767546)
		(end 53.96738 -149.021546)
		(width 0.1651)
		(layer "B.Cu")
		(net "M_M_DQS_DN<2>")
	)
	(segment
		(start 54.512464 -149.7076)
		(end 54.737508 -149.482556)
		(width 0.1651)
		(layer "B.Cu")
		(net "M_M_DQS_DN<2>")
	)
	(segment
		(start 53.96738 -149.352)
		(end 54.32298 -149.7076)
		(width 0.1651)
		(layer "B.Cu")
		(net "M_M_DQS_DN<2>")
	)
	(segment
		(start 54.32298 -149.7076)
		(end 54.512464 -149.7076)
		(width 0.1651)
		(layer "B.Cu")
		(net "M_M_DQS_DN<2>")
	)
	(segment
		(start 53.96738 -149.021546)
		(end 53.96738 -149.352)
		(width 0.1651)
		(layer "B.Cu")
		(net "M_M_DQS_DN<2>")
	)
	(segment
		(start 54.22138 -148.513546)
		(end 54.22138 -148.767546)
		(width 0.1651)
		(layer "B.Cu")
		(net "M_M_DQS_DN<2>")
	)
	(segment
		(start 55.266844 -141.438376)
		(end 55.109364 -141.595856)
		(width 0.14224)
		(layer "In11.Cu")
		(net "M_M_DQS_DN<2>")
	)
	(segment
		(start 64.999362 -111.825532)
		(end 64.501522 -112.323372)
		(width 0.14224)
		(layer "In11.Cu")
		(net "M_M_DQS_DN<2>")
	)
	(segment
		(start 56.415432 -120.663462)
		(end 56.415432 -121.186702)
		(width 0.14224)
		(layer "In11.Cu")
		(net "M_M_DQS_DN<2>")
	)
	(segment
		(start 66.11874 -110.706154)
		(end 66.11874 -111.483394)
		(width 0.14224)
		(layer "In11.Cu")
		(net "M_M_DQS_DN<2>")
	)
	(segment
		(start 56.415432 -121.186702)
		(end 55.984648 -121.617486)
		(width 0.14224)
		(layer "In11.Cu")
		(net "M_M_DQS_DN<2>")
	)
	(segment
		(start 55.266844 -134.116064)
		(end 55.266844 -136.697974)
		(width 0.14224)
		(layer "In11.Cu")
		(net "M_M_DQS_DN<2>")
	)
	(segment
		(start 71.816976 -100.862638)
		(end 71.816722 -100.862892)
		(width 0.0889)
		(layer "In11.Cu")
		(net "M_M_DQS_DN<2>")
	)
	(segment
		(start 57.167272 -119.911622)
		(end 56.415432 -120.663462)
		(width 0.14224)
		(layer "In11.Cu")
		(net "M_M_DQS_DN<2>")
	)
	(segment
		(start 62.542166 -115.059968)
		(end 61.764926 -115.059968)
		(width 0.14224)
		(layer "In11.Cu")
		(net "M_M_DQS_DN<2>")
	)
	(segment
		(start 71.873872 -101.557836)
		(end 71.873872 -102.740968)
		(width 0.0889)
		(layer "In11.Cu")
		(net "M_M_DQS_DN<2>")
	)
	(segment
		(start 55.109364 -141.595856)
		(end 55.109364 -141.849856)
		(width 0.14224)
		(layer "In11.Cu")
		(net "M_M_DQS_DN<2>")
	)
	(segment
		(start 71.873872 -102.740968)
		(end 69.859144 -104.755696)
		(width 0.0889)
		(layer "In11.Cu")
		(net "M_M_DQS_DN<2>")
	)
	(segment
		(start 55.109364 -133.958584)
		(end 55.266844 -134.116064)
		(width 0.14224)
		(layer "In11.Cu")
		(net "M_M_DQS_DN<2>")
	)
	(segment
		(start 54.304438 -154.443176)
		(end 54.737508 -154.876246)
		(width 0.14224)
		(layer "In11.Cu")
		(net "M_M_DQS_DN<2>")
	)
	(segment
		(start 65.776602 -111.825532)
		(end 64.999362 -111.825532)
		(width 0.14224)
		(layer "In11.Cu")
		(net "M_M_DQS_DN<2>")
	)
	(segment
		(start 71.816976 -99.872038)
		(end 71.810626 -99.882706)
		(width 0.0889)
		(layer "In11.Cu")
		(net "M_M_DQS_DN<2>")
	)
	(segment
		(start 68.4276 -108.591096)
		(end 67.735958 -109.282738)
		(width 0.14224)
		(layer "In11.Cu")
		(net "M_M_DQS_DN<2>")
	)
	(segment
		(start 66.61658 -110.208314)
		(end 66.11874 -110.706154)
		(width 0.14224)
		(layer "In11.Cu")
		(net "M_M_DQS_DN<2>")
	)
	(segment
		(start 69.045328 -108.135928)
		(end 68.59016 -108.591096)
		(width 0.14224)
		(layer "In11.Cu")
		(net "M_M_DQS_DN<2>")
	)
	(segment
		(start 72.339962 -98.58629)
		(end 72.307196 -98.58629)
		(width 0.0889)
		(layer "In11.Cu")
		(net "M_M_DQS_DN<2>")
	)
	(segment
		(start 54.304438 -151.1046)
		(end 54.093618 -151.31542)
		(width 0.14224)
		(layer "In11.Cu")
		(net "M_M_DQS_DN<2>")
	)
	(segment
		(start 55.266844 -142.007336)
		(end 55.266844 -142.261336)
		(width 0.14224)
		(layer "In11.Cu")
		(net "M_M_DQS_DN<2>")
	)
	(segment
		(start 61.267086 -115.557808)
		(end 61.267086 -116.335048)
		(width 0.14224)
		(layer "In11.Cu")
		(net "M_M_DQS_DN<2>")
	)
	(segment
		(start 64.501522 -113.100612)
		(end 64.159384 -113.44275)
		(width 0.14224)
		(layer "In11.Cu")
		(net "M_M_DQS_DN<2>")
	)
	(segment
		(start 62.884304 -113.94059)
		(end 62.884304 -114.71783)
		(width 0.14224)
		(layer "In11.Cu")
		(net "M_M_DQS_DN<2>")
	)
	(segment
		(start 54.093618 -151.31542)
		(end 54.093618 -152.97658)
		(width 0.14224)
		(layer "In11.Cu")
		(net "M_M_DQS_DN<2>")
	)
	(segment
		(start 55.109364 -143.495776)
		(end 55.266844 -143.653256)
		(width 0.14224)
		(layer "In11.Cu")
		(net "M_M_DQS_DN<2>")
	)
	(segment
		(start 55.984648 -126.291086)
		(end 55.266844 -127.00889)
		(width 0.14224)
		(layer "In11.Cu")
		(net "M_M_DQS_DN<2>")
	)
	(segment
		(start 76.636372 -96.109536)
		(end 76.603606 -96.109536)
		(width 0.0889)
		(layer "In11.Cu")
		(net "M_M_DQS_DN<2>")
	)
	(segment
		(start 69.045328 -105.513378)
		(end 69.045328 -108.135928)
		(width 0.14224)
		(layer "In11.Cu")
		(net "M_M_DQS_DN<2>")
	)
	(segment
		(start 55.266844 -146.256248)
		(end 55.109364 -146.413728)
		(width 0.14224)
		(layer "In11.Cu")
		(net "M_M_DQS_DN<2>")
	)
	(segment
		(start 55.266844 -138.912854)
		(end 55.266844 -141.438376)
		(width 0.14224)
		(layer "In11.Cu")
		(net "M_M_DQS_DN<2>")
	)
	(segment
		(start 55.109364 -136.855454)
		(end 55.109364 -137.109454)
		(width 0.14224)
		(layer "In11.Cu")
		(net "M_M_DQS_DN<2>")
	)
	(segment
		(start 78.90129 -94.543372)
		(end 78.684882 -94.919038)
		(width 0.0889)
		(layer "In11.Cu")
		(net "M_M_DQS_DN<2>")
	)
	(segment
		(start 55.266844 -127.00889)
		(end 55.266844 -132.6388)
		(width 0.14224)
		(layer "In11.Cu")
		(net "M_M_DQS_DN<2>")
	)
	(segment
		(start 68.59016 -108.591096)
		(end 68.4276 -108.591096)
		(width 0.14224)
		(layer "In11.Cu")
		(net "M_M_DQS_DN<2>")
	)
	(segment
		(start 54.737508 -149.482556)
		(end 54.664356 -149.482556)
		(width 0.14224)
		(layer "In11.Cu")
		(net "M_M_DQS_DN<2>")
	)
	(segment
		(start 78.355698 -95.118936)
		(end 78.320392 -95.118936)
		(width 0.0889)
		(layer "In11.Cu")
		(net "M_M_DQS_DN<2>")
	)
	(segment
		(start 55.266844 -138.343894)
		(end 55.109364 -138.501374)
		(width 0.14224)
		(layer "In11.Cu")
		(net "M_M_DQS_DN<2>")
	)
	(segment
		(start 74.057002 -97.59569)
		(end 74.024236 -97.59569)
		(width 0.0889)
		(layer "In11.Cu")
		(net "M_M_DQS_DN<2>")
	)
	(segment
		(start 55.266844 -143.653256)
		(end 55.266844 -146.256248)
		(width 0.14224)
		(layer "In11.Cu")
		(net "M_M_DQS_DN<2>")
	)
	(segment
		(start 55.109364 -147.490688)
		(end 55.266844 -147.648168)
		(width 0.14224)
		(layer "In11.Cu")
		(net "M_M_DQS_DN<2>")
	)
	(segment
		(start 55.266844 -143.084296)
		(end 55.109364 -143.241776)
		(width 0.14224)
		(layer "In11.Cu")
		(net "M_M_DQS_DN<2>")
	)
	(segment
		(start 61.764926 -115.059968)
		(end 61.267086 -115.557808)
		(width 0.14224)
		(layer "In11.Cu")
		(net "M_M_DQS_DN<2>")
	)
	(segment
		(start 55.266844 -147.079208)
		(end 55.109364 -147.236688)
		(width 0.14224)
		(layer "In11.Cu")
		(net "M_M_DQS_DN<2>")
	)
	(segment
		(start 54.977538 -149.482556)
		(end 54.737508 -149.482556)
		(width 0.14224)
		(layer "In11.Cu")
		(net "M_M_DQS_DN<2>")
	)
	(segment
		(start 54.304438 -149.842474)
		(end 54.304438 -151.1046)
		(width 0.14224)
		(layer "In11.Cu")
		(net "M_M_DQS_DN<2>")
	)
	(segment
		(start 54.093618 -152.97658)
		(end 54.304438 -153.1874)
		(width 0.14224)
		(layer "In11.Cu")
		(net "M_M_DQS_DN<2>")
	)
	(segment
		(start 61.267086 -116.335048)
		(end 60.924948 -116.677186)
		(width 0.14224)
		(layer "In11.Cu")
		(net "M_M_DQS_DN<2>")
	)
	(segment
		(start 59.30773 -118.294404)
		(end 58.531252 -118.294404)
		(width 0.14224)
		(layer "In11.Cu")
		(net "M_M_DQS_DN<2>")
	)
	(segment
		(start 69.80301 -104.755696)
		(end 69.787262 -104.771444)
		(width 0.0889)
		(layer "In11.Cu")
		(net "M_M_DQS_DN<2>")
	)
	(segment
		(start 74.919332 -97.100136)
		(end 74.886566 -97.100136)
		(width 0.0889)
		(layer "In11.Cu")
		(net "M_M_DQS_DN<2>")
	)
	(segment
		(start 55.109364 -148.313648)
		(end 55.266844 -148.471128)
		(width 0.14224)
		(layer "In11.Cu")
		(net "M_M_DQS_DN<2>")
	)
	(segment
		(start 55.109364 -138.501374)
		(end 55.109364 -138.755374)
		(width 0.14224)
		(layer "In11.Cu")
		(net "M_M_DQS_DN<2>")
	)
	(segment
		(start 55.109364 -141.849856)
		(end 55.266844 -142.007336)
		(width 0.14224)
		(layer "In11.Cu")
		(net "M_M_DQS_DN<2>")
	)
	(segment
		(start 58.03265 -118.793006)
		(end 58.03265 -119.408956)
		(width 0.14224)
		(layer "In11.Cu")
		(net "M_M_DQS_DN<2>")
	)
	(segment
		(start 77.479906 -95.61449)
		(end 77.458316 -95.61449)
		(width 0.0889)
		(layer "In11.Cu")
		(net "M_M_DQS_DN<2>")
	)
	(segment
		(start 58.531252 -118.294404)
		(end 58.03265 -118.793006)
		(width 0.14224)
		(layer "In11.Cu")
		(net "M_M_DQS_DN<2>")
	)
	(segment
		(start 55.109364 -148.059648)
		(end 55.109364 -148.313648)
		(width 0.14224)
		(layer "In11.Cu")
		(net "M_M_DQS_DN<2>")
	)
	(segment
		(start 59.649868 -117.175026)
		(end 59.649868 -117.952266)
		(width 0.14224)
		(layer "In11.Cu")
		(net "M_M_DQS_DN<2>")
	)
	(segment
		(start 62.884304 -114.71783)
		(end 62.542166 -115.059968)
		(width 0.14224)
		(layer "In11.Cu")
		(net "M_M_DQS_DN<2>")
	)
	(segment
		(start 55.266844 -148.471128)
		(end 55.266844 -149.19325)
		(width 0.14224)
		(layer "In11.Cu")
		(net "M_M_DQS_DN<2>")
	)
	(segment
		(start 55.109364 -133.05028)
		(end 55.266844 -133.20776)
		(width 0.14224)
		(layer "In11.Cu")
		(net "M_M_DQS_DN<2>")
	)
	(segment
		(start 67.39382 -110.208314)
		(end 66.61658 -110.208314)
		(width 0.14224)
		(layer "In11.Cu")
		(net "M_M_DQS_DN<2>")
	)
	(segment
		(start 54.664356 -149.482556)
		(end 54.304438 -149.842474)
		(width 0.14224)
		(layer "In11.Cu")
		(net "M_M_DQS_DN<2>")
	)
	(segment
		(start 60.147708 -116.677186)
		(end 59.649868 -117.175026)
		(width 0.14224)
		(layer "In11.Cu")
		(net "M_M_DQS_DN<2>")
	)
	(segment
		(start 60.924948 -116.677186)
		(end 60.147708 -116.677186)
		(width 0.14224)
		(layer "In11.Cu")
		(net "M_M_DQS_DN<2>")
	)
	(segment
		(start 58.03265 -119.408956)
		(end 57.529984 -119.911622)
		(width 0.14224)
		(layer "In11.Cu")
		(net "M_M_DQS_DN<2>")
	)
	(segment
		(start 55.109364 -142.418816)
		(end 55.109364 -142.672816)
		(width 0.14224)
		(layer "In11.Cu")
		(net "M_M_DQS_DN<2>")
	)
	(segment
		(start 55.266844 -147.902168)
		(end 55.109364 -148.059648)
		(width 0.14224)
		(layer "In11.Cu")
		(net "M_M_DQS_DN<2>")
	)
	(segment
		(start 55.266844 -137.520934)
		(end 55.109364 -137.678414)
		(width 0.14224)
		(layer "In11.Cu")
		(net "M_M_DQS_DN<2>")
	)
	(segment
		(start 55.109364 -146.667728)
		(end 55.266844 -146.825208)
		(width 0.14224)
		(layer "In11.Cu")
		(net "M_M_DQS_DN<2>")
	)
	(segment
		(start 55.266844 -133.20776)
		(end 55.266844 -133.547104)
		(width 0.14224)
		(layer "In11.Cu")
		(net "M_M_DQS_DN<2>")
	)
	(segment
		(start 55.266844 -133.547104)
		(end 55.109364 -133.704584)
		(width 0.14224)
		(layer "In11.Cu")
		(net "M_M_DQS_DN<2>")
	)
	(segment
		(start 64.159384 -113.44275)
		(end 63.382144 -113.44275)
		(width 0.14224)
		(layer "In11.Cu")
		(net "M_M_DQS_DN<2>")
	)
	(segment
		(start 54.304438 -153.1874)
		(end 54.304438 -154.443176)
		(width 0.14224)
		(layer "In11.Cu")
		(net "M_M_DQS_DN<2>")
	)
	(segment
		(start 66.11874 -111.483394)
		(end 65.776602 -111.825532)
		(width 0.14224)
		(layer "In11.Cu")
		(net "M_M_DQS_DN<2>")
	)
	(segment
		(start 55.266844 -142.261336)
		(end 55.109364 -142.418816)
		(width 0.14224)
		(layer "In11.Cu")
		(net "M_M_DQS_DN<2>")
	)
	(segment
		(start 55.109364 -137.932414)
		(end 55.266844 -138.089894)
		(width 0.14224)
		(layer "In11.Cu")
		(net "M_M_DQS_DN<2>")
	)
	(segment
		(start 55.109364 -142.672816)
		(end 55.266844 -142.830296)
		(width 0.14224)
		(layer "In11.Cu")
		(net "M_M_DQS_DN<2>")
	)
	(segment
		(start 69.787262 -104.771444)
		(end 69.045328 -105.513378)
		(width 0.14224)
		(layer "In11.Cu")
		(net "M_M_DQS_DN<2>")
	)
	(segment
		(start 75.774042 -96.60509)
		(end 75.741276 -96.60509)
		(width 0.0889)
		(layer "In11.Cu")
		(net "M_M_DQS_DN<2>")
	)
	(segment
		(start 59.649868 -117.952266)
		(end 59.30773 -118.294404)
		(width 0.14224)
		(layer "In11.Cu")
		(net "M_M_DQS_DN<2>")
	)
	(segment
		(start 73.202292 -98.090736)
		(end 73.169526 -98.090736)
		(width 0.0889)
		(layer "In11.Cu")
		(net "M_M_DQS_DN<2>")
	)
	(segment
		(start 55.109364 -137.109454)
		(end 55.266844 -137.266934)
		(width 0.14224)
		(layer "In11.Cu")
		(net "M_M_DQS_DN<2>")
	)
	(segment
		(start 71.816976 -100.462588)
		(end 71.821802 -100.471224)
		(width 0.0889)
		(layer "In11.Cu")
		(net "M_M_DQS_DN<2>")
	)
	(segment
		(start 55.266844 -142.830296)
		(end 55.266844 -143.084296)
		(width 0.14224)
		(layer "In11.Cu")
		(net "M_M_DQS_DN<2>")
	)
	(segment
		(start 55.109364 -137.678414)
		(end 55.109364 -137.932414)
		(width 0.14224)
		(layer "In11.Cu")
		(net "M_M_DQS_DN<2>")
	)
	(segment
		(start 69.859144 -104.755696)
		(end 69.80301 -104.755696)
		(width 0.0889)
		(layer "In11.Cu")
		(net "M_M_DQS_DN<2>")
	)
	(segment
		(start 55.266844 -132.6388)
		(end 55.109364 -132.79628)
		(width 0.14224)
		(layer "In11.Cu")
		(net "M_M_DQS_DN<2>")
	)
	(segment
		(start 77.826362 -95.414338)
		(end 77.82306 -95.42018)
		(width 0.0889)
		(layer "In11.Cu")
		(net "M_M_DQS_DN<2>")
	)
	(segment
		(start 55.266844 -137.266934)
		(end 55.266844 -137.520934)
		(width 0.14224)
		(layer "In11.Cu")
		(net "M_M_DQS_DN<2>")
	)
	(segment
		(start 79.196692 -94.223586)
		(end 78.90129 -94.543372)
		(width 0.0889)
		(layer "In11.Cu")
		(net "M_M_DQS_DN<2>")
	)
	(segment
		(start 55.109364 -143.241776)
		(end 55.109364 -143.495776)
		(width 0.14224)
		(layer "In11.Cu")
		(net "M_M_DQS_DN<2>")
	)
	(segment
		(start 55.266844 -138.089894)
		(end 55.266844 -138.343894)
		(width 0.14224)
		(layer "In11.Cu")
		(net "M_M_DQS_DN<2>")
	)
	(segment
		(start 55.266844 -136.697974)
		(end 55.109364 -136.855454)
		(width 0.14224)
		(layer "In11.Cu")
		(net "M_M_DQS_DN<2>")
	)
	(segment
		(start 55.109364 -132.79628)
		(end 55.109364 -133.05028)
		(width 0.14224)
		(layer "In11.Cu")
		(net "M_M_DQS_DN<2>")
	)
	(segment
		(start 71.810626 -101.44252)
		(end 71.873872 -101.557836)
		(width 0.0889)
		(layer "In11.Cu")
		(net "M_M_DQS_DN<2>")
	)
	(segment
		(start 64.501522 -112.323372)
		(end 64.501522 -113.100612)
		(width 0.14224)
		(layer "In11.Cu")
		(net "M_M_DQS_DN<2>")
	)
	(segment
		(start 55.109364 -147.236688)
		(end 55.109364 -147.490688)
		(width 0.14224)
		(layer "In11.Cu")
		(net "M_M_DQS_DN<2>")
	)
	(segment
		(start 63.382144 -113.44275)
		(end 62.884304 -113.94059)
		(width 0.14224)
		(layer "In11.Cu")
		(net "M_M_DQS_DN<2>")
	)
	(segment
		(start 55.266844 -146.825208)
		(end 55.266844 -147.079208)
		(width 0.14224)
		(layer "In11.Cu")
		(net "M_M_DQS_DN<2>")
	)
	(segment
		(start 55.266844 -149.19325)
		(end 54.977538 -149.482556)
		(width 0.14224)
		(layer "In11.Cu")
		(net "M_M_DQS_DN<2>")
	)
	(segment
		(start 55.109364 -133.704584)
		(end 55.109364 -133.958584)
		(width 0.14224)
		(layer "In11.Cu")
		(net "M_M_DQS_DN<2>")
	)
	(segment
		(start 55.109364 -138.755374)
		(end 55.266844 -138.912854)
		(width 0.14224)
		(layer "In11.Cu")
		(net "M_M_DQS_DN<2>")
	)
	(segment
		(start 55.984648 -121.617486)
		(end 55.984648 -126.291086)
		(width 0.14224)
		(layer "In11.Cu")
		(net "M_M_DQS_DN<2>")
	)
	(segment
		(start 55.109364 -146.413728)
		(end 55.109364 -146.667728)
		(width 0.14224)
		(layer "In11.Cu")
		(net "M_M_DQS_DN<2>")
	)
	(segment
		(start 55.266844 -147.648168)
		(end 55.266844 -147.902168)
		(width 0.14224)
		(layer "In11.Cu")
		(net "M_M_DQS_DN<2>")
	)
	(segment
		(start 57.529984 -119.911622)
		(end 57.167272 -119.911622)
		(width 0.14224)
		(layer "In11.Cu")
		(net "M_M_DQS_DN<2>")
	)
	(segment
		(start 67.735958 -109.282738)
		(end 67.735958 -109.866176)
		(width 0.14224)
		(layer "In11.Cu")
		(net "M_M_DQS_DN<2>")
	)
	(segment
		(start 67.735958 -109.866176)
		(end 67.39382 -110.208314)
		(width 0.14224)
		(layer "In11.Cu")
		(net "M_M_DQS_DN<2>")
	)
	(arc
		(start 77.82306 -95.42018)
		(mid 77.677094 -95.562579)
		(end 77.479906 -95.61449)
		(width 0.0889)
		(layer "In11.Cu")
		(net "M_M_DQS_DN<2>")
	)
	(arc
		(start 71.816976 -99.472242)
		(mid 71.870475 -99.67214)
		(end 71.816976 -99.872038)
		(width 0.0889)
		(layer "In11.Cu")
		(net "M_M_DQS_DN<2>")
	)
	(arc
		(start 78.684882 -94.919038)
		(mid 78.545889 -95.061118)
		(end 78.355698 -95.118936)
		(width 0.0889)
		(layer "In11.Cu")
		(net "M_M_DQS_DN<2>")
	)
	(arc
		(start 77.458316 -95.61449)
		(mid 77.175099 -95.698771)
		(end 76.968096 -95.909638)
		(width 0.0889)
		(layer "In11.Cu")
		(net "M_M_DQS_DN<2>")
	)
	(arc
		(start 74.886566 -97.100136)
		(mid 74.601142 -97.183603)
		(end 74.392536 -97.395538)
		(width 0.0889)
		(layer "In11.Cu")
		(net "M_M_DQS_DN<2>")
	)
	(arc
		(start 76.603606 -96.109536)
		(mid 76.318182 -96.193003)
		(end 76.109576 -96.404938)
		(width 0.0889)
		(layer "In11.Cu")
		(net "M_M_DQS_DN<2>")
	)
	(arc
		(start 76.109576 -96.404938)
		(mid 75.967893 -96.548742)
		(end 75.774042 -96.60509)
		(width 0.0889)
		(layer "In11.Cu")
		(net "M_M_DQS_DN<2>")
	)
	(arc
		(start 76.968096 -95.909638)
		(mid 76.828017 -96.052374)
		(end 76.636372 -96.109536)
		(width 0.0889)
		(layer "In11.Cu")
		(net "M_M_DQS_DN<2>")
	)
	(arc
		(start 72.675496 -98.386138)
		(mid 72.533813 -98.529942)
		(end 72.339962 -98.58629)
		(width 0.0889)
		(layer "In11.Cu")
		(net "M_M_DQS_DN<2>")
	)
	(arc
		(start 71.810626 -99.882706)
		(mid 71.737828 -100.173469)
		(end 71.816976 -100.462588)
		(width 0.0889)
		(layer "In11.Cu")
		(net "M_M_DQS_DN<2>")
	)
	(arc
		(start 73.534016 -97.890838)
		(mid 73.393937 -98.033574)
		(end 73.202292 -98.090736)
		(width 0.0889)
		(layer "In11.Cu")
		(net "M_M_DQS_DN<2>")
	)
	(arc
		(start 72.307196 -98.58629)
		(mid 71.811719 -98.890733)
		(end 71.816976 -99.472242)
		(width 0.0889)
		(layer "In11.Cu")
		(net "M_M_DQS_DN<2>")
	)
	(arc
		(start 71.821802 -100.471224)
		(mid 71.870557 -100.667576)
		(end 71.816976 -100.862638)
		(width 0.0889)
		(layer "In11.Cu")
		(net "M_M_DQS_DN<2>")
	)
	(arc
		(start 74.024236 -97.59569)
		(mid 73.741019 -97.679971)
		(end 73.534016 -97.890838)
		(width 0.0889)
		(layer "In11.Cu")
		(net "M_M_DQS_DN<2>")
	)
	(arc
		(start 73.169526 -98.090736)
		(mid 72.884102 -98.174203)
		(end 72.675496 -98.386138)
		(width 0.0889)
		(layer "In11.Cu")
		(net "M_M_DQS_DN<2>")
	)
	(arc
		(start 75.741276 -96.60509)
		(mid 75.458059 -96.689371)
		(end 75.251056 -96.900238)
		(width 0.0889)
		(layer "In11.Cu")
		(net "M_M_DQS_DN<2>")
	)
	(arc
		(start 75.251056 -96.900238)
		(mid 75.110977 -97.042974)
		(end 74.919332 -97.100136)
		(width 0.0889)
		(layer "In11.Cu")
		(net "M_M_DQS_DN<2>")
	)
	(arc
		(start 74.392536 -97.395538)
		(mid 74.250853 -97.539342)
		(end 74.057002 -97.59569)
		(width 0.0889)
		(layer "In11.Cu")
		(net "M_M_DQS_DN<2>")
	)
	(arc
		(start 78.320392 -95.118936)
		(mid 78.034968 -95.202403)
		(end 77.826362 -95.414338)
		(width 0.0889)
		(layer "In11.Cu")
		(net "M_M_DQS_DN<2>")
	)
	(arc
		(start 71.816722 -100.862892)
		(mid 71.737783 -101.151897)
		(end 71.810626 -101.44252)
		(width 0.0889)
		(layer "In11.Cu")
		(net "M_M_DQS_DN<2>")
	)
	(segment
		(start 45.171868 -154.6606)
		(end 45.387514 -154.876246)
		(width 0.1651)
		(layer "F.Cu")
		(net "M_M_DQS_DN<1>")
	)
	(segment
		(start 44.999402 -155.80487)
		(end 44.600368 -155.405836)
		(width 0.1651)
		(layer "F.Cu")
		(net "M_M_DQS_DN<1>")
	)
	(segment
		(start 44.600368 -155.405836)
		(end 44.600368 -155.008072)
		(width 0.1651)
		(layer "F.Cu")
		(net "M_M_DQS_DN<1>")
	)
	(segment
		(start 44.94784 -154.6606)
		(end 45.171868 -154.6606)
		(width 0.1651)
		(layer "F.Cu")
		(net "M_M_DQS_DN<1>")
	)
	(segment
		(start 44.999402 -156.87294)
		(end 44.999402 -155.80487)
		(width 0.1651)
		(layer "F.Cu")
		(net "M_M_DQS_DN<1>")
	)
	(segment
		(start 44.600368 -155.008072)
		(end 44.94784 -154.6606)
		(width 0.1651)
		(layer "F.Cu")
		(net "M_M_DQS_DN<1>")
	)
	(segment
		(start 75.475846 -90.756486)
		(end 74.904346 -90.756486)
		(width 0.1651)
		(layer "F.Cu")
		(net "M_M_DQS_DN<1>")
	)
	(via
		(at 45.387514 -154.876246)
		(size 0.508)
		(drill 0.254)
		(layers "F.Cu" "B.Cu")
		(net "M_M_DQS_DN<1>")
	)
	(via
		(at 45.387514 -149.482556)
		(size 0.508)
		(drill 0.254)
		(layers "F.Cu" "B.Cu")
		(net "M_M_DQS_DN<1>")
	)
	(via
		(at 74.904346 -90.756486)
		(size 0.508)
		(drill 0.254)
		(layers "F.Cu" "B.Cu")
		(net "M_M_DQS_DN<1>")
	)
	(segment
		(start 44.617386 -149.352)
		(end 44.972986 -149.7076)
		(width 0.1651)
		(layer "B.Cu")
		(net "M_M_DQS_DN<1>")
	)
	(segment
		(start 45.16247 -149.7076)
		(end 45.387514 -149.482556)
		(width 0.1651)
		(layer "B.Cu")
		(net "M_M_DQS_DN<1>")
	)
	(segment
		(start 44.617386 -149.021546)
		(end 44.617386 -149.352)
		(width 0.1651)
		(layer "B.Cu")
		(net "M_M_DQS_DN<1>")
	)
	(segment
		(start 44.999402 -148.38553)
		(end 44.871386 -148.513546)
		(width 0.1651)
		(layer "B.Cu")
		(net "M_M_DQS_DN<1>")
	)
	(segment
		(start 44.871386 -148.767546)
		(end 44.617386 -149.021546)
		(width 0.1651)
		(layer "B.Cu")
		(net "M_M_DQS_DN<1>")
	)
	(segment
		(start 44.871386 -148.513546)
		(end 44.871386 -148.767546)
		(width 0.1651)
		(layer "B.Cu")
		(net "M_M_DQS_DN<1>")
	)
	(segment
		(start 44.999402 -147.478496)
		(end 44.999402 -148.38553)
		(width 0.1651)
		(layer "B.Cu")
		(net "M_M_DQS_DN<1>")
	)
	(segment
		(start 44.972986 -149.7076)
		(end 45.16247 -149.7076)
		(width 0.1651)
		(layer "B.Cu")
		(net "M_M_DQS_DN<1>")
	)
	(segment
		(start 45.76445 -147.93214)
		(end 45.900594 -147.795996)
		(width 0.14224)
		(layer "In11.Cu")
		(net "M_M_DQS_DN<1>")
	)
	(segment
		(start 45.387514 -149.482556)
		(end 45.667168 -149.482556)
		(width 0.14224)
		(layer "In11.Cu")
		(net "M_M_DQS_DN<1>")
	)
	(segment
		(start 46.152054 -122.996452)
		(end 45.773848 -122.618246)
		(width 0.14224)
		(layer "In11.Cu")
		(net "M_M_DQS_DN<1>")
	)
	(segment
		(start 48.86452 -117.097302)
		(end 48.137826 -116.370354)
		(width 0.14224)
		(layer "In11.Cu")
		(net "M_M_DQS_DN<1>")
	)
	(segment
		(start 48.558196 -117.715792)
		(end 48.86452 -117.409468)
		(width 0.14224)
		(layer "In11.Cu")
		(net "M_M_DQS_DN<1>")
	)
	(segment
		(start 46.535848 -123.21794)
		(end 46.31436 -122.996452)
		(width 0.14224)
		(layer "In11.Cu")
		(net "M_M_DQS_DN<1>")
	)
	(segment
		(start 45.900594 -149.24913)
		(end 45.900594 -148.322284)
		(width 0.14224)
		(layer "In11.Cu")
		(net "M_M_DQS_DN<1>")
	)
	(segment
		(start 46.535848 -117.571266)
		(end 46.983396 -117.123718)
		(width 0.14224)
		(layer "In11.Cu")
		(net "M_M_DQS_DN<1>")
	)
	(segment
		(start 48.137826 -115.834414)
		(end 48.600614 -115.371626)
		(width 0.14224)
		(layer "In11.Cu")
		(net "M_M_DQS_DN<1>")
	)
	(segment
		(start 45.773848 -122.618246)
		(end 45.773848 -121.962418)
		(width 0.14224)
		(layer "In11.Cu")
		(net "M_M_DQS_DN<1>")
	)
	(segment
		(start 46.535848 -128.297432)
		(end 46.535848 -123.21794)
		(width 0.14224)
		(layer "In11.Cu")
		(net "M_M_DQS_DN<1>")
	)
	(segment
		(start 46.535848 -120.93194)
		(end 46.31436 -120.710452)
		(width 0.14224)
		(layer "In11.Cu")
		(net "M_M_DQS_DN<1>")
	)
	(segment
		(start 44.743624 -151.31542)
		(end 44.743624 -152.97658)
		(width 0.14224)
		(layer "In11.Cu")
		(net "M_M_DQS_DN<1>")
	)
	(segment
		(start 68.373498 -95.031814)
		(end 69.276976 -94.128336)
		(width 0.0889)
		(layer "In11.Cu")
		(net "M_M_DQS_DN<1>")
	)
	(segment
		(start 66.425572 -96.130364)
		(end 67.519296 -95.031814)
		(width 0.0889)
		(layer "In11.Cu")
		(net "M_M_DQS_DN<1>")
	)
	(segment
		(start 49.755044 -114.753136)
		(end 49.755044 -114.21745)
		(width 0.14224)
		(layer "In11.Cu")
		(net "M_M_DQS_DN<1>")
	)
	(segment
		(start 75.218544 -91.00439)
		(end 75.197462 -90.92565)
		(width 0.0889)
		(layer "In11.Cu")
		(net "M_M_DQS_DN<1>")
	)
	(segment
		(start 44.954444 -153.1874)
		(end 44.954444 -154.443176)
		(width 0.14224)
		(layer "In11.Cu")
		(net "M_M_DQS_DN<1>")
	)
	(segment
		(start 45.900594 -128.932686)
		(end 46.535848 -128.297432)
		(width 0.14224)
		(layer "In11.Cu")
		(net "M_M_DQS_DN<1>")
	)
	(segment
		(start 64.154558 -97.19564)
		(end 64.176656 -97.195386)
		(width 0.0889)
		(layer "In11.Cu")
		(net "M_M_DQS_DN<1>")
	)
	(segment
		(start 46.31436 -121.584212)
		(end 46.535848 -121.362724)
		(width 0.14224)
		(layer "In11.Cu")
		(net "M_M_DQS_DN<1>")
	)
	(segment
		(start 48.24603 -117.715792)
		(end 48.558196 -117.715792)
		(width 0.14224)
		(layer "In11.Cu")
		(net "M_M_DQS_DN<1>")
	)
	(segment
		(start 45.764196 -147.36318)
		(end 45.764196 -147.10918)
		(width 0.14224)
		(layer "In11.Cu")
		(net "M_M_DQS_DN<1>")
	)
	(segment
		(start 46.535848 -119.076724)
		(end 46.535848 -117.571266)
		(width 0.14224)
		(layer "In11.Cu")
		(net "M_M_DQS_DN<1>")
	)
	(segment
		(start 44.954444 -154.443176)
		(end 45.387514 -154.876246)
		(width 0.14224)
		(layer "In11.Cu")
		(net "M_M_DQS_DN<1>")
	)
	(segment
		(start 62.415928 -101.557074)
		(end 62.415928 -98.13544)
		(width 0.14224)
		(layer "In11.Cu")
		(net "M_M_DQS_DN<1>")
	)
	(segment
		(start 64.176656 -97.195386)
		(end 64.216534 -97.233994)
		(width 0.0889)
		(layer "In11.Cu")
		(net "M_M_DQS_DN<1>")
	)
	(segment
		(start 66.271394 -97.2312)
		(end 66.425572 -97.077022)
		(width 0.0889)
		(layer "In11.Cu")
		(net "M_M_DQS_DN<1>")
	)
	(segment
		(start 49.863756 -116.098574)
		(end 50.174652 -116.098574)
		(width 0.14224)
		(layer "In11.Cu")
		(net "M_M_DQS_DN<1>")
	)
	(segment
		(start 46.152054 -119.298212)
		(end 46.31436 -119.298212)
		(width 0.14224)
		(layer "In11.Cu")
		(net "M_M_DQS_DN<1>")
	)
	(segment
		(start 71.457312 -93.137736)
		(end 71.485252 -93.137736)
		(width 0.0889)
		(layer "In11.Cu")
		(net "M_M_DQS_DN<1>")
	)
	(segment
		(start 45.900594 -146.972782)
		(end 45.900594 -128.932686)
		(width 0.14224)
		(layer "In11.Cu")
		(net "M_M_DQS_DN<1>")
	)
	(segment
		(start 69.276976 -94.128336)
		(end 69.7738 -94.128336)
		(width 0.0889)
		(layer "In11.Cu")
		(net "M_M_DQS_DN<1>")
	)
	(segment
		(start 45.764196 -147.10918)
		(end 45.900594 -146.972782)
		(width 0.14224)
		(layer "In11.Cu")
		(net "M_M_DQS_DN<1>")
	)
	(segment
		(start 50.481738 -115.480084)
		(end 49.755044 -114.753136)
		(width 0.14224)
		(layer "In11.Cu")
		(net "M_M_DQS_DN<1>")
	)
	(segment
		(start 74.024236 -91.65209)
		(end 74.057002 -91.65209)
		(width 0.0889)
		(layer "In11.Cu")
		(net "M_M_DQS_DN<1>")
	)
	(segment
		(start 73.169526 -92.147136)
		(end 73.202292 -92.147136)
		(width 0.0889)
		(layer "In11.Cu")
		(net "M_M_DQS_DN<1>")
	)
	(segment
		(start 44.954444 -149.842474)
		(end 44.954444 -151.1046)
		(width 0.14224)
		(layer "In11.Cu")
		(net "M_M_DQS_DN<1>")
	)
	(segment
		(start 45.387514 -149.482556)
		(end 45.314362 -149.482556)
		(width 0.14224)
		(layer "In11.Cu")
		(net "M_M_DQS_DN<1>")
	)
	(segment
		(start 50.174652 -116.098574)
		(end 50.481738 -115.791488)
		(width 0.14224)
		(layer "In11.Cu")
		(net "M_M_DQS_DN<1>")
	)
	(segment
		(start 45.900594 -147.795996)
		(end 45.900594 -147.499578)
		(width 0.14224)
		(layer "In11.Cu")
		(net "M_M_DQS_DN<1>")
	)
	(segment
		(start 62.415928 -98.13544)
		(end 63.35268 -97.198688)
		(width 0.14224)
		(layer "In11.Cu")
		(net "M_M_DQS_DN<1>")
	)
	(segment
		(start 67.519296 -95.031814)
		(end 68.373498 -95.031814)
		(width 0.0889)
		(layer "In11.Cu")
		(net "M_M_DQS_DN<1>")
	)
	(segment
		(start 49.755552 -114.21745)
		(end 62.415928 -101.557074)
		(width 0.14224)
		(layer "In11.Cu")
		(net "M_M_DQS_DN<1>")
	)
	(segment
		(start 44.954444 -151.1046)
		(end 44.743624 -151.31542)
		(width 0.14224)
		(layer "In11.Cu")
		(net "M_M_DQS_DN<1>")
	)
	(segment
		(start 48.86452 -117.409468)
		(end 48.86452 -117.097302)
		(width 0.14224)
		(layer "In11.Cu")
		(net "M_M_DQS_DN<1>")
	)
	(segment
		(start 64.216534 -97.233994)
		(end 64.355218 -97.2312)
		(width 0.0889)
		(layer "In11.Cu")
		(net "M_M_DQS_DN<1>")
	)
	(segment
		(start 70.593966 -93.633036)
		(end 70.62978 -93.633036)
		(width 0.0889)
		(layer "In11.Cu")
		(net "M_M_DQS_DN<1>")
	)
	(segment
		(start 47.653956 -117.123718)
		(end 48.24603 -117.715792)
		(width 0.14224)
		(layer "In11.Cu")
		(net "M_M_DQS_DN<1>")
	)
	(segment
		(start 48.137826 -116.370354)
		(end 48.137826 -115.834414)
		(width 0.14224)
		(layer "In11.Cu")
		(net "M_M_DQS_DN<1>")
	)
	(segment
		(start 46.152054 -121.584212)
		(end 46.31436 -121.584212)
		(width 0.14224)
		(layer "In11.Cu")
		(net "M_M_DQS_DN<1>")
	)
	(segment
		(start 46.31436 -122.996452)
		(end 46.152054 -122.996452)
		(width 0.14224)
		(layer "In11.Cu")
		(net "M_M_DQS_DN<1>")
	)
	(segment
		(start 46.31436 -119.298212)
		(end 46.535848 -119.076724)
		(width 0.14224)
		(layer "In11.Cu")
		(net "M_M_DQS_DN<1>")
	)
	(segment
		(start 64.355218 -97.2312)
		(end 66.271394 -97.2312)
		(width 0.0889)
		(layer "In11.Cu")
		(net "M_M_DQS_DN<1>")
	)
	(segment
		(start 45.799248 -120.357646)
		(end 45.799248 -119.651018)
		(width 0.14224)
		(layer "In11.Cu")
		(net "M_M_DQS_DN<1>")
	)
	(segment
		(start 63.35268 -97.198688)
		(end 63.999364 -97.198688)
		(width 0.14224)
		(layer "In11.Cu")
		(net "M_M_DQS_DN<1>")
	)
	(segment
		(start 48.600614 -115.371626)
		(end 49.137062 -115.371626)
		(width 0.14224)
		(layer "In11.Cu")
		(net "M_M_DQS_DN<1>")
	)
	(segment
		(start 66.425572 -97.077022)
		(end 66.425572 -96.130364)
		(width 0.0889)
		(layer "In11.Cu")
		(net "M_M_DQS_DN<1>")
	)
	(segment
		(start 45.314362 -149.482556)
		(end 44.954444 -149.842474)
		(width 0.14224)
		(layer "In11.Cu")
		(net "M_M_DQS_DN<1>")
	)
	(segment
		(start 49.755044 -114.21745)
		(end 49.755552 -114.21745)
		(width 0.14224)
		(layer "In11.Cu")
		(net "M_M_DQS_DN<1>")
	)
	(segment
		(start 46.983396 -117.123718)
		(end 47.653956 -117.123718)
		(width 0.14224)
		(layer "In11.Cu")
		(net "M_M_DQS_DN<1>")
	)
	(segment
		(start 63.999364 -97.198688)
		(end 64.154558 -97.19564)
		(width 0.14224)
		(layer "In11.Cu")
		(net "M_M_DQS_DN<1>")
	)
	(segment
		(start 45.900594 -148.322284)
		(end 45.76445 -148.18614)
		(width 0.14224)
		(layer "In11.Cu")
		(net "M_M_DQS_DN<1>")
	)
	(segment
		(start 45.773848 -121.962418)
		(end 46.152054 -121.584212)
		(width 0.14224)
		(layer "In11.Cu")
		(net "M_M_DQS_DN<1>")
	)
	(segment
		(start 46.31436 -120.710452)
		(end 46.152054 -120.710452)
		(width 0.14224)
		(layer "In11.Cu")
		(net "M_M_DQS_DN<1>")
	)
	(segment
		(start 75.197462 -90.92565)
		(end 74.904346 -90.756486)
		(width 0.0889)
		(layer "In11.Cu")
		(net "M_M_DQS_DN<1>")
	)
	(segment
		(start 50.481738 -115.791488)
		(end 50.481738 -115.480084)
		(width 0.14224)
		(layer "In11.Cu")
		(net "M_M_DQS_DN<1>")
	)
	(segment
		(start 45.799248 -119.651018)
		(end 46.152054 -119.298212)
		(width 0.14224)
		(layer "In11.Cu")
		(net "M_M_DQS_DN<1>")
	)
	(segment
		(start 45.900594 -147.499578)
		(end 45.764196 -147.36318)
		(width 0.14224)
		(layer "In11.Cu")
		(net "M_M_DQS_DN<1>")
	)
	(segment
		(start 72.307196 -92.64269)
		(end 72.339962 -92.64269)
		(width 0.0889)
		(layer "In11.Cu")
		(net "M_M_DQS_DN<1>")
	)
	(segment
		(start 45.667168 -149.482556)
		(end 45.900594 -149.24913)
		(width 0.14224)
		(layer "In11.Cu")
		(net "M_M_DQS_DN<1>")
	)
	(segment
		(start 46.535848 -121.362724)
		(end 46.535848 -120.93194)
		(width 0.14224)
		(layer "In11.Cu")
		(net "M_M_DQS_DN<1>")
	)
	(segment
		(start 74.886566 -91.156536)
		(end 74.919332 -91.156536)
		(width 0.0889)
		(layer "In11.Cu")
		(net "M_M_DQS_DN<1>")
	)
	(segment
		(start 49.137062 -115.371626)
		(end 49.863756 -116.098574)
		(width 0.14224)
		(layer "In11.Cu")
		(net "M_M_DQS_DN<1>")
	)
	(segment
		(start 44.743624 -152.97658)
		(end 44.954444 -153.1874)
		(width 0.14224)
		(layer "In11.Cu")
		(net "M_M_DQS_DN<1>")
	)
	(segment
		(start 45.76445 -148.18614)
		(end 45.76445 -147.93214)
		(width 0.14224)
		(layer "In11.Cu")
		(net "M_M_DQS_DN<1>")
	)
	(segment
		(start 46.152054 -120.710452)
		(end 45.799248 -120.357646)
		(width 0.14224)
		(layer "In11.Cu")
		(net "M_M_DQS_DN<1>")
	)
	(arc
		(start 73.534016 -91.947238)
		(mid 73.74102 -91.736374)
		(end 74.024236 -91.65209)
		(width 0.0889)
		(layer "In11.Cu")
		(net "M_M_DQS_DN<1>")
	)
	(arc
		(start 72.675496 -92.442538)
		(mid 72.884104 -92.230606)
		(end 73.169526 -92.147136)
		(width 0.0889)
		(layer "In11.Cu")
		(net "M_M_DQS_DN<1>")
	)
	(arc
		(start 71.485252 -93.137736)
		(mid 71.676894 -93.08057)
		(end 71.816976 -92.937838)
		(width 0.0889)
		(layer "In11.Cu")
		(net "M_M_DQS_DN<1>")
	)
	(arc
		(start 71.816976 -92.937838)
		(mid 72.02398 -92.726974)
		(end 72.307196 -92.64269)
		(width 0.0889)
		(layer "In11.Cu")
		(net "M_M_DQS_DN<1>")
	)
	(arc
		(start 72.339962 -92.64269)
		(mid 72.533812 -92.58634)
		(end 72.675496 -92.442538)
		(width 0.0889)
		(layer "In11.Cu")
		(net "M_M_DQS_DN<1>")
	)
	(arc
		(start 74.057002 -91.65209)
		(mid 74.250852 -91.59574)
		(end 74.392536 -91.451938)
		(width 0.0889)
		(layer "In11.Cu")
		(net "M_M_DQS_DN<1>")
	)
	(arc
		(start 73.202292 -92.147136)
		(mid 73.393934 -92.08997)
		(end 73.534016 -91.947238)
		(width 0.0889)
		(layer "In11.Cu")
		(net "M_M_DQS_DN<1>")
	)
	(arc
		(start 74.392536 -91.451938)
		(mid 74.601144 -91.240006)
		(end 74.886566 -91.156536)
		(width 0.0889)
		(layer "In11.Cu")
		(net "M_M_DQS_DN<1>")
	)
	(arc
		(start 70.099936 -93.928438)
		(mid 70.308544 -93.716506)
		(end 70.593966 -93.633036)
		(width 0.0889)
		(layer "In11.Cu")
		(net "M_M_DQS_DN<1>")
	)
	(arc
		(start 74.919332 -91.156536)
		(mid 75.085626 -91.113302)
		(end 75.218544 -91.00439)
		(width 0.0889)
		(layer "In11.Cu")
		(net "M_M_DQS_DN<1>")
	)
	(arc
		(start 69.7738 -94.128336)
		(mid 69.962336 -94.06991)
		(end 70.099936 -93.928438)
		(width 0.0889)
		(layer "In11.Cu")
		(net "M_M_DQS_DN<1>")
	)
	(arc
		(start 70.958456 -93.433138)
		(mid 71.169169 -93.220059)
		(end 71.457312 -93.137736)
		(width 0.0889)
		(layer "In11.Cu")
		(net "M_M_DQS_DN<1>")
	)
	(arc
		(start 70.62978 -93.633036)
		(mid 70.819709 -93.575166)
		(end 70.958456 -93.433138)
		(width 0.0889)
		(layer "In11.Cu")
		(net "M_M_DQS_DN<1>")
	)
	(segment
		(start 81.485232 -83.32724)
		(end 80.913732 -83.32724)
		(width 0.1651)
		(layer "F.Cu")
		(net "M_M_DQS_DN<17>")
	)
	(segment
		(start 72.6313 -153.7716)
		(end 72.817228 -153.957528)
		(width 0.1651)
		(layer "F.Cu")
		(net "M_M_DQS_DN<17>")
	)
	(segment
		(start 72.56526 -154.45613)
		(end 72.35698 -154.45613)
		(width 0.1651)
		(layer "F.Cu")
		(net "M_M_DQS_DN<17>")
	)
	(segment
		(start 72.817228 -153.957528)
		(end 72.817228 -154.204162)
		(width 0.1651)
		(layer "F.Cu")
		(net "M_M_DQS_DN<17>")
	)
	(segment
		(start 73.049384 -152.932384)
		(end 72.6313 -153.350468)
		(width 0.1651)
		(layer "F.Cu")
		(net "M_M_DQS_DN<17>")
	)
	(segment
		(start 72.6313 -153.350468)
		(end 72.6313 -153.7716)
		(width 0.1651)
		(layer "F.Cu")
		(net "M_M_DQS_DN<17>")
	)
	(segment
		(start 72.35698 -154.45613)
		(end 72.16775 -154.2669)
		(width 0.1651)
		(layer "F.Cu")
		(net "M_M_DQS_DN<17>")
	)
	(segment
		(start 72.817228 -154.204162)
		(end 72.56526 -154.45613)
		(width 0.1651)
		(layer "F.Cu")
		(net "M_M_DQS_DN<17>")
	)
	(segment
		(start 73.049384 -152.273)
		(end 73.049384 -152.932384)
		(width 0.1651)
		(layer "F.Cu")
		(net "M_M_DQS_DN<17>")
	)
	(segment
		(start 72.16775 -154.2669)
		(end 72.1487 -154.2669)
		(width 0.1651)
		(layer "F.Cu")
		(net "M_M_DQS_DN<17>")
	)
	(via
		(at 72.142096 -150.0886)
		(size 0.508)
		(drill 0.254)
		(layers "F.Cu" "B.Cu")
		(net "M_M_DQS_DN<17>")
	)
	(via
		(at 72.1487 -154.2669)
		(size 0.508)
		(drill 0.254)
		(layers "F.Cu" "B.Cu")
		(net "M_M_DQS_DN<17>")
	)
	(via
		(at 80.913732 -83.32724)
		(size 0.508)
		(drill 0.254)
		(layers "F.Cu" "B.Cu")
		(net "M_M_DQS_DN<17>")
	)
	(segment
		(start 72.33666 -149.894036)
		(end 72.142096 -150.0886)
		(width 0.1651)
		(layer "B.Cu")
		(net "M_M_DQS_DN<17>")
	)
	(segment
		(start 72.6059 -150.977854)
		(end 72.6059 -150.622)
		(width 0.1651)
		(layer "B.Cu")
		(net "M_M_DQS_DN<17>")
	)
	(segment
		(start 72.7837 -150.114)
		(end 72.563736 -149.894036)
		(width 0.1651)
		(layer "B.Cu")
		(net "M_M_DQS_DN<17>")
	)
	(segment
		(start 72.7837 -150.4442)
		(end 72.7837 -150.114)
		(width 0.1651)
		(layer "B.Cu")
		(net "M_M_DQS_DN<17>")
	)
	(segment
		(start 73.049384 -152.078436)
		(end 73.049638 -152.077928)
		(width 0.1651)
		(layer "B.Cu")
		(net "M_M_DQS_DN<17>")
	)
	(segment
		(start 72.6059 -150.622)
		(end 72.7837 -150.4442)
		(width 0.1651)
		(layer "B.Cu")
		(net "M_M_DQS_DN<17>")
	)
	(segment
		(start 72.563736 -149.894036)
		(end 72.33666 -149.894036)
		(width 0.1651)
		(layer "B.Cu")
		(net "M_M_DQS_DN<17>")
	)
	(segment
		(start 73.049638 -152.077928)
		(end 73.049638 -151.421592)
		(width 0.1651)
		(layer "B.Cu")
		(net "M_M_DQS_DN<17>")
	)
	(segment
		(start 73.049638 -151.421592)
		(end 72.6059 -150.977854)
		(width 0.1651)
		(layer "B.Cu")
		(net "M_M_DQS_DN<17>")
	)
	(segment
		(start 72.924416 -123.733814)
		(end 72.924416 -149.30628)
		(width 0.14224)
		(layer "In4.Cu")
		(net "M_M_DQS_DN<17>")
	)
	(segment
		(start 80.570324 -99.960938)
		(end 80.468216 -100.13823)
		(width 0.0889)
		(layer "In4.Cu")
		(net "M_M_DQS_DN<17>")
	)
	(segment
		(start 80.567022 -86.498938)
		(end 80.573372 -86.509606)
		(width 0.0889)
		(layer "In4.Cu")
		(net "M_M_DQS_DN<17>")
	)
	(segment
		(start 80.468216 -100.13823)
		(end 80.28432 -100.322126)
		(width 0.0889)
		(layer "In4.Cu")
		(net "M_M_DQS_DN<17>")
	)
	(segment
		(start 80.567022 -96.404938)
		(end 80.573372 -96.415606)
		(width 0.0889)
		(layer "In4.Cu")
		(net "M_M_DQS_DN<17>")
	)
	(segment
		(start 80.32369 -105.105454)
		(end 74.008488 -111.420656)
		(width 0.14224)
		(layer "In4.Cu")
		(net "M_M_DQS_DN<17>")
	)
	(segment
		(start 72.855074 -115.610132)
		(end 72.711564 -115.610132)
		(width 0.14224)
		(layer "In4.Cu")
		(net "M_M_DQS_DN<17>")
	)
	(segment
		(start 80.567022 -90.461338)
		(end 80.573372 -90.472006)
		(width 0.0889)
		(layer "In4.Cu")
		(net "M_M_DQS_DN<17>")
	)
	(segment
		(start 80.913732 -83.32724)
		(end 80.913732 -82.989166)
		(width 0.0889)
		(layer "In4.Cu")
		(net "M_M_DQS_DN<17>")
	)
	(segment
		(start 80.567022 -91.451938)
		(end 80.573372 -91.462606)
		(width 0.0889)
		(layer "In4.Cu")
		(net "M_M_DQS_DN<17>")
	)
	(segment
		(start 80.562196 -95.405702)
		(end 80.567022 -95.414338)
		(width 0.0889)
		(layer "In4.Cu")
		(net "M_M_DQS_DN<17>")
	)
	(segment
		(start 80.32369 -103.000048)
		(end 80.32369 -105.105454)
		(width 0.14224)
		(layer "In4.Cu")
		(net "M_M_DQS_DN<17>")
	)
	(segment
		(start 80.573372 -94.01302)
		(end 80.567022 -94.023688)
		(width 0.0889)
		(layer "In4.Cu")
		(net "M_M_DQS_DN<17>")
	)
	(segment
		(start 72.382888 -117.190012)
		(end 72.484488 -117.291612)
		(width 0.14224)
		(layer "In4.Cu")
		(net "M_M_DQS_DN<17>")
	)
	(segment
		(start 74.008488 -111.420656)
		(end 74.008488 -114.313208)
		(width 0.14224)
		(layer "In4.Cu")
		(net "M_M_DQS_DN<17>")
	)
	(segment
		(start 73.184004 -115.137692)
		(end 73.184004 -115.281202)
		(width 0.14224)
		(layer "In4.Cu")
		(net "M_M_DQS_DN<17>")
	)
	(segment
		(start 80.567022 -97.395538)
		(end 80.573372 -97.406206)
		(width 0.0889)
		(layer "In4.Cu")
		(net "M_M_DQS_DN<17>")
	)
	(segment
		(start 72.484488 -117.291612)
		(end 72.484488 -117.756432)
		(width 0.14224)
		(layer "In4.Cu")
		(net "M_M_DQS_DN<17>")
	)
	(segment
		(start 80.562196 -85.499702)
		(end 80.567022 -85.508338)
		(width 0.0889)
		(layer "In4.Cu")
		(net "M_M_DQS_DN<17>")
	)
	(segment
		(start 73.184004 -115.281202)
		(end 72.855074 -115.610132)
		(width 0.14224)
		(layer "In4.Cu")
		(net "M_M_DQS_DN<17>")
	)
	(segment
		(start 80.562196 -92.433902)
		(end 80.567022 -92.442538)
		(width 0.0889)
		(layer "In4.Cu")
		(net "M_M_DQS_DN<17>")
	)
	(segment
		(start 80.913732 -82.989166)
		(end 80.85582 -82.931254)
		(width 0.0889)
		(layer "In4.Cu")
		(net "M_M_DQS_DN<17>")
	)
	(segment
		(start 74.008488 -114.313208)
		(end 73.184004 -115.137692)
		(width 0.14224)
		(layer "In4.Cu")
		(net "M_M_DQS_DN<17>")
	)
	(segment
		(start 72.382888 -115.938808)
		(end 72.382888 -117.190012)
		(width 0.14224)
		(layer "In4.Cu")
		(net "M_M_DQS_DN<17>")
	)
	(segment
		(start 80.570832 -99.960176)
		(end 80.570324 -99.960938)
		(width 0.0889)
		(layer "In4.Cu")
		(net "M_M_DQS_DN<17>")
	)
	(segment
		(start 80.562196 -89.462102)
		(end 80.567022 -89.470738)
		(width 0.0889)
		(layer "In4.Cu")
		(net "M_M_DQS_DN<17>")
	)
	(segment
		(start 80.567022 -84.517738)
		(end 80.573372 -84.528406)
		(width 0.0889)
		(layer "In4.Cu")
		(net "M_M_DQS_DN<17>")
	)
	(segment
		(start 80.567022 -83.527138)
		(end 80.573372 -83.537806)
		(width 0.0889)
		(layer "In4.Cu")
		(net "M_M_DQS_DN<17>")
	)
	(segment
		(start 80.562196 -96.396302)
		(end 80.567022 -96.404938)
		(width 0.0889)
		(layer "In4.Cu")
		(net "M_M_DQS_DN<17>")
	)
	(segment
		(start 80.562196 -90.452702)
		(end 80.567022 -90.461338)
		(width 0.0889)
		(layer "In4.Cu")
		(net "M_M_DQS_DN<17>")
	)
	(segment
		(start 80.567022 -89.470738)
		(end 80.573372 -89.481406)
		(width 0.0889)
		(layer "In4.Cu")
		(net "M_M_DQS_DN<17>")
	)
	(segment
		(start 72.711564 -115.610132)
		(end 72.382888 -115.938808)
		(width 0.14224)
		(layer "In4.Cu")
		(net "M_M_DQS_DN<17>")
	)
	(segment
		(start 80.562196 -87.480902)
		(end 80.567022 -87.489538)
		(width 0.0889)
		(layer "In4.Cu")
		(net "M_M_DQS_DN<17>")
	)
	(segment
		(start 80.28432 -102.960678)
		(end 80.32369 -103.000048)
		(width 0.0889)
		(layer "In4.Cu")
		(net "M_M_DQS_DN<17>")
	)
	(segment
		(start 80.562196 -84.509102)
		(end 80.567022 -84.517738)
		(width 0.0889)
		(layer "In4.Cu")
		(net "M_M_DQS_DN<17>")
	)
	(segment
		(start 72.484488 -117.756432)
		(end 72.382888 -117.858032)
		(width 0.14224)
		(layer "In4.Cu")
		(net "M_M_DQS_DN<17>")
	)
	(segment
		(start 72.382888 -123.192286)
		(end 72.924416 -123.733814)
		(width 0.14224)
		(layer "In4.Cu")
		(net "M_M_DQS_DN<17>")
	)
	(segment
		(start 80.567022 -95.414338)
		(end 80.573372 -95.425006)
		(width 0.0889)
		(layer "In4.Cu")
		(net "M_M_DQS_DN<17>")
	)
	(segment
		(start 80.562196 -86.490302)
		(end 80.567022 -86.498938)
		(width 0.0889)
		(layer "In4.Cu")
		(net "M_M_DQS_DN<17>")
	)
	(segment
		(start 72.382888 -117.858032)
		(end 72.382888 -123.192286)
		(width 0.14224)
		(layer "In4.Cu")
		(net "M_M_DQS_DN<17>")
	)
	(segment
		(start 72.924416 -149.30628)
		(end 72.142096 -150.0886)
		(width 0.14224)
		(layer "In4.Cu")
		(net "M_M_DQS_DN<17>")
	)
	(segment
		(start 80.567022 -98.386138)
		(end 80.573372 -98.396806)
		(width 0.0889)
		(layer "In4.Cu")
		(net "M_M_DQS_DN<17>")
	)
	(segment
		(start 80.567022 -92.442538)
		(end 80.573372 -92.453206)
		(width 0.0889)
		(layer "In4.Cu")
		(net "M_M_DQS_DN<17>")
	)
	(segment
		(start 80.562196 -88.471502)
		(end 80.567022 -88.480138)
		(width 0.0889)
		(layer "In4.Cu")
		(net "M_M_DQS_DN<17>")
	)
	(segment
		(start 80.28432 -100.322126)
		(end 80.28432 -102.960678)
		(width 0.0889)
		(layer "In4.Cu")
		(net "M_M_DQS_DN<17>")
	)
	(segment
		(start 80.567022 -85.508338)
		(end 80.573372 -85.519006)
		(width 0.0889)
		(layer "In4.Cu")
		(net "M_M_DQS_DN<17>")
	)
	(segment
		(start 80.562196 -98.377502)
		(end 80.567022 -98.386138)
		(width 0.0889)
		(layer "In4.Cu")
		(net "M_M_DQS_DN<17>")
	)
	(segment
		(start 80.562196 -91.443302)
		(end 80.567022 -91.451938)
		(width 0.0889)
		(layer "In4.Cu")
		(net "M_M_DQS_DN<17>")
	)
	(segment
		(start 80.567022 -88.480138)
		(end 80.573372 -88.490806)
		(width 0.0889)
		(layer "In4.Cu")
		(net "M_M_DQS_DN<17>")
	)
	(segment
		(start 80.562196 -93.424502)
		(end 80.567022 -93.433138)
		(width 0.0889)
		(layer "In4.Cu")
		(net "M_M_DQS_DN<17>")
	)
	(segment
		(start 80.562196 -97.386902)
		(end 80.567022 -97.395538)
		(width 0.0889)
		(layer "In4.Cu")
		(net "M_M_DQS_DN<17>")
	)
	(segment
		(start 80.567022 -87.489538)
		(end 80.573372 -87.500206)
		(width 0.0889)
		(layer "In4.Cu")
		(net "M_M_DQS_DN<17>")
	)
	(arc
		(start 80.567022 -96.995488)
		(mid 80.513552 -97.190551)
		(end 80.562196 -97.386902)
		(width 0.0889)
		(layer "In4.Cu")
		(net "M_M_DQS_DN<17>")
	)
	(arc
		(start 80.573372 -90.472006)
		(mid 80.64617 -90.762769)
		(end 80.567022 -91.051888)
		(width 0.0889)
		(layer "In4.Cu")
		(net "M_M_DQS_DN<17>")
	)
	(arc
		(start 80.567022 -98.976688)
		(mid 80.513396 -99.17684)
		(end 80.567022 -99.376992)
		(width 0.0889)
		(layer "In4.Cu")
		(net "M_M_DQS_DN<17>")
	)
	(arc
		(start 80.567022 -95.014288)
		(mid 80.513552 -95.209351)
		(end 80.562196 -95.405702)
		(width 0.0889)
		(layer "In4.Cu")
		(net "M_M_DQS_DN<17>")
	)
	(arc
		(start 80.567022 -94.023688)
		(mid 80.513523 -94.223586)
		(end 80.567022 -94.423484)
		(width 0.0889)
		(layer "In4.Cu")
		(net "M_M_DQS_DN<17>")
	)
	(arc
		(start 80.567022 -93.033088)
		(mid 80.513552 -93.228151)
		(end 80.562196 -93.424502)
		(width 0.0889)
		(layer "In4.Cu")
		(net "M_M_DQS_DN<17>")
	)
	(arc
		(start 80.85582 -82.931254)
		(mid 80.553599 -83.152704)
		(end 80.567022 -83.527138)
		(width 0.0889)
		(layer "In4.Cu")
		(net "M_M_DQS_DN<17>")
	)
	(arc
		(start 80.567022 -85.108288)
		(mid 80.513552 -85.303351)
		(end 80.562196 -85.499702)
		(width 0.0889)
		(layer "In4.Cu")
		(net "M_M_DQS_DN<17>")
	)
	(arc
		(start 80.567022 -96.004888)
		(mid 80.513552 -96.199951)
		(end 80.562196 -96.396302)
		(width 0.0889)
		(layer "In4.Cu")
		(net "M_M_DQS_DN<17>")
	)
	(arc
		(start 80.573372 -96.415606)
		(mid 80.64617 -96.706369)
		(end 80.567022 -96.995488)
		(width 0.0889)
		(layer "In4.Cu")
		(net "M_M_DQS_DN<17>")
	)
	(arc
		(start 80.573372 -86.509606)
		(mid 80.64617 -86.800369)
		(end 80.567022 -87.089488)
		(width 0.0889)
		(layer "In4.Cu")
		(net "M_M_DQS_DN<17>")
	)
	(arc
		(start 80.567022 -86.098888)
		(mid 80.513552 -86.293951)
		(end 80.562196 -86.490302)
		(width 0.0889)
		(layer "In4.Cu")
		(net "M_M_DQS_DN<17>")
	)
	(arc
		(start 80.573372 -83.537806)
		(mid 80.64617 -83.828569)
		(end 80.567022 -84.117688)
		(width 0.0889)
		(layer "In4.Cu")
		(net "M_M_DQS_DN<17>")
	)
	(arc
		(start 80.573372 -95.425006)
		(mid 80.64617 -95.715769)
		(end 80.567022 -96.004888)
		(width 0.0889)
		(layer "In4.Cu")
		(net "M_M_DQS_DN<17>")
	)
	(arc
		(start 80.567022 -94.423484)
		(mid 80.646153 -94.718886)
		(end 80.567022 -95.014288)
		(width 0.0889)
		(layer "In4.Cu")
		(net "M_M_DQS_DN<17>")
	)
	(arc
		(start 80.573372 -97.406206)
		(mid 80.64617 -97.696969)
		(end 80.567022 -97.986088)
		(width 0.0889)
		(layer "In4.Cu")
		(net "M_M_DQS_DN<17>")
	)
	(arc
		(start 80.573372 -98.396806)
		(mid 80.64617 -98.687569)
		(end 80.567022 -98.976688)
		(width 0.0889)
		(layer "In4.Cu")
		(net "M_M_DQS_DN<17>")
	)
	(arc
		(start 80.567022 -88.080088)
		(mid 80.513552 -88.275151)
		(end 80.562196 -88.471502)
		(width 0.0889)
		(layer "In4.Cu")
		(net "M_M_DQS_DN<17>")
	)
	(arc
		(start 80.567022 -87.089488)
		(mid 80.513552 -87.284551)
		(end 80.562196 -87.480902)
		(width 0.0889)
		(layer "In4.Cu")
		(net "M_M_DQS_DN<17>")
	)
	(arc
		(start 80.567022 -90.061288)
		(mid 80.513552 -90.256351)
		(end 80.562196 -90.452702)
		(width 0.0889)
		(layer "In4.Cu")
		(net "M_M_DQS_DN<17>")
	)
	(arc
		(start 80.567022 -97.986088)
		(mid 80.513552 -98.181151)
		(end 80.562196 -98.377502)
		(width 0.0889)
		(layer "In4.Cu")
		(net "M_M_DQS_DN<17>")
	)
	(arc
		(start 80.573372 -87.500206)
		(mid 80.64617 -87.790969)
		(end 80.567022 -88.080088)
		(width 0.0889)
		(layer "In4.Cu")
		(net "M_M_DQS_DN<17>")
	)
	(arc
		(start 80.573372 -85.519006)
		(mid 80.64617 -85.809769)
		(end 80.567022 -86.098888)
		(width 0.0889)
		(layer "In4.Cu")
		(net "M_M_DQS_DN<17>")
	)
	(arc
		(start 80.567022 -92.042488)
		(mid 80.513552 -92.237551)
		(end 80.562196 -92.433902)
		(width 0.0889)
		(layer "In4.Cu")
		(net "M_M_DQS_DN<17>")
	)
	(arc
		(start 80.573372 -91.462606)
		(mid 80.64617 -91.753369)
		(end 80.567022 -92.042488)
		(width 0.0889)
		(layer "In4.Cu")
		(net "M_M_DQS_DN<17>")
	)
	(arc
		(start 80.567022 -99.376992)
		(mid 80.645887 -99.668074)
		(end 80.570832 -99.960176)
		(width 0.0889)
		(layer "In4.Cu")
		(net "M_M_DQS_DN<17>")
	)
	(arc
		(start 80.573372 -89.481406)
		(mid 80.64617 -89.772169)
		(end 80.567022 -90.061288)
		(width 0.0889)
		(layer "In4.Cu")
		(net "M_M_DQS_DN<17>")
	)
	(arc
		(start 80.573372 -92.453206)
		(mid 80.64617 -92.743969)
		(end 80.567022 -93.033088)
		(width 0.0889)
		(layer "In4.Cu")
		(net "M_M_DQS_DN<17>")
	)
	(arc
		(start 80.573372 -88.490806)
		(mid 80.64617 -88.781569)
		(end 80.567022 -89.070688)
		(width 0.0889)
		(layer "In4.Cu")
		(net "M_M_DQS_DN<17>")
	)
	(arc
		(start 80.567022 -91.051888)
		(mid 80.513552 -91.246951)
		(end 80.562196 -91.443302)
		(width 0.0889)
		(layer "In4.Cu")
		(net "M_M_DQS_DN<17>")
	)
	(arc
		(start 80.573372 -84.528406)
		(mid 80.64617 -84.819169)
		(end 80.567022 -85.108288)
		(width 0.0889)
		(layer "In4.Cu")
		(net "M_M_DQS_DN<17>")
	)
	(arc
		(start 80.567022 -89.070688)
		(mid 80.513552 -89.265751)
		(end 80.562196 -89.462102)
		(width 0.0889)
		(layer "In4.Cu")
		(net "M_M_DQS_DN<17>")
	)
	(arc
		(start 80.567022 -93.433138)
		(mid 80.646244 -93.722256)
		(end 80.573372 -94.01302)
		(width 0.0889)
		(layer "In4.Cu")
		(net "M_M_DQS_DN<17>")
	)
	(arc
		(start 80.567022 -84.117688)
		(mid 80.513552 -84.312751)
		(end 80.562196 -84.509102)
		(width 0.0889)
		(layer "In4.Cu")
		(net "M_M_DQS_DN<17>")
	)
	(segment
		(start 72.592438 -153.823162)
		(end 72.592438 -153.285698)
		(width 0.14224)
		(layer "In11.Cu")
		(net "M_M_DQS_DN<17>")
	)
	(segment
		(start 72.17664 -151.83612)
		(end 72.038464 -151.83612)
		(width 0.14224)
		(layer "In11.Cu")
		(net "M_M_DQS_DN<17>")
	)
	(segment
		(start 72.389238 -153.082498)
		(end 72.064118 -153.082498)
		(width 0.14224)
		(layer "In11.Cu")
		(net "M_M_DQS_DN<17>")
	)
	(segment
		(start 71.906384 -151.70404)
		(end 71.906384 -151.35606)
		(width 0.14224)
		(layer "In11.Cu")
		(net "M_M_DQS_DN<17>")
	)
	(segment
		(start 72.056244 -151.2062)
		(end 72.297544 -151.2062)
		(width 0.14224)
		(layer "In11.Cu")
		(net "M_M_DQS_DN<17>")
	)
	(segment
		(start 72.046084 -152.49906)
		(end 72.170036 -152.49906)
		(width 0.14224)
		(layer "In11.Cu")
		(net "M_M_DQS_DN<17>")
	)
	(segment
		(start 72.038464 -151.83612)
		(end 71.906384 -151.70404)
		(width 0.14224)
		(layer "In11.Cu")
		(net "M_M_DQS_DN<17>")
	)
	(segment
		(start 72.576944 -150.523448)
		(end 72.142096 -150.0886)
		(width 0.14224)
		(layer "In11.Cu")
		(net "M_M_DQS_DN<17>")
	)
	(segment
		(start 72.064118 -153.082498)
		(end 71.906384 -152.924764)
		(width 0.14224)
		(layer "In11.Cu")
		(net "M_M_DQS_DN<17>")
	)
	(segment
		(start 72.297544 -151.2062)
		(end 72.576944 -150.9268)
		(width 0.14224)
		(layer "In11.Cu")
		(net "M_M_DQS_DN<17>")
	)
	(segment
		(start 72.170036 -152.49906)
		(end 72.328278 -152.340818)
		(width 0.14224)
		(layer "In11.Cu")
		(net "M_M_DQS_DN<17>")
	)
	(segment
		(start 72.576944 -150.9268)
		(end 72.576944 -150.523448)
		(width 0.14224)
		(layer "In11.Cu")
		(net "M_M_DQS_DN<17>")
	)
	(segment
		(start 71.906384 -151.35606)
		(end 72.056244 -151.2062)
		(width 0.14224)
		(layer "In11.Cu")
		(net "M_M_DQS_DN<17>")
	)
	(segment
		(start 72.328278 -152.340818)
		(end 72.328278 -151.987758)
		(width 0.14224)
		(layer "In11.Cu")
		(net "M_M_DQS_DN<17>")
	)
	(segment
		(start 72.1487 -154.2669)
		(end 72.592438 -153.823162)
		(width 0.14224)
		(layer "In11.Cu")
		(net "M_M_DQS_DN<17>")
	)
	(segment
		(start 72.328278 -151.987758)
		(end 72.17664 -151.83612)
		(width 0.14224)
		(layer "In11.Cu")
		(net "M_M_DQS_DN<17>")
	)
	(segment
		(start 71.906384 -152.63876)
		(end 72.046084 -152.49906)
		(width 0.14224)
		(layer "In11.Cu")
		(net "M_M_DQS_DN<17>")
	)
	(segment
		(start 71.906384 -152.924764)
		(end 71.906384 -152.63876)
		(width 0.14224)
		(layer "In11.Cu")
		(net "M_M_DQS_DN<17>")
	)
	(segment
		(start 72.592438 -153.285698)
		(end 72.389238 -153.082498)
		(width 0.14224)
		(layer "In11.Cu")
		(net "M_M_DQS_DN<17>")
	)
	(segment
		(start 146.307048 -154.45613)
		(end 146.117818 -154.2669)
		(width 0.1651)
		(layer "F.Cu")
		(net "M_M_DQS_DN<16>")
	)
	(segment
		(start 146.999452 -152.932384)
		(end 146.581368 -153.350468)
		(width 0.1651)
		(layer "F.Cu")
		(net "M_M_DQS_DN<16>")
	)
	(segment
		(start 146.767296 -154.204162)
		(end 146.515328 -154.45613)
		(width 0.1651)
		(layer "F.Cu")
		(net "M_M_DQS_DN<16>")
	)
	(segment
		(start 146.581368 -153.350468)
		(end 146.581368 -153.7716)
		(width 0.1651)
		(layer "F.Cu")
		(net "M_M_DQS_DN<16>")
	)
	(segment
		(start 146.999452 -152.273)
		(end 146.999452 -152.932384)
		(width 0.1651)
		(layer "F.Cu")
		(net "M_M_DQS_DN<16>")
	)
	(segment
		(start 146.117818 -154.2669)
		(end 146.098768 -154.2669)
		(width 0.1651)
		(layer "F.Cu")
		(net "M_M_DQS_DN<16>")
	)
	(segment
		(start 118.212362 -90.575384)
		(end 118.783862 -90.575384)
		(width 0.1651)
		(layer "F.Cu")
		(net "M_M_DQS_DN<16>")
	)
	(segment
		(start 146.515328 -154.45613)
		(end 146.307048 -154.45613)
		(width 0.1651)
		(layer "F.Cu")
		(net "M_M_DQS_DN<16>")
	)
	(segment
		(start 146.767296 -153.957528)
		(end 146.767296 -154.204162)
		(width 0.1651)
		(layer "F.Cu")
		(net "M_M_DQS_DN<16>")
	)
	(segment
		(start 146.581368 -153.7716)
		(end 146.767296 -153.957528)
		(width 0.1651)
		(layer "F.Cu")
		(net "M_M_DQS_DN<16>")
	)
	(via
		(at 146.092164 -150.0886)
		(size 0.508)
		(drill 0.254)
		(layers "F.Cu" "B.Cu")
		(net "M_M_DQS_DN<16>")
	)
	(via
		(at 118.783862 -90.575384)
		(size 0.508)
		(drill 0.254)
		(layers "F.Cu" "B.Cu")
		(net "M_M_DQS_DN<16>")
	)
	(via
		(at 146.098768 -154.2669)
		(size 0.508)
		(drill 0.254)
		(layers "F.Cu" "B.Cu")
		(net "M_M_DQS_DN<16>")
	)
	(segment
		(start 146.555968 -150.977854)
		(end 146.555968 -150.622)
		(width 0.1651)
		(layer "B.Cu")
		(net "M_M_DQS_DN<16>")
	)
	(segment
		(start 146.286728 -149.894036)
		(end 146.092164 -150.0886)
		(width 0.1651)
		(layer "B.Cu")
		(net "M_M_DQS_DN<16>")
	)
	(segment
		(start 146.999452 -152.078436)
		(end 146.999706 -152.077928)
		(width 0.1651)
		(layer "B.Cu")
		(net "M_M_DQS_DN<16>")
	)
	(segment
		(start 146.733768 -150.4442)
		(end 146.733768 -150.114)
		(width 0.1651)
		(layer "B.Cu")
		(net "M_M_DQS_DN<16>")
	)
	(segment
		(start 146.999706 -152.077928)
		(end 146.999706 -151.421592)
		(width 0.1651)
		(layer "B.Cu")
		(net "M_M_DQS_DN<16>")
	)
	(segment
		(start 146.555968 -150.622)
		(end 146.733768 -150.4442)
		(width 0.1651)
		(layer "B.Cu")
		(net "M_M_DQS_DN<16>")
	)
	(segment
		(start 146.733768 -150.114)
		(end 146.513804 -149.894036)
		(width 0.1651)
		(layer "B.Cu")
		(net "M_M_DQS_DN<16>")
	)
	(segment
		(start 146.513804 -149.894036)
		(end 146.286728 -149.894036)
		(width 0.1651)
		(layer "B.Cu")
		(net "M_M_DQS_DN<16>")
	)
	(segment
		(start 146.999706 -151.421592)
		(end 146.555968 -150.977854)
		(width 0.1651)
		(layer "B.Cu")
		(net "M_M_DQS_DN<16>")
	)
	(segment
		(start 132.973826 -112.69218)
		(end 133.265926 -112.98428)
		(width 0.14224)
		(layer "In11.Cu")
		(net "M_M_DQS_DN<16>")
	)
	(segment
		(start 123.594368 -102.252018)
		(end 123.588018 -102.262686)
		(width 0.0889)
		(layer "In11.Cu")
		(net "M_M_DQS_DN<16>")
	)
	(segment
		(start 146.531838 -153.349706)
		(end 146.531838 -153.83383)
		(width 0.14224)
		(layer "In11.Cu")
		(net "M_M_DQS_DN<16>")
	)
	(segment
		(start 123.065032 -96.423988)
		(end 123.097798 -96.423988)
		(width 0.0889)
		(layer "In11.Cu")
		(net "M_M_DQS_DN<16>")
	)
	(segment
		(start 124.782072 -103.358188)
		(end 124.854462 -103.358188)
		(width 0.0889)
		(layer "In11.Cu")
		(net "M_M_DQS_DN<16>")
	)
	(segment
		(start 123.588018 -97.309686)
		(end 123.583192 -97.318322)
		(width 0.0889)
		(layer "In11.Cu")
		(net "M_M_DQS_DN<16>")
	)
	(segment
		(start 146.143472 -151.83612)
		(end 146.298412 -151.99106)
		(width 0.14224)
		(layer "In11.Cu")
		(net "M_M_DQS_DN<16>")
	)
	(segment
		(start 118.437152 -92.356686)
		(end 118.432326 -92.365322)
		(width 0.0889)
		(layer "In11.Cu")
		(net "M_M_DQS_DN<16>")
	)
	(segment
		(start 121.012712 -95.232982)
		(end 121.016014 -95.238824)
		(width 0.0889)
		(layer "In11.Cu")
		(net "M_M_DQS_DN<16>")
	)
	(segment
		(start 123.588018 -102.262686)
		(end 123.583192 -102.271322)
		(width 0.0889)
		(layer "In11.Cu")
		(net "M_M_DQS_DN<16>")
	)
	(segment
		(start 145.856452 -151.70404)
		(end 145.988532 -151.83612)
		(width 0.14224)
		(layer "In11.Cu")
		(net "M_M_DQS_DN<16>")
	)
	(segment
		(start 118.443502 -93.336618)
		(end 118.437152 -93.347286)
		(width 0.0889)
		(layer "In11.Cu")
		(net "M_M_DQS_DN<16>")
	)
	(segment
		(start 127.726948 -107.45978)
		(end 129.335784 -107.45978)
		(width 0.14224)
		(layer "In11.Cu")
		(net "M_M_DQS_DN<16>")
	)
	(segment
		(start 125.017022 -104.463342)
		(end 125.056392 -104.502712)
		(width 0.0889)
		(layer "In11.Cu")
		(net "M_M_DQS_DN<16>")
	)
	(segment
		(start 145.988532 -151.83612)
		(end 146.143472 -151.83612)
		(width 0.14224)
		(layer "In11.Cu")
		(net "M_M_DQS_DN<16>")
	)
	(segment
		(start 146.247612 -151.2062)
		(end 146.006312 -151.2062)
		(width 0.14224)
		(layer "In11.Cu")
		(net "M_M_DQS_DN<16>")
	)
	(segment
		(start 145.856452 -151.35606)
		(end 145.856452 -151.70404)
		(width 0.14224)
		(layer "In11.Cu")
		(net "M_M_DQS_DN<16>")
	)
	(segment
		(start 125.056392 -104.789224)
		(end 127.726948 -107.45978)
		(width 0.14224)
		(layer "In11.Cu")
		(net "M_M_DQS_DN<16>")
	)
	(segment
		(start 118.768876 -93.947234)
		(end 118.796816 -93.947234)
		(width 0.0889)
		(layer "In11.Cu")
		(net "M_M_DQS_DN<16>")
	)
	(segment
		(start 123.594368 -98.289618)
		(end 123.588018 -98.300286)
		(width 0.0889)
		(layer "In11.Cu")
		(net "M_M_DQS_DN<16>")
	)
	(segment
		(start 145.856452 -152.63876)
		(end 145.856452 -152.99944)
		(width 0.14224)
		(layer "In11.Cu")
		(net "M_M_DQS_DN<16>")
	)
	(segment
		(start 123.594368 -99.280218)
		(end 123.588018 -99.290886)
		(width 0.0889)
		(layer "In11.Cu")
		(net "M_M_DQS_DN<16>")
	)
	(segment
		(start 145.996152 -152.49906)
		(end 145.856452 -152.63876)
		(width 0.14224)
		(layer "In11.Cu")
		(net "M_M_DQS_DN<16>")
	)
	(segment
		(start 118.783862 -90.575384)
		(end 118.783862 -90.23731)
		(width 0.0889)
		(layer "In11.Cu")
		(net "M_M_DQS_DN<16>")
	)
	(segment
		(start 136.63676 -112.98428)
		(end 146.874484 -123.222004)
		(width 0.14224)
		(layer "In11.Cu")
		(net "M_M_DQS_DN<16>")
	)
	(segment
		(start 122.202702 -95.928434)
		(end 122.235468 -95.928434)
		(width 0.0889)
		(layer "In11.Cu")
		(net "M_M_DQS_DN<16>")
	)
	(segment
		(start 146.092164 -150.0886)
		(end 146.527012 -150.523448)
		(width 0.14224)
		(layer "In11.Cu")
		(net "M_M_DQS_DN<16>")
	)
	(segment
		(start 146.298412 -151.99106)
		(end 146.298412 -152.34412)
		(width 0.14224)
		(layer "In11.Cu")
		(net "M_M_DQS_DN<16>")
	)
	(segment
		(start 123.588018 -101.272086)
		(end 123.583192 -101.280722)
		(width 0.0889)
		(layer "In11.Cu")
		(net "M_M_DQS_DN<16>")
	)
	(segment
		(start 146.143472 -152.49906)
		(end 145.996152 -152.49906)
		(width 0.14224)
		(layer "In11.Cu")
		(net "M_M_DQS_DN<16>")
	)
	(segment
		(start 146.527012 -150.523448)
		(end 146.527012 -150.9268)
		(width 0.14224)
		(layer "In11.Cu")
		(net "M_M_DQS_DN<16>")
	)
	(segment
		(start 146.019012 -153.162)
		(end 146.344132 -153.162)
		(width 0.14224)
		(layer "In11.Cu")
		(net "M_M_DQS_DN<16>")
	)
	(segment
		(start 125.056392 -104.502712)
		(end 125.056392 -104.52481)
		(width 0.0889)
		(layer "In11.Cu")
		(net "M_M_DQS_DN<16>")
	)
	(segment
		(start 119.624348 -94.442534)
		(end 119.660162 -94.442534)
		(width 0.0889)
		(layer "In11.Cu")
		(net "M_M_DQS_DN<16>")
	)
	(segment
		(start 146.344132 -153.162)
		(end 146.531838 -153.349706)
		(width 0.14224)
		(layer "In11.Cu")
		(net "M_M_DQS_DN<16>")
	)
	(segment
		(start 123.919742 -102.862634)
		(end 123.952508 -102.862634)
		(width 0.0889)
		(layer "In11.Cu")
		(net "M_M_DQS_DN<16>")
	)
	(segment
		(start 118.437152 -91.366086)
		(end 118.432326 -91.374722)
		(width 0.0889)
		(layer "In11.Cu")
		(net "M_M_DQS_DN<16>")
	)
	(segment
		(start 118.443502 -91.355418)
		(end 118.437152 -91.366086)
		(width 0.0889)
		(layer "In11.Cu")
		(net "M_M_DQS_DN<16>")
	)
	(segment
		(start 145.856452 -152.99944)
		(end 146.019012 -153.162)
		(width 0.14224)
		(layer "In11.Cu")
		(net "M_M_DQS_DN<16>")
	)
	(segment
		(start 125.056392 -104.52481)
		(end 125.056392 -104.789224)
		(width 0.14224)
		(layer "In11.Cu")
		(net "M_M_DQS_DN<16>")
	)
	(segment
		(start 123.594368 -101.261418)
		(end 123.588018 -101.272086)
		(width 0.0889)
		(layer "In11.Cu")
		(net "M_M_DQS_DN<16>")
	)
	(segment
		(start 146.874484 -123.222004)
		(end 146.874484 -149.30628)
		(width 0.14224)
		(layer "In11.Cu")
		(net "M_M_DQS_DN<16>")
	)
	(segment
		(start 146.874484 -149.30628)
		(end 146.092164 -150.0886)
		(width 0.14224)
		(layer "In11.Cu")
		(net "M_M_DQS_DN<16>")
	)
	(segment
		(start 125.017022 -103.520748)
		(end 125.017022 -104.463342)
		(width 0.0889)
		(layer "In11.Cu")
		(net "M_M_DQS_DN<16>")
	)
	(segment
		(start 120.482868 -94.937834)
		(end 120.522492 -94.937834)
		(width 0.0889)
		(layer "In11.Cu")
		(net "M_M_DQS_DN<16>")
	)
	(segment
		(start 121.359168 -95.433134)
		(end 121.372122 -95.433134)
		(width 0.0889)
		(layer "In11.Cu")
		(net "M_M_DQS_DN<16>")
	)
	(segment
		(start 146.527012 -150.9268)
		(end 146.247612 -151.2062)
		(width 0.14224)
		(layer "In11.Cu")
		(net "M_M_DQS_DN<16>")
	)
	(segment
		(start 118.443502 -92.346018)
		(end 118.437152 -92.356686)
		(width 0.0889)
		(layer "In11.Cu")
		(net "M_M_DQS_DN<16>")
	)
	(segment
		(start 132.973826 -111.097822)
		(end 132.973826 -112.69218)
		(width 0.14224)
		(layer "In11.Cu")
		(net "M_M_DQS_DN<16>")
	)
	(segment
		(start 146.298412 -152.34412)
		(end 146.143472 -152.49906)
		(width 0.14224)
		(layer "In11.Cu")
		(net "M_M_DQS_DN<16>")
	)
	(segment
		(start 124.854462 -103.358188)
		(end 125.017022 -103.520748)
		(width 0.0889)
		(layer "In11.Cu")
		(net "M_M_DQS_DN<16>")
	)
	(segment
		(start 123.594368 -97.299018)
		(end 123.588018 -97.309686)
		(width 0.0889)
		(layer "In11.Cu")
		(net "M_M_DQS_DN<16>")
	)
	(segment
		(start 133.265926 -112.98428)
		(end 136.63676 -112.98428)
		(width 0.14224)
		(layer "In11.Cu")
		(net "M_M_DQS_DN<16>")
	)
	(segment
		(start 118.783862 -90.23731)
		(end 118.72595 -90.179398)
		(width 0.0889)
		(layer "In11.Cu")
		(net "M_M_DQS_DN<16>")
	)
	(segment
		(start 129.335784 -107.45978)
		(end 132.973826 -111.097822)
		(width 0.14224)
		(layer "In11.Cu")
		(net "M_M_DQS_DN<16>")
	)
	(segment
		(start 146.006312 -151.2062)
		(end 145.856452 -151.35606)
		(width 0.14224)
		(layer "In11.Cu")
		(net "M_M_DQS_DN<16>")
	)
	(segment
		(start 118.437152 -93.347286)
		(end 118.432326 -93.355922)
		(width 0.0889)
		(layer "In11.Cu")
		(net "M_M_DQS_DN<16>")
	)
	(segment
		(start 146.531838 -153.83383)
		(end 146.098768 -154.2669)
		(width 0.14224)
		(layer "In11.Cu")
		(net "M_M_DQS_DN<16>")
	)
	(segment
		(start 123.588018 -99.290886)
		(end 123.583192 -99.299522)
		(width 0.0889)
		(layer "In11.Cu")
		(net "M_M_DQS_DN<16>")
	)
	(segment
		(start 123.588018 -98.300286)
		(end 123.583192 -98.308922)
		(width 0.0889)
		(layer "In11.Cu")
		(net "M_M_DQS_DN<16>")
	)
	(arc
		(start 118.432326 -93.355922)
		(mid 118.436073 -93.745178)
		(end 118.768876 -93.947234)
		(width 0.0889)
		(layer "In11.Cu")
		(net "M_M_DQS_DN<16>")
	)
	(arc
		(start 118.72595 -90.179398)
		(mid 118.423681 -90.400947)
		(end 118.437152 -90.775536)
		(width 0.0889)
		(layer "In11.Cu")
		(net "M_M_DQS_DN<16>")
	)
	(arc
		(start 119.295672 -94.242636)
		(mid 119.434416 -94.384669)
		(end 119.624348 -94.442534)
		(width 0.0889)
		(layer "In11.Cu")
		(net "M_M_DQS_DN<16>")
	)
	(arc
		(start 124.446538 -103.158036)
		(mid 124.588221 -103.30184)
		(end 124.782072 -103.358188)
		(width 0.0889)
		(layer "In11.Cu")
		(net "M_M_DQS_DN<16>")
	)
	(arc
		(start 120.522492 -94.937834)
		(mid 120.805709 -95.022115)
		(end 121.012712 -95.232982)
		(width 0.0889)
		(layer "In11.Cu")
		(net "M_M_DQS_DN<16>")
	)
	(arc
		(start 123.097798 -96.423988)
		(mid 123.590188 -96.722921)
		(end 123.594368 -97.299018)
		(width 0.0889)
		(layer "In11.Cu")
		(net "M_M_DQS_DN<16>")
	)
	(arc
		(start 118.796816 -93.947234)
		(mid 119.084961 -94.029553)
		(end 119.295672 -94.242636)
		(width 0.0889)
		(layer "In11.Cu")
		(net "M_M_DQS_DN<16>")
	)
	(arc
		(start 118.437152 -91.766136)
		(mid 118.516374 -92.055254)
		(end 118.443502 -92.346018)
		(width 0.0889)
		(layer "In11.Cu")
		(net "M_M_DQS_DN<16>")
	)
	(arc
		(start 123.588018 -98.700336)
		(mid 123.66724 -98.989454)
		(end 123.594368 -99.280218)
		(width 0.0889)
		(layer "In11.Cu")
		(net "M_M_DQS_DN<16>")
	)
	(arc
		(start 123.583192 -101.280722)
		(mid 123.534437 -101.477074)
		(end 123.588018 -101.672136)
		(width 0.0889)
		(layer "In11.Cu")
		(net "M_M_DQS_DN<16>")
	)
	(arc
		(start 123.588018 -100.28174)
		(mid 123.534519 -100.481638)
		(end 123.588018 -100.681536)
		(width 0.0889)
		(layer "In11.Cu")
		(net "M_M_DQS_DN<16>")
	)
	(arc
		(start 123.583192 -97.318322)
		(mid 123.534437 -97.514674)
		(end 123.588018 -97.709736)
		(width 0.0889)
		(layer "In11.Cu")
		(net "M_M_DQS_DN<16>")
	)
	(arc
		(start 123.583192 -99.299522)
		(mid 123.534437 -99.495874)
		(end 123.588018 -99.690936)
		(width 0.0889)
		(layer "In11.Cu")
		(net "M_M_DQS_DN<16>")
	)
	(arc
		(start 118.432326 -92.365322)
		(mid 118.383571 -92.561674)
		(end 118.437152 -92.756736)
		(width 0.0889)
		(layer "In11.Cu")
		(net "M_M_DQS_DN<16>")
	)
	(arc
		(start 121.870978 -95.728536)
		(mid 122.011057 -95.871272)
		(end 122.202702 -95.928434)
		(width 0.0889)
		(layer "In11.Cu")
		(net "M_M_DQS_DN<16>")
	)
	(arc
		(start 123.588018 -97.709736)
		(mid 123.66724 -97.998854)
		(end 123.594368 -98.289618)
		(width 0.0889)
		(layer "In11.Cu")
		(net "M_M_DQS_DN<16>")
	)
	(arc
		(start 123.588018 -100.681536)
		(mid 123.66724 -100.970654)
		(end 123.594368 -101.261418)
		(width 0.0889)
		(layer "In11.Cu")
		(net "M_M_DQS_DN<16>")
	)
	(arc
		(start 122.729498 -96.223836)
		(mid 122.871181 -96.36764)
		(end 123.065032 -96.423988)
		(width 0.0889)
		(layer "In11.Cu")
		(net "M_M_DQS_DN<16>")
	)
	(arc
		(start 121.372122 -95.433134)
		(mid 121.660267 -95.515453)
		(end 121.870978 -95.728536)
		(width 0.0889)
		(layer "In11.Cu")
		(net "M_M_DQS_DN<16>")
	)
	(arc
		(start 118.437152 -92.756736)
		(mid 118.516374 -93.045854)
		(end 118.443502 -93.336618)
		(width 0.0889)
		(layer "In11.Cu")
		(net "M_M_DQS_DN<16>")
	)
	(arc
		(start 123.583192 -102.271322)
		(mid 123.586939 -102.660578)
		(end 123.919742 -102.862634)
		(width 0.0889)
		(layer "In11.Cu")
		(net "M_M_DQS_DN<16>")
	)
	(arc
		(start 118.437152 -90.775536)
		(mid 118.516374 -91.064654)
		(end 118.443502 -91.355418)
		(width 0.0889)
		(layer "In11.Cu")
		(net "M_M_DQS_DN<16>")
	)
	(arc
		(start 120.154192 -94.737936)
		(mid 120.292936 -94.879969)
		(end 120.482868 -94.937834)
		(width 0.0889)
		(layer "In11.Cu")
		(net "M_M_DQS_DN<16>")
	)
	(arc
		(start 123.588018 -99.690936)
		(mid 123.667149 -99.986338)
		(end 123.588018 -100.28174)
		(width 0.0889)
		(layer "In11.Cu")
		(net "M_M_DQS_DN<16>")
	)
	(arc
		(start 118.432326 -91.374722)
		(mid 118.383571 -91.571074)
		(end 118.437152 -91.766136)
		(width 0.0889)
		(layer "In11.Cu")
		(net "M_M_DQS_DN<16>")
	)
	(arc
		(start 119.660162 -94.442534)
		(mid 119.945586 -94.526001)
		(end 120.154192 -94.737936)
		(width 0.0889)
		(layer "In11.Cu")
		(net "M_M_DQS_DN<16>")
	)
	(arc
		(start 122.235468 -95.928434)
		(mid 122.520892 -96.011901)
		(end 122.729498 -96.223836)
		(width 0.0889)
		(layer "In11.Cu")
		(net "M_M_DQS_DN<16>")
	)
	(arc
		(start 121.016014 -95.238824)
		(mid 121.16198 -95.381223)
		(end 121.359168 -95.433134)
		(width 0.0889)
		(layer "In11.Cu")
		(net "M_M_DQS_DN<16>")
	)
	(arc
		(start 123.588018 -101.672136)
		(mid 123.66724 -101.961254)
		(end 123.594368 -102.252018)
		(width 0.0889)
		(layer "In11.Cu")
		(net "M_M_DQS_DN<16>")
	)
	(arc
		(start 123.583192 -98.308922)
		(mid 123.534437 -98.505274)
		(end 123.588018 -98.700336)
		(width 0.0889)
		(layer "In11.Cu")
		(net "M_M_DQS_DN<16>")
	)
	(arc
		(start 123.952508 -102.862634)
		(mid 124.237932 -102.946101)
		(end 124.446538 -103.158036)
		(width 0.0889)
		(layer "In11.Cu")
		(net "M_M_DQS_DN<16>")
	)
	(segment
		(start 137.417302 -153.957528)
		(end 137.417302 -154.204162)
		(width 0.1651)
		(layer "F.Cu")
		(net "M_M_DQS_DN<15>")
	)
	(segment
		(start 137.649458 -152.932384)
		(end 137.231374 -153.350468)
		(width 0.1651)
		(layer "F.Cu")
		(net "M_M_DQS_DN<15>")
	)
	(segment
		(start 137.417302 -154.204162)
		(end 137.165334 -154.45613)
		(width 0.1651)
		(layer "F.Cu")
		(net "M_M_DQS_DN<15>")
	)
	(segment
		(start 136.767824 -154.2669)
		(end 136.748774 -154.2669)
		(width 0.1651)
		(layer "F.Cu")
		(net "M_M_DQS_DN<15>")
	)
	(segment
		(start 137.649458 -152.273)
		(end 137.649458 -152.932384)
		(width 0.1651)
		(layer "F.Cu")
		(net "M_M_DQS_DN<15>")
	)
	(segment
		(start 137.165334 -154.45613)
		(end 136.957054 -154.45613)
		(width 0.1651)
		(layer "F.Cu")
		(net "M_M_DQS_DN<15>")
	)
	(segment
		(start 137.231374 -153.7716)
		(end 137.417302 -153.957528)
		(width 0.1651)
		(layer "F.Cu")
		(net "M_M_DQS_DN<15>")
	)
	(segment
		(start 137.231374 -153.350468)
		(end 137.231374 -153.7716)
		(width 0.1651)
		(layer "F.Cu")
		(net "M_M_DQS_DN<15>")
	)
	(segment
		(start 113.061242 -90.575384)
		(end 113.632742 -90.575384)
		(width 0.1651)
		(layer "F.Cu")
		(net "M_M_DQS_DN<15>")
	)
	(segment
		(start 136.957054 -154.45613)
		(end 136.767824 -154.2669)
		(width 0.1651)
		(layer "F.Cu")
		(net "M_M_DQS_DN<15>")
	)
	(via
		(at 136.748774 -154.2669)
		(size 0.508)
		(drill 0.254)
		(layers "F.Cu" "B.Cu")
		(net "M_M_DQS_DN<15>")
	)
	(via
		(at 113.632742 -90.575384)
		(size 0.508)
		(drill 0.254)
		(layers "F.Cu" "B.Cu")
		(net "M_M_DQS_DN<15>")
	)
	(via
		(at 136.74217 -150.0886)
		(size 0.508)
		(drill 0.254)
		(layers "F.Cu" "B.Cu")
		(net "M_M_DQS_DN<15>")
	)
	(segment
		(start 137.649458 -152.078436)
		(end 137.649458 -151.421338)
		(width 0.1651)
		(layer "B.Cu")
		(net "M_M_DQS_DN<15>")
	)
	(segment
		(start 137.383774 -150.4442)
		(end 137.383774 -150.114)
		(width 0.1651)
		(layer "B.Cu")
		(net "M_M_DQS_DN<15>")
	)
	(segment
		(start 137.649458 -151.421338)
		(end 137.205974 -150.977854)
		(width 0.1651)
		(layer "B.Cu")
		(net "M_M_DQS_DN<15>")
	)
	(segment
		(start 137.383774 -150.114)
		(end 137.16381 -149.894036)
		(width 0.1651)
		(layer "B.Cu")
		(net "M_M_DQS_DN<15>")
	)
	(segment
		(start 137.205974 -150.622)
		(end 137.383774 -150.4442)
		(width 0.1651)
		(layer "B.Cu")
		(net "M_M_DQS_DN<15>")
	)
	(segment
		(start 137.16381 -149.894036)
		(end 136.936734 -149.894036)
		(width 0.1651)
		(layer "B.Cu")
		(net "M_M_DQS_DN<15>")
	)
	(segment
		(start 137.205974 -150.977854)
		(end 137.205974 -150.622)
		(width 0.1651)
		(layer "B.Cu")
		(net "M_M_DQS_DN<15>")
	)
	(segment
		(start 136.936734 -149.894036)
		(end 136.74217 -150.0886)
		(width 0.1651)
		(layer "B.Cu")
		(net "M_M_DQS_DN<15>")
	)
	(segment
		(start 113.632742 -90.575384)
		(end 113.632742 -90.23731)
		(width 0.0889)
		(layer "In11.Cu")
		(net "M_M_DQS_DN<15>")
	)
	(segment
		(start 113.286032 -96.319086)
		(end 113.281206 -96.327722)
		(width 0.0889)
		(layer "In11.Cu")
		(net "M_M_DQS_DN<15>")
	)
	(segment
		(start 117.578632 -102.166928)
		(end 117.584982 -102.177596)
		(width 0.0889)
		(layer "In11.Cu")
		(net "M_M_DQS_DN<15>")
	)
	(segment
		(start 136.669018 -153.162)
		(end 136.994138 -153.162)
		(width 0.14224)
		(layer "In11.Cu")
		(net "M_M_DQS_DN<15>")
	)
	(segment
		(start 133.802882 -120.591072)
		(end 137.52449 -124.31268)
		(width 0.14224)
		(layer "In11.Cu")
		(net "M_M_DQS_DN<15>")
	)
	(segment
		(start 137.181844 -153.83383)
		(end 136.748774 -154.2669)
		(width 0.14224)
		(layer "In11.Cu")
		(net "M_M_DQS_DN<15>")
	)
	(segment
		(start 136.948418 -151.99106)
		(end 136.948418 -152.34412)
		(width 0.14224)
		(layer "In11.Cu")
		(net "M_M_DQS_DN<15>")
	)
	(segment
		(start 137.177018 -150.9268)
		(end 136.897618 -151.2062)
		(width 0.14224)
		(layer "In11.Cu")
		(net "M_M_DQS_DN<15>")
	)
	(segment
		(start 136.506458 -152.63876)
		(end 136.506458 -152.99944)
		(width 0.14224)
		(layer "In11.Cu")
		(net "M_M_DQS_DN<15>")
	)
	(segment
		(start 136.948418 -152.34412)
		(end 136.793478 -152.49906)
		(width 0.14224)
		(layer "In11.Cu")
		(net "M_M_DQS_DN<15>")
	)
	(segment
		(start 117.52326 -107.188)
		(end 117.52326 -113.131092)
		(width 0.14224)
		(layer "In11.Cu")
		(net "M_M_DQS_DN<15>")
	)
	(segment
		(start 113.286032 -95.328486)
		(end 113.281206 -95.337122)
		(width 0.0889)
		(layer "In11.Cu")
		(net "M_M_DQS_DN<15>")
	)
	(segment
		(start 124.98324 -120.591072)
		(end 133.802882 -120.591072)
		(width 0.14224)
		(layer "In11.Cu")
		(net "M_M_DQS_DN<15>")
	)
	(segment
		(start 136.506458 -151.35606)
		(end 136.506458 -151.70404)
		(width 0.14224)
		(layer "In11.Cu")
		(net "M_M_DQS_DN<15>")
	)
	(segment
		(start 136.646158 -152.49906)
		(end 136.506458 -152.63876)
		(width 0.14224)
		(layer "In11.Cu")
		(net "M_M_DQS_DN<15>")
	)
	(segment
		(start 117.52326 -107.165902)
		(end 117.52326 -107.188)
		(width 0.0889)
		(layer "In11.Cu")
		(net "M_M_DQS_DN<15>")
	)
	(segment
		(start 117.571774 -105.12679)
		(end 117.587522 -105.154222)
		(width 0.0889)
		(layer "In11.Cu")
		(net "M_M_DQS_DN<15>")
	)
	(segment
		(start 136.638538 -151.83612)
		(end 136.793478 -151.83612)
		(width 0.14224)
		(layer "In11.Cu")
		(net "M_M_DQS_DN<15>")
	)
	(segment
		(start 136.793478 -151.83612)
		(end 136.948418 -151.99106)
		(width 0.14224)
		(layer "In11.Cu")
		(net "M_M_DQS_DN<15>")
	)
	(segment
		(start 136.656318 -151.2062)
		(end 136.506458 -151.35606)
		(width 0.14224)
		(layer "In11.Cu")
		(net "M_M_DQS_DN<15>")
	)
	(segment
		(start 116.197126 -98.405188)
		(end 116.229892 -98.405188)
		(width 0.0889)
		(layer "In11.Cu")
		(net "M_M_DQS_DN<15>")
	)
	(segment
		(start 137.157968 -149.573488)
		(end 137.157968 -149.672802)
		(width 0.14224)
		(layer "In11.Cu")
		(net "M_M_DQS_DN<15>")
	)
	(segment
		(start 113.286032 -93.347286)
		(end 113.281206 -93.355922)
		(width 0.0889)
		(layer "In11.Cu")
		(net "M_M_DQS_DN<15>")
	)
	(segment
		(start 117.571774 -104.13619)
		(end 117.587522 -104.163622)
		(width 0.0889)
		(layer "In11.Cu")
		(net "M_M_DQS_DN<15>")
	)
	(segment
		(start 117.571774 -103.14559)
		(end 117.587522 -103.173022)
		(width 0.0889)
		(layer "In11.Cu")
		(net "M_M_DQS_DN<15>")
	)
	(segment
		(start 117.52326 -113.131092)
		(end 124.98324 -120.591072)
		(width 0.14224)
		(layer "In11.Cu")
		(net "M_M_DQS_DN<15>")
	)
	(segment
		(start 113.286032 -92.356686)
		(end 113.281206 -92.365322)
		(width 0.0889)
		(layer "In11.Cu")
		(net "M_M_DQS_DN<15>")
	)
	(segment
		(start 113.617756 -96.919034)
		(end 113.650522 -96.919034)
		(width 0.0889)
		(layer "In11.Cu")
		(net "M_M_DQS_DN<15>")
	)
	(segment
		(start 114.480086 -97.414588)
		(end 114.512852 -97.414588)
		(width 0.0889)
		(layer "In11.Cu")
		(net "M_M_DQS_DN<15>")
	)
	(segment
		(start 136.793478 -152.49906)
		(end 136.646158 -152.49906)
		(width 0.14224)
		(layer "In11.Cu")
		(net "M_M_DQS_DN<15>")
	)
	(segment
		(start 115.334796 -97.909634)
		(end 115.367562 -97.909634)
		(width 0.0889)
		(layer "In11.Cu")
		(net "M_M_DQS_DN<15>")
	)
	(segment
		(start 113.292382 -92.346018)
		(end 113.286032 -92.356686)
		(width 0.0889)
		(layer "In11.Cu")
		(net "M_M_DQS_DN<15>")
	)
	(segment
		(start 113.632742 -90.23731)
		(end 113.57483 -90.179398)
		(width 0.0889)
		(layer "In11.Cu")
		(net "M_M_DQS_DN<15>")
	)
	(segment
		(start 113.292382 -96.308418)
		(end 113.286032 -96.319086)
		(width 0.0889)
		(layer "In11.Cu")
		(net "M_M_DQS_DN<15>")
	)
	(segment
		(start 136.506458 -151.70404)
		(end 136.638538 -151.83612)
		(width 0.14224)
		(layer "In11.Cu")
		(net "M_M_DQS_DN<15>")
	)
	(segment
		(start 136.897618 -151.2062)
		(end 136.656318 -151.2062)
		(width 0.14224)
		(layer "In11.Cu")
		(net "M_M_DQS_DN<15>")
	)
	(segment
		(start 117.584982 -100.76561)
		(end 117.578632 -100.776278)
		(width 0.0889)
		(layer "In11.Cu")
		(net "M_M_DQS_DN<15>")
	)
	(segment
		(start 137.52449 -149.206966)
		(end 137.157968 -149.573488)
		(width 0.14224)
		(layer "In11.Cu")
		(net "M_M_DQS_DN<15>")
	)
	(segment
		(start 113.292382 -93.336618)
		(end 113.286032 -93.347286)
		(width 0.0889)
		(layer "In11.Cu")
		(net "M_M_DQS_DN<15>")
	)
	(segment
		(start 137.177018 -150.523448)
		(end 137.177018 -150.9268)
		(width 0.14224)
		(layer "In11.Cu")
		(net "M_M_DQS_DN<15>")
	)
	(segment
		(start 117.578886 -105.729532)
		(end 117.578632 -105.729532)
		(width 0.0889)
		(layer "In11.Cu")
		(net "M_M_DQS_DN<15>")
	)
	(segment
		(start 117.578632 -100.776278)
		(end 117.573806 -100.784914)
		(width 0.0889)
		(layer "In11.Cu")
		(net "M_M_DQS_DN<15>")
	)
	(segment
		(start 113.286032 -91.366086)
		(end 113.281206 -91.374722)
		(width 0.0889)
		(layer "In11.Cu")
		(net "M_M_DQS_DN<15>")
	)
	(segment
		(start 117.051836 -98.900234)
		(end 117.084602 -98.900234)
		(width 0.0889)
		(layer "In11.Cu")
		(net "M_M_DQS_DN<15>")
	)
	(segment
		(start 113.286032 -94.737936)
		(end 113.292382 -94.748604)
		(width 0.0889)
		(layer "In11.Cu")
		(net "M_M_DQS_DN<15>")
	)
	(segment
		(start 117.48389 -105.893362)
		(end 117.48389 -107.126532)
		(width 0.0889)
		(layer "In11.Cu")
		(net "M_M_DQS_DN<15>")
	)
	(segment
		(start 136.74217 -150.0886)
		(end 137.177018 -150.523448)
		(width 0.14224)
		(layer "In11.Cu")
		(net "M_M_DQS_DN<15>")
	)
	(segment
		(start 117.578632 -105.729532)
		(end 117.48389 -105.893362)
		(width 0.0889)
		(layer "In11.Cu")
		(net "M_M_DQS_DN<15>")
	)
	(segment
		(start 137.157968 -149.672802)
		(end 136.74217 -150.0886)
		(width 0.14224)
		(layer "In11.Cu")
		(net "M_M_DQS_DN<15>")
	)
	(segment
		(start 137.181844 -153.349706)
		(end 137.181844 -153.83383)
		(width 0.14224)
		(layer "In11.Cu")
		(net "M_M_DQS_DN<15>")
	)
	(segment
		(start 136.506458 -152.99944)
		(end 136.669018 -153.162)
		(width 0.14224)
		(layer "In11.Cu")
		(net "M_M_DQS_DN<15>")
	)
	(segment
		(start 136.994138 -153.162)
		(end 137.181844 -153.349706)
		(width 0.14224)
		(layer "In11.Cu")
		(net "M_M_DQS_DN<15>")
	)
	(segment
		(start 117.48389 -107.126532)
		(end 117.52326 -107.165902)
		(width 0.0889)
		(layer "In11.Cu")
		(net "M_M_DQS_DN<15>")
	)
	(segment
		(start 137.52449 -124.31268)
		(end 137.52449 -149.206966)
		(width 0.14224)
		(layer "In11.Cu")
		(net "M_M_DQS_DN<15>")
	)
	(segment
		(start 113.292382 -91.355418)
		(end 113.286032 -91.366086)
		(width 0.0889)
		(layer "In11.Cu")
		(net "M_M_DQS_DN<15>")
	)
	(arc
		(start 114.144552 -97.214436)
		(mid 114.286235 -97.35824)
		(end 114.480086 -97.414588)
		(width 0.0889)
		(layer "In11.Cu")
		(net "M_M_DQS_DN<15>")
	)
	(arc
		(start 116.229892 -98.405188)
		(mid 116.513109 -98.489469)
		(end 116.720112 -98.700336)
		(width 0.0889)
		(layer "In11.Cu")
		(net "M_M_DQS_DN<15>")
	)
	(arc
		(start 113.650522 -96.919034)
		(mid 113.935946 -97.002501)
		(end 114.144552 -97.214436)
		(width 0.0889)
		(layer "In11.Cu")
		(net "M_M_DQS_DN<15>")
	)
	(arc
		(start 117.578632 -102.757986)
		(mid 117.525194 -102.950891)
		(end 117.571774 -103.14559)
		(width 0.0889)
		(layer "In11.Cu")
		(net "M_M_DQS_DN<15>")
	)
	(arc
		(start 117.587522 -104.163622)
		(mid 117.657919 -104.452573)
		(end 117.578632 -104.739186)
		(width 0.0889)
		(layer "In11.Cu")
		(net "M_M_DQS_DN<15>")
	)
	(arc
		(start 115.367562 -97.909634)
		(mid 115.652986 -97.993101)
		(end 115.861592 -98.205036)
		(width 0.0889)
		(layer "In11.Cu")
		(net "M_M_DQS_DN<15>")
	)
	(arc
		(start 117.084602 -98.900234)
		(mid 117.5828 -99.202978)
		(end 117.578632 -99.785932)
		(width 0.0889)
		(layer "In11.Cu")
		(net "M_M_DQS_DN<15>")
	)
	(arc
		(start 117.587522 -105.154222)
		(mid 117.657921 -105.442999)
		(end 117.578886 -105.729532)
		(width 0.0889)
		(layer "In11.Cu")
		(net "M_M_DQS_DN<15>")
	)
	(arc
		(start 113.286032 -92.756736)
		(mid 113.365254 -93.045854)
		(end 113.292382 -93.336618)
		(width 0.0889)
		(layer "In11.Cu")
		(net "M_M_DQS_DN<15>")
	)
	(arc
		(start 114.512852 -97.414588)
		(mid 114.796069 -97.498869)
		(end 115.003072 -97.709736)
		(width 0.0889)
		(layer "In11.Cu")
		(net "M_M_DQS_DN<15>")
	)
	(arc
		(start 117.578632 -101.767132)
		(mid 117.525133 -101.96703)
		(end 117.578632 -102.166928)
		(width 0.0889)
		(layer "In11.Cu")
		(net "M_M_DQS_DN<15>")
	)
	(arc
		(start 113.57483 -90.179398)
		(mid 113.272561 -90.400947)
		(end 113.286032 -90.775536)
		(width 0.0889)
		(layer "In11.Cu")
		(net "M_M_DQS_DN<15>")
	)
	(arc
		(start 115.861592 -98.205036)
		(mid 116.003275 -98.34884)
		(end 116.197126 -98.405188)
		(width 0.0889)
		(layer "In11.Cu")
		(net "M_M_DQS_DN<15>")
	)
	(arc
		(start 113.286032 -95.728536)
		(mid 113.365254 -96.017654)
		(end 113.292382 -96.308418)
		(width 0.0889)
		(layer "In11.Cu")
		(net "M_M_DQS_DN<15>")
	)
	(arc
		(start 117.578632 -99.785932)
		(mid 117.525133 -99.98583)
		(end 117.578632 -100.185728)
		(width 0.0889)
		(layer "In11.Cu")
		(net "M_M_DQS_DN<15>")
	)
	(arc
		(start 113.286032 -93.747336)
		(mid 113.365163 -94.042738)
		(end 113.286032 -94.33814)
		(width 0.0889)
		(layer "In11.Cu")
		(net "M_M_DQS_DN<15>")
	)
	(arc
		(start 117.578632 -103.748586)
		(mid 117.525194 -103.941491)
		(end 117.571774 -104.13619)
		(width 0.0889)
		(layer "In11.Cu")
		(net "M_M_DQS_DN<15>")
	)
	(arc
		(start 117.578632 -101.176328)
		(mid 117.657763 -101.47173)
		(end 117.578632 -101.767132)
		(width 0.0889)
		(layer "In11.Cu")
		(net "M_M_DQS_DN<15>")
	)
	(arc
		(start 117.573806 -100.784914)
		(mid 117.525051 -100.981266)
		(end 117.578632 -101.176328)
		(width 0.0889)
		(layer "In11.Cu")
		(net "M_M_DQS_DN<15>")
	)
	(arc
		(start 113.286032 -90.775536)
		(mid 113.365254 -91.064654)
		(end 113.292382 -91.355418)
		(width 0.0889)
		(layer "In11.Cu")
		(net "M_M_DQS_DN<15>")
	)
	(arc
		(start 113.292382 -94.748604)
		(mid 113.36518 -95.039367)
		(end 113.286032 -95.328486)
		(width 0.0889)
		(layer "In11.Cu")
		(net "M_M_DQS_DN<15>")
	)
	(arc
		(start 113.281206 -96.327722)
		(mid 113.284953 -96.716978)
		(end 113.617756 -96.919034)
		(width 0.0889)
		(layer "In11.Cu")
		(net "M_M_DQS_DN<15>")
	)
	(arc
		(start 113.281206 -92.365322)
		(mid 113.232451 -92.561674)
		(end 113.286032 -92.756736)
		(width 0.0889)
		(layer "In11.Cu")
		(net "M_M_DQS_DN<15>")
	)
	(arc
		(start 113.281206 -93.355922)
		(mid 113.232451 -93.552274)
		(end 113.286032 -93.747336)
		(width 0.0889)
		(layer "In11.Cu")
		(net "M_M_DQS_DN<15>")
	)
	(arc
		(start 117.584982 -102.177596)
		(mid 117.657902 -102.468613)
		(end 117.578632 -102.757986)
		(width 0.0889)
		(layer "In11.Cu")
		(net "M_M_DQS_DN<15>")
	)
	(arc
		(start 117.578632 -104.739186)
		(mid 117.525194 -104.932091)
		(end 117.571774 -105.12679)
		(width 0.0889)
		(layer "In11.Cu")
		(net "M_M_DQS_DN<15>")
	)
	(arc
		(start 113.281206 -91.374722)
		(mid 113.232451 -91.571074)
		(end 113.286032 -91.766136)
		(width 0.0889)
		(layer "In11.Cu")
		(net "M_M_DQS_DN<15>")
	)
	(arc
		(start 113.286032 -94.33814)
		(mid 113.232533 -94.538038)
		(end 113.286032 -94.737936)
		(width 0.0889)
		(layer "In11.Cu")
		(net "M_M_DQS_DN<15>")
	)
	(arc
		(start 113.281206 -95.337122)
		(mid 113.232451 -95.533474)
		(end 113.286032 -95.728536)
		(width 0.0889)
		(layer "In11.Cu")
		(net "M_M_DQS_DN<15>")
	)
	(arc
		(start 113.286032 -91.766136)
		(mid 113.365254 -92.055254)
		(end 113.292382 -92.346018)
		(width 0.0889)
		(layer "In11.Cu")
		(net "M_M_DQS_DN<15>")
	)
	(arc
		(start 117.578632 -100.185728)
		(mid 117.657854 -100.474846)
		(end 117.584982 -100.76561)
		(width 0.0889)
		(layer "In11.Cu")
		(net "M_M_DQS_DN<15>")
	)
	(arc
		(start 115.003072 -97.709736)
		(mid 115.143151 -97.852472)
		(end 115.334796 -97.909634)
		(width 0.0889)
		(layer "In11.Cu")
		(net "M_M_DQS_DN<15>")
	)
	(arc
		(start 116.720112 -98.700336)
		(mid 116.860191 -98.843072)
		(end 117.051836 -98.900234)
		(width 0.0889)
		(layer "In11.Cu")
		(net "M_M_DQS_DN<15>")
	)
	(arc
		(start 117.587522 -103.173022)
		(mid 117.657919 -103.461973)
		(end 117.578632 -103.748586)
		(width 0.0889)
		(layer "In11.Cu")
		(net "M_M_DQS_DN<15>")
	)
	(segment
		(start 128.299464 -152.273)
		(end 128.299464 -152.932384)
		(width 0.1651)
		(layer "F.Cu")
		(net "M_M_DQS_DN<14>")
	)
	(segment
		(start 127.60706 -154.45613)
		(end 127.41783 -154.2669)
		(width 0.1651)
		(layer "F.Cu")
		(net "M_M_DQS_DN<14>")
	)
	(segment
		(start 127.41783 -154.2669)
		(end 127.39878 -154.2669)
		(width 0.1651)
		(layer "F.Cu")
		(net "M_M_DQS_DN<14>")
	)
	(segment
		(start 128.299464 -152.932384)
		(end 127.88138 -153.350468)
		(width 0.1651)
		(layer "F.Cu")
		(net "M_M_DQS_DN<14>")
	)
	(segment
		(start 115.636802 -94.042738)
		(end 116.208302 -94.042738)
		(width 0.1651)
		(layer "F.Cu")
		(net "M_M_DQS_DN<14>")
	)
	(segment
		(start 127.88138 -153.350468)
		(end 127.88138 -153.7716)
		(width 0.1651)
		(layer "F.Cu")
		(net "M_M_DQS_DN<14>")
	)
	(segment
		(start 128.067308 -153.957528)
		(end 128.067308 -154.204162)
		(width 0.1651)
		(layer "F.Cu")
		(net "M_M_DQS_DN<14>")
	)
	(segment
		(start 127.88138 -153.7716)
		(end 128.067308 -153.957528)
		(width 0.1651)
		(layer "F.Cu")
		(net "M_M_DQS_DN<14>")
	)
	(segment
		(start 128.067308 -154.204162)
		(end 127.81534 -154.45613)
		(width 0.1651)
		(layer "F.Cu")
		(net "M_M_DQS_DN<14>")
	)
	(segment
		(start 127.81534 -154.45613)
		(end 127.60706 -154.45613)
		(width 0.1651)
		(layer "F.Cu")
		(net "M_M_DQS_DN<14>")
	)
	(via
		(at 116.208302 -94.042738)
		(size 0.508)
		(drill 0.254)
		(layers "F.Cu" "B.Cu")
		(net "M_M_DQS_DN<14>")
	)
	(via
		(at 127.39878 -154.2669)
		(size 0.508)
		(drill 0.254)
		(layers "F.Cu" "B.Cu")
		(net "M_M_DQS_DN<14>")
	)
	(via
		(at 127.392176 -150.0886)
		(size 0.508)
		(drill 0.254)
		(layers "F.Cu" "B.Cu")
		(net "M_M_DQS_DN<14>")
	)
	(segment
		(start 128.299718 -151.421592)
		(end 127.85598 -150.977854)
		(width 0.1651)
		(layer "B.Cu")
		(net "M_M_DQS_DN<14>")
	)
	(segment
		(start 127.85598 -150.622)
		(end 128.03378 -150.4442)
		(width 0.1651)
		(layer "B.Cu")
		(net "M_M_DQS_DN<14>")
	)
	(segment
		(start 128.03378 -150.4442)
		(end 128.03378 -150.114)
		(width 0.1651)
		(layer "B.Cu")
		(net "M_M_DQS_DN<14>")
	)
	(segment
		(start 127.58674 -149.894036)
		(end 127.392176 -150.0886)
		(width 0.1651)
		(layer "B.Cu")
		(net "M_M_DQS_DN<14>")
	)
	(segment
		(start 127.85598 -150.977854)
		(end 127.85598 -150.622)
		(width 0.1651)
		(layer "B.Cu")
		(net "M_M_DQS_DN<14>")
	)
	(segment
		(start 128.299464 -152.078436)
		(end 128.299718 -152.077928)
		(width 0.1651)
		(layer "B.Cu")
		(net "M_M_DQS_DN<14>")
	)
	(segment
		(start 127.813816 -149.894036)
		(end 127.58674 -149.894036)
		(width 0.1651)
		(layer "B.Cu")
		(net "M_M_DQS_DN<14>")
	)
	(segment
		(start 128.299718 -152.077928)
		(end 128.299718 -151.421592)
		(width 0.1651)
		(layer "B.Cu")
		(net "M_M_DQS_DN<14>")
	)
	(segment
		(start 128.03378 -150.114)
		(end 127.813816 -149.894036)
		(width 0.1651)
		(layer "B.Cu")
		(net "M_M_DQS_DN<14>")
	)
	(segment
		(start 115.856766 -97.2058)
		(end 115.861592 -97.214436)
		(width 0.0889)
		(layer "In4.Cu")
		(net "M_M_DQS_DN<14>")
	)
	(segment
		(start 115.861592 -102.167436)
		(end 115.867942 -102.178104)
		(width 0.0889)
		(layer "In4.Cu")
		(net "M_M_DQS_DN<14>")
	)
	(segment
		(start 115.856766 -99.187)
		(end 115.861592 -99.195636)
		(width 0.0889)
		(layer "In4.Cu")
		(net "M_M_DQS_DN<14>")
	)
	(segment
		(start 128.174496 -149.30628)
		(end 127.392176 -150.0886)
		(width 0.14224)
		(layer "In4.Cu")
		(net "M_M_DQS_DN<14>")
	)
	(segment
		(start 116.79936 -106.477308)
		(end 116.890292 -106.56824)
		(width 0.0889)
		(layer "In4.Cu")
		(net "M_M_DQS_DN<14>")
	)
	(segment
		(start 116.79936 -105.929684)
		(end 116.79936 -106.477308)
		(width 0.0889)
		(layer "In4.Cu")
		(net "M_M_DQS_DN<14>")
	)
	(segment
		(start 115.856766 -104.14)
		(end 115.861592 -104.148636)
		(width 0.0889)
		(layer "In4.Cu")
		(net "M_M_DQS_DN<14>")
	)
	(segment
		(start 115.867942 -94.822518)
		(end 115.861592 -94.833186)
		(width 0.0889)
		(layer "In4.Cu")
		(net "M_M_DQS_DN<14>")
	)
	(segment
		(start 116.890292 -107.22483)
		(end 116.929662 -107.2642)
		(width 0.0889)
		(layer "In4.Cu")
		(net "M_M_DQS_DN<14>")
	)
	(segment
		(start 116.890292 -106.56824)
		(end 116.890292 -107.22483)
		(width 0.0889)
		(layer "In4.Cu")
		(net "M_M_DQS_DN<14>")
	)
	(segment
		(start 115.861592 -96.223836)
		(end 115.867942 -96.234504)
		(width 0.0889)
		(layer "In4.Cu")
		(net "M_M_DQS_DN<14>")
	)
	(segment
		(start 115.856766 -103.1494)
		(end 115.861592 -103.158036)
		(width 0.0889)
		(layer "In4.Cu")
		(net "M_M_DQS_DN<14>")
	)
	(segment
		(start 115.856766 -101.1682)
		(end 115.861592 -101.176836)
		(width 0.0889)
		(layer "In4.Cu")
		(net "M_M_DQS_DN<14>")
	)
	(segment
		(start 116.929662 -107.286298)
		(end 116.929662 -112.856264)
		(width 0.14224)
		(layer "In4.Cu")
		(net "M_M_DQS_DN<14>")
	)
	(segment
		(start 115.861592 -98.205036)
		(end 115.867942 -98.215704)
		(width 0.0889)
		(layer "In4.Cu")
		(net "M_M_DQS_DN<14>")
	)
	(segment
		(start 115.861592 -97.214436)
		(end 115.867942 -97.225104)
		(width 0.0889)
		(layer "In4.Cu")
		(net "M_M_DQS_DN<14>")
	)
	(segment
		(start 115.856766 -96.2152)
		(end 115.861592 -96.223836)
		(width 0.0889)
		(layer "In4.Cu")
		(net "M_M_DQS_DN<14>")
	)
	(segment
		(start 115.861592 -103.158036)
		(end 115.867942 -103.168704)
		(width 0.0889)
		(layer "In4.Cu")
		(net "M_M_DQS_DN<14>")
	)
	(segment
		(start 115.861592 -100.186236)
		(end 115.867942 -100.196904)
		(width 0.0889)
		(layer "In4.Cu")
		(net "M_M_DQS_DN<14>")
	)
	(segment
		(start 115.856766 -98.1964)
		(end 115.861592 -98.205036)
		(width 0.0889)
		(layer "In4.Cu")
		(net "M_M_DQS_DN<14>")
	)
	(segment
		(start 115.856766 -94.234)
		(end 115.861592 -94.242636)
		(width 0.0889)
		(layer "In4.Cu")
		(net "M_M_DQS_DN<14>")
	)
	(segment
		(start 115.861592 -101.176836)
		(end 115.867942 -101.187504)
		(width 0.0889)
		(layer "In4.Cu")
		(net "M_M_DQS_DN<14>")
	)
	(segment
		(start 115.861592 -104.148636)
		(end 115.867942 -104.159304)
		(width 0.0889)
		(layer "In4.Cu")
		(net "M_M_DQS_DN<14>")
	)
	(segment
		(start 115.856766 -102.1588)
		(end 115.861592 -102.167436)
		(width 0.0889)
		(layer "In4.Cu")
		(net "M_M_DQS_DN<14>")
	)
	(segment
		(start 115.856766 -100.1776)
		(end 115.861592 -100.186236)
		(width 0.0889)
		(layer "In4.Cu")
		(net "M_M_DQS_DN<14>")
	)
	(segment
		(start 128.174496 -124.101098)
		(end 128.174496 -149.30628)
		(width 0.14224)
		(layer "In4.Cu")
		(net "M_M_DQS_DN<14>")
	)
	(segment
		(start 116.197126 -105.339388)
		(end 116.233194 -105.339388)
		(width 0.0889)
		(layer "In4.Cu")
		(net "M_M_DQS_DN<14>")
	)
	(segment
		(start 116.208302 -94.042738)
		(end 116.208302 -93.704664)
		(width 0.0889)
		(layer "In4.Cu")
		(net "M_M_DQS_DN<14>")
	)
	(segment
		(start 115.861592 -99.195636)
		(end 115.867942 -99.206304)
		(width 0.0889)
		(layer "In4.Cu")
		(net "M_M_DQS_DN<14>")
	)
	(segment
		(start 116.208302 -93.704664)
		(end 116.15039 -93.646752)
		(width 0.0889)
		(layer "In4.Cu")
		(net "M_M_DQS_DN<14>")
	)
	(segment
		(start 116.929662 -107.2642)
		(end 116.929662 -107.286298)
		(width 0.0889)
		(layer "In4.Cu")
		(net "M_M_DQS_DN<14>")
	)
	(segment
		(start 116.929662 -112.856264)
		(end 128.174496 -124.101098)
		(width 0.14224)
		(layer "In4.Cu")
		(net "M_M_DQS_DN<14>")
	)
	(arc
		(start 115.867942 -96.234504)
		(mid 115.94074 -96.525267)
		(end 115.861592 -96.814386)
		(width 0.0889)
		(layer "In4.Cu")
		(net "M_M_DQS_DN<14>")
	)
	(arc
		(start 115.867942 -99.206304)
		(mid 115.94074 -99.497067)
		(end 115.861592 -99.786186)
		(width 0.0889)
		(layer "In4.Cu")
		(net "M_M_DQS_DN<14>")
	)
	(arc
		(start 115.861592 -100.776786)
		(mid 115.808122 -100.971849)
		(end 115.856766 -101.1682)
		(width 0.0889)
		(layer "In4.Cu")
		(net "M_M_DQS_DN<14>")
	)
	(arc
		(start 115.861592 -98.795586)
		(mid 115.808122 -98.990649)
		(end 115.856766 -99.187)
		(width 0.0889)
		(layer "In4.Cu")
		(net "M_M_DQS_DN<14>")
	)
	(arc
		(start 115.867942 -100.196904)
		(mid 115.94074 -100.487667)
		(end 115.861592 -100.776786)
		(width 0.0889)
		(layer "In4.Cu")
		(net "M_M_DQS_DN<14>")
	)
	(arc
		(start 115.867942 -102.178104)
		(mid 115.94074 -102.468867)
		(end 115.861592 -102.757986)
		(width 0.0889)
		(layer "In4.Cu")
		(net "M_M_DQS_DN<14>")
	)
	(arc
		(start 115.867942 -104.159304)
		(mid 115.94074 -104.450067)
		(end 115.861592 -104.739186)
		(width 0.0889)
		(layer "In4.Cu")
		(net "M_M_DQS_DN<14>")
	)
	(arc
		(start 115.867942 -103.168704)
		(mid 115.94074 -103.459467)
		(end 115.861592 -103.748586)
		(width 0.0889)
		(layer "In4.Cu")
		(net "M_M_DQS_DN<14>")
	)
	(arc
		(start 116.15039 -93.646752)
		(mid 115.850354 -93.863764)
		(end 115.856766 -94.234)
		(width 0.0889)
		(layer "In4.Cu")
		(net "M_M_DQS_DN<14>")
	)
	(arc
		(start 115.861592 -99.786186)
		(mid 115.808122 -99.981249)
		(end 115.856766 -100.1776)
		(width 0.0889)
		(layer "In4.Cu")
		(net "M_M_DQS_DN<14>")
	)
	(arc
		(start 116.233194 -105.339388)
		(mid 116.634877 -105.520789)
		(end 116.79936 -105.929684)
		(width 0.0889)
		(layer "In4.Cu")
		(net "M_M_DQS_DN<14>")
	)
	(arc
		(start 115.861592 -94.242636)
		(mid 115.940814 -94.531754)
		(end 115.867942 -94.822518)
		(width 0.0889)
		(layer "In4.Cu")
		(net "M_M_DQS_DN<14>")
	)
	(arc
		(start 115.861592 -101.767386)
		(mid 115.808122 -101.962449)
		(end 115.856766 -102.1588)
		(width 0.0889)
		(layer "In4.Cu")
		(net "M_M_DQS_DN<14>")
	)
	(arc
		(start 115.861592 -102.757986)
		(mid 115.808122 -102.953049)
		(end 115.856766 -103.1494)
		(width 0.0889)
		(layer "In4.Cu")
		(net "M_M_DQS_DN<14>")
	)
	(arc
		(start 115.861592 -94.833186)
		(mid 115.808093 -95.033084)
		(end 115.861592 -95.232982)
		(width 0.0889)
		(layer "In4.Cu")
		(net "M_M_DQS_DN<14>")
	)
	(arc
		(start 115.867942 -98.215704)
		(mid 115.94074 -98.506467)
		(end 115.861592 -98.795586)
		(width 0.0889)
		(layer "In4.Cu")
		(net "M_M_DQS_DN<14>")
	)
	(arc
		(start 115.861592 -103.748586)
		(mid 115.808122 -103.943649)
		(end 115.856766 -104.14)
		(width 0.0889)
		(layer "In4.Cu")
		(net "M_M_DQS_DN<14>")
	)
	(arc
		(start 115.861592 -104.739186)
		(mid 115.858844 -105.134653)
		(end 116.197126 -105.339388)
		(width 0.0889)
		(layer "In4.Cu")
		(net "M_M_DQS_DN<14>")
	)
	(arc
		(start 115.861592 -97.804986)
		(mid 115.808122 -98.000049)
		(end 115.856766 -98.1964)
		(width 0.0889)
		(layer "In4.Cu")
		(net "M_M_DQS_DN<14>")
	)
	(arc
		(start 115.861592 -95.232982)
		(mid 115.940723 -95.528384)
		(end 115.861592 -95.823786)
		(width 0.0889)
		(layer "In4.Cu")
		(net "M_M_DQS_DN<14>")
	)
	(arc
		(start 115.867942 -101.187504)
		(mid 115.94074 -101.478267)
		(end 115.861592 -101.767386)
		(width 0.0889)
		(layer "In4.Cu")
		(net "M_M_DQS_DN<14>")
	)
	(arc
		(start 115.861592 -95.823786)
		(mid 115.808122 -96.018849)
		(end 115.856766 -96.2152)
		(width 0.0889)
		(layer "In4.Cu")
		(net "M_M_DQS_DN<14>")
	)
	(arc
		(start 115.861592 -96.814386)
		(mid 115.808122 -97.009449)
		(end 115.856766 -97.2058)
		(width 0.0889)
		(layer "In4.Cu")
		(net "M_M_DQS_DN<14>")
	)
	(arc
		(start 115.867942 -97.225104)
		(mid 115.94074 -97.515867)
		(end 115.861592 -97.804986)
		(width 0.0889)
		(layer "In4.Cu")
		(net "M_M_DQS_DN<14>")
	)
	(segment
		(start 127.156464 -151.70404)
		(end 127.288544 -151.83612)
		(width 0.14224)
		(layer "In11.Cu")
		(net "M_M_DQS_DN<14>")
	)
	(segment
		(start 127.827024 -150.9268)
		(end 127.547624 -151.2062)
		(width 0.14224)
		(layer "In11.Cu")
		(net "M_M_DQS_DN<14>")
	)
	(segment
		(start 127.547624 -151.2062)
		(end 127.306324 -151.2062)
		(width 0.14224)
		(layer "In11.Cu")
		(net "M_M_DQS_DN<14>")
	)
	(segment
		(start 127.83185 -153.349706)
		(end 127.83185 -153.83383)
		(width 0.14224)
		(layer "In11.Cu")
		(net "M_M_DQS_DN<14>")
	)
	(segment
		(start 127.598424 -151.99106)
		(end 127.598424 -152.34412)
		(width 0.14224)
		(layer "In11.Cu")
		(net "M_M_DQS_DN<14>")
	)
	(segment
		(start 127.644144 -153.162)
		(end 127.83185 -153.349706)
		(width 0.14224)
		(layer "In11.Cu")
		(net "M_M_DQS_DN<14>")
	)
	(segment
		(start 127.598424 -152.34412)
		(end 127.443484 -152.49906)
		(width 0.14224)
		(layer "In11.Cu")
		(net "M_M_DQS_DN<14>")
	)
	(segment
		(start 127.156464 -152.63876)
		(end 127.156464 -152.99944)
		(width 0.14224)
		(layer "In11.Cu")
		(net "M_M_DQS_DN<14>")
	)
	(segment
		(start 127.443484 -151.83612)
		(end 127.598424 -151.99106)
		(width 0.14224)
		(layer "In11.Cu")
		(net "M_M_DQS_DN<14>")
	)
	(segment
		(start 127.288544 -151.83612)
		(end 127.443484 -151.83612)
		(width 0.14224)
		(layer "In11.Cu")
		(net "M_M_DQS_DN<14>")
	)
	(segment
		(start 127.296164 -152.49906)
		(end 127.156464 -152.63876)
		(width 0.14224)
		(layer "In11.Cu")
		(net "M_M_DQS_DN<14>")
	)
	(segment
		(start 127.443484 -152.49906)
		(end 127.296164 -152.49906)
		(width 0.14224)
		(layer "In11.Cu")
		(net "M_M_DQS_DN<14>")
	)
	(segment
		(start 127.83185 -153.83383)
		(end 127.39878 -154.2669)
		(width 0.14224)
		(layer "In11.Cu")
		(net "M_M_DQS_DN<14>")
	)
	(segment
		(start 127.319024 -153.162)
		(end 127.644144 -153.162)
		(width 0.14224)
		(layer "In11.Cu")
		(net "M_M_DQS_DN<14>")
	)
	(segment
		(start 127.306324 -151.2062)
		(end 127.156464 -151.35606)
		(width 0.14224)
		(layer "In11.Cu")
		(net "M_M_DQS_DN<14>")
	)
	(segment
		(start 127.392176 -150.0886)
		(end 127.827024 -150.523448)
		(width 0.14224)
		(layer "In11.Cu")
		(net "M_M_DQS_DN<14>")
	)
	(segment
		(start 127.156464 -152.99944)
		(end 127.319024 -153.162)
		(width 0.14224)
		(layer "In11.Cu")
		(net "M_M_DQS_DN<14>")
	)
	(segment
		(start 127.827024 -150.523448)
		(end 127.827024 -150.9268)
		(width 0.14224)
		(layer "In11.Cu")
		(net "M_M_DQS_DN<14>")
	)
	(segment
		(start 127.156464 -151.35606)
		(end 127.156464 -151.70404)
		(width 0.14224)
		(layer "In11.Cu")
		(net "M_M_DQS_DN<14>")
	)
	(segment
		(start 118.94947 -152.93213)
		(end 118.531132 -153.350468)
		(width 0.1651)
		(layer "F.Cu")
		(net "M_M_DQS_DN<13>")
	)
	(segment
		(start 118.94947 -152.273)
		(end 118.94947 -152.93213)
		(width 0.1651)
		(layer "F.Cu")
		(net "M_M_DQS_DN<13>")
	)
	(segment
		(start 108.768896 -93.052138)
		(end 109.340396 -93.052138)
		(width 0.1651)
		(layer "F.Cu")
		(net "M_M_DQS_DN<13>")
	)
	(segment
		(start 118.531132 -153.7716)
		(end 118.71706 -153.957528)
		(width 0.1651)
		(layer "F.Cu")
		(net "M_M_DQS_DN<13>")
	)
	(segment
		(start 118.067582 -154.2669)
		(end 118.048532 -154.2669)
		(width 0.1651)
		(layer "F.Cu")
		(net "M_M_DQS_DN<13>")
	)
	(segment
		(start 118.256812 -154.45613)
		(end 118.067582 -154.2669)
		(width 0.1651)
		(layer "F.Cu")
		(net "M_M_DQS_DN<13>")
	)
	(segment
		(start 118.531132 -153.350468)
		(end 118.531132 -153.7716)
		(width 0.1651)
		(layer "F.Cu")
		(net "M_M_DQS_DN<13>")
	)
	(segment
		(start 118.465092 -154.45613)
		(end 118.256812 -154.45613)
		(width 0.1651)
		(layer "F.Cu")
		(net "M_M_DQS_DN<13>")
	)
	(segment
		(start 118.71706 -153.957528)
		(end 118.71706 -154.204162)
		(width 0.1651)
		(layer "F.Cu")
		(net "M_M_DQS_DN<13>")
	)
	(segment
		(start 118.71706 -154.204162)
		(end 118.465092 -154.45613)
		(width 0.1651)
		(layer "F.Cu")
		(net "M_M_DQS_DN<13>")
	)
	(via
		(at 118.048532 -154.2669)
		(size 0.508)
		(drill 0.254)
		(layers "F.Cu" "B.Cu")
		(net "M_M_DQS_DN<13>")
	)
	(via
		(at 118.041928 -150.0886)
		(size 0.508)
		(drill 0.254)
		(layers "F.Cu" "B.Cu")
		(net "M_M_DQS_DN<13>")
	)
	(via
		(at 109.340396 -93.052138)
		(size 0.508)
		(drill 0.254)
		(layers "F.Cu" "B.Cu")
		(net "M_M_DQS_DN<13>")
	)
	(segment
		(start 118.505732 -150.977854)
		(end 118.505732 -150.622)
		(width 0.1651)
		(layer "B.Cu")
		(net "M_M_DQS_DN<13>")
	)
	(segment
		(start 118.94947 -151.421592)
		(end 118.505732 -150.977854)
		(width 0.1651)
		(layer "B.Cu")
		(net "M_M_DQS_DN<13>")
	)
	(segment
		(start 118.683532 -150.4442)
		(end 118.683532 -150.114)
		(width 0.1651)
		(layer "B.Cu")
		(net "M_M_DQS_DN<13>")
	)
	(segment
		(start 118.236492 -149.894036)
		(end 118.041928 -150.0886)
		(width 0.1651)
		(layer "B.Cu")
		(net "M_M_DQS_DN<13>")
	)
	(segment
		(start 118.463568 -149.894036)
		(end 118.236492 -149.894036)
		(width 0.1651)
		(layer "B.Cu")
		(net "M_M_DQS_DN<13>")
	)
	(segment
		(start 118.94947 -152.078436)
		(end 118.94947 -151.421592)
		(width 0.1651)
		(layer "B.Cu")
		(net "M_M_DQS_DN<13>")
	)
	(segment
		(start 118.683532 -150.114)
		(end 118.463568 -149.894036)
		(width 0.1651)
		(layer "B.Cu")
		(net "M_M_DQS_DN<13>")
	)
	(segment
		(start 118.505732 -150.622)
		(end 118.683532 -150.4442)
		(width 0.1651)
		(layer "B.Cu")
		(net "M_M_DQS_DN<13>")
	)
	(segment
		(start 117.80647 -151.35606)
		(end 117.80647 -151.70404)
		(width 0.14224)
		(layer "In11.Cu")
		(net "M_M_DQS_DN<13>")
	)
	(segment
		(start 117.80647 -151.70404)
		(end 117.93855 -151.83612)
		(width 0.14224)
		(layer "In11.Cu")
		(net "M_M_DQS_DN<13>")
	)
	(segment
		(start 118.550182 -149.35073)
		(end 118.550182 -149.617176)
		(width 0.14224)
		(layer "In11.Cu")
		(net "M_M_DQS_DN<13>")
	)
	(segment
		(start 118.74246 -126.674118)
		(end 118.824502 -126.872238)
		(width 0.14224)
		(layer "In11.Cu")
		(net "M_M_DQS_DN<13>")
	)
	(segment
		(start 109.874558 -104.793796)
		(end 109.874558 -116.082318)
		(width 0.14224)
		(layer "In11.Cu")
		(net "M_M_DQS_DN<13>")
	)
	(segment
		(start 108.98886 -93.2434)
		(end 108.993686 -93.252036)
		(width 0.0889)
		(layer "In11.Cu")
		(net "M_M_DQS_DN<13>")
	)
	(segment
		(start 108.141516 -99.280218)
		(end 108.135166 -99.290886)
		(width 0.0889)
		(layer "In11.Cu")
		(net "M_M_DQS_DN<13>")
	)
	(segment
		(start 118.550182 -149.617176)
		(end 118.078758 -150.0886)
		(width 0.14224)
		(layer "In11.Cu")
		(net "M_M_DQS_DN<13>")
	)
	(segment
		(start 118.24843 -151.99106)
		(end 118.24843 -152.34412)
		(width 0.14224)
		(layer "In11.Cu")
		(net "M_M_DQS_DN<13>")
	)
	(segment
		(start 117.80647 -152.99944)
		(end 117.96903 -153.162)
		(width 0.14224)
		(layer "In11.Cu")
		(net "M_M_DQS_DN<13>")
	)
	(segment
		(start 118.481856 -153.349706)
		(end 118.481856 -153.833576)
		(width 0.14224)
		(layer "In11.Cu")
		(net "M_M_DQS_DN<13>")
	)
	(segment
		(start 109.157262 -100.469446)
		(end 109.835188 -101.147626)
		(width 0.0889)
		(layer "In11.Cu")
		(net "M_M_DQS_DN<13>")
	)
	(segment
		(start 109.874558 -116.082318)
		(end 115.417854 -121.625614)
		(width 0.14224)
		(layer "In11.Cu")
		(net "M_M_DQS_DN<13>")
	)
	(segment
		(start 115.417854 -122.83186)
		(end 118.3767 -125.790706)
		(width 0.14224)
		(layer "In11.Cu")
		(net "M_M_DQS_DN<13>")
	)
	(segment
		(start 108.135166 -95.328486)
		(end 108.13034 -95.337122)
		(width 0.0889)
		(layer "In11.Cu")
		(net "M_M_DQS_DN<13>")
	)
	(segment
		(start 117.95633 -151.2062)
		(end 117.80647 -151.35606)
		(width 0.14224)
		(layer "In11.Cu")
		(net "M_M_DQS_DN<13>")
	)
	(segment
		(start 109.835188 -101.147626)
		(end 109.835188 -104.732328)
		(width 0.0889)
		(layer "In11.Cu")
		(net "M_M_DQS_DN<13>")
	)
	(segment
		(start 118.042182 -150.0886)
		(end 118.47703 -150.523448)
		(width 0.14224)
		(layer "In11.Cu")
		(net "M_M_DQS_DN<13>")
	)
	(segment
		(start 118.078758 -150.0886)
		(end 118.042182 -150.0886)
		(width 0.14224)
		(layer "In11.Cu")
		(net "M_M_DQS_DN<13>")
	)
	(segment
		(start 109.340396 -92.714064)
		(end 109.282484 -92.656152)
		(width 0.0889)
		(layer "In11.Cu")
		(net "M_M_DQS_DN<13>")
	)
	(segment
		(start 108.135166 -96.319086)
		(end 108.13034 -96.327722)
		(width 0.0889)
		(layer "In11.Cu")
		(net "M_M_DQS_DN<13>")
	)
	(segment
		(start 108.993686 -100.18649)
		(end 109.157262 -100.469446)
		(width 0.0889)
		(layer "In11.Cu")
		(net "M_M_DQS_DN<13>")
	)
	(segment
		(start 108.141516 -97.299018)
		(end 108.135166 -97.309686)
		(width 0.0889)
		(layer "In11.Cu")
		(net "M_M_DQS_DN<13>")
	)
	(segment
		(start 118.19763 -151.2062)
		(end 117.95633 -151.2062)
		(width 0.14224)
		(layer "In11.Cu")
		(net "M_M_DQS_DN<13>")
	)
	(segment
		(start 118.481856 -153.833576)
		(end 118.048532 -154.2669)
		(width 0.14224)
		(layer "In11.Cu")
		(net "M_M_DQS_DN<13>")
	)
	(segment
		(start 118.09349 -152.49906)
		(end 117.94617 -152.49906)
		(width 0.14224)
		(layer "In11.Cu")
		(net "M_M_DQS_DN<13>")
	)
	(segment
		(start 117.94617 -152.49906)
		(end 117.80647 -152.63876)
		(width 0.14224)
		(layer "In11.Cu")
		(net "M_M_DQS_DN<13>")
	)
	(segment
		(start 118.47703 -150.523448)
		(end 118.47703 -150.9268)
		(width 0.14224)
		(layer "In11.Cu")
		(net "M_M_DQS_DN<13>")
	)
	(segment
		(start 118.824502 -149.07641)
		(end 118.550182 -149.35073)
		(width 0.14224)
		(layer "In11.Cu")
		(net "M_M_DQS_DN<13>")
	)
	(segment
		(start 117.80647 -152.63876)
		(end 117.80647 -152.99944)
		(width 0.14224)
		(layer "In11.Cu")
		(net "M_M_DQS_DN<13>")
	)
	(segment
		(start 115.417854 -121.625614)
		(end 115.417854 -122.83186)
		(width 0.14224)
		(layer "In11.Cu")
		(net "M_M_DQS_DN<13>")
	)
	(segment
		(start 118.824502 -126.872238)
		(end 118.824502 -149.07641)
		(width 0.14224)
		(layer "In11.Cu")
		(net "M_M_DQS_DN<13>")
	)
	(segment
		(start 118.3767 -125.790706)
		(end 118.74246 -126.674118)
		(width 0.14224)
		(layer "In11.Cu")
		(net "M_M_DQS_DN<13>")
	)
	(segment
		(start 108.993686 -93.252036)
		(end 109.000036 -93.262704)
		(width 0.0889)
		(layer "In11.Cu")
		(net "M_M_DQS_DN<13>")
	)
	(segment
		(start 108.135166 -98.300286)
		(end 108.13034 -98.308922)
		(width 0.0889)
		(layer "In11.Cu")
		(net "M_M_DQS_DN<13>")
	)
	(segment
		(start 108.141516 -96.308418)
		(end 108.135166 -96.319086)
		(width 0.0889)
		(layer "In11.Cu")
		(net "M_M_DQS_DN<13>")
	)
	(segment
		(start 108.49483 -94.137988)
		(end 108.4707 -94.137988)
		(width 0.0889)
		(layer "In11.Cu")
		(net "M_M_DQS_DN<13>")
	)
	(segment
		(start 118.09349 -151.83612)
		(end 118.24843 -151.99106)
		(width 0.14224)
		(layer "In11.Cu")
		(net "M_M_DQS_DN<13>")
	)
	(segment
		(start 118.24843 -152.34412)
		(end 118.09349 -152.49906)
		(width 0.14224)
		(layer "In11.Cu")
		(net "M_M_DQS_DN<13>")
	)
	(segment
		(start 108.135166 -94.737936)
		(end 108.141516 -94.748604)
		(width 0.0889)
		(layer "In11.Cu")
		(net "M_M_DQS_DN<13>")
	)
	(segment
		(start 118.47703 -150.9268)
		(end 118.19763 -151.2062)
		(width 0.14224)
		(layer "In11.Cu")
		(net "M_M_DQS_DN<13>")
	)
	(segment
		(start 117.93855 -151.83612)
		(end 118.09349 -151.83612)
		(width 0.14224)
		(layer "In11.Cu")
		(net "M_M_DQS_DN<13>")
	)
	(segment
		(start 109.874558 -104.771698)
		(end 109.874558 -104.793796)
		(width 0.0889)
		(layer "In11.Cu")
		(net "M_M_DQS_DN<13>")
	)
	(segment
		(start 118.041928 -150.0886)
		(end 118.042182 -150.0886)
		(width 0.14224)
		(layer "In11.Cu")
		(net "M_M_DQS_DN<13>")
	)
	(segment
		(start 117.96903 -153.162)
		(end 118.29415 -153.162)
		(width 0.14224)
		(layer "In11.Cu")
		(net "M_M_DQS_DN<13>")
	)
	(segment
		(start 108.47705 -99.891088)
		(end 108.49483 -99.891088)
		(width 0.0889)
		(layer "In11.Cu")
		(net "M_M_DQS_DN<13>")
	)
	(segment
		(start 109.340396 -93.052138)
		(end 109.340396 -92.714064)
		(width 0.0889)
		(layer "In11.Cu")
		(net "M_M_DQS_DN<13>")
	)
	(segment
		(start 108.135166 -97.309686)
		(end 108.13034 -97.318322)
		(width 0.0889)
		(layer "In11.Cu")
		(net "M_M_DQS_DN<13>")
	)
	(segment
		(start 108.141516 -98.289618)
		(end 108.135166 -98.300286)
		(width 0.0889)
		(layer "In11.Cu")
		(net "M_M_DQS_DN<13>")
	)
	(segment
		(start 118.29415 -153.162)
		(end 118.481856 -153.349706)
		(width 0.14224)
		(layer "In11.Cu")
		(net "M_M_DQS_DN<13>")
	)
	(segment
		(start 108.135166 -99.290886)
		(end 108.13034 -99.299522)
		(width 0.0889)
		(layer "In11.Cu")
		(net "M_M_DQS_DN<13>")
	)
	(segment
		(start 109.835188 -104.732328)
		(end 109.874558 -104.771698)
		(width 0.0889)
		(layer "In11.Cu")
		(net "M_M_DQS_DN<13>")
	)
	(arc
		(start 108.13034 -95.337122)
		(mid 108.081585 -95.533474)
		(end 108.135166 -95.728536)
		(width 0.0889)
		(layer "In11.Cu")
		(net "M_M_DQS_DN<13>")
	)
	(arc
		(start 108.135166 -97.709736)
		(mid 108.214388 -97.998854)
		(end 108.141516 -98.289618)
		(width 0.0889)
		(layer "In11.Cu")
		(net "M_M_DQS_DN<13>")
	)
	(arc
		(start 108.4707 -94.137988)
		(mid 108.132585 -94.34269)
		(end 108.135166 -94.737936)
		(width 0.0889)
		(layer "In11.Cu")
		(net "M_M_DQS_DN<13>")
	)
	(arc
		(start 108.13034 -99.299522)
		(mid 108.136628 -99.693177)
		(end 108.47705 -99.891088)
		(width 0.0889)
		(layer "In11.Cu")
		(net "M_M_DQS_DN<13>")
	)
	(arc
		(start 109.282484 -92.656152)
		(mid 108.982448 -92.873164)
		(end 108.98886 -93.2434)
		(width 0.0889)
		(layer "In11.Cu")
		(net "M_M_DQS_DN<13>")
	)
	(arc
		(start 108.141516 -94.748604)
		(mid 108.214314 -95.039367)
		(end 108.135166 -95.328486)
		(width 0.0889)
		(layer "In11.Cu")
		(net "M_M_DQS_DN<13>")
	)
	(arc
		(start 108.13034 -98.308922)
		(mid 108.081585 -98.505274)
		(end 108.135166 -98.700336)
		(width 0.0889)
		(layer "In11.Cu")
		(net "M_M_DQS_DN<13>")
	)
	(arc
		(start 108.135166 -98.700336)
		(mid 108.214388 -98.989454)
		(end 108.141516 -99.280218)
		(width 0.0889)
		(layer "In11.Cu")
		(net "M_M_DQS_DN<13>")
	)
	(arc
		(start 108.13034 -96.327722)
		(mid 108.081585 -96.524074)
		(end 108.135166 -96.719136)
		(width 0.0889)
		(layer "In11.Cu")
		(net "M_M_DQS_DN<13>")
	)
	(arc
		(start 108.135166 -95.728536)
		(mid 108.214388 -96.017654)
		(end 108.141516 -96.308418)
		(width 0.0889)
		(layer "In11.Cu")
		(net "M_M_DQS_DN<13>")
	)
	(arc
		(start 108.135166 -96.719136)
		(mid 108.214388 -97.008254)
		(end 108.141516 -97.299018)
		(width 0.0889)
		(layer "In11.Cu")
		(net "M_M_DQS_DN<13>")
	)
	(arc
		(start 109.000036 -93.262704)
		(mid 108.993859 -93.842636)
		(end 108.49483 -94.137988)
		(width 0.0889)
		(layer "In11.Cu")
		(net "M_M_DQS_DN<13>")
	)
	(arc
		(start 108.49483 -99.891088)
		(mid 108.782975 -99.973407)
		(end 108.993686 -100.18649)
		(width 0.0889)
		(layer "In11.Cu")
		(net "M_M_DQS_DN<13>")
	)
	(arc
		(start 108.13034 -97.318322)
		(mid 108.081585 -97.514674)
		(end 108.135166 -97.709736)
		(width 0.0889)
		(layer "In11.Cu")
		(net "M_M_DQS_DN<13>")
	)
	(segment
		(start 63.006986 -154.45613)
		(end 62.817756 -154.2669)
		(width 0.1651)
		(layer "F.Cu")
		(net "M_M_DQS_DN<12>")
	)
	(segment
		(start 85.777832 -85.803486)
		(end 85.206332 -85.803486)
		(width 0.1651)
		(layer "F.Cu")
		(net "M_M_DQS_DN<12>")
	)
	(segment
		(start 62.817756 -154.2669)
		(end 62.798706 -154.2669)
		(width 0.1651)
		(layer "F.Cu")
		(net "M_M_DQS_DN<12>")
	)
	(segment
		(start 63.467234 -154.204162)
		(end 63.215266 -154.45613)
		(width 0.1651)
		(layer "F.Cu")
		(net "M_M_DQS_DN<12>")
	)
	(segment
		(start 63.467234 -153.957528)
		(end 63.467234 -154.204162)
		(width 0.1651)
		(layer "F.Cu")
		(net "M_M_DQS_DN<12>")
	)
	(segment
		(start 63.69939 -152.273)
		(end 63.69939 -152.932384)
		(width 0.1651)
		(layer "F.Cu")
		(net "M_M_DQS_DN<12>")
	)
	(segment
		(start 63.215266 -154.45613)
		(end 63.006986 -154.45613)
		(width 0.1651)
		(layer "F.Cu")
		(net "M_M_DQS_DN<12>")
	)
	(segment
		(start 63.281306 -153.7716)
		(end 63.467234 -153.957528)
		(width 0.1651)
		(layer "F.Cu")
		(net "M_M_DQS_DN<12>")
	)
	(segment
		(start 63.69939 -152.932384)
		(end 63.281306 -153.350468)
		(width 0.1651)
		(layer "F.Cu")
		(net "M_M_DQS_DN<12>")
	)
	(segment
		(start 63.281306 -153.350468)
		(end 63.281306 -153.7716)
		(width 0.1651)
		(layer "F.Cu")
		(net "M_M_DQS_DN<12>")
	)
	(via
		(at 62.792102 -150.0886)
		(size 0.508)
		(drill 0.254)
		(layers "F.Cu" "B.Cu")
		(net "M_M_DQS_DN<12>")
	)
	(via
		(at 85.206332 -85.803486)
		(size 0.508)
		(drill 0.254)
		(layers "F.Cu" "B.Cu")
		(net "M_M_DQS_DN<12>")
	)
	(via
		(at 62.798706 -154.2669)
		(size 0.508)
		(drill 0.254)
		(layers "F.Cu" "B.Cu")
		(net "M_M_DQS_DN<12>")
	)
	(segment
		(start 63.69939 -151.421846)
		(end 63.699644 -151.421592)
		(width 0.1651)
		(layer "B.Cu")
		(net "M_M_DQS_DN<12>")
	)
	(segment
		(start 63.69939 -152.078436)
		(end 63.69939 -151.421846)
		(width 0.1651)
		(layer "B.Cu")
		(net "M_M_DQS_DN<12>")
	)
	(segment
		(start 63.213742 -149.894036)
		(end 62.986666 -149.894036)
		(width 0.1651)
		(layer "B.Cu")
		(net "M_M_DQS_DN<12>")
	)
	(segment
		(start 63.255906 -150.622)
		(end 63.433706 -150.4442)
		(width 0.1651)
		(layer "B.Cu")
		(net "M_M_DQS_DN<12>")
	)
	(segment
		(start 63.699644 -151.421592)
		(end 63.255906 -150.977854)
		(width 0.1651)
		(layer "B.Cu")
		(net "M_M_DQS_DN<12>")
	)
	(segment
		(start 63.433706 -150.4442)
		(end 63.433706 -150.114)
		(width 0.1651)
		(layer "B.Cu")
		(net "M_M_DQS_DN<12>")
	)
	(segment
		(start 62.986666 -149.894036)
		(end 62.792102 -150.0886)
		(width 0.1651)
		(layer "B.Cu")
		(net "M_M_DQS_DN<12>")
	)
	(segment
		(start 63.433706 -150.114)
		(end 63.213742 -149.894036)
		(width 0.1651)
		(layer "B.Cu")
		(net "M_M_DQS_DN<12>")
	)
	(segment
		(start 63.255906 -150.977854)
		(end 63.255906 -150.622)
		(width 0.1651)
		(layer "B.Cu")
		(net "M_M_DQS_DN<12>")
	)
	(segment
		(start 76.573888 -108.862368)
		(end 76.573888 -114.313208)
		(width 0.14224)
		(layer "In11.Cu")
		(net "M_M_DQS_DN<12>")
	)
	(segment
		(start 83.741768 -96.453452)
		(end 81.772252 -98.422968)
		(width 0.0889)
		(layer "In11.Cu")
		(net "M_M_DQS_DN<12>")
	)
	(segment
		(start 84.859622 -86.594188)
		(end 84.854796 -86.602824)
		(width 0.0889)
		(layer "In11.Cu")
		(net "M_M_DQS_DN<12>")
	)
	(segment
		(start 84.001102 -95.414338)
		(end 84.007452 -95.425006)
		(width 0.0889)
		(layer "In11.Cu")
		(net "M_M_DQS_DN<12>")
	)
	(segment
		(start 62.84341 -151.83612)
		(end 62.99835 -151.99106)
		(width 0.14224)
		(layer "In11.Cu")
		(net "M_M_DQS_DN<12>")
	)
	(segment
		(start 80.2767 -103.13543)
		(end 80.31607 -103.1748)
		(width 0.0889)
		(layer "In11.Cu")
		(net "M_M_DQS_DN<12>")
	)
	(segment
		(start 63.574422 -149.313646)
		(end 62.799468 -150.0886)
		(width 0.14224)
		(layer "In11.Cu")
		(net "M_M_DQS_DN<12>")
	)
	(segment
		(start 62.55639 -152.63876)
		(end 62.55639 -152.99944)
		(width 0.14224)
		(layer "In11.Cu")
		(net "M_M_DQS_DN<12>")
	)
	(segment
		(start 84.007452 -94.01302)
		(end 84.001102 -94.023688)
		(width 0.0889)
		(layer "In11.Cu")
		(net "M_M_DQS_DN<12>")
	)
	(segment
		(start 84.865972 -89.55532)
		(end 84.859622 -89.565988)
		(width 0.0889)
		(layer "In11.Cu")
		(net "M_M_DQS_DN<12>")
	)
	(segment
		(start 62.799468 -150.0886)
		(end 62.792102 -150.0886)
		(width 0.14224)
		(layer "In11.Cu")
		(net "M_M_DQS_DN<12>")
	)
	(segment
		(start 80.2767 -100.48875)
		(end 80.2767 -103.13543)
		(width 0.0889)
		(layer "In11.Cu")
		(net "M_M_DQS_DN<12>")
	)
	(segment
		(start 85.206332 -85.803486)
		(end 85.206332 -85.465412)
		(width 0.0889)
		(layer "In11.Cu")
		(net "M_M_DQS_DN<12>")
	)
	(segment
		(start 63.04407 -153.162)
		(end 63.231776 -153.349706)
		(width 0.14224)
		(layer "In11.Cu")
		(net "M_M_DQS_DN<12>")
	)
	(segment
		(start 62.55639 -151.35606)
		(end 62.55639 -151.70404)
		(width 0.14224)
		(layer "In11.Cu")
		(net "M_M_DQS_DN<12>")
	)
	(segment
		(start 62.55639 -152.99944)
		(end 62.71895 -153.162)
		(width 0.14224)
		(layer "In11.Cu")
		(net "M_M_DQS_DN<12>")
	)
	(segment
		(start 62.69609 -152.49906)
		(end 62.55639 -152.63876)
		(width 0.14224)
		(layer "In11.Cu")
		(net "M_M_DQS_DN<12>")
	)
	(segment
		(start 81.169764 -99.76739)
		(end 80.724248 -99.76739)
		(width 0.0889)
		(layer "In11.Cu")
		(net "M_M_DQS_DN<12>")
	)
	(segment
		(start 63.231776 -153.349706)
		(end 63.231776 -153.83383)
		(width 0.14224)
		(layer "In11.Cu")
		(net "M_M_DQS_DN<12>")
	)
	(segment
		(start 84.865972 -91.53652)
		(end 84.859622 -91.547188)
		(width 0.0889)
		(layer "In11.Cu")
		(net "M_M_DQS_DN<12>")
	)
	(segment
		(start 80.724248 -99.76739)
		(end 80.62468 -99.866958)
		(width 0.0889)
		(layer "In11.Cu")
		(net "M_M_DQS_DN<12>")
	)
	(segment
		(start 84.000848 -96.005142)
		(end 83.741768 -96.453452)
		(width 0.0889)
		(layer "In11.Cu")
		(net "M_M_DQS_DN<12>")
	)
	(segment
		(start 62.99835 -151.99106)
		(end 62.99835 -152.34412)
		(width 0.14224)
		(layer "In11.Cu")
		(net "M_M_DQS_DN<12>")
	)
	(segment
		(start 62.68847 -151.83612)
		(end 62.84341 -151.83612)
		(width 0.14224)
		(layer "In11.Cu")
		(net "M_M_DQS_DN<12>")
	)
	(segment
		(start 84.865972 -88.56472)
		(end 84.859622 -88.575388)
		(width 0.0889)
		(layer "In11.Cu")
		(net "M_M_DQS_DN<12>")
	)
	(segment
		(start 62.71895 -153.162)
		(end 63.04407 -153.162)
		(width 0.14224)
		(layer "In11.Cu")
		(net "M_M_DQS_DN<12>")
	)
	(segment
		(start 84.859622 -91.547188)
		(end 84.854796 -91.555824)
		(width 0.0889)
		(layer "In11.Cu")
		(net "M_M_DQS_DN<12>")
	)
	(segment
		(start 83.996276 -95.405702)
		(end 84.001102 -95.414338)
		(width 0.0889)
		(layer "In11.Cu")
		(net "M_M_DQS_DN<12>")
	)
	(segment
		(start 84.859622 -87.584788)
		(end 84.854796 -87.593424)
		(width 0.0889)
		(layer "In11.Cu")
		(net "M_M_DQS_DN<12>")
	)
	(segment
		(start 83.996276 -93.424502)
		(end 84.001102 -93.433138)
		(width 0.0889)
		(layer "In11.Cu")
		(net "M_M_DQS_DN<12>")
	)
	(segment
		(start 62.84341 -152.49906)
		(end 62.69609 -152.49906)
		(width 0.14224)
		(layer "In11.Cu")
		(net "M_M_DQS_DN<12>")
	)
	(segment
		(start 84.859622 -90.556588)
		(end 84.854796 -90.565224)
		(width 0.0889)
		(layer "In11.Cu")
		(net "M_M_DQS_DN<12>")
	)
	(segment
		(start 84.365592 -92.83319)
		(end 84.332826 -92.83319)
		(width 0.0889)
		(layer "In11.Cu")
		(net "M_M_DQS_DN<12>")
	)
	(segment
		(start 70.343776 -120.54332)
		(end 67.041014 -120.54332)
		(width 0.14224)
		(layer "In11.Cu")
		(net "M_M_DQS_DN<12>")
	)
	(segment
		(start 63.231776 -153.83383)
		(end 62.798706 -154.2669)
		(width 0.14224)
		(layer "In11.Cu")
		(net "M_M_DQS_DN<12>")
	)
	(segment
		(start 81.772252 -98.422968)
		(end 81.772252 -99.164902)
		(width 0.0889)
		(layer "In11.Cu")
		(net "M_M_DQS_DN<12>")
	)
	(segment
		(start 62.792102 -150.0886)
		(end 63.22695 -150.523448)
		(width 0.14224)
		(layer "In11.Cu")
		(net "M_M_DQS_DN<12>")
	)
	(segment
		(start 84.001102 -96.004888)
		(end 84.000848 -96.005142)
		(width 0.0889)
		(layer "In11.Cu")
		(net "M_M_DQS_DN<12>")
	)
	(segment
		(start 64.047116 -123.537218)
		(end 63.574422 -124.67844)
		(width 0.14224)
		(layer "In11.Cu")
		(net "M_M_DQS_DN<12>")
	)
	(segment
		(start 62.70625 -151.2062)
		(end 62.55639 -151.35606)
		(width 0.14224)
		(layer "In11.Cu")
		(net "M_M_DQS_DN<12>")
	)
	(segment
		(start 62.55639 -151.70404)
		(end 62.68847 -151.83612)
		(width 0.14224)
		(layer "In11.Cu")
		(net "M_M_DQS_DN<12>")
	)
	(segment
		(start 80.62468 -99.866958)
		(end 80.509872 -100.065586)
		(width 0.0889)
		(layer "In11.Cu")
		(net "M_M_DQS_DN<12>")
	)
	(segment
		(start 62.94755 -151.2062)
		(end 62.70625 -151.2062)
		(width 0.14224)
		(layer "In11.Cu")
		(net "M_M_DQS_DN<12>")
	)
	(segment
		(start 80.31607 -103.1748)
		(end 80.31607 -103.196898)
		(width 0.0889)
		(layer "In11.Cu")
		(net "M_M_DQS_DN<12>")
	)
	(segment
		(start 84.865972 -90.54592)
		(end 84.859622 -90.556588)
		(width 0.0889)
		(layer "In11.Cu")
		(net "M_M_DQS_DN<12>")
	)
	(segment
		(start 84.865972 -86.58352)
		(end 84.859622 -86.594188)
		(width 0.0889)
		(layer "In11.Cu")
		(net "M_M_DQS_DN<12>")
	)
	(segment
		(start 63.22695 -150.9268)
		(end 62.94755 -151.2062)
		(width 0.14224)
		(layer "In11.Cu")
		(net "M_M_DQS_DN<12>")
	)
	(segment
		(start 85.206332 -85.465412)
		(end 85.14842 -85.4075)
		(width 0.0889)
		(layer "In11.Cu")
		(net "M_M_DQS_DN<12>")
	)
	(segment
		(start 62.99835 -152.34412)
		(end 62.84341 -152.49906)
		(width 0.14224)
		(layer "In11.Cu")
		(net "M_M_DQS_DN<12>")
	)
	(segment
		(start 81.772252 -99.164902)
		(end 81.169764 -99.76739)
		(width 0.0889)
		(layer "In11.Cu")
		(net "M_M_DQS_DN<12>")
	)
	(segment
		(start 67.041014 -120.54332)
		(end 64.047116 -123.537218)
		(width 0.14224)
		(layer "In11.Cu")
		(net "M_M_DQS_DN<12>")
	)
	(segment
		(start 80.31607 -103.196898)
		(end 80.31607 -105.120186)
		(width 0.14224)
		(layer "In11.Cu")
		(net "M_M_DQS_DN<12>")
	)
	(segment
		(start 76.573888 -114.313208)
		(end 70.343776 -120.54332)
		(width 0.14224)
		(layer "In11.Cu")
		(net "M_M_DQS_DN<12>")
	)
	(segment
		(start 84.865972 -87.57412)
		(end 84.859622 -87.584788)
		(width 0.0889)
		(layer "In11.Cu")
		(net "M_M_DQS_DN<12>")
	)
	(segment
		(start 80.509872 -100.065586)
		(end 80.2767 -100.48875)
		(width 0.0889)
		(layer "In11.Cu")
		(net "M_M_DQS_DN<12>")
	)
	(segment
		(start 63.22695 -150.523448)
		(end 63.22695 -150.9268)
		(width 0.14224)
		(layer "In11.Cu")
		(net "M_M_DQS_DN<12>")
	)
	(segment
		(start 84.859622 -89.565988)
		(end 84.854796 -89.574624)
		(width 0.0889)
		(layer "In11.Cu")
		(net "M_M_DQS_DN<12>")
	)
	(segment
		(start 80.31607 -105.120186)
		(end 76.573888 -108.862368)
		(width 0.14224)
		(layer "In11.Cu")
		(net "M_M_DQS_DN<12>")
	)
	(segment
		(start 84.859622 -88.575388)
		(end 84.854796 -88.584024)
		(width 0.0889)
		(layer "In11.Cu")
		(net "M_M_DQS_DN<12>")
	)
	(segment
		(start 63.574422 -124.67844)
		(end 63.574422 -149.313646)
		(width 0.14224)
		(layer "In11.Cu")
		(net "M_M_DQS_DN<12>")
	)
	(arc
		(start 84.854796 -89.574624)
		(mid 84.806041 -89.770976)
		(end 84.859622 -89.966038)
		(width 0.0889)
		(layer "In11.Cu")
		(net "M_M_DQS_DN<12>")
	)
	(arc
		(start 84.332826 -92.83319)
		(mid 83.999908 -93.035181)
		(end 83.996276 -93.424502)
		(width 0.0889)
		(layer "In11.Cu")
		(net "M_M_DQS_DN<12>")
	)
	(arc
		(start 84.859622 -90.956638)
		(mid 84.938844 -91.245756)
		(end 84.865972 -91.53652)
		(width 0.0889)
		(layer "In11.Cu")
		(net "M_M_DQS_DN<12>")
	)
	(arc
		(start 84.854796 -91.555824)
		(mid 84.806041 -91.752176)
		(end 84.859622 -91.947238)
		(width 0.0889)
		(layer "In11.Cu")
		(net "M_M_DQS_DN<12>")
	)
	(arc
		(start 84.859622 -87.984838)
		(mid 84.938844 -88.273956)
		(end 84.865972 -88.56472)
		(width 0.0889)
		(layer "In11.Cu")
		(net "M_M_DQS_DN<12>")
	)
	(arc
		(start 84.859622 -89.966038)
		(mid 84.938844 -90.255156)
		(end 84.865972 -90.54592)
		(width 0.0889)
		(layer "In11.Cu")
		(net "M_M_DQS_DN<12>")
	)
	(arc
		(start 84.001102 -94.423484)
		(mid 84.080233 -94.718886)
		(end 84.001102 -95.014288)
		(width 0.0889)
		(layer "In11.Cu")
		(net "M_M_DQS_DN<12>")
	)
	(arc
		(start 84.859622 -91.947238)
		(mid 84.863951 -92.53041)
		(end 84.365592 -92.83319)
		(width 0.0889)
		(layer "In11.Cu")
		(net "M_M_DQS_DN<12>")
	)
	(arc
		(start 84.859622 -86.003638)
		(mid 84.938844 -86.292756)
		(end 84.865972 -86.58352)
		(width 0.0889)
		(layer "In11.Cu")
		(net "M_M_DQS_DN<12>")
	)
	(arc
		(start 84.001102 -95.014288)
		(mid 83.947632 -95.209351)
		(end 83.996276 -95.405702)
		(width 0.0889)
		(layer "In11.Cu")
		(net "M_M_DQS_DN<12>")
	)
	(arc
		(start 84.854796 -86.602824)
		(mid 84.806041 -86.799176)
		(end 84.859622 -86.994238)
		(width 0.0889)
		(layer "In11.Cu")
		(net "M_M_DQS_DN<12>")
	)
	(arc
		(start 84.859622 -88.975438)
		(mid 84.938844 -89.264556)
		(end 84.865972 -89.55532)
		(width 0.0889)
		(layer "In11.Cu")
		(net "M_M_DQS_DN<12>")
	)
	(arc
		(start 84.854796 -87.593424)
		(mid 84.806041 -87.789776)
		(end 84.859622 -87.984838)
		(width 0.0889)
		(layer "In11.Cu")
		(net "M_M_DQS_DN<12>")
	)
	(arc
		(start 84.001102 -94.023688)
		(mid 83.947603 -94.223586)
		(end 84.001102 -94.423484)
		(width 0.0889)
		(layer "In11.Cu")
		(net "M_M_DQS_DN<12>")
	)
	(arc
		(start 85.14842 -85.4075)
		(mid 84.846151 -85.629049)
		(end 84.859622 -86.003638)
		(width 0.0889)
		(layer "In11.Cu")
		(net "M_M_DQS_DN<12>")
	)
	(arc
		(start 84.001102 -93.433138)
		(mid 84.080324 -93.722256)
		(end 84.007452 -94.01302)
		(width 0.0889)
		(layer "In11.Cu")
		(net "M_M_DQS_DN<12>")
	)
	(arc
		(start 84.854796 -88.584024)
		(mid 84.806041 -88.780376)
		(end 84.859622 -88.975438)
		(width 0.0889)
		(layer "In11.Cu")
		(net "M_M_DQS_DN<12>")
	)
	(arc
		(start 84.859622 -86.994238)
		(mid 84.938844 -87.283356)
		(end 84.865972 -87.57412)
		(width 0.0889)
		(layer "In11.Cu")
		(net "M_M_DQS_DN<12>")
	)
	(arc
		(start 84.007452 -95.425006)
		(mid 84.08025 -95.715769)
		(end 84.001102 -96.004888)
		(width 0.0889)
		(layer "In11.Cu")
		(net "M_M_DQS_DN<12>")
	)
	(arc
		(start 84.854796 -90.565224)
		(mid 84.806041 -90.761576)
		(end 84.859622 -90.956638)
		(width 0.0889)
		(layer "In11.Cu")
		(net "M_M_DQS_DN<12>")
	)
	(segment
		(start 53.467762 -154.2669)
		(end 53.448712 -154.2669)
		(width 0.1651)
		(layer "F.Cu")
		(net "M_M_DQS_DN<11>")
	)
	(segment
		(start 81.485232 -93.23324)
		(end 80.913732 -93.23324)
		(width 0.1651)
		(layer "F.Cu")
		(net "M_M_DQS_DN<11>")
	)
	(segment
		(start 53.656992 -154.45613)
		(end 53.467762 -154.2669)
		(width 0.1651)
		(layer "F.Cu")
		(net "M_M_DQS_DN<11>")
	)
	(segment
		(start 54.349396 -152.932384)
		(end 53.931312 -153.350468)
		(width 0.1651)
		(layer "F.Cu")
		(net "M_M_DQS_DN<11>")
	)
	(segment
		(start 53.931312 -153.350468)
		(end 53.931312 -153.7716)
		(width 0.1651)
		(layer "F.Cu")
		(net "M_M_DQS_DN<11>")
	)
	(segment
		(start 53.865272 -154.45613)
		(end 53.656992 -154.45613)
		(width 0.1651)
		(layer "F.Cu")
		(net "M_M_DQS_DN<11>")
	)
	(segment
		(start 54.11724 -153.957528)
		(end 54.11724 -154.204162)
		(width 0.1651)
		(layer "F.Cu")
		(net "M_M_DQS_DN<11>")
	)
	(segment
		(start 54.11724 -154.204162)
		(end 53.865272 -154.45613)
		(width 0.1651)
		(layer "F.Cu")
		(net "M_M_DQS_DN<11>")
	)
	(segment
		(start 53.931312 -153.7716)
		(end 54.11724 -153.957528)
		(width 0.1651)
		(layer "F.Cu")
		(net "M_M_DQS_DN<11>")
	)
	(segment
		(start 54.349396 -152.273)
		(end 54.349396 -152.932384)
		(width 0.1651)
		(layer "F.Cu")
		(net "M_M_DQS_DN<11>")
	)
	(via
		(at 53.442108 -150.0886)
		(size 0.508)
		(drill 0.254)
		(layers "F.Cu" "B.Cu")
		(net "M_M_DQS_DN<11>")
	)
	(via
		(at 53.448712 -154.2669)
		(size 0.508)
		(drill 0.254)
		(layers "F.Cu" "B.Cu")
		(net "M_M_DQS_DN<11>")
	)
	(via
		(at 80.913732 -93.23324)
		(size 0.508)
		(drill 0.254)
		(layers "F.Cu" "B.Cu")
		(net "M_M_DQS_DN<11>")
	)
	(segment
		(start 54.349396 -152.078436)
		(end 54.34965 -152.077928)
		(width 0.1651)
		(layer "B.Cu")
		(net "M_M_DQS_DN<11>")
	)
	(segment
		(start 54.34965 -152.077928)
		(end 54.34965 -151.421592)
		(width 0.1651)
		(layer "B.Cu")
		(net "M_M_DQS_DN<11>")
	)
	(segment
		(start 54.34965 -151.421592)
		(end 53.905912 -150.977854)
		(width 0.1651)
		(layer "B.Cu")
		(net "M_M_DQS_DN<11>")
	)
	(segment
		(start 53.905912 -150.977854)
		(end 53.905912 -150.622)
		(width 0.1651)
		(layer "B.Cu")
		(net "M_M_DQS_DN<11>")
	)
	(segment
		(start 53.863748 -149.894036)
		(end 53.636672 -149.894036)
		(width 0.1651)
		(layer "B.Cu")
		(net "M_M_DQS_DN<11>")
	)
	(segment
		(start 54.083712 -150.4442)
		(end 54.083712 -150.114)
		(width 0.1651)
		(layer "B.Cu")
		(net "M_M_DQS_DN<11>")
	)
	(segment
		(start 53.905912 -150.622)
		(end 54.083712 -150.4442)
		(width 0.1651)
		(layer "B.Cu")
		(net "M_M_DQS_DN<11>")
	)
	(segment
		(start 54.083712 -150.114)
		(end 53.863748 -149.894036)
		(width 0.1651)
		(layer "B.Cu")
		(net "M_M_DQS_DN<11>")
	)
	(segment
		(start 53.636672 -149.894036)
		(end 53.442108 -150.0886)
		(width 0.1651)
		(layer "B.Cu")
		(net "M_M_DQS_DN<11>")
	)
	(segment
		(start 53.630576 -151.99106)
		(end 53.630576 -152.34412)
		(width 0.14224)
		(layer "In11.Cu")
		(net "M_M_DQS_DN<11>")
	)
	(segment
		(start 53.876956 -150.9268)
		(end 53.597556 -151.2062)
		(width 0.14224)
		(layer "In11.Cu")
		(net "M_M_DQS_DN<11>")
	)
	(segment
		(start 78.355952 -94.31909)
		(end 78.32598 -94.31909)
		(width 0.0889)
		(layer "In11.Cu")
		(net "M_M_DQS_DN<11>")
	)
	(segment
		(start 80.913732 -93.23324)
		(end 81.206848 -93.064076)
		(width 0.0889)
		(layer "In11.Cu")
		(net "M_M_DQS_DN<11>")
	)
	(segment
		(start 53.449474 -150.0886)
		(end 53.442108 -150.0886)
		(width 0.14224)
		(layer "In11.Cu")
		(net "M_M_DQS_DN<11>")
	)
	(segment
		(start 53.206396 -151.70404)
		(end 53.338476 -151.83612)
		(width 0.14224)
		(layer "In11.Cu")
		(net "M_M_DQS_DN<11>")
	)
	(segment
		(start 53.475636 -152.49906)
		(end 53.346096 -152.49906)
		(width 0.14224)
		(layer "In11.Cu")
		(net "M_M_DQS_DN<11>")
	)
	(segment
		(start 53.368956 -153.162)
		(end 53.694076 -153.162)
		(width 0.14224)
		(layer "In11.Cu")
		(net "M_M_DQS_DN<11>")
	)
	(segment
		(start 53.881782 -153.349706)
		(end 53.881782 -153.83383)
		(width 0.14224)
		(layer "In11.Cu")
		(net "M_M_DQS_DN<11>")
	)
	(segment
		(start 53.338476 -151.83612)
		(end 53.475636 -151.83612)
		(width 0.14224)
		(layer "In11.Cu")
		(net "M_M_DQS_DN<11>")
	)
	(segment
		(start 68.313808 -107.460288)
		(end 55.288688 -120.485408)
		(width 0.14224)
		(layer "In11.Cu")
		(net "M_M_DQS_DN<11>")
	)
	(segment
		(start 79.218282 -93.82379)
		(end 79.178658 -93.82379)
		(width 0.0889)
		(layer "In11.Cu")
		(net "M_M_DQS_DN<11>")
	)
	(segment
		(start 71.061072 -102.40391)
		(end 69.514212 -103.95077)
		(width 0.0889)
		(layer "In11.Cu")
		(net "M_M_DQS_DN<11>")
	)
	(segment
		(start 71.491856 -98.281236)
		(end 71.45909 -98.281236)
		(width 0.0889)
		(layer "In11.Cu")
		(net "M_M_DQS_DN<11>")
	)
	(segment
		(start 72.346566 -97.78619)
		(end 72.3138 -97.78619)
		(width 0.0889)
		(layer "In11.Cu")
		(net "M_M_DQS_DN<11>")
	)
	(segment
		(start 74.063606 -96.79559)
		(end 74.03084 -96.79559)
		(width 0.0889)
		(layer "In11.Cu")
		(net "M_M_DQS_DN<11>")
	)
	(segment
		(start 53.881782 -153.83383)
		(end 53.448712 -154.2669)
		(width 0.14224)
		(layer "In11.Cu")
		(net "M_M_DQS_DN<11>")
	)
	(segment
		(start 68.313808 -105.2068)
		(end 68.313808 -107.460288)
		(width 0.14224)
		(layer "In11.Cu")
		(net "M_M_DQS_DN<11>")
	)
	(segment
		(start 71.123556 -100.462588)
		(end 71.11873 -100.471224)
		(width 0.0889)
		(layer "In11.Cu")
		(net "M_M_DQS_DN<11>")
	)
	(segment
		(start 53.876956 -150.523448)
		(end 53.876956 -150.9268)
		(width 0.14224)
		(layer "In11.Cu")
		(net "M_M_DQS_DN<11>")
	)
	(segment
		(start 53.206396 -152.99944)
		(end 53.368956 -153.162)
		(width 0.14224)
		(layer "In11.Cu")
		(net "M_M_DQS_DN<11>")
	)
	(segment
		(start 53.346096 -152.49906)
		(end 53.206396 -152.63876)
		(width 0.14224)
		(layer "In11.Cu")
		(net "M_M_DQS_DN<11>")
	)
	(segment
		(start 77.49286 -94.81439)
		(end 77.46492 -94.81439)
		(width 0.0889)
		(layer "In11.Cu")
		(net "M_M_DQS_DN<11>")
	)
	(segment
		(start 75.780646 -95.80499)
		(end 75.74788 -95.80499)
		(width 0.0889)
		(layer "In11.Cu")
		(net "M_M_DQS_DN<11>")
	)
	(segment
		(start 71.061072 -101.561392)
		(end 71.061072 -102.40391)
		(width 0.0889)
		(layer "In11.Cu")
		(net "M_M_DQS_DN<11>")
	)
	(segment
		(start 53.442108 -150.0886)
		(end 53.876956 -150.523448)
		(width 0.14224)
		(layer "In11.Cu")
		(net "M_M_DQS_DN<11>")
	)
	(segment
		(start 80.928718 -92.83319)
		(end 80.898746 -92.83319)
		(width 0.0889)
		(layer "In11.Cu")
		(net "M_M_DQS_DN<11>")
	)
	(segment
		(start 55.288688 -125.971808)
		(end 54.224428 -127.036068)
		(width 0.14224)
		(layer "In11.Cu")
		(net "M_M_DQS_DN<11>")
	)
	(segment
		(start 71.123556 -99.872038)
		(end 71.129906 -99.882706)
		(width 0.0889)
		(layer "In11.Cu")
		(net "M_M_DQS_DN<11>")
	)
	(segment
		(start 54.224428 -127.036068)
		(end 54.224428 -149.313646)
		(width 0.14224)
		(layer "In11.Cu")
		(net "M_M_DQS_DN<11>")
	)
	(segment
		(start 73.208896 -97.290636)
		(end 73.17613 -97.290636)
		(width 0.0889)
		(layer "In11.Cu")
		(net "M_M_DQS_DN<11>")
	)
	(segment
		(start 54.224428 -149.313646)
		(end 53.449474 -150.0886)
		(width 0.14224)
		(layer "In11.Cu")
		(net "M_M_DQS_DN<11>")
	)
	(segment
		(start 69.514212 -103.95077)
		(end 69.514212 -104.006396)
		(width 0.0889)
		(layer "In11.Cu")
		(net "M_M_DQS_DN<11>")
	)
	(segment
		(start 53.630576 -152.34412)
		(end 53.475636 -152.49906)
		(width 0.14224)
		(layer "In11.Cu")
		(net "M_M_DQS_DN<11>")
	)
	(segment
		(start 53.206396 -152.63876)
		(end 53.206396 -152.99944)
		(width 0.14224)
		(layer "In11.Cu")
		(net "M_M_DQS_DN<11>")
	)
	(segment
		(start 81.206848 -93.064076)
		(end 81.22793 -92.985336)
		(width 0.0889)
		(layer "In11.Cu")
		(net "M_M_DQS_DN<11>")
	)
	(segment
		(start 53.694076 -153.162)
		(end 53.881782 -153.349706)
		(width 0.14224)
		(layer "In11.Cu")
		(net "M_M_DQS_DN<11>")
	)
	(segment
		(start 69.498464 -104.022144)
		(end 68.313808 -105.2068)
		(width 0.14224)
		(layer "In11.Cu")
		(net "M_M_DQS_DN<11>")
	)
	(segment
		(start 69.514212 -104.006396)
		(end 69.498464 -104.022144)
		(width 0.0889)
		(layer "In11.Cu")
		(net "M_M_DQS_DN<11>")
	)
	(segment
		(start 80.068166 -93.32849)
		(end 80.044036 -93.32849)
		(width 0.0889)
		(layer "In11.Cu")
		(net "M_M_DQS_DN<11>")
	)
	(segment
		(start 55.288688 -120.485408)
		(end 55.288688 -125.971808)
		(width 0.14224)
		(layer "In11.Cu")
		(net "M_M_DQS_DN<11>")
	)
	(segment
		(start 76.642976 -95.309436)
		(end 76.61021 -95.309436)
		(width 0.0889)
		(layer "In11.Cu")
		(net "M_M_DQS_DN<11>")
	)
	(segment
		(start 53.475636 -151.83612)
		(end 53.630576 -151.99106)
		(width 0.14224)
		(layer "In11.Cu")
		(net "M_M_DQS_DN<11>")
	)
	(segment
		(start 53.356256 -151.2062)
		(end 53.206396 -151.35606)
		(width 0.14224)
		(layer "In11.Cu")
		(net "M_M_DQS_DN<11>")
	)
	(segment
		(start 71.129906 -101.44252)
		(end 71.061072 -101.561392)
		(width 0.0889)
		(layer "In11.Cu")
		(net "M_M_DQS_DN<11>")
	)
	(segment
		(start 74.925936 -96.300036)
		(end 74.89317 -96.300036)
		(width 0.0889)
		(layer "In11.Cu")
		(net "M_M_DQS_DN<11>")
	)
	(segment
		(start 53.206396 -151.35606)
		(end 53.206396 -151.70404)
		(width 0.14224)
		(layer "In11.Cu")
		(net "M_M_DQS_DN<11>")
	)
	(segment
		(start 53.597556 -151.2062)
		(end 53.356256 -151.2062)
		(width 0.14224)
		(layer "In11.Cu")
		(net "M_M_DQS_DN<11>")
	)
	(arc
		(start 75.74788 -95.80499)
		(mid 75.556238 -95.862156)
		(end 75.416156 -96.004888)
		(width 0.0889)
		(layer "In11.Cu")
		(net "M_M_DQS_DN<11>")
	)
	(arc
		(start 80.044036 -93.32849)
		(mid 79.850186 -93.38484)
		(end 79.708502 -93.528642)
		(width 0.0889)
		(layer "In11.Cu")
		(net "M_M_DQS_DN<11>")
	)
	(arc
		(start 71.123556 -99.472242)
		(mid 71.070057 -99.67214)
		(end 71.123556 -99.872038)
		(width 0.0889)
		(layer "In11.Cu")
		(net "M_M_DQS_DN<11>")
	)
	(arc
		(start 71.11873 -100.471224)
		(mid 71.069975 -100.667576)
		(end 71.123556 -100.862638)
		(width 0.0889)
		(layer "In11.Cu")
		(net "M_M_DQS_DN<11>")
	)
	(arc
		(start 76.274676 -95.509588)
		(mid 76.066068 -95.72152)
		(end 75.780646 -95.80499)
		(width 0.0889)
		(layer "In11.Cu")
		(net "M_M_DQS_DN<11>")
	)
	(arc
		(start 80.567022 -93.033088)
		(mid 80.356309 -93.246167)
		(end 80.068166 -93.32849)
		(width 0.0889)
		(layer "In11.Cu")
		(net "M_M_DQS_DN<11>")
	)
	(arc
		(start 77.991716 -94.518988)
		(mid 77.781003 -94.732067)
		(end 77.49286 -94.81439)
		(width 0.0889)
		(layer "In11.Cu")
		(net "M_M_DQS_DN<11>")
	)
	(arc
		(start 71.129906 -99.882706)
		(mid 71.202704 -100.173469)
		(end 71.123556 -100.462588)
		(width 0.0889)
		(layer "In11.Cu")
		(net "M_M_DQS_DN<11>")
	)
	(arc
		(start 77.46492 -94.81439)
		(mid 77.273278 -94.871556)
		(end 77.133196 -95.014288)
		(width 0.0889)
		(layer "In11.Cu")
		(net "M_M_DQS_DN<11>")
	)
	(arc
		(start 71.123556 -98.881438)
		(mid 71.202687 -99.17684)
		(end 71.123556 -99.472242)
		(width 0.0889)
		(layer "In11.Cu")
		(net "M_M_DQS_DN<11>")
	)
	(arc
		(start 76.61021 -95.309436)
		(mid 76.41636 -95.365786)
		(end 76.274676 -95.509588)
		(width 0.0889)
		(layer "In11.Cu")
		(net "M_M_DQS_DN<11>")
	)
	(arc
		(start 71.123556 -100.862638)
		(mid 71.202778 -101.151756)
		(end 71.129906 -101.44252)
		(width 0.0889)
		(layer "In11.Cu")
		(net "M_M_DQS_DN<11>")
	)
	(arc
		(start 73.699116 -96.995488)
		(mid 73.492112 -97.206352)
		(end 73.208896 -97.290636)
		(width 0.0889)
		(layer "In11.Cu")
		(net "M_M_DQS_DN<11>")
	)
	(arc
		(start 80.898746 -92.83319)
		(mid 80.707104 -92.890356)
		(end 80.567022 -93.033088)
		(width 0.0889)
		(layer "In11.Cu")
		(net "M_M_DQS_DN<11>")
	)
	(arc
		(start 71.45909 -98.281236)
		(mid 71.120921 -98.486034)
		(end 71.123556 -98.881438)
		(width 0.0889)
		(layer "In11.Cu")
		(net "M_M_DQS_DN<11>")
	)
	(arc
		(start 73.17613 -97.290636)
		(mid 72.98228 -97.346986)
		(end 72.840596 -97.490788)
		(width 0.0889)
		(layer "In11.Cu")
		(net "M_M_DQS_DN<11>")
	)
	(arc
		(start 74.89317 -96.300036)
		(mid 74.69932 -96.356386)
		(end 74.557636 -96.500188)
		(width 0.0889)
		(layer "In11.Cu")
		(net "M_M_DQS_DN<11>")
	)
	(arc
		(start 72.840596 -97.490788)
		(mid 72.631988 -97.70272)
		(end 72.346566 -97.78619)
		(width 0.0889)
		(layer "In11.Cu")
		(net "M_M_DQS_DN<11>")
	)
	(arc
		(start 75.416156 -96.004888)
		(mid 75.209152 -96.215752)
		(end 74.925936 -96.300036)
		(width 0.0889)
		(layer "In11.Cu")
		(net "M_M_DQS_DN<11>")
	)
	(arc
		(start 71.982076 -97.986088)
		(mid 71.775072 -98.196952)
		(end 71.491856 -98.281236)
		(width 0.0889)
		(layer "In11.Cu")
		(net "M_M_DQS_DN<11>")
	)
	(arc
		(start 72.3138 -97.78619)
		(mid 72.122158 -97.843356)
		(end 71.982076 -97.986088)
		(width 0.0889)
		(layer "In11.Cu")
		(net "M_M_DQS_DN<11>")
	)
	(arc
		(start 81.22793 -92.985336)
		(mid 81.095049 -92.876353)
		(end 80.928718 -92.83319)
		(width 0.0889)
		(layer "In11.Cu")
		(net "M_M_DQS_DN<11>")
	)
	(arc
		(start 79.708502 -93.528642)
		(mid 79.501498 -93.739506)
		(end 79.218282 -93.82379)
		(width 0.0889)
		(layer "In11.Cu")
		(net "M_M_DQS_DN<11>")
	)
	(arc
		(start 77.133196 -95.014288)
		(mid 76.926192 -95.225152)
		(end 76.642976 -95.309436)
		(width 0.0889)
		(layer "In11.Cu")
		(net "M_M_DQS_DN<11>")
	)
	(arc
		(start 78.32598 -94.31909)
		(mid 78.132877 -94.375609)
		(end 77.991716 -94.518988)
		(width 0.0889)
		(layer "In11.Cu")
		(net "M_M_DQS_DN<11>")
	)
	(arc
		(start 74.557636 -96.500188)
		(mid 74.349028 -96.71212)
		(end 74.063606 -96.79559)
		(width 0.0889)
		(layer "In11.Cu")
		(net "M_M_DQS_DN<11>")
	)
	(arc
		(start 78.849982 -94.023688)
		(mid 78.641374 -94.23562)
		(end 78.355952 -94.31909)
		(width 0.0889)
		(layer "In11.Cu")
		(net "M_M_DQS_DN<11>")
	)
	(arc
		(start 74.03084 -96.79559)
		(mid 73.839198 -96.852756)
		(end 73.699116 -96.995488)
		(width 0.0889)
		(layer "In11.Cu")
		(net "M_M_DQS_DN<11>")
	)
	(arc
		(start 79.178658 -93.82379)
		(mid 78.988729 -93.88166)
		(end 78.849982 -94.023688)
		(width 0.0889)
		(layer "In11.Cu")
		(net "M_M_DQS_DN<11>")
	)
	(segment
		(start 44.117768 -154.2669)
		(end 44.098718 -154.2669)
		(width 0.1651)
		(layer "F.Cu")
		(net "M_M_DQS_DN<10>")
	)
	(segment
		(start 44.767246 -154.204162)
		(end 44.515278 -154.45613)
		(width 0.1651)
		(layer "F.Cu")
		(net "M_M_DQS_DN<10>")
	)
	(segment
		(start 44.999402 -152.273)
		(end 44.999402 -152.932384)
		(width 0.1651)
		(layer "F.Cu")
		(net "M_M_DQS_DN<10>")
	)
	(segment
		(start 44.515278 -154.45613)
		(end 44.306998 -154.45613)
		(width 0.1651)
		(layer "F.Cu")
		(net "M_M_DQS_DN<10>")
	)
	(segment
		(start 44.581318 -153.7716)
		(end 44.767246 -153.957528)
		(width 0.1651)
		(layer "F.Cu")
		(net "M_M_DQS_DN<10>")
	)
	(segment
		(start 44.767246 -153.957528)
		(end 44.767246 -154.204162)
		(width 0.1651)
		(layer "F.Cu")
		(net "M_M_DQS_DN<10>")
	)
	(segment
		(start 77.192886 -91.747086)
		(end 76.621386 -91.747086)
		(width 0.1651)
		(layer "F.Cu")
		(net "M_M_DQS_DN<10>")
	)
	(segment
		(start 44.306998 -154.45613)
		(end 44.117768 -154.2669)
		(width 0.1651)
		(layer "F.Cu")
		(net "M_M_DQS_DN<10>")
	)
	(segment
		(start 44.581318 -153.350468)
		(end 44.581318 -153.7716)
		(width 0.1651)
		(layer "F.Cu")
		(net "M_M_DQS_DN<10>")
	)
	(segment
		(start 44.999402 -152.932384)
		(end 44.581318 -153.350468)
		(width 0.1651)
		(layer "F.Cu")
		(net "M_M_DQS_DN<10>")
	)
	(via
		(at 76.621386 -91.747086)
		(size 0.508)
		(drill 0.254)
		(layers "F.Cu" "B.Cu")
		(net "M_M_DQS_DN<10>")
	)
	(via
		(at 44.098718 -154.2669)
		(size 0.508)
		(drill 0.254)
		(layers "F.Cu" "B.Cu")
		(net "M_M_DQS_DN<10>")
	)
	(via
		(at 44.092114 -150.0886)
		(size 0.508)
		(drill 0.254)
		(layers "F.Cu" "B.Cu")
		(net "M_M_DQS_DN<10>")
	)
	(segment
		(start 44.999402 -152.078436)
		(end 44.999402 -151.421338)
		(width 0.1651)
		(layer "B.Cu")
		(net "M_M_DQS_DN<10>")
	)
	(segment
		(start 44.286678 -149.894036)
		(end 44.092114 -150.0886)
		(width 0.1651)
		(layer "B.Cu")
		(net "M_M_DQS_DN<10>")
	)
	(segment
		(start 44.555918 -150.622)
		(end 44.733718 -150.4442)
		(width 0.1651)
		(layer "B.Cu")
		(net "M_M_DQS_DN<10>")
	)
	(segment
		(start 44.999402 -151.421338)
		(end 44.555918 -150.977854)
		(width 0.1651)
		(layer "B.Cu")
		(net "M_M_DQS_DN<10>")
	)
	(segment
		(start 44.733718 -150.4442)
		(end 44.733718 -150.114)
		(width 0.1651)
		(layer "B.Cu")
		(net "M_M_DQS_DN<10>")
	)
	(segment
		(start 44.733718 -150.114)
		(end 44.513754 -149.894036)
		(width 0.1651)
		(layer "B.Cu")
		(net "M_M_DQS_DN<10>")
	)
	(segment
		(start 44.555918 -150.977854)
		(end 44.555918 -150.622)
		(width 0.1651)
		(layer "B.Cu")
		(net "M_M_DQS_DN<10>")
	)
	(segment
		(start 44.513754 -149.894036)
		(end 44.286678 -149.894036)
		(width 0.1651)
		(layer "B.Cu")
		(net "M_M_DQS_DN<10>")
	)
	(segment
		(start 44.298362 -152.34412)
		(end 44.143422 -152.49906)
		(width 0.14224)
		(layer "In11.Cu")
		(net "M_M_DQS_DN<10>")
	)
	(segment
		(start 44.006262 -151.2062)
		(end 43.856402 -151.35606)
		(width 0.14224)
		(layer "In11.Cu")
		(net "M_M_DQS_DN<10>")
	)
	(segment
		(start 44.531788 -153.83383)
		(end 44.098718 -154.2669)
		(width 0.14224)
		(layer "In11.Cu")
		(net "M_M_DQS_DN<10>")
	)
	(segment
		(start 44.018962 -153.162)
		(end 44.344082 -153.162)
		(width 0.14224)
		(layer "In11.Cu")
		(net "M_M_DQS_DN<10>")
	)
	(segment
		(start 45.031914 -147.583144)
		(end 44.874434 -147.740624)
		(width 0.14224)
		(layer "In11.Cu")
		(net "M_M_DQS_DN<10>")
	)
	(segment
		(start 43.856402 -151.35606)
		(end 43.856402 -151.70404)
		(width 0.14224)
		(layer "In11.Cu")
		(net "M_M_DQS_DN<10>")
	)
	(segment
		(start 44.09948 -150.0886)
		(end 44.092114 -150.0886)
		(width 0.14224)
		(layer "In11.Cu")
		(net "M_M_DQS_DN<10>")
	)
	(segment
		(start 64.534288 -96.38665)
		(end 63.351918 -96.38665)
		(width 0.14224)
		(layer "In11.Cu")
		(net "M_M_DQS_DN<10>")
	)
	(segment
		(start 67.223386 -94.460314)
		(end 65.33642 -96.34728)
		(width 0.0889)
		(layer "In11.Cu")
		(net "M_M_DQS_DN<10>")
	)
	(segment
		(start 76.632562 -91.347036)
		(end 76.599796 -91.347036)
		(width 0.0889)
		(layer "In11.Cu")
		(net "M_M_DQS_DN<10>")
	)
	(segment
		(start 43.856402 -151.70404)
		(end 43.988482 -151.83612)
		(width 0.14224)
		(layer "In11.Cu")
		(net "M_M_DQS_DN<10>")
	)
	(segment
		(start 70.629526 -92.83319)
		(end 70.59676 -92.83319)
		(width 0.0889)
		(layer "In11.Cu")
		(net "M_M_DQS_DN<10>")
	)
	(segment
		(start 69.765926 -93.328236)
		(end 69.320664 -93.328236)
		(width 0.0889)
		(layer "In11.Cu")
		(net "M_M_DQS_DN<10>")
	)
	(segment
		(start 45.095922 -125.412754)
		(end 44.874434 -125.634242)
		(width 0.14224)
		(layer "In11.Cu")
		(net "M_M_DQS_DN<10>")
	)
	(segment
		(start 69.320664 -93.328236)
		(end 68.188586 -94.460314)
		(width 0.0889)
		(layer "In11.Cu")
		(net "M_M_DQS_DN<10>")
	)
	(segment
		(start 44.531788 -153.349706)
		(end 44.531788 -153.83383)
		(width 0.14224)
		(layer "In11.Cu")
		(net "M_M_DQS_DN<10>")
	)
	(segment
		(start 44.874434 -149.313646)
		(end 44.09948 -150.0886)
		(width 0.14224)
		(layer "In11.Cu")
		(net "M_M_DQS_DN<10>")
	)
	(segment
		(start 45.095922 -127.698754)
		(end 44.874434 -127.920242)
		(width 0.14224)
		(layer "In11.Cu")
		(net "M_M_DQS_DN<10>")
	)
	(segment
		(start 44.143422 -152.49906)
		(end 43.996102 -152.49906)
		(width 0.14224)
		(layer "In11.Cu")
		(net "M_M_DQS_DN<10>")
	)
	(segment
		(start 45.031914 -148.152104)
		(end 45.031914 -148.406104)
		(width 0.14224)
		(layer "In11.Cu")
		(net "M_M_DQS_DN<10>")
	)
	(segment
		(start 44.874434 -147.740624)
		(end 44.874434 -147.994624)
		(width 0.14224)
		(layer "In11.Cu")
		(net "M_M_DQS_DN<10>")
	)
	(segment
		(start 44.247562 -151.2062)
		(end 44.006262 -151.2062)
		(width 0.14224)
		(layer "In11.Cu")
		(net "M_M_DQS_DN<10>")
	)
	(segment
		(start 45.926756 -125.034548)
		(end 45.54855 -125.412754)
		(width 0.14224)
		(layer "In11.Cu")
		(net "M_M_DQS_DN<10>")
	)
	(segment
		(start 76.914502 -91.91625)
		(end 76.993242 -91.894914)
		(width 0.0889)
		(layer "In11.Cu")
		(net "M_M_DQS_DN<10>")
	)
	(segment
		(start 45.031914 -148.406104)
		(end 44.874434 -148.563584)
		(width 0.14224)
		(layer "In11.Cu")
		(net "M_M_DQS_DN<10>")
	)
	(segment
		(start 44.874434 -147.994624)
		(end 45.031914 -148.152104)
		(width 0.14224)
		(layer "In11.Cu")
		(net "M_M_DQS_DN<10>")
	)
	(segment
		(start 44.526962 -150.9268)
		(end 44.247562 -151.2062)
		(width 0.14224)
		(layer "In11.Cu")
		(net "M_M_DQS_DN<10>")
	)
	(segment
		(start 64.595756 -96.34728)
		(end 64.556386 -96.38665)
		(width 0.0889)
		(layer "In11.Cu")
		(net "M_M_DQS_DN<10>")
	)
	(segment
		(start 73.208896 -91.347036)
		(end 73.17613 -91.347036)
		(width 0.0889)
		(layer "In11.Cu")
		(net "M_M_DQS_DN<10>")
	)
	(segment
		(start 45.095922 -124.000514)
		(end 45.54855 -124.000514)
		(width 0.14224)
		(layer "In11.Cu")
		(net "M_M_DQS_DN<10>")
	)
	(segment
		(start 44.874434 -147.171664)
		(end 45.031914 -147.329144)
		(width 0.14224)
		(layer "In11.Cu")
		(net "M_M_DQS_DN<10>")
	)
	(segment
		(start 76.621386 -91.747086)
		(end 76.830174 -91.867482)
		(width 0.0889)
		(layer "In11.Cu")
		(net "M_M_DQS_DN<10>")
	)
	(segment
		(start 44.298362 -151.99106)
		(end 44.298362 -152.34412)
		(width 0.14224)
		(layer "In11.Cu")
		(net "M_M_DQS_DN<10>")
	)
	(segment
		(start 68.188586 -94.460314)
		(end 67.223386 -94.460314)
		(width 0.0889)
		(layer "In11.Cu")
		(net "M_M_DQS_DN<10>")
	)
	(segment
		(start 45.948092 -126.676912)
		(end 45.948092 -127.33274)
		(width 0.14224)
		(layer "In11.Cu")
		(net "M_M_DQS_DN<10>")
	)
	(segment
		(start 45.557694 -126.286514)
		(end 45.948092 -126.676912)
		(width 0.14224)
		(layer "In11.Cu")
		(net "M_M_DQS_DN<10>")
	)
	(segment
		(start 43.856402 -152.99944)
		(end 44.018962 -153.162)
		(width 0.14224)
		(layer "In11.Cu")
		(net "M_M_DQS_DN<10>")
	)
	(segment
		(start 44.874434 -148.563584)
		(end 44.874434 -149.313646)
		(width 0.14224)
		(layer "In11.Cu")
		(net "M_M_DQS_DN<10>")
	)
	(segment
		(start 43.996102 -152.49906)
		(end 43.856402 -152.63876)
		(width 0.14224)
		(layer "In11.Cu")
		(net "M_M_DQS_DN<10>")
	)
	(segment
		(start 44.143422 -151.83612)
		(end 44.298362 -151.99106)
		(width 0.14224)
		(layer "In11.Cu")
		(net "M_M_DQS_DN<10>")
	)
	(segment
		(start 44.874434 -125.634242)
		(end 44.874434 -126.065026)
		(width 0.14224)
		(layer "In11.Cu")
		(net "M_M_DQS_DN<10>")
	)
	(segment
		(start 74.905108 -90.35669)
		(end 74.903584 -90.35669)
		(width 0.0889)
		(layer "In11.Cu")
		(net "M_M_DQS_DN<10>")
	)
	(segment
		(start 45.54855 -125.412754)
		(end 45.095922 -125.412754)
		(width 0.14224)
		(layer "In11.Cu")
		(net "M_M_DQS_DN<10>")
	)
	(segment
		(start 72.346566 -91.84259)
		(end 72.3138 -91.84259)
		(width 0.0889)
		(layer "In11.Cu")
		(net "M_M_DQS_DN<10>")
	)
	(segment
		(start 44.344082 -153.162)
		(end 44.531788 -153.349706)
		(width 0.14224)
		(layer "In11.Cu")
		(net "M_M_DQS_DN<10>")
	)
	(segment
		(start 44.092114 -150.0886)
		(end 44.526962 -150.523448)
		(width 0.14224)
		(layer "In11.Cu")
		(net "M_M_DQS_DN<10>")
	)
	(segment
		(start 45.031914 -147.329144)
		(end 45.031914 -147.583144)
		(width 0.14224)
		(layer "In11.Cu")
		(net "M_M_DQS_DN<10>")
	)
	(segment
		(start 45.948092 -127.33274)
		(end 45.582078 -127.698754)
		(width 0.14224)
		(layer "In11.Cu")
		(net "M_M_DQS_DN<10>")
	)
	(segment
		(start 76.830174 -91.867482)
		(end 76.914502 -91.91625)
		(width 0.0889)
		(layer "In11.Cu")
		(net "M_M_DQS_DN<10>")
	)
	(segment
		(start 43.856402 -152.63876)
		(end 43.856402 -152.99944)
		(width 0.14224)
		(layer "In11.Cu")
		(net "M_M_DQS_DN<10>")
	)
	(segment
		(start 44.874434 -127.920242)
		(end 44.874434 -147.171664)
		(width 0.14224)
		(layer "In11.Cu")
		(net "M_M_DQS_DN<10>")
	)
	(segment
		(start 43.988482 -151.83612)
		(end 44.143422 -151.83612)
		(width 0.14224)
		(layer "In11.Cu")
		(net "M_M_DQS_DN<10>")
	)
	(segment
		(start 63.351918 -96.38665)
		(end 61.669168 -98.0694)
		(width 0.14224)
		(layer "In11.Cu")
		(net "M_M_DQS_DN<10>")
	)
	(segment
		(start 44.874434 -123.779026)
		(end 45.095922 -124.000514)
		(width 0.14224)
		(layer "In11.Cu")
		(net "M_M_DQS_DN<10>")
	)
	(segment
		(start 74.059542 -90.85199)
		(end 74.03084 -90.85199)
		(width 0.0889)
		(layer "In11.Cu")
		(net "M_M_DQS_DN<10>")
	)
	(segment
		(start 61.669168 -101.313234)
		(end 44.874434 -118.107968)
		(width 0.14224)
		(layer "In11.Cu")
		(net "M_M_DQS_DN<10>")
	)
	(segment
		(start 45.54855 -124.000514)
		(end 45.926756 -124.37872)
		(width 0.14224)
		(layer "In11.Cu")
		(net "M_M_DQS_DN<10>")
	)
	(segment
		(start 44.874434 -126.065026)
		(end 45.095922 -126.286514)
		(width 0.14224)
		(layer "In11.Cu")
		(net "M_M_DQS_DN<10>")
	)
	(segment
		(start 61.669168 -98.0694)
		(end 61.669168 -101.313234)
		(width 0.14224)
		(layer "In11.Cu")
		(net "M_M_DQS_DN<10>")
	)
	(segment
		(start 71.491856 -92.337636)
		(end 71.45909 -92.337636)
		(width 0.0889)
		(layer "In11.Cu")
		(net "M_M_DQS_DN<10>")
	)
	(segment
		(start 44.526962 -150.523448)
		(end 44.526962 -150.9268)
		(width 0.14224)
		(layer "In11.Cu")
		(net "M_M_DQS_DN<10>")
	)
	(segment
		(start 45.582078 -127.698754)
		(end 45.095922 -127.698754)
		(width 0.14224)
		(layer "In11.Cu")
		(net "M_M_DQS_DN<10>")
	)
	(segment
		(start 65.33642 -96.34728)
		(end 64.595756 -96.34728)
		(width 0.0889)
		(layer "In11.Cu")
		(net "M_M_DQS_DN<10>")
	)
	(segment
		(start 64.556386 -96.38665)
		(end 64.534288 -96.38665)
		(width 0.0889)
		(layer "In11.Cu")
		(net "M_M_DQS_DN<10>")
	)
	(segment
		(start 45.926756 -124.37872)
		(end 45.926756 -125.034548)
		(width 0.14224)
		(layer "In11.Cu")
		(net "M_M_DQS_DN<10>")
	)
	(segment
		(start 75.777852 -90.85199)
		(end 75.74915 -90.85199)
		(width 0.0889)
		(layer "In11.Cu")
		(net "M_M_DQS_DN<10>")
	)
	(segment
		(start 44.874434 -118.107968)
		(end 44.874434 -123.779026)
		(width 0.14224)
		(layer "In11.Cu")
		(net "M_M_DQS_DN<10>")
	)
	(segment
		(start 69.76618 -93.32849)
		(end 69.765926 -93.328236)
		(width 0.0889)
		(layer "In11.Cu")
		(net "M_M_DQS_DN<10>")
	)
	(segment
		(start 45.095922 -126.286514)
		(end 45.557694 -126.286514)
		(width 0.14224)
		(layer "In11.Cu")
		(net "M_M_DQS_DN<10>")
	)
	(arc
		(start 72.840596 -91.547188)
		(mid 72.631988 -91.75912)
		(end 72.346566 -91.84259)
		(width 0.0889)
		(layer "In11.Cu")
		(net "M_M_DQS_DN<10>")
	)
	(arc
		(start 75.251056 -90.556588)
		(mid 75.104884 -90.410253)
		(end 74.905108 -90.35669)
		(width 0.0889)
		(layer "In11.Cu")
		(net "M_M_DQS_DN<10>")
	)
	(arc
		(start 71.982076 -92.042488)
		(mid 71.775072 -92.253352)
		(end 71.491856 -92.337636)
		(width 0.0889)
		(layer "In11.Cu")
		(net "M_M_DQS_DN<10>")
	)
	(arc
		(start 76.109576 -91.051888)
		(mid 75.969497 -90.909152)
		(end 75.777852 -90.85199)
		(width 0.0889)
		(layer "In11.Cu")
		(net "M_M_DQS_DN<10>")
	)
	(arc
		(start 70.59676 -92.83319)
		(mid 70.405118 -92.890356)
		(end 70.265036 -93.033088)
		(width 0.0889)
		(layer "In11.Cu")
		(net "M_M_DQS_DN<10>")
	)
	(arc
		(start 72.3138 -91.84259)
		(mid 72.122158 -91.899756)
		(end 71.982076 -92.042488)
		(width 0.0889)
		(layer "In11.Cu")
		(net "M_M_DQS_DN<10>")
	)
	(arc
		(start 75.74915 -90.85199)
		(mid 75.461463 -90.769469)
		(end 75.251056 -90.556588)
		(width 0.0889)
		(layer "In11.Cu")
		(net "M_M_DQS_DN<10>")
	)
	(arc
		(start 76.599796 -91.347036)
		(mid 76.316579 -91.262755)
		(end 76.109576 -91.051888)
		(width 0.0889)
		(layer "In11.Cu")
		(net "M_M_DQS_DN<10>")
	)
	(arc
		(start 74.557636 -90.556588)
		(mid 74.347283 -90.76956)
		(end 74.059542 -90.85199)
		(width 0.0889)
		(layer "In11.Cu")
		(net "M_M_DQS_DN<10>")
	)
	(arc
		(start 74.03084 -90.85199)
		(mid 73.839198 -90.909156)
		(end 73.699116 -91.051888)
		(width 0.0889)
		(layer "In11.Cu")
		(net "M_M_DQS_DN<10>")
	)
	(arc
		(start 76.993242 -91.894914)
		(mid 76.955602 -91.526975)
		(end 76.632562 -91.347036)
		(width 0.0889)
		(layer "In11.Cu")
		(net "M_M_DQS_DN<10>")
	)
	(arc
		(start 71.45909 -92.337636)
		(mid 71.26524 -92.393986)
		(end 71.123556 -92.537788)
		(width 0.0889)
		(layer "In11.Cu")
		(net "M_M_DQS_DN<10>")
	)
	(arc
		(start 73.17613 -91.347036)
		(mid 72.98228 -91.403386)
		(end 72.840596 -91.547188)
		(width 0.0889)
		(layer "In11.Cu")
		(net "M_M_DQS_DN<10>")
	)
	(arc
		(start 73.699116 -91.051888)
		(mid 73.492112 -91.262752)
		(end 73.208896 -91.347036)
		(width 0.0889)
		(layer "In11.Cu")
		(net "M_M_DQS_DN<10>")
	)
	(arc
		(start 71.123556 -92.537788)
		(mid 70.914948 -92.74972)
		(end 70.629526 -92.83319)
		(width 0.0889)
		(layer "In11.Cu")
		(net "M_M_DQS_DN<10>")
	)
	(arc
		(start 74.903584 -90.35669)
		(mid 74.703811 -90.410259)
		(end 74.557636 -90.556588)
		(width 0.0889)
		(layer "In11.Cu")
		(net "M_M_DQS_DN<10>")
	)
	(arc
		(start 70.265036 -93.033088)
		(mid 70.054323 -93.246167)
		(end 69.76618 -93.32849)
		(width 0.0889)
		(layer "In11.Cu")
		(net "M_M_DQS_DN<10>")
	)
	(segment
		(start 75.475846 -85.803486)
		(end 74.904346 -85.803486)
		(width 0.1651)
		(layer "F.Cu")
		(net "M_M_DQS_DN<0>")
	)
	(segment
		(start 35.649408 -156.87294)
		(end 35.649408 -155.80487)
		(width 0.1651)
		(layer "F.Cu")
		(net "M_M_DQS_DN<0>")
	)
	(segment
		(start 35.649408 -155.80487)
		(end 35.267392 -155.422854)
		(width 0.1651)
		(layer "F.Cu")
		(net "M_M_DQS_DN<0>")
	)
	(segment
		(start 35.267392 -154.991054)
		(end 35.597846 -154.6606)
		(width 0.1651)
		(layer "F.Cu")
		(net "M_M_DQS_DN<0>")
	)
	(segment
		(start 35.597846 -154.6606)
		(end 35.821874 -154.6606)
		(width 0.1651)
		(layer "F.Cu")
		(net "M_M_DQS_DN<0>")
	)
	(segment
		(start 35.267392 -155.422854)
		(end 35.267392 -154.991054)
		(width 0.1651)
		(layer "F.Cu")
		(net "M_M_DQS_DN<0>")
	)
	(segment
		(start 35.821874 -154.6606)
		(end 36.03752 -154.876246)
		(width 0.1651)
		(layer "F.Cu")
		(net "M_M_DQS_DN<0>")
	)
	(via
		(at 74.904346 -85.803486)
		(size 0.508)
		(drill 0.254)
		(layers "F.Cu" "B.Cu")
		(net "M_M_DQS_DN<0>")
	)
	(via
		(at 36.03752 -154.876246)
		(size 0.508)
		(drill 0.254)
		(layers "F.Cu" "B.Cu")
		(net "M_M_DQS_DN<0>")
	)
	(via
		(at 36.03752 -149.482556)
		(size 0.508)
		(drill 0.254)
		(layers "F.Cu" "B.Cu")
		(net "M_M_DQS_DN<0>")
	)
	(segment
		(start 35.521392 -148.767546)
		(end 35.267392 -149.021546)
		(width 0.1651)
		(layer "B.Cu")
		(net "M_M_DQS_DN<0>")
	)
	(segment
		(start 35.622992 -149.7076)
		(end 35.812476 -149.7076)
		(width 0.1651)
		(layer "B.Cu")
		(net "M_M_DQS_DN<0>")
	)
	(segment
		(start 35.267392 -149.021546)
		(end 35.267392 -149.352)
		(width 0.1651)
		(layer "B.Cu")
		(net "M_M_DQS_DN<0>")
	)
	(segment
		(start 35.521392 -148.513546)
		(end 35.521392 -148.767546)
		(width 0.1651)
		(layer "B.Cu")
		(net "M_M_DQS_DN<0>")
	)
	(segment
		(start 35.649408 -147.478496)
		(end 35.649408 -148.38553)
		(width 0.1651)
		(layer "B.Cu")
		(net "M_M_DQS_DN<0>")
	)
	(segment
		(start 35.649408 -148.38553)
		(end 35.521392 -148.513546)
		(width 0.1651)
		(layer "B.Cu")
		(net "M_M_DQS_DN<0>")
	)
	(segment
		(start 35.267392 -149.352)
		(end 35.622992 -149.7076)
		(width 0.1651)
		(layer "B.Cu")
		(net "M_M_DQS_DN<0>")
	)
	(segment
		(start 35.812476 -149.7076)
		(end 36.03752 -149.482556)
		(width 0.1651)
		(layer "B.Cu")
		(net "M_M_DQS_DN<0>")
	)
	(segment
		(start 35.842448 -124.063252)
		(end 35.842448 -124.71908)
		(width 0.14224)
		(layer "In11.Cu")
		(net "M_M_DQS_DN<0>")
	)
	(segment
		(start 37.493448 -112.16132)
		(end 37.493448 -118.89232)
		(width 0.14224)
		(layer "In11.Cu")
		(net "M_M_DQS_DN<0>")
	)
	(segment
		(start 35.842448 -124.71908)
		(end 36.220654 -125.097286)
		(width 0.14224)
		(layer "In11.Cu")
		(net "M_M_DQS_DN<0>")
	)
	(segment
		(start 74.904346 -85.803486)
		(end 74.15022 -85.71738)
		(width 0.0889)
		(layer "In11.Cu")
		(net "M_M_DQS_DN<0>")
	)
	(segment
		(start 36.28263 -149.482556)
		(end 36.03752 -149.482556)
		(width 0.14224)
		(layer "In11.Cu")
		(net "M_M_DQS_DN<0>")
	)
	(segment
		(start 36.519612 -119.113046)
		(end 36.133024 -119.499634)
		(width 0.14224)
		(layer "In11.Cu")
		(net "M_M_DQS_DN<0>")
	)
	(segment
		(start 36.5506 -138.020298)
		(end 36.5506 -138.303508)
		(width 0.14224)
		(layer "In11.Cu")
		(net "M_M_DQS_DN<0>")
	)
	(segment
		(start 36.39312 -138.714988)
		(end 36.5506 -138.872468)
		(width 0.14224)
		(layer "In11.Cu")
		(net "M_M_DQS_DN<0>")
	)
	(segment
		(start 36.5506 -148.609304)
		(end 36.5506 -149.214586)
		(width 0.14224)
		(layer "In11.Cu")
		(net "M_M_DQS_DN<0>")
	)
	(segment
		(start 49.185322 -104.09936)
		(end 45.047408 -104.09936)
		(width 0.14224)
		(layer "In11.Cu")
		(net "M_M_DQS_DN<0>")
	)
	(segment
		(start 35.39363 -152.97658)
		(end 35.60445 -153.1874)
		(width 0.14224)
		(layer "In11.Cu")
		(net "M_M_DQS_DN<0>")
	)
	(segment
		(start 67.188842 -89.67089)
		(end 66.747898 -89.67089)
		(width 0.0889)
		(layer "In11.Cu")
		(net "M_M_DQS_DN<0>")
	)
	(segment
		(start 36.39312 -141.670786)
		(end 36.39312 -141.924786)
		(width 0.14224)
		(layer "In11.Cu")
		(net "M_M_DQS_DN<0>")
	)
	(segment
		(start 35.933634 -121.777252)
		(end 35.933634 -122.43308)
		(width 0.14224)
		(layer "In11.Cu")
		(net "M_M_DQS_DN<0>")
	)
	(segment
		(start 37.27196 -120.525286)
		(end 37.493448 -120.746774)
		(width 0.14224)
		(layer "In11.Cu")
		(net "M_M_DQS_DN<0>")
	)
	(segment
		(start 45.047408 -104.09936)
		(end 41.105328 -108.04144)
		(width 0.14224)
		(layer "In11.Cu")
		(net "M_M_DQS_DN<0>")
	)
	(segment
		(start 36.5506 -137.509758)
		(end 36.42233 -137.638028)
		(width 0.14224)
		(layer "In11.Cu")
		(net "M_M_DQS_DN<0>")
	)
	(segment
		(start 73.202292 -86.203536)
		(end 73.169526 -86.203536)
		(width 0.0889)
		(layer "In11.Cu")
		(net "M_M_DQS_DN<0>")
	)
	(segment
		(start 36.5506 -146.963384)
		(end 36.5506 -147.217384)
		(width 0.14224)
		(layer "In11.Cu")
		(net "M_M_DQS_DN<0>")
	)
	(segment
		(start 37.493448 -120.746774)
		(end 37.493448 -121.177558)
		(width 0.14224)
		(layer "In11.Cu")
		(net "M_M_DQS_DN<0>")
	)
	(segment
		(start 36.502848 -120.525286)
		(end 37.27196 -120.525286)
		(width 0.14224)
		(layer "In11.Cu")
		(net "M_M_DQS_DN<0>")
	)
	(segment
		(start 36.5506 -149.214586)
		(end 36.28263 -149.482556)
		(width 0.14224)
		(layer "In11.Cu")
		(net "M_M_DQS_DN<0>")
	)
	(segment
		(start 37.272722 -119.113046)
		(end 36.519612 -119.113046)
		(width 0.14224)
		(layer "In11.Cu")
		(net "M_M_DQS_DN<0>")
	)
	(segment
		(start 36.42233 -137.638028)
		(end 36.42233 -137.892028)
		(width 0.14224)
		(layer "In11.Cu")
		(net "M_M_DQS_DN<0>")
	)
	(segment
		(start 37.27196 -123.685046)
		(end 36.220654 -123.685046)
		(width 0.14224)
		(layer "In11.Cu")
		(net "M_M_DQS_DN<0>")
	)
	(segment
		(start 36.5506 -141.513306)
		(end 36.39312 -141.670786)
		(width 0.14224)
		(layer "In11.Cu")
		(net "M_M_DQS_DN<0>")
	)
	(segment
		(start 36.5506 -138.872468)
		(end 36.5506 -141.513306)
		(width 0.14224)
		(layer "In11.Cu")
		(net "M_M_DQS_DN<0>")
	)
	(segment
		(start 69.768212 -88.184736)
		(end 69.735446 -88.184736)
		(width 0.0889)
		(layer "In11.Cu")
		(net "M_M_DQS_DN<0>")
	)
	(segment
		(start 37.493448 -121.177558)
		(end 37.27196 -121.399046)
		(width 0.14224)
		(layer "In11.Cu")
		(net "M_M_DQS_DN<0>")
	)
	(segment
		(start 36.5506 -138.303508)
		(end 36.39312 -138.460988)
		(width 0.14224)
		(layer "In11.Cu")
		(net "M_M_DQS_DN<0>")
	)
	(segment
		(start 36.03752 -149.482556)
		(end 35.964368 -149.482556)
		(width 0.14224)
		(layer "In11.Cu")
		(net "M_M_DQS_DN<0>")
	)
	(segment
		(start 36.133024 -119.499634)
		(end 36.133024 -120.155462)
		(width 0.14224)
		(layer "In11.Cu")
		(net "M_M_DQS_DN<0>")
	)
	(segment
		(start 36.39312 -143.316706)
		(end 36.39312 -143.570706)
		(width 0.14224)
		(layer "In11.Cu")
		(net "M_M_DQS_DN<0>")
	)
	(segment
		(start 37.493448 -123.463558)
		(end 37.27196 -123.685046)
		(width 0.14224)
		(layer "In11.Cu")
		(net "M_M_DQS_DN<0>")
	)
	(segment
		(start 36.39312 -148.197824)
		(end 36.39312 -148.451824)
		(width 0.14224)
		(layer "In11.Cu")
		(net "M_M_DQS_DN<0>")
	)
	(segment
		(start 72.339962 -86.69909)
		(end 72.307196 -86.69909)
		(width 0.0889)
		(layer "In11.Cu")
		(net "M_M_DQS_DN<0>")
	)
	(segment
		(start 37.22624 -125.097286)
		(end 37.447728 -125.318774)
		(width 0.14224)
		(layer "In11.Cu")
		(net "M_M_DQS_DN<0>")
	)
	(segment
		(start 37.27196 -121.399046)
		(end 36.31184 -121.399046)
		(width 0.14224)
		(layer "In11.Cu")
		(net "M_M_DQS_DN<0>")
	)
	(segment
		(start 63.45047 -89.325704)
		(end 63.428372 -89.325704)
		(width 0.0889)
		(layer "In11.Cu")
		(net "M_M_DQS_DN<0>")
	)
	(segment
		(start 68.905882 -88.68029)
		(end 68.873116 -88.68029)
		(width 0.0889)
		(layer "In11.Cu")
		(net "M_M_DQS_DN<0>")
	)
	(segment
		(start 36.39312 -146.551904)
		(end 36.39312 -146.805904)
		(width 0.14224)
		(layer "In11.Cu")
		(net "M_M_DQS_DN<0>")
	)
	(segment
		(start 36.5506 -143.159226)
		(end 36.39312 -143.316706)
		(width 0.14224)
		(layer "In11.Cu")
		(net "M_M_DQS_DN<0>")
	)
	(segment
		(start 36.5506 -147.786344)
		(end 36.5506 -148.040344)
		(width 0.14224)
		(layer "In11.Cu")
		(net "M_M_DQS_DN<0>")
	)
	(segment
		(start 36.31184 -122.811286)
		(end 37.27196 -122.811286)
		(width 0.14224)
		(layer "In11.Cu")
		(net "M_M_DQS_DN<0>")
	)
	(segment
		(start 36.42233 -137.892028)
		(end 36.5506 -138.020298)
		(width 0.14224)
		(layer "In11.Cu")
		(net "M_M_DQS_DN<0>")
	)
	(segment
		(start 53.515768 -98.5266)
		(end 53.515768 -99.768914)
		(width 0.14224)
		(layer "In11.Cu")
		(net "M_M_DQS_DN<0>")
	)
	(segment
		(start 36.39312 -146.805904)
		(end 36.5506 -146.963384)
		(width 0.14224)
		(layer "In11.Cu")
		(net "M_M_DQS_DN<0>")
	)
	(segment
		(start 36.430458 -136.815068)
		(end 36.430458 -137.069068)
		(width 0.14224)
		(layer "In11.Cu")
		(net "M_M_DQS_DN<0>")
	)
	(segment
		(start 71.485252 -87.194136)
		(end 71.452486 -87.194136)
		(width 0.0889)
		(layer "In11.Cu")
		(net "M_M_DQS_DN<0>")
	)
	(segment
		(start 35.60445 -154.443176)
		(end 36.03752 -154.876246)
		(width 0.14224)
		(layer "In11.Cu")
		(net "M_M_DQS_DN<0>")
	)
	(segment
		(start 36.220654 -125.097286)
		(end 37.22624 -125.097286)
		(width 0.14224)
		(layer "In11.Cu")
		(net "M_M_DQS_DN<0>")
	)
	(segment
		(start 63.428372 -89.325704)
		(end 62.716664 -89.325704)
		(width 0.14224)
		(layer "In11.Cu")
		(net "M_M_DQS_DN<0>")
	)
	(segment
		(start 53.515768 -99.768914)
		(end 49.185322 -104.09936)
		(width 0.14224)
		(layer "In11.Cu")
		(net "M_M_DQS_DN<0>")
	)
	(segment
		(start 36.5506 -142.082266)
		(end 36.5506 -142.336266)
		(width 0.14224)
		(layer "In11.Cu")
		(net "M_M_DQS_DN<0>")
	)
	(segment
		(start 37.447728 -125.777752)
		(end 36.5506 -126.67488)
		(width 0.14224)
		(layer "In11.Cu")
		(net "M_M_DQS_DN<0>")
	)
	(segment
		(start 62.716664 -89.325704)
		(end 53.515768 -98.5266)
		(width 0.14224)
		(layer "In11.Cu")
		(net "M_M_DQS_DN<0>")
	)
	(segment
		(start 41.105328 -108.54944)
		(end 37.493448 -112.16132)
		(width 0.14224)
		(layer "In11.Cu")
		(net "M_M_DQS_DN<0>")
	)
	(segment
		(start 36.430458 -137.069068)
		(end 36.5506 -137.18921)
		(width 0.14224)
		(layer "In11.Cu")
		(net "M_M_DQS_DN<0>")
	)
	(segment
		(start 63.48984 -89.365074)
		(end 63.45047 -89.325704)
		(width 0.0889)
		(layer "In11.Cu")
		(net "M_M_DQS_DN<0>")
	)
	(segment
		(start 36.5506 -148.040344)
		(end 36.39312 -148.197824)
		(width 0.14224)
		(layer "In11.Cu")
		(net "M_M_DQS_DN<0>")
	)
	(segment
		(start 36.31184 -121.399046)
		(end 35.933634 -121.777252)
		(width 0.14224)
		(layer "In11.Cu")
		(net "M_M_DQS_DN<0>")
	)
	(segment
		(start 36.5506 -142.336266)
		(end 36.39312 -142.493746)
		(width 0.14224)
		(layer "In11.Cu")
		(net "M_M_DQS_DN<0>")
	)
	(segment
		(start 36.5506 -137.18921)
		(end 36.5506 -137.509758)
		(width 0.14224)
		(layer "In11.Cu")
		(net "M_M_DQS_DN<0>")
	)
	(segment
		(start 36.39312 -148.451824)
		(end 36.5506 -148.609304)
		(width 0.14224)
		(layer "In11.Cu")
		(net "M_M_DQS_DN<0>")
	)
	(segment
		(start 36.5506 -136.694926)
		(end 36.430458 -136.815068)
		(width 0.14224)
		(layer "In11.Cu")
		(net "M_M_DQS_DN<0>")
	)
	(segment
		(start 36.39312 -138.460988)
		(end 36.39312 -138.714988)
		(width 0.14224)
		(layer "In11.Cu")
		(net "M_M_DQS_DN<0>")
	)
	(segment
		(start 35.39363 -151.31542)
		(end 35.39363 -152.97658)
		(width 0.14224)
		(layer "In11.Cu")
		(net "M_M_DQS_DN<0>")
	)
	(segment
		(start 36.39312 -147.374864)
		(end 36.39312 -147.628864)
		(width 0.14224)
		(layer "In11.Cu")
		(net "M_M_DQS_DN<0>")
	)
	(segment
		(start 74.067416 -85.70849)
		(end 74.024236 -85.70849)
		(width 0.0889)
		(layer "In11.Cu")
		(net "M_M_DQS_DN<0>")
	)
	(segment
		(start 35.60445 -149.842474)
		(end 35.60445 -151.1046)
		(width 0.14224)
		(layer "In11.Cu")
		(net "M_M_DQS_DN<0>")
	)
	(segment
		(start 66.442082 -89.365074)
		(end 63.48984 -89.365074)
		(width 0.0889)
		(layer "In11.Cu")
		(net "M_M_DQS_DN<0>")
	)
	(segment
		(start 37.447728 -125.318774)
		(end 37.447728 -125.777752)
		(width 0.14224)
		(layer "In11.Cu")
		(net "M_M_DQS_DN<0>")
	)
	(segment
		(start 41.105328 -108.04144)
		(end 41.105328 -108.54944)
		(width 0.14224)
		(layer "In11.Cu")
		(net "M_M_DQS_DN<0>")
	)
	(segment
		(start 35.964368 -149.482556)
		(end 35.60445 -149.842474)
		(width 0.14224)
		(layer "In11.Cu")
		(net "M_M_DQS_DN<0>")
	)
	(segment
		(start 37.493448 -118.89232)
		(end 37.272722 -119.113046)
		(width 0.14224)
		(layer "In11.Cu")
		(net "M_M_DQS_DN<0>")
	)
	(segment
		(start 36.39312 -143.570706)
		(end 36.5506 -143.728186)
		(width 0.14224)
		(layer "In11.Cu")
		(net "M_M_DQS_DN<0>")
	)
	(segment
		(start 36.5506 -147.217384)
		(end 36.39312 -147.374864)
		(width 0.14224)
		(layer "In11.Cu")
		(net "M_M_DQS_DN<0>")
	)
	(segment
		(start 66.747898 -89.67089)
		(end 66.442082 -89.365074)
		(width 0.0889)
		(layer "In11.Cu")
		(net "M_M_DQS_DN<0>")
	)
	(segment
		(start 35.60445 -151.1046)
		(end 35.39363 -151.31542)
		(width 0.14224)
		(layer "In11.Cu")
		(net "M_M_DQS_DN<0>")
	)
	(segment
		(start 36.5506 -142.905226)
		(end 36.5506 -143.159226)
		(width 0.14224)
		(layer "In11.Cu")
		(net "M_M_DQS_DN<0>")
	)
	(segment
		(start 36.39312 -147.628864)
		(end 36.5506 -147.786344)
		(width 0.14224)
		(layer "In11.Cu")
		(net "M_M_DQS_DN<0>")
	)
	(segment
		(start 68.051172 -89.175336)
		(end 68.018406 -89.175336)
		(width 0.0889)
		(layer "In11.Cu")
		(net "M_M_DQS_DN<0>")
	)
	(segment
		(start 36.39312 -141.924786)
		(end 36.5506 -142.082266)
		(width 0.14224)
		(layer "In11.Cu")
		(net "M_M_DQS_DN<0>")
	)
	(segment
		(start 35.933634 -122.43308)
		(end 36.31184 -122.811286)
		(width 0.14224)
		(layer "In11.Cu")
		(net "M_M_DQS_DN<0>")
	)
	(segment
		(start 36.220654 -123.685046)
		(end 35.842448 -124.063252)
		(width 0.14224)
		(layer "In11.Cu")
		(net "M_M_DQS_DN<0>")
	)
	(segment
		(start 37.27196 -122.811286)
		(end 37.493448 -123.032774)
		(width 0.14224)
		(layer "In11.Cu")
		(net "M_M_DQS_DN<0>")
	)
	(segment
		(start 36.39312 -142.493746)
		(end 36.39312 -142.747746)
		(width 0.14224)
		(layer "In11.Cu")
		(net "M_M_DQS_DN<0>")
	)
	(segment
		(start 36.5506 -146.394424)
		(end 36.39312 -146.551904)
		(width 0.14224)
		(layer "In11.Cu")
		(net "M_M_DQS_DN<0>")
	)
	(segment
		(start 36.5506 -126.67488)
		(end 36.5506 -136.694926)
		(width 0.14224)
		(layer "In11.Cu")
		(net "M_M_DQS_DN<0>")
	)
	(segment
		(start 70.622922 -87.68969)
		(end 70.590156 -87.68969)
		(width 0.0889)
		(layer "In11.Cu")
		(net "M_M_DQS_DN<0>")
	)
	(segment
		(start 35.60445 -153.1874)
		(end 35.60445 -154.443176)
		(width 0.14224)
		(layer "In11.Cu")
		(net "M_M_DQS_DN<0>")
	)
	(segment
		(start 36.5506 -143.728186)
		(end 36.5506 -146.394424)
		(width 0.14224)
		(layer "In11.Cu")
		(net "M_M_DQS_DN<0>")
	)
	(segment
		(start 36.39312 -142.747746)
		(end 36.5506 -142.905226)
		(width 0.14224)
		(layer "In11.Cu")
		(net "M_M_DQS_DN<0>")
	)
	(segment
		(start 36.133024 -120.155462)
		(end 36.502848 -120.525286)
		(width 0.14224)
		(layer "In11.Cu")
		(net "M_M_DQS_DN<0>")
	)
	(segment
		(start 37.493448 -123.032774)
		(end 37.493448 -123.463558)
		(width 0.14224)
		(layer "In11.Cu")
		(net "M_M_DQS_DN<0>")
	)
	(arc
		(start 72.675496 -86.498938)
		(mid 72.533813 -86.642742)
		(end 72.339962 -86.69909)
		(width 0.0889)
		(layer "In11.Cu")
		(net "M_M_DQS_DN<0>")
	)
	(arc
		(start 69.241416 -88.480138)
		(mid 69.099733 -88.623942)
		(end 68.905882 -88.68029)
		(width 0.0889)
		(layer "In11.Cu")
		(net "M_M_DQS_DN<0>")
	)
	(arc
		(start 70.099936 -87.984838)
		(mid 69.959857 -88.127574)
		(end 69.768212 -88.184736)
		(width 0.0889)
		(layer "In11.Cu")
		(net "M_M_DQS_DN<0>")
	)
	(arc
		(start 68.873116 -88.68029)
		(mid 68.589899 -88.764571)
		(end 68.382896 -88.975438)
		(width 0.0889)
		(layer "In11.Cu")
		(net "M_M_DQS_DN<0>")
	)
	(arc
		(start 73.169526 -86.203536)
		(mid 72.884102 -86.287003)
		(end 72.675496 -86.498938)
		(width 0.0889)
		(layer "In11.Cu")
		(net "M_M_DQS_DN<0>")
	)
	(arc
		(start 73.534016 -86.003638)
		(mid 73.393937 -86.146374)
		(end 73.202292 -86.203536)
		(width 0.0889)
		(layer "In11.Cu")
		(net "M_M_DQS_DN<0>")
	)
	(arc
		(start 72.307196 -86.69909)
		(mid 72.023979 -86.783371)
		(end 71.816976 -86.994238)
		(width 0.0889)
		(layer "In11.Cu")
		(net "M_M_DQS_DN<0>")
	)
	(arc
		(start 74.024236 -85.70849)
		(mid 73.741019 -85.792771)
		(end 73.534016 -86.003638)
		(width 0.0889)
		(layer "In11.Cu")
		(net "M_M_DQS_DN<0>")
	)
	(arc
		(start 74.15022 -85.71738)
		(mid 74.108975 -85.71147)
		(end 74.067416 -85.70849)
		(width 0.0889)
		(layer "In11.Cu")
		(net "M_M_DQS_DN<0>")
	)
	(arc
		(start 71.816976 -86.994238)
		(mid 71.676897 -87.136974)
		(end 71.485252 -87.194136)
		(width 0.0889)
		(layer "In11.Cu")
		(net "M_M_DQS_DN<0>")
	)
	(arc
		(start 70.958456 -87.489538)
		(mid 70.816773 -87.633342)
		(end 70.622922 -87.68969)
		(width 0.0889)
		(layer "In11.Cu")
		(net "M_M_DQS_DN<0>")
	)
	(arc
		(start 70.590156 -87.68969)
		(mid 70.306939 -87.773971)
		(end 70.099936 -87.984838)
		(width 0.0889)
		(layer "In11.Cu")
		(net "M_M_DQS_DN<0>")
	)
	(arc
		(start 68.018406 -89.175336)
		(mid 67.732982 -89.258803)
		(end 67.524376 -89.470738)
		(width 0.0889)
		(layer "In11.Cu")
		(net "M_M_DQS_DN<0>")
	)
	(arc
		(start 67.524376 -89.470738)
		(mid 67.382693 -89.614542)
		(end 67.188842 -89.67089)
		(width 0.0889)
		(layer "In11.Cu")
		(net "M_M_DQS_DN<0>")
	)
	(arc
		(start 68.382896 -88.975438)
		(mid 68.242817 -89.118174)
		(end 68.051172 -89.175336)
		(width 0.0889)
		(layer "In11.Cu")
		(net "M_M_DQS_DN<0>")
	)
	(arc
		(start 71.452486 -87.194136)
		(mid 71.167062 -87.277603)
		(end 70.958456 -87.489538)
		(width 0.0889)
		(layer "In11.Cu")
		(net "M_M_DQS_DN<0>")
	)
	(arc
		(start 69.735446 -88.184736)
		(mid 69.450022 -88.268203)
		(end 69.241416 -88.480138)
		(width 0.0889)
		(layer "In11.Cu")
		(net "M_M_DQS_DN<0>")
	)
	(segment
		(start 42.449496 -152.273)
		(end 42.449496 -153.542746)
		(width 0.1651)
		(layer "F.Cu")
		(net "M_M_DQ<9>")
	)
	(segment
		(start 76.334366 -90.26144)
		(end 75.762866 -90.26144)
		(width 0.1651)
		(layer "F.Cu")
		(net "M_M_DQ<9>")
	)
	(via
		(at 75.762866 -90.26144)
		(size 0.508)
		(drill 0.254)
		(layers "F.Cu" "B.Cu")
		(net "M_M_DQ<9>")
	)
	(via
		(at 43.12158 -149.533356)
		(size 0.508)
		(drill 0.254)
		(layers "F.Cu" "B.Cu")
		(net "M_M_DQ<9>")
	)
	(via
		(at 42.449496 -153.542746)
		(size 0.508)
		(drill 0.254)
		(layers "F.Cu" "B.Cu")
		(net "M_M_DQ<9>")
	)
	(segment
		(start 43.29938 -148.852382)
		(end 43.12158 -149.030182)
		(width 0.1651)
		(layer "B.Cu")
		(net "M_M_DQ<9>")
	)
	(segment
		(start 43.12158 -149.030182)
		(end 43.12158 -149.533356)
		(width 0.1651)
		(layer "B.Cu")
		(net "M_M_DQ<9>")
	)
	(segment
		(start 43.29938 -147.478496)
		(end 43.29938 -148.852382)
		(width 0.1651)
		(layer "B.Cu")
		(net "M_M_DQ<9>")
	)
	(segment
		(start 64.58585 -95.031814)
		(end 65.594992 -95.031814)
		(width 0.0889)
		(layer "In11.Cu")
		(net "M_M_DQ<9>")
	)
	(segment
		(start 43.609514 -141.3256)
		(end 43.609514 -138.709654)
		(width 0.14224)
		(layer "In11.Cu")
		(net "M_M_DQ<9>")
	)
	(segment
		(start 43.914568 -128.620774)
		(end 43.759628 -128.465834)
		(width 0.14224)
		(layer "In11.Cu")
		(net "M_M_DQ<9>")
	)
	(segment
		(start 43.736768 -143.6624)
		(end 43.736768 -141.452854)
		(width 0.14224)
		(layer "In11.Cu")
		(net "M_M_DQ<9>")
	)
	(segment
		(start 42.825162 -151.892)
		(end 42.610786 -151.677624)
		(width 0.14224)
		(layer "In11.Cu")
		(net "M_M_DQ<9>")
	)
	(segment
		(start 43.914568 -117.745256)
		(end 60.729368 -100.930456)
		(width 0.14224)
		(layer "In11.Cu")
		(net "M_M_DQ<9>")
	)
	(segment
		(start 64.324992 -95.292672)
		(end 64.58585 -95.031814)
		(width 0.0889)
		(layer "In11.Cu")
		(net "M_M_DQ<9>")
	)
	(segment
		(start 43.228768 -121.935748)
		(end 43.431968 -121.732548)
		(width 0.14224)
		(layer "In11.Cu")
		(net "M_M_DQ<9>")
	)
	(segment
		(start 43.914568 -123.154948)
		(end 43.914568 -122.748548)
		(width 0.14224)
		(layer "In11.Cu")
		(net "M_M_DQ<9>")
	)
	(segment
		(start 42.670984 -150.391368)
		(end 42.670984 -149.9616)
		(width 0.14224)
		(layer "In11.Cu")
		(net "M_M_DQ<9>")
	)
	(segment
		(start 43.736768 -146.304254)
		(end 43.609514 -146.177)
		(width 0.14224)
		(layer "In11.Cu")
		(net "M_M_DQ<9>")
	)
	(segment
		(start 43.914568 -119.497348)
		(end 43.711368 -119.294148)
		(width 0.14224)
		(layer "In11.Cu")
		(net "M_M_DQ<9>")
	)
	(segment
		(start 42.610786 -151.677624)
		(end 42.610786 -151.316944)
		(width 0.14224)
		(layer "In11.Cu")
		(net "M_M_DQ<9>")
	)
	(segment
		(start 43.477942 -124.170948)
		(end 43.260518 -123.953524)
		(width 0.14224)
		(layer "In11.Cu")
		(net "M_M_DQ<9>")
	)
	(segment
		(start 43.914568 -127.498094)
		(end 43.914568 -124.374148)
		(width 0.14224)
		(layer "In11.Cu")
		(net "M_M_DQ<9>")
	)
	(segment
		(start 72.3138 -90.85199)
		(end 72.346566 -90.85199)
		(width 0.0889)
		(layer "In11.Cu")
		(net "M_M_DQ<9>")
	)
	(segment
		(start 43.609514 -148.514054)
		(end 43.736768 -148.3868)
		(width 0.14224)
		(layer "In11.Cu")
		(net "M_M_DQ<9>")
	)
	(segment
		(start 43.457368 -129.4892)
		(end 43.914568 -129.032)
		(width 0.14224)
		(layer "In11.Cu")
		(net "M_M_DQ<9>")
	)
	(segment
		(start 42.850562 -153.0858)
		(end 42.610786 -152.846024)
		(width 0.14224)
		(layer "In11.Cu")
		(net "M_M_DQ<9>")
	)
	(segment
		(start 42.449496 -153.542746)
		(end 42.698416 -153.542746)
		(width 0.14224)
		(layer "In11.Cu")
		(net "M_M_DQ<9>")
	)
	(segment
		(start 43.609514 -146.177)
		(end 43.609514 -143.789654)
		(width 0.14224)
		(layer "In11.Cu")
		(net "M_M_DQ<9>")
	)
	(segment
		(start 43.759628 -127.653034)
		(end 43.914568 -127.498094)
		(width 0.14224)
		(layer "In11.Cu")
		(net "M_M_DQ<9>")
	)
	(segment
		(start 43.939968 -132.488686)
		(end 43.939968 -132.054854)
		(width 0.14224)
		(layer "In11.Cu")
		(net "M_M_DQ<9>")
	)
	(segment
		(start 71.45909 -91.347036)
		(end 71.491856 -91.347036)
		(width 0.0889)
		(layer "In11.Cu")
		(net "M_M_DQ<9>")
	)
	(segment
		(start 43.457368 -129.8194)
		(end 43.457368 -129.4892)
		(width 0.14224)
		(layer "In11.Cu")
		(net "M_M_DQ<9>")
	)
	(segment
		(start 70.59676 -91.84259)
		(end 70.629526 -91.84259)
		(width 0.0889)
		(layer "In11.Cu")
		(net "M_M_DQ<9>")
	)
	(segment
		(start 43.759628 -128.465834)
		(end 43.4467 -128.465834)
		(width 0.14224)
		(layer "In11.Cu")
		(net "M_M_DQ<9>")
	)
	(segment
		(start 43.26763 -120.716548)
		(end 43.26763 -120.310148)
		(width 0.14224)
		(layer "In11.Cu")
		(net "M_M_DQ<9>")
	)
	(segment
		(start 43.260518 -123.547124)
		(end 43.449494 -123.358148)
		(width 0.14224)
		(layer "In11.Cu")
		(net "M_M_DQ<9>")
	)
	(segment
		(start 43.12158 -149.444456)
		(end 43.609514 -148.956522)
		(width 0.14224)
		(layer "In11.Cu")
		(net "M_M_DQ<9>")
	)
	(segment
		(start 68.490592 -93.152214)
		(end 69.30517 -92.337636)
		(width 0.0889)
		(layer "In11.Cu")
		(net "M_M_DQ<9>")
	)
	(segment
		(start 42.610786 -152.846024)
		(end 42.610786 -152.538176)
		(width 0.14224)
		(layer "In11.Cu")
		(net "M_M_DQ<9>")
	)
	(segment
		(start 43.449494 -119.294148)
		(end 43.246294 -119.090948)
		(width 0.14224)
		(layer "In11.Cu")
		(net "M_M_DQ<9>")
	)
	(segment
		(start 42.610786 -152.538176)
		(end 42.825162 -152.3238)
		(width 0.14224)
		(layer "In11.Cu")
		(net "M_M_DQ<9>")
	)
	(segment
		(start 43.431968 -122.545348)
		(end 43.228768 -122.342148)
		(width 0.14224)
		(layer "In11.Cu")
		(net "M_M_DQ<9>")
	)
	(segment
		(start 43.431968 -121.732548)
		(end 43.711368 -121.732548)
		(width 0.14224)
		(layer "In11.Cu")
		(net "M_M_DQ<9>")
	)
	(segment
		(start 42.901362 -151.026368)
		(end 42.901362 -150.621746)
		(width 0.14224)
		(layer "In11.Cu")
		(net "M_M_DQ<9>")
	)
	(segment
		(start 43.4467 -128.465834)
		(end 43.29176 -128.310894)
		(width 0.14224)
		(layer "In11.Cu")
		(net "M_M_DQ<9>")
	)
	(segment
		(start 43.939968 -133.8834)
		(end 43.939968 -133.611366)
		(width 0.14224)
		(layer "In11.Cu")
		(net "M_M_DQ<9>")
	)
	(segment
		(start 63.379604 -95.3008)
		(end 64.316864 -95.3008)
		(width 0.14224)
		(layer "In11.Cu")
		(net "M_M_DQ<9>")
	)
	(segment
		(start 43.711368 -122.545348)
		(end 43.431968 -122.545348)
		(width 0.14224)
		(layer "In11.Cu")
		(net "M_M_DQ<9>")
	)
	(segment
		(start 43.260518 -123.953524)
		(end 43.260518 -123.547124)
		(width 0.14224)
		(layer "In11.Cu")
		(net "M_M_DQ<9>")
	)
	(segment
		(start 43.711368 -123.358148)
		(end 43.914568 -123.154948)
		(width 0.14224)
		(layer "In11.Cu")
		(net "M_M_DQ<9>")
	)
	(segment
		(start 43.914568 -121.529348)
		(end 43.914568 -121.122948)
		(width 0.14224)
		(layer "In11.Cu")
		(net "M_M_DQ<9>")
	)
	(segment
		(start 43.246294 -118.684548)
		(end 43.449494 -118.481348)
		(width 0.14224)
		(layer "In11.Cu")
		(net "M_M_DQ<9>")
	)
	(segment
		(start 43.12158 -149.533356)
		(end 43.12158 -149.444456)
		(width 0.14224)
		(layer "In11.Cu")
		(net "M_M_DQ<9>")
	)
	(segment
		(start 43.711368 -121.732548)
		(end 43.914568 -121.529348)
		(width 0.14224)
		(layer "In11.Cu")
		(net "M_M_DQ<9>")
	)
	(segment
		(start 43.914568 -129.032)
		(end 43.914568 -128.620774)
		(width 0.14224)
		(layer "In11.Cu")
		(net "M_M_DQ<9>")
	)
	(segment
		(start 43.449494 -123.358148)
		(end 43.711368 -123.358148)
		(width 0.14224)
		(layer "In11.Cu")
		(net "M_M_DQ<9>")
	)
	(segment
		(start 43.29176 -127.807974)
		(end 43.4467 -127.653034)
		(width 0.14224)
		(layer "In11.Cu")
		(net "M_M_DQ<9>")
	)
	(segment
		(start 65.594992 -95.031814)
		(end 67.474592 -93.152214)
		(width 0.0889)
		(layer "In11.Cu")
		(net "M_M_DQ<9>")
	)
	(segment
		(start 43.785028 -132.643626)
		(end 43.939968 -132.488686)
		(width 0.14224)
		(layer "In11.Cu")
		(net "M_M_DQ<9>")
	)
	(segment
		(start 43.47083 -120.106948)
		(end 43.711368 -120.106948)
		(width 0.14224)
		(layer "In11.Cu")
		(net "M_M_DQ<9>")
	)
	(segment
		(start 43.711368 -120.106948)
		(end 43.914568 -119.903748)
		(width 0.14224)
		(layer "In11.Cu")
		(net "M_M_DQ<9>")
	)
	(segment
		(start 60.729368 -97.951036)
		(end 63.379604 -95.3008)
		(width 0.14224)
		(layer "In11.Cu")
		(net "M_M_DQ<9>")
	)
	(segment
		(start 43.711368 -138.6078)
		(end 43.711368 -136.677654)
		(width 0.14224)
		(layer "In11.Cu")
		(net "M_M_DQ<9>")
	)
	(segment
		(start 42.901362 -150.621746)
		(end 42.670984 -150.391368)
		(width 0.14224)
		(layer "In11.Cu")
		(net "M_M_DQ<9>")
	)
	(segment
		(start 43.711368 -136.677654)
		(end 43.609514 -136.5758)
		(width 0.14224)
		(layer "In11.Cu")
		(net "M_M_DQ<9>")
	)
	(segment
		(start 43.711368 -124.170948)
		(end 43.477942 -124.170948)
		(width 0.14224)
		(layer "In11.Cu")
		(net "M_M_DQ<9>")
	)
	(segment
		(start 43.609514 -134.213854)
		(end 43.939968 -133.8834)
		(width 0.14224)
		(layer "In11.Cu")
		(net "M_M_DQ<9>")
	)
	(segment
		(start 43.736768 -141.452854)
		(end 43.609514 -141.3256)
		(width 0.14224)
		(layer "In11.Cu")
		(net "M_M_DQ<9>")
	)
	(segment
		(start 42.825162 -152.3238)
		(end 42.825162 -151.892)
		(width 0.14224)
		(layer "In11.Cu")
		(net "M_M_DQ<9>")
	)
	(segment
		(start 43.099228 -149.533356)
		(end 43.12158 -149.533356)
		(width 0.14224)
		(layer "In11.Cu")
		(net "M_M_DQ<9>")
	)
	(segment
		(start 43.785028 -133.456426)
		(end 43.465496 -133.456426)
		(width 0.14224)
		(layer "In11.Cu")
		(net "M_M_DQ<9>")
	)
	(segment
		(start 43.449494 -118.481348)
		(end 43.711368 -118.481348)
		(width 0.14224)
		(layer "In11.Cu")
		(net "M_M_DQ<9>")
	)
	(segment
		(start 43.914568 -119.903748)
		(end 43.914568 -119.497348)
		(width 0.14224)
		(layer "In11.Cu")
		(net "M_M_DQ<9>")
	)
	(segment
		(start 43.711368 -118.481348)
		(end 43.914568 -118.278148)
		(width 0.14224)
		(layer "In11.Cu")
		(net "M_M_DQ<9>")
	)
	(segment
		(start 69.30517 -92.337636)
		(end 69.774816 -92.337636)
		(width 0.0889)
		(layer "In11.Cu")
		(net "M_M_DQ<9>")
	)
	(segment
		(start 43.29176 -128.310894)
		(end 43.29176 -127.807974)
		(width 0.14224)
		(layer "In11.Cu")
		(net "M_M_DQ<9>")
	)
	(segment
		(start 43.609514 -129.971546)
		(end 43.457368 -129.8194)
		(width 0.14224)
		(layer "In11.Cu")
		(net "M_M_DQ<9>")
	)
	(segment
		(start 43.609514 -131.7244)
		(end 43.609514 -129.971546)
		(width 0.14224)
		(layer "In11.Cu")
		(net "M_M_DQ<9>")
	)
	(segment
		(start 43.228768 -122.342148)
		(end 43.228768 -121.935748)
		(width 0.14224)
		(layer "In11.Cu")
		(net "M_M_DQ<9>")
	)
	(segment
		(start 43.736768 -148.3868)
		(end 43.736768 -146.304254)
		(width 0.14224)
		(layer "In11.Cu")
		(net "M_M_DQ<9>")
	)
	(segment
		(start 42.610786 -151.316944)
		(end 42.901362 -151.026368)
		(width 0.14224)
		(layer "In11.Cu")
		(net "M_M_DQ<9>")
	)
	(segment
		(start 43.609514 -136.5758)
		(end 43.609514 -134.213854)
		(width 0.14224)
		(layer "In11.Cu")
		(net "M_M_DQ<9>")
	)
	(segment
		(start 74.03084 -89.86139)
		(end 74.063606 -89.86139)
		(width 0.0889)
		(layer "In11.Cu")
		(net "M_M_DQ<9>")
	)
	(segment
		(start 75.251056 -89.565988)
		(end 75.26782 -89.595452)
		(width 0.0889)
		(layer "In11.Cu")
		(net "M_M_DQ<9>")
	)
	(segment
		(start 43.914568 -122.748548)
		(end 43.711368 -122.545348)
		(width 0.14224)
		(layer "In11.Cu")
		(net "M_M_DQ<9>")
	)
	(segment
		(start 43.711368 -119.294148)
		(end 43.449494 -119.294148)
		(width 0.14224)
		(layer "In11.Cu")
		(net "M_M_DQ<9>")
	)
	(segment
		(start 43.939968 -133.611366)
		(end 43.785028 -133.456426)
		(width 0.14224)
		(layer "In11.Cu")
		(net "M_M_DQ<9>")
	)
	(segment
		(start 43.914568 -124.374148)
		(end 43.711368 -124.170948)
		(width 0.14224)
		(layer "In11.Cu")
		(net "M_M_DQ<9>")
	)
	(segment
		(start 43.914568 -118.278148)
		(end 43.914568 -117.745256)
		(width 0.14224)
		(layer "In11.Cu")
		(net "M_M_DQ<9>")
	)
	(segment
		(start 43.609514 -143.789654)
		(end 43.736768 -143.6624)
		(width 0.14224)
		(layer "In11.Cu")
		(net "M_M_DQ<9>")
	)
	(segment
		(start 64.316864 -95.3008)
		(end 64.324992 -95.292672)
		(width 0.14224)
		(layer "In11.Cu")
		(net "M_M_DQ<9>")
	)
	(segment
		(start 42.670984 -149.9616)
		(end 43.099228 -149.533356)
		(width 0.14224)
		(layer "In11.Cu")
		(net "M_M_DQ<9>")
	)
	(segment
		(start 43.609514 -138.709654)
		(end 43.711368 -138.6078)
		(width 0.14224)
		(layer "In11.Cu")
		(net "M_M_DQ<9>")
	)
	(segment
		(start 42.698416 -153.542746)
		(end 42.850562 -153.3906)
		(width 0.14224)
		(layer "In11.Cu")
		(net "M_M_DQ<9>")
	)
	(segment
		(start 43.310556 -133.301486)
		(end 43.310556 -132.798566)
		(width 0.14224)
		(layer "In11.Cu")
		(net "M_M_DQ<9>")
	)
	(segment
		(start 43.609514 -148.956522)
		(end 43.609514 -148.514054)
		(width 0.14224)
		(layer "In11.Cu")
		(net "M_M_DQ<9>")
	)
	(segment
		(start 43.465496 -133.456426)
		(end 43.310556 -133.301486)
		(width 0.14224)
		(layer "In11.Cu")
		(net "M_M_DQ<9>")
	)
	(segment
		(start 43.47083 -120.919748)
		(end 43.26763 -120.716548)
		(width 0.14224)
		(layer "In11.Cu")
		(net "M_M_DQ<9>")
	)
	(segment
		(start 60.729368 -100.930456)
		(end 60.729368 -97.951036)
		(width 0.14224)
		(layer "In11.Cu")
		(net "M_M_DQ<9>")
	)
	(segment
		(start 43.246294 -119.090948)
		(end 43.246294 -118.684548)
		(width 0.14224)
		(layer "In11.Cu")
		(net "M_M_DQ<9>")
	)
	(segment
		(start 43.914568 -121.122948)
		(end 43.711368 -120.919748)
		(width 0.14224)
		(layer "In11.Cu")
		(net "M_M_DQ<9>")
	)
	(segment
		(start 43.310556 -132.798566)
		(end 43.465496 -132.643626)
		(width 0.14224)
		(layer "In11.Cu")
		(net "M_M_DQ<9>")
	)
	(segment
		(start 43.465496 -132.643626)
		(end 43.785028 -132.643626)
		(width 0.14224)
		(layer "In11.Cu")
		(net "M_M_DQ<9>")
	)
	(segment
		(start 43.26763 -120.310148)
		(end 43.47083 -120.106948)
		(width 0.14224)
		(layer "In11.Cu")
		(net "M_M_DQ<9>")
	)
	(segment
		(start 73.17613 -90.356436)
		(end 73.208896 -90.356436)
		(width 0.0889)
		(layer "In11.Cu")
		(net "M_M_DQ<9>")
	)
	(segment
		(start 42.850562 -153.3906)
		(end 42.850562 -153.0858)
		(width 0.14224)
		(layer "In11.Cu")
		(net "M_M_DQ<9>")
	)
	(segment
		(start 75.26782 -89.595452)
		(end 75.762866 -90.26144)
		(width 0.0889)
		(layer "In11.Cu")
		(net "M_M_DQ<9>")
	)
	(segment
		(start 67.474592 -93.152214)
		(end 68.490592 -93.152214)
		(width 0.0889)
		(layer "In11.Cu")
		(net "M_M_DQ<9>")
	)
	(segment
		(start 43.4467 -127.653034)
		(end 43.759628 -127.653034)
		(width 0.14224)
		(layer "In11.Cu")
		(net "M_M_DQ<9>")
	)
	(segment
		(start 43.711368 -120.919748)
		(end 43.47083 -120.919748)
		(width 0.14224)
		(layer "In11.Cu")
		(net "M_M_DQ<9>")
	)
	(segment
		(start 43.939968 -132.054854)
		(end 43.609514 -131.7244)
		(width 0.14224)
		(layer "In11.Cu")
		(net "M_M_DQ<9>")
	)
	(arc
		(start 74.063606 -89.86139)
		(mid 74.34903 -89.777923)
		(end 74.557636 -89.565988)
		(width 0.0889)
		(layer "In11.Cu")
		(net "M_M_DQ<9>")
	)
	(arc
		(start 74.557636 -89.565988)
		(mid 74.904346 -89.365677)
		(end 75.251056 -89.565988)
		(width 0.0889)
		(layer "In11.Cu")
		(net "M_M_DQ<9>")
	)
	(arc
		(start 73.699116 -90.061288)
		(mid 73.839195 -89.918552)
		(end 74.03084 -89.86139)
		(width 0.0889)
		(layer "In11.Cu")
		(net "M_M_DQ<9>")
	)
	(arc
		(start 70.629526 -91.84259)
		(mid 70.91495 -91.759123)
		(end 71.123556 -91.547188)
		(width 0.0889)
		(layer "In11.Cu")
		(net "M_M_DQ<9>")
	)
	(arc
		(start 71.982076 -91.051888)
		(mid 72.122155 -90.909152)
		(end 72.3138 -90.85199)
		(width 0.0889)
		(layer "In11.Cu")
		(net "M_M_DQ<9>")
	)
	(arc
		(start 70.265036 -92.042488)
		(mid 70.405115 -91.899752)
		(end 70.59676 -91.84259)
		(width 0.0889)
		(layer "In11.Cu")
		(net "M_M_DQ<9>")
	)
	(arc
		(start 69.774816 -92.337636)
		(mid 70.058033 -92.253355)
		(end 70.265036 -92.042488)
		(width 0.0889)
		(layer "In11.Cu")
		(net "M_M_DQ<9>")
	)
	(arc
		(start 71.123556 -91.547188)
		(mid 71.265239 -91.403384)
		(end 71.45909 -91.347036)
		(width 0.0889)
		(layer "In11.Cu")
		(net "M_M_DQ<9>")
	)
	(arc
		(start 71.491856 -91.347036)
		(mid 71.775073 -91.262755)
		(end 71.982076 -91.051888)
		(width 0.0889)
		(layer "In11.Cu")
		(net "M_M_DQ<9>")
	)
	(arc
		(start 72.840596 -90.556588)
		(mid 72.982279 -90.412784)
		(end 73.17613 -90.356436)
		(width 0.0889)
		(layer "In11.Cu")
		(net "M_M_DQ<9>")
	)
	(arc
		(start 73.208896 -90.356436)
		(mid 73.492113 -90.272155)
		(end 73.699116 -90.061288)
		(width 0.0889)
		(layer "In11.Cu")
		(net "M_M_DQ<9>")
	)
	(arc
		(start 72.346566 -90.85199)
		(mid 72.63199 -90.768523)
		(end 72.840596 -90.556588)
		(width 0.0889)
		(layer "In11.Cu")
		(net "M_M_DQ<9>")
	)
	(segment
		(start 78.051406 -91.25204)
		(end 77.479906 -91.25204)
		(width 0.1651)
		(layer "F.Cu")
		(net "M_M_DQ<8>")
	)
	(segment
		(start 43.29938 -156.87294)
		(end 43.29938 -156.878782)
		(width 0.1651)
		(layer "F.Cu")
		(net "M_M_DQ<8>")
	)
	(segment
		(start 43.29938 -156.878782)
		(end 43.12158 -155.0162)
		(width 0.1651)
		(layer "F.Cu")
		(net "M_M_DQ<8>")
	)
	(via
		(at 42.449496 -150.814278)
		(size 0.508)
		(drill 0.254)
		(layers "F.Cu" "B.Cu")
		(net "M_M_DQ<8>")
	)
	(via
		(at 43.12158 -155.0162)
		(size 0.508)
		(drill 0.254)
		(layers "F.Cu" "B.Cu")
		(net "M_M_DQ<8>")
	)
	(via
		(at 77.479906 -91.25204)
		(size 0.508)
		(drill 0.254)
		(layers "F.Cu" "B.Cu")
		(net "M_M_DQ<8>")
	)
	(segment
		(start 42.449496 -152.078436)
		(end 42.449496 -150.814278)
		(width 0.1651)
		(layer "B.Cu")
		(net "M_M_DQ<8>")
	)
	(segment
		(start 42.873168 -141.528546)
		(end 42.873168 -143.637)
		(width 0.14224)
		(layer "In11.Cu")
		(net "M_M_DQ<8>")
	)
	(segment
		(start 42.974514 -136.6012)
		(end 42.873168 -136.702546)
		(width 0.14224)
		(layer "In11.Cu")
		(net "M_M_DQ<8>")
	)
	(segment
		(start 42.085514 -150.450296)
		(end 42.449496 -150.814278)
		(width 0.14224)
		(layer "In11.Cu")
		(net "M_M_DQ<8>")
	)
	(segment
		(start 69.17055 -92.202762)
		(end 69.17055 -92.20327)
		(width 0.0889)
		(layer "In11.Cu")
		(net "M_M_DQ<8>")
	)
	(segment
		(start 76.639166 -90.165936)
		(end 76.6064 -90.165936)
		(width 0.0889)
		(layer "In11.Cu")
		(net "M_M_DQ<8>")
	)
	(segment
		(start 42.016426 -151.247348)
		(end 42.016426 -153.911046)
		(width 0.14224)
		(layer "In11.Cu")
		(net "M_M_DQ<8>")
	)
	(segment
		(start 77.150468 -90.491056)
		(end 77.133196 -90.461338)
		(width 0.0889)
		(layer "In11.Cu")
		(net "M_M_DQ<8>")
	)
	(segment
		(start 42.974514 -134.060946)
		(end 42.974514 -134.433818)
		(width 0.14224)
		(layer "In11.Cu")
		(net "M_M_DQ<8>")
	)
	(segment
		(start 42.873168 -143.637)
		(end 42.923714 -143.687546)
		(width 0.14224)
		(layer "In11.Cu")
		(net "M_M_DQ<8>")
	)
	(segment
		(start 60.145168 -97.858072)
		(end 60.145168 -100.616512)
		(width 0.14224)
		(layer "In11.Cu")
		(net "M_M_DQ<8>")
	)
	(segment
		(start 42.449496 -150.814278)
		(end 42.016426 -151.247348)
		(width 0.14224)
		(layer "In11.Cu")
		(net "M_M_DQ<8>")
	)
	(segment
		(start 42.873168 -136.702546)
		(end 42.873168 -138.7094)
		(width 0.14224)
		(layer "In11.Cu")
		(net "M_M_DQ<8>")
	)
	(segment
		(start 42.936414 -146.177)
		(end 42.873168 -146.240246)
		(width 0.14224)
		(layer "In11.Cu")
		(net "M_M_DQ<8>")
	)
	(segment
		(start 42.873168 -148.4376)
		(end 42.936414 -148.500846)
		(width 0.14224)
		(layer "In11.Cu")
		(net "M_M_DQ<8>")
	)
	(segment
		(start 42.631614 -131.141978)
		(end 42.974514 -131.484878)
		(width 0.14224)
		(layer "In11.Cu")
		(net "M_M_DQ<8>")
	)
	(segment
		(start 43.330368 -125.429772)
		(end 43.330368 -125.836172)
		(width 0.14224)
		(layer "In11.Cu")
		(net "M_M_DQ<8>")
	)
	(segment
		(start 42.974514 -131.484878)
		(end 42.974514 -131.9784)
		(width 0.14224)
		(layer "In11.Cu")
		(net "M_M_DQ<8>")
	)
	(segment
		(start 42.936414 -148.960078)
		(end 42.085514 -149.810978)
		(width 0.14224)
		(layer "In11.Cu")
		(net "M_M_DQ<8>")
	)
	(segment
		(start 69.17055 -92.20327)
		(end 69.170804 -92.20327)
		(width 0.0889)
		(layer "In11.Cu")
		(net "M_M_DQ<8>")
	)
	(segment
		(start 42.974514 -138.810746)
		(end 42.974514 -139.320778)
		(width 0.14224)
		(layer "In11.Cu")
		(net "M_M_DQ<8>")
	)
	(segment
		(start 64.52616 -94.841822)
		(end 64.324992 -94.640654)
		(width 0.0889)
		(layer "In11.Cu")
		(net "M_M_DQ<8>")
	)
	(segment
		(start 74.922126 -89.175336)
		(end 74.886566 -89.175336)
		(width 0.0889)
		(layer "In11.Cu")
		(net "M_M_DQ<8>")
	)
	(segment
		(start 42.631614 -135.9789)
		(end 42.974514 -136.3218)
		(width 0.14224)
		(layer "In11.Cu")
		(net "M_M_DQ<8>")
	)
	(segment
		(start 67.395852 -92.962222)
		(end 65.516252 -94.841822)
		(width 0.0889)
		(layer "In11.Cu")
		(net "M_M_DQ<8>")
	)
	(segment
		(start 65.516252 -94.841822)
		(end 64.52616 -94.841822)
		(width 0.0889)
		(layer "In11.Cu")
		(net "M_M_DQ<8>")
	)
	(segment
		(start 72.339962 -90.66149)
		(end 72.307196 -90.66149)
		(width 0.0889)
		(layer "In11.Cu")
		(net "M_M_DQ<8>")
	)
	(segment
		(start 60.145168 -100.616512)
		(end 42.746168 -118.015512)
		(width 0.14224)
		(layer "In11.Cu")
		(net "M_M_DQ<8>")
	)
	(segment
		(start 42.974514 -134.433818)
		(end 42.631614 -134.776718)
		(width 0.14224)
		(layer "In11.Cu")
		(net "M_M_DQ<8>")
	)
	(segment
		(start 42.016426 -153.911046)
		(end 43.12158 -155.0162)
		(width 0.14224)
		(layer "In11.Cu")
		(net "M_M_DQ<8>")
	)
	(segment
		(start 42.671746 -132.281168)
		(end 42.671746 -133.758178)
		(width 0.14224)
		(layer "In11.Cu")
		(net "M_M_DQ<8>")
	)
	(segment
		(start 42.873168 -138.7094)
		(end 42.974514 -138.810746)
		(width 0.14224)
		(layer "In11.Cu")
		(net "M_M_DQ<8>")
	)
	(segment
		(start 42.923714 -141.035278)
		(end 42.923714 -141.478)
		(width 0.14224)
		(layer "In11.Cu")
		(net "M_M_DQ<8>")
	)
	(segment
		(start 63.33744 -94.6658)
		(end 60.145168 -97.858072)
		(width 0.14224)
		(layer "In11.Cu")
		(net "M_M_DQ<8>")
	)
	(segment
		(start 42.746168 -129.0574)
		(end 42.898568 -129.2098)
		(width 0.14224)
		(layer "In11.Cu")
		(net "M_M_DQ<8>")
	)
	(segment
		(start 42.949368 -125.226572)
		(end 43.127168 -125.226572)
		(width 0.14224)
		(layer "In11.Cu")
		(net "M_M_DQ<8>")
	)
	(segment
		(start 69.170804 -92.20327)
		(end 68.411852 -92.962222)
		(width 0.0889)
		(layer "In11.Cu")
		(net "M_M_DQ<8>")
	)
	(segment
		(start 43.127168 -126.039372)
		(end 42.949368 -126.039372)
		(width 0.14224)
		(layer "In11.Cu")
		(net "M_M_DQ<8>")
	)
	(segment
		(start 42.085514 -149.810978)
		(end 42.085514 -150.450296)
		(width 0.14224)
		(layer "In11.Cu")
		(net "M_M_DQ<8>")
	)
	(segment
		(start 42.923714 -141.478)
		(end 42.873168 -141.528546)
		(width 0.14224)
		(layer "In11.Cu")
		(net "M_M_DQ<8>")
	)
	(segment
		(start 64.324992 -94.640654)
		(end 64.299846 -94.6658)
		(width 0.14224)
		(layer "In11.Cu")
		(net "M_M_DQ<8>")
	)
	(segment
		(start 68.411852 -92.962222)
		(end 67.395852 -92.962222)
		(width 0.0889)
		(layer "In11.Cu")
		(net "M_M_DQ<8>")
	)
	(segment
		(start 42.631614 -140.743178)
		(end 42.923714 -141.035278)
		(width 0.14224)
		(layer "In11.Cu")
		(net "M_M_DQ<8>")
	)
	(segment
		(start 42.746168 -118.015512)
		(end 42.746168 -125.023372)
		(width 0.14224)
		(layer "In11.Cu")
		(net "M_M_DQ<8>")
	)
	(segment
		(start 42.949368 -126.039372)
		(end 42.746168 -126.242572)
		(width 0.14224)
		(layer "In11.Cu")
		(net "M_M_DQ<8>")
	)
	(segment
		(start 42.644314 -144.365218)
		(end 42.644314 -145.592546)
		(width 0.14224)
		(layer "In11.Cu")
		(net "M_M_DQ<8>")
	)
	(segment
		(start 42.644314 -145.592546)
		(end 42.936414 -145.884646)
		(width 0.14224)
		(layer "In11.Cu")
		(net "M_M_DQ<8>")
	)
	(segment
		(start 42.923714 -143.687546)
		(end 42.923714 -144.085818)
		(width 0.14224)
		(layer "In11.Cu")
		(net "M_M_DQ<8>")
	)
	(segment
		(start 42.671746 -133.758178)
		(end 42.974514 -134.060946)
		(width 0.14224)
		(layer "In11.Cu")
		(net "M_M_DQ<8>")
	)
	(segment
		(start 42.974514 -131.9784)
		(end 42.671746 -132.281168)
		(width 0.14224)
		(layer "In11.Cu")
		(net "M_M_DQ<8>")
	)
	(segment
		(start 42.898568 -129.795524)
		(end 42.631614 -130.062478)
		(width 0.14224)
		(layer "In11.Cu")
		(net "M_M_DQ<8>")
	)
	(segment
		(start 42.936414 -145.884646)
		(end 42.936414 -146.177)
		(width 0.14224)
		(layer "In11.Cu")
		(net "M_M_DQ<8>")
	)
	(segment
		(start 77.479906 -91.25204)
		(end 77.150468 -90.491056)
		(width 0.0889)
		(layer "In11.Cu")
		(net "M_M_DQ<8>")
	)
	(segment
		(start 43.330368 -125.836172)
		(end 43.127168 -126.039372)
		(width 0.14224)
		(layer "In11.Cu")
		(net "M_M_DQ<8>")
	)
	(segment
		(start 64.299846 -94.6658)
		(end 63.33744 -94.6658)
		(width 0.14224)
		(layer "In11.Cu")
		(net "M_M_DQ<8>")
	)
	(segment
		(start 42.923714 -144.085818)
		(end 42.644314 -144.365218)
		(width 0.14224)
		(layer "In11.Cu")
		(net "M_M_DQ<8>")
	)
	(segment
		(start 75.784456 -89.67089)
		(end 75.75169 -89.67089)
		(width 0.0889)
		(layer "In11.Cu")
		(net "M_M_DQ<8>")
	)
	(segment
		(start 42.974514 -139.320778)
		(end 42.631614 -139.663678)
		(width 0.14224)
		(layer "In11.Cu")
		(net "M_M_DQ<8>")
	)
	(segment
		(start 42.746168 -125.023372)
		(end 42.949368 -125.226572)
		(width 0.14224)
		(layer "In11.Cu")
		(net "M_M_DQ<8>")
	)
	(segment
		(start 74.057002 -89.67089)
		(end 74.024236 -89.67089)
		(width 0.0889)
		(layer "In11.Cu")
		(net "M_M_DQ<8>")
	)
	(segment
		(start 42.873168 -146.240246)
		(end 42.873168 -148.4376)
		(width 0.14224)
		(layer "In11.Cu")
		(net "M_M_DQ<8>")
	)
	(segment
		(start 42.631614 -134.776718)
		(end 42.631614 -135.9789)
		(width 0.14224)
		(layer "In11.Cu")
		(net "M_M_DQ<8>")
	)
	(segment
		(start 70.622922 -91.65209)
		(end 70.590156 -91.65209)
		(width 0.0889)
		(layer "In11.Cu")
		(net "M_M_DQ<8>")
	)
	(segment
		(start 42.898568 -129.2098)
		(end 42.898568 -129.795524)
		(width 0.14224)
		(layer "In11.Cu")
		(net "M_M_DQ<8>")
	)
	(segment
		(start 42.974514 -136.3218)
		(end 42.974514 -136.6012)
		(width 0.14224)
		(layer "In11.Cu")
		(net "M_M_DQ<8>")
	)
	(segment
		(start 71.485252 -91.156536)
		(end 71.452486 -91.156536)
		(width 0.0889)
		(layer "In11.Cu")
		(net "M_M_DQ<8>")
	)
	(segment
		(start 42.936414 -148.500846)
		(end 42.936414 -148.960078)
		(width 0.14224)
		(layer "In11.Cu")
		(net "M_M_DQ<8>")
	)
	(segment
		(start 69.226176 -92.147136)
		(end 69.17055 -92.202762)
		(width 0.0889)
		(layer "In11.Cu")
		(net "M_M_DQ<8>")
	)
	(segment
		(start 42.631614 -139.663678)
		(end 42.631614 -140.743178)
		(width 0.14224)
		(layer "In11.Cu")
		(net "M_M_DQ<8>")
	)
	(segment
		(start 73.202292 -90.165936)
		(end 73.169526 -90.165936)
		(width 0.0889)
		(layer "In11.Cu")
		(net "M_M_DQ<8>")
	)
	(segment
		(start 69.768212 -92.147136)
		(end 69.226176 -92.147136)
		(width 0.0889)
		(layer "In11.Cu")
		(net "M_M_DQ<8>")
	)
	(segment
		(start 42.631614 -130.062478)
		(end 42.631614 -131.141978)
		(width 0.14224)
		(layer "In11.Cu")
		(net "M_M_DQ<8>")
	)
	(segment
		(start 43.127168 -125.226572)
		(end 43.330368 -125.429772)
		(width 0.14224)
		(layer "In11.Cu")
		(net "M_M_DQ<8>")
	)
	(segment
		(start 42.746168 -126.242572)
		(end 42.746168 -129.0574)
		(width 0.14224)
		(layer "In11.Cu")
		(net "M_M_DQ<8>")
	)
	(arc
		(start 72.675496 -90.461338)
		(mid 72.533813 -90.605142)
		(end 72.339962 -90.66149)
		(width 0.0889)
		(layer "In11.Cu")
		(net "M_M_DQ<8>")
	)
	(arc
		(start 70.958456 -91.451938)
		(mid 70.816773 -91.595742)
		(end 70.622922 -91.65209)
		(width 0.0889)
		(layer "In11.Cu")
		(net "M_M_DQ<8>")
	)
	(arc
		(start 70.590156 -91.65209)
		(mid 70.306939 -91.736371)
		(end 70.099936 -91.947238)
		(width 0.0889)
		(layer "In11.Cu")
		(net "M_M_DQ<8>")
	)
	(arc
		(start 75.75169 -89.67089)
		(mid 75.55784 -89.61454)
		(end 75.416156 -89.470738)
		(width 0.0889)
		(layer "In11.Cu")
		(net "M_M_DQ<8>")
	)
	(arc
		(start 74.392536 -89.470738)
		(mid 74.250853 -89.614542)
		(end 74.057002 -89.67089)
		(width 0.0889)
		(layer "In11.Cu")
		(net "M_M_DQ<8>")
	)
	(arc
		(start 70.099936 -91.947238)
		(mid 69.959857 -92.089974)
		(end 69.768212 -92.147136)
		(width 0.0889)
		(layer "In11.Cu")
		(net "M_M_DQ<8>")
	)
	(arc
		(start 76.274676 -89.966038)
		(mid 76.067672 -89.755174)
		(end 75.784456 -89.67089)
		(width 0.0889)
		(layer "In11.Cu")
		(net "M_M_DQ<8>")
	)
	(arc
		(start 77.133196 -90.461338)
		(mid 76.924588 -90.249406)
		(end 76.639166 -90.165936)
		(width 0.0889)
		(layer "In11.Cu")
		(net "M_M_DQ<8>")
	)
	(arc
		(start 72.307196 -90.66149)
		(mid 72.023979 -90.745771)
		(end 71.816976 -90.956638)
		(width 0.0889)
		(layer "In11.Cu")
		(net "M_M_DQ<8>")
	)
	(arc
		(start 73.169526 -90.165936)
		(mid 72.884102 -90.249403)
		(end 72.675496 -90.461338)
		(width 0.0889)
		(layer "In11.Cu")
		(net "M_M_DQ<8>")
	)
	(arc
		(start 76.6064 -90.165936)
		(mid 76.414758 -90.10877)
		(end 76.274676 -89.966038)
		(width 0.0889)
		(layer "In11.Cu")
		(net "M_M_DQ<8>")
	)
	(arc
		(start 75.416156 -89.470738)
		(mid 75.207548 -89.258806)
		(end 74.922126 -89.175336)
		(width 0.0889)
		(layer "In11.Cu")
		(net "M_M_DQ<8>")
	)
	(arc
		(start 74.886566 -89.175336)
		(mid 74.601142 -89.258803)
		(end 74.392536 -89.470738)
		(width 0.0889)
		(layer "In11.Cu")
		(net "M_M_DQ<8>")
	)
	(arc
		(start 71.816976 -90.956638)
		(mid 71.676897 -91.099374)
		(end 71.485252 -91.156536)
		(width 0.0889)
		(layer "In11.Cu")
		(net "M_M_DQ<8>")
	)
	(arc
		(start 74.024236 -89.67089)
		(mid 73.741019 -89.755171)
		(end 73.534016 -89.966038)
		(width 0.0889)
		(layer "In11.Cu")
		(net "M_M_DQ<8>")
	)
	(arc
		(start 73.534016 -89.966038)
		(mid 73.393937 -90.108774)
		(end 73.202292 -90.165936)
		(width 0.0889)
		(layer "In11.Cu")
		(net "M_M_DQ<8>")
	)
	(arc
		(start 71.452486 -91.156536)
		(mid 71.167062 -91.240003)
		(end 70.958456 -91.451938)
		(width 0.0889)
		(layer "In11.Cu")
		(net "M_M_DQ<8>")
	)
	(segment
		(start 37.34943 -152.273)
		(end 37.34943 -153.542746)
		(width 0.1651)
		(layer "F.Cu")
		(net "M_M_DQ<7>")
	)
	(segment
		(start 75.475846 -86.794086)
		(end 74.904346 -86.794086)
		(width 0.1651)
		(layer "F.Cu")
		(net "M_M_DQ<7>")
	)
	(via
		(at 74.904346 -86.794086)
		(size 0.508)
		(drill 0.254)
		(layers "F.Cu" "B.Cu")
		(net "M_M_DQ<7>")
	)
	(via
		(at 37.34943 -153.542746)
		(size 0.508)
		(drill 0.254)
		(layers "F.Cu" "B.Cu")
		(net "M_M_DQ<7>")
	)
	(via
		(at 38.199314 -149.533356)
		(size 0.508)
		(drill 0.254)
		(layers "F.Cu" "B.Cu")
		(net "M_M_DQ<7>")
	)
	(segment
		(start 38.199314 -147.478496)
		(end 38.199314 -149.533356)
		(width 0.1651)
		(layer "B.Cu")
		(net "M_M_DQ<7>")
	)
	(segment
		(start 38.199568 -147.478496)
		(end 38.199314 -147.478496)
		(width 0.1651)
		(layer "B.Cu")
		(net "M_M_DQ<7>")
	)
	(segment
		(start 38.834568 -131.064254)
		(end 38.47465 -131.424172)
		(width 0.14224)
		(layer "In11.Cu")
		(net "M_M_DQ<7>")
	)
	(segment
		(start 41.285414 -112.14735)
		(end 41.084246 -112.14735)
		(width 0.14224)
		(layer "In11.Cu")
		(net "M_M_DQ<7>")
	)
	(segment
		(start 39.825422 -111.808514)
		(end 40.624252 -112.607344)
		(width 0.14224)
		(layer "In11.Cu")
		(net "M_M_DQ<7>")
	)
	(segment
		(start 38.476174 -134.478522)
		(end 38.834568 -134.836916)
		(width 0.14224)
		(layer "In11.Cu")
		(net "M_M_DQ<7>")
	)
	(segment
		(start 43.84421 -109.387386)
		(end 43.19778 -108.740956)
		(width 0.14224)
		(layer "In11.Cu")
		(net "M_M_DQ<7>")
	)
	(segment
		(start 38.905434 -112.728502)
		(end 39.704264 -113.527332)
		(width 0.14224)
		(layer "In11.Cu")
		(net "M_M_DQ<7>")
	)
	(segment
		(start 38.783768 -144.375886)
		(end 38.783768 -145.567146)
		(width 0.14224)
		(layer "In11.Cu")
		(net "M_M_DQ<7>")
	)
	(segment
		(start 38.176962 -149.533356)
		(end 37.748718 -149.9616)
		(width 0.14224)
		(layer "In11.Cu")
		(net "M_M_DQ<7>")
	)
	(segment
		(start 39.704264 -113.527332)
		(end 39.704264 -113.7285)
		(width 0.14224)
		(layer "In11.Cu")
		(net "M_M_DQ<7>")
	)
	(segment
		(start 37.793168 -150.435818)
		(end 37.793168 -151.1046)
		(width 0.14224)
		(layer "In11.Cu")
		(net "M_M_DQ<7>")
	)
	(segment
		(start 38.478968 -136.7282)
		(end 38.631368 -136.8806)
		(width 0.14224)
		(layer "In11.Cu")
		(net "M_M_DQ<7>")
	)
	(segment
		(start 38.905434 -112.527334)
		(end 38.905434 -112.728502)
		(width 0.14224)
		(layer "In11.Cu")
		(net "M_M_DQ<7>")
	)
	(segment
		(start 38.631368 -148.3868)
		(end 38.55212 -148.466048)
		(width 0.14224)
		(layer "In11.Cu")
		(net "M_M_DQ<7>")
	)
	(segment
		(start 37.767768 -151.9174)
		(end 37.767768 -152.2222)
		(width 0.14224)
		(layer "In11.Cu")
		(net "M_M_DQ<7>")
	)
	(segment
		(start 38.187122 -127.778256)
		(end 38.032182 -127.933196)
		(width 0.14224)
		(layer "In11.Cu")
		(net "M_M_DQ<7>")
	)
	(segment
		(start 41.084246 -112.14735)
		(end 40.285416 -111.34852)
		(width 0.14224)
		(layer "In11.Cu")
		(net "M_M_DQ<7>")
	)
	(segment
		(start 74.370438 -86.872064)
		(end 74.219308 -86.88959)
		(width 0.0889)
		(layer "In11.Cu")
		(net "M_M_DQ<7>")
	)
	(segment
		(start 38.710616 -127.778256)
		(end 38.187122 -127.778256)
		(width 0.14224)
		(layer "In11.Cu")
		(net "M_M_DQ<7>")
	)
	(segment
		(start 48.073564 -105.3592)
		(end 44.045378 -109.387386)
		(width 0.14224)
		(layer "In11.Cu")
		(net "M_M_DQ<7>")
	)
	(segment
		(start 39.704264 -113.7285)
		(end 39.063168 -114.369596)
		(width 0.14224)
		(layer "In11.Cu")
		(net "M_M_DQ<7>")
	)
	(segment
		(start 37.748718 -150.391368)
		(end 37.793168 -150.435818)
		(width 0.14224)
		(layer "In11.Cu")
		(net "M_M_DQ<7>")
	)
	(segment
		(start 73.208896 -87.384636)
		(end 73.17613 -87.384636)
		(width 0.0889)
		(layer "In11.Cu")
		(net "M_M_DQ<7>")
	)
	(segment
		(start 40.74541 -110.888526)
		(end 41.54424 -111.687356)
		(width 0.14224)
		(layer "In11.Cu")
		(net "M_M_DQ<7>")
	)
	(segment
		(start 55.166768 -98.679)
		(end 55.166768 -100.3554)
		(width 0.14224)
		(layer "In11.Cu")
		(net "M_M_DQ<7>")
	)
	(segment
		(start 38.55212 -129.859278)
		(end 38.834568 -130.141726)
		(width 0.14224)
		(layer "In11.Cu")
		(net "M_M_DQ<7>")
	)
	(segment
		(start 38.428168 -145.922746)
		(end 38.428168 -146.2278)
		(width 0.14224)
		(layer "In11.Cu")
		(net "M_M_DQ<7>")
	)
	(segment
		(start 37.51072 -152.752552)
		(end 37.799518 -153.04135)
		(width 0.14224)
		(layer "In11.Cu")
		(net "M_M_DQ<7>")
	)
	(segment
		(start 38.800786 -132.274818)
		(end 38.800786 -133.866382)
		(width 0.14224)
		(layer "In11.Cu")
		(net "M_M_DQ<7>")
	)
	(segment
		(start 41.54424 -111.888524)
		(end 41.285414 -112.14735)
		(width 0.14224)
		(layer "In11.Cu")
		(net "M_M_DQ<7>")
	)
	(segment
		(start 37.767768 -152.2222)
		(end 37.51072 -152.479248)
		(width 0.14224)
		(layer "In11.Cu")
		(net "M_M_DQ<7>")
	)
	(segment
		(start 38.507416 -144.099534)
		(end 38.783768 -144.375886)
		(width 0.14224)
		(layer "In11.Cu")
		(net "M_M_DQ<7>")
	)
	(segment
		(start 37.799518 -153.364946)
		(end 37.621718 -153.542746)
		(width 0.14224)
		(layer "In11.Cu")
		(net "M_M_DQ<7>")
	)
	(segment
		(start 38.865556 -128.745996)
		(end 38.865556 -129.001012)
		(width 0.14224)
		(layer "In11.Cu")
		(net "M_M_DQ<7>")
	)
	(segment
		(start 38.507416 -143.811752)
		(end 38.507416 -144.099534)
		(width 0.14224)
		(layer "In11.Cu")
		(net "M_M_DQ<7>")
	)
	(segment
		(start 41.665398 -109.968538)
		(end 42.464228 -110.767368)
		(width 0.14224)
		(layer "In11.Cu")
		(net "M_M_DQ<7>")
	)
	(segment
		(start 38.631368 -146.431)
		(end 38.631368 -148.3868)
		(width 0.14224)
		(layer "In11.Cu")
		(net "M_M_DQ<7>")
	)
	(segment
		(start 50.162968 -105.3592)
		(end 48.073564 -105.3592)
		(width 0.14224)
		(layer "In11.Cu")
		(net "M_M_DQ<7>")
	)
	(segment
		(start 38.428168 -146.2278)
		(end 38.631368 -146.431)
		(width 0.14224)
		(layer "In11.Cu")
		(net "M_M_DQ<7>")
	)
	(segment
		(start 37.748718 -149.9616)
		(end 37.748718 -150.391368)
		(width 0.14224)
		(layer "In11.Cu")
		(net "M_M_DQ<7>")
	)
	(segment
		(start 63.264288 -91.0844)
		(end 62.761368 -91.0844)
		(width 0.14224)
		(layer "In11.Cu")
		(net "M_M_DQ<7>")
	)
	(segment
		(start 38.55212 -148.466048)
		(end 38.55212 -149.191472)
		(width 0.14224)
		(layer "In11.Cu")
		(net "M_M_DQ<7>")
	)
	(segment
		(start 41.54424 -111.687356)
		(end 41.54424 -111.888524)
		(width 0.14224)
		(layer "In11.Cu")
		(net "M_M_DQ<7>")
	)
	(segment
		(start 40.624252 -112.808512)
		(end 40.365426 -113.067338)
		(width 0.14224)
		(layer "In11.Cu")
		(net "M_M_DQ<7>")
	)
	(segment
		(start 38.55212 -129.314448)
		(end 38.55212 -129.859278)
		(width 0.14224)
		(layer "In11.Cu")
		(net "M_M_DQ<7>")
	)
	(segment
		(start 38.631368 -138.7348)
		(end 38.453568 -138.9126)
		(width 0.14224)
		(layer "In11.Cu")
		(net "M_M_DQ<7>")
	)
	(segment
		(start 38.631368 -141.608048)
		(end 38.631368 -143.6878)
		(width 0.14224)
		(layer "In11.Cu")
		(net "M_M_DQ<7>")
	)
	(segment
		(start 42.714418 -109.177582)
		(end 43.384216 -109.84738)
		(width 0.14224)
		(layer "In11.Cu")
		(net "M_M_DQ<7>")
	)
	(segment
		(start 37.799518 -153.04135)
		(end 37.799518 -153.364946)
		(width 0.14224)
		(layer "In11.Cu")
		(net "M_M_DQ<7>")
	)
	(segment
		(start 66.638424 -90.776806)
		(end 63.571882 -90.776806)
		(width 0.0889)
		(layer "In11.Cu")
		(net "M_M_DQ<7>")
	)
	(segment
		(start 55.166768 -100.3554)
		(end 50.162968 -105.3592)
		(width 0.14224)
		(layer "In11.Cu")
		(net "M_M_DQ<7>")
	)
	(segment
		(start 38.453568 -138.9126)
		(end 38.453568 -139.361926)
		(width 0.14224)
		(layer "In11.Cu")
		(net "M_M_DQ<7>")
	)
	(segment
		(start 39.063168 -114.369596)
		(end 39.063168 -126.6698)
		(width 0.14224)
		(layer "In11.Cu")
		(net "M_M_DQ<7>")
	)
	(segment
		(start 41.004236 -110.428532)
		(end 40.74541 -110.687358)
		(width 0.14224)
		(layer "In11.Cu")
		(net "M_M_DQ<7>")
	)
	(segment
		(start 39.825422 -111.607346)
		(end 39.825422 -111.808514)
		(width 0.14224)
		(layer "In11.Cu")
		(net "M_M_DQ<7>")
	)
	(segment
		(start 37.51072 -151.660352)
		(end 37.767768 -151.9174)
		(width 0.14224)
		(layer "In11.Cu")
		(net "M_M_DQ<7>")
	)
	(segment
		(start 41.924224 -109.508544)
		(end 41.665398 -109.76737)
		(width 0.14224)
		(layer "In11.Cu")
		(net "M_M_DQ<7>")
	)
	(segment
		(start 42.464228 -110.968536)
		(end 42.205402 -111.227362)
		(width 0.14224)
		(layer "In11.Cu")
		(net "M_M_DQ<7>")
	)
	(segment
		(start 42.004234 -111.227362)
		(end 41.205404 -110.428532)
		(width 0.14224)
		(layer "In11.Cu")
		(net "M_M_DQ<7>")
	)
	(segment
		(start 38.541198 -149.191472)
		(end 38.199314 -149.533356)
		(width 0.14224)
		(layer "In11.Cu")
		(net "M_M_DQ<7>")
	)
	(segment
		(start 39.365428 -112.268508)
		(end 39.16426 -112.268508)
		(width 0.14224)
		(layer "In11.Cu")
		(net "M_M_DQ<7>")
	)
	(segment
		(start 38.631368 -143.6878)
		(end 38.507416 -143.811752)
		(width 0.14224)
		(layer "In11.Cu")
		(net "M_M_DQ<7>")
	)
	(segment
		(start 42.205402 -111.227362)
		(end 42.004234 -111.227362)
		(width 0.14224)
		(layer "In11.Cu")
		(net "M_M_DQ<7>")
	)
	(segment
		(start 38.809168 -140.690854)
		(end 38.44925 -141.050772)
		(width 0.14224)
		(layer "In11.Cu")
		(net "M_M_DQ<7>")
	)
	(segment
		(start 42.924222 -110.307374)
		(end 42.125392 -109.508544)
		(width 0.14224)
		(layer "In11.Cu")
		(net "M_M_DQ<7>")
	)
	(segment
		(start 42.125392 -109.508544)
		(end 41.924224 -109.508544)
		(width 0.14224)
		(layer "In11.Cu")
		(net "M_M_DQ<7>")
	)
	(segment
		(start 70.629526 -88.87079)
		(end 70.59676 -88.87079)
		(width 0.0889)
		(layer "In11.Cu")
		(net "M_M_DQ<7>")
	)
	(segment
		(start 43.12539 -110.307374)
		(end 42.924222 -110.307374)
		(width 0.14224)
		(layer "In11.Cu")
		(net "M_M_DQ<7>")
	)
	(segment
		(start 38.834568 -130.141726)
		(end 38.834568 -131.064254)
		(width 0.14224)
		(layer "In11.Cu")
		(net "M_M_DQ<7>")
	)
	(segment
		(start 38.55212 -149.191472)
		(end 38.541198 -149.191472)
		(width 0.14224)
		(layer "In11.Cu")
		(net "M_M_DQ<7>")
	)
	(segment
		(start 69.774816 -89.365836)
		(end 69.74205 -89.365836)
		(width 0.0889)
		(layer "In11.Cu")
		(net "M_M_DQ<7>")
	)
	(segment
		(start 68.057776 -90.356436)
		(end 67.869816 -90.356436)
		(width 0.0889)
		(layer "In11.Cu")
		(net "M_M_DQ<7>")
	)
	(segment
		(start 38.865556 -129.001012)
		(end 38.55212 -129.314448)
		(width 0.14224)
		(layer "In11.Cu")
		(net "M_M_DQ<7>")
	)
	(segment
		(start 68.912486 -89.86139)
		(end 68.87972 -89.86139)
		(width 0.0889)
		(layer "In11.Cu")
		(net "M_M_DQ<7>")
	)
	(segment
		(start 43.384216 -109.84738)
		(end 43.384216 -110.048548)
		(width 0.14224)
		(layer "In11.Cu")
		(net "M_M_DQ<7>")
	)
	(segment
		(start 63.356744 -90.991944)
		(end 63.264288 -91.0844)
		(width 0.14224)
		(layer "In11.Cu")
		(net "M_M_DQ<7>")
	)
	(segment
		(start 74.219308 -86.88959)
		(end 74.03084 -86.88959)
		(width 0.0889)
		(layer "In11.Cu")
		(net "M_M_DQ<7>")
	)
	(segment
		(start 38.800786 -133.866382)
		(end 38.476174 -134.190994)
		(width 0.14224)
		(layer "In11.Cu")
		(net "M_M_DQ<7>")
	)
	(segment
		(start 40.084248 -111.34852)
		(end 39.825422 -111.607346)
		(width 0.14224)
		(layer "In11.Cu")
		(net "M_M_DQ<7>")
	)
	(segment
		(start 43.384216 -110.048548)
		(end 43.12539 -110.307374)
		(width 0.14224)
		(layer "In11.Cu")
		(net "M_M_DQ<7>")
	)
	(segment
		(start 40.285416 -111.34852)
		(end 40.084248 -111.34852)
		(width 0.14224)
		(layer "In11.Cu")
		(net "M_M_DQ<7>")
	)
	(segment
		(start 37.51072 -152.479248)
		(end 37.51072 -152.752552)
		(width 0.14224)
		(layer "In11.Cu")
		(net "M_M_DQ<7>")
	)
	(segment
		(start 41.665398 -109.76737)
		(end 41.665398 -109.968538)
		(width 0.14224)
		(layer "In11.Cu")
		(net "M_M_DQ<7>")
	)
	(segment
		(start 38.809168 -139.717526)
		(end 38.809168 -140.690854)
		(width 0.14224)
		(layer "In11.Cu")
		(net "M_M_DQ<7>")
	)
	(segment
		(start 74.904346 -86.794086)
		(end 74.370438 -86.872064)
		(width 0.0889)
		(layer "In11.Cu")
		(net "M_M_DQ<7>")
	)
	(segment
		(start 38.783768 -145.567146)
		(end 38.428168 -145.922746)
		(width 0.14224)
		(layer "In11.Cu")
		(net "M_M_DQ<7>")
	)
	(segment
		(start 38.44925 -141.42593)
		(end 38.631368 -141.608048)
		(width 0.14224)
		(layer "In11.Cu")
		(net "M_M_DQ<7>")
	)
	(segment
		(start 38.478968 -136.2964)
		(end 38.478968 -136.7282)
		(width 0.14224)
		(layer "In11.Cu")
		(net "M_M_DQ<7>")
	)
	(segment
		(start 38.47465 -131.424172)
		(end 38.47465 -131.948682)
		(width 0.14224)
		(layer "In11.Cu")
		(net "M_M_DQ<7>")
	)
	(segment
		(start 38.187122 -128.591056)
		(end 38.710616 -128.591056)
		(width 0.14224)
		(layer "In11.Cu")
		(net "M_M_DQ<7>")
	)
	(segment
		(start 67.101466 -90.85199)
		(end 66.713608 -90.85199)
		(width 0.0889)
		(layer "In11.Cu")
		(net "M_M_DQ<7>")
	)
	(segment
		(start 40.365426 -113.067338)
		(end 40.164258 -113.067338)
		(width 0.14224)
		(layer "In11.Cu")
		(net "M_M_DQ<7>")
	)
	(segment
		(start 37.793168 -151.1046)
		(end 37.51072 -151.387048)
		(width 0.14224)
		(layer "In11.Cu")
		(net "M_M_DQ<7>")
	)
	(segment
		(start 38.834568 -135.9408)
		(end 38.478968 -136.2964)
		(width 0.14224)
		(layer "In11.Cu")
		(net "M_M_DQ<7>")
	)
	(segment
		(start 72.346566 -87.88019)
		(end 72.3138 -87.88019)
		(width 0.0889)
		(layer "In11.Cu")
		(net "M_M_DQ<7>")
	)
	(segment
		(start 38.865556 -126.867412)
		(end 38.865556 -127.623316)
		(width 0.14224)
		(layer "In11.Cu")
		(net "M_M_DQ<7>")
	)
	(segment
		(start 42.971212 -108.740956)
		(end 42.714418 -108.99775)
		(width 0.14224)
		(layer "In11.Cu")
		(net "M_M_DQ<7>")
	)
	(segment
		(start 38.44925 -141.050772)
		(end 38.44925 -141.42593)
		(width 0.14224)
		(layer "In11.Cu")
		(net "M_M_DQ<7>")
	)
	(segment
		(start 38.032182 -128.436116)
		(end 38.187122 -128.591056)
		(width 0.14224)
		(layer "In11.Cu")
		(net "M_M_DQ<7>")
	)
	(segment
		(start 66.713608 -90.85199)
		(end 66.638424 -90.776806)
		(width 0.0889)
		(layer "In11.Cu")
		(net "M_M_DQ<7>")
	)
	(segment
		(start 44.045378 -109.387386)
		(end 43.84421 -109.387386)
		(width 0.14224)
		(layer "In11.Cu")
		(net "M_M_DQ<7>")
	)
	(segment
		(start 37.51072 -151.387048)
		(end 37.51072 -151.660352)
		(width 0.14224)
		(layer "In11.Cu")
		(net "M_M_DQ<7>")
	)
	(segment
		(start 63.571882 -90.776806)
		(end 63.356744 -90.991944)
		(width 0.0889)
		(layer "In11.Cu")
		(net "M_M_DQ<7>")
	)
	(segment
		(start 38.032182 -127.933196)
		(end 38.032182 -128.436116)
		(width 0.14224)
		(layer "In11.Cu")
		(net "M_M_DQ<7>")
	)
	(segment
		(start 38.631368 -136.8806)
		(end 38.631368 -138.7348)
		(width 0.14224)
		(layer "In11.Cu")
		(net "M_M_DQ<7>")
	)
	(segment
		(start 62.761368 -91.0844)
		(end 55.166768 -98.679)
		(width 0.14224)
		(layer "In11.Cu")
		(net "M_M_DQ<7>")
	)
	(segment
		(start 38.453568 -139.361926)
		(end 38.809168 -139.717526)
		(width 0.14224)
		(layer "In11.Cu")
		(net "M_M_DQ<7>")
	)
	(segment
		(start 38.199314 -149.533356)
		(end 38.176962 -149.533356)
		(width 0.14224)
		(layer "In11.Cu")
		(net "M_M_DQ<7>")
	)
	(segment
		(start 39.063168 -126.6698)
		(end 38.865556 -126.867412)
		(width 0.14224)
		(layer "In11.Cu")
		(net "M_M_DQ<7>")
	)
	(segment
		(start 43.19778 -108.740956)
		(end 42.971212 -108.740956)
		(width 0.14224)
		(layer "In11.Cu")
		(net "M_M_DQ<7>")
	)
	(segment
		(start 37.621718 -153.542746)
		(end 37.34943 -153.542746)
		(width 0.14224)
		(layer "In11.Cu")
		(net "M_M_DQ<7>")
	)
	(segment
		(start 40.164258 -113.067338)
		(end 39.365428 -112.268508)
		(width 0.14224)
		(layer "In11.Cu")
		(net "M_M_DQ<7>")
	)
	(segment
		(start 38.47465 -131.948682)
		(end 38.800786 -132.274818)
		(width 0.14224)
		(layer "In11.Cu")
		(net "M_M_DQ<7>")
	)
	(segment
		(start 40.74541 -110.687358)
		(end 40.74541 -110.888526)
		(width 0.14224)
		(layer "In11.Cu")
		(net "M_M_DQ<7>")
	)
	(segment
		(start 38.834568 -134.836916)
		(end 38.834568 -135.9408)
		(width 0.14224)
		(layer "In11.Cu")
		(net "M_M_DQ<7>")
	)
	(segment
		(start 38.865556 -127.623316)
		(end 38.710616 -127.778256)
		(width 0.14224)
		(layer "In11.Cu")
		(net "M_M_DQ<7>")
	)
	(segment
		(start 71.491856 -88.375236)
		(end 71.45909 -88.375236)
		(width 0.0889)
		(layer "In11.Cu")
		(net "M_M_DQ<7>")
	)
	(segment
		(start 38.710616 -128.591056)
		(end 38.865556 -128.745996)
		(width 0.14224)
		(layer "In11.Cu")
		(net "M_M_DQ<7>")
	)
	(segment
		(start 42.714418 -108.99775)
		(end 42.714418 -109.177582)
		(width 0.14224)
		(layer "In11.Cu")
		(net "M_M_DQ<7>")
	)
	(segment
		(start 42.464228 -110.767368)
		(end 42.464228 -110.968536)
		(width 0.14224)
		(layer "In11.Cu")
		(net "M_M_DQ<7>")
	)
	(segment
		(start 40.624252 -112.607344)
		(end 40.624252 -112.808512)
		(width 0.14224)
		(layer "In11.Cu")
		(net "M_M_DQ<7>")
	)
	(segment
		(start 39.16426 -112.268508)
		(end 38.905434 -112.527334)
		(width 0.14224)
		(layer "In11.Cu")
		(net "M_M_DQ<7>")
	)
	(segment
		(start 41.205404 -110.428532)
		(end 41.004236 -110.428532)
		(width 0.14224)
		(layer "In11.Cu")
		(net "M_M_DQ<7>")
	)
	(segment
		(start 38.476174 -134.190994)
		(end 38.476174 -134.478522)
		(width 0.14224)
		(layer "In11.Cu")
		(net "M_M_DQ<7>")
	)
	(arc
		(start 73.699116 -87.089488)
		(mid 73.492112 -87.300352)
		(end 73.208896 -87.384636)
		(width 0.0889)
		(layer "In11.Cu")
		(net "M_M_DQ<7>")
	)
	(arc
		(start 72.840596 -87.584788)
		(mid 72.631988 -87.79672)
		(end 72.346566 -87.88019)
		(width 0.0889)
		(layer "In11.Cu")
		(net "M_M_DQ<7>")
	)
	(arc
		(start 69.406516 -89.565988)
		(mid 69.197908 -89.77792)
		(end 68.912486 -89.86139)
		(width 0.0889)
		(layer "In11.Cu")
		(net "M_M_DQ<7>")
	)
	(arc
		(start 67.869816 -90.356436)
		(mid 67.766528 -90.417364)
		(end 67.683888 -90.504264)
		(width 0.0889)
		(layer "In11.Cu")
		(net "M_M_DQ<7>")
	)
	(arc
		(start 74.03084 -86.88959)
		(mid 73.839198 -86.946756)
		(end 73.699116 -87.089488)
		(width 0.0889)
		(layer "In11.Cu")
		(net "M_M_DQ<7>")
	)
	(arc
		(start 72.3138 -87.88019)
		(mid 72.122158 -87.937356)
		(end 71.982076 -88.080088)
		(width 0.0889)
		(layer "In11.Cu")
		(net "M_M_DQ<7>")
	)
	(arc
		(start 69.74205 -89.365836)
		(mid 69.5482 -89.422186)
		(end 69.406516 -89.565988)
		(width 0.0889)
		(layer "In11.Cu")
		(net "M_M_DQ<7>")
	)
	(arc
		(start 71.982076 -88.080088)
		(mid 71.775072 -88.290952)
		(end 71.491856 -88.375236)
		(width 0.0889)
		(layer "In11.Cu")
		(net "M_M_DQ<7>")
	)
	(arc
		(start 67.683888 -90.504264)
		(mid 67.440624 -90.758429)
		(end 67.101466 -90.85199)
		(width 0.0889)
		(layer "In11.Cu")
		(net "M_M_DQ<7>")
	)
	(arc
		(start 68.87972 -89.86139)
		(mid 68.688078 -89.918556)
		(end 68.547996 -90.061288)
		(width 0.0889)
		(layer "In11.Cu")
		(net "M_M_DQ<7>")
	)
	(arc
		(start 71.123556 -88.575388)
		(mid 70.914948 -88.78732)
		(end 70.629526 -88.87079)
		(width 0.0889)
		(layer "In11.Cu")
		(net "M_M_DQ<7>")
	)
	(arc
		(start 73.17613 -87.384636)
		(mid 72.98228 -87.440986)
		(end 72.840596 -87.584788)
		(width 0.0889)
		(layer "In11.Cu")
		(net "M_M_DQ<7>")
	)
	(arc
		(start 70.59676 -88.87079)
		(mid 70.405118 -88.927956)
		(end 70.265036 -89.070688)
		(width 0.0889)
		(layer "In11.Cu")
		(net "M_M_DQ<7>")
	)
	(arc
		(start 68.547996 -90.061288)
		(mid 68.340992 -90.272152)
		(end 68.057776 -90.356436)
		(width 0.0889)
		(layer "In11.Cu")
		(net "M_M_DQ<7>")
	)
	(arc
		(start 70.265036 -89.070688)
		(mid 70.058032 -89.281552)
		(end 69.774816 -89.365836)
		(width 0.0889)
		(layer "In11.Cu")
		(net "M_M_DQ<7>")
	)
	(arc
		(start 71.45909 -88.375236)
		(mid 71.26524 -88.431586)
		(end 71.123556 -88.575388)
		(width 0.0889)
		(layer "In11.Cu")
		(net "M_M_DQ<7>")
	)
	(segment
		(start 38.199568 -155.118054)
		(end 38.199314 -155.1178)
		(width 0.1651)
		(layer "F.Cu")
		(net "M_M_DQ<6>")
	)
	(segment
		(start 38.199568 -155.9052)
		(end 38.331648 -155.77312)
		(width 0.1651)
		(layer "F.Cu")
		(net "M_M_DQ<6>")
	)
	(segment
		(start 77.192886 -87.784686)
		(end 76.621386 -87.784686)
		(width 0.1651)
		(layer "F.Cu")
		(net "M_M_DQ<6>")
	)
	(segment
		(start 38.199568 -156.87294)
		(end 38.199568 -155.9052)
		(width 0.1651)
		(layer "F.Cu")
		(net "M_M_DQ<6>")
	)
	(segment
		(start 38.331648 -155.77312)
		(end 38.331648 -155.55468)
		(width 0.1651)
		(layer "F.Cu")
		(net "M_M_DQ<6>")
	)
	(segment
		(start 38.199568 -155.4226)
		(end 38.199568 -155.118054)
		(width 0.1651)
		(layer "F.Cu")
		(net "M_M_DQ<6>")
	)
	(segment
		(start 38.331648 -155.55468)
		(end 38.199568 -155.4226)
		(width 0.1651)
		(layer "F.Cu")
		(net "M_M_DQ<6>")
	)
	(via
		(at 76.621386 -87.784686)
		(size 0.508)
		(drill 0.254)
		(layers "F.Cu" "B.Cu")
		(net "M_M_DQ<6>")
	)
	(via
		(at 37.34943 -150.814278)
		(size 0.508)
		(drill 0.254)
		(layers "F.Cu" "B.Cu")
		(net "M_M_DQ<6>")
	)
	(via
		(at 38.199314 -155.1178)
		(size 0.508)
		(drill 0.254)
		(layers "F.Cu" "B.Cu")
		(net "M_M_DQ<6>")
	)
	(segment
		(start 37.34943 -152.078436)
		(end 37.34943 -150.814278)
		(width 0.1651)
		(layer "B.Cu")
		(net "M_M_DQ<6>")
	)
	(segment
		(start 37.95649 -131.83743)
		(end 37.95649 -131.456176)
		(width 0.14224)
		(layer "In11.Cu")
		(net "M_M_DQ<6>")
	)
	(segment
		(start 37.91712 -146.177)
		(end 37.91712 -145.857468)
		(width 0.14224)
		(layer "In11.Cu")
		(net "M_M_DQ<6>")
	)
	(segment
		(start 37.18052 -150.645368)
		(end 37.18052 -149.671278)
		(width 0.14224)
		(layer "In11.Cu")
		(net "M_M_DQ<6>")
	)
	(segment
		(start 73.169526 -87.194136)
		(end 73.202292 -87.194136)
		(width 0.0889)
		(layer "In11.Cu")
		(net "M_M_DQ<6>")
	)
	(segment
		(start 66.717164 -90.586814)
		(end 66.79184 -90.66149)
		(width 0.0889)
		(layer "In11.Cu")
		(net "M_M_DQ<6>")
	)
	(segment
		(start 41.857168 -108.3564)
		(end 43.594528 -106.61904)
		(width 0.14224)
		(layer "In11.Cu")
		(net "M_M_DQ<6>")
	)
	(segment
		(start 45.175678 -105.239058)
		(end 45.175678 -105.03789)
		(width 0.14224)
		(layer "In11.Cu")
		(net "M_M_DQ<6>")
	)
	(segment
		(start 36.91636 -151.247348)
		(end 36.91636 -153.834846)
		(width 0.14224)
		(layer "In11.Cu")
		(net "M_M_DQ<6>")
	)
	(segment
		(start 37.767768 -141.576552)
		(end 37.93109 -141.41323)
		(width 0.14224)
		(layer "In11.Cu")
		(net "M_M_DQ<6>")
	)
	(segment
		(start 37.767768 -132.026152)
		(end 37.95649 -131.83743)
		(width 0.14224)
		(layer "In11.Cu")
		(net "M_M_DQ<6>")
	)
	(segment
		(start 46.23181 -106.29519)
		(end 45.175678 -105.239058)
		(width 0.14224)
		(layer "In11.Cu")
		(net "M_M_DQ<6>")
	)
	(segment
		(start 37.767768 -138.7348)
		(end 37.767768 -136.9568)
		(width 0.14224)
		(layer "In11.Cu")
		(net "M_M_DQ<6>")
	)
	(segment
		(start 38.072568 -124.587)
		(end 38.072568 -124.207016)
		(width 0.14224)
		(layer "In11.Cu")
		(net "M_M_DQ<6>")
	)
	(segment
		(start 37.970968 -129.692654)
		(end 37.970968 -129.4638)
		(width 0.14224)
		(layer "In11.Cu")
		(net "M_M_DQ<6>")
	)
	(segment
		(start 37.93109 -141.41323)
		(end 37.93109 -141.006576)
		(width 0.14224)
		(layer "In11.Cu")
		(net "M_M_DQ<6>")
	)
	(segment
		(start 63.362078 -90.356944)
		(end 63.591948 -90.586814)
		(width 0.0889)
		(layer "In11.Cu")
		(net "M_M_DQ<6>")
	)
	(segment
		(start 37.91712 -139.460478)
		(end 37.91712 -138.884152)
		(width 0.14224)
		(layer "In11.Cu")
		(net "M_M_DQ<6>")
	)
	(segment
		(start 38.072568 -124.207016)
		(end 38.428168 -123.851416)
		(width 0.14224)
		(layer "In11.Cu")
		(net "M_M_DQ<6>")
	)
	(segment
		(start 49.772824 -104.8512)
		(end 54.430168 -100.193856)
		(width 0.14224)
		(layer "In11.Cu")
		(net "M_M_DQ<6>")
	)
	(segment
		(start 37.34943 -150.814278)
		(end 36.91636 -151.247348)
		(width 0.14224)
		(layer "In11.Cu")
		(net "M_M_DQ<6>")
	)
	(segment
		(start 70.590156 -88.68029)
		(end 70.622922 -88.68029)
		(width 0.0889)
		(layer "In11.Cu")
		(net "M_M_DQ<6>")
	)
	(segment
		(start 74.197972 -86.69909)
		(end 74.665332 -86.473284)
		(width 0.0889)
		(layer "In11.Cu")
		(net "M_M_DQ<6>")
	)
	(segment
		(start 37.767768 -136.9568)
		(end 37.983922 -136.740646)
		(width 0.14224)
		(layer "In11.Cu")
		(net "M_M_DQ<6>")
	)
	(segment
		(start 37.767768 -134.0358)
		(end 37.767768 -132.026152)
		(width 0.14224)
		(layer "In11.Cu")
		(net "M_M_DQ<6>")
	)
	(segment
		(start 36.91636 -153.834846)
		(end 38.199314 -155.1178)
		(width 0.14224)
		(layer "In11.Cu")
		(net "M_M_DQ<6>")
	)
	(segment
		(start 62.777624 -90.356944)
		(end 63.362078 -90.356944)
		(width 0.14224)
		(layer "In11.Cu")
		(net "M_M_DQ<6>")
	)
	(segment
		(start 37.91712 -138.884152)
		(end 37.767768 -138.7348)
		(width 0.14224)
		(layer "In11.Cu")
		(net "M_M_DQ<6>")
	)
	(segment
		(start 37.970968 -129.4638)
		(end 37.539168 -129.032)
		(width 0.14224)
		(layer "In11.Cu")
		(net "M_M_DQ<6>")
	)
	(segment
		(start 67.833494 -90.165936)
		(end 68.051172 -90.165936)
		(width 0.0889)
		(layer "In11.Cu")
		(net "M_M_DQ<6>")
	)
	(segment
		(start 44.715684 -105.699052)
		(end 45.771816 -106.755184)
		(width 0.14224)
		(layer "In11.Cu")
		(net "M_M_DQ<6>")
	)
	(segment
		(start 45.771816 -106.755184)
		(end 45.972984 -106.755184)
		(width 0.14224)
		(layer "In11.Cu")
		(net "M_M_DQ<6>")
	)
	(segment
		(start 38.428168 -123.851416)
		(end 38.428168 -112.2934)
		(width 0.14224)
		(layer "In11.Cu")
		(net "M_M_DQ<6>")
	)
	(segment
		(start 37.996368 -148.5392)
		(end 37.767768 -148.3106)
		(width 0.14224)
		(layer "In11.Cu")
		(net "M_M_DQ<6>")
	)
	(segment
		(start 38.428168 -126.3396)
		(end 38.428168 -124.9426)
		(width 0.14224)
		(layer "In11.Cu")
		(net "M_M_DQ<6>")
	)
	(segment
		(start 37.589968 -134.80542)
		(end 37.919914 -134.475474)
		(width 0.14224)
		(layer "In11.Cu")
		(net "M_M_DQ<6>")
	)
	(segment
		(start 45.311822 -107.215178)
		(end 44.25569 -106.159046)
		(width 0.14224)
		(layer "In11.Cu")
		(net "M_M_DQ<6>")
	)
	(segment
		(start 37.914072 -143.783304)
		(end 37.767768 -143.637)
		(width 0.14224)
		(layer "In11.Cu")
		(net "M_M_DQ<6>")
	)
	(segment
		(start 44.514516 -105.699052)
		(end 44.715684 -105.699052)
		(width 0.14224)
		(layer "In11.Cu")
		(net "M_M_DQ<6>")
	)
	(segment
		(start 37.539168 -129.032)
		(end 37.539168 -127.2286)
		(width 0.14224)
		(layer "In11.Cu")
		(net "M_M_DQ<6>")
	)
	(segment
		(start 75.432666 -86.69909)
		(end 75.784456 -86.69909)
		(width 0.0889)
		(layer "In11.Cu")
		(net "M_M_DQ<6>")
	)
	(segment
		(start 66.79184 -90.66149)
		(end 67.101466 -90.66149)
		(width 0.0889)
		(layer "In11.Cu")
		(net "M_M_DQ<6>")
	)
	(segment
		(start 54.430168 -98.7044)
		(end 62.777624 -90.356944)
		(width 0.14224)
		(layer "In11.Cu")
		(net "M_M_DQ<6>")
	)
	(segment
		(start 44.25569 -106.159046)
		(end 44.25569 -105.957878)
		(width 0.14224)
		(layer "In11.Cu")
		(net "M_M_DQ<6>")
	)
	(segment
		(start 44.851828 -107.675172)
		(end 45.052996 -107.675172)
		(width 0.14224)
		(layer "In11.Cu")
		(net "M_M_DQ<6>")
	)
	(segment
		(start 63.591948 -90.586814)
		(end 66.717164 -90.586814)
		(width 0.0889)
		(layer "In11.Cu")
		(net "M_M_DQ<6>")
	)
	(segment
		(start 37.95649 -131.456176)
		(end 37.564568 -131.064254)
		(width 0.14224)
		(layer "In11.Cu")
		(net "M_M_DQ<6>")
	)
	(segment
		(start 37.615368 -139.76223)
		(end 37.91712 -139.460478)
		(width 0.14224)
		(layer "In11.Cu")
		(net "M_M_DQ<6>")
	)
	(segment
		(start 45.362368 -104.8512)
		(end 49.772824 -104.8512)
		(width 0.14224)
		(layer "In11.Cu")
		(net "M_M_DQ<6>")
	)
	(segment
		(start 74.903584 -86.39429)
		(end 74.905108 -86.39429)
		(width 0.0889)
		(layer "In11.Cu")
		(net "M_M_DQ<6>")
	)
	(segment
		(start 37.767768 -148.3106)
		(end 37.767768 -146.326352)
		(width 0.14224)
		(layer "In11.Cu")
		(net "M_M_DQ<6>")
	)
	(segment
		(start 37.767768 -146.326352)
		(end 37.91712 -146.177)
		(width 0.14224)
		(layer "In11.Cu")
		(net "M_M_DQ<6>")
	)
	(segment
		(start 37.996368 -148.85543)
		(end 37.996368 -148.5392)
		(width 0.14224)
		(layer "In11.Cu")
		(net "M_M_DQ<6>")
	)
	(segment
		(start 76.274676 -86.994238)
		(end 76.29144 -87.02294)
		(width 0.0889)
		(layer "In11.Cu")
		(net "M_M_DQ<6>")
	)
	(segment
		(start 43.795696 -106.61904)
		(end 44.851828 -107.675172)
		(width 0.14224)
		(layer "In11.Cu")
		(net "M_M_DQ<6>")
	)
	(segment
		(start 37.914072 -144.071086)
		(end 37.914072 -143.783304)
		(width 0.14224)
		(layer "In11.Cu")
		(net "M_M_DQ<6>")
	)
	(segment
		(start 45.972984 -106.755184)
		(end 46.23181 -106.496358)
		(width 0.14224)
		(layer "In11.Cu")
		(net "M_M_DQ<6>")
	)
	(segment
		(start 37.589968 -135.9662)
		(end 37.589968 -134.80542)
		(width 0.14224)
		(layer "In11.Cu")
		(net "M_M_DQ<6>")
	)
	(segment
		(start 37.564568 -130.099054)
		(end 37.970968 -129.692654)
		(width 0.14224)
		(layer "In11.Cu")
		(net "M_M_DQ<6>")
	)
	(segment
		(start 44.25569 -105.957878)
		(end 44.514516 -105.699052)
		(width 0.14224)
		(layer "In11.Cu")
		(net "M_M_DQ<6>")
	)
	(segment
		(start 45.311822 -107.416346)
		(end 45.311822 -107.215178)
		(width 0.14224)
		(layer "In11.Cu")
		(net "M_M_DQ<6>")
	)
	(segment
		(start 74.024236 -86.69909)
		(end 74.197972 -86.69909)
		(width 0.0889)
		(layer "In11.Cu")
		(net "M_M_DQ<6>")
	)
	(segment
		(start 54.430168 -100.193856)
		(end 54.430168 -98.7044)
		(width 0.14224)
		(layer "In11.Cu")
		(net "M_M_DQ<6>")
	)
	(segment
		(start 46.23181 -106.496358)
		(end 46.23181 -106.29519)
		(width 0.14224)
		(layer "In11.Cu")
		(net "M_M_DQ<6>")
	)
	(segment
		(start 76.29144 -87.02294)
		(end 76.621386 -87.784686)
		(width 0.0889)
		(layer "In11.Cu")
		(net "M_M_DQ<6>")
	)
	(segment
		(start 37.18052 -149.671278)
		(end 37.996368 -148.85543)
		(width 0.14224)
		(layer "In11.Cu")
		(net "M_M_DQ<6>")
	)
	(segment
		(start 37.983922 -136.360154)
		(end 37.589968 -135.9662)
		(width 0.14224)
		(layer "In11.Cu")
		(net "M_M_DQ<6>")
	)
	(segment
		(start 37.615368 -140.690854)
		(end 37.615368 -139.76223)
		(width 0.14224)
		(layer "In11.Cu")
		(net "M_M_DQ<6>")
	)
	(segment
		(start 71.452486 -88.184736)
		(end 71.485252 -88.184736)
		(width 0.0889)
		(layer "In11.Cu")
		(net "M_M_DQ<6>")
	)
	(segment
		(start 37.539168 -127.2286)
		(end 38.428168 -126.3396)
		(width 0.14224)
		(layer "In11.Cu")
		(net "M_M_DQ<6>")
	)
	(segment
		(start 37.919914 -134.475474)
		(end 37.919914 -134.187946)
		(width 0.14224)
		(layer "In11.Cu")
		(net "M_M_DQ<6>")
	)
	(segment
		(start 37.91712 -145.857468)
		(end 37.513768 -145.454116)
		(width 0.14224)
		(layer "In11.Cu")
		(net "M_M_DQ<6>")
	)
	(segment
		(start 37.513768 -144.47139)
		(end 37.914072 -144.071086)
		(width 0.14224)
		(layer "In11.Cu")
		(net "M_M_DQ<6>")
	)
	(segment
		(start 38.428168 -112.2934)
		(end 41.857168 -108.8644)
		(width 0.14224)
		(layer "In11.Cu")
		(net "M_M_DQ<6>")
	)
	(segment
		(start 37.34943 -150.814278)
		(end 37.18052 -150.645368)
		(width 0.14224)
		(layer "In11.Cu")
		(net "M_M_DQ<6>")
	)
	(segment
		(start 41.857168 -108.8644)
		(end 41.857168 -108.3564)
		(width 0.14224)
		(layer "In11.Cu")
		(net "M_M_DQ<6>")
	)
	(segment
		(start 37.93109 -141.006576)
		(end 37.615368 -140.690854)
		(width 0.14224)
		(layer "In11.Cu")
		(net "M_M_DQ<6>")
	)
	(segment
		(start 37.513768 -145.454116)
		(end 37.513768 -144.47139)
		(width 0.14224)
		(layer "In11.Cu")
		(net "M_M_DQ<6>")
	)
	(segment
		(start 43.594528 -106.61904)
		(end 43.795696 -106.61904)
		(width 0.14224)
		(layer "In11.Cu")
		(net "M_M_DQ<6>")
	)
	(segment
		(start 37.767768 -143.637)
		(end 37.767768 -141.576552)
		(width 0.14224)
		(layer "In11.Cu")
		(net "M_M_DQ<6>")
	)
	(segment
		(start 69.735446 -89.175336)
		(end 69.768212 -89.175336)
		(width 0.0889)
		(layer "In11.Cu")
		(net "M_M_DQ<6>")
	)
	(segment
		(start 45.052996 -107.675172)
		(end 45.311822 -107.416346)
		(width 0.14224)
		(layer "In11.Cu")
		(net "M_M_DQ<6>")
	)
	(segment
		(start 37.919914 -134.187946)
		(end 37.767768 -134.0358)
		(width 0.14224)
		(layer "In11.Cu")
		(net "M_M_DQ<6>")
	)
	(segment
		(start 72.307196 -87.68969)
		(end 72.339962 -87.68969)
		(width 0.0889)
		(layer "In11.Cu")
		(net "M_M_DQ<6>")
	)
	(segment
		(start 45.175678 -105.03789)
		(end 45.362368 -104.8512)
		(width 0.14224)
		(layer "In11.Cu")
		(net "M_M_DQ<6>")
	)
	(segment
		(start 68.873116 -89.67089)
		(end 68.905882 -89.67089)
		(width 0.0889)
		(layer "In11.Cu")
		(net "M_M_DQ<6>")
	)
	(segment
		(start 37.983922 -136.740646)
		(end 37.983922 -136.360154)
		(width 0.14224)
		(layer "In11.Cu")
		(net "M_M_DQ<6>")
	)
	(segment
		(start 37.564568 -131.064254)
		(end 37.564568 -130.099054)
		(width 0.14224)
		(layer "In11.Cu")
		(net "M_M_DQ<6>")
	)
	(segment
		(start 38.428168 -124.9426)
		(end 38.072568 -124.587)
		(width 0.14224)
		(layer "In11.Cu")
		(net "M_M_DQ<6>")
	)
	(arc
		(start 70.099936 -88.975438)
		(mid 70.30694 -88.764574)
		(end 70.590156 -88.68029)
		(width 0.0889)
		(layer "In11.Cu")
		(net "M_M_DQ<6>")
	)
	(arc
		(start 74.665332 -86.473284)
		(mid 74.778085 -86.414553)
		(end 74.903584 -86.39429)
		(width 0.0889)
		(layer "In11.Cu")
		(net "M_M_DQ<6>")
	)
	(arc
		(start 68.051172 -90.165936)
		(mid 68.242814 -90.10877)
		(end 68.382896 -89.966038)
		(width 0.0889)
		(layer "In11.Cu")
		(net "M_M_DQ<6>")
	)
	(arc
		(start 73.534016 -86.994238)
		(mid 73.74102 -86.783374)
		(end 74.024236 -86.69909)
		(width 0.0889)
		(layer "In11.Cu")
		(net "M_M_DQ<6>")
	)
	(arc
		(start 68.382896 -89.966038)
		(mid 68.5899 -89.755174)
		(end 68.873116 -89.67089)
		(width 0.0889)
		(layer "In11.Cu")
		(net "M_M_DQ<6>")
	)
	(arc
		(start 68.905882 -89.67089)
		(mid 69.099732 -89.61454)
		(end 69.241416 -89.470738)
		(width 0.0889)
		(layer "In11.Cu")
		(net "M_M_DQ<6>")
	)
	(arc
		(start 73.202292 -87.194136)
		(mid 73.393934 -87.13697)
		(end 73.534016 -86.994238)
		(width 0.0889)
		(layer "In11.Cu")
		(net "M_M_DQ<6>")
	)
	(arc
		(start 71.816976 -87.984838)
		(mid 72.02398 -87.773974)
		(end 72.307196 -87.68969)
		(width 0.0889)
		(layer "In11.Cu")
		(net "M_M_DQ<6>")
	)
	(arc
		(start 72.675496 -87.489538)
		(mid 72.884104 -87.277606)
		(end 73.169526 -87.194136)
		(width 0.0889)
		(layer "In11.Cu")
		(net "M_M_DQ<6>")
	)
	(arc
		(start 70.622922 -88.68029)
		(mid 70.816772 -88.62394)
		(end 70.958456 -88.480138)
		(width 0.0889)
		(layer "In11.Cu")
		(net "M_M_DQ<6>")
	)
	(arc
		(start 69.241416 -89.470738)
		(mid 69.450024 -89.258806)
		(end 69.735446 -89.175336)
		(width 0.0889)
		(layer "In11.Cu")
		(net "M_M_DQ<6>")
	)
	(arc
		(start 67.101466 -90.66149)
		(mid 67.316913 -90.609252)
		(end 67.484498 -90.464132)
		(width 0.0889)
		(layer "In11.Cu")
		(net "M_M_DQ<6>")
	)
	(arc
		(start 70.958456 -88.480138)
		(mid 71.167064 -88.268206)
		(end 71.452486 -88.184736)
		(width 0.0889)
		(layer "In11.Cu")
		(net "M_M_DQ<6>")
	)
	(arc
		(start 75.784456 -86.69909)
		(mid 76.067673 -86.783371)
		(end 76.274676 -86.994238)
		(width 0.0889)
		(layer "In11.Cu")
		(net "M_M_DQ<6>")
	)
	(arc
		(start 71.485252 -88.184736)
		(mid 71.676894 -88.12757)
		(end 71.816976 -87.984838)
		(width 0.0889)
		(layer "In11.Cu")
		(net "M_M_DQ<6>")
	)
	(arc
		(start 75.251056 -86.594188)
		(mid 75.327788 -86.671017)
		(end 75.432666 -86.69909)
		(width 0.0889)
		(layer "In11.Cu")
		(net "M_M_DQ<6>")
	)
	(arc
		(start 67.484498 -90.464132)
		(mid 67.630598 -90.281798)
		(end 67.833494 -90.165936)
		(width 0.0889)
		(layer "In11.Cu")
		(net "M_M_DQ<6>")
	)
	(arc
		(start 69.768212 -89.175336)
		(mid 69.959854 -89.11817)
		(end 70.099936 -88.975438)
		(width 0.0889)
		(layer "In11.Cu")
		(net "M_M_DQ<6>")
	)
	(arc
		(start 72.339962 -87.68969)
		(mid 72.533812 -87.63334)
		(end 72.675496 -87.489538)
		(width 0.0889)
		(layer "In11.Cu")
		(net "M_M_DQ<6>")
	)
	(arc
		(start 74.905108 -86.39429)
		(mid 75.104881 -86.447859)
		(end 75.251056 -86.594188)
		(width 0.0889)
		(layer "In11.Cu")
		(net "M_M_DQ<6>")
	)
	(segment
		(start 119.070882 -92.061538)
		(end 119.642382 -92.061538)
		(width 0.1651)
		(layer "F.Cu")
		(net "M_M_DQ<63>")
	)
	(segment
		(start 148.699474 -152.273)
		(end 148.699474 -153.542746)
		(width 0.1651)
		(layer "F.Cu")
		(net "M_M_DQ<63>")
	)
	(via
		(at 149.549358 -149.533356)
		(size 0.508)
		(drill 0.254)
		(layers "F.Cu" "B.Cu")
		(net "M_M_DQ<63>")
	)
	(via
		(at 148.699474 -153.542746)
		(size 0.508)
		(drill 0.254)
		(layers "F.Cu" "B.Cu")
		(net "M_M_DQ<63>")
	)
	(via
		(at 119.642382 -92.061538)
		(size 0.508)
		(drill 0.254)
		(layers "F.Cu" "B.Cu")
		(net "M_M_DQ<63>")
	)
	(segment
		(start 149.549358 -147.478496)
		(end 149.549358 -149.533356)
		(width 0.1651)
		(layer "B.Cu")
		(net "M_M_DQ<63>")
	)
	(segment
		(start 123.058174 -94.442534)
		(end 123.093988 -94.442534)
		(width 0.0889)
		(layer "In11.Cu")
		(net "M_M_DQ<63>")
	)
	(segment
		(start 126.40691 -102.353872)
		(end 126.406656 -102.353872)
		(width 0.0889)
		(layer "In11.Cu")
		(net "M_M_DQ<63>")
	)
	(segment
		(start 149.984968 -141.713204)
		(end 149.984968 -143.6116)
		(width 0.14224)
		(layer "In11.Cu")
		(net "M_M_DQ<63>")
	)
	(segment
		(start 149.143212 -151.1046)
		(end 148.860764 -151.387048)
		(width 0.14224)
		(layer "In11.Cu")
		(net "M_M_DQ<63>")
	)
	(segment
		(start 149.33041 -126.340616)
		(end 149.33041 -126.843536)
		(width 0.14224)
		(layer "In11.Cu")
		(net "M_M_DQ<63>")
	)
	(segment
		(start 150.105364 -135.972042)
		(end 149.822662 -136.254744)
		(width 0.14224)
		(layer "In11.Cu")
		(net "M_M_DQ<63>")
	)
	(segment
		(start 150.130764 -131.205478)
		(end 149.927564 -131.408678)
		(width 0.14224)
		(layer "In11.Cu")
		(net "M_M_DQ<63>")
	)
	(segment
		(start 119.642382 -92.061538)
		(end 120.137428 -92.727272)
		(width 0.0889)
		(layer "In11.Cu")
		(net "M_M_DQ<63>")
	)
	(segment
		(start 150.14829 -127.811276)
		(end 149.492208 -127.811276)
		(width 0.14224)
		(layer "In11.Cu")
		(net "M_M_DQ<63>")
	)
	(segment
		(start 149.999192 -128.624076)
		(end 150.154132 -128.779016)
		(width 0.14224)
		(layer "In11.Cu")
		(net "M_M_DQ<63>")
	)
	(segment
		(start 149.149562 -153.364946)
		(end 148.971762 -153.542746)
		(width 0.14224)
		(layer "In11.Cu")
		(net "M_M_DQ<63>")
	)
	(segment
		(start 149.520656 -128.624076)
		(end 149.999192 -128.624076)
		(width 0.14224)
		(layer "In11.Cu")
		(net "M_M_DQ<63>")
	)
	(segment
		(start 150.30323 -127.656336)
		(end 150.14829 -127.811276)
		(width 0.14224)
		(layer "In11.Cu")
		(net "M_M_DQ<63>")
	)
	(segment
		(start 149.470364 -125.019054)
		(end 150.154132 -125.702822)
		(width 0.14224)
		(layer "In11.Cu")
		(net "M_M_DQ<63>")
	)
	(segment
		(start 149.984968 -148.336)
		(end 149.902164 -148.418804)
		(width 0.14224)
		(layer "In11.Cu")
		(net "M_M_DQ<63>")
	)
	(segment
		(start 149.984968 -136.906)
		(end 149.984968 -138.7602)
		(width 0.14224)
		(layer "In11.Cu")
		(net "M_M_DQ<63>")
	)
	(segment
		(start 126.495556 -102.367334)
		(end 126.570486 -102.370128)
		(width 0.0889)
		(layer "In11.Cu")
		(net "M_M_DQ<63>")
	)
	(segment
		(start 149.098762 -150.391368)
		(end 149.143212 -150.435818)
		(width 0.14224)
		(layer "In11.Cu")
		(net "M_M_DQ<63>")
	)
	(segment
		(start 149.48535 -126.998476)
		(end 150.14829 -126.998476)
		(width 0.14224)
		(layer "In11.Cu")
		(net "M_M_DQ<63>")
	)
	(segment
		(start 125.305058 -96.71939)
		(end 125.311408 -96.730058)
		(width 0.0889)
		(layer "In11.Cu")
		(net "M_M_DQ<63>")
	)
	(segment
		(start 150.071328 -144.313402)
		(end 150.071328 -145.659094)
		(width 0.14224)
		(layer "In11.Cu")
		(net "M_M_DQ<63>")
	)
	(segment
		(start 149.902164 -148.418804)
		(end 149.902164 -149.191472)
		(width 0.14224)
		(layer "In11.Cu")
		(net "M_M_DQ<63>")
	)
	(segment
		(start 150.130764 -139.689078)
		(end 150.130764 -140.69695)
		(width 0.14224)
		(layer "In11.Cu")
		(net "M_M_DQ<63>")
	)
	(segment
		(start 149.984968 -138.7602)
		(end 149.807168 -138.938)
		(width 0.14224)
		(layer "In11.Cu")
		(net "M_M_DQ<63>")
	)
	(segment
		(start 150.105364 -134.757668)
		(end 150.105364 -135.972042)
		(width 0.14224)
		(layer "In11.Cu")
		(net "M_M_DQ<63>")
	)
	(segment
		(start 136.479788 -109.932724)
		(end 149.470364 -122.9233)
		(width 0.14224)
		(layer "In11.Cu")
		(net "M_M_DQ<63>")
	)
	(segment
		(start 149.927564 -131.408678)
		(end 149.927564 -131.9022)
		(width 0.14224)
		(layer "In11.Cu")
		(net "M_M_DQ<63>")
	)
	(segment
		(start 150.130764 -130.087878)
		(end 150.130764 -131.205478)
		(width 0.14224)
		(layer "In11.Cu")
		(net "M_M_DQ<63>")
	)
	(segment
		(start 149.807168 -139.365482)
		(end 150.130764 -139.689078)
		(width 0.14224)
		(layer "In11.Cu")
		(net "M_M_DQ<63>")
	)
	(segment
		(start 149.999192 -126.185676)
		(end 149.48535 -126.185676)
		(width 0.14224)
		(layer "In11.Cu")
		(net "M_M_DQ<63>")
	)
	(segment
		(start 149.492208 -127.811276)
		(end 149.351492 -127.951992)
		(width 0.14224)
		(layer "In11.Cu")
		(net "M_M_DQ<63>")
	)
	(segment
		(start 149.902164 -146.177)
		(end 149.984968 -146.259804)
		(width 0.14224)
		(layer "In11.Cu")
		(net "M_M_DQ<63>")
	)
	(segment
		(start 120.485916 -92.956634)
		(end 120.518682 -92.956634)
		(width 0.0889)
		(layer "In11.Cu")
		(net "M_M_DQ<63>")
	)
	(segment
		(start 149.549358 -149.533356)
		(end 149.527006 -149.533356)
		(width 0.14224)
		(layer "In11.Cu")
		(net "M_M_DQ<63>")
	)
	(segment
		(start 122.202702 -93.947234)
		(end 122.230642 -93.947234)
		(width 0.0889)
		(layer "In11.Cu")
		(net "M_M_DQ<63>")
	)
	(segment
		(start 149.927564 -134.579868)
		(end 150.105364 -134.757668)
		(width 0.14224)
		(layer "In11.Cu")
		(net "M_M_DQ<63>")
	)
	(segment
		(start 150.154132 -126.030736)
		(end 149.999192 -126.185676)
		(width 0.14224)
		(layer "In11.Cu")
		(net "M_M_DQ<63>")
	)
	(segment
		(start 149.927564 -131.9022)
		(end 149.984968 -131.959604)
		(width 0.14224)
		(layer "In11.Cu")
		(net "M_M_DQ<63>")
	)
	(segment
		(start 149.984968 -143.6116)
		(end 149.927564 -143.669004)
		(width 0.14224)
		(layer "In11.Cu")
		(net "M_M_DQ<63>")
	)
	(segment
		(start 149.807168 -138.938)
		(end 149.807168 -139.365482)
		(width 0.14224)
		(layer "In11.Cu")
		(net "M_M_DQ<63>")
	)
	(segment
		(start 149.33041 -126.843536)
		(end 149.48535 -126.998476)
		(width 0.14224)
		(layer "In11.Cu")
		(net "M_M_DQ<63>")
	)
	(segment
		(start 149.984968 -131.959604)
		(end 149.984968 -134.0358)
		(width 0.14224)
		(layer "In11.Cu")
		(net "M_M_DQ<63>")
	)
	(segment
		(start 150.130764 -140.69695)
		(end 149.807168 -141.020546)
		(width 0.14224)
		(layer "In11.Cu")
		(net "M_M_DQ<63>")
	)
	(segment
		(start 150.154132 -129.084832)
		(end 149.902164 -129.3368)
		(width 0.14224)
		(layer "In11.Cu")
		(net "M_M_DQ<63>")
	)
	(segment
		(start 120.137428 -92.727272)
		(end 120.154192 -92.756736)
		(width 0.0889)
		(layer "In11.Cu")
		(net "M_M_DQ<63>")
	)
	(segment
		(start 125.305058 -100.681536)
		(end 125.311408 -100.692204)
		(width 0.0889)
		(layer "In11.Cu")
		(net "M_M_DQ<63>")
	)
	(segment
		(start 121.012712 -93.252036)
		(end 121.016014 -93.257878)
		(width 0.0889)
		(layer "In11.Cu")
		(net "M_M_DQ<63>")
	)
	(segment
		(start 125.305058 -101.272086)
		(end 125.300232 -101.280722)
		(width 0.0889)
		(layer "In11.Cu")
		(net "M_M_DQ<63>")
	)
	(segment
		(start 149.927564 -143.669004)
		(end 149.927564 -144.169638)
		(width 0.14224)
		(layer "In11.Cu")
		(net "M_M_DQ<63>")
	)
	(segment
		(start 128.542796 -103.827072)
		(end 134.648448 -109.932724)
		(width 0.14224)
		(layer "In11.Cu")
		(net "M_M_DQ<63>")
	)
	(segment
		(start 149.48535 -126.185676)
		(end 149.33041 -126.340616)
		(width 0.14224)
		(layer "In11.Cu")
		(net "M_M_DQ<63>")
	)
	(segment
		(start 149.984968 -146.259804)
		(end 149.984968 -148.336)
		(width 0.14224)
		(layer "In11.Cu")
		(net "M_M_DQ<63>")
	)
	(segment
		(start 126.570486 -102.370128)
		(end 126.868174 -102.667816)
		(width 0.0889)
		(layer "In11.Cu")
		(net "M_M_DQ<63>")
	)
	(segment
		(start 149.927564 -134.093204)
		(end 149.927564 -134.579868)
		(width 0.14224)
		(layer "In11.Cu")
		(net "M_M_DQ<63>")
	)
	(segment
		(start 149.527006 -149.533356)
		(end 149.098762 -149.9616)
		(width 0.14224)
		(layer "In11.Cu")
		(net "M_M_DQ<63>")
	)
	(segment
		(start 149.098762 -149.9616)
		(end 149.098762 -150.391368)
		(width 0.14224)
		(layer "In11.Cu")
		(net "M_M_DQ<63>")
	)
	(segment
		(start 149.927564 -144.169638)
		(end 150.071328 -144.313402)
		(width 0.14224)
		(layer "In11.Cu")
		(net "M_M_DQ<63>")
	)
	(segment
		(start 149.822662 -136.743694)
		(end 149.984968 -136.906)
		(width 0.14224)
		(layer "In11.Cu")
		(net "M_M_DQ<63>")
	)
	(segment
		(start 149.143212 -150.435818)
		(end 149.143212 -151.1046)
		(width 0.14224)
		(layer "In11.Cu")
		(net "M_M_DQ<63>")
	)
	(segment
		(start 149.807168 -141.020546)
		(end 149.807168 -141.535404)
		(width 0.14224)
		(layer "In11.Cu")
		(net "M_M_DQ<63>")
	)
	(segment
		(start 125.305058 -99.290886)
		(end 125.300232 -99.299522)
		(width 0.0889)
		(layer "In11.Cu")
		(net "M_M_DQ<63>")
	)
	(segment
		(start 148.860764 -151.660352)
		(end 149.117812 -151.9174)
		(width 0.14224)
		(layer "In11.Cu")
		(net "M_M_DQ<63>")
	)
	(segment
		(start 149.117812 -151.9174)
		(end 149.117812 -152.2222)
		(width 0.14224)
		(layer "In11.Cu")
		(net "M_M_DQ<63>")
	)
	(segment
		(start 126.868174 -103.683816)
		(end 126.96063 -103.776272)
		(width 0.0889)
		(layer "In11.Cu")
		(net "M_M_DQ<63>")
	)
	(segment
		(start 134.648448 -109.932724)
		(end 136.479788 -109.932724)
		(width 0.14224)
		(layer "In11.Cu")
		(net "M_M_DQ<63>")
	)
	(segment
		(start 126.96063 -103.776272)
		(end 127.286004 -103.776272)
		(width 0.0889)
		(layer "In11.Cu")
		(net "M_M_DQ<63>")
	)
	(segment
		(start 149.807168 -141.535404)
		(end 149.984968 -141.713204)
		(width 0.14224)
		(layer "In11.Cu")
		(net "M_M_DQ<63>")
	)
	(segment
		(start 149.902164 -129.859278)
		(end 150.130764 -130.087878)
		(width 0.14224)
		(layer "In11.Cu")
		(net "M_M_DQ<63>")
	)
	(segment
		(start 149.984968 -134.0358)
		(end 149.927564 -134.093204)
		(width 0.14224)
		(layer "In11.Cu")
		(net "M_M_DQ<63>")
	)
	(segment
		(start 150.071328 -145.659094)
		(end 149.902164 -145.828258)
		(width 0.14224)
		(layer "In11.Cu")
		(net "M_M_DQ<63>")
	)
	(segment
		(start 126.868174 -102.667816)
		(end 126.868174 -103.683816)
		(width 0.0889)
		(layer "In11.Cu")
		(net "M_M_DQ<63>")
	)
	(segment
		(start 123.916694 -94.937834)
		(end 123.956318 -94.937834)
		(width 0.0889)
		(layer "In11.Cu")
		(net "M_M_DQ<63>")
	)
	(segment
		(start 149.470364 -122.9233)
		(end 149.470364 -125.019054)
		(width 0.14224)
		(layer "In11.Cu")
		(net "M_M_DQ<63>")
	)
	(segment
		(start 149.902164 -145.828258)
		(end 149.902164 -146.177)
		(width 0.14224)
		(layer "In11.Cu")
		(net "M_M_DQ<63>")
	)
	(segment
		(start 125.305058 -98.300286)
		(end 125.300232 -98.308922)
		(width 0.0889)
		(layer "In11.Cu")
		(net "M_M_DQ<63>")
	)
	(segment
		(start 150.154132 -128.779016)
		(end 150.154132 -129.084832)
		(width 0.14224)
		(layer "In11.Cu")
		(net "M_M_DQ<63>")
	)
	(segment
		(start 149.902164 -129.3368)
		(end 149.902164 -129.859278)
		(width 0.14224)
		(layer "In11.Cu")
		(net "M_M_DQ<63>")
	)
	(segment
		(start 150.154132 -125.702822)
		(end 150.154132 -126.030736)
		(width 0.14224)
		(layer "In11.Cu")
		(net "M_M_DQ<63>")
	)
	(segment
		(start 125.636782 -101.872034)
		(end 125.673358 -101.872034)
		(width 0.0889)
		(layer "In11.Cu")
		(net "M_M_DQ<63>")
	)
	(segment
		(start 127.286004 -103.776272)
		(end 127.336804 -103.827072)
		(width 0.14224)
		(layer "In11.Cu")
		(net "M_M_DQ<63>")
	)
	(segment
		(start 148.860764 -152.479248)
		(end 148.860764 -152.752552)
		(width 0.14224)
		(layer "In11.Cu")
		(net "M_M_DQ<63>")
	)
	(segment
		(start 149.822662 -136.254744)
		(end 149.822662 -136.743694)
		(width 0.14224)
		(layer "In11.Cu")
		(net "M_M_DQ<63>")
	)
	(segment
		(start 149.902164 -149.191472)
		(end 149.891242 -149.191472)
		(width 0.14224)
		(layer "In11.Cu")
		(net "M_M_DQ<63>")
	)
	(segment
		(start 148.860764 -152.752552)
		(end 149.149562 -153.04135)
		(width 0.14224)
		(layer "In11.Cu")
		(net "M_M_DQ<63>")
	)
	(segment
		(start 149.117812 -152.2222)
		(end 148.860764 -152.479248)
		(width 0.14224)
		(layer "In11.Cu")
		(net "M_M_DQ<63>")
	)
	(segment
		(start 149.351492 -127.951992)
		(end 149.351492 -128.454912)
		(width 0.14224)
		(layer "In11.Cu")
		(net "M_M_DQ<63>")
	)
	(segment
		(start 149.351492 -128.454912)
		(end 149.520656 -128.624076)
		(width 0.14224)
		(layer "In11.Cu")
		(net "M_M_DQ<63>")
	)
	(segment
		(start 150.14829 -126.998476)
		(end 150.30323 -127.153416)
		(width 0.14224)
		(layer "In11.Cu")
		(net "M_M_DQ<63>")
	)
	(segment
		(start 149.891242 -149.191472)
		(end 149.549358 -149.533356)
		(width 0.14224)
		(layer "In11.Cu")
		(net "M_M_DQ<63>")
	)
	(segment
		(start 148.860764 -151.387048)
		(end 148.860764 -151.660352)
		(width 0.14224)
		(layer "In11.Cu")
		(net "M_M_DQ<63>")
	)
	(segment
		(start 125.300232 -96.710754)
		(end 125.305058 -96.71939)
		(width 0.0889)
		(layer "In11.Cu")
		(net "M_M_DQ<63>")
	)
	(segment
		(start 127.336804 -103.827072)
		(end 128.542796 -103.827072)
		(width 0.14224)
		(layer "In11.Cu")
		(net "M_M_DQ<63>")
	)
	(segment
		(start 150.30323 -127.153416)
		(end 150.30323 -127.656336)
		(width 0.14224)
		(layer "In11.Cu")
		(net "M_M_DQ<63>")
	)
	(segment
		(start 148.971762 -153.542746)
		(end 148.699474 -153.542746)
		(width 0.14224)
		(layer "In11.Cu")
		(net "M_M_DQ<63>")
	)
	(segment
		(start 121.359168 -93.452188)
		(end 121.380758 -93.452188)
		(width 0.0889)
		(layer "In11.Cu")
		(net "M_M_DQ<63>")
	)
	(segment
		(start 149.149562 -153.04135)
		(end 149.149562 -153.364946)
		(width 0.14224)
		(layer "In11.Cu")
		(net "M_M_DQ<63>")
	)
	(segment
		(start 125.311408 -99.280218)
		(end 125.305058 -99.290886)
		(width 0.0889)
		(layer "In11.Cu")
		(net "M_M_DQ<63>")
	)
	(arc
		(start 121.016014 -93.257878)
		(mid 121.16198 -93.400277)
		(end 121.359168 -93.452188)
		(width 0.0889)
		(layer "In11.Cu")
		(net "M_M_DQ<63>")
	)
	(arc
		(start 125.311408 -100.692204)
		(mid 125.384206 -100.982967)
		(end 125.305058 -101.272086)
		(width 0.0889)
		(layer "In11.Cu")
		(net "M_M_DQ<63>")
	)
	(arc
		(start 123.093988 -94.442534)
		(mid 123.379412 -94.526001)
		(end 123.588018 -94.737936)
		(width 0.0889)
		(layer "In11.Cu")
		(net "M_M_DQ<63>")
	)
	(arc
		(start 125.300232 -101.280722)
		(mid 125.303979 -101.669978)
		(end 125.636782 -101.872034)
		(width 0.0889)
		(layer "In11.Cu")
		(net "M_M_DQ<63>")
	)
	(arc
		(start 125.305058 -96.31934)
		(mid 125.251588 -96.514403)
		(end 125.300232 -96.710754)
		(width 0.0889)
		(layer "In11.Cu")
		(net "M_M_DQ<63>")
	)
	(arc
		(start 126.163578 -102.167182)
		(mid 126.266642 -102.28478)
		(end 126.40691 -102.353872)
		(width 0.0889)
		(layer "In11.Cu")
		(net "M_M_DQ<63>")
	)
	(arc
		(start 123.956318 -94.937834)
		(mid 124.239535 -95.022115)
		(end 124.446538 -95.232982)
		(width 0.0889)
		(layer "In11.Cu")
		(net "M_M_DQ<63>")
	)
	(arc
		(start 122.729498 -94.242636)
		(mid 122.868242 -94.384669)
		(end 123.058174 -94.442534)
		(width 0.0889)
		(layer "In11.Cu")
		(net "M_M_DQ<63>")
	)
	(arc
		(start 125.305058 -99.690936)
		(mid 125.384189 -99.986338)
		(end 125.305058 -100.28174)
		(width 0.0889)
		(layer "In11.Cu")
		(net "M_M_DQ<63>")
	)
	(arc
		(start 125.305058 -97.710244)
		(mid 125.384063 -98.005282)
		(end 125.305058 -98.300286)
		(width 0.0889)
		(layer "In11.Cu")
		(net "M_M_DQ<63>")
	)
	(arc
		(start 125.305058 -97.310448)
		(mid 125.251559 -97.510346)
		(end 125.305058 -97.710244)
		(width 0.0889)
		(layer "In11.Cu")
		(net "M_M_DQ<63>")
	)
	(arc
		(start 125.305058 -100.28174)
		(mid 125.251559 -100.481638)
		(end 125.305058 -100.681536)
		(width 0.0889)
		(layer "In11.Cu")
		(net "M_M_DQ<63>")
	)
	(arc
		(start 125.311408 -96.730058)
		(mid 125.384172 -97.021075)
		(end 125.305058 -97.310448)
		(width 0.0889)
		(layer "In11.Cu")
		(net "M_M_DQ<63>")
	)
	(arc
		(start 125.300232 -98.308922)
		(mid 125.251477 -98.505274)
		(end 125.305058 -98.700336)
		(width 0.0889)
		(layer "In11.Cu")
		(net "M_M_DQ<63>")
	)
	(arc
		(start 124.814838 -95.433388)
		(mid 125.310315 -95.737831)
		(end 125.305058 -96.31934)
		(width 0.0889)
		(layer "In11.Cu")
		(net "M_M_DQ<63>")
	)
	(arc
		(start 120.518682 -92.956634)
		(mid 120.804106 -93.040101)
		(end 121.012712 -93.252036)
		(width 0.0889)
		(layer "In11.Cu")
		(net "M_M_DQ<63>")
	)
	(arc
		(start 121.380758 -93.452188)
		(mid 121.663975 -93.536469)
		(end 121.870978 -93.747336)
		(width 0.0889)
		(layer "In11.Cu")
		(net "M_M_DQ<63>")
	)
	(arc
		(start 125.673358 -101.872034)
		(mid 125.956575 -101.956315)
		(end 126.163578 -102.167182)
		(width 0.0889)
		(layer "In11.Cu")
		(net "M_M_DQ<63>")
	)
	(arc
		(start 126.406656 -102.353872)
		(mid 126.450728 -102.363093)
		(end 126.495556 -102.367334)
		(width 0.0889)
		(layer "In11.Cu")
		(net "M_M_DQ<63>")
	)
	(arc
		(start 122.230642 -93.947234)
		(mid 122.518787 -94.029553)
		(end 122.729498 -94.242636)
		(width 0.0889)
		(layer "In11.Cu")
		(net "M_M_DQ<63>")
	)
	(arc
		(start 124.446538 -95.232982)
		(mid 124.588221 -95.376786)
		(end 124.782072 -95.433134)
		(width 0.0889)
		(layer "In11.Cu")
		(net "M_M_DQ<63>")
	)
	(arc
		(start 125.300232 -99.299522)
		(mid 125.251477 -99.495874)
		(end 125.305058 -99.690936)
		(width 0.0889)
		(layer "In11.Cu")
		(net "M_M_DQ<63>")
	)
	(arc
		(start 121.870978 -93.747336)
		(mid 122.011057 -93.890072)
		(end 122.202702 -93.947234)
		(width 0.0889)
		(layer "In11.Cu")
		(net "M_M_DQ<63>")
	)
	(arc
		(start 123.588018 -94.737936)
		(mid 123.726762 -94.879969)
		(end 123.916694 -94.937834)
		(width 0.0889)
		(layer "In11.Cu")
		(net "M_M_DQ<63>")
	)
	(arc
		(start 124.782072 -95.433134)
		(mid 124.798457 -95.433026)
		(end 124.814838 -95.433388)
		(width 0.0889)
		(layer "In11.Cu")
		(net "M_M_DQ<63>")
	)
	(arc
		(start 120.154192 -92.756736)
		(mid 120.294271 -92.899472)
		(end 120.485916 -92.956634)
		(width 0.0889)
		(layer "In11.Cu")
		(net "M_M_DQ<63>")
	)
	(arc
		(start 125.305058 -98.700336)
		(mid 125.38428 -98.989454)
		(end 125.311408 -99.280218)
		(width 0.0889)
		(layer "In11.Cu")
		(net "M_M_DQ<63>")
	)
	(segment
		(start 149.549612 -156.87294)
		(end 149.549612 -155.9052)
		(width 0.1651)
		(layer "F.Cu")
		(net "M_M_DQ<62>")
	)
	(segment
		(start 149.549612 -155.4226)
		(end 149.549612 -155.118054)
		(width 0.1651)
		(layer "F.Cu")
		(net "M_M_DQ<62>")
	)
	(segment
		(start 119.070882 -90.080338)
		(end 119.642382 -90.080338)
		(width 0.1651)
		(layer "F.Cu")
		(net "M_M_DQ<62>")
	)
	(segment
		(start 149.549358 -156.87294)
		(end 149.549612 -156.87294)
		(width 0.1651)
		(layer "F.Cu")
		(net "M_M_DQ<62>")
	)
	(segment
		(start 149.549612 -155.118054)
		(end 149.549358 -155.1178)
		(width 0.1651)
		(layer "F.Cu")
		(net "M_M_DQ<62>")
	)
	(segment
		(start 149.549612 -155.9052)
		(end 149.681692 -155.77312)
		(width 0.1651)
		(layer "F.Cu")
		(net "M_M_DQ<62>")
	)
	(segment
		(start 149.681692 -155.77312)
		(end 149.681692 -155.55468)
		(width 0.1651)
		(layer "F.Cu")
		(net "M_M_DQ<62>")
	)
	(segment
		(start 149.681692 -155.55468)
		(end 149.549612 -155.4226)
		(width 0.1651)
		(layer "F.Cu")
		(net "M_M_DQ<62>")
	)
	(via
		(at 148.699474 -150.814278)
		(size 0.508)
		(drill 0.254)
		(layers "F.Cu" "B.Cu")
		(net "M_M_DQ<62>")
	)
	(via
		(at 119.642382 -90.080338)
		(size 0.508)
		(drill 0.254)
		(layers "F.Cu" "B.Cu")
		(net "M_M_DQ<62>")
	)
	(via
		(at 149.549358 -155.1178)
		(size 0.508)
		(drill 0.254)
		(layers "F.Cu" "B.Cu")
		(net "M_M_DQ<62>")
	)
	(segment
		(start 148.699474 -152.078436)
		(end 148.699474 -150.814278)
		(width 0.1651)
		(layer "B.Cu")
		(net "M_M_DQ<62>")
	)
	(segment
		(start 148.943822 -145.593054)
		(end 149.267164 -145.916396)
		(width 0.14224)
		(layer "In11.Cu")
		(net "M_M_DQ<62>")
	)
	(segment
		(start 148.530564 -150.645368)
		(end 148.699474 -150.814278)
		(width 0.14224)
		(layer "In11.Cu")
		(net "M_M_DQ<62>")
	)
	(segment
		(start 128.36652 -104.4448)
		(end 134.436104 -110.514384)
		(width 0.14224)
		(layer "In11.Cu")
		(net "M_M_DQ<62>")
	)
	(segment
		(start 126.677674 -103.76281)
		(end 126.835154 -103.92029)
		(width 0.0889)
		(layer "In11.Cu")
		(net "M_M_DQ<62>")
	)
	(segment
		(start 148.826982 -129.017014)
		(end 149.267164 -129.457196)
		(width 0.14224)
		(layer "In11.Cu")
		(net "M_M_DQ<62>")
	)
	(segment
		(start 126.488698 -102.557834)
		(end 126.677674 -102.74681)
		(width 0.0889)
		(layer "In11.Cu")
		(net "M_M_DQ<62>")
	)
	(segment
		(start 125.133608 -96.803972)
		(end 125.139958 -96.81464)
		(width 0.0889)
		(layer "In11.Cu")
		(net "M_M_DQ<62>")
	)
	(segment
		(start 120.479312 -93.147134)
		(end 120.500902 -93.147134)
		(width 0.0889)
		(layer "In11.Cu")
		(net "M_M_DQ<62>")
	)
	(segment
		(start 119.642382 -90.080338)
		(end 119.312436 -90.842084)
		(width 0.0889)
		(layer "In11.Cu")
		(net "M_M_DQ<62>")
	)
	(segment
		(start 149.121368 -134.0358)
		(end 149.165564 -134.079996)
		(width 0.14224)
		(layer "In11.Cu")
		(net "M_M_DQ<62>")
	)
	(segment
		(start 123.054618 -94.633288)
		(end 123.094242 -94.633288)
		(width 0.0889)
		(layer "In11.Cu")
		(net "M_M_DQ<62>")
	)
	(segment
		(start 149.063964 -131.307078)
		(end 149.165564 -131.408678)
		(width 0.14224)
		(layer "In11.Cu")
		(net "M_M_DQ<62>")
	)
	(segment
		(start 148.994368 -139.733274)
		(end 148.994368 -140.741146)
		(width 0.14224)
		(layer "In11.Cu")
		(net "M_M_DQ<62>")
	)
	(segment
		(start 123.916948 -95.128588)
		(end 123.952762 -95.128588)
		(width 0.0889)
		(layer "In11.Cu")
		(net "M_M_DQ<62>")
	)
	(segment
		(start 149.121368 -141.522196)
		(end 149.121368 -143.6624)
		(width 0.14224)
		(layer "In11.Cu")
		(net "M_M_DQ<62>")
	)
	(segment
		(start 149.121368 -148.3106)
		(end 149.362414 -148.551646)
		(width 0.14224)
		(layer "In11.Cu")
		(net "M_M_DQ<62>")
	)
	(segment
		(start 149.362414 -148.839428)
		(end 148.530564 -149.671278)
		(width 0.14224)
		(layer "In11.Cu")
		(net "M_M_DQ<62>")
	)
	(segment
		(start 149.253194 -143.794226)
		(end 149.253194 -144.082008)
		(width 0.14224)
		(layer "In11.Cu")
		(net "M_M_DQ<62>")
	)
	(segment
		(start 149.267164 -129.457196)
		(end 149.267164 -129.859278)
		(width 0.14224)
		(layer "In11.Cu")
		(net "M_M_DQ<62>")
	)
	(segment
		(start 125.133608 -100.766118)
		(end 125.139958 -100.776786)
		(width 0.0889)
		(layer "In11.Cu")
		(net "M_M_DQ<62>")
	)
	(segment
		(start 125.630178 -102.062534)
		(end 125.662944 -102.062534)
		(width 0.0889)
		(layer "In11.Cu")
		(net "M_M_DQ<62>")
	)
	(segment
		(start 149.165564 -131.408678)
		(end 149.165564 -131.9784)
		(width 0.14224)
		(layer "In11.Cu")
		(net "M_M_DQ<62>")
	)
	(segment
		(start 122.204734 -94.137988)
		(end 122.228864 -94.137988)
		(width 0.0889)
		(layer "In11.Cu")
		(net "M_M_DQ<62>")
	)
	(segment
		(start 149.267164 -129.859278)
		(end 149.063964 -130.062478)
		(width 0.14224)
		(layer "In11.Cu")
		(net "M_M_DQ<62>")
	)
	(segment
		(start 148.699474 -150.814278)
		(end 148.266404 -151.247348)
		(width 0.14224)
		(layer "In11.Cu")
		(net "M_M_DQ<62>")
	)
	(segment
		(start 119.312436 -90.842084)
		(end 119.295672 -90.870786)
		(width 0.0889)
		(layer "In11.Cu")
		(net "M_M_DQ<62>")
	)
	(segment
		(start 149.121368 -143.6624)
		(end 149.253194 -143.794226)
		(width 0.14224)
		(layer "In11.Cu")
		(net "M_M_DQ<62>")
	)
	(segment
		(start 149.121368 -132.022596)
		(end 149.121368 -134.0358)
		(width 0.14224)
		(layer "In11.Cu")
		(net "M_M_DQ<62>")
	)
	(segment
		(start 149.253194 -144.082008)
		(end 148.943822 -144.39138)
		(width 0.14224)
		(layer "In11.Cu")
		(net "M_M_DQ<62>")
	)
	(segment
		(start 149.267164 -139.460478)
		(end 148.994368 -139.733274)
		(width 0.14224)
		(layer "In11.Cu")
		(net "M_M_DQ<62>")
	)
	(segment
		(start 149.165564 -134.079996)
		(end 149.165564 -134.579868)
		(width 0.14224)
		(layer "In11.Cu")
		(net "M_M_DQ<62>")
	)
	(segment
		(start 148.943822 -144.39138)
		(end 148.943822 -145.593054)
		(width 0.14224)
		(layer "In11.Cu")
		(net "M_M_DQ<62>")
	)
	(segment
		(start 149.121368 -146.297396)
		(end 149.121368 -148.3106)
		(width 0.14224)
		(layer "In11.Cu")
		(net "M_M_DQ<62>")
	)
	(segment
		(start 149.267164 -136.264396)
		(end 149.267164 -136.658604)
		(width 0.14224)
		(layer "In11.Cu")
		(net "M_M_DQ<62>")
	)
	(segment
		(start 136.252712 -110.514384)
		(end 148.826982 -123.088654)
		(width 0.14224)
		(layer "In11.Cu")
		(net "M_M_DQ<62>")
	)
	(segment
		(start 149.267164 -145.916396)
		(end 149.267164 -146.1516)
		(width 0.14224)
		(layer "In11.Cu")
		(net "M_M_DQ<62>")
	)
	(segment
		(start 148.994368 -140.741146)
		(end 149.304502 -141.05128)
		(width 0.14224)
		(layer "In11.Cu")
		(net "M_M_DQ<62>")
	)
	(segment
		(start 149.165564 -134.579868)
		(end 149.063964 -134.681468)
		(width 0.14224)
		(layer "In11.Cu")
		(net "M_M_DQ<62>")
	)
	(segment
		(start 149.063964 -134.681468)
		(end 149.063964 -136.061196)
		(width 0.14224)
		(layer "In11.Cu")
		(net "M_M_DQ<62>")
	)
	(segment
		(start 125.139958 -96.81464)
		(end 125.144784 -96.823276)
		(width 0.0889)
		(layer "In11.Cu")
		(net "M_M_DQ<62>")
	)
	(segment
		(start 149.063964 -130.062478)
		(end 149.063964 -131.307078)
		(width 0.14224)
		(layer "In11.Cu")
		(net "M_M_DQ<62>")
	)
	(segment
		(start 148.530564 -149.671278)
		(end 148.530564 -150.645368)
		(width 0.14224)
		(layer "In11.Cu")
		(net "M_M_DQ<62>")
	)
	(segment
		(start 149.304502 -141.339062)
		(end 149.121368 -141.522196)
		(width 0.14224)
		(layer "In11.Cu")
		(net "M_M_DQ<62>")
	)
	(segment
		(start 149.063964 -136.061196)
		(end 149.267164 -136.264396)
		(width 0.14224)
		(layer "In11.Cu")
		(net "M_M_DQ<62>")
	)
	(segment
		(start 149.267164 -146.1516)
		(end 149.121368 -146.297396)
		(width 0.14224)
		(layer "In11.Cu")
		(net "M_M_DQ<62>")
	)
	(segment
		(start 127.052832 -104.4448)
		(end 128.36652 -104.4448)
		(width 0.14224)
		(layer "In11.Cu")
		(net "M_M_DQ<62>")
	)
	(segment
		(start 149.304502 -141.05128)
		(end 149.304502 -141.339062)
		(width 0.14224)
		(layer "In11.Cu")
		(net "M_M_DQ<62>")
	)
	(segment
		(start 148.266404 -151.247348)
		(end 148.266404 -153.834846)
		(width 0.14224)
		(layer "In11.Cu")
		(net "M_M_DQ<62>")
	)
	(segment
		(start 119.290846 -91.2622)
		(end 119.295672 -91.270836)
		(width 0.0889)
		(layer "In11.Cu")
		(net "M_M_DQ<62>")
	)
	(segment
		(start 149.267164 -138.905996)
		(end 149.267164 -139.460478)
		(width 0.14224)
		(layer "In11.Cu")
		(net "M_M_DQ<62>")
	)
	(segment
		(start 125.144784 -99.187)
		(end 125.139958 -99.195636)
		(width 0.0889)
		(layer "In11.Cu")
		(net "M_M_DQ<62>")
	)
	(segment
		(start 121.341388 -93.642688)
		(end 121.374154 -93.642688)
		(width 0.0889)
		(layer "In11.Cu")
		(net "M_M_DQ<62>")
	)
	(segment
		(start 125.139958 -99.195636)
		(end 125.133608 -99.206304)
		(width 0.0889)
		(layer "In11.Cu")
		(net "M_M_DQ<62>")
	)
	(segment
		(start 149.267164 -136.658604)
		(end 149.121368 -136.8044)
		(width 0.14224)
		(layer "In11.Cu")
		(net "M_M_DQ<62>")
	)
	(segment
		(start 149.121368 -138.7602)
		(end 149.267164 -138.905996)
		(width 0.14224)
		(layer "In11.Cu")
		(net "M_M_DQ<62>")
	)
	(segment
		(start 120.844056 -93.341444)
		(end 120.847358 -93.347286)
		(width 0.0889)
		(layer "In11.Cu")
		(net "M_M_DQ<62>")
	)
	(segment
		(start 134.436104 -110.514384)
		(end 136.252712 -110.514384)
		(width 0.14224)
		(layer "In11.Cu")
		(net "M_M_DQ<62>")
	)
	(segment
		(start 125.144784 -100.1776)
		(end 125.139958 -100.186236)
		(width 0.0889)
		(layer "In11.Cu")
		(net "M_M_DQ<62>")
	)
	(segment
		(start 119.295672 -91.270836)
		(end 119.302022 -91.281504)
		(width 0.0889)
		(layer "In11.Cu")
		(net "M_M_DQ<62>")
	)
	(segment
		(start 149.121368 -136.8044)
		(end 149.121368 -138.7602)
		(width 0.14224)
		(layer "In11.Cu")
		(net "M_M_DQ<62>")
	)
	(segment
		(start 148.266404 -153.834846)
		(end 149.549358 -155.1178)
		(width 0.14224)
		(layer "In11.Cu")
		(net "M_M_DQ<62>")
	)
	(segment
		(start 126.835154 -104.227122)
		(end 127.052832 -104.4448)
		(width 0.14224)
		(layer "In11.Cu")
		(net "M_M_DQ<62>")
	)
	(segment
		(start 126.677674 -102.74681)
		(end 126.677674 -103.76281)
		(width 0.0889)
		(layer "In11.Cu")
		(net "M_M_DQ<62>")
	)
	(segment
		(start 149.362414 -148.551646)
		(end 149.362414 -148.839428)
		(width 0.14224)
		(layer "In11.Cu")
		(net "M_M_DQ<62>")
	)
	(segment
		(start 126.835154 -103.92029)
		(end 126.835154 -104.227122)
		(width 0.0889)
		(layer "In11.Cu")
		(net "M_M_DQ<62>")
	)
	(segment
		(start 149.165564 -131.9784)
		(end 149.121368 -132.022596)
		(width 0.14224)
		(layer "In11.Cu")
		(net "M_M_DQ<62>")
	)
	(segment
		(start 148.826982 -123.088654)
		(end 148.826982 -129.017014)
		(width 0.14224)
		(layer "In11.Cu")
		(net "M_M_DQ<62>")
	)
	(arc
		(start 125.139958 -97.805748)
		(mid 125.193384 -98.011599)
		(end 125.133608 -98.215704)
		(width 0.0889)
		(layer "In11.Cu")
		(net "M_M_DQ<62>")
	)
	(arc
		(start 123.422918 -94.833186)
		(mid 123.631526 -95.045118)
		(end 123.916948 -95.128588)
		(width 0.0889)
		(layer "In11.Cu")
		(net "M_M_DQ<62>")
	)
	(arc
		(start 125.139958 -98.795586)
		(mid 125.193428 -98.990649)
		(end 125.144784 -99.187)
		(width 0.0889)
		(layer "In11.Cu")
		(net "M_M_DQ<62>")
	)
	(arc
		(start 124.775468 -95.624142)
		(mid 124.793375 -95.623733)
		(end 124.811282 -95.624142)
		(width 0.0889)
		(layer "In11.Cu")
		(net "M_M_DQ<62>")
	)
	(arc
		(start 123.952762 -95.128588)
		(mid 124.142691 -95.186458)
		(end 124.281438 -95.328486)
		(width 0.0889)
		(layer "In11.Cu")
		(net "M_M_DQ<62>")
	)
	(arc
		(start 121.374154 -93.642688)
		(mid 121.565796 -93.699854)
		(end 121.705878 -93.842586)
		(width 0.0889)
		(layer "In11.Cu")
		(net "M_M_DQ<62>")
	)
	(arc
		(start 119.625872 -92.601034)
		(mid 119.693315 -92.641516)
		(end 119.76608 -92.671392)
		(width 0.0889)
		(layer "In11.Cu")
		(net "M_M_DQ<62>")
	)
	(arc
		(start 120.500902 -93.147134)
		(mid 120.698063 -93.199093)
		(end 120.844056 -93.341444)
		(width 0.0889)
		(layer "In11.Cu")
		(net "M_M_DQ<62>")
	)
	(arc
		(start 125.139958 -100.776786)
		(mid 125.193457 -100.976684)
		(end 125.139958 -101.176582)
		(width 0.0889)
		(layer "In11.Cu")
		(net "M_M_DQ<62>")
	)
	(arc
		(start 119.295672 -90.870786)
		(mid 119.242202 -91.065849)
		(end 119.290846 -91.2622)
		(width 0.0889)
		(layer "In11.Cu")
		(net "M_M_DQ<62>")
	)
	(arc
		(start 121.705878 -93.842586)
		(mid 121.916591 -94.055665)
		(end 122.204734 -94.137988)
		(width 0.0889)
		(layer "In11.Cu")
		(net "M_M_DQ<62>")
	)
	(arc
		(start 119.295672 -91.861386)
		(mid 119.253313 -92.155051)
		(end 119.424704 -92.397326)
		(width 0.0889)
		(layer "In11.Cu")
		(net "M_M_DQ<62>")
	)
	(arc
		(start 124.811282 -95.624142)
		(mid 125.144251 -95.83169)
		(end 125.139958 -96.22409)
		(width 0.0889)
		(layer "In11.Cu")
		(net "M_M_DQ<62>")
	)
	(arc
		(start 125.144784 -96.823276)
		(mid 125.193537 -97.019738)
		(end 125.139958 -97.214944)
		(width 0.0889)
		(layer "In11.Cu")
		(net "M_M_DQ<62>")
	)
	(arc
		(start 119.424704 -92.397326)
		(mid 119.536367 -92.488237)
		(end 119.625872 -92.601034)
		(width 0.0889)
		(layer "In11.Cu")
		(net "M_M_DQ<62>")
	)
	(arc
		(start 125.139958 -99.786186)
		(mid 125.193428 -99.981249)
		(end 125.144784 -100.1776)
		(width 0.0889)
		(layer "In11.Cu")
		(net "M_M_DQ<62>")
	)
	(arc
		(start 125.998478 -102.262686)
		(mid 126.205482 -102.47355)
		(end 126.488698 -102.557834)
		(width 0.0889)
		(layer "In11.Cu")
		(net "M_M_DQ<62>")
	)
	(arc
		(start 120.847358 -93.347286)
		(mid 121.055966 -93.559218)
		(end 121.341388 -93.642688)
		(width 0.0889)
		(layer "In11.Cu")
		(net "M_M_DQ<62>")
	)
	(arc
		(start 119.76608 -92.671392)
		(mid 119.894323 -92.74102)
		(end 119.989092 -92.851986)
		(width 0.0889)
		(layer "In11.Cu")
		(net "M_M_DQ<62>")
	)
	(arc
		(start 125.139958 -100.186236)
		(mid 125.060736 -100.475354)
		(end 125.133608 -100.766118)
		(width 0.0889)
		(layer "In11.Cu")
		(net "M_M_DQ<62>")
	)
	(arc
		(start 125.139958 -101.176582)
		(mid 125.134704 -101.75809)
		(end 125.630178 -102.062534)
		(width 0.0889)
		(layer "In11.Cu")
		(net "M_M_DQ<62>")
	)
	(arc
		(start 125.662944 -102.062534)
		(mid 125.856794 -102.118884)
		(end 125.998478 -102.262686)
		(width 0.0889)
		(layer "In11.Cu")
		(net "M_M_DQ<62>")
	)
	(arc
		(start 123.094242 -94.633288)
		(mid 123.284171 -94.691158)
		(end 123.422918 -94.833186)
		(width 0.0889)
		(layer "In11.Cu")
		(net "M_M_DQ<62>")
	)
	(arc
		(start 119.989092 -92.851986)
		(mid 120.196096 -93.06285)
		(end 120.479312 -93.147134)
		(width 0.0889)
		(layer "In11.Cu")
		(net "M_M_DQ<62>")
	)
	(arc
		(start 125.133608 -98.215704)
		(mid 125.06081 -98.506467)
		(end 125.139958 -98.795586)
		(width 0.0889)
		(layer "In11.Cu")
		(net "M_M_DQ<62>")
	)
	(arc
		(start 122.564398 -94.33814)
		(mid 122.771402 -94.549004)
		(end 123.054618 -94.633288)
		(width 0.0889)
		(layer "In11.Cu")
		(net "M_M_DQ<62>")
	)
	(arc
		(start 122.228864 -94.137988)
		(mid 122.422714 -94.194338)
		(end 122.564398 -94.33814)
		(width 0.0889)
		(layer "In11.Cu")
		(net "M_M_DQ<62>")
	)
	(arc
		(start 124.281438 -95.328486)
		(mid 124.490037 -95.540516)
		(end 124.775468 -95.624142)
		(width 0.0889)
		(layer "In11.Cu")
		(net "M_M_DQ<62>")
	)
	(arc
		(start 125.139958 -97.214944)
		(mid 125.060827 -97.510346)
		(end 125.139958 -97.805748)
		(width 0.0889)
		(layer "In11.Cu")
		(net "M_M_DQ<62>")
	)
	(arc
		(start 119.302022 -91.281504)
		(mid 119.37482 -91.572267)
		(end 119.295672 -91.861386)
		(width 0.0889)
		(layer "In11.Cu")
		(net "M_M_DQ<62>")
	)
	(arc
		(start 125.133608 -99.206304)
		(mid 125.06081 -99.497067)
		(end 125.139958 -99.786186)
		(width 0.0889)
		(layer "In11.Cu")
		(net "M_M_DQ<62>")
	)
	(arc
		(start 125.139958 -96.22409)
		(mid 125.060736 -96.513208)
		(end 125.133608 -96.803972)
		(width 0.0889)
		(layer "In11.Cu")
		(net "M_M_DQ<62>")
	)
	(segment
		(start 116.495322 -91.565984)
		(end 117.066822 -91.565984)
		(width 0.1651)
		(layer "F.Cu")
		(net "M_M_DQ<61>")
	)
	(segment
		(start 142.749524 -152.273)
		(end 142.749524 -153.542746)
		(width 0.1651)
		(layer "F.Cu")
		(net "M_M_DQ<61>")
	)
	(via
		(at 142.749524 -153.542746)
		(size 0.508)
		(drill 0.254)
		(layers "F.Cu" "B.Cu")
		(net "M_M_DQ<61>")
	)
	(via
		(at 143.523208 -149.533356)
		(size 0.508)
		(drill 0.254)
		(layers "F.Cu" "B.Cu")
		(net "M_M_DQ<61>")
	)
	(via
		(at 117.066822 -91.565984)
		(size 0.508)
		(drill 0.254)
		(layers "F.Cu" "B.Cu")
		(net "M_M_DQ<61>")
	)
	(segment
		(start 143.523208 -149.501352)
		(end 143.523208 -149.533356)
		(width 0.1651)
		(layer "B.Cu")
		(net "M_M_DQ<61>")
	)
	(segment
		(start 143.599408 -147.478496)
		(end 143.599408 -149.425152)
		(width 0.1651)
		(layer "B.Cu")
		(net "M_M_DQ<61>")
	)
	(segment
		(start 143.599408 -149.425152)
		(end 143.523208 -149.501352)
		(width 0.1651)
		(layer "B.Cu")
		(net "M_M_DQ<61>")
	)
	(segment
		(start 143.199612 -151.129746)
		(end 142.910814 -151.418544)
		(width 0.14224)
		(layer "In11.Cu")
		(net "M_M_DQ<61>")
	)
	(segment
		(start 144.015968 -143.6624)
		(end 143.933164 -143.745204)
		(width 0.14224)
		(layer "In11.Cu")
		(net "M_M_DQ<61>")
	)
	(segment
		(start 121.877328 -103.242618)
		(end 121.870978 -103.253286)
		(width 0.0889)
		(layer "In11.Cu")
		(net "M_M_DQ<61>")
	)
	(segment
		(start 122.933968 -111.379)
		(end 126.413768 -114.8588)
		(width 0.14224)
		(layer "In11.Cu")
		(net "M_M_DQ<61>")
	)
	(segment
		(start 144.07007 -123.696222)
		(end 144.07007 -129.162302)
		(width 0.14224)
		(layer "In11.Cu")
		(net "M_M_DQ<61>")
	)
	(segment
		(start 135.232648 -114.8588)
		(end 144.07007 -123.696222)
		(width 0.14224)
		(layer "In11.Cu")
		(net "M_M_DQ<61>")
	)
	(segment
		(start 117.914166 -95.433134)
		(end 117.938296 -95.433134)
		(width 0.0889)
		(layer "In11.Cu")
		(net "M_M_DQ<61>")
	)
	(segment
		(start 121.877328 -102.252018)
		(end 121.870978 -102.262686)
		(width 0.0889)
		(layer "In11.Cu")
		(net "M_M_DQ<61>")
	)
	(segment
		(start 117.048788 -94.937834)
		(end 117.088412 -94.937834)
		(width 0.0889)
		(layer "In11.Cu")
		(net "M_M_DQ<61>")
	)
	(segment
		(start 144.041368 -131.985004)
		(end 144.041368 -133.985)
		(width 0.14224)
		(layer "In11.Cu")
		(net "M_M_DQ<61>")
	)
	(segment
		(start 121.870978 -101.272086)
		(end 121.866152 -101.280722)
		(width 0.0889)
		(layer "In11.Cu")
		(net "M_M_DQ<61>")
	)
	(segment
		(start 116.726462 -93.336618)
		(end 116.720112 -93.347286)
		(width 0.0889)
		(layer "In11.Cu")
		(net "M_M_DQ<61>")
	)
	(segment
		(start 144.07007 -129.162302)
		(end 143.933164 -129.299208)
		(width 0.14224)
		(layer "In11.Cu")
		(net "M_M_DQ<61>")
	)
	(segment
		(start 142.910814 -152.586944)
		(end 142.910814 -152.898856)
		(width 0.14224)
		(layer "In11.Cu")
		(net "M_M_DQ<61>")
	)
	(segment
		(start 121.870978 -100.281486)
		(end 121.866152 -100.290122)
		(width 0.0889)
		(layer "In11.Cu")
		(net "M_M_DQ<61>")
	)
	(segment
		(start 122.933968 -105.392474)
		(end 122.933968 -109.002322)
		(width 0.14224)
		(layer "In11.Cu")
		(net "M_M_DQ<61>")
	)
	(segment
		(start 144.041368 -133.985)
		(end 143.933164 -134.093204)
		(width 0.14224)
		(layer "In11.Cu")
		(net "M_M_DQ<61>")
	)
	(segment
		(start 120.485916 -96.919034)
		(end 120.518682 -96.919034)
		(width 0.0889)
		(layer "In11.Cu")
		(net "M_M_DQ<61>")
	)
	(segment
		(start 123.088908 -109.820202)
		(end 122.933968 -109.975142)
		(width 0.14224)
		(layer "In11.Cu")
		(net "M_M_DQ<61>")
	)
	(segment
		(start 122.933968 -109.002322)
		(end 123.088908 -109.157262)
		(width 0.14224)
		(layer "In11.Cu")
		(net "M_M_DQ<61>")
	)
	(segment
		(start 123.622054 -109.665262)
		(end 123.467114 -109.820202)
		(width 0.14224)
		(layer "In11.Cu")
		(net "M_M_DQ<61>")
	)
	(segment
		(start 143.933164 -131.434078)
		(end 143.933164 -131.8768)
		(width 0.14224)
		(layer "In11.Cu")
		(net "M_M_DQ<61>")
	)
	(segment
		(start 121.877328 -99.280218)
		(end 121.870978 -99.290886)
		(width 0.0889)
		(layer "In11.Cu")
		(net "M_M_DQ<61>")
	)
	(segment
		(start 143.907764 -138.843004)
		(end 143.907764 -139.308078)
		(width 0.14224)
		(layer "In11.Cu")
		(net "M_M_DQ<61>")
	)
	(segment
		(start 143.072612 -150.5204)
		(end 143.199612 -150.6474)
		(width 0.14224)
		(layer "In11.Cu")
		(net "M_M_DQ<61>")
	)
	(segment
		(start 144.041368 -136.658604)
		(end 144.041368 -138.7094)
		(width 0.14224)
		(layer "In11.Cu")
		(net "M_M_DQ<61>")
	)
	(segment
		(start 143.148812 -152.348946)
		(end 142.910814 -152.586944)
		(width 0.14224)
		(layer "In11.Cu")
		(net "M_M_DQ<61>")
	)
	(segment
		(start 143.933164 -134.093204)
		(end 143.933164 -134.617968)
		(width 0.14224)
		(layer "In11.Cu")
		(net "M_M_DQ<61>")
	)
	(segment
		(start 143.933164 -131.8768)
		(end 144.041368 -131.985004)
		(width 0.14224)
		(layer "In11.Cu")
		(net "M_M_DQ<61>")
	)
	(segment
		(start 143.933164 -141.035278)
		(end 143.933164 -141.478)
		(width 0.14224)
		(layer "In11.Cu")
		(net "M_M_DQ<61>")
	)
	(segment
		(start 122.729498 -104.739186)
		(end 122.65152 -104.874314)
		(width 0.0889)
		(layer "In11.Cu")
		(net "M_M_DQ<61>")
	)
	(segment
		(start 143.148812 -151.993854)
		(end 143.148812 -152.348946)
		(width 0.14224)
		(layer "In11.Cu")
		(net "M_M_DQ<61>")
	)
	(segment
		(start 143.933164 -129.299208)
		(end 143.933164 -129.920238)
		(width 0.14224)
		(layer "In11.Cu")
		(net "M_M_DQ<61>")
	)
	(segment
		(start 121.359168 -97.414588)
		(end 121.380758 -97.414588)
		(width 0.0889)
		(layer "In11.Cu")
		(net "M_M_DQ<61>")
	)
	(segment
		(start 143.072612 -149.9616)
		(end 143.072612 -150.5204)
		(width 0.14224)
		(layer "In11.Cu")
		(net "M_M_DQ<61>")
	)
	(segment
		(start 143.907764 -145.607024)
		(end 143.907764 -146.1008)
		(width 0.14224)
		(layer "In11.Cu")
		(net "M_M_DQ<61>")
	)
	(segment
		(start 118.768876 -95.928434)
		(end 118.801642 -95.928434)
		(width 0.0889)
		(layer "In11.Cu")
		(net "M_M_DQ<61>")
	)
	(segment
		(start 121.870978 -102.262686)
		(end 121.866152 -102.271322)
		(width 0.0889)
		(layer "In11.Cu")
		(net "M_M_DQ<61>")
	)
	(segment
		(start 123.622054 -109.312202)
		(end 123.622054 -109.665262)
		(width 0.14224)
		(layer "In11.Cu")
		(net "M_M_DQ<61>")
	)
	(segment
		(start 126.413768 -114.8588)
		(end 135.232648 -114.8588)
		(width 0.14224)
		(layer "In11.Cu")
		(net "M_M_DQ<61>")
	)
	(segment
		(start 117.066822 -91.565984)
		(end 116.737384 -92.326968)
		(width 0.0889)
		(layer "In11.Cu")
		(net "M_M_DQ<61>")
	)
	(segment
		(start 123.467114 -109.820202)
		(end 123.088908 -109.820202)
		(width 0.14224)
		(layer "In11.Cu")
		(net "M_M_DQ<61>")
	)
	(segment
		(start 122.933968 -109.975142)
		(end 122.933968 -111.379)
		(width 0.14224)
		(layer "In11.Cu")
		(net "M_M_DQ<61>")
	)
	(segment
		(start 144.015968 -131.351274)
		(end 143.933164 -131.434078)
		(width 0.14224)
		(layer "In11.Cu")
		(net "M_M_DQ<61>")
	)
	(segment
		(start 122.65152 -104.874314)
		(end 122.65152 -105.110026)
		(width 0.0889)
		(layer "In11.Cu")
		(net "M_M_DQ<61>")
	)
	(segment
		(start 143.021812 -153.542746)
		(end 142.749524 -153.542746)
		(width 0.14224)
		(layer "In11.Cu")
		(net "M_M_DQ<61>")
	)
	(segment
		(start 121.877328 -100.270818)
		(end 121.870978 -100.281486)
		(width 0.0889)
		(layer "In11.Cu")
		(net "M_M_DQ<61>")
	)
	(segment
		(start 123.088908 -109.157262)
		(end 123.467114 -109.157262)
		(width 0.14224)
		(layer "In11.Cu")
		(net "M_M_DQ<61>")
	)
	(segment
		(start 142.910814 -151.418544)
		(end 142.910814 -151.755856)
		(width 0.14224)
		(layer "In11.Cu")
		(net "M_M_DQ<61>")
	)
	(segment
		(start 144.060164 -145.454624)
		(end 143.907764 -145.607024)
		(width 0.14224)
		(layer "In11.Cu")
		(net "M_M_DQ<61>")
	)
	(segment
		(start 143.933164 -134.617968)
		(end 143.996664 -134.681468)
		(width 0.14224)
		(layer "In11.Cu")
		(net "M_M_DQ<61>")
	)
	(segment
		(start 143.174212 -153.390346)
		(end 143.021812 -153.542746)
		(width 0.14224)
		(layer "In11.Cu")
		(net "M_M_DQ<61>")
	)
	(segment
		(start 143.174212 -153.162254)
		(end 143.174212 -153.390346)
		(width 0.14224)
		(layer "In11.Cu")
		(net "M_M_DQ<61>")
	)
	(segment
		(start 143.523208 -149.533356)
		(end 143.500856 -149.533356)
		(width 0.14224)
		(layer "In11.Cu")
		(net "M_M_DQ<61>")
	)
	(segment
		(start 144.015968 -146.209004)
		(end 144.015968 -148.2598)
		(width 0.14224)
		(layer "In11.Cu")
		(net "M_M_DQ<61>")
	)
	(segment
		(start 142.910814 -152.898856)
		(end 143.174212 -153.162254)
		(width 0.14224)
		(layer "In11.Cu")
		(net "M_M_DQ<61>")
	)
	(segment
		(start 142.910814 -151.755856)
		(end 143.148812 -151.993854)
		(width 0.14224)
		(layer "In11.Cu")
		(net "M_M_DQ<61>")
	)
	(segment
		(start 144.015968 -141.560804)
		(end 144.015968 -143.6624)
		(width 0.14224)
		(layer "In11.Cu")
		(net "M_M_DQ<61>")
	)
	(segment
		(start 143.199612 -150.6474)
		(end 143.199612 -151.129746)
		(width 0.14224)
		(layer "In11.Cu")
		(net "M_M_DQ<61>")
	)
	(segment
		(start 143.500856 -149.533356)
		(end 143.072612 -149.9616)
		(width 0.14224)
		(layer "In11.Cu")
		(net "M_M_DQ<61>")
	)
	(segment
		(start 123.467114 -109.157262)
		(end 123.622054 -109.312202)
		(width 0.14224)
		(layer "In11.Cu")
		(net "M_M_DQ<61>")
	)
	(segment
		(start 143.907764 -146.1008)
		(end 144.015968 -146.209004)
		(width 0.14224)
		(layer "In11.Cu")
		(net "M_M_DQ<61>")
	)
	(segment
		(start 121.012712 -97.214436)
		(end 121.016014 -97.220278)
		(width 0.0889)
		(layer "In11.Cu")
		(net "M_M_DQ<61>")
	)
	(segment
		(start 121.870978 -103.253286)
		(end 121.866152 -103.261922)
		(width 0.0889)
		(layer "In11.Cu")
		(net "M_M_DQ<61>")
	)
	(segment
		(start 119.631206 -96.423988)
		(end 119.663972 -96.423988)
		(width 0.0889)
		(layer "In11.Cu")
		(net "M_M_DQ<61>")
	)
	(segment
		(start 144.041368 -140.927074)
		(end 143.933164 -141.035278)
		(width 0.14224)
		(layer "In11.Cu")
		(net "M_M_DQ<61>")
	)
	(segment
		(start 121.877328 -101.261418)
		(end 121.870978 -101.272086)
		(width 0.0889)
		(layer "In11.Cu")
		(net "M_M_DQ<61>")
	)
	(segment
		(start 143.933164 -129.920238)
		(end 144.015968 -130.003042)
		(width 0.14224)
		(layer "In11.Cu")
		(net "M_M_DQ<61>")
	)
	(segment
		(start 144.060164 -144.398238)
		(end 144.060164 -145.454624)
		(width 0.14224)
		(layer "In11.Cu")
		(net "M_M_DQ<61>")
	)
	(segment
		(start 144.041368 -139.441682)
		(end 144.041368 -140.927074)
		(width 0.14224)
		(layer "In11.Cu")
		(net "M_M_DQ<61>")
	)
	(segment
		(start 121.870978 -99.290886)
		(end 121.866152 -99.299522)
		(width 0.0889)
		(layer "In11.Cu")
		(net "M_M_DQ<61>")
	)
	(segment
		(start 143.907764 -136.027668)
		(end 143.907764 -136.525)
		(width 0.14224)
		(layer "In11.Cu")
		(net "M_M_DQ<61>")
	)
	(segment
		(start 143.933164 -144.271238)
		(end 144.060164 -144.398238)
		(width 0.14224)
		(layer "In11.Cu")
		(net "M_M_DQ<61>")
	)
	(segment
		(start 143.996664 -134.681468)
		(end 143.996664 -135.938768)
		(width 0.14224)
		(layer "In11.Cu")
		(net "M_M_DQ<61>")
	)
	(segment
		(start 143.996664 -135.938768)
		(end 143.907764 -136.027668)
		(width 0.14224)
		(layer "In11.Cu")
		(net "M_M_DQ<61>")
	)
	(segment
		(start 143.907764 -148.368004)
		(end 143.907764 -149.1488)
		(width 0.14224)
		(layer "In11.Cu")
		(net "M_M_DQ<61>")
	)
	(segment
		(start 143.907764 -136.525)
		(end 144.041368 -136.658604)
		(width 0.14224)
		(layer "In11.Cu")
		(net "M_M_DQ<61>")
	)
	(segment
		(start 143.907764 -139.308078)
		(end 144.041368 -139.441682)
		(width 0.14224)
		(layer "In11.Cu")
		(net "M_M_DQ<61>")
	)
	(segment
		(start 122.202702 -103.853234)
		(end 122.235468 -103.853234)
		(width 0.0889)
		(layer "In11.Cu")
		(net "M_M_DQ<61>")
	)
	(segment
		(start 144.015968 -148.2598)
		(end 143.907764 -148.368004)
		(width 0.14224)
		(layer "In11.Cu")
		(net "M_M_DQ<61>")
	)
	(segment
		(start 116.737384 -92.326968)
		(end 116.715286 -92.365322)
		(width 0.0889)
		(layer "In11.Cu")
		(net "M_M_DQ<61>")
	)
	(segment
		(start 144.015968 -130.003042)
		(end 144.015968 -131.351274)
		(width 0.14224)
		(layer "In11.Cu")
		(net "M_M_DQ<61>")
	)
	(segment
		(start 143.933164 -141.478)
		(end 144.015968 -141.560804)
		(width 0.14224)
		(layer "In11.Cu")
		(net "M_M_DQ<61>")
	)
	(segment
		(start 122.65152 -105.110026)
		(end 122.933968 -105.392474)
		(width 0.0889)
		(layer "In11.Cu")
		(net "M_M_DQ<61>")
	)
	(segment
		(start 116.720112 -93.347286)
		(end 116.715286 -93.355922)
		(width 0.0889)
		(layer "In11.Cu")
		(net "M_M_DQ<61>")
	)
	(segment
		(start 143.933164 -143.745204)
		(end 143.933164 -144.271238)
		(width 0.14224)
		(layer "In11.Cu")
		(net "M_M_DQ<61>")
	)
	(segment
		(start 144.041368 -138.7094)
		(end 143.907764 -138.843004)
		(width 0.14224)
		(layer "In11.Cu")
		(net "M_M_DQ<61>")
	)
	(segment
		(start 143.907764 -149.1488)
		(end 143.523208 -149.533356)
		(width 0.14224)
		(layer "In11.Cu")
		(net "M_M_DQ<61>")
	)
	(arc
		(start 121.870978 -102.662736)
		(mid 121.9502 -102.951854)
		(end 121.877328 -103.242618)
		(width 0.0889)
		(layer "In11.Cu")
		(net "M_M_DQ<61>")
	)
	(arc
		(start 121.870978 -97.710244)
		(mid 121.950109 -98.005646)
		(end 121.870978 -98.301048)
		(width 0.0889)
		(layer "In11.Cu")
		(net "M_M_DQ<61>")
	)
	(arc
		(start 117.938296 -95.433134)
		(mid 118.226441 -95.515453)
		(end 118.437152 -95.728536)
		(width 0.0889)
		(layer "In11.Cu")
		(net "M_M_DQ<61>")
	)
	(arc
		(start 121.870978 -98.700844)
		(mid 121.880617 -98.718113)
		(end 121.889774 -98.735642)
		(width 0.0889)
		(layer "In11.Cu")
		(net "M_M_DQ<61>")
	)
	(arc
		(start 121.866152 -102.271322)
		(mid 121.817397 -102.467674)
		(end 121.870978 -102.662736)
		(width 0.0889)
		(layer "In11.Cu")
		(net "M_M_DQ<61>")
	)
	(arc
		(start 118.437152 -95.728536)
		(mid 118.577231 -95.871272)
		(end 118.768876 -95.928434)
		(width 0.0889)
		(layer "In11.Cu")
		(net "M_M_DQ<61>")
	)
	(arc
		(start 118.801642 -95.928434)
		(mid 119.087066 -96.011901)
		(end 119.295672 -96.223836)
		(width 0.0889)
		(layer "In11.Cu")
		(net "M_M_DQ<61>")
	)
	(arc
		(start 116.720112 -93.747336)
		(mid 116.799243 -94.042738)
		(end 116.720112 -94.33814)
		(width 0.0889)
		(layer "In11.Cu")
		(net "M_M_DQ<61>")
	)
	(arc
		(start 121.866152 -101.280722)
		(mid 121.817397 -101.477074)
		(end 121.870978 -101.672136)
		(width 0.0889)
		(layer "In11.Cu")
		(net "M_M_DQ<61>")
	)
	(arc
		(start 121.870978 -100.681536)
		(mid 121.9502 -100.970654)
		(end 121.877328 -101.261418)
		(width 0.0889)
		(layer "In11.Cu")
		(net "M_M_DQ<61>")
	)
	(arc
		(start 120.154192 -96.719136)
		(mid 120.294271 -96.861872)
		(end 120.485916 -96.919034)
		(width 0.0889)
		(layer "In11.Cu")
		(net "M_M_DQ<61>")
	)
	(arc
		(start 121.866152 -99.299522)
		(mid 121.817397 -99.495874)
		(end 121.870978 -99.690936)
		(width 0.0889)
		(layer "In11.Cu")
		(net "M_M_DQ<61>")
	)
	(arc
		(start 121.016014 -97.220278)
		(mid 121.16198 -97.362677)
		(end 121.359168 -97.414588)
		(width 0.0889)
		(layer "In11.Cu")
		(net "M_M_DQ<61>")
	)
	(arc
		(start 121.889774 -98.735642)
		(mid 121.950052 -99.009455)
		(end 121.877328 -99.280218)
		(width 0.0889)
		(layer "In11.Cu")
		(net "M_M_DQ<61>")
	)
	(arc
		(start 117.088412 -94.937834)
		(mid 117.371629 -95.022115)
		(end 117.578632 -95.232982)
		(width 0.0889)
		(layer "In11.Cu")
		(net "M_M_DQ<61>")
	)
	(arc
		(start 116.720112 -94.33814)
		(mid 116.715867 -94.730385)
		(end 117.048788 -94.937834)
		(width 0.0889)
		(layer "In11.Cu")
		(net "M_M_DQ<61>")
	)
	(arc
		(start 121.870978 -99.690936)
		(mid 121.9502 -99.980054)
		(end 121.877328 -100.270818)
		(width 0.0889)
		(layer "In11.Cu")
		(net "M_M_DQ<61>")
	)
	(arc
		(start 121.866152 -103.261922)
		(mid 121.869899 -103.651178)
		(end 122.202702 -103.853234)
		(width 0.0889)
		(layer "In11.Cu")
		(net "M_M_DQ<61>")
	)
	(arc
		(start 119.663972 -96.423988)
		(mid 119.947189 -96.508269)
		(end 120.154192 -96.719136)
		(width 0.0889)
		(layer "In11.Cu")
		(net "M_M_DQ<61>")
	)
	(arc
		(start 116.720112 -92.756736)
		(mid 116.799334 -93.045854)
		(end 116.726462 -93.336618)
		(width 0.0889)
		(layer "In11.Cu")
		(net "M_M_DQ<61>")
	)
	(arc
		(start 121.870978 -101.672136)
		(mid 121.9502 -101.961254)
		(end 121.877328 -102.252018)
		(width 0.0889)
		(layer "In11.Cu")
		(net "M_M_DQ<61>")
	)
	(arc
		(start 116.715286 -92.365322)
		(mid 116.666531 -92.561674)
		(end 116.720112 -92.756736)
		(width 0.0889)
		(layer "In11.Cu")
		(net "M_M_DQ<61>")
	)
	(arc
		(start 121.380758 -97.414588)
		(mid 121.66395 -97.499253)
		(end 121.870978 -97.710244)
		(width 0.0889)
		(layer "In11.Cu")
		(net "M_M_DQ<61>")
	)
	(arc
		(start 116.715286 -93.355922)
		(mid 116.666531 -93.552274)
		(end 116.720112 -93.747336)
		(width 0.0889)
		(layer "In11.Cu")
		(net "M_M_DQ<61>")
	)
	(arc
		(start 120.518682 -96.919034)
		(mid 120.804106 -97.002501)
		(end 121.012712 -97.214436)
		(width 0.0889)
		(layer "In11.Cu")
		(net "M_M_DQ<61>")
	)
	(arc
		(start 122.235468 -103.853234)
		(mid 122.733719 -104.156074)
		(end 122.729498 -104.739186)
		(width 0.0889)
		(layer "In11.Cu")
		(net "M_M_DQ<61>")
	)
	(arc
		(start 121.870978 -98.301048)
		(mid 121.817479 -98.500946)
		(end 121.870978 -98.700844)
		(width 0.0889)
		(layer "In11.Cu")
		(net "M_M_DQ<61>")
	)
	(arc
		(start 121.866152 -100.290122)
		(mid 121.817397 -100.486474)
		(end 121.870978 -100.681536)
		(width 0.0889)
		(layer "In11.Cu")
		(net "M_M_DQ<61>")
	)
	(arc
		(start 119.295672 -96.223836)
		(mid 119.437355 -96.36764)
		(end 119.631206 -96.423988)
		(width 0.0889)
		(layer "In11.Cu")
		(net "M_M_DQ<61>")
	)
	(arc
		(start 117.578632 -95.232982)
		(mid 117.720315 -95.376786)
		(end 117.914166 -95.433134)
		(width 0.0889)
		(layer "In11.Cu")
		(net "M_M_DQ<61>")
	)
	(segment
		(start 143.599408 -155.547568)
		(end 143.501364 -155.0162)
		(width 0.1651)
		(layer "F.Cu")
		(net "M_M_DQ<60>")
	)
	(segment
		(start 143.599408 -156.87294)
		(end 143.599408 -155.547568)
		(width 0.1651)
		(layer "F.Cu")
		(net "M_M_DQ<60>")
	)
	(segment
		(start 116.495322 -90.575384)
		(end 117.066822 -90.575384)
		(width 0.1651)
		(layer "F.Cu")
		(net "M_M_DQ<60>")
	)
	(via
		(at 142.749524 -150.814278)
		(size 0.508)
		(drill 0.254)
		(layers "F.Cu" "B.Cu")
		(net "M_M_DQ<60>")
	)
	(via
		(at 143.501364 -155.0162)
		(size 0.508)
		(drill 0.254)
		(layers "F.Cu" "B.Cu")
		(net "M_M_DQ<60>")
	)
	(via
		(at 117.066822 -90.575384)
		(size 0.508)
		(drill 0.254)
		(layers "F.Cu" "B.Cu")
		(net "M_M_DQ<60>")
	)
	(segment
		(start 142.749524 -152.078436)
		(end 142.749524 -150.814278)
		(width 0.1651)
		(layer "B.Cu")
		(net "M_M_DQ<60>")
	)
	(segment
		(start 142.474442 -154.24023)
		(end 143.250412 -155.0162)
		(width 0.14224)
		(layer "In11.Cu")
		(net "M_M_DQ<60>")
	)
	(segment
		(start 143.057626 -134.663942)
		(end 143.057626 -135.99033)
		(width 0.14224)
		(layer "In11.Cu")
		(net "M_M_DQ<60>")
	)
	(segment
		(start 142.316454 -153.78049)
		(end 142.474442 -153.938478)
		(width 0.14224)
		(layer "In11.Cu")
		(net "M_M_DQ<60>")
	)
	(segment
		(start 143.185388 -136.118092)
		(end 143.185388 -139.420854)
		(width 0.14224)
		(layer "In11.Cu")
		(net "M_M_DQ<60>")
	)
	(segment
		(start 121.710704 -103.1494)
		(end 121.705878 -103.158036)
		(width 0.0889)
		(layer "In11.Cu")
		(net "M_M_DQ<60>")
	)
	(segment
		(start 143.185388 -139.420854)
		(end 143.100298 -139.505944)
		(width 0.14224)
		(layer "In11.Cu")
		(net "M_M_DQ<60>")
	)
	(segment
		(start 121.341388 -97.605088)
		(end 121.374154 -97.605088)
		(width 0.0889)
		(layer "In11.Cu")
		(net "M_M_DQ<60>")
	)
	(segment
		(start 143.057626 -135.99033)
		(end 143.185388 -136.118092)
		(width 0.14224)
		(layer "In11.Cu")
		(net "M_M_DQ<60>")
	)
	(segment
		(start 122.196098 -104.043734)
		(end 122.228864 -104.043734)
		(width 0.0889)
		(layer "In11.Cu")
		(net "M_M_DQ<60>")
	)
	(segment
		(start 122.564398 -104.643936)
		(end 122.451368 -104.756966)
		(width 0.0889)
		(layer "In11.Cu")
		(net "M_M_DQ<60>")
	)
	(segment
		(start 142.316454 -151.247348)
		(end 142.316454 -153.78049)
		(width 0.14224)
		(layer "In11.Cu")
		(net "M_M_DQ<60>")
	)
	(segment
		(start 142.434564 -149.760178)
		(end 142.434564 -150.499318)
		(width 0.14224)
		(layer "In11.Cu")
		(net "M_M_DQ<60>")
	)
	(segment
		(start 121.710704 -101.1682)
		(end 121.705878 -101.176836)
		(width 0.0889)
		(layer "In11.Cu")
		(net "M_M_DQ<60>")
	)
	(segment
		(start 122.451368 -104.756966)
		(end 122.451368 -105.065322)
		(width 0.0889)
		(layer "In11.Cu")
		(net "M_M_DQ<60>")
	)
	(segment
		(start 117.049042 -95.128588)
		(end 117.084856 -95.128588)
		(width 0.0889)
		(layer "In11.Cu")
		(net "M_M_DQ<60>")
	)
	(segment
		(start 122.211592 -105.305098)
		(end 122.222768 -105.316274)
		(width 0.14224)
		(layer "In11.Cu")
		(net "M_M_DQ<60>")
	)
	(segment
		(start 120.844056 -97.303844)
		(end 120.847358 -97.309686)
		(width 0.0889)
		(layer "In11.Cu")
		(net "M_M_DQ<60>")
	)
	(segment
		(start 116.555012 -93.252036)
		(end 116.548662 -93.262704)
		(width 0.0889)
		(layer "In11.Cu")
		(net "M_M_DQ<60>")
	)
	(segment
		(start 142.749524 -150.814278)
		(end 142.316454 -151.247348)
		(width 0.14224)
		(layer "In11.Cu")
		(net "M_M_DQ<60>")
	)
	(segment
		(start 121.705878 -103.158036)
		(end 121.699528 -103.168704)
		(width 0.0889)
		(layer "In11.Cu")
		(net "M_M_DQ<60>")
	)
	(segment
		(start 116.559838 -93.2434)
		(end 116.555012 -93.252036)
		(width 0.0889)
		(layer "In11.Cu")
		(net "M_M_DQ<60>")
	)
	(segment
		(start 143.234664 -145.781268)
		(end 143.234664 -148.960078)
		(width 0.14224)
		(layer "In11.Cu")
		(net "M_M_DQ<60>")
	)
	(segment
		(start 116.555012 -92.261436)
		(end 116.548662 -92.272104)
		(width 0.0889)
		(layer "In11.Cu")
		(net "M_M_DQ<60>")
	)
	(segment
		(start 117.912388 -95.623888)
		(end 117.940328 -95.623888)
		(width 0.0889)
		(layer "In11.Cu")
		(net "M_M_DQ<60>")
	)
	(segment
		(start 116.559838 -94.234)
		(end 116.555012 -94.242636)
		(width 0.0889)
		(layer "In11.Cu")
		(net "M_M_DQ<60>")
	)
	(segment
		(start 143.250412 -155.0162)
		(end 143.501364 -155.0162)
		(width 0.14224)
		(layer "In11.Cu")
		(net "M_M_DQ<60>")
	)
	(segment
		(start 122.451368 -105.065322)
		(end 122.211592 -105.305098)
		(width 0.0889)
		(layer "In11.Cu")
		(net "M_M_DQ<60>")
	)
	(segment
		(start 143.234664 -148.960078)
		(end 142.434564 -149.760178)
		(width 0.14224)
		(layer "In11.Cu")
		(net "M_M_DQ<60>")
	)
	(segment
		(start 143.100298 -140.862812)
		(end 143.247364 -141.009878)
		(width 0.14224)
		(layer "In11.Cu")
		(net "M_M_DQ<60>")
	)
	(segment
		(start 143.206724 -131.368038)
		(end 143.206724 -134.514844)
		(width 0.14224)
		(layer "In11.Cu")
		(net "M_M_DQ<60>")
	)
	(segment
		(start 142.981172 -144.366742)
		(end 142.981172 -145.527776)
		(width 0.14224)
		(layer "In11.Cu")
		(net "M_M_DQ<60>")
	)
	(segment
		(start 121.705878 -101.176836)
		(end 121.699528 -101.187504)
		(width 0.0889)
		(layer "In11.Cu")
		(net "M_M_DQ<60>")
	)
	(segment
		(start 142.434564 -150.499318)
		(end 142.749524 -150.814278)
		(width 0.14224)
		(layer "In11.Cu")
		(net "M_M_DQ<60>")
	)
	(segment
		(start 143.206724 -134.514844)
		(end 143.057626 -134.663942)
		(width 0.14224)
		(layer "In11.Cu")
		(net "M_M_DQ<60>")
	)
	(segment
		(start 122.222768 -111.506)
		(end 126.185168 -115.4684)
		(width 0.14224)
		(layer "In11.Cu")
		(net "M_M_DQ<60>")
	)
	(segment
		(start 118.762272 -96.118934)
		(end 118.795038 -96.118934)
		(width 0.0889)
		(layer "In11.Cu")
		(net "M_M_DQ<60>")
	)
	(segment
		(start 122.222768 -105.316274)
		(end 122.222768 -111.506)
		(width 0.14224)
		(layer "In11.Cu")
		(net "M_M_DQ<60>")
	)
	(segment
		(start 143.10741 -131.268724)
		(end 143.206724 -131.368038)
		(width 0.14224)
		(layer "In11.Cu")
		(net "M_M_DQ<60>")
	)
	(segment
		(start 117.066822 -90.575384)
		(end 116.571776 -91.241372)
		(width 0.0889)
		(layer "In11.Cu")
		(net "M_M_DQ<60>")
	)
	(segment
		(start 121.710704 -99.187)
		(end 121.705878 -99.195636)
		(width 0.0889)
		(layer "In11.Cu")
		(net "M_M_DQ<60>")
	)
	(segment
		(start 120.479312 -97.109534)
		(end 120.500902 -97.109534)
		(width 0.0889)
		(layer "In11.Cu")
		(net "M_M_DQ<60>")
	)
	(segment
		(start 119.624602 -96.614488)
		(end 119.657368 -96.614488)
		(width 0.0889)
		(layer "In11.Cu")
		(net "M_M_DQ<60>")
	)
	(segment
		(start 116.571776 -91.241372)
		(end 116.555012 -91.270836)
		(width 0.0889)
		(layer "In11.Cu")
		(net "M_M_DQ<60>")
	)
	(segment
		(start 143.100298 -139.505944)
		(end 143.100298 -140.862812)
		(width 0.14224)
		(layer "In11.Cu")
		(net "M_M_DQ<60>")
	)
	(segment
		(start 121.705878 -102.167436)
		(end 121.699528 -102.178104)
		(width 0.0889)
		(layer "In11.Cu")
		(net "M_M_DQ<60>")
	)
	(segment
		(start 142.474442 -153.938478)
		(end 142.474442 -154.24023)
		(width 0.14224)
		(layer "In11.Cu")
		(net "M_M_DQ<60>")
	)
	(segment
		(start 116.555012 -91.270836)
		(end 116.548662 -91.281504)
		(width 0.0889)
		(layer "In11.Cu")
		(net "M_M_DQ<60>")
	)
	(segment
		(start 121.710704 -100.1776)
		(end 121.705878 -100.186236)
		(width 0.0889)
		(layer "In11.Cu")
		(net "M_M_DQ<60>")
	)
	(segment
		(start 143.206724 -129.808478)
		(end 143.10741 -129.907792)
		(width 0.14224)
		(layer "In11.Cu")
		(net "M_M_DQ<60>")
	)
	(segment
		(start 142.981172 -145.527776)
		(end 143.234664 -145.781268)
		(width 0.14224)
		(layer "In11.Cu")
		(net "M_M_DQ<60>")
	)
	(segment
		(start 126.185168 -115.4684)
		(end 134.962138 -115.4684)
		(width 0.14224)
		(layer "In11.Cu")
		(net "M_M_DQ<60>")
	)
	(segment
		(start 143.206724 -123.712986)
		(end 143.206724 -129.808478)
		(width 0.14224)
		(layer "In11.Cu")
		(net "M_M_DQ<60>")
	)
	(segment
		(start 116.559838 -92.2528)
		(end 116.555012 -92.261436)
		(width 0.0889)
		(layer "In11.Cu")
		(net "M_M_DQ<60>")
	)
	(segment
		(start 121.705878 -100.186236)
		(end 121.699528 -100.196904)
		(width 0.0889)
		(layer "In11.Cu")
		(net "M_M_DQ<60>")
	)
	(segment
		(start 121.710704 -102.1588)
		(end 121.705878 -102.167436)
		(width 0.0889)
		(layer "In11.Cu")
		(net "M_M_DQ<60>")
	)
	(segment
		(start 134.962138 -115.4684)
		(end 143.206724 -123.712986)
		(width 0.14224)
		(layer "In11.Cu")
		(net "M_M_DQ<60>")
	)
	(segment
		(start 121.705878 -99.195636)
		(end 121.699528 -99.206304)
		(width 0.0889)
		(layer "In11.Cu")
		(net "M_M_DQ<60>")
	)
	(segment
		(start 143.247364 -141.009878)
		(end 143.247364 -144.10055)
		(width 0.14224)
		(layer "In11.Cu")
		(net "M_M_DQ<60>")
	)
	(segment
		(start 143.10741 -129.907792)
		(end 143.10741 -131.268724)
		(width 0.14224)
		(layer "In11.Cu")
		(net "M_M_DQ<60>")
	)
	(segment
		(start 143.247364 -144.10055)
		(end 142.981172 -144.366742)
		(width 0.14224)
		(layer "In11.Cu")
		(net "M_M_DQ<60>")
	)
	(arc
		(start 121.699528 -101.187504)
		(mid 121.62673 -101.478267)
		(end 121.705878 -101.767386)
		(width 0.0889)
		(layer "In11.Cu")
		(net "M_M_DQ<60>")
	)
	(arc
		(start 122.228864 -104.043734)
		(mid 122.567033 -104.248532)
		(end 122.564398 -104.643936)
		(width 0.0889)
		(layer "In11.Cu")
		(net "M_M_DQ<60>")
	)
	(arc
		(start 117.084856 -95.128588)
		(mid 117.274785 -95.186458)
		(end 117.413532 -95.328486)
		(width 0.0889)
		(layer "In11.Cu")
		(net "M_M_DQ<60>")
	)
	(arc
		(start 119.989092 -96.814386)
		(mid 120.196096 -97.02525)
		(end 120.479312 -97.109534)
		(width 0.0889)
		(layer "In11.Cu")
		(net "M_M_DQ<60>")
	)
	(arc
		(start 120.847358 -97.309686)
		(mid 121.055966 -97.521618)
		(end 121.341388 -97.605088)
		(width 0.0889)
		(layer "In11.Cu")
		(net "M_M_DQ<60>")
	)
	(arc
		(start 121.705878 -100.776786)
		(mid 121.759348 -100.971849)
		(end 121.710704 -101.1682)
		(width 0.0889)
		(layer "In11.Cu")
		(net "M_M_DQ<60>")
	)
	(arc
		(start 120.500902 -97.109534)
		(mid 120.698063 -97.161493)
		(end 120.844056 -97.303844)
		(width 0.0889)
		(layer "In11.Cu")
		(net "M_M_DQ<60>")
	)
	(arc
		(start 121.705878 -97.805748)
		(mid 121.759377 -98.005646)
		(end 121.705878 -98.205544)
		(width 0.0889)
		(layer "In11.Cu")
		(net "M_M_DQ<60>")
	)
	(arc
		(start 116.555012 -93.842586)
		(mid 116.608482 -94.037649)
		(end 116.559838 -94.234)
		(width 0.0889)
		(layer "In11.Cu")
		(net "M_M_DQ<60>")
	)
	(arc
		(start 121.699528 -103.168704)
		(mid 121.703559 -103.744886)
		(end 122.196098 -104.043734)
		(width 0.0889)
		(layer "In11.Cu")
		(net "M_M_DQ<60>")
	)
	(arc
		(start 121.699528 -102.178104)
		(mid 121.62673 -102.468867)
		(end 121.705878 -102.757986)
		(width 0.0889)
		(layer "In11.Cu")
		(net "M_M_DQ<60>")
	)
	(arc
		(start 116.555012 -92.851986)
		(mid 116.608482 -93.047049)
		(end 116.559838 -93.2434)
		(width 0.0889)
		(layer "In11.Cu")
		(net "M_M_DQ<60>")
	)
	(arc
		(start 121.705878 -102.757986)
		(mid 121.759348 -102.953049)
		(end 121.710704 -103.1494)
		(width 0.0889)
		(layer "In11.Cu")
		(net "M_M_DQ<60>")
	)
	(arc
		(start 116.548662 -92.272104)
		(mid 116.475864 -92.562867)
		(end 116.555012 -92.851986)
		(width 0.0889)
		(layer "In11.Cu")
		(net "M_M_DQ<60>")
	)
	(arc
		(start 116.555012 -94.242636)
		(mid 116.550683 -94.825808)
		(end 117.049042 -95.128588)
		(width 0.0889)
		(layer "In11.Cu")
		(net "M_M_DQ<60>")
	)
	(arc
		(start 118.795038 -96.118934)
		(mid 118.988888 -96.175284)
		(end 119.130572 -96.319086)
		(width 0.0889)
		(layer "In11.Cu")
		(net "M_M_DQ<60>")
	)
	(arc
		(start 119.130572 -96.319086)
		(mid 119.33918 -96.531018)
		(end 119.624602 -96.614488)
		(width 0.0889)
		(layer "In11.Cu")
		(net "M_M_DQ<60>")
	)
	(arc
		(start 121.732294 -98.85045)
		(mid 121.758669 -99.02111)
		(end 121.710704 -99.187)
		(width 0.0889)
		(layer "In11.Cu")
		(net "M_M_DQ<60>")
	)
	(arc
		(start 121.699528 -99.206304)
		(mid 121.62673 -99.497067)
		(end 121.705878 -99.786186)
		(width 0.0889)
		(layer "In11.Cu")
		(net "M_M_DQ<60>")
	)
	(arc
		(start 121.705878 -99.786186)
		(mid 121.759348 -99.981249)
		(end 121.710704 -100.1776)
		(width 0.0889)
		(layer "In11.Cu")
		(net "M_M_DQ<60>")
	)
	(arc
		(start 117.413532 -95.328486)
		(mid 117.624245 -95.541565)
		(end 117.912388 -95.623888)
		(width 0.0889)
		(layer "In11.Cu")
		(net "M_M_DQ<60>")
	)
	(arc
		(start 121.705878 -101.767386)
		(mid 121.759348 -101.962449)
		(end 121.710704 -102.1588)
		(width 0.0889)
		(layer "In11.Cu")
		(net "M_M_DQ<60>")
	)
	(arc
		(start 121.374154 -97.605088)
		(mid 121.565813 -97.662761)
		(end 121.705878 -97.805748)
		(width 0.0889)
		(layer "In11.Cu")
		(net "M_M_DQ<60>")
	)
	(arc
		(start 116.548662 -93.262704)
		(mid 116.475864 -93.553467)
		(end 116.555012 -93.842586)
		(width 0.0889)
		(layer "In11.Cu")
		(net "M_M_DQ<60>")
	)
	(arc
		(start 116.555012 -91.861386)
		(mid 116.608482 -92.056449)
		(end 116.559838 -92.2528)
		(width 0.0889)
		(layer "In11.Cu")
		(net "M_M_DQ<60>")
	)
	(arc
		(start 118.272052 -95.823786)
		(mid 118.479056 -96.03465)
		(end 118.762272 -96.118934)
		(width 0.0889)
		(layer "In11.Cu")
		(net "M_M_DQ<60>")
	)
	(arc
		(start 121.705878 -98.796348)
		(mid 121.720215 -98.822848)
		(end 121.732294 -98.85045)
		(width 0.0889)
		(layer "In11.Cu")
		(net "M_M_DQ<60>")
	)
	(arc
		(start 119.657368 -96.614488)
		(mid 119.84901 -96.671654)
		(end 119.989092 -96.814386)
		(width 0.0889)
		(layer "In11.Cu")
		(net "M_M_DQ<60>")
	)
	(arc
		(start 117.940328 -95.623888)
		(mid 118.13197 -95.681054)
		(end 118.272052 -95.823786)
		(width 0.0889)
		(layer "In11.Cu")
		(net "M_M_DQ<60>")
	)
	(arc
		(start 116.548662 -91.281504)
		(mid 116.475864 -91.572267)
		(end 116.555012 -91.861386)
		(width 0.0889)
		(layer "In11.Cu")
		(net "M_M_DQ<60>")
	)
	(arc
		(start 121.699528 -100.196904)
		(mid 121.62673 -100.487667)
		(end 121.705878 -100.776786)
		(width 0.0889)
		(layer "In11.Cu")
		(net "M_M_DQ<60>")
	)
	(arc
		(start 121.705878 -98.205544)
		(mid 121.626747 -98.500946)
		(end 121.705878 -98.796348)
		(width 0.0889)
		(layer "In11.Cu")
		(net "M_M_DQ<60>")
	)
	(segment
		(start 31.39948 -152.273)
		(end 31.39948 -153.542746)
		(width 0.1651)
		(layer "F.Cu")
		(net "M_M_DQ<5>")
	)
	(segment
		(start 77.192886 -84.812886)
		(end 76.621386 -84.812886)
		(width 0.1651)
		(layer "F.Cu")
		(net "M_M_DQ<5>")
	)
	(via
		(at 32.173164 -149.533356)
		(size 0.508)
		(drill 0.254)
		(layers "F.Cu" "B.Cu")
		(net "M_M_DQ<5>")
	)
	(via
		(at 76.621386 -84.812886)
		(size 0.508)
		(drill 0.254)
		(layers "F.Cu" "B.Cu")
		(net "M_M_DQ<5>")
	)
	(via
		(at 31.39948 -153.542746)
		(size 0.508)
		(drill 0.254)
		(layers "F.Cu" "B.Cu")
		(net "M_M_DQ<5>")
	)
	(segment
		(start 32.249364 -147.478496)
		(end 32.249364 -149.457156)
		(width 0.1651)
		(layer "B.Cu")
		(net "M_M_DQ<5>")
	)
	(segment
		(start 32.249364 -149.457156)
		(end 32.173164 -149.533356)
		(width 0.1651)
		(layer "B.Cu")
		(net "M_M_DQ<5>")
	)
	(segment
		(start 32.55772 -148.466048)
		(end 32.687768 -148.336)
		(width 0.14224)
		(layer "In11.Cu")
		(net "M_M_DQ<5>")
	)
	(segment
		(start 32.521398 -126.88697)
		(end 32.941768 -126.4666)
		(width 0.14224)
		(layer "In11.Cu")
		(net "M_M_DQ<5>")
	)
	(segment
		(start 32.55772 -136.027668)
		(end 32.64662 -135.938768)
		(width 0.14224)
		(layer "In11.Cu")
		(net "M_M_DQ<5>")
	)
	(segment
		(start 38.859968 -107.6706)
		(end 38.859968 -106.684826)
		(width 0.14224)
		(layer "In11.Cu")
		(net "M_M_DQ<5>")
	)
	(segment
		(start 32.687768 -138.811)
		(end 32.687768 -136.6774)
		(width 0.14224)
		(layer "In11.Cu")
		(net "M_M_DQ<5>")
	)
	(segment
		(start 32.941768 -126.4666)
		(end 32.941768 -113.07699)
		(width 0.14224)
		(layer "In11.Cu")
		(net "M_M_DQ<5>")
	)
	(segment
		(start 32.55772 -139.308078)
		(end 32.55772 -138.941048)
		(width 0.14224)
		(layer "In11.Cu")
		(net "M_M_DQ<5>")
	)
	(segment
		(start 31.849568 -150.6474)
		(end 31.849568 -151.129746)
		(width 0.14224)
		(layer "In11.Cu")
		(net "M_M_DQ<5>")
	)
	(segment
		(start 31.722568 -150.5204)
		(end 31.849568 -150.6474)
		(width 0.14224)
		(layer "In11.Cu")
		(net "M_M_DQ<5>")
	)
	(segment
		(start 32.173164 -149.533356)
		(end 32.55772 -149.1488)
		(width 0.14224)
		(layer "In11.Cu")
		(net "M_M_DQ<5>")
	)
	(segment
		(start 70.59676 -84.90839)
		(end 70.629526 -84.90839)
		(width 0.0889)
		(layer "In11.Cu")
		(net "M_M_DQ<5>")
	)
	(segment
		(start 32.64662 -140.971778)
		(end 32.64662 -139.396978)
		(width 0.14224)
		(layer "In11.Cu")
		(net "M_M_DQ<5>")
	)
	(segment
		(start 32.55772 -149.1488)
		(end 32.55772 -148.466048)
		(width 0.14224)
		(layer "In11.Cu")
		(net "M_M_DQ<5>")
	)
	(segment
		(start 32.687768 -146.230848)
		(end 32.55772 -146.1008)
		(width 0.14224)
		(layer "In11.Cu")
		(net "M_M_DQ<5>")
	)
	(segment
		(start 31.56077 -151.418544)
		(end 31.56077 -151.755856)
		(width 0.14224)
		(layer "In11.Cu")
		(net "M_M_DQ<5>")
	)
	(segment
		(start 75.745086 -83.91779)
		(end 75.777852 -83.91779)
		(width 0.0889)
		(layer "In11.Cu")
		(net "M_M_DQ<5>")
	)
	(segment
		(start 66.510916 -86.565232)
		(end 66.835274 -86.88959)
		(width 0.0889)
		(layer "In11.Cu")
		(net "M_M_DQ<5>")
	)
	(segment
		(start 65.650618 -86.052406)
		(end 66.294254 -86.052406)
		(width 0.0889)
		(layer "In11.Cu")
		(net "M_M_DQ<5>")
	)
	(segment
		(start 51.200558 -98.302064)
		(end 51.200558 -97.68459)
		(width 0.14224)
		(layer "In11.Cu")
		(net "M_M_DQ<5>")
	)
	(segment
		(start 32.64662 -131.370578)
		(end 32.64662 -129.983738)
		(width 0.14224)
		(layer "In11.Cu")
		(net "M_M_DQ<5>")
	)
	(segment
		(start 32.687768 -141.633448)
		(end 32.58312 -141.5288)
		(width 0.14224)
		(layer "In11.Cu")
		(net "M_M_DQ<5>")
	)
	(segment
		(start 32.58312 -143.665448)
		(end 32.687768 -143.5608)
		(width 0.14224)
		(layer "In11.Cu")
		(net "M_M_DQ<5>")
	)
	(segment
		(start 32.71012 -145.454624)
		(end 32.71012 -144.398238)
		(width 0.14224)
		(layer "In11.Cu")
		(net "M_M_DQ<5>")
	)
	(segment
		(start 66.835274 -86.88959)
		(end 67.195446 -86.88959)
		(width 0.0889)
		(layer "In11.Cu")
		(net "M_M_DQ<5>")
	)
	(segment
		(start 74.882756 -83.42249)
		(end 74.92238 -83.42249)
		(width 0.0889)
		(layer "In11.Cu")
		(net "M_M_DQ<5>")
	)
	(segment
		(start 32.687768 -132.032248)
		(end 32.58312 -131.9276)
		(width 0.14224)
		(layer "In11.Cu")
		(net "M_M_DQ<5>")
	)
	(segment
		(start 31.824168 -153.162254)
		(end 31.824168 -153.390346)
		(width 0.14224)
		(layer "In11.Cu")
		(net "M_M_DQ<5>")
	)
	(segment
		(start 41.069768 -102.87)
		(end 42.758868 -101.1809)
		(width 0.14224)
		(layer "In11.Cu")
		(net "M_M_DQ<5>")
	)
	(segment
		(start 31.824168 -153.390346)
		(end 31.671768 -153.542746)
		(width 0.14224)
		(layer "In11.Cu")
		(net "M_M_DQ<5>")
	)
	(segment
		(start 76.109576 -84.117688)
		(end 76.12634 -84.147152)
		(width 0.0889)
		(layer "In11.Cu")
		(net "M_M_DQ<5>")
	)
	(segment
		(start 32.64662 -129.983738)
		(end 32.521398 -129.858516)
		(width 0.14224)
		(layer "In11.Cu")
		(net "M_M_DQ<5>")
	)
	(segment
		(start 32.687768 -148.336)
		(end 32.687768 -146.230848)
		(width 0.14224)
		(layer "In11.Cu")
		(net "M_M_DQ<5>")
	)
	(segment
		(start 40.866822 -105.0798)
		(end 41.069768 -104.876854)
		(width 0.14224)
		(layer "In11.Cu")
		(net "M_M_DQ<5>")
	)
	(segment
		(start 31.849568 -151.129746)
		(end 31.56077 -151.418544)
		(width 0.14224)
		(layer "In11.Cu")
		(net "M_M_DQ<5>")
	)
	(segment
		(start 31.56077 -152.586944)
		(end 31.56077 -152.898856)
		(width 0.14224)
		(layer "In11.Cu")
		(net "M_M_DQ<5>")
	)
	(segment
		(start 32.58312 -144.271238)
		(end 32.58312 -143.665448)
		(width 0.14224)
		(layer "In11.Cu")
		(net "M_M_DQ<5>")
	)
	(segment
		(start 68.02501 -86.394036)
		(end 68.057776 -86.394036)
		(width 0.0889)
		(layer "In11.Cu")
		(net "M_M_DQ<5>")
	)
	(segment
		(start 73.169272 -83.42249)
		(end 73.208896 -83.42249)
		(width 0.0889)
		(layer "In11.Cu")
		(net "M_M_DQ<5>")
	)
	(segment
		(start 39.53637 -105.40873)
		(end 39.8653 -105.0798)
		(width 0.14224)
		(layer "In11.Cu")
		(net "M_M_DQ<5>")
	)
	(segment
		(start 66.510916 -86.269068)
		(end 66.510916 -86.565232)
		(width 0.0889)
		(layer "In11.Cu")
		(net "M_M_DQ<5>")
	)
	(segment
		(start 62.398148 -86.487)
		(end 65.216024 -86.487)
		(width 0.14224)
		(layer "In11.Cu")
		(net "M_M_DQ<5>")
	)
	(segment
		(start 66.294254 -86.052406)
		(end 66.510916 -86.269068)
		(width 0.0889)
		(layer "In11.Cu")
		(net "M_M_DQ<5>")
	)
	(segment
		(start 34.884614 -111.645954)
		(end 38.859968 -107.6706)
		(width 0.14224)
		(layer "In11.Cu")
		(net "M_M_DQ<5>")
	)
	(segment
		(start 34.372804 -111.645954)
		(end 34.884614 -111.645954)
		(width 0.14224)
		(layer "In11.Cu")
		(net "M_M_DQ<5>")
	)
	(segment
		(start 68.87972 -85.89899)
		(end 68.912486 -85.89899)
		(width 0.0889)
		(layer "In11.Cu")
		(net "M_M_DQ<5>")
	)
	(segment
		(start 32.55772 -145.607024)
		(end 32.71012 -145.454624)
		(width 0.14224)
		(layer "In11.Cu")
		(net "M_M_DQ<5>")
	)
	(segment
		(start 31.722568 -149.9616)
		(end 31.722568 -150.5204)
		(width 0.14224)
		(layer "In11.Cu")
		(net "M_M_DQ<5>")
	)
	(segment
		(start 32.64662 -139.396978)
		(end 32.55772 -139.308078)
		(width 0.14224)
		(layer "In11.Cu")
		(net "M_M_DQ<5>")
	)
	(segment
		(start 32.150812 -149.533356)
		(end 31.722568 -149.9616)
		(width 0.14224)
		(layer "In11.Cu")
		(net "M_M_DQ<5>")
	)
	(segment
		(start 32.58312 -131.9276)
		(end 32.58312 -131.434078)
		(width 0.14224)
		(layer "In11.Cu")
		(net "M_M_DQ<5>")
	)
	(segment
		(start 32.55772 -146.1008)
		(end 32.55772 -145.607024)
		(width 0.14224)
		(layer "In11.Cu")
		(net "M_M_DQ<5>")
	)
	(segment
		(start 71.45909 -84.412836)
		(end 71.491856 -84.412836)
		(width 0.0889)
		(layer "In11.Cu")
		(net "M_M_DQ<5>")
	)
	(segment
		(start 32.58312 -141.5288)
		(end 32.58312 -141.035278)
		(width 0.14224)
		(layer "In11.Cu")
		(net "M_M_DQ<5>")
	)
	(segment
		(start 32.173164 -149.533356)
		(end 32.150812 -149.533356)
		(width 0.14224)
		(layer "In11.Cu")
		(net "M_M_DQ<5>")
	)
	(segment
		(start 32.687768 -134.0358)
		(end 32.687768 -132.032248)
		(width 0.14224)
		(layer "In11.Cu")
		(net "M_M_DQ<5>")
	)
	(segment
		(start 32.521398 -129.858516)
		(end 32.521398 -126.88697)
		(width 0.14224)
		(layer "In11.Cu")
		(net "M_M_DQ<5>")
	)
	(segment
		(start 32.64662 -134.681468)
		(end 32.58312 -134.617968)
		(width 0.14224)
		(layer "In11.Cu")
		(net "M_M_DQ<5>")
	)
	(segment
		(start 69.74205 -85.403436)
		(end 69.774816 -85.403436)
		(width 0.0889)
		(layer "In11.Cu")
		(net "M_M_DQ<5>")
	)
	(segment
		(start 32.58312 -131.434078)
		(end 32.64662 -131.370578)
		(width 0.14224)
		(layer "In11.Cu")
		(net "M_M_DQ<5>")
	)
	(segment
		(start 76.12634 -84.147152)
		(end 76.621386 -84.812886)
		(width 0.0889)
		(layer "In11.Cu")
		(net "M_M_DQ<5>")
	)
	(segment
		(start 32.941768 -113.07699)
		(end 34.372804 -111.645954)
		(width 0.14224)
		(layer "In11.Cu")
		(net "M_M_DQ<5>")
	)
	(segment
		(start 31.56077 -152.898856)
		(end 31.824168 -153.162254)
		(width 0.14224)
		(layer "In11.Cu")
		(net "M_M_DQ<5>")
	)
	(segment
		(start 31.798768 -151.993854)
		(end 31.798768 -152.348946)
		(width 0.14224)
		(layer "In11.Cu")
		(net "M_M_DQ<5>")
	)
	(segment
		(start 39.8653 -105.0798)
		(end 40.866822 -105.0798)
		(width 0.14224)
		(layer "In11.Cu")
		(net "M_M_DQ<5>")
	)
	(segment
		(start 38.859968 -106.684826)
		(end 39.147242 -105.991152)
		(width 0.14224)
		(layer "In11.Cu")
		(net "M_M_DQ<5>")
	)
	(segment
		(start 32.64662 -135.938768)
		(end 32.64662 -134.681468)
		(width 0.14224)
		(layer "In11.Cu")
		(net "M_M_DQ<5>")
	)
	(segment
		(start 31.671768 -153.542746)
		(end 31.39948 -153.542746)
		(width 0.14224)
		(layer "In11.Cu")
		(net "M_M_DQ<5>")
	)
	(segment
		(start 31.56077 -151.755856)
		(end 31.798768 -151.993854)
		(width 0.14224)
		(layer "In11.Cu")
		(net "M_M_DQ<5>")
	)
	(segment
		(start 42.758868 -101.1809)
		(end 48.321722 -101.1809)
		(width 0.14224)
		(layer "In11.Cu")
		(net "M_M_DQ<5>")
	)
	(segment
		(start 51.200558 -97.68459)
		(end 62.398148 -86.487)
		(width 0.14224)
		(layer "In11.Cu")
		(net "M_M_DQ<5>")
	)
	(segment
		(start 65.216024 -86.487)
		(end 65.650618 -86.052406)
		(width 0.0889)
		(layer "In11.Cu")
		(net "M_M_DQ<5>")
	)
	(segment
		(start 31.798768 -152.348946)
		(end 31.56077 -152.586944)
		(width 0.14224)
		(layer "In11.Cu")
		(net "M_M_DQ<5>")
	)
	(segment
		(start 32.55772 -138.941048)
		(end 32.687768 -138.811)
		(width 0.14224)
		(layer "In11.Cu")
		(net "M_M_DQ<5>")
	)
	(segment
		(start 32.687768 -143.5608)
		(end 32.687768 -141.633448)
		(width 0.14224)
		(layer "In11.Cu")
		(net "M_M_DQ<5>")
	)
	(segment
		(start 32.58312 -141.035278)
		(end 32.64662 -140.971778)
		(width 0.14224)
		(layer "In11.Cu")
		(net "M_M_DQ<5>")
	)
	(segment
		(start 32.58312 -134.140448)
		(end 32.687768 -134.0358)
		(width 0.14224)
		(layer "In11.Cu")
		(net "M_M_DQ<5>")
	)
	(segment
		(start 48.321722 -101.1809)
		(end 51.200558 -98.302064)
		(width 0.14224)
		(layer "In11.Cu")
		(net "M_M_DQ<5>")
	)
	(segment
		(start 32.71012 -144.398238)
		(end 32.58312 -144.271238)
		(width 0.14224)
		(layer "In11.Cu")
		(net "M_M_DQ<5>")
	)
	(segment
		(start 32.58312 -134.617968)
		(end 32.58312 -134.140448)
		(width 0.14224)
		(layer "In11.Cu")
		(net "M_M_DQ<5>")
	)
	(segment
		(start 72.3138 -83.91779)
		(end 72.346566 -83.91779)
		(width 0.0889)
		(layer "In11.Cu")
		(net "M_M_DQ<5>")
	)
	(segment
		(start 32.687768 -136.6774)
		(end 32.55772 -136.547352)
		(width 0.14224)
		(layer "In11.Cu")
		(net "M_M_DQ<5>")
	)
	(segment
		(start 32.55772 -136.547352)
		(end 32.55772 -136.027668)
		(width 0.14224)
		(layer "In11.Cu")
		(net "M_M_DQ<5>")
	)
	(segment
		(start 39.147242 -105.991152)
		(end 39.53637 -105.40873)
		(width 0.14224)
		(layer "In11.Cu")
		(net "M_M_DQ<5>")
	)
	(segment
		(start 41.069768 -104.876854)
		(end 41.069768 -102.87)
		(width 0.14224)
		(layer "In11.Cu")
		(net "M_M_DQ<5>")
	)
	(arc
		(start 71.982076 -84.117688)
		(mid 72.122155 -83.974952)
		(end 72.3138 -83.91779)
		(width 0.0889)
		(layer "In11.Cu")
		(net "M_M_DQ<5>")
	)
	(arc
		(start 68.912486 -85.89899)
		(mid 69.19791 -85.815523)
		(end 69.406516 -85.603588)
		(width 0.0889)
		(layer "In11.Cu")
		(net "M_M_DQ<5>")
	)
	(arc
		(start 72.840596 -83.622388)
		(mid 72.97934 -83.480355)
		(end 73.169272 -83.42249)
		(width 0.0889)
		(layer "In11.Cu")
		(net "M_M_DQ<5>")
	)
	(arc
		(start 67.689476 -86.594188)
		(mid 67.831159 -86.450384)
		(end 68.02501 -86.394036)
		(width 0.0889)
		(layer "In11.Cu")
		(net "M_M_DQ<5>")
	)
	(arc
		(start 71.491856 -84.412836)
		(mid 71.775073 -84.328555)
		(end 71.982076 -84.117688)
		(width 0.0889)
		(layer "In11.Cu")
		(net "M_M_DQ<5>")
	)
	(arc
		(start 73.208896 -83.42249)
		(mid 73.492113 -83.338209)
		(end 73.699116 -83.127342)
		(width 0.0889)
		(layer "In11.Cu")
		(net "M_M_DQ<5>")
	)
	(arc
		(start 69.406516 -85.603588)
		(mid 69.548199 -85.459784)
		(end 69.74205 -85.403436)
		(width 0.0889)
		(layer "In11.Cu")
		(net "M_M_DQ<5>")
	)
	(arc
		(start 71.123556 -84.612988)
		(mid 71.265239 -84.469184)
		(end 71.45909 -84.412836)
		(width 0.0889)
		(layer "In11.Cu")
		(net "M_M_DQ<5>")
	)
	(arc
		(start 75.251056 -83.622388)
		(mid 75.459664 -83.83432)
		(end 75.745086 -83.91779)
		(width 0.0889)
		(layer "In11.Cu")
		(net "M_M_DQ<5>")
	)
	(arc
		(start 74.392536 -83.127342)
		(mid 74.59954 -83.338206)
		(end 74.882756 -83.42249)
		(width 0.0889)
		(layer "In11.Cu")
		(net "M_M_DQ<5>")
	)
	(arc
		(start 68.057776 -86.394036)
		(mid 68.340993 -86.309755)
		(end 68.547996 -86.098888)
		(width 0.0889)
		(layer "In11.Cu")
		(net "M_M_DQ<5>")
	)
	(arc
		(start 70.265036 -85.108288)
		(mid 70.405115 -84.965552)
		(end 70.59676 -84.90839)
		(width 0.0889)
		(layer "In11.Cu")
		(net "M_M_DQ<5>")
	)
	(arc
		(start 73.699116 -83.127342)
		(mid 74.045826 -82.927031)
		(end 74.392536 -83.127342)
		(width 0.0889)
		(layer "In11.Cu")
		(net "M_M_DQ<5>")
	)
	(arc
		(start 68.547996 -86.098888)
		(mid 68.688075 -85.956152)
		(end 68.87972 -85.89899)
		(width 0.0889)
		(layer "In11.Cu")
		(net "M_M_DQ<5>")
	)
	(arc
		(start 72.346566 -83.91779)
		(mid 72.63199 -83.834323)
		(end 72.840596 -83.622388)
		(width 0.0889)
		(layer "In11.Cu")
		(net "M_M_DQ<5>")
	)
	(arc
		(start 70.629526 -84.90839)
		(mid 70.91495 -84.824923)
		(end 71.123556 -84.612988)
		(width 0.0889)
		(layer "In11.Cu")
		(net "M_M_DQ<5>")
	)
	(arc
		(start 67.195446 -86.88959)
		(mid 67.48087 -86.806123)
		(end 67.689476 -86.594188)
		(width 0.0889)
		(layer "In11.Cu")
		(net "M_M_DQ<5>")
	)
	(arc
		(start 74.92238 -83.42249)
		(mid 75.112309 -83.48036)
		(end 75.251056 -83.622388)
		(width 0.0889)
		(layer "In11.Cu")
		(net "M_M_DQ<5>")
	)
	(arc
		(start 75.777852 -83.91779)
		(mid 75.969494 -83.974956)
		(end 76.109576 -84.117688)
		(width 0.0889)
		(layer "In11.Cu")
		(net "M_M_DQ<5>")
	)
	(arc
		(start 69.774816 -85.403436)
		(mid 70.058033 -85.319155)
		(end 70.265036 -85.108288)
		(width 0.0889)
		(layer "In11.Cu")
		(net "M_M_DQ<5>")
	)
	(segment
		(start 119.929402 -91.565984)
		(end 120.500902 -91.565984)
		(width 0.1651)
		(layer "F.Cu")
		(net "M_M_DQ<59>")
	)
	(segment
		(start 150.399496 -152.273)
		(end 150.399496 -153.542746)
		(width 0.1651)
		(layer "F.Cu")
		(net "M_M_DQ<59>")
	)
	(via
		(at 151.24938 -149.533356)
		(size 0.508)
		(drill 0.254)
		(layers "F.Cu" "B.Cu")
		(net "M_M_DQ<59>")
	)
	(via
		(at 150.399496 -153.542746)
		(size 0.508)
		(drill 0.254)
		(layers "F.Cu" "B.Cu")
		(net "M_M_DQ<59>")
	)
	(via
		(at 120.500902 -91.565984)
		(size 0.508)
		(drill 0.254)
		(layers "F.Cu" "B.Cu")
		(net "M_M_DQ<59>")
	)
	(segment
		(start 151.24938 -147.478496)
		(end 151.24938 -149.533356)
		(width 0.1651)
		(layer "B.Cu")
		(net "M_M_DQ<59>")
	)
	(segment
		(start 132.6007 -106.292904)
		(end 135.133334 -108.825538)
		(width 0.14224)
		(layer "In11.Cu")
		(net "M_M_DQ<59>")
	)
	(segment
		(start 126.163578 -99.195636)
		(end 126.169928 -99.206304)
		(width 0.0889)
		(layer "In11.Cu")
		(net "M_M_DQ<59>")
	)
	(segment
		(start 131.625848 -104.454452)
		(end 131.875784 -104.704388)
		(width 0.14224)
		(layer "In11.Cu")
		(net "M_M_DQ<59>")
	)
	(segment
		(start 151.756364 -130.041142)
		(end 151.756364 -131.268978)
		(width 0.14224)
		(layer "In11.Cu")
		(net "M_M_DQ<59>")
	)
	(segment
		(start 131.875784 -104.923336)
		(end 131.662932 -105.136188)
		(width 0.14224)
		(layer "In11.Cu")
		(net "M_M_DQ<59>")
	)
	(segment
		(start 130.9751 -104.667304)
		(end 131.194048 -104.667304)
		(width 0.14224)
		(layer "In11.Cu")
		(net "M_M_DQ<59>")
	)
	(segment
		(start 150.772368 -123.8758)
		(end 150.645368 -124.0028)
		(width 0.14224)
		(layer "In11.Cu")
		(net "M_M_DQ<59>")
	)
	(segment
		(start 123.065032 -93.452188)
		(end 123.097798 -93.452188)
		(width 0.0889)
		(layer "In11.Cu")
		(net "M_M_DQ<59>")
	)
	(segment
		(start 120.500902 -91.565984)
		(end 120.996456 -92.232734)
		(width 0.0889)
		(layer "In11.Cu")
		(net "M_M_DQ<59>")
	)
	(segment
		(start 151.438102 -129.202942)
		(end 151.603964 -129.368804)
		(width 0.14224)
		(layer "In11.Cu")
		(net "M_M_DQ<59>")
	)
	(segment
		(start 151.756364 -140.870178)
		(end 151.616664 -141.009878)
		(width 0.14224)
		(layer "In11.Cu")
		(net "M_M_DQ<59>")
	)
	(segment
		(start 126.158752 -96.2152)
		(end 126.163578 -96.223836)
		(width 0.0889)
		(layer "In11.Cu")
		(net "M_M_DQ<59>")
	)
	(segment
		(start 131.912868 -105.605072)
		(end 132.131816 -105.605072)
		(width 0.14224)
		(layer "In11.Cu")
		(net "M_M_DQ<59>")
	)
	(segment
		(start 150.798784 -150.391368)
		(end 150.843234 -150.435818)
		(width 0.14224)
		(layer "In11.Cu")
		(net "M_M_DQ<59>")
	)
	(segment
		(start 150.560786 -151.387048)
		(end 150.560786 -151.660352)
		(width 0.14224)
		(layer "In11.Cu")
		(net "M_M_DQ<59>")
	)
	(segment
		(start 151.781764 -136.023604)
		(end 151.603964 -136.201404)
		(width 0.14224)
		(layer "In11.Cu")
		(net "M_M_DQ<59>")
	)
	(segment
		(start 124.775214 -94.442534)
		(end 124.811028 -94.442534)
		(width 0.0889)
		(layer "In11.Cu")
		(net "M_M_DQ<59>")
	)
	(segment
		(start 127.873252 -102.845362)
		(end 128.216914 -102.845362)
		(width 0.0889)
		(layer "In11.Cu")
		(net "M_M_DQ<59>")
	)
	(segment
		(start 126.169928 -100.766118)
		(end 126.163578 -100.776786)
		(width 0.0889)
		(layer "In11.Cu")
		(net "M_M_DQ<59>")
	)
	(segment
		(start 150.645368 -124.4092)
		(end 150.848568 -124.6124)
		(width 0.14224)
		(layer "In11.Cu")
		(net "M_M_DQ<59>")
	)
	(segment
		(start 151.24938 -149.533356)
		(end 151.227028 -149.533356)
		(width 0.14224)
		(layer "In11.Cu")
		(net "M_M_DQ<59>")
	)
	(segment
		(start 129.153158 -102.845362)
		(end 130.9751 -104.667304)
		(width 0.14224)
		(layer "In11.Cu")
		(net "M_M_DQ<59>")
	)
	(segment
		(start 151.616664 -141.009878)
		(end 151.616664 -144.182338)
		(width 0.14224)
		(layer "In11.Cu")
		(net "M_M_DQ<59>")
	)
	(segment
		(start 150.849584 -153.364946)
		(end 150.671784 -153.542746)
		(width 0.14224)
		(layer "In11.Cu")
		(net "M_M_DQ<59>")
	)
	(segment
		(start 151.616664 -131.408678)
		(end 151.616664 -134.573264)
		(width 0.14224)
		(layer "In11.Cu")
		(net "M_M_DQ<59>")
	)
	(segment
		(start 122.202702 -92.956634)
		(end 122.235468 -92.956634)
		(width 0.0889)
		(layer "In11.Cu")
		(net "M_M_DQ<59>")
	)
	(segment
		(start 150.849584 -153.04135)
		(end 150.849584 -153.364946)
		(width 0.14224)
		(layer "In11.Cu")
		(net "M_M_DQ<59>")
	)
	(segment
		(start 151.603964 -129.888742)
		(end 151.756364 -130.041142)
		(width 0.14224)
		(layer "In11.Cu")
		(net "M_M_DQ<59>")
	)
	(segment
		(start 131.662932 -105.136188)
		(end 131.662932 -105.355136)
		(width 0.14224)
		(layer "In11.Cu")
		(net "M_M_DQ<59>")
	)
	(segment
		(start 151.756364 -131.268978)
		(end 151.616664 -131.408678)
		(width 0.14224)
		(layer "In11.Cu")
		(net "M_M_DQ<59>")
	)
	(segment
		(start 151.603964 -136.201404)
		(end 151.603964 -139.562078)
		(width 0.14224)
		(layer "In11.Cu")
		(net "M_M_DQ<59>")
	)
	(segment
		(start 121.359168 -92.461588)
		(end 121.380758 -92.461588)
		(width 0.0889)
		(layer "In11.Cu")
		(net "M_M_DQ<59>")
	)
	(segment
		(start 150.817834 -152.2222)
		(end 150.560786 -152.479248)
		(width 0.14224)
		(layer "In11.Cu")
		(net "M_M_DQ<59>")
	)
	(segment
		(start 127.555752 -101.872288)
		(end 127.790702 -102.107238)
		(width 0.0889)
		(layer "In11.Cu")
		(net "M_M_DQ<59>")
	)
	(segment
		(start 150.645368 -124.0028)
		(end 150.645368 -124.4092)
		(width 0.14224)
		(layer "In11.Cu")
		(net "M_M_DQ<59>")
	)
	(segment
		(start 150.843234 -150.435818)
		(end 150.843234 -151.1046)
		(width 0.14224)
		(layer "In11.Cu")
		(net "M_M_DQ<59>")
	)
	(segment
		(start 123.919742 -93.947234)
		(end 123.947682 -93.947234)
		(width 0.0889)
		(layer "In11.Cu")
		(net "M_M_DQ<59>")
	)
	(segment
		(start 151.336502 -123.8758)
		(end 150.772368 -123.8758)
		(width 0.14224)
		(layer "In11.Cu")
		(net "M_M_DQ<59>")
	)
	(segment
		(start 131.875784 -104.704388)
		(end 131.875784 -104.923336)
		(width 0.14224)
		(layer "In11.Cu")
		(net "M_M_DQ<59>")
	)
	(segment
		(start 132.813552 -105.616756)
		(end 132.813552 -105.861104)
		(width 0.14224)
		(layer "In11.Cu")
		(net "M_M_DQ<59>")
	)
	(segment
		(start 151.227028 -149.533356)
		(end 150.798784 -149.9616)
		(width 0.14224)
		(layer "In11.Cu")
		(net "M_M_DQ<59>")
	)
	(segment
		(start 150.671784 -153.542746)
		(end 150.399496 -153.542746)
		(width 0.14224)
		(layer "In11.Cu")
		(net "M_M_DQ<59>")
	)
	(segment
		(start 125.633734 -94.937834)
		(end 125.673358 -94.937834)
		(width 0.0889)
		(layer "In11.Cu")
		(net "M_M_DQ<59>")
	)
	(segment
		(start 151.24938 -149.546564)
		(end 151.24938 -149.533356)
		(width 0.14224)
		(layer "In11.Cu")
		(net "M_M_DQ<59>")
	)
	(segment
		(start 131.4069 -104.454452)
		(end 131.625848 -104.454452)
		(width 0.14224)
		(layer "In11.Cu")
		(net "M_M_DQ<59>")
	)
	(segment
		(start 126.499112 -101.376734)
		(end 126.528068 -101.376734)
		(width 0.0889)
		(layer "In11.Cu")
		(net "M_M_DQ<59>")
	)
	(segment
		(start 151.578564 -145.853404)
		(end 151.578564 -149.21738)
		(width 0.14224)
		(layer "In11.Cu")
		(net "M_M_DQ<59>")
	)
	(segment
		(start 135.133334 -108.825538)
		(end 136.877044 -108.825538)
		(width 0.14224)
		(layer "In11.Cu")
		(net "M_M_DQ<59>")
	)
	(segment
		(start 126.158752 -100.1776)
		(end 126.163578 -100.186236)
		(width 0.0889)
		(layer "In11.Cu")
		(net "M_M_DQ<59>")
	)
	(segment
		(start 151.438102 -123.386596)
		(end 151.438102 -123.7742)
		(width 0.14224)
		(layer "In11.Cu")
		(net "M_M_DQ<59>")
	)
	(segment
		(start 151.438102 -123.7742)
		(end 151.336502 -123.8758)
		(width 0.14224)
		(layer "In11.Cu")
		(net "M_M_DQ<59>")
	)
	(segment
		(start 128.216914 -102.845362)
		(end 129.153158 -102.845362)
		(width 0.14224)
		(layer "In11.Cu")
		(net "M_M_DQ<59>")
	)
	(segment
		(start 151.603964 -129.368804)
		(end 151.603964 -129.888742)
		(width 0.14224)
		(layer "In11.Cu")
		(net "M_M_DQ<59>")
	)
	(segment
		(start 150.817834 -151.9174)
		(end 150.817834 -152.2222)
		(width 0.14224)
		(layer "In11.Cu")
		(net "M_M_DQ<59>")
	)
	(segment
		(start 151.616664 -144.182338)
		(end 151.832564 -144.398238)
		(width 0.14224)
		(layer "In11.Cu")
		(net "M_M_DQ<59>")
	)
	(segment
		(start 131.194048 -104.667304)
		(end 131.4069 -104.454452)
		(width 0.14224)
		(layer "In11.Cu")
		(net "M_M_DQ<59>")
	)
	(segment
		(start 127.790702 -102.107238)
		(end 127.790702 -102.762812)
		(width 0.0889)
		(layer "In11.Cu")
		(net "M_M_DQ<59>")
	)
	(segment
		(start 151.438102 -124.739654)
		(end 151.438102 -129.202942)
		(width 0.14224)
		(layer "In11.Cu")
		(net "M_M_DQ<59>")
	)
	(segment
		(start 132.6007 -106.073956)
		(end 132.6007 -106.292904)
		(width 0.14224)
		(layer "In11.Cu")
		(net "M_M_DQ<59>")
	)
	(segment
		(start 151.832564 -145.599404)
		(end 151.578564 -145.853404)
		(width 0.14224)
		(layer "In11.Cu")
		(net "M_M_DQ<59>")
	)
	(segment
		(start 150.843234 -151.1046)
		(end 150.560786 -151.387048)
		(width 0.14224)
		(layer "In11.Cu")
		(net "M_M_DQ<59>")
	)
	(segment
		(start 150.560786 -152.752552)
		(end 150.849584 -153.04135)
		(width 0.14224)
		(layer "In11.Cu")
		(net "M_M_DQ<59>")
	)
	(segment
		(start 150.848568 -124.6124)
		(end 151.310848 -124.6124)
		(width 0.14224)
		(layer "In11.Cu")
		(net "M_M_DQ<59>")
	)
	(segment
		(start 151.603964 -139.562078)
		(end 151.756364 -139.714478)
		(width 0.14224)
		(layer "In11.Cu")
		(net "M_M_DQ<59>")
	)
	(segment
		(start 151.616664 -134.573264)
		(end 151.781764 -134.738364)
		(width 0.14224)
		(layer "In11.Cu")
		(net "M_M_DQ<59>")
	)
	(segment
		(start 151.578564 -149.21738)
		(end 151.24938 -149.546564)
		(width 0.14224)
		(layer "In11.Cu")
		(net "M_M_DQ<59>")
	)
	(segment
		(start 151.832564 -144.398238)
		(end 151.832564 -145.599404)
		(width 0.14224)
		(layer "In11.Cu")
		(net "M_M_DQ<59>")
	)
	(segment
		(start 150.798784 -149.9616)
		(end 150.798784 -150.391368)
		(width 0.14224)
		(layer "In11.Cu")
		(net "M_M_DQ<59>")
	)
	(segment
		(start 132.813552 -105.861104)
		(end 132.6007 -106.073956)
		(width 0.14224)
		(layer "In11.Cu")
		(net "M_M_DQ<59>")
	)
	(segment
		(start 151.756364 -139.714478)
		(end 151.756364 -140.870178)
		(width 0.14224)
		(layer "In11.Cu")
		(net "M_M_DQ<59>")
	)
	(segment
		(start 150.560786 -151.660352)
		(end 150.817834 -151.9174)
		(width 0.14224)
		(layer "In11.Cu")
		(net "M_M_DQ<59>")
	)
	(segment
		(start 151.310848 -124.6124)
		(end 151.438102 -124.739654)
		(width 0.14224)
		(layer "In11.Cu")
		(net "M_M_DQ<59>")
	)
	(segment
		(start 132.589016 -105.39222)
		(end 132.813552 -105.616756)
		(width 0.14224)
		(layer "In11.Cu")
		(net "M_M_DQ<59>")
	)
	(segment
		(start 132.344668 -105.39222)
		(end 132.589016 -105.39222)
		(width 0.14224)
		(layer "In11.Cu")
		(net "M_M_DQ<59>")
	)
	(segment
		(start 131.662932 -105.355136)
		(end 131.912868 -105.605072)
		(width 0.14224)
		(layer "In11.Cu")
		(net "M_M_DQ<59>")
	)
	(segment
		(start 120.996456 -92.232734)
		(end 121.016014 -92.267278)
		(width 0.0889)
		(layer "In11.Cu")
		(net "M_M_DQ<59>")
	)
	(segment
		(start 150.560786 -152.479248)
		(end 150.560786 -152.752552)
		(width 0.14224)
		(layer "In11.Cu")
		(net "M_M_DQ<59>")
	)
	(segment
		(start 136.877044 -108.825538)
		(end 151.438102 -123.386596)
		(width 0.14224)
		(layer "In11.Cu")
		(net "M_M_DQ<59>")
	)
	(segment
		(start 126.163578 -96.223836)
		(end 126.169928 -96.234504)
		(width 0.0889)
		(layer "In11.Cu")
		(net "M_M_DQ<59>")
	)
	(segment
		(start 127.790702 -102.762812)
		(end 127.873252 -102.845362)
		(width 0.0889)
		(layer "In11.Cu")
		(net "M_M_DQ<59>")
	)
	(segment
		(start 132.131816 -105.605072)
		(end 132.344668 -105.39222)
		(width 0.14224)
		(layer "In11.Cu")
		(net "M_M_DQ<59>")
	)
	(segment
		(start 127.357632 -101.872288)
		(end 127.555752 -101.872288)
		(width 0.0889)
		(layer "In11.Cu")
		(net "M_M_DQ<59>")
	)
	(segment
		(start 151.781764 -134.738364)
		(end 151.781764 -136.023604)
		(width 0.14224)
		(layer "In11.Cu")
		(net "M_M_DQ<59>")
	)
	(arc
		(start 123.588018 -93.747336)
		(mid 123.728097 -93.890072)
		(end 123.919742 -93.947234)
		(width 0.0889)
		(layer "In11.Cu")
		(net "M_M_DQ<59>")
	)
	(arc
		(start 126.163578 -98.205544)
		(mid 126.242709 -98.500946)
		(end 126.163578 -98.796348)
		(width 0.0889)
		(layer "In11.Cu")
		(net "M_M_DQ<59>")
	)
	(arc
		(start 126.163578 -98.796348)
		(mid 126.110104 -98.995992)
		(end 126.163578 -99.195636)
		(width 0.0889)
		(layer "In11.Cu")
		(net "M_M_DQ<59>")
	)
	(arc
		(start 124.811028 -94.442534)
		(mid 125.096452 -94.526001)
		(end 125.305058 -94.737936)
		(width 0.0889)
		(layer "In11.Cu")
		(net "M_M_DQ<59>")
	)
	(arc
		(start 127.022098 -101.672136)
		(mid 127.163781 -101.81594)
		(end 127.357632 -101.872288)
		(width 0.0889)
		(layer "In11.Cu")
		(net "M_M_DQ<59>")
	)
	(arc
		(start 124.446538 -94.242636)
		(mid 124.585282 -94.384669)
		(end 124.775214 -94.442534)
		(width 0.0889)
		(layer "In11.Cu")
		(net "M_M_DQ<59>")
	)
	(arc
		(start 126.163578 -97.214944)
		(mid 126.242709 -97.510346)
		(end 126.163578 -97.805748)
		(width 0.0889)
		(layer "In11.Cu")
		(net "M_M_DQ<59>")
	)
	(arc
		(start 122.235468 -92.956634)
		(mid 122.520892 -93.040101)
		(end 122.729498 -93.252036)
		(width 0.0889)
		(layer "In11.Cu")
		(net "M_M_DQ<59>")
	)
	(arc
		(start 126.163578 -97.805748)
		(mid 126.110079 -98.005646)
		(end 126.163578 -98.205544)
		(width 0.0889)
		(layer "In11.Cu")
		(net "M_M_DQ<59>")
	)
	(arc
		(start 121.870978 -92.756736)
		(mid 122.011057 -92.899472)
		(end 122.202702 -92.956634)
		(width 0.0889)
		(layer "In11.Cu")
		(net "M_M_DQ<59>")
	)
	(arc
		(start 123.947682 -93.947234)
		(mid 124.235827 -94.029553)
		(end 124.446538 -94.242636)
		(width 0.0889)
		(layer "In11.Cu")
		(net "M_M_DQ<59>")
	)
	(arc
		(start 126.163578 -99.786186)
		(mid 126.110108 -99.981249)
		(end 126.158752 -100.1776)
		(width 0.0889)
		(layer "In11.Cu")
		(net "M_M_DQ<59>")
	)
	(arc
		(start 126.163578 -96.815148)
		(mid 126.110079 -97.015046)
		(end 126.163578 -97.214944)
		(width 0.0889)
		(layer "In11.Cu")
		(net "M_M_DQ<59>")
	)
	(arc
		(start 126.163578 -100.776786)
		(mid 126.160995 -101.172033)
		(end 126.499112 -101.376734)
		(width 0.0889)
		(layer "In11.Cu")
		(net "M_M_DQ<59>")
	)
	(arc
		(start 126.163578 -95.823786)
		(mid 126.110108 -96.018849)
		(end 126.158752 -96.2152)
		(width 0.0889)
		(layer "In11.Cu")
		(net "M_M_DQ<59>")
	)
	(arc
		(start 126.528068 -101.376734)
		(mid 126.813492 -101.460201)
		(end 127.022098 -101.672136)
		(width 0.0889)
		(layer "In11.Cu")
		(net "M_M_DQ<59>")
	)
	(arc
		(start 122.729498 -93.252036)
		(mid 122.871181 -93.39584)
		(end 123.065032 -93.452188)
		(width 0.0889)
		(layer "In11.Cu")
		(net "M_M_DQ<59>")
	)
	(arc
		(start 126.169928 -96.234504)
		(mid 126.242784 -96.525665)
		(end 126.163578 -96.815148)
		(width 0.0889)
		(layer "In11.Cu")
		(net "M_M_DQ<59>")
	)
	(arc
		(start 121.016014 -92.267278)
		(mid 121.16198 -92.409677)
		(end 121.359168 -92.461588)
		(width 0.0889)
		(layer "In11.Cu")
		(net "M_M_DQ<59>")
	)
	(arc
		(start 126.169928 -99.206304)
		(mid 126.242726 -99.497067)
		(end 126.163578 -99.786186)
		(width 0.0889)
		(layer "In11.Cu")
		(net "M_M_DQ<59>")
	)
	(arc
		(start 125.305058 -94.737936)
		(mid 125.443802 -94.879969)
		(end 125.633734 -94.937834)
		(width 0.0889)
		(layer "In11.Cu")
		(net "M_M_DQ<59>")
	)
	(arc
		(start 123.097798 -93.452188)
		(mid 123.381015 -93.536469)
		(end 123.588018 -93.747336)
		(width 0.0889)
		(layer "In11.Cu")
		(net "M_M_DQ<59>")
	)
	(arc
		(start 126.163578 -100.186236)
		(mid 126.2428 -100.475354)
		(end 126.169928 -100.766118)
		(width 0.0889)
		(layer "In11.Cu")
		(net "M_M_DQ<59>")
	)
	(arc
		(start 121.380758 -92.461588)
		(mid 121.663975 -92.545869)
		(end 121.870978 -92.756736)
		(width 0.0889)
		(layer "In11.Cu")
		(net "M_M_DQ<59>")
	)
	(arc
		(start 125.673358 -94.937834)
		(mid 126.168835 -95.242277)
		(end 126.163578 -95.823786)
		(width 0.0889)
		(layer "In11.Cu")
		(net "M_M_DQ<59>")
	)
	(segment
		(start 151.24938 -155.881832)
		(end 151.380952 -155.75026)
		(width 0.1651)
		(layer "F.Cu")
		(net "M_M_DQ<58>")
	)
	(segment
		(start 151.24938 -156.87294)
		(end 151.24938 -155.881832)
		(width 0.1651)
		(layer "F.Cu")
		(net "M_M_DQ<58>")
	)
	(segment
		(start 151.380952 -155.52674)
		(end 151.24938 -155.395168)
		(width 0.1651)
		(layer "F.Cu")
		(net "M_M_DQ<58>")
	)
	(segment
		(start 119.929402 -90.575384)
		(end 120.500902 -90.575384)
		(width 0.1651)
		(layer "F.Cu")
		(net "M_M_DQ<58>")
	)
	(segment
		(start 151.24938 -155.395168)
		(end 151.24938 -155.1178)
		(width 0.1651)
		(layer "F.Cu")
		(net "M_M_DQ<58>")
	)
	(segment
		(start 151.380952 -155.75026)
		(end 151.380952 -155.52674)
		(width 0.1651)
		(layer "F.Cu")
		(net "M_M_DQ<58>")
	)
	(via
		(at 120.500902 -90.575384)
		(size 0.508)
		(drill 0.254)
		(layers "F.Cu" "B.Cu")
		(net "M_M_DQ<58>")
	)
	(via
		(at 151.24938 -155.1178)
		(size 0.508)
		(drill 0.254)
		(layers "F.Cu" "B.Cu")
		(net "M_M_DQ<58>")
	)
	(via
		(at 150.399496 -150.814278)
		(size 0.508)
		(drill 0.254)
		(layers "F.Cu" "B.Cu")
		(net "M_M_DQ<58>")
	)
	(segment
		(start 150.399496 -152.078436)
		(end 150.399496 -150.814278)
		(width 0.1651)
		(layer "B.Cu")
		(net "M_M_DQ<58>")
	)
	(segment
		(start 123.058428 -93.642688)
		(end 123.091194 -93.642688)
		(width 0.0889)
		(layer "In11.Cu")
		(net "M_M_DQ<58>")
	)
	(segment
		(start 126.488698 -101.567234)
		(end 126.521464 -101.567234)
		(width 0.0889)
		(layer "In11.Cu")
		(net "M_M_DQ<58>")
	)
	(segment
		(start 150.884636 -145.77314)
		(end 150.884636 -149.006306)
		(width 0.14224)
		(layer "In11.Cu")
		(net "M_M_DQ<58>")
	)
	(segment
		(start 150.99157 -131.460748)
		(end 150.99157 -134.461758)
		(width 0.14224)
		(layer "In11.Cu")
		(net "M_M_DQ<58>")
	)
	(segment
		(start 136.706356 -109.393228)
		(end 150.105364 -122.792236)
		(width 0.14224)
		(layer "In11.Cu")
		(net "M_M_DQ<58>")
	)
	(segment
		(start 125.992128 -96.308418)
		(end 125.998478 -96.319086)
		(width 0.0889)
		(layer "In11.Cu")
		(net "M_M_DQ<58>")
	)
	(segment
		(start 150.105364 -124.732796)
		(end 150.892764 -125.520196)
		(width 0.14224)
		(layer "In11.Cu")
		(net "M_M_DQ<58>")
	)
	(segment
		(start 150.948898 -139.378944)
		(end 150.686262 -139.64158)
		(width 0.14224)
		(layer "In11.Cu")
		(net "M_M_DQ<58>")
	)
	(segment
		(start 150.288752 -150.703534)
		(end 150.399496 -150.814278)
		(width 0.14224)
		(layer "In11.Cu")
		(net "M_M_DQ<58>")
	)
	(segment
		(start 150.65756 -144.404842)
		(end 150.65756 -145.546064)
		(width 0.14224)
		(layer "In11.Cu")
		(net "M_M_DQ<58>")
	)
	(segment
		(start 120.479312 -92.156534)
		(end 120.500902 -92.156534)
		(width 0.0889)
		(layer "In11.Cu")
		(net "M_M_DQ<58>")
	)
	(segment
		(start 127.476758 -102.062788)
		(end 127.600202 -102.186232)
		(width 0.0889)
		(layer "In11.Cu")
		(net "M_M_DQ<58>")
	)
	(segment
		(start 127.789432 -103.3526)
		(end 128.862328 -103.3526)
		(width 0.14224)
		(layer "In11.Cu")
		(net "M_M_DQ<58>")
	)
	(segment
		(start 121.341388 -92.652088)
		(end 121.374154 -92.652088)
		(width 0.0889)
		(layer "In11.Cu")
		(net "M_M_DQ<58>")
	)
	(segment
		(start 150.288752 -149.60219)
		(end 150.288752 -150.703534)
		(width 0.14224)
		(layer "In11.Cu")
		(net "M_M_DQ<58>")
	)
	(segment
		(start 150.658068 -134.79526)
		(end 150.658068 -135.936736)
		(width 0.14224)
		(layer "In11.Cu")
		(net "M_M_DQ<58>")
	)
	(segment
		(start 120.844056 -92.350844)
		(end 120.847358 -92.356686)
		(width 0.0889)
		(layer "In11.Cu")
		(net "M_M_DQ<58>")
	)
	(segment
		(start 150.884636 -149.006306)
		(end 150.288752 -149.60219)
		(width 0.14224)
		(layer "In11.Cu")
		(net "M_M_DQ<58>")
	)
	(segment
		(start 150.686262 -139.64158)
		(end 150.686262 -140.854176)
		(width 0.14224)
		(layer "In11.Cu")
		(net "M_M_DQ<58>")
	)
	(segment
		(start 127.351028 -102.062788)
		(end 127.476758 -102.062788)
		(width 0.0889)
		(layer "In11.Cu")
		(net "M_M_DQ<58>")
	)
	(segment
		(start 150.927054 -144.135348)
		(end 150.65756 -144.404842)
		(width 0.14224)
		(layer "In11.Cu")
		(net "M_M_DQ<58>")
	)
	(segment
		(start 122.196098 -93.147134)
		(end 122.228864 -93.147134)
		(width 0.0889)
		(layer "In11.Cu")
		(net "M_M_DQ<58>")
	)
	(segment
		(start 149.966426 -153.834846)
		(end 151.24938 -155.1178)
		(width 0.14224)
		(layer "In11.Cu")
		(net "M_M_DQ<58>")
	)
	(segment
		(start 128.862328 -103.3526)
		(end 134.902956 -109.393228)
		(width 0.14224)
		(layer "In11.Cu")
		(net "M_M_DQ<58>")
	)
	(segment
		(start 150.696168 -130.030474)
		(end 150.696168 -131.165346)
		(width 0.14224)
		(layer "In11.Cu")
		(net "M_M_DQ<58>")
	)
	(segment
		(start 150.927054 -141.094968)
		(end 150.927054 -144.135348)
		(width 0.14224)
		(layer "In11.Cu")
		(net "M_M_DQ<58>")
	)
	(segment
		(start 134.902956 -109.393228)
		(end 136.706356 -109.393228)
		(width 0.14224)
		(layer "In11.Cu")
		(net "M_M_DQ<58>")
	)
	(segment
		(start 123.921774 -94.137988)
		(end 123.945904 -94.137988)
		(width 0.0889)
		(layer "In11.Cu")
		(net "M_M_DQ<58>")
	)
	(segment
		(start 120.005856 -91.241372)
		(end 119.989092 -91.270836)
		(width 0.0889)
		(layer "In11.Cu")
		(net "M_M_DQ<58>")
	)
	(segment
		(start 150.65756 -145.546064)
		(end 150.884636 -145.77314)
		(width 0.14224)
		(layer "In11.Cu")
		(net "M_M_DQ<58>")
	)
	(segment
		(start 150.948898 -136.227566)
		(end 150.948898 -139.378944)
		(width 0.14224)
		(layer "In11.Cu")
		(net "M_M_DQ<58>")
	)
	(segment
		(start 127.600202 -102.841806)
		(end 127.749554 -102.991158)
		(width 0.0889)
		(layer "In11.Cu")
		(net "M_M_DQ<58>")
	)
	(segment
		(start 127.749554 -102.991158)
		(end 127.749554 -103.312722)
		(width 0.0889)
		(layer "In11.Cu")
		(net "M_M_DQ<58>")
	)
	(segment
		(start 127.749554 -103.312722)
		(end 127.789432 -103.3526)
		(width 0.14224)
		(layer "In11.Cu")
		(net "M_M_DQ<58>")
	)
	(segment
		(start 150.892764 -125.520196)
		(end 150.892764 -129.833878)
		(width 0.14224)
		(layer "In11.Cu")
		(net "M_M_DQ<58>")
	)
	(segment
		(start 150.658068 -135.936736)
		(end 150.948898 -136.227566)
		(width 0.14224)
		(layer "In11.Cu")
		(net "M_M_DQ<58>")
	)
	(segment
		(start 119.989092 -91.270836)
		(end 119.982742 -91.281504)
		(width 0.0889)
		(layer "In11.Cu")
		(net "M_M_DQ<58>")
	)
	(segment
		(start 150.686262 -140.854176)
		(end 150.927054 -141.094968)
		(width 0.14224)
		(layer "In11.Cu")
		(net "M_M_DQ<58>")
	)
	(segment
		(start 150.399496 -150.814278)
		(end 149.966426 -151.247348)
		(width 0.14224)
		(layer "In11.Cu")
		(net "M_M_DQ<58>")
	)
	(segment
		(start 125.633988 -95.128588)
		(end 125.669802 -95.128588)
		(width 0.0889)
		(layer "In11.Cu")
		(net "M_M_DQ<58>")
	)
	(segment
		(start 150.696168 -131.165346)
		(end 150.99157 -131.460748)
		(width 0.14224)
		(layer "In11.Cu")
		(net "M_M_DQ<58>")
	)
	(segment
		(start 150.892764 -129.833878)
		(end 150.696168 -130.030474)
		(width 0.14224)
		(layer "In11.Cu")
		(net "M_M_DQ<58>")
	)
	(segment
		(start 124.771658 -94.633288)
		(end 124.811282 -94.633288)
		(width 0.0889)
		(layer "In11.Cu")
		(net "M_M_DQ<58>")
	)
	(segment
		(start 150.105364 -122.792236)
		(end 150.105364 -124.732796)
		(width 0.14224)
		(layer "In11.Cu")
		(net "M_M_DQ<58>")
	)
	(segment
		(start 120.500902 -90.575384)
		(end 120.005856 -91.241372)
		(width 0.0889)
		(layer "In11.Cu")
		(net "M_M_DQ<58>")
	)
	(segment
		(start 149.966426 -151.247348)
		(end 149.966426 -153.834846)
		(width 0.14224)
		(layer "In11.Cu")
		(net "M_M_DQ<58>")
	)
	(segment
		(start 150.99157 -134.461758)
		(end 150.658068 -134.79526)
		(width 0.14224)
		(layer "In11.Cu")
		(net "M_M_DQ<58>")
	)
	(segment
		(start 127.600202 -102.186232)
		(end 127.600202 -102.841806)
		(width 0.0889)
		(layer "In11.Cu")
		(net "M_M_DQ<58>")
	)
	(segment
		(start 125.998478 -100.681536)
		(end 125.992128 -100.692204)
		(width 0.0889)
		(layer "In11.Cu")
		(net "M_M_DQ<58>")
	)
	(arc
		(start 125.998478 -95.728536)
		(mid 125.919256 -96.017654)
		(end 125.992128 -96.308418)
		(width 0.0889)
		(layer "In11.Cu")
		(net "M_M_DQ<58>")
	)
	(arc
		(start 120.847358 -92.356686)
		(mid 121.055966 -92.568618)
		(end 121.341388 -92.652088)
		(width 0.0889)
		(layer "In11.Cu")
		(net "M_M_DQ<58>")
	)
	(arc
		(start 124.811282 -94.633288)
		(mid 125.001211 -94.691158)
		(end 125.139958 -94.833186)
		(width 0.0889)
		(layer "In11.Cu")
		(net "M_M_DQ<58>")
	)
	(arc
		(start 125.998478 -96.319086)
		(mid 126.052197 -96.519382)
		(end 125.998478 -96.719644)
		(width 0.0889)
		(layer "In11.Cu")
		(net "M_M_DQ<58>")
	)
	(arc
		(start 125.992128 -100.692204)
		(mid 125.996159 -101.268386)
		(end 126.488698 -101.567234)
		(width 0.0889)
		(layer "In11.Cu")
		(net "M_M_DQ<58>")
	)
	(arc
		(start 126.521464 -101.567234)
		(mid 126.715314 -101.623584)
		(end 126.856998 -101.767386)
		(width 0.0889)
		(layer "In11.Cu")
		(net "M_M_DQ<58>")
	)
	(arc
		(start 120.500902 -92.156534)
		(mid 120.698063 -92.208493)
		(end 120.844056 -92.350844)
		(width 0.0889)
		(layer "In11.Cu")
		(net "M_M_DQ<58>")
	)
	(arc
		(start 125.139958 -94.833186)
		(mid 125.348566 -95.045118)
		(end 125.633988 -95.128588)
		(width 0.0889)
		(layer "In11.Cu")
		(net "M_M_DQ<58>")
	)
	(arc
		(start 123.945904 -94.137988)
		(mid 124.139754 -94.194338)
		(end 124.281438 -94.33814)
		(width 0.0889)
		(layer "In11.Cu")
		(net "M_M_DQ<58>")
	)
	(arc
		(start 121.374154 -92.652088)
		(mid 121.565796 -92.709254)
		(end 121.705878 -92.851986)
		(width 0.0889)
		(layer "In11.Cu")
		(net "M_M_DQ<58>")
	)
	(arc
		(start 125.998478 -98.301048)
		(mid 126.051977 -98.500946)
		(end 125.998478 -98.700844)
		(width 0.0889)
		(layer "In11.Cu")
		(net "M_M_DQ<58>")
	)
	(arc
		(start 125.998478 -100.28174)
		(mid 126.051977 -100.481638)
		(end 125.998478 -100.681536)
		(width 0.0889)
		(layer "In11.Cu")
		(net "M_M_DQ<58>")
	)
	(arc
		(start 121.705878 -92.851986)
		(mid 121.912882 -93.06285)
		(end 122.196098 -93.147134)
		(width 0.0889)
		(layer "In11.Cu")
		(net "M_M_DQ<58>")
	)
	(arc
		(start 125.998478 -97.310448)
		(mid 126.051977 -97.510346)
		(end 125.998478 -97.710244)
		(width 0.0889)
		(layer "In11.Cu")
		(net "M_M_DQ<58>")
	)
	(arc
		(start 125.998478 -96.719644)
		(mid 125.919347 -97.015046)
		(end 125.998478 -97.310448)
		(width 0.0889)
		(layer "In11.Cu")
		(net "M_M_DQ<58>")
	)
	(arc
		(start 126.003304 -99.299522)
		(mid 126.052059 -99.495874)
		(end 125.998478 -99.690936)
		(width 0.0889)
		(layer "In11.Cu")
		(net "M_M_DQ<58>")
	)
	(arc
		(start 125.669802 -95.128588)
		(mid 126.002771 -95.336136)
		(end 125.998478 -95.728536)
		(width 0.0889)
		(layer "In11.Cu")
		(net "M_M_DQ<58>")
	)
	(arc
		(start 123.091194 -93.642688)
		(mid 123.282836 -93.699854)
		(end 123.422918 -93.842586)
		(width 0.0889)
		(layer "In11.Cu")
		(net "M_M_DQ<58>")
	)
	(arc
		(start 122.564398 -93.347286)
		(mid 122.773006 -93.559218)
		(end 123.058428 -93.642688)
		(width 0.0889)
		(layer "In11.Cu")
		(net "M_M_DQ<58>")
	)
	(arc
		(start 125.998478 -98.700844)
		(mid 125.919527 -99.000827)
		(end 126.003304 -99.299522)
		(width 0.0889)
		(layer "In11.Cu")
		(net "M_M_DQ<58>")
	)
	(arc
		(start 125.998478 -97.710244)
		(mid 125.919347 -98.005646)
		(end 125.998478 -98.301048)
		(width 0.0889)
		(layer "In11.Cu")
		(net "M_M_DQ<58>")
	)
	(arc
		(start 124.281438 -94.33814)
		(mid 124.488442 -94.549004)
		(end 124.771658 -94.633288)
		(width 0.0889)
		(layer "In11.Cu")
		(net "M_M_DQ<58>")
	)
	(arc
		(start 123.422918 -93.842586)
		(mid 123.633631 -94.055665)
		(end 123.921774 -94.137988)
		(width 0.0889)
		(layer "In11.Cu")
		(net "M_M_DQ<58>")
	)
	(arc
		(start 126.856998 -101.767386)
		(mid 127.065606 -101.979318)
		(end 127.351028 -102.062788)
		(width 0.0889)
		(layer "In11.Cu")
		(net "M_M_DQ<58>")
	)
	(arc
		(start 119.982742 -91.281504)
		(mid 119.986773 -91.857686)
		(end 120.479312 -92.156534)
		(width 0.0889)
		(layer "In11.Cu")
		(net "M_M_DQ<58>")
	)
	(arc
		(start 125.998478 -99.690936)
		(mid 125.919347 -99.986338)
		(end 125.998478 -100.28174)
		(width 0.0889)
		(layer "In11.Cu")
		(net "M_M_DQ<58>")
	)
	(arc
		(start 122.228864 -93.147134)
		(mid 122.422714 -93.203484)
		(end 122.564398 -93.347286)
		(width 0.0889)
		(layer "In11.Cu")
		(net "M_M_DQ<58>")
	)
	(segment
		(start 117.353842 -92.061538)
		(end 117.925342 -92.061538)
		(width 0.1651)
		(layer "F.Cu")
		(net "M_M_DQ<57>")
	)
	(segment
		(start 144.449546 -152.273)
		(end 144.449546 -153.542746)
		(width 0.1651)
		(layer "F.Cu")
		(net "M_M_DQ<57>")
	)
	(via
		(at 117.925342 -92.061538)
		(size 0.508)
		(drill 0.254)
		(layers "F.Cu" "B.Cu")
		(net "M_M_DQ<57>")
	)
	(via
		(at 145.12163 -149.533356)
		(size 0.508)
		(drill 0.254)
		(layers "F.Cu" "B.Cu")
		(net "M_M_DQ<57>")
	)
	(via
		(at 144.449546 -153.542746)
		(size 0.508)
		(drill 0.254)
		(layers "F.Cu" "B.Cu")
		(net "M_M_DQ<57>")
	)
	(segment
		(start 145.12163 -149.030182)
		(end 145.12163 -149.533356)
		(width 0.1651)
		(layer "B.Cu")
		(net "M_M_DQ<57>")
	)
	(segment
		(start 145.29943 -148.852382)
		(end 145.12163 -149.030182)
		(width 0.1651)
		(layer "B.Cu")
		(net "M_M_DQ<57>")
	)
	(segment
		(start 145.29943 -147.478496)
		(end 145.29943 -148.852382)
		(width 0.1651)
		(layer "B.Cu")
		(net "M_M_DQ<57>")
	)
	(segment
		(start 121.359168 -96.423988)
		(end 121.380758 -96.423988)
		(width 0.0889)
		(layer "In11.Cu")
		(net "M_M_DQ<57>")
	)
	(segment
		(start 145.609564 -138.868404)
		(end 145.609564 -141.369796)
		(width 0.14224)
		(layer "In11.Cu")
		(net "M_M_DQ<57>")
	)
	(segment
		(start 144.610836 -152.538176)
		(end 144.610836 -152.846024)
		(width 0.14224)
		(layer "In11.Cu")
		(net "M_M_DQ<57>")
	)
	(segment
		(start 144.610836 -152.846024)
		(end 144.850612 -153.0858)
		(width 0.14224)
		(layer "In11.Cu")
		(net "M_M_DQ<57>")
	)
	(segment
		(start 144.850612 -153.3906)
		(end 144.698466 -153.542746)
		(width 0.14224)
		(layer "In11.Cu")
		(net "M_M_DQ<57>")
	)
	(segment
		(start 144.610836 -151.677624)
		(end 144.825212 -151.892)
		(width 0.14224)
		(layer "In11.Cu")
		(net "M_M_DQ<57>")
	)
	(segment
		(start 119.631206 -95.433134)
		(end 119.655336 -95.433134)
		(width 0.0889)
		(layer "In11.Cu")
		(net "M_M_DQ<57>")
	)
	(segment
		(start 131.437634 -111.485426)
		(end 131.592574 -111.330486)
		(width 0.14224)
		(layer "In11.Cu")
		(net "M_M_DQ<57>")
	)
	(segment
		(start 123.904756 -105.028746)
		(end 124.116592 -105.240582)
		(width 0.0889)
		(layer "In11.Cu")
		(net "M_M_DQ<57>")
	)
	(segment
		(start 117.595396 -92.823284)
		(end 117.578632 -92.851986)
		(width 0.0889)
		(layer "In11.Cu")
		(net "M_M_DQ<57>")
	)
	(segment
		(start 145.609564 -136.5758)
		(end 145.743168 -136.709404)
		(width 0.14224)
		(layer "In11.Cu")
		(net "M_M_DQ<57>")
	)
	(segment
		(start 145.609564 -146.177)
		(end 145.717768 -146.285204)
		(width 0.14224)
		(layer "In11.Cu")
		(net "M_M_DQ<57>")
	)
	(segment
		(start 117.573806 -93.2434)
		(end 117.578632 -93.252036)
		(width 0.0889)
		(layer "In11.Cu")
		(net "M_M_DQ<57>")
	)
	(segment
		(start 145.717768 -148.336)
		(end 145.609564 -148.444204)
		(width 0.14224)
		(layer "In11.Cu")
		(net "M_M_DQ<57>")
	)
	(segment
		(start 144.901412 -151.026368)
		(end 144.610836 -151.316944)
		(width 0.14224)
		(layer "In11.Cu")
		(net "M_M_DQ<57>")
	)
	(segment
		(start 122.729498 -102.167436)
		(end 122.735848 -102.178104)
		(width 0.0889)
		(layer "In11.Cu")
		(net "M_M_DQ<57>")
	)
	(segment
		(start 117.578632 -93.252036)
		(end 117.584982 -93.262704)
		(width 0.0889)
		(layer "In11.Cu")
		(net "M_M_DQ<57>")
	)
	(segment
		(start 145.717768 -146.285204)
		(end 145.717768 -148.336)
		(width 0.14224)
		(layer "In11.Cu")
		(net "M_M_DQ<57>")
	)
	(segment
		(start 130.929634 -112.89157)
		(end 131.282694 -112.89157)
		(width 0.14224)
		(layer "In11.Cu")
		(net "M_M_DQ<57>")
	)
	(segment
		(start 144.698466 -153.542746)
		(end 144.449546 -153.542746)
		(width 0.14224)
		(layer "In11.Cu")
		(net "M_M_DQ<57>")
	)
	(segment
		(start 130.774694 -112.73663)
		(end 130.929634 -112.89157)
		(width 0.14224)
		(layer "In11.Cu")
		(net "M_M_DQ<57>")
	)
	(segment
		(start 145.743168 -138.7348)
		(end 145.609564 -138.868404)
		(width 0.14224)
		(layer "In11.Cu")
		(net "M_M_DQ<57>")
	)
	(segment
		(start 145.609564 -129.368804)
		(end 145.609564 -131.8514)
		(width 0.14224)
		(layer "In11.Cu")
		(net "M_M_DQ<57>")
	)
	(segment
		(start 145.609564 -127.120396)
		(end 145.743168 -127.254)
		(width 0.14224)
		(layer "In11.Cu")
		(net "M_M_DQ<57>")
	)
	(segment
		(start 128.855978 -108.20781)
		(end 130.774694 -110.126526)
		(width 0.14224)
		(layer "In11.Cu")
		(net "M_M_DQ<57>")
	)
	(segment
		(start 122.724672 -101.1682)
		(end 122.729498 -101.176836)
		(width 0.0889)
		(layer "In11.Cu")
		(net "M_M_DQ<57>")
	)
	(segment
		(start 131.945634 -111.330486)
		(end 132.100574 -111.485426)
		(width 0.14224)
		(layer "In11.Cu")
		(net "M_M_DQ<57>")
	)
	(segment
		(start 145.12163 -149.444456)
		(end 145.12163 -149.533356)
		(width 0.14224)
		(layer "In11.Cu")
		(net "M_M_DQ<57>")
	)
	(segment
		(start 145.609564 -148.444204)
		(end 145.609564 -148.956522)
		(width 0.14224)
		(layer "In11.Cu")
		(net "M_M_DQ<57>")
	)
	(segment
		(start 117.925342 -92.061538)
		(end 117.595396 -92.823284)
		(width 0.0889)
		(layer "In11.Cu")
		(net "M_M_DQ<57>")
	)
	(segment
		(start 122.729498 -99.195636)
		(end 122.735848 -99.206304)
		(width 0.0889)
		(layer "In11.Cu")
		(net "M_M_DQ<57>")
	)
	(segment
		(start 145.609564 -143.770604)
		(end 145.609564 -146.177)
		(width 0.14224)
		(layer "In11.Cu")
		(net "M_M_DQ<57>")
	)
	(segment
		(start 144.825212 -151.892)
		(end 144.825212 -152.3238)
		(width 0.14224)
		(layer "In11.Cu")
		(net "M_M_DQ<57>")
	)
	(segment
		(start 123.904756 -103.947468)
		(end 123.904756 -105.028746)
		(width 0.0889)
		(layer "In11.Cu")
		(net "M_M_DQ<57>")
	)
	(segment
		(start 132.100574 -111.485426)
		(end 132.100574 -113.387124)
		(width 0.14224)
		(layer "In11.Cu")
		(net "M_M_DQ<57>")
	)
	(segment
		(start 132.46354 -113.75009)
		(end 136.095994 -113.75009)
		(width 0.14224)
		(layer "In11.Cu")
		(net "M_M_DQ<57>")
	)
	(segment
		(start 130.774694 -110.126526)
		(end 130.774694 -112.73663)
		(width 0.14224)
		(layer "In11.Cu")
		(net "M_M_DQ<57>")
	)
	(segment
		(start 145.12163 -149.533356)
		(end 145.099278 -149.533356)
		(width 0.14224)
		(layer "In11.Cu")
		(net "M_M_DQ<57>")
	)
	(segment
		(start 144.850612 -153.0858)
		(end 144.850612 -153.3906)
		(width 0.14224)
		(layer "In11.Cu")
		(net "M_M_DQ<57>")
	)
	(segment
		(start 145.717768 -143.6624)
		(end 145.609564 -143.770604)
		(width 0.14224)
		(layer "In11.Cu")
		(net "M_M_DQ<57>")
	)
	(segment
		(start 145.609564 -131.8514)
		(end 145.717768 -131.959604)
		(width 0.14224)
		(layer "In11.Cu")
		(net "M_M_DQ<57>")
	)
	(segment
		(start 122.724672 -99.187)
		(end 122.729498 -99.195636)
		(width 0.0889)
		(layer "In11.Cu")
		(net "M_M_DQ<57>")
	)
	(segment
		(start 145.099278 -149.533356)
		(end 144.671034 -149.9616)
		(width 0.14224)
		(layer "In11.Cu")
		(net "M_M_DQ<57>")
	)
	(segment
		(start 117.907308 -94.442534)
		(end 117.943122 -94.442534)
		(width 0.0889)
		(layer "In11.Cu")
		(net "M_M_DQ<57>")
	)
	(segment
		(start 118.765828 -94.937834)
		(end 118.805452 -94.937834)
		(width 0.0889)
		(layer "In11.Cu")
		(net "M_M_DQ<57>")
	)
	(segment
		(start 145.743168 -127.254)
		(end 145.743168 -129.2352)
		(width 0.14224)
		(layer "In11.Cu")
		(net "M_M_DQ<57>")
	)
	(segment
		(start 145.743168 -136.709404)
		(end 145.743168 -138.7348)
		(width 0.14224)
		(layer "In11.Cu")
		(net "M_M_DQ<57>")
	)
	(segment
		(start 144.671034 -149.9616)
		(end 144.671034 -150.391368)
		(width 0.14224)
		(layer "In11.Cu")
		(net "M_M_DQ<57>")
	)
	(segment
		(start 121.012712 -96.223836)
		(end 121.016014 -96.229678)
		(width 0.0889)
		(layer "In11.Cu")
		(net "M_M_DQ<57>")
	)
	(segment
		(start 144.901412 -150.621746)
		(end 144.901412 -151.026368)
		(width 0.14224)
		(layer "In11.Cu")
		(net "M_M_DQ<57>")
	)
	(segment
		(start 127.08382 -108.20781)
		(end 128.855978 -108.20781)
		(width 0.14224)
		(layer "In11.Cu")
		(net "M_M_DQ<57>")
	)
	(segment
		(start 145.743168 -129.2352)
		(end 145.609564 -129.368804)
		(width 0.14224)
		(layer "In11.Cu")
		(net "M_M_DQ<57>")
	)
	(segment
		(start 122.202702 -96.919034)
		(end 122.235468 -96.919034)
		(width 0.0889)
		(layer "In11.Cu")
		(net "M_M_DQ<57>")
	)
	(segment
		(start 122.724672 -102.1588)
		(end 122.729498 -102.167436)
		(width 0.0889)
		(layer "In11.Cu")
		(net "M_M_DQ<57>")
	)
	(segment
		(start 145.717768 -134.1374)
		(end 145.609564 -134.245604)
		(width 0.14224)
		(layer "In11.Cu")
		(net "M_M_DQ<57>")
	)
	(segment
		(start 145.609564 -141.369796)
		(end 145.717768 -141.478)
		(width 0.14224)
		(layer "In11.Cu")
		(net "M_M_DQ<57>")
	)
	(segment
		(start 145.717768 -141.478)
		(end 145.717768 -143.6624)
		(width 0.14224)
		(layer "In11.Cu")
		(net "M_M_DQ<57>")
	)
	(segment
		(start 123.065032 -103.358188)
		(end 123.097798 -103.358188)
		(width 0.0889)
		(layer "In11.Cu")
		(net "M_M_DQ<57>")
	)
	(segment
		(start 122.729498 -100.186236)
		(end 122.735848 -100.196904)
		(width 0.0889)
		(layer "In11.Cu")
		(net "M_M_DQ<57>")
	)
	(segment
		(start 144.671034 -150.391368)
		(end 144.901412 -150.621746)
		(width 0.14224)
		(layer "In11.Cu")
		(net "M_M_DQ<57>")
	)
	(segment
		(start 124.116592 -105.240582)
		(end 127.08382 -108.20781)
		(width 0.14224)
		(layer "In11.Cu")
		(net "M_M_DQ<57>")
	)
	(segment
		(start 144.610836 -151.316944)
		(end 144.610836 -151.677624)
		(width 0.14224)
		(layer "In11.Cu")
		(net "M_M_DQ<57>")
	)
	(segment
		(start 131.437634 -112.73663)
		(end 131.437634 -111.485426)
		(width 0.14224)
		(layer "In11.Cu")
		(net "M_M_DQ<57>")
	)
	(segment
		(start 122.724672 -100.1776)
		(end 122.729498 -100.186236)
		(width 0.0889)
		(layer "In11.Cu")
		(net "M_M_DQ<57>")
	)
	(segment
		(start 144.825212 -152.3238)
		(end 144.610836 -152.538176)
		(width 0.14224)
		(layer "In11.Cu")
		(net "M_M_DQ<57>")
	)
	(segment
		(start 145.609564 -134.245604)
		(end 145.609564 -136.5758)
		(width 0.14224)
		(layer "In11.Cu")
		(net "M_M_DQ<57>")
	)
	(segment
		(start 120.485916 -95.928434)
		(end 120.518682 -95.928434)
		(width 0.0889)
		(layer "In11.Cu")
		(net "M_M_DQ<57>")
	)
	(segment
		(start 145.609564 -148.956522)
		(end 145.12163 -149.444456)
		(width 0.14224)
		(layer "In11.Cu")
		(net "M_M_DQ<57>")
	)
	(segment
		(start 145.609564 -123.26366)
		(end 145.609564 -127.120396)
		(width 0.14224)
		(layer "In11.Cu")
		(net "M_M_DQ<57>")
	)
	(segment
		(start 145.717768 -131.959604)
		(end 145.717768 -134.1374)
		(width 0.14224)
		(layer "In11.Cu")
		(net "M_M_DQ<57>")
	)
	(segment
		(start 132.100574 -113.387124)
		(end 132.46354 -113.75009)
		(width 0.14224)
		(layer "In11.Cu")
		(net "M_M_DQ<57>")
	)
	(segment
		(start 131.592574 -111.330486)
		(end 131.945634 -111.330486)
		(width 0.14224)
		(layer "In11.Cu")
		(net "M_M_DQ<57>")
	)
	(segment
		(start 136.095994 -113.75009)
		(end 145.609564 -123.26366)
		(width 0.14224)
		(layer "In11.Cu")
		(net "M_M_DQ<57>")
	)
	(segment
		(start 131.282694 -112.89157)
		(end 131.437634 -112.73663)
		(width 0.14224)
		(layer "In11.Cu")
		(net "M_M_DQ<57>")
	)
	(segment
		(start 122.729498 -101.176836)
		(end 122.735848 -101.187504)
		(width 0.0889)
		(layer "In11.Cu")
		(net "M_M_DQ<57>")
	)
	(segment
		(start 123.441206 -103.483918)
		(end 123.904756 -103.947468)
		(width 0.0889)
		(layer "In11.Cu")
		(net "M_M_DQ<57>")
	)
	(arc
		(start 122.735848 -99.206304)
		(mid 122.808646 -99.497067)
		(end 122.729498 -99.786186)
		(width 0.0889)
		(layer "In11.Cu")
		(net "M_M_DQ<57>")
	)
	(arc
		(start 122.729498 -100.776786)
		(mid 122.676028 -100.971849)
		(end 122.724672 -101.1682)
		(width 0.0889)
		(layer "In11.Cu")
		(net "M_M_DQ<57>")
	)
	(arc
		(start 122.735848 -101.187504)
		(mid 122.808646 -101.478267)
		(end 122.729498 -101.767386)
		(width 0.0889)
		(layer "In11.Cu")
		(net "M_M_DQ<57>")
	)
	(arc
		(start 122.729498 -98.795586)
		(mid 122.676028 -98.990649)
		(end 122.724672 -99.187)
		(width 0.0889)
		(layer "In11.Cu")
		(net "M_M_DQ<57>")
	)
	(arc
		(start 120.518682 -95.928434)
		(mid 120.804106 -96.011901)
		(end 121.012712 -96.223836)
		(width 0.0889)
		(layer "In11.Cu")
		(net "M_M_DQ<57>")
	)
	(arc
		(start 117.943122 -94.442534)
		(mid 118.228546 -94.526001)
		(end 118.437152 -94.737936)
		(width 0.0889)
		(layer "In11.Cu")
		(net "M_M_DQ<57>")
	)
	(arc
		(start 121.016014 -96.229678)
		(mid 121.16198 -96.372077)
		(end 121.359168 -96.423988)
		(width 0.0889)
		(layer "In11.Cu")
		(net "M_M_DQ<57>")
	)
	(arc
		(start 119.295672 -95.232982)
		(mid 119.437355 -95.376786)
		(end 119.631206 -95.433134)
		(width 0.0889)
		(layer "In11.Cu")
		(net "M_M_DQ<57>")
	)
	(arc
		(start 117.578632 -93.842586)
		(mid 117.574222 -94.235049)
		(end 117.907308 -94.442534)
		(width 0.0889)
		(layer "In11.Cu")
		(net "M_M_DQ<57>")
	)
	(arc
		(start 122.729498 -101.767386)
		(mid 122.676028 -101.962449)
		(end 122.724672 -102.1588)
		(width 0.0889)
		(layer "In11.Cu")
		(net "M_M_DQ<57>")
	)
	(arc
		(start 122.235468 -96.919034)
		(mid 122.733719 -97.221874)
		(end 122.729498 -97.804986)
		(width 0.0889)
		(layer "In11.Cu")
		(net "M_M_DQ<57>")
	)
	(arc
		(start 120.154192 -95.728536)
		(mid 120.294271 -95.871272)
		(end 120.485916 -95.928434)
		(width 0.0889)
		(layer "In11.Cu")
		(net "M_M_DQ<57>")
	)
	(arc
		(start 122.729498 -97.804986)
		(mid 122.675847 -98.005282)
		(end 122.729498 -98.205544)
		(width 0.0889)
		(layer "In11.Cu")
		(net "M_M_DQ<57>")
	)
	(arc
		(start 122.735848 -100.196904)
		(mid 122.808646 -100.487667)
		(end 122.729498 -100.776786)
		(width 0.0889)
		(layer "In11.Cu")
		(net "M_M_DQ<57>")
	)
	(arc
		(start 118.805452 -94.937834)
		(mid 119.088669 -95.022115)
		(end 119.295672 -95.232982)
		(width 0.0889)
		(layer "In11.Cu")
		(net "M_M_DQ<57>")
	)
	(arc
		(start 122.729498 -98.205544)
		(mid 122.808503 -98.500582)
		(end 122.729498 -98.795586)
		(width 0.0889)
		(layer "In11.Cu")
		(net "M_M_DQ<57>")
	)
	(arc
		(start 121.870978 -96.719136)
		(mid 122.011057 -96.861872)
		(end 122.202702 -96.919034)
		(width 0.0889)
		(layer "In11.Cu")
		(net "M_M_DQ<57>")
	)
	(arc
		(start 122.729498 -99.786186)
		(mid 122.676028 -99.981249)
		(end 122.724672 -100.1776)
		(width 0.0889)
		(layer "In11.Cu")
		(net "M_M_DQ<57>")
	)
	(arc
		(start 119.655336 -95.433134)
		(mid 119.943481 -95.515453)
		(end 120.154192 -95.728536)
		(width 0.0889)
		(layer "In11.Cu")
		(net "M_M_DQ<57>")
	)
	(arc
		(start 121.380758 -96.423988)
		(mid 121.663975 -96.508269)
		(end 121.870978 -96.719136)
		(width 0.0889)
		(layer "In11.Cu")
		(net "M_M_DQ<57>")
	)
	(arc
		(start 118.437152 -94.737936)
		(mid 118.575896 -94.879969)
		(end 118.765828 -94.937834)
		(width 0.0889)
		(layer "In11.Cu")
		(net "M_M_DQ<57>")
	)
	(arc
		(start 123.097798 -103.358188)
		(mid 123.279458 -103.393846)
		(end 123.441206 -103.483918)
		(width 0.0889)
		(layer "In11.Cu")
		(net "M_M_DQ<57>")
	)
	(arc
		(start 117.584982 -93.262704)
		(mid 117.65778 -93.553467)
		(end 117.578632 -93.842586)
		(width 0.0889)
		(layer "In11.Cu")
		(net "M_M_DQ<57>")
	)
	(arc
		(start 117.578632 -92.851986)
		(mid 117.525162 -93.047049)
		(end 117.573806 -93.2434)
		(width 0.0889)
		(layer "In11.Cu")
		(net "M_M_DQ<57>")
	)
	(arc
		(start 122.735848 -102.178104)
		(mid 122.808646 -102.468867)
		(end 122.729498 -102.757986)
		(width 0.0889)
		(layer "In11.Cu")
		(net "M_M_DQ<57>")
	)
	(arc
		(start 122.729498 -102.757986)
		(mid 122.72675 -103.153453)
		(end 123.065032 -103.358188)
		(width 0.0889)
		(layer "In11.Cu")
		(net "M_M_DQ<57>")
	)
	(segment
		(start 117.353842 -90.080338)
		(end 117.925342 -90.080338)
		(width 0.1651)
		(layer "F.Cu")
		(net "M_M_DQ<56>")
	)
	(segment
		(start 145.29943 -156.87294)
		(end 145.29943 -156.878782)
		(width 0.1651)
		(layer "F.Cu")
		(net "M_M_DQ<56>")
	)
	(segment
		(start 145.29943 -156.878782)
		(end 145.12163 -155.0162)
		(width 0.1651)
		(layer "F.Cu")
		(net "M_M_DQ<56>")
	)
	(via
		(at 117.925342 -90.080338)
		(size 0.508)
		(drill 0.254)
		(layers "F.Cu" "B.Cu")
		(net "M_M_DQ<56>")
	)
	(via
		(at 144.449546 -150.814278)
		(size 0.508)
		(drill 0.254)
		(layers "F.Cu" "B.Cu")
		(net "M_M_DQ<56>")
	)
	(via
		(at 145.12163 -155.0162)
		(size 0.508)
		(drill 0.254)
		(layers "F.Cu" "B.Cu")
		(net "M_M_DQ<56>")
	)
	(segment
		(start 144.449546 -152.078436)
		(end 144.449546 -150.814278)
		(width 0.1651)
		(layer "B.Cu")
		(net "M_M_DQ<56>")
	)
	(segment
		(start 119.629428 -95.623888)
		(end 119.657368 -95.623888)
		(width 0.0889)
		(layer "In11.Cu")
		(net "M_M_DQ<56>")
	)
	(segment
		(start 144.902682 -148.99386)
		(end 144.085564 -149.810978)
		(width 0.14224)
		(layer "In11.Cu")
		(net "M_M_DQ<56>")
	)
	(segment
		(start 130.17881 -110.443518)
		(end 130.17881 -113.01222)
		(width 0.14224)
		(layer "In11.Cu")
		(net "M_M_DQ<56>")
	)
	(segment
		(start 144.888458 -134.519924)
		(end 144.661382 -134.747)
		(width 0.14224)
		(layer "In11.Cu")
		(net "M_M_DQ<56>")
	)
	(segment
		(start 117.903752 -94.633288)
		(end 117.943376 -94.633288)
		(width 0.0889)
		(layer "In11.Cu")
		(net "M_M_DQ<56>")
	)
	(segment
		(start 123.349512 -103.661464)
		(end 123.712478 -104.02443)
		(width 0.0889)
		(layer "In11.Cu")
		(net "M_M_DQ<56>")
	)
	(segment
		(start 144.916906 -129.777236)
		(end 144.631664 -130.062478)
		(width 0.14224)
		(layer "In11.Cu")
		(net "M_M_DQ<56>")
	)
	(segment
		(start 144.449546 -150.814278)
		(end 144.016476 -151.247348)
		(width 0.14224)
		(layer "In11.Cu")
		(net "M_M_DQ<56>")
	)
	(segment
		(start 144.631664 -140.743178)
		(end 144.89557 -141.007084)
		(width 0.14224)
		(layer "In11.Cu")
		(net "M_M_DQ<56>")
	)
	(segment
		(start 144.661382 -135.976614)
		(end 144.902682 -136.217914)
		(width 0.14224)
		(layer "In11.Cu")
		(net "M_M_DQ<56>")
	)
	(segment
		(start 144.085564 -149.810978)
		(end 144.085564 -150.450296)
		(width 0.14224)
		(layer "In11.Cu")
		(net "M_M_DQ<56>")
	)
	(segment
		(start 117.413532 -93.347286)
		(end 117.418358 -93.355922)
		(width 0.0889)
		(layer "In11.Cu")
		(net "M_M_DQ<56>")
	)
	(segment
		(start 144.89557 -144.114012)
		(end 144.675606 -144.333976)
		(width 0.14224)
		(layer "In11.Cu")
		(net "M_M_DQ<56>")
	)
	(segment
		(start 120.479312 -96.118934)
		(end 120.500902 -96.118934)
		(width 0.0889)
		(layer "In11.Cu")
		(net "M_M_DQ<56>")
	)
	(segment
		(start 144.902682 -139.39266)
		(end 144.631664 -139.663678)
		(width 0.14224)
		(layer "In11.Cu")
		(net "M_M_DQ<56>")
	)
	(segment
		(start 117.413532 -92.356686)
		(end 117.418358 -92.365322)
		(width 0.0889)
		(layer "In11.Cu")
		(net "M_M_DQ<56>")
	)
	(segment
		(start 123.058428 -103.548688)
		(end 123.091194 -103.548688)
		(width 0.0889)
		(layer "In11.Cu")
		(net "M_M_DQ<56>")
	)
	(segment
		(start 135.657082 -114.275362)
		(end 144.916906 -123.535186)
		(width 0.14224)
		(layer "In11.Cu")
		(net "M_M_DQ<56>")
	)
	(segment
		(start 117.413532 -91.366086)
		(end 117.418358 -91.374722)
		(width 0.0889)
		(layer "In11.Cu")
		(net "M_M_DQ<56>")
	)
	(segment
		(start 144.675606 -145.591784)
		(end 144.902682 -145.81886)
		(width 0.14224)
		(layer "In11.Cu")
		(net "M_M_DQ<56>")
	)
	(segment
		(start 123.481592 -104.810814)
		(end 123.481592 -105.50652)
		(width 0.14224)
		(layer "In11.Cu")
		(net "M_M_DQ<56>")
	)
	(segment
		(start 123.712478 -104.579928)
		(end 123.481592 -104.810814)
		(width 0.0889)
		(layer "In11.Cu")
		(net "M_M_DQ<56>")
	)
	(segment
		(start 128.421892 -108.6866)
		(end 130.17881 -110.443518)
		(width 0.14224)
		(layer "In11.Cu")
		(net "M_M_DQ<56>")
	)
	(segment
		(start 121.341388 -96.614488)
		(end 121.374154 -96.614488)
		(width 0.0889)
		(layer "In11.Cu")
		(net "M_M_DQ<56>")
	)
	(segment
		(start 130.17881 -113.01222)
		(end 131.441952 -114.275362)
		(width 0.14224)
		(layer "In11.Cu")
		(net "M_M_DQ<56>")
	)
	(segment
		(start 120.844056 -96.313244)
		(end 120.847358 -96.319086)
		(width 0.0889)
		(layer "In11.Cu")
		(net "M_M_DQ<56>")
	)
	(segment
		(start 144.661382 -134.747)
		(end 144.661382 -135.976614)
		(width 0.14224)
		(layer "In11.Cu")
		(net "M_M_DQ<56>")
	)
	(segment
		(start 122.564398 -102.262686)
		(end 122.569224 -102.271322)
		(width 0.0889)
		(layer "In11.Cu")
		(net "M_M_DQ<56>")
	)
	(segment
		(start 144.675606 -144.333976)
		(end 144.675606 -145.591784)
		(width 0.14224)
		(layer "In11.Cu")
		(net "M_M_DQ<56>")
	)
	(segment
		(start 144.631664 -131.141978)
		(end 144.888458 -131.398772)
		(width 0.14224)
		(layer "In11.Cu")
		(net "M_M_DQ<56>")
	)
	(segment
		(start 122.558048 -100.270818)
		(end 122.564398 -100.281486)
		(width 0.0889)
		(layer "In11.Cu")
		(net "M_M_DQ<56>")
	)
	(segment
		(start 117.45341 -90.715084)
		(end 117.430296 -90.746072)
		(width 0.0889)
		(layer "In11.Cu")
		(net "M_M_DQ<56>")
	)
	(segment
		(start 122.564398 -100.281486)
		(end 122.569224 -100.290122)
		(width 0.0889)
		(layer "In11.Cu")
		(net "M_M_DQ<56>")
	)
	(segment
		(start 122.564398 -101.272086)
		(end 122.569224 -101.280722)
		(width 0.0889)
		(layer "In11.Cu")
		(net "M_M_DQ<56>")
	)
	(segment
		(start 144.631664 -130.062478)
		(end 144.631664 -131.141978)
		(width 0.14224)
		(layer "In11.Cu")
		(net "M_M_DQ<56>")
	)
	(segment
		(start 144.825466 -155.0162)
		(end 145.12163 -155.0162)
		(width 0.14224)
		(layer "In11.Cu")
		(net "M_M_DQ<56>")
	)
	(segment
		(start 122.558048 -99.280218)
		(end 122.564398 -99.290886)
		(width 0.0889)
		(layer "In11.Cu")
		(net "M_M_DQ<56>")
	)
	(segment
		(start 122.558048 -102.252018)
		(end 122.564398 -102.262686)
		(width 0.0889)
		(layer "In11.Cu")
		(net "M_M_DQ<56>")
	)
	(segment
		(start 117.407182 -91.355418)
		(end 117.413532 -91.366086)
		(width 0.0889)
		(layer "In11.Cu")
		(net "M_M_DQ<56>")
	)
	(segment
		(start 122.564398 -99.290886)
		(end 122.569224 -99.299522)
		(width 0.0889)
		(layer "In11.Cu")
		(net "M_M_DQ<56>")
	)
	(segment
		(start 122.196098 -97.109534)
		(end 122.228864 -97.109534)
		(width 0.0889)
		(layer "In11.Cu")
		(net "M_M_DQ<56>")
	)
	(segment
		(start 117.925342 -90.080338)
		(end 117.45341 -90.715084)
		(width 0.0889)
		(layer "In11.Cu")
		(net "M_M_DQ<56>")
	)
	(segment
		(start 131.441952 -114.275362)
		(end 135.657082 -114.275362)
		(width 0.14224)
		(layer "In11.Cu")
		(net "M_M_DQ<56>")
	)
	(segment
		(start 126.661672 -108.6866)
		(end 128.421892 -108.6866)
		(width 0.14224)
		(layer "In11.Cu")
		(net "M_M_DQ<56>")
	)
	(segment
		(start 144.89557 -141.007084)
		(end 144.89557 -144.114012)
		(width 0.14224)
		(layer "In11.Cu")
		(net "M_M_DQ<56>")
	)
	(segment
		(start 117.407182 -92.346018)
		(end 117.413532 -92.356686)
		(width 0.0889)
		(layer "In11.Cu")
		(net "M_M_DQ<56>")
	)
	(segment
		(start 144.888458 -131.398772)
		(end 144.888458 -134.519924)
		(width 0.14224)
		(layer "In11.Cu")
		(net "M_M_DQ<56>")
	)
	(segment
		(start 144.085564 -150.450296)
		(end 144.449546 -150.814278)
		(width 0.14224)
		(layer "In11.Cu")
		(net "M_M_DQ<56>")
	)
	(segment
		(start 122.558048 -101.261418)
		(end 122.564398 -101.272086)
		(width 0.0889)
		(layer "In11.Cu")
		(net "M_M_DQ<56>")
	)
	(segment
		(start 117.430296 -90.746072)
		(end 117.413532 -90.775536)
		(width 0.0889)
		(layer "In11.Cu")
		(net "M_M_DQ<56>")
	)
	(segment
		(start 123.481592 -105.50652)
		(end 126.661672 -108.6866)
		(width 0.14224)
		(layer "In11.Cu")
		(net "M_M_DQ<56>")
	)
	(segment
		(start 117.407182 -93.336618)
		(end 117.413532 -93.347286)
		(width 0.0889)
		(layer "In11.Cu")
		(net "M_M_DQ<56>")
	)
	(segment
		(start 144.016476 -151.247348)
		(end 144.016476 -154.20721)
		(width 0.14224)
		(layer "In11.Cu")
		(net "M_M_DQ<56>")
	)
	(segment
		(start 144.902682 -136.217914)
		(end 144.902682 -139.39266)
		(width 0.14224)
		(layer "In11.Cu")
		(net "M_M_DQ<56>")
	)
	(segment
		(start 144.902682 -145.81886)
		(end 144.902682 -148.99386)
		(width 0.14224)
		(layer "In11.Cu")
		(net "M_M_DQ<56>")
	)
	(segment
		(start 144.631664 -139.663678)
		(end 144.631664 -140.743178)
		(width 0.14224)
		(layer "In11.Cu")
		(net "M_M_DQ<56>")
	)
	(segment
		(start 123.712478 -104.02443)
		(end 123.712478 -104.579928)
		(width 0.0889)
		(layer "In11.Cu")
		(net "M_M_DQ<56>")
	)
	(segment
		(start 144.916906 -123.535186)
		(end 144.916906 -129.777236)
		(width 0.14224)
		(layer "In11.Cu")
		(net "M_M_DQ<56>")
	)
	(segment
		(start 144.016476 -154.20721)
		(end 144.825466 -155.0162)
		(width 0.14224)
		(layer "In11.Cu")
		(net "M_M_DQ<56>")
	)
	(segment
		(start 118.766082 -95.128588)
		(end 118.801896 -95.128588)
		(width 0.0889)
		(layer "In11.Cu")
		(net "M_M_DQ<56>")
	)
	(arc
		(start 117.413532 -90.775536)
		(mid 117.33431 -91.064654)
		(end 117.407182 -91.355418)
		(width 0.0889)
		(layer "In11.Cu")
		(net "M_M_DQ<56>")
	)
	(arc
		(start 120.847358 -96.319086)
		(mid 121.055966 -96.531018)
		(end 121.341388 -96.614488)
		(width 0.0889)
		(layer "In11.Cu")
		(net "M_M_DQ<56>")
	)
	(arc
		(start 122.564398 -101.672136)
		(mid 122.485176 -101.961254)
		(end 122.558048 -102.252018)
		(width 0.0889)
		(layer "In11.Cu")
		(net "M_M_DQ<56>")
	)
	(arc
		(start 119.657368 -95.623888)
		(mid 119.84901 -95.681054)
		(end 119.989092 -95.823786)
		(width 0.0889)
		(layer "In11.Cu")
		(net "M_M_DQ<56>")
	)
	(arc
		(start 122.564398 -100.681536)
		(mid 122.485176 -100.970654)
		(end 122.558048 -101.261418)
		(width 0.0889)
		(layer "In11.Cu")
		(net "M_M_DQ<56>")
	)
	(arc
		(start 117.413532 -93.747336)
		(mid 117.408278 -94.328844)
		(end 117.903752 -94.633288)
		(width 0.0889)
		(layer "In11.Cu")
		(net "M_M_DQ<56>")
	)
	(arc
		(start 118.801896 -95.128588)
		(mid 118.991825 -95.186458)
		(end 119.130572 -95.328486)
		(width 0.0889)
		(layer "In11.Cu")
		(net "M_M_DQ<56>")
	)
	(arc
		(start 118.272052 -94.833186)
		(mid 118.48066 -95.045118)
		(end 118.766082 -95.128588)
		(width 0.0889)
		(layer "In11.Cu")
		(net "M_M_DQ<56>")
	)
	(arc
		(start 122.569224 -100.290122)
		(mid 122.617979 -100.486474)
		(end 122.564398 -100.681536)
		(width 0.0889)
		(layer "In11.Cu")
		(net "M_M_DQ<56>")
	)
	(arc
		(start 123.091194 -103.548688)
		(mid 123.23102 -103.580637)
		(end 123.349512 -103.661464)
		(width 0.0889)
		(layer "In11.Cu")
		(net "M_M_DQ<56>")
	)
	(arc
		(start 117.418358 -91.374722)
		(mid 117.467113 -91.571074)
		(end 117.413532 -91.766136)
		(width 0.0889)
		(layer "In11.Cu")
		(net "M_M_DQ<56>")
	)
	(arc
		(start 119.130572 -95.328486)
		(mid 119.341285 -95.541565)
		(end 119.629428 -95.623888)
		(width 0.0889)
		(layer "In11.Cu")
		(net "M_M_DQ<56>")
	)
	(arc
		(start 122.564398 -97.709736)
		(mid 122.485208 -98.005392)
		(end 122.564398 -98.301048)
		(width 0.0889)
		(layer "In11.Cu")
		(net "M_M_DQ<56>")
	)
	(arc
		(start 122.564398 -98.301048)
		(mid 122.617872 -98.500692)
		(end 122.564398 -98.700336)
		(width 0.0889)
		(layer "In11.Cu")
		(net "M_M_DQ<56>")
	)
	(arc
		(start 122.564398 -99.690936)
		(mid 122.485176 -99.980054)
		(end 122.558048 -100.270818)
		(width 0.0889)
		(layer "In11.Cu")
		(net "M_M_DQ<56>")
	)
	(arc
		(start 121.705878 -96.814386)
		(mid 121.912882 -97.02525)
		(end 122.196098 -97.109534)
		(width 0.0889)
		(layer "In11.Cu")
		(net "M_M_DQ<56>")
	)
	(arc
		(start 122.564398 -102.662736)
		(mid 122.560069 -103.245908)
		(end 123.058428 -103.548688)
		(width 0.0889)
		(layer "In11.Cu")
		(net "M_M_DQ<56>")
	)
	(arc
		(start 122.228864 -97.109534)
		(mid 122.567033 -97.314332)
		(end 122.564398 -97.709736)
		(width 0.0889)
		(layer "In11.Cu")
		(net "M_M_DQ<56>")
	)
	(arc
		(start 122.569224 -99.299522)
		(mid 122.617979 -99.495874)
		(end 122.564398 -99.690936)
		(width 0.0889)
		(layer "In11.Cu")
		(net "M_M_DQ<56>")
	)
	(arc
		(start 117.418358 -93.355922)
		(mid 117.467113 -93.552274)
		(end 117.413532 -93.747336)
		(width 0.0889)
		(layer "In11.Cu")
		(net "M_M_DQ<56>")
	)
	(arc
		(start 121.374154 -96.614488)
		(mid 121.565796 -96.671654)
		(end 121.705878 -96.814386)
		(width 0.0889)
		(layer "In11.Cu")
		(net "M_M_DQ<56>")
	)
	(arc
		(start 117.413532 -91.766136)
		(mid 117.33431 -92.055254)
		(end 117.407182 -92.346018)
		(width 0.0889)
		(layer "In11.Cu")
		(net "M_M_DQ<56>")
	)
	(arc
		(start 117.943376 -94.633288)
		(mid 118.133305 -94.691158)
		(end 118.272052 -94.833186)
		(width 0.0889)
		(layer "In11.Cu")
		(net "M_M_DQ<56>")
	)
	(arc
		(start 122.569224 -102.271322)
		(mid 122.617979 -102.467674)
		(end 122.564398 -102.662736)
		(width 0.0889)
		(layer "In11.Cu")
		(net "M_M_DQ<56>")
	)
	(arc
		(start 120.500902 -96.118934)
		(mid 120.698063 -96.170893)
		(end 120.844056 -96.313244)
		(width 0.0889)
		(layer "In11.Cu")
		(net "M_M_DQ<56>")
	)
	(arc
		(start 122.564398 -98.700336)
		(mid 122.485176 -98.989454)
		(end 122.558048 -99.280218)
		(width 0.0889)
		(layer "In11.Cu")
		(net "M_M_DQ<56>")
	)
	(arc
		(start 117.418358 -92.365322)
		(mid 117.467113 -92.561674)
		(end 117.413532 -92.756736)
		(width 0.0889)
		(layer "In11.Cu")
		(net "M_M_DQ<56>")
	)
	(arc
		(start 122.569224 -101.280722)
		(mid 122.617979 -101.477074)
		(end 122.564398 -101.672136)
		(width 0.0889)
		(layer "In11.Cu")
		(net "M_M_DQ<56>")
	)
	(arc
		(start 117.413532 -92.756736)
		(mid 117.33431 -93.045854)
		(end 117.407182 -93.336618)
		(width 0.0889)
		(layer "In11.Cu")
		(net "M_M_DQ<56>")
	)
	(arc
		(start 119.989092 -95.823786)
		(mid 120.196096 -96.03465)
		(end 120.479312 -96.118934)
		(width 0.0889)
		(layer "In11.Cu")
		(net "M_M_DQ<56>")
	)
	(segment
		(start 113.919762 -92.061538)
		(end 114.491262 -92.061538)
		(width 0.1651)
		(layer "F.Cu")
		(net "M_M_DQ<55>")
	)
	(segment
		(start 139.34948 -152.273)
		(end 139.34948 -153.542746)
		(width 0.1651)
		(layer "F.Cu")
		(net "M_M_DQ<55>")
	)
	(via
		(at 139.34948 -153.542746)
		(size 0.508)
		(drill 0.254)
		(layers "F.Cu" "B.Cu")
		(net "M_M_DQ<55>")
	)
	(via
		(at 114.491262 -92.061538)
		(size 0.508)
		(drill 0.254)
		(layers "F.Cu" "B.Cu")
		(net "M_M_DQ<55>")
	)
	(via
		(at 140.199364 -149.533356)
		(size 0.508)
		(drill 0.254)
		(layers "F.Cu" "B.Cu")
		(net "M_M_DQ<55>")
	)
	(segment
		(start 140.199364 -147.478496)
		(end 140.199364 -149.533356)
		(width 0.1651)
		(layer "B.Cu")
		(net "M_M_DQ<55>")
	)
	(segment
		(start 139.51077 -151.387048)
		(end 139.51077 -151.660352)
		(width 0.14224)
		(layer "In11.Cu")
		(net "M_M_DQ<55>")
	)
	(segment
		(start 127.401828 -117.94998)
		(end 127.246888 -117.79504)
		(width 0.14224)
		(layer "In11.Cu")
		(net "M_M_DQ<55>")
	)
	(segment
		(start 127.401828 -118.399306)
		(end 127.401828 -117.94998)
		(width 0.14224)
		(layer "In11.Cu")
		(net "M_M_DQ<55>")
	)
	(segment
		(start 140.75537 -136.077452)
		(end 140.75537 -134.757668)
		(width 0.14224)
		(layer "In11.Cu")
		(net "M_M_DQ<55>")
	)
	(segment
		(start 117.084602 -96.919034)
		(end 117.051836 -96.919034)
		(width 0.0889)
		(layer "In11.Cu")
		(net "M_M_DQ<55>")
	)
	(segment
		(start 139.799568 -153.364946)
		(end 139.621768 -153.542746)
		(width 0.14224)
		(layer "In11.Cu")
		(net "M_M_DQ<55>")
	)
	(segment
		(start 140.78077 -130.087878)
		(end 140.55217 -129.859278)
		(width 0.14224)
		(layer "In11.Cu")
		(net "M_M_DQ<55>")
	)
	(segment
		(start 126.583948 -118.554246)
		(end 126.230888 -118.554246)
		(width 0.14224)
		(layer "In11.Cu")
		(net "M_M_DQ<55>")
	)
	(segment
		(start 119.295672 -102.167436)
		(end 119.290846 -102.1588)
		(width 0.0889)
		(layer "In11.Cu")
		(net "M_M_DQ<55>")
	)
	(segment
		(start 140.78077 -139.689078)
		(end 140.55217 -139.460478)
		(width 0.14224)
		(layer "In11.Cu")
		(net "M_M_DQ<55>")
	)
	(segment
		(start 116.229892 -96.423988)
		(end 116.197126 -96.423988)
		(width 0.0889)
		(layer "In11.Cu")
		(net "M_M_DQ<55>")
	)
	(segment
		(start 140.50137 -141.5034)
		(end 140.50137 -141.086078)
		(width 0.14224)
		(layer "In11.Cu")
		(net "M_M_DQ<55>")
	)
	(segment
		(start 140.55217 -138.921998)
		(end 140.637768 -138.8364)
		(width 0.14224)
		(layer "In11.Cu")
		(net "M_M_DQ<55>")
	)
	(segment
		(start 127.556768 -118.554246)
		(end 127.401828 -118.399306)
		(width 0.14224)
		(layer "In11.Cu")
		(net "M_M_DQ<55>")
	)
	(segment
		(start 119.781066 -112.163098)
		(end 119.781066 -106.94035)
		(width 0.14224)
		(layer "In11.Cu")
		(net "M_M_DQ<55>")
	)
	(segment
		(start 140.695934 -129.269236)
		(end 140.695934 -127.185166)
		(width 0.14224)
		(layer "In11.Cu")
		(net "M_M_DQ<55>")
	)
	(segment
		(start 119.295672 -99.195636)
		(end 119.290846 -99.187)
		(width 0.0889)
		(layer "In11.Cu")
		(net "M_M_DQ<55>")
	)
	(segment
		(start 140.199364 -149.533356)
		(end 140.55217 -149.18055)
		(width 0.14224)
		(layer "In11.Cu")
		(net "M_M_DQ<55>")
	)
	(segment
		(start 140.637768 -141.639798)
		(end 140.50137 -141.5034)
		(width 0.14224)
		(layer "In11.Cu")
		(net "M_M_DQ<55>")
	)
	(segment
		(start 127.909828 -118.554246)
		(end 127.556768 -118.554246)
		(width 0.14224)
		(layer "In11.Cu")
		(net "M_M_DQ<55>")
	)
	(segment
		(start 139.767818 -151.9174)
		(end 139.767818 -152.2222)
		(width 0.14224)
		(layer "In11.Cu")
		(net "M_M_DQ<55>")
	)
	(segment
		(start 127.246888 -117.79504)
		(end 126.893828 -117.79504)
		(width 0.14224)
		(layer "In11.Cu")
		(net "M_M_DQ<55>")
	)
	(segment
		(start 140.721334 -145.661634)
		(end 140.721334 -144.313402)
		(width 0.14224)
		(layer "In11.Cu")
		(net "M_M_DQ<55>")
	)
	(segment
		(start 140.57757 -134.070598)
		(end 140.637768 -134.0104)
		(width 0.14224)
		(layer "In11.Cu")
		(net "M_M_DQ<55>")
	)
	(segment
		(start 140.57757 -134.579868)
		(end 140.57757 -134.070598)
		(width 0.14224)
		(layer "In11.Cu")
		(net "M_M_DQ<55>")
	)
	(segment
		(start 140.637768 -131.987798)
		(end 140.57757 -131.9276)
		(width 0.14224)
		(layer "In11.Cu")
		(net "M_M_DQ<55>")
	)
	(segment
		(start 140.637768 -134.0104)
		(end 140.637768 -131.987798)
		(width 0.14224)
		(layer "In11.Cu")
		(net "M_M_DQ<55>")
	)
	(segment
		(start 140.50137 -141.086078)
		(end 140.78077 -140.806678)
		(width 0.14224)
		(layer "In11.Cu")
		(net "M_M_DQ<55>")
	)
	(segment
		(start 139.793218 -150.435818)
		(end 139.793218 -151.1046)
		(width 0.14224)
		(layer "In11.Cu")
		(net "M_M_DQ<55>")
	)
	(segment
		(start 139.793218 -151.1046)
		(end 139.51077 -151.387048)
		(width 0.14224)
		(layer "In11.Cu")
		(net "M_M_DQ<55>")
	)
	(segment
		(start 119.295672 -104.148636)
		(end 119.290846 -104.14)
		(width 0.0889)
		(layer "In11.Cu")
		(net "M_M_DQ<55>")
	)
	(segment
		(start 114.998246 -93.355922)
		(end 115.003072 -93.347286)
		(width 0.0889)
		(layer "In11.Cu")
		(net "M_M_DQ<55>")
	)
	(segment
		(start 129.24282 -118.462044)
		(end 128.88976 -118.462044)
		(width 0.14224)
		(layer "In11.Cu")
		(net "M_M_DQ<55>")
	)
	(segment
		(start 133.599428 -117.79504)
		(end 129.545588 -117.79504)
		(width 0.14224)
		(layer "In11.Cu")
		(net "M_M_DQ<55>")
	)
	(segment
		(start 126.075948 -118.399306)
		(end 126.075948 -117.94998)
		(width 0.14224)
		(layer "In11.Cu")
		(net "M_M_DQ<55>")
	)
	(segment
		(start 128.064768 -117.94998)
		(end 128.064768 -118.399306)
		(width 0.14224)
		(layer "In11.Cu")
		(net "M_M_DQ<55>")
	)
	(segment
		(start 126.893828 -117.79504)
		(end 126.738888 -117.94998)
		(width 0.14224)
		(layer "In11.Cu")
		(net "M_M_DQ<55>")
	)
	(segment
		(start 126.230888 -118.554246)
		(end 126.075948 -118.399306)
		(width 0.14224)
		(layer "In11.Cu")
		(net "M_M_DQ<55>")
	)
	(segment
		(start 119.302022 -103.168704)
		(end 119.295672 -103.158036)
		(width 0.0889)
		(layer "In11.Cu")
		(net "M_M_DQ<55>")
	)
	(segment
		(start 128.219708 -117.79504)
		(end 128.064768 -117.94998)
		(width 0.14224)
		(layer "In11.Cu")
		(net "M_M_DQ<55>")
	)
	(segment
		(start 140.57757 -131.9276)
		(end 140.57757 -131.408678)
		(width 0.14224)
		(layer "In11.Cu")
		(net "M_M_DQ<55>")
	)
	(segment
		(start 126.075948 -117.94998)
		(end 125.921008 -117.79504)
		(width 0.14224)
		(layer "In11.Cu")
		(net "M_M_DQ<55>")
	)
	(segment
		(start 140.637768 -136.661398)
		(end 140.55217 -136.5758)
		(width 0.14224)
		(layer "In11.Cu")
		(net "M_M_DQ<55>")
	)
	(segment
		(start 129.390648 -118.314216)
		(end 129.24282 -118.462044)
		(width 0.14224)
		(layer "In11.Cu")
		(net "M_M_DQ<55>")
	)
	(segment
		(start 140.57757 -143.747998)
		(end 140.637768 -143.6878)
		(width 0.14224)
		(layer "In11.Cu")
		(net "M_M_DQ<55>")
	)
	(segment
		(start 139.767818 -152.2222)
		(end 139.51077 -152.479248)
		(width 0.14224)
		(layer "In11.Cu")
		(net "M_M_DQ<55>")
	)
	(segment
		(start 125.921008 -117.79504)
		(end 125.413008 -117.79504)
		(width 0.14224)
		(layer "In11.Cu")
		(net "M_M_DQ<55>")
	)
	(segment
		(start 139.332716 -123.528328)
		(end 133.599428 -117.79504)
		(width 0.14224)
		(layer "In11.Cu")
		(net "M_M_DQ<55>")
	)
	(segment
		(start 128.727708 -118.299992)
		(end 128.727708 -117.94998)
		(width 0.14224)
		(layer "In11.Cu")
		(net "M_M_DQ<55>")
	)
	(segment
		(start 140.78077 -131.205478)
		(end 140.78077 -130.087878)
		(width 0.14224)
		(layer "In11.Cu")
		(net "M_M_DQ<55>")
	)
	(segment
		(start 119.302022 -105.149904)
		(end 119.295672 -105.139236)
		(width 0.0889)
		(layer "In11.Cu")
		(net "M_M_DQ<55>")
	)
	(segment
		(start 129.390648 -117.94998)
		(end 129.390648 -118.314216)
		(width 0.14224)
		(layer "In11.Cu")
		(net "M_M_DQ<55>")
	)
	(segment
		(start 125.413008 -117.79504)
		(end 119.781066 -112.163098)
		(width 0.14224)
		(layer "In11.Cu")
		(net "M_M_DQ<55>")
	)
	(segment
		(start 119.302022 -102.178104)
		(end 119.295672 -102.167436)
		(width 0.0889)
		(layer "In11.Cu")
		(net "M_M_DQ<55>")
	)
	(segment
		(start 140.485368 -124.326396)
		(end 139.6873 -123.528328)
		(width 0.14224)
		(layer "In11.Cu")
		(net "M_M_DQ<55>")
	)
	(segment
		(start 139.6873 -123.528328)
		(end 139.332716 -123.528328)
		(width 0.14224)
		(layer "In11.Cu")
		(net "M_M_DQ<55>")
	)
	(segment
		(start 140.75537 -134.757668)
		(end 140.57757 -134.579868)
		(width 0.14224)
		(layer "In11.Cu")
		(net "M_M_DQ<55>")
	)
	(segment
		(start 140.199364 -149.533356)
		(end 140.177012 -149.533356)
		(width 0.14224)
		(layer "In11.Cu")
		(net "M_M_DQ<55>")
	)
	(segment
		(start 139.51077 -151.660352)
		(end 139.767818 -151.9174)
		(width 0.14224)
		(layer "In11.Cu")
		(net "M_M_DQ<55>")
	)
	(segment
		(start 114.998246 -95.337122)
		(end 115.003072 -95.328486)
		(width 0.0889)
		(layer "In11.Cu")
		(net "M_M_DQ<55>")
	)
	(segment
		(start 129.545588 -117.79504)
		(end 129.390648 -117.94998)
		(width 0.14224)
		(layer "In11.Cu")
		(net "M_M_DQ<55>")
	)
	(segment
		(start 128.572768 -117.79504)
		(end 128.219708 -117.79504)
		(width 0.14224)
		(layer "In11.Cu")
		(net "M_M_DQ<55>")
	)
	(segment
		(start 119.242078 -106.143298)
		(end 119.242078 -105.929938)
		(width 0.0889)
		(layer "In11.Cu")
		(net "M_M_DQ<55>")
	)
	(segment
		(start 119.781066 -106.94035)
		(end 119.557292 -106.716576)
		(width 0.0889)
		(layer "In11.Cu")
		(net "M_M_DQ<55>")
	)
	(segment
		(start 119.295672 -100.186236)
		(end 119.290846 -100.1776)
		(width 0.0889)
		(layer "In11.Cu")
		(net "M_M_DQ<55>")
	)
	(segment
		(start 140.695934 -127.185166)
		(end 140.485368 -126.9746)
		(width 0.14224)
		(layer "In11.Cu")
		(net "M_M_DQ<55>")
	)
	(segment
		(start 118.801642 -97.909634)
		(end 118.768876 -97.909634)
		(width 0.0889)
		(layer "In11.Cu")
		(net "M_M_DQ<55>")
	)
	(segment
		(start 139.748768 -150.391368)
		(end 139.793218 -150.435818)
		(width 0.14224)
		(layer "In11.Cu")
		(net "M_M_DQ<55>")
	)
	(segment
		(start 119.295672 -103.158036)
		(end 119.290846 -103.1494)
		(width 0.0889)
		(layer "In11.Cu")
		(net "M_M_DQ<55>")
	)
	(segment
		(start 114.986308 -92.727272)
		(end 114.491262 -92.061538)
		(width 0.0889)
		(layer "In11.Cu")
		(net "M_M_DQ<55>")
	)
	(segment
		(start 139.51077 -152.479248)
		(end 139.51077 -152.752552)
		(width 0.14224)
		(layer "In11.Cu")
		(net "M_M_DQ<55>")
	)
	(segment
		(start 140.55217 -129.413)
		(end 140.695934 -129.269236)
		(width 0.14224)
		(layer "In11.Cu")
		(net "M_M_DQ<55>")
	)
	(segment
		(start 126.738888 -118.399306)
		(end 126.583948 -118.554246)
		(width 0.14224)
		(layer "In11.Cu")
		(net "M_M_DQ<55>")
	)
	(segment
		(start 115.003072 -93.347286)
		(end 115.009422 -93.336618)
		(width 0.0889)
		(layer "In11.Cu")
		(net "M_M_DQ<55>")
	)
	(segment
		(start 139.621768 -153.542746)
		(end 139.34948 -153.542746)
		(width 0.14224)
		(layer "In11.Cu")
		(net "M_M_DQ<55>")
	)
	(segment
		(start 117.946932 -97.414588)
		(end 117.914166 -97.414588)
		(width 0.0889)
		(layer "In11.Cu")
		(net "M_M_DQ<55>")
	)
	(segment
		(start 140.485368 -126.9746)
		(end 140.485368 -124.326396)
		(width 0.14224)
		(layer "In11.Cu")
		(net "M_M_DQ<55>")
	)
	(segment
		(start 115.003072 -92.756736)
		(end 114.986308 -92.727272)
		(width 0.0889)
		(layer "In11.Cu")
		(net "M_M_DQ<55>")
	)
	(segment
		(start 140.57757 -144.169638)
		(end 140.57757 -143.747998)
		(width 0.14224)
		(layer "In11.Cu")
		(net "M_M_DQ<55>")
	)
	(segment
		(start 128.064768 -118.399306)
		(end 127.909828 -118.554246)
		(width 0.14224)
		(layer "In11.Cu")
		(net "M_M_DQ<55>")
	)
	(segment
		(start 119.557292 -106.458512)
		(end 119.242078 -106.143298)
		(width 0.0889)
		(layer "In11.Cu")
		(net "M_M_DQ<55>")
	)
	(segment
		(start 140.78077 -140.806678)
		(end 140.78077 -139.689078)
		(width 0.14224)
		(layer "In11.Cu")
		(net "M_M_DQ<55>")
	)
	(segment
		(start 119.302022 -104.159304)
		(end 119.295672 -104.148636)
		(width 0.0889)
		(layer "In11.Cu")
		(net "M_M_DQ<55>")
	)
	(segment
		(start 140.55217 -129.859278)
		(end 140.55217 -129.413)
		(width 0.14224)
		(layer "In11.Cu")
		(net "M_M_DQ<55>")
	)
	(segment
		(start 140.55217 -139.460478)
		(end 140.55217 -138.921998)
		(width 0.14224)
		(layer "In11.Cu")
		(net "M_M_DQ<55>")
	)
	(segment
		(start 115.367562 -95.928434)
		(end 115.334796 -95.928434)
		(width 0.0889)
		(layer "In11.Cu")
		(net "M_M_DQ<55>")
	)
	(segment
		(start 140.57757 -131.408678)
		(end 140.78077 -131.205478)
		(width 0.14224)
		(layer "In11.Cu")
		(net "M_M_DQ<55>")
	)
	(segment
		(start 139.51077 -152.752552)
		(end 139.799568 -153.04135)
		(width 0.14224)
		(layer "In11.Cu")
		(net "M_M_DQ<55>")
	)
	(segment
		(start 140.55217 -149.18055)
		(end 140.55217 -145.830798)
		(width 0.14224)
		(layer "In11.Cu")
		(net "M_M_DQ<55>")
	)
	(segment
		(start 140.721334 -144.313402)
		(end 140.57757 -144.169638)
		(width 0.14224)
		(layer "In11.Cu")
		(net "M_M_DQ<55>")
	)
	(segment
		(start 119.302022 -101.187504)
		(end 119.295672 -101.176836)
		(width 0.0889)
		(layer "In11.Cu")
		(net "M_M_DQ<55>")
	)
	(segment
		(start 128.88976 -118.462044)
		(end 128.727708 -118.299992)
		(width 0.14224)
		(layer "In11.Cu")
		(net "M_M_DQ<55>")
	)
	(segment
		(start 139.748768 -149.9616)
		(end 139.748768 -150.391368)
		(width 0.14224)
		(layer "In11.Cu")
		(net "M_M_DQ<55>")
	)
	(segment
		(start 140.177012 -149.533356)
		(end 139.748768 -149.9616)
		(width 0.14224)
		(layer "In11.Cu")
		(net "M_M_DQ<55>")
	)
	(segment
		(start 140.637768 -138.8364)
		(end 140.637768 -136.661398)
		(width 0.14224)
		(layer "In11.Cu")
		(net "M_M_DQ<55>")
	)
	(segment
		(start 119.295672 -101.176836)
		(end 119.290846 -101.1682)
		(width 0.0889)
		(layer "In11.Cu")
		(net "M_M_DQ<55>")
	)
	(segment
		(start 140.637768 -143.6878)
		(end 140.637768 -141.639798)
		(width 0.14224)
		(layer "In11.Cu")
		(net "M_M_DQ<55>")
	)
	(segment
		(start 119.557292 -106.716576)
		(end 119.557292 -106.458512)
		(width 0.0889)
		(layer "In11.Cu")
		(net "M_M_DQ<55>")
	)
	(segment
		(start 128.727708 -117.94998)
		(end 128.572768 -117.79504)
		(width 0.14224)
		(layer "In11.Cu")
		(net "M_M_DQ<55>")
	)
	(segment
		(start 140.55217 -136.5758)
		(end 140.55217 -136.280652)
		(width 0.14224)
		(layer "In11.Cu")
		(net "M_M_DQ<55>")
	)
	(segment
		(start 119.295672 -105.139236)
		(end 119.290846 -105.1306)
		(width 0.0889)
		(layer "In11.Cu")
		(net "M_M_DQ<55>")
	)
	(segment
		(start 119.302022 -100.196904)
		(end 119.295672 -100.186236)
		(width 0.0889)
		(layer "In11.Cu")
		(net "M_M_DQ<55>")
	)
	(segment
		(start 140.55217 -136.280652)
		(end 140.75537 -136.077452)
		(width 0.14224)
		(layer "In11.Cu")
		(net "M_M_DQ<55>")
	)
	(segment
		(start 119.302022 -99.206304)
		(end 119.295672 -99.195636)
		(width 0.0889)
		(layer "In11.Cu")
		(net "M_M_DQ<55>")
	)
	(segment
		(start 126.738888 -117.94998)
		(end 126.738888 -118.399306)
		(width 0.14224)
		(layer "In11.Cu")
		(net "M_M_DQ<55>")
	)
	(segment
		(start 140.55217 -145.830798)
		(end 140.721334 -145.661634)
		(width 0.14224)
		(layer "In11.Cu")
		(net "M_M_DQ<55>")
	)
	(segment
		(start 139.799568 -153.04135)
		(end 139.799568 -153.364946)
		(width 0.14224)
		(layer "In11.Cu")
		(net "M_M_DQ<55>")
	)
	(segment
		(start 115.009422 -94.748604)
		(end 115.003072 -94.737936)
		(width 0.0889)
		(layer "In11.Cu")
		(net "M_M_DQ<55>")
	)
	(arc
		(start 119.290846 -105.1306)
		(mid 119.242091 -104.934248)
		(end 119.295672 -104.739186)
		(width 0.0889)
		(layer "In11.Cu")
		(net "M_M_DQ<55>")
	)
	(arc
		(start 115.861592 -96.223836)
		(mid 115.652984 -96.011904)
		(end 115.367562 -95.928434)
		(width 0.0889)
		(layer "In11.Cu")
		(net "M_M_DQ<55>")
	)
	(arc
		(start 119.295672 -98.795586)
		(mid 119.300001 -98.212414)
		(end 118.801642 -97.909634)
		(width 0.0889)
		(layer "In11.Cu")
		(net "M_M_DQ<55>")
	)
	(arc
		(start 117.914166 -97.414588)
		(mid 117.720316 -97.358238)
		(end 117.578632 -97.214436)
		(width 0.0889)
		(layer "In11.Cu")
		(net "M_M_DQ<55>")
	)
	(arc
		(start 115.003072 -94.33814)
		(mid 115.082203 -94.042738)
		(end 115.003072 -93.747336)
		(width 0.0889)
		(layer "In11.Cu")
		(net "M_M_DQ<55>")
	)
	(arc
		(start 118.437152 -97.709736)
		(mid 118.230148 -97.498872)
		(end 117.946932 -97.414588)
		(width 0.0889)
		(layer "In11.Cu")
		(net "M_M_DQ<55>")
	)
	(arc
		(start 117.578632 -97.214436)
		(mid 117.370024 -97.002504)
		(end 117.084602 -96.919034)
		(width 0.0889)
		(layer "In11.Cu")
		(net "M_M_DQ<55>")
	)
	(arc
		(start 119.295672 -100.776786)
		(mid 119.374894 -100.487668)
		(end 119.302022 -100.196904)
		(width 0.0889)
		(layer "In11.Cu")
		(net "M_M_DQ<55>")
	)
	(arc
		(start 117.051836 -96.919034)
		(mid 116.860194 -96.861868)
		(end 116.720112 -96.719136)
		(width 0.0889)
		(layer "In11.Cu")
		(net "M_M_DQ<55>")
	)
	(arc
		(start 115.009422 -93.336618)
		(mid 115.08222 -93.045855)
		(end 115.003072 -92.756736)
		(width 0.0889)
		(layer "In11.Cu")
		(net "M_M_DQ<55>")
	)
	(arc
		(start 119.295672 -104.739186)
		(mid 119.374894 -104.450068)
		(end 119.302022 -104.159304)
		(width 0.0889)
		(layer "In11.Cu")
		(net "M_M_DQ<55>")
	)
	(arc
		(start 119.290846 -100.1776)
		(mid 119.242091 -99.981248)
		(end 119.295672 -99.786186)
		(width 0.0889)
		(layer "In11.Cu")
		(net "M_M_DQ<55>")
	)
	(arc
		(start 119.290846 -104.14)
		(mid 119.242091 -103.943648)
		(end 119.295672 -103.748586)
		(width 0.0889)
		(layer "In11.Cu")
		(net "M_M_DQ<55>")
	)
	(arc
		(start 115.003072 -93.747336)
		(mid 114.949602 -93.552273)
		(end 114.998246 -93.355922)
		(width 0.0889)
		(layer "In11.Cu")
		(net "M_M_DQ<55>")
	)
	(arc
		(start 119.290846 -99.187)
		(mid 119.242091 -98.990648)
		(end 119.295672 -98.795586)
		(width 0.0889)
		(layer "In11.Cu")
		(net "M_M_DQ<55>")
	)
	(arc
		(start 116.720112 -96.719136)
		(mid 116.513108 -96.508272)
		(end 116.229892 -96.423988)
		(width 0.0889)
		(layer "In11.Cu")
		(net "M_M_DQ<55>")
	)
	(arc
		(start 119.290846 -103.1494)
		(mid 119.242091 -102.953048)
		(end 119.295672 -102.757986)
		(width 0.0889)
		(layer "In11.Cu")
		(net "M_M_DQ<55>")
	)
	(arc
		(start 115.334796 -95.928434)
		(mid 115.001878 -95.726443)
		(end 114.998246 -95.337122)
		(width 0.0889)
		(layer "In11.Cu")
		(net "M_M_DQ<55>")
	)
	(arc
		(start 119.295672 -102.757986)
		(mid 119.374894 -102.468868)
		(end 119.302022 -102.178104)
		(width 0.0889)
		(layer "In11.Cu")
		(net "M_M_DQ<55>")
	)
	(arc
		(start 116.197126 -96.423988)
		(mid 116.003276 -96.367638)
		(end 115.861592 -96.223836)
		(width 0.0889)
		(layer "In11.Cu")
		(net "M_M_DQ<55>")
	)
	(arc
		(start 119.295672 -103.748586)
		(mid 119.374894 -103.459468)
		(end 119.302022 -103.168704)
		(width 0.0889)
		(layer "In11.Cu")
		(net "M_M_DQ<55>")
	)
	(arc
		(start 119.295672 -101.767386)
		(mid 119.374894 -101.478268)
		(end 119.302022 -101.187504)
		(width 0.0889)
		(layer "In11.Cu")
		(net "M_M_DQ<55>")
	)
	(arc
		(start 119.290846 -102.1588)
		(mid 119.242091 -101.962448)
		(end 119.295672 -101.767386)
		(width 0.0889)
		(layer "In11.Cu")
		(net "M_M_DQ<55>")
	)
	(arc
		(start 115.003072 -94.737936)
		(mid 114.949573 -94.538038)
		(end 115.003072 -94.33814)
		(width 0.0889)
		(layer "In11.Cu")
		(net "M_M_DQ<55>")
	)
	(arc
		(start 119.295672 -105.729786)
		(mid 119.374894 -105.440668)
		(end 119.302022 -105.149904)
		(width 0.0889)
		(layer "In11.Cu")
		(net "M_M_DQ<55>")
	)
	(arc
		(start 119.290846 -101.1682)
		(mid 119.242091 -100.971848)
		(end 119.295672 -100.776786)
		(width 0.0889)
		(layer "In11.Cu")
		(net "M_M_DQ<55>")
	)
	(arc
		(start 119.295672 -99.786186)
		(mid 119.374894 -99.497068)
		(end 119.302022 -99.206304)
		(width 0.0889)
		(layer "In11.Cu")
		(net "M_M_DQ<55>")
	)
	(arc
		(start 119.242078 -105.929938)
		(mid 119.255716 -105.826341)
		(end 119.295672 -105.729786)
		(width 0.0889)
		(layer "In11.Cu")
		(net "M_M_DQ<55>")
	)
	(arc
		(start 118.768876 -97.909634)
		(mid 118.577234 -97.852468)
		(end 118.437152 -97.709736)
		(width 0.0889)
		(layer "In11.Cu")
		(net "M_M_DQ<55>")
	)
	(arc
		(start 115.003072 -95.328486)
		(mid 115.082294 -95.039368)
		(end 115.009422 -94.748604)
		(width 0.0889)
		(layer "In11.Cu")
		(net "M_M_DQ<55>")
	)
	(segment
		(start 140.199618 -155.4226)
		(end 140.331698 -155.55468)
		(width 0.1651)
		(layer "F.Cu")
		(net "M_M_DQ<54>")
	)
	(segment
		(start 140.331698 -155.77312)
		(end 140.199618 -155.9052)
		(width 0.1651)
		(layer "F.Cu")
		(net "M_M_DQ<54>")
	)
	(segment
		(start 140.199618 -156.87294)
		(end 140.199364 -156.87294)
		(width 0.1651)
		(layer "F.Cu")
		(net "M_M_DQ<54>")
	)
	(segment
		(start 140.199618 -155.118054)
		(end 140.199618 -155.4226)
		(width 0.1651)
		(layer "F.Cu")
		(net "M_M_DQ<54>")
	)
	(segment
		(start 140.199364 -155.1178)
		(end 140.199618 -155.118054)
		(width 0.1651)
		(layer "F.Cu")
		(net "M_M_DQ<54>")
	)
	(segment
		(start 140.331698 -155.55468)
		(end 140.331698 -155.77312)
		(width 0.1651)
		(layer "F.Cu")
		(net "M_M_DQ<54>")
	)
	(segment
		(start 113.919762 -90.080338)
		(end 114.491262 -90.080338)
		(width 0.1651)
		(layer "F.Cu")
		(net "M_M_DQ<54>")
	)
	(segment
		(start 140.199618 -155.9052)
		(end 140.199618 -156.87294)
		(width 0.1651)
		(layer "F.Cu")
		(net "M_M_DQ<54>")
	)
	(via
		(at 114.491262 -90.080338)
		(size 0.508)
		(drill 0.254)
		(layers "F.Cu" "B.Cu")
		(net "M_M_DQ<54>")
	)
	(via
		(at 140.199364 -155.1178)
		(size 0.508)
		(drill 0.254)
		(layers "F.Cu" "B.Cu")
		(net "M_M_DQ<54>")
	)
	(via
		(at 139.34948 -150.814278)
		(size 0.508)
		(drill 0.254)
		(layers "F.Cu" "B.Cu")
		(net "M_M_DQ<54>")
	)
	(segment
		(start 139.34948 -152.078436)
		(end 139.34948 -150.814278)
		(width 0.1651)
		(layer "B.Cu")
		(net "M_M_DQ<54>")
	)
	(segment
		(start 114.831622 -94.822518)
		(end 114.837972 -94.833186)
		(width 0.0889)
		(layer "In11.Cu")
		(net "M_M_DQ<54>")
	)
	(segment
		(start 119.130572 -103.253286)
		(end 119.135398 -103.261922)
		(width 0.0889)
		(layer "In11.Cu")
		(net "M_M_DQ<54>")
	)
	(segment
		(start 119.130572 -101.272086)
		(end 119.135398 -101.280722)
		(width 0.0889)
		(layer "In11.Cu")
		(net "M_M_DQ<54>")
	)
	(segment
		(start 129.468626 -119.058182)
		(end 130.178556 -118.348252)
		(width 0.14224)
		(layer "In11.Cu")
		(net "M_M_DQ<54>")
	)
	(segment
		(start 119.130572 -104.243886)
		(end 119.135398 -104.252522)
		(width 0.0889)
		(layer "In11.Cu")
		(net "M_M_DQ<54>")
	)
	(segment
		(start 116.190522 -96.614488)
		(end 116.223288 -96.614488)
		(width 0.0889)
		(layer "In11.Cu")
		(net "M_M_DQ<54>")
	)
	(segment
		(start 114.837972 -93.252036)
		(end 114.831622 -93.262704)
		(width 0.0889)
		(layer "In11.Cu")
		(net "M_M_DQ<54>")
	)
	(segment
		(start 139.268454 -150.733252)
		(end 139.34948 -150.814278)
		(width 0.14224)
		(layer "In11.Cu")
		(net "M_M_DQ<54>")
	)
	(segment
		(start 114.491262 -90.080338)
		(end 114.161316 -90.842084)
		(width 0.0889)
		(layer "In11.Cu")
		(net "M_M_DQ<54>")
	)
	(segment
		(start 119.130572 -100.281486)
		(end 119.135398 -100.290122)
		(width 0.0889)
		(layer "In11.Cu")
		(net "M_M_DQ<54>")
	)
	(segment
		(start 139.72286 -140.817092)
		(end 139.86637 -140.960602)
		(width 0.14224)
		(layer "In11.Cu")
		(net "M_M_DQ<54>")
	)
	(segment
		(start 119.124222 -103.242618)
		(end 119.130572 -103.253286)
		(width 0.0889)
		(layer "In11.Cu")
		(net "M_M_DQ<54>")
	)
	(segment
		(start 119.051324 -106.222546)
		(end 119.366792 -106.538014)
		(width 0.0889)
		(layer "In11.Cu")
		(net "M_M_DQ<54>")
	)
	(segment
		(start 119.146066 -112.391698)
		(end 125.81255 -119.058182)
		(width 0.14224)
		(layer "In11.Cu")
		(net "M_M_DQ<54>")
	)
	(segment
		(start 119.130572 -102.262686)
		(end 119.135398 -102.271322)
		(width 0.0889)
		(layer "In11.Cu")
		(net "M_M_DQ<54>")
	)
	(segment
		(start 139.72286 -139.548108)
		(end 139.72286 -140.817092)
		(width 0.14224)
		(layer "In11.Cu")
		(net "M_M_DQ<54>")
	)
	(segment
		(start 133.40715 -118.348252)
		(end 139.083796 -124.024898)
		(width 0.14224)
		(layer "In11.Cu")
		(net "M_M_DQ<54>")
	)
	(segment
		(start 139.34948 -150.814278)
		(end 138.91641 -151.247348)
		(width 0.14224)
		(layer "In11.Cu")
		(net "M_M_DQ<54>")
	)
	(segment
		(start 139.815062 -129.961386)
		(end 139.71397 -130.062478)
		(width 0.14224)
		(layer "In11.Cu")
		(net "M_M_DQ<54>")
	)
	(segment
		(start 114.161316 -90.842084)
		(end 114.144552 -90.870786)
		(width 0.0889)
		(layer "In11.Cu")
		(net "M_M_DQ<54>")
	)
	(segment
		(start 139.81557 -131.408678)
		(end 139.81557 -134.579868)
		(width 0.14224)
		(layer "In11.Cu")
		(net "M_M_DQ<54>")
	)
	(segment
		(start 119.366792 -106.538014)
		(end 119.366792 -106.719624)
		(width 0.0889)
		(layer "In11.Cu")
		(net "M_M_DQ<54>")
	)
	(segment
		(start 119.130572 -99.290886)
		(end 119.135398 -99.299522)
		(width 0.0889)
		(layer "In11.Cu")
		(net "M_M_DQ<54>")
	)
	(segment
		(start 118.762272 -98.100134)
		(end 118.795038 -98.100134)
		(width 0.0889)
		(layer "In11.Cu")
		(net "M_M_DQ<54>")
	)
	(segment
		(start 139.443968 -125.4506)
		(end 139.748768 -125.7554)
		(width 0.14224)
		(layer "In11.Cu")
		(net "M_M_DQ<54>")
	)
	(segment
		(start 115.328192 -96.118934)
		(end 115.360958 -96.118934)
		(width 0.0889)
		(layer "In11.Cu")
		(net "M_M_DQ<54>")
	)
	(segment
		(start 119.146066 -106.94035)
		(end 119.146066 -112.391698)
		(width 0.14224)
		(layer "In11.Cu")
		(net "M_M_DQ<54>")
	)
	(segment
		(start 139.829286 -139.441682)
		(end 139.72286 -139.548108)
		(width 0.14224)
		(layer "In11.Cu")
		(net "M_M_DQ<54>")
	)
	(segment
		(start 139.829032 -149.022816)
		(end 139.268454 -149.583394)
		(width 0.14224)
		(layer "In11.Cu")
		(net "M_M_DQ<54>")
	)
	(segment
		(start 117.045232 -97.109534)
		(end 117.077998 -97.109534)
		(width 0.0889)
		(layer "In11.Cu")
		(net "M_M_DQ<54>")
	)
	(segment
		(start 119.124222 -99.280218)
		(end 119.130572 -99.290886)
		(width 0.0889)
		(layer "In11.Cu")
		(net "M_M_DQ<54>")
	)
	(segment
		(start 117.907562 -97.605088)
		(end 117.940328 -97.605088)
		(width 0.0889)
		(layer "In11.Cu")
		(net "M_M_DQ<54>")
	)
	(segment
		(start 139.86637 -144.118838)
		(end 139.701524 -144.283684)
		(width 0.14224)
		(layer "In11.Cu")
		(net "M_M_DQ<54>")
	)
	(segment
		(start 139.86637 -140.960602)
		(end 139.86637 -144.118838)
		(width 0.14224)
		(layer "In11.Cu")
		(net "M_M_DQ<54>")
	)
	(segment
		(start 125.81255 -119.058182)
		(end 129.468626 -119.058182)
		(width 0.14224)
		(layer "In11.Cu")
		(net "M_M_DQ<54>")
	)
	(segment
		(start 119.124222 -104.233218)
		(end 119.130572 -104.243886)
		(width 0.0889)
		(layer "In11.Cu")
		(net "M_M_DQ<54>")
	)
	(segment
		(start 114.144552 -91.270836)
		(end 114.150902 -91.281504)
		(width 0.0889)
		(layer "In11.Cu")
		(net "M_M_DQ<54>")
	)
	(segment
		(start 139.083796 -124.024898)
		(end 139.316968 -124.024898)
		(width 0.14224)
		(layer "In11.Cu")
		(net "M_M_DQ<54>")
	)
	(segment
		(start 139.316968 -124.024898)
		(end 139.443968 -124.151898)
		(width 0.14224)
		(layer "In11.Cu")
		(net "M_M_DQ<54>")
	)
	(segment
		(start 119.124222 -100.270818)
		(end 119.130572 -100.281486)
		(width 0.0889)
		(layer "In11.Cu")
		(net "M_M_DQ<54>")
	)
	(segment
		(start 114.139726 -91.2622)
		(end 114.144552 -91.270836)
		(width 0.0889)
		(layer "In11.Cu")
		(net "M_M_DQ<54>")
	)
	(segment
		(start 139.701524 -145.641822)
		(end 139.829032 -145.76933)
		(width 0.14224)
		(layer "In11.Cu")
		(net "M_M_DQ<54>")
	)
	(segment
		(start 119.051324 -105.929938)
		(end 119.051324 -106.222546)
		(width 0.0889)
		(layer "In11.Cu")
		(net "M_M_DQ<54>")
	)
	(segment
		(start 119.124222 -101.261418)
		(end 119.130572 -101.272086)
		(width 0.0889)
		(layer "In11.Cu")
		(net "M_M_DQ<54>")
	)
	(segment
		(start 139.829032 -145.76933)
		(end 139.829032 -149.022816)
		(width 0.14224)
		(layer "In11.Cu")
		(net "M_M_DQ<54>")
	)
	(segment
		(start 138.91641 -153.834846)
		(end 140.199364 -155.1178)
		(width 0.14224)
		(layer "In11.Cu")
		(net "M_M_DQ<54>")
	)
	(segment
		(start 119.124222 -102.252018)
		(end 119.130572 -102.262686)
		(width 0.0889)
		(layer "In11.Cu")
		(net "M_M_DQ<54>")
	)
	(segment
		(start 119.124222 -105.223818)
		(end 119.130572 -105.234486)
		(width 0.0889)
		(layer "In11.Cu")
		(net "M_M_DQ<54>")
	)
	(segment
		(start 114.842798 -93.2434)
		(end 114.837972 -93.252036)
		(width 0.0889)
		(layer "In11.Cu")
		(net "M_M_DQ<54>")
	)
	(segment
		(start 114.842798 -94.234)
		(end 114.837972 -94.242636)
		(width 0.0889)
		(layer "In11.Cu")
		(net "M_M_DQ<54>")
	)
	(segment
		(start 139.815062 -126.400306)
		(end 139.815062 -129.961386)
		(width 0.14224)
		(layer "In11.Cu")
		(net "M_M_DQ<54>")
	)
	(segment
		(start 139.71397 -136.083548)
		(end 139.829286 -136.198864)
		(width 0.14224)
		(layer "In11.Cu")
		(net "M_M_DQ<54>")
	)
	(segment
		(start 139.71397 -134.681468)
		(end 139.71397 -136.083548)
		(width 0.14224)
		(layer "In11.Cu")
		(net "M_M_DQ<54>")
	)
	(segment
		(start 139.81557 -134.579868)
		(end 139.71397 -134.681468)
		(width 0.14224)
		(layer "In11.Cu")
		(net "M_M_DQ<54>")
	)
	(segment
		(start 139.748768 -126.334012)
		(end 139.815062 -126.400306)
		(width 0.14224)
		(layer "In11.Cu")
		(net "M_M_DQ<54>")
	)
	(segment
		(start 139.71397 -131.307078)
		(end 139.81557 -131.408678)
		(width 0.14224)
		(layer "In11.Cu")
		(net "M_M_DQ<54>")
	)
	(segment
		(start 139.268454 -149.583394)
		(end 139.268454 -150.733252)
		(width 0.14224)
		(layer "In11.Cu")
		(net "M_M_DQ<54>")
	)
	(segment
		(start 119.130572 -105.234486)
		(end 119.135398 -105.243122)
		(width 0.0889)
		(layer "In11.Cu")
		(net "M_M_DQ<54>")
	)
	(segment
		(start 139.748768 -125.7554)
		(end 139.748768 -126.334012)
		(width 0.14224)
		(layer "In11.Cu")
		(net "M_M_DQ<54>")
	)
	(segment
		(start 138.91641 -151.247348)
		(end 138.91641 -153.834846)
		(width 0.14224)
		(layer "In11.Cu")
		(net "M_M_DQ<54>")
	)
	(segment
		(start 139.71397 -130.062478)
		(end 139.71397 -131.307078)
		(width 0.14224)
		(layer "In11.Cu")
		(net "M_M_DQ<54>")
	)
	(segment
		(start 130.178556 -118.348252)
		(end 133.40715 -118.348252)
		(width 0.14224)
		(layer "In11.Cu")
		(net "M_M_DQ<54>")
	)
	(segment
		(start 119.366792 -106.719624)
		(end 119.146066 -106.94035)
		(width 0.0889)
		(layer "In11.Cu")
		(net "M_M_DQ<54>")
	)
	(segment
		(start 139.443968 -124.151898)
		(end 139.443968 -125.4506)
		(width 0.14224)
		(layer "In11.Cu")
		(net "M_M_DQ<54>")
	)
	(segment
		(start 139.829286 -136.198864)
		(end 139.829286 -139.441682)
		(width 0.14224)
		(layer "In11.Cu")
		(net "M_M_DQ<54>")
	)
	(segment
		(start 139.701524 -144.283684)
		(end 139.701524 -145.641822)
		(width 0.14224)
		(layer "In11.Cu")
		(net "M_M_DQ<54>")
	)
	(arc
		(start 114.837972 -93.842586)
		(mid 114.891442 -94.037649)
		(end 114.842798 -94.234)
		(width 0.0889)
		(layer "In11.Cu")
		(net "M_M_DQ<54>")
	)
	(arc
		(start 119.130572 -102.662736)
		(mid 119.05135 -102.951854)
		(end 119.124222 -103.242618)
		(width 0.0889)
		(layer "In11.Cu")
		(net "M_M_DQ<54>")
	)
	(arc
		(start 115.696492 -96.319086)
		(mid 115.9051 -96.531018)
		(end 116.190522 -96.614488)
		(width 0.0889)
		(layer "In11.Cu")
		(net "M_M_DQ<54>")
	)
	(arc
		(start 119.135398 -99.299522)
		(mid 119.184153 -99.495874)
		(end 119.130572 -99.690936)
		(width 0.0889)
		(layer "In11.Cu")
		(net "M_M_DQ<54>")
	)
	(arc
		(start 118.795038 -98.100134)
		(mid 119.133207 -98.304932)
		(end 119.130572 -98.700336)
		(width 0.0889)
		(layer "In11.Cu")
		(net "M_M_DQ<54>")
	)
	(arc
		(start 119.135398 -103.261922)
		(mid 119.184153 -103.458274)
		(end 119.130572 -103.653336)
		(width 0.0889)
		(layer "In11.Cu")
		(net "M_M_DQ<54>")
	)
	(arc
		(start 119.135398 -104.252522)
		(mid 119.184153 -104.448874)
		(end 119.130572 -104.643936)
		(width 0.0889)
		(layer "In11.Cu")
		(net "M_M_DQ<54>")
	)
	(arc
		(start 114.144552 -91.861386)
		(mid 114.101979 -92.154161)
		(end 114.27206 -92.39631)
		(width 0.0889)
		(layer "In11.Cu")
		(net "M_M_DQ<54>")
	)
	(arc
		(start 119.135398 -102.271322)
		(mid 119.184153 -102.467674)
		(end 119.130572 -102.662736)
		(width 0.0889)
		(layer "In11.Cu")
		(net "M_M_DQ<54>")
	)
	(arc
		(start 119.130572 -105.634536)
		(mid 119.071505 -105.777022)
		(end 119.051324 -105.929938)
		(width 0.0889)
		(layer "In11.Cu")
		(net "M_M_DQ<54>")
	)
	(arc
		(start 114.651536 -92.685362)
		(mid 114.869895 -92.922333)
		(end 114.842798 -93.2434)
		(width 0.0889)
		(layer "In11.Cu")
		(net "M_M_DQ<54>")
	)
	(arc
		(start 119.135398 -101.280722)
		(mid 119.184153 -101.477074)
		(end 119.130572 -101.672136)
		(width 0.0889)
		(layer "In11.Cu")
		(net "M_M_DQ<54>")
	)
	(arc
		(start 119.130572 -103.653336)
		(mid 119.05135 -103.942454)
		(end 119.124222 -104.233218)
		(width 0.0889)
		(layer "In11.Cu")
		(net "M_M_DQ<54>")
	)
	(arc
		(start 116.223288 -96.614488)
		(mid 116.41493 -96.671654)
		(end 116.555012 -96.814386)
		(width 0.0889)
		(layer "In11.Cu")
		(net "M_M_DQ<54>")
	)
	(arc
		(start 114.837972 -94.833186)
		(mid 114.891471 -95.033084)
		(end 114.837972 -95.232982)
		(width 0.0889)
		(layer "In11.Cu")
		(net "M_M_DQ<54>")
	)
	(arc
		(start 116.555012 -96.814386)
		(mid 116.762016 -97.02525)
		(end 117.045232 -97.109534)
		(width 0.0889)
		(layer "In11.Cu")
		(net "M_M_DQ<54>")
	)
	(arc
		(start 119.130572 -100.681536)
		(mid 119.05135 -100.970654)
		(end 119.124222 -101.261418)
		(width 0.0889)
		(layer "In11.Cu")
		(net "M_M_DQ<54>")
	)
	(arc
		(start 119.130572 -104.643936)
		(mid 119.05135 -104.933054)
		(end 119.124222 -105.223818)
		(width 0.0889)
		(layer "In11.Cu")
		(net "M_M_DQ<54>")
	)
	(arc
		(start 114.837972 -95.232982)
		(mid 114.832718 -95.81449)
		(end 115.328192 -96.118934)
		(width 0.0889)
		(layer "In11.Cu")
		(net "M_M_DQ<54>")
	)
	(arc
		(start 114.406172 -92.501974)
		(mid 114.518261 -92.607844)
		(end 114.651536 -92.685362)
		(width 0.0889)
		(layer "In11.Cu")
		(net "M_M_DQ<54>")
	)
	(arc
		(start 117.077998 -97.109534)
		(mid 117.271848 -97.165884)
		(end 117.413532 -97.309686)
		(width 0.0889)
		(layer "In11.Cu")
		(net "M_M_DQ<54>")
	)
	(arc
		(start 117.940328 -97.605088)
		(mid 118.13197 -97.662254)
		(end 118.272052 -97.804986)
		(width 0.0889)
		(layer "In11.Cu")
		(net "M_M_DQ<54>")
	)
	(arc
		(start 114.831622 -93.262704)
		(mid 114.758824 -93.553467)
		(end 114.837972 -93.842586)
		(width 0.0889)
		(layer "In11.Cu")
		(net "M_M_DQ<54>")
	)
	(arc
		(start 119.130572 -98.700336)
		(mid 119.05135 -98.989454)
		(end 119.124222 -99.280218)
		(width 0.0889)
		(layer "In11.Cu")
		(net "M_M_DQ<54>")
	)
	(arc
		(start 118.272052 -97.804986)
		(mid 118.479056 -98.01585)
		(end 118.762272 -98.100134)
		(width 0.0889)
		(layer "In11.Cu")
		(net "M_M_DQ<54>")
	)
	(arc
		(start 115.360958 -96.118934)
		(mid 115.554808 -96.175284)
		(end 115.696492 -96.319086)
		(width 0.0889)
		(layer "In11.Cu")
		(net "M_M_DQ<54>")
	)
	(arc
		(start 119.130572 -99.690936)
		(mid 119.05135 -99.980054)
		(end 119.124222 -100.270818)
		(width 0.0889)
		(layer "In11.Cu")
		(net "M_M_DQ<54>")
	)
	(arc
		(start 114.150902 -91.281504)
		(mid 114.2237 -91.572267)
		(end 114.144552 -91.861386)
		(width 0.0889)
		(layer "In11.Cu")
		(net "M_M_DQ<54>")
	)
	(arc
		(start 114.837972 -94.242636)
		(mid 114.75875 -94.531754)
		(end 114.831622 -94.822518)
		(width 0.0889)
		(layer "In11.Cu")
		(net "M_M_DQ<54>")
	)
	(arc
		(start 114.144552 -90.870786)
		(mid 114.091082 -91.065849)
		(end 114.139726 -91.2622)
		(width 0.0889)
		(layer "In11.Cu")
		(net "M_M_DQ<54>")
	)
	(arc
		(start 117.413532 -97.309686)
		(mid 117.62214 -97.521618)
		(end 117.907562 -97.605088)
		(width 0.0889)
		(layer "In11.Cu")
		(net "M_M_DQ<54>")
	)
	(arc
		(start 114.27206 -92.39631)
		(mid 114.341436 -92.446196)
		(end 114.406172 -92.501974)
		(width 0.0889)
		(layer "In11.Cu")
		(net "M_M_DQ<54>")
	)
	(arc
		(start 119.135398 -105.243122)
		(mid 119.184153 -105.439474)
		(end 119.130572 -105.634536)
		(width 0.0889)
		(layer "In11.Cu")
		(net "M_M_DQ<54>")
	)
	(arc
		(start 119.135398 -100.290122)
		(mid 119.184153 -100.486474)
		(end 119.130572 -100.681536)
		(width 0.0889)
		(layer "In11.Cu")
		(net "M_M_DQ<54>")
	)
	(arc
		(start 119.130572 -101.672136)
		(mid 119.05135 -101.961254)
		(end 119.124222 -102.252018)
		(width 0.0889)
		(layer "In11.Cu")
		(net "M_M_DQ<54>")
	)
	(segment
		(start 133.39953 -152.273)
		(end 133.39953 -153.542746)
		(width 0.1651)
		(layer "F.Cu")
		(net "M_M_DQ<53>")
	)
	(segment
		(start 111.344202 -91.565984)
		(end 111.915702 -91.565984)
		(width 0.1651)
		(layer "F.Cu")
		(net "M_M_DQ<53>")
	)
	(via
		(at 133.39953 -153.542746)
		(size 0.508)
		(drill 0.254)
		(layers "F.Cu" "B.Cu")
		(net "M_M_DQ<53>")
	)
	(via
		(at 111.915702 -91.565984)
		(size 0.508)
		(drill 0.254)
		(layers "F.Cu" "B.Cu")
		(net "M_M_DQ<53>")
	)
	(via
		(at 134.173214 -149.533356)
		(size 0.508)
		(drill 0.254)
		(layers "F.Cu" "B.Cu")
		(net "M_M_DQ<53>")
	)
	(segment
		(start 134.249414 -147.478496)
		(end 134.249414 -149.457156)
		(width 0.1651)
		(layer "B.Cu")
		(net "M_M_DQ<53>")
	)
	(segment
		(start 134.249414 -149.457156)
		(end 134.173214 -149.533356)
		(width 0.1651)
		(layer "B.Cu")
		(net "M_M_DQ<53>")
	)
	(segment
		(start 111.568992 -94.737936)
		(end 111.575342 -94.748604)
		(width 0.0889)
		(layer "In11.Cu")
		(net "M_M_DQ<53>")
	)
	(segment
		(start 115.861592 -103.158036)
		(end 115.867942 -103.168704)
		(width 0.0889)
		(layer "In11.Cu")
		(net "M_M_DQ<53>")
	)
	(segment
		(start 133.486144 -123.320048)
		(end 133.716014 -123.320048)
		(width 0.14224)
		(layer "In11.Cu")
		(net "M_M_DQ<53>")
	)
	(segment
		(start 134.071868 -123.675902)
		(end 134.071868 -123.883928)
		(width 0.14224)
		(layer "In11.Cu")
		(net "M_M_DQ<53>")
	)
	(segment
		(start 113.617756 -98.900234)
		(end 113.650522 -98.900234)
		(width 0.0889)
		(layer "In11.Cu")
		(net "M_M_DQ<53>")
	)
	(segment
		(start 134.795768 -148.2852)
		(end 134.55777 -148.523198)
		(width 0.14224)
		(layer "In11.Cu")
		(net "M_M_DQ<53>")
	)
	(segment
		(start 115.334796 -99.890834)
		(end 115.367562 -99.890834)
		(width 0.0889)
		(layer "In11.Cu")
		(net "M_M_DQ<53>")
	)
	(segment
		(start 134.94131 -132.110988)
		(end 134.94131 -132.409438)
		(width 0.14224)
		(layer "In11.Cu")
		(net "M_M_DQ<53>")
	)
	(segment
		(start 134.64667 -131.370578)
		(end 134.58317 -131.434078)
		(width 0.14224)
		(layer "In11.Cu")
		(net "M_M_DQ<53>")
	)
	(segment
		(start 134.58317 -131.752848)
		(end 134.94131 -132.110988)
		(width 0.14224)
		(layer "In11.Cu")
		(net "M_M_DQ<53>")
	)
	(segment
		(start 134.78637 -133.377178)
		(end 134.94131 -133.532118)
		(width 0.14224)
		(layer "In11.Cu")
		(net "M_M_DQ<53>")
	)
	(segment
		(start 134.459218 -132.719318)
		(end 134.459218 -133.222238)
		(width 0.14224)
		(layer "In11.Cu")
		(net "M_M_DQ<53>")
	)
	(segment
		(start 115.861592 -102.167436)
		(end 115.867942 -102.178104)
		(width 0.0889)
		(layer "In11.Cu")
		(net "M_M_DQ<53>")
	)
	(segment
		(start 115.861592 -104.148636)
		(end 115.867942 -104.159304)
		(width 0.0889)
		(layer "In11.Cu")
		(net "M_M_DQ<53>")
	)
	(segment
		(start 134.902448 -128.7526)
		(end 134.902448 -129.05232)
		(width 0.14224)
		(layer "In11.Cu")
		(net "M_M_DQ<53>")
	)
	(segment
		(start 133.824218 -153.162254)
		(end 133.824218 -153.390346)
		(width 0.14224)
		(layer "In11.Cu")
		(net "M_M_DQ<53>")
	)
	(segment
		(start 134.902448 -129.05232)
		(end 134.58317 -129.371598)
		(width 0.14224)
		(layer "In11.Cu")
		(net "M_M_DQ<53>")
	)
	(segment
		(start 134.173214 -149.533356)
		(end 134.150862 -149.533356)
		(width 0.14224)
		(layer "In11.Cu")
		(net "M_M_DQ<53>")
	)
	(segment
		(start 134.58317 -129.920238)
		(end 134.64667 -129.983738)
		(width 0.14224)
		(layer "In11.Cu")
		(net "M_M_DQ<53>")
	)
	(segment
		(start 134.440676 -128.569212)
		(end 134.71906 -128.569212)
		(width 0.14224)
		(layer "In11.Cu")
		(net "M_M_DQ<53>")
	)
	(segment
		(start 134.94131 -133.843014)
		(end 134.58317 -134.201154)
		(width 0.14224)
		(layer "In11.Cu")
		(net "M_M_DQ<53>")
	)
	(segment
		(start 115.132866 -105.936542)
		(end 115.132866 -106.488738)
		(width 0.0889)
		(layer "In11.Cu")
		(net "M_M_DQ<53>")
	)
	(segment
		(start 134.64667 -135.938768)
		(end 134.55777 -136.027668)
		(width 0.14224)
		(layer "In11.Cu")
		(net "M_M_DQ<53>")
	)
	(segment
		(start 115.856766 -103.1494)
		(end 115.861592 -103.158036)
		(width 0.0889)
		(layer "In11.Cu")
		(net "M_M_DQ<53>")
	)
	(segment
		(start 132.74294 -123.854718)
		(end 132.951474 -123.854718)
		(width 0.14224)
		(layer "In11.Cu")
		(net "M_M_DQ<53>")
	)
	(segment
		(start 133.722618 -150.5204)
		(end 133.849618 -150.6474)
		(width 0.14224)
		(layer "In11.Cu")
		(net "M_M_DQ<53>")
	)
	(segment
		(start 134.459218 -133.222238)
		(end 134.614158 -133.377178)
		(width 0.14224)
		(layer "In11.Cu")
		(net "M_M_DQ<53>")
	)
	(segment
		(start 111.900716 -97.909634)
		(end 111.933482 -97.909634)
		(width 0.0889)
		(layer "In11.Cu")
		(net "M_M_DQ<53>")
	)
	(segment
		(start 133.849618 -150.6474)
		(end 133.849618 -151.129746)
		(width 0.14224)
		(layer "In11.Cu")
		(net "M_M_DQ<53>")
	)
	(segment
		(start 134.58317 -131.434078)
		(end 134.58317 -131.752848)
		(width 0.14224)
		(layer "In11.Cu")
		(net "M_M_DQ<53>")
	)
	(segment
		(start 111.568992 -93.347286)
		(end 111.564166 -93.355922)
		(width 0.0889)
		(layer "In11.Cu")
		(net "M_M_DQ<53>")
	)
	(segment
		(start 134.668768 -141.588998)
		(end 134.668768 -143.7386)
		(width 0.14224)
		(layer "In11.Cu")
		(net "M_M_DQ<53>")
	)
	(segment
		(start 133.798818 -152.348946)
		(end 133.56082 -152.586944)
		(width 0.14224)
		(layer "In11.Cu")
		(net "M_M_DQ<53>")
	)
	(segment
		(start 133.56082 -152.898856)
		(end 133.824218 -153.162254)
		(width 0.14224)
		(layer "In11.Cu")
		(net "M_M_DQ<53>")
	)
	(segment
		(start 115.018312 -107.509056)
		(end 115.018312 -113.967514)
		(width 0.14224)
		(layer "In11.Cu")
		(net "M_M_DQ<53>")
	)
	(segment
		(start 115.132866 -106.488738)
		(end 115.364768 -106.72064)
		(width 0.0889)
		(layer "In11.Cu")
		(net "M_M_DQ<53>")
	)
	(segment
		(start 111.575342 -96.308418)
		(end 111.568992 -96.319086)
		(width 0.0889)
		(layer "In11.Cu")
		(net "M_M_DQ<53>")
	)
	(segment
		(start 115.856766 -104.14)
		(end 115.861592 -104.148636)
		(width 0.0889)
		(layer "In11.Cu")
		(net "M_M_DQ<53>")
	)
	(segment
		(start 134.071868 -123.883928)
		(end 134.617968 -124.430028)
		(width 0.14224)
		(layer "In11.Cu")
		(net "M_M_DQ<53>")
	)
	(segment
		(start 134.58317 -129.371598)
		(end 134.58317 -129.920238)
		(width 0.14224)
		(layer "In11.Cu")
		(net "M_M_DQ<53>")
	)
	(segment
		(start 133.716014 -123.320048)
		(end 134.071868 -123.675902)
		(width 0.14224)
		(layer "In11.Cu")
		(net "M_M_DQ<53>")
	)
	(segment
		(start 111.568992 -95.328486)
		(end 111.564166 -95.337122)
		(width 0.0889)
		(layer "In11.Cu")
		(net "M_M_DQ<53>")
	)
	(segment
		(start 134.278624 -125.866144)
		(end 134.278624 -128.40716)
		(width 0.14224)
		(layer "In11.Cu")
		(net "M_M_DQ<53>")
	)
	(segment
		(start 134.64667 -129.983738)
		(end 134.64667 -131.370578)
		(width 0.14224)
		(layer "In11.Cu")
		(net "M_M_DQ<53>")
	)
	(segment
		(start 134.58317 -144.271238)
		(end 134.71017 -144.398238)
		(width 0.14224)
		(layer "In11.Cu")
		(net "M_M_DQ<53>")
	)
	(segment
		(start 133.56082 -152.586944)
		(end 133.56082 -152.898856)
		(width 0.14224)
		(layer "In11.Cu")
		(net "M_M_DQ<53>")
	)
	(segment
		(start 134.614158 -132.564378)
		(end 134.459218 -132.719318)
		(width 0.14224)
		(layer "In11.Cu")
		(net "M_M_DQ<53>")
	)
	(segment
		(start 134.58317 -143.824198)
		(end 134.58317 -144.271238)
		(width 0.14224)
		(layer "In11.Cu")
		(net "M_M_DQ<53>")
	)
	(segment
		(start 133.798818 -151.993854)
		(end 133.798818 -152.348946)
		(width 0.14224)
		(layer "In11.Cu")
		(net "M_M_DQ<53>")
	)
	(segment
		(start 115.364768 -107.1626)
		(end 115.018312 -107.509056)
		(width 0.14224)
		(layer "In11.Cu")
		(net "M_M_DQ<53>")
	)
	(segment
		(start 133.824218 -153.390346)
		(end 133.671818 -153.542746)
		(width 0.14224)
		(layer "In11.Cu")
		(net "M_M_DQ<53>")
	)
	(segment
		(start 134.55777 -136.027668)
		(end 134.55777 -139.308078)
		(width 0.14224)
		(layer "In11.Cu")
		(net "M_M_DQ<53>")
	)
	(segment
		(start 134.795768 -146.364198)
		(end 134.795768 -148.2852)
		(width 0.14224)
		(layer "In11.Cu")
		(net "M_M_DQ<53>")
	)
	(segment
		(start 111.915702 -91.565984)
		(end 111.586264 -92.326968)
		(width 0.0889)
		(layer "In11.Cu")
		(net "M_M_DQ<53>")
	)
	(segment
		(start 134.617968 -125.5268)
		(end 134.278624 -125.866144)
		(width 0.14224)
		(layer "In11.Cu")
		(net "M_M_DQ<53>")
	)
	(segment
		(start 134.71017 -145.454624)
		(end 134.55777 -145.607024)
		(width 0.14224)
		(layer "In11.Cu")
		(net "M_M_DQ<53>")
	)
	(segment
		(start 112.763046 -98.405188)
		(end 112.795812 -98.405188)
		(width 0.0889)
		(layer "In11.Cu")
		(net "M_M_DQ<53>")
	)
	(segment
		(start 134.278624 -128.40716)
		(end 134.440676 -128.569212)
		(width 0.14224)
		(layer "In11.Cu")
		(net "M_M_DQ<53>")
	)
	(segment
		(start 133.56082 -151.418544)
		(end 133.56082 -151.755856)
		(width 0.14224)
		(layer "In11.Cu")
		(net "M_M_DQ<53>")
	)
	(segment
		(start 134.55777 -149.1488)
		(end 134.173214 -149.533356)
		(width 0.14224)
		(layer "In11.Cu")
		(net "M_M_DQ<53>")
	)
	(segment
		(start 134.58317 -141.5034)
		(end 134.668768 -141.588998)
		(width 0.14224)
		(layer "In11.Cu")
		(net "M_M_DQ<53>")
	)
	(segment
		(start 132.388102 -123.49988)
		(end 132.74294 -123.854718)
		(width 0.14224)
		(layer "In11.Cu")
		(net "M_M_DQ<53>")
	)
	(segment
		(start 134.94131 -133.532118)
		(end 134.94131 -133.843014)
		(width 0.14224)
		(layer "In11.Cu")
		(net "M_M_DQ<53>")
	)
	(segment
		(start 134.55777 -139.308078)
		(end 134.64667 -139.396978)
		(width 0.14224)
		(layer "In11.Cu")
		(net "M_M_DQ<53>")
	)
	(segment
		(start 134.58317 -134.201154)
		(end 134.58317 -134.617968)
		(width 0.14224)
		(layer "In11.Cu")
		(net "M_M_DQ<53>")
	)
	(segment
		(start 115.018312 -113.967514)
		(end 124.550678 -123.49988)
		(width 0.14224)
		(layer "In11.Cu")
		(net "M_M_DQ<53>")
	)
	(segment
		(start 111.568992 -97.309686)
		(end 111.564166 -97.318322)
		(width 0.0889)
		(layer "In11.Cu")
		(net "M_M_DQ<53>")
	)
	(segment
		(start 115.807998 -105.26141)
		(end 115.132866 -105.936542)
		(width 0.0889)
		(layer "In11.Cu")
		(net "M_M_DQ<53>")
	)
	(segment
		(start 134.668768 -143.7386)
		(end 134.58317 -143.824198)
		(width 0.14224)
		(layer "In11.Cu")
		(net "M_M_DQ<53>")
	)
	(segment
		(start 115.364768 -106.72064)
		(end 115.364768 -107.1626)
		(width 0.14224)
		(layer "In11.Cu")
		(net "M_M_DQ<53>")
	)
	(segment
		(start 111.575342 -93.336618)
		(end 111.568992 -93.347286)
		(width 0.0889)
		(layer "In11.Cu")
		(net "M_M_DQ<53>")
	)
	(segment
		(start 134.71017 -144.398238)
		(end 134.71017 -145.454624)
		(width 0.14224)
		(layer "In11.Cu")
		(net "M_M_DQ<53>")
	)
	(segment
		(start 124.550678 -123.49988)
		(end 132.388102 -123.49988)
		(width 0.14224)
		(layer "In11.Cu")
		(net "M_M_DQ<53>")
	)
	(segment
		(start 133.56082 -151.755856)
		(end 133.798818 -151.993854)
		(width 0.14224)
		(layer "In11.Cu")
		(net "M_M_DQ<53>")
	)
	(segment
		(start 134.614158 -133.377178)
		(end 134.78637 -133.377178)
		(width 0.14224)
		(layer "In11.Cu")
		(net "M_M_DQ<53>")
	)
	(segment
		(start 115.856766 -102.1588)
		(end 115.861592 -102.167436)
		(width 0.0889)
		(layer "In11.Cu")
		(net "M_M_DQ<53>")
	)
	(segment
		(start 133.849618 -151.129746)
		(end 133.56082 -151.418544)
		(width 0.14224)
		(layer "In11.Cu")
		(net "M_M_DQ<53>")
	)
	(segment
		(start 134.150862 -149.533356)
		(end 133.722618 -149.9616)
		(width 0.14224)
		(layer "In11.Cu")
		(net "M_M_DQ<53>")
	)
	(segment
		(start 115.807998 -104.939338)
		(end 115.807998 -105.26141)
		(width 0.0889)
		(layer "In11.Cu")
		(net "M_M_DQ<53>")
	)
	(segment
		(start 134.617968 -124.430028)
		(end 134.617968 -125.5268)
		(width 0.14224)
		(layer "In11.Cu")
		(net "M_M_DQ<53>")
	)
	(segment
		(start 111.568992 -96.319086)
		(end 111.564166 -96.327722)
		(width 0.0889)
		(layer "In11.Cu")
		(net "M_M_DQ<53>")
	)
	(segment
		(start 134.64667 -139.396978)
		(end 134.64667 -140.971778)
		(width 0.14224)
		(layer "In11.Cu")
		(net "M_M_DQ<53>")
	)
	(segment
		(start 134.55777 -145.607024)
		(end 134.55777 -146.1262)
		(width 0.14224)
		(layer "In11.Cu")
		(net "M_M_DQ<53>")
	)
	(segment
		(start 134.94131 -132.409438)
		(end 134.78637 -132.564378)
		(width 0.14224)
		(layer "In11.Cu")
		(net "M_M_DQ<53>")
	)
	(segment
		(start 134.64667 -134.681468)
		(end 134.64667 -135.938768)
		(width 0.14224)
		(layer "In11.Cu")
		(net "M_M_DQ<53>")
	)
	(segment
		(start 134.55777 -146.1262)
		(end 134.795768 -146.364198)
		(width 0.14224)
		(layer "In11.Cu")
		(net "M_M_DQ<53>")
	)
	(segment
		(start 111.586264 -92.326968)
		(end 111.564166 -92.365322)
		(width 0.0889)
		(layer "In11.Cu")
		(net "M_M_DQ<53>")
	)
	(segment
		(start 134.71906 -128.569212)
		(end 134.902448 -128.7526)
		(width 0.14224)
		(layer "In11.Cu")
		(net "M_M_DQ<53>")
	)
	(segment
		(start 134.78637 -132.564378)
		(end 134.614158 -132.564378)
		(width 0.14224)
		(layer "In11.Cu")
		(net "M_M_DQ<53>")
	)
	(segment
		(start 134.55777 -148.523198)
		(end 134.55777 -149.1488)
		(width 0.14224)
		(layer "In11.Cu")
		(net "M_M_DQ<53>")
	)
	(segment
		(start 132.951474 -123.854718)
		(end 133.486144 -123.320048)
		(width 0.14224)
		(layer "In11.Cu")
		(net "M_M_DQ<53>")
	)
	(segment
		(start 134.58317 -134.617968)
		(end 134.64667 -134.681468)
		(width 0.14224)
		(layer "In11.Cu")
		(net "M_M_DQ<53>")
	)
	(segment
		(start 133.722618 -149.9616)
		(end 133.722618 -150.5204)
		(width 0.14224)
		(layer "In11.Cu")
		(net "M_M_DQ<53>")
	)
	(segment
		(start 134.64667 -140.971778)
		(end 134.58317 -141.035278)
		(width 0.14224)
		(layer "In11.Cu")
		(net "M_M_DQ<53>")
	)
	(segment
		(start 115.861592 -101.176836)
		(end 115.867942 -101.187504)
		(width 0.0889)
		(layer "In11.Cu")
		(net "M_M_DQ<53>")
	)
	(segment
		(start 133.671818 -153.542746)
		(end 133.39953 -153.542746)
		(width 0.14224)
		(layer "In11.Cu")
		(net "M_M_DQ<53>")
	)
	(segment
		(start 134.58317 -141.035278)
		(end 134.58317 -141.5034)
		(width 0.14224)
		(layer "In11.Cu")
		(net "M_M_DQ<53>")
	)
	(segment
		(start 115.856766 -101.1682)
		(end 115.861592 -101.176836)
		(width 0.0889)
		(layer "In11.Cu")
		(net "M_M_DQ<53>")
	)
	(segment
		(start 114.480086 -99.395788)
		(end 114.512852 -99.395788)
		(width 0.0889)
		(layer "In11.Cu")
		(net "M_M_DQ<53>")
	)
	(segment
		(start 111.575342 -97.299018)
		(end 111.568992 -97.309686)
		(width 0.0889)
		(layer "In11.Cu")
		(net "M_M_DQ<53>")
	)
	(arc
		(start 111.568992 -95.728536)
		(mid 111.648214 -96.017654)
		(end 111.575342 -96.308418)
		(width 0.0889)
		(layer "In11.Cu")
		(net "M_M_DQ<53>")
	)
	(arc
		(start 111.575342 -94.748604)
		(mid 111.64814 -95.039367)
		(end 111.568992 -95.328486)
		(width 0.0889)
		(layer "In11.Cu")
		(net "M_M_DQ<53>")
	)
	(arc
		(start 113.286032 -98.700336)
		(mid 113.426111 -98.843072)
		(end 113.617756 -98.900234)
		(width 0.0889)
		(layer "In11.Cu")
		(net "M_M_DQ<53>")
	)
	(arc
		(start 115.867942 -103.168704)
		(mid 115.94074 -103.459467)
		(end 115.861592 -103.748586)
		(width 0.0889)
		(layer "In11.Cu")
		(net "M_M_DQ<53>")
	)
	(arc
		(start 111.564166 -95.337122)
		(mid 111.515411 -95.533474)
		(end 111.568992 -95.728536)
		(width 0.0889)
		(layer "In11.Cu")
		(net "M_M_DQ<53>")
	)
	(arc
		(start 111.564166 -97.318322)
		(mid 111.567913 -97.707578)
		(end 111.900716 -97.909634)
		(width 0.0889)
		(layer "In11.Cu")
		(net "M_M_DQ<53>")
	)
	(arc
		(start 111.564166 -92.365322)
		(mid 111.515411 -92.561674)
		(end 111.568992 -92.756736)
		(width 0.0889)
		(layer "In11.Cu")
		(net "M_M_DQ<53>")
	)
	(arc
		(start 114.144552 -99.195636)
		(mid 114.286235 -99.33944)
		(end 114.480086 -99.395788)
		(width 0.0889)
		(layer "In11.Cu")
		(net "M_M_DQ<53>")
	)
	(arc
		(start 115.861592 -103.748586)
		(mid 115.808122 -103.943649)
		(end 115.856766 -104.14)
		(width 0.0889)
		(layer "In11.Cu")
		(net "M_M_DQ<53>")
	)
	(arc
		(start 115.367562 -99.890834)
		(mid 115.865813 -100.193674)
		(end 115.861592 -100.776786)
		(width 0.0889)
		(layer "In11.Cu")
		(net "M_M_DQ<53>")
	)
	(arc
		(start 113.650522 -98.900234)
		(mid 113.935946 -98.983701)
		(end 114.144552 -99.195636)
		(width 0.0889)
		(layer "In11.Cu")
		(net "M_M_DQ<53>")
	)
	(arc
		(start 115.861592 -104.739186)
		(mid 115.821605 -104.835732)
		(end 115.807998 -104.939338)
		(width 0.0889)
		(layer "In11.Cu")
		(net "M_M_DQ<53>")
	)
	(arc
		(start 114.512852 -99.395788)
		(mid 114.796069 -99.480069)
		(end 115.003072 -99.690936)
		(width 0.0889)
		(layer "In11.Cu")
		(net "M_M_DQ<53>")
	)
	(arc
		(start 111.933482 -97.909634)
		(mid 112.218906 -97.993101)
		(end 112.427512 -98.205036)
		(width 0.0889)
		(layer "In11.Cu")
		(net "M_M_DQ<53>")
	)
	(arc
		(start 111.564166 -96.327722)
		(mid 111.515411 -96.524074)
		(end 111.568992 -96.719136)
		(width 0.0889)
		(layer "In11.Cu")
		(net "M_M_DQ<53>")
	)
	(arc
		(start 115.861592 -100.776786)
		(mid 115.808122 -100.971849)
		(end 115.856766 -101.1682)
		(width 0.0889)
		(layer "In11.Cu")
		(net "M_M_DQ<53>")
	)
	(arc
		(start 115.861592 -102.757986)
		(mid 115.808122 -102.953049)
		(end 115.856766 -103.1494)
		(width 0.0889)
		(layer "In11.Cu")
		(net "M_M_DQ<53>")
	)
	(arc
		(start 115.867942 -104.159304)
		(mid 115.94074 -104.450067)
		(end 115.861592 -104.739186)
		(width 0.0889)
		(layer "In11.Cu")
		(net "M_M_DQ<53>")
	)
	(arc
		(start 111.568992 -96.719136)
		(mid 111.648214 -97.008254)
		(end 111.575342 -97.299018)
		(width 0.0889)
		(layer "In11.Cu")
		(net "M_M_DQ<53>")
	)
	(arc
		(start 112.795812 -98.405188)
		(mid 113.079029 -98.489469)
		(end 113.286032 -98.700336)
		(width 0.0889)
		(layer "In11.Cu")
		(net "M_M_DQ<53>")
	)
	(arc
		(start 115.003072 -99.690936)
		(mid 115.143151 -99.833672)
		(end 115.334796 -99.890834)
		(width 0.0889)
		(layer "In11.Cu")
		(net "M_M_DQ<53>")
	)
	(arc
		(start 111.568992 -92.756736)
		(mid 111.648214 -93.045854)
		(end 111.575342 -93.336618)
		(width 0.0889)
		(layer "In11.Cu")
		(net "M_M_DQ<53>")
	)
	(arc
		(start 115.867942 -101.187504)
		(mid 115.94074 -101.478267)
		(end 115.861592 -101.767386)
		(width 0.0889)
		(layer "In11.Cu")
		(net "M_M_DQ<53>")
	)
	(arc
		(start 111.568992 -93.747336)
		(mid 111.648123 -94.042738)
		(end 111.568992 -94.33814)
		(width 0.0889)
		(layer "In11.Cu")
		(net "M_M_DQ<53>")
	)
	(arc
		(start 111.564166 -93.355922)
		(mid 111.515411 -93.552274)
		(end 111.568992 -93.747336)
		(width 0.0889)
		(layer "In11.Cu")
		(net "M_M_DQ<53>")
	)
	(arc
		(start 111.568992 -94.33814)
		(mid 111.515493 -94.538038)
		(end 111.568992 -94.737936)
		(width 0.0889)
		(layer "In11.Cu")
		(net "M_M_DQ<53>")
	)
	(arc
		(start 115.867942 -102.178104)
		(mid 115.94074 -102.468867)
		(end 115.861592 -102.757986)
		(width 0.0889)
		(layer "In11.Cu")
		(net "M_M_DQ<53>")
	)
	(arc
		(start 115.861592 -101.767386)
		(mid 115.808122 -101.962449)
		(end 115.856766 -102.1588)
		(width 0.0889)
		(layer "In11.Cu")
		(net "M_M_DQ<53>")
	)
	(arc
		(start 112.427512 -98.205036)
		(mid 112.569195 -98.34884)
		(end 112.763046 -98.405188)
		(width 0.0889)
		(layer "In11.Cu")
		(net "M_M_DQ<53>")
	)
	(segment
		(start 111.344202 -90.575384)
		(end 111.915702 -90.575384)
		(width 0.1651)
		(layer "F.Cu")
		(net "M_M_DQ<52>")
	)
	(segment
		(start 134.249414 -156.87294)
		(end 134.249414 -155.547568)
		(width 0.1651)
		(layer "F.Cu")
		(net "M_M_DQ<52>")
	)
	(segment
		(start 134.249414 -155.547568)
		(end 134.15137 -155.0162)
		(width 0.1651)
		(layer "F.Cu")
		(net "M_M_DQ<52>")
	)
	(via
		(at 111.915702 -90.575384)
		(size 0.508)
		(drill 0.254)
		(layers "F.Cu" "B.Cu")
		(net "M_M_DQ<52>")
	)
	(via
		(at 134.15137 -155.0162)
		(size 0.508)
		(drill 0.254)
		(layers "F.Cu" "B.Cu")
		(net "M_M_DQ<52>")
	)
	(via
		(at 133.39953 -150.814278)
		(size 0.508)
		(drill 0.254)
		(layers "F.Cu" "B.Cu")
		(net "M_M_DQ<52>")
	)
	(segment
		(start 133.39953 -152.078436)
		(end 133.39953 -150.814278)
		(width 0.1651)
		(layer "B.Cu")
		(net "M_M_DQ<52>")
	)
	(segment
		(start 111.403892 -93.252036)
		(end 111.397542 -93.262704)
		(width 0.0889)
		(layer "In11.Cu")
		(net "M_M_DQ<52>")
	)
	(segment
		(start 115.696492 -103.253286)
		(end 115.701318 -103.261922)
		(width 0.0889)
		(layer "In11.Cu")
		(net "M_M_DQ<52>")
	)
	(segment
		(start 133.551168 -144.4244)
		(end 133.551168 -145.447766)
		(width 0.14224)
		(layer "In11.Cu")
		(net "M_M_DQ<52>")
	)
	(segment
		(start 133.88467 -148.993098)
		(end 133.601968 -149.2758)
		(width 0.14224)
		(layer "In11.Cu")
		(net "M_M_DQ<52>")
	)
	(segment
		(start 133.08457 -149.488398)
		(end 133.08457 -150.499318)
		(width 0.14224)
		(layer "In11.Cu")
		(net "M_M_DQ<52>")
	)
	(segment
		(start 115.617244 -104.939338)
		(end 115.617244 -105.182162)
		(width 0.0889)
		(layer "In11.Cu")
		(net "M_M_DQ<52>")
	)
	(segment
		(start 114.942366 -105.85704)
		(end 114.942366 -106.39679)
		(width 0.0889)
		(layer "In11.Cu")
		(net "M_M_DQ<52>")
	)
	(segment
		(start 133.66877 -134.705852)
		(end 133.66877 -135.951468)
		(width 0.14224)
		(layer "In11.Cu")
		(net "M_M_DQ<52>")
	)
	(segment
		(start 133.88467 -145.781268)
		(end 133.88467 -148.993098)
		(width 0.14224)
		(layer "In11.Cu")
		(net "M_M_DQ<52>")
	)
	(segment
		(start 111.420656 -91.241372)
		(end 111.403892 -91.270836)
		(width 0.0889)
		(layer "In11.Cu")
		(net "M_M_DQ<52>")
	)
	(segment
		(start 111.408718 -96.2152)
		(end 111.403892 -96.223836)
		(width 0.0889)
		(layer "In11.Cu")
		(net "M_M_DQ<52>")
	)
	(segment
		(start 115.690142 -104.233218)
		(end 115.696492 -104.243886)
		(width 0.0889)
		(layer "In11.Cu")
		(net "M_M_DQ<52>")
	)
	(segment
		(start 115.328192 -100.081334)
		(end 115.360958 -100.081334)
		(width 0.0889)
		(layer "In11.Cu")
		(net "M_M_DQ<52>")
	)
	(segment
		(start 133.89737 -129.3876)
		(end 133.89737 -129.767838)
		(width 0.14224)
		(layer "In11.Cu")
		(net "M_M_DQ<52>")
	)
	(segment
		(start 124.180854 -124.0282)
		(end 132.230622 -124.0282)
		(width 0.14224)
		(layer "In11.Cu")
		(net "M_M_DQ<52>")
	)
	(segment
		(start 133.124448 -153.938478)
		(end 133.124448 -154.24023)
		(width 0.14224)
		(layer "In11.Cu")
		(net "M_M_DQ<52>")
	)
	(segment
		(start 133.890004 -139.462764)
		(end 133.551168 -139.8016)
		(width 0.14224)
		(layer "In11.Cu")
		(net "M_M_DQ<52>")
	)
	(segment
		(start 134.042912 -141.15542)
		(end 134.042912 -141.443202)
		(width 0.14224)
		(layer "In11.Cu")
		(net "M_M_DQ<52>")
	)
	(segment
		(start 133.39953 -150.814278)
		(end 132.96646 -151.247348)
		(width 0.14224)
		(layer "In11.Cu")
		(net "M_M_DQ<52>")
	)
	(segment
		(start 133.08457 -150.499318)
		(end 133.39953 -150.814278)
		(width 0.14224)
		(layer "In11.Cu")
		(net "M_M_DQ<52>")
	)
	(segment
		(start 114.383312 -114.230658)
		(end 124.180854 -124.0282)
		(width 0.14224)
		(layer "In11.Cu")
		(net "M_M_DQ<52>")
	)
	(segment
		(start 115.696492 -104.243886)
		(end 115.701318 -104.252522)
		(width 0.0889)
		(layer "In11.Cu")
		(net "M_M_DQ<52>")
	)
	(segment
		(start 132.96646 -151.247348)
		(end 132.96646 -153.78049)
		(width 0.14224)
		(layer "In11.Cu")
		(net "M_M_DQ<52>")
	)
	(segment
		(start 133.66877 -129.996438)
		(end 133.66877 -131.180078)
		(width 0.14224)
		(layer "In11.Cu")
		(net "M_M_DQ<52>")
	)
	(segment
		(start 133.830568 -141.655546)
		(end 133.830568 -143.6624)
		(width 0.14224)
		(layer "In11.Cu")
		(net "M_M_DQ<52>")
	)
	(segment
		(start 112.756442 -98.595688)
		(end 112.789208 -98.595688)
		(width 0.0889)
		(layer "In11.Cu")
		(net "M_M_DQ<52>")
	)
	(segment
		(start 133.691122 -129.181352)
		(end 133.89737 -129.3876)
		(width 0.14224)
		(layer "In11.Cu")
		(net "M_M_DQ<52>")
	)
	(segment
		(start 133.124448 -154.24023)
		(end 133.900418 -155.0162)
		(width 0.14224)
		(layer "In11.Cu")
		(net "M_M_DQ<52>")
	)
	(segment
		(start 115.690142 -101.261418)
		(end 115.696492 -101.272086)
		(width 0.0889)
		(layer "In11.Cu")
		(net "M_M_DQ<52>")
	)
	(segment
		(start 133.830568 -143.6624)
		(end 133.89737 -143.729202)
		(width 0.14224)
		(layer "In11.Cu")
		(net "M_M_DQ<52>")
	)
	(segment
		(start 115.690142 -102.252018)
		(end 115.696492 -102.262686)
		(width 0.0889)
		(layer "In11.Cu")
		(net "M_M_DQ<52>")
	)
	(segment
		(start 133.66877 -131.180078)
		(end 133.89737 -131.408678)
		(width 0.14224)
		(layer "In11.Cu")
		(net "M_M_DQ<52>")
	)
	(segment
		(start 111.408718 -97.2058)
		(end 111.403892 -97.214436)
		(width 0.0889)
		(layer "In11.Cu")
		(net "M_M_DQ<52>")
	)
	(segment
		(start 133.89737 -143.729202)
		(end 133.89737 -144.078198)
		(width 0.14224)
		(layer "In11.Cu")
		(net "M_M_DQ<52>")
	)
	(segment
		(start 133.551168 -145.447766)
		(end 133.88467 -145.781268)
		(width 0.14224)
		(layer "In11.Cu")
		(net "M_M_DQ<52>")
	)
	(segment
		(start 114.674142 -106.665014)
		(end 114.383312 -106.955844)
		(width 0.14224)
		(layer "In11.Cu")
		(net "M_M_DQ<52>")
	)
	(segment
		(start 133.66877 -135.951468)
		(end 133.890004 -136.172702)
		(width 0.14224)
		(layer "In11.Cu")
		(net "M_M_DQ<52>")
	)
	(segment
		(start 133.601968 -149.2758)
		(end 133.297168 -149.2758)
		(width 0.14224)
		(layer "In11.Cu")
		(net "M_M_DQ<52>")
	)
	(segment
		(start 133.551168 -140.663676)
		(end 134.042912 -141.15542)
		(width 0.14224)
		(layer "In11.Cu")
		(net "M_M_DQ<52>")
	)
	(segment
		(start 115.690142 -103.242618)
		(end 115.696492 -103.253286)
		(width 0.0889)
		(layer "In11.Cu")
		(net "M_M_DQ<52>")
	)
	(segment
		(start 133.89737 -131.408678)
		(end 133.89737 -134.477252)
		(width 0.14224)
		(layer "In11.Cu")
		(net "M_M_DQ<52>")
	)
	(segment
		(start 115.617244 -105.182162)
		(end 114.942366 -105.85704)
		(width 0.0889)
		(layer "In11.Cu")
		(net "M_M_DQ<52>")
	)
	(segment
		(start 133.900418 -155.0162)
		(end 134.15137 -155.0162)
		(width 0.14224)
		(layer "In11.Cu")
		(net "M_M_DQ<52>")
	)
	(segment
		(start 132.789168 -124.586746)
		(end 132.789168 -126.873)
		(width 0.14224)
		(layer "In11.Cu")
		(net "M_M_DQ<52>")
	)
	(segment
		(start 133.297168 -149.2758)
		(end 133.08457 -149.488398)
		(width 0.14224)
		(layer "In11.Cu")
		(net "M_M_DQ<52>")
	)
	(segment
		(start 111.408718 -93.2434)
		(end 111.403892 -93.252036)
		(width 0.0889)
		(layer "In11.Cu")
		(net "M_M_DQ<52>")
	)
	(segment
		(start 111.403892 -91.270836)
		(end 111.397542 -91.281504)
		(width 0.0889)
		(layer "In11.Cu")
		(net "M_M_DQ<52>")
	)
	(segment
		(start 133.890004 -136.172702)
		(end 133.890004 -139.462764)
		(width 0.14224)
		(layer "In11.Cu")
		(net "M_M_DQ<52>")
	)
	(segment
		(start 111.403892 -97.214436)
		(end 111.397542 -97.225104)
		(width 0.0889)
		(layer "In11.Cu")
		(net "M_M_DQ<52>")
	)
	(segment
		(start 114.473482 -99.586288)
		(end 114.506248 -99.586288)
		(width 0.0889)
		(layer "In11.Cu")
		(net "M_M_DQ<52>")
	)
	(segment
		(start 111.403892 -92.261436)
		(end 111.397542 -92.272104)
		(width 0.0889)
		(layer "In11.Cu")
		(net "M_M_DQ<52>")
	)
	(segment
		(start 113.611152 -99.090734)
		(end 113.643918 -99.090734)
		(width 0.0889)
		(layer "In11.Cu")
		(net "M_M_DQ<52>")
	)
	(segment
		(start 111.408718 -92.2528)
		(end 111.403892 -92.261436)
		(width 0.0889)
		(layer "In11.Cu")
		(net "M_M_DQ<52>")
	)
	(segment
		(start 133.691122 -127.774954)
		(end 133.691122 -129.181352)
		(width 0.14224)
		(layer "In11.Cu")
		(net "M_M_DQ<52>")
	)
	(segment
		(start 133.89737 -134.477252)
		(end 133.66877 -134.705852)
		(width 0.14224)
		(layer "In11.Cu")
		(net "M_M_DQ<52>")
	)
	(segment
		(start 134.042912 -141.443202)
		(end 133.830568 -141.655546)
		(width 0.14224)
		(layer "In11.Cu")
		(net "M_M_DQ<52>")
	)
	(segment
		(start 111.408718 -94.234)
		(end 111.403892 -94.242636)
		(width 0.0889)
		(layer "In11.Cu")
		(net "M_M_DQ<52>")
	)
	(segment
		(start 114.383312 -106.955844)
		(end 114.383312 -114.230658)
		(width 0.14224)
		(layer "In11.Cu")
		(net "M_M_DQ<52>")
	)
	(segment
		(start 132.789168 -126.873)
		(end 133.691122 -127.774954)
		(width 0.14224)
		(layer "In11.Cu")
		(net "M_M_DQ<52>")
	)
	(segment
		(start 133.89737 -129.767838)
		(end 133.66877 -129.996438)
		(width 0.14224)
		(layer "In11.Cu")
		(net "M_M_DQ<52>")
	)
	(segment
		(start 115.696492 -102.262686)
		(end 115.701318 -102.271322)
		(width 0.0889)
		(layer "In11.Cu")
		(net "M_M_DQ<52>")
	)
	(segment
		(start 115.696492 -101.272086)
		(end 115.701318 -101.280722)
		(width 0.0889)
		(layer "In11.Cu")
		(net "M_M_DQ<52>")
	)
	(segment
		(start 111.403892 -96.223836)
		(end 111.397542 -96.234504)
		(width 0.0889)
		(layer "In11.Cu")
		(net "M_M_DQ<52>")
	)
	(segment
		(start 111.915702 -90.575384)
		(end 111.420656 -91.241372)
		(width 0.0889)
		(layer "In11.Cu")
		(net "M_M_DQ<52>")
	)
	(segment
		(start 133.89737 -144.078198)
		(end 133.551168 -144.4244)
		(width 0.14224)
		(layer "In11.Cu")
		(net "M_M_DQ<52>")
	)
	(segment
		(start 111.397542 -94.822518)
		(end 111.403892 -94.833186)
		(width 0.0889)
		(layer "In11.Cu")
		(net "M_M_DQ<52>")
	)
	(segment
		(start 132.230622 -124.0282)
		(end 132.789168 -124.586746)
		(width 0.14224)
		(layer "In11.Cu")
		(net "M_M_DQ<52>")
	)
	(segment
		(start 132.96646 -153.78049)
		(end 133.124448 -153.938478)
		(width 0.14224)
		(layer "In11.Cu")
		(net "M_M_DQ<52>")
	)
	(segment
		(start 114.942366 -106.39679)
		(end 114.674142 -106.665014)
		(width 0.0889)
		(layer "In11.Cu")
		(net "M_M_DQ<52>")
	)
	(segment
		(start 111.894112 -98.100134)
		(end 111.926878 -98.100134)
		(width 0.0889)
		(layer "In11.Cu")
		(net "M_M_DQ<52>")
	)
	(segment
		(start 133.551168 -139.8016)
		(end 133.551168 -140.663676)
		(width 0.14224)
		(layer "In11.Cu")
		(net "M_M_DQ<52>")
	)
	(arc
		(start 115.701318 -103.261922)
		(mid 115.750073 -103.458274)
		(end 115.696492 -103.653336)
		(width 0.0889)
		(layer "In11.Cu")
		(net "M_M_DQ<52>")
	)
	(arc
		(start 111.926878 -98.100134)
		(mid 112.120728 -98.156484)
		(end 112.262412 -98.300286)
		(width 0.0889)
		(layer "In11.Cu")
		(net "M_M_DQ<52>")
	)
	(arc
		(start 111.397542 -93.262704)
		(mid 111.324744 -93.553467)
		(end 111.403892 -93.842586)
		(width 0.0889)
		(layer "In11.Cu")
		(net "M_M_DQ<52>")
	)
	(arc
		(start 115.701318 -101.280722)
		(mid 115.750073 -101.477074)
		(end 115.696492 -101.672136)
		(width 0.0889)
		(layer "In11.Cu")
		(net "M_M_DQ<52>")
	)
	(arc
		(start 113.979452 -99.290886)
		(mid 114.18806 -99.502818)
		(end 114.473482 -99.586288)
		(width 0.0889)
		(layer "In11.Cu")
		(net "M_M_DQ<52>")
	)
	(arc
		(start 112.789208 -98.595688)
		(mid 112.98085 -98.652854)
		(end 113.120932 -98.795586)
		(width 0.0889)
		(layer "In11.Cu")
		(net "M_M_DQ<52>")
	)
	(arc
		(start 111.403892 -95.232982)
		(mid 111.324761 -95.528384)
		(end 111.403892 -95.823786)
		(width 0.0889)
		(layer "In11.Cu")
		(net "M_M_DQ<52>")
	)
	(arc
		(start 115.360958 -100.081334)
		(mid 115.699127 -100.286132)
		(end 115.696492 -100.681536)
		(width 0.0889)
		(layer "In11.Cu")
		(net "M_M_DQ<52>")
	)
	(arc
		(start 113.643918 -99.090734)
		(mid 113.837768 -99.147084)
		(end 113.979452 -99.290886)
		(width 0.0889)
		(layer "In11.Cu")
		(net "M_M_DQ<52>")
	)
	(arc
		(start 111.397542 -97.225104)
		(mid 111.401573 -97.801286)
		(end 111.894112 -98.100134)
		(width 0.0889)
		(layer "In11.Cu")
		(net "M_M_DQ<52>")
	)
	(arc
		(start 111.397542 -92.272104)
		(mid 111.324744 -92.562867)
		(end 111.403892 -92.851986)
		(width 0.0889)
		(layer "In11.Cu")
		(net "M_M_DQ<52>")
	)
	(arc
		(start 111.403892 -91.861386)
		(mid 111.457362 -92.056449)
		(end 111.408718 -92.2528)
		(width 0.0889)
		(layer "In11.Cu")
		(net "M_M_DQ<52>")
	)
	(arc
		(start 115.701318 -102.271322)
		(mid 115.750073 -102.467674)
		(end 115.696492 -102.662736)
		(width 0.0889)
		(layer "In11.Cu")
		(net "M_M_DQ<52>")
	)
	(arc
		(start 112.262412 -98.300286)
		(mid 112.47102 -98.512218)
		(end 112.756442 -98.595688)
		(width 0.0889)
		(layer "In11.Cu")
		(net "M_M_DQ<52>")
	)
	(arc
		(start 114.506248 -99.586288)
		(mid 114.69789 -99.643454)
		(end 114.837972 -99.786186)
		(width 0.0889)
		(layer "In11.Cu")
		(net "M_M_DQ<52>")
	)
	(arc
		(start 115.696492 -100.681536)
		(mid 115.61727 -100.970654)
		(end 115.690142 -101.261418)
		(width 0.0889)
		(layer "In11.Cu")
		(net "M_M_DQ<52>")
	)
	(arc
		(start 115.696492 -101.672136)
		(mid 115.61727 -101.961254)
		(end 115.690142 -102.252018)
		(width 0.0889)
		(layer "In11.Cu")
		(net "M_M_DQ<52>")
	)
	(arc
		(start 111.403892 -96.814386)
		(mid 111.457362 -97.009449)
		(end 111.408718 -97.2058)
		(width 0.0889)
		(layer "In11.Cu")
		(net "M_M_DQ<52>")
	)
	(arc
		(start 115.696492 -102.662736)
		(mid 115.61727 -102.951854)
		(end 115.690142 -103.242618)
		(width 0.0889)
		(layer "In11.Cu")
		(net "M_M_DQ<52>")
	)
	(arc
		(start 115.696492 -104.643936)
		(mid 115.637425 -104.786422)
		(end 115.617244 -104.939338)
		(width 0.0889)
		(layer "In11.Cu")
		(net "M_M_DQ<52>")
	)
	(arc
		(start 115.701318 -104.252522)
		(mid 115.750073 -104.448874)
		(end 115.696492 -104.643936)
		(width 0.0889)
		(layer "In11.Cu")
		(net "M_M_DQ<52>")
	)
	(arc
		(start 115.696492 -103.653336)
		(mid 115.61727 -103.942454)
		(end 115.690142 -104.233218)
		(width 0.0889)
		(layer "In11.Cu")
		(net "M_M_DQ<52>")
	)
	(arc
		(start 113.120932 -98.795586)
		(mid 113.327936 -99.00645)
		(end 113.611152 -99.090734)
		(width 0.0889)
		(layer "In11.Cu")
		(net "M_M_DQ<52>")
	)
	(arc
		(start 114.837972 -99.786186)
		(mid 115.044976 -99.99705)
		(end 115.328192 -100.081334)
		(width 0.0889)
		(layer "In11.Cu")
		(net "M_M_DQ<52>")
	)
	(arc
		(start 111.403892 -93.842586)
		(mid 111.457362 -94.037649)
		(end 111.408718 -94.234)
		(width 0.0889)
		(layer "In11.Cu")
		(net "M_M_DQ<52>")
	)
	(arc
		(start 111.397542 -96.234504)
		(mid 111.324744 -96.525267)
		(end 111.403892 -96.814386)
		(width 0.0889)
		(layer "In11.Cu")
		(net "M_M_DQ<52>")
	)
	(arc
		(start 111.403892 -94.833186)
		(mid 111.457391 -95.033084)
		(end 111.403892 -95.232982)
		(width 0.0889)
		(layer "In11.Cu")
		(net "M_M_DQ<52>")
	)
	(arc
		(start 111.403892 -92.851986)
		(mid 111.457362 -93.047049)
		(end 111.408718 -93.2434)
		(width 0.0889)
		(layer "In11.Cu")
		(net "M_M_DQ<52>")
	)
	(arc
		(start 111.403892 -95.823786)
		(mid 111.457362 -96.018849)
		(end 111.408718 -96.2152)
		(width 0.0889)
		(layer "In11.Cu")
		(net "M_M_DQ<52>")
	)
	(arc
		(start 111.397542 -91.281504)
		(mid 111.324744 -91.572267)
		(end 111.403892 -91.861386)
		(width 0.0889)
		(layer "In11.Cu")
		(net "M_M_DQ<52>")
	)
	(arc
		(start 111.403892 -94.242636)
		(mid 111.32467 -94.531754)
		(end 111.397542 -94.822518)
		(width 0.0889)
		(layer "In11.Cu")
		(net "M_M_DQ<52>")
	)
	(segment
		(start 114.778282 -91.565984)
		(end 115.349782 -91.565984)
		(width 0.1651)
		(layer "F.Cu")
		(net "M_M_DQ<51>")
	)
	(segment
		(start 141.049502 -152.273)
		(end 141.049502 -153.542746)
		(width 0.1651)
		(layer "F.Cu")
		(net "M_M_DQ<51>")
	)
	(via
		(at 141.899386 -149.533356)
		(size 0.508)
		(drill 0.254)
		(layers "F.Cu" "B.Cu")
		(net "M_M_DQ<51>")
	)
	(via
		(at 141.049502 -153.542746)
		(size 0.508)
		(drill 0.254)
		(layers "F.Cu" "B.Cu")
		(net "M_M_DQ<51>")
	)
	(via
		(at 115.349782 -91.565984)
		(size 0.508)
		(drill 0.254)
		(layers "F.Cu" "B.Cu")
		(net "M_M_DQ<51>")
	)
	(segment
		(start 141.899386 -147.478496)
		(end 141.899386 -149.533356)
		(width 0.1651)
		(layer "B.Cu")
		(net "M_M_DQ<51>")
	)
	(segment
		(start 137.034016 -119.86006)
		(end 137.034016 -119.641112)
		(width 0.14224)
		(layer "In11.Cu")
		(net "M_M_DQ<51>")
	)
	(segment
		(start 115.861592 -94.242636)
		(end 115.856766 -94.234)
		(width 0.0889)
		(layer "In11.Cu")
		(net "M_M_DQ<51>")
	)
	(segment
		(start 142.40637 -140.870178)
		(end 142.40637 -139.714478)
		(width 0.14224)
		(layer "In11.Cu")
		(net "M_M_DQ<51>")
	)
	(segment
		(start 142.415768 -124.369068)
		(end 139.814808 -121.768108)
		(width 0.14224)
		(layer "In11.Cu")
		(net "M_M_DQ<51>")
	)
	(segment
		(start 137.283952 -120.109996)
		(end 137.034016 -119.86006)
		(width 0.14224)
		(layer "In11.Cu")
		(net "M_M_DQ<51>")
	)
	(segment
		(start 138.440668 -121.047764)
		(end 138.22172 -121.047764)
		(width 0.14224)
		(layer "In11.Cu")
		(net "M_M_DQ<51>")
	)
	(segment
		(start 141.210792 -151.387048)
		(end 141.210792 -151.660352)
		(width 0.14224)
		(layer "In11.Cu")
		(net "M_M_DQ<51>")
	)
	(segment
		(start 142.43177 -136.026652)
		(end 142.43177 -134.738364)
		(width 0.14224)
		(layer "In11.Cu")
		(net "M_M_DQ<51>")
	)
	(segment
		(start 138.189208 -120.142508)
		(end 137.939272 -119.892572)
		(width 0.14224)
		(layer "In11.Cu")
		(net "M_M_DQ<51>")
	)
	(segment
		(start 137.971784 -120.797828)
		(end 137.971784 -120.57888)
		(width 0.14224)
		(layer "In11.Cu")
		(net "M_M_DQ<51>")
	)
	(segment
		(start 120.149366 -98.308922)
		(end 120.154192 -98.300286)
		(width 0.0889)
		(layer "In11.Cu")
		(net "M_M_DQ<51>")
	)
	(segment
		(start 138.87704 -120.83034)
		(end 138.658092 -120.83034)
		(width 0.14224)
		(layer "In11.Cu")
		(net "M_M_DQ<51>")
	)
	(segment
		(start 142.43177 -134.738364)
		(end 142.26667 -134.573264)
		(width 0.14224)
		(layer "In11.Cu")
		(net "M_M_DQ<51>")
	)
	(segment
		(start 138.909552 -121.735596)
		(end 138.909552 -121.516648)
		(width 0.14224)
		(layer "In11.Cu")
		(net "M_M_DQ<51>")
	)
	(segment
		(start 141.49959 -153.04135)
		(end 141.49959 -153.364946)
		(width 0.14224)
		(layer "In11.Cu")
		(net "M_M_DQ<51>")
	)
	(segment
		(start 142.339568 -143.6116)
		(end 142.339568 -141.550898)
		(width 0.14224)
		(layer "In11.Cu")
		(net "M_M_DQ<51>")
	)
	(segment
		(start 142.339568 -141.550898)
		(end 142.26667 -141.478)
		(width 0.14224)
		(layer "In11.Cu")
		(net "M_M_DQ<51>")
	)
	(segment
		(start 142.26667 -131.408678)
		(end 142.40637 -131.268978)
		(width 0.14224)
		(layer "In11.Cu")
		(net "M_M_DQ<51>")
	)
	(segment
		(start 141.49324 -151.1046)
		(end 141.210792 -151.387048)
		(width 0.14224)
		(layer "In11.Cu")
		(net "M_M_DQ<51>")
	)
	(segment
		(start 115.861592 -93.252036)
		(end 115.856766 -93.2434)
		(width 0.0889)
		(layer "In11.Cu")
		(net "M_M_DQ<51>")
	)
	(segment
		(start 119.663972 -97.414588)
		(end 119.631206 -97.414588)
		(width 0.0889)
		(layer "In11.Cu")
		(net "M_M_DQ<51>")
	)
	(segment
		(start 120.149366 -101.280722)
		(end 120.154192 -101.272086)
		(width 0.0889)
		(layer "In11.Cu")
		(net "M_M_DQ<51>")
	)
	(segment
		(start 120.154192 -100.281486)
		(end 120.160542 -100.270818)
		(width 0.0889)
		(layer "In11.Cu")
		(net "M_M_DQ<51>")
	)
	(segment
		(start 120.149366 -103.261922)
		(end 120.154192 -103.253286)
		(width 0.0889)
		(layer "In11.Cu")
		(net "M_M_DQ<51>")
	)
	(segment
		(start 115.861592 -92.261436)
		(end 115.844828 -92.231972)
		(width 0.0889)
		(layer "In11.Cu")
		(net "M_M_DQ<51>")
	)
	(segment
		(start 142.48257 -144.398238)
		(end 142.26667 -144.182338)
		(width 0.14224)
		(layer "In11.Cu")
		(net "M_M_DQ<51>")
	)
	(segment
		(start 142.314168 -138.7856)
		(end 142.314168 -136.610598)
		(width 0.14224)
		(layer "In11.Cu")
		(net "M_M_DQ<51>")
	)
	(segment
		(start 142.26667 -134.573264)
		(end 142.26667 -134.083298)
		(width 0.14224)
		(layer "In11.Cu")
		(net "M_M_DQ<51>")
	)
	(segment
		(start 120.149366 -99.299522)
		(end 120.154192 -99.290886)
		(width 0.0889)
		(layer "In11.Cu")
		(net "M_M_DQ<51>")
	)
	(segment
		(start 141.32179 -153.542746)
		(end 141.049502 -153.542746)
		(width 0.14224)
		(layer "In11.Cu")
		(net "M_M_DQ<51>")
	)
	(segment
		(start 142.26667 -143.684498)
		(end 142.339568 -143.6116)
		(width 0.14224)
		(layer "In11.Cu")
		(net "M_M_DQ<51>")
	)
	(segment
		(start 120.149366 -104.252522)
		(end 120.154192 -104.243886)
		(width 0.0889)
		(layer "In11.Cu")
		(net "M_M_DQ<51>")
	)
	(segment
		(start 141.46784 -152.2222)
		(end 141.210792 -152.479248)
		(width 0.14224)
		(layer "In11.Cu")
		(net "M_M_DQ<51>")
	)
	(segment
		(start 116.221256 -95.433134)
		(end 116.197126 -95.433134)
		(width 0.0889)
		(layer "In11.Cu")
		(net "M_M_DQ<51>")
	)
	(segment
		(start 142.314168 -126.3904)
		(end 142.415768 -126.2888)
		(width 0.14224)
		(layer "In11.Cu")
		(net "M_M_DQ<51>")
	)
	(segment
		(start 142.40637 -139.714478)
		(end 142.25397 -139.562078)
		(width 0.14224)
		(layer "In11.Cu")
		(net "M_M_DQ<51>")
	)
	(segment
		(start 142.22857 -149.21738)
		(end 142.22857 -145.805652)
		(width 0.14224)
		(layer "In11.Cu")
		(net "M_M_DQ<51>")
	)
	(segment
		(start 121.051066 -106.665014)
		(end 120.801384 -106.415332)
		(width 0.0889)
		(layer "In11.Cu")
		(net "M_M_DQ<51>")
	)
	(segment
		(start 137.25144 -119.20474)
		(end 134.656576 -116.609876)
		(width 0.14224)
		(layer "In11.Cu")
		(net "M_M_DQ<51>")
	)
	(segment
		(start 120.154192 -104.243886)
		(end 120.160542 -104.233218)
		(width 0.0889)
		(layer "In11.Cu")
		(net "M_M_DQ<51>")
	)
	(segment
		(start 137.971784 -120.57888)
		(end 138.189208 -120.361456)
		(width 0.14224)
		(layer "In11.Cu")
		(net "M_M_DQ<51>")
	)
	(segment
		(start 142.25397 -136.204452)
		(end 142.43177 -136.026652)
		(width 0.14224)
		(layer "In11.Cu")
		(net "M_M_DQ<51>")
	)
	(segment
		(start 139.814808 -121.768108)
		(end 139.59586 -121.768108)
		(width 0.14224)
		(layer "In11.Cu")
		(net "M_M_DQ<51>")
	)
	(segment
		(start 115.844828 -92.231972)
		(end 115.349782 -91.565984)
		(width 0.0889)
		(layer "In11.Cu")
		(net "M_M_DQ<51>")
	)
	(segment
		(start 142.40637 -131.268978)
		(end 142.40637 -130.113278)
		(width 0.14224)
		(layer "In11.Cu")
		(net "M_M_DQ<51>")
	)
	(segment
		(start 141.877034 -149.533356)
		(end 141.44879 -149.9616)
		(width 0.14224)
		(layer "In11.Cu")
		(net "M_M_DQ<51>")
	)
	(segment
		(start 142.25397 -139.562078)
		(end 142.25397 -138.845798)
		(width 0.14224)
		(layer "In11.Cu")
		(net "M_M_DQ<51>")
	)
	(segment
		(start 117.946932 -96.423988)
		(end 117.914166 -96.423988)
		(width 0.0889)
		(layer "In11.Cu")
		(net "M_M_DQ<51>")
	)
	(segment
		(start 138.658092 -120.83034)
		(end 138.440668 -121.047764)
		(width 0.14224)
		(layer "In11.Cu")
		(net "M_M_DQ<51>")
	)
	(segment
		(start 141.46784 -151.9174)
		(end 141.46784 -152.2222)
		(width 0.14224)
		(layer "In11.Cu")
		(net "M_M_DQ<51>")
	)
	(segment
		(start 120.154192 -98.300286)
		(end 120.160542 -98.289618)
		(width 0.0889)
		(layer "In11.Cu")
		(net "M_M_DQ<51>")
	)
	(segment
		(start 138.22172 -121.047764)
		(end 137.971784 -120.797828)
		(width 0.14224)
		(layer "In11.Cu")
		(net "M_M_DQ<51>")
	)
	(segment
		(start 142.25397 -129.346198)
		(end 142.314168 -129.286)
		(width 0.14224)
		(layer "In11.Cu")
		(net "M_M_DQ<51>")
	)
	(segment
		(start 117.084602 -95.928434)
		(end 117.051836 -95.928434)
		(width 0.0889)
		(layer "In11.Cu")
		(net "M_M_DQ<51>")
	)
	(segment
		(start 141.44879 -149.9616)
		(end 141.44879 -150.391368)
		(width 0.14224)
		(layer "In11.Cu")
		(net "M_M_DQ<51>")
	)
	(segment
		(start 142.40637 -130.113278)
		(end 142.25397 -129.960878)
		(width 0.14224)
		(layer "In11.Cu")
		(net "M_M_DQ<51>")
	)
	(segment
		(start 115.867942 -92.272104)
		(end 115.861592 -92.261436)
		(width 0.0889)
		(layer "In11.Cu")
		(net "M_M_DQ<51>")
	)
	(segment
		(start 139.378436 -121.985532)
		(end 139.159488 -121.985532)
		(width 0.14224)
		(layer "In11.Cu")
		(net "M_M_DQ<51>")
	)
	(segment
		(start 139.59586 -121.768108)
		(end 139.378436 -121.985532)
		(width 0.14224)
		(layer "In11.Cu")
		(net "M_M_DQ<51>")
	)
	(segment
		(start 142.26667 -134.083298)
		(end 142.339568 -134.0104)
		(width 0.14224)
		(layer "In11.Cu")
		(net "M_M_DQ<51>")
	)
	(segment
		(start 118.801642 -96.919034)
		(end 118.768876 -96.919034)
		(width 0.0889)
		(layer "In11.Cu")
		(net "M_M_DQ<51>")
	)
	(segment
		(start 142.26667 -144.182338)
		(end 142.26667 -143.684498)
		(width 0.14224)
		(layer "In11.Cu")
		(net "M_M_DQ<51>")
	)
	(segment
		(start 142.314168 -136.610598)
		(end 142.25397 -136.5504)
		(width 0.14224)
		(layer "In11.Cu")
		(net "M_M_DQ<51>")
	)
	(segment
		(start 141.899386 -149.546564)
		(end 142.22857 -149.21738)
		(width 0.14224)
		(layer "In11.Cu")
		(net "M_M_DQ<51>")
	)
	(segment
		(start 120.154192 -105.234486)
		(end 120.160542 -105.223818)
		(width 0.0889)
		(layer "In11.Cu")
		(net "M_M_DQ<51>")
	)
	(segment
		(start 120.154192 -101.272086)
		(end 120.160542 -101.261418)
		(width 0.0889)
		(layer "In11.Cu")
		(net "M_M_DQ<51>")
	)
	(segment
		(start 120.149366 -100.290122)
		(end 120.154192 -100.281486)
		(width 0.0889)
		(layer "In11.Cu")
		(net "M_M_DQ<51>")
	)
	(segment
		(start 137.034016 -119.641112)
		(end 137.25144 -119.423688)
		(width 0.14224)
		(layer "In11.Cu")
		(net "M_M_DQ<51>")
	)
	(segment
		(start 126.107444 -116.609876)
		(end 121.051066 -111.553498)
		(width 0.14224)
		(layer "In11.Cu")
		(net "M_M_DQ<51>")
	)
	(segment
		(start 120.149366 -102.271322)
		(end 120.154192 -102.262686)
		(width 0.0889)
		(layer "In11.Cu")
		(net "M_M_DQ<51>")
	)
	(segment
		(start 141.899386 -149.533356)
		(end 141.899386 -149.546564)
		(width 0.14224)
		(layer "In11.Cu")
		(net "M_M_DQ<51>")
	)
	(segment
		(start 137.720324 -119.892572)
		(end 137.5029 -120.109996)
		(width 0.14224)
		(layer "In11.Cu")
		(net "M_M_DQ<51>")
	)
	(segment
		(start 138.909552 -121.516648)
		(end 139.126976 -121.299224)
		(width 0.14224)
		(layer "In11.Cu")
		(net "M_M_DQ<51>")
	)
	(segment
		(start 142.314168 -129.286)
		(end 142.314168 -126.3904)
		(width 0.14224)
		(layer "In11.Cu")
		(net "M_M_DQ<51>")
	)
	(segment
		(start 141.49959 -153.364946)
		(end 141.32179 -153.542746)
		(width 0.14224)
		(layer "In11.Cu")
		(net "M_M_DQ<51>")
	)
	(segment
		(start 142.25397 -136.5504)
		(end 142.25397 -136.204452)
		(width 0.14224)
		(layer "In11.Cu")
		(net "M_M_DQ<51>")
	)
	(segment
		(start 137.25144 -119.423688)
		(end 137.25144 -119.20474)
		(width 0.14224)
		(layer "In11.Cu")
		(net "M_M_DQ<51>")
	)
	(segment
		(start 139.126976 -121.299224)
		(end 139.126976 -121.080276)
		(width 0.14224)
		(layer "In11.Cu")
		(net "M_M_DQ<51>")
	)
	(segment
		(start 142.25397 -129.960878)
		(end 142.25397 -129.346198)
		(width 0.14224)
		(layer "In11.Cu")
		(net "M_M_DQ<51>")
	)
	(segment
		(start 141.210792 -152.752552)
		(end 141.49959 -153.04135)
		(width 0.14224)
		(layer "In11.Cu")
		(net "M_M_DQ<51>")
	)
	(segment
		(start 142.26667 -141.478)
		(end 142.26667 -141.009878)
		(width 0.14224)
		(layer "In11.Cu")
		(net "M_M_DQ<51>")
	)
	(segment
		(start 139.126976 -121.080276)
		(end 138.87704 -120.83034)
		(width 0.14224)
		(layer "In11.Cu")
		(net "M_M_DQ<51>")
	)
	(segment
		(start 142.339568 -134.0104)
		(end 142.339568 -131.975098)
		(width 0.14224)
		(layer "In11.Cu")
		(net "M_M_DQ<51>")
	)
	(segment
		(start 137.939272 -119.892572)
		(end 137.720324 -119.892572)
		(width 0.14224)
		(layer "In11.Cu")
		(net "M_M_DQ<51>")
	)
	(segment
		(start 120.154192 -102.262686)
		(end 120.160542 -102.252018)
		(width 0.0889)
		(layer "In11.Cu")
		(net "M_M_DQ<51>")
	)
	(segment
		(start 141.49324 -150.435818)
		(end 141.49324 -151.1046)
		(width 0.14224)
		(layer "In11.Cu")
		(net "M_M_DQ<51>")
	)
	(segment
		(start 141.899386 -149.533356)
		(end 141.877034 -149.533356)
		(width 0.14224)
		(layer "In11.Cu")
		(net "M_M_DQ<51>")
	)
	(segment
		(start 115.867942 -93.262704)
		(end 115.861592 -93.252036)
		(width 0.0889)
		(layer "In11.Cu")
		(net "M_M_DQ<51>")
	)
	(segment
		(start 121.051066 -111.553498)
		(end 121.051066 -106.665014)
		(width 0.14224)
		(layer "In11.Cu")
		(net "M_M_DQ<51>")
	)
	(segment
		(start 137.5029 -120.109996)
		(end 137.283952 -120.109996)
		(width 0.14224)
		(layer "In11.Cu")
		(net "M_M_DQ<51>")
	)
	(segment
		(start 142.48257 -145.551652)
		(end 142.48257 -144.398238)
		(width 0.14224)
		(layer "In11.Cu")
		(net "M_M_DQ<51>")
	)
	(segment
		(start 141.44879 -150.391368)
		(end 141.49324 -150.435818)
		(width 0.14224)
		(layer "In11.Cu")
		(net "M_M_DQ<51>")
	)
	(segment
		(start 142.26667 -131.9022)
		(end 142.26667 -131.408678)
		(width 0.14224)
		(layer "In11.Cu")
		(net "M_M_DQ<51>")
	)
	(segment
		(start 134.656576 -116.609876)
		(end 126.107444 -116.609876)
		(width 0.14224)
		(layer "In11.Cu")
		(net "M_M_DQ<51>")
	)
	(segment
		(start 120.154192 -99.290886)
		(end 120.160542 -99.280218)
		(width 0.0889)
		(layer "In11.Cu")
		(net "M_M_DQ<51>")
	)
	(segment
		(start 120.149366 -105.243122)
		(end 120.154192 -105.234486)
		(width 0.0889)
		(layer "In11.Cu")
		(net "M_M_DQ<51>")
	)
	(segment
		(start 142.22857 -145.805652)
		(end 142.48257 -145.551652)
		(width 0.14224)
		(layer "In11.Cu")
		(net "M_M_DQ<51>")
	)
	(segment
		(start 142.25397 -138.845798)
		(end 142.314168 -138.7856)
		(width 0.14224)
		(layer "In11.Cu")
		(net "M_M_DQ<51>")
	)
	(segment
		(start 138.189208 -120.361456)
		(end 138.189208 -120.142508)
		(width 0.14224)
		(layer "In11.Cu")
		(net "M_M_DQ<51>")
	)
	(segment
		(start 120.154192 -103.253286)
		(end 120.160542 -103.242618)
		(width 0.0889)
		(layer "In11.Cu")
		(net "M_M_DQ<51>")
	)
	(segment
		(start 141.210792 -152.479248)
		(end 141.210792 -152.752552)
		(width 0.14224)
		(layer "In11.Cu")
		(net "M_M_DQ<51>")
	)
	(segment
		(start 142.415768 -126.2888)
		(end 142.415768 -124.369068)
		(width 0.14224)
		(layer "In11.Cu")
		(net "M_M_DQ<51>")
	)
	(segment
		(start 120.801384 -106.415332)
		(end 120.801384 -106.300778)
		(width 0.0889)
		(layer "In11.Cu")
		(net "M_M_DQ<51>")
	)
	(segment
		(start 142.26667 -141.009878)
		(end 142.40637 -140.870178)
		(width 0.14224)
		(layer "In11.Cu")
		(net "M_M_DQ<51>")
	)
	(segment
		(start 115.861592 -94.833186)
		(end 115.867942 -94.822518)
		(width 0.0889)
		(layer "In11.Cu")
		(net "M_M_DQ<51>")
	)
	(segment
		(start 139.159488 -121.985532)
		(end 138.909552 -121.735596)
		(width 0.14224)
		(layer "In11.Cu")
		(net "M_M_DQ<51>")
	)
	(segment
		(start 141.210792 -151.660352)
		(end 141.46784 -151.9174)
		(width 0.14224)
		(layer "In11.Cu")
		(net "M_M_DQ<51>")
	)
	(segment
		(start 120.801384 -106.300778)
		(end 120.217946 -105.71734)
		(width 0.0889)
		(layer "In11.Cu")
		(net "M_M_DQ<51>")
	)
	(segment
		(start 142.339568 -131.975098)
		(end 142.26667 -131.9022)
		(width 0.14224)
		(layer "In11.Cu")
		(net "M_M_DQ<51>")
	)
	(arc
		(start 120.154192 -102.662736)
		(mid 120.100722 -102.467673)
		(end 120.149366 -102.271322)
		(width 0.0889)
		(layer "In11.Cu")
		(net "M_M_DQ<51>")
	)
	(arc
		(start 116.720112 -95.728536)
		(mid 116.509399 -95.515457)
		(end 116.221256 -95.433134)
		(width 0.0889)
		(layer "In11.Cu")
		(net "M_M_DQ<51>")
	)
	(arc
		(start 117.051836 -95.928434)
		(mid 116.860194 -95.871268)
		(end 116.720112 -95.728536)
		(width 0.0889)
		(layer "In11.Cu")
		(net "M_M_DQ<51>")
	)
	(arc
		(start 120.154192 -103.653336)
		(mid 120.100722 -103.458273)
		(end 120.149366 -103.261922)
		(width 0.0889)
		(layer "In11.Cu")
		(net "M_M_DQ<51>")
	)
	(arc
		(start 117.578632 -96.223836)
		(mid 117.370024 -96.011904)
		(end 117.084602 -95.928434)
		(width 0.0889)
		(layer "In11.Cu")
		(net "M_M_DQ<51>")
	)
	(arc
		(start 120.160542 -103.242618)
		(mid 120.23334 -102.951855)
		(end 120.154192 -102.662736)
		(width 0.0889)
		(layer "In11.Cu")
		(net "M_M_DQ<51>")
	)
	(arc
		(start 115.856766 -93.2434)
		(mid 115.808011 -93.047048)
		(end 115.861592 -92.851986)
		(width 0.0889)
		(layer "In11.Cu")
		(net "M_M_DQ<51>")
	)
	(arc
		(start 120.154192 -99.690936)
		(mid 120.100722 -99.495873)
		(end 120.149366 -99.299522)
		(width 0.0889)
		(layer "In11.Cu")
		(net "M_M_DQ<51>")
	)
	(arc
		(start 115.867942 -94.822518)
		(mid 115.94074 -94.531755)
		(end 115.861592 -94.242636)
		(width 0.0889)
		(layer "In11.Cu")
		(net "M_M_DQ<51>")
	)
	(arc
		(start 120.160542 -102.252018)
		(mid 120.23334 -101.961255)
		(end 120.154192 -101.672136)
		(width 0.0889)
		(layer "In11.Cu")
		(net "M_M_DQ<51>")
	)
	(arc
		(start 115.856766 -94.234)
		(mid 115.808011 -94.037648)
		(end 115.861592 -93.842586)
		(width 0.0889)
		(layer "In11.Cu")
		(net "M_M_DQ<51>")
	)
	(arc
		(start 120.160542 -105.223818)
		(mid 120.23334 -104.933055)
		(end 120.154192 -104.643936)
		(width 0.0889)
		(layer "In11.Cu")
		(net "M_M_DQ<51>")
	)
	(arc
		(start 120.154192 -100.681536)
		(mid 120.100722 -100.486473)
		(end 120.149366 -100.290122)
		(width 0.0889)
		(layer "In11.Cu")
		(net "M_M_DQ<51>")
	)
	(arc
		(start 115.861592 -93.842586)
		(mid 115.940814 -93.553468)
		(end 115.867942 -93.262704)
		(width 0.0889)
		(layer "In11.Cu")
		(net "M_M_DQ<51>")
	)
	(arc
		(start 120.160542 -104.233218)
		(mid 120.23334 -103.942455)
		(end 120.154192 -103.653336)
		(width 0.0889)
		(layer "In11.Cu")
		(net "M_M_DQ<51>")
	)
	(arc
		(start 117.914166 -96.423988)
		(mid 117.720316 -96.367638)
		(end 117.578632 -96.223836)
		(width 0.0889)
		(layer "In11.Cu")
		(net "M_M_DQ<51>")
	)
	(arc
		(start 119.631206 -97.414588)
		(mid 119.437356 -97.358238)
		(end 119.295672 -97.214436)
		(width 0.0889)
		(layer "In11.Cu")
		(net "M_M_DQ<51>")
	)
	(arc
		(start 120.160542 -100.270818)
		(mid 120.23334 -99.980055)
		(end 120.154192 -99.690936)
		(width 0.0889)
		(layer "In11.Cu")
		(net "M_M_DQ<51>")
	)
	(arc
		(start 120.154192 -104.643936)
		(mid 120.100722 -104.448873)
		(end 120.149366 -104.252522)
		(width 0.0889)
		(layer "In11.Cu")
		(net "M_M_DQ<51>")
	)
	(arc
		(start 120.160542 -101.261418)
		(mid 120.23334 -100.970655)
		(end 120.154192 -100.681536)
		(width 0.0889)
		(layer "In11.Cu")
		(net "M_M_DQ<51>")
	)
	(arc
		(start 115.861592 -92.851986)
		(mid 115.940814 -92.562868)
		(end 115.867942 -92.272104)
		(width 0.0889)
		(layer "In11.Cu")
		(net "M_M_DQ<51>")
	)
	(arc
		(start 120.160542 -99.280218)
		(mid 120.23334 -98.989455)
		(end 120.154192 -98.700336)
		(width 0.0889)
		(layer "In11.Cu")
		(net "M_M_DQ<51>")
	)
	(arc
		(start 120.154192 -98.700336)
		(mid 120.100722 -98.505273)
		(end 120.149366 -98.308922)
		(width 0.0889)
		(layer "In11.Cu")
		(net "M_M_DQ<51>")
	)
	(arc
		(start 118.437152 -96.719136)
		(mid 118.230148 -96.508272)
		(end 117.946932 -96.423988)
		(width 0.0889)
		(layer "In11.Cu")
		(net "M_M_DQ<51>")
	)
	(arc
		(start 120.217946 -105.71734)
		(mid 120.104786 -105.491636)
		(end 120.149366 -105.243122)
		(width 0.0889)
		(layer "In11.Cu")
		(net "M_M_DQ<51>")
	)
	(arc
		(start 119.295672 -97.214436)
		(mid 119.087064 -97.002504)
		(end 118.801642 -96.919034)
		(width 0.0889)
		(layer "In11.Cu")
		(net "M_M_DQ<51>")
	)
	(arc
		(start 118.768876 -96.919034)
		(mid 118.577234 -96.861868)
		(end 118.437152 -96.719136)
		(width 0.0889)
		(layer "In11.Cu")
		(net "M_M_DQ<51>")
	)
	(arc
		(start 116.197126 -95.433134)
		(mid 115.859011 -95.228432)
		(end 115.861592 -94.833186)
		(width 0.0889)
		(layer "In11.Cu")
		(net "M_M_DQ<51>")
	)
	(arc
		(start 120.154192 -101.672136)
		(mid 120.100722 -101.477073)
		(end 120.149366 -101.280722)
		(width 0.0889)
		(layer "In11.Cu")
		(net "M_M_DQ<51>")
	)
	(arc
		(start 120.160542 -98.289618)
		(mid 120.156511 -97.713436)
		(end 119.663972 -97.414588)
		(width 0.0889)
		(layer "In11.Cu")
		(net "M_M_DQ<51>")
	)
	(segment
		(start 141.899386 -155.395168)
		(end 141.899386 -155.1178)
		(width 0.1651)
		(layer "F.Cu")
		(net "M_M_DQ<50>")
	)
	(segment
		(start 114.778282 -90.575384)
		(end 115.349782 -90.575384)
		(width 0.1651)
		(layer "F.Cu")
		(net "M_M_DQ<50>")
	)
	(segment
		(start 141.899386 -155.881832)
		(end 142.030958 -155.75026)
		(width 0.1651)
		(layer "F.Cu")
		(net "M_M_DQ<50>")
	)
	(segment
		(start 141.899386 -156.87294)
		(end 141.899386 -155.881832)
		(width 0.1651)
		(layer "F.Cu")
		(net "M_M_DQ<50>")
	)
	(segment
		(start 142.030958 -155.75026)
		(end 142.030958 -155.52674)
		(width 0.1651)
		(layer "F.Cu")
		(net "M_M_DQ<50>")
	)
	(segment
		(start 142.030958 -155.52674)
		(end 141.899386 -155.395168)
		(width 0.1651)
		(layer "F.Cu")
		(net "M_M_DQ<50>")
	)
	(via
		(at 115.349782 -90.575384)
		(size 0.508)
		(drill 0.254)
		(layers "F.Cu" "B.Cu")
		(net "M_M_DQ<50>")
	)
	(via
		(at 141.899386 -155.1178)
		(size 0.508)
		(drill 0.254)
		(layers "F.Cu" "B.Cu")
		(net "M_M_DQ<50>")
	)
	(via
		(at 141.049502 -150.814278)
		(size 0.508)
		(drill 0.254)
		(layers "F.Cu" "B.Cu")
		(net "M_M_DQ<50>")
	)
	(segment
		(start 141.049502 -152.078436)
		(end 141.049502 -150.814278)
		(width 0.1651)
		(layer "B.Cu")
		(net "M_M_DQ<50>")
	)
	(segment
		(start 141.049502 -150.814278)
		(end 140.616432 -151.247348)
		(width 0.14224)
		(layer "In11.Cu")
		(net "M_M_DQ<50>")
	)
	(segment
		(start 120.610884 -106.379518)
		(end 120.082818 -105.851452)
		(width 0.0889)
		(layer "In11.Cu")
		(net "M_M_DQ<50>")
	)
	(segment
		(start 119.989092 -98.205036)
		(end 119.993918 -98.1964)
		(width 0.0889)
		(layer "In11.Cu")
		(net "M_M_DQ<50>")
	)
	(segment
		(start 141.61516 -134.488174)
		(end 141.61516 -134.200392)
		(width 0.14224)
		(layer "In11.Cu")
		(net "M_M_DQ<50>")
	)
	(segment
		(start 141.54277 -129.3876)
		(end 141.348968 -129.193798)
		(width 0.14224)
		(layer "In11.Cu")
		(net "M_M_DQ<50>")
	)
	(segment
		(start 117.077998 -96.118934)
		(end 117.045232 -96.118934)
		(width 0.0889)
		(layer "In11.Cu")
		(net "M_M_DQ<50>")
	)
	(segment
		(start 118.795038 -97.109534)
		(end 118.762272 -97.109534)
		(width 0.0889)
		(layer "In11.Cu")
		(net "M_M_DQ<50>")
	)
	(segment
		(start 114.944398 -91.120722)
		(end 115.349782 -90.575384)
		(width 0.0889)
		(layer "In11.Cu")
		(net "M_M_DQ<50>")
	)
	(segment
		(start 119.989092 -103.158036)
		(end 119.993918 -103.1494)
		(width 0.0889)
		(layer "In11.Cu")
		(net "M_M_DQ<50>")
	)
	(segment
		(start 125.74651 -117.163342)
		(end 120.416066 -111.832898)
		(width 0.14224)
		(layer "In11.Cu")
		(net "M_M_DQ<50>")
	)
	(segment
		(start 119.982742 -104.159304)
		(end 119.989092 -104.148636)
		(width 0.0889)
		(layer "In11.Cu")
		(net "M_M_DQ<50>")
	)
	(segment
		(start 119.989092 -104.148636)
		(end 119.993918 -104.14)
		(width 0.0889)
		(layer "In11.Cu")
		(net "M_M_DQ<50>")
	)
	(segment
		(start 141.33957 -145.578068)
		(end 141.33957 -144.372838)
		(width 0.14224)
		(layer "In11.Cu")
		(net "M_M_DQ<50>")
	)
	(segment
		(start 141.61897 -143.780002)
		(end 141.474952 -143.635984)
		(width 0.14224)
		(layer "In11.Cu")
		(net "M_M_DQ<50>")
	)
	(segment
		(start 133.648704 -117.163342)
		(end 125.74651 -117.163342)
		(width 0.14224)
		(layer "In11.Cu")
		(net "M_M_DQ<50>")
	)
	(segment
		(start 116.223288 -95.623888)
		(end 116.195348 -95.623888)
		(width 0.0889)
		(layer "In11.Cu")
		(net "M_M_DQ<50>")
	)
	(segment
		(start 141.049502 -150.814278)
		(end 140.70457 -150.469346)
		(width 0.14224)
		(layer "In11.Cu")
		(net "M_M_DQ<50>")
	)
	(segment
		(start 141.474952 -143.635984)
		(end 141.474952 -141.596618)
		(width 0.14224)
		(layer "In11.Cu")
		(net "M_M_DQ<50>")
	)
	(segment
		(start 141.450568 -124.923804)
		(end 141.545564 -124.828808)
		(width 0.14224)
		(layer "In11.Cu")
		(net "M_M_DQ<50>")
	)
	(segment
		(start 141.56817 -148.972778)
		(end 141.56817 -145.806668)
		(width 0.14224)
		(layer "In11.Cu")
		(net "M_M_DQ<50>")
	)
	(segment
		(start 140.616432 -153.834846)
		(end 141.899386 -155.1178)
		(width 0.14224)
		(layer "In11.Cu")
		(net "M_M_DQ<50>")
	)
	(segment
		(start 141.474952 -141.596618)
		(end 141.61897 -141.4526)
		(width 0.14224)
		(layer "In11.Cu")
		(net "M_M_DQ<50>")
	)
	(segment
		(start 141.545564 -124.828808)
		(end 141.545564 -124.442728)
		(width 0.14224)
		(layer "In11.Cu")
		(net "M_M_DQ<50>")
	)
	(segment
		(start 119.989092 -100.186236)
		(end 119.993918 -100.1776)
		(width 0.0889)
		(layer "In11.Cu")
		(net "M_M_DQ<50>")
	)
	(segment
		(start 141.54277 -129.833878)
		(end 141.54277 -129.3876)
		(width 0.14224)
		(layer "In11.Cu")
		(net "M_M_DQ<50>")
	)
	(segment
		(start 119.989092 -102.167436)
		(end 119.993918 -102.1588)
		(width 0.0889)
		(layer "In11.Cu")
		(net "M_M_DQ<50>")
	)
	(segment
		(start 119.657368 -97.605088)
		(end 119.624602 -97.605088)
		(width 0.0889)
		(layer "In11.Cu")
		(net "M_M_DQ<50>")
	)
	(segment
		(start 141.475968 -134.0612)
		(end 141.475968 -132.057902)
		(width 0.14224)
		(layer "In11.Cu")
		(net "M_M_DQ<50>")
	)
	(segment
		(start 119.989092 -105.139236)
		(end 119.993918 -105.1306)
		(width 0.0889)
		(layer "In11.Cu")
		(net "M_M_DQ<50>")
	)
	(segment
		(start 141.475968 -136.693402)
		(end 141.602968 -136.566402)
		(width 0.14224)
		(layer "In11.Cu")
		(net "M_M_DQ<50>")
	)
	(segment
		(start 115.696492 -93.347286)
		(end 115.690142 -93.336618)
		(width 0.0889)
		(layer "In11.Cu")
		(net "M_M_DQ<50>")
	)
	(segment
		(start 119.989092 -99.195636)
		(end 119.993918 -99.187)
		(width 0.0889)
		(layer "In11.Cu")
		(net "M_M_DQ<50>")
	)
	(segment
		(start 141.704568 -131.829302)
		(end 141.704568 -131.4958)
		(width 0.14224)
		(layer "In11.Cu")
		(net "M_M_DQ<50>")
	)
	(segment
		(start 119.982742 -101.187504)
		(end 119.989092 -101.176836)
		(width 0.0889)
		(layer "In11.Cu")
		(net "M_M_DQ<50>")
	)
	(segment
		(start 141.61516 -134.200392)
		(end 141.475968 -134.0612)
		(width 0.14224)
		(layer "In11.Cu")
		(net "M_M_DQ<50>")
	)
	(segment
		(start 141.475968 -138.8618)
		(end 141.475968 -136.693402)
		(width 0.14224)
		(layer "In11.Cu")
		(net "M_M_DQ<50>")
	)
	(segment
		(start 140.616432 -151.247348)
		(end 140.616432 -153.834846)
		(width 0.14224)
		(layer "In11.Cu")
		(net "M_M_DQ<50>")
	)
	(segment
		(start 141.61897 -141.136878)
		(end 141.41577 -140.933678)
		(width 0.14224)
		(layer "In11.Cu")
		(net "M_M_DQ<50>")
	)
	(segment
		(start 120.610884 -106.470196)
		(end 120.610884 -106.379518)
		(width 0.0889)
		(layer "In11.Cu")
		(net "M_M_DQ<50>")
	)
	(segment
		(start 141.54277 -127.085598)
		(end 141.54277 -126.451614)
		(width 0.14224)
		(layer "In11.Cu")
		(net "M_M_DQ<50>")
	)
	(segment
		(start 139.474448 -122.989086)
		(end 133.648704 -117.163342)
		(width 0.14224)
		(layer "In11.Cu")
		(net "M_M_DQ<50>")
	)
	(segment
		(start 141.41577 -140.933678)
		(end 141.41577 -139.562078)
		(width 0.14224)
		(layer "In11.Cu")
		(net "M_M_DQ<50>")
	)
	(segment
		(start 141.41577 -139.562078)
		(end 141.54277 -139.435078)
		(width 0.14224)
		(layer "In11.Cu")
		(net "M_M_DQ<50>")
	)
	(segment
		(start 115.690142 -94.748604)
		(end 115.696492 -94.737936)
		(width 0.0889)
		(layer "In11.Cu")
		(net "M_M_DQ<50>")
	)
	(segment
		(start 141.348968 -129.193798)
		(end 141.348968 -127.2794)
		(width 0.14224)
		(layer "In11.Cu")
		(net "M_M_DQ<50>")
	)
	(segment
		(start 119.982742 -102.178104)
		(end 119.989092 -102.167436)
		(width 0.0889)
		(layer "In11.Cu")
		(net "M_M_DQ<50>")
	)
	(segment
		(start 141.475968 -132.057902)
		(end 141.704568 -131.829302)
		(width 0.14224)
		(layer "In11.Cu")
		(net "M_M_DQ<50>")
	)
	(segment
		(start 119.982742 -100.196904)
		(end 119.989092 -100.186236)
		(width 0.0889)
		(layer "In11.Cu")
		(net "M_M_DQ<50>")
	)
	(segment
		(start 141.56817 -145.806668)
		(end 141.33957 -145.578068)
		(width 0.14224)
		(layer "In11.Cu")
		(net "M_M_DQ<50>")
	)
	(segment
		(start 141.602968 -136.270746)
		(end 141.39037 -136.058148)
		(width 0.14224)
		(layer "In11.Cu")
		(net "M_M_DQ<50>")
	)
	(segment
		(start 141.704568 -131.4958)
		(end 141.41577 -131.207002)
		(width 0.14224)
		(layer "In11.Cu")
		(net "M_M_DQ<50>")
	)
	(segment
		(start 141.54277 -126.451614)
		(end 141.450568 -126.359412)
		(width 0.14224)
		(layer "In11.Cu")
		(net "M_M_DQ<50>")
	)
	(segment
		(start 141.41577 -129.960878)
		(end 141.54277 -129.833878)
		(width 0.14224)
		(layer "In11.Cu")
		(net "M_M_DQ<50>")
	)
	(segment
		(start 141.39037 -136.058148)
		(end 141.39037 -134.712964)
		(width 0.14224)
		(layer "In11.Cu")
		(net "M_M_DQ<50>")
	)
	(segment
		(start 115.701318 -93.355922)
		(end 115.696492 -93.347286)
		(width 0.0889)
		(layer "In11.Cu")
		(net "M_M_DQ<50>")
	)
	(segment
		(start 141.41577 -131.207002)
		(end 141.41577 -129.960878)
		(width 0.14224)
		(layer "In11.Cu")
		(net "M_M_DQ<50>")
	)
	(segment
		(start 119.982742 -105.149904)
		(end 119.989092 -105.139236)
		(width 0.0889)
		(layer "In11.Cu")
		(net "M_M_DQ<50>")
	)
	(segment
		(start 141.450568 -126.359412)
		(end 141.450568 -124.923804)
		(width 0.14224)
		(layer "In11.Cu")
		(net "M_M_DQ<50>")
	)
	(segment
		(start 119.982742 -99.206304)
		(end 119.989092 -99.195636)
		(width 0.0889)
		(layer "In11.Cu")
		(net "M_M_DQ<50>")
	)
	(segment
		(start 119.989092 -101.176836)
		(end 119.993918 -101.1682)
		(width 0.0889)
		(layer "In11.Cu")
		(net "M_M_DQ<50>")
	)
	(segment
		(start 140.091922 -122.989086)
		(end 139.474448 -122.989086)
		(width 0.14224)
		(layer "In11.Cu")
		(net "M_M_DQ<50>")
	)
	(segment
		(start 140.70457 -150.469346)
		(end 140.70457 -149.836378)
		(width 0.14224)
		(layer "In11.Cu")
		(net "M_M_DQ<50>")
	)
	(segment
		(start 141.39037 -134.712964)
		(end 141.61516 -134.488174)
		(width 0.14224)
		(layer "In11.Cu")
		(net "M_M_DQ<50>")
	)
	(segment
		(start 117.940328 -96.614488)
		(end 117.907562 -96.614488)
		(width 0.0889)
		(layer "In11.Cu")
		(net "M_M_DQ<50>")
	)
	(segment
		(start 141.602968 -136.566402)
		(end 141.602968 -136.270746)
		(width 0.14224)
		(layer "In11.Cu")
		(net "M_M_DQ<50>")
	)
	(segment
		(start 141.545564 -124.442728)
		(end 140.091922 -122.989086)
		(width 0.14224)
		(layer "In11.Cu")
		(net "M_M_DQ<50>")
	)
	(segment
		(start 119.982742 -103.168704)
		(end 119.989092 -103.158036)
		(width 0.0889)
		(layer "In11.Cu")
		(net "M_M_DQ<50>")
	)
	(segment
		(start 141.54277 -138.928602)
		(end 141.475968 -138.8618)
		(width 0.14224)
		(layer "In11.Cu")
		(net "M_M_DQ<50>")
	)
	(segment
		(start 120.416066 -111.832898)
		(end 120.416066 -106.665014)
		(width 0.14224)
		(layer "In11.Cu")
		(net "M_M_DQ<50>")
	)
	(segment
		(start 141.33957 -144.372838)
		(end 141.61897 -144.093438)
		(width 0.14224)
		(layer "In11.Cu")
		(net "M_M_DQ<50>")
	)
	(segment
		(start 141.348968 -127.2794)
		(end 141.54277 -127.085598)
		(width 0.14224)
		(layer "In11.Cu")
		(net "M_M_DQ<50>")
	)
	(segment
		(start 140.70457 -149.836378)
		(end 141.56817 -148.972778)
		(width 0.14224)
		(layer "In11.Cu")
		(net "M_M_DQ<50>")
	)
	(segment
		(start 119.982742 -98.215704)
		(end 119.989092 -98.205036)
		(width 0.0889)
		(layer "In11.Cu")
		(net "M_M_DQ<50>")
	)
	(segment
		(start 120.416066 -106.665014)
		(end 120.610884 -106.470196)
		(width 0.0889)
		(layer "In11.Cu")
		(net "M_M_DQ<50>")
	)
	(segment
		(start 141.61897 -141.4526)
		(end 141.61897 -141.136878)
		(width 0.14224)
		(layer "In11.Cu")
		(net "M_M_DQ<50>")
	)
	(segment
		(start 141.54277 -139.435078)
		(end 141.54277 -138.928602)
		(width 0.14224)
		(layer "In11.Cu")
		(net "M_M_DQ<50>")
	)
	(segment
		(start 141.61897 -144.093438)
		(end 141.61897 -143.780002)
		(width 0.14224)
		(layer "In11.Cu")
		(net "M_M_DQ<50>")
	)
	(arc
		(start 115.690142 -93.336618)
		(mid 115.617344 -93.045855)
		(end 115.696492 -92.756736)
		(width 0.0889)
		(layer "In11.Cu")
		(net "M_M_DQ<50>")
	)
	(arc
		(start 119.989092 -98.795586)
		(mid 119.90987 -98.506468)
		(end 119.982742 -98.215704)
		(width 0.0889)
		(layer "In11.Cu")
		(net "M_M_DQ<50>")
	)
	(arc
		(start 115.696492 -92.756736)
		(mid 115.724194 -92.414866)
		(end 115.477036 -92.177108)
		(width 0.0889)
		(layer "In11.Cu")
		(net "M_M_DQ<50>")
	)
	(arc
		(start 115.696492 -94.737936)
		(mid 115.749991 -94.538038)
		(end 115.696492 -94.33814)
		(width 0.0889)
		(layer "In11.Cu")
		(net "M_M_DQ<50>")
	)
	(arc
		(start 119.993918 -99.187)
		(mid 120.042673 -98.990648)
		(end 119.989092 -98.795586)
		(width 0.0889)
		(layer "In11.Cu")
		(net "M_M_DQ<50>")
	)
	(arc
		(start 119.993918 -102.1588)
		(mid 120.042673 -101.962448)
		(end 119.989092 -101.767386)
		(width 0.0889)
		(layer "In11.Cu")
		(net "M_M_DQ<50>")
	)
	(arc
		(start 119.993918 -104.14)
		(mid 120.042673 -103.943648)
		(end 119.989092 -103.748586)
		(width 0.0889)
		(layer "In11.Cu")
		(net "M_M_DQ<50>")
	)
	(arc
		(start 120.082818 -105.851452)
		(mid 119.915782 -105.517349)
		(end 119.982742 -105.149904)
		(width 0.0889)
		(layer "In11.Cu")
		(net "M_M_DQ<50>")
	)
	(arc
		(start 119.989092 -99.786186)
		(mid 119.90987 -99.497068)
		(end 119.982742 -99.206304)
		(width 0.0889)
		(layer "In11.Cu")
		(net "M_M_DQ<50>")
	)
	(arc
		(start 119.130572 -97.309686)
		(mid 118.988889 -97.165882)
		(end 118.795038 -97.109534)
		(width 0.0889)
		(layer "In11.Cu")
		(net "M_M_DQ<50>")
	)
	(arc
		(start 119.993918 -101.1682)
		(mid 120.042673 -100.971848)
		(end 119.989092 -100.776786)
		(width 0.0889)
		(layer "In11.Cu")
		(net "M_M_DQ<50>")
	)
	(arc
		(start 118.762272 -97.109534)
		(mid 118.479055 -97.025253)
		(end 118.272052 -96.814386)
		(width 0.0889)
		(layer "In11.Cu")
		(net "M_M_DQ<50>")
	)
	(arc
		(start 119.989092 -104.739186)
		(mid 119.90987 -104.450068)
		(end 119.982742 -104.159304)
		(width 0.0889)
		(layer "In11.Cu")
		(net "M_M_DQ<50>")
	)
	(arc
		(start 119.989092 -102.757986)
		(mid 119.90987 -102.468868)
		(end 119.982742 -102.178104)
		(width 0.0889)
		(layer "In11.Cu")
		(net "M_M_DQ<50>")
	)
	(arc
		(start 117.413532 -96.319086)
		(mid 117.271849 -96.175282)
		(end 117.077998 -96.118934)
		(width 0.0889)
		(layer "In11.Cu")
		(net "M_M_DQ<50>")
	)
	(arc
		(start 114.914172 -91.612974)
		(mid 114.88164 -91.363924)
		(end 114.944398 -91.120722)
		(width 0.0889)
		(layer "In11.Cu")
		(net "M_M_DQ<50>")
	)
	(arc
		(start 116.195348 -95.623888)
		(mid 115.696467 -95.328451)
		(end 115.690142 -94.748604)
		(width 0.0889)
		(layer "In11.Cu")
		(net "M_M_DQ<50>")
	)
	(arc
		(start 119.989092 -103.748586)
		(mid 119.90987 -103.459468)
		(end 119.982742 -103.168704)
		(width 0.0889)
		(layer "In11.Cu")
		(net "M_M_DQ<50>")
	)
	(arc
		(start 116.555012 -95.823786)
		(mid 116.414933 -95.68105)
		(end 116.223288 -95.623888)
		(width 0.0889)
		(layer "In11.Cu")
		(net "M_M_DQ<50>")
	)
	(arc
		(start 119.989092 -100.776786)
		(mid 119.90987 -100.487668)
		(end 119.982742 -100.196904)
		(width 0.0889)
		(layer "In11.Cu")
		(net "M_M_DQ<50>")
	)
	(arc
		(start 115.477036 -92.177108)
		(mid 115.129152 -91.961357)
		(end 114.914172 -91.612974)
		(width 0.0889)
		(layer "In11.Cu")
		(net "M_M_DQ<50>")
	)
	(arc
		(start 119.993918 -100.1776)
		(mid 120.042673 -99.981248)
		(end 119.989092 -99.786186)
		(width 0.0889)
		(layer "In11.Cu")
		(net "M_M_DQ<50>")
	)
	(arc
		(start 119.993918 -103.1494)
		(mid 120.042673 -102.953048)
		(end 119.989092 -102.757986)
		(width 0.0889)
		(layer "In11.Cu")
		(net "M_M_DQ<50>")
	)
	(arc
		(start 115.696492 -93.747336)
		(mid 115.749962 -93.552273)
		(end 115.701318 -93.355922)
		(width 0.0889)
		(layer "In11.Cu")
		(net "M_M_DQ<50>")
	)
	(arc
		(start 119.993918 -98.1964)
		(mid 119.990171 -97.807144)
		(end 119.657368 -97.605088)
		(width 0.0889)
		(layer "In11.Cu")
		(net "M_M_DQ<50>")
	)
	(arc
		(start 117.907562 -96.614488)
		(mid 117.622138 -96.531021)
		(end 117.413532 -96.319086)
		(width 0.0889)
		(layer "In11.Cu")
		(net "M_M_DQ<50>")
	)
	(arc
		(start 115.696492 -94.33814)
		(mid 115.617361 -94.042738)
		(end 115.696492 -93.747336)
		(width 0.0889)
		(layer "In11.Cu")
		(net "M_M_DQ<50>")
	)
	(arc
		(start 118.272052 -96.814386)
		(mid 118.131973 -96.67165)
		(end 117.940328 -96.614488)
		(width 0.0889)
		(layer "In11.Cu")
		(net "M_M_DQ<50>")
	)
	(arc
		(start 119.993918 -105.1306)
		(mid 120.042673 -104.934248)
		(end 119.989092 -104.739186)
		(width 0.0889)
		(layer "In11.Cu")
		(net "M_M_DQ<50>")
	)
	(arc
		(start 119.624602 -97.605088)
		(mid 119.339178 -97.521621)
		(end 119.130572 -97.309686)
		(width 0.0889)
		(layer "In11.Cu")
		(net "M_M_DQ<50>")
	)
	(arc
		(start 119.989092 -101.767386)
		(mid 119.90987 -101.478268)
		(end 119.982742 -101.187504)
		(width 0.0889)
		(layer "In11.Cu")
		(net "M_M_DQ<50>")
	)
	(arc
		(start 117.045232 -96.118934)
		(mid 116.762015 -96.034653)
		(end 116.555012 -95.823786)
		(width 0.0889)
		(layer "In11.Cu")
		(net "M_M_DQ<50>")
	)
	(segment
		(start 32.249364 -156.87294)
		(end 32.249364 -155.547568)
		(width 0.1651)
		(layer "F.Cu")
		(net "M_M_DQ<4>")
	)
	(segment
		(start 32.249364 -155.547568)
		(end 32.15132 -155.0162)
		(width 0.1651)
		(layer "F.Cu")
		(net "M_M_DQ<4>")
	)
	(segment
		(start 78.051406 -85.30844)
		(end 77.479906 -85.30844)
		(width 0.1651)
		(layer "F.Cu")
		(net "M_M_DQ<4>")
	)
	(via
		(at 32.15132 -155.0162)
		(size 0.508)
		(drill 0.254)
		(layers "F.Cu" "B.Cu")
		(net "M_M_DQ<4>")
	)
	(via
		(at 31.39948 -150.814278)
		(size 0.508)
		(drill 0.254)
		(layers "F.Cu" "B.Cu")
		(net "M_M_DQ<4>")
	)
	(via
		(at 77.479906 -85.30844)
		(size 0.508)
		(drill 0.254)
		(layers "F.Cu" "B.Cu")
		(net "M_M_DQ<4>")
	)
	(segment
		(start 31.39948 -152.078436)
		(end 31.39948 -150.814278)
		(width 0.1651)
		(layer "B.Cu")
		(net "M_M_DQ<4>")
	)
	(segment
		(start 31.28137 -150.696168)
		(end 31.39948 -150.814278)
		(width 0.14224)
		(layer "In11.Cu")
		(net "M_M_DQ<4>")
	)
	(segment
		(start 30.96641 -153.83129)
		(end 32.15132 -155.0162)
		(width 0.14224)
		(layer "In11.Cu")
		(net "M_M_DQ<4>")
	)
	(segment
		(start 66.914268 -86.69909)
		(end 66.701416 -86.486238)
		(width 0.0889)
		(layer "In11.Cu")
		(net "M_M_DQ<4>")
	)
	(segment
		(start 32.306768 -125.827536)
		(end 31.955994 -126.674118)
		(width 0.14224)
		(layer "In11.Cu")
		(net "M_M_DQ<4>")
	)
	(segment
		(start 68.905882 -85.70849)
		(end 68.873116 -85.70849)
		(width 0.0889)
		(layer "In11.Cu")
		(net "M_M_DQ<4>")
	)
	(segment
		(start 76.639166 -84.222336)
		(end 76.6064 -84.222336)
		(width 0.0889)
		(layer "In11.Cu")
		(net "M_M_DQ<4>")
	)
	(segment
		(start 38.301168 -106.756708)
		(end 38.301168 -107.5182)
		(width 0.14224)
		(layer "In11.Cu")
		(net "M_M_DQ<4>")
	)
	(segment
		(start 31.874968 -136.353296)
		(end 31.874968 -139.38123)
		(width 0.14224)
		(layer "In11.Cu")
		(net "M_M_DQ<4>")
	)
	(segment
		(start 31.68777 -144.412208)
		(end 31.68777 -145.51025)
		(width 0.14224)
		(layer "In11.Cu")
		(net "M_M_DQ<4>")
	)
	(segment
		(start 75.784456 -83.72729)
		(end 75.75169 -83.72729)
		(width 0.0889)
		(layer "In11.Cu")
		(net "M_M_DQ<4>")
	)
	(segment
		(start 31.83255 -148.878798)
		(end 31.655004 -149.30755)
		(width 0.14224)
		(layer "In11.Cu")
		(net "M_M_DQ<4>")
	)
	(segment
		(start 31.874968 -139.38123)
		(end 31.712662 -139.773152)
		(width 0.14224)
		(layer "In11.Cu")
		(net "M_M_DQ<4>")
	)
	(segment
		(start 34.28873 -111.0488)
		(end 32.306768 -113.030762)
		(width 0.14224)
		(layer "In11.Cu")
		(net "M_M_DQ<4>")
	)
	(segment
		(start 31.89732 -143.90624)
		(end 31.68777 -144.412208)
		(width 0.14224)
		(layer "In11.Cu")
		(net "M_M_DQ<4>")
	)
	(segment
		(start 77.479906 -85.30844)
		(end 77.150468 -84.547456)
		(width 0.0889)
		(layer "In11.Cu")
		(net "M_M_DQ<4>")
	)
	(segment
		(start 70.622922 -84.71789)
		(end 70.590156 -84.71789)
		(width 0.0889)
		(layer "In11.Cu")
		(net "M_M_DQ<4>")
	)
	(segment
		(start 31.844996 -129.794)
		(end 31.802832 -129.8956)
		(width 0.14224)
		(layer "In11.Cu")
		(net "M_M_DQ<4>")
	)
	(segment
		(start 39.958518 -104.15905)
		(end 39.533576 -104.583992)
		(width 0.14224)
		(layer "In11.Cu")
		(net "M_M_DQ<4>")
	)
	(segment
		(start 66.701416 -86.486238)
		(end 66.701416 -86.181438)
		(width 0.0889)
		(layer "In11.Cu")
		(net "M_M_DQ<4>")
	)
	(segment
		(start 42.581322 -100.6475)
		(end 40.587168 -102.641654)
		(width 0.14224)
		(layer "In11.Cu")
		(net "M_M_DQ<4>")
	)
	(segment
		(start 31.712662 -139.773152)
		(end 31.712662 -140.694918)
		(width 0.14224)
		(layer "In11.Cu")
		(net "M_M_DQ<4>")
	)
	(segment
		(start 66.701416 -86.181438)
		(end 66.381884 -85.861906)
		(width 0.0889)
		(layer "In11.Cu")
		(net "M_M_DQ<4>")
	)
	(segment
		(start 62.203584 -86.0044)
		(end 50.721768 -97.486216)
		(width 0.14224)
		(layer "In11.Cu")
		(net "M_M_DQ<4>")
	)
	(segment
		(start 31.655004 -149.30755)
		(end 31.28137 -149.681184)
		(width 0.14224)
		(layer "In11.Cu")
		(net "M_M_DQ<4>")
	)
	(segment
		(start 77.150468 -84.547456)
		(end 77.133196 -84.517738)
		(width 0.0889)
		(layer "In11.Cu")
		(net "M_M_DQ<4>")
	)
	(segment
		(start 31.874968 -126.869952)
		(end 31.874968 -129.721864)
		(width 0.14224)
		(layer "In11.Cu")
		(net "M_M_DQ<4>")
	)
	(segment
		(start 31.874968 -129.721864)
		(end 31.844996 -129.794)
		(width 0.14224)
		(layer "In11.Cu")
		(net "M_M_DQ<4>")
	)
	(segment
		(start 66.381884 -85.861906)
		(end 65.267586 -85.861906)
		(width 0.0889)
		(layer "In11.Cu")
		(net "M_M_DQ<4>")
	)
	(segment
		(start 31.955994 -126.674118)
		(end 31.874968 -126.869952)
		(width 0.14224)
		(layer "In11.Cu")
		(net "M_M_DQ<4>")
	)
	(segment
		(start 50.721768 -98.095054)
		(end 48.169322 -100.6475)
		(width 0.14224)
		(layer "In11.Cu")
		(net "M_M_DQ<4>")
	)
	(segment
		(start 68.051172 -86.203536)
		(end 68.018406 -86.203536)
		(width 0.0889)
		(layer "In11.Cu")
		(net "M_M_DQ<4>")
	)
	(segment
		(start 39.533576 -104.583992)
		(end 38.80231 -105.547414)
		(width 0.14224)
		(layer "In11.Cu")
		(net "M_M_DQ<4>")
	)
	(segment
		(start 31.89732 -141.140688)
		(end 31.89732 -143.90624)
		(width 0.14224)
		(layer "In11.Cu")
		(net "M_M_DQ<4>")
	)
	(segment
		(start 65.267586 -85.861906)
		(end 65.125092 -86.0044)
		(width 0.0889)
		(layer "In11.Cu")
		(net "M_M_DQ<4>")
	)
	(segment
		(start 31.68777 -145.51025)
		(end 31.83255 -145.859754)
		(width 0.14224)
		(layer "In11.Cu")
		(net "M_M_DQ<4>")
	)
	(segment
		(start 38.301168 -107.5182)
		(end 34.770568 -111.0488)
		(width 0.14224)
		(layer "In11.Cu")
		(net "M_M_DQ<4>")
	)
	(segment
		(start 74.067416 -82.73669)
		(end 74.024236 -82.73669)
		(width 0.0889)
		(layer "In11.Cu")
		(net "M_M_DQ<4>")
	)
	(segment
		(start 31.83255 -145.859754)
		(end 31.83255 -148.878798)
		(width 0.14224)
		(layer "In11.Cu")
		(net "M_M_DQ<4>")
	)
	(segment
		(start 31.66872 -134.829296)
		(end 31.66872 -135.855202)
		(width 0.14224)
		(layer "In11.Cu")
		(net "M_M_DQ<4>")
	)
	(segment
		(start 40.587168 -102.641654)
		(end 39.958518 -104.15905)
		(width 0.14224)
		(layer "In11.Cu")
		(net "M_M_DQ<4>")
	)
	(segment
		(start 32.306768 -113.030762)
		(end 32.306768 -125.827536)
		(width 0.14224)
		(layer "In11.Cu")
		(net "M_M_DQ<4>")
	)
	(segment
		(start 31.89732 -134.2771)
		(end 31.66872 -134.829296)
		(width 0.14224)
		(layer "In11.Cu")
		(net "M_M_DQ<4>")
	)
	(segment
		(start 31.66872 -131.085082)
		(end 31.89732 -131.637024)
		(width 0.14224)
		(layer "In11.Cu")
		(net "M_M_DQ<4>")
	)
	(segment
		(start 72.339962 -83.72729)
		(end 72.307196 -83.72729)
		(width 0.0889)
		(layer "In11.Cu")
		(net "M_M_DQ<4>")
	)
	(segment
		(start 31.66872 -135.855202)
		(end 31.874968 -136.353296)
		(width 0.14224)
		(layer "In11.Cu")
		(net "M_M_DQ<4>")
	)
	(segment
		(start 67.188842 -86.69909)
		(end 66.914268 -86.69909)
		(width 0.0889)
		(layer "In11.Cu")
		(net "M_M_DQ<4>")
	)
	(segment
		(start 48.169322 -100.6475)
		(end 42.581322 -100.6475)
		(width 0.14224)
		(layer "In11.Cu")
		(net "M_M_DQ<4>")
	)
	(segment
		(start 34.770568 -111.0488)
		(end 34.28873 -111.0488)
		(width 0.14224)
		(layer "In11.Cu")
		(net "M_M_DQ<4>")
	)
	(segment
		(start 31.712662 -140.694918)
		(end 31.89732 -141.140688)
		(width 0.14224)
		(layer "In11.Cu")
		(net "M_M_DQ<4>")
	)
	(segment
		(start 69.768212 -85.212936)
		(end 69.735446 -85.212936)
		(width 0.0889)
		(layer "In11.Cu")
		(net "M_M_DQ<4>")
	)
	(segment
		(start 65.125092 -86.0044)
		(end 62.203584 -86.0044)
		(width 0.14224)
		(layer "In11.Cu")
		(net "M_M_DQ<4>")
	)
	(segment
		(start 74.922126 -83.231736)
		(end 74.886312 -83.231736)
		(width 0.0889)
		(layer "In11.Cu")
		(net "M_M_DQ<4>")
	)
	(segment
		(start 31.89732 -131.637024)
		(end 31.89732 -134.2771)
		(width 0.14224)
		(layer "In11.Cu")
		(net "M_M_DQ<4>")
	)
	(segment
		(start 50.721768 -97.486216)
		(end 50.721768 -98.095054)
		(width 0.14224)
		(layer "In11.Cu")
		(net "M_M_DQ<4>")
	)
	(segment
		(start 31.28137 -149.681184)
		(end 31.28137 -150.696168)
		(width 0.14224)
		(layer "In11.Cu")
		(net "M_M_DQ<4>")
	)
	(segment
		(start 38.80231 -105.547414)
		(end 38.301168 -106.756708)
		(width 0.14224)
		(layer "In11.Cu")
		(net "M_M_DQ<4>")
	)
	(segment
		(start 31.39948 -150.814278)
		(end 30.96641 -151.247348)
		(width 0.14224)
		(layer "In11.Cu")
		(net "M_M_DQ<4>")
	)
	(segment
		(start 31.802832 -129.8956)
		(end 31.66872 -130.219958)
		(width 0.14224)
		(layer "In11.Cu")
		(net "M_M_DQ<4>")
	)
	(segment
		(start 31.66872 -130.219958)
		(end 31.66872 -131.085082)
		(width 0.14224)
		(layer "In11.Cu")
		(net "M_M_DQ<4>")
	)
	(segment
		(start 30.96641 -151.247348)
		(end 30.96641 -153.83129)
		(width 0.14224)
		(layer "In11.Cu")
		(net "M_M_DQ<4>")
	)
	(segment
		(start 73.20534 -83.231736)
		(end 73.169526 -83.231736)
		(width 0.0889)
		(layer "In11.Cu")
		(net "M_M_DQ<4>")
	)
	(segment
		(start 71.485252 -84.222336)
		(end 71.452486 -84.222336)
		(width 0.0889)
		(layer "In11.Cu")
		(net "M_M_DQ<4>")
	)
	(arc
		(start 73.534016 -83.031838)
		(mid 73.395272 -83.173871)
		(end 73.20534 -83.231736)
		(width 0.0889)
		(layer "In11.Cu")
		(net "M_M_DQ<4>")
	)
	(arc
		(start 74.886312 -83.231736)
		(mid 74.696383 -83.173866)
		(end 74.557636 -83.031838)
		(width 0.0889)
		(layer "In11.Cu")
		(net "M_M_DQ<4>")
	)
	(arc
		(start 73.169526 -83.231736)
		(mid 72.884102 -83.315203)
		(end 72.675496 -83.527138)
		(width 0.0889)
		(layer "In11.Cu")
		(net "M_M_DQ<4>")
	)
	(arc
		(start 70.590156 -84.71789)
		(mid 70.306939 -84.802171)
		(end 70.099936 -85.013038)
		(width 0.0889)
		(layer "In11.Cu")
		(net "M_M_DQ<4>")
	)
	(arc
		(start 76.274676 -84.022438)
		(mid 76.067672 -83.811574)
		(end 75.784456 -83.72729)
		(width 0.0889)
		(layer "In11.Cu")
		(net "M_M_DQ<4>")
	)
	(arc
		(start 72.675496 -83.527138)
		(mid 72.533813 -83.670942)
		(end 72.339962 -83.72729)
		(width 0.0889)
		(layer "In11.Cu")
		(net "M_M_DQ<4>")
	)
	(arc
		(start 76.6064 -84.222336)
		(mid 76.414758 -84.16517)
		(end 76.274676 -84.022438)
		(width 0.0889)
		(layer "In11.Cu")
		(net "M_M_DQ<4>")
	)
	(arc
		(start 72.307196 -83.72729)
		(mid 72.023979 -83.811571)
		(end 71.816976 -84.022438)
		(width 0.0889)
		(layer "In11.Cu")
		(net "M_M_DQ<4>")
	)
	(arc
		(start 71.452486 -84.222336)
		(mid 71.167062 -84.305803)
		(end 70.958456 -84.517738)
		(width 0.0889)
		(layer "In11.Cu")
		(net "M_M_DQ<4>")
	)
	(arc
		(start 69.735446 -85.212936)
		(mid 69.450022 -85.296403)
		(end 69.241416 -85.508338)
		(width 0.0889)
		(layer "In11.Cu")
		(net "M_M_DQ<4>")
	)
	(arc
		(start 68.873116 -85.70849)
		(mid 68.589899 -85.792771)
		(end 68.382896 -86.003638)
		(width 0.0889)
		(layer "In11.Cu")
		(net "M_M_DQ<4>")
	)
	(arc
		(start 67.524376 -86.498938)
		(mid 67.382693 -86.642742)
		(end 67.188842 -86.69909)
		(width 0.0889)
		(layer "In11.Cu")
		(net "M_M_DQ<4>")
	)
	(arc
		(start 70.099936 -85.013038)
		(mid 69.959857 -85.155774)
		(end 69.768212 -85.212936)
		(width 0.0889)
		(layer "In11.Cu")
		(net "M_M_DQ<4>")
	)
	(arc
		(start 68.382896 -86.003638)
		(mid 68.242817 -86.146374)
		(end 68.051172 -86.203536)
		(width 0.0889)
		(layer "In11.Cu")
		(net "M_M_DQ<4>")
	)
	(arc
		(start 70.958456 -84.517738)
		(mid 70.816773 -84.661542)
		(end 70.622922 -84.71789)
		(width 0.0889)
		(layer "In11.Cu")
		(net "M_M_DQ<4>")
	)
	(arc
		(start 71.816976 -84.022438)
		(mid 71.676897 -84.165174)
		(end 71.485252 -84.222336)
		(width 0.0889)
		(layer "In11.Cu")
		(net "M_M_DQ<4>")
	)
	(arc
		(start 74.557636 -83.031838)
		(mid 74.350632 -82.820974)
		(end 74.067416 -82.73669)
		(width 0.0889)
		(layer "In11.Cu")
		(net "M_M_DQ<4>")
	)
	(arc
		(start 77.133196 -84.517738)
		(mid 76.924588 -84.305806)
		(end 76.639166 -84.222336)
		(width 0.0889)
		(layer "In11.Cu")
		(net "M_M_DQ<4>")
	)
	(arc
		(start 75.416156 -83.527138)
		(mid 75.207548 -83.315206)
		(end 74.922126 -83.231736)
		(width 0.0889)
		(layer "In11.Cu")
		(net "M_M_DQ<4>")
	)
	(arc
		(start 75.75169 -83.72729)
		(mid 75.55784 -83.67094)
		(end 75.416156 -83.527138)
		(width 0.0889)
		(layer "In11.Cu")
		(net "M_M_DQ<4>")
	)
	(arc
		(start 69.241416 -85.508338)
		(mid 69.099733 -85.652142)
		(end 68.905882 -85.70849)
		(width 0.0889)
		(layer "In11.Cu")
		(net "M_M_DQ<4>")
	)
	(arc
		(start 68.018406 -86.203536)
		(mid 67.732982 -86.287003)
		(end 67.524376 -86.498938)
		(width 0.0889)
		(layer "In11.Cu")
		(net "M_M_DQ<4>")
	)
	(arc
		(start 74.024236 -82.73669)
		(mid 73.741019 -82.820971)
		(end 73.534016 -83.031838)
		(width 0.0889)
		(layer "In11.Cu")
		(net "M_M_DQ<4>")
	)
	(segment
		(start 135.099552 -152.273)
		(end 135.099552 -153.542746)
		(width 0.1651)
		(layer "F.Cu")
		(net "M_M_DQ<49>")
	)
	(segment
		(start 112.202722 -92.061538)
		(end 112.774222 -92.061538)
		(width 0.1651)
		(layer "F.Cu")
		(net "M_M_DQ<49>")
	)
	(via
		(at 135.771636 -149.533356)
		(size 0.508)
		(drill 0.254)
		(layers "F.Cu" "B.Cu")
		(net "M_M_DQ<49>")
	)
	(via
		(at 112.774222 -92.061538)
		(size 0.508)
		(drill 0.254)
		(layers "F.Cu" "B.Cu")
		(net "M_M_DQ<49>")
	)
	(via
		(at 135.099552 -153.542746)
		(size 0.508)
		(drill 0.254)
		(layers "F.Cu" "B.Cu")
		(net "M_M_DQ<49>")
	)
	(segment
		(start 135.949436 -147.478496)
		(end 135.949436 -148.852382)
		(width 0.1651)
		(layer "B.Cu")
		(net "M_M_DQ<49>")
	)
	(segment
		(start 135.949436 -148.852382)
		(end 135.771636 -149.030182)
		(width 0.1651)
		(layer "B.Cu")
		(net "M_M_DQ<49>")
	)
	(segment
		(start 135.771636 -149.030182)
		(end 135.771636 -149.533356)
		(width 0.1651)
		(layer "B.Cu")
		(net "M_M_DQ<49>")
	)
	(segment
		(start 136.25957 -143.697198)
		(end 136.25957 -148.956522)
		(width 0.14224)
		(layer "In11.Cu")
		(net "M_M_DQ<49>")
	)
	(segment
		(start 116.720112 -100.281486)
		(end 116.713254 -100.293678)
		(width 0.0889)
		(layer "In11.Cu")
		(net "M_M_DQ<49>")
	)
	(segment
		(start 136.25957 -141.392656)
		(end 136.370568 -141.503654)
		(width 0.14224)
		(layer "In11.Cu")
		(net "M_M_DQ<49>")
	)
	(segment
		(start 112.422686 -94.234)
		(end 112.427512 -94.242636)
		(width 0.0889)
		(layer "In11.Cu")
		(net "M_M_DQ<49>")
	)
	(segment
		(start 129.218944 -121.840752)
		(end 129.218944 -121.533412)
		(width 0.14224)
		(layer "In11.Cu")
		(net "M_M_DQ<49>")
	)
	(segment
		(start 132.071618 -121.840752)
		(end 132.071618 -121.5263)
		(width 0.14224)
		(layer "In11.Cu")
		(net "M_M_DQ<49>")
	)
	(segment
		(start 131.408678 -121.5263)
		(end 131.408678 -121.840752)
		(width 0.14224)
		(layer "In11.Cu")
		(net "M_M_DQ<49>")
	)
	(segment
		(start 135.260842 -151.677624)
		(end 135.475218 -151.892)
		(width 0.14224)
		(layer "In11.Cu")
		(net "M_M_DQ<49>")
	)
	(segment
		(start 132.071618 -121.5263)
		(end 132.226558 -121.37136)
		(width 0.14224)
		(layer "In11.Cu")
		(net "M_M_DQ<49>")
	)
	(segment
		(start 135.749284 -149.533356)
		(end 135.32104 -149.9616)
		(width 0.14224)
		(layer "In11.Cu")
		(net "M_M_DQ<49>")
	)
	(segment
		(start 135.32104 -150.391368)
		(end 135.551418 -150.621746)
		(width 0.14224)
		(layer "In11.Cu")
		(net "M_M_DQ<49>")
	)
	(segment
		(start 136.25957 -126.889256)
		(end 136.703562 -127.333248)
		(width 0.14224)
		(layer "In11.Cu")
		(net "M_M_DQ<49>")
	)
	(segment
		(start 136.101074 -128.01854)
		(end 136.101074 -128.24206)
		(width 0.14224)
		(layer "In11.Cu")
		(net "M_M_DQ<49>")
	)
	(segment
		(start 129.064004 -121.995692)
		(end 129.218944 -121.840752)
		(width 0.14224)
		(layer "In11.Cu")
		(net "M_M_DQ<49>")
	)
	(segment
		(start 124.842778 -121.995692)
		(end 127.738124 -121.995692)
		(width 0.14224)
		(layer "In11.Cu")
		(net "M_M_DQ<49>")
	)
	(segment
		(start 136.703562 -128.902206)
		(end 136.25957 -129.346198)
		(width 0.14224)
		(layer "In11.Cu")
		(net "M_M_DQ<49>")
	)
	(segment
		(start 131.916678 -121.995692)
		(end 132.071618 -121.840752)
		(width 0.14224)
		(layer "In11.Cu")
		(net "M_M_DQ<49>")
	)
	(segment
		(start 135.475218 -151.892)
		(end 135.475218 -152.3238)
		(width 0.14224)
		(layer "In11.Cu")
		(net "M_M_DQ<49>")
	)
	(segment
		(start 112.422686 -96.2152)
		(end 112.427512 -96.223836)
		(width 0.0889)
		(layer "In11.Cu")
		(net "M_M_DQ<49>")
	)
	(segment
		(start 128.710944 -121.995692)
		(end 129.064004 -121.995692)
		(width 0.14224)
		(layer "In11.Cu")
		(net "M_M_DQ<49>")
	)
	(segment
		(start 136.370568 -134.0612)
		(end 136.25957 -134.172198)
		(width 0.14224)
		(layer "In11.Cu")
		(net "M_M_DQ<49>")
	)
	(segment
		(start 136.25957 -138.820398)
		(end 136.25957 -141.392656)
		(width 0.14224)
		(layer "In11.Cu")
		(net "M_M_DQ<49>")
	)
	(segment
		(start 116.729002 -106.209846)
		(end 116.720112 -106.225086)
		(width 0.0889)
		(layer "In11.Cu")
		(net "M_M_DQ<49>")
	)
	(segment
		(start 136.256014 -127.8636)
		(end 136.101074 -128.01854)
		(width 0.14224)
		(layer "In11.Cu")
		(net "M_M_DQ<49>")
	)
	(segment
		(start 136.370568 -136.686798)
		(end 136.370568 -138.7094)
		(width 0.14224)
		(layer "In11.Cu")
		(net "M_M_DQ<49>")
	)
	(segment
		(start 116.579142 -113.732056)
		(end 124.842778 -121.995692)
		(width 0.14224)
		(layer "In11.Cu")
		(net "M_M_DQ<49>")
	)
	(segment
		(start 136.101074 -128.24206)
		(end 136.256014 -128.397)
		(width 0.14224)
		(layer "In11.Cu")
		(net "M_M_DQ<49>")
	)
	(segment
		(start 136.703562 -127.70866)
		(end 136.548622 -127.8636)
		(width 0.14224)
		(layer "In11.Cu")
		(net "M_M_DQ<49>")
	)
	(segment
		(start 116.729002 -102.247446)
		(end 116.713254 -102.274878)
		(width 0.0889)
		(layer "In11.Cu")
		(net "M_M_DQ<49>")
	)
	(segment
		(start 116.729002 -103.238046)
		(end 116.713254 -103.265478)
		(width 0.0889)
		(layer "In11.Cu")
		(net "M_M_DQ<49>")
	)
	(segment
		(start 112.444276 -92.823284)
		(end 112.427512 -92.851986)
		(width 0.0889)
		(layer "In11.Cu")
		(net "M_M_DQ<49>")
	)
	(segment
		(start 129.726944 -121.378472)
		(end 129.881884 -121.533412)
		(width 0.14224)
		(layer "In11.Cu")
		(net "M_M_DQ<49>")
	)
	(segment
		(start 112.427512 -96.223836)
		(end 112.433862 -96.234504)
		(width 0.0889)
		(layer "In11.Cu")
		(net "M_M_DQ<49>")
	)
	(segment
		(start 131.253738 -121.37136)
		(end 131.408678 -121.5263)
		(width 0.14224)
		(layer "In11.Cu")
		(net "M_M_DQ<49>")
	)
	(segment
		(start 136.25957 -131.740656)
		(end 136.370568 -131.851654)
		(width 0.14224)
		(layer "In11.Cu")
		(net "M_M_DQ<49>")
	)
	(segment
		(start 116.726462 -100.270818)
		(end 116.720112 -100.281486)
		(width 0.0889)
		(layer "In11.Cu")
		(net "M_M_DQ<49>")
	)
	(segment
		(start 136.25957 -129.346198)
		(end 136.25957 -131.740656)
		(width 0.14224)
		(layer "In11.Cu")
		(net "M_M_DQ<49>")
	)
	(segment
		(start 128.401064 -121.378472)
		(end 128.556004 -121.533412)
		(width 0.14224)
		(layer "In11.Cu")
		(net "M_M_DQ<49>")
	)
	(segment
		(start 129.218944 -121.533412)
		(end 129.373884 -121.378472)
		(width 0.14224)
		(layer "In11.Cu")
		(net "M_M_DQ<49>")
	)
	(segment
		(start 116.729002 -105.219246)
		(end 116.720112 -105.234486)
		(width 0.0889)
		(layer "In11.Cu")
		(net "M_M_DQ<49>")
	)
	(segment
		(start 127.738124 -121.995692)
		(end 127.893064 -121.840752)
		(width 0.14224)
		(layer "In11.Cu")
		(net "M_M_DQ<49>")
	)
	(segment
		(start 116.729002 -104.228646)
		(end 116.713254 -104.256078)
		(width 0.0889)
		(layer "In11.Cu")
		(net "M_M_DQ<49>")
	)
	(segment
		(start 135.551418 -151.026368)
		(end 135.260842 -151.316944)
		(width 0.14224)
		(layer "In11.Cu")
		(net "M_M_DQ<49>")
	)
	(segment
		(start 130.036824 -121.995692)
		(end 130.590798 -121.995692)
		(width 0.14224)
		(layer "In11.Cu")
		(net "M_M_DQ<49>")
	)
	(segment
		(start 136.256014 -128.397)
		(end 136.548622 -128.397)
		(width 0.14224)
		(layer "In11.Cu")
		(net "M_M_DQ<49>")
	)
	(segment
		(start 136.703562 -127.333248)
		(end 136.703562 -127.70866)
		(width 0.14224)
		(layer "In11.Cu")
		(net "M_M_DQ<49>")
	)
	(segment
		(start 136.548622 -128.397)
		(end 136.703562 -128.55194)
		(width 0.14224)
		(layer "In11.Cu")
		(net "M_M_DQ<49>")
	)
	(segment
		(start 135.475218 -152.3238)
		(end 135.260842 -152.538176)
		(width 0.14224)
		(layer "In11.Cu")
		(net "M_M_DQ<49>")
	)
	(segment
		(start 114.480086 -98.405188)
		(end 114.512852 -98.405188)
		(width 0.0889)
		(layer "In11.Cu")
		(net "M_M_DQ<49>")
	)
	(segment
		(start 135.771636 -149.533356)
		(end 135.749284 -149.533356)
		(width 0.14224)
		(layer "In11.Cu")
		(net "M_M_DQ<49>")
	)
	(segment
		(start 115.334796 -98.900234)
		(end 115.367562 -98.900234)
		(width 0.0889)
		(layer "In11.Cu")
		(net "M_M_DQ<49>")
	)
	(segment
		(start 135.771636 -149.444456)
		(end 135.771636 -149.533356)
		(width 0.14224)
		(layer "In11.Cu")
		(net "M_M_DQ<49>")
	)
	(segment
		(start 112.427512 -93.252036)
		(end 112.433862 -93.262704)
		(width 0.0889)
		(layer "In11.Cu")
		(net "M_M_DQ<49>")
	)
	(segment
		(start 116.652294 -106.319828)
		(end 116.579142 -106.555286)
		(width 0.0889)
		(layer "In11.Cu")
		(net "M_M_DQ<49>")
	)
	(segment
		(start 136.370568 -141.503654)
		(end 136.370568 -143.5862)
		(width 0.14224)
		(layer "In11.Cu")
		(net "M_M_DQ<49>")
	)
	(segment
		(start 136.25957 -148.956522)
		(end 135.771636 -149.444456)
		(width 0.14224)
		(layer "In11.Cu")
		(net "M_M_DQ<49>")
	)
	(segment
		(start 127.893064 -121.840752)
		(end 127.893064 -121.533412)
		(width 0.14224)
		(layer "In11.Cu")
		(net "M_M_DQ<49>")
	)
	(segment
		(start 135.551418 -150.621746)
		(end 135.551418 -151.026368)
		(width 0.14224)
		(layer "In11.Cu")
		(net "M_M_DQ<49>")
	)
	(segment
		(start 127.893064 -121.533412)
		(end 128.048004 -121.378472)
		(width 0.14224)
		(layer "In11.Cu")
		(net "M_M_DQ<49>")
	)
	(segment
		(start 112.774222 -92.061538)
		(end 112.444276 -92.823284)
		(width 0.0889)
		(layer "In11.Cu")
		(net "M_M_DQ<49>")
	)
	(segment
		(start 113.617756 -97.909634)
		(end 113.650522 -97.909634)
		(width 0.0889)
		(layer "In11.Cu")
		(net "M_M_DQ<49>")
	)
	(segment
		(start 136.25957 -124.420376)
		(end 136.25957 -126.889256)
		(width 0.14224)
		(layer "In11.Cu")
		(net "M_M_DQ<49>")
	)
	(segment
		(start 116.579142 -106.78287)
		(end 116.579142 -113.732056)
		(width 0.14224)
		(layer "In11.Cu")
		(net "M_M_DQ<49>")
	)
	(segment
		(start 130.590798 -121.995692)
		(end 130.745738 -121.840752)
		(width 0.14224)
		(layer "In11.Cu")
		(net "M_M_DQ<49>")
	)
	(segment
		(start 131.563618 -121.995692)
		(end 131.916678 -121.995692)
		(width 0.14224)
		(layer "In11.Cu")
		(net "M_M_DQ<49>")
	)
	(segment
		(start 135.260842 -152.538176)
		(end 135.260842 -152.846024)
		(width 0.14224)
		(layer "In11.Cu")
		(net "M_M_DQ<49>")
	)
	(segment
		(start 112.763046 -97.414588)
		(end 112.795812 -97.414588)
		(width 0.0889)
		(layer "In11.Cu")
		(net "M_M_DQ<49>")
	)
	(segment
		(start 135.260842 -151.316944)
		(end 135.260842 -151.677624)
		(width 0.14224)
		(layer "In11.Cu")
		(net "M_M_DQ<49>")
	)
	(segment
		(start 135.260842 -152.846024)
		(end 135.500618 -153.0858)
		(width 0.14224)
		(layer "In11.Cu")
		(net "M_M_DQ<49>")
	)
	(segment
		(start 136.703562 -128.55194)
		(end 136.703562 -128.902206)
		(width 0.14224)
		(layer "In11.Cu")
		(net "M_M_DQ<49>")
	)
	(segment
		(start 130.745738 -121.5263)
		(end 130.900678 -121.37136)
		(width 0.14224)
		(layer "In11.Cu")
		(net "M_M_DQ<49>")
	)
	(segment
		(start 136.370568 -143.5862)
		(end 136.25957 -143.697198)
		(width 0.14224)
		(layer "In11.Cu")
		(net "M_M_DQ<49>")
	)
	(segment
		(start 136.548622 -127.8636)
		(end 136.256014 -127.8636)
		(width 0.14224)
		(layer "In11.Cu")
		(net "M_M_DQ<49>")
	)
	(segment
		(start 129.881884 -121.533412)
		(end 129.881884 -121.840752)
		(width 0.14224)
		(layer "In11.Cu")
		(net "M_M_DQ<49>")
	)
	(segment
		(start 135.32104 -149.9616)
		(end 135.32104 -150.391368)
		(width 0.14224)
		(layer "In11.Cu")
		(net "M_M_DQ<49>")
	)
	(segment
		(start 116.579142 -106.555286)
		(end 116.579142 -106.78287)
		(width 0.0889)
		(layer "In11.Cu")
		(net "M_M_DQ<49>")
	)
	(segment
		(start 112.422686 -93.2434)
		(end 112.427512 -93.252036)
		(width 0.0889)
		(layer "In11.Cu")
		(net "M_M_DQ<49>")
	)
	(segment
		(start 129.881884 -121.840752)
		(end 130.036824 -121.995692)
		(width 0.14224)
		(layer "In11.Cu")
		(net "M_M_DQ<49>")
	)
	(segment
		(start 136.25957 -136.5758)
		(end 136.370568 -136.686798)
		(width 0.14224)
		(layer "In11.Cu")
		(net "M_M_DQ<49>")
	)
	(segment
		(start 112.433862 -94.822518)
		(end 112.427512 -94.833186)
		(width 0.0889)
		(layer "In11.Cu")
		(net "M_M_DQ<49>")
	)
	(segment
		(start 136.25957 -134.172198)
		(end 136.25957 -136.5758)
		(width 0.14224)
		(layer "In11.Cu")
		(net "M_M_DQ<49>")
	)
	(segment
		(start 135.348472 -153.542746)
		(end 135.099552 -153.542746)
		(width 0.14224)
		(layer "In11.Cu")
		(net "M_M_DQ<49>")
	)
	(segment
		(start 135.500618 -153.3906)
		(end 135.348472 -153.542746)
		(width 0.14224)
		(layer "In11.Cu")
		(net "M_M_DQ<49>")
	)
	(segment
		(start 128.048004 -121.378472)
		(end 128.401064 -121.378472)
		(width 0.14224)
		(layer "In11.Cu")
		(net "M_M_DQ<49>")
	)
	(segment
		(start 128.556004 -121.533412)
		(end 128.556004 -121.840752)
		(width 0.14224)
		(layer "In11.Cu")
		(net "M_M_DQ<49>")
	)
	(segment
		(start 135.500618 -153.0858)
		(end 135.500618 -153.3906)
		(width 0.14224)
		(layer "In11.Cu")
		(net "M_M_DQ<49>")
	)
	(segment
		(start 129.373884 -121.378472)
		(end 129.726944 -121.378472)
		(width 0.14224)
		(layer "In11.Cu")
		(net "M_M_DQ<49>")
	)
	(segment
		(start 128.556004 -121.840752)
		(end 128.710944 -121.995692)
		(width 0.14224)
		(layer "In11.Cu")
		(net "M_M_DQ<49>")
	)
	(segment
		(start 131.408678 -121.840752)
		(end 131.563618 -121.995692)
		(width 0.14224)
		(layer "In11.Cu")
		(net "M_M_DQ<49>")
	)
	(segment
		(start 133.210554 -121.37136)
		(end 136.25957 -124.420376)
		(width 0.14224)
		(layer "In11.Cu")
		(net "M_M_DQ<49>")
	)
	(segment
		(start 130.745738 -121.840752)
		(end 130.745738 -121.5263)
		(width 0.14224)
		(layer "In11.Cu")
		(net "M_M_DQ<49>")
	)
	(segment
		(start 116.197126 -99.395788)
		(end 116.229892 -99.395788)
		(width 0.0889)
		(layer "In11.Cu")
		(net "M_M_DQ<49>")
	)
	(segment
		(start 116.720112 -105.234486)
		(end 116.713254 -105.246678)
		(width 0.0889)
		(layer "In11.Cu")
		(net "M_M_DQ<49>")
	)
	(segment
		(start 136.370568 -138.7094)
		(end 136.25957 -138.820398)
		(width 0.14224)
		(layer "In11.Cu")
		(net "M_M_DQ<49>")
	)
	(segment
		(start 130.900678 -121.37136)
		(end 131.253738 -121.37136)
		(width 0.14224)
		(layer "In11.Cu")
		(net "M_M_DQ<49>")
	)
	(segment
		(start 116.729002 -101.256846)
		(end 116.713254 -101.284278)
		(width 0.0889)
		(layer "In11.Cu")
		(net "M_M_DQ<49>")
	)
	(segment
		(start 132.226558 -121.37136)
		(end 133.210554 -121.37136)
		(width 0.14224)
		(layer "In11.Cu")
		(net "M_M_DQ<49>")
	)
	(segment
		(start 136.370568 -131.851654)
		(end 136.370568 -134.0612)
		(width 0.14224)
		(layer "In11.Cu")
		(net "M_M_DQ<49>")
	)
	(arc
		(start 112.427512 -96.814386)
		(mid 112.424764 -97.209853)
		(end 112.763046 -97.414588)
		(width 0.0889)
		(layer "In11.Cu")
		(net "M_M_DQ<49>")
	)
	(arc
		(start 116.720112 -105.634282)
		(mid 116.799301 -105.920897)
		(end 116.729002 -106.209846)
		(width 0.0889)
		(layer "In11.Cu")
		(net "M_M_DQ<49>")
	)
	(arc
		(start 116.713254 -100.293678)
		(mid 116.666578 -100.488379)
		(end 116.720112 -100.681282)
		(width 0.0889)
		(layer "In11.Cu")
		(net "M_M_DQ<49>")
	)
	(arc
		(start 112.795812 -97.414588)
		(mid 113.079029 -97.498869)
		(end 113.286032 -97.709736)
		(width 0.0889)
		(layer "In11.Cu")
		(net "M_M_DQ<49>")
	)
	(arc
		(start 113.286032 -97.709736)
		(mid 113.426111 -97.852472)
		(end 113.617756 -97.909634)
		(width 0.0889)
		(layer "In11.Cu")
		(net "M_M_DQ<49>")
	)
	(arc
		(start 116.720112 -102.662482)
		(mid 116.799301 -102.949097)
		(end 116.729002 -103.238046)
		(width 0.0889)
		(layer "In11.Cu")
		(net "M_M_DQ<49>")
	)
	(arc
		(start 112.427512 -93.842586)
		(mid 112.374042 -94.037649)
		(end 112.422686 -94.234)
		(width 0.0889)
		(layer "In11.Cu")
		(net "M_M_DQ<49>")
	)
	(arc
		(start 112.433862 -96.234504)
		(mid 112.50666 -96.525267)
		(end 112.427512 -96.814386)
		(width 0.0889)
		(layer "In11.Cu")
		(net "M_M_DQ<49>")
	)
	(arc
		(start 116.713254 -105.246678)
		(mid 116.666578 -105.441379)
		(end 116.720112 -105.634282)
		(width 0.0889)
		(layer "In11.Cu")
		(net "M_M_DQ<49>")
	)
	(arc
		(start 112.427512 -92.851986)
		(mid 112.374042 -93.047049)
		(end 112.422686 -93.2434)
		(width 0.0889)
		(layer "In11.Cu")
		(net "M_M_DQ<49>")
	)
	(arc
		(start 116.720112 -103.653082)
		(mid 116.799301 -103.939697)
		(end 116.729002 -104.228646)
		(width 0.0889)
		(layer "In11.Cu")
		(net "M_M_DQ<49>")
	)
	(arc
		(start 112.427512 -95.232982)
		(mid 112.506643 -95.528384)
		(end 112.427512 -95.823786)
		(width 0.0889)
		(layer "In11.Cu")
		(net "M_M_DQ<49>")
	)
	(arc
		(start 113.650522 -97.909634)
		(mid 113.935946 -97.993101)
		(end 114.144552 -98.205036)
		(width 0.0889)
		(layer "In11.Cu")
		(net "M_M_DQ<49>")
	)
	(arc
		(start 115.367562 -98.900234)
		(mid 115.652986 -98.983701)
		(end 115.861592 -99.195636)
		(width 0.0889)
		(layer "In11.Cu")
		(net "M_M_DQ<49>")
	)
	(arc
		(start 116.713254 -101.284278)
		(mid 116.666578 -101.478979)
		(end 116.720112 -101.671882)
		(width 0.0889)
		(layer "In11.Cu")
		(net "M_M_DQ<49>")
	)
	(arc
		(start 115.861592 -99.195636)
		(mid 116.003275 -99.33944)
		(end 116.197126 -99.395788)
		(width 0.0889)
		(layer "In11.Cu")
		(net "M_M_DQ<49>")
	)
	(arc
		(start 112.427512 -94.833186)
		(mid 112.374013 -95.033084)
		(end 112.427512 -95.232982)
		(width 0.0889)
		(layer "In11.Cu")
		(net "M_M_DQ<49>")
	)
	(arc
		(start 116.720112 -106.225086)
		(mid 116.68855 -106.274138)
		(end 116.652294 -106.319828)
		(width 0.0889)
		(layer "In11.Cu")
		(net "M_M_DQ<49>")
	)
	(arc
		(start 112.433862 -93.262704)
		(mid 112.50666 -93.553467)
		(end 112.427512 -93.842586)
		(width 0.0889)
		(layer "In11.Cu")
		(net "M_M_DQ<49>")
	)
	(arc
		(start 116.713254 -104.256078)
		(mid 116.666578 -104.450779)
		(end 116.720112 -104.643682)
		(width 0.0889)
		(layer "In11.Cu")
		(net "M_M_DQ<49>")
	)
	(arc
		(start 112.427512 -94.242636)
		(mid 112.506734 -94.531754)
		(end 112.433862 -94.822518)
		(width 0.0889)
		(layer "In11.Cu")
		(net "M_M_DQ<49>")
	)
	(arc
		(start 116.720112 -104.643682)
		(mid 116.799301 -104.930297)
		(end 116.729002 -105.219246)
		(width 0.0889)
		(layer "In11.Cu")
		(net "M_M_DQ<49>")
	)
	(arc
		(start 114.512852 -98.405188)
		(mid 114.796069 -98.489469)
		(end 115.003072 -98.700336)
		(width 0.0889)
		(layer "In11.Cu")
		(net "M_M_DQ<49>")
	)
	(arc
		(start 116.720112 -101.671882)
		(mid 116.799301 -101.958497)
		(end 116.729002 -102.247446)
		(width 0.0889)
		(layer "In11.Cu")
		(net "M_M_DQ<49>")
	)
	(arc
		(start 114.144552 -98.205036)
		(mid 114.286235 -98.34884)
		(end 114.480086 -98.405188)
		(width 0.0889)
		(layer "In11.Cu")
		(net "M_M_DQ<49>")
	)
	(arc
		(start 116.720112 -100.681282)
		(mid 116.799301 -100.967897)
		(end 116.729002 -101.256846)
		(width 0.0889)
		(layer "In11.Cu")
		(net "M_M_DQ<49>")
	)
	(arc
		(start 116.713254 -102.274878)
		(mid 116.666578 -102.469579)
		(end 116.720112 -102.662482)
		(width 0.0889)
		(layer "In11.Cu")
		(net "M_M_DQ<49>")
	)
	(arc
		(start 115.003072 -98.700336)
		(mid 115.143151 -98.843072)
		(end 115.334796 -98.900234)
		(width 0.0889)
		(layer "In11.Cu")
		(net "M_M_DQ<49>")
	)
	(arc
		(start 112.427512 -95.823786)
		(mid 112.374042 -96.018849)
		(end 112.422686 -96.2152)
		(width 0.0889)
		(layer "In11.Cu")
		(net "M_M_DQ<49>")
	)
	(arc
		(start 116.229892 -99.395788)
		(mid 116.722282 -99.694721)
		(end 116.726462 -100.270818)
		(width 0.0889)
		(layer "In11.Cu")
		(net "M_M_DQ<49>")
	)
	(arc
		(start 116.713254 -103.265478)
		(mid 116.666578 -103.460179)
		(end 116.720112 -103.653082)
		(width 0.0889)
		(layer "In11.Cu")
		(net "M_M_DQ<49>")
	)
	(segment
		(start 112.202722 -90.080338)
		(end 112.774222 -90.080338)
		(width 0.1651)
		(layer "F.Cu")
		(net "M_M_DQ<48>")
	)
	(segment
		(start 135.949436 -156.878782)
		(end 135.771636 -155.0162)
		(width 0.1651)
		(layer "F.Cu")
		(net "M_M_DQ<48>")
	)
	(segment
		(start 135.949436 -156.87294)
		(end 135.949436 -156.878782)
		(width 0.1651)
		(layer "F.Cu")
		(net "M_M_DQ<48>")
	)
	(via
		(at 135.771636 -155.0162)
		(size 0.508)
		(drill 0.254)
		(layers "F.Cu" "B.Cu")
		(net "M_M_DQ<48>")
	)
	(via
		(at 112.774222 -90.080338)
		(size 0.508)
		(drill 0.254)
		(layers "F.Cu" "B.Cu")
		(net "M_M_DQ<48>")
	)
	(via
		(at 135.099552 -150.814278)
		(size 0.508)
		(drill 0.254)
		(layers "F.Cu" "B.Cu")
		(net "M_M_DQ<48>")
	)
	(segment
		(start 135.099552 -152.078436)
		(end 135.099552 -150.814278)
		(width 0.1651)
		(layer "B.Cu")
		(net "M_M_DQ<48>")
	)
	(segment
		(start 134.911592 -149.634956)
		(end 134.911592 -150.626318)
		(width 0.14224)
		(layer "In11.Cu")
		(net "M_M_DQ<48>")
	)
	(segment
		(start 116.56187 -100.17379)
		(end 116.546122 -100.201222)
		(width 0.0889)
		(layer "In11.Cu")
		(net "M_M_DQ<48>")
	)
	(segment
		(start 134.666482 -154.20721)
		(end 135.475472 -155.0162)
		(width 0.14224)
		(layer "In11.Cu")
		(net "M_M_DQ<48>")
	)
	(segment
		(start 135.311134 -124.174504)
		(end 135.311134 -126.135638)
		(width 0.14224)
		(layer "In11.Cu")
		(net "M_M_DQ<48>")
	)
	(segment
		(start 116.56187 -105.12679)
		(end 116.546122 -105.154222)
		(width 0.0889)
		(layer "In11.Cu")
		(net "M_M_DQ<48>")
	)
	(segment
		(start 112.756442 -97.605088)
		(end 112.789208 -97.605088)
		(width 0.0889)
		(layer "In11.Cu")
		(net "M_M_DQ<48>")
	)
	(segment
		(start 135.550402 -129.793746)
		(end 135.31596 -130.028188)
		(width 0.14224)
		(layer "In11.Cu")
		(net "M_M_DQ<48>")
	)
	(segment
		(start 135.31596 -130.028188)
		(end 135.31596 -131.176268)
		(width 0.14224)
		(layer "In11.Cu")
		(net "M_M_DQ<48>")
	)
	(segment
		(start 135.29437 -144.365218)
		(end 135.29437 -145.583402)
		(width 0.14224)
		(layer "In11.Cu")
		(net "M_M_DQ<48>")
	)
	(segment
		(start 135.28167 -139.663678)
		(end 135.28167 -140.743178)
		(width 0.14224)
		(layer "In11.Cu")
		(net "M_M_DQ<48>")
	)
	(segment
		(start 112.256062 -96.308418)
		(end 112.262412 -96.319086)
		(width 0.0889)
		(layer "In11.Cu")
		(net "M_M_DQ<48>")
	)
	(segment
		(start 112.262412 -96.319086)
		(end 112.267238 -96.327722)
		(width 0.0889)
		(layer "In11.Cu")
		(net "M_M_DQ<48>")
	)
	(segment
		(start 112.262412 -92.356686)
		(end 112.267238 -92.365322)
		(width 0.0889)
		(layer "In11.Cu")
		(net "M_M_DQ<48>")
	)
	(segment
		(start 112.256062 -93.336618)
		(end 112.262412 -93.347286)
		(width 0.0889)
		(layer "In11.Cu")
		(net "M_M_DQ<48>")
	)
	(segment
		(start 116.56187 -103.14559)
		(end 116.546122 -103.173022)
		(width 0.0889)
		(layer "In11.Cu")
		(net "M_M_DQ<48>")
	)
	(segment
		(start 114.473482 -98.595688)
		(end 114.506248 -98.595688)
		(width 0.0889)
		(layer "In11.Cu")
		(net "M_M_DQ<48>")
	)
	(segment
		(start 135.62457 -131.484878)
		(end 135.62457 -134.433818)
		(width 0.14224)
		(layer "In11.Cu")
		(net "M_M_DQ<48>")
	)
	(segment
		(start 135.535924 -136.19861)
		(end 135.535924 -139.409424)
		(width 0.14224)
		(layer "In11.Cu")
		(net "M_M_DQ<48>")
	)
	(segment
		(start 135.31596 -131.176268)
		(end 135.62457 -131.484878)
		(width 0.14224)
		(layer "In11.Cu")
		(net "M_M_DQ<48>")
	)
	(segment
		(start 135.550402 -126.374906)
		(end 135.550402 -129.793746)
		(width 0.14224)
		(layer "In11.Cu")
		(net "M_M_DQ<48>")
	)
	(segment
		(start 112.262412 -91.366086)
		(end 112.267238 -91.374722)
		(width 0.0889)
		(layer "In11.Cu")
		(net "M_M_DQ<48>")
	)
	(segment
		(start 135.62457 -134.433818)
		(end 135.316214 -134.742174)
		(width 0.14224)
		(layer "In11.Cu")
		(net "M_M_DQ<48>")
	)
	(segment
		(start 133.870446 -122.733816)
		(end 135.311134 -124.174504)
		(width 0.14224)
		(layer "In11.Cu")
		(net "M_M_DQ<48>")
	)
	(segment
		(start 112.279176 -90.746072)
		(end 112.262412 -90.775536)
		(width 0.0889)
		(layer "In11.Cu")
		(net "M_M_DQ<48>")
	)
	(segment
		(start 112.256062 -92.346018)
		(end 112.262412 -92.356686)
		(width 0.0889)
		(layer "In11.Cu")
		(net "M_M_DQ<48>")
	)
	(segment
		(start 134.666482 -151.247348)
		(end 134.666482 -154.20721)
		(width 0.14224)
		(layer "In11.Cu")
		(net "M_M_DQ<48>")
	)
	(segment
		(start 135.543036 -149.003512)
		(end 134.911592 -149.634956)
		(width 0.14224)
		(layer "In11.Cu")
		(net "M_M_DQ<48>")
	)
	(segment
		(start 135.54329 -141.004798)
		(end 135.54329 -144.116298)
		(width 0.14224)
		(layer "In11.Cu")
		(net "M_M_DQ<48>")
	)
	(segment
		(start 134.911592 -150.626318)
		(end 135.099552 -150.814278)
		(width 0.14224)
		(layer "In11.Cu")
		(net "M_M_DQ<48>")
	)
	(segment
		(start 115.944142 -106.78287)
		(end 115.944142 -113.9952)
		(width 0.14224)
		(layer "In11.Cu")
		(net "M_M_DQ<48>")
	)
	(segment
		(start 115.944142 -113.9952)
		(end 124.682758 -122.733816)
		(width 0.14224)
		(layer "In11.Cu")
		(net "M_M_DQ<48>")
	)
	(segment
		(start 135.316214 -134.742174)
		(end 135.316214 -135.9789)
		(width 0.14224)
		(layer "In11.Cu")
		(net "M_M_DQ<48>")
	)
	(segment
		(start 116.56187 -102.15499)
		(end 116.546122 -102.182422)
		(width 0.0889)
		(layer "In11.Cu")
		(net "M_M_DQ<48>")
	)
	(segment
		(start 116.429536 -106.26344)
		(end 116.179092 -106.54792)
		(width 0.0889)
		(layer "In11.Cu")
		(net "M_M_DQ<48>")
	)
	(segment
		(start 135.099552 -150.814278)
		(end 134.666482 -151.247348)
		(width 0.14224)
		(layer "In11.Cu")
		(net "M_M_DQ<48>")
	)
	(segment
		(start 135.28167 -140.743178)
		(end 135.54329 -141.004798)
		(width 0.14224)
		(layer "In11.Cu")
		(net "M_M_DQ<48>")
	)
	(segment
		(start 115.328192 -99.090734)
		(end 115.360958 -99.090734)
		(width 0.0889)
		(layer "In11.Cu")
		(net "M_M_DQ<48>")
	)
	(segment
		(start 116.56187 -101.16439)
		(end 116.546122 -101.191822)
		(width 0.0889)
		(layer "In11.Cu")
		(net "M_M_DQ<48>")
	)
	(segment
		(start 112.262412 -94.737936)
		(end 112.256062 -94.748604)
		(width 0.0889)
		(layer "In11.Cu")
		(net "M_M_DQ<48>")
	)
	(segment
		(start 135.316214 -135.9789)
		(end 135.535924 -136.19861)
		(width 0.14224)
		(layer "In11.Cu")
		(net "M_M_DQ<48>")
	)
	(segment
		(start 112.774222 -90.080338)
		(end 112.279176 -90.746072)
		(width 0.0889)
		(layer "In11.Cu")
		(net "M_M_DQ<48>")
	)
	(segment
		(start 112.262412 -95.328486)
		(end 112.267238 -95.337122)
		(width 0.0889)
		(layer "In11.Cu")
		(net "M_M_DQ<48>")
	)
	(segment
		(start 135.29437 -145.583402)
		(end 135.543036 -145.832068)
		(width 0.14224)
		(layer "In11.Cu")
		(net "M_M_DQ<48>")
	)
	(segment
		(start 135.535924 -139.409424)
		(end 135.28167 -139.663678)
		(width 0.14224)
		(layer "In11.Cu")
		(net "M_M_DQ<48>")
	)
	(segment
		(start 112.262412 -93.347286)
		(end 112.267238 -93.355922)
		(width 0.0889)
		(layer "In11.Cu")
		(net "M_M_DQ<48>")
	)
	(segment
		(start 116.56187 -104.13619)
		(end 116.546122 -104.163622)
		(width 0.0889)
		(layer "In11.Cu")
		(net "M_M_DQ<48>")
	)
	(segment
		(start 135.54329 -144.116298)
		(end 135.29437 -144.365218)
		(width 0.14224)
		(layer "In11.Cu")
		(net "M_M_DQ<48>")
	)
	(segment
		(start 113.611152 -98.100134)
		(end 113.643918 -98.100134)
		(width 0.0889)
		(layer "In11.Cu")
		(net "M_M_DQ<48>")
	)
	(segment
		(start 135.475472 -155.0162)
		(end 135.771636 -155.0162)
		(width 0.14224)
		(layer "In11.Cu")
		(net "M_M_DQ<48>")
	)
	(segment
		(start 124.682758 -122.733816)
		(end 133.870446 -122.733816)
		(width 0.14224)
		(layer "In11.Cu")
		(net "M_M_DQ<48>")
	)
	(segment
		(start 116.179092 -106.54792)
		(end 115.944142 -106.78287)
		(width 0.0889)
		(layer "In11.Cu")
		(net "M_M_DQ<48>")
	)
	(segment
		(start 112.256062 -91.355418)
		(end 112.262412 -91.366086)
		(width 0.0889)
		(layer "In11.Cu")
		(net "M_M_DQ<48>")
	)
	(segment
		(start 135.543036 -145.832068)
		(end 135.543036 -149.003512)
		(width 0.14224)
		(layer "In11.Cu")
		(net "M_M_DQ<48>")
	)
	(segment
		(start 135.311134 -126.135638)
		(end 135.550402 -126.374906)
		(width 0.14224)
		(layer "In11.Cu")
		(net "M_M_DQ<48>")
	)
	(segment
		(start 116.190522 -99.586288)
		(end 116.223288 -99.586288)
		(width 0.0889)
		(layer "In11.Cu")
		(net "M_M_DQ<48>")
	)
	(arc
		(start 112.262412 -91.766136)
		(mid 112.18319 -92.055254)
		(end 112.256062 -92.346018)
		(width 0.0889)
		(layer "In11.Cu")
		(net "M_M_DQ<48>")
	)
	(arc
		(start 116.555012 -102.757986)
		(mid 116.60845 -102.950891)
		(end 116.56187 -103.14559)
		(width 0.0889)
		(layer "In11.Cu")
		(net "M_M_DQ<48>")
	)
	(arc
		(start 114.506248 -98.595688)
		(mid 114.69789 -98.652854)
		(end 114.837972 -98.795586)
		(width 0.0889)
		(layer "In11.Cu")
		(net "M_M_DQ<48>")
	)
	(arc
		(start 116.546122 -101.191822)
		(mid 116.475725 -101.480773)
		(end 116.555012 -101.767386)
		(width 0.0889)
		(layer "In11.Cu")
		(net "M_M_DQ<48>")
	)
	(arc
		(start 116.555012 -103.748586)
		(mid 116.60845 -103.941491)
		(end 116.56187 -104.13619)
		(width 0.0889)
		(layer "In11.Cu")
		(net "M_M_DQ<48>")
	)
	(arc
		(start 112.267238 -92.365322)
		(mid 112.315993 -92.561674)
		(end 112.262412 -92.756736)
		(width 0.0889)
		(layer "In11.Cu")
		(net "M_M_DQ<48>")
	)
	(arc
		(start 114.837972 -98.795586)
		(mid 115.044976 -99.00645)
		(end 115.328192 -99.090734)
		(width 0.0889)
		(layer "In11.Cu")
		(net "M_M_DQ<48>")
	)
	(arc
		(start 116.555012 -105.729786)
		(mid 116.598026 -106.021503)
		(end 116.429536 -106.26344)
		(width 0.0889)
		(layer "In11.Cu")
		(net "M_M_DQ<48>")
	)
	(arc
		(start 116.546122 -104.163622)
		(mid 116.475725 -104.452573)
		(end 116.555012 -104.739186)
		(width 0.0889)
		(layer "In11.Cu")
		(net "M_M_DQ<48>")
	)
	(arc
		(start 112.267238 -93.355922)
		(mid 112.315993 -93.552274)
		(end 112.262412 -93.747336)
		(width 0.0889)
		(layer "In11.Cu")
		(net "M_M_DQ<48>")
	)
	(arc
		(start 112.262412 -92.756736)
		(mid 112.18319 -93.045854)
		(end 112.256062 -93.336618)
		(width 0.0889)
		(layer "In11.Cu")
		(net "M_M_DQ<48>")
	)
	(arc
		(start 112.262412 -96.719136)
		(mid 112.258083 -97.302308)
		(end 112.756442 -97.605088)
		(width 0.0889)
		(layer "In11.Cu")
		(net "M_M_DQ<48>")
	)
	(arc
		(start 113.120932 -97.804986)
		(mid 113.327936 -98.01585)
		(end 113.611152 -98.100134)
		(width 0.0889)
		(layer "In11.Cu")
		(net "M_M_DQ<48>")
	)
	(arc
		(start 116.546122 -103.173022)
		(mid 116.475725 -103.461973)
		(end 116.555012 -103.748586)
		(width 0.0889)
		(layer "In11.Cu")
		(net "M_M_DQ<48>")
	)
	(arc
		(start 113.643918 -98.100134)
		(mid 113.837768 -98.156484)
		(end 113.979452 -98.300286)
		(width 0.0889)
		(layer "In11.Cu")
		(net "M_M_DQ<48>")
	)
	(arc
		(start 116.546122 -105.154222)
		(mid 116.475725 -105.443173)
		(end 116.555012 -105.729786)
		(width 0.0889)
		(layer "In11.Cu")
		(net "M_M_DQ<48>")
	)
	(arc
		(start 112.267238 -95.337122)
		(mid 112.315993 -95.533474)
		(end 112.262412 -95.728536)
		(width 0.0889)
		(layer "In11.Cu")
		(net "M_M_DQ<48>")
	)
	(arc
		(start 113.979452 -98.300286)
		(mid 114.18806 -98.512218)
		(end 114.473482 -98.595688)
		(width 0.0889)
		(layer "In11.Cu")
		(net "M_M_DQ<48>")
	)
	(arc
		(start 116.546122 -102.182422)
		(mid 116.475725 -102.471373)
		(end 116.555012 -102.757986)
		(width 0.0889)
		(layer "In11.Cu")
		(net "M_M_DQ<48>")
	)
	(arc
		(start 112.262412 -90.775536)
		(mid 112.18319 -91.064654)
		(end 112.256062 -91.355418)
		(width 0.0889)
		(layer "In11.Cu")
		(net "M_M_DQ<48>")
	)
	(arc
		(start 115.360958 -99.090734)
		(mid 115.554808 -99.147084)
		(end 115.696492 -99.290886)
		(width 0.0889)
		(layer "In11.Cu")
		(net "M_M_DQ<48>")
	)
	(arc
		(start 116.555012 -104.739186)
		(mid 116.60845 -104.932091)
		(end 116.56187 -105.12679)
		(width 0.0889)
		(layer "In11.Cu")
		(net "M_M_DQ<48>")
	)
	(arc
		(start 116.546122 -100.201222)
		(mid 116.475725 -100.490173)
		(end 116.555012 -100.776786)
		(width 0.0889)
		(layer "In11.Cu")
		(net "M_M_DQ<48>")
	)
	(arc
		(start 115.696492 -99.290886)
		(mid 115.9051 -99.502818)
		(end 116.190522 -99.586288)
		(width 0.0889)
		(layer "In11.Cu")
		(net "M_M_DQ<48>")
	)
	(arc
		(start 112.267238 -91.374722)
		(mid 112.315993 -91.571074)
		(end 112.262412 -91.766136)
		(width 0.0889)
		(layer "In11.Cu")
		(net "M_M_DQ<48>")
	)
	(arc
		(start 116.223288 -99.586288)
		(mid 116.555132 -99.786405)
		(end 116.56187 -100.17379)
		(width 0.0889)
		(layer "In11.Cu")
		(net "M_M_DQ<48>")
	)
	(arc
		(start 116.555012 -101.767386)
		(mid 116.60845 -101.960291)
		(end 116.56187 -102.15499)
		(width 0.0889)
		(layer "In11.Cu")
		(net "M_M_DQ<48>")
	)
	(arc
		(start 112.267238 -96.327722)
		(mid 112.315993 -96.524074)
		(end 112.262412 -96.719136)
		(width 0.0889)
		(layer "In11.Cu")
		(net "M_M_DQ<48>")
	)
	(arc
		(start 112.262412 -95.728536)
		(mid 112.18319 -96.017654)
		(end 112.256062 -96.308418)
		(width 0.0889)
		(layer "In11.Cu")
		(net "M_M_DQ<48>")
	)
	(arc
		(start 112.256062 -94.748604)
		(mid 112.183264 -95.039367)
		(end 112.262412 -95.328486)
		(width 0.0889)
		(layer "In11.Cu")
		(net "M_M_DQ<48>")
	)
	(arc
		(start 112.789208 -97.605088)
		(mid 112.98085 -97.662254)
		(end 113.120932 -97.804986)
		(width 0.0889)
		(layer "In11.Cu")
		(net "M_M_DQ<48>")
	)
	(arc
		(start 116.555012 -100.776786)
		(mid 116.60845 -100.969691)
		(end 116.56187 -101.16439)
		(width 0.0889)
		(layer "In11.Cu")
		(net "M_M_DQ<48>")
	)
	(arc
		(start 112.262412 -93.747336)
		(mid 112.183281 -94.042738)
		(end 112.262412 -94.33814)
		(width 0.0889)
		(layer "In11.Cu")
		(net "M_M_DQ<48>")
	)
	(arc
		(start 112.262412 -94.33814)
		(mid 112.315911 -94.538038)
		(end 112.262412 -94.737936)
		(width 0.0889)
		(layer "In11.Cu")
		(net "M_M_DQ<48>")
	)
	(segment
		(start 116.495322 -95.528384)
		(end 117.066822 -95.528384)
		(width 0.1651)
		(layer "F.Cu")
		(net "M_M_DQ<47>")
	)
	(segment
		(start 129.999486 -152.273)
		(end 129.999486 -153.542746)
		(width 0.1651)
		(layer "F.Cu")
		(net "M_M_DQ<47>")
	)
	(via
		(at 129.999486 -153.542746)
		(size 0.508)
		(drill 0.254)
		(layers "F.Cu" "B.Cu")
		(net "M_M_DQ<47>")
	)
	(via
		(at 130.84937 -149.533356)
		(size 0.508)
		(drill 0.254)
		(layers "F.Cu" "B.Cu")
		(net "M_M_DQ<47>")
	)
	(via
		(at 117.066822 -95.528384)
		(size 0.508)
		(drill 0.254)
		(layers "F.Cu" "B.Cu")
		(net "M_M_DQ<47>")
	)
	(segment
		(start 130.84937 -147.478496)
		(end 130.84937 -149.533356)
		(width 0.1651)
		(layer "B.Cu")
		(net "M_M_DQ<47>")
	)
	(segment
		(start 118.934992 -106.96956)
		(end 118.934992 -106.798618)
		(width 0.0889)
		(layer "In4.Cu")
		(net "M_M_DQ<47>")
	)
	(segment
		(start 126.785878 -119.826278)
		(end 126.56693 -119.826278)
		(width 0.14224)
		(layer "In4.Cu")
		(net "M_M_DQ<47>")
	)
	(segment
		(start 126.534926 -118.95963)
		(end 126.245874 -118.670578)
		(width 0.14224)
		(layer "In4.Cu")
		(net "M_M_DQ<47>")
	)
	(segment
		(start 131.151376 -141.516354)
		(end 131.151376 -141.086078)
		(width 0.14224)
		(layer "In4.Cu")
		(net "M_M_DQ<47>")
	)
	(segment
		(start 118.437152 -105.234486)
		(end 118.443502 -105.223818)
		(width 0.0889)
		(layer "In4.Cu")
		(net "M_M_DQ<47>")
	)
	(segment
		(start 117.587522 -103.173022)
		(end 117.571774 -103.14559)
		(width 0.0889)
		(layer "In4.Cu")
		(net "M_M_DQ<47>")
	)
	(segment
		(start 130.985768 -127.889)
		(end 130.985768 -125.7808)
		(width 0.14224)
		(layer "In4.Cu")
		(net "M_M_DQ<47>")
	)
	(segment
		(start 131.290568 -143.5862)
		(end 131.290568 -141.655546)
		(width 0.14224)
		(layer "In4.Cu")
		(net "M_M_DQ<47>")
	)
	(segment
		(start 131.290568 -138.6586)
		(end 131.290568 -136.6774)
		(width 0.14224)
		(layer "In4.Cu")
		(net "M_M_DQ<47>")
	)
	(segment
		(start 117.578632 -96.223836)
		(end 117.561868 -96.194372)
		(width 0.0889)
		(layer "In4.Cu")
		(net "M_M_DQ<47>")
	)
	(segment
		(start 131.202176 -136.232392)
		(end 131.405376 -136.029192)
		(width 0.14224)
		(layer "In4.Cu")
		(net "M_M_DQ<47>")
	)
	(segment
		(start 130.444494 -123.522232)
		(end 130.444494 -122.15495)
		(width 0.14224)
		(layer "In4.Cu")
		(net "M_M_DQ<47>")
	)
	(segment
		(start 131.191254 -149.191472)
		(end 131.202176 -149.191472)
		(width 0.14224)
		(layer "In4.Cu")
		(net "M_M_DQ<47>")
	)
	(segment
		(start 127.541528 -120.800876)
		(end 127.254762 -120.51411)
		(width 0.14224)
		(layer "In4.Cu")
		(net "M_M_DQ<47>")
	)
	(segment
		(start 131.227576 -134.5311)
		(end 131.227576 -134.098792)
		(width 0.14224)
		(layer "In4.Cu")
		(net "M_M_DQ<47>")
	)
	(segment
		(start 117.584982 -102.177596)
		(end 117.578632 -102.166928)
		(width 0.0889)
		(layer "In4.Cu")
		(net "M_M_DQ<47>")
	)
	(segment
		(start 119.184928 -112.444276)
		(end 119.184928 -107.219496)
		(width 0.14224)
		(layer "In4.Cu")
		(net "M_M_DQ<47>")
	)
	(segment
		(start 117.946932 -104.348788)
		(end 117.920516 -104.348788)
		(width 0.0889)
		(layer "In4.Cu")
		(net "M_M_DQ<47>")
	)
	(segment
		(start 131.202176 -139.460478)
		(end 131.202176 -138.746992)
		(width 0.14224)
		(layer "In4.Cu")
		(net "M_M_DQ<47>")
	)
	(segment
		(start 119.184928 -107.219496)
		(end 118.934992 -106.96956)
		(width 0.0889)
		(layer "In4.Cu")
		(net "M_M_DQ<47>")
	)
	(segment
		(start 126.245874 -118.670578)
		(end 126.066042 -118.670578)
		(width 0.14224)
		(layer "In4.Cu")
		(net "M_M_DQ<47>")
	)
	(segment
		(start 129.09042 -120.800876)
		(end 127.541528 -120.800876)
		(width 0.14224)
		(layer "In4.Cu")
		(net "M_M_DQ<47>")
	)
	(segment
		(start 131.151376 -141.086078)
		(end 131.430776 -140.806678)
		(width 0.14224)
		(layer "In4.Cu")
		(net "M_M_DQ<47>")
	)
	(segment
		(start 131.202176 -128.105408)
		(end 130.985768 -127.889)
		(width 0.14224)
		(layer "In4.Cu")
		(net "M_M_DQ<47>")
	)
	(segment
		(start 131.202176 -145.833338)
		(end 131.37134 -145.664174)
		(width 0.14224)
		(layer "In4.Cu")
		(net "M_M_DQ<47>")
	)
	(segment
		(start 117.584982 -97.225104)
		(end 117.578632 -97.214436)
		(width 0.0889)
		(layer "In4.Cu")
		(net "M_M_DQ<47>")
	)
	(segment
		(start 118.432326 -105.243122)
		(end 118.437152 -105.234486)
		(width 0.0889)
		(layer "In4.Cu")
		(net "M_M_DQ<47>")
	)
	(segment
		(start 117.578632 -97.214436)
		(end 117.573806 -97.2058)
		(width 0.0889)
		(layer "In4.Cu")
		(net "M_M_DQ<47>")
	)
	(segment
		(start 131.202176 -125.564392)
		(end 131.202176 -124.279914)
		(width 0.14224)
		(layer "In4.Cu")
		(net "M_M_DQ<47>")
	)
	(segment
		(start 131.430776 -130.087878)
		(end 131.202176 -129.859278)
		(width 0.14224)
		(layer "In4.Cu")
		(net "M_M_DQ<47>")
	)
	(segment
		(start 125.629162 -118.88851)
		(end 119.184928 -112.444276)
		(width 0.14224)
		(layer "In4.Cu")
		(net "M_M_DQ<47>")
	)
	(segment
		(start 131.227576 -144.169638)
		(end 131.227576 -143.649192)
		(width 0.14224)
		(layer "In4.Cu")
		(net "M_M_DQ<47>")
	)
	(segment
		(start 131.430776 -139.689078)
		(end 131.202176 -139.460478)
		(width 0.14224)
		(layer "In4.Cu")
		(net "M_M_DQ<47>")
	)
	(segment
		(start 131.227576 -134.098792)
		(end 131.265168 -134.0612)
		(width 0.14224)
		(layer "In4.Cu")
		(net "M_M_DQ<47>")
	)
	(segment
		(start 126.56693 -119.826278)
		(end 126.316994 -119.576342)
		(width 0.14224)
		(layer "In4.Cu")
		(net "M_M_DQ<47>")
	)
	(segment
		(start 131.227576 -131.8768)
		(end 131.227576 -131.408678)
		(width 0.14224)
		(layer "In4.Cu")
		(net "M_M_DQ<47>")
	)
	(segment
		(start 117.584982 -96.234504)
		(end 117.578632 -96.223836)
		(width 0.0889)
		(layer "In4.Cu")
		(net "M_M_DQ<47>")
	)
	(segment
		(start 127.307086 -119.30507)
		(end 126.785878 -119.826278)
		(width 0.14224)
		(layer "In4.Cu")
		(net "M_M_DQ<47>")
	)
	(segment
		(start 117.584982 -99.206304)
		(end 117.578632 -99.195636)
		(width 0.0889)
		(layer "In4.Cu")
		(net "M_M_DQ<47>")
	)
	(segment
		(start 131.227576 -143.649192)
		(end 131.290568 -143.5862)
		(width 0.14224)
		(layer "In4.Cu")
		(net "M_M_DQ<47>")
	)
	(segment
		(start 126.066042 -118.670578)
		(end 125.84811 -118.88851)
		(width 0.14224)
		(layer "In4.Cu")
		(net "M_M_DQ<47>")
	)
	(segment
		(start 118.5164 -106.380026)
		(end 118.5164 -105.929938)
		(width 0.0889)
		(layer "In4.Cu")
		(net "M_M_DQ<47>")
	)
	(segment
		(start 117.45341 -96.048576)
		(end 117.066822 -95.528384)
		(width 0.0889)
		(layer "In4.Cu")
		(net "M_M_DQ<47>")
	)
	(segment
		(start 127.254762 -120.51411)
		(end 127.254762 -120.295162)
		(width 0.14224)
		(layer "In4.Cu")
		(net "M_M_DQ<47>")
	)
	(segment
		(start 117.573806 -100.784914)
		(end 117.578632 -100.776278)
		(width 0.0889)
		(layer "In4.Cu")
		(net "M_M_DQ<47>")
	)
	(segment
		(start 117.578632 -99.195636)
		(end 117.573806 -99.187)
		(width 0.0889)
		(layer "In4.Cu")
		(net "M_M_DQ<47>")
	)
	(segment
		(start 117.584982 -98.215704)
		(end 117.578632 -98.205036)
		(width 0.0889)
		(layer "In4.Cu")
		(net "M_M_DQ<47>")
	)
	(segment
		(start 127.254762 -120.295162)
		(end 127.77597 -119.773954)
		(width 0.14224)
		(layer "In4.Cu")
		(net "M_M_DQ<47>")
	)
	(segment
		(start 131.202176 -124.279914)
		(end 130.444494 -123.522232)
		(width 0.14224)
		(layer "In4.Cu")
		(net "M_M_DQ<47>")
	)
	(segment
		(start 126.534926 -119.139462)
		(end 126.534926 -118.95963)
		(width 0.14224)
		(layer "In4.Cu")
		(net "M_M_DQ<47>")
	)
	(segment
		(start 131.290568 -136.6774)
		(end 131.202176 -136.589008)
		(width 0.14224)
		(layer "In4.Cu")
		(net "M_M_DQ<47>")
	)
	(segment
		(start 131.202176 -136.589008)
		(end 131.202176 -136.232392)
		(width 0.14224)
		(layer "In4.Cu")
		(net "M_M_DQ<47>")
	)
	(segment
		(start 131.265168 -131.914392)
		(end 131.227576 -131.8768)
		(width 0.14224)
		(layer "In4.Cu")
		(net "M_M_DQ<47>")
	)
	(segment
		(start 126.316994 -119.357394)
		(end 126.534926 -119.139462)
		(width 0.14224)
		(layer "In4.Cu")
		(net "M_M_DQ<47>")
	)
	(segment
		(start 130.84937 -149.533356)
		(end 131.191254 -149.191472)
		(width 0.14224)
		(layer "In4.Cu")
		(net "M_M_DQ<47>")
	)
	(segment
		(start 130.985768 -125.7808)
		(end 131.202176 -125.564392)
		(width 0.14224)
		(layer "In4.Cu")
		(net "M_M_DQ<47>")
	)
	(segment
		(start 131.37134 -144.313402)
		(end 131.227576 -144.169638)
		(width 0.14224)
		(layer "In4.Cu")
		(net "M_M_DQ<47>")
	)
	(segment
		(start 131.290568 -141.655546)
		(end 131.151376 -141.516354)
		(width 0.14224)
		(layer "In4.Cu")
		(net "M_M_DQ<47>")
	)
	(segment
		(start 131.265168 -134.0612)
		(end 131.265168 -131.914392)
		(width 0.14224)
		(layer "In4.Cu")
		(net "M_M_DQ<47>")
	)
	(segment
		(start 117.578632 -98.205036)
		(end 117.573806 -98.1964)
		(width 0.0889)
		(layer "In4.Cu")
		(net "M_M_DQ<47>")
	)
	(segment
		(start 130.444494 -122.15495)
		(end 129.09042 -120.800876)
		(width 0.14224)
		(layer "In4.Cu")
		(net "M_M_DQ<47>")
	)
	(segment
		(start 127.77597 -119.594122)
		(end 127.486918 -119.30507)
		(width 0.14224)
		(layer "In4.Cu")
		(net "M_M_DQ<47>")
	)
	(segment
		(start 118.934992 -106.798618)
		(end 118.5164 -106.380026)
		(width 0.0889)
		(layer "In4.Cu")
		(net "M_M_DQ<47>")
	)
	(segment
		(start 131.430776 -131.205478)
		(end 131.430776 -130.087878)
		(width 0.14224)
		(layer "In4.Cu")
		(net "M_M_DQ<47>")
	)
	(segment
		(start 131.430776 -140.806678)
		(end 131.430776 -139.689078)
		(width 0.14224)
		(layer "In4.Cu")
		(net "M_M_DQ<47>")
	)
	(segment
		(start 131.202176 -138.746992)
		(end 131.290568 -138.6586)
		(width 0.14224)
		(layer "In4.Cu")
		(net "M_M_DQ<47>")
	)
	(segment
		(start 131.202176 -129.859278)
		(end 131.202176 -128.105408)
		(width 0.14224)
		(layer "In4.Cu")
		(net "M_M_DQ<47>")
	)
	(segment
		(start 131.227576 -131.408678)
		(end 131.430776 -131.205478)
		(width 0.14224)
		(layer "In4.Cu")
		(net "M_M_DQ<47>")
	)
	(segment
		(start 125.84811 -118.88851)
		(end 125.629162 -118.88851)
		(width 0.14224)
		(layer "In4.Cu")
		(net "M_M_DQ<47>")
	)
	(segment
		(start 131.405376 -136.029192)
		(end 131.405376 -134.7089)
		(width 0.14224)
		(layer "In4.Cu")
		(net "M_M_DQ<47>")
	)
	(segment
		(start 131.405376 -134.7089)
		(end 131.227576 -134.5311)
		(width 0.14224)
		(layer "In4.Cu")
		(net "M_M_DQ<47>")
	)
	(segment
		(start 126.316994 -119.576342)
		(end 126.316994 -119.357394)
		(width 0.14224)
		(layer "In4.Cu")
		(net "M_M_DQ<47>")
	)
	(segment
		(start 127.486918 -119.30507)
		(end 127.307086 -119.30507)
		(width 0.14224)
		(layer "In4.Cu")
		(net "M_M_DQ<47>")
	)
	(segment
		(start 117.578632 -100.776278)
		(end 117.584982 -100.76561)
		(width 0.0889)
		(layer "In4.Cu")
		(net "M_M_DQ<47>")
	)
	(segment
		(start 131.202176 -149.191472)
		(end 131.202176 -145.833338)
		(width 0.14224)
		(layer "In4.Cu")
		(net "M_M_DQ<47>")
	)
	(segment
		(start 131.37134 -145.664174)
		(end 131.37134 -144.313402)
		(width 0.14224)
		(layer "In4.Cu")
		(net "M_M_DQ<47>")
	)
	(segment
		(start 117.561868 -96.194372)
		(end 117.45341 -96.048576)
		(width 0.0889)
		(layer "In4.Cu")
		(net "M_M_DQ<47>")
	)
	(segment
		(start 127.77597 -119.773954)
		(end 127.77597 -119.594122)
		(width 0.14224)
		(layer "In4.Cu")
		(net "M_M_DQ<47>")
	)
	(arc
		(start 117.578632 -102.166928)
		(mid 117.525133 -101.96703)
		(end 117.578632 -101.767132)
		(width 0.0889)
		(layer "In4.Cu")
		(net "M_M_DQ<47>")
	)
	(arc
		(start 118.443502 -105.223818)
		(mid 118.439471 -104.647636)
		(end 117.946932 -104.348788)
		(width 0.0889)
		(layer "In4.Cu")
		(net "M_M_DQ<47>")
	)
	(arc
		(start 117.578632 -96.814386)
		(mid 117.657854 -96.525268)
		(end 117.584982 -96.234504)
		(width 0.0889)
		(layer "In4.Cu")
		(net "M_M_DQ<47>")
	)
	(arc
		(start 117.573806 -99.187)
		(mid 117.525051 -98.990648)
		(end 117.578632 -98.795586)
		(width 0.0889)
		(layer "In4.Cu")
		(net "M_M_DQ<47>")
	)
	(arc
		(start 117.573806 -100.1776)
		(mid 117.525051 -99.981248)
		(end 117.578632 -99.786186)
		(width 0.0889)
		(layer "In4.Cu")
		(net "M_M_DQ<47>")
	)
	(arc
		(start 117.578632 -98.795586)
		(mid 117.657854 -98.506468)
		(end 117.584982 -98.215704)
		(width 0.0889)
		(layer "In4.Cu")
		(net "M_M_DQ<47>")
	)
	(arc
		(start 117.578632 -100.185728)
		(mid 117.576142 -100.181709)
		(end 117.573806 -100.1776)
		(width 0.0889)
		(layer "In4.Cu")
		(net "M_M_DQ<47>")
	)
	(arc
		(start 117.578632 -103.748586)
		(mid 117.657821 -103.461971)
		(end 117.587522 -103.173022)
		(width 0.0889)
		(layer "In4.Cu")
		(net "M_M_DQ<47>")
	)
	(arc
		(start 117.578632 -99.786186)
		(mid 117.657854 -99.497068)
		(end 117.584982 -99.206304)
		(width 0.0889)
		(layer "In4.Cu")
		(net "M_M_DQ<47>")
	)
	(arc
		(start 117.920516 -104.348788)
		(mid 117.577502 -104.146661)
		(end 117.578632 -103.748586)
		(width 0.0889)
		(layer "In4.Cu")
		(net "M_M_DQ<47>")
	)
	(arc
		(start 117.571774 -103.14559)
		(mid 117.525098 -102.950889)
		(end 117.578632 -102.757986)
		(width 0.0889)
		(layer "In4.Cu")
		(net "M_M_DQ<47>")
	)
	(arc
		(start 118.5164 -105.929938)
		(mid 118.496209 -105.777024)
		(end 118.437152 -105.634536)
		(width 0.0889)
		(layer "In4.Cu")
		(net "M_M_DQ<47>")
	)
	(arc
		(start 117.578632 -102.757986)
		(mid 117.657981 -102.468614)
		(end 117.584982 -102.177596)
		(width 0.0889)
		(layer "In4.Cu")
		(net "M_M_DQ<47>")
	)
	(arc
		(start 117.578632 -101.767132)
		(mid 117.657763 -101.47173)
		(end 117.578632 -101.176328)
		(width 0.0889)
		(layer "In4.Cu")
		(net "M_M_DQ<47>")
	)
	(arc
		(start 117.573806 -98.1964)
		(mid 117.525051 -98.000048)
		(end 117.578632 -97.804986)
		(width 0.0889)
		(layer "In4.Cu")
		(net "M_M_DQ<47>")
	)
	(arc
		(start 117.578632 -97.804986)
		(mid 117.657854 -97.515868)
		(end 117.584982 -97.225104)
		(width 0.0889)
		(layer "In4.Cu")
		(net "M_M_DQ<47>")
	)
	(arc
		(start 117.584982 -100.76561)
		(mid 117.65778 -100.474847)
		(end 117.578632 -100.185728)
		(width 0.0889)
		(layer "In4.Cu")
		(net "M_M_DQ<47>")
	)
	(arc
		(start 118.437152 -105.634536)
		(mid 118.383682 -105.439473)
		(end 118.432326 -105.243122)
		(width 0.0889)
		(layer "In4.Cu")
		(net "M_M_DQ<47>")
	)
	(arc
		(start 117.578632 -101.176328)
		(mid 117.525162 -100.981265)
		(end 117.573806 -100.784914)
		(width 0.0889)
		(layer "In4.Cu")
		(net "M_M_DQ<47>")
	)
	(arc
		(start 117.573806 -97.2058)
		(mid 117.525051 -97.009448)
		(end 117.578632 -96.814386)
		(width 0.0889)
		(layer "In4.Cu")
		(net "M_M_DQ<47>")
	)
	(segment
		(start 130.449574 -153.04135)
		(end 130.160776 -152.752552)
		(width 0.14224)
		(layer "In11.Cu")
		(net "M_M_DQ<47>")
	)
	(segment
		(start 130.398774 -150.391368)
		(end 130.398774 -149.9616)
		(width 0.14224)
		(layer "In11.Cu")
		(net "M_M_DQ<47>")
	)
	(segment
		(start 130.160776 -151.387048)
		(end 130.443224 -151.1046)
		(width 0.14224)
		(layer "In11.Cu")
		(net "M_M_DQ<47>")
	)
	(segment
		(start 130.160776 -152.479248)
		(end 130.417824 -152.2222)
		(width 0.14224)
		(layer "In11.Cu")
		(net "M_M_DQ<47>")
	)
	(segment
		(start 130.827018 -149.533356)
		(end 130.84937 -149.533356)
		(width 0.14224)
		(layer "In11.Cu")
		(net "M_M_DQ<47>")
	)
	(segment
		(start 130.417824 -151.9174)
		(end 130.160776 -151.660352)
		(width 0.14224)
		(layer "In11.Cu")
		(net "M_M_DQ<47>")
	)
	(segment
		(start 130.443224 -150.435818)
		(end 130.398774 -150.391368)
		(width 0.14224)
		(layer "In11.Cu")
		(net "M_M_DQ<47>")
	)
	(segment
		(start 130.160776 -152.752552)
		(end 130.160776 -152.479248)
		(width 0.14224)
		(layer "In11.Cu")
		(net "M_M_DQ<47>")
	)
	(segment
		(start 130.160776 -151.660352)
		(end 130.160776 -151.387048)
		(width 0.14224)
		(layer "In11.Cu")
		(net "M_M_DQ<47>")
	)
	(segment
		(start 129.999486 -153.542746)
		(end 130.271774 -153.542746)
		(width 0.14224)
		(layer "In11.Cu")
		(net "M_M_DQ<47>")
	)
	(segment
		(start 130.398774 -149.9616)
		(end 130.827018 -149.533356)
		(width 0.14224)
		(layer "In11.Cu")
		(net "M_M_DQ<47>")
	)
	(segment
		(start 130.443224 -151.1046)
		(end 130.443224 -150.435818)
		(width 0.14224)
		(layer "In11.Cu")
		(net "M_M_DQ<47>")
	)
	(segment
		(start 130.449574 -153.364946)
		(end 130.449574 -153.04135)
		(width 0.14224)
		(layer "In11.Cu")
		(net "M_M_DQ<47>")
	)
	(segment
		(start 130.417824 -152.2222)
		(end 130.417824 -151.9174)
		(width 0.14224)
		(layer "In11.Cu")
		(net "M_M_DQ<47>")
	)
	(segment
		(start 130.271774 -153.542746)
		(end 130.449574 -153.364946)
		(width 0.14224)
		(layer "In11.Cu")
		(net "M_M_DQ<47>")
	)
	(segment
		(start 130.849624 -156.87294)
		(end 130.849624 -155.9052)
		(width 0.1651)
		(layer "F.Cu")
		(net "M_M_DQ<46>")
	)
	(segment
		(start 130.849624 -155.118054)
		(end 130.84937 -155.1178)
		(width 0.1651)
		(layer "F.Cu")
		(net "M_M_DQ<46>")
	)
	(segment
		(start 130.84937 -156.87294)
		(end 130.849624 -156.87294)
		(width 0.1651)
		(layer "F.Cu")
		(net "M_M_DQ<46>")
	)
	(segment
		(start 130.849624 -155.4226)
		(end 130.849624 -155.118054)
		(width 0.1651)
		(layer "F.Cu")
		(net "M_M_DQ<46>")
	)
	(segment
		(start 130.981704 -155.55468)
		(end 130.849624 -155.4226)
		(width 0.1651)
		(layer "F.Cu")
		(net "M_M_DQ<46>")
	)
	(segment
		(start 130.849624 -155.9052)
		(end 130.981704 -155.77312)
		(width 0.1651)
		(layer "F.Cu")
		(net "M_M_DQ<46>")
	)
	(segment
		(start 130.981704 -155.77312)
		(end 130.981704 -155.55468)
		(width 0.1651)
		(layer "F.Cu")
		(net "M_M_DQ<46>")
	)
	(segment
		(start 116.495322 -93.547184)
		(end 117.066822 -93.547184)
		(width 0.1651)
		(layer "F.Cu")
		(net "M_M_DQ<46>")
	)
	(via
		(at 117.066822 -93.547184)
		(size 0.508)
		(drill 0.254)
		(layers "F.Cu" "B.Cu")
		(net "M_M_DQ<46>")
	)
	(via
		(at 130.84937 -155.1178)
		(size 0.508)
		(drill 0.254)
		(layers "F.Cu" "B.Cu")
		(net "M_M_DQ<46>")
	)
	(via
		(at 129.999486 -150.814278)
		(size 0.508)
		(drill 0.254)
		(layers "F.Cu" "B.Cu")
		(net "M_M_DQ<46>")
	)
	(segment
		(start 129.999486 -152.078436)
		(end 129.999486 -150.814278)
		(width 0.1651)
		(layer "B.Cu")
		(net "M_M_DQ<46>")
	)
	(segment
		(start 130.363976 -134.6327)
		(end 130.363976 -136.081008)
		(width 0.14224)
		(layer "In4.Cu")
		(net "M_M_DQ<46>")
	)
	(segment
		(start 117.418358 -101.662992)
		(end 117.413532 -101.671628)
		(width 0.0889)
		(layer "In4.Cu")
		(net "M_M_DQ<46>")
	)
	(segment
		(start 130.363976 -140.908278)
		(end 130.516376 -141.060678)
		(width 0.14224)
		(layer "In4.Cu")
		(net "M_M_DQ<46>")
	)
	(segment
		(start 130.516376 -144.118838)
		(end 130.243834 -144.39138)
		(width 0.14224)
		(layer "In4.Cu")
		(net "M_M_DQ<46>")
	)
	(segment
		(start 130.465576 -131.408678)
		(end 130.465576 -131.9276)
		(width 0.14224)
		(layer "In4.Cu")
		(net "M_M_DQ<46>")
	)
	(segment
		(start 118.744492 -106.880914)
		(end 118.744492 -107.024932)
		(width 0.0889)
		(layer "In4.Cu")
		(net "M_M_DQ<46>")
	)
	(segment
		(start 130.363976 -139.663678)
		(end 130.363976 -140.908278)
		(width 0.14224)
		(layer "In4.Cu")
		(net "M_M_DQ<46>")
	)
	(segment
		(start 130.567176 -145.857468)
		(end 130.567176 -148.934678)
		(width 0.14224)
		(layer "In4.Cu")
		(net "M_M_DQ<46>")
	)
	(segment
		(start 130.243834 -144.39138)
		(end 130.243834 -145.534126)
		(width 0.14224)
		(layer "In4.Cu")
		(net "M_M_DQ<46>")
	)
	(segment
		(start 117.413532 -102.262432)
		(end 117.418358 -102.271068)
		(width 0.0889)
		(layer "In4.Cu")
		(net "M_M_DQ<46>")
	)
	(segment
		(start 117.066822 -93.547184)
		(end 116.736876 -94.309184)
		(width 0.0889)
		(layer "In4.Cu")
		(net "M_M_DQ<46>")
	)
	(segment
		(start 130.516376 -143.751808)
		(end 130.516376 -144.118838)
		(width 0.14224)
		(layer "In4.Cu")
		(net "M_M_DQ<46>")
	)
	(segment
		(start 130.567176 -136.284208)
		(end 130.567176 -136.525)
		(width 0.14224)
		(layer "In4.Cu")
		(net "M_M_DQ<46>")
	)
	(segment
		(start 118.325646 -105.929938)
		(end 118.325646 -106.462068)
		(width 0.0889)
		(layer "In4.Cu")
		(net "M_M_DQ<46>")
	)
	(segment
		(start 130.567176 -128.283208)
		(end 130.567176 -129.859278)
		(width 0.14224)
		(layer "In4.Cu")
		(net "M_M_DQ<46>")
	)
	(segment
		(start 130.426968 -128.143)
		(end 130.567176 -128.283208)
		(width 0.14224)
		(layer "In4.Cu")
		(net "M_M_DQ<46>")
	)
	(segment
		(start 130.363976 -130.062478)
		(end 130.363976 -131.307078)
		(width 0.14224)
		(layer "In4.Cu")
		(net "M_M_DQ<46>")
	)
	(segment
		(start 129.919222 -122.357134)
		(end 129.919222 -123.79833)
		(width 0.14224)
		(layer "In4.Cu")
		(net "M_M_DQ<46>")
	)
	(segment
		(start 117.413532 -100.681028)
		(end 117.407182 -100.691696)
		(width 0.0889)
		(layer "In4.Cu")
		(net "M_M_DQ<46>")
	)
	(segment
		(start 118.549928 -107.219496)
		(end 118.549928 -112.563656)
		(width 0.14224)
		(layer "In4.Cu")
		(net "M_M_DQ<46>")
	)
	(segment
		(start 118.549928 -112.563656)
		(end 127.339598 -121.353326)
		(width 0.14224)
		(layer "In4.Cu")
		(net "M_M_DQ<46>")
	)
	(segment
		(start 130.426968 -141.567408)
		(end 130.426968 -143.6624)
		(width 0.14224)
		(layer "In4.Cu")
		(net "M_M_DQ<46>")
	)
	(segment
		(start 130.363976 -131.307078)
		(end 130.465576 -131.408678)
		(width 0.14224)
		(layer "In4.Cu")
		(net "M_M_DQ<46>")
	)
	(segment
		(start 130.567176 -139.460478)
		(end 130.363976 -139.663678)
		(width 0.14224)
		(layer "In4.Cu")
		(net "M_M_DQ<46>")
	)
	(segment
		(start 130.426968 -134.0612)
		(end 130.465576 -134.099808)
		(width 0.14224)
		(layer "In4.Cu")
		(net "M_M_DQ<46>")
	)
	(segment
		(start 117.404642 -103.238046)
		(end 117.42039 -103.265478)
		(width 0.0889)
		(layer "In4.Cu")
		(net "M_M_DQ<46>")
	)
	(segment
		(start 127.339598 -121.353326)
		(end 128.915414 -121.353326)
		(width 0.14224)
		(layer "In4.Cu")
		(net "M_M_DQ<46>")
	)
	(segment
		(start 130.045968 -123.925076)
		(end 130.045968 -125.3998)
		(width 0.14224)
		(layer "In4.Cu")
		(net "M_M_DQ<46>")
	)
	(segment
		(start 130.567176 -148.934678)
		(end 129.999486 -149.502368)
		(width 0.14224)
		(layer "In4.Cu")
		(net "M_M_DQ<46>")
	)
	(segment
		(start 128.915414 -121.353326)
		(end 129.919222 -122.357134)
		(width 0.14224)
		(layer "In4.Cu")
		(net "M_M_DQ<46>")
	)
	(segment
		(start 130.426968 -143.6624)
		(end 130.516376 -143.751808)
		(width 0.14224)
		(layer "In4.Cu")
		(net "M_M_DQ<46>")
	)
	(segment
		(start 118.744492 -107.024932)
		(end 118.549928 -107.219496)
		(width 0.0889)
		(layer "In4.Cu")
		(net "M_M_DQ<46>")
	)
	(segment
		(start 129.999486 -149.502368)
		(end 129.999486 -150.814278)
		(width 0.14224)
		(layer "In4.Cu")
		(net "M_M_DQ<46>")
	)
	(segment
		(start 130.567176 -136.525)
		(end 130.423158 -136.669018)
		(width 0.14224)
		(layer "In4.Cu")
		(net "M_M_DQ<46>")
	)
	(segment
		(start 116.736876 -94.309184)
		(end 116.720112 -94.33814)
		(width 0.0889)
		(layer "In4.Cu")
		(net "M_M_DQ<46>")
	)
	(segment
		(start 116.720112 -95.328486)
		(end 116.715286 -95.337122)
		(width 0.0889)
		(layer "In4.Cu")
		(net "M_M_DQ<46>")
	)
	(segment
		(start 130.423158 -138.93419)
		(end 130.567176 -139.078208)
		(width 0.14224)
		(layer "In4.Cu")
		(net "M_M_DQ<46>")
	)
	(segment
		(start 130.465576 -134.099808)
		(end 130.465576 -134.5311)
		(width 0.14224)
		(layer "In4.Cu")
		(net "M_M_DQ<46>")
	)
	(segment
		(start 117.907562 -104.539288)
		(end 117.940328 -104.539288)
		(width 0.0889)
		(layer "In4.Cu")
		(net "M_M_DQ<46>")
	)
	(segment
		(start 130.567176 -139.078208)
		(end 130.567176 -139.460478)
		(width 0.14224)
		(layer "In4.Cu")
		(net "M_M_DQ<46>")
	)
	(segment
		(start 130.363976 -136.081008)
		(end 130.567176 -136.284208)
		(width 0.14224)
		(layer "In4.Cu")
		(net "M_M_DQ<46>")
	)
	(segment
		(start 118.325646 -106.462068)
		(end 118.744492 -106.880914)
		(width 0.0889)
		(layer "In4.Cu")
		(net "M_M_DQ<46>")
	)
	(segment
		(start 130.567176 -129.859278)
		(end 130.363976 -130.062478)
		(width 0.14224)
		(layer "In4.Cu")
		(net "M_M_DQ<46>")
	)
	(segment
		(start 116.720112 -94.737936)
		(end 116.726462 -94.748604)
		(width 0.0889)
		(layer "In4.Cu")
		(net "M_M_DQ<46>")
	)
	(segment
		(start 118.272052 -105.139236)
		(end 118.265702 -105.149904)
		(width 0.0889)
		(layer "In4.Cu")
		(net "M_M_DQ<46>")
	)
	(segment
		(start 130.516376 -141.060678)
		(end 130.516376 -141.478)
		(width 0.14224)
		(layer "In4.Cu")
		(net "M_M_DQ<46>")
	)
	(segment
		(start 118.276878 -105.1306)
		(end 118.272052 -105.139236)
		(width 0.0889)
		(layer "In4.Cu")
		(net "M_M_DQ<46>")
	)
	(segment
		(start 130.423158 -136.669018)
		(end 130.423158 -138.93419)
		(width 0.14224)
		(layer "In4.Cu")
		(net "M_M_DQ<46>")
	)
	(segment
		(start 130.516376 -141.478)
		(end 130.426968 -141.567408)
		(width 0.14224)
		(layer "In4.Cu")
		(net "M_M_DQ<46>")
	)
	(segment
		(start 130.045968 -125.3998)
		(end 130.426968 -125.7808)
		(width 0.14224)
		(layer "In4.Cu")
		(net "M_M_DQ<46>")
	)
	(segment
		(start 130.426968 -125.7808)
		(end 130.426968 -128.143)
		(width 0.14224)
		(layer "In4.Cu")
		(net "M_M_DQ<46>")
	)
	(segment
		(start 130.426968 -131.966208)
		(end 130.426968 -134.0612)
		(width 0.14224)
		(layer "In4.Cu")
		(net "M_M_DQ<46>")
	)
	(segment
		(start 117.413532 -99.290886)
		(end 117.418358 -99.299522)
		(width 0.0889)
		(layer "In4.Cu")
		(net "M_M_DQ<46>")
	)
	(segment
		(start 130.243834 -145.534126)
		(end 130.567176 -145.857468)
		(width 0.14224)
		(layer "In4.Cu")
		(net "M_M_DQ<46>")
	)
	(segment
		(start 129.919222 -123.79833)
		(end 130.045968 -123.925076)
		(width 0.14224)
		(layer "In4.Cu")
		(net "M_M_DQ<46>")
	)
	(segment
		(start 130.465576 -131.9276)
		(end 130.426968 -131.966208)
		(width 0.14224)
		(layer "In4.Cu")
		(net "M_M_DQ<46>")
	)
	(segment
		(start 130.465576 -134.5311)
		(end 130.363976 -134.6327)
		(width 0.14224)
		(layer "In4.Cu")
		(net "M_M_DQ<46>")
	)
	(arc
		(start 117.413532 -96.319594)
		(mid 117.467065 -96.519492)
		(end 117.413532 -96.71939)
		(width 0.0889)
		(layer "In4.Cu")
		(net "M_M_DQ<46>")
	)
	(arc
		(start 117.413532 -98.300794)
		(mid 117.467031 -98.500692)
		(end 117.413532 -98.70059)
		(width 0.0889)
		(layer "In4.Cu")
		(net "M_M_DQ<46>")
	)
	(arc
		(start 116.819172 -95.89262)
		(mid 116.861967 -95.979586)
		(end 116.933472 -96.04502)
		(width 0.0889)
		(layer "In4.Cu")
		(net "M_M_DQ<46>")
	)
	(arc
		(start 116.933472 -96.04502)
		(mid 116.988391 -96.070755)
		(end 117.047772 -96.08312)
		(width 0.0889)
		(layer "In4.Cu")
		(net "M_M_DQ<46>")
	)
	(arc
		(start 117.413532 -101.271578)
		(mid 117.467002 -101.466641)
		(end 117.418358 -101.662992)
		(width 0.0889)
		(layer "In4.Cu")
		(net "M_M_DQ<46>")
	)
	(arc
		(start 117.413532 -96.71939)
		(mid 117.334401 -97.014792)
		(end 117.413532 -97.310194)
		(width 0.0889)
		(layer "In4.Cu")
		(net "M_M_DQ<46>")
	)
	(arc
		(start 117.407182 -100.691696)
		(mid 117.334384 -100.982459)
		(end 117.413532 -101.271578)
		(width 0.0889)
		(layer "In4.Cu")
		(net "M_M_DQ<46>")
	)
	(arc
		(start 117.42039 -103.265478)
		(mid 117.467066 -103.460179)
		(end 117.413532 -103.653082)
		(width 0.0889)
		(layer "In4.Cu")
		(net "M_M_DQ<46>")
	)
	(arc
		(start 117.418358 -102.271068)
		(mid 117.467113 -102.46742)
		(end 117.413532 -102.662482)
		(width 0.0889)
		(layer "In4.Cu")
		(net "M_M_DQ<46>")
	)
	(arc
		(start 116.726462 -94.748604)
		(mid 116.79926 -95.039367)
		(end 116.720112 -95.328486)
		(width 0.0889)
		(layer "In4.Cu")
		(net "M_M_DQ<46>")
	)
	(arc
		(start 116.720112 -95.728536)
		(mid 116.768814 -95.811078)
		(end 116.819172 -95.89262)
		(width 0.0889)
		(layer "In4.Cu")
		(net "M_M_DQ<46>")
	)
	(arc
		(start 118.265702 -105.149904)
		(mid 118.192904 -105.440667)
		(end 118.272052 -105.729786)
		(width 0.0889)
		(layer "In4.Cu")
		(net "M_M_DQ<46>")
	)
	(arc
		(start 117.413532 -99.690936)
		(mid 117.335254 -99.954587)
		(end 117.38483 -100.225098)
		(width 0.0889)
		(layer "In4.Cu")
		(net "M_M_DQ<46>")
	)
	(arc
		(start 117.413532 -97.70999)
		(mid 117.334401 -98.005392)
		(end 117.413532 -98.300794)
		(width 0.0889)
		(layer "In4.Cu")
		(net "M_M_DQ<46>")
	)
	(arc
		(start 117.940328 -104.539288)
		(mid 118.273246 -104.741279)
		(end 118.276878 -105.1306)
		(width 0.0889)
		(layer "In4.Cu")
		(net "M_M_DQ<46>")
	)
	(arc
		(start 117.418358 -99.299522)
		(mid 117.467113 -99.495874)
		(end 117.413532 -99.690936)
		(width 0.0889)
		(layer "In4.Cu")
		(net "M_M_DQ<46>")
	)
	(arc
		(start 118.272052 -105.729786)
		(mid 118.312039 -105.826332)
		(end 118.325646 -105.929938)
		(width 0.0889)
		(layer "In4.Cu")
		(net "M_M_DQ<46>")
	)
	(arc
		(start 117.413532 -103.653082)
		(mid 117.409204 -104.236258)
		(end 117.907562 -104.539288)
		(width 0.0889)
		(layer "In4.Cu")
		(net "M_M_DQ<46>")
	)
	(arc
		(start 117.38483 -100.225098)
		(mid 117.398479 -100.253524)
		(end 117.413532 -100.281232)
		(width 0.0889)
		(layer "In4.Cu")
		(net "M_M_DQ<46>")
	)
	(arc
		(start 117.047772 -96.08312)
		(mid 117.214631 -96.130384)
		(end 117.352572 -96.23552)
		(width 0.0889)
		(layer "In4.Cu")
		(net "M_M_DQ<46>")
	)
	(arc
		(start 117.413532 -102.662482)
		(mid 117.334343 -102.949097)
		(end 117.404642 -103.238046)
		(width 0.0889)
		(layer "In4.Cu")
		(net "M_M_DQ<46>")
	)
	(arc
		(start 116.715286 -95.337122)
		(mid 116.666531 -95.533474)
		(end 116.720112 -95.728536)
		(width 0.0889)
		(layer "In4.Cu")
		(net "M_M_DQ<46>")
	)
	(arc
		(start 117.413532 -101.671628)
		(mid 117.334401 -101.96703)
		(end 117.413532 -102.262432)
		(width 0.0889)
		(layer "In4.Cu")
		(net "M_M_DQ<46>")
	)
	(arc
		(start 117.413532 -100.281232)
		(mid 117.467031 -100.48113)
		(end 117.413532 -100.681028)
		(width 0.0889)
		(layer "In4.Cu")
		(net "M_M_DQ<46>")
	)
	(arc
		(start 117.413532 -97.310194)
		(mid 117.467031 -97.510092)
		(end 117.413532 -97.70999)
		(width 0.0889)
		(layer "In4.Cu")
		(net "M_M_DQ<46>")
	)
	(arc
		(start 116.720112 -94.33814)
		(mid 116.666613 -94.538038)
		(end 116.720112 -94.737936)
		(width 0.0889)
		(layer "In4.Cu")
		(net "M_M_DQ<46>")
	)
	(arc
		(start 117.413532 -98.70059)
		(mid 117.334527 -98.995738)
		(end 117.413532 -99.290886)
		(width 0.0889)
		(layer "In4.Cu")
		(net "M_M_DQ<46>")
	)
	(arc
		(start 117.352572 -96.23552)
		(mid 117.385245 -96.275967)
		(end 117.413532 -96.319594)
		(width 0.0889)
		(layer "In4.Cu")
		(net "M_M_DQ<46>")
	)
	(segment
		(start 129.566416 -151.247348)
		(end 129.999486 -150.814278)
		(width 0.14224)
		(layer "In11.Cu")
		(net "M_M_DQ<46>")
	)
	(segment
		(start 129.566416 -153.834846)
		(end 129.566416 -151.247348)
		(width 0.14224)
		(layer "In11.Cu")
		(net "M_M_DQ<46>")
	)
	(segment
		(start 130.84937 -155.1178)
		(end 129.566416 -153.834846)
		(width 0.14224)
		(layer "In11.Cu")
		(net "M_M_DQ<46>")
	)
	(segment
		(start 113.919762 -95.033084)
		(end 114.491262 -95.033084)
		(width 0.1651)
		(layer "F.Cu")
		(net "M_M_DQ<45>")
	)
	(segment
		(start 124.049536 -152.273)
		(end 124.049536 -153.542746)
		(width 0.1651)
		(layer "F.Cu")
		(net "M_M_DQ<45>")
	)
	(via
		(at 124.049536 -153.542746)
		(size 0.508)
		(drill 0.254)
		(layers "F.Cu" "B.Cu")
		(net "M_M_DQ<45>")
	)
	(via
		(at 124.82322 -149.533356)
		(size 0.508)
		(drill 0.254)
		(layers "F.Cu" "B.Cu")
		(net "M_M_DQ<45>")
	)
	(via
		(at 114.491262 -95.033084)
		(size 0.508)
		(drill 0.254)
		(layers "F.Cu" "B.Cu")
		(net "M_M_DQ<45>")
	)
	(segment
		(start 124.89942 -149.457156)
		(end 124.82322 -149.533356)
		(width 0.1651)
		(layer "B.Cu")
		(net "M_M_DQ<45>")
	)
	(segment
		(start 124.89942 -147.478496)
		(end 124.89942 -149.457156)
		(width 0.1651)
		(layer "B.Cu")
		(net "M_M_DQ<45>")
	)
	(segment
		(start 116.460016 -115.872006)
		(end 116.711984 -115.620038)
		(width 0.14224)
		(layer "In4.Cu")
		(net "M_M_DQ<45>")
	)
	(segment
		(start 125.321568 -134.023608)
		(end 125.143768 -134.201408)
		(width 0.14224)
		(layer "In4.Cu")
		(net "M_M_DQ<45>")
	)
	(segment
		(start 114.144552 -105.139236)
		(end 114.150902 -105.149904)
		(width 0.0889)
		(layer "In4.Cu")
		(net "M_M_DQ<45>")
	)
	(segment
		(start 116.241068 -115.872006)
		(end 116.460016 -115.872006)
		(width 0.14224)
		(layer "In4.Cu")
		(net "M_M_DQ<45>")
	)
	(segment
		(start 123.80087 -123.431808)
		(end 124.166376 -123.431808)
		(width 0.14224)
		(layer "In4.Cu")
		(net "M_M_DQ<45>")
	)
	(segment
		(start 125.321568 -141.617192)
		(end 125.321568 -143.6878)
		(width 0.14224)
		(layer "In4.Cu")
		(net "M_M_DQ<45>")
	)
	(segment
		(start 125.238764 -129.977896)
		(end 125.397768 -130.1369)
		(width 0.14224)
		(layer "In4.Cu")
		(net "M_M_DQ<45>")
	)
	(segment
		(start 125.397768 -131.089654)
		(end 125.092968 -131.394454)
		(width 0.14224)
		(layer "In4.Cu")
		(net "M_M_DQ<45>")
	)
	(segment
		(start 125.321568 -138.7348)
		(end 125.121924 -138.934444)
		(width 0.14224)
		(layer "In4.Cu")
		(net "M_M_DQ<45>")
	)
	(segment
		(start 114.144552 -102.167436)
		(end 114.150902 -102.178104)
		(width 0.0889)
		(layer "In4.Cu")
		(net "M_M_DQ<45>")
	)
	(segment
		(start 125.233176 -143.776192)
		(end 125.233176 -144.271238)
		(width 0.14224)
		(layer "In4.Cu")
		(net "M_M_DQ<45>")
	)
	(segment
		(start 114.144552 -100.186236)
		(end 114.150902 -100.196904)
		(width 0.0889)
		(layer "In4.Cu")
		(net "M_M_DQ<45>")
	)
	(segment
		(start 125.321568 -136.638792)
		(end 125.321568 -138.7348)
		(width 0.14224)
		(layer "In4.Cu")
		(net "M_M_DQ<45>")
	)
	(segment
		(start 114.139726 -101.1682)
		(end 114.144552 -101.176836)
		(width 0.0889)
		(layer "In4.Cu")
		(net "M_M_DQ<45>")
	)
	(segment
		(start 125.321568 -148.4884)
		(end 124.82322 -148.986748)
		(width 0.14224)
		(layer "In4.Cu")
		(net "M_M_DQ<45>")
	)
	(segment
		(start 114.477292 -106.38282)
		(end 114.477292 -106.98226)
		(width 0.0889)
		(layer "In4.Cu")
		(net "M_M_DQ<45>")
	)
	(segment
		(start 115.774216 -114.68227)
		(end 115.993418 -114.68227)
		(width 0.14224)
		(layer "In4.Cu")
		(net "M_M_DQ<45>")
	)
	(segment
		(start 116.243354 -115.151154)
		(end 115.991132 -115.403376)
		(width 0.14224)
		(layer "In4.Cu")
		(net "M_M_DQ<45>")
	)
	(segment
		(start 116.9289 -116.559838)
		(end 123.80087 -123.431808)
		(width 0.14224)
		(layer "In4.Cu")
		(net "M_M_DQ<45>")
	)
	(segment
		(start 125.166628 -148.022056)
		(end 125.321568 -148.176996)
		(width 0.14224)
		(layer "In4.Cu")
		(net "M_M_DQ<45>")
	)
	(segment
		(start 114.714528 -114.345466)
		(end 115.3033 -114.934238)
		(width 0.14224)
		(layer "In4.Cu")
		(net "M_M_DQ<45>")
	)
	(segment
		(start 125.423168 -139.725654)
		(end 125.423168 -140.845286)
		(width 0.14224)
		(layer "In4.Cu")
		(net "M_M_DQ<45>")
	)
	(segment
		(start 116.9289 -116.341144)
		(end 116.9289 -116.559838)
		(width 0.14224)
		(layer "In4.Cu")
		(net "M_M_DQ<45>")
	)
	(segment
		(start 125.423168 -140.845286)
		(end 125.169168 -141.099286)
		(width 0.14224)
		(layer "In4.Cu")
		(net "M_M_DQ<45>")
	)
	(segment
		(start 125.321568 -136.0424)
		(end 125.167136 -136.196832)
		(width 0.14224)
		(layer "In4.Cu")
		(net "M_M_DQ<45>")
	)
	(segment
		(start 125.321568 -143.6878)
		(end 125.233176 -143.776192)
		(width 0.14224)
		(layer "In4.Cu")
		(net "M_M_DQ<45>")
	)
	(segment
		(start 125.238764 -129.216404)
		(end 125.238764 -129.977896)
		(width 0.14224)
		(layer "In4.Cu")
		(net "M_M_DQ<45>")
	)
	(segment
		(start 125.207776 -146.1516)
		(end 125.321568 -146.265392)
		(width 0.14224)
		(layer "In4.Cu")
		(net "M_M_DQ<45>")
	)
	(segment
		(start 114.139726 -105.1306)
		(end 114.144552 -105.139236)
		(width 0.0889)
		(layer "In4.Cu")
		(net "M_M_DQ<45>")
	)
	(segment
		(start 114.139726 -100.1776)
		(end 114.144552 -100.186236)
		(width 0.0889)
		(layer "In4.Cu")
		(net "M_M_DQ<45>")
	)
	(segment
		(start 114.477292 -106.98226)
		(end 114.714528 -107.219496)
		(width 0.0889)
		(layer "In4.Cu")
		(net "M_M_DQ<45>")
	)
	(segment
		(start 117.181122 -116.088922)
		(end 116.9289 -116.341144)
		(width 0.14224)
		(layer "In4.Cu")
		(net "M_M_DQ<45>")
	)
	(segment
		(start 114.144552 -101.176836)
		(end 114.150902 -101.187504)
		(width 0.0889)
		(layer "In4.Cu")
		(net "M_M_DQ<45>")
	)
	(segment
		(start 114.144552 -104.148636)
		(end 114.150902 -104.159304)
		(width 0.0889)
		(layer "In4.Cu")
		(net "M_M_DQ<45>")
	)
	(segment
		(start 115.3033 -114.934238)
		(end 115.522248 -114.934238)
		(width 0.14224)
		(layer "In4.Cu")
		(net "M_M_DQ<45>")
	)
	(segment
		(start 124.295916 -147.364196)
		(end 124.295916 -147.867116)
		(width 0.14224)
		(layer "In4.Cu")
		(net "M_M_DQ<45>")
	)
	(segment
		(start 125.121924 -138.934444)
		(end 125.121924 -139.42441)
		(width 0.14224)
		(layer "In4.Cu")
		(net "M_M_DQ<45>")
	)
	(segment
		(start 125.118368 -126.752604)
		(end 125.981968 -127.616204)
		(width 0.14224)
		(layer "In4.Cu")
		(net "M_M_DQ<45>")
	)
	(segment
		(start 125.981968 -127.616204)
		(end 125.981968 -128.4732)
		(width 0.14224)
		(layer "In4.Cu")
		(net "M_M_DQ<45>")
	)
	(segment
		(start 125.233176 -144.271238)
		(end 125.360176 -144.398238)
		(width 0.14224)
		(layer "In4.Cu")
		(net "M_M_DQ<45>")
	)
	(segment
		(start 116.243354 -114.932206)
		(end 116.243354 -115.151154)
		(width 0.14224)
		(layer "In4.Cu")
		(net "M_M_DQ<45>")
	)
	(segment
		(start 125.360176 -144.398238)
		(end 125.360176 -145.454624)
		(width 0.14224)
		(layer "In4.Cu")
		(net "M_M_DQ<45>")
	)
	(segment
		(start 114.139726 -102.1588)
		(end 114.144552 -102.167436)
		(width 0.0889)
		(layer "In4.Cu")
		(net "M_M_DQ<45>")
	)
	(segment
		(start 116.711984 -115.620038)
		(end 116.931186 -115.620038)
		(width 0.14224)
		(layer "In4.Cu")
		(net "M_M_DQ<45>")
	)
	(segment
		(start 125.981968 -128.4732)
		(end 125.238764 -129.216404)
		(width 0.14224)
		(layer "In4.Cu")
		(net "M_M_DQ<45>")
	)
	(segment
		(start 125.321568 -146.265392)
		(end 125.321568 -147.054316)
		(width 0.14224)
		(layer "In4.Cu")
		(net "M_M_DQ<45>")
	)
	(segment
		(start 125.321568 -147.054316)
		(end 125.166628 -147.209256)
		(width 0.14224)
		(layer "In4.Cu")
		(net "M_M_DQ<45>")
	)
	(segment
		(start 115.522248 -114.934238)
		(end 115.774216 -114.68227)
		(width 0.14224)
		(layer "In4.Cu")
		(net "M_M_DQ<45>")
	)
	(segment
		(start 125.207776 -145.607024)
		(end 125.207776 -146.1516)
		(width 0.14224)
		(layer "In4.Cu")
		(net "M_M_DQ<45>")
	)
	(segment
		(start 125.143768 -134.5438)
		(end 125.321568 -134.7216)
		(width 0.14224)
		(layer "In4.Cu")
		(net "M_M_DQ<45>")
	)
	(segment
		(start 125.169168 -141.099286)
		(end 125.169168 -141.464792)
		(width 0.14224)
		(layer "In4.Cu")
		(net "M_M_DQ<45>")
	)
	(segment
		(start 117.181122 -115.869974)
		(end 117.181122 -116.088922)
		(width 0.14224)
		(layer "In4.Cu")
		(net "M_M_DQ<45>")
	)
	(segment
		(start 125.092968 -131.394454)
		(end 125.092968 -131.8768)
		(width 0.14224)
		(layer "In4.Cu")
		(net "M_M_DQ<45>")
	)
	(segment
		(start 114.090958 -105.996486)
		(end 114.477292 -106.38282)
		(width 0.0889)
		(layer "In4.Cu")
		(net "M_M_DQ<45>")
	)
	(segment
		(start 125.166628 -147.209256)
		(end 124.450856 -147.209256)
		(width 0.14224)
		(layer "In4.Cu")
		(net "M_M_DQ<45>")
	)
	(segment
		(start 124.450856 -148.022056)
		(end 125.166628 -148.022056)
		(width 0.14224)
		(layer "In4.Cu")
		(net "M_M_DQ<45>")
	)
	(segment
		(start 114.090958 -105.929684)
		(end 114.090958 -105.996486)
		(width 0.0889)
		(layer "In4.Cu")
		(net "M_M_DQ<45>")
	)
	(segment
		(start 114.139726 -104.14)
		(end 114.144552 -104.148636)
		(width 0.0889)
		(layer "In4.Cu")
		(net "M_M_DQ<45>")
	)
	(segment
		(start 125.143768 -134.201408)
		(end 125.143768 -134.5438)
		(width 0.14224)
		(layer "In4.Cu")
		(net "M_M_DQ<45>")
	)
	(segment
		(start 125.167136 -136.48436)
		(end 125.321568 -136.638792)
		(width 0.14224)
		(layer "In4.Cu")
		(net "M_M_DQ<45>")
	)
	(segment
		(start 125.092968 -131.8768)
		(end 125.321568 -132.1054)
		(width 0.14224)
		(layer "In4.Cu")
		(net "M_M_DQ<45>")
	)
	(segment
		(start 114.491262 -95.033084)
		(end 114.207544 -95.666306)
		(width 0.0889)
		(layer "In4.Cu")
		(net "M_M_DQ<45>")
	)
	(segment
		(start 114.144552 -103.158036)
		(end 114.150902 -103.168704)
		(width 0.0889)
		(layer "In4.Cu")
		(net "M_M_DQ<45>")
	)
	(segment
		(start 124.295916 -147.867116)
		(end 124.450856 -148.022056)
		(width 0.14224)
		(layer "In4.Cu")
		(net "M_M_DQ<45>")
	)
	(segment
		(start 125.397768 -130.1369)
		(end 125.397768 -131.089654)
		(width 0.14224)
		(layer "In4.Cu")
		(net "M_M_DQ<45>")
	)
	(segment
		(start 125.321568 -148.176996)
		(end 125.321568 -148.4884)
		(width 0.14224)
		(layer "In4.Cu")
		(net "M_M_DQ<45>")
	)
	(segment
		(start 114.714528 -107.219496)
		(end 114.714528 -114.345466)
		(width 0.14224)
		(layer "In4.Cu")
		(net "M_M_DQ<45>")
	)
	(segment
		(start 125.321568 -134.7216)
		(end 125.321568 -136.0424)
		(width 0.14224)
		(layer "In4.Cu")
		(net "M_M_DQ<45>")
	)
	(segment
		(start 115.993418 -114.68227)
		(end 116.243354 -114.932206)
		(width 0.14224)
		(layer "In4.Cu")
		(net "M_M_DQ<45>")
	)
	(segment
		(start 125.121924 -139.42441)
		(end 125.423168 -139.725654)
		(width 0.14224)
		(layer "In4.Cu")
		(net "M_M_DQ<45>")
	)
	(segment
		(start 125.167136 -136.196832)
		(end 125.167136 -136.48436)
		(width 0.14224)
		(layer "In4.Cu")
		(net "M_M_DQ<45>")
	)
	(segment
		(start 125.118368 -125.7554)
		(end 125.118368 -126.752604)
		(width 0.14224)
		(layer "In4.Cu")
		(net "M_M_DQ<45>")
	)
	(segment
		(start 124.82322 -148.986748)
		(end 124.82322 -149.533356)
		(width 0.14224)
		(layer "In4.Cu")
		(net "M_M_DQ<45>")
	)
	(segment
		(start 114.139726 -103.1494)
		(end 114.144552 -103.158036)
		(width 0.0889)
		(layer "In4.Cu")
		(net "M_M_DQ<45>")
	)
	(segment
		(start 115.991132 -115.403376)
		(end 115.991132 -115.62207)
		(width 0.14224)
		(layer "In4.Cu")
		(net "M_M_DQ<45>")
	)
	(segment
		(start 125.360176 -145.454624)
		(end 125.207776 -145.607024)
		(width 0.14224)
		(layer "In4.Cu")
		(net "M_M_DQ<45>")
	)
	(segment
		(start 115.991132 -115.62207)
		(end 116.241068 -115.872006)
		(width 0.14224)
		(layer "In4.Cu")
		(net "M_M_DQ<45>")
	)
	(segment
		(start 125.321568 -132.1054)
		(end 125.321568 -134.023608)
		(width 0.14224)
		(layer "In4.Cu")
		(net "M_M_DQ<45>")
	)
	(segment
		(start 124.166376 -123.431808)
		(end 125.270768 -124.5362)
		(width 0.14224)
		(layer "In4.Cu")
		(net "M_M_DQ<45>")
	)
	(segment
		(start 125.270768 -125.603)
		(end 125.118368 -125.7554)
		(width 0.14224)
		(layer "In4.Cu")
		(net "M_M_DQ<45>")
	)
	(segment
		(start 125.270768 -124.5362)
		(end 125.270768 -125.603)
		(width 0.14224)
		(layer "In4.Cu")
		(net "M_M_DQ<45>")
	)
	(segment
		(start 124.450856 -147.209256)
		(end 124.295916 -147.364196)
		(width 0.14224)
		(layer "In4.Cu")
		(net "M_M_DQ<45>")
	)
	(segment
		(start 125.169168 -141.464792)
		(end 125.321568 -141.617192)
		(width 0.14224)
		(layer "In4.Cu")
		(net "M_M_DQ<45>")
	)
	(segment
		(start 116.931186 -115.620038)
		(end 117.181122 -115.869974)
		(width 0.14224)
		(layer "In4.Cu")
		(net "M_M_DQ<45>")
	)
	(arc
		(start 114.144552 -102.757986)
		(mid 114.091082 -102.953049)
		(end 114.139726 -103.1494)
		(width 0.0889)
		(layer "In4.Cu")
		(net "M_M_DQ<45>")
	)
	(arc
		(start 114.144552 -105.729786)
		(mid 114.104598 -105.82621)
		(end 114.090958 -105.929684)
		(width 0.0889)
		(layer "In4.Cu")
		(net "M_M_DQ<45>")
	)
	(arc
		(start 114.144552 -97.805494)
		(mid 114.091053 -98.005392)
		(end 114.144552 -98.20529)
		(width 0.0889)
		(layer "In4.Cu")
		(net "M_M_DQ<45>")
	)
	(arc
		(start 114.144552 -95.824294)
		(mid 114.091053 -96.024192)
		(end 114.144552 -96.22409)
		(width 0.0889)
		(layer "In4.Cu")
		(net "M_M_DQ<45>")
	)
	(arc
		(start 114.144552 -96.814894)
		(mid 114.091053 -97.014792)
		(end 114.144552 -97.21469)
		(width 0.0889)
		(layer "In4.Cu")
		(net "M_M_DQ<45>")
	)
	(arc
		(start 114.150902 -103.168704)
		(mid 114.2237 -103.459467)
		(end 114.144552 -103.748586)
		(width 0.0889)
		(layer "In4.Cu")
		(net "M_M_DQ<45>")
	)
	(arc
		(start 114.144552 -99.786186)
		(mid 114.091082 -99.981249)
		(end 114.139726 -100.1776)
		(width 0.0889)
		(layer "In4.Cu")
		(net "M_M_DQ<45>")
	)
	(arc
		(start 114.150902 -101.187504)
		(mid 114.2237 -101.478267)
		(end 114.144552 -101.767386)
		(width 0.0889)
		(layer "In4.Cu")
		(net "M_M_DQ<45>")
	)
	(arc
		(start 114.144552 -96.22409)
		(mid 114.223683 -96.519492)
		(end 114.144552 -96.814894)
		(width 0.0889)
		(layer "In4.Cu")
		(net "M_M_DQ<45>")
	)
	(arc
		(start 114.150902 -104.159304)
		(mid 114.2237 -104.450067)
		(end 114.144552 -104.739186)
		(width 0.0889)
		(layer "In4.Cu")
		(net "M_M_DQ<45>")
	)
	(arc
		(start 114.144552 -100.776786)
		(mid 114.091082 -100.971849)
		(end 114.139726 -101.1682)
		(width 0.0889)
		(layer "In4.Cu")
		(net "M_M_DQ<45>")
	)
	(arc
		(start 114.150902 -100.196904)
		(mid 114.2237 -100.487667)
		(end 114.144552 -100.776786)
		(width 0.0889)
		(layer "In4.Cu")
		(net "M_M_DQ<45>")
	)
	(arc
		(start 114.144552 -97.21469)
		(mid 114.223683 -97.510092)
		(end 114.144552 -97.805494)
		(width 0.0889)
		(layer "In4.Cu")
		(net "M_M_DQ<45>")
	)
	(arc
		(start 114.150902 -102.178104)
		(mid 114.2237 -102.468867)
		(end 114.144552 -102.757986)
		(width 0.0889)
		(layer "In4.Cu")
		(net "M_M_DQ<45>")
	)
	(arc
		(start 114.144552 -103.748586)
		(mid 114.091082 -103.943649)
		(end 114.139726 -104.14)
		(width 0.0889)
		(layer "In4.Cu")
		(net "M_M_DQ<45>")
	)
	(arc
		(start 114.144552 -99.19589)
		(mid 114.147661 -99.201137)
		(end 114.150902 -99.206304)
		(width 0.0889)
		(layer "In4.Cu")
		(net "M_M_DQ<45>")
	)
	(arc
		(start 114.144552 -101.767386)
		(mid 114.091082 -101.962449)
		(end 114.139726 -102.1588)
		(width 0.0889)
		(layer "In4.Cu")
		(net "M_M_DQ<45>")
	)
	(arc
		(start 114.207544 -95.666306)
		(mid 114.181756 -95.747575)
		(end 114.144552 -95.824294)
		(width 0.0889)
		(layer "In4.Cu")
		(net "M_M_DQ<45>")
	)
	(arc
		(start 114.144552 -98.796094)
		(mid 114.091053 -98.995992)
		(end 114.144552 -99.19589)
		(width 0.0889)
		(layer "In4.Cu")
		(net "M_M_DQ<45>")
	)
	(arc
		(start 114.144552 -98.20529)
		(mid 114.223683 -98.500692)
		(end 114.144552 -98.796094)
		(width 0.0889)
		(layer "In4.Cu")
		(net "M_M_DQ<45>")
	)
	(arc
		(start 114.150902 -105.149904)
		(mid 114.2237 -105.440667)
		(end 114.144552 -105.729786)
		(width 0.0889)
		(layer "In4.Cu")
		(net "M_M_DQ<45>")
	)
	(arc
		(start 114.150902 -99.206304)
		(mid 114.2237 -99.497067)
		(end 114.144552 -99.786186)
		(width 0.0889)
		(layer "In4.Cu")
		(net "M_M_DQ<45>")
	)
	(arc
		(start 114.144552 -104.739186)
		(mid 114.091082 -104.934249)
		(end 114.139726 -105.1306)
		(width 0.0889)
		(layer "In4.Cu")
		(net "M_M_DQ<45>")
	)
	(segment
		(start 124.210826 -152.586944)
		(end 124.448824 -152.348946)
		(width 0.14224)
		(layer "In11.Cu")
		(net "M_M_DQ<45>")
	)
	(segment
		(start 124.499624 -150.6474)
		(end 124.372624 -150.5204)
		(width 0.14224)
		(layer "In11.Cu")
		(net "M_M_DQ<45>")
	)
	(segment
		(start 124.210826 -152.898856)
		(end 124.210826 -152.586944)
		(width 0.14224)
		(layer "In11.Cu")
		(net "M_M_DQ<45>")
	)
	(segment
		(start 124.210826 -151.755856)
		(end 124.210826 -151.418544)
		(width 0.14224)
		(layer "In11.Cu")
		(net "M_M_DQ<45>")
	)
	(segment
		(start 124.210826 -151.418544)
		(end 124.499624 -151.129746)
		(width 0.14224)
		(layer "In11.Cu")
		(net "M_M_DQ<45>")
	)
	(segment
		(start 124.372624 -150.5204)
		(end 124.372624 -149.9616)
		(width 0.14224)
		(layer "In11.Cu")
		(net "M_M_DQ<45>")
	)
	(segment
		(start 124.372624 -149.9616)
		(end 124.800868 -149.533356)
		(width 0.14224)
		(layer "In11.Cu")
		(net "M_M_DQ<45>")
	)
	(segment
		(start 124.474224 -153.390346)
		(end 124.474224 -153.162254)
		(width 0.14224)
		(layer "In11.Cu")
		(net "M_M_DQ<45>")
	)
	(segment
		(start 124.800868 -149.533356)
		(end 124.82322 -149.533356)
		(width 0.14224)
		(layer "In11.Cu")
		(net "M_M_DQ<45>")
	)
	(segment
		(start 124.474224 -153.162254)
		(end 124.210826 -152.898856)
		(width 0.14224)
		(layer "In11.Cu")
		(net "M_M_DQ<45>")
	)
	(segment
		(start 124.448824 -151.993854)
		(end 124.210826 -151.755856)
		(width 0.14224)
		(layer "In11.Cu")
		(net "M_M_DQ<45>")
	)
	(segment
		(start 124.448824 -152.348946)
		(end 124.448824 -151.993854)
		(width 0.14224)
		(layer "In11.Cu")
		(net "M_M_DQ<45>")
	)
	(segment
		(start 124.499624 -151.129746)
		(end 124.499624 -150.6474)
		(width 0.14224)
		(layer "In11.Cu")
		(net "M_M_DQ<45>")
	)
	(segment
		(start 124.321824 -153.542746)
		(end 124.474224 -153.390346)
		(width 0.14224)
		(layer "In11.Cu")
		(net "M_M_DQ<45>")
	)
	(segment
		(start 124.049536 -153.542746)
		(end 124.321824 -153.542746)
		(width 0.14224)
		(layer "In11.Cu")
		(net "M_M_DQ<45>")
	)
	(segment
		(start 113.919762 -94.042738)
		(end 114.491262 -94.042738)
		(width 0.1651)
		(layer "F.Cu")
		(net "M_M_DQ<44>")
	)
	(segment
		(start 124.89942 -155.365196)
		(end 124.897896 -155.363672)
		(width 0.1651)
		(layer "F.Cu")
		(net "M_M_DQ<44>")
	)
	(segment
		(start 124.89942 -156.87294)
		(end 124.89942 -155.365196)
		(width 0.1651)
		(layer "F.Cu")
		(net "M_M_DQ<44>")
	)
	(via
		(at 124.049536 -150.814278)
		(size 0.508)
		(drill 0.254)
		(layers "F.Cu" "B.Cu")
		(net "M_M_DQ<44>")
	)
	(via
		(at 114.491262 -94.042738)
		(size 0.508)
		(drill 0.254)
		(layers "F.Cu" "B.Cu")
		(net "M_M_DQ<44>")
	)
	(via
		(at 124.897896 -155.363672)
		(size 0.508)
		(drill 0.254)
		(layers "F.Cu" "B.Cu")
		(net "M_M_DQ<44>")
	)
	(segment
		(start 124.049536 -152.078436)
		(end 124.049536 -150.814278)
		(width 0.1651)
		(layer "B.Cu")
		(net "M_M_DQ<44>")
	)
	(segment
		(start 124.483368 -132.093208)
		(end 124.483368 -134.0612)
		(width 0.14224)
		(layer "In4.Cu")
		(net "M_M_DQ<44>")
	)
	(segment
		(start 124.483368 -141.6812)
		(end 124.483368 -143.6878)
		(width 0.14224)
		(layer "In4.Cu")
		(net "M_M_DQ<44>")
	)
	(segment
		(start 123.686062 -124.066808)
		(end 124.044964 -124.066808)
		(width 0.14224)
		(layer "In4.Cu")
		(net "M_M_DQ<44>")
	)
	(segment
		(start 124.635768 -141.5288)
		(end 124.483368 -141.6812)
		(width 0.14224)
		(layer "In4.Cu")
		(net "M_M_DQ<44>")
	)
	(segment
		(start 113.973102 -103.242618)
		(end 113.979452 -103.253286)
		(width 0.0889)
		(layer "In4.Cu")
		(net "M_M_DQ<44>")
	)
	(segment
		(start 123.50115 -147.210526)
		(end 123.50115 -149.079966)
		(width 0.14224)
		(layer "In4.Cu")
		(net "M_M_DQ<44>")
	)
	(segment
		(start 124.572776 -139.333478)
		(end 124.318776 -139.587478)
		(width 0.14224)
		(layer "In4.Cu")
		(net "M_M_DQ<44>")
	)
	(segment
		(start 124.483368 -134.0612)
		(end 124.547376 -134.125208)
		(width 0.14224)
		(layer "In4.Cu")
		(net "M_M_DQ<44>")
	)
	(segment
		(start 113.979452 -104.243886)
		(end 113.984278 -104.252522)
		(width 0.0889)
		(layer "In4.Cu")
		(net "M_M_DQ<44>")
	)
	(segment
		(start 124.483368 -143.6878)
		(end 124.547376 -143.751808)
		(width 0.14224)
		(layer "In4.Cu")
		(net "M_M_DQ<44>")
	)
	(segment
		(start 123.50115 -149.079966)
		(end 124.049536 -149.628352)
		(width 0.14224)
		(layer "In4.Cu")
		(net "M_M_DQ<44>")
	)
	(segment
		(start 113.979452 -99.291394)
		(end 113.984278 -99.299522)
		(width 0.0889)
		(layer "In4.Cu")
		(net "M_M_DQ<44>")
	)
	(segment
		(start 124.483368 -136.665208)
		(end 124.483368 -138.9126)
		(width 0.14224)
		(layer "In4.Cu")
		(net "M_M_DQ<44>")
	)
	(segment
		(start 124.572776 -136.205468)
		(end 124.572776 -136.5758)
		(width 0.14224)
		(layer "In4.Cu")
		(net "M_M_DQ<44>")
	)
	(segment
		(start 124.318776 -140.781278)
		(end 124.635768 -141.09827)
		(width 0.14224)
		(layer "In4.Cu")
		(net "M_M_DQ<44>")
	)
	(segment
		(start 124.572776 -136.5758)
		(end 124.483368 -136.665208)
		(width 0.14224)
		(layer "In4.Cu")
		(net "M_M_DQ<44>")
	)
	(segment
		(start 113.979452 -105.234486)
		(end 113.984278 -105.243122)
		(width 0.0889)
		(layer "In4.Cu")
		(net "M_M_DQ<44>")
	)
	(segment
		(start 113.973102 -101.261418)
		(end 113.979452 -101.272086)
		(width 0.0889)
		(layer "In4.Cu")
		(net "M_M_DQ<44>")
	)
	(segment
		(start 124.547376 -129.400808)
		(end 124.547376 -129.767838)
		(width 0.14224)
		(layer "In4.Cu")
		(net "M_M_DQ<44>")
	)
	(segment
		(start 124.588778 -145.83537)
		(end 124.588778 -146.122898)
		(width 0.14224)
		(layer "In4.Cu")
		(net "M_M_DQ<44>")
	)
	(segment
		(start 113.979452 -103.253286)
		(end 113.984278 -103.261922)
		(width 0.0889)
		(layer "In4.Cu")
		(net "M_M_DQ<44>")
	)
	(segment
		(start 124.635768 -131.470654)
		(end 124.635768 -131.940808)
		(width 0.14224)
		(layer "In4.Cu")
		(net "M_M_DQ<44>")
	)
	(segment
		(start 114.079528 -114.460274)
		(end 123.686062 -124.066808)
		(width 0.14224)
		(layer "In4.Cu")
		(net "M_M_DQ<44>")
	)
	(segment
		(start 124.711968 -127.812292)
		(end 124.915168 -128.015492)
		(width 0.14224)
		(layer "In4.Cu")
		(net "M_M_DQ<44>")
	)
	(segment
		(start 124.049536 -149.628352)
		(end 124.049536 -150.814278)
		(width 0.14224)
		(layer "In4.Cu")
		(net "M_M_DQ<44>")
	)
	(segment
		(start 124.330968 -129.1844)
		(end 124.547376 -129.400808)
		(width 0.14224)
		(layer "In4.Cu")
		(net "M_M_DQ<44>")
	)
	(segment
		(start 124.330968 -127.609092)
		(end 124.534168 -127.812292)
		(width 0.14224)
		(layer "In4.Cu")
		(net "M_M_DQ<44>")
	)
	(segment
		(start 124.547376 -144.081246)
		(end 124.127768 -144.500854)
		(width 0.14224)
		(layer "In4.Cu")
		(net "M_M_DQ<44>")
	)
	(segment
		(start 124.483368 -138.9126)
		(end 124.572776 -139.002008)
		(width 0.14224)
		(layer "In4.Cu")
		(net "M_M_DQ<44>")
	)
	(segment
		(start 113.973102 -105.223818)
		(end 113.979452 -105.234486)
		(width 0.0889)
		(layer "In4.Cu")
		(net "M_M_DQ<44>")
	)
	(segment
		(start 113.973102 -100.270818)
		(end 113.979452 -100.281486)
		(width 0.0889)
		(layer "In4.Cu")
		(net "M_M_DQ<44>")
	)
	(segment
		(start 124.711968 -128.625092)
		(end 124.534168 -128.625092)
		(width 0.14224)
		(layer "In4.Cu")
		(net "M_M_DQ<44>")
	)
	(segment
		(start 124.349764 -125.647196)
		(end 124.547376 -125.844808)
		(width 0.14224)
		(layer "In4.Cu")
		(net "M_M_DQ<44>")
	)
	(segment
		(start 124.572776 -139.002008)
		(end 124.572776 -139.333478)
		(width 0.14224)
		(layer "In4.Cu")
		(net "M_M_DQ<44>")
	)
	(segment
		(start 124.318776 -139.587478)
		(end 124.318776 -140.781278)
		(width 0.14224)
		(layer "In4.Cu")
		(net "M_M_DQ<44>")
	)
	(segment
		(start 113.973102 -104.233218)
		(end 113.979452 -104.243886)
		(width 0.0889)
		(layer "In4.Cu")
		(net "M_M_DQ<44>")
	)
	(segment
		(start 124.318776 -135.951468)
		(end 124.572776 -136.205468)
		(width 0.14224)
		(layer "In4.Cu")
		(net "M_M_DQ<44>")
	)
	(segment
		(start 124.547376 -134.125208)
		(end 124.547376 -134.479792)
		(width 0.14224)
		(layer "In4.Cu")
		(net "M_M_DQ<44>")
	)
	(segment
		(start 124.349764 -124.371608)
		(end 124.349764 -125.647196)
		(width 0.14224)
		(layer "In4.Cu")
		(net "M_M_DQ<44>")
	)
	(segment
		(start 124.127768 -145.37436)
		(end 124.588778 -145.83537)
		(width 0.14224)
		(layer "In4.Cu")
		(net "M_M_DQ<44>")
	)
	(segment
		(start 124.915168 -128.421892)
		(end 124.711968 -128.625092)
		(width 0.14224)
		(layer "In4.Cu")
		(net "M_M_DQ<44>")
	)
	(segment
		(start 114.079528 -107.219496)
		(end 114.079528 -114.460274)
		(width 0.14224)
		(layer "In4.Cu")
		(net "M_M_DQ<44>")
	)
	(segment
		(start 124.534168 -127.812292)
		(end 124.711968 -127.812292)
		(width 0.14224)
		(layer "In4.Cu")
		(net "M_M_DQ<44>")
	)
	(segment
		(start 124.635768 -131.940808)
		(end 124.483368 -132.093208)
		(width 0.14224)
		(layer "In4.Cu")
		(net "M_M_DQ<44>")
	)
	(segment
		(start 124.547376 -127)
		(end 124.330968 -127.216408)
		(width 0.14224)
		(layer "In4.Cu")
		(net "M_M_DQ<44>")
	)
	(segment
		(start 124.044964 -124.066808)
		(end 124.349764 -124.371608)
		(width 0.14224)
		(layer "In4.Cu")
		(net "M_M_DQ<44>")
	)
	(segment
		(start 124.127768 -144.500854)
		(end 124.127768 -145.37436)
		(width 0.14224)
		(layer "In4.Cu")
		(net "M_M_DQ<44>")
	)
	(segment
		(start 124.318776 -129.996438)
		(end 124.318776 -131.153662)
		(width 0.14224)
		(layer "In4.Cu")
		(net "M_M_DQ<44>")
	)
	(segment
		(start 114.286792 -106.461814)
		(end 114.286792 -107.012232)
		(width 0.0889)
		(layer "In4.Cu")
		(net "M_M_DQ<44>")
	)
	(segment
		(start 124.547376 -125.844808)
		(end 124.547376 -127)
		(width 0.14224)
		(layer "In4.Cu")
		(net "M_M_DQ<44>")
	)
	(segment
		(start 113.900458 -106.07548)
		(end 114.286792 -106.461814)
		(width 0.0889)
		(layer "In4.Cu")
		(net "M_M_DQ<44>")
	)
	(segment
		(start 124.547376 -129.767838)
		(end 124.318776 -129.996438)
		(width 0.14224)
		(layer "In4.Cu")
		(net "M_M_DQ<44>")
	)
	(segment
		(start 113.979452 -101.272086)
		(end 113.984278 -101.280722)
		(width 0.0889)
		(layer "In4.Cu")
		(net "M_M_DQ<44>")
	)
	(segment
		(start 124.330968 -127.216408)
		(end 124.330968 -127.609092)
		(width 0.14224)
		(layer "In4.Cu")
		(net "M_M_DQ<44>")
	)
	(segment
		(start 113.979452 -102.262686)
		(end 113.984278 -102.271322)
		(width 0.0889)
		(layer "In4.Cu")
		(net "M_M_DQ<44>")
	)
	(segment
		(start 124.318776 -134.708392)
		(end 124.318776 -135.951468)
		(width 0.14224)
		(layer "In4.Cu")
		(net "M_M_DQ<44>")
	)
	(segment
		(start 124.547376 -134.479792)
		(end 124.318776 -134.708392)
		(width 0.14224)
		(layer "In4.Cu")
		(net "M_M_DQ<44>")
	)
	(segment
		(start 114.286792 -107.012232)
		(end 114.079528 -107.219496)
		(width 0.0889)
		(layer "In4.Cu")
		(net "M_M_DQ<44>")
	)
	(segment
		(start 124.588778 -146.122898)
		(end 123.50115 -147.210526)
		(width 0.14224)
		(layer "In4.Cu")
		(net "M_M_DQ<44>")
	)
	(segment
		(start 113.900458 -105.929938)
		(end 113.900458 -106.07548)
		(width 0.0889)
		(layer "In4.Cu")
		(net "M_M_DQ<44>")
	)
	(segment
		(start 124.547376 -143.751808)
		(end 124.547376 -144.081246)
		(width 0.14224)
		(layer "In4.Cu")
		(net "M_M_DQ<44>")
	)
	(segment
		(start 124.635768 -141.09827)
		(end 124.635768 -141.5288)
		(width 0.14224)
		(layer "In4.Cu")
		(net "M_M_DQ<44>")
	)
	(segment
		(start 114.491262 -94.042738)
		(end 114.09172 -94.597982)
		(width 0.0889)
		(layer "In4.Cu")
		(net "M_M_DQ<44>")
	)
	(segment
		(start 124.915168 -128.015492)
		(end 124.915168 -128.421892)
		(width 0.14224)
		(layer "In4.Cu")
		(net "M_M_DQ<44>")
	)
	(segment
		(start 113.973102 -102.252018)
		(end 113.979452 -102.262686)
		(width 0.0889)
		(layer "In4.Cu")
		(net "M_M_DQ<44>")
	)
	(segment
		(start 124.534168 -128.625092)
		(end 124.330968 -128.828292)
		(width 0.14224)
		(layer "In4.Cu")
		(net "M_M_DQ<44>")
	)
	(segment
		(start 113.979452 -100.281486)
		(end 113.984278 -100.290122)
		(width 0.0889)
		(layer "In4.Cu")
		(net "M_M_DQ<44>")
	)
	(segment
		(start 124.330968 -128.828292)
		(end 124.330968 -129.1844)
		(width 0.14224)
		(layer "In4.Cu")
		(net "M_M_DQ<44>")
	)
	(segment
		(start 124.318776 -131.153662)
		(end 124.635768 -131.470654)
		(width 0.14224)
		(layer "In4.Cu")
		(net "M_M_DQ<44>")
	)
	(arc
		(start 113.984278 -102.271322)
		(mid 114.033033 -102.467674)
		(end 113.979452 -102.662736)
		(width 0.0889)
		(layer "In4.Cu")
		(net "M_M_DQ<44>")
	)
	(arc
		(start 113.979452 -97.70999)
		(mid 113.900321 -98.005392)
		(end 113.979452 -98.300794)
		(width 0.0889)
		(layer "In4.Cu")
		(net "M_M_DQ<44>")
	)
	(arc
		(start 114.09172 -94.597982)
		(mid 113.907034 -94.943772)
		(end 113.979452 -95.328994)
		(width 0.0889)
		(layer "In4.Cu")
		(net "M_M_DQ<44>")
	)
	(arc
		(start 113.979452 -95.72879)
		(mid 113.900321 -96.024192)
		(end 113.979452 -96.319594)
		(width 0.0889)
		(layer "In4.Cu")
		(net "M_M_DQ<44>")
	)
	(arc
		(start 113.979452 -98.300794)
		(mid 114.032951 -98.500692)
		(end 113.979452 -98.70059)
		(width 0.0889)
		(layer "In4.Cu")
		(net "M_M_DQ<44>")
	)
	(arc
		(start 113.984278 -100.290122)
		(mid 114.033033 -100.486474)
		(end 113.979452 -100.681536)
		(width 0.0889)
		(layer "In4.Cu")
		(net "M_M_DQ<44>")
	)
	(arc
		(start 113.979452 -96.319594)
		(mid 114.032951 -96.519492)
		(end 113.979452 -96.71939)
		(width 0.0889)
		(layer "In4.Cu")
		(net "M_M_DQ<44>")
	)
	(arc
		(start 113.979452 -96.71939)
		(mid 113.900321 -97.014792)
		(end 113.979452 -97.310194)
		(width 0.0889)
		(layer "In4.Cu")
		(net "M_M_DQ<44>")
	)
	(arc
		(start 113.979452 -104.643936)
		(mid 113.90023 -104.933054)
		(end 113.973102 -105.223818)
		(width 0.0889)
		(layer "In4.Cu")
		(net "M_M_DQ<44>")
	)
	(arc
		(start 113.984278 -105.243122)
		(mid 114.033033 -105.439474)
		(end 113.979452 -105.634536)
		(width 0.0889)
		(layer "In4.Cu")
		(net "M_M_DQ<44>")
	)
	(arc
		(start 113.979452 -99.690936)
		(mid 113.90023 -99.980054)
		(end 113.973102 -100.270818)
		(width 0.0889)
		(layer "In4.Cu")
		(net "M_M_DQ<44>")
	)
	(arc
		(start 113.979452 -105.634536)
		(mid 113.920507 -105.777037)
		(end 113.900458 -105.929938)
		(width 0.0889)
		(layer "In4.Cu")
		(net "M_M_DQ<44>")
	)
	(arc
		(start 113.984278 -103.261922)
		(mid 114.033033 -103.458274)
		(end 113.979452 -103.653336)
		(width 0.0889)
		(layer "In4.Cu")
		(net "M_M_DQ<44>")
	)
	(arc
		(start 113.984278 -101.280722)
		(mid 114.033033 -101.477074)
		(end 113.979452 -101.672136)
		(width 0.0889)
		(layer "In4.Cu")
		(net "M_M_DQ<44>")
	)
	(arc
		(start 113.979452 -103.653336)
		(mid 113.90023 -103.942454)
		(end 113.973102 -104.233218)
		(width 0.0889)
		(layer "In4.Cu")
		(net "M_M_DQ<44>")
	)
	(arc
		(start 113.979452 -97.310194)
		(mid 114.032951 -97.510092)
		(end 113.979452 -97.70999)
		(width 0.0889)
		(layer "In4.Cu")
		(net "M_M_DQ<44>")
	)
	(arc
		(start 113.979452 -95.328994)
		(mid 114.032951 -95.528892)
		(end 113.979452 -95.72879)
		(width 0.0889)
		(layer "In4.Cu")
		(net "M_M_DQ<44>")
	)
	(arc
		(start 113.984278 -104.252522)
		(mid 114.033033 -104.448874)
		(end 113.979452 -104.643936)
		(width 0.0889)
		(layer "In4.Cu")
		(net "M_M_DQ<44>")
	)
	(arc
		(start 113.979452 -101.672136)
		(mid 113.90023 -101.961254)
		(end 113.973102 -102.252018)
		(width 0.0889)
		(layer "In4.Cu")
		(net "M_M_DQ<44>")
	)
	(arc
		(start 113.979452 -102.662736)
		(mid 113.90023 -102.951854)
		(end 113.973102 -103.242618)
		(width 0.0889)
		(layer "In4.Cu")
		(net "M_M_DQ<44>")
	)
	(arc
		(start 113.979452 -98.70059)
		(mid 113.900321 -98.995992)
		(end 113.979452 -99.291394)
		(width 0.0889)
		(layer "In4.Cu")
		(net "M_M_DQ<44>")
	)
	(arc
		(start 113.984278 -99.299522)
		(mid 114.033033 -99.495874)
		(end 113.979452 -99.690936)
		(width 0.0889)
		(layer "In4.Cu")
		(net "M_M_DQ<44>")
	)
	(arc
		(start 113.979452 -100.681536)
		(mid 113.90023 -100.970654)
		(end 113.973102 -101.261418)
		(width 0.0889)
		(layer "In4.Cu")
		(net "M_M_DQ<44>")
	)
	(segment
		(start 123.774454 -154.24023)
		(end 123.774454 -153.938478)
		(width 0.14224)
		(layer "In11.Cu")
		(net "M_M_DQ<44>")
	)
	(segment
		(start 123.774454 -153.938478)
		(end 123.616466 -153.78049)
		(width 0.14224)
		(layer "In11.Cu")
		(net "M_M_DQ<44>")
	)
	(segment
		(start 123.616466 -151.247348)
		(end 124.049536 -150.814278)
		(width 0.14224)
		(layer "In11.Cu")
		(net "M_M_DQ<44>")
	)
	(segment
		(start 123.616466 -153.78049)
		(end 123.616466 -151.247348)
		(width 0.14224)
		(layer "In11.Cu")
		(net "M_M_DQ<44>")
	)
	(segment
		(start 124.897896 -155.363672)
		(end 123.774454 -154.24023)
		(width 0.14224)
		(layer "In11.Cu")
		(net "M_M_DQ<44>")
	)
	(segment
		(start 131.699508 -152.273)
		(end 131.699508 -153.542746)
		(width 0.1651)
		(layer "F.Cu")
		(net "M_M_DQ<43>")
	)
	(segment
		(start 117.353842 -95.033084)
		(end 117.925342 -95.033084)
		(width 0.1651)
		(layer "F.Cu")
		(net "M_M_DQ<43>")
	)
	(via
		(at 132.549392 -149.533356)
		(size 0.508)
		(drill 0.254)
		(layers "F.Cu" "B.Cu")
		(net "M_M_DQ<43>")
	)
	(via
		(at 131.699508 -153.542746)
		(size 0.508)
		(drill 0.254)
		(layers "F.Cu" "B.Cu")
		(net "M_M_DQ<43>")
	)
	(via
		(at 117.925342 -95.033084)
		(size 0.508)
		(drill 0.254)
		(layers "F.Cu" "B.Cu")
		(net "M_M_DQ<43>")
	)
	(segment
		(start 132.549392 -147.478496)
		(end 132.549392 -149.533356)
		(width 0.1651)
		(layer "B.Cu")
		(net "M_M_DQ<43>")
	)
	(segment
		(start 132.916676 -131.9276)
		(end 132.966968 -131.977892)
		(width 0.14224)
		(layer "In4.Cu")
		(net "M_M_DQ<43>")
	)
	(segment
		(start 120.470168 -112.193832)
		(end 125.877574 -117.601238)
		(width 0.14224)
		(layer "In4.Cu")
		(net "M_M_DQ<43>")
	)
	(segment
		(start 130.570986 -120.705626)
		(end 130.789934 -120.705626)
		(width 0.14224)
		(layer "In4.Cu")
		(net "M_M_DQ<43>")
	)
	(segment
		(start 133.081776 -136.003792)
		(end 132.903976 -136.181592)
		(width 0.14224)
		(layer "In4.Cu")
		(net "M_M_DQ<43>")
	)
	(segment
		(start 132.903976 -138.924792)
		(end 132.903976 -139.562078)
		(width 0.14224)
		(layer "In4.Cu")
		(net "M_M_DQ<43>")
	)
	(segment
		(start 119.295672 -105.139236)
		(end 119.302022 -105.149904)
		(width 0.0889)
		(layer "In4.Cu")
		(net "M_M_DQ<43>")
	)
	(segment
		(start 127.466598 -117.601238)
		(end 130.570986 -120.705626)
		(width 0.14224)
		(layer "In4.Cu")
		(net "M_M_DQ<43>")
	)
	(segment
		(start 132.903976 -136.525)
		(end 132.966968 -136.587992)
		(width 0.14224)
		(layer "In4.Cu")
		(net "M_M_DQ<43>")
	)
	(segment
		(start 132.916676 -134.111492)
		(end 132.916676 -134.520432)
		(width 0.14224)
		(layer "In4.Cu")
		(net "M_M_DQ<43>")
	)
	(segment
		(start 120.470168 -107.234736)
		(end 120.470168 -112.193832)
		(width 0.14224)
		(layer "In4.Cu")
		(net "M_M_DQ<43>")
	)
	(segment
		(start 132.903976 -129.960878)
		(end 133.056376 -130.113278)
		(width 0.14224)
		(layer "In4.Cu")
		(net "M_M_DQ<43>")
	)
	(segment
		(start 133.132576 -145.604992)
		(end 132.878576 -145.858992)
		(width 0.14224)
		(layer "In4.Cu")
		(net "M_M_DQ<43>")
	)
	(segment
		(start 119.290846 -106.1212)
		(end 119.295672 -106.129836)
		(width 0.0889)
		(layer "In4.Cu")
		(net "M_M_DQ<43>")
	)
	(segment
		(start 133.056376 -131.268978)
		(end 132.916676 -131.408678)
		(width 0.14224)
		(layer "In4.Cu")
		(net "M_M_DQ<43>")
	)
	(segment
		(start 132.012436 -123.04268)
		(end 132.192268 -123.04268)
		(width 0.14224)
		(layer "In4.Cu")
		(net "M_M_DQ<43>")
	)
	(segment
		(start 118.432326 -101.663246)
		(end 118.437152 -101.671882)
		(width 0.0889)
		(layer "In4.Cu")
		(net "M_M_DQ<43>")
	)
	(segment
		(start 132.903976 -139.562078)
		(end 133.017768 -139.67587)
		(width 0.1016)
		(layer "In4.Cu")
		(net "M_M_DQ<43>")
	)
	(segment
		(start 132.549392 -149.546564)
		(end 132.549392 -149.533356)
		(width 0.14224)
		(layer "In4.Cu")
		(net "M_M_DQ<43>")
	)
	(segment
		(start 119.631206 -106.329988)
		(end 119.663972 -106.329988)
		(width 0.0889)
		(layer "In4.Cu")
		(net "M_M_DQ<43>")
	)
	(segment
		(start 131.258818 -121.393458)
		(end 131.971796 -122.106436)
		(width 0.14224)
		(layer "In4.Cu")
		(net "M_M_DQ<43>")
	)
	(segment
		(start 131.404868 -121.02846)
		(end 131.258818 -121.17451)
		(width 0.14224)
		(layer "In4.Cu")
		(net "M_M_DQ<43>")
	)
	(segment
		(start 133.056376 -130.113278)
		(end 133.056376 -131.268978)
		(width 0.14224)
		(layer "In4.Cu")
		(net "M_M_DQ<43>")
	)
	(segment
		(start 133.081776 -134.685532)
		(end 133.081776 -136.003792)
		(width 0.14224)
		(layer "In4.Cu")
		(net "M_M_DQ<43>")
	)
	(segment
		(start 132.192268 -123.04268)
		(end 132.396738 -122.83821)
		(width 0.14224)
		(layer "In4.Cu")
		(net "M_M_DQ<43>")
	)
	(segment
		(start 118.768876 -103.853234)
		(end 118.801642 -103.853234)
		(width 0.0889)
		(layer "In4.Cu")
		(net "M_M_DQ<43>")
	)
	(segment
		(start 132.966968 -134.0612)
		(end 132.916676 -134.111492)
		(width 0.14224)
		(layer "In4.Cu")
		(net "M_M_DQ<43>")
	)
	(segment
		(start 120.454928 -107.219496)
		(end 120.470168 -107.234736)
		(width 0.14224)
		(layer "In4.Cu")
		(net "M_M_DQ<43>")
	)
	(segment
		(start 125.877574 -117.601238)
		(end 127.466598 -117.601238)
		(width 0.14224)
		(layer "In4.Cu")
		(net "M_M_DQ<43>")
	)
	(segment
		(start 132.943092 -123.148598)
		(end 132.943092 -124.839476)
		(width 0.14224)
		(layer "In4.Cu")
		(net "M_M_DQ<43>")
	)
	(segment
		(start 118.430294 -100.668836)
		(end 118.446042 -100.696268)
		(width 0.0889)
		(layer "In4.Cu")
		(net "M_M_DQ<43>")
	)
	(segment
		(start 118.437152 -101.671882)
		(end 118.443502 -101.68255)
		(width 0.0889)
		(layer "In4.Cu")
		(net "M_M_DQ<43>")
	)
	(segment
		(start 119.290846 -105.1306)
		(end 119.295672 -105.139236)
		(width 0.0889)
		(layer "In4.Cu")
		(net "M_M_DQ<43>")
	)
	(segment
		(start 119.295672 -104.148636)
		(end 119.302022 -104.159304)
		(width 0.0889)
		(layer "In4.Cu")
		(net "M_M_DQ<43>")
	)
	(segment
		(start 133.017768 -140.908786)
		(end 132.789168 -141.137386)
		(width 0.1016)
		(layer "In4.Cu")
		(net "M_M_DQ<43>")
	)
	(segment
		(start 131.115816 -120.559576)
		(end 131.404868 -120.848628)
		(width 0.14224)
		(layer "In4.Cu")
		(net "M_M_DQ<43>")
	)
	(segment
		(start 132.632704 -122.83821)
		(end 132.943092 -123.148598)
		(width 0.14224)
		(layer "In4.Cu")
		(net "M_M_DQ<43>")
	)
	(segment
		(start 132.789168 -144.05483)
		(end 133.132576 -144.398238)
		(width 0.14224)
		(layer "In4.Cu")
		(net "M_M_DQ<43>")
	)
	(segment
		(start 130.789934 -120.705626)
		(end 130.935984 -120.559576)
		(width 0.14224)
		(layer "In4.Cu")
		(net "M_M_DQ<43>")
	)
	(segment
		(start 132.916676 -134.520432)
		(end 133.081776 -134.685532)
		(width 0.14224)
		(layer "In4.Cu")
		(net "M_M_DQ<43>")
	)
	(segment
		(start 132.789168 -124.9934)
		(end 132.789168 -127.723392)
		(width 0.14224)
		(layer "In4.Cu")
		(net "M_M_DQ<43>")
	)
	(segment
		(start 130.935984 -120.559576)
		(end 131.115816 -120.559576)
		(width 0.14224)
		(layer "In4.Cu")
		(net "M_M_DQ<43>")
	)
	(segment
		(start 131.723384 -122.753628)
		(end 132.012436 -123.04268)
		(width 0.14224)
		(layer "In4.Cu")
		(net "M_M_DQ<43>")
	)
	(segment
		(start 133.132576 -144.398238)
		(end 133.132576 -145.604992)
		(width 0.14224)
		(layer "In4.Cu")
		(net "M_M_DQ<43>")
	)
	(segment
		(start 132.966968 -131.977892)
		(end 132.966968 -134.0612)
		(width 0.14224)
		(layer "In4.Cu")
		(net "M_M_DQ<43>")
	)
	(segment
		(start 132.966968 -136.587992)
		(end 132.966968 -138.8618)
		(width 0.14224)
		(layer "In4.Cu")
		(net "M_M_DQ<43>")
	)
	(segment
		(start 132.878576 -149.21738)
		(end 132.549392 -149.546564)
		(width 0.14224)
		(layer "In4.Cu")
		(net "M_M_DQ<43>")
	)
	(segment
		(start 120.154192 -106.625136)
		(end 120.232932 -106.76128)
		(width 0.0889)
		(layer "In4.Cu")
		(net "M_M_DQ<43>")
	)
	(segment
		(start 132.396738 -122.83821)
		(end 132.632704 -122.83821)
		(width 0.14224)
		(layer "In4.Cu")
		(net "M_M_DQ<43>")
	)
	(segment
		(start 131.971796 -122.106436)
		(end 131.971796 -122.325384)
		(width 0.14224)
		(layer "In4.Cu")
		(net "M_M_DQ<43>")
	)
	(segment
		(start 132.903976 -127.8382)
		(end 132.903976 -129.960878)
		(width 0.14224)
		(layer "In4.Cu")
		(net "M_M_DQ<43>")
	)
	(segment
		(start 118.443502 -103.242618)
		(end 118.437152 -103.253286)
		(width 0.0889)
		(layer "In4.Cu")
		(net "M_M_DQ<43>")
	)
	(segment
		(start 131.258818 -121.17451)
		(end 131.258818 -121.393458)
		(width 0.14224)
		(layer "In4.Cu")
		(net "M_M_DQ<43>")
	)
	(segment
		(start 132.943092 -124.839476)
		(end 132.789168 -124.9934)
		(width 0.14224)
		(layer "In4.Cu")
		(net "M_M_DQ<43>")
	)
	(segment
		(start 132.789168 -141.137386)
		(end 132.789168 -144.05483)
		(width 0.14224)
		(layer "In4.Cu")
		(net "M_M_DQ<43>")
	)
	(segment
		(start 120.232932 -106.9975)
		(end 120.454928 -107.219496)
		(width 0.0889)
		(layer "In4.Cu")
		(net "M_M_DQ<43>")
	)
	(segment
		(start 132.878576 -145.858992)
		(end 132.878576 -149.21738)
		(width 0.14224)
		(layer "In4.Cu")
		(net "M_M_DQ<43>")
	)
	(segment
		(start 131.404868 -120.848628)
		(end 131.404868 -121.02846)
		(width 0.14224)
		(layer "In4.Cu")
		(net "M_M_DQ<43>")
	)
	(segment
		(start 131.971796 -122.325384)
		(end 131.723384 -122.573796)
		(width 0.14224)
		(layer "In4.Cu")
		(net "M_M_DQ<43>")
	)
	(segment
		(start 118.437152 -103.253286)
		(end 118.432326 -103.261922)
		(width 0.0889)
		(layer "In4.Cu")
		(net "M_M_DQ<43>")
	)
	(segment
		(start 132.789168 -127.723392)
		(end 132.903976 -127.8382)
		(width 0.14224)
		(layer "In4.Cu")
		(net "M_M_DQ<43>")
	)
	(segment
		(start 120.232932 -106.76128)
		(end 120.232932 -106.9975)
		(width 0.0889)
		(layer "In4.Cu")
		(net "M_M_DQ<43>")
	)
	(segment
		(start 132.966968 -138.8618)
		(end 132.903976 -138.924792)
		(width 0.14224)
		(layer "In4.Cu")
		(net "M_M_DQ<43>")
	)
	(segment
		(start 132.916676 -131.408678)
		(end 132.916676 -131.9276)
		(width 0.14224)
		(layer "In4.Cu")
		(net "M_M_DQ<43>")
	)
	(segment
		(start 131.723384 -122.573796)
		(end 131.723384 -122.753628)
		(width 0.14224)
		(layer "In4.Cu")
		(net "M_M_DQ<43>")
	)
	(segment
		(start 133.017768 -139.67587)
		(end 133.017768 -140.908786)
		(width 0.1016)
		(layer "In4.Cu")
		(net "M_M_DQ<43>")
	)
	(segment
		(start 132.903976 -136.181592)
		(end 132.903976 -136.525)
		(width 0.14224)
		(layer "In4.Cu")
		(net "M_M_DQ<43>")
	)
	(arc
		(start 118.437152 -96.71939)
		(mid 118.516283 -97.014792)
		(end 118.437152 -97.310194)
		(width 0.0889)
		(layer "In4.Cu")
		(net "M_M_DQ<43>")
	)
	(arc
		(start 118.437152 -102.662736)
		(mid 118.516374 -102.951854)
		(end 118.443502 -103.242618)
		(width 0.0889)
		(layer "In4.Cu")
		(net "M_M_DQ<43>")
	)
	(arc
		(start 119.302022 -105.149904)
		(mid 119.37482 -105.440667)
		(end 119.295672 -105.729786)
		(width 0.0889)
		(layer "In4.Cu")
		(net "M_M_DQ<43>")
	)
	(arc
		(start 118.801642 -103.853234)
		(mid 119.087066 -103.936701)
		(end 119.295672 -104.148636)
		(width 0.0889)
		(layer "In4.Cu")
		(net "M_M_DQ<43>")
	)
	(arc
		(start 118.437152 -101.271832)
		(mid 118.383682 -101.466895)
		(end 118.432326 -101.663246)
		(width 0.0889)
		(layer "In4.Cu")
		(net "M_M_DQ<43>")
	)
	(arc
		(start 117.925342 -95.033084)
		(mid 118.200534 -95.366748)
		(end 118.437152 -95.72879)
		(width 0.0889)
		(layer "In4.Cu")
		(net "M_M_DQ<43>")
	)
	(arc
		(start 118.443502 -101.68255)
		(mid 118.5163 -101.973313)
		(end 118.437152 -102.262432)
		(width 0.0889)
		(layer "In4.Cu")
		(net "M_M_DQ<43>")
	)
	(arc
		(start 118.437152 -95.72879)
		(mid 118.516283 -96.024192)
		(end 118.437152 -96.319594)
		(width 0.0889)
		(layer "In4.Cu")
		(net "M_M_DQ<43>")
	)
	(arc
		(start 118.437152 -102.262432)
		(mid 118.383526 -102.462584)
		(end 118.437152 -102.662736)
		(width 0.0889)
		(layer "In4.Cu")
		(net "M_M_DQ<43>")
	)
	(arc
		(start 119.295672 -104.739186)
		(mid 119.242202 -104.934249)
		(end 119.290846 -105.1306)
		(width 0.0889)
		(layer "In4.Cu")
		(net "M_M_DQ<43>")
	)
	(arc
		(start 118.437152 -98.70059)
		(mid 118.516283 -98.995992)
		(end 118.437152 -99.291394)
		(width 0.0889)
		(layer "In4.Cu")
		(net "M_M_DQ<43>")
	)
	(arc
		(start 118.437152 -99.291394)
		(mid 118.383653 -99.491292)
		(end 118.437152 -99.69119)
		(width 0.0889)
		(layer "In4.Cu")
		(net "M_M_DQ<43>")
	)
	(arc
		(start 118.443502 -99.70135)
		(mid 118.5163 -99.992113)
		(end 118.437152 -100.281232)
		(width 0.0889)
		(layer "In4.Cu")
		(net "M_M_DQ<43>")
	)
	(arc
		(start 119.295672 -106.129836)
		(mid 119.437355 -106.27364)
		(end 119.631206 -106.329988)
		(width 0.0889)
		(layer "In4.Cu")
		(net "M_M_DQ<43>")
	)
	(arc
		(start 118.437152 -100.281232)
		(mid 118.383714 -100.474137)
		(end 118.430294 -100.668836)
		(width 0.0889)
		(layer "In4.Cu")
		(net "M_M_DQ<43>")
	)
	(arc
		(start 118.437152 -98.300794)
		(mid 118.383653 -98.500692)
		(end 118.437152 -98.70059)
		(width 0.0889)
		(layer "In4.Cu")
		(net "M_M_DQ<43>")
	)
	(arc
		(start 119.295672 -105.729786)
		(mid 119.24099 -105.924848)
		(end 119.290846 -106.1212)
		(width 0.0889)
		(layer "In4.Cu")
		(net "M_M_DQ<43>")
	)
	(arc
		(start 119.663972 -106.329988)
		(mid 119.947189 -106.414269)
		(end 120.154192 -106.625136)
		(width 0.0889)
		(layer "In4.Cu")
		(net "M_M_DQ<43>")
	)
	(arc
		(start 118.437152 -97.70999)
		(mid 118.516283 -98.005392)
		(end 118.437152 -98.300794)
		(width 0.0889)
		(layer "In4.Cu")
		(net "M_M_DQ<43>")
	)
	(arc
		(start 119.302022 -104.159304)
		(mid 119.37482 -104.450067)
		(end 119.295672 -104.739186)
		(width 0.0889)
		(layer "In4.Cu")
		(net "M_M_DQ<43>")
	)
	(arc
		(start 118.437152 -96.319594)
		(mid 118.383653 -96.519492)
		(end 118.437152 -96.71939)
		(width 0.0889)
		(layer "In4.Cu")
		(net "M_M_DQ<43>")
	)
	(arc
		(start 118.437152 -99.69119)
		(mid 118.440237 -99.696326)
		(end 118.443502 -99.70135)
		(width 0.0889)
		(layer "In4.Cu")
		(net "M_M_DQ<43>")
	)
	(arc
		(start 118.437152 -103.653336)
		(mid 118.577231 -103.796072)
		(end 118.768876 -103.853234)
		(width 0.0889)
		(layer "In4.Cu")
		(net "M_M_DQ<43>")
	)
	(arc
		(start 118.432326 -103.261922)
		(mid 118.383571 -103.458274)
		(end 118.437152 -103.653336)
		(width 0.0889)
		(layer "In4.Cu")
		(net "M_M_DQ<43>")
	)
	(arc
		(start 118.437152 -97.310194)
		(mid 118.383653 -97.510092)
		(end 118.437152 -97.70999)
		(width 0.0889)
		(layer "In4.Cu")
		(net "M_M_DQ<43>")
	)
	(arc
		(start 118.446042 -100.696268)
		(mid 118.516439 -100.985219)
		(end 118.437152 -101.271832)
		(width 0.0889)
		(layer "In4.Cu")
		(net "M_M_DQ<43>")
	)
	(segment
		(start 131.860798 -152.752552)
		(end 131.860798 -152.479248)
		(width 0.14224)
		(layer "In11.Cu")
		(net "M_M_DQ<43>")
	)
	(segment
		(start 132.143246 -150.435818)
		(end 132.098796 -150.391368)
		(width 0.14224)
		(layer "In11.Cu")
		(net "M_M_DQ<43>")
	)
	(segment
		(start 131.860798 -151.387048)
		(end 132.143246 -151.1046)
		(width 0.14224)
		(layer "In11.Cu")
		(net "M_M_DQ<43>")
	)
	(segment
		(start 132.149596 -153.364946)
		(end 132.149596 -153.04135)
		(width 0.14224)
		(layer "In11.Cu")
		(net "M_M_DQ<43>")
	)
	(segment
		(start 132.098796 -149.9616)
		(end 132.52704 -149.533356)
		(width 0.14224)
		(layer "In11.Cu")
		(net "M_M_DQ<43>")
	)
	(segment
		(start 131.860798 -151.660352)
		(end 131.860798 -151.387048)
		(width 0.14224)
		(layer "In11.Cu")
		(net "M_M_DQ<43>")
	)
	(segment
		(start 131.699508 -153.542746)
		(end 131.971796 -153.542746)
		(width 0.14224)
		(layer "In11.Cu")
		(net "M_M_DQ<43>")
	)
	(segment
		(start 131.860798 -152.479248)
		(end 132.117846 -152.2222)
		(width 0.14224)
		(layer "In11.Cu")
		(net "M_M_DQ<43>")
	)
	(segment
		(start 132.098796 -150.391368)
		(end 132.098796 -149.9616)
		(width 0.14224)
		(layer "In11.Cu")
		(net "M_M_DQ<43>")
	)
	(segment
		(start 132.143246 -151.1046)
		(end 132.143246 -150.435818)
		(width 0.14224)
		(layer "In11.Cu")
		(net "M_M_DQ<43>")
	)
	(segment
		(start 132.117846 -152.2222)
		(end 132.117846 -151.9174)
		(width 0.14224)
		(layer "In11.Cu")
		(net "M_M_DQ<43>")
	)
	(segment
		(start 132.149596 -153.04135)
		(end 131.860798 -152.752552)
		(width 0.14224)
		(layer "In11.Cu")
		(net "M_M_DQ<43>")
	)
	(segment
		(start 131.971796 -153.542746)
		(end 132.149596 -153.364946)
		(width 0.14224)
		(layer "In11.Cu")
		(net "M_M_DQ<43>")
	)
	(segment
		(start 132.52704 -149.533356)
		(end 132.549392 -149.533356)
		(width 0.14224)
		(layer "In11.Cu")
		(net "M_M_DQ<43>")
	)
	(segment
		(start 132.117846 -151.9174)
		(end 131.860798 -151.660352)
		(width 0.14224)
		(layer "In11.Cu")
		(net "M_M_DQ<43>")
	)
	(segment
		(start 132.680964 -155.52674)
		(end 132.549392 -155.395168)
		(width 0.1651)
		(layer "F.Cu")
		(net "M_M_DQ<42>")
	)
	(segment
		(start 132.549392 -155.395168)
		(end 132.549392 -155.1178)
		(width 0.1651)
		(layer "F.Cu")
		(net "M_M_DQ<42>")
	)
	(segment
		(start 132.549392 -155.881832)
		(end 132.680964 -155.75026)
		(width 0.1651)
		(layer "F.Cu")
		(net "M_M_DQ<42>")
	)
	(segment
		(start 132.549392 -156.87294)
		(end 132.549392 -155.881832)
		(width 0.1651)
		(layer "F.Cu")
		(net "M_M_DQ<42>")
	)
	(segment
		(start 132.680964 -155.75026)
		(end 132.680964 -155.52674)
		(width 0.1651)
		(layer "F.Cu")
		(net "M_M_DQ<42>")
	)
	(segment
		(start 117.353842 -94.042738)
		(end 117.925342 -94.042738)
		(width 0.1651)
		(layer "F.Cu")
		(net "M_M_DQ<42>")
	)
	(via
		(at 117.925342 -94.042738)
		(size 0.508)
		(drill 0.254)
		(layers "F.Cu" "B.Cu")
		(net "M_M_DQ<42>")
	)
	(via
		(at 131.699508 -150.814278)
		(size 0.508)
		(drill 0.254)
		(layers "F.Cu" "B.Cu")
		(net "M_M_DQ<42>")
	)
	(via
		(at 132.549392 -155.1178)
		(size 0.508)
		(drill 0.254)
		(layers "F.Cu" "B.Cu")
		(net "M_M_DQ<42>")
	)
	(segment
		(start 131.699508 -152.078436)
		(end 131.699508 -150.814278)
		(width 0.1651)
		(layer "B.Cu")
		(net "M_M_DQ<42>")
	)
	(segment
		(start 132.192776 -136.284208)
		(end 132.192776 -136.5758)
		(width 0.14224)
		(layer "In4.Cu")
		(net "M_M_DQ<42>")
	)
	(segment
		(start 132.128768 -136.639808)
		(end 132.128768 -138.7856)
		(width 0.14224)
		(layer "In4.Cu")
		(net "M_M_DQ<42>")
	)
	(segment
		(start 132.065776 -140.933678)
		(end 132.268976 -141.136878)
		(width 0.14224)
		(layer "In4.Cu")
		(net "M_M_DQ<42>")
	)
	(segment
		(start 132.040376 -136.131808)
		(end 132.192776 -136.284208)
		(width 0.14224)
		(layer "In4.Cu")
		(net "M_M_DQ<42>")
	)
	(segment
		(start 119.124222 -106.214418)
		(end 119.130572 -106.225086)
		(width 0.0889)
		(layer "In4.Cu")
		(net "M_M_DQ<42>")
	)
	(segment
		(start 117.925342 -94.042738)
		(end 117.559582 -94.871286)
		(width 0.0889)
		(layer "In4.Cu")
		(net "M_M_DQ<42>")
	)
	(segment
		(start 119.819928 -112.365536)
		(end 125.641862 -118.18747)
		(width 0.14224)
		(layer "In4.Cu")
		(net "M_M_DQ<42>")
	)
	(segment
		(start 132.255768 -131.877308)
		(end 132.128768 -132.004308)
		(width 0.14224)
		(layer "In4.Cu")
		(net "M_M_DQ<42>")
	)
	(segment
		(start 118.272052 -101.767132)
		(end 118.276878 -101.775768)
		(width 0.0889)
		(layer "In4.Cu")
		(net "M_M_DQ<42>")
	)
	(segment
		(start 131.989576 -144.372838)
		(end 131.989576 -145.578068)
		(width 0.14224)
		(layer "In4.Cu")
		(net "M_M_DQ<42>")
	)
	(segment
		(start 132.192776 -139.435078)
		(end 132.065776 -139.562078)
		(width 0.14224)
		(layer "In4.Cu")
		(net "M_M_DQ<42>")
	)
	(segment
		(start 119.989092 -106.720386)
		(end 120.042432 -106.813096)
		(width 0.0889)
		(layer "In4.Cu")
		(net "M_M_DQ<42>")
	)
	(segment
		(start 118.272052 -100.776532)
		(end 118.27891 -100.788724)
		(width 0.0889)
		(layer "In4.Cu")
		(net "M_M_DQ<42>")
	)
	(segment
		(start 130.9497 -121.878852)
		(end 130.9497 -123.11126)
		(width 0.14224)
		(layer "In4.Cu")
		(net "M_M_DQ<42>")
	)
	(segment
		(start 132.001768 -125.7808)
		(end 132.001768 -126.257812)
		(width 0.14224)
		(layer "In4.Cu")
		(net "M_M_DQ<42>")
	)
	(segment
		(start 132.128768 -138.7856)
		(end 132.192776 -138.849608)
		(width 0.14224)
		(layer "In4.Cu")
		(net "M_M_DQ<42>")
	)
	(segment
		(start 131.699508 -149.491446)
		(end 131.699508 -150.814278)
		(width 0.14224)
		(layer "In4.Cu")
		(net "M_M_DQ<42>")
	)
	(segment
		(start 132.001768 -126.257812)
		(end 132.192776 -126.44882)
		(width 0.14224)
		(layer "In4.Cu")
		(net "M_M_DQ<42>")
	)
	(segment
		(start 132.192776 -129.833878)
		(end 132.065776 -129.960878)
		(width 0.14224)
		(layer "In4.Cu")
		(net "M_M_DQ<42>")
	)
	(segment
		(start 118.263162 -101.751892)
		(end 118.272052 -101.767132)
		(width 0.0889)
		(layer "In4.Cu")
		(net "M_M_DQ<42>")
	)
	(segment
		(start 119.819928 -107.219496)
		(end 119.819928 -112.365536)
		(width 0.14224)
		(layer "In4.Cu")
		(net "M_M_DQ<42>")
	)
	(segment
		(start 132.065776 -131.332478)
		(end 132.255768 -131.52247)
		(width 0.14224)
		(layer "In4.Cu")
		(net "M_M_DQ<42>")
	)
	(segment
		(start 132.218176 -145.806668)
		(end 132.218176 -148.972778)
		(width 0.14224)
		(layer "In4.Cu")
		(net "M_M_DQ<42>")
	)
	(segment
		(start 120.042432 -106.996992)
		(end 119.819928 -107.219496)
		(width 0.0889)
		(layer "In4.Cu")
		(net "M_M_DQ<42>")
	)
	(segment
		(start 119.124222 -105.223818)
		(end 119.130572 -105.234486)
		(width 0.0889)
		(layer "In4.Cu")
		(net "M_M_DQ<42>")
	)
	(segment
		(start 132.281676 -134.439152)
		(end 132.040376 -134.680452)
		(width 0.14224)
		(layer "In4.Cu")
		(net "M_M_DQ<42>")
	)
	(segment
		(start 125.641862 -118.18747)
		(end 127.258318 -118.18747)
		(width 0.14224)
		(layer "In4.Cu")
		(net "M_M_DQ<42>")
	)
	(segment
		(start 131.849368 -125.6284)
		(end 132.001768 -125.7808)
		(width 0.14224)
		(layer "In4.Cu")
		(net "M_M_DQ<42>")
	)
	(segment
		(start 132.192776 -126.44882)
		(end 132.192776 -129.833878)
		(width 0.14224)
		(layer "In4.Cu")
		(net "M_M_DQ<42>")
	)
	(segment
		(start 132.040376 -134.680452)
		(end 132.040376 -136.131808)
		(width 0.14224)
		(layer "In4.Cu")
		(net "M_M_DQ<42>")
	)
	(segment
		(start 119.130572 -104.243886)
		(end 119.135398 -104.252522)
		(width 0.0889)
		(layer "In4.Cu")
		(net "M_M_DQ<42>")
	)
	(segment
		(start 132.065776 -139.562078)
		(end 132.065776 -140.933678)
		(width 0.14224)
		(layer "In4.Cu")
		(net "M_M_DQ<42>")
	)
	(segment
		(start 132.255768 -131.52247)
		(end 132.255768 -131.877308)
		(width 0.14224)
		(layer "In4.Cu")
		(net "M_M_DQ<42>")
	)
	(segment
		(start 132.268976 -143.777208)
		(end 132.268976 -144.093438)
		(width 0.14224)
		(layer "In4.Cu")
		(net "M_M_DQ<42>")
	)
	(segment
		(start 118.276878 -103.1494)
		(end 118.272052 -103.158036)
		(width 0.0889)
		(layer "In4.Cu")
		(net "M_M_DQ<42>")
	)
	(segment
		(start 132.124958 -141.622018)
		(end 132.124958 -143.63319)
		(width 0.14224)
		(layer "In4.Cu")
		(net "M_M_DQ<42>")
	)
	(segment
		(start 132.268976 -144.093438)
		(end 131.989576 -144.372838)
		(width 0.14224)
		(layer "In4.Cu")
		(net "M_M_DQ<42>")
	)
	(segment
		(start 132.192776 -138.849608)
		(end 132.192776 -139.435078)
		(width 0.14224)
		(layer "In4.Cu")
		(net "M_M_DQ<42>")
	)
	(segment
		(start 118.272052 -103.158036)
		(end 118.265702 -103.168704)
		(width 0.0889)
		(layer "In4.Cu")
		(net "M_M_DQ<42>")
	)
	(segment
		(start 127.258318 -118.18747)
		(end 130.9497 -121.878852)
		(width 0.14224)
		(layer "In4.Cu")
		(net "M_M_DQ<42>")
	)
	(segment
		(start 120.042432 -106.813096)
		(end 120.042432 -106.996992)
		(width 0.0889)
		(layer "In4.Cu")
		(net "M_M_DQ<42>")
	)
	(segment
		(start 119.130572 -105.234486)
		(end 119.135398 -105.243122)
		(width 0.0889)
		(layer "In4.Cu")
		(net "M_M_DQ<42>")
	)
	(segment
		(start 132.192776 -136.5758)
		(end 132.128768 -136.639808)
		(width 0.14224)
		(layer "In4.Cu")
		(net "M_M_DQ<42>")
	)
	(segment
		(start 119.624602 -106.520488)
		(end 119.657368 -106.520488)
		(width 0.0889)
		(layer "In4.Cu")
		(net "M_M_DQ<42>")
	)
	(segment
		(start 131.989576 -145.578068)
		(end 132.218176 -145.806668)
		(width 0.14224)
		(layer "In4.Cu")
		(net "M_M_DQ<42>")
	)
	(segment
		(start 132.218176 -148.972778)
		(end 131.699508 -149.491446)
		(width 0.14224)
		(layer "In4.Cu")
		(net "M_M_DQ<42>")
	)
	(segment
		(start 130.9497 -123.11126)
		(end 131.849368 -124.010928)
		(width 0.14224)
		(layer "In4.Cu")
		(net "M_M_DQ<42>")
	)
	(segment
		(start 132.128768 -132.004308)
		(end 132.128768 -134.0612)
		(width 0.14224)
		(layer "In4.Cu")
		(net "M_M_DQ<42>")
	)
	(segment
		(start 132.065776 -129.960878)
		(end 132.065776 -131.332478)
		(width 0.14224)
		(layer "In4.Cu")
		(net "M_M_DQ<42>")
	)
	(segment
		(start 132.124958 -143.63319)
		(end 132.268976 -143.777208)
		(width 0.14224)
		(layer "In4.Cu")
		(net "M_M_DQ<42>")
	)
	(segment
		(start 132.268976 -141.136878)
		(end 132.268976 -141.478)
		(width 0.14224)
		(layer "In4.Cu")
		(net "M_M_DQ<42>")
	)
	(segment
		(start 132.128768 -134.0612)
		(end 132.281676 -134.214108)
		(width 0.14224)
		(layer "In4.Cu")
		(net "M_M_DQ<42>")
	)
	(segment
		(start 118.762272 -104.043734)
		(end 118.795038 -104.043734)
		(width 0.0889)
		(layer "In4.Cu")
		(net "M_M_DQ<42>")
	)
	(segment
		(start 132.281676 -134.214108)
		(end 132.281676 -134.439152)
		(width 0.14224)
		(layer "In4.Cu")
		(net "M_M_DQ<42>")
	)
	(segment
		(start 131.849368 -124.010928)
		(end 131.849368 -125.6284)
		(width 0.14224)
		(layer "In4.Cu")
		(net "M_M_DQ<42>")
	)
	(segment
		(start 132.268976 -141.478)
		(end 132.124958 -141.622018)
		(width 0.14224)
		(layer "In4.Cu")
		(net "M_M_DQ<42>")
	)
	(segment
		(start 118.265702 -100.765864)
		(end 118.272052 -100.776532)
		(width 0.0889)
		(layer "In4.Cu")
		(net "M_M_DQ<42>")
	)
	(arc
		(start 119.130572 -106.225086)
		(mid 119.33918 -106.437018)
		(end 119.624602 -106.520488)
		(width 0.0889)
		(layer "In4.Cu")
		(net "M_M_DQ<42>")
	)
	(arc
		(start 118.272052 -96.814894)
		(mid 118.325551 -97.014792)
		(end 118.272052 -97.21469)
		(width 0.0889)
		(layer "In4.Cu")
		(net "M_M_DQ<42>")
	)
	(arc
		(start 119.130572 -104.643936)
		(mid 119.05135 -104.933054)
		(end 119.124222 -105.223818)
		(width 0.0889)
		(layer "In4.Cu")
		(net "M_M_DQ<42>")
	)
	(arc
		(start 118.27891 -100.788724)
		(mid 118.325586 -100.983425)
		(end 118.272052 -101.176328)
		(width 0.0889)
		(layer "In4.Cu")
		(net "M_M_DQ<42>")
	)
	(arc
		(start 117.559582 -94.871286)
		(mid 117.555465 -95.186284)
		(end 117.780562 -95.406718)
		(width 0.0889)
		(layer "In4.Cu")
		(net "M_M_DQ<42>")
	)
	(arc
		(start 119.130572 -105.634536)
		(mid 119.045912 -105.923585)
		(end 119.124222 -106.214418)
		(width 0.0889)
		(layer "In4.Cu")
		(net "M_M_DQ<42>")
	)
	(arc
		(start 118.272052 -97.805494)
		(mid 118.325551 -98.005392)
		(end 118.272052 -98.20529)
		(width 0.0889)
		(layer "In4.Cu")
		(net "M_M_DQ<42>")
	)
	(arc
		(start 118.265702 -103.168704)
		(mid 118.192904 -103.459467)
		(end 118.272052 -103.748586)
		(width 0.0889)
		(layer "In4.Cu")
		(net "M_M_DQ<42>")
	)
	(arc
		(start 118.276878 -99.794568)
		(mid 118.325633 -99.99092)
		(end 118.272052 -100.185982)
		(width 0.0889)
		(layer "In4.Cu")
		(net "M_M_DQ<42>")
	)
	(arc
		(start 118.272052 -98.796094)
		(mid 118.325551 -98.995992)
		(end 118.272052 -99.19589)
		(width 0.0889)
		(layer "In4.Cu")
		(net "M_M_DQ<42>")
	)
	(arc
		(start 119.657368 -106.520488)
		(mid 119.84901 -106.577654)
		(end 119.989092 -106.720386)
		(width 0.0889)
		(layer "In4.Cu")
		(net "M_M_DQ<42>")
	)
	(arc
		(start 118.272052 -96.22409)
		(mid 118.192921 -96.519492)
		(end 118.272052 -96.814894)
		(width 0.0889)
		(layer "In4.Cu")
		(net "M_M_DQ<42>")
	)
	(arc
		(start 118.272052 -101.176328)
		(mid 118.192863 -101.462943)
		(end 118.263162 -101.751892)
		(width 0.0889)
		(layer "In4.Cu")
		(net "M_M_DQ<42>")
	)
	(arc
		(start 118.795038 -104.043734)
		(mid 118.988888 -104.100084)
		(end 119.130572 -104.243886)
		(width 0.0889)
		(layer "In4.Cu")
		(net "M_M_DQ<42>")
	)
	(arc
		(start 119.135398 -104.252522)
		(mid 119.184153 -104.448874)
		(end 119.130572 -104.643936)
		(width 0.0889)
		(layer "In4.Cu")
		(net "M_M_DQ<42>")
	)
	(arc
		(start 118.272052 -102.757986)
		(mid 118.325522 -102.953049)
		(end 118.276878 -103.1494)
		(width 0.0889)
		(layer "In4.Cu")
		(net "M_M_DQ<42>")
	)
	(arc
		(start 118.272052 -99.19589)
		(mid 118.192921 -99.491292)
		(end 118.272052 -99.786694)
		(width 0.0889)
		(layer "In4.Cu")
		(net "M_M_DQ<42>")
	)
	(arc
		(start 118.276878 -101.775768)
		(mid 118.325633 -101.97212)
		(end 118.272052 -102.167182)
		(width 0.0889)
		(layer "In4.Cu")
		(net "M_M_DQ<42>")
	)
	(arc
		(start 118.272052 -97.21469)
		(mid 118.192921 -97.510092)
		(end 118.272052 -97.805494)
		(width 0.0889)
		(layer "In4.Cu")
		(net "M_M_DQ<42>")
	)
	(arc
		(start 118.272052 -99.786694)
		(mid 118.27441 -99.790665)
		(end 118.276878 -99.794568)
		(width 0.0889)
		(layer "In4.Cu")
		(net "M_M_DQ<42>")
	)
	(arc
		(start 118.272052 -103.748586)
		(mid 118.479056 -103.95945)
		(end 118.762272 -104.043734)
		(width 0.0889)
		(layer "In4.Cu")
		(net "M_M_DQ<42>")
	)
	(arc
		(start 118.272052 -102.167182)
		(mid 118.192921 -102.462584)
		(end 118.272052 -102.757986)
		(width 0.0889)
		(layer "In4.Cu")
		(net "M_M_DQ<42>")
	)
	(arc
		(start 119.135398 -105.243122)
		(mid 119.184153 -105.439474)
		(end 119.130572 -105.634536)
		(width 0.0889)
		(layer "In4.Cu")
		(net "M_M_DQ<42>")
	)
	(arc
		(start 118.272052 -98.20529)
		(mid 118.192921 -98.500692)
		(end 118.272052 -98.796094)
		(width 0.0889)
		(layer "In4.Cu")
		(net "M_M_DQ<42>")
	)
	(arc
		(start 118.272052 -95.824294)
		(mid 118.325551 -96.024192)
		(end 118.272052 -96.22409)
		(width 0.0889)
		(layer "In4.Cu")
		(net "M_M_DQ<42>")
	)
	(arc
		(start 117.780562 -95.406718)
		(mid 118.061537 -95.574046)
		(end 118.272052 -95.824294)
		(width 0.0889)
		(layer "In4.Cu")
		(net "M_M_DQ<42>")
	)
	(arc
		(start 118.272052 -100.185982)
		(mid 118.19283 -100.4751)
		(end 118.265702 -100.765864)
		(width 0.0889)
		(layer "In4.Cu")
		(net "M_M_DQ<42>")
	)
	(segment
		(start 131.266438 -153.834846)
		(end 131.266438 -151.247348)
		(width 0.14224)
		(layer "In11.Cu")
		(net "M_M_DQ<42>")
	)
	(segment
		(start 132.549392 -155.1178)
		(end 131.266438 -153.834846)
		(width 0.14224)
		(layer "In11.Cu")
		(net "M_M_DQ<42>")
	)
	(segment
		(start 131.266438 -151.247348)
		(end 131.699508 -150.814278)
		(width 0.14224)
		(layer "In11.Cu")
		(net "M_M_DQ<42>")
	)
	(segment
		(start 114.778282 -95.528384)
		(end 115.349782 -95.528384)
		(width 0.1651)
		(layer "F.Cu")
		(net "M_M_DQ<41>")
	)
	(segment
		(start 125.749558 -152.273)
		(end 125.749558 -153.542746)
		(width 0.1651)
		(layer "F.Cu")
		(net "M_M_DQ<41>")
	)
	(via
		(at 115.349782 -95.528384)
		(size 0.508)
		(drill 0.254)
		(layers "F.Cu" "B.Cu")
		(net "M_M_DQ<41>")
	)
	(via
		(at 126.421642 -149.533356)
		(size 0.508)
		(drill 0.254)
		(layers "F.Cu" "B.Cu")
		(net "M_M_DQ<41>")
	)
	(via
		(at 125.749558 -153.542746)
		(size 0.508)
		(drill 0.254)
		(layers "F.Cu" "B.Cu")
		(net "M_M_DQ<41>")
	)
	(segment
		(start 126.599442 -147.478496)
		(end 126.599442 -148.852382)
		(width 0.1651)
		(layer "B.Cu")
		(net "M_M_DQ<41>")
	)
	(segment
		(start 126.599442 -148.852382)
		(end 126.421642 -149.030182)
		(width 0.1651)
		(layer "B.Cu")
		(net "M_M_DQ<41>")
	)
	(segment
		(start 126.421642 -149.030182)
		(end 126.421642 -149.533356)
		(width 0.1651)
		(layer "B.Cu")
		(net "M_M_DQ<41>")
	)
	(segment
		(start 119.362982 -117.253004)
		(end 119.615458 -117.000528)
		(width 0.14224)
		(layer "In4.Cu")
		(net "M_M_DQ<41>")
	)
	(segment
		(start 120.553226 -117.938296)
		(end 120.553226 -117.719348)
		(width 0.14224)
		(layer "In4.Cu")
		(net "M_M_DQ<41>")
	)
	(segment
		(start 115.861592 -107.09656)
		(end 115.861592 -106.720386)
		(width 0.0889)
		(layer "In4.Cu")
		(net "M_M_DQ<41>")
	)
	(segment
		(start 126.915164 -136.6266)
		(end 126.915164 -134.118604)
		(width 0.14224)
		(layer "In4.Cu")
		(net "M_M_DQ<41>")
	)
	(segment
		(start 127.023368 -141.5288)
		(end 126.915164 -141.420596)
		(width 0.14224)
		(layer "In4.Cu")
		(net "M_M_DQ<41>")
	)
	(segment
		(start 122.428762 -119.594884)
		(end 122.178826 -119.344948)
		(width 0.14224)
		(layer "In4.Cu")
		(net "M_M_DQ<41>")
	)
	(segment
		(start 119.362982 -117.471952)
		(end 119.362982 -117.253004)
		(width 0.14224)
		(layer "In4.Cu")
		(net "M_M_DQ<41>")
	)
	(segment
		(start 118.67769 -115.843812)
		(end 115.984528 -113.15065)
		(width 0.14224)
		(layer "In4.Cu")
		(net "M_M_DQ<41>")
	)
	(segment
		(start 115.003072 -104.243886)
		(end 115.009422 -104.233218)
		(width 0.0889)
		(layer "In4.Cu")
		(net "M_M_DQ<41>")
	)
	(segment
		(start 124.22759 -122.33656)
		(end 122.176286 -120.285256)
		(width 0.14224)
		(layer "In4.Cu")
		(net "M_M_DQ<41>")
	)
	(segment
		(start 120.550686 -118.659656)
		(end 120.30075 -118.40972)
		(width 0.14224)
		(layer "In4.Cu")
		(net "M_M_DQ<41>")
	)
	(segment
		(start 127.239776 -129.044192)
		(end 127.239776 -127.292608)
		(width 0.14224)
		(layer "In4.Cu")
		(net "M_M_DQ<41>")
	)
	(segment
		(start 121.238518 -119.12854)
		(end 121.490994 -118.876064)
		(width 0.14224)
		(layer "In4.Cu")
		(net "M_M_DQ<41>")
	)
	(segment
		(start 115.984528 -113.15065)
		(end 115.984528 -107.219496)
		(width 0.14224)
		(layer "In4.Cu")
		(net "M_M_DQ<41>")
	)
	(segment
		(start 115.003072 -101.272086)
		(end 115.009422 -101.261418)
		(width 0.0889)
		(layer "In4.Cu")
		(net "M_M_DQ<41>")
	)
	(segment
		(start 118.67515 -116.78412)
		(end 118.425214 -116.534184)
		(width 0.14224)
		(layer "In4.Cu")
		(net "M_M_DQ<41>")
	)
	(segment
		(start 127.023368 -136.734804)
		(end 126.915164 -136.6266)
		(width 0.14224)
		(layer "In4.Cu")
		(net "M_M_DQ<41>")
	)
	(segment
		(start 122.178826 -119.344948)
		(end 121.959878 -119.344948)
		(width 0.14224)
		(layer "In4.Cu")
		(net "M_M_DQ<41>")
	)
	(segment
		(start 126.693168 -137.5918)
		(end 127.023368 -137.2616)
		(width 0.14224)
		(layer "In4.Cu")
		(net "M_M_DQ<41>")
	)
	(segment
		(start 127.023368 -143.002)
		(end 126.820168 -142.7988)
		(width 0.14224)
		(layer "In4.Cu")
		(net "M_M_DQ<41>")
	)
	(segment
		(start 126.915164 -138.919204)
		(end 127.023368 -138.811)
		(width 0.14224)
		(layer "In4.Cu")
		(net "M_M_DQ<41>")
	)
	(segment
		(start 126.421642 -149.533356)
		(end 126.915164 -149.039834)
		(width 0.14224)
		(layer "In4.Cu")
		(net "M_M_DQ<41>")
	)
	(segment
		(start 115.367562 -105.834434)
		(end 115.334796 -105.834434)
		(width 0.0889)
		(layer "In4.Cu")
		(net "M_M_DQ<41>")
	)
	(segment
		(start 121.02211 -118.40718)
		(end 120.769634 -118.659656)
		(width 0.14224)
		(layer "In4.Cu")
		(net "M_M_DQ<41>")
	)
	(segment
		(start 125.089666 -122.33656)
		(end 124.22759 -122.33656)
		(width 0.14224)
		(layer "In4.Cu")
		(net "M_M_DQ<41>")
	)
	(segment
		(start 121.959878 -119.344948)
		(end 121.707402 -119.597424)
		(width 0.14224)
		(layer "In4.Cu")
		(net "M_M_DQ<41>")
	)
	(segment
		(start 127.023368 -143.6878)
		(end 127.023368 -143.002)
		(width 0.14224)
		(layer "In4.Cu")
		(net "M_M_DQ<41>")
	)
	(segment
		(start 115.984528 -107.219496)
		(end 115.861592 -107.09656)
		(width 0.0889)
		(layer "In4.Cu")
		(net "M_M_DQ<41>")
	)
	(segment
		(start 126.915164 -143.796004)
		(end 127.023368 -143.6878)
		(width 0.14224)
		(layer "In4.Cu")
		(net "M_M_DQ<41>")
	)
	(segment
		(start 118.894098 -116.78412)
		(end 118.67515 -116.78412)
		(width 0.14224)
		(layer "In4.Cu")
		(net "M_M_DQ<41>")
	)
	(segment
		(start 126.870968 -126.9238)
		(end 126.870968 -124.117862)
		(width 0.14224)
		(layer "In4.Cu")
		(net "M_M_DQ<41>")
	)
	(segment
		(start 114.998246 -101.280722)
		(end 115.003072 -101.272086)
		(width 0.0889)
		(layer "In4.Cu")
		(net "M_M_DQ<41>")
	)
	(segment
		(start 126.915164 -134.118604)
		(end 127.023368 -134.0104)
		(width 0.14224)
		(layer "In4.Cu")
		(net "M_M_DQ<41>")
	)
	(segment
		(start 115.003072 -102.262686)
		(end 115.009422 -102.252018)
		(width 0.0889)
		(layer "In4.Cu")
		(net "M_M_DQ<41>")
	)
	(segment
		(start 121.488454 -119.597424)
		(end 121.238518 -119.347488)
		(width 0.14224)
		(layer "In4.Cu")
		(net "M_M_DQ<41>")
	)
	(segment
		(start 119.365522 -116.531644)
		(end 119.146574 -116.531644)
		(width 0.14224)
		(layer "In4.Cu")
		(net "M_M_DQ<41>")
	)
	(segment
		(start 127.239776 -127.292608)
		(end 126.870968 -126.9238)
		(width 0.14224)
		(layer "In4.Cu")
		(net "M_M_DQ<41>")
	)
	(segment
		(start 120.30075 -118.190772)
		(end 120.553226 -117.938296)
		(width 0.14224)
		(layer "In4.Cu")
		(net "M_M_DQ<41>")
	)
	(segment
		(start 121.241058 -118.40718)
		(end 121.02211 -118.40718)
		(width 0.14224)
		(layer "In4.Cu")
		(net "M_M_DQ<41>")
	)
	(segment
		(start 121.707402 -119.597424)
		(end 121.488454 -119.597424)
		(width 0.14224)
		(layer "In4.Cu")
		(net "M_M_DQ<41>")
	)
	(segment
		(start 118.67769 -116.06276)
		(end 118.67769 -115.843812)
		(width 0.14224)
		(layer "In4.Cu")
		(net "M_M_DQ<41>")
	)
	(segment
		(start 122.176286 -120.066308)
		(end 122.428762 -119.813832)
		(width 0.14224)
		(layer "In4.Cu")
		(net "M_M_DQ<41>")
	)
	(segment
		(start 126.870968 -124.117862)
		(end 125.089666 -122.33656)
		(width 0.14224)
		(layer "In4.Cu")
		(net "M_M_DQ<41>")
	)
	(segment
		(start 126.915164 -141.420596)
		(end 126.915164 -138.919204)
		(width 0.14224)
		(layer "In4.Cu")
		(net "M_M_DQ<41>")
	)
	(segment
		(start 126.915164 -149.039834)
		(end 126.915164 -143.796004)
		(width 0.14224)
		(layer "In4.Cu")
		(net "M_M_DQ<41>")
	)
	(segment
		(start 114.998246 -102.271322)
		(end 115.003072 -102.262686)
		(width 0.0889)
		(layer "In4.Cu")
		(net "M_M_DQ<41>")
	)
	(segment
		(start 127.023368 -138.3792)
		(end 126.693168 -138.049)
		(width 0.14224)
		(layer "In4.Cu")
		(net "M_M_DQ<41>")
	)
	(segment
		(start 114.998246 -104.252522)
		(end 115.003072 -104.243886)
		(width 0.0889)
		(layer "In4.Cu")
		(net "M_M_DQ<41>")
	)
	(segment
		(start 119.615458 -116.78158)
		(end 119.365522 -116.531644)
		(width 0.14224)
		(layer "In4.Cu")
		(net "M_M_DQ<41>")
	)
	(segment
		(start 114.998246 -105.243122)
		(end 115.003072 -105.234486)
		(width 0.0889)
		(layer "In4.Cu")
		(net "M_M_DQ<41>")
	)
	(segment
		(start 127.023368 -141.986)
		(end 127.023368 -141.5288)
		(width 0.14224)
		(layer "In4.Cu")
		(net "M_M_DQ<41>")
	)
	(segment
		(start 119.612918 -117.721888)
		(end 119.362982 -117.471952)
		(width 0.14224)
		(layer "In4.Cu")
		(net "M_M_DQ<41>")
	)
	(segment
		(start 122.176286 -120.285256)
		(end 122.176286 -120.066308)
		(width 0.14224)
		(layer "In4.Cu")
		(net "M_M_DQ<41>")
	)
	(segment
		(start 115.003072 -105.234486)
		(end 115.009422 -105.223818)
		(width 0.0889)
		(layer "In4.Cu")
		(net "M_M_DQ<41>")
	)
	(segment
		(start 115.003072 -103.253286)
		(end 115.009422 -103.242618)
		(width 0.0889)
		(layer "In4.Cu")
		(net "M_M_DQ<41>")
	)
	(segment
		(start 120.769634 -118.659656)
		(end 120.550686 -118.659656)
		(width 0.14224)
		(layer "In4.Cu")
		(net "M_M_DQ<41>")
	)
	(segment
		(start 115.003072 -100.281486)
		(end 115.009422 -100.270818)
		(width 0.0889)
		(layer "In4.Cu")
		(net "M_M_DQ<41>")
	)
	(segment
		(start 120.30329 -117.469412)
		(end 120.084342 -117.469412)
		(width 0.14224)
		(layer "In4.Cu")
		(net "M_M_DQ<41>")
	)
	(segment
		(start 126.915164 -131.793996)
		(end 126.915164 -129.368804)
		(width 0.14224)
		(layer "In4.Cu")
		(net "M_M_DQ<41>")
	)
	(segment
		(start 127.023368 -137.2616)
		(end 127.023368 -136.734804)
		(width 0.14224)
		(layer "In4.Cu")
		(net "M_M_DQ<41>")
	)
	(segment
		(start 118.425214 -116.534184)
		(end 118.425214 -116.315236)
		(width 0.14224)
		(layer "In4.Cu")
		(net "M_M_DQ<41>")
	)
	(segment
		(start 114.998246 -100.290122)
		(end 115.003072 -100.281486)
		(width 0.0889)
		(layer "In4.Cu")
		(net "M_M_DQ<41>")
	)
	(segment
		(start 118.425214 -116.315236)
		(end 118.67769 -116.06276)
		(width 0.14224)
		(layer "In4.Cu")
		(net "M_M_DQ<41>")
	)
	(segment
		(start 126.915164 -129.368804)
		(end 127.239776 -129.044192)
		(width 0.14224)
		(layer "In4.Cu")
		(net "M_M_DQ<41>")
	)
	(segment
		(start 127.023368 -131.9022)
		(end 126.915164 -131.793996)
		(width 0.14224)
		(layer "In4.Cu")
		(net "M_M_DQ<41>")
	)
	(segment
		(start 120.30075 -118.40972)
		(end 120.30075 -118.190772)
		(width 0.14224)
		(layer "In4.Cu")
		(net "M_M_DQ<41>")
	)
	(segment
		(start 119.615458 -117.000528)
		(end 119.615458 -116.78158)
		(width 0.14224)
		(layer "In4.Cu")
		(net "M_M_DQ<41>")
	)
	(segment
		(start 119.831866 -117.721888)
		(end 119.612918 -117.721888)
		(width 0.14224)
		(layer "In4.Cu")
		(net "M_M_DQ<41>")
	)
	(segment
		(start 121.238518 -119.347488)
		(end 121.238518 -119.12854)
		(width 0.14224)
		(layer "In4.Cu")
		(net "M_M_DQ<41>")
	)
	(segment
		(start 119.146574 -116.531644)
		(end 118.894098 -116.78412)
		(width 0.14224)
		(layer "In4.Cu")
		(net "M_M_DQ<41>")
	)
	(segment
		(start 121.490994 -118.876064)
		(end 121.490994 -118.657116)
		(width 0.14224)
		(layer "In4.Cu")
		(net "M_M_DQ<41>")
	)
	(segment
		(start 114.998246 -103.261922)
		(end 115.003072 -103.253286)
		(width 0.0889)
		(layer "In4.Cu")
		(net "M_M_DQ<41>")
	)
	(segment
		(start 121.490994 -118.657116)
		(end 121.241058 -118.40718)
		(width 0.14224)
		(layer "In4.Cu")
		(net "M_M_DQ<41>")
	)
	(segment
		(start 126.820168 -142.1892)
		(end 127.023368 -141.986)
		(width 0.14224)
		(layer "In4.Cu")
		(net "M_M_DQ<41>")
	)
	(segment
		(start 122.428762 -119.813832)
		(end 122.428762 -119.594884)
		(width 0.14224)
		(layer "In4.Cu")
		(net "M_M_DQ<41>")
	)
	(segment
		(start 126.693168 -138.049)
		(end 126.693168 -137.5918)
		(width 0.14224)
		(layer "In4.Cu")
		(net "M_M_DQ<41>")
	)
	(segment
		(start 120.553226 -117.719348)
		(end 120.30329 -117.469412)
		(width 0.14224)
		(layer "In4.Cu")
		(net "M_M_DQ<41>")
	)
	(segment
		(start 120.084342 -117.469412)
		(end 119.831866 -117.721888)
		(width 0.14224)
		(layer "In4.Cu")
		(net "M_M_DQ<41>")
	)
	(segment
		(start 127.023368 -138.811)
		(end 127.023368 -138.3792)
		(width 0.14224)
		(layer "In4.Cu")
		(net "M_M_DQ<41>")
	)
	(segment
		(start 126.820168 -142.7988)
		(end 126.820168 -142.1892)
		(width 0.14224)
		(layer "In4.Cu")
		(net "M_M_DQ<41>")
	)
	(segment
		(start 127.023368 -134.0104)
		(end 127.023368 -131.9022)
		(width 0.14224)
		(layer "In4.Cu")
		(net "M_M_DQ<41>")
	)
	(segment
		(start 115.06581 -96.16186)
		(end 115.349782 -95.528384)
		(width 0.0889)
		(layer "In4.Cu")
		(net "M_M_DQ<41>")
	)
	(arc
		(start 115.009422 -102.252018)
		(mid 115.08222 -101.961255)
		(end 115.003072 -101.672136)
		(width 0.0889)
		(layer "In4.Cu")
		(net "M_M_DQ<41>")
	)
	(arc
		(start 115.009422 -105.223818)
		(mid 115.08222 -104.933055)
		(end 115.003072 -104.643936)
		(width 0.0889)
		(layer "In4.Cu")
		(net "M_M_DQ<41>")
	)
	(arc
		(start 115.003072 -98.70059)
		(mid 114.949573 -98.500692)
		(end 115.003072 -98.300794)
		(width 0.0889)
		(layer "In4.Cu")
		(net "M_M_DQ<41>")
	)
	(arc
		(start 115.861592 -106.720386)
		(mid 115.940814 -106.431268)
		(end 115.867942 -106.140504)
		(width 0.0889)
		(layer "In4.Cu")
		(net "M_M_DQ<41>")
	)
	(arc
		(start 115.009422 -100.270818)
		(mid 115.081681 -100.01266)
		(end 115.032536 -99.749102)
		(width 0.0889)
		(layer "In4.Cu")
		(net "M_M_DQ<41>")
	)
	(arc
		(start 115.032536 -99.749102)
		(mid 115.018558 -99.719763)
		(end 115.003072 -99.69119)
		(width 0.0889)
		(layer "In4.Cu")
		(net "M_M_DQ<41>")
	)
	(arc
		(start 115.003072 -103.653336)
		(mid 114.949602 -103.458273)
		(end 114.998246 -103.261922)
		(width 0.0889)
		(layer "In4.Cu")
		(net "M_M_DQ<41>")
	)
	(arc
		(start 115.003072 -102.662736)
		(mid 114.949602 -102.467673)
		(end 114.998246 -102.271322)
		(width 0.0889)
		(layer "In4.Cu")
		(net "M_M_DQ<41>")
	)
	(arc
		(start 115.009422 -104.233218)
		(mid 115.08222 -103.942455)
		(end 115.003072 -103.653336)
		(width 0.0889)
		(layer "In4.Cu")
		(net "M_M_DQ<41>")
	)
	(arc
		(start 115.003072 -97.70999)
		(mid 114.949573 -97.510092)
		(end 115.003072 -97.310194)
		(width 0.0889)
		(layer "In4.Cu")
		(net "M_M_DQ<41>")
	)
	(arc
		(start 115.334796 -105.834434)
		(mid 115.001878 -105.632443)
		(end 114.998246 -105.243122)
		(width 0.0889)
		(layer "In4.Cu")
		(net "M_M_DQ<41>")
	)
	(arc
		(start 115.003072 -97.310194)
		(mid 115.082203 -97.014792)
		(end 115.003072 -96.71939)
		(width 0.0889)
		(layer "In4.Cu")
		(net "M_M_DQ<41>")
	)
	(arc
		(start 115.003072 -99.69119)
		(mid 114.949573 -99.491292)
		(end 115.003072 -99.291394)
		(width 0.0889)
		(layer "In4.Cu")
		(net "M_M_DQ<41>")
	)
	(arc
		(start 115.003072 -96.319594)
		(mid 115.040119 -96.242987)
		(end 115.06581 -96.16186)
		(width 0.0889)
		(layer "In4.Cu")
		(net "M_M_DQ<41>")
	)
	(arc
		(start 115.009422 -103.242618)
		(mid 115.08222 -102.951855)
		(end 115.003072 -102.662736)
		(width 0.0889)
		(layer "In4.Cu")
		(net "M_M_DQ<41>")
	)
	(arc
		(start 115.003072 -99.291394)
		(mid 115.082203 -98.995992)
		(end 115.003072 -98.70059)
		(width 0.0889)
		(layer "In4.Cu")
		(net "M_M_DQ<41>")
	)
	(arc
		(start 115.003072 -100.681536)
		(mid 114.949602 -100.486473)
		(end 114.998246 -100.290122)
		(width 0.0889)
		(layer "In4.Cu")
		(net "M_M_DQ<41>")
	)
	(arc
		(start 115.003072 -104.643936)
		(mid 114.949602 -104.448873)
		(end 114.998246 -104.252522)
		(width 0.0889)
		(layer "In4.Cu")
		(net "M_M_DQ<41>")
	)
	(arc
		(start 115.003072 -98.300794)
		(mid 115.082203 -98.005392)
		(end 115.003072 -97.70999)
		(width 0.0889)
		(layer "In4.Cu")
		(net "M_M_DQ<41>")
	)
	(arc
		(start 115.867942 -106.140504)
		(mid 115.658427 -105.92095)
		(end 115.367562 -105.834434)
		(width 0.0889)
		(layer "In4.Cu")
		(net "M_M_DQ<41>")
	)
	(arc
		(start 115.003072 -101.672136)
		(mid 114.949602 -101.477073)
		(end 114.998246 -101.280722)
		(width 0.0889)
		(layer "In4.Cu")
		(net "M_M_DQ<41>")
	)
	(arc
		(start 115.009422 -101.261418)
		(mid 115.08222 -100.970655)
		(end 115.003072 -100.681536)
		(width 0.0889)
		(layer "In4.Cu")
		(net "M_M_DQ<41>")
	)
	(arc
		(start 115.003072 -96.71939)
		(mid 114.949573 -96.519492)
		(end 115.003072 -96.319594)
		(width 0.0889)
		(layer "In4.Cu")
		(net "M_M_DQ<41>")
	)
	(segment
		(start 125.971046 -150.391368)
		(end 125.971046 -149.9616)
		(width 0.14224)
		(layer "In11.Cu")
		(net "M_M_DQ<41>")
	)
	(segment
		(start 125.749558 -153.542746)
		(end 125.998478 -153.542746)
		(width 0.14224)
		(layer "In11.Cu")
		(net "M_M_DQ<41>")
	)
	(segment
		(start 126.39929 -149.533356)
		(end 126.421642 -149.533356)
		(width 0.14224)
		(layer "In11.Cu")
		(net "M_M_DQ<41>")
	)
	(segment
		(start 125.910848 -151.316944)
		(end 126.201424 -151.026368)
		(width 0.14224)
		(layer "In11.Cu")
		(net "M_M_DQ<41>")
	)
	(segment
		(start 126.125224 -152.3238)
		(end 126.125224 -151.892)
		(width 0.14224)
		(layer "In11.Cu")
		(net "M_M_DQ<41>")
	)
	(segment
		(start 125.910848 -152.846024)
		(end 125.910848 -152.538176)
		(width 0.14224)
		(layer "In11.Cu")
		(net "M_M_DQ<41>")
	)
	(segment
		(start 126.201424 -151.026368)
		(end 126.201424 -150.621746)
		(width 0.14224)
		(layer "In11.Cu")
		(net "M_M_DQ<41>")
	)
	(segment
		(start 126.150624 -153.3906)
		(end 126.150624 -153.0858)
		(width 0.14224)
		(layer "In11.Cu")
		(net "M_M_DQ<41>")
	)
	(segment
		(start 125.998478 -153.542746)
		(end 126.150624 -153.3906)
		(width 0.14224)
		(layer "In11.Cu")
		(net "M_M_DQ<41>")
	)
	(segment
		(start 125.971046 -149.9616)
		(end 126.39929 -149.533356)
		(width 0.14224)
		(layer "In11.Cu")
		(net "M_M_DQ<41>")
	)
	(segment
		(start 126.125224 -151.892)
		(end 125.910848 -151.677624)
		(width 0.14224)
		(layer "In11.Cu")
		(net "M_M_DQ<41>")
	)
	(segment
		(start 126.150624 -153.0858)
		(end 125.910848 -152.846024)
		(width 0.14224)
		(layer "In11.Cu")
		(net "M_M_DQ<41>")
	)
	(segment
		(start 125.910848 -151.677624)
		(end 125.910848 -151.316944)
		(width 0.14224)
		(layer "In11.Cu")
		(net "M_M_DQ<41>")
	)
	(segment
		(start 126.201424 -150.621746)
		(end 125.971046 -150.391368)
		(width 0.14224)
		(layer "In11.Cu")
		(net "M_M_DQ<41>")
	)
	(segment
		(start 125.910848 -152.538176)
		(end 126.125224 -152.3238)
		(width 0.14224)
		(layer "In11.Cu")
		(net "M_M_DQ<41>")
	)
	(segment
		(start 126.599442 -156.87294)
		(end 126.599442 -156.878782)
		(width 0.1651)
		(layer "F.Cu")
		(net "M_M_DQ<40>")
	)
	(segment
		(start 114.778282 -93.547184)
		(end 115.349782 -93.547184)
		(width 0.1651)
		(layer "F.Cu")
		(net "M_M_DQ<40>")
	)
	(segment
		(start 126.599442 -156.878782)
		(end 126.450852 -155.322778)
		(width 0.1651)
		(layer "F.Cu")
		(net "M_M_DQ<40>")
	)
	(segment
		(start 126.450852 -155.322778)
		(end 126.515368 -155.2448)
		(width 0.1651)
		(layer "F.Cu")
		(net "M_M_DQ<40>")
	)
	(via
		(at 115.349782 -93.547184)
		(size 0.508)
		(drill 0.254)
		(layers "F.Cu" "B.Cu")
		(net "M_M_DQ<40>")
	)
	(via
		(at 125.749558 -150.814278)
		(size 0.508)
		(drill 0.254)
		(layers "F.Cu" "B.Cu")
		(net "M_M_DQ<40>")
	)
	(via
		(at 126.515368 -155.2448)
		(size 0.508)
		(drill 0.254)
		(layers "F.Cu" "B.Cu")
		(net "M_M_DQ<40>")
	)
	(segment
		(start 125.749558 -152.078436)
		(end 125.749558 -150.814278)
		(width 0.1651)
		(layer "B.Cu")
		(net "M_M_DQ<40>")
	)
	(segment
		(start 126.236476 -145.847562)
		(end 125.944376 -145.555462)
		(width 0.14224)
		(layer "In4.Cu")
		(net "M_M_DQ<40>")
	)
	(segment
		(start 114.831622 -105.149904)
		(end 114.837972 -105.139236)
		(width 0.0889)
		(layer "In4.Cu")
		(net "M_M_DQ<40>")
	)
	(segment
		(start 125.944376 -145.555462)
		(end 125.944376 -144.360138)
		(width 0.14224)
		(layer "In4.Cu")
		(net "M_M_DQ<40>")
	)
	(segment
		(start 126.185168 -141.592808)
		(end 126.235968 -141.542008)
		(width 0.14224)
		(layer "In4.Cu")
		(net "M_M_DQ<40>")
	)
	(segment
		(start 125.931676 -130.062478)
		(end 126.229364 -129.76479)
		(width 0.14224)
		(layer "In4.Cu")
		(net "M_M_DQ<40>")
	)
	(segment
		(start 114.837972 -103.158036)
		(end 114.842798 -103.1494)
		(width 0.0889)
		(layer "In4.Cu")
		(net "M_M_DQ<40>")
	)
	(segment
		(start 124.268484 -122.84837)
		(end 123.91771 -122.84837)
		(width 0.14224)
		(layer "In4.Cu")
		(net "M_M_DQ<40>")
	)
	(segment
		(start 114.831622 -103.168704)
		(end 114.837972 -103.158036)
		(width 0.0889)
		(layer "In4.Cu")
		(net "M_M_DQ<40>")
	)
	(segment
		(start 126.591568 -127.263144)
		(end 126.229364 -126.90094)
		(width 0.14224)
		(layer "In4.Cu")
		(net "M_M_DQ<40>")
	)
	(segment
		(start 126.007368 -136.843008)
		(end 126.274576 -136.5758)
		(width 0.14224)
		(layer "In4.Cu")
		(net "M_M_DQ<40>")
	)
	(segment
		(start 115.349782 -93.547184)
		(end 115.06073 -94.200726)
		(width 0.0889)
		(layer "In4.Cu")
		(net "M_M_DQ<40>")
	)
	(segment
		(start 115.377468 -113.297462)
		(end 115.377468 -107.191556)
		(width 0.14224)
		(layer "In4.Cu")
		(net "M_M_DQ<40>")
	)
	(segment
		(start 126.229364 -126.90094)
		(end 126.229364 -125.901196)
		(width 0.14224)
		(layer "In4.Cu")
		(net "M_M_DQ<40>")
	)
	(segment
		(start 126.274576 -139.320778)
		(end 126.274576 -138.773408)
		(width 0.14224)
		(layer "In4.Cu")
		(net "M_M_DQ<40>")
	)
	(segment
		(start 125.749558 -150.814278)
		(end 125.749558 -149.446996)
		(width 0.14224)
		(layer "In4.Cu")
		(net "M_M_DQ<40>")
	)
	(segment
		(start 126.236476 -148.960078)
		(end 126.236476 -145.847562)
		(width 0.14224)
		(layer "In4.Cu")
		(net "M_M_DQ<40>")
	)
	(segment
		(start 126.235968 -141.542008)
		(end 126.235968 -141.04747)
		(width 0.14224)
		(layer "In4.Cu")
		(net "M_M_DQ<40>")
	)
	(segment
		(start 114.831622 -101.187504)
		(end 114.837972 -101.176836)
		(width 0.0889)
		(layer "In4.Cu")
		(net "M_M_DQ<40>")
	)
	(segment
		(start 114.831622 -100.196904)
		(end 114.837972 -100.186236)
		(width 0.0889)
		(layer "In4.Cu")
		(net "M_M_DQ<40>")
	)
	(segment
		(start 115.360958 -106.024934)
		(end 115.328192 -106.024934)
		(width 0.0889)
		(layer "In4.Cu")
		(net "M_M_DQ<40>")
	)
	(segment
		(start 126.229364 -125.901196)
		(end 125.778768 -125.4506)
		(width 0.14224)
		(layer "In4.Cu")
		(net "M_M_DQ<40>")
	)
	(segment
		(start 114.837972 -104.148636)
		(end 114.842798 -104.14)
		(width 0.0889)
		(layer "In4.Cu")
		(net "M_M_DQ<40>")
	)
	(segment
		(start 126.274576 -134.428992)
		(end 126.274576 -134.176008)
		(width 0.14224)
		(layer "In4.Cu")
		(net "M_M_DQ<40>")
	)
	(segment
		(start 123.91771 -122.84837)
		(end 117.754654 -116.685314)
		(width 0.14224)
		(layer "In4.Cu")
		(net "M_M_DQ<40>")
	)
	(segment
		(start 125.778768 -124.358654)
		(end 124.268484 -122.84837)
		(width 0.14224)
		(layer "In4.Cu")
		(net "M_M_DQ<40>")
	)
	(segment
		(start 125.778768 -125.4506)
		(end 125.778768 -124.358654)
		(width 0.14224)
		(layer "In4.Cu")
		(net "M_M_DQ<40>")
	)
	(segment
		(start 126.223776 -144.080738)
		(end 126.223776 -143.751808)
		(width 0.14224)
		(layer "In4.Cu")
		(net "M_M_DQ<40>")
	)
	(segment
		(start 114.837972 -95.23349)
		(end 114.96929 -95.005906)
		(width 0.0889)
		(layer "In4.Cu")
		(net "M_M_DQ<40>")
	)
	(segment
		(start 126.108968 -132.067808)
		(end 126.274576 -131.9022)
		(width 0.14224)
		(layer "In4.Cu")
		(net "M_M_DQ<40>")
	)
	(segment
		(start 126.229364 -129.216404)
		(end 126.591568 -128.8542)
		(width 0.14224)
		(layer "In4.Cu")
		(net "M_M_DQ<40>")
	)
	(segment
		(start 126.185168 -143.7132)
		(end 126.185168 -141.592808)
		(width 0.14224)
		(layer "In4.Cu")
		(net "M_M_DQ<40>")
	)
	(segment
		(start 126.274576 -136.5758)
		(end 126.274576 -136.284208)
		(width 0.14224)
		(layer "In4.Cu")
		(net "M_M_DQ<40>")
	)
	(segment
		(start 117.754654 -116.685314)
		(end 117.754654 -115.674648)
		(width 0.14224)
		(layer "In4.Cu")
		(net "M_M_DQ<40>")
	)
	(segment
		(start 114.837972 -102.167436)
		(end 114.842798 -102.1588)
		(width 0.0889)
		(layer "In4.Cu")
		(net "M_M_DQ<40>")
	)
	(segment
		(start 126.274576 -138.773408)
		(end 126.007368 -138.5062)
		(width 0.14224)
		(layer "In4.Cu")
		(net "M_M_DQ<40>")
	)
	(segment
		(start 114.831622 -102.178104)
		(end 114.837972 -102.167436)
		(width 0.0889)
		(layer "In4.Cu")
		(net "M_M_DQ<40>")
	)
	(segment
		(start 125.749558 -149.446996)
		(end 126.236476 -148.960078)
		(width 0.14224)
		(layer "In4.Cu")
		(net "M_M_DQ<40>")
	)
	(segment
		(start 114.837972 -101.176836)
		(end 114.842798 -101.1682)
		(width 0.0889)
		(layer "In4.Cu")
		(net "M_M_DQ<40>")
	)
	(segment
		(start 126.274576 -136.284208)
		(end 125.931676 -135.941308)
		(width 0.14224)
		(layer "In4.Cu")
		(net "M_M_DQ<40>")
	)
	(segment
		(start 126.235968 -141.04747)
		(end 125.931676 -140.743178)
		(width 0.14224)
		(layer "In4.Cu")
		(net "M_M_DQ<40>")
	)
	(segment
		(start 126.591568 -128.8542)
		(end 126.591568 -127.263144)
		(width 0.14224)
		(layer "In4.Cu")
		(net "M_M_DQ<40>")
	)
	(segment
		(start 126.229364 -129.76479)
		(end 126.229364 -129.216404)
		(width 0.14224)
		(layer "In4.Cu")
		(net "M_M_DQ<40>")
	)
	(segment
		(start 125.931676 -134.771892)
		(end 126.274576 -134.428992)
		(width 0.14224)
		(layer "In4.Cu")
		(net "M_M_DQ<40>")
	)
	(segment
		(start 126.108968 -134.0104)
		(end 126.108968 -132.067808)
		(width 0.14224)
		(layer "In4.Cu")
		(net "M_M_DQ<40>")
	)
	(segment
		(start 126.274576 -134.176008)
		(end 126.108968 -134.0104)
		(width 0.14224)
		(layer "In4.Cu")
		(net "M_M_DQ<40>")
	)
	(segment
		(start 125.931676 -135.941308)
		(end 125.931676 -134.771892)
		(width 0.14224)
		(layer "In4.Cu")
		(net "M_M_DQ<40>")
	)
	(segment
		(start 115.377468 -107.191556)
		(end 115.6208 -106.948224)
		(width 0.0889)
		(layer "In4.Cu")
		(net "M_M_DQ<40>")
	)
	(segment
		(start 114.837972 -105.139236)
		(end 114.842798 -105.1306)
		(width 0.0889)
		(layer "In4.Cu")
		(net "M_M_DQ<40>")
	)
	(segment
		(start 115.6208 -106.948224)
		(end 115.6208 -106.67746)
		(width 0.0889)
		(layer "In4.Cu")
		(net "M_M_DQ<40>")
	)
	(segment
		(start 126.274576 -131.484878)
		(end 125.931676 -131.141978)
		(width 0.14224)
		(layer "In4.Cu")
		(net "M_M_DQ<40>")
	)
	(segment
		(start 125.931676 -140.743178)
		(end 125.931676 -139.663678)
		(width 0.14224)
		(layer "In4.Cu")
		(net "M_M_DQ<40>")
	)
	(segment
		(start 114.831622 -104.159304)
		(end 114.837972 -104.148636)
		(width 0.0889)
		(layer "In4.Cu")
		(net "M_M_DQ<40>")
	)
	(segment
		(start 126.223776 -143.751808)
		(end 126.185168 -143.7132)
		(width 0.14224)
		(layer "In4.Cu")
		(net "M_M_DQ<40>")
	)
	(segment
		(start 125.931676 -139.663678)
		(end 126.274576 -139.320778)
		(width 0.14224)
		(layer "In4.Cu")
		(net "M_M_DQ<40>")
	)
	(segment
		(start 126.007368 -138.5062)
		(end 126.007368 -136.843008)
		(width 0.14224)
		(layer "In4.Cu")
		(net "M_M_DQ<40>")
	)
	(segment
		(start 117.754654 -115.674648)
		(end 115.377468 -113.297462)
		(width 0.14224)
		(layer "In4.Cu")
		(net "M_M_DQ<40>")
	)
	(segment
		(start 114.837972 -100.186236)
		(end 114.842798 -100.1776)
		(width 0.0889)
		(layer "In4.Cu")
		(net "M_M_DQ<40>")
	)
	(segment
		(start 126.274576 -131.9022)
		(end 126.274576 -131.484878)
		(width 0.14224)
		(layer "In4.Cu")
		(net "M_M_DQ<40>")
	)
	(segment
		(start 125.931676 -131.141978)
		(end 125.931676 -130.062478)
		(width 0.14224)
		(layer "In4.Cu")
		(net "M_M_DQ<40>")
	)
	(segment
		(start 125.944376 -144.360138)
		(end 126.223776 -144.080738)
		(width 0.14224)
		(layer "In4.Cu")
		(net "M_M_DQ<40>")
	)
	(arc
		(start 114.837972 -97.21469)
		(mid 114.891471 -97.014792)
		(end 114.837972 -96.814894)
		(width 0.0889)
		(layer "In4.Cu")
		(net "M_M_DQ<40>")
	)
	(arc
		(start 114.837972 -100.776786)
		(mid 114.75875 -100.487668)
		(end 114.831622 -100.196904)
		(width 0.0889)
		(layer "In4.Cu")
		(net "M_M_DQ<40>")
	)
	(arc
		(start 114.837972 -96.22409)
		(mid 114.891471 -96.024192)
		(end 114.837972 -95.824294)
		(width 0.0889)
		(layer "In4.Cu")
		(net "M_M_DQ<40>")
	)
	(arc
		(start 114.837972 -95.824294)
		(mid 114.758841 -95.528892)
		(end 114.837972 -95.23349)
		(width 0.0889)
		(layer "In4.Cu")
		(net "M_M_DQ<40>")
	)
	(arc
		(start 114.842798 -103.1494)
		(mid 114.891553 -102.953048)
		(end 114.837972 -102.757986)
		(width 0.0889)
		(layer "In4.Cu")
		(net "M_M_DQ<40>")
	)
	(arc
		(start 114.837972 -103.748586)
		(mid 114.75875 -103.459468)
		(end 114.831622 -103.168704)
		(width 0.0889)
		(layer "In4.Cu")
		(net "M_M_DQ<40>")
	)
	(arc
		(start 114.837972 -98.20529)
		(mid 114.891471 -98.005392)
		(end 114.837972 -97.805494)
		(width 0.0889)
		(layer "In4.Cu")
		(net "M_M_DQ<40>")
	)
	(arc
		(start 114.837972 -96.814894)
		(mid 114.758841 -96.519492)
		(end 114.837972 -96.22409)
		(width 0.0889)
		(layer "In4.Cu")
		(net "M_M_DQ<40>")
	)
	(arc
		(start 114.842798 -101.1682)
		(mid 114.891553 -100.971848)
		(end 114.837972 -100.776786)
		(width 0.0889)
		(layer "In4.Cu")
		(net "M_M_DQ<40>")
	)
	(arc
		(start 114.842798 -105.1306)
		(mid 114.891553 -104.934248)
		(end 114.837972 -104.739186)
		(width 0.0889)
		(layer "In4.Cu")
		(net "M_M_DQ<40>")
	)
	(arc
		(start 114.857276 -99.824286)
		(mid 114.848164 -99.805213)
		(end 114.837972 -99.786694)
		(width 0.0889)
		(layer "In4.Cu")
		(net "M_M_DQ<40>")
	)
	(arc
		(start 114.837972 -104.739186)
		(mid 114.75875 -104.450068)
		(end 114.831622 -104.159304)
		(width 0.0889)
		(layer "In4.Cu")
		(net "M_M_DQ<40>")
	)
	(arc
		(start 114.837972 -97.805494)
		(mid 114.758841 -97.510092)
		(end 114.837972 -97.21469)
		(width 0.0889)
		(layer "In4.Cu")
		(net "M_M_DQ<40>")
	)
	(arc
		(start 114.837972 -102.757986)
		(mid 114.75875 -102.468868)
		(end 114.831622 -102.178104)
		(width 0.0889)
		(layer "In4.Cu")
		(net "M_M_DQ<40>")
	)
	(arc
		(start 114.837972 -99.19589)
		(mid 114.891471 -98.995992)
		(end 114.837972 -98.796094)
		(width 0.0889)
		(layer "In4.Cu")
		(net "M_M_DQ<40>")
	)
	(arc
		(start 114.837972 -98.796094)
		(mid 114.758841 -98.500692)
		(end 114.837972 -98.20529)
		(width 0.0889)
		(layer "In4.Cu")
		(net "M_M_DQ<40>")
	)
	(arc
		(start 114.837972 -101.767386)
		(mid 114.75875 -101.478268)
		(end 114.831622 -101.187504)
		(width 0.0889)
		(layer "In4.Cu")
		(net "M_M_DQ<40>")
	)
	(arc
		(start 114.984784 -94.702376)
		(mid 115.013649 -94.856011)
		(end 114.96929 -95.005906)
		(width 0.0889)
		(layer "In4.Cu")
		(net "M_M_DQ<40>")
	)
	(arc
		(start 115.6208 -106.67746)
		(mid 115.705536 -106.265733)
		(end 115.360958 -106.024934)
		(width 0.0889)
		(layer "In4.Cu")
		(net "M_M_DQ<40>")
	)
	(arc
		(start 114.842798 -104.14)
		(mid 114.891553 -103.943648)
		(end 114.837972 -103.748586)
		(width 0.0889)
		(layer "In4.Cu")
		(net "M_M_DQ<40>")
	)
	(arc
		(start 115.06073 -94.200726)
		(mid 115.036251 -94.271381)
		(end 115.003072 -94.338394)
		(width 0.0889)
		(layer "In4.Cu")
		(net "M_M_DQ<40>")
	)
	(arc
		(start 114.837972 -99.786694)
		(mid 114.758841 -99.491292)
		(end 114.837972 -99.19589)
		(width 0.0889)
		(layer "In4.Cu")
		(net "M_M_DQ<40>")
	)
	(arc
		(start 115.003072 -94.338394)
		(mid 114.950079 -94.518185)
		(end 114.984784 -94.702376)
		(width 0.0889)
		(layer "In4.Cu")
		(net "M_M_DQ<40>")
	)
	(arc
		(start 114.842798 -100.1776)
		(mid 114.891128 -100.002637)
		(end 114.857276 -99.824286)
		(width 0.0889)
		(layer "In4.Cu")
		(net "M_M_DQ<40>")
	)
	(arc
		(start 114.842798 -102.1588)
		(mid 114.891553 -101.962448)
		(end 114.837972 -101.767386)
		(width 0.0889)
		(layer "In4.Cu")
		(net "M_M_DQ<40>")
	)
	(arc
		(start 115.328192 -106.024934)
		(mid 114.835802 -105.726001)
		(end 114.831622 -105.149904)
		(width 0.0889)
		(layer "In4.Cu")
		(net "M_M_DQ<40>")
	)
	(segment
		(start 126.515368 -155.2448)
		(end 125.316488 -154.04592)
		(width 0.14224)
		(layer "In11.Cu")
		(net "M_M_DQ<40>")
	)
	(segment
		(start 125.316488 -151.247348)
		(end 125.749558 -150.814278)
		(width 0.14224)
		(layer "In11.Cu")
		(net "M_M_DQ<40>")
	)
	(segment
		(start 125.316488 -154.04592)
		(end 125.316488 -151.247348)
		(width 0.14224)
		(layer "In11.Cu")
		(net "M_M_DQ<40>")
	)
	(segment
		(start 39.049452 -152.273)
		(end 39.049452 -153.542746)
		(width 0.1651)
		(layer "F.Cu")
		(net "M_M_DQ<3>")
	)
	(segment
		(start 75.475846 -87.784686)
		(end 74.904346 -87.784686)
		(width 0.1651)
		(layer "F.Cu")
		(net "M_M_DQ<3>")
	)
	(via
		(at 74.904346 -87.784686)
		(size 0.508)
		(drill 0.254)
		(layers "F.Cu" "B.Cu")
		(net "M_M_DQ<3>")
	)
	(via
		(at 39.049452 -153.542746)
		(size 0.508)
		(drill 0.254)
		(layers "F.Cu" "B.Cu")
		(net "M_M_DQ<3>")
	)
	(via
		(at 39.899336 -149.533356)
		(size 0.508)
		(drill 0.254)
		(layers "F.Cu" "B.Cu")
		(net "M_M_DQ<3>")
	)
	(segment
		(start 39.899336 -147.478496)
		(end 39.899336 -149.533356)
		(width 0.1651)
		(layer "B.Cu")
		(net "M_M_DQ<3>")
	)
	(segment
		(start 72.346566 -88.87079)
		(end 72.3138 -88.87079)
		(width 0.0889)
		(layer "In11.Cu")
		(net "M_M_DQ<3>")
	)
	(segment
		(start 40.460168 -146.738848)
		(end 40.460168 -147.697952)
		(width 0.14224)
		(layer "In11.Cu")
		(net "M_M_DQ<3>")
	)
	(segment
		(start 40.26662 -143.2052)
		(end 40.26662 -144.182338)
		(width 0.14224)
		(layer "In11.Cu")
		(net "M_M_DQ<3>")
	)
	(segment
		(start 40.07993 -127.354838)
		(end 40.07993 -129.786888)
		(width 0.14224)
		(layer "In11.Cu")
		(net "M_M_DQ<3>")
	)
	(segment
		(start 68.057776 -91.347036)
		(end 67.777106 -91.347036)
		(width 0.0889)
		(layer "In11.Cu")
		(net "M_M_DQ<3>")
	)
	(segment
		(start 40.636952 -126.297436)
		(end 40.636952 -126.797816)
		(width 0.14224)
		(layer "In11.Cu")
		(net "M_M_DQ<3>")
	)
	(segment
		(start 45.40885 -112.119664)
		(end 40.333168 -117.195346)
		(width 0.14224)
		(layer "In11.Cu")
		(net "M_M_DQ<3>")
	)
	(segment
		(start 40.636952 -123.555252)
		(end 40.333168 -123.859036)
		(width 0.14224)
		(layer "In11.Cu")
		(net "M_M_DQ<3>")
	)
	(segment
		(start 40.460168 -147.697952)
		(end 40.22852 -147.9296)
		(width 0.14224)
		(layer "In11.Cu")
		(net "M_M_DQ<3>")
	)
	(segment
		(start 63.537338 -92.057474)
		(end 63.29807 -92.296742)
		(width 0.0889)
		(layer "In11.Cu")
		(net "M_M_DQ<3>")
	)
	(segment
		(start 39.49319 -151.1046)
		(end 39.210742 -151.387048)
		(width 0.14224)
		(layer "In11.Cu")
		(net "M_M_DQ<3>")
	)
	(segment
		(start 40.460168 -132.485384)
		(end 40.460168 -132.856224)
		(width 0.14224)
		(layer "In11.Cu")
		(net "M_M_DQ<3>")
	)
	(segment
		(start 40.07993 -129.786888)
		(end 40.40632 -130.113278)
		(width 0.14224)
		(layer "In11.Cu")
		(net "M_M_DQ<3>")
	)
	(segment
		(start 67.777106 -91.347036)
		(end 67.504056 -91.620086)
		(width 0.0889)
		(layer "In11.Cu")
		(net "M_M_DQ<3>")
	)
	(segment
		(start 39.899336 -149.546564)
		(end 39.899336 -149.533356)
		(width 0.14224)
		(layer "In11.Cu")
		(net "M_M_DQ<3>")
	)
	(segment
		(start 40.26662 -141.009878)
		(end 40.26662 -141.9352)
		(width 0.14224)
		(layer "In11.Cu")
		(net "M_M_DQ<3>")
	)
	(segment
		(start 40.22852 -145.799048)
		(end 40.22852 -146.5072)
		(width 0.14224)
		(layer "In11.Cu")
		(net "M_M_DQ<3>")
	)
	(segment
		(start 39.876984 -149.533356)
		(end 39.44874 -149.9616)
		(width 0.14224)
		(layer "In11.Cu")
		(net "M_M_DQ<3>")
	)
	(segment
		(start 40.636952 -118.169436)
		(end 40.636952 -118.678452)
		(width 0.14224)
		(layer "In11.Cu")
		(net "M_M_DQ<3>")
	)
	(segment
		(start 63.29807 -92.296742)
		(end 63.098426 -92.296742)
		(width 0.14224)
		(layer "In11.Cu")
		(net "M_M_DQ<3>")
	)
	(segment
		(start 39.210742 -151.660352)
		(end 39.46779 -151.9174)
		(width 0.14224)
		(layer "In11.Cu")
		(net "M_M_DQ<3>")
	)
	(segment
		(start 39.899336 -149.533356)
		(end 39.876984 -149.533356)
		(width 0.14224)
		(layer "In11.Cu")
		(net "M_M_DQ<3>")
	)
	(segment
		(start 40.180768 -131.49453)
		(end 40.180768 -132.205984)
		(width 0.14224)
		(layer "In11.Cu")
		(net "M_M_DQ<3>")
	)
	(segment
		(start 71.491856 -89.365836)
		(end 71.45909 -89.365836)
		(width 0.0889)
		(layer "In11.Cu")
		(net "M_M_DQ<3>")
	)
	(segment
		(start 39.46779 -151.9174)
		(end 39.46779 -152.2222)
		(width 0.14224)
		(layer "In11.Cu")
		(net "M_M_DQ<3>")
	)
	(segment
		(start 40.636952 -120.304052)
		(end 40.333168 -120.607836)
		(width 0.14224)
		(layer "In11.Cu")
		(net "M_M_DQ<3>")
	)
	(segment
		(start 40.636952 -119.795036)
		(end 40.636952 -120.304052)
		(width 0.14224)
		(layer "In11.Cu")
		(net "M_M_DQ<3>")
	)
	(segment
		(start 46.230032 -111.298482)
		(end 45.942504 -111.298482)
		(width 0.14224)
		(layer "In11.Cu")
		(net "M_M_DQ<3>")
	)
	(segment
		(start 39.210742 -152.752552)
		(end 39.49954 -153.04135)
		(width 0.14224)
		(layer "In11.Cu")
		(net "M_M_DQ<3>")
	)
	(segment
		(start 40.206168 -138.303)
		(end 40.206168 -139.514326)
		(width 0.14224)
		(layer "In11.Cu")
		(net "M_M_DQ<3>")
	)
	(segment
		(start 40.333168 -121.116852)
		(end 40.636952 -121.420636)
		(width 0.14224)
		(layer "In11.Cu")
		(net "M_M_DQ<3>")
	)
	(segment
		(start 45.080428 -110.436406)
		(end 44.7929 -110.436406)
		(width 0.14224)
		(layer "In11.Cu")
		(net "M_M_DQ<3>")
	)
	(segment
		(start 40.636952 -125.180852)
		(end 40.333168 -125.484636)
		(width 0.14224)
		(layer "In11.Cu")
		(net "M_M_DQ<3>")
	)
	(segment
		(start 40.48252 -145.545048)
		(end 40.22852 -145.799048)
		(width 0.14224)
		(layer "In11.Cu")
		(net "M_M_DQ<3>")
	)
	(segment
		(start 40.206168 -139.514326)
		(end 40.40632 -139.714478)
		(width 0.14224)
		(layer "In11.Cu")
		(net "M_M_DQ<3>")
	)
	(segment
		(start 44.834048 -111.544862)
		(end 45.121576 -111.544862)
		(width 0.14224)
		(layer "In11.Cu")
		(net "M_M_DQ<3>")
	)
	(segment
		(start 56.563768 -100.964746)
		(end 46.230032 -111.298482)
		(width 0.14224)
		(layer "In11.Cu")
		(net "M_M_DQ<3>")
	)
	(segment
		(start 40.636952 -121.420636)
		(end 40.636952 -121.929652)
		(width 0.14224)
		(layer "In11.Cu")
		(net "M_M_DQ<3>")
	)
	(segment
		(start 40.333168 -117.195346)
		(end 40.333168 -117.865652)
		(width 0.14224)
		(layer "In11.Cu")
		(net "M_M_DQ<3>")
	)
	(segment
		(start 40.510968 -137.9982)
		(end 40.206168 -138.303)
		(width 0.14224)
		(layer "In11.Cu")
		(net "M_M_DQ<3>")
	)
	(segment
		(start 40.561768 -142.910052)
		(end 40.26662 -143.2052)
		(width 0.14224)
		(layer "In11.Cu")
		(net "M_M_DQ<3>")
	)
	(segment
		(start 74.081894 -87.88019)
		(end 74.03084 -87.88019)
		(width 0.0889)
		(layer "In11.Cu")
		(net "M_M_DQ<3>")
	)
	(segment
		(start 40.460168 -132.856224)
		(end 40.180768 -133.135624)
		(width 0.14224)
		(layer "In11.Cu")
		(net "M_M_DQ<3>")
	)
	(segment
		(start 40.333168 -123.859036)
		(end 40.333168 -124.368052)
		(width 0.14224)
		(layer "In11.Cu")
		(net "M_M_DQ<3>")
	)
	(segment
		(start 40.26662 -141.9352)
		(end 40.561768 -142.230348)
		(width 0.14224)
		(layer "In11.Cu")
		(net "M_M_DQ<3>")
	)
	(segment
		(start 40.180768 -134.487412)
		(end 40.43172 -134.738364)
		(width 0.14224)
		(layer "In11.Cu")
		(net "M_M_DQ<3>")
	)
	(segment
		(start 40.636952 -121.929652)
		(end 40.333168 -122.233436)
		(width 0.14224)
		(layer "In11.Cu")
		(net "M_M_DQ<3>")
	)
	(segment
		(start 39.49319 -150.435818)
		(end 39.49319 -151.1046)
		(width 0.14224)
		(layer "In11.Cu")
		(net "M_M_DQ<3>")
	)
	(segment
		(start 39.49954 -153.364946)
		(end 39.32174 -153.542746)
		(width 0.14224)
		(layer "In11.Cu")
		(net "M_M_DQ<3>")
	)
	(segment
		(start 44.7929 -110.436406)
		(end 40.355774 -114.873532)
		(width 0.14224)
		(layer "In11.Cu")
		(net "M_M_DQ<3>")
	)
	(segment
		(start 66.74612 -91.620086)
		(end 66.308732 -92.057474)
		(width 0.0889)
		(layer "In11.Cu")
		(net "M_M_DQ<3>")
	)
	(segment
		(start 56.563768 -98.8314)
		(end 56.563768 -100.964746)
		(width 0.14224)
		(layer "In11.Cu")
		(net "M_M_DQ<3>")
	)
	(segment
		(start 67.504056 -91.620086)
		(end 66.74612 -91.620086)
		(width 0.0889)
		(layer "In11.Cu")
		(net "M_M_DQ<3>")
	)
	(segment
		(start 40.40632 -130.113278)
		(end 40.40632 -131.268978)
		(width 0.14224)
		(layer "In11.Cu")
		(net "M_M_DQ<3>")
	)
	(segment
		(start 40.333168 -117.865652)
		(end 40.636952 -118.169436)
		(width 0.14224)
		(layer "In11.Cu")
		(net "M_M_DQ<3>")
	)
	(segment
		(start 40.636952 -118.678452)
		(end 40.333168 -118.982236)
		(width 0.14224)
		(layer "In11.Cu")
		(net "M_M_DQ<3>")
	)
	(segment
		(start 40.636952 -123.046236)
		(end 40.636952 -123.555252)
		(width 0.14224)
		(layer "In11.Cu")
		(net "M_M_DQ<3>")
	)
	(segment
		(start 45.121576 -111.544862)
		(end 45.40885 -111.832136)
		(width 0.14224)
		(layer "In11.Cu")
		(net "M_M_DQ<3>")
	)
	(segment
		(start 40.180768 -133.135624)
		(end 40.180768 -134.487412)
		(width 0.14224)
		(layer "In11.Cu")
		(net "M_M_DQ<3>")
	)
	(segment
		(start 40.355774 -115.16106)
		(end 40.643048 -115.448334)
		(width 0.14224)
		(layer "In11.Cu")
		(net "M_M_DQ<3>")
	)
	(segment
		(start 39.44874 -149.9616)
		(end 39.44874 -150.391368)
		(width 0.14224)
		(layer "In11.Cu")
		(net "M_M_DQ<3>")
	)
	(segment
		(start 40.40632 -131.268978)
		(end 40.180768 -131.49453)
		(width 0.14224)
		(layer "In11.Cu")
		(net "M_M_DQ<3>")
	)
	(segment
		(start 73.208896 -88.375236)
		(end 73.17613 -88.375236)
		(width 0.0889)
		(layer "In11.Cu")
		(net "M_M_DQ<3>")
	)
	(segment
		(start 39.46779 -152.2222)
		(end 39.210742 -152.479248)
		(width 0.14224)
		(layer "In11.Cu")
		(net "M_M_DQ<3>")
	)
	(segment
		(start 40.40632 -140.870178)
		(end 40.26662 -141.009878)
		(width 0.14224)
		(layer "In11.Cu")
		(net "M_M_DQ<3>")
	)
	(segment
		(start 40.333168 -119.491252)
		(end 40.636952 -119.795036)
		(width 0.14224)
		(layer "In11.Cu")
		(net "M_M_DQ<3>")
	)
	(segment
		(start 40.22852 -147.9296)
		(end 40.22852 -149.21738)
		(width 0.14224)
		(layer "In11.Cu")
		(net "M_M_DQ<3>")
	)
	(segment
		(start 40.561768 -142.230348)
		(end 40.561768 -142.910052)
		(width 0.14224)
		(layer "In11.Cu")
		(net "M_M_DQ<3>")
	)
	(segment
		(start 40.333168 -122.233436)
		(end 40.333168 -122.742452)
		(width 0.14224)
		(layer "In11.Cu")
		(net "M_M_DQ<3>")
	)
	(segment
		(start 40.180768 -132.205984)
		(end 40.460168 -132.485384)
		(width 0.14224)
		(layer "In11.Cu")
		(net "M_M_DQ<3>")
	)
	(segment
		(start 40.333168 -125.993652)
		(end 40.636952 -126.297436)
		(width 0.14224)
		(layer "In11.Cu")
		(net "M_M_DQ<3>")
	)
	(segment
		(start 40.206168 -137.0584)
		(end 40.510968 -137.3632)
		(width 0.14224)
		(layer "In11.Cu")
		(net "M_M_DQ<3>")
	)
	(segment
		(start 70.629526 -89.86139)
		(end 70.59676 -89.86139)
		(width 0.0889)
		(layer "In11.Cu")
		(net "M_M_DQ<3>")
	)
	(segment
		(start 40.643048 -115.448334)
		(end 40.930576 -115.448334)
		(width 0.14224)
		(layer "In11.Cu")
		(net "M_M_DQ<3>")
	)
	(segment
		(start 40.333168 -120.607836)
		(end 40.333168 -121.116852)
		(width 0.14224)
		(layer "In11.Cu")
		(net "M_M_DQ<3>")
	)
	(segment
		(start 40.636952 -126.797816)
		(end 40.07993 -127.354838)
		(width 0.14224)
		(layer "In11.Cu")
		(net "M_M_DQ<3>")
	)
	(segment
		(start 40.48252 -144.398238)
		(end 40.48252 -145.545048)
		(width 0.14224)
		(layer "In11.Cu")
		(net "M_M_DQ<3>")
	)
	(segment
		(start 66.308732 -92.057474)
		(end 63.537338 -92.057474)
		(width 0.0889)
		(layer "In11.Cu")
		(net "M_M_DQ<3>")
	)
	(segment
		(start 45.40885 -111.832136)
		(end 45.40885 -112.119664)
		(width 0.14224)
		(layer "In11.Cu")
		(net "M_M_DQ<3>")
	)
	(segment
		(start 63.098426 -92.296742)
		(end 56.563768 -98.8314)
		(width 0.14224)
		(layer "In11.Cu")
		(net "M_M_DQ<3>")
	)
	(segment
		(start 40.40632 -139.714478)
		(end 40.40632 -140.870178)
		(width 0.14224)
		(layer "In11.Cu")
		(net "M_M_DQ<3>")
	)
	(segment
		(start 39.44874 -150.391368)
		(end 39.49319 -150.435818)
		(width 0.14224)
		(layer "In11.Cu")
		(net "M_M_DQ<3>")
	)
	(segment
		(start 40.355774 -114.873532)
		(end 40.355774 -115.16106)
		(width 0.14224)
		(layer "In11.Cu")
		(net "M_M_DQ<3>")
	)
	(segment
		(start 40.333168 -118.982236)
		(end 40.333168 -119.491252)
		(width 0.14224)
		(layer "In11.Cu")
		(net "M_M_DQ<3>")
	)
	(segment
		(start 40.43172 -136.070848)
		(end 40.206168 -136.2964)
		(width 0.14224)
		(layer "In11.Cu")
		(net "M_M_DQ<3>")
	)
	(segment
		(start 40.26662 -144.182338)
		(end 40.48252 -144.398238)
		(width 0.14224)
		(layer "In11.Cu")
		(net "M_M_DQ<3>")
	)
	(segment
		(start 40.43172 -134.738364)
		(end 40.43172 -136.070848)
		(width 0.14224)
		(layer "In11.Cu")
		(net "M_M_DQ<3>")
	)
	(segment
		(start 39.49954 -153.04135)
		(end 39.49954 -153.364946)
		(width 0.14224)
		(layer "In11.Cu")
		(net "M_M_DQ<3>")
	)
	(segment
		(start 40.22852 -146.5072)
		(end 40.460168 -146.738848)
		(width 0.14224)
		(layer "In11.Cu")
		(net "M_M_DQ<3>")
	)
	(segment
		(start 40.22852 -149.21738)
		(end 39.899336 -149.546564)
		(width 0.14224)
		(layer "In11.Cu")
		(net "M_M_DQ<3>")
	)
	(segment
		(start 74.904346 -87.784686)
		(end 74.081894 -87.88019)
		(width 0.0889)
		(layer "In11.Cu")
		(net "M_M_DQ<3>")
	)
	(segment
		(start 69.774816 -90.356436)
		(end 69.74205 -90.356436)
		(width 0.0889)
		(layer "In11.Cu")
		(net "M_M_DQ<3>")
	)
	(segment
		(start 40.636952 -124.671836)
		(end 40.636952 -125.180852)
		(width 0.14224)
		(layer "In11.Cu")
		(net "M_M_DQ<3>")
	)
	(segment
		(start 40.930576 -115.448334)
		(end 44.834048 -111.544862)
		(width 0.14224)
		(layer "In11.Cu")
		(net "M_M_DQ<3>")
	)
	(segment
		(start 40.333168 -124.368052)
		(end 40.636952 -124.671836)
		(width 0.14224)
		(layer "In11.Cu")
		(net "M_M_DQ<3>")
	)
	(segment
		(start 45.942504 -111.298482)
		(end 45.080428 -110.436406)
		(width 0.14224)
		(layer "In11.Cu")
		(net "M_M_DQ<3>")
	)
	(segment
		(start 40.510968 -137.3632)
		(end 40.510968 -137.9982)
		(width 0.14224)
		(layer "In11.Cu")
		(net "M_M_DQ<3>")
	)
	(segment
		(start 39.210742 -151.387048)
		(end 39.210742 -151.660352)
		(width 0.14224)
		(layer "In11.Cu")
		(net "M_M_DQ<3>")
	)
	(segment
		(start 40.333168 -125.484636)
		(end 40.333168 -125.993652)
		(width 0.14224)
		(layer "In11.Cu")
		(net "M_M_DQ<3>")
	)
	(segment
		(start 40.206168 -136.2964)
		(end 40.206168 -137.0584)
		(width 0.14224)
		(layer "In11.Cu")
		(net "M_M_DQ<3>")
	)
	(segment
		(start 39.32174 -153.542746)
		(end 39.049452 -153.542746)
		(width 0.14224)
		(layer "In11.Cu")
		(net "M_M_DQ<3>")
	)
	(segment
		(start 39.210742 -152.479248)
		(end 39.210742 -152.752552)
		(width 0.14224)
		(layer "In11.Cu")
		(net "M_M_DQ<3>")
	)
	(segment
		(start 40.333168 -122.742452)
		(end 40.636952 -123.046236)
		(width 0.14224)
		(layer "In11.Cu")
		(net "M_M_DQ<3>")
	)
	(arc
		(start 68.838826 -90.855546)
		(mid 68.670583 -90.91993)
		(end 68.547996 -91.051888)
		(width 0.0889)
		(layer "In11.Cu")
		(net "M_M_DQ<3>")
	)
	(arc
		(start 68.547996 -91.051888)
		(mid 68.340992 -91.262752)
		(end 68.057776 -91.347036)
		(width 0.0889)
		(layer "In11.Cu")
		(net "M_M_DQ<3>")
	)
	(arc
		(start 68.96608 -90.847926)
		(mid 68.90257 -90.853692)
		(end 68.838826 -90.855546)
		(width 0.0889)
		(layer "In11.Cu")
		(net "M_M_DQ<3>")
	)
	(arc
		(start 73.17613 -88.375236)
		(mid 72.98228 -88.431586)
		(end 72.840596 -88.575388)
		(width 0.0889)
		(layer "In11.Cu")
		(net "M_M_DQ<3>")
	)
	(arc
		(start 71.123556 -89.565988)
		(mid 70.914948 -89.77792)
		(end 70.629526 -89.86139)
		(width 0.0889)
		(layer "In11.Cu")
		(net "M_M_DQ<3>")
	)
	(arc
		(start 69.74205 -90.356436)
		(mid 69.5482 -90.412786)
		(end 69.406516 -90.556588)
		(width 0.0889)
		(layer "In11.Cu")
		(net "M_M_DQ<3>")
	)
	(arc
		(start 72.840596 -88.575388)
		(mid 72.631988 -88.78732)
		(end 72.346566 -88.87079)
		(width 0.0889)
		(layer "In11.Cu")
		(net "M_M_DQ<3>")
	)
	(arc
		(start 69.406516 -90.556588)
		(mid 69.22065 -90.754204)
		(end 68.96608 -90.847926)
		(width 0.0889)
		(layer "In11.Cu")
		(net "M_M_DQ<3>")
	)
	(arc
		(start 70.265036 -90.061288)
		(mid 70.058032 -90.272152)
		(end 69.774816 -90.356436)
		(width 0.0889)
		(layer "In11.Cu")
		(net "M_M_DQ<3>")
	)
	(arc
		(start 73.699116 -88.080088)
		(mid 73.492112 -88.290952)
		(end 73.208896 -88.375236)
		(width 0.0889)
		(layer "In11.Cu")
		(net "M_M_DQ<3>")
	)
	(arc
		(start 74.03084 -87.88019)
		(mid 73.839198 -87.937356)
		(end 73.699116 -88.080088)
		(width 0.0889)
		(layer "In11.Cu")
		(net "M_M_DQ<3>")
	)
	(arc
		(start 70.59676 -89.86139)
		(mid 70.405118 -89.918556)
		(end 70.265036 -90.061288)
		(width 0.0889)
		(layer "In11.Cu")
		(net "M_M_DQ<3>")
	)
	(arc
		(start 72.3138 -88.87079)
		(mid 72.122158 -88.927956)
		(end 71.982076 -89.070688)
		(width 0.0889)
		(layer "In11.Cu")
		(net "M_M_DQ<3>")
	)
	(arc
		(start 71.982076 -89.070688)
		(mid 71.775072 -89.281552)
		(end 71.491856 -89.365836)
		(width 0.0889)
		(layer "In11.Cu")
		(net "M_M_DQ<3>")
	)
	(arc
		(start 71.45909 -89.365836)
		(mid 71.26524 -89.422186)
		(end 71.123556 -89.565988)
		(width 0.0889)
		(layer "In11.Cu")
		(net "M_M_DQ<3>")
	)
	(segment
		(start 109.627416 -94.538038)
		(end 110.198916 -94.538038)
		(width 0.1651)
		(layer "F.Cu")
		(net "M_M_DQ<39>")
	)
	(segment
		(start 120.649492 -152.273)
		(end 120.649492 -153.542746)
		(width 0.1651)
		(layer "F.Cu")
		(net "M_M_DQ<39>")
	)
	(via
		(at 120.649492 -153.542746)
		(size 0.508)
		(drill 0.254)
		(layers "F.Cu" "B.Cu")
		(net "M_M_DQ<39>")
	)
	(via
		(at 121.499376 -149.533356)
		(size 0.508)
		(drill 0.254)
		(layers "F.Cu" "B.Cu")
		(net "M_M_DQ<39>")
	)
	(via
		(at 110.198916 -94.538038)
		(size 0.508)
		(drill 0.254)
		(layers "F.Cu" "B.Cu")
		(net "M_M_DQ<39>")
	)
	(segment
		(start 121.499376 -147.478496)
		(end 121.499376 -149.533356)
		(width 0.1651)
		(layer "B.Cu")
		(net "M_M_DQ<39>")
	)
	(segment
		(start 121.852182 -146.177)
		(end 121.917968 -146.242786)
		(width 0.14224)
		(layer "In11.Cu")
		(net "M_M_DQ<39>")
	)
	(segment
		(start 121.877582 -131.9022)
		(end 121.917968 -131.942586)
		(width 0.14224)
		(layer "In11.Cu")
		(net "M_M_DQ<39>")
	)
	(segment
		(start 121.852182 -129.337054)
		(end 121.852182 -129.859278)
		(width 0.14224)
		(layer "In11.Cu")
		(net "M_M_DQ<39>")
	)
	(segment
		(start 121.517156 -125.048518)
		(end 121.387616 -125.178058)
		(width 0.14224)
		(layer "In11.Cu")
		(net "M_M_DQ<39>")
	)
	(segment
		(start 121.517156 -124.61494)
		(end 121.517156 -125.048518)
		(width 0.14224)
		(layer "In11.Cu")
		(net "M_M_DQ<39>")
	)
	(segment
		(start 121.720356 -127.321818)
		(end 121.720356 -127.674878)
		(width 0.14224)
		(layer "In11.Cu")
		(net "M_M_DQ<39>")
	)
	(segment
		(start 110.18393 -98.900234)
		(end 110.216696 -98.900234)
		(width 0.0889)
		(layer "In11.Cu")
		(net "M_M_DQ<39>")
	)
	(segment
		(start 121.179844 -126.503938)
		(end 121.024904 -126.658878)
		(width 0.14224)
		(layer "In11.Cu")
		(net "M_M_DQ<39>")
	)
	(segment
		(start 121.06783 -151.9174)
		(end 121.06783 -152.2222)
		(width 0.14224)
		(layer "In11.Cu")
		(net "M_M_DQ<39>")
	)
	(segment
		(start 121.852182 -136.260332)
		(end 121.852182 -136.5758)
		(width 0.14224)
		(layer "In11.Cu")
		(net "M_M_DQ<39>")
	)
	(segment
		(start 122.080782 -139.689078)
		(end 122.080782 -140.806678)
		(width 0.14224)
		(layer "In11.Cu")
		(net "M_M_DQ<39>")
	)
	(segment
		(start 121.801382 -141.5288)
		(end 121.917968 -141.645386)
		(width 0.14224)
		(layer "In11.Cu")
		(net "M_M_DQ<39>")
	)
	(segment
		(start 121.024904 -125.332998)
		(end 121.024904 -125.686058)
		(width 0.14224)
		(layer "In11.Cu")
		(net "M_M_DQ<39>")
	)
	(segment
		(start 121.565416 -126.503938)
		(end 121.179844 -126.503938)
		(width 0.14224)
		(layer "In11.Cu")
		(net "M_M_DQ<39>")
	)
	(segment
		(start 121.04878 -150.391368)
		(end 121.09323 -150.435818)
		(width 0.14224)
		(layer "In11.Cu")
		(net "M_M_DQ<39>")
	)
	(segment
		(start 109.858556 -97.299018)
		(end 109.852206 -97.309686)
		(width 0.0889)
		(layer "In11.Cu")
		(net "M_M_DQ<39>")
	)
	(segment
		(start 109.860842 -94.538038)
		(end 109.803184 -94.595696)
		(width 0.0889)
		(layer "In11.Cu")
		(net "M_M_DQ<39>")
	)
	(segment
		(start 109.858556 -98.289618)
		(end 109.852206 -98.300286)
		(width 0.0889)
		(layer "In11.Cu")
		(net "M_M_DQ<39>")
	)
	(segment
		(start 121.024904 -128.509776)
		(end 121.852182 -129.337054)
		(width 0.14224)
		(layer "In11.Cu")
		(net "M_M_DQ<39>")
	)
	(segment
		(start 121.877582 -144.169638)
		(end 122.021346 -144.313402)
		(width 0.14224)
		(layer "In11.Cu")
		(net "M_M_DQ<39>")
	)
	(segment
		(start 121.852182 -136.5758)
		(end 121.917968 -136.641586)
		(width 0.14224)
		(layer "In11.Cu")
		(net "M_M_DQ<39>")
	)
	(segment
		(start 122.080782 -130.087878)
		(end 122.080782 -131.205478)
		(width 0.14224)
		(layer "In11.Cu")
		(net "M_M_DQ<39>")
	)
	(segment
		(start 121.917968 -148.4122)
		(end 121.852182 -148.477986)
		(width 0.14224)
		(layer "In11.Cu")
		(net "M_M_DQ<39>")
	)
	(segment
		(start 120.810782 -152.752552)
		(end 121.09958 -153.04135)
		(width 0.14224)
		(layer "In11.Cu")
		(net "M_M_DQ<39>")
	)
	(segment
		(start 121.09323 -151.1046)
		(end 120.810782 -151.387048)
		(width 0.14224)
		(layer "In11.Cu")
		(net "M_M_DQ<39>")
	)
	(segment
		(start 122.055382 -134.757668)
		(end 122.055382 -136.057132)
		(width 0.14224)
		(layer "In11.Cu")
		(net "M_M_DQ<39>")
	)
	(segment
		(start 121.179844 -127.166878)
		(end 121.565416 -127.166878)
		(width 0.14224)
		(layer "In11.Cu")
		(net "M_M_DQ<39>")
	)
	(segment
		(start 121.917968 -134.0104)
		(end 121.877582 -134.050786)
		(width 0.14224)
		(layer "In11.Cu")
		(net "M_M_DQ<39>")
	)
	(segment
		(start 121.024904 -126.658878)
		(end 121.024904 -127.011938)
		(width 0.14224)
		(layer "In11.Cu")
		(net "M_M_DQ<39>")
	)
	(segment
		(start 110.710726 -99.195636)
		(end 110.714028 -99.201478)
		(width 0.0889)
		(layer "In11.Cu")
		(net "M_M_DQ<39>")
	)
	(segment
		(start 109.858556 -96.308418)
		(end 109.852206 -96.319086)
		(width 0.0889)
		(layer "In11.Cu")
		(net "M_M_DQ<39>")
	)
	(segment
		(start 122.021346 -144.313402)
		(end 122.021346 -145.641822)
		(width 0.14224)
		(layer "In11.Cu")
		(net "M_M_DQ<39>")
	)
	(segment
		(start 112.011968 -115.109752)
		(end 121.517156 -124.61494)
		(width 0.14224)
		(layer "In11.Cu")
		(net "M_M_DQ<39>")
	)
	(segment
		(start 111.895128 -99.89058)
		(end 111.937292 -99.89058)
		(width 0.0889)
		(layer "In11.Cu")
		(net "M_M_DQ<39>")
	)
	(segment
		(start 121.024904 -125.686058)
		(end 121.179844 -125.840998)
		(width 0.14224)
		(layer "In11.Cu")
		(net "M_M_DQ<39>")
	)
	(segment
		(start 121.852182 -129.859278)
		(end 122.080782 -130.087878)
		(width 0.14224)
		(layer "In11.Cu")
		(net "M_M_DQ<39>")
	)
	(segment
		(start 121.917968 -143.6878)
		(end 121.877582 -143.728186)
		(width 0.14224)
		(layer "In11.Cu")
		(net "M_M_DQ<39>")
	)
	(segment
		(start 121.024904 -127.984758)
		(end 121.024904 -128.509776)
		(width 0.14224)
		(layer "In11.Cu")
		(net "M_M_DQ<39>")
	)
	(segment
		(start 121.917968 -136.641586)
		(end 121.917968 -138.811)
		(width 0.14224)
		(layer "In11.Cu")
		(net "M_M_DQ<39>")
	)
	(segment
		(start 121.09958 -153.04135)
		(end 121.09958 -153.364946)
		(width 0.14224)
		(layer "In11.Cu")
		(net "M_M_DQ<39>")
	)
	(segment
		(start 121.720356 -127.674878)
		(end 121.565416 -127.829818)
		(width 0.14224)
		(layer "In11.Cu")
		(net "M_M_DQ<39>")
	)
	(segment
		(start 112.367568 -102.861364)
		(end 112.364774 -102.864158)
		(width 0.0889)
		(layer "In11.Cu")
		(net "M_M_DQ<39>")
	)
	(segment
		(start 109.852206 -94.737936)
		(end 109.858556 -94.748604)
		(width 0.0889)
		(layer "In11.Cu")
		(net "M_M_DQ<39>")
	)
	(segment
		(start 121.179844 -127.829818)
		(end 121.024904 -127.984758)
		(width 0.14224)
		(layer "In11.Cu")
		(net "M_M_DQ<39>")
	)
	(segment
		(start 121.09958 -153.364946)
		(end 120.92178 -153.542746)
		(width 0.14224)
		(layer "In11.Cu")
		(net "M_M_DQ<39>")
	)
	(segment
		(start 121.179844 -125.178058)
		(end 121.024904 -125.332998)
		(width 0.14224)
		(layer "In11.Cu")
		(net "M_M_DQ<39>")
	)
	(segment
		(start 110.198916 -94.538038)
		(end 109.860842 -94.538038)
		(width 0.0889)
		(layer "In11.Cu")
		(net "M_M_DQ<39>")
	)
	(segment
		(start 121.565416 -125.840998)
		(end 121.720356 -125.995938)
		(width 0.14224)
		(layer "In11.Cu")
		(net "M_M_DQ<39>")
	)
	(segment
		(start 121.84126 -149.191472)
		(end 121.499376 -149.533356)
		(width 0.14224)
		(layer "In11.Cu")
		(net "M_M_DQ<39>")
	)
	(segment
		(start 121.852182 -145.810986)
		(end 121.852182 -146.177)
		(width 0.14224)
		(layer "In11.Cu")
		(net "M_M_DQ<39>")
	)
	(segment
		(start 109.852206 -96.319086)
		(end 109.84738 -96.327722)
		(width 0.0889)
		(layer "In11.Cu")
		(net "M_M_DQ<39>")
	)
	(segment
		(start 112.427512 -100.776278)
		(end 112.422686 -100.784914)
		(width 0.0889)
		(layer "In11.Cu")
		(net "M_M_DQ<39>")
	)
	(segment
		(start 120.810782 -151.387048)
		(end 120.810782 -151.660352)
		(width 0.14224)
		(layer "In11.Cu")
		(net "M_M_DQ<39>")
	)
	(segment
		(start 112.291368 -103.36022)
		(end 112.291368 -105.3592)
		(width 0.14224)
		(layer "In11.Cu")
		(net "M_M_DQ<39>")
	)
	(segment
		(start 121.852182 -139.460478)
		(end 122.080782 -139.689078)
		(width 0.14224)
		(layer "In11.Cu")
		(net "M_M_DQ<39>")
	)
	(segment
		(start 120.810782 -151.660352)
		(end 121.06783 -151.9174)
		(width 0.14224)
		(layer "In11.Cu")
		(net "M_M_DQ<39>")
	)
	(segment
		(start 109.852206 -98.300286)
		(end 109.84738 -98.308922)
		(width 0.0889)
		(layer "In11.Cu")
		(net "M_M_DQ<39>")
	)
	(segment
		(start 121.801382 -141.086078)
		(end 121.801382 -141.5288)
		(width 0.14224)
		(layer "In11.Cu")
		(net "M_M_DQ<39>")
	)
	(segment
		(start 121.917968 -138.811)
		(end 121.852182 -138.876786)
		(width 0.14224)
		(layer "In11.Cu")
		(net "M_M_DQ<39>")
	)
	(segment
		(start 120.810782 -152.479248)
		(end 120.810782 -152.752552)
		(width 0.14224)
		(layer "In11.Cu")
		(net "M_M_DQ<39>")
	)
	(segment
		(start 121.499376 -149.533356)
		(end 121.477024 -149.533356)
		(width 0.14224)
		(layer "In11.Cu")
		(net "M_M_DQ<39>")
	)
	(segment
		(start 121.917968 -146.242786)
		(end 121.917968 -148.4122)
		(width 0.14224)
		(layer "In11.Cu")
		(net "M_M_DQ<39>")
	)
	(segment
		(start 121.09323 -150.435818)
		(end 121.09323 -151.1046)
		(width 0.14224)
		(layer "In11.Cu")
		(net "M_M_DQ<39>")
	)
	(segment
		(start 122.021346 -145.641822)
		(end 121.852182 -145.810986)
		(width 0.14224)
		(layer "In11.Cu")
		(net "M_M_DQ<39>")
	)
	(segment
		(start 121.387616 -125.178058)
		(end 121.179844 -125.178058)
		(width 0.14224)
		(layer "In11.Cu")
		(net "M_M_DQ<39>")
	)
	(segment
		(start 121.917968 -131.942586)
		(end 121.917968 -134.0104)
		(width 0.14224)
		(layer "In11.Cu")
		(net "M_M_DQ<39>")
	)
	(segment
		(start 121.877582 -143.728186)
		(end 121.877582 -144.169638)
		(width 0.14224)
		(layer "In11.Cu")
		(net "M_M_DQ<39>")
	)
	(segment
		(start 112.011968 -105.6386)
		(end 112.011968 -115.109752)
		(width 0.14224)
		(layer "In11.Cu")
		(net "M_M_DQ<39>")
	)
	(segment
		(start 109.852206 -97.309686)
		(end 109.84738 -97.318322)
		(width 0.0889)
		(layer "In11.Cu")
		(net "M_M_DQ<39>")
	)
	(segment
		(start 121.565416 -127.829818)
		(end 121.179844 -127.829818)
		(width 0.14224)
		(layer "In11.Cu")
		(net "M_M_DQ<39>")
	)
	(segment
		(start 121.024904 -127.011938)
		(end 121.179844 -127.166878)
		(width 0.14224)
		(layer "In11.Cu")
		(net "M_M_DQ<39>")
	)
	(segment
		(start 121.179844 -125.840998)
		(end 121.565416 -125.840998)
		(width 0.14224)
		(layer "In11.Cu")
		(net "M_M_DQ<39>")
	)
	(segment
		(start 121.06783 -152.2222)
		(end 120.857772 -152.432004)
		(width 0.14224)
		(layer "In11.Cu")
		(net "M_M_DQ<39>")
	)
	(segment
		(start 112.427512 -102.166928)
		(end 112.433862 -102.177596)
		(width 0.0889)
		(layer "In11.Cu")
		(net "M_M_DQ<39>")
	)
	(segment
		(start 121.852182 -138.876786)
		(end 121.852182 -139.460478)
		(width 0.14224)
		(layer "In11.Cu")
		(net "M_M_DQ<39>")
	)
	(segment
		(start 112.364774 -103.286814)
		(end 112.291368 -103.36022)
		(width 0.14224)
		(layer "In11.Cu")
		(net "M_M_DQ<39>")
	)
	(segment
		(start 121.852182 -148.477986)
		(end 121.852182 -149.191472)
		(width 0.14224)
		(layer "In11.Cu")
		(net "M_M_DQ<39>")
	)
	(segment
		(start 122.080782 -131.205478)
		(end 121.877582 -131.408678)
		(width 0.14224)
		(layer "In11.Cu")
		(net "M_M_DQ<39>")
	)
	(segment
		(start 121.720356 -125.995938)
		(end 121.720356 -126.348998)
		(width 0.14224)
		(layer "In11.Cu")
		(net "M_M_DQ<39>")
	)
	(segment
		(start 112.364774 -102.864158)
		(end 112.364774 -103.286814)
		(width 0.0889)
		(layer "In11.Cu")
		(net "M_M_DQ<39>")
	)
	(segment
		(start 120.92178 -153.542746)
		(end 120.649492 -153.542746)
		(width 0.14224)
		(layer "In11.Cu")
		(net "M_M_DQ<39>")
	)
	(segment
		(start 112.433862 -100.76561)
		(end 112.427512 -100.776278)
		(width 0.0889)
		(layer "In11.Cu")
		(net "M_M_DQ<39>")
	)
	(segment
		(start 122.055382 -136.057132)
		(end 121.852182 -136.260332)
		(width 0.14224)
		(layer "In11.Cu")
		(net "M_M_DQ<39>")
	)
	(segment
		(start 120.857772 -152.432004)
		(end 120.810782 -152.479248)
		(width 0.14224)
		(layer "In11.Cu")
		(net "M_M_DQ<39>")
	)
	(segment
		(start 111.057182 -99.395788)
		(end 111.078772 -99.395788)
		(width 0.0889)
		(layer "In11.Cu")
		(net "M_M_DQ<39>")
	)
	(segment
		(start 112.291368 -105.3592)
		(end 112.011968 -105.6386)
		(width 0.14224)
		(layer "In11.Cu")
		(net "M_M_DQ<39>")
	)
	(segment
		(start 121.04878 -149.9616)
		(end 121.04878 -150.391368)
		(width 0.14224)
		(layer "In11.Cu")
		(net "M_M_DQ<39>")
	)
	(segment
		(start 121.877582 -131.408678)
		(end 121.877582 -131.9022)
		(width 0.14224)
		(layer "In11.Cu")
		(net "M_M_DQ<39>")
	)
	(segment
		(start 121.877582 -134.579868)
		(end 122.055382 -134.757668)
		(width 0.14224)
		(layer "In11.Cu")
		(net "M_M_DQ<39>")
	)
	(segment
		(start 122.080782 -140.806678)
		(end 121.801382 -141.086078)
		(width 0.14224)
		(layer "In11.Cu")
		(net "M_M_DQ<39>")
	)
	(segment
		(start 112.427512 -102.757986)
		(end 112.367568 -102.861364)
		(width 0.0889)
		(layer "In11.Cu")
		(net "M_M_DQ<39>")
	)
	(segment
		(start 121.877582 -134.050786)
		(end 121.877582 -134.579868)
		(width 0.14224)
		(layer "In11.Cu")
		(net "M_M_DQ<39>")
	)
	(segment
		(start 121.565416 -127.166878)
		(end 121.720356 -127.321818)
		(width 0.14224)
		(layer "In11.Cu")
		(net "M_M_DQ<39>")
	)
	(segment
		(start 121.720356 -126.348998)
		(end 121.565416 -126.503938)
		(width 0.14224)
		(layer "In11.Cu")
		(net "M_M_DQ<39>")
	)
	(segment
		(start 121.852182 -149.191472)
		(end 121.84126 -149.191472)
		(width 0.14224)
		(layer "In11.Cu")
		(net "M_M_DQ<39>")
	)
	(segment
		(start 121.917968 -141.645386)
		(end 121.917968 -143.6878)
		(width 0.14224)
		(layer "In11.Cu")
		(net "M_M_DQ<39>")
	)
	(segment
		(start 121.477024 -149.533356)
		(end 121.04878 -149.9616)
		(width 0.14224)
		(layer "In11.Cu")
		(net "M_M_DQ<39>")
	)
	(arc
		(start 109.852206 -95.328486)
		(mid 109.849762 -95.332787)
		(end 109.84738 -95.337122)
		(width 0.0889)
		(layer "In11.Cu")
		(net "M_M_DQ<39>")
	)
	(arc
		(start 111.937292 -99.89058)
		(mid 112.429682 -100.189513)
		(end 112.433862 -100.76561)
		(width 0.0889)
		(layer "In11.Cu")
		(net "M_M_DQ<39>")
	)
	(arc
		(start 112.427512 -101.767132)
		(mid 112.374013 -101.96703)
		(end 112.427512 -102.166928)
		(width 0.0889)
		(layer "In11.Cu")
		(net "M_M_DQ<39>")
	)
	(arc
		(start 109.858556 -94.748604)
		(mid 109.931354 -95.039367)
		(end 109.852206 -95.328486)
		(width 0.0889)
		(layer "In11.Cu")
		(net "M_M_DQ<39>")
	)
	(arc
		(start 109.852206 -96.719136)
		(mid 109.931428 -97.008254)
		(end 109.858556 -97.299018)
		(width 0.0889)
		(layer "In11.Cu")
		(net "M_M_DQ<39>")
	)
	(arc
		(start 111.078772 -99.395788)
		(mid 111.361989 -99.480069)
		(end 111.568992 -99.690936)
		(width 0.0889)
		(layer "In11.Cu")
		(net "M_M_DQ<39>")
	)
	(arc
		(start 112.427512 -101.176328)
		(mid 112.506643 -101.47173)
		(end 112.427512 -101.767132)
		(width 0.0889)
		(layer "In11.Cu")
		(net "M_M_DQ<39>")
	)
	(arc
		(start 110.714028 -99.201478)
		(mid 110.859994 -99.343877)
		(end 111.057182 -99.395788)
		(width 0.0889)
		(layer "In11.Cu")
		(net "M_M_DQ<39>")
	)
	(arc
		(start 111.568992 -99.690936)
		(mid 111.706681 -99.83222)
		(end 111.895128 -99.89058)
		(width 0.0889)
		(layer "In11.Cu")
		(net "M_M_DQ<39>")
	)
	(arc
		(start 112.433862 -102.177596)
		(mid 112.506782 -102.468613)
		(end 112.427512 -102.757986)
		(width 0.0889)
		(layer "In11.Cu")
		(net "M_M_DQ<39>")
	)
	(arc
		(start 109.803184 -94.595696)
		(mid 109.813512 -94.644538)
		(end 109.829854 -94.691708)
		(width 0.0889)
		(layer "In11.Cu")
		(net "M_M_DQ<39>")
	)
	(arc
		(start 109.84738 -96.327722)
		(mid 109.798625 -96.524074)
		(end 109.852206 -96.719136)
		(width 0.0889)
		(layer "In11.Cu")
		(net "M_M_DQ<39>")
	)
	(arc
		(start 109.84738 -97.318322)
		(mid 109.798625 -97.514674)
		(end 109.852206 -97.709736)
		(width 0.0889)
		(layer "In11.Cu")
		(net "M_M_DQ<39>")
	)
	(arc
		(start 109.852206 -97.709736)
		(mid 109.931428 -97.998854)
		(end 109.858556 -98.289618)
		(width 0.0889)
		(layer "In11.Cu")
		(net "M_M_DQ<39>")
	)
	(arc
		(start 109.84738 -95.337122)
		(mid 109.798625 -95.533474)
		(end 109.852206 -95.728536)
		(width 0.0889)
		(layer "In11.Cu")
		(net "M_M_DQ<39>")
	)
	(arc
		(start 112.422686 -100.784914)
		(mid 112.373931 -100.981266)
		(end 112.427512 -101.176328)
		(width 0.0889)
		(layer "In11.Cu")
		(net "M_M_DQ<39>")
	)
	(arc
		(start 109.852206 -95.728536)
		(mid 109.931428 -96.017654)
		(end 109.858556 -96.308418)
		(width 0.0889)
		(layer "In11.Cu")
		(net "M_M_DQ<39>")
	)
	(arc
		(start 110.216696 -98.900234)
		(mid 110.50212 -98.983701)
		(end 110.710726 -99.195636)
		(width 0.0889)
		(layer "In11.Cu")
		(net "M_M_DQ<39>")
	)
	(arc
		(start 109.829854 -94.691708)
		(mid 109.840026 -94.715308)
		(end 109.852206 -94.737936)
		(width 0.0889)
		(layer "In11.Cu")
		(net "M_M_DQ<39>")
	)
	(arc
		(start 109.84738 -98.308922)
		(mid 109.851127 -98.698178)
		(end 110.18393 -98.900234)
		(width 0.0889)
		(layer "In11.Cu")
		(net "M_M_DQ<39>")
	)
	(segment
		(start 121.49963 -155.118054)
		(end 121.499376 -155.1178)
		(width 0.1651)
		(layer "F.Cu")
		(net "M_M_DQ<38>")
	)
	(segment
		(start 121.49963 -156.87294)
		(end 121.49963 -155.9052)
		(width 0.1651)
		(layer "F.Cu")
		(net "M_M_DQ<38>")
	)
	(segment
		(start 121.49963 -155.9052)
		(end 121.63171 -155.77312)
		(width 0.1651)
		(layer "F.Cu")
		(net "M_M_DQ<38>")
	)
	(segment
		(start 121.49963 -155.4226)
		(end 121.49963 -155.118054)
		(width 0.1651)
		(layer "F.Cu")
		(net "M_M_DQ<38>")
	)
	(segment
		(start 121.63171 -155.55468)
		(end 121.49963 -155.4226)
		(width 0.1651)
		(layer "F.Cu")
		(net "M_M_DQ<38>")
	)
	(segment
		(start 109.627416 -92.556584)
		(end 110.198916 -92.556584)
		(width 0.1651)
		(layer "F.Cu")
		(net "M_M_DQ<38>")
	)
	(segment
		(start 121.63171 -155.77312)
		(end 121.63171 -155.55468)
		(width 0.1651)
		(layer "F.Cu")
		(net "M_M_DQ<38>")
	)
	(segment
		(start 121.499376 -156.87294)
		(end 121.49963 -156.87294)
		(width 0.1651)
		(layer "F.Cu")
		(net "M_M_DQ<38>")
	)
	(via
		(at 120.649492 -150.814278)
		(size 0.508)
		(drill 0.254)
		(layers "F.Cu" "B.Cu")
		(net "M_M_DQ<38>")
	)
	(via
		(at 121.499376 -155.1178)
		(size 0.508)
		(drill 0.254)
		(layers "F.Cu" "B.Cu")
		(net "M_M_DQ<38>")
	)
	(via
		(at 110.198916 -92.556584)
		(size 0.508)
		(drill 0.254)
		(layers "F.Cu" "B.Cu")
		(net "M_M_DQ<38>")
	)
	(segment
		(start 120.649492 -152.078436)
		(end 120.649492 -150.814278)
		(width 0.1651)
		(layer "B.Cu")
		(net "M_M_DQ<38>")
	)
	(segment
		(start 120.53951 -150.704296)
		(end 120.649492 -150.814278)
		(width 0.14224)
		(layer "In11.Cu")
		(net "M_M_DQ<38>")
	)
	(segment
		(start 121.13133 -139.54633)
		(end 121.013982 -139.663678)
		(width 0.14224)
		(layer "In11.Cu")
		(net "M_M_DQ<38>")
	)
	(segment
		(start 111.656368 -105.2322)
		(end 111.376968 -105.5116)
		(width 0.14224)
		(layer "In11.Cu")
		(net "M_M_DQ<38>")
	)
	(segment
		(start 121.115582 -131.408678)
		(end 121.115582 -134.579868)
		(width 0.14224)
		(layer "In11.Cu")
		(net "M_M_DQ<38>")
	)
	(segment
		(start 109.680756 -94.822518)
		(end 109.687106 -94.833186)
		(width 0.0889)
		(layer "In11.Cu")
		(net "M_M_DQ<38>")
	)
	(segment
		(start 109.691932 -96.2152)
		(end 109.687106 -96.223836)
		(width 0.0889)
		(layer "In11.Cu")
		(net "M_M_DQ<38>")
	)
	(segment
		(start 121.013982 -136.129268)
		(end 121.13133 -136.246616)
		(width 0.14224)
		(layer "In11.Cu")
		(net "M_M_DQ<38>")
	)
	(segment
		(start 120.216422 -151.247348)
		(end 120.216422 -153.834846)
		(width 0.14224)
		(layer "In11.Cu")
		(net "M_M_DQ<38>")
	)
	(segment
		(start 110.54207 -99.285044)
		(end 110.545372 -99.290886)
		(width 0.0889)
		(layer "In11.Cu")
		(net "M_M_DQ<38>")
	)
	(segment
		(start 109.691932 -98.1964)
		(end 109.687106 -98.205036)
		(width 0.0889)
		(layer "In11.Cu")
		(net "M_M_DQ<38>")
	)
	(segment
		(start 121.013982 -130.062478)
		(end 121.013982 -131.307078)
		(width 0.14224)
		(layer "In11.Cu")
		(net "M_M_DQ<38>")
	)
	(segment
		(start 121.013982 -134.681468)
		(end 121.013982 -136.129268)
		(width 0.14224)
		(layer "In11.Cu")
		(net "M_M_DQ<38>")
	)
	(segment
		(start 120.407684 -128.701292)
		(end 121.102882 -129.39649)
		(width 0.14224)
		(layer "In11.Cu")
		(net "M_M_DQ<38>")
	)
	(segment
		(start 120.216422 -153.834846)
		(end 121.499376 -155.1178)
		(width 0.14224)
		(layer "In11.Cu")
		(net "M_M_DQ<38>")
	)
	(segment
		(start 109.691932 -97.2058)
		(end 109.687106 -97.214436)
		(width 0.0889)
		(layer "In11.Cu")
		(net "M_M_DQ<38>")
	)
	(segment
		(start 111.039402 -99.586288)
		(end 111.072168 -99.586288)
		(width 0.0889)
		(layer "In11.Cu")
		(net "M_M_DQ<38>")
	)
	(segment
		(start 111.376968 -115.372896)
		(end 120.407684 -124.403612)
		(width 0.14224)
		(layer "In11.Cu")
		(net "M_M_DQ<38>")
	)
	(segment
		(start 110.177326 -99.090734)
		(end 110.198916 -99.090734)
		(width 0.0889)
		(layer "In11.Cu")
		(net "M_M_DQ<38>")
	)
	(segment
		(start 120.407684 -124.403612)
		(end 120.407684 -128.701292)
		(width 0.14224)
		(layer "In11.Cu")
		(net "M_M_DQ<38>")
	)
	(segment
		(start 109.687106 -93.252036)
		(end 109.680756 -93.262704)
		(width 0.0889)
		(layer "In11.Cu")
		(net "M_M_DQ<38>")
	)
	(segment
		(start 121.102882 -129.973578)
		(end 121.013982 -130.062478)
		(width 0.14224)
		(layer "In11.Cu")
		(net "M_M_DQ<38>")
	)
	(segment
		(start 109.691932 -94.234)
		(end 109.687106 -94.242636)
		(width 0.0889)
		(layer "In11.Cu")
		(net "M_M_DQ<38>")
	)
	(segment
		(start 111.894112 -100.081334)
		(end 111.933736 -100.081334)
		(width 0.0889)
		(layer "In11.Cu")
		(net "M_M_DQ<38>")
	)
	(segment
		(start 121.102882 -129.39649)
		(end 121.102882 -129.973578)
		(width 0.14224)
		(layer "In11.Cu")
		(net "M_M_DQ<38>")
	)
	(segment
		(start 112.267238 -101.662992)
		(end 112.262412 -101.671628)
		(width 0.0889)
		(layer "In11.Cu")
		(net "M_M_DQ<38>")
	)
	(segment
		(start 109.687106 -96.223836)
		(end 109.680756 -96.234504)
		(width 0.0889)
		(layer "In11.Cu")
		(net "M_M_DQ<38>")
	)
	(segment
		(start 111.376968 -105.5116)
		(end 111.376968 -115.372896)
		(width 0.14224)
		(layer "In11.Cu")
		(net "M_M_DQ<38>")
	)
	(segment
		(start 121.11736 -149.0345)
		(end 120.53951 -149.61235)
		(width 0.14224)
		(layer "In11.Cu")
		(net "M_M_DQ<38>")
	)
	(segment
		(start 121.13133 -136.246616)
		(end 121.13133 -139.54633)
		(width 0.14224)
		(layer "In11.Cu")
		(net "M_M_DQ<38>")
	)
	(segment
		(start 109.70387 -93.222572)
		(end 109.687106 -93.252036)
		(width 0.0889)
		(layer "In11.Cu")
		(net "M_M_DQ<38>")
	)
	(segment
		(start 121.013982 -140.908278)
		(end 121.166382 -141.060678)
		(width 0.14224)
		(layer "In11.Cu")
		(net "M_M_DQ<38>")
	)
	(segment
		(start 121.166382 -144.118838)
		(end 120.89384 -144.39138)
		(width 0.14224)
		(layer "In11.Cu")
		(net "M_M_DQ<38>")
	)
	(segment
		(start 120.649492 -150.814278)
		(end 120.216422 -151.247348)
		(width 0.14224)
		(layer "In11.Cu")
		(net "M_M_DQ<38>")
	)
	(segment
		(start 121.166382 -141.060678)
		(end 121.166382 -144.118838)
		(width 0.14224)
		(layer "In11.Cu")
		(net "M_M_DQ<38>")
	)
	(segment
		(start 111.739934 -103.286814)
		(end 111.656368 -103.37038)
		(width 0.14224)
		(layer "In11.Cu")
		(net "M_M_DQ<38>")
	)
	(segment
		(start 109.687106 -98.205036)
		(end 109.680756 -98.215704)
		(width 0.0889)
		(layer "In11.Cu")
		(net "M_M_DQ<38>")
	)
	(segment
		(start 121.013982 -131.307078)
		(end 121.115582 -131.408678)
		(width 0.14224)
		(layer "In11.Cu")
		(net "M_M_DQ<38>")
	)
	(segment
		(start 112.262412 -102.637336)
		(end 112.087406 -102.939342)
		(width 0.0889)
		(layer "In11.Cu")
		(net "M_M_DQ<38>")
	)
	(segment
		(start 112.087406 -102.939342)
		(end 111.739934 -103.286814)
		(width 0.0889)
		(layer "In11.Cu")
		(net "M_M_DQ<38>")
	)
	(segment
		(start 120.53951 -149.61235)
		(end 120.53951 -150.704296)
		(width 0.14224)
		(layer "In11.Cu")
		(net "M_M_DQ<38>")
	)
	(segment
		(start 120.89384 -144.39138)
		(end 120.89384 -145.534126)
		(width 0.14224)
		(layer "In11.Cu")
		(net "M_M_DQ<38>")
	)
	(segment
		(start 109.687106 -97.214436)
		(end 109.680756 -97.225104)
		(width 0.0889)
		(layer "In11.Cu")
		(net "M_M_DQ<38>")
	)
	(segment
		(start 121.013982 -139.663678)
		(end 121.013982 -140.908278)
		(width 0.14224)
		(layer "In11.Cu")
		(net "M_M_DQ<38>")
	)
	(segment
		(start 112.262412 -100.681028)
		(end 112.256062 -100.691696)
		(width 0.0889)
		(layer "In11.Cu")
		(net "M_M_DQ<38>")
	)
	(segment
		(start 121.115582 -134.579868)
		(end 121.013982 -134.681468)
		(width 0.14224)
		(layer "In11.Cu")
		(net "M_M_DQ<38>")
	)
	(segment
		(start 121.11736 -145.757646)
		(end 121.11736 -149.0345)
		(width 0.14224)
		(layer "In11.Cu")
		(net "M_M_DQ<38>")
	)
	(segment
		(start 110.198916 -92.556584)
		(end 109.70387 -93.222572)
		(width 0.0889)
		(layer "In11.Cu")
		(net "M_M_DQ<38>")
	)
	(segment
		(start 111.656368 -103.37038)
		(end 111.656368 -105.2322)
		(width 0.14224)
		(layer "In11.Cu")
		(net "M_M_DQ<38>")
	)
	(segment
		(start 120.89384 -145.534126)
		(end 121.11736 -145.757646)
		(width 0.14224)
		(layer "In11.Cu")
		(net "M_M_DQ<38>")
	)
	(segment
		(start 112.262412 -102.262432)
		(end 112.267238 -102.271068)
		(width 0.0889)
		(layer "In11.Cu")
		(net "M_M_DQ<38>")
	)
	(arc
		(start 112.262412 -101.271578)
		(mid 112.315882 -101.466641)
		(end 112.267238 -101.662992)
		(width 0.0889)
		(layer "In11.Cu")
		(net "M_M_DQ<38>")
	)
	(arc
		(start 112.256062 -100.691696)
		(mid 112.183264 -100.982459)
		(end 112.262412 -101.271578)
		(width 0.0889)
		(layer "In11.Cu")
		(net "M_M_DQ<38>")
	)
	(arc
		(start 109.680756 -93.262704)
		(mid 109.607958 -93.553467)
		(end 109.687106 -93.842586)
		(width 0.0889)
		(layer "In11.Cu")
		(net "M_M_DQ<38>")
	)
	(arc
		(start 110.198916 -99.090734)
		(mid 110.396077 -99.142693)
		(end 110.54207 -99.285044)
		(width 0.0889)
		(layer "In11.Cu")
		(net "M_M_DQ<38>")
	)
	(arc
		(start 112.262412 -101.671628)
		(mid 112.183281 -101.96703)
		(end 112.262412 -102.262432)
		(width 0.0889)
		(layer "In11.Cu")
		(net "M_M_DQ<38>")
	)
	(arc
		(start 112.267238 -102.271068)
		(mid 112.31273 -102.45483)
		(end 112.262412 -102.637336)
		(width 0.0889)
		(layer "In11.Cu")
		(net "M_M_DQ<38>")
	)
	(arc
		(start 109.687106 -96.814386)
		(mid 109.740576 -97.009449)
		(end 109.691932 -97.2058)
		(width 0.0889)
		(layer "In11.Cu")
		(net "M_M_DQ<38>")
	)
	(arc
		(start 111.933736 -100.081334)
		(mid 112.266652 -100.288786)
		(end 112.262412 -100.681028)
		(width 0.0889)
		(layer "In11.Cu")
		(net "M_M_DQ<38>")
	)
	(arc
		(start 109.687106 -93.842586)
		(mid 109.740576 -94.037649)
		(end 109.691932 -94.234)
		(width 0.0889)
		(layer "In11.Cu")
		(net "M_M_DQ<38>")
	)
	(arc
		(start 109.680756 -96.234504)
		(mid 109.607958 -96.525267)
		(end 109.687106 -96.814386)
		(width 0.0889)
		(layer "In11.Cu")
		(net "M_M_DQ<38>")
	)
	(arc
		(start 109.687106 -97.804986)
		(mid 109.740576 -98.000049)
		(end 109.691932 -98.1964)
		(width 0.0889)
		(layer "In11.Cu")
		(net "M_M_DQ<38>")
	)
	(arc
		(start 111.072168 -99.586288)
		(mid 111.26381 -99.643454)
		(end 111.403892 -99.786186)
		(width 0.0889)
		(layer "In11.Cu")
		(net "M_M_DQ<38>")
	)
	(arc
		(start 109.680756 -97.225104)
		(mid 109.607958 -97.515867)
		(end 109.687106 -97.804986)
		(width 0.0889)
		(layer "In11.Cu")
		(net "M_M_DQ<38>")
	)
	(arc
		(start 109.680756 -98.215704)
		(mid 109.684787 -98.791886)
		(end 110.177326 -99.090734)
		(width 0.0889)
		(layer "In11.Cu")
		(net "M_M_DQ<38>")
	)
	(arc
		(start 109.687106 -94.833186)
		(mid 109.740605 -95.033084)
		(end 109.687106 -95.232982)
		(width 0.0889)
		(layer "In11.Cu")
		(net "M_M_DQ<38>")
	)
	(arc
		(start 109.687106 -94.242636)
		(mid 109.607884 -94.531754)
		(end 109.680756 -94.822518)
		(width 0.0889)
		(layer "In11.Cu")
		(net "M_M_DQ<38>")
	)
	(arc
		(start 111.403892 -99.786186)
		(mid 111.610896 -99.99705)
		(end 111.894112 -100.081334)
		(width 0.0889)
		(layer "In11.Cu")
		(net "M_M_DQ<38>")
	)
	(arc
		(start 109.687106 -95.232982)
		(mid 109.607975 -95.528384)
		(end 109.687106 -95.823786)
		(width 0.0889)
		(layer "In11.Cu")
		(net "M_M_DQ<38>")
	)
	(arc
		(start 110.545372 -99.290886)
		(mid 110.75398 -99.502818)
		(end 111.039402 -99.586288)
		(width 0.0889)
		(layer "In11.Cu")
		(net "M_M_DQ<38>")
	)
	(arc
		(start 109.687106 -95.823786)
		(mid 109.740576 -96.018849)
		(end 109.691932 -96.2152)
		(width 0.0889)
		(layer "In11.Cu")
		(net "M_M_DQ<38>")
	)
	(segment
		(start 114.699542 -152.273)
		(end 114.699542 -153.542746)
		(width 0.1651)
		(layer "F.Cu")
		(net "M_M_DQ<37>")
	)
	(segment
		(start 107.051856 -93.052138)
		(end 107.623356 -93.052138)
		(width 0.1651)
		(layer "F.Cu")
		(net "M_M_DQ<37>")
	)
	(via
		(at 115.473226 -149.533356)
		(size 0.508)
		(drill 0.254)
		(layers "F.Cu" "B.Cu")
		(net "M_M_DQ<37>")
	)
	(via
		(at 107.623356 -93.052138)
		(size 0.508)
		(drill 0.254)
		(layers "F.Cu" "B.Cu")
		(net "M_M_DQ<37>")
	)
	(via
		(at 114.699542 -153.542746)
		(size 0.508)
		(drill 0.254)
		(layers "F.Cu" "B.Cu")
		(net "M_M_DQ<37>")
	)
	(segment
		(start 115.549426 -149.457156)
		(end 115.473226 -149.533356)
		(width 0.1651)
		(layer "B.Cu")
		(net "M_M_DQ<37>")
	)
	(segment
		(start 115.549426 -147.478496)
		(end 115.549426 -149.457156)
		(width 0.1651)
		(layer "B.Cu")
		(net "M_M_DQ<37>")
	)
	(segment
		(start 115.974368 -141.655546)
		(end 115.974368 -143.637)
		(width 0.14224)
		(layer "In11.Cu")
		(net "M_M_DQ<37>")
	)
	(segment
		(start 115.14963 -150.6474)
		(end 115.14963 -151.129746)
		(width 0.14224)
		(layer "In11.Cu")
		(net "M_M_DQ<37>")
	)
	(segment
		(start 115.806982 -134.52856)
		(end 116.025168 -134.746746)
		(width 0.14224)
		(layer "In11.Cu")
		(net "M_M_DQ<37>")
	)
	(segment
		(start 116.025168 -136.016746)
		(end 115.831112 -136.210802)
		(width 0.14224)
		(layer "In11.Cu")
		(net "M_M_DQ<37>")
	)
	(segment
		(start 115.12423 -153.162254)
		(end 115.12423 -153.390346)
		(width 0.14224)
		(layer "In11.Cu")
		(net "M_M_DQ<37>")
	)
	(segment
		(start 116.010182 -144.398238)
		(end 116.010182 -145.454624)
		(width 0.14224)
		(layer "In11.Cu")
		(net "M_M_DQ<37>")
	)
	(segment
		(start 109.797088 -119.32539)
		(end 110.047024 -119.575326)
		(width 0.14224)
		(layer "In11.Cu")
		(net "M_M_DQ<37>")
	)
	(segment
		(start 107.604306 -104.36352)
		(end 107.604306 -118.199916)
		(width 0.14224)
		(layer "In11.Cu")
		(net "M_M_DQ<37>")
	)
	(segment
		(start 106.424476 -96.308418)
		(end 106.418126 -96.319086)
		(width 0.0889)
		(layer "In11.Cu")
		(net "M_M_DQ<37>")
	)
	(segment
		(start 106.418126 -98.300286)
		(end 106.4133 -98.308922)
		(width 0.0889)
		(layer "In11.Cu")
		(net "M_M_DQ<37>")
	)
	(segment
		(start 109.044486 -119.640096)
		(end 109.263434 -119.640096)
		(width 0.14224)
		(layer "In11.Cu")
		(net "M_M_DQ<37>")
	)
	(segment
		(start 115.857782 -149.1488)
		(end 115.473226 -149.533356)
		(width 0.14224)
		(layer "In11.Cu")
		(net "M_M_DQ<37>")
	)
	(segment
		(start 106.418126 -99.290886)
		(end 106.4133 -99.299522)
		(width 0.0889)
		(layer "In11.Cu")
		(net "M_M_DQ<37>")
	)
	(segment
		(start 106.497374 -100.418138)
		(end 107.223306 -101.14407)
		(width 0.0889)
		(layer "In11.Cu")
		(net "M_M_DQ<37>")
	)
	(segment
		(start 110.047024 -119.575326)
		(end 110.047024 -119.794274)
		(width 0.14224)
		(layer "In11.Cu")
		(net "M_M_DQ<37>")
	)
	(segment
		(start 106.418126 -95.328486)
		(end 106.4133 -95.337122)
		(width 0.0889)
		(layer "In11.Cu")
		(net "M_M_DQ<37>")
	)
	(segment
		(start 115.857782 -148.579586)
		(end 115.857782 -149.1488)
		(width 0.14224)
		(layer "In11.Cu")
		(net "M_M_DQ<37>")
	)
	(segment
		(start 107.663488 -104.304338)
		(end 107.604306 -104.36352)
		(width 0.14224)
		(layer "In11.Cu")
		(net "M_M_DQ<37>")
	)
	(segment
		(start 115.974368 -143.637)
		(end 115.883182 -143.728186)
		(width 0.14224)
		(layer "In11.Cu")
		(net "M_M_DQ<37>")
	)
	(segment
		(start 115.771168 -131.445)
		(end 115.771168 -131.825746)
		(width 0.14224)
		(layer "In11.Cu")
		(net "M_M_DQ<37>")
	)
	(segment
		(start 114.860832 -152.898856)
		(end 115.12423 -153.162254)
		(width 0.14224)
		(layer "In11.Cu")
		(net "M_M_DQ<37>")
	)
	(segment
		(start 107.223306 -103.864156)
		(end 107.663488 -104.304338)
		(width 0.0889)
		(layer "In11.Cu")
		(net "M_M_DQ<37>")
	)
	(segment
		(start 115.09883 -152.348946)
		(end 114.860832 -152.586944)
		(width 0.14224)
		(layer "In11.Cu")
		(net "M_M_DQ<37>")
	)
	(segment
		(start 115.974368 -146.268186)
		(end 115.974368 -148.463)
		(width 0.14224)
		(layer "In11.Cu")
		(net "M_M_DQ<37>")
	)
	(segment
		(start 116.025168 -140.6906)
		(end 115.793012 -140.922756)
		(width 0.14224)
		(layer "In11.Cu")
		(net "M_M_DQ<37>")
	)
	(segment
		(start 116.025168 -134.746746)
		(end 116.025168 -136.016746)
		(width 0.14224)
		(layer "In11.Cu")
		(net "M_M_DQ<37>")
	)
	(segment
		(start 115.02263 -150.5204)
		(end 115.14963 -150.6474)
		(width 0.14224)
		(layer "In11.Cu")
		(net "M_M_DQ<37>")
	)
	(segment
		(start 109.263434 -119.640096)
		(end 109.57814 -119.32539)
		(width 0.14224)
		(layer "In11.Cu")
		(net "M_M_DQ<37>")
	)
	(segment
		(start 109.732318 -120.327928)
		(end 109.982254 -120.577864)
		(width 0.14224)
		(layer "In11.Cu")
		(net "M_M_DQ<37>")
	)
	(segment
		(start 115.09883 -151.993854)
		(end 115.09883 -152.348946)
		(width 0.14224)
		(layer "In11.Cu")
		(net "M_M_DQ<37>")
	)
	(segment
		(start 115.831112 -136.210802)
		(end 115.831112 -136.55929)
		(width 0.14224)
		(layer "In11.Cu")
		(net "M_M_DQ<37>")
	)
	(segment
		(start 114.860832 -152.586944)
		(end 114.860832 -152.898856)
		(width 0.14224)
		(layer "In11.Cu")
		(net "M_M_DQ<37>")
	)
	(segment
		(start 115.450874 -149.533356)
		(end 115.02263 -149.9616)
		(width 0.14224)
		(layer "In11.Cu")
		(net "M_M_DQ<37>")
	)
	(segment
		(start 115.14963 -151.129746)
		(end 114.860832 -151.418544)
		(width 0.14224)
		(layer "In11.Cu")
		(net "M_M_DQ<37>")
	)
	(segment
		(start 114.860832 -151.755856)
		(end 115.09883 -151.993854)
		(width 0.14224)
		(layer "In11.Cu")
		(net "M_M_DQ<37>")
	)
	(segment
		(start 110.984792 -120.513094)
		(end 110.984792 -120.732042)
		(width 0.14224)
		(layer "In11.Cu")
		(net "M_M_DQ<37>")
	)
	(segment
		(start 107.223306 -101.14407)
		(end 107.223306 -103.864156)
		(width 0.0889)
		(layer "In11.Cu")
		(net "M_M_DQ<37>")
	)
	(segment
		(start 114.860832 -151.418544)
		(end 114.860832 -151.755856)
		(width 0.14224)
		(layer "In11.Cu")
		(net "M_M_DQ<37>")
	)
	(segment
		(start 115.831112 -136.55929)
		(end 115.974368 -136.702546)
		(width 0.14224)
		(layer "In11.Cu")
		(net "M_M_DQ<37>")
	)
	(segment
		(start 106.418126 -96.319086)
		(end 106.4133 -96.327722)
		(width 0.0889)
		(layer "In11.Cu")
		(net "M_M_DQ<37>")
	)
	(segment
		(start 115.473226 -149.533356)
		(end 115.450874 -149.533356)
		(width 0.14224)
		(layer "In11.Cu")
		(net "M_M_DQ<37>")
	)
	(segment
		(start 110.201202 -120.577864)
		(end 110.515908 -120.263158)
		(width 0.14224)
		(layer "In11.Cu")
		(net "M_M_DQ<37>")
	)
	(segment
		(start 115.974368 -148.463)
		(end 115.857782 -148.579586)
		(width 0.14224)
		(layer "In11.Cu")
		(net "M_M_DQ<37>")
	)
	(segment
		(start 115.806982 -134.152386)
		(end 115.806982 -134.52856)
		(width 0.14224)
		(layer "In11.Cu")
		(net "M_M_DQ<37>")
	)
	(segment
		(start 106.424476 -97.299018)
		(end 106.418126 -97.309686)
		(width 0.0889)
		(layer "In11.Cu")
		(net "M_M_DQ<37>")
	)
	(segment
		(start 115.771168 -131.825746)
		(end 115.974368 -132.028946)
		(width 0.14224)
		(layer "In11.Cu")
		(net "M_M_DQ<37>")
	)
	(segment
		(start 115.974368 -133.985)
		(end 115.806982 -134.152386)
		(width 0.14224)
		(layer "In11.Cu")
		(net "M_M_DQ<37>")
	)
	(segment
		(start 115.486688 -126.082298)
		(end 115.486688 -128.929892)
		(width 0.14224)
		(layer "In11.Cu")
		(net "M_M_DQ<37>")
	)
	(segment
		(start 115.486688 -128.929892)
		(end 115.883182 -129.326386)
		(width 0.14224)
		(layer "In11.Cu")
		(net "M_M_DQ<37>")
	)
	(segment
		(start 106.418126 -97.309686)
		(end 106.4133 -97.318322)
		(width 0.0889)
		(layer "In11.Cu")
		(net "M_M_DQ<37>")
	)
	(segment
		(start 106.424476 -99.280218)
		(end 106.418126 -99.290886)
		(width 0.0889)
		(layer "In11.Cu")
		(net "M_M_DQ<37>")
	)
	(segment
		(start 115.12423 -153.390346)
		(end 114.97183 -153.542746)
		(width 0.14224)
		(layer "In11.Cu")
		(net "M_M_DQ<37>")
	)
	(segment
		(start 116.101368 -131.1148)
		(end 115.771168 -131.445)
		(width 0.14224)
		(layer "In11.Cu")
		(net "M_M_DQ<37>")
	)
	(segment
		(start 115.883182 -129.920238)
		(end 116.101368 -130.138424)
		(width 0.14224)
		(layer "In11.Cu")
		(net "M_M_DQ<37>")
	)
	(segment
		(start 110.670086 -121.265696)
		(end 115.486688 -126.082298)
		(width 0.14224)
		(layer "In11.Cu")
		(net "M_M_DQ<37>")
	)
	(segment
		(start 115.974368 -132.028946)
		(end 115.974368 -133.985)
		(width 0.14224)
		(layer "In11.Cu")
		(net "M_M_DQ<37>")
	)
	(segment
		(start 116.010182 -145.454624)
		(end 115.857782 -145.607024)
		(width 0.14224)
		(layer "In11.Cu")
		(net "M_M_DQ<37>")
	)
	(segment
		(start 107.604306 -118.199916)
		(end 109.044486 -119.640096)
		(width 0.14224)
		(layer "In11.Cu")
		(net "M_M_DQ<37>")
	)
	(segment
		(start 115.857782 -145.607024)
		(end 115.857782 -146.1516)
		(width 0.14224)
		(layer "In11.Cu")
		(net "M_M_DQ<37>")
	)
	(segment
		(start 115.883182 -129.326386)
		(end 115.883182 -129.920238)
		(width 0.14224)
		(layer "In11.Cu")
		(net "M_M_DQ<37>")
	)
	(segment
		(start 110.984792 -120.732042)
		(end 110.670086 -121.046748)
		(width 0.14224)
		(layer "In11.Cu")
		(net "M_M_DQ<37>")
	)
	(segment
		(start 110.734856 -120.263158)
		(end 110.984792 -120.513094)
		(width 0.14224)
		(layer "In11.Cu")
		(net "M_M_DQ<37>")
	)
	(segment
		(start 115.793012 -141.47419)
		(end 115.974368 -141.655546)
		(width 0.14224)
		(layer "In11.Cu")
		(net "M_M_DQ<37>")
	)
	(segment
		(start 106.424476 -98.289618)
		(end 106.418126 -98.300286)
		(width 0.0889)
		(layer "In11.Cu")
		(net "M_M_DQ<37>")
	)
	(segment
		(start 115.883182 -143.728186)
		(end 115.883182 -144.271238)
		(width 0.14224)
		(layer "In11.Cu")
		(net "M_M_DQ<37>")
	)
	(segment
		(start 110.047024 -119.794274)
		(end 109.732318 -120.10898)
		(width 0.14224)
		(layer "In11.Cu")
		(net "M_M_DQ<37>")
	)
	(segment
		(start 115.02263 -149.9616)
		(end 115.02263 -150.5204)
		(width 0.14224)
		(layer "In11.Cu")
		(net "M_M_DQ<37>")
	)
	(segment
		(start 115.857782 -146.1516)
		(end 115.974368 -146.268186)
		(width 0.14224)
		(layer "In11.Cu")
		(net "M_M_DQ<37>")
	)
	(segment
		(start 115.796568 -138.9126)
		(end 115.796568 -139.4206)
		(width 0.14224)
		(layer "In11.Cu")
		(net "M_M_DQ<37>")
	)
	(segment
		(start 110.515908 -120.263158)
		(end 110.734856 -120.263158)
		(width 0.14224)
		(layer "In11.Cu")
		(net "M_M_DQ<37>")
	)
	(segment
		(start 109.57814 -119.32539)
		(end 109.797088 -119.32539)
		(width 0.14224)
		(layer "In11.Cu")
		(net "M_M_DQ<37>")
	)
	(segment
		(start 106.497374 -99.986338)
		(end 106.497374 -100.418138)
		(width 0.0889)
		(layer "In11.Cu")
		(net "M_M_DQ<37>")
	)
	(segment
		(start 115.974368 -136.702546)
		(end 115.974368 -138.7348)
		(width 0.14224)
		(layer "In11.Cu")
		(net "M_M_DQ<37>")
	)
	(segment
		(start 115.796568 -139.4206)
		(end 116.025168 -139.6492)
		(width 0.14224)
		(layer "In11.Cu")
		(net "M_M_DQ<37>")
	)
	(segment
		(start 109.732318 -120.10898)
		(end 109.732318 -120.327928)
		(width 0.14224)
		(layer "In11.Cu")
		(net "M_M_DQ<37>")
	)
	(segment
		(start 115.793012 -140.922756)
		(end 115.793012 -141.47419)
		(width 0.14224)
		(layer "In11.Cu")
		(net "M_M_DQ<37>")
	)
	(segment
		(start 114.97183 -153.542746)
		(end 114.699542 -153.542746)
		(width 0.14224)
		(layer "In11.Cu")
		(net "M_M_DQ<37>")
	)
	(segment
		(start 115.883182 -144.271238)
		(end 116.010182 -144.398238)
		(width 0.14224)
		(layer "In11.Cu")
		(net "M_M_DQ<37>")
	)
	(segment
		(start 116.101368 -130.138424)
		(end 116.101368 -131.1148)
		(width 0.14224)
		(layer "In11.Cu")
		(net "M_M_DQ<37>")
	)
	(segment
		(start 109.982254 -120.577864)
		(end 110.201202 -120.577864)
		(width 0.14224)
		(layer "In11.Cu")
		(net "M_M_DQ<37>")
	)
	(segment
		(start 116.025168 -139.6492)
		(end 116.025168 -140.6906)
		(width 0.14224)
		(layer "In11.Cu")
		(net "M_M_DQ<37>")
	)
	(segment
		(start 110.670086 -121.046748)
		(end 110.670086 -121.265696)
		(width 0.14224)
		(layer "In11.Cu")
		(net "M_M_DQ<37>")
	)
	(segment
		(start 106.786426 -93.147388)
		(end 106.75366 -93.147388)
		(width 0.0889)
		(layer "In11.Cu")
		(net "M_M_DQ<37>")
	)
	(segment
		(start 106.418126 -94.737936)
		(end 106.424476 -94.748604)
		(width 0.0889)
		(layer "In11.Cu")
		(net "M_M_DQ<37>")
	)
	(segment
		(start 115.974368 -138.7348)
		(end 115.796568 -138.9126)
		(width 0.14224)
		(layer "In11.Cu")
		(net "M_M_DQ<37>")
	)
	(arc
		(start 106.418126 -95.728536)
		(mid 106.497348 -96.017654)
		(end 106.424476 -96.308418)
		(width 0.0889)
		(layer "In11.Cu")
		(net "M_M_DQ<37>")
	)
	(arc
		(start 106.4133 -98.308922)
		(mid 106.364545 -98.505274)
		(end 106.418126 -98.700336)
		(width 0.0889)
		(layer "In11.Cu")
		(net "M_M_DQ<37>")
	)
	(arc
		(start 106.4133 -99.299522)
		(mid 106.364545 -99.495874)
		(end 106.418126 -99.690936)
		(width 0.0889)
		(layer "In11.Cu")
		(net "M_M_DQ<37>")
	)
	(arc
		(start 106.418126 -99.690936)
		(mid 106.477193 -99.833422)
		(end 106.497374 -99.986338)
		(width 0.0889)
		(layer "In11.Cu")
		(net "M_M_DQ<37>")
	)
	(arc
		(start 106.418126 -94.33814)
		(mid 106.364627 -94.538038)
		(end 106.418126 -94.737936)
		(width 0.0889)
		(layer "In11.Cu")
		(net "M_M_DQ<37>")
	)
	(arc
		(start 106.418126 -98.700336)
		(mid 106.497348 -98.989454)
		(end 106.424476 -99.280218)
		(width 0.0889)
		(layer "In11.Cu")
		(net "M_M_DQ<37>")
	)
	(arc
		(start 106.4133 -97.318322)
		(mid 106.364545 -97.514674)
		(end 106.418126 -97.709736)
		(width 0.0889)
		(layer "In11.Cu")
		(net "M_M_DQ<37>")
	)
	(arc
		(start 106.424476 -94.748604)
		(mid 106.497274 -95.039367)
		(end 106.418126 -95.328486)
		(width 0.0889)
		(layer "In11.Cu")
		(net "M_M_DQ<37>")
	)
	(arc
		(start 106.418126 -96.719136)
		(mid 106.497348 -97.008254)
		(end 106.424476 -97.299018)
		(width 0.0889)
		(layer "In11.Cu")
		(net "M_M_DQ<37>")
	)
	(arc
		(start 106.418126 -97.709736)
		(mid 106.497348 -97.998854)
		(end 106.424476 -98.289618)
		(width 0.0889)
		(layer "In11.Cu")
		(net "M_M_DQ<37>")
	)
	(arc
		(start 106.4133 -95.337122)
		(mid 106.364545 -95.533474)
		(end 106.418126 -95.728536)
		(width 0.0889)
		(layer "In11.Cu")
		(net "M_M_DQ<37>")
	)
	(arc
		(start 107.623356 -93.052138)
		(mid 107.207592 -93.123497)
		(end 106.786426 -93.147388)
		(width 0.0889)
		(layer "In11.Cu")
		(net "M_M_DQ<37>")
	)
	(arc
		(start 106.4133 -96.327722)
		(mid 106.364545 -96.524074)
		(end 106.418126 -96.719136)
		(width 0.0889)
		(layer "In11.Cu")
		(net "M_M_DQ<37>")
	)
	(arc
		(start 106.418126 -93.747336)
		(mid 106.497257 -94.042738)
		(end 106.418126 -94.33814)
		(width 0.0889)
		(layer "In11.Cu")
		(net "M_M_DQ<37>")
	)
	(arc
		(start 106.75366 -93.147388)
		(mid 106.415545 -93.35209)
		(end 106.418126 -93.747336)
		(width 0.0889)
		(layer "In11.Cu")
		(net "M_M_DQ<37>")
	)
	(segment
		(start 115.549426 -156.87294)
		(end 115.549426 -155.547568)
		(width 0.1651)
		(layer "F.Cu")
		(net "M_M_DQ<36>")
	)
	(segment
		(start 107.051856 -91.070938)
		(end 107.623356 -91.070938)
		(width 0.1016)
		(layer "F.Cu")
		(net "M_M_DQ<36>")
	)
	(segment
		(start 115.549426 -155.547568)
		(end 115.451382 -155.0162)
		(width 0.1651)
		(layer "F.Cu")
		(net "M_M_DQ<36>")
	)
	(via
		(at 107.623356 -91.070938)
		(size 0.508)
		(drill 0.254)
		(layers "F.Cu" "B.Cu")
		(net "M_M_DQ<36>")
	)
	(via
		(at 115.451382 -155.0162)
		(size 0.508)
		(drill 0.254)
		(layers "F.Cu" "B.Cu")
		(net "M_M_DQ<36>")
	)
	(via
		(at 114.699542 -150.814278)
		(size 0.508)
		(drill 0.254)
		(layers "F.Cu" "B.Cu")
		(net "M_M_DQ<36>")
	)
	(segment
		(start 114.699542 -152.078436)
		(end 114.699542 -150.814278)
		(width 0.1651)
		(layer "B.Cu")
		(net "M_M_DQ<36>")
	)
	(segment
		(start 106.253026 -98.205036)
		(end 106.246676 -98.215704)
		(width 0.0889)
		(layer "In11.Cu")
		(net "M_M_DQ<36>")
	)
	(segment
		(start 106.257852 -99.187)
		(end 106.253026 -99.195636)
		(width 0.0889)
		(layer "In11.Cu")
		(net "M_M_DQ<36>")
	)
	(segment
		(start 106.30662 -100.496878)
		(end 107.028488 -101.218746)
		(width 0.0889)
		(layer "In11.Cu")
		(net "M_M_DQ<36>")
	)
	(segment
		(start 115.136168 -134.0612)
		(end 115.197382 -134.122414)
		(width 0.14224)
		(layer "In11.Cu")
		(net "M_M_DQ<36>")
	)
	(segment
		(start 106.969306 -118.399052)
		(end 114.801396 -126.231142)
		(width 0.14224)
		(layer "In11.Cu")
		(net "M_M_DQ<36>")
	)
	(segment
		(start 114.93119 -145.527776)
		(end 115.184682 -145.781268)
		(width 0.14224)
		(layer "In11.Cu")
		(net "M_M_DQ<36>")
	)
	(segment
		(start 106.246676 -94.822518)
		(end 106.253026 -94.833186)
		(width 0.0889)
		(layer "In11.Cu")
		(net "M_M_DQ<36>")
	)
	(segment
		(start 106.969306 -104.462834)
		(end 106.969306 -118.399052)
		(width 0.14224)
		(layer "In11.Cu")
		(net "M_M_DQ<36>")
	)
	(segment
		(start 106.253026 -99.195636)
		(end 106.246676 -99.206304)
		(width 0.0889)
		(layer "In11.Cu")
		(net "M_M_DQ<36>")
	)
	(segment
		(start 114.801396 -128.940814)
		(end 115.197382 -129.3368)
		(width 0.14224)
		(layer "In11.Cu")
		(net "M_M_DQ<36>")
	)
	(segment
		(start 115.20043 -155.0162)
		(end 115.451382 -155.0162)
		(width 0.14224)
		(layer "In11.Cu")
		(net "M_M_DQ<36>")
	)
	(segment
		(start 114.424968 -149.719792)
		(end 114.424968 -150.539704)
		(width 0.14224)
		(layer "In11.Cu")
		(net "M_M_DQ<36>")
	)
	(segment
		(start 106.257852 -96.2152)
		(end 106.253026 -96.223836)
		(width 0.0889)
		(layer "In11.Cu")
		(net "M_M_DQ<36>")
	)
	(segment
		(start 115.197382 -141.5542)
		(end 115.110768 -141.640814)
		(width 0.14224)
		(layer "In11.Cu")
		(net "M_M_DQ<36>")
	)
	(segment
		(start 115.136168 -138.811)
		(end 115.222782 -138.897614)
		(width 0.14224)
		(layer "In11.Cu")
		(net "M_M_DQ<36>")
	)
	(segment
		(start 115.136168 -132.014214)
		(end 115.136168 -134.0612)
		(width 0.14224)
		(layer "In11.Cu")
		(net "M_M_DQ<36>")
	)
	(segment
		(start 106.257852 -98.1964)
		(end 106.253026 -98.205036)
		(width 0.0889)
		(layer "In11.Cu")
		(net "M_M_DQ<36>")
	)
	(segment
		(start 106.253026 -96.223836)
		(end 106.246676 -96.234504)
		(width 0.0889)
		(layer "In11.Cu")
		(net "M_M_DQ<36>")
	)
	(segment
		(start 114.968782 -129.996438)
		(end 114.968782 -131.180078)
		(width 0.14224)
		(layer "In11.Cu")
		(net "M_M_DQ<36>")
	)
	(segment
		(start 114.699542 -150.814278)
		(end 114.266472 -151.247348)
		(width 0.14224)
		(layer "In11.Cu")
		(net "M_M_DQ<36>")
	)
	(segment
		(start 114.968782 -140.781278)
		(end 115.197382 -141.009878)
		(width 0.14224)
		(layer "In11.Cu")
		(net "M_M_DQ<36>")
	)
	(segment
		(start 115.197382 -141.009878)
		(end 115.197382 -141.5542)
		(width 0.14224)
		(layer "In11.Cu")
		(net "M_M_DQ<36>")
	)
	(segment
		(start 115.197382 -134.456932)
		(end 114.968782 -134.685532)
		(width 0.14224)
		(layer "In11.Cu")
		(net "M_M_DQ<36>")
	)
	(segment
		(start 106.253026 -97.214436)
		(end 106.246676 -97.225104)
		(width 0.0889)
		(layer "In11.Cu")
		(net "M_M_DQ<36>")
	)
	(segment
		(start 114.968782 -134.685532)
		(end 114.968782 -135.951468)
		(width 0.14224)
		(layer "In11.Cu")
		(net "M_M_DQ<36>")
	)
	(segment
		(start 107.623356 -91.409012)
		(end 107.558332 -91.474036)
		(width 0.0889)
		(layer "In11.Cu")
		(net "M_M_DQ<36>")
	)
	(segment
		(start 106.776012 -92.956888)
		(end 106.743246 -92.956888)
		(width 0.0889)
		(layer "In11.Cu")
		(net "M_M_DQ<36>")
	)
	(segment
		(start 115.197382 -134.122414)
		(end 115.197382 -134.456932)
		(width 0.14224)
		(layer "In11.Cu")
		(net "M_M_DQ<36>")
	)
	(segment
		(start 114.968782 -131.180078)
		(end 115.197382 -131.408678)
		(width 0.14224)
		(layer "In11.Cu")
		(net "M_M_DQ<36>")
	)
	(segment
		(start 114.968782 -135.951468)
		(end 115.222782 -136.205468)
		(width 0.14224)
		(layer "In11.Cu")
		(net "M_M_DQ<36>")
	)
	(segment
		(start 115.184682 -148.960078)
		(end 114.424968 -149.719792)
		(width 0.14224)
		(layer "In11.Cu")
		(net "M_M_DQ<36>")
	)
	(segment
		(start 114.93119 -144.324578)
		(end 114.93119 -145.527776)
		(width 0.14224)
		(layer "In11.Cu")
		(net "M_M_DQ<36>")
	)
	(segment
		(start 115.136168 -148.5392)
		(end 115.184682 -148.587714)
		(width 0.14224)
		(layer "In11.Cu")
		(net "M_M_DQ<36>")
	)
	(segment
		(start 114.968782 -139.587478)
		(end 114.968782 -140.781278)
		(width 0.14224)
		(layer "In11.Cu")
		(net "M_M_DQ<36>")
	)
	(segment
		(start 115.110768 -141.640814)
		(end 115.110768 -143.6624)
		(width 0.14224)
		(layer "In11.Cu")
		(net "M_M_DQ<36>")
	)
	(segment
		(start 115.136168 -136.713214)
		(end 115.136168 -138.811)
		(width 0.14224)
		(layer "In11.Cu")
		(net "M_M_DQ<36>")
	)
	(segment
		(start 115.197382 -131.408678)
		(end 115.197382 -131.953)
		(width 0.14224)
		(layer "In11.Cu")
		(net "M_M_DQ<36>")
	)
	(segment
		(start 115.222782 -136.205468)
		(end 115.222782 -136.6266)
		(width 0.14224)
		(layer "In11.Cu")
		(net "M_M_DQ<36>")
	)
	(segment
		(start 115.184682 -148.587714)
		(end 115.184682 -148.960078)
		(width 0.14224)
		(layer "In11.Cu")
		(net "M_M_DQ<36>")
	)
	(segment
		(start 115.197382 -144.058386)
		(end 114.93119 -144.324578)
		(width 0.14224)
		(layer "In11.Cu")
		(net "M_M_DQ<36>")
	)
	(segment
		(start 114.801396 -126.231142)
		(end 114.801396 -128.940814)
		(width 0.14224)
		(layer "In11.Cu")
		(net "M_M_DQ<36>")
	)
	(segment
		(start 115.110768 -143.6624)
		(end 115.197382 -143.749014)
		(width 0.14224)
		(layer "In11.Cu")
		(net "M_M_DQ<36>")
	)
	(segment
		(start 115.197382 -143.749014)
		(end 115.197382 -144.058386)
		(width 0.14224)
		(layer "In11.Cu")
		(net "M_M_DQ<36>")
	)
	(segment
		(start 114.42446 -154.24023)
		(end 115.20043 -155.0162)
		(width 0.14224)
		(layer "In11.Cu")
		(net "M_M_DQ<36>")
	)
	(segment
		(start 107.028488 -101.218746)
		(end 107.028488 -104.403652)
		(width 0.0889)
		(layer "In11.Cu")
		(net "M_M_DQ<36>")
	)
	(segment
		(start 107.623356 -91.070938)
		(end 107.623356 -91.409012)
		(width 0.0889)
		(layer "In11.Cu")
		(net "M_M_DQ<36>")
	)
	(segment
		(start 115.197382 -131.953)
		(end 115.136168 -132.014214)
		(width 0.14224)
		(layer "In11.Cu")
		(net "M_M_DQ<36>")
	)
	(segment
		(start 106.30662 -99.986338)
		(end 106.30662 -100.496878)
		(width 0.0889)
		(layer "In11.Cu")
		(net "M_M_DQ<36>")
	)
	(segment
		(start 114.266472 -153.78049)
		(end 114.42446 -153.938478)
		(width 0.14224)
		(layer "In11.Cu")
		(net "M_M_DQ<36>")
	)
	(segment
		(start 115.136168 -146.225514)
		(end 115.136168 -148.5392)
		(width 0.14224)
		(layer "In11.Cu")
		(net "M_M_DQ<36>")
	)
	(segment
		(start 115.197382 -129.3368)
		(end 115.197382 -129.767838)
		(width 0.14224)
		(layer "In11.Cu")
		(net "M_M_DQ<36>")
	)
	(segment
		(start 115.184682 -146.177)
		(end 115.136168 -146.225514)
		(width 0.14224)
		(layer "In11.Cu")
		(net "M_M_DQ<36>")
	)
	(segment
		(start 106.257852 -97.2058)
		(end 106.253026 -97.214436)
		(width 0.0889)
		(layer "In11.Cu")
		(net "M_M_DQ<36>")
	)
	(segment
		(start 115.184682 -145.781268)
		(end 115.184682 -146.177)
		(width 0.14224)
		(layer "In11.Cu")
		(net "M_M_DQ<36>")
	)
	(segment
		(start 115.222782 -139.333478)
		(end 114.968782 -139.587478)
		(width 0.14224)
		(layer "In11.Cu")
		(net "M_M_DQ<36>")
	)
	(segment
		(start 114.424968 -150.539704)
		(end 114.699542 -150.814278)
		(width 0.14224)
		(layer "In11.Cu")
		(net "M_M_DQ<36>")
	)
	(segment
		(start 115.222782 -136.6266)
		(end 115.136168 -136.713214)
		(width 0.14224)
		(layer "In11.Cu")
		(net "M_M_DQ<36>")
	)
	(segment
		(start 115.197382 -129.767838)
		(end 114.968782 -129.996438)
		(width 0.14224)
		(layer "In11.Cu")
		(net "M_M_DQ<36>")
	)
	(segment
		(start 114.266472 -151.247348)
		(end 114.266472 -153.78049)
		(width 0.14224)
		(layer "In11.Cu")
		(net "M_M_DQ<36>")
	)
	(segment
		(start 114.42446 -153.938478)
		(end 114.42446 -154.24023)
		(width 0.14224)
		(layer "In11.Cu")
		(net "M_M_DQ<36>")
	)
	(segment
		(start 107.028488 -104.403652)
		(end 106.969306 -104.462834)
		(width 0.14224)
		(layer "In11.Cu")
		(net "M_M_DQ<36>")
	)
	(segment
		(start 115.222782 -138.897614)
		(end 115.222782 -139.333478)
		(width 0.14224)
		(layer "In11.Cu")
		(net "M_M_DQ<36>")
	)
	(arc
		(start 106.253026 -98.795586)
		(mid 106.306496 -98.990649)
		(end 106.257852 -99.187)
		(width 0.0889)
		(layer "In11.Cu")
		(net "M_M_DQ<36>")
	)
	(arc
		(start 106.253026 -93.84284)
		(mid 106.306525 -94.042738)
		(end 106.253026 -94.242636)
		(width 0.0889)
		(layer "In11.Cu")
		(net "M_M_DQ<36>")
	)
	(arc
		(start 106.253026 -94.242636)
		(mid 106.173804 -94.531754)
		(end 106.246676 -94.822518)
		(width 0.0889)
		(layer "In11.Cu")
		(net "M_M_DQ<36>")
	)
	(arc
		(start 106.253026 -95.823786)
		(mid 106.306496 -96.018849)
		(end 106.257852 -96.2152)
		(width 0.0889)
		(layer "In11.Cu")
		(net "M_M_DQ<36>")
	)
	(arc
		(start 106.253026 -94.833186)
		(mid 106.306525 -95.033084)
		(end 106.253026 -95.232982)
		(width 0.0889)
		(layer "In11.Cu")
		(net "M_M_DQ<36>")
	)
	(arc
		(start 106.246676 -97.225104)
		(mid 106.173878 -97.515867)
		(end 106.253026 -97.804986)
		(width 0.0889)
		(layer "In11.Cu")
		(net "M_M_DQ<36>")
	)
	(arc
		(start 106.253026 -96.814386)
		(mid 106.306496 -97.009449)
		(end 106.257852 -97.2058)
		(width 0.0889)
		(layer "In11.Cu")
		(net "M_M_DQ<36>")
	)
	(arc
		(start 106.743246 -92.956888)
		(mid 106.247769 -93.261331)
		(end 106.253026 -93.84284)
		(width 0.0889)
		(layer "In11.Cu")
		(net "M_M_DQ<36>")
	)
	(arc
		(start 106.246676 -96.234504)
		(mid 106.173878 -96.525267)
		(end 106.253026 -96.814386)
		(width 0.0889)
		(layer "In11.Cu")
		(net "M_M_DQ<36>")
	)
	(arc
		(start 107.111546 -92.35694)
		(mid 107.114129 -92.752187)
		(end 106.776012 -92.956888)
		(width 0.0889)
		(layer "In11.Cu")
		(net "M_M_DQ<36>")
	)
	(arc
		(start 106.246676 -98.215704)
		(mid 106.173878 -98.506467)
		(end 106.253026 -98.795586)
		(width 0.0889)
		(layer "In11.Cu")
		(net "M_M_DQ<36>")
	)
	(arc
		(start 106.253026 -95.232982)
		(mid 106.173895 -95.528384)
		(end 106.253026 -95.823786)
		(width 0.0889)
		(layer "In11.Cu")
		(net "M_M_DQ<36>")
	)
	(arc
		(start 106.253026 -97.804986)
		(mid 106.306496 -98.000049)
		(end 106.257852 -98.1964)
		(width 0.0889)
		(layer "In11.Cu")
		(net "M_M_DQ<36>")
	)
	(arc
		(start 106.253026 -99.786186)
		(mid 106.293002 -99.882731)
		(end 106.30662 -99.986338)
		(width 0.0889)
		(layer "In11.Cu")
		(net "M_M_DQ<36>")
	)
	(arc
		(start 106.246676 -99.206304)
		(mid 106.173878 -99.497067)
		(end 106.253026 -99.786186)
		(width 0.0889)
		(layer "In11.Cu")
		(net "M_M_DQ<36>")
	)
	(arc
		(start 107.558332 -91.474036)
		(mid 107.095972 -91.794606)
		(end 107.111546 -92.35694)
		(width 0.0889)
		(layer "In11.Cu")
		(net "M_M_DQ<36>")
	)
	(segment
		(start 122.349514 -152.273)
		(end 122.349514 -153.542746)
		(width 0.1651)
		(layer "F.Cu")
		(net "M_M_DQ<35>")
	)
	(segment
		(start 110.485682 -94.042738)
		(end 111.057182 -94.042738)
		(width 0.1651)
		(layer "F.Cu")
		(net "M_M_DQ<35>")
	)
	(via
		(at 111.057182 -94.042738)
		(size 0.508)
		(drill 0.254)
		(layers "F.Cu" "B.Cu")
		(net "M_M_DQ<35>")
	)
	(via
		(at 123.199398 -149.533356)
		(size 0.508)
		(drill 0.254)
		(layers "F.Cu" "B.Cu")
		(net "M_M_DQ<35>")
	)
	(via
		(at 122.349514 -153.542746)
		(size 0.508)
		(drill 0.254)
		(layers "F.Cu" "B.Cu")
		(net "M_M_DQ<35>")
	)
	(segment
		(start 123.199398 -147.478496)
		(end 123.199398 -149.533356)
		(width 0.1651)
		(layer "B.Cu")
		(net "M_M_DQ<35>")
	)
	(segment
		(start 123.199398 -149.533356)
		(end 123.177046 -149.533356)
		(width 0.14224)
		(layer "In11.Cu")
		(net "M_M_DQ<35>")
	)
	(segment
		(start 113.46942 -102.979474)
		(end 113.54181 -103.051864)
		(width 0.0889)
		(layer "In11.Cu")
		(net "M_M_DQ<35>")
	)
	(segment
		(start 111.057182 -98.405188)
		(end 111.078772 -98.405188)
		(width 0.0889)
		(layer "In11.Cu")
		(net "M_M_DQ<35>")
	)
	(segment
		(start 110.710726 -96.223836)
		(end 110.719616 -96.239076)
		(width 0.0889)
		(layer "In11.Cu")
		(net "M_M_DQ<35>")
	)
	(segment
		(start 123.566682 -134.088886)
		(end 123.566682 -134.573264)
		(width 0.14224)
		(layer "In11.Cu")
		(net "M_M_DQ<35>")
	)
	(segment
		(start 123.528582 -145.810732)
		(end 123.528582 -146.1262)
		(width 0.14224)
		(layer "In11.Cu")
		(net "M_M_DQ<35>")
	)
	(segment
		(start 123.566682 -131.953)
		(end 123.619768 -132.006086)
		(width 0.14224)
		(layer "In11.Cu")
		(net "M_M_DQ<35>")
	)
	(segment
		(start 123.566682 -134.573264)
		(end 123.731782 -134.738364)
		(width 0.14224)
		(layer "In11.Cu")
		(net "M_M_DQ<35>")
	)
	(segment
		(start 123.605798 -139.66063)
		(end 123.605798 -140.88237)
		(width 0.1016)
		(layer "In11.Cu")
		(net "M_M_DQ<35>")
	)
	(segment
		(start 123.528582 -148.503386)
		(end 123.528582 -149.21738)
		(width 0.14224)
		(layer "In11.Cu")
		(net "M_M_DQ<35>")
	)
	(segment
		(start 114.145568 -105.156)
		(end 113.367312 -105.934256)
		(width 0.14224)
		(layer "In11.Cu")
		(net "M_M_DQ<35>")
	)
	(segment
		(start 122.799602 -153.04135)
		(end 122.799602 -153.364946)
		(width 0.14224)
		(layer "In11.Cu")
		(net "M_M_DQ<35>")
	)
	(segment
		(start 122.767852 -151.9174)
		(end 122.767852 -152.2222)
		(width 0.14224)
		(layer "In11.Cu")
		(net "M_M_DQ<35>")
	)
	(segment
		(start 123.566682 -144.182338)
		(end 123.782582 -144.398238)
		(width 0.14224)
		(layer "In11.Cu")
		(net "M_M_DQ<35>")
	)
	(segment
		(start 114.145568 -103.34244)
		(end 114.145568 -105.156)
		(width 0.14224)
		(layer "In11.Cu")
		(net "M_M_DQ<35>")
	)
	(segment
		(start 113.292382 -102.25151)
		(end 113.277396 -102.277164)
		(width 0.0889)
		(layer "In11.Cu")
		(net "M_M_DQ<35>")
	)
	(segment
		(start 113.54181 -103.051864)
		(end 113.854992 -103.051864)
		(width 0.0889)
		(layer "In11.Cu")
		(net "M_M_DQ<35>")
	)
	(segment
		(start 123.782582 -144.398238)
		(end 123.782582 -145.556732)
		(width 0.14224)
		(layer "In11.Cu")
		(net "M_M_DQ<35>")
	)
	(segment
		(start 123.41606 -124.784104)
		(end 123.41606 -127.529844)
		(width 0.14224)
		(layer "In11.Cu")
		(net "M_M_DQ<35>")
	)
	(segment
		(start 122.932444 -128.347724)
		(end 123.26112 -128.347724)
		(width 0.14224)
		(layer "In11.Cu")
		(net "M_M_DQ<35>")
	)
	(segment
		(start 122.621802 -153.542746)
		(end 122.349514 -153.542746)
		(width 0.14224)
		(layer "In11.Cu")
		(net "M_M_DQ<35>")
	)
	(segment
		(start 122.748802 -150.391368)
		(end 122.793252 -150.435818)
		(width 0.14224)
		(layer "In11.Cu")
		(net "M_M_DQ<35>")
	)
	(segment
		(start 123.731782 -134.738364)
		(end 123.731782 -136.006332)
		(width 0.14224)
		(layer "In11.Cu")
		(net "M_M_DQ<35>")
	)
	(segment
		(start 123.619768 -134.0358)
		(end 123.566682 -134.088886)
		(width 0.14224)
		(layer "In11.Cu")
		(net "M_M_DQ<35>")
	)
	(segment
		(start 123.619768 -132.006086)
		(end 123.619768 -134.0358)
		(width 0.14224)
		(layer "In11.Cu")
		(net "M_M_DQ<35>")
	)
	(segment
		(start 123.528582 -146.1262)
		(end 123.619768 -146.217386)
		(width 0.14224)
		(layer "In11.Cu")
		(net "M_M_DQ<35>")
	)
	(segment
		(start 123.605798 -140.88237)
		(end 123.566682 -140.921486)
		(width 0.1016)
		(layer "In11.Cu")
		(net "M_M_DQ<35>")
	)
	(segment
		(start 110.710726 -97.214436)
		(end 110.719616 -97.229676)
		(width 0.0889)
		(layer "In11.Cu")
		(net "M_M_DQ<35>")
	)
	(segment
		(start 122.510804 -151.660352)
		(end 122.767852 -151.9174)
		(width 0.14224)
		(layer "In11.Cu")
		(net "M_M_DQ<35>")
	)
	(segment
		(start 122.799602 -153.364946)
		(end 122.621802 -153.542746)
		(width 0.14224)
		(layer "In11.Cu")
		(net "M_M_DQ<35>")
	)
	(segment
		(start 123.619768 -138.7856)
		(end 123.553982 -138.851386)
		(width 0.14224)
		(layer "In11.Cu")
		(net "M_M_DQ<35>")
	)
	(segment
		(start 111.057182 -93.704664)
		(end 110.999524 -93.647006)
		(width 0.0889)
		(layer "In11.Cu")
		(net "M_M_DQ<35>")
	)
	(segment
		(start 113.286032 -100.681028)
		(end 113.292382 -100.691696)
		(width 0.0889)
		(layer "In11.Cu")
		(net "M_M_DQ<35>")
	)
	(segment
		(start 110.717076 -94.822518)
		(end 110.710726 -94.833186)
		(width 0.0889)
		(layer "In11.Cu")
		(net "M_M_DQ<35>")
	)
	(segment
		(start 122.777504 -128.192784)
		(end 122.932444 -128.347724)
		(width 0.14224)
		(layer "In11.Cu")
		(net "M_M_DQ<35>")
	)
	(segment
		(start 123.528582 -149.21738)
		(end 123.199398 -149.546564)
		(width 0.14224)
		(layer "In11.Cu")
		(net "M_M_DQ<35>")
	)
	(segment
		(start 113.367312 -105.934256)
		(end 113.367312 -114.735356)
		(width 0.14224)
		(layer "In11.Cu")
		(net "M_M_DQ<35>")
	)
	(segment
		(start 123.467368 -136.270746)
		(end 123.467368 -136.626346)
		(width 0.14224)
		(layer "In11.Cu")
		(net "M_M_DQ<35>")
	)
	(segment
		(start 123.619768 -136.778746)
		(end 123.619768 -138.7856)
		(width 0.14224)
		(layer "In11.Cu")
		(net "M_M_DQ<35>")
	)
	(segment
		(start 123.26112 -127.684784)
		(end 122.932444 -127.684784)
		(width 0.14224)
		(layer "In11.Cu")
		(net "M_M_DQ<35>")
	)
	(segment
		(start 123.41606 -128.502664)
		(end 123.41606 -129.666492)
		(width 0.14224)
		(layer "In11.Cu")
		(net "M_M_DQ<35>")
	)
	(segment
		(start 123.782582 -145.556732)
		(end 123.528582 -145.810732)
		(width 0.14224)
		(layer "In11.Cu")
		(net "M_M_DQ<35>")
	)
	(segment
		(start 122.793252 -150.435818)
		(end 122.793252 -151.1046)
		(width 0.14224)
		(layer "In11.Cu")
		(net "M_M_DQ<35>")
	)
	(segment
		(start 123.26112 -128.347724)
		(end 123.41606 -128.502664)
		(width 0.14224)
		(layer "In11.Cu")
		(net "M_M_DQ<35>")
	)
	(segment
		(start 113.854992 -103.051864)
		(end 114.051842 -103.248714)
		(width 0.0889)
		(layer "In11.Cu")
		(net "M_M_DQ<35>")
	)
	(segment
		(start 113.286032 -101.271578)
		(end 113.281206 -101.280214)
		(width 0.0889)
		(layer "In11.Cu")
		(net "M_M_DQ<35>")
	)
	(segment
		(start 123.553982 -139.608814)
		(end 123.605798 -139.66063)
		(width 0.1016)
		(layer "In11.Cu")
		(net "M_M_DQ<35>")
	)
	(segment
		(start 122.932444 -127.684784)
		(end 122.777504 -127.839724)
		(width 0.14224)
		(layer "In11.Cu")
		(net "M_M_DQ<35>")
	)
	(segment
		(start 112.756188 -99.395534)
		(end 112.799114 -99.395534)
		(width 0.0889)
		(layer "In11.Cu")
		(net "M_M_DQ<35>")
	)
	(segment
		(start 123.619768 -148.4122)
		(end 123.528582 -148.503386)
		(width 0.14224)
		(layer "In11.Cu")
		(net "M_M_DQ<35>")
	)
	(segment
		(start 111.057182 -94.042738)
		(end 111.057182 -93.704664)
		(width 0.0889)
		(layer "In11.Cu")
		(net "M_M_DQ<35>")
	)
	(segment
		(start 123.177046 -149.533356)
		(end 122.748802 -149.9616)
		(width 0.14224)
		(layer "In11.Cu")
		(net "M_M_DQ<35>")
	)
	(segment
		(start 123.467368 -136.626346)
		(end 123.619768 -136.778746)
		(width 0.14224)
		(layer "In11.Cu")
		(net "M_M_DQ<35>")
	)
	(segment
		(start 123.619768 -146.217386)
		(end 123.619768 -148.4122)
		(width 0.14224)
		(layer "In11.Cu")
		(net "M_M_DQ<35>")
	)
	(segment
		(start 110.710726 -95.232982)
		(end 110.717076 -95.24365)
		(width 0.0889)
		(layer "In11.Cu")
		(net "M_M_DQ<35>")
	)
	(segment
		(start 122.510804 -152.479248)
		(end 122.510804 -152.752552)
		(width 0.14224)
		(layer "In11.Cu")
		(net "M_M_DQ<35>")
	)
	(segment
		(start 122.510804 -151.387048)
		(end 122.510804 -151.660352)
		(width 0.14224)
		(layer "In11.Cu")
		(net "M_M_DQ<35>")
	)
	(segment
		(start 123.566682 -140.921486)
		(end 123.566682 -144.182338)
		(width 0.14224)
		(layer "In11.Cu")
		(net "M_M_DQ<35>")
	)
	(segment
		(start 122.510804 -152.752552)
		(end 122.799602 -153.04135)
		(width 0.14224)
		(layer "In11.Cu")
		(net "M_M_DQ<35>")
	)
	(segment
		(start 123.731782 -136.006332)
		(end 123.467368 -136.270746)
		(width 0.14224)
		(layer "In11.Cu")
		(net "M_M_DQ<35>")
	)
	(segment
		(start 122.767852 -152.2222)
		(end 122.510804 -152.479248)
		(width 0.14224)
		(layer "In11.Cu")
		(net "M_M_DQ<35>")
	)
	(segment
		(start 123.41606 -129.666492)
		(end 123.822968 -130.0734)
		(width 0.14224)
		(layer "In11.Cu")
		(net "M_M_DQ<35>")
	)
	(segment
		(start 123.553982 -138.851386)
		(end 123.553982 -139.608814)
		(width 0.14224)
		(layer "In11.Cu")
		(net "M_M_DQ<35>")
	)
	(segment
		(start 114.051842 -103.248714)
		(end 114.145568 -103.34244)
		(width 0.14224)
		(layer "In11.Cu")
		(net "M_M_DQ<35>")
	)
	(segment
		(start 123.822968 -130.0734)
		(end 123.822968 -131.152392)
		(width 0.14224)
		(layer "In11.Cu")
		(net "M_M_DQ<35>")
	)
	(segment
		(start 123.41606 -127.529844)
		(end 123.26112 -127.684784)
		(width 0.14224)
		(layer "In11.Cu")
		(net "M_M_DQ<35>")
	)
	(segment
		(start 113.367312 -114.735356)
		(end 123.41606 -124.784104)
		(width 0.14224)
		(layer "In11.Cu")
		(net "M_M_DQ<35>")
	)
	(segment
		(start 122.777504 -127.839724)
		(end 122.777504 -128.192784)
		(width 0.14224)
		(layer "In11.Cu")
		(net "M_M_DQ<35>")
	)
	(segment
		(start 123.199398 -149.546564)
		(end 123.199398 -149.533356)
		(width 0.14224)
		(layer "In11.Cu")
		(net "M_M_DQ<35>")
	)
	(segment
		(start 111.900716 -98.900234)
		(end 111.933482 -98.900234)
		(width 0.0889)
		(layer "In11.Cu")
		(net "M_M_DQ<35>")
	)
	(segment
		(start 113.286032 -102.662228)
		(end 113.46942 -102.979474)
		(width 0.0889)
		(layer "In11.Cu")
		(net "M_M_DQ<35>")
	)
	(segment
		(start 123.566682 -131.408678)
		(end 123.566682 -131.953)
		(width 0.14224)
		(layer "In11.Cu")
		(net "M_M_DQ<35>")
	)
	(segment
		(start 122.793252 -151.1046)
		(end 122.510804 -151.387048)
		(width 0.14224)
		(layer "In11.Cu")
		(net "M_M_DQ<35>")
	)
	(segment
		(start 123.822968 -131.152392)
		(end 123.566682 -131.408678)
		(width 0.14224)
		(layer "In11.Cu")
		(net "M_M_DQ<35>")
	)
	(segment
		(start 122.748802 -149.9616)
		(end 122.748802 -150.391368)
		(width 0.14224)
		(layer "In11.Cu")
		(net "M_M_DQ<35>")
	)
	(arc
		(start 110.710726 -95.82404)
		(mid 110.657193 -96.023938)
		(end 110.710726 -96.223836)
		(width 0.0889)
		(layer "In11.Cu")
		(net "M_M_DQ<35>")
	)
	(arc
		(start 110.999524 -93.647006)
		(mid 110.697327 -93.868288)
		(end 110.710726 -94.242636)
		(width 0.0889)
		(layer "In11.Cu")
		(net "M_M_DQ<35>")
	)
	(arc
		(start 110.710726 -94.242636)
		(mid 110.78988 -94.531754)
		(end 110.717076 -94.822518)
		(width 0.0889)
		(layer "In11.Cu")
		(net "M_M_DQ<35>")
	)
	(arc
		(start 113.292382 -100.691696)
		(mid 113.36518 -100.982459)
		(end 113.286032 -101.271578)
		(width 0.0889)
		(layer "In11.Cu")
		(net "M_M_DQ<35>")
	)
	(arc
		(start 110.710726 -96.81464)
		(mid 110.657193 -97.014538)
		(end 110.710726 -97.214436)
		(width 0.0889)
		(layer "In11.Cu")
		(net "M_M_DQ<35>")
	)
	(arc
		(start 111.568992 -98.700336)
		(mid 111.709071 -98.843072)
		(end 111.900716 -98.900234)
		(width 0.0889)
		(layer "In11.Cu")
		(net "M_M_DQ<35>")
	)
	(arc
		(start 113.277396 -102.277164)
		(mid 113.232381 -102.470802)
		(end 113.286032 -102.662228)
		(width 0.0889)
		(layer "In11.Cu")
		(net "M_M_DQ<35>")
	)
	(arc
		(start 110.710726 -97.80524)
		(mid 110.710809 -98.205181)
		(end 111.057182 -98.405188)
		(width 0.0889)
		(layer "In11.Cu")
		(net "M_M_DQ<35>")
	)
	(arc
		(start 113.281206 -101.280214)
		(mid 113.232451 -101.476566)
		(end 113.286032 -101.671628)
		(width 0.0889)
		(layer "In11.Cu")
		(net "M_M_DQ<35>")
	)
	(arc
		(start 113.286032 -101.671628)
		(mid 113.365254 -101.960746)
		(end 113.292382 -102.25151)
		(width 0.0889)
		(layer "In11.Cu")
		(net "M_M_DQ<35>")
	)
	(arc
		(start 112.799114 -99.395534)
		(mid 113.291979 -99.701231)
		(end 113.286032 -100.281232)
		(width 0.0889)
		(layer "In11.Cu")
		(net "M_M_DQ<35>")
	)
	(arc
		(start 110.719616 -97.229676)
		(mid 110.790013 -97.518627)
		(end 110.710726 -97.80524)
		(width 0.0889)
		(layer "In11.Cu")
		(net "M_M_DQ<35>")
	)
	(arc
		(start 110.710726 -94.833186)
		(mid 110.657193 -95.033084)
		(end 110.710726 -95.232982)
		(width 0.0889)
		(layer "In11.Cu")
		(net "M_M_DQ<35>")
	)
	(arc
		(start 113.286032 -100.281232)
		(mid 113.232533 -100.48113)
		(end 113.286032 -100.681028)
		(width 0.0889)
		(layer "In11.Cu")
		(net "M_M_DQ<35>")
	)
	(arc
		(start 111.933482 -98.900234)
		(mid 112.218906 -98.983701)
		(end 112.427512 -99.195636)
		(width 0.0889)
		(layer "In11.Cu")
		(net "M_M_DQ<35>")
	)
	(arc
		(start 110.717076 -95.24365)
		(mid 110.789996 -95.534667)
		(end 110.710726 -95.82404)
		(width 0.0889)
		(layer "In11.Cu")
		(net "M_M_DQ<35>")
	)
	(arc
		(start 111.078772 -98.405188)
		(mid 111.361989 -98.489469)
		(end 111.568992 -98.700336)
		(width 0.0889)
		(layer "In11.Cu")
		(net "M_M_DQ<35>")
	)
	(arc
		(start 110.719616 -96.239076)
		(mid 110.790013 -96.528027)
		(end 110.710726 -96.81464)
		(width 0.0889)
		(layer "In11.Cu")
		(net "M_M_DQ<35>")
	)
	(arc
		(start 112.427512 -99.195636)
		(mid 112.566256 -99.337669)
		(end 112.756188 -99.395534)
		(width 0.0889)
		(layer "In11.Cu")
		(net "M_M_DQ<35>")
	)
	(segment
		(start 110.485682 -93.052138)
		(end 111.057182 -93.052138)
		(width 0.1651)
		(layer "F.Cu")
		(net "M_M_DQ<34>")
	)
	(segment
		(start 123.199398 -155.395168)
		(end 123.199398 -155.1178)
		(width 0.1651)
		(layer "F.Cu")
		(net "M_M_DQ<34>")
	)
	(segment
		(start 123.33097 -155.75026)
		(end 123.33097 -155.52674)
		(width 0.1651)
		(layer "F.Cu")
		(net "M_M_DQ<34>")
	)
	(segment
		(start 123.33097 -155.52674)
		(end 123.199398 -155.395168)
		(width 0.1651)
		(layer "F.Cu")
		(net "M_M_DQ<34>")
	)
	(segment
		(start 123.199398 -156.87294)
		(end 123.199398 -155.881832)
		(width 0.1651)
		(layer "F.Cu")
		(net "M_M_DQ<34>")
	)
	(segment
		(start 123.199398 -155.881832)
		(end 123.33097 -155.75026)
		(width 0.1651)
		(layer "F.Cu")
		(net "M_M_DQ<34>")
	)
	(via
		(at 111.057182 -93.052138)
		(size 0.508)
		(drill 0.254)
		(layers "F.Cu" "B.Cu")
		(net "M_M_DQ<34>")
	)
	(via
		(at 122.349514 -150.814278)
		(size 0.508)
		(drill 0.254)
		(layers "F.Cu" "B.Cu")
		(net "M_M_DQ<34>")
	)
	(via
		(at 123.199398 -155.1178)
		(size 0.508)
		(drill 0.254)
		(layers "F.Cu" "B.Cu")
		(net "M_M_DQ<34>")
	)
	(segment
		(start 122.349514 -152.078436)
		(end 122.349514 -150.814278)
		(width 0.1651)
		(layer "B.Cu")
		(net "M_M_DQ<34>")
	)
	(segment
		(start 110.539022 -94.327472)
		(end 110.545372 -94.33814)
		(width 0.0889)
		(layer "In11.Cu")
		(net "M_M_DQ<34>")
	)
	(segment
		(start 122.827288 -136.164574)
		(end 122.827288 -139.47648)
		(width 0.14224)
		(layer "In11.Cu")
		(net "M_M_DQ<34>")
	)
	(segment
		(start 110.536482 -96.303846)
		(end 110.545372 -96.319086)
		(width 0.0889)
		(layer "In11.Cu")
		(net "M_M_DQ<34>")
	)
	(segment
		(start 122.807984 -131.319016)
		(end 122.807984 -134.595362)
		(width 0.14224)
		(layer "In11.Cu")
		(net "M_M_DQ<34>")
	)
	(segment
		(start 122.86996 -141.527022)
		(end 122.775218 -141.621764)
		(width 0.14224)
		(layer "In11.Cu")
		(net "M_M_DQ<34>")
	)
	(segment
		(start 112.646968 -105.8926)
		(end 112.646968 -114.916204)
		(width 0.14224)
		(layer "In11.Cu")
		(net "M_M_DQ<34>")
	)
	(segment
		(start 122.654568 -139.6492)
		(end 122.654568 -140.7414)
		(width 0.14224)
		(layer "In11.Cu")
		(net "M_M_DQ<34>")
	)
	(segment
		(start 122.818398 -129.347976)
		(end 122.818398 -129.858262)
		(width 0.14224)
		(layer "In11.Cu")
		(net "M_M_DQ<34>")
	)
	(segment
		(start 122.72264 -131.233672)
		(end 122.807984 -131.319016)
		(width 0.14224)
		(layer "In11.Cu")
		(net "M_M_DQ<34>")
	)
	(segment
		(start 122.238262 -150.703026)
		(end 122.349514 -150.814278)
		(width 0.14224)
		(layer "In11.Cu")
		(net "M_M_DQ<34>")
	)
	(segment
		(start 122.603768 -145.61439)
		(end 122.884184 -145.894806)
		(width 0.14224)
		(layer "In11.Cu")
		(net "M_M_DQ<34>")
	)
	(segment
		(start 122.28068 -124.549916)
		(end 122.28068 -128.810258)
		(width 0.14224)
		(layer "In11.Cu")
		(net "M_M_DQ<34>")
	)
	(segment
		(start 112.646968 -114.916204)
		(end 122.28068 -124.549916)
		(width 0.14224)
		(layer "In11.Cu")
		(net "M_M_DQ<34>")
	)
	(segment
		(start 122.238262 -149.602698)
		(end 122.238262 -150.703026)
		(width 0.14224)
		(layer "In11.Cu")
		(net "M_M_DQ<34>")
	)
	(segment
		(start 122.775218 -143.60525)
		(end 122.837956 -143.667988)
		(width 0.14224)
		(layer "In11.Cu")
		(net "M_M_DQ<34>")
	)
	(segment
		(start 122.884184 -145.894806)
		(end 122.884184 -148.956776)
		(width 0.14224)
		(layer "In11.Cu")
		(net "M_M_DQ<34>")
	)
	(segment
		(start 122.578368 -134.824978)
		(end 122.578368 -135.915654)
		(width 0.14224)
		(layer "In11.Cu")
		(net "M_M_DQ<34>")
	)
	(segment
		(start 122.86996 -140.956792)
		(end 122.86996 -141.527022)
		(width 0.14224)
		(layer "In11.Cu")
		(net "M_M_DQ<34>")
	)
	(segment
		(start 122.807984 -134.595362)
		(end 122.578368 -134.824978)
		(width 0.14224)
		(layer "In11.Cu")
		(net "M_M_DQ<34>")
	)
	(segment
		(start 111.057182 -93.390212)
		(end 110.992158 -93.455236)
		(width 0.0889)
		(layer "In11.Cu")
		(net "M_M_DQ<34>")
	)
	(segment
		(start 113.120932 -102.757732)
		(end 113.200942 -102.895908)
		(width 0.0889)
		(layer "In11.Cu")
		(net "M_M_DQ<34>")
	)
	(segment
		(start 112.74933 -99.586034)
		(end 112.792256 -99.586034)
		(width 0.0889)
		(layer "In11.Cu")
		(net "M_M_DQ<34>")
	)
	(segment
		(start 111.894112 -99.090734)
		(end 111.926878 -99.090734)
		(width 0.0889)
		(layer "In11.Cu")
		(net "M_M_DQ<34>")
	)
	(segment
		(start 112.999774 -103.375968)
		(end 112.977168 -103.398574)
		(width 0.14224)
		(layer "In11.Cu")
		(net "M_M_DQ<34>")
	)
	(segment
		(start 111.039402 -98.595688)
		(end 111.072168 -98.595688)
		(width 0.0889)
		(layer "In11.Cu")
		(net "M_M_DQ<34>")
	)
	(segment
		(start 122.837956 -144.174464)
		(end 122.603768 -144.408652)
		(width 0.14224)
		(layer "In11.Cu")
		(net "M_M_DQ<34>")
	)
	(segment
		(start 113.200942 -103.1748)
		(end 112.999774 -103.375968)
		(width 0.0889)
		(layer "In11.Cu")
		(net "M_M_DQ<34>")
	)
	(segment
		(start 121.916444 -153.834846)
		(end 123.199398 -155.1178)
		(width 0.14224)
		(layer "In11.Cu")
		(net "M_M_DQ<34>")
	)
	(segment
		(start 122.837956 -143.667988)
		(end 122.837956 -144.174464)
		(width 0.14224)
		(layer "In11.Cu")
		(net "M_M_DQ<34>")
	)
	(segment
		(start 122.72264 -129.95402)
		(end 122.72264 -131.233672)
		(width 0.14224)
		(layer "In11.Cu")
		(net "M_M_DQ<34>")
	)
	(segment
		(start 122.603768 -144.408652)
		(end 122.603768 -145.61439)
		(width 0.14224)
		(layer "In11.Cu")
		(net "M_M_DQ<34>")
	)
	(segment
		(start 122.775218 -141.621764)
		(end 122.775218 -143.60525)
		(width 0.14224)
		(layer "In11.Cu")
		(net "M_M_DQ<34>")
	)
	(segment
		(start 110.545372 -94.737936)
		(end 110.539022 -94.748604)
		(width 0.0889)
		(layer "In11.Cu")
		(net "M_M_DQ<34>")
	)
	(segment
		(start 122.818398 -129.858262)
		(end 122.72264 -129.95402)
		(width 0.14224)
		(layer "In11.Cu")
		(net "M_M_DQ<34>")
	)
	(segment
		(start 112.977168 -105.5624)
		(end 112.646968 -105.8926)
		(width 0.14224)
		(layer "In11.Cu")
		(net "M_M_DQ<34>")
	)
	(segment
		(start 122.827288 -139.47648)
		(end 122.654568 -139.6492)
		(width 0.14224)
		(layer "In11.Cu")
		(net "M_M_DQ<34>")
	)
	(segment
		(start 122.349514 -150.814278)
		(end 121.916444 -151.247348)
		(width 0.14224)
		(layer "In11.Cu")
		(net "M_M_DQ<34>")
	)
	(segment
		(start 113.200942 -102.895908)
		(end 113.200942 -103.1748)
		(width 0.0889)
		(layer "In11.Cu")
		(net "M_M_DQ<34>")
	)
	(segment
		(start 110.536482 -97.294446)
		(end 110.545372 -97.309686)
		(width 0.0889)
		(layer "In11.Cu")
		(net "M_M_DQ<34>")
	)
	(segment
		(start 121.916444 -151.247348)
		(end 121.916444 -153.834846)
		(width 0.14224)
		(layer "In11.Cu")
		(net "M_M_DQ<34>")
	)
	(segment
		(start 122.654568 -140.7414)
		(end 122.86996 -140.956792)
		(width 0.14224)
		(layer "In11.Cu")
		(net "M_M_DQ<34>")
	)
	(segment
		(start 122.578368 -135.915654)
		(end 122.827288 -136.164574)
		(width 0.14224)
		(layer "In11.Cu")
		(net "M_M_DQ<34>")
	)
	(segment
		(start 111.057182 -93.052138)
		(end 111.057182 -93.390212)
		(width 0.0889)
		(layer "In11.Cu")
		(net "M_M_DQ<34>")
	)
	(segment
		(start 112.977168 -103.398574)
		(end 112.977168 -105.5624)
		(width 0.14224)
		(layer "In11.Cu")
		(net "M_M_DQ<34>")
	)
	(segment
		(start 113.12779 -102.154482)
		(end 113.110264 -102.185216)
		(width 0.0889)
		(layer "In11.Cu")
		(net "M_M_DQ<34>")
	)
	(segment
		(start 122.884184 -148.956776)
		(end 122.238262 -149.602698)
		(width 0.14224)
		(layer "In11.Cu")
		(net "M_M_DQ<34>")
	)
	(segment
		(start 113.114582 -100.76561)
		(end 113.120932 -100.776278)
		(width 0.0889)
		(layer "In11.Cu")
		(net "M_M_DQ<34>")
	)
	(segment
		(start 122.28068 -128.810258)
		(end 122.818398 -129.347976)
		(width 0.14224)
		(layer "In11.Cu")
		(net "M_M_DQ<34>")
	)
	(arc
		(start 113.120932 -101.176074)
		(mid 113.041801 -101.471476)
		(end 113.120932 -101.766878)
		(width 0.0889)
		(layer "In11.Cu")
		(net "M_M_DQ<34>")
	)
	(arc
		(start 110.539022 -94.748604)
		(mid 110.466224 -95.039367)
		(end 110.545372 -95.328486)
		(width 0.0889)
		(layer "In11.Cu")
		(net "M_M_DQ<34>")
	)
	(arc
		(start 110.992158 -93.455236)
		(mid 110.53263 -93.770284)
		(end 110.539022 -94.327472)
		(width 0.0889)
		(layer "In11.Cu")
		(net "M_M_DQ<34>")
	)
	(arc
		(start 113.120932 -101.766878)
		(mid 113.17437 -101.959783)
		(end 113.12779 -102.154482)
		(width 0.0889)
		(layer "In11.Cu")
		(net "M_M_DQ<34>")
	)
	(arc
		(start 110.545372 -95.728282)
		(mid 110.466183 -96.014897)
		(end 110.536482 -96.303846)
		(width 0.0889)
		(layer "In11.Cu")
		(net "M_M_DQ<34>")
	)
	(arc
		(start 112.792256 -99.586034)
		(mid 113.125172 -99.793486)
		(end 113.120932 -100.185728)
		(width 0.0889)
		(layer "In11.Cu")
		(net "M_M_DQ<34>")
	)
	(arc
		(start 113.120932 -100.185728)
		(mid 113.04171 -100.474846)
		(end 113.114582 -100.76561)
		(width 0.0889)
		(layer "In11.Cu")
		(net "M_M_DQ<34>")
	)
	(arc
		(start 111.926878 -99.090734)
		(mid 112.120728 -99.147084)
		(end 112.262412 -99.290886)
		(width 0.0889)
		(layer "In11.Cu")
		(net "M_M_DQ<34>")
	)
	(arc
		(start 112.262412 -99.290886)
		(mid 112.467971 -99.500983)
		(end 112.74933 -99.586034)
		(width 0.0889)
		(layer "In11.Cu")
		(net "M_M_DQ<34>")
	)
	(arc
		(start 113.110264 -102.185216)
		(mid 113.041665 -102.47285)
		(end 113.120932 -102.757732)
		(width 0.0889)
		(layer "In11.Cu")
		(net "M_M_DQ<34>")
	)
	(arc
		(start 111.072168 -98.595688)
		(mid 111.26381 -98.652854)
		(end 111.403892 -98.795586)
		(width 0.0889)
		(layer "In11.Cu")
		(net "M_M_DQ<34>")
	)
	(arc
		(start 110.545372 -96.319086)
		(mid 110.598905 -96.518984)
		(end 110.545372 -96.718882)
		(width 0.0889)
		(layer "In11.Cu")
		(net "M_M_DQ<34>")
	)
	(arc
		(start 111.403892 -98.795586)
		(mid 111.610896 -99.00645)
		(end 111.894112 -99.090734)
		(width 0.0889)
		(layer "In11.Cu")
		(net "M_M_DQ<34>")
	)
	(arc
		(start 113.120932 -100.776278)
		(mid 113.174431 -100.976176)
		(end 113.120932 -101.176074)
		(width 0.0889)
		(layer "In11.Cu")
		(net "M_M_DQ<34>")
	)
	(arc
		(start 110.545372 -96.718882)
		(mid 110.466183 -97.005497)
		(end 110.536482 -97.294446)
		(width 0.0889)
		(layer "In11.Cu")
		(net "M_M_DQ<34>")
	)
	(arc
		(start 110.545372 -97.309686)
		(mid 110.598905 -97.509584)
		(end 110.545372 -97.709482)
		(width 0.0889)
		(layer "In11.Cu")
		(net "M_M_DQ<34>")
	)
	(arc
		(start 110.545372 -95.328486)
		(mid 110.598905 -95.528384)
		(end 110.545372 -95.728282)
		(width 0.0889)
		(layer "In11.Cu")
		(net "M_M_DQ<34>")
	)
	(arc
		(start 110.545372 -94.33814)
		(mid 110.598905 -94.538038)
		(end 110.545372 -94.737936)
		(width 0.0889)
		(layer "In11.Cu")
		(net "M_M_DQ<34>")
	)
	(arc
		(start 110.545372 -97.709482)
		(mid 110.541044 -98.292658)
		(end 111.039402 -98.595688)
		(width 0.0889)
		(layer "In11.Cu")
		(net "M_M_DQ<34>")
	)
	(segment
		(start 116.399564 -152.273)
		(end 116.399564 -153.542746)
		(width 0.1651)
		(layer "F.Cu")
		(net "M_M_DQ<33>")
	)
	(segment
		(start 107.051856 -94.042738)
		(end 107.623356 -94.042738)
		(width 0.1651)
		(layer "F.Cu")
		(net "M_M_DQ<33>")
	)
	(via
		(at 107.623356 -94.042738)
		(size 0.508)
		(drill 0.254)
		(layers "F.Cu" "B.Cu")
		(net "M_M_DQ<33>")
	)
	(via
		(at 117.071648 -149.533356)
		(size 0.508)
		(drill 0.254)
		(layers "F.Cu" "B.Cu")
		(net "M_M_DQ<33>")
	)
	(via
		(at 116.399564 -153.542746)
		(size 0.508)
		(drill 0.254)
		(layers "F.Cu" "B.Cu")
		(net "M_M_DQ<33>")
	)
	(segment
		(start 117.249448 -147.478496)
		(end 117.249448 -148.852382)
		(width 0.1651)
		(layer "B.Cu")
		(net "M_M_DQ<33>")
	)
	(segment
		(start 117.249448 -148.852382)
		(end 117.071648 -149.030182)
		(width 0.1651)
		(layer "B.Cu")
		(net "M_M_DQ<33>")
	)
	(segment
		(start 117.071648 -149.030182)
		(end 117.071648 -149.533356)
		(width 0.1651)
		(layer "B.Cu")
		(net "M_M_DQ<33>")
	)
	(segment
		(start 116.91366 -126.728474)
		(end 117.0686 -126.883414)
		(width 0.14224)
		(layer "In11.Cu")
		(net "M_M_DQ<33>")
	)
	(segment
		(start 117.853968 -128.663954)
		(end 117.853968 -129.0828)
		(width 0.14224)
		(layer "In11.Cu")
		(net "M_M_DQ<33>")
	)
	(segment
		(start 107.61218 -100.386388)
		(end 107.623356 -100.386388)
		(width 0.0889)
		(layer "In11.Cu")
		(net "M_M_DQ<33>")
	)
	(segment
		(start 107.623356 -100.386388)
		(end 107.641136 -100.386134)
		(width 0.0889)
		(layer "In11.Cu")
		(net "M_M_DQ<33>")
	)
	(segment
		(start 113.000536 -121.875804)
		(end 113.219484 -121.875804)
		(width 0.14224)
		(layer "In11.Cu")
		(net "M_M_DQ<33>")
	)
	(segment
		(start 116.560854 -152.846024)
		(end 116.80063 -153.0858)
		(width 0.14224)
		(layer "In11.Cu")
		(net "M_M_DQ<33>")
	)
	(segment
		(start 117.699028 -128.509014)
		(end 117.853968 -128.663954)
		(width 0.14224)
		(layer "In11.Cu")
		(net "M_M_DQ<33>")
	)
	(segment
		(start 116.85143 -150.621746)
		(end 116.85143 -151.026368)
		(width 0.14224)
		(layer "In11.Cu")
		(net "M_M_DQ<33>")
	)
	(segment
		(start 114.425476 -121.995946)
		(end 114.425476 -123.377198)
		(width 0.14224)
		(layer "In11.Cu")
		(net "M_M_DQ<33>")
	)
	(segment
		(start 116.648484 -153.542746)
		(end 116.399564 -153.542746)
		(width 0.14224)
		(layer "In11.Cu")
		(net "M_M_DQ<33>")
	)
	(segment
		(start 108.893356 -105.001314)
		(end 108.893356 -116.463826)
		(width 0.14224)
		(layer "In11.Cu")
		(net "M_M_DQ<33>")
	)
	(segment
		(start 117.676168 -134.1374)
		(end 117.559582 -134.253986)
		(width 0.14224)
		(layer "In11.Cu")
		(net "M_M_DQ<33>")
	)
	(segment
		(start 117.0686 -126.883414)
		(end 117.699028 -126.883414)
		(width 0.14224)
		(layer "In11.Cu")
		(net "M_M_DQ<33>")
	)
	(segment
		(start 117.559582 -141.36116)
		(end 117.676168 -141.477746)
		(width 0.14224)
		(layer "In11.Cu")
		(net "M_M_DQ<33>")
	)
	(segment
		(start 114.425476 -123.377198)
		(end 117.00383 -125.955552)
		(width 0.14224)
		(layer "In11.Cu")
		(net "M_M_DQ<33>")
	)
	(segment
		(start 108.893356 -116.463826)
		(end 113.183924 -120.754394)
		(width 0.14224)
		(layer "In11.Cu")
		(net "M_M_DQ<33>")
	)
	(segment
		(start 116.80063 -153.0858)
		(end 116.80063 -153.3906)
		(width 0.14224)
		(layer "In11.Cu")
		(net "M_M_DQ<33>")
	)
	(segment
		(start 117.676168 -148.4122)
		(end 117.559582 -148.528786)
		(width 0.14224)
		(layer "In11.Cu")
		(net "M_M_DQ<33>")
	)
	(segment
		(start 116.621052 -150.391368)
		(end 116.85143 -150.621746)
		(width 0.14224)
		(layer "In11.Cu")
		(net "M_M_DQ<33>")
	)
	(segment
		(start 117.676168 -138.684)
		(end 117.559582 -138.800586)
		(width 0.14224)
		(layer "In11.Cu")
		(net "M_M_DQ<33>")
	)
	(segment
		(start 116.77523 -151.892)
		(end 116.77523 -152.3238)
		(width 0.14224)
		(layer "In11.Cu")
		(net "M_M_DQ<33>")
	)
	(segment
		(start 116.560854 -152.538176)
		(end 116.560854 -152.846024)
		(width 0.14224)
		(layer "In11.Cu")
		(net "M_M_DQ<33>")
	)
	(segment
		(start 117.676168 -131.840986)
		(end 117.676168 -134.1374)
		(width 0.14224)
		(layer "In11.Cu")
		(net "M_M_DQ<33>")
	)
	(segment
		(start 113.219484 -121.875804)
		(end 113.652808 -121.442226)
		(width 0.14224)
		(layer "In11.Cu")
		(net "M_M_DQ<33>")
	)
	(segment
		(start 117.559582 -136.5758)
		(end 117.676168 -136.692386)
		(width 0.14224)
		(layer "In11.Cu")
		(net "M_M_DQ<33>")
	)
	(segment
		(start 117.676168 -136.692386)
		(end 117.676168 -138.684)
		(width 0.14224)
		(layer "In11.Cu")
		(net "M_M_DQ<33>")
	)
	(segment
		(start 116.77523 -152.3238)
		(end 116.560854 -152.538176)
		(width 0.14224)
		(layer "In11.Cu")
		(net "M_M_DQ<33>")
	)
	(segment
		(start 116.85143 -151.026368)
		(end 116.560854 -151.316944)
		(width 0.14224)
		(layer "In11.Cu")
		(net "M_M_DQ<33>")
	)
	(segment
		(start 116.91366 -127.851154)
		(end 116.91366 -128.354074)
		(width 0.14224)
		(layer "In11.Cu")
		(net "M_M_DQ<33>")
	)
	(segment
		(start 117.676168 -146.293586)
		(end 117.676168 -148.4122)
		(width 0.14224)
		(layer "In11.Cu")
		(net "M_M_DQ<33>")
	)
	(segment
		(start 117.699028 -126.883414)
		(end 117.853968 -127.038354)
		(width 0.14224)
		(layer "In11.Cu")
		(net "M_M_DQ<33>")
	)
	(segment
		(start 113.183924 -120.754394)
		(end 113.183924 -120.973342)
		(width 0.14224)
		(layer "In11.Cu")
		(net "M_M_DQ<33>")
	)
	(segment
		(start 107.27182 -99.187)
		(end 107.276646 -99.195636)
		(width 0.0889)
		(layer "In11.Cu")
		(net "M_M_DQ<33>")
	)
	(segment
		(start 112.7506 -121.40692)
		(end 112.7506 -121.625868)
		(width 0.14224)
		(layer "In11.Cu")
		(net "M_M_DQ<33>")
	)
	(segment
		(start 117.0686 -127.696214)
		(end 116.91366 -127.851154)
		(width 0.14224)
		(layer "In11.Cu")
		(net "M_M_DQ<33>")
	)
	(segment
		(start 113.871756 -121.442226)
		(end 114.425476 -121.995946)
		(width 0.14224)
		(layer "In11.Cu")
		(net "M_M_DQ<33>")
	)
	(segment
		(start 117.071648 -149.444456)
		(end 117.071648 -149.533356)
		(width 0.14224)
		(layer "In11.Cu")
		(net "M_M_DQ<33>")
	)
	(segment
		(start 107.27182 -96.2152)
		(end 107.276646 -96.223836)
		(width 0.0889)
		(layer "In11.Cu")
		(net "M_M_DQ<33>")
	)
	(segment
		(start 117.559582 -148.956522)
		(end 117.071648 -149.444456)
		(width 0.14224)
		(layer "In11.Cu")
		(net "M_M_DQ<33>")
	)
	(segment
		(start 117.559582 -143.702786)
		(end 117.559582 -146.177)
		(width 0.14224)
		(layer "In11.Cu")
		(net "M_M_DQ<33>")
	)
	(segment
		(start 112.7506 -121.625868)
		(end 113.000536 -121.875804)
		(width 0.14224)
		(layer "In11.Cu")
		(net "M_M_DQ<33>")
	)
	(segment
		(start 117.559582 -134.253986)
		(end 117.559582 -136.5758)
		(width 0.14224)
		(layer "In11.Cu")
		(net "M_M_DQ<33>")
	)
	(segment
		(start 117.071648 -149.533356)
		(end 117.049296 -149.533356)
		(width 0.14224)
		(layer "In11.Cu")
		(net "M_M_DQ<33>")
	)
	(segment
		(start 117.0686 -128.509014)
		(end 117.699028 -128.509014)
		(width 0.14224)
		(layer "In11.Cu")
		(net "M_M_DQ<33>")
	)
	(segment
		(start 117.853968 -127.038354)
		(end 117.853968 -127.541274)
		(width 0.14224)
		(layer "In11.Cu")
		(net "M_M_DQ<33>")
	)
	(segment
		(start 117.853968 -129.0828)
		(end 117.559582 -129.377186)
		(width 0.14224)
		(layer "In11.Cu")
		(net "M_M_DQ<33>")
	)
	(segment
		(start 117.559582 -148.528786)
		(end 117.559582 -148.956522)
		(width 0.14224)
		(layer "In11.Cu")
		(net "M_M_DQ<33>")
	)
	(segment
		(start 108.214922 -100.977192)
		(end 108.214922 -103.777288)
		(width 0.0889)
		(layer "In11.Cu")
		(net "M_M_DQ<33>")
	)
	(segment
		(start 116.560854 -151.316944)
		(end 116.560854 -151.677624)
		(width 0.14224)
		(layer "In11.Cu")
		(net "M_M_DQ<33>")
	)
	(segment
		(start 107.27182 -98.1964)
		(end 107.276646 -98.205036)
		(width 0.0889)
		(layer "In11.Cu")
		(net "M_M_DQ<33>")
	)
	(segment
		(start 107.282996 -94.822518)
		(end 107.276646 -94.833186)
		(width 0.0889)
		(layer "In11.Cu")
		(net "M_M_DQ<33>")
	)
	(segment
		(start 107.276646 -97.214436)
		(end 107.282996 -97.225104)
		(width 0.0889)
		(layer "In11.Cu")
		(net "M_M_DQ<33>")
	)
	(segment
		(start 107.623356 -94.042738)
		(end 107.33024 -93.873828)
		(width 0.0889)
		(layer "In11.Cu")
		(net "M_M_DQ<33>")
	)
	(segment
		(start 117.00383 -126.135384)
		(end 116.91366 -126.225554)
		(width 0.14224)
		(layer "In11.Cu")
		(net "M_M_DQ<33>")
	)
	(segment
		(start 113.652808 -121.442226)
		(end 113.871756 -121.442226)
		(width 0.14224)
		(layer "In11.Cu")
		(net "M_M_DQ<33>")
	)
	(segment
		(start 117.049296 -149.533356)
		(end 116.621052 -149.9616)
		(width 0.14224)
		(layer "In11.Cu")
		(net "M_M_DQ<33>")
	)
	(segment
		(start 116.91366 -128.354074)
		(end 117.0686 -128.509014)
		(width 0.14224)
		(layer "In11.Cu")
		(net "M_M_DQ<33>")
	)
	(segment
		(start 116.91366 -126.225554)
		(end 116.91366 -126.728474)
		(width 0.14224)
		(layer "In11.Cu")
		(net "M_M_DQ<33>")
	)
	(segment
		(start 116.80063 -153.3906)
		(end 116.648484 -153.542746)
		(width 0.14224)
		(layer "In11.Cu")
		(net "M_M_DQ<33>")
	)
	(segment
		(start 117.853968 -127.541274)
		(end 117.699028 -127.696214)
		(width 0.14224)
		(layer "In11.Cu")
		(net "M_M_DQ<33>")
	)
	(segment
		(start 108.710984 -104.738678)
		(end 108.933488 -104.961182)
		(width 0.0889)
		(layer "In11.Cu")
		(net "M_M_DQ<33>")
	)
	(segment
		(start 117.559582 -129.377186)
		(end 117.559582 -131.7244)
		(width 0.14224)
		(layer "In11.Cu")
		(net "M_M_DQ<33>")
	)
	(segment
		(start 117.559582 -138.800586)
		(end 117.559582 -141.36116)
		(width 0.14224)
		(layer "In11.Cu")
		(net "M_M_DQ<33>")
	)
	(segment
		(start 107.276646 -99.195636)
		(end 107.282996 -99.206304)
		(width 0.0889)
		(layer "In11.Cu")
		(net "M_M_DQ<33>")
	)
	(segment
		(start 107.276646 -98.205036)
		(end 107.282996 -98.215704)
		(width 0.0889)
		(layer "In11.Cu")
		(net "M_M_DQ<33>")
	)
	(segment
		(start 113.183924 -120.973342)
		(end 112.7506 -121.40692)
		(width 0.14224)
		(layer "In11.Cu")
		(net "M_M_DQ<33>")
	)
	(segment
		(start 117.699028 -127.696214)
		(end 117.0686 -127.696214)
		(width 0.14224)
		(layer "In11.Cu")
		(net "M_M_DQ<33>")
	)
	(segment
		(start 108.933488 -104.961182)
		(end 108.893356 -105.001314)
		(width 0.14224)
		(layer "In11.Cu")
		(net "M_M_DQ<33>")
	)
	(segment
		(start 107.33024 -93.873828)
		(end 107.2515 -93.895164)
		(width 0.0889)
		(layer "In11.Cu")
		(net "M_M_DQ<33>")
	)
	(segment
		(start 116.621052 -149.9616)
		(end 116.621052 -150.391368)
		(width 0.14224)
		(layer "In11.Cu")
		(net "M_M_DQ<33>")
	)
	(segment
		(start 108.710984 -104.27335)
		(end 108.710984 -104.738678)
		(width 0.0889)
		(layer "In11.Cu")
		(net "M_M_DQ<33>")
	)
	(segment
		(start 117.559582 -146.177)
		(end 117.676168 -146.293586)
		(width 0.14224)
		(layer "In11.Cu")
		(net "M_M_DQ<33>")
	)
	(segment
		(start 117.00383 -125.955552)
		(end 117.00383 -126.135384)
		(width 0.14224)
		(layer "In11.Cu")
		(net "M_M_DQ<33>")
	)
	(segment
		(start 116.560854 -151.677624)
		(end 116.77523 -151.892)
		(width 0.14224)
		(layer "In11.Cu")
		(net "M_M_DQ<33>")
	)
	(segment
		(start 117.676168 -141.477746)
		(end 117.676168 -143.5862)
		(width 0.14224)
		(layer "In11.Cu")
		(net "M_M_DQ<33>")
	)
	(segment
		(start 117.676168 -143.5862)
		(end 117.559582 -143.702786)
		(width 0.14224)
		(layer "In11.Cu")
		(net "M_M_DQ<33>")
	)
	(segment
		(start 117.559582 -131.7244)
		(end 117.676168 -131.840986)
		(width 0.14224)
		(layer "In11.Cu")
		(net "M_M_DQ<33>")
	)
	(segment
		(start 108.214922 -103.777288)
		(end 108.710984 -104.27335)
		(width 0.0889)
		(layer "In11.Cu")
		(net "M_M_DQ<33>")
	)
	(segment
		(start 107.276646 -96.223836)
		(end 107.282996 -96.234504)
		(width 0.0889)
		(layer "In11.Cu")
		(net "M_M_DQ<33>")
	)
	(segment
		(start 107.27182 -97.2058)
		(end 107.276646 -97.214436)
		(width 0.0889)
		(layer "In11.Cu")
		(net "M_M_DQ<33>")
	)
	(arc
		(start 107.276646 -95.823786)
		(mid 107.223176 -96.018849)
		(end 107.27182 -96.2152)
		(width 0.0889)
		(layer "In11.Cu")
		(net "M_M_DQ<33>")
	)
	(arc
		(start 107.282996 -97.225104)
		(mid 107.355794 -97.515867)
		(end 107.276646 -97.804986)
		(width 0.0889)
		(layer "In11.Cu")
		(net "M_M_DQ<33>")
	)
	(arc
		(start 107.2515 -93.895164)
		(mid 107.224231 -94.071793)
		(end 107.276646 -94.242636)
		(width 0.0889)
		(layer "In11.Cu")
		(net "M_M_DQ<33>")
	)
	(arc
		(start 107.276646 -98.795586)
		(mid 107.223176 -98.990649)
		(end 107.27182 -99.187)
		(width 0.0889)
		(layer "In11.Cu")
		(net "M_M_DQ<33>")
	)
	(arc
		(start 107.282996 -99.206304)
		(mid 107.355794 -99.497067)
		(end 107.276646 -99.786186)
		(width 0.0889)
		(layer "In11.Cu")
		(net "M_M_DQ<33>")
	)
	(arc
		(start 107.276646 -99.786186)
		(mid 107.273898 -100.181653)
		(end 107.61218 -100.386388)
		(width 0.0889)
		(layer "In11.Cu")
		(net "M_M_DQ<33>")
	)
	(arc
		(start 107.282996 -96.234504)
		(mid 107.355794 -96.525267)
		(end 107.276646 -96.814386)
		(width 0.0889)
		(layer "In11.Cu")
		(net "M_M_DQ<33>")
	)
	(arc
		(start 107.276646 -95.232982)
		(mid 107.355777 -95.528384)
		(end 107.276646 -95.823786)
		(width 0.0889)
		(layer "In11.Cu")
		(net "M_M_DQ<33>")
	)
	(arc
		(start 107.276646 -94.242636)
		(mid 107.355868 -94.531754)
		(end 107.282996 -94.822518)
		(width 0.0889)
		(layer "In11.Cu")
		(net "M_M_DQ<33>")
	)
	(arc
		(start 107.282996 -98.215704)
		(mid 107.355794 -98.506467)
		(end 107.276646 -98.795586)
		(width 0.0889)
		(layer "In11.Cu")
		(net "M_M_DQ<33>")
	)
	(arc
		(start 107.276646 -94.833186)
		(mid 107.223147 -95.033084)
		(end 107.276646 -95.232982)
		(width 0.0889)
		(layer "In11.Cu")
		(net "M_M_DQ<33>")
	)
	(arc
		(start 107.276646 -96.814386)
		(mid 107.223176 -97.009449)
		(end 107.27182 -97.2058)
		(width 0.0889)
		(layer "In11.Cu")
		(net "M_M_DQ<33>")
	)
	(arc
		(start 107.641136 -100.386134)
		(mid 108.047886 -100.56531)
		(end 108.214922 -100.977192)
		(width 0.0889)
		(layer "In11.Cu")
		(net "M_M_DQ<33>")
	)
	(arc
		(start 107.276646 -97.804986)
		(mid 107.223176 -98.000049)
		(end 107.27182 -98.1964)
		(width 0.0889)
		(layer "In11.Cu")
		(net "M_M_DQ<33>")
	)
	(segment
		(start 117.249448 -156.878782)
		(end 117.071648 -155.0162)
		(width 0.1651)
		(layer "F.Cu")
		(net "M_M_DQ<32>")
	)
	(segment
		(start 117.249448 -156.87294)
		(end 117.249448 -156.878782)
		(width 0.1651)
		(layer "F.Cu")
		(net "M_M_DQ<32>")
	)
	(segment
		(start 107.910376 -92.556584)
		(end 108.481876 -92.556584)
		(width 0.1651)
		(layer "F.Cu")
		(net "M_M_DQ<32>")
	)
	(via
		(at 108.481876 -92.556584)
		(size 0.508)
		(drill 0.254)
		(layers "F.Cu" "B.Cu")
		(net "M_M_DQ<32>")
	)
	(via
		(at 116.399564 -150.814278)
		(size 0.508)
		(drill 0.254)
		(layers "F.Cu" "B.Cu")
		(net "M_M_DQ<32>")
	)
	(via
		(at 117.071648 -155.0162)
		(size 0.508)
		(drill 0.254)
		(layers "F.Cu" "B.Cu")
		(net "M_M_DQ<32>")
	)
	(segment
		(start 116.399564 -152.078436)
		(end 116.399564 -150.814278)
		(width 0.1651)
		(layer "B.Cu")
		(net "M_M_DQ<32>")
	)
	(segment
		(start 107.111546 -98.300286)
		(end 107.116372 -98.308922)
		(width 0.0889)
		(layer "In11.Cu")
		(net "M_M_DQ<32>")
	)
	(segment
		(start 116.886482 -148.960078)
		(end 116.035582 -149.810978)
		(width 0.14224)
		(layer "In11.Cu")
		(net "M_M_DQ<32>")
	)
	(segment
		(start 116.886482 -148.562314)
		(end 116.886482 -148.960078)
		(width 0.14224)
		(layer "In11.Cu")
		(net "M_M_DQ<32>")
	)
	(segment
		(start 107.105196 -98.289618)
		(end 107.111546 -98.300286)
		(width 0.0889)
		(layer "In11.Cu")
		(net "M_M_DQ<32>")
	)
	(segment
		(start 116.594382 -144.363186)
		(end 116.594382 -145.577814)
		(width 0.14224)
		(layer "In11.Cu")
		(net "M_M_DQ<32>")
	)
	(segment
		(start 116.812568 -141.615414)
		(end 116.812568 -143.7132)
		(width 0.14224)
		(layer "In11.Cu")
		(net "M_M_DQ<32>")
	)
	(segment
		(start 116.775484 -155.0162)
		(end 117.071648 -155.0162)
		(width 0.14224)
		(layer "In11.Cu")
		(net "M_M_DQ<32>")
	)
	(segment
		(start 116.812568 -143.7132)
		(end 116.873782 -143.774414)
		(width 0.14224)
		(layer "In11.Cu")
		(net "M_M_DQ<32>")
	)
	(segment
		(start 107.634532 -93.452188)
		(end 107.623356 -93.452188)
		(width 0.0889)
		(layer "In11.Cu")
		(net "M_M_DQ<32>")
	)
	(segment
		(start 116.837968 -138.8872)
		(end 116.924582 -138.973814)
		(width 0.14224)
		(layer "In11.Cu")
		(net "M_M_DQ<32>")
	)
	(segment
		(start 107.62361 -100.577142)
		(end 107.630722 -100.577142)
		(width 0.0889)
		(layer "In11.Cu")
		(net "M_M_DQ<32>")
	)
	(segment
		(start 115.966494 -154.20721)
		(end 116.775484 -155.0162)
		(width 0.14224)
		(layer "In11.Cu")
		(net "M_M_DQ<32>")
	)
	(segment
		(start 116.873782 -143.774414)
		(end 116.873782 -144.083786)
		(width 0.14224)
		(layer "In11.Cu")
		(net "M_M_DQ<32>")
	)
	(segment
		(start 108.02366 -103.856282)
		(end 108.520992 -104.353614)
		(width 0.0889)
		(layer "In11.Cu")
		(net "M_M_DQ<32>")
	)
	(segment
		(start 108.520992 -104.738678)
		(end 108.298488 -104.961182)
		(width 0.0889)
		(layer "In11.Cu")
		(net "M_M_DQ<32>")
	)
	(segment
		(start 108.298488 -104.961182)
		(end 108.239306 -105.020364)
		(width 0.14224)
		(layer "In11.Cu")
		(net "M_M_DQ<32>")
	)
	(segment
		(start 116.035582 -149.810978)
		(end 116.035582 -150.450296)
		(width 0.14224)
		(layer "In11.Cu")
		(net "M_M_DQ<32>")
	)
	(segment
		(start 116.581682 -130.062478)
		(end 116.581682 -131.141978)
		(width 0.14224)
		(layer "In11.Cu")
		(net "M_M_DQ<32>")
	)
	(segment
		(start 116.812568 -146.276314)
		(end 116.812568 -148.4884)
		(width 0.14224)
		(layer "In11.Cu")
		(net "M_M_DQ<32>")
	)
	(segment
		(start 116.924582 -136.71804)
		(end 116.837968 -136.804654)
		(width 0.14224)
		(layer "In11.Cu")
		(net "M_M_DQ<32>")
	)
	(segment
		(start 116.886482 -145.869914)
		(end 116.886482 -146.2024)
		(width 0.14224)
		(layer "In11.Cu")
		(net "M_M_DQ<32>")
	)
	(segment
		(start 116.581682 -139.663678)
		(end 116.581682 -140.743178)
		(width 0.14224)
		(layer "In11.Cu")
		(net "M_M_DQ<32>")
	)
	(segment
		(start 116.886482 -146.2024)
		(end 116.812568 -146.276314)
		(width 0.14224)
		(layer "In11.Cu")
		(net "M_M_DQ<32>")
	)
	(segment
		(start 116.812568 -148.4884)
		(end 116.886482 -148.562314)
		(width 0.14224)
		(layer "In11.Cu")
		(net "M_M_DQ<32>")
	)
	(segment
		(start 116.581682 -135.96366)
		(end 116.924582 -136.30656)
		(width 0.14224)
		(layer "In11.Cu")
		(net "M_M_DQ<32>")
	)
	(segment
		(start 116.873782 -141.5542)
		(end 116.812568 -141.615414)
		(width 0.14224)
		(layer "In11.Cu")
		(net "M_M_DQ<32>")
	)
	(segment
		(start 116.581682 -140.743178)
		(end 116.873782 -141.035278)
		(width 0.14224)
		(layer "In11.Cu")
		(net "M_M_DQ<32>")
	)
	(segment
		(start 116.924582 -136.30656)
		(end 116.924582 -136.71804)
		(width 0.14224)
		(layer "In11.Cu")
		(net "M_M_DQ<32>")
	)
	(segment
		(start 107.105196 -96.308418)
		(end 107.111546 -96.319086)
		(width 0.0889)
		(layer "In11.Cu")
		(net "M_M_DQ<32>")
	)
	(segment
		(start 108.481876 -92.556584)
		(end 107.98683 -93.222572)
		(width 0.0889)
		(layer "In11.Cu")
		(net "M_M_DQ<32>")
	)
	(segment
		(start 116.924582 -129.719578)
		(end 116.581682 -130.062478)
		(width 0.14224)
		(layer "In11.Cu")
		(net "M_M_DQ<32>")
	)
	(segment
		(start 115.966494 -151.247348)
		(end 115.966494 -154.20721)
		(width 0.14224)
		(layer "In11.Cu")
		(net "M_M_DQ<32>")
	)
	(segment
		(start 116.924582 -131.8514)
		(end 116.837968 -131.938014)
		(width 0.14224)
		(layer "In11.Cu")
		(net "M_M_DQ<32>")
	)
	(segment
		(start 116.837968 -134.0866)
		(end 116.924582 -134.173214)
		(width 0.14224)
		(layer "In11.Cu")
		(net "M_M_DQ<32>")
	)
	(segment
		(start 108.239306 -116.717826)
		(end 111.99876 -120.47728)
		(width 0.14224)
		(layer "In11.Cu")
		(net "M_M_DQ<32>")
	)
	(segment
		(start 116.924582 -139.320778)
		(end 116.581682 -139.663678)
		(width 0.14224)
		(layer "In11.Cu")
		(net "M_M_DQ<32>")
	)
	(segment
		(start 116.035582 -150.450296)
		(end 116.399564 -150.814278)
		(width 0.14224)
		(layer "In11.Cu")
		(net "M_M_DQ<32>")
	)
	(segment
		(start 116.594382 -145.577814)
		(end 116.886482 -145.869914)
		(width 0.14224)
		(layer "In11.Cu")
		(net "M_M_DQ<32>")
	)
	(segment
		(start 116.218716 -125.847602)
		(end 116.218716 -128.692148)
		(width 0.14224)
		(layer "In11.Cu")
		(net "M_M_DQ<32>")
	)
	(segment
		(start 108.520992 -104.353614)
		(end 108.520992 -104.738678)
		(width 0.0889)
		(layer "In11.Cu")
		(net "M_M_DQ<32>")
	)
	(segment
		(start 116.218716 -128.692148)
		(end 116.924582 -129.398014)
		(width 0.14224)
		(layer "In11.Cu")
		(net "M_M_DQ<32>")
	)
	(segment
		(start 116.581682 -134.774432)
		(end 116.581682 -135.96366)
		(width 0.14224)
		(layer "In11.Cu")
		(net "M_M_DQ<32>")
	)
	(segment
		(start 107.105196 -99.280218)
		(end 107.111546 -99.290886)
		(width 0.0889)
		(layer "In11.Cu")
		(net "M_M_DQ<32>")
	)
	(segment
		(start 116.873782 -144.083786)
		(end 116.594382 -144.363186)
		(width 0.14224)
		(layer "In11.Cu")
		(net "M_M_DQ<32>")
	)
	(segment
		(start 107.105196 -97.299018)
		(end 107.111546 -97.309686)
		(width 0.0889)
		(layer "In11.Cu")
		(net "M_M_DQ<32>")
	)
	(segment
		(start 107.98683 -93.222572)
		(end 107.970066 -93.252036)
		(width 0.0889)
		(layer "In11.Cu")
		(net "M_M_DQ<32>")
	)
	(segment
		(start 116.924582 -131.484878)
		(end 116.924582 -131.8514)
		(width 0.14224)
		(layer "In11.Cu")
		(net "M_M_DQ<32>")
	)
	(segment
		(start 116.837968 -136.804654)
		(end 116.837968 -138.8872)
		(width 0.14224)
		(layer "In11.Cu")
		(net "M_M_DQ<32>")
	)
	(segment
		(start 107.111546 -95.328486)
		(end 107.116372 -95.337122)
		(width 0.0889)
		(layer "In11.Cu")
		(net "M_M_DQ<32>")
	)
	(segment
		(start 107.111546 -96.319086)
		(end 107.116372 -96.327722)
		(width 0.0889)
		(layer "In11.Cu")
		(net "M_M_DQ<32>")
	)
	(segment
		(start 116.924582 -134.431532)
		(end 116.581682 -134.774432)
		(width 0.14224)
		(layer "In11.Cu")
		(net "M_M_DQ<32>")
	)
	(segment
		(start 116.924582 -138.973814)
		(end 116.924582 -139.320778)
		(width 0.14224)
		(layer "In11.Cu")
		(net "M_M_DQ<32>")
	)
	(segment
		(start 108.239306 -105.020364)
		(end 108.239306 -116.717826)
		(width 0.14224)
		(layer "In11.Cu")
		(net "M_M_DQ<32>")
	)
	(segment
		(start 107.620054 -100.577396)
		(end 107.62361 -100.577142)
		(width 0.0889)
		(layer "In11.Cu")
		(net "M_M_DQ<32>")
	)
	(segment
		(start 107.111546 -99.290886)
		(end 107.116372 -99.299522)
		(width 0.0889)
		(layer "In11.Cu")
		(net "M_M_DQ<32>")
	)
	(segment
		(start 111.99876 -120.47728)
		(end 111.99876 -121.627646)
		(width 0.14224)
		(layer "In11.Cu")
		(net "M_M_DQ<32>")
	)
	(segment
		(start 111.99876 -121.627646)
		(end 116.218716 -125.847602)
		(width 0.14224)
		(layer "In11.Cu")
		(net "M_M_DQ<32>")
	)
	(segment
		(start 116.873782 -141.035278)
		(end 116.873782 -141.5542)
		(width 0.14224)
		(layer "In11.Cu")
		(net "M_M_DQ<32>")
	)
	(segment
		(start 116.399564 -150.814278)
		(end 115.966494 -151.247348)
		(width 0.14224)
		(layer "In11.Cu")
		(net "M_M_DQ<32>")
	)
	(segment
		(start 116.924582 -129.398014)
		(end 116.924582 -129.719578)
		(width 0.14224)
		(layer "In11.Cu")
		(net "M_M_DQ<32>")
	)
	(segment
		(start 116.837968 -131.938014)
		(end 116.837968 -134.0866)
		(width 0.14224)
		(layer "In11.Cu")
		(net "M_M_DQ<32>")
	)
	(segment
		(start 107.111546 -97.309686)
		(end 107.116372 -97.318322)
		(width 0.0889)
		(layer "In11.Cu")
		(net "M_M_DQ<32>")
	)
	(segment
		(start 116.924582 -134.173214)
		(end 116.924582 -134.431532)
		(width 0.14224)
		(layer "In11.Cu")
		(net "M_M_DQ<32>")
	)
	(segment
		(start 107.111546 -94.737936)
		(end 107.105196 -94.748604)
		(width 0.0889)
		(layer "In11.Cu")
		(net "M_M_DQ<32>")
	)
	(segment
		(start 116.581682 -131.141978)
		(end 116.924582 -131.484878)
		(width 0.14224)
		(layer "In11.Cu")
		(net "M_M_DQ<32>")
	)
	(segment
		(start 108.02366 -100.977192)
		(end 108.02366 -103.856282)
		(width 0.0889)
		(layer "In11.Cu")
		(net "M_M_DQ<32>")
	)
	(arc
		(start 107.116372 -99.299522)
		(mid 107.165127 -99.495874)
		(end 107.111546 -99.690936)
		(width 0.0889)
		(layer "In11.Cu")
		(net "M_M_DQ<32>")
	)
	(arc
		(start 107.630722 -100.577142)
		(mid 107.909036 -100.696795)
		(end 108.02366 -100.977192)
		(width 0.0889)
		(layer "In11.Cu")
		(net "M_M_DQ<32>")
	)
	(arc
		(start 107.111546 -98.700336)
		(mid 107.032324 -98.989454)
		(end 107.105196 -99.280218)
		(width 0.0889)
		(layer "In11.Cu")
		(net "M_M_DQ<32>")
	)
	(arc
		(start 107.116372 -95.337122)
		(mid 107.165127 -95.533474)
		(end 107.111546 -95.728536)
		(width 0.0889)
		(layer "In11.Cu")
		(net "M_M_DQ<32>")
	)
	(arc
		(start 107.111546 -95.728536)
		(mid 107.032324 -96.017654)
		(end 107.105196 -96.308418)
		(width 0.0889)
		(layer "In11.Cu")
		(net "M_M_DQ<32>")
	)
	(arc
		(start 107.111546 -99.690936)
		(mid 107.110782 -100.280412)
		(end 107.620054 -100.577396)
		(width 0.0889)
		(layer "In11.Cu")
		(net "M_M_DQ<32>")
	)
	(arc
		(start 107.081828 -93.805756)
		(mid 107.033268 -94.075481)
		(end 107.111546 -94.33814)
		(width 0.0889)
		(layer "In11.Cu")
		(net "M_M_DQ<32>")
	)
	(arc
		(start 107.116372 -98.308922)
		(mid 107.165127 -98.505274)
		(end 107.111546 -98.700336)
		(width 0.0889)
		(layer "In11.Cu")
		(net "M_M_DQ<32>")
	)
	(arc
		(start 107.970066 -93.252036)
		(mid 107.828383 -93.39584)
		(end 107.634532 -93.452188)
		(width 0.0889)
		(layer "In11.Cu")
		(net "M_M_DQ<32>")
	)
	(arc
		(start 107.111546 -97.709736)
		(mid 107.032324 -97.998854)
		(end 107.105196 -98.289618)
		(width 0.0889)
		(layer "In11.Cu")
		(net "M_M_DQ<32>")
	)
	(arc
		(start 107.111546 -94.33814)
		(mid 107.165045 -94.538038)
		(end 107.111546 -94.737936)
		(width 0.0889)
		(layer "In11.Cu")
		(net "M_M_DQ<32>")
	)
	(arc
		(start 107.623356 -93.452188)
		(mid 107.299848 -93.548165)
		(end 107.081828 -93.805756)
		(width 0.0889)
		(layer "In11.Cu")
		(net "M_M_DQ<32>")
	)
	(arc
		(start 107.116372 -96.327722)
		(mid 107.165127 -96.524074)
		(end 107.111546 -96.719136)
		(width 0.0889)
		(layer "In11.Cu")
		(net "M_M_DQ<32>")
	)
	(arc
		(start 107.116372 -97.318322)
		(mid 107.165127 -97.514674)
		(end 107.111546 -97.709736)
		(width 0.0889)
		(layer "In11.Cu")
		(net "M_M_DQ<32>")
	)
	(arc
		(start 107.105196 -94.748604)
		(mid 107.032398 -95.039367)
		(end 107.111546 -95.328486)
		(width 0.0889)
		(layer "In11.Cu")
		(net "M_M_DQ<32>")
	)
	(arc
		(start 107.111546 -96.719136)
		(mid 107.032324 -97.008254)
		(end 107.105196 -97.299018)
		(width 0.0889)
		(layer "In11.Cu")
		(net "M_M_DQ<32>")
	)
	(segment
		(start 86.636352 -87.28964)
		(end 86.064852 -87.28964)
		(width 0.1651)
		(layer "F.Cu")
		(net "M_M_DQ<31>")
	)
	(segment
		(start 65.399412 -152.273)
		(end 65.399412 -153.542746)
		(width 0.1651)
		(layer "F.Cu")
		(net "M_M_DQ<31>")
	)
	(via
		(at 65.399412 -153.542746)
		(size 0.508)
		(drill 0.254)
		(layers "F.Cu" "B.Cu")
		(net "M_M_DQ<31>")
	)
	(via
		(at 66.249296 -149.533356)
		(size 0.508)
		(drill 0.254)
		(layers "F.Cu" "B.Cu")
		(net "M_M_DQ<31>")
	)
	(via
		(at 86.064852 -87.28964)
		(size 0.508)
		(drill 0.254)
		(layers "F.Cu" "B.Cu")
		(net "M_M_DQ<31>")
	)
	(segment
		(start 66.249296 -147.478496)
		(end 66.249296 -149.533356)
		(width 0.1651)
		(layer "B.Cu")
		(net "M_M_DQ<31>")
	)
	(segment
		(start 66.24955 -147.478496)
		(end 66.249296 -147.478496)
		(width 0.1651)
		(layer "B.Cu")
		(net "M_M_DQ<31>")
	)
	(segment
		(start 66.551302 -141.086078)
		(end 66.551302 -141.5796)
		(width 0.14224)
		(layer "In11.Cu")
		(net "M_M_DQ<31>")
	)
	(segment
		(start 78.732634 -116.667534)
		(end 78.44536 -116.954808)
		(width 0.14224)
		(layer "In11.Cu")
		(net "M_M_DQ<31>")
	)
	(segment
		(start 66.249296 -149.533356)
		(end 66.226944 -149.533356)
		(width 0.14224)
		(layer "In11.Cu")
		(net "M_M_DQ<31>")
	)
	(segment
		(start 82.562192 -102.95763)
		(end 82.77225 -103.167688)
		(width 0.0889)
		(layer "In11.Cu")
		(net "M_M_DQ<31>")
	)
	(segment
		(start 85.713316 -95.405702)
		(end 85.718142 -95.414338)
		(width 0.0889)
		(layer "In11.Cu")
		(net "M_M_DQ<31>")
	)
	(segment
		(start 66.830702 -131.205478)
		(end 66.627502 -131.408678)
		(width 0.14224)
		(layer "In11.Cu")
		(net "M_M_DQ<31>")
	)
	(segment
		(start 75.371452 -120.120664)
		(end 75.152504 -120.120664)
		(width 0.14224)
		(layer "In11.Cu")
		(net "M_M_DQ<31>")
	)
	(segment
		(start 66.771266 -145.646902)
		(end 66.602102 -145.816066)
		(width 0.14224)
		(layer "In11.Cu")
		(net "M_M_DQ<31>")
	)
	(segment
		(start 75.152504 -120.120664)
		(end 74.79665 -120.476518)
		(width 0.14224)
		(layer "In11.Cu")
		(net "M_M_DQ<31>")
	)
	(segment
		(start 66.627502 -144.169638)
		(end 66.771266 -144.313402)
		(width 0.14224)
		(layer "In11.Cu")
		(net "M_M_DQ<31>")
	)
	(segment
		(start 73.78192 -121.979944)
		(end 73.78192 -122.198892)
		(width 0.14224)
		(layer "In11.Cu")
		(net "M_M_DQ<31>")
	)
	(segment
		(start 66.602102 -138.856466)
		(end 66.602102 -139.460478)
		(width 0.14224)
		(layer "In11.Cu")
		(net "M_M_DQ<31>")
	)
	(segment
		(start 66.602102 -139.460478)
		(end 66.830702 -139.689078)
		(width 0.14224)
		(layer "In11.Cu")
		(net "M_M_DQ<31>")
	)
	(segment
		(start 84.806536 -98.62947)
		(end 83.019392 -100.416614)
		(width 0.0889)
		(layer "In11.Cu")
		(net "M_M_DQ<31>")
	)
	(segment
		(start 75.946254 -119.545862)
		(end 76.081128 -119.680736)
		(width 0.14224)
		(layer "In11.Cu")
		(net "M_M_DQ<31>")
	)
	(segment
		(start 78.44536 -116.954808)
		(end 78.157832 -116.954808)
		(width 0.14224)
		(layer "In11.Cu")
		(net "M_M_DQ<31>")
	)
	(segment
		(start 72.853296 -122.419872)
		(end 72.464168 -122.809)
		(width 0.14224)
		(layer "In11.Cu")
		(net "M_M_DQ<31>")
	)
	(segment
		(start 65.84315 -150.435818)
		(end 65.84315 -151.1046)
		(width 0.14224)
		(layer "In11.Cu")
		(net "M_M_DQ<31>")
	)
	(segment
		(start 66.672968 -138.7856)
		(end 66.602102 -138.856466)
		(width 0.14224)
		(layer "In11.Cu")
		(net "M_M_DQ<31>")
	)
	(segment
		(start 72.464168 -122.809)
		(end 68.171822 -122.809)
		(width 0.14224)
		(layer "In11.Cu")
		(net "M_M_DQ<31>")
	)
	(segment
		(start 86.576662 -88.575388)
		(end 86.571836 -88.584024)
		(width 0.0889)
		(layer "In11.Cu")
		(net "M_M_DQ<31>")
	)
	(segment
		(start 86.583012 -90.54592)
		(end 86.576662 -90.556588)
		(width 0.0889)
		(layer "In11.Cu")
		(net "M_M_DQ<31>")
	)
	(segment
		(start 65.560702 -151.387048)
		(end 65.560702 -151.660352)
		(width 0.14224)
		(layer "In11.Cu")
		(net "M_M_DQ<31>")
	)
	(segment
		(start 86.559898 -87.955374)
		(end 86.576662 -87.984838)
		(width 0.0889)
		(layer "In11.Cu")
		(net "M_M_DQ<31>")
	)
	(segment
		(start 66.602102 -145.816066)
		(end 66.602102 -146.2024)
		(width 0.14224)
		(layer "In11.Cu")
		(net "M_M_DQ<31>")
	)
	(segment
		(start 78.915768 -115.3414)
		(end 78.448662 -115.808506)
		(width 0.14224)
		(layer "In11.Cu")
		(net "M_M_DQ<31>")
	)
	(segment
		(start 65.7987 -150.391368)
		(end 65.84315 -150.435818)
		(width 0.14224)
		(layer "In11.Cu")
		(net "M_M_DQ<31>")
	)
	(segment
		(start 86.583012 -88.56472)
		(end 86.576662 -88.575388)
		(width 0.0889)
		(layer "In11.Cu")
		(net "M_M_DQ<31>")
	)
	(segment
		(start 66.551302 -141.5796)
		(end 66.672968 -141.701266)
		(width 0.14224)
		(layer "In11.Cu")
		(net "M_M_DQ<31>")
	)
	(segment
		(start 74.931524 -120.83034)
		(end 74.931524 -121.049288)
		(width 0.14224)
		(layer "In11.Cu")
		(net "M_M_DQ<31>")
	)
	(segment
		(start 66.672968 -136.646666)
		(end 66.672968 -138.7856)
		(width 0.14224)
		(layer "In11.Cu")
		(net "M_M_DQ<31>")
	)
	(segment
		(start 66.602102 -149.191472)
		(end 66.59118 -149.191472)
		(width 0.14224)
		(layer "In11.Cu")
		(net "M_M_DQ<31>")
	)
	(segment
		(start 73.426066 -122.554746)
		(end 73.207118 -122.554746)
		(width 0.14224)
		(layer "In11.Cu")
		(net "M_M_DQ<31>")
	)
	(segment
		(start 76.081128 -119.899684)
		(end 75.725274 -120.255538)
		(width 0.14224)
		(layer "In11.Cu")
		(net "M_M_DQ<31>")
	)
	(segment
		(start 66.59118 -149.191472)
		(end 66.249296 -149.533356)
		(width 0.14224)
		(layer "In11.Cu")
		(net "M_M_DQ<31>")
	)
	(segment
		(start 76.874878 -119.105934)
		(end 76.65593 -119.105934)
		(width 0.14224)
		(layer "In11.Cu")
		(net "M_M_DQ<31>")
	)
	(segment
		(start 83.019392 -102.016814)
		(end 82.562192 -102.474014)
		(width 0.0889)
		(layer "In11.Cu")
		(net "M_M_DQ<31>")
	)
	(segment
		(start 75.506326 -120.255538)
		(end 75.371452 -120.120664)
		(width 0.14224)
		(layer "In11.Cu")
		(net "M_M_DQ<31>")
	)
	(segment
		(start 86.576662 -92.537788)
		(end 86.571836 -92.546424)
		(width 0.0889)
		(layer "In11.Cu")
		(net "M_M_DQ<31>")
	)
	(segment
		(start 82.77225 -105.896918)
		(end 78.915768 -109.7534)
		(width 0.14224)
		(layer "In11.Cu")
		(net "M_M_DQ<31>")
	)
	(segment
		(start 66.805302 -136.011412)
		(end 66.602102 -136.214612)
		(width 0.14224)
		(layer "In11.Cu")
		(net "M_M_DQ<31>")
	)
	(segment
		(start 66.627502 -143.758666)
		(end 66.627502 -144.169638)
		(width 0.14224)
		(layer "In11.Cu")
		(net "M_M_DQ<31>")
	)
	(segment
		(start 77.290168 -116.967)
		(end 77.290168 -117.983)
		(width 0.14224)
		(layer "In11.Cu")
		(net "M_M_DQ<31>")
	)
	(segment
		(start 82.77225 -103.167688)
		(end 82.77225 -105.896918)
		(width 0.14224)
		(layer "In11.Cu")
		(net "M_M_DQ<31>")
	)
	(segment
		(start 66.627502 -131.9022)
		(end 66.672968 -131.947666)
		(width 0.14224)
		(layer "In11.Cu")
		(net "M_M_DQ<31>")
	)
	(segment
		(start 74.221848 -121.270268)
		(end 74.0029 -121.270268)
		(width 0.14224)
		(layer "In11.Cu")
		(net "M_M_DQ<31>")
	)
	(segment
		(start 66.627502 -131.408678)
		(end 66.627502 -131.9022)
		(width 0.14224)
		(layer "In11.Cu")
		(net "M_M_DQ<31>")
	)
	(segment
		(start 66.602102 -146.2024)
		(end 66.672968 -146.273266)
		(width 0.14224)
		(layer "In11.Cu")
		(net "M_M_DQ<31>")
	)
	(segment
		(start 86.583012 -92.52712)
		(end 86.576662 -92.537788)
		(width 0.0889)
		(layer "In11.Cu")
		(net "M_M_DQ<31>")
	)
	(segment
		(start 78.732634 -116.380006)
		(end 78.732634 -116.667534)
		(width 0.14224)
		(layer "In11.Cu")
		(net "M_M_DQ<31>")
	)
	(segment
		(start 74.79665 -120.695466)
		(end 74.931524 -120.83034)
		(width 0.14224)
		(layer "In11.Cu")
		(net "M_M_DQ<31>")
	)
	(segment
		(start 66.602102 -136.214612)
		(end 66.602102 -136.5758)
		(width 0.14224)
		(layer "In11.Cu")
		(net "M_M_DQ<31>")
	)
	(segment
		(start 74.57567 -121.405142)
		(end 74.356722 -121.405142)
		(width 0.14224)
		(layer "In11.Cu")
		(net "M_M_DQ<31>")
	)
	(segment
		(start 66.602102 -136.5758)
		(end 66.672968 -136.646666)
		(width 0.14224)
		(layer "In11.Cu")
		(net "M_M_DQ<31>")
	)
	(segment
		(start 66.627502 -134.579868)
		(end 66.805302 -134.757668)
		(width 0.14224)
		(layer "In11.Cu")
		(net "M_M_DQ<31>")
	)
	(segment
		(start 65.8495 -153.364946)
		(end 65.6717 -153.542746)
		(width 0.14224)
		(layer "In11.Cu")
		(net "M_M_DQ<31>")
	)
	(segment
		(start 73.78192 -122.198892)
		(end 73.426066 -122.554746)
		(width 0.14224)
		(layer "In11.Cu")
		(net "M_M_DQ<31>")
	)
	(segment
		(start 75.946254 -119.326914)
		(end 75.946254 -119.545862)
		(width 0.14224)
		(layer "In11.Cu")
		(net "M_M_DQ<31>")
	)
	(segment
		(start 85.227922 -97.290636)
		(end 85.139022 -97.290636)
		(width 0.0889)
		(layer "In11.Cu")
		(net "M_M_DQ<31>")
	)
	(segment
		(start 65.84315 -151.1046)
		(end 65.560702 -151.387048)
		(width 0.14224)
		(layer "In11.Cu")
		(net "M_M_DQ<31>")
	)
	(segment
		(start 65.81775 -152.2222)
		(end 65.560702 -152.479248)
		(width 0.14224)
		(layer "In11.Cu")
		(net "M_M_DQ<31>")
	)
	(segment
		(start 66.830702 -139.689078)
		(end 66.830702 -140.806678)
		(width 0.14224)
		(layer "In11.Cu")
		(net "M_M_DQ<31>")
	)
	(segment
		(start 77.586332 -116.670836)
		(end 77.290168 -116.967)
		(width 0.14224)
		(layer "In11.Cu")
		(net "M_M_DQ<31>")
	)
	(segment
		(start 78.157832 -116.954808)
		(end 77.87386 -116.670836)
		(width 0.14224)
		(layer "In11.Cu")
		(net "M_M_DQ<31>")
	)
	(segment
		(start 66.745866 -124.234956)
		(end 66.745866 -125.555502)
		(width 0.14224)
		(layer "In11.Cu")
		(net "M_M_DQ<31>")
	)
	(segment
		(start 77.230732 -118.531132)
		(end 77.230732 -118.75008)
		(width 0.14224)
		(layer "In11.Cu")
		(net "M_M_DQ<31>")
	)
	(segment
		(start 76.081128 -119.680736)
		(end 76.081128 -119.899684)
		(width 0.14224)
		(layer "In11.Cu")
		(net "M_M_DQ<31>")
	)
	(segment
		(start 82.562192 -102.474014)
		(end 82.562192 -102.95763)
		(width 0.0889)
		(layer "In11.Cu")
		(net "M_M_DQ<31>")
	)
	(segment
		(start 66.805302 -134.757668)
		(end 66.805302 -136.011412)
		(width 0.14224)
		(layer "In11.Cu")
		(net "M_M_DQ<31>")
	)
	(segment
		(start 77.230732 -118.75008)
		(end 76.874878 -119.105934)
		(width 0.14224)
		(layer "In11.Cu")
		(net "M_M_DQ<31>")
	)
	(segment
		(start 66.226944 -149.533356)
		(end 65.7987 -149.9616)
		(width 0.14224)
		(layer "In11.Cu")
		(net "M_M_DQ<31>")
	)
	(segment
		(start 66.627502 -134.081266)
		(end 66.627502 -134.579868)
		(width 0.14224)
		(layer "In11.Cu")
		(net "M_M_DQ<31>")
	)
	(segment
		(start 73.072244 -122.419872)
		(end 72.853296 -122.419872)
		(width 0.14224)
		(layer "In11.Cu")
		(net "M_M_DQ<31>")
	)
	(segment
		(start 66.771266 -144.313402)
		(end 66.771266 -145.646902)
		(width 0.14224)
		(layer "In11.Cu")
		(net "M_M_DQ<31>")
	)
	(segment
		(start 85.138768 -97.29089)
		(end 85.04047 -97.29089)
		(width 0.0889)
		(layer "In11.Cu")
		(net "M_M_DQ<31>")
	)
	(segment
		(start 65.560702 -151.660352)
		(end 65.81775 -151.9174)
		(width 0.14224)
		(layer "In11.Cu")
		(net "M_M_DQ<31>")
	)
	(segment
		(start 66.672968 -131.947666)
		(end 66.672968 -134.0358)
		(width 0.14224)
		(layer "In11.Cu")
		(net "M_M_DQ<31>")
	)
	(segment
		(start 65.7987 -149.9616)
		(end 65.7987 -150.391368)
		(width 0.14224)
		(layer "In11.Cu")
		(net "M_M_DQ<31>")
	)
	(segment
		(start 76.65593 -119.105934)
		(end 76.521056 -118.97106)
		(width 0.14224)
		(layer "In11.Cu")
		(net "M_M_DQ<31>")
	)
	(segment
		(start 66.672968 -148.463)
		(end 66.602102 -148.533866)
		(width 0.14224)
		(layer "In11.Cu")
		(net "M_M_DQ<31>")
	)
	(segment
		(start 66.745866 -125.555502)
		(end 66.602102 -125.699266)
		(width 0.14224)
		(layer "In11.Cu")
		(net "M_M_DQ<31>")
	)
	(segment
		(start 75.725274 -120.255538)
		(end 75.506326 -120.255538)
		(width 0.14224)
		(layer "In11.Cu")
		(net "M_M_DQ<31>")
	)
	(segment
		(start 66.672968 -143.7132)
		(end 66.627502 -143.758666)
		(width 0.14224)
		(layer "In11.Cu")
		(net "M_M_DQ<31>")
	)
	(segment
		(start 86.583012 -91.53652)
		(end 86.576662 -91.547188)
		(width 0.0889)
		(layer "In11.Cu")
		(net "M_M_DQ<31>")
	)
	(segment
		(start 66.672968 -134.0358)
		(end 66.627502 -134.081266)
		(width 0.14224)
		(layer "In11.Cu")
		(net "M_M_DQ<31>")
	)
	(segment
		(start 77.87386 -116.670836)
		(end 77.586332 -116.670836)
		(width 0.14224)
		(layer "In11.Cu")
		(net "M_M_DQ<31>")
	)
	(segment
		(start 86.576662 -89.565988)
		(end 86.571836 -89.574624)
		(width 0.0889)
		(layer "In11.Cu")
		(net "M_M_DQ<31>")
	)
	(segment
		(start 77.095858 -118.17731)
		(end 77.095858 -118.396258)
		(width 0.14224)
		(layer "In11.Cu")
		(net "M_M_DQ<31>")
	)
	(segment
		(start 85.713316 -96.396302)
		(end 85.718142 -96.404938)
		(width 0.0889)
		(layer "In11.Cu")
		(net "M_M_DQ<31>")
	)
	(segment
		(start 68.171822 -122.809)
		(end 66.745866 -124.234956)
		(width 0.14224)
		(layer "In11.Cu")
		(net "M_M_DQ<31>")
	)
	(segment
		(start 86.064852 -87.28964)
		(end 86.559898 -87.955374)
		(width 0.0889)
		(layer "In11.Cu")
		(net "M_M_DQ<31>")
	)
	(segment
		(start 85.139022 -97.290636)
		(end 85.138768 -97.29089)
		(width 0.0889)
		(layer "In11.Cu")
		(net "M_M_DQ<31>")
	)
	(segment
		(start 73.207118 -122.554746)
		(end 73.072244 -122.419872)
		(width 0.14224)
		(layer "In11.Cu")
		(net "M_M_DQ<31>")
	)
	(segment
		(start 84.806536 -97.524824)
		(end 84.806536 -98.62947)
		(width 0.0889)
		(layer "In11.Cu")
		(net "M_M_DQ<31>")
	)
	(segment
		(start 86.583012 -89.55532)
		(end 86.576662 -89.565988)
		(width 0.0889)
		(layer "In11.Cu")
		(net "M_M_DQ<31>")
	)
	(segment
		(start 65.560702 -152.479248)
		(end 65.560702 -152.752552)
		(width 0.14224)
		(layer "In11.Cu")
		(net "M_M_DQ<31>")
	)
	(segment
		(start 76.302108 -118.97106)
		(end 75.946254 -119.326914)
		(width 0.14224)
		(layer "In11.Cu")
		(net "M_M_DQ<31>")
	)
	(segment
		(start 86.576662 -91.547188)
		(end 86.571836 -91.555824)
		(width 0.0889)
		(layer "In11.Cu")
		(net "M_M_DQ<31>")
	)
	(segment
		(start 78.915768 -109.7534)
		(end 78.915768 -115.3414)
		(width 0.14224)
		(layer "In11.Cu")
		(net "M_M_DQ<31>")
	)
	(segment
		(start 85.718142 -95.414338)
		(end 85.724492 -95.425006)
		(width 0.0889)
		(layer "In11.Cu")
		(net "M_M_DQ<31>")
	)
	(segment
		(start 65.8495 -153.04135)
		(end 65.8495 -153.364946)
		(width 0.14224)
		(layer "In11.Cu")
		(net "M_M_DQ<31>")
	)
	(segment
		(start 66.830702 -130.087878)
		(end 66.830702 -131.205478)
		(width 0.14224)
		(layer "In11.Cu")
		(net "M_M_DQ<31>")
	)
	(segment
		(start 74.79665 -120.476518)
		(end 74.79665 -120.695466)
		(width 0.14224)
		(layer "In11.Cu")
		(net "M_M_DQ<31>")
	)
	(segment
		(start 66.602102 -148.533866)
		(end 66.602102 -149.191472)
		(width 0.14224)
		(layer "In11.Cu")
		(net "M_M_DQ<31>")
	)
	(segment
		(start 76.521056 -118.97106)
		(end 76.302108 -118.97106)
		(width 0.14224)
		(layer "In11.Cu")
		(net "M_M_DQ<31>")
	)
	(segment
		(start 86.086442 -93.82379)
		(end 86.046818 -93.82379)
		(width 0.0889)
		(layer "In11.Cu")
		(net "M_M_DQ<31>")
	)
	(segment
		(start 73.647046 -121.84507)
		(end 73.78192 -121.979944)
		(width 0.14224)
		(layer "In11.Cu")
		(net "M_M_DQ<31>")
	)
	(segment
		(start 65.6717 -153.542746)
		(end 65.399412 -153.542746)
		(width 0.14224)
		(layer "In11.Cu")
		(net "M_M_DQ<31>")
	)
	(segment
		(start 66.672968 -141.701266)
		(end 66.672968 -143.7132)
		(width 0.14224)
		(layer "In11.Cu")
		(net "M_M_DQ<31>")
	)
	(segment
		(start 77.290168 -117.983)
		(end 77.095858 -118.17731)
		(width 0.14224)
		(layer "In11.Cu")
		(net "M_M_DQ<31>")
	)
	(segment
		(start 65.81775 -151.9174)
		(end 65.81775 -152.2222)
		(width 0.14224)
		(layer "In11.Cu")
		(net "M_M_DQ<31>")
	)
	(segment
		(start 74.356722 -121.405142)
		(end 74.221848 -121.270268)
		(width 0.14224)
		(layer "In11.Cu")
		(net "M_M_DQ<31>")
	)
	(segment
		(start 86.576662 -90.556588)
		(end 86.571836 -90.565224)
		(width 0.0889)
		(layer "In11.Cu")
		(net "M_M_DQ<31>")
	)
	(segment
		(start 78.448662 -116.096034)
		(end 78.732634 -116.380006)
		(width 0.14224)
		(layer "In11.Cu")
		(net "M_M_DQ<31>")
	)
	(segment
		(start 74.0029 -121.270268)
		(end 73.647046 -121.626122)
		(width 0.14224)
		(layer "In11.Cu")
		(net "M_M_DQ<31>")
	)
	(segment
		(start 65.560702 -152.752552)
		(end 65.8495 -153.04135)
		(width 0.14224)
		(layer "In11.Cu")
		(net "M_M_DQ<31>")
	)
	(segment
		(start 66.602102 -129.859278)
		(end 66.830702 -130.087878)
		(width 0.14224)
		(layer "In11.Cu")
		(net "M_M_DQ<31>")
	)
	(segment
		(start 77.095858 -118.396258)
		(end 77.230732 -118.531132)
		(width 0.14224)
		(layer "In11.Cu")
		(net "M_M_DQ<31>")
	)
	(segment
		(start 85.04047 -97.29089)
		(end 84.806536 -97.524824)
		(width 0.0889)
		(layer "In11.Cu")
		(net "M_M_DQ<31>")
	)
	(segment
		(start 66.602102 -125.699266)
		(end 66.602102 -129.859278)
		(width 0.14224)
		(layer "In11.Cu")
		(net "M_M_DQ<31>")
	)
	(segment
		(start 66.672968 -146.273266)
		(end 66.672968 -148.463)
		(width 0.14224)
		(layer "In11.Cu")
		(net "M_M_DQ<31>")
	)
	(segment
		(start 74.931524 -121.049288)
		(end 74.57567 -121.405142)
		(width 0.14224)
		(layer "In11.Cu")
		(net "M_M_DQ<31>")
	)
	(segment
		(start 73.647046 -121.626122)
		(end 73.647046 -121.84507)
		(width 0.14224)
		(layer "In11.Cu")
		(net "M_M_DQ<31>")
	)
	(segment
		(start 78.448662 -115.808506)
		(end 78.448662 -116.096034)
		(width 0.14224)
		(layer "In11.Cu")
		(net "M_M_DQ<31>")
	)
	(segment
		(start 66.830702 -140.806678)
		(end 66.551302 -141.086078)
		(width 0.14224)
		(layer "In11.Cu")
		(net "M_M_DQ<31>")
	)
	(segment
		(start 83.019392 -100.416614)
		(end 83.019392 -102.016814)
		(width 0.0889)
		(layer "In11.Cu")
		(net "M_M_DQ<31>")
	)
	(segment
		(start 85.718142 -96.404938)
		(end 85.724492 -96.415606)
		(width 0.0889)
		(layer "In11.Cu")
		(net "M_M_DQ<31>")
	)
	(arc
		(start 85.718142 -94.423484)
		(mid 85.797273 -94.718886)
		(end 85.718142 -95.014288)
		(width 0.0889)
		(layer "In11.Cu")
		(net "M_M_DQ<31>")
	)
	(arc
		(start 85.724492 -96.415606)
		(mid 85.720461 -96.991788)
		(end 85.227922 -97.290636)
		(width 0.0889)
		(layer "In11.Cu")
		(net "M_M_DQ<31>")
	)
	(arc
		(start 86.576662 -88.975438)
		(mid 86.655884 -89.264556)
		(end 86.583012 -89.55532)
		(width 0.0889)
		(layer "In11.Cu")
		(net "M_M_DQ<31>")
	)
	(arc
		(start 85.718142 -95.014288)
		(mid 85.664672 -95.209351)
		(end 85.713316 -95.405702)
		(width 0.0889)
		(layer "In11.Cu")
		(net "M_M_DQ<31>")
	)
	(arc
		(start 86.576662 -92.937838)
		(mid 86.581916 -93.519346)
		(end 86.086442 -93.82379)
		(width 0.0889)
		(layer "In11.Cu")
		(net "M_M_DQ<31>")
	)
	(arc
		(start 86.571836 -91.555824)
		(mid 86.523081 -91.752176)
		(end 86.576662 -91.947238)
		(width 0.0889)
		(layer "In11.Cu")
		(net "M_M_DQ<31>")
	)
	(arc
		(start 86.576662 -91.947238)
		(mid 86.655884 -92.236356)
		(end 86.583012 -92.52712)
		(width 0.0889)
		(layer "In11.Cu")
		(net "M_M_DQ<31>")
	)
	(arc
		(start 86.571836 -92.546424)
		(mid 86.523081 -92.742776)
		(end 86.576662 -92.937838)
		(width 0.0889)
		(layer "In11.Cu")
		(net "M_M_DQ<31>")
	)
	(arc
		(start 86.046818 -93.82379)
		(mid 85.713902 -94.031242)
		(end 85.718142 -94.423484)
		(width 0.0889)
		(layer "In11.Cu")
		(net "M_M_DQ<31>")
	)
	(arc
		(start 86.576662 -87.984838)
		(mid 86.655884 -88.273956)
		(end 86.583012 -88.56472)
		(width 0.0889)
		(layer "In11.Cu")
		(net "M_M_DQ<31>")
	)
	(arc
		(start 86.576662 -89.966038)
		(mid 86.655884 -90.255156)
		(end 86.583012 -90.54592)
		(width 0.0889)
		(layer "In11.Cu")
		(net "M_M_DQ<31>")
	)
	(arc
		(start 86.576662 -90.956638)
		(mid 86.655884 -91.245756)
		(end 86.583012 -91.53652)
		(width 0.0889)
		(layer "In11.Cu")
		(net "M_M_DQ<31>")
	)
	(arc
		(start 86.571836 -90.565224)
		(mid 86.523081 -90.761576)
		(end 86.576662 -90.956638)
		(width 0.0889)
		(layer "In11.Cu")
		(net "M_M_DQ<31>")
	)
	(arc
		(start 85.718142 -96.004888)
		(mid 85.664672 -96.199951)
		(end 85.713316 -96.396302)
		(width 0.0889)
		(layer "In11.Cu")
		(net "M_M_DQ<31>")
	)
	(arc
		(start 86.571836 -88.584024)
		(mid 86.523081 -88.780376)
		(end 86.576662 -88.975438)
		(width 0.0889)
		(layer "In11.Cu")
		(net "M_M_DQ<31>")
	)
	(arc
		(start 86.571836 -89.574624)
		(mid 86.523081 -89.770976)
		(end 86.576662 -89.966038)
		(width 0.0889)
		(layer "In11.Cu")
		(net "M_M_DQ<31>")
	)
	(arc
		(start 85.724492 -95.425006)
		(mid 85.79729 -95.715769)
		(end 85.718142 -96.004888)
		(width 0.0889)
		(layer "In11.Cu")
		(net "M_M_DQ<31>")
	)
	(segment
		(start 66.24955 -155.4226)
		(end 66.24955 -155.118054)
		(width 0.1651)
		(layer "F.Cu")
		(net "M_M_DQ<30>")
	)
	(segment
		(start 66.24955 -156.87294)
		(end 66.24955 -155.9052)
		(width 0.1651)
		(layer "F.Cu")
		(net "M_M_DQ<30>")
	)
	(segment
		(start 66.38163 -155.55468)
		(end 66.24955 -155.4226)
		(width 0.1651)
		(layer "F.Cu")
		(net "M_M_DQ<30>")
	)
	(segment
		(start 86.636352 -85.30844)
		(end 86.064852 -85.30844)
		(width 0.1651)
		(layer "F.Cu")
		(net "M_M_DQ<30>")
	)
	(segment
		(start 66.24955 -155.9052)
		(end 66.38163 -155.77312)
		(width 0.1651)
		(layer "F.Cu")
		(net "M_M_DQ<30>")
	)
	(segment
		(start 66.24955 -155.118054)
		(end 66.249296 -155.1178)
		(width 0.1651)
		(layer "F.Cu")
		(net "M_M_DQ<30>")
	)
	(segment
		(start 66.38163 -155.77312)
		(end 66.38163 -155.55468)
		(width 0.1651)
		(layer "F.Cu")
		(net "M_M_DQ<30>")
	)
	(via
		(at 65.399412 -150.814278)
		(size 0.508)
		(drill 0.254)
		(layers "F.Cu" "B.Cu")
		(net "M_M_DQ<30>")
	)
	(via
		(at 86.064852 -85.30844)
		(size 0.508)
		(drill 0.254)
		(layers "F.Cu" "B.Cu")
		(net "M_M_DQ<30>")
	)
	(via
		(at 66.249296 -155.1178)
		(size 0.508)
		(drill 0.254)
		(layers "F.Cu" "B.Cu")
		(net "M_M_DQ<30>")
	)
	(segment
		(start 65.399412 -152.078436)
		(end 65.399412 -150.814278)
		(width 0.1651)
		(layer "B.Cu")
		(net "M_M_DQ<30>")
	)
	(segment
		(start 86.411562 -88.480138)
		(end 86.405212 -88.490806)
		(width 0.0889)
		(layer "In11.Cu")
		(net "M_M_DQ<30>")
	)
	(segment
		(start 65.967102 -148.940266)
		(end 65.225168 -149.6822)
		(width 0.14224)
		(layer "In11.Cu")
		(net "M_M_DQ<30>")
	)
	(segment
		(start 85.553042 -96.500188)
		(end 85.557868 -96.508824)
		(width 0.0889)
		(layer "In11.Cu")
		(net "M_M_DQ<30>")
	)
	(segment
		(start 65.967102 -138.816334)
		(end 65.967102 -139.460478)
		(width 0.14224)
		(layer "In11.Cu")
		(net "M_M_DQ<30>")
	)
	(segment
		(start 85.546692 -96.48952)
		(end 85.553042 -96.500188)
		(width 0.0889)
		(layer "In11.Cu")
		(net "M_M_DQ<30>")
	)
	(segment
		(start 65.809368 -124.1806)
		(end 65.809368 -125.6284)
		(width 0.14224)
		(layer "In11.Cu")
		(net "M_M_DQ<30>")
	)
	(segment
		(start 86.064852 -87.88019)
		(end 86.079838 -87.88019)
		(width 0.0889)
		(layer "In11.Cu")
		(net "M_M_DQ<30>")
	)
	(segment
		(start 65.763902 -131.307078)
		(end 65.865502 -131.408678)
		(width 0.14224)
		(layer "In11.Cu")
		(net "M_M_DQ<30>")
	)
	(segment
		(start 85.060028 -97.100898)
		(end 84.96173 -97.100898)
		(width 0.0889)
		(layer "In11.Cu")
		(net "M_M_DQ<30>")
	)
	(segment
		(start 65.865502 -131.408678)
		(end 65.865502 -131.9022)
		(width 0.14224)
		(layer "In11.Cu")
		(net "M_M_DQ<30>")
	)
	(segment
		(start 82.13725 -105.617518)
		(end 78.255368 -109.4994)
		(width 0.14224)
		(layer "In11.Cu")
		(net "M_M_DQ<30>")
	)
	(segment
		(start 65.967102 -125.786134)
		(end 65.967102 -129.859278)
		(width 0.14224)
		(layer "In11.Cu")
		(net "M_M_DQ<30>")
	)
	(segment
		(start 65.64376 -145.534126)
		(end 65.967102 -145.857468)
		(width 0.14224)
		(layer "In11.Cu")
		(net "M_M_DQ<30>")
	)
	(segment
		(start 86.411562 -89.470738)
		(end 86.405212 -89.481406)
		(width 0.0889)
		(layer "In11.Cu")
		(net "M_M_DQ<30>")
	)
	(segment
		(start 76.604368 -117.7544)
		(end 72.184768 -122.174)
		(width 0.14224)
		(layer "In11.Cu")
		(net "M_M_DQ<30>")
	)
	(segment
		(start 86.411562 -90.461338)
		(end 86.405212 -90.472006)
		(width 0.0889)
		(layer "In11.Cu")
		(net "M_M_DQ<30>")
	)
	(segment
		(start 65.64376 -144.39138)
		(end 65.64376 -145.534126)
		(width 0.14224)
		(layer "In11.Cu")
		(net "M_M_DQ<30>")
	)
	(segment
		(start 65.834768 -146.309334)
		(end 65.834768 -148.4376)
		(width 0.14224)
		(layer "In11.Cu")
		(net "M_M_DQ<30>")
	)
	(segment
		(start 82.13725 -103.167688)
		(end 82.13725 -105.617518)
		(width 0.14224)
		(layer "In11.Cu")
		(net "M_M_DQ<30>")
	)
	(segment
		(start 86.064852 -85.30844)
		(end 85.734906 -86.070186)
		(width 0.0889)
		(layer "In11.Cu")
		(net "M_M_DQ<30>")
	)
	(segment
		(start 86.411562 -91.451938)
		(end 86.405212 -91.462606)
		(width 0.0889)
		(layer "In11.Cu")
		(net "M_M_DQ<30>")
	)
	(segment
		(start 85.718142 -86.498938)
		(end 85.724492 -86.509606)
		(width 0.0889)
		(layer "In11.Cu")
		(net "M_M_DQ<30>")
	)
	(segment
		(start 65.967102 -136.276588)
		(end 65.967102 -136.69772)
		(width 0.14224)
		(layer "In11.Cu")
		(net "M_M_DQ<30>")
	)
	(segment
		(start 82.358992 -102.945946)
		(end 82.13725 -103.167688)
		(width 0.0889)
		(layer "In11.Cu")
		(net "M_M_DQ<30>")
	)
	(segment
		(start 65.967102 -145.857468)
		(end 65.967102 -146.177)
		(width 0.14224)
		(layer "In11.Cu")
		(net "M_M_DQ<30>")
	)
	(segment
		(start 65.763902 -136.073388)
		(end 65.967102 -136.276588)
		(width 0.14224)
		(layer "In11.Cu")
		(net "M_M_DQ<30>")
	)
	(segment
		(start 65.225168 -150.640034)
		(end 65.399412 -150.814278)
		(width 0.14224)
		(layer "In11.Cu")
		(net "M_M_DQ<30>")
	)
	(segment
		(start 65.763902 -130.062478)
		(end 65.763902 -131.307078)
		(width 0.14224)
		(layer "In11.Cu")
		(net "M_M_DQ<30>")
	)
	(segment
		(start 64.966342 -151.247348)
		(end 64.966342 -153.834846)
		(width 0.14224)
		(layer "In11.Cu")
		(net "M_M_DQ<30>")
	)
	(segment
		(start 65.834768 -148.4376)
		(end 65.967102 -148.569934)
		(width 0.14224)
		(layer "In11.Cu")
		(net "M_M_DQ<30>")
	)
	(segment
		(start 65.834768 -134.0104)
		(end 65.865502 -134.041134)
		(width 0.14224)
		(layer "In11.Cu")
		(net "M_M_DQ<30>")
	)
	(segment
		(start 65.916302 -144.118838)
		(end 65.64376 -144.39138)
		(width 0.14224)
		(layer "In11.Cu")
		(net "M_M_DQ<30>")
	)
	(segment
		(start 65.967102 -136.69772)
		(end 65.823084 -136.841738)
		(width 0.14224)
		(layer "In11.Cu")
		(net "M_M_DQ<30>")
	)
	(segment
		(start 65.916302 -141.060678)
		(end 65.916302 -141.5796)
		(width 0.14224)
		(layer "In11.Cu")
		(net "M_M_DQ<30>")
	)
	(segment
		(start 65.967102 -129.859278)
		(end 65.763902 -130.062478)
		(width 0.14224)
		(layer "In11.Cu")
		(net "M_M_DQ<30>")
	)
	(segment
		(start 65.865502 -131.9022)
		(end 65.834768 -131.932934)
		(width 0.14224)
		(layer "In11.Cu")
		(net "M_M_DQ<30>")
	)
	(segment
		(start 65.823084 -136.841738)
		(end 65.823084 -138.672316)
		(width 0.14224)
		(layer "In11.Cu")
		(net "M_M_DQ<30>")
	)
	(segment
		(start 85.132418 -97.100136)
		(end 85.13191 -97.100644)
		(width 0.0889)
		(layer "In11.Cu")
		(net "M_M_DQ<30>")
	)
	(segment
		(start 65.763902 -139.663678)
		(end 65.763902 -140.908278)
		(width 0.14224)
		(layer "In11.Cu")
		(net "M_M_DQ<30>")
	)
	(segment
		(start 65.865502 -134.041134)
		(end 65.865502 -134.579868)
		(width 0.14224)
		(layer "In11.Cu")
		(net "M_M_DQ<30>")
	)
	(segment
		(start 65.967102 -146.177)
		(end 65.834768 -146.309334)
		(width 0.14224)
		(layer "In11.Cu")
		(net "M_M_DQ<30>")
	)
	(segment
		(start 65.834768 -131.932934)
		(end 65.834768 -134.0104)
		(width 0.14224)
		(layer "In11.Cu")
		(net "M_M_DQ<30>")
	)
	(segment
		(start 78.255368 -115.0366)
		(end 76.604368 -116.6876)
		(width 0.14224)
		(layer "In11.Cu")
		(net "M_M_DQ<30>")
	)
	(segment
		(start 85.713316 -86.490302)
		(end 85.718142 -86.498938)
		(width 0.0889)
		(layer "In11.Cu")
		(net "M_M_DQ<30>")
	)
	(segment
		(start 85.060282 -97.100644)
		(end 85.060028 -97.100898)
		(width 0.0889)
		(layer "In11.Cu")
		(net "M_M_DQ<30>")
	)
	(segment
		(start 84.96173 -97.100898)
		(end 84.616544 -97.446084)
		(width 0.0889)
		(layer "In11.Cu")
		(net "M_M_DQ<30>")
	)
	(segment
		(start 65.916302 -143.794734)
		(end 65.916302 -144.118838)
		(width 0.14224)
		(layer "In11.Cu")
		(net "M_M_DQ<30>")
	)
	(segment
		(start 84.616544 -97.446084)
		(end 84.616544 -98.55073)
		(width 0.0889)
		(layer "In11.Cu")
		(net "M_M_DQ<30>")
	)
	(segment
		(start 85.546692 -95.49892)
		(end 85.553042 -95.509588)
		(width 0.0889)
		(layer "In11.Cu")
		(net "M_M_DQ<30>")
	)
	(segment
		(start 82.8294 -101.927406)
		(end 82.358992 -102.397814)
		(width 0.0889)
		(layer "In11.Cu")
		(net "M_M_DQ<30>")
	)
	(segment
		(start 76.604368 -116.6876)
		(end 76.604368 -117.7544)
		(width 0.14224)
		(layer "In11.Cu")
		(net "M_M_DQ<30>")
	)
	(segment
		(start 72.184768 -122.174)
		(end 67.815968 -122.174)
		(width 0.14224)
		(layer "In11.Cu")
		(net "M_M_DQ<30>")
	)
	(segment
		(start 65.865502 -134.579868)
		(end 65.763902 -134.681468)
		(width 0.14224)
		(layer "In11.Cu")
		(net "M_M_DQ<30>")
	)
	(segment
		(start 67.815968 -122.174)
		(end 65.809368 -124.1806)
		(width 0.14224)
		(layer "In11.Cu")
		(net "M_M_DQ<30>")
	)
	(segment
		(start 65.916302 -141.5796)
		(end 65.834768 -141.661134)
		(width 0.14224)
		(layer "In11.Cu")
		(net "M_M_DQ<30>")
	)
	(segment
		(start 86.416388 -88.471502)
		(end 86.411562 -88.480138)
		(width 0.0889)
		(layer "In11.Cu")
		(net "M_M_DQ<30>")
	)
	(segment
		(start 65.834768 -141.661134)
		(end 65.834768 -143.7132)
		(width 0.14224)
		(layer "In11.Cu")
		(net "M_M_DQ<30>")
	)
	(segment
		(start 85.734906 -86.070186)
		(end 85.718142 -86.098888)
		(width 0.0889)
		(layer "In11.Cu")
		(net "M_M_DQ<30>")
	)
	(segment
		(start 82.358992 -102.397814)
		(end 82.358992 -102.945946)
		(width 0.0889)
		(layer "In11.Cu")
		(net "M_M_DQ<30>")
	)
	(segment
		(start 65.763902 -134.681468)
		(end 65.763902 -136.073388)
		(width 0.14224)
		(layer "In11.Cu")
		(net "M_M_DQ<30>")
	)
	(segment
		(start 86.416388 -90.452702)
		(end 86.411562 -90.461338)
		(width 0.0889)
		(layer "In11.Cu")
		(net "M_M_DQ<30>")
	)
	(segment
		(start 65.834768 -143.7132)
		(end 65.916302 -143.794734)
		(width 0.14224)
		(layer "In11.Cu")
		(net "M_M_DQ<30>")
	)
	(segment
		(start 65.967102 -139.460478)
		(end 65.763902 -139.663678)
		(width 0.14224)
		(layer "In11.Cu")
		(net "M_M_DQ<30>")
	)
	(segment
		(start 86.416388 -89.462102)
		(end 86.411562 -89.470738)
		(width 0.0889)
		(layer "In11.Cu")
		(net "M_M_DQ<30>")
	)
	(segment
		(start 86.411562 -92.442538)
		(end 86.405212 -92.453206)
		(width 0.0889)
		(layer "In11.Cu")
		(net "M_M_DQ<30>")
	)
	(segment
		(start 65.809368 -125.6284)
		(end 65.967102 -125.786134)
		(width 0.14224)
		(layer "In11.Cu")
		(net "M_M_DQ<30>")
	)
	(segment
		(start 65.399412 -150.814278)
		(end 64.966342 -151.247348)
		(width 0.14224)
		(layer "In11.Cu")
		(net "M_M_DQ<30>")
	)
	(segment
		(start 84.616544 -98.55073)
		(end 82.8294 -100.337874)
		(width 0.0889)
		(layer "In11.Cu")
		(net "M_M_DQ<30>")
	)
	(segment
		(start 65.225168 -149.6822)
		(end 65.225168 -150.640034)
		(width 0.14224)
		(layer "In11.Cu")
		(net "M_M_DQ<30>")
	)
	(segment
		(start 85.713316 -87.480902)
		(end 85.882734 -87.775034)
		(width 0.0889)
		(layer "In11.Cu")
		(net "M_M_DQ<30>")
	)
	(segment
		(start 65.967102 -148.569934)
		(end 65.967102 -148.940266)
		(width 0.14224)
		(layer "In11.Cu")
		(net "M_M_DQ<30>")
	)
	(segment
		(start 82.8294 -100.337874)
		(end 82.8294 -101.927406)
		(width 0.0889)
		(layer "In11.Cu")
		(net "M_M_DQ<30>")
	)
	(segment
		(start 65.823084 -138.672316)
		(end 65.967102 -138.816334)
		(width 0.14224)
		(layer "In11.Cu")
		(net "M_M_DQ<30>")
	)
	(segment
		(start 85.221318 -97.100136)
		(end 85.132418 -97.100136)
		(width 0.0889)
		(layer "In11.Cu")
		(net "M_M_DQ<30>")
	)
	(segment
		(start 85.553042 -95.509588)
		(end 85.557868 -95.518224)
		(width 0.0889)
		(layer "In11.Cu")
		(net "M_M_DQ<30>")
	)
	(segment
		(start 86.082886 -93.633036)
		(end 86.047072 -93.633036)
		(width 0.0889)
		(layer "In11.Cu")
		(net "M_M_DQ<30>")
	)
	(segment
		(start 65.763902 -140.908278)
		(end 65.916302 -141.060678)
		(width 0.14224)
		(layer "In11.Cu")
		(net "M_M_DQ<30>")
	)
	(segment
		(start 86.416388 -92.433902)
		(end 86.411562 -92.442538)
		(width 0.0889)
		(layer "In11.Cu")
		(net "M_M_DQ<30>")
	)
	(segment
		(start 85.13191 -97.100644)
		(end 85.060282 -97.100644)
		(width 0.0889)
		(layer "In11.Cu")
		(net "M_M_DQ<30>")
	)
	(segment
		(start 78.255368 -109.4994)
		(end 78.255368 -115.0366)
		(width 0.14224)
		(layer "In11.Cu")
		(net "M_M_DQ<30>")
	)
	(segment
		(start 64.966342 -153.834846)
		(end 66.249296 -155.1178)
		(width 0.14224)
		(layer "In11.Cu")
		(net "M_M_DQ<30>")
	)
	(segment
		(start 85.553042 -94.518988)
		(end 85.557868 -94.527624)
		(width 0.0889)
		(layer "In11.Cu")
		(net "M_M_DQ<30>")
	)
	(segment
		(start 86.416388 -91.443302)
		(end 86.411562 -91.451938)
		(width 0.0889)
		(layer "In11.Cu")
		(net "M_M_DQ<30>")
	)
	(arc
		(start 86.405212 -89.481406)
		(mid 86.332414 -89.772169)
		(end 86.411562 -90.061288)
		(width 0.0889)
		(layer "In11.Cu")
		(net "M_M_DQ<30>")
	)
	(arc
		(start 86.411562 -93.033088)
		(mid 86.415972 -93.425551)
		(end 86.082886 -93.633036)
		(width 0.0889)
		(layer "In11.Cu")
		(net "M_M_DQ<30>")
	)
	(arc
		(start 85.557868 -96.508824)
		(mid 85.554121 -96.89808)
		(end 85.221318 -97.100136)
		(width 0.0889)
		(layer "In11.Cu")
		(net "M_M_DQ<30>")
	)
	(arc
		(start 86.405212 -88.490806)
		(mid 86.332414 -88.781569)
		(end 86.411562 -89.070688)
		(width 0.0889)
		(layer "In11.Cu")
		(net "M_M_DQ<30>")
	)
	(arc
		(start 86.405212 -92.453206)
		(mid 86.332414 -92.743969)
		(end 86.411562 -93.033088)
		(width 0.0889)
		(layer "In11.Cu")
		(net "M_M_DQ<30>")
	)
	(arc
		(start 86.411562 -90.061288)
		(mid 86.465032 -90.256351)
		(end 86.416388 -90.452702)
		(width 0.0889)
		(layer "In11.Cu")
		(net "M_M_DQ<30>")
	)
	(arc
		(start 85.557868 -94.527624)
		(mid 85.606623 -94.723976)
		(end 85.553042 -94.919038)
		(width 0.0889)
		(layer "In11.Cu")
		(net "M_M_DQ<30>")
	)
	(arc
		(start 85.718142 -87.089488)
		(mid 85.664672 -87.284551)
		(end 85.713316 -87.480902)
		(width 0.0889)
		(layer "In11.Cu")
		(net "M_M_DQ<30>")
	)
	(arc
		(start 85.882734 -87.775034)
		(mid 85.959707 -87.852003)
		(end 86.064852 -87.88019)
		(width 0.0889)
		(layer "In11.Cu")
		(net "M_M_DQ<30>")
	)
	(arc
		(start 86.079838 -87.88019)
		(mid 86.412756 -88.082181)
		(end 86.416388 -88.471502)
		(width 0.0889)
		(layer "In11.Cu")
		(net "M_M_DQ<30>")
	)
	(arc
		(start 85.557868 -95.518224)
		(mid 85.606623 -95.714576)
		(end 85.553042 -95.909638)
		(width 0.0889)
		(layer "In11.Cu")
		(net "M_M_DQ<30>")
	)
	(arc
		(start 86.405212 -90.472006)
		(mid 86.332414 -90.762769)
		(end 86.411562 -91.051888)
		(width 0.0889)
		(layer "In11.Cu")
		(net "M_M_DQ<30>")
	)
	(arc
		(start 86.047072 -93.633036)
		(mid 85.548821 -93.935876)
		(end 85.553042 -94.518988)
		(width 0.0889)
		(layer "In11.Cu")
		(net "M_M_DQ<30>")
	)
	(arc
		(start 85.724492 -86.509606)
		(mid 85.79729 -86.800369)
		(end 85.718142 -87.089488)
		(width 0.0889)
		(layer "In11.Cu")
		(net "M_M_DQ<30>")
	)
	(arc
		(start 86.411562 -92.042488)
		(mid 86.465032 -92.237551)
		(end 86.416388 -92.433902)
		(width 0.0889)
		(layer "In11.Cu")
		(net "M_M_DQ<30>")
	)
	(arc
		(start 86.405212 -91.462606)
		(mid 86.332414 -91.753369)
		(end 86.411562 -92.042488)
		(width 0.0889)
		(layer "In11.Cu")
		(net "M_M_DQ<30>")
	)
	(arc
		(start 86.411562 -89.070688)
		(mid 86.465032 -89.265751)
		(end 86.416388 -89.462102)
		(width 0.0889)
		(layer "In11.Cu")
		(net "M_M_DQ<30>")
	)
	(arc
		(start 85.553042 -95.909638)
		(mid 85.47382 -96.198756)
		(end 85.546692 -96.48952)
		(width 0.0889)
		(layer "In11.Cu")
		(net "M_M_DQ<30>")
	)
	(arc
		(start 86.411562 -91.051888)
		(mid 86.465032 -91.246951)
		(end 86.416388 -91.443302)
		(width 0.0889)
		(layer "In11.Cu")
		(net "M_M_DQ<30>")
	)
	(arc
		(start 85.718142 -86.098888)
		(mid 85.664672 -86.293951)
		(end 85.713316 -86.490302)
		(width 0.0889)
		(layer "In11.Cu")
		(net "M_M_DQ<30>")
	)
	(arc
		(start 85.553042 -94.919038)
		(mid 85.47382 -95.208156)
		(end 85.546692 -95.49892)
		(width 0.0889)
		(layer "In11.Cu")
		(net "M_M_DQ<30>")
	)
	(segment
		(start 39.899336 -155.395168)
		(end 39.899336 -155.1178)
		(width 0.1651)
		(layer "F.Cu")
		(net "M_M_DQ<2>")
	)
	(segment
		(start 39.899336 -156.87294)
		(end 39.899336 -155.881832)
		(width 0.1651)
		(layer "F.Cu")
		(net "M_M_DQ<2>")
	)
	(segment
		(start 40.030908 -155.52674)
		(end 39.899336 -155.395168)
		(width 0.1651)
		(layer "F.Cu")
		(net "M_M_DQ<2>")
	)
	(segment
		(start 76.334366 -88.28024)
		(end 75.762866 -88.28024)
		(width 0.1651)
		(layer "F.Cu")
		(net "M_M_DQ<2>")
	)
	(segment
		(start 40.030908 -155.75026)
		(end 40.030908 -155.52674)
		(width 0.1651)
		(layer "F.Cu")
		(net "M_M_DQ<2>")
	)
	(segment
		(start 39.899336 -155.881832)
		(end 40.030908 -155.75026)
		(width 0.1651)
		(layer "F.Cu")
		(net "M_M_DQ<2>")
	)
	(via
		(at 39.899336 -155.1178)
		(size 0.508)
		(drill 0.254)
		(layers "F.Cu" "B.Cu")
		(net "M_M_DQ<2>")
	)
	(via
		(at 75.762866 -88.28024)
		(size 0.508)
		(drill 0.254)
		(layers "F.Cu" "B.Cu")
		(net "M_M_DQ<2>")
	)
	(via
		(at 39.049452 -150.814278)
		(size 0.508)
		(drill 0.254)
		(layers "F.Cu" "B.Cu")
		(net "M_M_DQ<2>")
	)
	(segment
		(start 39.049452 -152.078436)
		(end 39.049452 -150.814278)
		(width 0.1651)
		(layer "B.Cu")
		(net "M_M_DQ<2>")
	)
	(segment
		(start 39.418768 -146.6088)
		(end 39.418768 -148.336)
		(width 0.14224)
		(layer "In11.Cu")
		(net "M_M_DQ<2>")
	)
	(segment
		(start 39.406068 -127.0381)
		(end 39.406068 -129.1463)
		(width 0.14224)
		(layer "In11.Cu")
		(net "M_M_DQ<2>")
	)
	(segment
		(start 66.229992 -91.867482)
		(end 63.613792 -91.867482)
		(width 0.0889)
		(layer "In11.Cu")
		(net "M_M_DQ<2>")
	)
	(segment
		(start 70.622922 -89.67089)
		(end 70.590156 -89.67089)
		(width 0.0889)
		(layer "In11.Cu")
		(net "M_M_DQ<2>")
	)
	(segment
		(start 39.54272 -129.833878)
		(end 39.41572 -129.960878)
		(width 0.14224)
		(layer "In11.Cu")
		(net "M_M_DQ<2>")
	)
	(segment
		(start 49.620678 -106.722164)
		(end 49.620678 -107.009692)
		(width 0.14224)
		(layer "In11.Cu")
		(net "M_M_DQ<2>")
	)
	(segment
		(start 38.616382 -151.247348)
		(end 38.616382 -153.834846)
		(width 0.14224)
		(layer "In11.Cu")
		(net "M_M_DQ<2>")
	)
	(segment
		(start 39.621968 -146.4056)
		(end 39.418768 -146.6088)
		(width 0.14224)
		(layer "In11.Cu")
		(net "M_M_DQ<2>")
	)
	(segment
		(start 46.245526 -110.384844)
		(end 45.932598 -110.384844)
		(width 0.14224)
		(layer "In11.Cu")
		(net "M_M_DQ<2>")
	)
	(segment
		(start 39.672768 -141.449552)
		(end 39.469568 -141.652752)
		(width 0.14224)
		(layer "In11.Cu")
		(net "M_M_DQ<2>")
	)
	(segment
		(start 73.202292 -88.184736)
		(end 73.169526 -88.184736)
		(width 0.0889)
		(layer "In11.Cu")
		(net "M_M_DQ<2>")
	)
	(segment
		(start 39.698168 -126.746)
		(end 39.406068 -127.0381)
		(width 0.14224)
		(layer "In11.Cu")
		(net "M_M_DQ<2>")
	)
	(segment
		(start 75.762866 -88.28024)
		(end 75.433428 -87.519256)
		(width 0.0889)
		(layer "In11.Cu")
		(net "M_M_DQ<2>")
	)
	(segment
		(start 55.903368 -98.7044)
		(end 55.903368 -100.726748)
		(width 0.14224)
		(layer "In11.Cu")
		(net "M_M_DQ<2>")
	)
	(segment
		(start 39.698168 -134.405116)
		(end 39.39032 -134.712964)
		(width 0.14224)
		(layer "In11.Cu")
		(net "M_M_DQ<2>")
	)
	(segment
		(start 39.469568 -136.8298)
		(end 39.469568 -138.8618)
		(width 0.14224)
		(layer "In11.Cu")
		(net "M_M_DQ<2>")
	)
	(segment
		(start 63.403734 -91.657424)
		(end 63.392558 -91.6686)
		(width 0.14224)
		(layer "In11.Cu")
		(net "M_M_DQ<2>")
	)
	(segment
		(start 39.672768 -141.071854)
		(end 39.672768 -141.449552)
		(width 0.14224)
		(layer "In11.Cu")
		(net "M_M_DQ<2>")
	)
	(segment
		(start 68.051172 -91.156536)
		(end 67.698874 -91.156536)
		(width 0.0889)
		(layer "In11.Cu")
		(net "M_M_DQ<2>")
	)
	(segment
		(start 39.418768 -148.336)
		(end 39.56812 -148.485352)
		(width 0.14224)
		(layer "In11.Cu")
		(net "M_M_DQ<2>")
	)
	(segment
		(start 67.425316 -91.430094)
		(end 66.66738 -91.430094)
		(width 0.0889)
		(layer "In11.Cu")
		(net "M_M_DQ<2>")
	)
	(segment
		(start 39.469568 -138.8618)
		(end 39.647368 -139.0396)
		(width 0.14224)
		(layer "In11.Cu")
		(net "M_M_DQ<2>")
	)
	(segment
		(start 39.39032 -136.064752)
		(end 39.647368 -136.3218)
		(width 0.14224)
		(layer "In11.Cu")
		(net "M_M_DQ<2>")
	)
	(segment
		(start 39.41572 -139.703302)
		(end 39.41572 -140.814806)
		(width 0.14224)
		(layer "In11.Cu")
		(net "M_M_DQ<2>")
	)
	(segment
		(start 39.698168 -114.632994)
		(end 39.698168 -115.4176)
		(width 0.14224)
		(layer "In11.Cu")
		(net "M_M_DQ<2>")
	)
	(segment
		(start 38.70452 -150.469346)
		(end 39.049452 -150.814278)
		(width 0.14224)
		(layer "In11.Cu")
		(net "M_M_DQ<2>")
	)
	(segment
		(start 45.569124 -108.998766)
		(end 45.856398 -109.28604)
		(width 0.14224)
		(layer "In11.Cu")
		(net "M_M_DQ<2>")
	)
	(segment
		(start 39.672768 -143.637)
		(end 39.672768 -144.03959)
		(width 0.14224)
		(layer "In11.Cu")
		(net "M_M_DQ<2>")
	)
	(segment
		(start 39.621968 -145.860516)
		(end 39.621968 -146.4056)
		(width 0.14224)
		(layer "In11.Cu")
		(net "M_M_DQ<2>")
	)
	(segment
		(start 67.698874 -91.156536)
		(end 67.425316 -91.430094)
		(width 0.0889)
		(layer "In11.Cu")
		(net "M_M_DQ<2>")
	)
	(segment
		(start 39.39032 -134.712964)
		(end 39.39032 -136.064752)
		(width 0.14224)
		(layer "In11.Cu")
		(net "M_M_DQ<2>")
	)
	(segment
		(start 39.647368 -136.3218)
		(end 39.647368 -136.652)
		(width 0.14224)
		(layer "In11.Cu")
		(net "M_M_DQ<2>")
	)
	(segment
		(start 39.406068 -129.1463)
		(end 39.54272 -129.282952)
		(width 0.14224)
		(layer "In11.Cu")
		(net "M_M_DQ<2>")
	)
	(segment
		(start 39.049452 -150.814278)
		(end 38.616382 -151.247348)
		(width 0.14224)
		(layer "In11.Cu")
		(net "M_M_DQ<2>")
	)
	(segment
		(start 39.469568 -143.4338)
		(end 39.672768 -143.637)
		(width 0.14224)
		(layer "In11.Cu")
		(net "M_M_DQ<2>")
	)
	(segment
		(start 71.485252 -89.175336)
		(end 71.452486 -89.175336)
		(width 0.0889)
		(layer "In11.Cu")
		(net "M_M_DQ<2>")
	)
	(segment
		(start 39.469568 -141.652752)
		(end 39.469568 -143.4338)
		(width 0.14224)
		(layer "In11.Cu")
		(net "M_M_DQ<2>")
	)
	(segment
		(start 39.698168 -115.4176)
		(end 40.252142 -115.971574)
		(width 0.14224)
		(layer "In11.Cu")
		(net "M_M_DQ<2>")
	)
	(segment
		(start 75.433428 -87.519256)
		(end 75.416156 -87.489538)
		(width 0.0889)
		(layer "In11.Cu")
		(net "M_M_DQ<2>")
	)
	(segment
		(start 72.339962 -88.68029)
		(end 72.307196 -88.68029)
		(width 0.0889)
		(layer "In11.Cu")
		(net "M_M_DQ<2>")
	)
	(segment
		(start 48.489362 -105.8418)
		(end 45.569124 -108.762038)
		(width 0.14224)
		(layer "In11.Cu")
		(net "M_M_DQ<2>")
	)
	(segment
		(start 45.569124 -108.762038)
		(end 45.569124 -108.998766)
		(width 0.14224)
		(layer "In11.Cu")
		(net "M_M_DQ<2>")
	)
	(segment
		(start 74.057002 -87.68969)
		(end 74.024236 -87.68969)
		(width 0.0889)
		(layer "In11.Cu")
		(net "M_M_DQ<2>")
	)
	(segment
		(start 50.788316 -105.8418)
		(end 48.489362 -105.8418)
		(width 0.14224)
		(layer "In11.Cu")
		(net "M_M_DQ<2>")
	)
	(segment
		(start 39.56812 -148.485352)
		(end 39.56812 -148.972778)
		(width 0.14224)
		(layer "In11.Cu")
		(net "M_M_DQ<2>")
	)
	(segment
		(start 55.903368 -100.726748)
		(end 50.788316 -105.8418)
		(width 0.14224)
		(layer "In11.Cu")
		(net "M_M_DQ<2>")
	)
	(segment
		(start 49.333404 -106.43489)
		(end 49.620678 -106.722164)
		(width 0.14224)
		(layer "In11.Cu")
		(net "M_M_DQ<2>")
	)
	(segment
		(start 39.698168 -131.470654)
		(end 39.698168 -134.405116)
		(width 0.14224)
		(layer "In11.Cu")
		(net "M_M_DQ<2>")
	)
	(segment
		(start 40.252142 -116.378228)
		(end 39.698168 -116.932202)
		(width 0.14224)
		(layer "In11.Cu")
		(net "M_M_DQ<2>")
	)
	(segment
		(start 63.392558 -91.6686)
		(end 62.939168 -91.6686)
		(width 0.14224)
		(layer "In11.Cu")
		(net "M_M_DQ<2>")
	)
	(segment
		(start 39.41572 -129.960878)
		(end 39.41572 -131.188206)
		(width 0.14224)
		(layer "In11.Cu")
		(net "M_M_DQ<2>")
	)
	(segment
		(start 40.252142 -115.971574)
		(end 40.252142 -116.378228)
		(width 0.14224)
		(layer "In11.Cu")
		(net "M_M_DQ<2>")
	)
	(segment
		(start 63.613792 -91.867482)
		(end 63.403734 -91.657424)
		(width 0.0889)
		(layer "In11.Cu")
		(net "M_M_DQ<2>")
	)
	(segment
		(start 44.808394 -109.522768)
		(end 39.698168 -114.632994)
		(width 0.14224)
		(layer "In11.Cu")
		(net "M_M_DQ<2>")
	)
	(segment
		(start 45.070522 -109.522768)
		(end 44.808394 -109.522768)
		(width 0.14224)
		(layer "In11.Cu")
		(net "M_M_DQ<2>")
	)
	(segment
		(start 49.620678 -107.009692)
		(end 46.245526 -110.384844)
		(width 0.14224)
		(layer "In11.Cu")
		(net "M_M_DQ<2>")
	)
	(segment
		(start 66.66738 -91.430094)
		(end 66.229992 -91.867482)
		(width 0.0889)
		(layer "In11.Cu")
		(net "M_M_DQ<2>")
	)
	(segment
		(start 39.54272 -129.282952)
		(end 39.54272 -129.833878)
		(width 0.14224)
		(layer "In11.Cu")
		(net "M_M_DQ<2>")
	)
	(segment
		(start 39.647368 -136.652)
		(end 39.469568 -136.8298)
		(width 0.14224)
		(layer "In11.Cu")
		(net "M_M_DQ<2>")
	)
	(segment
		(start 38.616382 -153.834846)
		(end 39.899336 -155.1178)
		(width 0.14224)
		(layer "In11.Cu")
		(net "M_M_DQ<2>")
	)
	(segment
		(start 46.194726 -109.28604)
		(end 49.045876 -106.43489)
		(width 0.14224)
		(layer "In11.Cu")
		(net "M_M_DQ<2>")
	)
	(segment
		(start 45.856398 -109.28604)
		(end 46.194726 -109.28604)
		(width 0.14224)
		(layer "In11.Cu")
		(net "M_M_DQ<2>")
	)
	(segment
		(start 39.56812 -148.972778)
		(end 38.70452 -149.836378)
		(width 0.14224)
		(layer "In11.Cu")
		(net "M_M_DQ<2>")
	)
	(segment
		(start 39.647368 -139.0396)
		(end 39.647368 -139.471654)
		(width 0.14224)
		(layer "In11.Cu")
		(net "M_M_DQ<2>")
	)
	(segment
		(start 38.70452 -149.836378)
		(end 38.70452 -150.469346)
		(width 0.14224)
		(layer "In11.Cu")
		(net "M_M_DQ<2>")
	)
	(segment
		(start 45.932598 -110.384844)
		(end 45.070522 -109.522768)
		(width 0.14224)
		(layer "In11.Cu")
		(net "M_M_DQ<2>")
	)
	(segment
		(start 39.698168 -116.932202)
		(end 39.698168 -126.746)
		(width 0.14224)
		(layer "In11.Cu")
		(net "M_M_DQ<2>")
	)
	(segment
		(start 39.647368 -139.471654)
		(end 39.41572 -139.703302)
		(width 0.14224)
		(layer "In11.Cu")
		(net "M_M_DQ<2>")
	)
	(segment
		(start 39.672768 -144.03959)
		(end 39.33952 -144.372838)
		(width 0.14224)
		(layer "In11.Cu")
		(net "M_M_DQ<2>")
	)
	(segment
		(start 49.045876 -106.43489)
		(end 49.333404 -106.43489)
		(width 0.14224)
		(layer "In11.Cu")
		(net "M_M_DQ<2>")
	)
	(segment
		(start 39.41572 -131.188206)
		(end 39.698168 -131.470654)
		(width 0.14224)
		(layer "In11.Cu")
		(net "M_M_DQ<2>")
	)
	(segment
		(start 39.41572 -140.814806)
		(end 39.672768 -141.071854)
		(width 0.14224)
		(layer "In11.Cu")
		(net "M_M_DQ<2>")
	)
	(segment
		(start 74.922126 -87.194136)
		(end 74.886566 -87.194136)
		(width 0.0889)
		(layer "In11.Cu")
		(net "M_M_DQ<2>")
	)
	(segment
		(start 39.33952 -144.372838)
		(end 39.33952 -145.578068)
		(width 0.14224)
		(layer "In11.Cu")
		(net "M_M_DQ<2>")
	)
	(segment
		(start 69.768212 -90.165936)
		(end 69.735446 -90.165936)
		(width 0.0889)
		(layer "In11.Cu")
		(net "M_M_DQ<2>")
	)
	(segment
		(start 62.939168 -91.6686)
		(end 55.903368 -98.7044)
		(width 0.14224)
		(layer "In11.Cu")
		(net "M_M_DQ<2>")
	)
	(segment
		(start 39.33952 -145.578068)
		(end 39.621968 -145.860516)
		(width 0.14224)
		(layer "In11.Cu")
		(net "M_M_DQ<2>")
	)
	(arc
		(start 68.850002 -90.66276)
		(mid 68.580091 -90.751912)
		(end 68.382896 -90.956638)
		(width 0.0889)
		(layer "In11.Cu")
		(net "M_M_DQ<2>")
	)
	(arc
		(start 74.392536 -87.489538)
		(mid 74.250853 -87.633342)
		(end 74.057002 -87.68969)
		(width 0.0889)
		(layer "In11.Cu")
		(net "M_M_DQ<2>")
	)
	(arc
		(start 69.241416 -90.461338)
		(mid 69.113665 -90.596439)
		(end 68.938648 -90.659204)
		(width 0.0889)
		(layer "In11.Cu")
		(net "M_M_DQ<2>")
	)
	(arc
		(start 74.886566 -87.194136)
		(mid 74.601142 -87.277603)
		(end 74.392536 -87.489538)
		(width 0.0889)
		(layer "In11.Cu")
		(net "M_M_DQ<2>")
	)
	(arc
		(start 75.416156 -87.489538)
		(mid 75.207548 -87.277606)
		(end 74.922126 -87.194136)
		(width 0.0889)
		(layer "In11.Cu")
		(net "M_M_DQ<2>")
	)
	(arc
		(start 68.938648 -90.659204)
		(mid 68.894387 -90.662525)
		(end 68.850002 -90.66276)
		(width 0.0889)
		(layer "In11.Cu")
		(net "M_M_DQ<2>")
	)
	(arc
		(start 68.382896 -90.956638)
		(mid 68.242817 -91.099374)
		(end 68.051172 -91.156536)
		(width 0.0889)
		(layer "In11.Cu")
		(net "M_M_DQ<2>")
	)
	(arc
		(start 71.816976 -88.975438)
		(mid 71.676897 -89.118174)
		(end 71.485252 -89.175336)
		(width 0.0889)
		(layer "In11.Cu")
		(net "M_M_DQ<2>")
	)
	(arc
		(start 70.958456 -89.470738)
		(mid 70.816773 -89.614542)
		(end 70.622922 -89.67089)
		(width 0.0889)
		(layer "In11.Cu")
		(net "M_M_DQ<2>")
	)
	(arc
		(start 73.534016 -87.984838)
		(mid 73.393937 -88.127574)
		(end 73.202292 -88.184736)
		(width 0.0889)
		(layer "In11.Cu")
		(net "M_M_DQ<2>")
	)
	(arc
		(start 74.024236 -87.68969)
		(mid 73.741019 -87.773971)
		(end 73.534016 -87.984838)
		(width 0.0889)
		(layer "In11.Cu")
		(net "M_M_DQ<2>")
	)
	(arc
		(start 70.590156 -89.67089)
		(mid 70.306939 -89.755171)
		(end 70.099936 -89.966038)
		(width 0.0889)
		(layer "In11.Cu")
		(net "M_M_DQ<2>")
	)
	(arc
		(start 69.735446 -90.165936)
		(mid 69.450022 -90.249403)
		(end 69.241416 -90.461338)
		(width 0.0889)
		(layer "In11.Cu")
		(net "M_M_DQ<2>")
	)
	(arc
		(start 73.169526 -88.184736)
		(mid 72.884102 -88.268203)
		(end 72.675496 -88.480138)
		(width 0.0889)
		(layer "In11.Cu")
		(net "M_M_DQ<2>")
	)
	(arc
		(start 72.307196 -88.68029)
		(mid 72.023979 -88.764571)
		(end 71.816976 -88.975438)
		(width 0.0889)
		(layer "In11.Cu")
		(net "M_M_DQ<2>")
	)
	(arc
		(start 72.675496 -88.480138)
		(mid 72.533813 -88.623942)
		(end 72.339962 -88.68029)
		(width 0.0889)
		(layer "In11.Cu")
		(net "M_M_DQ<2>")
	)
	(arc
		(start 70.099936 -89.966038)
		(mid 69.959857 -90.108774)
		(end 69.768212 -90.165936)
		(width 0.0889)
		(layer "In11.Cu")
		(net "M_M_DQ<2>")
	)
	(arc
		(start 71.452486 -89.175336)
		(mid 71.167062 -89.258803)
		(end 70.958456 -89.470738)
		(width 0.0889)
		(layer "In11.Cu")
		(net "M_M_DQ<2>")
	)
	(segment
		(start 84.060792 -86.794086)
		(end 83.489292 -86.794086)
		(width 0.1651)
		(layer "F.Cu")
		(net "M_M_DQ<29>")
	)
	(segment
		(start 59.449462 -152.273)
		(end 59.449462 -153.542746)
		(width 0.1651)
		(layer "F.Cu")
		(net "M_M_DQ<29>")
	)
	(via
		(at 83.489292 -86.794086)
		(size 0.508)
		(drill 0.254)
		(layers "F.Cu" "B.Cu")
		(net "M_M_DQ<29>")
	)
	(via
		(at 60.223146 -149.533356)
		(size 0.508)
		(drill 0.254)
		(layers "F.Cu" "B.Cu")
		(net "M_M_DQ<29>")
	)
	(via
		(at 59.449462 -153.542746)
		(size 0.508)
		(drill 0.254)
		(layers "F.Cu" "B.Cu")
		(net "M_M_DQ<29>")
	)
	(segment
		(start 60.299346 -147.478496)
		(end 60.299346 -149.457156)
		(width 0.1651)
		(layer "B.Cu")
		(net "M_M_DQ<29>")
	)
	(segment
		(start 60.299346 -149.457156)
		(end 60.223146 -149.533356)
		(width 0.1651)
		(layer "B.Cu")
		(net "M_M_DQ<29>")
	)
	(segment
		(start 74.292968 -107.95)
		(end 74.292968 -112.776)
		(width 0.14224)
		(layer "In11.Cu")
		(net "M_M_DQ<29>")
	)
	(segment
		(start 60.729368 -134.0612)
		(end 60.633102 -134.157466)
		(width 0.14224)
		(layer "In11.Cu")
		(net "M_M_DQ<29>")
	)
	(segment
		(start 60.475368 -139.446)
		(end 60.696602 -139.667234)
		(width 0.14224)
		(layer "In11.Cu")
		(net "M_M_DQ<29>")
	)
	(segment
		(start 60.633102 -134.157466)
		(end 60.633102 -134.617968)
		(width 0.14224)
		(layer "In11.Cu")
		(net "M_M_DQ<29>")
	)
	(segment
		(start 79.214472 -97.78619)
		(end 79.181706 -97.78619)
		(width 0.0889)
		(layer "In11.Cu")
		(net "M_M_DQ<29>")
	)
	(segment
		(start 64.6176 -119.5451)
		(end 64.398652 -119.5451)
		(width 0.14224)
		(layer "In11.Cu")
		(net "M_M_DQ<29>")
	)
	(segment
		(start 60.760102 -145.56232)
		(end 60.526168 -145.796254)
		(width 0.14224)
		(layer "In11.Cu")
		(net "M_M_DQ<29>")
	)
	(segment
		(start 61.168788 -122.993912)
		(end 60.94984 -122.993912)
		(width 0.14224)
		(layer "In11.Cu")
		(net "M_M_DQ<29>")
	)
	(segment
		(start 60.526168 -141.528546)
		(end 60.729368 -141.731746)
		(width 0.14224)
		(layer "In11.Cu")
		(net "M_M_DQ<29>")
	)
	(segment
		(start 59.89955 -150.6474)
		(end 59.89955 -151.129746)
		(width 0.14224)
		(layer "In11.Cu")
		(net "M_M_DQ<29>")
	)
	(segment
		(start 60.729368 -132.079746)
		(end 60.729368 -134.0612)
		(width 0.14224)
		(layer "In11.Cu")
		(net "M_M_DQ<29>")
	)
	(segment
		(start 63.467996 -120.694704)
		(end 63.249048 -120.694704)
		(width 0.14224)
		(layer "In11.Cu")
		(net "M_M_DQ<29>")
	)
	(segment
		(start 74.292968 -112.776)
		(end 69.243702 -117.825266)
		(width 0.14224)
		(layer "In11.Cu")
		(net "M_M_DQ<29>")
	)
	(segment
		(start 60.223146 -149.533356)
		(end 60.200794 -149.533356)
		(width 0.14224)
		(layer "In11.Cu")
		(net "M_M_DQ<29>")
	)
	(segment
		(start 59.610752 -151.418544)
		(end 59.610752 -151.755856)
		(width 0.14224)
		(layer "In11.Cu")
		(net "M_M_DQ<29>")
	)
	(segment
		(start 61.74359 -122.200162)
		(end 61.74359 -122.41911)
		(width 0.14224)
		(layer "In11.Cu")
		(net "M_M_DQ<29>")
	)
	(segment
		(start 60.542932 -131.377436)
		(end 60.542932 -131.89331)
		(width 0.14224)
		(layer "In11.Cu")
		(net "M_M_DQ<29>")
	)
	(segment
		(start 82.284062 -92.442538)
		(end 82.290412 -92.453206)
		(width 0.0889)
		(layer "In11.Cu")
		(net "M_M_DQ<29>")
	)
	(segment
		(start 60.729368 -136.621266)
		(end 60.729368 -138.7094)
		(width 0.14224)
		(layer "In11.Cu")
		(net "M_M_DQ<29>")
	)
	(segment
		(start 59.87415 -153.162254)
		(end 59.87415 -153.390346)
		(width 0.14224)
		(layer "In11.Cu")
		(net "M_M_DQ<29>")
	)
	(segment
		(start 60.322968 -125.8062)
		(end 60.322968 -127.583946)
		(width 0.14224)
		(layer "In11.Cu")
		(net "M_M_DQ<29>")
	)
	(segment
		(start 82.279236 -92.433902)
		(end 82.284062 -92.442538)
		(width 0.0889)
		(layer "In11.Cu")
		(net "M_M_DQ<29>")
	)
	(segment
		(start 64.128142 -120.205246)
		(end 64.128142 -120.424194)
		(width 0.14224)
		(layer "In11.Cu")
		(net "M_M_DQ<29>")
	)
	(segment
		(start 80.076802 -97.290636)
		(end 80.044036 -97.290636)
		(width 0.0889)
		(layer "In11.Cu")
		(net "M_M_DQ<29>")
	)
	(segment
		(start 82.648552 -91.84259)
		(end 82.615786 -91.84259)
		(width 0.0889)
		(layer "In11.Cu")
		(net "M_M_DQ<29>")
	)
	(segment
		(start 60.696602 -131.223766)
		(end 60.542932 -131.377436)
		(width 0.14224)
		(layer "In11.Cu")
		(net "M_M_DQ<29>")
	)
	(segment
		(start 60.551568 -136.443466)
		(end 60.729368 -136.621266)
		(width 0.14224)
		(layer "In11.Cu")
		(net "M_M_DQ<29>")
	)
	(segment
		(start 61.828934 -122.504454)
		(end 61.828934 -122.723402)
		(width 0.14224)
		(layer "In11.Cu")
		(net "M_M_DQ<29>")
	)
	(segment
		(start 65.277746 -119.27459)
		(end 64.921892 -119.630444)
		(width 0.14224)
		(layer "In11.Cu")
		(net "M_M_DQ<29>")
	)
	(segment
		(start 60.729368 -143.3068)
		(end 60.449968 -143.5862)
		(width 0.14224)
		(layer "In11.Cu")
		(net "M_M_DQ<29>")
	)
	(segment
		(start 60.602368 -123.341384)
		(end 60.602368 -125.5268)
		(width 0.14224)
		(layer "In11.Cu")
		(net "M_M_DQ<29>")
	)
	(segment
		(start 60.551568 -136.083802)
		(end 60.551568 -136.443466)
		(width 0.14224)
		(layer "In11.Cu")
		(net "M_M_DQ<29>")
	)
	(segment
		(start 59.610752 -152.586944)
		(end 59.610752 -152.898856)
		(width 0.14224)
		(layer "In11.Cu")
		(net "M_M_DQ<29>")
	)
	(segment
		(start 60.696602 -139.667234)
		(end 60.696602 -140.971778)
		(width 0.14224)
		(layer "In11.Cu")
		(net "M_M_DQ<29>")
	)
	(segment
		(start 60.696602 -135.938768)
		(end 60.551568 -136.083802)
		(width 0.14224)
		(layer "In11.Cu")
		(net "M_M_DQ<29>")
	)
	(segment
		(start 60.526168 -141.142212)
		(end 60.526168 -141.528546)
		(width 0.14224)
		(layer "In11.Cu")
		(net "M_M_DQ<29>")
	)
	(segment
		(start 83.148932 -90.54592)
		(end 83.142582 -90.556588)
		(width 0.0889)
		(layer "In11.Cu")
		(net "M_M_DQ<29>")
	)
	(segment
		(start 78.845156 -98.377502)
		(end 78.973934 -98.60788)
		(width 0.0889)
		(layer "In11.Cu")
		(net "M_M_DQ<29>")
	)
	(segment
		(start 64.128142 -120.424194)
		(end 63.772288 -120.780048)
		(width 0.14224)
		(layer "In11.Cu")
		(net "M_M_DQ<29>")
	)
	(segment
		(start 60.760102 -144.378934)
		(end 60.760102 -145.56232)
		(width 0.14224)
		(layer "In11.Cu")
		(net "M_M_DQ<29>")
	)
	(segment
		(start 60.322968 -127.583946)
		(end 60.830968 -128.091946)
		(width 0.14224)
		(layer "In11.Cu")
		(net "M_M_DQ<29>")
	)
	(segment
		(start 83.142582 -90.556588)
		(end 83.137756 -90.565224)
		(width 0.0889)
		(layer "In11.Cu")
		(net "M_M_DQ<29>")
	)
	(segment
		(start 60.94984 -122.993912)
		(end 60.602368 -123.341384)
		(width 0.14224)
		(layer "In11.Cu")
		(net "M_M_DQ<29>")
	)
	(segment
		(start 63.249048 -120.694704)
		(end 62.893194 -121.050558)
		(width 0.14224)
		(layer "In11.Cu")
		(net "M_M_DQ<29>")
	)
	(segment
		(start 82.279236 -93.424502)
		(end 82.284062 -93.433138)
		(width 0.0889)
		(layer "In11.Cu")
		(net "M_M_DQ<29>")
	)
	(segment
		(start 60.551568 -129.4384)
		(end 60.551568 -129.838704)
		(width 0.14224)
		(layer "In11.Cu")
		(net "M_M_DQ<29>")
	)
	(segment
		(start 64.398652 -119.5451)
		(end 64.042798 -119.900954)
		(width 0.14224)
		(layer "In11.Cu")
		(net "M_M_DQ<29>")
	)
	(segment
		(start 59.84875 -151.993854)
		(end 59.84875 -152.348946)
		(width 0.14224)
		(layer "In11.Cu")
		(net "M_M_DQ<29>")
	)
	(segment
		(start 81.793842 -95.309436)
		(end 81.761076 -95.309436)
		(width 0.0889)
		(layer "In11.Cu")
		(net "M_M_DQ<29>")
	)
	(segment
		(start 83.159854 -87.55507)
		(end 83.137756 -87.593424)
		(width 0.0889)
		(layer "In11.Cu")
		(net "M_M_DQ<29>")
	)
	(segment
		(start 60.830968 -128.091946)
		(end 60.830968 -129.159)
		(width 0.14224)
		(layer "In11.Cu")
		(net "M_M_DQ<29>")
	)
	(segment
		(start 66.071496 -118.48084)
		(end 65.852548 -118.48084)
		(width 0.14224)
		(layer "In11.Cu")
		(net "M_M_DQ<29>")
	)
	(segment
		(start 65.548256 -118.395496)
		(end 65.192402 -118.75135)
		(width 0.14224)
		(layer "In11.Cu")
		(net "M_M_DQ<29>")
	)
	(segment
		(start 62.318392 -121.844308)
		(end 62.099444 -121.844308)
		(width 0.14224)
		(layer "In11.Cu")
		(net "M_M_DQ<29>")
	)
	(segment
		(start 59.89955 -151.129746)
		(end 59.610752 -151.418544)
		(width 0.14224)
		(layer "In11.Cu")
		(net "M_M_DQ<29>")
	)
	(segment
		(start 60.729368 -138.7094)
		(end 60.475368 -138.9634)
		(width 0.14224)
		(layer "In11.Cu")
		(net "M_M_DQ<29>")
	)
	(segment
		(start 83.142582 -88.575388)
		(end 83.137756 -88.584024)
		(width 0.0889)
		(layer "In11.Cu")
		(net "M_M_DQ<29>")
	)
	(segment
		(start 62.978538 -121.35485)
		(end 62.978538 -121.573798)
		(width 0.14224)
		(layer "In11.Cu")
		(net "M_M_DQ<29>")
	)
	(segment
		(start 60.696602 -129.983738)
		(end 60.696602 -131.223766)
		(width 0.14224)
		(layer "In11.Cu")
		(net "M_M_DQ<29>")
	)
	(segment
		(start 62.403736 -121.929652)
		(end 62.318392 -121.844308)
		(width 0.14224)
		(layer "In11.Cu")
		(net "M_M_DQ<29>")
	)
	(segment
		(start 60.449968 -143.5862)
		(end 60.449968 -144.0688)
		(width 0.14224)
		(layer "In11.Cu")
		(net "M_M_DQ<29>")
	)
	(segment
		(start 60.729368 -141.731746)
		(end 60.729368 -143.3068)
		(width 0.14224)
		(layer "In11.Cu")
		(net "M_M_DQ<29>")
	)
	(segment
		(start 69.243702 -117.825266)
		(end 66.72707 -117.825266)
		(width 0.14224)
		(layer "In11.Cu")
		(net "M_M_DQ<29>")
	)
	(segment
		(start 60.729368 -148.3106)
		(end 60.607702 -148.432266)
		(width 0.14224)
		(layer "In11.Cu")
		(net "M_M_DQ<29>")
	)
	(segment
		(start 64.702944 -119.630444)
		(end 64.6176 -119.5451)
		(width 0.14224)
		(layer "In11.Cu")
		(net "M_M_DQ<29>")
	)
	(segment
		(start 64.042798 -120.119902)
		(end 64.128142 -120.205246)
		(width 0.14224)
		(layer "In11.Cu")
		(net "M_M_DQ<29>")
	)
	(segment
		(start 59.72175 -153.542746)
		(end 59.449462 -153.542746)
		(width 0.14224)
		(layer "In11.Cu")
		(net "M_M_DQ<29>")
	)
	(segment
		(start 61.47308 -123.079256)
		(end 61.254132 -123.079256)
		(width 0.14224)
		(layer "In11.Cu")
		(net "M_M_DQ<29>")
	)
	(segment
		(start 60.729368 -146.354546)
		(end 60.729368 -148.3106)
		(width 0.14224)
		(layer "In11.Cu")
		(net "M_M_DQ<29>")
	)
	(segment
		(start 77.94625 -104.296718)
		(end 74.292968 -107.95)
		(width 0.14224)
		(layer "In11.Cu")
		(net "M_M_DQ<29>")
	)
	(segment
		(start 62.893194 -121.269506)
		(end 62.978538 -121.35485)
		(width 0.14224)
		(layer "In11.Cu")
		(net "M_M_DQ<29>")
	)
	(segment
		(start 60.551568 -129.838704)
		(end 60.696602 -129.983738)
		(width 0.14224)
		(layer "In11.Cu")
		(net "M_M_DQ<29>")
	)
	(segment
		(start 60.542932 -131.89331)
		(end 60.729368 -132.079746)
		(width 0.14224)
		(layer "In11.Cu")
		(net "M_M_DQ<29>")
	)
	(segment
		(start 77.722984 -101.181154)
		(end 77.722984 -102.362762)
		(width 0.0889)
		(layer "In11.Cu")
		(net "M_M_DQ<29>")
	)
	(segment
		(start 83.148932 -89.55532)
		(end 83.142582 -89.565988)
		(width 0.0889)
		(layer "In11.Cu")
		(net "M_M_DQ<29>")
	)
	(segment
		(start 59.87415 -153.390346)
		(end 59.72175 -153.542746)
		(width 0.14224)
		(layer "In11.Cu")
		(net "M_M_DQ<29>")
	)
	(segment
		(start 60.696602 -134.681468)
		(end 60.696602 -135.938768)
		(width 0.14224)
		(layer "In11.Cu")
		(net "M_M_DQ<29>")
	)
	(segment
		(start 61.74359 -122.41911)
		(end 61.828934 -122.504454)
		(width 0.14224)
		(layer "In11.Cu")
		(net "M_M_DQ<29>")
	)
	(segment
		(start 83.148932 -88.56472)
		(end 83.142582 -88.575388)
		(width 0.0889)
		(layer "In11.Cu")
		(net "M_M_DQ<29>")
	)
	(segment
		(start 65.192402 -118.75135)
		(end 65.192402 -118.970298)
		(width 0.14224)
		(layer "In11.Cu")
		(net "M_M_DQ<29>")
	)
	(segment
		(start 59.77255 -149.9616)
		(end 59.77255 -150.5204)
		(width 0.14224)
		(layer "In11.Cu")
		(net "M_M_DQ<29>")
	)
	(segment
		(start 65.767204 -118.395496)
		(end 65.548256 -118.395496)
		(width 0.14224)
		(layer "In11.Cu")
		(net "M_M_DQ<29>")
	)
	(segment
		(start 61.828934 -122.723402)
		(end 61.47308 -123.079256)
		(width 0.14224)
		(layer "In11.Cu")
		(net "M_M_DQ<29>")
	)
	(segment
		(start 59.610752 -151.755856)
		(end 59.84875 -151.993854)
		(width 0.14224)
		(layer "In11.Cu")
		(net "M_M_DQ<29>")
	)
	(segment
		(start 77.94625 -102.586028)
		(end 77.94625 -104.296718)
		(width 0.14224)
		(layer "In11.Cu")
		(net "M_M_DQ<29>")
	)
	(segment
		(start 83.489292 -86.794086)
		(end 83.159854 -87.55507)
		(width 0.0889)
		(layer "In11.Cu")
		(net "M_M_DQ<29>")
	)
	(segment
		(start 62.893194 -121.050558)
		(end 62.893194 -121.269506)
		(width 0.14224)
		(layer "In11.Cu")
		(net "M_M_DQ<29>")
	)
	(segment
		(start 63.55334 -120.780048)
		(end 63.467996 -120.694704)
		(width 0.14224)
		(layer "In11.Cu")
		(net "M_M_DQ<29>")
	)
	(segment
		(start 60.475368 -138.9634)
		(end 60.475368 -139.446)
		(width 0.14224)
		(layer "In11.Cu")
		(net "M_M_DQ<29>")
	)
	(segment
		(start 59.84875 -152.348946)
		(end 59.610752 -152.586944)
		(width 0.14224)
		(layer "In11.Cu")
		(net "M_M_DQ<29>")
	)
	(segment
		(start 62.099444 -121.844308)
		(end 61.74359 -122.200162)
		(width 0.14224)
		(layer "In11.Cu")
		(net "M_M_DQ<29>")
	)
	(segment
		(start 80.931512 -96.79559)
		(end 80.898746 -96.79559)
		(width 0.0889)
		(layer "In11.Cu")
		(net "M_M_DQ<29>")
	)
	(segment
		(start 78.973934 -98.60788)
		(end 78.973934 -99.142804)
		(width 0.0889)
		(layer "In11.Cu")
		(net "M_M_DQ<29>")
	)
	(segment
		(start 60.602368 -125.5268)
		(end 60.322968 -125.8062)
		(width 0.14224)
		(layer "In11.Cu")
		(net "M_M_DQ<29>")
	)
	(segment
		(start 65.852548 -118.48084)
		(end 65.767204 -118.395496)
		(width 0.14224)
		(layer "In11.Cu")
		(net "M_M_DQ<29>")
	)
	(segment
		(start 60.526168 -146.151346)
		(end 60.729368 -146.354546)
		(width 0.14224)
		(layer "In11.Cu")
		(net "M_M_DQ<29>")
	)
	(segment
		(start 65.277746 -119.055642)
		(end 65.277746 -119.27459)
		(width 0.14224)
		(layer "In11.Cu")
		(net "M_M_DQ<29>")
	)
	(segment
		(start 62.622684 -121.929652)
		(end 62.403736 -121.929652)
		(width 0.14224)
		(layer "In11.Cu")
		(net "M_M_DQ<29>")
	)
	(segment
		(start 60.696602 -140.971778)
		(end 60.526168 -141.142212)
		(width 0.14224)
		(layer "In11.Cu")
		(net "M_M_DQ<29>")
	)
	(segment
		(start 82.290412 -94.01302)
		(end 82.284062 -94.023688)
		(width 0.0889)
		(layer "In11.Cu")
		(net "M_M_DQ<29>")
	)
	(segment
		(start 61.254132 -123.079256)
		(end 61.168788 -122.993912)
		(width 0.14224)
		(layer "In11.Cu")
		(net "M_M_DQ<29>")
	)
	(segment
		(start 60.607702 -148.432266)
		(end 60.607702 -149.1488)
		(width 0.14224)
		(layer "In11.Cu")
		(net "M_M_DQ<29>")
	)
	(segment
		(start 64.921892 -119.630444)
		(end 64.702944 -119.630444)
		(width 0.14224)
		(layer "In11.Cu")
		(net "M_M_DQ<29>")
	)
	(segment
		(start 60.449968 -144.0688)
		(end 60.760102 -144.378934)
		(width 0.14224)
		(layer "In11.Cu")
		(net "M_M_DQ<29>")
	)
	(segment
		(start 59.77255 -150.5204)
		(end 59.89955 -150.6474)
		(width 0.14224)
		(layer "In11.Cu")
		(net "M_M_DQ<29>")
	)
	(segment
		(start 60.607702 -149.1488)
		(end 60.223146 -149.533356)
		(width 0.14224)
		(layer "In11.Cu")
		(net "M_M_DQ<29>")
	)
	(segment
		(start 78.973934 -99.142804)
		(end 78.230984 -99.885754)
		(width 0.0889)
		(layer "In11.Cu")
		(net "M_M_DQ<29>")
	)
	(segment
		(start 59.610752 -152.898856)
		(end 59.87415 -153.162254)
		(width 0.14224)
		(layer "In11.Cu")
		(net "M_M_DQ<29>")
	)
	(segment
		(start 63.772288 -120.780048)
		(end 63.55334 -120.780048)
		(width 0.14224)
		(layer "In11.Cu")
		(net "M_M_DQ<29>")
	)
	(segment
		(start 65.192402 -118.970298)
		(end 65.277746 -119.055642)
		(width 0.14224)
		(layer "In11.Cu")
		(net "M_M_DQ<29>")
	)
	(segment
		(start 60.830968 -129.159)
		(end 60.551568 -129.4384)
		(width 0.14224)
		(layer "In11.Cu")
		(net "M_M_DQ<29>")
	)
	(segment
		(start 64.042798 -119.900954)
		(end 64.042798 -120.119902)
		(width 0.14224)
		(layer "In11.Cu")
		(net "M_M_DQ<29>")
	)
	(segment
		(start 60.526168 -145.796254)
		(end 60.526168 -146.151346)
		(width 0.14224)
		(layer "In11.Cu")
		(net "M_M_DQ<29>")
	)
	(segment
		(start 78.230984 -99.885754)
		(end 78.230984 -100.673154)
		(width 0.0889)
		(layer "In11.Cu")
		(net "M_M_DQ<29>")
	)
	(segment
		(start 66.72707 -117.825266)
		(end 66.071496 -118.48084)
		(width 0.14224)
		(layer "In11.Cu")
		(net "M_M_DQ<29>")
	)
	(segment
		(start 62.978538 -121.573798)
		(end 62.622684 -121.929652)
		(width 0.14224)
		(layer "In11.Cu")
		(net "M_M_DQ<29>")
	)
	(segment
		(start 78.230984 -100.673154)
		(end 77.722984 -101.181154)
		(width 0.0889)
		(layer "In11.Cu")
		(net "M_M_DQ<29>")
	)
	(segment
		(start 83.142582 -89.565988)
		(end 83.137756 -89.574624)
		(width 0.0889)
		(layer "In11.Cu")
		(net "M_M_DQ<29>")
	)
	(segment
		(start 77.722984 -102.362762)
		(end 77.94625 -102.586028)
		(width 0.0889)
		(layer "In11.Cu")
		(net "M_M_DQ<29>")
	)
	(segment
		(start 60.200794 -149.533356)
		(end 59.77255 -149.9616)
		(width 0.14224)
		(layer "In11.Cu")
		(net "M_M_DQ<29>")
	)
	(segment
		(start 60.633102 -134.617968)
		(end 60.696602 -134.681468)
		(width 0.14224)
		(layer "In11.Cu")
		(net "M_M_DQ<29>")
	)
	(arc
		(start 82.615786 -91.84259)
		(mid 82.282868 -92.044581)
		(end 82.279236 -92.433902)
		(width 0.0889)
		(layer "In11.Cu")
		(net "M_M_DQ<29>")
	)
	(arc
		(start 82.284062 -93.033088)
		(mid 82.230592 -93.228151)
		(end 82.279236 -93.424502)
		(width 0.0889)
		(layer "In11.Cu")
		(net "M_M_DQ<29>")
	)
	(arc
		(start 82.284062 -93.433138)
		(mid 82.363284 -93.722256)
		(end 82.290412 -94.01302)
		(width 0.0889)
		(layer "In11.Cu")
		(net "M_M_DQ<29>")
	)
	(arc
		(start 80.567022 -96.995488)
		(mid 80.360018 -97.206352)
		(end 80.076802 -97.290636)
		(width 0.0889)
		(layer "In11.Cu")
		(net "M_M_DQ<29>")
	)
	(arc
		(start 83.137756 -87.593424)
		(mid 83.089001 -87.789776)
		(end 83.142582 -87.984838)
		(width 0.0889)
		(layer "In11.Cu")
		(net "M_M_DQ<29>")
	)
	(arc
		(start 80.044036 -97.290636)
		(mid 79.850186 -97.346986)
		(end 79.708502 -97.490788)
		(width 0.0889)
		(layer "In11.Cu")
		(net "M_M_DQ<29>")
	)
	(arc
		(start 83.142582 -88.975438)
		(mid 83.221804 -89.264556)
		(end 83.148932 -89.55532)
		(width 0.0889)
		(layer "In11.Cu")
		(net "M_M_DQ<29>")
	)
	(arc
		(start 82.284062 -94.023688)
		(mid 82.230563 -94.223586)
		(end 82.284062 -94.423484)
		(width 0.0889)
		(layer "In11.Cu")
		(net "M_M_DQ<29>")
	)
	(arc
		(start 83.142582 -90.956638)
		(mid 83.146911 -91.53981)
		(end 82.648552 -91.84259)
		(width 0.0889)
		(layer "In11.Cu")
		(net "M_M_DQ<29>")
	)
	(arc
		(start 83.137756 -89.574624)
		(mid 83.089001 -89.770976)
		(end 83.142582 -89.966038)
		(width 0.0889)
		(layer "In11.Cu")
		(net "M_M_DQ<29>")
	)
	(arc
		(start 83.142582 -87.984838)
		(mid 83.221804 -88.273956)
		(end 83.148932 -88.56472)
		(width 0.0889)
		(layer "In11.Cu")
		(net "M_M_DQ<29>")
	)
	(arc
		(start 83.142582 -89.966038)
		(mid 83.221804 -90.255156)
		(end 83.148932 -90.54592)
		(width 0.0889)
		(layer "In11.Cu")
		(net "M_M_DQ<29>")
	)
	(arc
		(start 79.181706 -97.78619)
		(mid 78.848788 -97.988181)
		(end 78.845156 -98.377502)
		(width 0.0889)
		(layer "In11.Cu")
		(net "M_M_DQ<29>")
	)
	(arc
		(start 80.898746 -96.79559)
		(mid 80.707104 -96.852756)
		(end 80.567022 -96.995488)
		(width 0.0889)
		(layer "In11.Cu")
		(net "M_M_DQ<29>")
	)
	(arc
		(start 83.137756 -88.584024)
		(mid 83.089001 -88.780376)
		(end 83.142582 -88.975438)
		(width 0.0889)
		(layer "In11.Cu")
		(net "M_M_DQ<29>")
	)
	(arc
		(start 79.708502 -97.490788)
		(mid 79.499894 -97.70272)
		(end 79.214472 -97.78619)
		(width 0.0889)
		(layer "In11.Cu")
		(net "M_M_DQ<29>")
	)
	(arc
		(start 82.284062 -94.423484)
		(mid 82.289316 -95.004992)
		(end 81.793842 -95.309436)
		(width 0.0889)
		(layer "In11.Cu")
		(net "M_M_DQ<29>")
	)
	(arc
		(start 82.290412 -92.453206)
		(mid 82.36321 -92.743969)
		(end 82.284062 -93.033088)
		(width 0.0889)
		(layer "In11.Cu")
		(net "M_M_DQ<29>")
	)
	(arc
		(start 83.137756 -90.565224)
		(mid 83.089001 -90.761576)
		(end 83.142582 -90.956638)
		(width 0.0889)
		(layer "In11.Cu")
		(net "M_M_DQ<29>")
	)
	(arc
		(start 81.425542 -95.909638)
		(mid 81.429871 -96.49281)
		(end 80.931512 -96.79559)
		(width 0.0889)
		(layer "In11.Cu")
		(net "M_M_DQ<29>")
	)
	(arc
		(start 81.761076 -95.309436)
		(mid 81.422907 -95.514234)
		(end 81.425542 -95.909638)
		(width 0.0889)
		(layer "In11.Cu")
		(net "M_M_DQ<29>")
	)
	(segment
		(start 60.299346 -156.87294)
		(end 60.299346 -155.547568)
		(width 0.1651)
		(layer "F.Cu")
		(net "M_M_DQ<28>")
	)
	(segment
		(start 84.060792 -85.803486)
		(end 83.489292 -85.803486)
		(width 0.0889)
		(layer "F.Cu")
		(net "M_M_DQ<28>")
	)
	(segment
		(start 60.299346 -155.547568)
		(end 60.201302 -155.0162)
		(width 0.1651)
		(layer "F.Cu")
		(net "M_M_DQ<28>")
	)
	(via
		(at 59.449462 -150.814278)
		(size 0.508)
		(drill 0.254)
		(layers "F.Cu" "B.Cu")
		(net "M_M_DQ<28>")
	)
	(via
		(at 83.489292 -85.803486)
		(size 0.508)
		(drill 0.254)
		(layers "F.Cu" "B.Cu")
		(net "M_M_DQ<28>")
	)
	(via
		(at 60.201302 -155.0162)
		(size 0.508)
		(drill 0.254)
		(layers "F.Cu" "B.Cu")
		(net "M_M_DQ<28>")
	)
	(segment
		(start 59.449462 -152.078436)
		(end 59.449462 -150.814278)
		(width 0.1651)
		(layer "B.Cu")
		(net "M_M_DQ<28>")
	)
	(segment
		(start 82.977482 -86.498938)
		(end 82.971132 -86.509606)
		(width 0.0889)
		(layer "In11.Cu")
		(net "M_M_DQ<28>")
	)
	(segment
		(start 59.947302 -131.9022)
		(end 59.865768 -131.983734)
		(width 0.14224)
		(layer "In11.Cu")
		(net "M_M_DQ<28>")
	)
	(segment
		(start 59.865768 -141.706854)
		(end 59.865768 -143.6116)
		(width 0.14224)
		(layer "In11.Cu")
		(net "M_M_DQ<28>")
	)
	(segment
		(start 82.977482 -90.461338)
		(end 82.971132 -90.472006)
		(width 0.0889)
		(layer "In11.Cu")
		(net "M_M_DQ<28>")
	)
	(segment
		(start 59.865768 -148.3106)
		(end 59.934602 -148.379434)
		(width 0.14224)
		(layer "In11.Cu")
		(net "M_M_DQ<28>")
	)
	(segment
		(start 59.68111 -145.527776)
		(end 59.934602 -145.781268)
		(width 0.14224)
		(layer "In11.Cu")
		(net "M_M_DQ<28>")
	)
	(segment
		(start 77.31125 -102.586028)
		(end 77.31125 -104.017318)
		(width 0.14224)
		(layer "In11.Cu")
		(net "M_M_DQ<28>")
	)
	(segment
		(start 59.992768 -129.3876)
		(end 59.992768 -129.722372)
		(width 0.14224)
		(layer "In11.Cu")
		(net "M_M_DQ<28>")
	)
	(segment
		(start 59.865768 -134.0866)
		(end 60.01385 -134.234682)
		(width 0.14224)
		(layer "In11.Cu")
		(net "M_M_DQ<28>")
	)
	(segment
		(start 59.016392 -153.83129)
		(end 60.201302 -155.0162)
		(width 0.14224)
		(layer "In11.Cu")
		(net "M_M_DQ<28>")
	)
	(segment
		(start 59.934602 -146.234912)
		(end 59.865768 -146.303746)
		(width 0.14224)
		(layer "In11.Cu")
		(net "M_M_DQ<28>")
	)
	(segment
		(start 82.977482 -89.470738)
		(end 82.971132 -89.481406)
		(width 0.0889)
		(layer "In11.Cu")
		(net "M_M_DQ<28>")
	)
	(segment
		(start 59.947302 -143.693134)
		(end 59.947302 -144.063466)
		(width 0.14224)
		(layer "In11.Cu")
		(net "M_M_DQ<28>")
	)
	(segment
		(start 77.31125 -104.017318)
		(end 73.657968 -107.6706)
		(width 0.14224)
		(layer "In11.Cu")
		(net "M_M_DQ<28>")
	)
	(segment
		(start 68.848478 -117.30609)
		(end 65.958974 -117.30609)
		(width 0.14224)
		(layer "In11.Cu")
		(net "M_M_DQ<28>")
	)
	(segment
		(start 59.986164 -123.2789)
		(end 59.986164 -124.060204)
		(width 0.14224)
		(layer "In11.Cu")
		(net "M_M_DQ<28>")
	)
	(segment
		(start 59.732164 -127.552196)
		(end 59.789568 -127.6096)
		(width 0.14224)
		(layer "In11.Cu")
		(net "M_M_DQ<28>")
	)
	(segment
		(start 59.718702 -129.996438)
		(end 59.718702 -131.180078)
		(width 0.14224)
		(layer "In11.Cu")
		(net "M_M_DQ<28>")
	)
	(segment
		(start 59.934602 -145.781268)
		(end 59.934602 -146.234912)
		(width 0.14224)
		(layer "In11.Cu")
		(net "M_M_DQ<28>")
	)
	(segment
		(start 59.972702 -136.6012)
		(end 59.865768 -136.708134)
		(width 0.14224)
		(layer "In11.Cu")
		(net "M_M_DQ<28>")
	)
	(segment
		(start 59.865768 -131.983734)
		(end 59.865768 -134.0866)
		(width 0.14224)
		(layer "In11.Cu")
		(net "M_M_DQ<28>")
	)
	(segment
		(start 59.134502 -149.760178)
		(end 59.134502 -150.499318)
		(width 0.14224)
		(layer "In11.Cu")
		(net "M_M_DQ<28>")
	)
	(segment
		(start 59.865768 -143.6116)
		(end 59.947302 -143.693134)
		(width 0.14224)
		(layer "In11.Cu")
		(net "M_M_DQ<28>")
	)
	(segment
		(start 78.040992 -100.594414)
		(end 77.532992 -101.102414)
		(width 0.0889)
		(layer "In11.Cu")
		(net "M_M_DQ<28>")
	)
	(segment
		(start 65.958974 -117.30609)
		(end 59.986164 -123.2789)
		(width 0.14224)
		(layer "In11.Cu")
		(net "M_M_DQ<28>")
	)
	(segment
		(start 82.112612 -92.52712)
		(end 82.118962 -92.537788)
		(width 0.0889)
		(layer "In11.Cu")
		(net "M_M_DQ<28>")
	)
	(segment
		(start 78.783942 -99.064064)
		(end 78.040992 -99.807014)
		(width 0.0889)
		(layer "In11.Cu")
		(net "M_M_DQ<28>")
	)
	(segment
		(start 60.062872 -141.116304)
		(end 60.062872 -141.50975)
		(width 0.14224)
		(layer "In11.Cu")
		(net "M_M_DQ<28>")
	)
	(segment
		(start 82.982308 -88.471502)
		(end 82.977482 -88.480138)
		(width 0.0889)
		(layer "In11.Cu")
		(net "M_M_DQ<28>")
	)
	(segment
		(start 59.992768 -129.722372)
		(end 59.718702 -129.996438)
		(width 0.14224)
		(layer "In11.Cu")
		(net "M_M_DQ<28>")
	)
	(segment
		(start 59.134502 -150.499318)
		(end 59.449462 -150.814278)
		(width 0.14224)
		(layer "In11.Cu")
		(net "M_M_DQ<28>")
	)
	(segment
		(start 59.718702 -131.180078)
		(end 59.947302 -131.408678)
		(width 0.14224)
		(layer "In11.Cu")
		(net "M_M_DQ<28>")
	)
	(segment
		(start 59.449462 -150.814278)
		(end 59.016392 -151.247348)
		(width 0.14224)
		(layer "In11.Cu")
		(net "M_M_DQ<28>")
	)
	(segment
		(start 59.789568 -129.1844)
		(end 59.992768 -129.3876)
		(width 0.14224)
		(layer "In11.Cu")
		(net "M_M_DQ<28>")
	)
	(segment
		(start 82.982308 -87.480902)
		(end 82.977482 -87.489538)
		(width 0.0889)
		(layer "In11.Cu")
		(net "M_M_DQ<28>")
	)
	(segment
		(start 59.718702 -140.772134)
		(end 60.062872 -141.116304)
		(width 0.14224)
		(layer "In11.Cu")
		(net "M_M_DQ<28>")
	)
	(segment
		(start 77.532992 -102.364286)
		(end 77.31125 -102.586028)
		(width 0.0889)
		(layer "In11.Cu")
		(net "M_M_DQ<28>")
	)
	(segment
		(start 78.783942 -98.657918)
		(end 78.783942 -99.064064)
		(width 0.0889)
		(layer "In11.Cu")
		(net "M_M_DQ<28>")
	)
	(segment
		(start 60.062872 -141.50975)
		(end 59.865768 -141.706854)
		(width 0.14224)
		(layer "In11.Cu")
		(net "M_M_DQ<28>")
	)
	(segment
		(start 59.789568 -127.6096)
		(end 59.789568 -129.1844)
		(width 0.14224)
		(layer "In11.Cu")
		(net "M_M_DQ<28>")
	)
	(segment
		(start 59.972702 -138.943334)
		(end 59.972702 -139.333478)
		(width 0.14224)
		(layer "In11.Cu")
		(net "M_M_DQ<28>")
	)
	(segment
		(start 82.118962 -94.518988)
		(end 82.123788 -94.527624)
		(width 0.0889)
		(layer "In11.Cu")
		(net "M_M_DQ<28>")
	)
	(segment
		(start 78.040992 -99.807014)
		(end 78.040992 -100.594414)
		(width 0.0889)
		(layer "In11.Cu")
		(net "M_M_DQ<28>")
	)
	(segment
		(start 82.977482 -88.480138)
		(end 82.971132 -88.490806)
		(width 0.0889)
		(layer "In11.Cu")
		(net "M_M_DQ<28>")
	)
	(segment
		(start 59.947302 -131.408678)
		(end 59.947302 -131.9022)
		(width 0.14224)
		(layer "In11.Cu")
		(net "M_M_DQ<28>")
	)
	(segment
		(start 59.934602 -148.379434)
		(end 59.934602 -148.960078)
		(width 0.14224)
		(layer "In11.Cu")
		(net "M_M_DQ<28>")
	)
	(segment
		(start 82.641948 -91.65209)
		(end 82.609182 -91.65209)
		(width 0.0889)
		(layer "In11.Cu")
		(net "M_M_DQ<28>")
	)
	(segment
		(start 59.732164 -124.314204)
		(end 59.732164 -127.552196)
		(width 0.14224)
		(layer "In11.Cu")
		(net "M_M_DQ<28>")
	)
	(segment
		(start 83.489292 -85.803486)
		(end 82.994246 -86.469474)
		(width 0.0889)
		(layer "In11.Cu")
		(net "M_M_DQ<28>")
	)
	(segment
		(start 81.787238 -95.118936)
		(end 81.754472 -95.118936)
		(width 0.0889)
		(layer "In11.Cu")
		(net "M_M_DQ<28>")
	)
	(segment
		(start 73.657968 -112.4966)
		(end 68.848478 -117.30609)
		(width 0.14224)
		(layer "In11.Cu")
		(net "M_M_DQ<28>")
	)
	(segment
		(start 59.718702 -135.951468)
		(end 59.972702 -136.205468)
		(width 0.14224)
		(layer "In11.Cu")
		(net "M_M_DQ<28>")
	)
	(segment
		(start 82.118962 -92.537788)
		(end 82.123788 -92.546424)
		(width 0.0889)
		(layer "In11.Cu")
		(net "M_M_DQ<28>")
	)
	(segment
		(start 59.865768 -146.303746)
		(end 59.865768 -148.3106)
		(width 0.14224)
		(layer "In11.Cu")
		(net "M_M_DQ<28>")
	)
	(segment
		(start 82.977482 -87.489538)
		(end 82.971132 -87.500206)
		(width 0.0889)
		(layer "In11.Cu")
		(net "M_M_DQ<28>")
	)
	(segment
		(start 78.678532 -98.47072)
		(end 78.783942 -98.657918)
		(width 0.0889)
		(layer "In11.Cu")
		(net "M_M_DQ<28>")
	)
	(segment
		(start 59.865768 -138.8364)
		(end 59.972702 -138.943334)
		(width 0.14224)
		(layer "In11.Cu")
		(net "M_M_DQ<28>")
	)
	(segment
		(start 60.01385 -134.420864)
		(end 59.718702 -134.716012)
		(width 0.14224)
		(layer "In11.Cu")
		(net "M_M_DQ<28>")
	)
	(segment
		(start 77.532992 -101.102414)
		(end 77.532992 -102.364286)
		(width 0.0889)
		(layer "In11.Cu")
		(net "M_M_DQ<28>")
	)
	(segment
		(start 59.865768 -136.708134)
		(end 59.865768 -138.8364)
		(width 0.14224)
		(layer "In11.Cu")
		(net "M_M_DQ<28>")
	)
	(segment
		(start 59.934602 -148.960078)
		(end 59.134502 -149.760178)
		(width 0.14224)
		(layer "In11.Cu")
		(net "M_M_DQ<28>")
	)
	(segment
		(start 59.718702 -134.716012)
		(end 59.718702 -135.951468)
		(width 0.14224)
		(layer "In11.Cu")
		(net "M_M_DQ<28>")
	)
	(segment
		(start 82.118962 -93.928438)
		(end 82.112612 -93.939106)
		(width 0.0889)
		(layer "In11.Cu")
		(net "M_M_DQ<28>")
	)
	(segment
		(start 82.982308 -89.462102)
		(end 82.977482 -89.470738)
		(width 0.0889)
		(layer "In11.Cu")
		(net "M_M_DQ<28>")
	)
	(segment
		(start 79.207868 -97.59569)
		(end 79.175102 -97.59569)
		(width 0.0889)
		(layer "In11.Cu")
		(net "M_M_DQ<28>")
	)
	(segment
		(start 59.68111 -144.329658)
		(end 59.68111 -145.527776)
		(width 0.14224)
		(layer "In11.Cu")
		(net "M_M_DQ<28>")
	)
	(segment
		(start 59.947302 -144.063466)
		(end 59.68111 -144.329658)
		(width 0.14224)
		(layer "In11.Cu")
		(net "M_M_DQ<28>")
	)
	(segment
		(start 59.972702 -136.205468)
		(end 59.972702 -136.6012)
		(width 0.14224)
		(layer "In11.Cu")
		(net "M_M_DQ<28>")
	)
	(segment
		(start 59.718702 -139.587478)
		(end 59.718702 -140.772134)
		(width 0.14224)
		(layer "In11.Cu")
		(net "M_M_DQ<28>")
	)
	(segment
		(start 73.657968 -107.6706)
		(end 73.657968 -112.4966)
		(width 0.14224)
		(layer "In11.Cu")
		(net "M_M_DQ<28>")
	)
	(segment
		(start 82.994246 -86.469474)
		(end 82.977482 -86.498938)
		(width 0.0889)
		(layer "In11.Cu")
		(net "M_M_DQ<28>")
	)
	(segment
		(start 82.982308 -90.452702)
		(end 82.977482 -90.461338)
		(width 0.0889)
		(layer "In11.Cu")
		(net "M_M_DQ<28>")
	)
	(segment
		(start 80.924908 -96.60509)
		(end 80.892142 -96.60509)
		(width 0.0889)
		(layer "In11.Cu")
		(net "M_M_DQ<28>")
	)
	(segment
		(start 60.01385 -134.234682)
		(end 60.01385 -134.420864)
		(width 0.14224)
		(layer "In11.Cu")
		(net "M_M_DQ<28>")
	)
	(segment
		(start 59.016392 -151.247348)
		(end 59.016392 -153.83129)
		(width 0.14224)
		(layer "In11.Cu")
		(net "M_M_DQ<28>")
	)
	(segment
		(start 59.986164 -124.060204)
		(end 59.732164 -124.314204)
		(width 0.14224)
		(layer "In11.Cu")
		(net "M_M_DQ<28>")
	)
	(segment
		(start 59.972702 -139.333478)
		(end 59.718702 -139.587478)
		(width 0.14224)
		(layer "In11.Cu")
		(net "M_M_DQ<28>")
	)
	(segment
		(start 80.070198 -97.100136)
		(end 80.037432 -97.100136)
		(width 0.0889)
		(layer "In11.Cu")
		(net "M_M_DQ<28>")
	)
	(arc
		(start 82.977482 -88.080088)
		(mid 83.030952 -88.275151)
		(end 82.982308 -88.471502)
		(width 0.0889)
		(layer "In11.Cu")
		(net "M_M_DQ<28>")
	)
	(arc
		(start 79.543402 -97.395538)
		(mid 79.401719 -97.539342)
		(end 79.207868 -97.59569)
		(width 0.0889)
		(layer "In11.Cu")
		(net "M_M_DQ<28>")
	)
	(arc
		(start 82.123788 -94.527624)
		(mid 82.120041 -94.91688)
		(end 81.787238 -95.118936)
		(width 0.0889)
		(layer "In11.Cu")
		(net "M_M_DQ<28>")
	)
	(arc
		(start 82.971132 -88.490806)
		(mid 82.898334 -88.781569)
		(end 82.977482 -89.070688)
		(width 0.0889)
		(layer "In11.Cu")
		(net "M_M_DQ<28>")
	)
	(arc
		(start 82.609182 -91.65209)
		(mid 82.116792 -91.951023)
		(end 82.112612 -92.52712)
		(width 0.0889)
		(layer "In11.Cu")
		(net "M_M_DQ<28>")
	)
	(arc
		(start 82.971132 -87.500206)
		(mid 82.898334 -87.790969)
		(end 82.977482 -88.080088)
		(width 0.0889)
		(layer "In11.Cu")
		(net "M_M_DQ<28>")
	)
	(arc
		(start 82.977482 -89.070688)
		(mid 83.030952 -89.265751)
		(end 82.982308 -89.462102)
		(width 0.0889)
		(layer "In11.Cu")
		(net "M_M_DQ<28>")
	)
	(arc
		(start 81.260442 -96.004888)
		(mid 81.26319 -96.400355)
		(end 80.924908 -96.60509)
		(width 0.0889)
		(layer "In11.Cu")
		(net "M_M_DQ<28>")
	)
	(arc
		(start 82.971132 -86.509606)
		(mid 82.898334 -86.800369)
		(end 82.977482 -87.089488)
		(width 0.0889)
		(layer "In11.Cu")
		(net "M_M_DQ<28>")
	)
	(arc
		(start 82.977482 -87.089488)
		(mid 83.030952 -87.284551)
		(end 82.982308 -87.480902)
		(width 0.0889)
		(layer "In11.Cu")
		(net "M_M_DQ<28>")
	)
	(arc
		(start 80.892142 -96.60509)
		(mid 80.608925 -96.689371)
		(end 80.401922 -96.900238)
		(width 0.0889)
		(layer "In11.Cu")
		(net "M_M_DQ<28>")
	)
	(arc
		(start 80.037432 -97.100136)
		(mid 79.752008 -97.183603)
		(end 79.543402 -97.395538)
		(width 0.0889)
		(layer "In11.Cu")
		(net "M_M_DQ<28>")
	)
	(arc
		(start 82.118962 -93.528642)
		(mid 82.172461 -93.72854)
		(end 82.118962 -93.928438)
		(width 0.0889)
		(layer "In11.Cu")
		(net "M_M_DQ<28>")
	)
	(arc
		(start 82.971132 -90.472006)
		(mid 82.898334 -90.762769)
		(end 82.977482 -91.051888)
		(width 0.0889)
		(layer "In11.Cu")
		(net "M_M_DQ<28>")
	)
	(arc
		(start 82.112612 -93.939106)
		(mid 82.039814 -94.229869)
		(end 82.118962 -94.518988)
		(width 0.0889)
		(layer "In11.Cu")
		(net "M_M_DQ<28>")
	)
	(arc
		(start 79.175102 -97.59569)
		(mid 78.682712 -97.894623)
		(end 78.678532 -98.47072)
		(width 0.0889)
		(layer "In11.Cu")
		(net "M_M_DQ<28>")
	)
	(arc
		(start 80.401922 -96.900238)
		(mid 80.261843 -97.042974)
		(end 80.070198 -97.100136)
		(width 0.0889)
		(layer "In11.Cu")
		(net "M_M_DQ<28>")
	)
	(arc
		(start 82.971132 -89.481406)
		(mid 82.898334 -89.772169)
		(end 82.977482 -90.061288)
		(width 0.0889)
		(layer "In11.Cu")
		(net "M_M_DQ<28>")
	)
	(arc
		(start 82.118962 -92.937838)
		(mid 82.039831 -93.23324)
		(end 82.118962 -93.528642)
		(width 0.0889)
		(layer "In11.Cu")
		(net "M_M_DQ<28>")
	)
	(arc
		(start 82.977482 -91.051888)
		(mid 82.98023 -91.447355)
		(end 82.641948 -91.65209)
		(width 0.0889)
		(layer "In11.Cu")
		(net "M_M_DQ<28>")
	)
	(arc
		(start 82.977482 -90.061288)
		(mid 83.030952 -90.256351)
		(end 82.982308 -90.452702)
		(width 0.0889)
		(layer "In11.Cu")
		(net "M_M_DQ<28>")
	)
	(arc
		(start 82.123788 -92.546424)
		(mid 82.172543 -92.742776)
		(end 82.118962 -92.937838)
		(width 0.0889)
		(layer "In11.Cu")
		(net "M_M_DQ<28>")
	)
	(arc
		(start 81.754472 -95.118936)
		(mid 81.256221 -95.421776)
		(end 81.260442 -96.004888)
		(width 0.0889)
		(layer "In11.Cu")
		(net "M_M_DQ<28>")
	)
	(segment
		(start 67.099434 -152.273)
		(end 67.099434 -153.542746)
		(width 0.1651)
		(layer "F.Cu")
		(net "M_M_DQ<27>")
	)
	(segment
		(start 87.494872 -86.794086)
		(end 86.923372 -86.794086)
		(width 0.1651)
		(layer "F.Cu")
		(net "M_M_DQ<27>")
	)
	(via
		(at 86.923372 -86.794086)
		(size 0.508)
		(drill 0.254)
		(layers "F.Cu" "B.Cu")
		(net "M_M_DQ<27>")
	)
	(via
		(at 67.099434 -153.542746)
		(size 0.508)
		(drill 0.254)
		(layers "F.Cu" "B.Cu")
		(net "M_M_DQ<27>")
	)
	(via
		(at 67.949318 -149.533356)
		(size 0.508)
		(drill 0.254)
		(layers "F.Cu" "B.Cu")
		(net "M_M_DQ<27>")
	)
	(segment
		(start 67.949318 -147.478496)
		(end 67.949318 -149.533356)
		(width 0.1651)
		(layer "B.Cu")
		(net "M_M_DQ<27>")
	)
	(segment
		(start 67.949572 -147.478496)
		(end 67.949318 -147.478496)
		(width 0.1651)
		(layer "B.Cu")
		(net "M_M_DQ<27>")
	)
	(segment
		(start 67.543172 -150.435818)
		(end 67.543172 -151.1046)
		(width 0.14224)
		(layer "In11.Cu")
		(net "M_M_DQ<27>")
	)
	(segment
		(start 68.374768 -136.621266)
		(end 68.374768 -138.7348)
		(width 0.14224)
		(layer "In11.Cu")
		(net "M_M_DQ<27>")
	)
	(segment
		(start 68.303902 -129.960878)
		(end 68.456302 -130.113278)
		(width 0.14224)
		(layer "In11.Cu")
		(net "M_M_DQ<27>")
	)
	(segment
		(start 76.523088 -122.012964)
		(end 76.303886 -122.012964)
		(width 0.14224)
		(layer "In11.Cu")
		(net "M_M_DQ<27>")
	)
	(segment
		(start 68.303902 -126.34087)
		(end 68.303902 -129.960878)
		(width 0.14224)
		(layer "In11.Cu")
		(net "M_M_DQ<27>")
	)
	(segment
		(start 67.543172 -151.1046)
		(end 67.260724 -151.387048)
		(width 0.14224)
		(layer "In11.Cu")
		(net "M_M_DQ<27>")
	)
	(segment
		(start 74.794618 -122.802396)
		(end 74.57567 -122.802396)
		(width 0.14224)
		(layer "In11.Cu")
		(net "M_M_DQ<27>")
	)
	(segment
		(start 68.481702 -134.738364)
		(end 68.481702 -136.036812)
		(width 0.14224)
		(layer "In11.Cu")
		(net "M_M_DQ<27>")
	)
	(segment
		(start 68.303902 -139.4968)
		(end 68.39204 -139.584938)
		(width 0.1016)
		(layer "In11.Cu")
		(net "M_M_DQ<27>")
	)
	(segment
		(start 78.024482 -119.353584)
		(end 77.668628 -119.709438)
		(width 0.14224)
		(layer "In11.Cu")
		(net "M_M_DQ<27>")
	)
	(segment
		(start 85.936074 -98.600768)
		(end 83.895184 -100.641658)
		(width 0.0889)
		(layer "In11.Cu")
		(net "M_M_DQ<27>")
	)
	(segment
		(start 75.36942 -122.008646)
		(end 75.36942 -122.227594)
		(width 0.14224)
		(layer "In11.Cu")
		(net "M_M_DQ<27>")
	)
	(segment
		(start 68.532502 -144.398238)
		(end 68.532502 -145.587212)
		(width 0.14224)
		(layer "In11.Cu")
		(net "M_M_DQ<27>")
	)
	(segment
		(start 76.830174 -121.389648)
		(end 76.878942 -121.438416)
		(width 0.14224)
		(layer "In11.Cu")
		(net "M_M_DQ<27>")
	)
	(segment
		(start 77.668628 -119.709438)
		(end 77.668628 -119.928386)
		(width 0.14224)
		(layer "In11.Cu")
		(net "M_M_DQ<27>")
	)
	(segment
		(start 68.425568 -126.219204)
		(end 68.303902 -126.34087)
		(width 0.14224)
		(layer "In11.Cu")
		(net "M_M_DQ<27>")
	)
	(segment
		(start 68.278502 -148.356066)
		(end 68.278502 -149.21738)
		(width 0.14224)
		(layer "In11.Cu")
		(net "M_M_DQ<27>")
	)
	(segment
		(start 86.583012 -96.48952)
		(end 86.576662 -96.500188)
		(width 0.0889)
		(layer "In11.Cu")
		(net "M_M_DQ<27>")
	)
	(segment
		(start 87.430356 -91.443302)
		(end 87.435182 -91.451938)
		(width 0.0889)
		(layer "In11.Cu")
		(net "M_M_DQ<27>")
	)
	(segment
		(start 68.425568 -125.6792)
		(end 68.425568 -126.219204)
		(width 0.14224)
		(layer "In11.Cu")
		(net "M_M_DQ<27>")
	)
	(segment
		(start 76.878942 -121.65711)
		(end 76.523088 -122.012964)
		(width 0.14224)
		(layer "In11.Cu")
		(net "M_M_DQ<27>")
	)
	(segment
		(start 68.316602 -134.573264)
		(end 68.481702 -134.738364)
		(width 0.14224)
		(layer "In11.Cu")
		(net "M_M_DQ<27>")
	)
	(segment
		(start 77.668628 -119.928386)
		(end 77.982318 -120.242584)
		(width 0.14224)
		(layer "In11.Cu")
		(net "M_M_DQ<27>")
	)
	(segment
		(start 68.39204 -141.021562)
		(end 68.316602 -141.097)
		(width 0.1016)
		(layer "In11.Cu")
		(net "M_M_DQ<27>")
	)
	(segment
		(start 67.260724 -152.752552)
		(end 67.549522 -153.04135)
		(width 0.14224)
		(layer "In11.Cu")
		(net "M_M_DQ<27>")
	)
	(segment
		(start 79.01813 -118.972584)
		(end 79.01813 -119.197882)
		(width 0.14224)
		(layer "In11.Cu")
		(net "M_M_DQ<27>")
	)
	(segment
		(start 80.185768 -117.192298)
		(end 78.818232 -118.559834)
		(width 0.14224)
		(layer "In11.Cu")
		(net "M_M_DQ<27>")
	)
	(segment
		(start 67.949318 -149.546564)
		(end 67.949318 -149.533356)
		(width 0.14224)
		(layer "In11.Cu")
		(net "M_M_DQ<27>")
	)
	(segment
		(start 75.36942 -122.227594)
		(end 75.73645 -122.595132)
		(width 0.14224)
		(layer "In11.Cu")
		(net "M_M_DQ<27>")
	)
	(segment
		(start 87.435182 -88.480138)
		(end 87.441532 -88.490806)
		(width 0.0889)
		(layer "In11.Cu")
		(net "M_M_DQ<27>")
	)
	(segment
		(start 78.443328 -119.553736)
		(end 78.24343 -119.353584)
		(width 0.14224)
		(layer "In11.Cu")
		(net "M_M_DQ<27>")
	)
	(segment
		(start 77.626464 -120.817132)
		(end 77.407262 -120.817132)
		(width 0.14224)
		(layer "In11.Cu")
		(net "M_M_DQ<27>")
	)
	(segment
		(start 84.136992 -106.360976)
		(end 80.185768 -110.3122)
		(width 0.14224)
		(layer "In11.Cu")
		(net "M_M_DQ<27>")
	)
	(segment
		(start 68.374768 -138.7348)
		(end 68.303902 -138.805666)
		(width 0.14224)
		(layer "In11.Cu")
		(net "M_M_DQ<27>")
	)
	(segment
		(start 83.895184 -100.641658)
		(end 83.895184 -102.844346)
		(width 0.0889)
		(layer "In11.Cu")
		(net "M_M_DQ<27>")
	)
	(segment
		(start 68.456302 -130.113278)
		(end 68.456302 -131.268978)
		(width 0.14224)
		(layer "In11.Cu")
		(net "M_M_DQ<27>")
	)
	(segment
		(start 67.498722 -149.9616)
		(end 67.498722 -150.391368)
		(width 0.14224)
		(layer "In11.Cu")
		(net "M_M_DQ<27>")
	)
	(segment
		(start 68.481702 -136.036812)
		(end 68.303902 -136.214612)
		(width 0.14224)
		(layer "In11.Cu")
		(net "M_M_DQ<27>")
	)
	(segment
		(start 75.944222 -121.652792)
		(end 75.725274 -121.652792)
		(width 0.14224)
		(layer "In11.Cu")
		(net "M_M_DQ<27>")
	)
	(segment
		(start 75.161394 -123.16968)
		(end 74.794618 -122.802396)
		(width 0.14224)
		(layer "In11.Cu")
		(net "M_M_DQ<27>")
	)
	(segment
		(start 67.549522 -153.364946)
		(end 67.371722 -153.542746)
		(width 0.14224)
		(layer "In11.Cu")
		(net "M_M_DQ<27>")
	)
	(segment
		(start 78.24343 -119.353584)
		(end 78.024482 -119.353584)
		(width 0.14224)
		(layer "In11.Cu")
		(net "M_M_DQ<27>")
	)
	(segment
		(start 86.923372 -86.794086)
		(end 87.418418 -87.460074)
		(width 0.0889)
		(layer "In11.Cu")
		(net "M_M_DQ<27>")
	)
	(segment
		(start 73.273666 -124.1044)
		(end 69.619368 -124.1044)
		(width 0.14224)
		(layer "In11.Cu")
		(net "M_M_DQ<27>")
	)
	(segment
		(start 67.260724 -151.387048)
		(end 67.260724 -151.660352)
		(width 0.14224)
		(layer "In11.Cu")
		(net "M_M_DQ<27>")
	)
	(segment
		(start 86.576662 -96.500188)
		(end 86.571836 -96.508824)
		(width 0.0889)
		(layer "In11.Cu")
		(net "M_M_DQ<27>")
	)
	(segment
		(start 68.316602 -141.097)
		(end 68.316602 -144.182338)
		(width 0.14224)
		(layer "In11.Cu")
		(net "M_M_DQ<27>")
	)
	(segment
		(start 87.430356 -89.462102)
		(end 87.435182 -89.470738)
		(width 0.0889)
		(layer "In11.Cu")
		(net "M_M_DQ<27>")
	)
	(segment
		(start 67.949318 -149.533356)
		(end 67.926966 -149.533356)
		(width 0.14224)
		(layer "In11.Cu")
		(net "M_M_DQ<27>")
	)
	(segment
		(start 68.316602 -134.144766)
		(end 68.316602 -134.573264)
		(width 0.14224)
		(layer "In11.Cu")
		(net "M_M_DQ<27>")
	)
	(segment
		(start 76.874878 -120.503188)
		(end 76.519024 -120.859042)
		(width 0.14224)
		(layer "In11.Cu")
		(net "M_M_DQ<27>")
	)
	(segment
		(start 69.619368 -124.1044)
		(end 69.136768 -124.587)
		(width 0.14224)
		(layer "In11.Cu")
		(net "M_M_DQ<27>")
	)
	(segment
		(start 80.185768 -110.3122)
		(end 80.185768 -117.192298)
		(width 0.14224)
		(layer "In11.Cu")
		(net "M_M_DQ<27>")
	)
	(segment
		(start 79.01813 -119.197882)
		(end 78.662276 -119.553736)
		(width 0.14224)
		(layer "In11.Cu")
		(net "M_M_DQ<27>")
	)
	(segment
		(start 75.73645 -122.813826)
		(end 75.380596 -123.16968)
		(width 0.14224)
		(layer "In11.Cu")
		(net "M_M_DQ<27>")
	)
	(segment
		(start 68.374768 -131.909566)
		(end 68.374768 -134.0866)
		(width 0.14224)
		(layer "In11.Cu")
		(net "M_M_DQ<27>")
	)
	(segment
		(start 67.371722 -153.542746)
		(end 67.099434 -153.542746)
		(width 0.14224)
		(layer "In11.Cu")
		(net "M_M_DQ<27>")
	)
	(segment
		(start 68.303902 -138.805666)
		(end 68.303902 -139.4968)
		(width 0.14224)
		(layer "In11.Cu")
		(net "M_M_DQ<27>")
	)
	(segment
		(start 77.982318 -120.461278)
		(end 77.626464 -120.817132)
		(width 0.14224)
		(layer "In11.Cu")
		(net "M_M_DQ<27>")
	)
	(segment
		(start 68.456302 -131.268978)
		(end 68.316602 -131.408678)
		(width 0.14224)
		(layer "In11.Cu")
		(net "M_M_DQ<27>")
	)
	(segment
		(start 78.662276 -119.553736)
		(end 78.443328 -119.553736)
		(width 0.14224)
		(layer "In11.Cu")
		(net "M_M_DQ<27>")
	)
	(segment
		(start 87.418418 -87.460074)
		(end 87.435182 -87.489538)
		(width 0.0889)
		(layer "In11.Cu")
		(net "M_M_DQ<27>")
	)
	(segment
		(start 68.316602 -144.182338)
		(end 68.532502 -144.398238)
		(width 0.14224)
		(layer "In11.Cu")
		(net "M_M_DQ<27>")
	)
	(segment
		(start 75.380596 -123.16968)
		(end 75.161394 -123.16968)
		(width 0.14224)
		(layer "In11.Cu")
		(net "M_M_DQ<27>")
	)
	(segment
		(start 86.583012 -95.49892)
		(end 86.576662 -95.509588)
		(width 0.0889)
		(layer "In11.Cu")
		(net "M_M_DQ<27>")
	)
	(segment
		(start 75.73645 -122.595132)
		(end 75.73645 -122.813826)
		(width 0.14224)
		(layer "In11.Cu")
		(net "M_M_DQ<27>")
	)
	(segment
		(start 67.549522 -153.04135)
		(end 67.549522 -153.364946)
		(width 0.14224)
		(layer "In11.Cu")
		(net "M_M_DQ<27>")
	)
	(segment
		(start 77.982318 -120.242584)
		(end 77.982318 -120.461278)
		(width 0.14224)
		(layer "In11.Cu")
		(net "M_M_DQ<27>")
	)
	(segment
		(start 68.316602 -131.8514)
		(end 68.374768 -131.909566)
		(width 0.14224)
		(layer "In11.Cu")
		(net "M_M_DQ<27>")
	)
	(segment
		(start 68.278502 -149.21738)
		(end 67.949318 -149.546564)
		(width 0.14224)
		(layer "In11.Cu")
		(net "M_M_DQ<27>")
	)
	(segment
		(start 87.430356 -90.452702)
		(end 87.435182 -90.461338)
		(width 0.0889)
		(layer "In11.Cu")
		(net "M_M_DQ<27>")
	)
	(segment
		(start 68.374768 -148.2598)
		(end 68.278502 -148.356066)
		(width 0.14224)
		(layer "In11.Cu")
		(net "M_M_DQ<27>")
	)
	(segment
		(start 67.926966 -149.533356)
		(end 67.498722 -149.9616)
		(width 0.14224)
		(layer "In11.Cu")
		(net "M_M_DQ<27>")
	)
	(segment
		(start 67.260724 -151.660352)
		(end 67.517772 -151.9174)
		(width 0.14224)
		(layer "In11.Cu")
		(net "M_M_DQ<27>")
	)
	(segment
		(start 84.136992 -103.086154)
		(end 84.136992 -106.360976)
		(width 0.14224)
		(layer "In11.Cu")
		(net "M_M_DQ<27>")
	)
	(segment
		(start 77.407262 -120.817132)
		(end 77.093826 -120.503188)
		(width 0.14224)
		(layer "In11.Cu")
		(net "M_M_DQ<27>")
	)
	(segment
		(start 86.941152 -94.31909)
		(end 86.905338 -94.31909)
		(width 0.0889)
		(layer "In11.Cu")
		(net "M_M_DQ<27>")
	)
	(segment
		(start 67.517772 -152.2222)
		(end 67.260724 -152.479248)
		(width 0.14224)
		(layer "In11.Cu")
		(net "M_M_DQ<27>")
	)
	(segment
		(start 83.895184 -102.844346)
		(end 84.136992 -103.086154)
		(width 0.0889)
		(layer "In11.Cu")
		(net "M_M_DQ<27>")
	)
	(segment
		(start 68.278502 -146.1262)
		(end 68.374768 -146.222466)
		(width 0.14224)
		(layer "In11.Cu")
		(net "M_M_DQ<27>")
	)
	(segment
		(start 87.435182 -91.451938)
		(end 87.441532 -91.462606)
		(width 0.0889)
		(layer "In11.Cu")
		(net "M_M_DQ<27>")
	)
	(segment
		(start 69.136768 -124.968)
		(end 68.425568 -125.6792)
		(width 0.14224)
		(layer "In11.Cu")
		(net "M_M_DQ<27>")
	)
	(segment
		(start 68.303902 -136.5504)
		(end 68.374768 -136.621266)
		(width 0.14224)
		(layer "In11.Cu")
		(net "M_M_DQ<27>")
	)
	(segment
		(start 68.532502 -145.587212)
		(end 68.278502 -145.841212)
		(width 0.14224)
		(layer "In11.Cu")
		(net "M_M_DQ<27>")
	)
	(segment
		(start 76.519024 -121.07799)
		(end 76.830174 -121.389648)
		(width 0.14224)
		(layer "In11.Cu")
		(net "M_M_DQ<27>")
	)
	(segment
		(start 68.316602 -131.408678)
		(end 68.316602 -131.8514)
		(width 0.14224)
		(layer "In11.Cu")
		(net "M_M_DQ<27>")
	)
	(segment
		(start 86.583012 -97.48012)
		(end 85.936074 -98.600768)
		(width 0.0889)
		(layer "In11.Cu")
		(net "M_M_DQ<27>")
	)
	(segment
		(start 76.519024 -120.859042)
		(end 76.519024 -121.07799)
		(width 0.14224)
		(layer "In11.Cu")
		(net "M_M_DQ<27>")
	)
	(segment
		(start 69.136768 -124.587)
		(end 69.136768 -124.968)
		(width 0.14224)
		(layer "In11.Cu")
		(net "M_M_DQ<27>")
	)
	(segment
		(start 87.430356 -92.433902)
		(end 87.435182 -92.442538)
		(width 0.0889)
		(layer "In11.Cu")
		(net "M_M_DQ<27>")
	)
	(segment
		(start 76.303886 -122.012964)
		(end 75.944222 -121.652792)
		(width 0.14224)
		(layer "In11.Cu")
		(net "M_M_DQ<27>")
	)
	(segment
		(start 68.374768 -146.222466)
		(end 68.374768 -148.2598)
		(width 0.14224)
		(layer "In11.Cu")
		(net "M_M_DQ<27>")
	)
	(segment
		(start 87.430356 -93.424502)
		(end 87.435182 -93.433138)
		(width 0.0889)
		(layer "In11.Cu")
		(net "M_M_DQ<27>")
	)
	(segment
		(start 77.093826 -120.503188)
		(end 76.874878 -120.503188)
		(width 0.14224)
		(layer "In11.Cu")
		(net "M_M_DQ<27>")
	)
	(segment
		(start 67.498722 -150.391368)
		(end 67.543172 -150.435818)
		(width 0.14224)
		(layer "In11.Cu")
		(net "M_M_DQ<27>")
	)
	(segment
		(start 87.435182 -87.489538)
		(end 87.441532 -87.500206)
		(width 0.0889)
		(layer "In11.Cu")
		(net "M_M_DQ<27>")
	)
	(segment
		(start 68.39204 -139.584938)
		(end 68.39204 -141.021562)
		(width 0.1016)
		(layer "In11.Cu")
		(net "M_M_DQ<27>")
	)
	(segment
		(start 74.57567 -122.802396)
		(end 73.273666 -124.1044)
		(width 0.14224)
		(layer "In11.Cu")
		(net "M_M_DQ<27>")
	)
	(segment
		(start 75.725274 -121.652792)
		(end 75.36942 -122.008646)
		(width 0.14224)
		(layer "In11.Cu")
		(net "M_M_DQ<27>")
	)
	(segment
		(start 78.818232 -118.559834)
		(end 78.818232 -118.772686)
		(width 0.14224)
		(layer "In11.Cu")
		(net "M_M_DQ<27>")
	)
	(segment
		(start 87.435182 -90.461338)
		(end 87.441532 -90.472006)
		(width 0.0889)
		(layer "In11.Cu")
		(net "M_M_DQ<27>")
	)
	(segment
		(start 86.576662 -95.509588)
		(end 86.571836 -95.518224)
		(width 0.0889)
		(layer "In11.Cu")
		(net "M_M_DQ<27>")
	)
	(segment
		(start 78.818232 -118.772686)
		(end 79.01813 -118.972584)
		(width 0.14224)
		(layer "In11.Cu")
		(net "M_M_DQ<27>")
	)
	(segment
		(start 67.260724 -152.479248)
		(end 67.260724 -152.752552)
		(width 0.14224)
		(layer "In11.Cu")
		(net "M_M_DQ<27>")
	)
	(segment
		(start 87.430356 -88.471502)
		(end 87.435182 -88.480138)
		(width 0.0889)
		(layer "In11.Cu")
		(net "M_M_DQ<27>")
	)
	(segment
		(start 67.517772 -151.9174)
		(end 67.517772 -152.2222)
		(width 0.14224)
		(layer "In11.Cu")
		(net "M_M_DQ<27>")
	)
	(segment
		(start 87.435182 -92.442538)
		(end 87.441532 -92.453206)
		(width 0.0889)
		(layer "In11.Cu")
		(net "M_M_DQ<27>")
	)
	(segment
		(start 68.303902 -136.214612)
		(end 68.303902 -136.5504)
		(width 0.14224)
		(layer "In11.Cu")
		(net "M_M_DQ<27>")
	)
	(segment
		(start 87.435182 -89.470738)
		(end 87.441532 -89.481406)
		(width 0.0889)
		(layer "In11.Cu")
		(net "M_M_DQ<27>")
	)
	(segment
		(start 76.878942 -121.438416)
		(end 76.878942 -121.65711)
		(width 0.14224)
		(layer "In11.Cu")
		(net "M_M_DQ<27>")
	)
	(segment
		(start 68.278502 -145.841212)
		(end 68.278502 -146.1262)
		(width 0.14224)
		(layer "In11.Cu")
		(net "M_M_DQ<27>")
	)
	(segment
		(start 68.374768 -134.0866)
		(end 68.316602 -134.144766)
		(width 0.14224)
		(layer "In11.Cu")
		(net "M_M_DQ<27>")
	)
	(arc
		(start 87.441532 -89.481406)
		(mid 87.51433 -89.772169)
		(end 87.435182 -90.061288)
		(width 0.0889)
		(layer "In11.Cu")
		(net "M_M_DQ<27>")
	)
	(arc
		(start 87.435182 -88.080088)
		(mid 87.381712 -88.275151)
		(end 87.430356 -88.471502)
		(width 0.0889)
		(layer "In11.Cu")
		(net "M_M_DQ<27>")
	)
	(arc
		(start 87.435182 -93.033088)
		(mid 87.381712 -93.228151)
		(end 87.430356 -93.424502)
		(width 0.0889)
		(layer "In11.Cu")
		(net "M_M_DQ<27>")
	)
	(arc
		(start 87.435182 -92.042488)
		(mid 87.381712 -92.237551)
		(end 87.430356 -92.433902)
		(width 0.0889)
		(layer "In11.Cu")
		(net "M_M_DQ<27>")
	)
	(arc
		(start 86.905338 -94.31909)
		(mid 86.572369 -94.526638)
		(end 86.576662 -94.919038)
		(width 0.0889)
		(layer "In11.Cu")
		(net "M_M_DQ<27>")
	)
	(arc
		(start 86.576662 -94.919038)
		(mid 86.655884 -95.208156)
		(end 86.583012 -95.49892)
		(width 0.0889)
		(layer "In11.Cu")
		(net "M_M_DQ<27>")
	)
	(arc
		(start 87.441532 -87.500206)
		(mid 87.51433 -87.790969)
		(end 87.435182 -88.080088)
		(width 0.0889)
		(layer "In11.Cu")
		(net "M_M_DQ<27>")
	)
	(arc
		(start 86.571836 -95.518224)
		(mid 86.523081 -95.714576)
		(end 86.576662 -95.909638)
		(width 0.0889)
		(layer "In11.Cu")
		(net "M_M_DQ<27>")
	)
	(arc
		(start 87.441532 -88.490806)
		(mid 87.51433 -88.781569)
		(end 87.435182 -89.070688)
		(width 0.0889)
		(layer "In11.Cu")
		(net "M_M_DQ<27>")
	)
	(arc
		(start 87.441532 -91.462606)
		(mid 87.51433 -91.753369)
		(end 87.435182 -92.042488)
		(width 0.0889)
		(layer "In11.Cu")
		(net "M_M_DQ<27>")
	)
	(arc
		(start 87.435182 -89.070688)
		(mid 87.381712 -89.265751)
		(end 87.430356 -89.462102)
		(width 0.0889)
		(layer "In11.Cu")
		(net "M_M_DQ<27>")
	)
	(arc
		(start 87.441532 -90.472006)
		(mid 87.51433 -90.762769)
		(end 87.435182 -91.051888)
		(width 0.0889)
		(layer "In11.Cu")
		(net "M_M_DQ<27>")
	)
	(arc
		(start 87.435182 -91.051888)
		(mid 87.381712 -91.246951)
		(end 87.430356 -91.443302)
		(width 0.0889)
		(layer "In11.Cu")
		(net "M_M_DQ<27>")
	)
	(arc
		(start 86.576662 -96.900238)
		(mid 86.655884 -97.189356)
		(end 86.583012 -97.48012)
		(width 0.0889)
		(layer "In11.Cu")
		(net "M_M_DQ<27>")
	)
	(arc
		(start 86.576662 -95.909638)
		(mid 86.655884 -96.198756)
		(end 86.583012 -96.48952)
		(width 0.0889)
		(layer "In11.Cu")
		(net "M_M_DQ<27>")
	)
	(arc
		(start 87.435182 -93.433138)
		(mid 87.439511 -94.01631)
		(end 86.941152 -94.31909)
		(width 0.0889)
		(layer "In11.Cu")
		(net "M_M_DQ<27>")
	)
	(arc
		(start 86.571836 -96.508824)
		(mid 86.523081 -96.705176)
		(end 86.576662 -96.900238)
		(width 0.0889)
		(layer "In11.Cu")
		(net "M_M_DQ<27>")
	)
	(arc
		(start 87.435182 -90.061288)
		(mid 87.381712 -90.256351)
		(end 87.430356 -90.452702)
		(width 0.0889)
		(layer "In11.Cu")
		(net "M_M_DQ<27>")
	)
	(arc
		(start 87.441532 -92.453206)
		(mid 87.51433 -92.743969)
		(end 87.435182 -93.033088)
		(width 0.0889)
		(layer "In11.Cu")
		(net "M_M_DQ<27>")
	)
	(segment
		(start 68.08089 -155.52674)
		(end 67.949318 -155.395168)
		(width 0.1651)
		(layer "F.Cu")
		(net "M_M_DQ<26>")
	)
	(segment
		(start 67.949318 -156.87294)
		(end 67.949318 -155.881832)
		(width 0.1651)
		(layer "F.Cu")
		(net "M_M_DQ<26>")
	)
	(segment
		(start 68.08089 -155.75026)
		(end 68.08089 -155.52674)
		(width 0.1651)
		(layer "F.Cu")
		(net "M_M_DQ<26>")
	)
	(segment
		(start 67.949572 -156.87294)
		(end 67.949318 -156.87294)
		(width 0.1651)
		(layer "F.Cu")
		(net "M_M_DQ<26>")
	)
	(segment
		(start 67.949318 -155.395168)
		(end 67.949318 -155.1178)
		(width 0.1651)
		(layer "F.Cu")
		(net "M_M_DQ<26>")
	)
	(segment
		(start 87.494872 -85.803486)
		(end 86.923372 -85.803486)
		(width 0.1651)
		(layer "F.Cu")
		(net "M_M_DQ<26>")
	)
	(segment
		(start 67.949318 -155.881832)
		(end 68.08089 -155.75026)
		(width 0.1651)
		(layer "F.Cu")
		(net "M_M_DQ<26>")
	)
	(via
		(at 67.949318 -155.1178)
		(size 0.508)
		(drill 0.254)
		(layers "F.Cu" "B.Cu")
		(net "M_M_DQ<26>")
	)
	(via
		(at 86.923372 -85.803486)
		(size 0.508)
		(drill 0.254)
		(layers "F.Cu" "B.Cu")
		(net "M_M_DQ<26>")
	)
	(via
		(at 67.099434 -150.814278)
		(size 0.508)
		(drill 0.254)
		(layers "F.Cu" "B.Cu")
		(net "M_M_DQ<26>")
	)
	(segment
		(start 67.099434 -152.078436)
		(end 67.099434 -150.814278)
		(width 0.1651)
		(layer "B.Cu")
		(net "M_M_DQ<26>")
	)
	(segment
		(start 87.263732 -88.56472)
		(end 87.270082 -88.575388)
		(width 0.0889)
		(layer "In11.Cu")
		(net "M_M_DQ<26>")
	)
	(segment
		(start 67.668902 -144.093438)
		(end 67.389502 -144.372838)
		(width 0.14224)
		(layer "In11.Cu")
		(net "M_M_DQ<26>")
	)
	(segment
		(start 83.501992 -103.047546)
		(end 83.501992 -106.081576)
		(width 0.14224)
		(layer "In11.Cu")
		(net "M_M_DQ<26>")
	)
	(segment
		(start 87.270082 -92.537788)
		(end 87.274908 -92.546424)
		(width 0.0889)
		(layer "In11.Cu")
		(net "M_M_DQ<26>")
	)
	(segment
		(start 86.941406 -94.128336)
		(end 86.901782 -94.128336)
		(width 0.0889)
		(layer "In11.Cu")
		(net "M_M_DQ<26>")
	)
	(segment
		(start 86.576662 -86.994238)
		(end 86.741254 -87.27948)
		(width 0.0889)
		(layer "In11.Cu")
		(net "M_M_DQ<26>")
	)
	(segment
		(start 83.705192 -100.562918)
		(end 83.705192 -102.844346)
		(width 0.0889)
		(layer "In11.Cu")
		(net "M_M_DQ<26>")
	)
	(segment
		(start 67.618102 -146.177)
		(end 67.511168 -146.283934)
		(width 0.14224)
		(layer "In11.Cu")
		(net "M_M_DQ<26>")
	)
	(segment
		(start 87.270082 -90.556588)
		(end 87.274908 -90.565224)
		(width 0.0889)
		(layer "In11.Cu")
		(net "M_M_DQ<26>")
	)
	(segment
		(start 67.681602 -131.8514)
		(end 67.536568 -131.996434)
		(width 0.14224)
		(layer "In11.Cu")
		(net "M_M_DQ<26>")
	)
	(segment
		(start 67.668902 -143.820134)
		(end 67.668902 -144.093438)
		(width 0.14224)
		(layer "In11.Cu")
		(net "M_M_DQ<26>")
	)
	(segment
		(start 86.923372 -85.803486)
		(end 86.593934 -86.56447)
		(width 0.0889)
		(layer "In11.Cu")
		(net "M_M_DQ<26>")
	)
	(segment
		(start 66.666364 -153.834846)
		(end 67.949318 -155.1178)
		(width 0.14224)
		(layer "In11.Cu")
		(net "M_M_DQ<26>")
	)
	(segment
		(start 67.536568 -124.409454)
		(end 67.536568 -125.7554)
		(width 0.14224)
		(layer "In11.Cu")
		(net "M_M_DQ<26>")
	)
	(segment
		(start 67.592702 -136.251188)
		(end 67.592702 -136.6012)
		(width 0.14224)
		(layer "In11.Cu")
		(net "M_M_DQ<26>")
	)
	(segment
		(start 67.511168 -136.682734)
		(end 67.511168 -138.7602)
		(width 0.14224)
		(layer "In11.Cu")
		(net "M_M_DQ<26>")
	)
	(segment
		(start 67.536568 -141.584934)
		(end 67.536568 -143.6878)
		(width 0.14224)
		(layer "In11.Cu")
		(net "M_M_DQ<26>")
	)
	(segment
		(start 67.440302 -134.712964)
		(end 67.440302 -136.098788)
		(width 0.14224)
		(layer "In11.Cu")
		(net "M_M_DQ<26>")
	)
	(segment
		(start 83.705192 -102.844346)
		(end 83.501992 -103.047546)
		(width 0.0889)
		(layer "In11.Cu")
		(net "M_M_DQ<26>")
	)
	(segment
		(start 87.263732 -92.52712)
		(end 87.270082 -92.537788)
		(width 0.0889)
		(layer "In11.Cu")
		(net "M_M_DQ<26>")
	)
	(segment
		(start 85.783928 -98.484182)
		(end 83.705192 -100.562918)
		(width 0.0889)
		(layer "In11.Cu")
		(net "M_M_DQ<26>")
	)
	(segment
		(start 86.416388 -95.405702)
		(end 86.411562 -95.414338)
		(width 0.0889)
		(layer "In11.Cu")
		(net "M_M_DQ<26>")
	)
	(segment
		(start 67.618102 -145.806668)
		(end 67.618102 -146.177)
		(width 0.14224)
		(layer "In11.Cu")
		(net "M_M_DQ<26>")
	)
	(segment
		(start 67.618102 -148.544534)
		(end 67.618102 -148.972778)
		(width 0.14224)
		(layer "In11.Cu")
		(net "M_M_DQ<26>")
	)
	(segment
		(start 67.389502 -145.578068)
		(end 67.618102 -145.806668)
		(width 0.14224)
		(layer "In11.Cu")
		(net "M_M_DQ<26>")
	)
	(segment
		(start 67.536568 -134.0612)
		(end 67.670426 -134.195058)
		(width 0.14224)
		(layer "In11.Cu")
		(net "M_M_DQ<26>")
	)
	(segment
		(start 67.536568 -125.7554)
		(end 67.592702 -125.811534)
		(width 0.14224)
		(layer "In11.Cu")
		(net "M_M_DQ<26>")
	)
	(segment
		(start 79.550768 -110.0328)
		(end 79.550768 -117.148356)
		(width 0.14224)
		(layer "In11.Cu")
		(net "M_M_DQ<26>")
	)
	(segment
		(start 67.099434 -150.814278)
		(end 66.666364 -151.247348)
		(width 0.14224)
		(layer "In11.Cu")
		(net "M_M_DQ<26>")
	)
	(segment
		(start 87.263732 -91.53652)
		(end 87.270082 -91.547188)
		(width 0.0889)
		(layer "In11.Cu")
		(net "M_M_DQ<26>")
	)
	(segment
		(start 87.270082 -91.547188)
		(end 87.274908 -91.555824)
		(width 0.0889)
		(layer "In11.Cu")
		(net "M_M_DQ<26>")
	)
	(segment
		(start 86.593934 -86.56447)
		(end 86.571836 -86.602824)
		(width 0.0889)
		(layer "In11.Cu")
		(net "M_M_DQ<26>")
	)
	(segment
		(start 86.411562 -96.404938)
		(end 86.405212 -96.415606)
		(width 0.0889)
		(layer "In11.Cu")
		(net "M_M_DQ<26>")
	)
	(segment
		(start 67.465702 -139.562078)
		(end 67.465702 -140.933678)
		(width 0.14224)
		(layer "In11.Cu")
		(net "M_M_DQ<26>")
	)
	(segment
		(start 67.511168 -146.283934)
		(end 67.511168 -148.4376)
		(width 0.14224)
		(layer "In11.Cu")
		(net "M_M_DQ<26>")
	)
	(segment
		(start 86.923372 -87.384636)
		(end 86.934548 -87.384636)
		(width 0.0889)
		(layer "In11.Cu")
		(net "M_M_DQ<26>")
	)
	(segment
		(start 87.263732 -89.55532)
		(end 87.270082 -89.565988)
		(width 0.0889)
		(layer "In11.Cu")
		(net "M_M_DQ<26>")
	)
	(segment
		(start 67.592702 -129.833878)
		(end 67.465702 -129.960878)
		(width 0.14224)
		(layer "In11.Cu")
		(net "M_M_DQ<26>")
	)
	(segment
		(start 67.389502 -144.372838)
		(end 67.389502 -145.578068)
		(width 0.14224)
		(layer "In11.Cu")
		(net "M_M_DQ<26>")
	)
	(segment
		(start 73.255124 -123.444)
		(end 68.502022 -123.444)
		(width 0.14224)
		(layer "In11.Cu")
		(net "M_M_DQ<26>")
	)
	(segment
		(start 67.592702 -125.811534)
		(end 67.592702 -129.833878)
		(width 0.14224)
		(layer "In11.Cu")
		(net "M_M_DQ<26>")
	)
	(segment
		(start 86.416388 -97.386902)
		(end 85.783928 -98.484182)
		(width 0.0889)
		(layer "In11.Cu")
		(net "M_M_DQ<26>")
	)
	(segment
		(start 79.550768 -117.148356)
		(end 73.255124 -123.444)
		(width 0.14224)
		(layer "In11.Cu")
		(net "M_M_DQ<26>")
	)
	(segment
		(start 67.681602 -131.548378)
		(end 67.681602 -131.8514)
		(width 0.14224)
		(layer "In11.Cu")
		(net "M_M_DQ<26>")
	)
	(segment
		(start 68.502022 -123.444)
		(end 67.536568 -124.409454)
		(width 0.14224)
		(layer "In11.Cu")
		(net "M_M_DQ<26>")
	)
	(segment
		(start 67.592702 -138.841734)
		(end 67.592702 -139.435078)
		(width 0.14224)
		(layer "In11.Cu")
		(net "M_M_DQ<26>")
	)
	(segment
		(start 83.501992 -106.081576)
		(end 79.550768 -110.0328)
		(width 0.14224)
		(layer "In11.Cu")
		(net "M_M_DQ<26>")
	)
	(segment
		(start 67.511168 -138.7602)
		(end 67.592702 -138.841734)
		(width 0.14224)
		(layer "In11.Cu")
		(net "M_M_DQ<26>")
	)
	(segment
		(start 67.465702 -131.332478)
		(end 67.681602 -131.548378)
		(width 0.14224)
		(layer "In11.Cu")
		(net "M_M_DQ<26>")
	)
	(segment
		(start 67.592702 -139.435078)
		(end 67.465702 -139.562078)
		(width 0.14224)
		(layer "In11.Cu")
		(net "M_M_DQ<26>")
	)
	(segment
		(start 67.592702 -136.6012)
		(end 67.511168 -136.682734)
		(width 0.14224)
		(layer "In11.Cu")
		(net "M_M_DQ<26>")
	)
	(segment
		(start 87.270082 -89.565988)
		(end 87.274908 -89.574624)
		(width 0.0889)
		(layer "In11.Cu")
		(net "M_M_DQ<26>")
	)
	(segment
		(start 67.536568 -131.996434)
		(end 67.536568 -134.0612)
		(width 0.14224)
		(layer "In11.Cu")
		(net "M_M_DQ<26>")
	)
	(segment
		(start 66.666364 -151.247348)
		(end 66.666364 -153.834846)
		(width 0.14224)
		(layer "In11.Cu")
		(net "M_M_DQ<26>")
	)
	(segment
		(start 67.618102 -148.972778)
		(end 66.754502 -149.836378)
		(width 0.14224)
		(layer "In11.Cu")
		(net "M_M_DQ<26>")
	)
	(segment
		(start 67.670426 -134.48284)
		(end 67.440302 -134.712964)
		(width 0.14224)
		(layer "In11.Cu")
		(net "M_M_DQ<26>")
	)
	(segment
		(start 67.465702 -140.933678)
		(end 67.668902 -141.136878)
		(width 0.14224)
		(layer "In11.Cu")
		(net "M_M_DQ<26>")
	)
	(segment
		(start 87.263732 -90.54592)
		(end 87.270082 -90.556588)
		(width 0.0889)
		(layer "In11.Cu")
		(net "M_M_DQ<26>")
	)
	(segment
		(start 67.668902 -141.4526)
		(end 67.536568 -141.584934)
		(width 0.14224)
		(layer "In11.Cu")
		(net "M_M_DQ<26>")
	)
	(segment
		(start 67.511168 -148.4376)
		(end 67.618102 -148.544534)
		(width 0.14224)
		(layer "In11.Cu")
		(net "M_M_DQ<26>")
	)
	(segment
		(start 86.411562 -95.414338)
		(end 86.405212 -95.425006)
		(width 0.0889)
		(layer "In11.Cu")
		(net "M_M_DQ<26>")
	)
	(segment
		(start 67.465702 -129.960878)
		(end 67.465702 -131.332478)
		(width 0.14224)
		(layer "In11.Cu")
		(net "M_M_DQ<26>")
	)
	(segment
		(start 66.754502 -150.469346)
		(end 67.099434 -150.814278)
		(width 0.14224)
		(layer "In11.Cu")
		(net "M_M_DQ<26>")
	)
	(segment
		(start 67.670426 -134.195058)
		(end 67.670426 -134.48284)
		(width 0.14224)
		(layer "In11.Cu")
		(net "M_M_DQ<26>")
	)
	(segment
		(start 67.440302 -136.098788)
		(end 67.592702 -136.251188)
		(width 0.14224)
		(layer "In11.Cu")
		(net "M_M_DQ<26>")
	)
	(segment
		(start 67.668902 -141.136878)
		(end 67.668902 -141.4526)
		(width 0.14224)
		(layer "In11.Cu")
		(net "M_M_DQ<26>")
	)
	(segment
		(start 67.536568 -143.6878)
		(end 67.668902 -143.820134)
		(width 0.14224)
		(layer "In11.Cu")
		(net "M_M_DQ<26>")
	)
	(segment
		(start 66.754502 -149.836378)
		(end 66.754502 -150.469346)
		(width 0.14224)
		(layer "In11.Cu")
		(net "M_M_DQ<26>")
	)
	(segment
		(start 87.270082 -88.575388)
		(end 87.274908 -88.584024)
		(width 0.0889)
		(layer "In11.Cu")
		(net "M_M_DQ<26>")
	)
	(segment
		(start 86.416388 -96.396302)
		(end 86.411562 -96.404938)
		(width 0.0889)
		(layer "In11.Cu")
		(net "M_M_DQ<26>")
	)
	(arc
		(start 86.411562 -95.014288)
		(mid 86.465032 -95.209351)
		(end 86.416388 -95.405702)
		(width 0.0889)
		(layer "In11.Cu")
		(net "M_M_DQ<26>")
	)
	(arc
		(start 87.270082 -92.937838)
		(mid 87.190951 -93.23324)
		(end 87.270082 -93.528642)
		(width 0.0889)
		(layer "In11.Cu")
		(net "M_M_DQ<26>")
	)
	(arc
		(start 86.411562 -96.995488)
		(mid 86.465032 -97.190551)
		(end 86.416388 -97.386902)
		(width 0.0889)
		(layer "In11.Cu")
		(net "M_M_DQ<26>")
	)
	(arc
		(start 87.270082 -90.956638)
		(mid 87.19086 -91.245756)
		(end 87.263732 -91.53652)
		(width 0.0889)
		(layer "In11.Cu")
		(net "M_M_DQ<26>")
	)
	(arc
		(start 87.274908 -88.584024)
		(mid 87.323663 -88.780376)
		(end 87.270082 -88.975438)
		(width 0.0889)
		(layer "In11.Cu")
		(net "M_M_DQ<26>")
	)
	(arc
		(start 87.274908 -90.565224)
		(mid 87.323663 -90.761576)
		(end 87.270082 -90.956638)
		(width 0.0889)
		(layer "In11.Cu")
		(net "M_M_DQ<26>")
	)
	(arc
		(start 87.270082 -93.528642)
		(mid 87.274327 -93.920887)
		(end 86.941406 -94.128336)
		(width 0.0889)
		(layer "In11.Cu")
		(net "M_M_DQ<26>")
	)
	(arc
		(start 87.274908 -92.546424)
		(mid 87.323663 -92.742776)
		(end 87.270082 -92.937838)
		(width 0.0889)
		(layer "In11.Cu")
		(net "M_M_DQ<26>")
	)
	(arc
		(start 86.411562 -96.004888)
		(mid 86.465032 -96.199951)
		(end 86.416388 -96.396302)
		(width 0.0889)
		(layer "In11.Cu")
		(net "M_M_DQ<26>")
	)
	(arc
		(start 87.274908 -91.555824)
		(mid 87.323663 -91.752176)
		(end 87.270082 -91.947238)
		(width 0.0889)
		(layer "In11.Cu")
		(net "M_M_DQ<26>")
	)
	(arc
		(start 86.405212 -95.425006)
		(mid 86.332414 -95.715769)
		(end 86.411562 -96.004888)
		(width 0.0889)
		(layer "In11.Cu")
		(net "M_M_DQ<26>")
	)
	(arc
		(start 87.270082 -89.966038)
		(mid 87.19086 -90.255156)
		(end 87.263732 -90.54592)
		(width 0.0889)
		(layer "In11.Cu")
		(net "M_M_DQ<26>")
	)
	(arc
		(start 86.901782 -94.128336)
		(mid 86.406305 -94.432779)
		(end 86.411562 -95.014288)
		(width 0.0889)
		(layer "In11.Cu")
		(net "M_M_DQ<26>")
	)
	(arc
		(start 87.274908 -89.574624)
		(mid 87.323663 -89.770976)
		(end 87.270082 -89.966038)
		(width 0.0889)
		(layer "In11.Cu")
		(net "M_M_DQ<26>")
	)
	(arc
		(start 86.405212 -96.415606)
		(mid 86.332414 -96.706369)
		(end 86.411562 -96.995488)
		(width 0.0889)
		(layer "In11.Cu")
		(net "M_M_DQ<26>")
	)
	(arc
		(start 86.934548 -87.384636)
		(mid 87.272717 -87.589434)
		(end 87.270082 -87.984838)
		(width 0.0889)
		(layer "In11.Cu")
		(net "M_M_DQ<26>")
	)
	(arc
		(start 87.270082 -87.984838)
		(mid 87.19086 -88.273956)
		(end 87.263732 -88.56472)
		(width 0.0889)
		(layer "In11.Cu")
		(net "M_M_DQ<26>")
	)
	(arc
		(start 87.270082 -91.947238)
		(mid 87.19086 -92.236356)
		(end 87.263732 -92.52712)
		(width 0.0889)
		(layer "In11.Cu")
		(net "M_M_DQ<26>")
	)
	(arc
		(start 86.741254 -87.27948)
		(mid 86.818227 -87.356449)
		(end 86.923372 -87.384636)
		(width 0.0889)
		(layer "In11.Cu")
		(net "M_M_DQ<26>")
	)
	(arc
		(start 87.270082 -88.975438)
		(mid 87.19086 -89.264556)
		(end 87.263732 -89.55532)
		(width 0.0889)
		(layer "In11.Cu")
		(net "M_M_DQ<26>")
	)
	(arc
		(start 86.571836 -86.602824)
		(mid 86.523081 -86.799176)
		(end 86.576662 -86.994238)
		(width 0.0889)
		(layer "In11.Cu")
		(net "M_M_DQ<26>")
	)
	(segment
		(start 61.149484 -152.273)
		(end 61.149484 -153.542746)
		(width 0.1651)
		(layer "F.Cu")
		(net "M_M_DQ<25>")
	)
	(segment
		(start 84.919312 -87.28964)
		(end 84.347812 -87.28964)
		(width 0.1651)
		(layer "F.Cu")
		(net "M_M_DQ<25>")
	)
	(via
		(at 61.821568 -149.533356)
		(size 0.508)
		(drill 0.254)
		(layers "F.Cu" "B.Cu")
		(net "M_M_DQ<25>")
	)
	(via
		(at 84.347812 -87.28964)
		(size 0.508)
		(drill 0.254)
		(layers "F.Cu" "B.Cu")
		(net "M_M_DQ<25>")
	)
	(via
		(at 61.149484 -153.542746)
		(size 0.508)
		(drill 0.254)
		(layers "F.Cu" "B.Cu")
		(net "M_M_DQ<25>")
	)
	(segment
		(start 61.821568 -149.030182)
		(end 61.821568 -149.533356)
		(width 0.1651)
		(layer "B.Cu")
		(net "M_M_DQ<25>")
	)
	(segment
		(start 61.999368 -148.852382)
		(end 61.821568 -149.030182)
		(width 0.1651)
		(layer "B.Cu")
		(net "M_M_DQ<25>")
	)
	(segment
		(start 61.999368 -147.478496)
		(end 61.999368 -148.852382)
		(width 0.1651)
		(layer "B.Cu")
		(net "M_M_DQ<25>")
	)
	(segment
		(start 62.309502 -131.699)
		(end 62.431168 -131.820666)
		(width 0.14224)
		(layer "In11.Cu")
		(net "M_M_DQ<25>")
	)
	(segment
		(start 67.20078 -118.893082)
		(end 67.04584 -119.048022)
		(width 0.14224)
		(layer "In11.Cu")
		(net "M_M_DQ<25>")
	)
	(segment
		(start 73.76795 -115.50269)
		(end 73.76795 -115.790218)
		(width 0.14224)
		(layer "In11.Cu")
		(net "M_M_DQ<25>")
	)
	(segment
		(start 72.618346 -116.652294)
		(end 72.618346 -116.939822)
		(width 0.14224)
		(layer "In11.Cu")
		(net "M_M_DQ<25>")
	)
	(segment
		(start 68.82638 -118.893082)
		(end 68.67144 -119.048022)
		(width 0.14224)
		(layer "In11.Cu")
		(net "M_M_DQ<25>")
	)
	(segment
		(start 71.468742 -117.801898)
		(end 71.468742 -118.089426)
		(width 0.14224)
		(layer "In11.Cu")
		(net "M_M_DQ<25>")
	)
	(segment
		(start 70.57644 -118.346728)
		(end 70.289166 -118.634002)
		(width 0.14224)
		(layer "In11.Cu")
		(net "M_M_DQ<25>")
	)
	(segment
		(start 79.654654 -98.677222)
		(end 79.654654 -99.681284)
		(width 0.0889)
		(layer "In11.Cu")
		(net "M_M_DQ<25>")
	)
	(segment
		(start 62.431168 -146.329146)
		(end 62.431168 -148.3614)
		(width 0.14224)
		(layer "In11.Cu")
		(net "M_M_DQ<25>")
	)
	(segment
		(start 62.431168 -131.820666)
		(end 62.431168 -134.2136)
		(width 0.14224)
		(layer "In11.Cu")
		(net "M_M_DQ<25>")
	)
	(segment
		(start 66.672968 -119.507)
		(end 62.309502 -123.870466)
		(width 0.14224)
		(layer "In11.Cu")
		(net "M_M_DQ<25>")
	)
	(segment
		(start 70.863968 -118.346728)
		(end 70.57644 -118.346728)
		(width 0.14224)
		(layer "In11.Cu")
		(net "M_M_DQ<25>")
	)
	(segment
		(start 61.310774 -152.538176)
		(end 61.310774 -152.846024)
		(width 0.14224)
		(layer "In11.Cu")
		(net "M_M_DQ<25>")
	)
	(segment
		(start 68.01358 -119.666512)
		(end 67.85864 -119.511572)
		(width 0.14224)
		(layer "In11.Cu")
		(net "M_M_DQ<25>")
	)
	(segment
		(start 71.43877 -117.771926)
		(end 71.468742 -117.801898)
		(width 0.14224)
		(layer "In11.Cu")
		(net "M_M_DQ<25>")
	)
	(segment
		(start 72.875648 -116.04752)
		(end 72.588374 -116.334794)
		(width 0.14224)
		(layer "In11.Cu")
		(net "M_M_DQ<25>")
	)
	(segment
		(start 67.7037 -118.893082)
		(end 67.20078 -118.893082)
		(width 0.14224)
		(layer "In11.Cu")
		(net "M_M_DQ<25>")
	)
	(segment
		(start 62.431168 -134.2136)
		(end 62.309502 -134.335266)
		(width 0.14224)
		(layer "In11.Cu")
		(net "M_M_DQ<25>")
	)
	(segment
		(start 62.309502 -143.784066)
		(end 62.309502 -146.20748)
		(width 0.14224)
		(layer "In11.Cu")
		(net "M_M_DQ<25>")
	)
	(segment
		(start 72.043544 -117.227096)
		(end 72.013572 -117.197124)
		(width 0.14224)
		(layer "In11.Cu")
		(net "M_M_DQ<25>")
	)
	(segment
		(start 79.043784 -102.475538)
		(end 79.29245 -102.724204)
		(width 0.0889)
		(layer "In11.Cu")
		(net "M_M_DQ<25>")
	)
	(segment
		(start 82.648552 -95.80499)
		(end 82.615786 -95.80499)
		(width 0.0889)
		(layer "In11.Cu")
		(net "M_M_DQ<25>")
	)
	(segment
		(start 75.588368 -108.4834)
		(end 75.588368 -113.9698)
		(width 0.14224)
		(layer "In11.Cu")
		(net "M_M_DQ<25>")
	)
	(segment
		(start 70.89394 -118.3767)
		(end 70.863968 -118.346728)
		(width 0.14224)
		(layer "In11.Cu")
		(net "M_M_DQ<25>")
	)
	(segment
		(start 73.737978 -115.472718)
		(end 73.76795 -115.50269)
		(width 0.14224)
		(layer "In11.Cu")
		(net "M_M_DQ<25>")
	)
	(segment
		(start 71.43877 -117.484398)
		(end 71.43877 -117.771926)
		(width 0.14224)
		(layer "In11.Cu")
		(net "M_M_DQ<25>")
	)
	(segment
		(start 67.85864 -119.511572)
		(end 67.85864 -119.048022)
		(width 0.14224)
		(layer "In11.Cu")
		(net "M_M_DQ<25>")
	)
	(segment
		(start 69.48424 -119.35206)
		(end 69.48424 -119.048022)
		(width 0.14224)
		(layer "In11.Cu")
		(net "M_M_DQ<25>")
	)
	(segment
		(start 79.29245 -102.724204)
		(end 79.29245 -104.779318)
		(width 0.14224)
		(layer "In11.Cu")
		(net "M_M_DQ<25>")
	)
	(segment
		(start 71.726044 -117.197124)
		(end 71.43877 -117.484398)
		(width 0.14224)
		(layer "In11.Cu")
		(net "M_M_DQ<25>")
	)
	(segment
		(start 72.588374 -116.334794)
		(end 72.588374 -116.622322)
		(width 0.14224)
		(layer "In11.Cu")
		(net "M_M_DQ<25>")
	)
	(segment
		(start 67.04584 -119.35206)
		(end 66.8909 -119.507)
		(width 0.14224)
		(layer "In11.Cu")
		(net "M_M_DQ<25>")
	)
	(segment
		(start 66.8909 -119.507)
		(end 66.672968 -119.507)
		(width 0.14224)
		(layer "In11.Cu")
		(net "M_M_DQ<25>")
	)
	(segment
		(start 79.654654 -99.681284)
		(end 79.043784 -100.292154)
		(width 0.0889)
		(layer "In11.Cu")
		(net "M_M_DQ<25>")
	)
	(segment
		(start 73.480676 -116.077492)
		(end 73.193148 -116.077492)
		(width 0.14224)
		(layer "In11.Cu")
		(net "M_M_DQ<25>")
	)
	(segment
		(start 74.025252 -114.897916)
		(end 73.737978 -115.18519)
		(width 0.14224)
		(layer "In11.Cu")
		(net "M_M_DQ<25>")
	)
	(segment
		(start 79.29245 -104.779318)
		(end 75.588368 -108.4834)
		(width 0.14224)
		(layer "In11.Cu")
		(net "M_M_DQ<25>")
	)
	(segment
		(start 73.76795 -115.790218)
		(end 73.480676 -116.077492)
		(width 0.14224)
		(layer "In11.Cu")
		(net "M_M_DQ<25>")
	)
	(segment
		(start 82.279236 -96.396302)
		(end 82.284062 -96.404938)
		(width 0.0889)
		(layer "In11.Cu")
		(net "M_M_DQ<25>")
	)
	(segment
		(start 70.051168 -119.507)
		(end 69.63918 -119.507)
		(width 0.14224)
		(layer "In11.Cu")
		(net "M_M_DQ<25>")
	)
	(segment
		(start 69.3293 -118.893082)
		(end 68.82638 -118.893082)
		(width 0.14224)
		(layer "In11.Cu")
		(net "M_M_DQ<25>")
	)
	(segment
		(start 62.309502 -148.483066)
		(end 62.309502 -148.956522)
		(width 0.14224)
		(layer "In11.Cu")
		(net "M_M_DQ<25>")
	)
	(segment
		(start 61.310774 -152.846024)
		(end 61.55055 -153.0858)
		(width 0.14224)
		(layer "In11.Cu")
		(net "M_M_DQ<25>")
	)
	(segment
		(start 67.04584 -119.048022)
		(end 67.04584 -119.35206)
		(width 0.14224)
		(layer "In11.Cu")
		(net "M_M_DQ<25>")
	)
	(segment
		(start 70.289166 -118.634002)
		(end 70.289166 -118.92153)
		(width 0.14224)
		(layer "In11.Cu")
		(net "M_M_DQ<25>")
	)
	(segment
		(start 82.284062 -96.404938)
		(end 82.290412 -96.415606)
		(width 0.0889)
		(layer "In11.Cu")
		(net "M_M_DQ<25>")
	)
	(segment
		(start 61.55055 -153.3906)
		(end 61.398404 -153.542746)
		(width 0.14224)
		(layer "In11.Cu")
		(net "M_M_DQ<25>")
	)
	(segment
		(start 61.310774 -151.316944)
		(end 61.310774 -151.677624)
		(width 0.14224)
		(layer "In11.Cu")
		(net "M_M_DQ<25>")
	)
	(segment
		(start 80.931512 -97.78619)
		(end 80.898746 -97.78619)
		(width 0.0889)
		(layer "In11.Cu")
		(net "M_M_DQ<25>")
	)
	(segment
		(start 80.076802 -98.281236)
		(end 80.040734 -98.281236)
		(width 0.0889)
		(layer "In11.Cu")
		(net "M_M_DQ<25>")
	)
	(segment
		(start 72.013572 -117.197124)
		(end 71.726044 -117.197124)
		(width 0.14224)
		(layer "In11.Cu")
		(net "M_M_DQ<25>")
	)
	(segment
		(start 61.370972 -150.391368)
		(end 61.60135 -150.621746)
		(width 0.14224)
		(layer "In11.Cu")
		(net "M_M_DQ<25>")
	)
	(segment
		(start 71.468742 -118.089426)
		(end 71.181468 -118.3767)
		(width 0.14224)
		(layer "In11.Cu")
		(net "M_M_DQ<25>")
	)
	(segment
		(start 75.588368 -113.9698)
		(end 74.63028 -114.927888)
		(width 0.14224)
		(layer "In11.Cu")
		(net "M_M_DQ<25>")
	)
	(segment
		(start 83.142582 -94.518988)
		(end 83.137756 -94.527624)
		(width 0.0889)
		(layer "In11.Cu")
		(net "M_M_DQ<25>")
	)
	(segment
		(start 61.52515 -152.3238)
		(end 61.310774 -152.538176)
		(width 0.14224)
		(layer "In11.Cu")
		(net "M_M_DQ<25>")
	)
	(segment
		(start 61.60135 -151.026368)
		(end 61.310774 -151.316944)
		(width 0.14224)
		(layer "In11.Cu")
		(net "M_M_DQ<25>")
	)
	(segment
		(start 81.793842 -97.290636)
		(end 81.772252 -97.290636)
		(width 0.0889)
		(layer "In11.Cu")
		(net "M_M_DQ<25>")
	)
	(segment
		(start 61.799216 -149.533356)
		(end 61.370972 -149.9616)
		(width 0.14224)
		(layer "In11.Cu")
		(net "M_M_DQ<25>")
	)
	(segment
		(start 61.398404 -153.542746)
		(end 61.149484 -153.542746)
		(width 0.14224)
		(layer "In11.Cu")
		(net "M_M_DQ<25>")
	)
	(segment
		(start 61.370972 -149.9616)
		(end 61.370972 -150.391368)
		(width 0.14224)
		(layer "In11.Cu")
		(net "M_M_DQ<25>")
	)
	(segment
		(start 74.31278 -114.897916)
		(end 74.025252 -114.897916)
		(width 0.14224)
		(layer "In11.Cu")
		(net "M_M_DQ<25>")
	)
	(segment
		(start 68.67144 -119.048022)
		(end 68.67144 -119.511572)
		(width 0.14224)
		(layer "In11.Cu")
		(net "M_M_DQ<25>")
	)
	(segment
		(start 62.431168 -136.697466)
		(end 62.431168 -138.7602)
		(width 0.14224)
		(layer "In11.Cu")
		(net "M_M_DQ<25>")
	)
	(segment
		(start 74.63028 -114.927888)
		(end 74.342752 -114.927888)
		(width 0.14224)
		(layer "In11.Cu")
		(net "M_M_DQ<25>")
	)
	(segment
		(start 61.52515 -151.892)
		(end 61.52515 -152.3238)
		(width 0.14224)
		(layer "In11.Cu")
		(net "M_M_DQ<25>")
	)
	(segment
		(start 62.309502 -141.351)
		(end 62.431168 -141.472666)
		(width 0.14224)
		(layer "In11.Cu")
		(net "M_M_DQ<25>")
	)
	(segment
		(start 74.342752 -114.927888)
		(end 74.31278 -114.897916)
		(width 0.14224)
		(layer "In11.Cu")
		(net "M_M_DQ<25>")
	)
	(segment
		(start 62.309502 -138.881866)
		(end 62.309502 -141.351)
		(width 0.14224)
		(layer "In11.Cu")
		(net "M_M_DQ<25>")
	)
	(segment
		(start 62.309502 -146.20748)
		(end 62.431168 -146.329146)
		(width 0.14224)
		(layer "In11.Cu")
		(net "M_M_DQ<25>")
	)
	(segment
		(start 69.48424 -119.048022)
		(end 69.3293 -118.893082)
		(width 0.14224)
		(layer "In11.Cu")
		(net "M_M_DQ<25>")
	)
	(segment
		(start 62.431168 -138.7602)
		(end 62.309502 -138.881866)
		(width 0.14224)
		(layer "In11.Cu")
		(net "M_M_DQ<25>")
	)
	(segment
		(start 62.309502 -136.5758)
		(end 62.431168 -136.697466)
		(width 0.14224)
		(layer "In11.Cu")
		(net "M_M_DQ<25>")
	)
	(segment
		(start 61.55055 -153.0858)
		(end 61.55055 -153.3906)
		(width 0.14224)
		(layer "In11.Cu")
		(net "M_M_DQ<25>")
	)
	(segment
		(start 62.309502 -134.335266)
		(end 62.309502 -136.5758)
		(width 0.14224)
		(layer "In11.Cu")
		(net "M_M_DQ<25>")
	)
	(segment
		(start 62.309502 -123.870466)
		(end 62.309502 -131.699)
		(width 0.14224)
		(layer "In11.Cu")
		(net "M_M_DQ<25>")
	)
	(segment
		(start 71.181468 -118.3767)
		(end 70.89394 -118.3767)
		(width 0.14224)
		(layer "In11.Cu")
		(net "M_M_DQ<25>")
	)
	(segment
		(start 61.60135 -150.621746)
		(end 61.60135 -151.026368)
		(width 0.14224)
		(layer "In11.Cu")
		(net "M_M_DQ<25>")
	)
	(segment
		(start 72.588374 -116.622322)
		(end 72.618346 -116.652294)
		(width 0.14224)
		(layer "In11.Cu")
		(net "M_M_DQ<25>")
	)
	(segment
		(start 61.310774 -151.677624)
		(end 61.52515 -151.892)
		(width 0.14224)
		(layer "In11.Cu")
		(net "M_M_DQ<25>")
	)
	(segment
		(start 69.63918 -119.507)
		(end 69.48424 -119.35206)
		(width 0.14224)
		(layer "In11.Cu")
		(net "M_M_DQ<25>")
	)
	(segment
		(start 61.821568 -149.444456)
		(end 61.821568 -149.533356)
		(width 0.14224)
		(layer "In11.Cu")
		(net "M_M_DQ<25>")
	)
	(segment
		(start 62.309502 -148.956522)
		(end 61.821568 -149.444456)
		(width 0.14224)
		(layer "In11.Cu")
		(net "M_M_DQ<25>")
	)
	(segment
		(start 73.193148 -116.077492)
		(end 73.163176 -116.04752)
		(width 0.14224)
		(layer "In11.Cu")
		(net "M_M_DQ<25>")
	)
	(segment
		(start 62.431168 -143.6624)
		(end 62.309502 -143.784066)
		(width 0.14224)
		(layer "In11.Cu")
		(net "M_M_DQ<25>")
	)
	(segment
		(start 70.319138 -118.951502)
		(end 70.319138 -119.23903)
		(width 0.14224)
		(layer "In11.Cu")
		(net "M_M_DQ<25>")
	)
	(segment
		(start 61.821568 -149.533356)
		(end 61.799216 -149.533356)
		(width 0.14224)
		(layer "In11.Cu")
		(net "M_M_DQ<25>")
	)
	(segment
		(start 68.5165 -119.666512)
		(end 68.01358 -119.666512)
		(width 0.14224)
		(layer "In11.Cu")
		(net "M_M_DQ<25>")
	)
	(segment
		(start 83.4898 -92.337636)
		(end 83.489546 -92.337636)
		(width 0.0889)
		(layer "In11.Cu")
		(net "M_M_DQ<25>")
	)
	(segment
		(start 70.289166 -118.92153)
		(end 70.319138 -118.951502)
		(width 0.14224)
		(layer "In11.Cu")
		(net "M_M_DQ<25>")
	)
	(segment
		(start 67.85864 -119.048022)
		(end 67.7037 -118.893082)
		(width 0.14224)
		(layer "In11.Cu")
		(net "M_M_DQ<25>")
	)
	(segment
		(start 83.142582 -93.928438)
		(end 83.148932 -93.939106)
		(width 0.0889)
		(layer "In11.Cu")
		(net "M_M_DQ<25>")
	)
	(segment
		(start 62.431168 -148.3614)
		(end 62.309502 -148.483066)
		(width 0.14224)
		(layer "In11.Cu")
		(net "M_M_DQ<25>")
	)
	(segment
		(start 84.347812 -87.28964)
		(end 84.041234 -87.996522)
		(width 0.0889)
		(layer "In11.Cu")
		(net "M_M_DQ<25>")
	)
	(segment
		(start 73.737978 -115.18519)
		(end 73.737978 -115.472718)
		(width 0.14224)
		(layer "In11.Cu")
		(net "M_M_DQ<25>")
	)
	(segment
		(start 68.67144 -119.511572)
		(end 68.5165 -119.666512)
		(width 0.14224)
		(layer "In11.Cu")
		(net "M_M_DQ<25>")
	)
	(segment
		(start 72.331072 -117.227096)
		(end 72.043544 -117.227096)
		(width 0.14224)
		(layer "In11.Cu")
		(net "M_M_DQ<25>")
	)
	(segment
		(start 79.043784 -100.292154)
		(end 79.043784 -102.475538)
		(width 0.0889)
		(layer "In11.Cu")
		(net "M_M_DQ<25>")
	)
	(segment
		(start 73.163176 -116.04752)
		(end 72.875648 -116.04752)
		(width 0.14224)
		(layer "In11.Cu")
		(net "M_M_DQ<25>")
	)
	(segment
		(start 72.618346 -116.939822)
		(end 72.331072 -117.227096)
		(width 0.14224)
		(layer "In11.Cu")
		(net "M_M_DQ<25>")
	)
	(segment
		(start 70.319138 -119.23903)
		(end 70.051168 -119.507)
		(width 0.14224)
		(layer "In11.Cu")
		(net "M_M_DQ<25>")
	)
	(segment
		(start 62.431168 -141.472666)
		(end 62.431168 -143.6624)
		(width 0.14224)
		(layer "In11.Cu")
		(net "M_M_DQ<25>")
	)
	(arc
		(start 83.489546 -92.337636)
		(mid 83.142744 -92.537757)
		(end 83.142582 -92.938092)
		(width 0.0889)
		(layer "In11.Cu")
		(net "M_M_DQ<25>")
	)
	(arc
		(start 83.148932 -93.939106)
		(mid 83.22173 -94.229869)
		(end 83.142582 -94.518988)
		(width 0.0889)
		(layer "In11.Cu")
		(net "M_M_DQ<25>")
	)
	(arc
		(start 84.041234 -87.996522)
		(mid 84.02282 -88.039347)
		(end 84.001102 -88.080596)
		(width 0.0889)
		(layer "In11.Cu")
		(net "M_M_DQ<25>")
	)
	(arc
		(start 84.001102 -88.080596)
		(mid 83.947603 -88.280494)
		(end 84.001102 -88.480392)
		(width 0.0889)
		(layer "In11.Cu")
		(net "M_M_DQ<25>")
	)
	(arc
		(start 83.137756 -94.527624)
		(mid 83.089001 -94.723976)
		(end 83.142582 -94.919038)
		(width 0.0889)
		(layer "In11.Cu")
		(net "M_M_DQ<25>")
	)
	(arc
		(start 84.001102 -89.470992)
		(mid 84.080233 -89.766394)
		(end 84.001102 -90.061796)
		(width 0.0889)
		(layer "In11.Cu")
		(net "M_M_DQ<25>")
	)
	(arc
		(start 84.001102 -91.452192)
		(mid 84.001068 -92.042547)
		(end 83.4898 -92.337636)
		(width 0.0889)
		(layer "In11.Cu")
		(net "M_M_DQ<25>")
	)
	(arc
		(start 81.425542 -97.490788)
		(mid 81.216934 -97.70272)
		(end 80.931512 -97.78619)
		(width 0.0889)
		(layer "In11.Cu")
		(net "M_M_DQ<25>")
	)
	(arc
		(start 84.001102 -91.052396)
		(mid 83.947603 -91.252294)
		(end 84.001102 -91.452192)
		(width 0.0889)
		(layer "In11.Cu")
		(net "M_M_DQ<25>")
	)
	(arc
		(start 84.001102 -90.461592)
		(mid 84.080233 -90.756994)
		(end 84.001102 -91.052396)
		(width 0.0889)
		(layer "In11.Cu")
		(net "M_M_DQ<25>")
	)
	(arc
		(start 83.142582 -93.528642)
		(mid 83.089083 -93.72854)
		(end 83.142582 -93.928438)
		(width 0.0889)
		(layer "In11.Cu")
		(net "M_M_DQ<25>")
	)
	(arc
		(start 80.567022 -97.986088)
		(mid 80.360018 -98.196952)
		(end 80.076802 -98.281236)
		(width 0.0889)
		(layer "In11.Cu")
		(net "M_M_DQ<25>")
	)
	(arc
		(start 83.142582 -92.938092)
		(mid 83.221679 -93.233384)
		(end 83.142582 -93.528642)
		(width 0.0889)
		(layer "In11.Cu")
		(net "M_M_DQ<25>")
	)
	(arc
		(start 84.001102 -88.480392)
		(mid 84.080233 -88.775794)
		(end 84.001102 -89.071196)
		(width 0.0889)
		(layer "In11.Cu")
		(net "M_M_DQ<25>")
	)
	(arc
		(start 84.001102 -90.061796)
		(mid 83.947603 -90.261694)
		(end 84.001102 -90.461592)
		(width 0.0889)
		(layer "In11.Cu")
		(net "M_M_DQ<25>")
	)
	(arc
		(start 82.615786 -95.80499)
		(mid 82.282868 -96.006981)
		(end 82.279236 -96.396302)
		(width 0.0889)
		(layer "In11.Cu")
		(net "M_M_DQ<25>")
	)
	(arc
		(start 84.001102 -89.071196)
		(mid 83.947603 -89.271094)
		(end 84.001102 -89.470992)
		(width 0.0889)
		(layer "In11.Cu")
		(net "M_M_DQ<25>")
	)
	(arc
		(start 82.290412 -96.415606)
		(mid 82.286381 -96.991788)
		(end 81.793842 -97.290636)
		(width 0.0889)
		(layer "In11.Cu")
		(net "M_M_DQ<25>")
	)
	(arc
		(start 80.040734 -98.281236)
		(mid 79.768399 -98.401913)
		(end 79.654654 -98.677222)
		(width 0.0889)
		(layer "In11.Cu")
		(net "M_M_DQ<25>")
	)
	(arc
		(start 80.898746 -97.78619)
		(mid 80.707104 -97.843356)
		(end 80.567022 -97.986088)
		(width 0.0889)
		(layer "In11.Cu")
		(net "M_M_DQ<25>")
	)
	(arc
		(start 81.772252 -97.290636)
		(mid 81.572092 -97.344271)
		(end 81.425542 -97.490788)
		(width 0.0889)
		(layer "In11.Cu")
		(net "M_M_DQ<25>")
	)
	(arc
		(start 83.142582 -94.919038)
		(mid 83.146911 -95.50221)
		(end 82.648552 -95.80499)
		(width 0.0889)
		(layer "In11.Cu")
		(net "M_M_DQ<25>")
	)
	(segment
		(start 61.999368 -156.878782)
		(end 61.821568 -155.0162)
		(width 0.1651)
		(layer "F.Cu")
		(net "M_M_DQ<24>")
	)
	(segment
		(start 61.999368 -156.87294)
		(end 61.999368 -156.878782)
		(width 0.1651)
		(layer "F.Cu")
		(net "M_M_DQ<24>")
	)
	(segment
		(start 84.919312 -85.30844)
		(end 84.347812 -85.30844)
		(width 0.1651)
		(layer "F.Cu")
		(net "M_M_DQ<24>")
	)
	(via
		(at 61.821568 -155.0162)
		(size 0.508)
		(drill 0.254)
		(layers "F.Cu" "B.Cu")
		(net "M_M_DQ<24>")
	)
	(via
		(at 84.347812 -85.30844)
		(size 0.508)
		(drill 0.254)
		(layers "F.Cu" "B.Cu")
		(net "M_M_DQ<24>")
	)
	(via
		(at 61.149484 -150.814278)
		(size 0.508)
		(drill 0.254)
		(layers "F.Cu" "B.Cu")
		(net "M_M_DQ<24>")
	)
	(segment
		(start 61.149484 -152.078436)
		(end 61.149484 -150.814278)
		(width 0.1651)
		(layer "B.Cu")
		(net "M_M_DQ<24>")
	)
	(segment
		(start 61.617352 -139.377928)
		(end 61.331602 -139.663678)
		(width 0.14224)
		(layer "In11.Cu")
		(net "M_M_DQ<24>")
	)
	(segment
		(start 61.623702 -141.035278)
		(end 61.623702 -144.085818)
		(width 0.14224)
		(layer "In11.Cu")
		(net "M_M_DQ<24>")
	)
	(segment
		(start 61.331602 -139.663678)
		(end 61.331602 -140.743178)
		(width 0.14224)
		(layer "In11.Cu")
		(net "M_M_DQ<24>")
	)
	(segment
		(start 61.567568 -146.296634)
		(end 61.567568 -149.028912)
		(width 0.14224)
		(layer "In11.Cu")
		(net "M_M_DQ<24>")
	)
	(segment
		(start 60.716414 -151.247348)
		(end 60.716414 -153.911046)
		(width 0.14224)
		(layer "In11.Cu")
		(net "M_M_DQ<24>")
	)
	(segment
		(start 61.331602 -135.95858)
		(end 61.617352 -136.24433)
		(width 0.14224)
		(layer "In11.Cu")
		(net "M_M_DQ<24>")
	)
	(segment
		(start 82.641948 -95.61449)
		(end 82.609182 -95.61449)
		(width 0.0889)
		(layer "In11.Cu")
		(net "M_M_DQ<24>")
	)
	(segment
		(start 74.927968 -113.0554)
		(end 69.629274 -118.354094)
		(width 0.14224)
		(layer "In11.Cu")
		(net "M_M_DQ<24>")
	)
	(segment
		(start 83.96732 -86.766908)
		(end 83.836002 -86.994492)
		(width 0.0889)
		(layer "In11.Cu")
		(net "M_M_DQ<24>")
	)
	(segment
		(start 78.65745 -102.724204)
		(end 78.65745 -104.499918)
		(width 0.14224)
		(layer "In11.Cu")
		(net "M_M_DQ<24>")
	)
	(segment
		(start 61.610494 -146.253708)
		(end 61.567568 -146.296634)
		(width 0.14224)
		(layer "In11.Cu")
		(net "M_M_DQ<24>")
	)
	(segment
		(start 78.853792 -102.527862)
		(end 78.65745 -102.724204)
		(width 0.0889)
		(layer "In11.Cu")
		(net "M_M_DQ<24>")
	)
	(segment
		(start 69.629274 -118.354094)
		(end 66.911728 -118.354094)
		(width 0.14224)
		(layer "In11.Cu")
		(net "M_M_DQ<24>")
	)
	(segment
		(start 80.924908 -97.59569)
		(end 80.892142 -97.59569)
		(width 0.0889)
		(layer "In11.Cu")
		(net "M_M_DQ<24>")
	)
	(segment
		(start 61.331602 -134.776718)
		(end 61.331602 -135.95858)
		(width 0.14224)
		(layer "In11.Cu")
		(net "M_M_DQ<24>")
	)
	(segment
		(start 61.674502 -124.12472)
		(end 61.288168 -124.511054)
		(width 0.14224)
		(layer "In11.Cu")
		(net "M_M_DQ<24>")
	)
	(segment
		(start 61.674502 -123.59132)
		(end 61.674502 -124.12472)
		(width 0.14224)
		(layer "In11.Cu")
		(net "M_M_DQ<24>")
	)
	(segment
		(start 61.610494 -145.838926)
		(end 61.610494 -146.253708)
		(width 0.14224)
		(layer "In11.Cu")
		(net "M_M_DQ<24>")
	)
	(segment
		(start 82.118962 -96.500188)
		(end 82.123788 -96.508824)
		(width 0.0889)
		(layer "In11.Cu")
		(net "M_M_DQ<24>")
	)
	(segment
		(start 61.59627 -129.816098)
		(end 61.331602 -130.080766)
		(width 0.14224)
		(layer "In11.Cu")
		(net "M_M_DQ<24>")
	)
	(segment
		(start 78.65745 -104.499918)
		(end 74.927968 -108.2294)
		(width 0.14224)
		(layer "In11.Cu")
		(net "M_M_DQ<24>")
	)
	(segment
		(start 60.716414 -153.911046)
		(end 61.821568 -155.0162)
		(width 0.14224)
		(layer "In11.Cu")
		(net "M_M_DQ<24>")
	)
	(segment
		(start 60.886594 -149.709886)
		(end 60.886594 -150.551388)
		(width 0.14224)
		(layer "In11.Cu")
		(net "M_M_DQ<24>")
	)
	(segment
		(start 82.112612 -96.48952)
		(end 82.118962 -96.500188)
		(width 0.0889)
		(layer "In11.Cu")
		(net "M_M_DQ<24>")
	)
	(segment
		(start 61.628274 -131.454906)
		(end 61.628274 -134.480046)
		(width 0.14224)
		(layer "In11.Cu")
		(net "M_M_DQ<24>")
	)
	(segment
		(start 61.623702 -144.085818)
		(end 61.344302 -144.365218)
		(width 0.14224)
		(layer "In11.Cu")
		(net "M_M_DQ<24>")
	)
	(segment
		(start 79.464154 -99.603052)
		(end 78.853792 -100.213414)
		(width 0.0889)
		(layer "In11.Cu")
		(net "M_M_DQ<24>")
	)
	(segment
		(start 81.787238 -97.100136)
		(end 81.772252 -97.100136)
		(width 0.0889)
		(layer "In11.Cu")
		(net "M_M_DQ<24>")
	)
	(segment
		(start 61.617352 -136.24433)
		(end 61.617352 -139.377928)
		(width 0.14224)
		(layer "In11.Cu")
		(net "M_M_DQ<24>")
	)
	(segment
		(start 61.288168 -124.511054)
		(end 61.288168 -129.0066)
		(width 0.14224)
		(layer "In11.Cu")
		(net "M_M_DQ<24>")
	)
	(segment
		(start 78.853792 -100.213414)
		(end 78.853792 -102.527862)
		(width 0.0889)
		(layer "In11.Cu")
		(net "M_M_DQ<24>")
	)
	(segment
		(start 61.288168 -129.0066)
		(end 61.59627 -129.314702)
		(width 0.14224)
		(layer "In11.Cu")
		(net "M_M_DQ<24>")
	)
	(segment
		(start 61.331602 -130.080766)
		(end 61.331602 -131.158234)
		(width 0.14224)
		(layer "In11.Cu")
		(net "M_M_DQ<24>")
	)
	(segment
		(start 61.344302 -144.365218)
		(end 61.344302 -145.572734)
		(width 0.14224)
		(layer "In11.Cu")
		(net "M_M_DQ<24>")
	)
	(segment
		(start 61.149484 -150.814278)
		(end 60.716414 -151.247348)
		(width 0.14224)
		(layer "In11.Cu")
		(net "M_M_DQ<24>")
	)
	(segment
		(start 60.886594 -150.551388)
		(end 61.149484 -150.814278)
		(width 0.14224)
		(layer "In11.Cu")
		(net "M_M_DQ<24>")
	)
	(segment
		(start 61.331602 -131.158234)
		(end 61.628274 -131.454906)
		(width 0.14224)
		(layer "In11.Cu")
		(net "M_M_DQ<24>")
	)
	(segment
		(start 84.347812 -85.30844)
		(end 84.001102 -86.099396)
		(width 0.0889)
		(layer "In11.Cu")
		(net "M_M_DQ<24>")
	)
	(segment
		(start 61.567568 -149.028912)
		(end 60.886594 -149.709886)
		(width 0.14224)
		(layer "In11.Cu")
		(net "M_M_DQ<24>")
	)
	(segment
		(start 82.971132 -94.01302)
		(end 82.977482 -94.023688)
		(width 0.0889)
		(layer "In11.Cu")
		(net "M_M_DQ<24>")
	)
	(segment
		(start 80.070198 -98.090736)
		(end 80.037432 -98.090736)
		(width 0.0889)
		(layer "In11.Cu")
		(net "M_M_DQ<24>")
	)
	(segment
		(start 61.344302 -145.572734)
		(end 61.610494 -145.838926)
		(width 0.14224)
		(layer "In11.Cu")
		(net "M_M_DQ<24>")
	)
	(segment
		(start 66.911728 -118.354094)
		(end 61.674502 -123.59132)
		(width 0.14224)
		(layer "In11.Cu")
		(net "M_M_DQ<24>")
	)
	(segment
		(start 61.331602 -140.743178)
		(end 61.623702 -141.035278)
		(width 0.14224)
		(layer "In11.Cu")
		(net "M_M_DQ<24>")
	)
	(segment
		(start 83.4898 -92.147136)
		(end 83.489292 -92.147136)
		(width 0.0889)
		(layer "In11.Cu")
		(net "M_M_DQ<24>")
	)
	(segment
		(start 61.628274 -134.480046)
		(end 61.331602 -134.776718)
		(width 0.14224)
		(layer "In11.Cu")
		(net "M_M_DQ<24>")
	)
	(segment
		(start 61.59627 -129.314702)
		(end 61.59627 -129.816098)
		(width 0.14224)
		(layer "In11.Cu")
		(net "M_M_DQ<24>")
	)
	(segment
		(start 79.464154 -98.676206)
		(end 79.464154 -99.603052)
		(width 0.0889)
		(layer "In11.Cu")
		(net "M_M_DQ<24>")
	)
	(segment
		(start 74.927968 -108.2294)
		(end 74.927968 -113.0554)
		(width 0.14224)
		(layer "In11.Cu")
		(net "M_M_DQ<24>")
	)
	(arc
		(start 82.977482 -95.014288)
		(mid 82.98023 -95.409755)
		(end 82.641948 -95.61449)
		(width 0.0889)
		(layer "In11.Cu")
		(net "M_M_DQ<24>")
	)
	(arc
		(start 83.836002 -86.994492)
		(mid 83.756871 -87.289894)
		(end 83.836002 -87.585296)
		(width 0.0889)
		(layer "In11.Cu")
		(net "M_M_DQ<24>")
	)
	(arc
		(start 83.836002 -89.566496)
		(mid 83.889501 -89.766394)
		(end 83.836002 -89.966292)
		(width 0.0889)
		(layer "In11.Cu")
		(net "M_M_DQ<24>")
	)
	(arc
		(start 82.977482 -93.033596)
		(mid 83.031049 -93.233384)
		(end 82.977482 -93.433138)
		(width 0.0889)
		(layer "In11.Cu")
		(net "M_M_DQ<24>")
	)
	(arc
		(start 82.977482 -93.433138)
		(mid 82.89826 -93.722256)
		(end 82.971132 -94.01302)
		(width 0.0889)
		(layer "In11.Cu")
		(net "M_M_DQ<24>")
	)
	(arc
		(start 83.836002 -89.966292)
		(mid 83.756871 -90.261694)
		(end 83.836002 -90.557096)
		(width 0.0889)
		(layer "In11.Cu")
		(net "M_M_DQ<24>")
	)
	(arc
		(start 84.001102 -86.099396)
		(mid 83.948109 -86.279187)
		(end 83.982814 -86.463378)
		(width 0.0889)
		(layer "In11.Cu")
		(net "M_M_DQ<24>")
	)
	(arc
		(start 83.836002 -90.956892)
		(mid 83.756871 -91.252294)
		(end 83.836002 -91.547696)
		(width 0.0889)
		(layer "In11.Cu")
		(net "M_M_DQ<24>")
	)
	(arc
		(start 83.982814 -86.463378)
		(mid 84.011679 -86.617013)
		(end 83.96732 -86.766908)
		(width 0.0889)
		(layer "In11.Cu")
		(net "M_M_DQ<24>")
	)
	(arc
		(start 83.836002 -87.585296)
		(mid 83.889501 -87.785194)
		(end 83.836002 -87.985092)
		(width 0.0889)
		(layer "In11.Cu")
		(net "M_M_DQ<24>")
	)
	(arc
		(start 81.260442 -97.395538)
		(mid 81.118759 -97.539342)
		(end 80.924908 -97.59569)
		(width 0.0889)
		(layer "In11.Cu")
		(net "M_M_DQ<24>")
	)
	(arc
		(start 83.836002 -87.985092)
		(mid 83.756871 -88.280494)
		(end 83.836002 -88.575896)
		(width 0.0889)
		(layer "In11.Cu")
		(net "M_M_DQ<24>")
	)
	(arc
		(start 80.037432 -98.090736)
		(mid 79.632883 -98.268014)
		(end 79.464154 -98.676206)
		(width 0.0889)
		(layer "In11.Cu")
		(net "M_M_DQ<24>")
	)
	(arc
		(start 82.977482 -94.423484)
		(mid 82.898351 -94.718886)
		(end 82.977482 -95.014288)
		(width 0.0889)
		(layer "In11.Cu")
		(net "M_M_DQ<24>")
	)
	(arc
		(start 83.836002 -88.575896)
		(mid 83.889501 -88.775794)
		(end 83.836002 -88.975692)
		(width 0.0889)
		(layer "In11.Cu")
		(net "M_M_DQ<24>")
	)
	(arc
		(start 83.836002 -91.547696)
		(mid 83.835849 -91.947249)
		(end 83.4898 -92.147136)
		(width 0.0889)
		(layer "In11.Cu")
		(net "M_M_DQ<24>")
	)
	(arc
		(start 82.609182 -95.61449)
		(mid 82.116792 -95.913423)
		(end 82.112612 -96.48952)
		(width 0.0889)
		(layer "In11.Cu")
		(net "M_M_DQ<24>")
	)
	(arc
		(start 83.836002 -88.975692)
		(mid 83.756871 -89.271094)
		(end 83.836002 -89.566496)
		(width 0.0889)
		(layer "In11.Cu")
		(net "M_M_DQ<24>")
	)
	(arc
		(start 81.772252 -97.100136)
		(mid 81.476784 -97.179288)
		(end 81.260442 -97.395538)
		(width 0.0889)
		(layer "In11.Cu")
		(net "M_M_DQ<24>")
	)
	(arc
		(start 82.977482 -94.023688)
		(mid 83.030981 -94.223586)
		(end 82.977482 -94.423484)
		(width 0.0889)
		(layer "In11.Cu")
		(net "M_M_DQ<24>")
	)
	(arc
		(start 83.836002 -90.557096)
		(mid 83.889501 -90.756994)
		(end 83.836002 -90.956892)
		(width 0.0889)
		(layer "In11.Cu")
		(net "M_M_DQ<24>")
	)
	(arc
		(start 80.892142 -97.59569)
		(mid 80.608925 -97.679971)
		(end 80.401922 -97.890838)
		(width 0.0889)
		(layer "In11.Cu")
		(net "M_M_DQ<24>")
	)
	(arc
		(start 83.489292 -92.147136)
		(mid 82.977441 -92.442631)
		(end 82.977482 -93.033596)
		(width 0.0889)
		(layer "In11.Cu")
		(net "M_M_DQ<24>")
	)
	(arc
		(start 80.401922 -97.890838)
		(mid 80.261843 -98.033574)
		(end 80.070198 -98.090736)
		(width 0.0889)
		(layer "In11.Cu")
		(net "M_M_DQ<24>")
	)
	(arc
		(start 82.123788 -96.508824)
		(mid 82.120041 -96.89808)
		(end 81.787238 -97.100136)
		(width 0.0889)
		(layer "In11.Cu")
		(net "M_M_DQ<24>")
	)
	(segment
		(start 80.626712 -94.718886)
		(end 80.055212 -94.718886)
		(width 0.1651)
		(layer "F.Cu")
		(net "M_M_DQ<23>")
	)
	(segment
		(start 56.049418 -152.273)
		(end 56.049418 -153.542746)
		(width 0.1651)
		(layer "F.Cu")
		(net "M_M_DQ<23>")
	)
	(via
		(at 56.899302 -149.533356)
		(size 0.508)
		(drill 0.254)
		(layers "F.Cu" "B.Cu")
		(net "M_M_DQ<23>")
	)
	(via
		(at 56.049418 -153.542746)
		(size 0.508)
		(drill 0.254)
		(layers "F.Cu" "B.Cu")
		(net "M_M_DQ<23>")
	)
	(via
		(at 80.055212 -94.718886)
		(size 0.508)
		(drill 0.254)
		(layers "F.Cu" "B.Cu")
		(net "M_M_DQ<23>")
	)
	(segment
		(start 56.899556 -147.478496)
		(end 56.899302 -147.478496)
		(width 0.1651)
		(layer "B.Cu")
		(net "M_M_DQ<23>")
	)
	(segment
		(start 56.899302 -147.478496)
		(end 56.899302 -149.533356)
		(width 0.1651)
		(layer "B.Cu")
		(net "M_M_DQ<23>")
	)
	(segment
		(start 66.826638 -113.10493)
		(end 57.579768 -122.3518)
		(width 0.14224)
		(layer "In11.Cu")
		(net "M_M_DQ<23>")
	)
	(segment
		(start 57.239662 -132.60959)
		(end 57.084722 -132.76453)
		(width 0.14224)
		(layer "In11.Cu")
		(net "M_M_DQ<23>")
	)
	(segment
		(start 57.198768 -129.805938)
		(end 57.452768 -130.059938)
		(width 0.14224)
		(layer "In11.Cu")
		(net "M_M_DQ<23>")
	)
	(segment
		(start 57.569862 -133.891274)
		(end 57.173368 -134.287768)
		(width 0.14224)
		(layer "In11.Cu")
		(net "M_M_DQ<23>")
	)
	(segment
		(start 57.325768 -148.5392)
		(end 57.147968 -148.717)
		(width 0.14224)
		(layer "In11.Cu")
		(net "M_M_DQ<23>")
	)
	(segment
		(start 78.359762 -96.300036)
		(end 78.338172 -96.300036)
		(width 0.0889)
		(layer "In11.Cu")
		(net "M_M_DQ<23>")
	)
	(segment
		(start 57.424828 -127.689864)
		(end 56.999886 -127.689864)
		(width 0.14224)
		(layer "In11.Cu")
		(net "M_M_DQ<23>")
	)
	(segment
		(start 57.020968 -142.6972)
		(end 57.325768 -143.002)
		(width 0.14224)
		(layer "In11.Cu")
		(net "M_M_DQ<23>")
	)
	(segment
		(start 57.198768 -129.3622)
		(end 57.198768 -129.805938)
		(width 0.14224)
		(layer "In11.Cu")
		(net "M_M_DQ<23>")
	)
	(segment
		(start 57.325768 -143.002)
		(end 57.325768 -143.637)
		(width 0.14224)
		(layer "In11.Cu")
		(net "M_M_DQ<23>")
	)
	(segment
		(start 57.173368 -134.475728)
		(end 57.455308 -134.757668)
		(width 0.14224)
		(layer "In11.Cu")
		(net "M_M_DQ<23>")
	)
	(segment
		(start 57.122568 -141.071346)
		(end 57.122568 -141.45006)
		(width 0.14224)
		(layer "In11.Cu")
		(net "M_M_DQ<23>")
	)
	(segment
		(start 73.787 -101.491796)
		(end 73.787 -103.097076)
		(width 0.0889)
		(layer "In11.Cu")
		(net "M_M_DQ<23>")
	)
	(segment
		(start 57.139586 -146.270218)
		(end 57.325768 -146.4564)
		(width 0.14224)
		(layer "In11.Cu")
		(net "M_M_DQ<23>")
	)
	(segment
		(start 57.325768 -142.0876)
		(end 57.020968 -142.3924)
		(width 0.14224)
		(layer "In11.Cu")
		(net "M_M_DQ<23>")
	)
	(segment
		(start 69.252846 -111.389922)
		(end 69.252846 -111.67745)
		(width 0.14224)
		(layer "In11.Cu")
		(net "M_M_DQ<23>")
	)
	(segment
		(start 56.448706 -150.391368)
		(end 56.493156 -150.435818)
		(width 0.14224)
		(layer "In11.Cu")
		(net "M_M_DQ<23>")
	)
	(segment
		(start 69.827648 -111.102648)
		(end 69.54012 -111.102648)
		(width 0.14224)
		(layer "In11.Cu")
		(net "M_M_DQ<23>")
	)
	(segment
		(start 70.221348 -111.20882)
		(end 69.93382 -111.20882)
		(width 0.14224)
		(layer "In11.Cu")
		(net "M_M_DQ<23>")
	)
	(segment
		(start 56.467756 -152.2222)
		(end 56.210708 -152.479248)
		(width 0.14224)
		(layer "In11.Cu")
		(net "M_M_DQ<23>")
	)
	(segment
		(start 56.899302 -149.533356)
		(end 56.87695 -149.533356)
		(width 0.14224)
		(layer "In11.Cu")
		(net "M_M_DQ<23>")
	)
	(segment
		(start 74.063606 -98.77679)
		(end 74.03084 -98.77679)
		(width 0.0889)
		(layer "In11.Cu")
		(net "M_M_DQ<23>")
	)
	(segment
		(start 67.575938 -113.566702)
		(end 67.114166 -113.10493)
		(width 0.14224)
		(layer "In11.Cu")
		(net "M_M_DQ<23>")
	)
	(segment
		(start 56.493156 -150.435818)
		(end 56.493156 -151.1046)
		(width 0.14224)
		(layer "In11.Cu")
		(net "M_M_DQ<23>")
	)
	(segment
		(start 74.925936 -98.281236)
		(end 74.89317 -98.281236)
		(width 0.0889)
		(layer "In11.Cu")
		(net "M_M_DQ<23>")
	)
	(segment
		(start 56.844946 -127.844804)
		(end 56.844946 -128.347724)
		(width 0.14224)
		(layer "In11.Cu")
		(net "M_M_DQ<23>")
	)
	(segment
		(start 57.020968 -147.5486)
		(end 57.325768 -147.8534)
		(width 0.14224)
		(layer "In11.Cu")
		(net "M_M_DQ<23>")
	)
	(segment
		(start 56.493156 -151.1046)
		(end 56.210708 -151.387048)
		(width 0.14224)
		(layer "In11.Cu")
		(net "M_M_DQ<23>")
	)
	(segment
		(start 57.084722 -133.26745)
		(end 57.239662 -133.42239)
		(width 0.14224)
		(layer "In11.Cu")
		(net "M_M_DQ<23>")
	)
	(segment
		(start 77.497686 -96.79559)
		(end 77.46492 -96.79559)
		(width 0.0889)
		(layer "In11.Cu")
		(net "M_M_DQ<23>")
	)
	(segment
		(start 72.419464 -104.726486)
		(end 71.321168 -105.824782)
		(width 0.14224)
		(layer "In11.Cu")
		(net "M_M_DQ<23>")
	)
	(segment
		(start 57.452768 -130.059938)
		(end 57.452768 -131.114546)
		(width 0.14224)
		(layer "In11.Cu")
		(net "M_M_DQ<23>")
	)
	(segment
		(start 75.780646 -97.78619)
		(end 75.74788 -97.78619)
		(width 0.0889)
		(layer "In11.Cu")
		(net "M_M_DQ<23>")
	)
	(segment
		(start 57.579768 -127.534924)
		(end 57.424828 -127.689864)
		(width 0.14224)
		(layer "In11.Cu")
		(net "M_M_DQ<23>")
	)
	(segment
		(start 56.844946 -128.347724)
		(end 56.999886 -128.502664)
		(width 0.14224)
		(layer "In11.Cu")
		(net "M_M_DQ<23>")
	)
	(segment
		(start 72.419464 -104.464612)
		(end 72.419464 -104.726486)
		(width 0.0889)
		(layer "In11.Cu")
		(net "M_M_DQ<23>")
	)
	(segment
		(start 57.325768 -143.637)
		(end 57.177686 -143.785082)
		(width 0.14224)
		(layer "In11.Cu")
		(net "M_M_DQ<23>")
	)
	(segment
		(start 57.579768 -128.657604)
		(end 57.579768 -128.9812)
		(width 0.14224)
		(layer "In11.Cu")
		(net "M_M_DQ<23>")
	)
	(segment
		(start 57.325768 -146.4564)
		(end 57.325768 -146.8628)
		(width 0.14224)
		(layer "In11.Cu")
		(net "M_M_DQ<23>")
	)
	(segment
		(start 79.725774 -95.47987)
		(end 79.708502 -95.509588)
		(width 0.0889)
		(layer "In11.Cu")
		(net "M_M_DQ<23>")
	)
	(segment
		(start 57.325768 -147.8534)
		(end 57.325768 -148.5392)
		(width 0.14224)
		(layer "In11.Cu")
		(net "M_M_DQ<23>")
	)
	(segment
		(start 67.663568 -112.504728)
		(end 68.15074 -112.9919)
		(width 0.14224)
		(layer "In11.Cu")
		(net "M_M_DQ<23>")
	)
	(segment
		(start 57.177686 -144.072864)
		(end 57.503568 -144.398746)
		(width 0.14224)
		(layer "In11.Cu")
		(net "M_M_DQ<23>")
	)
	(segment
		(start 77.995018 -96.494346)
		(end 77.991716 -96.500188)
		(width 0.0889)
		(layer "In11.Cu")
		(net "M_M_DQ<23>")
	)
	(segment
		(start 67.663568 -112.2172)
		(end 67.663568 -112.504728)
		(width 0.14224)
		(layer "In11.Cu")
		(net "M_M_DQ<23>")
	)
	(segment
		(start 69.54012 -111.102648)
		(end 69.252846 -111.389922)
		(width 0.14224)
		(layer "In11.Cu")
		(net "M_M_DQ<23>")
	)
	(segment
		(start 57.173368 -134.287768)
		(end 57.173368 -134.475728)
		(width 0.14224)
		(layer "In11.Cu")
		(net "M_M_DQ<23>")
	)
	(segment
		(start 57.325768 -141.65326)
		(end 57.325768 -142.0876)
		(width 0.14224)
		(layer "In11.Cu")
		(net "M_M_DQ<23>")
	)
	(segment
		(start 57.020968 -142.3924)
		(end 57.020968 -142.6972)
		(width 0.14224)
		(layer "In11.Cu")
		(net "M_M_DQ<23>")
	)
	(segment
		(start 57.351168 -137.3124)
		(end 57.098184 -137.565384)
		(width 0.14224)
		(layer "In11.Cu")
		(net "M_M_DQ<23>")
	)
	(segment
		(start 57.503568 -139.711938)
		(end 57.503568 -140.690346)
		(width 0.14224)
		(layer "In11.Cu")
		(net "M_M_DQ<23>")
	)
	(segment
		(start 57.503568 -144.398746)
		(end 57.503568 -145.542254)
		(width 0.14224)
		(layer "In11.Cu")
		(net "M_M_DQ<23>")
	)
	(segment
		(start 57.503568 -140.690346)
		(end 57.122568 -141.071346)
		(width 0.14224)
		(layer "In11.Cu")
		(net "M_M_DQ<23>")
	)
	(segment
		(start 57.177686 -143.785082)
		(end 57.177686 -144.072864)
		(width 0.14224)
		(layer "In11.Cu")
		(net "M_M_DQ<23>")
	)
	(segment
		(start 56.999886 -128.502664)
		(end 57.424828 -128.502664)
		(width 0.14224)
		(layer "In11.Cu")
		(net "M_M_DQ<23>")
	)
	(segment
		(start 57.198768 -139.407138)
		(end 57.503568 -139.711938)
		(width 0.14224)
		(layer "In11.Cu")
		(net "M_M_DQ<23>")
	)
	(segment
		(start 57.569862 -133.57733)
		(end 57.569862 -133.891274)
		(width 0.14224)
		(layer "In11.Cu")
		(net "M_M_DQ<23>")
	)
	(segment
		(start 57.452768 -131.114546)
		(end 57.122568 -131.444746)
		(width 0.14224)
		(layer "In11.Cu")
		(net "M_M_DQ<23>")
	)
	(segment
		(start 57.122568 -131.680712)
		(end 57.569862 -132.128006)
		(width 0.14224)
		(layer "In11.Cu")
		(net "M_M_DQ<23>")
	)
	(segment
		(start 57.173368 -136.2964)
		(end 57.173368 -136.8044)
		(width 0.14224)
		(layer "In11.Cu")
		(net "M_M_DQ<23>")
	)
	(segment
		(start 56.467756 -151.9174)
		(end 56.467756 -152.2222)
		(width 0.14224)
		(layer "In11.Cu")
		(net "M_M_DQ<23>")
	)
	(segment
		(start 56.210708 -152.752552)
		(end 56.499506 -153.04135)
		(width 0.14224)
		(layer "In11.Cu")
		(net "M_M_DQ<23>")
	)
	(segment
		(start 67.950842 -111.929926)
		(end 67.663568 -112.2172)
		(width 0.14224)
		(layer "In11.Cu")
		(net "M_M_DQ<23>")
	)
	(segment
		(start 57.424828 -128.502664)
		(end 57.579768 -128.657604)
		(width 0.14224)
		(layer "In11.Cu")
		(net "M_M_DQ<23>")
	)
	(segment
		(start 57.084722 -132.76453)
		(end 57.084722 -133.26745)
		(width 0.14224)
		(layer "In11.Cu")
		(net "M_M_DQ<23>")
	)
	(segment
		(start 69.01307 -112.417098)
		(end 68.725542 -112.417098)
		(width 0.14224)
		(layer "In11.Cu")
		(net "M_M_DQ<23>")
	)
	(segment
		(start 57.147968 -149.28469)
		(end 56.899302 -149.533356)
		(width 0.14224)
		(layer "In11.Cu")
		(net "M_M_DQ<23>")
	)
	(segment
		(start 57.569862 -132.45465)
		(end 57.414922 -132.60959)
		(width 0.14224)
		(layer "In11.Cu")
		(net "M_M_DQ<23>")
	)
	(segment
		(start 57.139586 -145.906236)
		(end 57.139586 -146.270218)
		(width 0.14224)
		(layer "In11.Cu")
		(net "M_M_DQ<23>")
	)
	(segment
		(start 56.210708 -152.479248)
		(end 56.210708 -152.752552)
		(width 0.14224)
		(layer "In11.Cu")
		(net "M_M_DQ<23>")
	)
	(segment
		(start 73.69429 -101.349302)
		(end 73.700132 -101.359716)
		(width 0.0889)
		(layer "In11.Cu")
		(net "M_M_DQ<23>")
	)
	(segment
		(start 57.569862 -132.128006)
		(end 57.569862 -132.45465)
		(width 0.14224)
		(layer "In11.Cu")
		(net "M_M_DQ<23>")
	)
	(segment
		(start 68.15074 -112.9919)
		(end 68.15074 -113.279428)
		(width 0.14224)
		(layer "In11.Cu")
		(net "M_M_DQ<23>")
	)
	(segment
		(start 57.122568 -131.444746)
		(end 57.122568 -131.680712)
		(width 0.14224)
		(layer "In11.Cu")
		(net "M_M_DQ<23>")
	)
	(segment
		(start 57.239662 -133.42239)
		(end 57.414922 -133.42239)
		(width 0.14224)
		(layer "In11.Cu")
		(net "M_M_DQ<23>")
	)
	(segment
		(start 56.87695 -149.533356)
		(end 56.448706 -149.9616)
		(width 0.14224)
		(layer "In11.Cu")
		(net "M_M_DQ<23>")
	)
	(segment
		(start 69.359018 -112.07115)
		(end 69.01307 -112.417098)
		(width 0.14224)
		(layer "In11.Cu")
		(net "M_M_DQ<23>")
	)
	(segment
		(start 73.700132 -101.359716)
		(end 73.787 -101.491796)
		(width 0.0889)
		(layer "In11.Cu")
		(net "M_M_DQ<23>")
	)
	(segment
		(start 68.725542 -112.417098)
		(end 68.23837 -111.929926)
		(width 0.14224)
		(layer "In11.Cu")
		(net "M_M_DQ<23>")
	)
	(segment
		(start 69.252846 -111.67745)
		(end 69.359018 -111.783622)
		(width 0.14224)
		(layer "In11.Cu")
		(net "M_M_DQ<23>")
	)
	(segment
		(start 80.055212 -94.718886)
		(end 79.725774 -95.47987)
		(width 0.0889)
		(layer "In11.Cu")
		(net "M_M_DQ<23>")
	)
	(segment
		(start 57.455308 -136.01446)
		(end 57.173368 -136.2964)
		(width 0.14224)
		(layer "In11.Cu")
		(net "M_M_DQ<23>")
	)
	(segment
		(start 56.448706 -149.9616)
		(end 56.448706 -150.391368)
		(width 0.14224)
		(layer "In11.Cu")
		(net "M_M_DQ<23>")
	)
	(segment
		(start 69.359018 -111.783622)
		(end 69.359018 -112.07115)
		(width 0.14224)
		(layer "In11.Cu")
		(net "M_M_DQ<23>")
	)
	(segment
		(start 57.147968 -148.717)
		(end 57.147968 -149.28469)
		(width 0.14224)
		(layer "In11.Cu")
		(net "M_M_DQ<23>")
	)
	(segment
		(start 56.999886 -127.689864)
		(end 56.844946 -127.844804)
		(width 0.14224)
		(layer "In11.Cu")
		(net "M_M_DQ<23>")
	)
	(segment
		(start 57.020968 -147.1676)
		(end 57.020968 -147.5486)
		(width 0.14224)
		(layer "In11.Cu")
		(net "M_M_DQ<23>")
	)
	(segment
		(start 73.787 -103.097076)
		(end 72.419464 -104.464612)
		(width 0.0889)
		(layer "In11.Cu")
		(net "M_M_DQ<23>")
	)
	(segment
		(start 73.705466 -99.95662)
		(end 73.699116 -99.967288)
		(width 0.0889)
		(layer "In11.Cu")
		(net "M_M_DQ<23>")
	)
	(segment
		(start 67.114166 -113.10493)
		(end 66.826638 -113.10493)
		(width 0.14224)
		(layer "In11.Cu")
		(net "M_M_DQ<23>")
	)
	(segment
		(start 73.69429 -99.368102)
		(end 73.699116 -99.376738)
		(width 0.0889)
		(layer "In11.Cu")
		(net "M_M_DQ<23>")
	)
	(segment
		(start 57.455308 -134.757668)
		(end 57.455308 -136.01446)
		(width 0.14224)
		(layer "In11.Cu")
		(net "M_M_DQ<23>")
	)
	(segment
		(start 56.499506 -153.364946)
		(end 56.321706 -153.542746)
		(width 0.14224)
		(layer "In11.Cu")
		(net "M_M_DQ<23>")
	)
	(segment
		(start 57.579768 -122.3518)
		(end 57.579768 -127.534924)
		(width 0.14224)
		(layer "In11.Cu")
		(net "M_M_DQ<23>")
	)
	(segment
		(start 57.414922 -132.60959)
		(end 57.239662 -132.60959)
		(width 0.14224)
		(layer "In11.Cu")
		(net "M_M_DQ<23>")
	)
	(segment
		(start 57.351168 -138.2268)
		(end 57.351168 -138.684)
		(width 0.14224)
		(layer "In11.Cu")
		(net "M_M_DQ<23>")
	)
	(segment
		(start 68.15074 -113.279428)
		(end 67.863466 -113.566702)
		(width 0.14224)
		(layer "In11.Cu")
		(net "M_M_DQ<23>")
	)
	(segment
		(start 69.93382 -111.20882)
		(end 69.827648 -111.102648)
		(width 0.14224)
		(layer "In11.Cu")
		(net "M_M_DQ<23>")
	)
	(segment
		(start 68.23837 -111.929926)
		(end 67.950842 -111.929926)
		(width 0.14224)
		(layer "In11.Cu")
		(net "M_M_DQ<23>")
	)
	(segment
		(start 57.098184 -137.565384)
		(end 57.098184 -137.973816)
		(width 0.14224)
		(layer "In11.Cu")
		(net "M_M_DQ<23>")
	)
	(segment
		(start 76.642976 -97.290636)
		(end 76.61021 -97.290636)
		(width 0.0889)
		(layer "In11.Cu")
		(net "M_M_DQ<23>")
	)
	(segment
		(start 67.863466 -113.566702)
		(end 67.575938 -113.566702)
		(width 0.14224)
		(layer "In11.Cu")
		(net "M_M_DQ<23>")
	)
	(segment
		(start 57.122568 -141.45006)
		(end 57.325768 -141.65326)
		(width 0.14224)
		(layer "In11.Cu")
		(net "M_M_DQ<23>")
	)
	(segment
		(start 56.210708 -151.660352)
		(end 56.467756 -151.9174)
		(width 0.14224)
		(layer "In11.Cu")
		(net "M_M_DQ<23>")
	)
	(segment
		(start 57.098184 -137.973816)
		(end 57.351168 -138.2268)
		(width 0.14224)
		(layer "In11.Cu")
		(net "M_M_DQ<23>")
	)
	(segment
		(start 56.210708 -151.387048)
		(end 56.210708 -151.660352)
		(width 0.14224)
		(layer "In11.Cu")
		(net "M_M_DQ<23>")
	)
	(segment
		(start 57.351168 -138.684)
		(end 57.198768 -138.8364)
		(width 0.14224)
		(layer "In11.Cu")
		(net "M_M_DQ<23>")
	)
	(segment
		(start 57.579768 -128.9812)
		(end 57.198768 -129.3622)
		(width 0.14224)
		(layer "In11.Cu")
		(net "M_M_DQ<23>")
	)
	(segment
		(start 57.173368 -136.8044)
		(end 57.351168 -136.9822)
		(width 0.14224)
		(layer "In11.Cu")
		(net "M_M_DQ<23>")
	)
	(segment
		(start 79.214472 -95.80499)
		(end 79.181706 -95.80499)
		(width 0.0889)
		(layer "In11.Cu")
		(net "M_M_DQ<23>")
	)
	(segment
		(start 57.198768 -138.8364)
		(end 57.198768 -139.407138)
		(width 0.14224)
		(layer "In11.Cu")
		(net "M_M_DQ<23>")
	)
	(segment
		(start 57.414922 -133.42239)
		(end 57.569862 -133.57733)
		(width 0.14224)
		(layer "In11.Cu")
		(net "M_M_DQ<23>")
	)
	(segment
		(start 71.321168 -105.824782)
		(end 71.321168 -110.109)
		(width 0.14224)
		(layer "In11.Cu")
		(net "M_M_DQ<23>")
	)
	(segment
		(start 56.499506 -153.04135)
		(end 56.499506 -153.364946)
		(width 0.14224)
		(layer "In11.Cu")
		(net "M_M_DQ<23>")
	)
	(segment
		(start 57.351168 -136.9822)
		(end 57.351168 -137.3124)
		(width 0.14224)
		(layer "In11.Cu")
		(net "M_M_DQ<23>")
	)
	(segment
		(start 57.325768 -146.8628)
		(end 57.020968 -147.1676)
		(width 0.14224)
		(layer "In11.Cu")
		(net "M_M_DQ<23>")
	)
	(segment
		(start 57.503568 -145.542254)
		(end 57.139586 -145.906236)
		(width 0.14224)
		(layer "In11.Cu")
		(net "M_M_DQ<23>")
	)
	(segment
		(start 56.321706 -153.542746)
		(end 56.049418 -153.542746)
		(width 0.14224)
		(layer "In11.Cu")
		(net "M_M_DQ<23>")
	)
	(segment
		(start 71.321168 -110.109)
		(end 70.221348 -111.20882)
		(width 0.14224)
		(layer "In11.Cu")
		(net "M_M_DQ<23>")
	)
	(arc
		(start 76.61021 -97.290636)
		(mid 76.41636 -97.346986)
		(end 76.274676 -97.490788)
		(width 0.0889)
		(layer "In11.Cu")
		(net "M_M_DQ<23>")
	)
	(arc
		(start 77.46492 -96.79559)
		(mid 77.273278 -96.852756)
		(end 77.133196 -96.995488)
		(width 0.0889)
		(layer "In11.Cu")
		(net "M_M_DQ<23>")
	)
	(arc
		(start 73.699116 -100.367084)
		(mid 73.778247 -100.662486)
		(end 73.699116 -100.957888)
		(width 0.0889)
		(layer "In11.Cu")
		(net "M_M_DQ<23>")
	)
	(arc
		(start 74.03084 -98.77679)
		(mid 73.697922 -98.978781)
		(end 73.69429 -99.368102)
		(width 0.0889)
		(layer "In11.Cu")
		(net "M_M_DQ<23>")
	)
	(arc
		(start 75.74788 -97.78619)
		(mid 75.556238 -97.843356)
		(end 75.416156 -97.986088)
		(width 0.0889)
		(layer "In11.Cu")
		(net "M_M_DQ<23>")
	)
	(arc
		(start 73.699116 -100.957888)
		(mid 73.645646 -101.152951)
		(end 73.69429 -101.349302)
		(width 0.0889)
		(layer "In11.Cu")
		(net "M_M_DQ<23>")
	)
	(arc
		(start 74.557636 -98.481388)
		(mid 74.349028 -98.69332)
		(end 74.063606 -98.77679)
		(width 0.0889)
		(layer "In11.Cu")
		(net "M_M_DQ<23>")
	)
	(arc
		(start 73.699116 -99.376738)
		(mid 73.778338 -99.665856)
		(end 73.705466 -99.95662)
		(width 0.0889)
		(layer "In11.Cu")
		(net "M_M_DQ<23>")
	)
	(arc
		(start 79.181706 -95.80499)
		(mid 78.990064 -95.862156)
		(end 78.849982 -96.004888)
		(width 0.0889)
		(layer "In11.Cu")
		(net "M_M_DQ<23>")
	)
	(arc
		(start 78.849982 -96.004888)
		(mid 78.642978 -96.215752)
		(end 78.359762 -96.300036)
		(width 0.0889)
		(layer "In11.Cu")
		(net "M_M_DQ<23>")
	)
	(arc
		(start 74.89317 -98.281236)
		(mid 74.69932 -98.337586)
		(end 74.557636 -98.481388)
		(width 0.0889)
		(layer "In11.Cu")
		(net "M_M_DQ<23>")
	)
	(arc
		(start 76.274676 -97.490788)
		(mid 76.066068 -97.70272)
		(end 75.780646 -97.78619)
		(width 0.0889)
		(layer "In11.Cu")
		(net "M_M_DQ<23>")
	)
	(arc
		(start 77.133196 -96.995488)
		(mid 76.926192 -97.206352)
		(end 76.642976 -97.290636)
		(width 0.0889)
		(layer "In11.Cu")
		(net "M_M_DQ<23>")
	)
	(arc
		(start 75.416156 -97.986088)
		(mid 75.209152 -98.196952)
		(end 74.925936 -98.281236)
		(width 0.0889)
		(layer "In11.Cu")
		(net "M_M_DQ<23>")
	)
	(arc
		(start 78.338172 -96.300036)
		(mid 78.141011 -96.351995)
		(end 77.995018 -96.494346)
		(width 0.0889)
		(layer "In11.Cu")
		(net "M_M_DQ<23>")
	)
	(arc
		(start 73.699116 -99.967288)
		(mid 73.645617 -100.167186)
		(end 73.699116 -100.367084)
		(width 0.0889)
		(layer "In11.Cu")
		(net "M_M_DQ<23>")
	)
	(arc
		(start 77.991716 -96.500188)
		(mid 77.783108 -96.71212)
		(end 77.497686 -96.79559)
		(width 0.0889)
		(layer "In11.Cu")
		(net "M_M_DQ<23>")
	)
	(arc
		(start 79.708502 -95.509588)
		(mid 79.499894 -95.72152)
		(end 79.214472 -95.80499)
		(width 0.0889)
		(layer "In11.Cu")
		(net "M_M_DQ<23>")
	)
	(segment
		(start 56.899556 -156.87294)
		(end 56.899556 -155.9052)
		(width 0.1651)
		(layer "F.Cu")
		(net "M_M_DQ<22>")
	)
	(segment
		(start 57.031636 -155.55468)
		(end 56.899556 -155.4226)
		(width 0.1651)
		(layer "F.Cu")
		(net "M_M_DQ<22>")
	)
	(segment
		(start 57.031636 -155.77312)
		(end 57.031636 -155.55468)
		(width 0.1651)
		(layer "F.Cu")
		(net "M_M_DQ<22>")
	)
	(segment
		(start 82.343752 -93.72854)
		(end 81.772252 -93.72854)
		(width 0.1651)
		(layer "F.Cu")
		(net "M_M_DQ<22>")
	)
	(segment
		(start 56.899556 -155.9052)
		(end 57.031636 -155.77312)
		(width 0.1651)
		(layer "F.Cu")
		(net "M_M_DQ<22>")
	)
	(segment
		(start 56.899556 -155.4226)
		(end 56.899556 -155.118054)
		(width 0.1651)
		(layer "F.Cu")
		(net "M_M_DQ<22>")
	)
	(segment
		(start 56.899556 -155.118054)
		(end 56.899302 -155.1178)
		(width 0.1651)
		(layer "F.Cu")
		(net "M_M_DQ<22>")
	)
	(via
		(at 81.772252 -93.72854)
		(size 0.508)
		(drill 0.254)
		(layers "F.Cu" "B.Cu")
		(net "M_M_DQ<22>")
	)
	(via
		(at 56.899302 -155.1178)
		(size 0.508)
		(drill 0.254)
		(layers "F.Cu" "B.Cu")
		(net "M_M_DQ<22>")
	)
	(via
		(at 56.049418 -150.815294)
		(size 0.508)
		(drill 0.254)
		(layers "F.Cu" "B.Cu")
		(net "M_M_DQ<22>")
	)
	(segment
		(start 56.049418 -152.078436)
		(end 56.049418 -150.815294)
		(width 0.1651)
		(layer "B.Cu")
		(net "M_M_DQ<22>")
	)
	(segment
		(start 56.614568 -141.40434)
		(end 56.487568 -141.53134)
		(width 0.14224)
		(layer "In11.Cu")
		(net "M_M_DQ<22>")
	)
	(segment
		(start 56.617108 -148.59254)
		(end 56.617108 -148.934678)
		(width 0.14224)
		(layer "In11.Cu")
		(net "M_M_DQ<22>")
	)
	(segment
		(start 56.411368 -138.811)
		(end 56.617108 -139.01674)
		(width 0.14224)
		(layer "In11.Cu")
		(net "M_M_DQ<22>")
	)
	(segment
		(start 56.413908 -134.681468)
		(end 56.413908 -136.07034)
		(width 0.14224)
		(layer "In11.Cu")
		(net "M_M_DQ<22>")
	)
	(segment
		(start 68.872354 -110.830614)
		(end 68.584826 -110.830614)
		(width 0.14224)
		(layer "In11.Cu")
		(net "M_M_DQ<22>")
	)
	(segment
		(start 73.597008 -103.018336)
		(end 72.27443 -104.340914)
		(width 0.0889)
		(layer "In11.Cu")
		(net "M_M_DQ<22>")
	)
	(segment
		(start 56.617108 -139.460478)
		(end 56.284368 -139.793218)
		(width 0.14224)
		(layer "In11.Cu")
		(net "M_M_DQ<22>")
	)
	(segment
		(start 56.665368 -136.3218)
		(end 56.665368 -136.652)
		(width 0.14224)
		(layer "In11.Cu")
		(net "M_M_DQ<22>")
	)
	(segment
		(start 68.584826 -110.830614)
		(end 68.504054 -110.749842)
		(width 0.14224)
		(layer "In11.Cu")
		(net "M_M_DQ<22>")
	)
	(segment
		(start 80.072992 -94.31909)
		(end 80.037178 -94.31909)
		(width 0.0889)
		(layer "In11.Cu")
		(net "M_M_DQ<22>")
	)
	(segment
		(start 55.616348 -151.248364)
		(end 55.616348 -153.834846)
		(width 0.14224)
		(layer "In11.Cu")
		(net "M_M_DQ<22>")
	)
	(segment
		(start 69.159628 -110.54334)
		(end 68.872354 -110.830614)
		(width 0.14224)
		(layer "In11.Cu")
		(net "M_M_DQ<22>")
	)
	(segment
		(start 73.534016 -99.872038)
		(end 73.527666 -99.882706)
		(width 0.0889)
		(layer "In11.Cu")
		(net "M_M_DQ<22>")
	)
	(segment
		(start 75.774042 -97.59569)
		(end 75.741276 -97.59569)
		(width 0.0889)
		(layer "In11.Cu")
		(net "M_M_DQ<22>")
	)
	(segment
		(start 56.309768 -131.202938)
		(end 56.515508 -131.408678)
		(width 0.14224)
		(layer "In11.Cu")
		(net "M_M_DQ<22>")
	)
	(segment
		(start 55.880508 -150.646384)
		(end 56.049418 -150.815294)
		(width 0.14224)
		(layer "In11.Cu")
		(net "M_M_DQ<22>")
	)
	(segment
		(start 56.360568 -148.336)
		(end 56.617108 -148.59254)
		(width 0.14224)
		(layer "In11.Cu")
		(net "M_M_DQ<22>")
	)
	(segment
		(start 69.291962 -109.522006)
		(end 69.002656 -109.811312)
		(width 0.14224)
		(layer "In11.Cu")
		(net "M_M_DQ<22>")
	)
	(segment
		(start 56.665368 -136.652)
		(end 56.411368 -136.906)
		(width 0.14224)
		(layer "In11.Cu")
		(net "M_M_DQ<22>")
	)
	(segment
		(start 77.479906 -96.60509)
		(end 77.458316 -96.60509)
		(width 0.0889)
		(layer "In11.Cu")
		(net "M_M_DQ<22>")
	)
	(segment
		(start 74.057002 -98.58629)
		(end 74.024236 -98.58629)
		(width 0.0889)
		(layer "In11.Cu")
		(net "M_M_DQ<22>")
	)
	(segment
		(start 70.230492 -109.023404)
		(end 70.666864 -109.459776)
		(width 0.14224)
		(layer "In11.Cu")
		(net "M_M_DQ<22>")
	)
	(segment
		(start 68.504054 -110.749842)
		(end 68.216526 -110.749842)
		(width 0.14224)
		(layer "In11.Cu")
		(net "M_M_DQ<22>")
	)
	(segment
		(start 56.617108 -139.01674)
		(end 56.617108 -139.460478)
		(width 0.14224)
		(layer "In11.Cu")
		(net "M_M_DQ<22>")
	)
	(segment
		(start 56.411368 -136.906)
		(end 56.411368 -138.811)
		(width 0.14224)
		(layer "In11.Cu")
		(net "M_M_DQ<22>")
	)
	(segment
		(start 72.27443 -104.340914)
		(end 71.906892 -104.340914)
		(width 0.0889)
		(layer "In11.Cu")
		(net "M_M_DQ<22>")
	)
	(segment
		(start 56.639968 -144.045178)
		(end 56.293766 -144.39138)
		(width 0.14224)
		(layer "In11.Cu")
		(net "M_M_DQ<22>")
	)
	(segment
		(start 56.60644 -145.8468)
		(end 56.60644 -146.134328)
		(width 0.14224)
		(layer "In11.Cu")
		(net "M_M_DQ<22>")
	)
	(segment
		(start 73.527666 -101.44252)
		(end 73.534016 -101.453188)
		(width 0.0889)
		(layer "In11.Cu")
		(net "M_M_DQ<22>")
	)
	(segment
		(start 56.049418 -150.815294)
		(end 55.616348 -151.248364)
		(width 0.14224)
		(layer "In11.Cu")
		(net "M_M_DQ<22>")
	)
	(segment
		(start 70.230492 -108.735876)
		(end 70.230492 -109.023404)
		(width 0.14224)
		(layer "In11.Cu")
		(net "M_M_DQ<22>")
	)
	(segment
		(start 56.293766 -145.534126)
		(end 56.60644 -145.8468)
		(width 0.14224)
		(layer "In11.Cu")
		(net "M_M_DQ<22>")
	)
	(segment
		(start 56.60644 -146.134328)
		(end 56.360568 -146.3802)
		(width 0.14224)
		(layer "In11.Cu")
		(net "M_M_DQ<22>")
	)
	(segment
		(start 56.309768 -130.166618)
		(end 56.309768 -131.202938)
		(width 0.14224)
		(layer "In11.Cu")
		(net "M_M_DQ<22>")
	)
	(segment
		(start 73.534016 -101.453188)
		(end 73.597008 -101.548946)
		(width 0.0889)
		(layer "In11.Cu")
		(net "M_M_DQ<22>")
	)
	(segment
		(start 73.597008 -101.548946)
		(end 73.597008 -103.018336)
		(width 0.0889)
		(layer "In11.Cu")
		(net "M_M_DQ<22>")
	)
	(segment
		(start 56.284368 -139.793218)
		(end 56.284368 -140.741146)
		(width 0.14224)
		(layer "In11.Cu")
		(net "M_M_DQ<22>")
	)
	(segment
		(start 55.616348 -153.834846)
		(end 56.899302 -155.1178)
		(width 0.14224)
		(layer "In11.Cu")
		(net "M_M_DQ<22>")
	)
	(segment
		(start 56.919368 -122.047)
		(end 56.919368 -126.8222)
		(width 0.14224)
		(layer "In11.Cu")
		(net "M_M_DQ<22>")
	)
	(segment
		(start 56.267604 -127.473964)
		(end 56.267604 -129.066036)
		(width 0.14224)
		(layer "In11.Cu")
		(net "M_M_DQ<22>")
	)
	(segment
		(start 70.686168 -108.2802)
		(end 70.230492 -108.735876)
		(width 0.14224)
		(layer "In11.Cu")
		(net "M_M_DQ<22>")
	)
	(segment
		(start 56.614568 -141.071346)
		(end 56.614568 -141.40434)
		(width 0.14224)
		(layer "In11.Cu")
		(net "M_M_DQ<22>")
	)
	(segment
		(start 69.159628 -110.255812)
		(end 69.159628 -110.54334)
		(width 0.14224)
		(layer "In11.Cu")
		(net "M_M_DQ<22>")
	)
	(segment
		(start 56.487568 -143.3068)
		(end 56.639968 -143.4592)
		(width 0.14224)
		(layer "In11.Cu")
		(net "M_M_DQ<22>")
	)
	(segment
		(start 56.487568 -141.53134)
		(end 56.487568 -143.3068)
		(width 0.14224)
		(layer "In11.Cu")
		(net "M_M_DQ<22>")
	)
	(segment
		(start 56.267604 -129.066036)
		(end 56.628538 -129.42697)
		(width 0.14224)
		(layer "In11.Cu")
		(net "M_M_DQ<22>")
	)
	(segment
		(start 76.636372 -97.100136)
		(end 76.603606 -97.100136)
		(width 0.0889)
		(layer "In11.Cu")
		(net "M_M_DQ<22>")
	)
	(segment
		(start 69.57949 -109.522006)
		(end 69.291962 -109.522006)
		(width 0.14224)
		(layer "In11.Cu")
		(net "M_M_DQ<22>")
	)
	(segment
		(start 55.880508 -149.671278)
		(end 55.880508 -150.646384)
		(width 0.14224)
		(layer "In11.Cu")
		(net "M_M_DQ<22>")
	)
	(segment
		(start 70.37959 -110.034578)
		(end 70.092062 -110.034578)
		(width 0.14224)
		(layer "In11.Cu")
		(net "M_M_DQ<22>")
	)
	(segment
		(start 56.284368 -140.741146)
		(end 56.614568 -141.071346)
		(width 0.14224)
		(layer "In11.Cu")
		(net "M_M_DQ<22>")
	)
	(segment
		(start 79.708502 -94.518988)
		(end 79.543402 -94.805246)
		(width 0.0889)
		(layer "In11.Cu")
		(net "M_M_DQ<22>")
	)
	(segment
		(start 78.353158 -96.109536)
		(end 78.320392 -96.109536)
		(width 0.0889)
		(layer "In11.Cu")
		(net "M_M_DQ<22>")
	)
	(segment
		(start 70.666864 -109.459776)
		(end 70.666864 -109.747304)
		(width 0.14224)
		(layer "In11.Cu")
		(net "M_M_DQ<22>")
	)
	(segment
		(start 71.906892 -104.340914)
		(end 70.686168 -105.561638)
		(width 0.14224)
		(layer "In11.Cu")
		(net "M_M_DQ<22>")
	)
	(segment
		(start 77.826362 -96.404938)
		(end 77.82306 -96.41078)
		(width 0.0889)
		(layer "In11.Cu")
		(net "M_M_DQ<22>")
	)
	(segment
		(start 56.919368 -126.8222)
		(end 56.267604 -127.473964)
		(width 0.14224)
		(layer "In11.Cu")
		(net "M_M_DQ<22>")
	)
	(segment
		(start 79.207868 -95.61449)
		(end 79.175102 -95.61449)
		(width 0.0889)
		(layer "In11.Cu")
		(net "M_M_DQ<22>")
	)
	(segment
		(start 56.515508 -131.408678)
		(end 56.515508 -134.579868)
		(width 0.14224)
		(layer "In11.Cu")
		(net "M_M_DQ<22>")
	)
	(segment
		(start 70.092062 -110.034578)
		(end 69.57949 -109.522006)
		(width 0.14224)
		(layer "In11.Cu")
		(net "M_M_DQ<22>")
	)
	(segment
		(start 69.002656 -109.811312)
		(end 69.002656 -110.09884)
		(width 0.14224)
		(layer "In11.Cu")
		(net "M_M_DQ<22>")
	)
	(segment
		(start 56.360568 -146.3802)
		(end 56.360568 -148.336)
		(width 0.14224)
		(layer "In11.Cu")
		(net "M_M_DQ<22>")
	)
	(segment
		(start 56.628538 -129.847848)
		(end 56.309768 -130.166618)
		(width 0.14224)
		(layer "In11.Cu")
		(net "M_M_DQ<22>")
	)
	(segment
		(start 56.413908 -136.07034)
		(end 56.665368 -136.3218)
		(width 0.14224)
		(layer "In11.Cu")
		(net "M_M_DQ<22>")
	)
	(segment
		(start 56.293766 -144.39138)
		(end 56.293766 -145.534126)
		(width 0.14224)
		(layer "In11.Cu")
		(net "M_M_DQ<22>")
	)
	(segment
		(start 70.666864 -109.747304)
		(end 70.37959 -110.034578)
		(width 0.14224)
		(layer "In11.Cu")
		(net "M_M_DQ<22>")
	)
	(segment
		(start 74.919332 -98.090736)
		(end 74.886566 -98.090736)
		(width 0.0889)
		(layer "In11.Cu")
		(net "M_M_DQ<22>")
	)
	(segment
		(start 56.628538 -129.42697)
		(end 56.628538 -129.847848)
		(width 0.14224)
		(layer "In11.Cu")
		(net "M_M_DQ<22>")
	)
	(segment
		(start 80.950308 -93.82379)
		(end 80.895698 -93.82379)
		(width 0.0889)
		(layer "In11.Cu")
		(net "M_M_DQ<22>")
	)
	(segment
		(start 69.002656 -110.09884)
		(end 69.159628 -110.255812)
		(width 0.14224)
		(layer "In11.Cu")
		(net "M_M_DQ<22>")
	)
	(segment
		(start 56.617108 -148.934678)
		(end 55.880508 -149.671278)
		(width 0.14224)
		(layer "In11.Cu")
		(net "M_M_DQ<22>")
	)
	(segment
		(start 68.216526 -110.749842)
		(end 56.919368 -122.047)
		(width 0.14224)
		(layer "In11.Cu")
		(net "M_M_DQ<22>")
	)
	(segment
		(start 73.534016 -100.462588)
		(end 73.538842 -100.471224)
		(width 0.0889)
		(layer "In11.Cu")
		(net "M_M_DQ<22>")
	)
	(segment
		(start 56.515508 -134.579868)
		(end 56.413908 -134.681468)
		(width 0.14224)
		(layer "In11.Cu")
		(net "M_M_DQ<22>")
	)
	(segment
		(start 56.639968 -143.4592)
		(end 56.639968 -144.045178)
		(width 0.14224)
		(layer "In11.Cu")
		(net "M_M_DQ<22>")
	)
	(segment
		(start 70.686168 -105.561638)
		(end 70.686168 -108.2802)
		(width 0.14224)
		(layer "In11.Cu")
		(net "M_M_DQ<22>")
	)
	(segment
		(start 81.772252 -93.72854)
		(end 80.950308 -93.82379)
		(width 0.0889)
		(layer "In11.Cu")
		(net "M_M_DQ<22>")
	)
	(arc
		(start 75.251056 -97.890838)
		(mid 75.110977 -98.033574)
		(end 74.919332 -98.090736)
		(width 0.0889)
		(layer "In11.Cu")
		(net "M_M_DQ<22>")
	)
	(arc
		(start 80.567022 -94.023688)
		(mid 80.358414 -94.23562)
		(end 80.072992 -94.31909)
		(width 0.0889)
		(layer "In11.Cu")
		(net "M_M_DQ<22>")
	)
	(arc
		(start 73.534016 -100.862638)
		(mid 73.454794 -101.151756)
		(end 73.527666 -101.44252)
		(width 0.0889)
		(layer "In11.Cu")
		(net "M_M_DQ<22>")
	)
	(arc
		(start 77.458316 -96.60509)
		(mid 77.175099 -96.689371)
		(end 76.968096 -96.900238)
		(width 0.0889)
		(layer "In11.Cu")
		(net "M_M_DQ<22>")
	)
	(arc
		(start 78.684882 -95.909638)
		(mid 78.544803 -96.052374)
		(end 78.353158 -96.109536)
		(width 0.0889)
		(layer "In11.Cu")
		(net "M_M_DQ<22>")
	)
	(arc
		(start 79.543402 -94.805246)
		(mid 79.515341 -94.909784)
		(end 79.543402 -95.014288)
		(width 0.0889)
		(layer "In11.Cu")
		(net "M_M_DQ<22>")
	)
	(arc
		(start 77.82306 -96.41078)
		(mid 77.677094 -96.553179)
		(end 77.479906 -96.60509)
		(width 0.0889)
		(layer "In11.Cu")
		(net "M_M_DQ<22>")
	)
	(arc
		(start 74.392536 -98.386138)
		(mid 74.250853 -98.529942)
		(end 74.057002 -98.58629)
		(width 0.0889)
		(layer "In11.Cu")
		(net "M_M_DQ<22>")
	)
	(arc
		(start 76.603606 -97.100136)
		(mid 76.318182 -97.183603)
		(end 76.109576 -97.395538)
		(width 0.0889)
		(layer "In11.Cu")
		(net "M_M_DQ<22>")
	)
	(arc
		(start 80.037178 -94.31909)
		(mid 79.847249 -94.37696)
		(end 79.708502 -94.518988)
		(width 0.0889)
		(layer "In11.Cu")
		(net "M_M_DQ<22>")
	)
	(arc
		(start 74.024236 -98.58629)
		(mid 73.528759 -98.890733)
		(end 73.534016 -99.472242)
		(width 0.0889)
		(layer "In11.Cu")
		(net "M_M_DQ<22>")
	)
	(arc
		(start 73.534016 -99.472242)
		(mid 73.587515 -99.67214)
		(end 73.534016 -99.872038)
		(width 0.0889)
		(layer "In11.Cu")
		(net "M_M_DQ<22>")
	)
	(arc
		(start 74.886566 -98.090736)
		(mid 74.601142 -98.174203)
		(end 74.392536 -98.386138)
		(width 0.0889)
		(layer "In11.Cu")
		(net "M_M_DQ<22>")
	)
	(arc
		(start 76.968096 -96.900238)
		(mid 76.828017 -97.042974)
		(end 76.636372 -97.100136)
		(width 0.0889)
		(layer "In11.Cu")
		(net "M_M_DQ<22>")
	)
	(arc
		(start 79.175102 -95.61449)
		(mid 78.891885 -95.698771)
		(end 78.684882 -95.909638)
		(width 0.0889)
		(layer "In11.Cu")
		(net "M_M_DQ<22>")
	)
	(arc
		(start 79.543402 -95.014288)
		(mid 79.54615 -95.409755)
		(end 79.207868 -95.61449)
		(width 0.0889)
		(layer "In11.Cu")
		(net "M_M_DQ<22>")
	)
	(arc
		(start 76.109576 -97.395538)
		(mid 75.967893 -97.539342)
		(end 75.774042 -97.59569)
		(width 0.0889)
		(layer "In11.Cu")
		(net "M_M_DQ<22>")
	)
	(arc
		(start 78.320392 -96.109536)
		(mid 78.034968 -96.193003)
		(end 77.826362 -96.404938)
		(width 0.0889)
		(layer "In11.Cu")
		(net "M_M_DQ<22>")
	)
	(arc
		(start 80.895698 -93.82379)
		(mid 80.705769 -93.88166)
		(end 80.567022 -94.023688)
		(width 0.0889)
		(layer "In11.Cu")
		(net "M_M_DQ<22>")
	)
	(arc
		(start 73.527666 -99.882706)
		(mid 73.454868 -100.173469)
		(end 73.534016 -100.462588)
		(width 0.0889)
		(layer "In11.Cu")
		(net "M_M_DQ<22>")
	)
	(arc
		(start 73.538842 -100.471224)
		(mid 73.587597 -100.667576)
		(end 73.534016 -100.862638)
		(width 0.0889)
		(layer "In11.Cu")
		(net "M_M_DQ<22>")
	)
	(arc
		(start 75.741276 -97.59569)
		(mid 75.458059 -97.679971)
		(end 75.251056 -97.890838)
		(width 0.0889)
		(layer "In11.Cu")
		(net "M_M_DQ<22>")
	)
	(segment
		(start 79.768192 -92.24264)
		(end 79.196692 -92.24264)
		(width 0.1651)
		(layer "F.Cu")
		(net "M_M_DQ<21>")
	)
	(segment
		(start 50.099468 -152.273)
		(end 50.099468 -153.542746)
		(width 0.1651)
		(layer "F.Cu")
		(net "M_M_DQ<21>")
	)
	(via
		(at 79.196692 -92.24264)
		(size 0.508)
		(drill 0.254)
		(layers "F.Cu" "B.Cu")
		(net "M_M_DQ<21>")
	)
	(via
		(at 50.099468 -153.542746)
		(size 0.508)
		(drill 0.254)
		(layers "F.Cu" "B.Cu")
		(net "M_M_DQ<21>")
	)
	(via
		(at 50.873152 -149.533356)
		(size 0.508)
		(drill 0.254)
		(layers "F.Cu" "B.Cu")
		(net "M_M_DQ<21>")
	)
	(segment
		(start 50.949352 -149.457156)
		(end 50.873152 -149.533356)
		(width 0.1651)
		(layer "B.Cu")
		(net "M_M_DQ<21>")
	)
	(segment
		(start 50.949352 -147.478496)
		(end 50.949352 -149.457156)
		(width 0.1651)
		(layer "B.Cu")
		(net "M_M_DQ<21>")
	)
	(segment
		(start 77.995018 -92.531946)
		(end 77.991716 -92.537788)
		(width 0.0889)
		(layer "In11.Cu")
		(net "M_M_DQ<21>")
	)
	(segment
		(start 50.371756 -153.542746)
		(end 50.099468 -153.542746)
		(width 0.14224)
		(layer "In11.Cu")
		(net "M_M_DQ<21>")
	)
	(segment
		(start 51.442112 -139.492482)
		(end 51.442112 -140.792962)
		(width 0.14224)
		(layer "In11.Cu")
		(net "M_M_DQ<21>")
	)
	(segment
		(start 52.804568 -125.222)
		(end 51.864768 -126.1618)
		(width 0.14224)
		(layer "In11.Cu")
		(net "M_M_DQ<21>")
	)
	(segment
		(start 50.524156 -153.162254)
		(end 50.524156 -153.390346)
		(width 0.14224)
		(layer "In11.Cu")
		(net "M_M_DQ<21>")
	)
	(segment
		(start 51.410108 -145.579084)
		(end 51.1937 -145.795492)
		(width 0.14224)
		(layer "In11.Cu")
		(net "M_M_DQ<21>")
	)
	(segment
		(start 51.559968 -146.558)
		(end 51.559968 -146.9644)
		(width 0.14224)
		(layer "In11.Cu")
		(net "M_M_DQ<21>")
	)
	(segment
		(start 52.804568 -119.850408)
		(end 52.804568 -125.222)
		(width 0.14224)
		(layer "In11.Cu")
		(net "M_M_DQ<21>")
	)
	(segment
		(start 71.491856 -96.300036)
		(end 71.45909 -96.300036)
		(width 0.0889)
		(layer "In11.Cu")
		(net "M_M_DQ<21>")
	)
	(segment
		(start 51.442112 -140.792962)
		(end 51.215036 -141.020038)
		(width 0.14224)
		(layer "In11.Cu")
		(net "M_M_DQ<21>")
	)
	(segment
		(start 51.215036 -141.409928)
		(end 51.382168 -141.57706)
		(width 0.14224)
		(layer "In11.Cu")
		(net "M_M_DQ<21>")
	)
	(segment
		(start 51.1937 -146.191732)
		(end 51.559968 -146.558)
		(width 0.14224)
		(layer "In11.Cu")
		(net "M_M_DQ<21>")
	)
	(segment
		(start 67.938904 -102.07498)
		(end 66.570098 -103.443786)
		(width 0.14224)
		(layer "In11.Cu")
		(net "M_M_DQ<21>")
	)
	(segment
		(start 74.922126 -94.31909)
		(end 74.886312 -94.31909)
		(width 0.0889)
		(layer "In11.Cu")
		(net "M_M_DQ<21>")
	)
	(segment
		(start 50.260758 -151.755856)
		(end 50.498756 -151.993854)
		(width 0.14224)
		(layer "In11.Cu")
		(net "M_M_DQ<21>")
	)
	(segment
		(start 74.05878 -94.81439)
		(end 74.03084 -94.81439)
		(width 0.0889)
		(layer "In11.Cu")
		(net "M_M_DQ<21>")
	)
	(segment
		(start 51.165252 -136.180576)
		(end 51.165252 -136.648952)
		(width 0.14224)
		(layer "In11.Cu")
		(net "M_M_DQ<21>")
	)
	(segment
		(start 51.215036 -141.020038)
		(end 51.215036 -141.409928)
		(width 0.14224)
		(layer "In11.Cu")
		(net "M_M_DQ<21>")
	)
	(segment
		(start 51.406552 -135.939276)
		(end 51.165252 -136.180576)
		(width 0.14224)
		(layer "In11.Cu")
		(net "M_M_DQ<21>")
	)
	(segment
		(start 51.257708 -149.29866)
		(end 51.023012 -149.533356)
		(width 0.14224)
		(layer "In11.Cu")
		(net "M_M_DQ<21>")
	)
	(segment
		(start 51.215036 -132.107432)
		(end 51.52009 -132.412486)
		(width 0.14224)
		(layer "In11.Cu")
		(net "M_M_DQ<21>")
	)
	(segment
		(start 51.864768 -127.3556)
		(end 51.559968 -127.6604)
		(width 0.14224)
		(layer "In11.Cu")
		(net "M_M_DQ<21>")
	)
	(segment
		(start 51.559968 -146.9644)
		(end 51.229768 -147.2946)
		(width 0.14224)
		(layer "In11.Cu")
		(net "M_M_DQ<21>")
	)
	(segment
		(start 68.90766 -100.75799)
		(end 68.87972 -100.75799)
		(width 0.0889)
		(layer "In11.Cu")
		(net "M_M_DQ<21>")
	)
	(segment
		(start 51.559968 -129.11074)
		(end 51.257708 -129.413)
		(width 0.14224)
		(layer "In11.Cu")
		(net "M_M_DQ<21>")
	)
	(segment
		(start 51.1937 -145.795492)
		(end 51.1937 -146.191732)
		(width 0.14224)
		(layer "In11.Cu")
		(net "M_M_DQ<21>")
	)
	(segment
		(start 51.283108 -134.617968)
		(end 51.406552 -134.741412)
		(width 0.14224)
		(layer "In11.Cu")
		(net "M_M_DQ<21>")
	)
	(segment
		(start 69.406516 -99.872038)
		(end 69.412866 -99.882706)
		(width 0.0889)
		(layer "In11.Cu")
		(net "M_M_DQ<21>")
	)
	(segment
		(start 51.283108 -134.047484)
		(end 51.283108 -134.617968)
		(width 0.14224)
		(layer "In11.Cu")
		(net "M_M_DQ<21>")
	)
	(segment
		(start 50.549556 -151.129746)
		(end 50.260758 -151.418544)
		(width 0.14224)
		(layer "In11.Cu")
		(net "M_M_DQ<21>")
	)
	(segment
		(start 51.215036 -131.50215)
		(end 51.215036 -132.107432)
		(width 0.14224)
		(layer "In11.Cu")
		(net "M_M_DQ<21>")
	)
	(segment
		(start 50.524156 -153.390346)
		(end 50.371756 -153.542746)
		(width 0.14224)
		(layer "In11.Cu")
		(net "M_M_DQ<21>")
	)
	(segment
		(start 51.449224 -130.086354)
		(end 51.449224 -131.267962)
		(width 0.14224)
		(layer "In11.Cu")
		(net "M_M_DQ<21>")
	)
	(segment
		(start 68.547996 -100.957888)
		(end 68.541646 -100.967032)
		(width 0.0889)
		(layer "In11.Cu")
		(net "M_M_DQ<21>")
	)
	(segment
		(start 50.422556 -149.9616)
		(end 50.422556 -150.5204)
		(width 0.14224)
		(layer "In11.Cu")
		(net "M_M_DQ<21>")
	)
	(segment
		(start 78.375256 -92.337636)
		(end 78.338172 -92.337636)
		(width 0.0889)
		(layer "In11.Cu")
		(net "M_M_DQ<21>")
	)
	(segment
		(start 51.52009 -132.412486)
		(end 51.52009 -133.810502)
		(width 0.14224)
		(layer "In11.Cu")
		(net "M_M_DQ<21>")
	)
	(segment
		(start 51.559968 -127.6604)
		(end 51.559968 -129.11074)
		(width 0.14224)
		(layer "In11.Cu")
		(net "M_M_DQ<21>")
	)
	(segment
		(start 73.208896 -95.309436)
		(end 73.17613 -95.309436)
		(width 0.0889)
		(layer "In11.Cu")
		(net "M_M_DQ<21>")
	)
	(segment
		(start 51.410108 -144.398238)
		(end 51.410108 -145.579084)
		(width 0.14224)
		(layer "In11.Cu")
		(net "M_M_DQ<21>")
	)
	(segment
		(start 51.222148 -138.79322)
		(end 51.222148 -139.272518)
		(width 0.14224)
		(layer "In11.Cu")
		(net "M_M_DQ<21>")
	)
	(segment
		(start 77.497686 -92.83319)
		(end 77.46492 -92.83319)
		(width 0.0889)
		(layer "In11.Cu")
		(net "M_M_DQ<21>")
	)
	(segment
		(start 50.422556 -150.5204)
		(end 50.549556 -150.6474)
		(width 0.14224)
		(layer "In11.Cu")
		(net "M_M_DQ<21>")
	)
	(segment
		(start 51.449224 -131.267962)
		(end 51.215036 -131.50215)
		(width 0.14224)
		(layer "In11.Cu")
		(net "M_M_DQ<21>")
	)
	(segment
		(start 51.559968 -148.2344)
		(end 51.257708 -148.53666)
		(width 0.14224)
		(layer "In11.Cu")
		(net "M_M_DQ<21>")
	)
	(segment
		(start 51.406552 -134.741412)
		(end 51.406552 -135.939276)
		(width 0.14224)
		(layer "In11.Cu")
		(net "M_M_DQ<21>")
	)
	(segment
		(start 50.498756 -152.348946)
		(end 50.260758 -152.586944)
		(width 0.14224)
		(layer "In11.Cu")
		(net "M_M_DQ<21>")
	)
	(segment
		(start 79.196692 -92.24264)
		(end 78.375256 -92.337636)
		(width 0.0889)
		(layer "In11.Cu")
		(net "M_M_DQ<21>")
	)
	(segment
		(start 70.629526 -96.79559)
		(end 70.59676 -96.79559)
		(width 0.0889)
		(layer "In11.Cu")
		(net "M_M_DQ<21>")
	)
	(segment
		(start 51.222148 -144.210278)
		(end 51.410108 -144.398238)
		(width 0.14224)
		(layer "In11.Cu")
		(net "M_M_DQ<21>")
	)
	(segment
		(start 51.48453 -138.530838)
		(end 51.222148 -138.79322)
		(width 0.14224)
		(layer "In11.Cu")
		(net "M_M_DQ<21>")
	)
	(segment
		(start 50.260758 -152.586944)
		(end 50.260758 -152.898856)
		(width 0.14224)
		(layer "In11.Cu")
		(net "M_M_DQ<21>")
	)
	(segment
		(start 51.257708 -129.894838)
		(end 51.449224 -130.086354)
		(width 0.14224)
		(layer "In11.Cu")
		(net "M_M_DQ<21>")
	)
	(segment
		(start 76.63434 -93.32849)
		(end 76.61021 -93.32849)
		(width 0.0889)
		(layer "In11.Cu")
		(net "M_M_DQ<21>")
	)
	(segment
		(start 72.346566 -95.80499)
		(end 72.3138 -95.80499)
		(width 0.0889)
		(layer "In11.Cu")
		(net "M_M_DQ<21>")
	)
	(segment
		(start 51.382168 -143.521176)
		(end 51.222148 -143.681196)
		(width 0.14224)
		(layer "In11.Cu")
		(net "M_M_DQ<21>")
	)
	(segment
		(start 51.52009 -133.810502)
		(end 51.283108 -134.047484)
		(width 0.14224)
		(layer "In11.Cu")
		(net "M_M_DQ<21>")
	)
	(segment
		(start 67.938904 -101.712776)
		(end 67.938904 -102.07498)
		(width 0.0889)
		(layer "In11.Cu")
		(net "M_M_DQ<21>")
	)
	(segment
		(start 66.570098 -106.084878)
		(end 52.804568 -119.850408)
		(width 0.14224)
		(layer "In11.Cu")
		(net "M_M_DQ<21>")
	)
	(segment
		(start 50.260758 -152.898856)
		(end 50.524156 -153.162254)
		(width 0.14224)
		(layer "In11.Cu")
		(net "M_M_DQ<21>")
	)
	(segment
		(start 51.382168 -141.57706)
		(end 51.382168 -143.521176)
		(width 0.14224)
		(layer "In11.Cu")
		(net "M_M_DQ<21>")
	)
	(segment
		(start 75.784456 -93.82379)
		(end 75.744832 -93.82379)
		(width 0.0889)
		(layer "In11.Cu")
		(net "M_M_DQ<21>")
	)
	(segment
		(start 51.222148 -139.272518)
		(end 51.442112 -139.492482)
		(width 0.14224)
		(layer "In11.Cu")
		(net "M_M_DQ<21>")
	)
	(segment
		(start 50.873152 -149.533356)
		(end 50.8508 -149.533356)
		(width 0.14224)
		(layer "In11.Cu")
		(net "M_M_DQ<21>")
	)
	(segment
		(start 51.864768 -126.1618)
		(end 51.864768 -127.3556)
		(width 0.14224)
		(layer "In11.Cu")
		(net "M_M_DQ<21>")
	)
	(segment
		(start 69.76618 -97.29089)
		(end 69.74205 -97.29089)
		(width 0.0889)
		(layer "In11.Cu")
		(net "M_M_DQ<21>")
	)
	(segment
		(start 51.229768 -147.2946)
		(end 51.229768 -147.6248)
		(width 0.14224)
		(layer "In11.Cu")
		(net "M_M_DQ<21>")
	)
	(segment
		(start 66.570098 -103.443786)
		(end 66.570098 -106.084878)
		(width 0.14224)
		(layer "In11.Cu")
		(net "M_M_DQ<21>")
	)
	(segment
		(start 51.222148 -143.681196)
		(end 51.222148 -144.210278)
		(width 0.14224)
		(layer "In11.Cu")
		(net "M_M_DQ<21>")
	)
	(segment
		(start 51.257708 -129.413)
		(end 51.257708 -129.894838)
		(width 0.14224)
		(layer "In11.Cu")
		(net "M_M_DQ<21>")
	)
	(segment
		(start 50.260758 -151.418544)
		(end 50.260758 -151.755856)
		(width 0.14224)
		(layer "In11.Cu")
		(net "M_M_DQ<21>")
	)
	(segment
		(start 50.549556 -150.6474)
		(end 50.549556 -151.129746)
		(width 0.14224)
		(layer "In11.Cu")
		(net "M_M_DQ<21>")
	)
	(segment
		(start 51.257708 -148.53666)
		(end 51.257708 -149.29866)
		(width 0.14224)
		(layer "In11.Cu")
		(net "M_M_DQ<21>")
	)
	(segment
		(start 50.8508 -149.533356)
		(end 50.422556 -149.9616)
		(width 0.14224)
		(layer "In11.Cu")
		(net "M_M_DQ<21>")
	)
	(segment
		(start 50.498756 -151.993854)
		(end 50.498756 -152.348946)
		(width 0.14224)
		(layer "In11.Cu")
		(net "M_M_DQ<21>")
	)
	(segment
		(start 51.48453 -136.96823)
		(end 51.48453 -138.530838)
		(width 0.14224)
		(layer "In11.Cu")
		(net "M_M_DQ<21>")
	)
	(segment
		(start 51.165252 -136.648952)
		(end 51.48453 -136.96823)
		(width 0.14224)
		(layer "In11.Cu")
		(net "M_M_DQ<21>")
	)
	(segment
		(start 51.559968 -147.955)
		(end 51.559968 -148.2344)
		(width 0.14224)
		(layer "In11.Cu")
		(net "M_M_DQ<21>")
	)
	(segment
		(start 68.541646 -100.967032)
		(end 68.267072 -101.384608)
		(width 0.0889)
		(layer "In11.Cu")
		(net "M_M_DQ<21>")
	)
	(segment
		(start 51.023012 -149.533356)
		(end 50.873152 -149.533356)
		(width 0.14224)
		(layer "In11.Cu")
		(net "M_M_DQ<21>")
	)
	(segment
		(start 51.229768 -147.6248)
		(end 51.559968 -147.955)
		(width 0.14224)
		(layer "In11.Cu")
		(net "M_M_DQ<21>")
	)
	(segment
		(start 68.267072 -101.384608)
		(end 67.938904 -101.712776)
		(width 0.0889)
		(layer "In11.Cu")
		(net "M_M_DQ<21>")
	)
	(arc
		(start 70.59676 -96.79559)
		(mid 70.405118 -96.852756)
		(end 70.265036 -96.995488)
		(width 0.0889)
		(layer "In11.Cu")
		(net "M_M_DQ<21>")
	)
	(arc
		(start 68.87972 -100.75799)
		(mid 68.688078 -100.815156)
		(end 68.547996 -100.957888)
		(width 0.0889)
		(layer "In11.Cu")
		(net "M_M_DQ<21>")
	)
	(arc
		(start 76.274676 -93.528642)
		(mid 76.067672 -93.739506)
		(end 75.784456 -93.82379)
		(width 0.0889)
		(layer "In11.Cu")
		(net "M_M_DQ<21>")
	)
	(arc
		(start 74.886312 -94.31909)
		(mid 74.696383 -94.37696)
		(end 74.557636 -94.518988)
		(width 0.0889)
		(layer "In11.Cu")
		(net "M_M_DQ<21>")
	)
	(arc
		(start 78.338172 -92.337636)
		(mid 78.141011 -92.389595)
		(end 77.995018 -92.531946)
		(width 0.0889)
		(layer "In11.Cu")
		(net "M_M_DQ<21>")
	)
	(arc
		(start 69.412866 -99.882706)
		(mid 69.406689 -100.462638)
		(end 68.90766 -100.75799)
		(width 0.0889)
		(layer "In11.Cu")
		(net "M_M_DQ<21>")
	)
	(arc
		(start 69.406516 -98.481642)
		(mid 69.353017 -98.68154)
		(end 69.406516 -98.881438)
		(width 0.0889)
		(layer "In11.Cu")
		(net "M_M_DQ<21>")
	)
	(arc
		(start 74.557636 -94.518988)
		(mid 74.346923 -94.732067)
		(end 74.05878 -94.81439)
		(width 0.0889)
		(layer "In11.Cu")
		(net "M_M_DQ<21>")
	)
	(arc
		(start 69.74205 -97.29089)
		(mid 69.403935 -97.495592)
		(end 69.406516 -97.890838)
		(width 0.0889)
		(layer "In11.Cu")
		(net "M_M_DQ<21>")
	)
	(arc
		(start 71.982076 -96.004888)
		(mid 71.775072 -96.215752)
		(end 71.491856 -96.300036)
		(width 0.0889)
		(layer "In11.Cu")
		(net "M_M_DQ<21>")
	)
	(arc
		(start 69.406516 -97.890838)
		(mid 69.485647 -98.18624)
		(end 69.406516 -98.481642)
		(width 0.0889)
		(layer "In11.Cu")
		(net "M_M_DQ<21>")
	)
	(arc
		(start 69.406516 -99.472242)
		(mid 69.353017 -99.67214)
		(end 69.406516 -99.872038)
		(width 0.0889)
		(layer "In11.Cu")
		(net "M_M_DQ<21>")
	)
	(arc
		(start 73.17613 -95.309436)
		(mid 72.98228 -95.365786)
		(end 72.840596 -95.509588)
		(width 0.0889)
		(layer "In11.Cu")
		(net "M_M_DQ<21>")
	)
	(arc
		(start 71.45909 -96.300036)
		(mid 71.26524 -96.356386)
		(end 71.123556 -96.500188)
		(width 0.0889)
		(layer "In11.Cu")
		(net "M_M_DQ<21>")
	)
	(arc
		(start 71.123556 -96.500188)
		(mid 70.914948 -96.71212)
		(end 70.629526 -96.79559)
		(width 0.0889)
		(layer "In11.Cu")
		(net "M_M_DQ<21>")
	)
	(arc
		(start 77.46492 -92.83319)
		(mid 77.273278 -92.890356)
		(end 77.133196 -93.033088)
		(width 0.0889)
		(layer "In11.Cu")
		(net "M_M_DQ<21>")
	)
	(arc
		(start 72.3138 -95.80499)
		(mid 72.122158 -95.862156)
		(end 71.982076 -96.004888)
		(width 0.0889)
		(layer "In11.Cu")
		(net "M_M_DQ<21>")
	)
	(arc
		(start 69.406516 -98.881438)
		(mid 69.485647 -99.17684)
		(end 69.406516 -99.472242)
		(width 0.0889)
		(layer "In11.Cu")
		(net "M_M_DQ<21>")
	)
	(arc
		(start 75.416156 -94.023688)
		(mid 75.207548 -94.23562)
		(end 74.922126 -94.31909)
		(width 0.0889)
		(layer "In11.Cu")
		(net "M_M_DQ<21>")
	)
	(arc
		(start 77.991716 -92.537788)
		(mid 77.783108 -92.74972)
		(end 77.497686 -92.83319)
		(width 0.0889)
		(layer "In11.Cu")
		(net "M_M_DQ<21>")
	)
	(arc
		(start 72.840596 -95.509588)
		(mid 72.631988 -95.72152)
		(end 72.346566 -95.80499)
		(width 0.0889)
		(layer "In11.Cu")
		(net "M_M_DQ<21>")
	)
	(arc
		(start 77.133196 -93.033088)
		(mid 76.922483 -93.246167)
		(end 76.63434 -93.32849)
		(width 0.0889)
		(layer "In11.Cu")
		(net "M_M_DQ<21>")
	)
	(arc
		(start 74.03084 -94.81439)
		(mid 73.839198 -94.871556)
		(end 73.699116 -95.014288)
		(width 0.0889)
		(layer "In11.Cu")
		(net "M_M_DQ<21>")
	)
	(arc
		(start 76.61021 -93.32849)
		(mid 76.41636 -93.38484)
		(end 76.274676 -93.528642)
		(width 0.0889)
		(layer "In11.Cu")
		(net "M_M_DQ<21>")
	)
	(arc
		(start 75.744832 -93.82379)
		(mid 75.554903 -93.88166)
		(end 75.416156 -94.023688)
		(width 0.0889)
		(layer "In11.Cu")
		(net "M_M_DQ<21>")
	)
	(arc
		(start 70.265036 -96.995488)
		(mid 70.054323 -97.208567)
		(end 69.76618 -97.29089)
		(width 0.0889)
		(layer "In11.Cu")
		(net "M_M_DQ<21>")
	)
	(arc
		(start 73.699116 -95.014288)
		(mid 73.492112 -95.225152)
		(end 73.208896 -95.309436)
		(width 0.0889)
		(layer "In11.Cu")
		(net "M_M_DQ<21>")
	)
	(segment
		(start 80.626712 -91.747086)
		(end 80.055212 -91.747086)
		(width 0.1651)
		(layer "F.Cu")
		(net "M_M_DQ<20>")
	)
	(segment
		(start 50.949352 -155.547568)
		(end 50.851308 -155.0162)
		(width 0.1651)
		(layer "F.Cu")
		(net "M_M_DQ<20>")
	)
	(segment
		(start 50.949352 -156.87294)
		(end 50.949352 -155.547568)
		(width 0.1651)
		(layer "F.Cu")
		(net "M_M_DQ<20>")
	)
	(via
		(at 50.099468 -150.814278)
		(size 0.508)
		(drill 0.254)
		(layers "F.Cu" "B.Cu")
		(net "M_M_DQ<20>")
	)
	(via
		(at 80.055212 -91.747086)
		(size 0.508)
		(drill 0.254)
		(layers "F.Cu" "B.Cu")
		(net "M_M_DQ<20>")
	)
	(via
		(at 50.851308 -155.0162)
		(size 0.508)
		(drill 0.254)
		(layers "F.Cu" "B.Cu")
		(net "M_M_DQ<20>")
	)
	(segment
		(start 50.099468 -152.078436)
		(end 50.099468 -150.814278)
		(width 0.1651)
		(layer "B.Cu")
		(net "M_M_DQ<20>")
	)
	(segment
		(start 71.485252 -96.109536)
		(end 71.452486 -96.109536)
		(width 0.0889)
		(layer "In11.Cu")
		(net "M_M_DQ<20>")
	)
	(segment
		(start 50.597562 -139.358624)
		(end 50.399442 -139.556744)
		(width 0.14224)
		(layer "In11.Cu")
		(net "M_M_DQ<20>")
	)
	(segment
		(start 67.487546 -101.623622)
		(end 66.091308 -103.01986)
		(width 0.14224)
		(layer "In11.Cu")
		(net "M_M_DQ<20>")
	)
	(segment
		(start 50.537618 -145.734278)
		(end 50.537618 -148.45665)
		(width 0.14224)
		(layer "In11.Cu")
		(net "M_M_DQ<20>")
	)
	(segment
		(start 50.518568 -134.0612)
		(end 50.569876 -134.112508)
		(width 0.14224)
		(layer "In11.Cu")
		(net "M_M_DQ<20>")
	)
	(segment
		(start 66.091308 -103.01986)
		(end 66.091308 -105.665524)
		(width 0.14224)
		(layer "In11.Cu")
		(net "M_M_DQ<20>")
	)
	(segment
		(start 50.395378 -144.267936)
		(end 50.395378 -145.592038)
		(width 0.14224)
		(layer "In11.Cu")
		(net "M_M_DQ<20>")
	)
	(segment
		(start 50.620168 -127.381)
		(end 50.620168 -129.744978)
		(width 0.14224)
		(layer "In11.Cu")
		(net "M_M_DQ<20>")
	)
	(segment
		(start 69.768212 -97.100136)
		(end 69.740272 -97.100136)
		(width 0.0889)
		(layer "In11.Cu")
		(net "M_M_DQ<20>")
	)
	(segment
		(start 50.584608 -148.50364)
		(end 50.584608 -148.960078)
		(width 0.14224)
		(layer "In11.Cu")
		(net "M_M_DQ<20>")
	)
	(segment
		(start 51.204368 -126.7968)
		(end 50.620168 -127.381)
		(width 0.14224)
		(layer "In11.Cu")
		(net "M_M_DQ<20>")
	)
	(segment
		(start 68.382896 -100.862638)
		(end 68.11899 -101.263958)
		(width 0.0889)
		(layer "In11.Cu")
		(net "M_M_DQ<20>")
	)
	(segment
		(start 66.091308 -105.665524)
		(end 52.144168 -119.612664)
		(width 0.14224)
		(layer "In11.Cu")
		(net "M_M_DQ<20>")
	)
	(segment
		(start 50.518568 -138.7348)
		(end 50.597562 -138.813794)
		(width 0.14224)
		(layer "In11.Cu")
		(net "M_M_DQ<20>")
	)
	(segment
		(start 74.92238 -94.128336)
		(end 74.882756 -94.128336)
		(width 0.0889)
		(layer "In11.Cu")
		(net "M_M_DQ<20>")
	)
	(segment
		(start 73.202292 -95.118936)
		(end 73.169526 -95.118936)
		(width 0.0889)
		(layer "In11.Cu")
		(net "M_M_DQ<20>")
	)
	(segment
		(start 50.584608 -148.960078)
		(end 49.991518 -149.553168)
		(width 0.14224)
		(layer "In11.Cu")
		(net "M_M_DQ<20>")
	)
	(segment
		(start 50.419762 -131.231132)
		(end 50.537872 -131.349242)
		(width 0.14224)
		(layer "In11.Cu")
		(net "M_M_DQ<20>")
	)
	(segment
		(start 52.144168 -119.612664)
		(end 52.144168 -124.9172)
		(width 0.14224)
		(layer "In11.Cu")
		(net "M_M_DQ<20>")
	)
	(segment
		(start 50.399442 -139.556744)
		(end 50.399442 -140.812012)
		(width 0.14224)
		(layer "In11.Cu")
		(net "M_M_DQ<20>")
	)
	(segment
		(start 74.057002 -94.623636)
		(end 74.032872 -94.623636)
		(width 0.0889)
		(layer "In11.Cu")
		(net "M_M_DQ<20>")
	)
	(segment
		(start 50.419762 -129.945384)
		(end 50.419762 -131.231132)
		(width 0.14224)
		(layer "In11.Cu")
		(net "M_M_DQ<20>")
	)
	(segment
		(start 50.518568 -136.65454)
		(end 50.518568 -138.7348)
		(width 0.14224)
		(layer "In11.Cu")
		(net "M_M_DQ<20>")
	)
	(segment
		(start 50.575972 -136.597136)
		(end 50.518568 -136.65454)
		(width 0.14224)
		(layer "In11.Cu")
		(net "M_M_DQ<20>")
	)
	(segment
		(start 50.597562 -138.813794)
		(end 50.597562 -139.358624)
		(width 0.14224)
		(layer "In11.Cu")
		(net "M_M_DQ<20>")
	)
	(segment
		(start 49.991518 -149.553168)
		(end 49.991518 -150.706328)
		(width 0.14224)
		(layer "In11.Cu")
		(net "M_M_DQ<20>")
	)
	(segment
		(start 50.395378 -145.592038)
		(end 50.537618 -145.734278)
		(width 0.14224)
		(layer "In11.Cu")
		(net "M_M_DQ<20>")
	)
	(segment
		(start 50.569876 -134.112508)
		(end 50.569876 -134.517892)
		(width 0.14224)
		(layer "In11.Cu")
		(net "M_M_DQ<20>")
	)
	(segment
		(start 69.235066 -99.95662)
		(end 69.241416 -99.967288)
		(width 0.0889)
		(layer "In11.Cu")
		(net "M_M_DQ<20>")
	)
	(segment
		(start 49.666398 -153.78049)
		(end 49.824386 -153.938478)
		(width 0.14224)
		(layer "In11.Cu")
		(net "M_M_DQ<20>")
	)
	(segment
		(start 49.824386 -153.938478)
		(end 49.824386 -154.24023)
		(width 0.14224)
		(layer "In11.Cu")
		(net "M_M_DQ<20>")
	)
	(segment
		(start 50.620168 -129.744978)
		(end 50.419762 -129.945384)
		(width 0.14224)
		(layer "In11.Cu")
		(net "M_M_DQ<20>")
	)
	(segment
		(start 50.575972 -136.158732)
		(end 50.575972 -136.597136)
		(width 0.14224)
		(layer "In11.Cu")
		(net "M_M_DQ<20>")
	)
	(segment
		(start 76.636372 -93.137736)
		(end 76.608432 -93.137736)
		(width 0.0889)
		(layer "In11.Cu")
		(net "M_M_DQ<20>")
	)
	(segment
		(start 50.558954 -143.753586)
		(end 50.594514 -143.789146)
		(width 0.14224)
		(layer "In11.Cu")
		(net "M_M_DQ<20>")
	)
	(segment
		(start 68.11899 -101.263958)
		(end 67.759326 -101.623622)
		(width 0.0889)
		(layer "In11.Cu")
		(net "M_M_DQ<20>")
	)
	(segment
		(start 49.666398 -151.247348)
		(end 49.666398 -153.78049)
		(width 0.14224)
		(layer "In11.Cu")
		(net "M_M_DQ<20>")
	)
	(segment
		(start 50.569876 -134.517892)
		(end 50.368708 -134.71906)
		(width 0.14224)
		(layer "In11.Cu")
		(net "M_M_DQ<20>")
	)
	(segment
		(start 50.600356 -155.0162)
		(end 50.851308 -155.0162)
		(width 0.14224)
		(layer "In11.Cu")
		(net "M_M_DQ<20>")
	)
	(segment
		(start 50.537618 -148.45665)
		(end 50.584608 -148.50364)
		(width 0.14224)
		(layer "In11.Cu")
		(net "M_M_DQ<20>")
	)
	(segment
		(start 51.204368 -125.857)
		(end 51.204368 -126.7968)
		(width 0.14224)
		(layer "In11.Cu")
		(net "M_M_DQ<20>")
	)
	(segment
		(start 52.144168 -124.9172)
		(end 51.204368 -125.857)
		(width 0.14224)
		(layer "In11.Cu")
		(net "M_M_DQ<20>")
	)
	(segment
		(start 49.824386 -154.24023)
		(end 50.600356 -155.0162)
		(width 0.14224)
		(layer "In11.Cu")
		(net "M_M_DQ<20>")
	)
	(segment
		(start 50.537872 -131.936236)
		(end 50.518568 -131.95554)
		(width 0.14224)
		(layer "In11.Cu")
		(net "M_M_DQ<20>")
	)
	(segment
		(start 50.518568 -131.95554)
		(end 50.518568 -134.0612)
		(width 0.14224)
		(layer "In11.Cu")
		(net "M_M_DQ<20>")
	)
	(segment
		(start 50.594514 -143.789146)
		(end 50.594514 -144.0688)
		(width 0.14224)
		(layer "In11.Cu")
		(net "M_M_DQ<20>")
	)
	(segment
		(start 80.055212 -91.747086)
		(end 79.23276 -91.84259)
		(width 0.0889)
		(layer "In11.Cu")
		(net "M_M_DQ<20>")
	)
	(segment
		(start 72.339962 -95.61449)
		(end 72.307196 -95.61449)
		(width 0.0889)
		(layer "In11.Cu")
		(net "M_M_DQ<20>")
	)
	(segment
		(start 50.399442 -140.812012)
		(end 50.558954 -140.971524)
		(width 0.14224)
		(layer "In11.Cu")
		(net "M_M_DQ<20>")
	)
	(segment
		(start 75.7809 -93.633036)
		(end 75.745086 -93.633036)
		(width 0.0889)
		(layer "In11.Cu")
		(net "M_M_DQ<20>")
	)
	(segment
		(start 50.099468 -150.814278)
		(end 49.666398 -151.247348)
		(width 0.14224)
		(layer "In11.Cu")
		(net "M_M_DQ<20>")
	)
	(segment
		(start 49.991518 -150.706328)
		(end 50.099468 -150.814278)
		(width 0.14224)
		(layer "In11.Cu")
		(net "M_M_DQ<20>")
	)
	(segment
		(start 77.479906 -92.64269)
		(end 77.458316 -92.64269)
		(width 0.0889)
		(layer "In11.Cu")
		(net "M_M_DQ<20>")
	)
	(segment
		(start 67.759326 -101.623622)
		(end 67.487546 -101.623622)
		(width 0.0889)
		(layer "In11.Cu")
		(net "M_M_DQ<20>")
	)
	(segment
		(start 50.368708 -134.71906)
		(end 50.368708 -135.951468)
		(width 0.14224)
		(layer "In11.Cu")
		(net "M_M_DQ<20>")
	)
	(segment
		(start 50.368708 -135.951468)
		(end 50.575972 -136.158732)
		(width 0.14224)
		(layer "In11.Cu")
		(net "M_M_DQ<20>")
	)
	(segment
		(start 77.826362 -92.442538)
		(end 77.82306 -92.44838)
		(width 0.0889)
		(layer "In11.Cu")
		(net "M_M_DQ<20>")
	)
	(segment
		(start 68.905882 -100.567236)
		(end 68.881752 -100.567236)
		(width 0.0889)
		(layer "In11.Cu")
		(net "M_M_DQ<20>")
	)
	(segment
		(start 78.353158 -92.147136)
		(end 78.320392 -92.147136)
		(width 0.0889)
		(layer "In11.Cu")
		(net "M_M_DQ<20>")
	)
	(segment
		(start 50.537872 -131.349242)
		(end 50.537872 -131.936236)
		(width 0.14224)
		(layer "In11.Cu")
		(net "M_M_DQ<20>")
	)
	(segment
		(start 79.23276 -91.84259)
		(end 78.866238 -91.84259)
		(width 0.0889)
		(layer "In11.Cu")
		(net "M_M_DQ<20>")
	)
	(segment
		(start 50.594514 -144.0688)
		(end 50.395378 -144.267936)
		(width 0.14224)
		(layer "In11.Cu")
		(net "M_M_DQ<20>")
	)
	(segment
		(start 70.622922 -96.60509)
		(end 70.590156 -96.60509)
		(width 0.0889)
		(layer "In11.Cu")
		(net "M_M_DQ<20>")
	)
	(segment
		(start 50.558954 -140.971524)
		(end 50.558954 -143.753586)
		(width 0.14224)
		(layer "In11.Cu")
		(net "M_M_DQ<20>")
	)
	(arc
		(start 74.882756 -94.128336)
		(mid 74.599539 -94.212617)
		(end 74.392536 -94.423484)
		(width 0.0889)
		(layer "In11.Cu")
		(net "M_M_DQ<20>")
	)
	(arc
		(start 76.608432 -93.137736)
		(mid 76.320287 -93.220055)
		(end 76.109576 -93.433138)
		(width 0.0889)
		(layer "In11.Cu")
		(net "M_M_DQ<20>")
	)
	(arc
		(start 71.452486 -96.109536)
		(mid 71.167062 -96.193003)
		(end 70.958456 -96.404938)
		(width 0.0889)
		(layer "In11.Cu")
		(net "M_M_DQ<20>")
	)
	(arc
		(start 78.684882 -91.947238)
		(mid 78.544803 -92.089974)
		(end 78.353158 -92.147136)
		(width 0.0889)
		(layer "In11.Cu")
		(net "M_M_DQ<20>")
	)
	(arc
		(start 72.675496 -95.414338)
		(mid 72.533813 -95.558142)
		(end 72.339962 -95.61449)
		(width 0.0889)
		(layer "In11.Cu")
		(net "M_M_DQ<20>")
	)
	(arc
		(start 77.458316 -92.64269)
		(mid 77.175099 -92.726971)
		(end 76.968096 -92.937838)
		(width 0.0889)
		(layer "In11.Cu")
		(net "M_M_DQ<20>")
	)
	(arc
		(start 70.590156 -96.60509)
		(mid 70.306939 -96.689371)
		(end 70.099936 -96.900238)
		(width 0.0889)
		(layer "In11.Cu")
		(net "M_M_DQ<20>")
	)
	(arc
		(start 69.241416 -99.967288)
		(mid 69.243999 -100.362535)
		(end 68.905882 -100.567236)
		(width 0.0889)
		(layer "In11.Cu")
		(net "M_M_DQ<20>")
	)
	(arc
		(start 76.109576 -93.433138)
		(mid 75.970832 -93.575171)
		(end 75.7809 -93.633036)
		(width 0.0889)
		(layer "In11.Cu")
		(net "M_M_DQ<20>")
	)
	(arc
		(start 75.745086 -93.633036)
		(mid 75.459662 -93.716503)
		(end 75.251056 -93.928438)
		(width 0.0889)
		(layer "In11.Cu")
		(net "M_M_DQ<20>")
	)
	(arc
		(start 69.241416 -98.386138)
		(mid 69.162285 -98.68154)
		(end 69.241416 -98.976942)
		(width 0.0889)
		(layer "In11.Cu")
		(net "M_M_DQ<20>")
	)
	(arc
		(start 73.534016 -94.919038)
		(mid 73.393937 -95.061774)
		(end 73.202292 -95.118936)
		(width 0.0889)
		(layer "In11.Cu")
		(net "M_M_DQ<20>")
	)
	(arc
		(start 69.740272 -97.100136)
		(mid 69.238263 -97.40106)
		(end 69.241416 -97.986342)
		(width 0.0889)
		(layer "In11.Cu")
		(net "M_M_DQ<20>")
	)
	(arc
		(start 69.241416 -99.376738)
		(mid 69.162194 -99.665856)
		(end 69.235066 -99.95662)
		(width 0.0889)
		(layer "In11.Cu")
		(net "M_M_DQ<20>")
	)
	(arc
		(start 78.320392 -92.147136)
		(mid 78.034968 -92.230603)
		(end 77.826362 -92.442538)
		(width 0.0889)
		(layer "In11.Cu")
		(net "M_M_DQ<20>")
	)
	(arc
		(start 69.241416 -98.976942)
		(mid 69.294915 -99.17684)
		(end 69.241416 -99.376738)
		(width 0.0889)
		(layer "In11.Cu")
		(net "M_M_DQ<20>")
	)
	(arc
		(start 74.032872 -94.623636)
		(mid 73.744727 -94.705955)
		(end 73.534016 -94.919038)
		(width 0.0889)
		(layer "In11.Cu")
		(net "M_M_DQ<20>")
	)
	(arc
		(start 69.241416 -97.986342)
		(mid 69.294915 -98.18624)
		(end 69.241416 -98.386138)
		(width 0.0889)
		(layer "In11.Cu")
		(net "M_M_DQ<20>")
	)
	(arc
		(start 73.169526 -95.118936)
		(mid 72.884102 -95.202403)
		(end 72.675496 -95.414338)
		(width 0.0889)
		(layer "In11.Cu")
		(net "M_M_DQ<20>")
	)
	(arc
		(start 68.881752 -100.567236)
		(mid 68.593607 -100.649555)
		(end 68.382896 -100.862638)
		(width 0.0889)
		(layer "In11.Cu")
		(net "M_M_DQ<20>")
	)
	(arc
		(start 75.251056 -93.928438)
		(mid 75.112312 -94.070471)
		(end 74.92238 -94.128336)
		(width 0.0889)
		(layer "In11.Cu")
		(net "M_M_DQ<20>")
	)
	(arc
		(start 76.968096 -92.937838)
		(mid 76.828017 -93.080574)
		(end 76.636372 -93.137736)
		(width 0.0889)
		(layer "In11.Cu")
		(net "M_M_DQ<20>")
	)
	(arc
		(start 74.392536 -94.423484)
		(mid 74.250853 -94.567288)
		(end 74.057002 -94.623636)
		(width 0.0889)
		(layer "In11.Cu")
		(net "M_M_DQ<20>")
	)
	(arc
		(start 77.82306 -92.44838)
		(mid 77.677094 -92.590779)
		(end 77.479906 -92.64269)
		(width 0.0889)
		(layer "In11.Cu")
		(net "M_M_DQ<20>")
	)
	(arc
		(start 71.816976 -95.909638)
		(mid 71.676897 -96.052374)
		(end 71.485252 -96.109536)
		(width 0.0889)
		(layer "In11.Cu")
		(net "M_M_DQ<20>")
	)
	(arc
		(start 72.307196 -95.61449)
		(mid 72.023979 -95.698771)
		(end 71.816976 -95.909638)
		(width 0.0889)
		(layer "In11.Cu")
		(net "M_M_DQ<20>")
	)
	(arc
		(start 78.866238 -91.84259)
		(mid 78.761537 -91.870622)
		(end 78.684882 -91.947238)
		(width 0.0889)
		(layer "In11.Cu")
		(net "M_M_DQ<20>")
	)
	(arc
		(start 70.099936 -96.900238)
		(mid 69.959857 -97.042974)
		(end 69.768212 -97.100136)
		(width 0.0889)
		(layer "In11.Cu")
		(net "M_M_DQ<20>")
	)
	(arc
		(start 70.958456 -96.404938)
		(mid 70.816773 -96.548742)
		(end 70.622922 -96.60509)
		(width 0.0889)
		(layer "In11.Cu")
		(net "M_M_DQ<20>")
	)
	(segment
		(start 76.334366 -85.30844)
		(end 75.762866 -85.30844)
		(width 0.1651)
		(layer "F.Cu")
		(net "M_M_DQ<1>")
	)
	(segment
		(start 33.099502 -152.273)
		(end 33.099502 -153.542746)
		(width 0.1651)
		(layer "F.Cu")
		(net "M_M_DQ<1>")
	)
	(via
		(at 33.771586 -149.533356)
		(size 0.508)
		(drill 0.254)
		(layers "F.Cu" "B.Cu")
		(net "M_M_DQ<1>")
	)
	(via
		(at 75.762866 -85.30844)
		(size 0.508)
		(drill 0.254)
		(layers "F.Cu" "B.Cu")
		(net "M_M_DQ<1>")
	)
	(via
		(at 33.099502 -153.542746)
		(size 0.508)
		(drill 0.254)
		(layers "F.Cu" "B.Cu")
		(net "M_M_DQ<1>")
	)
	(segment
		(start 33.949386 -147.478496)
		(end 33.949386 -148.852382)
		(width 0.1651)
		(layer "B.Cu")
		(net "M_M_DQ<1>")
	)
	(segment
		(start 33.771586 -149.030182)
		(end 33.771586 -149.533356)
		(width 0.1651)
		(layer "B.Cu")
		(net "M_M_DQ<1>")
	)
	(segment
		(start 33.949386 -148.852382)
		(end 33.771586 -149.030182)
		(width 0.1651)
		(layer "B.Cu")
		(net "M_M_DQ<1>")
	)
	(segment
		(start 34.592768 -117.1702)
		(end 34.592768 -117.5766)
		(width 0.14224)
		(layer "In11.Cu")
		(net "M_M_DQ<1>")
	)
	(segment
		(start 62.628018 -87.611712)
		(end 52.158138 -98.081592)
		(width 0.14224)
		(layer "In11.Cu")
		(net "M_M_DQ<1>")
	)
	(segment
		(start 34.364168 -129.1336)
		(end 34.25952 -129.238248)
		(width 0.14224)
		(layer "In11.Cu")
		(net "M_M_DQ<1>")
	)
	(segment
		(start 66.163952 -87.398606)
		(end 64.472312 -87.398606)
		(width 0.0889)
		(layer "In11.Cu")
		(net "M_M_DQ<1>")
	)
	(segment
		(start 34.25952 -146.2024)
		(end 34.364168 -146.307048)
		(width 0.14224)
		(layer "In11.Cu")
		(net "M_M_DQ<1>")
	)
	(segment
		(start 34.364168 -128.737868)
		(end 34.364168 -129.1336)
		(width 0.14224)
		(layer "In11.Cu")
		(net "M_M_DQ<1>")
	)
	(segment
		(start 34.209228 -127.770128)
		(end 33.901888 -127.770128)
		(width 0.14224)
		(layer "In11.Cu")
		(net "M_M_DQ<1>")
	)
	(segment
		(start 34.25952 -129.238248)
		(end 34.25952 -131.797552)
		(width 0.14224)
		(layer "In11.Cu")
		(net "M_M_DQ<1>")
	)
	(segment
		(start 66.645536 -87.88019)
		(end 66.163952 -87.398606)
		(width 0.0889)
		(layer "In11.Cu")
		(net "M_M_DQ<1>")
	)
	(segment
		(start 33.500568 -153.3906)
		(end 33.348422 -153.542746)
		(width 0.14224)
		(layer "In11.Cu")
		(net "M_M_DQ<1>")
	)
	(segment
		(start 64.259206 -87.611712)
		(end 62.628018 -87.611712)
		(width 0.14224)
		(layer "In11.Cu")
		(net "M_M_DQ<1>")
	)
	(segment
		(start 35.761168 -112.8268)
		(end 35.583368 -113.0046)
		(width 0.14224)
		(layer "In11.Cu")
		(net "M_M_DQ<1>")
	)
	(segment
		(start 68.057776 -87.384636)
		(end 68.02501 -87.384636)
		(width 0.0889)
		(layer "In11.Cu")
		(net "M_M_DQ<1>")
	)
	(segment
		(start 34.25952 -148.364448)
		(end 34.25952 -148.956522)
		(width 0.14224)
		(layer "In11.Cu")
		(net "M_M_DQ<1>")
	)
	(segment
		(start 33.348422 -153.542746)
		(end 33.099502 -153.542746)
		(width 0.14224)
		(layer "In11.Cu")
		(net "M_M_DQ<1>")
	)
	(segment
		(start 34.25952 -136.572752)
		(end 34.389568 -136.7028)
		(width 0.14224)
		(layer "In11.Cu")
		(net "M_M_DQ<1>")
	)
	(segment
		(start 34.211768 -116.7892)
		(end 34.592768 -117.1702)
		(width 0.14224)
		(layer "In11.Cu")
		(net "M_M_DQ<1>")
	)
	(segment
		(start 74.060812 -83.91779)
		(end 74.03084 -83.91779)
		(width 0.0889)
		(layer "In11.Cu")
		(net "M_M_DQ<1>")
	)
	(segment
		(start 39.850568 -108.051854)
		(end 35.761168 -112.141254)
		(width 0.14224)
		(layer "In11.Cu")
		(net "M_M_DQ<1>")
	)
	(segment
		(start 34.364168 -146.307048)
		(end 34.364168 -148.2598)
		(width 0.14224)
		(layer "In11.Cu")
		(net "M_M_DQ<1>")
	)
	(segment
		(start 34.211768 -126.8222)
		(end 34.364168 -126.9746)
		(width 0.14224)
		(layer "In11.Cu")
		(net "M_M_DQ<1>")
	)
	(segment
		(start 33.551368 -151.026368)
		(end 33.260792 -151.316944)
		(width 0.14224)
		(layer "In11.Cu")
		(net "M_M_DQ<1>")
	)
	(segment
		(start 34.211768 -117.9576)
		(end 34.211768 -126.8222)
		(width 0.14224)
		(layer "In11.Cu")
		(net "M_M_DQ<1>")
	)
	(segment
		(start 34.389568 -133.985)
		(end 34.25952 -134.115048)
		(width 0.14224)
		(layer "In11.Cu")
		(net "M_M_DQ<1>")
	)
	(segment
		(start 33.771586 -149.533356)
		(end 33.749234 -149.533356)
		(width 0.14224)
		(layer "In11.Cu")
		(net "M_M_DQ<1>")
	)
	(segment
		(start 34.389568 -138.7094)
		(end 34.25952 -138.839448)
		(width 0.14224)
		(layer "In11.Cu")
		(net "M_M_DQ<1>")
	)
	(segment
		(start 34.25952 -148.956522)
		(end 33.771586 -149.444456)
		(width 0.14224)
		(layer "In11.Cu")
		(net "M_M_DQ<1>")
	)
	(segment
		(start 75.26782 -84.642452)
		(end 75.251056 -84.612988)
		(width 0.0889)
		(layer "In11.Cu")
		(net "M_M_DQ<1>")
	)
	(segment
		(start 52.158138 -98.081592)
		(end 52.158138 -98.809556)
		(width 0.14224)
		(layer "In11.Cu")
		(net "M_M_DQ<1>")
	)
	(segment
		(start 34.211768 -113.2332)
		(end 34.211768 -113.860072)
		(width 0.14224)
		(layer "In11.Cu")
		(net "M_M_DQ<1>")
	)
	(segment
		(start 34.389568 -136.7028)
		(end 34.389568 -138.7094)
		(width 0.14224)
		(layer "In11.Cu")
		(net "M_M_DQ<1>")
	)
	(segment
		(start 39.850568 -107.518454)
		(end 39.850568 -108.051854)
		(width 0.14224)
		(layer "In11.Cu")
		(net "M_M_DQ<1>")
	)
	(segment
		(start 52.158138 -98.809556)
		(end 48.821594 -102.1461)
		(width 0.14224)
		(layer "In11.Cu")
		(net "M_M_DQ<1>")
	)
	(segment
		(start 33.32099 -150.391368)
		(end 33.551368 -150.621746)
		(width 0.14224)
		(layer "In11.Cu")
		(net "M_M_DQ<1>")
	)
	(segment
		(start 72.346566 -84.90839)
		(end 72.3138 -84.90839)
		(width 0.0889)
		(layer "In11.Cu")
		(net "M_M_DQ<1>")
	)
	(segment
		(start 33.260792 -152.538176)
		(end 33.260792 -152.846024)
		(width 0.14224)
		(layer "In11.Cu")
		(net "M_M_DQ<1>")
	)
	(segment
		(start 34.364168 -148.2598)
		(end 34.25952 -148.364448)
		(width 0.14224)
		(layer "In11.Cu")
		(net "M_M_DQ<1>")
	)
	(segment
		(start 33.260792 -151.677624)
		(end 33.475168 -151.892)
		(width 0.14224)
		(layer "In11.Cu")
		(net "M_M_DQ<1>")
	)
	(segment
		(start 33.500568 -153.0858)
		(end 33.500568 -153.3906)
		(width 0.14224)
		(layer "In11.Cu")
		(net "M_M_DQ<1>")
	)
	(segment
		(start 43.571668 -102.1461)
		(end 43.1038 -102.613968)
		(width 0.14224)
		(layer "In11.Cu")
		(net "M_M_DQ<1>")
	)
	(segment
		(start 34.25952 -143.741648)
		(end 34.25952 -146.2024)
		(width 0.14224)
		(layer "In11.Cu")
		(net "M_M_DQ<1>")
	)
	(segment
		(start 34.25952 -131.797552)
		(end 34.389568 -131.9276)
		(width 0.14224)
		(layer "In11.Cu")
		(net "M_M_DQ<1>")
	)
	(segment
		(start 73.208896 -84.412836)
		(end 73.17613 -84.412836)
		(width 0.0889)
		(layer "In11.Cu")
		(net "M_M_DQ<1>")
	)
	(segment
		(start 70.629526 -85.89899)
		(end 70.59676 -85.89899)
		(width 0.0889)
		(layer "In11.Cu")
		(net "M_M_DQ<1>")
	)
	(segment
		(start 33.32099 -149.9616)
		(end 33.32099 -150.391368)
		(width 0.14224)
		(layer "In11.Cu")
		(net "M_M_DQ<1>")
	)
	(segment
		(start 67.191382 -87.88019)
		(end 66.645536 -87.88019)
		(width 0.0889)
		(layer "In11.Cu")
		(net "M_M_DQ<1>")
	)
	(segment
		(start 33.746948 -128.427988)
		(end 33.901888 -128.582928)
		(width 0.14224)
		(layer "In11.Cu")
		(net "M_M_DQ<1>")
	)
	(segment
		(start 34.25952 -141.271752)
		(end 34.364168 -141.3764)
		(width 0.14224)
		(layer "In11.Cu")
		(net "M_M_DQ<1>")
	)
	(segment
		(start 33.901888 -127.770128)
		(end 33.746948 -127.925068)
		(width 0.14224)
		(layer "In11.Cu")
		(net "M_M_DQ<1>")
	)
	(segment
		(start 34.354008 -114.002312)
		(end 35.872928 -114.002312)
		(width 0.14224)
		(layer "In11.Cu")
		(net "M_M_DQ<1>")
	)
	(segment
		(start 34.211768 -114.794792)
		(end 34.211768 -116.7892)
		(width 0.14224)
		(layer "In11.Cu")
		(net "M_M_DQ<1>")
	)
	(segment
		(start 36.015168 -114.144552)
		(end 36.015168 -114.510312)
		(width 0.14224)
		(layer "In11.Cu")
		(net "M_M_DQ<1>")
	)
	(segment
		(start 33.551368 -150.621746)
		(end 33.551368 -151.026368)
		(width 0.14224)
		(layer "In11.Cu")
		(net "M_M_DQ<1>")
	)
	(segment
		(start 74.915522 -84.412836)
		(end 74.882756 -84.412836)
		(width 0.0889)
		(layer "In11.Cu")
		(net "M_M_DQ<1>")
	)
	(segment
		(start 68.912486 -86.88959)
		(end 68.87972 -86.88959)
		(width 0.0889)
		(layer "In11.Cu")
		(net "M_M_DQ<1>")
	)
	(segment
		(start 35.872928 -114.652552)
		(end 34.354008 -114.652552)
		(width 0.14224)
		(layer "In11.Cu")
		(net "M_M_DQ<1>")
	)
	(segment
		(start 33.901888 -128.582928)
		(end 34.209228 -128.582928)
		(width 0.14224)
		(layer "In11.Cu")
		(net "M_M_DQ<1>")
	)
	(segment
		(start 34.364168 -141.3764)
		(end 34.364168 -143.637)
		(width 0.14224)
		(layer "In11.Cu")
		(net "M_M_DQ<1>")
	)
	(segment
		(start 34.354008 -114.652552)
		(end 34.211768 -114.794792)
		(width 0.14224)
		(layer "In11.Cu")
		(net "M_M_DQ<1>")
	)
	(segment
		(start 34.25952 -134.115048)
		(end 34.25952 -136.572752)
		(width 0.14224)
		(layer "In11.Cu")
		(net "M_M_DQ<1>")
	)
	(segment
		(start 34.440368 -113.0046)
		(end 34.211768 -113.2332)
		(width 0.14224)
		(layer "In11.Cu")
		(net "M_M_DQ<1>")
	)
	(segment
		(start 34.25952 -138.839448)
		(end 34.25952 -141.271752)
		(width 0.14224)
		(layer "In11.Cu")
		(net "M_M_DQ<1>")
	)
	(segment
		(start 34.364168 -126.9746)
		(end 34.364168 -127.615188)
		(width 0.14224)
		(layer "In11.Cu")
		(net "M_M_DQ<1>")
	)
	(segment
		(start 69.774816 -86.394036)
		(end 69.74205 -86.394036)
		(width 0.0889)
		(layer "In11.Cu")
		(net "M_M_DQ<1>")
	)
	(segment
		(start 34.592768 -117.5766)
		(end 34.211768 -117.9576)
		(width 0.14224)
		(layer "In11.Cu")
		(net "M_M_DQ<1>")
	)
	(segment
		(start 34.364168 -143.637)
		(end 34.25952 -143.741648)
		(width 0.14224)
		(layer "In11.Cu")
		(net "M_M_DQ<1>")
	)
	(segment
		(start 33.746948 -127.925068)
		(end 33.746948 -128.427988)
		(width 0.14224)
		(layer "In11.Cu")
		(net "M_M_DQ<1>")
	)
	(segment
		(start 33.260792 -152.846024)
		(end 33.500568 -153.0858)
		(width 0.14224)
		(layer "In11.Cu")
		(net "M_M_DQ<1>")
	)
	(segment
		(start 75.762866 -85.30844)
		(end 75.26782 -84.642452)
		(width 0.0889)
		(layer "In11.Cu")
		(net "M_M_DQ<1>")
	)
	(segment
		(start 34.364168 -127.615188)
		(end 34.209228 -127.770128)
		(width 0.14224)
		(layer "In11.Cu")
		(net "M_M_DQ<1>")
	)
	(segment
		(start 48.821594 -102.1461)
		(end 43.571668 -102.1461)
		(width 0.14224)
		(layer "In11.Cu")
		(net "M_M_DQ<1>")
	)
	(segment
		(start 33.475168 -151.892)
		(end 33.475168 -152.3238)
		(width 0.14224)
		(layer "In11.Cu")
		(net "M_M_DQ<1>")
	)
	(segment
		(start 35.583368 -113.0046)
		(end 34.440368 -113.0046)
		(width 0.14224)
		(layer "In11.Cu")
		(net "M_M_DQ<1>")
	)
	(segment
		(start 35.761168 -112.141254)
		(end 35.761168 -112.8268)
		(width 0.14224)
		(layer "In11.Cu")
		(net "M_M_DQ<1>")
	)
	(segment
		(start 34.389568 -131.9276)
		(end 34.389568 -133.985)
		(width 0.14224)
		(layer "In11.Cu")
		(net "M_M_DQ<1>")
	)
	(segment
		(start 43.1038 -104.265222)
		(end 39.850568 -107.518454)
		(width 0.14224)
		(layer "In11.Cu")
		(net "M_M_DQ<1>")
	)
	(segment
		(start 34.211768 -113.860072)
		(end 34.354008 -114.002312)
		(width 0.14224)
		(layer "In11.Cu")
		(net "M_M_DQ<1>")
	)
	(segment
		(start 43.1038 -102.613968)
		(end 43.1038 -104.265222)
		(width 0.14224)
		(layer "In11.Cu")
		(net "M_M_DQ<1>")
	)
	(segment
		(start 35.872928 -114.002312)
		(end 36.015168 -114.144552)
		(width 0.14224)
		(layer "In11.Cu")
		(net "M_M_DQ<1>")
	)
	(segment
		(start 64.472312 -87.398606)
		(end 64.259206 -87.611712)
		(width 0.0889)
		(layer "In11.Cu")
		(net "M_M_DQ<1>")
	)
	(segment
		(start 33.749234 -149.533356)
		(end 33.32099 -149.9616)
		(width 0.14224)
		(layer "In11.Cu")
		(net "M_M_DQ<1>")
	)
	(segment
		(start 33.771586 -149.444456)
		(end 33.771586 -149.533356)
		(width 0.14224)
		(layer "In11.Cu")
		(net "M_M_DQ<1>")
	)
	(segment
		(start 33.475168 -152.3238)
		(end 33.260792 -152.538176)
		(width 0.14224)
		(layer "In11.Cu")
		(net "M_M_DQ<1>")
	)
	(segment
		(start 71.491856 -85.403436)
		(end 71.45909 -85.403436)
		(width 0.0889)
		(layer "In11.Cu")
		(net "M_M_DQ<1>")
	)
	(segment
		(start 33.260792 -151.316944)
		(end 33.260792 -151.677624)
		(width 0.14224)
		(layer "In11.Cu")
		(net "M_M_DQ<1>")
	)
	(segment
		(start 34.209228 -128.582928)
		(end 34.364168 -128.737868)
		(width 0.14224)
		(layer "In11.Cu")
		(net "M_M_DQ<1>")
	)
	(segment
		(start 36.015168 -114.510312)
		(end 35.872928 -114.652552)
		(width 0.14224)
		(layer "In11.Cu")
		(net "M_M_DQ<1>")
	)
	(arc
		(start 74.03084 -83.91779)
		(mid 73.839198 -83.974956)
		(end 73.699116 -84.117688)
		(width 0.0889)
		(layer "In11.Cu")
		(net "M_M_DQ<1>")
	)
	(arc
		(start 70.59676 -85.89899)
		(mid 70.405118 -85.956156)
		(end 70.265036 -86.098888)
		(width 0.0889)
		(layer "In11.Cu")
		(net "M_M_DQ<1>")
	)
	(arc
		(start 70.265036 -86.098888)
		(mid 70.058032 -86.309752)
		(end 69.774816 -86.394036)
		(width 0.0889)
		(layer "In11.Cu")
		(net "M_M_DQ<1>")
	)
	(arc
		(start 68.02501 -87.384636)
		(mid 67.83116 -87.440986)
		(end 67.689476 -87.584788)
		(width 0.0889)
		(layer "In11.Cu")
		(net "M_M_DQ<1>")
	)
	(arc
		(start 71.45909 -85.403436)
		(mid 71.26524 -85.459786)
		(end 71.123556 -85.603588)
		(width 0.0889)
		(layer "In11.Cu")
		(net "M_M_DQ<1>")
	)
	(arc
		(start 67.689476 -87.584788)
		(mid 67.479123 -87.79776)
		(end 67.191382 -87.88019)
		(width 0.0889)
		(layer "In11.Cu")
		(net "M_M_DQ<1>")
	)
	(arc
		(start 72.3138 -84.90839)
		(mid 72.122158 -84.965556)
		(end 71.982076 -85.108288)
		(width 0.0889)
		(layer "In11.Cu")
		(net "M_M_DQ<1>")
	)
	(arc
		(start 68.87972 -86.88959)
		(mid 68.688078 -86.946756)
		(end 68.547996 -87.089488)
		(width 0.0889)
		(layer "In11.Cu")
		(net "M_M_DQ<1>")
	)
	(arc
		(start 73.699116 -84.117688)
		(mid 73.492112 -84.328552)
		(end 73.208896 -84.412836)
		(width 0.0889)
		(layer "In11.Cu")
		(net "M_M_DQ<1>")
	)
	(arc
		(start 68.547996 -87.089488)
		(mid 68.340992 -87.300352)
		(end 68.057776 -87.384636)
		(width 0.0889)
		(layer "In11.Cu")
		(net "M_M_DQ<1>")
	)
	(arc
		(start 69.406516 -86.594188)
		(mid 69.197908 -86.80612)
		(end 68.912486 -86.88959)
		(width 0.0889)
		(layer "In11.Cu")
		(net "M_M_DQ<1>")
	)
	(arc
		(start 71.123556 -85.603588)
		(mid 70.914948 -85.81552)
		(end 70.629526 -85.89899)
		(width 0.0889)
		(layer "In11.Cu")
		(net "M_M_DQ<1>")
	)
	(arc
		(start 74.392536 -84.117688)
		(mid 74.252457 -83.974952)
		(end 74.060812 -83.91779)
		(width 0.0889)
		(layer "In11.Cu")
		(net "M_M_DQ<1>")
	)
	(arc
		(start 75.251056 -84.612988)
		(mid 75.109373 -84.469184)
		(end 74.915522 -84.412836)
		(width 0.0889)
		(layer "In11.Cu")
		(net "M_M_DQ<1>")
	)
	(arc
		(start 73.17613 -84.412836)
		(mid 72.98228 -84.469186)
		(end 72.840596 -84.612988)
		(width 0.0889)
		(layer "In11.Cu")
		(net "M_M_DQ<1>")
	)
	(arc
		(start 72.840596 -84.612988)
		(mid 72.631988 -84.82492)
		(end 72.346566 -84.90839)
		(width 0.0889)
		(layer "In11.Cu")
		(net "M_M_DQ<1>")
	)
	(arc
		(start 69.74205 -86.394036)
		(mid 69.5482 -86.450386)
		(end 69.406516 -86.594188)
		(width 0.0889)
		(layer "In11.Cu")
		(net "M_M_DQ<1>")
	)
	(arc
		(start 71.982076 -85.108288)
		(mid 71.775072 -85.319152)
		(end 71.491856 -85.403436)
		(width 0.0889)
		(layer "In11.Cu")
		(net "M_M_DQ<1>")
	)
	(arc
		(start 74.882756 -84.412836)
		(mid 74.599539 -84.328555)
		(end 74.392536 -84.117688)
		(width 0.0889)
		(layer "In11.Cu")
		(net "M_M_DQ<1>")
	)
	(segment
		(start 57.74944 -152.273)
		(end 57.74944 -153.542746)
		(width 0.1651)
		(layer "F.Cu")
		(net "M_M_DQ<19>")
	)
	(segment
		(start 81.485232 -95.21444)
		(end 80.913732 -95.21444)
		(width 0.1651)
		(layer "F.Cu")
		(net "M_M_DQ<19>")
	)
	(via
		(at 57.74944 -153.542746)
		(size 0.508)
		(drill 0.254)
		(layers "F.Cu" "B.Cu")
		(net "M_M_DQ<19>")
	)
	(via
		(at 58.599324 -149.533356)
		(size 0.508)
		(drill 0.254)
		(layers "F.Cu" "B.Cu")
		(net "M_M_DQ<19>")
	)
	(via
		(at 80.913732 -95.21444)
		(size 0.508)
		(drill 0.254)
		(layers "F.Cu" "B.Cu")
		(net "M_M_DQ<19>")
	)
	(segment
		(start 58.599324 -147.478496)
		(end 58.599324 -149.533356)
		(width 0.1651)
		(layer "B.Cu")
		(net "M_M_DQ<19>")
	)
	(segment
		(start 58.599578 -147.478496)
		(end 58.599324 -147.478496)
		(width 0.1651)
		(layer "B.Cu")
		(net "M_M_DQ<19>")
	)
	(segment
		(start 68.506086 -114.829082)
		(end 68.183506 -115.151662)
		(width 0.14224)
		(layer "In11.Cu")
		(net "M_M_DQ<19>")
	)
	(segment
		(start 59.027568 -134.0358)
		(end 58.966608 -134.09676)
		(width 0.14224)
		(layer "In11.Cu")
		(net "M_M_DQ<19>")
	)
	(segment
		(start 80.583786 -95.976186)
		(end 80.567022 -96.004888)
		(width 0.0889)
		(layer "In11.Cu")
		(net "M_M_DQ<19>")
	)
	(segment
		(start 59.027568 -137.287)
		(end 58.824368 -137.4902)
		(width 0.14224)
		(layer "In11.Cu")
		(net "M_M_DQ<19>")
	)
	(segment
		(start 75.41133 -101.349302)
		(end 75.539854 -101.580188)
		(width 0.0889)
		(layer "In11.Cu")
		(net "M_M_DQ<19>")
	)
	(segment
		(start 70.805294 -112.529874)
		(end 70.51802 -112.817148)
		(width 0.14224)
		(layer "In11.Cu")
		(net "M_M_DQ<19>")
	)
	(segment
		(start 58.966608 -131.8768)
		(end 59.027568 -131.93776)
		(width 0.14224)
		(layer "In11.Cu")
		(net "M_M_DQ<19>")
	)
	(segment
		(start 58.199528 -153.04135)
		(end 58.199528 -153.364946)
		(width 0.14224)
		(layer "In11.Cu")
		(net "M_M_DQ<19>")
	)
	(segment
		(start 70.51802 -113.104676)
		(end 71.037958 -113.624614)
		(width 0.14224)
		(layer "In11.Cu")
		(net "M_M_DQ<19>")
	)
	(segment
		(start 77.995018 -97.484946)
		(end 77.991716 -97.490788)
		(width 0.0889)
		(layer "In11.Cu")
		(net "M_M_DQ<19>")
	)
	(segment
		(start 58.928508 -145.84426)
		(end 58.928508 -146.1516)
		(width 0.14224)
		(layer "In11.Cu")
		(net "M_M_DQ<19>")
	)
	(segment
		(start 59.106308 -140.870178)
		(end 58.966608 -141.009878)
		(width 0.14224)
		(layer "In11.Cu")
		(net "M_M_DQ<19>")
	)
	(segment
		(start 58.953908 -139.562078)
		(end 59.106308 -139.714478)
		(width 0.14224)
		(layer "In11.Cu")
		(net "M_M_DQ<19>")
	)
	(segment
		(start 59.027568 -148.4376)
		(end 58.928508 -148.53666)
		(width 0.14224)
		(layer "In11.Cu")
		(net "M_M_DQ<19>")
	)
	(segment
		(start 59.182508 -144.398238)
		(end 59.182508 -145.59026)
		(width 0.14224)
		(layer "In11.Cu")
		(net "M_M_DQ<19>")
	)
	(segment
		(start 70.45071 -114.18697)
		(end 69.943218 -113.679478)
		(width 0.14224)
		(layer "In11.Cu")
		(net "M_M_DQ<19>")
	)
	(segment
		(start 58.167778 -151.9174)
		(end 58.167778 -152.2222)
		(width 0.14224)
		(layer "In11.Cu")
		(net "M_M_DQ<19>")
	)
	(segment
		(start 68.793614 -114.829082)
		(end 68.506086 -114.829082)
		(width 0.14224)
		(layer "In11.Cu")
		(net "M_M_DQ<19>")
	)
	(segment
		(start 69.362574 -115.398042)
		(end 68.793614 -114.829082)
		(width 0.14224)
		(layer "In11.Cu")
		(net "M_M_DQ<19>")
	)
	(segment
		(start 58.966608 -134.09676)
		(end 58.966608 -134.573264)
		(width 0.14224)
		(layer "In11.Cu")
		(net "M_M_DQ<19>")
	)
	(segment
		(start 58.953908 -129.960878)
		(end 59.106308 -130.113278)
		(width 0.14224)
		(layer "In11.Cu")
		(net "M_M_DQ<19>")
	)
	(segment
		(start 59.027568 -143.637)
		(end 58.966608 -143.69796)
		(width 0.14224)
		(layer "In11.Cu")
		(net "M_M_DQ<19>")
	)
	(segment
		(start 58.021728 -153.542746)
		(end 57.74944 -153.542746)
		(width 0.14224)
		(layer "In11.Cu")
		(net "M_M_DQ<19>")
	)
	(segment
		(start 59.027568 -131.93776)
		(end 59.027568 -134.0358)
		(width 0.14224)
		(layer "In11.Cu")
		(net "M_M_DQ<19>")
	)
	(segment
		(start 69.949822 -114.835686)
		(end 69.949822 -115.110768)
		(width 0.14224)
		(layer "In11.Cu")
		(net "M_M_DQ<19>")
	)
	(segment
		(start 59.027568 -141.51356)
		(end 59.027568 -143.637)
		(width 0.14224)
		(layer "In11.Cu")
		(net "M_M_DQ<19>")
	)
	(segment
		(start 58.167778 -152.2222)
		(end 57.91073 -152.479248)
		(width 0.14224)
		(layer "In11.Cu")
		(net "M_M_DQ<19>")
	)
	(segment
		(start 59.027568 -146.25066)
		(end 59.027568 -148.4376)
		(width 0.14224)
		(layer "In11.Cu")
		(net "M_M_DQ<19>")
	)
	(segment
		(start 75.780646 -98.77679)
		(end 75.74788 -98.77679)
		(width 0.0889)
		(layer "In11.Cu")
		(net "M_M_DQ<19>")
	)
	(segment
		(start 58.798968 -123.0122)
		(end 58.798968 -127.0254)
		(width 0.14224)
		(layer "In11.Cu")
		(net "M_M_DQ<19>")
	)
	(segment
		(start 73.322434 -105.683304)
		(end 73.322434 -105.832656)
		(width 0.0889)
		(layer "In11.Cu")
		(net "M_M_DQ<19>")
	)
	(segment
		(start 75.539854 -101.580188)
		(end 75.539854 -103.465884)
		(width 0.0889)
		(layer "In11.Cu")
		(net "M_M_DQ<19>")
	)
	(segment
		(start 67.608704 -116.013992)
		(end 67.321176 -116.013992)
		(width 0.14224)
		(layer "In11.Cu")
		(net "M_M_DQ<19>")
	)
	(segment
		(start 70.51802 -112.817148)
		(end 70.51802 -113.104676)
		(width 0.14224)
		(layer "In11.Cu")
		(net "M_M_DQ<19>")
	)
	(segment
		(start 59.106308 -130.113278)
		(end 59.106308 -131.268978)
		(width 0.14224)
		(layer "In11.Cu")
		(net "M_M_DQ<19>")
	)
	(segment
		(start 59.027568 -136.59866)
		(end 59.027568 -137.287)
		(width 0.14224)
		(layer "In11.Cu")
		(net "M_M_DQ<19>")
	)
	(segment
		(start 69.368416 -114.25428)
		(end 69.949822 -114.835686)
		(width 0.14224)
		(layer "In11.Cu")
		(net "M_M_DQ<19>")
	)
	(segment
		(start 58.576972 -149.533356)
		(end 58.148728 -149.9616)
		(width 0.14224)
		(layer "In11.Cu")
		(net "M_M_DQ<19>")
	)
	(segment
		(start 58.966608 -134.573264)
		(end 59.131708 -134.738364)
		(width 0.14224)
		(layer "In11.Cu")
		(net "M_M_DQ<19>")
	)
	(segment
		(start 75.422506 -99.95662)
		(end 75.416156 -99.967288)
		(width 0.0889)
		(layer "In11.Cu")
		(net "M_M_DQ<19>")
	)
	(segment
		(start 58.599324 -149.533356)
		(end 58.576972 -149.533356)
		(width 0.14224)
		(layer "In11.Cu")
		(net "M_M_DQ<19>")
	)
	(segment
		(start 68.183506 -115.43919)
		(end 68.725288 -115.980972)
		(width 0.14224)
		(layer "In11.Cu")
		(net "M_M_DQ<19>")
	)
	(segment
		(start 58.953908 -129.33426)
		(end 58.953908 -129.960878)
		(width 0.14224)
		(layer "In11.Cu")
		(net "M_M_DQ<19>")
	)
	(segment
		(start 58.966608 -131.408678)
		(end 58.966608 -131.8768)
		(width 0.14224)
		(layer "In11.Cu")
		(net "M_M_DQ<19>")
	)
	(segment
		(start 71.740522 -112.890046)
		(end 71.452994 -112.890046)
		(width 0.14224)
		(layer "In11.Cu")
		(net "M_M_DQ<19>")
	)
	(segment
		(start 69.65569 -113.679478)
		(end 69.368416 -113.966752)
		(width 0.14224)
		(layer "In11.Cu")
		(net "M_M_DQ<19>")
	)
	(segment
		(start 58.199528 -153.364946)
		(end 58.021728 -153.542746)
		(width 0.14224)
		(layer "In11.Cu")
		(net "M_M_DQ<19>")
	)
	(segment
		(start 58.928508 -148.53666)
		(end 58.928508 -149.21738)
		(width 0.14224)
		(layer "In11.Cu")
		(net "M_M_DQ<19>")
	)
	(segment
		(start 68.120006 -116.525294)
		(end 67.608704 -116.013992)
		(width 0.14224)
		(layer "In11.Cu")
		(net "M_M_DQ<19>")
	)
	(segment
		(start 59.131708 -134.738364)
		(end 59.131708 -136.01446)
		(width 0.14224)
		(layer "In11.Cu")
		(net "M_M_DQ<19>")
	)
	(segment
		(start 58.966608 -141.4526)
		(end 59.027568 -141.51356)
		(width 0.14224)
		(layer "In11.Cu")
		(net "M_M_DQ<19>")
	)
	(segment
		(start 59.027568 -138.7602)
		(end 58.953908 -138.83386)
		(width 0.14224)
		(layer "In11.Cu")
		(net "M_M_DQ<19>")
	)
	(segment
		(start 58.798968 -127.0254)
		(end 59.052968 -127.2794)
		(width 0.14224)
		(layer "In11.Cu")
		(net "M_M_DQ<19>")
	)
	(segment
		(start 58.148728 -150.391368)
		(end 58.193178 -150.435818)
		(width 0.14224)
		(layer "In11.Cu")
		(net "M_M_DQ<19>")
	)
	(segment
		(start 72.616568 -106.538522)
		(end 72.616568 -112.014)
		(width 0.14224)
		(layer "In11.Cu")
		(net "M_M_DQ<19>")
	)
	(segment
		(start 69.943218 -113.679478)
		(end 69.65569 -113.679478)
		(width 0.14224)
		(layer "In11.Cu")
		(net "M_M_DQ<19>")
	)
	(segment
		(start 58.953908 -136.525)
		(end 59.027568 -136.59866)
		(width 0.14224)
		(layer "In11.Cu")
		(net "M_M_DQ<19>")
	)
	(segment
		(start 59.182508 -145.59026)
		(end 58.928508 -145.84426)
		(width 0.14224)
		(layer "In11.Cu")
		(net "M_M_DQ<19>")
	)
	(segment
		(start 71.037958 -113.624614)
		(end 71.037958 -113.899696)
		(width 0.14224)
		(layer "In11.Cu")
		(net "M_M_DQ<19>")
	)
	(segment
		(start 58.824368 -138.0744)
		(end 59.027568 -138.2776)
		(width 0.14224)
		(layer "In11.Cu")
		(net "M_M_DQ<19>")
	)
	(segment
		(start 57.91073 -152.752552)
		(end 58.199528 -153.04135)
		(width 0.14224)
		(layer "In11.Cu")
		(net "M_M_DQ<19>")
	)
	(segment
		(start 71.037958 -113.899696)
		(end 70.750684 -114.18697)
		(width 0.14224)
		(layer "In11.Cu")
		(net "M_M_DQ<19>")
	)
	(segment
		(start 58.966608 -144.182338)
		(end 59.182508 -144.398238)
		(width 0.14224)
		(layer "In11.Cu")
		(net "M_M_DQ<19>")
	)
	(segment
		(start 75.41133 -99.368102)
		(end 75.416156 -99.376738)
		(width 0.0889)
		(layer "In11.Cu")
		(net "M_M_DQ<19>")
	)
	(segment
		(start 68.725288 -116.23802)
		(end 68.438014 -116.525294)
		(width 0.14224)
		(layer "In11.Cu")
		(net "M_M_DQ<19>")
	)
	(segment
		(start 69.662548 -115.398042)
		(end 69.362574 -115.398042)
		(width 0.14224)
		(layer "In11.Cu")
		(net "M_M_DQ<19>")
	)
	(segment
		(start 80.913732 -95.21444)
		(end 80.583786 -95.976186)
		(width 0.0889)
		(layer "In11.Cu")
		(net "M_M_DQ<19>")
	)
	(segment
		(start 71.452994 -112.890046)
		(end 71.092822 -112.529874)
		(width 0.14224)
		(layer "In11.Cu")
		(net "M_M_DQ<19>")
	)
	(segment
		(start 58.148728 -149.9616)
		(end 58.148728 -150.391368)
		(width 0.14224)
		(layer "In11.Cu")
		(net "M_M_DQ<19>")
	)
	(segment
		(start 57.91073 -151.387048)
		(end 57.91073 -151.660352)
		(width 0.14224)
		(layer "In11.Cu")
		(net "M_M_DQ<19>")
	)
	(segment
		(start 79.214472 -96.79559)
		(end 79.181706 -96.79559)
		(width 0.0889)
		(layer "In11.Cu")
		(net "M_M_DQ<19>")
	)
	(segment
		(start 67.321176 -116.013992)
		(end 67.028568 -116.3066)
		(width 0.14224)
		(layer "In11.Cu")
		(net "M_M_DQ<19>")
	)
	(segment
		(start 58.966608 -141.009878)
		(end 58.966608 -141.4526)
		(width 0.14224)
		(layer "In11.Cu")
		(net "M_M_DQ<19>")
	)
	(segment
		(start 65.504568 -116.3066)
		(end 58.798968 -123.0122)
		(width 0.14224)
		(layer "In11.Cu")
		(net "M_M_DQ<19>")
	)
	(segment
		(start 59.052968 -127.2794)
		(end 59.052968 -129.2352)
		(width 0.14224)
		(layer "In11.Cu")
		(net "M_M_DQ<19>")
	)
	(segment
		(start 58.599324 -149.546564)
		(end 58.599324 -149.533356)
		(width 0.14224)
		(layer "In11.Cu")
		(net "M_M_DQ<19>")
	)
	(segment
		(start 58.953908 -138.83386)
		(end 58.953908 -139.562078)
		(width 0.14224)
		(layer "In11.Cu")
		(net "M_M_DQ<19>")
	)
	(segment
		(start 57.91073 -151.660352)
		(end 58.167778 -151.9174)
		(width 0.14224)
		(layer "In11.Cu")
		(net "M_M_DQ<19>")
	)
	(segment
		(start 68.183506 -115.151662)
		(end 68.183506 -115.43919)
		(width 0.14224)
		(layer "In11.Cu")
		(net "M_M_DQ<19>")
	)
	(segment
		(start 72.616568 -112.014)
		(end 71.740522 -112.890046)
		(width 0.14224)
		(layer "In11.Cu")
		(net "M_M_DQ<19>")
	)
	(segment
		(start 75.539854 -103.465884)
		(end 73.322434 -105.683304)
		(width 0.0889)
		(layer "In11.Cu")
		(net "M_M_DQ<19>")
	)
	(segment
		(start 58.193178 -151.1046)
		(end 57.91073 -151.387048)
		(width 0.14224)
		(layer "In11.Cu")
		(net "M_M_DQ<19>")
	)
	(segment
		(start 59.052968 -129.2352)
		(end 58.953908 -129.33426)
		(width 0.14224)
		(layer "In11.Cu")
		(net "M_M_DQ<19>")
	)
	(segment
		(start 68.438014 -116.525294)
		(end 68.120006 -116.525294)
		(width 0.14224)
		(layer "In11.Cu")
		(net "M_M_DQ<19>")
	)
	(segment
		(start 57.91073 -152.479248)
		(end 57.91073 -152.752552)
		(width 0.14224)
		(layer "In11.Cu")
		(net "M_M_DQ<19>")
	)
	(segment
		(start 58.966608 -143.69796)
		(end 58.966608 -144.182338)
		(width 0.14224)
		(layer "In11.Cu")
		(net "M_M_DQ<19>")
	)
	(segment
		(start 78.359762 -97.290636)
		(end 78.338172 -97.290636)
		(width 0.0889)
		(layer "In11.Cu")
		(net "M_M_DQ<19>")
	)
	(segment
		(start 58.193178 -150.435818)
		(end 58.193178 -151.1046)
		(width 0.14224)
		(layer "In11.Cu")
		(net "M_M_DQ<19>")
	)
	(segment
		(start 58.928508 -146.1516)
		(end 59.027568 -146.25066)
		(width 0.14224)
		(layer "In11.Cu")
		(net "M_M_DQ<19>")
	)
	(segment
		(start 58.953908 -136.19226)
		(end 58.953908 -136.525)
		(width 0.14224)
		(layer "In11.Cu")
		(net "M_M_DQ<19>")
	)
	(segment
		(start 68.725288 -115.980972)
		(end 68.725288 -116.23802)
		(width 0.14224)
		(layer "In11.Cu")
		(net "M_M_DQ<19>")
	)
	(segment
		(start 80.076802 -96.300036)
		(end 80.044036 -96.300036)
		(width 0.0889)
		(layer "In11.Cu")
		(net "M_M_DQ<19>")
	)
	(segment
		(start 73.322434 -105.832656)
		(end 72.616568 -106.538522)
		(width 0.14224)
		(layer "In11.Cu")
		(net "M_M_DQ<19>")
	)
	(segment
		(start 69.368416 -113.966752)
		(end 69.368416 -114.25428)
		(width 0.14224)
		(layer "In11.Cu")
		(net "M_M_DQ<19>")
	)
	(segment
		(start 58.928508 -149.21738)
		(end 58.599324 -149.546564)
		(width 0.14224)
		(layer "In11.Cu")
		(net "M_M_DQ<19>")
	)
	(segment
		(start 59.027568 -138.2776)
		(end 59.027568 -138.7602)
		(width 0.14224)
		(layer "In11.Cu")
		(net "M_M_DQ<19>")
	)
	(segment
		(start 67.028568 -116.3066)
		(end 65.504568 -116.3066)
		(width 0.14224)
		(layer "In11.Cu")
		(net "M_M_DQ<19>")
	)
	(segment
		(start 71.092822 -112.529874)
		(end 70.805294 -112.529874)
		(width 0.14224)
		(layer "In11.Cu")
		(net "M_M_DQ<19>")
	)
	(segment
		(start 69.949822 -115.110768)
		(end 69.662548 -115.398042)
		(width 0.14224)
		(layer "In11.Cu")
		(net "M_M_DQ<19>")
	)
	(segment
		(start 59.131708 -136.01446)
		(end 58.953908 -136.19226)
		(width 0.14224)
		(layer "In11.Cu")
		(net "M_M_DQ<19>")
	)
	(segment
		(start 59.106308 -131.268978)
		(end 58.966608 -131.408678)
		(width 0.14224)
		(layer "In11.Cu")
		(net "M_M_DQ<19>")
	)
	(segment
		(start 76.642976 -98.281236)
		(end 76.61021 -98.281236)
		(width 0.0889)
		(layer "In11.Cu")
		(net "M_M_DQ<19>")
	)
	(segment
		(start 77.497686 -97.78619)
		(end 77.46492 -97.78619)
		(width 0.0889)
		(layer "In11.Cu")
		(net "M_M_DQ<19>")
	)
	(segment
		(start 59.106308 -139.714478)
		(end 59.106308 -140.870178)
		(width 0.14224)
		(layer "In11.Cu")
		(net "M_M_DQ<19>")
	)
	(segment
		(start 58.824368 -137.4902)
		(end 58.824368 -138.0744)
		(width 0.14224)
		(layer "In11.Cu")
		(net "M_M_DQ<19>")
	)
	(segment
		(start 70.750684 -114.18697)
		(end 70.45071 -114.18697)
		(width 0.14224)
		(layer "In11.Cu")
		(net "M_M_DQ<19>")
	)
	(arc
		(start 75.416156 -100.957888)
		(mid 75.362686 -101.152951)
		(end 75.41133 -101.349302)
		(width 0.0889)
		(layer "In11.Cu")
		(net "M_M_DQ<19>")
	)
	(arc
		(start 76.274676 -98.481388)
		(mid 76.066068 -98.69332)
		(end 75.780646 -98.77679)
		(width 0.0889)
		(layer "In11.Cu")
		(net "M_M_DQ<19>")
	)
	(arc
		(start 79.181706 -96.79559)
		(mid 78.990064 -96.852756)
		(end 78.849982 -96.995488)
		(width 0.0889)
		(layer "In11.Cu")
		(net "M_M_DQ<19>")
	)
	(arc
		(start 80.044036 -96.300036)
		(mid 79.850186 -96.356386)
		(end 79.708502 -96.500188)
		(width 0.0889)
		(layer "In11.Cu")
		(net "M_M_DQ<19>")
	)
	(arc
		(start 75.416156 -99.376738)
		(mid 75.495378 -99.665856)
		(end 75.422506 -99.95662)
		(width 0.0889)
		(layer "In11.Cu")
		(net "M_M_DQ<19>")
	)
	(arc
		(start 75.74788 -98.77679)
		(mid 75.414962 -98.978781)
		(end 75.41133 -99.368102)
		(width 0.0889)
		(layer "In11.Cu")
		(net "M_M_DQ<19>")
	)
	(arc
		(start 76.61021 -98.281236)
		(mid 76.41636 -98.337586)
		(end 76.274676 -98.481388)
		(width 0.0889)
		(layer "In11.Cu")
		(net "M_M_DQ<19>")
	)
	(arc
		(start 77.133196 -97.986088)
		(mid 76.926192 -98.196952)
		(end 76.642976 -98.281236)
		(width 0.0889)
		(layer "In11.Cu")
		(net "M_M_DQ<19>")
	)
	(arc
		(start 80.567022 -96.004888)
		(mid 80.360018 -96.215752)
		(end 80.076802 -96.300036)
		(width 0.0889)
		(layer "In11.Cu")
		(net "M_M_DQ<19>")
	)
	(arc
		(start 75.416156 -100.367084)
		(mid 75.495287 -100.662486)
		(end 75.416156 -100.957888)
		(width 0.0889)
		(layer "In11.Cu")
		(net "M_M_DQ<19>")
	)
	(arc
		(start 77.991716 -97.490788)
		(mid 77.783108 -97.70272)
		(end 77.497686 -97.78619)
		(width 0.0889)
		(layer "In11.Cu")
		(net "M_M_DQ<19>")
	)
	(arc
		(start 78.849982 -96.995488)
		(mid 78.642978 -97.206352)
		(end 78.359762 -97.290636)
		(width 0.0889)
		(layer "In11.Cu")
		(net "M_M_DQ<19>")
	)
	(arc
		(start 79.708502 -96.500188)
		(mid 79.499894 -96.71212)
		(end 79.214472 -96.79559)
		(width 0.0889)
		(layer "In11.Cu")
		(net "M_M_DQ<19>")
	)
	(arc
		(start 77.46492 -97.78619)
		(mid 77.273278 -97.843356)
		(end 77.133196 -97.986088)
		(width 0.0889)
		(layer "In11.Cu")
		(net "M_M_DQ<19>")
	)
	(arc
		(start 75.416156 -99.967288)
		(mid 75.362657 -100.167186)
		(end 75.416156 -100.367084)
		(width 0.0889)
		(layer "In11.Cu")
		(net "M_M_DQ<19>")
	)
	(arc
		(start 78.338172 -97.290636)
		(mid 78.141011 -97.342595)
		(end 77.995018 -97.484946)
		(width 0.0889)
		(layer "In11.Cu")
		(net "M_M_DQ<19>")
	)
	(segment
		(start 58.730896 -155.52674)
		(end 58.599324 -155.395168)
		(width 0.1651)
		(layer "F.Cu")
		(net "M_M_DQ<18>")
	)
	(segment
		(start 58.730896 -155.75026)
		(end 58.730896 -155.52674)
		(width 0.1651)
		(layer "F.Cu")
		(net "M_M_DQ<18>")
	)
	(segment
		(start 82.343752 -94.718886)
		(end 81.772252 -94.718886)
		(width 0.1651)
		(layer "F.Cu")
		(net "M_M_DQ<18>")
	)
	(segment
		(start 58.599324 -156.87294)
		(end 58.599324 -155.881832)
		(width 0.1651)
		(layer "F.Cu")
		(net "M_M_DQ<18>")
	)
	(segment
		(start 58.599578 -156.87294)
		(end 58.599324 -156.87294)
		(width 0.1651)
		(layer "F.Cu")
		(net "M_M_DQ<18>")
	)
	(segment
		(start 58.599324 -155.395168)
		(end 58.599324 -155.1178)
		(width 0.1651)
		(layer "F.Cu")
		(net "M_M_DQ<18>")
	)
	(segment
		(start 58.599324 -155.881832)
		(end 58.730896 -155.75026)
		(width 0.1651)
		(layer "F.Cu")
		(net "M_M_DQ<18>")
	)
	(via
		(at 57.74944 -150.814278)
		(size 0.508)
		(drill 0.254)
		(layers "F.Cu" "B.Cu")
		(net "M_M_DQ<18>")
	)
	(via
		(at 58.599324 -155.1178)
		(size 0.508)
		(drill 0.254)
		(layers "F.Cu" "B.Cu")
		(net "M_M_DQ<18>")
	)
	(via
		(at 81.772252 -94.718886)
		(size 0.508)
		(drill 0.254)
		(layers "F.Cu" "B.Cu")
		(net "M_M_DQ<18>")
	)
	(segment
		(start 57.74944 -152.078436)
		(end 57.74944 -150.814278)
		(width 0.1651)
		(layer "B.Cu")
		(net "M_M_DQ<18>")
	)
	(segment
		(start 58.417968 -143.5354)
		(end 58.417968 -143.994378)
		(width 0.14224)
		(layer "In11.Cu")
		(net "M_M_DQ<18>")
	)
	(segment
		(start 58.316368 -148.6154)
		(end 58.316368 -149.123654)
		(width 0.14224)
		(layer "In11.Cu")
		(net "M_M_DQ<18>")
	)
	(segment
		(start 73.353422 -105.383584)
		(end 72.873362 -105.383584)
		(width 0.0889)
		(layer "In11.Cu")
		(net "M_M_DQ<18>")
	)
	(segment
		(start 70.77583 -111.57712)
		(end 67.854576 -114.498374)
		(width 0.14224)
		(layer "In11.Cu")
		(net "M_M_DQ<18>")
	)
	(segment
		(start 80.567022 -95.014288)
		(end 80.401922 -95.300292)
		(width 0.0889)
		(layer "In11.Cu")
		(net "M_M_DQ<18>")
	)
	(segment
		(start 58.036968 -131.141978)
		(end 58.214768 -131.319778)
		(width 0.14224)
		(layer "In11.Cu")
		(net "M_M_DQ<18>")
	)
	(segment
		(start 76.636372 -98.090736)
		(end 76.603606 -98.090736)
		(width 0.0889)
		(layer "In11.Cu")
		(net "M_M_DQ<18>")
	)
	(segment
		(start 58.036968 -138.7094)
		(end 58.367168 -139.0396)
		(width 0.14224)
		(layer "In11.Cu")
		(net "M_M_DQ<18>")
	)
	(segment
		(start 58.367168 -146.2532)
		(end 58.087768 -146.5326)
		(width 0.14224)
		(layer "In11.Cu")
		(net "M_M_DQ<18>")
	)
	(segment
		(start 58.417968 -134.3914)
		(end 58.011568 -134.7978)
		(width 0.14224)
		(layer "In11.Cu")
		(net "M_M_DQ<18>")
	)
	(segment
		(start 58.217562 -122.628914)
		(end 58.217562 -129.859024)
		(width 0.14224)
		(layer "In11.Cu")
		(net "M_M_DQ<18>")
	)
	(segment
		(start 71.693532 -111.920528)
		(end 71.406512 -111.920528)
		(width 0.14224)
		(layer "In11.Cu")
		(net "M_M_DQ<18>")
	)
	(segment
		(start 71.406512 -111.920528)
		(end 71.06285 -111.57712)
		(width 0.14224)
		(layer "In11.Cu")
		(net "M_M_DQ<18>")
	)
	(segment
		(start 58.214768 -133.731)
		(end 58.417968 -133.9342)
		(width 0.14224)
		(layer "In11.Cu")
		(net "M_M_DQ<18>")
	)
	(segment
		(start 58.214768 -131.319778)
		(end 58.214768 -133.731)
		(width 0.14224)
		(layer "In11.Cu")
		(net "M_M_DQ<18>")
	)
	(segment
		(start 78.353158 -97.100136)
		(end 78.320392 -97.100136)
		(width 0.0889)
		(layer "In11.Cu")
		(net "M_M_DQ<18>")
	)
	(segment
		(start 57.74944 -150.814278)
		(end 57.31637 -151.247348)
		(width 0.14224)
		(layer "In11.Cu")
		(net "M_M_DQ<18>")
	)
	(segment
		(start 66.006218 -115.127786)
		(end 65.71869 -115.127786)
		(width 0.14224)
		(layer "In11.Cu")
		(net "M_M_DQ<18>")
	)
	(segment
		(start 58.417968 -143.994378)
		(end 58.039508 -144.372838)
		(width 0.14224)
		(layer "In11.Cu")
		(net "M_M_DQ<18>")
	)
	(segment
		(start 71.956168 -106.300778)
		(end 71.956168 -110.396782)
		(width 0.14224)
		(layer "In11.Cu")
		(net "M_M_DQ<18>")
	)
	(segment
		(start 66.58102 -114.552984)
		(end 67.067938 -115.039902)
		(width 0.14224)
		(layer "In11.Cu")
		(net "M_M_DQ<18>")
	)
	(segment
		(start 57.31637 -153.834846)
		(end 58.599324 -155.1178)
		(width 0.14224)
		(layer "In11.Cu")
		(net "M_M_DQ<18>")
	)
	(segment
		(start 66.58102 -114.265456)
		(end 66.58102 -114.552984)
		(width 0.14224)
		(layer "In11.Cu")
		(net "M_M_DQ<18>")
	)
	(segment
		(start 75.349862 -103.387144)
		(end 73.353422 -105.383584)
		(width 0.0889)
		(layer "In11.Cu")
		(net "M_M_DQ<18>")
	)
	(segment
		(start 58.316368 -149.123654)
		(end 58.062622 -149.3774)
		(width 0.14224)
		(layer "In11.Cu")
		(net "M_M_DQ<18>")
	)
	(segment
		(start 80.070198 -96.109536)
		(end 80.037432 -96.109536)
		(width 0.0889)
		(layer "In11.Cu")
		(net "M_M_DQ<18>")
	)
	(segment
		(start 67.567556 -114.498374)
		(end 67.101466 -114.03203)
		(width 0.14224)
		(layer "In11.Cu")
		(net "M_M_DQ<18>")
	)
	(segment
		(start 79.207868 -96.60509)
		(end 79.175102 -96.60509)
		(width 0.0889)
		(layer "In11.Cu")
		(net "M_M_DQ<18>")
	)
	(segment
		(start 81.772252 -94.718886)
		(end 80.948276 -94.81439)
		(width 0.0889)
		(layer "In11.Cu")
		(net "M_M_DQ<18>")
	)
	(segment
		(start 77.479906 -97.59569)
		(end 77.458316 -97.59569)
		(width 0.0889)
		(layer "In11.Cu")
		(net "M_M_DQ<18>")
	)
	(segment
		(start 66.814446 -114.03203)
		(end 66.58102 -114.265456)
		(width 0.14224)
		(layer "In11.Cu")
		(net "M_M_DQ<18>")
	)
	(segment
		(start 58.039508 -144.372838)
		(end 58.039508 -145.59534)
		(width 0.14224)
		(layer "In11.Cu")
		(net "M_M_DQ<18>")
	)
	(segment
		(start 72.873362 -105.383584)
		(end 71.956168 -106.300778)
		(width 0.14224)
		(layer "In11.Cu")
		(net "M_M_DQ<18>")
	)
	(segment
		(start 58.417968 -141.096746)
		(end 58.417968 -141.605)
		(width 0.14224)
		(layer "In11.Cu")
		(net "M_M_DQ<18>")
	)
	(segment
		(start 71.637652 -110.715298)
		(end 71.637652 -111.002318)
		(width 0.14224)
		(layer "In11.Cu")
		(net "M_M_DQ<18>")
	)
	(segment
		(start 58.039508 -145.59534)
		(end 58.367168 -145.923)
		(width 0.14224)
		(layer "In11.Cu")
		(net "M_M_DQ<18>")
	)
	(segment
		(start 57.706768 -149.3774)
		(end 57.404508 -149.67966)
		(width 0.14224)
		(layer "In11.Cu")
		(net "M_M_DQ<18>")
	)
	(segment
		(start 65.71869 -115.127786)
		(end 58.217562 -122.628914)
		(width 0.14224)
		(layer "In11.Cu")
		(net "M_M_DQ<18>")
	)
	(segment
		(start 67.067938 -115.32743)
		(end 66.780664 -115.614704)
		(width 0.14224)
		(layer "In11.Cu")
		(net "M_M_DQ<18>")
	)
	(segment
		(start 66.493136 -115.614704)
		(end 66.006218 -115.127786)
		(width 0.14224)
		(layer "In11.Cu")
		(net "M_M_DQ<18>")
	)
	(segment
		(start 67.067938 -115.039902)
		(end 67.067938 -115.32743)
		(width 0.14224)
		(layer "In11.Cu")
		(net "M_M_DQ<18>")
	)
	(segment
		(start 58.417968 -133.9342)
		(end 58.417968 -134.3914)
		(width 0.14224)
		(layer "In11.Cu")
		(net "M_M_DQ<18>")
	)
	(segment
		(start 58.33491 -136.582658)
		(end 58.036968 -136.8806)
		(width 0.14224)
		(layer "In11.Cu")
		(net "M_M_DQ<18>")
	)
	(segment
		(start 58.189368 -141.8336)
		(end 58.189368 -143.3068)
		(width 0.14224)
		(layer "In11.Cu")
		(net "M_M_DQ<18>")
	)
	(segment
		(start 58.036968 -130.039618)
		(end 58.036968 -131.141978)
		(width 0.14224)
		(layer "In11.Cu")
		(net "M_M_DQ<18>")
	)
	(segment
		(start 58.036968 -136.8806)
		(end 58.036968 -138.7094)
		(width 0.14224)
		(layer "In11.Cu")
		(net "M_M_DQ<18>")
	)
	(segment
		(start 58.011568 -134.7978)
		(end 58.011568 -135.9916)
		(width 0.14224)
		(layer "In11.Cu")
		(net "M_M_DQ<18>")
	)
	(segment
		(start 58.367168 -145.923)
		(end 58.367168 -146.2532)
		(width 0.14224)
		(layer "In11.Cu")
		(net "M_M_DQ<18>")
	)
	(segment
		(start 57.31637 -151.247348)
		(end 57.31637 -153.834846)
		(width 0.14224)
		(layer "In11.Cu")
		(net "M_M_DQ<18>")
	)
	(segment
		(start 80.401922 -95.509588)
		(end 80.406748 -95.518224)
		(width 0.0889)
		(layer "In11.Cu")
		(net "M_M_DQ<18>")
	)
	(segment
		(start 58.087768 -146.5326)
		(end 58.087768 -148.3868)
		(width 0.14224)
		(layer "In11.Cu")
		(net "M_M_DQ<18>")
	)
	(segment
		(start 58.367168 -139.471146)
		(end 58.115708 -139.722606)
		(width 0.14224)
		(layer "In11.Cu")
		(net "M_M_DQ<18>")
	)
	(segment
		(start 58.087768 -148.3868)
		(end 58.316368 -148.6154)
		(width 0.14224)
		(layer "In11.Cu")
		(net "M_M_DQ<18>")
	)
	(segment
		(start 66.780664 -115.614704)
		(end 66.493136 -115.614704)
		(width 0.14224)
		(layer "In11.Cu")
		(net "M_M_DQ<18>")
	)
	(segment
		(start 58.189368 -143.3068)
		(end 58.417968 -143.5354)
		(width 0.14224)
		(layer "In11.Cu")
		(net "M_M_DQ<18>")
	)
	(segment
		(start 71.637652 -111.002318)
		(end 71.981314 -111.345726)
		(width 0.14224)
		(layer "In11.Cu")
		(net "M_M_DQ<18>")
	)
	(segment
		(start 77.826362 -97.395538)
		(end 77.82306 -97.40138)
		(width 0.0889)
		(layer "In11.Cu")
		(net "M_M_DQ<18>")
	)
	(segment
		(start 75.244706 -101.44252)
		(end 75.349862 -101.629972)
		(width 0.0889)
		(layer "In11.Cu")
		(net "M_M_DQ<18>")
	)
	(segment
		(start 57.404508 -150.469346)
		(end 57.74944 -150.814278)
		(width 0.14224)
		(layer "In11.Cu")
		(net "M_M_DQ<18>")
	)
	(segment
		(start 58.217562 -129.859024)
		(end 58.036968 -130.039618)
		(width 0.14224)
		(layer "In11.Cu")
		(net "M_M_DQ<18>")
	)
	(segment
		(start 58.115708 -140.794486)
		(end 58.417968 -141.096746)
		(width 0.14224)
		(layer "In11.Cu")
		(net "M_M_DQ<18>")
	)
	(segment
		(start 67.854576 -114.498374)
		(end 67.567556 -114.498374)
		(width 0.14224)
		(layer "In11.Cu")
		(net "M_M_DQ<18>")
	)
	(segment
		(start 75.774042 -98.58629)
		(end 75.741276 -98.58629)
		(width 0.0889)
		(layer "In11.Cu")
		(net "M_M_DQ<18>")
	)
	(segment
		(start 58.417968 -141.605)
		(end 58.189368 -141.8336)
		(width 0.14224)
		(layer "In11.Cu")
		(net "M_M_DQ<18>")
	)
	(segment
		(start 57.404508 -149.67966)
		(end 57.404508 -150.469346)
		(width 0.14224)
		(layer "In11.Cu")
		(net "M_M_DQ<18>")
	)
	(segment
		(start 71.981314 -111.632746)
		(end 71.693532 -111.920528)
		(width 0.14224)
		(layer "In11.Cu")
		(net "M_M_DQ<18>")
	)
	(segment
		(start 58.062622 -149.3774)
		(end 57.706768 -149.3774)
		(width 0.14224)
		(layer "In11.Cu")
		(net "M_M_DQ<18>")
	)
	(segment
		(start 71.06285 -111.57712)
		(end 70.77583 -111.57712)
		(width 0.14224)
		(layer "In11.Cu")
		(net "M_M_DQ<18>")
	)
	(segment
		(start 58.011568 -135.9916)
		(end 58.33491 -136.314942)
		(width 0.14224)
		(layer "In11.Cu")
		(net "M_M_DQ<18>")
	)
	(segment
		(start 75.251056 -99.872038)
		(end 75.244706 -99.882706)
		(width 0.0889)
		(layer "In11.Cu")
		(net "M_M_DQ<18>")
	)
	(segment
		(start 58.33491 -136.314942)
		(end 58.33491 -136.582658)
		(width 0.14224)
		(layer "In11.Cu")
		(net "M_M_DQ<18>")
	)
	(segment
		(start 75.251056 -100.462588)
		(end 75.255882 -100.471224)
		(width 0.0889)
		(layer "In11.Cu")
		(net "M_M_DQ<18>")
	)
	(segment
		(start 67.101466 -114.03203)
		(end 66.814446 -114.03203)
		(width 0.14224)
		(layer "In11.Cu")
		(net "M_M_DQ<18>")
	)
	(segment
		(start 71.956168 -110.396782)
		(end 71.637652 -110.715298)
		(width 0.14224)
		(layer "In11.Cu")
		(net "M_M_DQ<18>")
	)
	(segment
		(start 71.981314 -111.345726)
		(end 71.981314 -111.632746)
		(width 0.14224)
		(layer "In11.Cu")
		(net "M_M_DQ<18>")
	)
	(segment
		(start 58.115708 -139.722606)
		(end 58.115708 -140.794486)
		(width 0.14224)
		(layer "In11.Cu")
		(net "M_M_DQ<18>")
	)
	(segment
		(start 58.367168 -139.0396)
		(end 58.367168 -139.471146)
		(width 0.14224)
		(layer "In11.Cu")
		(net "M_M_DQ<18>")
	)
	(segment
		(start 80.948276 -94.81439)
		(end 80.898746 -94.81439)
		(width 0.0889)
		(layer "In11.Cu")
		(net "M_M_DQ<18>")
	)
	(segment
		(start 75.349862 -101.629972)
		(end 75.349862 -103.387144)
		(width 0.0889)
		(layer "In11.Cu")
		(net "M_M_DQ<18>")
	)
	(arc
		(start 75.244706 -99.882706)
		(mid 75.171908 -100.173469)
		(end 75.251056 -100.462588)
		(width 0.0889)
		(layer "In11.Cu")
		(net "M_M_DQ<18>")
	)
	(arc
		(start 76.603606 -98.090736)
		(mid 76.318182 -98.174203)
		(end 76.109576 -98.386138)
		(width 0.0889)
		(layer "In11.Cu")
		(net "M_M_DQ<18>")
	)
	(arc
		(start 76.968096 -97.890838)
		(mid 76.828017 -98.033574)
		(end 76.636372 -98.090736)
		(width 0.0889)
		(layer "In11.Cu")
		(net "M_M_DQ<18>")
	)
	(arc
		(start 77.82306 -97.40138)
		(mid 77.677094 -97.543779)
		(end 77.479906 -97.59569)
		(width 0.0889)
		(layer "In11.Cu")
		(net "M_M_DQ<18>")
	)
	(arc
		(start 78.684882 -96.900238)
		(mid 78.544803 -97.042974)
		(end 78.353158 -97.100136)
		(width 0.0889)
		(layer "In11.Cu")
		(net "M_M_DQ<18>")
	)
	(arc
		(start 75.251056 -99.472242)
		(mid 75.304555 -99.67214)
		(end 75.251056 -99.872038)
		(width 0.0889)
		(layer "In11.Cu")
		(net "M_M_DQ<18>")
	)
	(arc
		(start 77.458316 -97.59569)
		(mid 77.175099 -97.679971)
		(end 76.968096 -97.890838)
		(width 0.0889)
		(layer "In11.Cu")
		(net "M_M_DQ<18>")
	)
	(arc
		(start 75.251056 -100.862638)
		(mid 75.171834 -101.151756)
		(end 75.244706 -101.44252)
		(width 0.0889)
		(layer "In11.Cu")
		(net "M_M_DQ<18>")
	)
	(arc
		(start 80.037432 -96.109536)
		(mid 79.752008 -96.193003)
		(end 79.543402 -96.404938)
		(width 0.0889)
		(layer "In11.Cu")
		(net "M_M_DQ<18>")
	)
	(arc
		(start 80.898746 -94.81439)
		(mid 80.707104 -94.871556)
		(end 80.567022 -95.014288)
		(width 0.0889)
		(layer "In11.Cu")
		(net "M_M_DQ<18>")
	)
	(arc
		(start 79.175102 -96.60509)
		(mid 78.891885 -96.689371)
		(end 78.684882 -96.900238)
		(width 0.0889)
		(layer "In11.Cu")
		(net "M_M_DQ<18>")
	)
	(arc
		(start 76.109576 -98.386138)
		(mid 75.967893 -98.529942)
		(end 75.774042 -98.58629)
		(width 0.0889)
		(layer "In11.Cu")
		(net "M_M_DQ<18>")
	)
	(arc
		(start 75.255882 -100.471224)
		(mid 75.304637 -100.667576)
		(end 75.251056 -100.862638)
		(width 0.0889)
		(layer "In11.Cu")
		(net "M_M_DQ<18>")
	)
	(arc
		(start 80.406748 -95.518224)
		(mid 80.403001 -95.90748)
		(end 80.070198 -96.109536)
		(width 0.0889)
		(layer "In11.Cu")
		(net "M_M_DQ<18>")
	)
	(arc
		(start 75.741276 -98.58629)
		(mid 75.245799 -98.890733)
		(end 75.251056 -99.472242)
		(width 0.0889)
		(layer "In11.Cu")
		(net "M_M_DQ<18>")
	)
	(arc
		(start 80.401922 -95.300292)
		(mid 80.373895 -95.40494)
		(end 80.401922 -95.509588)
		(width 0.0889)
		(layer "In11.Cu")
		(net "M_M_DQ<18>")
	)
	(arc
		(start 78.320392 -97.100136)
		(mid 78.034968 -97.183603)
		(end 77.826362 -97.395538)
		(width 0.0889)
		(layer "In11.Cu")
		(net "M_M_DQ<18>")
	)
	(arc
		(start 79.543402 -96.404938)
		(mid 79.401719 -96.548742)
		(end 79.207868 -96.60509)
		(width 0.0889)
		(layer "In11.Cu")
		(net "M_M_DQ<18>")
	)
	(segment
		(start 79.768192 -93.23324)
		(end 79.196692 -93.23324)
		(width 0.1651)
		(layer "F.Cu")
		(net "M_M_DQ<17>")
	)
	(segment
		(start 51.79949 -152.273)
		(end 51.79949 -153.542746)
		(width 0.1651)
		(layer "F.Cu")
		(net "M_M_DQ<17>")
	)
	(via
		(at 51.79949 -153.542746)
		(size 0.508)
		(drill 0.254)
		(layers "F.Cu" "B.Cu")
		(net "M_M_DQ<17>")
	)
	(via
		(at 79.196692 -93.23324)
		(size 0.508)
		(drill 0.254)
		(layers "F.Cu" "B.Cu")
		(net "M_M_DQ<17>")
	)
	(via
		(at 52.471574 -149.533356)
		(size 0.508)
		(drill 0.254)
		(layers "F.Cu" "B.Cu")
		(net "M_M_DQ<17>")
	)
	(segment
		(start 52.471574 -149.030182)
		(end 52.471574 -149.533356)
		(width 0.1651)
		(layer "B.Cu")
		(net "M_M_DQ<17>")
	)
	(segment
		(start 52.649374 -148.852382)
		(end 52.471574 -149.030182)
		(width 0.1651)
		(layer "B.Cu")
		(net "M_M_DQ<17>")
	)
	(segment
		(start 52.649374 -147.478496)
		(end 52.649374 -148.852382)
		(width 0.1651)
		(layer "B.Cu")
		(net "M_M_DQ<17>")
	)
	(segment
		(start 53.083968 -143.3576)
		(end 53.083968 -143.7386)
		(width 0.14224)
		(layer "In11.Cu")
		(net "M_M_DQ<17>")
	)
	(segment
		(start 52.251356 -150.621746)
		(end 52.251356 -151.026368)
		(width 0.14224)
		(layer "In11.Cu")
		(net "M_M_DQ<17>")
	)
	(segment
		(start 74.925936 -95.309436)
		(end 74.89317 -95.309436)
		(width 0.0889)
		(layer "In11.Cu")
		(net "M_M_DQ<17>")
	)
	(segment
		(start 53.337968 -132.1054)
		(end 53.337968 -132.439664)
		(width 0.14224)
		(layer "In11.Cu")
		(net "M_M_DQ<17>")
	)
	(segment
		(start 76.639166 -94.31909)
		(end 76.603352 -94.31909)
		(width 0.0889)
		(layer "In11.Cu")
		(net "M_M_DQ<17>")
	)
	(segment
		(start 52.200556 -153.3906)
		(end 52.04841 -153.542746)
		(width 0.14224)
		(layer "In11.Cu")
		(net "M_M_DQ<17>")
	)
	(segment
		(start 52.959508 -148.956522)
		(end 52.471574 -149.444456)
		(width 0.14224)
		(layer "In11.Cu")
		(net "M_M_DQ<17>")
	)
	(segment
		(start 78.641194 -93.326458)
		(end 78.619096 -93.32849)
		(width 0.0889)
		(layer "In11.Cu")
		(net "M_M_DQ<17>")
	)
	(segment
		(start 54.48554 -125.446028)
		(end 53.160168 -126.7714)
		(width 0.14224)
		(layer "In11.Cu")
		(net "M_M_DQ<17>")
	)
	(segment
		(start 54.48554 -120.58015)
		(end 54.3306 -120.73509)
		(width 0.14224)
		(layer "In11.Cu")
		(net "M_M_DQ<17>")
	)
	(segment
		(start 53.969666 -121.39295)
		(end 54.124606 -121.54789)
		(width 0.14224)
		(layer "In11.Cu")
		(net "M_M_DQ<17>")
	)
	(segment
		(start 52.931568 -137.855198)
		(end 53.20157 -138.1252)
		(width 0.14224)
		(layer "In11.Cu")
		(net "M_M_DQ<17>")
	)
	(segment
		(start 77.995018 -93.5228)
		(end 77.991716 -93.528642)
		(width 0.0889)
		(layer "In11.Cu")
		(net "M_M_DQ<17>")
	)
	(segment
		(start 52.449222 -149.533356)
		(end 52.020978 -149.9616)
		(width 0.14224)
		(layer "In11.Cu")
		(net "M_M_DQ<17>")
	)
	(segment
		(start 69.27596 -102.414578)
		(end 68.801488 -102.88905)
		(width 0.0889)
		(layer "In11.Cu")
		(net "M_M_DQ<17>")
	)
	(segment
		(start 52.946046 -133.299454)
		(end 53.258466 -133.611874)
		(width 0.14224)
		(layer "In11.Cu")
		(net "M_M_DQ<17>")
	)
	(segment
		(start 52.175156 -151.892)
		(end 52.175156 -152.3238)
		(width 0.14224)
		(layer "In11.Cu")
		(net "M_M_DQ<17>")
	)
	(segment
		(start 67.527678 -106.923586)
		(end 54.48554 -119.965724)
		(width 0.14224)
		(layer "In11.Cu")
		(net "M_M_DQ<17>")
	)
	(segment
		(start 52.829968 -143.1036)
		(end 53.083968 -143.3576)
		(width 0.14224)
		(layer "In11.Cu")
		(net "M_M_DQ<17>")
	)
	(segment
		(start 54.48554 -119.965724)
		(end 54.48554 -120.58015)
		(width 0.14224)
		(layer "In11.Cu")
		(net "M_M_DQ<17>")
	)
	(segment
		(start 54.3306 -124.79909)
		(end 54.48554 -124.95403)
		(width 0.14224)
		(layer "In11.Cu")
		(net "M_M_DQ<17>")
	)
	(segment
		(start 53.160168 -126.7714)
		(end 53.160168 -129.01168)
		(width 0.14224)
		(layer "In11.Cu")
		(net "M_M_DQ<17>")
	)
	(segment
		(start 52.829968 -147.4978)
		(end 53.083968 -147.7518)
		(width 0.14224)
		(layer "In11.Cu")
		(net "M_M_DQ<17>")
	)
	(segment
		(start 52.020978 -150.391368)
		(end 52.251356 -150.621746)
		(width 0.14224)
		(layer "In11.Cu")
		(net "M_M_DQ<17>")
	)
	(segment
		(start 70.629526 -97.78619)
		(end 70.60057 -97.78619)
		(width 0.0889)
		(layer "In11.Cu")
		(net "M_M_DQ<17>")
	)
	(segment
		(start 78.619096 -93.32849)
		(end 78.338172 -93.32849)
		(width 0.0889)
		(layer "In11.Cu")
		(net "M_M_DQ<17>")
	)
	(segment
		(start 52.829968 -142.4686)
		(end 52.829968 -143.1036)
		(width 0.14224)
		(layer "In11.Cu")
		(net "M_M_DQ<17>")
	)
	(segment
		(start 52.020978 -149.9616)
		(end 52.020978 -150.391368)
		(width 0.14224)
		(layer "In11.Cu")
		(net "M_M_DQ<17>")
	)
	(segment
		(start 52.959508 -138.85926)
		(end 52.959508 -141.37894)
		(width 0.14224)
		(layer "In11.Cu")
		(net "M_M_DQ<17>")
	)
	(segment
		(start 53.337968 -132.439664)
		(end 52.946046 -132.831586)
		(width 0.14224)
		(layer "In11.Cu")
		(net "M_M_DQ<17>")
	)
	(segment
		(start 52.175156 -152.3238)
		(end 51.96078 -152.538176)
		(width 0.14224)
		(layer "In11.Cu")
		(net "M_M_DQ<17>")
	)
	(segment
		(start 53.20157 -138.1252)
		(end 53.20157 -138.617198)
		(width 0.14224)
		(layer "In11.Cu")
		(net "M_M_DQ<17>")
	)
	(segment
		(start 54.3306 -122.36069)
		(end 54.124606 -122.36069)
		(width 0.14224)
		(layer "In11.Cu")
		(net "M_M_DQ<17>")
	)
	(segment
		(start 68.801488 -102.88905)
		(end 68.801488 -103.21671)
		(width 0.0889)
		(layer "In11.Cu")
		(net "M_M_DQ<17>")
	)
	(segment
		(start 52.959508 -148.38426)
		(end 52.959508 -148.956522)
		(width 0.14224)
		(layer "In11.Cu")
		(net "M_M_DQ<17>")
	)
	(segment
		(start 77.501496 -93.82379)
		(end 77.461872 -93.82379)
		(width 0.0889)
		(layer "In11.Cu")
		(net "M_M_DQ<17>")
	)
	(segment
		(start 51.96078 -152.846024)
		(end 52.200556 -153.0858)
		(width 0.14224)
		(layer "In11.Cu")
		(net "M_M_DQ<17>")
	)
	(segment
		(start 54.124606 -121.54789)
		(end 54.3306 -121.54789)
		(width 0.14224)
		(layer "In11.Cu")
		(net "M_M_DQ<17>")
	)
	(segment
		(start 69.774816 -101.253036)
		(end 69.74205 -101.253036)
		(width 0.0889)
		(layer "In11.Cu")
		(net "M_M_DQ<17>")
	)
	(segment
		(start 53.258466 -133.962902)
		(end 52.959508 -134.26186)
		(width 0.14224)
		(layer "In11.Cu")
		(net "M_M_DQ<17>")
	)
	(segment
		(start 54.124606 -123.98629)
		(end 53.969666 -124.14123)
		(width 0.14224)
		(layer "In11.Cu")
		(net "M_M_DQ<17>")
	)
	(segment
		(start 53.969666 -123.01855)
		(end 54.124606 -123.17349)
		(width 0.14224)
		(layer "In11.Cu")
		(net "M_M_DQ<17>")
	)
	(segment
		(start 54.3306 -120.73509)
		(end 54.124606 -120.73509)
		(width 0.14224)
		(layer "In11.Cu")
		(net "M_M_DQ<17>")
	)
	(segment
		(start 53.083968 -143.7386)
		(end 52.959508 -143.86306)
		(width 0.14224)
		(layer "In11.Cu")
		(net "M_M_DQ<17>")
	)
	(segment
		(start 53.969666 -120.89003)
		(end 53.969666 -121.39295)
		(width 0.14224)
		(layer "In11.Cu")
		(net "M_M_DQ<17>")
	)
	(segment
		(start 54.3306 -121.54789)
		(end 54.48554 -121.70283)
		(width 0.14224)
		(layer "In11.Cu")
		(net "M_M_DQ<17>")
	)
	(segment
		(start 52.829968 -147.1168)
		(end 52.829968 -147.4978)
		(width 0.14224)
		(layer "In11.Cu")
		(net "M_M_DQ<17>")
	)
	(segment
		(start 54.124606 -124.79909)
		(end 54.3306 -124.79909)
		(width 0.14224)
		(layer "In11.Cu")
		(net "M_M_DQ<17>")
	)
	(segment
		(start 72.346566 -96.79559)
		(end 72.3138 -96.79559)
		(width 0.0889)
		(layer "In11.Cu")
		(net "M_M_DQ<17>")
	)
	(segment
		(start 53.083968 -146.8628)
		(end 52.829968 -147.1168)
		(width 0.14224)
		(layer "In11.Cu")
		(net "M_M_DQ<17>")
	)
	(segment
		(start 54.535324 -123.83135)
		(end 54.380384 -123.98629)
		(width 0.14224)
		(layer "In11.Cu")
		(net "M_M_DQ<17>")
	)
	(segment
		(start 53.083968 -142.2146)
		(end 52.829968 -142.4686)
		(width 0.14224)
		(layer "In11.Cu")
		(net "M_M_DQ<17>")
	)
	(segment
		(start 51.96078 -152.538176)
		(end 51.96078 -152.846024)
		(width 0.14224)
		(layer "In11.Cu")
		(net "M_M_DQ<17>")
	)
	(segment
		(start 69.406516 -101.453188)
		(end 69.27596 -101.679756)
		(width 0.0889)
		(layer "In11.Cu")
		(net "M_M_DQ<17>")
	)
	(segment
		(start 52.946046 -131.713478)
		(end 53.337968 -132.1054)
		(width 0.14224)
		(layer "In11.Cu")
		(net "M_M_DQ<17>")
	)
	(segment
		(start 52.946046 -132.831586)
		(end 52.946046 -133.299454)
		(width 0.14224)
		(layer "In11.Cu")
		(net "M_M_DQ<17>")
	)
	(segment
		(start 51.96078 -151.316944)
		(end 51.96078 -151.677624)
		(width 0.14224)
		(layer "In11.Cu")
		(net "M_M_DQ<17>")
	)
	(segment
		(start 67.527678 -104.49052)
		(end 67.527678 -106.923586)
		(width 0.14224)
		(layer "In11.Cu")
		(net "M_M_DQ<17>")
	)
	(segment
		(start 53.969666 -122.51563)
		(end 53.969666 -123.01855)
		(width 0.14224)
		(layer "In11.Cu")
		(net "M_M_DQ<17>")
	)
	(segment
		(start 52.471574 -149.533356)
		(end 52.449222 -149.533356)
		(width 0.14224)
		(layer "In11.Cu")
		(net "M_M_DQ<17>")
	)
	(segment
		(start 69.27596 -101.679756)
		(end 69.27596 -102.414578)
		(width 0.0889)
		(layer "In11.Cu")
		(net "M_M_DQ<17>")
	)
	(segment
		(start 52.959508 -134.26186)
		(end 52.959508 -136.57834)
		(width 0.14224)
		(layer "In11.Cu")
		(net "M_M_DQ<17>")
	)
	(segment
		(start 52.959508 -141.37894)
		(end 53.083968 -141.5034)
		(width 0.14224)
		(layer "In11.Cu")
		(net "M_M_DQ<17>")
	)
	(segment
		(start 79.196692 -93.23324)
		(end 78.641194 -93.326458)
		(width 0.0889)
		(layer "In11.Cu")
		(net "M_M_DQ<17>")
	)
	(segment
		(start 53.083968 -148.2598)
		(end 52.959508 -148.38426)
		(width 0.14224)
		(layer "In11.Cu")
		(net "M_M_DQ<17>")
	)
	(segment
		(start 68.801488 -103.21671)
		(end 67.527678 -104.49052)
		(width 0.14224)
		(layer "In11.Cu")
		(net "M_M_DQ<17>")
	)
	(segment
		(start 53.20157 -136.820402)
		(end 53.20157 -137.2616)
		(width 0.14224)
		(layer "In11.Cu")
		(net "M_M_DQ<17>")
	)
	(segment
		(start 54.124606 -120.73509)
		(end 53.969666 -120.89003)
		(width 0.14224)
		(layer "In11.Cu")
		(net "M_M_DQ<17>")
	)
	(segment
		(start 54.380384 -123.98629)
		(end 54.124606 -123.98629)
		(width 0.14224)
		(layer "In11.Cu")
		(net "M_M_DQ<17>")
	)
	(segment
		(start 54.48554 -121.70283)
		(end 54.48554 -122.20575)
		(width 0.14224)
		(layer "In11.Cu")
		(net "M_M_DQ<17>")
	)
	(segment
		(start 75.77582 -94.81439)
		(end 75.74788 -94.81439)
		(width 0.0889)
		(layer "In11.Cu")
		(net "M_M_DQ<17>")
	)
	(segment
		(start 70.271386 -99.95662)
		(end 70.265036 -99.967288)
		(width 0.0889)
		(layer "In11.Cu")
		(net "M_M_DQ<17>")
	)
	(segment
		(start 53.258466 -133.611874)
		(end 53.258466 -133.962902)
		(width 0.14224)
		(layer "In11.Cu")
		(net "M_M_DQ<17>")
	)
	(segment
		(start 52.959508 -143.86306)
		(end 52.959508 -146.20494)
		(width 0.14224)
		(layer "In11.Cu")
		(net "M_M_DQ<17>")
	)
	(segment
		(start 52.471574 -149.444456)
		(end 52.471574 -149.533356)
		(width 0.14224)
		(layer "In11.Cu")
		(net "M_M_DQ<17>")
	)
	(segment
		(start 53.20157 -138.617198)
		(end 52.959508 -138.85926)
		(width 0.14224)
		(layer "In11.Cu")
		(net "M_M_DQ<17>")
	)
	(segment
		(start 71.491856 -97.290636)
		(end 71.45909 -97.290636)
		(width 0.0889)
		(layer "In11.Cu")
		(net "M_M_DQ<17>")
	)
	(segment
		(start 54.380384 -123.17349)
		(end 54.535324 -123.32843)
		(width 0.14224)
		(layer "In11.Cu")
		(net "M_M_DQ<17>")
	)
	(segment
		(start 54.124606 -123.17349)
		(end 54.380384 -123.17349)
		(width 0.14224)
		(layer "In11.Cu")
		(net "M_M_DQ<17>")
	)
	(segment
		(start 54.535324 -123.32843)
		(end 54.535324 -123.83135)
		(width 0.14224)
		(layer "In11.Cu")
		(net "M_M_DQ<17>")
	)
	(segment
		(start 54.124606 -122.36069)
		(end 53.969666 -122.51563)
		(width 0.14224)
		(layer "In11.Cu")
		(net "M_M_DQ<17>")
	)
	(segment
		(start 52.959508 -146.20494)
		(end 53.083968 -146.3294)
		(width 0.14224)
		(layer "In11.Cu")
		(net "M_M_DQ<17>")
	)
	(segment
		(start 52.959508 -136.57834)
		(end 53.20157 -136.820402)
		(width 0.14224)
		(layer "In11.Cu")
		(net "M_M_DQ<17>")
	)
	(segment
		(start 53.969666 -124.64415)
		(end 54.124606 -124.79909)
		(width 0.14224)
		(layer "In11.Cu")
		(net "M_M_DQ<17>")
	)
	(segment
		(start 74.063606 -95.80499)
		(end 74.03084 -95.80499)
		(width 0.0889)
		(layer "In11.Cu")
		(net "M_M_DQ<17>")
	)
	(segment
		(start 52.251356 -151.026368)
		(end 51.96078 -151.316944)
		(width 0.14224)
		(layer "In11.Cu")
		(net "M_M_DQ<17>")
	)
	(segment
		(start 52.200556 -153.0858)
		(end 52.200556 -153.3906)
		(width 0.14224)
		(layer "In11.Cu")
		(net "M_M_DQ<17>")
	)
	(segment
		(start 53.20157 -137.2616)
		(end 52.931568 -137.531602)
		(width 0.14224)
		(layer "In11.Cu")
		(net "M_M_DQ<17>")
	)
	(segment
		(start 53.083968 -147.7518)
		(end 53.083968 -148.2598)
		(width 0.14224)
		(layer "In11.Cu")
		(net "M_M_DQ<17>")
	)
	(segment
		(start 53.083968 -146.3294)
		(end 53.083968 -146.8628)
		(width 0.14224)
		(layer "In11.Cu")
		(net "M_M_DQ<17>")
	)
	(segment
		(start 51.96078 -151.677624)
		(end 52.175156 -151.892)
		(width 0.14224)
		(layer "In11.Cu")
		(net "M_M_DQ<17>")
	)
	(segment
		(start 73.208896 -96.300036)
		(end 73.17613 -96.300036)
		(width 0.0889)
		(layer "In11.Cu")
		(net "M_M_DQ<17>")
	)
	(segment
		(start 53.969666 -124.14123)
		(end 53.969666 -124.64415)
		(width 0.14224)
		(layer "In11.Cu")
		(net "M_M_DQ<17>")
	)
	(segment
		(start 54.48554 -122.20575)
		(end 54.3306 -122.36069)
		(width 0.14224)
		(layer "In11.Cu")
		(net "M_M_DQ<17>")
	)
	(segment
		(start 52.04841 -153.542746)
		(end 51.79949 -153.542746)
		(width 0.14224)
		(layer "In11.Cu")
		(net "M_M_DQ<17>")
	)
	(segment
		(start 53.083968 -141.5034)
		(end 53.083968 -142.2146)
		(width 0.14224)
		(layer "In11.Cu")
		(net "M_M_DQ<17>")
	)
	(segment
		(start 52.946046 -129.225802)
		(end 52.946046 -131.713478)
		(width 0.14224)
		(layer "In11.Cu")
		(net "M_M_DQ<17>")
	)
	(segment
		(start 54.48554 -124.95403)
		(end 54.48554 -125.446028)
		(width 0.14224)
		(layer "In11.Cu")
		(net "M_M_DQ<17>")
	)
	(segment
		(start 52.931568 -137.531602)
		(end 52.931568 -137.855198)
		(width 0.14224)
		(layer "In11.Cu")
		(net "M_M_DQ<17>")
	)
	(segment
		(start 53.160168 -129.01168)
		(end 52.946046 -129.225802)
		(width 0.14224)
		(layer "In11.Cu")
		(net "M_M_DQ<17>")
	)
	(arc
		(start 70.265036 -98.976942)
		(mid 70.211537 -99.17684)
		(end 70.265036 -99.376738)
		(width 0.0889)
		(layer "In11.Cu")
		(net "M_M_DQ<17>")
	)
	(arc
		(start 75.416156 -95.014288)
		(mid 75.209152 -95.225152)
		(end 74.925936 -95.309436)
		(width 0.0889)
		(layer "In11.Cu")
		(net "M_M_DQ<17>")
	)
	(arc
		(start 71.123556 -97.490788)
		(mid 70.914948 -97.70272)
		(end 70.629526 -97.78619)
		(width 0.0889)
		(layer "In11.Cu")
		(net "M_M_DQ<17>")
	)
	(arc
		(start 76.274676 -94.518988)
		(mid 76.063963 -94.732067)
		(end 75.77582 -94.81439)
		(width 0.0889)
		(layer "In11.Cu")
		(net "M_M_DQ<17>")
	)
	(arc
		(start 69.74205 -101.253036)
		(mid 69.5482 -101.309386)
		(end 69.406516 -101.453188)
		(width 0.0889)
		(layer "In11.Cu")
		(net "M_M_DQ<17>")
	)
	(arc
		(start 70.265036 -100.367084)
		(mid 70.27029 -100.948592)
		(end 69.774816 -101.253036)
		(width 0.0889)
		(layer "In11.Cu")
		(net "M_M_DQ<17>")
	)
	(arc
		(start 76.603352 -94.31909)
		(mid 76.413423 -94.37696)
		(end 76.274676 -94.518988)
		(width 0.0889)
		(layer "In11.Cu")
		(net "M_M_DQ<17>")
	)
	(arc
		(start 70.265036 -99.967288)
		(mid 70.211537 -100.167186)
		(end 70.265036 -100.367084)
		(width 0.0889)
		(layer "In11.Cu")
		(net "M_M_DQ<17>")
	)
	(arc
		(start 71.982076 -96.995488)
		(mid 71.775072 -97.206352)
		(end 71.491856 -97.290636)
		(width 0.0889)
		(layer "In11.Cu")
		(net "M_M_DQ<17>")
	)
	(arc
		(start 71.45909 -97.290636)
		(mid 71.26524 -97.346986)
		(end 71.123556 -97.490788)
		(width 0.0889)
		(layer "In11.Cu")
		(net "M_M_DQ<17>")
	)
	(arc
		(start 78.338172 -93.32849)
		(mid 78.141011 -93.380449)
		(end 77.995018 -93.5228)
		(width 0.0889)
		(layer "In11.Cu")
		(net "M_M_DQ<17>")
	)
	(arc
		(start 73.699116 -96.004888)
		(mid 73.492112 -96.215752)
		(end 73.208896 -96.300036)
		(width 0.0889)
		(layer "In11.Cu")
		(net "M_M_DQ<17>")
	)
	(arc
		(start 70.265036 -98.386138)
		(mid 70.344167 -98.68154)
		(end 70.265036 -98.976942)
		(width 0.0889)
		(layer "In11.Cu")
		(net "M_M_DQ<17>")
	)
	(arc
		(start 70.265036 -99.376738)
		(mid 70.344258 -99.665856)
		(end 70.271386 -99.95662)
		(width 0.0889)
		(layer "In11.Cu")
		(net "M_M_DQ<17>")
	)
	(arc
		(start 75.74788 -94.81439)
		(mid 75.556238 -94.871556)
		(end 75.416156 -95.014288)
		(width 0.0889)
		(layer "In11.Cu")
		(net "M_M_DQ<17>")
	)
	(arc
		(start 77.461872 -93.82379)
		(mid 77.271943 -93.88166)
		(end 77.133196 -94.023688)
		(width 0.0889)
		(layer "In11.Cu")
		(net "M_M_DQ<17>")
	)
	(arc
		(start 73.17613 -96.300036)
		(mid 72.98228 -96.356386)
		(end 72.840596 -96.500188)
		(width 0.0889)
		(layer "In11.Cu")
		(net "M_M_DQ<17>")
	)
	(arc
		(start 72.840596 -96.500188)
		(mid 72.631988 -96.71212)
		(end 72.346566 -96.79559)
		(width 0.0889)
		(layer "In11.Cu")
		(net "M_M_DQ<17>")
	)
	(arc
		(start 70.60057 -97.78619)
		(mid 70.262455 -97.990892)
		(end 70.265036 -98.386138)
		(width 0.0889)
		(layer "In11.Cu")
		(net "M_M_DQ<17>")
	)
	(arc
		(start 77.133196 -94.023688)
		(mid 76.924588 -94.23562)
		(end 76.639166 -94.31909)
		(width 0.0889)
		(layer "In11.Cu")
		(net "M_M_DQ<17>")
	)
	(arc
		(start 77.991716 -93.528642)
		(mid 77.784712 -93.739506)
		(end 77.501496 -93.82379)
		(width 0.0889)
		(layer "In11.Cu")
		(net "M_M_DQ<17>")
	)
	(arc
		(start 74.557636 -95.509588)
		(mid 74.349028 -95.72152)
		(end 74.063606 -95.80499)
		(width 0.0889)
		(layer "In11.Cu")
		(net "M_M_DQ<17>")
	)
	(arc
		(start 74.89317 -95.309436)
		(mid 74.69932 -95.365786)
		(end 74.557636 -95.509588)
		(width 0.0889)
		(layer "In11.Cu")
		(net "M_M_DQ<17>")
	)
	(arc
		(start 74.03084 -95.80499)
		(mid 73.839198 -95.862156)
		(end 73.699116 -96.004888)
		(width 0.0889)
		(layer "In11.Cu")
		(net "M_M_DQ<17>")
	)
	(arc
		(start 72.3138 -96.79559)
		(mid 72.122158 -96.852756)
		(end 71.982076 -96.995488)
		(width 0.0889)
		(layer "In11.Cu")
		(net "M_M_DQ<17>")
	)
	(segment
		(start 81.485232 -92.24264)
		(end 80.913732 -92.24264)
		(width 0.1651)
		(layer "F.Cu")
		(net "M_M_DQ<16>")
	)
	(segment
		(start 52.649374 -156.87294)
		(end 52.649374 -156.878782)
		(width 0.1651)
		(layer "F.Cu")
		(net "M_M_DQ<16>")
	)
	(segment
		(start 52.649374 -156.878782)
		(end 52.471574 -155.0162)
		(width 0.1651)
		(layer "F.Cu")
		(net "M_M_DQ<16>")
	)
	(via
		(at 80.913732 -92.24264)
		(size 0.508)
		(drill 0.254)
		(layers "F.Cu" "B.Cu")
		(net "M_M_DQ<16>")
	)
	(via
		(at 51.79949 -150.814278)
		(size 0.508)
		(drill 0.254)
		(layers "F.Cu" "B.Cu")
		(net "M_M_DQ<16>")
	)
	(via
		(at 52.471574 -155.0162)
		(size 0.508)
		(drill 0.254)
		(layers "F.Cu" "B.Cu")
		(net "M_M_DQ<16>")
	)
	(segment
		(start 51.79949 -152.078436)
		(end 51.79949 -150.814278)
		(width 0.1651)
		(layer "B.Cu")
		(net "M_M_DQ<16>")
	)
	(segment
		(start 52.324508 -134.433818)
		(end 51.981608 -134.776718)
		(width 0.14224)
		(layer "In11.Cu")
		(net "M_M_DQ<16>")
	)
	(segment
		(start 52.324508 -131.953)
		(end 52.220368 -132.05714)
		(width 0.14224)
		(layer "In11.Cu")
		(net "M_M_DQ<16>")
	)
	(segment
		(start 71.485252 -97.100136)
		(end 71.452486 -97.100136)
		(width 0.0889)
		(layer "In11.Cu")
		(net "M_M_DQ<16>")
	)
	(segment
		(start 52.273708 -144.085818)
		(end 51.994308 -144.365218)
		(width 0.14224)
		(layer "In11.Cu")
		(net "M_M_DQ<16>")
	)
	(segment
		(start 52.324508 -134.16534)
		(end 52.324508 -134.433818)
		(width 0.14224)
		(layer "In11.Cu")
		(net "M_M_DQ<16>")
	)
	(segment
		(start 69.768212 -101.062536)
		(end 69.735446 -101.062536)
		(width 0.0889)
		(layer "In11.Cu")
		(net "M_M_DQ<16>")
	)
	(segment
		(start 52.220368 -138.7094)
		(end 52.324508 -138.81354)
		(width 0.14224)
		(layer "In11.Cu")
		(net "M_M_DQ<16>")
	)
	(segment
		(start 53.490368 -125.5014)
		(end 52.499768 -126.492)
		(width 0.14224)
		(layer "In11.Cu")
		(net "M_M_DQ<16>")
	)
	(segment
		(start 51.36642 -154.20721)
		(end 52.17541 -155.0162)
		(width 0.14224)
		(layer "In11.Cu")
		(net "M_M_DQ<16>")
	)
	(segment
		(start 68.352416 -102.767638)
		(end 67.048888 -104.071166)
		(width 0.14224)
		(layer "In11.Cu")
		(net "M_M_DQ<16>")
	)
	(segment
		(start 52.499768 -128.6002)
		(end 52.324508 -128.77546)
		(width 0.14224)
		(layer "In11.Cu")
		(net "M_M_DQ<16>")
	)
	(segment
		(start 51.981608 -139.663678)
		(end 51.981608 -140.743178)
		(width 0.14224)
		(layer "In11.Cu")
		(net "M_M_DQ<16>")
	)
	(segment
		(start 52.220368 -132.05714)
		(end 52.220368 -134.0612)
		(width 0.14224)
		(layer "In11.Cu")
		(net "M_M_DQ<16>")
	)
	(segment
		(start 51.435508 -149.810978)
		(end 51.435508 -150.450296)
		(width 0.14224)
		(layer "In11.Cu")
		(net "M_M_DQ<16>")
	)
	(segment
		(start 80.913732 -92.24264)
		(end 80.092296 -92.337636)
		(width 0.0889)
		(layer "In11.Cu")
		(net "M_M_DQ<16>")
	)
	(segment
		(start 79.214472 -92.83319)
		(end 79.181706 -92.83319)
		(width 0.0889)
		(layer "In11.Cu")
		(net "M_M_DQ<16>")
	)
	(segment
		(start 74.057002 -95.61449)
		(end 74.024236 -95.61449)
		(width 0.0889)
		(layer "In11.Cu")
		(net "M_M_DQ<16>")
	)
	(segment
		(start 75.774042 -94.623636)
		(end 75.749912 -94.623636)
		(width 0.0889)
		(layer "In11.Cu")
		(net "M_M_DQ<16>")
	)
	(segment
		(start 67.048888 -104.071166)
		(end 67.048888 -106.504232)
		(width 0.14224)
		(layer "In11.Cu")
		(net "M_M_DQ<16>")
	)
	(segment
		(start 53.490368 -120.062752)
		(end 53.490368 -125.5014)
		(width 0.14224)
		(layer "In11.Cu")
		(net "M_M_DQ<16>")
	)
	(segment
		(start 52.324508 -136.77646)
		(end 52.220368 -136.8806)
		(width 0.14224)
		(layer "In11.Cu")
		(net "M_M_DQ<16>")
	)
	(segment
		(start 52.324508 -138.81354)
		(end 52.324508 -139.320778)
		(width 0.14224)
		(layer "In11.Cu")
		(net "M_M_DQ<16>")
	)
	(segment
		(start 68.654168 -102.767638)
		(end 68.352416 -102.767638)
		(width 0.0889)
		(layer "In11.Cu")
		(net "M_M_DQ<16>")
	)
	(segment
		(start 51.435508 -150.450296)
		(end 51.79949 -150.814278)
		(width 0.14224)
		(layer "In11.Cu")
		(net "M_M_DQ<16>")
	)
	(segment
		(start 52.220368 -136.8806)
		(end 52.220368 -138.7094)
		(width 0.14224)
		(layer "In11.Cu")
		(net "M_M_DQ<16>")
	)
	(segment
		(start 52.220368 -148.4122)
		(end 52.286408 -148.47824)
		(width 0.14224)
		(layer "In11.Cu")
		(net "M_M_DQ<16>")
	)
	(segment
		(start 52.324508 -131.484878)
		(end 52.324508 -131.953)
		(width 0.14224)
		(layer "In11.Cu")
		(net "M_M_DQ<16>")
	)
	(segment
		(start 51.981608 -140.743178)
		(end 52.273708 -141.035278)
		(width 0.14224)
		(layer "In11.Cu")
		(net "M_M_DQ<16>")
	)
	(segment
		(start 70.099936 -99.872038)
		(end 70.093586 -99.882706)
		(width 0.0889)
		(layer "In11.Cu")
		(net "M_M_DQ<16>")
	)
	(segment
		(start 76.63942 -94.128336)
		(end 76.599796 -94.128336)
		(width 0.0889)
		(layer "In11.Cu")
		(net "M_M_DQ<16>")
	)
	(segment
		(start 52.324508 -136.29894)
		(end 52.324508 -136.77646)
		(width 0.14224)
		(layer "In11.Cu")
		(net "M_M_DQ<16>")
	)
	(segment
		(start 51.981608 -134.776718)
		(end 51.981608 -135.95604)
		(width 0.14224)
		(layer "In11.Cu")
		(net "M_M_DQ<16>")
	)
	(segment
		(start 52.286408 -148.960078)
		(end 51.435508 -149.810978)
		(width 0.14224)
		(layer "In11.Cu")
		(net "M_M_DQ<16>")
	)
	(segment
		(start 69.241416 -101.357938)
		(end 69.085968 -101.627686)
		(width 0.0889)
		(layer "In11.Cu")
		(net "M_M_DQ<16>")
	)
	(segment
		(start 52.220368 -146.26844)
		(end 52.220368 -148.4122)
		(width 0.14224)
		(layer "In11.Cu")
		(net "M_M_DQ<16>")
	)
	(segment
		(start 52.220368 -141.63294)
		(end 52.220368 -143.6878)
		(width 0.14224)
		(layer "In11.Cu")
		(net "M_M_DQ<16>")
	)
	(segment
		(start 51.981608 -131.141978)
		(end 52.324508 -131.484878)
		(width 0.14224)
		(layer "In11.Cu")
		(net "M_M_DQ<16>")
	)
	(segment
		(start 77.492098 -93.633036)
		(end 77.462126 -93.633036)
		(width 0.0889)
		(layer "In11.Cu")
		(net "M_M_DQ<16>")
	)
	(segment
		(start 51.79949 -150.814278)
		(end 51.36642 -151.247348)
		(width 0.14224)
		(layer "In11.Cu")
		(net "M_M_DQ<16>")
	)
	(segment
		(start 52.273708 -141.035278)
		(end 52.273708 -141.5796)
		(width 0.14224)
		(layer "In11.Cu")
		(net "M_M_DQ<16>")
	)
	(segment
		(start 70.099936 -100.462588)
		(end 70.104762 -100.471224)
		(width 0.0889)
		(layer "In11.Cu")
		(net "M_M_DQ<16>")
	)
	(segment
		(start 52.273708 -141.5796)
		(end 52.220368 -141.63294)
		(width 0.14224)
		(layer "In11.Cu")
		(net "M_M_DQ<16>")
	)
	(segment
		(start 52.324508 -128.77546)
		(end 52.324508 -129.719578)
		(width 0.14224)
		(layer "In11.Cu")
		(net "M_M_DQ<16>")
	)
	(segment
		(start 52.273708 -143.74114)
		(end 52.273708 -144.085818)
		(width 0.14224)
		(layer "In11.Cu")
		(net "M_M_DQ<16>")
	)
	(segment
		(start 78.575408 -93.137482)
		(end 78.338172 -93.137482)
		(width 0.0889)
		(layer "In11.Cu")
		(net "M_M_DQ<16>")
	)
	(segment
		(start 78.981554 -92.89288)
		(end 78.575408 -93.137482)
		(width 0.0889)
		(layer "In11.Cu")
		(net "M_M_DQ<16>")
	)
	(segment
		(start 51.994308 -144.365218)
		(end 51.994308 -145.569686)
		(width 0.14224)
		(layer "In11.Cu")
		(net "M_M_DQ<16>")
	)
	(segment
		(start 51.981608 -135.95604)
		(end 52.324508 -136.29894)
		(width 0.14224)
		(layer "In11.Cu")
		(net "M_M_DQ<16>")
	)
	(segment
		(start 70.622922 -97.59569)
		(end 70.590156 -97.59569)
		(width 0.0889)
		(layer "In11.Cu")
		(net "M_M_DQ<16>")
	)
	(segment
		(start 52.220368 -143.6878)
		(end 52.273708 -143.74114)
		(width 0.14224)
		(layer "In11.Cu")
		(net "M_M_DQ<16>")
	)
	(segment
		(start 52.324508 -139.320778)
		(end 51.981608 -139.663678)
		(width 0.14224)
		(layer "In11.Cu")
		(net "M_M_DQ<16>")
	)
	(segment
		(start 69.085968 -101.627686)
		(end 69.085968 -102.335838)
		(width 0.0889)
		(layer "In11.Cu")
		(net "M_M_DQ<16>")
	)
	(segment
		(start 73.202292 -96.109536)
		(end 73.169526 -96.109536)
		(width 0.0889)
		(layer "In11.Cu")
		(net "M_M_DQ<16>")
	)
	(segment
		(start 80.092296 -92.337636)
		(end 80.044036 -92.337636)
		(width 0.0889)
		(layer "In11.Cu")
		(net "M_M_DQ<16>")
	)
	(segment
		(start 52.17541 -155.0162)
		(end 52.471574 -155.0162)
		(width 0.14224)
		(layer "In11.Cu")
		(net "M_M_DQ<16>")
	)
	(segment
		(start 52.220368 -134.0612)
		(end 52.324508 -134.16534)
		(width 0.14224)
		(layer "In11.Cu")
		(net "M_M_DQ<16>")
	)
	(segment
		(start 77.826108 -93.433138)
		(end 77.826362 -93.433138)
		(width 0.0889)
		(layer "In11.Cu")
		(net "M_M_DQ<16>")
	)
	(segment
		(start 74.919332 -95.118936)
		(end 74.886566 -95.118936)
		(width 0.0889)
		(layer "In11.Cu")
		(net "M_M_DQ<16>")
	)
	(segment
		(start 51.994308 -145.569686)
		(end 52.286408 -145.861786)
		(width 0.14224)
		(layer "In11.Cu")
		(net "M_M_DQ<16>")
	)
	(segment
		(start 52.286408 -146.2024)
		(end 52.220368 -146.26844)
		(width 0.14224)
		(layer "In11.Cu")
		(net "M_M_DQ<16>")
	)
	(segment
		(start 67.048888 -106.504232)
		(end 53.490368 -120.062752)
		(width 0.14224)
		(layer "In11.Cu")
		(net "M_M_DQ<16>")
	)
	(segment
		(start 72.339962 -96.60509)
		(end 72.307196 -96.60509)
		(width 0.0889)
		(layer "In11.Cu")
		(net "M_M_DQ<16>")
	)
	(segment
		(start 52.286408 -148.47824)
		(end 52.286408 -148.960078)
		(width 0.14224)
		(layer "In11.Cu")
		(net "M_M_DQ<16>")
	)
	(segment
		(start 51.981608 -130.062478)
		(end 51.981608 -131.141978)
		(width 0.14224)
		(layer "In11.Cu")
		(net "M_M_DQ<16>")
	)
	(segment
		(start 52.499768 -126.492)
		(end 52.499768 -128.6002)
		(width 0.14224)
		(layer "In11.Cu")
		(net "M_M_DQ<16>")
	)
	(segment
		(start 52.324508 -129.719578)
		(end 51.981608 -130.062478)
		(width 0.14224)
		(layer "In11.Cu")
		(net "M_M_DQ<16>")
	)
	(segment
		(start 77.829664 -93.426788)
		(end 77.826108 -93.433138)
		(width 0.0889)
		(layer "In11.Cu")
		(net "M_M_DQ<16>")
	)
	(segment
		(start 51.36642 -151.247348)
		(end 51.36642 -154.20721)
		(width 0.14224)
		(layer "In11.Cu")
		(net "M_M_DQ<16>")
	)
	(segment
		(start 69.085968 -102.335838)
		(end 68.654168 -102.767638)
		(width 0.0889)
		(layer "In11.Cu")
		(net "M_M_DQ<16>")
	)
	(segment
		(start 52.286408 -145.861786)
		(end 52.286408 -146.2024)
		(width 0.14224)
		(layer "In11.Cu")
		(net "M_M_DQ<16>")
	)
	(arc
		(start 74.024236 -95.61449)
		(mid 73.741019 -95.698771)
		(end 73.534016 -95.909638)
		(width 0.0889)
		(layer "In11.Cu")
		(net "M_M_DQ<16>")
	)
	(arc
		(start 70.958456 -97.395538)
		(mid 70.816773 -97.539342)
		(end 70.622922 -97.59569)
		(width 0.0889)
		(layer "In11.Cu")
		(net "M_M_DQ<16>")
	)
	(arc
		(start 73.169526 -96.109536)
		(mid 72.884102 -96.193003)
		(end 72.675496 -96.404938)
		(width 0.0889)
		(layer "In11.Cu")
		(net "M_M_DQ<16>")
	)
	(arc
		(start 69.735446 -101.062536)
		(mid 69.450022 -101.146003)
		(end 69.241416 -101.357938)
		(width 0.0889)
		(layer "In11.Cu")
		(net "M_M_DQ<16>")
	)
	(arc
		(start 75.251056 -94.919038)
		(mid 75.110977 -95.061774)
		(end 74.919332 -95.118936)
		(width 0.0889)
		(layer "In11.Cu")
		(net "M_M_DQ<16>")
	)
	(arc
		(start 71.816976 -96.900238)
		(mid 71.676897 -97.042974)
		(end 71.485252 -97.100136)
		(width 0.0889)
		(layer "In11.Cu")
		(net "M_M_DQ<16>")
	)
	(arc
		(start 79.181706 -92.83319)
		(mid 79.077865 -92.850393)
		(end 78.981554 -92.89288)
		(width 0.0889)
		(layer "In11.Cu")
		(net "M_M_DQ<16>")
	)
	(arc
		(start 70.099936 -98.881438)
		(mid 70.020805 -99.17684)
		(end 70.099936 -99.472242)
		(width 0.0889)
		(layer "In11.Cu")
		(net "M_M_DQ<16>")
	)
	(arc
		(start 80.044036 -92.337636)
		(mid 79.850186 -92.393986)
		(end 79.708502 -92.537788)
		(width 0.0889)
		(layer "In11.Cu")
		(net "M_M_DQ<16>")
	)
	(arc
		(start 73.534016 -95.909638)
		(mid 73.393937 -96.052374)
		(end 73.202292 -96.109536)
		(width 0.0889)
		(layer "In11.Cu")
		(net "M_M_DQ<16>")
	)
	(arc
		(start 74.392536 -95.414338)
		(mid 74.250853 -95.558142)
		(end 74.057002 -95.61449)
		(width 0.0889)
		(layer "In11.Cu")
		(net "M_M_DQ<16>")
	)
	(arc
		(start 77.826362 -93.433138)
		(mid 77.685205 -93.576523)
		(end 77.492098 -93.633036)
		(width 0.0889)
		(layer "In11.Cu")
		(net "M_M_DQ<16>")
	)
	(arc
		(start 77.462126 -93.633036)
		(mid 77.176702 -93.716503)
		(end 76.968096 -93.928438)
		(width 0.0889)
		(layer "In11.Cu")
		(net "M_M_DQ<16>")
	)
	(arc
		(start 74.886566 -95.118936)
		(mid 74.601142 -95.202403)
		(end 74.392536 -95.414338)
		(width 0.0889)
		(layer "In11.Cu")
		(net "M_M_DQ<16>")
	)
	(arc
		(start 79.708502 -92.537788)
		(mid 79.499894 -92.74972)
		(end 79.214472 -92.83319)
		(width 0.0889)
		(layer "In11.Cu")
		(net "M_M_DQ<16>")
	)
	(arc
		(start 70.104762 -100.471224)
		(mid 70.101015 -100.86048)
		(end 69.768212 -101.062536)
		(width 0.0889)
		(layer "In11.Cu")
		(net "M_M_DQ<16>")
	)
	(arc
		(start 70.099936 -98.481642)
		(mid 70.153435 -98.68154)
		(end 70.099936 -98.881438)
		(width 0.0889)
		(layer "In11.Cu")
		(net "M_M_DQ<16>")
	)
	(arc
		(start 76.109576 -94.423484)
		(mid 75.967893 -94.567288)
		(end 75.774042 -94.623636)
		(width 0.0889)
		(layer "In11.Cu")
		(net "M_M_DQ<16>")
	)
	(arc
		(start 71.452486 -97.100136)
		(mid 71.167062 -97.183603)
		(end 70.958456 -97.395538)
		(width 0.0889)
		(layer "In11.Cu")
		(net "M_M_DQ<16>")
	)
	(arc
		(start 72.307196 -96.60509)
		(mid 72.023979 -96.689371)
		(end 71.816976 -96.900238)
		(width 0.0889)
		(layer "In11.Cu")
		(net "M_M_DQ<16>")
	)
	(arc
		(start 76.968096 -93.928438)
		(mid 76.829352 -94.070471)
		(end 76.63942 -94.128336)
		(width 0.0889)
		(layer "In11.Cu")
		(net "M_M_DQ<16>")
	)
	(arc
		(start 72.675496 -96.404938)
		(mid 72.533813 -96.548742)
		(end 72.339962 -96.60509)
		(width 0.0889)
		(layer "In11.Cu")
		(net "M_M_DQ<16>")
	)
	(arc
		(start 75.749912 -94.623636)
		(mid 75.461767 -94.705955)
		(end 75.251056 -94.919038)
		(width 0.0889)
		(layer "In11.Cu")
		(net "M_M_DQ<16>")
	)
	(arc
		(start 70.590156 -97.59569)
		(mid 70.094679 -97.900133)
		(end 70.099936 -98.481642)
		(width 0.0889)
		(layer "In11.Cu")
		(net "M_M_DQ<16>")
	)
	(arc
		(start 70.093586 -99.882706)
		(mid 70.020788 -100.173469)
		(end 70.099936 -100.462588)
		(width 0.0889)
		(layer "In11.Cu")
		(net "M_M_DQ<16>")
	)
	(arc
		(start 78.338172 -93.137482)
		(mid 78.045591 -93.214795)
		(end 77.829664 -93.426788)
		(width 0.0889)
		(layer "In11.Cu")
		(net "M_M_DQ<16>")
	)
	(arc
		(start 70.099936 -99.472242)
		(mid 70.153435 -99.67214)
		(end 70.099936 -99.872038)
		(width 0.0889)
		(layer "In11.Cu")
		(net "M_M_DQ<16>")
	)
	(arc
		(start 76.599796 -94.128336)
		(mid 76.316579 -94.212617)
		(end 76.109576 -94.423484)
		(width 0.0889)
		(layer "In11.Cu")
		(net "M_M_DQ<16>")
	)
	(segment
		(start 46.699424 -152.273)
		(end 46.699424 -153.542746)
		(width 0.1651)
		(layer "F.Cu")
		(net "M_M_DQ<15>")
	)
	(segment
		(start 75.475846 -92.737686)
		(end 74.904346 -92.737686)
		(width 0.1651)
		(layer "F.Cu")
		(net "M_M_DQ<15>")
	)
	(via
		(at 74.904346 -92.737686)
		(size 0.508)
		(drill 0.254)
		(layers "F.Cu" "B.Cu")
		(net "M_M_DQ<15>")
	)
	(via
		(at 47.549308 -149.533356)
		(size 0.508)
		(drill 0.254)
		(layers "F.Cu" "B.Cu")
		(net "M_M_DQ<15>")
	)
	(via
		(at 46.699424 -153.542746)
		(size 0.508)
		(drill 0.254)
		(layers "F.Cu" "B.Cu")
		(net "M_M_DQ<15>")
	)
	(segment
		(start 47.549562 -147.478496)
		(end 47.549308 -147.478496)
		(width 0.1651)
		(layer "B.Cu")
		(net "M_M_DQ<15>")
	)
	(segment
		(start 47.549308 -147.478496)
		(end 47.549308 -149.533356)
		(width 0.1651)
		(layer "B.Cu")
		(net "M_M_DQ<15>")
	)
	(segment
		(start 69.375782 -95.54845)
		(end 68.864226 -96.060006)
		(width 0.0889)
		(layer "In11.Cu")
		(net "M_M_DQ<15>")
	)
	(segment
		(start 47.143162 -151.1046)
		(end 46.860714 -151.387048)
		(width 0.14224)
		(layer "In11.Cu")
		(net "M_M_DQ<15>")
	)
	(segment
		(start 47.098712 -149.9616)
		(end 47.098712 -150.391368)
		(width 0.14224)
		(layer "In11.Cu")
		(net "M_M_DQ<15>")
	)
	(segment
		(start 74.081894 -92.83319)
		(end 74.03084 -92.83319)
		(width 0.0889)
		(layer "In11.Cu")
		(net "M_M_DQ<15>")
	)
	(segment
		(start 47.149512 -153.04135)
		(end 47.149512 -153.364946)
		(width 0.14224)
		(layer "In11.Cu")
		(net "M_M_DQ<15>")
	)
	(segment
		(start 73.20026 -93.32849)
		(end 73.17613 -93.32849)
		(width 0.0889)
		(layer "In11.Cu")
		(net "M_M_DQ<15>")
	)
	(segment
		(start 69.771006 -95.30969)
		(end 69.735192 -95.30969)
		(width 0.0889)
		(layer "In11.Cu")
		(net "M_M_DQ<15>")
	)
	(segment
		(start 47.978568 -136.830054)
		(end 47.978568 -138.7348)
		(width 0.14224)
		(layer "In11.Cu")
		(net "M_M_DQ<15>")
	)
	(segment
		(start 72.350376 -93.82379)
		(end 72.310752 -93.82379)
		(width 0.0889)
		(layer "In11.Cu")
		(net "M_M_DQ<15>")
	)
	(segment
		(start 47.800768 -136.322054)
		(end 47.800768 -136.652254)
		(width 0.14224)
		(layer "In11.Cu")
		(net "M_M_DQ<15>")
	)
	(segment
		(start 47.149512 -153.364946)
		(end 46.971712 -153.542746)
		(width 0.14224)
		(layer "In11.Cu")
		(net "M_M_DQ<15>")
	)
	(segment
		(start 67.172332 -98.930206)
		(end 65.145158 -98.930206)
		(width 0.0889)
		(layer "In11.Cu")
		(net "M_M_DQ<15>")
	)
	(segment
		(start 56.384952 -110.692438)
		(end 56.67248 -110.692438)
		(width 0.14224)
		(layer "In11.Cu")
		(net "M_M_DQ<15>")
	)
	(segment
		(start 47.792386 -144.03451)
		(end 48.130968 -144.373092)
		(width 0.14224)
		(layer "In11.Cu")
		(net "M_M_DQ<15>")
	)
	(segment
		(start 47.978568 -146.5072)
		(end 47.978568 -148.411946)
		(width 0.14224)
		(layer "In11.Cu")
		(net "M_M_DQ<15>")
	)
	(segment
		(start 47.812198 -134.17677)
		(end 47.812198 -134.464552)
		(width 0.14224)
		(layer "In11.Cu")
		(net "M_M_DQ<15>")
	)
	(segment
		(start 47.978568 -138.7348)
		(end 47.800768 -138.9126)
		(width 0.14224)
		(layer "In11.Cu")
		(net "M_M_DQ<15>")
	)
	(segment
		(start 48.105568 -129.1082)
		(end 47.876968 -129.3368)
		(width 0.14224)
		(layer "In11.Cu")
		(net "M_M_DQ<15>")
	)
	(segment
		(start 64.941958 -99.133406)
		(end 64.005968 -100.069396)
		(width 0.14224)
		(layer "In11.Cu")
		(net "M_M_DQ<15>")
	)
	(segment
		(start 47.824644 -131.446524)
		(end 47.824644 -131.79933)
		(width 0.14224)
		(layer "In11.Cu")
		(net "M_M_DQ<15>")
	)
	(segment
		(start 60.19038 -107.487466)
		(end 60.477654 -107.77474)
		(width 0.14224)
		(layer "In11.Cu")
		(net "M_M_DQ<15>")
	)
	(segment
		(start 47.978568 -141.681454)
		(end 47.978568 -143.5608)
		(width 0.14224)
		(layer "In11.Cu")
		(net "M_M_DQ<15>")
	)
	(segment
		(start 48.130714 -130.087878)
		(end 48.130714 -131.140454)
		(width 0.14224)
		(layer "In11.Cu")
		(net "M_M_DQ<15>")
	)
	(segment
		(start 67.908932 -96.060006)
		(end 67.486784 -96.482154)
		(width 0.0889)
		(layer "In11.Cu")
		(net "M_M_DQ<15>")
	)
	(segment
		(start 56.097678 -110.117636)
		(end 56.097678 -110.405164)
		(width 0.14224)
		(layer "In11.Cu")
		(net "M_M_DQ<15>")
	)
	(segment
		(start 47.812198 -134.464552)
		(end 48.232568 -134.884922)
		(width 0.14224)
		(layer "In11.Cu")
		(net "M_M_DQ<15>")
	)
	(segment
		(start 47.891192 -149.191472)
		(end 47.549308 -149.533356)
		(width 0.14224)
		(layer "In11.Cu")
		(net "M_M_DQ<15>")
	)
	(segment
		(start 48.105568 -120.408954)
		(end 48.105568 -129.1082)
		(width 0.14224)
		(layer "In11.Cu")
		(net "M_M_DQ<15>")
	)
	(segment
		(start 47.800768 -138.9126)
		(end 47.800768 -139.359132)
		(width 0.14224)
		(layer "In11.Cu")
		(net "M_M_DQ<15>")
	)
	(segment
		(start 47.978568 -134.0104)
		(end 47.812198 -134.17677)
		(width 0.14224)
		(layer "In11.Cu")
		(net "M_M_DQ<15>")
	)
	(segment
		(start 59.877452 -107.487466)
		(end 60.19038 -107.487466)
		(width 0.14224)
		(layer "In11.Cu")
		(net "M_M_DQ<15>")
	)
	(segment
		(start 48.207168 -139.765532)
		(end 48.207168 -140.6398)
		(width 0.14224)
		(layer "In11.Cu")
		(net "M_M_DQ<15>")
	)
	(segment
		(start 46.971712 -153.542746)
		(end 46.699424 -153.542746)
		(width 0.14224)
		(layer "In11.Cu")
		(net "M_M_DQ<15>")
	)
	(segment
		(start 60.477654 -108.036868)
		(end 48.105568 -120.408954)
		(width 0.14224)
		(layer "In11.Cu")
		(net "M_M_DQ<15>")
	)
	(segment
		(start 47.824644 -131.79933)
		(end 47.978568 -131.953254)
		(width 0.14224)
		(layer "In11.Cu")
		(net "M_M_DQ<15>")
	)
	(segment
		(start 46.860714 -151.660352)
		(end 47.117762 -151.9174)
		(width 0.14224)
		(layer "In11.Cu")
		(net "M_M_DQ<15>")
	)
	(segment
		(start 60.477654 -107.77474)
		(end 60.477654 -108.036868)
		(width 0.14224)
		(layer "In11.Cu")
		(net "M_M_DQ<15>")
	)
	(segment
		(start 47.817532 -146.346164)
		(end 47.978568 -146.5072)
		(width 0.14224)
		(layer "In11.Cu")
		(net "M_M_DQ<15>")
	)
	(segment
		(start 71.488046 -94.31909)
		(end 71.452232 -94.31909)
		(width 0.0889)
		(layer "In11.Cu")
		(net "M_M_DQ<15>")
	)
	(segment
		(start 46.860714 -152.479248)
		(end 46.860714 -152.752552)
		(width 0.14224)
		(layer "In11.Cu")
		(net "M_M_DQ<15>")
	)
	(segment
		(start 47.978568 -131.953254)
		(end 47.978568 -134.0104)
		(width 0.14224)
		(layer "In11.Cu")
		(net "M_M_DQ<15>")
	)
	(segment
		(start 70.6247 -94.81439)
		(end 70.59676 -94.81439)
		(width 0.0889)
		(layer "In11.Cu")
		(net "M_M_DQ<15>")
	)
	(segment
		(start 64.005968 -100.069396)
		(end 64.005968 -102.209346)
		(width 0.14224)
		(layer "In11.Cu")
		(net "M_M_DQ<15>")
	)
	(segment
		(start 47.800768 -139.359132)
		(end 48.207168 -139.765532)
		(width 0.14224)
		(layer "In11.Cu")
		(net "M_M_DQ<15>")
	)
	(segment
		(start 48.232568 -134.884922)
		(end 48.232568 -135.890254)
		(width 0.14224)
		(layer "In11.Cu")
		(net "M_M_DQ<15>")
	)
	(segment
		(start 65.145158 -98.930206)
		(end 64.941958 -99.133406)
		(width 0.0889)
		(layer "In11.Cu")
		(net "M_M_DQ<15>")
	)
	(segment
		(start 46.860714 -151.387048)
		(end 46.860714 -151.660352)
		(width 0.14224)
		(layer "In11.Cu")
		(net "M_M_DQ<15>")
	)
	(segment
		(start 47.902114 -148.4884)
		(end 47.902114 -149.191472)
		(width 0.14224)
		(layer "In11.Cu")
		(net "M_M_DQ<15>")
	)
	(segment
		(start 47.792386 -143.746982)
		(end 47.792386 -144.03451)
		(width 0.14224)
		(layer "In11.Cu")
		(net "M_M_DQ<15>")
	)
	(segment
		(start 47.876968 -129.834132)
		(end 48.130714 -130.087878)
		(width 0.14224)
		(layer "In11.Cu")
		(net "M_M_DQ<15>")
	)
	(segment
		(start 47.741332 -141.444218)
		(end 47.978568 -141.681454)
		(width 0.14224)
		(layer "In11.Cu")
		(net "M_M_DQ<15>")
	)
	(segment
		(start 67.486784 -98.615754)
		(end 67.172332 -98.930206)
		(width 0.0889)
		(layer "In11.Cu")
		(net "M_M_DQ<15>")
	)
	(segment
		(start 74.904346 -92.737686)
		(end 74.081894 -92.83319)
		(width 0.0889)
		(layer "In11.Cu")
		(net "M_M_DQ<15>")
	)
	(segment
		(start 48.232568 -135.890254)
		(end 47.800768 -136.322054)
		(width 0.14224)
		(layer "In11.Cu")
		(net "M_M_DQ<15>")
	)
	(segment
		(start 48.130968 -144.373092)
		(end 48.130968 -145.6182)
		(width 0.14224)
		(layer "In11.Cu")
		(net "M_M_DQ<15>")
	)
	(segment
		(start 47.902114 -149.191472)
		(end 47.891192 -149.191472)
		(width 0.14224)
		(layer "In11.Cu")
		(net "M_M_DQ<15>")
	)
	(segment
		(start 47.876968 -129.3368)
		(end 47.876968 -129.834132)
		(width 0.14224)
		(layer "In11.Cu")
		(net "M_M_DQ<15>")
	)
	(segment
		(start 68.864226 -96.060006)
		(end 67.908932 -96.060006)
		(width 0.0889)
		(layer "In11.Cu")
		(net "M_M_DQ<15>")
	)
	(segment
		(start 47.143162 -150.435818)
		(end 47.143162 -151.1046)
		(width 0.14224)
		(layer "In11.Cu")
		(net "M_M_DQ<15>")
	)
	(segment
		(start 48.130714 -131.140454)
		(end 47.824644 -131.446524)
		(width 0.14224)
		(layer "In11.Cu")
		(net "M_M_DQ<15>")
	)
	(segment
		(start 47.741332 -141.105636)
		(end 47.741332 -141.444218)
		(width 0.14224)
		(layer "In11.Cu")
		(net "M_M_DQ<15>")
	)
	(segment
		(start 47.098712 -150.391368)
		(end 47.143162 -150.435818)
		(width 0.14224)
		(layer "In11.Cu")
		(net "M_M_DQ<15>")
	)
	(segment
		(start 47.978568 -143.5608)
		(end 47.792386 -143.746982)
		(width 0.14224)
		(layer "In11.Cu")
		(net "M_M_DQ<15>")
	)
	(segment
		(start 47.817532 -145.931636)
		(end 47.817532 -146.346164)
		(width 0.14224)
		(layer "In11.Cu")
		(net "M_M_DQ<15>")
	)
	(segment
		(start 47.549308 -149.533356)
		(end 47.526956 -149.533356)
		(width 0.14224)
		(layer "In11.Cu")
		(net "M_M_DQ<15>")
	)
	(segment
		(start 67.486784 -96.482154)
		(end 67.486784 -98.615754)
		(width 0.0889)
		(layer "In11.Cu")
		(net "M_M_DQ<15>")
	)
	(segment
		(start 48.207168 -140.6398)
		(end 47.741332 -141.105636)
		(width 0.14224)
		(layer "In11.Cu")
		(net "M_M_DQ<15>")
	)
	(segment
		(start 47.117762 -152.2222)
		(end 46.860714 -152.479248)
		(width 0.14224)
		(layer "In11.Cu")
		(net "M_M_DQ<15>")
	)
	(segment
		(start 46.860714 -152.752552)
		(end 47.149512 -153.04135)
		(width 0.14224)
		(layer "In11.Cu")
		(net "M_M_DQ<15>")
	)
	(segment
		(start 64.005968 -102.209346)
		(end 56.097678 -110.117636)
		(width 0.14224)
		(layer "In11.Cu")
		(net "M_M_DQ<15>")
	)
	(segment
		(start 47.800768 -136.652254)
		(end 47.978568 -136.830054)
		(width 0.14224)
		(layer "In11.Cu")
		(net "M_M_DQ<15>")
	)
	(segment
		(start 48.130968 -145.6182)
		(end 47.817532 -145.931636)
		(width 0.14224)
		(layer "In11.Cu")
		(net "M_M_DQ<15>")
	)
	(segment
		(start 47.978568 -148.411946)
		(end 47.902114 -148.4884)
		(width 0.14224)
		(layer "In11.Cu")
		(net "M_M_DQ<15>")
	)
	(segment
		(start 56.67248 -110.692438)
		(end 59.877452 -107.487466)
		(width 0.14224)
		(layer "In11.Cu")
		(net "M_M_DQ<15>")
	)
	(segment
		(start 56.097678 -110.405164)
		(end 56.384952 -110.692438)
		(width 0.14224)
		(layer "In11.Cu")
		(net "M_M_DQ<15>")
	)
	(segment
		(start 47.117762 -151.9174)
		(end 47.117762 -152.2222)
		(width 0.14224)
		(layer "In11.Cu")
		(net "M_M_DQ<15>")
	)
	(segment
		(start 47.526956 -149.533356)
		(end 47.098712 -149.9616)
		(width 0.14224)
		(layer "In11.Cu")
		(net "M_M_DQ<15>")
	)
	(arc
		(start 72.310752 -93.82379)
		(mid 72.120823 -93.88166)
		(end 71.982076 -94.023688)
		(width 0.0889)
		(layer "In11.Cu")
		(net "M_M_DQ<15>")
	)
	(arc
		(start 69.406516 -95.509588)
		(mid 69.392557 -95.530131)
		(end 69.375782 -95.54845)
		(width 0.0889)
		(layer "In11.Cu")
		(net "M_M_DQ<15>")
	)
	(arc
		(start 72.840596 -93.528642)
		(mid 72.633592 -93.739506)
		(end 72.350376 -93.82379)
		(width 0.0889)
		(layer "In11.Cu")
		(net "M_M_DQ<15>")
	)
	(arc
		(start 69.735192 -95.30969)
		(mid 69.545263 -95.36756)
		(end 69.406516 -95.509588)
		(width 0.0889)
		(layer "In11.Cu")
		(net "M_M_DQ<15>")
	)
	(arc
		(start 71.123556 -94.518988)
		(mid 70.912843 -94.732067)
		(end 70.6247 -94.81439)
		(width 0.0889)
		(layer "In11.Cu")
		(net "M_M_DQ<15>")
	)
	(arc
		(start 71.982076 -94.023688)
		(mid 71.773468 -94.23562)
		(end 71.488046 -94.31909)
		(width 0.0889)
		(layer "In11.Cu")
		(net "M_M_DQ<15>")
	)
	(arc
		(start 70.265036 -95.014288)
		(mid 70.056428 -95.22622)
		(end 69.771006 -95.30969)
		(width 0.0889)
		(layer "In11.Cu")
		(net "M_M_DQ<15>")
	)
	(arc
		(start 73.699116 -93.033088)
		(mid 73.488403 -93.246167)
		(end 73.20026 -93.32849)
		(width 0.0889)
		(layer "In11.Cu")
		(net "M_M_DQ<15>")
	)
	(arc
		(start 70.59676 -94.81439)
		(mid 70.405118 -94.871556)
		(end 70.265036 -95.014288)
		(width 0.0889)
		(layer "In11.Cu")
		(net "M_M_DQ<15>")
	)
	(arc
		(start 74.03084 -92.83319)
		(mid 73.839198 -92.890356)
		(end 73.699116 -93.033088)
		(width 0.0889)
		(layer "In11.Cu")
		(net "M_M_DQ<15>")
	)
	(arc
		(start 73.17613 -93.32849)
		(mid 72.98228 -93.38484)
		(end 72.840596 -93.528642)
		(width 0.0889)
		(layer "In11.Cu")
		(net "M_M_DQ<15>")
	)
	(arc
		(start 71.452232 -94.31909)
		(mid 71.262303 -94.37696)
		(end 71.123556 -94.518988)
		(width 0.0889)
		(layer "In11.Cu")
		(net "M_M_DQ<15>")
	)
	(segment
		(start 47.549562 -155.118054)
		(end 47.549308 -155.1178)
		(width 0.1651)
		(layer "F.Cu")
		(net "M_M_DQ<14>")
	)
	(segment
		(start 47.549562 -155.9052)
		(end 47.681642 -155.77312)
		(width 0.1651)
		(layer "F.Cu")
		(net "M_M_DQ<14>")
	)
	(segment
		(start 47.549562 -156.87294)
		(end 47.549562 -155.9052)
		(width 0.1651)
		(layer "F.Cu")
		(net "M_M_DQ<14>")
	)
	(segment
		(start 47.549562 -155.4226)
		(end 47.549562 -155.118054)
		(width 0.1651)
		(layer "F.Cu")
		(net "M_M_DQ<14>")
	)
	(segment
		(start 47.681642 -155.77312)
		(end 47.681642 -155.55468)
		(width 0.1651)
		(layer "F.Cu")
		(net "M_M_DQ<14>")
	)
	(segment
		(start 47.681642 -155.55468)
		(end 47.549562 -155.4226)
		(width 0.1651)
		(layer "F.Cu")
		(net "M_M_DQ<14>")
	)
	(segment
		(start 75.475846 -91.747086)
		(end 74.904346 -91.747086)
		(width 0.1651)
		(layer "F.Cu")
		(net "M_M_DQ<14>")
	)
	(via
		(at 74.904346 -91.747086)
		(size 0.508)
		(drill 0.254)
		(layers "F.Cu" "B.Cu")
		(net "M_M_DQ<14>")
	)
	(via
		(at 47.549308 -155.1178)
		(size 0.508)
		(drill 0.254)
		(layers "F.Cu" "B.Cu")
		(net "M_M_DQ<14>")
	)
	(via
		(at 46.699424 -150.814278)
		(size 0.508)
		(drill 0.254)
		(layers "F.Cu" "B.Cu")
		(net "M_M_DQ<14>")
	)
	(segment
		(start 46.699424 -152.078436)
		(end 46.699424 -150.814278)
		(width 0.1651)
		(layer "B.Cu")
		(net "M_M_DQ<14>")
	)
	(segment
		(start 74.4093 -92.413074)
		(end 74.392536 -92.442538)
		(width 0.0889)
		(layer "In11.Cu")
		(net "M_M_DQ<14>")
	)
	(segment
		(start 69.241416 -95.414084)
		(end 68.785486 -95.870014)
		(width 0.0889)
		(layer "In11.Cu")
		(net "M_M_DQ<14>")
	)
	(segment
		(start 47.063914 -134.681468)
		(end 47.063914 -136.067292)
		(width 0.14224)
		(layer "In11.Cu")
		(net "M_M_DQ<14>")
	)
	(segment
		(start 65.265046 -98.740214)
		(end 65.023238 -98.498406)
		(width 0.0889)
		(layer "In11.Cu")
		(net "M_M_DQ<14>")
	)
	(segment
		(start 71.4883 -94.128336)
		(end 71.448676 -94.128336)
		(width 0.0889)
		(layer "In11.Cu")
		(net "M_M_DQ<14>")
	)
	(segment
		(start 46.699424 -150.814278)
		(end 46.266354 -151.247348)
		(width 0.14224)
		(layer "In11.Cu")
		(net "M_M_DQ<14>")
	)
	(segment
		(start 47.063914 -139.663678)
		(end 47.063914 -140.908278)
		(width 0.14224)
		(layer "In11.Cu")
		(net "M_M_DQ<14>")
	)
	(segment
		(start 47.267114 -139.460478)
		(end 47.063914 -139.663678)
		(width 0.14224)
		(layer "In11.Cu")
		(net "M_M_DQ<14>")
	)
	(segment
		(start 46.266354 -153.834846)
		(end 47.549308 -155.1178)
		(width 0.14224)
		(layer "In11.Cu")
		(net "M_M_DQ<14>")
	)
	(segment
		(start 47.165514 -134.579868)
		(end 47.063914 -134.681468)
		(width 0.14224)
		(layer "In11.Cu")
		(net "M_M_DQ<14>")
	)
	(segment
		(start 47.063914 -131.307078)
		(end 47.165514 -131.408678)
		(width 0.14224)
		(layer "In11.Cu")
		(net "M_M_DQ<14>")
	)
	(segment
		(start 56.020208 -111.579914)
		(end 47.470568 -120.129554)
		(width 0.14224)
		(layer "In11.Cu")
		(net "M_M_DQ<14>")
	)
	(segment
		(start 74.057002 -92.64269)
		(end 74.024236 -92.64269)
		(width 0.0889)
		(layer "In11.Cu")
		(net "M_M_DQ<14>")
	)
	(segment
		(start 47.267114 -148.615146)
		(end 47.267114 -148.934678)
		(width 0.14224)
		(layer "In11.Cu")
		(net "M_M_DQ<14>")
	)
	(segment
		(start 55.732934 -111.005112)
		(end 56.020208 -111.292386)
		(width 0.14224)
		(layer "In11.Cu")
		(net "M_M_DQ<14>")
	)
	(segment
		(start 65.023238 -98.498406)
		(end 64.415162 -98.498406)
		(width 0.14224)
		(layer "In11.Cu")
		(net "M_M_DQ<14>")
	)
	(segment
		(start 47.267114 -148.934678)
		(end 46.530514 -149.671278)
		(width 0.14224)
		(layer "In11.Cu")
		(net "M_M_DQ<14>")
	)
	(segment
		(start 63.396368 -99.5172)
		(end 63.396368 -101.904546)
		(width 0.14224)
		(layer "In11.Cu")
		(net "M_M_DQ<14>")
	)
	(segment
		(start 47.114968 -148.463)
		(end 47.267114 -148.615146)
		(width 0.14224)
		(layer "In11.Cu")
		(net "M_M_DQ<14>")
	)
	(segment
		(start 47.216314 -141.060678)
		(end 47.216314 -141.5542)
		(width 0.14224)
		(layer "In11.Cu")
		(net "M_M_DQ<14>")
	)
	(segment
		(start 47.470568 -120.129554)
		(end 47.470568 -128.8034)
		(width 0.14224)
		(layer "In11.Cu")
		(net "M_M_DQ<14>")
	)
	(segment
		(start 56.020208 -111.292386)
		(end 56.020208 -111.579914)
		(width 0.14224)
		(layer "In11.Cu")
		(net "M_M_DQ<14>")
	)
	(segment
		(start 47.063914 -136.067292)
		(end 47.267114 -136.270492)
		(width 0.14224)
		(layer "In11.Cu")
		(net "M_M_DQ<14>")
	)
	(segment
		(start 74.904346 -91.747086)
		(end 74.4093 -92.413074)
		(width 0.0889)
		(layer "In11.Cu")
		(net "M_M_DQ<14>")
	)
	(segment
		(start 47.216314 -144.118838)
		(end 46.943772 -144.39138)
		(width 0.14224)
		(layer "In11.Cu")
		(net "M_M_DQ<14>")
	)
	(segment
		(start 64.415162 -98.498406)
		(end 63.396368 -99.5172)
		(width 0.14224)
		(layer "In11.Cu")
		(net "M_M_DQ<14>")
	)
	(segment
		(start 67.093592 -98.740214)
		(end 65.265046 -98.740214)
		(width 0.0889)
		(layer "In11.Cu")
		(net "M_M_DQ<14>")
	)
	(segment
		(start 47.165768 -129.1082)
		(end 47.165768 -129.960624)
		(width 0.14224)
		(layer "In11.Cu")
		(net "M_M_DQ<14>")
	)
	(segment
		(start 47.470568 -128.8034)
		(end 47.165768 -129.1082)
		(width 0.14224)
		(layer "In11.Cu")
		(net "M_M_DQ<14>")
	)
	(segment
		(start 47.267114 -136.270492)
		(end 47.267114 -136.4996)
		(width 0.14224)
		(layer "In11.Cu")
		(net "M_M_DQ<14>")
	)
	(segment
		(start 46.530514 -150.645368)
		(end 46.699424 -150.814278)
		(width 0.14224)
		(layer "In11.Cu")
		(net "M_M_DQ<14>")
	)
	(segment
		(start 51.856132 -113.73231)
		(end 52.143406 -114.019584)
		(width 0.14224)
		(layer "In11.Cu")
		(net "M_M_DQ<14>")
	)
	(segment
		(start 46.530514 -149.671278)
		(end 46.530514 -150.645368)
		(width 0.14224)
		(layer "In11.Cu")
		(net "M_M_DQ<14>")
	)
	(segment
		(start 67.296792 -98.537014)
		(end 67.093592 -98.740214)
		(width 0.0889)
		(layer "In11.Cu")
		(net "M_M_DQ<14>")
	)
	(segment
		(start 51.856132 -113.444782)
		(end 51.856132 -113.73231)
		(width 0.14224)
		(layer "In11.Cu")
		(net "M_M_DQ<14>")
	)
	(segment
		(start 47.267114 -138.963146)
		(end 47.267114 -139.460478)
		(width 0.14224)
		(layer "In11.Cu")
		(net "M_M_DQ<14>")
	)
	(segment
		(start 47.114968 -146.252946)
		(end 47.114968 -148.463)
		(width 0.14224)
		(layer "In11.Cu")
		(net "M_M_DQ<14>")
	)
	(segment
		(start 47.216314 -143.738346)
		(end 47.216314 -144.118838)
		(width 0.14224)
		(layer "In11.Cu")
		(net "M_M_DQ<14>")
	)
	(segment
		(start 52.430934 -114.019584)
		(end 55.445406 -111.005112)
		(width 0.14224)
		(layer "In11.Cu")
		(net "M_M_DQ<14>")
	)
	(segment
		(start 47.114968 -136.651746)
		(end 47.114968 -138.811)
		(width 0.14224)
		(layer "In11.Cu")
		(net "M_M_DQ<14>")
	)
	(segment
		(start 72.34682 -93.633036)
		(end 72.311006 -93.633036)
		(width 0.0889)
		(layer "In11.Cu")
		(net "M_M_DQ<14>")
	)
	(segment
		(start 69.77126 -95.118936)
		(end 69.731636 -95.118936)
		(width 0.0889)
		(layer "In11.Cu")
		(net "M_M_DQ<14>")
	)
	(segment
		(start 47.191168 -146.176746)
		(end 47.114968 -146.252946)
		(width 0.14224)
		(layer "In11.Cu")
		(net "M_M_DQ<14>")
	)
	(segment
		(start 55.445406 -111.005112)
		(end 55.732934 -111.005112)
		(width 0.14224)
		(layer "In11.Cu")
		(net "M_M_DQ<14>")
	)
	(segment
		(start 52.143406 -114.019584)
		(end 52.430934 -114.019584)
		(width 0.14224)
		(layer "In11.Cu")
		(net "M_M_DQ<14>")
	)
	(segment
		(start 67.296792 -96.403414)
		(end 67.296792 -98.537014)
		(width 0.0889)
		(layer "In11.Cu")
		(net "M_M_DQ<14>")
	)
	(segment
		(start 67.830192 -95.870014)
		(end 67.296792 -96.403414)
		(width 0.0889)
		(layer "In11.Cu")
		(net "M_M_DQ<14>")
	)
	(segment
		(start 47.063914 -130.062478)
		(end 47.063914 -131.307078)
		(width 0.14224)
		(layer "In11.Cu")
		(net "M_M_DQ<14>")
	)
	(segment
		(start 46.266354 -151.247348)
		(end 46.266354 -153.834846)
		(width 0.14224)
		(layer "In11.Cu")
		(net "M_M_DQ<14>")
	)
	(segment
		(start 63.396368 -101.904546)
		(end 51.856132 -113.444782)
		(width 0.14224)
		(layer "In11.Cu")
		(net "M_M_DQ<14>")
	)
	(segment
		(start 46.943772 -145.534126)
		(end 47.191168 -145.781522)
		(width 0.14224)
		(layer "In11.Cu")
		(net "M_M_DQ<14>")
	)
	(segment
		(start 47.063914 -140.908278)
		(end 47.216314 -141.060678)
		(width 0.14224)
		(layer "In11.Cu")
		(net "M_M_DQ<14>")
	)
	(segment
		(start 47.267114 -136.4996)
		(end 47.114968 -136.651746)
		(width 0.14224)
		(layer "In11.Cu")
		(net "M_M_DQ<14>")
	)
	(segment
		(start 47.114968 -141.655546)
		(end 47.114968 -143.637)
		(width 0.14224)
		(layer "In11.Cu")
		(net "M_M_DQ<14>")
	)
	(segment
		(start 70.622922 -94.623636)
		(end 70.598792 -94.623636)
		(width 0.0889)
		(layer "In11.Cu")
		(net "M_M_DQ<14>")
	)
	(segment
		(start 47.165514 -131.408678)
		(end 47.165514 -134.579868)
		(width 0.14224)
		(layer "In11.Cu")
		(net "M_M_DQ<14>")
	)
	(segment
		(start 47.216314 -141.5542)
		(end 47.114968 -141.655546)
		(width 0.14224)
		(layer "In11.Cu")
		(net "M_M_DQ<14>")
	)
	(segment
		(start 73.202292 -93.137736)
		(end 73.174352 -93.137736)
		(width 0.0889)
		(layer "In11.Cu")
		(net "M_M_DQ<14>")
	)
	(segment
		(start 47.165768 -129.960624)
		(end 47.063914 -130.062478)
		(width 0.14224)
		(layer "In11.Cu")
		(net "M_M_DQ<14>")
	)
	(segment
		(start 47.114968 -143.637)
		(end 47.216314 -143.738346)
		(width 0.14224)
		(layer "In11.Cu")
		(net "M_M_DQ<14>")
	)
	(segment
		(start 47.114968 -138.811)
		(end 47.267114 -138.963146)
		(width 0.14224)
		(layer "In11.Cu")
		(net "M_M_DQ<14>")
	)
	(segment
		(start 47.191168 -145.781522)
		(end 47.191168 -146.176746)
		(width 0.14224)
		(layer "In11.Cu")
		(net "M_M_DQ<14>")
	)
	(segment
		(start 68.785486 -95.870014)
		(end 67.830192 -95.870014)
		(width 0.0889)
		(layer "In11.Cu")
		(net "M_M_DQ<14>")
	)
	(segment
		(start 46.943772 -144.39138)
		(end 46.943772 -145.534126)
		(width 0.14224)
		(layer "In11.Cu")
		(net "M_M_DQ<14>")
	)
	(arc
		(start 70.099936 -94.919038)
		(mid 69.961192 -95.061071)
		(end 69.77126 -95.118936)
		(width 0.0889)
		(layer "In11.Cu")
		(net "M_M_DQ<14>")
	)
	(arc
		(start 70.598792 -94.623636)
		(mid 70.310647 -94.705955)
		(end 70.099936 -94.919038)
		(width 0.0889)
		(layer "In11.Cu")
		(net "M_M_DQ<14>")
	)
	(arc
		(start 72.675496 -93.433138)
		(mid 72.536752 -93.575171)
		(end 72.34682 -93.633036)
		(width 0.0889)
		(layer "In11.Cu")
		(net "M_M_DQ<14>")
	)
	(arc
		(start 71.448676 -94.128336)
		(mid 71.165459 -94.212617)
		(end 70.958456 -94.423484)
		(width 0.0889)
		(layer "In11.Cu")
		(net "M_M_DQ<14>")
	)
	(arc
		(start 72.311006 -93.633036)
		(mid 72.025582 -93.716503)
		(end 71.816976 -93.928438)
		(width 0.0889)
		(layer "In11.Cu")
		(net "M_M_DQ<14>")
	)
	(arc
		(start 73.174352 -93.137736)
		(mid 72.886207 -93.220055)
		(end 72.675496 -93.433138)
		(width 0.0889)
		(layer "In11.Cu")
		(net "M_M_DQ<14>")
	)
	(arc
		(start 70.958456 -94.423484)
		(mid 70.816773 -94.567288)
		(end 70.622922 -94.623636)
		(width 0.0889)
		(layer "In11.Cu")
		(net "M_M_DQ<14>")
	)
	(arc
		(start 74.024236 -92.64269)
		(mid 73.741019 -92.726971)
		(end 73.534016 -92.937838)
		(width 0.0889)
		(layer "In11.Cu")
		(net "M_M_DQ<14>")
	)
	(arc
		(start 69.731636 -95.118936)
		(mid 69.448419 -95.203217)
		(end 69.241416 -95.414084)
		(width 0.0889)
		(layer "In11.Cu")
		(net "M_M_DQ<14>")
	)
	(arc
		(start 74.392536 -92.442538)
		(mid 74.250853 -92.586342)
		(end 74.057002 -92.64269)
		(width 0.0889)
		(layer "In11.Cu")
		(net "M_M_DQ<14>")
	)
	(arc
		(start 71.816976 -93.928438)
		(mid 71.678232 -94.070471)
		(end 71.4883 -94.128336)
		(width 0.0889)
		(layer "In11.Cu")
		(net "M_M_DQ<14>")
	)
	(arc
		(start 73.534016 -92.937838)
		(mid 73.393937 -93.080574)
		(end 73.202292 -93.137736)
		(width 0.0889)
		(layer "In11.Cu")
		(net "M_M_DQ<14>")
	)
	(segment
		(start 40.749474 -152.273)
		(end 40.749474 -153.542746)
		(width 0.1651)
		(layer "F.Cu")
		(net "M_M_DQ<13>")
	)
	(segment
		(start 77.192886 -89.765886)
		(end 76.621386 -89.765886)
		(width 0.1651)
		(layer "F.Cu")
		(net "M_M_DQ<13>")
	)
	(via
		(at 76.621386 -89.765886)
		(size 0.508)
		(drill 0.254)
		(layers "F.Cu" "B.Cu")
		(net "M_M_DQ<13>")
	)
	(via
		(at 40.749474 -153.542746)
		(size 0.508)
		(drill 0.254)
		(layers "F.Cu" "B.Cu")
		(net "M_M_DQ<13>")
	)
	(via
		(at 41.523158 -149.533356)
		(size 0.508)
		(drill 0.254)
		(layers "F.Cu" "B.Cu")
		(net "M_M_DQ<13>")
	)
	(segment
		(start 41.599358 -147.478496)
		(end 41.599358 -149.457156)
		(width 0.1651)
		(layer "B.Cu")
		(net "M_M_DQ<13>")
	)
	(segment
		(start 41.599358 -149.457156)
		(end 41.523158 -149.533356)
		(width 0.1651)
		(layer "B.Cu")
		(net "M_M_DQ<13>")
	)
	(segment
		(start 42.060114 -145.454624)
		(end 41.907714 -145.607024)
		(width 0.14224)
		(layer "In11.Cu")
		(net "M_M_DQ<13>")
	)
	(segment
		(start 42.24655 -117.616986)
		(end 42.24655 -118.4656)
		(width 0.14224)
		(layer "In11.Cu")
		(net "M_M_DQ<13>")
	)
	(segment
		(start 42.24655 -120.464072)
		(end 41.984168 -120.726454)
		(width 0.14224)
		(layer "In11.Cu")
		(net "M_M_DQ<13>")
	)
	(segment
		(start 74.063606 -88.87079)
		(end 74.03084 -88.87079)
		(width 0.0889)
		(layer "In11.Cu")
		(net "M_M_DQ<13>")
	)
	(segment
		(start 41.933114 -129.417572)
		(end 41.933114 -129.920238)
		(width 0.14224)
		(layer "In11.Cu")
		(net "M_M_DQ<13>")
	)
	(segment
		(start 41.907714 -149.1488)
		(end 41.523158 -149.533356)
		(width 0.14224)
		(layer "In11.Cu")
		(net "M_M_DQ<13>")
	)
	(segment
		(start 41.907714 -146.1516)
		(end 42.034968 -146.278854)
		(width 0.14224)
		(layer "In11.Cu")
		(net "M_M_DQ<13>")
	)
	(segment
		(start 42.24655 -127.603758)
		(end 42.042588 -127.80772)
		(width 0.14224)
		(layer "In11.Cu")
		(net "M_M_DQ<13>")
	)
	(segment
		(start 42.108882 -128.62052)
		(end 42.253154 -128.764792)
		(width 0.14224)
		(layer "In11.Cu")
		(net "M_M_DQ<13>")
	)
	(segment
		(start 42.24655 -119.3292)
		(end 42.24655 -120.464072)
		(width 0.14224)
		(layer "In11.Cu")
		(net "M_M_DQ<13>")
	)
	(segment
		(start 42.060114 -144.398238)
		(end 42.060114 -145.454624)
		(width 0.14224)
		(layer "In11.Cu")
		(net "M_M_DQ<13>")
	)
	(segment
		(start 41.552368 -127.93472)
		(end 41.552368 -128.49352)
		(width 0.14224)
		(layer "In11.Cu")
		(net "M_M_DQ<13>")
	)
	(segment
		(start 42.24655 -118.4656)
		(end 41.984168 -118.727982)
		(width 0.14224)
		(layer "In11.Cu")
		(net "M_M_DQ<13>")
	)
	(segment
		(start 63.320676 -94.0054)
		(end 59.560968 -97.765108)
		(width 0.14224)
		(layer "In11.Cu")
		(net "M_M_DQ<13>")
	)
	(segment
		(start 41.523158 -149.533356)
		(end 41.500806 -149.533356)
		(width 0.14224)
		(layer "In11.Cu")
		(net "M_M_DQ<13>")
	)
	(segment
		(start 64.7446 -93.621606)
		(end 64.403732 -93.962474)
		(width 0.0889)
		(layer "In11.Cu")
		(net "M_M_DQ<13>")
	)
	(segment
		(start 40.910764 -152.586944)
		(end 40.910764 -152.898856)
		(width 0.14224)
		(layer "In11.Cu")
		(net "M_M_DQ<13>")
	)
	(segment
		(start 42.034968 -133.950456)
		(end 41.866312 -134.119112)
		(width 0.14224)
		(layer "In11.Cu")
		(net "M_M_DQ<13>")
	)
	(segment
		(start 41.199562 -150.6474)
		(end 41.199562 -151.129746)
		(width 0.14224)
		(layer "In11.Cu")
		(net "M_M_DQ<13>")
	)
	(segment
		(start 41.907714 -139.308078)
		(end 41.996614 -139.396978)
		(width 0.14224)
		(layer "In11.Cu")
		(net "M_M_DQ<13>")
	)
	(segment
		(start 41.996614 -135.938768)
		(end 41.848786 -136.086596)
		(width 0.14224)
		(layer "In11.Cu")
		(net "M_M_DQ<13>")
	)
	(segment
		(start 71.491856 -90.356436)
		(end 71.45909 -90.356436)
		(width 0.0889)
		(layer "In11.Cu")
		(net "M_M_DQ<13>")
	)
	(segment
		(start 41.812718 -141.005814)
		(end 41.812718 -141.383004)
		(width 0.14224)
		(layer "In11.Cu")
		(net "M_M_DQ<13>")
	)
	(segment
		(start 69.359526 -91.557094)
		(end 69.085206 -91.557094)
		(width 0.0889)
		(layer "In11.Cu")
		(net "M_M_DQ<13>")
	)
	(segment
		(start 41.958768 -124.680218)
		(end 42.24655 -124.968)
		(width 0.14224)
		(layer "In11.Cu")
		(net "M_M_DQ<13>")
	)
	(segment
		(start 42.24655 -125.848872)
		(end 41.984168 -126.111254)
		(width 0.14224)
		(layer "In11.Cu")
		(net "M_M_DQ<13>")
	)
	(segment
		(start 41.866312 -134.119112)
		(end 41.866312 -134.551166)
		(width 0.14224)
		(layer "In11.Cu")
		(net "M_M_DQ<13>")
	)
	(segment
		(start 64.403732 -93.962474)
		(end 64.360806 -94.0054)
		(width 0.14224)
		(layer "In11.Cu")
		(net "M_M_DQ<13>")
	)
	(segment
		(start 41.866312 -134.551166)
		(end 41.996614 -134.681468)
		(width 0.14224)
		(layer "In11.Cu")
		(net "M_M_DQ<13>")
	)
	(segment
		(start 41.984168 -126.111254)
		(end 41.984168 -126.440946)
		(width 0.14224)
		(layer "In11.Cu")
		(net "M_M_DQ<13>")
	)
	(segment
		(start 41.907714 -148.412454)
		(end 41.907714 -149.1488)
		(width 0.14224)
		(layer "In11.Cu")
		(net "M_M_DQ<13>")
	)
	(segment
		(start 41.933114 -129.920238)
		(end 42.115486 -130.10261)
		(width 0.14224)
		(layer "In11.Cu")
		(net "M_M_DQ<13>")
	)
	(segment
		(start 42.034968 -141.605254)
		(end 42.034968 -143.637)
		(width 0.14224)
		(layer "In11.Cu")
		(net "M_M_DQ<13>")
	)
	(segment
		(start 41.500806 -149.533356)
		(end 41.072562 -149.9616)
		(width 0.14224)
		(layer "In11.Cu")
		(net "M_M_DQ<13>")
	)
	(segment
		(start 41.996614 -139.396978)
		(end 41.996614 -140.821918)
		(width 0.14224)
		(layer "In11.Cu")
		(net "M_M_DQ<13>")
	)
	(segment
		(start 42.115486 -131.137914)
		(end 41.841166 -131.412234)
		(width 0.14224)
		(layer "In11.Cu")
		(net "M_M_DQ<13>")
	)
	(segment
		(start 69.569584 -91.347036)
		(end 69.359526 -91.557094)
		(width 0.0889)
		(layer "In11.Cu")
		(net "M_M_DQ<13>")
	)
	(segment
		(start 73.208896 -89.365836)
		(end 73.17613 -89.365836)
		(width 0.0889)
		(layer "In11.Cu")
		(net "M_M_DQ<13>")
	)
	(segment
		(start 41.552368 -128.49352)
		(end 41.679368 -128.62052)
		(width 0.14224)
		(layer "In11.Cu")
		(net "M_M_DQ<13>")
	)
	(segment
		(start 64.360806 -94.0054)
		(end 63.320676 -94.0054)
		(width 0.14224)
		(layer "In11.Cu")
		(net "M_M_DQ<13>")
	)
	(segment
		(start 76.12634 -89.100152)
		(end 76.109576 -89.070688)
		(width 0.0889)
		(layer "In11.Cu")
		(net "M_M_DQ<13>")
	)
	(segment
		(start 59.560968 -100.302568)
		(end 42.24655 -117.616986)
		(width 0.14224)
		(layer "In11.Cu")
		(net "M_M_DQ<13>")
	)
	(segment
		(start 41.996614 -140.821918)
		(end 41.812718 -141.005814)
		(width 0.14224)
		(layer "In11.Cu")
		(net "M_M_DQ<13>")
	)
	(segment
		(start 42.24655 -123.825)
		(end 41.958768 -124.112782)
		(width 0.14224)
		(layer "In11.Cu")
		(net "M_M_DQ<13>")
	)
	(segment
		(start 67.096132 -92.427806)
		(end 65.902332 -93.621606)
		(width 0.0889)
		(layer "In11.Cu")
		(net "M_M_DQ<13>")
	)
	(segment
		(start 42.009568 -122.174254)
		(end 42.009568 -122.521218)
		(width 0.14224)
		(layer "In11.Cu")
		(net "M_M_DQ<13>")
	)
	(segment
		(start 41.984168 -121.132346)
		(end 42.24655 -121.394728)
		(width 0.14224)
		(layer "In11.Cu")
		(net "M_M_DQ<13>")
	)
	(segment
		(start 41.848786 -136.086596)
		(end 41.848786 -136.604756)
		(width 0.14224)
		(layer "In11.Cu")
		(net "M_M_DQ<13>")
	)
	(segment
		(start 42.034968 -132.31495)
		(end 42.034968 -133.950456)
		(width 0.14224)
		(layer "In11.Cu")
		(net "M_M_DQ<13>")
	)
	(segment
		(start 42.24655 -126.703328)
		(end 42.24655 -127.603758)
		(width 0.14224)
		(layer "In11.Cu")
		(net "M_M_DQ<13>")
	)
	(segment
		(start 42.253154 -128.764792)
		(end 42.253154 -129.097532)
		(width 0.14224)
		(layer "In11.Cu")
		(net "M_M_DQ<13>")
	)
	(segment
		(start 41.933114 -144.271238)
		(end 42.060114 -144.398238)
		(width 0.14224)
		(layer "In11.Cu")
		(net "M_M_DQ<13>")
	)
	(segment
		(start 41.679368 -127.80772)
		(end 41.552368 -127.93472)
		(width 0.14224)
		(layer "In11.Cu")
		(net "M_M_DQ<13>")
	)
	(segment
		(start 69.774816 -91.347036)
		(end 69.569584 -91.347036)
		(width 0.0889)
		(layer "In11.Cu")
		(net "M_M_DQ<13>")
	)
	(segment
		(start 42.115486 -130.10261)
		(end 42.115486 -131.137914)
		(width 0.14224)
		(layer "In11.Cu")
		(net "M_M_DQ<13>")
	)
	(segment
		(start 42.034968 -143.637)
		(end 41.933114 -143.738854)
		(width 0.14224)
		(layer "In11.Cu")
		(net "M_M_DQ<13>")
	)
	(segment
		(start 40.910764 -152.898856)
		(end 41.174162 -153.162254)
		(width 0.14224)
		(layer "In11.Cu")
		(net "M_M_DQ<13>")
	)
	(segment
		(start 65.902332 -93.621606)
		(end 64.7446 -93.621606)
		(width 0.0889)
		(layer "In11.Cu")
		(net "M_M_DQ<13>")
	)
	(segment
		(start 41.984168 -120.726454)
		(end 41.984168 -121.132346)
		(width 0.14224)
		(layer "In11.Cu")
		(net "M_M_DQ<13>")
	)
	(segment
		(start 41.174162 -153.162254)
		(end 41.174162 -153.390346)
		(width 0.14224)
		(layer "In11.Cu")
		(net "M_M_DQ<13>")
	)
	(segment
		(start 42.24655 -121.937272)
		(end 42.009568 -122.174254)
		(width 0.14224)
		(layer "In11.Cu")
		(net "M_M_DQ<13>")
	)
	(segment
		(start 41.679368 -128.62052)
		(end 42.108882 -128.62052)
		(width 0.14224)
		(layer "In11.Cu")
		(net "M_M_DQ<13>")
	)
	(segment
		(start 68.214494 -92.427806)
		(end 67.096132 -92.427806)
		(width 0.0889)
		(layer "In11.Cu")
		(net "M_M_DQ<13>")
	)
	(segment
		(start 70.629526 -90.85199)
		(end 70.59676 -90.85199)
		(width 0.0889)
		(layer "In11.Cu")
		(net "M_M_DQ<13>")
	)
	(segment
		(start 41.199562 -151.129746)
		(end 40.910764 -151.418544)
		(width 0.14224)
		(layer "In11.Cu")
		(net "M_M_DQ<13>")
	)
	(segment
		(start 41.021762 -153.542746)
		(end 40.749474 -153.542746)
		(width 0.14224)
		(layer "In11.Cu")
		(net "M_M_DQ<13>")
	)
	(segment
		(start 41.907714 -138.862054)
		(end 41.907714 -139.308078)
		(width 0.14224)
		(layer "In11.Cu")
		(net "M_M_DQ<13>")
	)
	(segment
		(start 42.042588 -127.80772)
		(end 41.679368 -127.80772)
		(width 0.14224)
		(layer "In11.Cu")
		(net "M_M_DQ<13>")
	)
	(segment
		(start 41.984168 -118.727982)
		(end 41.984168 -119.066818)
		(width 0.14224)
		(layer "In11.Cu")
		(net "M_M_DQ<13>")
	)
	(segment
		(start 41.148762 -152.348946)
		(end 40.910764 -152.586944)
		(width 0.14224)
		(layer "In11.Cu")
		(net "M_M_DQ<13>")
	)
	(segment
		(start 40.910764 -151.418544)
		(end 40.910764 -151.755856)
		(width 0.14224)
		(layer "In11.Cu")
		(net "M_M_DQ<13>")
	)
	(segment
		(start 41.174162 -153.390346)
		(end 41.021762 -153.542746)
		(width 0.14224)
		(layer "In11.Cu")
		(net "M_M_DQ<13>")
	)
	(segment
		(start 42.24655 -124.968)
		(end 42.24655 -125.848872)
		(width 0.14224)
		(layer "In11.Cu")
		(net "M_M_DQ<13>")
	)
	(segment
		(start 40.910764 -151.755856)
		(end 41.148762 -151.993854)
		(width 0.14224)
		(layer "In11.Cu")
		(net "M_M_DQ<13>")
	)
	(segment
		(start 41.958768 -124.112782)
		(end 41.958768 -124.680218)
		(width 0.14224)
		(layer "In11.Cu")
		(net "M_M_DQ<13>")
	)
	(segment
		(start 41.072562 -150.5204)
		(end 41.199562 -150.6474)
		(width 0.14224)
		(layer "In11.Cu")
		(net "M_M_DQ<13>")
	)
	(segment
		(start 42.034968 -138.7348)
		(end 41.907714 -138.862054)
		(width 0.14224)
		(layer "In11.Cu")
		(net "M_M_DQ<13>")
	)
	(segment
		(start 76.621386 -89.765886)
		(end 76.12634 -89.100152)
		(width 0.0889)
		(layer "In11.Cu")
		(net "M_M_DQ<13>")
	)
	(segment
		(start 69.085206 -91.557094)
		(end 68.214494 -92.427806)
		(width 0.0889)
		(layer "In11.Cu")
		(net "M_M_DQ<13>")
	)
	(segment
		(start 41.996614 -134.681468)
		(end 41.996614 -135.938768)
		(width 0.14224)
		(layer "In11.Cu")
		(net "M_M_DQ<13>")
	)
	(segment
		(start 42.24655 -121.394728)
		(end 42.24655 -121.937272)
		(width 0.14224)
		(layer "In11.Cu")
		(net "M_M_DQ<13>")
	)
	(segment
		(start 42.034968 -136.790938)
		(end 42.034968 -138.7348)
		(width 0.14224)
		(layer "In11.Cu")
		(net "M_M_DQ<13>")
	)
	(segment
		(start 42.034968 -148.2852)
		(end 41.907714 -148.412454)
		(width 0.14224)
		(layer "In11.Cu")
		(net "M_M_DQ<13>")
	)
	(segment
		(start 41.072562 -149.9616)
		(end 41.072562 -150.5204)
		(width 0.14224)
		(layer "In11.Cu")
		(net "M_M_DQ<13>")
	)
	(segment
		(start 41.148762 -151.993854)
		(end 41.148762 -152.348946)
		(width 0.14224)
		(layer "In11.Cu")
		(net "M_M_DQ<13>")
	)
	(segment
		(start 41.812718 -141.383004)
		(end 42.034968 -141.605254)
		(width 0.14224)
		(layer "In11.Cu")
		(net "M_M_DQ<13>")
	)
	(segment
		(start 41.907714 -145.607024)
		(end 41.907714 -146.1516)
		(width 0.14224)
		(layer "In11.Cu")
		(net "M_M_DQ<13>")
	)
	(segment
		(start 41.841166 -131.412234)
		(end 41.841166 -132.121148)
		(width 0.14224)
		(layer "In11.Cu")
		(net "M_M_DQ<13>")
	)
	(segment
		(start 42.034968 -146.278854)
		(end 42.034968 -148.2852)
		(width 0.14224)
		(layer "In11.Cu")
		(net "M_M_DQ<13>")
	)
	(segment
		(start 41.933114 -143.738854)
		(end 41.933114 -144.271238)
		(width 0.14224)
		(layer "In11.Cu")
		(net "M_M_DQ<13>")
	)
	(segment
		(start 42.24655 -122.7582)
		(end 42.24655 -123.825)
		(width 0.14224)
		(layer "In11.Cu")
		(net "M_M_DQ<13>")
	)
	(segment
		(start 42.253154 -129.097532)
		(end 41.933114 -129.417572)
		(width 0.14224)
		(layer "In11.Cu")
		(net "M_M_DQ<13>")
	)
	(segment
		(start 72.346566 -89.86139)
		(end 72.3138 -89.86139)
		(width 0.0889)
		(layer "In11.Cu")
		(net "M_M_DQ<13>")
	)
	(segment
		(start 41.984168 -119.066818)
		(end 42.24655 -119.3292)
		(width 0.14224)
		(layer "In11.Cu")
		(net "M_M_DQ<13>")
	)
	(segment
		(start 59.560968 -97.765108)
		(end 59.560968 -100.302568)
		(width 0.14224)
		(layer "In11.Cu")
		(net "M_M_DQ<13>")
	)
	(segment
		(start 41.984168 -126.440946)
		(end 42.24655 -126.703328)
		(width 0.14224)
		(layer "In11.Cu")
		(net "M_M_DQ<13>")
	)
	(segment
		(start 42.009568 -122.521218)
		(end 42.24655 -122.7582)
		(width 0.14224)
		(layer "In11.Cu")
		(net "M_M_DQ<13>")
	)
	(segment
		(start 75.777852 -88.87079)
		(end 75.745086 -88.87079)
		(width 0.0889)
		(layer "In11.Cu")
		(net "M_M_DQ<13>")
	)
	(segment
		(start 41.841166 -132.121148)
		(end 42.034968 -132.31495)
		(width 0.14224)
		(layer "In11.Cu")
		(net "M_M_DQ<13>")
	)
	(segment
		(start 41.848786 -136.604756)
		(end 42.034968 -136.790938)
		(width 0.14224)
		(layer "In11.Cu")
		(net "M_M_DQ<13>")
	)
	(arc
		(start 73.17613 -89.365836)
		(mid 72.98228 -89.422186)
		(end 72.840596 -89.565988)
		(width 0.0889)
		(layer "In11.Cu")
		(net "M_M_DQ<13>")
	)
	(arc
		(start 72.3138 -89.86139)
		(mid 72.122158 -89.918556)
		(end 71.982076 -90.061288)
		(width 0.0889)
		(layer "In11.Cu")
		(net "M_M_DQ<13>")
	)
	(arc
		(start 70.59676 -90.85199)
		(mid 70.405118 -90.909156)
		(end 70.265036 -91.051888)
		(width 0.0889)
		(layer "In11.Cu")
		(net "M_M_DQ<13>")
	)
	(arc
		(start 73.699116 -89.070688)
		(mid 73.492112 -89.281552)
		(end 73.208896 -89.365836)
		(width 0.0889)
		(layer "In11.Cu")
		(net "M_M_DQ<13>")
	)
	(arc
		(start 76.109576 -89.070688)
		(mid 75.969497 -88.927952)
		(end 75.777852 -88.87079)
		(width 0.0889)
		(layer "In11.Cu")
		(net "M_M_DQ<13>")
	)
	(arc
		(start 71.123556 -90.556588)
		(mid 70.914948 -90.76852)
		(end 70.629526 -90.85199)
		(width 0.0889)
		(layer "In11.Cu")
		(net "M_M_DQ<13>")
	)
	(arc
		(start 71.45909 -90.356436)
		(mid 71.26524 -90.412786)
		(end 71.123556 -90.556588)
		(width 0.0889)
		(layer "In11.Cu")
		(net "M_M_DQ<13>")
	)
	(arc
		(start 72.840596 -89.565988)
		(mid 72.631988 -89.77792)
		(end 72.346566 -89.86139)
		(width 0.0889)
		(layer "In11.Cu")
		(net "M_M_DQ<13>")
	)
	(arc
		(start 71.982076 -90.061288)
		(mid 71.775072 -90.272152)
		(end 71.491856 -90.356436)
		(width 0.0889)
		(layer "In11.Cu")
		(net "M_M_DQ<13>")
	)
	(arc
		(start 74.557636 -88.575388)
		(mid 74.349028 -88.78732)
		(end 74.063606 -88.87079)
		(width 0.0889)
		(layer "In11.Cu")
		(net "M_M_DQ<13>")
	)
	(arc
		(start 75.745086 -88.87079)
		(mid 75.459662 -88.787323)
		(end 75.251056 -88.575388)
		(width 0.0889)
		(layer "In11.Cu")
		(net "M_M_DQ<13>")
	)
	(arc
		(start 75.251056 -88.575388)
		(mid 74.904346 -88.375077)
		(end 74.557636 -88.575388)
		(width 0.0889)
		(layer "In11.Cu")
		(net "M_M_DQ<13>")
	)
	(arc
		(start 70.265036 -91.051888)
		(mid 70.058032 -91.262752)
		(end 69.774816 -91.347036)
		(width 0.0889)
		(layer "In11.Cu")
		(net "M_M_DQ<13>")
	)
	(arc
		(start 74.03084 -88.87079)
		(mid 73.839198 -88.927956)
		(end 73.699116 -89.070688)
		(width 0.0889)
		(layer "In11.Cu")
		(net "M_M_DQ<13>")
	)
	(segment
		(start 41.599358 -155.547568)
		(end 41.501314 -155.0162)
		(width 0.1651)
		(layer "F.Cu")
		(net "M_M_DQ<12>")
	)
	(segment
		(start 78.051406 -90.26144)
		(end 77.479906 -90.26144)
		(width 0.1651)
		(layer "F.Cu")
		(net "M_M_DQ<12>")
	)
	(segment
		(start 41.599358 -156.87294)
		(end 41.599358 -155.547568)
		(width 0.1651)
		(layer "F.Cu")
		(net "M_M_DQ<12>")
	)
	(via
		(at 41.501314 -155.0162)
		(size 0.508)
		(drill 0.254)
		(layers "F.Cu" "B.Cu")
		(net "M_M_DQ<12>")
	)
	(via
		(at 77.479906 -90.26144)
		(size 0.508)
		(drill 0.254)
		(layers "F.Cu" "B.Cu")
		(net "M_M_DQ<12>")
	)
	(via
		(at 40.749474 -150.814278)
		(size 0.508)
		(drill 0.254)
		(layers "F.Cu" "B.Cu")
		(net "M_M_DQ<12>")
	)
	(segment
		(start 40.749474 -152.078436)
		(end 40.749474 -150.814278)
		(width 0.1651)
		(layer "B.Cu")
		(net "M_M_DQ<12>")
	)
	(segment
		(start 41.234614 -148.960078)
		(end 40.434514 -149.760178)
		(width 0.14224)
		(layer "In11.Cu")
		(net "M_M_DQ<12>")
	)
	(segment
		(start 75.784456 -88.68029)
		(end 75.75169 -88.68029)
		(width 0.0889)
		(layer "In11.Cu")
		(net "M_M_DQ<12>")
	)
	(segment
		(start 41.272714 -139.333478)
		(end 41.018714 -139.587478)
		(width 0.14224)
		(layer "In11.Cu")
		(net "M_M_DQ<12>")
	)
	(segment
		(start 68.134992 -92.237814)
		(end 67.017392 -92.237814)
		(width 0.0889)
		(layer "In11.Cu")
		(net "M_M_DQ<12>")
	)
	(segment
		(start 41.247314 -144.069054)
		(end 40.981122 -144.335246)
		(width 0.14224)
		(layer "In11.Cu")
		(net "M_M_DQ<12>")
	)
	(segment
		(start 41.171368 -132.028946)
		(end 41.171368 -134.061454)
		(width 0.14224)
		(layer "In11.Cu")
		(net "M_M_DQ<12>")
	)
	(segment
		(start 64.622934 -93.3196)
		(end 63.329312 -93.3196)
		(width 0.14224)
		(layer "In11.Cu")
		(net "M_M_DQ<12>")
	)
	(segment
		(start 41.247314 -141.478)
		(end 41.171368 -141.553946)
		(width 0.14224)
		(layer "In11.Cu")
		(net "M_M_DQ<12>")
	)
	(segment
		(start 41.189402 -129.82575)
		(end 41.018714 -129.996438)
		(width 0.14224)
		(layer "In11.Cu")
		(net "M_M_DQ<12>")
	)
	(segment
		(start 67.017392 -92.237814)
		(end 65.823592 -93.431614)
		(width 0.0889)
		(layer "In11.Cu")
		(net "M_M_DQ<12>")
	)
	(segment
		(start 59.078368 -99.887024)
		(end 41.476168 -117.489224)
		(width 0.14224)
		(layer "In11.Cu")
		(net "M_M_DQ<12>")
	)
	(segment
		(start 41.171368 -148.2852)
		(end 41.234614 -148.348446)
		(width 0.14224)
		(layer "In11.Cu")
		(net "M_M_DQ<12>")
	)
	(segment
		(start 63.329312 -93.3196)
		(end 59.078368 -97.570544)
		(width 0.14224)
		(layer "In11.Cu")
		(net "M_M_DQ<12>")
	)
	(segment
		(start 73.202292 -89.175336)
		(end 73.169526 -89.175336)
		(width 0.0889)
		(layer "In11.Cu")
		(net "M_M_DQ<12>")
	)
	(segment
		(start 40.981122 -145.527776)
		(end 41.234614 -145.781268)
		(width 0.14224)
		(layer "In11.Cu")
		(net "M_M_DQ<12>")
	)
	(segment
		(start 40.316404 -151.247348)
		(end 40.316404 -153.83129)
		(width 0.14224)
		(layer "In11.Cu")
		(net "M_M_DQ<12>")
	)
	(segment
		(start 41.223946 -136.1567)
		(end 41.223946 -136.599168)
		(width 0.14224)
		(layer "In11.Cu")
		(net "M_M_DQ<12>")
	)
	(segment
		(start 41.207182 -131.993132)
		(end 41.171368 -132.028946)
		(width 0.14224)
		(layer "In11.Cu")
		(net "M_M_DQ<12>")
	)
	(segment
		(start 74.922126 -88.184736)
		(end 74.886566 -88.184736)
		(width 0.0889)
		(layer "In11.Cu")
		(net "M_M_DQ<12>")
	)
	(segment
		(start 40.841168 -127.6604)
		(end 40.841168 -128.9304)
		(width 0.14224)
		(layer "In11.Cu")
		(net "M_M_DQ<12>")
	)
	(segment
		(start 69.490082 -91.156536)
		(end 69.280024 -91.366594)
		(width 0.0889)
		(layer "In11.Cu")
		(net "M_M_DQ<12>")
	)
	(segment
		(start 41.234614 -148.348446)
		(end 41.234614 -148.960078)
		(width 0.14224)
		(layer "In11.Cu")
		(net "M_M_DQ<12>")
	)
	(segment
		(start 40.316404 -153.83129)
		(end 41.501314 -155.0162)
		(width 0.14224)
		(layer "In11.Cu")
		(net "M_M_DQ<12>")
	)
	(segment
		(start 64.734948 -93.431614)
		(end 64.629792 -93.326458)
		(width 0.0889)
		(layer "In11.Cu")
		(net "M_M_DQ<12>")
	)
	(segment
		(start 69.006212 -91.366594)
		(end 68.134992 -92.237814)
		(width 0.0889)
		(layer "In11.Cu")
		(net "M_M_DQ<12>")
	)
	(segment
		(start 74.057002 -88.68029)
		(end 74.024236 -88.68029)
		(width 0.0889)
		(layer "In11.Cu")
		(net "M_M_DQ<12>")
	)
	(segment
		(start 41.206928 -134.097014)
		(end 41.206928 -134.533894)
		(width 0.14224)
		(layer "In11.Cu")
		(net "M_M_DQ<12>")
	)
	(segment
		(start 41.476168 -127.0254)
		(end 40.841168 -127.6604)
		(width 0.14224)
		(layer "In11.Cu")
		(net "M_M_DQ<12>")
	)
	(segment
		(start 41.234614 -146.2024)
		(end 41.171368 -146.265646)
		(width 0.14224)
		(layer "In11.Cu")
		(net "M_M_DQ<12>")
	)
	(segment
		(start 76.639166 -89.175336)
		(end 76.6064 -89.175336)
		(width 0.0889)
		(layer "In11.Cu")
		(net "M_M_DQ<12>")
	)
	(segment
		(start 64.629792 -93.326458)
		(end 64.622934 -93.3196)
		(width 0.14224)
		(layer "In11.Cu")
		(net "M_M_DQ<12>")
	)
	(segment
		(start 77.479906 -90.26144)
		(end 77.150468 -89.500456)
		(width 0.0889)
		(layer "In11.Cu")
		(net "M_M_DQ<12>")
	)
	(segment
		(start 41.223946 -136.599168)
		(end 41.171368 -136.651746)
		(width 0.14224)
		(layer "In11.Cu")
		(net "M_M_DQ<12>")
	)
	(segment
		(start 40.434514 -150.499318)
		(end 40.749474 -150.814278)
		(width 0.14224)
		(layer "In11.Cu")
		(net "M_M_DQ<12>")
	)
	(segment
		(start 41.171368 -136.651746)
		(end 41.171368 -138.684)
		(width 0.14224)
		(layer "In11.Cu")
		(net "M_M_DQ<12>")
	)
	(segment
		(start 41.247314 -141.009878)
		(end 41.247314 -141.478)
		(width 0.14224)
		(layer "In11.Cu")
		(net "M_M_DQ<12>")
	)
	(segment
		(start 41.206928 -134.533894)
		(end 41.018714 -134.722108)
		(width 0.14224)
		(layer "In11.Cu")
		(net "M_M_DQ<12>")
	)
	(segment
		(start 41.018714 -135.951468)
		(end 41.223946 -136.1567)
		(width 0.14224)
		(layer "In11.Cu")
		(net "M_M_DQ<12>")
	)
	(segment
		(start 71.485252 -90.165936)
		(end 71.452486 -90.165936)
		(width 0.0889)
		(layer "In11.Cu")
		(net "M_M_DQ<12>")
	)
	(segment
		(start 41.018714 -134.722108)
		(end 41.018714 -135.951468)
		(width 0.14224)
		(layer "In11.Cu")
		(net "M_M_DQ<12>")
	)
	(segment
		(start 72.339962 -89.67089)
		(end 72.307196 -89.67089)
		(width 0.0889)
		(layer "In11.Cu")
		(net "M_M_DQ<12>")
	)
	(segment
		(start 41.234614 -145.781268)
		(end 41.234614 -146.2024)
		(width 0.14224)
		(layer "In11.Cu")
		(net "M_M_DQ<12>")
	)
	(segment
		(start 40.749474 -150.814278)
		(end 40.316404 -151.247348)
		(width 0.14224)
		(layer "In11.Cu")
		(net "M_M_DQ<12>")
	)
	(segment
		(start 41.171368 -138.684)
		(end 41.272714 -138.785346)
		(width 0.14224)
		(layer "In11.Cu")
		(net "M_M_DQ<12>")
	)
	(segment
		(start 65.823592 -93.431614)
		(end 64.734948 -93.431614)
		(width 0.0889)
		(layer "In11.Cu")
		(net "M_M_DQ<12>")
	)
	(segment
		(start 41.171368 -146.265646)
		(end 41.171368 -148.2852)
		(width 0.14224)
		(layer "In11.Cu")
		(net "M_M_DQ<12>")
	)
	(segment
		(start 41.018714 -140.781278)
		(end 41.247314 -141.009878)
		(width 0.14224)
		(layer "In11.Cu")
		(net "M_M_DQ<12>")
	)
	(segment
		(start 41.018714 -139.587478)
		(end 41.018714 -140.781278)
		(width 0.14224)
		(layer "In11.Cu")
		(net "M_M_DQ<12>")
	)
	(segment
		(start 77.150468 -89.500456)
		(end 77.133196 -89.470738)
		(width 0.0889)
		(layer "In11.Cu")
		(net "M_M_DQ<12>")
	)
	(segment
		(start 41.207182 -131.368546)
		(end 41.207182 -131.993132)
		(width 0.14224)
		(layer "In11.Cu")
		(net "M_M_DQ<12>")
	)
	(segment
		(start 40.981122 -144.335246)
		(end 40.981122 -145.527776)
		(width 0.14224)
		(layer "In11.Cu")
		(net "M_M_DQ<12>")
	)
	(segment
		(start 41.272714 -138.785346)
		(end 41.272714 -139.333478)
		(width 0.14224)
		(layer "In11.Cu")
		(net "M_M_DQ<12>")
	)
	(segment
		(start 41.247314 -143.687546)
		(end 41.247314 -144.069054)
		(width 0.14224)
		(layer "In11.Cu")
		(net "M_M_DQ<12>")
	)
	(segment
		(start 40.841168 -128.9304)
		(end 41.189402 -129.278634)
		(width 0.14224)
		(layer "In11.Cu")
		(net "M_M_DQ<12>")
	)
	(segment
		(start 41.018714 -129.996438)
		(end 41.018714 -131.180078)
		(width 0.14224)
		(layer "In11.Cu")
		(net "M_M_DQ<12>")
	)
	(segment
		(start 41.171368 -143.6116)
		(end 41.247314 -143.687546)
		(width 0.14224)
		(layer "In11.Cu")
		(net "M_M_DQ<12>")
	)
	(segment
		(start 41.476168 -117.489224)
		(end 41.476168 -127.0254)
		(width 0.14224)
		(layer "In11.Cu")
		(net "M_M_DQ<12>")
	)
	(segment
		(start 59.078368 -97.570544)
		(end 59.078368 -99.887024)
		(width 0.14224)
		(layer "In11.Cu")
		(net "M_M_DQ<12>")
	)
	(segment
		(start 40.434514 -149.760178)
		(end 40.434514 -150.499318)
		(width 0.14224)
		(layer "In11.Cu")
		(net "M_M_DQ<12>")
	)
	(segment
		(start 41.018714 -131.180078)
		(end 41.207182 -131.368546)
		(width 0.14224)
		(layer "In11.Cu")
		(net "M_M_DQ<12>")
	)
	(segment
		(start 41.189402 -129.278634)
		(end 41.189402 -129.82575)
		(width 0.14224)
		(layer "In11.Cu")
		(net "M_M_DQ<12>")
	)
	(segment
		(start 41.171368 -141.553946)
		(end 41.171368 -143.6116)
		(width 0.14224)
		(layer "In11.Cu")
		(net "M_M_DQ<12>")
	)
	(segment
		(start 69.280024 -91.366594)
		(end 69.006212 -91.366594)
		(width 0.0889)
		(layer "In11.Cu")
		(net "M_M_DQ<12>")
	)
	(segment
		(start 41.171368 -134.061454)
		(end 41.206928 -134.097014)
		(width 0.14224)
		(layer "In11.Cu")
		(net "M_M_DQ<12>")
	)
	(segment
		(start 69.768212 -91.156536)
		(end 69.490082 -91.156536)
		(width 0.0889)
		(layer "In11.Cu")
		(net "M_M_DQ<12>")
	)
	(segment
		(start 70.622922 -90.66149)
		(end 70.590156 -90.66149)
		(width 0.0889)
		(layer "In11.Cu")
		(net "M_M_DQ<12>")
	)
	(arc
		(start 72.307196 -89.67089)
		(mid 72.023979 -89.755171)
		(end 71.816976 -89.966038)
		(width 0.0889)
		(layer "In11.Cu")
		(net "M_M_DQ<12>")
	)
	(arc
		(start 71.452486 -90.165936)
		(mid 71.167062 -90.249403)
		(end 70.958456 -90.461338)
		(width 0.0889)
		(layer "In11.Cu")
		(net "M_M_DQ<12>")
	)
	(arc
		(start 74.392536 -88.480138)
		(mid 74.250853 -88.623942)
		(end 74.057002 -88.68029)
		(width 0.0889)
		(layer "In11.Cu")
		(net "M_M_DQ<12>")
	)
	(arc
		(start 73.169526 -89.175336)
		(mid 72.884102 -89.258803)
		(end 72.675496 -89.470738)
		(width 0.0889)
		(layer "In11.Cu")
		(net "M_M_DQ<12>")
	)
	(arc
		(start 72.675496 -89.470738)
		(mid 72.533813 -89.614542)
		(end 72.339962 -89.67089)
		(width 0.0889)
		(layer "In11.Cu")
		(net "M_M_DQ<12>")
	)
	(arc
		(start 76.274676 -88.975438)
		(mid 76.067672 -88.764574)
		(end 75.784456 -88.68029)
		(width 0.0889)
		(layer "In11.Cu")
		(net "M_M_DQ<12>")
	)
	(arc
		(start 75.75169 -88.68029)
		(mid 75.55784 -88.62394)
		(end 75.416156 -88.480138)
		(width 0.0889)
		(layer "In11.Cu")
		(net "M_M_DQ<12>")
	)
	(arc
		(start 76.6064 -89.175336)
		(mid 76.414758 -89.11817)
		(end 76.274676 -88.975438)
		(width 0.0889)
		(layer "In11.Cu")
		(net "M_M_DQ<12>")
	)
	(arc
		(start 73.534016 -88.975438)
		(mid 73.393937 -89.118174)
		(end 73.202292 -89.175336)
		(width 0.0889)
		(layer "In11.Cu")
		(net "M_M_DQ<12>")
	)
	(arc
		(start 70.099936 -90.956638)
		(mid 69.959857 -91.099374)
		(end 69.768212 -91.156536)
		(width 0.0889)
		(layer "In11.Cu")
		(net "M_M_DQ<12>")
	)
	(arc
		(start 71.816976 -89.966038)
		(mid 71.676897 -90.108774)
		(end 71.485252 -90.165936)
		(width 0.0889)
		(layer "In11.Cu")
		(net "M_M_DQ<12>")
	)
	(arc
		(start 70.958456 -90.461338)
		(mid 70.816773 -90.605142)
		(end 70.622922 -90.66149)
		(width 0.0889)
		(layer "In11.Cu")
		(net "M_M_DQ<12>")
	)
	(arc
		(start 74.024236 -88.68029)
		(mid 73.741019 -88.764571)
		(end 73.534016 -88.975438)
		(width 0.0889)
		(layer "In11.Cu")
		(net "M_M_DQ<12>")
	)
	(arc
		(start 77.133196 -89.470738)
		(mid 76.924588 -89.258806)
		(end 76.639166 -89.175336)
		(width 0.0889)
		(layer "In11.Cu")
		(net "M_M_DQ<12>")
	)
	(arc
		(start 75.416156 -88.480138)
		(mid 75.207548 -88.268206)
		(end 74.922126 -88.184736)
		(width 0.0889)
		(layer "In11.Cu")
		(net "M_M_DQ<12>")
	)
	(arc
		(start 74.886566 -88.184736)
		(mid 74.601142 -88.268203)
		(end 74.392536 -88.480138)
		(width 0.0889)
		(layer "In11.Cu")
		(net "M_M_DQ<12>")
	)
	(arc
		(start 70.590156 -90.66149)
		(mid 70.306939 -90.745771)
		(end 70.099936 -90.956638)
		(width 0.0889)
		(layer "In11.Cu")
		(net "M_M_DQ<12>")
	)
	(segment
		(start 76.334366 -93.23324)
		(end 75.762866 -93.23324)
		(width 0.1651)
		(layer "F.Cu")
		(net "M_M_DQ<11>")
	)
	(segment
		(start 48.399446 -152.273)
		(end 48.399446 -153.542746)
		(width 0.1651)
		(layer "F.Cu")
		(net "M_M_DQ<11>")
	)
	(via
		(at 48.399446 -153.542746)
		(size 0.508)
		(drill 0.254)
		(layers "F.Cu" "B.Cu")
		(net "M_M_DQ<11>")
	)
	(via
		(at 75.762866 -93.23324)
		(size 0.508)
		(drill 0.254)
		(layers "F.Cu" "B.Cu")
		(net "M_M_DQ<11>")
	)
	(via
		(at 49.24933 -149.533356)
		(size 0.508)
		(drill 0.254)
		(layers "F.Cu" "B.Cu")
		(net "M_M_DQ<11>")
	)
	(segment
		(start 49.24933 -147.478496)
		(end 49.24933 -149.533356)
		(width 0.1651)
		(layer "B.Cu")
		(net "M_M_DQ<11>")
	)
	(segment
		(start 49.249584 -147.478496)
		(end 49.24933 -147.478496)
		(width 0.1651)
		(layer "B.Cu")
		(net "M_M_DQ<11>")
	)
	(segment
		(start 48.817784 -151.9174)
		(end 48.817784 -152.2222)
		(width 0.14224)
		(layer "In11.Cu")
		(net "M_M_DQ<11>")
	)
	(segment
		(start 49.502568 -120.632474)
		(end 49.502568 -125.738382)
		(width 0.14224)
		(layer "In11.Cu")
		(net "M_M_DQ<11>")
	)
	(segment
		(start 73.205086 -94.31909)
		(end 73.169272 -94.31909)
		(width 0.0889)
		(layer "In11.Cu")
		(net "M_M_DQ<11>")
	)
	(segment
		(start 51.128168 -119.191786)
		(end 51.128168 -124.4854)
		(width 0.14224)
		(layer "In11.Cu")
		(net "M_M_DQ<11>")
	)
	(segment
		(start 49.756314 -139.714478)
		(end 49.756314 -140.817854)
		(width 0.14224)
		(layer "In11.Cu")
		(net "M_M_DQ<11>")
	)
	(segment
		(start 68.46951 -100.102924)
		(end 68.166234 -100.301552)
		(width 0.0889)
		(layer "In11.Cu")
		(net "M_M_DQ<11>")
	)
	(segment
		(start 49.226978 -149.533356)
		(end 48.798734 -149.9616)
		(width 0.14224)
		(layer "In11.Cu")
		(net "M_M_DQ<11>")
	)
	(segment
		(start 49.680368 -143.4592)
		(end 49.502568 -143.637)
		(width 0.14224)
		(layer "In11.Cu")
		(net "M_M_DQ<11>")
	)
	(segment
		(start 69.774816 -96.300036)
		(end 69.74205 -96.300036)
		(width 0.0889)
		(layer "In11.Cu")
		(net "M_M_DQ<11>")
	)
	(segment
		(start 50.518568 -124.6886)
		(end 50.315368 -124.4854)
		(width 0.14224)
		(layer "In11.Cu")
		(net "M_M_DQ<11>")
	)
	(segment
		(start 49.477168 -145.974054)
		(end 49.477168 -146.253454)
		(width 0.14224)
		(layer "In11.Cu")
		(net "M_M_DQ<11>")
	)
	(segment
		(start 50.252884 -126.07925)
		(end 50.252884 -126.48565)
		(width 0.14224)
		(layer "In11.Cu")
		(net "M_M_DQ<11>")
	)
	(segment
		(start 49.527968 -136.271254)
		(end 49.527968 -136.703054)
		(width 0.14224)
		(layer "In11.Cu")
		(net "M_M_DQ<11>")
	)
	(segment
		(start 49.650904 -125.886718)
		(end 50.060352 -125.886718)
		(width 0.14224)
		(layer "In11.Cu")
		(net "M_M_DQ<11>")
	)
	(segment
		(start 49.603914 -138.963654)
		(end 49.603914 -139.562078)
		(width 0.14224)
		(layer "In11.Cu")
		(net "M_M_DQ<11>")
	)
	(segment
		(start 48.560736 -152.479248)
		(end 48.560736 -152.752552)
		(width 0.14224)
		(layer "In11.Cu")
		(net "M_M_DQ<11>")
	)
	(segment
		(start 49.680368 -138.8872)
		(end 49.603914 -138.963654)
		(width 0.14224)
		(layer "In11.Cu")
		(net "M_M_DQ<11>")
	)
	(segment
		(start 49.616614 -131.8768)
		(end 49.680368 -131.940554)
		(width 0.14224)
		(layer "In11.Cu")
		(net "M_M_DQ<11>")
	)
	(segment
		(start 72.34174 -94.81439)
		(end 72.3138 -94.81439)
		(width 0.0889)
		(layer "In11.Cu")
		(net "M_M_DQ<11>")
	)
	(segment
		(start 49.832768 -130.189732)
		(end 49.832768 -131.192524)
		(width 0.14224)
		(layer "In11.Cu")
		(net "M_M_DQ<11>")
	)
	(segment
		(start 49.680368 -133.8072)
		(end 49.527968 -133.9596)
		(width 0.14224)
		(layer "In11.Cu")
		(net "M_M_DQ<11>")
	)
	(segment
		(start 50.112168 -120.429274)
		(end 49.705768 -120.429274)
		(width 0.14224)
		(layer "In11.Cu")
		(net "M_M_DQ<11>")
	)
	(segment
		(start 68.54317 -99.368102)
		(end 68.547996 -99.376738)
		(width 0.0889)
		(layer "In11.Cu")
		(net "M_M_DQ<11>")
	)
	(segment
		(start 49.527968 -133.9596)
		(end 49.527968 -134.484618)
		(width 0.14224)
		(layer "In11.Cu")
		(net "M_M_DQ<11>")
	)
	(segment
		(start 65.912746 -100.539042)
		(end 65.326768 -101.12502)
		(width 0.14224)
		(layer "In11.Cu")
		(net "M_M_DQ<11>")
	)
	(segment
		(start 49.680368 -131.940554)
		(end 49.680368 -133.8072)
		(width 0.14224)
		(layer "In11.Cu")
		(net "M_M_DQ<11>")
	)
	(segment
		(start 65.164716 -103.475282)
		(end 64.47282 -103.475282)
		(width 0.14224)
		(layer "In11.Cu")
		(net "M_M_DQ<11>")
	)
	(segment
		(start 50.315368 -120.632474)
		(end 50.112168 -120.429274)
		(width 0.14224)
		(layer "In11.Cu")
		(net "M_M_DQ<11>")
	)
	(segment
		(start 48.843184 -150.435818)
		(end 48.843184 -151.1046)
		(width 0.14224)
		(layer "In11.Cu")
		(net "M_M_DQ<11>")
	)
	(segment
		(start 49.24933 -149.546564)
		(end 49.24933 -149.533356)
		(width 0.14224)
		(layer "In11.Cu")
		(net "M_M_DQ<11>")
	)
	(segment
		(start 75.762866 -93.23324)
		(end 74.939144 -93.32849)
		(width 0.0889)
		(layer "In11.Cu")
		(net "M_M_DQ<11>")
	)
	(segment
		(start 49.758092 -126.699518)
		(end 49.603914 -126.853696)
		(width 0.14224)
		(layer "In11.Cu")
		(net "M_M_DQ<11>")
	)
	(segment
		(start 49.781714 -134.738364)
		(end 49.781714 -136.017508)
		(width 0.14224)
		(layer "In11.Cu")
		(net "M_M_DQ<11>")
	)
	(segment
		(start 48.560736 -151.660352)
		(end 48.817784 -151.9174)
		(width 0.14224)
		(layer "In11.Cu")
		(net "M_M_DQ<11>")
	)
	(segment
		(start 49.781968 -148.3106)
		(end 49.578514 -148.514054)
		(width 0.14224)
		(layer "In11.Cu")
		(net "M_M_DQ<11>")
	)
	(segment
		(start 64.324992 -103.62311)
		(end 64.324992 -103.97617)
		(width 0.14224)
		(layer "In11.Cu")
		(net "M_M_DQ<11>")
	)
	(segment
		(start 68.166234 -100.301552)
		(end 66.150236 -100.301552)
		(width 0.0889)
		(layer "In11.Cu")
		(net "M_M_DQ<11>")
	)
	(segment
		(start 68.554346 -99.95662)
		(end 68.529708 -99.997768)
		(width 0.0889)
		(layer "In11.Cu")
		(net "M_M_DQ<11>")
	)
	(segment
		(start 49.477168 -146.253454)
		(end 49.781968 -146.558254)
		(width 0.14224)
		(layer "In11.Cu")
		(net "M_M_DQ<11>")
	)
	(segment
		(start 48.817784 -152.2222)
		(end 48.560736 -152.479248)
		(width 0.14224)
		(layer "In11.Cu")
		(net "M_M_DQ<11>")
	)
	(segment
		(start 64.487044 -104.138222)
		(end 65.164716 -104.138222)
		(width 0.14224)
		(layer "In11.Cu")
		(net "M_M_DQ<11>")
	)
	(segment
		(start 49.578514 -148.514054)
		(end 49.578514 -149.21738)
		(width 0.14224)
		(layer "In11.Cu")
		(net "M_M_DQ<11>")
	)
	(segment
		(start 49.502568 -143.637)
		(end 49.502568 -144.068292)
		(width 0.14224)
		(layer "In11.Cu")
		(net "M_M_DQ<11>")
	)
	(segment
		(start 65.164716 -104.138222)
		(end 65.326768 -104.300274)
		(width 0.14224)
		(layer "In11.Cu")
		(net "M_M_DQ<11>")
	)
	(segment
		(start 68.912486 -96.79559)
		(end 68.727828 -96.79559)
		(width 0.0889)
		(layer "In11.Cu")
		(net "M_M_DQ<11>")
	)
	(segment
		(start 65.326768 -103.31323)
		(end 65.164716 -103.475282)
		(width 0.14224)
		(layer "In11.Cu")
		(net "M_M_DQ<11>")
	)
	(segment
		(start 71.491856 -95.309436)
		(end 71.45909 -95.309436)
		(width 0.0889)
		(layer "In11.Cu")
		(net "M_M_DQ<11>")
	)
	(segment
		(start 49.832514 -144.398238)
		(end 49.832514 -145.618708)
		(width 0.14224)
		(layer "In11.Cu")
		(net "M_M_DQ<11>")
	)
	(segment
		(start 49.756314 -140.817854)
		(end 49.477168 -141.097)
		(width 0.14224)
		(layer "In11.Cu")
		(net "M_M_DQ<11>")
	)
	(segment
		(start 49.502568 -144.068292)
		(end 49.832514 -144.398238)
		(width 0.14224)
		(layer "In11.Cu")
		(net "M_M_DQ<11>")
	)
	(segment
		(start 49.832768 -131.192524)
		(end 49.616614 -131.408678)
		(width 0.14224)
		(layer "In11.Cu")
		(net "M_M_DQ<11>")
	)
	(segment
		(start 65.326768 -104.993186)
		(end 51.128168 -119.191786)
		(width 0.14224)
		(layer "In11.Cu")
		(net "M_M_DQ<11>")
	)
	(segment
		(start 65.326768 -101.12502)
		(end 65.326768 -103.31323)
		(width 0.14224)
		(layer "In11.Cu")
		(net "M_M_DQ<11>")
	)
	(segment
		(start 49.680368 -136.855454)
		(end 49.680368 -138.8872)
		(width 0.14224)
		(layer "In11.Cu")
		(net "M_M_DQ<11>")
	)
	(segment
		(start 64.47282 -103.475282)
		(end 64.324992 -103.62311)
		(width 0.14224)
		(layer "In11.Cu")
		(net "M_M_DQ<11>")
	)
	(segment
		(start 48.560736 -152.752552)
		(end 48.849534 -153.04135)
		(width 0.14224)
		(layer "In11.Cu")
		(net "M_M_DQ<11>")
	)
	(segment
		(start 49.832514 -145.618708)
		(end 49.477168 -145.974054)
		(width 0.14224)
		(layer "In11.Cu")
		(net "M_M_DQ<11>")
	)
	(segment
		(start 48.798734 -150.391368)
		(end 48.843184 -150.435818)
		(width 0.14224)
		(layer "In11.Cu")
		(net "M_M_DQ<11>")
	)
	(segment
		(start 49.527968 -134.484618)
		(end 49.781714 -134.738364)
		(width 0.14224)
		(layer "In11.Cu")
		(net "M_M_DQ<11>")
	)
	(segment
		(start 48.843184 -151.1046)
		(end 48.560736 -151.387048)
		(width 0.14224)
		(layer "In11.Cu")
		(net "M_M_DQ<11>")
	)
	(segment
		(start 65.326768 -104.300274)
		(end 65.326768 -104.993186)
		(width 0.14224)
		(layer "In11.Cu")
		(net "M_M_DQ<11>")
	)
	(segment
		(start 48.798734 -149.9616)
		(end 48.798734 -150.391368)
		(width 0.14224)
		(layer "In11.Cu")
		(net "M_M_DQ<11>")
	)
	(segment
		(start 49.477168 -141.097)
		(end 49.477168 -141.579346)
		(width 0.14224)
		(layer "In11.Cu")
		(net "M_M_DQ<11>")
	)
	(segment
		(start 66.150236 -100.301552)
		(end 65.912746 -100.539042)
		(width 0.0889)
		(layer "In11.Cu")
		(net "M_M_DQ<11>")
	)
	(segment
		(start 49.781714 -136.017508)
		(end 49.527968 -136.271254)
		(width 0.14224)
		(layer "In11.Cu")
		(net "M_M_DQ<11>")
	)
	(segment
		(start 50.252884 -126.48565)
		(end 50.039016 -126.699518)
		(width 0.14224)
		(layer "In11.Cu")
		(net "M_M_DQ<11>")
	)
	(segment
		(start 49.502568 -125.738382)
		(end 49.650904 -125.886718)
		(width 0.14224)
		(layer "In11.Cu")
		(net "M_M_DQ<11>")
	)
	(segment
		(start 49.781968 -146.558254)
		(end 49.781968 -148.3106)
		(width 0.14224)
		(layer "In11.Cu")
		(net "M_M_DQ<11>")
	)
	(segment
		(start 49.527968 -136.703054)
		(end 49.680368 -136.855454)
		(width 0.14224)
		(layer "In11.Cu")
		(net "M_M_DQ<11>")
	)
	(segment
		(start 48.849534 -153.04135)
		(end 48.849534 -153.364946)
		(width 0.14224)
		(layer "In11.Cu")
		(net "M_M_DQ<11>")
	)
	(segment
		(start 48.560736 -151.387048)
		(end 48.560736 -151.660352)
		(width 0.14224)
		(layer "In11.Cu")
		(net "M_M_DQ<11>")
	)
	(segment
		(start 49.578514 -149.21738)
		(end 49.24933 -149.546564)
		(width 0.14224)
		(layer "In11.Cu")
		(net "M_M_DQ<11>")
	)
	(segment
		(start 74.939144 -93.32849)
		(end 74.89317 -93.32849)
		(width 0.0889)
		(layer "In11.Cu")
		(net "M_M_DQ<11>")
	)
	(segment
		(start 48.849534 -153.364946)
		(end 48.671734 -153.542746)
		(width 0.14224)
		(layer "In11.Cu")
		(net "M_M_DQ<11>")
	)
	(segment
		(start 49.603914 -126.853696)
		(end 49.603914 -129.960878)
		(width 0.14224)
		(layer "In11.Cu")
		(net "M_M_DQ<11>")
	)
	(segment
		(start 50.315368 -124.4854)
		(end 50.315368 -120.632474)
		(width 0.14224)
		(layer "In11.Cu")
		(net "M_M_DQ<11>")
	)
	(segment
		(start 49.705768 -120.429274)
		(end 49.502568 -120.632474)
		(width 0.14224)
		(layer "In11.Cu")
		(net "M_M_DQ<11>")
	)
	(segment
		(start 50.039016 -126.699518)
		(end 49.758092 -126.699518)
		(width 0.14224)
		(layer "In11.Cu")
		(net "M_M_DQ<11>")
	)
	(segment
		(start 49.477168 -141.579346)
		(end 49.680368 -141.782546)
		(width 0.14224)
		(layer "In11.Cu")
		(net "M_M_DQ<11>")
	)
	(segment
		(start 50.924968 -124.6886)
		(end 50.518568 -124.6886)
		(width 0.14224)
		(layer "In11.Cu")
		(net "M_M_DQ<11>")
	)
	(segment
		(start 74.067416 -93.82379)
		(end 74.027792 -93.82379)
		(width 0.0889)
		(layer "In11.Cu")
		(net "M_M_DQ<11>")
	)
	(segment
		(start 70.629526 -95.80499)
		(end 70.59676 -95.80499)
		(width 0.0889)
		(layer "In11.Cu")
		(net "M_M_DQ<11>")
	)
	(segment
		(start 50.060352 -125.886718)
		(end 50.252884 -126.07925)
		(width 0.14224)
		(layer "In11.Cu")
		(net "M_M_DQ<11>")
	)
	(segment
		(start 51.128168 -124.4854)
		(end 50.924968 -124.6886)
		(width 0.14224)
		(layer "In11.Cu")
		(net "M_M_DQ<11>")
	)
	(segment
		(start 68.54317 -98.377502)
		(end 68.547996 -98.386138)
		(width 0.0889)
		(layer "In11.Cu")
		(net "M_M_DQ<11>")
	)
	(segment
		(start 68.547996 -98.386138)
		(end 68.554346 -98.396806)
		(width 0.0889)
		(layer "In11.Cu")
		(net "M_M_DQ<11>")
	)
	(segment
		(start 68.464938 -97.251266)
		(end 68.554346 -97.406206)
		(width 0.0889)
		(layer "In11.Cu")
		(net "M_M_DQ<11>")
	)
	(segment
		(start 49.680368 -141.782546)
		(end 49.680368 -143.4592)
		(width 0.14224)
		(layer "In11.Cu")
		(net "M_M_DQ<11>")
	)
	(segment
		(start 49.616614 -131.408678)
		(end 49.616614 -131.8768)
		(width 0.14224)
		(layer "In11.Cu")
		(net "M_M_DQ<11>")
	)
	(segment
		(start 48.671734 -153.542746)
		(end 48.399446 -153.542746)
		(width 0.14224)
		(layer "In11.Cu")
		(net "M_M_DQ<11>")
	)
	(segment
		(start 49.603914 -129.960878)
		(end 49.832768 -130.189732)
		(width 0.14224)
		(layer "In11.Cu")
		(net "M_M_DQ<11>")
	)
	(segment
		(start 68.529708 -99.997768)
		(end 68.46951 -100.102924)
		(width 0.0889)
		(layer "In11.Cu")
		(net "M_M_DQ<11>")
	)
	(segment
		(start 49.24933 -149.533356)
		(end 49.226978 -149.533356)
		(width 0.14224)
		(layer "In11.Cu")
		(net "M_M_DQ<11>")
	)
	(segment
		(start 64.324992 -103.97617)
		(end 64.487044 -104.138222)
		(width 0.14224)
		(layer "In11.Cu")
		(net "M_M_DQ<11>")
	)
	(segment
		(start 49.603914 -139.562078)
		(end 49.756314 -139.714478)
		(width 0.14224)
		(layer "In11.Cu")
		(net "M_M_DQ<11>")
	)
	(arc
		(start 72.840596 -94.518988)
		(mid 72.629883 -94.732067)
		(end 72.34174 -94.81439)
		(width 0.0889)
		(layer "In11.Cu")
		(net "M_M_DQ<11>")
	)
	(arc
		(start 71.123556 -95.509588)
		(mid 70.914948 -95.72152)
		(end 70.629526 -95.80499)
		(width 0.0889)
		(layer "In11.Cu")
		(net "M_M_DQ<11>")
	)
	(arc
		(start 69.406516 -96.500188)
		(mid 69.197908 -96.71212)
		(end 68.912486 -96.79559)
		(width 0.0889)
		(layer "In11.Cu")
		(net "M_M_DQ<11>")
	)
	(arc
		(start 73.699116 -94.023688)
		(mid 73.490508 -94.23562)
		(end 73.205086 -94.31909)
		(width 0.0889)
		(layer "In11.Cu")
		(net "M_M_DQ<11>")
	)
	(arc
		(start 70.265036 -96.004888)
		(mid 70.058032 -96.215752)
		(end 69.774816 -96.300036)
		(width 0.0889)
		(layer "In11.Cu")
		(net "M_M_DQ<11>")
	)
	(arc
		(start 68.554346 -97.406206)
		(mid 68.627144 -97.696969)
		(end 68.547996 -97.986088)
		(width 0.0889)
		(layer "In11.Cu")
		(net "M_M_DQ<11>")
	)
	(arc
		(start 69.74205 -96.300036)
		(mid 69.5482 -96.356386)
		(end 69.406516 -96.500188)
		(width 0.0889)
		(layer "In11.Cu")
		(net "M_M_DQ<11>")
	)
	(arc
		(start 74.027792 -93.82379)
		(mid 73.837863 -93.88166)
		(end 73.699116 -94.023688)
		(width 0.0889)
		(layer "In11.Cu")
		(net "M_M_DQ<11>")
	)
	(arc
		(start 68.547996 -99.376738)
		(mid 68.627218 -99.665856)
		(end 68.554346 -99.95662)
		(width 0.0889)
		(layer "In11.Cu")
		(net "M_M_DQ<11>")
	)
	(arc
		(start 74.557636 -93.528642)
		(mid 74.350632 -93.739506)
		(end 74.067416 -93.82379)
		(width 0.0889)
		(layer "In11.Cu")
		(net "M_M_DQ<11>")
	)
	(arc
		(start 74.89317 -93.32849)
		(mid 74.69932 -93.38484)
		(end 74.557636 -93.528642)
		(width 0.0889)
		(layer "In11.Cu")
		(net "M_M_DQ<11>")
	)
	(arc
		(start 71.982076 -95.014288)
		(mid 71.775072 -95.225152)
		(end 71.491856 -95.309436)
		(width 0.0889)
		(layer "In11.Cu")
		(net "M_M_DQ<11>")
	)
	(arc
		(start 68.727828 -96.79559)
		(mid 68.519284 -96.978969)
		(end 68.464938 -97.251266)
		(width 0.0889)
		(layer "In11.Cu")
		(net "M_M_DQ<11>")
	)
	(arc
		(start 68.547996 -98.976688)
		(mid 68.494526 -99.171751)
		(end 68.54317 -99.368102)
		(width 0.0889)
		(layer "In11.Cu")
		(net "M_M_DQ<11>")
	)
	(arc
		(start 72.3138 -94.81439)
		(mid 72.122158 -94.871556)
		(end 71.982076 -95.014288)
		(width 0.0889)
		(layer "In11.Cu")
		(net "M_M_DQ<11>")
	)
	(arc
		(start 68.554346 -98.396806)
		(mid 68.627144 -98.687569)
		(end 68.547996 -98.976688)
		(width 0.0889)
		(layer "In11.Cu")
		(net "M_M_DQ<11>")
	)
	(arc
		(start 68.547996 -97.986088)
		(mid 68.494526 -98.181151)
		(end 68.54317 -98.377502)
		(width 0.0889)
		(layer "In11.Cu")
		(net "M_M_DQ<11>")
	)
	(arc
		(start 70.59676 -95.80499)
		(mid 70.405118 -95.862156)
		(end 70.265036 -96.004888)
		(width 0.0889)
		(layer "In11.Cu")
		(net "M_M_DQ<11>")
	)
	(arc
		(start 73.169272 -94.31909)
		(mid 72.979343 -94.37696)
		(end 72.840596 -94.518988)
		(width 0.0889)
		(layer "In11.Cu")
		(net "M_M_DQ<11>")
	)
	(arc
		(start 71.45909 -95.309436)
		(mid 71.26524 -95.365786)
		(end 71.123556 -95.509588)
		(width 0.0889)
		(layer "In11.Cu")
		(net "M_M_DQ<11>")
	)
	(segment
		(start 49.380902 -155.75026)
		(end 49.380902 -155.52674)
		(width 0.1651)
		(layer "F.Cu")
		(net "M_M_DQ<10>")
	)
	(segment
		(start 49.24933 -155.395168)
		(end 49.24933 -155.1178)
		(width 0.1651)
		(layer "F.Cu")
		(net "M_M_DQ<10>")
	)
	(segment
		(start 49.380902 -155.52674)
		(end 49.24933 -155.395168)
		(width 0.1651)
		(layer "F.Cu")
		(net "M_M_DQ<10>")
	)
	(segment
		(start 77.192886 -92.737686)
		(end 76.621386 -92.737686)
		(width 0.1651)
		(layer "F.Cu")
		(net "M_M_DQ<10>")
	)
	(segment
		(start 49.24933 -155.881832)
		(end 49.380902 -155.75026)
		(width 0.1651)
		(layer "F.Cu")
		(net "M_M_DQ<10>")
	)
	(segment
		(start 49.249584 -156.87294)
		(end 49.24933 -156.87294)
		(width 0.1651)
		(layer "F.Cu")
		(net "M_M_DQ<10>")
	)
	(segment
		(start 49.24933 -156.87294)
		(end 49.24933 -155.881832)
		(width 0.1651)
		(layer "F.Cu")
		(net "M_M_DQ<10>")
	)
	(via
		(at 48.399446 -150.814278)
		(size 0.508)
		(drill 0.254)
		(layers "F.Cu" "B.Cu")
		(net "M_M_DQ<10>")
	)
	(via
		(at 49.24933 -155.1178)
		(size 0.508)
		(drill 0.254)
		(layers "F.Cu" "B.Cu")
		(net "M_M_DQ<10>")
	)
	(via
		(at 76.621386 -92.737686)
		(size 0.508)
		(drill 0.254)
		(layers "F.Cu" "B.Cu")
		(net "M_M_DQ<10>")
	)
	(segment
		(start 48.399446 -152.078436)
		(end 48.399446 -150.814278)
		(width 0.1651)
		(layer "B.Cu")
		(net "M_M_DQ<10>")
	)
	(segment
		(start 48.816768 -129.2606)
		(end 48.994568 -129.4384)
		(width 0.14224)
		(layer "In11.Cu")
		(net "M_M_DQ<10>")
	)
	(segment
		(start 47.966376 -151.247348)
		(end 47.966376 -153.834846)
		(width 0.14224)
		(layer "In11.Cu")
		(net "M_M_DQ<10>")
	)
	(segment
		(start 70.590156 -95.61449)
		(end 70.622922 -95.61449)
		(width 0.0889)
		(layer "In11.Cu")
		(net "M_M_DQ<10>")
	)
	(segment
		(start 48.765714 -129.960878)
		(end 48.765714 -131.190746)
		(width 0.14224)
		(layer "In11.Cu")
		(net "M_M_DQ<10>")
	)
	(segment
		(start 49.096168 -131.813046)
		(end 48.816768 -132.092446)
		(width 0.14224)
		(layer "In11.Cu")
		(net "M_M_DQ<10>")
	)
	(segment
		(start 48.816768 -120.605042)
		(end 48.816768 -129.2606)
		(width 0.14224)
		(layer "In11.Cu")
		(net "M_M_DQ<10>")
	)
	(segment
		(start 49.086516 -138.953748)
		(end 49.086516 -139.241276)
		(width 0.14224)
		(layer "In11.Cu")
		(net "M_M_DQ<10>")
	)
	(segment
		(start 48.842168 -136.829546)
		(end 48.842168 -138.7094)
		(width 0.14224)
		(layer "In11.Cu")
		(net "M_M_DQ<10>")
	)
	(segment
		(start 75.79995 -92.64269)
		(end 76.621386 -92.737686)
		(width 0.0889)
		(layer "In11.Cu")
		(net "M_M_DQ<10>")
	)
	(segment
		(start 60.987178 -107.285028)
		(end 63.82385 -104.448356)
		(width 0.14224)
		(layer "In11.Cu")
		(net "M_M_DQ<10>")
	)
	(segment
		(start 65.912746 -99.896168)
		(end 65.910714 -99.8982)
		(width 0.14224)
		(layer "In11.Cu")
		(net "M_M_DQ<10>")
	)
	(segment
		(start 48.968914 -144.093438)
		(end 48.689514 -144.372838)
		(width 0.14224)
		(layer "In11.Cu")
		(net "M_M_DQ<10>")
	)
	(segment
		(start 48.842168 -138.7094)
		(end 49.086516 -138.953748)
		(width 0.14224)
		(layer "In11.Cu")
		(net "M_M_DQ<10>")
	)
	(segment
		(start 48.981614 -134.471664)
		(end 48.740314 -134.712964)
		(width 0.14224)
		(layer "In11.Cu")
		(net "M_M_DQ<10>")
	)
	(segment
		(start 72.315832 -94.623636)
		(end 72.339962 -94.623636)
		(width 0.0889)
		(layer "In11.Cu")
		(net "M_M_DQ<10>")
	)
	(segment
		(start 68.376546 -98.47072)
		(end 68.382896 -98.481388)
		(width 0.0889)
		(layer "In11.Cu")
		(net "M_M_DQ<10>")
	)
	(segment
		(start 60.412376 -106.710226)
		(end 60.412376 -106.997754)
		(width 0.14224)
		(layer "In11.Cu")
		(net "M_M_DQ<10>")
	)
	(segment
		(start 48.918114 -145.806668)
		(end 48.918114 -146.177)
		(width 0.14224)
		(layer "In11.Cu")
		(net "M_M_DQ<10>")
	)
	(segment
		(start 71.452486 -95.118936)
		(end 71.485252 -95.118936)
		(width 0.0889)
		(layer "In11.Cu")
		(net "M_M_DQ<10>")
	)
	(segment
		(start 48.816768 -134.0358)
		(end 48.981614 -134.200646)
		(width 0.14224)
		(layer "In11.Cu")
		(net "M_M_DQ<10>")
	)
	(segment
		(start 48.689514 -145.578068)
		(end 48.918114 -145.806668)
		(width 0.14224)
		(layer "In11.Cu")
		(net "M_M_DQ<10>")
	)
	(segment
		(start 74.891392 -93.137736)
		(end 74.919332 -93.137736)
		(width 0.0889)
		(layer "In11.Cu")
		(net "M_M_DQ<10>")
	)
	(segment
		(start 48.994568 -129.732024)
		(end 48.765714 -129.960878)
		(width 0.14224)
		(layer "In11.Cu")
		(net "M_M_DQ<10>")
	)
	(segment
		(start 74.028046 -93.633036)
		(end 74.06386 -93.633036)
		(width 0.0889)
		(layer "In11.Cu")
		(net "M_M_DQ<10>")
	)
	(segment
		(start 48.054514 -150.469346)
		(end 48.399446 -150.814278)
		(width 0.14224)
		(layer "In11.Cu")
		(net "M_M_DQ<10>")
	)
	(segment
		(start 48.981614 -134.200646)
		(end 48.981614 -134.471664)
		(width 0.14224)
		(layer "In11.Cu")
		(net "M_M_DQ<10>")
	)
	(segment
		(start 48.816768 -132.092446)
		(end 48.816768 -134.0358)
		(width 0.14224)
		(layer "In11.Cu")
		(net "M_M_DQ<10>")
	)
	(segment
		(start 48.816768 -143.637)
		(end 48.968914 -143.789146)
		(width 0.14224)
		(layer "In11.Cu")
		(net "M_M_DQ<10>")
	)
	(segment
		(start 65.910714 -99.8982)
		(end 65.428368 -99.8982)
		(width 0.14224)
		(layer "In11.Cu")
		(net "M_M_DQ<10>")
	)
	(segment
		(start 66.128138 -100.11156)
		(end 65.912746 -99.896168)
		(width 0.0889)
		(layer "In11.Cu")
		(net "M_M_DQ<10>")
	)
	(segment
		(start 68.281804 -97.315528)
		(end 68.387722 -97.499424)
		(width 0.0889)
		(layer "In11.Cu")
		(net "M_M_DQ<10>")
	)
	(segment
		(start 48.997616 -136.674098)
		(end 48.842168 -136.829546)
		(width 0.14224)
		(layer "In11.Cu")
		(net "M_M_DQ<10>")
	)
	(segment
		(start 48.399446 -150.814278)
		(end 47.966376 -151.247348)
		(width 0.14224)
		(layer "In11.Cu")
		(net "M_M_DQ<10>")
	)
	(segment
		(start 48.968914 -143.789146)
		(end 48.968914 -144.093438)
		(width 0.14224)
		(layer "In11.Cu")
		(net "M_M_DQ<10>")
	)
	(segment
		(start 48.816768 -141.680946)
		(end 48.816768 -143.637)
		(width 0.14224)
		(layer "In11.Cu")
		(net "M_M_DQ<10>")
	)
	(segment
		(start 64.398652 -105.023158)
		(end 48.816768 -120.605042)
		(width 0.14224)
		(layer "In11.Cu")
		(net "M_M_DQ<10>")
	)
	(segment
		(start 64.398652 -104.73563)
		(end 64.398652 -105.023158)
		(width 0.14224)
		(layer "In11.Cu")
		(net "M_M_DQ<10>")
	)
	(segment
		(start 64.615568 -100.711)
		(end 64.615568 -102.507034)
		(width 0.14224)
		(layer "In11.Cu")
		(net "M_M_DQ<10>")
	)
	(segment
		(start 68.327016 -99.968812)
		(end 68.109338 -100.11156)
		(width 0.0889)
		(layer "In11.Cu")
		(net "M_M_DQ<10>")
	)
	(segment
		(start 48.997616 -136.299194)
		(end 48.997616 -136.674098)
		(width 0.14224)
		(layer "In11.Cu")
		(net "M_M_DQ<10>")
	)
	(segment
		(start 69.735446 -96.109536)
		(end 69.768212 -96.109536)
		(width 0.0889)
		(layer "In11.Cu")
		(net "M_M_DQ<10>")
	)
	(segment
		(start 68.382896 -98.481388)
		(end 68.387722 -98.490024)
		(width 0.0889)
		(layer "In11.Cu")
		(net "M_M_DQ<10>")
	)
	(segment
		(start 48.816768 -146.278346)
		(end 48.816768 -148.3868)
		(width 0.14224)
		(layer "In11.Cu")
		(net "M_M_DQ<10>")
	)
	(segment
		(start 48.918114 -146.177)
		(end 48.816768 -146.278346)
		(width 0.14224)
		(layer "In11.Cu")
		(net "M_M_DQ<10>")
	)
	(segment
		(start 48.918114 -148.972778)
		(end 48.054514 -149.836378)
		(width 0.14224)
		(layer "In11.Cu")
		(net "M_M_DQ<10>")
	)
	(segment
		(start 68.382896 -99.872038)
		(end 68.327016 -99.968812)
		(width 0.0889)
		(layer "In11.Cu")
		(net "M_M_DQ<10>")
	)
	(segment
		(start 60.412376 -106.997754)
		(end 60.69965 -107.285028)
		(width 0.14224)
		(layer "In11.Cu")
		(net "M_M_DQ<10>")
	)
	(segment
		(start 73.165716 -94.128336)
		(end 73.20534 -94.128336)
		(width 0.0889)
		(layer "In11.Cu")
		(net "M_M_DQ<10>")
	)
	(segment
		(start 48.968914 -141.136878)
		(end 48.968914 -141.5288)
		(width 0.14224)
		(layer "In11.Cu")
		(net "M_M_DQ<10>")
	)
	(segment
		(start 48.765714 -139.562078)
		(end 48.765714 -140.933678)
		(width 0.14224)
		(layer "In11.Cu")
		(net "M_M_DQ<10>")
	)
	(segment
		(start 48.816768 -148.3868)
		(end 48.918114 -148.488146)
		(width 0.14224)
		(layer "In11.Cu")
		(net "M_M_DQ<10>")
	)
	(segment
		(start 75.741276 -92.64269)
		(end 75.79995 -92.64269)
		(width 0.0889)
		(layer "In11.Cu")
		(net "M_M_DQ<10>")
	)
	(segment
		(start 68.691506 -96.60509)
		(end 68.905882 -96.60509)
		(width 0.0889)
		(layer "In11.Cu")
		(net "M_M_DQ<10>")
	)
	(segment
		(start 49.096168 -131.5212)
		(end 49.096168 -131.813046)
		(width 0.14224)
		(layer "In11.Cu")
		(net "M_M_DQ<10>")
	)
	(segment
		(start 64.615568 -102.507034)
		(end 60.412376 -106.710226)
		(width 0.14224)
		(layer "In11.Cu")
		(net "M_M_DQ<10>")
	)
	(segment
		(start 48.994568 -129.4384)
		(end 48.994568 -129.732024)
		(width 0.14224)
		(layer "In11.Cu")
		(net "M_M_DQ<10>")
	)
	(segment
		(start 60.69965 -107.285028)
		(end 60.987178 -107.285028)
		(width 0.14224)
		(layer "In11.Cu")
		(net "M_M_DQ<10>")
	)
	(segment
		(start 48.918114 -148.488146)
		(end 48.918114 -148.972778)
		(width 0.14224)
		(layer "In11.Cu")
		(net "M_M_DQ<10>")
	)
	(segment
		(start 63.82385 -104.448356)
		(end 64.111378 -104.448356)
		(width 0.14224)
		(layer "In11.Cu")
		(net "M_M_DQ<10>")
	)
	(segment
		(start 48.054514 -149.836378)
		(end 48.054514 -150.469346)
		(width 0.14224)
		(layer "In11.Cu")
		(net "M_M_DQ<10>")
	)
	(segment
		(start 48.765714 -140.933678)
		(end 48.968914 -141.136878)
		(width 0.14224)
		(layer "In11.Cu")
		(net "M_M_DQ<10>")
	)
	(segment
		(start 48.740314 -136.041892)
		(end 48.997616 -136.299194)
		(width 0.14224)
		(layer "In11.Cu")
		(net "M_M_DQ<10>")
	)
	(segment
		(start 47.966376 -153.834846)
		(end 49.24933 -155.1178)
		(width 0.14224)
		(layer "In11.Cu")
		(net "M_M_DQ<10>")
	)
	(segment
		(start 65.428368 -99.8982)
		(end 64.615568 -100.711)
		(width 0.14224)
		(layer "In11.Cu")
		(net "M_M_DQ<10>")
	)
	(segment
		(start 68.109338 -100.11156)
		(end 66.128138 -100.11156)
		(width 0.0889)
		(layer "In11.Cu")
		(net "M_M_DQ<10>")
	)
	(segment
		(start 64.111378 -104.448356)
		(end 64.398652 -104.73563)
		(width 0.14224)
		(layer "In11.Cu")
		(net "M_M_DQ<10>")
	)
	(segment
		(start 49.086516 -139.241276)
		(end 48.765714 -139.562078)
		(width 0.14224)
		(layer "In11.Cu")
		(net "M_M_DQ<10>")
	)
	(segment
		(start 48.968914 -141.5288)
		(end 48.816768 -141.680946)
		(width 0.14224)
		(layer "In11.Cu")
		(net "M_M_DQ<10>")
	)
	(segment
		(start 48.689514 -144.372838)
		(end 48.689514 -145.578068)
		(width 0.14224)
		(layer "In11.Cu")
		(net "M_M_DQ<10>")
	)
	(segment
		(start 48.765714 -131.190746)
		(end 49.096168 -131.5212)
		(width 0.14224)
		(layer "In11.Cu")
		(net "M_M_DQ<10>")
	)
	(segment
		(start 48.740314 -134.712964)
		(end 48.740314 -136.041892)
		(width 0.14224)
		(layer "In11.Cu")
		(net "M_M_DQ<10>")
	)
	(arc
		(start 70.958456 -95.414338)
		(mid 71.167064 -95.202406)
		(end 71.452486 -95.118936)
		(width 0.0889)
		(layer "In11.Cu")
		(net "M_M_DQ<10>")
	)
	(arc
		(start 71.816976 -94.919038)
		(mid 72.027689 -94.705959)
		(end 72.315832 -94.623636)
		(width 0.0889)
		(layer "In11.Cu")
		(net "M_M_DQ<10>")
	)
	(arc
		(start 74.919332 -93.137736)
		(mid 75.110974 -93.08057)
		(end 75.251056 -92.937838)
		(width 0.0889)
		(layer "In11.Cu")
		(net "M_M_DQ<10>")
	)
	(arc
		(start 73.534016 -93.928438)
		(mid 73.742624 -93.716506)
		(end 74.028046 -93.633036)
		(width 0.0889)
		(layer "In11.Cu")
		(net "M_M_DQ<10>")
	)
	(arc
		(start 72.339962 -94.623636)
		(mid 72.533812 -94.567286)
		(end 72.675496 -94.423484)
		(width 0.0889)
		(layer "In11.Cu")
		(net "M_M_DQ<10>")
	)
	(arc
		(start 68.382896 -99.472242)
		(mid 68.436395 -99.67214)
		(end 68.382896 -99.872038)
		(width 0.0889)
		(layer "In11.Cu")
		(net "M_M_DQ<10>")
	)
	(arc
		(start 68.387722 -98.490024)
		(mid 68.436477 -98.686376)
		(end 68.382896 -98.881438)
		(width 0.0889)
		(layer "In11.Cu")
		(net "M_M_DQ<10>")
	)
	(arc
		(start 68.281804 -97.315528)
		(mid 68.353707 -96.883643)
		(end 68.691506 -96.60509)
		(width 0.0889)
		(layer "In11.Cu")
		(net "M_M_DQ<10>")
	)
	(arc
		(start 68.387722 -97.499424)
		(mid 68.436477 -97.695776)
		(end 68.382896 -97.890838)
		(width 0.0889)
		(layer "In11.Cu")
		(net "M_M_DQ<10>")
	)
	(arc
		(start 74.06386 -93.633036)
		(mid 74.253789 -93.575166)
		(end 74.392536 -93.433138)
		(width 0.0889)
		(layer "In11.Cu")
		(net "M_M_DQ<10>")
	)
	(arc
		(start 68.905882 -96.60509)
		(mid 69.099732 -96.54874)
		(end 69.241416 -96.404938)
		(width 0.0889)
		(layer "In11.Cu")
		(net "M_M_DQ<10>")
	)
	(arc
		(start 69.768212 -96.109536)
		(mid 69.959854 -96.05237)
		(end 70.099936 -95.909638)
		(width 0.0889)
		(layer "In11.Cu")
		(net "M_M_DQ<10>")
	)
	(arc
		(start 70.099936 -95.909638)
		(mid 70.30694 -95.698774)
		(end 70.590156 -95.61449)
		(width 0.0889)
		(layer "In11.Cu")
		(net "M_M_DQ<10>")
	)
	(arc
		(start 68.382896 -97.890838)
		(mid 68.303674 -98.179956)
		(end 68.376546 -98.47072)
		(width 0.0889)
		(layer "In11.Cu")
		(net "M_M_DQ<10>")
	)
	(arc
		(start 70.622922 -95.61449)
		(mid 70.816772 -95.55814)
		(end 70.958456 -95.414338)
		(width 0.0889)
		(layer "In11.Cu")
		(net "M_M_DQ<10>")
	)
	(arc
		(start 72.675496 -94.423484)
		(mid 72.8825 -94.21262)
		(end 73.165716 -94.128336)
		(width 0.0889)
		(layer "In11.Cu")
		(net "M_M_DQ<10>")
	)
	(arc
		(start 74.392536 -93.433138)
		(mid 74.603249 -93.220059)
		(end 74.891392 -93.137736)
		(width 0.0889)
		(layer "In11.Cu")
		(net "M_M_DQ<10>")
	)
	(arc
		(start 73.20534 -94.128336)
		(mid 73.395269 -94.070466)
		(end 73.534016 -93.928438)
		(width 0.0889)
		(layer "In11.Cu")
		(net "M_M_DQ<10>")
	)
	(arc
		(start 75.251056 -92.937838)
		(mid 75.45806 -92.726974)
		(end 75.741276 -92.64269)
		(width 0.0889)
		(layer "In11.Cu")
		(net "M_M_DQ<10>")
	)
	(arc
		(start 68.382896 -98.881438)
		(mid 68.303765 -99.17684)
		(end 68.382896 -99.472242)
		(width 0.0889)
		(layer "In11.Cu")
		(net "M_M_DQ<10>")
	)
	(arc
		(start 69.241416 -96.404938)
		(mid 69.450024 -96.193006)
		(end 69.735446 -96.109536)
		(width 0.0889)
		(layer "In11.Cu")
		(net "M_M_DQ<10>")
	)
	(arc
		(start 71.485252 -95.118936)
		(mid 71.676894 -95.06177)
		(end 71.816976 -94.919038)
		(width 0.0889)
		(layer "In11.Cu")
		(net "M_M_DQ<10>")
	)
	(segment
		(start 33.949386 -156.878782)
		(end 33.771586 -155.0162)
		(width 0.1651)
		(layer "F.Cu")
		(net "M_M_DQ<0>")
	)
	(segment
		(start 33.949386 -156.87294)
		(end 33.949386 -156.878782)
		(width 0.1651)
		(layer "F.Cu")
		(net "M_M_DQ<0>")
	)
	(segment
		(start 78.051406 -86.29904)
		(end 77.479906 -86.29904)
		(width 0.1651)
		(layer "F.Cu")
		(net "M_M_DQ<0>")
	)
	(via
		(at 33.771586 -155.0162)
		(size 0.508)
		(drill 0.254)
		(layers "F.Cu" "B.Cu")
		(net "M_M_DQ<0>")
	)
	(via
		(at 77.479906 -86.29904)
		(size 0.508)
		(drill 0.254)
		(layers "F.Cu" "B.Cu")
		(net "M_M_DQ<0>")
	)
	(via
		(at 33.099502 -150.814278)
		(size 0.508)
		(drill 0.254)
		(layers "F.Cu" "B.Cu")
		(net "M_M_DQ<0>")
	)
	(segment
		(start 33.099502 -152.078436)
		(end 33.099502 -150.814278)
		(width 0.1651)
		(layer "B.Cu")
		(net "M_M_DQ<0>")
	)
	(segment
		(start 66.723768 -87.68969)
		(end 66.242692 -87.208614)
		(width 0.0889)
		(layer "In11.Cu")
		(net "M_M_DQ<0>")
	)
	(segment
		(start 33.576768 -113.13033)
		(end 33.576768 -126.6952)
		(width 0.14224)
		(layer "In11.Cu")
		(net "M_M_DQ<0>")
	)
	(segment
		(start 41.679368 -103.049832)
		(end 41.679368 -104.978454)
		(width 0.14224)
		(layer "In11.Cu")
		(net "M_M_DQ<0>")
	)
	(segment
		(start 33.099502 -150.814278)
		(end 32.666432 -151.247348)
		(width 0.14224)
		(layer "In11.Cu")
		(net "M_M_DQ<0>")
	)
	(segment
		(start 33.652968 -131.546854)
		(end 33.652968 -131.899152)
		(width 0.14224)
		(layer "In11.Cu")
		(net "M_M_DQ<0>")
	)
	(segment
		(start 33.58642 -148.960078)
		(end 32.73552 -149.810978)
		(width 0.14224)
		(layer "In11.Cu")
		(net "M_M_DQ<0>")
	)
	(segment
		(start 33.58642 -148.498052)
		(end 33.58642 -148.960078)
		(width 0.14224)
		(layer "In11.Cu")
		(net "M_M_DQ<0>")
	)
	(segment
		(start 74.922126 -84.222336)
		(end 74.88936 -84.222336)
		(width 0.0889)
		(layer "In11.Cu")
		(net "M_M_DQ<0>")
	)
	(segment
		(start 67.188842 -87.68969)
		(end 66.723768 -87.68969)
		(width 0.0889)
		(layer "In11.Cu")
		(net "M_M_DQ<0>")
	)
	(segment
		(start 33.128204 -128.888236)
		(end 33.62452 -129.384552)
		(width 0.14224)
		(layer "In11.Cu")
		(net "M_M_DQ<0>")
	)
	(segment
		(start 33.62452 -129.384552)
		(end 33.62452 -129.720594)
		(width 0.14224)
		(layer "In11.Cu")
		(net "M_M_DQ<0>")
	)
	(segment
		(start 64.233552 -86.976712)
		(end 62.585854 -86.976712)
		(width 0.14224)
		(layer "In11.Cu")
		(net "M_M_DQ<0>")
	)
	(segment
		(start 33.62452 -134.433818)
		(end 33.28162 -134.776718)
		(width 0.14224)
		(layer "In11.Cu")
		(net "M_M_DQ<0>")
	)
	(segment
		(start 69.768212 -86.203536)
		(end 69.735446 -86.203536)
		(width 0.0889)
		(layer "In11.Cu")
		(net "M_M_DQ<0>")
	)
	(segment
		(start 33.62452 -139.320778)
		(end 33.28162 -139.663678)
		(width 0.14224)
		(layer "In11.Cu")
		(net "M_M_DQ<0>")
	)
	(segment
		(start 33.525968 -136.674352)
		(end 33.525968 -138.7602)
		(width 0.14224)
		(layer "In11.Cu")
		(net "M_M_DQ<0>")
	)
	(segment
		(start 39.342568 -107.315254)
		(end 39.342568 -107.874054)
		(width 0.14224)
		(layer "In11.Cu")
		(net "M_M_DQ<0>")
	)
	(segment
		(start 68.905882 -86.69909)
		(end 68.873116 -86.69909)
		(width 0.0889)
		(layer "In11.Cu")
		(net "M_M_DQ<0>")
	)
	(segment
		(start 33.525968 -146.262852)
		(end 33.525968 -148.4376)
		(width 0.14224)
		(layer "In11.Cu")
		(net "M_M_DQ<0>")
	)
	(segment
		(start 33.525968 -132.026152)
		(end 33.525968 -133.9088)
		(width 0.14224)
		(layer "In11.Cu")
		(net "M_M_DQ<0>")
	)
	(segment
		(start 77.479906 -86.29904)
		(end 77.150468 -85.538056)
		(width 0.0889)
		(layer "In11.Cu")
		(net "M_M_DQ<0>")
	)
	(segment
		(start 32.73552 -149.810978)
		(end 32.73552 -150.450296)
		(width 0.14224)
		(layer "In11.Cu")
		(net "M_M_DQ<0>")
	)
	(segment
		(start 33.57372 -144.085818)
		(end 33.29432 -144.365218)
		(width 0.14224)
		(layer "In11.Cu")
		(net "M_M_DQ<0>")
	)
	(segment
		(start 33.314386 -130.030728)
		(end 33.314386 -131.208272)
		(width 0.14224)
		(layer "In11.Cu")
		(net "M_M_DQ<0>")
	)
	(segment
		(start 32.666432 -153.911046)
		(end 33.771586 -155.0162)
		(width 0.14224)
		(layer "In11.Cu")
		(net "M_M_DQ<0>")
	)
	(segment
		(start 33.28162 -135.950452)
		(end 33.62452 -136.293352)
		(width 0.14224)
		(layer "In11.Cu")
		(net "M_M_DQ<0>")
	)
	(segment
		(start 32.666432 -151.247348)
		(end 32.666432 -153.911046)
		(width 0.14224)
		(layer "In11.Cu")
		(net "M_M_DQ<0>")
	)
	(segment
		(start 33.62452 -136.293352)
		(end 33.62452 -136.5758)
		(width 0.14224)
		(layer "In11.Cu")
		(net "M_M_DQ<0>")
	)
	(segment
		(start 72.339962 -84.71789)
		(end 72.307196 -84.71789)
		(width 0.0889)
		(layer "In11.Cu")
		(net "M_M_DQ<0>")
	)
	(segment
		(start 33.62452 -129.720594)
		(end 33.314386 -130.030728)
		(width 0.14224)
		(layer "In11.Cu")
		(net "M_M_DQ<0>")
	)
	(segment
		(start 68.051172 -87.194136)
		(end 68.018406 -87.194136)
		(width 0.0889)
		(layer "In11.Cu")
		(net "M_M_DQ<0>")
	)
	(segment
		(start 33.576768 -126.6952)
		(end 33.128204 -127.143764)
		(width 0.14224)
		(layer "In11.Cu")
		(net "M_M_DQ<0>")
	)
	(segment
		(start 32.73552 -150.450296)
		(end 33.099502 -150.814278)
		(width 0.14224)
		(layer "In11.Cu")
		(net "M_M_DQ<0>")
	)
	(segment
		(start 70.622922 -85.70849)
		(end 70.590156 -85.70849)
		(width 0.0889)
		(layer "In11.Cu")
		(net "M_M_DQ<0>")
	)
	(segment
		(start 74.067416 -83.72729)
		(end 74.024236 -83.72729)
		(width 0.0889)
		(layer "In11.Cu")
		(net "M_M_DQ<0>")
	)
	(segment
		(start 33.57372 -141.5034)
		(end 33.525968 -141.551152)
		(width 0.14224)
		(layer "In11.Cu")
		(net "M_M_DQ<0>")
	)
	(segment
		(start 51.679348 -97.883218)
		(end 51.679348 -98.534474)
		(width 0.14224)
		(layer "In11.Cu")
		(net "M_M_DQ<0>")
	)
	(segment
		(start 62.585854 -86.976712)
		(end 51.679348 -97.883218)
		(width 0.14224)
		(layer "In11.Cu")
		(net "M_M_DQ<0>")
	)
	(segment
		(start 75.784456 -84.71789)
		(end 75.75169 -84.71789)
		(width 0.0889)
		(layer "In11.Cu")
		(net "M_M_DQ<0>")
	)
	(segment
		(start 33.525968 -141.551152)
		(end 33.525968 -143.6116)
		(width 0.14224)
		(layer "In11.Cu")
		(net "M_M_DQ<0>")
	)
	(segment
		(start 76.639166 -85.212936)
		(end 76.6064 -85.212936)
		(width 0.0889)
		(layer "In11.Cu")
		(net "M_M_DQ<0>")
	)
	(segment
		(start 33.525968 -148.4376)
		(end 33.58642 -148.498052)
		(width 0.14224)
		(layer "In11.Cu")
		(net "M_M_DQ<0>")
	)
	(segment
		(start 64.465454 -87.208614)
		(end 64.233552 -86.976712)
		(width 0.0889)
		(layer "In11.Cu")
		(net "M_M_DQ<0>")
	)
	(segment
		(start 48.550322 -101.6635)
		(end 43.0657 -101.6635)
		(width 0.14224)
		(layer "In11.Cu")
		(net "M_M_DQ<0>")
	)
	(segment
		(start 33.57372 -143.659352)
		(end 33.57372 -144.085818)
		(width 0.14224)
		(layer "In11.Cu")
		(net "M_M_DQ<0>")
	)
	(segment
		(start 43.0657 -101.6635)
		(end 41.679368 -103.049832)
		(width 0.14224)
		(layer "In11.Cu")
		(net "M_M_DQ<0>")
	)
	(segment
		(start 33.652968 -131.899152)
		(end 33.525968 -132.026152)
		(width 0.14224)
		(layer "In11.Cu")
		(net "M_M_DQ<0>")
	)
	(segment
		(start 71.485252 -85.212936)
		(end 71.452486 -85.212936)
		(width 0.0889)
		(layer "In11.Cu")
		(net "M_M_DQ<0>")
	)
	(segment
		(start 33.29432 -145.564606)
		(end 33.58642 -145.856706)
		(width 0.14224)
		(layer "In11.Cu")
		(net "M_M_DQ<0>")
	)
	(segment
		(start 33.29432 -144.365218)
		(end 33.29432 -145.564606)
		(width 0.14224)
		(layer "In11.Cu")
		(net "M_M_DQ<0>")
	)
	(segment
		(start 39.342568 -107.874054)
		(end 34.872422 -112.3442)
		(width 0.14224)
		(layer "In11.Cu")
		(net "M_M_DQ<0>")
	)
	(segment
		(start 33.58642 -146.2024)
		(end 33.525968 -146.262852)
		(width 0.14224)
		(layer "In11.Cu")
		(net "M_M_DQ<0>")
	)
	(segment
		(start 33.28162 -134.776718)
		(end 33.28162 -135.950452)
		(width 0.14224)
		(layer "In11.Cu")
		(net "M_M_DQ<0>")
	)
	(segment
		(start 33.525968 -133.9088)
		(end 33.62452 -134.007352)
		(width 0.14224)
		(layer "In11.Cu")
		(net "M_M_DQ<0>")
	)
	(segment
		(start 66.242692 -87.208614)
		(end 64.465454 -87.208614)
		(width 0.0889)
		(layer "In11.Cu")
		(net "M_M_DQ<0>")
	)
	(segment
		(start 33.62452 -138.858752)
		(end 33.62452 -139.320778)
		(width 0.14224)
		(layer "In11.Cu")
		(net "M_M_DQ<0>")
	)
	(segment
		(start 34.872422 -112.3442)
		(end 34.362898 -112.3442)
		(width 0.14224)
		(layer "In11.Cu")
		(net "M_M_DQ<0>")
	)
	(segment
		(start 33.62452 -136.5758)
		(end 33.525968 -136.674352)
		(width 0.14224)
		(layer "In11.Cu")
		(net "M_M_DQ<0>")
	)
	(segment
		(start 51.679348 -98.534474)
		(end 48.550322 -101.6635)
		(width 0.14224)
		(layer "In11.Cu")
		(net "M_M_DQ<0>")
	)
	(segment
		(start 33.57372 -141.035278)
		(end 33.57372 -141.5034)
		(width 0.14224)
		(layer "In11.Cu")
		(net "M_M_DQ<0>")
	)
	(segment
		(start 33.525968 -143.6116)
		(end 33.57372 -143.659352)
		(width 0.14224)
		(layer "In11.Cu")
		(net "M_M_DQ<0>")
	)
	(segment
		(start 73.202292 -84.222336)
		(end 73.169526 -84.222336)
		(width 0.0889)
		(layer "In11.Cu")
		(net "M_M_DQ<0>")
	)
	(segment
		(start 77.150468 -85.538056)
		(end 77.133196 -85.508338)
		(width 0.0889)
		(layer "In11.Cu")
		(net "M_M_DQ<0>")
	)
	(segment
		(start 34.362898 -112.3442)
		(end 33.576768 -113.13033)
		(width 0.14224)
		(layer "In11.Cu")
		(net "M_M_DQ<0>")
	)
	(segment
		(start 33.314386 -131.208272)
		(end 33.652968 -131.546854)
		(width 0.14224)
		(layer "In11.Cu")
		(net "M_M_DQ<0>")
	)
	(segment
		(start 41.679368 -104.978454)
		(end 39.342568 -107.315254)
		(width 0.14224)
		(layer "In11.Cu")
		(net "M_M_DQ<0>")
	)
	(segment
		(start 33.28162 -140.743178)
		(end 33.57372 -141.035278)
		(width 0.14224)
		(layer "In11.Cu")
		(net "M_M_DQ<0>")
	)
	(segment
		(start 33.28162 -139.663678)
		(end 33.28162 -140.743178)
		(width 0.14224)
		(layer "In11.Cu")
		(net "M_M_DQ<0>")
	)
	(segment
		(start 33.58642 -145.856706)
		(end 33.58642 -146.2024)
		(width 0.14224)
		(layer "In11.Cu")
		(net "M_M_DQ<0>")
	)
	(segment
		(start 33.128204 -127.143764)
		(end 33.128204 -128.888236)
		(width 0.14224)
		(layer "In11.Cu")
		(net "M_M_DQ<0>")
	)
	(segment
		(start 33.525968 -138.7602)
		(end 33.62452 -138.858752)
		(width 0.14224)
		(layer "In11.Cu")
		(net "M_M_DQ<0>")
	)
	(segment
		(start 33.62452 -134.007352)
		(end 33.62452 -134.433818)
		(width 0.14224)
		(layer "In11.Cu")
		(net "M_M_DQ<0>")
	)
	(arc
		(start 77.133196 -85.508338)
		(mid 76.924588 -85.296406)
		(end 76.639166 -85.212936)
		(width 0.0889)
		(layer "In11.Cu")
		(net "M_M_DQ<0>")
	)
	(arc
		(start 70.590156 -85.70849)
		(mid 70.306939 -85.792771)
		(end 70.099936 -86.003638)
		(width 0.0889)
		(layer "In11.Cu")
		(net "M_M_DQ<0>")
	)
	(arc
		(start 67.524376 -87.489538)
		(mid 67.382693 -87.633342)
		(end 67.188842 -87.68969)
		(width 0.0889)
		(layer "In11.Cu")
		(net "M_M_DQ<0>")
	)
	(arc
		(start 73.169526 -84.222336)
		(mid 72.884102 -84.305803)
		(end 72.675496 -84.517738)
		(width 0.0889)
		(layer "In11.Cu")
		(net "M_M_DQ<0>")
	)
	(arc
		(start 72.675496 -84.517738)
		(mid 72.533813 -84.661542)
		(end 72.339962 -84.71789)
		(width 0.0889)
		(layer "In11.Cu")
		(net "M_M_DQ<0>")
	)
	(arc
		(start 71.816976 -85.013038)
		(mid 71.676897 -85.155774)
		(end 71.485252 -85.212936)
		(width 0.0889)
		(layer "In11.Cu")
		(net "M_M_DQ<0>")
	)
	(arc
		(start 71.452486 -85.212936)
		(mid 71.167062 -85.296403)
		(end 70.958456 -85.508338)
		(width 0.0889)
		(layer "In11.Cu")
		(net "M_M_DQ<0>")
	)
	(arc
		(start 68.382896 -86.994238)
		(mid 68.242817 -87.136974)
		(end 68.051172 -87.194136)
		(width 0.0889)
		(layer "In11.Cu")
		(net "M_M_DQ<0>")
	)
	(arc
		(start 74.557636 -84.022438)
		(mid 74.350632 -83.811574)
		(end 74.067416 -83.72729)
		(width 0.0889)
		(layer "In11.Cu")
		(net "M_M_DQ<0>")
	)
	(arc
		(start 70.099936 -86.003638)
		(mid 69.959857 -86.146374)
		(end 69.768212 -86.203536)
		(width 0.0889)
		(layer "In11.Cu")
		(net "M_M_DQ<0>")
	)
	(arc
		(start 73.534016 -84.022438)
		(mid 73.393937 -84.165174)
		(end 73.202292 -84.222336)
		(width 0.0889)
		(layer "In11.Cu")
		(net "M_M_DQ<0>")
	)
	(arc
		(start 70.958456 -85.508338)
		(mid 70.816773 -85.652142)
		(end 70.622922 -85.70849)
		(width 0.0889)
		(layer "In11.Cu")
		(net "M_M_DQ<0>")
	)
	(arc
		(start 68.873116 -86.69909)
		(mid 68.589899 -86.783371)
		(end 68.382896 -86.994238)
		(width 0.0889)
		(layer "In11.Cu")
		(net "M_M_DQ<0>")
	)
	(arc
		(start 72.307196 -84.71789)
		(mid 72.023979 -84.802171)
		(end 71.816976 -85.013038)
		(width 0.0889)
		(layer "In11.Cu")
		(net "M_M_DQ<0>")
	)
	(arc
		(start 76.274676 -85.013038)
		(mid 76.067672 -84.802174)
		(end 75.784456 -84.71789)
		(width 0.0889)
		(layer "In11.Cu")
		(net "M_M_DQ<0>")
	)
	(arc
		(start 76.6064 -85.212936)
		(mid 76.414758 -85.15577)
		(end 76.274676 -85.013038)
		(width 0.0889)
		(layer "In11.Cu")
		(net "M_M_DQ<0>")
	)
	(arc
		(start 75.75169 -84.71789)
		(mid 75.55784 -84.66154)
		(end 75.416156 -84.517738)
		(width 0.0889)
		(layer "In11.Cu")
		(net "M_M_DQ<0>")
	)
	(arc
		(start 75.416156 -84.517738)
		(mid 75.207548 -84.305806)
		(end 74.922126 -84.222336)
		(width 0.0889)
		(layer "In11.Cu")
		(net "M_M_DQ<0>")
	)
	(arc
		(start 69.241416 -86.498938)
		(mid 69.099733 -86.642742)
		(end 68.905882 -86.69909)
		(width 0.0889)
		(layer "In11.Cu")
		(net "M_M_DQ<0>")
	)
	(arc
		(start 69.735446 -86.203536)
		(mid 69.450022 -86.287003)
		(end 69.241416 -86.498938)
		(width 0.0889)
		(layer "In11.Cu")
		(net "M_M_DQ<0>")
	)
	(arc
		(start 74.88936 -84.222336)
		(mid 74.697718 -84.16517)
		(end 74.557636 -84.022438)
		(width 0.0889)
		(layer "In11.Cu")
		(net "M_M_DQ<0>")
	)
	(arc
		(start 68.018406 -87.194136)
		(mid 67.732982 -87.277603)
		(end 67.524376 -87.489538)
		(width 0.0889)
		(layer "In11.Cu")
		(net "M_M_DQ<0>")
	)
	(arc
		(start 74.024236 -83.72729)
		(mid 73.741019 -83.811571)
		(end 73.534016 -84.022438)
		(width 0.0889)
		(layer "In11.Cu")
		(net "M_M_DQ<0>")
	)
	(segment
		(start 102.947724 -93.72854)
		(end 102.376224 -93.72854)
		(width 0.1016)
		(layer "F.Cu")
		(net "M_M_CS_N<7>")
	)
	(via
		(at 102.376224 -93.72854)
		(size 0.508)
		(drill 0.254)
		(layers "F.Cu" "B.Cu")
		(net "M_M_CS_N<7>")
	)
	(via
		(at 112.99952 -148.773388)
		(size 0.4572)
		(drill 0.2032)
		(layers "F.Cu" "B.Cu")
		(net "M_M_CS_N<7>")
	)
	(segment
		(start 112.99952 -147.478496)
		(end 112.99952 -148.773388)
		(width 0.1651)
		(layer "B.Cu")
		(net "M_M_CS_N<7>")
	)
	(segment
		(start 112.519968 -129.8702)
		(end 112.697768 -130.048)
		(width 0.14224)
		(layer "In2.Cu")
		(net "M_M_CS_N<7>")
	)
	(segment
		(start 103.985568 -119.996966)
		(end 107.640374 -123.651772)
		(width 0.14224)
		(layer "In2.Cu")
		(net "M_M_CS_N<7>")
	)
	(segment
		(start 107.640374 -124.671074)
		(end 108.48594 -125.51664)
		(width 0.14224)
		(layer "In2.Cu")
		(net "M_M_CS_N<7>")
	)
	(segment
		(start 109.173772 -126.204472)
		(end 111.586518 -128.617218)
		(width 0.14224)
		(layer "In2.Cu")
		(net "M_M_CS_N<7>")
	)
	(segment
		(start 104.264968 -100.66274)
		(end 104.264968 -102.874064)
		(width 0.14224)
		(layer "In2.Cu")
		(net "M_M_CS_N<7>")
	)
	(segment
		(start 103.350568 -96.7994)
		(end 103.909368 -97.3582)
		(width 0.14224)
		(layer "In2.Cu")
		(net "M_M_CS_N<7>")
	)
	(segment
		(start 108.48594 -125.51664)
		(end 108.704888 -125.51664)
		(width 0.14224)
		(layer "In2.Cu")
		(net "M_M_CS_N<7>")
	)
	(segment
		(start 102.376224 -93.72854)
		(end 103.350568 -94.702884)
		(width 0.14224)
		(layer "In2.Cu")
		(net "M_M_CS_N<7>")
	)
	(segment
		(start 112.519968 -129.325116)
		(end 112.519968 -129.8702)
		(width 0.14224)
		(layer "In2.Cu")
		(net "M_M_CS_N<7>")
	)
	(segment
		(start 112.469168 -131.1148)
		(end 112.697768 -131.3434)
		(width 0.14224)
		(layer "In2.Cu")
		(net "M_M_CS_N<7>")
	)
	(segment
		(start 103.350568 -94.702884)
		(end 103.350568 -96.7994)
		(width 0.14224)
		(layer "In2.Cu")
		(net "M_M_CS_N<7>")
	)
	(segment
		(start 112.697768 -133.6294)
		(end 112.584992 -133.742176)
		(width 0.14224)
		(layer "In2.Cu")
		(net "M_M_CS_N<7>")
	)
	(segment
		(start 108.704888 -125.51664)
		(end 108.94187 -125.279658)
		(width 0.14224)
		(layer "In2.Cu")
		(net "M_M_CS_N<7>")
	)
	(segment
		(start 112.99952 -146.885152)
		(end 112.99952 -148.773388)
		(width 0.14224)
		(layer "In2.Cu")
		(net "M_M_CS_N<7>")
	)
	(segment
		(start 104.264968 -102.874064)
		(end 103.985568 -103.153464)
		(width 0.14224)
		(layer "In2.Cu")
		(net "M_M_CS_N<7>")
	)
	(segment
		(start 112.697768 -130.048)
		(end 112.697768 -130.5306)
		(width 0.14224)
		(layer "In2.Cu")
		(net "M_M_CS_N<7>")
	)
	(segment
		(start 108.94187 -125.279658)
		(end 109.160818 -125.279658)
		(width 0.14224)
		(layer "In2.Cu")
		(net "M_M_CS_N<7>")
	)
	(segment
		(start 109.160818 -125.279658)
		(end 109.410754 -125.529594)
		(width 0.14224)
		(layer "In2.Cu")
		(net "M_M_CS_N<7>")
	)
	(segment
		(start 111.586518 -128.617218)
		(end 111.81207 -128.617218)
		(width 0.14224)
		(layer "In2.Cu")
		(net "M_M_CS_N<7>")
	)
	(segment
		(start 109.173772 -125.985524)
		(end 109.173772 -126.204472)
		(width 0.14224)
		(layer "In2.Cu")
		(net "M_M_CS_N<7>")
	)
	(segment
		(start 109.410754 -125.748542)
		(end 109.173772 -125.985524)
		(width 0.14224)
		(layer "In2.Cu")
		(net "M_M_CS_N<7>")
	)
	(segment
		(start 112.697768 -130.5306)
		(end 112.469168 -130.7592)
		(width 0.14224)
		(layer "In2.Cu")
		(net "M_M_CS_N<7>")
	)
	(segment
		(start 103.985568 -103.153464)
		(end 103.985568 -119.996966)
		(width 0.14224)
		(layer "In2.Cu")
		(net "M_M_CS_N<7>")
	)
	(segment
		(start 103.909368 -100.30714)
		(end 104.264968 -100.66274)
		(width 0.14224)
		(layer "In2.Cu")
		(net "M_M_CS_N<7>")
	)
	(segment
		(start 111.81207 -128.617218)
		(end 112.519968 -129.325116)
		(width 0.14224)
		(layer "In2.Cu")
		(net "M_M_CS_N<7>")
	)
	(segment
		(start 109.410754 -125.529594)
		(end 109.410754 -125.748542)
		(width 0.14224)
		(layer "In2.Cu")
		(net "M_M_CS_N<7>")
	)
	(segment
		(start 112.697768 -131.3434)
		(end 112.697768 -133.6294)
		(width 0.14224)
		(layer "In2.Cu")
		(net "M_M_CS_N<7>")
	)
	(segment
		(start 112.584992 -133.742176)
		(end 112.584992 -146.470624)
		(width 0.14224)
		(layer "In2.Cu")
		(net "M_M_CS_N<7>")
	)
	(segment
		(start 107.640374 -123.651772)
		(end 107.640374 -124.671074)
		(width 0.14224)
		(layer "In2.Cu")
		(net "M_M_CS_N<7>")
	)
	(segment
		(start 112.584992 -146.470624)
		(end 112.99952 -146.885152)
		(width 0.14224)
		(layer "In2.Cu")
		(net "M_M_CS_N<7>")
	)
	(segment
		(start 103.909368 -97.3582)
		(end 103.909368 -100.30714)
		(width 0.14224)
		(layer "In2.Cu")
		(net "M_M_CS_N<7>")
	)
	(segment
		(start 112.469168 -130.7592)
		(end 112.469168 -131.1148)
		(width 0.14224)
		(layer "In2.Cu")
		(net "M_M_CS_N<7>")
	)
	(segment
		(start 102.947724 -94.718886)
		(end 102.376224 -94.718886)
		(width 0.1016)
		(layer "F.Cu")
		(net "M_M_CS_N<6>")
	)
	(via
		(at 102.376224 -94.718886)
		(size 0.508)
		(drill 0.254)
		(layers "F.Cu" "B.Cu")
		(net "M_M_CS_N<6>")
	)
	(via
		(at 112.99952 -150.789386)
		(size 0.4572)
		(drill 0.2032)
		(layers "F.Cu" "B.Cu")
		(net "M_M_CS_N<6>")
	)
	(segment
		(start 112.99952 -152.078436)
		(end 112.99952 -150.789386)
		(width 0.1651)
		(layer "B.Cu")
		(net "M_M_CS_N<6>")
	)
	(segment
		(start 111.757968 -130.7084)
		(end 111.554768 -130.5052)
		(width 0.14224)
		(layer "In2.Cu")
		(net "M_M_CS_N<6>")
	)
	(segment
		(start 107.132374 -124.88164)
		(end 107.132374 -123.862338)
		(width 0.14224)
		(layer "In2.Cu")
		(net "M_M_CS_N<6>")
	)
	(segment
		(start 111.714026 -140.240258)
		(end 111.71174 -140.237972)
		(width 0.14224)
		(layer "In2.Cu")
		(net "M_M_CS_N<6>")
	)
	(segment
		(start 111.71174 -141.588744)
		(end 111.714026 -141.586458)
		(width 0.14224)
		(layer "In2.Cu")
		(net "M_M_CS_N<6>")
	)
	(segment
		(start 103.477568 -120.207532)
		(end 103.477568 -102.9462)
		(width 0.14224)
		(layer "In2.Cu")
		(net "M_M_CS_N<6>")
	)
	(segment
		(start 107.132374 -123.862338)
		(end 103.477568 -120.207532)
		(width 0.14224)
		(layer "In2.Cu")
		(net "M_M_CS_N<6>")
	)
	(segment
		(start 103.756968 -102.6668)
		(end 103.756968 -100.8634)
		(width 0.14224)
		(layer "In2.Cu")
		(net "M_M_CS_N<6>")
	)
	(segment
		(start 111.71174 -140.237972)
		(end 111.71174 -134.091172)
		(width 0.14224)
		(layer "In2.Cu")
		(net "M_M_CS_N<6>")
	)
	(segment
		(start 111.36757 -129.116836)
		(end 107.132374 -124.88164)
		(width 0.14224)
		(layer "In2.Cu")
		(net "M_M_CS_N<6>")
	)
	(segment
		(start 103.375968 -100.4824)
		(end 103.375968 -97.6122)
		(width 0.14224)
		(layer "In2.Cu")
		(net "M_M_CS_N<6>")
	)
	(segment
		(start 111.656368 -134.0358)
		(end 111.656368 -131.318)
		(width 0.14224)
		(layer "In2.Cu")
		(net "M_M_CS_N<6>")
	)
	(segment
		(start 112.584992 -149.086824)
		(end 112.584992 -147.334224)
		(width 0.14224)
		(layer "In2.Cu")
		(net "M_M_CS_N<6>")
	)
	(segment
		(start 103.477568 -102.9462)
		(end 103.756968 -102.6668)
		(width 0.14224)
		(layer "In2.Cu")
		(net "M_M_CS_N<6>")
	)
	(segment
		(start 111.757968 -131.2164)
		(end 111.757968 -130.7084)
		(width 0.14224)
		(layer "In2.Cu")
		(net "M_M_CS_N<6>")
	)
	(segment
		(start 111.71174 -146.460972)
		(end 111.71174 -141.588744)
		(width 0.14224)
		(layer "In2.Cu")
		(net "M_M_CS_N<6>")
	)
	(segment
		(start 111.71174 -134.091172)
		(end 111.656368 -134.0358)
		(width 0.14224)
		(layer "In2.Cu")
		(net "M_M_CS_N<6>")
	)
	(segment
		(start 112.99952 -150.789386)
		(end 112.99952 -150.104856)
		(width 0.14224)
		(layer "In2.Cu")
		(net "M_M_CS_N<6>")
	)
	(segment
		(start 111.554768 -130.048)
		(end 111.756698 -129.84607)
		(width 0.14224)
		(layer "In2.Cu")
		(net "M_M_CS_N<6>")
	)
	(segment
		(start 103.756968 -100.8634)
		(end 103.375968 -100.4824)
		(width 0.14224)
		(layer "In2.Cu")
		(net "M_M_CS_N<6>")
	)
	(segment
		(start 103.375968 -97.6122)
		(end 102.867968 -97.1042)
		(width 0.14224)
		(layer "In2.Cu")
		(net "M_M_CS_N<6>")
	)
	(segment
		(start 112.723168 -149.225)
		(end 112.584992 -149.086824)
		(width 0.14224)
		(layer "In2.Cu")
		(net "M_M_CS_N<6>")
	)
	(segment
		(start 112.723168 -149.828504)
		(end 112.723168 -149.225)
		(width 0.14224)
		(layer "In2.Cu")
		(net "M_M_CS_N<6>")
	)
	(segment
		(start 111.554768 -130.5052)
		(end 111.554768 -130.048)
		(width 0.14224)
		(layer "In2.Cu")
		(net "M_M_CS_N<6>")
	)
	(segment
		(start 111.494316 -129.116836)
		(end 111.36757 -129.116836)
		(width 0.14224)
		(layer "In2.Cu")
		(net "M_M_CS_N<6>")
	)
	(segment
		(start 111.714026 -141.586458)
		(end 111.714026 -140.240258)
		(width 0.14224)
		(layer "In2.Cu")
		(net "M_M_CS_N<6>")
	)
	(segment
		(start 111.756698 -129.379218)
		(end 111.494316 -129.116836)
		(width 0.14224)
		(layer "In2.Cu")
		(net "M_M_CS_N<6>")
	)
	(segment
		(start 111.756698 -129.84607)
		(end 111.756698 -129.379218)
		(width 0.14224)
		(layer "In2.Cu")
		(net "M_M_CS_N<6>")
	)
	(segment
		(start 112.584992 -147.334224)
		(end 111.71174 -146.460972)
		(width 0.14224)
		(layer "In2.Cu")
		(net "M_M_CS_N<6>")
	)
	(segment
		(start 112.99952 -150.104856)
		(end 112.723168 -149.828504)
		(width 0.14224)
		(layer "In2.Cu")
		(net "M_M_CS_N<6>")
	)
	(segment
		(start 111.656368 -131.318)
		(end 111.757968 -131.2164)
		(width 0.14224)
		(layer "In2.Cu")
		(net "M_M_CS_N<6>")
	)
	(segment
		(start 102.867968 -97.1042)
		(end 102.867968 -95.21063)
		(width 0.14224)
		(layer "In2.Cu")
		(net "M_M_CS_N<6>")
	)
	(segment
		(start 102.867968 -95.21063)
		(end 102.376224 -94.718886)
		(width 0.14224)
		(layer "In2.Cu")
		(net "M_M_CS_N<6>")
	)
	(segment
		(start 100.372164 -93.23324)
		(end 99.800664 -93.23324)
		(width 0.1016)
		(layer "F.Cu")
		(net "M_M_CS_N<5>")
	)
	(via
		(at 109.599476 -150.785068)
		(size 0.4572)
		(drill 0.2032)
		(layers "F.Cu" "B.Cu")
		(net "M_M_CS_N<5>")
	)
	(via
		(at 99.800664 -93.23324)
		(size 0.508)
		(drill 0.254)
		(layers "F.Cu" "B.Cu")
		(net "M_M_CS_N<5>")
	)
	(segment
		(start 109.599476 -152.078436)
		(end 109.599476 -150.785068)
		(width 0.1651)
		(layer "B.Cu")
		(net "M_M_CS_N<5>")
	)
	(segment
		(start 103.072438 -123.577858)
		(end 102.804214 -123.577858)
		(width 0.14224)
		(layer "In2.Cu")
		(net "M_M_CS_N<5>")
	)
	(segment
		(start 103.95077 -123.84913)
		(end 103.95077 -123.561602)
		(width 0.14224)
		(layer "In2.Cu")
		(net "M_M_CS_N<5>")
	)
	(segment
		(start 109.421168 -149.352)
		(end 109.163358 -149.09419)
		(width 0.14224)
		(layer "In2.Cu")
		(net "M_M_CS_N<5>")
	)
	(segment
		(start 101.710744 -122.347736)
		(end 101.420422 -122.057414)
		(width 0.14224)
		(layer "In2.Cu")
		(net "M_M_CS_N<5>")
	)
	(segment
		(start 100.147374 -95.414338)
		(end 100.1522 -95.405702)
		(width 0.0889)
		(layer "In2.Cu")
		(net "M_M_CS_N<5>")
	)
	(segment
		(start 101.420168 -103.091488)
		(end 100.607368 -102.278688)
		(width 0.0889)
		(layer "In2.Cu")
		(net "M_M_CS_N<5>")
	)
	(segment
		(start 108.201968 -130.048)
		(end 108.379768 -129.8702)
		(width 0.14224)
		(layer "In2.Cu")
		(net "M_M_CS_N<5>")
	)
	(segment
		(start 100.141024 -98.396806)
		(end 100.147374 -98.386138)
		(width 0.0889)
		(layer "In2.Cu")
		(net "M_M_CS_N<5>")
	)
	(segment
		(start 108.379768 -129.8702)
		(end 108.379768 -129.02184)
		(width 0.14224)
		(layer "In2.Cu")
		(net "M_M_CS_N<5>")
	)
	(segment
		(start 101.420422 -122.057414)
		(end 101.420422 -121.02465)
		(width 0.14224)
		(layer "In2.Cu")
		(net "M_M_CS_N<5>")
	)
	(segment
		(start 102.003352 -122.347736)
		(end 101.710744 -122.347736)
		(width 0.14224)
		(layer "In2.Cu")
		(net "M_M_CS_N<5>")
	)
	(segment
		(start 108.338112 -146.592544)
		(end 108.338112 -141.893544)
		(width 0.14224)
		(layer "In2.Cu")
		(net "M_M_CS_N<5>")
	)
	(segment
		(start 108.334556 -140.201396)
		(end 108.334556 -134.690612)
		(width 0.14224)
		(layer "In2.Cu")
		(net "M_M_CS_N<5>")
	)
	(segment
		(start 103.638096 -124.161804)
		(end 103.95077 -123.84913)
		(width 0.14224)
		(layer "In2.Cu")
		(net "M_M_CS_N<5>")
	)
	(segment
		(start 100.141024 -96.415606)
		(end 100.147374 -96.404938)
		(width 0.0889)
		(layer "In2.Cu")
		(net "M_M_CS_N<5>")
	)
	(segment
		(start 100.147374 -94.023688)
		(end 100.141024 -94.01302)
		(width 0.0889)
		(layer "In2.Cu")
		(net "M_M_CS_N<5>")
	)
	(segment
		(start 101.420168 -121.024396)
		(end 101.420168 -103.406194)
		(width 0.14224)
		(layer "In2.Cu")
		(net "M_M_CS_N<5>")
	)
	(segment
		(start 102.479094 -123.021598)
		(end 102.813104 -122.687588)
		(width 0.14224)
		(layer "In2.Cu")
		(net "M_M_CS_N<5>")
	)
	(segment
		(start 109.163358 -149.09419)
		(end 109.163358 -147.41779)
		(width 0.14224)
		(layer "In2.Cu")
		(net "M_M_CS_N<5>")
	)
	(segment
		(start 109.599476 -150.104856)
		(end 109.421168 -149.926548)
		(width 0.14224)
		(layer "In2.Cu")
		(net "M_M_CS_N<5>")
	)
	(segment
		(start 108.338112 -141.893544)
		(end 108.31576 -141.871192)
		(width 0.14224)
		(layer "In2.Cu")
		(net "M_M_CS_N<5>")
	)
	(segment
		(start 100.147374 -97.395538)
		(end 100.1522 -97.386902)
		(width 0.0889)
		(layer "In2.Cu")
		(net "M_M_CS_N<5>")
	)
	(segment
		(start 108.31576 -140.220192)
		(end 108.334556 -140.201396)
		(width 0.14224)
		(layer "In2.Cu")
		(net "M_M_CS_N<5>")
	)
	(segment
		(start 102.813104 -122.687588)
		(end 102.813104 -122.41022)
		(width 0.14224)
		(layer "In2.Cu")
		(net "M_M_CS_N<5>")
	)
	(segment
		(start 108.342176 -134.682992)
		(end 108.342176 -132.474208)
		(width 0.14224)
		(layer "In2.Cu")
		(net "M_M_CS_N<5>")
	)
	(segment
		(start 108.31576 -141.871192)
		(end 108.31576 -140.220192)
		(width 0.14224)
		(layer "In2.Cu")
		(net "M_M_CS_N<5>")
	)
	(segment
		(start 100.141024 -97.406206)
		(end 100.147374 -97.395538)
		(width 0.0889)
		(layer "In2.Cu")
		(net "M_M_CS_N<5>")
	)
	(segment
		(start 100.147374 -96.404938)
		(end 100.1522 -96.396302)
		(width 0.0889)
		(layer "In2.Cu")
		(net "M_M_CS_N<5>")
	)
	(segment
		(start 102.511098 -122.108214)
		(end 102.242874 -122.108214)
		(width 0.14224)
		(layer "In2.Cu")
		(net "M_M_CS_N<5>")
	)
	(segment
		(start 103.393494 -123.256802)
		(end 103.072438 -123.577858)
		(width 0.14224)
		(layer "In2.Cu")
		(net "M_M_CS_N<5>")
	)
	(segment
		(start 102.813104 -122.41022)
		(end 102.511098 -122.108214)
		(width 0.14224)
		(layer "In2.Cu")
		(net "M_M_CS_N<5>")
	)
	(segment
		(start 108.379768 -129.02184)
		(end 104.85374 -125.495812)
		(width 0.14224)
		(layer "In2.Cu")
		(net "M_M_CS_N<5>")
	)
	(segment
		(start 101.420422 -121.02465)
		(end 101.420168 -121.024396)
		(width 0.14224)
		(layer "In2.Cu")
		(net "M_M_CS_N<5>")
	)
	(segment
		(start 108.201968 -130.5052)
		(end 108.201968 -130.048)
		(width 0.14224)
		(layer "In2.Cu")
		(net "M_M_CS_N<5>")
	)
	(segment
		(start 104.55529 -124.394214)
		(end 104.211374 -124.73813)
		(width 0.14224)
		(layer "In2.Cu")
		(net "M_M_CS_N<5>")
	)
	(segment
		(start 104.783382 -124.394214)
		(end 104.55529 -124.394214)
		(width 0.14224)
		(layer "In2.Cu")
		(net "M_M_CS_N<5>")
	)
	(segment
		(start 109.163358 -147.41779)
		(end 108.338112 -146.592544)
		(width 0.14224)
		(layer "In2.Cu")
		(net "M_M_CS_N<5>")
	)
	(segment
		(start 100.104194 -93.93174)
		(end 99.800664 -93.23324)
		(width 0.0889)
		(layer "In2.Cu")
		(net "M_M_CS_N<5>")
	)
	(segment
		(start 100.141024 -95.425006)
		(end 100.147374 -95.414338)
		(width 0.0889)
		(layer "In2.Cu")
		(net "M_M_CS_N<5>")
	)
	(segment
		(start 102.479094 -123.252738)
		(end 102.479094 -123.021598)
		(width 0.14224)
		(layer "In2.Cu")
		(net "M_M_CS_N<5>")
	)
	(segment
		(start 108.342176 -132.474208)
		(end 108.227368 -132.3594)
		(width 0.14224)
		(layer "In2.Cu")
		(net "M_M_CS_N<5>")
	)
	(segment
		(start 108.334556 -134.690612)
		(end 108.342176 -134.682992)
		(width 0.14224)
		(layer "In2.Cu")
		(net "M_M_CS_N<5>")
	)
	(segment
		(start 102.804214 -123.577858)
		(end 102.479094 -123.252738)
		(width 0.14224)
		(layer "In2.Cu")
		(net "M_M_CS_N<5>")
	)
	(segment
		(start 100.607368 -99.540822)
		(end 100.289614 -99.223068)
		(width 0.0889)
		(layer "In2.Cu")
		(net "M_M_CS_N<5>")
	)
	(segment
		(start 103.95077 -123.561602)
		(end 103.64597 -123.256802)
		(width 0.14224)
		(layer "In2.Cu")
		(net "M_M_CS_N<5>")
	)
	(segment
		(start 109.421168 -149.926548)
		(end 109.421168 -149.352)
		(width 0.14224)
		(layer "In2.Cu")
		(net "M_M_CS_N<5>")
	)
	(segment
		(start 108.227368 -131.3688)
		(end 108.379768 -131.2164)
		(width 0.14224)
		(layer "In2.Cu")
		(net "M_M_CS_N<5>")
	)
	(segment
		(start 100.147374 -98.386138)
		(end 100.1522 -98.377502)
		(width 0.0889)
		(layer "In2.Cu")
		(net "M_M_CS_N<5>")
	)
	(segment
		(start 105.100374 -124.998734)
		(end 105.100374 -124.711206)
		(width 0.14224)
		(layer "In2.Cu")
		(net "M_M_CS_N<5>")
	)
	(segment
		(start 103.638096 -124.385578)
		(end 103.638096 -124.161804)
		(width 0.14224)
		(layer "In2.Cu")
		(net "M_M_CS_N<5>")
	)
	(segment
		(start 104.85374 -125.495812)
		(end 104.85374 -125.245368)
		(width 0.14224)
		(layer "In2.Cu")
		(net "M_M_CS_N<5>")
	)
	(segment
		(start 103.64597 -123.256802)
		(end 103.393494 -123.256802)
		(width 0.14224)
		(layer "In2.Cu")
		(net "M_M_CS_N<5>")
	)
	(segment
		(start 104.85374 -125.245368)
		(end 105.100374 -124.998734)
		(width 0.14224)
		(layer "In2.Cu")
		(net "M_M_CS_N<5>")
	)
	(segment
		(start 100.289614 -99.223068)
		(end 100.147374 -98.976688)
		(width 0.0889)
		(layer "In2.Cu")
		(net "M_M_CS_N<5>")
	)
	(segment
		(start 104.211374 -124.73813)
		(end 103.990648 -124.73813)
		(width 0.14224)
		(layer "In2.Cu")
		(net "M_M_CS_N<5>")
	)
	(segment
		(start 108.227368 -132.3594)
		(end 108.227368 -131.3688)
		(width 0.14224)
		(layer "In2.Cu")
		(net "M_M_CS_N<5>")
	)
	(segment
		(start 105.100374 -124.711206)
		(end 104.783382 -124.394214)
		(width 0.14224)
		(layer "In2.Cu")
		(net "M_M_CS_N<5>")
	)
	(segment
		(start 102.242874 -122.108214)
		(end 102.003352 -122.347736)
		(width 0.14224)
		(layer "In2.Cu")
		(net "M_M_CS_N<5>")
	)
	(segment
		(start 109.599476 -150.785068)
		(end 109.599476 -150.104856)
		(width 0.14224)
		(layer "In2.Cu")
		(net "M_M_CS_N<5>")
	)
	(segment
		(start 103.990648 -124.73813)
		(end 103.638096 -124.385578)
		(width 0.14224)
		(layer "In2.Cu")
		(net "M_M_CS_N<5>")
	)
	(segment
		(start 108.379768 -130.683)
		(end 108.201968 -130.5052)
		(width 0.14224)
		(layer "In2.Cu")
		(net "M_M_CS_N<5>")
	)
	(segment
		(start 101.420168 -103.406194)
		(end 101.420168 -103.091488)
		(width 0.0889)
		(layer "In2.Cu")
		(net "M_M_CS_N<5>")
	)
	(segment
		(start 108.379768 -131.2164)
		(end 108.379768 -130.683)
		(width 0.14224)
		(layer "In2.Cu")
		(net "M_M_CS_N<5>")
	)
	(segment
		(start 100.607368 -102.278688)
		(end 100.607368 -99.540822)
		(width 0.0889)
		(layer "In2.Cu")
		(net "M_M_CS_N<5>")
	)
	(arc
		(start 100.147374 -96.004888)
		(mid 100.068152 -95.71577)
		(end 100.141024 -95.425006)
		(width 0.0889)
		(layer "In2.Cu")
		(net "M_M_CS_N<5>")
	)
	(arc
		(start 100.1522 -97.386902)
		(mid 100.200955 -97.19055)
		(end 100.147374 -96.995488)
		(width 0.0889)
		(layer "In2.Cu")
		(net "M_M_CS_N<5>")
	)
	(arc
		(start 100.147374 -95.014288)
		(mid 100.068243 -94.718886)
		(end 100.147374 -94.423484)
		(width 0.0889)
		(layer "In2.Cu")
		(net "M_M_CS_N<5>")
	)
	(arc
		(start 100.1522 -98.377502)
		(mid 100.200955 -98.18115)
		(end 100.147374 -97.986088)
		(width 0.0889)
		(layer "In2.Cu")
		(net "M_M_CS_N<5>")
	)
	(arc
		(start 100.141024 -94.01302)
		(mid 100.121068 -93.973078)
		(end 100.104194 -93.93174)
		(width 0.0889)
		(layer "In2.Cu")
		(net "M_M_CS_N<5>")
	)
	(arc
		(start 100.147374 -94.423484)
		(mid 100.200873 -94.223586)
		(end 100.147374 -94.023688)
		(width 0.0889)
		(layer "In2.Cu")
		(net "M_M_CS_N<5>")
	)
	(arc
		(start 100.147374 -97.986088)
		(mid 100.068152 -97.69697)
		(end 100.141024 -97.406206)
		(width 0.0889)
		(layer "In2.Cu")
		(net "M_M_CS_N<5>")
	)
	(arc
		(start 100.147374 -98.976688)
		(mid 100.068152 -98.68757)
		(end 100.141024 -98.396806)
		(width 0.0889)
		(layer "In2.Cu")
		(net "M_M_CS_N<5>")
	)
	(arc
		(start 100.1522 -96.396302)
		(mid 100.200955 -96.19995)
		(end 100.147374 -96.004888)
		(width 0.0889)
		(layer "In2.Cu")
		(net "M_M_CS_N<5>")
	)
	(arc
		(start 100.147374 -96.995488)
		(mid 100.068152 -96.70637)
		(end 100.141024 -96.415606)
		(width 0.0889)
		(layer "In2.Cu")
		(net "M_M_CS_N<5>")
	)
	(arc
		(start 100.1522 -95.405702)
		(mid 100.200955 -95.20935)
		(end 100.147374 -95.014288)
		(width 0.0889)
		(layer "In2.Cu")
		(net "M_M_CS_N<5>")
	)
	(segment
		(start 97.796858 -91.747086)
		(end 97.225358 -91.747086)
		(width 0.1016)
		(layer "F.Cu")
		(net "M_M_CS_N<4>")
	)
	(via
		(at 105.349802 -150.788878)
		(size 0.4572)
		(drill 0.2032)
		(layers "F.Cu" "B.Cu")
		(net "M_M_CS_N<4>")
	)
	(via
		(at 97.225358 -91.747086)
		(size 0.508)
		(drill 0.254)
		(layers "F.Cu" "B.Cu")
		(net "M_M_CS_N<4>")
	)
	(segment
		(start 105.349548 -152.078436)
		(end 105.349548 -150.789132)
		(width 0.1651)
		(layer "B.Cu")
		(net "M_M_CS_N<4>")
	)
	(segment
		(start 105.349548 -150.789132)
		(end 105.349802 -150.788878)
		(width 0.1651)
		(layer "B.Cu")
		(net "M_M_CS_N<4>")
	)
	(segment
		(start 97.743518 -94.01302)
		(end 97.737168 -94.023688)
		(width 0.0889)
		(layer "In2.Cu")
		(net "M_M_CS_N<4>")
	)
	(segment
		(start 105.349802 -149.992334)
		(end 105.349802 -150.788878)
		(width 0.14224)
		(layer "In2.Cu")
		(net "M_M_CS_N<4>")
	)
	(segment
		(start 104.927146 -148.084286)
		(end 104.927146 -149.569678)
		(width 0.14224)
		(layer "In2.Cu")
		(net "M_M_CS_N<4>")
	)
	(segment
		(start 104.087422 -138.607546)
		(end 104.087422 -139.522454)
		(width 0.14224)
		(layer "In2.Cu")
		(net "M_M_CS_N<4>")
	)
	(segment
		(start 104.087422 -139.522454)
		(end 104.112568 -139.5476)
		(width 0.14224)
		(layer "In2.Cu")
		(net "M_M_CS_N<4>")
	)
	(segment
		(start 97.68967 -92.586302)
		(end 97.68967 -93.16339)
		(width 0.0889)
		(layer "In2.Cu")
		(net "M_M_CS_N<4>")
	)
	(segment
		(start 97.225358 -91.747086)
		(end 97.225358 -92.12199)
		(width 0.0889)
		(layer "In2.Cu")
		(net "M_M_CS_N<4>")
	)
	(segment
		(start 98.854768 -103.078534)
		(end 98.854768 -123.08967)
		(width 0.14224)
		(layer "In2.Cu")
		(net "M_M_CS_N<4>")
	)
	(segment
		(start 101.521768 -125.75667)
		(end 101.521768 -126.891034)
		(width 0.14224)
		(layer "In2.Cu")
		(net "M_M_CS_N<4>")
	)
	(segment
		(start 97.225358 -92.12199)
		(end 97.68967 -92.586302)
		(width 0.0889)
		(layer "In2.Cu")
		(net "M_M_CS_N<4>")
	)
	(segment
		(start 97.732342 -96.396302)
		(end 97.737168 -96.404938)
		(width 0.0889)
		(layer "In2.Cu")
		(net "M_M_CS_N<4>")
	)
	(segment
		(start 97.737168 -97.395538)
		(end 97.743518 -97.406206)
		(width 0.0889)
		(layer "In2.Cu")
		(net "M_M_CS_N<4>")
	)
	(segment
		(start 104.087422 -136.895586)
		(end 104.188768 -136.996932)
		(width 0.14224)
		(layer "In2.Cu")
		(net "M_M_CS_N<4>")
	)
	(segment
		(start 97.660968 -99.5934)
		(end 97.659952 -99.594416)
		(width 0.0889)
		(layer "In2.Cu")
		(net "M_M_CS_N<4>")
	)
	(segment
		(start 104.214168 -130.4544)
		(end 104.010968 -130.6576)
		(width 0.14224)
		(layer "In2.Cu")
		(net "M_M_CS_N<4>")
	)
	(segment
		(start 97.732342 -93.424502)
		(end 97.737168 -93.433138)
		(width 0.0889)
		(layer "In2.Cu")
		(net "M_M_CS_N<4>")
	)
	(segment
		(start 97.659952 -99.594416)
		(end 97.659952 -100.34016)
		(width 0.0889)
		(layer "In2.Cu")
		(net "M_M_CS_N<4>")
	)
	(segment
		(start 98.854768 -102.861364)
		(end 98.854768 -103.078534)
		(width 0.0889)
		(layer "In2.Cu")
		(net "M_M_CS_N<4>")
	)
	(segment
		(start 97.732342 -95.405702)
		(end 97.737168 -95.414338)
		(width 0.0889)
		(layer "In2.Cu")
		(net "M_M_CS_N<4>")
	)
	(segment
		(start 101.521768 -126.891034)
		(end 103.960168 -129.329434)
		(width 0.14224)
		(layer "In2.Cu")
		(net "M_M_CS_N<4>")
	)
	(segment
		(start 104.091232 -144.403064)
		(end 104.15143 -144.463262)
		(width 0.14224)
		(layer "In2.Cu")
		(net "M_M_CS_N<4>")
	)
	(segment
		(start 98.854768 -123.08967)
		(end 101.521768 -125.75667)
		(width 0.14224)
		(layer "In2.Cu")
		(net "M_M_CS_N<4>")
	)
	(segment
		(start 104.137968 -134.8232)
		(end 104.137968 -135.680704)
		(width 0.14224)
		(layer "In2.Cu")
		(net "M_M_CS_N<4>")
	)
	(segment
		(start 97.732342 -98.377502)
		(end 97.737168 -98.386138)
		(width 0.0889)
		(layer "In2.Cu")
		(net "M_M_CS_N<4>")
	)
	(segment
		(start 104.112568 -139.5476)
		(end 104.112568 -140.512546)
		(width 0.14224)
		(layer "In2.Cu")
		(net "M_M_CS_N<4>")
	)
	(segment
		(start 104.087422 -135.73125)
		(end 104.087422 -136.895586)
		(width 0.14224)
		(layer "In2.Cu")
		(net "M_M_CS_N<4>")
	)
	(segment
		(start 104.214168 -130.048)
		(end 104.214168 -130.4544)
		(width 0.14224)
		(layer "In2.Cu")
		(net "M_M_CS_N<4>")
	)
	(segment
		(start 104.065324 -140.55979)
		(end 104.065324 -143.226028)
		(width 0.14224)
		(layer "In2.Cu")
		(net "M_M_CS_N<4>")
	)
	(segment
		(start 97.737168 -98.386138)
		(end 97.743518 -98.396806)
		(width 0.0889)
		(layer "In2.Cu")
		(net "M_M_CS_N<4>")
	)
	(segment
		(start 97.737168 -95.414338)
		(end 97.743518 -95.425006)
		(width 0.0889)
		(layer "In2.Cu")
		(net "M_M_CS_N<4>")
	)
	(segment
		(start 104.112568 -140.512546)
		(end 104.065324 -140.55979)
		(width 0.14224)
		(layer "In2.Cu")
		(net "M_M_CS_N<4>")
	)
	(segment
		(start 97.732342 -97.386902)
		(end 97.737168 -97.395538)
		(width 0.0889)
		(layer "In2.Cu")
		(net "M_M_CS_N<4>")
	)
	(segment
		(start 104.010968 -130.6576)
		(end 104.010968 -131.1148)
		(width 0.14224)
		(layer "In2.Cu")
		(net "M_M_CS_N<4>")
	)
	(segment
		(start 104.188768 -136.996932)
		(end 104.188768 -138.5062)
		(width 0.14224)
		(layer "In2.Cu")
		(net "M_M_CS_N<4>")
	)
	(segment
		(start 104.065324 -143.226028)
		(end 104.091232 -143.251936)
		(width 0.14224)
		(layer "In2.Cu")
		(net "M_M_CS_N<4>")
	)
	(segment
		(start 103.960168 -129.794)
		(end 104.214168 -130.048)
		(width 0.14224)
		(layer "In2.Cu")
		(net "M_M_CS_N<4>")
	)
	(segment
		(start 104.137968 -135.680704)
		(end 104.087422 -135.73125)
		(width 0.14224)
		(layer "In2.Cu")
		(net "M_M_CS_N<4>")
	)
	(segment
		(start 104.15143 -144.463262)
		(end 104.15143 -145.726658)
		(width 0.14224)
		(layer "In2.Cu")
		(net "M_M_CS_N<4>")
	)
	(segment
		(start 104.010968 -131.1148)
		(end 104.091232 -131.195064)
		(width 0.14224)
		(layer "In2.Cu")
		(net "M_M_CS_N<4>")
	)
	(segment
		(start 104.188768 -138.5062)
		(end 104.087422 -138.607546)
		(width 0.14224)
		(layer "In2.Cu")
		(net "M_M_CS_N<4>")
	)
	(segment
		(start 104.15143 -145.726658)
		(end 104.08412 -145.793968)
		(width 0.14224)
		(layer "In2.Cu")
		(net "M_M_CS_N<4>")
	)
	(segment
		(start 97.737168 -96.404938)
		(end 97.743518 -96.415606)
		(width 0.0889)
		(layer "In2.Cu")
		(net "M_M_CS_N<4>")
	)
	(segment
		(start 98.676968 -102.683564)
		(end 98.854768 -102.861364)
		(width 0.0889)
		(layer "In2.Cu")
		(net "M_M_CS_N<4>")
	)
	(segment
		(start 104.927146 -149.569678)
		(end 105.349802 -149.992334)
		(width 0.14224)
		(layer "In2.Cu")
		(net "M_M_CS_N<4>")
	)
	(segment
		(start 104.08412 -145.793968)
		(end 104.08412 -147.24126)
		(width 0.14224)
		(layer "In2.Cu")
		(net "M_M_CS_N<4>")
	)
	(segment
		(start 104.08412 -147.24126)
		(end 104.927146 -148.084286)
		(width 0.14224)
		(layer "In2.Cu")
		(net "M_M_CS_N<4>")
	)
	(segment
		(start 104.091232 -143.251936)
		(end 104.091232 -144.403064)
		(width 0.14224)
		(layer "In2.Cu")
		(net "M_M_CS_N<4>")
	)
	(segment
		(start 104.091232 -134.776464)
		(end 104.137968 -134.8232)
		(width 0.14224)
		(layer "In2.Cu")
		(net "M_M_CS_N<4>")
	)
	(segment
		(start 104.091232 -131.195064)
		(end 104.091232 -134.776464)
		(width 0.14224)
		(layer "In2.Cu")
		(net "M_M_CS_N<4>")
	)
	(segment
		(start 98.676968 -101.357176)
		(end 98.676968 -102.683564)
		(width 0.0889)
		(layer "In2.Cu")
		(net "M_M_CS_N<4>")
	)
	(segment
		(start 103.960168 -129.329434)
		(end 103.960168 -129.794)
		(width 0.14224)
		(layer "In2.Cu")
		(net "M_M_CS_N<4>")
	)
	(segment
		(start 97.659952 -100.34016)
		(end 98.676968 -101.357176)
		(width 0.0889)
		(layer "In2.Cu")
		(net "M_M_CS_N<4>")
	)
	(arc
		(start 97.743518 -97.406206)
		(mid 97.816316 -97.696969)
		(end 97.737168 -97.986088)
		(width 0.0889)
		(layer "In2.Cu")
		(net "M_M_CS_N<4>")
	)
	(arc
		(start 97.737168 -94.423484)
		(mid 97.816299 -94.718886)
		(end 97.737168 -95.014288)
		(width 0.0889)
		(layer "In2.Cu")
		(net "M_M_CS_N<4>")
	)
	(arc
		(start 97.743518 -96.415606)
		(mid 97.816316 -96.706369)
		(end 97.737168 -96.995488)
		(width 0.0889)
		(layer "In2.Cu")
		(net "M_M_CS_N<4>")
	)
	(arc
		(start 97.743518 -95.425006)
		(mid 97.816316 -95.715769)
		(end 97.737168 -96.004888)
		(width 0.0889)
		(layer "In2.Cu")
		(net "M_M_CS_N<4>")
	)
	(arc
		(start 97.737168 -93.433138)
		(mid 97.81639 -93.722256)
		(end 97.743518 -94.01302)
		(width 0.0889)
		(layer "In2.Cu")
		(net "M_M_CS_N<4>")
	)
	(arc
		(start 97.737168 -96.004888)
		(mid 97.683698 -96.199951)
		(end 97.732342 -96.396302)
		(width 0.0889)
		(layer "In2.Cu")
		(net "M_M_CS_N<4>")
	)
	(arc
		(start 97.737168 -96.995488)
		(mid 97.683698 -97.190551)
		(end 97.732342 -97.386902)
		(width 0.0889)
		(layer "In2.Cu")
		(net "M_M_CS_N<4>")
	)
	(arc
		(start 97.737168 -94.023688)
		(mid 97.683669 -94.223586)
		(end 97.737168 -94.423484)
		(width 0.0889)
		(layer "In2.Cu")
		(net "M_M_CS_N<4>")
	)
	(arc
		(start 97.68967 -93.16339)
		(mid 97.688818 -93.297571)
		(end 97.732342 -93.424502)
		(width 0.0889)
		(layer "In2.Cu")
		(net "M_M_CS_N<4>")
	)
	(arc
		(start 97.737168 -98.976688)
		(mid 97.6364 -99.277303)
		(end 97.660968 -99.5934)
		(width 0.0889)
		(layer "In2.Cu")
		(net "M_M_CS_N<4>")
	)
	(arc
		(start 97.737168 -97.986088)
		(mid 97.683698 -98.181151)
		(end 97.732342 -98.377502)
		(width 0.0889)
		(layer "In2.Cu")
		(net "M_M_CS_N<4>")
	)
	(arc
		(start 97.737168 -95.014288)
		(mid 97.683698 -95.209351)
		(end 97.732342 -95.405702)
		(width 0.0889)
		(layer "In2.Cu")
		(net "M_M_CS_N<4>")
	)
	(arc
		(start 97.743518 -98.396806)
		(mid 97.816316 -98.687569)
		(end 97.737168 -98.976688)
		(width 0.0889)
		(layer "In2.Cu")
		(net "M_M_CS_N<4>")
	)
	(segment
		(start 102.089204 -92.24264)
		(end 101.517704 -92.24264)
		(width 0.1016)
		(layer "F.Cu")
		(net "M_M_CS_N<3>")
	)
	(segment
		(start 112.99952 -156.87294)
		(end 112.99952 -154.905456)
		(width 0.1651)
		(layer "F.Cu")
		(net "M_M_CS_N<3>")
	)
	(via
		(at 112.99952 -154.905456)
		(size 0.508)
		(drill 0.254)
		(layers "F.Cu" "B.Cu")
		(net "M_M_CS_N<3>")
	)
	(via
		(at 101.517704 -92.24264)
		(size 0.508)
		(drill 0.254)
		(layers "F.Cu" "B.Cu")
		(net "M_M_CS_N<3>")
	)
	(segment
		(start 101.813868 -92.538804)
		(end 101.813868 -92.8497)
		(width 0.14224)
		(layer "In2.Cu")
		(net "M_M_CS_N<3>")
	)
	(segment
		(start 113.510568 -131.3688)
		(end 113.40719 -131.472178)
		(width 0.14224)
		(layer "In2.Cu")
		(net "M_M_CS_N<3>")
	)
	(segment
		(start 102.207568 -93.2434)
		(end 102.664768 -93.2434)
		(width 0.14224)
		(layer "In2.Cu")
		(net "M_M_CS_N<3>")
	)
	(segment
		(start 112.99952 -154.257248)
		(end 112.99952 -154.905456)
		(width 0.14224)
		(layer "In2.Cu")
		(net "M_M_CS_N<3>")
	)
	(segment
		(start 104.493568 -103.364284)
		(end 104.493568 -119.7864)
		(width 0.14224)
		(layer "In2.Cu")
		(net "M_M_CS_N<3>")
	)
	(segment
		(start 113.336578 -144.98701)
		(end 113.41354 -145.063972)
		(width 0.14224)
		(layer "In2.Cu")
		(net "M_M_CS_N<3>")
	)
	(segment
		(start 113.459768 -135.509)
		(end 113.459768 -139.3698)
		(width 0.14224)
		(layer "In2.Cu")
		(net "M_M_CS_N<3>")
	)
	(segment
		(start 104.214168 -96.6724)
		(end 104.595168 -96.6724)
		(width 0.14224)
		(layer "In2.Cu")
		(net "M_M_CS_N<3>")
	)
	(segment
		(start 103.858568 -96.3168)
		(end 104.214168 -96.6724)
		(width 0.14224)
		(layer "In2.Cu")
		(net "M_M_CS_N<3>")
	)
	(segment
		(start 102.664768 -93.2434)
		(end 103.858568 -94.4372)
		(width 0.14224)
		(layer "In2.Cu")
		(net "M_M_CS_N<3>")
	)
	(segment
		(start 113.472722 -128.765554)
		(end 113.472722 -129.806446)
		(width 0.14224)
		(layer "In2.Cu")
		(net "M_M_CS_N<3>")
	)
	(segment
		(start 113.40719 -135.456422)
		(end 113.459768 -135.509)
		(width 0.14224)
		(layer "In2.Cu")
		(net "M_M_CS_N<3>")
	)
	(segment
		(start 101.517704 -92.24264)
		(end 101.813868 -92.538804)
		(width 0.14224)
		(layer "In2.Cu")
		(net "M_M_CS_N<3>")
	)
	(segment
		(start 113.336578 -144.36979)
		(end 113.336578 -144.98701)
		(width 0.14224)
		(layer "In2.Cu")
		(net "M_M_CS_N<3>")
	)
	(segment
		(start 104.493568 -119.7864)
		(end 113.472722 -128.765554)
		(width 0.14224)
		(layer "In2.Cu")
		(net "M_M_CS_N<3>")
	)
	(segment
		(start 113.41354 -145.063972)
		(end 113.41354 -146.384772)
		(width 0.14224)
		(layer "In2.Cu")
		(net "M_M_CS_N<3>")
	)
	(segment
		(start 113.485168 -153.0604)
		(end 113.561368 -153.1366)
		(width 0.14224)
		(layer "In2.Cu")
		(net "M_M_CS_N<3>")
	)
	(segment
		(start 113.47323 -146.444462)
		(end 113.47323 -148.982938)
		(width 0.14224)
		(layer "In2.Cu")
		(net "M_M_CS_N<3>")
	)
	(segment
		(start 113.561368 -153.1366)
		(end 113.561368 -153.6954)
		(width 0.14224)
		(layer "In2.Cu")
		(net "M_M_CS_N<3>")
	)
	(segment
		(start 113.40719 -131.472178)
		(end 113.40719 -135.456422)
		(width 0.14224)
		(layer "In2.Cu")
		(net "M_M_CS_N<3>")
	)
	(segment
		(start 113.459768 -139.3698)
		(end 113.411508 -139.41806)
		(width 0.14224)
		(layer "In2.Cu")
		(net "M_M_CS_N<3>")
	)
	(segment
		(start 113.510568 -130.7338)
		(end 113.510568 -131.3688)
		(width 0.14224)
		(layer "In2.Cu")
		(net "M_M_CS_N<3>")
	)
	(segment
		(start 113.231168 -149.225)
		(end 113.231168 -149.606)
		(width 0.14224)
		(layer "In2.Cu")
		(net "M_M_CS_N<3>")
	)
	(segment
		(start 103.858568 -94.4372)
		(end 103.858568 -96.3168)
		(width 0.14224)
		(layer "In2.Cu")
		(net "M_M_CS_N<3>")
	)
	(segment
		(start 113.472722 -129.806446)
		(end 113.275364 -130.003804)
		(width 0.14224)
		(layer "In2.Cu")
		(net "M_M_CS_N<3>")
	)
	(segment
		(start 113.47323 -148.982938)
		(end 113.231168 -149.225)
		(width 0.14224)
		(layer "In2.Cu")
		(net "M_M_CS_N<3>")
	)
	(segment
		(start 113.561368 -153.6954)
		(end 112.99952 -154.257248)
		(width 0.14224)
		(layer "In2.Cu")
		(net "M_M_CS_N<3>")
	)
	(segment
		(start 113.485168 -149.86)
		(end 113.485168 -153.0604)
		(width 0.14224)
		(layer "In2.Cu")
		(net "M_M_CS_N<3>")
	)
	(segment
		(start 113.411508 -144.29486)
		(end 113.336578 -144.36979)
		(width 0.14224)
		(layer "In2.Cu")
		(net "M_M_CS_N<3>")
	)
	(segment
		(start 113.41354 -146.384772)
		(end 113.47323 -146.444462)
		(width 0.14224)
		(layer "In2.Cu")
		(net "M_M_CS_N<3>")
	)
	(segment
		(start 113.275364 -130.498596)
		(end 113.510568 -130.7338)
		(width 0.14224)
		(layer "In2.Cu")
		(net "M_M_CS_N<3>")
	)
	(segment
		(start 101.813868 -92.8497)
		(end 102.207568 -93.2434)
		(width 0.14224)
		(layer "In2.Cu")
		(net "M_M_CS_N<3>")
	)
	(segment
		(start 113.275364 -130.003804)
		(end 113.275364 -130.498596)
		(width 0.14224)
		(layer "In2.Cu")
		(net "M_M_CS_N<3>")
	)
	(segment
		(start 113.231168 -149.606)
		(end 113.485168 -149.86)
		(width 0.14224)
		(layer "In2.Cu")
		(net "M_M_CS_N<3>")
	)
	(segment
		(start 113.411508 -139.41806)
		(end 113.411508 -144.29486)
		(width 0.14224)
		(layer "In2.Cu")
		(net "M_M_CS_N<3>")
	)
	(segment
		(start 104.595168 -96.6724)
		(end 104.87279 -96.950022)
		(width 0.14224)
		(layer "In2.Cu")
		(net "M_M_CS_N<3>")
	)
	(segment
		(start 104.87279 -102.985062)
		(end 104.493568 -103.364284)
		(width 0.14224)
		(layer "In2.Cu")
		(net "M_M_CS_N<3>")
	)
	(segment
		(start 104.87279 -96.950022)
		(end 104.87279 -102.985062)
		(width 0.14224)
		(layer "In2.Cu")
		(net "M_M_CS_N<3>")
	)
	(segment
		(start 102.089204 -93.23324)
		(end 101.517704 -93.23324)
		(width 0.1016)
		(layer "F.Cu")
		(net "M_M_CS_N<2>")
	)
	(segment
		(start 112.99952 -152.273)
		(end 112.99952 -153.571956)
		(width 0.1651)
		(layer "F.Cu")
		(net "M_M_CS_N<2>")
	)
	(via
		(at 101.517704 -93.23324)
		(size 0.508)
		(drill 0.254)
		(layers "F.Cu" "B.Cu")
		(net "M_M_CS_N<2>")
	)
	(via
		(at 112.99952 -153.571956)
		(size 0.508)
		(drill 0.254)
		(layers "F.Cu" "B.Cu")
		(net "M_M_CS_N<2>")
	)
	(segment
		(start 101.902768 -93.9038)
		(end 102.055168 -94.0562)
		(width 0.14224)
		(layer "In2.Cu")
		(net "M_M_CS_N<2>")
	)
	(segment
		(start 110.818168 -129.286)
		(end 110.818168 -129.921)
		(width 0.14224)
		(layer "In2.Cu")
		(net "M_M_CS_N<2>")
	)
	(segment
		(start 102.969568 -120.418098)
		(end 106.624374 -124.072904)
		(width 0.14224)
		(layer "In2.Cu")
		(net "M_M_CS_N<2>")
	)
	(segment
		(start 101.902768 -94.5388)
		(end 101.902768 -94.8944)
		(width 0.14224)
		(layer "In2.Cu")
		(net "M_M_CS_N<2>")
	)
	(segment
		(start 111.71555 -147.277582)
		(end 111.71555 -149.115018)
		(width 0.14224)
		(layer "In2.Cu")
		(net "M_M_CS_N<2>")
	)
	(segment
		(start 112.585246 -150.585678)
		(end 112.585246 -153.157682)
		(width 0.14224)
		(layer "In2.Cu")
		(net "M_M_CS_N<2>")
	)
	(segment
		(start 101.902768 -94.8944)
		(end 102.029768 -95.0214)
		(width 0.14224)
		(layer "In2.Cu")
		(net "M_M_CS_N<2>")
	)
	(segment
		(start 102.715568 -102.0064)
		(end 102.715568 -102.362)
		(width 0.14224)
		(layer "In2.Cu")
		(net "M_M_CS_N<2>")
	)
	(segment
		(start 101.902768 -95.9104)
		(end 102.004368 -96.012)
		(width 0.14224)
		(layer "In2.Cu")
		(net "M_M_CS_N<2>")
	)
	(segment
		(start 102.029768 -95.0214)
		(end 102.029768 -95.4024)
		(width 0.14224)
		(layer "In2.Cu")
		(net "M_M_CS_N<2>")
	)
	(segment
		(start 101.902768 -96.8756)
		(end 102.867968 -97.8408)
		(width 0.14224)
		(layer "In2.Cu")
		(net "M_M_CS_N<2>")
	)
	(segment
		(start 102.715568 -102.362)
		(end 102.969568 -102.616)
		(width 0.14224)
		(layer "In2.Cu")
		(net "M_M_CS_N<2>")
	)
	(segment
		(start 110.9091 -130.011932)
		(end 110.9091 -130.515868)
		(width 0.14224)
		(layer "In2.Cu")
		(net "M_M_CS_N<2>")
	)
	(segment
		(start 111.71555 -149.115018)
		(end 112.18545 -149.584918)
		(width 0.14224)
		(layer "In2.Cu")
		(net "M_M_CS_N<2>")
	)
	(segment
		(start 102.055168 -94.0562)
		(end 102.055168 -94.3864)
		(width 0.14224)
		(layer "In2.Cu")
		(net "M_M_CS_N<2>")
	)
	(segment
		(start 110.864396 -133.786372)
		(end 110.864396 -134.564628)
		(width 0.14224)
		(layer "In2.Cu")
		(net "M_M_CS_N<2>")
	)
	(segment
		(start 110.875826 -145.701258)
		(end 110.875826 -146.437858)
		(width 0.14224)
		(layer "In2.Cu")
		(net "M_M_CS_N<2>")
	)
	(segment
		(start 110.883192 -134.583424)
		(end 110.883192 -141.971776)
		(width 0.14224)
		(layer "In2.Cu")
		(net "M_M_CS_N<2>")
	)
	(segment
		(start 101.902768 -93.618304)
		(end 101.902768 -93.9038)
		(width 0.14224)
		(layer "In2.Cu")
		(net "M_M_CS_N<2>")
	)
	(segment
		(start 110.818168 -129.921)
		(end 110.9091 -130.011932)
		(width 0.14224)
		(layer "In2.Cu")
		(net "M_M_CS_N<2>")
	)
	(segment
		(start 112.585246 -153.157682)
		(end 112.99952 -153.571956)
		(width 0.14224)
		(layer "In2.Cu")
		(net "M_M_CS_N<2>")
	)
	(segment
		(start 110.883192 -141.971776)
		(end 110.861348 -141.99362)
		(width 0.14224)
		(layer "In2.Cu")
		(net "M_M_CS_N<2>")
	)
	(segment
		(start 101.902768 -95.5294)
		(end 101.902768 -95.9104)
		(width 0.14224)
		(layer "In2.Cu")
		(net "M_M_CS_N<2>")
	)
	(segment
		(start 102.029768 -95.4024)
		(end 101.902768 -95.5294)
		(width 0.14224)
		(layer "In2.Cu")
		(net "M_M_CS_N<2>")
	)
	(segment
		(start 110.861348 -145.68678)
		(end 110.875826 -145.701258)
		(width 0.14224)
		(layer "In2.Cu")
		(net "M_M_CS_N<2>")
	)
	(segment
		(start 102.867968 -101.854)
		(end 102.715568 -102.0064)
		(width 0.14224)
		(layer "In2.Cu")
		(net "M_M_CS_N<2>")
	)
	(segment
		(start 102.055168 -94.3864)
		(end 101.902768 -94.5388)
		(width 0.14224)
		(layer "In2.Cu")
		(net "M_M_CS_N<2>")
	)
	(segment
		(start 106.624374 -125.092206)
		(end 110.818168 -129.286)
		(width 0.14224)
		(layer "In2.Cu")
		(net "M_M_CS_N<2>")
	)
	(segment
		(start 102.867968 -97.8408)
		(end 102.867968 -101.854)
		(width 0.14224)
		(layer "In2.Cu")
		(net "M_M_CS_N<2>")
	)
	(segment
		(start 102.004368 -96.012)
		(end 102.004368 -96.4184)
		(width 0.14224)
		(layer "In2.Cu")
		(net "M_M_CS_N<2>")
	)
	(segment
		(start 110.875826 -146.437858)
		(end 111.71555 -147.277582)
		(width 0.14224)
		(layer "In2.Cu")
		(net "M_M_CS_N<2>")
	)
	(segment
		(start 112.18545 -150.185882)
		(end 112.585246 -150.585678)
		(width 0.14224)
		(layer "In2.Cu")
		(net "M_M_CS_N<2>")
	)
	(segment
		(start 112.18545 -149.584918)
		(end 112.18545 -150.185882)
		(width 0.14224)
		(layer "In2.Cu")
		(net "M_M_CS_N<2>")
	)
	(segment
		(start 102.004368 -96.4184)
		(end 101.902768 -96.52)
		(width 0.14224)
		(layer "In2.Cu")
		(net "M_M_CS_N<2>")
	)
	(segment
		(start 110.864396 -134.564628)
		(end 110.883192 -134.583424)
		(width 0.14224)
		(layer "In2.Cu")
		(net "M_M_CS_N<2>")
	)
	(segment
		(start 110.847886 -131.296918)
		(end 110.970314 -131.419346)
		(width 0.14224)
		(layer "In2.Cu")
		(net "M_M_CS_N<2>")
	)
	(segment
		(start 110.970314 -131.419346)
		(end 110.970314 -133.680454)
		(width 0.14224)
		(layer "In2.Cu")
		(net "M_M_CS_N<2>")
	)
	(segment
		(start 110.847886 -130.577082)
		(end 110.847886 -131.296918)
		(width 0.14224)
		(layer "In2.Cu")
		(net "M_M_CS_N<2>")
	)
	(segment
		(start 101.902768 -96.52)
		(end 101.902768 -96.8756)
		(width 0.14224)
		(layer "In2.Cu")
		(net "M_M_CS_N<2>")
	)
	(segment
		(start 102.969568 -102.616)
		(end 102.969568 -120.418098)
		(width 0.14224)
		(layer "In2.Cu")
		(net "M_M_CS_N<2>")
	)
	(segment
		(start 110.970314 -133.680454)
		(end 110.864396 -133.786372)
		(width 0.14224)
		(layer "In2.Cu")
		(net "M_M_CS_N<2>")
	)
	(segment
		(start 106.624374 -124.072904)
		(end 106.624374 -125.092206)
		(width 0.14224)
		(layer "In2.Cu")
		(net "M_M_CS_N<2>")
	)
	(segment
		(start 110.9091 -130.515868)
		(end 110.847886 -130.577082)
		(width 0.14224)
		(layer "In2.Cu")
		(net "M_M_CS_N<2>")
	)
	(segment
		(start 101.517704 -93.23324)
		(end 101.902768 -93.618304)
		(width 0.14224)
		(layer "In2.Cu")
		(net "M_M_CS_N<2>")
	)
	(segment
		(start 110.861348 -141.99362)
		(end 110.861348 -145.68678)
		(width 0.14224)
		(layer "In2.Cu")
		(net "M_M_CS_N<2>")
	)
	(segment
		(start 109.599476 -152.273)
		(end 109.599476 -153.542746)
		(width 0.1651)
		(layer "F.Cu")
		(net "M_M_CS_N<1>")
	)
	(segment
		(start 99.513898 -91.747086)
		(end 98.942398 -91.747086)
		(width 0.1016)
		(layer "F.Cu")
		(net "M_M_CS_N<1>")
	)
	(via
		(at 98.942398 -91.747086)
		(size 0.508)
		(drill 0.254)
		(layers "F.Cu" "B.Cu")
		(net "M_M_CS_N<1>")
	)
	(via
		(at 109.599476 -153.542746)
		(size 0.508)
		(drill 0.254)
		(layers "F.Cu" "B.Cu")
		(net "M_M_CS_N<1>")
	)
	(segment
		(start 99.454208 -98.976942)
		(end 99.44608 -98.991166)
		(width 0.0889)
		(layer "In2.Cu")
		(net "M_M_CS_N<1>")
	)
	(segment
		(start 107.46486 -134.746492)
		(end 107.46486 -139.470892)
		(width 0.14224)
		(layer "In2.Cu")
		(net "M_M_CS_N<1>")
	)
	(segment
		(start 100.378768 -100.210112)
		(end 100.378768 -102.438454)
		(width 0.0889)
		(layer "In2.Cu")
		(net "M_M_CS_N<1>")
	)
	(segment
		(start 99.454208 -95.414338)
		(end 99.463098 -95.429578)
		(width 0.0889)
		(layer "In2.Cu")
		(net "M_M_CS_N<1>")
	)
	(segment
		(start 107.457494 -143.517874)
		(end 107.457494 -144.340326)
		(width 0.14224)
		(layer "In2.Cu")
		(net "M_M_CS_N<1>")
	)
	(segment
		(start 107.617768 -133.5786)
		(end 107.457494 -133.738874)
		(width 0.14224)
		(layer "In2.Cu")
		(net "M_M_CS_N<1>")
	)
	(segment
		(start 99.437952 -92.413836)
		(end 99.463098 -92.457778)
		(width 0.0889)
		(layer "In2.Cu")
		(net "M_M_CS_N<1>")
	)
	(segment
		(start 109.189012 -153.132282)
		(end 109.599476 -153.542746)
		(width 0.14224)
		(layer "In2.Cu")
		(net "M_M_CS_N<1>")
	)
	(segment
		(start 99.454208 -96.404938)
		(end 99.463098 -96.420178)
		(width 0.0889)
		(layer "In2.Cu")
		(net "M_M_CS_N<1>")
	)
	(segment
		(start 99.460558 -94.01302)
		(end 99.454208 -94.023688)
		(width 0.0889)
		(layer "In2.Cu")
		(net "M_M_CS_N<1>")
	)
	(segment
		(start 99.454208 -94.423484)
		(end 99.460558 -94.434152)
		(width 0.0889)
		(layer "In2.Cu")
		(net "M_M_CS_N<1>")
	)
	(segment
		(start 107.46486 -139.470892)
		(end 107.479846 -139.485878)
		(width 0.14224)
		(layer "In2.Cu")
		(net "M_M_CS_N<1>")
	)
	(segment
		(start 107.461304 -146.655536)
		(end 108.338112 -147.532344)
		(width 0.14224)
		(layer "In2.Cu")
		(net "M_M_CS_N<1>")
	)
	(segment
		(start 107.461304 -144.344136)
		(end 107.461304 -146.655536)
		(width 0.14224)
		(layer "In2.Cu")
		(net "M_M_CS_N<1>")
	)
	(segment
		(start 107.479846 -143.495522)
		(end 107.457494 -143.517874)
		(width 0.14224)
		(layer "In2.Cu")
		(net "M_M_CS_N<1>")
	)
	(segment
		(start 98.942398 -91.747086)
		(end 99.437952 -92.413836)
		(width 0.0889)
		(layer "In2.Cu")
		(net "M_M_CS_N<1>")
	)
	(segment
		(start 107.457494 -133.738874)
		(end 107.457494 -134.739126)
		(width 0.14224)
		(layer "In2.Cu")
		(net "M_M_CS_N<1>")
	)
	(segment
		(start 107.450636 -130.646932)
		(end 107.450636 -131.303268)
		(width 0.14224)
		(layer "In2.Cu")
		(net "M_M_CS_N<1>")
	)
	(segment
		(start 107.617768 -131.4704)
		(end 107.617768 -133.5786)
		(width 0.14224)
		(layer "In2.Cu")
		(net "M_M_CS_N<1>")
	)
	(segment
		(start 107.479846 -139.485878)
		(end 107.479846 -143.495522)
		(width 0.14224)
		(layer "In2.Cu")
		(net "M_M_CS_N<1>")
	)
	(segment
		(start 99.843844 -99.675188)
		(end 100.378768 -100.210112)
		(width 0.0889)
		(layer "In2.Cu")
		(net "M_M_CS_N<1>")
	)
	(segment
		(start 107.457494 -144.340326)
		(end 107.461304 -144.344136)
		(width 0.14224)
		(layer "In2.Cu")
		(net "M_M_CS_N<1>")
	)
	(segment
		(start 100.912168 -103.334566)
		(end 100.912168 -122.272806)
		(width 0.14224)
		(layer "In2.Cu")
		(net "M_M_CS_N<1>")
	)
	(segment
		(start 107.522518 -129.95275)
		(end 107.522518 -130.57505)
		(width 0.14224)
		(layer "In2.Cu")
		(net "M_M_CS_N<1>")
	)
	(segment
		(start 107.389168 -129.8194)
		(end 107.522518 -129.95275)
		(width 0.14224)
		(layer "In2.Cu")
		(net "M_M_CS_N<1>")
	)
	(segment
		(start 108.338112 -147.532344)
		(end 108.338112 -149.742144)
		(width 0.14224)
		(layer "In2.Cu")
		(net "M_M_CS_N<1>")
	)
	(segment
		(start 109.189012 -150.593044)
		(end 109.189012 -153.132282)
		(width 0.14224)
		(layer "In2.Cu")
		(net "M_M_CS_N<1>")
	)
	(segment
		(start 100.378768 -102.438454)
		(end 100.912168 -102.971854)
		(width 0.0889)
		(layer "In2.Cu")
		(net "M_M_CS_N<1>")
	)
	(segment
		(start 107.450636 -131.303268)
		(end 107.617768 -131.4704)
		(width 0.14224)
		(layer "In2.Cu")
		(net "M_M_CS_N<1>")
	)
	(segment
		(start 108.338112 -149.742144)
		(end 109.189012 -150.593044)
		(width 0.14224)
		(layer "In2.Cu")
		(net "M_M_CS_N<1>")
	)
	(segment
		(start 99.454208 -98.386138)
		(end 99.463098 -98.401378)
		(width 0.0889)
		(layer "In2.Cu")
		(net "M_M_CS_N<1>")
	)
	(segment
		(start 107.389168 -128.749806)
		(end 107.389168 -129.8194)
		(width 0.14224)
		(layer "In2.Cu")
		(net "M_M_CS_N<1>")
	)
	(segment
		(start 107.457494 -134.739126)
		(end 107.46486 -134.746492)
		(width 0.14224)
		(layer "In2.Cu")
		(net "M_M_CS_N<1>")
	)
	(segment
		(start 100.912168 -102.971854)
		(end 100.912168 -103.334566)
		(width 0.0889)
		(layer "In2.Cu")
		(net "M_M_CS_N<1>")
	)
	(segment
		(start 107.522518 -130.57505)
		(end 107.450636 -130.646932)
		(width 0.14224)
		(layer "In2.Cu")
		(net "M_M_CS_N<1>")
	)
	(segment
		(start 100.912168 -122.272806)
		(end 107.389168 -128.749806)
		(width 0.14224)
		(layer "In2.Cu")
		(net "M_M_CS_N<1>")
	)
	(segment
		(start 99.454208 -97.395538)
		(end 99.463098 -97.410778)
		(width 0.0889)
		(layer "In2.Cu")
		(net "M_M_CS_N<1>")
	)
	(arc
		(start 99.463098 -96.420178)
		(mid 99.533495 -96.709129)
		(end 99.454208 -96.995742)
		(width 0.0889)
		(layer "In2.Cu")
		(net "M_M_CS_N<1>")
	)
	(arc
		(start 99.454208 -94.023688)
		(mid 99.400675 -94.223586)
		(end 99.454208 -94.423484)
		(width 0.0889)
		(layer "In2.Cu")
		(net "M_M_CS_N<1>")
	)
	(arc
		(start 99.454208 -95.014542)
		(mid 99.400675 -95.21444)
		(end 99.454208 -95.414338)
		(width 0.0889)
		(layer "In2.Cu")
		(net "M_M_CS_N<1>")
	)
	(arc
		(start 99.454208 -93.033342)
		(mid 99.400675 -93.23324)
		(end 99.454208 -93.433138)
		(width 0.0889)
		(layer "In2.Cu")
		(net "M_M_CS_N<1>")
	)
	(arc
		(start 99.460558 -94.434152)
		(mid 99.533478 -94.725169)
		(end 99.454208 -95.014542)
		(width 0.0889)
		(layer "In2.Cu")
		(net "M_M_CS_N<1>")
	)
	(arc
		(start 99.454208 -96.995742)
		(mid 99.400675 -97.19564)
		(end 99.454208 -97.395538)
		(width 0.0889)
		(layer "In2.Cu")
		(net "M_M_CS_N<1>")
	)
	(arc
		(start 99.454208 -97.986342)
		(mid 99.400675 -98.18624)
		(end 99.454208 -98.386138)
		(width 0.0889)
		(layer "In2.Cu")
		(net "M_M_CS_N<1>")
	)
	(arc
		(start 99.463098 -95.429578)
		(mid 99.533495 -95.718529)
		(end 99.454208 -96.005142)
		(width 0.0889)
		(layer "In2.Cu")
		(net "M_M_CS_N<1>")
	)
	(arc
		(start 99.463098 -98.401378)
		(mid 99.533495 -98.690329)
		(end 99.454208 -98.976942)
		(width 0.0889)
		(layer "In2.Cu")
		(net "M_M_CS_N<1>")
	)
	(arc
		(start 99.463098 -97.410778)
		(mid 99.533495 -97.699729)
		(end 99.454208 -97.986342)
		(width 0.0889)
		(layer "In2.Cu")
		(net "M_M_CS_N<1>")
	)
	(arc
		(start 99.454208 -96.005142)
		(mid 99.400675 -96.20504)
		(end 99.454208 -96.404938)
		(width 0.0889)
		(layer "In2.Cu")
		(net "M_M_CS_N<1>")
	)
	(arc
		(start 99.463098 -92.457778)
		(mid 99.533495 -92.746729)
		(end 99.454208 -93.033342)
		(width 0.0889)
		(layer "In2.Cu")
		(net "M_M_CS_N<1>")
	)
	(arc
		(start 99.44608 -98.991166)
		(mid 99.400493 -99.185079)
		(end 99.453954 -99.376992)
		(width 0.0889)
		(layer "In2.Cu")
		(net "M_M_CS_N<1>")
	)
	(arc
		(start 99.453954 -99.376992)
		(mid 99.619105 -99.56505)
		(end 99.843844 -99.675188)
		(width 0.0889)
		(layer "In2.Cu")
		(net "M_M_CS_N<1>")
	)
	(arc
		(start 99.454208 -93.433138)
		(mid 99.53343 -93.722256)
		(end 99.460558 -94.01302)
		(width 0.0889)
		(layer "In2.Cu")
		(net "M_M_CS_N<1>")
	)
	(segment
		(start 105.349548 -152.273)
		(end 105.349548 -154.251914)
		(width 0.1651)
		(layer "F.Cu")
		(net "M_M_CS_N<0>")
	)
	(segment
		(start 97.796858 -93.72854)
		(end 97.225358 -93.72854)
		(width 0.1016)
		(layer "F.Cu")
		(net "M_M_CS_N<0>")
	)
	(segment
		(start 105.349548 -154.251914)
		(end 105.349294 -154.252168)
		(width 0.1651)
		(layer "F.Cu")
		(net "M_M_CS_N<0>")
	)
	(via
		(at 97.225358 -93.72854)
		(size 0.508)
		(drill 0.254)
		(layers "F.Cu" "B.Cu")
		(net "M_M_CS_N<0>")
	)
	(via
		(at 105.349294 -154.252168)
		(size 0.508)
		(drill 0.254)
		(layers "F.Cu" "B.Cu")
		(net "M_M_CS_N<0>")
	)
	(segment
		(start 97.225358 -93.72854)
		(end 97.555558 -94.49054)
		(width 0.0889)
		(layer "In2.Cu")
		(net "M_M_CS_N<0>")
	)
	(segment
		(start 97.572068 -97.490788)
		(end 97.576894 -97.499424)
		(width 0.0889)
		(layer "In2.Cu")
		(net "M_M_CS_N<0>")
	)
	(segment
		(start 105.128568 -154.031442)
		(end 105.349294 -154.252168)
		(width 0.14224)
		(layer "In2.Cu")
		(net "M_M_CS_N<0>")
	)
	(segment
		(start 100.525326 -125.765814)
		(end 100.805742 -125.765814)
		(width 0.14224)
		(layer "In2.Cu")
		(net "M_M_CS_N<0>")
	)
	(segment
		(start 101.013768 -127.1016)
		(end 103.254556 -129.342388)
		(width 0.14224)
		(layer "In2.Cu")
		(net "M_M_CS_N<0>")
	)
	(segment
		(start 103.21163 -141.75867)
		(end 103.21163 -144.945862)
		(width 0.14224)
		(layer "In2.Cu")
		(net "M_M_CS_N<0>")
	)
	(segment
		(start 97.381568 -99.5426)
		(end 97.383092 -99.544124)
		(width 0.0889)
		(layer "In2.Cu")
		(net "M_M_CS_N<0>")
	)
	(segment
		(start 97.565718 -95.49892)
		(end 97.572068 -95.509588)
		(width 0.0889)
		(layer "In2.Cu")
		(net "M_M_CS_N<0>")
	)
	(segment
		(start 103.218234 -141.752066)
		(end 103.21163 -141.75867)
		(width 0.14224)
		(layer "In2.Cu")
		(net "M_M_CS_N<0>")
	)
	(segment
		(start 97.572068 -96.500188)
		(end 97.576894 -96.508824)
		(width 0.0889)
		(layer "In2.Cu")
		(net "M_M_CS_N<0>")
	)
	(segment
		(start 103.247698 -130.60553)
		(end 103.247698 -131.24307)
		(width 0.14224)
		(layer "In2.Cu")
		(net "M_M_CS_N<0>")
	)
	(segment
		(start 103.210614 -133.692646)
		(end 103.210614 -135.394446)
		(width 0.14224)
		(layer "In2.Cu")
		(net "M_M_CS_N<0>")
	)
	(segment
		(start 103.21417 -140.173202)
		(end 103.218234 -140.177266)
		(width 0.14224)
		(layer "In2.Cu")
		(net "M_M_CS_N<0>")
	)
	(segment
		(start 103.214424 -144.948656)
		(end 103.214424 -147.20316)
		(width 0.14224)
		(layer "In2.Cu")
		(net "M_M_CS_N<0>")
	)
	(segment
		(start 103.21417 -135.398002)
		(end 103.21417 -140.173202)
		(width 0.14224)
		(layer "In2.Cu")
		(net "M_M_CS_N<0>")
	)
	(segment
		(start 99.95027 -124.903738)
		(end 99.95027 -125.191266)
		(width 0.14224)
		(layer "In2.Cu")
		(net "M_M_CS_N<0>")
	)
	(segment
		(start 104.938322 -151.235918)
		(end 105.128568 -151.426164)
		(width 0.14224)
		(layer "In2.Cu")
		(net "M_M_CS_N<0>")
	)
	(segment
		(start 98.346768 -101.565456)
		(end 98.346768 -102.9208)
		(width 0.0889)
		(layer "In2.Cu")
		(net "M_M_CS_N<0>")
	)
	(segment
		(start 98.346768 -123.300236)
		(end 99.95027 -124.903738)
		(width 0.14224)
		(layer "In2.Cu")
		(net "M_M_CS_N<0>")
	)
	(segment
		(start 100.805742 -125.765814)
		(end 101.013768 -125.97384)
		(width 0.14224)
		(layer "In2.Cu")
		(net "M_M_CS_N<0>")
	)
	(segment
		(start 103.162862 -130.083306)
		(end 103.162862 -130.520694)
		(width 0.14224)
		(layer "In2.Cu")
		(net "M_M_CS_N<0>")
	)
	(segment
		(start 103.071168 -131.4196)
		(end 103.071168 -133.5532)
		(width 0.14224)
		(layer "In2.Cu")
		(net "M_M_CS_N<0>")
	)
	(segment
		(start 105.128568 -151.426164)
		(end 105.128568 -154.031442)
		(width 0.14224)
		(layer "In2.Cu")
		(net "M_M_CS_N<0>")
	)
	(segment
		(start 103.254556 -129.991612)
		(end 103.162862 -130.083306)
		(width 0.14224)
		(layer "In2.Cu")
		(net "M_M_CS_N<0>")
	)
	(segment
		(start 97.572068 -98.481388)
		(end 97.576894 -98.490024)
		(width 0.0889)
		(layer "In2.Cu")
		(net "M_M_CS_N<0>")
	)
	(segment
		(start 99.95027 -125.191266)
		(end 99.66452 -125.477016)
		(width 0.14224)
		(layer "In2.Cu")
		(net "M_M_CS_N<0>")
	)
	(segment
		(start 97.565718 -97.48012)
		(end 97.572068 -97.490788)
		(width 0.0889)
		(layer "In2.Cu")
		(net "M_M_CS_N<0>")
	)
	(segment
		(start 100.211128 -126.080012)
		(end 100.525326 -125.765814)
		(width 0.14224)
		(layer "In2.Cu")
		(net "M_M_CS_N<0>")
	)
	(segment
		(start 103.21163 -144.945862)
		(end 103.214424 -144.948656)
		(width 0.14224)
		(layer "In2.Cu")
		(net "M_M_CS_N<0>")
	)
	(segment
		(start 97.572068 -95.509588)
		(end 97.576894 -95.518224)
		(width 0.0889)
		(layer "In2.Cu")
		(net "M_M_CS_N<0>")
	)
	(segment
		(start 97.383092 -99.544124)
		(end 97.383092 -100.60178)
		(width 0.0889)
		(layer "In2.Cu")
		(net "M_M_CS_N<0>")
	)
	(segment
		(start 104.087422 -148.076158)
		(end 104.087422 -149.572218)
		(width 0.14224)
		(layer "In2.Cu")
		(net "M_M_CS_N<0>")
	)
	(segment
		(start 104.087422 -149.572218)
		(end 104.938322 -150.423118)
		(width 0.14224)
		(layer "In2.Cu")
		(net "M_M_CS_N<0>")
	)
	(segment
		(start 97.555558 -94.49054)
		(end 97.576894 -94.527624)
		(width 0.0889)
		(layer "In2.Cu")
		(net "M_M_CS_N<0>")
	)
	(segment
		(start 103.254556 -129.342388)
		(end 103.254556 -129.991612)
		(width 0.14224)
		(layer "In2.Cu")
		(net "M_M_CS_N<0>")
	)
	(segment
		(start 103.218234 -140.177266)
		(end 103.218234 -141.752066)
		(width 0.14224)
		(layer "In2.Cu")
		(net "M_M_CS_N<0>")
	)
	(segment
		(start 104.938322 -150.423118)
		(end 104.938322 -151.235918)
		(width 0.14224)
		(layer "In2.Cu")
		(net "M_M_CS_N<0>")
	)
	(segment
		(start 97.383092 -100.60178)
		(end 98.346768 -101.565456)
		(width 0.0889)
		(layer "In2.Cu")
		(net "M_M_CS_N<0>")
	)
	(segment
		(start 103.071168 -133.5532)
		(end 103.210614 -133.692646)
		(width 0.14224)
		(layer "In2.Cu")
		(net "M_M_CS_N<0>")
	)
	(segment
		(start 99.66452 -125.767592)
		(end 99.97694 -126.080012)
		(width 0.14224)
		(layer "In2.Cu")
		(net "M_M_CS_N<0>")
	)
	(segment
		(start 103.214424 -147.20316)
		(end 104.087422 -148.076158)
		(width 0.14224)
		(layer "In2.Cu")
		(net "M_M_CS_N<0>")
	)
	(segment
		(start 103.247698 -131.24307)
		(end 103.071168 -131.4196)
		(width 0.14224)
		(layer "In2.Cu")
		(net "M_M_CS_N<0>")
	)
	(segment
		(start 97.565718 -96.48952)
		(end 97.572068 -96.500188)
		(width 0.0889)
		(layer "In2.Cu")
		(net "M_M_CS_N<0>")
	)
	(segment
		(start 101.013768 -125.97384)
		(end 101.013768 -127.1016)
		(width 0.14224)
		(layer "In2.Cu")
		(net "M_M_CS_N<0>")
	)
	(segment
		(start 97.565718 -98.47072)
		(end 97.572068 -98.481388)
		(width 0.0889)
		(layer "In2.Cu")
		(net "M_M_CS_N<0>")
	)
	(segment
		(start 103.162862 -130.520694)
		(end 103.247698 -130.60553)
		(width 0.14224)
		(layer "In2.Cu")
		(net "M_M_CS_N<0>")
	)
	(segment
		(start 98.346768 -102.9208)
		(end 98.346768 -123.300236)
		(width 0.14224)
		(layer "In2.Cu")
		(net "M_M_CS_N<0>")
	)
	(segment
		(start 103.210614 -135.394446)
		(end 103.21417 -135.398002)
		(width 0.14224)
		(layer "In2.Cu")
		(net "M_M_CS_N<0>")
	)
	(segment
		(start 99.97694 -126.080012)
		(end 100.211128 -126.080012)
		(width 0.14224)
		(layer "In2.Cu")
		(net "M_M_CS_N<0>")
	)
	(segment
		(start 99.66452 -125.477016)
		(end 99.66452 -125.767592)
		(width 0.14224)
		(layer "In2.Cu")
		(net "M_M_CS_N<0>")
	)
	(arc
		(start 97.572068 -95.909638)
		(mid 97.492846 -96.198756)
		(end 97.565718 -96.48952)
		(width 0.0889)
		(layer "In2.Cu")
		(net "M_M_CS_N<0>")
	)
	(arc
		(start 97.576894 -95.518224)
		(mid 97.625649 -95.714576)
		(end 97.572068 -95.909638)
		(width 0.0889)
		(layer "In2.Cu")
		(net "M_M_CS_N<0>")
	)
	(arc
		(start 97.572068 -98.881438)
		(mid 97.436521 -99.200411)
		(end 97.381568 -99.5426)
		(width 0.0889)
		(layer "In2.Cu")
		(net "M_M_CS_N<0>")
	)
	(arc
		(start 97.576894 -96.508824)
		(mid 97.625649 -96.705176)
		(end 97.572068 -96.900238)
		(width 0.0889)
		(layer "In2.Cu")
		(net "M_M_CS_N<0>")
	)
	(arc
		(start 97.572068 -96.900238)
		(mid 97.492846 -97.189356)
		(end 97.565718 -97.48012)
		(width 0.0889)
		(layer "In2.Cu")
		(net "M_M_CS_N<0>")
	)
	(arc
		(start 97.576894 -97.499424)
		(mid 97.625649 -97.695776)
		(end 97.572068 -97.890838)
		(width 0.0889)
		(layer "In2.Cu")
		(net "M_M_CS_N<0>")
	)
	(arc
		(start 97.576894 -94.527624)
		(mid 97.625649 -94.723976)
		(end 97.572068 -94.919038)
		(width 0.0889)
		(layer "In2.Cu")
		(net "M_M_CS_N<0>")
	)
	(arc
		(start 97.572068 -97.890838)
		(mid 97.492846 -98.179956)
		(end 97.565718 -98.47072)
		(width 0.0889)
		(layer "In2.Cu")
		(net "M_M_CS_N<0>")
	)
	(arc
		(start 97.572068 -94.919038)
		(mid 97.492846 -95.208156)
		(end 97.565718 -95.49892)
		(width 0.0889)
		(layer "In2.Cu")
		(net "M_M_CS_N<0>")
	)
	(arc
		(start 97.576894 -98.490024)
		(mid 97.625649 -98.686376)
		(end 97.572068 -98.881438)
		(width 0.0889)
		(layer "In2.Cu")
		(net "M_M_CS_N<0>")
	)
	(segment
		(start 93.504258 -92.24264)
		(end 92.932758 -92.24264)
		(width 0.1016)
		(layer "F.Cu")
		(net "M_M_CLK_DP<3>")
	)
	(via
		(at 91.825572 -148.771356)
		(size 0.508)
		(drill 0.254)
		(layers "F.Cu" "B.Cu")
		(net "M_M_CLK_DP<3>")
	)
	(via
		(at 92.932758 -92.24264)
		(size 0.508)
		(drill 0.254)
		(layers "F.Cu" "B.Cu")
		(net "M_M_CLK_DP<3>")
	)
	(segment
		(start 91.749372 -148.695156)
		(end 91.825572 -148.771356)
		(width 0.1651)
		(layer "B.Cu")
		(net "M_M_CLK_DP<3>")
	)
	(segment
		(start 91.749372 -147.478496)
		(end 91.749372 -148.695156)
		(width 0.1651)
		(layer "B.Cu")
		(net "M_M_CLK_DP<3>")
	)
	(segment
		(start 93.444568 -96.500188)
		(end 93.439742 -96.508824)
		(width 0.0889)
		(layer "In2.Cu")
		(net "M_M_CLK_DP<3>")
	)
	(segment
		(start 93.444568 -94.518988)
		(end 93.439742 -94.527624)
		(width 0.0889)
		(layer "In2.Cu")
		(net "M_M_CLK_DP<3>")
	)
	(segment
		(start 94.841568 -132.87248)
		(end 95.21063 -133.241542)
		(width 0.14224)
		(layer "In2.Cu")
		(net "M_M_CLK_DP<3>")
	)
	(segment
		(start 93.723968 -100.254054)
		(end 93.723968 -102.026974)
		(width 0.0889)
		(layer "In2.Cu")
		(net "M_M_CLK_DP<3>")
	)
	(segment
		(start 93.38818 -99.918266)
		(end 93.723968 -100.254054)
		(width 0.0889)
		(layer "In2.Cu")
		(net "M_M_CLK_DP<3>")
	)
	(segment
		(start 94.615254 -149.97684)
		(end 92.494608 -149.97684)
		(width 0.14224)
		(layer "In2.Cu")
		(net "M_M_CLK_DP<3>")
	)
	(segment
		(start 95.705168 -139.496546)
		(end 95.705168 -145.0594)
		(width 0.14224)
		(layer "In2.Cu")
		(net "M_M_CLK_DP<3>")
	)
	(segment
		(start 93.450918 -98.47072)
		(end 93.444568 -98.481388)
		(width 0.0889)
		(layer "In2.Cu")
		(net "M_M_CLK_DP<3>")
	)
	(segment
		(start 92.02674 -148.972524)
		(end 91.825572 -148.771356)
		(width 0.14224)
		(layer "In2.Cu")
		(net "M_M_CLK_DP<3>")
	)
	(segment
		(start 94.841568 -127.170434)
		(end 94.841568 -132.87248)
		(width 0.14224)
		(layer "In2.Cu")
		(net "M_M_CLK_DP<3>")
	)
	(segment
		(start 93.450918 -96.48952)
		(end 93.444568 -96.500188)
		(width 0.0889)
		(layer "In2.Cu")
		(net "M_M_CLK_DP<3>")
	)
	(segment
		(start 93.723968 -102.026974)
		(end 93.763338 -102.066344)
		(width 0.0889)
		(layer "In2.Cu")
		(net "M_M_CLK_DP<3>")
	)
	(segment
		(start 93.38818 -99.563174)
		(end 93.38818 -99.918266)
		(width 0.0889)
		(layer "In2.Cu")
		(net "M_M_CLK_DP<3>")
	)
	(segment
		(start 93.450918 -95.49892)
		(end 93.444568 -95.509588)
		(width 0.0889)
		(layer "In2.Cu")
		(net "M_M_CLK_DP<3>")
	)
	(segment
		(start 93.444568 -97.490788)
		(end 93.439742 -97.499424)
		(width 0.0889)
		(layer "In2.Cu")
		(net "M_M_CLK_DP<3>")
	)
	(segment
		(start 93.444568 -93.928438)
		(end 93.450918 -93.939106)
		(width 0.0889)
		(layer "In2.Cu")
		(net "M_M_CLK_DP<3>")
	)
	(segment
		(start 94.048834 -103.491792)
		(end 94.049088 -103.492046)
		(width 0.14224)
		(layer "In2.Cu")
		(net "M_M_CLK_DP<3>")
	)
	(segment
		(start 93.39707 -99.554284)
		(end 93.38818 -99.563174)
		(width 0.0889)
		(layer "In2.Cu")
		(net "M_M_CLK_DP<3>")
	)
	(segment
		(start 93.763338 -102.066344)
		(end 93.763338 -102.088442)
		(width 0.0889)
		(layer "In2.Cu")
		(net "M_M_CLK_DP<3>")
	)
	(segment
		(start 92.02674 -149.508972)
		(end 92.02674 -148.972524)
		(width 0.14224)
		(layer "In2.Cu")
		(net "M_M_CLK_DP<3>")
	)
	(segment
		(start 94.049088 -103.492046)
		(end 94.049088 -126.377954)
		(width 0.14224)
		(layer "In2.Cu")
		(net "M_M_CLK_DP<3>")
	)
	(segment
		(start 92.639642 -92.073476)
		(end 92.560902 -92.094812)
		(width 0.0889)
		(layer "In2.Cu")
		(net "M_M_CLK_DP<3>")
	)
	(segment
		(start 93.450918 -97.48012)
		(end 93.444568 -97.490788)
		(width 0.0889)
		(layer "In2.Cu")
		(net "M_M_CLK_DP<3>")
	)
	(segment
		(start 94.048326 -103.491792)
		(end 94.048834 -103.491792)
		(width 0.14224)
		(layer "In2.Cu")
		(net "M_M_CLK_DP<3>")
	)
	(segment
		(start 95.273368 -149.318726)
		(end 94.615254 -149.97684)
		(width 0.14224)
		(layer "In2.Cu")
		(net "M_M_CLK_DP<3>")
	)
	(segment
		(start 92.932758 -92.24264)
		(end 92.639642 -92.073476)
		(width 0.0889)
		(layer "In2.Cu")
		(net "M_M_CLK_DP<3>")
	)
	(segment
		(start 93.763338 -102.088442)
		(end 93.763338 -103.206804)
		(width 0.14224)
		(layer "In2.Cu")
		(net "M_M_CLK_DP<3>")
	)
	(segment
		(start 95.21063 -139.002008)
		(end 95.705168 -139.496546)
		(width 0.14224)
		(layer "In2.Cu")
		(net "M_M_CLK_DP<3>")
	)
	(segment
		(start 93.763338 -103.206804)
		(end 94.048326 -103.491792)
		(width 0.14224)
		(layer "In2.Cu")
		(net "M_M_CLK_DP<3>")
	)
	(segment
		(start 92.494608 -149.97684)
		(end 92.02674 -149.508972)
		(width 0.14224)
		(layer "In2.Cu")
		(net "M_M_CLK_DP<3>")
	)
	(segment
		(start 93.444568 -98.481388)
		(end 93.439742 -98.490024)
		(width 0.0889)
		(layer "In2.Cu")
		(net "M_M_CLK_DP<3>")
	)
	(segment
		(start 94.049088 -126.377954)
		(end 94.841568 -127.170434)
		(width 0.14224)
		(layer "In2.Cu")
		(net "M_M_CLK_DP<3>")
	)
	(segment
		(start 95.273368 -145.4912)
		(end 95.273368 -149.318726)
		(width 0.14224)
		(layer "In2.Cu")
		(net "M_M_CLK_DP<3>")
	)
	(segment
		(start 95.21063 -133.241542)
		(end 95.21063 -139.002008)
		(width 0.14224)
		(layer "In2.Cu")
		(net "M_M_CLK_DP<3>")
	)
	(segment
		(start 95.705168 -145.0594)
		(end 95.273368 -145.4912)
		(width 0.14224)
		(layer "In2.Cu")
		(net "M_M_CLK_DP<3>")
	)
	(segment
		(start 93.444568 -95.509588)
		(end 93.439742 -95.518224)
		(width 0.0889)
		(layer "In2.Cu")
		(net "M_M_CLK_DP<3>")
	)
	(segment
		(start 92.921582 -92.64269)
		(end 92.954348 -92.64269)
		(width 0.0889)
		(layer "In2.Cu")
		(net "M_M_CLK_DP<3>")
	)
	(segment
		(start 93.444568 -99.472242)
		(end 93.39707 -99.554284)
		(width 0.0889)
		(layer "In2.Cu")
		(net "M_M_CLK_DP<3>")
	)
	(arc
		(start 93.444568 -96.900238)
		(mid 93.52379 -97.189356)
		(end 93.450918 -97.48012)
		(width 0.0889)
		(layer "In2.Cu")
		(net "M_M_CLK_DP<3>")
	)
	(arc
		(start 93.450918 -93.939106)
		(mid 93.523716 -94.229869)
		(end 93.444568 -94.518988)
		(width 0.0889)
		(layer "In2.Cu")
		(net "M_M_CLK_DP<3>")
	)
	(arc
		(start 93.439742 -94.527624)
		(mid 93.390987 -94.723976)
		(end 93.444568 -94.919038)
		(width 0.0889)
		(layer "In2.Cu")
		(net "M_M_CLK_DP<3>")
	)
	(arc
		(start 93.444568 -93.528642)
		(mid 93.391069 -93.72854)
		(end 93.444568 -93.928438)
		(width 0.0889)
		(layer "In2.Cu")
		(net "M_M_CLK_DP<3>")
	)
	(arc
		(start 92.954348 -92.64269)
		(mid 93.449825 -92.947133)
		(end 93.444568 -93.528642)
		(width 0.0889)
		(layer "In2.Cu")
		(net "M_M_CLK_DP<3>")
	)
	(arc
		(start 93.444568 -94.919038)
		(mid 93.52379 -95.208156)
		(end 93.450918 -95.49892)
		(width 0.0889)
		(layer "In2.Cu")
		(net "M_M_CLK_DP<3>")
	)
	(arc
		(start 93.444568 -98.881438)
		(mid 93.523699 -99.17684)
		(end 93.444568 -99.472242)
		(width 0.0889)
		(layer "In2.Cu")
		(net "M_M_CLK_DP<3>")
	)
	(arc
		(start 93.439742 -98.490024)
		(mid 93.390987 -98.686376)
		(end 93.444568 -98.881438)
		(width 0.0889)
		(layer "In2.Cu")
		(net "M_M_CLK_DP<3>")
	)
	(arc
		(start 93.444568 -97.890838)
		(mid 93.52379 -98.179956)
		(end 93.450918 -98.47072)
		(width 0.0889)
		(layer "In2.Cu")
		(net "M_M_CLK_DP<3>")
	)
	(arc
		(start 93.444568 -95.909638)
		(mid 93.52379 -96.198756)
		(end 93.450918 -96.48952)
		(width 0.0889)
		(layer "In2.Cu")
		(net "M_M_CLK_DP<3>")
	)
	(arc
		(start 93.439742 -97.499424)
		(mid 93.390987 -97.695776)
		(end 93.444568 -97.890838)
		(width 0.0889)
		(layer "In2.Cu")
		(net "M_M_CLK_DP<3>")
	)
	(arc
		(start 93.439742 -95.518224)
		(mid 93.390987 -95.714576)
		(end 93.444568 -95.909638)
		(width 0.0889)
		(layer "In2.Cu")
		(net "M_M_CLK_DP<3>")
	)
	(arc
		(start 92.560902 -92.094812)
		(mid 92.598529 -92.462688)
		(end 92.921582 -92.64269)
		(width 0.0889)
		(layer "In2.Cu")
		(net "M_M_CLK_DP<3>")
	)
	(arc
		(start 93.439742 -96.508824)
		(mid 93.390987 -96.705176)
		(end 93.444568 -96.900238)
		(width 0.0889)
		(layer "In2.Cu")
		(net "M_M_CLK_DP<3>")
	)
	(segment
		(start 94.649798 -92.24264)
		(end 95.221298 -92.24264)
		(width 0.1016)
		(layer "F.Cu")
		(net "M_M_CLK_DP<1>")
	)
	(segment
		(start 91.749372 -156.87294)
		(end 91.749372 -155.509468)
		(width 0.1651)
		(layer "F.Cu")
		(net "M_M_CLK_DP<1>")
	)
	(via
		(at 91.749372 -155.509468)
		(size 0.508)
		(drill 0.254)
		(layers "F.Cu" "B.Cu")
		(net "M_M_CLK_DP<1>")
	)
	(via
		(at 94.649798 -92.24264)
		(size 0.508)
		(drill 0.254)
		(layers "F.Cu" "B.Cu")
		(net "M_M_CLK_DP<1>")
	)
	(segment
		(start 95.776288 -125.589792)
		(end 96.94291 -126.756414)
		(width 0.14224)
		(layer "In2.Cu")
		(net "M_M_CLK_DP<1>")
	)
	(segment
		(start 95.161608 -93.928438)
		(end 95.167958 -93.939106)
		(width 0.0889)
		(layer "In2.Cu")
		(net "M_M_CLK_DP<1>")
	)
	(segment
		(start 92.001848 -155.761944)
		(end 91.749372 -155.509468)
		(width 0.14224)
		(layer "In2.Cu")
		(net "M_M_CLK_DP<1>")
	)
	(segment
		(start 95.167958 -97.48012)
		(end 95.161608 -97.490788)
		(width 0.0889)
		(layer "In2.Cu")
		(net "M_M_CLK_DP<1>")
	)
	(segment
		(start 95.167958 -96.48952)
		(end 95.161608 -96.500188)
		(width 0.0889)
		(layer "In2.Cu")
		(net "M_M_CLK_DP<1>")
	)
	(segment
		(start 95.161608 -95.509588)
		(end 95.156782 -95.518224)
		(width 0.0889)
		(layer "In2.Cu")
		(net "M_M_CLK_DP<1>")
	)
	(segment
		(start 95.108268 -99.9109)
		(end 95.438468 -100.2411)
		(width 0.0889)
		(layer "In2.Cu")
		(net "M_M_CLK_DP<1>")
	)
	(segment
		(start 95.776288 -102.831392)
		(end 95.776288 -125.589792)
		(width 0.14224)
		(layer "In2.Cu")
		(net "M_M_CLK_DP<1>")
	)
	(segment
		(start 97.28835 -154.236166)
		(end 94.795848 -156.728668)
		(width 0.14224)
		(layer "In2.Cu")
		(net "M_M_CLK_DP<1>")
	)
	(segment
		(start 95.161608 -96.500188)
		(end 95.156782 -96.508824)
		(width 0.0889)
		(layer "In2.Cu")
		(net "M_M_CLK_DP<1>")
	)
	(segment
		(start 95.167958 -99.461066)
		(end 95.108268 -99.568)
		(width 0.0889)
		(layer "In2.Cu")
		(net "M_M_CLK_DP<1>")
	)
	(segment
		(start 95.471488 -102.001066)
		(end 95.471488 -102.526592)
		(width 0.14224)
		(layer "In2.Cu")
		(net "M_M_CLK_DP<1>")
	)
	(segment
		(start 95.167958 -95.49892)
		(end 95.161608 -95.509588)
		(width 0.0889)
		(layer "In2.Cu")
		(net "M_M_CLK_DP<1>")
	)
	(segment
		(start 95.108268 -99.568)
		(end 95.108268 -99.9109)
		(width 0.0889)
		(layer "In2.Cu")
		(net "M_M_CLK_DP<1>")
	)
	(segment
		(start 95.161608 -97.490788)
		(end 95.156782 -97.499424)
		(width 0.0889)
		(layer "In2.Cu")
		(net "M_M_CLK_DP<1>")
	)
	(segment
		(start 96.94291 -126.756414)
		(end 96.94291 -129.197862)
		(width 0.14224)
		(layer "In2.Cu")
		(net "M_M_CLK_DP<1>")
	)
	(segment
		(start 97.315782 -140.598906)
		(end 97.203768 -140.71092)
		(width 0.14224)
		(layer "In2.Cu")
		(net "M_M_CLK_DP<1>")
	)
	(segment
		(start 95.438468 -101.968046)
		(end 95.471488 -102.001066)
		(width 0.0889)
		(layer "In2.Cu")
		(net "M_M_CLK_DP<1>")
	)
	(segment
		(start 92.43568 -156.728668)
		(end 92.001848 -156.294836)
		(width 0.14224)
		(layer "In2.Cu")
		(net "M_M_CLK_DP<1>")
	)
	(segment
		(start 95.161608 -98.481388)
		(end 95.156782 -98.490024)
		(width 0.0889)
		(layer "In2.Cu")
		(net "M_M_CLK_DP<1>")
	)
	(segment
		(start 96.94291 -129.197862)
		(end 97.315782 -129.570734)
		(width 0.14224)
		(layer "In2.Cu")
		(net "M_M_CLK_DP<1>")
	)
	(segment
		(start 94.356682 -92.073476)
		(end 94.277942 -92.094812)
		(width 0.0889)
		(layer "In2.Cu")
		(net "M_M_CLK_DP<1>")
	)
	(segment
		(start 97.203768 -140.71092)
		(end 97.203768 -142.1384)
		(width 0.14224)
		(layer "In2.Cu")
		(net "M_M_CLK_DP<1>")
	)
	(segment
		(start 92.001848 -156.294836)
		(end 92.001848 -155.761944)
		(width 0.14224)
		(layer "In2.Cu")
		(net "M_M_CLK_DP<1>")
	)
	(segment
		(start 95.438468 -100.2411)
		(end 95.438468 -101.968046)
		(width 0.0889)
		(layer "In2.Cu")
		(net "M_M_CLK_DP<1>")
	)
	(segment
		(start 95.161608 -94.518988)
		(end 95.156782 -94.527624)
		(width 0.0889)
		(layer "In2.Cu")
		(net "M_M_CLK_DP<1>")
	)
	(segment
		(start 94.795848 -156.728668)
		(end 92.43568 -156.728668)
		(width 0.14224)
		(layer "In2.Cu")
		(net "M_M_CLK_DP<1>")
	)
	(segment
		(start 95.161608 -98.881438)
		(end 95.161862 -98.881692)
		(width 0.0889)
		(layer "In2.Cu")
		(net "M_M_CLK_DP<1>")
	)
	(segment
		(start 94.649798 -92.24264)
		(end 94.356682 -92.073476)
		(width 0.0889)
		(layer "In2.Cu")
		(net "M_M_CLK_DP<1>")
	)
	(segment
		(start 95.167958 -98.47072)
		(end 95.161608 -98.481388)
		(width 0.0889)
		(layer "In2.Cu")
		(net "M_M_CLK_DP<1>")
	)
	(segment
		(start 97.315782 -129.570734)
		(end 97.315782 -140.598906)
		(width 0.14224)
		(layer "In2.Cu")
		(net "M_M_CLK_DP<1>")
	)
	(segment
		(start 97.28835 -142.222982)
		(end 97.28835 -154.236166)
		(width 0.14224)
		(layer "In2.Cu")
		(net "M_M_CLK_DP<1>")
	)
	(segment
		(start 95.471488 -102.526592)
		(end 95.776288 -102.831392)
		(width 0.14224)
		(layer "In2.Cu")
		(net "M_M_CLK_DP<1>")
	)
	(segment
		(start 94.638622 -92.64269)
		(end 94.671388 -92.64269)
		(width 0.0889)
		(layer "In2.Cu")
		(net "M_M_CLK_DP<1>")
	)
	(segment
		(start 97.203768 -142.1384)
		(end 97.28835 -142.222982)
		(width 0.14224)
		(layer "In2.Cu")
		(net "M_M_CLK_DP<1>")
	)
	(arc
		(start 95.156782 -96.508824)
		(mid 95.108027 -96.705176)
		(end 95.161608 -96.900238)
		(width 0.0889)
		(layer "In2.Cu")
		(net "M_M_CLK_DP<1>")
	)
	(arc
		(start 95.167958 -93.939106)
		(mid 95.240756 -94.229869)
		(end 95.161608 -94.518988)
		(width 0.0889)
		(layer "In2.Cu")
		(net "M_M_CLK_DP<1>")
	)
	(arc
		(start 95.156782 -97.499424)
		(mid 95.108027 -97.695776)
		(end 95.161608 -97.890838)
		(width 0.0889)
		(layer "In2.Cu")
		(net "M_M_CLK_DP<1>")
	)
	(arc
		(start 95.156782 -94.527624)
		(mid 95.108027 -94.723976)
		(end 95.161608 -94.919038)
		(width 0.0889)
		(layer "In2.Cu")
		(net "M_M_CLK_DP<1>")
	)
	(arc
		(start 95.161608 -94.919038)
		(mid 95.24083 -95.208156)
		(end 95.167958 -95.49892)
		(width 0.0889)
		(layer "In2.Cu")
		(net "M_M_CLK_DP<1>")
	)
	(arc
		(start 95.156782 -95.518224)
		(mid 95.108027 -95.714576)
		(end 95.161608 -95.909638)
		(width 0.0889)
		(layer "In2.Cu")
		(net "M_M_CLK_DP<1>")
	)
	(arc
		(start 94.277942 -92.094812)
		(mid 94.257823 -92.161897)
		(end 94.249748 -92.231464)
		(width 0.0889)
		(layer "In2.Cu")
		(net "M_M_CLK_DP<1>")
	)
	(arc
		(start 94.249748 -92.231464)
		(mid 94.359017 -92.517615)
		(end 94.638622 -92.64269)
		(width 0.0889)
		(layer "In2.Cu")
		(net "M_M_CLK_DP<1>")
	)
	(arc
		(start 95.161608 -96.900238)
		(mid 95.24083 -97.189356)
		(end 95.167958 -97.48012)
		(width 0.0889)
		(layer "In2.Cu")
		(net "M_M_CLK_DP<1>")
	)
	(arc
		(start 95.161608 -97.890838)
		(mid 95.24083 -98.179956)
		(end 95.167958 -98.47072)
		(width 0.0889)
		(layer "In2.Cu")
		(net "M_M_CLK_DP<1>")
	)
	(arc
		(start 95.161608 -95.909638)
		(mid 95.24083 -96.198756)
		(end 95.167958 -96.48952)
		(width 0.0889)
		(layer "In2.Cu")
		(net "M_M_CLK_DP<1>")
	)
	(arc
		(start 95.161862 -98.881692)
		(mid 95.240799 -99.170586)
		(end 95.167958 -99.461066)
		(width 0.0889)
		(layer "In2.Cu")
		(net "M_M_CLK_DP<1>")
	)
	(arc
		(start 94.671388 -92.64269)
		(mid 95.166865 -92.947133)
		(end 95.161608 -93.528642)
		(width 0.0889)
		(layer "In2.Cu")
		(net "M_M_CLK_DP<1>")
	)
	(arc
		(start 95.156782 -98.490024)
		(mid 95.108027 -98.686376)
		(end 95.161608 -98.881438)
		(width 0.0889)
		(layer "In2.Cu")
		(net "M_M_CLK_DP<1>")
	)
	(arc
		(start 95.161608 -93.528642)
		(mid 95.108109 -93.72854)
		(end 95.161608 -93.928438)
		(width 0.0889)
		(layer "In2.Cu")
		(net "M_M_CLK_DP<1>")
	)
	(segment
		(start 93.504258 -93.23324)
		(end 92.932758 -93.23324)
		(width 0.1016)
		(layer "F.Cu")
		(net "M_M_CLK_DP<2>")
	)
	(via
		(at 92.932758 -93.23324)
		(size 0.508)
		(drill 0.254)
		(layers "F.Cu" "B.Cu")
		(net "M_M_CLK_DP<2>")
	)
	(via
		(at 91.938856 -150.785068)
		(size 0.508)
		(drill 0.254)
		(layers "F.Cu" "B.Cu")
		(net "M_M_CLK_DP<2>")
	)
	(segment
		(start 91.749372 -150.974552)
		(end 91.938856 -150.785068)
		(width 0.1651)
		(layer "B.Cu")
		(net "M_M_CLK_DP<2>")
	)
	(segment
		(start 91.749372 -152.078436)
		(end 91.749372 -150.974552)
		(width 0.1651)
		(layer "B.Cu")
		(net "M_M_CLK_DP<2>")
	)
	(segment
		(start 94.36608 -135.258556)
		(end 94.252288 -135.372348)
		(width 0.14224)
		(layer "In2.Cu")
		(net "M_M_CLK_DP<2>")
	)
	(segment
		(start 92.586048 -96.404938)
		(end 92.592398 -96.415606)
		(width 0.0889)
		(layer "In2.Cu")
		(net "M_M_CLK_DP<2>")
	)
	(segment
		(start 92.226638 -151.300942)
		(end 92.226638 -151.07285)
		(width 0.14224)
		(layer "In2.Cu")
		(net "M_M_CLK_DP<2>")
	)
	(segment
		(start 94.36608 -137.573004)
		(end 94.252288 -137.686796)
		(width 0.14224)
		(layer "In2.Cu")
		(net "M_M_CLK_DP<2>")
	)
	(segment
		(start 91.519502 -151.678132)
		(end 91.849448 -151.678132)
		(width 0.14224)
		(layer "In2.Cu")
		(net "M_M_CLK_DP<2>")
	)
	(segment
		(start 94.252288 -145.142458)
		(end 94.252288 -146.063462)
		(width 0.14224)
		(layer "In2.Cu")
		(net "M_M_CLK_DP<2>")
	)
	(segment
		(start 92.597986 -99.398328)
		(end 92.669868 -99.535234)
		(width 0.0889)
		(layer "In2.Cu")
		(net "M_M_CLK_DP<2>")
	)
	(segment
		(start 94.252288 -144.477486)
		(end 94.352364 -144.577562)
		(width 0.14224)
		(layer "In2.Cu")
		(net "M_M_CLK_DP<2>")
	)
	(segment
		(start 93.927168 -131.015232)
		(end 94.04096 -131.129024)
		(width 0.14224)
		(layer "In2.Cu")
		(net "M_M_CLK_DP<2>")
	)
	(segment
		(start 93.312742 -147.114006)
		(end 93.201744 -147.114006)
		(width 0.14224)
		(layer "In2.Cu")
		(net "M_M_CLK_DP<2>")
	)
	(segment
		(start 92.907104 -103.543608)
		(end 93.210888 -103.847392)
		(width 0.14224)
		(layer "In2.Cu")
		(net "M_M_CLK_DP<2>")
	)
	(segment
		(start 94.36608 -134.793736)
		(end 94.36608 -135.258556)
		(width 0.14224)
		(layer "In2.Cu")
		(net "M_M_CLK_DP<2>")
	)
	(segment
		(start 93.210888 -126.758192)
		(end 93.927168 -127.474472)
		(width 0.14224)
		(layer "In2.Cu")
		(net "M_M_CLK_DP<2>")
	)
	(segment
		(start 93.927168 -127.474472)
		(end 93.927168 -129.889758)
		(width 0.14224)
		(layer "In2.Cu")
		(net "M_M_CLK_DP<2>")
	)
	(segment
		(start 94.36608 -136.41578)
		(end 94.252288 -136.529572)
		(width 0.14224)
		(layer "In2.Cu")
		(net "M_M_CLK_DP<2>")
	)
	(segment
		(start 91.392502 -151.551132)
		(end 91.519502 -151.678132)
		(width 0.14224)
		(layer "In2.Cu")
		(net "M_M_CLK_DP<2>")
	)
	(segment
		(start 93.201744 -147.114006)
		(end 92.698062 -147.617688)
		(width 0.14224)
		(layer "In2.Cu")
		(net "M_M_CLK_DP<2>")
	)
	(segment
		(start 94.36608 -138.730228)
		(end 94.252288 -138.84402)
		(width 0.14224)
		(layer "In2.Cu")
		(net "M_M_CLK_DP<2>")
	)
	(segment
		(start 94.36608 -143.885158)
		(end 94.252288 -143.99895)
		(width 0.14224)
		(layer "In2.Cu")
		(net "M_M_CLK_DP<2>")
	)
	(segment
		(start 94.252288 -139.30884)
		(end 94.739968 -139.79652)
		(width 0.14224)
		(layer "In2.Cu")
		(net "M_M_CLK_DP<2>")
	)
	(segment
		(start 92.581222 -97.386902)
		(end 92.596716 -97.41408)
		(width 0.0889)
		(layer "In2.Cu")
		(net "M_M_CLK_DP<2>")
	)
	(segment
		(start 94.013782 -130.441192)
		(end 93.927168 -130.527806)
		(width 0.14224)
		(layer "In2.Cu")
		(net "M_M_CLK_DP<2>")
	)
	(segment
		(start 92.226638 -151.07285)
		(end 91.938856 -150.785068)
		(width 0.14224)
		(layer "In2.Cu")
		(net "M_M_CLK_DP<2>")
	)
	(segment
		(start 93.641672 -146.785076)
		(end 93.312742 -147.114006)
		(width 0.14224)
		(layer "In2.Cu")
		(net "M_M_CLK_DP<2>")
	)
	(segment
		(start 94.252288 -142.29588)
		(end 94.252288 -143.306546)
		(width 0.14224)
		(layer "In2.Cu")
		(net "M_M_CLK_DP<2>")
	)
	(segment
		(start 93.927168 -132.172456)
		(end 94.04096 -132.286248)
		(width 0.14224)
		(layer "In2.Cu")
		(net "M_M_CLK_DP<2>")
	)
	(segment
		(start 92.874084 -101.89972)
		(end 92.907104 -101.93274)
		(width 0.0889)
		(layer "In2.Cu")
		(net "M_M_CLK_DP<2>")
	)
	(segment
		(start 94.36608 -143.420338)
		(end 94.36608 -143.885158)
		(width 0.14224)
		(layer "In2.Cu")
		(net "M_M_CLK_DP<2>")
	)
	(segment
		(start 94.36608 -138.265408)
		(end 94.36608 -138.730228)
		(width 0.14224)
		(layer "In2.Cu")
		(net "M_M_CLK_DP<2>")
	)
	(segment
		(start 91.811348 -147.617688)
		(end 91.392502 -148.036534)
		(width 0.14224)
		(layer "In2.Cu")
		(net "M_M_CLK_DP<2>")
	)
	(segment
		(start 91.392502 -148.036534)
		(end 91.392502 -151.551132)
		(width 0.14224)
		(layer "In2.Cu")
		(net "M_M_CLK_DP<2>")
	)
	(segment
		(start 92.907104 -101.93274)
		(end 92.907104 -101.954838)
		(width 0.0889)
		(layer "In2.Cu")
		(net "M_M_CLK_DP<2>")
	)
	(segment
		(start 94.252288 -137.686796)
		(end 94.252288 -138.151616)
		(width 0.14224)
		(layer "In2.Cu")
		(net "M_M_CLK_DP<2>")
	)
	(segment
		(start 94.252288 -136.529572)
		(end 94.252288 -136.994392)
		(width 0.14224)
		(layer "In2.Cu")
		(net "M_M_CLK_DP<2>")
	)
	(segment
		(start 92.581222 -95.405702)
		(end 92.586048 -95.414338)
		(width 0.0889)
		(layer "In2.Cu")
		(net "M_M_CLK_DP<2>")
	)
	(segment
		(start 92.907104 -101.954838)
		(end 92.907104 -103.543608)
		(width 0.14224)
		(layer "In2.Cu")
		(net "M_M_CLK_DP<2>")
	)
	(segment
		(start 92.586048 -95.414338)
		(end 92.592398 -95.425006)
		(width 0.0889)
		(layer "In2.Cu")
		(net "M_M_CLK_DP<2>")
	)
	(segment
		(start 94.739968 -141.8082)
		(end 94.252288 -142.29588)
		(width 0.14224)
		(layer "In2.Cu")
		(net "M_M_CLK_DP<2>")
	)
	(segment
		(start 91.849448 -151.678132)
		(end 92.226638 -151.300942)
		(width 0.14224)
		(layer "In2.Cu")
		(net "M_M_CLK_DP<2>")
	)
)
